(kicad_pcb
	(version 20260206)
	(generator "pcbnew")
	(generator_version "10.0")
	(general
		(thickness 1.6)
		(legacy_teardrops no)
	)
	(paper "A4")
	(layers
		(0 "F.Cu" signal "TOP")
		(4 "In1.Cu" signal "GND")
		(6 "In2.Cu" signal "IN1")
		(8 "In3.Cu" signal "GND1")
		(10 "In4.Cu" signal "IN2")
		(12 "In5.Cu" signal "GND2")
		(14 "In6.Cu" signal "IN3")
		(16 "In7.Cu" signal "GND3")
		(18 "In8.Cu" signal "VCC")
		(20 "In9.Cu" signal "VCC1")
		(22 "In10.Cu" signal "GND4")
		(24 "In11.Cu" signal "IN4")
		(26 "In12.Cu" signal "GND5")
		(28 "In13.Cu" signal "IN5")
		(30 "In14.Cu" signal "GND6")
		(32 "In15.Cu" signal "IN6")
		(34 "In16.Cu" signal "GND7")
		(2 "B.Cu" signal "BOTTOM")
		(9 "F.Adhes" user "F.Adhesive")
		(11 "B.Adhes" user "B.Adhesive")
		(13 "F.Paste" user "Package Geometry/Pastemask Top")
		(15 "B.Paste" user "Package Geometry/Pastemask Bottom")
		(5 "F.SilkS" user "Ref Des/Silkscreen Top")
		(7 "B.SilkS" user "Ref Des/Silkscreen Bottom")
		(1 "F.Mask" user "Board Geometry/Soldermask Top")
		(3 "B.Mask" user "Board Geometry/Soldermask Bottom")
		(17 "Dwgs.User" user "User.Drawings")
		(19 "Cmts.User" user "User.Comments")
		(21 "Eco1.User" user "User.Eco1")
		(23 "Eco2.User" user "User.Eco2")
		(25 "Edge.Cuts" user "Board Geometry/Outline")
		(27 "Margin" user)
		(31 "F.CrtYd" user "Package Geometry/Place Bound Top")
		(29 "B.CrtYd" user "Package Geometry/Place Bound Bottom")
		(35 "F.Fab" user "Ref Des/Assembly Top")
		(33 "B.Fab" user "Ref Des/Assembly Bottom")
	)
	(setup
		(pad_to_mask_clearance 0)
		(allow_soldermask_bridges_in_footprints no)
		(tenting
			(front yes)
			(back yes)
		)
		(covering
			(front no)
			(back no)
		)
		(plugging
			(front no)
			(back no)
		)
		(capping no)
		(filling no)
		(pcbplotparams
			(layerselection 0x00000000_00000000_55555555_5755f5ff)
			(plot_on_all_layers_selection 0x00000000_00000000_00000000_00000000)
			(disableapertmacros no)
			(usegerberextensions no)
			(usegerberattributes yes)
			(usegerberadvancedattributes yes)
			(creategerberjobfile yes)
			(dashed_line_dash_ratio 12)
			(dashed_line_gap_ratio 3)
			(svgprecision 4)
			(plotframeref no)
			(mode 1)
			(useauxorigin no)
			(pdf_front_fp_property_popups yes)
			(pdf_back_fp_property_popups yes)
			(pdf_metadata yes)
			(pdf_single_document no)
			(dxfpolygonmode yes)
			(dxfimperialunits yes)
			(dxfusepcbnewfont yes)
			(psnegative no)
			(psa4output no)
			(plot_black_and_white yes)
			(sketchpadsonfab no)
			(plotpadnumbers no)
			(hidednponfab no)
			(sketchdnponfab yes)
			(crossoutdnponfab yes)
			(subtractmaskfromsilk no)
			(outputformat 1)
			(mirror no)
			(drillshape 1)
			(scaleselection 1)
			(outputdirectory "")
		)
	)
	(segment
		(start 85.514688 -255.375918)
		(end 85.243162 -256.031238)
		(width 0.14732)
		(layer "In15.Cu")
		(net "P5E_CPU1_PE0_TX_DP<0>")
	)
	(segment
		(start 89.837768 -224.065084)
		(end 89.828878 -224.070164)
		(width 0.0889)
		(layer "In15.Cu")
		(net "P5E_CPU1_PE0_TX_DP<0>")
	)
	(segment
		(start 92.488258 -395.005306)
		(end 92.651326 -395.072616)
		(width 0.14732)
		(layer "In15.Cu")
		(net "P5E_CPU1_PE0_TX_DP<0>")
	)
	(segment
		(start 89.180416 -225.194622)
		(end 89.180416 -225.2218)
		(width 0.0889)
		(layer "In15.Cu")
		(net "P5E_CPU1_PE0_TX_DP<0>")
	)
	(segment
		(start 84.940648 -311.154318)
		(end 78.430882 -326.606916)
		(width 0.14732)
		(layer "In15.Cu")
		(net "P5E_CPU1_PE0_TX_DP<0>")
	)
	(segment
		(start 88.428576 -226.506278)
		(end 88.427814 -226.506786)
		(width 0.0889)
		(layer "In15.Cu")
		(net "P5E_CPU1_PE0_TX_DP<0>")
	)
	(segment
		(start 86.106508 -250.858782)
		(end 86.016592 -251.36983)
		(width 0.14732)
		(layer "In15.Cu")
		(net "P5E_CPU1_PE0_TX_DP<0>")
	)
	(segment
		(start 92.058998 -393.967208)
		(end 92.05849 -393.96797)
		(width 0.14732)
		(layer "In15.Cu")
		(net "P5E_CPU1_PE0_TX_DP<0>")
	)
	(segment
		(start 73.591166 -336.094324)
		(end 74.421238 -351.378266)
		(width 0.14732)
		(layer "In15.Cu")
		(net "P5E_CPU1_PE0_TX_DP<0>")
	)
	(segment
		(start 92.05849 -393.96797)
		(end 92.221558 -394.03528)
		(width 0.14732)
		(layer "In15.Cu")
		(net "P5E_CPU1_PE0_TX_DP<0>")
	)
	(segment
		(start 83.160616 -260.166104)
		(end 82.143346 -266.662408)
		(width 0.14732)
		(layer "In15.Cu")
		(net "P5E_CPU1_PE0_TX_DP<0>")
	)
	(segment
		(start 92.818458 -395.476476)
		(end 92.750894 -395.639036)
		(width 0.14732)
		(layer "In15.Cu")
		(net "P5E_CPU1_PE0_TX_DP<0>")
	)
	(segment
		(start 92.651326 -395.072616)
		(end 92.818458 -395.476476)
		(width 0.14732)
		(layer "In15.Cu")
		(net "P5E_CPU1_PE0_TX_DP<0>")
	)
	(segment
		(start 85.778848 -247.810782)
		(end 85.778848 -249.228356)
		(width 0.14732)
		(layer "In15.Cu")
		(net "P5E_CPU1_PE0_TX_DP<0>")
	)
	(segment
		(start 90.18143 -224.118424)
		(end 90.160348 -224.040446)
		(width 0.0889)
		(layer "In15.Cu")
		(net "P5E_CPU1_PE0_TX_DP<0>")
	)
	(segment
		(start 85.243162 -256.031238)
		(end 84.48294 -256.791714)
		(width 0.14732)
		(layer "In15.Cu")
		(net "P5E_CPU1_PE0_TX_DP<0>")
	)
	(segment
		(start 89.371424 -224.876614)
		(end 89.370408 -224.877122)
		(width 0.0889)
		(layer "In15.Cu")
		(net "P5E_CPU1_PE0_TX_DP<0>")
	)
	(segment
		(start 92.321126 -394.6017)
		(end 92.488258 -395.005306)
		(width 0.14732)
		(layer "In15.Cu")
		(net "P5E_CPU1_PE0_TX_DP<0>")
	)
	(segment
		(start 92.750894 -395.639036)
		(end 92.918026 -396.042642)
		(width 0.14732)
		(layer "In15.Cu")
		(net "P5E_CPU1_PE0_TX_DP<0>")
	)
	(segment
		(start 85.33384 -254.350774)
		(end 85.514688 -255.375918)
		(width 0.14732)
		(layer "In15.Cu")
		(net "P5E_CPU1_PE0_TX_DP<0>")
	)
	(segment
		(start 85.33384 -252.7808)
		(end 85.33384 -254.350774)
		(width 0.14732)
		(layer "In15.Cu")
		(net "P5E_CPU1_PE0_TX_DP<0>")
	)
	(segment
		(start 94.497398 -399.856198)
		(end 94.497398 -400.563588)
		(width 0.14732)
		(layer "In15.Cu")
		(net "P5E_CPU1_PE0_TX_DP<0>")
	)
	(segment
		(start 84.48294 -256.791714)
		(end 83.160616 -260.166104)
		(width 0.14732)
		(layer "In15.Cu")
		(net "P5E_CPU1_PE0_TX_DP<0>")
	)
	(segment
		(start 85.437218 -252.197362)
		(end 85.33384 -252.7808)
		(width 0.14732)
		(layer "In15.Cu")
		(net "P5E_CPU1_PE0_TX_DP<0>")
	)
	(segment
		(start 90.024966 -224.389442)
		(end 90.18143 -224.118424)
		(width 0.0889)
		(layer "In15.Cu")
		(net "P5E_CPU1_PE0_TX_DP<0>")
	)
	(segment
		(start 91.62923 -392.929872)
		(end 91.628722 -392.930634)
		(width 0.14732)
		(layer "In15.Cu")
		(net "P5E_CPU1_PE0_TX_DP<0>")
	)
	(segment
		(start 83.366102 -233.56443)
		(end 83.757516 -243.417852)
		(width 0.14732)
		(layer "In15.Cu")
		(net "P5E_CPU1_PE0_TX_DP<0>")
	)
	(segment
		(start 74.421238 -351.378266)
		(end 91.62923 -392.929872)
		(width 0.14732)
		(layer "In15.Cu")
		(net "P5E_CPU1_PE0_TX_DP<0>")
	)
	(segment
		(start 94.497398 -400.563588)
		(end 94.792038 -400.858228)
		(width 0.14732)
		(layer "In15.Cu")
		(net "P5E_CPU1_PE0_TX_DP<0>")
	)
	(segment
		(start 91.958922 -393.401804)
		(end 91.891358 -393.564364)
		(width 0.14732)
		(layer "In15.Cu")
		(net "P5E_CPU1_PE0_TX_DP<0>")
	)
	(segment
		(start 85.778848 -249.228356)
		(end 86.106508 -250.019566)
		(width 0.14732)
		(layer "In15.Cu")
		(net "P5E_CPU1_PE0_TX_DP<0>")
	)
	(segment
		(start 88.43391 -226.50323)
		(end 88.428576 -226.506278)
		(width 0.0889)
		(layer "In15.Cu")
		(net "P5E_CPU1_PE0_TX_DP<0>")
	)
	(segment
		(start 92.38869 -394.43914)
		(end 92.321126 -394.6017)
		(width 0.14732)
		(layer "In15.Cu")
		(net "P5E_CPU1_PE0_TX_DP<0>")
	)
	(arc
		(start 90.160348 -224.040446)
		(mid 89.996252 -224.016099)
		(end 89.837768 -224.065084)
		(width 0.0889)
		(layer "In15.Cu")
		(net "P5E_CPU1_PE0_TX_DP<0>")
	)
	(arc
		(start 89.367614 -224.8789)
		(mid 89.232681 -225.012254)
		(end 89.180416 -225.194622)
		(width 0.0889)
		(layer "In15.Cu")
		(net "P5E_CPU1_PE0_TX_DP<0>")
	)
	(arc
		(start 88.240616 -226.84105)
		(mid 88.162505 -227.117999)
		(end 87.958168 -227.320602)
		(width 0.0889)
		(layer "In15.Cu")
		(net "P5E_CPU1_PE0_TX_DP<0>")
	)
	(arc
		(start 88.427814 -226.506786)
		(mid 88.292881 -226.64014)
		(end 88.240616 -226.822508)
		(width 0.0889)
		(layer "In15.Cu")
		(net "P5E_CPU1_PE0_TX_DP<0>")
	)
	(arc
		(start 88.710516 -226.017328)
		(mid 88.636525 -226.296894)
		(end 88.43391 -226.50323)
		(width 0.0889)
		(layer "In15.Cu")
		(net "P5E_CPU1_PE0_TX_DP<0>")
	)
	(arc
		(start 89.828878 -224.070164)
		(mid 89.697964 -224.206524)
		(end 89.650316 -224.389442)
		(width 0.0889)
		(layer "In15.Cu")
		(net "P5E_CPU1_PE0_TX_DP<0>")
	)
	(arc
		(start 87.949278 -227.325682)
		(mid 87.818364 -227.462042)
		(end 87.770716 -227.64496)
		(width 0.0889)
		(layer "In15.Cu")
		(net "P5E_CPU1_PE0_TX_DP<0>")
	)
	(arc
		(start 88.889078 -225.69805)
		(mid 88.758164 -225.83441)
		(end 88.710516 -226.017328)
		(width 0.0889)
		(layer "In15.Cu")
		(net "P5E_CPU1_PE0_TX_DP<0>")
	)
	(arc
		(start 87.488268 -228.134672)
		(mid 87.44721 -228.161559)
		(end 87.410036 -228.1936)
		(width 0.0889)
		(layer "In15.Cu")
		(net "P5E_CPU1_PE0_TX_DP<0>")
	)
	(arc
		(start 89.650316 -224.389442)
		(mid 89.576325 -224.669008)
		(end 89.37371 -224.875344)
		(width 0.0889)
		(layer "In15.Cu")
		(net "P5E_CPU1_PE0_TX_DP<0>")
	)
	(arc
		(start 89.180416 -225.2218)
		(mid 89.100254 -225.493989)
		(end 88.897968 -225.69297)
		(width 0.0889)
		(layer "In15.Cu")
		(net "P5E_CPU1_PE0_TX_DP<0>")
	)
	(arc
		(start 87.770716 -227.659184)
		(mid 87.691575 -227.933807)
		(end 87.488268 -228.134672)
		(width 0.0889)
		(layer "In15.Cu")
		(net "P5E_CPU1_PE0_TX_DP<0>")
	)
	(segment
		(start 66.333878 -402.104352)
		(end 66.33845 -402.104352)
		(width 0.13208)
		(layer "F.Cu")
		(net "P5E_CPU1_PE0_TX_DN<9>")
	)
	(segment
		(start 66.66484 -401.16379)
		(end 66.359278 -400.858228)
		(width 0.13208)
		(layer "F.Cu")
		(net "P5E_CPU1_PE0_TX_DN<9>")
	)
	(segment
		(start 66.66484 -401.777962)
		(end 66.66484 -401.16379)
		(width 0.13208)
		(layer "F.Cu")
		(net "P5E_CPU1_PE0_TX_DN<9>")
	)
	(segment
		(start 98.482912 -224.389696)
		(end 98.483166 -224.389442)
		(width 0.13208)
		(layer "F.Cu")
		(net "P5E_CPU1_PE0_TX_DN<9>")
	)
	(segment
		(start 66.33845 -402.104352)
		(end 66.66484 -401.777962)
		(width 0.13208)
		(layer "F.Cu")
		(net "P5E_CPU1_PE0_TX_DN<9>")
	)
	(segment
		(start 98.482912 -224.925382)
		(end 98.482912 -224.389696)
		(width 0.13208)
		(layer "F.Cu")
		(net "P5E_CPU1_PE0_TX_DN<9>")
	)
	(segment
		(start 72.403462 -250.17476)
		(end 72.320404 -252.642624)
		(width 0.14732)
		(layer "In15.Cu")
		(net "P5E_CPU1_PE0_TX_DN<9>")
	)
	(segment
		(start 98.287078 -224.070164)
		(end 98.295968 -224.065084)
		(width 0.0889)
		(layer "In15.Cu")
		(net "P5E_CPU1_PE0_TX_DN<9>")
	)
	(segment
		(start 64.365886 -335.313782)
		(end 64.646302 -346.407486)
		(width 0.14732)
		(layer "In15.Cu")
		(net "P5E_CPU1_PE0_TX_DN<9>")
	)
	(segment
		(start 73.84923 -232.977182)
		(end 73.84796 -232.98658)
		(width 0.14732)
		(layer "In15.Cu")
		(net "P5E_CPU1_PE0_TX_DN<9>")
	)
	(segment
		(start 66.665856 -400.55165)
		(end 66.359278 -400.858228)
		(width 0.14732)
		(layer "In15.Cu")
		(net "P5E_CPU1_PE0_TX_DN<9>")
	)
	(segment
		(start 71.533258 -320.020188)
		(end 67.903852 -325.807324)
		(width 0.14732)
		(layer "In15.Cu")
		(net "P5E_CPU1_PE0_TX_DN<9>")
	)
	(segment
		(start 72.320404 -252.642624)
		(end 72.320404 -252.766068)
		(width 0.14732)
		(layer "In15.Cu")
		(net "P5E_CPU1_PE0_TX_DN<9>")
	)
	(segment
		(start 64.968374 -351.436178)
		(end 66.665856 -399.930112)
		(width 0.14732)
		(layer "In15.Cu")
		(net "P5E_CPU1_PE0_TX_DN<9>")
	)
	(segment
		(start 94.160594 -210.722718)
		(end 86.930992 -210.722718)
		(width 0.14732)
		(layer "In15.Cu")
		(net "P5E_CPU1_PE0_TX_DN<9>")
	)
	(segment
		(start 67.903852 -325.807324)
		(end 64.669416 -333.616808)
		(width 0.14732)
		(layer "In15.Cu")
		(net "P5E_CPU1_PE0_TX_DN<9>")
	)
	(segment
		(start 97.347278 -219.18676)
		(end 97.356168 -219.18168)
		(width 0.0889)
		(layer "In15.Cu")
		(net "P5E_CPU1_PE0_TX_DN<9>")
	)
	(segment
		(start 97.356168 -219.830396)
		(end 97.347278 -219.825316)
		(width 0.0889)
		(layer "In15.Cu")
		(net "P5E_CPU1_PE0_TX_DN<9>")
	)
	(segment
		(start 97.356168 -216.574878)
		(end 97.347278 -216.569798)
		(width 0.0889)
		(layer "In15.Cu")
		(net "P5E_CPU1_PE0_TX_DN<9>")
	)
	(segment
		(start 86.930992 -210.722718)
		(end 83.012788 -212.845142)
		(width 0.14732)
		(layer "In15.Cu")
		(net "P5E_CPU1_PE0_TX_DN<9>")
	)
	(segment
		(start 96.878394 -215.756744)
		(end 96.877124 -215.755982)
		(width 0.0889)
		(layer "In15.Cu")
		(net "P5E_CPU1_PE0_TX_DN<9>")
	)
	(segment
		(start 97.168208 -214.644732)
		(end 97.168208 -214.424768)
		(width 0.0889)
		(layer "In15.Cu")
		(net "P5E_CPU1_PE0_TX_DN<9>")
	)
	(segment
		(start 96.698816 -213.186518)
		(end 96.740726 -213.144608)
		(width 0.0889)
		(layer "In15.Cu")
		(net "P5E_CPU1_PE0_TX_DN<9>")
	)
	(segment
		(start 96.888808 -215.762586)
		(end 96.886014 -215.761062)
		(width 0.0889)
		(layer "In15.Cu")
		(net "P5E_CPU1_PE0_TX_DN<9>")
	)
	(segment
		(start 98.295968 -224.065084)
		(end 98.302064 -224.061528)
		(width 0.0889)
		(layer "In15.Cu")
		(net "P5E_CPU1_PE0_TX_DN<9>")
	)
	(segment
		(start 96.885252 -215.760554)
		(end 96.882712 -215.75903)
		(width 0.0889)
		(layer "In15.Cu")
		(net "P5E_CPU1_PE0_TX_DN<9>")
	)
	(segment
		(start 98.483166 -224.389442)
		(end 98.63963 -224.66046)
		(width 0.0889)
		(layer "In15.Cu")
		(net "P5E_CPU1_PE0_TX_DN<9>")
	)
	(segment
		(start 75.587606 -221.782132)
		(end 73.849484 -232.977182)
		(width 0.14732)
		(layer "In15.Cu")
		(net "P5E_CPU1_PE0_TX_DN<9>")
	)
	(segment
		(start 97.638362 -221.94774)
		(end 97.638362 -221.932246)
		(width 0.0889)
		(layer "In15.Cu")
		(net "P5E_CPU1_PE0_TX_DN<9>")
	)
	(segment
		(start 96.509586 -212.138768)
		(end 95.75292 -211.382102)
		(width 0.14732)
		(layer "In15.Cu")
		(net "P5E_CPU1_PE0_TX_DN<9>")
	)
	(segment
		(start 83.012788 -212.845142)
		(end 77.622654 -217.833194)
		(width 0.14732)
		(layer "In15.Cu")
		(net "P5E_CPU1_PE0_TX_DN<9>")
	)
	(segment
		(start 96.740726 -213.144608)
		(end 96.740726 -213.12251)
		(width 0.0889)
		(layer "In15.Cu")
		(net "P5E_CPU1_PE0_TX_DN<9>")
	)
	(segment
		(start 98.295968 -224.7138)
		(end 98.287078 -224.70872)
		(width 0.0889)
		(layer "In15.Cu")
		(net "P5E_CPU1_PE0_TX_DN<9>")
	)
	(segment
		(start 96.740726 -213.12251)
		(end 96.740726 -212.69706)
		(width 0.14732)
		(layer "In15.Cu")
		(net "P5E_CPU1_PE0_TX_DN<9>")
	)
	(segment
		(start 96.698816 -213.893908)
		(end 96.698816 -213.186518)
		(width 0.0889)
		(layer "In15.Cu")
		(net "P5E_CPU1_PE0_TX_DN<9>")
	)
	(segment
		(start 64.669416 -333.616808)
		(end 64.365886 -335.313782)
		(width 0.14732)
		(layer "In15.Cu")
		(net "P5E_CPU1_PE0_TX_DN<9>")
	)
	(segment
		(start 96.89211 -215.764618)
		(end 96.888808 -215.762586)
		(width 0.0889)
		(layer "In15.Cu")
		(net "P5E_CPU1_PE0_TX_DN<9>")
	)
	(segment
		(start 95.75292 -211.382102)
		(end 94.160594 -210.722718)
		(width 0.14732)
		(layer "In15.Cu")
		(net "P5E_CPU1_PE0_TX_DN<9>")
	)
	(segment
		(start 64.646302 -346.407486)
		(end 64.968374 -351.436178)
		(width 0.14732)
		(layer "In15.Cu")
		(net "P5E_CPU1_PE0_TX_DN<9>")
	)
	(segment
		(start 96.877124 -215.117426)
		(end 96.886014 -215.112346)
		(width 0.0889)
		(layer "In15.Cu")
		(net "P5E_CPU1_PE0_TX_DN<9>")
	)
	(segment
		(start 72.320404 -252.766068)
		(end 75.932538 -309.54091)
		(width 0.14732)
		(layer "In15.Cu")
		(net "P5E_CPU1_PE0_TX_DN<9>")
	)
	(segment
		(start 96.886014 -215.761062)
		(end 96.885252 -215.760554)
		(width 0.0889)
		(layer "In15.Cu")
		(net "P5E_CPU1_PE0_TX_DN<9>")
	)
	(segment
		(start 73.84796 -232.98658)
		(end 72.403462 -250.17476)
		(width 0.14732)
		(layer "In15.Cu")
		(net "P5E_CPU1_PE0_TX_DN<9>")
	)
	(segment
		(start 96.740726 -212.69706)
		(end 96.509586 -212.138768)
		(width 0.14732)
		(layer "In15.Cu")
		(net "P5E_CPU1_PE0_TX_DN<9>")
	)
	(segment
		(start 97.347278 -217.559128)
		(end 97.356168 -217.554048)
		(width 0.0889)
		(layer "In15.Cu")
		(net "P5E_CPU1_PE0_TX_DN<9>")
	)
	(segment
		(start 97.347278 -220.814646)
		(end 97.356168 -220.809566)
		(width 0.0889)
		(layer "In15.Cu")
		(net "P5E_CPU1_PE0_TX_DN<9>")
	)
	(segment
		(start 98.578416 -223.575626)
		(end 98.578416 -223.561402)
		(width 0.0889)
		(layer "In15.Cu")
		(net "P5E_CPU1_PE0_TX_DN<9>")
	)
	(segment
		(start 97.83191 -222.275654)
		(end 97.816924 -222.267018)
		(width 0.0889)
		(layer "In15.Cu")
		(net "P5E_CPU1_PE0_TX_DN<9>")
	)
	(segment
		(start 73.849484 -232.977182)
		(end 73.84923 -232.977182)
		(width 0.14732)
		(layer "In15.Cu")
		(net "P5E_CPU1_PE0_TX_DN<9>")
	)
	(segment
		(start 97.356168 -218.202764)
		(end 97.347278 -218.197684)
		(width 0.0889)
		(layer "In15.Cu")
		(net "P5E_CPU1_PE0_TX_DN<9>")
	)
	(segment
		(start 98.295968 -223.085914)
		(end 98.287078 -223.080834)
		(width 0.0889)
		(layer "In15.Cu")
		(net "P5E_CPU1_PE0_TX_DN<9>")
	)
	(segment
		(start 66.665856 -399.930112)
		(end 66.665856 -400.55165)
		(width 0.14732)
		(layer "In15.Cu")
		(net "P5E_CPU1_PE0_TX_DN<9>")
	)
	(segment
		(start 97.638362 -218.707716)
		(end 97.638362 -218.676728)
		(width 0.0889)
		(layer "In15.Cu")
		(net "P5E_CPU1_PE0_TX_DN<9>")
	)
	(segment
		(start 97.356168 -221.458282)
		(end 97.347278 -221.453202)
		(width 0.0889)
		(layer "In15.Cu")
		(net "P5E_CPU1_PE0_TX_DN<9>")
	)
	(segment
		(start 75.932538 -309.54091)
		(end 71.533258 -320.020188)
		(width 0.14732)
		(layer "In15.Cu")
		(net "P5E_CPU1_PE0_TX_DN<9>")
	)
	(segment
		(start 96.881696 -215.758522)
		(end 96.880426 -215.75776)
		(width 0.0889)
		(layer "In15.Cu")
		(net "P5E_CPU1_PE0_TX_DN<9>")
	)
	(segment
		(start 98.63963 -224.66046)
		(end 98.618548 -224.738438)
		(width 0.0889)
		(layer "In15.Cu")
		(net "P5E_CPU1_PE0_TX_DN<9>")
	)
	(segment
		(start 96.882712 -215.75903)
		(end 96.881696 -215.758522)
		(width 0.0889)
		(layer "In15.Cu")
		(net "P5E_CPU1_PE0_TX_DN<9>")
	)
	(segment
		(start 96.880426 -215.75776)
		(end 96.878394 -215.756744)
		(width 0.0889)
		(layer "In15.Cu")
		(net "P5E_CPU1_PE0_TX_DN<9>")
	)
	(segment
		(start 98.10877 -222.751396)
		(end 98.108516 -222.761556)
		(width 0.0889)
		(layer "In15.Cu")
		(net "P5E_CPU1_PE0_TX_DN<9>")
	)
	(segment
		(start 77.622654 -217.833194)
		(end 75.587606 -221.782132)
		(width 0.14732)
		(layer "In15.Cu")
		(net "P5E_CPU1_PE0_TX_DN<9>")
	)
	(arc
		(start 96.882966 -214.093298)
		(mid 96.773819 -214.00937)
		(end 96.698816 -213.893908)
		(width 0.0889)
		(layer "In15.Cu")
		(net "P5E_CPU1_PE0_TX_DN<9>")
	)
	(arc
		(start 97.347278 -216.569798)
		(mid 97.216364 -216.433438)
		(end 97.168716 -216.25052)
		(width 0.0889)
		(layer "In15.Cu")
		(net "P5E_CPU1_PE0_TX_DN<9>")
	)
	(arc
		(start 97.16897 -217.866214)
		(mid 97.219441 -217.690206)
		(end 97.347278 -217.559128)
		(width 0.0889)
		(layer "In15.Cu")
		(net "P5E_CPU1_PE0_TX_DN<9>")
	)
	(arc
		(start 97.816924 -222.267018)
		(mid 97.68601 -222.130658)
		(end 97.638362 -221.94774)
		(width 0.0889)
		(layer "In15.Cu")
		(net "P5E_CPU1_PE0_TX_DN<9>")
	)
	(arc
		(start 96.877124 -215.755982)
		(mid 96.74621 -215.619622)
		(end 96.698562 -215.436704)
		(width 0.0889)
		(layer "In15.Cu")
		(net "P5E_CPU1_PE0_TX_DN<9>")
	)
	(arc
		(start 97.168716 -216.25052)
		(mid 97.094725 -215.970954)
		(end 96.89211 -215.764618)
		(width 0.0889)
		(layer "In15.Cu")
		(net "P5E_CPU1_PE0_TX_DN<9>")
	)
	(arc
		(start 97.168208 -214.424768)
		(mid 97.056929 -214.232062)
		(end 96.882966 -214.093298)
		(width 0.0889)
		(layer "In15.Cu")
		(net "P5E_CPU1_PE0_TX_DN<9>")
	)
	(arc
		(start 97.356168 -219.18168)
		(mid 97.558991 -218.981449)
		(end 97.638362 -218.707716)
		(width 0.0889)
		(layer "In15.Cu")
		(net "P5E_CPU1_PE0_TX_DN<9>")
	)
	(arc
		(start 96.698816 -215.421972)
		(mid 96.74987 -215.247392)
		(end 96.877124 -215.117426)
		(width 0.0889)
		(layer "In15.Cu")
		(net "P5E_CPU1_PE0_TX_DN<9>")
	)
	(arc
		(start 97.347278 -219.825316)
		(mid 97.168681 -219.506038)
		(end 97.347278 -219.18676)
		(width 0.0889)
		(layer "In15.Cu")
		(net "P5E_CPU1_PE0_TX_DN<9>")
	)
	(arc
		(start 97.638362 -221.932246)
		(mid 97.558992 -221.658512)
		(end 97.356168 -221.458282)
		(width 0.0889)
		(layer "In15.Cu")
		(net "P5E_CPU1_PE0_TX_DN<9>")
	)
	(arc
		(start 98.578416 -223.561402)
		(mid 98.499275 -223.286779)
		(end 98.295968 -223.085914)
		(width 0.0889)
		(layer "In15.Cu")
		(net "P5E_CPU1_PE0_TX_DN<9>")
	)
	(arc
		(start 97.16897 -217.888566)
		(mid 97.168803 -217.87739)
		(end 97.16897 -217.866214)
		(width 0.0889)
		(layer "In15.Cu")
		(net "P5E_CPU1_PE0_TX_DN<9>")
	)
	(arc
		(start 96.886014 -215.112346)
		(mid 97.087296 -214.914859)
		(end 97.168208 -214.644732)
		(width 0.0889)
		(layer "In15.Cu")
		(net "P5E_CPU1_PE0_TX_DN<9>")
	)
	(arc
		(start 97.347278 -221.453202)
		(mid 97.218959 -221.32123)
		(end 97.16897 -221.144084)
		(width 0.0889)
		(layer "In15.Cu")
		(net "P5E_CPU1_PE0_TX_DN<9>")
	)
	(arc
		(start 98.287078 -224.70872)
		(mid 98.108602 -224.389442)
		(end 98.287078 -224.070164)
		(width 0.0889)
		(layer "In15.Cu")
		(net "P5E_CPU1_PE0_TX_DN<9>")
	)
	(arc
		(start 97.347278 -218.197684)
		(mid 97.218959 -218.065712)
		(end 97.16897 -217.888566)
		(width 0.0889)
		(layer "In15.Cu")
		(net "P5E_CPU1_PE0_TX_DN<9>")
	)
	(arc
		(start 97.16897 -221.121732)
		(mid 97.219441 -220.945724)
		(end 97.347278 -220.814646)
		(width 0.0889)
		(layer "In15.Cu")
		(net "P5E_CPU1_PE0_TX_DN<9>")
	)
	(arc
		(start 98.109024 -222.776288)
		(mid 98.108691 -222.763844)
		(end 98.10877 -222.751396)
		(width 0.0889)
		(layer "In15.Cu")
		(net "P5E_CPU1_PE0_TX_DN<9>")
	)
	(arc
		(start 98.618548 -224.738438)
		(mid 98.454452 -224.762785)
		(end 98.295968 -224.7138)
		(width 0.0889)
		(layer "In15.Cu")
		(net "P5E_CPU1_PE0_TX_DN<9>")
	)
	(arc
		(start 98.302064 -224.061528)
		(mid 98.504477 -223.855115)
		(end 98.578416 -223.575626)
		(width 0.0889)
		(layer "In15.Cu")
		(net "P5E_CPU1_PE0_TX_DN<9>")
	)
	(arc
		(start 98.287078 -223.080834)
		(mid 98.159998 -222.95082)
		(end 98.109024 -222.776288)
		(width 0.0889)
		(layer "In15.Cu")
		(net "P5E_CPU1_PE0_TX_DN<9>")
	)
	(arc
		(start 97.638362 -218.676728)
		(mid 97.558992 -218.402994)
		(end 97.356168 -218.202764)
		(width 0.0889)
		(layer "In15.Cu")
		(net "P5E_CPU1_PE0_TX_DN<9>")
	)
	(arc
		(start 96.698562 -215.436704)
		(mid 96.698614 -215.429337)
		(end 96.698816 -215.421972)
		(width 0.0889)
		(layer "In15.Cu")
		(net "P5E_CPU1_PE0_TX_DN<9>")
	)
	(arc
		(start 97.356168 -217.554048)
		(mid 97.6387 -217.064527)
		(end 97.356168 -216.574878)
		(width 0.0889)
		(layer "In15.Cu")
		(net "P5E_CPU1_PE0_TX_DN<9>")
	)
	(arc
		(start 98.108516 -222.761556)
		(mid 98.034525 -222.48199)
		(end 97.83191 -222.275654)
		(width 0.0889)
		(layer "In15.Cu")
		(net "P5E_CPU1_PE0_TX_DN<9>")
	)
	(arc
		(start 97.356168 -220.809566)
		(mid 97.6387 -220.320045)
		(end 97.356168 -219.830396)
		(width 0.0889)
		(layer "In15.Cu")
		(net "P5E_CPU1_PE0_TX_DN<9>")
	)
	(arc
		(start 97.16897 -221.144084)
		(mid 97.168803 -221.132908)
		(end 97.16897 -221.121732)
		(width 0.0889)
		(layer "In15.Cu")
		(net "P5E_CPU1_PE0_TX_DN<9>")
	)
	(segment
		(start 69.72808 -401.777962)
		(end 69.72808 -401.16379)
		(width 0.13208)
		(layer "F.Cu")
		(net "P5E_CPU1_PE0_TX_DN<8>")
	)
	(segment
		(start 69.72808 -401.16379)
		(end 69.422518 -400.858228)
		(width 0.13208)
		(layer "F.Cu")
		(net "P5E_CPU1_PE0_TX_DN<8>")
	)
	(segment
		(start 69.397118 -402.104352)
		(end 69.40169 -402.104352)
		(width 0.13208)
		(layer "F.Cu")
		(net "P5E_CPU1_PE0_TX_DN<8>")
	)
	(segment
		(start 98.013012 -224.111312)
		(end 98.013012 -223.575626)
		(width 0.13208)
		(layer "F.Cu")
		(net "P5E_CPU1_PE0_TX_DN<8>")
	)
	(segment
		(start 69.40169 -402.104352)
		(end 69.72808 -401.777962)
		(width 0.13208)
		(layer "F.Cu")
		(net "P5E_CPU1_PE0_TX_DN<8>")
	)
	(segment
		(start 98.013266 -224.111566)
		(end 98.013012 -224.111312)
		(width 0.13208)
		(layer "F.Cu")
		(net "P5E_CPU1_PE0_TX_DN<8>")
	)
	(segment
		(start 69.717158 -400.563588)
		(end 69.422518 -400.858228)
		(width 0.14732)
		(layer "In15.Cu")
		(net "P5E_CPU1_PE0_TX_DN<8>")
	)
	(segment
		(start 95.758762 -213.893654)
		(end 95.759016 -213.8934)
		(width 0.0889)
		(layer "In15.Cu")
		(net "P5E_CPU1_PE0_TX_DN<8>")
	)
	(segment
		(start 95.759016 -213.8934)
		(end 95.759016 -213.186518)
		(width 0.0889)
		(layer "In15.Cu")
		(net "P5E_CPU1_PE0_TX_DN<8>")
	)
	(segment
		(start 97.856548 -223.846644)
		(end 97.77857 -223.867472)
		(width 0.0889)
		(layer "In15.Cu")
		(net "P5E_CPU1_PE0_TX_DN<8>")
	)
	(segment
		(start 96.407478 -220.814646)
		(end 96.416368 -220.809566)
		(width 0.0889)
		(layer "In15.Cu")
		(net "P5E_CPU1_PE0_TX_DN<8>")
	)
	(segment
		(start 77.44079 -220.361002)
		(end 77.440536 -220.361256)
		(width 0.14732)
		(layer "In15.Cu")
		(net "P5E_CPU1_PE0_TX_DN<8>")
	)
	(segment
		(start 95.95231 -215.764618)
		(end 95.949008 -215.762586)
		(width 0.0889)
		(layer "In15.Cu")
		(net "P5E_CPU1_PE0_TX_DN<8>")
	)
	(segment
		(start 77.440536 -220.361256)
		(end 76.465938 -222.252032)
		(width 0.14732)
		(layer "In15.Cu")
		(net "P5E_CPU1_PE0_TX_DN<8>")
	)
	(segment
		(start 65.605152 -334.082136)
		(end 65.354454 -335.214214)
		(width 0.14732)
		(layer "In15.Cu")
		(net "P5E_CPU1_PE0_TX_DN<8>")
	)
	(segment
		(start 96.422464 -219.833952)
		(end 96.416368 -219.830396)
		(width 0.0889)
		(layer "In15.Cu")
		(net "P5E_CPU1_PE0_TX_DN<8>")
	)
	(segment
		(start 87.225378 -211.652358)
		(end 83.498182 -213.67115)
		(width 0.14732)
		(layer "In15.Cu")
		(net "P5E_CPU1_PE0_TX_DN<8>")
	)
	(segment
		(start 65.763902 -348.903798)
		(end 65.914778 -351.441004)
		(width 0.14732)
		(layer "In15.Cu")
		(net "P5E_CPU1_PE0_TX_DN<8>")
	)
	(segment
		(start 83.498182 -213.67115)
		(end 78.416658 -218.46794)
		(width 0.14732)
		(layer "In15.Cu")
		(net "P5E_CPU1_PE0_TX_DN<8>")
	)
	(segment
		(start 96.422464 -216.578434)
		(end 96.416368 -216.574878)
		(width 0.0889)
		(layer "In15.Cu")
		(net "P5E_CPU1_PE0_TX_DN<8>")
	)
	(segment
		(start 73.305924 -252.67666)
		(end 76.923138 -309.685436)
		(width 0.14732)
		(layer "In15.Cu")
		(net "P5E_CPU1_PE0_TX_DN<8>")
	)
	(segment
		(start 95.945452 -215.760554)
		(end 95.942912 -215.75903)
		(width 0.0889)
		(layer "In15.Cu")
		(net "P5E_CPU1_PE0_TX_DN<8>")
	)
	(segment
		(start 73.382124 -250.220988)
		(end 73.34377 -251.356876)
		(width 0.14732)
		(layer "In15.Cu")
		(net "P5E_CPU1_PE0_TX_DN<8>")
	)
	(segment
		(start 95.800926 -213.12251)
		(end 95.800926 -212.768688)
		(width 0.14732)
		(layer "In15.Cu")
		(net "P5E_CPU1_PE0_TX_DN<8>")
	)
	(segment
		(start 97.356168 -223.085914)
		(end 97.347278 -223.080834)
		(width 0.0889)
		(layer "In15.Cu")
		(net "P5E_CPU1_PE0_TX_DN<8>")
	)
	(segment
		(start 76.923138 -309.685436)
		(end 72.314562 -320.583814)
		(width 0.14732)
		(layer "In15.Cu")
		(net "P5E_CPU1_PE0_TX_DN<8>")
	)
	(segment
		(start 95.941896 -215.758522)
		(end 95.940626 -215.75776)
		(width 0.0889)
		(layer "In15.Cu")
		(net "P5E_CPU1_PE0_TX_DN<8>")
	)
	(segment
		(start 69.717158 -399.672048)
		(end 69.717158 -400.563588)
		(width 0.14732)
		(layer "In15.Cu")
		(net "P5E_CPU1_PE0_TX_DN<8>")
	)
	(segment
		(start 96.416368 -221.458282)
		(end 96.407478 -221.453202)
		(width 0.0889)
		(layer "In15.Cu")
		(net "P5E_CPU1_PE0_TX_DN<8>")
	)
	(segment
		(start 95.800926 -212.768688)
		(end 95.228156 -212.195918)
		(width 0.14732)
		(layer "In15.Cu")
		(net "P5E_CPU1_PE0_TX_DN<8>")
	)
	(segment
		(start 95.938594 -215.756744)
		(end 95.937324 -215.755982)
		(width 0.0889)
		(layer "In15.Cu")
		(net "P5E_CPU1_PE0_TX_DN<8>")
	)
	(segment
		(start 65.354454 -335.214214)
		(end 65.763902 -348.903798)
		(width 0.14732)
		(layer "In15.Cu")
		(net "P5E_CPU1_PE0_TX_DN<8>")
	)
	(segment
		(start 72.314562 -320.583814)
		(end 68.894198 -326.141334)
		(width 0.14732)
		(layer "In15.Cu")
		(net "P5E_CPU1_PE0_TX_DN<8>")
	)
	(segment
		(start 73.305924 -252.490478)
		(end 73.305924 -252.67666)
		(width 0.14732)
		(layer "In15.Cu")
		(net "P5E_CPU1_PE0_TX_DN<8>")
	)
	(segment
		(start 96.407478 -219.18676)
		(end 96.415352 -219.182188)
		(width 0.0889)
		(layer "In15.Cu")
		(net "P5E_CPU1_PE0_TX_DN<8>")
	)
	(segment
		(start 96.698562 -218.707716)
		(end 96.698562 -218.676728)
		(width 0.0889)
		(layer "In15.Cu")
		(net "P5E_CPU1_PE0_TX_DN<8>")
	)
	(segment
		(start 73.34377 -251.356876)
		(end 73.305924 -252.490478)
		(width 0.14732)
		(layer "In15.Cu")
		(net "P5E_CPU1_PE0_TX_DN<8>")
	)
	(segment
		(start 95.937324 -215.117426)
		(end 95.946214 -215.112346)
		(width 0.0889)
		(layer "In15.Cu")
		(net "P5E_CPU1_PE0_TX_DN<8>")
	)
	(segment
		(start 97.16897 -222.751396)
		(end 97.168716 -222.761556)
		(width 0.0889)
		(layer "In15.Cu")
		(net "P5E_CPU1_PE0_TX_DN<8>")
	)
	(segment
		(start 96.407478 -217.559128)
		(end 96.416368 -217.554048)
		(width 0.0889)
		(layer "In15.Cu")
		(net "P5E_CPU1_PE0_TX_DN<8>")
	)
	(segment
		(start 95.946214 -215.761062)
		(end 95.945452 -215.760554)
		(width 0.0889)
		(layer "In15.Cu")
		(net "P5E_CPU1_PE0_TX_DN<8>")
	)
	(segment
		(start 97.638616 -223.584262)
		(end 97.638616 -223.557084)
		(width 0.0889)
		(layer "In15.Cu")
		(net "P5E_CPU1_PE0_TX_DN<8>")
	)
	(segment
		(start 96.416368 -218.202764)
		(end 96.407478 -218.197684)
		(width 0.0889)
		(layer "In15.Cu")
		(net "P5E_CPU1_PE0_TX_DN<8>")
	)
	(segment
		(start 96.415352 -219.182188)
		(end 96.416368 -219.18168)
		(width 0.0889)
		(layer "In15.Cu")
		(net "P5E_CPU1_PE0_TX_DN<8>")
	)
	(segment
		(start 95.949008 -215.762586)
		(end 95.946214 -215.761062)
		(width 0.0889)
		(layer "In15.Cu")
		(net "P5E_CPU1_PE0_TX_DN<8>")
	)
	(segment
		(start 74.776838 -233.130852)
		(end 73.382124 -250.220988)
		(width 0.14732)
		(layer "In15.Cu")
		(net "P5E_CPU1_PE0_TX_DN<8>")
	)
	(segment
		(start 76.465938 -222.252032)
		(end 74.776838 -233.130852)
		(width 0.14732)
		(layer "In15.Cu")
		(net "P5E_CPU1_PE0_TX_DN<8>")
	)
	(segment
		(start 95.759016 -213.186518)
		(end 95.800926 -213.144608)
		(width 0.0889)
		(layer "In15.Cu")
		(net "P5E_CPU1_PE0_TX_DN<8>")
	)
	(segment
		(start 96.89211 -222.275654)
		(end 96.877124 -222.267018)
		(width 0.0889)
		(layer "In15.Cu")
		(net "P5E_CPU1_PE0_TX_DN<8>")
	)
	(segment
		(start 96.698562 -221.94774)
		(end 96.698562 -221.932246)
		(width 0.0889)
		(layer "In15.Cu")
		(net "P5E_CPU1_PE0_TX_DN<8>")
	)
	(segment
		(start 93.915484 -211.652358)
		(end 87.225378 -211.652358)
		(width 0.14732)
		(layer "In15.Cu")
		(net "P5E_CPU1_PE0_TX_DN<8>")
	)
	(segment
		(start 95.942912 -215.75903)
		(end 95.941896 -215.758522)
		(width 0.0889)
		(layer "In15.Cu")
		(net "P5E_CPU1_PE0_TX_DN<8>")
	)
	(segment
		(start 68.894198 -326.141334)
		(end 65.605152 -334.082136)
		(width 0.14732)
		(layer "In15.Cu")
		(net "P5E_CPU1_PE0_TX_DN<8>")
	)
	(segment
		(start 78.416658 -218.46794)
		(end 77.44079 -220.361002)
		(width 0.14732)
		(layer "In15.Cu")
		(net "P5E_CPU1_PE0_TX_DN<8>")
	)
	(segment
		(start 65.914778 -351.441004)
		(end 69.717158 -399.672048)
		(width 0.14732)
		(layer "In15.Cu")
		(net "P5E_CPU1_PE0_TX_DN<8>")
	)
	(segment
		(start 96.228408 -214.644732)
		(end 96.228408 -214.424768)
		(width 0.0889)
		(layer "In15.Cu")
		(net "P5E_CPU1_PE0_TX_DN<8>")
	)
	(segment
		(start 96.416368 -216.574878)
		(end 96.407478 -216.569798)
		(width 0.0889)
		(layer "In15.Cu")
		(net "P5E_CPU1_PE0_TX_DN<8>")
	)
	(segment
		(start 95.940626 -215.75776)
		(end 95.938594 -215.756744)
		(width 0.0889)
		(layer "In15.Cu")
		(net "P5E_CPU1_PE0_TX_DN<8>")
	)
	(segment
		(start 95.759016 -213.893908)
		(end 95.758762 -213.893654)
		(width 0.0889)
		(layer "In15.Cu")
		(net "P5E_CPU1_PE0_TX_DN<8>")
	)
	(segment
		(start 95.800926 -213.144608)
		(end 95.800926 -213.12251)
		(width 0.0889)
		(layer "In15.Cu")
		(net "P5E_CPU1_PE0_TX_DN<8>")
	)
	(segment
		(start 98.013012 -223.575626)
		(end 97.856548 -223.846644)
		(width 0.0889)
		(layer "In15.Cu")
		(net "P5E_CPU1_PE0_TX_DN<8>")
	)
	(segment
		(start 96.416368 -219.830396)
		(end 96.407478 -219.825316)
		(width 0.0889)
		(layer "In15.Cu")
		(net "P5E_CPU1_PE0_TX_DN<8>")
	)
	(segment
		(start 95.228156 -212.195918)
		(end 93.915484 -211.652358)
		(width 0.14732)
		(layer "In15.Cu")
		(net "P5E_CPU1_PE0_TX_DN<8>")
	)
	(arc
		(start 96.877124 -222.267018)
		(mid 96.74621 -222.130658)
		(end 96.698562 -221.94774)
		(width 0.0889)
		(layer "In15.Cu")
		(net "P5E_CPU1_PE0_TX_DN<8>")
	)
	(arc
		(start 96.407478 -221.453202)
		(mid 96.279074 -221.321257)
		(end 96.228916 -221.144084)
		(width 0.0889)
		(layer "In15.Cu")
		(net "P5E_CPU1_PE0_TX_DN<8>")
	)
	(arc
		(start 96.416368 -217.554048)
		(mid 96.698982 -217.06793)
		(end 96.422464 -216.578434)
		(width 0.0889)
		(layer "In15.Cu")
		(net "P5E_CPU1_PE0_TX_DN<8>")
	)
	(arc
		(start 97.168716 -222.761556)
		(mid 97.094725 -222.48199)
		(end 96.89211 -222.275654)
		(width 0.0889)
		(layer "In15.Cu")
		(net "P5E_CPU1_PE0_TX_DN<8>")
	)
	(arc
		(start 96.22917 -221.119192)
		(mid 96.280224 -220.944612)
		(end 96.407478 -220.814646)
		(width 0.0889)
		(layer "In15.Cu")
		(net "P5E_CPU1_PE0_TX_DN<8>")
	)
	(arc
		(start 96.228408 -214.424768)
		(mid 96.117129 -214.232062)
		(end 95.943166 -214.093298)
		(width 0.0889)
		(layer "In15.Cu")
		(net "P5E_CPU1_PE0_TX_DN<8>")
	)
	(arc
		(start 97.16897 -222.773748)
		(mid 97.168803 -222.762572)
		(end 97.16897 -222.751396)
		(width 0.0889)
		(layer "In15.Cu")
		(net "P5E_CPU1_PE0_TX_DN<8>")
	)
	(arc
		(start 95.943166 -214.093298)
		(mid 95.834019 -214.00937)
		(end 95.759016 -213.893908)
		(width 0.0889)
		(layer "In15.Cu")
		(net "P5E_CPU1_PE0_TX_DN<8>")
	)
	(arc
		(start 96.407478 -218.197684)
		(mid 96.279074 -218.065739)
		(end 96.228916 -217.888566)
		(width 0.0889)
		(layer "In15.Cu")
		(net "P5E_CPU1_PE0_TX_DN<8>")
	)
	(arc
		(start 96.698562 -218.676728)
		(mid 96.619192 -218.402994)
		(end 96.416368 -218.202764)
		(width 0.0889)
		(layer "In15.Cu")
		(net "P5E_CPU1_PE0_TX_DN<8>")
	)
	(arc
		(start 97.347278 -223.080834)
		(mid 97.219385 -222.949772)
		(end 97.16897 -222.773748)
		(width 0.0889)
		(layer "In15.Cu")
		(net "P5E_CPU1_PE0_TX_DN<8>")
	)
	(arc
		(start 96.228916 -217.888566)
		(mid 96.228836 -217.876118)
		(end 96.22917 -217.863674)
		(width 0.0889)
		(layer "In15.Cu")
		(net "P5E_CPU1_PE0_TX_DN<8>")
	)
	(arc
		(start 96.416368 -220.809566)
		(mid 96.698982 -220.323448)
		(end 96.422464 -219.833952)
		(width 0.0889)
		(layer "In15.Cu")
		(net "P5E_CPU1_PE0_TX_DN<8>")
	)
	(arc
		(start 96.698562 -221.932246)
		(mid 96.619192 -221.658512)
		(end 96.416368 -221.458282)
		(width 0.0889)
		(layer "In15.Cu")
		(net "P5E_CPU1_PE0_TX_DN<8>")
	)
	(arc
		(start 96.407478 -219.825316)
		(mid 96.229002 -219.506038)
		(end 96.407478 -219.18676)
		(width 0.0889)
		(layer "In15.Cu")
		(net "P5E_CPU1_PE0_TX_DN<8>")
	)
	(arc
		(start 95.759016 -215.421972)
		(mid 95.81007 -215.247392)
		(end 95.937324 -215.117426)
		(width 0.0889)
		(layer "In15.Cu")
		(net "P5E_CPU1_PE0_TX_DN<8>")
	)
	(arc
		(start 95.946214 -215.112346)
		(mid 96.147496 -214.914859)
		(end 96.228408 -214.644732)
		(width 0.0889)
		(layer "In15.Cu")
		(net "P5E_CPU1_PE0_TX_DN<8>")
	)
	(arc
		(start 96.228916 -216.25052)
		(mid 96.154925 -215.970954)
		(end 95.95231 -215.764618)
		(width 0.0889)
		(layer "In15.Cu")
		(net "P5E_CPU1_PE0_TX_DN<8>")
	)
	(arc
		(start 96.228916 -221.144084)
		(mid 96.228836 -221.131636)
		(end 96.22917 -221.119192)
		(width 0.0889)
		(layer "In15.Cu")
		(net "P5E_CPU1_PE0_TX_DN<8>")
	)
	(arc
		(start 95.758762 -215.436704)
		(mid 95.758814 -215.429337)
		(end 95.759016 -215.421972)
		(width 0.0889)
		(layer "In15.Cu")
		(net "P5E_CPU1_PE0_TX_DN<8>")
	)
	(arc
		(start 96.22917 -217.863674)
		(mid 96.280224 -217.689094)
		(end 96.407478 -217.559128)
		(width 0.0889)
		(layer "In15.Cu")
		(net "P5E_CPU1_PE0_TX_DN<8>")
	)
	(arc
		(start 95.937324 -215.755982)
		(mid 95.80641 -215.619622)
		(end 95.758762 -215.436704)
		(width 0.0889)
		(layer "In15.Cu")
		(net "P5E_CPU1_PE0_TX_DN<8>")
	)
	(arc
		(start 97.638616 -223.557084)
		(mid 97.558454 -223.284895)
		(end 97.356168 -223.085914)
		(width 0.0889)
		(layer "In15.Cu")
		(net "P5E_CPU1_PE0_TX_DN<8>")
	)
	(arc
		(start 96.407478 -216.569798)
		(mid 96.276564 -216.433438)
		(end 96.228916 -216.25052)
		(width 0.0889)
		(layer "In15.Cu")
		(net "P5E_CPU1_PE0_TX_DN<8>")
	)
	(arc
		(start 97.77857 -223.867472)
		(mid 97.677249 -223.741351)
		(end 97.638616 -223.584262)
		(width 0.0889)
		(layer "In15.Cu")
		(net "P5E_CPU1_PE0_TX_DN<8>")
	)
	(arc
		(start 96.416368 -219.18168)
		(mid 96.619191 -218.981449)
		(end 96.698562 -218.707716)
		(width 0.0889)
		(layer "In15.Cu")
		(net "P5E_CPU1_PE0_TX_DN<8>")
	)
	(segment
		(start 72.460358 -402.104352)
		(end 72.46493 -402.104352)
		(width 0.13208)
		(layer "F.Cu")
		(net "P5E_CPU1_PE0_TX_DN<7>")
	)
	(segment
		(start 72.79132 -401.777962)
		(end 72.79132 -401.16379)
		(width 0.13208)
		(layer "F.Cu")
		(net "P5E_CPU1_PE0_TX_DN<7>")
	)
	(segment
		(start 72.46493 -402.104352)
		(end 72.79132 -401.777962)
		(width 0.13208)
		(layer "F.Cu")
		(net "P5E_CPU1_PE0_TX_DN<7>")
	)
	(segment
		(start 96.603312 -224.925382)
		(end 96.603566 -224.925128)
		(width 0.13208)
		(layer "F.Cu")
		(net "P5E_CPU1_PE0_TX_DN<7>")
	)
	(segment
		(start 72.79132 -401.16379)
		(end 72.485758 -400.858228)
		(width 0.13208)
		(layer "F.Cu")
		(net "P5E_CPU1_PE0_TX_DN<7>")
	)
	(segment
		(start 96.603566 -224.925128)
		(end 96.603566 -224.389442)
		(width 0.13208)
		(layer "F.Cu")
		(net "P5E_CPU1_PE0_TX_DN<7>")
	)
	(segment
		(start 94.818962 -215.436704)
		(end 94.818962 -215.42248)
		(width 0.0889)
		(layer "In15.Cu")
		(net "P5E_CPU1_PE0_TX_DN<7>")
	)
	(segment
		(start 95.009208 -215.762586)
		(end 95.006414 -215.761062)
		(width 0.0889)
		(layer "In15.Cu")
		(net "P5E_CPU1_PE0_TX_DN<7>")
	)
	(segment
		(start 95.000826 -215.75776)
		(end 94.998794 -215.756744)
		(width 0.0889)
		(layer "In15.Cu")
		(net "P5E_CPU1_PE0_TX_DN<7>")
	)
	(segment
		(start 95.476568 -216.574878)
		(end 95.467678 -216.569798)
		(width 0.0889)
		(layer "In15.Cu")
		(net "P5E_CPU1_PE0_TX_DN<7>")
	)
	(segment
		(start 93.921326 -212.86216)
		(end 93.641164 -212.581998)
		(width 0.14732)
		(layer "In15.Cu")
		(net "P5E_CPU1_PE0_TX_DN<7>")
	)
	(segment
		(start 72.780398 -400.563588)
		(end 72.485758 -400.858228)
		(width 0.14732)
		(layer "In15.Cu")
		(net "P5E_CPU1_PE0_TX_DN<7>")
	)
	(segment
		(start 94.348808 -214.622634)
		(end 94.348808 -214.424768)
		(width 0.0889)
		(layer "In15.Cu")
		(net "P5E_CPU1_PE0_TX_DN<7>")
	)
	(segment
		(start 87.931498 -212.581998)
		(end 83.515962 -214.973662)
		(width 0.14732)
		(layer "In15.Cu")
		(net "P5E_CPU1_PE0_TX_DN<7>")
	)
	(segment
		(start 83.515962 -214.973662)
		(end 79.105506 -219.16771)
		(width 0.14732)
		(layer "In15.Cu")
		(net "P5E_CPU1_PE0_TX_DN<7>")
	)
	(segment
		(start 95.946214 -222.272098)
		(end 95.94469 -222.271336)
		(width 0.0889)
		(layer "In15.Cu")
		(net "P5E_CPU1_PE0_TX_DN<7>")
	)
	(segment
		(start 66.929508 -352.30054)
		(end 72.780398 -399.885408)
		(width 0.14732)
		(layer "In15.Cu")
		(net "P5E_CPU1_PE0_TX_DN<7>")
	)
	(segment
		(start 95.467678 -220.814646)
		(end 95.476568 -220.809566)
		(width 0.0889)
		(layer "In15.Cu")
		(net "P5E_CPU1_PE0_TX_DN<7>")
	)
	(segment
		(start 96.76003 -224.66046)
		(end 96.738948 -224.738438)
		(width 0.0889)
		(layer "In15.Cu")
		(net "P5E_CPU1_PE0_TX_DN<7>")
	)
	(segment
		(start 93.879416 -213.214458)
		(end 93.921326 -213.172548)
		(width 0.0889)
		(layer "In15.Cu")
		(net "P5E_CPU1_PE0_TX_DN<7>")
	)
	(segment
		(start 93.879416 -213.893908)
		(end 93.879416 -213.214458)
		(width 0.0889)
		(layer "In15.Cu")
		(net "P5E_CPU1_PE0_TX_DN<7>")
	)
	(segment
		(start 95.949008 -222.273622)
		(end 95.946214 -222.272098)
		(width 0.0889)
		(layer "In15.Cu")
		(net "P5E_CPU1_PE0_TX_DN<7>")
	)
	(segment
		(start 79.105506 -219.16771)
		(end 77.48397 -222.3135)
		(width 0.14732)
		(layer "In15.Cu")
		(net "P5E_CPU1_PE0_TX_DN<7>")
	)
	(segment
		(start 95.006414 -215.761062)
		(end 95.005652 -215.760554)
		(width 0.0889)
		(layer "In15.Cu")
		(net "P5E_CPU1_PE0_TX_DN<7>")
	)
	(segment
		(start 74.24039 -252.402848)
		(end 77.987398 -309.669434)
		(width 0.14732)
		(layer "In15.Cu")
		(net "P5E_CPU1_PE0_TX_DN<7>")
	)
	(segment
		(start 69.709792 -326.64273)
		(end 66.645282 -334.041496)
		(width 0.14732)
		(layer "In15.Cu")
		(net "P5E_CPU1_PE0_TX_DN<7>")
	)
	(segment
		(start 94.53626 -214.946992)
		(end 94.52737 -214.941912)
		(width 0.0889)
		(layer "In15.Cu")
		(net "P5E_CPU1_PE0_TX_DN<7>")
	)
	(segment
		(start 95.94469 -222.271336)
		(end 95.937324 -222.267018)
		(width 0.0889)
		(layer "In15.Cu")
		(net "P5E_CPU1_PE0_TX_DN<7>")
	)
	(segment
		(start 95.95231 -222.275654)
		(end 95.949008 -222.273622)
		(width 0.0889)
		(layer "In15.Cu")
		(net "P5E_CPU1_PE0_TX_DN<7>")
	)
	(segment
		(start 96.603566 -224.389442)
		(end 96.76003 -224.66046)
		(width 0.0889)
		(layer "In15.Cu")
		(net "P5E_CPU1_PE0_TX_DN<7>")
	)
	(segment
		(start 96.416368 -223.085914)
		(end 96.407478 -223.080834)
		(width 0.0889)
		(layer "In15.Cu")
		(net "P5E_CPU1_PE0_TX_DN<7>")
	)
	(segment
		(start 77.48397 -222.3135)
		(end 75.806554 -233.117898)
		(width 0.14732)
		(layer "In15.Cu")
		(net "P5E_CPU1_PE0_TX_DN<7>")
	)
	(segment
		(start 75.806554 -233.117898)
		(end 74.305922 -250.457716)
		(width 0.14732)
		(layer "In15.Cu")
		(net "P5E_CPU1_PE0_TX_DN<7>")
	)
	(segment
		(start 95.758762 -218.707716)
		(end 95.758762 -218.676728)
		(width 0.0889)
		(layer "In15.Cu")
		(net "P5E_CPU1_PE0_TX_DN<7>")
	)
	(segment
		(start 66.505074 -334.84566)
		(end 66.50482 -334.84566)
		(width 0.14732)
		(layer "In15.Cu")
		(net "P5E_CPU1_PE0_TX_DN<7>")
	)
	(segment
		(start 95.476568 -221.458282)
		(end 95.467678 -221.453202)
		(width 0.0889)
		(layer "In15.Cu")
		(net "P5E_CPU1_PE0_TX_DN<7>")
	)
	(segment
		(start 66.500248 -334.872584)
		(end 66.929508 -352.30054)
		(width 0.14732)
		(layer "In15.Cu")
		(net "P5E_CPU1_PE0_TX_DN<7>")
	)
	(segment
		(start 95.476568 -219.830396)
		(end 95.467678 -219.825316)
		(width 0.0889)
		(layer "In15.Cu")
		(net "P5E_CPU1_PE0_TX_DN<7>")
	)
	(segment
		(start 93.921326 -213.172548)
		(end 93.921326 -213.15045)
		(width 0.0889)
		(layer "In15.Cu")
		(net "P5E_CPU1_PE0_TX_DN<7>")
	)
	(segment
		(start 95.005652 -215.760554)
		(end 95.003112 -215.75903)
		(width 0.0889)
		(layer "In15.Cu")
		(net "P5E_CPU1_PE0_TX_DN<7>")
	)
	(segment
		(start 96.698816 -223.575626)
		(end 96.698816 -223.561402)
		(width 0.0889)
		(layer "In15.Cu")
		(net "P5E_CPU1_PE0_TX_DN<7>")
	)
	(segment
		(start 66.50482 -334.84566)
		(end 66.500248 -334.872584)
		(width 0.14732)
		(layer "In15.Cu")
		(net "P5E_CPU1_PE0_TX_DN<7>")
	)
	(segment
		(start 95.01251 -215.764618)
		(end 95.009208 -215.762586)
		(width 0.0889)
		(layer "In15.Cu")
		(net "P5E_CPU1_PE0_TX_DN<7>")
	)
	(segment
		(start 66.645282 -334.041496)
		(end 66.505074 -334.84566)
		(width 0.14732)
		(layer "In15.Cu")
		(net "P5E_CPU1_PE0_TX_DN<7>")
	)
	(segment
		(start 93.921326 -213.15045)
		(end 93.921326 -212.86216)
		(width 0.14732)
		(layer "In15.Cu")
		(net "P5E_CPU1_PE0_TX_DN<7>")
	)
	(segment
		(start 77.987398 -309.669434)
		(end 73.20153 -320.990976)
		(width 0.14732)
		(layer "In15.Cu")
		(net "P5E_CPU1_PE0_TX_DN<7>")
	)
	(segment
		(start 96.416368 -224.7138)
		(end 96.407478 -224.70872)
		(width 0.0889)
		(layer "In15.Cu")
		(net "P5E_CPU1_PE0_TX_DN<7>")
	)
	(segment
		(start 95.467678 -217.559128)
		(end 95.476568 -217.554048)
		(width 0.0889)
		(layer "In15.Cu")
		(net "P5E_CPU1_PE0_TX_DN<7>")
	)
	(segment
		(start 96.22917 -222.751396)
		(end 96.228916 -222.761556)
		(width 0.0889)
		(layer "In15.Cu")
		(net "P5E_CPU1_PE0_TX_DN<7>")
	)
	(segment
		(start 93.641164 -212.581998)
		(end 87.931498 -212.581998)
		(width 0.14732)
		(layer "In15.Cu")
		(net "P5E_CPU1_PE0_TX_DN<7>")
	)
	(segment
		(start 95.002096 -215.758522)
		(end 95.000826 -215.75776)
		(width 0.0889)
		(layer "In15.Cu")
		(net "P5E_CPU1_PE0_TX_DN<7>")
	)
	(segment
		(start 94.998794 -215.756744)
		(end 94.997524 -215.755982)
		(width 0.0889)
		(layer "In15.Cu")
		(net "P5E_CPU1_PE0_TX_DN<7>")
	)
	(segment
		(start 73.20153 -320.990976)
		(end 69.709792 -326.64273)
		(width 0.14732)
		(layer "In15.Cu")
		(net "P5E_CPU1_PE0_TX_DN<7>")
	)
	(segment
		(start 95.476568 -218.202764)
		(end 95.467678 -218.197684)
		(width 0.0889)
		(layer "In15.Cu")
		(net "P5E_CPU1_PE0_TX_DN<7>")
	)
	(segment
		(start 95.758762 -221.94774)
		(end 95.758762 -221.932246)
		(width 0.0889)
		(layer "In15.Cu")
		(net "P5E_CPU1_PE0_TX_DN<7>")
	)
	(segment
		(start 96.407478 -224.070164)
		(end 96.416368 -224.065084)
		(width 0.0889)
		(layer "In15.Cu")
		(net "P5E_CPU1_PE0_TX_DN<7>")
	)
	(segment
		(start 96.416368 -224.065084)
		(end 96.422464 -224.061528)
		(width 0.0889)
		(layer "In15.Cu")
		(net "P5E_CPU1_PE0_TX_DN<7>")
	)
	(segment
		(start 74.305922 -250.457716)
		(end 74.24039 -252.402848)
		(width 0.14732)
		(layer "In15.Cu")
		(net "P5E_CPU1_PE0_TX_DN<7>")
	)
	(segment
		(start 95.003112 -215.75903)
		(end 95.002096 -215.758522)
		(width 0.0889)
		(layer "In15.Cu")
		(net "P5E_CPU1_PE0_TX_DN<7>")
	)
	(segment
		(start 95.467678 -219.18676)
		(end 95.476568 -219.18168)
		(width 0.0889)
		(layer "In15.Cu")
		(net "P5E_CPU1_PE0_TX_DN<7>")
	)
	(segment
		(start 72.780398 -399.885408)
		(end 72.780398 -400.563588)
		(width 0.14732)
		(layer "In15.Cu")
		(net "P5E_CPU1_PE0_TX_DN<7>")
	)
	(arc
		(start 94.52737 -214.941912)
		(mid 94.396456 -214.805552)
		(end 94.348808 -214.622634)
		(width 0.0889)
		(layer "In15.Cu")
		(net "P5E_CPU1_PE0_TX_DN<7>")
	)
	(arc
		(start 95.467678 -219.825316)
		(mid 95.289081 -219.506038)
		(end 95.467678 -219.18676)
		(width 0.0889)
		(layer "In15.Cu")
		(net "P5E_CPU1_PE0_TX_DN<7>")
	)
	(arc
		(start 95.937324 -222.267018)
		(mid 95.80641 -222.130658)
		(end 95.758762 -221.94774)
		(width 0.0889)
		(layer "In15.Cu")
		(net "P5E_CPU1_PE0_TX_DN<7>")
	)
	(arc
		(start 95.28937 -221.144084)
		(mid 95.289203 -221.132908)
		(end 95.28937 -221.121732)
		(width 0.0889)
		(layer "In15.Cu")
		(net "P5E_CPU1_PE0_TX_DN<7>")
	)
	(arc
		(start 94.063566 -214.093298)
		(mid 93.954419 -214.00937)
		(end 93.879416 -213.893908)
		(width 0.0889)
		(layer "In15.Cu")
		(net "P5E_CPU1_PE0_TX_DN<7>")
	)
	(arc
		(start 95.28937 -217.866214)
		(mid 95.339841 -217.690206)
		(end 95.467678 -217.559128)
		(width 0.0889)
		(layer "In15.Cu")
		(net "P5E_CPU1_PE0_TX_DN<7>")
	)
	(arc
		(start 94.997524 -215.755982)
		(mid 94.86661 -215.619622)
		(end 94.818962 -215.436704)
		(width 0.0889)
		(layer "In15.Cu")
		(net "P5E_CPU1_PE0_TX_DN<7>")
	)
	(arc
		(start 96.698816 -223.561402)
		(mid 96.619675 -223.286779)
		(end 96.416368 -223.085914)
		(width 0.0889)
		(layer "In15.Cu")
		(net "P5E_CPU1_PE0_TX_DN<7>")
	)
	(arc
		(start 96.229424 -222.776288)
		(mid 96.229091 -222.763844)
		(end 96.22917 -222.751396)
		(width 0.0889)
		(layer "In15.Cu")
		(net "P5E_CPU1_PE0_TX_DN<7>")
	)
	(arc
		(start 94.818962 -215.42248)
		(mid 94.739743 -215.147795)
		(end 94.53626 -214.946992)
		(width 0.0889)
		(layer "In15.Cu")
		(net "P5E_CPU1_PE0_TX_DN<7>")
	)
	(arc
		(start 95.467678 -221.453202)
		(mid 95.339359 -221.32123)
		(end 95.28937 -221.144084)
		(width 0.0889)
		(layer "In15.Cu")
		(net "P5E_CPU1_PE0_TX_DN<7>")
	)
	(arc
		(start 96.407478 -224.70872)
		(mid 96.229002 -224.389442)
		(end 96.407478 -224.070164)
		(width 0.0889)
		(layer "In15.Cu")
		(net "P5E_CPU1_PE0_TX_DN<7>")
	)
	(arc
		(start 95.476568 -219.18168)
		(mid 95.679391 -218.981449)
		(end 95.758762 -218.707716)
		(width 0.0889)
		(layer "In15.Cu")
		(net "P5E_CPU1_PE0_TX_DN<7>")
	)
	(arc
		(start 94.348808 -214.424768)
		(mid 94.237529 -214.232062)
		(end 94.063566 -214.093298)
		(width 0.0889)
		(layer "In15.Cu")
		(net "P5E_CPU1_PE0_TX_DN<7>")
	)
	(arc
		(start 95.476568 -220.809566)
		(mid 95.7591 -220.320045)
		(end 95.476568 -219.830396)
		(width 0.0889)
		(layer "In15.Cu")
		(net "P5E_CPU1_PE0_TX_DN<7>")
	)
	(arc
		(start 95.289116 -216.25052)
		(mid 95.215125 -215.970954)
		(end 95.01251 -215.764618)
		(width 0.0889)
		(layer "In15.Cu")
		(net "P5E_CPU1_PE0_TX_DN<7>")
	)
	(arc
		(start 95.476568 -217.554048)
		(mid 95.7591 -217.064527)
		(end 95.476568 -216.574878)
		(width 0.0889)
		(layer "In15.Cu")
		(net "P5E_CPU1_PE0_TX_DN<7>")
	)
	(arc
		(start 95.28937 -221.121732)
		(mid 95.339841 -220.945724)
		(end 95.467678 -220.814646)
		(width 0.0889)
		(layer "In15.Cu")
		(net "P5E_CPU1_PE0_TX_DN<7>")
	)
	(arc
		(start 95.758762 -221.932246)
		(mid 95.679392 -221.658512)
		(end 95.476568 -221.458282)
		(width 0.0889)
		(layer "In15.Cu")
		(net "P5E_CPU1_PE0_TX_DN<7>")
	)
	(arc
		(start 96.738948 -224.738438)
		(mid 96.574852 -224.762785)
		(end 96.416368 -224.7138)
		(width 0.0889)
		(layer "In15.Cu")
		(net "P5E_CPU1_PE0_TX_DN<7>")
	)
	(arc
		(start 96.407478 -223.080834)
		(mid 96.280398 -222.95082)
		(end 96.229424 -222.776288)
		(width 0.0889)
		(layer "In15.Cu")
		(net "P5E_CPU1_PE0_TX_DN<7>")
	)
	(arc
		(start 95.758762 -218.676728)
		(mid 95.679392 -218.402994)
		(end 95.476568 -218.202764)
		(width 0.0889)
		(layer "In15.Cu")
		(net "P5E_CPU1_PE0_TX_DN<7>")
	)
	(arc
		(start 95.28937 -217.888566)
		(mid 95.289203 -217.87739)
		(end 95.28937 -217.866214)
		(width 0.0889)
		(layer "In15.Cu")
		(net "P5E_CPU1_PE0_TX_DN<7>")
	)
	(arc
		(start 96.228916 -222.761556)
		(mid 96.154925 -222.48199)
		(end 95.95231 -222.275654)
		(width 0.0889)
		(layer "In15.Cu")
		(net "P5E_CPU1_PE0_TX_DN<7>")
	)
	(arc
		(start 95.467678 -218.197684)
		(mid 95.339359 -218.065712)
		(end 95.28937 -217.888566)
		(width 0.0889)
		(layer "In15.Cu")
		(net "P5E_CPU1_PE0_TX_DN<7>")
	)
	(arc
		(start 95.467678 -216.569798)
		(mid 95.336764 -216.433438)
		(end 95.289116 -216.25052)
		(width 0.0889)
		(layer "In15.Cu")
		(net "P5E_CPU1_PE0_TX_DN<7>")
	)
	(arc
		(start 96.422464 -224.061528)
		(mid 96.624877 -223.855115)
		(end 96.698816 -223.575626)
		(width 0.0889)
		(layer "In15.Cu")
		(net "P5E_CPU1_PE0_TX_DN<7>")
	)
	(segment
		(start 96.133666 -224.111566)
		(end 96.133666 -223.57588)
		(width 0.13208)
		(layer "F.Cu")
		(net "P5E_CPU1_PE0_TX_DN<6>")
	)
	(segment
		(start 96.133666 -223.57588)
		(end 96.133412 -223.575626)
		(width 0.13208)
		(layer "F.Cu")
		(net "P5E_CPU1_PE0_TX_DN<6>")
	)
	(segment
		(start 75.523598 -402.104352)
		(end 75.52817 -402.104352)
		(width 0.13208)
		(layer "F.Cu")
		(net "P5E_CPU1_PE0_TX_DN<6>")
	)
	(segment
		(start 75.52817 -402.104352)
		(end 75.85456 -401.777962)
		(width 0.13208)
		(layer "F.Cu")
		(net "P5E_CPU1_PE0_TX_DN<6>")
	)
	(segment
		(start 75.85456 -401.777962)
		(end 75.85456 -401.16379)
		(width 0.13208)
		(layer "F.Cu")
		(net "P5E_CPU1_PE0_TX_DN<6>")
	)
	(segment
		(start 75.85456 -401.16379)
		(end 75.548998 -400.858228)
		(width 0.13208)
		(layer "F.Cu")
		(net "P5E_CPU1_PE0_TX_DN<6>")
	)
	(segment
		(start 90.589608 -214.622634)
		(end 90.589608 -214.424768)
		(width 0.0889)
		(layer "In15.Cu")
		(net "P5E_CPU1_PE0_TX_DN<6>")
	)
	(segment
		(start 95.28937 -222.751396)
		(end 95.289116 -222.761556)
		(width 0.0889)
		(layer "In15.Cu")
		(net "P5E_CPU1_PE0_TX_DN<6>")
	)
	(segment
		(start 94.527878 -220.814646)
		(end 94.536768 -220.809566)
		(width 0.0889)
		(layer "In15.Cu")
		(net "P5E_CPU1_PE0_TX_DN<6>")
	)
	(segment
		(start 84.029296 -215.851232)
		(end 79.86395 -219.746576)
		(width 0.14732)
		(layer "In15.Cu")
		(net "P5E_CPU1_PE0_TX_DN<6>")
	)
	(segment
		(start 79.86395 -219.746576)
		(end 78.386686 -222.611696)
		(width 0.14732)
		(layer "In15.Cu")
		(net "P5E_CPU1_PE0_TX_DN<6>")
	)
	(segment
		(start 75.186286 -251.942854)
		(end 78.954884 -309.83555)
		(width 0.14732)
		(layer "In15.Cu")
		(net "P5E_CPU1_PE0_TX_DN<6>")
	)
	(segment
		(start 95.976948 -223.846644)
		(end 95.89897 -223.867472)
		(width 0.0889)
		(layer "In15.Cu")
		(net "P5E_CPU1_PE0_TX_DN<6>")
	)
	(segment
		(start 67.46367 -335.340198)
		(end 67.901058 -352.193352)
		(width 0.14732)
		(layer "In15.Cu")
		(net "P5E_CPU1_PE0_TX_DN<6>")
	)
	(segment
		(start 78.954884 -309.83555)
		(end 73.875646 -321.813174)
		(width 0.14732)
		(layer "In15.Cu")
		(net "P5E_CPU1_PE0_TX_DN<6>")
	)
	(segment
		(start 96.133412 -223.575626)
		(end 95.976948 -223.846644)
		(width 0.0889)
		(layer "In15.Cu")
		(net "P5E_CPU1_PE0_TX_DN<6>")
	)
	(segment
		(start 94.527878 -219.18676)
		(end 94.536768 -219.18168)
		(width 0.0889)
		(layer "In15.Cu")
		(net "P5E_CPU1_PE0_TX_DN<6>")
	)
	(segment
		(start 94.527878 -217.559128)
		(end 94.536768 -217.554048)
		(width 0.0889)
		(layer "In15.Cu")
		(net "P5E_CPU1_PE0_TX_DN<6>")
	)
	(segment
		(start 91.247214 -215.761062)
		(end 91.24569 -215.7603)
		(width 0.0889)
		(layer "In15.Cu")
		(net "P5E_CPU1_PE0_TX_DN<6>")
	)
	(segment
		(start 95.006414 -222.272098)
		(end 95.00489 -222.271336)
		(width 0.0889)
		(layer "In15.Cu")
		(net "P5E_CPU1_PE0_TX_DN<6>")
	)
	(segment
		(start 75.843638 -399.743168)
		(end 75.843638 -400.563588)
		(width 0.14732)
		(layer "In15.Cu")
		(net "P5E_CPU1_PE0_TX_DN<6>")
	)
	(segment
		(start 95.00489 -222.271336)
		(end 94.997524 -222.267018)
		(width 0.0889)
		(layer "In15.Cu")
		(net "P5E_CPU1_PE0_TX_DN<6>")
	)
	(segment
		(start 94.536768 -216.574878)
		(end 94.527878 -216.569798)
		(width 0.0889)
		(layer "In15.Cu")
		(net "P5E_CPU1_PE0_TX_DN<6>")
	)
	(segment
		(start 70.573138 -327.097898)
		(end 67.656964 -334.138778)
		(width 0.14732)
		(layer "In15.Cu")
		(net "P5E_CPU1_PE0_TX_DN<6>")
	)
	(segment
		(start 67.901058 -352.193352)
		(end 75.843638 -399.743168)
		(width 0.14732)
		(layer "In15.Cu")
		(net "P5E_CPU1_PE0_TX_DN<6>")
	)
	(segment
		(start 87.621364 -213.905592)
		(end 84.029296 -215.851232)
		(width 0.14732)
		(layer "In15.Cu")
		(net "P5E_CPU1_PE0_TX_DN<6>")
	)
	(segment
		(start 67.656964 -334.138778)
		(end 67.46367 -335.340198)
		(width 0.14732)
		(layer "In15.Cu")
		(net "P5E_CPU1_PE0_TX_DN<6>")
	)
	(segment
		(start 95.759016 -223.584262)
		(end 95.759016 -223.557084)
		(width 0.0889)
		(layer "In15.Cu")
		(net "P5E_CPU1_PE0_TX_DN<6>")
	)
	(segment
		(start 94.818962 -218.707716)
		(end 94.818962 -218.676728)
		(width 0.0889)
		(layer "In15.Cu")
		(net "P5E_CPU1_PE0_TX_DN<6>")
	)
	(segment
		(start 90.77706 -214.946992)
		(end 90.76817 -214.941912)
		(width 0.0889)
		(layer "In15.Cu")
		(net "P5E_CPU1_PE0_TX_DN<6>")
	)
	(segment
		(start 78.386686 -222.611696)
		(end 76.747878 -233.167174)
		(width 0.14732)
		(layer "In15.Cu")
		(net "P5E_CPU1_PE0_TX_DN<6>")
	)
	(segment
		(start 95.009208 -222.273622)
		(end 95.006414 -222.272098)
		(width 0.0889)
		(layer "In15.Cu")
		(net "P5E_CPU1_PE0_TX_DN<6>")
	)
	(segment
		(start 90.330528 -214.10803)
		(end 90.169746 -213.947502)
		(width 0.0889)
		(layer "In15.Cu")
		(net "P5E_CPU1_PE0_TX_DN<6>")
	)
	(segment
		(start 94.536768 -218.202764)
		(end 94.527878 -218.197684)
		(width 0.0889)
		(layer "In15.Cu")
		(net "P5E_CPU1_PE0_TX_DN<6>")
	)
	(segment
		(start 95.476568 -223.085914)
		(end 95.467678 -223.080834)
		(width 0.0889)
		(layer "In15.Cu")
		(net "P5E_CPU1_PE0_TX_DN<6>")
	)
	(segment
		(start 93.126814 -215.761062)
		(end 93.112082 -215.752426)
		(width 0.0889)
		(layer "In15.Cu")
		(net "P5E_CPU1_PE0_TX_DN<6>")
	)
	(segment
		(start 89.6874 -213.905592)
		(end 89.665302 -213.905592)
		(width 0.0889)
		(layer "In15.Cu")
		(net "P5E_CPU1_PE0_TX_DN<6>")
	)
	(segment
		(start 89.665302 -213.905592)
		(end 87.621364 -213.905592)
		(width 0.14732)
		(layer "In15.Cu")
		(net "P5E_CPU1_PE0_TX_DN<6>")
	)
	(segment
		(start 94.536768 -219.830396)
		(end 94.527878 -219.825316)
		(width 0.0889)
		(layer "In15.Cu")
		(net "P5E_CPU1_PE0_TX_DN<6>")
	)
	(segment
		(start 92.187014 -215.761062)
		(end 92.172282 -215.752426)
		(width 0.0889)
		(layer "In15.Cu")
		(net "P5E_CPU1_PE0_TX_DN<6>")
	)
	(segment
		(start 94.542864 -216.578434)
		(end 94.536768 -216.574878)
		(width 0.0889)
		(layer "In15.Cu")
		(net "P5E_CPU1_PE0_TX_DN<6>")
	)
	(segment
		(start 91.24569 -215.7603)
		(end 91.238324 -215.755982)
		(width 0.0889)
		(layer "In15.Cu")
		(net "P5E_CPU1_PE0_TX_DN<6>")
	)
	(segment
		(start 94.542864 -219.833952)
		(end 94.536768 -219.830396)
		(width 0.0889)
		(layer "In15.Cu")
		(net "P5E_CPU1_PE0_TX_DN<6>")
	)
	(segment
		(start 73.875646 -321.813174)
		(end 70.573138 -327.097898)
		(width 0.14732)
		(layer "In15.Cu")
		(net "P5E_CPU1_PE0_TX_DN<6>")
	)
	(segment
		(start 75.843638 -400.563588)
		(end 75.548998 -400.858228)
		(width 0.14732)
		(layer "In15.Cu")
		(net "P5E_CPU1_PE0_TX_DN<6>")
	)
	(segment
		(start 89.72931 -213.947502)
		(end 89.6874 -213.905592)
		(width 0.0889)
		(layer "In15.Cu")
		(net "P5E_CPU1_PE0_TX_DN<6>")
	)
	(segment
		(start 95.01251 -222.275654)
		(end 95.009208 -222.273622)
		(width 0.0889)
		(layer "In15.Cu")
		(net "P5E_CPU1_PE0_TX_DN<6>")
	)
	(segment
		(start 75.229974 -250.64466)
		(end 75.186286 -251.942854)
		(width 0.14732)
		(layer "In15.Cu")
		(net "P5E_CPU1_PE0_TX_DN<6>")
	)
	(segment
		(start 94.07271 -215.764618)
		(end 94.067376 -215.76157)
		(width 0.0889)
		(layer "In15.Cu")
		(net "P5E_CPU1_PE0_TX_DN<6>")
	)
	(segment
		(start 90.169746 -213.947502)
		(end 89.72931 -213.947502)
		(width 0.0889)
		(layer "In15.Cu")
		(net "P5E_CPU1_PE0_TX_DN<6>")
	)
	(segment
		(start 91.059762 -215.436704)
		(end 91.059762 -215.42248)
		(width 0.0889)
		(layer "In15.Cu")
		(net "P5E_CPU1_PE0_TX_DN<6>")
	)
	(segment
		(start 76.747878 -233.167174)
		(end 75.230736 -250.637548)
		(width 0.14732)
		(layer "In15.Cu")
		(net "P5E_CPU1_PE0_TX_DN<6>")
	)
	(segment
		(start 75.230736 -250.637548)
		(end 75.230482 -250.637548)
		(width 0.14732)
		(layer "In15.Cu")
		(net "P5E_CPU1_PE0_TX_DN<6>")
	)
	(segment
		(start 75.230482 -250.637548)
		(end 75.229974 -250.64466)
		(width 0.14732)
		(layer "In15.Cu")
		(net "P5E_CPU1_PE0_TX_DN<6>")
	)
	(segment
		(start 94.066614 -215.761062)
		(end 94.051882 -215.752426)
		(width 0.0889)
		(layer "In15.Cu")
		(net "P5E_CPU1_PE0_TX_DN<6>")
	)
	(segment
		(start 94.536768 -221.458282)
		(end 94.527878 -221.453202)
		(width 0.0889)
		(layer "In15.Cu")
		(net "P5E_CPU1_PE0_TX_DN<6>")
	)
	(segment
		(start 94.818962 -221.94774)
		(end 94.818962 -221.932246)
		(width 0.0889)
		(layer "In15.Cu")
		(net "P5E_CPU1_PE0_TX_DN<6>")
	)
	(segment
		(start 94.067376 -215.76157)
		(end 94.066614 -215.761062)
		(width 0.0889)
		(layer "In15.Cu")
		(net "P5E_CPU1_PE0_TX_DN<6>")
	)
	(arc
		(start 95.89897 -223.867472)
		(mid 95.797649 -223.741351)
		(end 95.759016 -223.584262)
		(width 0.0889)
		(layer "In15.Cu")
		(net "P5E_CPU1_PE0_TX_DN<6>")
	)
	(arc
		(start 95.759016 -223.557084)
		(mid 95.678854 -223.284895)
		(end 95.476568 -223.085914)
		(width 0.0889)
		(layer "In15.Cu")
		(net "P5E_CPU1_PE0_TX_DN<6>")
	)
	(arc
		(start 94.536768 -219.18168)
		(mid 94.739591 -218.981449)
		(end 94.818962 -218.707716)
		(width 0.0889)
		(layer "In15.Cu")
		(net "P5E_CPU1_PE0_TX_DN<6>")
	)
	(arc
		(start 94.349316 -216.25052)
		(mid 94.275325 -215.970954)
		(end 94.07271 -215.764618)
		(width 0.0889)
		(layer "In15.Cu")
		(net "P5E_CPU1_PE0_TX_DN<6>")
	)
	(arc
		(start 94.818962 -218.676728)
		(mid 94.739592 -218.402994)
		(end 94.536768 -218.202764)
		(width 0.0889)
		(layer "In15.Cu")
		(net "P5E_CPU1_PE0_TX_DN<6>")
	)
	(arc
		(start 93.112082 -215.752426)
		(mid 92.835607 -215.685106)
		(end 92.56141 -215.761062)
		(width 0.0889)
		(layer "In15.Cu")
		(net "P5E_CPU1_PE0_TX_DN<6>")
	)
	(arc
		(start 94.051882 -215.752426)
		(mid 93.775407 -215.685106)
		(end 93.50121 -215.761062)
		(width 0.0889)
		(layer "In15.Cu")
		(net "P5E_CPU1_PE0_TX_DN<6>")
	)
	(arc
		(start 94.818962 -221.932246)
		(mid 94.739592 -221.658512)
		(end 94.536768 -221.458282)
		(width 0.0889)
		(layer "In15.Cu")
		(net "P5E_CPU1_PE0_TX_DN<6>")
	)
	(arc
		(start 94.527878 -216.569798)
		(mid 94.396964 -216.433438)
		(end 94.349316 -216.25052)
		(width 0.0889)
		(layer "In15.Cu")
		(net "P5E_CPU1_PE0_TX_DN<6>")
	)
	(arc
		(start 90.589608 -214.424768)
		(mid 90.487979 -214.243564)
		(end 90.330528 -214.10803)
		(width 0.0889)
		(layer "In15.Cu")
		(net "P5E_CPU1_PE0_TX_DN<6>")
	)
	(arc
		(start 91.238324 -215.755982)
		(mid 91.10741 -215.619622)
		(end 91.059762 -215.436704)
		(width 0.0889)
		(layer "In15.Cu")
		(net "P5E_CPU1_PE0_TX_DN<6>")
	)
	(arc
		(start 94.527878 -221.453202)
		(mid 94.399559 -221.32123)
		(end 94.34957 -221.144084)
		(width 0.0889)
		(layer "In15.Cu")
		(net "P5E_CPU1_PE0_TX_DN<6>")
	)
	(arc
		(start 95.467678 -223.080834)
		(mid 95.339785 -222.949772)
		(end 95.28937 -222.773748)
		(width 0.0889)
		(layer "In15.Cu")
		(net "P5E_CPU1_PE0_TX_DN<6>")
	)
	(arc
		(start 94.997524 -222.267018)
		(mid 94.86661 -222.130658)
		(end 94.818962 -221.94774)
		(width 0.0889)
		(layer "In15.Cu")
		(net "P5E_CPU1_PE0_TX_DN<6>")
	)
	(arc
		(start 94.527878 -218.197684)
		(mid 94.399474 -218.065739)
		(end 94.349316 -217.888566)
		(width 0.0889)
		(layer "In15.Cu")
		(net "P5E_CPU1_PE0_TX_DN<6>")
	)
	(arc
		(start 94.34957 -217.863674)
		(mid 94.400624 -217.689094)
		(end 94.527878 -217.559128)
		(width 0.0889)
		(layer "In15.Cu")
		(net "P5E_CPU1_PE0_TX_DN<6>")
	)
	(arc
		(start 95.289116 -222.761556)
		(mid 95.215125 -222.48199)
		(end 95.01251 -222.275654)
		(width 0.0889)
		(layer "In15.Cu")
		(net "P5E_CPU1_PE0_TX_DN<6>")
	)
	(arc
		(start 92.172282 -215.752426)
		(mid 91.895807 -215.685106)
		(end 91.62161 -215.761062)
		(width 0.0889)
		(layer "In15.Cu")
		(net "P5E_CPU1_PE0_TX_DN<6>")
	)
	(arc
		(start 92.56141 -215.761062)
		(mid 92.374212 -215.811205)
		(end 92.187014 -215.761062)
		(width 0.0889)
		(layer "In15.Cu")
		(net "P5E_CPU1_PE0_TX_DN<6>")
	)
	(arc
		(start 93.50121 -215.761062)
		(mid 93.314012 -215.811205)
		(end 93.126814 -215.761062)
		(width 0.0889)
		(layer "In15.Cu")
		(net "P5E_CPU1_PE0_TX_DN<6>")
	)
	(arc
		(start 94.34957 -221.144084)
		(mid 94.34949 -221.131636)
		(end 94.349824 -221.119192)
		(width 0.0889)
		(layer "In15.Cu")
		(net "P5E_CPU1_PE0_TX_DN<6>")
	)
	(arc
		(start 90.76817 -214.941912)
		(mid 90.637256 -214.805552)
		(end 90.589608 -214.622634)
		(width 0.0889)
		(layer "In15.Cu")
		(net "P5E_CPU1_PE0_TX_DN<6>")
	)
	(arc
		(start 91.059762 -215.42248)
		(mid 90.980543 -215.147795)
		(end 90.77706 -214.946992)
		(width 0.0889)
		(layer "In15.Cu")
		(net "P5E_CPU1_PE0_TX_DN<6>")
	)
	(arc
		(start 95.28937 -222.773748)
		(mid 95.289203 -222.762572)
		(end 95.28937 -222.751396)
		(width 0.0889)
		(layer "In15.Cu")
		(net "P5E_CPU1_PE0_TX_DN<6>")
	)
	(arc
		(start 94.527878 -219.825316)
		(mid 94.349402 -219.506038)
		(end 94.527878 -219.18676)
		(width 0.0889)
		(layer "In15.Cu")
		(net "P5E_CPU1_PE0_TX_DN<6>")
	)
	(arc
		(start 94.349316 -217.888566)
		(mid 94.349236 -217.876118)
		(end 94.34957 -217.863674)
		(width 0.0889)
		(layer "In15.Cu")
		(net "P5E_CPU1_PE0_TX_DN<6>")
	)
	(arc
		(start 94.536768 -220.809566)
		(mid 94.819382 -220.323448)
		(end 94.542864 -219.833952)
		(width 0.0889)
		(layer "In15.Cu")
		(net "P5E_CPU1_PE0_TX_DN<6>")
	)
	(arc
		(start 91.62161 -215.761062)
		(mid 91.434412 -215.811205)
		(end 91.247214 -215.761062)
		(width 0.0889)
		(layer "In15.Cu")
		(net "P5E_CPU1_PE0_TX_DN<6>")
	)
	(arc
		(start 94.536768 -217.554048)
		(mid 94.819382 -217.06793)
		(end 94.542864 -216.578434)
		(width 0.0889)
		(layer "In15.Cu")
		(net "P5E_CPU1_PE0_TX_DN<6>")
	)
	(arc
		(start 94.349824 -221.119192)
		(mid 94.400734 -220.944623)
		(end 94.527878 -220.814646)
		(width 0.0889)
		(layer "In15.Cu")
		(net "P5E_CPU1_PE0_TX_DN<6>")
	)
	(segment
		(start 78.59141 -402.104352)
		(end 78.9178 -401.777962)
		(width 0.13208)
		(layer "F.Cu")
		(net "P5E_CPU1_PE0_TX_DN<5>")
	)
	(segment
		(start 78.9178 -401.777962)
		(end 78.9178 -401.16379)
		(width 0.13208)
		(layer "F.Cu")
		(net "P5E_CPU1_PE0_TX_DN<5>")
	)
	(segment
		(start 78.9178 -401.16379)
		(end 78.612238 -400.858228)
		(width 0.13208)
		(layer "F.Cu")
		(net "P5E_CPU1_PE0_TX_DN<5>")
	)
	(segment
		(start 78.586838 -402.104352)
		(end 78.59141 -402.104352)
		(width 0.13208)
		(layer "F.Cu")
		(net "P5E_CPU1_PE0_TX_DN<5>")
	)
	(segment
		(start 94.723966 -224.925128)
		(end 94.723966 -224.389442)
		(width 0.13208)
		(layer "F.Cu")
		(net "P5E_CPU1_PE0_TX_DN<5>")
	)
	(segment
		(start 94.723712 -224.925382)
		(end 94.723966 -224.925128)
		(width 0.13208)
		(layer "F.Cu")
		(net "P5E_CPU1_PE0_TX_DN<5>")
	)
	(segment
		(start 93.879162 -221.94774)
		(end 93.879162 -221.932246)
		(width 0.0889)
		(layer "In15.Cu")
		(net "P5E_CPU1_PE0_TX_DN<5>")
	)
	(segment
		(start 94.536768 -223.085914)
		(end 94.527878 -223.080834)
		(width 0.0889)
		(layer "In15.Cu")
		(net "P5E_CPU1_PE0_TX_DN<5>")
	)
	(segment
		(start 88.89746 -216.574878)
		(end 88.882728 -216.566242)
		(width 0.0889)
		(layer "In15.Cu")
		(net "P5E_CPU1_PE0_TX_DN<5>")
	)
	(segment
		(start 80.37195 -251.351542)
		(end 80.37195 -252.217428)
		(width 0.14732)
		(layer "In15.Cu")
		(net "P5E_CPU1_PE0_TX_DN<5>")
	)
	(segment
		(start 85.329268 -216.499186)
		(end 85.287358 -216.457276)
		(width 0.0889)
		(layer "In15.Cu")
		(net "P5E_CPU1_PE0_TX_DN<5>")
	)
	(segment
		(start 93.588078 -220.814646)
		(end 93.596968 -220.809566)
		(width 0.0889)
		(layer "In15.Cu")
		(net "P5E_CPU1_PE0_TX_DN<5>")
	)
	(segment
		(start 79.449422 -222.708978)
		(end 77.728318 -233.609642)
		(width 0.14732)
		(layer "In15.Cu")
		(net "P5E_CPU1_PE0_TX_DN<5>")
	)
	(segment
		(start 78.46822 -247.622314)
		(end 78.467966 -247.622314)
		(width 0.14732)
		(layer "In15.Cu")
		(net "P5E_CPU1_PE0_TX_DN<5>")
	)
	(segment
		(start 93.40977 -217.866214)
		(end 93.409516 -217.878406)
		(width 0.0889)
		(layer "In15.Cu")
		(net "P5E_CPU1_PE0_TX_DN<5>")
	)
	(segment
		(start 93.596968 -218.202764)
		(end 93.588078 -218.197684)
		(width 0.0889)
		(layer "In15.Cu")
		(net "P5E_CPU1_PE0_TX_DN<5>")
	)
	(segment
		(start 78.91272 -399.657316)
		(end 78.906878 -399.875248)
		(width 0.14732)
		(layer "In15.Cu")
		(net "P5E_CPU1_PE0_TX_DN<5>")
	)
	(segment
		(start 89.837768 -216.574878)
		(end 89.827354 -216.568782)
		(width 0.0889)
		(layer "In15.Cu")
		(net "P5E_CPU1_PE0_TX_DN<5>")
	)
	(segment
		(start 68.45808 -335.490058)
		(end 68.94195 -352.265996)
		(width 0.14732)
		(layer "In15.Cu")
		(net "P5E_CPU1_PE0_TX_DN<5>")
	)
	(segment
		(start 92.663264 -216.578434)
		(end 92.657168 -216.574878)
		(width 0.0889)
		(layer "In15.Cu")
		(net "P5E_CPU1_PE0_TX_DN<5>")
	)
	(segment
		(start 77.853794 -258.6736)
		(end 77.141578 -266.592304)
		(width 0.14732)
		(layer "In15.Cu")
		(net "P5E_CPU1_PE0_TX_DN<5>")
	)
	(segment
		(start 94.06509 -222.271336)
		(end 94.057724 -222.267018)
		(width 0.0889)
		(layer "In15.Cu")
		(net "P5E_CPU1_PE0_TX_DN<5>")
	)
	(segment
		(start 68.946522 -352.26625)
		(end 78.91272 -399.657316)
		(width 0.14732)
		(layer "In15.Cu")
		(net "P5E_CPU1_PE0_TX_DN<5>")
	)
	(segment
		(start 77.728318 -233.609642)
		(end 77.931772 -244.748304)
		(width 0.14732)
		(layer "In15.Cu")
		(net "P5E_CPU1_PE0_TX_DN<5>")
	)
	(segment
		(start 74.425556 -323.052694)
		(end 71.539862 -327.439782)
		(width 0.14732)
		(layer "In15.Cu")
		(net "P5E_CPU1_PE0_TX_DN<5>")
	)
	(segment
		(start 80.664812 -220.340682)
		(end 79.449422 -222.708978)
		(width 0.14732)
		(layer "In15.Cu")
		(net "P5E_CPU1_PE0_TX_DN<5>")
	)
	(segment
		(start 68.46189 -335.464912)
		(end 68.45808 -335.490058)
		(width 0.14732)
		(layer "In15.Cu")
		(net "P5E_CPU1_PE0_TX_DN<5>")
	)
	(segment
		(start 87.95766 -216.574878)
		(end 87.942928 -216.566242)
		(width 0.0889)
		(layer "In15.Cu")
		(net "P5E_CPU1_PE0_TX_DN<5>")
	)
	(segment
		(start 77.854302 -258.6736)
		(end 77.853794 -258.6736)
		(width 0.14732)
		(layer "In15.Cu")
		(net "P5E_CPU1_PE0_TX_DN<5>")
	)
	(segment
		(start 80.37195 -252.217428)
		(end 80.371188 -252.217174)
		(width 0.14732)
		(layer "In15.Cu")
		(net "P5E_CPU1_PE0_TX_DN<5>")
	)
	(segment
		(start 85.287358 -216.457276)
		(end 85.26526 -216.457276)
		(width 0.0889)
		(layer "In15.Cu")
		(net "P5E_CPU1_PE0_TX_DN<5>")
	)
	(segment
		(start 78.467966 -247.622314)
		(end 78.47584 -247.664224)
		(width 0.14732)
		(layer "In15.Cu")
		(net "P5E_CPU1_PE0_TX_DN<5>")
	)
	(segment
		(start 94.536768 -224.7138)
		(end 94.527878 -224.70872)
		(width 0.0889)
		(layer "In15.Cu")
		(net "P5E_CPU1_PE0_TX_DN<5>")
	)
	(segment
		(start 79.303626 -249.210068)
		(end 79.303626 -249.210322)
		(width 0.14732)
		(layer "In15.Cu")
		(net "P5E_CPU1_PE0_TX_DN<5>")
	)
	(segment
		(start 93.879162 -218.707716)
		(end 93.879162 -218.676728)
		(width 0.0889)
		(layer "In15.Cu")
		(net "P5E_CPU1_PE0_TX_DN<5>")
	)
	(segment
		(start 93.409516 -217.878406)
		(end 93.409516 -217.859864)
		(width 0.0889)
		(layer "In15.Cu")
		(net "P5E_CPU1_PE0_TX_DN<5>")
	)
	(segment
		(start 84.681822 -216.573354)
		(end 80.664812 -220.340682)
		(width 0.14732)
		(layer "In15.Cu")
		(net "P5E_CPU1_PE0_TX_DN<5>")
	)
	(segment
		(start 93.596968 -221.458282)
		(end 93.588078 -221.453202)
		(width 0.0889)
		(layer "In15.Cu")
		(net "P5E_CPU1_PE0_TX_DN<5>")
	)
	(segment
		(start 94.819216 -223.575626)
		(end 94.819216 -223.561402)
		(width 0.0889)
		(layer "In15.Cu")
		(net "P5E_CPU1_PE0_TX_DN<5>")
	)
	(segment
		(start 86.735412 -216.499186)
		(end 85.329268 -216.499186)
		(width 0.0889)
		(layer "In15.Cu")
		(net "P5E_CPU1_PE0_TX_DN<5>")
	)
	(segment
		(start 90.226896 -216.566242)
		(end 90.212164 -216.574878)
		(width 0.0889)
		(layer "In15.Cu")
		(net "P5E_CPU1_PE0_TX_DN<5>")
	)
	(segment
		(start 78.47584 -247.664224)
		(end 79.303626 -249.210068)
		(width 0.14732)
		(layer "In15.Cu")
		(net "P5E_CPU1_PE0_TX_DN<5>")
	)
	(segment
		(start 93.596968 -219.830396)
		(end 93.588078 -219.825316)
		(width 0.0889)
		(layer "In15.Cu")
		(net "P5E_CPU1_PE0_TX_DN<5>")
	)
	(segment
		(start 94.066614 -222.272098)
		(end 94.06509 -222.271336)
		(width 0.0889)
		(layer "In15.Cu")
		(net "P5E_CPU1_PE0_TX_DN<5>")
	)
	(segment
		(start 94.536768 -224.065084)
		(end 94.542864 -224.061528)
		(width 0.0889)
		(layer "In15.Cu")
		(net "P5E_CPU1_PE0_TX_DN<5>")
	)
	(segment
		(start 94.88043 -224.66046)
		(end 94.859348 -224.738438)
		(width 0.0889)
		(layer "In15.Cu")
		(net "P5E_CPU1_PE0_TX_DN<5>")
	)
	(segment
		(start 68.94195 -352.265996)
		(end 68.946522 -352.26625)
		(width 0.14732)
		(layer "In15.Cu")
		(net "P5E_CPU1_PE0_TX_DN<5>")
	)
	(segment
		(start 80.104488 -250.706382)
		(end 80.37195 -251.351542)
		(width 0.14732)
		(layer "In15.Cu")
		(net "P5E_CPU1_PE0_TX_DN<5>")
	)
	(segment
		(start 94.723966 -224.389442)
		(end 94.88043 -224.66046)
		(width 0.0889)
		(layer "In15.Cu")
		(net "P5E_CPU1_PE0_TX_DN<5>")
	)
	(segment
		(start 77.931772 -244.748304)
		(end 78.46822 -247.622314)
		(width 0.14732)
		(layer "In15.Cu")
		(net "P5E_CPU1_PE0_TX_DN<5>")
	)
	(segment
		(start 84.974938 -216.457276)
		(end 84.681822 -216.573354)
		(width 0.14732)
		(layer "In15.Cu")
		(net "P5E_CPU1_PE0_TX_DN<5>")
	)
	(segment
		(start 93.127068 -217.388694)
		(end 93.118178 -217.383614)
		(width 0.0889)
		(layer "In15.Cu")
		(net "P5E_CPU1_PE0_TX_DN<5>")
	)
	(segment
		(start 68.61556 -334.50022)
		(end 68.462144 -335.464912)
		(width 0.14732)
		(layer "In15.Cu")
		(net "P5E_CPU1_PE0_TX_DN<5>")
	)
	(segment
		(start 94.07271 -222.275654)
		(end 94.069408 -222.273622)
		(width 0.0889)
		(layer "In15.Cu")
		(net "P5E_CPU1_PE0_TX_DN<5>")
	)
	(segment
		(start 71.539862 -327.439782)
		(end 68.61556 -334.50022)
		(width 0.14732)
		(layer "In15.Cu")
		(net "P5E_CPU1_PE0_TX_DN<5>")
	)
	(segment
		(start 85.26526 -216.457276)
		(end 84.974938 -216.457276)
		(width 0.14732)
		(layer "In15.Cu")
		(net "P5E_CPU1_PE0_TX_DN<5>")
	)
	(segment
		(start 94.069408 -222.273622)
		(end 94.066614 -222.272098)
		(width 0.0889)
		(layer "In15.Cu")
		(net "P5E_CPU1_PE0_TX_DN<5>")
	)
	(segment
		(start 79.907384 -310.027828)
		(end 74.425556 -323.052694)
		(width 0.14732)
		(layer "In15.Cu")
		(net "P5E_CPU1_PE0_TX_DN<5>")
	)
	(segment
		(start 94.527878 -224.070164)
		(end 94.536768 -224.065084)
		(width 0.0889)
		(layer "In15.Cu")
		(net "P5E_CPU1_PE0_TX_DN<5>")
	)
	(segment
		(start 68.462144 -335.464912)
		(end 68.46189 -335.464912)
		(width 0.14732)
		(layer "In15.Cu")
		(net "P5E_CPU1_PE0_TX_DN<5>")
	)
	(segment
		(start 77.141578 -266.592304)
		(end 79.907384 -310.027828)
		(width 0.14732)
		(layer "In15.Cu")
		(net "P5E_CPU1_PE0_TX_DN<5>")
	)
	(segment
		(start 88.905842 -216.579704)
		(end 88.89746 -216.574878)
		(width 0.0889)
		(layer "In15.Cu")
		(net "P5E_CPU1_PE0_TX_DN<5>")
	)
	(segment
		(start 78.906878 -399.875248)
		(end 78.906878 -400.563588)
		(width 0.14732)
		(layer "In15.Cu")
		(net "P5E_CPU1_PE0_TX_DN<5>")
	)
	(segment
		(start 93.588078 -219.18676)
		(end 93.596968 -219.18168)
		(width 0.0889)
		(layer "In15.Cu")
		(net "P5E_CPU1_PE0_TX_DN<5>")
	)
	(segment
		(start 78.906878 -400.563588)
		(end 78.612238 -400.858228)
		(width 0.14732)
		(layer "In15.Cu")
		(net "P5E_CPU1_PE0_TX_DN<5>")
	)
	(segment
		(start 92.106496 -216.566242)
		(end 92.091764 -216.574878)
		(width 0.0889)
		(layer "In15.Cu")
		(net "P5E_CPU1_PE0_TX_DN<5>")
	)
	(segment
		(start 79.303626 -249.210322)
		(end 80.104488 -250.706382)
		(width 0.14732)
		(layer "In15.Cu")
		(net "P5E_CPU1_PE0_TX_DN<5>")
	)
	(segment
		(start 80.371188 -252.217174)
		(end 77.854302 -258.6736)
		(width 0.14732)
		(layer "In15.Cu")
		(net "P5E_CPU1_PE0_TX_DN<5>")
	)
	(arc
		(start 93.588078 -219.825316)
		(mid 93.409481 -219.506038)
		(end 93.588078 -219.18676)
		(width 0.0889)
		(layer "In15.Cu")
		(net "P5E_CPU1_PE0_TX_DN<5>")
	)
	(arc
		(start 88.332056 -216.574878)
		(mid 88.144858 -216.625021)
		(end 87.95766 -216.574878)
		(width 0.0889)
		(layer "In15.Cu")
		(net "P5E_CPU1_PE0_TX_DN<5>")
	)
	(arc
		(start 91.717368 -216.574878)
		(mid 91.434666 -216.499102)
		(end 91.151964 -216.574878)
		(width 0.0889)
		(layer "In15.Cu")
		(net "P5E_CPU1_PE0_TX_DN<5>")
	)
	(arc
		(start 93.118178 -217.383614)
		(mid 92.987264 -217.247254)
		(end 92.939616 -217.064336)
		(width 0.0889)
		(layer "In15.Cu")
		(net "P5E_CPU1_PE0_TX_DN<5>")
	)
	(arc
		(start 93.40977 -221.144084)
		(mid 93.409603 -221.132908)
		(end 93.40977 -221.121732)
		(width 0.0889)
		(layer "In15.Cu")
		(net "P5E_CPU1_PE0_TX_DN<5>")
	)
	(arc
		(start 92.939616 -217.064336)
		(mid 92.8657 -216.784834)
		(end 92.663264 -216.578434)
		(width 0.0889)
		(layer "In15.Cu")
		(net "P5E_CPU1_PE0_TX_DN<5>")
	)
	(arc
		(start 93.879162 -221.932246)
		(mid 93.799792 -221.658512)
		(end 93.596968 -221.458282)
		(width 0.0889)
		(layer "In15.Cu")
		(net "P5E_CPU1_PE0_TX_DN<5>")
	)
	(arc
		(start 89.27211 -216.574878)
		(mid 89.089605 -216.625116)
		(end 88.905842 -216.579704)
		(width 0.0889)
		(layer "In15.Cu")
		(net "P5E_CPU1_PE0_TX_DN<5>")
	)
	(arc
		(start 94.34957 -222.776288)
		(mid 94.349373 -222.768923)
		(end 94.349316 -222.761556)
		(width 0.0889)
		(layer "In15.Cu")
		(net "P5E_CPU1_PE0_TX_DN<5>")
	)
	(arc
		(start 90.777568 -216.574878)
		(mid 90.503369 -216.499043)
		(end 90.226896 -216.566242)
		(width 0.0889)
		(layer "In15.Cu")
		(net "P5E_CPU1_PE0_TX_DN<5>")
	)
	(arc
		(start 94.542864 -224.061528)
		(mid 94.745277 -223.855115)
		(end 94.819216 -223.575626)
		(width 0.0889)
		(layer "In15.Cu")
		(net "P5E_CPU1_PE0_TX_DN<5>")
	)
	(arc
		(start 93.588078 -221.453202)
		(mid 93.459759 -221.32123)
		(end 93.40977 -221.144084)
		(width 0.0889)
		(layer "In15.Cu")
		(net "P5E_CPU1_PE0_TX_DN<5>")
	)
	(arc
		(start 93.409516 -217.859864)
		(mid 93.329354 -217.587675)
		(end 93.127068 -217.388694)
		(width 0.0889)
		(layer "In15.Cu")
		(net "P5E_CPU1_PE0_TX_DN<5>")
	)
	(arc
		(start 90.212164 -216.574878)
		(mid 90.024966 -216.625021)
		(end 89.837768 -216.574878)
		(width 0.0889)
		(layer "In15.Cu")
		(net "P5E_CPU1_PE0_TX_DN<5>")
	)
	(arc
		(start 87.942928 -216.566242)
		(mid 87.666453 -216.498922)
		(end 87.392256 -216.574878)
		(width 0.0889)
		(layer "In15.Cu")
		(net "P5E_CPU1_PE0_TX_DN<5>")
	)
	(arc
		(start 94.527878 -224.70872)
		(mid 94.349402 -224.389442)
		(end 94.527878 -224.070164)
		(width 0.0889)
		(layer "In15.Cu")
		(net "P5E_CPU1_PE0_TX_DN<5>")
	)
	(arc
		(start 93.40977 -217.888566)
		(mid 93.409603 -217.87739)
		(end 93.40977 -217.866214)
		(width 0.0889)
		(layer "In15.Cu")
		(net "P5E_CPU1_PE0_TX_DN<5>")
	)
	(arc
		(start 94.349316 -222.761556)
		(mid 94.275325 -222.48199)
		(end 94.07271 -222.275654)
		(width 0.0889)
		(layer "In15.Cu")
		(net "P5E_CPU1_PE0_TX_DN<5>")
	)
	(arc
		(start 93.879162 -218.676728)
		(mid 93.799792 -218.402994)
		(end 93.596968 -218.202764)
		(width 0.0889)
		(layer "In15.Cu")
		(net "P5E_CPU1_PE0_TX_DN<5>")
	)
	(arc
		(start 93.40977 -221.121732)
		(mid 93.460241 -220.945724)
		(end 93.588078 -220.814646)
		(width 0.0889)
		(layer "In15.Cu")
		(net "P5E_CPU1_PE0_TX_DN<5>")
	)
	(arc
		(start 87.392256 -216.574878)
		(mid 87.205909 -216.62502)
		(end 87.019384 -216.57564)
		(width 0.0889)
		(layer "In15.Cu")
		(net "P5E_CPU1_PE0_TX_DN<5>")
	)
	(arc
		(start 94.057724 -222.267018)
		(mid 93.92681 -222.130658)
		(end 93.879162 -221.94774)
		(width 0.0889)
		(layer "In15.Cu")
		(net "P5E_CPU1_PE0_TX_DN<5>")
	)
	(arc
		(start 92.657168 -216.574878)
		(mid 92.382969 -216.499043)
		(end 92.106496 -216.566242)
		(width 0.0889)
		(layer "In15.Cu")
		(net "P5E_CPU1_PE0_TX_DN<5>")
	)
	(arc
		(start 89.827354 -216.568782)
		(mid 89.548922 -216.498936)
		(end 89.27211 -216.574878)
		(width 0.0889)
		(layer "In15.Cu")
		(net "P5E_CPU1_PE0_TX_DN<5>")
	)
	(arc
		(start 93.596968 -219.18168)
		(mid 93.799791 -218.981449)
		(end 93.879162 -218.707716)
		(width 0.0889)
		(layer "In15.Cu")
		(net "P5E_CPU1_PE0_TX_DN<5>")
	)
	(arc
		(start 87.019384 -216.57564)
		(mid 86.882462 -216.518589)
		(end 86.735412 -216.499186)
		(width 0.0889)
		(layer "In15.Cu")
		(net "P5E_CPU1_PE0_TX_DN<5>")
	)
	(arc
		(start 92.091764 -216.574878)
		(mid 91.904566 -216.625021)
		(end 91.717368 -216.574878)
		(width 0.0889)
		(layer "In15.Cu")
		(net "P5E_CPU1_PE0_TX_DN<5>")
	)
	(arc
		(start 88.882728 -216.566242)
		(mid 88.606253 -216.498922)
		(end 88.332056 -216.574878)
		(width 0.0889)
		(layer "In15.Cu")
		(net "P5E_CPU1_PE0_TX_DN<5>")
	)
	(arc
		(start 94.819216 -223.561402)
		(mid 94.740075 -223.286779)
		(end 94.536768 -223.085914)
		(width 0.0889)
		(layer "In15.Cu")
		(net "P5E_CPU1_PE0_TX_DN<5>")
	)
	(arc
		(start 94.859348 -224.738438)
		(mid 94.695252 -224.762785)
		(end 94.536768 -224.7138)
		(width 0.0889)
		(layer "In15.Cu")
		(net "P5E_CPU1_PE0_TX_DN<5>")
	)
	(arc
		(start 93.596968 -220.809566)
		(mid 93.8795 -220.320045)
		(end 93.596968 -219.830396)
		(width 0.0889)
		(layer "In15.Cu")
		(net "P5E_CPU1_PE0_TX_DN<5>")
	)
	(arc
		(start 93.588078 -218.197684)
		(mid 93.459759 -218.065712)
		(end 93.40977 -217.888566)
		(width 0.0889)
		(layer "In15.Cu")
		(net "P5E_CPU1_PE0_TX_DN<5>")
	)
	(arc
		(start 94.527878 -223.080834)
		(mid 94.400624 -222.950868)
		(end 94.34957 -222.776288)
		(width 0.0889)
		(layer "In15.Cu")
		(net "P5E_CPU1_PE0_TX_DN<5>")
	)
	(arc
		(start 91.151964 -216.574878)
		(mid 90.964766 -216.625021)
		(end 90.777568 -216.574878)
		(width 0.0889)
		(layer "In15.Cu")
		(net "P5E_CPU1_PE0_TX_DN<5>")
	)
	(segment
		(start 94.254066 -224.111566)
		(end 94.253812 -224.111312)
		(width 0.13208)
		(layer "F.Cu")
		(net "P5E_CPU1_PE0_TX_DN<4>")
	)
	(segment
		(start 81.98104 -401.777962)
		(end 81.98104 -401.16379)
		(width 0.13208)
		(layer "F.Cu")
		(net "P5E_CPU1_PE0_TX_DN<4>")
	)
	(segment
		(start 81.65465 -402.104352)
		(end 81.98104 -401.777962)
		(width 0.13208)
		(layer "F.Cu")
		(net "P5E_CPU1_PE0_TX_DN<4>")
	)
	(segment
		(start 94.253812 -224.111312)
		(end 94.253812 -223.575626)
		(width 0.13208)
		(layer "F.Cu")
		(net "P5E_CPU1_PE0_TX_DN<4>")
	)
	(segment
		(start 81.98104 -401.16379)
		(end 81.675478 -400.858228)
		(width 0.13208)
		(layer "F.Cu")
		(net "P5E_CPU1_PE0_TX_DN<4>")
	)
	(segment
		(start 81.650078 -402.104352)
		(end 81.65465 -402.104352)
		(width 0.13208)
		(layer "F.Cu")
		(net "P5E_CPU1_PE0_TX_DN<4>")
	)
	(segment
		(start 84.963 -218.60002)
		(end 82.171286 -220.35008)
		(width 0.14732)
		(layer "In15.Cu")
		(net "P5E_CPU1_PE0_TX_DN<4>")
	)
	(segment
		(start 78.78953 -258.850892)
		(end 78.788514 -258.85394)
		(width 0.14732)
		(layer "In15.Cu")
		(net "P5E_CPU1_PE0_TX_DN<4>")
	)
	(segment
		(start 92.19311 -219.020136)
		(end 92.191332 -219.01912)
		(width 0.0889)
		(layer "In15.Cu")
		(net "P5E_CPU1_PE0_TX_DN<4>")
	)
	(segment
		(start 93.12529 -222.271336)
		(end 93.117924 -222.267018)
		(width 0.0889)
		(layer "In15.Cu")
		(net "P5E_CPU1_PE0_TX_DN<4>")
	)
	(segment
		(start 80.860138 -310.267604)
		(end 75.169522 -323.787008)
		(width 0.14732)
		(layer "In15.Cu")
		(net "P5E_CPU1_PE0_TX_DN<4>")
	)
	(segment
		(start 81.970118 -399.672048)
		(end 81.970118 -400.563588)
		(width 0.14732)
		(layer "In15.Cu")
		(net "P5E_CPU1_PE0_TX_DN<4>")
	)
	(segment
		(start 87.094822 -218.64193)
		(end 85.96884 -218.64193)
		(width 0.0889)
		(layer "In15.Cu")
		(net "P5E_CPU1_PE0_TX_DN<4>")
	)
	(segment
		(start 92.648278 -220.814646)
		(end 92.657168 -220.809566)
		(width 0.0889)
		(layer "In15.Cu")
		(net "P5E_CPU1_PE0_TX_DN<4>")
	)
	(segment
		(start 87.41029 -218.957144)
		(end 87.094822 -218.64193)
		(width 0.0889)
		(layer "In15.Cu")
		(net "P5E_CPU1_PE0_TX_DN<4>")
	)
	(segment
		(start 72.273668 -328.15403)
		(end 72.261476 -328.17816)
		(width 0.14732)
		(layer "In15.Cu")
		(net "P5E_CPU1_PE0_TX_DN<4>")
	)
	(segment
		(start 69.933058 -351.97542)
		(end 81.970118 -399.672048)
		(width 0.14732)
		(layer "In15.Cu")
		(net "P5E_CPU1_PE0_TX_DN<4>")
	)
	(segment
		(start 80.167734 -248.852436)
		(end 80.94599 -250.307602)
		(width 0.14732)
		(layer "In15.Cu")
		(net "P5E_CPU1_PE0_TX_DN<4>")
	)
	(segment
		(start 89.367614 -219.01658)
		(end 89.3572 -219.010484)
		(width 0.0889)
		(layer "In15.Cu")
		(net "P5E_CPU1_PE0_TX_DN<4>")
	)
	(segment
		(start 69.408294 -335.53908)
		(end 69.933058 -351.97542)
		(width 0.14732)
		(layer "In15.Cu")
		(net "P5E_CPU1_PE0_TX_DN<4>")
	)
	(segment
		(start 93.596968 -223.085914)
		(end 93.588078 -223.080834)
		(width 0.0889)
		(layer "In15.Cu")
		(net "P5E_CPU1_PE0_TX_DN<4>")
	)
	(segment
		(start 93.879416 -223.584262)
		(end 93.879416 -223.557084)
		(width 0.0889)
		(layer "In15.Cu")
		(net "P5E_CPU1_PE0_TX_DN<4>")
	)
	(segment
		(start 93.13291 -222.275654)
		(end 93.129608 -222.273622)
		(width 0.0889)
		(layer "In15.Cu")
		(net "P5E_CPU1_PE0_TX_DN<4>")
	)
	(segment
		(start 78.915514 -244.907054)
		(end 79.362808 -247.347486)
		(width 0.14732)
		(layer "In15.Cu")
		(net "P5E_CPU1_PE0_TX_DN<4>")
	)
	(segment
		(start 81.306924 -252.393196)
		(end 78.78953 -258.850892)
		(width 0.14732)
		(layer "In15.Cu")
		(net "P5E_CPU1_PE0_TX_DN<4>")
	)
	(segment
		(start 80.94599 -250.307602)
		(end 81.307432 -251.180092)
		(width 0.14732)
		(layer "In15.Cu")
		(net "P5E_CPU1_PE0_TX_DN<4>")
	)
	(segment
		(start 78.77429 -258.889754)
		(end 78.080108 -266.604496)
		(width 0.14732)
		(layer "In15.Cu")
		(net "P5E_CPU1_PE0_TX_DN<4>")
	)
	(segment
		(start 92.939616 -220.334078)
		(end 92.939616 -220.319854)
		(width 0.0889)
		(layer "In15.Cu")
		(net "P5E_CPU1_PE0_TX_DN<4>")
	)
	(segment
		(start 69.53504 -334.760824)
		(end 69.408294 -335.53908)
		(width 0.14732)
		(layer "In15.Cu")
		(net "P5E_CPU1_PE0_TX_DN<4>")
	)
	(segment
		(start 93.126814 -222.272098)
		(end 93.12529 -222.271336)
		(width 0.0889)
		(layer "In15.Cu")
		(net "P5E_CPU1_PE0_TX_DN<4>")
	)
	(segment
		(start 94.253812 -223.575626)
		(end 94.097348 -223.846644)
		(width 0.0889)
		(layer "In15.Cu")
		(net "P5E_CPU1_PE0_TX_DN<4>")
	)
	(segment
		(start 92.1893 -219.01785)
		(end 92.187014 -219.01658)
		(width 0.0889)
		(layer "In15.Cu")
		(net "P5E_CPU1_PE0_TX_DN<4>")
	)
	(segment
		(start 72.261476 -328.17816)
		(end 69.53504 -334.760824)
		(width 0.14732)
		(layer "In15.Cu")
		(net "P5E_CPU1_PE0_TX_DN<4>")
	)
	(segment
		(start 92.663264 -219.833952)
		(end 92.657168 -219.830396)
		(width 0.0889)
		(layer "In15.Cu")
		(net "P5E_CPU1_PE0_TX_DN<4>")
	)
	(segment
		(start 81.307432 -251.180092)
		(end 81.307432 -252.39345)
		(width 0.14732)
		(layer "In15.Cu")
		(net "P5E_CPU1_PE0_TX_DN<4>")
	)
	(segment
		(start 75.169522 -323.787008)
		(end 72.273668 -328.15403)
		(width 0.14732)
		(layer "In15.Cu")
		(net "P5E_CPU1_PE0_TX_DN<4>")
	)
	(segment
		(start 92.657168 -219.830396)
		(end 92.648278 -219.825316)
		(width 0.0889)
		(layer "In15.Cu")
		(net "P5E_CPU1_PE0_TX_DN<4>")
	)
	(segment
		(start 78.712822 -233.807508)
		(end 78.915514 -244.907054)
		(width 0.14732)
		(layer "In15.Cu")
		(net "P5E_CPU1_PE0_TX_DN<4>")
	)
	(segment
		(start 93.129608 -222.273622)
		(end 93.126814 -222.272098)
		(width 0.0889)
		(layer "In15.Cu")
		(net "P5E_CPU1_PE0_TX_DN<4>")
	)
	(segment
		(start 94.097348 -223.846644)
		(end 94.01937 -223.867472)
		(width 0.0889)
		(layer "In15.Cu")
		(net "P5E_CPU1_PE0_TX_DN<4>")
	)
	(segment
		(start 85.92693 -218.60002)
		(end 85.904832 -218.60002)
		(width 0.0889)
		(layer "In15.Cu")
		(net "P5E_CPU1_PE0_TX_DN<4>")
	)
	(segment
		(start 91.247214 -219.01658)
		(end 91.232482 -219.007944)
		(width 0.0889)
		(layer "In15.Cu")
		(net "P5E_CPU1_PE0_TX_DN<4>")
	)
	(segment
		(start 79.362808 -247.347486)
		(end 80.167734 -248.852436)
		(width 0.14732)
		(layer "In15.Cu")
		(net "P5E_CPU1_PE0_TX_DN<4>")
	)
	(segment
		(start 87.41029 -218.957398)
		(end 87.41029 -218.957144)
		(width 0.0889)
		(layer "In15.Cu")
		(net "P5E_CPU1_PE0_TX_DN<4>")
	)
	(segment
		(start 78.788514 -258.85394)
		(end 78.774544 -258.889754)
		(width 0.14732)
		(layer "In15.Cu")
		(net "P5E_CPU1_PE0_TX_DN<4>")
	)
	(segment
		(start 92.657168 -221.458282)
		(end 92.648278 -221.453202)
		(width 0.0889)
		(layer "In15.Cu")
		(net "P5E_CPU1_PE0_TX_DN<4>")
	)
	(segment
		(start 81.421478 -221.147386)
		(end 80.473296 -222.891096)
		(width 0.14732)
		(layer "In15.Cu")
		(net "P5E_CPU1_PE0_TX_DN<4>")
	)
	(segment
		(start 81.307432 -252.39345)
		(end 81.306924 -252.393196)
		(width 0.14732)
		(layer "In15.Cu")
		(net "P5E_CPU1_PE0_TX_DN<4>")
	)
	(segment
		(start 92.187014 -219.01658)
		(end 92.172282 -219.007944)
		(width 0.0889)
		(layer "In15.Cu")
		(net "P5E_CPU1_PE0_TX_DN<4>")
	)
	(segment
		(start 85.96884 -218.64193)
		(end 85.92693 -218.60002)
		(width 0.0889)
		(layer "In15.Cu")
		(net "P5E_CPU1_PE0_TX_DN<4>")
	)
	(segment
		(start 78.774544 -258.889754)
		(end 78.77429 -258.889754)
		(width 0.14732)
		(layer "In15.Cu")
		(net "P5E_CPU1_PE0_TX_DN<4>")
	)
	(segment
		(start 80.473296 -222.891096)
		(end 78.712822 -233.807508)
		(width 0.14732)
		(layer "In15.Cu")
		(net "P5E_CPU1_PE0_TX_DN<4>")
	)
	(segment
		(start 78.080108 -266.604496)
		(end 80.860138 -310.267604)
		(width 0.14732)
		(layer "In15.Cu")
		(net "P5E_CPU1_PE0_TX_DN<4>")
	)
	(segment
		(start 92.939362 -221.94774)
		(end 92.939362 -221.932246)
		(width 0.0889)
		(layer "In15.Cu")
		(net "P5E_CPU1_PE0_TX_DN<4>")
	)
	(segment
		(start 85.904832 -218.60002)
		(end 84.963 -218.60002)
		(width 0.14732)
		(layer "In15.Cu")
		(net "P5E_CPU1_PE0_TX_DN<4>")
	)
	(segment
		(start 93.40977 -222.751396)
		(end 93.409516 -222.761556)
		(width 0.0889)
		(layer "In15.Cu")
		(net "P5E_CPU1_PE0_TX_DN<4>")
	)
	(segment
		(start 82.171286 -220.35008)
		(end 81.421478 -221.147386)
		(width 0.14732)
		(layer "In15.Cu")
		(net "P5E_CPU1_PE0_TX_DN<4>")
	)
	(segment
		(start 81.970118 -400.563588)
		(end 81.675478 -400.858228)
		(width 0.14732)
		(layer "In15.Cu")
		(net "P5E_CPU1_PE0_TX_DN<4>")
	)
	(segment
		(start 92.191332 -219.01912)
		(end 92.1893 -219.01785)
		(width 0.0889)
		(layer "In15.Cu")
		(net "P5E_CPU1_PE0_TX_DN<4>")
	)
	(segment
		(start 90.307414 -219.01658)
		(end 90.292682 -219.007944)
		(width 0.0889)
		(layer "In15.Cu")
		(net "P5E_CPU1_PE0_TX_DN<4>")
	)
	(arc
		(start 92.470224 -221.119192)
		(mid 92.521134 -220.944623)
		(end 92.648278 -220.814646)
		(width 0.0889)
		(layer "In15.Cu")
		(net "P5E_CPU1_PE0_TX_DN<4>")
	)
	(arc
		(start 92.657168 -220.809566)
		(mid 92.860473 -220.6087)
		(end 92.939616 -220.334078)
		(width 0.0889)
		(layer "In15.Cu")
		(net "P5E_CPU1_PE0_TX_DN<4>")
	)
	(arc
		(start 91.232482 -219.007944)
		(mid 90.956007 -218.940624)
		(end 90.68181 -219.01658)
		(width 0.0889)
		(layer "In15.Cu")
		(net "P5E_CPU1_PE0_TX_DN<4>")
	)
	(arc
		(start 92.172282 -219.007944)
		(mid 91.895807 -218.940624)
		(end 91.62161 -219.01658)
		(width 0.0889)
		(layer "In15.Cu")
		(net "P5E_CPU1_PE0_TX_DN<4>")
	)
	(arc
		(start 94.01937 -223.867472)
		(mid 93.918049 -223.741351)
		(end 93.879416 -223.584262)
		(width 0.0889)
		(layer "In15.Cu")
		(net "P5E_CPU1_PE0_TX_DN<4>")
	)
	(arc
		(start 91.62161 -219.01658)
		(mid 91.434412 -219.066723)
		(end 91.247214 -219.01658)
		(width 0.0889)
		(layer "In15.Cu")
		(net "P5E_CPU1_PE0_TX_DN<4>")
	)
	(arc
		(start 93.40977 -222.773748)
		(mid 93.409603 -222.762572)
		(end 93.40977 -222.751396)
		(width 0.0889)
		(layer "In15.Cu")
		(net "P5E_CPU1_PE0_TX_DN<4>")
	)
	(arc
		(start 92.648278 -219.825316)
		(mid 92.517364 -219.688956)
		(end 92.469716 -219.506038)
		(width 0.0889)
		(layer "In15.Cu")
		(net "P5E_CPU1_PE0_TX_DN<4>")
	)
	(arc
		(start 93.409516 -222.761556)
		(mid 93.335525 -222.48199)
		(end 93.13291 -222.275654)
		(width 0.0889)
		(layer "In15.Cu")
		(net "P5E_CPU1_PE0_TX_DN<4>")
	)
	(arc
		(start 93.117924 -222.267018)
		(mid 92.98701 -222.130658)
		(end 92.939362 -221.94774)
		(width 0.0889)
		(layer "In15.Cu")
		(net "P5E_CPU1_PE0_TX_DN<4>")
	)
	(arc
		(start 87.862664 -219.01658)
		(mid 87.675466 -219.066723)
		(end 87.488268 -219.01658)
		(width 0.0889)
		(layer "In15.Cu")
		(net "P5E_CPU1_PE0_TX_DN<4>")
	)
	(arc
		(start 87.488268 -219.01658)
		(mid 87.447338 -218.989547)
		(end 87.41029 -218.957398)
		(width 0.0889)
		(layer "In15.Cu")
		(net "P5E_CPU1_PE0_TX_DN<4>")
	)
	(arc
		(start 93.588078 -223.080834)
		(mid 93.460185 -222.949772)
		(end 93.40977 -222.773748)
		(width 0.0889)
		(layer "In15.Cu")
		(net "P5E_CPU1_PE0_TX_DN<4>")
	)
	(arc
		(start 92.469716 -219.506038)
		(mid 92.395725 -219.226472)
		(end 92.19311 -219.020136)
		(width 0.0889)
		(layer "In15.Cu")
		(net "P5E_CPU1_PE0_TX_DN<4>")
	)
	(arc
		(start 92.939362 -221.932246)
		(mid 92.859992 -221.658512)
		(end 92.657168 -221.458282)
		(width 0.0889)
		(layer "In15.Cu")
		(net "P5E_CPU1_PE0_TX_DN<4>")
	)
	(arc
		(start 89.74201 -219.01658)
		(mid 89.554812 -219.066723)
		(end 89.367614 -219.01658)
		(width 0.0889)
		(layer "In15.Cu")
		(net "P5E_CPU1_PE0_TX_DN<4>")
	)
	(arc
		(start 93.879416 -223.557084)
		(mid 93.799254 -223.284895)
		(end 93.596968 -223.085914)
		(width 0.0889)
		(layer "In15.Cu")
		(net "P5E_CPU1_PE0_TX_DN<4>")
	)
	(arc
		(start 88.802464 -219.01658)
		(mid 88.615266 -219.066723)
		(end 88.428068 -219.01658)
		(width 0.0889)
		(layer "In15.Cu")
		(net "P5E_CPU1_PE0_TX_DN<4>")
	)
	(arc
		(start 88.428068 -219.01658)
		(mid 88.145366 -218.940804)
		(end 87.862664 -219.01658)
		(width 0.0889)
		(layer "In15.Cu")
		(net "P5E_CPU1_PE0_TX_DN<4>")
	)
	(arc
		(start 90.68181 -219.01658)
		(mid 90.494612 -219.066723)
		(end 90.307414 -219.01658)
		(width 0.0889)
		(layer "In15.Cu")
		(net "P5E_CPU1_PE0_TX_DN<4>")
	)
	(arc
		(start 89.3572 -219.010484)
		(mid 89.079022 -218.940761)
		(end 88.802464 -219.01658)
		(width 0.0889)
		(layer "In15.Cu")
		(net "P5E_CPU1_PE0_TX_DN<4>")
	)
	(arc
		(start 92.939616 -220.319854)
		(mid 92.8657 -220.040352)
		(end 92.663264 -219.833952)
		(width 0.0889)
		(layer "In15.Cu")
		(net "P5E_CPU1_PE0_TX_DN<4>")
	)
	(arc
		(start 92.648278 -221.453202)
		(mid 92.519959 -221.32123)
		(end 92.46997 -221.144084)
		(width 0.0889)
		(layer "In15.Cu")
		(net "P5E_CPU1_PE0_TX_DN<4>")
	)
	(arc
		(start 92.46997 -221.144084)
		(mid 92.46989 -221.131636)
		(end 92.470224 -221.119192)
		(width 0.0889)
		(layer "In15.Cu")
		(net "P5E_CPU1_PE0_TX_DN<4>")
	)
	(arc
		(start 90.292682 -219.007944)
		(mid 90.016207 -218.940624)
		(end 89.74201 -219.01658)
		(width 0.0889)
		(layer "In15.Cu")
		(net "P5E_CPU1_PE0_TX_DN<4>")
	)
	(segment
		(start 92.844112 -224.925382)
		(end 92.844366 -224.925128)
		(width 0.13208)
		(layer "F.Cu")
		(net "P5E_CPU1_PE0_TX_DN<3>")
	)
	(segment
		(start 85.04428 -401.16379)
		(end 84.738718 -400.858228)
		(width 0.13208)
		(layer "F.Cu")
		(net "P5E_CPU1_PE0_TX_DN<3>")
	)
	(segment
		(start 85.04428 -401.777962)
		(end 85.04428 -401.16379)
		(width 0.13208)
		(layer "F.Cu")
		(net "P5E_CPU1_PE0_TX_DN<3>")
	)
	(segment
		(start 92.844366 -224.925128)
		(end 92.844366 -224.389442)
		(width 0.13208)
		(layer "F.Cu")
		(net "P5E_CPU1_PE0_TX_DN<3>")
	)
	(segment
		(start 84.71789 -402.104352)
		(end 85.04428 -401.777962)
		(width 0.13208)
		(layer "F.Cu")
		(net "P5E_CPU1_PE0_TX_DN<3>")
	)
	(segment
		(start 84.713318 -402.104352)
		(end 84.71789 -402.104352)
		(width 0.13208)
		(layer "F.Cu")
		(net "P5E_CPU1_PE0_TX_DN<3>")
	)
	(segment
		(start 85.904832 -219.83954)
		(end 85.330792 -219.83954)
		(width 0.14732)
		(layer "In15.Cu")
		(net "P5E_CPU1_PE0_TX_DN<3>")
	)
	(segment
		(start 81.48066 -223.036384)
		(end 79.687674 -233.931206)
		(width 0.14732)
		(layer "In15.Cu")
		(net "P5E_CPU1_PE0_TX_DN<3>")
	)
	(segment
		(start 91.529916 -221.133924)
		(end 91.529916 -221.115382)
		(width 0.0889)
		(layer "In15.Cu")
		(net "P5E_CPU1_PE0_TX_DN<3>")
	)
	(segment
		(start 73.359264 -328.235564)
		(end 70.466712 -335.219294)
		(width 0.14732)
		(layer "In15.Cu")
		(net "P5E_CPU1_PE0_TX_DN<3>")
	)
	(segment
		(start 70.936358 -351.707958)
		(end 85.033358 -399.720308)
		(width 0.14732)
		(layer "In15.Cu")
		(net "P5E_CPU1_PE0_TX_DN<3>")
	)
	(segment
		(start 70.466712 -335.219294)
		(end 70.37705 -335.686654)
		(width 0.14732)
		(layer "In15.Cu")
		(net "P5E_CPU1_PE0_TX_DN<3>")
	)
	(segment
		(start 92.19311 -222.275654)
		(end 92.189808 -222.273622)
		(width 0.0889)
		(layer "In15.Cu")
		(net "P5E_CPU1_PE0_TX_DN<3>")
	)
	(segment
		(start 91.717368 -221.458282)
		(end 91.708478 -221.453202)
		(width 0.0889)
		(layer "In15.Cu")
		(net "P5E_CPU1_PE0_TX_DN<3>")
	)
	(segment
		(start 90.226896 -219.82176)
		(end 90.212164 -219.830396)
		(width 0.0889)
		(layer "In15.Cu")
		(net "P5E_CPU1_PE0_TX_DN<3>")
	)
	(segment
		(start 92.187014 -222.272098)
		(end 92.18549 -222.271336)
		(width 0.0889)
		(layer "In15.Cu")
		(net "P5E_CPU1_PE0_TX_DN<3>")
	)
	(segment
		(start 87.01786 -219.830396)
		(end 86.994492 -219.816934)
		(width 0.0889)
		(layer "In15.Cu")
		(net "P5E_CPU1_PE0_TX_DN<3>")
	)
	(segment
		(start 92.657168 -223.085914)
		(end 92.648278 -223.080834)
		(width 0.0889)
		(layer "In15.Cu")
		(net "P5E_CPU1_PE0_TX_DN<3>")
	)
	(segment
		(start 91.999562 -221.94774)
		(end 91.999562 -221.932246)
		(width 0.0889)
		(layer "In15.Cu")
		(net "P5E_CPU1_PE0_TX_DN<3>")
	)
	(segment
		(start 82.238342 -252.579124)
		(end 79.69377 -259.105654)
		(width 0.14732)
		(layer "In15.Cu")
		(net "P5E_CPU1_PE0_TX_DN<3>")
	)
	(segment
		(start 79.69377 -259.105654)
		(end 79.017622 -266.616688)
		(width 0.14732)
		(layer "In15.Cu")
		(net "P5E_CPU1_PE0_TX_DN<3>")
	)
	(segment
		(start 87.40648 -219.82176)
		(end 87.391748 -219.830396)
		(width 0.0889)
		(layer "In15.Cu")
		(net "P5E_CPU1_PE0_TX_DN<3>")
	)
	(segment
		(start 88.332564 -219.830396)
		(end 88.320626 -219.837254)
		(width 0.0889)
		(layer "In15.Cu")
		(net "P5E_CPU1_PE0_TX_DN<3>")
	)
	(segment
		(start 92.939616 -223.575626)
		(end 92.939616 -223.561402)
		(width 0.0889)
		(layer "In15.Cu")
		(net "P5E_CPU1_PE0_TX_DN<3>")
	)
	(segment
		(start 87.029798 -219.837254)
		(end 87.01786 -219.830396)
		(width 0.0889)
		(layer "In15.Cu")
		(net "P5E_CPU1_PE0_TX_DN<3>")
	)
	(segment
		(start 85.96884 -219.88145)
		(end 85.92693 -219.83954)
		(width 0.0889)
		(layer "In15.Cu")
		(net "P5E_CPU1_PE0_TX_DN<3>")
	)
	(segment
		(start 75.994768 -324.320916)
		(end 73.359264 -328.235564)
		(width 0.14732)
		(layer "In15.Cu")
		(net "P5E_CPU1_PE0_TX_DN<3>")
	)
	(segment
		(start 82.241644 -252.569218)
		(end 82.238342 -252.579124)
		(width 0.14732)
		(layer "In15.Cu")
		(net "P5E_CPU1_PE0_TX_DN<3>")
	)
	(segment
		(start 85.330792 -219.83954)
		(end 82.303112 -221.628462)
		(width 0.14732)
		(layer "In15.Cu")
		(net "P5E_CPU1_PE0_TX_DN<3>")
	)
	(segment
		(start 82.241898 -252.569218)
		(end 82.241644 -252.569218)
		(width 0.14732)
		(layer "In15.Cu")
		(net "P5E_CPU1_PE0_TX_DN<3>")
	)
	(segment
		(start 81.811622 -310.50103)
		(end 75.994768 -324.320916)
		(width 0.14732)
		(layer "In15.Cu")
		(net "P5E_CPU1_PE0_TX_DN<3>")
	)
	(segment
		(start 85.033358 -399.720308)
		(end 85.033358 -400.563588)
		(width 0.14732)
		(layer "In15.Cu")
		(net "P5E_CPU1_PE0_TX_DN<3>")
	)
	(segment
		(start 82.241898 -251.006102)
		(end 82.241898 -252.569218)
		(width 0.14732)
		(layer "In15.Cu")
		(net "P5E_CPU1_PE0_TX_DN<3>")
	)
	(segment
		(start 70.371208 -335.717134)
		(end 70.936358 -351.707958)
		(width 0.14732)
		(layer "In15.Cu")
		(net "P5E_CPU1_PE0_TX_DN<3>")
	)
	(segment
		(start 92.657168 -224.7138)
		(end 92.648278 -224.70872)
		(width 0.0889)
		(layer "In15.Cu")
		(net "P5E_CPU1_PE0_TX_DN<3>")
	)
	(segment
		(start 79.90078 -245.046246)
		(end 80.2513 -247.036082)
		(width 0.14732)
		(layer "In15.Cu")
		(net "P5E_CPU1_PE0_TX_DN<3>")
	)
	(segment
		(start 92.844366 -224.389442)
		(end 93.00083 -224.66046)
		(width 0.0889)
		(layer "In15.Cu")
		(net "P5E_CPU1_PE0_TX_DN<3>")
	)
	(segment
		(start 92.46997 -222.751396)
		(end 92.469716 -222.761556)
		(width 0.0889)
		(layer "In15.Cu")
		(net "P5E_CPU1_PE0_TX_DN<3>")
	)
	(segment
		(start 79.017622 -266.616688)
		(end 81.811622 -310.50103)
		(width 0.14732)
		(layer "In15.Cu")
		(net "P5E_CPU1_PE0_TX_DN<3>")
	)
	(segment
		(start 81.789016 -249.912124)
		(end 82.241898 -251.006102)
		(width 0.14732)
		(layer "In15.Cu")
		(net "P5E_CPU1_PE0_TX_DN<3>")
	)
	(segment
		(start 92.18549 -222.271336)
		(end 92.178124 -222.267018)
		(width 0.0889)
		(layer "In15.Cu")
		(net "P5E_CPU1_PE0_TX_DN<3>")
	)
	(segment
		(start 86.264496 -219.88145)
		(end 85.96884 -219.88145)
		(width 0.0889)
		(layer "In15.Cu")
		(net "P5E_CPU1_PE0_TX_DN<3>")
	)
	(segment
		(start 85.92693 -219.83954)
		(end 85.904832 -219.83954)
		(width 0.0889)
		(layer "In15.Cu")
		(net "P5E_CPU1_PE0_TX_DN<3>")
	)
	(segment
		(start 91.247468 -220.644212)
		(end 91.238578 -220.639132)
		(width 0.0889)
		(layer "In15.Cu")
		(net "P5E_CPU1_PE0_TX_DN<3>")
	)
	(segment
		(start 80.2513 -247.036082)
		(end 81.789016 -249.912124)
		(width 0.14732)
		(layer "In15.Cu")
		(net "P5E_CPU1_PE0_TX_DN<3>")
	)
	(segment
		(start 92.657168 -224.065084)
		(end 92.663264 -224.061528)
		(width 0.0889)
		(layer "In15.Cu")
		(net "P5E_CPU1_PE0_TX_DN<3>")
	)
	(segment
		(start 79.687674 -233.931206)
		(end 79.90078 -245.046246)
		(width 0.14732)
		(layer "In15.Cu")
		(net "P5E_CPU1_PE0_TX_DN<3>")
	)
	(segment
		(start 92.648278 -224.070164)
		(end 92.657168 -224.065084)
		(width 0.0889)
		(layer "In15.Cu")
		(net "P5E_CPU1_PE0_TX_DN<3>")
	)
	(segment
		(start 93.00083 -224.66046)
		(end 92.979748 -224.738438)
		(width 0.0889)
		(layer "In15.Cu")
		(net "P5E_CPU1_PE0_TX_DN<3>")
	)
	(segment
		(start 70.376796 -335.686654)
		(end 70.371208 -335.717134)
		(width 0.14732)
		(layer "In15.Cu")
		(net "P5E_CPU1_PE0_TX_DN<3>")
	)
	(segment
		(start 85.033358 -400.563588)
		(end 84.738718 -400.858228)
		(width 0.14732)
		(layer "In15.Cu")
		(net "P5E_CPU1_PE0_TX_DN<3>")
	)
	(segment
		(start 92.189808 -222.273622)
		(end 92.187014 -222.272098)
		(width 0.0889)
		(layer "In15.Cu")
		(net "P5E_CPU1_PE0_TX_DN<3>")
	)
	(segment
		(start 70.37705 -335.686654)
		(end 70.376796 -335.686654)
		(width 0.14732)
		(layer "In15.Cu")
		(net "P5E_CPU1_PE0_TX_DN<3>")
	)
	(segment
		(start 90.783664 -219.833952)
		(end 90.777568 -219.830396)
		(width 0.0889)
		(layer "In15.Cu")
		(net "P5E_CPU1_PE0_TX_DN<3>")
	)
	(segment
		(start 82.303112 -221.628462)
		(end 81.48066 -223.036384)
		(width 0.14732)
		(layer "In15.Cu")
		(net "P5E_CPU1_PE0_TX_DN<3>")
	)
	(arc
		(start 91.999562 -221.932246)
		(mid 91.920192 -221.658512)
		(end 91.717368 -221.458282)
		(width 0.0889)
		(layer "In15.Cu")
		(net "P5E_CPU1_PE0_TX_DN<3>")
	)
	(arc
		(start 87.95766 -219.830396)
		(mid 87.683207 -219.754433)
		(end 87.40648 -219.82176)
		(width 0.0889)
		(layer "In15.Cu")
		(net "P5E_CPU1_PE0_TX_DN<3>")
	)
	(arc
		(start 91.708478 -221.453202)
		(mid 91.577564 -221.316842)
		(end 91.529916 -221.133924)
		(width 0.0889)
		(layer "In15.Cu")
		(net "P5E_CPU1_PE0_TX_DN<3>")
	)
	(arc
		(start 92.648278 -223.080834)
		(mid 92.521198 -222.95082)
		(end 92.470224 -222.776288)
		(width 0.0889)
		(layer "In15.Cu")
		(net "P5E_CPU1_PE0_TX_DN<3>")
	)
	(arc
		(start 88.320626 -219.837254)
		(mid 88.138261 -219.880697)
		(end 87.95766 -219.830396)
		(width 0.0889)
		(layer "In15.Cu")
		(net "P5E_CPU1_PE0_TX_DN<3>")
	)
	(arc
		(start 89.837768 -219.830396)
		(mid 89.555066 -219.75462)
		(end 89.272364 -219.830396)
		(width 0.0889)
		(layer "In15.Cu")
		(net "P5E_CPU1_PE0_TX_DN<3>")
	)
	(arc
		(start 92.469716 -222.761556)
		(mid 92.395725 -222.48199)
		(end 92.19311 -222.275654)
		(width 0.0889)
		(layer "In15.Cu")
		(net "P5E_CPU1_PE0_TX_DN<3>")
	)
	(arc
		(start 92.648278 -224.70872)
		(mid 92.469802 -224.389442)
		(end 92.648278 -224.070164)
		(width 0.0889)
		(layer "In15.Cu")
		(net "P5E_CPU1_PE0_TX_DN<3>")
	)
	(arc
		(start 89.272364 -219.830396)
		(mid 89.085166 -219.880539)
		(end 88.897968 -219.830396)
		(width 0.0889)
		(layer "In15.Cu")
		(net "P5E_CPU1_PE0_TX_DN<3>")
	)
	(arc
		(start 92.979748 -224.738438)
		(mid 92.815652 -224.762785)
		(end 92.657168 -224.7138)
		(width 0.0889)
		(layer "In15.Cu")
		(net "P5E_CPU1_PE0_TX_DN<3>")
	)
	(arc
		(start 91.529916 -221.115382)
		(mid 91.449754 -220.843193)
		(end 91.247468 -220.644212)
		(width 0.0889)
		(layer "In15.Cu")
		(net "P5E_CPU1_PE0_TX_DN<3>")
	)
	(arc
		(start 87.391748 -219.830396)
		(mid 87.211655 -219.880472)
		(end 87.029798 -219.837254)
		(width 0.0889)
		(layer "In15.Cu")
		(net "P5E_CPU1_PE0_TX_DN<3>")
	)
	(arc
		(start 86.994492 -219.816934)
		(mid 86.721628 -219.754414)
		(end 86.452202 -219.830396)
		(width 0.0889)
		(layer "In15.Cu")
		(net "P5E_CPU1_PE0_TX_DN<3>")
	)
	(arc
		(start 91.060016 -220.319854)
		(mid 90.9861 -220.040352)
		(end 90.783664 -219.833952)
		(width 0.0889)
		(layer "In15.Cu")
		(net "P5E_CPU1_PE0_TX_DN<3>")
	)
	(arc
		(start 92.939616 -223.561402)
		(mid 92.860475 -223.286779)
		(end 92.657168 -223.085914)
		(width 0.0889)
		(layer "In15.Cu")
		(net "P5E_CPU1_PE0_TX_DN<3>")
	)
	(arc
		(start 88.897968 -219.830396)
		(mid 88.615266 -219.75462)
		(end 88.332564 -219.830396)
		(width 0.0889)
		(layer "In15.Cu")
		(net "P5E_CPU1_PE0_TX_DN<3>")
	)
	(arc
		(start 90.212164 -219.830396)
		(mid 90.024966 -219.880539)
		(end 89.837768 -219.830396)
		(width 0.0889)
		(layer "In15.Cu")
		(net "P5E_CPU1_PE0_TX_DN<3>")
	)
	(arc
		(start 86.452202 -219.830396)
		(mid 86.361712 -219.868282)
		(end 86.264496 -219.88145)
		(width 0.0889)
		(layer "In15.Cu")
		(net "P5E_CPU1_PE0_TX_DN<3>")
	)
	(arc
		(start 91.238578 -220.639132)
		(mid 91.107664 -220.502772)
		(end 91.060016 -220.319854)
		(width 0.0889)
		(layer "In15.Cu")
		(net "P5E_CPU1_PE0_TX_DN<3>")
	)
	(arc
		(start 92.178124 -222.267018)
		(mid 92.04721 -222.130658)
		(end 91.999562 -221.94774)
		(width 0.0889)
		(layer "In15.Cu")
		(net "P5E_CPU1_PE0_TX_DN<3>")
	)
	(arc
		(start 92.663264 -224.061528)
		(mid 92.865677 -223.855115)
		(end 92.939616 -223.575626)
		(width 0.0889)
		(layer "In15.Cu")
		(net "P5E_CPU1_PE0_TX_DN<3>")
	)
	(arc
		(start 90.777568 -219.830396)
		(mid 90.503369 -219.754561)
		(end 90.226896 -219.82176)
		(width 0.0889)
		(layer "In15.Cu")
		(net "P5E_CPU1_PE0_TX_DN<3>")
	)
	(arc
		(start 92.470224 -222.776288)
		(mid 92.469891 -222.763844)
		(end 92.46997 -222.751396)
		(width 0.0889)
		(layer "In15.Cu")
		(net "P5E_CPU1_PE0_TX_DN<3>")
	)
	(segment
		(start 92.374466 -224.111566)
		(end 92.374212 -224.111312)
		(width 0.13208)
		(layer "F.Cu")
		(net "P5E_CPU1_PE0_TX_DN<2>")
	)
	(segment
		(start 92.374212 -224.111312)
		(end 92.374212 -223.575626)
		(width 0.13208)
		(layer "F.Cu")
		(net "P5E_CPU1_PE0_TX_DN<2>")
	)
	(segment
		(start 87.776558 -402.104352)
		(end 87.78113 -402.104352)
		(width 0.13208)
		(layer "F.Cu")
		(net "P5E_CPU1_PE0_TX_DN<2>")
	)
	(segment
		(start 88.10752 -401.16379)
		(end 87.801958 -400.858228)
		(width 0.13208)
		(layer "F.Cu")
		(net "P5E_CPU1_PE0_TX_DN<2>")
	)
	(segment
		(start 88.10752 -401.777962)
		(end 88.10752 -401.16379)
		(width 0.13208)
		(layer "F.Cu")
		(net "P5E_CPU1_PE0_TX_DN<2>")
	)
	(segment
		(start 87.78113 -402.104352)
		(end 88.10752 -401.777962)
		(width 0.13208)
		(layer "F.Cu")
		(net "P5E_CPU1_PE0_TX_DN<2>")
	)
	(segment
		(start 71.338694 -336.009996)
		(end 71.335646 -336.034126)
		(width 0.14732)
		(layer "In15.Cu")
		(net "P5E_CPU1_PE0_TX_DN<2>")
	)
	(segment
		(start 89.367614 -222.272098)
		(end 89.3572 -222.266002)
		(width 0.0889)
		(layer "In15.Cu")
		(net "P5E_CPU1_PE0_TX_DN<2>")
	)
	(segment
		(start 83.181444 -252.746256)
		(end 83.18119 -252.746256)
		(width 0.14732)
		(layer "In15.Cu")
		(net "P5E_CPU1_PE0_TX_DN<2>")
	)
	(segment
		(start 80.84566 -244.8179)
		(end 81.201006 -246.839994)
		(width 0.14732)
		(layer "In15.Cu")
		(net "P5E_CPU1_PE0_TX_DN<2>")
	)
	(segment
		(start 81.201006 -246.839994)
		(end 82.632804 -249.51817)
		(width 0.14732)
		(layer "In15.Cu")
		(net "P5E_CPU1_PE0_TX_DN<2>")
	)
	(segment
		(start 88.096598 -399.694908)
		(end 88.096598 -400.563588)
		(width 0.14732)
		(layer "In15.Cu")
		(net "P5E_CPU1_PE0_TX_DN<2>")
	)
	(segment
		(start 83.181444 -250.843796)
		(end 83.181444 -252.746256)
		(width 0.14732)
		(layer "In15.Cu")
		(net "P5E_CPU1_PE0_TX_DN<2>")
	)
	(segment
		(start 90.307414 -222.272098)
		(end 90.292682 -222.263462)
		(width 0.0889)
		(layer "In15.Cu")
		(net "P5E_CPU1_PE0_TX_DN<2>")
	)
	(segment
		(start 79.960216 -266.62888)
		(end 82.766916 -310.718962)
		(width 0.14732)
		(layer "In15.Cu")
		(net "P5E_CPU1_PE0_TX_DN<2>")
	)
	(segment
		(start 80.63865 -234.03306)
		(end 80.84566 -244.8179)
		(width 0.14732)
		(layer "In15.Cu")
		(net "P5E_CPU1_PE0_TX_DN<2>")
	)
	(segment
		(start 80.618076 -259.322824)
		(end 79.960216 -266.62888)
		(width 0.14732)
		(layer "In15.Cu")
		(net "P5E_CPU1_PE0_TX_DN<2>")
	)
	(segment
		(start 85.325712 -222.196152)
		(end 83.856068 -222.196152)
		(width 0.0889)
		(layer "In15.Cu")
		(net "P5E_CPU1_PE0_TX_DN<2>")
	)
	(segment
		(start 71.338948 -336.009996)
		(end 71.338694 -336.009996)
		(width 0.14732)
		(layer "In15.Cu")
		(net "P5E_CPU1_PE0_TX_DN<2>")
	)
	(segment
		(start 76.78928 -324.922388)
		(end 74.226166 -328.69378)
		(width 0.14732)
		(layer "In15.Cu")
		(net "P5E_CPU1_PE0_TX_DN<2>")
	)
	(segment
		(start 91.231974 -222.263462)
		(end 91.232482 -222.263462)
		(width 0.0889)
		(layer "In15.Cu")
		(net "P5E_CPU1_PE0_TX_DN<2>")
	)
	(segment
		(start 88.096598 -400.563588)
		(end 87.801958 -400.858228)
		(width 0.14732)
		(layer "In15.Cu")
		(net "P5E_CPU1_PE0_TX_DN<2>")
	)
	(segment
		(start 74.226166 -328.69378)
		(end 71.408798 -335.494376)
		(width 0.14732)
		(layer "In15.Cu")
		(net "P5E_CPU1_PE0_TX_DN<2>")
	)
	(segment
		(start 82.632804 -249.51817)
		(end 83.181444 -250.843796)
		(width 0.14732)
		(layer "In15.Cu")
		(net "P5E_CPU1_PE0_TX_DN<2>")
	)
	(segment
		(start 91.717368 -223.085914)
		(end 91.708478 -223.080834)
		(width 0.0889)
		(layer "In15.Cu")
		(net "P5E_CPU1_PE0_TX_DN<2>")
	)
	(segment
		(start 92.374212 -223.575626)
		(end 92.217748 -223.846644)
		(width 0.0889)
		(layer "In15.Cu")
		(net "P5E_CPU1_PE0_TX_DN<2>")
	)
	(segment
		(start 83.79206 -222.154242)
		(end 83.380326 -222.154242)
		(width 0.14732)
		(layer "In15.Cu")
		(net "P5E_CPU1_PE0_TX_DN<2>")
	)
	(segment
		(start 83.18119 -252.746256)
		(end 80.618076 -259.322824)
		(width 0.14732)
		(layer "In15.Cu")
		(net "P5E_CPU1_PE0_TX_DN<2>")
	)
	(segment
		(start 71.335646 -336.034126)
		(end 72.0344 -351.748344)
		(width 0.14732)
		(layer "In15.Cu")
		(net "P5E_CPU1_PE0_TX_DN<2>")
	)
	(segment
		(start 82.459576 -223.221296)
		(end 80.63865 -234.03306)
		(width 0.14732)
		(layer "In15.Cu")
		(net "P5E_CPU1_PE0_TX_DN<2>")
	)
	(segment
		(start 91.999816 -223.584262)
		(end 91.999816 -223.557084)
		(width 0.0889)
		(layer "In15.Cu")
		(net "P5E_CPU1_PE0_TX_DN<2>")
	)
	(segment
		(start 83.010248 -222.329248)
		(end 82.459576 -223.221296)
		(width 0.14732)
		(layer "In15.Cu")
		(net "P5E_CPU1_PE0_TX_DN<2>")
	)
	(segment
		(start 83.814158 -222.154242)
		(end 83.79206 -222.154242)
		(width 0.0889)
		(layer "In15.Cu")
		(net "P5E_CPU1_PE0_TX_DN<2>")
	)
	(segment
		(start 92.217748 -223.846644)
		(end 92.13977 -223.867472)
		(width 0.0889)
		(layer "In15.Cu")
		(net "P5E_CPU1_PE0_TX_DN<2>")
	)
	(segment
		(start 83.380326 -222.154242)
		(end 83.010248 -222.329248)
		(width 0.14732)
		(layer "In15.Cu")
		(net "P5E_CPU1_PE0_TX_DN<2>")
	)
	(segment
		(start 83.856068 -222.196152)
		(end 83.814158 -222.154242)
		(width 0.0889)
		(layer "In15.Cu")
		(net "P5E_CPU1_PE0_TX_DN<2>")
	)
	(segment
		(start 91.53017 -222.751396)
		(end 91.529916 -222.761556)
		(width 0.0889)
		(layer "In15.Cu")
		(net "P5E_CPU1_PE0_TX_DN<2>")
	)
	(segment
		(start 82.766916 -310.718962)
		(end 76.78928 -324.922388)
		(width 0.14732)
		(layer "In15.Cu")
		(net "P5E_CPU1_PE0_TX_DN<2>")
	)
	(segment
		(start 91.25331 -222.275654)
		(end 91.231974 -222.263462)
		(width 0.0889)
		(layer "In15.Cu")
		(net "P5E_CPU1_PE0_TX_DN<2>")
	)
	(segment
		(start 72.0344 -351.748344)
		(end 88.096598 -399.694908)
		(width 0.14732)
		(layer "In15.Cu")
		(net "P5E_CPU1_PE0_TX_DN<2>")
	)
	(segment
		(start 71.408798 -335.494376)
		(end 71.338948 -336.009996)
		(width 0.14732)
		(layer "In15.Cu")
		(net "P5E_CPU1_PE0_TX_DN<2>")
	)
	(arc
		(start 87.862664 -222.272098)
		(mid 87.675466 -222.322241)
		(end 87.488268 -222.272098)
		(width 0.0889)
		(layer "In15.Cu")
		(net "P5E_CPU1_PE0_TX_DN<2>")
	)
	(arc
		(start 91.529916 -222.761556)
		(mid 91.455925 -222.48199)
		(end 91.25331 -222.275654)
		(width 0.0889)
		(layer "In15.Cu")
		(net "P5E_CPU1_PE0_TX_DN<2>")
	)
	(arc
		(start 87.488268 -222.272098)
		(mid 87.205566 -222.196322)
		(end 86.922864 -222.272098)
		(width 0.0889)
		(layer "In15.Cu")
		(net "P5E_CPU1_PE0_TX_DN<2>")
	)
	(arc
		(start 91.708478 -223.080834)
		(mid 91.580585 -222.949772)
		(end 91.53017 -222.773748)
		(width 0.0889)
		(layer "In15.Cu")
		(net "P5E_CPU1_PE0_TX_DN<2>")
	)
	(arc
		(start 90.68181 -222.272098)
		(mid 90.494612 -222.322241)
		(end 90.307414 -222.272098)
		(width 0.0889)
		(layer "In15.Cu")
		(net "P5E_CPU1_PE0_TX_DN<2>")
	)
	(arc
		(start 91.999816 -223.557084)
		(mid 91.919654 -223.284895)
		(end 91.717368 -223.085914)
		(width 0.0889)
		(layer "In15.Cu")
		(net "P5E_CPU1_PE0_TX_DN<2>")
	)
	(arc
		(start 85.608668 -222.272098)
		(mid 85.472196 -222.215475)
		(end 85.325712 -222.196152)
		(width 0.0889)
		(layer "In15.Cu")
		(net "P5E_CPU1_PE0_TX_DN<2>")
	)
	(arc
		(start 85.983064 -222.272098)
		(mid 85.795866 -222.322241)
		(end 85.608668 -222.272098)
		(width 0.0889)
		(layer "In15.Cu")
		(net "P5E_CPU1_PE0_TX_DN<2>")
	)
	(arc
		(start 89.74201 -222.272098)
		(mid 89.554812 -222.322241)
		(end 89.367614 -222.272098)
		(width 0.0889)
		(layer "In15.Cu")
		(net "P5E_CPU1_PE0_TX_DN<2>")
	)
	(arc
		(start 88.428068 -222.272098)
		(mid 88.145366 -222.196322)
		(end 87.862664 -222.272098)
		(width 0.0889)
		(layer "In15.Cu")
		(net "P5E_CPU1_PE0_TX_DN<2>")
	)
	(arc
		(start 92.13977 -223.867472)
		(mid 92.038449 -223.741351)
		(end 91.999816 -223.584262)
		(width 0.0889)
		(layer "In15.Cu")
		(net "P5E_CPU1_PE0_TX_DN<2>")
	)
	(arc
		(start 91.53017 -222.773748)
		(mid 91.530003 -222.762572)
		(end 91.53017 -222.751396)
		(width 0.0889)
		(layer "In15.Cu")
		(net "P5E_CPU1_PE0_TX_DN<2>")
	)
	(arc
		(start 86.548468 -222.272098)
		(mid 86.265766 -222.196322)
		(end 85.983064 -222.272098)
		(width 0.0889)
		(layer "In15.Cu")
		(net "P5E_CPU1_PE0_TX_DN<2>")
	)
	(arc
		(start 88.802464 -222.272098)
		(mid 88.615266 -222.322241)
		(end 88.428068 -222.272098)
		(width 0.0889)
		(layer "In15.Cu")
		(net "P5E_CPU1_PE0_TX_DN<2>")
	)
	(arc
		(start 86.922864 -222.272098)
		(mid 86.735666 -222.322241)
		(end 86.548468 -222.272098)
		(width 0.0889)
		(layer "In15.Cu")
		(net "P5E_CPU1_PE0_TX_DN<2>")
	)
	(arc
		(start 89.3572 -222.266002)
		(mid 89.079022 -222.196279)
		(end 88.802464 -222.272098)
		(width 0.0889)
		(layer "In15.Cu")
		(net "P5E_CPU1_PE0_TX_DN<2>")
	)
	(arc
		(start 91.232482 -222.263462)
		(mid 90.956007 -222.196142)
		(end 90.68181 -222.272098)
		(width 0.0889)
		(layer "In15.Cu")
		(net "P5E_CPU1_PE0_TX_DN<2>")
	)
	(arc
		(start 90.292682 -222.263462)
		(mid 90.016207 -222.196142)
		(end 89.74201 -222.272098)
		(width 0.0889)
		(layer "In15.Cu")
		(net "P5E_CPU1_PE0_TX_DN<2>")
	)
	(segment
		(start 90.964512 -224.925382)
		(end 90.964766 -224.925128)
		(width 0.13208)
		(layer "F.Cu")
		(net "P5E_CPU1_PE0_TX_DN<1>")
	)
	(segment
		(start 90.964766 -224.925128)
		(end 90.964766 -224.389442)
		(width 0.13208)
		(layer "F.Cu")
		(net "P5E_CPU1_PE0_TX_DN<1>")
	)
	(segment
		(start 90.839798 -402.104352)
		(end 90.84437 -402.104352)
		(width 0.13208)
		(layer "F.Cu")
		(net "P5E_CPU1_PE0_TX_DN<1>")
	)
	(segment
		(start 91.17076 -401.777962)
		(end 91.17076 -401.16379)
		(width 0.13208)
		(layer "F.Cu")
		(net "P5E_CPU1_PE0_TX_DN<1>")
	)
	(segment
		(start 90.84437 -402.104352)
		(end 91.17076 -401.777962)
		(width 0.13208)
		(layer "F.Cu")
		(net "P5E_CPU1_PE0_TX_DN<1>")
	)
	(segment
		(start 91.17076 -401.16379)
		(end 90.865198 -400.858228)
		(width 0.13208)
		(layer "F.Cu")
		(net "P5E_CPU1_PE0_TX_DN<1>")
	)
	(segment
		(start 83.819746 -223.752664)
		(end 81.822036 -234.145836)
		(width 0.14732)
		(layer "In15.Cu")
		(net "P5E_CPU1_PE0_TX_DN<1>")
	)
	(segment
		(start 84.456016 -223.175576)
		(end 84.171536 -223.460056)
		(width 0.0889)
		(layer "In15.Cu")
		(net "P5E_CPU1_PE0_TX_DN<1>")
	)
	(segment
		(start 83.471258 -249.112786)
		(end 84.111084 -250.65736)
		(width 0.14732)
		(layer "In15.Cu")
		(net "P5E_CPU1_PE0_TX_DN<1>")
	)
	(segment
		(start 84.112608 -223.460056)
		(end 84.097114 -223.47555)
		(width 0.0889)
		(layer "In15.Cu")
		(net "P5E_CPU1_PE0_TX_DN<1>")
	)
	(segment
		(start 91.060016 -223.575626)
		(end 91.060016 -223.561402)
		(width 0.0889)
		(layer "In15.Cu")
		(net "P5E_CPU1_PE0_TX_DN<1>")
	)
	(segment
		(start 82.14614 -246.63527)
		(end 83.471258 -249.112786)
		(width 0.14732)
		(layer "In15.Cu")
		(net "P5E_CPU1_PE0_TX_DN<1>")
	)
	(segment
		(start 81.89595 -245.21541)
		(end 82.14614 -246.63527)
		(width 0.14732)
		(layer "In15.Cu")
		(net "P5E_CPU1_PE0_TX_DN<1>")
	)
	(segment
		(start 86.078568 -223.085914)
		(end 86.068154 -223.079818)
		(width 0.0889)
		(layer "In15.Cu")
		(net "P5E_CPU1_PE0_TX_DN<1>")
	)
	(segment
		(start 80.892904 -266.641072)
		(end 83.71078 -310.90362)
		(width 0.14732)
		(layer "In15.Cu")
		(net "P5E_CPU1_PE0_TX_DN<1>")
	)
	(segment
		(start 74.979784 -329.357228)
		(end 72.388984 -335.612486)
		(width 0.14732)
		(layer "In15.Cu")
		(net "P5E_CPU1_PE0_TX_DN<1>")
	)
	(segment
		(start 81.532476 -259.537708)
		(end 80.892904 -266.641072)
		(width 0.14732)
		(layer "In15.Cu")
		(net "P5E_CPU1_PE0_TX_DN<1>")
	)
	(segment
		(start 85.138514 -223.085914)
		(end 85.123782 -223.077278)
		(width 0.0889)
		(layer "In15.Cu")
		(net "P5E_CPU1_PE0_TX_DN<1>")
	)
	(segment
		(start 72.388984 -335.612486)
		(end 72.314816 -336.152744)
		(width 0.14732)
		(layer "In15.Cu")
		(net "P5E_CPU1_PE0_TX_DN<1>")
	)
	(segment
		(start 91.12123 -224.66046)
		(end 91.100148 -224.738438)
		(width 0.0889)
		(layer "In15.Cu")
		(net "P5E_CPU1_PE0_TX_DN<1>")
	)
	(segment
		(start 90.226896 -223.077278)
		(end 90.212164 -223.085914)
		(width 0.0889)
		(layer "In15.Cu")
		(net "P5E_CPU1_PE0_TX_DN<1>")
	)
	(segment
		(start 84.097114 -223.47555)
		(end 83.819746 -223.752664)
		(width 0.14732)
		(layer "In15.Cu")
		(net "P5E_CPU1_PE0_TX_DN<1>")
	)
	(segment
		(start 72.314816 -336.152744)
		(end 73.070466 -351.402904)
		(width 0.14732)
		(layer "In15.Cu")
		(net "P5E_CPU1_PE0_TX_DN<1>")
	)
	(segment
		(start 90.768678 -224.070164)
		(end 90.777568 -224.065084)
		(width 0.0889)
		(layer "In15.Cu")
		(net "P5E_CPU1_PE0_TX_DN<1>")
	)
	(segment
		(start 84.111084 -250.65736)
		(end 84.111084 -252.921008)
		(width 0.14732)
		(layer "In15.Cu")
		(net "P5E_CPU1_PE0_TX_DN<1>")
	)
	(segment
		(start 90.964766 -224.389442)
		(end 91.12123 -224.66046)
		(width 0.0889)
		(layer "In15.Cu")
		(net "P5E_CPU1_PE0_TX_DN<1>")
	)
	(segment
		(start 77.415898 -325.85787)
		(end 74.979784 -329.357228)
		(width 0.14732)
		(layer "In15.Cu")
		(net "P5E_CPU1_PE0_TX_DN<1>")
	)
	(segment
		(start 91.159838 -399.791428)
		(end 91.159838 -400.563588)
		(width 0.14732)
		(layer "In15.Cu")
		(net "P5E_CPU1_PE0_TX_DN<1>")
	)
	(segment
		(start 81.822036 -234.145836)
		(end 81.89595 -245.21541)
		(width 0.14732)
		(layer "In15.Cu")
		(net "P5E_CPU1_PE0_TX_DN<1>")
	)
	(segment
		(start 91.159838 -400.563588)
		(end 90.865198 -400.858228)
		(width 0.14732)
		(layer "In15.Cu")
		(net "P5E_CPU1_PE0_TX_DN<1>")
	)
	(segment
		(start 90.777568 -224.7138)
		(end 90.768678 -224.70872)
		(width 0.0889)
		(layer "In15.Cu")
		(net "P5E_CPU1_PE0_TX_DN<1>")
	)
	(segment
		(start 83.71078 -310.90362)
		(end 77.415898 -325.85787)
		(width 0.14732)
		(layer "In15.Cu")
		(net "P5E_CPU1_PE0_TX_DN<1>")
	)
	(segment
		(start 84.171536 -223.460056)
		(end 84.112608 -223.460056)
		(width 0.0889)
		(layer "In15.Cu")
		(net "P5E_CPU1_PE0_TX_DN<1>")
	)
	(segment
		(start 88.347296 -223.077278)
		(end 88.332564 -223.085914)
		(width 0.0889)
		(layer "In15.Cu")
		(net "P5E_CPU1_PE0_TX_DN<1>")
	)
	(segment
		(start 73.070466 -351.402904)
		(end 91.159838 -399.791428)
		(width 0.14732)
		(layer "In15.Cu")
		(net "P5E_CPU1_PE0_TX_DN<1>")
	)
	(segment
		(start 84.111084 -252.921008)
		(end 81.532476 -259.537708)
		(width 0.14732)
		(layer "In15.Cu")
		(net "P5E_CPU1_PE0_TX_DN<1>")
	)
	(segment
		(start 90.777568 -224.065084)
		(end 90.783664 -224.061528)
		(width 0.0889)
		(layer "In15.Cu")
		(net "P5E_CPU1_PE0_TX_DN<1>")
	)
	(arc
		(start 84.57311 -223.085914)
		(mid 84.511625 -223.126909)
		(end 84.456016 -223.175576)
		(width 0.0889)
		(layer "In15.Cu")
		(net "P5E_CPU1_PE0_TX_DN<1>")
	)
	(arc
		(start 90.768678 -224.70872)
		(mid 90.590202 -224.389442)
		(end 90.768678 -224.070164)
		(width 0.0889)
		(layer "In15.Cu")
		(net "P5E_CPU1_PE0_TX_DN<1>")
	)
	(arc
		(start 90.212164 -223.085914)
		(mid 90.024966 -223.136057)
		(end 89.837768 -223.085914)
		(width 0.0889)
		(layer "In15.Cu")
		(net "P5E_CPU1_PE0_TX_DN<1>")
	)
	(arc
		(start 85.51291 -223.085914)
		(mid 85.325712 -223.136057)
		(end 85.138514 -223.085914)
		(width 0.0889)
		(layer "In15.Cu")
		(net "P5E_CPU1_PE0_TX_DN<1>")
	)
	(arc
		(start 85.123782 -223.077278)
		(mid 84.847341 -223.010112)
		(end 84.57311 -223.085914)
		(width 0.0889)
		(layer "In15.Cu")
		(net "P5E_CPU1_PE0_TX_DN<1>")
	)
	(arc
		(start 91.060016 -223.561402)
		(mid 90.980875 -223.286779)
		(end 90.777568 -223.085914)
		(width 0.0889)
		(layer "In15.Cu")
		(net "P5E_CPU1_PE0_TX_DN<1>")
	)
	(arc
		(start 88.332564 -223.085914)
		(mid 88.145366 -223.136057)
		(end 87.958168 -223.085914)
		(width 0.0889)
		(layer "In15.Cu")
		(net "P5E_CPU1_PE0_TX_DN<1>")
	)
	(arc
		(start 86.068154 -223.079818)
		(mid 85.789722 -223.010004)
		(end 85.51291 -223.085914)
		(width 0.0889)
		(layer "In15.Cu")
		(net "P5E_CPU1_PE0_TX_DN<1>")
	)
	(arc
		(start 87.392764 -223.085914)
		(mid 87.205566 -223.136057)
		(end 87.018368 -223.085914)
		(width 0.0889)
		(layer "In15.Cu")
		(net "P5E_CPU1_PE0_TX_DN<1>")
	)
	(arc
		(start 89.272364 -223.085914)
		(mid 89.085166 -223.136057)
		(end 88.897968 -223.085914)
		(width 0.0889)
		(layer "In15.Cu")
		(net "P5E_CPU1_PE0_TX_DN<1>")
	)
	(arc
		(start 91.100148 -224.738438)
		(mid 90.936052 -224.762785)
		(end 90.777568 -224.7138)
		(width 0.0889)
		(layer "In15.Cu")
		(net "P5E_CPU1_PE0_TX_DN<1>")
	)
	(arc
		(start 87.018368 -223.085914)
		(mid 86.735666 -223.010172)
		(end 86.452964 -223.085914)
		(width 0.0889)
		(layer "In15.Cu")
		(net "P5E_CPU1_PE0_TX_DN<1>")
	)
	(arc
		(start 90.783664 -224.061528)
		(mid 90.986077 -223.855115)
		(end 91.060016 -223.575626)
		(width 0.0889)
		(layer "In15.Cu")
		(net "P5E_CPU1_PE0_TX_DN<1>")
	)
	(arc
		(start 90.777568 -223.085914)
		(mid 90.503339 -223.009989)
		(end 90.226896 -223.077278)
		(width 0.0889)
		(layer "In15.Cu")
		(net "P5E_CPU1_PE0_TX_DN<1>")
	)
	(arc
		(start 88.897968 -223.085914)
		(mid 88.623739 -223.009989)
		(end 88.347296 -223.077278)
		(width 0.0889)
		(layer "In15.Cu")
		(net "P5E_CPU1_PE0_TX_DN<1>")
	)
	(arc
		(start 86.452964 -223.085914)
		(mid 86.265766 -223.136057)
		(end 86.078568 -223.085914)
		(width 0.0889)
		(layer "In15.Cu")
		(net "P5E_CPU1_PE0_TX_DN<1>")
	)
	(arc
		(start 89.837768 -223.085914)
		(mid 89.555066 -223.010172)
		(end 89.272364 -223.085914)
		(width 0.0889)
		(layer "In15.Cu")
		(net "P5E_CPU1_PE0_TX_DN<1>")
	)
	(arc
		(start 87.958168 -223.085914)
		(mid 87.675466 -223.010172)
		(end 87.392764 -223.085914)
		(width 0.0889)
		(layer "In15.Cu")
		(net "P5E_CPU1_PE0_TX_DN<1>")
	)
	(segment
		(start 104.121966 -224.925128)
		(end 104.121966 -224.389442)
		(width 0.13208)
		(layer "F.Cu")
		(net "P5E_CPU1_PE0_TX_DN<15>")
	)
	(segment
		(start 47.954438 -402.104352)
		(end 47.95901 -402.104352)
		(width 0.13208)
		(layer "F.Cu")
		(net "P5E_CPU1_PE0_TX_DN<15>")
	)
	(segment
		(start 48.2854 -401.777962)
		(end 48.2854 -401.16379)
		(width 0.13208)
		(layer "F.Cu")
		(net "P5E_CPU1_PE0_TX_DN<15>")
	)
	(segment
		(start 47.95901 -402.104352)
		(end 48.2854 -401.777962)
		(width 0.13208)
		(layer "F.Cu")
		(net "P5E_CPU1_PE0_TX_DN<15>")
	)
	(segment
		(start 48.2854 -401.16379)
		(end 47.979838 -400.858228)
		(width 0.13208)
		(layer "F.Cu")
		(net "P5E_CPU1_PE0_TX_DN<15>")
	)
	(segment
		(start 104.121712 -224.925382)
		(end 104.121966 -224.925128)
		(width 0.13208)
		(layer "F.Cu")
		(net "P5E_CPU1_PE0_TX_DN<15>")
	)
	(segment
		(start 61.272674 -319.676272)
		(end 60.468256 -321.618356)
		(width 0.14732)
		(layer "In15.Cu")
		(net "P5E_CPU1_PE0_TX_DN<15>")
	)
	(segment
		(start 102.807008 -214.470996)
		(end 102.806754 -214.470996)
		(width 0.0889)
		(layer "In15.Cu")
		(net "P5E_CPU1_PE0_TX_DN<15>")
	)
	(segment
		(start 48.274478 -400.563588)
		(end 47.979838 -400.858228)
		(width 0.14732)
		(layer "In15.Cu")
		(net "P5E_CPU1_PE0_TX_DN<15>")
	)
	(segment
		(start 102.524814 -215.761062)
		(end 102.52329 -215.7603)
		(width 0.0889)
		(layer "In15.Cu")
		(net "P5E_CPU1_PE0_TX_DN<15>")
	)
	(segment
		(start 103.464614 -222.272098)
		(end 103.46309 -222.271336)
		(width 0.0889)
		(layer "In15.Cu")
		(net "P5E_CPU1_PE0_TX_DN<15>")
	)
	(segment
		(start 102.337362 -213.186518)
		(end 102.379272 -213.144608)
		(width 0.0889)
		(layer "In15.Cu")
		(net "P5E_CPU1_PE0_TX_DN<15>")
	)
	(segment
		(start 49.167542 -397.83004)
		(end 48.274478 -400.029934)
		(width 0.14732)
		(layer "In15.Cu")
		(net "P5E_CPU1_PE0_TX_DN<15>")
	)
	(segment
		(start 102.379272 -211.280756)
		(end 101.252528 -208.560416)
		(width 0.14732)
		(layer "In15.Cu")
		(net "P5E_CPU1_PE0_TX_DN<15>")
	)
	(segment
		(start 59.069986 -350.01708)
		(end 57.804812 -365.383826)
		(width 0.14732)
		(layer "In15.Cu")
		(net "P5E_CPU1_PE0_TX_DN<15>")
	)
	(segment
		(start 66.626486 -314.971176)
		(end 65.273682 -315.874908)
		(width 0.14732)
		(layer "In15.Cu")
		(net "P5E_CPU1_PE0_TX_DN<15>")
	)
	(segment
		(start 67.206622 -314.39104)
		(end 66.626486 -314.971176)
		(width 0.14732)
		(layer "In15.Cu")
		(net "P5E_CPU1_PE0_TX_DN<15>")
	)
	(segment
		(start 56.487822 -374.204738)
		(end 49.697386 -396.118588)
		(width 0.14732)
		(layer "In15.Cu")
		(net "P5E_CPU1_PE0_TX_DN<15>")
	)
	(segment
		(start 66.627248 -249.904758)
		(end 66.520568 -253.473458)
		(width 0.14732)
		(layer "In15.Cu")
		(net "P5E_CPU1_PE0_TX_DN<15>")
	)
	(segment
		(start 49.5681 -396.536672)
		(end 49.167542 -397.83004)
		(width 0.14732)
		(layer "In15.Cu")
		(net "P5E_CPU1_PE0_TX_DN<15>")
	)
	(segment
		(start 64.270128 -316.878716)
		(end 63.274702 -317.291212)
		(width 0.14732)
		(layer "In15.Cu")
		(net "P5E_CPU1_PE0_TX_DN<15>")
	)
	(segment
		(start 84.929218 -201.505058)
		(end 72.876664 -214.39251)
		(width 0.14732)
		(layer "In15.Cu")
		(net "P5E_CPU1_PE0_TX_DN<15>")
	)
	(segment
		(start 69.918326 -220.093286)
		(end 69.897752 -220.133164)
		(width 0.14732)
		(layer "In15.Cu")
		(net "P5E_CPU1_PE0_TX_DN<15>")
	)
	(segment
		(start 102.986078 -219.18676)
		(end 102.994968 -219.18168)
		(width 0.0889)
		(layer "In15.Cu")
		(net "P5E_CPU1_PE0_TX_DN<15>")
	)
	(segment
		(start 101.252528 -208.560416)
		(end 94.612968 -201.920856)
		(width 0.14732)
		(layer "In15.Cu")
		(net "P5E_CPU1_PE0_TX_DN<15>")
	)
	(segment
		(start 103.277162 -221.94774)
		(end 103.277162 -221.932246)
		(width 0.0889)
		(layer "In15.Cu")
		(net "P5E_CPU1_PE0_TX_DN<15>")
	)
	(segment
		(start 90.726768 -200.311258)
		(end 89.205816 -200.307194)
		(width 0.14732)
		(layer "In15.Cu")
		(net "P5E_CPU1_PE0_TX_DN<15>")
	)
	(segment
		(start 102.994968 -221.458282)
		(end 102.986078 -221.453202)
		(width 0.0889)
		(layer "In15.Cu")
		(net "P5E_CPU1_PE0_TX_DN<15>")
	)
	(segment
		(start 102.379272 -213.12251)
		(end 102.379272 -211.280756)
		(width 0.14732)
		(layer "In15.Cu")
		(net "P5E_CPU1_PE0_TX_DN<15>")
	)
	(segment
		(start 59.511438 -322.20662)
		(end 58.843672 -322.874386)
		(width 0.14732)
		(layer "In15.Cu")
		(net "P5E_CPU1_PE0_TX_DN<15>")
	)
	(segment
		(start 69.91858 -220.093286)
		(end 69.918326 -220.093286)
		(width 0.14732)
		(layer "In15.Cu")
		(net "P5E_CPU1_PE0_TX_DN<15>")
	)
	(segment
		(start 49.697132 -396.119096)
		(end 49.697386 -396.119096)
		(width 0.14732)
		(layer "In15.Cu")
		(net "P5E_CPU1_PE0_TX_DN<15>")
	)
	(segment
		(start 49.697386 -396.118588)
		(end 49.697132 -396.119096)
		(width 0.14732)
		(layer "In15.Cu")
		(net "P5E_CPU1_PE0_TX_DN<15>")
	)
	(segment
		(start 103.277162 -218.707716)
		(end 103.277162 -218.676728)
		(width 0.0889)
		(layer "In15.Cu")
		(net "P5E_CPU1_PE0_TX_DN<15>")
	)
	(segment
		(start 66.520568 -253.473458)
		(end 69.857874 -305.592988)
		(width 0.14732)
		(layer "In15.Cu")
		(net "P5E_CPU1_PE0_TX_DN<15>")
	)
	(segment
		(start 102.374446 -213.928452)
		(end 102.341934 -213.84514)
		(width 0.0889)
		(layer "In15.Cu")
		(net "P5E_CPU1_PE0_TX_DN<15>")
	)
	(segment
		(start 58.582814 -323.503798)
		(end 57.227216 -324.859396)
		(width 0.14732)
		(layer "In15.Cu")
		(net "P5E_CPU1_PE0_TX_DN<15>")
	)
	(segment
		(start 103.934768 -223.085914)
		(end 103.925878 -223.080834)
		(width 0.0889)
		(layer "In15.Cu")
		(net "P5E_CPU1_PE0_TX_DN<15>")
	)
	(segment
		(start 89.205816 -200.307194)
		(end 89.196164 -200.307194)
		(width 0.14732)
		(layer "In15.Cu")
		(net "P5E_CPU1_PE0_TX_DN<15>")
	)
	(segment
		(start 102.379272 -213.144608)
		(end 102.379272 -213.12251)
		(width 0.0889)
		(layer "In15.Cu")
		(net "P5E_CPU1_PE0_TX_DN<15>")
	)
	(segment
		(start 102.527608 -215.762586)
		(end 102.524814 -215.761062)
		(width 0.0889)
		(layer "In15.Cu")
		(net "P5E_CPU1_PE0_TX_DN<15>")
	)
	(segment
		(start 102.52329 -215.7603)
		(end 102.515924 -215.755982)
		(width 0.0889)
		(layer "In15.Cu")
		(net "P5E_CPU1_PE0_TX_DN<15>")
	)
	(segment
		(start 61.272674 -319.676526)
		(end 61.272674 -319.676272)
		(width 0.14732)
		(layer "In15.Cu")
		(net "P5E_CPU1_PE0_TX_DN<15>")
	)
	(segment
		(start 68.029582 -232.222548)
		(end 66.627248 -249.904758)
		(width 0.14732)
		(layer "In15.Cu")
		(net "P5E_CPU1_PE0_TX_DN<15>")
	)
	(segment
		(start 72.876664 -214.39251)
		(end 69.91858 -220.093286)
		(width 0.14732)
		(layer "In15.Cu")
		(net "P5E_CPU1_PE0_TX_DN<15>")
	)
	(segment
		(start 102.994968 -216.574878)
		(end 102.986078 -216.569798)
		(width 0.0889)
		(layer "In15.Cu")
		(net "P5E_CPU1_PE0_TX_DN<15>")
	)
	(segment
		(start 103.937054 -224.063814)
		(end 103.940864 -224.061528)
		(width 0.0889)
		(layer "In15.Cu")
		(net "P5E_CPU1_PE0_TX_DN<15>")
	)
	(segment
		(start 68.669916 -309.826914)
		(end 68.669662 -309.827168)
		(width 0.14732)
		(layer "In15.Cu")
		(net "P5E_CPU1_PE0_TX_DN<15>")
	)
	(segment
		(start 65.273682 -315.874908)
		(end 64.270128 -316.878716)
		(width 0.14732)
		(layer "In15.Cu")
		(net "P5E_CPU1_PE0_TX_DN<15>")
	)
	(segment
		(start 60.468256 -321.618356)
		(end 60.14085 -321.945762)
		(width 0.14732)
		(layer "In15.Cu")
		(net "P5E_CPU1_PE0_TX_DN<15>")
	)
	(segment
		(start 104.27843 -224.66046)
		(end 104.257348 -224.738438)
		(width 0.0889)
		(layer "In15.Cu")
		(net "P5E_CPU1_PE0_TX_DN<15>")
	)
	(segment
		(start 68.669662 -309.827422)
		(end 68.496688 -310.444134)
		(width 0.14732)
		(layer "In15.Cu")
		(net "P5E_CPU1_PE0_TX_DN<15>")
	)
	(segment
		(start 102.337362 -213.820756)
		(end 102.337362 -213.186518)
		(width 0.0889)
		(layer "In15.Cu")
		(net "P5E_CPU1_PE0_TX_DN<15>")
	)
	(segment
		(start 102.994968 -219.830396)
		(end 102.986078 -219.825316)
		(width 0.0889)
		(layer "In15.Cu")
		(net "P5E_CPU1_PE0_TX_DN<15>")
	)
	(segment
		(start 49.697386 -396.119096)
		(end 49.568608 -396.535148)
		(width 0.14732)
		(layer "In15.Cu")
		(net "P5E_CPU1_PE0_TX_DN<15>")
	)
	(segment
		(start 58.843672 -322.874386)
		(end 58.582814 -323.503798)
		(width 0.14732)
		(layer "In15.Cu")
		(net "P5E_CPU1_PE0_TX_DN<15>")
	)
	(segment
		(start 104.217216 -223.575626)
		(end 104.217216 -223.561402)
		(width 0.0889)
		(layer "In15.Cu")
		(net "P5E_CPU1_PE0_TX_DN<15>")
	)
	(segment
		(start 69.857874 -305.592988)
		(end 68.669916 -309.826914)
		(width 0.14732)
		(layer "In15.Cu")
		(net "P5E_CPU1_PE0_TX_DN<15>")
	)
	(segment
		(start 63.274702 -317.291212)
		(end 62.044072 -318.521842)
		(width 0.14732)
		(layer "In15.Cu")
		(net "P5E_CPU1_PE0_TX_DN<15>")
	)
	(segment
		(start 103.925878 -224.070164)
		(end 103.935276 -224.06483)
		(width 0.0889)
		(layer "In15.Cu")
		(net "P5E_CPU1_PE0_TX_DN<15>")
	)
	(segment
		(start 57.227216 -332.122018)
		(end 59.069986 -350.01708)
		(width 0.14732)
		(layer "In15.Cu")
		(net "P5E_CPU1_PE0_TX_DN<15>")
	)
	(segment
		(start 60.14085 -321.945762)
		(end 59.511438 -322.20662)
		(width 0.14732)
		(layer "In15.Cu")
		(net "P5E_CPU1_PE0_TX_DN<15>")
	)
	(segment
		(start 87.681816 -200.30313)
		(end 84.929218 -201.505058)
		(width 0.14732)
		(layer "In15.Cu")
		(net "P5E_CPU1_PE0_TX_DN<15>")
	)
	(segment
		(start 102.986078 -217.559128)
		(end 102.994968 -217.554048)
		(width 0.0889)
		(layer "In15.Cu")
		(net "P5E_CPU1_PE0_TX_DN<15>")
	)
	(segment
		(start 102.994968 -218.202764)
		(end 102.986078 -218.197684)
		(width 0.0889)
		(layer "In15.Cu")
		(net "P5E_CPU1_PE0_TX_DN<15>")
	)
	(segment
		(start 68.669662 -309.827168)
		(end 68.669662 -309.827422)
		(width 0.14732)
		(layer "In15.Cu")
		(net "P5E_CPU1_PE0_TX_DN<15>")
	)
	(segment
		(start 102.807008 -214.644732)
		(end 102.807008 -214.470996)
		(width 0.0889)
		(layer "In15.Cu")
		(net "P5E_CPU1_PE0_TX_DN<15>")
	)
	(segment
		(start 103.46309 -222.271336)
		(end 103.455724 -222.267018)
		(width 0.0889)
		(layer "In15.Cu")
		(net "P5E_CPU1_PE0_TX_DN<15>")
	)
	(segment
		(start 103.74757 -222.751396)
		(end 103.747316 -222.761556)
		(width 0.0889)
		(layer "In15.Cu")
		(net "P5E_CPU1_PE0_TX_DN<15>")
	)
	(segment
		(start 103.47071 -222.275654)
		(end 103.467408 -222.273622)
		(width 0.0889)
		(layer "In15.Cu")
		(net "P5E_CPU1_PE0_TX_DN<15>")
	)
	(segment
		(start 102.53091 -215.764618)
		(end 102.527608 -215.762586)
		(width 0.0889)
		(layer "In15.Cu")
		(net "P5E_CPU1_PE0_TX_DN<15>")
	)
	(segment
		(start 94.612968 -201.920856)
		(end 90.726768 -200.311258)
		(width 0.14732)
		(layer "In15.Cu")
		(net "P5E_CPU1_PE0_TX_DN<15>")
	)
	(segment
		(start 104.121966 -224.389442)
		(end 104.27843 -224.66046)
		(width 0.0889)
		(layer "In15.Cu")
		(net "P5E_CPU1_PE0_TX_DN<15>")
	)
	(segment
		(start 49.568608 -396.535148)
		(end 49.5681 -396.536672)
		(width 0.14732)
		(layer "In15.Cu")
		(net "P5E_CPU1_PE0_TX_DN<15>")
	)
	(segment
		(start 69.897752 -220.133164)
		(end 68.029582 -232.222548)
		(width 0.14732)
		(layer "In15.Cu")
		(net "P5E_CPU1_PE0_TX_DN<15>")
	)
	(segment
		(start 103.935276 -224.06483)
		(end 103.937054 -224.063814)
		(width 0.0889)
		(layer "In15.Cu")
		(net "P5E_CPU1_PE0_TX_DN<15>")
	)
	(segment
		(start 48.274478 -400.029934)
		(end 48.274478 -400.563588)
		(width 0.14732)
		(layer "In15.Cu")
		(net "P5E_CPU1_PE0_TX_DN<15>")
	)
	(segment
		(start 68.496688 -310.444134)
		(end 67.206622 -314.39104)
		(width 0.14732)
		(layer "In15.Cu")
		(net "P5E_CPU1_PE0_TX_DN<15>")
	)
	(segment
		(start 57.804812 -365.383826)
		(end 56.487822 -374.204738)
		(width 0.14732)
		(layer "In15.Cu")
		(net "P5E_CPU1_PE0_TX_DN<15>")
	)
	(segment
		(start 57.227216 -324.859396)
		(end 57.227216 -332.122018)
		(width 0.14732)
		(layer "In15.Cu")
		(net "P5E_CPU1_PE0_TX_DN<15>")
	)
	(segment
		(start 102.986078 -220.814646)
		(end 102.994968 -220.809566)
		(width 0.0889)
		(layer "In15.Cu")
		(net "P5E_CPU1_PE0_TX_DN<15>")
	)
	(segment
		(start 103.467408 -222.273622)
		(end 103.464614 -222.272098)
		(width 0.0889)
		(layer "In15.Cu")
		(net "P5E_CPU1_PE0_TX_DN<15>")
	)
	(segment
		(start 102.515924 -215.117426)
		(end 102.524814 -215.112346)
		(width 0.0889)
		(layer "In15.Cu")
		(net "P5E_CPU1_PE0_TX_DN<15>")
	)
	(segment
		(start 89.196164 -200.307194)
		(end 87.681816 -200.30313)
		(width 0.14732)
		(layer "In15.Cu")
		(net "P5E_CPU1_PE0_TX_DN<15>")
	)
	(segment
		(start 103.934768 -224.7138)
		(end 103.925878 -224.70872)
		(width 0.0889)
		(layer "In15.Cu")
		(net "P5E_CPU1_PE0_TX_DN<15>")
	)
	(segment
		(start 62.044072 -318.521842)
		(end 61.272674 -319.676526)
		(width 0.14732)
		(layer "In15.Cu")
		(net "P5E_CPU1_PE0_TX_DN<15>")
	)
	(arc
		(start 102.986078 -216.569798)
		(mid 102.855164 -216.433438)
		(end 102.807516 -216.25052)
		(width 0.0889)
		(layer "In15.Cu")
		(net "P5E_CPU1_PE0_TX_DN<15>")
	)
	(arc
		(start 102.80777 -221.121732)
		(mid 102.858241 -220.945724)
		(end 102.986078 -220.814646)
		(width 0.0889)
		(layer "In15.Cu")
		(net "P5E_CPU1_PE0_TX_DN<15>")
	)
	(arc
		(start 103.925878 -223.080834)
		(mid 103.798798 -222.95082)
		(end 103.747824 -222.776288)
		(width 0.0889)
		(layer "In15.Cu")
		(net "P5E_CPU1_PE0_TX_DN<15>")
	)
	(arc
		(start 102.80777 -217.888566)
		(mid 102.807603 -217.87739)
		(end 102.80777 -217.866214)
		(width 0.0889)
		(layer "In15.Cu")
		(net "P5E_CPU1_PE0_TX_DN<15>")
	)
	(arc
		(start 102.515924 -215.755982)
		(mid 102.337327 -215.436704)
		(end 102.515924 -215.117426)
		(width 0.0889)
		(layer "In15.Cu")
		(net "P5E_CPU1_PE0_TX_DN<15>")
	)
	(arc
		(start 102.341934 -213.84514)
		(mid 102.338522 -213.833161)
		(end 102.337362 -213.820756)
		(width 0.0889)
		(layer "In15.Cu")
		(net "P5E_CPU1_PE0_TX_DN<15>")
	)
	(arc
		(start 104.257348 -224.738438)
		(mid 104.093252 -224.762785)
		(end 103.934768 -224.7138)
		(width 0.0889)
		(layer "In15.Cu")
		(net "P5E_CPU1_PE0_TX_DN<15>")
	)
	(arc
		(start 103.747316 -222.761556)
		(mid 103.673325 -222.48199)
		(end 103.47071 -222.275654)
		(width 0.0889)
		(layer "In15.Cu")
		(net "P5E_CPU1_PE0_TX_DN<15>")
	)
	(arc
		(start 103.940864 -224.061528)
		(mid 104.143277 -223.855115)
		(end 104.217216 -223.575626)
		(width 0.0889)
		(layer "In15.Cu")
		(net "P5E_CPU1_PE0_TX_DN<15>")
	)
	(arc
		(start 102.80777 -221.144084)
		(mid 102.807603 -221.132908)
		(end 102.80777 -221.121732)
		(width 0.0889)
		(layer "In15.Cu")
		(net "P5E_CPU1_PE0_TX_DN<15>")
	)
	(arc
		(start 102.521766 -214.093298)
		(mid 102.433327 -214.024092)
		(end 102.374446 -213.928452)
		(width 0.0889)
		(layer "In15.Cu")
		(net "P5E_CPU1_PE0_TX_DN<15>")
	)
	(arc
		(start 102.78237 -214.365586)
		(mid 102.674043 -214.208414)
		(end 102.521766 -214.093298)
		(width 0.0889)
		(layer "In15.Cu")
		(net "P5E_CPU1_PE0_TX_DN<15>")
	)
	(arc
		(start 102.994968 -220.809566)
		(mid 103.2775 -220.320045)
		(end 102.994968 -219.830396)
		(width 0.0889)
		(layer "In15.Cu")
		(net "P5E_CPU1_PE0_TX_DN<15>")
	)
	(arc
		(start 102.80777 -217.866214)
		(mid 102.858241 -217.690206)
		(end 102.986078 -217.559128)
		(width 0.0889)
		(layer "In15.Cu")
		(net "P5E_CPU1_PE0_TX_DN<15>")
	)
	(arc
		(start 103.925878 -224.70872)
		(mid 103.747402 -224.389442)
		(end 103.925878 -224.070164)
		(width 0.0889)
		(layer "In15.Cu")
		(net "P5E_CPU1_PE0_TX_DN<15>")
	)
	(arc
		(start 102.807516 -216.25052)
		(mid 102.733525 -215.970954)
		(end 102.53091 -215.764618)
		(width 0.0889)
		(layer "In15.Cu")
		(net "P5E_CPU1_PE0_TX_DN<15>")
	)
	(arc
		(start 104.217216 -223.561402)
		(mid 104.138075 -223.286779)
		(end 103.934768 -223.085914)
		(width 0.0889)
		(layer "In15.Cu")
		(net "P5E_CPU1_PE0_TX_DN<15>")
	)
	(arc
		(start 102.806754 -214.470996)
		(mid 102.80042 -214.416934)
		(end 102.78237 -214.365586)
		(width 0.0889)
		(layer "In15.Cu")
		(net "P5E_CPU1_PE0_TX_DN<15>")
	)
	(arc
		(start 102.986078 -218.197684)
		(mid 102.857759 -218.065712)
		(end 102.80777 -217.888566)
		(width 0.0889)
		(layer "In15.Cu")
		(net "P5E_CPU1_PE0_TX_DN<15>")
	)
	(arc
		(start 103.277162 -221.932246)
		(mid 103.197792 -221.658512)
		(end 102.994968 -221.458282)
		(width 0.0889)
		(layer "In15.Cu")
		(net "P5E_CPU1_PE0_TX_DN<15>")
	)
	(arc
		(start 103.747824 -222.776288)
		(mid 103.747491 -222.763844)
		(end 103.74757 -222.751396)
		(width 0.0889)
		(layer "In15.Cu")
		(net "P5E_CPU1_PE0_TX_DN<15>")
	)
	(arc
		(start 102.994968 -219.18168)
		(mid 103.197791 -218.981449)
		(end 103.277162 -218.707716)
		(width 0.0889)
		(layer "In15.Cu")
		(net "P5E_CPU1_PE0_TX_DN<15>")
	)
	(arc
		(start 102.994968 -217.554048)
		(mid 103.2775 -217.064527)
		(end 102.994968 -216.574878)
		(width 0.0889)
		(layer "In15.Cu")
		(net "P5E_CPU1_PE0_TX_DN<15>")
	)
	(arc
		(start 102.986078 -219.825316)
		(mid 102.807481 -219.506038)
		(end 102.986078 -219.18676)
		(width 0.0889)
		(layer "In15.Cu")
		(net "P5E_CPU1_PE0_TX_DN<15>")
	)
	(arc
		(start 102.524814 -215.112346)
		(mid 102.726096 -214.914859)
		(end 102.807008 -214.644732)
		(width 0.0889)
		(layer "In15.Cu")
		(net "P5E_CPU1_PE0_TX_DN<15>")
	)
	(arc
		(start 103.455724 -222.267018)
		(mid 103.32481 -222.130658)
		(end 103.277162 -221.94774)
		(width 0.0889)
		(layer "In15.Cu")
		(net "P5E_CPU1_PE0_TX_DN<15>")
	)
	(arc
		(start 102.986078 -221.453202)
		(mid 102.857759 -221.32123)
		(end 102.80777 -221.144084)
		(width 0.0889)
		(layer "In15.Cu")
		(net "P5E_CPU1_PE0_TX_DN<15>")
	)
	(arc
		(start 103.277162 -218.676728)
		(mid 103.197792 -218.402994)
		(end 102.994968 -218.202764)
		(width 0.0889)
		(layer "In15.Cu")
		(net "P5E_CPU1_PE0_TX_DN<15>")
	)
	(segment
		(start 103.652066 -224.111566)
		(end 103.652066 -223.57588)
		(width 0.13208)
		(layer "F.Cu")
		(net "P5E_CPU1_PE0_TX_DN<14>")
	)
	(segment
		(start 51.02225 -402.104352)
		(end 51.34864 -401.777962)
		(width 0.13208)
		(layer "F.Cu")
		(net "P5E_CPU1_PE0_TX_DN<14>")
	)
	(segment
		(start 51.34864 -401.777962)
		(end 51.34864 -401.16379)
		(width 0.13208)
		(layer "F.Cu")
		(net "P5E_CPU1_PE0_TX_DN<14>")
	)
	(segment
		(start 103.652066 -223.57588)
		(end 103.651812 -223.575626)
		(width 0.13208)
		(layer "F.Cu")
		(net "P5E_CPU1_PE0_TX_DN<14>")
	)
	(segment
		(start 51.017678 -402.104352)
		(end 51.02225 -402.104352)
		(width 0.13208)
		(layer "F.Cu")
		(net "P5E_CPU1_PE0_TX_DN<14>")
	)
	(segment
		(start 51.34864 -401.16379)
		(end 51.043078 -400.858228)
		(width 0.13208)
		(layer "F.Cu")
		(net "P5E_CPU1_PE0_TX_DN<14>")
	)
	(segment
		(start 60.611512 -322.869052)
		(end 60.612782 -322.868544)
		(width 0.14732)
		(layer "In15.Cu")
		(net "P5E_CPU1_PE0_TX_DN<14>")
	)
	(segment
		(start 66.835528 -317.579502)
		(end 64.071246 -320.343276)
		(width 0.14732)
		(layer "In15.Cu")
		(net "P5E_CPU1_PE0_TX_DN<14>")
	)
	(segment
		(start 101.397562 -213.186518)
		(end 101.439472 -213.144608)
		(width 0.0889)
		(layer "In15.Cu")
		(net "P5E_CPU1_PE0_TX_DN<14>")
	)
	(segment
		(start 59.684412 -323.528436)
		(end 59.49442 -323.986906)
		(width 0.14732)
		(layer "In15.Cu")
		(net "P5E_CPU1_PE0_TX_DN<14>")
	)
	(segment
		(start 51.337718 -399.933922)
		(end 51.337718 -400.563588)
		(width 0.14732)
		(layer "In15.Cu")
		(net "P5E_CPU1_PE0_TX_DN<14>")
	)
	(segment
		(start 62.476634 -321.00393)
		(end 60.611512 -322.869052)
		(width 0.14732)
		(layer "In15.Cu")
		(net "P5E_CPU1_PE0_TX_DN<14>")
	)
	(segment
		(start 102.055168 -221.458282)
		(end 102.046278 -221.453202)
		(width 0.0889)
		(layer "In15.Cu")
		(net "P5E_CPU1_PE0_TX_DN<14>")
	)
	(segment
		(start 70.799198 -220.527372)
		(end 68.983098 -232.278936)
		(width 0.14732)
		(layer "In15.Cu")
		(net "P5E_CPU1_PE0_TX_DN<14>")
	)
	(segment
		(start 102.061264 -219.833952)
		(end 102.055168 -219.830396)
		(width 0.0889)
		(layer "In15.Cu")
		(net "P5E_CPU1_PE0_TX_DN<14>")
	)
	(segment
		(start 67.53733 -254.377698)
		(end 70.997572 -308.181756)
		(width 0.14732)
		(layer "In15.Cu")
		(net "P5E_CPU1_PE0_TX_DN<14>")
	)
	(segment
		(start 101.585014 -215.112346)
		(end 101.597968 -215.103964)
		(width 0.0889)
		(layer "In15.Cu")
		(net "P5E_CPU1_PE0_TX_DN<14>")
	)
	(segment
		(start 102.337362 -218.707716)
		(end 102.337362 -218.676728)
		(width 0.0889)
		(layer "In15.Cu")
		(net "P5E_CPU1_PE0_TX_DN<14>")
	)
	(segment
		(start 102.527608 -222.273622)
		(end 102.524814 -222.272098)
		(width 0.0889)
		(layer "In15.Cu")
		(net "P5E_CPU1_PE0_TX_DN<14>")
	)
	(segment
		(start 101.576124 -215.117426)
		(end 101.583998 -215.112854)
		(width 0.0889)
		(layer "In15.Cu")
		(net "P5E_CPU1_PE0_TX_DN<14>")
	)
	(segment
		(start 103.495348 -223.846644)
		(end 103.41737 -223.867472)
		(width 0.0889)
		(layer "In15.Cu")
		(net "P5E_CPU1_PE0_TX_DN<14>")
	)
	(segment
		(start 102.53091 -222.275654)
		(end 102.527608 -222.273622)
		(width 0.0889)
		(layer "In15.Cu")
		(net "P5E_CPU1_PE0_TX_DN<14>")
	)
	(segment
		(start 57.475374 -375.890028)
		(end 52.140612 -397.696182)
		(width 0.14732)
		(layer "In15.Cu")
		(net "P5E_CPU1_PE0_TX_DN<14>")
	)
	(segment
		(start 90.524584 -201.266806)
		(end 87.975948 -201.261726)
		(width 0.14732)
		(layer "In15.Cu")
		(net "P5E_CPU1_PE0_TX_DN<14>")
	)
	(segment
		(start 73.677526 -214.980266)
		(end 70.820026 -220.487494)
		(width 0.14732)
		(layer "In15.Cu")
		(net "P5E_CPU1_PE0_TX_DN<14>")
	)
	(segment
		(start 70.819772 -220.487494)
		(end 70.799198 -220.527372)
		(width 0.14732)
		(layer "In15.Cu")
		(net "P5E_CPU1_PE0_TX_DN<14>")
	)
	(segment
		(start 59.49442 -323.986906)
		(end 58.17108 -325.310246)
		(width 0.14732)
		(layer "In15.Cu")
		(net "P5E_CPU1_PE0_TX_DN<14>")
	)
	(segment
		(start 68.983098 -232.278936)
		(end 67.676776 -249.954542)
		(width 0.14732)
		(layer "In15.Cu")
		(net "P5E_CPU1_PE0_TX_DN<14>")
	)
	(segment
		(start 103.651812 -223.575626)
		(end 103.495348 -223.846644)
		(width 0.0889)
		(layer "In15.Cu")
		(net "P5E_CPU1_PE0_TX_DN<14>")
	)
	(segment
		(start 102.337362 -221.94774)
		(end 102.337362 -221.932246)
		(width 0.0889)
		(layer "In15.Cu")
		(net "P5E_CPU1_PE0_TX_DN<14>")
	)
	(segment
		(start 60.033408 -350.044512)
		(end 58.91403 -364.715044)
		(width 0.14732)
		(layer "In15.Cu")
		(net "P5E_CPU1_PE0_TX_DN<14>")
	)
	(segment
		(start 102.524814 -222.272098)
		(end 102.52329 -222.271336)
		(width 0.0889)
		(layer "In15.Cu")
		(net "P5E_CPU1_PE0_TX_DN<14>")
	)
	(segment
		(start 101.439472 -211.537296)
		(end 100.396294 -209.01914)
		(width 0.14732)
		(layer "In15.Cu")
		(net "P5E_CPU1_PE0_TX_DN<14>")
	)
	(segment
		(start 94.14256 -202.765406)
		(end 90.524584 -201.266806)
		(width 0.14732)
		(layer "In15.Cu")
		(net "P5E_CPU1_PE0_TX_DN<14>")
	)
	(segment
		(start 60.612782 -322.868544)
		(end 60.154312 -323.058536)
		(width 0.14732)
		(layer "In15.Cu")
		(net "P5E_CPU1_PE0_TX_DN<14>")
	)
	(segment
		(start 64.071246 -320.343276)
		(end 62.476634 -321.00393)
		(width 0.14732)
		(layer "In15.Cu")
		(net "P5E_CPU1_PE0_TX_DN<14>")
	)
	(segment
		(start 101.583998 -215.112854)
		(end 101.585014 -215.112346)
		(width 0.0889)
		(layer "In15.Cu")
		(net "P5E_CPU1_PE0_TX_DN<14>")
	)
	(segment
		(start 101.397562 -213.788244)
		(end 101.397562 -213.186518)
		(width 0.0889)
		(layer "In15.Cu")
		(net "P5E_CPU1_PE0_TX_DN<14>")
	)
	(segment
		(start 67.856608 -316.121288)
		(end 66.835528 -317.579502)
		(width 0.14732)
		(layer "In15.Cu")
		(net "P5E_CPU1_PE0_TX_DN<14>")
	)
	(segment
		(start 58.91403 -364.715044)
		(end 57.475374 -375.890028)
		(width 0.14732)
		(layer "In15.Cu")
		(net "P5E_CPU1_PE0_TX_DN<14>")
	)
	(segment
		(start 102.054152 -219.182188)
		(end 102.055168 -219.18168)
		(width 0.0889)
		(layer "In15.Cu")
		(net "P5E_CPU1_PE0_TX_DN<14>")
	)
	(segment
		(start 102.046278 -217.559128)
		(end 102.055168 -217.554048)
		(width 0.0889)
		(layer "In15.Cu")
		(net "P5E_CPU1_PE0_TX_DN<14>")
	)
	(segment
		(start 58.17108 -325.310246)
		(end 58.17108 -331.446378)
		(width 0.14732)
		(layer "In15.Cu")
		(net "P5E_CPU1_PE0_TX_DN<14>")
	)
	(segment
		(start 85.502242 -202.341734)
		(end 73.677526 -214.980266)
		(width 0.14732)
		(layer "In15.Cu")
		(net "P5E_CPU1_PE0_TX_DN<14>")
	)
	(segment
		(start 52.140612 -397.696182)
		(end 51.337718 -399.933922)
		(width 0.14732)
		(layer "In15.Cu")
		(net "P5E_CPU1_PE0_TX_DN<14>")
	)
	(segment
		(start 67.676776 -249.954542)
		(end 67.53733 -254.377698)
		(width 0.14732)
		(layer "In15.Cu")
		(net "P5E_CPU1_PE0_TX_DN<14>")
	)
	(segment
		(start 70.820026 -220.487494)
		(end 70.819772 -220.487494)
		(width 0.14732)
		(layer "In15.Cu")
		(net "P5E_CPU1_PE0_TX_DN<14>")
	)
	(segment
		(start 103.277416 -223.584262)
		(end 103.277416 -223.557084)
		(width 0.0889)
		(layer "In15.Cu")
		(net "P5E_CPU1_PE0_TX_DN<14>")
	)
	(segment
		(start 102.52329 -222.271336)
		(end 102.515924 -222.267018)
		(width 0.0889)
		(layer "In15.Cu")
		(net "P5E_CPU1_PE0_TX_DN<14>")
	)
	(segment
		(start 60.154312 -323.058536)
		(end 59.684412 -323.528436)
		(width 0.14732)
		(layer "In15.Cu")
		(net "P5E_CPU1_PE0_TX_DN<14>")
	)
	(segment
		(start 102.055168 -219.830396)
		(end 102.046278 -219.825316)
		(width 0.0889)
		(layer "In15.Cu")
		(net "P5E_CPU1_PE0_TX_DN<14>")
	)
	(segment
		(start 101.439472 -213.12251)
		(end 101.439472 -211.537296)
		(width 0.14732)
		(layer "In15.Cu")
		(net "P5E_CPU1_PE0_TX_DN<14>")
	)
	(segment
		(start 102.80777 -222.751396)
		(end 102.807516 -222.761556)
		(width 0.0889)
		(layer "In15.Cu")
		(net "P5E_CPU1_PE0_TX_DN<14>")
	)
	(segment
		(start 102.055168 -218.202764)
		(end 102.046278 -218.197684)
		(width 0.0889)
		(layer "In15.Cu")
		(net "P5E_CPU1_PE0_TX_DN<14>")
	)
	(segment
		(start 101.59111 -215.764618)
		(end 101.576124 -215.755982)
		(width 0.0889)
		(layer "In15.Cu")
		(net "P5E_CPU1_PE0_TX_DN<14>")
	)
	(segment
		(start 101.439472 -213.144608)
		(end 101.439472 -213.12251)
		(width 0.0889)
		(layer "In15.Cu")
		(net "P5E_CPU1_PE0_TX_DN<14>")
	)
	(segment
		(start 102.046278 -219.18676)
		(end 102.054152 -219.182188)
		(width 0.0889)
		(layer "In15.Cu")
		(net "P5E_CPU1_PE0_TX_DN<14>")
	)
	(segment
		(start 58.17108 -331.446378)
		(end 60.033408 -350.044512)
		(width 0.14732)
		(layer "In15.Cu")
		(net "P5E_CPU1_PE0_TX_DN<14>")
	)
	(segment
		(start 102.055168 -216.574878)
		(end 102.046278 -216.569798)
		(width 0.0889)
		(layer "In15.Cu")
		(net "P5E_CPU1_PE0_TX_DN<14>")
	)
	(segment
		(start 101.866954 -214.622634)
		(end 101.866954 -214.504778)
		(width 0.0889)
		(layer "In15.Cu")
		(net "P5E_CPU1_PE0_TX_DN<14>")
	)
	(segment
		(start 102.994968 -223.085914)
		(end 102.986078 -223.080834)
		(width 0.0889)
		(layer "In15.Cu")
		(net "P5E_CPU1_PE0_TX_DN<14>")
	)
	(segment
		(start 70.997572 -308.181756)
		(end 67.856608 -316.121288)
		(width 0.14732)
		(layer "In15.Cu")
		(net "P5E_CPU1_PE0_TX_DN<14>")
	)
	(segment
		(start 51.337718 -400.563588)
		(end 51.043078 -400.858228)
		(width 0.14732)
		(layer "In15.Cu")
		(net "P5E_CPU1_PE0_TX_DN<14>")
	)
	(segment
		(start 102.046278 -220.814646)
		(end 102.055168 -220.809566)
		(width 0.0889)
		(layer "In15.Cu")
		(net "P5E_CPU1_PE0_TX_DN<14>")
	)
	(segment
		(start 100.396294 -209.01914)
		(end 94.14256 -202.765406)
		(width 0.14732)
		(layer "In15.Cu")
		(net "P5E_CPU1_PE0_TX_DN<14>")
	)
	(segment
		(start 102.061264 -216.578434)
		(end 102.055168 -216.574878)
		(width 0.0889)
		(layer "In15.Cu")
		(net "P5E_CPU1_PE0_TX_DN<14>")
	)
	(segment
		(start 87.975948 -201.261726)
		(end 85.502242 -202.341734)
		(width 0.14732)
		(layer "In15.Cu")
		(net "P5E_CPU1_PE0_TX_DN<14>")
	)
	(arc
		(start 101.867716 -217.888566)
		(mid 101.867636 -217.876118)
		(end 101.86797 -217.863674)
		(width 0.0889)
		(layer "In15.Cu")
		(net "P5E_CPU1_PE0_TX_DN<14>")
	)
	(arc
		(start 101.867716 -221.144084)
		(mid 101.867636 -221.131636)
		(end 101.86797 -221.119192)
		(width 0.0889)
		(layer "In15.Cu")
		(net "P5E_CPU1_PE0_TX_DN<14>")
	)
	(arc
		(start 102.055168 -217.554048)
		(mid 102.337782 -217.06793)
		(end 102.061264 -216.578434)
		(width 0.0889)
		(layer "In15.Cu")
		(net "P5E_CPU1_PE0_TX_DN<14>")
	)
	(arc
		(start 102.046278 -219.825316)
		(mid 101.867802 -219.506038)
		(end 102.046278 -219.18676)
		(width 0.0889)
		(layer "In15.Cu")
		(net "P5E_CPU1_PE0_TX_DN<14>")
	)
	(arc
		(start 101.576124 -215.755982)
		(mid 101.397527 -215.436704)
		(end 101.576124 -215.117426)
		(width 0.0889)
		(layer "In15.Cu")
		(net "P5E_CPU1_PE0_TX_DN<14>")
	)
	(arc
		(start 102.046278 -216.569798)
		(mid 101.915364 -216.433438)
		(end 101.867716 -216.25052)
		(width 0.0889)
		(layer "In15.Cu")
		(net "P5E_CPU1_PE0_TX_DN<14>")
	)
	(arc
		(start 103.277416 -223.557084)
		(mid 103.197254 -223.284895)
		(end 102.994968 -223.085914)
		(width 0.0889)
		(layer "In15.Cu")
		(net "P5E_CPU1_PE0_TX_DN<14>")
	)
	(arc
		(start 101.559868 -214.081614)
		(mid 101.440752 -213.955937)
		(end 101.397562 -213.788244)
		(width 0.0889)
		(layer "In15.Cu")
		(net "P5E_CPU1_PE0_TX_DN<14>")
	)
	(arc
		(start 102.046278 -221.453202)
		(mid 101.917874 -221.321257)
		(end 101.867716 -221.144084)
		(width 0.0889)
		(layer "In15.Cu")
		(net "P5E_CPU1_PE0_TX_DN<14>")
	)
	(arc
		(start 102.515924 -222.267018)
		(mid 102.38501 -222.130658)
		(end 102.337362 -221.94774)
		(width 0.0889)
		(layer "In15.Cu")
		(net "P5E_CPU1_PE0_TX_DN<14>")
	)
	(arc
		(start 102.337362 -218.676728)
		(mid 102.257992 -218.402994)
		(end 102.055168 -218.202764)
		(width 0.0889)
		(layer "In15.Cu")
		(net "P5E_CPU1_PE0_TX_DN<14>")
	)
	(arc
		(start 103.41737 -223.867472)
		(mid 103.316049 -223.741351)
		(end 103.277416 -223.584262)
		(width 0.0889)
		(layer "In15.Cu")
		(net "P5E_CPU1_PE0_TX_DN<14>")
	)
	(arc
		(start 101.819964 -214.349584)
		(mid 101.727325 -214.230449)
		(end 101.619812 -214.12454)
		(width 0.0889)
		(layer "In15.Cu")
		(net "P5E_CPU1_PE0_TX_DN<14>")
	)
	(arc
		(start 102.055168 -219.18168)
		(mid 102.257991 -218.981449)
		(end 102.337362 -218.707716)
		(width 0.0889)
		(layer "In15.Cu")
		(net "P5E_CPU1_PE0_TX_DN<14>")
	)
	(arc
		(start 101.86797 -217.863674)
		(mid 101.919024 -217.689094)
		(end 102.046278 -217.559128)
		(width 0.0889)
		(layer "In15.Cu")
		(net "P5E_CPU1_PE0_TX_DN<14>")
	)
	(arc
		(start 101.619812 -214.12454)
		(mid 101.590709 -214.101863)
		(end 101.559868 -214.081614)
		(width 0.0889)
		(layer "In15.Cu")
		(net "P5E_CPU1_PE0_TX_DN<14>")
	)
	(arc
		(start 101.597968 -215.103964)
		(mid 101.795229 -214.898358)
		(end 101.866954 -214.622634)
		(width 0.0889)
		(layer "In15.Cu")
		(net "P5E_CPU1_PE0_TX_DN<14>")
	)
	(arc
		(start 101.866954 -214.504778)
		(mid 101.855142 -214.42364)
		(end 101.819964 -214.349584)
		(width 0.0889)
		(layer "In15.Cu")
		(net "P5E_CPU1_PE0_TX_DN<14>")
	)
	(arc
		(start 102.807516 -222.761556)
		(mid 102.733525 -222.48199)
		(end 102.53091 -222.275654)
		(width 0.0889)
		(layer "In15.Cu")
		(net "P5E_CPU1_PE0_TX_DN<14>")
	)
	(arc
		(start 102.046278 -218.197684)
		(mid 101.917874 -218.065739)
		(end 101.867716 -217.888566)
		(width 0.0889)
		(layer "In15.Cu")
		(net "P5E_CPU1_PE0_TX_DN<14>")
	)
	(arc
		(start 102.337362 -221.932246)
		(mid 102.257992 -221.658512)
		(end 102.055168 -221.458282)
		(width 0.0889)
		(layer "In15.Cu")
		(net "P5E_CPU1_PE0_TX_DN<14>")
	)
	(arc
		(start 101.86797 -221.119192)
		(mid 101.919024 -220.944612)
		(end 102.046278 -220.814646)
		(width 0.0889)
		(layer "In15.Cu")
		(net "P5E_CPU1_PE0_TX_DN<14>")
	)
	(arc
		(start 102.986078 -223.080834)
		(mid 102.858185 -222.949772)
		(end 102.80777 -222.773748)
		(width 0.0889)
		(layer "In15.Cu")
		(net "P5E_CPU1_PE0_TX_DN<14>")
	)
	(arc
		(start 101.867716 -216.25052)
		(mid 101.793725 -215.970954)
		(end 101.59111 -215.764618)
		(width 0.0889)
		(layer "In15.Cu")
		(net "P5E_CPU1_PE0_TX_DN<14>")
	)
	(arc
		(start 102.80777 -222.773748)
		(mid 102.807603 -222.762572)
		(end 102.80777 -222.751396)
		(width 0.0889)
		(layer "In15.Cu")
		(net "P5E_CPU1_PE0_TX_DN<14>")
	)
	(arc
		(start 102.055168 -220.809566)
		(mid 102.337782 -220.323448)
		(end 102.061264 -219.833952)
		(width 0.0889)
		(layer "In15.Cu")
		(net "P5E_CPU1_PE0_TX_DN<14>")
	)
	(segment
		(start 54.41188 -401.777962)
		(end 54.41188 -401.16379)
		(width 0.13208)
		(layer "F.Cu")
		(net "P5E_CPU1_PE0_TX_DN<13>")
	)
	(segment
		(start 102.242112 -224.389696)
		(end 102.242366 -224.389442)
		(width 0.13208)
		(layer "F.Cu")
		(net "P5E_CPU1_PE0_TX_DN<13>")
	)
	(segment
		(start 54.08549 -402.104352)
		(end 54.41188 -401.777962)
		(width 0.13208)
		(layer "F.Cu")
		(net "P5E_CPU1_PE0_TX_DN<13>")
	)
	(segment
		(start 102.242112 -224.925382)
		(end 102.242112 -224.389696)
		(width 0.13208)
		(layer "F.Cu")
		(net "P5E_CPU1_PE0_TX_DN<13>")
	)
	(segment
		(start 54.41188 -401.16379)
		(end 54.106318 -400.858228)
		(width 0.13208)
		(layer "F.Cu")
		(net "P5E_CPU1_PE0_TX_DN<13>")
	)
	(segment
		(start 54.080918 -402.104352)
		(end 54.08549 -402.104352)
		(width 0.13208)
		(layer "F.Cu")
		(net "P5E_CPU1_PE0_TX_DN<13>")
	)
	(segment
		(start 100.457762 -213.186518)
		(end 100.499672 -213.144608)
		(width 0.0889)
		(layer "In15.Cu")
		(net "P5E_CPU1_PE0_TX_DN<13>")
	)
	(segment
		(start 100.499672 -213.12251)
		(end 100.499672 -211.830158)
		(width 0.14732)
		(layer "In15.Cu")
		(net "P5E_CPU1_PE0_TX_DN<13>")
	)
	(segment
		(start 101.59111 -222.275654)
		(end 101.587808 -222.273622)
		(width 0.0889)
		(layer "In15.Cu")
		(net "P5E_CPU1_PE0_TX_DN<13>")
	)
	(segment
		(start 102.046278 -224.070164)
		(end 102.055168 -224.065084)
		(width 0.0889)
		(layer "In15.Cu")
		(net "P5E_CPU1_PE0_TX_DN<13>")
	)
	(segment
		(start 100.457762 -213.819486)
		(end 100.457762 -213.186518)
		(width 0.0889)
		(layer "In15.Cu")
		(net "P5E_CPU1_PE0_TX_DN<13>")
	)
	(segment
		(start 74.464164 -215.51265)
		(end 71.731378 -220.780102)
		(width 0.14732)
		(layer "In15.Cu")
		(net "P5E_CPU1_PE0_TX_DN<13>")
	)
	(segment
		(start 58.995818 -374.802146)
		(end 54.400958 -399.932652)
		(width 0.14732)
		(layer "In15.Cu")
		(net "P5E_CPU1_PE0_TX_DN<13>")
	)
	(segment
		(start 66.692272 -319.551304)
		(end 64.38392 -321.859402)
		(width 0.14732)
		(layer "In15.Cu")
		(net "P5E_CPU1_PE0_TX_DN<13>")
	)
	(segment
		(start 60.556394 -324.292722)
		(end 59.11977 -325.729346)
		(width 0.14732)
		(layer "In15.Cu")
		(net "P5E_CPU1_PE0_TX_DN<13>")
	)
	(segment
		(start 90.346276 -202.207876)
		(end 89.24798 -202.205082)
		(width 0.14732)
		(layer "In15.Cu")
		(net "P5E_CPU1_PE0_TX_DN<13>")
	)
	(segment
		(start 101.397562 -221.94774)
		(end 101.397562 -221.932246)
		(width 0.0889)
		(layer "In15.Cu")
		(net "P5E_CPU1_PE0_TX_DN<13>")
	)
	(segment
		(start 71.731378 -220.780102)
		(end 71.731124 -220.780102)
		(width 0.14732)
		(layer "In15.Cu")
		(net "P5E_CPU1_PE0_TX_DN<13>")
	)
	(segment
		(start 101.115368 -218.202764)
		(end 101.106478 -218.197684)
		(width 0.0889)
		(layer "In15.Cu")
		(net "P5E_CPU1_PE0_TX_DN<13>")
	)
	(segment
		(start 93.335348 -203.446126)
		(end 90.346276 -202.207876)
		(width 0.14732)
		(layer "In15.Cu")
		(net "P5E_CPU1_PE0_TX_DN<13>")
	)
	(segment
		(start 100.636324 -215.117426)
		(end 100.644198 -215.112854)
		(width 0.0889)
		(layer "In15.Cu")
		(net "P5E_CPU1_PE0_TX_DN<13>")
	)
	(segment
		(start 102.055168 -224.7138)
		(end 102.046278 -224.70872)
		(width 0.0889)
		(layer "In15.Cu")
		(net "P5E_CPU1_PE0_TX_DN<13>")
	)
	(segment
		(start 100.494592 -213.927182)
		(end 100.462334 -213.84387)
		(width 0.0889)
		(layer "In15.Cu")
		(net "P5E_CPU1_PE0_TX_DN<13>")
	)
	(segment
		(start 101.397816 -220.338396)
		(end 101.397816 -220.309948)
		(width 0.0889)
		(layer "In15.Cu")
		(net "P5E_CPU1_PE0_TX_DN<13>")
	)
	(segment
		(start 102.39883 -224.66046)
		(end 102.377748 -224.738438)
		(width 0.0889)
		(layer "In15.Cu")
		(net "P5E_CPU1_PE0_TX_DN<13>")
	)
	(segment
		(start 101.58349 -222.271336)
		(end 101.576124 -222.267018)
		(width 0.0889)
		(layer "In15.Cu")
		(net "P5E_CPU1_PE0_TX_DN<13>")
	)
	(segment
		(start 101.397562 -218.707716)
		(end 101.397562 -218.676728)
		(width 0.0889)
		(layer "In15.Cu")
		(net "P5E_CPU1_PE0_TX_DN<13>")
	)
	(segment
		(start 101.587808 -222.273622)
		(end 101.585014 -222.272098)
		(width 0.0889)
		(layer "In15.Cu")
		(net "P5E_CPU1_PE0_TX_DN<13>")
	)
	(segment
		(start 59.11977 -325.729346)
		(end 59.11977 -330.560172)
		(width 0.14732)
		(layer "In15.Cu")
		(net "P5E_CPU1_PE0_TX_DN<13>")
	)
	(segment
		(start 100.499672 -213.144608)
		(end 100.499672 -213.12251)
		(width 0.0889)
		(layer "In15.Cu")
		(net "P5E_CPU1_PE0_TX_DN<13>")
	)
	(segment
		(start 100.644198 -215.112854)
		(end 100.645214 -215.112346)
		(width 0.0889)
		(layer "In15.Cu")
		(net "P5E_CPU1_PE0_TX_DN<13>")
	)
	(segment
		(start 101.115368 -221.458282)
		(end 101.106478 -221.453202)
		(width 0.0889)
		(layer "In15.Cu")
		(net "P5E_CPU1_PE0_TX_DN<13>")
	)
	(segment
		(start 100.65131 -215.764618)
		(end 100.648008 -215.762586)
		(width 0.0889)
		(layer "In15.Cu")
		(net "P5E_CPU1_PE0_TX_DN<13>")
	)
	(segment
		(start 68.497704 -254.31115)
		(end 72.002904 -308.616858)
		(width 0.14732)
		(layer "In15.Cu")
		(net "P5E_CPU1_PE0_TX_DN<13>")
	)
	(segment
		(start 71.731124 -220.780102)
		(end 71.71055 -220.81998)
		(width 0.14732)
		(layer "In15.Cu")
		(net "P5E_CPU1_PE0_TX_DN<13>")
	)
	(segment
		(start 101.115368 -219.830396)
		(end 101.106478 -219.825316)
		(width 0.0889)
		(layer "In15.Cu")
		(net "P5E_CPU1_PE0_TX_DN<13>")
	)
	(segment
		(start 64.38392 -321.859402)
		(end 63.939928 -322.043552)
		(width 0.14732)
		(layer "In15.Cu")
		(net "P5E_CPU1_PE0_TX_DN<13>")
	)
	(segment
		(start 88.146382 -202.202288)
		(end 86.068916 -203.109322)
		(width 0.14732)
		(layer "In15.Cu")
		(net "P5E_CPU1_PE0_TX_DN<13>")
	)
	(segment
		(start 61.386974 -323.948806)
		(end 60.556394 -324.292722)
		(width 0.14732)
		(layer "In15.Cu")
		(net "P5E_CPU1_PE0_TX_DN<13>")
	)
	(segment
		(start 101.106478 -220.814646)
		(end 101.115368 -220.809566)
		(width 0.0889)
		(layer "In15.Cu")
		(net "P5E_CPU1_PE0_TX_DN<13>")
	)
	(segment
		(start 61.074808 -350.505014)
		(end 58.995818 -374.802146)
		(width 0.14732)
		(layer "In15.Cu")
		(net "P5E_CPU1_PE0_TX_DN<13>")
	)
	(segment
		(start 100.499672 -211.830158)
		(end 99.637342 -209.74812)
		(width 0.14732)
		(layer "In15.Cu")
		(net "P5E_CPU1_PE0_TX_DN<13>")
	)
	(segment
		(start 59.11977 -330.560172)
		(end 61.074808 -350.505014)
		(width 0.14732)
		(layer "In15.Cu")
		(net "P5E_CPU1_PE0_TX_DN<13>")
	)
	(segment
		(start 69.90715 -232.489756)
		(end 68.614544 -249.992896)
		(width 0.14732)
		(layer "In15.Cu")
		(net "P5E_CPU1_PE0_TX_DN<13>")
	)
	(segment
		(start 102.055168 -223.085914)
		(end 102.046278 -223.080834)
		(width 0.0889)
		(layer "In15.Cu")
		(net "P5E_CPU1_PE0_TX_DN<13>")
	)
	(segment
		(start 68.497704 -253.462282)
		(end 68.497704 -254.31115)
		(width 0.14732)
		(layer "In15.Cu")
		(net "P5E_CPU1_PE0_TX_DN<13>")
	)
	(segment
		(start 100.64369 -215.7603)
		(end 100.636324 -215.755982)
		(width 0.0889)
		(layer "In15.Cu")
		(net "P5E_CPU1_PE0_TX_DN<13>")
	)
	(segment
		(start 89.24798 -202.205082)
		(end 89.241884 -202.204828)
		(width 0.14732)
		(layer "In15.Cu")
		(net "P5E_CPU1_PE0_TX_DN<13>")
	)
	(segment
		(start 63.339472 -322.643754)
		(end 61.386974 -323.948806)
		(width 0.14732)
		(layer "In15.Cu")
		(net "P5E_CPU1_PE0_TX_DN<13>")
	)
	(segment
		(start 101.86797 -222.751396)
		(end 101.867716 -222.761556)
		(width 0.0889)
		(layer "In15.Cu")
		(net "P5E_CPU1_PE0_TX_DN<13>")
	)
	(segment
		(start 101.115368 -216.574878)
		(end 101.106478 -216.569798)
		(width 0.0889)
		(layer "In15.Cu")
		(net "P5E_CPU1_PE0_TX_DN<13>")
	)
	(segment
		(start 100.927408 -214.644732)
		(end 100.927408 -214.470996)
		(width 0.0889)
		(layer "In15.Cu")
		(net "P5E_CPU1_PE0_TX_DN<13>")
	)
	(segment
		(start 100.927408 -214.470996)
		(end 100.927154 -214.470996)
		(width 0.0889)
		(layer "In15.Cu")
		(net "P5E_CPU1_PE0_TX_DN<13>")
	)
	(segment
		(start 102.337616 -223.575626)
		(end 102.337616 -223.561402)
		(width 0.0889)
		(layer "In15.Cu")
		(net "P5E_CPU1_PE0_TX_DN<13>")
	)
	(segment
		(start 63.939928 -322.043552)
		(end 63.339472 -322.643754)
		(width 0.14732)
		(layer "In15.Cu")
		(net "P5E_CPU1_PE0_TX_DN<13>")
	)
	(segment
		(start 100.645214 -215.761062)
		(end 100.64369 -215.7603)
		(width 0.0889)
		(layer "In15.Cu")
		(net "P5E_CPU1_PE0_TX_DN<13>")
	)
	(segment
		(start 101.106478 -217.559128)
		(end 101.115368 -217.554048)
		(width 0.0889)
		(layer "In15.Cu")
		(net "P5E_CPU1_PE0_TX_DN<13>")
	)
	(segment
		(start 68.594986 -316.833758)
		(end 66.692272 -319.551304)
		(width 0.14732)
		(layer "In15.Cu")
		(net "P5E_CPU1_PE0_TX_DN<13>")
	)
	(segment
		(start 54.400958 -400.563588)
		(end 54.106318 -400.858228)
		(width 0.14732)
		(layer "In15.Cu")
		(net "P5E_CPU1_PE0_TX_DN<13>")
	)
	(segment
		(start 54.400958 -399.932652)
		(end 54.400958 -400.563588)
		(width 0.14732)
		(layer "In15.Cu")
		(net "P5E_CPU1_PE0_TX_DN<13>")
	)
	(segment
		(start 72.002904 -308.616858)
		(end 68.594986 -316.833758)
		(width 0.14732)
		(layer "In15.Cu")
		(net "P5E_CPU1_PE0_TX_DN<13>")
	)
	(segment
		(start 89.241884 -202.204828)
		(end 88.146382 -202.202288)
		(width 0.14732)
		(layer "In15.Cu")
		(net "P5E_CPU1_PE0_TX_DN<13>")
	)
	(segment
		(start 102.055168 -224.065084)
		(end 102.061264 -224.061528)
		(width 0.0889)
		(layer "In15.Cu")
		(net "P5E_CPU1_PE0_TX_DN<13>")
	)
	(segment
		(start 68.614544 -249.992896)
		(end 68.497704 -253.462282)
		(width 0.14732)
		(layer "In15.Cu")
		(net "P5E_CPU1_PE0_TX_DN<13>")
	)
	(segment
		(start 100.648008 -215.762586)
		(end 100.645214 -215.761062)
		(width 0.0889)
		(layer "In15.Cu")
		(net "P5E_CPU1_PE0_TX_DN<13>")
	)
	(segment
		(start 101.397816 -217.082878)
		(end 101.397816 -217.05443)
		(width 0.0889)
		(layer "In15.Cu")
		(net "P5E_CPU1_PE0_TX_DN<13>")
	)
	(segment
		(start 102.242366 -224.389442)
		(end 102.39883 -224.66046)
		(width 0.0889)
		(layer "In15.Cu")
		(net "P5E_CPU1_PE0_TX_DN<13>")
	)
	(segment
		(start 99.637342 -209.74812)
		(end 93.335348 -203.446126)
		(width 0.14732)
		(layer "In15.Cu")
		(net "P5E_CPU1_PE0_TX_DN<13>")
	)
	(segment
		(start 101.106478 -219.18676)
		(end 101.115368 -219.18168)
		(width 0.0889)
		(layer "In15.Cu")
		(net "P5E_CPU1_PE0_TX_DN<13>")
	)
	(segment
		(start 71.71055 -220.81998)
		(end 69.90715 -232.489756)
		(width 0.14732)
		(layer "In15.Cu")
		(net "P5E_CPU1_PE0_TX_DN<13>")
	)
	(segment
		(start 101.585014 -222.272098)
		(end 101.58349 -222.271336)
		(width 0.0889)
		(layer "In15.Cu")
		(net "P5E_CPU1_PE0_TX_DN<13>")
	)
	(segment
		(start 86.068916 -203.109322)
		(end 74.464164 -215.51265)
		(width 0.14732)
		(layer "In15.Cu")
		(net "P5E_CPU1_PE0_TX_DN<13>")
	)
	(arc
		(start 102.337616 -223.561402)
		(mid 102.258475 -223.286779)
		(end 102.055168 -223.085914)
		(width 0.0889)
		(layer "In15.Cu")
		(net "P5E_CPU1_PE0_TX_DN<13>")
	)
	(arc
		(start 100.92817 -221.144084)
		(mid 100.928003 -221.132908)
		(end 100.92817 -221.121732)
		(width 0.0889)
		(layer "In15.Cu")
		(net "P5E_CPU1_PE0_TX_DN<13>")
	)
	(arc
		(start 101.397562 -218.676728)
		(mid 101.318192 -218.402994)
		(end 101.115368 -218.202764)
		(width 0.0889)
		(layer "In15.Cu")
		(net "P5E_CPU1_PE0_TX_DN<13>")
	)
	(arc
		(start 100.92817 -221.121732)
		(mid 100.978663 -220.945754)
		(end 101.106478 -220.814646)
		(width 0.0889)
		(layer "In15.Cu")
		(net "P5E_CPU1_PE0_TX_DN<13>")
	)
	(arc
		(start 102.046278 -223.080834)
		(mid 101.919198 -222.95082)
		(end 101.868224 -222.776288)
		(width 0.0889)
		(layer "In15.Cu")
		(net "P5E_CPU1_PE0_TX_DN<13>")
	)
	(arc
		(start 100.927916 -219.512642)
		(mid 100.927822 -219.50426)
		(end 100.927916 -219.495878)
		(width 0.0889)
		(layer "In15.Cu")
		(net "P5E_CPU1_PE0_TX_DN<13>")
	)
	(arc
		(start 101.115368 -217.554048)
		(mid 101.317654 -217.355067)
		(end 101.397816 -217.082878)
		(width 0.0889)
		(layer "In15.Cu")
		(net "P5E_CPU1_PE0_TX_DN<13>")
	)
	(arc
		(start 101.397562 -221.932246)
		(mid 101.318192 -221.658512)
		(end 101.115368 -221.458282)
		(width 0.0889)
		(layer "In15.Cu")
		(net "P5E_CPU1_PE0_TX_DN<13>")
	)
	(arc
		(start 100.457762 -215.436704)
		(mid 100.457814 -215.429337)
		(end 100.458016 -215.421972)
		(width 0.0889)
		(layer "In15.Cu")
		(net "P5E_CPU1_PE0_TX_DN<13>")
	)
	(arc
		(start 101.867716 -222.761556)
		(mid 101.793725 -222.48199)
		(end 101.59111 -222.275654)
		(width 0.0889)
		(layer "In15.Cu")
		(net "P5E_CPU1_PE0_TX_DN<13>")
	)
	(arc
		(start 101.576124 -222.267018)
		(mid 101.44521 -222.130658)
		(end 101.397562 -221.94774)
		(width 0.0889)
		(layer "In15.Cu")
		(net "P5E_CPU1_PE0_TX_DN<13>")
	)
	(arc
		(start 102.046278 -224.70872)
		(mid 101.867802 -224.389442)
		(end 102.046278 -224.070164)
		(width 0.0889)
		(layer "In15.Cu")
		(net "P5E_CPU1_PE0_TX_DN<13>")
	)
	(arc
		(start 101.397816 -217.05443)
		(mid 101.319705 -216.777481)
		(end 101.115368 -216.574878)
		(width 0.0889)
		(layer "In15.Cu")
		(net "P5E_CPU1_PE0_TX_DN<13>")
	)
	(arc
		(start 101.106478 -221.453202)
		(mid 100.978159 -221.32123)
		(end 100.92817 -221.144084)
		(width 0.0889)
		(layer "In15.Cu")
		(net "P5E_CPU1_PE0_TX_DN<13>")
	)
	(arc
		(start 102.061264 -224.061528)
		(mid 102.263677 -223.855115)
		(end 102.337616 -223.575626)
		(width 0.0889)
		(layer "In15.Cu")
		(net "P5E_CPU1_PE0_TX_DN<13>")
	)
	(arc
		(start 101.106478 -219.825316)
		(mid 100.977189 -219.69183)
		(end 100.927916 -219.512642)
		(width 0.0889)
		(layer "In15.Cu")
		(net "P5E_CPU1_PE0_TX_DN<13>")
	)
	(arc
		(start 100.642166 -214.093298)
		(mid 100.553352 -214.023587)
		(end 100.494592 -213.927182)
		(width 0.0889)
		(layer "In15.Cu")
		(net "P5E_CPU1_PE0_TX_DN<13>")
	)
	(arc
		(start 100.92817 -217.866214)
		(mid 100.978663 -217.690236)
		(end 101.106478 -217.559128)
		(width 0.0889)
		(layer "In15.Cu")
		(net "P5E_CPU1_PE0_TX_DN<13>")
	)
	(arc
		(start 100.927916 -219.495878)
		(mid 100.977985 -219.318653)
		(end 101.106478 -219.18676)
		(width 0.0889)
		(layer "In15.Cu")
		(net "P5E_CPU1_PE0_TX_DN<13>")
	)
	(arc
		(start 100.927916 -216.25052)
		(mid 100.853925 -215.970954)
		(end 100.65131 -215.764618)
		(width 0.0889)
		(layer "In15.Cu")
		(net "P5E_CPU1_PE0_TX_DN<13>")
	)
	(arc
		(start 101.115368 -219.18168)
		(mid 101.318191 -218.981449)
		(end 101.397562 -218.707716)
		(width 0.0889)
		(layer "In15.Cu")
		(net "P5E_CPU1_PE0_TX_DN<13>")
	)
	(arc
		(start 100.92817 -217.888566)
		(mid 100.928003 -217.87739)
		(end 100.92817 -217.866214)
		(width 0.0889)
		(layer "In15.Cu")
		(net "P5E_CPU1_PE0_TX_DN<13>")
	)
	(arc
		(start 101.397816 -220.309948)
		(mid 101.319705 -220.032999)
		(end 101.115368 -219.830396)
		(width 0.0889)
		(layer "In15.Cu")
		(net "P5E_CPU1_PE0_TX_DN<13>")
	)
	(arc
		(start 100.458016 -215.421972)
		(mid 100.50907 -215.247392)
		(end 100.636324 -215.117426)
		(width 0.0889)
		(layer "In15.Cu")
		(net "P5E_CPU1_PE0_TX_DN<13>")
	)
	(arc
		(start 100.636324 -215.755982)
		(mid 100.50541 -215.619622)
		(end 100.457762 -215.436704)
		(width 0.0889)
		(layer "In15.Cu")
		(net "P5E_CPU1_PE0_TX_DN<13>")
	)
	(arc
		(start 102.377748 -224.738438)
		(mid 102.213652 -224.762785)
		(end 102.055168 -224.7138)
		(width 0.0889)
		(layer "In15.Cu")
		(net "P5E_CPU1_PE0_TX_DN<13>")
	)
	(arc
		(start 101.868224 -222.776288)
		(mid 101.867891 -222.763844)
		(end 101.86797 -222.751396)
		(width 0.0889)
		(layer "In15.Cu")
		(net "P5E_CPU1_PE0_TX_DN<13>")
	)
	(arc
		(start 101.106478 -218.197684)
		(mid 100.978159 -218.065712)
		(end 100.92817 -217.888566)
		(width 0.0889)
		(layer "In15.Cu")
		(net "P5E_CPU1_PE0_TX_DN<13>")
	)
	(arc
		(start 100.927154 -214.470996)
		(mid 100.92082 -214.416934)
		(end 100.90277 -214.365586)
		(width 0.0889)
		(layer "In15.Cu")
		(net "P5E_CPU1_PE0_TX_DN<13>")
	)
	(arc
		(start 100.462334 -213.84387)
		(mid 100.458915 -213.83189)
		(end 100.457762 -213.819486)
		(width 0.0889)
		(layer "In15.Cu")
		(net "P5E_CPU1_PE0_TX_DN<13>")
	)
	(arc
		(start 101.115368 -220.809566)
		(mid 101.317654 -220.610585)
		(end 101.397816 -220.338396)
		(width 0.0889)
		(layer "In15.Cu")
		(net "P5E_CPU1_PE0_TX_DN<13>")
	)
	(arc
		(start 100.90277 -214.365586)
		(mid 100.794443 -214.208414)
		(end 100.642166 -214.093298)
		(width 0.0889)
		(layer "In15.Cu")
		(net "P5E_CPU1_PE0_TX_DN<13>")
	)
	(arc
		(start 101.106478 -216.569798)
		(mid 100.975564 -216.433438)
		(end 100.927916 -216.25052)
		(width 0.0889)
		(layer "In15.Cu")
		(net "P5E_CPU1_PE0_TX_DN<13>")
	)
	(arc
		(start 100.645214 -215.112346)
		(mid 100.846496 -214.914859)
		(end 100.927408 -214.644732)
		(width 0.0889)
		(layer "In15.Cu")
		(net "P5E_CPU1_PE0_TX_DN<13>")
	)
	(segment
		(start 57.144158 -402.104352)
		(end 57.14873 -402.104352)
		(width 0.13208)
		(layer "F.Cu")
		(net "P5E_CPU1_PE0_TX_DN<12>")
	)
	(segment
		(start 101.772466 -223.57588)
		(end 101.772212 -223.575626)
		(width 0.13208)
		(layer "F.Cu")
		(net "P5E_CPU1_PE0_TX_DN<12>")
	)
	(segment
		(start 57.47512 -401.777962)
		(end 57.47512 -401.16379)
		(width 0.13208)
		(layer "F.Cu")
		(net "P5E_CPU1_PE0_TX_DN<12>")
	)
	(segment
		(start 57.47512 -401.16379)
		(end 57.169558 -400.858228)
		(width 0.13208)
		(layer "F.Cu")
		(net "P5E_CPU1_PE0_TX_DN<12>")
	)
	(segment
		(start 101.772466 -224.111566)
		(end 101.772466 -223.57588)
		(width 0.13208)
		(layer "F.Cu")
		(net "P5E_CPU1_PE0_TX_DN<12>")
	)
	(segment
		(start 57.14873 -402.104352)
		(end 57.47512 -401.777962)
		(width 0.13208)
		(layer "F.Cu")
		(net "P5E_CPU1_PE0_TX_DN<12>")
	)
	(segment
		(start 99.708208 -215.762586)
		(end 99.705414 -215.761062)
		(width 0.0889)
		(layer "In15.Cu")
		(net "P5E_CPU1_PE0_TX_DN<12>")
	)
	(segment
		(start 60.080906 -326.12457)
		(end 60.080906 -330.253848)
		(width 0.14732)
		(layer "In15.Cu")
		(net "P5E_CPU1_PE0_TX_DN<12>")
	)
	(segment
		(start 99.71151 -215.764618)
		(end 99.708208 -215.762586)
		(width 0.0889)
		(layer "In15.Cu")
		(net "P5E_CPU1_PE0_TX_DN<12>")
	)
	(segment
		(start 72.982836 -308.883558)
		(end 69.58965 -317.074042)
		(width 0.14732)
		(layer "In15.Cu")
		(net "P5E_CPU1_PE0_TX_DN<12>")
	)
	(segment
		(start 101.615748 -223.846644)
		(end 101.53777 -223.867472)
		(width 0.0889)
		(layer "In15.Cu")
		(net "P5E_CPU1_PE0_TX_DN<12>")
	)
	(segment
		(start 64.423798 -322.896992)
		(end 63.979044 -323.341492)
		(width 0.14732)
		(layer "In15.Cu")
		(net "P5E_CPU1_PE0_TX_DN<12>")
	)
	(segment
		(start 100.166678 -217.559128)
		(end 100.175568 -217.554048)
		(width 0.0889)
		(layer "In15.Cu")
		(net "P5E_CPU1_PE0_TX_DN<12>")
	)
	(segment
		(start 69.429884 -253.686564)
		(end 69.42963 -253.686564)
		(width 0.14732)
		(layer "In15.Cu")
		(net "P5E_CPU1_PE0_TX_DN<12>")
	)
	(segment
		(start 100.17252 -219.183458)
		(end 100.174552 -219.182188)
		(width 0.0889)
		(layer "In15.Cu")
		(net "P5E_CPU1_PE0_TX_DN<12>")
	)
	(segment
		(start 100.166678 -220.814646)
		(end 100.175568 -220.809566)
		(width 0.0889)
		(layer "In15.Cu")
		(net "P5E_CPU1_PE0_TX_DN<12>")
	)
	(segment
		(start 75.282806 -216.075006)
		(end 74.026522 -218.496134)
		(width 0.14732)
		(layer "In15.Cu")
		(net "P5E_CPU1_PE0_TX_DN<12>")
	)
	(segment
		(start 99.559872 -213.144608)
		(end 99.559872 -213.12251)
		(width 0.0889)
		(layer "In15.Cu")
		(net "P5E_CPU1_PE0_TX_DN<12>")
	)
	(segment
		(start 86.729062 -203.840334)
		(end 75.282806 -216.075006)
		(width 0.14732)
		(layer "In15.Cu")
		(net "P5E_CPU1_PE0_TX_DN<12>")
	)
	(segment
		(start 62.016386 -350.378522)
		(end 60.465208 -375.728992)
		(width 0.14732)
		(layer "In15.Cu")
		(net "P5E_CPU1_PE0_TX_DN<12>")
	)
	(segment
		(start 90.039444 -203.147676)
		(end 88.32596 -203.14285)
		(width 0.14732)
		(layer "In15.Cu")
		(net "P5E_CPU1_PE0_TX_DN<12>")
	)
	(segment
		(start 100.167694 -219.825824)
		(end 100.166678 -219.825316)
		(width 0.0889)
		(layer "In15.Cu")
		(net "P5E_CPU1_PE0_TX_DN<12>")
	)
	(segment
		(start 69.58965 -317.074042)
		(end 67.422776 -320.16827)
		(width 0.14732)
		(layer "In15.Cu")
		(net "P5E_CPU1_PE0_TX_DN<12>")
	)
	(segment
		(start 99.705414 -215.761062)
		(end 99.70389 -215.7603)
		(width 0.0889)
		(layer "In15.Cu")
		(net "P5E_CPU1_PE0_TX_DN<12>")
	)
	(segment
		(start 70.96887 -232.559352)
		(end 69.55155 -250.041156)
		(width 0.14732)
		(layer "In15.Cu")
		(net "P5E_CPU1_PE0_TX_DN<12>")
	)
	(segment
		(start 69.42963 -253.686564)
		(end 69.429376 -253.700026)
		(width 0.14732)
		(layer "In15.Cu")
		(net "P5E_CPU1_PE0_TX_DN<12>")
	)
	(segment
		(start 61.133736 -325.07174)
		(end 60.080906 -326.12457)
		(width 0.14732)
		(layer "In15.Cu")
		(net "P5E_CPU1_PE0_TX_DN<12>")
	)
	(segment
		(start 99.696524 -215.117426)
		(end 99.704398 -215.112854)
		(width 0.0889)
		(layer "In15.Cu")
		(net "P5E_CPU1_PE0_TX_DN<12>")
	)
	(segment
		(start 100.175568 -221.458282)
		(end 100.166678 -221.453202)
		(width 0.0889)
		(layer "In15.Cu")
		(net "P5E_CPU1_PE0_TX_DN<12>")
	)
	(segment
		(start 67.422776 -320.16827)
		(end 64.885316 -322.70573)
		(width 0.14732)
		(layer "In15.Cu")
		(net "P5E_CPU1_PE0_TX_DN<12>")
	)
	(segment
		(start 100.166678 -219.18676)
		(end 100.17252 -219.183458)
		(width 0.0889)
		(layer "In15.Cu")
		(net "P5E_CPU1_PE0_TX_DN<12>")
	)
	(segment
		(start 99.559872 -212.007704)
		(end 98.847402 -210.287616)
		(width 0.14732)
		(layer "In15.Cu")
		(net "P5E_CPU1_PE0_TX_DN<12>")
	)
	(segment
		(start 99.559872 -213.12251)
		(end 99.559872 -212.007704)
		(width 0.14732)
		(layer "In15.Cu")
		(net "P5E_CPU1_PE0_TX_DN<12>")
	)
	(segment
		(start 88.32596 -203.14285)
		(end 86.729062 -203.840334)
		(width 0.14732)
		(layer "In15.Cu")
		(net "P5E_CPU1_PE0_TX_DN<12>")
	)
	(segment
		(start 57.464198 -399.911316)
		(end 57.464198 -400.563588)
		(width 0.14732)
		(layer "In15.Cu")
		(net "P5E_CPU1_PE0_TX_DN<12>")
	)
	(segment
		(start 60.080906 -330.253848)
		(end 62.016386 -350.378522)
		(width 0.14732)
		(layer "In15.Cu")
		(net "P5E_CPU1_PE0_TX_DN<12>")
	)
	(segment
		(start 99.517962 -213.880954)
		(end 99.517962 -213.186518)
		(width 0.0889)
		(layer "In15.Cu")
		(net "P5E_CPU1_PE0_TX_DN<12>")
	)
	(segment
		(start 101.772212 -223.575626)
		(end 101.615748 -223.846644)
		(width 0.0889)
		(layer "In15.Cu")
		(net "P5E_CPU1_PE0_TX_DN<12>")
	)
	(segment
		(start 92.887292 -204.327506)
		(end 90.039444 -203.147676)
		(width 0.14732)
		(layer "In15.Cu")
		(net "P5E_CPU1_PE0_TX_DN<12>")
	)
	(segment
		(start 69.55155 -250.041156)
		(end 69.429884 -253.686564)
		(width 0.14732)
		(layer "In15.Cu")
		(net "P5E_CPU1_PE0_TX_DN<12>")
	)
	(segment
		(start 99.704398 -215.112854)
		(end 99.705414 -215.112346)
		(width 0.0889)
		(layer "In15.Cu")
		(net "P5E_CPU1_PE0_TX_DN<12>")
	)
	(segment
		(start 100.181664 -216.578434)
		(end 100.166678 -216.569798)
		(width 0.0889)
		(layer "In15.Cu")
		(net "P5E_CPU1_PE0_TX_DN<12>")
	)
	(segment
		(start 69.429376 -253.700026)
		(end 72.982836 -308.883558)
		(width 0.14732)
		(layer "In15.Cu")
		(net "P5E_CPU1_PE0_TX_DN<12>")
	)
	(segment
		(start 100.179378 -219.832682)
		(end 100.167694 -219.825824)
		(width 0.0889)
		(layer "In15.Cu")
		(net "P5E_CPU1_PE0_TX_DN<12>")
	)
	(segment
		(start 100.174552 -219.182188)
		(end 100.175568 -219.18168)
		(width 0.0889)
		(layer "In15.Cu")
		(net "P5E_CPU1_PE0_TX_DN<12>")
	)
	(segment
		(start 57.878726 -396.582646)
		(end 57.46623 -399.909284)
		(width 0.14732)
		(layer "In15.Cu")
		(net "P5E_CPU1_PE0_TX_DN<12>")
	)
	(segment
		(start 61.808614 -324.79234)
		(end 61.133736 -325.07174)
		(width 0.14732)
		(layer "In15.Cu")
		(net "P5E_CPU1_PE0_TX_DN<12>")
	)
	(segment
		(start 57.46623 -399.909284)
		(end 57.464198 -399.911316)
		(width 0.14732)
		(layer "In15.Cu")
		(net "P5E_CPU1_PE0_TX_DN<12>")
	)
	(segment
		(start 98.847402 -210.287616)
		(end 92.887292 -204.327506)
		(width 0.14732)
		(layer "In15.Cu")
		(net "P5E_CPU1_PE0_TX_DN<12>")
	)
	(segment
		(start 101.397816 -223.584262)
		(end 101.397816 -223.557084)
		(width 0.0889)
		(layer "In15.Cu")
		(net "P5E_CPU1_PE0_TX_DN<12>")
	)
	(segment
		(start 99.517962 -213.186518)
		(end 99.559872 -213.144608)
		(width 0.0889)
		(layer "In15.Cu")
		(net "P5E_CPU1_PE0_TX_DN<12>")
	)
	(segment
		(start 60.465208 -375.728992)
		(end 57.878726 -396.582646)
		(width 0.14732)
		(layer "In15.Cu")
		(net "P5E_CPU1_PE0_TX_DN<12>")
	)
	(segment
		(start 74.026522 -218.496134)
		(end 72.76719 -220.923358)
		(width 0.14732)
		(layer "In15.Cu")
		(net "P5E_CPU1_PE0_TX_DN<12>")
	)
	(segment
		(start 63.979044 -323.341492)
		(end 61.808614 -324.79234)
		(width 0.14732)
		(layer "In15.Cu")
		(net "P5E_CPU1_PE0_TX_DN<12>")
	)
	(segment
		(start 64.885316 -322.70573)
		(end 64.423798 -322.896992)
		(width 0.14732)
		(layer "In15.Cu")
		(net "P5E_CPU1_PE0_TX_DN<12>")
	)
	(segment
		(start 100.457762 -221.94774)
		(end 100.457762 -221.932246)
		(width 0.0889)
		(layer "In15.Cu")
		(net "P5E_CPU1_PE0_TX_DN<12>")
	)
	(segment
		(start 100.181664 -219.833952)
		(end 100.179378 -219.832682)
		(width 0.0889)
		(layer "In15.Cu")
		(net "P5E_CPU1_PE0_TX_DN<12>")
	)
	(segment
		(start 100.65131 -222.275654)
		(end 100.636324 -222.267018)
		(width 0.0889)
		(layer "In15.Cu")
		(net "P5E_CPU1_PE0_TX_DN<12>")
	)
	(segment
		(start 99.70389 -215.7603)
		(end 99.696524 -215.755982)
		(width 0.0889)
		(layer "In15.Cu")
		(net "P5E_CPU1_PE0_TX_DN<12>")
	)
	(segment
		(start 100.457762 -218.707716)
		(end 100.457762 -218.676728)
		(width 0.0889)
		(layer "In15.Cu")
		(net "P5E_CPU1_PE0_TX_DN<12>")
	)
	(segment
		(start 57.464198 -400.563588)
		(end 57.169558 -400.858228)
		(width 0.14732)
		(layer "In15.Cu")
		(net "P5E_CPU1_PE0_TX_DN<12>")
	)
	(segment
		(start 101.115368 -223.085914)
		(end 101.106478 -223.080834)
		(width 0.0889)
		(layer "In15.Cu")
		(net "P5E_CPU1_PE0_TX_DN<12>")
	)
	(segment
		(start 100.92817 -222.751396)
		(end 100.927916 -222.761556)
		(width 0.0889)
		(layer "In15.Cu")
		(net "P5E_CPU1_PE0_TX_DN<12>")
	)
	(segment
		(start 100.175568 -218.202764)
		(end 100.166678 -218.197684)
		(width 0.0889)
		(layer "In15.Cu")
		(net "P5E_CPU1_PE0_TX_DN<12>")
	)
	(segment
		(start 99.987608 -214.644732)
		(end 99.987608 -214.582248)
		(width 0.0889)
		(layer "In15.Cu")
		(net "P5E_CPU1_PE0_TX_DN<12>")
	)
	(segment
		(start 72.76719 -220.923358)
		(end 70.96887 -232.559352)
		(width 0.14732)
		(layer "In15.Cu")
		(net "P5E_CPU1_PE0_TX_DN<12>")
	)
	(arc
		(start 100.166678 -216.569798)
		(mid 100.035764 -216.433438)
		(end 99.988116 -216.25052)
		(width 0.0889)
		(layer "In15.Cu")
		(net "P5E_CPU1_PE0_TX_DN<12>")
	)
	(arc
		(start 99.988116 -216.25052)
		(mid 99.914125 -215.970954)
		(end 99.71151 -215.764618)
		(width 0.0889)
		(layer "In15.Cu")
		(net "P5E_CPU1_PE0_TX_DN<12>")
	)
	(arc
		(start 99.98837 -217.863674)
		(mid 100.039424 -217.689094)
		(end 100.166678 -217.559128)
		(width 0.0889)
		(layer "In15.Cu")
		(net "P5E_CPU1_PE0_TX_DN<12>")
	)
	(arc
		(start 99.518216 -215.421972)
		(mid 99.56927 -215.247392)
		(end 99.696524 -215.117426)
		(width 0.0889)
		(layer "In15.Cu")
		(net "P5E_CPU1_PE0_TX_DN<12>")
	)
	(arc
		(start 99.696524 -214.091012)
		(mid 99.595091 -214.011995)
		(end 99.523296 -213.905338)
		(width 0.0889)
		(layer "In15.Cu")
		(net "P5E_CPU1_PE0_TX_DN<12>")
	)
	(arc
		(start 99.517962 -215.436704)
		(mid 99.518014 -215.429337)
		(end 99.518216 -215.421972)
		(width 0.0889)
		(layer "In15.Cu")
		(net "P5E_CPU1_PE0_TX_DN<12>")
	)
	(arc
		(start 99.705414 -215.112346)
		(mid 99.906696 -214.914859)
		(end 99.987608 -214.644732)
		(width 0.0889)
		(layer "In15.Cu")
		(net "P5E_CPU1_PE0_TX_DN<12>")
	)
	(arc
		(start 101.106478 -223.080834)
		(mid 100.978585 -222.949772)
		(end 100.92817 -222.773748)
		(width 0.0889)
		(layer "In15.Cu")
		(net "P5E_CPU1_PE0_TX_DN<12>")
	)
	(arc
		(start 100.927916 -222.761556)
		(mid 100.853925 -222.48199)
		(end 100.65131 -222.275654)
		(width 0.0889)
		(layer "In15.Cu")
		(net "P5E_CPU1_PE0_TX_DN<12>")
	)
	(arc
		(start 100.166678 -218.197684)
		(mid 100.038274 -218.065739)
		(end 99.988116 -217.888566)
		(width 0.0889)
		(layer "In15.Cu")
		(net "P5E_CPU1_PE0_TX_DN<12>")
	)
	(arc
		(start 99.987608 -214.582248)
		(mid 99.9093 -214.296803)
		(end 99.696524 -214.091012)
		(width 0.0889)
		(layer "In15.Cu")
		(net "P5E_CPU1_PE0_TX_DN<12>")
	)
	(arc
		(start 100.175568 -219.18168)
		(mid 100.378391 -218.981449)
		(end 100.457762 -218.707716)
		(width 0.0889)
		(layer "In15.Cu")
		(net "P5E_CPU1_PE0_TX_DN<12>")
	)
	(arc
		(start 99.988624 -221.119192)
		(mid 100.039534 -220.944623)
		(end 100.166678 -220.814646)
		(width 0.0889)
		(layer "In15.Cu")
		(net "P5E_CPU1_PE0_TX_DN<12>")
	)
	(arc
		(start 100.457762 -218.676728)
		(mid 100.378392 -218.402994)
		(end 100.175568 -218.202764)
		(width 0.0889)
		(layer "In15.Cu")
		(net "P5E_CPU1_PE0_TX_DN<12>")
	)
	(arc
		(start 100.457762 -221.932246)
		(mid 100.378392 -221.658512)
		(end 100.175568 -221.458282)
		(width 0.0889)
		(layer "In15.Cu")
		(net "P5E_CPU1_PE0_TX_DN<12>")
	)
	(arc
		(start 99.988116 -217.888566)
		(mid 99.988036 -217.876118)
		(end 99.98837 -217.863674)
		(width 0.0889)
		(layer "In15.Cu")
		(net "P5E_CPU1_PE0_TX_DN<12>")
	)
	(arc
		(start 100.166678 -221.453202)
		(mid 100.038359 -221.32123)
		(end 99.98837 -221.144084)
		(width 0.0889)
		(layer "In15.Cu")
		(net "P5E_CPU1_PE0_TX_DN<12>")
	)
	(arc
		(start 101.53777 -223.867472)
		(mid 101.436449 -223.741351)
		(end 101.397816 -223.584262)
		(width 0.0889)
		(layer "In15.Cu")
		(net "P5E_CPU1_PE0_TX_DN<12>")
	)
	(arc
		(start 100.636324 -222.267018)
		(mid 100.50541 -222.130658)
		(end 100.457762 -221.94774)
		(width 0.0889)
		(layer "In15.Cu")
		(net "P5E_CPU1_PE0_TX_DN<12>")
	)
	(arc
		(start 99.98837 -221.144084)
		(mid 99.98829 -221.131636)
		(end 99.988624 -221.119192)
		(width 0.0889)
		(layer "In15.Cu")
		(net "P5E_CPU1_PE0_TX_DN<12>")
	)
	(arc
		(start 100.175568 -217.554048)
		(mid 100.458182 -217.06793)
		(end 100.181664 -216.578434)
		(width 0.0889)
		(layer "In15.Cu")
		(net "P5E_CPU1_PE0_TX_DN<12>")
	)
	(arc
		(start 100.175568 -220.809566)
		(mid 100.458182 -220.323448)
		(end 100.181664 -219.833952)
		(width 0.0889)
		(layer "In15.Cu")
		(net "P5E_CPU1_PE0_TX_DN<12>")
	)
	(arc
		(start 99.696524 -215.755982)
		(mid 99.56561 -215.619622)
		(end 99.517962 -215.436704)
		(width 0.0889)
		(layer "In15.Cu")
		(net "P5E_CPU1_PE0_TX_DN<12>")
	)
	(arc
		(start 100.92817 -222.773748)
		(mid 100.928003 -222.762572)
		(end 100.92817 -222.751396)
		(width 0.0889)
		(layer "In15.Cu")
		(net "P5E_CPU1_PE0_TX_DN<12>")
	)
	(arc
		(start 101.397816 -223.557084)
		(mid 101.317654 -223.284895)
		(end 101.115368 -223.085914)
		(width 0.0889)
		(layer "In15.Cu")
		(net "P5E_CPU1_PE0_TX_DN<12>")
	)
	(arc
		(start 99.523296 -213.905338)
		(mid 99.519313 -213.893436)
		(end 99.517962 -213.880954)
		(width 0.0889)
		(layer "In15.Cu")
		(net "P5E_CPU1_PE0_TX_DN<12>")
	)
	(arc
		(start 100.166678 -219.825316)
		(mid 99.988202 -219.506038)
		(end 100.166678 -219.18676)
		(width 0.0889)
		(layer "In15.Cu")
		(net "P5E_CPU1_PE0_TX_DN<12>")
	)
	(segment
		(start 60.207398 -402.104352)
		(end 60.21197 -402.104352)
		(width 0.13208)
		(layer "F.Cu")
		(net "P5E_CPU1_PE0_TX_DN<11>")
	)
	(segment
		(start 60.53836 -401.777962)
		(end 60.53836 -401.16379)
		(width 0.13208)
		(layer "F.Cu")
		(net "P5E_CPU1_PE0_TX_DN<11>")
	)
	(segment
		(start 100.362512 -224.925382)
		(end 100.362512 -224.389696)
		(width 0.13208)
		(layer "F.Cu")
		(net "P5E_CPU1_PE0_TX_DN<11>")
	)
	(segment
		(start 60.21197 -402.104352)
		(end 60.53836 -401.777962)
		(width 0.13208)
		(layer "F.Cu")
		(net "P5E_CPU1_PE0_TX_DN<11>")
	)
	(segment
		(start 60.53836 -401.16379)
		(end 60.232798 -400.858228)
		(width 0.13208)
		(layer "F.Cu")
		(net "P5E_CPU1_PE0_TX_DN<11>")
	)
	(segment
		(start 100.362512 -224.389696)
		(end 100.362766 -224.389442)
		(width 0.13208)
		(layer "F.Cu")
		(net "P5E_CPU1_PE0_TX_DN<11>")
	)
	(segment
		(start 100.458016 -223.575626)
		(end 100.458016 -223.561402)
		(width 0.0889)
		(layer "In15.Cu")
		(net "P5E_CPU1_PE0_TX_DN<11>")
	)
	(segment
		(start 99.047808 -214.644732)
		(end 99.047808 -214.424768)
		(width 0.0889)
		(layer "In15.Cu")
		(net "P5E_CPU1_PE0_TX_DN<11>")
	)
	(segment
		(start 69.630036 -319.411604)
		(end 67.988434 -322.009262)
		(width 0.14732)
		(layer "In15.Cu")
		(net "P5E_CPU1_PE0_TX_DN<11>")
	)
	(segment
		(start 99.226878 -219.18676)
		(end 99.235768 -219.18168)
		(width 0.0889)
		(layer "In15.Cu")
		(net "P5E_CPU1_PE0_TX_DN<11>")
	)
	(segment
		(start 100.175568 -223.085914)
		(end 100.174552 -223.085406)
		(width 0.0889)
		(layer "In15.Cu")
		(net "P5E_CPU1_PE0_TX_DN<11>")
	)
	(segment
		(start 99.226878 -217.559128)
		(end 99.235768 -217.554048)
		(width 0.0889)
		(layer "In15.Cu")
		(net "P5E_CPU1_PE0_TX_DN<11>")
	)
	(segment
		(start 100.174552 -223.085406)
		(end 100.166678 -223.080834)
		(width 0.0889)
		(layer "In15.Cu")
		(net "P5E_CPU1_PE0_TX_DN<11>")
	)
	(segment
		(start 98.77171 -215.764618)
		(end 98.768408 -215.762586)
		(width 0.0889)
		(layer "In15.Cu")
		(net "P5E_CPU1_PE0_TX_DN<11>")
	)
	(segment
		(start 98.768408 -215.762586)
		(end 98.765614 -215.761062)
		(width 0.0889)
		(layer "In15.Cu")
		(net "P5E_CPU1_PE0_TX_DN<11>")
	)
	(segment
		(start 98.578162 -213.186518)
		(end 98.620072 -213.144608)
		(width 0.0889)
		(layer "In15.Cu")
		(net "P5E_CPU1_PE0_TX_DN<11>")
	)
	(segment
		(start 67.988434 -322.009262)
		(end 65.609216 -324.012814)
		(width 0.14732)
		(layer "In15.Cu")
		(net "P5E_CPU1_PE0_TX_DN<11>")
	)
	(segment
		(start 99.517962 -218.707716)
		(end 99.517962 -218.676728)
		(width 0.0889)
		(layer "In15.Cu")
		(net "P5E_CPU1_PE0_TX_DN<11>")
	)
	(segment
		(start 81.97596 -210.982052)
		(end 76.053188 -216.67216)
		(width 0.14732)
		(layer "In15.Cu")
		(net "P5E_CPU1_PE0_TX_DN<11>")
	)
	(segment
		(start 98.620072 -212.22589)
		(end 98.049842 -210.849464)
		(width 0.14732)
		(layer "In15.Cu")
		(net "P5E_CPU1_PE0_TX_DN<11>")
	)
	(segment
		(start 86.2076 -208.684368)
		(end 81.97596 -210.982052)
		(width 0.14732)
		(layer "In15.Cu")
		(net "P5E_CPU1_PE0_TX_DN<11>")
	)
	(segment
		(start 98.578416 -213.893908)
		(end 98.578162 -213.8934)
		(width 0.0889)
		(layer "In15.Cu")
		(net "P5E_CPU1_PE0_TX_DN<11>")
	)
	(segment
		(start 99.226878 -220.814646)
		(end 99.235768 -220.809566)
		(width 0.0889)
		(layer "In15.Cu")
		(net "P5E_CPU1_PE0_TX_DN<11>")
	)
	(segment
		(start 98.049842 -210.849464)
		(end 96.83496 -209.634582)
		(width 0.14732)
		(layer "In15.Cu")
		(net "P5E_CPU1_PE0_TX_DN<11>")
	)
	(segment
		(start 63.035434 -325.577708)
		(end 62.42685 -325.577708)
		(width 0.14732)
		(layer "In15.Cu")
		(net "P5E_CPU1_PE0_TX_DN<11>")
	)
	(segment
		(start 98.765614 -215.761062)
		(end 98.76409 -215.7603)
		(width 0.0889)
		(layer "In15.Cu")
		(net "P5E_CPU1_PE0_TX_DN<11>")
	)
	(segment
		(start 99.518216 -220.338396)
		(end 99.518216 -220.309948)
		(width 0.0889)
		(layer "In15.Cu")
		(net "P5E_CPU1_PE0_TX_DN<11>")
	)
	(segment
		(start 71.898764 -232.692448)
		(end 70.491096 -250.085352)
		(width 0.14732)
		(layer "In15.Cu")
		(net "P5E_CPU1_PE0_TX_DN<11>")
	)
	(segment
		(start 61.015626 -329.59675)
		(end 62.985396 -350.539304)
		(width 0.14732)
		(layer "In15.Cu")
		(net "P5E_CPU1_PE0_TX_DN<11>")
	)
	(segment
		(start 70.381876 -253.321566)
		(end 70.381622 -253.334774)
		(width 0.14732)
		(layer "In15.Cu")
		(net "P5E_CPU1_PE0_TX_DN<11>")
	)
	(segment
		(start 99.235768 -218.202764)
		(end 99.226878 -218.197684)
		(width 0.0889)
		(layer "In15.Cu")
		(net "P5E_CPU1_PE0_TX_DN<11>")
	)
	(segment
		(start 99.517962 -221.94774)
		(end 99.517962 -221.932246)
		(width 0.0889)
		(layer "In15.Cu")
		(net "P5E_CPU1_PE0_TX_DN<11>")
	)
	(segment
		(start 62.42685 -325.577708)
		(end 61.60516 -325.918068)
		(width 0.14732)
		(layer "In15.Cu")
		(net "P5E_CPU1_PE0_TX_DN<11>")
	)
	(segment
		(start 100.166678 -224.070164)
		(end 100.175568 -224.065084)
		(width 0.0889)
		(layer "In15.Cu")
		(net "P5E_CPU1_PE0_TX_DN<11>")
	)
	(segment
		(start 100.362766 -224.389442)
		(end 100.51923 -224.66046)
		(width 0.0889)
		(layer "In15.Cu")
		(net "P5E_CPU1_PE0_TX_DN<11>")
	)
	(segment
		(start 99.518216 -217.082878)
		(end 99.518216 -217.05443)
		(width 0.0889)
		(layer "In15.Cu")
		(net "P5E_CPU1_PE0_TX_DN<11>")
	)
	(segment
		(start 100.175568 -224.065084)
		(end 100.181664 -224.061528)
		(width 0.0889)
		(layer "In15.Cu")
		(net "P5E_CPU1_PE0_TX_DN<11>")
	)
	(segment
		(start 74.857864 -218.976956)
		(end 74.85761 -218.976956)
		(width 0.14732)
		(layer "In15.Cu")
		(net "P5E_CPU1_PE0_TX_DN<11>")
	)
	(segment
		(start 61.60516 -325.918068)
		(end 61.015626 -326.507602)
		(width 0.14732)
		(layer "In15.Cu")
		(net "P5E_CPU1_PE0_TX_DN<11>")
	)
	(segment
		(start 99.98837 -222.751396)
		(end 99.988116 -222.761556)
		(width 0.0889)
		(layer "In15.Cu")
		(net "P5E_CPU1_PE0_TX_DN<11>")
	)
	(segment
		(start 62.985396 -350.539304)
		(end 60.527438 -399.81886)
		(width 0.14732)
		(layer "In15.Cu")
		(net "P5E_CPU1_PE0_TX_DN<11>")
	)
	(segment
		(start 61.015626 -326.507602)
		(end 61.015626 -329.59675)
		(width 0.14732)
		(layer "In15.Cu")
		(net "P5E_CPU1_PE0_TX_DN<11>")
	)
	(segment
		(start 73.66254 -221.28099)
		(end 71.898764 -232.692448)
		(width 0.14732)
		(layer "In15.Cu")
		(net "P5E_CPU1_PE0_TX_DN<11>")
	)
	(segment
		(start 65.609216 -324.012814)
		(end 63.035434 -325.577708)
		(width 0.14732)
		(layer "In15.Cu")
		(net "P5E_CPU1_PE0_TX_DN<11>")
	)
	(segment
		(start 99.71151 -222.275654)
		(end 99.705414 -222.272098)
		(width 0.0889)
		(layer "In15.Cu")
		(net "P5E_CPU1_PE0_TX_DN<11>")
	)
	(segment
		(start 98.620072 -213.144608)
		(end 98.620072 -213.12251)
		(width 0.0889)
		(layer "In15.Cu")
		(net "P5E_CPU1_PE0_TX_DN<11>")
	)
	(segment
		(start 98.76409 -215.7603)
		(end 98.756724 -215.755982)
		(width 0.0889)
		(layer "In15.Cu")
		(net "P5E_CPU1_PE0_TX_DN<11>")
	)
	(segment
		(start 96.83496 -209.634582)
		(end 94.540578 -208.684368)
		(width 0.14732)
		(layer "In15.Cu")
		(net "P5E_CPU1_PE0_TX_DN<11>")
	)
	(segment
		(start 74.85761 -218.976956)
		(end 73.66254 -221.28099)
		(width 0.14732)
		(layer "In15.Cu")
		(net "P5E_CPU1_PE0_TX_DN<11>")
	)
	(segment
		(start 70.38213 -253.321566)
		(end 70.381876 -253.321566)
		(width 0.14732)
		(layer "In15.Cu")
		(net "P5E_CPU1_PE0_TX_DN<11>")
	)
	(segment
		(start 99.235768 -216.574878)
		(end 99.226878 -216.569798)
		(width 0.0889)
		(layer "In15.Cu")
		(net "P5E_CPU1_PE0_TX_DN<11>")
	)
	(segment
		(start 98.620072 -213.12251)
		(end 98.620072 -212.22589)
		(width 0.14732)
		(layer "In15.Cu")
		(net "P5E_CPU1_PE0_TX_DN<11>")
	)
	(segment
		(start 70.491096 -250.085352)
		(end 70.38213 -253.321566)
		(width 0.14732)
		(layer "In15.Cu")
		(net "P5E_CPU1_PE0_TX_DN<11>")
	)
	(segment
		(start 98.578162 -213.8934)
		(end 98.578162 -213.186518)
		(width 0.0889)
		(layer "In15.Cu")
		(net "P5E_CPU1_PE0_TX_DN<11>")
	)
	(segment
		(start 60.527438 -400.563588)
		(end 60.232798 -400.858228)
		(width 0.14732)
		(layer "In15.Cu")
		(net "P5E_CPU1_PE0_TX_DN<11>")
	)
	(segment
		(start 70.381622 -253.334774)
		(end 73.94702 -309.014114)
		(width 0.14732)
		(layer "In15.Cu")
		(net "P5E_CPU1_PE0_TX_DN<11>")
	)
	(segment
		(start 94.540578 -208.684368)
		(end 86.2076 -208.684368)
		(width 0.14732)
		(layer "In15.Cu")
		(net "P5E_CPU1_PE0_TX_DN<11>")
	)
	(segment
		(start 100.175568 -224.7138)
		(end 100.166678 -224.70872)
		(width 0.0889)
		(layer "In15.Cu")
		(net "P5E_CPU1_PE0_TX_DN<11>")
	)
	(segment
		(start 100.51923 -224.66046)
		(end 100.498148 -224.738438)
		(width 0.0889)
		(layer "In15.Cu")
		(net "P5E_CPU1_PE0_TX_DN<11>")
	)
	(segment
		(start 73.94702 -309.014114)
		(end 69.630036 -319.411604)
		(width 0.14732)
		(layer "In15.Cu")
		(net "P5E_CPU1_PE0_TX_DN<11>")
	)
	(segment
		(start 99.705414 -222.272098)
		(end 99.696524 -222.267018)
		(width 0.0889)
		(layer "In15.Cu")
		(net "P5E_CPU1_PE0_TX_DN<11>")
	)
	(segment
		(start 76.053188 -216.67216)
		(end 74.857864 -218.976956)
		(width 0.14732)
		(layer "In15.Cu")
		(net "P5E_CPU1_PE0_TX_DN<11>")
	)
	(segment
		(start 98.756724 -215.117426)
		(end 98.765614 -215.112346)
		(width 0.0889)
		(layer "In15.Cu")
		(net "P5E_CPU1_PE0_TX_DN<11>")
	)
	(segment
		(start 60.527438 -399.81886)
		(end 60.527438 -400.563588)
		(width 0.14732)
		(layer "In15.Cu")
		(net "P5E_CPU1_PE0_TX_DN<11>")
	)
	(segment
		(start 99.235768 -219.830396)
		(end 99.226878 -219.825316)
		(width 0.0889)
		(layer "In15.Cu")
		(net "P5E_CPU1_PE0_TX_DN<11>")
	)
	(segment
		(start 99.235768 -221.458282)
		(end 99.226878 -221.453202)
		(width 0.0889)
		(layer "In15.Cu")
		(net "P5E_CPU1_PE0_TX_DN<11>")
	)
	(arc
		(start 98.756724 -215.755982)
		(mid 98.62581 -215.619622)
		(end 98.578162 -215.436704)
		(width 0.0889)
		(layer "In15.Cu")
		(net "P5E_CPU1_PE0_TX_DN<11>")
	)
	(arc
		(start 99.226878 -221.453202)
		(mid 99.098559 -221.32123)
		(end 99.04857 -221.144084)
		(width 0.0889)
		(layer "In15.Cu")
		(net "P5E_CPU1_PE0_TX_DN<11>")
	)
	(arc
		(start 99.696524 -222.267018)
		(mid 99.56561 -222.130658)
		(end 99.517962 -221.94774)
		(width 0.0889)
		(layer "In15.Cu")
		(net "P5E_CPU1_PE0_TX_DN<11>")
	)
	(arc
		(start 99.226878 -218.197684)
		(mid 99.098559 -218.065712)
		(end 99.04857 -217.888566)
		(width 0.0889)
		(layer "In15.Cu")
		(net "P5E_CPU1_PE0_TX_DN<11>")
	)
	(arc
		(start 99.235768 -217.554048)
		(mid 99.438054 -217.355067)
		(end 99.518216 -217.082878)
		(width 0.0889)
		(layer "In15.Cu")
		(net "P5E_CPU1_PE0_TX_DN<11>")
	)
	(arc
		(start 99.04857 -219.495878)
		(mid 99.098585 -219.318747)
		(end 99.226878 -219.18676)
		(width 0.0889)
		(layer "In15.Cu")
		(net "P5E_CPU1_PE0_TX_DN<11>")
	)
	(arc
		(start 99.04857 -219.512642)
		(mid 99.048476 -219.50426)
		(end 99.04857 -219.495878)
		(width 0.0889)
		(layer "In15.Cu")
		(net "P5E_CPU1_PE0_TX_DN<11>")
	)
	(arc
		(start 99.235768 -219.18168)
		(mid 99.438591 -218.981449)
		(end 99.517962 -218.707716)
		(width 0.0889)
		(layer "In15.Cu")
		(net "P5E_CPU1_PE0_TX_DN<11>")
	)
	(arc
		(start 99.518216 -217.05443)
		(mid 99.440105 -216.777481)
		(end 99.235768 -216.574878)
		(width 0.0889)
		(layer "In15.Cu")
		(net "P5E_CPU1_PE0_TX_DN<11>")
	)
	(arc
		(start 98.578162 -215.436704)
		(mid 98.578214 -215.429337)
		(end 98.578416 -215.421972)
		(width 0.0889)
		(layer "In15.Cu")
		(net "P5E_CPU1_PE0_TX_DN<11>")
	)
	(arc
		(start 99.518216 -220.309948)
		(mid 99.440105 -220.032999)
		(end 99.235768 -219.830396)
		(width 0.0889)
		(layer "In15.Cu")
		(net "P5E_CPU1_PE0_TX_DN<11>")
	)
	(arc
		(start 99.048316 -216.25052)
		(mid 98.974325 -215.970954)
		(end 98.77171 -215.764618)
		(width 0.0889)
		(layer "In15.Cu")
		(net "P5E_CPU1_PE0_TX_DN<11>")
	)
	(arc
		(start 99.988624 -222.776288)
		(mid 99.988291 -222.763844)
		(end 99.98837 -222.751396)
		(width 0.0889)
		(layer "In15.Cu")
		(net "P5E_CPU1_PE0_TX_DN<11>")
	)
	(arc
		(start 99.047808 -214.424768)
		(mid 98.936529 -214.232062)
		(end 98.762566 -214.093298)
		(width 0.0889)
		(layer "In15.Cu")
		(net "P5E_CPU1_PE0_TX_DN<11>")
	)
	(arc
		(start 100.166678 -223.080834)
		(mid 100.039598 -222.95082)
		(end 99.988624 -222.776288)
		(width 0.0889)
		(layer "In15.Cu")
		(net "P5E_CPU1_PE0_TX_DN<11>")
	)
	(arc
		(start 100.166678 -224.70872)
		(mid 99.988202 -224.389442)
		(end 100.166678 -224.070164)
		(width 0.0889)
		(layer "In15.Cu")
		(net "P5E_CPU1_PE0_TX_DN<11>")
	)
	(arc
		(start 99.988116 -222.761556)
		(mid 99.914125 -222.48199)
		(end 99.71151 -222.275654)
		(width 0.0889)
		(layer "In15.Cu")
		(net "P5E_CPU1_PE0_TX_DN<11>")
	)
	(arc
		(start 100.498148 -224.738438)
		(mid 100.334052 -224.762785)
		(end 100.175568 -224.7138)
		(width 0.0889)
		(layer "In15.Cu")
		(net "P5E_CPU1_PE0_TX_DN<11>")
	)
	(arc
		(start 100.458016 -223.561402)
		(mid 100.378875 -223.286779)
		(end 100.175568 -223.085914)
		(width 0.0889)
		(layer "In15.Cu")
		(net "P5E_CPU1_PE0_TX_DN<11>")
	)
	(arc
		(start 100.181664 -224.061528)
		(mid 100.384077 -223.855115)
		(end 100.458016 -223.575626)
		(width 0.0889)
		(layer "In15.Cu")
		(net "P5E_CPU1_PE0_TX_DN<11>")
	)
	(arc
		(start 99.226878 -216.569798)
		(mid 99.095964 -216.433438)
		(end 99.048316 -216.25052)
		(width 0.0889)
		(layer "In15.Cu")
		(net "P5E_CPU1_PE0_TX_DN<11>")
	)
	(arc
		(start 99.235768 -220.809566)
		(mid 99.438054 -220.610585)
		(end 99.518216 -220.338396)
		(width 0.0889)
		(layer "In15.Cu")
		(net "P5E_CPU1_PE0_TX_DN<11>")
	)
	(arc
		(start 99.517962 -218.676728)
		(mid 99.438592 -218.402994)
		(end 99.235768 -218.202764)
		(width 0.0889)
		(layer "In15.Cu")
		(net "P5E_CPU1_PE0_TX_DN<11>")
	)
	(arc
		(start 99.04857 -217.866214)
		(mid 99.099063 -217.690236)
		(end 99.226878 -217.559128)
		(width 0.0889)
		(layer "In15.Cu")
		(net "P5E_CPU1_PE0_TX_DN<11>")
	)
	(arc
		(start 98.765614 -215.112346)
		(mid 98.966896 -214.914859)
		(end 99.047808 -214.644732)
		(width 0.0889)
		(layer "In15.Cu")
		(net "P5E_CPU1_PE0_TX_DN<11>")
	)
	(arc
		(start 99.226878 -219.825316)
		(mid 99.097766 -219.691781)
		(end 99.04857 -219.512642)
		(width 0.0889)
		(layer "In15.Cu")
		(net "P5E_CPU1_PE0_TX_DN<11>")
	)
	(arc
		(start 98.578416 -215.421972)
		(mid 98.62947 -215.247392)
		(end 98.756724 -215.117426)
		(width 0.0889)
		(layer "In15.Cu")
		(net "P5E_CPU1_PE0_TX_DN<11>")
	)
	(arc
		(start 98.762566 -214.093298)
		(mid 98.653419 -214.00937)
		(end 98.578416 -213.893908)
		(width 0.0889)
		(layer "In15.Cu")
		(net "P5E_CPU1_PE0_TX_DN<11>")
	)
	(arc
		(start 99.04857 -221.121732)
		(mid 99.099063 -220.945754)
		(end 99.226878 -220.814646)
		(width 0.0889)
		(layer "In15.Cu")
		(net "P5E_CPU1_PE0_TX_DN<11>")
	)
	(arc
		(start 99.517962 -221.932246)
		(mid 99.438592 -221.658512)
		(end 99.235768 -221.458282)
		(width 0.0889)
		(layer "In15.Cu")
		(net "P5E_CPU1_PE0_TX_DN<11>")
	)
	(arc
		(start 99.04857 -221.144084)
		(mid 99.048403 -221.132908)
		(end 99.04857 -221.121732)
		(width 0.0889)
		(layer "In15.Cu")
		(net "P5E_CPU1_PE0_TX_DN<11>")
	)
	(arc
		(start 99.04857 -217.888566)
		(mid 99.048403 -217.87739)
		(end 99.04857 -217.866214)
		(width 0.0889)
		(layer "In15.Cu")
		(net "P5E_CPU1_PE0_TX_DN<11>")
	)
	(segment
		(start 99.892866 -224.111566)
		(end 99.892866 -223.57588)
		(width 0.13208)
		(layer "F.Cu")
		(net "P5E_CPU1_PE0_TX_DN<10>")
	)
	(segment
		(start 63.6016 -401.777962)
		(end 63.6016 -401.16379)
		(width 0.13208)
		(layer "F.Cu")
		(net "P5E_CPU1_PE0_TX_DN<10>")
	)
	(segment
		(start 63.270638 -402.104352)
		(end 63.27521 -402.104352)
		(width 0.13208)
		(layer "F.Cu")
		(net "P5E_CPU1_PE0_TX_DN<10>")
	)
	(segment
		(start 63.27521 -402.104352)
		(end 63.6016 -401.777962)
		(width 0.13208)
		(layer "F.Cu")
		(net "P5E_CPU1_PE0_TX_DN<10>")
	)
	(segment
		(start 99.892866 -223.57588)
		(end 99.892612 -223.575626)
		(width 0.13208)
		(layer "F.Cu")
		(net "P5E_CPU1_PE0_TX_DN<10>")
	)
	(segment
		(start 63.6016 -401.16379)
		(end 63.296038 -400.858228)
		(width 0.13208)
		(layer "F.Cu")
		(net "P5E_CPU1_PE0_TX_DN<10>")
	)
	(segment
		(start 98.295968 -218.202764)
		(end 98.287078 -218.197684)
		(width 0.0889)
		(layer "In15.Cu")
		(net "P5E_CPU1_PE0_TX_DN<10>")
	)
	(segment
		(start 82.669126 -211.729574)
		(end 76.8223 -217.273886)
		(width 0.14732)
		(layer "In15.Cu")
		(net "P5E_CPU1_PE0_TX_DN<10>")
	)
	(segment
		(start 98.768408 -222.273622)
		(end 98.765614 -222.272098)
		(width 0.0889)
		(layer "In15.Cu")
		(net "P5E_CPU1_PE0_TX_DN<10>")
	)
	(segment
		(start 98.287078 -219.18676)
		(end 98.294952 -219.182188)
		(width 0.0889)
		(layer "In15.Cu")
		(net "P5E_CPU1_PE0_TX_DN<10>")
	)
	(segment
		(start 97.680526 -213.12251)
		(end 97.680526 -212.510624)
		(width 0.14732)
		(layer "In15.Cu")
		(net "P5E_CPU1_PE0_TX_DN<10>")
	)
	(segment
		(start 74.933302 -309.368444)
		(end 70.769734 -319.366138)
		(width 0.14732)
		(layer "In15.Cu")
		(net "P5E_CPU1_PE0_TX_DN<10>")
	)
	(segment
		(start 72.845168 -232.821734)
		(end 72.843898 -232.831386)
		(width 0.14732)
		(layer "In15.Cu")
		(net "P5E_CPU1_PE0_TX_DN<10>")
	)
	(segment
		(start 99.235768 -223.085914)
		(end 99.226878 -223.080834)
		(width 0.0889)
		(layer "In15.Cu")
		(net "P5E_CPU1_PE0_TX_DN<10>")
	)
	(segment
		(start 71.425054 -250.12904)
		(end 71.383398 -251.367544)
		(width 0.14732)
		(layer "In15.Cu")
		(net "P5E_CPU1_PE0_TX_DN<10>")
	)
	(segment
		(start 72.845422 -232.821734)
		(end 72.845168 -232.821734)
		(width 0.14732)
		(layer "In15.Cu")
		(net "P5E_CPU1_PE0_TX_DN<10>")
	)
	(segment
		(start 63.730124 -348.362524)
		(end 64.01181 -351.533714)
		(width 0.14732)
		(layer "In15.Cu")
		(net "P5E_CPU1_PE0_TX_DN<10>")
	)
	(segment
		(start 98.108008 -214.644732)
		(end 98.108008 -214.424768)
		(width 0.0889)
		(layer "In15.Cu")
		(net "P5E_CPU1_PE0_TX_DN<10>")
	)
	(segment
		(start 98.287078 -220.814646)
		(end 98.295968 -220.809566)
		(width 0.0889)
		(layer "In15.Cu")
		(net "P5E_CPU1_PE0_TX_DN<10>")
	)
	(segment
		(start 71.383398 -251.367544)
		(end 71.341488 -252.613414)
		(width 0.14732)
		(layer "In15.Cu")
		(net "P5E_CPU1_PE0_TX_DN<10>")
	)
	(segment
		(start 63.246254 -335.303876)
		(end 63.246254 -337.91525)
		(width 0.14732)
		(layer "In15.Cu")
		(net "P5E_CPU1_PE0_TX_DN<10>")
	)
	(segment
		(start 86.469474 -209.671158)
		(end 82.669126 -211.729574)
		(width 0.14732)
		(layer "In15.Cu")
		(net "P5E_CPU1_PE0_TX_DN<10>")
	)
	(segment
		(start 98.287078 -217.559128)
		(end 98.295968 -217.554048)
		(width 0.0889)
		(layer "In15.Cu")
		(net "P5E_CPU1_PE0_TX_DN<10>")
	)
	(segment
		(start 99.736148 -223.846644)
		(end 99.65817 -223.867472)
		(width 0.0889)
		(layer "In15.Cu")
		(net "P5E_CPU1_PE0_TX_DN<10>")
	)
	(segment
		(start 63.590932 -399.943066)
		(end 63.590932 -400.563334)
		(width 0.14732)
		(layer "In15.Cu")
		(net "P5E_CPU1_PE0_TX_DN<10>")
	)
	(segment
		(start 98.578162 -218.707716)
		(end 98.578162 -218.676728)
		(width 0.0889)
		(layer "In15.Cu")
		(net "P5E_CPU1_PE0_TX_DN<10>")
	)
	(segment
		(start 97.820226 -215.75776)
		(end 97.818194 -215.756744)
		(width 0.0889)
		(layer "In15.Cu")
		(net "P5E_CPU1_PE0_TX_DN<10>")
	)
	(segment
		(start 70.769734 -319.366138)
		(end 66.88709 -325.492618)
		(width 0.14732)
		(layer "In15.Cu")
		(net "P5E_CPU1_PE0_TX_DN<10>")
	)
	(segment
		(start 97.821496 -215.758522)
		(end 97.820226 -215.75776)
		(width 0.0889)
		(layer "In15.Cu")
		(net "P5E_CPU1_PE0_TX_DN<10>")
	)
	(segment
		(start 98.578416 -220.334078)
		(end 98.578416 -220.319854)
		(width 0.0889)
		(layer "In15.Cu")
		(net "P5E_CPU1_PE0_TX_DN<10>")
	)
	(segment
		(start 63.590932 -400.563334)
		(end 63.296038 -400.858228)
		(width 0.14732)
		(layer "In15.Cu")
		(net "P5E_CPU1_PE0_TX_DN<10>")
	)
	(segment
		(start 94.187518 -209.671158)
		(end 86.469474 -209.671158)
		(width 0.14732)
		(layer "In15.Cu")
		(net "P5E_CPU1_PE0_TX_DN<10>")
	)
	(segment
		(start 97.818194 -215.756744)
		(end 97.816924 -215.755982)
		(width 0.0889)
		(layer "In15.Cu")
		(net "P5E_CPU1_PE0_TX_DN<10>")
	)
	(segment
		(start 66.88582 -325.484236)
		(end 63.733426 -333.095092)
		(width 0.14732)
		(layer "In15.Cu")
		(net "P5E_CPU1_PE0_TX_DN<10>")
	)
	(segment
		(start 96.353376 -210.568286)
		(end 94.187518 -209.671158)
		(width 0.14732)
		(layer "In15.Cu")
		(net "P5E_CPU1_PE0_TX_DN<10>")
	)
	(segment
		(start 63.733426 -333.095092)
		(end 63.246254 -335.303876)
		(width 0.14732)
		(layer "In15.Cu")
		(net "P5E_CPU1_PE0_TX_DN<10>")
	)
	(segment
		(start 98.294952 -219.182188)
		(end 98.295968 -219.18168)
		(width 0.0889)
		(layer "In15.Cu")
		(net "P5E_CPU1_PE0_TX_DN<10>")
	)
	(segment
		(start 66.886836 -325.492618)
		(end 66.88582 -325.484236)
		(width 0.14732)
		(layer "In15.Cu")
		(net "P5E_CPU1_PE0_TX_DN<10>")
	)
	(segment
		(start 97.245424 -211.460334)
		(end 96.353376 -210.568286)
		(width 0.14732)
		(layer "In15.Cu")
		(net "P5E_CPU1_PE0_TX_DN<10>")
	)
	(segment
		(start 66.88709 -325.492618)
		(end 66.886836 -325.492618)
		(width 0.14732)
		(layer "In15.Cu")
		(net "P5E_CPU1_PE0_TX_DN<10>")
	)
	(segment
		(start 71.341488 -252.613414)
		(end 74.933302 -309.368444)
		(width 0.14732)
		(layer "In15.Cu")
		(net "P5E_CPU1_PE0_TX_DN<10>")
	)
	(segment
		(start 97.824798 -215.112854)
		(end 97.825814 -215.112346)
		(width 0.0889)
		(layer "In15.Cu")
		(net "P5E_CPU1_PE0_TX_DN<10>")
	)
	(segment
		(start 97.83191 -215.764618)
		(end 97.828608 -215.762586)
		(width 0.0889)
		(layer "In15.Cu")
		(net "P5E_CPU1_PE0_TX_DN<10>")
	)
	(segment
		(start 98.77171 -222.275654)
		(end 98.768408 -222.273622)
		(width 0.0889)
		(layer "In15.Cu")
		(net "P5E_CPU1_PE0_TX_DN<10>")
	)
	(segment
		(start 98.765614 -222.272098)
		(end 98.76409 -222.271336)
		(width 0.0889)
		(layer "In15.Cu")
		(net "P5E_CPU1_PE0_TX_DN<10>")
	)
	(segment
		(start 64.01181 -351.533714)
		(end 63.590932 -399.943066)
		(width 0.14732)
		(layer "In15.Cu")
		(net "P5E_CPU1_PE0_TX_DN<10>")
	)
	(segment
		(start 97.816924 -215.117426)
		(end 97.824798 -215.112854)
		(width 0.0889)
		(layer "In15.Cu")
		(net "P5E_CPU1_PE0_TX_DN<10>")
	)
	(segment
		(start 97.828608 -215.762586)
		(end 97.825814 -215.761062)
		(width 0.0889)
		(layer "In15.Cu")
		(net "P5E_CPU1_PE0_TX_DN<10>")
	)
	(segment
		(start 97.638616 -213.186518)
		(end 97.680526 -213.144608)
		(width 0.0889)
		(layer "In15.Cu")
		(net "P5E_CPU1_PE0_TX_DN<10>")
	)
	(segment
		(start 98.302064 -219.833952)
		(end 98.295968 -219.830396)
		(width 0.0889)
		(layer "In15.Cu")
		(net "P5E_CPU1_PE0_TX_DN<10>")
	)
	(segment
		(start 75.703176 -219.44584)
		(end 74.585068 -221.615508)
		(width 0.14732)
		(layer "In15.Cu")
		(net "P5E_CPU1_PE0_TX_DN<10>")
	)
	(segment
		(start 97.822512 -215.75903)
		(end 97.821496 -215.758522)
		(width 0.0889)
		(layer "In15.Cu")
		(net "P5E_CPU1_PE0_TX_DN<10>")
	)
	(segment
		(start 72.134222 -241.481864)
		(end 71.425054 -250.12904)
		(width 0.14732)
		(layer "In15.Cu")
		(net "P5E_CPU1_PE0_TX_DN<10>")
	)
	(segment
		(start 99.04857 -222.751396)
		(end 99.048316 -222.761556)
		(width 0.0889)
		(layer "In15.Cu")
		(net "P5E_CPU1_PE0_TX_DN<10>")
	)
	(segment
		(start 97.680526 -212.510624)
		(end 97.245424 -211.460334)
		(width 0.14732)
		(layer "In15.Cu")
		(net "P5E_CPU1_PE0_TX_DN<10>")
	)
	(segment
		(start 98.578162 -221.94774)
		(end 98.578162 -221.932246)
		(width 0.0889)
		(layer "In15.Cu")
		(net "P5E_CPU1_PE0_TX_DN<10>")
	)
	(segment
		(start 98.295968 -219.830396)
		(end 98.287078 -219.825316)
		(width 0.0889)
		(layer "In15.Cu")
		(net "P5E_CPU1_PE0_TX_DN<10>")
	)
	(segment
		(start 99.892612 -223.575626)
		(end 99.736148 -223.846644)
		(width 0.0889)
		(layer "In15.Cu")
		(net "P5E_CPU1_PE0_TX_DN<10>")
	)
	(segment
		(start 98.578416 -217.07856)
		(end 98.578416 -217.064336)
		(width 0.0889)
		(layer "In15.Cu")
		(net "P5E_CPU1_PE0_TX_DN<10>")
	)
	(segment
		(start 97.638616 -213.893908)
		(end 97.638616 -213.186518)
		(width 0.0889)
		(layer "In15.Cu")
		(net "P5E_CPU1_PE0_TX_DN<10>")
	)
	(segment
		(start 97.825052 -215.760554)
		(end 97.822512 -215.75903)
		(width 0.0889)
		(layer "In15.Cu")
		(net "P5E_CPU1_PE0_TX_DN<10>")
	)
	(segment
		(start 97.680526 -213.144608)
		(end 97.680526 -213.12251)
		(width 0.0889)
		(layer "In15.Cu")
		(net "P5E_CPU1_PE0_TX_DN<10>")
	)
	(segment
		(start 97.825814 -215.761062)
		(end 97.825052 -215.760554)
		(width 0.0889)
		(layer "In15.Cu")
		(net "P5E_CPU1_PE0_TX_DN<10>")
	)
	(segment
		(start 72.843898 -232.831386)
		(end 72.134222 -241.481864)
		(width 0.14732)
		(layer "In15.Cu")
		(net "P5E_CPU1_PE0_TX_DN<10>")
	)
	(segment
		(start 98.302064 -216.578434)
		(end 98.295968 -216.574878)
		(width 0.0889)
		(layer "In15.Cu")
		(net "P5E_CPU1_PE0_TX_DN<10>")
	)
	(segment
		(start 98.76409 -222.271336)
		(end 98.756724 -222.267018)
		(width 0.0889)
		(layer "In15.Cu")
		(net "P5E_CPU1_PE0_TX_DN<10>")
	)
	(segment
		(start 75.703176 -219.445586)
		(end 75.703176 -219.44584)
		(width 0.14732)
		(layer "In15.Cu")
		(net "P5E_CPU1_PE0_TX_DN<10>")
	)
	(segment
		(start 76.8223 -217.273886)
		(end 75.703176 -219.445586)
		(width 0.14732)
		(layer "In15.Cu")
		(net "P5E_CPU1_PE0_TX_DN<10>")
	)
	(segment
		(start 99.518216 -223.584262)
		(end 99.518216 -223.557084)
		(width 0.0889)
		(layer "In15.Cu")
		(net "P5E_CPU1_PE0_TX_DN<10>")
	)
	(segment
		(start 63.246254 -337.91525)
		(end 63.730124 -348.362524)
		(width 0.14732)
		(layer "In15.Cu")
		(net "P5E_CPU1_PE0_TX_DN<10>")
	)
	(segment
		(start 74.585068 -221.615508)
		(end 72.845422 -232.821734)
		(width 0.14732)
		(layer "In15.Cu")
		(net "P5E_CPU1_PE0_TX_DN<10>")
	)
	(segment
		(start 98.295968 -221.458282)
		(end 98.287078 -221.453202)
		(width 0.0889)
		(layer "In15.Cu")
		(net "P5E_CPU1_PE0_TX_DN<10>")
	)
	(segment
		(start 98.295968 -216.574878)
		(end 98.287078 -216.569798)
		(width 0.0889)
		(layer "In15.Cu")
		(net "P5E_CPU1_PE0_TX_DN<10>")
	)
	(arc
		(start 98.295968 -217.554048)
		(mid 98.499273 -217.353182)
		(end 98.578416 -217.07856)
		(width 0.0889)
		(layer "In15.Cu")
		(net "P5E_CPU1_PE0_TX_DN<10>")
	)
	(arc
		(start 98.578162 -221.932246)
		(mid 98.498792 -221.658512)
		(end 98.295968 -221.458282)
		(width 0.0889)
		(layer "In15.Cu")
		(net "P5E_CPU1_PE0_TX_DN<10>")
	)
	(arc
		(start 98.756724 -222.267018)
		(mid 98.62581 -222.130658)
		(end 98.578162 -221.94774)
		(width 0.0889)
		(layer "In15.Cu")
		(net "P5E_CPU1_PE0_TX_DN<10>")
	)
	(arc
		(start 97.816924 -215.755982)
		(mid 97.68601 -215.619622)
		(end 97.638362 -215.436704)
		(width 0.0889)
		(layer "In15.Cu")
		(net "P5E_CPU1_PE0_TX_DN<10>")
	)
	(arc
		(start 99.65817 -223.867472)
		(mid 99.556849 -223.741351)
		(end 99.518216 -223.584262)
		(width 0.0889)
		(layer "In15.Cu")
		(net "P5E_CPU1_PE0_TX_DN<10>")
	)
	(arc
		(start 99.518216 -223.557084)
		(mid 99.438054 -223.284895)
		(end 99.235768 -223.085914)
		(width 0.0889)
		(layer "In15.Cu")
		(net "P5E_CPU1_PE0_TX_DN<10>")
	)
	(arc
		(start 99.048316 -222.761556)
		(mid 98.974325 -222.48199)
		(end 98.77171 -222.275654)
		(width 0.0889)
		(layer "In15.Cu")
		(net "P5E_CPU1_PE0_TX_DN<10>")
	)
	(arc
		(start 98.578416 -220.319854)
		(mid 98.5045 -220.040352)
		(end 98.302064 -219.833952)
		(width 0.0889)
		(layer "In15.Cu")
		(net "P5E_CPU1_PE0_TX_DN<10>")
	)
	(arc
		(start 97.638616 -215.421972)
		(mid 97.68967 -215.247392)
		(end 97.816924 -215.117426)
		(width 0.0889)
		(layer "In15.Cu")
		(net "P5E_CPU1_PE0_TX_DN<10>")
	)
	(arc
		(start 98.287078 -219.825316)
		(mid 98.108602 -219.506038)
		(end 98.287078 -219.18676)
		(width 0.0889)
		(layer "In15.Cu")
		(net "P5E_CPU1_PE0_TX_DN<10>")
	)
	(arc
		(start 97.638362 -215.436704)
		(mid 97.638414 -215.429337)
		(end 97.638616 -215.421972)
		(width 0.0889)
		(layer "In15.Cu")
		(net "P5E_CPU1_PE0_TX_DN<10>")
	)
	(arc
		(start 98.295968 -220.809566)
		(mid 98.499273 -220.6087)
		(end 98.578416 -220.334078)
		(width 0.0889)
		(layer "In15.Cu")
		(net "P5E_CPU1_PE0_TX_DN<10>")
	)
	(arc
		(start 98.10877 -217.863674)
		(mid 98.159824 -217.689094)
		(end 98.287078 -217.559128)
		(width 0.0889)
		(layer "In15.Cu")
		(net "P5E_CPU1_PE0_TX_DN<10>")
	)
	(arc
		(start 98.578162 -218.676728)
		(mid 98.498792 -218.402994)
		(end 98.295968 -218.202764)
		(width 0.0889)
		(layer "In15.Cu")
		(net "P5E_CPU1_PE0_TX_DN<10>")
	)
	(arc
		(start 98.578416 -217.064336)
		(mid 98.5045 -216.784834)
		(end 98.302064 -216.578434)
		(width 0.0889)
		(layer "In15.Cu")
		(net "P5E_CPU1_PE0_TX_DN<10>")
	)
	(arc
		(start 98.295968 -219.18168)
		(mid 98.498791 -218.981449)
		(end 98.578162 -218.707716)
		(width 0.0889)
		(layer "In15.Cu")
		(net "P5E_CPU1_PE0_TX_DN<10>")
	)
	(arc
		(start 97.825814 -215.112346)
		(mid 98.027096 -214.914859)
		(end 98.108008 -214.644732)
		(width 0.0889)
		(layer "In15.Cu")
		(net "P5E_CPU1_PE0_TX_DN<10>")
	)
	(arc
		(start 98.287078 -216.569798)
		(mid 98.156164 -216.433438)
		(end 98.108516 -216.25052)
		(width 0.0889)
		(layer "In15.Cu")
		(net "P5E_CPU1_PE0_TX_DN<10>")
	)
	(arc
		(start 97.822766 -214.093298)
		(mid 97.713619 -214.00937)
		(end 97.638616 -213.893908)
		(width 0.0889)
		(layer "In15.Cu")
		(net "P5E_CPU1_PE0_TX_DN<10>")
	)
	(arc
		(start 98.108516 -217.888566)
		(mid 98.108436 -217.876118)
		(end 98.10877 -217.863674)
		(width 0.0889)
		(layer "In15.Cu")
		(net "P5E_CPU1_PE0_TX_DN<10>")
	)
	(arc
		(start 98.108008 -214.424768)
		(mid 97.996729 -214.232062)
		(end 97.822766 -214.093298)
		(width 0.0889)
		(layer "In15.Cu")
		(net "P5E_CPU1_PE0_TX_DN<10>")
	)
	(arc
		(start 98.287078 -221.453202)
		(mid 98.158674 -221.321257)
		(end 98.108516 -221.144084)
		(width 0.0889)
		(layer "In15.Cu")
		(net "P5E_CPU1_PE0_TX_DN<10>")
	)
	(arc
		(start 98.108516 -216.25052)
		(mid 98.034525 -215.970954)
		(end 97.83191 -215.764618)
		(width 0.0889)
		(layer "In15.Cu")
		(net "P5E_CPU1_PE0_TX_DN<10>")
	)
	(arc
		(start 98.108516 -221.144084)
		(mid 98.108436 -221.131636)
		(end 98.10877 -221.119192)
		(width 0.0889)
		(layer "In15.Cu")
		(net "P5E_CPU1_PE0_TX_DN<10>")
	)
	(arc
		(start 98.287078 -218.197684)
		(mid 98.158674 -218.065739)
		(end 98.108516 -217.888566)
		(width 0.0889)
		(layer "In15.Cu")
		(net "P5E_CPU1_PE0_TX_DN<10>")
	)
	(arc
		(start 99.226878 -223.080834)
		(mid 99.098985 -222.949772)
		(end 99.04857 -222.773748)
		(width 0.0889)
		(layer "In15.Cu")
		(net "P5E_CPU1_PE0_TX_DN<10>")
	)
	(arc
		(start 98.10877 -221.119192)
		(mid 98.159824 -220.944612)
		(end 98.287078 -220.814646)
		(width 0.0889)
		(layer "In15.Cu")
		(net "P5E_CPU1_PE0_TX_DN<10>")
	)
	(arc
		(start 99.04857 -222.773748)
		(mid 99.048403 -222.762572)
		(end 99.04857 -222.751396)
		(width 0.0889)
		(layer "In15.Cu")
		(net "P5E_CPU1_PE0_TX_DN<10>")
	)
	(segment
		(start 93.903038 -402.104352)
		(end 93.90761 -402.104352)
		(width 0.13208)
		(layer "F.Cu")
		(net "P5E_CPU1_PE0_TX_DN<0>")
	)
	(segment
		(start 94.234 -401.16379)
		(end 93.928438 -400.858228)
		(width 0.13208)
		(layer "F.Cu")
		(net "P5E_CPU1_PE0_TX_DN<0>")
	)
	(segment
		(start 94.234 -401.777962)
		(end 94.234 -401.16379)
		(width 0.13208)
		(layer "F.Cu")
		(net "P5E_CPU1_PE0_TX_DN<0>")
	)
	(segment
		(start 90.494866 -223.57588)
		(end 90.494612 -223.575626)
		(width 0.13208)
		(layer "F.Cu")
		(net "P5E_CPU1_PE0_TX_DN<0>")
	)
	(segment
		(start 90.494866 -224.111566)
		(end 90.494866 -223.57588)
		(width 0.13208)
		(layer "F.Cu")
		(net "P5E_CPU1_PE0_TX_DN<0>")
	)
	(segment
		(start 93.90761 -402.104352)
		(end 94.234 -401.777962)
		(width 0.13208)
		(layer "F.Cu")
		(net "P5E_CPU1_PE0_TX_DN<0>")
	)
	(segment
		(start 88.332564 -226.341686)
		(end 88.326468 -226.345242)
		(width 0.0889)
		(layer "In15.Cu")
		(net "P5E_CPU1_PE0_TX_DN<0>")
	)
	(segment
		(start 85.05952 -252.75667)
		(end 85.05952 -254.374904)
		(width 0.14732)
		(layer "In15.Cu")
		(net "P5E_CPU1_PE0_TX_DN<0>")
	)
	(segment
		(start 75.934824 -329.719178)
		(end 73.313798 -336.046826)
		(width 0.14732)
		(layer "In15.Cu")
		(net "P5E_CPU1_PE0_TX_DN<0>")
	)
	(segment
		(start 90.249248 -223.87052)
		(end 90.248994 -223.870774)
		(width 0.0889)
		(layer "In15.Cu")
		(net "P5E_CPU1_PE0_TX_DN<0>")
	)
	(segment
		(start 84.248244 -256.638044)
		(end 82.89417 -260.093968)
		(width 0.14732)
		(layer "In15.Cu")
		(net "P5E_CPU1_PE0_TX_DN<0>")
	)
	(segment
		(start 89.272364 -224.7138)
		(end 89.266268 -224.717356)
		(width 0.0889)
		(layer "In15.Cu")
		(net "P5E_CPU1_PE0_TX_DN<0>")
	)
	(segment
		(start 85.175598 -255.477518)
		(end 85.010498 -255.875536)
		(width 0.14732)
		(layer "In15.Cu")
		(net "P5E_CPU1_PE0_TX_DN<0>")
	)
	(segment
		(start 88.520016 -225.998786)
		(end 88.520016 -226.017328)
		(width 0.0889)
		(layer "In15.Cu")
		(net "P5E_CPU1_PE0_TX_DN<0>")
	)
	(segment
		(start 85.230462 -255.344676)
		(end 85.175598 -255.477264)
		(width 0.14732)
		(layer "In15.Cu")
		(net "P5E_CPU1_PE0_TX_DN<0>")
	)
	(segment
		(start 85.832188 -250.074176)
		(end 85.832188 -250.834652)
		(width 0.14732)
		(layer "In15.Cu")
		(net "P5E_CPU1_PE0_TX_DN<0>")
	)
	(segment
		(start 84.662772 -311.107328)
		(end 78.189074 -326.47382)
		(width 0.14732)
		(layer "In15.Cu")
		(net "P5E_CPU1_PE0_TX_DN<0>")
	)
	(segment
		(start 74.149712 -351.439988)
		(end 94.223078 -399.910808)
		(width 0.14732)
		(layer "In15.Cu")
		(net "P5E_CPU1_PE0_TX_DN<0>")
	)
	(segment
		(start 89.278968 -224.710244)
		(end 89.272364 -224.7138)
		(width 0.0889)
		(layer "In15.Cu")
		(net "P5E_CPU1_PE0_TX_DN<0>")
	)
	(segment
		(start 85.832188 -250.834652)
		(end 85.75675 -251.262134)
		(width 0.14732)
		(layer "In15.Cu")
		(net "P5E_CPU1_PE0_TX_DN<0>")
	)
	(segment
		(start 86.911942 -228.422454)
		(end 86.853014 -228.422454)
		(width 0.0889)
		(layer "In15.Cu")
		(net "P5E_CPU1_PE0_TX_DN<0>")
	)
	(segment
		(start 78.189074 -326.47382)
		(end 75.934824 -329.719178)
		(width 0.14732)
		(layer "In15.Cu")
		(net "P5E_CPU1_PE0_TX_DN<0>")
	)
	(segment
		(start 89.743026 -223.899984)
		(end 89.732104 -223.906334)
		(width 0.0889)
		(layer "In15.Cu")
		(net "P5E_CPU1_PE0_TX_DN<0>")
	)
	(segment
		(start 83.487514 -232.501186)
		(end 83.089496 -233.517948)
		(width 0.14732)
		(layer "In15.Cu")
		(net "P5E_CPU1_PE0_TX_DN<0>")
	)
	(segment
		(start 85.010498 -255.875536)
		(end 84.248244 -256.638044)
		(width 0.14732)
		(layer "In15.Cu")
		(net "P5E_CPU1_PE0_TX_DN<0>")
	)
	(segment
		(start 90.494612 -223.575626)
		(end 90.338148 -223.846644)
		(width 0.0889)
		(layer "In15.Cu")
		(net "P5E_CPU1_PE0_TX_DN<0>")
	)
	(segment
		(start 82.89417 -260.093968)
		(end 81.867502 -266.649708)
		(width 0.14732)
		(layer "In15.Cu")
		(net "P5E_CPU1_PE0_TX_DN<0>")
	)
	(segment
		(start 88.049862 -226.831144)
		(end 88.049862 -226.83978)
		(width 0.0889)
		(layer "In15.Cu")
		(net "P5E_CPU1_PE0_TX_DN<0>")
	)
	(segment
		(start 84.804504 -230.470964)
		(end 83.487514 -232.501186)
		(width 0.14732)
		(layer "In15.Cu")
		(net "P5E_CPU1_PE0_TX_DN<0>")
	)
	(segment
		(start 85.504528 -247.87098)
		(end 85.504528 -249.282966)
		(width 0.14732)
		(layer "In15.Cu")
		(net "P5E_CPU1_PE0_TX_DN<0>")
	)
	(segment
		(start 85.504528 -249.282966)
		(end 85.832188 -250.074176)
		(width 0.14732)
		(layer "In15.Cu")
		(net "P5E_CPU1_PE0_TX_DN<0>")
	)
	(segment
		(start 83.485482 -243.48313)
		(end 85.504528 -247.87098)
		(width 0.14732)
		(layer "In15.Cu")
		(net "P5E_CPU1_PE0_TX_DN<0>")
	)
	(segment
		(start 85.75675 -251.262134)
		(end 85.177376 -252.089666)
		(width 0.14732)
		(layer "In15.Cu")
		(net "P5E_CPU1_PE0_TX_DN<0>")
	)
	(segment
		(start 85.175344 -255.477518)
		(end 85.175598 -255.477518)
		(width 0.14732)
		(layer "In15.Cu")
		(net "P5E_CPU1_PE0_TX_DN<0>")
	)
	(segment
		(start 85.177376 -252.089666)
		(end 85.05952 -252.75667)
		(width 0.14732)
		(layer "In15.Cu")
		(net "P5E_CPU1_PE0_TX_DN<0>")
	)
	(segment
		(start 85.05952 -254.374904)
		(end 85.230462 -255.344676)
		(width 0.14732)
		(layer "In15.Cu")
		(net "P5E_CPU1_PE0_TX_DN<0>")
	)
	(segment
		(start 86.83752 -228.437948)
		(end 84.804504 -230.470964)
		(width 0.14732)
		(layer "In15.Cu")
		(net "P5E_CPU1_PE0_TX_DN<0>")
	)
	(segment
		(start 73.313798 -336.046826)
		(end 74.149712 -351.439988)
		(width 0.14732)
		(layer "In15.Cu")
		(net "P5E_CPU1_PE0_TX_DN<0>")
	)
	(segment
		(start 88.989662 -225.203258)
		(end 88.989662 -225.211894)
		(width 0.0889)
		(layer "In15.Cu")
		(net "P5E_CPU1_PE0_TX_DN<0>")
	)
	(segment
		(start 81.867502 -266.649708)
		(end 84.662772 -311.107328)
		(width 0.14732)
		(layer "In15.Cu")
		(net "P5E_CPU1_PE0_TX_DN<0>")
	)
	(segment
		(start 83.089496 -233.517948)
		(end 83.485482 -243.48313)
		(width 0.14732)
		(layer "In15.Cu")
		(net "P5E_CPU1_PE0_TX_DN<0>")
	)
	(segment
		(start 86.853014 -228.422454)
		(end 86.83752 -228.437948)
		(width 0.0889)
		(layer "In15.Cu")
		(net "P5E_CPU1_PE0_TX_DN<0>")
	)
	(segment
		(start 94.223078 -400.563588)
		(end 93.928438 -400.858228)
		(width 0.14732)
		(layer "In15.Cu")
		(net "P5E_CPU1_PE0_TX_DN<0>")
	)
	(segment
		(start 87.275416 -228.05898)
		(end 86.911942 -228.422454)
		(width 0.0889)
		(layer "In15.Cu")
		(net "P5E_CPU1_PE0_TX_DN<0>")
	)
	(segment
		(start 85.175598 -255.477264)
		(end 85.175344 -255.477518)
		(width 0.14732)
		(layer "In15.Cu")
		(net "P5E_CPU1_PE0_TX_DN<0>")
	)
	(segment
		(start 87.862664 -227.155502)
		(end 87.850472 -227.162614)
		(width 0.0889)
		(layer "In15.Cu")
		(net "P5E_CPU1_PE0_TX_DN<0>")
	)
	(segment
		(start 90.338148 -223.846644)
		(end 90.249248 -223.87052)
		(width 0.0889)
		(layer "In15.Cu")
		(net "P5E_CPU1_PE0_TX_DN<0>")
	)
	(segment
		(start 88.341454 -226.336606)
		(end 88.332564 -226.341686)
		(width 0.0889)
		(layer "In15.Cu")
		(net "P5E_CPU1_PE0_TX_DN<0>")
	)
	(segment
		(start 94.223078 -399.910808)
		(end 94.223078 -400.563588)
		(width 0.14732)
		(layer "In15.Cu")
		(net "P5E_CPU1_PE0_TX_DN<0>")
	)
	(arc
		(start 89.732104 -223.906334)
		(mid 89.53272 -224.112214)
		(end 89.46007 -224.389442)
		(width 0.0889)
		(layer "In15.Cu")
		(net "P5E_CPU1_PE0_TX_DN<0>")
	)
	(arc
		(start 88.326468 -226.345242)
		(mid 88.123881 -226.551593)
		(end 88.049862 -226.831144)
		(width 0.0889)
		(layer "In15.Cu")
		(net "P5E_CPU1_PE0_TX_DN<0>")
	)
	(arc
		(start 88.520016 -226.017328)
		(mid 88.472337 -226.200228)
		(end 88.341454 -226.336606)
		(width 0.0889)
		(layer "In15.Cu")
		(net "P5E_CPU1_PE0_TX_DN<0>")
	)
	(arc
		(start 90.229182 -223.862646)
		(mid 89.98188 -223.826205)
		(end 89.743026 -223.899984)
		(width 0.0889)
		(layer "In15.Cu")
		(net "P5E_CPU1_PE0_TX_DN<0>")
	)
	(arc
		(start 88.989662 -225.211894)
		(mid 88.937392 -225.394259)
		(end 88.802464 -225.527616)
		(width 0.0889)
		(layer "In15.Cu")
		(net "P5E_CPU1_PE0_TX_DN<0>")
	)
	(arc
		(start 87.4014 -227.964238)
		(mid 87.335103 -228.007212)
		(end 87.275416 -228.05898)
		(width 0.0889)
		(layer "In15.Cu")
		(net "P5E_CPU1_PE0_TX_DN<0>")
	)
	(arc
		(start 87.850472 -227.162614)
		(mid 87.652244 -227.368462)
		(end 87.579962 -227.64496)
		(width 0.0889)
		(layer "In15.Cu")
		(net "P5E_CPU1_PE0_TX_DN<0>")
	)
	(arc
		(start 89.46007 -224.389442)
		(mid 89.411665 -224.573633)
		(end 89.278968 -224.710244)
		(width 0.0889)
		(layer "In15.Cu")
		(net "P5E_CPU1_PE0_TX_DN<0>")
	)
	(arc
		(start 88.049862 -226.83978)
		(mid 87.997592 -227.022145)
		(end 87.862664 -227.155502)
		(width 0.0889)
		(layer "In15.Cu")
		(net "P5E_CPU1_PE0_TX_DN<0>")
	)
	(arc
		(start 87.579962 -227.64496)
		(mid 87.532283 -227.82786)
		(end 87.4014 -227.964238)
		(width 0.0889)
		(layer "In15.Cu")
		(net "P5E_CPU1_PE0_TX_DN<0>")
	)
	(arc
		(start 90.248994 -223.870774)
		(mid 90.239127 -223.866616)
		(end 90.229182 -223.862646)
		(width 0.0889)
		(layer "In15.Cu")
		(net "P5E_CPU1_PE0_TX_DN<0>")
	)
	(arc
		(start 88.802464 -225.527616)
		(mid 88.600178 -225.726597)
		(end 88.520016 -225.998786)
		(width 0.0889)
		(layer "In15.Cu")
		(net "P5E_CPU1_PE0_TX_DN<0>")
	)
	(arc
		(start 89.266268 -224.717356)
		(mid 89.063681 -224.923707)
		(end 88.989662 -225.203258)
		(width 0.0889)
		(layer "In15.Cu")
		(net "P5E_CPU1_PE0_TX_DN<0>")
	)
	(segment
		(start 30.121098 -12.824968)
		(end 32.602678 -15.306548)
		(width 0.13208)
		(layer "F.Cu")
		(net "P5E_CPU1_PE1_TX_C_DP<9>")
	)
	(segment
		(start 30.118558 -11.989054)
		(end 30.118558 -11.995404)
		(width 0.13208)
		(layer "F.Cu")
		(net "P5E_CPU1_PE1_TX_C_DP<9>")
	)
	(segment
		(start 29.947108 -11.817604)
		(end 30.118558 -11.989054)
		(width 0.13208)
		(layer "F.Cu")
		(net "P5E_CPU1_PE1_TX_C_DP<9>")
	)
	(segment
		(start 32.602678 -15.502636)
		(end 32.272478 -15.832836)
		(width 0.13208)
		(layer "F.Cu")
		(net "P5E_CPU1_PE1_TX_C_DP<9>")
	)
	(segment
		(start 29.947108 -11.26998)
		(end 29.947108 -11.817604)
		(width 0.13208)
		(layer "F.Cu")
		(net "P5E_CPU1_PE1_TX_C_DP<9>")
	)
	(segment
		(start 30.121098 -11.997944)
		(end 30.121098 -12.824968)
		(width 0.13208)
		(layer "F.Cu")
		(net "P5E_CPU1_PE1_TX_C_DP<9>")
	)
	(segment
		(start 30.118558 -11.995404)
		(end 30.121098 -11.997944)
		(width 0.13208)
		(layer "F.Cu")
		(net "P5E_CPU1_PE1_TX_C_DP<9>")
	)
	(segment
		(start 32.602678 -15.306548)
		(end 32.602678 -15.502636)
		(width 0.13208)
		(layer "F.Cu")
		(net "P5E_CPU1_PE1_TX_C_DP<9>")
	)
	(segment
		(start 32.180022 -11.993372)
		(end 32.180022 -12.46251)
		(width 0.13208)
		(layer "F.Cu")
		(net "P5E_CPU1_PE1_TX_C_DP<8>")
	)
	(segment
		(start 35.655758 -17.031716)
		(end 35.980878 -17.356836)
		(width 0.13208)
		(layer "F.Cu")
		(net "P5E_CPU1_PE1_TX_C_DP<8>")
	)
	(segment
		(start 32.3469 -11.26998)
		(end 32.3469 -11.826494)
		(width 0.13208)
		(layer "F.Cu")
		(net "P5E_CPU1_PE1_TX_C_DP<8>")
	)
	(segment
		(start 32.3469 -11.826494)
		(end 32.180022 -11.993372)
		(width 0.13208)
		(layer "F.Cu")
		(net "P5E_CPU1_PE1_TX_C_DP<8>")
	)
	(segment
		(start 35.655758 -15.938246)
		(end 35.655758 -17.031716)
		(width 0.13208)
		(layer "F.Cu")
		(net "P5E_CPU1_PE1_TX_C_DP<8>")
	)
	(segment
		(start 32.180022 -12.46251)
		(end 35.655758 -15.938246)
		(width 0.13208)
		(layer "F.Cu")
		(net "P5E_CPU1_PE1_TX_C_DP<8>")
	)
	(segment
		(start 38.190678 -15.502636)
		(end 37.860478 -15.832836)
		(width 0.13208)
		(layer "F.Cu")
		(net "P5E_CPU1_PE1_TX_C_DP<7>")
	)
	(segment
		(start 38.190678 -14.491208)
		(end 38.190678 -15.502636)
		(width 0.13208)
		(layer "F.Cu")
		(net "P5E_CPU1_PE1_TX_C_DP<7>")
	)
	(segment
		(start 39.231062 -13.450824)
		(end 38.190678 -14.491208)
		(width 0.13208)
		(layer "F.Cu")
		(net "P5E_CPU1_PE1_TX_C_DP<7>")
	)
	(segment
		(start 39.231062 -11.991594)
		(end 39.231062 -13.450824)
		(width 0.13208)
		(layer "F.Cu")
		(net "P5E_CPU1_PE1_TX_C_DP<7>")
	)
	(segment
		(start 39.057072 -11.26998)
		(end 39.057072 -11.817604)
		(width 0.13208)
		(layer "F.Cu")
		(net "P5E_CPU1_PE1_TX_C_DP<7>")
	)
	(segment
		(start 39.057072 -11.817604)
		(end 39.231062 -11.991594)
		(width 0.13208)
		(layer "F.Cu")
		(net "P5E_CPU1_PE1_TX_C_DP<7>")
	)
	(segment
		(start 41.549574 -17.031716)
		(end 41.874694 -17.356836)
		(width 0.13208)
		(layer "F.Cu")
		(net "P5E_CPU1_PE1_TX_C_DP<6>")
	)
	(segment
		(start 41.456864 -11.26998)
		(end 41.456864 -11.833098)
		(width 0.13208)
		(layer "F.Cu")
		(net "P5E_CPU1_PE1_TX_C_DP<6>")
	)
	(segment
		(start 41.456864 -11.833098)
		(end 41.289986 -11.999976)
		(width 0.13208)
		(layer "F.Cu")
		(net "P5E_CPU1_PE1_TX_C_DP<6>")
	)
	(segment
		(start 41.549574 -14.308582)
		(end 41.549574 -17.031716)
		(width 0.13208)
		(layer "F.Cu")
		(net "P5E_CPU1_PE1_TX_C_DP<6>")
	)
	(segment
		(start 41.289986 -11.999976)
		(end 41.289986 -14.048994)
		(width 0.13208)
		(layer "F.Cu")
		(net "P5E_CPU1_PE1_TX_C_DP<6>")
	)
	(segment
		(start 41.289986 -14.048994)
		(end 41.549574 -14.308582)
		(width 0.13208)
		(layer "F.Cu")
		(net "P5E_CPU1_PE1_TX_C_DP<6>")
	)
	(segment
		(start 42.831004 -13.759434)
		(end 44.084494 -15.012924)
		(width 0.13208)
		(layer "F.Cu")
		(net "P5E_CPU1_PE1_TX_C_DP<5>")
	)
	(segment
		(start 42.831004 -11.991594)
		(end 42.831004 -13.759434)
		(width 0.13208)
		(layer "F.Cu")
		(net "P5E_CPU1_PE1_TX_C_DP<5>")
	)
	(segment
		(start 42.657014 -11.26998)
		(end 42.657014 -11.817604)
		(width 0.13208)
		(layer "F.Cu")
		(net "P5E_CPU1_PE1_TX_C_DP<5>")
	)
	(segment
		(start 44.084494 -15.502636)
		(end 43.754294 -15.832836)
		(width 0.13208)
		(layer "F.Cu")
		(net "P5E_CPU1_PE1_TX_C_DP<5>")
	)
	(segment
		(start 44.084494 -15.012924)
		(end 44.084494 -15.502636)
		(width 0.13208)
		(layer "F.Cu")
		(net "P5E_CPU1_PE1_TX_C_DP<5>")
	)
	(segment
		(start 42.657014 -11.817604)
		(end 42.831004 -11.991594)
		(width 0.13208)
		(layer "F.Cu")
		(net "P5E_CPU1_PE1_TX_C_DP<5>")
	)
	(segment
		(start 44.887642 -12.001246)
		(end 44.887642 -12.761214)
		(width 0.13208)
		(layer "F.Cu")
		(net "P5E_CPU1_PE1_TX_C_DP<4>")
	)
	(segment
		(start 44.887642 -12.761214)
		(end 47.135034 -15.008606)
		(width 0.13208)
		(layer "F.Cu")
		(net "P5E_CPU1_PE1_TX_C_DP<4>")
	)
	(segment
		(start 47.135034 -17.029176)
		(end 47.462694 -17.356836)
		(width 0.13208)
		(layer "F.Cu")
		(net "P5E_CPU1_PE1_TX_C_DP<4>")
	)
	(segment
		(start 45.05706 -11.831828)
		(end 44.887642 -12.001246)
		(width 0.13208)
		(layer "F.Cu")
		(net "P5E_CPU1_PE1_TX_C_DP<4>")
	)
	(segment
		(start 45.05706 -11.26998)
		(end 45.05706 -11.831828)
		(width 0.13208)
		(layer "F.Cu")
		(net "P5E_CPU1_PE1_TX_C_DP<4>")
	)
	(segment
		(start 47.135034 -15.008606)
		(end 47.135034 -17.029176)
		(width 0.13208)
		(layer "F.Cu")
		(net "P5E_CPU1_PE1_TX_C_DP<4>")
	)
	(segment
		(start 50.267108 -11.26998)
		(end 50.267108 -11.817604)
		(width 0.13208)
		(layer "F.Cu")
		(net "P5E_CPU1_PE1_TX_C_DP<3>")
	)
	(segment
		(start 49.669954 -14.40942)
		(end 49.669954 -15.505176)
		(width 0.13208)
		(layer "F.Cu")
		(net "P5E_CPU1_PE1_TX_C_DP<3>")
	)
	(segment
		(start 50.267108 -11.817604)
		(end 50.438558 -11.989054)
		(width 0.13208)
		(layer "F.Cu")
		(net "P5E_CPU1_PE1_TX_C_DP<3>")
	)
	(segment
		(start 50.438558 -11.989054)
		(end 50.438558 -13.640816)
		(width 0.13208)
		(layer "F.Cu")
		(net "P5E_CPU1_PE1_TX_C_DP<3>")
	)
	(segment
		(start 49.669954 -15.505176)
		(end 49.342294 -15.832836)
		(width 0.13208)
		(layer "F.Cu")
		(net "P5E_CPU1_PE1_TX_C_DP<3>")
	)
	(segment
		(start 50.438558 -13.640816)
		(end 49.669954 -14.40942)
		(width 0.13208)
		(layer "F.Cu")
		(net "P5E_CPU1_PE1_TX_C_DP<3>")
	)
	(segment
		(start 52.75707 -17.029176)
		(end 53.08473 -17.356836)
		(width 0.13208)
		(layer "F.Cu")
		(net "P5E_CPU1_PE1_TX_C_DP<2>")
	)
	(segment
		(start 52.6669 -11.834622)
		(end 52.497482 -12.00404)
		(width 0.13208)
		(layer "F.Cu")
		(net "P5E_CPU1_PE1_TX_C_DP<2>")
	)
	(segment
		(start 52.75707 -14.311122)
		(end 52.75707 -17.029176)
		(width 0.13208)
		(layer "F.Cu")
		(net "P5E_CPU1_PE1_TX_C_DP<2>")
	)
	(segment
		(start 52.497482 -14.051534)
		(end 52.75707 -14.311122)
		(width 0.13208)
		(layer "F.Cu")
		(net "P5E_CPU1_PE1_TX_C_DP<2>")
	)
	(segment
		(start 52.497482 -12.00404)
		(end 52.497482 -14.051534)
		(width 0.13208)
		(layer "F.Cu")
		(net "P5E_CPU1_PE1_TX_C_DP<2>")
	)
	(segment
		(start 52.6669 -11.26998)
		(end 52.6669 -11.834622)
		(width 0.13208)
		(layer "F.Cu")
		(net "P5E_CPU1_PE1_TX_C_DP<2>")
	)
	(segment
		(start 53.86705 -11.817604)
		(end 54.0385 -11.989054)
		(width 0.13208)
		(layer "F.Cu")
		(net "P5E_CPU1_PE1_TX_C_DP<1>")
	)
	(segment
		(start 54.04104 -13.78585)
		(end 55.29453 -15.03934)
		(width 0.13208)
		(layer "F.Cu")
		(net "P5E_CPU1_PE1_TX_C_DP<1>")
	)
	(segment
		(start 54.0385 -11.989308)
		(end 54.04104 -11.991848)
		(width 0.13208)
		(layer "F.Cu")
		(net "P5E_CPU1_PE1_TX_C_DP<1>")
	)
	(segment
		(start 53.86705 -11.26998)
		(end 53.86705 -11.817604)
		(width 0.13208)
		(layer "F.Cu")
		(net "P5E_CPU1_PE1_TX_C_DP<1>")
	)
	(segment
		(start 54.04104 -11.991848)
		(end 54.04104 -13.78585)
		(width 0.13208)
		(layer "F.Cu")
		(net "P5E_CPU1_PE1_TX_C_DP<1>")
	)
	(segment
		(start 54.0385 -11.989054)
		(end 54.0385 -11.989308)
		(width 0.13208)
		(layer "F.Cu")
		(net "P5E_CPU1_PE1_TX_C_DP<1>")
	)
	(segment
		(start 55.29453 -15.03934)
		(end 55.29453 -15.502636)
		(width 0.13208)
		(layer "F.Cu")
		(net "P5E_CPU1_PE1_TX_C_DP<1>")
	)
	(segment
		(start 55.29453 -15.502636)
		(end 54.96433 -15.832836)
		(width 0.13208)
		(layer "F.Cu")
		(net "P5E_CPU1_PE1_TX_C_DP<1>")
	)
	(segment
		(start 19.318478 -11.989054)
		(end 19.318478 -12.442444)
		(width 0.13208)
		(layer "F.Cu")
		(net "P5E_CPU1_PE1_TX_C_DP<15>")
	)
	(segment
		(start 15.838678 -15.502636)
		(end 15.508478 -15.832836)
		(width 0.13208)
		(layer "F.Cu")
		(net "P5E_CPU1_PE1_TX_C_DP<15>")
	)
	(segment
		(start 19.147028 -11.817604)
		(end 19.318478 -11.989054)
		(width 0.13208)
		(layer "F.Cu")
		(net "P5E_CPU1_PE1_TX_C_DP<15>")
	)
	(segment
		(start 18.079974 -13.680948)
		(end 17.022064 -13.680948)
		(width 0.13208)
		(layer "F.Cu")
		(net "P5E_CPU1_PE1_TX_C_DP<15>")
	)
	(segment
		(start 19.147028 -11.26998)
		(end 19.147028 -11.817604)
		(width 0.13208)
		(layer "F.Cu")
		(net "P5E_CPU1_PE1_TX_C_DP<15>")
	)
	(segment
		(start 17.022064 -13.680948)
		(end 15.838678 -14.864334)
		(width 0.13208)
		(layer "F.Cu")
		(net "P5E_CPU1_PE1_TX_C_DP<15>")
	)
	(segment
		(start 15.838678 -14.864334)
		(end 15.838678 -15.502636)
		(width 0.13208)
		(layer "F.Cu")
		(net "P5E_CPU1_PE1_TX_C_DP<15>")
	)
	(segment
		(start 19.318478 -12.442444)
		(end 18.079974 -13.680948)
		(width 0.13208)
		(layer "F.Cu")
		(net "P5E_CPU1_PE1_TX_C_DP<15>")
	)
	(segment
		(start 18.889218 -17.029176)
		(end 19.216878 -17.356836)
		(width 0.13208)
		(layer "F.Cu")
		(net "P5E_CPU1_PE1_TX_C_DP<14>")
	)
	(segment
		(start 18.889218 -15.272766)
		(end 18.889218 -17.029176)
		(width 0.13208)
		(layer "F.Cu")
		(net "P5E_CPU1_PE1_TX_C_DP<14>")
	)
	(segment
		(start 21.547074 -11.26998)
		(end 21.547074 -11.816588)
		(width 0.13208)
		(layer "F.Cu")
		(net "P5E_CPU1_PE1_TX_C_DP<14>")
	)
	(segment
		(start 21.377402 -11.989054)
		(end 21.377402 -12.784582)
		(width 0.13208)
		(layer "F.Cu")
		(net "P5E_CPU1_PE1_TX_C_DP<14>")
	)
	(segment
		(start 21.377402 -12.784582)
		(end 18.889218 -15.272766)
		(width 0.13208)
		(layer "F.Cu")
		(net "P5E_CPU1_PE1_TX_C_DP<14>")
	)
	(segment
		(start 21.547074 -11.816588)
		(end 21.379942 -11.98372)
		(width 0.13208)
		(layer "F.Cu")
		(net "P5E_CPU1_PE1_TX_C_DP<14>")
	)
	(segment
		(start 21.379942 -11.986514)
		(end 21.377402 -11.989054)
		(width 0.13208)
		(layer "F.Cu")
		(net "P5E_CPU1_PE1_TX_C_DP<14>")
	)
	(segment
		(start 21.379942 -11.98372)
		(end 21.379942 -11.986514)
		(width 0.13208)
		(layer "F.Cu")
		(net "P5E_CPU1_PE1_TX_C_DP<14>")
	)
	(segment
		(start 22.92096 -13.134086)
		(end 21.426678 -14.628368)
		(width 0.13208)
		(layer "F.Cu")
		(net "P5E_CPU1_PE1_TX_C_DP<13>")
	)
	(segment
		(start 21.426678 -15.502636)
		(end 21.096478 -15.832836)
		(width 0.13208)
		(layer "F.Cu")
		(net "P5E_CPU1_PE1_TX_C_DP<13>")
	)
	(segment
		(start 22.74697 -11.26998)
		(end 22.74697 -11.817604)
		(width 0.13208)
		(layer "F.Cu")
		(net "P5E_CPU1_PE1_TX_C_DP<13>")
	)
	(segment
		(start 22.92096 -11.991594)
		(end 22.92096 -13.134086)
		(width 0.13208)
		(layer "F.Cu")
		(net "P5E_CPU1_PE1_TX_C_DP<13>")
	)
	(segment
		(start 21.426678 -14.628368)
		(end 21.426678 -15.502636)
		(width 0.13208)
		(layer "F.Cu")
		(net "P5E_CPU1_PE1_TX_C_DP<13>")
	)
	(segment
		(start 22.74697 -11.817604)
		(end 22.92096 -11.991594)
		(width 0.13208)
		(layer "F.Cu")
		(net "P5E_CPU1_PE1_TX_C_DP<13>")
	)
	(segment
		(start 24.980138 -11.961876)
		(end 24.980138 -11.986514)
		(width 0.13208)
		(layer "F.Cu")
		(net "P5E_CPU1_PE1_TX_C_DP<12>")
	)
	(segment
		(start 24.977598 -11.989054)
		(end 24.977598 -13.611098)
		(width 0.13208)
		(layer "F.Cu")
		(net "P5E_CPU1_PE1_TX_C_DP<12>")
	)
	(segment
		(start 25.147016 -11.26998)
		(end 25.147016 -11.794998)
		(width 0.13208)
		(layer "F.Cu")
		(net "P5E_CPU1_PE1_TX_C_DP<12>")
	)
	(segment
		(start 24.477218 -14.111478)
		(end 24.477218 -17.029176)
		(width 0.13208)
		(layer "F.Cu")
		(net "P5E_CPU1_PE1_TX_C_DP<12>")
	)
	(segment
		(start 24.977598 -13.611098)
		(end 24.477218 -14.111478)
		(width 0.13208)
		(layer "F.Cu")
		(net "P5E_CPU1_PE1_TX_C_DP<12>")
	)
	(segment
		(start 24.477218 -17.029176)
		(end 24.804878 -17.356836)
		(width 0.13208)
		(layer "F.Cu")
		(net "P5E_CPU1_PE1_TX_C_DP<12>")
	)
	(segment
		(start 24.980138 -11.986514)
		(end 24.977598 -11.989054)
		(width 0.13208)
		(layer "F.Cu")
		(net "P5E_CPU1_PE1_TX_C_DP<12>")
	)
	(segment
		(start 25.147016 -11.794998)
		(end 24.980138 -11.961876)
		(width 0.13208)
		(layer "F.Cu")
		(net "P5E_CPU1_PE1_TX_C_DP<12>")
	)
	(segment
		(start 26.518362 -11.99007)
		(end 26.520902 -11.99261)
		(width 0.13208)
		(layer "F.Cu")
		(net "P5E_CPU1_PE1_TX_C_DP<11>")
	)
	(segment
		(start 26.346912 -11.817604)
		(end 26.518362 -11.989054)
		(width 0.13208)
		(layer "F.Cu")
		(net "P5E_CPU1_PE1_TX_C_DP<11>")
	)
	(segment
		(start 27.014678 -15.502636)
		(end 26.684478 -15.832836)
		(width 0.13208)
		(layer "F.Cu")
		(net "P5E_CPU1_PE1_TX_C_DP<11>")
	)
	(segment
		(start 26.520902 -11.99261)
		(end 26.520902 -14.007592)
		(width 0.13208)
		(layer "F.Cu")
		(net "P5E_CPU1_PE1_TX_C_DP<11>")
	)
	(segment
		(start 26.346912 -11.26998)
		(end 26.346912 -11.817604)
		(width 0.13208)
		(layer "F.Cu")
		(net "P5E_CPU1_PE1_TX_C_DP<11>")
	)
	(segment
		(start 27.014678 -14.501368)
		(end 27.014678 -15.502636)
		(width 0.13208)
		(layer "F.Cu")
		(net "P5E_CPU1_PE1_TX_C_DP<11>")
	)
	(segment
		(start 26.520902 -14.007592)
		(end 27.014678 -14.501368)
		(width 0.13208)
		(layer "F.Cu")
		(net "P5E_CPU1_PE1_TX_C_DP<11>")
	)
	(segment
		(start 26.518362 -11.989054)
		(end 26.518362 -11.99007)
		(width 0.13208)
		(layer "F.Cu")
		(net "P5E_CPU1_PE1_TX_C_DP<11>")
	)
	(segment
		(start 30.067758 -17.031716)
		(end 30.392878 -17.356836)
		(width 0.13208)
		(layer "F.Cu")
		(net "P5E_CPU1_PE1_TX_C_DP<10>")
	)
	(segment
		(start 28.58008 -11.984228)
		(end 28.58008 -13.711428)
		(width 0.13208)
		(layer "F.Cu")
		(net "P5E_CPU1_PE1_TX_C_DP<10>")
	)
	(segment
		(start 30.067758 -15.199106)
		(end 30.067758 -17.031716)
		(width 0.13208)
		(layer "F.Cu")
		(net "P5E_CPU1_PE1_TX_C_DP<10>")
	)
	(segment
		(start 28.746958 -11.26998)
		(end 28.746958 -11.81735)
		(width 0.13208)
		(layer "F.Cu")
		(net "P5E_CPU1_PE1_TX_C_DP<10>")
	)
	(segment
		(start 28.58008 -13.711428)
		(end 30.067758 -15.199106)
		(width 0.13208)
		(layer "F.Cu")
		(net "P5E_CPU1_PE1_TX_C_DP<10>")
	)
	(segment
		(start 28.746958 -11.81735)
		(end 28.58008 -11.984228)
		(width 0.13208)
		(layer "F.Cu")
		(net "P5E_CPU1_PE1_TX_C_DP<10>")
	)
	(segment
		(start 56.099964 -12.727432)
		(end 58.34761 -14.975078)
		(width 0.13208)
		(layer "F.Cu")
		(net "P5E_CPU1_PE1_TX_C_DP<0>")
	)
	(segment
		(start 56.099964 -11.962384)
		(end 56.099964 -12.727432)
		(width 0.13208)
		(layer "F.Cu")
		(net "P5E_CPU1_PE1_TX_C_DP<0>")
	)
	(segment
		(start 56.267096 -11.26998)
		(end 56.267096 -11.795252)
		(width 0.13208)
		(layer "F.Cu")
		(net "P5E_CPU1_PE1_TX_C_DP<0>")
	)
	(segment
		(start 58.34761 -17.031716)
		(end 58.67273 -17.356836)
		(width 0.13208)
		(layer "F.Cu")
		(net "P5E_CPU1_PE1_TX_C_DP<0>")
	)
	(segment
		(start 56.267096 -11.795252)
		(end 56.099964 -11.962384)
		(width 0.13208)
		(layer "F.Cu")
		(net "P5E_CPU1_PE1_TX_C_DP<0>")
	)
	(segment
		(start 58.34761 -14.975078)
		(end 58.34761 -17.031716)
		(width 0.13208)
		(layer "F.Cu")
		(net "P5E_CPU1_PE1_TX_C_DP<0>")
	)
	(segment
		(start 30.380178 -11.997944)
		(end 30.380178 -12.717526)
		(width 0.13208)
		(layer "F.Cu")
		(net "P5E_CPU1_PE1_TX_C_DN<9>")
	)
	(segment
		(start 32.861758 -15.199106)
		(end 32.861758 -15.507716)
		(width 0.13208)
		(layer "F.Cu")
		(net "P5E_CPU1_PE1_TX_C_DN<9>")
	)
	(segment
		(start 32.861758 -15.507716)
		(end 33.186878 -15.832836)
		(width 0.13208)
		(layer "F.Cu")
		(net "P5E_CPU1_PE1_TX_C_DN<9>")
	)
	(segment
		(start 30.547056 -11.26998)
		(end 30.547056 -11.831066)
		(width 0.13208)
		(layer "F.Cu")
		(net "P5E_CPU1_PE1_TX_C_DN<9>")
	)
	(segment
		(start 30.380178 -12.717526)
		(end 32.861758 -15.199106)
		(width 0.13208)
		(layer "F.Cu")
		(net "P5E_CPU1_PE1_TX_C_DN<9>")
	)
	(segment
		(start 30.547056 -11.831066)
		(end 30.380178 -11.997944)
		(width 0.13208)
		(layer "F.Cu")
		(net "P5E_CPU1_PE1_TX_C_DN<9>")
	)
	(segment
		(start 35.396678 -16.045688)
		(end 35.396678 -17.026636)
		(width 0.13208)
		(layer "F.Cu")
		(net "P5E_CPU1_PE1_TX_C_DN<8>")
	)
	(segment
		(start 31.920942 -11.991594)
		(end 31.920942 -12.569952)
		(width 0.13208)
		(layer "F.Cu")
		(net "P5E_CPU1_PE1_TX_C_DN<8>")
	)
	(segment
		(start 31.746952 -11.26998)
		(end 31.746952 -11.817604)
		(width 0.13208)
		(layer "F.Cu")
		(net "P5E_CPU1_PE1_TX_C_DN<8>")
	)
	(segment
		(start 31.746952 -11.817604)
		(end 31.920942 -11.991594)
		(width 0.13208)
		(layer "F.Cu")
		(net "P5E_CPU1_PE1_TX_C_DN<8>")
	)
	(segment
		(start 35.396678 -17.026636)
		(end 35.066478 -17.356836)
		(width 0.13208)
		(layer "F.Cu")
		(net "P5E_CPU1_PE1_TX_C_DN<8>")
	)
	(segment
		(start 31.920942 -12.569952)
		(end 35.396678 -16.045688)
		(width 0.13208)
		(layer "F.Cu")
		(net "P5E_CPU1_PE1_TX_C_DN<8>")
	)
	(segment
		(start 39.65702 -11.804142)
		(end 39.490142 -11.97102)
		(width 0.13208)
		(layer "F.Cu")
		(net "P5E_CPU1_PE1_TX_C_DN<7>")
	)
	(segment
		(start 39.490142 -11.97102)
		(end 39.490142 -13.558266)
		(width 0.13208)
		(layer "F.Cu")
		(net "P5E_CPU1_PE1_TX_C_DN<7>")
	)
	(segment
		(start 39.490142 -13.558266)
		(end 38.449758 -14.59865)
		(width 0.13208)
		(layer "F.Cu")
		(net "P5E_CPU1_PE1_TX_C_DN<7>")
	)
	(segment
		(start 38.449758 -14.59865)
		(end 38.449758 -15.507716)
		(width 0.13208)
		(layer "F.Cu")
		(net "P5E_CPU1_PE1_TX_C_DN<7>")
	)
	(segment
		(start 39.65702 -11.26998)
		(end 39.65702 -11.804142)
		(width 0.13208)
		(layer "F.Cu")
		(net "P5E_CPU1_PE1_TX_C_DN<7>")
	)
	(segment
		(start 38.449758 -15.507716)
		(end 38.774878 -15.832836)
		(width 0.13208)
		(layer "F.Cu")
		(net "P5E_CPU1_PE1_TX_C_DN<7>")
	)
	(segment
		(start 41.030906 -11.991594)
		(end 41.030906 -14.156436)
		(width 0.13208)
		(layer "F.Cu")
		(net "P5E_CPU1_PE1_TX_C_DN<6>")
	)
	(segment
		(start 40.856916 -11.817604)
		(end 41.030906 -11.991594)
		(width 0.13208)
		(layer "F.Cu")
		(net "P5E_CPU1_PE1_TX_C_DN<6>")
	)
	(segment
		(start 40.856916 -11.26998)
		(end 40.856916 -11.817604)
		(width 0.13208)
		(layer "F.Cu")
		(net "P5E_CPU1_PE1_TX_C_DN<6>")
	)
	(segment
		(start 41.030906 -14.156436)
		(end 41.290494 -14.416024)
		(width 0.13208)
		(layer "F.Cu")
		(net "P5E_CPU1_PE1_TX_C_DN<6>")
	)
	(segment
		(start 41.290494 -17.026636)
		(end 40.960294 -17.356836)
		(width 0.13208)
		(layer "F.Cu")
		(net "P5E_CPU1_PE1_TX_C_DN<6>")
	)
	(segment
		(start 41.290494 -14.416024)
		(end 41.290494 -17.026636)
		(width 0.13208)
		(layer "F.Cu")
		(net "P5E_CPU1_PE1_TX_C_DN<6>")
	)
	(segment
		(start 43.090084 -13.651992)
		(end 44.343574 -14.905482)
		(width 0.13208)
		(layer "F.Cu")
		(net "P5E_CPU1_PE1_TX_C_DN<5>")
	)
	(segment
		(start 43.256962 -11.815826)
		(end 43.090084 -11.982704)
		(width 0.13208)
		(layer "F.Cu")
		(net "P5E_CPU1_PE1_TX_C_DN<5>")
	)
	(segment
		(start 43.090084 -11.982704)
		(end 43.090084 -13.651992)
		(width 0.13208)
		(layer "F.Cu")
		(net "P5E_CPU1_PE1_TX_C_DN<5>")
	)
	(segment
		(start 44.343574 -15.507716)
		(end 44.668694 -15.832836)
		(width 0.13208)
		(layer "F.Cu")
		(net "P5E_CPU1_PE1_TX_C_DN<5>")
	)
	(segment
		(start 44.343574 -14.905482)
		(end 44.343574 -15.507716)
		(width 0.13208)
		(layer "F.Cu")
		(net "P5E_CPU1_PE1_TX_C_DN<5>")
	)
	(segment
		(start 43.256962 -11.26998)
		(end 43.256962 -11.815826)
		(width 0.13208)
		(layer "F.Cu")
		(net "P5E_CPU1_PE1_TX_C_DN<5>")
	)
	(segment
		(start 44.628562 -12.868656)
		(end 46.875954 -15.116048)
		(width 0.13208)
		(layer "F.Cu")
		(net "P5E_CPU1_PE1_TX_C_DN<4>")
	)
	(segment
		(start 44.457112 -11.817604)
		(end 44.628562 -11.989054)
		(width 0.13208)
		(layer "F.Cu")
		(net "P5E_CPU1_PE1_TX_C_DN<4>")
	)
	(segment
		(start 44.628562 -11.989054)
		(end 44.628562 -12.868656)
		(width 0.13208)
		(layer "F.Cu")
		(net "P5E_CPU1_PE1_TX_C_DN<4>")
	)
	(segment
		(start 44.457112 -11.26998)
		(end 44.457112 -11.817604)
		(width 0.13208)
		(layer "F.Cu")
		(net "P5E_CPU1_PE1_TX_C_DN<4>")
	)
	(segment
		(start 46.875954 -15.116048)
		(end 46.875954 -17.029176)
		(width 0.13208)
		(layer "F.Cu")
		(net "P5E_CPU1_PE1_TX_C_DN<4>")
	)
	(segment
		(start 46.875954 -17.029176)
		(end 46.548294 -17.356836)
		(width 0.13208)
		(layer "F.Cu")
		(net "P5E_CPU1_PE1_TX_C_DN<4>")
	)
	(segment
		(start 49.931574 -15.507716)
		(end 50.256694 -15.832836)
		(width 0.13208)
		(layer "F.Cu")
		(net "P5E_CPU1_PE1_TX_C_DN<3>")
	)
	(segment
		(start 49.929034 -15.503906)
		(end 49.931574 -15.506446)
		(width 0.13208)
		(layer "F.Cu")
		(net "P5E_CPU1_PE1_TX_C_DN<3>")
	)
	(segment
		(start 50.867056 -11.26998)
		(end 50.867056 -11.815572)
		(width 0.13208)
		(layer "F.Cu")
		(net "P5E_CPU1_PE1_TX_C_DN<3>")
	)
	(segment
		(start 50.697638 -11.98499)
		(end 50.697638 -13.748258)
		(width 0.13208)
		(layer "F.Cu")
		(net "P5E_CPU1_PE1_TX_C_DN<3>")
	)
	(segment
		(start 49.931574 -15.506446)
		(end 49.931574 -15.507716)
		(width 0.13208)
		(layer "F.Cu")
		(net "P5E_CPU1_PE1_TX_C_DN<3>")
	)
	(segment
		(start 50.867056 -11.815572)
		(end 50.697638 -11.98499)
		(width 0.13208)
		(layer "F.Cu")
		(net "P5E_CPU1_PE1_TX_C_DN<3>")
	)
	(segment
		(start 50.697638 -13.748258)
		(end 49.929034 -14.516862)
		(width 0.13208)
		(layer "F.Cu")
		(net "P5E_CPU1_PE1_TX_C_DN<3>")
	)
	(segment
		(start 49.929034 -14.516862)
		(end 49.929034 -15.503906)
		(width 0.13208)
		(layer "F.Cu")
		(net "P5E_CPU1_PE1_TX_C_DN<3>")
	)
	(segment
		(start 52.238402 -14.158976)
		(end 52.49799 -14.418564)
		(width 0.13208)
		(layer "F.Cu")
		(net "P5E_CPU1_PE1_TX_C_DN<2>")
	)
	(segment
		(start 52.238402 -11.989054)
		(end 52.238402 -14.158976)
		(width 0.13208)
		(layer "F.Cu")
		(net "P5E_CPU1_PE1_TX_C_DN<2>")
	)
	(segment
		(start 52.066952 -11.817604)
		(end 52.238402 -11.989054)
		(width 0.13208)
		(layer "F.Cu")
		(net "P5E_CPU1_PE1_TX_C_DN<2>")
	)
	(segment
		(start 52.066952 -11.26998)
		(end 52.066952 -11.817604)
		(width 0.13208)
		(layer "F.Cu")
		(net "P5E_CPU1_PE1_TX_C_DN<2>")
	)
	(segment
		(start 52.49799 -17.029176)
		(end 52.17033 -17.356836)
		(width 0.13208)
		(layer "F.Cu")
		(net "P5E_CPU1_PE1_TX_C_DN<2>")
	)
	(segment
		(start 52.49799 -14.418564)
		(end 52.49799 -17.029176)
		(width 0.13208)
		(layer "F.Cu")
		(net "P5E_CPU1_PE1_TX_C_DN<2>")
	)
	(segment
		(start 55.55361 -14.931898)
		(end 55.55361 -15.507716)
		(width 0.13208)
		(layer "F.Cu")
		(net "P5E_CPU1_PE1_TX_C_DN<1>")
	)
	(segment
		(start 54.30012 -13.678408)
		(end 55.55361 -14.931898)
		(width 0.13208)
		(layer "F.Cu")
		(net "P5E_CPU1_PE1_TX_C_DN<1>")
	)
	(segment
		(start 54.466998 -11.82243)
		(end 54.30012 -11.989308)
		(width 0.13208)
		(layer "F.Cu")
		(net "P5E_CPU1_PE1_TX_C_DN<1>")
	)
	(segment
		(start 54.466998 -11.26998)
		(end 54.466998 -11.82243)
		(width 0.13208)
		(layer "F.Cu")
		(net "P5E_CPU1_PE1_TX_C_DN<1>")
	)
	(segment
		(start 55.55361 -15.507716)
		(end 55.87873 -15.832836)
		(width 0.13208)
		(layer "F.Cu")
		(net "P5E_CPU1_PE1_TX_C_DN<1>")
	)
	(segment
		(start 54.30012 -11.989308)
		(end 54.30012 -13.678408)
		(width 0.13208)
		(layer "F.Cu")
		(net "P5E_CPU1_PE1_TX_C_DN<1>")
	)
	(segment
		(start 16.097758 -15.507716)
		(end 16.422878 -15.832836)
		(width 0.13208)
		(layer "F.Cu")
		(net "P5E_CPU1_PE1_TX_C_DN<15>")
	)
	(segment
		(start 19.577558 -12.549886)
		(end 18.187416 -13.940028)
		(width 0.13208)
		(layer "F.Cu")
		(net "P5E_CPU1_PE1_TX_C_DN<15>")
	)
	(segment
		(start 19.746976 -11.26998)
		(end 19.746976 -11.825986)
		(width 0.13208)
		(layer "F.Cu")
		(net "P5E_CPU1_PE1_TX_C_DN<15>")
	)
	(segment
		(start 19.577558 -11.995404)
		(end 19.577558 -12.549886)
		(width 0.13208)
		(layer "F.Cu")
		(net "P5E_CPU1_PE1_TX_C_DN<15>")
	)
	(segment
		(start 17.129506 -13.940028)
		(end 16.097758 -14.971776)
		(width 0.13208)
		(layer "F.Cu")
		(net "P5E_CPU1_PE1_TX_C_DN<15>")
	)
	(segment
		(start 18.187416 -13.940028)
		(end 17.129506 -13.940028)
		(width 0.13208)
		(layer "F.Cu")
		(net "P5E_CPU1_PE1_TX_C_DN<15>")
	)
	(segment
		(start 19.746976 -11.825986)
		(end 19.577558 -11.995404)
		(width 0.13208)
		(layer "F.Cu")
		(net "P5E_CPU1_PE1_TX_C_DN<15>")
	)
	(segment
		(start 16.097758 -14.971776)
		(end 16.097758 -15.507716)
		(width 0.13208)
		(layer "F.Cu")
		(net "P5E_CPU1_PE1_TX_C_DN<15>")
	)
	(segment
		(start 18.630138 -15.165324)
		(end 18.630138 -17.029176)
		(width 0.13208)
		(layer "F.Cu")
		(net "P5E_CPU1_PE1_TX_C_DN<14>")
	)
	(segment
		(start 21.118322 -11.989054)
		(end 21.118322 -12.67714)
		(width 0.13208)
		(layer "F.Cu")
		(net "P5E_CPU1_PE1_TX_C_DN<14>")
	)
	(segment
		(start 20.946872 -11.817604)
		(end 21.118322 -11.989054)
		(width 0.13208)
		(layer "F.Cu")
		(net "P5E_CPU1_PE1_TX_C_DN<14>")
	)
	(segment
		(start 18.630138 -17.029176)
		(end 18.302478 -17.356836)
		(width 0.13208)
		(layer "F.Cu")
		(net "P5E_CPU1_PE1_TX_C_DN<14>")
	)
	(segment
		(start 20.946872 -11.26998)
		(end 20.946872 -11.817604)
		(width 0.13208)
		(layer "F.Cu")
		(net "P5E_CPU1_PE1_TX_C_DN<14>")
	)
	(segment
		(start 21.118322 -12.67714)
		(end 18.630138 -15.165324)
		(width 0.13208)
		(layer "F.Cu")
		(net "P5E_CPU1_PE1_TX_C_DN<14>")
	)
	(segment
		(start 23.18004 -11.989054)
		(end 23.18004 -13.241528)
		(width 0.13208)
		(layer "F.Cu")
		(net "P5E_CPU1_PE1_TX_C_DN<13>")
	)
	(segment
		(start 21.685758 -14.73581)
		(end 21.685758 -15.507716)
		(width 0.13208)
		(layer "F.Cu")
		(net "P5E_CPU1_PE1_TX_C_DN<13>")
	)
	(segment
		(start 23.346918 -11.26998)
		(end 23.346918 -11.822176)
		(width 0.13208)
		(layer "F.Cu")
		(net "P5E_CPU1_PE1_TX_C_DN<13>")
	)
	(segment
		(start 23.18004 -13.241528)
		(end 21.685758 -14.73581)
		(width 0.13208)
		(layer "F.Cu")
		(net "P5E_CPU1_PE1_TX_C_DN<13>")
	)
	(segment
		(start 23.346918 -11.822176)
		(end 23.18004 -11.989054)
		(width 0.13208)
		(layer "F.Cu")
		(net "P5E_CPU1_PE1_TX_C_DN<13>")
	)
	(segment
		(start 21.685758 -15.507716)
		(end 22.010878 -15.832836)
		(width 0.13208)
		(layer "F.Cu")
		(net "P5E_CPU1_PE1_TX_C_DN<13>")
	)
	(segment
		(start 24.718518 -11.989054)
		(end 24.718518 -13.503656)
		(width 0.13208)
		(layer "F.Cu")
		(net "P5E_CPU1_PE1_TX_C_DN<12>")
	)
	(segment
		(start 24.718518 -13.503656)
		(end 24.218138 -14.004036)
		(width 0.13208)
		(layer "F.Cu")
		(net "P5E_CPU1_PE1_TX_C_DN<12>")
	)
	(segment
		(start 24.218138 -17.029176)
		(end 23.890478 -17.356836)
		(width 0.13208)
		(layer "F.Cu")
		(net "P5E_CPU1_PE1_TX_C_DN<12>")
	)
	(segment
		(start 24.547068 -11.26998)
		(end 24.547068 -11.817604)
		(width 0.13208)
		(layer "F.Cu")
		(net "P5E_CPU1_PE1_TX_C_DN<12>")
	)
	(segment
		(start 24.218138 -14.004036)
		(end 24.218138 -17.029176)
		(width 0.13208)
		(layer "F.Cu")
		(net "P5E_CPU1_PE1_TX_C_DN<12>")
	)
	(segment
		(start 24.547068 -11.817604)
		(end 24.718518 -11.989054)
		(width 0.13208)
		(layer "F.Cu")
		(net "P5E_CPU1_PE1_TX_C_DN<12>")
	)
	(segment
		(start 27.273758 -14.393926)
		(end 27.273758 -15.507716)
		(width 0.13208)
		(layer "F.Cu")
		(net "P5E_CPU1_PE1_TX_C_DN<11>")
	)
	(segment
		(start 26.94686 -11.26998)
		(end 26.94686 -11.823954)
		(width 0.13208)
		(layer "F.Cu")
		(net "P5E_CPU1_PE1_TX_C_DN<11>")
	)
	(segment
		(start 27.273758 -15.507716)
		(end 27.598878 -15.832836)
		(width 0.13208)
		(layer "F.Cu")
		(net "P5E_CPU1_PE1_TX_C_DN<11>")
	)
	(segment
		(start 26.779982 -13.90015)
		(end 27.273758 -14.393926)
		(width 0.13208)
		(layer "F.Cu")
		(net "P5E_CPU1_PE1_TX_C_DN<11>")
	)
	(segment
		(start 26.779982 -11.990832)
		(end 26.779982 -13.90015)
		(width 0.13208)
		(layer "F.Cu")
		(net "P5E_CPU1_PE1_TX_C_DN<11>")
	)
	(segment
		(start 26.94686 -11.823954)
		(end 26.779982 -11.990832)
		(width 0.13208)
		(layer "F.Cu")
		(net "P5E_CPU1_PE1_TX_C_DN<11>")
	)
	(segment
		(start 28.14701 -11.26998)
		(end 28.14701 -11.817604)
		(width 0.13208)
		(layer "F.Cu")
		(net "P5E_CPU1_PE1_TX_C_DN<10>")
	)
	(segment
		(start 28.321 -13.81887)
		(end 29.808678 -15.306548)
		(width 0.13208)
		(layer "F.Cu")
		(net "P5E_CPU1_PE1_TX_C_DN<10>")
	)
	(segment
		(start 28.321 -11.991594)
		(end 28.321 -13.81887)
		(width 0.13208)
		(layer "F.Cu")
		(net "P5E_CPU1_PE1_TX_C_DN<10>")
	)
	(segment
		(start 29.808678 -15.306548)
		(end 29.808678 -17.026636)
		(width 0.13208)
		(layer "F.Cu")
		(net "P5E_CPU1_PE1_TX_C_DN<10>")
	)
	(segment
		(start 29.808678 -17.026636)
		(end 29.478478 -17.356836)
		(width 0.13208)
		(layer "F.Cu")
		(net "P5E_CPU1_PE1_TX_C_DN<10>")
	)
	(segment
		(start 28.14701 -11.817604)
		(end 28.321 -11.991594)
		(width 0.13208)
		(layer "F.Cu")
		(net "P5E_CPU1_PE1_TX_C_DN<10>")
	)
	(segment
		(start 55.840884 -12.834874)
		(end 58.08853 -15.08252)
		(width 0.13208)
		(layer "F.Cu")
		(net "P5E_CPU1_PE1_TX_C_DN<0>")
	)
	(segment
		(start 55.666894 -11.26998)
		(end 55.666894 -11.817604)
		(width 0.13208)
		(layer "F.Cu")
		(net "P5E_CPU1_PE1_TX_C_DN<0>")
	)
	(segment
		(start 58.08853 -15.08252)
		(end 58.08853 -17.026636)
		(width 0.13208)
		(layer "F.Cu")
		(net "P5E_CPU1_PE1_TX_C_DN<0>")
	)
	(segment
		(start 55.840884 -11.991594)
		(end 55.840884 -12.834874)
		(width 0.13208)
		(layer "F.Cu")
		(net "P5E_CPU1_PE1_TX_C_DN<0>")
	)
	(segment
		(start 55.666894 -11.817604)
		(end 55.840884 -11.991594)
		(width 0.13208)
		(layer "F.Cu")
		(net "P5E_CPU1_PE1_TX_C_DN<0>")
	)
	(segment
		(start 58.08853 -17.026636)
		(end 57.75833 -17.356836)
		(width 0.13208)
		(layer "F.Cu")
		(net "P5E_CPU1_PE1_TX_C_DN<0>")
	)
	(segment
		(start 97.543112 -221.134178)
		(end 97.543366 -221.133924)
		(width 0.13208)
		(layer "F.Cu")
		(net "P5E_CPU1_PE0_RX_DP<9>")
	)
	(segment
		(start 97.543112 -221.669864)
		(end 97.543112 -221.134178)
		(width 0.13208)
		(layer "F.Cu")
		(net "P5E_CPU1_PE0_RX_DP<9>")
	)
	(segment
		(start 68.759324 -397.64462)
		(end 68.611496 -397.502634)
		(width 0.14732)
		(layer "In13.Cu")
		(net "P5E_CPU1_PE0_RX_DP<9>")
	)
	(segment
		(start 68.74002 -396.61846)
		(end 68.592192 -396.476474)
		(width 0.14732)
		(layer "In13.Cu")
		(net "P5E_CPU1_PE0_RX_DP<9>")
	)
	(segment
		(start 95.991172 -211.254594)
		(end 96.466406 -212.401912)
		(width 0.14732)
		(layer "In13.Cu")
		(net "P5E_CPU1_PE0_RX_DP<9>")
	)
	(segment
		(start 96.466406 -212.401912)
		(end 96.466406 -213.135972)
		(width 0.14732)
		(layer "In13.Cu")
		(net "P5E_CPU1_PE0_RX_DP<9>")
	)
	(segment
		(start 68.652136 -391.942828)
		(end 68.504562 -391.800842)
		(width 0.14732)
		(layer "In13.Cu")
		(net "P5E_CPU1_PE0_RX_DP<9>")
	)
	(segment
		(start 80.668622 -213.547706)
		(end 82.570574 -211.9884)
		(width 0.14732)
		(layer "In13.Cu")
		(net "P5E_CPU1_PE0_RX_DP<9>")
	)
	(segment
		(start 97.261426 -218.368372)
		(end 97.2693 -218.372944)
		(width 0.0889)
		(layer "In13.Cu")
		(net "P5E_CPU1_PE0_RX_DP<9>")
	)
	(segment
		(start 68.408804 -389.263382)
		(end 68.526914 -389.132826)
		(width 0.14732)
		(layer "In13.Cu")
		(net "P5E_CPU1_PE0_RX_DP<9>")
	)
	(segment
		(start 96.799146 -214.941912)
		(end 96.790256 -214.946992)
		(width 0.0889)
		(layer "In13.Cu")
		(net "P5E_CPU1_PE0_RX_DP<9>")
	)
	(segment
		(start 87.947246 -210.496912)
		(end 88.365838 -210.370928)
		(width 0.14732)
		(layer "In13.Cu")
		(net "P5E_CPU1_PE0_RX_DP<9>")
	)
	(segment
		(start 68.746878 -396.987014)
		(end 68.74002 -396.61846)
		(width 0.14732)
		(layer "In13.Cu")
		(net "P5E_CPU1_PE0_RX_DP<9>")
	)
	(segment
		(start 66.742818 -406.313132)
		(end 68.459858 -404.596092)
		(width 0.14732)
		(layer "In13.Cu")
		(net "P5E_CPU1_PE0_RX_DP<9>")
	)
	(segment
		(start 68.592192 -396.476474)
		(end 68.585334 -396.108428)
		(width 0.14732)
		(layer "In13.Cu")
		(net "P5E_CPU1_PE0_RX_DP<9>")
	)
	(segment
		(start 96.508316 -213.929722)
		(end 96.508316 -213.930484)
		(width 0.0889)
		(layer "In13.Cu")
		(net "P5E_CPU1_PE0_RX_DP<9>")
	)
	(segment
		(start 68.517008 -392.458702)
		(end 68.658994 -392.311382)
		(width 0.14732)
		(layer "In13.Cu")
		(net "P5E_CPU1_PE0_RX_DP<9>")
	)
	(segment
		(start 68.679568 -393.401804)
		(end 68.53174 -393.259818)
		(width 0.14732)
		(layer "In13.Cu")
		(net "P5E_CPU1_PE0_RX_DP<9>")
	)
	(segment
		(start 68.583048 -390.254236)
		(end 68.561204 -389.81761)
		(width 0.14732)
		(layer "In13.Cu")
		(net "P5E_CPU1_PE0_RX_DP<9>")
	)
	(segment
		(start 87.795354 -210.415378)
		(end 87.947246 -210.496912)
		(width 0.14732)
		(layer "In13.Cu")
		(net "P5E_CPU1_PE0_RX_DP<9>")
	)
	(segment
		(start 94.008956 -209.965036)
		(end 95.19158 -210.455002)
		(width 0.14732)
		(layer "In13.Cu")
		(net "P5E_CPU1_PE0_RX_DP<9>")
	)
	(segment
		(start 96.50857 -213.200234)
		(end 96.50857 -213.929468)
		(width 0.0889)
		(layer "In13.Cu")
		(net "P5E_CPU1_PE0_RX_DP<9>")
	)
	(segment
		(start 70.482968 -437.31942)
		(end 70.132956 -437.31942)
		(width 0.14732)
		(layer "In13.Cu")
		(net "P5E_CPU1_PE0_RX_DP<9>")
	)
	(segment
		(start 68.611496 -397.502634)
		(end 68.604638 -397.134588)
		(width 0.14732)
		(layer "In13.Cu")
		(net "P5E_CPU1_PE0_RX_DP<9>")
	)
	(segment
		(start 96.978216 -216.25052)
		(end 96.978216 -216.260426)
		(width 0.0889)
		(layer "In13.Cu")
		(net "P5E_CPU1_PE0_RX_DP<9>")
	)
	(segment
		(start 88.447372 -210.218782)
		(end 89.290398 -209.965036)
		(width 0.14732)
		(layer "In13.Cu")
		(net "P5E_CPU1_PE0_RX_DP<9>")
	)
	(segment
		(start 66.660268 -330.02982)
		(end 69.742304 -322.589144)
		(width 0.14732)
		(layer "In13.Cu")
		(net "P5E_CPU1_PE0_RX_DP<9>")
	)
	(segment
		(start 97.6757 -220.773752)
		(end 97.69983 -220.862906)
		(width 0.0889)
		(layer "In13.Cu")
		(net "P5E_CPU1_PE0_RX_DP<9>")
	)
	(segment
		(start 68.526914 -389.132826)
		(end 68.50507 -388.6962)
		(width 0.14732)
		(layer "In13.Cu")
		(net "P5E_CPU1_PE0_RX_DP<9>")
	)
	(segment
		(start 68.31838 -387.456934)
		(end 66.693288 -354.961444)
		(width 0.14732)
		(layer "In13.Cu")
		(net "P5E_CPU1_PE0_RX_DP<9>")
	)
	(segment
		(start 82.570574 -211.9884)
		(end 87.795354 -210.415378)
		(width 0.14732)
		(layer "In13.Cu")
		(net "P5E_CPU1_PE0_RX_DP<9>")
	)
	(segment
		(start 69.97446 -437.160924)
		(end 69.97446 -416.631628)
		(width 0.14732)
		(layer "In13.Cu")
		(net "P5E_CPU1_PE0_RX_DP<9>")
	)
	(segment
		(start 96.790002 -215.925654)
		(end 96.790764 -215.926162)
		(width 0.0889)
		(layer "In13.Cu")
		(net "P5E_CPU1_PE0_RX_DP<9>")
	)
	(segment
		(start 68.561204 -389.81761)
		(end 68.430394 -389.6995)
		(width 0.14732)
		(layer "In13.Cu")
		(net "P5E_CPU1_PE0_RX_DP<9>")
	)
	(segment
		(start 68.63588 -398.786858)
		(end 68.624196 -398.160748)
		(width 0.14732)
		(layer "In13.Cu")
		(net "P5E_CPU1_PE0_RX_DP<9>")
	)
	(segment
		(start 89.290398 -209.965036)
		(end 94.008956 -209.965036)
		(width 0.14732)
		(layer "In13.Cu")
		(net "P5E_CPU1_PE0_RX_DP<9>")
	)
	(segment
		(start 69.97446 -416.631628)
		(end 66.742818 -410.608272)
		(width 0.14732)
		(layer "In13.Cu")
		(net "P5E_CPU1_PE0_RX_DP<9>")
	)
	(segment
		(start 96.978216 -219.490544)
		(end 96.978216 -219.515944)
		(width 0.0889)
		(layer "In13.Cu")
		(net "P5E_CPU1_PE0_RX_DP<9>")
	)
	(segment
		(start 68.37426 -388.57809)
		(end 68.35267 -388.141972)
		(width 0.14732)
		(layer "In13.Cu")
		(net "P5E_CPU1_PE0_RX_DP<9>")
	)
	(segment
		(start 68.701412 -394.56614)
		(end 68.553584 -394.424154)
		(width 0.14732)
		(layer "In13.Cu")
		(net "P5E_CPU1_PE0_RX_DP<9>")
	)
	(segment
		(start 96.508062 -215.414606)
		(end 96.508062 -215.436704)
		(width 0.0889)
		(layer "In13.Cu")
		(net "P5E_CPU1_PE0_RX_DP<9>")
	)
	(segment
		(start 68.720716 -395.5923)
		(end 68.572888 -395.450314)
		(width 0.14732)
		(layer "In13.Cu")
		(net "P5E_CPU1_PE0_RX_DP<9>")
	)
	(segment
		(start 68.430394 -389.6995)
		(end 68.408804 -389.263382)
		(width 0.14732)
		(layer "In13.Cu")
		(net "P5E_CPU1_PE0_RX_DP<9>")
	)
	(segment
		(start 72.263508 -318.989202)
		(end 76.210668 -309.5879)
		(width 0.14732)
		(layer "In13.Cu")
		(net "P5E_CPU1_PE0_RX_DP<9>")
	)
	(segment
		(start 66.693288 -354.961444)
		(end 66.660268 -344.266266)
		(width 0.14732)
		(layer "In13.Cu")
		(net "P5E_CPU1_PE0_RX_DP<9>")
	)
	(segment
		(start 97.69983 -220.862906)
		(end 97.543366 -221.133924)
		(width 0.0889)
		(layer "In13.Cu")
		(net "P5E_CPU1_PE0_RX_DP<9>")
	)
	(segment
		(start 72.594724 -252.651768)
		(end 72.677528 -250.190762)
		(width 0.14732)
		(layer "In13.Cu")
		(net "P5E_CPU1_PE0_RX_DP<9>")
	)
	(segment
		(start 66.742818 -410.608272)
		(end 66.742818 -406.313132)
		(width 0.14732)
		(layer "In13.Cu")
		(net "P5E_CPU1_PE0_RX_DP<9>")
	)
	(segment
		(start 96.790764 -215.926162)
		(end 96.792288 -215.926924)
		(width 0.0889)
		(layer "In13.Cu")
		(net "P5E_CPU1_PE0_RX_DP<9>")
	)
	(segment
		(start 68.35267 -388.141972)
		(end 68.47078 -388.011416)
		(width 0.14732)
		(layer "In13.Cu")
		(net "P5E_CPU1_PE0_RX_DP<9>")
	)
	(segment
		(start 68.686426 -393.770358)
		(end 68.679568 -393.401804)
		(width 0.14732)
		(layer "In13.Cu")
		(net "P5E_CPU1_PE0_RX_DP<9>")
	)
	(segment
		(start 97.447862 -220.311218)
		(end 97.447862 -220.334078)
		(width 0.0889)
		(layer "In13.Cu")
		(net "P5E_CPU1_PE0_RX_DP<9>")
	)
	(segment
		(start 68.727574 -395.960854)
		(end 68.720716 -395.5923)
		(width 0.14732)
		(layer "In13.Cu")
		(net "P5E_CPU1_PE0_RX_DP<9>")
	)
	(segment
		(start 68.56603 -395.082268)
		(end 68.70827 -394.934694)
		(width 0.14732)
		(layer "In13.Cu")
		(net "P5E_CPU1_PE0_RX_DP<9>")
	)
	(segment
		(start 96.977708 -214.461344)
		(end 96.977708 -214.622634)
		(width 0.0889)
		(layer "In13.Cu")
		(net "P5E_CPU1_PE0_RX_DP<9>")
	)
	(segment
		(start 96.784668 -215.922606)
		(end 96.790002 -215.925654)
		(width 0.0889)
		(layer "In13.Cu")
		(net "P5E_CPU1_PE0_RX_DP<9>")
	)
	(segment
		(start 70.132956 -437.31942)
		(end 69.97446 -437.160924)
		(width 0.14732)
		(layer "In13.Cu")
		(net "P5E_CPU1_PE0_RX_DP<9>")
	)
	(segment
		(start 68.553584 -394.424154)
		(end 68.544186 -393.917932)
		(width 0.14732)
		(layer "In13.Cu")
		(net "P5E_CPU1_PE0_RX_DP<9>")
	)
	(segment
		(start 68.459858 -400.706082)
		(end 68.63588 -398.786858)
		(width 0.14732)
		(layer "In13.Cu")
		(net "P5E_CPU1_PE0_RX_DP<9>")
	)
	(segment
		(start 68.464938 -390.384792)
		(end 68.583048 -390.254236)
		(width 0.14732)
		(layer "In13.Cu")
		(net "P5E_CPU1_PE0_RX_DP<9>")
	)
	(segment
		(start 68.448936 -387.57479)
		(end 68.31838 -387.456934)
		(width 0.14732)
		(layer "In13.Cu")
		(net "P5E_CPU1_PE0_RX_DP<9>")
	)
	(segment
		(start 68.47078 -388.011416)
		(end 68.448936 -387.57479)
		(width 0.14732)
		(layer "In13.Cu")
		(net "P5E_CPU1_PE0_RX_DP<9>")
	)
	(segment
		(start 68.658994 -392.311382)
		(end 68.652136 -391.942828)
		(width 0.14732)
		(layer "In13.Cu")
		(net "P5E_CPU1_PE0_RX_DP<9>")
	)
	(segment
		(start 68.50507 -388.6962)
		(end 68.37426 -388.57809)
		(width 0.14732)
		(layer "In13.Cu")
		(net "P5E_CPU1_PE0_RX_DP<9>")
	)
	(segment
		(start 68.624196 -398.160748)
		(end 68.766182 -398.013174)
		(width 0.14732)
		(layer "In13.Cu")
		(net "P5E_CPU1_PE0_RX_DP<9>")
	)
	(segment
		(start 88.365838 -210.370928)
		(end 88.447372 -210.218782)
		(width 0.14732)
		(layer "In13.Cu")
		(net "P5E_CPU1_PE0_RX_DP<9>")
	)
	(segment
		(start 68.486528 -390.82091)
		(end 68.464938 -390.384792)
		(width 0.14732)
		(layer "In13.Cu")
		(net "P5E_CPU1_PE0_RX_DP<9>")
	)
	(segment
		(start 96.466406 -213.135972)
		(end 96.466406 -213.15807)
		(width 0.0889)
		(layer "In13.Cu")
		(net "P5E_CPU1_PE0_RX_DP<9>")
	)
	(segment
		(start 70.6501 -436.889906)
		(end 70.6501 -437.152288)
		(width 0.14732)
		(layer "In13.Cu")
		(net "P5E_CPU1_PE0_RX_DP<9>")
	)
	(segment
		(start 68.70827 -394.934694)
		(end 68.701412 -394.56614)
		(width 0.14732)
		(layer "In13.Cu")
		(net "P5E_CPU1_PE0_RX_DP<9>")
	)
	(segment
		(start 97.447862 -217.0557)
		(end 97.447862 -217.072972)
		(width 0.0889)
		(layer "In13.Cu")
		(net "P5E_CPU1_PE0_RX_DP<9>")
	)
	(segment
		(start 96.978216 -217.859864)
		(end 96.978216 -217.8939)
		(width 0.0889)
		(layer "In13.Cu")
		(net "P5E_CPU1_PE0_RX_DP<9>")
	)
	(segment
		(start 74.120756 -233.019092)
		(end 76.105512 -220.235018)
		(width 0.14732)
		(layer "In13.Cu")
		(net "P5E_CPU1_PE0_RX_DP<9>")
	)
	(segment
		(start 68.604638 -397.134588)
		(end 68.746878 -396.987014)
		(width 0.14732)
		(layer "In13.Cu")
		(net "P5E_CPU1_PE0_RX_DP<9>")
	)
	(segment
		(start 76.105512 -220.235018)
		(end 77.360018 -217.800428)
		(width 0.14732)
		(layer "In13.Cu")
		(net "P5E_CPU1_PE0_RX_DP<9>")
	)
	(segment
		(start 66.660268 -344.266266)
		(end 66.660268 -330.02982)
		(width 0.14732)
		(layer "In13.Cu")
		(net "P5E_CPU1_PE0_RX_DP<9>")
	)
	(segment
		(start 96.50857 -213.929468)
		(end 96.508316 -213.929722)
		(width 0.0889)
		(layer "In13.Cu")
		(net "P5E_CPU1_PE0_RX_DP<9>")
	)
	(segment
		(start 68.544186 -393.917932)
		(end 68.686426 -393.770358)
		(width 0.14732)
		(layer "In13.Cu")
		(net "P5E_CPU1_PE0_RX_DP<9>")
	)
	(segment
		(start 72.594724 -252.757178)
		(end 72.594724 -252.651768)
		(width 0.14732)
		(layer "In13.Cu")
		(net "P5E_CPU1_PE0_RX_DP<9>")
	)
	(segment
		(start 95.19158 -210.455002)
		(end 95.991172 -211.254594)
		(width 0.14732)
		(layer "In13.Cu")
		(net "P5E_CPU1_PE0_RX_DP<9>")
	)
	(segment
		(start 97.26041 -218.367864)
		(end 97.261426 -218.368372)
		(width 0.0889)
		(layer "In13.Cu")
		(net "P5E_CPU1_PE0_RX_DP<9>")
	)
	(segment
		(start 70.6501 -437.152288)
		(end 70.482968 -437.31942)
		(width 0.14732)
		(layer "In13.Cu")
		(net "P5E_CPU1_PE0_RX_DP<9>")
	)
	(segment
		(start 68.459858 -404.596092)
		(end 68.459858 -400.706082)
		(width 0.14732)
		(layer "In13.Cu")
		(net "P5E_CPU1_PE0_RX_DP<9>")
	)
	(segment
		(start 68.572888 -395.450314)
		(end 68.56603 -395.082268)
		(width 0.14732)
		(layer "In13.Cu")
		(net "P5E_CPU1_PE0_RX_DP<9>")
	)
	(segment
		(start 68.504562 -391.800842)
		(end 68.486528 -390.82091)
		(width 0.14732)
		(layer "In13.Cu")
		(net "P5E_CPU1_PE0_RX_DP<9>")
	)
	(segment
		(start 96.792288 -215.926924)
		(end 96.799654 -215.931242)
		(width 0.0889)
		(layer "In13.Cu")
		(net "P5E_CPU1_PE0_RX_DP<9>")
	)
	(segment
		(start 68.766182 -398.013174)
		(end 68.759324 -397.64462)
		(width 0.14732)
		(layer "In13.Cu")
		(net "P5E_CPU1_PE0_RX_DP<9>")
	)
	(segment
		(start 68.585334 -396.108428)
		(end 68.727574 -395.960854)
		(width 0.14732)
		(layer "In13.Cu")
		(net "P5E_CPU1_PE0_RX_DP<9>")
	)
	(segment
		(start 72.677528 -250.190762)
		(end 74.120756 -233.019092)
		(width 0.14732)
		(layer "In13.Cu")
		(net "P5E_CPU1_PE0_RX_DP<9>")
	)
	(segment
		(start 76.210668 -309.5879)
		(end 72.594724 -252.757178)
		(width 0.14732)
		(layer "In13.Cu")
		(net "P5E_CPU1_PE0_RX_DP<9>")
	)
	(segment
		(start 68.53174 -393.259818)
		(end 68.517008 -392.458702)
		(width 0.14732)
		(layer "In13.Cu")
		(net "P5E_CPU1_PE0_RX_DP<9>")
	)
	(segment
		(start 96.466406 -213.15807)
		(end 96.50857 -213.200234)
		(width 0.0889)
		(layer "In13.Cu")
		(net "P5E_CPU1_PE0_RX_DP<9>")
	)
	(segment
		(start 97.2693 -219.0115)
		(end 97.26041 -219.01658)
		(width 0.0889)
		(layer "In13.Cu")
		(net "P5E_CPU1_PE0_RX_DP<9>")
	)
	(segment
		(start 77.360018 -217.800428)
		(end 80.668622 -213.547706)
		(width 0.14732)
		(layer "In13.Cu")
		(net "P5E_CPU1_PE0_RX_DP<9>")
	)
	(segment
		(start 69.742304 -322.589144)
		(end 72.263508 -318.989202)
		(width 0.14732)
		(layer "In13.Cu")
		(net "P5E_CPU1_PE0_RX_DP<9>")
	)
	(arc
		(start 97.26041 -219.01658)
		(mid 97.057587 -219.216811)
		(end 96.978216 -219.490544)
		(width 0.0889)
		(layer "In13.Cu")
		(net "P5E_CPU1_PE0_RX_DP<9>")
	)
	(arc
		(start 96.793558 -214.261954)
		(mid 96.902705 -214.345882)
		(end 96.977708 -214.461344)
		(width 0.0889)
		(layer "In13.Cu")
		(net "P5E_CPU1_PE0_RX_DP<9>")
	)
	(arc
		(start 96.799654 -215.931242)
		(mid 96.930568 -216.067602)
		(end 96.978216 -216.25052)
		(width 0.0889)
		(layer "In13.Cu")
		(net "P5E_CPU1_PE0_RX_DP<9>")
	)
	(arc
		(start 96.977454 -214.637366)
		(mid 96.9264 -214.811946)
		(end 96.799146 -214.941912)
		(width 0.0889)
		(layer "In13.Cu")
		(net "P5E_CPU1_PE0_RX_DP<9>")
	)
	(arc
		(start 96.508316 -213.930484)
		(mid 96.515601 -213.950046)
		(end 96.523556 -213.969346)
		(width 0.0889)
		(layer "In13.Cu")
		(net "P5E_CPU1_PE0_RX_DP<9>")
	)
	(arc
		(start 97.447862 -217.072972)
		(mid 97.395592 -217.255337)
		(end 97.260664 -217.388694)
		(width 0.0889)
		(layer "In13.Cu")
		(net "P5E_CPU1_PE0_RX_DP<9>")
	)
	(arc
		(start 97.260664 -219.995496)
		(mid 97.395597 -220.12885)
		(end 97.447862 -220.311218)
		(width 0.0889)
		(layer "In13.Cu")
		(net "P5E_CPU1_PE0_RX_DP<9>")
	)
	(arc
		(start 96.977708 -214.622634)
		(mid 96.977656 -214.630001)
		(end 96.977454 -214.637366)
		(width 0.0889)
		(layer "In13.Cu")
		(net "P5E_CPU1_PE0_RX_DP<9>")
	)
	(arc
		(start 97.260664 -216.739978)
		(mid 97.395597 -216.873332)
		(end 97.447862 -217.0557)
		(width 0.0889)
		(layer "In13.Cu")
		(net "P5E_CPU1_PE0_RX_DP<9>")
	)
	(arc
		(start 97.2693 -218.372944)
		(mid 97.447776 -218.692222)
		(end 97.2693 -219.0115)
		(width 0.0889)
		(layer "In13.Cu")
		(net "P5E_CPU1_PE0_RX_DP<9>")
	)
	(arc
		(start 96.978216 -216.260426)
		(mid 97.056327 -216.537375)
		(end 97.260664 -216.739978)
		(width 0.0889)
		(layer "In13.Cu")
		(net "P5E_CPU1_PE0_RX_DP<9>")
	)
	(arc
		(start 96.508062 -215.436704)
		(mid 96.582053 -215.71627)
		(end 96.784668 -215.922606)
		(width 0.0889)
		(layer "In13.Cu")
		(net "P5E_CPU1_PE0_RX_DP<9>")
	)
	(arc
		(start 96.790256 -214.946992)
		(mid 96.588974 -215.144479)
		(end 96.508062 -215.414606)
		(width 0.0889)
		(layer "In13.Cu")
		(net "P5E_CPU1_PE0_RX_DP<9>")
	)
	(arc
		(start 96.523556 -213.969346)
		(mid 96.63355 -214.138715)
		(end 96.793558 -214.261954)
		(width 0.0889)
		(layer "In13.Cu")
		(net "P5E_CPU1_PE0_RX_DP<9>")
	)
	(arc
		(start 96.978216 -217.8939)
		(mid 97.057586 -218.167634)
		(end 97.26041 -218.367864)
		(width 0.0889)
		(layer "In13.Cu")
		(net "P5E_CPU1_PE0_RX_DP<9>")
	)
	(arc
		(start 97.447862 -220.334078)
		(mid 97.506156 -220.570721)
		(end 97.658682 -220.760798)
		(width 0.0889)
		(layer "In13.Cu")
		(net "P5E_CPU1_PE0_RX_DP<9>")
	)
	(arc
		(start 97.260664 -217.388694)
		(mid 97.058378 -217.587675)
		(end 96.978216 -217.859864)
		(width 0.0889)
		(layer "In13.Cu")
		(net "P5E_CPU1_PE0_RX_DP<9>")
	)
	(arc
		(start 97.658682 -220.760798)
		(mid 97.66713 -220.767355)
		(end 97.6757 -220.773752)
		(width 0.0889)
		(layer "In13.Cu")
		(net "P5E_CPU1_PE0_RX_DP<9>")
	)
	(arc
		(start 96.978216 -219.515944)
		(mid 97.056327 -219.792893)
		(end 97.260664 -219.995496)
		(width 0.0889)
		(layer "In13.Cu")
		(net "P5E_CPU1_PE0_RX_DP<9>")
	)
	(segment
		(start 97.073212 -222.483426)
		(end 97.073212 -221.94774)
		(width 0.13208)
		(layer "F.Cu")
		(net "P5E_CPU1_PE0_RX_DP<8>")
	)
	(segment
		(start 97.073466 -222.48368)
		(end 97.073212 -222.483426)
		(width 0.13208)
		(layer "F.Cu")
		(net "P5E_CPU1_PE0_RX_DP<8>")
	)
	(segment
		(start 71.19493 -393.327636)
		(end 71.309484 -393.194032)
		(width 0.14732)
		(layer "In13.Cu")
		(net "P5E_CPU1_PE0_RX_DP<8>")
	)
	(segment
		(start 72.650096 -438.152286)
		(end 72.482964 -438.319418)
		(width 0.14732)
		(layer "In13.Cu")
		(net "P5E_CPU1_PE0_RX_DP<8>")
	)
	(segment
		(start 71.569072 -398.146016)
		(end 71.683626 -398.012412)
		(width 0.14732)
		(layer "In13.Cu")
		(net "P5E_CPU1_PE0_RX_DP<8>")
	)
	(segment
		(start 71.515732 -397.461994)
		(end 71.47433 -396.924784)
		(width 0.14732)
		(layer "In13.Cu")
		(net "P5E_CPU1_PE0_RX_DP<8>")
	)
	(segment
		(start 78.155292 -218.31046)
		(end 81.34858 -214.206074)
		(width 0.14732)
		(layer "In13.Cu")
		(net "P5E_CPU1_PE0_RX_DP<8>")
	)
	(segment
		(start 71.523098 -400.647662)
		(end 71.655178 -399.25879)
		(width 0.14732)
		(layer "In13.Cu")
		(net "P5E_CPU1_PE0_RX_DP<8>")
	)
	(segment
		(start 73.580244 -252.66777)
		(end 73.580244 -252.495304)
		(width 0.14732)
		(layer "In13.Cu")
		(net "P5E_CPU1_PE0_RX_DP<8>")
	)
	(segment
		(start 72.079612 -438.319418)
		(end 71.955152 -438.194958)
		(width 0.14732)
		(layer "In13.Cu")
		(net "P5E_CPU1_PE0_RX_DP<8>")
	)
	(segment
		(start 95.526352 -213.07425)
		(end 95.526352 -213.096348)
		(width 0.0889)
		(layer "In13.Cu")
		(net "P5E_CPU1_PE0_RX_DP<8>")
	)
	(segment
		(start 96.3295 -219.0115)
		(end 96.32061 -219.01658)
		(width 0.0889)
		(layer "In13.Cu")
		(net "P5E_CPU1_PE0_RX_DP<8>")
	)
	(segment
		(start 95.568262 -215.414606)
		(end 95.568262 -215.43264)
		(width 0.0889)
		(layer "In13.Cu")
		(net "P5E_CPU1_PE0_RX_DP<8>")
	)
	(segment
		(start 95.568516 -213.138512)
		(end 95.568516 -213.930484)
		(width 0.0889)
		(layer "In13.Cu")
		(net "P5E_CPU1_PE0_RX_DP<8>")
	)
	(segment
		(start 93.761306 -210.904836)
		(end 94.629478 -211.2645)
		(width 0.14732)
		(layer "In13.Cu")
		(net "P5E_CPU1_PE0_RX_DP<8>")
	)
	(segment
		(start 96.3295 -217.383614)
		(end 96.32061 -217.388694)
		(width 0.0889)
		(layer "In13.Cu")
		(net "P5E_CPU1_PE0_RX_DP<8>")
	)
	(segment
		(start 95.84944 -215.924892)
		(end 95.855536 -215.928702)
		(width 0.0889)
		(layer "In13.Cu")
		(net "P5E_CPU1_PE0_RX_DP<8>")
	)
	(segment
		(start 96.916748 -221.676722)
		(end 97.073212 -221.94774)
		(width 0.0889)
		(layer "In13.Cu")
		(net "P5E_CPU1_PE0_RX_DP<8>")
	)
	(segment
		(start 71.116444 -390.70407)
		(end 71.082662 -390.268206)
		(width 0.14732)
		(layer "In13.Cu")
		(net "P5E_CPU1_PE0_RX_DP<8>")
	)
	(segment
		(start 71.373492 -394.015976)
		(end 71.23938 -393.901676)
		(width 0.14732)
		(layer "In13.Cu")
		(net "P5E_CPU1_PE0_RX_DP<8>")
	)
	(segment
		(start 96.32061 -218.367864)
		(end 96.3295 -218.372944)
		(width 0.0889)
		(layer "In13.Cu")
		(net "P5E_CPU1_PE0_RX_DP<8>")
	)
	(segment
		(start 95.568516 -215.436958)
		(end 95.568516 -215.459564)
		(width 0.0889)
		(layer "In13.Cu")
		(net "P5E_CPU1_PE0_RX_DP<8>")
	)
	(segment
		(start 96.32061 -216.739978)
		(end 96.321626 -216.740486)
		(width 0.0889)
		(layer "In13.Cu")
		(net "P5E_CPU1_PE0_RX_DP<8>")
	)
	(segment
		(start 95.819214 -215.906858)
		(end 95.84944 -215.924892)
		(width 0.0889)
		(layer "In13.Cu")
		(net "P5E_CPU1_PE0_RX_DP<8>")
	)
	(segment
		(start 73.113138 -319.39992)
		(end 77.201014 -309.73268)
		(width 0.14732)
		(layer "In13.Cu")
		(net "P5E_CPU1_PE0_RX_DP<8>")
	)
	(segment
		(start 96.038416 -219.490544)
		(end 96.038416 -219.521532)
		(width 0.0889)
		(layer "In13.Cu")
		(net "P5E_CPU1_PE0_RX_DP<8>")
	)
	(segment
		(start 70.908926 -388.02945)
		(end 70.775068 -387.91515)
		(width 0.14732)
		(layer "In13.Cu")
		(net "P5E_CPU1_PE0_RX_DP<8>")
	)
	(segment
		(start 71.380858 -395.72057)
		(end 71.495158 -395.586966)
		(width 0.14732)
		(layer "In13.Cu")
		(net "P5E_CPU1_PE0_RX_DP<8>")
	)
	(segment
		(start 73.580244 -252.495304)
		(end 73.65619 -250.236736)
		(width 0.14732)
		(layer "In13.Cu")
		(net "P5E_CPU1_PE0_RX_DP<8>")
	)
	(segment
		(start 70.942708 -388.465314)
		(end 70.908926 -388.02945)
		(width 0.14732)
		(layer "In13.Cu")
		(net "P5E_CPU1_PE0_RX_DP<8>")
	)
	(segment
		(start 96.038416 -221.111826)
		(end 96.038416 -221.149418)
		(width 0.0889)
		(layer "In13.Cu")
		(net "P5E_CPU1_PE0_RX_DP<8>")
	)
	(segment
		(start 69.806058 -410.333444)
		(end 69.806058 -406.313132)
		(width 0.14732)
		(layer "In13.Cu")
		(net "P5E_CPU1_PE0_RX_DP<8>")
	)
	(segment
		(start 96.321626 -216.740486)
		(end 96.3295 -216.745058)
		(width 0.0889)
		(layer "In13.Cu")
		(net "P5E_CPU1_PE0_RX_DP<8>")
	)
	(segment
		(start 96.038416 -216.25052)
		(end 96.038416 -216.266014)
		(width 0.0889)
		(layer "In13.Cu")
		(net "P5E_CPU1_PE0_RX_DP<8>")
	)
	(segment
		(start 71.002144 -390.837928)
		(end 71.116444 -390.70407)
		(width 0.14732)
		(layer "In13.Cu")
		(net "P5E_CPU1_PE0_RX_DP<8>")
	)
	(segment
		(start 71.955152 -438.194958)
		(end 71.955152 -416.946588)
		(width 0.14732)
		(layer "In13.Cu")
		(net "P5E_CPU1_PE0_RX_DP<8>")
	)
	(segment
		(start 70.775068 -387.91515)
		(end 70.77583 -387.914642)
		(width 0.14732)
		(layer "In13.Cu")
		(net "P5E_CPU1_PE0_RX_DP<8>")
	)
	(segment
		(start 96.037908 -214.461344)
		(end 96.037908 -214.622634)
		(width 0.0889)
		(layer "In13.Cu")
		(net "P5E_CPU1_PE0_RX_DP<8>")
	)
	(segment
		(start 70.915276 -389.71855)
		(end 71.029576 -389.584692)
		(width 0.14732)
		(layer "In13.Cu")
		(net "P5E_CPU1_PE0_RX_DP<8>")
	)
	(segment
		(start 71.275702 -392.758168)
		(end 71.141844 -392.643614)
		(width 0.14732)
		(layer "In13.Cu")
		(net "P5E_CPU1_PE0_RX_DP<8>")
	)
	(segment
		(start 71.495158 -395.586966)
		(end 71.46163 -395.151102)
		(width 0.14732)
		(layer "In13.Cu")
		(net "P5E_CPU1_PE0_RX_DP<8>")
	)
	(segment
		(start 70.828408 -388.599172)
		(end 70.942708 -388.465314)
		(width 0.14732)
		(layer "In13.Cu")
		(net "P5E_CPU1_PE0_RX_DP<8>")
	)
	(segment
		(start 75.049634 -233.16311)
		(end 77.011022 -220.529912)
		(width 0.14732)
		(layer "In13.Cu")
		(net "P5E_CPU1_PE0_RX_DP<8>")
	)
	(segment
		(start 95.526352 -213.096348)
		(end 95.568516 -213.138512)
		(width 0.0889)
		(layer "In13.Cu")
		(net "P5E_CPU1_PE0_RX_DP<8>")
	)
	(segment
		(start 67.603878 -330.258928)
		(end 70.638416 -322.933314)
		(width 0.14732)
		(layer "In13.Cu")
		(net "P5E_CPU1_PE0_RX_DP<8>")
	)
	(segment
		(start 96.038416 -217.856308)
		(end 96.038416 -217.8939)
		(width 0.0889)
		(layer "In13.Cu")
		(net "P5E_CPU1_PE0_RX_DP<8>")
	)
	(segment
		(start 71.523098 -404.596092)
		(end 71.523098 -400.647662)
		(width 0.14732)
		(layer "In13.Cu")
		(net "P5E_CPU1_PE0_RX_DP<8>")
	)
	(segment
		(start 71.203312 -391.823702)
		(end 71.16953 -391.387838)
		(width 0.14732)
		(layer "In13.Cu")
		(net "P5E_CPU1_PE0_RX_DP<8>")
	)
	(segment
		(start 90.00363 -210.904836)
		(end 93.761306 -210.904836)
		(width 0.14732)
		(layer "In13.Cu")
		(net "P5E_CPU1_PE0_RX_DP<8>")
	)
	(segment
		(start 71.42099 -396.240762)
		(end 71.380858 -395.72057)
		(width 0.14732)
		(layer "In13.Cu")
		(net "P5E_CPU1_PE0_RX_DP<8>")
	)
	(segment
		(start 71.683626 -398.012412)
		(end 71.649844 -397.576548)
		(width 0.14732)
		(layer "In13.Cu")
		(net "P5E_CPU1_PE0_RX_DP<8>")
	)
	(segment
		(start 96.827848 -221.6531)
		(end 96.916748 -221.676722)
		(width 0.0889)
		(layer "In13.Cu")
		(net "P5E_CPU1_PE0_RX_DP<8>")
	)
	(segment
		(start 96.3295 -220.639132)
		(end 96.32061 -220.644212)
		(width 0.0889)
		(layer "In13.Cu")
		(net "P5E_CPU1_PE0_RX_DP<8>")
	)
	(segment
		(start 71.035672 -391.273284)
		(end 71.002144 -390.837928)
		(width 0.14732)
		(layer "In13.Cu")
		(net "P5E_CPU1_PE0_RX_DP<8>")
	)
	(segment
		(start 71.47433 -396.924784)
		(end 71.58863 -396.79118)
		(width 0.14732)
		(layer "In13.Cu")
		(net "P5E_CPU1_PE0_RX_DP<8>")
	)
	(segment
		(start 70.638416 -322.933314)
		(end 73.113138 -319.39992)
		(width 0.14732)
		(layer "In13.Cu")
		(net "P5E_CPU1_PE0_RX_DP<8>")
	)
	(segment
		(start 72.482964 -438.319418)
		(end 72.079612 -438.319418)
		(width 0.14732)
		(layer "In13.Cu")
		(net "P5E_CPU1_PE0_RX_DP<8>")
	)
	(segment
		(start 71.554848 -396.355316)
		(end 71.42099 -396.240762)
		(width 0.14732)
		(layer "In13.Cu")
		(net "P5E_CPU1_PE0_RX_DP<8>")
	)
	(segment
		(start 70.948804 -390.153906)
		(end 70.915276 -389.71855)
		(width 0.14732)
		(layer "In13.Cu")
		(net "P5E_CPU1_PE0_RX_DP<8>")
	)
	(segment
		(start 71.58863 -396.79118)
		(end 71.554848 -396.355316)
		(width 0.14732)
		(layer "In13.Cu")
		(net "P5E_CPU1_PE0_RX_DP<8>")
	)
	(segment
		(start 71.46163 -395.151102)
		(end 71.327518 -395.036548)
		(width 0.14732)
		(layer "In13.Cu")
		(net "P5E_CPU1_PE0_RX_DP<8>")
	)
	(segment
		(start 67.603878 -346.982288)
		(end 67.603878 -330.258928)
		(width 0.14732)
		(layer "In13.Cu")
		(net "P5E_CPU1_PE0_RX_DP<8>")
	)
	(segment
		(start 70.861936 -389.034528)
		(end 70.828408 -388.599172)
		(width 0.14732)
		(layer "In13.Cu")
		(net "P5E_CPU1_PE0_RX_DP<8>")
	)
	(segment
		(start 77.201014 -309.73268)
		(end 73.580244 -252.66777)
		(width 0.14732)
		(layer "In13.Cu")
		(net "P5E_CPU1_PE0_RX_DP<8>")
	)
	(segment
		(start 71.088758 -391.957306)
		(end 71.203312 -391.823702)
		(width 0.14732)
		(layer "In13.Cu")
		(net "P5E_CPU1_PE0_RX_DP<8>")
	)
	(segment
		(start 72.650096 -437.889904)
		(end 72.650096 -438.152286)
		(width 0.14732)
		(layer "In13.Cu")
		(net "P5E_CPU1_PE0_RX_DP<8>")
	)
	(segment
		(start 94.629478 -211.2645)
		(end 95.184214 -211.819236)
		(width 0.14732)
		(layer "In13.Cu")
		(net "P5E_CPU1_PE0_RX_DP<8>")
	)
	(segment
		(start 71.955152 -416.946588)
		(end 69.806058 -410.333444)
		(width 0.14732)
		(layer "In13.Cu")
		(net "P5E_CPU1_PE0_RX_DP<8>")
	)
	(segment
		(start 95.184214 -211.819236)
		(end 95.526352 -212.645244)
		(width 0.14732)
		(layer "In13.Cu")
		(net "P5E_CPU1_PE0_RX_DP<8>")
	)
	(segment
		(start 95.526352 -212.645244)
		(end 95.526352 -213.07425)
		(width 0.14732)
		(layer "In13.Cu")
		(net "P5E_CPU1_PE0_RX_DP<8>")
	)
	(segment
		(start 71.327518 -395.036548)
		(end 71.29272 -394.585698)
		(width 0.14732)
		(layer "In13.Cu")
		(net "P5E_CPU1_PE0_RX_DP<8>")
	)
	(segment
		(start 96.32061 -219.995496)
		(end 96.321626 -219.996004)
		(width 0.0889)
		(layer "In13.Cu")
		(net "P5E_CPU1_PE0_RX_DP<8>")
	)
	(segment
		(start 71.655178 -399.25879)
		(end 71.569072 -398.146016)
		(width 0.14732)
		(layer "In13.Cu")
		(net "P5E_CPU1_PE0_RX_DP<8>")
	)
	(segment
		(start 71.309484 -393.194032)
		(end 71.275702 -392.758168)
		(width 0.14732)
		(layer "In13.Cu")
		(net "P5E_CPU1_PE0_RX_DP<8>")
	)
	(segment
		(start 73.65619 -250.236736)
		(end 75.049634 -233.16311)
		(width 0.14732)
		(layer "In13.Cu")
		(net "P5E_CPU1_PE0_RX_DP<8>")
	)
	(segment
		(start 71.649844 -397.576548)
		(end 71.515732 -397.461994)
		(width 0.14732)
		(layer "In13.Cu")
		(net "P5E_CPU1_PE0_RX_DP<8>")
	)
	(segment
		(start 71.141844 -392.643614)
		(end 71.088758 -391.957306)
		(width 0.14732)
		(layer "In13.Cu")
		(net "P5E_CPU1_PE0_RX_DP<8>")
	)
	(segment
		(start 96.321626 -219.996004)
		(end 96.3295 -220.000576)
		(width 0.0889)
		(layer "In13.Cu")
		(net "P5E_CPU1_PE0_RX_DP<8>")
	)
	(segment
		(start 71.407274 -394.45184)
		(end 71.373492 -394.015976)
		(width 0.14732)
		(layer "In13.Cu")
		(net "P5E_CPU1_PE0_RX_DP<8>")
	)
	(segment
		(start 71.029576 -389.584692)
		(end 70.995794 -389.148828)
		(width 0.14732)
		(layer "In13.Cu")
		(net "P5E_CPU1_PE0_RX_DP<8>")
	)
	(segment
		(start 95.859346 -214.941912)
		(end 95.850456 -214.946992)
		(width 0.0889)
		(layer "In13.Cu")
		(net "P5E_CPU1_PE0_RX_DP<8>")
	)
	(segment
		(start 71.23938 -393.901676)
		(end 71.19493 -393.327636)
		(width 0.14732)
		(layer "In13.Cu")
		(net "P5E_CPU1_PE0_RX_DP<8>")
	)
	(segment
		(start 70.995794 -389.148828)
		(end 70.861936 -389.034528)
		(width 0.14732)
		(layer "In13.Cu")
		(net "P5E_CPU1_PE0_RX_DP<8>")
	)
	(segment
		(start 71.082662 -390.268206)
		(end 70.948804 -390.153906)
		(width 0.14732)
		(layer "In13.Cu")
		(net "P5E_CPU1_PE0_RX_DP<8>")
	)
	(segment
		(start 70.77583 -387.914642)
		(end 67.603878 -346.982288)
		(width 0.14732)
		(layer "In13.Cu")
		(net "P5E_CPU1_PE0_RX_DP<8>")
	)
	(segment
		(start 71.29272 -394.585698)
		(end 71.407274 -394.45184)
		(width 0.14732)
		(layer "In13.Cu")
		(net "P5E_CPU1_PE0_RX_DP<8>")
	)
	(segment
		(start 69.806058 -406.313132)
		(end 71.523098 -404.596092)
		(width 0.14732)
		(layer "In13.Cu")
		(net "P5E_CPU1_PE0_RX_DP<8>")
	)
	(segment
		(start 77.011022 -220.529912)
		(end 78.155292 -218.31046)
		(width 0.14732)
		(layer "In13.Cu")
		(net "P5E_CPU1_PE0_RX_DP<8>")
	)
	(segment
		(start 82.688176 -213.107778)
		(end 90.00363 -210.904836)
		(width 0.14732)
		(layer "In13.Cu")
		(net "P5E_CPU1_PE0_RX_DP<8>")
	)
	(segment
		(start 81.34858 -214.206074)
		(end 82.688176 -213.107778)
		(width 0.14732)
		(layer "In13.Cu")
		(net "P5E_CPU1_PE0_RX_DP<8>")
	)
	(segment
		(start 71.16953 -391.387838)
		(end 71.035672 -391.273284)
		(width 0.14732)
		(layer "In13.Cu")
		(net "P5E_CPU1_PE0_RX_DP<8>")
	)
	(arc
		(start 96.3295 -216.745058)
		(mid 96.508097 -217.064336)
		(end 96.3295 -217.383614)
		(width 0.0889)
		(layer "In13.Cu")
		(net "P5E_CPU1_PE0_RX_DP<8>")
	)
	(arc
		(start 95.855536 -215.928702)
		(mid 95.88414 -215.947635)
		(end 95.910908 -215.969088)
		(width 0.0889)
		(layer "In13.Cu")
		(net "P5E_CPU1_PE0_RX_DP<8>")
	)
	(arc
		(start 96.038416 -216.266014)
		(mid 96.117786 -216.539748)
		(end 96.32061 -216.739978)
		(width 0.0889)
		(layer "In13.Cu")
		(net "P5E_CPU1_PE0_RX_DP<8>")
	)
	(arc
		(start 96.038416 -217.8939)
		(mid 96.117786 -218.167634)
		(end 96.32061 -218.367864)
		(width 0.0889)
		(layer "In13.Cu")
		(net "P5E_CPU1_PE0_RX_DP<8>")
	)
	(arc
		(start 95.910908 -215.969088)
		(mid 96.005063 -216.09604)
		(end 96.038416 -216.25052)
		(width 0.0889)
		(layer "In13.Cu")
		(net "P5E_CPU1_PE0_RX_DP<8>")
	)
	(arc
		(start 96.32061 -221.623382)
		(mid 96.570705 -221.698543)
		(end 96.827848 -221.6531)
		(width 0.0889)
		(layer "In13.Cu")
		(net "P5E_CPU1_PE0_RX_DP<8>")
	)
	(arc
		(start 96.3295 -218.372944)
		(mid 96.507976 -218.692222)
		(end 96.3295 -219.0115)
		(width 0.0889)
		(layer "In13.Cu")
		(net "P5E_CPU1_PE0_RX_DP<8>")
	)
	(arc
		(start 95.853758 -214.261954)
		(mid 95.962905 -214.345882)
		(end 96.037908 -214.461344)
		(width 0.0889)
		(layer "In13.Cu")
		(net "P5E_CPU1_PE0_RX_DP<8>")
	)
	(arc
		(start 96.32061 -219.01658)
		(mid 96.117787 -219.216811)
		(end 96.038416 -219.490544)
		(width 0.0889)
		(layer "In13.Cu")
		(net "P5E_CPU1_PE0_RX_DP<8>")
	)
	(arc
		(start 96.32061 -220.644212)
		(mid 96.119328 -220.841699)
		(end 96.038416 -221.111826)
		(width 0.0889)
		(layer "In13.Cu")
		(net "P5E_CPU1_PE0_RX_DP<8>")
	)
	(arc
		(start 96.3295 -220.000576)
		(mid 96.508097 -220.319854)
		(end 96.3295 -220.639132)
		(width 0.0889)
		(layer "In13.Cu")
		(net "P5E_CPU1_PE0_RX_DP<8>")
	)
	(arc
		(start 95.568262 -215.43264)
		(mid 95.568385 -215.434799)
		(end 95.568516 -215.436958)
		(width 0.0889)
		(layer "In13.Cu")
		(net "P5E_CPU1_PE0_RX_DP<8>")
	)
	(arc
		(start 95.583756 -213.969346)
		(mid 95.69375 -214.138715)
		(end 95.853758 -214.261954)
		(width 0.0889)
		(layer "In13.Cu")
		(net "P5E_CPU1_PE0_RX_DP<8>")
	)
	(arc
		(start 96.32061 -217.388694)
		(mid 96.119328 -217.586181)
		(end 96.038416 -217.856308)
		(width 0.0889)
		(layer "In13.Cu")
		(net "P5E_CPU1_PE0_RX_DP<8>")
	)
	(arc
		(start 95.568516 -213.930484)
		(mid 95.575801 -213.950046)
		(end 95.583756 -213.969346)
		(width 0.0889)
		(layer "In13.Cu")
		(net "P5E_CPU1_PE0_RX_DP<8>")
	)
	(arc
		(start 96.038416 -219.521532)
		(mid 96.117786 -219.795266)
		(end 96.32061 -219.995496)
		(width 0.0889)
		(layer "In13.Cu")
		(net "P5E_CPU1_PE0_RX_DP<8>")
	)
	(arc
		(start 96.037908 -214.622634)
		(mid 95.990229 -214.805534)
		(end 95.859346 -214.941912)
		(width 0.0889)
		(layer "In13.Cu")
		(net "P5E_CPU1_PE0_RX_DP<8>")
	)
	(arc
		(start 96.038416 -221.149418)
		(mid 96.117786 -221.423152)
		(end 96.32061 -221.623382)
		(width 0.0889)
		(layer "In13.Cu")
		(net "P5E_CPU1_PE0_RX_DP<8>")
	)
	(arc
		(start 95.568516 -215.459564)
		(mid 95.6354 -215.715985)
		(end 95.819214 -215.906858)
		(width 0.0889)
		(layer "In13.Cu")
		(net "P5E_CPU1_PE0_RX_DP<8>")
	)
	(arc
		(start 95.850456 -214.946992)
		(mid 95.649174 -215.144479)
		(end 95.568262 -215.414606)
		(width 0.0889)
		(layer "In13.Cu")
		(net "P5E_CPU1_PE0_RX_DP<8>")
	)
	(segment
		(start 95.663512 -221.134178)
		(end 95.663766 -221.133924)
		(width 0.13208)
		(layer "F.Cu")
		(net "P5E_CPU1_PE0_RX_DP<7>")
	)
	(segment
		(start 95.663512 -221.669864)
		(end 95.663512 -221.134178)
		(width 0.13208)
		(layer "F.Cu")
		(net "P5E_CPU1_PE0_RX_DP<7>")
	)
	(segment
		(start 94.628716 -213.929722)
		(end 94.62897 -213.929468)
		(width 0.0889)
		(layer "In13.Cu")
		(net "P5E_CPU1_PE0_RX_DP<7>")
	)
	(segment
		(start 73.101708 -390.062466)
		(end 72.992742 -390.19607)
		(width 0.14732)
		(layer "In13.Cu")
		(net "P5E_CPU1_PE0_RX_DP<7>")
	)
	(segment
		(start 73.961498 -319.898268)
		(end 71.430642 -323.511926)
		(width 0.14732)
		(layer "In13.Cu")
		(net "P5E_CPU1_PE0_RX_DP<7>")
	)
	(segment
		(start 74.517504 -398.706594)
		(end 74.398632 -398.873218)
		(width 0.14732)
		(layer "In13.Cu")
		(net "P5E_CPU1_PE0_RX_DP<7>")
	)
	(segment
		(start 95.663766 -221.133924)
		(end 95.82023 -220.862906)
		(width 0.0889)
		(layer "In13.Cu")
		(net "P5E_CPU1_PE0_RX_DP<7>")
	)
	(segment
		(start 90.04427 -211.920328)
		(end 89.269824 -212.1535)
		(width 0.14732)
		(layer "In13.Cu")
		(net "P5E_CPU1_PE0_RX_DP<7>")
	)
	(segment
		(start 68.560188 -330.441808)
		(end 68.560188 -346.93225)
		(width 0.14732)
		(layer "In13.Cu")
		(net "P5E_CPU1_PE0_RX_DP<7>")
	)
	(segment
		(start 94.628716 -213.930484)
		(end 94.628716 -213.929722)
		(width 0.0889)
		(layer "In13.Cu")
		(net "P5E_CPU1_PE0_RX_DP<7>")
	)
	(segment
		(start 95.82023 -220.862906)
		(end 95.7961 -220.773752)
		(width 0.0889)
		(layer "In13.Cu")
		(net "P5E_CPU1_PE0_RX_DP<7>")
	)
	(segment
		(start 94.62897 -213.929468)
		(end 94.62897 -213.171532)
		(width 0.0889)
		(layer "In13.Cu")
		(net "P5E_CPU1_PE0_RX_DP<7>")
	)
	(segment
		(start 79.015082 -218.858846)
		(end 77.989176 -220.848682)
		(width 0.14732)
		(layer "In13.Cu")
		(net "P5E_CPU1_PE0_RX_DP<7>")
	)
	(segment
		(start 72.762618 -387.952234)
		(end 72.8091 -388.40664)
		(width 0.14732)
		(layer "In13.Cu")
		(net "P5E_CPU1_PE0_RX_DP<7>")
	)
	(segment
		(start 74.121264 -397.212058)
		(end 74.288142 -397.33093)
		(width 0.14732)
		(layer "In13.Cu")
		(net "P5E_CPU1_PE0_RX_DP<7>")
	)
	(segment
		(start 77.989176 -220.848682)
		(end 76.079096 -233.150918)
		(width 0.14732)
		(layer "In13.Cu")
		(net "P5E_CPU1_PE0_RX_DP<7>")
	)
	(segment
		(start 94.586806 -212.86851)
		(end 94.367604 -212.339174)
		(width 0.14732)
		(layer "In13.Cu")
		(net "P5E_CPU1_PE0_RX_DP<7>")
	)
	(segment
		(start 74.586338 -404.596092)
		(end 72.869298 -406.313132)
		(width 0.14732)
		(layer "In13.Cu")
		(net "P5E_CPU1_PE0_RX_DP<7>")
	)
	(segment
		(start 72.992742 -390.19607)
		(end 73.05929 -390.845802)
		(width 0.14732)
		(layer "In13.Cu")
		(net "P5E_CPU1_PE0_RX_DP<7>")
	)
	(segment
		(start 94.910656 -214.946992)
		(end 94.919546 -214.941912)
		(width 0.0889)
		(layer "In13.Cu")
		(net "P5E_CPU1_PE0_RX_DP<7>")
	)
	(segment
		(start 94.586806 -213.129368)
		(end 94.586806 -213.10727)
		(width 0.0889)
		(layer "In13.Cu")
		(net "P5E_CPU1_PE0_RX_DP<7>")
	)
	(segment
		(start 76.079096 -233.150918)
		(end 74.577956 -250.498356)
		(width 0.14732)
		(layer "In13.Cu")
		(net "P5E_CPU1_PE0_RX_DP<7>")
	)
	(segment
		(start 94.912688 -215.926924)
		(end 94.911164 -215.926162)
		(width 0.0889)
		(layer "In13.Cu")
		(net "P5E_CPU1_PE0_RX_DP<7>")
	)
	(segment
		(start 73.05929 -390.846564)
		(end 73.222866 -391.828274)
		(width 0.14732)
		(layer "In13.Cu")
		(net "P5E_CPU1_PE0_RX_DP<7>")
	)
	(segment
		(start 72.923146 -389.518652)
		(end 73.057258 -389.627618)
		(width 0.14732)
		(layer "In13.Cu")
		(net "P5E_CPU1_PE0_RX_DP<7>")
	)
	(segment
		(start 95.568262 -217.072972)
		(end 95.568262 -217.0557)
		(width 0.0889)
		(layer "In13.Cu")
		(net "P5E_CPU1_PE0_RX_DP<7>")
	)
	(segment
		(start 73.947782 -396.172944)
		(end 74.11466 -396.29207)
		(width 0.14732)
		(layer "In13.Cu")
		(net "P5E_CPU1_PE0_RX_DP<7>")
	)
	(segment
		(start 68.560188 -346.93225)
		(end 68.560442 -346.932504)
		(width 0.14732)
		(layer "In13.Cu")
		(net "P5E_CPU1_PE0_RX_DP<7>")
	)
	(segment
		(start 83.238848 -213.969854)
		(end 82.080354 -214.91956)
		(width 0.14732)
		(layer "In13.Cu")
		(net "P5E_CPU1_PE0_RX_DP<7>")
	)
	(segment
		(start 72.987662 -388.950454)
		(end 72.878696 -389.084058)
		(width 0.14732)
		(layer "In13.Cu")
		(net "P5E_CPU1_PE0_RX_DP<7>")
	)
	(segment
		(start 74.11466 -396.29207)
		(end 74.175366 -396.655544)
		(width 0.14732)
		(layer "In13.Cu")
		(net "P5E_CPU1_PE0_RX_DP<7>")
	)
	(segment
		(start 74.000106 -395.605762)
		(end 73.88098 -395.772386)
		(width 0.14732)
		(layer "In13.Cu")
		(net "P5E_CPU1_PE0_RX_DP<7>")
	)
	(segment
		(start 73.88098 -395.772386)
		(end 73.947782 -396.172944)
		(width 0.14732)
		(layer "In13.Cu")
		(net "P5E_CPU1_PE0_RX_DP<7>")
	)
	(segment
		(start 89.269824 -212.1535)
		(end 89.18829 -212.305646)
		(width 0.14732)
		(layer "In13.Cu")
		(net "P5E_CPU1_PE0_RX_DP<7>")
	)
	(segment
		(start 73.699116 -394.68171)
		(end 73.772522 -395.123162)
		(width 0.14732)
		(layer "In13.Cu")
		(net "P5E_CPU1_PE0_RX_DP<7>")
	)
	(segment
		(start 68.560442 -346.932758)
		(end 68.561712 -346.932758)
		(width 0.14732)
		(layer "In13.Cu")
		(net "P5E_CPU1_PE0_RX_DP<7>")
	)
	(segment
		(start 94.367604 -212.339174)
		(end 94.095316 -212.066886)
		(width 0.14732)
		(layer "In13.Cu")
		(net "P5E_CPU1_PE0_RX_DP<7>")
	)
	(segment
		(start 95.3897 -218.372944)
		(end 95.381826 -218.368372)
		(width 0.0889)
		(layer "In13.Cu")
		(net "P5E_CPU1_PE0_RX_DP<7>")
	)
	(segment
		(start 74.954892 -437.19496)
		(end 75.079352 -437.31942)
		(width 0.14732)
		(layer "In13.Cu")
		(net "P5E_CPU1_PE0_RX_DP<7>")
	)
	(segment
		(start 73.45807 -393.236704)
		(end 73.457562 -393.236704)
		(width 0.14732)
		(layer "In13.Cu")
		(net "P5E_CPU1_PE0_RX_DP<7>")
	)
	(segment
		(start 94.62897 -213.171532)
		(end 94.586806 -213.129368)
		(width 0.0889)
		(layer "In13.Cu")
		(net "P5E_CPU1_PE0_RX_DP<7>")
	)
	(segment
		(start 95.381826 -218.368372)
		(end 95.38081 -218.367864)
		(width 0.0889)
		(layer "In13.Cu")
		(net "P5E_CPU1_PE0_RX_DP<7>")
	)
	(segment
		(start 68.561966 -346.932504)
		(end 72.693784 -387.274816)
		(width 0.14732)
		(layer "In13.Cu")
		(net "P5E_CPU1_PE0_RX_DP<7>")
	)
	(segment
		(start 72.827134 -387.383782)
		(end 72.871584 -387.81863)
		(width 0.14732)
		(layer "In13.Cu")
		(net "P5E_CPU1_PE0_RX_DP<7>")
	)
	(segment
		(start 74.398632 -398.873218)
		(end 74.586338 -399.99793)
		(width 0.14732)
		(layer "In13.Cu")
		(net "P5E_CPU1_PE0_RX_DP<7>")
	)
	(segment
		(start 93.741748 -211.920328)
		(end 90.04427 -211.920328)
		(width 0.14732)
		(layer "In13.Cu")
		(net "P5E_CPU1_PE0_RX_DP<7>")
	)
	(segment
		(start 74.577956 -250.498356)
		(end 74.514456 -252.38583)
		(width 0.14732)
		(layer "In13.Cu")
		(net "P5E_CPU1_PE0_RX_DP<7>")
	)
	(segment
		(start 74.954892 -424.905932)
		(end 74.954892 -437.19496)
		(width 0.14732)
		(layer "In13.Cu")
		(net "P5E_CPU1_PE0_RX_DP<7>")
	)
	(segment
		(start 68.561712 -346.932758)
		(end 68.561966 -346.932504)
		(width 0.14732)
		(layer "In13.Cu")
		(net "P5E_CPU1_PE0_RX_DP<7>")
	)
	(segment
		(start 72.943212 -388.515606)
		(end 72.987662 -388.950454)
		(width 0.14732)
		(layer "In13.Cu")
		(net "P5E_CPU1_PE0_RX_DP<7>")
	)
	(segment
		(start 82.080354 -214.91956)
		(end 79.015082 -218.858846)
		(width 0.14732)
		(layer "In13.Cu")
		(net "P5E_CPU1_PE0_RX_DP<7>")
	)
	(segment
		(start 72.878696 -389.084058)
		(end 72.923146 -389.518652)
		(width 0.14732)
		(layer "In13.Cu")
		(net "P5E_CPU1_PE0_RX_DP<7>")
	)
	(segment
		(start 74.05624 -396.822168)
		(end 74.121264 -397.212058)
		(width 0.14732)
		(layer "In13.Cu")
		(net "P5E_CPU1_PE0_RX_DP<7>")
	)
	(segment
		(start 73.757282 -394.151358)
		(end 73.817988 -394.515086)
		(width 0.14732)
		(layer "In13.Cu")
		(net "P5E_CPU1_PE0_RX_DP<7>")
	)
	(segment
		(start 73.457562 -393.236704)
		(end 73.590404 -394.032486)
		(width 0.14732)
		(layer "In13.Cu")
		(net "P5E_CPU1_PE0_RX_DP<7>")
	)
	(segment
		(start 75.65009 -437.152288)
		(end 75.65009 -436.889906)
		(width 0.14732)
		(layer "In13.Cu")
		(net "P5E_CPU1_PE0_RX_DP<7>")
	)
	(segment
		(start 73.817988 -394.515086)
		(end 73.699116 -394.68171)
		(width 0.14732)
		(layer "In13.Cu")
		(net "P5E_CPU1_PE0_RX_DP<7>")
	)
	(segment
		(start 94.910402 -215.925654)
		(end 94.905068 -215.922606)
		(width 0.0889)
		(layer "In13.Cu")
		(net "P5E_CPU1_PE0_RX_DP<7>")
	)
	(segment
		(start 94.586806 -213.10727)
		(end 94.586806 -212.86851)
		(width 0.14732)
		(layer "In13.Cu")
		(net "P5E_CPU1_PE0_RX_DP<7>")
	)
	(segment
		(start 75.079352 -437.31942)
		(end 75.482958 -437.31942)
		(width 0.14732)
		(layer "In13.Cu")
		(net "P5E_CPU1_PE0_RX_DP<7>")
	)
	(segment
		(start 88.769698 -212.43163)
		(end 88.617806 -212.350096)
		(width 0.14732)
		(layer "In13.Cu")
		(net "P5E_CPU1_PE0_RX_DP<7>")
	)
	(segment
		(start 88.617806 -212.350096)
		(end 83.238848 -213.969854)
		(width 0.14732)
		(layer "In13.Cu")
		(net "P5E_CPU1_PE0_RX_DP<7>")
	)
	(segment
		(start 68.560442 -346.932504)
		(end 68.560442 -346.932758)
		(width 0.14732)
		(layer "In13.Cu")
		(net "P5E_CPU1_PE0_RX_DP<7>")
	)
	(segment
		(start 74.514456 -252.38583)
		(end 78.265528 -309.716424)
		(width 0.14732)
		(layer "In13.Cu")
		(net "P5E_CPU1_PE0_RX_DP<7>")
	)
	(segment
		(start 78.265528 -309.716424)
		(end 73.961498 -319.898268)
		(width 0.14732)
		(layer "In13.Cu")
		(net "P5E_CPU1_PE0_RX_DP<7>")
	)
	(segment
		(start 94.628462 -215.436704)
		(end 94.628462 -215.414606)
		(width 0.0889)
		(layer "In13.Cu")
		(net "P5E_CPU1_PE0_RX_DP<7>")
	)
	(segment
		(start 72.869298 -410.642816)
		(end 74.954892 -424.905932)
		(width 0.14732)
		(layer "In13.Cu")
		(net "P5E_CPU1_PE0_RX_DP<7>")
	)
	(segment
		(start 73.772522 -395.123162)
		(end 73.9394 -395.242034)
		(width 0.14732)
		(layer "In13.Cu")
		(net "P5E_CPU1_PE0_RX_DP<7>")
	)
	(segment
		(start 72.8091 -388.40664)
		(end 72.943212 -388.515606)
		(width 0.14732)
		(layer "In13.Cu")
		(net "P5E_CPU1_PE0_RX_DP<7>")
	)
	(segment
		(start 74.348594 -397.694404)
		(end 74.229722 -397.861028)
		(width 0.14732)
		(layer "In13.Cu")
		(net "P5E_CPU1_PE0_RX_DP<7>")
	)
	(segment
		(start 94.911164 -215.926162)
		(end 94.910402 -215.925654)
		(width 0.0889)
		(layer "In13.Cu")
		(net "P5E_CPU1_PE0_RX_DP<7>")
	)
	(segment
		(start 73.05929 -390.845802)
		(end 73.05929 -390.846564)
		(width 0.14732)
		(layer "In13.Cu")
		(net "P5E_CPU1_PE0_RX_DP<7>")
	)
	(segment
		(start 72.693022 -387.274816)
		(end 72.827134 -387.383782)
		(width 0.14732)
		(layer "In13.Cu")
		(net "P5E_CPU1_PE0_RX_DP<7>")
	)
	(segment
		(start 73.9394 -395.242034)
		(end 74.000106 -395.605762)
		(width 0.14732)
		(layer "In13.Cu")
		(net "P5E_CPU1_PE0_RX_DP<7>")
	)
	(segment
		(start 73.057258 -389.627618)
		(end 73.101708 -390.062466)
		(width 0.14732)
		(layer "In13.Cu")
		(net "P5E_CPU1_PE0_RX_DP<7>")
	)
	(segment
		(start 71.430642 -323.511926)
		(end 68.560188 -330.441808)
		(width 0.14732)
		(layer "In13.Cu")
		(net "P5E_CPU1_PE0_RX_DP<7>")
	)
	(segment
		(start 72.871584 -387.81863)
		(end 72.762618 -387.952234)
		(width 0.14732)
		(layer "In13.Cu")
		(net "P5E_CPU1_PE0_RX_DP<7>")
	)
	(segment
		(start 95.098616 -216.260426)
		(end 95.098616 -216.25052)
		(width 0.0889)
		(layer "In13.Cu")
		(net "P5E_CPU1_PE0_RX_DP<7>")
	)
	(segment
		(start 74.290174 -398.224248)
		(end 74.457052 -398.34312)
		(width 0.14732)
		(layer "In13.Cu")
		(net "P5E_CPU1_PE0_RX_DP<7>")
	)
	(segment
		(start 95.098616 -217.8939)
		(end 95.098616 -217.859864)
		(width 0.0889)
		(layer "In13.Cu")
		(net "P5E_CPU1_PE0_RX_DP<7>")
	)
	(segment
		(start 72.693784 -387.274816)
		(end 72.693022 -387.274816)
		(width 0.14732)
		(layer "In13.Cu")
		(net "P5E_CPU1_PE0_RX_DP<7>")
	)
	(segment
		(start 94.095316 -212.066886)
		(end 93.741748 -211.920328)
		(width 0.14732)
		(layer "In13.Cu")
		(net "P5E_CPU1_PE0_RX_DP<7>")
	)
	(segment
		(start 73.590404 -394.032486)
		(end 73.757282 -394.151358)
		(width 0.14732)
		(layer "In13.Cu")
		(net "P5E_CPU1_PE0_RX_DP<7>")
	)
	(segment
		(start 74.288142 -397.33093)
		(end 74.348594 -397.694404)
		(width 0.14732)
		(layer "In13.Cu")
		(net "P5E_CPU1_PE0_RX_DP<7>")
	)
	(segment
		(start 75.482958 -437.31942)
		(end 75.65009 -437.152288)
		(width 0.14732)
		(layer "In13.Cu")
		(net "P5E_CPU1_PE0_RX_DP<7>")
	)
	(segment
		(start 74.229722 -397.861028)
		(end 74.290174 -398.224248)
		(width 0.14732)
		(layer "In13.Cu")
		(net "P5E_CPU1_PE0_RX_DP<7>")
	)
	(segment
		(start 73.33615 -392.50493)
		(end 73.45807 -393.236704)
		(width 0.14732)
		(layer "In13.Cu")
		(net "P5E_CPU1_PE0_RX_DP<7>")
	)
	(segment
		(start 89.18829 -212.305646)
		(end 88.769698 -212.43163)
		(width 0.14732)
		(layer "In13.Cu")
		(net "P5E_CPU1_PE0_RX_DP<7>")
	)
	(segment
		(start 74.175366 -396.655544)
		(end 74.05624 -396.822168)
		(width 0.14732)
		(layer "In13.Cu")
		(net "P5E_CPU1_PE0_RX_DP<7>")
	)
	(segment
		(start 95.098108 -214.622634)
		(end 95.098108 -214.461344)
		(width 0.0889)
		(layer "In13.Cu")
		(net "P5E_CPU1_PE0_RX_DP<7>")
	)
	(segment
		(start 73.222866 -391.828274)
		(end 73.366376 -391.930636)
		(width 0.14732)
		(layer "In13.Cu")
		(net "P5E_CPU1_PE0_RX_DP<7>")
	)
	(segment
		(start 73.366376 -391.930636)
		(end 73.438258 -392.361674)
		(width 0.14732)
		(layer "In13.Cu")
		(net "P5E_CPU1_PE0_RX_DP<7>")
	)
	(segment
		(start 74.586338 -399.99793)
		(end 74.586338 -404.596092)
		(width 0.14732)
		(layer "In13.Cu")
		(net "P5E_CPU1_PE0_RX_DP<7>")
	)
	(segment
		(start 74.457052 -398.34312)
		(end 74.517504 -398.706594)
		(width 0.14732)
		(layer "In13.Cu")
		(net "P5E_CPU1_PE0_RX_DP<7>")
	)
	(segment
		(start 73.438258 -392.361674)
		(end 73.33615 -392.50493)
		(width 0.14732)
		(layer "In13.Cu")
		(net "P5E_CPU1_PE0_RX_DP<7>")
	)
	(segment
		(start 94.920054 -215.931242)
		(end 94.912688 -215.926924)
		(width 0.0889)
		(layer "In13.Cu")
		(net "P5E_CPU1_PE0_RX_DP<7>")
	)
	(segment
		(start 72.869298 -406.313132)
		(end 72.869298 -410.642816)
		(width 0.14732)
		(layer "In13.Cu")
		(net "P5E_CPU1_PE0_RX_DP<7>")
	)
	(segment
		(start 95.38081 -219.01658)
		(end 95.3897 -219.0115)
		(width 0.0889)
		(layer "In13.Cu")
		(net "P5E_CPU1_PE0_RX_DP<7>")
	)
	(segment
		(start 95.098616 -219.515944)
		(end 95.098616 -219.490544)
		(width 0.0889)
		(layer "In13.Cu")
		(net "P5E_CPU1_PE0_RX_DP<7>")
	)
	(segment
		(start 95.568262 -220.334078)
		(end 95.568262 -220.311218)
		(width 0.0889)
		(layer "In13.Cu")
		(net "P5E_CPU1_PE0_RX_DP<7>")
	)
	(arc
		(start 95.098616 -216.25052)
		(mid 95.050937 -216.06762)
		(end 94.920054 -215.931242)
		(width 0.0889)
		(layer "In13.Cu")
		(net "P5E_CPU1_PE0_RX_DP<7>")
	)
	(arc
		(start 95.7961 -220.773752)
		(mid 95.787529 -220.767356)
		(end 95.779082 -220.760798)
		(width 0.0889)
		(layer "In13.Cu")
		(net "P5E_CPU1_PE0_RX_DP<7>")
	)
	(arc
		(start 94.919546 -214.941912)
		(mid 95.0468 -214.811946)
		(end 95.097854 -214.637366)
		(width 0.0889)
		(layer "In13.Cu")
		(net "P5E_CPU1_PE0_RX_DP<7>")
	)
	(arc
		(start 95.098616 -217.859864)
		(mid 95.178778 -217.587675)
		(end 95.381064 -217.388694)
		(width 0.0889)
		(layer "In13.Cu")
		(net "P5E_CPU1_PE0_RX_DP<7>")
	)
	(arc
		(start 95.568262 -217.0557)
		(mid 95.515992 -216.873335)
		(end 95.381064 -216.739978)
		(width 0.0889)
		(layer "In13.Cu")
		(net "P5E_CPU1_PE0_RX_DP<7>")
	)
	(arc
		(start 95.098616 -219.490544)
		(mid 95.177986 -219.21681)
		(end 95.38081 -219.01658)
		(width 0.0889)
		(layer "In13.Cu")
		(net "P5E_CPU1_PE0_RX_DP<7>")
	)
	(arc
		(start 95.779082 -220.760798)
		(mid 95.626595 -220.570702)
		(end 95.568262 -220.334078)
		(width 0.0889)
		(layer "In13.Cu")
		(net "P5E_CPU1_PE0_RX_DP<7>")
	)
	(arc
		(start 95.097854 -214.637366)
		(mid 95.098051 -214.630001)
		(end 95.098108 -214.622634)
		(width 0.0889)
		(layer "In13.Cu")
		(net "P5E_CPU1_PE0_RX_DP<7>")
	)
	(arc
		(start 95.38081 -218.367864)
		(mid 95.177987 -218.167633)
		(end 95.098616 -217.8939)
		(width 0.0889)
		(layer "In13.Cu")
		(net "P5E_CPU1_PE0_RX_DP<7>")
	)
	(arc
		(start 95.381064 -219.995496)
		(mid 95.176729 -219.792891)
		(end 95.098616 -219.515944)
		(width 0.0889)
		(layer "In13.Cu")
		(net "P5E_CPU1_PE0_RX_DP<7>")
	)
	(arc
		(start 95.381064 -216.739978)
		(mid 95.176729 -216.537373)
		(end 95.098616 -216.260426)
		(width 0.0889)
		(layer "In13.Cu")
		(net "P5E_CPU1_PE0_RX_DP<7>")
	)
	(arc
		(start 95.568262 -220.311218)
		(mid 95.515992 -220.128853)
		(end 95.381064 -219.995496)
		(width 0.0889)
		(layer "In13.Cu")
		(net "P5E_CPU1_PE0_RX_DP<7>")
	)
	(arc
		(start 94.913958 -214.261954)
		(mid 94.753886 -214.138774)
		(end 94.643956 -213.969346)
		(width 0.0889)
		(layer "In13.Cu")
		(net "P5E_CPU1_PE0_RX_DP<7>")
	)
	(arc
		(start 95.098108 -214.461344)
		(mid 95.023103 -214.345885)
		(end 94.913958 -214.261954)
		(width 0.0889)
		(layer "In13.Cu")
		(net "P5E_CPU1_PE0_RX_DP<7>")
	)
	(arc
		(start 94.628462 -215.414606)
		(mid 94.709373 -215.144478)
		(end 94.910656 -214.946992)
		(width 0.0889)
		(layer "In13.Cu")
		(net "P5E_CPU1_PE0_RX_DP<7>")
	)
	(arc
		(start 94.905068 -215.922606)
		(mid 94.702481 -215.716255)
		(end 94.628462 -215.436704)
		(width 0.0889)
		(layer "In13.Cu")
		(net "P5E_CPU1_PE0_RX_DP<7>")
	)
	(arc
		(start 95.381064 -217.388694)
		(mid 95.515997 -217.25534)
		(end 95.568262 -217.072972)
		(width 0.0889)
		(layer "In13.Cu")
		(net "P5E_CPU1_PE0_RX_DP<7>")
	)
	(arc
		(start 94.643956 -213.969346)
		(mid 94.635993 -213.950049)
		(end 94.628716 -213.930484)
		(width 0.0889)
		(layer "In13.Cu")
		(net "P5E_CPU1_PE0_RX_DP<7>")
	)
	(arc
		(start 95.3897 -219.0115)
		(mid 95.568176 -218.692222)
		(end 95.3897 -218.372944)
		(width 0.0889)
		(layer "In13.Cu")
		(net "P5E_CPU1_PE0_RX_DP<7>")
	)
	(segment
		(start 95.193866 -221.947994)
		(end 95.193612 -221.94774)
		(width 0.13208)
		(layer "F.Cu")
		(net "P5E_CPU1_PE0_RX_DP<6>")
	)
	(segment
		(start 95.193866 -222.48368)
		(end 95.193866 -221.947994)
		(width 0.13208)
		(layer "F.Cu")
		(net "P5E_CPU1_PE0_RX_DP<6>")
	)
	(segment
		(start 94.44101 -217.388694)
		(end 94.4499 -217.383614)
		(width 0.0889)
		(layer "In13.Cu")
		(net "P5E_CPU1_PE0_RX_DP<6>")
	)
	(segment
		(start 90.50274 -212.857588)
		(end 83.5025 -214.965788)
		(width 0.14732)
		(layer "In13.Cu")
		(net "P5E_CPU1_PE0_RX_DP<6>")
	)
	(segment
		(start 76.634848 -391.371836)
		(end 76.690728 -391.736072)
		(width 0.14732)
		(layer "In13.Cu")
		(net "P5E_CPU1_PE0_RX_DP<6>")
	)
	(segment
		(start 75.932538 -406.313132)
		(end 75.932538 -410.980636)
		(width 0.14732)
		(layer "In13.Cu")
		(net "P5E_CPU1_PE0_RX_DP<6>")
	)
	(segment
		(start 75.932538 -410.980636)
		(end 76.137516 -411.859222)
		(width 0.14732)
		(layer "In13.Cu")
		(net "P5E_CPU1_PE0_RX_DP<6>")
	)
	(segment
		(start 94.158816 -217.8939)
		(end 94.158816 -217.856308)
		(width 0.0889)
		(layer "In13.Cu")
		(net "P5E_CPU1_PE0_RX_DP<6>")
	)
	(segment
		(start 76.854304 -392.799824)
		(end 76.910184 -393.164314)
		(width 0.14732)
		(layer "In13.Cu")
		(net "P5E_CPU1_PE0_RX_DP<6>")
	)
	(segment
		(start 77.687932 -398.227042)
		(end 77.567028 -398.392142)
		(width 0.14732)
		(layer "In13.Cu")
		(net "P5E_CPU1_PE0_RX_DP<6>")
	)
	(segment
		(start 93.970602 -215.925654)
		(end 93.965268 -215.922606)
		(width 0.0889)
		(layer "In13.Cu")
		(net "P5E_CPU1_PE0_RX_DP<6>")
	)
	(segment
		(start 76.249022 -389.816594)
		(end 76.414376 -389.937752)
		(width 0.14732)
		(layer "In13.Cu")
		(net "P5E_CPU1_PE0_RX_DP<6>")
	)
	(segment
		(start 94.158816 -216.266014)
		(end 94.158816 -216.25052)
		(width 0.0889)
		(layer "In13.Cu")
		(net "P5E_CPU1_PE0_RX_DP<6>")
	)
	(segment
		(start 94.442026 -218.368372)
		(end 94.44101 -218.367864)
		(width 0.0889)
		(layer "In13.Cu")
		(net "P5E_CPU1_PE0_RX_DP<6>")
	)
	(segment
		(start 77.407262 -396.400274)
		(end 77.463142 -396.76451)
		(width 0.14732)
		(layer "In13.Cu")
		(net "P5E_CPU1_PE0_RX_DP<6>")
	)
	(segment
		(start 94.4499 -220.000576)
		(end 94.442026 -219.996004)
		(width 0.0889)
		(layer "In13.Cu")
		(net "P5E_CPU1_PE0_RX_DP<6>")
	)
	(segment
		(start 76.68895 -392.67892)
		(end 76.854304 -392.799824)
		(width 0.14732)
		(layer "In13.Cu")
		(net "P5E_CPU1_PE0_RX_DP<6>")
	)
	(segment
		(start 77.255878 -395.416532)
		(end 77.134974 -395.581632)
		(width 0.14732)
		(layer "In13.Cu")
		(net "P5E_CPU1_PE0_RX_DP<6>")
	)
	(segment
		(start 94.158308 -214.622634)
		(end 94.158308 -214.461344)
		(width 0.0889)
		(layer "In13.Cu")
		(net "P5E_CPU1_PE0_RX_DP<6>")
	)
	(segment
		(start 76.469494 -391.250678)
		(end 76.634848 -391.371836)
		(width 0.14732)
		(layer "In13.Cu")
		(net "P5E_CPU1_PE0_RX_DP<6>")
	)
	(segment
		(start 69.4944 -346.85859)
		(end 70.266814 -351.733104)
		(width 0.14732)
		(layer "In13.Cu")
		(net "P5E_CPU1_PE0_RX_DP<6>")
	)
	(segment
		(start 70.827138 -354.524818)
		(end 76.24953 -389.816594)
		(width 0.14732)
		(layer "In13.Cu")
		(net "P5E_CPU1_PE0_RX_DP<6>")
	)
	(segment
		(start 77.649578 -398.930876)
		(end 77.649578 -404.596092)
		(width 0.14732)
		(layer "In13.Cu")
		(net "P5E_CPU1_PE0_RX_DP<6>")
	)
	(segment
		(start 76.414376 -389.937752)
		(end 76.470256 -390.301988)
		(width 0.14732)
		(layer "In13.Cu")
		(net "P5E_CPU1_PE0_RX_DP<6>")
	)
	(segment
		(start 77.241908 -396.279116)
		(end 77.407262 -396.400274)
		(width 0.14732)
		(layer "In13.Cu")
		(net "P5E_CPU1_PE0_RX_DP<6>")
	)
	(segment
		(start 77.463142 -396.76451)
		(end 77.341984 -396.92961)
		(width 0.14732)
		(layer "In13.Cu")
		(net "P5E_CPU1_PE0_RX_DP<6>")
	)
	(segment
		(start 82.75574 -215.577928)
		(end 79.80934 -219.365068)
		(width 0.14732)
		(layer "In13.Cu")
		(net "P5E_CPU1_PE0_RX_DP<6>")
	)
	(segment
		(start 77.079602 -438.319418)
		(end 77.482954 -438.319418)
		(width 0.14732)
		(layer "In13.Cu")
		(net "P5E_CPU1_PE0_RX_DP<6>")
	)
	(segment
		(start 75.461114 -251.938028)
		(end 79.233014 -309.882794)
		(width 0.14732)
		(layer "In13.Cu")
		(net "P5E_CPU1_PE0_RX_DP<6>")
	)
	(segment
		(start 72.226678 -324.080886)
		(end 69.4944 -330.675996)
		(width 0.14732)
		(layer "In13.Cu")
		(net "P5E_CPU1_PE0_RX_DP<6>")
	)
	(segment
		(start 76.850494 -393.728956)
		(end 76.849732 -393.728956)
		(width 0.14732)
		(layer "In13.Cu")
		(net "P5E_CPU1_PE0_RX_DP<6>")
	)
	(segment
		(start 76.950062 -394.37945)
		(end 77.034644 -394.931138)
		(width 0.14732)
		(layer "In13.Cu")
		(net "P5E_CPU1_PE0_RX_DP<6>")
	)
	(segment
		(start 93.970856 -214.946992)
		(end 93.979746 -214.941912)
		(width 0.0889)
		(layer "In13.Cu")
		(net "P5E_CPU1_PE0_RX_DP<6>")
	)
	(segment
		(start 77.567028 -398.392142)
		(end 77.649578 -398.930876)
		(width 0.14732)
		(layer "In13.Cu")
		(net "P5E_CPU1_PE0_RX_DP<6>")
	)
	(segment
		(start 77.482954 -438.319418)
		(end 77.650086 -438.152286)
		(width 0.14732)
		(layer "In13.Cu")
		(net "P5E_CPU1_PE0_RX_DP<6>")
	)
	(segment
		(start 76.910184 -393.164314)
		(end 76.78928 -393.329414)
		(width 0.14732)
		(layer "In13.Cu")
		(net "P5E_CPU1_PE0_RX_DP<6>")
	)
	(segment
		(start 93.980254 -215.931242)
		(end 93.972888 -215.926924)
		(width 0.0889)
		(layer "In13.Cu")
		(net "P5E_CPU1_PE0_RX_DP<6>")
	)
	(segment
		(start 77.466698 -397.741648)
		(end 77.632052 -397.862552)
		(width 0.14732)
		(layer "In13.Cu")
		(net "P5E_CPU1_PE0_RX_DP<6>")
	)
	(segment
		(start 74.72553 -320.512186)
		(end 72.226678 -324.080886)
		(width 0.14732)
		(layer "In13.Cu")
		(net "P5E_CPU1_PE0_RX_DP<6>")
	)
	(segment
		(start 93.647006 -213.012274)
		(end 93.49232 -212.857588)
		(width 0.14732)
		(layer "In13.Cu")
		(net "P5E_CPU1_PE0_RX_DP<6>")
	)
	(segment
		(start 93.68917 -213.929468)
		(end 93.68917 -213.190582)
		(width 0.0889)
		(layer "In13.Cu")
		(net "P5E_CPU1_PE0_RX_DP<6>")
	)
	(segment
		(start 77.134974 -395.581632)
		(end 77.241908 -396.279116)
		(width 0.14732)
		(layer "In13.Cu")
		(net "P5E_CPU1_PE0_RX_DP<6>")
	)
	(segment
		(start 77.199998 -395.052296)
		(end 77.255878 -395.416532)
		(width 0.14732)
		(layer "In13.Cu")
		(net "P5E_CPU1_PE0_RX_DP<6>")
	)
	(segment
		(start 94.4499 -216.745058)
		(end 94.442026 -216.740486)
		(width 0.0889)
		(layer "In13.Cu")
		(net "P5E_CPU1_PE0_RX_DP<6>")
	)
	(segment
		(start 76.137516 -411.859222)
		(end 76.955142 -424.001438)
		(width 0.14732)
		(layer "In13.Cu")
		(net "P5E_CPU1_PE0_RX_DP<6>")
	)
	(segment
		(start 93.688662 -215.436704)
		(end 93.688662 -215.414606)
		(width 0.0889)
		(layer "In13.Cu")
		(net "P5E_CPU1_PE0_RX_DP<6>")
	)
	(segment
		(start 76.955142 -438.194958)
		(end 77.079602 -438.319418)
		(width 0.14732)
		(layer "In13.Cu")
		(net "P5E_CPU1_PE0_RX_DP<6>")
	)
	(segment
		(start 94.4499 -218.372944)
		(end 94.442026 -218.368372)
		(width 0.0889)
		(layer "In13.Cu")
		(net "P5E_CPU1_PE0_RX_DP<6>")
	)
	(segment
		(start 79.80934 -219.365068)
		(end 78.8924 -221.143068)
		(width 0.14732)
		(layer "In13.Cu")
		(net "P5E_CPU1_PE0_RX_DP<6>")
	)
	(segment
		(start 76.24953 -389.816594)
		(end 76.249022 -389.816594)
		(width 0.14732)
		(layer "In13.Cu")
		(net "P5E_CPU1_PE0_RX_DP<6>")
	)
	(segment
		(start 75.50404 -250.66117)
		(end 75.461114 -251.938028)
		(width 0.14732)
		(layer "In13.Cu")
		(net "P5E_CPU1_PE0_RX_DP<6>")
	)
	(segment
		(start 76.349352 -390.467088)
		(end 76.469494 -391.250678)
		(width 0.14732)
		(layer "In13.Cu")
		(net "P5E_CPU1_PE0_RX_DP<6>")
	)
	(segment
		(start 93.68917 -213.190582)
		(end 93.647006 -213.148418)
		(width 0.0889)
		(layer "In13.Cu")
		(net "P5E_CPU1_PE0_RX_DP<6>")
	)
	(segment
		(start 76.955142 -424.001438)
		(end 76.955142 -438.194958)
		(width 0.14732)
		(layer "In13.Cu")
		(net "P5E_CPU1_PE0_RX_DP<6>")
	)
	(segment
		(start 77.034644 -394.931138)
		(end 77.199998 -395.052296)
		(width 0.14732)
		(layer "In13.Cu")
		(net "P5E_CPU1_PE0_RX_DP<6>")
	)
	(segment
		(start 76.78928 -393.329414)
		(end 76.850494 -393.728956)
		(width 0.14732)
		(layer "In13.Cu")
		(net "P5E_CPU1_PE0_RX_DP<6>")
	)
	(segment
		(start 93.688916 -213.929722)
		(end 93.68917 -213.929468)
		(width 0.0889)
		(layer "In13.Cu")
		(net "P5E_CPU1_PE0_RX_DP<6>")
	)
	(segment
		(start 93.647006 -213.148418)
		(end 93.647006 -213.12632)
		(width 0.0889)
		(layer "In13.Cu")
		(net "P5E_CPU1_PE0_RX_DP<6>")
	)
	(segment
		(start 93.647006 -213.12632)
		(end 93.647006 -213.012274)
		(width 0.14732)
		(layer "In13.Cu")
		(net "P5E_CPU1_PE0_RX_DP<6>")
	)
	(segment
		(start 93.971364 -215.926162)
		(end 93.970602 -215.925654)
		(width 0.0889)
		(layer "In13.Cu")
		(net "P5E_CPU1_PE0_RX_DP<6>")
	)
	(segment
		(start 94.44101 -219.01658)
		(end 94.4499 -219.0115)
		(width 0.0889)
		(layer "In13.Cu")
		(net "P5E_CPU1_PE0_RX_DP<6>")
	)
	(segment
		(start 79.233014 -309.882794)
		(end 74.72553 -320.512186)
		(width 0.14732)
		(layer "In13.Cu")
		(net "P5E_CPU1_PE0_RX_DP<6>")
	)
	(segment
		(start 95.037148 -221.676722)
		(end 94.948248 -221.6531)
		(width 0.0889)
		(layer "In13.Cu")
		(net "P5E_CPU1_PE0_RX_DP<6>")
	)
	(segment
		(start 76.690728 -391.736072)
		(end 76.56957 -391.901172)
		(width 0.14732)
		(layer "In13.Cu")
		(net "P5E_CPU1_PE0_RX_DP<6>")
	)
	(segment
		(start 77.015086 -393.850114)
		(end 77.07122 -394.21435)
		(width 0.14732)
		(layer "In13.Cu")
		(net "P5E_CPU1_PE0_RX_DP<6>")
	)
	(segment
		(start 78.8924 -221.143068)
		(end 77.02042 -233.200194)
		(width 0.14732)
		(layer "In13.Cu")
		(net "P5E_CPU1_PE0_RX_DP<6>")
	)
	(segment
		(start 94.44101 -220.644212)
		(end 94.4499 -220.639132)
		(width 0.0889)
		(layer "In13.Cu")
		(net "P5E_CPU1_PE0_RX_DP<6>")
	)
	(segment
		(start 77.632052 -397.862552)
		(end 77.687932 -398.227042)
		(width 0.14732)
		(layer "In13.Cu")
		(net "P5E_CPU1_PE0_RX_DP<6>")
	)
	(segment
		(start 94.158816 -221.149418)
		(end 94.158816 -221.111826)
		(width 0.0889)
		(layer "In13.Cu")
		(net "P5E_CPU1_PE0_RX_DP<6>")
	)
	(segment
		(start 69.4944 -330.675996)
		(end 69.4944 -346.85859)
		(width 0.14732)
		(layer "In13.Cu")
		(net "P5E_CPU1_PE0_RX_DP<6>")
	)
	(segment
		(start 94.442026 -216.740486)
		(end 94.44101 -216.739978)
		(width 0.0889)
		(layer "In13.Cu")
		(net "P5E_CPU1_PE0_RX_DP<6>")
	)
	(segment
		(start 76.849732 -393.728956)
		(end 77.015086 -393.850114)
		(width 0.14732)
		(layer "In13.Cu")
		(net "P5E_CPU1_PE0_RX_DP<6>")
	)
	(segment
		(start 76.56957 -391.901172)
		(end 76.68895 -392.67892)
		(width 0.14732)
		(layer "In13.Cu")
		(net "P5E_CPU1_PE0_RX_DP<6>")
	)
	(segment
		(start 93.688916 -213.930484)
		(end 93.688916 -213.929722)
		(width 0.0889)
		(layer "In13.Cu")
		(net "P5E_CPU1_PE0_RX_DP<6>")
	)
	(segment
		(start 76.470256 -390.301988)
		(end 76.349352 -390.467088)
		(width 0.14732)
		(layer "In13.Cu")
		(net "P5E_CPU1_PE0_RX_DP<6>")
	)
	(segment
		(start 95.193612 -221.94774)
		(end 95.037148 -221.676722)
		(width 0.0889)
		(layer "In13.Cu")
		(net "P5E_CPU1_PE0_RX_DP<6>")
	)
	(segment
		(start 77.02042 -233.200194)
		(end 75.50404 -250.66117)
		(width 0.14732)
		(layer "In13.Cu")
		(net "P5E_CPU1_PE0_RX_DP<6>")
	)
	(segment
		(start 94.158816 -219.521532)
		(end 94.158816 -219.490544)
		(width 0.0889)
		(layer "In13.Cu")
		(net "P5E_CPU1_PE0_RX_DP<6>")
	)
	(segment
		(start 93.49232 -212.857588)
		(end 90.50274 -212.857588)
		(width 0.14732)
		(layer "In13.Cu")
		(net "P5E_CPU1_PE0_RX_DP<6>")
	)
	(segment
		(start 70.266814 -351.733104)
		(end 70.827138 -354.524818)
		(width 0.14732)
		(layer "In13.Cu")
		(net "P5E_CPU1_PE0_RX_DP<6>")
	)
	(segment
		(start 83.5025 -214.965788)
		(end 82.75574 -215.577928)
		(width 0.14732)
		(layer "In13.Cu")
		(net "P5E_CPU1_PE0_RX_DP<6>")
	)
	(segment
		(start 94.442026 -219.996004)
		(end 94.44101 -219.995496)
		(width 0.0889)
		(layer "In13.Cu")
		(net "P5E_CPU1_PE0_RX_DP<6>")
	)
	(segment
		(start 77.649578 -404.596092)
		(end 75.932538 -406.313132)
		(width 0.14732)
		(layer "In13.Cu")
		(net "P5E_CPU1_PE0_RX_DP<6>")
	)
	(segment
		(start 77.341984 -396.92961)
		(end 77.466698 -397.741648)
		(width 0.14732)
		(layer "In13.Cu")
		(net "P5E_CPU1_PE0_RX_DP<6>")
	)
	(segment
		(start 77.07122 -394.21435)
		(end 76.950062 -394.37945)
		(width 0.14732)
		(layer "In13.Cu")
		(net "P5E_CPU1_PE0_RX_DP<6>")
	)
	(segment
		(start 77.650086 -438.152286)
		(end 77.650086 -437.889904)
		(width 0.14732)
		(layer "In13.Cu")
		(net "P5E_CPU1_PE0_RX_DP<6>")
	)
	(segment
		(start 93.972888 -215.926924)
		(end 93.971364 -215.926162)
		(width 0.0889)
		(layer "In13.Cu")
		(net "P5E_CPU1_PE0_RX_DP<6>")
	)
	(arc
		(start 94.158816 -217.856308)
		(mid 94.239727 -217.58618)
		(end 94.44101 -217.388694)
		(width 0.0889)
		(layer "In13.Cu")
		(net "P5E_CPU1_PE0_RX_DP<6>")
	)
	(arc
		(start 94.44101 -218.367864)
		(mid 94.238187 -218.167633)
		(end 94.158816 -217.8939)
		(width 0.0889)
		(layer "In13.Cu")
		(net "P5E_CPU1_PE0_RX_DP<6>")
	)
	(arc
		(start 93.974158 -214.261954)
		(mid 93.814086 -214.138774)
		(end 93.704156 -213.969346)
		(width 0.0889)
		(layer "In13.Cu")
		(net "P5E_CPU1_PE0_RX_DP<6>")
	)
	(arc
		(start 94.158816 -216.25052)
		(mid 94.111137 -216.06762)
		(end 93.980254 -215.931242)
		(width 0.0889)
		(layer "In13.Cu")
		(net "P5E_CPU1_PE0_RX_DP<6>")
	)
	(arc
		(start 94.44101 -216.739978)
		(mid 94.238187 -216.539747)
		(end 94.158816 -216.266014)
		(width 0.0889)
		(layer "In13.Cu")
		(net "P5E_CPU1_PE0_RX_DP<6>")
	)
	(arc
		(start 94.158816 -221.111826)
		(mid 94.239727 -220.841698)
		(end 94.44101 -220.644212)
		(width 0.0889)
		(layer "In13.Cu")
		(net "P5E_CPU1_PE0_RX_DP<6>")
	)
	(arc
		(start 94.4499 -217.383614)
		(mid 94.628497 -217.064336)
		(end 94.4499 -216.745058)
		(width 0.0889)
		(layer "In13.Cu")
		(net "P5E_CPU1_PE0_RX_DP<6>")
	)
	(arc
		(start 94.158054 -214.637366)
		(mid 94.158251 -214.630001)
		(end 94.158308 -214.622634)
		(width 0.0889)
		(layer "In13.Cu")
		(net "P5E_CPU1_PE0_RX_DP<6>")
	)
	(arc
		(start 93.704156 -213.969346)
		(mid 93.696193 -213.950049)
		(end 93.688916 -213.930484)
		(width 0.0889)
		(layer "In13.Cu")
		(net "P5E_CPU1_PE0_RX_DP<6>")
	)
	(arc
		(start 94.928436 -221.661228)
		(mid 94.680425 -221.697693)
		(end 94.44101 -221.623382)
		(width 0.0889)
		(layer "In13.Cu")
		(net "P5E_CPU1_PE0_RX_DP<6>")
	)
	(arc
		(start 94.158308 -214.461344)
		(mid 94.083303 -214.345885)
		(end 93.974158 -214.261954)
		(width 0.0889)
		(layer "In13.Cu")
		(net "P5E_CPU1_PE0_RX_DP<6>")
	)
	(arc
		(start 94.158816 -219.490544)
		(mid 94.238186 -219.21681)
		(end 94.44101 -219.01658)
		(width 0.0889)
		(layer "In13.Cu")
		(net "P5E_CPU1_PE0_RX_DP<6>")
	)
	(arc
		(start 94.44101 -219.995496)
		(mid 94.238187 -219.795265)
		(end 94.158816 -219.521532)
		(width 0.0889)
		(layer "In13.Cu")
		(net "P5E_CPU1_PE0_RX_DP<6>")
	)
	(arc
		(start 94.948248 -221.6531)
		(mid 94.938381 -221.657259)
		(end 94.928436 -221.661228)
		(width 0.0889)
		(layer "In13.Cu")
		(net "P5E_CPU1_PE0_RX_DP<6>")
	)
	(arc
		(start 94.4499 -219.0115)
		(mid 94.628376 -218.692222)
		(end 94.4499 -218.372944)
		(width 0.0889)
		(layer "In13.Cu")
		(net "P5E_CPU1_PE0_RX_DP<6>")
	)
	(arc
		(start 94.44101 -221.623382)
		(mid 94.238187 -221.423151)
		(end 94.158816 -221.149418)
		(width 0.0889)
		(layer "In13.Cu")
		(net "P5E_CPU1_PE0_RX_DP<6>")
	)
	(arc
		(start 93.979746 -214.941912)
		(mid 94.107 -214.811946)
		(end 94.158054 -214.637366)
		(width 0.0889)
		(layer "In13.Cu")
		(net "P5E_CPU1_PE0_RX_DP<6>")
	)
	(arc
		(start 94.4499 -220.639132)
		(mid 94.628497 -220.319854)
		(end 94.4499 -220.000576)
		(width 0.0889)
		(layer "In13.Cu")
		(net "P5E_CPU1_PE0_RX_DP<6>")
	)
	(arc
		(start 93.688662 -215.414606)
		(mid 93.769573 -215.144478)
		(end 93.970856 -214.946992)
		(width 0.0889)
		(layer "In13.Cu")
		(net "P5E_CPU1_PE0_RX_DP<6>")
	)
	(arc
		(start 93.965268 -215.922606)
		(mid 93.762681 -215.716255)
		(end 93.688662 -215.436704)
		(width 0.0889)
		(layer "In13.Cu")
		(net "P5E_CPU1_PE0_RX_DP<6>")
	)
	(segment
		(start 93.783912 -221.669864)
		(end 93.783912 -221.134178)
		(width 0.13208)
		(layer "F.Cu")
		(net "P5E_CPU1_PE0_RX_DP<5>")
	)
	(segment
		(start 93.783912 -221.134178)
		(end 93.784166 -221.133924)
		(width 0.13208)
		(layer "F.Cu")
		(net "P5E_CPU1_PE0_RX_DP<5>")
	)
	(segment
		(start 79.79664 -393.713208)
		(end 79.86649 -394.075158)
		(width 0.14732)
		(layer "In13.Cu")
		(net "P5E_CPU1_PE0_RX_DP<5>")
	)
	(segment
		(start 80.645762 -252.268736)
		(end 78.124304 -258.7371)
		(width 0.14732)
		(layer "In13.Cu")
		(net "P5E_CPU1_PE0_RX_DP<5>")
	)
	(segment
		(start 84.000086 -215.864694)
		(end 83.55838 -216.256108)
		(width 0.14732)
		(layer "In13.Cu")
		(net "P5E_CPU1_PE0_RX_DP<5>")
	)
	(segment
		(start 80.712818 -404.596092)
		(end 78.995778 -406.313132)
		(width 0.14732)
		(layer "In13.Cu")
		(net "P5E_CPU1_PE0_RX_DP<5>")
	)
	(segment
		(start 80.638142 -398.062704)
		(end 80.707992 -398.424654)
		(width 0.14732)
		(layer "In13.Cu")
		(net "P5E_CPU1_PE0_RX_DP<5>")
	)
	(segment
		(start 90.226896 -215.934798)
		(end 90.212164 -215.926162)
		(width 0.0889)
		(layer "In13.Cu")
		(net "P5E_CPU1_PE0_RX_DP<5>")
	)
	(segment
		(start 78.955138 -437.19496)
		(end 79.079598 -437.31942)
		(width 0.14732)
		(layer "In13.Cu")
		(net "P5E_CPU1_PE0_RX_DP<5>")
	)
	(segment
		(start 80.64627 -251.296932)
		(end 80.64627 -252.26899)
		(width 0.14732)
		(layer "In13.Cu")
		(net "P5E_CPU1_PE0_RX_DP<5>")
	)
	(segment
		(start 79.573628 -392.560048)
		(end 79.643478 -392.921998)
		(width 0.14732)
		(layer "In13.Cu")
		(net "P5E_CPU1_PE0_RX_DP<5>")
	)
	(segment
		(start 80.006952 -395.562582)
		(end 80.127856 -396.187676)
		(width 0.14732)
		(layer "In13.Cu")
		(net "P5E_CPU1_PE0_RX_DP<5>")
	)
	(segment
		(start 80.71866 -219.901008)
		(end 79.92364 -221.450408)
		(width 0.14732)
		(layer "In13.Cu")
		(net "P5E_CPU1_PE0_RX_DP<5>")
	)
	(segment
		(start 78.67777 -388.692644)
		(end 78.847442 -388.807198)
		(width 0.14732)
		(layer "In13.Cu")
		(net "P5E_CPU1_PE0_RX_DP<5>")
	)
	(segment
		(start 80.367632 -396.66418)
		(end 80.253078 -396.833852)
		(width 0.14732)
		(layer "In13.Cu")
		(net "P5E_CPU1_PE0_RX_DP<5>")
	)
	(segment
		(start 79.48295 -437.31942)
		(end 79.650082 -437.152288)
		(width 0.14732)
		(layer "In13.Cu")
		(net "P5E_CPU1_PE0_RX_DP<5>")
	)
	(segment
		(start 86.60892 -215.230202)
		(end 85.821774 -215.230202)
		(width 0.14732)
		(layer "In13.Cu")
		(net "P5E_CPU1_PE0_RX_DP<5>")
	)
	(segment
		(start 80.64627 -252.26899)
		(end 80.645762 -252.268736)
		(width 0.14732)
		(layer "In13.Cu")
		(net "P5E_CPU1_PE0_RX_DP<5>")
	)
	(segment
		(start 79.403702 -392.445494)
		(end 79.573628 -392.560048)
		(width 0.14732)
		(layer "In13.Cu")
		(net "P5E_CPU1_PE0_RX_DP<5>")
	)
	(segment
		(start 93.219016 -216.260426)
		(end 93.219016 -216.25052)
		(width 0.0889)
		(layer "In13.Cu")
		(net "P5E_CPU1_PE0_RX_DP<5>")
	)
	(segment
		(start 78.995778 -421.185086)
		(end 78.955138 -424.39463)
		(width 0.14732)
		(layer "In13.Cu")
		(net "P5E_CPU1_PE0_RX_DP<5>")
	)
	(segment
		(start 79.650082 -437.152288)
		(end 79.650082 -436.889906)
		(width 0.14732)
		(layer "In13.Cu")
		(net "P5E_CPU1_PE0_RX_DP<5>")
	)
	(segment
		(start 70.4596 -331.013308)
		(end 70.4596 -346.782136)
		(width 0.14732)
		(layer "In13.Cu")
		(net "P5E_CPU1_PE0_RX_DP<5>")
	)
	(segment
		(start 79.079598 -437.31942)
		(end 79.48295 -437.31942)
		(width 0.14732)
		(layer "In13.Cu")
		(net "P5E_CPU1_PE0_RX_DP<5>")
	)
	(segment
		(start 93.219016 -217.8939)
		(end 93.219016 -217.859864)
		(width 0.0889)
		(layer "In13.Cu")
		(net "P5E_CPU1_PE0_RX_DP<5>")
	)
	(segment
		(start 88.989662 -215.452198)
		(end 88.989662 -215.436704)
		(width 0.0889)
		(layer "In13.Cu")
		(net "P5E_CPU1_PE0_RX_DP<5>")
	)
	(segment
		(start 80.707992 -398.424654)
		(end 80.593438 -398.594326)
		(width 0.14732)
		(layer "In13.Cu")
		(net "P5E_CPU1_PE0_RX_DP<5>")
	)
	(segment
		(start 79.643478 -392.921998)
		(end 79.528924 -393.09167)
		(width 0.14732)
		(layer "In13.Cu")
		(net "P5E_CPU1_PE0_RX_DP<5>")
	)
	(segment
		(start 73.25741 -324.259448)
		(end 70.4596 -331.013308)
		(width 0.14732)
		(layer "In13.Cu")
		(net "P5E_CPU1_PE0_RX_DP<5>")
	)
	(segment
		(start 78.124304 -258.7371)
		(end 78.123796 -258.7371)
		(width 0.14732)
		(layer "In13.Cu")
		(net "P5E_CPU1_PE0_RX_DP<5>")
	)
	(segment
		(start 80.253078 -396.833852)
		(end 80.46847 -397.948404)
		(width 0.14732)
		(layer "In13.Cu")
		(net "P5E_CPU1_PE0_RX_DP<5>")
	)
	(segment
		(start 79.337408 -391.339832)
		(end 79.407258 -391.701782)
		(width 0.14732)
		(layer "In13.Cu")
		(net "P5E_CPU1_PE0_RX_DP<5>")
	)
	(segment
		(start 79.86649 -394.075158)
		(end 79.751936 -394.244576)
		(width 0.14732)
		(layer "In13.Cu")
		(net "P5E_CPU1_PE0_RX_DP<5>")
	)
	(segment
		(start 79.92364 -221.450408)
		(end 78.002892 -233.615484)
		(width 0.14732)
		(layer "In13.Cu")
		(net "P5E_CPU1_PE0_RX_DP<5>")
	)
	(segment
		(start 93.688662 -217.072972)
		(end 93.688662 -217.0557)
		(width 0.0889)
		(layer "In13.Cu")
		(net "P5E_CPU1_PE0_RX_DP<5>")
	)
	(segment
		(start 88.8111 -215.117426)
		(end 88.80221 -215.112346)
		(width 0.0889)
		(layer "In13.Cu")
		(net "P5E_CPU1_PE0_RX_DP<5>")
	)
	(segment
		(start 93.784166 -221.133924)
		(end 93.94063 -220.862906)
		(width 0.0889)
		(layer "In13.Cu")
		(net "P5E_CPU1_PE0_RX_DP<5>")
	)
	(segment
		(start 78.123796 -258.7371)
		(end 77.416914 -266.59586)
		(width 0.14732)
		(layer "In13.Cu")
		(net "P5E_CPU1_PE0_RX_DP<5>")
	)
	(segment
		(start 78.847442 -388.807198)
		(end 78.917292 -389.169148)
		(width 0.14732)
		(layer "In13.Cu")
		(net "P5E_CPU1_PE0_RX_DP<5>")
	)
	(segment
		(start 80.297782 -396.302484)
		(end 80.367632 -396.66418)
		(width 0.14732)
		(layer "In13.Cu")
		(net "P5E_CPU1_PE0_RX_DP<5>")
	)
	(segment
		(start 78.955138 -424.39463)
		(end 78.955138 -437.19496)
		(width 0.14732)
		(layer "In13.Cu")
		(net "P5E_CPU1_PE0_RX_DP<5>")
	)
	(segment
		(start 79.528924 -393.09167)
		(end 79.626968 -393.598908)
		(width 0.14732)
		(layer "In13.Cu")
		(net "P5E_CPU1_PE0_RX_DP<5>")
	)
	(segment
		(start 70.4596 -346.782136)
		(end 71.200264 -351.457514)
		(width 0.14732)
		(layer "In13.Cu")
		(net "P5E_CPU1_PE0_RX_DP<5>")
	)
	(segment
		(start 79.112364 -390.176766)
		(end 78.99781 -390.346438)
		(width 0.14732)
		(layer "In13.Cu")
		(net "P5E_CPU1_PE0_RX_DP<5>")
	)
	(segment
		(start 78.002892 -233.615484)
		(end 78.205838 -244.720364)
		(width 0.14732)
		(layer "In13.Cu")
		(net "P5E_CPU1_PE0_RX_DP<5>")
	)
	(segment
		(start 83.55838 -216.256108)
		(end 80.71866 -219.901008)
		(width 0.14732)
		(layer "In13.Cu")
		(net "P5E_CPU1_PE0_RX_DP<5>")
	)
	(segment
		(start 71.200264 -351.457514)
		(end 72.32777 -355.87178)
		(width 0.14732)
		(layer "In13.Cu")
		(net "P5E_CPU1_PE0_RX_DP<5>")
	)
	(segment
		(start 77.416914 -266.59586)
		(end 80.18526 -310.074818)
		(width 0.14732)
		(layer "In13.Cu")
		(net "P5E_CPU1_PE0_RX_DP<5>")
	)
	(segment
		(start 78.872588 -389.700262)
		(end 79.042514 -389.81507)
		(width 0.14732)
		(layer "In13.Cu")
		(net "P5E_CPU1_PE0_RX_DP<5>")
	)
	(segment
		(start 80.593438 -398.594326)
		(end 80.712818 -399.212054)
		(width 0.14732)
		(layer "In13.Cu")
		(net "P5E_CPU1_PE0_RX_DP<5>")
	)
	(segment
		(start 86.631018 -215.230202)
		(end 86.60892 -215.230202)
		(width 0.0889)
		(layer "In13.Cu")
		(net "P5E_CPU1_PE0_RX_DP<5>")
	)
	(segment
		(start 93.033088 -215.926924)
		(end 93.031564 -215.926162)
		(width 0.0889)
		(layer "In13.Cu")
		(net "P5E_CPU1_PE0_RX_DP<5>")
	)
	(segment
		(start 78.205838 -244.720364)
		(end 78.737968 -247.572022)
		(width 0.14732)
		(layer "In13.Cu")
		(net "P5E_CPU1_PE0_RX_DP<5>")
	)
	(segment
		(start 80.46847 -397.948404)
		(end 80.638142 -398.062704)
		(width 0.14732)
		(layer "In13.Cu")
		(net "P5E_CPU1_PE0_RX_DP<5>")
	)
	(segment
		(start 80.712818 -399.212054)
		(end 80.712818 -404.596092)
		(width 0.14732)
		(layer "In13.Cu")
		(net "P5E_CPU1_PE0_RX_DP<5>")
	)
	(segment
		(start 80.12176 -395.39291)
		(end 80.006952 -395.562582)
		(width 0.14732)
		(layer "In13.Cu")
		(net "P5E_CPU1_PE0_RX_DP<5>")
	)
	(segment
		(start 79.88173 -394.916406)
		(end 80.051656 -395.03096)
		(width 0.14732)
		(layer "In13.Cu")
		(net "P5E_CPU1_PE0_RX_DP<5>")
	)
	(segment
		(start 93.688662 -220.334078)
		(end 93.688662 -220.311218)
		(width 0.0889)
		(layer "In13.Cu")
		(net "P5E_CPU1_PE0_RX_DP<5>")
	)
	(segment
		(start 93.5101 -218.372944)
		(end 93.502226 -218.368372)
		(width 0.0889)
		(layer "In13.Cu")
		(net "P5E_CPU1_PE0_RX_DP<5>")
	)
	(segment
		(start 93.94063 -220.862906)
		(end 93.9165 -220.773752)
		(width 0.0889)
		(layer "In13.Cu")
		(net "P5E_CPU1_PE0_RX_DP<5>")
	)
	(segment
		(start 75.658726 -320.829686)
		(end 73.25741 -324.259448)
		(width 0.14732)
		(layer "In13.Cu")
		(net "P5E_CPU1_PE0_RX_DP<5>")
	)
	(segment
		(start 80.352392 -250.58751)
		(end 80.64627 -251.296932)
		(width 0.14732)
		(layer "In13.Cu")
		(net "P5E_CPU1_PE0_RX_DP<5>")
	)
	(segment
		(start 85.821774 -215.230202)
		(end 84.000086 -215.864694)
		(width 0.14732)
		(layer "In13.Cu")
		(net "P5E_CPU1_PE0_RX_DP<5>")
	)
	(segment
		(start 79.407258 -391.701782)
		(end 79.292704 -391.8712)
		(width 0.14732)
		(layer "In13.Cu")
		(net "P5E_CPU1_PE0_RX_DP<5>")
	)
	(segment
		(start 79.292704 -391.8712)
		(end 79.403702 -392.445494)
		(width 0.14732)
		(layer "In13.Cu")
		(net "P5E_CPU1_PE0_RX_DP<5>")
	)
	(segment
		(start 78.737968 -247.572022)
		(end 80.352392 -250.58751)
		(width 0.14732)
		(layer "In13.Cu")
		(net "P5E_CPU1_PE0_RX_DP<5>")
	)
	(segment
		(start 92.106496 -215.934798)
		(end 92.091764 -215.926162)
		(width 0.0889)
		(layer "In13.Cu")
		(net "P5E_CPU1_PE0_RX_DP<5>")
	)
	(segment
		(start 80.127856 -396.187676)
		(end 80.297782 -396.302484)
		(width 0.14732)
		(layer "In13.Cu")
		(net "P5E_CPU1_PE0_RX_DP<5>")
	)
	(segment
		(start 78.995778 -406.313132)
		(end 78.995778 -421.185086)
		(width 0.14732)
		(layer "In13.Cu")
		(net "P5E_CPU1_PE0_RX_DP<5>")
	)
	(segment
		(start 72.32777 -355.87178)
		(end 78.67777 -388.692644)
		(width 0.14732)
		(layer "In13.Cu")
		(net "P5E_CPU1_PE0_RX_DP<5>")
	)
	(segment
		(start 80.18526 -310.074818)
		(end 75.658726 -320.829686)
		(width 0.14732)
		(layer "In13.Cu")
		(net "P5E_CPU1_PE0_RX_DP<5>")
	)
	(segment
		(start 86.673182 -215.188038)
		(end 86.631018 -215.230202)
		(width 0.0889)
		(layer "In13.Cu")
		(net "P5E_CPU1_PE0_RX_DP<5>")
	)
	(segment
		(start 78.802738 -389.33882)
		(end 78.872588 -389.700262)
		(width 0.14732)
		(layer "In13.Cu")
		(net "P5E_CPU1_PE0_RX_DP<5>")
	)
	(segment
		(start 78.917292 -389.169148)
		(end 78.802738 -389.33882)
		(width 0.14732)
		(layer "In13.Cu")
		(net "P5E_CPU1_PE0_RX_DP<5>")
	)
	(segment
		(start 79.042514 -389.81507)
		(end 79.112364 -390.176766)
		(width 0.14732)
		(layer "In13.Cu")
		(net "P5E_CPU1_PE0_RX_DP<5>")
	)
	(segment
		(start 78.99781 -390.346438)
		(end 79.167736 -391.225532)
		(width 0.14732)
		(layer "In13.Cu")
		(net "P5E_CPU1_PE0_RX_DP<5>")
	)
	(segment
		(start 80.051656 -395.03096)
		(end 80.12176 -395.39291)
		(width 0.14732)
		(layer "In13.Cu")
		(net "P5E_CPU1_PE0_RX_DP<5>")
	)
	(segment
		(start 93.502226 -218.368372)
		(end 93.50121 -218.367864)
		(width 0.0889)
		(layer "In13.Cu")
		(net "P5E_CPU1_PE0_RX_DP<5>")
	)
	(segment
		(start 79.626968 -393.598908)
		(end 79.79664 -393.713208)
		(width 0.14732)
		(layer "In13.Cu")
		(net "P5E_CPU1_PE0_RX_DP<5>")
	)
	(segment
		(start 79.751936 -394.244576)
		(end 79.88173 -394.916406)
		(width 0.14732)
		(layer "In13.Cu")
		(net "P5E_CPU1_PE0_RX_DP<5>")
	)
	(segment
		(start 93.219016 -219.515944)
		(end 93.219016 -219.490544)
		(width 0.0889)
		(layer "In13.Cu")
		(net "P5E_CPU1_PE0_RX_DP<5>")
	)
	(segment
		(start 79.167736 -391.225532)
		(end 79.337408 -391.339832)
		(width 0.14732)
		(layer "In13.Cu")
		(net "P5E_CPU1_PE0_RX_DP<5>")
	)
	(segment
		(start 93.50121 -219.01658)
		(end 93.5101 -219.0115)
		(width 0.0889)
		(layer "In13.Cu")
		(net "P5E_CPU1_PE0_RX_DP<5>")
	)
	(segment
		(start 93.040454 -215.931242)
		(end 93.033088 -215.926924)
		(width 0.0889)
		(layer "In13.Cu")
		(net "P5E_CPU1_PE0_RX_DP<5>")
	)
	(segment
		(start 87.205312 -215.188038)
		(end 86.673182 -215.188038)
		(width 0.0889)
		(layer "In13.Cu")
		(net "P5E_CPU1_PE0_RX_DP<5>")
	)
	(segment
		(start 91.166696 -215.934798)
		(end 91.151964 -215.926162)
		(width 0.0889)
		(layer "In13.Cu")
		(net "P5E_CPU1_PE0_RX_DP<5>")
	)
	(arc
		(start 93.501464 -219.995496)
		(mid 93.297129 -219.792891)
		(end 93.219016 -219.515944)
		(width 0.0889)
		(layer "In13.Cu")
		(net "P5E_CPU1_PE0_RX_DP<5>")
	)
	(arc
		(start 92.657168 -215.926162)
		(mid 92.382969 -216.001997)
		(end 92.106496 -215.934798)
		(width 0.0889)
		(layer "In13.Cu")
		(net "P5E_CPU1_PE0_RX_DP<5>")
	)
	(arc
		(start 93.50121 -218.367864)
		(mid 93.298387 -218.167633)
		(end 93.219016 -217.8939)
		(width 0.0889)
		(layer "In13.Cu")
		(net "P5E_CPU1_PE0_RX_DP<5>")
	)
	(arc
		(start 93.219016 -219.490544)
		(mid 93.298386 -219.21681)
		(end 93.50121 -219.01658)
		(width 0.0889)
		(layer "In13.Cu")
		(net "P5E_CPU1_PE0_RX_DP<5>")
	)
	(arc
		(start 87.488014 -215.112346)
		(mid 87.351648 -215.168824)
		(end 87.205312 -215.188038)
		(width 0.0889)
		(layer "In13.Cu")
		(net "P5E_CPU1_PE0_RX_DP<5>")
	)
	(arc
		(start 93.688662 -220.311218)
		(mid 93.636392 -220.128853)
		(end 93.501464 -219.995496)
		(width 0.0889)
		(layer "In13.Cu")
		(net "P5E_CPU1_PE0_RX_DP<5>")
	)
	(arc
		(start 93.688662 -217.0557)
		(mid 93.636392 -216.873335)
		(end 93.501464 -216.739978)
		(width 0.0889)
		(layer "In13.Cu")
		(net "P5E_CPU1_PE0_RX_DP<5>")
	)
	(arc
		(start 92.091764 -215.926162)
		(mid 91.904566 -215.876019)
		(end 91.717368 -215.926162)
		(width 0.0889)
		(layer "In13.Cu")
		(net "P5E_CPU1_PE0_RX_DP<5>")
	)
	(arc
		(start 93.9165 -220.773752)
		(mid 93.907929 -220.767356)
		(end 93.899482 -220.760798)
		(width 0.0889)
		(layer "In13.Cu")
		(net "P5E_CPU1_PE0_RX_DP<5>")
	)
	(arc
		(start 93.501464 -216.739978)
		(mid 93.297129 -216.537373)
		(end 93.219016 -216.260426)
		(width 0.0889)
		(layer "In13.Cu")
		(net "P5E_CPU1_PE0_RX_DP<5>")
	)
	(arc
		(start 88.989662 -215.436704)
		(mid 88.941983 -215.253804)
		(end 88.8111 -215.117426)
		(width 0.0889)
		(layer "In13.Cu")
		(net "P5E_CPU1_PE0_RX_DP<5>")
	)
	(arc
		(start 93.031564 -215.926162)
		(mid 92.844366 -215.876019)
		(end 92.657168 -215.926162)
		(width 0.0889)
		(layer "In13.Cu")
		(net "P5E_CPU1_PE0_RX_DP<5>")
	)
	(arc
		(start 88.80221 -215.112346)
		(mid 88.615012 -215.062203)
		(end 88.427814 -215.112346)
		(width 0.0889)
		(layer "In13.Cu")
		(net "P5E_CPU1_PE0_RX_DP<5>")
	)
	(arc
		(start 88.427814 -215.112346)
		(mid 88.145112 -215.188088)
		(end 87.86241 -215.112346)
		(width 0.0889)
		(layer "In13.Cu")
		(net "P5E_CPU1_PE0_RX_DP<5>")
	)
	(arc
		(start 87.86241 -215.112346)
		(mid 87.675212 -215.062203)
		(end 87.488014 -215.112346)
		(width 0.0889)
		(layer "In13.Cu")
		(net "P5E_CPU1_PE0_RX_DP<5>")
	)
	(arc
		(start 93.5101 -219.0115)
		(mid 93.688576 -218.692222)
		(end 93.5101 -218.372944)
		(width 0.0889)
		(layer "In13.Cu")
		(net "P5E_CPU1_PE0_RX_DP<5>")
	)
	(arc
		(start 90.212164 -215.926162)
		(mid 90.024966 -215.876019)
		(end 89.837768 -215.926162)
		(width 0.0889)
		(layer "In13.Cu")
		(net "P5E_CPU1_PE0_RX_DP<5>")
	)
	(arc
		(start 89.837768 -215.926162)
		(mid 89.554812 -216.002065)
		(end 89.271856 -215.926162)
		(width 0.0889)
		(layer "In13.Cu")
		(net "P5E_CPU1_PE0_RX_DP<5>")
	)
	(arc
		(start 91.151964 -215.926162)
		(mid 90.964766 -215.876019)
		(end 90.777568 -215.926162)
		(width 0.0889)
		(layer "In13.Cu")
		(net "P5E_CPU1_PE0_RX_DP<5>")
	)
	(arc
		(start 93.899482 -220.760798)
		(mid 93.746995 -220.570702)
		(end 93.688662 -220.334078)
		(width 0.0889)
		(layer "In13.Cu")
		(net "P5E_CPU1_PE0_RX_DP<5>")
	)
	(arc
		(start 89.271856 -215.926162)
		(mid 89.069033 -215.725931)
		(end 88.989662 -215.452198)
		(width 0.0889)
		(layer "In13.Cu")
		(net "P5E_CPU1_PE0_RX_DP<5>")
	)
	(arc
		(start 91.717368 -215.926162)
		(mid 91.443169 -216.001997)
		(end 91.166696 -215.934798)
		(width 0.0889)
		(layer "In13.Cu")
		(net "P5E_CPU1_PE0_RX_DP<5>")
	)
	(arc
		(start 93.501464 -217.388694)
		(mid 93.636397 -217.25534)
		(end 93.688662 -217.072972)
		(width 0.0889)
		(layer "In13.Cu")
		(net "P5E_CPU1_PE0_RX_DP<5>")
	)
	(arc
		(start 90.777568 -215.926162)
		(mid 90.503369 -216.001997)
		(end 90.226896 -215.934798)
		(width 0.0889)
		(layer "In13.Cu")
		(net "P5E_CPU1_PE0_RX_DP<5>")
	)
	(arc
		(start 93.219016 -217.859864)
		(mid 93.299178 -217.587675)
		(end 93.501464 -217.388694)
		(width 0.0889)
		(layer "In13.Cu")
		(net "P5E_CPU1_PE0_RX_DP<5>")
	)
	(arc
		(start 93.219016 -216.25052)
		(mid 93.171337 -216.06762)
		(end 93.040454 -215.931242)
		(width 0.0889)
		(layer "In13.Cu")
		(net "P5E_CPU1_PE0_RX_DP<5>")
	)
	(segment
		(start 93.314266 -222.48368)
		(end 93.314012 -222.483426)
		(width 0.13208)
		(layer "F.Cu")
		(net "P5E_CPU1_PE0_RX_DP<4>")
	)
	(segment
		(start 93.314012 -222.483426)
		(end 93.314012 -221.94774)
		(width 0.13208)
		(layer "F.Cu")
		(net "P5E_CPU1_PE0_RX_DP<4>")
	)
	(segment
		(start 81.482946 -438.319418)
		(end 81.650078 -438.152286)
		(width 0.14732)
		(layer "In13.Cu")
		(net "P5E_CPU1_PE0_RX_DP<4>")
	)
	(segment
		(start 79.044546 -258.953254)
		(end 79.044292 -258.953254)
		(width 0.14732)
		(layer "In13.Cu")
		(net "P5E_CPU1_PE0_RX_DP<4>")
	)
	(segment
		(start 83.295744 -397.3703)
		(end 83.470242 -397.477996)
		(width 0.14732)
		(layer "In13.Cu")
		(net "P5E_CPU1_PE0_RX_DP<4>")
	)
	(segment
		(start 74.011282 -324.90029)
		(end 71.4248 -331.144626)
		(width 0.14732)
		(layer "In13.Cu")
		(net "P5E_CPU1_PE0_RX_DP<4>")
	)
	(segment
		(start 79.088488 -239.353344)
		(end 79.088488 -239.35309)
		(width 0.14732)
		(layer "In13.Cu")
		(net "P5E_CPU1_PE0_RX_DP<4>")
	)
	(segment
		(start 80.955134 -438.194958)
		(end 81.079594 -438.319418)
		(width 0.14732)
		(layer "In13.Cu")
		(net "P5E_CPU1_PE0_RX_DP<4>")
	)
	(segment
		(start 92.5703 -218.372944)
		(end 92.563188 -218.36888)
		(width 0.0889)
		(layer "In13.Cu")
		(net "P5E_CPU1_PE0_RX_DP<4>")
	)
	(segment
		(start 82.125058 -392.425174)
		(end 82.299556 -392.53287)
		(width 0.14732)
		(layer "In13.Cu")
		(net "P5E_CPU1_PE0_RX_DP<4>")
	)
	(segment
		(start 81.194656 -250.190508)
		(end 81.581752 -251.125482)
		(width 0.14732)
		(layer "In13.Cu")
		(net "P5E_CPU1_PE0_RX_DP<4>")
	)
	(segment
		(start 89.742264 -216.739978)
		(end 89.733882 -216.735152)
		(width 0.0889)
		(layer "In13.Cu")
		(net "P5E_CPU1_PE0_RX_DP<4>")
	)
	(segment
		(start 83.447636 -398.010888)
		(end 83.776058 -399.39849)
		(width 0.14732)
		(layer "In13.Cu")
		(net "P5E_CPU1_PE0_RX_DP<4>")
	)
	(segment
		(start 82.059018 -406.313132)
		(end 82.059018 -412.31566)
		(width 0.14732)
		(layer "In13.Cu")
		(net "P5E_CPU1_PE0_RX_DP<4>")
	)
	(segment
		(start 82.55635 -394.247116)
		(end 82.556858 -394.247116)
		(width 0.14732)
		(layer "In13.Cu")
		(net "P5E_CPU1_PE0_RX_DP<4>")
	)
	(segment
		(start 87.877142 -216.748614)
		(end 87.86241 -216.739978)
		(width 0.0889)
		(layer "In13.Cu")
		(net "P5E_CPU1_PE0_RX_DP<4>")
	)
	(segment
		(start 82.02041 -391.350754)
		(end 82.104992 -391.709402)
		(width 0.14732)
		(layer "In13.Cu")
		(net "P5E_CPU1_PE0_RX_DP<4>")
	)
	(segment
		(start 83.776058 -404.596092)
		(end 82.059018 -406.313132)
		(width 0.14732)
		(layer "In13.Cu")
		(net "P5E_CPU1_PE0_RX_DP<4>")
	)
	(segment
		(start 82.125566 -392.42492)
		(end 82.125058 -392.425174)
		(width 0.14732)
		(layer "In13.Cu")
		(net "P5E_CPU1_PE0_RX_DP<4>")
	)
	(segment
		(start 78.98765 -233.827066)
		(end 79.088488 -239.353344)
		(width 0.14732)
		(layer "In13.Cu")
		(net "P5E_CPU1_PE0_RX_DP<4>")
	)
	(segment
		(start 92.562426 -218.368372)
		(end 92.56141 -218.367864)
		(width 0.0889)
		(layer "In13.Cu")
		(net "P5E_CPU1_PE0_RX_DP<4>")
	)
	(segment
		(start 84.949284 -216.81567)
		(end 84.90712 -216.857834)
		(width 0.0889)
		(layer "In13.Cu")
		(net "P5E_CPU1_PE0_RX_DP<4>")
	)
	(segment
		(start 82.384392 -392.891518)
		(end 82.276696 -393.065762)
		(width 0.14732)
		(layer "In13.Cu")
		(net "P5E_CPU1_PE0_RX_DP<4>")
	)
	(segment
		(start 81.84642 -391.243312)
		(end 81.846166 -391.243312)
		(width 0.14732)
		(layer "In13.Cu")
		(net "P5E_CPU1_PE0_RX_DP<4>")
	)
	(segment
		(start 83.776058 -399.39849)
		(end 83.776058 -404.596092)
		(width 0.14732)
		(layer "In13.Cu")
		(net "P5E_CPU1_PE0_RX_DP<4>")
	)
	(segment
		(start 81.138014 -310.314086)
		(end 76.486258 -321.36588)
		(width 0.14732)
		(layer "In13.Cu")
		(net "P5E_CPU1_PE0_RX_DP<4>")
	)
	(segment
		(start 82.104992 -391.709402)
		(end 81.99755 -391.883646)
		(width 0.14732)
		(layer "In13.Cu")
		(net "P5E_CPU1_PE0_RX_DP<4>")
	)
	(segment
		(start 83.555078 -397.836644)
		(end 83.447636 -398.010888)
		(width 0.14732)
		(layer "In13.Cu")
		(net "P5E_CPU1_PE0_RX_DP<4>")
	)
	(segment
		(start 82.556858 -394.247116)
		(end 82.693764 -394.825728)
		(width 0.14732)
		(layer "In13.Cu")
		(net "P5E_CPU1_PE0_RX_DP<4>")
	)
	(segment
		(start 92.279216 -221.149418)
		(end 92.279216 -221.111826)
		(width 0.0889)
		(layer "In13.Cu")
		(net "P5E_CPU1_PE0_RX_DP<4>")
	)
	(segment
		(start 84.90712 -216.857834)
		(end 84.885022 -216.857834)
		(width 0.0889)
		(layer "In13.Cu")
		(net "P5E_CPU1_PE0_RX_DP<4>")
	)
	(segment
		(start 80.955134 -424.293284)
		(end 80.955134 -438.194958)
		(width 0.14732)
		(layer "In13.Cu")
		(net "P5E_CPU1_PE0_RX_DP<4>")
	)
	(segment
		(start 81.581752 -252.445012)
		(end 81.581244 -252.445012)
		(width 0.14732)
		(layer "In13.Cu")
		(net "P5E_CPU1_PE0_RX_DP<4>")
	)
	(segment
		(start 92.56141 -217.388694)
		(end 92.5703 -217.383614)
		(width 0.0889)
		(layer "In13.Cu")
		(net "P5E_CPU1_PE0_RX_DP<4>")
	)
	(segment
		(start 92.279216 -217.8939)
		(end 92.279216 -217.856308)
		(width 0.0889)
		(layer "In13.Cu")
		(net "P5E_CPU1_PE0_RX_DP<4>")
	)
	(segment
		(start 72.11187 -351.040446)
		(end 73.44918 -355.759766)
		(width 0.14732)
		(layer "In13.Cu")
		(net "P5E_CPU1_PE0_RX_DP<4>")
	)
	(segment
		(start 81.079594 -438.319418)
		(end 81.482946 -438.319418)
		(width 0.14732)
		(layer "In13.Cu")
		(net "P5E_CPU1_PE0_RX_DP<4>")
	)
	(segment
		(start 82.95259 -395.292072)
		(end 82.845402 -395.466062)
		(width 0.14732)
		(layer "In13.Cu")
		(net "P5E_CPU1_PE0_RX_DP<4>")
	)
	(segment
		(start 92.187014 -216.739978)
		(end 92.1766 -216.746074)
		(width 0.0889)
		(layer "In13.Cu")
		(net "P5E_CPU1_PE0_RX_DP<4>")
	)
	(segment
		(start 82.299556 -392.53287)
		(end 82.384392 -392.891518)
		(width 0.14732)
		(layer "In13.Cu")
		(net "P5E_CPU1_PE0_RX_DP<4>")
	)
	(segment
		(start 92.279216 -219.521532)
		(end 92.279216 -219.490544)
		(width 0.0889)
		(layer "In13.Cu")
		(net "P5E_CPU1_PE0_RX_DP<4>")
	)
	(segment
		(start 82.40522 -393.606782)
		(end 82.404712 -393.606782)
		(width 0.14732)
		(layer "In13.Cu")
		(net "P5E_CPU1_PE0_RX_DP<4>")
	)
	(segment
		(start 82.404712 -393.606782)
		(end 82.57921 -393.714224)
		(width 0.14732)
		(layer "In13.Cu")
		(net "P5E_CPU1_PE0_RX_DP<4>")
	)
	(segment
		(start 93.157548 -221.676722)
		(end 93.068648 -221.6531)
		(width 0.0889)
		(layer "In13.Cu")
		(net "P5E_CPU1_PE0_RX_DP<4>")
	)
	(segment
		(start 78.355444 -266.608052)
		(end 81.138014 -310.314086)
		(width 0.14732)
		(layer "In13.Cu")
		(net "P5E_CPU1_PE0_RX_DP<4>")
	)
	(segment
		(start 79.044292 -258.953254)
		(end 78.355444 -266.608052)
		(width 0.14732)
		(layer "In13.Cu")
		(net "P5E_CPU1_PE0_RX_DP<4>")
	)
	(segment
		(start 81.562194 -252.494034)
		(end 79.045308 -258.950968)
		(width 0.14732)
		(layer "In13.Cu")
		(net "P5E_CPU1_PE0_RX_DP<4>")
	)
	(segment
		(start 85.325712 -216.81567)
		(end 84.949284 -216.81567)
		(width 0.0889)
		(layer "In13.Cu")
		(net "P5E_CPU1_PE0_RX_DP<4>")
	)
	(segment
		(start 73.44918 -355.759766)
		(end 77.644244 -373.486426)
		(width 0.14732)
		(layer "In13.Cu")
		(net "P5E_CPU1_PE0_RX_DP<4>")
	)
	(segment
		(start 82.276696 -393.065762)
		(end 82.277204 -393.066016)
		(width 0.14732)
		(layer "In13.Cu")
		(net "P5E_CPU1_PE0_RX_DP<4>")
	)
	(segment
		(start 86.937342 -216.748614)
		(end 86.92261 -216.739978)
		(width 0.0889)
		(layer "In13.Cu")
		(net "P5E_CPU1_PE0_RX_DP<4>")
	)
	(segment
		(start 81.650078 -438.152286)
		(end 81.650078 -437.889904)
		(width 0.14732)
		(layer "In13.Cu")
		(net "P5E_CPU1_PE0_RX_DP<4>")
	)
	(segment
		(start 79.045308 -258.950968)
		(end 79.044546 -258.953254)
		(width 0.14732)
		(layer "In13.Cu")
		(net "P5E_CPU1_PE0_RX_DP<4>")
	)
	(segment
		(start 83.470242 -397.477996)
		(end 83.555078 -397.836644)
		(width 0.14732)
		(layer "In13.Cu")
		(net "P5E_CPU1_PE0_RX_DP<4>")
	)
	(segment
		(start 83.245198 -396.527782)
		(end 83.137756 -396.702026)
		(width 0.14732)
		(layer "In13.Cu")
		(net "P5E_CPU1_PE0_RX_DP<4>")
	)
	(segment
		(start 71.4248 -331.144626)
		(end 71.4248 -346.705682)
		(width 0.14732)
		(layer "In13.Cu")
		(net "P5E_CPU1_PE0_RX_DP<4>")
	)
	(segment
		(start 91.247468 -216.739978)
		(end 91.237054 -216.746074)
		(width 0.0889)
		(layer "In13.Cu")
		(net "P5E_CPU1_PE0_RX_DP<4>")
	)
	(segment
		(start 76.486258 -321.36588)
		(end 74.011282 -324.90029)
		(width 0.14732)
		(layer "In13.Cu")
		(net "P5E_CPU1_PE0_RX_DP<4>")
	)
	(segment
		(start 83.160362 -396.169134)
		(end 83.245198 -396.527782)
		(width 0.14732)
		(layer "In13.Cu")
		(net "P5E_CPU1_PE0_RX_DP<4>")
	)
	(segment
		(start 83.137756 -396.702026)
		(end 83.295744 -397.3703)
		(width 0.14732)
		(layer "In13.Cu")
		(net "P5E_CPU1_PE0_RX_DP<4>")
	)
	(segment
		(start 82.693764 -394.825728)
		(end 82.693256 -394.825728)
		(width 0.14732)
		(layer "In13.Cu")
		(net "P5E_CPU1_PE0_RX_DP<4>")
	)
	(segment
		(start 81.581752 -251.125482)
		(end 81.581752 -252.445012)
		(width 0.14732)
		(layer "In13.Cu")
		(net "P5E_CPU1_PE0_RX_DP<4>")
	)
	(segment
		(start 93.314012 -221.94774)
		(end 93.157548 -221.676722)
		(width 0.0889)
		(layer "In13.Cu")
		(net "P5E_CPU1_PE0_RX_DP<4>")
	)
	(segment
		(start 92.56141 -219.01658)
		(end 92.5703 -219.0115)
		(width 0.0889)
		(layer "In13.Cu")
		(net "P5E_CPU1_PE0_RX_DP<4>")
	)
	(segment
		(start 79.088488 -239.35309)
		(end 79.18958 -244.879622)
		(width 0.14732)
		(layer "In13.Cu")
		(net "P5E_CPU1_PE0_RX_DP<4>")
	)
	(segment
		(start 82.277204 -393.066016)
		(end 82.40522 -393.606782)
		(width 0.14732)
		(layer "In13.Cu")
		(net "P5E_CPU1_PE0_RX_DP<4>")
	)
	(segment
		(start 92.563188 -218.36888)
		(end 92.562426 -218.368372)
		(width 0.0889)
		(layer "In13.Cu")
		(net "P5E_CPU1_PE0_RX_DP<4>")
	)
	(segment
		(start 92.562426 -219.996004)
		(end 92.56141 -219.995496)
		(width 0.0889)
		(layer "In13.Cu")
		(net "P5E_CPU1_PE0_RX_DP<4>")
	)
	(segment
		(start 82.693256 -394.825728)
		(end 82.867754 -394.933424)
		(width 0.14732)
		(layer "In13.Cu")
		(net "P5E_CPU1_PE0_RX_DP<4>")
	)
	(segment
		(start 81.609946 -220.500448)
		(end 80.9371 -221.737428)
		(width 0.14732)
		(layer "In13.Cu")
		(net "P5E_CPU1_PE0_RX_DP<4>")
	)
	(segment
		(start 71.4248 -346.705682)
		(end 72.11187 -351.040446)
		(width 0.14732)
		(layer "In13.Cu")
		(net "P5E_CPU1_PE0_RX_DP<4>")
	)
	(segment
		(start 81.99755 -391.883646)
		(end 82.125566 -392.42492)
		(width 0.14732)
		(layer "In13.Cu")
		(net "P5E_CPU1_PE0_RX_DP<4>")
	)
	(segment
		(start 92.56141 -220.644212)
		(end 92.5703 -220.639132)
		(width 0.0889)
		(layer "In13.Cu")
		(net "P5E_CPU1_PE0_RX_DP<4>")
	)
	(segment
		(start 82.57921 -393.714224)
		(end 82.664046 -394.072872)
		(width 0.14732)
		(layer "In13.Cu")
		(net "P5E_CPU1_PE0_RX_DP<4>")
	)
	(segment
		(start 81.846166 -391.243312)
		(end 82.02041 -391.350754)
		(width 0.14732)
		(layer "In13.Cu")
		(net "P5E_CPU1_PE0_RX_DP<4>")
	)
	(segment
		(start 84.28228 -217.063574)
		(end 81.609946 -220.500448)
		(width 0.14732)
		(layer "In13.Cu")
		(net "P5E_CPU1_PE0_RX_DP<4>")
	)
	(segment
		(start 82.867754 -394.933424)
		(end 82.95259 -395.292072)
		(width 0.14732)
		(layer "In13.Cu")
		(net "P5E_CPU1_PE0_RX_DP<4>")
	)
	(segment
		(start 82.664046 -394.072872)
		(end 82.55635 -394.247116)
		(width 0.14732)
		(layer "In13.Cu")
		(net "P5E_CPU1_PE0_RX_DP<4>")
	)
	(segment
		(start 88.816942 -216.748614)
		(end 88.80221 -216.739978)
		(width 0.0889)
		(layer "In13.Cu")
		(net "P5E_CPU1_PE0_RX_DP<4>")
	)
	(segment
		(start 79.624936 -247.255792)
		(end 81.194656 -250.190508)
		(width 0.14732)
		(layer "In13.Cu")
		(net "P5E_CPU1_PE0_RX_DP<4>")
	)
	(segment
		(start 85.997542 -216.748614)
		(end 85.98281 -216.739978)
		(width 0.0889)
		(layer "In13.Cu")
		(net "P5E_CPU1_PE0_RX_DP<4>")
	)
	(segment
		(start 80.9371 -221.737428)
		(end 78.98765 -233.827066)
		(width 0.14732)
		(layer "In13.Cu")
		(net "P5E_CPU1_PE0_RX_DP<4>")
	)
	(segment
		(start 82.986118 -396.061692)
		(end 83.160362 -396.169134)
		(width 0.14732)
		(layer "In13.Cu")
		(net "P5E_CPU1_PE0_RX_DP<4>")
	)
	(segment
		(start 81.562702 -252.49251)
		(end 81.562194 -252.494034)
		(width 0.14732)
		(layer "In13.Cu")
		(net "P5E_CPU1_PE0_RX_DP<4>")
	)
	(segment
		(start 82.059018 -412.31566)
		(end 80.955134 -424.293284)
		(width 0.14732)
		(layer "In13.Cu")
		(net "P5E_CPU1_PE0_RX_DP<4>")
	)
	(segment
		(start 90.307414 -216.739978)
		(end 90.297 -216.746074)
		(width 0.0889)
		(layer "In13.Cu")
		(net "P5E_CPU1_PE0_RX_DP<4>")
	)
	(segment
		(start 92.5703 -220.000576)
		(end 92.562426 -219.996004)
		(width 0.0889)
		(layer "In13.Cu")
		(net "P5E_CPU1_PE0_RX_DP<4>")
	)
	(segment
		(start 79.18958 -244.879622)
		(end 79.624936 -247.255792)
		(width 0.14732)
		(layer "In13.Cu")
		(net "P5E_CPU1_PE0_RX_DP<4>")
	)
	(segment
		(start 84.885022 -216.857834)
		(end 84.48802 -216.857834)
		(width 0.14732)
		(layer "In13.Cu")
		(net "P5E_CPU1_PE0_RX_DP<4>")
	)
	(segment
		(start 77.644244 -373.486426)
		(end 81.84642 -391.243312)
		(width 0.14732)
		(layer "In13.Cu")
		(net "P5E_CPU1_PE0_RX_DP<4>")
	)
	(segment
		(start 84.48802 -216.857834)
		(end 84.28228 -217.063574)
		(width 0.14732)
		(layer "In13.Cu")
		(net "P5E_CPU1_PE0_RX_DP<4>")
	)
	(segment
		(start 81.581244 -252.445012)
		(end 81.562702 -252.49251)
		(width 0.14732)
		(layer "In13.Cu")
		(net "P5E_CPU1_PE0_RX_DP<4>")
	)
	(segment
		(start 82.845402 -395.466062)
		(end 82.986118 -396.061692)
		(width 0.14732)
		(layer "In13.Cu")
		(net "P5E_CPU1_PE0_RX_DP<4>")
	)
	(arc
		(start 87.86241 -216.739978)
		(mid 87.675212 -216.689835)
		(end 87.488014 -216.739978)
		(width 0.0889)
		(layer "In13.Cu")
		(net "P5E_CPU1_PE0_RX_DP<4>")
	)
	(arc
		(start 88.427814 -216.739978)
		(mid 88.153615 -216.815813)
		(end 87.877142 -216.748614)
		(width 0.0889)
		(layer "In13.Cu")
		(net "P5E_CPU1_PE0_RX_DP<4>")
	)
	(arc
		(start 86.548214 -216.739978)
		(mid 86.274015 -216.815813)
		(end 85.997542 -216.748614)
		(width 0.0889)
		(layer "In13.Cu")
		(net "P5E_CPU1_PE0_RX_DP<4>")
	)
	(arc
		(start 92.1766 -216.746074)
		(mid 91.898422 -216.815797)
		(end 91.621864 -216.739978)
		(width 0.0889)
		(layer "In13.Cu")
		(net "P5E_CPU1_PE0_RX_DP<4>")
	)
	(arc
		(start 92.56141 -218.367864)
		(mid 92.358587 -218.167633)
		(end 92.279216 -217.8939)
		(width 0.0889)
		(layer "In13.Cu")
		(net "P5E_CPU1_PE0_RX_DP<4>")
	)
	(arc
		(start 92.56141 -219.995496)
		(mid 92.358587 -219.795265)
		(end 92.279216 -219.521532)
		(width 0.0889)
		(layer "In13.Cu")
		(net "P5E_CPU1_PE0_RX_DP<4>")
	)
	(arc
		(start 85.98281 -216.739978)
		(mid 85.795612 -216.689835)
		(end 85.608414 -216.739978)
		(width 0.0889)
		(layer "In13.Cu")
		(net "P5E_CPU1_PE0_RX_DP<4>")
	)
	(arc
		(start 88.80221 -216.739978)
		(mid 88.615012 -216.689835)
		(end 88.427814 -216.739978)
		(width 0.0889)
		(layer "In13.Cu")
		(net "P5E_CPU1_PE0_RX_DP<4>")
	)
	(arc
		(start 92.279216 -221.111826)
		(mid 92.360127 -220.841698)
		(end 92.56141 -220.644212)
		(width 0.0889)
		(layer "In13.Cu")
		(net "P5E_CPU1_PE0_RX_DP<4>")
	)
	(arc
		(start 89.733882 -216.735152)
		(mid 89.55012 -216.689752)
		(end 89.367614 -216.739978)
		(width 0.0889)
		(layer "In13.Cu")
		(net "P5E_CPU1_PE0_RX_DP<4>")
	)
	(arc
		(start 90.68181 -216.739978)
		(mid 90.494612 -216.689835)
		(end 90.307414 -216.739978)
		(width 0.0889)
		(layer "In13.Cu")
		(net "P5E_CPU1_PE0_RX_DP<4>")
	)
	(arc
		(start 86.92261 -216.739978)
		(mid 86.735412 -216.689835)
		(end 86.548214 -216.739978)
		(width 0.0889)
		(layer "In13.Cu")
		(net "P5E_CPU1_PE0_RX_DP<4>")
	)
	(arc
		(start 93.048836 -221.661228)
		(mid 92.53131 -221.604907)
		(end 92.279216 -221.149418)
		(width 0.0889)
		(layer "In13.Cu")
		(net "P5E_CPU1_PE0_RX_DP<4>")
	)
	(arc
		(start 93.068648 -221.6531)
		(mid 93.058781 -221.657259)
		(end 93.048836 -221.661228)
		(width 0.0889)
		(layer "In13.Cu")
		(net "P5E_CPU1_PE0_RX_DP<4>")
	)
	(arc
		(start 91.621864 -216.739978)
		(mid 91.434666 -216.689835)
		(end 91.247468 -216.739978)
		(width 0.0889)
		(layer "In13.Cu")
		(net "P5E_CPU1_PE0_RX_DP<4>")
	)
	(arc
		(start 87.488014 -216.739978)
		(mid 87.213815 -216.815813)
		(end 86.937342 -216.748614)
		(width 0.0889)
		(layer "In13.Cu")
		(net "P5E_CPU1_PE0_RX_DP<4>")
	)
	(arc
		(start 92.5703 -220.639132)
		(mid 92.748897 -220.319854)
		(end 92.5703 -220.000576)
		(width 0.0889)
		(layer "In13.Cu")
		(net "P5E_CPU1_PE0_RX_DP<4>")
	)
	(arc
		(start 91.237054 -216.746074)
		(mid 90.958622 -216.81592)
		(end 90.68181 -216.739978)
		(width 0.0889)
		(layer "In13.Cu")
		(net "P5E_CPU1_PE0_RX_DP<4>")
	)
	(arc
		(start 89.367614 -216.739978)
		(mid 89.093415 -216.815813)
		(end 88.816942 -216.748614)
		(width 0.0889)
		(layer "In13.Cu")
		(net "P5E_CPU1_PE0_RX_DP<4>")
	)
	(arc
		(start 85.608414 -216.739978)
		(mid 85.472048 -216.796456)
		(end 85.325712 -216.81567)
		(width 0.0889)
		(layer "In13.Cu")
		(net "P5E_CPU1_PE0_RX_DP<4>")
	)
	(arc
		(start 90.297 -216.746074)
		(mid 90.018822 -216.815797)
		(end 89.742264 -216.739978)
		(width 0.0889)
		(layer "In13.Cu")
		(net "P5E_CPU1_PE0_RX_DP<4>")
	)
	(arc
		(start 92.279216 -219.490544)
		(mid 92.358586 -219.21681)
		(end 92.56141 -219.01658)
		(width 0.0889)
		(layer "In13.Cu")
		(net "P5E_CPU1_PE0_RX_DP<4>")
	)
	(arc
		(start 92.5703 -219.0115)
		(mid 92.748776 -218.692222)
		(end 92.5703 -218.372944)
		(width 0.0889)
		(layer "In13.Cu")
		(net "P5E_CPU1_PE0_RX_DP<4>")
	)
	(arc
		(start 92.279216 -217.856308)
		(mid 92.360127 -217.58618)
		(end 92.56141 -217.388694)
		(width 0.0889)
		(layer "In13.Cu")
		(net "P5E_CPU1_PE0_RX_DP<4>")
	)
	(arc
		(start 92.5703 -217.383614)
		(mid 92.69614 -216.872629)
		(end 92.187014 -216.739978)
		(width 0.0889)
		(layer "In13.Cu")
		(net "P5E_CPU1_PE0_RX_DP<4>")
	)
	(segment
		(start 92.374466 -220.855794)
		(end 92.374212 -220.85554)
		(width 0.13208)
		(layer "F.Cu")
		(net "P5E_CPU1_PE0_RX_DP<3>")
	)
	(segment
		(start 92.374212 -220.85554)
		(end 92.374212 -220.319854)
		(width 0.13208)
		(layer "F.Cu")
		(net "P5E_CPU1_PE0_RX_DP<3>")
	)
	(segment
		(start 72.742552 -350.444308)
		(end 72.14108 -346.64904)
		(width 0.14732)
		(layer "In13.Cu")
		(net "P5E_CPU1_PE0_RX_DP<3>")
	)
	(segment
		(start 86.564978 -399.564098)
		(end 73.783444 -353.600766)
		(width 0.14732)
		(layer "In13.Cu")
		(net "P5E_CPU1_PE0_RX_DP<3>")
	)
	(segment
		(start 82.241644 -252.569218)
		(end 82.241898 -252.569218)
		(width 0.14732)
		(layer "In13.Cu")
		(net "P5E_CPU1_PE0_RX_DP<3>")
	)
	(segment
		(start 91.232482 -219.007944)
		(end 91.251532 -219.01912)
		(width 0.0889)
		(layer "In13.Cu")
		(net "P5E_CPU1_PE0_RX_DP<3>")
	)
	(segment
		(start 85.844634 -219.025216)
		(end 85.844888 -219.025216)
		(width 0.0889)
		(layer "In13.Cu")
		(net "P5E_CPU1_PE0_RX_DP<3>")
	)
	(segment
		(start 86.173056 -218.927934)
		(end 87.110316 -218.915742)
		(width 0.0889)
		(layer "In13.Cu")
		(net "P5E_CPU1_PE0_RX_DP<3>")
	)
	(segment
		(start 90.292682 -219.007944)
		(end 90.307414 -219.01658)
		(width 0.0889)
		(layer "In13.Cu")
		(net "P5E_CPU1_PE0_RX_DP<3>")
	)
	(segment
		(start 82.68081 -424.207432)
		(end 84.847938 -411.536134)
		(width 0.14732)
		(layer "In13.Cu")
		(net "P5E_CPU1_PE0_RX_DP<3>")
	)
	(segment
		(start 82.241898 -251.006102)
		(end 81.790032 -249.914156)
		(width 0.14732)
		(layer "In13.Cu")
		(net "P5E_CPU1_PE0_RX_DP<3>")
	)
	(segment
		(start 85.792818 -218.996768)
		(end 85.844634 -219.025216)
		(width 0.0889)
		(layer "In13.Cu")
		(net "P5E_CPU1_PE0_RX_DP<3>")
	)
	(segment
		(start 91.708478 -219.825316)
		(end 91.717368 -219.830396)
		(width 0.0889)
		(layer "In13.Cu")
		(net "P5E_CPU1_PE0_RX_DP<3>")
	)
	(segment
		(start 79.017622 -266.616688)
		(end 79.69377 -259.105654)
		(width 0.14732)
		(layer "In13.Cu")
		(net "P5E_CPU1_PE0_RX_DP<3>")
	)
	(segment
		(start 82.234278 -252.591316)
		(end 82.241644 -252.569218)
		(width 0.14732)
		(layer "In13.Cu")
		(net "P5E_CPU1_PE0_RX_DP<3>")
	)
	(segment
		(start 86.564978 -404.4823)
		(end 86.564978 -399.564098)
		(width 0.14732)
		(layer "In13.Cu")
		(net "P5E_CPU1_PE0_RX_DP<3>")
	)
	(segment
		(start 92.217748 -220.590872)
		(end 92.374212 -220.319854)
		(width 0.0889)
		(layer "In13.Cu")
		(net "P5E_CPU1_PE0_RX_DP<3>")
	)
	(segment
		(start 82.97926 -220.418914)
		(end 85.321902 -219.135452)
		(width 0.14732)
		(layer "In13.Cu")
		(net "P5E_CPU1_PE0_RX_DP<3>")
	)
	(segment
		(start 84.847938 -411.536134)
		(end 84.847938 -406.19934)
		(width 0.14732)
		(layer "In13.Cu")
		(net "P5E_CPU1_PE0_RX_DP<3>")
	)
	(segment
		(start 83.650074 -438.089802)
		(end 83.650074 -437.741314)
		(width 0.14732)
		(layer "In13.Cu")
		(net "P5E_CPU1_PE0_RX_DP<3>")
	)
	(segment
		(start 91.999816 -220.309948)
		(end 91.999816 -220.32849)
		(width 0.0889)
		(layer "In13.Cu")
		(net "P5E_CPU1_PE0_RX_DP<3>")
	)
	(segment
		(start 84.847938 -406.19934)
		(end 86.564978 -404.4823)
		(width 0.14732)
		(layer "In13.Cu")
		(net "P5E_CPU1_PE0_RX_DP<3>")
	)
	(segment
		(start 82.241898 -252.569218)
		(end 82.241898 -251.006102)
		(width 0.14732)
		(layer "In13.Cu")
		(net "P5E_CPU1_PE0_RX_DP<3>")
	)
	(segment
		(start 83.650074 -437.741314)
		(end 83.5025 -437.59374)
		(width 0.14732)
		(layer "In13.Cu")
		(net "P5E_CPU1_PE0_RX_DP<3>")
	)
	(segment
		(start 85.321902 -219.135452)
		(end 85.771736 -219.002864)
		(width 0.14732)
		(layer "In13.Cu")
		(net "P5E_CPU1_PE0_RX_DP<3>")
	)
	(segment
		(start 85.844888 -219.025216)
		(end 86.173056 -218.927934)
		(width 0.0889)
		(layer "In13.Cu")
		(net "P5E_CPU1_PE0_RX_DP<3>")
	)
	(segment
		(start 83.5025 -437.59374)
		(end 82.965798 -437.59374)
		(width 0.14732)
		(layer "In13.Cu")
		(net "P5E_CPU1_PE0_RX_DP<3>")
	)
	(segment
		(start 89.3572 -219.010484)
		(end 89.367614 -219.01658)
		(width 0.0889)
		(layer "In13.Cu")
		(net "P5E_CPU1_PE0_RX_DP<3>")
	)
	(segment
		(start 81.790032 -249.914156)
		(end 80.2513 -247.036082)
		(width 0.14732)
		(layer "In13.Cu")
		(net "P5E_CPU1_PE0_RX_DP<3>")
	)
	(segment
		(start 80.2513 -247.036082)
		(end 79.90078 -245.046246)
		(width 0.14732)
		(layer "In13.Cu")
		(net "P5E_CPU1_PE0_RX_DP<3>")
	)
	(segment
		(start 92.13977 -220.6117)
		(end 92.217748 -220.590872)
		(width 0.0889)
		(layer "In13.Cu")
		(net "P5E_CPU1_PE0_RX_DP<3>")
	)
	(segment
		(start 85.771736 -219.002864)
		(end 85.792818 -218.996768)
		(width 0.0889)
		(layer "In13.Cu")
		(net "P5E_CPU1_PE0_RX_DP<3>")
	)
	(segment
		(start 72.14108 -331.139546)
		(end 74.478642 -325.49592)
		(width 0.14732)
		(layer "In13.Cu")
		(net "P5E_CPU1_PE0_RX_DP<3>")
	)
	(segment
		(start 87.110316 -218.915742)
		(end 87.112348 -218.915742)
		(width 0.0889)
		(layer "In13.Cu")
		(net "P5E_CPU1_PE0_RX_DP<3>")
	)
	(segment
		(start 82.965798 -437.59374)
		(end 82.68081 -437.308752)
		(width 0.14732)
		(layer "In13.Cu")
		(net "P5E_CPU1_PE0_RX_DP<3>")
	)
	(segment
		(start 74.478642 -325.49592)
		(end 77.03947 -321.839082)
		(width 0.14732)
		(layer "In13.Cu")
		(net "P5E_CPU1_PE0_RX_DP<3>")
	)
	(segment
		(start 82.68081 -437.308752)
		(end 82.68081 -424.207432)
		(width 0.14732)
		(layer "In13.Cu")
		(net "P5E_CPU1_PE0_RX_DP<3>")
	)
	(segment
		(start 79.687674 -233.931206)
		(end 81.649824 -222.009208)
		(width 0.14732)
		(layer "In13.Cu")
		(net "P5E_CPU1_PE0_RX_DP<3>")
	)
	(segment
		(start 87.862918 -219.016834)
		(end 87.862664 -219.01658)
		(width 0.0889)
		(layer "In13.Cu")
		(net "P5E_CPU1_PE0_RX_DP<3>")
	)
	(segment
		(start 79.90078 -245.046246)
		(end 79.687674 -233.931206)
		(width 0.14732)
		(layer "In13.Cu")
		(net "P5E_CPU1_PE0_RX_DP<3>")
	)
	(segment
		(start 82.258662 -220.9673)
		(end 82.97926 -220.418914)
		(width 0.14732)
		(layer "In13.Cu")
		(net "P5E_CPU1_PE0_RX_DP<3>")
	)
	(segment
		(start 73.783444 -353.600766)
		(end 72.742552 -350.444308)
		(width 0.14732)
		(layer "In13.Cu")
		(net "P5E_CPU1_PE0_RX_DP<3>")
	)
	(segment
		(start 79.69377 -259.105654)
		(end 82.234278 -252.591316)
		(width 0.14732)
		(layer "In13.Cu")
		(net "P5E_CPU1_PE0_RX_DP<3>")
	)
	(segment
		(start 77.03947 -321.839082)
		(end 81.811622 -310.501538)
		(width 0.14732)
		(layer "In13.Cu")
		(net "P5E_CPU1_PE0_RX_DP<3>")
	)
	(segment
		(start 72.14108 -346.64904)
		(end 72.14108 -331.139546)
		(width 0.14732)
		(layer "In13.Cu")
		(net "P5E_CPU1_PE0_RX_DP<3>")
	)
	(segment
		(start 81.649824 -222.009208)
		(end 82.258662 -220.9673)
		(width 0.14732)
		(layer "In13.Cu")
		(net "P5E_CPU1_PE0_RX_DP<3>")
	)
	(segment
		(start 81.811622 -310.501538)
		(end 79.017622 -266.616688)
		(width 0.14732)
		(layer "In13.Cu")
		(net "P5E_CPU1_PE0_RX_DP<3>")
	)
	(arc
		(start 88.802464 -219.01658)
		(mid 89.079023 -218.940837)
		(end 89.3572 -219.010484)
		(width 0.0889)
		(layer "In13.Cu")
		(net "P5E_CPU1_PE0_RX_DP<3>")
	)
	(arc
		(start 88.428068 -219.01658)
		(mid 88.615266 -219.066723)
		(end 88.802464 -219.01658)
		(width 0.0889)
		(layer "In13.Cu")
		(net "P5E_CPU1_PE0_RX_DP<3>")
	)
	(arc
		(start 89.74201 -219.01658)
		(mid 90.016209 -218.940745)
		(end 90.292682 -219.007944)
		(width 0.0889)
		(layer "In13.Cu")
		(net "P5E_CPU1_PE0_RX_DP<3>")
	)
	(arc
		(start 90.307414 -219.01658)
		(mid 90.494612 -219.066723)
		(end 90.68181 -219.01658)
		(width 0.0889)
		(layer "In13.Cu")
		(net "P5E_CPU1_PE0_RX_DP<3>")
	)
	(arc
		(start 91.251532 -219.01912)
		(mid 91.455363 -219.225613)
		(end 91.529916 -219.506038)
		(width 0.0889)
		(layer "In13.Cu")
		(net "P5E_CPU1_PE0_RX_DP<3>")
	)
	(arc
		(start 91.717368 -219.830396)
		(mid 91.921703 -220.033001)
		(end 91.999816 -220.309948)
		(width 0.0889)
		(layer "In13.Cu")
		(net "P5E_CPU1_PE0_RX_DP<3>")
	)
	(arc
		(start 91.999816 -220.32849)
		(mid 92.03849 -220.485558)
		(end 92.13977 -220.6117)
		(width 0.0889)
		(layer "In13.Cu")
		(net "P5E_CPU1_PE0_RX_DP<3>")
	)
	(arc
		(start 87.488268 -219.016834)
		(mid 87.67561 -219.06707)
		(end 87.862918 -219.016834)
		(width 0.0889)
		(layer "In13.Cu")
		(net "P5E_CPU1_PE0_RX_DP<3>")
	)
	(arc
		(start 91.529916 -219.506038)
		(mid 91.577595 -219.688938)
		(end 91.708478 -219.825316)
		(width 0.0889)
		(layer "In13.Cu")
		(net "P5E_CPU1_PE0_RX_DP<3>")
	)
	(arc
		(start 87.112348 -218.915742)
		(mid 87.306999 -218.941416)
		(end 87.488268 -219.016834)
		(width 0.0889)
		(layer "In13.Cu")
		(net "P5E_CPU1_PE0_RX_DP<3>")
	)
	(arc
		(start 90.68181 -219.01658)
		(mid 90.956009 -218.940745)
		(end 91.232482 -219.007944)
		(width 0.0889)
		(layer "In13.Cu")
		(net "P5E_CPU1_PE0_RX_DP<3>")
	)
	(arc
		(start 89.367614 -219.01658)
		(mid 89.554812 -219.066723)
		(end 89.74201 -219.01658)
		(width 0.0889)
		(layer "In13.Cu")
		(net "P5E_CPU1_PE0_RX_DP<3>")
	)
	(arc
		(start 87.862664 -219.01658)
		(mid 88.145366 -218.940804)
		(end 88.428068 -219.01658)
		(width 0.0889)
		(layer "In13.Cu")
		(net "P5E_CPU1_PE0_RX_DP<3>")
	)
	(segment
		(start 91.434666 -222.48368)
		(end 91.434666 -221.947994)
		(width 0.13208)
		(layer "F.Cu")
		(net "P5E_CPU1_PE0_RX_DP<2>")
	)
	(segment
		(start 91.434666 -221.947994)
		(end 91.434412 -221.94774)
		(width 0.13208)
		(layer "F.Cu")
		(net "P5E_CPU1_PE0_RX_DP<2>")
	)
	(segment
		(start 85.676232 -220.39961)
		(end 85.656928 -220.410024)
		(width 0.0889)
		(layer "In13.Cu")
		(net "P5E_CPU1_PE0_RX_DP<2>")
	)
	(segment
		(start 73.471024 -346.54363)
		(end 74.036174 -350.108774)
		(width 0.14732)
		(layer "In13.Cu")
		(net "P5E_CPU1_PE0_RX_DP<2>")
	)
	(segment
		(start 86.162896 -220.116146)
		(end 85.890354 -220.235018)
		(width 0.0889)
		(layer "In13.Cu")
		(net "P5E_CPU1_PE0_RX_DP<2>")
	)
	(segment
		(start 88.928702 -396.581122)
		(end 89.04478 -396.94358)
		(width 0.14732)
		(layer "In13.Cu")
		(net "P5E_CPU1_PE0_RX_DP<2>")
	)
	(segment
		(start 91.434412 -221.94774)
		(end 91.277948 -221.676722)
		(width 0.0889)
		(layer "In13.Cu")
		(net "P5E_CPU1_PE0_RX_DP<2>")
	)
	(segment
		(start 87.09406 -390.854946)
		(end 87.276178 -390.948672)
		(width 0.14732)
		(layer "In13.Cu")
		(net "P5E_CPU1_PE0_RX_DP<2>")
	)
	(segment
		(start 75.540108 -326.12203)
		(end 73.471024 -331.11694)
		(width 0.14732)
		(layer "In13.Cu")
		(net "P5E_CPU1_PE0_RX_DP<2>")
	)
	(segment
		(start 81.263998 -245.84279)
		(end 81.403698 -246.637048)
		(width 0.14732)
		(layer "In13.Cu")
		(net "P5E_CPU1_PE0_RX_DP<2>")
	)
	(segment
		(start 89.022428 -396.399004)
		(end 88.928702 -396.581122)
		(width 0.14732)
		(layer "In13.Cu")
		(net "P5E_CPU1_PE0_RX_DP<2>")
	)
	(segment
		(start 86.981284 -390.504172)
		(end 86.981792 -390.504426)
		(width 0.14732)
		(layer "In13.Cu")
		(net "P5E_CPU1_PE0_RX_DP<2>")
	)
	(segment
		(start 88.596724 -395.070584)
		(end 88.709246 -395.421612)
		(width 0.14732)
		(layer "In13.Cu")
		(net "P5E_CPU1_PE0_RX_DP<2>")
	)
	(segment
		(start 80.888078 -259.386324)
		(end 80.235552 -266.632436)
		(width 0.14732)
		(layer "In13.Cu")
		(net "P5E_CPU1_PE0_RX_DP<2>")
	)
	(segment
		(start 84.955126 -423.946828)
		(end 84.955126 -438.194958)
		(width 0.14732)
		(layer "In13.Cu")
		(net "P5E_CPU1_PE0_RX_DP<2>")
	)
	(segment
		(start 83.685888 -221.483428)
		(end 83.19516 -221.837758)
		(width 0.14732)
		(layer "In13.Cu")
		(net "P5E_CPU1_PE0_RX_DP<2>")
	)
	(segment
		(start 84.955126 -438.194958)
		(end 85.079586 -438.319418)
		(width 0.14732)
		(layer "In13.Cu")
		(net "P5E_CPU1_PE0_RX_DP<2>")
	)
	(segment
		(start 87.965026 -393.57427)
		(end 88.147398 -393.667996)
		(width 0.14732)
		(layer "In13.Cu")
		(net "P5E_CPU1_PE0_RX_DP<2>")
	)
	(segment
		(start 88.16594 -394.200888)
		(end 88.414606 -394.976858)
		(width 0.14732)
		(layer "In13.Cu")
		(net "P5E_CPU1_PE0_RX_DP<2>")
	)
	(segment
		(start 85.482938 -438.319418)
		(end 85.65007 -438.152286)
		(width 0.14732)
		(layer "In13.Cu")
		(net "P5E_CPU1_PE0_RX_DP<2>")
	)
	(segment
		(start 90.68181 -220.644212)
		(end 90.6907 -220.639132)
		(width 0.0889)
		(layer "In13.Cu")
		(net "P5E_CPU1_PE0_RX_DP<2>")
	)
	(segment
		(start 81.403698 -246.637048)
		(end 82.881216 -249.401076)
		(width 0.14732)
		(layer "In13.Cu")
		(net "P5E_CPU1_PE0_RX_DP<2>")
	)
	(segment
		(start 87.651844 -392.596878)
		(end 87.833962 -392.690604)
		(width 0.14732)
		(layer "In13.Cu")
		(net "P5E_CPU1_PE0_RX_DP<2>")
	)
	(segment
		(start 80.913478 -234.05338)
		(end 81.124552 -245.048786)
		(width 0.14732)
		(layer "In13.Cu")
		(net "P5E_CPU1_PE0_RX_DP<2>")
	)
	(segment
		(start 85.656928 -220.410024)
		(end 83.685888 -221.483428)
		(width 0.14732)
		(layer "In13.Cu")
		(net "P5E_CPU1_PE0_RX_DP<2>")
	)
	(segment
		(start 87.853012 -393.223496)
		(end 87.965534 -393.57427)
		(width 0.14732)
		(layer "In13.Cu")
		(net "P5E_CPU1_PE0_RX_DP<2>")
	)
	(segment
		(start 91.277948 -221.676722)
		(end 91.189048 -221.6531)
		(width 0.0889)
		(layer "In13.Cu")
		(net "P5E_CPU1_PE0_RX_DP<2>")
	)
	(segment
		(start 88.909906 -396.047976)
		(end 89.022428 -396.399004)
		(width 0.14732)
		(layer "In13.Cu")
		(net "P5E_CPU1_PE0_RX_DP<2>")
	)
	(segment
		(start 83.044792 -310.765444)
		(end 78.151482 -322.392802)
		(width 0.14732)
		(layer "In13.Cu")
		(net "P5E_CPU1_PE0_RX_DP<2>")
	)
	(segment
		(start 85.65007 -438.152286)
		(end 85.65007 -437.889904)
		(width 0.14732)
		(layer "In13.Cu")
		(net "P5E_CPU1_PE0_RX_DP<2>")
	)
	(segment
		(start 88.709246 -395.421612)
		(end 88.61552 -395.60373)
		(width 0.14732)
		(layer "In13.Cu")
		(net "P5E_CPU1_PE0_RX_DP<2>")
	)
	(segment
		(start 90.307414 -219.995496)
		(end 90.297 -220.001592)
		(width 0.0889)
		(layer "In13.Cu")
		(net "P5E_CPU1_PE0_RX_DP<2>")
	)
	(segment
		(start 83.19516 -221.837758)
		(end 82.882232 -222.365824)
		(width 0.14732)
		(layer "In13.Cu")
		(net "P5E_CPU1_PE0_RX_DP<2>")
	)
	(segment
		(start 87.3887 -391.2997)
		(end 87.294974 -391.481818)
		(width 0.14732)
		(layer "In13.Cu")
		(net "P5E_CPU1_PE0_RX_DP<2>")
	)
	(segment
		(start 74.036174 -350.108774)
		(end 86.981284 -390.504172)
		(width 0.14732)
		(layer "In13.Cu")
		(net "P5E_CPU1_PE0_RX_DP<2>")
	)
	(segment
		(start 89.902538 -404.596092)
		(end 88.185498 -406.313132)
		(width 0.14732)
		(layer "In13.Cu")
		(net "P5E_CPU1_PE0_RX_DP<2>")
	)
	(segment
		(start 73.471024 -331.11694)
		(end 73.471024 -346.54363)
		(width 0.14732)
		(layer "In13.Cu")
		(net "P5E_CPU1_PE0_RX_DP<2>")
	)
	(segment
		(start 89.04478 -396.94358)
		(end 89.227152 -397.037306)
		(width 0.14732)
		(layer "In13.Cu")
		(net "P5E_CPU1_PE0_RX_DP<2>")
	)
	(segment
		(start 86.981792 -390.504426)
		(end 87.09406 -390.854946)
		(width 0.14732)
		(layer "In13.Cu")
		(net "P5E_CPU1_PE0_RX_DP<2>")
	)
	(segment
		(start 82.881216 -249.401076)
		(end 83.455764 -250.789186)
		(width 0.14732)
		(layer "In13.Cu")
		(net "P5E_CPU1_PE0_RX_DP<2>")
	)
	(segment
		(start 90.6907 -220.000576)
		(end 90.68181 -219.995496)
		(width 0.0889)
		(layer "In13.Cu")
		(net "P5E_CPU1_PE0_RX_DP<2>")
	)
	(segment
		(start 85.890354 -220.235018)
		(end 85.692742 -220.34246)
		(width 0.0889)
		(layer "In13.Cu")
		(net "P5E_CPU1_PE0_RX_DP<2>")
	)
	(segment
		(start 88.259666 -394.019024)
		(end 88.16594 -394.200888)
		(width 0.14732)
		(layer "In13.Cu")
		(net "P5E_CPU1_PE0_RX_DP<2>")
	)
	(segment
		(start 88.61552 -395.60373)
		(end 88.727788 -395.95425)
		(width 0.14732)
		(layer "In13.Cu")
		(net "P5E_CPU1_PE0_RX_DP<2>")
	)
	(segment
		(start 87.833962 -392.690604)
		(end 87.946484 -393.041632)
		(width 0.14732)
		(layer "In13.Cu")
		(net "P5E_CPU1_PE0_RX_DP<2>")
	)
	(segment
		(start 88.147398 -393.667996)
		(end 88.259666 -394.019024)
		(width 0.14732)
		(layer "In13.Cu")
		(net "P5E_CPU1_PE0_RX_DP<2>")
	)
	(segment
		(start 85.692742 -220.34246)
		(end 85.676232 -220.39961)
		(width 0.0889)
		(layer "In13.Cu")
		(net "P5E_CPU1_PE0_RX_DP<2>")
	)
	(segment
		(start 88.185498 -406.313132)
		(end 88.185498 -411.45714)
		(width 0.14732)
		(layer "In13.Cu")
		(net "P5E_CPU1_PE0_RX_DP<2>")
	)
	(segment
		(start 89.33942 -397.38808)
		(end 89.245694 -397.570198)
		(width 0.14732)
		(layer "In13.Cu")
		(net "P5E_CPU1_PE0_RX_DP<2>")
	)
	(segment
		(start 78.151482 -322.392802)
		(end 75.540108 -326.12203)
		(width 0.14732)
		(layer "In13.Cu")
		(net "P5E_CPU1_PE0_RX_DP<2>")
	)
	(segment
		(start 88.185498 -411.45714)
		(end 84.955126 -423.946828)
		(width 0.14732)
		(layer "In13.Cu")
		(net "P5E_CPU1_PE0_RX_DP<2>")
	)
	(segment
		(start 88.727788 -395.95425)
		(end 88.909906 -396.047976)
		(width 0.14732)
		(layer "In13.Cu")
		(net "P5E_CPU1_PE0_RX_DP<2>")
	)
	(segment
		(start 83.455764 -252.797818)
		(end 80.888078 -259.386324)
		(width 0.14732)
		(layer "In13.Cu")
		(net "P5E_CPU1_PE0_RX_DP<2>")
	)
	(segment
		(start 89.902538 -399.619978)
		(end 89.902538 -404.596092)
		(width 0.14732)
		(layer "In13.Cu")
		(net "P5E_CPU1_PE0_RX_DP<2>")
	)
	(segment
		(start 87.946484 -393.041632)
		(end 87.853012 -393.223496)
		(width 0.14732)
		(layer "In13.Cu")
		(net "P5E_CPU1_PE0_RX_DP<2>")
	)
	(segment
		(start 89.227152 -397.037306)
		(end 89.33942 -397.38808)
		(width 0.14732)
		(layer "In13.Cu")
		(net "P5E_CPU1_PE0_RX_DP<2>")
	)
	(segment
		(start 83.455764 -250.789186)
		(end 83.455764 -252.797818)
		(width 0.14732)
		(layer "In13.Cu")
		(net "P5E_CPU1_PE0_RX_DP<2>")
	)
	(segment
		(start 87.276178 -390.948672)
		(end 87.3887 -391.2997)
		(width 0.14732)
		(layer "In13.Cu")
		(net "P5E_CPU1_PE0_RX_DP<2>")
	)
	(segment
		(start 82.882232 -222.365824)
		(end 80.913478 -234.05338)
		(width 0.14732)
		(layer "In13.Cu")
		(net "P5E_CPU1_PE0_RX_DP<2>")
	)
	(segment
		(start 85.079586 -438.319418)
		(end 85.482938 -438.319418)
		(width 0.14732)
		(layer "In13.Cu")
		(net "P5E_CPU1_PE0_RX_DP<2>")
	)
	(segment
		(start 90.399616 -221.149418)
		(end 90.399616 -221.111826)
		(width 0.0889)
		(layer "In13.Cu")
		(net "P5E_CPU1_PE0_RX_DP<2>")
	)
	(segment
		(start 87.965534 -393.57427)
		(end 87.965026 -393.57427)
		(width 0.14732)
		(layer "In13.Cu")
		(net "P5E_CPU1_PE0_RX_DP<2>")
	)
	(segment
		(start 88.414606 -394.976858)
		(end 88.596724 -395.070584)
		(width 0.14732)
		(layer "In13.Cu")
		(net "P5E_CPU1_PE0_RX_DP<2>")
	)
	(segment
		(start 89.245694 -397.570198)
		(end 89.902538 -399.619978)
		(width 0.14732)
		(layer "In13.Cu")
		(net "P5E_CPU1_PE0_RX_DP<2>")
	)
	(segment
		(start 80.235552 -266.632436)
		(end 83.044792 -310.765444)
		(width 0.14732)
		(layer "In13.Cu")
		(net "P5E_CPU1_PE0_RX_DP<2>")
	)
	(segment
		(start 87.294974 -391.481818)
		(end 87.651844 -392.596878)
		(width 0.14732)
		(layer "In13.Cu")
		(net "P5E_CPU1_PE0_RX_DP<2>")
	)
	(segment
		(start 81.124552 -245.048786)
		(end 81.263998 -245.84279)
		(width 0.14732)
		(layer "In13.Cu")
		(net "P5E_CPU1_PE0_RX_DP<2>")
	)
	(arc
		(start 90.68181 -219.995496)
		(mid 90.494612 -219.945353)
		(end 90.307414 -219.995496)
		(width 0.0889)
		(layer "In13.Cu")
		(net "P5E_CPU1_PE0_RX_DP<2>")
	)
	(arc
		(start 88.428068 -219.995496)
		(mid 88.145366 -220.071272)
		(end 87.862664 -219.995496)
		(width 0.0889)
		(layer "In13.Cu")
		(net "P5E_CPU1_PE0_RX_DP<2>")
	)
	(arc
		(start 88.802464 -219.995496)
		(mid 88.615266 -219.945353)
		(end 88.428068 -219.995496)
		(width 0.0889)
		(layer "In13.Cu")
		(net "P5E_CPU1_PE0_RX_DP<2>")
	)
	(arc
		(start 86.34476 -220.061028)
		(mid 86.252226 -220.083302)
		(end 86.162896 -220.116146)
		(width 0.0889)
		(layer "In13.Cu")
		(net "P5E_CPU1_PE0_RX_DP<2>")
	)
	(arc
		(start 87.862664 -219.995496)
		(mid 87.675466 -219.945353)
		(end 87.488268 -219.995496)
		(width 0.0889)
		(layer "In13.Cu")
		(net "P5E_CPU1_PE0_RX_DP<2>")
	)
	(arc
		(start 89.367868 -219.995496)
		(mid 89.085166 -220.071272)
		(end 88.802464 -219.995496)
		(width 0.0889)
		(layer "In13.Cu")
		(net "P5E_CPU1_PE0_RX_DP<2>")
	)
	(arc
		(start 86.553548 -219.992448)
		(mid 86.547387 -219.995868)
		(end 86.541102 -219.999052)
		(width 0.0889)
		(layer "In13.Cu")
		(net "P5E_CPU1_PE0_RX_DP<2>")
	)
	(arc
		(start 91.189048 -221.6531)
		(mid 91.179181 -221.657259)
		(end 91.169236 -221.661228)
		(width 0.0889)
		(layer "In13.Cu")
		(net "P5E_CPU1_PE0_RX_DP<2>")
	)
	(arc
		(start 90.399616 -221.111826)
		(mid 90.480527 -220.841698)
		(end 90.68181 -220.644212)
		(width 0.0889)
		(layer "In13.Cu")
		(net "P5E_CPU1_PE0_RX_DP<2>")
	)
	(arc
		(start 89.742264 -219.995496)
		(mid 89.555066 -219.945353)
		(end 89.367868 -219.995496)
		(width 0.0889)
		(layer "In13.Cu")
		(net "P5E_CPU1_PE0_RX_DP<2>")
	)
	(arc
		(start 86.541102 -219.999052)
		(mid 86.444883 -220.036226)
		(end 86.34476 -220.061028)
		(width 0.0889)
		(layer "In13.Cu")
		(net "P5E_CPU1_PE0_RX_DP<2>")
	)
	(arc
		(start 90.68181 -221.623382)
		(mid 90.478987 -221.423151)
		(end 90.399616 -221.149418)
		(width 0.0889)
		(layer "In13.Cu")
		(net "P5E_CPU1_PE0_RX_DP<2>")
	)
	(arc
		(start 91.169236 -221.661228)
		(mid 90.921225 -221.697693)
		(end 90.68181 -221.623382)
		(width 0.0889)
		(layer "In13.Cu")
		(net "P5E_CPU1_PE0_RX_DP<2>")
	)
	(arc
		(start 90.6907 -220.639132)
		(mid 90.869297 -220.319854)
		(end 90.6907 -220.000576)
		(width 0.0889)
		(layer "In13.Cu")
		(net "P5E_CPU1_PE0_RX_DP<2>")
	)
	(arc
		(start 87.488268 -219.995496)
		(mid 87.205566 -220.071272)
		(end 86.922864 -219.995496)
		(width 0.0889)
		(layer "In13.Cu")
		(net "P5E_CPU1_PE0_RX_DP<2>")
	)
	(arc
		(start 90.297 -220.001592)
		(mid 90.018822 -220.071315)
		(end 89.742264 -219.995496)
		(width 0.0889)
		(layer "In13.Cu")
		(net "P5E_CPU1_PE0_RX_DP<2>")
	)
	(arc
		(start 86.922864 -219.995496)
		(mid 86.738595 -219.945239)
		(end 86.553548 -219.992448)
		(width 0.0889)
		(layer "In13.Cu")
		(net "P5E_CPU1_PE0_RX_DP<2>")
	)
	(segment
		(start 90.494866 -220.855794)
		(end 90.494612 -220.85554)
		(width 0.13208)
		(layer "F.Cu")
		(net "P5E_CPU1_PE0_RX_DP<1>")
	)
	(segment
		(start 90.494612 -220.85554)
		(end 90.494612 -220.319854)
		(width 0.13208)
		(layer "F.Cu")
		(net "P5E_CPU1_PE0_RX_DP<1>")
	)
	(segment
		(start 83.71078 -310.90362)
		(end 80.892904 -266.641072)
		(width 0.14732)
		(layer "In13.Cu")
		(net "P5E_CPU1_PE0_RX_DP<1>")
	)
	(segment
		(start 84.111084 -252.921008)
		(end 84.111084 -250.65736)
		(width 0.14732)
		(layer "In13.Cu")
		(net "P5E_CPU1_PE0_RX_DP<1>")
	)
	(segment
		(start 87.48395 -220.988636)
		(end 87.583772 -220.888814)
		(width 0.0889)
		(layer "In13.Cu")
		(net "P5E_CPU1_PE0_RX_DP<1>")
	)
	(segment
		(start 87.608664 -385.664964)
		(end 87.606632 -385.658868)
		(width 0.14732)
		(layer "In13.Cu")
		(net "P5E_CPU1_PE0_RX_DP<1>")
	)
	(segment
		(start 84.180172 -221.967044)
		(end 86.303358 -221.143068)
		(width 0.14732)
		(layer "In13.Cu")
		(net "P5E_CPU1_PE0_RX_DP<1>")
	)
	(segment
		(start 87.754968 -386.06984)
		(end 87.608664 -385.664964)
		(width 0.14732)
		(layer "In13.Cu")
		(net "P5E_CPU1_PE0_RX_DP<1>")
	)
	(segment
		(start 84.111084 -250.65736)
		(end 83.471258 -249.112786)
		(width 0.14732)
		(layer "In13.Cu")
		(net "P5E_CPU1_PE0_RX_DP<1>")
	)
	(segment
		(start 86.61019 -382.89992)
		(end 86.609936 -382.899158)
		(width 0.14732)
		(layer "In13.Cu")
		(net "P5E_CPU1_PE0_RX_DP<1>")
	)
	(segment
		(start 80.892904 -266.641072)
		(end 81.532476 -259.537708)
		(width 0.14732)
		(layer "In13.Cu")
		(net "P5E_CPU1_PE0_RX_DP<1>")
	)
	(segment
		(start 75.99426 -326.760586)
		(end 78.606396 -323.030342)
		(width 0.14732)
		(layer "In13.Cu")
		(net "P5E_CPU1_PE0_RX_DP<1>")
	)
	(segment
		(start 86.96579 -437.59374)
		(end 86.680802 -437.308752)
		(width 0.14732)
		(layer "In13.Cu")
		(net "P5E_CPU1_PE0_RX_DP<1>")
	)
	(segment
		(start 90.338148 -220.590872)
		(end 90.494612 -220.319854)
		(width 0.0889)
		(layer "In13.Cu")
		(net "P5E_CPU1_PE0_RX_DP<1>")
	)
	(segment
		(start 88.802464 -220.644212)
		(end 88.802972 -220.64472)
		(width 0.0889)
		(layer "In13.Cu")
		(net "P5E_CPU1_PE0_RX_DP<1>")
	)
	(segment
		(start 90.974418 -406.19934)
		(end 92.691458 -404.4823)
		(width 0.14732)
		(layer "In13.Cu")
		(net "P5E_CPU1_PE0_RX_DP<1>")
	)
	(segment
		(start 92.691458 -404.4823)
		(end 92.691458 -399.738088)
		(width 0.14732)
		(layer "In13.Cu")
		(net "P5E_CPU1_PE0_RX_DP<1>")
	)
	(segment
		(start 90.248994 -220.615256)
		(end 90.249248 -220.614748)
		(width 0.0889)
		(layer "In13.Cu")
		(net "P5E_CPU1_PE0_RX_DP<1>")
	)
	(segment
		(start 87.27059 -221.143068)
		(end 87.409528 -221.00413)
		(width 0.14732)
		(layer "In13.Cu")
		(net "P5E_CPU1_PE0_RX_DP<1>")
	)
	(segment
		(start 81.532476 -259.537708)
		(end 84.111084 -252.921008)
		(width 0.14732)
		(layer "In13.Cu")
		(net "P5E_CPU1_PE0_RX_DP<1>")
	)
	(segment
		(start 81.898744 -245.651274)
		(end 81.815432 -233.178858)
		(width 0.14732)
		(layer "In13.Cu")
		(net "P5E_CPU1_PE0_RX_DP<1>")
	)
	(segment
		(start 86.303358 -221.143068)
		(end 87.27059 -221.143068)
		(width 0.14732)
		(layer "In13.Cu")
		(net "P5E_CPU1_PE0_RX_DP<1>")
	)
	(segment
		(start 90.249248 -220.614748)
		(end 90.338148 -220.590872)
		(width 0.0889)
		(layer "In13.Cu")
		(net "P5E_CPU1_PE0_RX_DP<1>")
	)
	(segment
		(start 83.773518 -222.251778)
		(end 84.180172 -221.967044)
		(width 0.14732)
		(layer "In13.Cu")
		(net "P5E_CPU1_PE0_RX_DP<1>")
	)
	(segment
		(start 87.425022 -220.988636)
		(end 87.48395 -220.988636)
		(width 0.0889)
		(layer "In13.Cu")
		(net "P5E_CPU1_PE0_RX_DP<1>")
	)
	(segment
		(start 86.680802 -423.845228)
		(end 90.974418 -411.290516)
		(width 0.14732)
		(layer "In13.Cu")
		(net "P5E_CPU1_PE0_RX_DP<1>")
	)
	(segment
		(start 74.19848 -331.095858)
		(end 75.99426 -326.760586)
		(width 0.14732)
		(layer "In13.Cu")
		(net "P5E_CPU1_PE0_RX_DP<1>")
	)
	(segment
		(start 74.777346 -350.13773)
		(end 74.19848 -346.486226)
		(width 0.14732)
		(layer "In13.Cu")
		(net "P5E_CPU1_PE0_RX_DP<1>")
	)
	(segment
		(start 82.035904 -246.42953)
		(end 81.898744 -245.651274)
		(width 0.14732)
		(layer "In13.Cu")
		(net "P5E_CPU1_PE0_RX_DP<1>")
	)
	(segment
		(start 81.815432 -233.178858)
		(end 83.543648 -222.617792)
		(width 0.14732)
		(layer "In13.Cu")
		(net "P5E_CPU1_PE0_RX_DP<1>")
	)
	(segment
		(start 87.409528 -221.00413)
		(end 87.425022 -220.988636)
		(width 0.0889)
		(layer "In13.Cu")
		(net "P5E_CPU1_PE0_RX_DP<1>")
	)
	(segment
		(start 83.471258 -249.112786)
		(end 82.035904 -246.42953)
		(width 0.14732)
		(layer "In13.Cu")
		(net "P5E_CPU1_PE0_RX_DP<1>")
	)
	(segment
		(start 87.650066 -437.741314)
		(end 87.502492 -437.59374)
		(width 0.14732)
		(layer "In13.Cu")
		(net "P5E_CPU1_PE0_RX_DP<1>")
	)
	(segment
		(start 87.755222 -386.070602)
		(end 87.754968 -386.06984)
		(width 0.14732)
		(layer "In13.Cu")
		(net "P5E_CPU1_PE0_RX_DP<1>")
	)
	(segment
		(start 87.650066 -438.089802)
		(end 87.650066 -437.741314)
		(width 0.14732)
		(layer "In13.Cu")
		(net "P5E_CPU1_PE0_RX_DP<1>")
	)
	(segment
		(start 86.609936 -382.899158)
		(end 74.777346 -350.13773)
		(width 0.14732)
		(layer "In13.Cu")
		(net "P5E_CPU1_PE0_RX_DP<1>")
	)
	(segment
		(start 92.691458 -399.738088)
		(end 87.755222 -386.070602)
		(width 0.14732)
		(layer "In13.Cu")
		(net "P5E_CPU1_PE0_RX_DP<1>")
	)
	(segment
		(start 78.606396 -323.030342)
		(end 83.71078 -310.90362)
		(width 0.14732)
		(layer "In13.Cu")
		(net "P5E_CPU1_PE0_RX_DP<1>")
	)
	(segment
		(start 74.19848 -346.486226)
		(end 74.19848 -331.095858)
		(width 0.14732)
		(layer "In13.Cu")
		(net "P5E_CPU1_PE0_RX_DP<1>")
	)
	(segment
		(start 87.606632 -385.658868)
		(end 86.61019 -382.89992)
		(width 0.14732)
		(layer "In13.Cu")
		(net "P5E_CPU1_PE0_RX_DP<1>")
	)
	(segment
		(start 87.502492 -437.59374)
		(end 86.96579 -437.59374)
		(width 0.14732)
		(layer "In13.Cu")
		(net "P5E_CPU1_PE0_RX_DP<1>")
	)
	(segment
		(start 83.543648 -222.617792)
		(end 83.773518 -222.251778)
		(width 0.14732)
		(layer "In13.Cu")
		(net "P5E_CPU1_PE0_RX_DP<1>")
	)
	(segment
		(start 90.974418 -411.290516)
		(end 90.974418 -406.19934)
		(width 0.14732)
		(layer "In13.Cu")
		(net "P5E_CPU1_PE0_RX_DP<1>")
	)
	(segment
		(start 86.680802 -437.308752)
		(end 86.680802 -423.845228)
		(width 0.14732)
		(layer "In13.Cu")
		(net "P5E_CPU1_PE0_RX_DP<1>")
	)
	(arc
		(start 88.428068 -220.644212)
		(mid 88.615266 -220.694355)
		(end 88.802464 -220.644212)
		(width 0.0889)
		(layer "In13.Cu")
		(net "P5E_CPU1_PE0_RX_DP<1>")
	)
	(arc
		(start 89.36736 -220.64472)
		(mid 89.555066 -220.695049)
		(end 89.742772 -220.64472)
		(width 0.0889)
		(layer "In13.Cu")
		(net "P5E_CPU1_PE0_RX_DP<1>")
	)
	(arc
		(start 89.742772 -220.64472)
		(mid 89.981708 -220.570715)
		(end 90.229182 -220.607128)
		(width 0.0889)
		(layer "In13.Cu")
		(net "P5E_CPU1_PE0_RX_DP<1>")
	)
	(arc
		(start 87.862664 -220.644212)
		(mid 88.145366 -220.56847)
		(end 88.428068 -220.644212)
		(width 0.0889)
		(layer "In13.Cu")
		(net "P5E_CPU1_PE0_RX_DP<1>")
	)
	(arc
		(start 87.764112 -220.716094)
		(mid 87.81145 -220.677497)
		(end 87.862664 -220.644212)
		(width 0.0889)
		(layer "In13.Cu")
		(net "P5E_CPU1_PE0_RX_DP<1>")
	)
	(arc
		(start 87.583772 -220.888814)
		(mid 87.672986 -220.801455)
		(end 87.764112 -220.716094)
		(width 0.0889)
		(layer "In13.Cu")
		(net "P5E_CPU1_PE0_RX_DP<1>")
	)
	(arc
		(start 90.229182 -220.607128)
		(mid 90.239126 -220.611099)
		(end 90.248994 -220.615256)
		(width 0.0889)
		(layer "In13.Cu")
		(net "P5E_CPU1_PE0_RX_DP<1>")
	)
	(arc
		(start 88.802972 -220.64472)
		(mid 89.085166 -220.569164)
		(end 89.36736 -220.64472)
		(width 0.0889)
		(layer "In13.Cu")
		(net "P5E_CPU1_PE0_RX_DP<1>")
	)
	(segment
		(start 103.181912 -221.669864)
		(end 103.181912 -221.134178)
		(width 0.13208)
		(layer "F.Cu")
		(net "P5E_CPU1_PE0_RX_DP<15>")
	)
	(segment
		(start 103.181912 -221.134178)
		(end 103.182166 -221.133924)
		(width 0.13208)
		(layer "F.Cu")
		(net "P5E_CPU1_PE0_RX_DP<15>")
	)
	(segment
		(start 67.733418 -314.18022)
		(end 68.933314 -309.90413)
		(width 0.14732)
		(layer "In13.Cu")
		(net "P5E_CPU1_PE0_RX_DP<15>")
	)
	(segment
		(start 87.065612 -199.53351)
		(end 90.619834 -199.53351)
		(width 0.14732)
		(layer "In13.Cu")
		(net "P5E_CPU1_PE0_RX_DP<15>")
	)
	(segment
		(start 66.901314 -249.919744)
		(end 68.309744 -232.16108)
		(width 0.14732)
		(layer "In13.Cu")
		(net "P5E_CPU1_PE0_RX_DP<15>")
	)
	(segment
		(start 51.410108 -396.70482)
		(end 51.506628 -396.348966)
		(width 0.14732)
		(layer "In13.Cu")
		(net "P5E_CPU1_PE0_RX_DP<15>")
	)
	(segment
		(start 48.701706 -411.140402)
		(end 48.363378 -410.259276)
		(width 0.14732)
		(layer "In13.Cu")
		(net "P5E_CPU1_PE0_RX_DP<15>")
	)
	(segment
		(start 54.155086 -384.542538)
		(end 54.303422 -384.447288)
		(width 0.14732)
		(layer "In13.Cu")
		(net "P5E_CPU1_PE0_RX_DP<15>")
	)
	(segment
		(start 63.682626 -317.2714)
		(end 64.265556 -317.2714)
		(width 0.14732)
		(layer "In13.Cu")
		(net "P5E_CPU1_PE0_RX_DP<15>")
	)
	(segment
		(start 57.127648 -370.814346)
		(end 58.485532 -362.446062)
		(width 0.14732)
		(layer "In13.Cu")
		(net "P5E_CPU1_PE0_RX_DP<15>")
	)
	(segment
		(start 53.114702 -389.933942)
		(end 53.207158 -389.506714)
		(width 0.14732)
		(layer "In13.Cu")
		(net "P5E_CPU1_PE0_RX_DP<15>")
	)
	(segment
		(start 99.522788 -206.578962)
		(end 99.831906 -206.88808)
		(width 0.14732)
		(layer "In13.Cu")
		(net "P5E_CPU1_PE0_RX_DP<15>")
	)
	(segment
		(start 54.633622 -382.92278)
		(end 54.538372 -382.774952)
		(width 0.14732)
		(layer "In13.Cu")
		(net "P5E_CPU1_PE0_RX_DP<15>")
	)
	(segment
		(start 65.847976 -315.68898)
		(end 66.32575 -315.68898)
		(width 0.14732)
		(layer "In13.Cu")
		(net "P5E_CPU1_PE0_RX_DP<15>")
	)
	(segment
		(start 102.617016 -219.490544)
		(end 102.617016 -219.515944)
		(width 0.0889)
		(layer "In13.Cu")
		(net "P5E_CPU1_PE0_RX_DP<15>")
	)
	(segment
		(start 100.618544 -207.502252)
		(end 102.104698 -211.090002)
		(width 0.14732)
		(layer "In13.Cu")
		(net "P5E_CPU1_PE0_RX_DP<15>")
	)
	(segment
		(start 76.233782 -209.705194)
		(end 84.29117 -200.966324)
		(width 0.14732)
		(layer "In13.Cu")
		(net "P5E_CPU1_PE0_RX_DP<15>")
	)
	(segment
		(start 53.679852 -386.737098)
		(end 53.827934 -386.641848)
		(width 0.14732)
		(layer "In13.Cu")
		(net "P5E_CPU1_PE0_RX_DP<15>")
	)
	(segment
		(start 66.32575 -315.68898)
		(end 66.878708 -315.40069)
		(width 0.14732)
		(layer "In13.Cu")
		(net "P5E_CPU1_PE0_RX_DP<15>")
	)
	(segment
		(start 100.004372 -206.88808)
		(end 100.618544 -207.502252)
		(width 0.14732)
		(layer "In13.Cu")
		(net "P5E_CPU1_PE0_RX_DP<15>")
	)
	(segment
		(start 51.839876 -395.125194)
		(end 51.738022 -394.947394)
		(width 0.14732)
		(layer "In13.Cu")
		(net "P5E_CPU1_PE0_RX_DP<15>")
	)
	(segment
		(start 57.747154 -436.983378)
		(end 57.734454 -436.979822)
		(width 0.14732)
		(layer "In13.Cu")
		(net "P5E_CPU1_PE0_RX_DP<15>")
	)
	(segment
		(start 51.028346 -397.554958)
		(end 51.232054 -396.80642)
		(width 0.14732)
		(layer "In13.Cu")
		(net "P5E_CPU1_PE0_RX_DP<15>")
	)
	(segment
		(start 70.134734 -305.622198)
		(end 66.795396 -253.46914)
		(width 0.14732)
		(layer "In13.Cu")
		(net "P5E_CPU1_PE0_RX_DP<15>")
	)
	(segment
		(start 102.147116 -213.893654)
		(end 102.147116 -213.930484)
		(width 0.0889)
		(layer "In13.Cu")
		(net "P5E_CPU1_PE0_RX_DP<15>")
	)
	(segment
		(start 102.146862 -213.217252)
		(end 102.146862 -213.8934)
		(width 0.0889)
		(layer "In13.Cu")
		(net "P5E_CPU1_PE0_RX_DP<15>")
	)
	(segment
		(start 48.363378 -406.313132)
		(end 50.080418 -404.596092)
		(width 0.14732)
		(layer "In13.Cu")
		(net "P5E_CPU1_PE0_RX_DP<15>")
	)
	(segment
		(start 68.934076 -309.901082)
		(end 70.134734 -305.622198)
		(width 0.14732)
		(layer "In13.Cu")
		(net "P5E_CPU1_PE0_RX_DP<15>")
	)
	(segment
		(start 58.705242 -323.28739)
		(end 59.41822 -322.574412)
		(width 0.14732)
		(layer "In13.Cu")
		(net "P5E_CPU1_PE0_RX_DP<15>")
	)
	(segment
		(start 52.540408 -391.997946)
		(end 52.96662 -390.030208)
		(width 0.14732)
		(layer "In13.Cu")
		(net "P5E_CPU1_PE0_RX_DP<15>")
	)
	(segment
		(start 66.795396 -253.46914)
		(end 66.795396 -253.468886)
		(width 0.14732)
		(layer "In13.Cu")
		(net "P5E_CPU1_PE0_RX_DP<15>")
	)
	(segment
		(start 58.485532 -362.446062)
		(end 59.14009 -342.085422)
		(width 0.14732)
		(layer "In13.Cu")
		(net "P5E_CPU1_PE0_RX_DP<15>")
	)
	(segment
		(start 59.41822 -322.574412)
		(end 60.056776 -322.309998)
		(width 0.14732)
		(layer "In13.Cu")
		(net "P5E_CPU1_PE0_RX_DP<15>")
	)
	(segment
		(start 60.419234 -322.067682)
		(end 61.387228 -321.099688)
		(width 0.14732)
		(layer "In13.Cu")
		(net "P5E_CPU1_PE0_RX_DP<15>")
	)
	(segment
		(start 66.795396 -253.468886)
		(end 66.901314 -249.919744)
		(width 0.14732)
		(layer "In13.Cu")
		(net "P5E_CPU1_PE0_RX_DP<15>")
	)
	(segment
		(start 68.309744 -232.16108)
		(end 70.434454 -218.412568)
		(width 0.14732)
		(layer "In13.Cu")
		(net "P5E_CPU1_PE0_RX_DP<15>")
	)
	(segment
		(start 90.619834 -199.53351)
		(end 94.085156 -200.968864)
		(width 0.14732)
		(layer "In13.Cu")
		(net "P5E_CPU1_PE0_RX_DP<15>")
	)
	(segment
		(start 84.29117 -200.966324)
		(end 87.065612 -199.53351)
		(width 0.14732)
		(layer "In13.Cu")
		(net "P5E_CPU1_PE0_RX_DP<15>")
	)
	(segment
		(start 51.405028 -396.17142)
		(end 51.405282 -396.170404)
		(width 0.14732)
		(layer "In13.Cu")
		(net "P5E_CPU1_PE0_RX_DP<15>")
	)
	(segment
		(start 103.3145 -220.773752)
		(end 103.33863 -220.862906)
		(width 0.0889)
		(layer "In13.Cu")
		(net "P5E_CPU1_PE0_RX_DP<15>")
	)
	(segment
		(start 54.303422 -384.447288)
		(end 54.395878 -384.02006)
		(width 0.14732)
		(layer "In13.Cu")
		(net "P5E_CPU1_PE0_RX_DP<15>")
	)
	(segment
		(start 102.429564 -215.926162)
		(end 102.438454 -215.931242)
		(width 0.0889)
		(layer "In13.Cu")
		(net "P5E_CPU1_PE0_RX_DP<15>")
	)
	(segment
		(start 61.387228 -321.099688)
		(end 61.387228 -319.566798)
		(width 0.14732)
		(layer "In13.Cu")
		(net "P5E_CPU1_PE0_RX_DP<15>")
	)
	(segment
		(start 53.352446 -388.836662)
		(end 53.444902 -388.409434)
		(width 0.14732)
		(layer "In13.Cu")
		(net "P5E_CPU1_PE0_RX_DP<15>")
	)
	(segment
		(start 57.7342 -436.979568)
		(end 57.648348 -436.825898)
		(width 0.14732)
		(layer "In13.Cu")
		(net "P5E_CPU1_PE0_RX_DP<15>")
	)
	(segment
		(start 51.232054 -396.80642)
		(end 51.410108 -396.70482)
		(width 0.14732)
		(layer "In13.Cu")
		(net "P5E_CPU1_PE0_RX_DP<15>")
	)
	(segment
		(start 52.96662 -390.030208)
		(end 52.966366 -390.029192)
		(width 0.14732)
		(layer "In13.Cu")
		(net "P5E_CPU1_PE0_RX_DP<15>")
	)
	(segment
		(start 53.442108 -387.834378)
		(end 53.59019 -387.739128)
		(width 0.14732)
		(layer "In13.Cu")
		(net "P5E_CPU1_PE0_RX_DP<15>")
	)
	(segment
		(start 53.111908 -389.358886)
		(end 53.20411 -388.931912)
		(width 0.14732)
		(layer "In13.Cu")
		(net "P5E_CPU1_PE0_RX_DP<15>")
	)
	(segment
		(start 58.705242 -323.80682)
		(end 58.705242 -323.28739)
		(width 0.14732)
		(layer "In13.Cu")
		(net "P5E_CPU1_PE0_RX_DP<15>")
	)
	(segment
		(start 102.104698 -211.090002)
		(end 102.104698 -213.15299)
		(width 0.14732)
		(layer "In13.Cu")
		(net "P5E_CPU1_PE0_RX_DP<15>")
	)
	(segment
		(start 58.650124 -436.889906)
		(end 58.650124 -437.152288)
		(width 0.14732)
		(layer "In13.Cu")
		(net "P5E_CPU1_PE0_RX_DP<15>")
	)
	(segment
		(start 64.265556 -317.2714)
		(end 65.847976 -315.68898)
		(width 0.14732)
		(layer "In13.Cu")
		(net "P5E_CPU1_PE0_RX_DP<15>")
	)
	(segment
		(start 60.056776 -322.309998)
		(end 60.419234 -322.067682)
		(width 0.14732)
		(layer "In13.Cu")
		(net "P5E_CPU1_PE0_RX_DP<15>")
	)
	(segment
		(start 102.146862 -215.414606)
		(end 102.146862 -215.436704)
		(width 0.0889)
		(layer "In13.Cu")
		(net "P5E_CPU1_PE0_RX_DP<15>")
	)
	(segment
		(start 53.82514 -386.066792)
		(end 53.917342 -385.639818)
		(width 0.14732)
		(layer "In13.Cu")
		(net "P5E_CPU1_PE0_RX_DP<15>")
	)
	(segment
		(start 53.444902 -388.409434)
		(end 53.349652 -388.261352)
		(width 0.14732)
		(layer "In13.Cu")
		(net "P5E_CPU1_PE0_RX_DP<15>")
	)
	(segment
		(start 54.065678 -385.544568)
		(end 54.158134 -385.11734)
		(width 0.14732)
		(layer "In13.Cu")
		(net "P5E_CPU1_PE0_RX_DP<15>")
	)
	(segment
		(start 102.617016 -216.25052)
		(end 102.617016 -216.260426)
		(width 0.0889)
		(layer "In13.Cu")
		(net "P5E_CPU1_PE0_RX_DP<15>")
	)
	(segment
		(start 53.349652 -388.261352)
		(end 53.442108 -387.834378)
		(width 0.14732)
		(layer "In13.Cu")
		(net "P5E_CPU1_PE0_RX_DP<15>")
	)
	(segment
		(start 51.738022 -394.947394)
		(end 52.540408 -391.997946)
		(width 0.14732)
		(layer "In13.Cu")
		(net "P5E_CPU1_PE0_RX_DP<15>")
	)
	(segment
		(start 70.434454 -218.412568)
		(end 72.366632 -214.688674)
		(width 0.14732)
		(layer "In13.Cu")
		(net "P5E_CPU1_PE0_RX_DP<15>")
	)
	(segment
		(start 99.522788 -206.406496)
		(end 99.522788 -206.578962)
		(width 0.14732)
		(layer "In13.Cu")
		(net "P5E_CPU1_PE0_RX_DP<15>")
	)
	(segment
		(start 58.091578 -325.288402)
		(end 58.705242 -323.80682)
		(width 0.14732)
		(layer "In13.Cu")
		(net "P5E_CPU1_PE0_RX_DP<15>")
	)
	(segment
		(start 51.565048 -395.582394)
		(end 51.743102 -395.480794)
		(width 0.14732)
		(layer "In13.Cu")
		(net "P5E_CPU1_PE0_RX_DP<15>")
	)
	(segment
		(start 50.080418 -400.63293)
		(end 51.028346 -397.554958)
		(width 0.14732)
		(layer "In13.Cu")
		(net "P5E_CPU1_PE0_RX_DP<15>")
	)
	(segment
		(start 58.650124 -437.152288)
		(end 58.502296 -437.300116)
		(width 0.14732)
		(layer "In13.Cu")
		(net "P5E_CPU1_PE0_RX_DP<15>")
	)
	(segment
		(start 53.827934 -386.641848)
		(end 53.92039 -386.21462)
		(width 0.14732)
		(layer "In13.Cu")
		(net "P5E_CPU1_PE0_RX_DP<15>")
	)
	(segment
		(start 53.682646 -387.3119)
		(end 53.587396 -387.164072)
		(width 0.14732)
		(layer "In13.Cu")
		(net "P5E_CPU1_PE0_RX_DP<15>")
	)
	(segment
		(start 99.831906 -206.88808)
		(end 100.004372 -206.88808)
		(width 0.14732)
		(layer "In13.Cu")
		(net "P5E_CPU1_PE0_RX_DP<15>")
	)
	(segment
		(start 54.776116 -381.677672)
		(end 57.127648 -370.814346)
		(width 0.14732)
		(layer "In13.Cu")
		(net "P5E_CPU1_PE0_RX_DP<15>")
	)
	(segment
		(start 72.366632 -214.688674)
		(end 76.233782 -209.705194)
		(width 0.14732)
		(layer "In13.Cu")
		(net "P5E_CPU1_PE0_RX_DP<15>")
	)
	(segment
		(start 58.091578 -330.007722)
		(end 58.091578 -325.288402)
		(width 0.14732)
		(layer "In13.Cu")
		(net "P5E_CPU1_PE0_RX_DP<15>")
	)
	(segment
		(start 103.33863 -220.862906)
		(end 103.182166 -221.133924)
		(width 0.0889)
		(layer "In13.Cu")
		(net "P5E_CPU1_PE0_RX_DP<15>")
	)
	(segment
		(start 102.9081 -219.0115)
		(end 102.89921 -219.01658)
		(width 0.0889)
		(layer "In13.Cu")
		(net "P5E_CPU1_PE0_RX_DP<15>")
	)
	(segment
		(start 54.158134 -385.11734)
		(end 54.062884 -384.969512)
		(width 0.14732)
		(layer "In13.Cu")
		(net "P5E_CPU1_PE0_RX_DP<15>")
	)
	(segment
		(start 48.363378 -410.259276)
		(end 48.363378 -406.313132)
		(width 0.14732)
		(layer "In13.Cu")
		(net "P5E_CPU1_PE0_RX_DP<15>")
	)
	(segment
		(start 54.538372 -382.774952)
		(end 54.630574 -382.347978)
		(width 0.14732)
		(layer "In13.Cu")
		(net "P5E_CPU1_PE0_RX_DP<15>")
	)
	(segment
		(start 51.743102 -395.480794)
		(end 51.839876 -395.125194)
		(width 0.14732)
		(layer "In13.Cu")
		(net "P5E_CPU1_PE0_RX_DP<15>")
	)
	(segment
		(start 54.630574 -382.347978)
		(end 54.77891 -382.252728)
		(width 0.14732)
		(layer "In13.Cu")
		(net "P5E_CPU1_PE0_RX_DP<15>")
	)
	(segment
		(start 102.89921 -218.367864)
		(end 102.9081 -218.372944)
		(width 0.0889)
		(layer "In13.Cu")
		(net "P5E_CPU1_PE0_RX_DP<15>")
	)
	(segment
		(start 53.917342 -385.639818)
		(end 54.065678 -385.544568)
		(width 0.14732)
		(layer "In13.Cu")
		(net "P5E_CPU1_PE0_RX_DP<15>")
	)
	(segment
		(start 102.146862 -213.8934)
		(end 102.147116 -213.893654)
		(width 0.0889)
		(layer "In13.Cu")
		(net "P5E_CPU1_PE0_RX_DP<15>")
	)
	(segment
		(start 51.506628 -396.348966)
		(end 51.405028 -396.17142)
		(width 0.14732)
		(layer "In13.Cu")
		(net "P5E_CPU1_PE0_RX_DP<15>")
	)
	(segment
		(start 102.617016 -217.859864)
		(end 102.617016 -217.8939)
		(width 0.0889)
		(layer "In13.Cu")
		(net "P5E_CPU1_PE0_RX_DP<15>")
	)
	(segment
		(start 102.104698 -213.175088)
		(end 102.146862 -213.217252)
		(width 0.0889)
		(layer "In13.Cu")
		(net "P5E_CPU1_PE0_RX_DP<15>")
	)
	(segment
		(start 54.541166 -383.350008)
		(end 54.633622 -382.92278)
		(width 0.14732)
		(layer "In13.Cu")
		(net "P5E_CPU1_PE0_RX_DP<15>")
	)
	(segment
		(start 54.062884 -384.969512)
		(end 54.155086 -384.542538)
		(width 0.14732)
		(layer "In13.Cu")
		(net "P5E_CPU1_PE0_RX_DP<15>")
	)
	(segment
		(start 50.080418 -404.596092)
		(end 50.080418 -400.63293)
		(width 0.14732)
		(layer "In13.Cu")
		(net "P5E_CPU1_PE0_RX_DP<15>")
	)
	(segment
		(start 102.423468 -215.922606)
		(end 102.429564 -215.926162)
		(width 0.0889)
		(layer "In13.Cu")
		(net "P5E_CPU1_PE0_RX_DP<15>")
	)
	(segment
		(start 66.878708 -315.40069)
		(end 67.733418 -314.18022)
		(width 0.14732)
		(layer "In13.Cu")
		(net "P5E_CPU1_PE0_RX_DP<15>")
	)
	(segment
		(start 51.183794 -413.913066)
		(end 48.701706 -411.140402)
		(width 0.14732)
		(layer "In13.Cu")
		(net "P5E_CPU1_PE0_RX_DP<15>")
	)
	(segment
		(start 52.966366 -390.029192)
		(end 53.114702 -389.933942)
		(width 0.14732)
		(layer "In13.Cu")
		(net "P5E_CPU1_PE0_RX_DP<15>")
	)
	(segment
		(start 102.104698 -213.15299)
		(end 102.104698 -213.175088)
		(width 0.0889)
		(layer "In13.Cu")
		(net "P5E_CPU1_PE0_RX_DP<15>")
	)
	(segment
		(start 53.92039 -386.21462)
		(end 53.82514 -386.066792)
		(width 0.14732)
		(layer "In13.Cu")
		(net "P5E_CPU1_PE0_RX_DP<15>")
	)
	(segment
		(start 103.086662 -217.0557)
		(end 103.086662 -217.072972)
		(width 0.0889)
		(layer "In13.Cu")
		(net "P5E_CPU1_PE0_RX_DP<15>")
	)
	(segment
		(start 53.587396 -387.164072)
		(end 53.679852 -386.737098)
		(width 0.14732)
		(layer "In13.Cu")
		(net "P5E_CPU1_PE0_RX_DP<15>")
	)
	(segment
		(start 54.871366 -381.8255)
		(end 54.776116 -381.677672)
		(width 0.14732)
		(layer "In13.Cu")
		(net "P5E_CPU1_PE0_RX_DP<15>")
	)
	(segment
		(start 51.405282 -396.170404)
		(end 51.565048 -395.582394)
		(width 0.14732)
		(layer "In13.Cu")
		(net "P5E_CPU1_PE0_RX_DP<15>")
	)
	(segment
		(start 54.300628 -383.872232)
		(end 54.39283 -383.445258)
		(width 0.14732)
		(layer "In13.Cu")
		(net "P5E_CPU1_PE0_RX_DP<15>")
	)
	(segment
		(start 57.734454 -436.979822)
		(end 57.7342 -436.979568)
		(width 0.14732)
		(layer "In13.Cu")
		(net "P5E_CPU1_PE0_RX_DP<15>")
	)
	(segment
		(start 102.437946 -214.941912)
		(end 102.429056 -214.946992)
		(width 0.0889)
		(layer "In13.Cu")
		(net "P5E_CPU1_PE0_RX_DP<15>")
	)
	(segment
		(start 61.387228 -319.566798)
		(end 63.682626 -317.2714)
		(width 0.14732)
		(layer "In13.Cu")
		(net "P5E_CPU1_PE0_RX_DP<15>")
	)
	(segment
		(start 68.933314 -309.90413)
		(end 68.934076 -309.901082)
		(width 0.14732)
		(layer "In13.Cu")
		(net "P5E_CPU1_PE0_RX_DP<15>")
	)
	(segment
		(start 54.39283 -383.445258)
		(end 54.541166 -383.350008)
		(width 0.14732)
		(layer "In13.Cu")
		(net "P5E_CPU1_PE0_RX_DP<15>")
	)
	(segment
		(start 57.648348 -436.825898)
		(end 51.183794 -413.913066)
		(width 0.14732)
		(layer "In13.Cu")
		(net "P5E_CPU1_PE0_RX_DP<15>")
	)
	(segment
		(start 58.116724 -437.300116)
		(end 57.747154 -436.983378)
		(width 0.14732)
		(layer "In13.Cu")
		(net "P5E_CPU1_PE0_RX_DP<15>")
	)
	(segment
		(start 102.616508 -214.461344)
		(end 102.616508 -214.622634)
		(width 0.0889)
		(layer "In13.Cu")
		(net "P5E_CPU1_PE0_RX_DP<15>")
	)
	(segment
		(start 59.14009 -342.085422)
		(end 58.091578 -330.007722)
		(width 0.14732)
		(layer "In13.Cu")
		(net "P5E_CPU1_PE0_RX_DP<15>")
	)
	(segment
		(start 54.395878 -384.02006)
		(end 54.300628 -383.872232)
		(width 0.14732)
		(layer "In13.Cu")
		(net "P5E_CPU1_PE0_RX_DP<15>")
	)
	(segment
		(start 53.59019 -387.739128)
		(end 53.682646 -387.3119)
		(width 0.14732)
		(layer "In13.Cu")
		(net "P5E_CPU1_PE0_RX_DP<15>")
	)
	(segment
		(start 53.207158 -389.506714)
		(end 53.111908 -389.358886)
		(width 0.14732)
		(layer "In13.Cu")
		(net "P5E_CPU1_PE0_RX_DP<15>")
	)
	(segment
		(start 54.77891 -382.252728)
		(end 54.871366 -381.8255)
		(width 0.14732)
		(layer "In13.Cu")
		(net "P5E_CPU1_PE0_RX_DP<15>")
	)
	(segment
		(start 103.086662 -220.311218)
		(end 103.086662 -220.334078)
		(width 0.0889)
		(layer "In13.Cu")
		(net "P5E_CPU1_PE0_RX_DP<15>")
	)
	(segment
		(start 53.20411 -388.931912)
		(end 53.352446 -388.836662)
		(width 0.14732)
		(layer "In13.Cu")
		(net "P5E_CPU1_PE0_RX_DP<15>")
	)
	(segment
		(start 94.085156 -200.968864)
		(end 99.522788 -206.406496)
		(width 0.14732)
		(layer "In13.Cu")
		(net "P5E_CPU1_PE0_RX_DP<15>")
	)
	(segment
		(start 58.502296 -437.300116)
		(end 58.116724 -437.300116)
		(width 0.14732)
		(layer "In13.Cu")
		(net "P5E_CPU1_PE0_RX_DP<15>")
	)
	(arc
		(start 102.617016 -217.8939)
		(mid 102.696386 -218.167634)
		(end 102.89921 -218.367864)
		(width 0.0889)
		(layer "In13.Cu")
		(net "P5E_CPU1_PE0_RX_DP<15>")
	)
	(arc
		(start 102.147116 -213.930484)
		(mid 102.154401 -213.950046)
		(end 102.162356 -213.969346)
		(width 0.0889)
		(layer "In13.Cu")
		(net "P5E_CPU1_PE0_RX_DP<15>")
	)
	(arc
		(start 102.429056 -214.946992)
		(mid 102.227774 -215.144479)
		(end 102.146862 -215.414606)
		(width 0.0889)
		(layer "In13.Cu")
		(net "P5E_CPU1_PE0_RX_DP<15>")
	)
	(arc
		(start 103.297482 -220.760798)
		(mid 103.30593 -220.767355)
		(end 103.3145 -220.773752)
		(width 0.0889)
		(layer "In13.Cu")
		(net "P5E_CPU1_PE0_RX_DP<15>")
	)
	(arc
		(start 102.899464 -219.995496)
		(mid 103.034397 -220.12885)
		(end 103.086662 -220.311218)
		(width 0.0889)
		(layer "In13.Cu")
		(net "P5E_CPU1_PE0_RX_DP<15>")
	)
	(arc
		(start 102.899464 -217.388694)
		(mid 102.697178 -217.587675)
		(end 102.617016 -217.859864)
		(width 0.0889)
		(layer "In13.Cu")
		(net "P5E_CPU1_PE0_RX_DP<15>")
	)
	(arc
		(start 103.086662 -220.334078)
		(mid 103.144956 -220.570721)
		(end 103.297482 -220.760798)
		(width 0.0889)
		(layer "In13.Cu")
		(net "P5E_CPU1_PE0_RX_DP<15>")
	)
	(arc
		(start 102.432358 -214.261954)
		(mid 102.541505 -214.345882)
		(end 102.616508 -214.461344)
		(width 0.0889)
		(layer "In13.Cu")
		(net "P5E_CPU1_PE0_RX_DP<15>")
	)
	(arc
		(start 102.9081 -218.372944)
		(mid 103.086576 -218.692222)
		(end 102.9081 -219.0115)
		(width 0.0889)
		(layer "In13.Cu")
		(net "P5E_CPU1_PE0_RX_DP<15>")
	)
	(arc
		(start 102.146862 -215.436704)
		(mid 102.220853 -215.71627)
		(end 102.423468 -215.922606)
		(width 0.0889)
		(layer "In13.Cu")
		(net "P5E_CPU1_PE0_RX_DP<15>")
	)
	(arc
		(start 102.617016 -216.260426)
		(mid 102.695127 -216.537375)
		(end 102.899464 -216.739978)
		(width 0.0889)
		(layer "In13.Cu")
		(net "P5E_CPU1_PE0_RX_DP<15>")
	)
	(arc
		(start 102.438454 -215.931242)
		(mid 102.569368 -216.067602)
		(end 102.617016 -216.25052)
		(width 0.0889)
		(layer "In13.Cu")
		(net "P5E_CPU1_PE0_RX_DP<15>")
	)
	(arc
		(start 102.899464 -216.739978)
		(mid 103.034397 -216.873332)
		(end 103.086662 -217.0557)
		(width 0.0889)
		(layer "In13.Cu")
		(net "P5E_CPU1_PE0_RX_DP<15>")
	)
	(arc
		(start 102.89921 -219.01658)
		(mid 102.696387 -219.216811)
		(end 102.617016 -219.490544)
		(width 0.0889)
		(layer "In13.Cu")
		(net "P5E_CPU1_PE0_RX_DP<15>")
	)
	(arc
		(start 102.616508 -214.622634)
		(mid 102.568829 -214.805534)
		(end 102.437946 -214.941912)
		(width 0.0889)
		(layer "In13.Cu")
		(net "P5E_CPU1_PE0_RX_DP<15>")
	)
	(arc
		(start 102.617016 -219.515944)
		(mid 102.695127 -219.792893)
		(end 102.899464 -219.995496)
		(width 0.0889)
		(layer "In13.Cu")
		(net "P5E_CPU1_PE0_RX_DP<15>")
	)
	(arc
		(start 102.162356 -213.969346)
		(mid 102.27235 -214.138715)
		(end 102.432358 -214.261954)
		(width 0.0889)
		(layer "In13.Cu")
		(net "P5E_CPU1_PE0_RX_DP<15>")
	)
	(arc
		(start 103.086662 -217.072972)
		(mid 103.034392 -217.255337)
		(end 102.899464 -217.388694)
		(width 0.0889)
		(layer "In13.Cu")
		(net "P5E_CPU1_PE0_RX_DP<15>")
	)
	(segment
		(start 102.712012 -222.483426)
		(end 102.712012 -221.94774)
		(width 0.13208)
		(layer "F.Cu")
		(net "P5E_CPU1_PE0_RX_DP<14>")
	)
	(segment
		(start 102.712266 -222.48368)
		(end 102.712012 -222.483426)
		(width 0.13208)
		(layer "F.Cu")
		(net "P5E_CPU1_PE0_RX_DP<14>")
	)
	(segment
		(start 55.431182 -388.450836)
		(end 55.50154 -388.019544)
		(width 0.14732)
		(layer "In13.Cu")
		(net "P5E_CPU1_PE0_RX_DP<14>")
	)
	(segment
		(start 101.489764 -215.926162)
		(end 101.498654 -215.931242)
		(width 0.0889)
		(layer "In13.Cu")
		(net "P5E_CPU1_PE0_RX_DP<14>")
	)
	(segment
		(start 87.298784 -200.490836)
		(end 90.437716 -200.490836)
		(width 0.14732)
		(layer "In13.Cu")
		(net "P5E_CPU1_PE0_RX_DP<14>")
	)
	(segment
		(start 53.910738 -396.99057)
		(end 54.052724 -396.120366)
		(width 0.14732)
		(layer "In13.Cu")
		(net "P5E_CPU1_PE0_RX_DP<14>")
	)
	(segment
		(start 59.029346 -325.538338)
		(end 59.766454 -323.759068)
		(width 0.14732)
		(layer "In13.Cu")
		(net "P5E_CPU1_PE0_RX_DP<14>")
	)
	(segment
		(start 54.27853 -395.637004)
		(end 54.158896 -395.470888)
		(width 0.14732)
		(layer "In13.Cu")
		(net "P5E_CPU1_PE0_RX_DP<14>")
	)
	(segment
		(start 59.38901 -363.427518)
		(end 60.313062 -343.342214)
		(width 0.14732)
		(layer "In13.Cu")
		(net "P5E_CPU1_PE0_RX_DP<14>")
	)
	(segment
		(start 55.39867 -387.876542)
		(end 59.38901 -363.427518)
		(width 0.14732)
		(layer "In13.Cu")
		(net "P5E_CPU1_PE0_RX_DP<14>")
	)
	(segment
		(start 101.677216 -216.25052)
		(end 101.677216 -216.266014)
		(width 0.0889)
		(layer "In13.Cu")
		(net "P5E_CPU1_PE0_RX_DP<14>")
	)
	(segment
		(start 71.269352 -308.13248)
		(end 67.812158 -254.373126)
		(width 0.14732)
		(layer "In13.Cu")
		(net "P5E_CPU1_PE0_RX_DP<14>")
	)
	(segment
		(start 101.207062 -215.414606)
		(end 101.207062 -215.436704)
		(width 0.0889)
		(layer "In13.Cu")
		(net "P5E_CPU1_PE0_RX_DP<14>")
	)
	(segment
		(start 59.766454 -323.759068)
		(end 60.021724 -323.504052)
		(width 0.14732)
		(layer "In13.Cu")
		(net "P5E_CPU1_PE0_RX_DP<14>")
	)
	(segment
		(start 55.036974 -390.092946)
		(end 55.107332 -389.661908)
		(width 0.14732)
		(layer "In13.Cu")
		(net "P5E_CPU1_PE0_RX_DP<14>")
	)
	(segment
		(start 58.062876 -415.440876)
		(end 54.54142 -412.550864)
		(width 0.14732)
		(layer "In13.Cu")
		(net "P5E_CPU1_PE0_RX_DP<14>")
	)
	(segment
		(start 73.176638 -215.207088)
		(end 76.965556 -210.324446)
		(width 0.14732)
		(layer "In13.Cu")
		(net "P5E_CPU1_PE0_RX_DP<14>")
	)
	(segment
		(start 59.955176 -417.333176)
		(end 58.062876 -415.440876)
		(width 0.14732)
		(layer "In13.Cu")
		(net "P5E_CPU1_PE0_RX_DP<14>")
	)
	(segment
		(start 61.313822 -322.74383)
		(end 63.328042 -320.72961)
		(width 0.14732)
		(layer "In13.Cu")
		(net "P5E_CPU1_PE0_RX_DP<14>")
	)
	(segment
		(start 53.805074 -397.639794)
		(end 53.97119 -397.520414)
		(width 0.14732)
		(layer "In13.Cu")
		(net "P5E_CPU1_PE0_RX_DP<14>")
	)
	(segment
		(start 101.677216 -219.490544)
		(end 101.677216 -219.521532)
		(width 0.0889)
		(layer "In13.Cu")
		(net "P5E_CPU1_PE0_RX_DP<14>")
	)
	(segment
		(start 101.483668 -215.922606)
		(end 101.489764 -215.926162)
		(width 0.0889)
		(layer "In13.Cu")
		(net "P5E_CPU1_PE0_RX_DP<14>")
	)
	(segment
		(start 101.677216 -221.111826)
		(end 101.677216 -221.149418)
		(width 0.0889)
		(layer "In13.Cu")
		(net "P5E_CPU1_PE0_RX_DP<14>")
	)
	(segment
		(start 54.856126 -391.201148)
		(end 54.926484 -390.77011)
		(width 0.14732)
		(layer "In13.Cu")
		(net "P5E_CPU1_PE0_RX_DP<14>")
	)
	(segment
		(start 101.95941 -216.739978)
		(end 101.960426 -216.740486)
		(width 0.0889)
		(layer "In13.Cu")
		(net "P5E_CPU1_PE0_RX_DP<14>")
	)
	(segment
		(start 60.90666 -322.912486)
		(end 61.313822 -322.74383)
		(width 0.14732)
		(layer "In13.Cu")
		(net "P5E_CPU1_PE0_RX_DP<14>")
	)
	(segment
		(start 60.079636 -438.319418)
		(end 59.955176 -438.194958)
		(width 0.14732)
		(layer "In13.Cu")
		(net "P5E_CPU1_PE0_RX_DP<14>")
	)
	(segment
		(start 93.046804 -201.571606)
		(end 100.022406 -208.547208)
		(width 0.14732)
		(layer "In13.Cu")
		(net "P5E_CPU1_PE0_RX_DP<14>")
	)
	(segment
		(start 68.016882 -316.355476)
		(end 71.269352 -308.13248)
		(width 0.14732)
		(layer "In13.Cu")
		(net "P5E_CPU1_PE0_RX_DP<14>")
	)
	(segment
		(start 101.9683 -217.383614)
		(end 101.95941 -217.388694)
		(width 0.0889)
		(layer "In13.Cu")
		(net "P5E_CPU1_PE0_RX_DP<14>")
	)
	(segment
		(start 55.217822 -388.984744)
		(end 55.28818 -388.553706)
		(width 0.14732)
		(layer "In13.Cu")
		(net "P5E_CPU1_PE0_RX_DP<14>")
	)
	(segment
		(start 60.65012 -438.152286)
		(end 60.482988 -438.319418)
		(width 0.14732)
		(layer "In13.Cu")
		(net "P5E_CPU1_PE0_RX_DP<14>")
	)
	(segment
		(start 54.737 -392.829288)
		(end 54.617366 -392.662918)
		(width 0.14732)
		(layer "In13.Cu")
		(net "P5E_CPU1_PE0_RX_DP<14>")
	)
	(segment
		(start 101.960426 -219.996004)
		(end 101.9683 -220.000576)
		(width 0.0889)
		(layer "In13.Cu")
		(net "P5E_CPU1_PE0_RX_DP<14>")
	)
	(segment
		(start 55.250334 -389.559038)
		(end 55.320692 -389.127746)
		(width 0.14732)
		(layer "In13.Cu")
		(net "P5E_CPU1_PE0_RX_DP<14>")
	)
	(segment
		(start 54.54142 -412.550864)
		(end 53.069236 -411.567122)
		(width 0.14732)
		(layer "In13.Cu")
		(net "P5E_CPU1_PE0_RX_DP<14>")
	)
	(segment
		(start 54.888384 -391.775442)
		(end 54.958742 -391.343896)
		(width 0.14732)
		(layer "In13.Cu")
		(net "P5E_CPU1_PE0_RX_DP<14>")
	)
	(segment
		(start 101.207316 -213.217252)
		(end 101.207316 -213.930484)
		(width 0.0889)
		(layer "In13.Cu")
		(net "P5E_CPU1_PE0_RX_DP<14>")
	)
	(segment
		(start 64.303656 -320.72961)
		(end 65.519808 -319.513712)
		(width 0.14732)
		(layer "In13.Cu")
		(net "P5E_CPU1_PE0_RX_DP<14>")
	)
	(segment
		(start 54.030372 -397.156686)
		(end 53.910738 -396.99057)
		(width 0.14732)
		(layer "In13.Cu")
		(net "P5E_CPU1_PE0_RX_DP<14>")
	)
	(segment
		(start 54.926484 -390.77011)
		(end 55.069486 -390.66724)
		(width 0.14732)
		(layer "In13.Cu")
		(net "P5E_CPU1_PE0_RX_DP<14>")
	)
	(segment
		(start 54.219094 -396.000732)
		(end 54.27853 -395.637004)
		(width 0.14732)
		(layer "In13.Cu")
		(net "P5E_CPU1_PE0_RX_DP<14>")
	)
	(segment
		(start 101.9683 -220.639132)
		(end 101.95941 -220.644212)
		(width 0.0889)
		(layer "In13.Cu")
		(net "P5E_CPU1_PE0_RX_DP<14>")
	)
	(segment
		(start 101.95941 -218.367864)
		(end 101.9683 -218.372944)
		(width 0.0889)
		(layer "In13.Cu")
		(net "P5E_CPU1_PE0_RX_DP<14>")
	)
	(segment
		(start 84.88045 -201.739754)
		(end 87.298784 -200.490836)
		(width 0.14732)
		(layer "In13.Cu")
		(net "P5E_CPU1_PE0_RX_DP<14>")
	)
	(segment
		(start 102.555548 -221.676722)
		(end 102.712012 -221.94774)
		(width 0.0889)
		(layer "In13.Cu")
		(net "P5E_CPU1_PE0_RX_DP<14>")
	)
	(segment
		(start 101.165152 -213.175088)
		(end 101.207316 -213.217252)
		(width 0.0889)
		(layer "In13.Cu")
		(net "P5E_CPU1_PE0_RX_DP<14>")
	)
	(segment
		(start 54.677564 -393.193016)
		(end 54.737 -392.829288)
		(width 0.14732)
		(layer "In13.Cu")
		(net "P5E_CPU1_PE0_RX_DP<14>")
	)
	(segment
		(start 101.676708 -214.461344)
		(end 101.676708 -214.622634)
		(width 0.0889)
		(layer "In13.Cu")
		(net "P5E_CPU1_PE0_RX_DP<14>")
	)
	(segment
		(start 102.466648 -221.6531)
		(end 102.555548 -221.676722)
		(width 0.0889)
		(layer "In13.Cu")
		(net "P5E_CPU1_PE0_RX_DP<14>")
	)
	(segment
		(start 67.812158 -254.373126)
		(end 67.950842 -249.96902)
		(width 0.14732)
		(layer "In13.Cu")
		(net "P5E_CPU1_PE0_RX_DP<14>")
	)
	(segment
		(start 51.426618 -410.620464)
		(end 51.426618 -406.313132)
		(width 0.14732)
		(layer "In13.Cu")
		(net "P5E_CPU1_PE0_RX_DP<14>")
	)
	(segment
		(start 67.950842 -249.96902)
		(end 69.256148 -232.306876)
		(width 0.14732)
		(layer "In13.Cu")
		(net "P5E_CPU1_PE0_RX_DP<14>")
	)
	(segment
		(start 101.498146 -214.941912)
		(end 101.489256 -214.946992)
		(width 0.0889)
		(layer "In13.Cu")
		(net "P5E_CPU1_PE0_RX_DP<14>")
	)
	(segment
		(start 100.022406 -208.547208)
		(end 101.165152 -211.305902)
		(width 0.14732)
		(layer "In13.Cu")
		(net "P5E_CPU1_PE0_RX_DP<14>")
	)
	(segment
		(start 60.021724 -323.504052)
		(end 60.90666 -322.912486)
		(width 0.14732)
		(layer "In13.Cu")
		(net "P5E_CPU1_PE0_RX_DP<14>")
	)
	(segment
		(start 60.65012 -437.889904)
		(end 60.65012 -438.152286)
		(width 0.14732)
		(layer "In13.Cu")
		(net "P5E_CPU1_PE0_RX_DP<14>")
	)
	(segment
		(start 55.28818 -388.553706)
		(end 55.431182 -388.450836)
		(width 0.14732)
		(layer "In13.Cu")
		(net "P5E_CPU1_PE0_RX_DP<14>")
	)
	(segment
		(start 55.139844 -390.235948)
		(end 55.036974 -390.092946)
		(width 0.14732)
		(layer "In13.Cu")
		(net "P5E_CPU1_PE0_RX_DP<14>")
	)
	(segment
		(start 54.353206 -394.281152)
		(end 54.511194 -393.31265)
		(width 0.14732)
		(layer "In13.Cu")
		(net "P5E_CPU1_PE0_RX_DP<14>")
	)
	(segment
		(start 101.960426 -216.740486)
		(end 101.9683 -216.745058)
		(width 0.0889)
		(layer "In13.Cu")
		(net "P5E_CPU1_PE0_RX_DP<14>")
	)
	(segment
		(start 101.677216 -217.856308)
		(end 101.677216 -217.8939)
		(width 0.0889)
		(layer "In13.Cu")
		(net "P5E_CPU1_PE0_RX_DP<14>")
	)
	(segment
		(start 59.955176 -438.194958)
		(end 59.955176 -417.333176)
		(width 0.14732)
		(layer "In13.Cu")
		(net "P5E_CPU1_PE0_RX_DP<14>")
	)
	(segment
		(start 60.313062 -343.342214)
		(end 59.029346 -329.618086)
		(width 0.14732)
		(layer "In13.Cu")
		(net "P5E_CPU1_PE0_RX_DP<14>")
	)
	(segment
		(start 54.247034 -394.93063)
		(end 54.413404 -394.810996)
		(width 0.14732)
		(layer "In13.Cu")
		(net "P5E_CPU1_PE0_RX_DP<14>")
	)
	(segment
		(start 55.50154 -388.019544)
		(end 55.39867 -387.876542)
		(width 0.14732)
		(layer "In13.Cu")
		(net "P5E_CPU1_PE0_RX_DP<14>")
	)
	(segment
		(start 101.165152 -213.15299)
		(end 101.165152 -213.175088)
		(width 0.0889)
		(layer "In13.Cu")
		(net "P5E_CPU1_PE0_RX_DP<14>")
	)
	(segment
		(start 101.9683 -219.0115)
		(end 101.95941 -219.01658)
		(width 0.0889)
		(layer "In13.Cu")
		(net "P5E_CPU1_PE0_RX_DP<14>")
	)
	(segment
		(start 69.256148 -232.306876)
		(end 71.356982 -218.714066)
		(width 0.14732)
		(layer "In13.Cu")
		(net "P5E_CPU1_PE0_RX_DP<14>")
	)
	(segment
		(start 53.069236 -411.567122)
		(end 51.64836 -410.978604)
		(width 0.14732)
		(layer "In13.Cu")
		(net "P5E_CPU1_PE0_RX_DP<14>")
	)
	(segment
		(start 54.511194 -393.31265)
		(end 54.677564 -393.193016)
		(width 0.14732)
		(layer "In13.Cu")
		(net "P5E_CPU1_PE0_RX_DP<14>")
	)
	(segment
		(start 66.07937 -319.121536)
		(end 68.016882 -316.355476)
		(width 0.14732)
		(layer "In13.Cu")
		(net "P5E_CPU1_PE0_RX_DP<14>")
	)
	(segment
		(start 101.95941 -219.995496)
		(end 101.960426 -219.996004)
		(width 0.0889)
		(layer "In13.Cu")
		(net "P5E_CPU1_PE0_RX_DP<14>")
	)
	(segment
		(start 101.165152 -211.305902)
		(end 101.165152 -213.15299)
		(width 0.14732)
		(layer "In13.Cu")
		(net "P5E_CPU1_PE0_RX_DP<14>")
	)
	(segment
		(start 65.519808 -319.513712)
		(end 66.07937 -319.121536)
		(width 0.14732)
		(layer "In13.Cu")
		(net "P5E_CPU1_PE0_RX_DP<14>")
	)
	(segment
		(start 53.725572 -398.126458)
		(end 53.805074 -397.639794)
		(width 0.14732)
		(layer "In13.Cu")
		(net "P5E_CPU1_PE0_RX_DP<14>")
	)
	(segment
		(start 53.143658 -404.596092)
		(end 53.143658 -400.611848)
		(width 0.14732)
		(layer "In13.Cu")
		(net "P5E_CPU1_PE0_RX_DP<14>")
	)
	(segment
		(start 54.47284 -394.447268)
		(end 54.353206 -394.281152)
		(width 0.14732)
		(layer "In13.Cu")
		(net "P5E_CPU1_PE0_RX_DP<14>")
	)
	(segment
		(start 51.426618 -406.313132)
		(end 53.143658 -404.596092)
		(width 0.14732)
		(layer "In13.Cu")
		(net "P5E_CPU1_PE0_RX_DP<14>")
	)
	(segment
		(start 90.437716 -200.490836)
		(end 93.046804 -201.571606)
		(width 0.14732)
		(layer "In13.Cu")
		(net "P5E_CPU1_PE0_RX_DP<14>")
	)
	(segment
		(start 54.745382 -391.878058)
		(end 54.888384 -391.775442)
		(width 0.14732)
		(layer "In13.Cu")
		(net "P5E_CPU1_PE0_RX_DP<14>")
	)
	(segment
		(start 76.965556 -210.324446)
		(end 84.88045 -201.739754)
		(width 0.14732)
		(layer "In13.Cu")
		(net "P5E_CPU1_PE0_RX_DP<14>")
	)
	(segment
		(start 53.97119 -397.520414)
		(end 54.030372 -397.156686)
		(width 0.14732)
		(layer "In13.Cu")
		(net "P5E_CPU1_PE0_RX_DP<14>")
	)
	(segment
		(start 59.029346 -329.618086)
		(end 59.029346 -325.538338)
		(width 0.14732)
		(layer "In13.Cu")
		(net "P5E_CPU1_PE0_RX_DP<14>")
	)
	(segment
		(start 51.64836 -410.978604)
		(end 51.426618 -410.620464)
		(width 0.14732)
		(layer "In13.Cu")
		(net "P5E_CPU1_PE0_RX_DP<14>")
	)
	(segment
		(start 63.328042 -320.72961)
		(end 64.303656 -320.72961)
		(width 0.14732)
		(layer "In13.Cu")
		(net "P5E_CPU1_PE0_RX_DP<14>")
	)
	(segment
		(start 55.320692 -389.127746)
		(end 55.217822 -388.984744)
		(width 0.14732)
		(layer "In13.Cu")
		(net "P5E_CPU1_PE0_RX_DP<14>")
	)
	(segment
		(start 60.482988 -438.319418)
		(end 60.079636 -438.319418)
		(width 0.14732)
		(layer "In13.Cu")
		(net "P5E_CPU1_PE0_RX_DP<14>")
	)
	(segment
		(start 55.069486 -390.66724)
		(end 55.139844 -390.235948)
		(width 0.14732)
		(layer "In13.Cu")
		(net "P5E_CPU1_PE0_RX_DP<14>")
	)
	(segment
		(start 54.413404 -394.810996)
		(end 54.47284 -394.447268)
		(width 0.14732)
		(layer "In13.Cu")
		(net "P5E_CPU1_PE0_RX_DP<14>")
	)
	(segment
		(start 54.958742 -391.343896)
		(end 54.856126 -391.201148)
		(width 0.14732)
		(layer "In13.Cu")
		(net "P5E_CPU1_PE0_RX_DP<14>")
	)
	(segment
		(start 54.617366 -392.662918)
		(end 54.745382 -391.878058)
		(width 0.14732)
		(layer "In13.Cu")
		(net "P5E_CPU1_PE0_RX_DP<14>")
	)
	(segment
		(start 71.356982 -218.714066)
		(end 73.176638 -215.207088)
		(width 0.14732)
		(layer "In13.Cu")
		(net "P5E_CPU1_PE0_RX_DP<14>")
	)
	(segment
		(start 53.143658 -400.611848)
		(end 53.725572 -398.126458)
		(width 0.14732)
		(layer "In13.Cu")
		(net "P5E_CPU1_PE0_RX_DP<14>")
	)
	(segment
		(start 55.107332 -389.661908)
		(end 55.250334 -389.559038)
		(width 0.14732)
		(layer "In13.Cu")
		(net "P5E_CPU1_PE0_RX_DP<14>")
	)
	(segment
		(start 54.052724 -396.120366)
		(end 54.219094 -396.000732)
		(width 0.14732)
		(layer "In13.Cu")
		(net "P5E_CPU1_PE0_RX_DP<14>")
	)
	(segment
		(start 54.158896 -395.470888)
		(end 54.247034 -394.93063)
		(width 0.14732)
		(layer "In13.Cu")
		(net "P5E_CPU1_PE0_RX_DP<14>")
	)
	(arc
		(start 101.676708 -214.622634)
		(mid 101.629029 -214.805534)
		(end 101.498146 -214.941912)
		(width 0.0889)
		(layer "In13.Cu")
		(net "P5E_CPU1_PE0_RX_DP<14>")
	)
	(arc
		(start 101.95941 -220.644212)
		(mid 101.758128 -220.841699)
		(end 101.677216 -221.111826)
		(width 0.0889)
		(layer "In13.Cu")
		(net "P5E_CPU1_PE0_RX_DP<14>")
	)
	(arc
		(start 101.492558 -214.261954)
		(mid 101.601705 -214.345882)
		(end 101.676708 -214.461344)
		(width 0.0889)
		(layer "In13.Cu")
		(net "P5E_CPU1_PE0_RX_DP<14>")
	)
	(arc
		(start 101.677216 -217.8939)
		(mid 101.756586 -218.167634)
		(end 101.95941 -218.367864)
		(width 0.0889)
		(layer "In13.Cu")
		(net "P5E_CPU1_PE0_RX_DP<14>")
	)
	(arc
		(start 101.489256 -214.946992)
		(mid 101.287974 -215.144479)
		(end 101.207062 -215.414606)
		(width 0.0889)
		(layer "In13.Cu")
		(net "P5E_CPU1_PE0_RX_DP<14>")
	)
	(arc
		(start 101.9683 -218.372944)
		(mid 102.146776 -218.692222)
		(end 101.9683 -219.0115)
		(width 0.0889)
		(layer "In13.Cu")
		(net "P5E_CPU1_PE0_RX_DP<14>")
	)
	(arc
		(start 101.677216 -219.521532)
		(mid 101.756586 -219.795266)
		(end 101.95941 -219.995496)
		(width 0.0889)
		(layer "In13.Cu")
		(net "P5E_CPU1_PE0_RX_DP<14>")
	)
	(arc
		(start 101.9683 -220.000576)
		(mid 102.146897 -220.319854)
		(end 101.9683 -220.639132)
		(width 0.0889)
		(layer "In13.Cu")
		(net "P5E_CPU1_PE0_RX_DP<14>")
	)
	(arc
		(start 102.446836 -221.661228)
		(mid 102.45678 -221.657257)
		(end 102.466648 -221.6531)
		(width 0.0889)
		(layer "In13.Cu")
		(net "P5E_CPU1_PE0_RX_DP<14>")
	)
	(arc
		(start 101.95941 -221.623382)
		(mid 102.198823 -221.697714)
		(end 102.446836 -221.661228)
		(width 0.0889)
		(layer "In13.Cu")
		(net "P5E_CPU1_PE0_RX_DP<14>")
	)
	(arc
		(start 101.677216 -221.149418)
		(mid 101.756586 -221.423152)
		(end 101.95941 -221.623382)
		(width 0.0889)
		(layer "In13.Cu")
		(net "P5E_CPU1_PE0_RX_DP<14>")
	)
	(arc
		(start 101.95941 -219.01658)
		(mid 101.756587 -219.216811)
		(end 101.677216 -219.490544)
		(width 0.0889)
		(layer "In13.Cu")
		(net "P5E_CPU1_PE0_RX_DP<14>")
	)
	(arc
		(start 101.9683 -216.745058)
		(mid 102.146897 -217.064336)
		(end 101.9683 -217.383614)
		(width 0.0889)
		(layer "In13.Cu")
		(net "P5E_CPU1_PE0_RX_DP<14>")
	)
	(arc
		(start 101.207062 -215.436704)
		(mid 101.281053 -215.71627)
		(end 101.483668 -215.922606)
		(width 0.0889)
		(layer "In13.Cu")
		(net "P5E_CPU1_PE0_RX_DP<14>")
	)
	(arc
		(start 101.95941 -217.388694)
		(mid 101.758128 -217.586181)
		(end 101.677216 -217.856308)
		(width 0.0889)
		(layer "In13.Cu")
		(net "P5E_CPU1_PE0_RX_DP<14>")
	)
	(arc
		(start 101.207316 -213.930484)
		(mid 101.214601 -213.950046)
		(end 101.222556 -213.969346)
		(width 0.0889)
		(layer "In13.Cu")
		(net "P5E_CPU1_PE0_RX_DP<14>")
	)
	(arc
		(start 101.677216 -216.266014)
		(mid 101.756586 -216.539748)
		(end 101.95941 -216.739978)
		(width 0.0889)
		(layer "In13.Cu")
		(net "P5E_CPU1_PE0_RX_DP<14>")
	)
	(arc
		(start 101.222556 -213.969346)
		(mid 101.33255 -214.138715)
		(end 101.492558 -214.261954)
		(width 0.0889)
		(layer "In13.Cu")
		(net "P5E_CPU1_PE0_RX_DP<14>")
	)
	(arc
		(start 101.498654 -215.931242)
		(mid 101.629568 -216.067602)
		(end 101.677216 -216.25052)
		(width 0.0889)
		(layer "In13.Cu")
		(net "P5E_CPU1_PE0_RX_DP<14>")
	)
	(segment
		(start 101.302312 -221.669864)
		(end 101.302312 -221.134178)
		(width 0.13208)
		(layer "F.Cu")
		(net "P5E_CPU1_PE0_RX_DP<13>")
	)
	(segment
		(start 101.302312 -221.134178)
		(end 101.302566 -221.133924)
		(width 0.13208)
		(layer "F.Cu")
		(net "P5E_CPU1_PE0_RX_DP<13>")
	)
	(segment
		(start 100.267262 -213.8934)
		(end 100.267516 -213.893654)
		(width 0.0889)
		(layer "In13.Cu")
		(net "P5E_CPU1_PE0_RX_DP<13>")
	)
	(segment
		(start 100.225098 -213.17585)
		(end 100.225098 -213.197948)
		(width 0.0889)
		(layer "In13.Cu")
		(net "P5E_CPU1_PE0_RX_DP<13>")
	)
	(segment
		(start 68.772024 -254.30226)
		(end 68.772024 -253.471426)
		(width 0.14732)
		(layer "In13.Cu")
		(net "P5E_CPU1_PE0_RX_DP<13>")
	)
	(segment
		(start 58.550556 -381.483108)
		(end 58.596276 -381.04826)
		(width 0.14732)
		(layer "In13.Cu")
		(net "P5E_CPU1_PE0_RX_DP<13>")
	)
	(segment
		(start 73.971658 -215.71585)
		(end 77.683868 -210.932268)
		(width 0.14732)
		(layer "In13.Cu")
		(net "P5E_CPU1_PE0_RX_DP<13>")
	)
	(segment
		(start 57.825386 -387.176772)
		(end 57.962546 -387.066028)
		(width 0.14732)
		(layer "In13.Cu")
		(net "P5E_CPU1_PE0_RX_DP<13>")
	)
	(segment
		(start 57.590944 -389.40994)
		(end 57.728104 -389.299196)
		(width 0.14732)
		(layer "In13.Cu")
		(net "P5E_CPU1_PE0_RX_DP<13>")
	)
	(segment
		(start 89.3953 -201.430636)
		(end 90.276934 -201.430636)
		(width 0.14732)
		(layer "In13.Cu")
		(net "P5E_CPU1_PE0_RX_DP<13>")
	)
	(segment
		(start 101.01961 -218.367864)
		(end 101.0285 -218.372944)
		(width 0.0889)
		(layer "In13.Cu")
		(net "P5E_CPU1_PE0_RX_DP<13>")
	)
	(segment
		(start 54.489858 -406.313132)
		(end 56.206898 -404.596092)
		(width 0.14732)
		(layer "In13.Cu")
		(net "P5E_CPU1_PE0_RX_DP<13>")
	)
	(segment
		(start 92.49537 -202.349608)
		(end 99.160076 -209.014314)
		(width 0.14732)
		(layer "In13.Cu")
		(net "P5E_CPU1_PE0_RX_DP<13>")
	)
	(segment
		(start 85.459316 -202.49896)
		(end 87.527638 -201.430636)
		(width 0.14732)
		(layer "In13.Cu")
		(net "P5E_CPU1_PE0_RX_DP<13>")
	)
	(segment
		(start 57.427876 -390.960864)
		(end 57.473342 -390.526524)
		(width 0.14732)
		(layer "In13.Cu")
		(net "P5E_CPU1_PE0_RX_DP<13>")
	)
	(segment
		(start 88.70442 -201.430636)
		(end 88.82888 -201.555096)
		(width 0.14732)
		(layer "In13.Cu")
		(net "P5E_CPU1_PE0_RX_DP<13>")
	)
	(segment
		(start 61.733176 -324.617334)
		(end 63.852044 -323.740018)
		(width 0.14732)
		(layer "In13.Cu")
		(net "P5E_CPU1_PE0_RX_DP<13>")
	)
	(segment
		(start 100.737416 -219.490544)
		(end 100.737416 -219.515944)
		(width 0.0889)
		(layer "In13.Cu")
		(net "P5E_CPU1_PE0_RX_DP<13>")
	)
	(segment
		(start 57.610502 -390.41578)
		(end 57.656222 -389.981186)
		(width 0.14732)
		(layer "In13.Cu")
		(net "P5E_CPU1_PE0_RX_DP<13>")
	)
	(segment
		(start 58.250328 -383.144776)
		(end 58.295794 -382.710436)
		(width 0.14732)
		(layer "In13.Cu")
		(net "P5E_CPU1_PE0_RX_DP<13>")
	)
	(segment
		(start 58.008266 -386.631434)
		(end 57.897522 -386.494528)
		(width 0.14732)
		(layer "In13.Cu")
		(net "P5E_CPU1_PE0_RX_DP<13>")
	)
	(segment
		(start 90.276934 -201.430636)
		(end 92.49537 -202.349608)
		(width 0.14732)
		(layer "In13.Cu")
		(net "P5E_CPU1_PE0_RX_DP<13>")
	)
	(segment
		(start 100.737416 -216.25052)
		(end 100.737416 -216.260426)
		(width 0.0889)
		(layer "In13.Cu")
		(net "P5E_CPU1_PE0_RX_DP<13>")
	)
	(segment
		(start 54.557168 -410.711396)
		(end 54.489858 -410.509466)
		(width 0.14732)
		(layer "In13.Cu")
		(net "P5E_CPU1_PE0_RX_DP<13>")
	)
	(segment
		(start 100.267516 -213.893654)
		(end 100.267516 -213.930484)
		(width 0.0889)
		(layer "In13.Cu")
		(net "P5E_CPU1_PE0_RX_DP<13>")
	)
	(segment
		(start 101.0285 -219.0115)
		(end 101.01961 -219.01658)
		(width 0.0889)
		(layer "In13.Cu")
		(net "P5E_CPU1_PE0_RX_DP<13>")
	)
	(segment
		(start 66.489326 -320.131694)
		(end 66.906902 -319.714372)
		(width 0.14732)
		(layer "In13.Cu")
		(net "P5E_CPU1_PE0_RX_DP<13>")
	)
	(segment
		(start 57.773824 -388.864602)
		(end 57.66308 -388.727696)
		(width 0.14732)
		(layer "In13.Cu")
		(net "P5E_CPU1_PE0_RX_DP<13>")
	)
	(segment
		(start 57.66308 -388.727696)
		(end 57.708546 -388.293356)
		(width 0.14732)
		(layer "In13.Cu")
		(net "P5E_CPU1_PE0_RX_DP<13>")
	)
	(segment
		(start 57.473342 -390.526524)
		(end 57.610502 -390.41578)
		(width 0.14732)
		(layer "In13.Cu")
		(net "P5E_CPU1_PE0_RX_DP<13>")
	)
	(segment
		(start 62.650116 -437.152288)
		(end 62.482984 -437.31942)
		(width 0.14732)
		(layer "In13.Cu")
		(net "P5E_CPU1_PE0_RX_DP<13>")
	)
	(segment
		(start 56.206898 -400.721322)
		(end 56.596788 -398.86128)
		(width 0.14732)
		(layer "In13.Cu")
		(net "P5E_CPU1_PE0_RX_DP<13>")
	)
	(segment
		(start 57.35574 -391.643108)
		(end 57.4929 -391.532364)
		(width 0.14732)
		(layer "In13.Cu")
		(net "P5E_CPU1_PE0_RX_DP<13>")
	)
	(segment
		(start 56.206898 -404.596092)
		(end 56.206898 -400.721322)
		(width 0.14732)
		(layer "In13.Cu")
		(net "P5E_CPU1_PE0_RX_DP<13>")
	)
	(segment
		(start 58.413396 -381.593852)
		(end 58.550556 -381.483108)
		(width 0.14732)
		(layer "In13.Cu")
		(net "P5E_CPU1_PE0_RX_DP<13>")
	)
	(segment
		(start 58.06059 -384.943604)
		(end 58.19775 -384.83286)
		(width 0.14732)
		(layer "In13.Cu")
		(net "P5E_CPU1_PE0_RX_DP<13>")
	)
	(segment
		(start 65.80251 -321.789552)
		(end 66.489326 -320.131694)
		(width 0.14732)
		(layer "In13.Cu")
		(net "P5E_CPU1_PE0_RX_DP<13>")
	)
	(segment
		(start 100.267262 -215.414606)
		(end 100.267262 -215.436704)
		(width 0.0889)
		(layer "In13.Cu")
		(net "P5E_CPU1_PE0_RX_DP<13>")
	)
	(segment
		(start 60.316364 -363.506258)
		(end 61.530738 -343.022174)
		(width 0.14732)
		(layer "In13.Cu")
		(net "P5E_CPU1_PE0_RX_DP<13>")
	)
	(segment
		(start 54.489858 -410.509466)
		(end 54.489858 -406.313132)
		(width 0.14732)
		(layer "In13.Cu")
		(net "P5E_CPU1_PE0_RX_DP<13>")
	)
	(segment
		(start 58.125868 -385.51485)
		(end 58.015124 -385.377944)
		(width 0.14732)
		(layer "In13.Cu")
		(net "P5E_CPU1_PE0_RX_DP<13>")
	)
	(segment
		(start 58.432954 -382.599692)
		(end 58.478674 -382.164844)
		(width 0.14732)
		(layer "In13.Cu")
		(net "P5E_CPU1_PE0_RX_DP<13>")
	)
	(segment
		(start 68.772024 -253.471426)
		(end 68.888356 -250.012962)
		(width 0.14732)
		(layer "In13.Cu")
		(net "P5E_CPU1_PE0_RX_DP<13>")
	)
	(segment
		(start 100.736908 -214.461344)
		(end 100.736908 -214.622634)
		(width 0.0889)
		(layer "In13.Cu")
		(net "P5E_CPU1_PE0_RX_DP<13>")
	)
	(segment
		(start 61.955172 -437.116728)
		(end 61.955172 -417.333176)
		(width 0.14732)
		(layer "In13.Cu")
		(net "P5E_CPU1_PE0_RX_DP<13>")
	)
	(segment
		(start 60.163964 -326.186546)
		(end 61.733176 -324.617334)
		(width 0.14732)
		(layer "In13.Cu")
		(net "P5E_CPU1_PE0_RX_DP<13>")
	)
	(segment
		(start 57.897522 -386.494528)
		(end 57.942988 -386.060188)
		(width 0.14732)
		(layer "In13.Cu")
		(net "P5E_CPU1_PE0_RX_DP<13>")
	)
	(segment
		(start 60.004706 -326.570594)
		(end 60.163964 -326.186546)
		(width 0.14732)
		(layer "In13.Cu")
		(net "P5E_CPU1_PE0_RX_DP<13>")
	)
	(segment
		(start 58.315352 -383.716276)
		(end 58.361072 -383.281682)
		(width 0.14732)
		(layer "In13.Cu")
		(net "P5E_CPU1_PE0_RX_DP<13>")
	)
	(segment
		(start 77.683868 -210.932268)
		(end 85.459316 -202.49896)
		(width 0.14732)
		(layer "In13.Cu")
		(net "P5E_CPU1_PE0_RX_DP<13>")
	)
	(segment
		(start 58.478674 -382.164844)
		(end 58.36793 -382.028192)
		(width 0.14732)
		(layer "In13.Cu")
		(net "P5E_CPU1_PE0_RX_DP<13>")
	)
	(segment
		(start 57.826148 -387.176772)
		(end 57.825386 -387.176772)
		(width 0.14732)
		(layer "In13.Cu")
		(net "P5E_CPU1_PE0_RX_DP<13>")
	)
	(segment
		(start 89.27084 -201.555096)
		(end 89.3953 -201.430636)
		(width 0.14732)
		(layer "In13.Cu")
		(net "P5E_CPU1_PE0_RX_DP<13>")
	)
	(segment
		(start 58.24347 -384.398266)
		(end 58.132726 -384.26136)
		(width 0.14732)
		(layer "In13.Cu")
		(net "P5E_CPU1_PE0_RX_DP<13>")
	)
	(segment
		(start 61.530738 -343.022174)
		(end 60.004706 -328.747374)
		(width 0.14732)
		(layer "In13.Cu")
		(net "P5E_CPU1_PE0_RX_DP<13>")
	)
	(segment
		(start 101.207062 -217.0557)
		(end 101.207062 -217.072972)
		(width 0.0889)
		(layer "In13.Cu")
		(net "P5E_CPU1_PE0_RX_DP<13>")
	)
	(segment
		(start 100.737416 -217.859864)
		(end 100.737416 -217.8939)
		(width 0.0889)
		(layer "In13.Cu")
		(net "P5E_CPU1_PE0_RX_DP<13>")
	)
	(segment
		(start 57.53862 -391.09777)
		(end 57.427876 -390.960864)
		(width 0.14732)
		(layer "In13.Cu")
		(net "P5E_CPU1_PE0_RX_DP<13>")
	)
	(segment
		(start 56.596788 -398.86128)
		(end 57.356248 -391.643108)
		(width 0.14732)
		(layer "In13.Cu")
		(net "P5E_CPU1_PE0_RX_DP<13>")
	)
	(segment
		(start 101.207062 -220.311218)
		(end 101.207062 -220.334078)
		(width 0.0889)
		(layer "In13.Cu")
		(net "P5E_CPU1_PE0_RX_DP<13>")
	)
	(segment
		(start 57.891426 -387.748018)
		(end 57.780682 -387.611112)
		(width 0.14732)
		(layer "In13.Cu")
		(net "P5E_CPU1_PE0_RX_DP<13>")
	)
	(segment
		(start 58.132726 -384.26136)
		(end 58.178192 -383.82702)
		(width 0.14732)
		(layer "In13.Cu")
		(net "P5E_CPU1_PE0_RX_DP<13>")
	)
	(segment
		(start 58.36793 -382.028192)
		(end 58.413396 -381.593852)
		(width 0.14732)
		(layer "In13.Cu")
		(net "P5E_CPU1_PE0_RX_DP<13>")
	)
	(segment
		(start 59.138566 -414.51657)
		(end 54.808882 -410.96311)
		(width 0.14732)
		(layer "In13.Cu")
		(net "P5E_CPU1_PE0_RX_DP<13>")
	)
	(segment
		(start 100.549964 -215.926162)
		(end 100.558854 -215.931242)
		(width 0.0889)
		(layer "In13.Cu")
		(net "P5E_CPU1_PE0_RX_DP<13>")
	)
	(segment
		(start 68.8467 -316.944502)
		(end 72.281034 -308.663086)
		(width 0.14732)
		(layer "In13.Cu")
		(net "P5E_CPU1_PE0_RX_DP<13>")
	)
	(segment
		(start 61.955172 -417.333176)
		(end 59.138566 -414.51657)
		(width 0.14732)
		(layer "In13.Cu")
		(net "P5E_CPU1_PE0_RX_DP<13>")
	)
	(segment
		(start 62.157864 -437.31942)
		(end 61.955172 -437.116728)
		(width 0.14732)
		(layer "In13.Cu")
		(net "P5E_CPU1_PE0_RX_DP<13>")
	)
	(segment
		(start 58.485532 -380.911608)
		(end 60.316364 -363.506258)
		(width 0.14732)
		(layer "In13.Cu")
		(net "P5E_CPU1_PE0_RX_DP<13>")
	)
	(segment
		(start 57.4929 -391.532364)
		(end 57.53862 -391.09777)
		(width 0.14732)
		(layer "In13.Cu")
		(net "P5E_CPU1_PE0_RX_DP<13>")
	)
	(segment
		(start 72.281034 -308.663086)
		(end 68.772024 -254.30226)
		(width 0.14732)
		(layer "In13.Cu")
		(net "P5E_CPU1_PE0_RX_DP<13>")
	)
	(segment
		(start 62.482984 -437.31942)
		(end 62.157864 -437.31942)
		(width 0.14732)
		(layer "In13.Cu")
		(net "P5E_CPU1_PE0_RX_DP<13>")
	)
	(segment
		(start 57.942988 -386.060188)
		(end 58.080148 -385.949444)
		(width 0.14732)
		(layer "In13.Cu")
		(net "P5E_CPU1_PE0_RX_DP<13>")
	)
	(segment
		(start 60.004706 -328.747374)
		(end 60.004706 -326.570594)
		(width 0.14732)
		(layer "In13.Cu")
		(net "P5E_CPU1_PE0_RX_DP<13>")
	)
	(segment
		(start 58.295794 -382.710436)
		(end 58.432954 -382.599692)
		(width 0.14732)
		(layer "In13.Cu")
		(net "P5E_CPU1_PE0_RX_DP<13>")
	)
	(segment
		(start 99.160076 -209.014314)
		(end 100.225098 -211.585556)
		(width 0.14732)
		(layer "In13.Cu")
		(net "P5E_CPU1_PE0_RX_DP<13>")
	)
	(segment
		(start 70.18528 -232.450132)
		(end 72.262492 -219.009976)
		(width 0.14732)
		(layer "In13.Cu")
		(net "P5E_CPU1_PE0_RX_DP<13>")
	)
	(segment
		(start 100.225098 -213.197948)
		(end 100.267262 -213.240112)
		(width 0.0889)
		(layer "In13.Cu")
		(net "P5E_CPU1_PE0_RX_DP<13>")
	)
	(segment
		(start 57.728104 -389.299196)
		(end 57.773824 -388.864602)
		(width 0.14732)
		(layer "In13.Cu")
		(net "P5E_CPU1_PE0_RX_DP<13>")
	)
	(segment
		(start 58.596276 -381.04826)
		(end 58.485532 -380.911608)
		(width 0.14732)
		(layer "In13.Cu")
		(net "P5E_CPU1_PE0_RX_DP<13>")
	)
	(segment
		(start 57.356248 -391.643108)
		(end 57.35574 -391.643108)
		(width 0.14732)
		(layer "In13.Cu")
		(net "P5E_CPU1_PE0_RX_DP<13>")
	)
	(segment
		(start 100.225098 -211.585556)
		(end 100.225098 -213.17585)
		(width 0.14732)
		(layer "In13.Cu")
		(net "P5E_CPU1_PE0_RX_DP<13>")
	)
	(segment
		(start 101.4349 -220.773752)
		(end 101.45903 -220.862906)
		(width 0.0889)
		(layer "In13.Cu")
		(net "P5E_CPU1_PE0_RX_DP<13>")
	)
	(segment
		(start 58.361072 -383.281682)
		(end 58.250328 -383.144776)
		(width 0.14732)
		(layer "In13.Cu")
		(net "P5E_CPU1_PE0_RX_DP<13>")
	)
	(segment
		(start 58.19775 -384.83286)
		(end 58.24347 -384.398266)
		(width 0.14732)
		(layer "In13.Cu")
		(net "P5E_CPU1_PE0_RX_DP<13>")
	)
	(segment
		(start 57.708546 -388.293356)
		(end 57.845706 -388.182612)
		(width 0.14732)
		(layer "In13.Cu")
		(net "P5E_CPU1_PE0_RX_DP<13>")
	)
	(segment
		(start 101.45903 -220.862906)
		(end 101.302566 -221.133924)
		(width 0.0889)
		(layer "In13.Cu")
		(net "P5E_CPU1_PE0_RX_DP<13>")
	)
	(segment
		(start 66.906902 -319.714372)
		(end 68.8467 -316.944502)
		(width 0.14732)
		(layer "In13.Cu")
		(net "P5E_CPU1_PE0_RX_DP<13>")
	)
	(segment
		(start 58.178192 -383.82702)
		(end 58.315352 -383.716276)
		(width 0.14732)
		(layer "In13.Cu")
		(net "P5E_CPU1_PE0_RX_DP<13>")
	)
	(segment
		(start 63.852044 -323.740018)
		(end 65.80251 -321.789552)
		(width 0.14732)
		(layer "In13.Cu")
		(net "P5E_CPU1_PE0_RX_DP<13>")
	)
	(segment
		(start 68.888356 -250.012962)
		(end 70.18528 -232.450132)
		(width 0.14732)
		(layer "In13.Cu")
		(net "P5E_CPU1_PE0_RX_DP<13>")
	)
	(segment
		(start 62.650116 -436.889906)
		(end 62.650116 -437.152288)
		(width 0.14732)
		(layer "In13.Cu")
		(net "P5E_CPU1_PE0_RX_DP<13>")
	)
	(segment
		(start 57.545478 -389.84428)
		(end 57.590944 -389.40994)
		(width 0.14732)
		(layer "In13.Cu")
		(net "P5E_CPU1_PE0_RX_DP<13>")
	)
	(segment
		(start 88.82888 -201.555096)
		(end 89.27084 -201.555096)
		(width 0.14732)
		(layer "In13.Cu")
		(net "P5E_CPU1_PE0_RX_DP<13>")
	)
	(segment
		(start 100.558346 -214.941912)
		(end 100.549456 -214.946992)
		(width 0.0889)
		(layer "In13.Cu")
		(net "P5E_CPU1_PE0_RX_DP<13>")
	)
	(segment
		(start 87.527638 -201.430636)
		(end 88.70442 -201.430636)
		(width 0.14732)
		(layer "In13.Cu")
		(net "P5E_CPU1_PE0_RX_DP<13>")
	)
	(segment
		(start 100.267262 -213.240112)
		(end 100.267262 -213.8934)
		(width 0.0889)
		(layer "In13.Cu")
		(net "P5E_CPU1_PE0_RX_DP<13>")
	)
	(segment
		(start 57.780682 -387.611112)
		(end 57.826148 -387.176772)
		(width 0.14732)
		(layer "In13.Cu")
		(net "P5E_CPU1_PE0_RX_DP<13>")
	)
	(segment
		(start 54.808882 -410.96311)
		(end 54.557168 -410.711396)
		(width 0.14732)
		(layer "In13.Cu")
		(net "P5E_CPU1_PE0_RX_DP<13>")
	)
	(segment
		(start 58.015124 -385.377944)
		(end 58.06059 -384.943604)
		(width 0.14732)
		(layer "In13.Cu")
		(net "P5E_CPU1_PE0_RX_DP<13>")
	)
	(segment
		(start 57.656222 -389.981186)
		(end 57.545478 -389.84428)
		(width 0.14732)
		(layer "In13.Cu")
		(net "P5E_CPU1_PE0_RX_DP<13>")
	)
	(segment
		(start 72.262492 -219.009976)
		(end 73.971658 -215.71585)
		(width 0.14732)
		(layer "In13.Cu")
		(net "P5E_CPU1_PE0_RX_DP<13>")
	)
	(segment
		(start 57.845706 -388.182612)
		(end 57.891426 -387.748018)
		(width 0.14732)
		(layer "In13.Cu")
		(net "P5E_CPU1_PE0_RX_DP<13>")
	)
	(segment
		(start 57.962546 -387.066028)
		(end 58.008266 -386.631434)
		(width 0.14732)
		(layer "In13.Cu")
		(net "P5E_CPU1_PE0_RX_DP<13>")
	)
	(segment
		(start 100.543868 -215.922606)
		(end 100.549964 -215.926162)
		(width 0.0889)
		(layer "In13.Cu")
		(net "P5E_CPU1_PE0_RX_DP<13>")
	)
	(segment
		(start 58.080148 -385.949444)
		(end 58.125868 -385.51485)
		(width 0.14732)
		(layer "In13.Cu")
		(net "P5E_CPU1_PE0_RX_DP<13>")
	)
	(arc
		(start 100.267262 -215.436704)
		(mid 100.341253 -215.71627)
		(end 100.543868 -215.922606)
		(width 0.0889)
		(layer "In13.Cu")
		(net "P5E_CPU1_PE0_RX_DP<13>")
	)
	(arc
		(start 100.552758 -214.261954)
		(mid 100.661905 -214.345882)
		(end 100.736908 -214.461344)
		(width 0.0889)
		(layer "In13.Cu")
		(net "P5E_CPU1_PE0_RX_DP<13>")
	)
	(arc
		(start 100.558854 -215.931242)
		(mid 100.689768 -216.067602)
		(end 100.737416 -216.25052)
		(width 0.0889)
		(layer "In13.Cu")
		(net "P5E_CPU1_PE0_RX_DP<13>")
	)
	(arc
		(start 101.019864 -216.739978)
		(mid 101.154797 -216.873332)
		(end 101.207062 -217.0557)
		(width 0.0889)
		(layer "In13.Cu")
		(net "P5E_CPU1_PE0_RX_DP<13>")
	)
	(arc
		(start 100.282756 -213.969346)
		(mid 100.39275 -214.138715)
		(end 100.552758 -214.261954)
		(width 0.0889)
		(layer "In13.Cu")
		(net "P5E_CPU1_PE0_RX_DP<13>")
	)
	(arc
		(start 101.019864 -219.995496)
		(mid 101.154797 -220.12885)
		(end 101.207062 -220.311218)
		(width 0.0889)
		(layer "In13.Cu")
		(net "P5E_CPU1_PE0_RX_DP<13>")
	)
	(arc
		(start 101.01961 -219.01658)
		(mid 100.816787 -219.216811)
		(end 100.737416 -219.490544)
		(width 0.0889)
		(layer "In13.Cu")
		(net "P5E_CPU1_PE0_RX_DP<13>")
	)
	(arc
		(start 101.417882 -220.760798)
		(mid 101.42633 -220.767355)
		(end 101.4349 -220.773752)
		(width 0.0889)
		(layer "In13.Cu")
		(net "P5E_CPU1_PE0_RX_DP<13>")
	)
	(arc
		(start 100.737416 -219.515944)
		(mid 100.815527 -219.792893)
		(end 101.019864 -219.995496)
		(width 0.0889)
		(layer "In13.Cu")
		(net "P5E_CPU1_PE0_RX_DP<13>")
	)
	(arc
		(start 101.0285 -218.372944)
		(mid 101.206976 -218.692222)
		(end 101.0285 -219.0115)
		(width 0.0889)
		(layer "In13.Cu")
		(net "P5E_CPU1_PE0_RX_DP<13>")
	)
	(arc
		(start 100.737416 -216.260426)
		(mid 100.815527 -216.537375)
		(end 101.019864 -216.739978)
		(width 0.0889)
		(layer "In13.Cu")
		(net "P5E_CPU1_PE0_RX_DP<13>")
	)
	(arc
		(start 100.549456 -214.946992)
		(mid 100.348174 -215.144479)
		(end 100.267262 -215.414606)
		(width 0.0889)
		(layer "In13.Cu")
		(net "P5E_CPU1_PE0_RX_DP<13>")
	)
	(arc
		(start 100.736908 -214.622634)
		(mid 100.689229 -214.805534)
		(end 100.558346 -214.941912)
		(width 0.0889)
		(layer "In13.Cu")
		(net "P5E_CPU1_PE0_RX_DP<13>")
	)
	(arc
		(start 101.207062 -220.334078)
		(mid 101.265356 -220.570721)
		(end 101.417882 -220.760798)
		(width 0.0889)
		(layer "In13.Cu")
		(net "P5E_CPU1_PE0_RX_DP<13>")
	)
	(arc
		(start 101.207062 -217.072972)
		(mid 101.154792 -217.255337)
		(end 101.019864 -217.388694)
		(width 0.0889)
		(layer "In13.Cu")
		(net "P5E_CPU1_PE0_RX_DP<13>")
	)
	(arc
		(start 100.737416 -217.8939)
		(mid 100.816786 -218.167634)
		(end 101.01961 -218.367864)
		(width 0.0889)
		(layer "In13.Cu")
		(net "P5E_CPU1_PE0_RX_DP<13>")
	)
	(arc
		(start 101.019864 -217.388694)
		(mid 100.817578 -217.587675)
		(end 100.737416 -217.859864)
		(width 0.0889)
		(layer "In13.Cu")
		(net "P5E_CPU1_PE0_RX_DP<13>")
	)
	(arc
		(start 100.267516 -213.930484)
		(mid 100.274801 -213.950046)
		(end 100.282756 -213.969346)
		(width 0.0889)
		(layer "In13.Cu")
		(net "P5E_CPU1_PE0_RX_DP<13>")
	)
	(segment
		(start 100.832666 -222.48368)
		(end 100.882958 -222.433388)
		(width 0.13208)
		(layer "F.Cu")
		(net "P5E_CPU1_PE0_RX_DP<12>")
	)
	(segment
		(start 100.882958 -222.433388)
		(end 100.882958 -221.998286)
		(width 0.13208)
		(layer "F.Cu")
		(net "P5E_CPU1_PE0_RX_DP<12>")
	)
	(segment
		(start 100.882958 -221.998286)
		(end 100.832412 -221.94774)
		(width 0.13208)
		(layer "F.Cu")
		(net "P5E_CPU1_PE0_RX_DP<12>")
	)
	(segment
		(start 60.468764 -383.648712)
		(end 60.49391 -383.212594)
		(width 0.14732)
		(layer "In13.Cu")
		(net "P5E_CPU1_PE0_RX_DP<12>")
	)
	(segment
		(start 59.810142 -397.503904)
		(end 59.831478 -397.135858)
		(width 0.14732)
		(layer "In13.Cu")
		(net "P5E_CPU1_PE0_RX_DP<12>")
	)
	(segment
		(start 59.270138 -400.54276)
		(end 59.631326 -398.084802)
		(width 0.14732)
		(layer "In13.Cu")
		(net "P5E_CPU1_PE0_RX_DP<12>")
	)
	(segment
		(start 60.533788 -382.52781)
		(end 60.558934 -382.091692)
		(width 0.14732)
		(layer "In13.Cu")
		(net "P5E_CPU1_PE0_RX_DP<12>")
	)
	(segment
		(start 99.327716 -213.240112)
		(end 99.327716 -213.930484)
		(width 0.0889)
		(layer "In13.Cu")
		(net "P5E_CPU1_PE0_RX_DP<12>")
	)
	(segment
		(start 99.604068 -215.922606)
		(end 99.610164 -215.926162)
		(width 0.0889)
		(layer "In13.Cu")
		(net "P5E_CPU1_PE0_RX_DP<12>")
	)
	(segment
		(start 99.285552 -213.17585)
		(end 99.285552 -213.197948)
		(width 0.0889)
		(layer "In13.Cu")
		(net "P5E_CPU1_PE0_RX_DP<12>")
	)
	(segment
		(start 60.715906 -381.53848)
		(end 60.599066 -381.406908)
		(width 0.14732)
		(layer "In13.Cu")
		(net "P5E_CPU1_PE0_RX_DP<12>")
	)
	(segment
		(start 64.48298 -438.319418)
		(end 64.079628 -438.319418)
		(width 0.14732)
		(layer "In13.Cu")
		(net "P5E_CPU1_PE0_RX_DP<12>")
	)
	(segment
		(start 57.553098 -406.313132)
		(end 59.270138 -404.596092)
		(width 0.14732)
		(layer "In13.Cu")
		(net "P5E_CPU1_PE0_RX_DP<12>")
	)
	(segment
		(start 61.043312 -326.679814)
		(end 61.839348 -325.883778)
		(width 0.14732)
		(layer "In13.Cu")
		(net "P5E_CPU1_PE0_RX_DP<12>")
	)
	(segment
		(start 59.695334 -396.98295)
		(end 60.164472 -388.89178)
		(width 0.14732)
		(layer "In13.Cu")
		(net "P5E_CPU1_PE0_RX_DP<12>")
	)
	(segment
		(start 64.650112 -437.889904)
		(end 64.650112 -438.152286)
		(width 0.14732)
		(layer "In13.Cu")
		(net "P5E_CPU1_PE0_RX_DP<12>")
	)
	(segment
		(start 64.650112 -438.152286)
		(end 64.48298 -438.319418)
		(width 0.14732)
		(layer "In13.Cu")
		(net "P5E_CPU1_PE0_RX_DP<12>")
	)
	(segment
		(start 59.270138 -404.596092)
		(end 59.270138 -400.54276)
		(width 0.14732)
		(layer "In13.Cu")
		(net "P5E_CPU1_PE0_RX_DP<12>")
	)
	(segment
		(start 64.079628 -438.319418)
		(end 63.955168 -438.194958)
		(width 0.14732)
		(layer "In13.Cu")
		(net "P5E_CPU1_PE0_RX_DP<12>")
	)
	(segment
		(start 60.599066 -381.406908)
		(end 62.73927 -344.505788)
		(width 0.14732)
		(layer "In13.Cu")
		(net "P5E_CPU1_PE0_RX_DP<12>")
	)
	(segment
		(start 100.07981 -219.995496)
		(end 100.080826 -219.996004)
		(width 0.0889)
		(layer "In13.Cu")
		(net "P5E_CPU1_PE0_RX_DP<12>")
	)
	(segment
		(start 87.787226 -202.497436)
		(end 90.18778 -202.497436)
		(width 0.14732)
		(layer "In13.Cu")
		(net "P5E_CPU1_PE0_RX_DP<12>")
	)
	(segment
		(start 86.116414 -203.360782)
		(end 87.787226 -202.497436)
		(width 0.14732)
		(layer "In13.Cu")
		(net "P5E_CPU1_PE0_RX_DP<12>")
	)
	(segment
		(start 99.618546 -214.941912)
		(end 99.609656 -214.946992)
		(width 0.0889)
		(layer "In13.Cu")
		(net "P5E_CPU1_PE0_RX_DP<12>")
	)
	(segment
		(start 92.035376 -203.262738)
		(end 98.36912 -209.596482)
		(width 0.14732)
		(layer "In13.Cu")
		(net "P5E_CPU1_PE0_RX_DP<12>")
	)
	(segment
		(start 60.585858 -383.78003)
		(end 60.468764 -383.648712)
		(width 0.14732)
		(layer "In13.Cu")
		(net "P5E_CPU1_PE0_RX_DP<12>")
	)
	(segment
		(start 60.625482 -383.0955)
		(end 60.650882 -382.659128)
		(width 0.14732)
		(layer "In13.Cu")
		(net "P5E_CPU1_PE0_RX_DP<12>")
	)
	(segment
		(start 63.955168 -438.194958)
		(end 63.955168 -417.094416)
		(width 0.14732)
		(layer "In13.Cu")
		(net "P5E_CPU1_PE0_RX_DP<12>")
	)
	(segment
		(start 100.0887 -217.383614)
		(end 100.07981 -217.388694)
		(width 0.0889)
		(layer "In13.Cu")
		(net "P5E_CPU1_PE0_RX_DP<12>")
	)
	(segment
		(start 100.080826 -219.996004)
		(end 100.0887 -220.000576)
		(width 0.0889)
		(layer "In13.Cu")
		(net "P5E_CPU1_PE0_RX_DP<12>")
	)
	(segment
		(start 100.0887 -219.0115)
		(end 100.07981 -219.01658)
		(width 0.0889)
		(layer "In13.Cu")
		(net "P5E_CPU1_PE0_RX_DP<12>")
	)
	(segment
		(start 60.43041 -386.458206)
		(end 60.45581 -386.021834)
		(width 0.14732)
		(layer "In13.Cu")
		(net "P5E_CPU1_PE0_RX_DP<12>")
	)
	(segment
		(start 99.285552 -211.808822)
		(end 99.285552 -213.17585)
		(width 0.14732)
		(layer "In13.Cu")
		(net "P5E_CPU1_PE0_RX_DP<12>")
	)
	(segment
		(start 60.20435 -388.206996)
		(end 60.233814 -387.696202)
		(width 0.14732)
		(layer "In13.Cu")
		(net "P5E_CPU1_PE0_RX_DP<12>")
	)
	(segment
		(start 73.29043 -219.346018)
		(end 74.87412 -216.293446)
		(width 0.14732)
		(layer "In13.Cu")
		(net "P5E_CPU1_PE0_RX_DP<12>")
	)
	(segment
		(start 100.0887 -220.639132)
		(end 100.07981 -220.644212)
		(width 0.0889)
		(layer "In13.Cu")
		(net "P5E_CPU1_PE0_RX_DP<12>")
	)
	(segment
		(start 62.73927 -344.505788)
		(end 61.043312 -328.884788)
		(width 0.14732)
		(layer "In13.Cu")
		(net "P5E_CPU1_PE0_RX_DP<12>")
	)
	(segment
		(start 60.40374 -384.769614)
		(end 60.428886 -384.333496)
		(width 0.14732)
		(layer "In13.Cu")
		(net "P5E_CPU1_PE0_RX_DP<12>")
	)
	(segment
		(start 67.432682 -320.54673)
		(end 67.5894 -320.389504)
		(width 0.14732)
		(layer "In13.Cu")
		(net "P5E_CPU1_PE0_RX_DP<12>")
	)
	(segment
		(start 59.831478 -397.135858)
		(end 59.695334 -396.98295)
		(width 0.14732)
		(layer "In13.Cu")
		(net "P5E_CPU1_PE0_RX_DP<12>")
	)
	(segment
		(start 99.327462 -215.414606)
		(end 99.327462 -215.436704)
		(width 0.0889)
		(layer "In13.Cu")
		(net "P5E_CPU1_PE0_RX_DP<12>")
	)
	(segment
		(start 60.365386 -387.579108)
		(end 60.390786 -387.142736)
		(width 0.14732)
		(layer "In13.Cu")
		(net "P5E_CPU1_PE0_RX_DP<12>")
	)
	(segment
		(start 61.839348 -325.883778)
		(end 64.14008 -325.883778)
		(width 0.14732)
		(layer "In13.Cu")
		(net "P5E_CPU1_PE0_RX_DP<12>")
	)
	(segment
		(start 60.273692 -387.011418)
		(end 60.298838 -386.5753)
		(width 0.14732)
		(layer "In13.Cu")
		(net "P5E_CPU1_PE0_RX_DP<12>")
	)
	(segment
		(start 78.499208 -211.622386)
		(end 86.116414 -203.360782)
		(width 0.14732)
		(layer "In13.Cu")
		(net "P5E_CPU1_PE0_RX_DP<12>")
	)
	(segment
		(start 60.233814 -387.696202)
		(end 60.365386 -387.579108)
		(width 0.14732)
		(layer "In13.Cu")
		(net "P5E_CPU1_PE0_RX_DP<12>")
	)
	(segment
		(start 60.650882 -382.659128)
		(end 60.533788 -382.52781)
		(width 0.14732)
		(layer "In13.Cu")
		(net "P5E_CPU1_PE0_RX_DP<12>")
	)
	(segment
		(start 60.495434 -385.337304)
		(end 60.520834 -384.900932)
		(width 0.14732)
		(layer "In13.Cu")
		(net "P5E_CPU1_PE0_RX_DP<12>")
	)
	(segment
		(start 67.5894 -320.389504)
		(end 69.850254 -317.161672)
		(width 0.14732)
		(layer "In13.Cu")
		(net "P5E_CPU1_PE0_RX_DP<12>")
	)
	(segment
		(start 57.553098 -410.302964)
		(end 57.553098 -406.313132)
		(width 0.14732)
		(layer "In13.Cu")
		(net "P5E_CPU1_PE0_RX_DP<12>")
	)
	(segment
		(start 60.296044 -388.774686)
		(end 60.321444 -388.338314)
		(width 0.14732)
		(layer "In13.Cu")
		(net "P5E_CPU1_PE0_RX_DP<12>")
	)
	(segment
		(start 60.390786 -387.142736)
		(end 60.273692 -387.011418)
		(width 0.14732)
		(layer "In13.Cu")
		(net "P5E_CPU1_PE0_RX_DP<12>")
	)
	(segment
		(start 60.49391 -383.212594)
		(end 60.625482 -383.0955)
		(width 0.14732)
		(layer "In13.Cu")
		(net "P5E_CPU1_PE0_RX_DP<12>")
	)
	(segment
		(start 64.14008 -325.883778)
		(end 65.986406 -324.037452)
		(width 0.14732)
		(layer "In13.Cu")
		(net "P5E_CPU1_PE0_RX_DP<12>")
	)
	(segment
		(start 100.07981 -218.367864)
		(end 100.0887 -218.372944)
		(width 0.0889)
		(layer "In13.Cu")
		(net "P5E_CPU1_PE0_RX_DP<12>")
	)
	(segment
		(start 99.797616 -217.856308)
		(end 99.797616 -217.8939)
		(width 0.0889)
		(layer "In13.Cu")
		(net "P5E_CPU1_PE0_RX_DP<12>")
	)
	(segment
		(start 60.321444 -388.338314)
		(end 60.20435 -388.206996)
		(width 0.14732)
		(layer "In13.Cu")
		(net "P5E_CPU1_PE0_RX_DP<12>")
	)
	(segment
		(start 60.428886 -384.333496)
		(end 60.560458 -384.216402)
		(width 0.14732)
		(layer "In13.Cu")
		(net "P5E_CPU1_PE0_RX_DP<12>")
	)
	(segment
		(start 60.69076 -381.974852)
		(end 60.715906 -381.53848)
		(width 0.14732)
		(layer "In13.Cu")
		(net "P5E_CPU1_PE0_RX_DP<12>")
	)
	(segment
		(start 99.797616 -221.111826)
		(end 99.797616 -221.149418)
		(width 0.0889)
		(layer "In13.Cu")
		(net "P5E_CPU1_PE0_RX_DP<12>")
	)
	(segment
		(start 90.18778 -202.497436)
		(end 92.035376 -203.262738)
		(width 0.14732)
		(layer "In13.Cu")
		(net "P5E_CPU1_PE0_RX_DP<12>")
	)
	(segment
		(start 60.45581 -386.021834)
		(end 60.338716 -385.890516)
		(width 0.14732)
		(layer "In13.Cu")
		(net "P5E_CPU1_PE0_RX_DP<12>")
	)
	(segment
		(start 60.558934 -382.091692)
		(end 60.69076 -381.974852)
		(width 0.14732)
		(layer "In13.Cu")
		(net "P5E_CPU1_PE0_RX_DP<12>")
	)
	(segment
		(start 60.338716 -385.890516)
		(end 60.363862 -385.454398)
		(width 0.14732)
		(layer "In13.Cu")
		(net "P5E_CPU1_PE0_RX_DP<12>")
	)
	(segment
		(start 65.986406 -324.037452)
		(end 67.432682 -320.54673)
		(width 0.14732)
		(layer "In13.Cu")
		(net "P5E_CPU1_PE0_RX_DP<12>")
	)
	(segment
		(start 99.797616 -219.490544)
		(end 99.797616 -219.521532)
		(width 0.0889)
		(layer "In13.Cu")
		(net "P5E_CPU1_PE0_RX_DP<12>")
	)
	(segment
		(start 61.043312 -328.884788)
		(end 61.043312 -326.679814)
		(width 0.14732)
		(layer "In13.Cu")
		(net "P5E_CPU1_PE0_RX_DP<12>")
	)
	(segment
		(start 100.587048 -221.6531)
		(end 100.675948 -221.676722)
		(width 0.0889)
		(layer "In13.Cu")
		(net "P5E_CPU1_PE0_RX_DP<12>")
	)
	(segment
		(start 60.560458 -384.216402)
		(end 60.585858 -383.78003)
		(width 0.14732)
		(layer "In13.Cu")
		(net "P5E_CPU1_PE0_RX_DP<12>")
	)
	(segment
		(start 100.675948 -221.676722)
		(end 100.832412 -221.94774)
		(width 0.0889)
		(layer "In13.Cu")
		(net "P5E_CPU1_PE0_RX_DP<12>")
	)
	(segment
		(start 99.797108 -214.461344)
		(end 99.797108 -214.622634)
		(width 0.0889)
		(layer "In13.Cu")
		(net "P5E_CPU1_PE0_RX_DP<12>")
	)
	(segment
		(start 100.07981 -216.739978)
		(end 100.080826 -216.740486)
		(width 0.0889)
		(layer "In13.Cu")
		(net "P5E_CPU1_PE0_RX_DP<12>")
	)
	(segment
		(start 99.797616 -216.25052)
		(end 99.797616 -216.266014)
		(width 0.0889)
		(layer "In13.Cu")
		(net "P5E_CPU1_PE0_RX_DP<12>")
	)
	(segment
		(start 59.657234 -397.639794)
		(end 59.810142 -397.503904)
		(width 0.14732)
		(layer "In13.Cu")
		(net "P5E_CPU1_PE0_RX_DP<12>")
	)
	(segment
		(start 99.285552 -213.197948)
		(end 99.327716 -213.240112)
		(width 0.0889)
		(layer "In13.Cu")
		(net "P5E_CPU1_PE0_RX_DP<12>")
	)
	(segment
		(start 60.164472 -388.89178)
		(end 60.296044 -388.774686)
		(width 0.14732)
		(layer "In13.Cu")
		(net "P5E_CPU1_PE0_RX_DP<12>")
	)
	(segment
		(start 98.36912 -209.596482)
		(end 99.285552 -211.808822)
		(width 0.14732)
		(layer "In13.Cu")
		(net "P5E_CPU1_PE0_RX_DP<12>")
	)
	(segment
		(start 99.610164 -215.926162)
		(end 99.619054 -215.931242)
		(width 0.0889)
		(layer "In13.Cu")
		(net "P5E_CPU1_PE0_RX_DP<12>")
	)
	(segment
		(start 73.260966 -308.929532)
		(end 69.704204 -253.695708)
		(width 0.14732)
		(layer "In13.Cu")
		(net "P5E_CPU1_PE0_RX_DP<12>")
	)
	(segment
		(start 57.828434 -410.967682)
		(end 57.553098 -410.302964)
		(width 0.14732)
		(layer "In13.Cu")
		(net "P5E_CPU1_PE0_RX_DP<12>")
	)
	(segment
		(start 69.850254 -317.161672)
		(end 73.260966 -308.929532)
		(width 0.14732)
		(layer "In13.Cu")
		(net "P5E_CPU1_PE0_RX_DP<12>")
	)
	(segment
		(start 100.080826 -216.740486)
		(end 100.0887 -216.745058)
		(width 0.0889)
		(layer "In13.Cu")
		(net "P5E_CPU1_PE0_RX_DP<12>")
	)
	(segment
		(start 69.704204 -253.695708)
		(end 69.825616 -250.056904)
		(width 0.14732)
		(layer "In13.Cu")
		(net "P5E_CPU1_PE0_RX_DP<12>")
	)
	(segment
		(start 71.239888 -232.612692)
		(end 73.29043 -219.346018)
		(width 0.14732)
		(layer "In13.Cu")
		(net "P5E_CPU1_PE0_RX_DP<12>")
	)
	(segment
		(start 59.631326 -398.084802)
		(end 59.657234 -397.639794)
		(width 0.14732)
		(layer "In13.Cu")
		(net "P5E_CPU1_PE0_RX_DP<12>")
	)
	(segment
		(start 60.298838 -386.5753)
		(end 60.43041 -386.458206)
		(width 0.14732)
		(layer "In13.Cu")
		(net "P5E_CPU1_PE0_RX_DP<12>")
	)
	(segment
		(start 63.955168 -417.094416)
		(end 57.828434 -410.967682)
		(width 0.14732)
		(layer "In13.Cu")
		(net "P5E_CPU1_PE0_RX_DP<12>")
	)
	(segment
		(start 69.825616 -250.056904)
		(end 71.239888 -232.612692)
		(width 0.14732)
		(layer "In13.Cu")
		(net "P5E_CPU1_PE0_RX_DP<12>")
	)
	(segment
		(start 74.87412 -216.293446)
		(end 78.499208 -211.622386)
		(width 0.14732)
		(layer "In13.Cu")
		(net "P5E_CPU1_PE0_RX_DP<12>")
	)
	(segment
		(start 60.520834 -384.900932)
		(end 60.40374 -384.769614)
		(width 0.14732)
		(layer "In13.Cu")
		(net "P5E_CPU1_PE0_RX_DP<12>")
	)
	(segment
		(start 60.363862 -385.454398)
		(end 60.495434 -385.337304)
		(width 0.14732)
		(layer "In13.Cu")
		(net "P5E_CPU1_PE0_RX_DP<12>")
	)
	(arc
		(start 99.797616 -216.266014)
		(mid 99.876986 -216.539748)
		(end 100.07981 -216.739978)
		(width 0.0889)
		(layer "In13.Cu")
		(net "P5E_CPU1_PE0_RX_DP<12>")
	)
	(arc
		(start 99.327716 -213.930484)
		(mid 99.335001 -213.950046)
		(end 99.342956 -213.969346)
		(width 0.0889)
		(layer "In13.Cu")
		(net "P5E_CPU1_PE0_RX_DP<12>")
	)
	(arc
		(start 99.619054 -215.931242)
		(mid 99.749968 -216.067602)
		(end 99.797616 -216.25052)
		(width 0.0889)
		(layer "In13.Cu")
		(net "P5E_CPU1_PE0_RX_DP<12>")
	)
	(arc
		(start 100.0887 -216.745058)
		(mid 100.267297 -217.064336)
		(end 100.0887 -217.383614)
		(width 0.0889)
		(layer "In13.Cu")
		(net "P5E_CPU1_PE0_RX_DP<12>")
	)
	(arc
		(start 99.797616 -219.521532)
		(mid 99.876986 -219.795266)
		(end 100.07981 -219.995496)
		(width 0.0889)
		(layer "In13.Cu")
		(net "P5E_CPU1_PE0_RX_DP<12>")
	)
	(arc
		(start 99.342956 -213.969346)
		(mid 99.45295 -214.138715)
		(end 99.612958 -214.261954)
		(width 0.0889)
		(layer "In13.Cu")
		(net "P5E_CPU1_PE0_RX_DP<12>")
	)
	(arc
		(start 100.07981 -219.01658)
		(mid 99.876987 -219.216811)
		(end 99.797616 -219.490544)
		(width 0.0889)
		(layer "In13.Cu")
		(net "P5E_CPU1_PE0_RX_DP<12>")
	)
	(arc
		(start 100.07981 -220.644212)
		(mid 99.878528 -220.841699)
		(end 99.797616 -221.111826)
		(width 0.0889)
		(layer "In13.Cu")
		(net "P5E_CPU1_PE0_RX_DP<12>")
	)
	(arc
		(start 99.609656 -214.946992)
		(mid 99.408374 -215.144479)
		(end 99.327462 -215.414606)
		(width 0.0889)
		(layer "In13.Cu")
		(net "P5E_CPU1_PE0_RX_DP<12>")
	)
	(arc
		(start 100.0887 -220.000576)
		(mid 100.267297 -220.319854)
		(end 100.0887 -220.639132)
		(width 0.0889)
		(layer "In13.Cu")
		(net "P5E_CPU1_PE0_RX_DP<12>")
	)
	(arc
		(start 99.612958 -214.261954)
		(mid 99.722105 -214.345882)
		(end 99.797108 -214.461344)
		(width 0.0889)
		(layer "In13.Cu")
		(net "P5E_CPU1_PE0_RX_DP<12>")
	)
	(arc
		(start 100.07981 -217.388694)
		(mid 99.878528 -217.586181)
		(end 99.797616 -217.856308)
		(width 0.0889)
		(layer "In13.Cu")
		(net "P5E_CPU1_PE0_RX_DP<12>")
	)
	(arc
		(start 99.797108 -214.622634)
		(mid 99.749429 -214.805534)
		(end 99.618546 -214.941912)
		(width 0.0889)
		(layer "In13.Cu")
		(net "P5E_CPU1_PE0_RX_DP<12>")
	)
	(arc
		(start 100.07981 -221.623382)
		(mid 100.319223 -221.697714)
		(end 100.567236 -221.661228)
		(width 0.0889)
		(layer "In13.Cu")
		(net "P5E_CPU1_PE0_RX_DP<12>")
	)
	(arc
		(start 100.0887 -218.372944)
		(mid 100.267176 -218.692222)
		(end 100.0887 -219.0115)
		(width 0.0889)
		(layer "In13.Cu")
		(net "P5E_CPU1_PE0_RX_DP<12>")
	)
	(arc
		(start 99.797616 -221.149418)
		(mid 99.876986 -221.423152)
		(end 100.07981 -221.623382)
		(width 0.0889)
		(layer "In13.Cu")
		(net "P5E_CPU1_PE0_RX_DP<12>")
	)
	(arc
		(start 100.567236 -221.661228)
		(mid 100.57718 -221.657257)
		(end 100.587048 -221.6531)
		(width 0.0889)
		(layer "In13.Cu")
		(net "P5E_CPU1_PE0_RX_DP<12>")
	)
	(arc
		(start 99.327462 -215.436704)
		(mid 99.401453 -215.71627)
		(end 99.604068 -215.922606)
		(width 0.0889)
		(layer "In13.Cu")
		(net "P5E_CPU1_PE0_RX_DP<12>")
	)
	(arc
		(start 99.797616 -217.8939)
		(mid 99.876986 -218.167634)
		(end 100.07981 -218.367864)
		(width 0.0889)
		(layer "In13.Cu")
		(net "P5E_CPU1_PE0_RX_DP<12>")
	)
	(segment
		(start 99.892866 -220.855794)
		(end 99.892866 -220.320108)
		(width 0.13208)
		(layer "F.Cu")
		(net "P5E_CPU1_PE0_RX_DP<11>")
	)
	(segment
		(start 99.892866 -220.320108)
		(end 99.892612 -220.319854)
		(width 0.13208)
		(layer "F.Cu")
		(net "P5E_CPU1_PE0_RX_DP<11>")
	)
	(segment
		(start 62.059058 -404.4823)
		(end 62.059058 -400.327876)
		(width 0.14732)
		(layer "In13.Cu")
		(net "P5E_CPU1_PE0_RX_DP<11>")
	)
	(segment
		(start 98.765614 -215.112346)
		(end 98.764598 -215.112854)
		(width 0.0889)
		(layer "In13.Cu")
		(net "P5E_CPU1_PE0_RX_DP<11>")
	)
	(segment
		(start 98.62058 -213.151212)
		(end 98.578416 -213.193376)
		(width 0.0889)
		(layer "In13.Cu")
		(net "P5E_CPU1_PE0_RX_DP<11>")
	)
	(segment
		(start 75.436984 -216.653618)
		(end 79.007716 -212.052662)
		(width 0.14732)
		(layer "In13.Cu")
		(net "P5E_CPU1_PE0_RX_DP<11>")
	)
	(segment
		(start 98.62058 -211.934298)
		(end 98.62058 -213.140036)
		(width 0.14732)
		(layer "In13.Cu")
		(net "P5E_CPU1_PE0_RX_DP<11>")
	)
	(segment
		(start 90.01125 -203.162916)
		(end 91.704922 -203.864464)
		(width 0.14732)
		(layer "In13.Cu")
		(net "P5E_CPU1_PE0_RX_DP<11>")
	)
	(segment
		(start 98.756724 -215.755982)
		(end 98.76409 -215.7603)
		(width 0.0889)
		(layer "In13.Cu")
		(net "P5E_CPU1_PE0_RX_DP<11>")
	)
	(segment
		(start 99.235768 -217.554048)
		(end 99.226878 -217.559128)
		(width 0.0889)
		(layer "In13.Cu")
		(net "P5E_CPU1_PE0_RX_DP<11>")
	)
	(segment
		(start 98.764598 -215.112854)
		(end 98.756724 -215.117426)
		(width 0.0889)
		(layer "In13.Cu")
		(net "P5E_CPU1_PE0_RX_DP<11>")
	)
	(segment
		(start 79.007716 -212.052662)
		(end 86.526116 -203.898246)
		(width 0.14732)
		(layer "In13.Cu")
		(net "P5E_CPU1_PE0_RX_DP<11>")
	)
	(segment
		(start 66.502534 -437.59374)
		(end 66.057272 -437.59374)
		(width 0.14732)
		(layer "In13.Cu")
		(net "P5E_CPU1_PE0_RX_DP<11>")
	)
	(segment
		(start 62.059058 -400.327876)
		(end 62.423548 -397.405352)
		(width 0.14732)
		(layer "In13.Cu")
		(net "P5E_CPU1_PE0_RX_DP<11>")
	)
	(segment
		(start 70.491096 -250.085352)
		(end 71.896224 -232.723944)
		(width 0.14732)
		(layer "In13.Cu")
		(net "P5E_CPU1_PE0_RX_DP<11>")
	)
	(segment
		(start 99.65817 -220.6117)
		(end 99.736148 -220.590872)
		(width 0.0889)
		(layer "In13.Cu")
		(net "P5E_CPU1_PE0_RX_DP<11>")
	)
	(segment
		(start 62.423548 -397.405352)
		(end 63.278004 -381.183388)
		(width 0.14732)
		(layer "In13.Cu")
		(net "P5E_CPU1_PE0_RX_DP<11>")
	)
	(segment
		(start 65.680844 -437.217312)
		(end 65.680844 -417.590478)
		(width 0.14732)
		(layer "In13.Cu")
		(net "P5E_CPU1_PE0_RX_DP<11>")
	)
	(segment
		(start 60.342018 -406.19934)
		(end 62.059058 -404.4823)
		(width 0.14732)
		(layer "In13.Cu")
		(net "P5E_CPU1_PE0_RX_DP<11>")
	)
	(segment
		(start 60.342018 -410.863288)
		(end 60.342018 -406.19934)
		(width 0.14732)
		(layer "In13.Cu")
		(net "P5E_CPU1_PE0_RX_DP<11>")
	)
	(segment
		(start 98.578416 -213.193376)
		(end 98.578416 -213.893908)
		(width 0.0889)
		(layer "In13.Cu")
		(net "P5E_CPU1_PE0_RX_DP<11>")
	)
	(segment
		(start 99.226878 -219.825316)
		(end 99.235768 -219.830396)
		(width 0.0889)
		(layer "In13.Cu")
		(net "P5E_CPU1_PE0_RX_DP<11>")
	)
	(segment
		(start 87.949278 -203.162916)
		(end 90.01125 -203.162916)
		(width 0.14732)
		(layer "In13.Cu")
		(net "P5E_CPU1_PE0_RX_DP<11>")
	)
	(segment
		(start 99.518216 -217.05443)
		(end 99.518216 -217.082878)
		(width 0.0889)
		(layer "In13.Cu")
		(net "P5E_CPU1_PE0_RX_DP<11>")
	)
	(segment
		(start 71.897748 -232.714292)
		(end 73.931526 -219.555568)
		(width 0.14732)
		(layer "In13.Cu")
		(net "P5E_CPU1_PE0_RX_DP<11>")
	)
	(segment
		(start 70.343776 -317.692024)
		(end 73.94702 -309.014114)
		(width 0.14732)
		(layer "In13.Cu")
		(net "P5E_CPU1_PE0_RX_DP<11>")
	)
	(segment
		(start 99.047808 -214.424768)
		(end 99.047808 -214.644732)
		(width 0.0889)
		(layer "In13.Cu")
		(net "P5E_CPU1_PE0_RX_DP<11>")
	)
	(segment
		(start 65.680844 -417.590478)
		(end 64.882014 -416.395154)
		(width 0.14732)
		(layer "In13.Cu")
		(net "P5E_CPU1_PE0_RX_DP<11>")
	)
	(segment
		(start 99.517962 -218.676728)
		(end 99.517962 -218.707716)
		(width 0.0889)
		(layer "In13.Cu")
		(net "P5E_CPU1_PE0_RX_DP<11>")
	)
	(segment
		(start 99.736148 -220.590872)
		(end 99.892612 -220.319854)
		(width 0.0889)
		(layer "In13.Cu")
		(net "P5E_CPU1_PE0_RX_DP<11>")
	)
	(segment
		(start 86.526116 -203.898246)
		(end 87.949278 -203.162916)
		(width 0.14732)
		(layer "In13.Cu")
		(net "P5E_CPU1_PE0_RX_DP<11>")
	)
	(segment
		(start 98.62058 -213.140036)
		(end 98.62058 -213.151212)
		(width 0.0889)
		(layer "In13.Cu")
		(net "P5E_CPU1_PE0_RX_DP<11>")
	)
	(segment
		(start 64.379602 -329.887072)
		(end 68.109338 -320.882518)
		(width 0.14732)
		(layer "In13.Cu")
		(net "P5E_CPU1_PE0_RX_DP<11>")
	)
	(segment
		(start 98.76409 -215.7603)
		(end 98.765614 -215.761062)
		(width 0.0889)
		(layer "In13.Cu")
		(net "P5E_CPU1_PE0_RX_DP<11>")
	)
	(segment
		(start 98.765614 -215.761062)
		(end 98.768408 -215.762586)
		(width 0.0889)
		(layer "In13.Cu")
		(net "P5E_CPU1_PE0_RX_DP<11>")
	)
	(segment
		(start 70.381622 -253.334774)
		(end 70.491096 -250.085352)
		(width 0.14732)
		(layer "In13.Cu")
		(net "P5E_CPU1_PE0_RX_DP<11>")
	)
	(segment
		(start 66.650108 -438.089802)
		(end 66.650108 -437.741314)
		(width 0.14732)
		(layer "In13.Cu")
		(net "P5E_CPU1_PE0_RX_DP<11>")
	)
	(segment
		(start 73.931526 -219.555568)
		(end 75.436984 -216.653618)
		(width 0.14732)
		(layer "In13.Cu")
		(net "P5E_CPU1_PE0_RX_DP<11>")
	)
	(segment
		(start 66.057272 -437.59374)
		(end 65.680844 -437.217312)
		(width 0.14732)
		(layer "In13.Cu")
		(net "P5E_CPU1_PE0_RX_DP<11>")
	)
	(segment
		(start 66.650108 -437.741314)
		(end 66.502534 -437.59374)
		(width 0.14732)
		(layer "In13.Cu")
		(net "P5E_CPU1_PE0_RX_DP<11>")
	)
	(segment
		(start 63.278004 -381.183388)
		(end 63.42634 -352.489262)
		(width 0.14732)
		(layer "In13.Cu")
		(net "P5E_CPU1_PE0_RX_DP<11>")
	)
	(segment
		(start 71.896224 -232.723944)
		(end 71.897748 -232.714292)
		(width 0.14732)
		(layer "In13.Cu")
		(net "P5E_CPU1_PE0_RX_DP<11>")
	)
	(segment
		(start 99.226878 -216.569798)
		(end 99.235768 -216.574878)
		(width 0.0889)
		(layer "In13.Cu")
		(net "P5E_CPU1_PE0_RX_DP<11>")
	)
	(segment
		(start 99.234752 -219.182188)
		(end 99.226878 -219.18676)
		(width 0.0889)
		(layer "In13.Cu")
		(net "P5E_CPU1_PE0_RX_DP<11>")
	)
	(segment
		(start 63.42634 -352.489262)
		(end 64.379602 -343.278714)
		(width 0.14732)
		(layer "In13.Cu")
		(net "P5E_CPU1_PE0_RX_DP<11>")
	)
	(segment
		(start 99.226878 -218.197684)
		(end 99.235768 -218.202764)
		(width 0.0889)
		(layer "In13.Cu")
		(net "P5E_CPU1_PE0_RX_DP<11>")
	)
	(segment
		(start 97.804732 -209.964274)
		(end 98.62058 -211.934298)
		(width 0.14732)
		(layer "In13.Cu")
		(net "P5E_CPU1_PE0_RX_DP<11>")
	)
	(segment
		(start 99.518216 -220.309948)
		(end 99.518216 -220.32849)
		(width 0.0889)
		(layer "In13.Cu")
		(net "P5E_CPU1_PE0_RX_DP<11>")
	)
	(segment
		(start 64.882014 -416.395154)
		(end 60.342018 -410.863288)
		(width 0.14732)
		(layer "In13.Cu")
		(net "P5E_CPU1_PE0_RX_DP<11>")
	)
	(segment
		(start 64.379602 -343.278714)
		(end 64.379602 -329.887072)
		(width 0.14732)
		(layer "In13.Cu")
		(net "P5E_CPU1_PE0_RX_DP<11>")
	)
	(segment
		(start 98.768408 -215.762586)
		(end 98.77171 -215.764618)
		(width 0.0889)
		(layer "In13.Cu")
		(net "P5E_CPU1_PE0_RX_DP<11>")
	)
	(segment
		(start 73.94702 -309.014114)
		(end 70.381622 -253.334774)
		(width 0.14732)
		(layer "In13.Cu")
		(net "P5E_CPU1_PE0_RX_DP<11>")
	)
	(segment
		(start 68.109338 -320.882518)
		(end 70.343776 -317.692024)
		(width 0.14732)
		(layer "In13.Cu")
		(net "P5E_CPU1_PE0_RX_DP<11>")
	)
	(segment
		(start 99.235768 -219.18168)
		(end 99.234752 -219.182188)
		(width 0.0889)
		(layer "In13.Cu")
		(net "P5E_CPU1_PE0_RX_DP<11>")
	)
	(segment
		(start 91.704922 -203.864464)
		(end 97.804732 -209.964274)
		(width 0.14732)
		(layer "In13.Cu")
		(net "P5E_CPU1_PE0_RX_DP<11>")
	)
	(arc
		(start 99.226878 -217.559128)
		(mid 99.098985 -217.69019)
		(end 99.04857 -217.866214)
		(width 0.0889)
		(layer "In13.Cu")
		(net "P5E_CPU1_PE0_RX_DP<11>")
	)
	(arc
		(start 99.517962 -218.707716)
		(mid 99.438592 -218.98145)
		(end 99.235768 -219.18168)
		(width 0.0889)
		(layer "In13.Cu")
		(net "P5E_CPU1_PE0_RX_DP<11>")
	)
	(arc
		(start 98.578416 -215.421972)
		(mid 98.578219 -215.429337)
		(end 98.578162 -215.436704)
		(width 0.0889)
		(layer "In13.Cu")
		(net "P5E_CPU1_PE0_RX_DP<11>")
	)
	(arc
		(start 99.048316 -219.495878)
		(mid 99.048222 -219.50426)
		(end 99.048316 -219.512642)
		(width 0.0889)
		(layer "In13.Cu")
		(net "P5E_CPU1_PE0_RX_DP<11>")
	)
	(arc
		(start 98.578162 -215.436704)
		(mid 98.625841 -215.619604)
		(end 98.756724 -215.755982)
		(width 0.0889)
		(layer "In13.Cu")
		(net "P5E_CPU1_PE0_RX_DP<11>")
	)
	(arc
		(start 99.518216 -220.32849)
		(mid 99.55689 -220.485558)
		(end 99.65817 -220.6117)
		(width 0.0889)
		(layer "In13.Cu")
		(net "P5E_CPU1_PE0_RX_DP<11>")
	)
	(arc
		(start 99.04857 -217.866214)
		(mid 99.048403 -217.87739)
		(end 99.04857 -217.888566)
		(width 0.0889)
		(layer "In13.Cu")
		(net "P5E_CPU1_PE0_RX_DP<11>")
	)
	(arc
		(start 99.235768 -216.574878)
		(mid 99.440103 -216.777483)
		(end 99.518216 -217.05443)
		(width 0.0889)
		(layer "In13.Cu")
		(net "P5E_CPU1_PE0_RX_DP<11>")
	)
	(arc
		(start 98.578416 -213.893908)
		(mid 98.653421 -214.009367)
		(end 98.762566 -214.093298)
		(width 0.0889)
		(layer "In13.Cu")
		(net "P5E_CPU1_PE0_RX_DP<11>")
	)
	(arc
		(start 99.048316 -216.25052)
		(mid 99.095995 -216.43342)
		(end 99.226878 -216.569798)
		(width 0.0889)
		(layer "In13.Cu")
		(net "P5E_CPU1_PE0_RX_DP<11>")
	)
	(arc
		(start 98.756724 -215.117426)
		(mid 98.62947 -215.247392)
		(end 98.578416 -215.421972)
		(width 0.0889)
		(layer "In13.Cu")
		(net "P5E_CPU1_PE0_RX_DP<11>")
	)
	(arc
		(start 99.04857 -217.888566)
		(mid 99.098585 -218.065697)
		(end 99.226878 -218.197684)
		(width 0.0889)
		(layer "In13.Cu")
		(net "P5E_CPU1_PE0_RX_DP<11>")
	)
	(arc
		(start 99.047808 -214.644732)
		(mid 98.966897 -214.91486)
		(end 98.765614 -215.112346)
		(width 0.0889)
		(layer "In13.Cu")
		(net "P5E_CPU1_PE0_RX_DP<11>")
	)
	(arc
		(start 98.77171 -215.764618)
		(mid 98.974297 -215.970969)
		(end 99.048316 -216.25052)
		(width 0.0889)
		(layer "In13.Cu")
		(net "P5E_CPU1_PE0_RX_DP<11>")
	)
	(arc
		(start 99.048316 -219.512642)
		(mid 99.097569 -219.691842)
		(end 99.226878 -219.825316)
		(width 0.0889)
		(layer "In13.Cu")
		(net "P5E_CPU1_PE0_RX_DP<11>")
	)
	(arc
		(start 99.235768 -218.202764)
		(mid 99.438591 -218.402995)
		(end 99.517962 -218.676728)
		(width 0.0889)
		(layer "In13.Cu")
		(net "P5E_CPU1_PE0_RX_DP<11>")
	)
	(arc
		(start 99.235768 -219.830396)
		(mid 99.440103 -220.033001)
		(end 99.518216 -220.309948)
		(width 0.0889)
		(layer "In13.Cu")
		(net "P5E_CPU1_PE0_RX_DP<11>")
	)
	(arc
		(start 99.518216 -217.082878)
		(mid 99.438054 -217.355067)
		(end 99.235768 -217.554048)
		(width 0.0889)
		(layer "In13.Cu")
		(net "P5E_CPU1_PE0_RX_DP<11>")
	)
	(arc
		(start 99.226878 -219.18676)
		(mid 99.098474 -219.318705)
		(end 99.048316 -219.495878)
		(width 0.0889)
		(layer "In13.Cu")
		(net "P5E_CPU1_PE0_RX_DP<11>")
	)
	(arc
		(start 98.762566 -214.093298)
		(mid 98.936529 -214.232062)
		(end 99.047808 -214.424768)
		(width 0.0889)
		(layer "In13.Cu")
		(net "P5E_CPU1_PE0_RX_DP<11>")
	)
	(segment
		(start 98.952812 -222.483426)
		(end 98.952812 -221.94774)
		(width 0.13208)
		(layer "F.Cu")
		(net "P5E_CPU1_PE0_RX_DP<10>")
	)
	(segment
		(start 98.953066 -222.48368)
		(end 98.952812 -222.483426)
		(width 0.13208)
		(layer "F.Cu")
		(net "P5E_CPU1_PE0_RX_DP<10>")
	)
	(segment
		(start 65.387728 -383.058416)
		(end 65.381886 -382.62179)
		(width 0.14732)
		(layer "In13.Cu")
		(net "P5E_CPU1_PE0_RX_DP<10>")
	)
	(segment
		(start 88.80348 -208.949036)
		(end 94.04985 -208.949036)
		(width 0.14732)
		(layer "In13.Cu")
		(net "P5E_CPU1_PE0_RX_DP<10>")
	)
	(segment
		(start 65.396618 -404.596092)
		(end 65.396618 -399.986246)
		(width 0.14732)
		(layer "In13.Cu")
		(net "P5E_CPU1_PE0_RX_DP<10>")
	)
	(segment
		(start 65.535302 -384.741166)
		(end 65.529206 -384.304032)
		(width 0.14732)
		(layer "In13.Cu")
		(net "P5E_CPU1_PE0_RX_DP<10>")
	)
	(segment
		(start 68.482972 -438.319418)
		(end 68.07962 -438.319418)
		(width 0.14732)
		(layer "In13.Cu")
		(net "P5E_CPU1_PE0_RX_DP<10>")
	)
	(segment
		(start 97.73285 -214.945214)
		(end 97.732088 -214.945722)
		(width 0.0889)
		(layer "In13.Cu")
		(net "P5E_CPU1_PE0_RX_DP<10>")
	)
	(segment
		(start 98.201226 -219.996004)
		(end 98.2091 -220.000576)
		(width 0.0889)
		(layer "In13.Cu")
		(net "P5E_CPU1_PE0_RX_DP<10>")
	)
	(segment
		(start 87.622888 -209.432144)
		(end 87.704422 -209.279998)
		(width 0.14732)
		(layer "In13.Cu")
		(net "P5E_CPU1_PE0_RX_DP<10>")
	)
	(segment
		(start 71.69912 -250.144788)
		(end 73.116694 -232.863644)
		(width 0.14732)
		(layer "In13.Cu")
		(net "P5E_CPU1_PE0_RX_DP<10>")
	)
	(segment
		(start 97.918016 -219.490544)
		(end 97.918016 -219.521532)
		(width 0.0889)
		(layer "In13.Cu")
		(net "P5E_CPU1_PE0_RX_DP<10>")
	)
	(segment
		(start 63.679578 -406.313132)
		(end 65.396618 -404.596092)
		(width 0.14732)
		(layer "In13.Cu")
		(net "P5E_CPU1_PE0_RX_DP<10>")
	)
	(segment
		(start 65.412366 -384.86715)
		(end 65.535302 -384.741166)
		(width 0.14732)
		(layer "In13.Cu")
		(net "P5E_CPU1_PE0_RX_DP<10>")
	)
	(segment
		(start 97.917508 -214.461344)
		(end 97.917508 -214.622634)
		(width 0.0889)
		(layer "In13.Cu")
		(net "P5E_CPU1_PE0_RX_DP<10>")
	)
	(segment
		(start 85.563964 -209.924396)
		(end 85.982048 -209.798666)
		(width 0.14732)
		(layer "In13.Cu")
		(net "P5E_CPU1_PE0_RX_DP<10>")
	)
	(segment
		(start 98.2091 -220.639132)
		(end 98.20021 -220.644212)
		(width 0.0889)
		(layer "In13.Cu")
		(net "P5E_CPU1_PE0_RX_DP<10>")
	)
	(segment
		(start 65.448688 -387.549136)
		(end 65.442846 -387.11251)
		(width 0.14732)
		(layer "In13.Cu")
		(net "P5E_CPU1_PE0_RX_DP<10>")
	)
	(segment
		(start 67.95516 -438.194958)
		(end 67.95516 -416.79749)
		(width 0.14732)
		(layer "In13.Cu")
		(net "P5E_CPU1_PE0_RX_DP<10>")
	)
	(segment
		(start 97.406206 -212.969348)
		(end 97.405952 -212.969602)
		(width 0.14732)
		(layer "In13.Cu")
		(net "P5E_CPU1_PE0_RX_DP<10>")
	)
	(segment
		(start 71.506334 -318.311276)
		(end 75.211178 -309.414926)
		(width 0.14732)
		(layer "In13.Cu")
		(net "P5E_CPU1_PE0_RX_DP<10>")
	)
	(segment
		(start 75.12685 -219.916248)
		(end 76.49972 -217.25128)
		(width 0.14732)
		(layer "In13.Cu")
		(net "P5E_CPU1_PE0_RX_DP<10>")
	)
	(segment
		(start 65.396618 -399.986246)
		(end 65.583562 -397.550132)
		(width 0.14732)
		(layer "In13.Cu")
		(net "P5E_CPU1_PE0_RX_DP<10>")
	)
	(segment
		(start 97.448116 -213.200234)
		(end 97.448116 -213.930484)
		(width 0.0889)
		(layer "In13.Cu")
		(net "P5E_CPU1_PE0_RX_DP<10>")
	)
	(segment
		(start 65.583562 -397.550132)
		(end 65.458086 -388.23519)
		(width 0.14732)
		(layer "In13.Cu")
		(net "P5E_CPU1_PE0_RX_DP<10>")
	)
	(segment
		(start 63.679578 -410.671264)
		(end 63.679578 -406.313132)
		(width 0.14732)
		(layer "In13.Cu")
		(net "P5E_CPU1_PE0_RX_DP<10>")
	)
	(segment
		(start 65.427606 -385.98983)
		(end 65.550288 -385.863846)
		(width 0.14732)
		(layer "In13.Cu")
		(net "P5E_CPU1_PE0_RX_DP<10>")
	)
	(segment
		(start 97.918016 -221.111826)
		(end 97.918016 -221.149418)
		(width 0.0889)
		(layer "In13.Cu")
		(net "P5E_CPU1_PE0_RX_DP<10>")
	)
	(segment
		(start 85.482176 -210.076542)
		(end 85.563964 -209.924396)
		(width 0.14732)
		(layer "In13.Cu")
		(net "P5E_CPU1_PE0_RX_DP<10>")
	)
	(segment
		(start 75.211178 -309.414926)
		(end 71.616316 -252.60935)
		(width 0.14732)
		(layer "In13.Cu")
		(net "P5E_CPU1_PE0_RX_DP<10>")
	)
	(segment
		(start 98.796348 -221.676722)
		(end 98.952812 -221.94774)
		(width 0.0889)
		(layer "In13.Cu")
		(net "P5E_CPU1_PE0_RX_DP<10>")
	)
	(segment
		(start 86.13394 -209.8802)
		(end 86.552532 -209.754216)
		(width 0.14732)
		(layer "In13.Cu")
		(net "P5E_CPU1_PE0_RX_DP<10>")
	)
	(segment
		(start 87.204296 -209.558128)
		(end 87.622888 -209.432144)
		(width 0.14732)
		(layer "In13.Cu")
		(net "P5E_CPU1_PE0_RX_DP<10>")
	)
	(segment
		(start 65.442846 -387.11251)
		(end 65.565528 -386.986526)
		(width 0.14732)
		(layer "In13.Cu")
		(net "P5E_CPU1_PE0_RX_DP<10>")
	)
	(segment
		(start 97.732088 -214.945722)
		(end 97.730056 -214.946992)
		(width 0.0889)
		(layer "In13.Cu")
		(net "P5E_CPU1_PE0_RX_DP<10>")
	)
	(segment
		(start 65.513966 -383.181352)
		(end 65.387728 -383.058416)
		(width 0.14732)
		(layer "In13.Cu")
		(net "P5E_CPU1_PE0_RX_DP<10>")
	)
	(segment
		(start 96.743266 -210.609688)
		(end 97.406206 -212.210142)
		(width 0.14732)
		(layer "In13.Cu")
		(net "P5E_CPU1_PE0_RX_DP<10>")
	)
	(segment
		(start 65.520062 -383.618486)
		(end 65.513966 -383.181352)
		(width 0.14732)
		(layer "In13.Cu")
		(net "P5E_CPU1_PE0_RX_DP<10>")
	)
	(segment
		(start 68.996306 -321.89547)
		(end 71.506334 -318.311276)
		(width 0.14732)
		(layer "In13.Cu")
		(net "P5E_CPU1_PE0_RX_DP<10>")
	)
	(segment
		(start 65.580768 -388.109206)
		(end 65.574926 -387.672072)
		(width 0.14732)
		(layer "In13.Cu")
		(net "P5E_CPU1_PE0_RX_DP<10>")
	)
	(segment
		(start 98.20021 -219.995496)
		(end 98.201226 -219.996004)
		(width 0.0889)
		(layer "In13.Cu")
		(net "P5E_CPU1_PE0_RX_DP<10>")
	)
	(segment
		(start 87.052404 -209.47634)
		(end 87.204296 -209.558128)
		(width 0.14732)
		(layer "In13.Cu")
		(net "P5E_CPU1_PE0_RX_DP<10>")
	)
	(segment
		(start 85.982048 -209.798666)
		(end 86.13394 -209.8802)
		(width 0.14732)
		(layer "In13.Cu")
		(net "P5E_CPU1_PE0_RX_DP<10>")
	)
	(segment
		(start 65.397126 -383.74447)
		(end 65.520062 -383.618486)
		(width 0.14732)
		(layer "In13.Cu")
		(net "P5E_CPU1_PE0_RX_DP<10>")
	)
	(segment
		(start 71.616316 -252.60935)
		(end 71.616316 -252.606556)
		(width 0.14732)
		(layer "In13.Cu")
		(net "P5E_CPU1_PE0_RX_DP<10>")
	)
	(segment
		(start 97.724468 -215.922606)
		(end 97.739454 -215.931242)
		(width 0.0889)
		(layer "In13.Cu")
		(net "P5E_CPU1_PE0_RX_DP<10>")
	)
	(segment
		(start 68.07962 -438.319418)
		(end 67.95516 -438.194958)
		(width 0.14732)
		(layer "In13.Cu")
		(net "P5E_CPU1_PE0_RX_DP<10>")
	)
	(segment
		(start 65.402968 -384.181096)
		(end 65.397126 -383.74447)
		(width 0.14732)
		(layer "In13.Cu")
		(net "P5E_CPU1_PE0_RX_DP<10>")
	)
	(segment
		(start 98.20021 -218.367864)
		(end 98.201226 -218.368372)
		(width 0.0889)
		(layer "In13.Cu")
		(net "P5E_CPU1_PE0_RX_DP<10>")
	)
	(segment
		(start 98.201226 -216.740486)
		(end 98.2091 -216.745058)
		(width 0.0889)
		(layer "In13.Cu")
		(net "P5E_CPU1_PE0_RX_DP<10>")
	)
	(segment
		(start 68.650104 -437.889904)
		(end 68.650104 -438.152286)
		(width 0.14732)
		(layer "In13.Cu")
		(net "P5E_CPU1_PE0_RX_DP<10>")
	)
	(segment
		(start 98.2091 -219.0115)
		(end 98.20021 -219.01658)
		(width 0.0889)
		(layer "In13.Cu")
		(net "P5E_CPU1_PE0_RX_DP<10>")
	)
	(segment
		(start 65.544446 -385.426712)
		(end 65.418208 -385.303776)
		(width 0.14732)
		(layer "In13.Cu")
		(net "P5E_CPU1_PE0_RX_DP<10>")
	)
	(segment
		(start 65.591436 -330.114402)
		(end 68.996306 -321.89547)
		(width 0.14732)
		(layer "In13.Cu")
		(net "P5E_CPU1_PE0_RX_DP<10>")
	)
	(segment
		(start 98.2091 -217.383614)
		(end 98.20021 -217.388694)
		(width 0.0889)
		(layer "In13.Cu")
		(net "P5E_CPU1_PE0_RX_DP<10>")
	)
	(segment
		(start 85.063584 -210.202526)
		(end 85.482176 -210.076542)
		(width 0.14732)
		(layer "In13.Cu")
		(net "P5E_CPU1_PE0_RX_DP<10>")
	)
	(segment
		(start 86.63432 -209.60207)
		(end 87.052404 -209.47634)
		(width 0.14732)
		(layer "In13.Cu")
		(net "P5E_CPU1_PE0_RX_DP<10>")
	)
	(segment
		(start 82.27822 -210.91398)
		(end 84.911692 -210.120992)
		(width 0.14732)
		(layer "In13.Cu")
		(net "P5E_CPU1_PE0_RX_DP<10>")
	)
	(segment
		(start 97.918016 -217.856308)
		(end 97.918016 -217.8939)
		(width 0.0889)
		(layer "In13.Cu")
		(net "P5E_CPU1_PE0_RX_DP<10>")
	)
	(segment
		(start 94.04985 -208.949036)
		(end 95.813118 -209.67954)
		(width 0.14732)
		(layer "In13.Cu")
		(net "P5E_CPU1_PE0_RX_DP<10>")
	)
	(segment
		(start 65.504568 -382.495552)
		(end 65.498726 -382.058418)
		(width 0.14732)
		(layer "In13.Cu")
		(net "P5E_CPU1_PE0_RX_DP<10>")
	)
	(segment
		(start 73.116694 -232.863644)
		(end 75.12685 -219.916248)
		(width 0.14732)
		(layer "In13.Cu")
		(net "P5E_CPU1_PE0_RX_DP<10>")
	)
	(segment
		(start 76.49972 -217.25128)
		(end 79.935578 -212.834728)
		(width 0.14732)
		(layer "In13.Cu")
		(net "P5E_CPU1_PE0_RX_DP<10>")
	)
	(segment
		(start 65.372488 -381.935736)
		(end 64.944498 -350.266508)
		(width 0.14732)
		(layer "In13.Cu")
		(net "P5E_CPU1_PE0_RX_DP<10>")
	)
	(segment
		(start 65.458086 -388.23519)
		(end 65.580768 -388.109206)
		(width 0.14732)
		(layer "In13.Cu")
		(net "P5E_CPU1_PE0_RX_DP<10>")
	)
	(segment
		(start 97.738946 -214.941912)
		(end 97.734374 -214.944452)
		(width 0.0889)
		(layer "In13.Cu")
		(net "P5E_CPU1_PE0_RX_DP<10>")
	)
	(segment
		(start 79.935578 -212.834728)
		(end 82.27822 -210.91398)
		(width 0.14732)
		(layer "In13.Cu")
		(net "P5E_CPU1_PE0_RX_DP<10>")
	)
	(segment
		(start 65.559686 -386.549392)
		(end 65.433448 -386.426456)
		(width 0.14732)
		(layer "In13.Cu")
		(net "P5E_CPU1_PE0_RX_DP<10>")
	)
	(segment
		(start 95.813118 -209.67954)
		(end 96.743266 -210.609688)
		(width 0.14732)
		(layer "In13.Cu")
		(net "P5E_CPU1_PE0_RX_DP<10>")
	)
	(segment
		(start 65.550288 -385.863846)
		(end 65.544446 -385.426712)
		(width 0.14732)
		(layer "In13.Cu")
		(net "P5E_CPU1_PE0_RX_DP<10>")
	)
	(segment
		(start 65.433448 -386.426456)
		(end 65.427606 -385.98983)
		(width 0.14732)
		(layer "In13.Cu")
		(net "P5E_CPU1_PE0_RX_DP<10>")
	)
	(segment
		(start 97.918016 -216.25052)
		(end 97.918016 -216.266014)
		(width 0.0889)
		(layer "In13.Cu")
		(net "P5E_CPU1_PE0_RX_DP<10>")
	)
	(segment
		(start 65.591436 -343.41054)
		(end 65.591436 -330.114402)
		(width 0.14732)
		(layer "In13.Cu")
		(net "P5E_CPU1_PE0_RX_DP<10>")
	)
	(segment
		(start 98.20021 -216.739978)
		(end 98.201226 -216.740486)
		(width 0.0889)
		(layer "In13.Cu")
		(net "P5E_CPU1_PE0_RX_DP<10>")
	)
	(segment
		(start 65.529206 -384.304032)
		(end 65.402968 -384.181096)
		(width 0.14732)
		(layer "In13.Cu")
		(net "P5E_CPU1_PE0_RX_DP<10>")
	)
	(segment
		(start 65.574926 -387.672072)
		(end 65.448688 -387.549136)
		(width 0.14732)
		(layer "In13.Cu")
		(net "P5E_CPU1_PE0_RX_DP<10>")
	)
	(segment
		(start 65.418208 -385.303776)
		(end 65.412366 -384.86715)
		(width 0.14732)
		(layer "In13.Cu")
		(net "P5E_CPU1_PE0_RX_DP<10>")
	)
	(segment
		(start 65.498726 -382.058418)
		(end 65.372488 -381.935736)
		(width 0.14732)
		(layer "In13.Cu")
		(net "P5E_CPU1_PE0_RX_DP<10>")
	)
	(segment
		(start 87.704422 -209.279998)
		(end 88.80348 -208.949036)
		(width 0.14732)
		(layer "In13.Cu")
		(net "P5E_CPU1_PE0_RX_DP<10>")
	)
	(segment
		(start 68.650104 -438.152286)
		(end 68.482972 -438.319418)
		(width 0.14732)
		(layer "In13.Cu")
		(net "P5E_CPU1_PE0_RX_DP<10>")
	)
	(segment
		(start 98.707448 -221.6531)
		(end 98.796348 -221.676722)
		(width 0.0889)
		(layer "In13.Cu")
		(net "P5E_CPU1_PE0_RX_DP<10>")
	)
	(segment
		(start 97.734374 -214.944452)
		(end 97.73285 -214.945214)
		(width 0.0889)
		(layer "In13.Cu")
		(net "P5E_CPU1_PE0_RX_DP<10>")
	)
	(segment
		(start 97.405952 -213.135972)
		(end 97.405952 -213.15807)
		(width 0.0889)
		(layer "In13.Cu")
		(net "P5E_CPU1_PE0_RX_DP<10>")
	)
	(segment
		(start 64.944498 -350.266508)
		(end 65.591436 -343.41054)
		(width 0.14732)
		(layer "In13.Cu")
		(net "P5E_CPU1_PE0_RX_DP<10>")
	)
	(segment
		(start 65.381886 -382.62179)
		(end 65.504568 -382.495552)
		(width 0.14732)
		(layer "In13.Cu")
		(net "P5E_CPU1_PE0_RX_DP<10>")
	)
	(segment
		(start 97.405952 -213.15807)
		(end 97.448116 -213.200234)
		(width 0.0889)
		(layer "In13.Cu")
		(net "P5E_CPU1_PE0_RX_DP<10>")
	)
	(segment
		(start 98.201226 -218.368372)
		(end 98.2091 -218.372944)
		(width 0.0889)
		(layer "In13.Cu")
		(net "P5E_CPU1_PE0_RX_DP<10>")
	)
	(segment
		(start 97.405952 -212.969602)
		(end 97.405952 -213.135972)
		(width 0.14732)
		(layer "In13.Cu")
		(net "P5E_CPU1_PE0_RX_DP<10>")
	)
	(segment
		(start 86.552532 -209.754216)
		(end 86.63432 -209.60207)
		(width 0.14732)
		(layer "In13.Cu")
		(net "P5E_CPU1_PE0_RX_DP<10>")
	)
	(segment
		(start 84.911692 -210.120992)
		(end 85.063584 -210.202526)
		(width 0.14732)
		(layer "In13.Cu")
		(net "P5E_CPU1_PE0_RX_DP<10>")
	)
	(segment
		(start 65.565528 -386.986526)
		(end 65.559686 -386.549392)
		(width 0.14732)
		(layer "In13.Cu")
		(net "P5E_CPU1_PE0_RX_DP<10>")
	)
	(segment
		(start 97.406206 -212.210142)
		(end 97.406206 -212.969348)
		(width 0.14732)
		(layer "In13.Cu")
		(net "P5E_CPU1_PE0_RX_DP<10>")
	)
	(segment
		(start 67.95516 -416.79749)
		(end 63.679578 -410.671264)
		(width 0.14732)
		(layer "In13.Cu")
		(net "P5E_CPU1_PE0_RX_DP<10>")
	)
	(segment
		(start 71.616316 -252.606556)
		(end 71.69912 -250.144788)
		(width 0.14732)
		(layer "In13.Cu")
		(net "P5E_CPU1_PE0_RX_DP<10>")
	)
	(arc
		(start 98.20021 -217.388694)
		(mid 97.998928 -217.586181)
		(end 97.918016 -217.856308)
		(width 0.0889)
		(layer "In13.Cu")
		(net "P5E_CPU1_PE0_RX_DP<10>")
	)
	(arc
		(start 98.2091 -218.372944)
		(mid 98.387576 -218.692222)
		(end 98.2091 -219.0115)
		(width 0.0889)
		(layer "In13.Cu")
		(net "P5E_CPU1_PE0_RX_DP<10>")
	)
	(arc
		(start 97.918016 -216.266014)
		(mid 97.997386 -216.539748)
		(end 98.20021 -216.739978)
		(width 0.0889)
		(layer "In13.Cu")
		(net "P5E_CPU1_PE0_RX_DP<10>")
	)
	(arc
		(start 97.730056 -214.946992)
		(mid 97.447533 -215.433205)
		(end 97.724468 -215.922606)
		(width 0.0889)
		(layer "In13.Cu")
		(net "P5E_CPU1_PE0_RX_DP<10>")
	)
	(arc
		(start 97.739454 -215.931242)
		(mid 97.870368 -216.067602)
		(end 97.918016 -216.25052)
		(width 0.0889)
		(layer "In13.Cu")
		(net "P5E_CPU1_PE0_RX_DP<10>")
	)
	(arc
		(start 97.918016 -221.149418)
		(mid 97.997386 -221.423152)
		(end 98.20021 -221.623382)
		(width 0.0889)
		(layer "In13.Cu")
		(net "P5E_CPU1_PE0_RX_DP<10>")
	)
	(arc
		(start 98.20021 -220.644212)
		(mid 97.998928 -220.841699)
		(end 97.918016 -221.111826)
		(width 0.0889)
		(layer "In13.Cu")
		(net "P5E_CPU1_PE0_RX_DP<10>")
	)
	(arc
		(start 97.918016 -217.8939)
		(mid 97.997386 -218.167634)
		(end 98.20021 -218.367864)
		(width 0.0889)
		(layer "In13.Cu")
		(net "P5E_CPU1_PE0_RX_DP<10>")
	)
	(arc
		(start 98.687636 -221.661228)
		(mid 98.69758 -221.657257)
		(end 98.707448 -221.6531)
		(width 0.0889)
		(layer "In13.Cu")
		(net "P5E_CPU1_PE0_RX_DP<10>")
	)
	(arc
		(start 97.917508 -214.622634)
		(mid 97.869829 -214.805534)
		(end 97.738946 -214.941912)
		(width 0.0889)
		(layer "In13.Cu")
		(net "P5E_CPU1_PE0_RX_DP<10>")
	)
	(arc
		(start 98.2091 -216.745058)
		(mid 98.387697 -217.064336)
		(end 98.2091 -217.383614)
		(width 0.0889)
		(layer "In13.Cu")
		(net "P5E_CPU1_PE0_RX_DP<10>")
	)
	(arc
		(start 98.20021 -219.01658)
		(mid 97.997387 -219.216811)
		(end 97.918016 -219.490544)
		(width 0.0889)
		(layer "In13.Cu")
		(net "P5E_CPU1_PE0_RX_DP<10>")
	)
	(arc
		(start 98.2091 -220.000576)
		(mid 98.387697 -220.319854)
		(end 98.2091 -220.639132)
		(width 0.0889)
		(layer "In13.Cu")
		(net "P5E_CPU1_PE0_RX_DP<10>")
	)
	(arc
		(start 97.463356 -213.969346)
		(mid 97.57335 -214.138715)
		(end 97.733358 -214.261954)
		(width 0.0889)
		(layer "In13.Cu")
		(net "P5E_CPU1_PE0_RX_DP<10>")
	)
	(arc
		(start 98.20021 -221.623382)
		(mid 98.439623 -221.697714)
		(end 98.687636 -221.661228)
		(width 0.0889)
		(layer "In13.Cu")
		(net "P5E_CPU1_PE0_RX_DP<10>")
	)
	(arc
		(start 97.448116 -213.930484)
		(mid 97.455401 -213.950046)
		(end 97.463356 -213.969346)
		(width 0.0889)
		(layer "In13.Cu")
		(net "P5E_CPU1_PE0_RX_DP<10>")
	)
	(arc
		(start 97.918016 -219.521532)
		(mid 97.997386 -219.795266)
		(end 98.20021 -219.995496)
		(width 0.0889)
		(layer "In13.Cu")
		(net "P5E_CPU1_PE0_RX_DP<10>")
	)
	(arc
		(start 97.733358 -214.261954)
		(mid 97.842505 -214.345882)
		(end 97.917508 -214.461344)
		(width 0.0889)
		(layer "In13.Cu")
		(net "P5E_CPU1_PE0_RX_DP<10>")
	)
	(segment
		(start 89.555066 -221.947994)
		(end 89.554812 -221.94774)
		(width 0.13208)
		(layer "F.Cu")
		(net "P5E_CPU1_PE0_RX_DP<0>")
	)
	(segment
		(start 89.555066 -222.48368)
		(end 89.555066 -221.947994)
		(width 0.13208)
		(layer "F.Cu")
		(net "P5E_CPU1_PE0_RX_DP<0>")
	)
	(segment
		(start 91.938856 -389.180578)
		(end 91.869768 -389.34263)
		(width 0.14732)
		(layer "In13.Cu")
		(net "P5E_CPU1_PE0_RX_DP<0>")
	)
	(segment
		(start 85.891116 -227.64496)
		(end 85.891116 -228.225604)
		(width 0.0889)
		(layer "In13.Cu")
		(net "P5E_CPU1_PE0_RX_DP<0>")
	)
	(segment
		(start 90.098118 -384.608578)
		(end 90.26144 -385.013962)
		(width 0.14732)
		(layer "In13.Cu")
		(net "P5E_CPU1_PE0_RX_DP<0>")
	)
	(segment
		(start 90.35542 -385.581144)
		(end 90.517472 -385.650232)
		(width 0.14732)
		(layer "In13.Cu")
		(net "P5E_CPU1_PE0_RX_DP<0>")
	)
	(segment
		(start 84.48294 -256.791714)
		(end 83.160616 -260.166104)
		(width 0.14732)
		(layer "In13.Cu")
		(net "P5E_CPU1_PE0_RX_DP<0>")
	)
	(segment
		(start 75.438 -331.304646)
		(end 75.438 -346.387928)
		(width 0.14732)
		(layer "In13.Cu")
		(net "P5E_CPU1_PE0_RX_DP<0>")
	)
	(segment
		(start 89.48293 -438.319418)
		(end 89.650062 -438.152286)
		(width 0.14732)
		(layer "In13.Cu")
		(net "P5E_CPU1_PE0_RX_DP<0>")
	)
	(segment
		(start 89.936066 -384.53949)
		(end 90.098118 -384.608578)
		(width 0.14732)
		(layer "In13.Cu")
		(net "P5E_CPU1_PE0_RX_DP<0>")
	)
	(segment
		(start 77.085952 -327.326498)
		(end 75.438 -331.304646)
		(width 0.14732)
		(layer "In13.Cu")
		(net "P5E_CPU1_PE0_RX_DP<0>")
	)
	(segment
		(start 94.311978 -411.37078)
		(end 88.955118 -424.5737)
		(width 0.14732)
		(layer "In13.Cu")
		(net "P5E_CPU1_PE0_RX_DP<0>")
	)
	(segment
		(start 85.33384 -254.350774)
		(end 85.514688 -255.375918)
		(width 0.14732)
		(layer "In13.Cu")
		(net "P5E_CPU1_PE0_RX_DP<0>")
	)
	(segment
		(start 91.194128 -387.664452)
		(end 91.35618 -387.73354)
		(width 0.14732)
		(layer "In13.Cu")
		(net "P5E_CPU1_PE0_RX_DP<0>")
	)
	(segment
		(start 86.361016 -226.822508)
		(end 86.361016 -226.84105)
		(width 0.0889)
		(layer "In13.Cu")
		(net "P5E_CPU1_PE0_RX_DP<0>")
	)
	(segment
		(start 88.897968 -222.437198)
		(end 88.889078 -222.442278)
		(width 0.0889)
		(layer "In13.Cu")
		(net "P5E_CPU1_PE0_RX_DP<0>")
	)
	(segment
		(start 89.180416 -221.939104)
		(end 89.180416 -221.957646)
		(width 0.0889)
		(layer "In13.Cu")
		(net "P5E_CPU1_PE0_RX_DP<0>")
	)
	(segment
		(start 83.365848 -233.557064)
		(end 83.757516 -243.417852)
		(width 0.14732)
		(layer "In13.Cu")
		(net "P5E_CPU1_PE0_RX_DP<0>")
	)
	(segment
		(start 91.519502 -388.138924)
		(end 91.450414 -388.300976)
		(width 0.14732)
		(layer "In13.Cu")
		(net "P5E_CPU1_PE0_RX_DP<0>")
	)
	(segment
		(start 89.398348 -221.676722)
		(end 89.32037 -221.655894)
		(width 0.0889)
		(layer "In13.Cu")
		(net "P5E_CPU1_PE0_RX_DP<0>")
	)
	(segment
		(start 86.106508 -250.858782)
		(end 86.016592 -251.36983)
		(width 0.14732)
		(layer "In13.Cu")
		(net "P5E_CPU1_PE0_RX_DP<0>")
	)
	(segment
		(start 91.35618 -387.73354)
		(end 91.519502 -388.138924)
		(width 0.14732)
		(layer "In13.Cu")
		(net "P5E_CPU1_PE0_RX_DP<0>")
	)
	(segment
		(start 86.078568 -227.320602)
		(end 86.069678 -227.325682)
		(width 0.0889)
		(layer "In13.Cu")
		(net "P5E_CPU1_PE0_RX_DP<0>")
	)
	(segment
		(start 85.891116 -228.225604)
		(end 85.93328 -228.267768)
		(width 0.0889)
		(layer "In13.Cu")
		(net "P5E_CPU1_PE0_RX_DP<0>")
	)
	(segment
		(start 75.997816 -349.918274)
		(end 89.516712 -383.497836)
		(width 0.14732)
		(layer "In13.Cu")
		(net "P5E_CPU1_PE0_RX_DP<0>")
	)
	(segment
		(start 94.311978 -406.313132)
		(end 94.311978 -411.37078)
		(width 0.14732)
		(layer "In13.Cu")
		(net "P5E_CPU1_PE0_RX_DP<0>")
	)
	(segment
		(start 83.72475 -232.639616)
		(end 83.365848 -233.557064)
		(width 0.14732)
		(layer "In13.Cu")
		(net "P5E_CPU1_PE0_RX_DP<0>")
	)
	(segment
		(start 90.192352 -385.176014)
		(end 90.35542 -385.581144)
		(width 0.14732)
		(layer "In13.Cu")
		(net "P5E_CPU1_PE0_RX_DP<0>")
	)
	(segment
		(start 91.869768 -389.34263)
		(end 96.029018 -399.673826)
		(width 0.14732)
		(layer "In13.Cu")
		(net "P5E_CPU1_PE0_RX_DP<0>")
	)
	(segment
		(start 90.774774 -386.622798)
		(end 90.936826 -386.691886)
		(width 0.14732)
		(layer "In13.Cu")
		(net "P5E_CPU1_PE0_RX_DP<0>")
	)
	(segment
		(start 75.438 -346.387928)
		(end 75.997816 -349.918274)
		(width 0.14732)
		(layer "In13.Cu")
		(net "P5E_CPU1_PE0_RX_DP<0>")
	)
	(segment
		(start 91.450414 -388.300976)
		(end 91.613482 -388.706106)
		(width 0.14732)
		(layer "In13.Cu")
		(net "P5E_CPU1_PE0_RX_DP<0>")
	)
	(segment
		(start 90.936826 -386.691886)
		(end 91.100148 -387.09727)
		(width 0.14732)
		(layer "In13.Cu")
		(net "P5E_CPU1_PE0_RX_DP<0>")
	)
	(segment
		(start 88.955118 -424.5737)
		(end 88.955118 -438.194958)
		(width 0.14732)
		(layer "In13.Cu")
		(net "P5E_CPU1_PE0_RX_DP<0>")
	)
	(segment
		(start 90.611706 -386.217668)
		(end 90.774774 -386.622798)
		(width 0.14732)
		(layer "In13.Cu")
		(net "P5E_CPU1_PE0_RX_DP<0>")
	)
	(segment
		(start 87.300816 -225.203258)
		(end 87.300816 -225.217482)
		(width 0.0889)
		(layer "In13.Cu")
		(net "P5E_CPU1_PE0_RX_DP<0>")
	)
	(segment
		(start 85.514688 -255.375918)
		(end 85.243162 -256.031238)
		(width 0.14732)
		(layer "In13.Cu")
		(net "P5E_CPU1_PE0_RX_DP<0>")
	)
	(segment
		(start 86.830916 -226.008692)
		(end 86.830916 -226.017328)
		(width 0.0889)
		(layer "In13.Cu")
		(net "P5E_CPU1_PE0_RX_DP<0>")
	)
	(segment
		(start 88.955118 -438.194958)
		(end 89.079578 -438.319418)
		(width 0.14732)
		(layer "In13.Cu")
		(net "P5E_CPU1_PE0_RX_DP<0>")
	)
	(segment
		(start 85.778848 -247.810782)
		(end 85.778848 -249.169174)
		(width 0.14732)
		(layer "In13.Cu")
		(net "P5E_CPU1_PE0_RX_DP<0>")
	)
	(segment
		(start 85.93328 -228.289866)
		(end 85.93328 -228.687884)
		(width 0.14732)
		(layer "In13.Cu")
		(net "P5E_CPU1_PE0_RX_DP<0>")
	)
	(segment
		(start 96.029018 -399.673826)
		(end 96.029018 -404.596092)
		(width 0.14732)
		(layer "In13.Cu")
		(net "P5E_CPU1_PE0_RX_DP<0>")
	)
	(segment
		(start 91.100148 -387.09727)
		(end 91.03106 -387.259322)
		(width 0.14732)
		(layer "In13.Cu")
		(net "P5E_CPU1_PE0_RX_DP<0>")
	)
	(segment
		(start 86.016592 -251.36983)
		(end 85.437218 -252.197362)
		(width 0.14732)
		(layer "In13.Cu")
		(net "P5E_CPU1_PE0_RX_DP<0>")
	)
	(segment
		(start 89.650062 -438.152286)
		(end 89.650062 -437.889904)
		(width 0.14732)
		(layer "In13.Cu")
		(net "P5E_CPU1_PE0_RX_DP<0>")
	)
	(segment
		(start 90.680794 -386.055616)
		(end 90.611706 -386.217668)
		(width 0.14732)
		(layer "In13.Cu")
		(net "P5E_CPU1_PE0_RX_DP<0>")
	)
	(segment
		(start 89.678764 -383.566924)
		(end 89.842086 -383.972308)
		(width 0.14732)
		(layer "In13.Cu")
		(net "P5E_CPU1_PE0_RX_DP<0>")
	)
	(segment
		(start 91.613482 -388.706106)
		(end 91.775534 -388.775194)
		(width 0.14732)
		(layer "In13.Cu")
		(net "P5E_CPU1_PE0_RX_DP<0>")
	)
	(segment
		(start 89.772998 -384.13436)
		(end 89.936066 -384.53949)
		(width 0.14732)
		(layer "In13.Cu")
		(net "P5E_CPU1_PE0_RX_DP<0>")
	)
	(segment
		(start 88.240616 -223.56699)
		(end 88.240616 -223.585532)
		(width 0.0889)
		(layer "In13.Cu")
		(net "P5E_CPU1_PE0_RX_DP<0>")
	)
	(segment
		(start 91.03106 -387.259322)
		(end 91.194128 -387.664452)
		(width 0.14732)
		(layer "In13.Cu")
		(net "P5E_CPU1_PE0_RX_DP<0>")
	)
	(segment
		(start 87.770716 -224.389442)
		(end 87.770716 -224.399348)
		(width 0.0889)
		(layer "In13.Cu")
		(net "P5E_CPU1_PE0_RX_DP<0>")
	)
	(segment
		(start 90.26144 -385.013962)
		(end 90.192352 -385.176014)
		(width 0.14732)
		(layer "In13.Cu")
		(net "P5E_CPU1_PE0_RX_DP<0>")
	)
	(segment
		(start 89.842086 -383.972308)
		(end 89.772998 -384.13436)
		(width 0.14732)
		(layer "In13.Cu")
		(net "P5E_CPU1_PE0_RX_DP<0>")
	)
	(segment
		(start 85.243162 -256.031238)
		(end 84.48294 -256.791714)
		(width 0.14732)
		(layer "In13.Cu")
		(net "P5E_CPU1_PE0_RX_DP<0>")
	)
	(segment
		(start 87.958168 -224.065084)
		(end 87.949278 -224.070164)
		(width 0.0889)
		(layer "In13.Cu")
		(net "P5E_CPU1_PE0_RX_DP<0>")
	)
	(segment
		(start 83.757516 -243.417852)
		(end 85.778848 -247.810782)
		(width 0.14732)
		(layer "In13.Cu")
		(net "P5E_CPU1_PE0_RX_DP<0>")
	)
	(segment
		(start 85.437218 -252.197362)
		(end 85.33384 -252.7808)
		(width 0.14732)
		(layer "In13.Cu")
		(net "P5E_CPU1_PE0_RX_DP<0>")
	)
	(segment
		(start 89.554812 -221.94774)
		(end 89.398348 -221.676722)
		(width 0.0889)
		(layer "In13.Cu")
		(net "P5E_CPU1_PE0_RX_DP<0>")
	)
	(segment
		(start 84.940648 -311.154318)
		(end 79.700628 -323.592444)
		(width 0.14732)
		(layer "In13.Cu")
		(net "P5E_CPU1_PE0_RX_DP<0>")
	)
	(segment
		(start 85.778848 -249.169174)
		(end 86.106508 -249.960384)
		(width 0.14732)
		(layer "In13.Cu")
		(net "P5E_CPU1_PE0_RX_DP<0>")
	)
	(segment
		(start 89.079578 -438.319418)
		(end 89.48293 -438.319418)
		(width 0.14732)
		(layer "In13.Cu")
		(net "P5E_CPU1_PE0_RX_DP<0>")
	)
	(segment
		(start 85.635338 -229.694486)
		(end 83.72475 -232.639616)
		(width 0.14732)
		(layer "In13.Cu")
		(net "P5E_CPU1_PE0_RX_DP<0>")
	)
	(segment
		(start 86.55431 -226.50323)
		(end 86.548214 -226.506786)
		(width 0.0889)
		(layer "In13.Cu")
		(net "P5E_CPU1_PE0_RX_DP<0>")
	)
	(segment
		(start 85.33384 -252.7808)
		(end 85.33384 -254.350774)
		(width 0.14732)
		(layer "In13.Cu")
		(net "P5E_CPU1_PE0_RX_DP<0>")
	)
	(segment
		(start 90.517472 -385.650232)
		(end 90.680794 -386.055616)
		(width 0.14732)
		(layer "In13.Cu")
		(net "P5E_CPU1_PE0_RX_DP<0>")
	)
	(segment
		(start 91.775534 -388.775194)
		(end 91.938856 -389.180578)
		(width 0.14732)
		(layer "In13.Cu")
		(net "P5E_CPU1_PE0_RX_DP<0>")
	)
	(segment
		(start 83.160616 -260.166104)
		(end 82.143346 -266.662408)
		(width 0.14732)
		(layer "In13.Cu")
		(net "P5E_CPU1_PE0_RX_DP<0>")
	)
	(segment
		(start 87.488268 -224.8789)
		(end 87.479378 -224.88398)
		(width 0.0889)
		(layer "In13.Cu")
		(net "P5E_CPU1_PE0_RX_DP<0>")
	)
	(segment
		(start 85.93328 -228.687884)
		(end 85.635338 -229.694486)
		(width 0.14732)
		(layer "In13.Cu")
		(net "P5E_CPU1_PE0_RX_DP<0>")
	)
	(segment
		(start 96.029018 -404.596092)
		(end 94.311978 -406.313132)
		(width 0.14732)
		(layer "In13.Cu")
		(net "P5E_CPU1_PE0_RX_DP<0>")
	)
	(segment
		(start 89.516712 -383.497836)
		(end 89.678764 -383.566924)
		(width 0.14732)
		(layer "In13.Cu")
		(net "P5E_CPU1_PE0_RX_DP<0>")
	)
	(segment
		(start 82.143346 -266.662408)
		(end 84.940648 -311.154318)
		(width 0.14732)
		(layer "In13.Cu")
		(net "P5E_CPU1_PE0_RX_DP<0>")
	)
	(segment
		(start 88.710516 -222.761556)
		(end 88.710516 -222.77578)
		(width 0.0889)
		(layer "In13.Cu")
		(net "P5E_CPU1_PE0_RX_DP<0>")
	)
	(segment
		(start 85.93328 -228.267768)
		(end 85.93328 -228.289866)
		(width 0.0889)
		(layer "In13.Cu")
		(net "P5E_CPU1_PE0_RX_DP<0>")
	)
	(segment
		(start 86.106508 -249.960384)
		(end 86.106508 -250.858782)
		(width 0.14732)
		(layer "In13.Cu")
		(net "P5E_CPU1_PE0_RX_DP<0>")
	)
	(segment
		(start 79.700628 -323.592444)
		(end 77.085952 -327.326498)
		(width 0.14732)
		(layer "In13.Cu")
		(net "P5E_CPU1_PE0_RX_DP<0>")
	)
	(arc
		(start 87.018114 -225.69297)
		(mid 86.883181 -225.826324)
		(end 86.830916 -226.008692)
		(width 0.0889)
		(layer "In13.Cu")
		(net "P5E_CPU1_PE0_RX_DP<0>")
	)
	(arc
		(start 86.548214 -226.506786)
		(mid 86.413281 -226.64014)
		(end 86.361016 -226.822508)
		(width 0.0889)
		(layer "In13.Cu")
		(net "P5E_CPU1_PE0_RX_DP<0>")
	)
	(arc
		(start 86.361016 -226.84105)
		(mid 86.282905 -227.117999)
		(end 86.078568 -227.320602)
		(width 0.0889)
		(layer "In13.Cu")
		(net "P5E_CPU1_PE0_RX_DP<0>")
	)
	(arc
		(start 88.427814 -223.251268)
		(mid 88.292881 -223.384622)
		(end 88.240616 -223.56699)
		(width 0.0889)
		(layer "In13.Cu")
		(net "P5E_CPU1_PE0_RX_DP<0>")
	)
	(arc
		(start 87.300816 -225.217482)
		(mid 87.221597 -225.492167)
		(end 87.018114 -225.69297)
		(width 0.0889)
		(layer "In13.Cu")
		(net "P5E_CPU1_PE0_RX_DP<0>")
	)
	(arc
		(start 88.710516 -222.77578)
		(mid 88.631297 -223.050465)
		(end 88.427814 -223.251268)
		(width 0.0889)
		(layer "In13.Cu")
		(net "P5E_CPU1_PE0_RX_DP<0>")
	)
	(arc
		(start 87.479378 -224.88398)
		(mid 87.348464 -225.02034)
		(end 87.300816 -225.203258)
		(width 0.0889)
		(layer "In13.Cu")
		(net "P5E_CPU1_PE0_RX_DP<0>")
	)
	(arc
		(start 88.240616 -223.585532)
		(mid 88.162505 -223.862481)
		(end 87.958168 -224.065084)
		(width 0.0889)
		(layer "In13.Cu")
		(net "P5E_CPU1_PE0_RX_DP<0>")
	)
	(arc
		(start 86.069678 -227.325682)
		(mid 85.938764 -227.462042)
		(end 85.891116 -227.64496)
		(width 0.0889)
		(layer "In13.Cu")
		(net "P5E_CPU1_PE0_RX_DP<0>")
	)
	(arc
		(start 86.830916 -226.017328)
		(mid 86.756925 -226.296894)
		(end 86.55431 -226.50323)
		(width 0.0889)
		(layer "In13.Cu")
		(net "P5E_CPU1_PE0_RX_DP<0>")
	)
	(arc
		(start 88.889078 -222.442278)
		(mid 88.758164 -222.578638)
		(end 88.710516 -222.761556)
		(width 0.0889)
		(layer "In13.Cu")
		(net "P5E_CPU1_PE0_RX_DP<0>")
	)
	(arc
		(start 89.180416 -221.957646)
		(mid 89.102305 -222.234595)
		(end 88.897968 -222.437198)
		(width 0.0889)
		(layer "In13.Cu")
		(net "P5E_CPU1_PE0_RX_DP<0>")
	)
	(arc
		(start 89.32037 -221.655894)
		(mid 89.219049 -221.782015)
		(end 89.180416 -221.939104)
		(width 0.0889)
		(layer "In13.Cu")
		(net "P5E_CPU1_PE0_RX_DP<0>")
	)
	(arc
		(start 87.770716 -224.399348)
		(mid 87.692605 -224.676297)
		(end 87.488268 -224.8789)
		(width 0.0889)
		(layer "In13.Cu")
		(net "P5E_CPU1_PE0_RX_DP<0>")
	)
	(arc
		(start 87.949278 -224.070164)
		(mid 87.818364 -224.206524)
		(end 87.770716 -224.389442)
		(width 0.0889)
		(layer "In13.Cu")
		(net "P5E_CPU1_PE0_RX_DP<0>")
	)
	(segment
		(start 98.013266 -220.320108)
		(end 98.013012 -220.319854)
		(width 0.13208)
		(layer "F.Cu")
		(net "P5E_CPU1_PE0_RX_DN<9>")
	)
	(segment
		(start 98.013266 -220.855794)
		(end 98.013266 -220.320108)
		(width 0.13208)
		(layer "F.Cu")
		(net "P5E_CPU1_PE0_RX_DN<9>")
	)
	(segment
		(start 97.168208 -214.424768)
		(end 97.168208 -214.644732)
		(width 0.0889)
		(layer "In13.Cu")
		(net "P5E_CPU1_PE0_RX_DN<9>")
	)
	(segment
		(start 66.418968 -354.96881)
		(end 66.385948 -344.266774)
		(width 0.14732)
		(layer "In13.Cu")
		(net "P5E_CPU1_PE0_RX_DN<9>")
	)
	(segment
		(start 97.347278 -219.825316)
		(end 97.356168 -219.830396)
		(width 0.0889)
		(layer "In13.Cu")
		(net "P5E_CPU1_PE0_RX_DN<9>")
	)
	(segment
		(start 96.223836 -211.099146)
		(end 96.740726 -212.347302)
		(width 0.14732)
		(layer "In13.Cu")
		(net "P5E_CPU1_PE0_RX_DN<9>")
	)
	(segment
		(start 82.439002 -211.741512)
		(end 89.249758 -209.690716)
		(width 0.14732)
		(layer "In13.Cu")
		(net "P5E_CPU1_PE0_RX_DN<9>")
	)
	(segment
		(start 70.6501 -438.089802)
		(end 70.6501 -437.741314)
		(width 0.14732)
		(layer "In13.Cu")
		(net "P5E_CPU1_PE0_RX_DN<9>")
	)
	(segment
		(start 97.347278 -218.197684)
		(end 97.356168 -218.202764)
		(width 0.0889)
		(layer "In13.Cu")
		(net "P5E_CPU1_PE0_RX_DN<9>")
	)
	(segment
		(start 73.84796 -232.98658)
		(end 75.841098 -220.148912)
		(width 0.14732)
		(layer "In13.Cu")
		(net "P5E_CPU1_PE0_RX_DN<9>")
	)
	(segment
		(start 66.385948 -329.97521)
		(end 69.500242 -322.456302)
		(width 0.14732)
		(layer "In13.Cu")
		(net "P5E_CPU1_PE0_RX_DN<9>")
	)
	(segment
		(start 97.356168 -219.18168)
		(end 97.355152 -219.182188)
		(width 0.0889)
		(layer "In13.Cu")
		(net "P5E_CPU1_PE0_RX_DN<9>")
	)
	(segment
		(start 96.877124 -215.755982)
		(end 96.88449 -215.7603)
		(width 0.0889)
		(layer "In13.Cu")
		(net "P5E_CPU1_PE0_RX_DN<9>")
	)
	(segment
		(start 80.47101 -213.35492)
		(end 82.439002 -211.741512)
		(width 0.14732)
		(layer "In13.Cu")
		(net "P5E_CPU1_PE0_RX_DN<9>")
	)
	(segment
		(start 94.70517 -209.956654)
		(end 94.705424 -209.956654)
		(width 0.14732)
		(layer "In13.Cu")
		(net "P5E_CPU1_PE0_RX_DN<9>")
	)
	(segment
		(start 75.932538 -309.54091)
		(end 72.320404 -252.766068)
		(width 0.14732)
		(layer "In13.Cu")
		(net "P5E_CPU1_PE0_RX_DN<9>")
	)
	(segment
		(start 97.856548 -220.590872)
		(end 98.013012 -220.319854)
		(width 0.0889)
		(layer "In13.Cu")
		(net "P5E_CPU1_PE0_RX_DN<9>")
	)
	(segment
		(start 72.403462 -250.17476)
		(end 73.84796 -232.98658)
		(width 0.14732)
		(layer "In13.Cu")
		(net "P5E_CPU1_PE0_RX_DN<9>")
	)
	(segment
		(start 70.019164 -437.59374)
		(end 69.70014 -437.274716)
		(width 0.14732)
		(layer "In13.Cu")
		(net "P5E_CPU1_PE0_RX_DN<9>")
	)
	(segment
		(start 97.638616 -217.05443)
		(end 97.638616 -217.082878)
		(width 0.0889)
		(layer "In13.Cu")
		(net "P5E_CPU1_PE0_RX_DN<9>")
	)
	(segment
		(start 72.320404 -252.766068)
		(end 72.320404 -252.646942)
		(width 0.14732)
		(layer "In13.Cu")
		(net "P5E_CPU1_PE0_RX_DN<9>")
	)
	(segment
		(start 69.500242 -322.456302)
		(end 72.021954 -318.855852)
		(width 0.14732)
		(layer "In13.Cu")
		(net "P5E_CPU1_PE0_RX_DN<9>")
	)
	(segment
		(start 72.320404 -252.646942)
		(end 72.403462 -250.17476)
		(width 0.14732)
		(layer "In13.Cu")
		(net "P5E_CPU1_PE0_RX_DN<9>")
	)
	(segment
		(start 75.841098 -220.148912)
		(end 77.127608 -217.652092)
		(width 0.14732)
		(layer "In13.Cu")
		(net "P5E_CPU1_PE0_RX_DN<9>")
	)
	(segment
		(start 68.212208 -390.830308)
		(end 66.418968 -354.96881)
		(width 0.14732)
		(layer "In13.Cu")
		(net "P5E_CPU1_PE0_RX_DN<9>")
	)
	(segment
		(start 70.6501 -437.741314)
		(end 70.502526 -437.59374)
		(width 0.14732)
		(layer "In13.Cu")
		(net "P5E_CPU1_PE0_RX_DN<9>")
	)
	(segment
		(start 68.236592 -392.13663)
		(end 68.212208 -390.830308)
		(width 0.14732)
		(layer "In13.Cu")
		(net "P5E_CPU1_PE0_RX_DN<9>")
	)
	(segment
		(start 97.355152 -219.182188)
		(end 97.347278 -219.18676)
		(width 0.0889)
		(layer "In13.Cu")
		(net "P5E_CPU1_PE0_RX_DN<9>")
	)
	(segment
		(start 97.638616 -220.309948)
		(end 97.638616 -220.32849)
		(width 0.0889)
		(layer "In13.Cu")
		(net "P5E_CPU1_PE0_RX_DN<9>")
	)
	(segment
		(start 66.468498 -406.19934)
		(end 68.185538 -404.4823)
		(width 0.14732)
		(layer "In13.Cu")
		(net "P5E_CPU1_PE0_RX_DN<9>")
	)
	(segment
		(start 97.638362 -218.676728)
		(end 97.638362 -218.707716)
		(width 0.0889)
		(layer "In13.Cu")
		(net "P5E_CPU1_PE0_RX_DN<9>")
	)
	(segment
		(start 89.249758 -209.690716)
		(end 94.063566 -209.690716)
		(width 0.14732)
		(layer "In13.Cu")
		(net "P5E_CPU1_PE0_RX_DN<9>")
	)
	(segment
		(start 96.740726 -213.15807)
		(end 96.698816 -213.19998)
		(width 0.0889)
		(layer "In13.Cu")
		(net "P5E_CPU1_PE0_RX_DN<9>")
	)
	(segment
		(start 72.021954 -318.855852)
		(end 75.932538 -309.54091)
		(width 0.14732)
		(layer "In13.Cu")
		(net "P5E_CPU1_PE0_RX_DN<9>")
	)
	(segment
		(start 68.185538 -400.693382)
		(end 68.361306 -398.776952)
		(width 0.14732)
		(layer "In13.Cu")
		(net "P5E_CPU1_PE0_RX_DN<9>")
	)
	(segment
		(start 68.185538 -404.4823)
		(end 68.185538 -400.693382)
		(width 0.14732)
		(layer "In13.Cu")
		(net "P5E_CPU1_PE0_RX_DN<9>")
	)
	(segment
		(start 97.77857 -220.6117)
		(end 97.856548 -220.590872)
		(width 0.0889)
		(layer "In13.Cu")
		(net "P5E_CPU1_PE0_RX_DN<9>")
	)
	(segment
		(start 96.740726 -212.347302)
		(end 96.740726 -213.135972)
		(width 0.14732)
		(layer "In13.Cu")
		(net "P5E_CPU1_PE0_RX_DN<9>")
	)
	(segment
		(start 77.127608 -217.652092)
		(end 80.47101 -213.35492)
		(width 0.14732)
		(layer "In13.Cu")
		(net "P5E_CPU1_PE0_RX_DN<9>")
	)
	(segment
		(start 96.886014 -215.112346)
		(end 96.884998 -215.112854)
		(width 0.0889)
		(layer "In13.Cu")
		(net "P5E_CPU1_PE0_RX_DN<9>")
	)
	(segment
		(start 96.884998 -215.112854)
		(end 96.877124 -215.117426)
		(width 0.0889)
		(layer "In13.Cu")
		(net "P5E_CPU1_PE0_RX_DN<9>")
	)
	(segment
		(start 96.740726 -213.135972)
		(end 96.740726 -213.15807)
		(width 0.0889)
		(layer "In13.Cu")
		(net "P5E_CPU1_PE0_RX_DN<9>")
	)
	(segment
		(start 69.70014 -437.274716)
		(end 69.70014 -416.700716)
		(width 0.14732)
		(layer "In13.Cu")
		(net "P5E_CPU1_PE0_RX_DN<9>")
	)
	(segment
		(start 94.705424 -209.956654)
		(end 95.347028 -210.222338)
		(width 0.14732)
		(layer "In13.Cu")
		(net "P5E_CPU1_PE0_RX_DN<9>")
	)
	(segment
		(start 97.347278 -216.569798)
		(end 97.356168 -216.574878)
		(width 0.0889)
		(layer "In13.Cu")
		(net "P5E_CPU1_PE0_RX_DN<9>")
	)
	(segment
		(start 96.886014 -215.761062)
		(end 96.888808 -215.762586)
		(width 0.0889)
		(layer "In13.Cu")
		(net "P5E_CPU1_PE0_RX_DN<9>")
	)
	(segment
		(start 96.698816 -213.19998)
		(end 96.698816 -213.893908)
		(width 0.0889)
		(layer "In13.Cu")
		(net "P5E_CPU1_PE0_RX_DN<9>")
	)
	(segment
		(start 66.468498 -410.67736)
		(end 66.468498 -406.19934)
		(width 0.14732)
		(layer "In13.Cu")
		(net "P5E_CPU1_PE0_RX_DN<9>")
	)
	(segment
		(start 94.063566 -209.690716)
		(end 94.70517 -209.956654)
		(width 0.14732)
		(layer "In13.Cu")
		(net "P5E_CPU1_PE0_RX_DN<9>")
	)
	(segment
		(start 68.361306 -398.776952)
		(end 68.236592 -392.13663)
		(width 0.14732)
		(layer "In13.Cu")
		(net "P5E_CPU1_PE0_RX_DN<9>")
	)
	(segment
		(start 66.385948 -344.266774)
		(end 66.385948 -329.97521)
		(width 0.14732)
		(layer "In13.Cu")
		(net "P5E_CPU1_PE0_RX_DN<9>")
	)
	(segment
		(start 95.347028 -210.222338)
		(end 96.223836 -211.099146)
		(width 0.14732)
		(layer "In13.Cu")
		(net "P5E_CPU1_PE0_RX_DN<9>")
	)
	(segment
		(start 97.356168 -217.554048)
		(end 97.347278 -217.559128)
		(width 0.0889)
		(layer "In13.Cu")
		(net "P5E_CPU1_PE0_RX_DN<9>")
	)
	(segment
		(start 69.70014 -416.700716)
		(end 66.468498 -410.67736)
		(width 0.14732)
		(layer "In13.Cu")
		(net "P5E_CPU1_PE0_RX_DN<9>")
	)
	(segment
		(start 70.502526 -437.59374)
		(end 70.019164 -437.59374)
		(width 0.14732)
		(layer "In13.Cu")
		(net "P5E_CPU1_PE0_RX_DN<9>")
	)
	(segment
		(start 96.88449 -215.7603)
		(end 96.886014 -215.761062)
		(width 0.0889)
		(layer "In13.Cu")
		(net "P5E_CPU1_PE0_RX_DN<9>")
	)
	(segment
		(start 96.888808 -215.762586)
		(end 96.89211 -215.764618)
		(width 0.0889)
		(layer "In13.Cu")
		(net "P5E_CPU1_PE0_RX_DN<9>")
	)
	(arc
		(start 97.16897 -217.866214)
		(mid 97.168803 -217.87739)
		(end 97.16897 -217.888566)
		(width 0.0889)
		(layer "In13.Cu")
		(net "P5E_CPU1_PE0_RX_DN<9>")
	)
	(arc
		(start 97.356168 -218.202764)
		(mid 97.558991 -218.402995)
		(end 97.638362 -218.676728)
		(width 0.0889)
		(layer "In13.Cu")
		(net "P5E_CPU1_PE0_RX_DN<9>")
	)
	(arc
		(start 97.16897 -217.888566)
		(mid 97.218985 -218.065697)
		(end 97.347278 -218.197684)
		(width 0.0889)
		(layer "In13.Cu")
		(net "P5E_CPU1_PE0_RX_DN<9>")
	)
	(arc
		(start 96.698562 -215.436704)
		(mid 96.746241 -215.619604)
		(end 96.877124 -215.755982)
		(width 0.0889)
		(layer "In13.Cu")
		(net "P5E_CPU1_PE0_RX_DN<9>")
	)
	(arc
		(start 97.168208 -214.644732)
		(mid 97.087297 -214.91486)
		(end 96.886014 -215.112346)
		(width 0.0889)
		(layer "In13.Cu")
		(net "P5E_CPU1_PE0_RX_DN<9>")
	)
	(arc
		(start 97.347278 -219.18676)
		(mid 97.218874 -219.318705)
		(end 97.168716 -219.495878)
		(width 0.0889)
		(layer "In13.Cu")
		(net "P5E_CPU1_PE0_RX_DN<9>")
	)
	(arc
		(start 97.168716 -219.512642)
		(mid 97.217969 -219.691842)
		(end 97.347278 -219.825316)
		(width 0.0889)
		(layer "In13.Cu")
		(net "P5E_CPU1_PE0_RX_DN<9>")
	)
	(arc
		(start 96.877124 -215.117426)
		(mid 96.74987 -215.247392)
		(end 96.698816 -215.421972)
		(width 0.0889)
		(layer "In13.Cu")
		(net "P5E_CPU1_PE0_RX_DN<9>")
	)
	(arc
		(start 97.168716 -219.495878)
		(mid 97.168622 -219.50426)
		(end 97.168716 -219.512642)
		(width 0.0889)
		(layer "In13.Cu")
		(net "P5E_CPU1_PE0_RX_DN<9>")
	)
	(arc
		(start 97.356168 -216.574878)
		(mid 97.560503 -216.777483)
		(end 97.638616 -217.05443)
		(width 0.0889)
		(layer "In13.Cu")
		(net "P5E_CPU1_PE0_RX_DN<9>")
	)
	(arc
		(start 96.89211 -215.764618)
		(mid 97.094697 -215.970969)
		(end 97.168716 -216.25052)
		(width 0.0889)
		(layer "In13.Cu")
		(net "P5E_CPU1_PE0_RX_DN<9>")
	)
	(arc
		(start 97.638616 -220.32849)
		(mid 97.67729 -220.485558)
		(end 97.77857 -220.6117)
		(width 0.0889)
		(layer "In13.Cu")
		(net "P5E_CPU1_PE0_RX_DN<9>")
	)
	(arc
		(start 97.638362 -218.707716)
		(mid 97.558992 -218.98145)
		(end 97.356168 -219.18168)
		(width 0.0889)
		(layer "In13.Cu")
		(net "P5E_CPU1_PE0_RX_DN<9>")
	)
	(arc
		(start 97.347278 -217.559128)
		(mid 97.219385 -217.69019)
		(end 97.16897 -217.866214)
		(width 0.0889)
		(layer "In13.Cu")
		(net "P5E_CPU1_PE0_RX_DN<9>")
	)
	(arc
		(start 96.698816 -213.893908)
		(mid 96.773821 -214.009367)
		(end 96.882966 -214.093298)
		(width 0.0889)
		(layer "In13.Cu")
		(net "P5E_CPU1_PE0_RX_DN<9>")
	)
	(arc
		(start 96.698816 -215.421972)
		(mid 96.698619 -215.429337)
		(end 96.698562 -215.436704)
		(width 0.0889)
		(layer "In13.Cu")
		(net "P5E_CPU1_PE0_RX_DN<9>")
	)
	(arc
		(start 97.168716 -216.25052)
		(mid 97.216395 -216.43342)
		(end 97.347278 -216.569798)
		(width 0.0889)
		(layer "In13.Cu")
		(net "P5E_CPU1_PE0_RX_DN<9>")
	)
	(arc
		(start 97.356168 -219.830396)
		(mid 97.560503 -220.033001)
		(end 97.638616 -220.309948)
		(width 0.0889)
		(layer "In13.Cu")
		(net "P5E_CPU1_PE0_RX_DN<9>")
	)
	(arc
		(start 97.638616 -217.082878)
		(mid 97.558454 -217.355067)
		(end 97.356168 -217.554048)
		(width 0.0889)
		(layer "In13.Cu")
		(net "P5E_CPU1_PE0_RX_DN<9>")
	)
	(arc
		(start 96.882966 -214.093298)
		(mid 97.056929 -214.232062)
		(end 97.168208 -214.424768)
		(width 0.0889)
		(layer "In13.Cu")
		(net "P5E_CPU1_PE0_RX_DN<9>")
	)
	(segment
		(start 96.603312 -221.669864)
		(end 96.603312 -221.134178)
		(width 0.13208)
		(layer "F.Cu")
		(net "P5E_CPU1_PE0_RX_DN<8>")
	)
	(segment
		(start 96.603312 -221.134178)
		(end 96.603566 -221.133924)
		(width 0.13208)
		(layer "F.Cu")
		(net "P5E_CPU1_PE0_RX_DN<8>")
	)
	(segment
		(start 74.776838 -233.130852)
		(end 76.746608 -220.443806)
		(width 0.14732)
		(layer "In13.Cu")
		(net "P5E_CPU1_PE0_RX_DN<8>")
	)
	(segment
		(start 67.329558 -330.204318)
		(end 70.396354 -322.800472)
		(width 0.14732)
		(layer "In13.Cu")
		(net "P5E_CPU1_PE0_RX_DN<8>")
	)
	(segment
		(start 71.680832 -416.990276)
		(end 69.531738 -410.377132)
		(width 0.14732)
		(layer "In13.Cu")
		(net "P5E_CPU1_PE0_RX_DN<8>")
	)
	(segment
		(start 96.698816 -220.319854)
		(end 96.698816 -220.334078)
		(width 0.0889)
		(layer "In13.Cu")
		(net "P5E_CPU1_PE0_RX_DN<8>")
	)
	(segment
		(start 96.407478 -221.453202)
		(end 96.416368 -221.458282)
		(width 0.0889)
		(layer "In13.Cu")
		(net "P5E_CPU1_PE0_RX_DN<8>")
	)
	(segment
		(start 96.407478 -216.569798)
		(end 96.416368 -216.574878)
		(width 0.0889)
		(layer "In13.Cu")
		(net "P5E_CPU1_PE0_RX_DN<8>")
	)
	(segment
		(start 96.228408 -214.424768)
		(end 96.228408 -214.644732)
		(width 0.0889)
		(layer "In13.Cu")
		(net "P5E_CPU1_PE0_RX_DN<8>")
	)
	(segment
		(start 71.680832 -438.30875)
		(end 71.680832 -416.990276)
		(width 0.14732)
		(layer "In13.Cu")
		(net "P5E_CPU1_PE0_RX_DN<8>")
	)
	(segment
		(start 67.329558 -346.992956)
		(end 67.329558 -330.204318)
		(width 0.14732)
		(layer "In13.Cu")
		(net "P5E_CPU1_PE0_RX_DN<8>")
	)
	(segment
		(start 72.871584 -319.266316)
		(end 76.923138 -309.685436)
		(width 0.14732)
		(layer "In13.Cu")
		(net "P5E_CPU1_PE0_RX_DN<8>")
	)
	(segment
		(start 73.305924 -252.67666)
		(end 73.305924 -252.490478)
		(width 0.14732)
		(layer "In13.Cu")
		(net "P5E_CPU1_PE0_RX_DN<8>")
	)
	(segment
		(start 73.382124 -250.220988)
		(end 74.776838 -233.130852)
		(width 0.14732)
		(layer "In13.Cu")
		(net "P5E_CPU1_PE0_RX_DN<8>")
	)
	(segment
		(start 76.923138 -309.685436)
		(end 73.305924 -252.67666)
		(width 0.14732)
		(layer "In13.Cu")
		(net "P5E_CPU1_PE0_RX_DN<8>")
	)
	(segment
		(start 71.96582 -438.593738)
		(end 71.680832 -438.30875)
		(width 0.14732)
		(layer "In13.Cu")
		(net "P5E_CPU1_PE0_RX_DN<8>")
	)
	(segment
		(start 95.800672 -212.590634)
		(end 95.800672 -213.07425)
		(width 0.14732)
		(layer "In13.Cu")
		(net "P5E_CPU1_PE0_RX_DN<8>")
	)
	(segment
		(start 95.758762 -215.436704)
		(end 95.758762 -215.459564)
		(width 0.0889)
		(layer "In13.Cu")
		(net "P5E_CPU1_PE0_RX_DN<8>")
	)
	(segment
		(start 76.746608 -220.443806)
		(end 77.922882 -218.16187)
		(width 0.14732)
		(layer "In13.Cu")
		(net "P5E_CPU1_PE0_RX_DN<8>")
	)
	(segment
		(start 95.946214 -215.112346)
		(end 95.937324 -215.117426)
		(width 0.0889)
		(layer "In13.Cu")
		(net "P5E_CPU1_PE0_RX_DN<8>")
	)
	(segment
		(start 77.922882 -218.16187)
		(end 81.150968 -214.013288)
		(width 0.14732)
		(layer "In13.Cu")
		(net "P5E_CPU1_PE0_RX_DN<8>")
	)
	(segment
		(start 96.416368 -219.830396)
		(end 96.422464 -219.833952)
		(width 0.0889)
		(layer "In13.Cu")
		(net "P5E_CPU1_PE0_RX_DN<8>")
	)
	(segment
		(start 71.248778 -404.4823)
		(end 71.248778 -400.634454)
		(width 0.14732)
		(layer "In13.Cu")
		(net "P5E_CPU1_PE0_RX_DN<8>")
	)
	(segment
		(start 72.650096 -438.741312)
		(end 72.502522 -438.593738)
		(width 0.14732)
		(layer "In13.Cu")
		(net "P5E_CPU1_PE0_RX_DN<8>")
	)
	(segment
		(start 95.758762 -213.138258)
		(end 95.758762 -213.8934)
		(width 0.0889)
		(layer "In13.Cu")
		(net "P5E_CPU1_PE0_RX_DN<8>")
	)
	(segment
		(start 72.502522 -438.593738)
		(end 71.96582 -438.593738)
		(width 0.14732)
		(layer "In13.Cu")
		(net "P5E_CPU1_PE0_RX_DN<8>")
	)
	(segment
		(start 95.758762 -213.8934)
		(end 95.759016 -213.893908)
		(width 0.0889)
		(layer "In13.Cu")
		(net "P5E_CPU1_PE0_RX_DN<8>")
	)
	(segment
		(start 73.305924 -252.490478)
		(end 73.382124 -250.220988)
		(width 0.14732)
		(layer "In13.Cu")
		(net "P5E_CPU1_PE0_RX_DN<8>")
	)
	(segment
		(start 69.531738 -410.377132)
		(end 69.531738 -406.19934)
		(width 0.14732)
		(layer "In13.Cu")
		(net "P5E_CPU1_PE0_RX_DN<8>")
	)
	(segment
		(start 95.800672 -213.07425)
		(end 95.800672 -213.096348)
		(width 0.0889)
		(layer "In13.Cu")
		(net "P5E_CPU1_PE0_RX_DN<8>")
	)
	(segment
		(start 96.738948 -221.48292)
		(end 96.76003 -221.404942)
		(width 0.0889)
		(layer "In13.Cu")
		(net "P5E_CPU1_PE0_RX_DN<8>")
	)
	(segment
		(start 71.379588 -399.256504)
		(end 67.329558 -346.992956)
		(width 0.14732)
		(layer "In13.Cu")
		(net "P5E_CPU1_PE0_RX_DN<8>")
	)
	(segment
		(start 82.556604 -212.86089)
		(end 89.96299 -210.630516)
		(width 0.14732)
		(layer "In13.Cu")
		(net "P5E_CPU1_PE0_RX_DN<8>")
	)
	(segment
		(start 96.416368 -219.18168)
		(end 96.407478 -219.18676)
		(width 0.0889)
		(layer "In13.Cu")
		(net "P5E_CPU1_PE0_RX_DN<8>")
	)
	(segment
		(start 95.917766 -215.744044)
		(end 95.95231 -215.764618)
		(width 0.0889)
		(layer "In13.Cu")
		(net "P5E_CPU1_PE0_RX_DN<8>")
	)
	(segment
		(start 95.416878 -211.663788)
		(end 95.800672 -212.590634)
		(width 0.14732)
		(layer "In13.Cu")
		(net "P5E_CPU1_PE0_RX_DN<8>")
	)
	(segment
		(start 94.300294 -210.831176)
		(end 94.300548 -210.831176)
		(width 0.14732)
		(layer "In13.Cu")
		(net "P5E_CPU1_PE0_RX_DN<8>")
	)
	(segment
		(start 71.248778 -400.634454)
		(end 71.379588 -399.256504)
		(width 0.14732)
		(layer "In13.Cu")
		(net "P5E_CPU1_PE0_RX_DN<8>")
	)
	(segment
		(start 96.698562 -218.676728)
		(end 96.698562 -218.707716)
		(width 0.0889)
		(layer "In13.Cu")
		(net "P5E_CPU1_PE0_RX_DN<8>")
	)
	(segment
		(start 96.407478 -218.197684)
		(end 96.416368 -218.202764)
		(width 0.0889)
		(layer "In13.Cu")
		(net "P5E_CPU1_PE0_RX_DN<8>")
	)
	(segment
		(start 94.300548 -210.831176)
		(end 94.784926 -211.031836)
		(width 0.14732)
		(layer "In13.Cu")
		(net "P5E_CPU1_PE0_RX_DN<8>")
	)
	(segment
		(start 94.784926 -211.031836)
		(end 95.416878 -211.663788)
		(width 0.14732)
		(layer "In13.Cu")
		(net "P5E_CPU1_PE0_RX_DN<8>")
	)
	(segment
		(start 93.815916 -210.630516)
		(end 94.300294 -210.831176)
		(width 0.14732)
		(layer "In13.Cu")
		(net "P5E_CPU1_PE0_RX_DN<8>")
	)
	(segment
		(start 95.800672 -213.096348)
		(end 95.758762 -213.138258)
		(width 0.0889)
		(layer "In13.Cu")
		(net "P5E_CPU1_PE0_RX_DN<8>")
	)
	(segment
		(start 96.407478 -219.825316)
		(end 96.416368 -219.830396)
		(width 0.0889)
		(layer "In13.Cu")
		(net "P5E_CPU1_PE0_RX_DN<8>")
	)
	(segment
		(start 96.698816 -217.064336)
		(end 96.698816 -217.07856)
		(width 0.0889)
		(layer "In13.Cu")
		(net "P5E_CPU1_PE0_RX_DN<8>")
	)
	(segment
		(start 89.96299 -210.630516)
		(end 93.815916 -210.630516)
		(width 0.14732)
		(layer "In13.Cu")
		(net "P5E_CPU1_PE0_RX_DN<8>")
	)
	(segment
		(start 96.416368 -220.809566)
		(end 96.407478 -220.814646)
		(width 0.0889)
		(layer "In13.Cu")
		(net "P5E_CPU1_PE0_RX_DN<8>")
	)
	(segment
		(start 96.416368 -217.554048)
		(end 96.407478 -217.559128)
		(width 0.0889)
		(layer "In13.Cu")
		(net "P5E_CPU1_PE0_RX_DN<8>")
	)
	(segment
		(start 72.650096 -439.0898)
		(end 72.650096 -438.741312)
		(width 0.14732)
		(layer "In13.Cu")
		(net "P5E_CPU1_PE0_RX_DN<8>")
	)
	(segment
		(start 96.76003 -221.404942)
		(end 96.603566 -221.133924)
		(width 0.0889)
		(layer "In13.Cu")
		(net "P5E_CPU1_PE0_RX_DN<8>")
	)
	(segment
		(start 69.531738 -406.19934)
		(end 71.248778 -404.4823)
		(width 0.14732)
		(layer "In13.Cu")
		(net "P5E_CPU1_PE0_RX_DN<8>")
	)
	(segment
		(start 70.396354 -322.800472)
		(end 72.871584 -319.266316)
		(width 0.14732)
		(layer "In13.Cu")
		(net "P5E_CPU1_PE0_RX_DN<8>")
	)
	(segment
		(start 96.416368 -216.574878)
		(end 96.422464 -216.578434)
		(width 0.0889)
		(layer "In13.Cu")
		(net "P5E_CPU1_PE0_RX_DN<8>")
	)
	(segment
		(start 81.150968 -214.013288)
		(end 82.556604 -212.86089)
		(width 0.14732)
		(layer "In13.Cu")
		(net "P5E_CPU1_PE0_RX_DN<8>")
	)
	(arc
		(start 96.407478 -219.18676)
		(mid 96.229002 -219.506038)
		(end 96.407478 -219.825316)
		(width 0.0889)
		(layer "In13.Cu")
		(net "P5E_CPU1_PE0_RX_DN<8>")
	)
	(arc
		(start 95.759016 -213.893908)
		(mid 95.834021 -214.009367)
		(end 95.943166 -214.093298)
		(width 0.0889)
		(layer "In13.Cu")
		(net "P5E_CPU1_PE0_RX_DN<8>")
	)
	(arc
		(start 96.422464 -216.578434)
		(mid 96.624877 -216.784847)
		(end 96.698816 -217.064336)
		(width 0.0889)
		(layer "In13.Cu")
		(net "P5E_CPU1_PE0_RX_DN<8>")
	)
	(arc
		(start 96.416368 -221.458282)
		(mid 96.574856 -221.507215)
		(end 96.738948 -221.48292)
		(width 0.0889)
		(layer "In13.Cu")
		(net "P5E_CPU1_PE0_RX_DN<8>")
	)
	(arc
		(start 96.228408 -214.644732)
		(mid 96.147497 -214.91486)
		(end 95.946214 -215.112346)
		(width 0.0889)
		(layer "In13.Cu")
		(net "P5E_CPU1_PE0_RX_DN<8>")
	)
	(arc
		(start 96.416368 -218.202764)
		(mid 96.619191 -218.402995)
		(end 96.698562 -218.676728)
		(width 0.0889)
		(layer "In13.Cu")
		(net "P5E_CPU1_PE0_RX_DN<8>")
	)
	(arc
		(start 95.937324 -215.117426)
		(mid 95.81007 -215.247392)
		(end 95.759016 -215.421972)
		(width 0.0889)
		(layer "In13.Cu")
		(net "P5E_CPU1_PE0_RX_DN<8>")
	)
	(arc
		(start 96.698816 -220.334078)
		(mid 96.619675 -220.608701)
		(end 96.416368 -220.809566)
		(width 0.0889)
		(layer "In13.Cu")
		(net "P5E_CPU1_PE0_RX_DN<8>")
	)
	(arc
		(start 96.228916 -216.25052)
		(mid 96.276595 -216.43342)
		(end 96.407478 -216.569798)
		(width 0.0889)
		(layer "In13.Cu")
		(net "P5E_CPU1_PE0_RX_DN<8>")
	)
	(arc
		(start 96.407478 -220.814646)
		(mid 96.280224 -220.944612)
		(end 96.22917 -221.119192)
		(width 0.0889)
		(layer "In13.Cu")
		(net "P5E_CPU1_PE0_RX_DN<8>")
	)
	(arc
		(start 95.759016 -215.421972)
		(mid 95.758819 -215.429337)
		(end 95.758762 -215.436704)
		(width 0.0889)
		(layer "In13.Cu")
		(net "P5E_CPU1_PE0_RX_DN<8>")
	)
	(arc
		(start 96.422464 -219.833952)
		(mid 96.624877 -220.040365)
		(end 96.698816 -220.319854)
		(width 0.0889)
		(layer "In13.Cu")
		(net "P5E_CPU1_PE0_RX_DN<8>")
	)
	(arc
		(start 95.943166 -214.093298)
		(mid 96.117129 -214.232062)
		(end 96.228408 -214.424768)
		(width 0.0889)
		(layer "In13.Cu")
		(net "P5E_CPU1_PE0_RX_DN<8>")
	)
	(arc
		(start 96.698816 -217.07856)
		(mid 96.619675 -217.353183)
		(end 96.416368 -217.554048)
		(width 0.0889)
		(layer "In13.Cu")
		(net "P5E_CPU1_PE0_RX_DN<8>")
	)
	(arc
		(start 96.407478 -217.559128)
		(mid 96.280224 -217.689094)
		(end 96.22917 -217.863674)
		(width 0.0889)
		(layer "In13.Cu")
		(net "P5E_CPU1_PE0_RX_DN<8>")
	)
	(arc
		(start 96.22917 -217.863674)
		(mid 96.228837 -217.876118)
		(end 96.228916 -217.888566)
		(width 0.0889)
		(layer "In13.Cu")
		(net "P5E_CPU1_PE0_RX_DN<8>")
	)
	(arc
		(start 96.22917 -221.119192)
		(mid 96.228837 -221.131636)
		(end 96.228916 -221.144084)
		(width 0.0889)
		(layer "In13.Cu")
		(net "P5E_CPU1_PE0_RX_DN<8>")
	)
	(arc
		(start 95.95231 -215.764618)
		(mid 96.154985 -215.970939)
		(end 96.228916 -216.25052)
		(width 0.0889)
		(layer "In13.Cu")
		(net "P5E_CPU1_PE0_RX_DN<8>")
	)
	(arc
		(start 96.228916 -221.144084)
		(mid 96.278985 -221.321309)
		(end 96.407478 -221.453202)
		(width 0.0889)
		(layer "In13.Cu")
		(net "P5E_CPU1_PE0_RX_DN<8>")
	)
	(arc
		(start 95.758762 -215.459564)
		(mid 95.801229 -215.622487)
		(end 95.917766 -215.744044)
		(width 0.0889)
		(layer "In13.Cu")
		(net "P5E_CPU1_PE0_RX_DN<8>")
	)
	(arc
		(start 96.228916 -217.888566)
		(mid 96.278985 -218.065791)
		(end 96.407478 -218.197684)
		(width 0.0889)
		(layer "In13.Cu")
		(net "P5E_CPU1_PE0_RX_DN<8>")
	)
	(arc
		(start 96.698562 -218.707716)
		(mid 96.619192 -218.98145)
		(end 96.416368 -219.18168)
		(width 0.0889)
		(layer "In13.Cu")
		(net "P5E_CPU1_PE0_RX_DN<8>")
	)
	(segment
		(start 96.133666 -220.855794)
		(end 96.133666 -220.320108)
		(width 0.13208)
		(layer "F.Cu")
		(net "P5E_CPU1_PE0_RX_DN<7>")
	)
	(segment
		(start 96.133666 -220.320108)
		(end 96.133412 -220.319854)
		(width 0.13208)
		(layer "F.Cu")
		(net "P5E_CPU1_PE0_RX_DN<7>")
	)
	(segment
		(start 72.789034 -390.894316)
		(end 72.788272 -390.893554)
		(width 0.14732)
		(layer "In13.Cu")
		(net "P5E_CPU1_PE0_RX_DN<7>")
	)
	(segment
		(start 72.594978 -406.19934)
		(end 74.312018 -404.4823)
		(width 0.14732)
		(layer "In13.Cu")
		(net "P5E_CPU1_PE0_RX_DN<7>")
	)
	(segment
		(start 74.239628 -252.390148)
		(end 74.30389 -250.481846)
		(width 0.14732)
		(layer "In13.Cu")
		(net "P5E_CPU1_PE0_RX_DN<7>")
	)
	(segment
		(start 95.476568 -217.554048)
		(end 95.467678 -217.559128)
		(width 0.0889)
		(layer "In13.Cu")
		(net "P5E_CPU1_PE0_RX_DN<7>")
	)
	(segment
		(start 94.997524 -215.755982)
		(end 95.00489 -215.7603)
		(width 0.0889)
		(layer "In13.Cu")
		(net "P5E_CPU1_PE0_RX_DN<7>")
	)
	(segment
		(start 95.288608 -214.424768)
		(end 95.288608 -214.644732)
		(width 0.0889)
		(layer "In13.Cu")
		(net "P5E_CPU1_PE0_RX_DN<7>")
	)
	(segment
		(start 74.109072 -398.806416)
		(end 74.109072 -398.806162)
		(width 0.14732)
		(layer "In13.Cu")
		(net "P5E_CPU1_PE0_RX_DN<7>")
	)
	(segment
		(start 94.250764 -211.834222)
		(end 94.600268 -212.183726)
		(width 0.14732)
		(layer "In13.Cu")
		(net "P5E_CPU1_PE0_RX_DN<7>")
	)
	(segment
		(start 95.005398 -215.112854)
		(end 94.997524 -215.117426)
		(width 0.0889)
		(layer "In13.Cu")
		(net "P5E_CPU1_PE0_RX_DN<7>")
	)
	(segment
		(start 77.987398 -309.669434)
		(end 74.239628 -252.390148)
		(width 0.14732)
		(layer "In13.Cu")
		(net "P5E_CPU1_PE0_RX_DN<7>")
	)
	(segment
		(start 75.806554 -233.117898)
		(end 77.724762 -220.762576)
		(width 0.14732)
		(layer "In13.Cu")
		(net "P5E_CPU1_PE0_RX_DN<7>")
	)
	(segment
		(start 75.65009 -437.741314)
		(end 75.502516 -437.59374)
		(width 0.14732)
		(layer "In13.Cu")
		(net "P5E_CPU1_PE0_RX_DN<7>")
	)
	(segment
		(start 74.312018 -404.4823)
		(end 74.312018 -400.02079)
		(width 0.14732)
		(layer "In13.Cu")
		(net "P5E_CPU1_PE0_RX_DN<7>")
	)
	(segment
		(start 93.796612 -211.646008)
		(end 94.250764 -211.834222)
		(width 0.14732)
		(layer "In13.Cu")
		(net "P5E_CPU1_PE0_RX_DN<7>")
	)
	(segment
		(start 95.009208 -215.762586)
		(end 95.01251 -215.764618)
		(width 0.0889)
		(layer "In13.Cu")
		(net "P5E_CPU1_PE0_RX_DN<7>")
	)
	(segment
		(start 68.285868 -346.93225)
		(end 68.285868 -330.387198)
		(width 0.14732)
		(layer "In13.Cu")
		(net "P5E_CPU1_PE0_RX_DN<7>")
	)
	(segment
		(start 94.861126 -213.129368)
		(end 94.819216 -213.171278)
		(width 0.0889)
		(layer "In13.Cu")
		(net "P5E_CPU1_PE0_RX_DN<7>")
	)
	(segment
		(start 74.96556 -437.59374)
		(end 74.680572 -437.308752)
		(width 0.14732)
		(layer "In13.Cu")
		(net "P5E_CPU1_PE0_RX_DN<7>")
	)
	(segment
		(start 94.861126 -212.8139)
		(end 94.861126 -213.10727)
		(width 0.14732)
		(layer "In13.Cu")
		(net "P5E_CPU1_PE0_RX_DN<7>")
	)
	(segment
		(start 95.759016 -220.309948)
		(end 95.759016 -220.32849)
		(width 0.0889)
		(layer "In13.Cu")
		(net "P5E_CPU1_PE0_RX_DN<7>")
	)
	(segment
		(start 95.976948 -220.590872)
		(end 96.133412 -220.319854)
		(width 0.0889)
		(layer "In13.Cu")
		(net "P5E_CPU1_PE0_RX_DN<7>")
	)
	(segment
		(start 71.18858 -323.379084)
		(end 73.719944 -319.764664)
		(width 0.14732)
		(layer "In13.Cu")
		(net "P5E_CPU1_PE0_RX_DN<7>")
	)
	(segment
		(start 81.882742 -214.726774)
		(end 83.107276 -213.722966)
		(width 0.14732)
		(layer "In13.Cu")
		(net "P5E_CPU1_PE0_RX_DN<7>")
	)
	(segment
		(start 95.476568 -219.18168)
		(end 95.475552 -219.182188)
		(width 0.0889)
		(layer "In13.Cu")
		(net "P5E_CPU1_PE0_RX_DN<7>")
	)
	(segment
		(start 72.788272 -390.893554)
		(end 68.285868 -346.93225)
		(width 0.14732)
		(layer "In13.Cu")
		(net "P5E_CPU1_PE0_RX_DN<7>")
	)
	(segment
		(start 83.107276 -213.722966)
		(end 90.00363 -211.646008)
		(width 0.14732)
		(layer "In13.Cu")
		(net "P5E_CPU1_PE0_RX_DN<7>")
	)
	(segment
		(start 95.467678 -216.569798)
		(end 95.476568 -216.574878)
		(width 0.0889)
		(layer "In13.Cu")
		(net "P5E_CPU1_PE0_RX_DN<7>")
	)
	(segment
		(start 75.853544 -314.71743)
		(end 77.987398 -309.669434)
		(width 0.14732)
		(layer "In13.Cu")
		(net "P5E_CPU1_PE0_RX_DN<7>")
	)
	(segment
		(start 90.00363 -211.646008)
		(end 93.796612 -211.646008)
		(width 0.14732)
		(layer "In13.Cu")
		(net "P5E_CPU1_PE0_RX_DN<7>")
	)
	(segment
		(start 95.467678 -218.197684)
		(end 95.476568 -218.202764)
		(width 0.0889)
		(layer "In13.Cu")
		(net "P5E_CPU1_PE0_RX_DN<7>")
	)
	(segment
		(start 74.680572 -437.308752)
		(end 74.680572 -424.925998)
		(width 0.14732)
		(layer "In13.Cu")
		(net "P5E_CPU1_PE0_RX_DN<7>")
	)
	(segment
		(start 95.467678 -219.825316)
		(end 95.476568 -219.830396)
		(width 0.0889)
		(layer "In13.Cu")
		(net "P5E_CPU1_PE0_RX_DN<7>")
	)
	(segment
		(start 75.502516 -437.59374)
		(end 74.96556 -437.59374)
		(width 0.14732)
		(layer "In13.Cu")
		(net "P5E_CPU1_PE0_RX_DN<7>")
	)
	(segment
		(start 75.65009 -438.089802)
		(end 75.65009 -437.741314)
		(width 0.14732)
		(layer "In13.Cu")
		(net "P5E_CPU1_PE0_RX_DN<7>")
	)
	(segment
		(start 74.680572 -424.925998)
		(end 72.594978 -410.662882)
		(width 0.14732)
		(layer "In13.Cu")
		(net "P5E_CPU1_PE0_RX_DN<7>")
	)
	(segment
		(start 75.85329 -314.71743)
		(end 75.853544 -314.71743)
		(width 0.14732)
		(layer "In13.Cu")
		(net "P5E_CPU1_PE0_RX_DN<7>")
	)
	(segment
		(start 95.00489 -215.7603)
		(end 95.006414 -215.761062)
		(width 0.0889)
		(layer "In13.Cu")
		(net "P5E_CPU1_PE0_RX_DN<7>")
	)
	(segment
		(start 95.758762 -218.676728)
		(end 95.758762 -218.707716)
		(width 0.0889)
		(layer "In13.Cu")
		(net "P5E_CPU1_PE0_RX_DN<7>")
	)
	(segment
		(start 94.600268 -212.183726)
		(end 94.861126 -212.8139)
		(width 0.14732)
		(layer "In13.Cu")
		(net "P5E_CPU1_PE0_RX_DN<7>")
	)
	(segment
		(start 95.006414 -215.761062)
		(end 95.009208 -215.762586)
		(width 0.0889)
		(layer "In13.Cu")
		(net "P5E_CPU1_PE0_RX_DN<7>")
	)
	(segment
		(start 73.719944 -319.764664)
		(end 75.85329 -314.71743)
		(width 0.14732)
		(layer "In13.Cu")
		(net "P5E_CPU1_PE0_RX_DN<7>")
	)
	(segment
		(start 72.594978 -410.662882)
		(end 72.594978 -406.19934)
		(width 0.14732)
		(layer "In13.Cu")
		(net "P5E_CPU1_PE0_RX_DN<7>")
	)
	(segment
		(start 95.89897 -220.6117)
		(end 95.976948 -220.590872)
		(width 0.0889)
		(layer "In13.Cu")
		(net "P5E_CPU1_PE0_RX_DN<7>")
	)
	(segment
		(start 95.006414 -215.112346)
		(end 95.005398 -215.112854)
		(width 0.0889)
		(layer "In13.Cu")
		(net "P5E_CPU1_PE0_RX_DN<7>")
	)
	(segment
		(start 94.819216 -213.171278)
		(end 94.819216 -213.893908)
		(width 0.0889)
		(layer "In13.Cu")
		(net "P5E_CPU1_PE0_RX_DN<7>")
	)
	(segment
		(start 77.724762 -220.762576)
		(end 78.782672 -218.710256)
		(width 0.14732)
		(layer "In13.Cu")
		(net "P5E_CPU1_PE0_RX_DN<7>")
	)
	(segment
		(start 74.312018 -400.02079)
		(end 74.109072 -398.806416)
		(width 0.14732)
		(layer "In13.Cu")
		(net "P5E_CPU1_PE0_RX_DN<7>")
	)
	(segment
		(start 95.759016 -217.05443)
		(end 95.759016 -217.082878)
		(width 0.0889)
		(layer "In13.Cu")
		(net "P5E_CPU1_PE0_RX_DN<7>")
	)
	(segment
		(start 68.285868 -330.387198)
		(end 71.18858 -323.379084)
		(width 0.14732)
		(layer "In13.Cu")
		(net "P5E_CPU1_PE0_RX_DN<7>")
	)
	(segment
		(start 74.109072 -398.806162)
		(end 72.789034 -390.894316)
		(width 0.14732)
		(layer "In13.Cu")
		(net "P5E_CPU1_PE0_RX_DN<7>")
	)
	(segment
		(start 94.861126 -213.10727)
		(end 94.861126 -213.129368)
		(width 0.0889)
		(layer "In13.Cu")
		(net "P5E_CPU1_PE0_RX_DN<7>")
	)
	(segment
		(start 95.475552 -219.182188)
		(end 95.467678 -219.18676)
		(width 0.0889)
		(layer "In13.Cu")
		(net "P5E_CPU1_PE0_RX_DN<7>")
	)
	(segment
		(start 78.782672 -218.710256)
		(end 81.882742 -214.726774)
		(width 0.14732)
		(layer "In13.Cu")
		(net "P5E_CPU1_PE0_RX_DN<7>")
	)
	(segment
		(start 74.30389 -250.481846)
		(end 75.806554 -233.117898)
		(width 0.14732)
		(layer "In13.Cu")
		(net "P5E_CPU1_PE0_RX_DN<7>")
	)
	(arc
		(start 95.467678 -217.559128)
		(mid 95.339785 -217.69019)
		(end 95.28937 -217.866214)
		(width 0.0889)
		(layer "In13.Cu")
		(net "P5E_CPU1_PE0_RX_DN<7>")
	)
	(arc
		(start 95.28937 -217.866214)
		(mid 95.289203 -217.87739)
		(end 95.28937 -217.888566)
		(width 0.0889)
		(layer "In13.Cu")
		(net "P5E_CPU1_PE0_RX_DN<7>")
	)
	(arc
		(start 95.476568 -219.830396)
		(mid 95.680903 -220.033001)
		(end 95.759016 -220.309948)
		(width 0.0889)
		(layer "In13.Cu")
		(net "P5E_CPU1_PE0_RX_DN<7>")
	)
	(arc
		(start 94.818962 -215.436704)
		(mid 94.866641 -215.619604)
		(end 94.997524 -215.755982)
		(width 0.0889)
		(layer "In13.Cu")
		(net "P5E_CPU1_PE0_RX_DN<7>")
	)
	(arc
		(start 95.758762 -218.707716)
		(mid 95.679392 -218.98145)
		(end 95.476568 -219.18168)
		(width 0.0889)
		(layer "In13.Cu")
		(net "P5E_CPU1_PE0_RX_DN<7>")
	)
	(arc
		(start 95.003366 -214.093298)
		(mid 95.177329 -214.232062)
		(end 95.288608 -214.424768)
		(width 0.0889)
		(layer "In13.Cu")
		(net "P5E_CPU1_PE0_RX_DN<7>")
	)
	(arc
		(start 95.759016 -217.082878)
		(mid 95.678854 -217.355067)
		(end 95.476568 -217.554048)
		(width 0.0889)
		(layer "In13.Cu")
		(net "P5E_CPU1_PE0_RX_DN<7>")
	)
	(arc
		(start 95.28937 -217.888566)
		(mid 95.339385 -218.065697)
		(end 95.467678 -218.197684)
		(width 0.0889)
		(layer "In13.Cu")
		(net "P5E_CPU1_PE0_RX_DN<7>")
	)
	(arc
		(start 95.289116 -219.512642)
		(mid 95.338369 -219.691842)
		(end 95.467678 -219.825316)
		(width 0.0889)
		(layer "In13.Cu")
		(net "P5E_CPU1_PE0_RX_DN<7>")
	)
	(arc
		(start 95.01251 -215.764618)
		(mid 95.215097 -215.970969)
		(end 95.289116 -216.25052)
		(width 0.0889)
		(layer "In13.Cu")
		(net "P5E_CPU1_PE0_RX_DN<7>")
	)
	(arc
		(start 95.476568 -216.574878)
		(mid 95.680903 -216.777483)
		(end 95.759016 -217.05443)
		(width 0.0889)
		(layer "In13.Cu")
		(net "P5E_CPU1_PE0_RX_DN<7>")
	)
	(arc
		(start 95.289116 -216.25052)
		(mid 95.336795 -216.43342)
		(end 95.467678 -216.569798)
		(width 0.0889)
		(layer "In13.Cu")
		(net "P5E_CPU1_PE0_RX_DN<7>")
	)
	(arc
		(start 95.467678 -219.18676)
		(mid 95.339274 -219.318705)
		(end 95.289116 -219.495878)
		(width 0.0889)
		(layer "In13.Cu")
		(net "P5E_CPU1_PE0_RX_DN<7>")
	)
	(arc
		(start 95.289116 -219.495878)
		(mid 95.289022 -219.50426)
		(end 95.289116 -219.512642)
		(width 0.0889)
		(layer "In13.Cu")
		(net "P5E_CPU1_PE0_RX_DN<7>")
	)
	(arc
		(start 94.819216 -215.421972)
		(mid 94.819019 -215.429337)
		(end 94.818962 -215.436704)
		(width 0.0889)
		(layer "In13.Cu")
		(net "P5E_CPU1_PE0_RX_DN<7>")
	)
	(arc
		(start 94.997524 -215.117426)
		(mid 94.87027 -215.247392)
		(end 94.819216 -215.421972)
		(width 0.0889)
		(layer "In13.Cu")
		(net "P5E_CPU1_PE0_RX_DN<7>")
	)
	(arc
		(start 94.819216 -213.893908)
		(mid 94.894221 -214.009367)
		(end 95.003366 -214.093298)
		(width 0.0889)
		(layer "In13.Cu")
		(net "P5E_CPU1_PE0_RX_DN<7>")
	)
	(arc
		(start 95.288608 -214.644732)
		(mid 95.207697 -214.91486)
		(end 95.006414 -215.112346)
		(width 0.0889)
		(layer "In13.Cu")
		(net "P5E_CPU1_PE0_RX_DN<7>")
	)
	(arc
		(start 95.476568 -218.202764)
		(mid 95.679391 -218.402995)
		(end 95.758762 -218.676728)
		(width 0.0889)
		(layer "In13.Cu")
		(net "P5E_CPU1_PE0_RX_DN<7>")
	)
	(arc
		(start 95.759016 -220.32849)
		(mid 95.79769 -220.485558)
		(end 95.89897 -220.6117)
		(width 0.0889)
		(layer "In13.Cu")
		(net "P5E_CPU1_PE0_RX_DN<7>")
	)
	(segment
		(start 94.723712 -221.134178)
		(end 94.723966 -221.133924)
		(width 0.13208)
		(layer "F.Cu")
		(net "P5E_CPU1_PE0_RX_DN<6>")
	)
	(segment
		(start 94.723712 -221.669864)
		(end 94.723712 -221.134178)
		(width 0.13208)
		(layer "F.Cu")
		(net "P5E_CPU1_PE0_RX_DN<6>")
	)
	(segment
		(start 69.996558 -351.781618)
		(end 69.22008 -346.880434)
		(width 0.14732)
		(layer "In13.Cu")
		(net "P5E_CPU1_PE0_RX_DN<6>")
	)
	(segment
		(start 94.527878 -219.825316)
		(end 94.536768 -219.830396)
		(width 0.0889)
		(layer "In13.Cu")
		(net "P5E_CPU1_PE0_RX_DN<6>")
	)
	(segment
		(start 94.536768 -219.18168)
		(end 94.535752 -219.182188)
		(width 0.0889)
		(layer "In13.Cu")
		(net "P5E_CPU1_PE0_RX_DN<6>")
	)
	(segment
		(start 94.536768 -220.809566)
		(end 94.535752 -220.810074)
		(width 0.0889)
		(layer "In13.Cu")
		(net "P5E_CPU1_PE0_RX_DN<6>")
	)
	(segment
		(start 69.22008 -330.621386)
		(end 71.984616 -323.948044)
		(width 0.14732)
		(layer "In13.Cu")
		(net "P5E_CPU1_PE0_RX_DN<6>")
	)
	(segment
		(start 94.066614 -215.112346)
		(end 94.065598 -215.112854)
		(width 0.0889)
		(layer "In13.Cu")
		(net "P5E_CPU1_PE0_RX_DN<6>")
	)
	(segment
		(start 94.536768 -217.554048)
		(end 94.535752 -217.554556)
		(width 0.0889)
		(layer "In13.Cu")
		(net "P5E_CPU1_PE0_RX_DN<6>")
	)
	(segment
		(start 76.680822 -438.30875)
		(end 76.680822 -424.010836)
		(width 0.14732)
		(layer "In13.Cu")
		(net "P5E_CPU1_PE0_RX_DN<6>")
	)
	(segment
		(start 71.984616 -323.948044)
		(end 74.483976 -320.378328)
		(width 0.14732)
		(layer "In13.Cu")
		(net "P5E_CPU1_PE0_RX_DN<6>")
	)
	(segment
		(start 76.680822 -424.010836)
		(end 75.865228 -411.899862)
		(width 0.14732)
		(layer "In13.Cu")
		(net "P5E_CPU1_PE0_RX_DN<6>")
	)
	(segment
		(start 75.229974 -250.64466)
		(end 76.747878 -233.167174)
		(width 0.14732)
		(layer "In13.Cu")
		(net "P5E_CPU1_PE0_RX_DN<6>")
	)
	(segment
		(start 82.558128 -215.385142)
		(end 83.370928 -214.7189)
		(width 0.14732)
		(layer "In13.Cu")
		(net "P5E_CPU1_PE0_RX_DN<6>")
	)
	(segment
		(start 77.375258 -398.951958)
		(end 70.556882 -354.57257)
		(width 0.14732)
		(layer "In13.Cu")
		(net "P5E_CPU1_PE0_RX_DN<6>")
	)
	(segment
		(start 77.650086 -439.0898)
		(end 77.650086 -438.741312)
		(width 0.14732)
		(layer "In13.Cu")
		(net "P5E_CPU1_PE0_RX_DN<6>")
	)
	(segment
		(start 94.06509 -215.7603)
		(end 94.066614 -215.761062)
		(width 0.0889)
		(layer "In13.Cu")
		(net "P5E_CPU1_PE0_RX_DN<6>")
	)
	(segment
		(start 77.375258 -404.4823)
		(end 77.375258 -398.951958)
		(width 0.14732)
		(layer "In13.Cu")
		(net "P5E_CPU1_PE0_RX_DN<6>")
	)
	(segment
		(start 75.658218 -406.19934)
		(end 77.375258 -404.4823)
		(width 0.14732)
		(layer "In13.Cu")
		(net "P5E_CPU1_PE0_RX_DN<6>")
	)
	(segment
		(start 94.818962 -218.676728)
		(end 94.818962 -218.707716)
		(width 0.0889)
		(layer "In13.Cu")
		(net "P5E_CPU1_PE0_RX_DN<6>")
	)
	(segment
		(start 83.370928 -214.7189)
		(end 90.4621 -212.583268)
		(width 0.14732)
		(layer "In13.Cu")
		(net "P5E_CPU1_PE0_RX_DN<6>")
	)
	(segment
		(start 74.483976 -320.378328)
		(end 78.954884 -309.83555)
		(width 0.14732)
		(layer "In13.Cu")
		(net "P5E_CPU1_PE0_RX_DN<6>")
	)
	(segment
		(start 76.96581 -438.593738)
		(end 76.680822 -438.30875)
		(width 0.14732)
		(layer "In13.Cu")
		(net "P5E_CPU1_PE0_RX_DN<6>")
	)
	(segment
		(start 94.348808 -214.424768)
		(end 94.348808 -214.644732)
		(width 0.0889)
		(layer "In13.Cu")
		(net "P5E_CPU1_PE0_RX_DN<6>")
	)
	(segment
		(start 79.57693 -219.216478)
		(end 82.558128 -215.385142)
		(width 0.14732)
		(layer "In13.Cu")
		(net "P5E_CPU1_PE0_RX_DN<6>")
	)
	(segment
		(start 90.4621 -212.583268)
		(end 93.606112 -212.583268)
		(width 0.14732)
		(layer "In13.Cu")
		(net "P5E_CPU1_PE0_RX_DN<6>")
	)
	(segment
		(start 93.879416 -213.190328)
		(end 93.879416 -213.893908)
		(width 0.0889)
		(layer "In13.Cu")
		(net "P5E_CPU1_PE0_RX_DN<6>")
	)
	(segment
		(start 94.859348 -221.48292)
		(end 94.88043 -221.404942)
		(width 0.0889)
		(layer "In13.Cu")
		(net "P5E_CPU1_PE0_RX_DN<6>")
	)
	(segment
		(start 77.502512 -438.593738)
		(end 76.96581 -438.593738)
		(width 0.14732)
		(layer "In13.Cu")
		(net "P5E_CPU1_PE0_RX_DN<6>")
	)
	(segment
		(start 78.627986 -221.056962)
		(end 79.57693 -219.216478)
		(width 0.14732)
		(layer "In13.Cu")
		(net "P5E_CPU1_PE0_RX_DN<6>")
	)
	(segment
		(start 93.921326 -213.12632)
		(end 93.921326 -213.148418)
		(width 0.0889)
		(layer "In13.Cu")
		(net "P5E_CPU1_PE0_RX_DN<6>")
	)
	(segment
		(start 78.954884 -309.83555)
		(end 75.186286 -251.942346)
		(width 0.14732)
		(layer "In13.Cu")
		(net "P5E_CPU1_PE0_RX_DN<6>")
	)
	(segment
		(start 94.066614 -215.761062)
		(end 94.069408 -215.762586)
		(width 0.0889)
		(layer "In13.Cu")
		(net "P5E_CPU1_PE0_RX_DN<6>")
	)
	(segment
		(start 94.88043 -221.404942)
		(end 94.723966 -221.133924)
		(width 0.0889)
		(layer "In13.Cu")
		(net "P5E_CPU1_PE0_RX_DN<6>")
	)
	(segment
		(start 76.747878 -233.167174)
		(end 78.627986 -221.056962)
		(width 0.14732)
		(layer "In13.Cu")
		(net "P5E_CPU1_PE0_RX_DN<6>")
	)
	(segment
		(start 93.606112 -212.583268)
		(end 93.921326 -212.898482)
		(width 0.14732)
		(layer "In13.Cu")
		(net "P5E_CPU1_PE0_RX_DN<6>")
	)
	(segment
		(start 94.057724 -215.755982)
		(end 94.06509 -215.7603)
		(width 0.0889)
		(layer "In13.Cu")
		(net "P5E_CPU1_PE0_RX_DN<6>")
	)
	(segment
		(start 93.921326 -212.898482)
		(end 93.921326 -213.12632)
		(width 0.14732)
		(layer "In13.Cu")
		(net "P5E_CPU1_PE0_RX_DN<6>")
	)
	(segment
		(start 75.186286 -251.942346)
		(end 75.229974 -250.64466)
		(width 0.14732)
		(layer "In13.Cu")
		(net "P5E_CPU1_PE0_RX_DN<6>")
	)
	(segment
		(start 94.069408 -215.762586)
		(end 94.07271 -215.764618)
		(width 0.0889)
		(layer "In13.Cu")
		(net "P5E_CPU1_PE0_RX_DN<6>")
	)
	(segment
		(start 94.535752 -220.810074)
		(end 94.527878 -220.814646)
		(width 0.0889)
		(layer "In13.Cu")
		(net "P5E_CPU1_PE0_RX_DN<6>")
	)
	(segment
		(start 93.921326 -213.148418)
		(end 93.879416 -213.190328)
		(width 0.0889)
		(layer "In13.Cu")
		(net "P5E_CPU1_PE0_RX_DN<6>")
	)
	(segment
		(start 70.556882 -354.57257)
		(end 69.996558 -351.781618)
		(width 0.14732)
		(layer "In13.Cu")
		(net "P5E_CPU1_PE0_RX_DN<6>")
	)
	(segment
		(start 94.536768 -219.830396)
		(end 94.542864 -219.833952)
		(width 0.0889)
		(layer "In13.Cu")
		(net "P5E_CPU1_PE0_RX_DN<6>")
	)
	(segment
		(start 94.535752 -219.182188)
		(end 94.527878 -219.18676)
		(width 0.0889)
		(layer "In13.Cu")
		(net "P5E_CPU1_PE0_RX_DN<6>")
	)
	(segment
		(start 94.527878 -216.569798)
		(end 94.536768 -216.574878)
		(width 0.0889)
		(layer "In13.Cu")
		(net "P5E_CPU1_PE0_RX_DN<6>")
	)
	(segment
		(start 94.535752 -217.554556)
		(end 94.527878 -217.559128)
		(width 0.0889)
		(layer "In13.Cu")
		(net "P5E_CPU1_PE0_RX_DN<6>")
	)
	(segment
		(start 94.536768 -216.574878)
		(end 94.542864 -216.578434)
		(width 0.0889)
		(layer "In13.Cu")
		(net "P5E_CPU1_PE0_RX_DN<6>")
	)
	(segment
		(start 75.865228 -411.899862)
		(end 75.658218 -411.012386)
		(width 0.14732)
		(layer "In13.Cu")
		(net "P5E_CPU1_PE0_RX_DN<6>")
	)
	(segment
		(start 69.22008 -346.880434)
		(end 69.22008 -330.621386)
		(width 0.14732)
		(layer "In13.Cu")
		(net "P5E_CPU1_PE0_RX_DN<6>")
	)
	(segment
		(start 94.065598 -215.112854)
		(end 94.057724 -215.117426)
		(width 0.0889)
		(layer "In13.Cu")
		(net "P5E_CPU1_PE0_RX_DN<6>")
	)
	(segment
		(start 94.527878 -218.197684)
		(end 94.536768 -218.202764)
		(width 0.0889)
		(layer "In13.Cu")
		(net "P5E_CPU1_PE0_RX_DN<6>")
	)
	(segment
		(start 77.650086 -438.741312)
		(end 77.502512 -438.593738)
		(width 0.14732)
		(layer "In13.Cu")
		(net "P5E_CPU1_PE0_RX_DN<6>")
	)
	(segment
		(start 75.658218 -411.012386)
		(end 75.658218 -406.19934)
		(width 0.14732)
		(layer "In13.Cu")
		(net "P5E_CPU1_PE0_RX_DN<6>")
	)
	(arc
		(start 94.349316 -221.144084)
		(mid 94.516504 -221.445809)
		(end 94.859348 -221.48292)
		(width 0.0889)
		(layer "In13.Cu")
		(net "P5E_CPU1_PE0_RX_DN<6>")
	)
	(arc
		(start 93.879416 -215.421972)
		(mid 93.879219 -215.429337)
		(end 93.879162 -215.436704)
		(width 0.0889)
		(layer "In13.Cu")
		(net "P5E_CPU1_PE0_RX_DN<6>")
	)
	(arc
		(start 94.527878 -217.559128)
		(mid 94.400624 -217.689094)
		(end 94.34957 -217.863674)
		(width 0.0889)
		(layer "In13.Cu")
		(net "P5E_CPU1_PE0_RX_DN<6>")
	)
	(arc
		(start 94.34957 -217.863674)
		(mid 94.349237 -217.876118)
		(end 94.349316 -217.888566)
		(width 0.0889)
		(layer "In13.Cu")
		(net "P5E_CPU1_PE0_RX_DN<6>")
	)
	(arc
		(start 94.063566 -214.093298)
		(mid 94.237529 -214.232062)
		(end 94.348808 -214.424768)
		(width 0.0889)
		(layer "In13.Cu")
		(net "P5E_CPU1_PE0_RX_DN<6>")
	)
	(arc
		(start 94.542864 -219.833952)
		(mid 94.819178 -220.323446)
		(end 94.536768 -220.809566)
		(width 0.0889)
		(layer "In13.Cu")
		(net "P5E_CPU1_PE0_RX_DN<6>")
	)
	(arc
		(start 94.34957 -221.119192)
		(mid 94.349236 -221.131636)
		(end 94.349316 -221.144084)
		(width 0.0889)
		(layer "In13.Cu")
		(net "P5E_CPU1_PE0_RX_DN<6>")
	)
	(arc
		(start 93.879416 -213.893908)
		(mid 93.954421 -214.009367)
		(end 94.063566 -214.093298)
		(width 0.0889)
		(layer "In13.Cu")
		(net "P5E_CPU1_PE0_RX_DN<6>")
	)
	(arc
		(start 94.527878 -219.18676)
		(mid 94.349402 -219.506038)
		(end 94.527878 -219.825316)
		(width 0.0889)
		(layer "In13.Cu")
		(net "P5E_CPU1_PE0_RX_DN<6>")
	)
	(arc
		(start 94.536768 -218.202764)
		(mid 94.739591 -218.402995)
		(end 94.818962 -218.676728)
		(width 0.0889)
		(layer "In13.Cu")
		(net "P5E_CPU1_PE0_RX_DN<6>")
	)
	(arc
		(start 94.349316 -216.25052)
		(mid 94.396995 -216.43342)
		(end 94.527878 -216.569798)
		(width 0.0889)
		(layer "In13.Cu")
		(net "P5E_CPU1_PE0_RX_DN<6>")
	)
	(arc
		(start 94.348808 -214.644732)
		(mid 94.267897 -214.91486)
		(end 94.066614 -215.112346)
		(width 0.0889)
		(layer "In13.Cu")
		(net "P5E_CPU1_PE0_RX_DN<6>")
	)
	(arc
		(start 94.07271 -215.764618)
		(mid 94.275297 -215.970969)
		(end 94.349316 -216.25052)
		(width 0.0889)
		(layer "In13.Cu")
		(net "P5E_CPU1_PE0_RX_DN<6>")
	)
	(arc
		(start 94.542864 -216.578434)
		(mid 94.819178 -217.067928)
		(end 94.536768 -217.554048)
		(width 0.0889)
		(layer "In13.Cu")
		(net "P5E_CPU1_PE0_RX_DN<6>")
	)
	(arc
		(start 94.818962 -218.707716)
		(mid 94.739592 -218.98145)
		(end 94.536768 -219.18168)
		(width 0.0889)
		(layer "In13.Cu")
		(net "P5E_CPU1_PE0_RX_DN<6>")
	)
	(arc
		(start 94.057724 -215.117426)
		(mid 93.93047 -215.247392)
		(end 93.879416 -215.421972)
		(width 0.0889)
		(layer "In13.Cu")
		(net "P5E_CPU1_PE0_RX_DN<6>")
	)
	(arc
		(start 93.879162 -215.436704)
		(mid 93.926841 -215.619604)
		(end 94.057724 -215.755982)
		(width 0.0889)
		(layer "In13.Cu")
		(net "P5E_CPU1_PE0_RX_DN<6>")
	)
	(arc
		(start 94.349316 -217.888566)
		(mid 94.399385 -218.065791)
		(end 94.527878 -218.197684)
		(width 0.0889)
		(layer "In13.Cu")
		(net "P5E_CPU1_PE0_RX_DN<6>")
	)
	(arc
		(start 94.527878 -220.814646)
		(mid 94.400542 -220.944581)
		(end 94.34957 -221.119192)
		(width 0.0889)
		(layer "In13.Cu")
		(net "P5E_CPU1_PE0_RX_DN<6>")
	)
	(segment
		(start 94.253812 -220.85554)
		(end 94.253812 -220.319854)
		(width 0.13208)
		(layer "F.Cu")
		(net "P5E_CPU1_PE0_RX_DN<5>")
	)
	(segment
		(start 94.254066 -220.855794)
		(end 94.253812 -220.85554)
		(width 0.13208)
		(layer "F.Cu")
		(net "P5E_CPU1_PE0_RX_DN<5>")
	)
	(segment
		(start 77.93609 -244.770656)
		(end 77.935836 -244.770656)
		(width 0.14732)
		(layer "In13.Cu")
		(net "P5E_CPU1_PE0_RX_DN<5>")
	)
	(segment
		(start 93.879162 -218.676728)
		(end 93.879162 -218.707716)
		(width 0.0889)
		(layer "In13.Cu")
		(net "P5E_CPU1_PE0_RX_DN<5>")
	)
	(segment
		(start 88.887046 -214.940896)
		(end 88.89746 -214.946992)
		(width 0.0889)
		(layer "In13.Cu")
		(net "P5E_CPU1_PE0_RX_DN<5>")
	)
	(segment
		(start 77.728572 -233.62031)
		(end 77.731874 -233.572812)
		(width 0.14732)
		(layer "In13.Cu")
		(net "P5E_CPU1_PE0_RX_DN<5>")
	)
	(segment
		(start 93.879416 -217.05443)
		(end 93.879416 -217.082878)
		(width 0.0889)
		(layer "In13.Cu")
		(net "P5E_CPU1_PE0_RX_DN<5>")
	)
	(segment
		(start 80.10398 -250.705112)
		(end 78.47584 -247.664224)
		(width 0.14732)
		(layer "In13.Cu")
		(net "P5E_CPU1_PE0_RX_DN<5>")
	)
	(segment
		(start 93.596968 -217.554048)
		(end 93.588078 -217.559128)
		(width 0.0889)
		(layer "In13.Cu")
		(net "P5E_CPU1_PE0_RX_DN<5>")
	)
	(segment
		(start 86.672928 -214.997792)
		(end 87.205312 -214.997792)
		(width 0.0889)
		(layer "In13.Cu")
		(net "P5E_CPU1_PE0_RX_DN<5>")
	)
	(segment
		(start 78.47584 -247.664224)
		(end 77.93609 -244.770656)
		(width 0.14732)
		(layer "In13.Cu")
		(net "P5E_CPU1_PE0_RX_DN<5>")
	)
	(segment
		(start 93.588078 -218.197684)
		(end 93.596968 -218.202764)
		(width 0.0889)
		(layer "In13.Cu")
		(net "P5E_CPU1_PE0_RX_DN<5>")
	)
	(segment
		(start 89.358724 -215.755982)
		(end 89.367614 -215.761062)
		(width 0.0889)
		(layer "In13.Cu")
		(net "P5E_CPU1_PE0_RX_DN<5>")
	)
	(segment
		(start 77.854302 -258.6736)
		(end 80.371188 -252.217174)
		(width 0.14732)
		(layer "In13.Cu")
		(net "P5E_CPU1_PE0_RX_DN<5>")
	)
	(segment
		(start 93.588078 -219.825316)
		(end 93.596968 -219.830396)
		(width 0.0889)
		(layer "In13.Cu")
		(net "P5E_CPU1_PE0_RX_DN<5>")
	)
	(segment
		(start 93.596968 -219.18168)
		(end 93.595952 -219.182188)
		(width 0.0889)
		(layer "In13.Cu")
		(net "P5E_CPU1_PE0_RX_DN<5>")
	)
	(segment
		(start 80.371188 -252.217174)
		(end 80.37195 -252.217428)
		(width 0.14732)
		(layer "In13.Cu")
		(net "P5E_CPU1_PE0_RX_DN<5>")
	)
	(segment
		(start 78.721458 -406.19934)
		(end 80.438498 -404.4823)
		(width 0.14732)
		(layer "In13.Cu")
		(net "P5E_CPU1_PE0_RX_DN<5>")
	)
	(segment
		(start 79.650082 -437.741314)
		(end 79.502508 -437.59374)
		(width 0.14732)
		(layer "In13.Cu")
		(net "P5E_CPU1_PE0_RX_DN<5>")
	)
	(segment
		(start 78.680818 -424.392852)
		(end 78.721458 -421.181784)
		(width 0.14732)
		(layer "In13.Cu")
		(net "P5E_CPU1_PE0_RX_DN<5>")
	)
	(segment
		(start 80.37195 -251.351542)
		(end 80.10398 -250.705112)
		(width 0.14732)
		(layer "In13.Cu")
		(net "P5E_CPU1_PE0_RX_DN<5>")
	)
	(segment
		(start 77.853794 -258.6736)
		(end 77.854302 -258.6736)
		(width 0.14732)
		(layer "In13.Cu")
		(net "P5E_CPU1_PE0_RX_DN<5>")
	)
	(segment
		(start 72.0598 -355.931978)
		(end 70.931278 -351.51314)
		(width 0.14732)
		(layer "In13.Cu")
		(net "P5E_CPU1_PE0_RX_DN<5>")
	)
	(segment
		(start 80.48625 -219.752672)
		(end 83.357212 -216.067386)
		(width 0.14732)
		(layer "In13.Cu")
		(net "P5E_CPU1_PE0_RX_DN<5>")
	)
	(segment
		(start 77.935836 -244.770656)
		(end 77.931772 -244.748304)
		(width 0.14732)
		(layer "In13.Cu")
		(net "P5E_CPU1_PE0_RX_DN<5>")
	)
	(segment
		(start 79.65948 -221.364302)
		(end 80.48625 -219.752672)
		(width 0.14732)
		(layer "In13.Cu")
		(net "P5E_CPU1_PE0_RX_DN<5>")
	)
	(segment
		(start 78.680818 -437.308752)
		(end 78.680818 -424.392852)
		(width 0.14732)
		(layer "In13.Cu")
		(net "P5E_CPU1_PE0_RX_DN<5>")
	)
	(segment
		(start 94.01937 -220.6117)
		(end 94.097348 -220.590872)
		(width 0.0889)
		(layer "In13.Cu")
		(net "P5E_CPU1_PE0_RX_DN<5>")
	)
	(segment
		(start 93.588078 -216.569798)
		(end 93.596968 -216.574878)
		(width 0.0889)
		(layer "In13.Cu")
		(net "P5E_CPU1_PE0_RX_DN<5>")
	)
	(segment
		(start 85.775292 -214.955882)
		(end 86.60892 -214.955882)
		(width 0.14732)
		(layer "In13.Cu")
		(net "P5E_CPU1_PE0_RX_DN<5>")
	)
	(segment
		(start 93.112082 -215.752426)
		(end 93.111574 -215.752426)
		(width 0.0889)
		(layer "In13.Cu")
		(net "P5E_CPU1_PE0_RX_DN<5>")
	)
	(segment
		(start 93.595952 -219.182188)
		(end 93.588078 -219.18676)
		(width 0.0889)
		(layer "In13.Cu")
		(net "P5E_CPU1_PE0_RX_DN<5>")
	)
	(segment
		(start 93.879416 -220.309948)
		(end 93.879416 -220.32849)
		(width 0.0889)
		(layer "In13.Cu")
		(net "P5E_CPU1_PE0_RX_DN<5>")
	)
	(segment
		(start 86.60892 -214.955882)
		(end 86.631018 -214.955882)
		(width 0.0889)
		(layer "In13.Cu")
		(net "P5E_CPU1_PE0_RX_DN<5>")
	)
	(segment
		(start 78.965806 -437.59374)
		(end 78.680818 -437.308752)
		(width 0.14732)
		(layer "In13.Cu")
		(net "P5E_CPU1_PE0_RX_DN<5>")
	)
	(segment
		(start 80.438498 -399.23847)
		(end 72.0598 -355.931978)
		(width 0.14732)
		(layer "In13.Cu")
		(net "P5E_CPU1_PE0_RX_DN<5>")
	)
	(segment
		(start 94.097348 -220.590872)
		(end 94.253812 -220.319854)
		(width 0.0889)
		(layer "In13.Cu")
		(net "P5E_CPU1_PE0_RX_DN<5>")
	)
	(segment
		(start 93.111574 -215.752426)
		(end 93.13291 -215.764618)
		(width 0.0889)
		(layer "In13.Cu")
		(net "P5E_CPU1_PE0_RX_DN<5>")
	)
	(segment
		(start 83.357212 -216.067386)
		(end 83.858608 -215.623394)
		(width 0.14732)
		(layer "In13.Cu")
		(net "P5E_CPU1_PE0_RX_DN<5>")
	)
	(segment
		(start 90.292682 -215.752426)
		(end 90.307414 -215.761062)
		(width 0.0889)
		(layer "In13.Cu")
		(net "P5E_CPU1_PE0_RX_DN<5>")
	)
	(segment
		(start 70.18528 -346.80398)
		(end 70.18528 -330.958698)
		(width 0.14732)
		(layer "In13.Cu")
		(net "P5E_CPU1_PE0_RX_DN<5>")
	)
	(segment
		(start 79.650082 -438.089802)
		(end 79.650082 -437.741314)
		(width 0.14732)
		(layer "In13.Cu")
		(net "P5E_CPU1_PE0_RX_DN<5>")
	)
	(segment
		(start 87.392764 -214.946992)
		(end 87.403178 -214.940896)
		(width 0.0889)
		(layer "In13.Cu")
		(net "P5E_CPU1_PE0_RX_DN<5>")
	)
	(segment
		(start 80.37195 -252.217428)
		(end 80.37195 -251.351542)
		(width 0.14732)
		(layer "In13.Cu")
		(net "P5E_CPU1_PE0_RX_DN<5>")
	)
	(segment
		(start 70.931278 -351.51314)
		(end 70.18528 -346.80398)
		(width 0.14732)
		(layer "In13.Cu")
		(net "P5E_CPU1_PE0_RX_DN<5>")
	)
	(segment
		(start 91.232482 -215.752426)
		(end 91.247214 -215.761062)
		(width 0.0889)
		(layer "In13.Cu")
		(net "P5E_CPU1_PE0_RX_DN<5>")
	)
	(segment
		(start 77.931772 -244.748304)
		(end 77.728572 -233.62031)
		(width 0.14732)
		(layer "In13.Cu")
		(net "P5E_CPU1_PE0_RX_DN<5>")
	)
	(segment
		(start 75.417172 -320.696336)
		(end 79.907384 -310.027828)
		(width 0.14732)
		(layer "In13.Cu")
		(net "P5E_CPU1_PE0_RX_DN<5>")
	)
	(segment
		(start 77.141578 -266.592304)
		(end 77.853794 -258.6736)
		(width 0.14732)
		(layer "In13.Cu")
		(net "P5E_CPU1_PE0_RX_DN<5>")
	)
	(segment
		(start 86.631018 -214.955882)
		(end 86.672928 -214.997792)
		(width 0.0889)
		(layer "In13.Cu")
		(net "P5E_CPU1_PE0_RX_DN<5>")
	)
	(segment
		(start 79.907384 -310.027828)
		(end 77.141578 -266.592304)
		(width 0.14732)
		(layer "In13.Cu")
		(net "P5E_CPU1_PE0_RX_DN<5>")
	)
	(segment
		(start 77.731874 -233.572812)
		(end 79.65948 -221.364302)
		(width 0.14732)
		(layer "In13.Cu")
		(net "P5E_CPU1_PE0_RX_DN<5>")
	)
	(segment
		(start 70.18528 -330.958698)
		(end 73.015348 -324.126606)
		(width 0.14732)
		(layer "In13.Cu")
		(net "P5E_CPU1_PE0_RX_DN<5>")
	)
	(segment
		(start 79.502508 -437.59374)
		(end 78.965806 -437.59374)
		(width 0.14732)
		(layer "In13.Cu")
		(net "P5E_CPU1_PE0_RX_DN<5>")
	)
	(segment
		(start 92.172282 -215.752426)
		(end 92.187014 -215.761062)
		(width 0.0889)
		(layer "In13.Cu")
		(net "P5E_CPU1_PE0_RX_DN<5>")
	)
	(segment
		(start 78.721458 -421.181784)
		(end 78.721458 -406.19934)
		(width 0.14732)
		(layer "In13.Cu")
		(net "P5E_CPU1_PE0_RX_DN<5>")
	)
	(segment
		(start 83.858608 -215.623394)
		(end 85.775292 -214.955882)
		(width 0.14732)
		(layer "In13.Cu")
		(net "P5E_CPU1_PE0_RX_DN<5>")
	)
	(segment
		(start 80.438498 -404.4823)
		(end 80.438498 -399.23847)
		(width 0.14732)
		(layer "In13.Cu")
		(net "P5E_CPU1_PE0_RX_DN<5>")
	)
	(segment
		(start 73.015348 -324.126606)
		(end 75.417172 -320.696336)
		(width 0.14732)
		(layer "In13.Cu")
		(net "P5E_CPU1_PE0_RX_DN<5>")
	)
	(segment
		(start 89.180162 -215.42248)
		(end 89.180162 -215.436704)
		(width 0.0889)
		(layer "In13.Cu")
		(net "P5E_CPU1_PE0_RX_DN<5>")
	)
	(arc
		(start 93.409516 -216.25052)
		(mid 93.457195 -216.43342)
		(end 93.588078 -216.569798)
		(width 0.0889)
		(layer "In13.Cu")
		(net "P5E_CPU1_PE0_RX_DN<5>")
	)
	(arc
		(start 91.247214 -215.761062)
		(mid 91.434412 -215.811205)
		(end 91.62161 -215.761062)
		(width 0.0889)
		(layer "In13.Cu")
		(net "P5E_CPU1_PE0_RX_DN<5>")
	)
	(arc
		(start 92.56141 -215.761062)
		(mid 92.835609 -215.685227)
		(end 93.112082 -215.752426)
		(width 0.0889)
		(layer "In13.Cu")
		(net "P5E_CPU1_PE0_RX_DN<5>")
	)
	(arc
		(start 89.74201 -215.761062)
		(mid 90.016209 -215.685227)
		(end 90.292682 -215.752426)
		(width 0.0889)
		(layer "In13.Cu")
		(net "P5E_CPU1_PE0_RX_DN<5>")
	)
	(arc
		(start 93.40977 -217.888566)
		(mid 93.459785 -218.065697)
		(end 93.588078 -218.197684)
		(width 0.0889)
		(layer "In13.Cu")
		(net "P5E_CPU1_PE0_RX_DN<5>")
	)
	(arc
		(start 91.62161 -215.761062)
		(mid 91.895809 -215.685227)
		(end 92.172282 -215.752426)
		(width 0.0889)
		(layer "In13.Cu")
		(net "P5E_CPU1_PE0_RX_DN<5>")
	)
	(arc
		(start 89.367614 -215.761062)
		(mid 89.554812 -215.811205)
		(end 89.74201 -215.761062)
		(width 0.0889)
		(layer "In13.Cu")
		(net "P5E_CPU1_PE0_RX_DN<5>")
	)
	(arc
		(start 93.40977 -217.866214)
		(mid 93.409603 -217.87739)
		(end 93.40977 -217.888566)
		(width 0.0889)
		(layer "In13.Cu")
		(net "P5E_CPU1_PE0_RX_DN<5>")
	)
	(arc
		(start 87.957914 -214.946992)
		(mid 88.145112 -214.997135)
		(end 88.33231 -214.946992)
		(width 0.0889)
		(layer "In13.Cu")
		(net "P5E_CPU1_PE0_RX_DN<5>")
	)
	(arc
		(start 90.307414 -215.761062)
		(mid 90.494612 -215.811205)
		(end 90.68181 -215.761062)
		(width 0.0889)
		(layer "In13.Cu")
		(net "P5E_CPU1_PE0_RX_DN<5>")
	)
	(arc
		(start 93.596968 -219.830396)
		(mid 93.801303 -220.033001)
		(end 93.879416 -220.309948)
		(width 0.0889)
		(layer "In13.Cu")
		(net "P5E_CPU1_PE0_RX_DN<5>")
	)
	(arc
		(start 93.879416 -217.082878)
		(mid 93.799254 -217.355067)
		(end 93.596968 -217.554048)
		(width 0.0889)
		(layer "In13.Cu")
		(net "P5E_CPU1_PE0_RX_DN<5>")
	)
	(arc
		(start 93.409516 -219.512642)
		(mid 93.458769 -219.691842)
		(end 93.588078 -219.825316)
		(width 0.0889)
		(layer "In13.Cu")
		(net "P5E_CPU1_PE0_RX_DN<5>")
	)
	(arc
		(start 93.879416 -220.32849)
		(mid 93.91809 -220.485558)
		(end 94.01937 -220.6117)
		(width 0.0889)
		(layer "In13.Cu")
		(net "P5E_CPU1_PE0_RX_DN<5>")
	)
	(arc
		(start 88.33231 -214.946992)
		(mid 88.608869 -214.871283)
		(end 88.887046 -214.940896)
		(width 0.0889)
		(layer "In13.Cu")
		(net "P5E_CPU1_PE0_RX_DN<5>")
	)
	(arc
		(start 93.879162 -218.707716)
		(mid 93.799792 -218.98145)
		(end 93.596968 -219.18168)
		(width 0.0889)
		(layer "In13.Cu")
		(net "P5E_CPU1_PE0_RX_DN<5>")
	)
	(arc
		(start 87.205312 -214.997792)
		(mid 87.302382 -214.984735)
		(end 87.392764 -214.946992)
		(width 0.0889)
		(layer "In13.Cu")
		(net "P5E_CPU1_PE0_RX_DN<5>")
	)
	(arc
		(start 93.409516 -219.495878)
		(mid 93.409422 -219.50426)
		(end 93.409516 -219.512642)
		(width 0.0889)
		(layer "In13.Cu")
		(net "P5E_CPU1_PE0_RX_DN<5>")
	)
	(arc
		(start 87.403178 -214.940896)
		(mid 87.681356 -214.871204)
		(end 87.957914 -214.946992)
		(width 0.0889)
		(layer "In13.Cu")
		(net "P5E_CPU1_PE0_RX_DN<5>")
	)
	(arc
		(start 89.180162 -215.436704)
		(mid 89.227841 -215.619604)
		(end 89.358724 -215.755982)
		(width 0.0889)
		(layer "In13.Cu")
		(net "P5E_CPU1_PE0_RX_DN<5>")
	)
	(arc
		(start 92.187014 -215.761062)
		(mid 92.374212 -215.811205)
		(end 92.56141 -215.761062)
		(width 0.0889)
		(layer "In13.Cu")
		(net "P5E_CPU1_PE0_RX_DN<5>")
	)
	(arc
		(start 88.89746 -214.946992)
		(mid 89.100941 -215.147796)
		(end 89.180162 -215.42248)
		(width 0.0889)
		(layer "In13.Cu")
		(net "P5E_CPU1_PE0_RX_DN<5>")
	)
	(arc
		(start 93.13291 -215.764618)
		(mid 93.335497 -215.970969)
		(end 93.409516 -216.25052)
		(width 0.0889)
		(layer "In13.Cu")
		(net "P5E_CPU1_PE0_RX_DN<5>")
	)
	(arc
		(start 93.596968 -218.202764)
		(mid 93.799791 -218.402995)
		(end 93.879162 -218.676728)
		(width 0.0889)
		(layer "In13.Cu")
		(net "P5E_CPU1_PE0_RX_DN<5>")
	)
	(arc
		(start 93.596968 -216.574878)
		(mid 93.801303 -216.777483)
		(end 93.879416 -217.05443)
		(width 0.0889)
		(layer "In13.Cu")
		(net "P5E_CPU1_PE0_RX_DN<5>")
	)
	(arc
		(start 93.588078 -217.559128)
		(mid 93.460185 -217.69019)
		(end 93.40977 -217.866214)
		(width 0.0889)
		(layer "In13.Cu")
		(net "P5E_CPU1_PE0_RX_DN<5>")
	)
	(arc
		(start 93.588078 -219.18676)
		(mid 93.459674 -219.318705)
		(end 93.409516 -219.495878)
		(width 0.0889)
		(layer "In13.Cu")
		(net "P5E_CPU1_PE0_RX_DN<5>")
	)
	(arc
		(start 90.68181 -215.761062)
		(mid 90.956009 -215.685227)
		(end 91.232482 -215.752426)
		(width 0.0889)
		(layer "In13.Cu")
		(net "P5E_CPU1_PE0_RX_DN<5>")
	)
	(segment
		(start 92.844112 -221.134178)
		(end 92.844366 -221.133924)
		(width 0.13208)
		(layer "F.Cu")
		(net "P5E_CPU1_PE0_RX_DN<4>")
	)
	(segment
		(start 92.844112 -221.669864)
		(end 92.844112 -221.134178)
		(width 0.13208)
		(layer "F.Cu")
		(net "P5E_CPU1_PE0_RX_DN<4>")
	)
	(segment
		(start 83.501738 -404.4823)
		(end 83.501738 -399.429732)
		(width 0.14732)
		(layer "In13.Cu")
		(net "P5E_CPU1_PE0_RX_DN<4>")
	)
	(segment
		(start 81.307432 -251.180092)
		(end 80.946244 -250.30811)
		(width 0.14732)
		(layer "In13.Cu")
		(net "P5E_CPU1_PE0_RX_DN<4>")
	)
	(segment
		(start 81.306924 -252.393196)
		(end 81.307432 -252.39345)
		(width 0.14732)
		(layer "In13.Cu")
		(net "P5E_CPU1_PE0_RX_DN<4>")
	)
	(segment
		(start 78.426564 -262.755888)
		(end 78.77429 -258.889754)
		(width 0.14732)
		(layer "In13.Cu")
		(net "P5E_CPU1_PE0_RX_DN<4>")
	)
	(segment
		(start 80.680814 -438.30875)
		(end 80.680814 -424.280584)
		(width 0.14732)
		(layer "In13.Cu")
		(net "P5E_CPU1_PE0_RX_DN<4>")
	)
	(segment
		(start 84.90712 -216.583514)
		(end 84.94903 -216.625424)
		(width 0.0889)
		(layer "In13.Cu")
		(net "P5E_CPU1_PE0_RX_DN<4>")
	)
	(segment
		(start 81.502504 -438.593738)
		(end 80.965802 -438.593738)
		(width 0.14732)
		(layer "In13.Cu")
		(net "P5E_CPU1_PE0_RX_DN<4>")
	)
	(segment
		(start 93.00083 -221.404942)
		(end 92.844366 -221.133924)
		(width 0.0889)
		(layer "In13.Cu")
		(net "P5E_CPU1_PE0_RX_DN<4>")
	)
	(segment
		(start 78.77429 -258.889754)
		(end 78.774544 -258.889754)
		(width 0.14732)
		(layer "In13.Cu")
		(net "P5E_CPU1_PE0_RX_DN<4>")
	)
	(segment
		(start 71.843392 -351.099628)
		(end 71.15048 -346.727526)
		(width 0.14732)
		(layer "In13.Cu")
		(net "P5E_CPU1_PE0_RX_DN<4>")
	)
	(segment
		(start 91.143328 -216.580212)
		(end 91.15171 -216.575386)
		(width 0.0889)
		(layer "In13.Cu")
		(net "P5E_CPU1_PE0_RX_DN<4>")
	)
	(segment
		(start 84.94903 -216.625424)
		(end 85.325712 -216.625424)
		(width 0.0889)
		(layer "In13.Cu")
		(net "P5E_CPU1_PE0_RX_DN<4>")
	)
	(segment
		(start 92.469462 -217.860626)
		(end 92.469462 -217.890852)
		(width 0.0889)
		(layer "In13.Cu")
		(net "P5E_CPU1_PE0_RX_DN<4>")
	)
	(segment
		(start 78.78953 -258.850892)
		(end 81.306924 -252.393196)
		(width 0.14732)
		(layer "In13.Cu")
		(net "P5E_CPU1_PE0_RX_DN<4>")
	)
	(segment
		(start 81.307432 -252.39345)
		(end 81.307432 -251.180092)
		(width 0.14732)
		(layer "In13.Cu")
		(net "P5E_CPU1_PE0_RX_DN<4>")
	)
	(segment
		(start 90.203274 -216.580212)
		(end 90.211656 -216.575386)
		(width 0.0889)
		(layer "In13.Cu")
		(net "P5E_CPU1_PE0_RX_DN<4>")
	)
	(segment
		(start 72.464676 -327.917556)
		(end 72.464676 -327.917302)
		(width 0.14732)
		(layer "In13.Cu")
		(net "P5E_CPU1_PE0_RX_DN<4>")
	)
	(segment
		(start 92.657676 -219.831158)
		(end 92.6592 -219.832174)
		(width 0.0889)
		(layer "In13.Cu")
		(net "P5E_CPU1_PE0_RX_DN<4>")
	)
	(segment
		(start 80.680814 -424.280584)
		(end 81.784698 -412.30296)
		(width 0.14732)
		(layer "In13.Cu")
		(net "P5E_CPU1_PE0_RX_DN<4>")
	)
	(segment
		(start 81.650078 -438.741312)
		(end 81.502504 -438.593738)
		(width 0.14732)
		(layer "In13.Cu")
		(net "P5E_CPU1_PE0_RX_DN<4>")
	)
	(segment
		(start 87.942928 -216.566242)
		(end 87.95766 -216.574878)
		(width 0.0889)
		(layer "In13.Cu")
		(net "P5E_CPU1_PE0_RX_DN<4>")
	)
	(segment
		(start 92.979748 -221.48292)
		(end 93.00083 -221.404942)
		(width 0.0889)
		(layer "In13.Cu")
		(net "P5E_CPU1_PE0_RX_DN<4>")
	)
	(segment
		(start 72.464676 -327.917302)
		(end 73.76922 -324.767448)
		(width 0.14732)
		(layer "In13.Cu")
		(net "P5E_CPU1_PE0_RX_DN<4>")
	)
	(segment
		(start 78.774544 -258.889754)
		(end 78.788514 -258.85394)
		(width 0.14732)
		(layer "In13.Cu")
		(net "P5E_CPU1_PE0_RX_DN<4>")
	)
	(segment
		(start 92.670122 -217.545666)
		(end 92.655644 -217.554048)
		(width 0.0889)
		(layer "In13.Cu")
		(net "P5E_CPU1_PE0_RX_DN<4>")
	)
	(segment
		(start 78.915514 -244.907054)
		(end 78.712822 -233.807508)
		(width 0.14732)
		(layer "In13.Cu")
		(net "P5E_CPU1_PE0_RX_DN<4>")
	)
	(segment
		(start 88.897968 -216.575386)
		(end 88.909906 -216.582498)
		(width 0.0889)
		(layer "In13.Cu")
		(net "P5E_CPU1_PE0_RX_DN<4>")
	)
	(segment
		(start 81.784698 -406.19934)
		(end 83.501738 -404.4823)
		(width 0.14732)
		(layer "In13.Cu")
		(net "P5E_CPU1_PE0_RX_DN<4>")
	)
	(segment
		(start 92.980002 -221.483682)
		(end 92.979748 -221.48292)
		(width 0.0889)
		(layer "In13.Cu")
		(net "P5E_CPU1_PE0_RX_DN<4>")
	)
	(segment
		(start 88.332056 -216.574878)
		(end 88.332564 -216.575132)
		(width 0.0889)
		(layer "In13.Cu")
		(net "P5E_CPU1_PE0_RX_DN<4>")
	)
	(segment
		(start 92.082874 -216.580212)
		(end 92.091256 -216.575386)
		(width 0.0889)
		(layer "In13.Cu")
		(net "P5E_CPU1_PE0_RX_DN<4>")
	)
	(segment
		(start 78.080108 -266.604496)
		(end 78.426564 -262.755888)
		(width 0.14732)
		(layer "In13.Cu")
		(net "P5E_CPU1_PE0_RX_DN<4>")
	)
	(segment
		(start 92.653104 -219.828618)
		(end 92.657676 -219.831158)
		(width 0.0889)
		(layer "In13.Cu")
		(net "P5E_CPU1_PE0_RX_DN<4>")
	)
	(segment
		(start 89.8271 -216.569036)
		(end 89.83726 -216.575132)
		(width 0.0889)
		(layer "In13.Cu")
		(net "P5E_CPU1_PE0_RX_DN<4>")
	)
	(segment
		(start 92.670122 -219.173552)
		(end 92.655644 -219.181934)
		(width 0.0889)
		(layer "In13.Cu")
		(net "P5E_CPU1_PE0_RX_DN<4>")
	)
	(segment
		(start 87.003128 -216.566242)
		(end 87.01786 -216.574878)
		(width 0.0889)
		(layer "In13.Cu")
		(net "P5E_CPU1_PE0_RX_DN<4>")
	)
	(segment
		(start 71.15048 -331.090016)
		(end 72.141334 -328.698098)
		(width 0.14732)
		(layer "In13.Cu")
		(net "P5E_CPU1_PE0_RX_DN<4>")
	)
	(segment
		(start 84.374228 -216.583514)
		(end 84.885022 -216.583514)
		(width 0.14732)
		(layer "In13.Cu")
		(net "P5E_CPU1_PE0_RX_DN<4>")
	)
	(segment
		(start 80.946244 -250.30811)
		(end 79.362808 -247.347486)
		(width 0.14732)
		(layer "In13.Cu")
		(net "P5E_CPU1_PE0_RX_DN<4>")
	)
	(segment
		(start 71.15048 -346.727526)
		(end 71.15048 -331.090016)
		(width 0.14732)
		(layer "In13.Cu")
		(net "P5E_CPU1_PE0_RX_DN<4>")
	)
	(segment
		(start 92.6592 -219.832174)
		(end 92.667582 -219.837)
		(width 0.0889)
		(layer "In13.Cu")
		(net "P5E_CPU1_PE0_RX_DN<4>")
	)
	(segment
		(start 78.788514 -258.85394)
		(end 78.78953 -258.850892)
		(width 0.14732)
		(layer "In13.Cu")
		(net "P5E_CPU1_PE0_RX_DN<4>")
	)
	(segment
		(start 80.673702 -221.647512)
		(end 81.379568 -220.349826)
		(width 0.14732)
		(layer "In13.Cu")
		(net "P5E_CPU1_PE0_RX_DN<4>")
	)
	(segment
		(start 73.183496 -355.828854)
		(end 71.843392 -351.099628)
		(width 0.14732)
		(layer "In13.Cu")
		(net "P5E_CPU1_PE0_RX_DN<4>")
	)
	(segment
		(start 81.650078 -439.0898)
		(end 81.650078 -438.741312)
		(width 0.14732)
		(layer "In13.Cu")
		(net "P5E_CPU1_PE0_RX_DN<4>")
	)
	(segment
		(start 84.885022 -216.583514)
		(end 84.90712 -216.583514)
		(width 0.0889)
		(layer "In13.Cu")
		(net "P5E_CPU1_PE0_RX_DN<4>")
	)
	(segment
		(start 78.712822 -233.807508)
		(end 80.673702 -221.647512)
		(width 0.14732)
		(layer "In13.Cu")
		(net "P5E_CPU1_PE0_RX_DN<4>")
	)
	(segment
		(start 81.379568 -220.349826)
		(end 84.076032 -216.881456)
		(width 0.14732)
		(layer "In13.Cu")
		(net "P5E_CPU1_PE0_RX_DN<4>")
	)
	(segment
		(start 76.244704 -321.23253)
		(end 80.860138 -310.267096)
		(width 0.14732)
		(layer "In13.Cu")
		(net "P5E_CPU1_PE0_RX_DN<4>")
	)
	(segment
		(start 86.063328 -216.566242)
		(end 86.07806 -216.574878)
		(width 0.0889)
		(layer "In13.Cu")
		(net "P5E_CPU1_PE0_RX_DN<4>")
	)
	(segment
		(start 92.652088 -219.82811)
		(end 92.653104 -219.828618)
		(width 0.0889)
		(layer "In13.Cu")
		(net "P5E_CPU1_PE0_RX_DN<4>")
	)
	(segment
		(start 84.076032 -216.881456)
		(end 84.374228 -216.583514)
		(width 0.14732)
		(layer "In13.Cu")
		(net "P5E_CPU1_PE0_RX_DN<4>")
	)
	(segment
		(start 92.651072 -218.199716)
		(end 92.658184 -218.20378)
		(width 0.0889)
		(layer "In13.Cu")
		(net "P5E_CPU1_PE0_RX_DN<4>")
	)
	(segment
		(start 80.965802 -438.593738)
		(end 80.680814 -438.30875)
		(width 0.14732)
		(layer "In13.Cu")
		(net "P5E_CPU1_PE0_RX_DN<4>")
	)
	(segment
		(start 72.141334 -328.698098)
		(end 72.464676 -327.917556)
		(width 0.14732)
		(layer "In13.Cu")
		(net "P5E_CPU1_PE0_RX_DN<4>")
	)
	(segment
		(start 92.469462 -221.116144)
		(end 92.469462 -221.14637)
		(width 0.0889)
		(layer "In13.Cu")
		(net "P5E_CPU1_PE0_RX_DN<4>")
	)
	(segment
		(start 81.784698 -412.30296)
		(end 81.784698 -406.19934)
		(width 0.14732)
		(layer "In13.Cu")
		(net "P5E_CPU1_PE0_RX_DN<4>")
	)
	(segment
		(start 79.362808 -247.347486)
		(end 78.915514 -244.907054)
		(width 0.14732)
		(layer "In13.Cu")
		(net "P5E_CPU1_PE0_RX_DN<4>")
	)
	(segment
		(start 89.83726 -216.575132)
		(end 89.837514 -216.575132)
		(width 0.0889)
		(layer "In13.Cu")
		(net "P5E_CPU1_PE0_RX_DN<4>")
	)
	(segment
		(start 80.860138 -310.267096)
		(end 78.080108 -266.604496)
		(width 0.14732)
		(layer "In13.Cu")
		(net "P5E_CPU1_PE0_RX_DN<4>")
	)
	(segment
		(start 92.658184 -218.20378)
		(end 92.670122 -218.210892)
		(width 0.0889)
		(layer "In13.Cu")
		(net "P5E_CPU1_PE0_RX_DN<4>")
	)
	(segment
		(start 73.76922 -324.767448)
		(end 76.244704 -321.23253)
		(width 0.14732)
		(layer "In13.Cu")
		(net "P5E_CPU1_PE0_RX_DN<4>")
	)
	(segment
		(start 83.501738 -399.429732)
		(end 73.183496 -355.828854)
		(width 0.14732)
		(layer "In13.Cu")
		(net "P5E_CPU1_PE0_RX_DN<4>")
	)
	(segment
		(start 92.670122 -220.801184)
		(end 92.655644 -220.809566)
		(width 0.0889)
		(layer "In13.Cu")
		(net "P5E_CPU1_PE0_RX_DN<4>")
	)
	(arc
		(start 92.469462 -221.14637)
		(mid 92.52275 -221.326743)
		(end 92.656914 -221.458536)
		(width 0.0889)
		(layer "In13.Cu")
		(net "P5E_CPU1_PE0_RX_DN<4>")
	)
	(arc
		(start 92.667582 -219.837)
		(mid 92.939078 -220.318373)
		(end 92.670122 -220.801184)
		(width 0.0889)
		(layer "In13.Cu")
		(net "P5E_CPU1_PE0_RX_DN<4>")
	)
	(arc
		(start 87.392256 -216.574878)
		(mid 87.666455 -216.499043)
		(end 87.942928 -216.566242)
		(width 0.0889)
		(layer "In13.Cu")
		(net "P5E_CPU1_PE0_RX_DN<4>")
	)
	(arc
		(start 92.469462 -217.890852)
		(mid 92.521036 -218.068341)
		(end 92.651072 -218.199716)
		(width 0.0889)
		(layer "In13.Cu")
		(net "P5E_CPU1_PE0_RX_DN<4>")
	)
	(arc
		(start 89.837514 -216.575132)
		(mid 90.019736 -216.625332)
		(end 90.203274 -216.580212)
		(width 0.0889)
		(layer "In13.Cu")
		(net "P5E_CPU1_PE0_RX_DN<4>")
	)
	(arc
		(start 92.656914 -221.458536)
		(mid 92.815596 -221.507774)
		(end 92.980002 -221.483682)
		(width 0.0889)
		(layer "In13.Cu")
		(net "P5E_CPU1_PE0_RX_DN<4>")
	)
	(arc
		(start 85.325712 -216.625424)
		(mid 85.422508 -216.612441)
		(end 85.512656 -216.574878)
		(width 0.0889)
		(layer "In13.Cu")
		(net "P5E_CPU1_PE0_RX_DN<4>")
	)
	(arc
		(start 91.717114 -216.575132)
		(mid 91.899336 -216.625332)
		(end 92.082874 -216.580212)
		(width 0.0889)
		(layer "In13.Cu")
		(net "P5E_CPU1_PE0_RX_DN<4>")
	)
	(arc
		(start 90.77706 -216.575132)
		(mid 90.959536 -216.625459)
		(end 91.143328 -216.580212)
		(width 0.0889)
		(layer "In13.Cu")
		(net "P5E_CPU1_PE0_RX_DN<4>")
	)
	(arc
		(start 86.07806 -216.574878)
		(mid 86.265258 -216.625021)
		(end 86.452456 -216.574878)
		(width 0.0889)
		(layer "In13.Cu")
		(net "P5E_CPU1_PE0_RX_DN<4>")
	)
	(arc
		(start 87.01786 -216.574878)
		(mid 87.205058 -216.625021)
		(end 87.392256 -216.574878)
		(width 0.0889)
		(layer "In13.Cu")
		(net "P5E_CPU1_PE0_RX_DN<4>")
	)
	(arc
		(start 86.452456 -216.574878)
		(mid 86.726655 -216.499043)
		(end 87.003128 -216.566242)
		(width 0.0889)
		(layer "In13.Cu")
		(net "P5E_CPU1_PE0_RX_DN<4>")
	)
	(arc
		(start 88.332564 -216.575132)
		(mid 88.615295 -216.499449)
		(end 88.897968 -216.575386)
		(width 0.0889)
		(layer "In13.Cu")
		(net "P5E_CPU1_PE0_RX_DN<4>")
	)
	(arc
		(start 92.655644 -219.181934)
		(mid 92.469326 -219.503991)
		(end 92.652088 -219.82811)
		(width 0.0889)
		(layer "In13.Cu")
		(net "P5E_CPU1_PE0_RX_DN<4>")
	)
	(arc
		(start 92.655644 -220.809566)
		(mid 92.523586 -220.939182)
		(end 92.469462 -221.116144)
		(width 0.0889)
		(layer "In13.Cu")
		(net "P5E_CPU1_PE0_RX_DN<4>")
	)
	(arc
		(start 88.909906 -216.582498)
		(mid 89.092076 -216.625487)
		(end 89.272364 -216.575132)
		(width 0.0889)
		(layer "In13.Cu")
		(net "P5E_CPU1_PE0_RX_DN<4>")
	)
	(arc
		(start 87.95766 -216.574878)
		(mid 88.144858 -216.625021)
		(end 88.332056 -216.574878)
		(width 0.0889)
		(layer "In13.Cu")
		(net "P5E_CPU1_PE0_RX_DN<4>")
	)
	(arc
		(start 89.272364 -216.575132)
		(mid 89.548923 -216.499355)
		(end 89.8271 -216.569036)
		(width 0.0889)
		(layer "In13.Cu")
		(net "P5E_CPU1_PE0_RX_DN<4>")
	)
	(arc
		(start 92.670122 -218.210892)
		(mid 92.939105 -218.692222)
		(end 92.670122 -219.173552)
		(width 0.0889)
		(layer "In13.Cu")
		(net "P5E_CPU1_PE0_RX_DN<4>")
	)
	(arc
		(start 90.211656 -216.575386)
		(mid 90.494329 -216.499415)
		(end 90.77706 -216.575132)
		(width 0.0889)
		(layer "In13.Cu")
		(net "P5E_CPU1_PE0_RX_DN<4>")
	)
	(arc
		(start 92.091256 -216.575386)
		(mid 92.859355 -216.774902)
		(end 92.670122 -217.545666)
		(width 0.0889)
		(layer "In13.Cu")
		(net "P5E_CPU1_PE0_RX_DN<4>")
	)
	(arc
		(start 92.655644 -217.554048)
		(mid 92.523586 -217.683664)
		(end 92.469462 -217.860626)
		(width 0.0889)
		(layer "In13.Cu")
		(net "P5E_CPU1_PE0_RX_DN<4>")
	)
	(arc
		(start 91.15171 -216.575386)
		(mid 91.434383 -216.499415)
		(end 91.717114 -216.575132)
		(width 0.0889)
		(layer "In13.Cu")
		(net "P5E_CPU1_PE0_RX_DN<4>")
	)
	(arc
		(start 85.512656 -216.574878)
		(mid 85.786855 -216.499043)
		(end 86.063328 -216.566242)
		(width 0.0889)
		(layer "In13.Cu")
		(net "P5E_CPU1_PE0_RX_DN<4>")
	)
	(segment
		(start 91.904312 -221.134178)
		(end 91.904566 -221.133924)
		(width 0.13208)
		(layer "F.Cu")
		(net "P5E_CPU1_PE0_RX_DN<3>")
	)
	(segment
		(start 91.904312 -221.669864)
		(end 91.904312 -221.134178)
		(width 0.13208)
		(layer "F.Cu")
		(net "P5E_CPU1_PE0_RX_DN<3>")
	)
	(segment
		(start 86.839298 -399.526506)
		(end 86.839298 -404.596092)
		(width 0.14732)
		(layer "In13.Cu")
		(net "P5E_CPU1_PE0_RX_DN<3>")
	)
	(segment
		(start 82.516218 -252.621034)
		(end 82.515964 -252.621034)
		(width 0.14732)
		(layer "In13.Cu")
		(net "P5E_CPU1_PE0_RX_DN<3>")
	)
	(segment
		(start 92.06103 -220.862906)
		(end 92.0369 -220.773752)
		(width 0.0889)
		(layer "In13.Cu")
		(net "P5E_CPU1_PE0_RX_DN<3>")
	)
	(segment
		(start 81.955894 -381.510032)
		(end 82.072988 -381.931418)
		(width 0.14732)
		(layer "In13.Cu")
		(net "P5E_CPU1_PE0_RX_DN<3>")
	)
	(segment
		(start 81.50606 -380.34849)
		(end 81.656428 -380.433072)
		(width 0.14732)
		(layer "In13.Cu")
		(net "P5E_CPU1_PE0_RX_DN<3>")
	)
	(segment
		(start 82.468212 -221.15272)
		(end 81.91246 -222.10395)
		(width 0.14732)
		(layer "In13.Cu")
		(net "P5E_CPU1_PE0_RX_DN<3>")
	)
	(segment
		(start 82.95513 -424.2308)
		(end 82.95513 -437.19496)
		(width 0.14732)
		(layer "In13.Cu")
		(net "P5E_CPU1_PE0_RX_DN<3>")
	)
	(segment
		(start 81.206594 -379.27153)
		(end 81.356962 -379.356366)
		(width 0.14732)
		(layer "In13.Cu")
		(net "P5E_CPU1_PE0_RX_DN<3>")
	)
	(segment
		(start 85.122258 -411.569916)
		(end 85.119464 -411.576012)
		(width 0.14732)
		(layer "In13.Cu")
		(net "P5E_CPU1_PE0_RX_DN<3>")
	)
	(segment
		(start 80.513936 -246.945404)
		(end 82.038444 -249.796808)
		(width 0.14732)
		(layer "In13.Cu")
		(net "P5E_CPU1_PE0_RX_DN<3>")
	)
	(segment
		(start 82.038444 -249.796808)
		(end 82.516218 -250.951492)
		(width 0.14732)
		(layer "In13.Cu")
		(net "P5E_CPU1_PE0_RX_DN<3>")
	)
	(segment
		(start 80.344264 -245.98249)
		(end 80.513936 -246.945404)
		(width 0.14732)
		(layer "In13.Cu")
		(net "P5E_CPU1_PE0_RX_DN<3>")
	)
	(segment
		(start 82.67192 -384.085338)
		(end 82.587084 -384.235452)
		(width 0.14732)
		(layer "In13.Cu")
		(net "P5E_CPU1_PE0_RX_DN<3>")
	)
	(segment
		(start 80.458818 -376.125486)
		(end 80.575912 -376.546618)
		(width 0.14732)
		(layer "In13.Cu")
		(net "P5E_CPU1_PE0_RX_DN<3>")
	)
	(segment
		(start 85.84946 -219.266008)
		(end 85.42782 -219.390468)
		(width 0.14732)
		(layer "In13.Cu")
		(net "P5E_CPU1_PE0_RX_DN<3>")
	)
	(segment
		(start 82.25536 -382.586992)
		(end 82.372454 -383.008378)
		(width 0.14732)
		(layer "In13.Cu")
		(net "P5E_CPU1_PE0_RX_DN<3>")
	)
	(segment
		(start 79.962502 -233.951018)
		(end 80.068674 -239.48517)
		(width 0.14732)
		(layer "In13.Cu")
		(net "P5E_CPU1_PE0_RX_DN<3>")
	)
	(segment
		(start 82.072988 -381.931418)
		(end 81.988152 -382.081532)
		(width 0.14732)
		(layer "In13.Cu")
		(net "P5E_CPU1_PE0_RX_DN<3>")
	)
	(segment
		(start 85.42782 -219.390468)
		(end 83.12912 -220.6498)
		(width 0.14732)
		(layer "In13.Cu")
		(net "P5E_CPU1_PE0_RX_DN<3>")
	)
	(segment
		(start 80.008984 -374.96369)
		(end 80.159352 -375.048526)
		(width 0.14732)
		(layer "In13.Cu")
		(net "P5E_CPU1_PE0_RX_DN<3>")
	)
	(segment
		(start 91.809062 -220.334078)
		(end 91.809062 -220.311218)
		(width 0.0889)
		(layer "In13.Cu")
		(net "P5E_CPU1_PE0_RX_DN<3>")
	)
	(segment
		(start 80.159352 -375.048526)
		(end 80.276446 -375.469658)
		(width 0.14732)
		(layer "In13.Cu")
		(net "P5E_CPU1_PE0_RX_DN<3>")
	)
	(segment
		(start 80.758284 -377.202446)
		(end 80.875378 -377.623578)
		(width 0.14732)
		(layer "In13.Cu")
		(net "P5E_CPU1_PE0_RX_DN<3>")
	)
	(segment
		(start 79.892144 -374.542812)
		(end 80.008984 -374.96369)
		(width 0.14732)
		(layer "In13.Cu")
		(net "P5E_CPU1_PE0_RX_DN<3>")
	)
	(segment
		(start 91.160854 -219.18676)
		(end 91.153488 -219.182442)
		(width 0.0889)
		(layer "In13.Cu")
		(net "P5E_CPU1_PE0_RX_DN<3>")
	)
	(segment
		(start 81.91246 -222.10395)
		(end 79.962502 -233.951018)
		(width 0.14732)
		(layer "In13.Cu")
		(net "P5E_CPU1_PE0_RX_DN<3>")
	)
	(segment
		(start 81.656428 -380.433072)
		(end 81.773522 -380.854458)
		(width 0.14732)
		(layer "In13.Cu")
		(net "P5E_CPU1_PE0_RX_DN<3>")
	)
	(segment
		(start 79.292958 -266.620244)
		(end 82.089498 -310.548528)
		(width 0.14732)
		(layer "In13.Cu")
		(net "P5E_CPU1_PE0_RX_DN<3>")
	)
	(segment
		(start 85.870542 -219.259912)
		(end 85.84946 -219.266008)
		(width 0.0889)
		(layer "In13.Cu")
		(net "P5E_CPU1_PE0_RX_DN<3>")
	)
	(segment
		(start 87.112094 -219.105988)
		(end 87.111586 -219.105988)
		(width 0.0889)
		(layer "In13.Cu")
		(net "P5E_CPU1_PE0_RX_DN<3>")
	)
	(segment
		(start 85.119464 -411.576012)
		(end 82.95513 -424.2308)
		(width 0.14732)
		(layer "In13.Cu")
		(net "P5E_CPU1_PE0_RX_DN<3>")
	)
	(segment
		(start 85.898736 -219.207842)
		(end 85.870542 -219.259912)
		(width 0.0889)
		(layer "In13.Cu")
		(net "P5E_CPU1_PE0_RX_DN<3>")
	)
	(segment
		(start 91.904566 -221.133924)
		(end 92.06103 -220.862906)
		(width 0.0889)
		(layer "In13.Cu")
		(net "P5E_CPU1_PE0_RX_DN<3>")
	)
	(segment
		(start 81.688686 -381.004572)
		(end 81.805526 -381.42545)
		(width 0.14732)
		(layer "In13.Cu")
		(net "P5E_CPU1_PE0_RX_DN<3>")
	)
	(segment
		(start 81.05775 -378.279406)
		(end 81.174844 -378.700538)
		(width 0.14732)
		(layer "In13.Cu")
		(net "P5E_CPU1_PE0_RX_DN<3>")
	)
	(segment
		(start 73.010268 -350.379284)
		(end 74.04608 -353.52101)
		(width 0.14732)
		(layer "In13.Cu")
		(net "P5E_CPU1_PE0_RX_DN<3>")
	)
	(segment
		(start 83.07959 -437.31942)
		(end 83.482942 -437.31942)
		(width 0.14732)
		(layer "In13.Cu")
		(net "P5E_CPU1_PE0_RX_DN<3>")
	)
	(segment
		(start 86.202012 -219.117926)
		(end 85.898736 -219.207842)
		(width 0.0889)
		(layer "In13.Cu")
		(net "P5E_CPU1_PE0_RX_DN<3>")
	)
	(segment
		(start 82.372454 -383.008378)
		(end 82.287618 -383.158492)
		(width 0.14732)
		(layer "In13.Cu")
		(net "P5E_CPU1_PE0_RX_DN<3>")
	)
	(segment
		(start 80.276446 -375.469658)
		(end 80.19161 -375.619772)
		(width 0.14732)
		(layer "In13.Cu")
		(net "P5E_CPU1_PE0_RX_DN<3>")
	)
	(segment
		(start 82.554826 -383.663952)
		(end 82.67192 -384.085338)
		(width 0.14732)
		(layer "In13.Cu")
		(net "P5E_CPU1_PE0_RX_DN<3>")
	)
	(segment
		(start 82.497422 -252.668532)
		(end 82.490056 -252.69063)
		(width 0.14732)
		(layer "In13.Cu")
		(net "P5E_CPU1_PE0_RX_DN<3>")
	)
	(segment
		(start 72.4154 -346.627196)
		(end 73.010268 -350.379284)
		(width 0.14732)
		(layer "In13.Cu")
		(net "P5E_CPU1_PE0_RX_DN<3>")
	)
	(segment
		(start 74.04608 -353.52101)
		(end 79.709518 -373.88673)
		(width 0.14732)
		(layer "In13.Cu")
		(net "P5E_CPU1_PE0_RX_DN<3>")
	)
	(segment
		(start 83.482942 -437.31942)
		(end 83.650074 -437.152288)
		(width 0.14732)
		(layer "In13.Cu")
		(net "P5E_CPU1_PE0_RX_DN<3>")
	)
	(segment
		(start 90.226896 -219.190316)
		(end 90.212164 -219.18168)
		(width 0.0889)
		(layer "In13.Cu")
		(net "P5E_CPU1_PE0_RX_DN<3>")
	)
	(segment
		(start 82.95513 -437.19496)
		(end 83.07959 -437.31942)
		(width 0.14732)
		(layer "In13.Cu")
		(net "P5E_CPU1_PE0_RX_DN<3>")
	)
	(segment
		(start 82.515964 -252.621034)
		(end 82.497422 -252.668532)
		(width 0.14732)
		(layer "In13.Cu")
		(net "P5E_CPU1_PE0_RX_DN<3>")
	)
	(segment
		(start 80.30845 -376.04065)
		(end 80.458818 -376.125486)
		(width 0.14732)
		(layer "In13.Cu")
		(net "P5E_CPU1_PE0_RX_DN<3>")
	)
	(segment
		(start 81.356962 -379.356366)
		(end 81.474056 -379.777498)
		(width 0.14732)
		(layer "In13.Cu")
		(net "P5E_CPU1_PE0_RX_DN<3>")
	)
	(segment
		(start 83.650074 -437.152288)
		(end 83.650074 -436.889906)
		(width 0.14732)
		(layer "In13.Cu")
		(net "P5E_CPU1_PE0_RX_DN<3>")
	)
	(segment
		(start 80.790542 -377.773692)
		(end 80.907382 -378.19457)
		(width 0.14732)
		(layer "In13.Cu")
		(net "P5E_CPU1_PE0_RX_DN<3>")
	)
	(segment
		(start 82.490056 -252.69063)
		(end 79.963518 -259.169154)
		(width 0.14732)
		(layer "In13.Cu")
		(net "P5E_CPU1_PE0_RX_DN<3>")
	)
	(segment
		(start 81.174844 -378.700538)
		(end 81.090008 -378.850652)
		(width 0.14732)
		(layer "In13.Cu")
		(net "P5E_CPU1_PE0_RX_DN<3>")
	)
	(segment
		(start 81.805526 -381.42545)
		(end 81.955894 -381.510032)
		(width 0.14732)
		(layer "In13.Cu")
		(net "P5E_CPU1_PE0_RX_DN<3>")
	)
	(segment
		(start 80.19161 -375.619772)
		(end 80.30845 -376.04065)
		(width 0.14732)
		(layer "In13.Cu")
		(net "P5E_CPU1_PE0_RX_DN<3>")
	)
	(segment
		(start 80.575912 -376.546618)
		(end 80.491076 -376.696732)
		(width 0.14732)
		(layer "In13.Cu")
		(net "P5E_CPU1_PE0_RX_DN<3>")
	)
	(segment
		(start 82.287618 -383.158492)
		(end 82.404458 -383.57937)
		(width 0.14732)
		(layer "In13.Cu")
		(net "P5E_CPU1_PE0_RX_DN<3>")
	)
	(segment
		(start 83.12912 -220.6498)
		(end 82.468212 -221.15272)
		(width 0.14732)
		(layer "In13.Cu")
		(net "P5E_CPU1_PE0_RX_DN<3>")
	)
	(segment
		(start 82.587338 -384.235452)
		(end 86.839298 -399.526506)
		(width 0.14732)
		(layer "In13.Cu")
		(net "P5E_CPU1_PE0_RX_DN<3>")
	)
	(segment
		(start 79.709518 -373.88673)
		(end 79.859886 -373.971566)
		(width 0.14732)
		(layer "In13.Cu")
		(net "P5E_CPU1_PE0_RX_DN<3>")
	)
	(segment
		(start 82.587084 -384.235452)
		(end 82.587338 -384.235452)
		(width 0.14732)
		(layer "In13.Cu")
		(net "P5E_CPU1_PE0_RX_DN<3>")
	)
	(segment
		(start 86.839298 -404.596092)
		(end 85.122258 -406.313132)
		(width 0.14732)
		(layer "In13.Cu")
		(net "P5E_CPU1_PE0_RX_DN<3>")
	)
	(segment
		(start 81.773522 -380.854458)
		(end 81.688686 -381.004572)
		(width 0.14732)
		(layer "In13.Cu")
		(net "P5E_CPU1_PE0_RX_DN<3>")
	)
	(segment
		(start 91.153488 -219.182442)
		(end 91.151964 -219.18168)
		(width 0.0889)
		(layer "In13.Cu")
		(net "P5E_CPU1_PE0_RX_DN<3>")
	)
	(segment
		(start 79.859886 -373.971566)
		(end 79.97698 -374.392698)
		(width 0.14732)
		(layer "In13.Cu")
		(net "P5E_CPU1_PE0_RX_DN<3>")
	)
	(segment
		(start 80.068674 -239.48517)
		(end 80.174846 -245.019576)
		(width 0.14732)
		(layer "In13.Cu")
		(net "P5E_CPU1_PE0_RX_DN<3>")
	)
	(segment
		(start 81.38922 -379.927612)
		(end 81.50606 -380.34849)
		(width 0.14732)
		(layer "In13.Cu")
		(net "P5E_CPU1_PE0_RX_DN<3>")
	)
	(segment
		(start 80.607916 -377.11761)
		(end 80.758284 -377.202446)
		(width 0.14732)
		(layer "In13.Cu")
		(net "P5E_CPU1_PE0_RX_DN<3>")
	)
	(segment
		(start 81.206848 -379.27153)
		(end 81.206594 -379.27153)
		(width 0.14732)
		(layer "In13.Cu")
		(net "P5E_CPU1_PE0_RX_DN<3>")
	)
	(segment
		(start 85.122258 -406.313132)
		(end 85.122258 -411.569916)
		(width 0.14732)
		(layer "In13.Cu")
		(net "P5E_CPU1_PE0_RX_DN<3>")
	)
	(segment
		(start 80.875378 -377.623578)
		(end 80.790542 -377.773692)
		(width 0.14732)
		(layer "In13.Cu")
		(net "P5E_CPU1_PE0_RX_DN<3>")
	)
	(segment
		(start 80.907382 -378.19457)
		(end 81.05775 -378.279406)
		(width 0.14732)
		(layer "In13.Cu")
		(net "P5E_CPU1_PE0_RX_DN<3>")
	)
	(segment
		(start 80.491076 -376.696732)
		(end 80.607916 -377.11761)
		(width 0.14732)
		(layer "In13.Cu")
		(net "P5E_CPU1_PE0_RX_DN<3>")
	)
	(segment
		(start 91.339416 -219.515944)
		(end 91.339416 -219.506038)
		(width 0.0889)
		(layer "In13.Cu")
		(net "P5E_CPU1_PE0_RX_DN<3>")
	)
	(segment
		(start 87.111586 -219.105988)
		(end 86.202012 -219.117926)
		(width 0.0889)
		(layer "In13.Cu")
		(net "P5E_CPU1_PE0_RX_DN<3>")
	)
	(segment
		(start 74.720704 -325.628762)
		(end 72.4154 -331.194156)
		(width 0.14732)
		(layer "In13.Cu")
		(net "P5E_CPU1_PE0_RX_DN<3>")
	)
	(segment
		(start 81.090008 -378.850652)
		(end 81.206848 -379.27153)
		(width 0.14732)
		(layer "In13.Cu")
		(net "P5E_CPU1_PE0_RX_DN<3>")
	)
	(segment
		(start 81.988152 -382.081532)
		(end 82.104992 -382.50241)
		(width 0.14732)
		(layer "In13.Cu")
		(net "P5E_CPU1_PE0_RX_DN<3>")
	)
	(segment
		(start 82.104992 -382.50241)
		(end 82.25536 -382.586992)
		(width 0.14732)
		(layer "In13.Cu")
		(net "P5E_CPU1_PE0_RX_DN<3>")
	)
	(segment
		(start 82.516218 -250.951492)
		(end 82.516218 -252.621034)
		(width 0.14732)
		(layer "In13.Cu")
		(net "P5E_CPU1_PE0_RX_DN<3>")
	)
	(segment
		(start 81.474056 -379.777498)
		(end 81.38922 -379.927612)
		(width 0.14732)
		(layer "In13.Cu")
		(net "P5E_CPU1_PE0_RX_DN<3>")
	)
	(segment
		(start 72.4154 -331.194156)
		(end 72.4154 -346.627196)
		(width 0.14732)
		(layer "In13.Cu")
		(net "P5E_CPU1_PE0_RX_DN<3>")
	)
	(segment
		(start 89.287096 -219.190316)
		(end 89.272364 -219.18168)
		(width 0.0889)
		(layer "In13.Cu")
		(net "P5E_CPU1_PE0_RX_DN<3>")
	)
	(segment
		(start 82.089498 -310.548528)
		(end 77.281024 -321.972432)
		(width 0.14732)
		(layer "In13.Cu")
		(net "P5E_CPU1_PE0_RX_DN<3>")
	)
	(segment
		(start 82.404458 -383.57937)
		(end 82.554826 -383.663952)
		(width 0.14732)
		(layer "In13.Cu")
		(net "P5E_CPU1_PE0_RX_DN<3>")
	)
	(segment
		(start 79.97698 -374.392698)
		(end 79.892144 -374.542812)
		(width 0.14732)
		(layer "In13.Cu")
		(net "P5E_CPU1_PE0_RX_DN<3>")
	)
	(segment
		(start 80.174846 -245.019576)
		(end 80.344264 -245.98249)
		(width 0.14732)
		(layer "In13.Cu")
		(net "P5E_CPU1_PE0_RX_DN<3>")
	)
	(segment
		(start 79.963518 -259.169154)
		(end 79.292958 -266.620244)
		(width 0.14732)
		(layer "In13.Cu")
		(net "P5E_CPU1_PE0_RX_DN<3>")
	)
	(segment
		(start 77.281024 -321.972432)
		(end 74.720704 -325.628762)
		(width 0.14732)
		(layer "In13.Cu")
		(net "P5E_CPU1_PE0_RX_DN<3>")
	)
	(arc
		(start 88.897968 -219.18168)
		(mid 88.615266 -219.257456)
		(end 88.332564 -219.18168)
		(width 0.0889)
		(layer "In13.Cu")
		(net "P5E_CPU1_PE0_RX_DN<3>")
	)
	(arc
		(start 91.621864 -219.995496)
		(mid 91.417529 -219.792891)
		(end 91.339416 -219.515944)
		(width 0.0889)
		(layer "In13.Cu")
		(net "P5E_CPU1_PE0_RX_DN<3>")
	)
	(arc
		(start 92.019882 -220.760798)
		(mid 91.867395 -220.570702)
		(end 91.809062 -220.334078)
		(width 0.0889)
		(layer "In13.Cu")
		(net "P5E_CPU1_PE0_RX_DN<3>")
	)
	(arc
		(start 91.809062 -220.311218)
		(mid 91.756792 -220.128853)
		(end 91.621864 -219.995496)
		(width 0.0889)
		(layer "In13.Cu")
		(net "P5E_CPU1_PE0_RX_DN<3>")
	)
	(arc
		(start 89.272364 -219.18168)
		(mid 89.085166 -219.131537)
		(end 88.897968 -219.18168)
		(width 0.0889)
		(layer "In13.Cu")
		(net "P5E_CPU1_PE0_RX_DN<3>")
	)
	(arc
		(start 91.339416 -219.506038)
		(mid 91.291737 -219.323138)
		(end 91.160854 -219.18676)
		(width 0.0889)
		(layer "In13.Cu")
		(net "P5E_CPU1_PE0_RX_DN<3>")
	)
	(arc
		(start 90.212164 -219.18168)
		(mid 90.024966 -219.131537)
		(end 89.837768 -219.18168)
		(width 0.0889)
		(layer "In13.Cu")
		(net "P5E_CPU1_PE0_RX_DN<3>")
	)
	(arc
		(start 87.958168 -219.18168)
		(mid 87.675466 -219.257456)
		(end 87.392764 -219.18168)
		(width 0.0889)
		(layer "In13.Cu")
		(net "P5E_CPU1_PE0_RX_DN<3>")
	)
	(arc
		(start 91.151964 -219.18168)
		(mid 90.964766 -219.131537)
		(end 90.777568 -219.18168)
		(width 0.0889)
		(layer "In13.Cu")
		(net "P5E_CPU1_PE0_RX_DN<3>")
	)
	(arc
		(start 88.332564 -219.18168)
		(mid 88.145366 -219.131537)
		(end 87.958168 -219.18168)
		(width 0.0889)
		(layer "In13.Cu")
		(net "P5E_CPU1_PE0_RX_DN<3>")
	)
	(arc
		(start 87.392764 -219.18168)
		(mid 87.257437 -219.125276)
		(end 87.112094 -219.105988)
		(width 0.0889)
		(layer "In13.Cu")
		(net "P5E_CPU1_PE0_RX_DN<3>")
	)
	(arc
		(start 90.777568 -219.18168)
		(mid 90.503369 -219.257515)
		(end 90.226896 -219.190316)
		(width 0.0889)
		(layer "In13.Cu")
		(net "P5E_CPU1_PE0_RX_DN<3>")
	)
	(arc
		(start 92.0369 -220.773752)
		(mid 92.028329 -220.767356)
		(end 92.019882 -220.760798)
		(width 0.0889)
		(layer "In13.Cu")
		(net "P5E_CPU1_PE0_RX_DN<3>")
	)
	(arc
		(start 89.837768 -219.18168)
		(mid 89.563569 -219.257515)
		(end 89.287096 -219.190316)
		(width 0.0889)
		(layer "In13.Cu")
		(net "P5E_CPU1_PE0_RX_DN<3>")
	)
	(segment
		(start 90.964512 -221.669864)
		(end 90.964512 -221.134178)
		(width 0.13208)
		(layer "F.Cu")
		(net "P5E_CPU1_PE0_RX_DN<2>")
	)
	(segment
		(start 90.964512 -221.134178)
		(end 90.964766 -221.133924)
		(width 0.13208)
		(layer "F.Cu")
		(net "P5E_CPU1_PE0_RX_DN<2>")
	)
	(segment
		(start 81.141062 -246.727726)
		(end 80.850486 -245.075456)
		(width 0.14732)
		(layer "In13.Cu")
		(net "P5E_CPU1_PE0_RX_DN<2>")
	)
	(segment
		(start 84.965794 -438.593738)
		(end 84.680806 -438.30875)
		(width 0.14732)
		(layer "In13.Cu")
		(net "P5E_CPU1_PE0_RX_DN<2>")
	)
	(segment
		(start 89.628218 -399.662904)
		(end 87.390732 -392.680698)
		(width 0.14732)
		(layer "In13.Cu")
		(net "P5E_CPU1_PE0_RX_DN<2>")
	)
	(segment
		(start 79.960216 -266.62888)
		(end 80.618076 -259.322824)
		(width 0.14732)
		(layer "In13.Cu")
		(net "P5E_CPU1_PE0_RX_DN<2>")
	)
	(segment
		(start 82.620104 -222.269812)
		(end 82.98815 -221.648782)
		(width 0.14732)
		(layer "In13.Cu")
		(net "P5E_CPU1_PE0_RX_DN<2>")
	)
	(segment
		(start 86.755478 -390.698228)
		(end 86.719918 -390.662668)
		(width 0.14732)
		(layer "In13.Cu")
		(net "P5E_CPU1_PE0_RX_DN<2>")
	)
	(segment
		(start 85.65007 -438.741312)
		(end 85.502496 -438.593738)
		(width 0.14732)
		(layer "In13.Cu")
		(net "P5E_CPU1_PE0_RX_DN<2>")
	)
	(segment
		(start 83.181444 -252.746256)
		(end 83.181444 -250.843796)
		(width 0.14732)
		(layer "In13.Cu")
		(net "P5E_CPU1_PE0_RX_DN<2>")
	)
	(segment
		(start 85.601302 -220.175328)
		(end 85.806534 -220.063822)
		(width 0.0889)
		(layer "In13.Cu")
		(net "P5E_CPU1_PE0_RX_DN<2>")
	)
	(segment
		(start 83.18119 -252.746256)
		(end 83.181444 -252.746256)
		(width 0.14732)
		(layer "In13.Cu")
		(net "P5E_CPU1_PE0_RX_DN<2>")
	)
	(segment
		(start 75.298046 -325.989188)
		(end 77.909928 -322.259452)
		(width 0.14732)
		(layer "In13.Cu")
		(net "P5E_CPU1_PE0_RX_DN<2>")
	)
	(segment
		(start 77.909928 -322.259452)
		(end 82.766916 -310.718454)
		(width 0.14732)
		(layer "In13.Cu")
		(net "P5E_CPU1_PE0_RX_DN<2>")
	)
	(segment
		(start 86.719918 -390.662668)
		(end 86.719918 -390.587738)
		(width 0.14732)
		(layer "In13.Cu")
		(net "P5E_CPU1_PE0_RX_DN<2>")
	)
	(segment
		(start 84.680806 -438.30875)
		(end 84.680806 -423.911776)
		(width 0.14732)
		(layer "In13.Cu")
		(net "P5E_CPU1_PE0_RX_DN<2>")
	)
	(segment
		(start 89.628218 -404.4823)
		(end 89.628218 -399.662904)
		(width 0.14732)
		(layer "In13.Cu")
		(net "P5E_CPU1_PE0_RX_DN<2>")
	)
	(segment
		(start 87.390732 -392.680698)
		(end 87.390478 -392.680444)
		(width 0.14732)
		(layer "In13.Cu")
		(net "P5E_CPU1_PE0_RX_DN<2>")
	)
	(segment
		(start 82.632804 -249.518424)
		(end 81.141062 -246.727726)
		(width 0.14732)
		(layer "In13.Cu")
		(net "P5E_CPU1_PE0_RX_DN<2>")
	)
	(segment
		(start 85.502496 -438.593738)
		(end 84.965794 -438.593738)
		(width 0.14732)
		(layer "In13.Cu")
		(net "P5E_CPU1_PE0_RX_DN<2>")
	)
	(segment
		(start 73.768458 -350.172528)
		(end 73.196704 -346.565474)
		(width 0.14732)
		(layer "In13.Cu")
		(net "P5E_CPU1_PE0_RX_DN<2>")
	)
	(segment
		(start 83.181444 -250.843796)
		(end 82.632804 -249.518424)
		(width 0.14732)
		(layer "In13.Cu")
		(net "P5E_CPU1_PE0_RX_DN<2>")
	)
	(segment
		(start 82.766916 -310.718454)
		(end 79.960216 -266.62888)
		(width 0.14732)
		(layer "In13.Cu")
		(net "P5E_CPU1_PE0_RX_DN<2>")
	)
	(segment
		(start 90.203274 -219.83573)
		(end 90.211656 -219.830904)
		(width 0.0889)
		(layer "In13.Cu")
		(net "P5E_CPU1_PE0_RX_DN<2>")
	)
	(segment
		(start 90.776552 -219.830396)
		(end 90.782902 -219.834206)
		(width 0.0889)
		(layer "In13.Cu")
		(net "P5E_CPU1_PE0_RX_DN<2>")
	)
	(segment
		(start 84.680806 -423.911776)
		(end 87.911178 -411.422088)
		(width 0.14732)
		(layer "In13.Cu")
		(net "P5E_CPU1_PE0_RX_DN<2>")
	)
	(segment
		(start 83.53933 -221.250764)
		(end 85.525864 -220.168978)
		(width 0.14732)
		(layer "In13.Cu")
		(net "P5E_CPU1_PE0_RX_DN<2>")
	)
	(segment
		(start 90.782902 -219.834206)
		(end 90.787474 -219.836746)
		(width 0.0889)
		(layer "In13.Cu")
		(net "P5E_CPU1_PE0_RX_DN<2>")
	)
	(segment
		(start 91.100148 -221.48292)
		(end 91.12123 -221.404942)
		(width 0.0889)
		(layer "In13.Cu")
		(net "P5E_CPU1_PE0_RX_DN<2>")
	)
	(segment
		(start 73.196704 -346.565474)
		(end 73.196704 -331.06233)
		(width 0.14732)
		(layer "In13.Cu")
		(net "P5E_CPU1_PE0_RX_DN<2>")
	)
	(segment
		(start 85.806534 -220.063822)
		(end 86.08695 -219.941648)
		(width 0.0889)
		(layer "In13.Cu")
		(net "P5E_CPU1_PE0_RX_DN<2>")
	)
	(segment
		(start 87.911178 -406.19934)
		(end 89.628218 -404.4823)
		(width 0.14732)
		(layer "In13.Cu")
		(net "P5E_CPU1_PE0_RX_DN<2>")
	)
	(segment
		(start 90.790522 -220.801184)
		(end 90.784934 -220.804486)
		(width 0.0889)
		(layer "In13.Cu")
		(net "P5E_CPU1_PE0_RX_DN<2>")
	)
	(segment
		(start 80.63865 -234.03306)
		(end 82.620104 -222.269812)
		(width 0.14732)
		(layer "In13.Cu")
		(net "P5E_CPU1_PE0_RX_DN<2>")
	)
	(segment
		(start 86.719918 -390.587738)
		(end 73.768458 -350.172528)
		(width 0.14732)
		(layer "In13.Cu")
		(net "P5E_CPU1_PE0_RX_DN<2>")
	)
	(segment
		(start 82.98815 -221.648782)
		(end 83.53933 -221.250764)
		(width 0.14732)
		(layer "In13.Cu")
		(net "P5E_CPU1_PE0_RX_DN<2>")
	)
	(segment
		(start 91.12123 -221.404942)
		(end 90.964766 -221.133924)
		(width 0.0889)
		(layer "In13.Cu")
		(net "P5E_CPU1_PE0_RX_DN<2>")
	)
	(segment
		(start 85.545168 -220.158564)
		(end 85.601302 -220.175328)
		(width 0.0889)
		(layer "In13.Cu")
		(net "P5E_CPU1_PE0_RX_DN<2>")
	)
	(segment
		(start 85.65007 -439.0898)
		(end 85.65007 -438.741312)
		(width 0.14732)
		(layer "In13.Cu")
		(net "P5E_CPU1_PE0_RX_DN<2>")
	)
	(segment
		(start 87.911178 -411.422088)
		(end 87.911178 -406.19934)
		(width 0.14732)
		(layer "In13.Cu")
		(net "P5E_CPU1_PE0_RX_DN<2>")
	)
	(segment
		(start 87.390478 -392.680444)
		(end 86.755478 -390.698228)
		(width 0.14732)
		(layer "In13.Cu")
		(net "P5E_CPU1_PE0_RX_DN<2>")
	)
	(segment
		(start 73.196704 -331.06233)
		(end 75.298046 -325.989188)
		(width 0.14732)
		(layer "In13.Cu")
		(net "P5E_CPU1_PE0_RX_DN<2>")
	)
	(segment
		(start 90.589862 -221.116144)
		(end 90.589862 -221.14637)
		(width 0.0889)
		(layer "In13.Cu")
		(net "P5E_CPU1_PE0_RX_DN<2>")
	)
	(segment
		(start 85.525864 -220.168978)
		(end 85.545168 -220.158564)
		(width 0.0889)
		(layer "In13.Cu")
		(net "P5E_CPU1_PE0_RX_DN<2>")
	)
	(segment
		(start 90.784934 -220.804486)
		(end 90.776044 -220.809566)
		(width 0.0889)
		(layer "In13.Cu")
		(net "P5E_CPU1_PE0_RX_DN<2>")
	)
	(segment
		(start 80.850486 -245.075456)
		(end 80.63865 -234.03306)
		(width 0.14732)
		(layer "In13.Cu")
		(net "P5E_CPU1_PE0_RX_DN<2>")
	)
	(segment
		(start 91.100402 -221.483682)
		(end 91.100148 -221.48292)
		(width 0.0889)
		(layer "In13.Cu")
		(net "P5E_CPU1_PE0_RX_DN<2>")
	)
	(segment
		(start 80.618076 -259.322824)
		(end 83.18119 -252.746256)
		(width 0.14732)
		(layer "In13.Cu")
		(net "P5E_CPU1_PE0_RX_DN<2>")
	)
	(arc
		(start 88.897714 -219.83065)
		(mid 89.085166 -219.880886)
		(end 89.272618 -219.83065)
		(width 0.0889)
		(layer "In13.Cu")
		(net "P5E_CPU1_PE0_RX_DN<2>")
	)
	(arc
		(start 90.589862 -221.14637)
		(mid 90.64315 -221.326743)
		(end 90.777314 -221.458536)
		(width 0.0889)
		(layer "In13.Cu")
		(net "P5E_CPU1_PE0_RX_DN<2>")
	)
	(arc
		(start 89.837514 -219.83065)
		(mid 90.019736 -219.88085)
		(end 90.203274 -219.83573)
		(width 0.0889)
		(layer "In13.Cu")
		(net "P5E_CPU1_PE0_RX_DN<2>")
	)
	(arc
		(start 86.310724 -219.87383)
		(mid 86.38606 -219.855264)
		(end 86.458552 -219.827602)
		(width 0.0889)
		(layer "In13.Cu")
		(net "P5E_CPU1_PE0_RX_DN<2>")
	)
	(arc
		(start 90.787474 -219.836746)
		(mid 90.986858 -220.042626)
		(end 91.059508 -220.319854)
		(width 0.0889)
		(layer "In13.Cu")
		(net "P5E_CPU1_PE0_RX_DN<2>")
	)
	(arc
		(start 90.211656 -219.830904)
		(mid 90.494045 -219.754933)
		(end 90.776552 -219.830396)
		(width 0.0889)
		(layer "In13.Cu")
		(net "P5E_CPU1_PE0_RX_DN<2>")
	)
	(arc
		(start 87.393018 -219.83065)
		(mid 87.675466 -219.754967)
		(end 87.957914 -219.83065)
		(width 0.0889)
		(layer "In13.Cu")
		(net "P5E_CPU1_PE0_RX_DN<2>")
	)
	(arc
		(start 89.272618 -219.83065)
		(mid 89.555066 -219.754967)
		(end 89.837514 -219.83065)
		(width 0.0889)
		(layer "In13.Cu")
		(net "P5E_CPU1_PE0_RX_DN<2>")
	)
	(arc
		(start 86.08695 -219.941648)
		(mid 86.196867 -219.901234)
		(end 86.310724 -219.87383)
		(width 0.0889)
		(layer "In13.Cu")
		(net "P5E_CPU1_PE0_RX_DN<2>")
	)
	(arc
		(start 86.458552 -219.827602)
		(mid 86.738738 -219.754969)
		(end 87.018114 -219.83065)
		(width 0.0889)
		(layer "In13.Cu")
		(net "P5E_CPU1_PE0_RX_DN<2>")
	)
	(arc
		(start 87.957914 -219.83065)
		(mid 88.145366 -219.880886)
		(end 88.332818 -219.83065)
		(width 0.0889)
		(layer "In13.Cu")
		(net "P5E_CPU1_PE0_RX_DN<2>")
	)
	(arc
		(start 88.332818 -219.83065)
		(mid 88.615266 -219.754967)
		(end 88.897714 -219.83065)
		(width 0.0889)
		(layer "In13.Cu")
		(net "P5E_CPU1_PE0_RX_DN<2>")
	)
	(arc
		(start 87.018114 -219.83065)
		(mid 87.205566 -219.880886)
		(end 87.393018 -219.83065)
		(width 0.0889)
		(layer "In13.Cu")
		(net "P5E_CPU1_PE0_RX_DN<2>")
	)
	(arc
		(start 90.777314 -221.458536)
		(mid 90.935996 -221.507774)
		(end 91.100402 -221.483682)
		(width 0.0889)
		(layer "In13.Cu")
		(net "P5E_CPU1_PE0_RX_DN<2>")
	)
	(arc
		(start 91.059508 -220.319854)
		(mid 90.9877 -220.59555)
		(end 90.790522 -220.801184)
		(width 0.0889)
		(layer "In13.Cu")
		(net "P5E_CPU1_PE0_RX_DN<2>")
	)
	(arc
		(start 90.776044 -220.809566)
		(mid 90.643986 -220.939182)
		(end 90.589862 -221.116144)
		(width 0.0889)
		(layer "In13.Cu")
		(net "P5E_CPU1_PE0_RX_DN<2>")
	)
	(segment
		(start 90.024712 -221.669864)
		(end 90.024966 -221.66961)
		(width 0.13208)
		(layer "F.Cu")
		(net "P5E_CPU1_PE0_RX_DN<1>")
	)
	(segment
		(start 90.024966 -221.66961)
		(end 90.024966 -221.133924)
		(width 0.13208)
		(layer "F.Cu")
		(net "P5E_CPU1_PE0_RX_DN<1>")
	)
	(segment
		(start 86.72068 -382.397508)
		(end 86.867746 -382.803654)
		(width 0.14732)
		(layer "In13.Cu")
		(net "P5E_CPU1_PE0_RX_DN<1>")
	)
	(segment
		(start 88.702388 -387.51891)
		(end 88.627712 -387.678168)
		(width 0.14732)
		(layer "In13.Cu")
		(net "P5E_CPU1_PE0_RX_DN<1>")
	)
	(segment
		(start 84.385404 -250.60275)
		(end 84.385404 -252.972824)
		(width 0.14732)
		(layer "In13.Cu")
		(net "P5E_CPU1_PE0_RX_DN<1>")
	)
	(segment
		(start 84.31022 -222.210884)
		(end 83.976464 -222.444818)
		(width 0.14732)
		(layer "In13.Cu")
		(net "P5E_CPU1_PE0_RX_DN<1>")
	)
	(segment
		(start 86.413848 -381.182118)
		(end 86.339172 -381.341376)
		(width 0.14732)
		(layer "In13.Cu")
		(net "P5E_CPU1_PE0_RX_DN<1>")
	)
	(segment
		(start 85.884004 -379.715014)
		(end 86.032594 -380.125986)
		(width 0.14732)
		(layer "In13.Cu")
		(net "P5E_CPU1_PE0_RX_DN<1>")
	)
	(segment
		(start 87.482934 -437.31942)
		(end 87.650066 -437.152288)
		(width 0.14732)
		(layer "In13.Cu")
		(net "P5E_CPU1_PE0_RX_DN<1>")
	)
	(segment
		(start 86.487508 -381.752602)
		(end 86.646766 -381.827278)
		(width 0.14732)
		(layer "In13.Cu")
		(net "P5E_CPU1_PE0_RX_DN<1>")
	)
	(segment
		(start 74.4728 -346.464382)
		(end 75.0443 -350.06915)
		(width 0.14732)
		(layer "In13.Cu")
		(net "P5E_CPU1_PE0_RX_DN<1>")
	)
	(segment
		(start 74.4728 -331.150468)
		(end 74.4728 -346.464382)
		(width 0.14732)
		(layer "In13.Cu")
		(net "P5E_CPU1_PE0_RX_DN<1>")
	)
	(segment
		(start 87.791036 -384.995674)
		(end 87.939626 -385.406646)
		(width 0.14732)
		(layer "In13.Cu")
		(net "P5E_CPU1_PE0_RX_DN<1>")
	)
	(segment
		(start 91.248738 -411.336236)
		(end 86.955122 -423.890948)
		(width 0.14732)
		(layer "In13.Cu")
		(net "P5E_CPU1_PE0_RX_DN<1>")
	)
	(segment
		(start 89.00922 -388.7343)
		(end 92.965778 -399.689828)
		(width 0.14732)
		(layer "In13.Cu")
		(net "P5E_CPU1_PE0_RX_DN<1>")
	)
	(segment
		(start 86.867746 -382.803654)
		(end 86.86927 -382.808226)
		(width 0.14732)
		(layer "In13.Cu")
		(net "P5E_CPU1_PE0_RX_DN<1>")
	)
	(segment
		(start 87.718646 -221.023434)
		(end 87.718392 -221.023434)
		(width 0.0889)
		(layer "In13.Cu")
		(net "P5E_CPU1_PE0_RX_DN<1>")
	)
	(segment
		(start 85.724746 -379.640338)
		(end 85.884004 -379.715014)
		(width 0.14732)
		(layer "In13.Cu")
		(net "P5E_CPU1_PE0_RX_DN<1>")
	)
	(segment
		(start 87.176864 -383.294382)
		(end 87.101934 -383.453894)
		(width 0.14732)
		(layer "In13.Cu")
		(net "P5E_CPU1_PE0_RX_DN<1>")
	)
	(segment
		(start 85.957664 -380.285498)
		(end 86.106 -380.69647)
		(width 0.14732)
		(layer "In13.Cu")
		(net "P5E_CPU1_PE0_RX_DN<1>")
	)
	(segment
		(start 88.776048 -388.088886)
		(end 88.93556 -388.163816)
		(width 0.14732)
		(layer "In13.Cu")
		(net "P5E_CPU1_PE0_RX_DN<1>")
	)
	(segment
		(start 86.955122 -423.890948)
		(end 86.955122 -437.19496)
		(width 0.14732)
		(layer "In13.Cu")
		(net "P5E_CPU1_PE0_RX_DN<1>")
	)
	(segment
		(start 81.16824 -266.644628)
		(end 83.988656 -310.95061)
		(width 0.14732)
		(layer "In13.Cu")
		(net "P5E_CPU1_PE0_RX_DN<1>")
	)
	(segment
		(start 92.965778 -404.596092)
		(end 91.248738 -406.313132)
		(width 0.14732)
		(layer "In13.Cu")
		(net "P5E_CPU1_PE0_RX_DN<1>")
	)
	(segment
		(start 90.18143 -220.862906)
		(end 90.160348 -220.784928)
		(width 0.0889)
		(layer "In13.Cu")
		(net "P5E_CPU1_PE0_RX_DN<1>")
	)
	(segment
		(start 87.892128 -220.857318)
		(end 87.891874 -220.857318)
		(width 0.0889)
		(layer "In13.Cu")
		(net "P5E_CPU1_PE0_RX_DN<1>")
	)
	(segment
		(start 87.939626 -385.406646)
		(end 87.864696 -385.566158)
		(width 0.14732)
		(layer "In13.Cu")
		(net "P5E_CPU1_PE0_RX_DN<1>")
	)
	(segment
		(start 88.321134 -386.462778)
		(end 88.246204 -386.62229)
		(width 0.14732)
		(layer "In13.Cu")
		(net "P5E_CPU1_PE0_RX_DN<1>")
	)
	(segment
		(start 84.385404 -252.972824)
		(end 81.802478 -259.601208)
		(width 0.14732)
		(layer "In13.Cu")
		(net "P5E_CPU1_PE0_RX_DN<1>")
	)
	(segment
		(start 87.864696 -385.566158)
		(end 87.865204 -385.565904)
		(width 0.14732)
		(layer "In13.Cu")
		(net "P5E_CPU1_PE0_RX_DN<1>")
	)
	(segment
		(start 87.631778 -384.920998)
		(end 87.791036 -384.995674)
		(width 0.14732)
		(layer "In13.Cu")
		(net "P5E_CPU1_PE0_RX_DN<1>")
	)
	(segment
		(start 86.646766 -381.827278)
		(end 86.795356 -382.23825)
		(width 0.14732)
		(layer "In13.Cu")
		(net "P5E_CPU1_PE0_RX_DN<1>")
	)
	(segment
		(start 86.868762 -382.80848)
		(end 87.028274 -382.88341)
		(width 0.14732)
		(layer "In13.Cu")
		(net "P5E_CPU1_PE0_RX_DN<1>")
	)
	(segment
		(start 86.339172 -381.341376)
		(end 86.487508 -381.752602)
		(width 0.14732)
		(layer "In13.Cu")
		(net "P5E_CPU1_PE0_RX_DN<1>")
	)
	(segment
		(start 90.024966 -221.133924)
		(end 90.18143 -220.862906)
		(width 0.0889)
		(layer "In13.Cu")
		(net "P5E_CPU1_PE0_RX_DN<1>")
	)
	(segment
		(start 86.35492 -221.417388)
		(end 84.31022 -222.210884)
		(width 0.14732)
		(layer "In13.Cu")
		(net "P5E_CPU1_PE0_RX_DN<1>")
	)
	(segment
		(start 75.0443 -350.06915)
		(end 85.724746 -379.640338)
		(width 0.14732)
		(layer "In13.Cu")
		(net "P5E_CPU1_PE0_RX_DN<1>")
	)
	(segment
		(start 87.384382 -221.417388)
		(end 86.35492 -221.417388)
		(width 0.14732)
		(layer "In13.Cu")
		(net "P5E_CPU1_PE0_RX_DN<1>")
	)
	(segment
		(start 87.603584 -221.198186)
		(end 87.384382 -221.417388)
		(width 0.14732)
		(layer "In13.Cu")
		(net "P5E_CPU1_PE0_RX_DN<1>")
	)
	(segment
		(start 82.29854 -246.338598)
		(end 83.71967 -248.995184)
		(width 0.14732)
		(layer "In13.Cu")
		(net "P5E_CPU1_PE0_RX_DN<1>")
	)
	(segment
		(start 86.032594 -380.125986)
		(end 85.957664 -380.285498)
		(width 0.14732)
		(layer "In13.Cu")
		(net "P5E_CPU1_PE0_RX_DN<1>")
	)
	(segment
		(start 87.865204 -385.565904)
		(end 87.866982 -385.571238)
		(width 0.14732)
		(layer "In13.Cu")
		(net "P5E_CPU1_PE0_RX_DN<1>")
	)
	(segment
		(start 83.988656 -310.95061)
		(end 78.84795 -323.163692)
		(width 0.14732)
		(layer "In13.Cu")
		(net "P5E_CPU1_PE0_RX_DN<1>")
	)
	(segment
		(start 87.409528 -383.939542)
		(end 87.558118 -384.350514)
		(width 0.14732)
		(layer "In13.Cu")
		(net "P5E_CPU1_PE0_RX_DN<1>")
	)
	(segment
		(start 87.079582 -437.31942)
		(end 87.482934 -437.31942)
		(width 0.14732)
		(layer "In13.Cu")
		(net "P5E_CPU1_PE0_RX_DN<1>")
	)
	(segment
		(start 82.090006 -233.200194)
		(end 82.173064 -245.626382)
		(width 0.14732)
		(layer "In13.Cu")
		(net "P5E_CPU1_PE0_RX_DN<1>")
	)
	(segment
		(start 87.718392 -221.023434)
		(end 87.619078 -221.122748)
		(width 0.0889)
		(layer "In13.Cu")
		(net "P5E_CPU1_PE0_RX_DN<1>")
	)
	(segment
		(start 86.795356 -382.23825)
		(end 86.72068 -382.397508)
		(width 0.14732)
		(layer "In13.Cu")
		(net "P5E_CPU1_PE0_RX_DN<1>")
	)
	(segment
		(start 88.39454 -387.033008)
		(end 88.554052 -387.107684)
		(width 0.14732)
		(layer "In13.Cu")
		(net "P5E_CPU1_PE0_RX_DN<1>")
	)
	(segment
		(start 82.173064 -245.626382)
		(end 82.29854 -246.338598)
		(width 0.14732)
		(layer "In13.Cu")
		(net "P5E_CPU1_PE0_RX_DN<1>")
	)
	(segment
		(start 81.802478 -259.601208)
		(end 81.16824 -266.644628)
		(width 0.14732)
		(layer "In13.Cu")
		(net "P5E_CPU1_PE0_RX_DN<1>")
	)
	(segment
		(start 83.976464 -222.444818)
		(end 83.805522 -222.716852)
		(width 0.14732)
		(layer "In13.Cu")
		(net "P5E_CPU1_PE0_RX_DN<1>")
	)
	(segment
		(start 92.965778 -399.689828)
		(end 92.965778 -404.596092)
		(width 0.14732)
		(layer "In13.Cu")
		(net "P5E_CPU1_PE0_RX_DN<1>")
	)
	(segment
		(start 86.86927 -382.808226)
		(end 86.868762 -382.80848)
		(width 0.14732)
		(layer "In13.Cu")
		(net "P5E_CPU1_PE0_RX_DN<1>")
	)
	(segment
		(start 87.25027 -383.864866)
		(end 87.409528 -383.939542)
		(width 0.14732)
		(layer "In13.Cu")
		(net "P5E_CPU1_PE0_RX_DN<1>")
	)
	(segment
		(start 88.013032 -385.976876)
		(end 88.172544 -386.051806)
		(width 0.14732)
		(layer "In13.Cu")
		(net "P5E_CPU1_PE0_RX_DN<1>")
	)
	(segment
		(start 88.01354 -385.976876)
		(end 88.013032 -385.976876)
		(width 0.14732)
		(layer "In13.Cu")
		(net "P5E_CPU1_PE0_RX_DN<1>")
	)
	(segment
		(start 87.866982 -385.571238)
		(end 88.013286 -385.976114)
		(width 0.14732)
		(layer "In13.Cu")
		(net "P5E_CPU1_PE0_RX_DN<1>")
	)
	(segment
		(start 87.558118 -384.350514)
		(end 87.483442 -384.509772)
		(width 0.14732)
		(layer "In13.Cu")
		(net "P5E_CPU1_PE0_RX_DN<1>")
	)
	(segment
		(start 86.106 -380.69647)
		(end 86.265258 -380.771146)
		(width 0.14732)
		(layer "In13.Cu")
		(net "P5E_CPU1_PE0_RX_DN<1>")
	)
	(segment
		(start 87.650066 -437.152288)
		(end 87.650066 -436.889906)
		(width 0.14732)
		(layer "In13.Cu")
		(net "P5E_CPU1_PE0_RX_DN<1>")
	)
	(segment
		(start 87.619078 -221.182692)
		(end 87.603584 -221.198186)
		(width 0.0889)
		(layer "In13.Cu")
		(net "P5E_CPU1_PE0_RX_DN<1>")
	)
	(segment
		(start 86.955122 -437.19496)
		(end 87.079582 -437.31942)
		(width 0.14732)
		(layer "In13.Cu")
		(net "P5E_CPU1_PE0_RX_DN<1>")
	)
	(segment
		(start 83.71967 -248.995184)
		(end 84.385404 -250.60275)
		(width 0.14732)
		(layer "In13.Cu")
		(net "P5E_CPU1_PE0_RX_DN<1>")
	)
	(segment
		(start 87.028274 -382.88341)
		(end 87.176864 -383.294382)
		(width 0.14732)
		(layer "In13.Cu")
		(net "P5E_CPU1_PE0_RX_DN<1>")
	)
	(segment
		(start 88.627712 -387.678168)
		(end 88.776048 -388.088886)
		(width 0.14732)
		(layer "In13.Cu")
		(net "P5E_CPU1_PE0_RX_DN<1>")
	)
	(segment
		(start 88.554052 -387.107684)
		(end 88.702388 -387.51891)
		(width 0.14732)
		(layer "In13.Cu")
		(net "P5E_CPU1_PE0_RX_DN<1>")
	)
	(segment
		(start 88.172544 -386.051806)
		(end 88.321134 -386.462778)
		(width 0.14732)
		(layer "In13.Cu")
		(net "P5E_CPU1_PE0_RX_DN<1>")
	)
	(segment
		(start 83.805522 -222.716852)
		(end 82.090006 -233.200194)
		(width 0.14732)
		(layer "In13.Cu")
		(net "P5E_CPU1_PE0_RX_DN<1>")
	)
	(segment
		(start 91.248738 -406.313132)
		(end 91.248738 -411.336236)
		(width 0.14732)
		(layer "In13.Cu")
		(net "P5E_CPU1_PE0_RX_DN<1>")
	)
	(segment
		(start 88.93556 -388.163816)
		(end 89.083896 -388.574788)
		(width 0.14732)
		(layer "In13.Cu")
		(net "P5E_CPU1_PE0_RX_DN<1>")
	)
	(segment
		(start 88.013286 -385.976114)
		(end 88.01354 -385.976876)
		(width 0.14732)
		(layer "In13.Cu")
		(net "P5E_CPU1_PE0_RX_DN<1>")
	)
	(segment
		(start 76.236322 -326.893428)
		(end 74.4728 -331.150468)
		(width 0.14732)
		(layer "In13.Cu")
		(net "P5E_CPU1_PE0_RX_DN<1>")
	)
	(segment
		(start 78.84795 -323.163692)
		(end 76.236322 -326.893428)
		(width 0.14732)
		(layer "In13.Cu")
		(net "P5E_CPU1_PE0_RX_DN<1>")
	)
	(segment
		(start 87.619078 -221.122748)
		(end 87.619078 -221.182692)
		(width 0.0889)
		(layer "In13.Cu")
		(net "P5E_CPU1_PE0_RX_DN<1>")
	)
	(segment
		(start 87.483442 -384.509772)
		(end 87.631778 -384.920998)
		(width 0.14732)
		(layer "In13.Cu")
		(net "P5E_CPU1_PE0_RX_DN<1>")
	)
	(segment
		(start 86.265258 -380.771146)
		(end 86.413848 -381.182118)
		(width 0.14732)
		(layer "In13.Cu")
		(net "P5E_CPU1_PE0_RX_DN<1>")
	)
	(segment
		(start 88.246204 -386.62229)
		(end 88.39454 -387.033008)
		(width 0.14732)
		(layer "In13.Cu")
		(net "P5E_CPU1_PE0_RX_DN<1>")
	)
	(segment
		(start 87.101934 -383.453894)
		(end 87.25027 -383.864866)
		(width 0.14732)
		(layer "In13.Cu")
		(net "P5E_CPU1_PE0_RX_DN<1>")
	)
	(segment
		(start 89.083896 -388.574788)
		(end 89.00922 -388.7343)
		(width 0.14732)
		(layer "In13.Cu")
		(net "P5E_CPU1_PE0_RX_DN<1>")
	)
	(arc
		(start 88.897968 -220.809566)
		(mid 88.615266 -220.885308)
		(end 88.332564 -220.809566)
		(width 0.0889)
		(layer "In13.Cu")
		(net "P5E_CPU1_PE0_RX_DN<1>")
	)
	(arc
		(start 89.837768 -220.809566)
		(mid 89.555066 -220.885308)
		(end 89.272364 -220.809566)
		(width 0.0889)
		(layer "In13.Cu")
		(net "P5E_CPU1_PE0_RX_DN<1>")
	)
	(arc
		(start 87.958168 -220.809566)
		(mid 87.923836 -220.831629)
		(end 87.892128 -220.857318)
		(width 0.0889)
		(layer "In13.Cu")
		(net "P5E_CPU1_PE0_RX_DN<1>")
	)
	(arc
		(start 89.272364 -220.809566)
		(mid 89.085166 -220.759423)
		(end 88.897968 -220.809566)
		(width 0.0889)
		(layer "In13.Cu")
		(net "P5E_CPU1_PE0_RX_DN<1>")
	)
	(arc
		(start 87.891874 -220.857318)
		(mid 87.804347 -220.939424)
		(end 87.718646 -221.023434)
		(width 0.0889)
		(layer "In13.Cu")
		(net "P5E_CPU1_PE0_RX_DN<1>")
	)
	(arc
		(start 88.332564 -220.809566)
		(mid 88.145366 -220.759423)
		(end 87.958168 -220.809566)
		(width 0.0889)
		(layer "In13.Cu")
		(net "P5E_CPU1_PE0_RX_DN<1>")
	)
	(arc
		(start 90.160348 -220.784928)
		(mid 89.996252 -220.760581)
		(end 89.837768 -220.809566)
		(width 0.0889)
		(layer "In13.Cu")
		(net "P5E_CPU1_PE0_RX_DN<1>")
	)
	(segment
		(start 103.652066 -220.855794)
		(end 103.651812 -220.85554)
		(width 0.13208)
		(layer "F.Cu")
		(net "P5E_CPU1_PE0_RX_DN<15>")
	)
	(segment
		(start 103.651812 -220.85554)
		(end 103.651812 -220.319854)
		(width 0.13208)
		(layer "F.Cu")
		(net "P5E_CPU1_PE0_RX_DN<15>")
	)
	(segment
		(start 65.734184 -315.41466)
		(end 66.25844 -315.41466)
		(width 0.14732)
		(layer "In13.Cu")
		(net "P5E_CPU1_PE0_RX_DN<15>")
	)
	(segment
		(start 102.986078 -219.825316)
		(end 102.994968 -219.830396)
		(width 0.0889)
		(layer "In13.Cu")
		(net "P5E_CPU1_PE0_RX_DN<15>")
	)
	(segment
		(start 66.25844 -315.41466)
		(end 66.692272 -315.188346)
		(width 0.14732)
		(layer "In13.Cu")
		(net "P5E_CPU1_PE0_RX_DN<15>")
	)
	(segment
		(start 69.857874 -305.592988)
		(end 66.521076 -253.47803)
		(width 0.14732)
		(layer "In13.Cu")
		(net "P5E_CPU1_PE0_RX_DN<15>")
	)
	(segment
		(start 61.112908 -320.985896)
		(end 61.112908 -319.453006)
		(width 0.14732)
		(layer "In13.Cu")
		(net "P5E_CPU1_PE0_RX_DN<15>")
	)
	(segment
		(start 102.337362 -213.8934)
		(end 102.337616 -213.893908)
		(width 0.0889)
		(layer "In13.Cu")
		(net "P5E_CPU1_PE0_RX_DN<15>")
	)
	(segment
		(start 57.494678 -437.113426)
		(end 57.393078 -436.931562)
		(width 0.14732)
		(layer "In13.Cu")
		(net "P5E_CPU1_PE0_RX_DN<15>")
	)
	(segment
		(start 103.495348 -220.590872)
		(end 103.651812 -220.319854)
		(width 0.0889)
		(layer "In13.Cu")
		(net "P5E_CPU1_PE0_RX_DN<15>")
	)
	(segment
		(start 61.112908 -319.453006)
		(end 63.568834 -316.99708)
		(width 0.14732)
		(layer "In13.Cu")
		(net "P5E_CPU1_PE0_RX_DN<15>")
	)
	(segment
		(start 102.379018 -211.005928)
		(end 102.379018 -213.15299)
		(width 0.14732)
		(layer "In13.Cu")
		(net "P5E_CPU1_PE0_RX_DN<15>")
	)
	(segment
		(start 68.669662 -309.827168)
		(end 68.669916 -309.826914)
		(width 0.14732)
		(layer "In13.Cu")
		(net "P5E_CPU1_PE0_RX_DN<15>")
	)
	(segment
		(start 86.99881 -199.25919)
		(end 90.674444 -199.25919)
		(width 0.14732)
		(layer "In13.Cu")
		(net "P5E_CPU1_PE0_RX_DN<15>")
	)
	(segment
		(start 58.50255 -437.574436)
		(end 58.015124 -437.574436)
		(width 0.14732)
		(layer "In13.Cu")
		(net "P5E_CPU1_PE0_RX_DN<15>")
	)
	(segment
		(start 49.806098 -404.4823)
		(end 49.806098 -400.591528)
		(width 0.14732)
		(layer "In13.Cu")
		(net "P5E_CPU1_PE0_RX_DN<15>")
	)
	(segment
		(start 58.21172 -362.419646)
		(end 58.865262 -342.092788)
		(width 0.14732)
		(layer "In13.Cu")
		(net "P5E_CPU1_PE0_RX_DN<15>")
	)
	(segment
		(start 57.393078 -436.931562)
		(end 50.936906 -414.048702)
		(width 0.14732)
		(layer "In13.Cu")
		(net "P5E_CPU1_PE0_RX_DN<15>")
	)
	(segment
		(start 72.134222 -214.540338)
		(end 72.134476 -214.540338)
		(width 0.14732)
		(layer "In13.Cu")
		(net "P5E_CPU1_PE0_RX_DN<15>")
	)
	(segment
		(start 66.521076 -253.464568)
		(end 66.627248 -249.90679)
		(width 0.14732)
		(layer "In13.Cu")
		(net "P5E_CPU1_PE0_RX_DN<15>")
	)
	(segment
		(start 52.273708 -391.932922)
		(end 56.8579 -370.763292)
		(width 0.14732)
		(layer "In13.Cu")
		(net "P5E_CPU1_PE0_RX_DN<15>")
	)
	(segment
		(start 48.089058 -410.31033)
		(end 48.089058 -406.19934)
		(width 0.14732)
		(layer "In13.Cu")
		(net "P5E_CPU1_PE0_RX_DN<15>")
	)
	(segment
		(start 68.669916 -309.826914)
		(end 69.857874 -305.592988)
		(width 0.14732)
		(layer "In13.Cu")
		(net "P5E_CPU1_PE0_RX_DN<15>")
	)
	(segment
		(start 49.806098 -400.591528)
		(end 50.764694 -397.478504)
		(width 0.14732)
		(layer "In13.Cu")
		(net "P5E_CPU1_PE0_RX_DN<15>")
	)
	(segment
		(start 103.277416 -220.309948)
		(end 103.277416 -220.32849)
		(width 0.0889)
		(layer "In13.Cu")
		(net "P5E_CPU1_PE0_RX_DN<15>")
	)
	(segment
		(start 70.17004 -218.326208)
		(end 72.134222 -214.540338)
		(width 0.14732)
		(layer "In13.Cu")
		(net "P5E_CPU1_PE0_RX_DN<15>")
	)
	(segment
		(start 57.817258 -325.233792)
		(end 58.430922 -323.75221)
		(width 0.14732)
		(layer "In13.Cu")
		(net "P5E_CPU1_PE0_RX_DN<15>")
	)
	(segment
		(start 67.481704 -314.061094)
		(end 68.669154 -309.828438)
		(width 0.14732)
		(layer "In13.Cu")
		(net "P5E_CPU1_PE0_RX_DN<15>")
	)
	(segment
		(start 102.337362 -213.81466)
		(end 102.337362 -213.8934)
		(width 0.0889)
		(layer "In13.Cu")
		(net "P5E_CPU1_PE0_RX_DN<15>")
	)
	(segment
		(start 60.244228 -321.854576)
		(end 61.112908 -320.985896)
		(width 0.14732)
		(layer "In13.Cu")
		(net "P5E_CPU1_PE0_RX_DN<15>")
	)
	(segment
		(start 51.300126 -395.510766)
		(end 51.30038 -395.50975)
		(width 0.14732)
		(layer "In13.Cu")
		(net "P5E_CPU1_PE0_RX_DN<15>")
	)
	(segment
		(start 66.627248 -249.90679)
		(end 66.626994 -249.90679)
		(width 0.14732)
		(layer "In13.Cu")
		(net "P5E_CPU1_PE0_RX_DN<15>")
	)
	(segment
		(start 68.038472 -232.119424)
		(end 70.17004 -218.326208)
		(width 0.14732)
		(layer "In13.Cu")
		(net "P5E_CPU1_PE0_RX_DN<15>")
	)
	(segment
		(start 66.626994 -249.90679)
		(end 66.627248 -249.904758)
		(width 0.14732)
		(layer "In13.Cu")
		(net "P5E_CPU1_PE0_RX_DN<15>")
	)
	(segment
		(start 66.692272 -315.188346)
		(end 67.481704 -314.061094)
		(width 0.14732)
		(layer "In13.Cu")
		(net "P5E_CPU1_PE0_RX_DN<15>")
	)
	(segment
		(start 102.807008 -214.424768)
		(end 102.807008 -214.644732)
		(width 0.0889)
		(layer "In13.Cu")
		(net "P5E_CPU1_PE0_RX_DN<15>")
	)
	(segment
		(start 59.926728 -322.06692)
		(end 60.244228 -321.854576)
		(width 0.14732)
		(layer "In13.Cu")
		(net "P5E_CPU1_PE0_RX_DN<15>")
	)
	(segment
		(start 100.851208 -207.346804)
		(end 102.35819 -210.9851)
		(width 0.14732)
		(layer "In13.Cu")
		(net "P5E_CPU1_PE0_RX_DN<15>")
	)
	(segment
		(start 94.240604 -200.7362)
		(end 100.851208 -207.346804)
		(width 0.14732)
		(layer "In13.Cu")
		(net "P5E_CPU1_PE0_RX_DN<15>")
	)
	(segment
		(start 64.151764 -316.99708)
		(end 65.734184 -315.41466)
		(width 0.14732)
		(layer "In13.Cu")
		(net "P5E_CPU1_PE0_RX_DN<15>")
	)
	(segment
		(start 59.262772 -322.341748)
		(end 59.926728 -322.06692)
		(width 0.14732)
		(layer "In13.Cu")
		(net "P5E_CPU1_PE0_RX_DN<15>")
	)
	(segment
		(start 102.35819 -210.9851)
		(end 102.379018 -211.005928)
		(width 0.14732)
		(layer "In13.Cu")
		(net "P5E_CPU1_PE0_RX_DN<15>")
	)
	(segment
		(start 102.337108 -213.814406)
		(end 102.337362 -213.81466)
		(width 0.0889)
		(layer "In13.Cu")
		(net "P5E_CPU1_PE0_RX_DN<15>")
	)
	(segment
		(start 58.430922 -323.75221)
		(end 58.430922 -323.173598)
		(width 0.14732)
		(layer "In13.Cu")
		(net "P5E_CPU1_PE0_RX_DN<15>")
	)
	(segment
		(start 102.986078 -216.569798)
		(end 102.994968 -216.574878)
		(width 0.0889)
		(layer "In13.Cu")
		(net "P5E_CPU1_PE0_RX_DN<15>")
	)
	(segment
		(start 50.936906 -414.048702)
		(end 48.463454 -411.285944)
		(width 0.14732)
		(layer "In13.Cu")
		(net "P5E_CPU1_PE0_RX_DN<15>")
	)
	(segment
		(start 58.015124 -437.574436)
		(end 57.491376 -437.125872)
		(width 0.14732)
		(layer "In13.Cu")
		(net "P5E_CPU1_PE0_RX_DN<15>")
	)
	(segment
		(start 102.337108 -213.216998)
		(end 102.337108 -213.814406)
		(width 0.0889)
		(layer "In13.Cu")
		(net "P5E_CPU1_PE0_RX_DN<15>")
	)
	(segment
		(start 102.515924 -215.755982)
		(end 102.524814 -215.761062)
		(width 0.0889)
		(layer "In13.Cu")
		(net "P5E_CPU1_PE0_RX_DN<15>")
	)
	(segment
		(start 103.277416 -217.05443)
		(end 103.277416 -217.082878)
		(width 0.0889)
		(layer "In13.Cu")
		(net "P5E_CPU1_PE0_RX_DN<15>")
	)
	(segment
		(start 48.463454 -411.285944)
		(end 48.089058 -410.31033)
		(width 0.14732)
		(layer "In13.Cu")
		(net "P5E_CPU1_PE0_RX_DN<15>")
	)
	(segment
		(start 68.669154 -309.828438)
		(end 68.669408 -309.827422)
		(width 0.14732)
		(layer "In13.Cu")
		(net "P5E_CPU1_PE0_RX_DN<15>")
	)
	(segment
		(start 68.669662 -309.827422)
		(end 68.669662 -309.827168)
		(width 0.14732)
		(layer "In13.Cu")
		(net "P5E_CPU1_PE0_RX_DN<15>")
	)
	(segment
		(start 103.41737 -220.6117)
		(end 103.495348 -220.590872)
		(width 0.0889)
		(layer "In13.Cu")
		(net "P5E_CPU1_PE0_RX_DN<15>")
	)
	(segment
		(start 72.134476 -214.540338)
		(end 76.023978 -209.527648)
		(width 0.14732)
		(layer "In13.Cu")
		(net "P5E_CPU1_PE0_RX_DN<15>")
	)
	(segment
		(start 66.521076 -253.47803)
		(end 66.521076 -253.464568)
		(width 0.14732)
		(layer "In13.Cu")
		(net "P5E_CPU1_PE0_RX_DN<15>")
	)
	(segment
		(start 102.379018 -213.175088)
		(end 102.337108 -213.216998)
		(width 0.0889)
		(layer "In13.Cu")
		(net "P5E_CPU1_PE0_RX_DN<15>")
	)
	(segment
		(start 102.379018 -213.15299)
		(end 102.379018 -213.175088)
		(width 0.0889)
		(layer "In13.Cu")
		(net "P5E_CPU1_PE0_RX_DN<15>")
	)
	(segment
		(start 50.764694 -397.478504)
		(end 51.300126 -395.510766)
		(width 0.14732)
		(layer "In13.Cu")
		(net "P5E_CPU1_PE0_RX_DN<15>")
	)
	(segment
		(start 84.12226 -200.744582)
		(end 86.99881 -199.25919)
		(width 0.14732)
		(layer "In13.Cu")
		(net "P5E_CPU1_PE0_RX_DN<15>")
	)
	(segment
		(start 66.627248 -249.904758)
		(end 68.036948 -232.12933)
		(width 0.14732)
		(layer "In13.Cu")
		(net "P5E_CPU1_PE0_RX_DN<15>")
	)
	(segment
		(start 48.089058 -406.19934)
		(end 49.806098 -404.4823)
		(width 0.14732)
		(layer "In13.Cu")
		(net "P5E_CPU1_PE0_RX_DN<15>")
	)
	(segment
		(start 51.30038 -395.50975)
		(end 52.273708 -391.932922)
		(width 0.14732)
		(layer "In13.Cu")
		(net "P5E_CPU1_PE0_RX_DN<15>")
	)
	(segment
		(start 102.524814 -215.112346)
		(end 102.515924 -215.117426)
		(width 0.0889)
		(layer "In13.Cu")
		(net "P5E_CPU1_PE0_RX_DN<15>")
	)
	(segment
		(start 102.986078 -218.197684)
		(end 102.994968 -218.202764)
		(width 0.0889)
		(layer "In13.Cu")
		(net "P5E_CPU1_PE0_RX_DN<15>")
	)
	(segment
		(start 57.491376 -437.125872)
		(end 57.494678 -437.113426)
		(width 0.14732)
		(layer "In13.Cu")
		(net "P5E_CPU1_PE0_RX_DN<15>")
	)
	(segment
		(start 102.994968 -217.554048)
		(end 102.986078 -217.559128)
		(width 0.0889)
		(layer "In13.Cu")
		(net "P5E_CPU1_PE0_RX_DN<15>")
	)
	(segment
		(start 68.036948 -232.12933)
		(end 68.038472 -232.119424)
		(width 0.14732)
		(layer "In13.Cu")
		(net "P5E_CPU1_PE0_RX_DN<15>")
	)
	(segment
		(start 103.277162 -218.676728)
		(end 103.277162 -218.707716)
		(width 0.0889)
		(layer "In13.Cu")
		(net "P5E_CPU1_PE0_RX_DN<15>")
	)
	(segment
		(start 68.669408 -309.827422)
		(end 68.669662 -309.827422)
		(width 0.14732)
		(layer "In13.Cu")
		(net "P5E_CPU1_PE0_RX_DN<15>")
	)
	(segment
		(start 58.650124 -437.72201)
		(end 58.50255 -437.574436)
		(width 0.14732)
		(layer "In13.Cu")
		(net "P5E_CPU1_PE0_RX_DN<15>")
	)
	(segment
		(start 57.817258 -330.01966)
		(end 57.817258 -325.233792)
		(width 0.14732)
		(layer "In13.Cu")
		(net "P5E_CPU1_PE0_RX_DN<15>")
	)
	(segment
		(start 102.994968 -219.18168)
		(end 102.986078 -219.18676)
		(width 0.0889)
		(layer "In13.Cu")
		(net "P5E_CPU1_PE0_RX_DN<15>")
	)
	(segment
		(start 58.650124 -438.089802)
		(end 58.650124 -437.72201)
		(width 0.14732)
		(layer "In13.Cu")
		(net "P5E_CPU1_PE0_RX_DN<15>")
	)
	(segment
		(start 76.023978 -209.527648)
		(end 84.12226 -200.744582)
		(width 0.14732)
		(layer "In13.Cu")
		(net "P5E_CPU1_PE0_RX_DN<15>")
	)
	(segment
		(start 102.524814 -215.761062)
		(end 102.53091 -215.764618)
		(width 0.0889)
		(layer "In13.Cu")
		(net "P5E_CPU1_PE0_RX_DN<15>")
	)
	(segment
		(start 58.865262 -342.092788)
		(end 57.817258 -330.01966)
		(width 0.14732)
		(layer "In13.Cu")
		(net "P5E_CPU1_PE0_RX_DN<15>")
	)
	(segment
		(start 56.8579 -370.763292)
		(end 58.21172 -362.419646)
		(width 0.14732)
		(layer "In13.Cu")
		(net "P5E_CPU1_PE0_RX_DN<15>")
	)
	(segment
		(start 58.430922 -323.173598)
		(end 59.262772 -322.341748)
		(width 0.14732)
		(layer "In13.Cu")
		(net "P5E_CPU1_PE0_RX_DN<15>")
	)
	(segment
		(start 90.674444 -199.25919)
		(end 94.240604 -200.7362)
		(width 0.14732)
		(layer "In13.Cu")
		(net "P5E_CPU1_PE0_RX_DN<15>")
	)
	(segment
		(start 63.568834 -316.99708)
		(end 64.151764 -316.99708)
		(width 0.14732)
		(layer "In13.Cu")
		(net "P5E_CPU1_PE0_RX_DN<15>")
	)
	(arc
		(start 103.277416 -220.32849)
		(mid 103.31609 -220.485558)
		(end 103.41737 -220.6117)
		(width 0.0889)
		(layer "In13.Cu")
		(net "P5E_CPU1_PE0_RX_DN<15>")
	)
	(arc
		(start 102.337616 -215.421972)
		(mid 102.337419 -215.429337)
		(end 102.337362 -215.436704)
		(width 0.0889)
		(layer "In13.Cu")
		(net "P5E_CPU1_PE0_RX_DN<15>")
	)
	(arc
		(start 103.277416 -217.082878)
		(mid 103.197254 -217.355067)
		(end 102.994968 -217.554048)
		(width 0.0889)
		(layer "In13.Cu")
		(net "P5E_CPU1_PE0_RX_DN<15>")
	)
	(arc
		(start 102.337616 -213.893908)
		(mid 102.412621 -214.009367)
		(end 102.521766 -214.093298)
		(width 0.0889)
		(layer "In13.Cu")
		(net "P5E_CPU1_PE0_RX_DN<15>")
	)
	(arc
		(start 102.986078 -217.559128)
		(mid 102.858185 -217.69019)
		(end 102.80777 -217.866214)
		(width 0.0889)
		(layer "In13.Cu")
		(net "P5E_CPU1_PE0_RX_DN<15>")
	)
	(arc
		(start 102.521766 -214.093298)
		(mid 102.695729 -214.232062)
		(end 102.807008 -214.424768)
		(width 0.0889)
		(layer "In13.Cu")
		(net "P5E_CPU1_PE0_RX_DN<15>")
	)
	(arc
		(start 102.994968 -219.830396)
		(mid 103.199303 -220.033001)
		(end 103.277416 -220.309948)
		(width 0.0889)
		(layer "In13.Cu")
		(net "P5E_CPU1_PE0_RX_DN<15>")
	)
	(arc
		(start 102.515924 -215.117426)
		(mid 102.38867 -215.247392)
		(end 102.337616 -215.421972)
		(width 0.0889)
		(layer "In13.Cu")
		(net "P5E_CPU1_PE0_RX_DN<15>")
	)
	(arc
		(start 102.80777 -217.888566)
		(mid 102.857785 -218.065697)
		(end 102.986078 -218.197684)
		(width 0.0889)
		(layer "In13.Cu")
		(net "P5E_CPU1_PE0_RX_DN<15>")
	)
	(arc
		(start 102.53091 -215.764618)
		(mid 102.733497 -215.970969)
		(end 102.807516 -216.25052)
		(width 0.0889)
		(layer "In13.Cu")
		(net "P5E_CPU1_PE0_RX_DN<15>")
	)
	(arc
		(start 103.277162 -218.707716)
		(mid 103.197792 -218.98145)
		(end 102.994968 -219.18168)
		(width 0.0889)
		(layer "In13.Cu")
		(net "P5E_CPU1_PE0_RX_DN<15>")
	)
	(arc
		(start 102.807008 -214.644732)
		(mid 102.726097 -214.91486)
		(end 102.524814 -215.112346)
		(width 0.0889)
		(layer "In13.Cu")
		(net "P5E_CPU1_PE0_RX_DN<15>")
	)
	(arc
		(start 102.807516 -216.25052)
		(mid 102.855195 -216.43342)
		(end 102.986078 -216.569798)
		(width 0.0889)
		(layer "In13.Cu")
		(net "P5E_CPU1_PE0_RX_DN<15>")
	)
	(arc
		(start 102.994968 -216.574878)
		(mid 103.199303 -216.777483)
		(end 103.277416 -217.05443)
		(width 0.0889)
		(layer "In13.Cu")
		(net "P5E_CPU1_PE0_RX_DN<15>")
	)
	(arc
		(start 102.337362 -215.436704)
		(mid 102.385041 -215.619604)
		(end 102.515924 -215.755982)
		(width 0.0889)
		(layer "In13.Cu")
		(net "P5E_CPU1_PE0_RX_DN<15>")
	)
	(arc
		(start 102.986078 -219.18676)
		(mid 102.857759 -219.318732)
		(end 102.80777 -219.495878)
		(width 0.0889)
		(layer "In13.Cu")
		(net "P5E_CPU1_PE0_RX_DN<15>")
	)
	(arc
		(start 102.80777 -219.512642)
		(mid 102.856877 -219.691831)
		(end 102.986078 -219.825316)
		(width 0.0889)
		(layer "In13.Cu")
		(net "P5E_CPU1_PE0_RX_DN<15>")
	)
	(arc
		(start 102.80777 -219.495878)
		(mid 102.807676 -219.50426)
		(end 102.80777 -219.512642)
		(width 0.0889)
		(layer "In13.Cu")
		(net "P5E_CPU1_PE0_RX_DN<15>")
	)
	(arc
		(start 102.80777 -217.866214)
		(mid 102.807603 -217.87739)
		(end 102.80777 -217.888566)
		(width 0.0889)
		(layer "In13.Cu")
		(net "P5E_CPU1_PE0_RX_DN<15>")
	)
	(arc
		(start 102.994968 -218.202764)
		(mid 103.197791 -218.402995)
		(end 103.277162 -218.676728)
		(width 0.0889)
		(layer "In13.Cu")
		(net "P5E_CPU1_PE0_RX_DN<15>")
	)
	(segment
		(start 102.242112 -221.134178)
		(end 102.242366 -221.133924)
		(width 0.13208)
		(layer "F.Cu")
		(net "P5E_CPU1_PE0_RX_DN<14>")
	)
	(segment
		(start 102.242112 -221.669864)
		(end 102.242112 -221.134178)
		(width 0.13208)
		(layer "F.Cu")
		(net "P5E_CPU1_PE0_RX_DN<14>")
	)
	(segment
		(start 72.944482 -215.058498)
		(end 76.755752 -210.1469)
		(width 0.14732)
		(layer "In13.Cu")
		(net "P5E_CPU1_PE0_RX_DN<14>")
	)
	(segment
		(start 60.502546 -438.593738)
		(end 59.965844 -438.593738)
		(width 0.14732)
		(layer "In13.Cu")
		(net "P5E_CPU1_PE0_RX_DN<14>")
	)
	(segment
		(start 102.055168 -216.574878)
		(end 102.061264 -216.578434)
		(width 0.0889)
		(layer "In13.Cu")
		(net "P5E_CPU1_PE0_RX_DN<14>")
	)
	(segment
		(start 101.585014 -215.112346)
		(end 101.576124 -215.117426)
		(width 0.0889)
		(layer "In13.Cu")
		(net "P5E_CPU1_PE0_RX_DN<14>")
	)
	(segment
		(start 67.676776 -249.954542)
		(end 68.983352 -232.275888)
		(width 0.14732)
		(layer "In13.Cu")
		(net "P5E_CPU1_PE0_RX_DN<14>")
	)
	(segment
		(start 102.055168 -217.554048)
		(end 102.046278 -217.559128)
		(width 0.0889)
		(layer "In13.Cu")
		(net "P5E_CPU1_PE0_RX_DN<14>")
	)
	(segment
		(start 60.65012 -439.0898)
		(end 60.65012 -438.741312)
		(width 0.14732)
		(layer "In13.Cu")
		(net "P5E_CPU1_PE0_RX_DN<14>")
	)
	(segment
		(start 102.055168 -219.830396)
		(end 102.061264 -219.833952)
		(width 0.0889)
		(layer "In13.Cu")
		(net "P5E_CPU1_PE0_RX_DN<14>")
	)
	(segment
		(start 63.21425 -320.45529)
		(end 64.189864 -320.45529)
		(width 0.14732)
		(layer "In13.Cu")
		(net "P5E_CPU1_PE0_RX_DN<14>")
	)
	(segment
		(start 52.869338 -400.580098)
		(end 53.456078 -398.073118)
		(width 0.14732)
		(layer "In13.Cu")
		(net "P5E_CPU1_PE0_RX_DN<14>")
	)
	(segment
		(start 52.869338 -404.4823)
		(end 52.869338 -400.580098)
		(width 0.14732)
		(layer "In13.Cu")
		(net "P5E_CPU1_PE0_RX_DN<14>")
	)
	(segment
		(start 93.202252 -201.338942)
		(end 100.25507 -208.39176)
		(width 0.14732)
		(layer "In13.Cu")
		(net "P5E_CPU1_PE0_RX_DN<14>")
	)
	(segment
		(start 58.755026 -325.483728)
		(end 59.53379 -323.60362)
		(width 0.14732)
		(layer "In13.Cu")
		(net "P5E_CPU1_PE0_RX_DN<14>")
	)
	(segment
		(start 101.397562 -213.8934)
		(end 101.397816 -213.893908)
		(width 0.0889)
		(layer "In13.Cu")
		(net "P5E_CPU1_PE0_RX_DN<14>")
	)
	(segment
		(start 54.37759 -412.77159)
		(end 52.939188 -411.8102)
		(width 0.14732)
		(layer "In13.Cu")
		(net "P5E_CPU1_PE0_RX_DN<14>")
	)
	(segment
		(start 59.680856 -417.446968)
		(end 57.878218 -415.644584)
		(width 0.14732)
		(layer "In13.Cu")
		(net "P5E_CPU1_PE0_RX_DN<14>")
	)
	(segment
		(start 59.115452 -363.39907)
		(end 60.03798 -343.348818)
		(width 0.14732)
		(layer "In13.Cu")
		(net "P5E_CPU1_PE0_RX_DN<14>")
	)
	(segment
		(start 58.755026 -329.63104)
		(end 58.755026 -325.483728)
		(width 0.14732)
		(layer "In13.Cu")
		(net "P5E_CPU1_PE0_RX_DN<14>")
	)
	(segment
		(start 70.991476 -308.088792)
		(end 67.53733 -254.377698)
		(width 0.14732)
		(layer "In13.Cu")
		(net "P5E_CPU1_PE0_RX_DN<14>")
	)
	(segment
		(start 68.983352 -232.275888)
		(end 68.984876 -232.26522)
		(width 0.14732)
		(layer "In13.Cu")
		(net "P5E_CPU1_PE0_RX_DN<14>")
	)
	(segment
		(start 87.231982 -200.216516)
		(end 90.492326 -200.216516)
		(width 0.14732)
		(layer "In13.Cu")
		(net "P5E_CPU1_PE0_RX_DN<14>")
	)
	(segment
		(start 51.152298 -410.698696)
		(end 51.152298 -406.19934)
		(width 0.14732)
		(layer "In13.Cu")
		(net "P5E_CPU1_PE0_RX_DN<14>")
	)
	(segment
		(start 68.984876 -232.26522)
		(end 71.092568 -218.627706)
		(width 0.14732)
		(layer "In13.Cu")
		(net "P5E_CPU1_PE0_RX_DN<14>")
	)
	(segment
		(start 101.576124 -215.755982)
		(end 101.585014 -215.761062)
		(width 0.0889)
		(layer "In13.Cu")
		(net "P5E_CPU1_PE0_RX_DN<14>")
	)
	(segment
		(start 102.046278 -216.569798)
		(end 102.055168 -216.574878)
		(width 0.0889)
		(layer "In13.Cu")
		(net "P5E_CPU1_PE0_RX_DN<14>")
	)
	(segment
		(start 101.439472 -213.15299)
		(end 101.439472 -213.175088)
		(width 0.0889)
		(layer "In13.Cu")
		(net "P5E_CPU1_PE0_RX_DN<14>")
	)
	(segment
		(start 65.342516 -319.302638)
		(end 65.882266 -318.924686)
		(width 0.14732)
		(layer "In13.Cu")
		(net "P5E_CPU1_PE0_RX_DN<14>")
	)
	(segment
		(start 64.189864 -320.45529)
		(end 65.342516 -319.302638)
		(width 0.14732)
		(layer "In13.Cu")
		(net "P5E_CPU1_PE0_RX_DN<14>")
	)
	(segment
		(start 101.439472 -213.175088)
		(end 101.397562 -213.216998)
		(width 0.0889)
		(layer "In13.Cu")
		(net "P5E_CPU1_PE0_RX_DN<14>")
	)
	(segment
		(start 59.53379 -323.60362)
		(end 59.846718 -323.290692)
		(width 0.14732)
		(layer "In13.Cu")
		(net "P5E_CPU1_PE0_RX_DN<14>")
	)
	(segment
		(start 53.456078 -398.073118)
		(end 59.115452 -363.39907)
		(width 0.14732)
		(layer "In13.Cu")
		(net "P5E_CPU1_PE0_RX_DN<14>")
	)
	(segment
		(start 57.878218 -415.644584)
		(end 54.37759 -412.77159)
		(width 0.14732)
		(layer "In13.Cu")
		(net "P5E_CPU1_PE0_RX_DN<14>")
	)
	(segment
		(start 101.585014 -215.761062)
		(end 101.59111 -215.764618)
		(width 0.0889)
		(layer "In13.Cu")
		(net "P5E_CPU1_PE0_RX_DN<14>")
	)
	(segment
		(start 65.882266 -318.924686)
		(end 67.77355 -316.224666)
		(width 0.14732)
		(layer "In13.Cu")
		(net "P5E_CPU1_PE0_RX_DN<14>")
	)
	(segment
		(start 102.055168 -219.18168)
		(end 102.046278 -219.18676)
		(width 0.0889)
		(layer "In13.Cu")
		(net "P5E_CPU1_PE0_RX_DN<14>")
	)
	(segment
		(start 102.046278 -221.453202)
		(end 102.055168 -221.458282)
		(width 0.0889)
		(layer "In13.Cu")
		(net "P5E_CPU1_PE0_RX_DN<14>")
	)
	(segment
		(start 61.158374 -322.511166)
		(end 63.21425 -320.45529)
		(width 0.14732)
		(layer "In13.Cu")
		(net "P5E_CPU1_PE0_RX_DN<14>")
	)
	(segment
		(start 102.337362 -218.676728)
		(end 102.337362 -218.707716)
		(width 0.0889)
		(layer "In13.Cu")
		(net "P5E_CPU1_PE0_RX_DN<14>")
	)
	(segment
		(start 60.776612 -322.669408)
		(end 61.158374 -322.511166)
		(width 0.14732)
		(layer "In13.Cu")
		(net "P5E_CPU1_PE0_RX_DN<14>")
	)
	(segment
		(start 71.092568 -218.627706)
		(end 72.944482 -215.058498)
		(width 0.14732)
		(layer "In13.Cu")
		(net "P5E_CPU1_PE0_RX_DN<14>")
	)
	(segment
		(start 102.046278 -219.825316)
		(end 102.055168 -219.830396)
		(width 0.0889)
		(layer "In13.Cu")
		(net "P5E_CPU1_PE0_RX_DN<14>")
	)
	(segment
		(start 76.755752 -210.1469)
		(end 84.71154 -201.518012)
		(width 0.14732)
		(layer "In13.Cu")
		(net "P5E_CPU1_PE0_RX_DN<14>")
	)
	(segment
		(start 101.439472 -211.251292)
		(end 101.439472 -213.15299)
		(width 0.14732)
		(layer "In13.Cu")
		(net "P5E_CPU1_PE0_RX_DN<14>")
	)
	(segment
		(start 100.25507 -208.39176)
		(end 101.439472 -211.251292)
		(width 0.14732)
		(layer "In13.Cu")
		(net "P5E_CPU1_PE0_RX_DN<14>")
	)
	(segment
		(start 60.03798 -343.348818)
		(end 58.755026 -329.63104)
		(width 0.14732)
		(layer "In13.Cu")
		(net "P5E_CPU1_PE0_RX_DN<14>")
	)
	(segment
		(start 67.53733 -254.377698)
		(end 67.676776 -249.954542)
		(width 0.14732)
		(layer "In13.Cu")
		(net "P5E_CPU1_PE0_RX_DN<14>")
	)
	(segment
		(start 60.65012 -438.741312)
		(end 60.502546 -438.593738)
		(width 0.14732)
		(layer "In13.Cu")
		(net "P5E_CPU1_PE0_RX_DN<14>")
	)
	(segment
		(start 51.152298 -406.19934)
		(end 52.869338 -404.4823)
		(width 0.14732)
		(layer "In13.Cu")
		(net "P5E_CPU1_PE0_RX_DN<14>")
	)
	(segment
		(start 84.71154 -201.518012)
		(end 87.231982 -200.216516)
		(width 0.14732)
		(layer "In13.Cu")
		(net "P5E_CPU1_PE0_RX_DN<14>")
	)
	(segment
		(start 102.337616 -217.064336)
		(end 102.337616 -217.07856)
		(width 0.0889)
		(layer "In13.Cu")
		(net "P5E_CPU1_PE0_RX_DN<14>")
	)
	(segment
		(start 90.492326 -200.216516)
		(end 93.202252 -201.338942)
		(width 0.14732)
		(layer "In13.Cu")
		(net "P5E_CPU1_PE0_RX_DN<14>")
	)
	(segment
		(start 59.680856 -438.30875)
		(end 59.680856 -417.446968)
		(width 0.14732)
		(layer "In13.Cu")
		(net "P5E_CPU1_PE0_RX_DN<14>")
	)
	(segment
		(start 102.337616 -220.319854)
		(end 102.337616 -220.334078)
		(width 0.0889)
		(layer "In13.Cu")
		(net "P5E_CPU1_PE0_RX_DN<14>")
	)
	(segment
		(start 102.39883 -221.404942)
		(end 102.242366 -221.133924)
		(width 0.0889)
		(layer "In13.Cu")
		(net "P5E_CPU1_PE0_RX_DN<14>")
	)
	(segment
		(start 102.377748 -221.48292)
		(end 102.39883 -221.404942)
		(width 0.0889)
		(layer "In13.Cu")
		(net "P5E_CPU1_PE0_RX_DN<14>")
	)
	(segment
		(start 67.77355 -316.224666)
		(end 70.991476 -308.088792)
		(width 0.14732)
		(layer "In13.Cu")
		(net "P5E_CPU1_PE0_RX_DN<14>")
	)
	(segment
		(start 102.046278 -218.197684)
		(end 102.055168 -218.202764)
		(width 0.0889)
		(layer "In13.Cu")
		(net "P5E_CPU1_PE0_RX_DN<14>")
	)
	(segment
		(start 102.055168 -220.809566)
		(end 102.046278 -220.814646)
		(width 0.0889)
		(layer "In13.Cu")
		(net "P5E_CPU1_PE0_RX_DN<14>")
	)
	(segment
		(start 59.846718 -323.290692)
		(end 60.776612 -322.669408)
		(width 0.14732)
		(layer "In13.Cu")
		(net "P5E_CPU1_PE0_RX_DN<14>")
	)
	(segment
		(start 52.939188 -411.8102)
		(end 51.46167 -411.198314)
		(width 0.14732)
		(layer "In13.Cu")
		(net "P5E_CPU1_PE0_RX_DN<14>")
	)
	(segment
		(start 101.867208 -214.424768)
		(end 101.867208 -214.644732)
		(width 0.0889)
		(layer "In13.Cu")
		(net "P5E_CPU1_PE0_RX_DN<14>")
	)
	(segment
		(start 101.397562 -213.216998)
		(end 101.397562 -213.8934)
		(width 0.0889)
		(layer "In13.Cu")
		(net "P5E_CPU1_PE0_RX_DN<14>")
	)
	(segment
		(start 51.46167 -411.198314)
		(end 51.152298 -410.698696)
		(width 0.14732)
		(layer "In13.Cu")
		(net "P5E_CPU1_PE0_RX_DN<14>")
	)
	(segment
		(start 59.965844 -438.593738)
		(end 59.680856 -438.30875)
		(width 0.14732)
		(layer "In13.Cu")
		(net "P5E_CPU1_PE0_RX_DN<14>")
	)
	(arc
		(start 101.397816 -213.893908)
		(mid 101.472821 -214.009367)
		(end 101.581966 -214.093298)
		(width 0.0889)
		(layer "In13.Cu")
		(net "P5E_CPU1_PE0_RX_DN<14>")
	)
	(arc
		(start 102.337616 -220.334078)
		(mid 102.258475 -220.608701)
		(end 102.055168 -220.809566)
		(width 0.0889)
		(layer "In13.Cu")
		(net "P5E_CPU1_PE0_RX_DN<14>")
	)
	(arc
		(start 101.397562 -215.436704)
		(mid 101.445241 -215.619604)
		(end 101.576124 -215.755982)
		(width 0.0889)
		(layer "In13.Cu")
		(net "P5E_CPU1_PE0_RX_DN<14>")
	)
	(arc
		(start 101.86797 -221.119192)
		(mid 101.867637 -221.131636)
		(end 101.867716 -221.144084)
		(width 0.0889)
		(layer "In13.Cu")
		(net "P5E_CPU1_PE0_RX_DN<14>")
	)
	(arc
		(start 102.055168 -218.202764)
		(mid 102.257991 -218.402995)
		(end 102.337362 -218.676728)
		(width 0.0889)
		(layer "In13.Cu")
		(net "P5E_CPU1_PE0_RX_DN<14>")
	)
	(arc
		(start 102.337616 -217.07856)
		(mid 102.258475 -217.353183)
		(end 102.055168 -217.554048)
		(width 0.0889)
		(layer "In13.Cu")
		(net "P5E_CPU1_PE0_RX_DN<14>")
	)
	(arc
		(start 101.867716 -217.888566)
		(mid 101.917785 -218.065791)
		(end 102.046278 -218.197684)
		(width 0.0889)
		(layer "In13.Cu")
		(net "P5E_CPU1_PE0_RX_DN<14>")
	)
	(arc
		(start 102.055168 -221.458282)
		(mid 102.213656 -221.507215)
		(end 102.377748 -221.48292)
		(width 0.0889)
		(layer "In13.Cu")
		(net "P5E_CPU1_PE0_RX_DN<14>")
	)
	(arc
		(start 101.867208 -214.644732)
		(mid 101.786297 -214.91486)
		(end 101.585014 -215.112346)
		(width 0.0889)
		(layer "In13.Cu")
		(net "P5E_CPU1_PE0_RX_DN<14>")
	)
	(arc
		(start 101.867716 -216.25052)
		(mid 101.915395 -216.43342)
		(end 102.046278 -216.569798)
		(width 0.0889)
		(layer "In13.Cu")
		(net "P5E_CPU1_PE0_RX_DN<14>")
	)
	(arc
		(start 102.046278 -220.814646)
		(mid 101.919024 -220.944612)
		(end 101.86797 -221.119192)
		(width 0.0889)
		(layer "In13.Cu")
		(net "P5E_CPU1_PE0_RX_DN<14>")
	)
	(arc
		(start 101.59111 -215.764618)
		(mid 101.793697 -215.970969)
		(end 101.867716 -216.25052)
		(width 0.0889)
		(layer "In13.Cu")
		(net "P5E_CPU1_PE0_RX_DN<14>")
	)
	(arc
		(start 102.061264 -216.578434)
		(mid 102.263677 -216.784847)
		(end 102.337616 -217.064336)
		(width 0.0889)
		(layer "In13.Cu")
		(net "P5E_CPU1_PE0_RX_DN<14>")
	)
	(arc
		(start 101.86797 -217.863674)
		(mid 101.867637 -217.876118)
		(end 101.867716 -217.888566)
		(width 0.0889)
		(layer "In13.Cu")
		(net "P5E_CPU1_PE0_RX_DN<14>")
	)
	(arc
		(start 101.867716 -221.144084)
		(mid 101.917785 -221.321309)
		(end 102.046278 -221.453202)
		(width 0.0889)
		(layer "In13.Cu")
		(net "P5E_CPU1_PE0_RX_DN<14>")
	)
	(arc
		(start 102.061264 -219.833952)
		(mid 102.263677 -220.040365)
		(end 102.337616 -220.319854)
		(width 0.0889)
		(layer "In13.Cu")
		(net "P5E_CPU1_PE0_RX_DN<14>")
	)
	(arc
		(start 102.046278 -219.18676)
		(mid 101.867802 -219.506038)
		(end 102.046278 -219.825316)
		(width 0.0889)
		(layer "In13.Cu")
		(net "P5E_CPU1_PE0_RX_DN<14>")
	)
	(arc
		(start 101.397816 -215.421972)
		(mid 101.397619 -215.429337)
		(end 101.397562 -215.436704)
		(width 0.0889)
		(layer "In13.Cu")
		(net "P5E_CPU1_PE0_RX_DN<14>")
	)
	(arc
		(start 102.046278 -217.559128)
		(mid 101.919024 -217.689094)
		(end 101.86797 -217.863674)
		(width 0.0889)
		(layer "In13.Cu")
		(net "P5E_CPU1_PE0_RX_DN<14>")
	)
	(arc
		(start 101.581966 -214.093298)
		(mid 101.755929 -214.232062)
		(end 101.867208 -214.424768)
		(width 0.0889)
		(layer "In13.Cu")
		(net "P5E_CPU1_PE0_RX_DN<14>")
	)
	(arc
		(start 101.576124 -215.117426)
		(mid 101.44887 -215.247392)
		(end 101.397816 -215.421972)
		(width 0.0889)
		(layer "In13.Cu")
		(net "P5E_CPU1_PE0_RX_DN<14>")
	)
	(arc
		(start 102.337362 -218.707716)
		(mid 102.257992 -218.98145)
		(end 102.055168 -219.18168)
		(width 0.0889)
		(layer "In13.Cu")
		(net "P5E_CPU1_PE0_RX_DN<14>")
	)
	(segment
		(start 101.718618 -220.373448)
		(end 101.772212 -220.319854)
		(width 0.13208)
		(layer "F.Cu")
		(net "P5E_CPU1_PE0_RX_DN<13>")
	)
	(segment
		(start 101.718618 -220.801946)
		(end 101.718618 -220.373448)
		(width 0.13208)
		(layer "F.Cu")
		(net "P5E_CPU1_PE0_RX_DN<13>")
	)
	(segment
		(start 101.772466 -220.855794)
		(end 101.718618 -220.801946)
		(width 0.13208)
		(layer "F.Cu")
		(net "P5E_CPU1_PE0_RX_DN<13>")
	)
	(segment
		(start 54.317138 -410.859732)
		(end 54.215538 -410.55417)
		(width 0.14732)
		(layer "In13.Cu")
		(net "P5E_CPU1_PE0_RX_DN<13>")
	)
	(segment
		(start 61.680852 -437.23052)
		(end 61.680852 -417.446968)
		(width 0.14732)
		(layer "In13.Cu")
		(net "P5E_CPU1_PE0_RX_DN<13>")
	)
	(segment
		(start 101.53777 -220.6117)
		(end 101.615748 -220.590872)
		(width 0.0889)
		(layer "In13.Cu")
		(net "P5E_CPU1_PE0_RX_DN<13>")
	)
	(segment
		(start 92.650818 -202.116944)
		(end 99.39274 -208.858866)
		(width 0.14732)
		(layer "In13.Cu")
		(net "P5E_CPU1_PE0_RX_DN<13>")
	)
	(segment
		(start 100.645214 -215.761062)
		(end 100.65131 -215.764618)
		(width 0.0889)
		(layer "In13.Cu")
		(net "P5E_CPU1_PE0_RX_DN<13>")
	)
	(segment
		(start 59.730386 -326.51573)
		(end 59.9313 -326.031098)
		(width 0.14732)
		(layer "In13.Cu")
		(net "P5E_CPU1_PE0_RX_DN<13>")
	)
	(segment
		(start 101.106478 -216.569798)
		(end 101.115368 -216.574878)
		(width 0.0889)
		(layer "In13.Cu")
		(net "P5E_CPU1_PE0_RX_DN<13>")
	)
	(segment
		(start 55.932578 -404.4823)
		(end 55.932578 -400.692874)
		(width 0.14732)
		(layer "In13.Cu")
		(net "P5E_CPU1_PE0_RX_DN<13>")
	)
	(segment
		(start 68.497704 -253.4666)
		(end 68.61429 -249.99823)
		(width 0.14732)
		(layer "In13.Cu")
		(net "P5E_CPU1_PE0_RX_DN<13>")
	)
	(segment
		(start 61.680852 -417.446968)
		(end 58.953908 -414.720278)
		(width 0.14732)
		(layer "In13.Cu")
		(net "P5E_CPU1_PE0_RX_DN<13>")
	)
	(segment
		(start 62.650116 -437.741314)
		(end 62.502542 -437.59374)
		(width 0.14732)
		(layer "In13.Cu")
		(net "P5E_CPU1_PE0_RX_DN<13>")
	)
	(segment
		(start 100.499418 -211.530946)
		(end 100.499418 -213.17585)
		(width 0.14732)
		(layer "In13.Cu")
		(net "P5E_CPU1_PE0_RX_DN<13>")
	)
	(segment
		(start 69.912484 -232.419144)
		(end 69.914008 -232.408476)
		(width 0.14732)
		(layer "In13.Cu")
		(net "P5E_CPU1_PE0_RX_DN<13>")
	)
	(segment
		(start 90.331544 -201.156316)
		(end 92.650818 -202.116944)
		(width 0.14732)
		(layer "In13.Cu")
		(net "P5E_CPU1_PE0_RX_DN<13>")
	)
	(segment
		(start 58.953908 -414.720278)
		(end 54.624224 -411.166818)
		(width 0.14732)
		(layer "In13.Cu")
		(net "P5E_CPU1_PE0_RX_DN<13>")
	)
	(segment
		(start 66.695828 -319.53708)
		(end 68.604638 -316.81166)
		(width 0.14732)
		(layer "In13.Cu")
		(net "P5E_CPU1_PE0_RX_DN<13>")
	)
	(segment
		(start 54.215538 -406.19934)
		(end 55.932578 -404.4823)
		(width 0.14732)
		(layer "In13.Cu")
		(net "P5E_CPU1_PE0_RX_DN<13>")
	)
	(segment
		(start 100.499418 -213.17585)
		(end 100.499418 -213.197948)
		(width 0.0889)
		(layer "In13.Cu")
		(net "P5E_CPU1_PE0_RX_DN<13>")
	)
	(segment
		(start 54.215538 -410.55417)
		(end 54.215538 -406.19934)
		(width 0.14732)
		(layer "In13.Cu")
		(net "P5E_CPU1_PE0_RX_DN<13>")
	)
	(segment
		(start 68.497704 -254.31115)
		(end 68.497704 -253.4666)
		(width 0.14732)
		(layer "In13.Cu")
		(net "P5E_CPU1_PE0_RX_DN<13>")
	)
	(segment
		(start 100.457508 -213.239858)
		(end 100.457508 -213.814406)
		(width 0.0889)
		(layer "In13.Cu")
		(net "P5E_CPU1_PE0_RX_DN<13>")
	)
	(segment
		(start 69.914008 -232.408476)
		(end 71.998078 -218.923616)
		(width 0.14732)
		(layer "In13.Cu")
		(net "P5E_CPU1_PE0_RX_DN<13>")
	)
	(segment
		(start 101.115368 -219.18168)
		(end 101.106478 -219.18676)
		(width 0.0889)
		(layer "In13.Cu")
		(net "P5E_CPU1_PE0_RX_DN<13>")
	)
	(segment
		(start 56.325262 -398.818608)
		(end 60.042806 -363.483652)
		(width 0.14732)
		(layer "In13.Cu")
		(net "P5E_CPU1_PE0_RX_DN<13>")
	)
	(segment
		(start 99.39274 -208.858866)
		(end 100.499418 -211.530946)
		(width 0.14732)
		(layer "In13.Cu")
		(net "P5E_CPU1_PE0_RX_DN<13>")
	)
	(segment
		(start 101.397816 -220.309948)
		(end 101.397816 -220.32849)
		(width 0.0889)
		(layer "In13.Cu")
		(net "P5E_CPU1_PE0_RX_DN<13>")
	)
	(segment
		(start 66.256662 -319.976246)
		(end 66.695828 -319.53708)
		(width 0.14732)
		(layer "In13.Cu")
		(net "P5E_CPU1_PE0_RX_DN<13>")
	)
	(segment
		(start 100.645214 -215.112346)
		(end 100.636324 -215.117426)
		(width 0.0889)
		(layer "In13.Cu")
		(net "P5E_CPU1_PE0_RX_DN<13>")
	)
	(segment
		(start 101.615748 -220.590872)
		(end 101.772212 -220.319854)
		(width 0.0889)
		(layer "In13.Cu")
		(net "P5E_CPU1_PE0_RX_DN<13>")
	)
	(segment
		(start 100.636324 -215.755982)
		(end 100.645214 -215.761062)
		(width 0.0889)
		(layer "In13.Cu")
		(net "P5E_CPU1_PE0_RX_DN<13>")
	)
	(segment
		(start 55.932578 -400.692874)
		(end 56.325262 -398.818608)
		(width 0.14732)
		(layer "In13.Cu")
		(net "P5E_CPU1_PE0_RX_DN<13>")
	)
	(segment
		(start 87.460836 -201.156316)
		(end 90.331544 -201.156316)
		(width 0.14732)
		(layer "In13.Cu")
		(net "P5E_CPU1_PE0_RX_DN<13>")
	)
	(segment
		(start 61.255402 -343.028778)
		(end 59.730386 -328.762106)
		(width 0.14732)
		(layer "In13.Cu")
		(net "P5E_CPU1_PE0_RX_DN<13>")
	)
	(segment
		(start 62.044072 -437.59374)
		(end 61.680852 -437.23052)
		(width 0.14732)
		(layer "In13.Cu")
		(net "P5E_CPU1_PE0_RX_DN<13>")
	)
	(segment
		(start 59.9313 -326.031098)
		(end 61.577728 -324.38467)
		(width 0.14732)
		(layer "In13.Cu")
		(net "P5E_CPU1_PE0_RX_DN<13>")
	)
	(segment
		(start 60.042806 -363.483652)
		(end 61.255402 -343.028778)
		(width 0.14732)
		(layer "In13.Cu")
		(net "P5E_CPU1_PE0_RX_DN<13>")
	)
	(segment
		(start 54.624224 -411.166818)
		(end 54.317138 -410.859732)
		(width 0.14732)
		(layer "In13.Cu")
		(net "P5E_CPU1_PE0_RX_DN<13>")
	)
	(segment
		(start 85.290152 -202.277218)
		(end 87.460836 -201.156316)
		(width 0.14732)
		(layer "In13.Cu")
		(net "P5E_CPU1_PE0_RX_DN<13>")
	)
	(segment
		(start 73.739502 -215.56726)
		(end 77.474064 -210.754722)
		(width 0.14732)
		(layer "In13.Cu")
		(net "P5E_CPU1_PE0_RX_DN<13>")
	)
	(segment
		(start 61.577728 -324.38467)
		(end 63.696596 -323.507354)
		(width 0.14732)
		(layer "In13.Cu")
		(net "P5E_CPU1_PE0_RX_DN<13>")
	)
	(segment
		(start 71.998078 -218.923616)
		(end 73.739502 -215.56726)
		(width 0.14732)
		(layer "In13.Cu")
		(net "P5E_CPU1_PE0_RX_DN<13>")
	)
	(segment
		(start 65.569846 -321.634104)
		(end 66.256662 -319.976246)
		(width 0.14732)
		(layer "In13.Cu")
		(net "P5E_CPU1_PE0_RX_DN<13>")
	)
	(segment
		(start 68.61429 -249.99823)
		(end 69.912484 -232.419144)
		(width 0.14732)
		(layer "In13.Cu")
		(net "P5E_CPU1_PE0_RX_DN<13>")
	)
	(segment
		(start 62.650116 -438.089802)
		(end 62.650116 -437.741314)
		(width 0.14732)
		(layer "In13.Cu")
		(net "P5E_CPU1_PE0_RX_DN<13>")
	)
	(segment
		(start 100.499418 -213.197948)
		(end 100.457508 -213.239858)
		(width 0.0889)
		(layer "In13.Cu")
		(net "P5E_CPU1_PE0_RX_DN<13>")
	)
	(segment
		(start 63.696596 -323.507354)
		(end 65.569846 -321.634104)
		(width 0.14732)
		(layer "In13.Cu")
		(net "P5E_CPU1_PE0_RX_DN<13>")
	)
	(segment
		(start 100.457762 -213.81466)
		(end 100.457762 -213.8934)
		(width 0.0889)
		(layer "In13.Cu")
		(net "P5E_CPU1_PE0_RX_DN<13>")
	)
	(segment
		(start 100.457508 -213.814406)
		(end 100.457762 -213.81466)
		(width 0.0889)
		(layer "In13.Cu")
		(net "P5E_CPU1_PE0_RX_DN<13>")
	)
	(segment
		(start 101.106478 -219.825316)
		(end 101.115368 -219.830396)
		(width 0.0889)
		(layer "In13.Cu")
		(net "P5E_CPU1_PE0_RX_DN<13>")
	)
	(segment
		(start 100.457762 -213.8934)
		(end 100.458016 -213.893908)
		(width 0.0889)
		(layer "In13.Cu")
		(net "P5E_CPU1_PE0_RX_DN<13>")
	)
	(segment
		(start 62.502542 -437.59374)
		(end 62.044072 -437.59374)
		(width 0.14732)
		(layer "In13.Cu")
		(net "P5E_CPU1_PE0_RX_DN<13>")
	)
	(segment
		(start 101.397816 -217.05443)
		(end 101.397816 -217.082878)
		(width 0.0889)
		(layer "In13.Cu")
		(net "P5E_CPU1_PE0_RX_DN<13>")
	)
	(segment
		(start 59.730386 -328.762106)
		(end 59.730386 -326.51573)
		(width 0.14732)
		(layer "In13.Cu")
		(net "P5E_CPU1_PE0_RX_DN<13>")
	)
	(segment
		(start 101.106478 -218.197684)
		(end 101.115368 -218.202764)
		(width 0.0889)
		(layer "In13.Cu")
		(net "P5E_CPU1_PE0_RX_DN<13>")
	)
	(segment
		(start 68.604638 -316.81166)
		(end 72.002904 -308.616858)
		(width 0.14732)
		(layer "In13.Cu")
		(net "P5E_CPU1_PE0_RX_DN<13>")
	)
	(segment
		(start 77.474064 -210.754722)
		(end 85.290152 -202.277218)
		(width 0.14732)
		(layer "In13.Cu")
		(net "P5E_CPU1_PE0_RX_DN<13>")
	)
	(segment
		(start 101.397562 -218.676728)
		(end 101.397562 -218.707716)
		(width 0.0889)
		(layer "In13.Cu")
		(net "P5E_CPU1_PE0_RX_DN<13>")
	)
	(segment
		(start 100.927408 -214.424768)
		(end 100.927408 -214.644732)
		(width 0.0889)
		(layer "In13.Cu")
		(net "P5E_CPU1_PE0_RX_DN<13>")
	)
	(segment
		(start 101.115368 -217.554048)
		(end 101.106478 -217.559128)
		(width 0.0889)
		(layer "In13.Cu")
		(net "P5E_CPU1_PE0_RX_DN<13>")
	)
	(segment
		(start 72.002904 -308.616858)
		(end 68.497704 -254.31115)
		(width 0.14732)
		(layer "In13.Cu")
		(net "P5E_CPU1_PE0_RX_DN<13>")
	)
	(arc
		(start 100.92817 -219.512642)
		(mid 100.977277 -219.691831)
		(end 101.106478 -219.825316)
		(width 0.0889)
		(layer "In13.Cu")
		(net "P5E_CPU1_PE0_RX_DN<13>")
	)
	(arc
		(start 100.458016 -213.893908)
		(mid 100.533021 -214.009367)
		(end 100.642166 -214.093298)
		(width 0.0889)
		(layer "In13.Cu")
		(net "P5E_CPU1_PE0_RX_DN<13>")
	)
	(arc
		(start 101.397562 -218.707716)
		(mid 101.318192 -218.98145)
		(end 101.115368 -219.18168)
		(width 0.0889)
		(layer "In13.Cu")
		(net "P5E_CPU1_PE0_RX_DN<13>")
	)
	(arc
		(start 100.642166 -214.093298)
		(mid 100.816129 -214.232062)
		(end 100.927408 -214.424768)
		(width 0.0889)
		(layer "In13.Cu")
		(net "P5E_CPU1_PE0_RX_DN<13>")
	)
	(arc
		(start 100.92817 -219.495878)
		(mid 100.928076 -219.50426)
		(end 100.92817 -219.512642)
		(width 0.0889)
		(layer "In13.Cu")
		(net "P5E_CPU1_PE0_RX_DN<13>")
	)
	(arc
		(start 101.106478 -217.559128)
		(mid 100.978585 -217.69019)
		(end 100.92817 -217.866214)
		(width 0.0889)
		(layer "In13.Cu")
		(net "P5E_CPU1_PE0_RX_DN<13>")
	)
	(arc
		(start 101.397816 -217.082878)
		(mid 101.317654 -217.355067)
		(end 101.115368 -217.554048)
		(width 0.0889)
		(layer "In13.Cu")
		(net "P5E_CPU1_PE0_RX_DN<13>")
	)
	(arc
		(start 100.927408 -214.644732)
		(mid 100.846497 -214.91486)
		(end 100.645214 -215.112346)
		(width 0.0889)
		(layer "In13.Cu")
		(net "P5E_CPU1_PE0_RX_DN<13>")
	)
	(arc
		(start 100.457762 -215.436704)
		(mid 100.505441 -215.619604)
		(end 100.636324 -215.755982)
		(width 0.0889)
		(layer "In13.Cu")
		(net "P5E_CPU1_PE0_RX_DN<13>")
	)
	(arc
		(start 101.115368 -219.830396)
		(mid 101.319703 -220.033001)
		(end 101.397816 -220.309948)
		(width 0.0889)
		(layer "In13.Cu")
		(net "P5E_CPU1_PE0_RX_DN<13>")
	)
	(arc
		(start 100.636324 -215.117426)
		(mid 100.50907 -215.247392)
		(end 100.458016 -215.421972)
		(width 0.0889)
		(layer "In13.Cu")
		(net "P5E_CPU1_PE0_RX_DN<13>")
	)
	(arc
		(start 100.927916 -216.25052)
		(mid 100.975595 -216.43342)
		(end 101.106478 -216.569798)
		(width 0.0889)
		(layer "In13.Cu")
		(net "P5E_CPU1_PE0_RX_DN<13>")
	)
	(arc
		(start 101.397816 -220.32849)
		(mid 101.43649 -220.485558)
		(end 101.53777 -220.6117)
		(width 0.0889)
		(layer "In13.Cu")
		(net "P5E_CPU1_PE0_RX_DN<13>")
	)
	(arc
		(start 101.115368 -216.574878)
		(mid 101.319703 -216.777483)
		(end 101.397816 -217.05443)
		(width 0.0889)
		(layer "In13.Cu")
		(net "P5E_CPU1_PE0_RX_DN<13>")
	)
	(arc
		(start 100.92817 -217.866214)
		(mid 100.928003 -217.87739)
		(end 100.92817 -217.888566)
		(width 0.0889)
		(layer "In13.Cu")
		(net "P5E_CPU1_PE0_RX_DN<13>")
	)
	(arc
		(start 101.115368 -218.202764)
		(mid 101.318191 -218.402995)
		(end 101.397562 -218.676728)
		(width 0.0889)
		(layer "In13.Cu")
		(net "P5E_CPU1_PE0_RX_DN<13>")
	)
	(arc
		(start 100.92817 -217.888566)
		(mid 100.978185 -218.065697)
		(end 101.106478 -218.197684)
		(width 0.0889)
		(layer "In13.Cu")
		(net "P5E_CPU1_PE0_RX_DN<13>")
	)
	(arc
		(start 101.106478 -219.18676)
		(mid 100.978159 -219.318732)
		(end 100.92817 -219.495878)
		(width 0.0889)
		(layer "In13.Cu")
		(net "P5E_CPU1_PE0_RX_DN<13>")
	)
	(arc
		(start 100.65131 -215.764618)
		(mid 100.853897 -215.970969)
		(end 100.927916 -216.25052)
		(width 0.0889)
		(layer "In13.Cu")
		(net "P5E_CPU1_PE0_RX_DN<13>")
	)
	(arc
		(start 100.458016 -215.421972)
		(mid 100.457819 -215.429337)
		(end 100.457762 -215.436704)
		(width 0.0889)
		(layer "In13.Cu")
		(net "P5E_CPU1_PE0_RX_DN<13>")
	)
	(segment
		(start 100.362512 -221.669864)
		(end 100.362512 -221.134178)
		(width 0.13208)
		(layer "F.Cu")
		(net "P5E_CPU1_PE0_RX_DN<12>")
	)
	(segment
		(start 100.362512 -221.134178)
		(end 100.362766 -221.133924)
		(width 0.13208)
		(layer "F.Cu")
		(net "P5E_CPU1_PE0_RX_DN<12>")
	)
	(segment
		(start 73.026016 -219.259658)
		(end 74.641964 -216.144856)
		(width 0.14732)
		(layer "In13.Cu")
		(net "P5E_CPU1_PE0_RX_DN<12>")
	)
	(segment
		(start 70.968616 -232.571036)
		(end 73.026016 -219.259658)
		(width 0.14732)
		(layer "In13.Cu")
		(net "P5E_CPU1_PE0_RX_DN<12>")
	)
	(segment
		(start 59.358022 -398.056862)
		(end 59.421014 -396.967202)
		(width 0.14732)
		(layer "In13.Cu")
		(net "P5E_CPU1_PE0_RX_DN<12>")
	)
	(segment
		(start 99.559872 -211.754212)
		(end 99.559872 -213.17585)
		(width 0.14732)
		(layer "In13.Cu")
		(net "P5E_CPU1_PE0_RX_DN<12>")
	)
	(segment
		(start 57.278778 -406.19934)
		(end 58.995818 -404.4823)
		(width 0.14732)
		(layer "In13.Cu")
		(net "P5E_CPU1_PE0_RX_DN<12>")
	)
	(segment
		(start 100.458016 -220.319854)
		(end 100.458016 -220.334078)
		(width 0.0889)
		(layer "In13.Cu")
		(net "P5E_CPU1_PE0_RX_DN<12>")
	)
	(segment
		(start 100.166678 -221.453202)
		(end 100.175568 -221.458282)
		(width 0.0889)
		(layer "In13.Cu")
		(net "P5E_CPU1_PE0_RX_DN<12>")
	)
	(segment
		(start 100.458016 -217.064336)
		(end 100.458016 -217.07856)
		(width 0.0889)
		(layer "In13.Cu")
		(net "P5E_CPU1_PE0_RX_DN<12>")
	)
	(segment
		(start 74.641964 -216.144856)
		(end 78.289404 -211.44484)
		(width 0.14732)
		(layer "In13.Cu")
		(net "P5E_CPU1_PE0_RX_DN<12>")
	)
	(segment
		(start 63.965836 -438.593738)
		(end 63.680848 -438.30875)
		(width 0.14732)
		(layer "In13.Cu")
		(net "P5E_CPU1_PE0_RX_DN<12>")
	)
	(segment
		(start 99.705414 -215.761062)
		(end 99.71151 -215.764618)
		(width 0.0889)
		(layer "In13.Cu")
		(net "P5E_CPU1_PE0_RX_DN<12>")
	)
	(segment
		(start 99.987608 -214.424768)
		(end 99.987608 -214.644732)
		(width 0.0889)
		(layer "In13.Cu")
		(net "P5E_CPU1_PE0_RX_DN<12>")
	)
	(segment
		(start 98.601784 -209.441034)
		(end 99.559872 -211.754212)
		(width 0.14732)
		(layer "In13.Cu")
		(net "P5E_CPU1_PE0_RX_DN<12>")
	)
	(segment
		(start 58.995818 -400.522694)
		(end 59.358022 -398.056862)
		(width 0.14732)
		(layer "In13.Cu")
		(net "P5E_CPU1_PE0_RX_DN<12>")
	)
	(segment
		(start 72.982836 -308.883558)
		(end 69.429376 -253.700026)
		(width 0.14732)
		(layer "In13.Cu")
		(net "P5E_CPU1_PE0_RX_DN<12>")
	)
	(segment
		(start 57.278778 -410.357574)
		(end 57.278778 -406.19934)
		(width 0.14732)
		(layer "In13.Cu")
		(net "P5E_CPU1_PE0_RX_DN<12>")
	)
	(segment
		(start 63.680848 -417.208208)
		(end 57.59577 -411.12313)
		(width 0.14732)
		(layer "In13.Cu")
		(net "P5E_CPU1_PE0_RX_DN<12>")
	)
	(segment
		(start 100.166678 -219.825316)
		(end 100.175568 -219.830396)
		(width 0.0889)
		(layer "In13.Cu")
		(net "P5E_CPU1_PE0_RX_DN<12>")
	)
	(segment
		(start 100.166678 -218.197684)
		(end 100.175568 -218.202764)
		(width 0.0889)
		(layer "In13.Cu")
		(net "P5E_CPU1_PE0_RX_DN<12>")
	)
	(segment
		(start 60.768992 -326.566022)
		(end 61.725556 -325.609458)
		(width 0.14732)
		(layer "In13.Cu")
		(net "P5E_CPU1_PE0_RX_DN<12>")
	)
	(segment
		(start 64.502538 -438.593738)
		(end 63.965836 -438.593738)
		(width 0.14732)
		(layer "In13.Cu")
		(net "P5E_CPU1_PE0_RX_DN<12>")
	)
	(segment
		(start 100.175568 -219.830396)
		(end 100.181664 -219.833952)
		(width 0.0889)
		(layer "In13.Cu")
		(net "P5E_CPU1_PE0_RX_DN<12>")
	)
	(segment
		(start 78.289404 -211.44484)
		(end 82.106008 -207.305402)
		(width 0.14732)
		(layer "In13.Cu")
		(net "P5E_CPU1_PE0_RX_DN<12>")
	)
	(segment
		(start 100.498148 -221.48292)
		(end 100.51923 -221.404942)
		(width 0.0889)
		(layer "In13.Cu")
		(net "P5E_CPU1_PE0_RX_DN<12>")
	)
	(segment
		(start 99.559872 -213.197948)
		(end 99.517962 -213.239858)
		(width 0.0889)
		(layer "In13.Cu")
		(net "P5E_CPU1_PE0_RX_DN<12>")
	)
	(segment
		(start 100.457762 -218.676728)
		(end 100.457762 -218.707716)
		(width 0.0889)
		(layer "In13.Cu")
		(net "P5E_CPU1_PE0_RX_DN<12>")
	)
	(segment
		(start 64.650112 -438.741312)
		(end 64.502538 -438.593738)
		(width 0.14732)
		(layer "In13.Cu")
		(net "P5E_CPU1_PE0_RX_DN<12>")
	)
	(segment
		(start 69.608192 -317.02883)
		(end 72.982836 -308.883558)
		(width 0.14732)
		(layer "In13.Cu")
		(net "P5E_CPU1_PE0_RX_DN<12>")
	)
	(segment
		(start 61.725556 -325.609458)
		(end 64.026288 -325.609458)
		(width 0.14732)
		(layer "In13.Cu")
		(net "P5E_CPU1_PE0_RX_DN<12>")
	)
	(segment
		(start 60.768992 -328.899774)
		(end 60.768992 -326.566022)
		(width 0.14732)
		(layer "In13.Cu")
		(net "P5E_CPU1_PE0_RX_DN<12>")
	)
	(segment
		(start 99.517962 -213.239858)
		(end 99.517962 -213.8934)
		(width 0.0889)
		(layer "In13.Cu")
		(net "P5E_CPU1_PE0_RX_DN<12>")
	)
	(segment
		(start 57.59577 -411.12313)
		(end 57.278778 -410.357574)
		(width 0.14732)
		(layer "In13.Cu")
		(net "P5E_CPU1_PE0_RX_DN<12>")
	)
	(segment
		(start 70.967092 -232.580688)
		(end 70.968616 -232.571036)
		(width 0.14732)
		(layer "In13.Cu")
		(net "P5E_CPU1_PE0_RX_DN<12>")
	)
	(segment
		(start 69.55155 -250.041156)
		(end 70.967092 -232.580688)
		(width 0.14732)
		(layer "In13.Cu")
		(net "P5E_CPU1_PE0_RX_DN<12>")
	)
	(segment
		(start 85.94725 -203.13904)
		(end 87.720424 -202.223116)
		(width 0.14732)
		(layer "In13.Cu")
		(net "P5E_CPU1_PE0_RX_DN<12>")
	)
	(segment
		(start 99.705414 -215.112346)
		(end 99.696524 -215.117426)
		(width 0.0889)
		(layer "In13.Cu")
		(net "P5E_CPU1_PE0_RX_DN<12>")
	)
	(segment
		(start 67.199764 -320.391282)
		(end 67.379342 -320.210942)
		(width 0.14732)
		(layer "In13.Cu")
		(net "P5E_CPU1_PE0_RX_DN<12>")
	)
	(segment
		(start 59.421268 -396.967202)
		(end 62.463934 -344.512646)
		(width 0.14732)
		(layer "In13.Cu")
		(net "P5E_CPU1_PE0_RX_DN<12>")
	)
	(segment
		(start 100.175568 -220.809566)
		(end 100.166678 -220.814646)
		(width 0.0889)
		(layer "In13.Cu")
		(net "P5E_CPU1_PE0_RX_DN<12>")
	)
	(segment
		(start 67.379342 -320.210942)
		(end 69.608192 -317.02883)
		(width 0.14732)
		(layer "In13.Cu")
		(net "P5E_CPU1_PE0_RX_DN<12>")
	)
	(segment
		(start 65.753742 -323.882004)
		(end 67.199764 -320.391282)
		(width 0.14732)
		(layer "In13.Cu")
		(net "P5E_CPU1_PE0_RX_DN<12>")
	)
	(segment
		(start 63.680848 -438.30875)
		(end 63.680848 -417.208208)
		(width 0.14732)
		(layer "In13.Cu")
		(net "P5E_CPU1_PE0_RX_DN<12>")
	)
	(segment
		(start 100.175568 -216.574878)
		(end 100.181664 -216.578434)
		(width 0.0889)
		(layer "In13.Cu")
		(net "P5E_CPU1_PE0_RX_DN<12>")
	)
	(segment
		(start 64.026288 -325.609458)
		(end 65.753742 -323.882004)
		(width 0.14732)
		(layer "In13.Cu")
		(net "P5E_CPU1_PE0_RX_DN<12>")
	)
	(segment
		(start 99.559872 -213.17585)
		(end 99.559872 -213.197948)
		(width 0.0889)
		(layer "In13.Cu")
		(net "P5E_CPU1_PE0_RX_DN<12>")
	)
	(segment
		(start 99.517962 -213.8934)
		(end 99.518216 -213.893908)
		(width 0.0889)
		(layer "In13.Cu")
		(net "P5E_CPU1_PE0_RX_DN<12>")
	)
	(segment
		(start 100.175568 -217.554048)
		(end 100.166678 -217.559128)
		(width 0.0889)
		(layer "In13.Cu")
		(net "P5E_CPU1_PE0_RX_DN<12>")
	)
	(segment
		(start 100.175568 -219.18168)
		(end 100.166678 -219.18676)
		(width 0.0889)
		(layer "In13.Cu")
		(net "P5E_CPU1_PE0_RX_DN<12>")
	)
	(segment
		(start 87.720424 -202.223116)
		(end 90.24239 -202.223116)
		(width 0.14732)
		(layer "In13.Cu")
		(net "P5E_CPU1_PE0_RX_DN<12>")
	)
	(segment
		(start 62.463934 -344.512646)
		(end 60.768992 -328.899774)
		(width 0.14732)
		(layer "In13.Cu")
		(net "P5E_CPU1_PE0_RX_DN<12>")
	)
	(segment
		(start 100.166678 -216.569798)
		(end 100.175568 -216.574878)
		(width 0.0889)
		(layer "In13.Cu")
		(net "P5E_CPU1_PE0_RX_DN<12>")
	)
	(segment
		(start 92.190824 -203.030074)
		(end 98.601784 -209.441034)
		(width 0.14732)
		(layer "In13.Cu")
		(net "P5E_CPU1_PE0_RX_DN<12>")
	)
	(segment
		(start 58.995818 -404.4823)
		(end 58.995818 -400.522694)
		(width 0.14732)
		(layer "In13.Cu")
		(net "P5E_CPU1_PE0_RX_DN<12>")
	)
	(segment
		(start 69.429376 -253.700026)
		(end 69.55155 -250.041156)
		(width 0.14732)
		(layer "In13.Cu")
		(net "P5E_CPU1_PE0_RX_DN<12>")
	)
	(segment
		(start 99.696524 -215.755982)
		(end 99.705414 -215.761062)
		(width 0.0889)
		(layer "In13.Cu")
		(net "P5E_CPU1_PE0_RX_DN<12>")
	)
	(segment
		(start 82.106262 -207.305402)
		(end 85.94725 -203.13904)
		(width 0.14732)
		(layer "In13.Cu")
		(net "P5E_CPU1_PE0_RX_DN<12>")
	)
	(segment
		(start 100.51923 -221.404942)
		(end 100.362766 -221.133924)
		(width 0.0889)
		(layer "In13.Cu")
		(net "P5E_CPU1_PE0_RX_DN<12>")
	)
	(segment
		(start 90.24239 -202.223116)
		(end 92.190824 -203.030074)
		(width 0.14732)
		(layer "In13.Cu")
		(net "P5E_CPU1_PE0_RX_DN<12>")
	)
	(segment
		(start 59.421014 -396.967202)
		(end 59.421268 -396.967202)
		(width 0.14732)
		(layer "In13.Cu")
		(net "P5E_CPU1_PE0_RX_DN<12>")
	)
	(segment
		(start 64.650112 -439.0898)
		(end 64.650112 -438.741312)
		(width 0.14732)
		(layer "In13.Cu")
		(net "P5E_CPU1_PE0_RX_DN<12>")
	)
	(segment
		(start 82.106008 -207.305402)
		(end 82.106262 -207.305402)
		(width 0.14732)
		(layer "In13.Cu")
		(net "P5E_CPU1_PE0_RX_DN<12>")
	)
	(arc
		(start 99.98837 -221.119192)
		(mid 99.988037 -221.131636)
		(end 99.988116 -221.144084)
		(width 0.0889)
		(layer "In13.Cu")
		(net "P5E_CPU1_PE0_RX_DN<12>")
	)
	(arc
		(start 99.98837 -217.863674)
		(mid 99.988037 -217.876118)
		(end 99.988116 -217.888566)
		(width 0.0889)
		(layer "In13.Cu")
		(net "P5E_CPU1_PE0_RX_DN<12>")
	)
	(arc
		(start 99.988116 -217.888566)
		(mid 100.038185 -218.065791)
		(end 100.166678 -218.197684)
		(width 0.0889)
		(layer "In13.Cu")
		(net "P5E_CPU1_PE0_RX_DN<12>")
	)
	(arc
		(start 99.518216 -213.893908)
		(mid 99.593221 -214.009367)
		(end 99.702366 -214.093298)
		(width 0.0889)
		(layer "In13.Cu")
		(net "P5E_CPU1_PE0_RX_DN<12>")
	)
	(arc
		(start 99.702366 -214.093298)
		(mid 99.876329 -214.232062)
		(end 99.987608 -214.424768)
		(width 0.0889)
		(layer "In13.Cu")
		(net "P5E_CPU1_PE0_RX_DN<12>")
	)
	(arc
		(start 99.987608 -214.644732)
		(mid 99.906697 -214.91486)
		(end 99.705414 -215.112346)
		(width 0.0889)
		(layer "In13.Cu")
		(net "P5E_CPU1_PE0_RX_DN<12>")
	)
	(arc
		(start 99.696524 -215.117426)
		(mid 99.56927 -215.247392)
		(end 99.518216 -215.421972)
		(width 0.0889)
		(layer "In13.Cu")
		(net "P5E_CPU1_PE0_RX_DN<12>")
	)
	(arc
		(start 100.166678 -217.559128)
		(mid 100.039424 -217.689094)
		(end 99.98837 -217.863674)
		(width 0.0889)
		(layer "In13.Cu")
		(net "P5E_CPU1_PE0_RX_DN<12>")
	)
	(arc
		(start 100.458016 -217.07856)
		(mid 100.378875 -217.353183)
		(end 100.175568 -217.554048)
		(width 0.0889)
		(layer "In13.Cu")
		(net "P5E_CPU1_PE0_RX_DN<12>")
	)
	(arc
		(start 99.517962 -215.436704)
		(mid 99.565641 -215.619604)
		(end 99.696524 -215.755982)
		(width 0.0889)
		(layer "In13.Cu")
		(net "P5E_CPU1_PE0_RX_DN<12>")
	)
	(arc
		(start 100.181664 -216.578434)
		(mid 100.384077 -216.784847)
		(end 100.458016 -217.064336)
		(width 0.0889)
		(layer "In13.Cu")
		(net "P5E_CPU1_PE0_RX_DN<12>")
	)
	(arc
		(start 100.458016 -220.334078)
		(mid 100.378875 -220.608701)
		(end 100.175568 -220.809566)
		(width 0.0889)
		(layer "In13.Cu")
		(net "P5E_CPU1_PE0_RX_DN<12>")
	)
	(arc
		(start 99.71151 -215.764618)
		(mid 99.914097 -215.970969)
		(end 99.988116 -216.25052)
		(width 0.0889)
		(layer "In13.Cu")
		(net "P5E_CPU1_PE0_RX_DN<12>")
	)
	(arc
		(start 100.175568 -218.202764)
		(mid 100.378391 -218.402995)
		(end 100.457762 -218.676728)
		(width 0.0889)
		(layer "In13.Cu")
		(net "P5E_CPU1_PE0_RX_DN<12>")
	)
	(arc
		(start 100.457762 -218.707716)
		(mid 100.378392 -218.98145)
		(end 100.175568 -219.18168)
		(width 0.0889)
		(layer "In13.Cu")
		(net "P5E_CPU1_PE0_RX_DN<12>")
	)
	(arc
		(start 99.988116 -221.144084)
		(mid 100.038185 -221.321309)
		(end 100.166678 -221.453202)
		(width 0.0889)
		(layer "In13.Cu")
		(net "P5E_CPU1_PE0_RX_DN<12>")
	)
	(arc
		(start 99.988116 -216.25052)
		(mid 100.035795 -216.43342)
		(end 100.166678 -216.569798)
		(width 0.0889)
		(layer "In13.Cu")
		(net "P5E_CPU1_PE0_RX_DN<12>")
	)
	(arc
		(start 100.166678 -219.18676)
		(mid 99.988202 -219.506038)
		(end 100.166678 -219.825316)
		(width 0.0889)
		(layer "In13.Cu")
		(net "P5E_CPU1_PE0_RX_DN<12>")
	)
	(arc
		(start 99.518216 -215.421972)
		(mid 99.518019 -215.429337)
		(end 99.517962 -215.436704)
		(width 0.0889)
		(layer "In13.Cu")
		(net "P5E_CPU1_PE0_RX_DN<12>")
	)
	(arc
		(start 100.181664 -219.833952)
		(mid 100.384077 -220.040365)
		(end 100.458016 -220.319854)
		(width 0.0889)
		(layer "In13.Cu")
		(net "P5E_CPU1_PE0_RX_DN<12>")
	)
	(arc
		(start 100.175568 -221.458282)
		(mid 100.334056 -221.507215)
		(end 100.498148 -221.48292)
		(width 0.0889)
		(layer "In13.Cu")
		(net "P5E_CPU1_PE0_RX_DN<12>")
	)
	(arc
		(start 100.166678 -220.814646)
		(mid 100.039424 -220.944612)
		(end 99.98837 -221.119192)
		(width 0.0889)
		(layer "In13.Cu")
		(net "P5E_CPU1_PE0_RX_DN<12>")
	)
	(segment
		(start 99.422712 -221.669864)
		(end 99.422712 -221.134178)
		(width 0.13208)
		(layer "F.Cu")
		(net "P5E_CPU1_PE0_RX_DN<11>")
	)
	(segment
		(start 99.422712 -221.134178)
		(end 99.422966 -221.133924)
		(width 0.13208)
		(layer "F.Cu")
		(net "P5E_CPU1_PE0_RX_DN<11>")
	)
	(segment
		(start 63.077344 -390.211056)
		(end 63.100204 -389.774938)
		(width 0.14732)
		(layer "In13.Cu")
		(net "P5E_CPU1_PE0_RX_DN<11>")
	)
	(segment
		(start 65.955164 -417.507166)
		(end 65.10274 -416.231324)
		(width 0.14732)
		(layer "In13.Cu")
		(net "P5E_CPU1_PE0_RX_DN<11>")
	)
	(segment
		(start 63.314072 -385.726432)
		(end 63.336932 -385.290314)
		(width 0.14732)
		(layer "In13.Cu")
		(net "P5E_CPU1_PE0_RX_DN<11>")
	)
	(segment
		(start 99.327462 -217.0557)
		(end 99.327462 -217.072972)
		(width 0.0889)
		(layer "In13.Cu")
		(net "P5E_CPU1_PE0_RX_DN<11>")
	)
	(segment
		(start 70.765162 -250.1011)
		(end 72.16902 -232.755948)
		(width 0.14732)
		(layer "In13.Cu")
		(net "P5E_CPU1_PE0_RX_DN<11>")
	)
	(segment
		(start 66.482976 -437.31942)
		(end 66.171064 -437.31942)
		(width 0.14732)
		(layer "In13.Cu")
		(net "P5E_CPU1_PE0_RX_DN<11>")
	)
	(segment
		(start 89.95664 -203.437236)
		(end 91.549474 -204.097128)
		(width 0.14732)
		(layer "In13.Cu")
		(net "P5E_CPU1_PE0_RX_DN<11>")
	)
	(segment
		(start 63.231268 -389.657082)
		(end 63.254128 -389.22071)
		(width 0.14732)
		(layer "In13.Cu")
		(net "P5E_CPU1_PE0_RX_DN<11>")
	)
	(segment
		(start 62.333378 -404.596092)
		(end 62.333378 -400.345148)
		(width 0.14732)
		(layer "In13.Cu")
		(net "P5E_CPU1_PE0_RX_DN<11>")
	)
	(segment
		(start 62.923166 -393.140438)
		(end 63.053976 -393.02309)
		(width 0.14732)
		(layer "In13.Cu")
		(net "P5E_CPU1_PE0_RX_DN<11>")
	)
	(segment
		(start 63.31331 -388.099554)
		(end 63.195708 -387.968744)
		(width 0.14732)
		(layer "In13.Cu")
		(net "P5E_CPU1_PE0_RX_DN<11>")
	)
	(segment
		(start 94.795594 -207.512158)
		(end 95.10649 -207.823054)
		(width 0.14732)
		(layer "In13.Cu")
		(net "P5E_CPU1_PE0_RX_DN<11>")
	)
	(segment
		(start 63.25489 -386.847588)
		(end 63.27775 -386.41147)
		(width 0.14732)
		(layer "In13.Cu")
		(net "P5E_CPU1_PE0_RX_DN<11>")
	)
	(segment
		(start 63.372492 -386.978398)
		(end 63.25489 -386.847588)
		(width 0.14732)
		(layer "In13.Cu")
		(net "P5E_CPU1_PE0_RX_DN<11>")
	)
	(segment
		(start 99.5553 -220.773752)
		(end 99.57943 -220.862906)
		(width 0.0889)
		(layer "In13.Cu")
		(net "P5E_CPU1_PE0_RX_DN<11>")
	)
	(segment
		(start 63.041022 -390.896094)
		(end 63.172086 -390.778492)
		(width 0.14732)
		(layer "In13.Cu")
		(net "P5E_CPU1_PE0_RX_DN<11>")
	)
	(segment
		(start 98.664268 -215.922606)
		(end 98.669602 -215.925654)
		(width 0.0889)
		(layer "In13.Cu")
		(net "P5E_CPU1_PE0_RX_DN<11>")
	)
	(segment
		(start 63.27775 -386.41147)
		(end 63.408814 -386.293614)
		(width 0.14732)
		(layer "In13.Cu")
		(net "P5E_CPU1_PE0_RX_DN<11>")
	)
	(segment
		(start 63.549784 -383.61493)
		(end 63.431928 -383.48412)
		(width 0.14732)
		(layer "In13.Cu")
		(net "P5E_CPU1_PE0_RX_DN<11>")
	)
	(segment
		(start 63.254128 -389.22071)
		(end 63.136526 -389.0899)
		(width 0.14732)
		(layer "In13.Cu")
		(net "P5E_CPU1_PE0_RX_DN<11>")
	)
	(segment
		(start 98.34626 -211.988908)
		(end 98.34626 -213.140036)
		(width 0.14732)
		(layer "In13.Cu")
		(net "P5E_CPU1_PE0_RX_DN<11>")
	)
	(segment
		(start 63.585852 -382.930146)
		(end 63.608712 -382.493774)
		(width 0.14732)
		(layer "In13.Cu")
		(net "P5E_CPU1_PE0_RX_DN<11>")
	)
	(segment
		(start 63.136526 -389.0899)
		(end 63.159386 -388.653782)
		(width 0.14732)
		(layer "In13.Cu")
		(net "P5E_CPU1_PE0_RX_DN<11>")
	)
	(segment
		(start 63.373 -384.605276)
		(end 63.39586 -384.169158)
		(width 0.14732)
		(layer "In13.Cu")
		(net "P5E_CPU1_PE0_RX_DN<11>")
	)
	(segment
		(start 63.431674 -385.857242)
		(end 63.314072 -385.726432)
		(width 0.14732)
		(layer "In13.Cu")
		(net "P5E_CPU1_PE0_RX_DN<11>")
	)
	(segment
		(start 97.572068 -210.119722)
		(end 98.34626 -211.988908)
		(width 0.14732)
		(layer "In13.Cu")
		(net "P5E_CPU1_PE0_RX_DN<11>")
	)
	(segment
		(start 98.857308 -214.461344)
		(end 98.857308 -214.622634)
		(width 0.0889)
		(layer "In13.Cu")
		(net "P5E_CPU1_PE0_RX_DN<11>")
	)
	(segment
		(start 66.650108 -436.889906)
		(end 66.650108 -437.152288)
		(width 0.14732)
		(layer "In13.Cu")
		(net "P5E_CPU1_PE0_RX_DN<11>")
	)
	(segment
		(start 63.70066 -352.504248)
		(end 64.653922 -343.292938)
		(width 0.14732)
		(layer "In13.Cu")
		(net "P5E_CPU1_PE0_RX_DN<11>")
	)
	(segment
		(start 63.112904 -391.899648)
		(end 63.136018 -391.463022)
		(width 0.14732)
		(layer "In13.Cu")
		(net "P5E_CPU1_PE0_RX_DN<11>")
	)
	(segment
		(start 98.669602 -215.925654)
		(end 98.670364 -215.926162)
		(width 0.0889)
		(layer "In13.Cu")
		(net "P5E_CPU1_PE0_RX_DN<11>")
	)
	(segment
		(start 98.387916 -213.929722)
		(end 98.387916 -213.930484)
		(width 0.0889)
		(layer "In13.Cu")
		(net "P5E_CPU1_PE0_RX_DN<11>")
	)
	(segment
		(start 63.608712 -382.493774)
		(end 63.490856 -382.362964)
		(width 0.14732)
		(layer "In13.Cu")
		(net "P5E_CPU1_PE0_RX_DN<11>")
	)
	(segment
		(start 63.218568 -387.532626)
		(end 63.349632 -387.41477)
		(width 0.14732)
		(layer "In13.Cu")
		(net "P5E_CPU1_PE0_RX_DN<11>")
	)
	(segment
		(start 60.616338 -410.76499)
		(end 60.616338 -406.313132)
		(width 0.14732)
		(layer "In13.Cu")
		(net "P5E_CPU1_PE0_RX_DN<11>")
	)
	(segment
		(start 79.21752 -212.230208)
		(end 86.69528 -204.119988)
		(width 0.14732)
		(layer "In13.Cu")
		(net "P5E_CPU1_PE0_RX_DN<11>")
	)
	(segment
		(start 62.982094 -392.019536)
		(end 62.98184 -392.01725)
		(width 0.14732)
		(layer "In13.Cu")
		(net "P5E_CPU1_PE0_RX_DN<11>")
	)
	(segment
		(start 63.1952 -390.341866)
		(end 63.077344 -390.211056)
		(width 0.14732)
		(layer "In13.Cu")
		(net "P5E_CPU1_PE0_RX_DN<11>")
	)
	(segment
		(start 94.795594 -207.343248)
		(end 94.795594 -207.512158)
		(width 0.14732)
		(layer "In13.Cu")
		(net "P5E_CPU1_PE0_RX_DN<11>")
	)
	(segment
		(start 63.39586 -384.169158)
		(end 63.526924 -384.051302)
		(width 0.14732)
		(layer "In13.Cu")
		(net "P5E_CPU1_PE0_RX_DN<11>")
	)
	(segment
		(start 63.29045 -388.535926)
		(end 63.31331 -388.099554)
		(width 0.14732)
		(layer "In13.Cu")
		(net "P5E_CPU1_PE0_RX_DN<11>")
	)
	(segment
		(start 63.490856 -384.736086)
		(end 63.373 -384.605276)
		(width 0.14732)
		(layer "In13.Cu")
		(net "P5E_CPU1_PE0_RX_DN<11>")
	)
	(segment
		(start 88.01608 -203.437236)
		(end 89.95664 -203.437236)
		(width 0.14732)
		(layer "In13.Cu")
		(net "P5E_CPU1_PE0_RX_DN<11>")
	)
	(segment
		(start 98.38817 -213.929468)
		(end 98.387916 -213.929722)
		(width 0.0889)
		(layer "In13.Cu")
		(net "P5E_CPU1_PE0_RX_DN<11>")
	)
	(segment
		(start 62.333378 -400.345148)
		(end 62.697106 -397.429482)
		(width 0.14732)
		(layer "In13.Cu")
		(net "P5E_CPU1_PE0_RX_DN<11>")
	)
	(segment
		(start 63.431928 -383.48412)
		(end 63.454788 -383.048002)
		(width 0.14732)
		(layer "In13.Cu")
		(net "P5E_CPU1_PE0_RX_DN<11>")
	)
	(segment
		(start 63.018162 -391.332212)
		(end 63.041022 -390.896094)
		(width 0.14732)
		(layer "In13.Cu")
		(net "P5E_CPU1_PE0_RX_DN<11>")
	)
	(segment
		(start 63.195708 -387.968744)
		(end 63.218568 -387.532626)
		(width 0.14732)
		(layer "In13.Cu")
		(net "P5E_CPU1_PE0_RX_DN<11>")
	)
	(segment
		(start 63.349632 -387.41477)
		(end 63.372492 -386.978398)
		(width 0.14732)
		(layer "In13.Cu")
		(net "P5E_CPU1_PE0_RX_DN<11>")
	)
	(segment
		(start 98.857816 -217.859864)
		(end 98.857816 -217.8939)
		(width 0.0889)
		(layer "In13.Cu")
		(net "P5E_CPU1_PE0_RX_DN<11>")
	)
	(segment
		(start 66.650108 -437.152288)
		(end 66.482976 -437.31942)
		(width 0.14732)
		(layer "In13.Cu")
		(net "P5E_CPU1_PE0_RX_DN<11>")
	)
	(segment
		(start 99.57943 -220.862906)
		(end 99.422966 -221.133924)
		(width 0.0889)
		(layer "In13.Cu")
		(net "P5E_CPU1_PE0_RX_DN<11>")
	)
	(segment
		(start 62.959234 -392.455654)
		(end 62.982094 -392.019536)
		(width 0.14732)
		(layer "In13.Cu")
		(net "P5E_CPU1_PE0_RX_DN<11>")
	)
	(segment
		(start 64.653922 -329.941682)
		(end 68.3514 -321.01536)
		(width 0.14732)
		(layer "In13.Cu")
		(net "P5E_CPU1_PE0_RX_DN<11>")
	)
	(segment
		(start 98.34626 -213.162134)
		(end 98.38817 -213.204044)
		(width 0.0889)
		(layer "In13.Cu")
		(net "P5E_CPU1_PE0_RX_DN<11>")
	)
	(segment
		(start 98.857816 -219.490544)
		(end 98.857816 -219.515944)
		(width 0.0889)
		(layer "In13.Cu")
		(net "P5E_CPU1_PE0_RX_DN<11>")
	)
	(segment
		(start 70.585838 -317.824866)
		(end 74.224896 -309.060342)
		(width 0.14732)
		(layer "In13.Cu")
		(net "P5E_CPU1_PE0_RX_DN<11>")
	)
	(segment
		(start 63.100204 -389.774938)
		(end 63.231268 -389.657082)
		(width 0.14732)
		(layer "In13.Cu")
		(net "P5E_CPU1_PE0_RX_DN<11>")
	)
	(segment
		(start 75.66914 -216.802208)
		(end 79.21752 -212.230208)
		(width 0.14732)
		(layer "In13.Cu")
		(net "P5E_CPU1_PE0_RX_DN<11>")
	)
	(segment
		(start 74.19594 -219.641928)
		(end 75.66914 -216.802208)
		(width 0.14732)
		(layer "In13.Cu")
		(net "P5E_CPU1_PE0_RX_DN<11>")
	)
	(segment
		(start 63.408814 -386.293614)
		(end 63.431674 -385.857242)
		(width 0.14732)
		(layer "In13.Cu")
		(net "P5E_CPU1_PE0_RX_DN<11>")
	)
	(segment
		(start 95.10649 -207.823054)
		(end 95.2754 -207.823054)
		(width 0.14732)
		(layer "In13.Cu")
		(net "P5E_CPU1_PE0_RX_DN<11>")
	)
	(segment
		(start 63.053976 -393.02309)
		(end 63.07709 -392.586464)
		(width 0.14732)
		(layer "In13.Cu")
		(net "P5E_CPU1_PE0_RX_DN<11>")
	)
	(segment
		(start 64.653922 -343.292938)
		(end 64.653922 -329.941682)
		(width 0.14732)
		(layer "In13.Cu")
		(net "P5E_CPU1_PE0_RX_DN<11>")
	)
	(segment
		(start 98.387662 -215.414606)
		(end 98.387662 -215.436704)
		(width 0.0889)
		(layer "In13.Cu")
		(net "P5E_CPU1_PE0_RX_DN<11>")
	)
	(segment
		(start 99.14001 -218.367864)
		(end 99.141026 -218.368372)
		(width 0.0889)
		(layer "In13.Cu")
		(net "P5E_CPU1_PE0_RX_DN<11>")
	)
	(segment
		(start 99.327462 -220.311218)
		(end 99.327462 -220.334078)
		(width 0.0889)
		(layer "In13.Cu")
		(net "P5E_CPU1_PE0_RX_DN<11>")
	)
	(segment
		(start 98.38817 -213.204044)
		(end 98.38817 -213.929468)
		(width 0.0889)
		(layer "In13.Cu")
		(net "P5E_CPU1_PE0_RX_DN<11>")
	)
	(segment
		(start 98.34626 -213.140036)
		(end 98.34626 -213.162134)
		(width 0.0889)
		(layer "In13.Cu")
		(net "P5E_CPU1_PE0_RX_DN<11>")
	)
	(segment
		(start 65.955164 -437.10352)
		(end 65.955164 -417.507166)
		(width 0.14732)
		(layer "In13.Cu")
		(net "P5E_CPU1_PE0_RX_DN<11>")
	)
	(segment
		(start 63.336932 -385.290314)
		(end 63.467996 -385.172458)
		(width 0.14732)
		(layer "In13.Cu")
		(net "P5E_CPU1_PE0_RX_DN<11>")
	)
	(segment
		(start 62.98184 -392.01725)
		(end 63.112904 -391.899648)
		(width 0.14732)
		(layer "In13.Cu")
		(net "P5E_CPU1_PE0_RX_DN<11>")
	)
	(segment
		(start 98.670364 -215.926162)
		(end 98.671888 -215.926924)
		(width 0.0889)
		(layer "In13.Cu")
		(net "P5E_CPU1_PE0_RX_DN<11>")
	)
	(segment
		(start 63.454788 -383.048002)
		(end 63.585852 -382.930146)
		(width 0.14732)
		(layer "In13.Cu")
		(net "P5E_CPU1_PE0_RX_DN<11>")
	)
	(segment
		(start 72.16902 -232.755948)
		(end 74.19594 -219.641928)
		(width 0.14732)
		(layer "In13.Cu")
		(net "P5E_CPU1_PE0_RX_DN<11>")
	)
	(segment
		(start 98.857816 -216.25052)
		(end 98.857816 -216.260426)
		(width 0.0889)
		(layer "In13.Cu")
		(net "P5E_CPU1_PE0_RX_DN<11>")
	)
	(segment
		(start 91.549474 -204.097128)
		(end 94.795594 -207.343248)
		(width 0.14732)
		(layer "In13.Cu")
		(net "P5E_CPU1_PE0_RX_DN<11>")
	)
	(segment
		(start 74.224896 -309.060342)
		(end 70.65645 -253.33071)
		(width 0.14732)
		(layer "In13.Cu")
		(net "P5E_CPU1_PE0_RX_DN<11>")
	)
	(segment
		(start 63.526924 -384.051302)
		(end 63.549784 -383.61493)
		(width 0.14732)
		(layer "In13.Cu")
		(net "P5E_CPU1_PE0_RX_DN<11>")
	)
	(segment
		(start 66.171064 -437.31942)
		(end 65.955164 -437.10352)
		(width 0.14732)
		(layer "In13.Cu")
		(net "P5E_CPU1_PE0_RX_DN<11>")
	)
	(segment
		(start 63.136018 -391.463022)
		(end 63.018162 -391.332212)
		(width 0.14732)
		(layer "In13.Cu")
		(net "P5E_CPU1_PE0_RX_DN<11>")
	)
	(segment
		(start 68.3514 -321.01536)
		(end 70.585838 -317.824866)
		(width 0.14732)
		(layer "In13.Cu")
		(net "P5E_CPU1_PE0_RX_DN<11>")
	)
	(segment
		(start 99.141026 -218.368372)
		(end 99.1489 -218.372944)
		(width 0.0889)
		(layer "In13.Cu")
		(net "P5E_CPU1_PE0_RX_DN<11>")
	)
	(segment
		(start 63.159386 -388.653782)
		(end 63.29045 -388.535926)
		(width 0.14732)
		(layer "In13.Cu")
		(net "P5E_CPU1_PE0_RX_DN<11>")
	)
	(segment
		(start 86.69528 -204.119988)
		(end 88.01608 -203.437236)
		(width 0.14732)
		(layer "In13.Cu")
		(net "P5E_CPU1_PE0_RX_DN<11>")
	)
	(segment
		(start 65.10274 -416.231324)
		(end 60.616338 -410.76499)
		(width 0.14732)
		(layer "In13.Cu")
		(net "P5E_CPU1_PE0_RX_DN<11>")
	)
	(segment
		(start 63.467996 -385.172458)
		(end 63.490856 -384.736086)
		(width 0.14732)
		(layer "In13.Cu")
		(net "P5E_CPU1_PE0_RX_DN<11>")
	)
	(segment
		(start 63.490856 -382.362964)
		(end 63.552324 -381.191262)
		(width 0.14732)
		(layer "In13.Cu")
		(net "P5E_CPU1_PE0_RX_DN<11>")
	)
	(segment
		(start 63.07709 -392.586464)
		(end 62.959234 -392.455654)
		(width 0.14732)
		(layer "In13.Cu")
		(net "P5E_CPU1_PE0_RX_DN<11>")
	)
	(segment
		(start 60.616338 -406.313132)
		(end 62.333378 -404.596092)
		(width 0.14732)
		(layer "In13.Cu")
		(net "P5E_CPU1_PE0_RX_DN<11>")
	)
	(segment
		(start 62.697106 -397.429482)
		(end 62.923166 -393.140438)
		(width 0.14732)
		(layer "In13.Cu")
		(net "P5E_CPU1_PE0_RX_DN<11>")
	)
	(segment
		(start 99.1489 -219.0115)
		(end 99.14001 -219.01658)
		(width 0.0889)
		(layer "In13.Cu")
		(net "P5E_CPU1_PE0_RX_DN<11>")
	)
	(segment
		(start 70.65645 -253.33071)
		(end 70.765162 -250.1011)
		(width 0.14732)
		(layer "In13.Cu")
		(net "P5E_CPU1_PE0_RX_DN<11>")
	)
	(segment
		(start 63.172086 -390.778492)
		(end 63.1952 -390.341866)
		(width 0.14732)
		(layer "In13.Cu")
		(net "P5E_CPU1_PE0_RX_DN<11>")
	)
	(segment
		(start 98.678746 -214.941912)
		(end 98.669856 -214.946992)
		(width 0.0889)
		(layer "In13.Cu")
		(net "P5E_CPU1_PE0_RX_DN<11>")
	)
	(segment
		(start 95.2754 -207.823054)
		(end 97.572068 -210.119722)
		(width 0.14732)
		(layer "In13.Cu")
		(net "P5E_CPU1_PE0_RX_DN<11>")
	)
	(segment
		(start 98.671888 -215.926924)
		(end 98.679254 -215.931242)
		(width 0.0889)
		(layer "In13.Cu")
		(net "P5E_CPU1_PE0_RX_DN<11>")
	)
	(segment
		(start 63.552324 -381.191262)
		(end 63.70066 -352.504248)
		(width 0.14732)
		(layer "In13.Cu")
		(net "P5E_CPU1_PE0_RX_DN<11>")
	)
	(arc
		(start 99.140264 -216.739978)
		(mid 99.275197 -216.873332)
		(end 99.327462 -217.0557)
		(width 0.0889)
		(layer "In13.Cu")
		(net "P5E_CPU1_PE0_RX_DN<11>")
	)
	(arc
		(start 98.857816 -219.515944)
		(mid 98.935927 -219.792893)
		(end 99.140264 -219.995496)
		(width 0.0889)
		(layer "In13.Cu")
		(net "P5E_CPU1_PE0_RX_DN<11>")
	)
	(arc
		(start 99.1489 -218.372944)
		(mid 99.327376 -218.692222)
		(end 99.1489 -219.0115)
		(width 0.0889)
		(layer "In13.Cu")
		(net "P5E_CPU1_PE0_RX_DN<11>")
	)
	(arc
		(start 98.857308 -214.622634)
		(mid 98.857256 -214.630001)
		(end 98.857054 -214.637366)
		(width 0.0889)
		(layer "In13.Cu")
		(net "P5E_CPU1_PE0_RX_DN<11>")
	)
	(arc
		(start 99.327462 -217.072972)
		(mid 99.275192 -217.255337)
		(end 99.140264 -217.388694)
		(width 0.0889)
		(layer "In13.Cu")
		(net "P5E_CPU1_PE0_RX_DN<11>")
	)
	(arc
		(start 98.387916 -213.930484)
		(mid 98.395201 -213.950046)
		(end 98.403156 -213.969346)
		(width 0.0889)
		(layer "In13.Cu")
		(net "P5E_CPU1_PE0_RX_DN<11>")
	)
	(arc
		(start 98.857816 -217.8939)
		(mid 98.937186 -218.167634)
		(end 99.14001 -218.367864)
		(width 0.0889)
		(layer "In13.Cu")
		(net "P5E_CPU1_PE0_RX_DN<11>")
	)
	(arc
		(start 98.679254 -215.931242)
		(mid 98.810168 -216.067602)
		(end 98.857816 -216.25052)
		(width 0.0889)
		(layer "In13.Cu")
		(net "P5E_CPU1_PE0_RX_DN<11>")
	)
	(arc
		(start 99.538282 -220.760798)
		(mid 99.54673 -220.767355)
		(end 99.5553 -220.773752)
		(width 0.0889)
		(layer "In13.Cu")
		(net "P5E_CPU1_PE0_RX_DN<11>")
	)
	(arc
		(start 98.673158 -214.261954)
		(mid 98.782305 -214.345882)
		(end 98.857308 -214.461344)
		(width 0.0889)
		(layer "In13.Cu")
		(net "P5E_CPU1_PE0_RX_DN<11>")
	)
	(arc
		(start 99.14001 -219.01658)
		(mid 98.937187 -219.216811)
		(end 98.857816 -219.490544)
		(width 0.0889)
		(layer "In13.Cu")
		(net "P5E_CPU1_PE0_RX_DN<11>")
	)
	(arc
		(start 98.387662 -215.436704)
		(mid 98.461653 -215.71627)
		(end 98.664268 -215.922606)
		(width 0.0889)
		(layer "In13.Cu")
		(net "P5E_CPU1_PE0_RX_DN<11>")
	)
	(arc
		(start 98.857816 -216.260426)
		(mid 98.935927 -216.537375)
		(end 99.140264 -216.739978)
		(width 0.0889)
		(layer "In13.Cu")
		(net "P5E_CPU1_PE0_RX_DN<11>")
	)
	(arc
		(start 98.403156 -213.969346)
		(mid 98.51315 -214.138715)
		(end 98.673158 -214.261954)
		(width 0.0889)
		(layer "In13.Cu")
		(net "P5E_CPU1_PE0_RX_DN<11>")
	)
	(arc
		(start 98.857054 -214.637366)
		(mid 98.806 -214.811946)
		(end 98.678746 -214.941912)
		(width 0.0889)
		(layer "In13.Cu")
		(net "P5E_CPU1_PE0_RX_DN<11>")
	)
	(arc
		(start 99.140264 -217.388694)
		(mid 98.937978 -217.587675)
		(end 98.857816 -217.859864)
		(width 0.0889)
		(layer "In13.Cu")
		(net "P5E_CPU1_PE0_RX_DN<11>")
	)
	(arc
		(start 99.140264 -219.995496)
		(mid 99.275197 -220.12885)
		(end 99.327462 -220.311218)
		(width 0.0889)
		(layer "In13.Cu")
		(net "P5E_CPU1_PE0_RX_DN<11>")
	)
	(arc
		(start 99.327462 -220.334078)
		(mid 99.385756 -220.570721)
		(end 99.538282 -220.760798)
		(width 0.0889)
		(layer "In13.Cu")
		(net "P5E_CPU1_PE0_RX_DN<11>")
	)
	(arc
		(start 98.669856 -214.946992)
		(mid 98.468574 -215.144479)
		(end 98.387662 -215.414606)
		(width 0.0889)
		(layer "In13.Cu")
		(net "P5E_CPU1_PE0_RX_DN<11>")
	)
	(segment
		(start 98.482912 -221.669864)
		(end 98.482912 -221.134178)
		(width 0.13208)
		(layer "F.Cu")
		(net "P5E_CPU1_PE0_RX_DN<10>")
	)
	(segment
		(start 98.482912 -221.134178)
		(end 98.483166 -221.133924)
		(width 0.13208)
		(layer "F.Cu")
		(net "P5E_CPU1_PE0_RX_DN<10>")
	)
	(segment
		(start 65.122298 -399.975578)
		(end 65.308988 -397.541496)
		(width 0.14732)
		(layer "In13.Cu")
		(net "P5E_CPU1_PE0_RX_DN<10>")
	)
	(segment
		(start 67.68084 -438.30875)
		(end 67.68084 -416.88385)
		(width 0.14732)
		(layer "In13.Cu")
		(net "P5E_CPU1_PE0_RX_DN<10>")
	)
	(segment
		(start 97.825814 -215.112346)
		(end 97.825052 -215.112854)
		(width 0.0889)
		(layer "In13.Cu")
		(net "P5E_CPU1_PE0_RX_DN<10>")
	)
	(segment
		(start 76.26731 -217.102944)
		(end 79.737966 -212.641942)
		(width 0.14732)
		(layer "In13.Cu")
		(net "P5E_CPU1_PE0_RX_DN<10>")
	)
	(segment
		(start 97.680526 -213.08314)
		(end 97.680272 -213.083394)
		(width 0.14732)
		(layer "In13.Cu")
		(net "P5E_CPU1_PE0_RX_DN<10>")
	)
	(segment
		(start 71.341996 -252.61824)
		(end 71.341996 -252.60173)
		(width 0.14732)
		(layer "In13.Cu")
		(net "P5E_CPU1_PE0_RX_DN<10>")
	)
	(segment
		(start 97.680272 -213.15807)
		(end 97.638362 -213.19998)
		(width 0.0889)
		(layer "In13.Cu")
		(net "P5E_CPU1_PE0_RX_DN<10>")
	)
	(segment
		(start 97.83318 -215.10752)
		(end 97.831148 -215.10879)
		(width 0.0889)
		(layer "In13.Cu")
		(net "P5E_CPU1_PE0_RX_DN<10>")
	)
	(segment
		(start 67.965828 -438.593738)
		(end 67.68084 -438.30875)
		(width 0.14732)
		(layer "In13.Cu")
		(net "P5E_CPU1_PE0_RX_DN<10>")
	)
	(segment
		(start 63.405258 -406.19934)
		(end 65.122298 -404.4823)
		(width 0.14732)
		(layer "In13.Cu")
		(net "P5E_CPU1_PE0_RX_DN<10>")
	)
	(segment
		(start 97.825052 -215.112854)
		(end 97.821242 -215.114886)
		(width 0.0889)
		(layer "In13.Cu")
		(net "P5E_CPU1_PE0_RX_DN<10>")
	)
	(segment
		(start 79.737966 -212.641942)
		(end 82.146648 -210.667092)
		(width 0.14732)
		(layer "In13.Cu")
		(net "P5E_CPU1_PE0_RX_DN<10>")
	)
	(segment
		(start 65.122298 -404.4823)
		(end 65.122298 -399.975578)
		(width 0.14732)
		(layer "In13.Cu")
		(net "P5E_CPU1_PE0_RX_DN<10>")
	)
	(segment
		(start 68.650104 -439.0898)
		(end 68.650104 -438.741312)
		(width 0.14732)
		(layer "In13.Cu")
		(net "P5E_CPU1_PE0_RX_DN<10>")
	)
	(segment
		(start 98.295968 -219.830396)
		(end 98.302064 -219.833952)
		(width 0.0889)
		(layer "In13.Cu")
		(net "P5E_CPU1_PE0_RX_DN<10>")
	)
	(segment
		(start 97.680272 -213.083394)
		(end 97.680272 -213.135972)
		(width 0.14732)
		(layer "In13.Cu")
		(net "P5E_CPU1_PE0_RX_DN<10>")
	)
	(segment
		(start 74.933302 -309.368444)
		(end 71.341996 -252.61824)
		(width 0.14732)
		(layer "In13.Cu")
		(net "P5E_CPU1_PE0_RX_DN<10>")
	)
	(segment
		(start 96.97593 -210.45424)
		(end 97.680526 -212.155532)
		(width 0.14732)
		(layer "In13.Cu")
		(net "P5E_CPU1_PE0_RX_DN<10>")
	)
	(segment
		(start 88.76284 -208.674716)
		(end 94.10446 -208.674716)
		(width 0.14732)
		(layer "In13.Cu")
		(net "P5E_CPU1_PE0_RX_DN<10>")
	)
	(segment
		(start 98.287078 -221.453202)
		(end 98.295968 -221.458282)
		(width 0.0889)
		(layer "In13.Cu")
		(net "P5E_CPU1_PE0_RX_DN<10>")
	)
	(segment
		(start 98.295968 -220.809566)
		(end 98.294952 -220.810074)
		(width 0.0889)
		(layer "In13.Cu")
		(net "P5E_CPU1_PE0_RX_DN<10>")
	)
	(segment
		(start 71.425054 -250.12904)
		(end 72.843898 -232.831386)
		(width 0.14732)
		(layer "In13.Cu")
		(net "P5E_CPU1_PE0_RX_DN<10>")
	)
	(segment
		(start 98.287078 -216.569798)
		(end 98.295968 -216.574878)
		(width 0.0889)
		(layer "In13.Cu")
		(net "P5E_CPU1_PE0_RX_DN<10>")
	)
	(segment
		(start 98.287078 -218.197684)
		(end 98.295968 -218.202764)
		(width 0.0889)
		(layer "In13.Cu")
		(net "P5E_CPU1_PE0_RX_DN<10>")
	)
	(segment
		(start 68.50253 -438.593738)
		(end 67.965828 -438.593738)
		(width 0.14732)
		(layer "In13.Cu")
		(net "P5E_CPU1_PE0_RX_DN<10>")
	)
	(segment
		(start 98.618548 -221.48292)
		(end 98.63963 -221.404942)
		(width 0.0889)
		(layer "In13.Cu")
		(net "P5E_CPU1_PE0_RX_DN<10>")
	)
	(segment
		(start 98.107754 -214.425784)
		(end 98.107754 -214.622634)
		(width 0.0889)
		(layer "In13.Cu")
		(net "P5E_CPU1_PE0_RX_DN<10>")
	)
	(segment
		(start 82.146648 -210.667092)
		(end 88.76284 -208.674716)
		(width 0.14732)
		(layer "In13.Cu")
		(net "P5E_CPU1_PE0_RX_DN<10>")
	)
	(segment
		(start 97.680526 -212.155532)
		(end 97.680526 -213.08314)
		(width 0.14732)
		(layer "In13.Cu")
		(net "P5E_CPU1_PE0_RX_DN<10>")
	)
	(segment
		(start 65.317116 -343.397586)
		(end 65.317116 -330.059792)
		(width 0.14732)
		(layer "In13.Cu")
		(net "P5E_CPU1_PE0_RX_DN<10>")
	)
	(segment
		(start 68.650104 -438.741312)
		(end 68.50253 -438.593738)
		(width 0.14732)
		(layer "In13.Cu")
		(net "P5E_CPU1_PE0_RX_DN<10>")
	)
	(segment
		(start 98.295968 -216.574878)
		(end 98.302064 -216.578434)
		(width 0.0889)
		(layer "In13.Cu")
		(net "P5E_CPU1_PE0_RX_DN<10>")
	)
	(segment
		(start 98.578162 -218.676728)
		(end 98.578162 -218.707716)
		(width 0.0889)
		(layer "In13.Cu")
		(net "P5E_CPU1_PE0_RX_DN<10>")
	)
	(segment
		(start 63.405258 -410.757624)
		(end 63.405258 -406.19934)
		(width 0.14732)
		(layer "In13.Cu")
		(net "P5E_CPU1_PE0_RX_DN<10>")
	)
	(segment
		(start 74.862436 -219.830142)
		(end 76.26731 -217.102944)
		(width 0.14732)
		(layer "In13.Cu")
		(net "P5E_CPU1_PE0_RX_DN<10>")
	)
	(segment
		(start 65.317116 -330.059792)
		(end 68.754244 -321.762628)
		(width 0.14732)
		(layer "In13.Cu")
		(net "P5E_CPU1_PE0_RX_DN<10>")
	)
	(segment
		(start 72.843898 -232.831386)
		(end 74.862436 -219.830142)
		(width 0.14732)
		(layer "In13.Cu")
		(net "P5E_CPU1_PE0_RX_DN<10>")
	)
	(segment
		(start 71.264272 -318.17818)
		(end 74.933302 -309.368444)
		(width 0.14732)
		(layer "In13.Cu")
		(net "P5E_CPU1_PE0_RX_DN<10>")
	)
	(segment
		(start 98.294952 -220.810074)
		(end 98.287078 -220.814646)
		(width 0.0889)
		(layer "In13.Cu")
		(net "P5E_CPU1_PE0_RX_DN<10>")
	)
	(segment
		(start 97.834704 -215.106504)
		(end 97.83318 -215.10752)
		(width 0.0889)
		(layer "In13.Cu")
		(net "P5E_CPU1_PE0_RX_DN<10>")
	)
	(segment
		(start 68.754244 -321.762628)
		(end 71.264272 -318.17818)
		(width 0.14732)
		(layer "In13.Cu")
		(net "P5E_CPU1_PE0_RX_DN<10>")
	)
	(segment
		(start 97.816924 -215.755982)
		(end 97.83191 -215.764618)
		(width 0.0889)
		(layer "In13.Cu")
		(net "P5E_CPU1_PE0_RX_DN<10>")
	)
	(segment
		(start 67.68084 -416.88385)
		(end 63.405258 -410.757624)
		(width 0.14732)
		(layer "In13.Cu")
		(net "P5E_CPU1_PE0_RX_DN<10>")
	)
	(segment
		(start 97.831148 -215.10879)
		(end 97.826322 -215.111584)
		(width 0.0889)
		(layer "In13.Cu")
		(net "P5E_CPU1_PE0_RX_DN<10>")
	)
	(segment
		(start 94.10446 -208.674716)
		(end 95.968566 -209.446876)
		(width 0.14732)
		(layer "In13.Cu")
		(net "P5E_CPU1_PE0_RX_DN<10>")
	)
	(segment
		(start 65.308988 -397.541496)
		(end 64.669924 -350.255332)
		(width 0.14732)
		(layer "In13.Cu")
		(net "P5E_CPU1_PE0_RX_DN<10>")
	)
	(segment
		(start 97.821242 -215.114886)
		(end 97.816924 -215.117426)
		(width 0.0889)
		(layer "In13.Cu")
		(net "P5E_CPU1_PE0_RX_DN<10>")
	)
	(segment
		(start 98.287078 -219.825316)
		(end 98.295968 -219.830396)
		(width 0.0889)
		(layer "In13.Cu")
		(net "P5E_CPU1_PE0_RX_DN<10>")
	)
	(segment
		(start 97.638362 -213.19998)
		(end 97.638362 -213.894416)
		(width 0.0889)
		(layer "In13.Cu")
		(net "P5E_CPU1_PE0_RX_DN<10>")
	)
	(segment
		(start 98.295968 -217.554048)
		(end 98.287078 -217.559128)
		(width 0.0889)
		(layer "In13.Cu")
		(net "P5E_CPU1_PE0_RX_DN<10>")
	)
	(segment
		(start 98.578416 -220.319854)
		(end 98.578416 -220.334078)
		(width 0.0889)
		(layer "In13.Cu")
		(net "P5E_CPU1_PE0_RX_DN<10>")
	)
	(segment
		(start 71.341996 -252.60173)
		(end 71.425054 -250.12904)
		(width 0.14732)
		(layer "In13.Cu")
		(net "P5E_CPU1_PE0_RX_DN<10>")
	)
	(segment
		(start 97.680272 -213.135972)
		(end 97.680272 -213.15807)
		(width 0.0889)
		(layer "In13.Cu")
		(net "P5E_CPU1_PE0_RX_DN<10>")
	)
	(segment
		(start 97.826322 -215.111584)
		(end 97.825814 -215.112346)
		(width 0.0889)
		(layer "In13.Cu")
		(net "P5E_CPU1_PE0_RX_DN<10>")
	)
	(segment
		(start 98.63963 -221.404942)
		(end 98.483166 -221.133924)
		(width 0.0889)
		(layer "In13.Cu")
		(net "P5E_CPU1_PE0_RX_DN<10>")
	)
	(segment
		(start 95.968566 -209.446876)
		(end 96.97593 -210.45424)
		(width 0.14732)
		(layer "In13.Cu")
		(net "P5E_CPU1_PE0_RX_DN<10>")
	)
	(segment
		(start 64.669924 -350.255332)
		(end 65.317116 -343.397586)
		(width 0.14732)
		(layer "In13.Cu")
		(net "P5E_CPU1_PE0_RX_DN<10>")
	)
	(segment
		(start 98.295968 -219.18168)
		(end 98.287078 -219.18676)
		(width 0.0889)
		(layer "In13.Cu")
		(net "P5E_CPU1_PE0_RX_DN<10>")
	)
	(arc
		(start 98.302064 -216.578434)
		(mid 98.578378 -217.067928)
		(end 98.295968 -217.554048)
		(width 0.0889)
		(layer "In13.Cu")
		(net "P5E_CPU1_PE0_RX_DN<10>")
	)
	(arc
		(start 97.822512 -214.093552)
		(mid 97.996603 -214.232646)
		(end 98.107754 -214.425784)
		(width 0.0889)
		(layer "In13.Cu")
		(net "P5E_CPU1_PE0_RX_DN<10>")
	)
	(arc
		(start 97.816924 -215.117426)
		(mid 97.638327 -215.436704)
		(end 97.816924 -215.755982)
		(width 0.0889)
		(layer "In13.Cu")
		(net "P5E_CPU1_PE0_RX_DN<10>")
	)
	(arc
		(start 98.287078 -220.814646)
		(mid 98.159824 -220.944612)
		(end 98.10877 -221.119192)
		(width 0.0889)
		(layer "In13.Cu")
		(net "P5E_CPU1_PE0_RX_DN<10>")
	)
	(arc
		(start 98.108516 -217.888566)
		(mid 98.158585 -218.065791)
		(end 98.287078 -218.197684)
		(width 0.0889)
		(layer "In13.Cu")
		(net "P5E_CPU1_PE0_RX_DN<10>")
	)
	(arc
		(start 98.287078 -219.18676)
		(mid 98.108602 -219.506038)
		(end 98.287078 -219.825316)
		(width 0.0889)
		(layer "In13.Cu")
		(net "P5E_CPU1_PE0_RX_DN<10>")
	)
	(arc
		(start 98.302064 -219.833952)
		(mid 98.504477 -220.040365)
		(end 98.578416 -220.319854)
		(width 0.0889)
		(layer "In13.Cu")
		(net "P5E_CPU1_PE0_RX_DN<10>")
	)
	(arc
		(start 98.10877 -221.119192)
		(mid 98.108573 -221.126557)
		(end 98.108516 -221.133924)
		(width 0.0889)
		(layer "In13.Cu")
		(net "P5E_CPU1_PE0_RX_DN<10>")
	)
	(arc
		(start 98.10877 -217.863674)
		(mid 98.108437 -217.876118)
		(end 98.108516 -217.888566)
		(width 0.0889)
		(layer "In13.Cu")
		(net "P5E_CPU1_PE0_RX_DN<10>")
	)
	(arc
		(start 98.578416 -220.334078)
		(mid 98.499275 -220.608701)
		(end 98.295968 -220.809566)
		(width 0.0889)
		(layer "In13.Cu")
		(net "P5E_CPU1_PE0_RX_DN<10>")
	)
	(arc
		(start 98.287078 -217.559128)
		(mid 98.159824 -217.689094)
		(end 98.10877 -217.863674)
		(width 0.0889)
		(layer "In13.Cu")
		(net "P5E_CPU1_PE0_RX_DN<10>")
	)
	(arc
		(start 98.108516 -216.25052)
		(mid 98.156195 -216.43342)
		(end 98.287078 -216.569798)
		(width 0.0889)
		(layer "In13.Cu")
		(net "P5E_CPU1_PE0_RX_DN<10>")
	)
	(arc
		(start 98.295968 -218.202764)
		(mid 98.498791 -218.402995)
		(end 98.578162 -218.676728)
		(width 0.0889)
		(layer "In13.Cu")
		(net "P5E_CPU1_PE0_RX_DN<10>")
	)
	(arc
		(start 98.578162 -218.707716)
		(mid 98.498792 -218.98145)
		(end 98.295968 -219.18168)
		(width 0.0889)
		(layer "In13.Cu")
		(net "P5E_CPU1_PE0_RX_DN<10>")
	)
	(arc
		(start 98.295968 -221.458282)
		(mid 98.454456 -221.507215)
		(end 98.618548 -221.48292)
		(width 0.0889)
		(layer "In13.Cu")
		(net "P5E_CPU1_PE0_RX_DN<10>")
	)
	(arc
		(start 98.107754 -214.622634)
		(mid 98.034773 -214.900419)
		(end 97.834704 -215.106504)
		(width 0.0889)
		(layer "In13.Cu")
		(net "P5E_CPU1_PE0_RX_DN<10>")
	)
	(arc
		(start 97.83191 -215.764618)
		(mid 98.034497 -215.970969)
		(end 98.108516 -216.25052)
		(width 0.0889)
		(layer "In13.Cu")
		(net "P5E_CPU1_PE0_RX_DN<10>")
	)
	(arc
		(start 97.638362 -213.894416)
		(mid 97.713436 -214.009701)
		(end 97.822512 -214.093552)
		(width 0.0889)
		(layer "In13.Cu")
		(net "P5E_CPU1_PE0_RX_DN<10>")
	)
	(arc
		(start 98.108516 -221.133924)
		(mid 98.156195 -221.316824)
		(end 98.287078 -221.453202)
		(width 0.0889)
		(layer "In13.Cu")
		(net "P5E_CPU1_PE0_RX_DN<10>")
	)
	(segment
		(start 89.084912 -221.669864)
		(end 89.085166 -221.66961)
		(width 0.13208)
		(layer "F.Cu")
		(net "P5E_CPU1_PE0_RX_DN<0>")
	)
	(segment
		(start 89.085166 -221.66961)
		(end 89.085166 -221.133924)
		(width 0.13208)
		(layer "F.Cu")
		(net "P5E_CPU1_PE0_RX_DN<0>")
	)
	(segment
		(start 85.973666 -227.16109)
		(end 85.983064 -227.155502)
		(width 0.0889)
		(layer "In13.Cu")
		(net "P5E_CPU1_PE0_RX_DN<0>")
	)
	(segment
		(start 88.989662 -221.956376)
		(end 88.989662 -221.94774)
		(width 0.0889)
		(layer "In13.Cu")
		(net "P5E_CPU1_PE0_RX_DN<0>")
	)
	(segment
		(start 85.230462 -255.344676)
		(end 85.05952 -254.374904)
		(width 0.14732)
		(layer "In13.Cu")
		(net "P5E_CPU1_PE0_RX_DN<0>")
	)
	(segment
		(start 88.332564 -223.085914)
		(end 88.341454 -223.080834)
		(width 0.0889)
		(layer "In13.Cu")
		(net "P5E_CPU1_PE0_RX_DN<0>")
	)
	(segment
		(start 84.248244 -256.638044)
		(end 85.010498 -255.875536)
		(width 0.14732)
		(layer "In13.Cu")
		(net "P5E_CPU1_PE0_RX_DN<0>")
	)
	(segment
		(start 88.520016 -222.761556)
		(end 88.520016 -222.75165)
		(width 0.0889)
		(layer "In13.Cu")
		(net "P5E_CPU1_PE0_RX_DN<0>")
	)
	(segment
		(start 85.65896 -228.648006)
		(end 85.65896 -228.289866)
		(width 0.14732)
		(layer "In13.Cu")
		(net "P5E_CPU1_PE0_RX_DN<0>")
	)
	(segment
		(start 85.75675 -251.262388)
		(end 85.832188 -250.834652)
		(width 0.14732)
		(layer "In13.Cu")
		(net "P5E_CPU1_PE0_RX_DN<0>")
	)
	(segment
		(start 85.05952 -254.374904)
		(end 85.05952 -252.75667)
		(width 0.14732)
		(layer "In13.Cu")
		(net "P5E_CPU1_PE0_RX_DN<0>")
	)
	(segment
		(start 94.037658 -406.19934)
		(end 95.754698 -404.4823)
		(width 0.14732)
		(layer "In13.Cu")
		(net "P5E_CPU1_PE0_RX_DN<0>")
	)
	(segment
		(start 85.05952 -252.75667)
		(end 85.177376 -252.089666)
		(width 0.14732)
		(layer "In13.Cu")
		(net "P5E_CPU1_PE0_RX_DN<0>")
	)
	(segment
		(start 85.65896 -228.289866)
		(end 85.65896 -228.267768)
		(width 0.0889)
		(layer "In13.Cu")
		(net "P5E_CPU1_PE0_RX_DN<0>")
	)
	(segment
		(start 75.16368 -331.250036)
		(end 76.84389 -327.193656)
		(width 0.14732)
		(layer "In13.Cu")
		(net "P5E_CPU1_PE0_RX_DN<0>")
	)
	(segment
		(start 85.832188 -250.834652)
		(end 85.832188 -250.014994)
		(width 0.14732)
		(layer "In13.Cu")
		(net "P5E_CPU1_PE0_RX_DN<0>")
	)
	(segment
		(start 84.662772 -311.107328)
		(end 81.867502 -266.649708)
		(width 0.14732)
		(layer "In13.Cu")
		(net "P5E_CPU1_PE0_RX_DN<0>")
	)
	(segment
		(start 85.832188 -250.014994)
		(end 85.504528 -249.223784)
		(width 0.14732)
		(layer "In13.Cu")
		(net "P5E_CPU1_PE0_RX_DN<0>")
	)
	(segment
		(start 82.89417 -260.093968)
		(end 84.248244 -256.638044)
		(width 0.14732)
		(layer "In13.Cu")
		(net "P5E_CPU1_PE0_RX_DN<0>")
	)
	(segment
		(start 86.922864 -225.527616)
		(end 86.931754 -225.522536)
		(width 0.0889)
		(layer "In13.Cu")
		(net "P5E_CPU1_PE0_RX_DN<0>")
	)
	(segment
		(start 83.485482 -243.48313)
		(end 83.091528 -233.567732)
		(width 0.14732)
		(layer "In13.Cu")
		(net "P5E_CPU1_PE0_RX_DN<0>")
	)
	(segment
		(start 86.640162 -226.025964)
		(end 86.640162 -226.003104)
		(width 0.0889)
		(layer "In13.Cu")
		(net "P5E_CPU1_PE0_RX_DN<0>")
	)
	(segment
		(start 83.091274 -233.567732)
		(end 83.089242 -233.510582)
		(width 0.14732)
		(layer "In13.Cu")
		(net "P5E_CPU1_PE0_RX_DN<0>")
	)
	(segment
		(start 87.392764 -224.7138)
		(end 87.401654 -224.70872)
		(width 0.0889)
		(layer "In13.Cu")
		(net "P5E_CPU1_PE0_RX_DN<0>")
	)
	(segment
		(start 85.177376 -252.089666)
		(end 85.75675 -251.262388)
		(width 0.14732)
		(layer "In13.Cu")
		(net "P5E_CPU1_PE0_RX_DN<0>")
	)
	(segment
		(start 75.16368 -346.409772)
		(end 75.16368 -331.250036)
		(width 0.14732)
		(layer "In13.Cu")
		(net "P5E_CPU1_PE0_RX_DN<0>")
	)
	(segment
		(start 85.175598 -255.477264)
		(end 85.230462 -255.344676)
		(width 0.14732)
		(layer "In13.Cu")
		(net "P5E_CPU1_PE0_RX_DN<0>")
	)
	(segment
		(start 85.010498 -255.875536)
		(end 85.175598 -255.477518)
		(width 0.14732)
		(layer "In13.Cu")
		(net "P5E_CPU1_PE0_RX_DN<0>")
	)
	(segment
		(start 85.65896 -228.267768)
		(end 85.70087 -228.225858)
		(width 0.0889)
		(layer "In13.Cu")
		(net "P5E_CPU1_PE0_RX_DN<0>")
	)
	(segment
		(start 87.580216 -224.389442)
		(end 87.580216 -224.379536)
		(width 0.0889)
		(layer "In13.Cu")
		(net "P5E_CPU1_PE0_RX_DN<0>")
	)
	(segment
		(start 79.459074 -323.459094)
		(end 84.662772 -311.107328)
		(width 0.14732)
		(layer "In13.Cu")
		(net "P5E_CPU1_PE0_RX_DN<0>")
	)
	(segment
		(start 95.754698 -404.4823)
		(end 95.754698 -399.72742)
		(width 0.14732)
		(layer "In13.Cu")
		(net "P5E_CPU1_PE0_RX_DN<0>")
	)
	(segment
		(start 94.037658 -411.317186)
		(end 94.037658 -406.19934)
		(width 0.14732)
		(layer "In13.Cu")
		(net "P5E_CPU1_PE0_RX_DN<0>")
	)
	(segment
		(start 83.479386 -232.513632)
		(end 85.38337 -229.578408)
		(width 0.14732)
		(layer "In13.Cu")
		(net "P5E_CPU1_PE0_RX_DN<0>")
	)
	(segment
		(start 89.650062 -438.741312)
		(end 89.502488 -438.593738)
		(width 0.14732)
		(layer "In13.Cu")
		(net "P5E_CPU1_PE0_RX_DN<0>")
	)
	(segment
		(start 83.089242 -233.510582)
		(end 83.479386 -232.513632)
		(width 0.14732)
		(layer "In13.Cu")
		(net "P5E_CPU1_PE0_RX_DN<0>")
	)
	(segment
		(start 88.965786 -438.593738)
		(end 88.680798 -438.30875)
		(width 0.14732)
		(layer "In13.Cu")
		(net "P5E_CPU1_PE0_RX_DN<0>")
	)
	(segment
		(start 86.446868 -226.345242)
		(end 86.452964 -226.341686)
		(width 0.0889)
		(layer "In13.Cu")
		(net "P5E_CPU1_PE0_RX_DN<0>")
	)
	(segment
		(start 83.091528 -233.567732)
		(end 83.091274 -233.567732)
		(width 0.14732)
		(layer "In13.Cu")
		(net "P5E_CPU1_PE0_RX_DN<0>")
	)
	(segment
		(start 89.24163 -221.404942)
		(end 89.085166 -221.133924)
		(width 0.0889)
		(layer "In13.Cu")
		(net "P5E_CPU1_PE0_RX_DN<0>")
	)
	(segment
		(start 81.867502 -266.649708)
		(end 82.89417 -260.093968)
		(width 0.14732)
		(layer "In13.Cu")
		(net "P5E_CPU1_PE0_RX_DN<0>")
	)
	(segment
		(start 85.38337 -229.578408)
		(end 85.65896 -228.648006)
		(width 0.14732)
		(layer "In13.Cu")
		(net "P5E_CPU1_PE0_RX_DN<0>")
	)
	(segment
		(start 85.504528 -249.223784)
		(end 85.504528 -247.87098)
		(width 0.14732)
		(layer "In13.Cu")
		(net "P5E_CPU1_PE0_RX_DN<0>")
	)
	(segment
		(start 86.170262 -226.83978)
		(end 86.170262 -226.831144)
		(width 0.0889)
		(layer "In13.Cu")
		(net "P5E_CPU1_PE0_RX_DN<0>")
	)
	(segment
		(start 76.84389 -327.193656)
		(end 79.459074 -323.459094)
		(width 0.14732)
		(layer "In13.Cu")
		(net "P5E_CPU1_PE0_RX_DN<0>")
	)
	(segment
		(start 88.680798 -424.520106)
		(end 94.037658 -411.317186)
		(width 0.14732)
		(layer "In13.Cu")
		(net "P5E_CPU1_PE0_RX_DN<0>")
	)
	(segment
		(start 89.650062 -439.0898)
		(end 89.650062 -438.741312)
		(width 0.14732)
		(layer "In13.Cu")
		(net "P5E_CPU1_PE0_RX_DN<0>")
	)
	(segment
		(start 89.2175 -221.494096)
		(end 89.24163 -221.404942)
		(width 0.0889)
		(layer "In13.Cu")
		(net "P5E_CPU1_PE0_RX_DN<0>")
	)
	(segment
		(start 89.502488 -438.593738)
		(end 88.965786 -438.593738)
		(width 0.14732)
		(layer "In13.Cu")
		(net "P5E_CPU1_PE0_RX_DN<0>")
	)
	(segment
		(start 85.970872 -227.162614)
		(end 85.973666 -227.16109)
		(width 0.0889)
		(layer "In13.Cu")
		(net "P5E_CPU1_PE0_RX_DN<0>")
	)
	(segment
		(start 87.110316 -225.203258)
		(end 87.110316 -225.193352)
		(width 0.0889)
		(layer "In13.Cu")
		(net "P5E_CPU1_PE0_RX_DN<0>")
	)
	(segment
		(start 95.754698 -399.72742)
		(end 75.731624 -349.991934)
		(width 0.14732)
		(layer "In13.Cu")
		(net "P5E_CPU1_PE0_RX_DN<0>")
	)
	(segment
		(start 88.680798 -438.30875)
		(end 88.680798 -424.520106)
		(width 0.14732)
		(layer "In13.Cu")
		(net "P5E_CPU1_PE0_RX_DN<0>")
	)
	(segment
		(start 85.70087 -228.225858)
		(end 85.70087 -227.64496)
		(width 0.0889)
		(layer "In13.Cu")
		(net "P5E_CPU1_PE0_RX_DN<0>")
	)
	(segment
		(start 85.504528 -247.87098)
		(end 83.485482 -243.48313)
		(width 0.14732)
		(layer "In13.Cu")
		(net "P5E_CPU1_PE0_RX_DN<0>")
	)
	(segment
		(start 85.971126 -227.162868)
		(end 85.970872 -227.162614)
		(width 0.0889)
		(layer "In13.Cu")
		(net "P5E_CPU1_PE0_RX_DN<0>")
	)
	(segment
		(start 85.175598 -255.477518)
		(end 85.175344 -255.477518)
		(width 0.14732)
		(layer "In13.Cu")
		(net "P5E_CPU1_PE0_RX_DN<0>")
	)
	(segment
		(start 75.731624 -349.991934)
		(end 75.16368 -346.409772)
		(width 0.14732)
		(layer "In13.Cu")
		(net "P5E_CPU1_PE0_RX_DN<0>")
	)
	(segment
		(start 88.049862 -223.584262)
		(end 88.049862 -223.561402)
		(width 0.0889)
		(layer "In13.Cu")
		(net "P5E_CPU1_PE0_RX_DN<0>")
	)
	(segment
		(start 85.175344 -255.477518)
		(end 85.175598 -255.477264)
		(width 0.14732)
		(layer "In13.Cu")
		(net "P5E_CPU1_PE0_RX_DN<0>")
	)
	(arc
		(start 86.452964 -226.341686)
		(mid 86.587897 -226.208332)
		(end 86.640162 -226.025964)
		(width 0.0889)
		(layer "In13.Cu")
		(net "P5E_CPU1_PE0_RX_DN<0>")
	)
	(arc
		(start 88.520016 -222.75165)
		(mid 88.598127 -222.474701)
		(end 88.802464 -222.272098)
		(width 0.0889)
		(layer "In13.Cu")
		(net "P5E_CPU1_PE0_RX_DN<0>")
	)
	(arc
		(start 88.989662 -221.94774)
		(mid 89.049705 -221.693853)
		(end 89.2175 -221.494096)
		(width 0.0889)
		(layer "In13.Cu")
		(net "P5E_CPU1_PE0_RX_DN<0>")
	)
	(arc
		(start 87.862664 -223.899984)
		(mid 87.997597 -223.76663)
		(end 88.049862 -223.584262)
		(width 0.0889)
		(layer "In13.Cu")
		(net "P5E_CPU1_PE0_RX_DN<0>")
	)
	(arc
		(start 87.401654 -224.70872)
		(mid 87.532568 -224.57236)
		(end 87.580216 -224.389442)
		(width 0.0889)
		(layer "In13.Cu")
		(net "P5E_CPU1_PE0_RX_DN<0>")
	)
	(arc
		(start 86.931754 -225.522536)
		(mid 87.062668 -225.386176)
		(end 87.110316 -225.203258)
		(width 0.0889)
		(layer "In13.Cu")
		(net "P5E_CPU1_PE0_RX_DN<0>")
	)
	(arc
		(start 87.580216 -224.379536)
		(mid 87.658327 -224.102587)
		(end 87.862664 -223.899984)
		(width 0.0889)
		(layer "In13.Cu")
		(net "P5E_CPU1_PE0_RX_DN<0>")
	)
	(arc
		(start 88.802464 -222.272098)
		(mid 88.937397 -222.138744)
		(end 88.989662 -221.956376)
		(width 0.0889)
		(layer "In13.Cu")
		(net "P5E_CPU1_PE0_RX_DN<0>")
	)
	(arc
		(start 88.341454 -223.080834)
		(mid 88.472368 -222.944474)
		(end 88.520016 -222.761556)
		(width 0.0889)
		(layer "In13.Cu")
		(net "P5E_CPU1_PE0_RX_DN<0>")
	)
	(arc
		(start 85.983064 -227.155502)
		(mid 86.117997 -227.022148)
		(end 86.170262 -226.83978)
		(width 0.0889)
		(layer "In13.Cu")
		(net "P5E_CPU1_PE0_RX_DN<0>")
	)
	(arc
		(start 87.110316 -225.193352)
		(mid 87.188427 -224.916403)
		(end 87.392764 -224.7138)
		(width 0.0889)
		(layer "In13.Cu")
		(net "P5E_CPU1_PE0_RX_DN<0>")
	)
	(arc
		(start 88.049862 -223.561402)
		(mid 88.129081 -223.286717)
		(end 88.332564 -223.085914)
		(width 0.0889)
		(layer "In13.Cu")
		(net "P5E_CPU1_PE0_RX_DN<0>")
	)
	(arc
		(start 86.640162 -226.003104)
		(mid 86.719381 -225.728419)
		(end 86.922864 -225.527616)
		(width 0.0889)
		(layer "In13.Cu")
		(net "P5E_CPU1_PE0_RX_DN<0>")
	)
	(arc
		(start 85.70087 -227.64496)
		(mid 85.77304 -227.368618)
		(end 85.971126 -227.162868)
		(width 0.0889)
		(layer "In13.Cu")
		(net "P5E_CPU1_PE0_RX_DN<0>")
	)
	(arc
		(start 86.170262 -226.831144)
		(mid 86.244253 -226.551578)
		(end 86.446868 -226.345242)
		(width 0.0889)
		(layer "In13.Cu")
		(net "P5E_CPU1_PE0_RX_DN<0>")
	)
	(segment
		(start 332.11389 -401.779994)
		(end 332.438248 -402.104352)
		(width 0.13208)
		(layer "F.Cu")
		(net "P5E_CPU0_PE4_TX_DP<9>")
	)
	(segment
		(start 332.412848 -400.858228)
		(end 332.11389 -401.157186)
		(width 0.13208)
		(layer "F.Cu")
		(net "P5E_CPU0_PE4_TX_DP<9>")
	)
	(segment
		(start 346.532962 -284.311598)
		(end 346.532962 -284.847284)
		(width 0.13208)
		(layer "F.Cu")
		(net "P5E_CPU0_PE4_TX_DP<9>")
	)
	(segment
		(start 332.11389 -401.157186)
		(end 332.11389 -401.779994)
		(width 0.13208)
		(layer "F.Cu")
		(net "P5E_CPU0_PE4_TX_DP<9>")
	)
	(segment
		(start 346.532962 -284.847284)
		(end 346.533216 -284.847538)
		(width 0.13208)
		(layer "F.Cu")
		(net "P5E_CPU0_PE4_TX_DP<9>")
	)
	(segment
		(start 312.90387 -331.972412)
		(end 311.817512 -334.594962)
		(width 0.14732)
		(layer "In2.Cu")
		(net "P5E_CPU0_PE4_TX_DP<9>")
	)
	(segment
		(start 345.218258 -289.752278)
		(end 345.218258 -290.175442)
		(width 0.0889)
		(layer "In2.Cu")
		(net "P5E_CPU0_PE4_TX_DP<9>")
	)
	(segment
		(start 332.118208 -400.563588)
		(end 332.412848 -400.858228)
		(width 0.14732)
		(layer "In2.Cu")
		(net "P5E_CPU0_PE4_TX_DP<9>")
	)
	(segment
		(start 318.227964 -359.590594)
		(end 332.118208 -399.305018)
		(width 0.14732)
		(layer "In2.Cu")
		(net "P5E_CPU0_PE4_TX_DP<9>")
	)
	(segment
		(start 346.533216 -284.847538)
		(end 346.376752 -285.118556)
		(width 0.0889)
		(layer "In2.Cu")
		(net "P5E_CPU0_PE4_TX_DP<9>")
	)
	(segment
		(start 345.688412 -287.28924)
		(end 345.688412 -287.304734)
		(width 0.0889)
		(layer "In2.Cu")
		(net "P5E_CPU0_PE4_TX_DP<9>")
	)
	(segment
		(start 312.167016 -344.790014)
		(end 318.227964 -359.590594)
		(width 0.14732)
		(layer "In2.Cu")
		(net "P5E_CPU0_PE4_TX_DP<9>")
	)
	(segment
		(start 346.376752 -285.118556)
		(end 346.400882 -285.20771)
		(width 0.0889)
		(layer "In2.Cu")
		(net "P5E_CPU0_PE4_TX_DP<9>")
	)
	(segment
		(start 333.57947 -311.296812)
		(end 312.90387 -331.972412)
		(width 0.14732)
		(layer "In2.Cu")
		(net "P5E_CPU0_PE4_TX_DP<9>")
	)
	(segment
		(start 344.748866 -288.917126)
		(end 344.748866 -289.079178)
		(width 0.0889)
		(layer "In2.Cu")
		(net "P5E_CPU0_PE4_TX_DP<9>")
	)
	(segment
		(start 344.832432 -290.561268)
		(end 344.832432 -290.696904)
		(width 0.0889)
		(layer "In2.Cu")
		(net "P5E_CPU0_PE4_TX_DP<9>")
	)
	(segment
		(start 345.406218 -287.778698)
		(end 345.397328 -287.783778)
		(width 0.0889)
		(layer "In2.Cu")
		(net "P5E_CPU0_PE4_TX_DP<9>")
	)
	(segment
		(start 345.869768 -286.968438)
		(end 345.866974 -286.969962)
		(width 0.0889)
		(layer "In2.Cu")
		(net "P5E_CPU0_PE4_TX_DP<9>")
	)
	(segment
		(start 345.218258 -290.175442)
		(end 344.832432 -290.561268)
		(width 0.0889)
		(layer "In2.Cu")
		(net "P5E_CPU0_PE4_TX_DP<9>")
	)
	(segment
		(start 344.874596 -290.739068)
		(end 344.874596 -290.761166)
		(width 0.0889)
		(layer "In2.Cu")
		(net "P5E_CPU0_PE4_TX_DP<9>")
	)
	(segment
		(start 346.158566 -286.466788)
		(end 346.158566 -286.475424)
		(width 0.0889)
		(layer "In2.Cu")
		(net "P5E_CPU0_PE4_TX_DP<9>")
	)
	(segment
		(start 344.874596 -290.761166)
		(end 344.874596 -299.373798)
		(width 0.14732)
		(layer "In2.Cu")
		(net "P5E_CPU0_PE4_TX_DP<9>")
	)
	(segment
		(start 344.874596 -299.373798)
		(end 344.07221 -301.311056)
		(width 0.14732)
		(layer "In2.Cu")
		(net "P5E_CPU0_PE4_TX_DP<9>")
	)
	(segment
		(start 332.118208 -399.305018)
		(end 332.118208 -400.563588)
		(width 0.14732)
		(layer "In2.Cu")
		(net "P5E_CPU0_PE4_TX_DP<9>")
	)
	(segment
		(start 345.87053 -286.96793)
		(end 345.869768 -286.968438)
		(width 0.0889)
		(layer "In2.Cu")
		(net "P5E_CPU0_PE4_TX_DP<9>")
	)
	(segment
		(start 344.832432 -290.696904)
		(end 344.874596 -290.739068)
		(width 0.0889)
		(layer "In2.Cu")
		(net "P5E_CPU0_PE4_TX_DP<9>")
	)
	(segment
		(start 346.628212 -285.64586)
		(end 346.628212 -285.679896)
		(width 0.0889)
		(layer "In2.Cu")
		(net "P5E_CPU0_PE4_TX_DP<9>")
	)
	(segment
		(start 344.936318 -288.592768)
		(end 344.927428 -288.597848)
		(width 0.0889)
		(layer "In2.Cu")
		(net "P5E_CPU0_PE4_TX_DP<9>")
	)
	(segment
		(start 311.817512 -342.807036)
		(end 312.167016 -344.790014)
		(width 0.14732)
		(layer "In2.Cu")
		(net "P5E_CPU0_PE4_TX_DP<9>")
	)
	(segment
		(start 345.218766 -288.103056)
		(end 345.218766 -288.121598)
		(width 0.0889)
		(layer "In2.Cu")
		(net "P5E_CPU0_PE4_TX_DP<9>")
	)
	(segment
		(start 345.88196 -286.961326)
		(end 345.87053 -286.96793)
		(width 0.0889)
		(layer "In2.Cu")
		(net "P5E_CPU0_PE4_TX_DP<9>")
	)
	(segment
		(start 344.07221 -301.311056)
		(end 335.10855 -310.275224)
		(width 0.14732)
		(layer "In2.Cu")
		(net "P5E_CPU0_PE4_TX_DP<9>")
	)
	(segment
		(start 335.10855 -310.275224)
		(end 333.57947 -311.296812)
		(width 0.14732)
		(layer "In2.Cu")
		(net "P5E_CPU0_PE4_TX_DP<9>")
	)
	(segment
		(start 311.817512 -334.594962)
		(end 311.817512 -342.807036)
		(width 0.14732)
		(layer "In2.Cu")
		(net "P5E_CPU0_PE4_TX_DP<9>")
	)
	(segment
		(start 344.933016 -289.277806)
		(end 344.933016 -289.278314)
		(width 0.0889)
		(layer "In2.Cu")
		(net "P5E_CPU0_PE4_TX_DP<9>")
	)
	(arc
		(start 346.345764 -286.151066)
		(mid 346.210831 -286.28442)
		(end 346.158566 -286.466788)
		(width 0.0889)
		(layer "In2.Cu")
		(net "P5E_CPU0_PE4_TX_DP<9>")
	)
	(arc
		(start 344.927428 -288.597848)
		(mid 344.796514 -288.734208)
		(end 344.748866 -288.917126)
		(width 0.0889)
		(layer "In2.Cu")
		(net "P5E_CPU0_PE4_TX_DP<9>")
	)
	(arc
		(start 344.933016 -289.278314)
		(mid 345.141615 -289.475614)
		(end 345.218258 -289.752278)
		(width 0.0889)
		(layer "In2.Cu")
		(net "P5E_CPU0_PE4_TX_DP<9>")
	)
	(arc
		(start 346.417646 -285.220664)
		(mid 346.569728 -285.410096)
		(end 346.628212 -285.64586)
		(width 0.0889)
		(layer "In2.Cu")
		(net "P5E_CPU0_PE4_TX_DP<9>")
	)
	(arc
		(start 345.397328 -287.783778)
		(mid 345.266414 -287.920138)
		(end 345.218766 -288.103056)
		(width 0.0889)
		(layer "In2.Cu")
		(net "P5E_CPU0_PE4_TX_DP<9>")
	)
	(arc
		(start 345.688412 -287.304734)
		(mid 345.609042 -287.578468)
		(end 345.406218 -287.778698)
		(width 0.0889)
		(layer "In2.Cu")
		(net "P5E_CPU0_PE4_TX_DP<9>")
	)
	(arc
		(start 346.400882 -285.20771)
		(mid 346.409323 -285.21411)
		(end 346.417646 -285.220664)
		(width 0.0889)
		(layer "In2.Cu")
		(net "P5E_CPU0_PE4_TX_DP<9>")
	)
	(arc
		(start 344.748866 -289.079178)
		(mid 344.82396 -289.194242)
		(end 344.933016 -289.277806)
		(width 0.0889)
		(layer "In2.Cu")
		(net "P5E_CPU0_PE4_TX_DP<9>")
	)
	(arc
		(start 345.218766 -288.121598)
		(mid 345.138604 -288.393787)
		(end 344.936318 -288.592768)
		(width 0.0889)
		(layer "In2.Cu")
		(net "P5E_CPU0_PE4_TX_DP<9>")
	)
	(arc
		(start 345.866974 -286.969962)
		(mid 345.73606 -287.106322)
		(end 345.688412 -287.28924)
		(width 0.0889)
		(layer "In2.Cu")
		(net "P5E_CPU0_PE4_TX_DP<9>")
	)
	(arc
		(start 346.158566 -286.475424)
		(mid 346.084575 -286.75499)
		(end 345.88196 -286.961326)
		(width 0.0889)
		(layer "In2.Cu")
		(net "P5E_CPU0_PE4_TX_DP<9>")
	)
	(arc
		(start 346.628212 -285.679896)
		(mid 346.54805 -285.952085)
		(end 346.345764 -286.151066)
		(width 0.0889)
		(layer "In2.Cu")
		(net "P5E_CPU0_PE4_TX_DP<9>")
	)
	(segment
		(start 345.593162 -285.939484)
		(end 345.593162 -286.47517)
		(width 0.13208)
		(layer "F.Cu")
		(net "P5E_CPU0_PE4_TX_DP<8>")
	)
	(segment
		(start 329.05065 -401.157186)
		(end 329.05065 -401.779994)
		(width 0.13208)
		(layer "F.Cu")
		(net "P5E_CPU0_PE4_TX_DP<8>")
	)
	(segment
		(start 329.05065 -401.779994)
		(end 329.375008 -402.104352)
		(width 0.13208)
		(layer "F.Cu")
		(net "P5E_CPU0_PE4_TX_DP<8>")
	)
	(segment
		(start 345.593162 -286.47517)
		(end 345.593416 -286.475424)
		(width 0.13208)
		(layer "F.Cu")
		(net "P5E_CPU0_PE4_TX_DP<8>")
	)
	(segment
		(start 329.349608 -400.858228)
		(end 329.05065 -401.157186)
		(width 0.13208)
		(layer "F.Cu")
		(net "P5E_CPU0_PE4_TX_DP<8>")
	)
	(segment
		(start 343.92997 -291.009324)
		(end 343.92997 -299.149516)
		(width 0.14732)
		(layer "In2.Cu")
		(net "P5E_CPU0_PE4_TX_DP<8>")
	)
	(segment
		(start 328.72553 -397.631666)
		(end 328.63028 -397.813022)
		(width 0.14732)
		(layer "In2.Cu")
		(net "P5E_CPU0_PE4_TX_DP<8>")
	)
	(segment
		(start 344.748612 -287.28924)
		(end 344.748612 -287.304734)
		(width 0.0889)
		(layer "In2.Cu")
		(net "P5E_CPU0_PE4_TX_DP<8>")
	)
	(segment
		(start 312.004964 -331.551534)
		(end 310.884824 -334.255872)
		(width 0.14732)
		(layer "In2.Cu")
		(net "P5E_CPU0_PE4_TX_DP<8>")
	)
	(segment
		(start 343.809066 -288.917126)
		(end 343.809066 -289.078416)
		(width 0.0889)
		(layer "In2.Cu")
		(net "P5E_CPU0_PE4_TX_DP<8>")
	)
	(segment
		(start 329.029822 -398.612106)
		(end 328.934318 -398.793208)
		(width 0.14732)
		(layer "In2.Cu")
		(net "P5E_CPU0_PE4_TX_DP<8>")
	)
	(segment
		(start 329.054968 -399.182082)
		(end 329.054968 -400.563588)
		(width 0.14732)
		(layer "In2.Cu")
		(net "P5E_CPU0_PE4_TX_DP<8>")
	)
	(segment
		(start 316.857126 -359.870502)
		(end 328.435208 -397.184626)
		(width 0.14732)
		(layer "In2.Cu")
		(net "P5E_CPU0_PE4_TX_DP<8>")
	)
	(segment
		(start 333.098648 -310.45785)
		(end 312.004964 -331.551534)
		(width 0.14732)
		(layer "In2.Cu")
		(net "P5E_CPU0_PE4_TX_DP<8>")
	)
	(segment
		(start 328.920602 -398.260062)
		(end 329.029822 -398.612106)
		(width 0.14732)
		(layer "In2.Cu")
		(net "P5E_CPU0_PE4_TX_DP<8>")
	)
	(segment
		(start 310.884824 -334.255872)
		(end 310.884824 -342.888824)
		(width 0.14732)
		(layer "In2.Cu")
		(net "P5E_CPU0_PE4_TX_DP<8>")
	)
	(segment
		(start 311.266078 -345.05265)
		(end 316.855856 -359.866184)
		(width 0.14732)
		(layer "In2.Cu")
		(net "P5E_CPU0_PE4_TX_DP<8>")
	)
	(segment
		(start 344.278966 -288.103056)
		(end 344.278966 -288.121598)
		(width 0.0889)
		(layer "In2.Cu")
		(net "P5E_CPU0_PE4_TX_DP<8>")
	)
	(segment
		(start 344.278712 -290.136326)
		(end 343.887806 -290.718494)
		(width 0.0889)
		(layer "In2.Cu")
		(net "P5E_CPU0_PE4_TX_DP<8>")
	)
	(segment
		(start 343.251536 -300.787816)
		(end 334.555592 -309.484268)
		(width 0.14732)
		(layer "In2.Cu")
		(net "P5E_CPU0_PE4_TX_DP<8>")
	)
	(segment
		(start 343.996518 -288.592768)
		(end 343.987628 -288.597848)
		(width 0.0889)
		(layer "In2.Cu")
		(net "P5E_CPU0_PE4_TX_DP<8>")
	)
	(segment
		(start 328.63028 -397.813022)
		(end 328.739246 -398.164558)
		(width 0.14732)
		(layer "In2.Cu")
		(net "P5E_CPU0_PE4_TX_DP<8>")
	)
	(segment
		(start 344.936064 -286.964882)
		(end 344.927174 -286.969962)
		(width 0.0889)
		(layer "In2.Cu")
		(net "P5E_CPU0_PE4_TX_DP<8>")
	)
	(segment
		(start 343.887806 -290.945062)
		(end 343.92997 -290.987226)
		(width 0.0889)
		(layer "In2.Cu")
		(net "P5E_CPU0_PE4_TX_DP<8>")
	)
	(segment
		(start 344.466418 -287.778698)
		(end 344.457528 -287.783778)
		(width 0.0889)
		(layer "In2.Cu")
		(net "P5E_CPU0_PE4_TX_DP<8>")
	)
	(segment
		(start 345.593416 -286.475424)
		(end 345.436952 -286.204406)
		(width 0.0889)
		(layer "In2.Cu")
		(net "P5E_CPU0_PE4_TX_DP<8>")
	)
	(segment
		(start 345.436952 -286.204406)
		(end 345.35872 -286.183578)
		(width 0.0889)
		(layer "In2.Cu")
		(net "P5E_CPU0_PE4_TX_DP<8>")
	)
	(segment
		(start 343.92997 -290.987226)
		(end 343.92997 -291.009324)
		(width 0.0889)
		(layer "In2.Cu")
		(net "P5E_CPU0_PE4_TX_DP<8>")
	)
	(segment
		(start 344.948256 -286.95777)
		(end 344.936064 -286.964882)
		(width 0.0889)
		(layer "In2.Cu")
		(net "P5E_CPU0_PE4_TX_DP<8>")
	)
	(segment
		(start 316.855856 -359.866184)
		(end 316.857126 -359.870502)
		(width 0.14732)
		(layer "In2.Cu")
		(net "P5E_CPU0_PE4_TX_DP<8>")
	)
	(segment
		(start 343.92997 -299.149516)
		(end 343.251536 -300.787816)
		(width 0.14732)
		(layer "In2.Cu")
		(net "P5E_CPU0_PE4_TX_DP<8>")
	)
	(segment
		(start 328.934318 -398.793208)
		(end 329.054968 -399.182082)
		(width 0.14732)
		(layer "In2.Cu")
		(net "P5E_CPU0_PE4_TX_DP<8>")
	)
	(segment
		(start 329.054968 -400.563588)
		(end 329.349608 -400.858228)
		(width 0.14732)
		(layer "In2.Cu")
		(net "P5E_CPU0_PE4_TX_DP<8>")
	)
	(segment
		(start 328.739246 -398.164558)
		(end 328.920602 -398.260062)
		(width 0.14732)
		(layer "In2.Cu")
		(net "P5E_CPU0_PE4_TX_DP<8>")
	)
	(segment
		(start 343.887806 -290.718494)
		(end 343.887806 -290.945062)
		(width 0.0889)
		(layer "In2.Cu")
		(net "P5E_CPU0_PE4_TX_DP<8>")
	)
	(segment
		(start 328.435208 -397.184626)
		(end 328.616564 -397.279622)
		(width 0.14732)
		(layer "In2.Cu")
		(net "P5E_CPU0_PE4_TX_DP<8>")
	)
	(segment
		(start 344.278712 -289.609784)
		(end 344.278712 -290.136326)
		(width 0.0889)
		(layer "In2.Cu")
		(net "P5E_CPU0_PE4_TX_DP<8>")
	)
	(segment
		(start 334.555592 -309.484268)
		(end 333.098648 -310.45785)
		(width 0.14732)
		(layer "In2.Cu")
		(net "P5E_CPU0_PE4_TX_DP<8>")
	)
	(segment
		(start 328.616564 -397.279622)
		(end 328.72553 -397.631666)
		(width 0.14732)
		(layer "In2.Cu")
		(net "P5E_CPU0_PE4_TX_DP<8>")
	)
	(segment
		(start 310.884824 -342.888824)
		(end 311.266078 -345.05265)
		(width 0.14732)
		(layer "In2.Cu")
		(net "P5E_CPU0_PE4_TX_DP<8>")
	)
	(arc
		(start 343.987628 -288.597848)
		(mid 343.856714 -288.734208)
		(end 343.809066 -288.917126)
		(width 0.0889)
		(layer "In2.Cu")
		(net "P5E_CPU0_PE4_TX_DP<8>")
	)
	(arc
		(start 344.278966 -288.121598)
		(mid 344.198804 -288.393787)
		(end 343.996518 -288.592768)
		(width 0.0889)
		(layer "In2.Cu")
		(net "P5E_CPU0_PE4_TX_DP<8>")
	)
	(arc
		(start 345.218766 -286.475424)
		(mid 345.146531 -286.751948)
		(end 344.948256 -286.95777)
		(width 0.0889)
		(layer "In2.Cu")
		(net "P5E_CPU0_PE4_TX_DP<8>")
	)
	(arc
		(start 344.457528 -287.783778)
		(mid 344.326614 -287.920138)
		(end 344.278966 -288.103056)
		(width 0.0889)
		(layer "In2.Cu")
		(net "P5E_CPU0_PE4_TX_DP<8>")
	)
	(arc
		(start 344.927174 -286.969962)
		(mid 344.79626 -287.106322)
		(end 344.748612 -287.28924)
		(width 0.0889)
		(layer "In2.Cu")
		(net "P5E_CPU0_PE4_TX_DP<8>")
	)
	(arc
		(start 343.993216 -289.277806)
		(mid 344.167426 -289.416744)
		(end 344.278712 -289.609784)
		(width 0.0889)
		(layer "In2.Cu")
		(net "P5E_CPU0_PE4_TX_DP<8>")
	)
	(arc
		(start 344.748612 -287.304734)
		(mid 344.669242 -287.578468)
		(end 344.466418 -287.778698)
		(width 0.0889)
		(layer "In2.Cu")
		(net "P5E_CPU0_PE4_TX_DP<8>")
	)
	(arc
		(start 343.809066 -289.078416)
		(mid 343.884071 -289.193875)
		(end 343.993216 -289.277806)
		(width 0.0889)
		(layer "In2.Cu")
		(net "P5E_CPU0_PE4_TX_DP<8>")
	)
	(arc
		(start 345.35872 -286.183578)
		(mid 345.255575 -286.313603)
		(end 345.218766 -286.475424)
		(width 0.0889)
		(layer "In2.Cu")
		(net "P5E_CPU0_PE4_TX_DP<8>")
	)
	(segment
		(start 325.98741 -401.157186)
		(end 325.98741 -401.779994)
		(width 0.13208)
		(layer "F.Cu")
		(net "P5E_CPU0_PE4_TX_DP<7>")
	)
	(segment
		(start 344.653362 -284.311598)
		(end 344.653362 -284.847284)
		(width 0.13208)
		(layer "F.Cu")
		(net "P5E_CPU0_PE4_TX_DP<7>")
	)
	(segment
		(start 326.286368 -400.858228)
		(end 325.98741 -401.157186)
		(width 0.13208)
		(layer "F.Cu")
		(net "P5E_CPU0_PE4_TX_DP<7>")
	)
	(segment
		(start 344.653362 -284.847284)
		(end 344.653616 -284.847538)
		(width 0.13208)
		(layer "F.Cu")
		(net "P5E_CPU0_PE4_TX_DP<7>")
	)
	(segment
		(start 325.98741 -401.779994)
		(end 326.311768 -402.104352)
		(width 0.13208)
		(layer "F.Cu")
		(net "P5E_CPU0_PE4_TX_DP<7>")
	)
	(segment
		(start 344.497152 -285.118556)
		(end 344.521282 -285.20771)
		(width 0.0889)
		(layer "In2.Cu")
		(net "P5E_CPU0_PE4_TX_DP<7>")
	)
	(segment
		(start 343.00033 -290.982146)
		(end 343.00033 -291.004244)
		(width 0.0889)
		(layer "In2.Cu")
		(net "P5E_CPU0_PE4_TX_DP<7>")
	)
	(segment
		(start 343.00033 -291.004244)
		(end 343.00033 -298.840906)
		(width 0.14732)
		(layer "In2.Cu")
		(net "P5E_CPU0_PE4_TX_DP<7>")
	)
	(segment
		(start 310.344312 -345.329256)
		(end 315.489844 -360.312462)
		(width 0.14732)
		(layer "In2.Cu")
		(net "P5E_CPU0_PE4_TX_DP<7>")
	)
	(segment
		(start 311.170574 -331.06233)
		(end 309.929022 -334.059784)
		(width 0.14732)
		(layer "In2.Cu")
		(net "P5E_CPU0_PE4_TX_DP<7>")
	)
	(segment
		(start 344.00236 -286.961326)
		(end 343.99474 -286.965644)
		(width 0.0889)
		(layer "In2.Cu")
		(net "P5E_CPU0_PE4_TX_DP<7>")
	)
	(segment
		(start 343.338912 -289.60953)
		(end 343.338912 -290.299902)
		(width 0.0889)
		(layer "In2.Cu")
		(net "P5E_CPU0_PE4_TX_DP<7>")
	)
	(segment
		(start 342.869266 -288.917126)
		(end 342.869266 -289.078416)
		(width 0.0889)
		(layer "In2.Cu")
		(net "P5E_CPU0_PE4_TX_DP<7>")
	)
	(segment
		(start 344.538046 -285.220664)
		(end 344.561668 -285.239714)
		(width 0.0889)
		(layer "In2.Cu")
		(net "P5E_CPU0_PE4_TX_DP<7>")
	)
	(segment
		(start 344.278966 -286.466788)
		(end 344.278966 -286.475424)
		(width 0.0889)
		(layer "In2.Cu")
		(net "P5E_CPU0_PE4_TX_DP<7>")
	)
	(segment
		(start 334.031082 -308.645052)
		(end 332.69555 -309.537608)
		(width 0.14732)
		(layer "In2.Cu")
		(net "P5E_CPU0_PE4_TX_DP<7>")
	)
	(segment
		(start 343.339166 -288.103056)
		(end 343.339166 -288.121598)
		(width 0.0889)
		(layer "In2.Cu")
		(net "P5E_CPU0_PE4_TX_DP<7>")
	)
	(segment
		(start 344.653616 -284.847538)
		(end 344.497152 -285.118556)
		(width 0.0889)
		(layer "In2.Cu")
		(net "P5E_CPU0_PE4_TX_DP<7>")
	)
	(segment
		(start 342.410034 -300.2661)
		(end 334.031082 -308.645052)
		(width 0.14732)
		(layer "In2.Cu")
		(net "P5E_CPU0_PE4_TX_DP<7>")
	)
	(segment
		(start 343.99474 -286.965644)
		(end 343.987374 -286.969962)
		(width 0.0889)
		(layer "In2.Cu")
		(net "P5E_CPU0_PE4_TX_DP<7>")
	)
	(segment
		(start 343.808812 -287.28924)
		(end 343.808812 -287.304734)
		(width 0.0889)
		(layer "In2.Cu")
		(net "P5E_CPU0_PE4_TX_DP<7>")
	)
	(segment
		(start 325.991728 -398.987264)
		(end 325.991728 -400.563588)
		(width 0.14732)
		(layer "In2.Cu")
		(net "P5E_CPU0_PE4_TX_DP<7>")
	)
	(segment
		(start 342.958166 -290.52647)
		(end 342.958166 -290.939982)
		(width 0.0889)
		(layer "In2.Cu")
		(net "P5E_CPU0_PE4_TX_DP<7>")
	)
	(segment
		(start 344.74785 -285.615634)
		(end 344.748612 -285.679896)
		(width 0.0889)
		(layer "In2.Cu")
		(net "P5E_CPU0_PE4_TX_DP<7>")
	)
	(segment
		(start 343.056718 -288.592768)
		(end 343.047828 -288.597848)
		(width 0.0889)
		(layer "In2.Cu")
		(net "P5E_CPU0_PE4_TX_DP<7>")
	)
	(segment
		(start 343.526618 -287.778698)
		(end 343.517728 -287.783778)
		(width 0.0889)
		(layer "In2.Cu")
		(net "P5E_CPU0_PE4_TX_DP<7>")
	)
	(segment
		(start 332.69555 -309.537608)
		(end 311.170574 -331.06233)
		(width 0.14732)
		(layer "In2.Cu")
		(net "P5E_CPU0_PE4_TX_DP<7>")
	)
	(segment
		(start 309.929022 -342.972644)
		(end 310.344312 -345.329256)
		(width 0.14732)
		(layer "In2.Cu")
		(net "P5E_CPU0_PE4_TX_DP<7>")
	)
	(segment
		(start 325.991728 -400.563588)
		(end 326.286368 -400.858228)
		(width 0.14732)
		(layer "In2.Cu")
		(net "P5E_CPU0_PE4_TX_DP<7>")
	)
	(segment
		(start 343.00033 -298.840906)
		(end 342.410034 -300.2661)
		(width 0.14732)
		(layer "In2.Cu")
		(net "P5E_CPU0_PE4_TX_DP<7>")
	)
	(segment
		(start 309.929022 -334.059784)
		(end 309.929022 -342.972644)
		(width 0.14732)
		(layer "In2.Cu")
		(net "P5E_CPU0_PE4_TX_DP<7>")
	)
	(segment
		(start 315.489844 -360.312462)
		(end 325.991728 -398.987264)
		(width 0.14732)
		(layer "In2.Cu")
		(net "P5E_CPU0_PE4_TX_DP<7>")
	)
	(segment
		(start 343.338912 -290.299902)
		(end 342.958166 -290.52647)
		(width 0.0889)
		(layer "In2.Cu")
		(net "P5E_CPU0_PE4_TX_DP<7>")
	)
	(segment
		(start 342.958166 -290.939982)
		(end 343.00033 -290.982146)
		(width 0.0889)
		(layer "In2.Cu")
		(net "P5E_CPU0_PE4_TX_DP<7>")
	)
	(arc
		(start 344.466164 -286.151066)
		(mid 344.331231 -286.28442)
		(end 344.278966 -286.466788)
		(width 0.0889)
		(layer "In2.Cu")
		(net "P5E_CPU0_PE4_TX_DP<7>")
	)
	(arc
		(start 344.278966 -286.475424)
		(mid 344.204975 -286.75499)
		(end 344.00236 -286.961326)
		(width 0.0889)
		(layer "In2.Cu")
		(net "P5E_CPU0_PE4_TX_DP<7>")
	)
	(arc
		(start 343.808812 -287.304734)
		(mid 343.729442 -287.578468)
		(end 343.526618 -287.778698)
		(width 0.0889)
		(layer "In2.Cu")
		(net "P5E_CPU0_PE4_TX_DP<7>")
	)
	(arc
		(start 344.521282 -285.20771)
		(mid 344.529723 -285.21411)
		(end 344.538046 -285.220664)
		(width 0.0889)
		(layer "In2.Cu")
		(net "P5E_CPU0_PE4_TX_DP<7>")
	)
	(arc
		(start 343.987374 -286.969962)
		(mid 343.85646 -287.106322)
		(end 343.808812 -287.28924)
		(width 0.0889)
		(layer "In2.Cu")
		(net "P5E_CPU0_PE4_TX_DP<7>")
	)
	(arc
		(start 343.053416 -289.277806)
		(mid 343.227548 -289.416653)
		(end 343.338912 -289.60953)
		(width 0.0889)
		(layer "In2.Cu")
		(net "P5E_CPU0_PE4_TX_DP<7>")
	)
	(arc
		(start 342.869266 -289.078416)
		(mid 342.944271 -289.193875)
		(end 343.053416 -289.277806)
		(width 0.0889)
		(layer "In2.Cu")
		(net "P5E_CPU0_PE4_TX_DP<7>")
	)
	(arc
		(start 344.748612 -285.679896)
		(mid 344.66845 -285.952085)
		(end 344.466164 -286.151066)
		(width 0.0889)
		(layer "In2.Cu")
		(net "P5E_CPU0_PE4_TX_DP<7>")
	)
	(arc
		(start 343.517728 -287.783778)
		(mid 343.386814 -287.920138)
		(end 343.339166 -288.103056)
		(width 0.0889)
		(layer "In2.Cu")
		(net "P5E_CPU0_PE4_TX_DP<7>")
	)
	(arc
		(start 343.339166 -288.121598)
		(mid 343.259004 -288.393787)
		(end 343.056718 -288.592768)
		(width 0.0889)
		(layer "In2.Cu")
		(net "P5E_CPU0_PE4_TX_DP<7>")
	)
	(arc
		(start 344.561668 -285.239714)
		(mid 344.696136 -285.407189)
		(end 344.74785 -285.615634)
		(width 0.0889)
		(layer "In2.Cu")
		(net "P5E_CPU0_PE4_TX_DP<7>")
	)
	(arc
		(start 343.047828 -288.597848)
		(mid 342.916914 -288.734208)
		(end 342.869266 -288.917126)
		(width 0.0889)
		(layer "In2.Cu")
		(net "P5E_CPU0_PE4_TX_DP<7>")
	)
	(segment
		(start 323.223128 -400.858228)
		(end 322.92417 -401.157186)
		(width 0.13208)
		(layer "F.Cu")
		(net "P5E_CPU0_PE4_TX_DP<6>")
	)
	(segment
		(start 322.92417 -401.779994)
		(end 323.248528 -402.104352)
		(width 0.13208)
		(layer "F.Cu")
		(net "P5E_CPU0_PE4_TX_DP<6>")
	)
	(segment
		(start 322.92417 -401.157186)
		(end 322.92417 -401.779994)
		(width 0.13208)
		(layer "F.Cu")
		(net "P5E_CPU0_PE4_TX_DP<6>")
	)
	(segment
		(start 343.713562 -285.939484)
		(end 343.713562 -286.47517)
		(width 0.13208)
		(layer "F.Cu")
		(net "P5E_CPU0_PE4_TX_DP<6>")
	)
	(segment
		(start 343.713562 -286.47517)
		(end 343.713816 -286.475424)
		(width 0.13208)
		(layer "F.Cu")
		(net "P5E_CPU0_PE4_TX_DP<6>")
	)
	(segment
		(start 322.60286 -397.491458)
		(end 322.752466 -397.58493)
		(width 0.14732)
		(layer "In2.Cu")
		(net "P5E_CPU0_PE4_TX_DP<6>")
	)
	(segment
		(start 343.557352 -286.204406)
		(end 343.47912 -286.183578)
		(width 0.0889)
		(layer "In2.Cu")
		(net "P5E_CPU0_PE4_TX_DP<6>")
	)
	(segment
		(start 342.398858 -290.299648)
		(end 342.027256 -290.526724)
		(width 0.0889)
		(layer "In2.Cu")
		(net "P5E_CPU0_PE4_TX_DP<6>")
	)
	(segment
		(start 322.500244 -396.490698)
		(end 322.598288 -396.916656)
		(width 0.14732)
		(layer "In2.Cu")
		(net "P5E_CPU0_PE4_TX_DP<6>")
	)
	(segment
		(start 342.027256 -290.939982)
		(end 342.06942 -290.982146)
		(width 0.0889)
		(layer "In2.Cu")
		(net "P5E_CPU0_PE4_TX_DP<6>")
	)
	(segment
		(start 342.116918 -288.592768)
		(end 342.108028 -288.597848)
		(width 0.0889)
		(layer "In2.Cu")
		(net "P5E_CPU0_PE4_TX_DP<6>")
	)
	(segment
		(start 314.08624 -360.500676)
		(end 322.351146 -396.39748)
		(width 0.14732)
		(layer "In2.Cu")
		(net "P5E_CPU0_PE4_TX_DP<6>")
	)
	(segment
		(start 322.928488 -398.882108)
		(end 322.928488 -400.563588)
		(width 0.14732)
		(layer "In2.Cu")
		(net "P5E_CPU0_PE4_TX_DP<6>")
	)
	(segment
		(start 322.757038 -398.159986)
		(end 322.92163 -398.87525)
		(width 0.14732)
		(layer "In2.Cu")
		(net "P5E_CPU0_PE4_TX_DP<6>")
	)
	(segment
		(start 308.99354 -343.054686)
		(end 309.428642 -345.523312)
		(width 0.14732)
		(layer "In2.Cu")
		(net "P5E_CPU0_PE4_TX_DP<6>")
	)
	(segment
		(start 322.752466 -397.58493)
		(end 322.85051 -398.010888)
		(width 0.14732)
		(layer "In2.Cu")
		(net "P5E_CPU0_PE4_TX_DP<6>")
	)
	(segment
		(start 333.479394 -307.856128)
		(end 332.152498 -308.742842)
		(width 0.14732)
		(layer "In2.Cu")
		(net "P5E_CPU0_PE4_TX_DP<6>")
	)
	(segment
		(start 332.152498 -308.742842)
		(end 310.366156 -330.529184)
		(width 0.14732)
		(layer "In2.Cu")
		(net "P5E_CPU0_PE4_TX_DP<6>")
	)
	(segment
		(start 343.713816 -286.475424)
		(end 343.557352 -286.204406)
		(width 0.0889)
		(layer "In2.Cu")
		(net "P5E_CPU0_PE4_TX_DP<6>")
	)
	(segment
		(start 322.85051 -398.010888)
		(end 322.757038 -398.159986)
		(width 0.14732)
		(layer "In2.Cu")
		(net "P5E_CPU0_PE4_TX_DP<6>")
	)
	(segment
		(start 342.869012 -287.28924)
		(end 342.869012 -287.304734)
		(width 0.0889)
		(layer "In2.Cu")
		(net "P5E_CPU0_PE4_TX_DP<6>")
	)
	(segment
		(start 342.06942 -298.548044)
		(end 341.561928 -299.773594)
		(width 0.14732)
		(layer "In2.Cu")
		(net "P5E_CPU0_PE4_TX_DP<6>")
	)
	(segment
		(start 342.398858 -289.75177)
		(end 342.398858 -290.299648)
		(width 0.0889)
		(layer "In2.Cu")
		(net "P5E_CPU0_PE4_TX_DP<6>")
	)
	(segment
		(start 342.06942 -290.982146)
		(end 342.06942 -291.004244)
		(width 0.0889)
		(layer "In2.Cu")
		(net "P5E_CPU0_PE4_TX_DP<6>")
	)
	(segment
		(start 341.929466 -288.917126)
		(end 341.929466 -289.078416)
		(width 0.0889)
		(layer "In2.Cu")
		(net "P5E_CPU0_PE4_TX_DP<6>")
	)
	(segment
		(start 343.056464 -286.964882)
		(end 343.047574 -286.969962)
		(width 0.0889)
		(layer "In2.Cu")
		(net "P5E_CPU0_PE4_TX_DP<6>")
	)
	(segment
		(start 343.068656 -286.95777)
		(end 343.056464 -286.964882)
		(width 0.0889)
		(layer "In2.Cu")
		(net "P5E_CPU0_PE4_TX_DP<6>")
	)
	(segment
		(start 309.428642 -345.523312)
		(end 314.08624 -360.500676)
		(width 0.14732)
		(layer "In2.Cu")
		(net "P5E_CPU0_PE4_TX_DP<6>")
	)
	(segment
		(start 342.399366 -288.103056)
		(end 342.399366 -288.121598)
		(width 0.0889)
		(layer "In2.Cu")
		(net "P5E_CPU0_PE4_TX_DP<6>")
	)
	(segment
		(start 322.928488 -400.563588)
		(end 323.223128 -400.858228)
		(width 0.14732)
		(layer "In2.Cu")
		(net "P5E_CPU0_PE4_TX_DP<6>")
	)
	(segment
		(start 341.561928 -299.773594)
		(end 333.479394 -307.856128)
		(width 0.14732)
		(layer "In2.Cu")
		(net "P5E_CPU0_PE4_TX_DP<6>")
	)
	(segment
		(start 322.92163 -398.87525)
		(end 322.928488 -398.882108)
		(width 0.14732)
		(layer "In2.Cu")
		(net "P5E_CPU0_PE4_TX_DP<6>")
	)
	(segment
		(start 322.598288 -396.916656)
		(end 322.50507 -397.065754)
		(width 0.14732)
		(layer "In2.Cu")
		(net "P5E_CPU0_PE4_TX_DP<6>")
	)
	(segment
		(start 322.50507 -397.065754)
		(end 322.60286 -397.491458)
		(width 0.14732)
		(layer "In2.Cu")
		(net "P5E_CPU0_PE4_TX_DP<6>")
	)
	(segment
		(start 308.99354 -333.842868)
		(end 308.99354 -343.054686)
		(width 0.14732)
		(layer "In2.Cu")
		(net "P5E_CPU0_PE4_TX_DP<6>")
	)
	(segment
		(start 342.027256 -290.526724)
		(end 342.027256 -290.939982)
		(width 0.0889)
		(layer "In2.Cu")
		(net "P5E_CPU0_PE4_TX_DP<6>")
	)
	(segment
		(start 310.366156 -330.529184)
		(end 308.99354 -333.842868)
		(width 0.14732)
		(layer "In2.Cu")
		(net "P5E_CPU0_PE4_TX_DP<6>")
	)
	(segment
		(start 322.351146 -396.39748)
		(end 322.500244 -396.490698)
		(width 0.14732)
		(layer "In2.Cu")
		(net "P5E_CPU0_PE4_TX_DP<6>")
	)
	(segment
		(start 342.586818 -287.778698)
		(end 342.577928 -287.783778)
		(width 0.0889)
		(layer "In2.Cu")
		(net "P5E_CPU0_PE4_TX_DP<6>")
	)
	(segment
		(start 342.06942 -291.004244)
		(end 342.06942 -298.548044)
		(width 0.14732)
		(layer "In2.Cu")
		(net "P5E_CPU0_PE4_TX_DP<6>")
	)
	(arc
		(start 343.47912 -286.183578)
		(mid 343.375975 -286.313603)
		(end 343.339166 -286.475424)
		(width 0.0889)
		(layer "In2.Cu")
		(net "P5E_CPU0_PE4_TX_DP<6>")
	)
	(arc
		(start 342.869012 -287.304734)
		(mid 342.789642 -287.578468)
		(end 342.586818 -287.778698)
		(width 0.0889)
		(layer "In2.Cu")
		(net "P5E_CPU0_PE4_TX_DP<6>")
	)
	(arc
		(start 343.047574 -286.969962)
		(mid 342.91666 -287.106322)
		(end 342.869012 -287.28924)
		(width 0.0889)
		(layer "In2.Cu")
		(net "P5E_CPU0_PE4_TX_DP<6>")
	)
	(arc
		(start 342.577928 -287.783778)
		(mid 342.447014 -287.920138)
		(end 342.399366 -288.103056)
		(width 0.0889)
		(layer "In2.Cu")
		(net "P5E_CPU0_PE4_TX_DP<6>")
	)
	(arc
		(start 342.108028 -288.597848)
		(mid 341.977114 -288.734208)
		(end 341.929466 -288.917126)
		(width 0.0889)
		(layer "In2.Cu")
		(net "P5E_CPU0_PE4_TX_DP<6>")
	)
	(arc
		(start 342.113616 -289.277806)
		(mid 342.322213 -289.475092)
		(end 342.398858 -289.75177)
		(width 0.0889)
		(layer "In2.Cu")
		(net "P5E_CPU0_PE4_TX_DP<6>")
	)
	(arc
		(start 342.399366 -288.121598)
		(mid 342.319204 -288.393787)
		(end 342.116918 -288.592768)
		(width 0.0889)
		(layer "In2.Cu")
		(net "P5E_CPU0_PE4_TX_DP<6>")
	)
	(arc
		(start 341.929466 -289.078416)
		(mid 342.004471 -289.193875)
		(end 342.113616 -289.277806)
		(width 0.0889)
		(layer "In2.Cu")
		(net "P5E_CPU0_PE4_TX_DP<6>")
	)
	(arc
		(start 343.339166 -286.475424)
		(mid 343.266931 -286.751948)
		(end 343.068656 -286.95777)
		(width 0.0889)
		(layer "In2.Cu")
		(net "P5E_CPU0_PE4_TX_DP<6>")
	)
	(segment
		(start 319.86093 -401.779994)
		(end 320.185288 -402.104352)
		(width 0.13208)
		(layer "F.Cu")
		(net "P5E_CPU0_PE4_TX_DP<5>")
	)
	(segment
		(start 342.773762 -284.847284)
		(end 342.774016 -284.847538)
		(width 0.13208)
		(layer "F.Cu")
		(net "P5E_CPU0_PE4_TX_DP<5>")
	)
	(segment
		(start 342.773762 -284.311598)
		(end 342.773762 -284.847284)
		(width 0.13208)
		(layer "F.Cu")
		(net "P5E_CPU0_PE4_TX_DP<5>")
	)
	(segment
		(start 320.159888 -400.858228)
		(end 319.86093 -401.157186)
		(width 0.13208)
		(layer "F.Cu")
		(net "P5E_CPU0_PE4_TX_DP<5>")
	)
	(segment
		(start 319.86093 -401.157186)
		(end 319.86093 -401.779994)
		(width 0.13208)
		(layer "F.Cu")
		(net "P5E_CPU0_PE4_TX_DP<5>")
	)
	(segment
		(start 342.114886 -286.965644)
		(end 342.11133 -286.967676)
		(width 0.0889)
		(layer "In2.Cu")
		(net "P5E_CPU0_PE4_TX_DP<5>")
	)
	(segment
		(start 340.989412 -289.082226)
		(end 341.000334 -289.112706)
		(width 0.0889)
		(layer "In2.Cu")
		(net "P5E_CPU0_PE4_TX_DP<5>")
	)
	(segment
		(start 341.13978 -290.92398)
		(end 341.13978 -298.053252)
		(width 0.14732)
		(layer "In2.Cu")
		(net "P5E_CPU0_PE4_TX_DP<5>")
	)
	(segment
		(start 341.649812 -287.776412)
		(end 341.640922 -287.781746)
		(width 0.0889)
		(layer "In2.Cu")
		(net "P5E_CPU0_PE4_TX_DP<5>")
	)
	(segment
		(start 309.75173 -326.048116)
		(end 309.406036 -326.39381)
		(width 0.14732)
		(layer "In2.Cu")
		(net "P5E_CPU0_PE4_TX_DP<5>")
	)
	(segment
		(start 340.598506 -299.360082)
		(end 332.786228 -307.17236)
		(width 0.14732)
		(layer "In2.Cu")
		(net "P5E_CPU0_PE4_TX_DP<5>")
	)
	(segment
		(start 331.611732 -307.95722)
		(end 314.33643 -325.232522)
		(width 0.14732)
		(layer "In2.Cu")
		(net "P5E_CPU0_PE4_TX_DP<5>")
	)
	(segment
		(start 308.511448 -345.711526)
		(end 312.738008 -360.88447)
		(width 0.14732)
		(layer "In2.Cu")
		(net "P5E_CPU0_PE4_TX_DP<5>")
	)
	(segment
		(start 309.406036 -326.39381)
		(end 309.221378 -326.839326)
		(width 0.14732)
		(layer "In2.Cu")
		(net "P5E_CPU0_PE4_TX_DP<5>")
	)
	(segment
		(start 341.459312 -288.09061)
		(end 341.459312 -288.103056)
		(width 0.0889)
		(layer "In2.Cu")
		(net "P5E_CPU0_PE4_TX_DP<5>")
	)
	(segment
		(start 312.840624 -325.852028)
		(end 310.224932 -325.852028)
		(width 0.14732)
		(layer "In2.Cu")
		(net "P5E_CPU0_PE4_TX_DP<5>")
	)
	(segment
		(start 341.659972 -287.77057)
		(end 341.649812 -287.776412)
		(width 0.0889)
		(layer "In2.Cu")
		(net "P5E_CPU0_PE4_TX_DP<5>")
	)
	(segment
		(start 341.097616 -290.859718)
		(end 341.13978 -290.901882)
		(width 0.0889)
		(layer "In2.Cu")
		(net "P5E_CPU0_PE4_TX_DP<5>")
	)
	(segment
		(start 342.12657 -286.958786)
		(end 342.114886 -286.965644)
		(width 0.0889)
		(layer "In2.Cu")
		(net "P5E_CPU0_PE4_TX_DP<5>")
	)
	(segment
		(start 342.399366 -286.466788)
		(end 342.399366 -286.485584)
		(width 0.0889)
		(layer "In2.Cu")
		(net "P5E_CPU0_PE4_TX_DP<5>")
	)
	(segment
		(start 341.458804 -289.751008)
		(end 341.458804 -290.29279)
		(width 0.0889)
		(layer "In2.Cu")
		(net "P5E_CPU0_PE4_TX_DP<5>")
	)
	(segment
		(start 308.05755 -343.136728)
		(end 308.511448 -345.711526)
		(width 0.14732)
		(layer "In2.Cu")
		(net "P5E_CPU0_PE4_TX_DP<5>")
	)
	(segment
		(start 308.05755 -333.588106)
		(end 308.05755 -343.136728)
		(width 0.14732)
		(layer "In2.Cu")
		(net "P5E_CPU0_PE4_TX_DP<5>")
	)
	(segment
		(start 341.187278 -288.586164)
		(end 341.17661 -288.592514)
		(width 0.0889)
		(layer "In2.Cu")
		(net "P5E_CPU0_PE4_TX_DP<5>")
	)
	(segment
		(start 341.13978 -298.053252)
		(end 340.598506 -299.360082)
		(width 0.14732)
		(layer "In2.Cu")
		(net "P5E_CPU0_PE4_TX_DP<5>")
	)
	(segment
		(start 341.097616 -290.52647)
		(end 341.097616 -290.859718)
		(width 0.0889)
		(layer "In2.Cu")
		(net "P5E_CPU0_PE4_TX_DP<5>")
	)
	(segment
		(start 341.13978 -290.901882)
		(end 341.13978 -290.92398)
		(width 0.0889)
		(layer "In2.Cu")
		(net "P5E_CPU0_PE4_TX_DP<5>")
	)
	(segment
		(start 312.738008 -360.88447)
		(end 319.865248 -398.579848)
		(width 0.14732)
		(layer "In2.Cu")
		(net "P5E_CPU0_PE4_TX_DP<5>")
	)
	(segment
		(start 341.116412 -289.247834)
		(end 341.173816 -289.27806)
		(width 0.0889)
		(layer "In2.Cu")
		(net "P5E_CPU0_PE4_TX_DP<5>")
	)
	(segment
		(start 342.617552 -285.118556)
		(end 342.641682 -285.20771)
		(width 0.0889)
		(layer "In2.Cu")
		(net "P5E_CPU0_PE4_TX_DP<5>")
	)
	(segment
		(start 332.786228 -307.17236)
		(end 331.611732 -307.95722)
		(width 0.14732)
		(layer "In2.Cu")
		(net "P5E_CPU0_PE4_TX_DP<5>")
	)
	(segment
		(start 309.221378 -327.736454)
		(end 308.05755 -333.588106)
		(width 0.14732)
		(layer "In2.Cu")
		(net "P5E_CPU0_PE4_TX_DP<5>")
	)
	(segment
		(start 319.865248 -400.563588)
		(end 320.159888 -400.858228)
		(width 0.14732)
		(layer "In2.Cu")
		(net "P5E_CPU0_PE4_TX_DP<5>")
	)
	(segment
		(start 342.399366 -286.485584)
		(end 342.398858 -286.486092)
		(width 0.0889)
		(layer "In2.Cu")
		(net "P5E_CPU0_PE4_TX_DP<5>")
	)
	(segment
		(start 341.458804 -290.29279)
		(end 341.097616 -290.52647)
		(width 0.0889)
		(layer "In2.Cu")
		(net "P5E_CPU0_PE4_TX_DP<5>")
	)
	(segment
		(start 340.989412 -288.90214)
		(end 340.989412 -289.082226)
		(width 0.0889)
		(layer "In2.Cu")
		(net "P5E_CPU0_PE4_TX_DP<5>")
	)
	(segment
		(start 314.33643 -325.232522)
		(end 312.840624 -325.852028)
		(width 0.14732)
		(layer "In2.Cu")
		(net "P5E_CPU0_PE4_TX_DP<5>")
	)
	(segment
		(start 310.224932 -325.852028)
		(end 309.75173 -326.048116)
		(width 0.14732)
		(layer "In2.Cu")
		(net "P5E_CPU0_PE4_TX_DP<5>")
	)
	(segment
		(start 319.865248 -398.579848)
		(end 319.865248 -400.563588)
		(width 0.14732)
		(layer "In2.Cu")
		(net "P5E_CPU0_PE4_TX_DP<5>")
	)
	(segment
		(start 342.774016 -284.847538)
		(end 342.617552 -285.118556)
		(width 0.0889)
		(layer "In2.Cu")
		(net "P5E_CPU0_PE4_TX_DP<5>")
	)
	(segment
		(start 342.869012 -285.64586)
		(end 342.869012 -285.679896)
		(width 0.0889)
		(layer "In2.Cu")
		(net "P5E_CPU0_PE4_TX_DP<5>")
	)
	(segment
		(start 309.221378 -326.839326)
		(end 309.221378 -327.736454)
		(width 0.14732)
		(layer "In2.Cu")
		(net "P5E_CPU0_PE4_TX_DP<5>")
	)
	(arc
		(start 342.398858 -286.486092)
		(mid 342.323598 -286.757519)
		(end 342.12657 -286.958786)
		(width 0.0889)
		(layer "In2.Cu")
		(net "P5E_CPU0_PE4_TX_DP<5>")
	)
	(arc
		(start 341.928958 -287.28924)
		(mid 341.85715 -287.564936)
		(end 341.659972 -287.77057)
		(width 0.0889)
		(layer "In2.Cu")
		(net "P5E_CPU0_PE4_TX_DP<5>")
	)
	(arc
		(start 342.586564 -286.151066)
		(mid 342.451631 -286.28442)
		(end 342.399366 -286.466788)
		(width 0.0889)
		(layer "In2.Cu")
		(net "P5E_CPU0_PE4_TX_DP<5>")
	)
	(arc
		(start 341.000334 -289.112706)
		(mid 341.045585 -289.191255)
		(end 341.116412 -289.247834)
		(width 0.0889)
		(layer "In2.Cu")
		(net "P5E_CPU0_PE4_TX_DP<5>")
	)
	(arc
		(start 341.459312 -288.103056)
		(mid 341.38662 -288.380261)
		(end 341.187278 -288.586164)
		(width 0.0889)
		(layer "In2.Cu")
		(net "P5E_CPU0_PE4_TX_DP<5>")
	)
	(arc
		(start 341.17661 -288.592514)
		(mid 341.043233 -288.723274)
		(end 340.989412 -288.90214)
		(width 0.0889)
		(layer "In2.Cu")
		(net "P5E_CPU0_PE4_TX_DP<5>")
	)
	(arc
		(start 341.640922 -287.781746)
		(mid 341.510827 -287.913086)
		(end 341.459312 -288.09061)
		(width 0.0889)
		(layer "In2.Cu")
		(net "P5E_CPU0_PE4_TX_DP<5>")
	)
	(arc
		(start 342.658446 -285.220664)
		(mid 342.810528 -285.410096)
		(end 342.869012 -285.64586)
		(width 0.0889)
		(layer "In2.Cu")
		(net "P5E_CPU0_PE4_TX_DP<5>")
	)
	(arc
		(start 341.173816 -289.27806)
		(mid 341.381961 -289.474967)
		(end 341.458804 -289.751008)
		(width 0.0889)
		(layer "In2.Cu")
		(net "P5E_CPU0_PE4_TX_DP<5>")
	)
	(arc
		(start 342.11133 -286.967676)
		(mid 341.977714 -287.104396)
		(end 341.928958 -287.28924)
		(width 0.0889)
		(layer "In2.Cu")
		(net "P5E_CPU0_PE4_TX_DP<5>")
	)
	(arc
		(start 342.641682 -285.20771)
		(mid 342.650123 -285.21411)
		(end 342.658446 -285.220664)
		(width 0.0889)
		(layer "In2.Cu")
		(net "P5E_CPU0_PE4_TX_DP<5>")
	)
	(arc
		(start 342.869012 -285.679896)
		(mid 342.78885 -285.952085)
		(end 342.586564 -286.151066)
		(width 0.0889)
		(layer "In2.Cu")
		(net "P5E_CPU0_PE4_TX_DP<5>")
	)
	(segment
		(start 316.79769 -401.157186)
		(end 316.79769 -401.779994)
		(width 0.13208)
		(layer "F.Cu")
		(net "P5E_CPU0_PE4_TX_DP<4>")
	)
	(segment
		(start 316.79769 -401.779994)
		(end 317.122048 -402.104352)
		(width 0.13208)
		(layer "F.Cu")
		(net "P5E_CPU0_PE4_TX_DP<4>")
	)
	(segment
		(start 341.833962 -286.47517)
		(end 341.834216 -286.475424)
		(width 0.13208)
		(layer "F.Cu")
		(net "P5E_CPU0_PE4_TX_DP<4>")
	)
	(segment
		(start 317.096648 -400.858228)
		(end 316.79769 -401.157186)
		(width 0.13208)
		(layer "F.Cu")
		(net "P5E_CPU0_PE4_TX_DP<4>")
	)
	(segment
		(start 341.833962 -285.939484)
		(end 341.833962 -286.47517)
		(width 0.13208)
		(layer "F.Cu")
		(net "P5E_CPU0_PE4_TX_DP<4>")
	)
	(segment
		(start 307.05298 -343.224866)
		(end 307.342286 -344.866468)
		(width 0.14732)
		(layer "In2.Cu")
		(net "P5E_CPU0_PE4_TX_DP<4>")
	)
	(segment
		(start 308.285642 -327.609962)
		(end 307.05298 -333.807562)
		(width 0.14732)
		(layer "In2.Cu")
		(net "P5E_CPU0_PE4_TX_DP<4>")
	)
	(segment
		(start 316.802008 -397.970502)
		(end 316.802008 -398.407382)
		(width 0.14732)
		(layer "In2.Cu")
		(net "P5E_CPU0_PE4_TX_DP<4>")
	)
	(segment
		(start 340.174072 -289.211004)
		(end 340.242144 -289.248596)
		(width 0.0889)
		(layer "In2.Cu")
		(net "P5E_CPU0_PE4_TX_DP<4>")
	)
	(segment
		(start 312.680604 -324.909688)
		(end 310.017414 -324.909688)
		(width 0.14732)
		(layer "In2.Cu")
		(net "P5E_CPU0_PE4_TX_DP<4>")
	)
	(segment
		(start 341.180674 -286.962596)
		(end 341.179658 -286.963104)
		(width 0.0889)
		(layer "In2.Cu")
		(net "P5E_CPU0_PE4_TX_DP<4>")
	)
	(segment
		(start 330.04125 -308.204108)
		(end 313.798458 -324.446646)
		(width 0.14732)
		(layer "In2.Cu")
		(net "P5E_CPU0_PE4_TX_DP<4>")
	)
	(segment
		(start 340.237318 -288.592768)
		(end 340.236556 -288.593276)
		(width 0.0889)
		(layer "In2.Cu")
		(net "P5E_CPU0_PE4_TX_DP<4>")
	)
	(segment
		(start 316.802008 -398.407382)
		(end 316.926468 -398.531842)
		(width 0.14732)
		(layer "In2.Cu")
		(net "P5E_CPU0_PE4_TX_DP<4>")
	)
	(segment
		(start 340.989666 -287.280604)
		(end 340.989666 -287.299146)
		(width 0.0889)
		(layer "In2.Cu")
		(net "P5E_CPU0_PE4_TX_DP<4>")
	)
	(segment
		(start 316.802008 -399.093182)
		(end 316.802008 -400.563588)
		(width 0.14732)
		(layer "In2.Cu")
		(net "P5E_CPU0_PE4_TX_DP<4>")
	)
	(segment
		(start 340.197694 -290.951158)
		(end 340.197694 -292.072568)
		(width 0.14732)
		(layer "In2.Cu")
		(net "P5E_CPU0_PE4_TX_DP<4>")
	)
	(segment
		(start 340.519766 -289.719004)
		(end 340.519766 -290.387024)
		(width 0.0889)
		(layer "In2.Cu")
		(net "P5E_CPU0_PE4_TX_DP<4>")
	)
	(segment
		(start 340.236556 -288.593276)
		(end 340.228428 -288.597848)
		(width 0.0889)
		(layer "In2.Cu")
		(net "P5E_CPU0_PE4_TX_DP<4>")
	)
	(segment
		(start 340.519766 -290.387024)
		(end 340.15553 -290.75126)
		(width 0.0889)
		(layer "In2.Cu")
		(net "P5E_CPU0_PE4_TX_DP<4>")
	)
	(segment
		(start 340.197694 -292.072568)
		(end 336.529172 -295.741344)
		(width 0.14732)
		(layer "In2.Cu")
		(net "P5E_CPU0_PE4_TX_DP<4>")
	)
	(segment
		(start 316.790832 -397.041116)
		(end 316.68593 -397.18234)
		(width 0.14732)
		(layer "In2.Cu")
		(net "P5E_CPU0_PE4_TX_DP<4>")
	)
	(segment
		(start 316.926468 -398.531842)
		(end 316.926468 -398.968722)
		(width 0.14732)
		(layer "In2.Cu")
		(net "P5E_CPU0_PE4_TX_DP<4>")
	)
	(segment
		(start 340.15553 -290.886896)
		(end 340.197694 -290.92906)
		(width 0.0889)
		(layer "In2.Cu")
		(net "P5E_CPU0_PE4_TX_DP<4>")
	)
	(segment
		(start 308.285642 -326.613012)
		(end 308.285642 -327.609962)
		(width 0.14732)
		(layer "In2.Cu")
		(net "P5E_CPU0_PE4_TX_DP<4>")
	)
	(segment
		(start 336.529172 -295.741344)
		(end 330.04125 -308.204108)
		(width 0.14732)
		(layer "In2.Cu")
		(net "P5E_CPU0_PE4_TX_DP<4>")
	)
	(segment
		(start 310.017414 -324.909688)
		(end 309.236618 -325.23303)
		(width 0.14732)
		(layer "In2.Cu")
		(net "P5E_CPU0_PE4_TX_DP<4>")
	)
	(segment
		(start 316.5856 -396.503652)
		(end 316.727078 -396.608554)
		(width 0.14732)
		(layer "In2.Cu")
		(net "P5E_CPU0_PE4_TX_DP<4>")
	)
	(segment
		(start 341.179658 -286.963104)
		(end 341.176864 -286.964882)
		(width 0.0889)
		(layer "In2.Cu")
		(net "P5E_CPU0_PE4_TX_DP<4>")
	)
	(segment
		(start 307.05298 -333.807562)
		(end 307.05298 -343.224866)
		(width 0.14732)
		(layer "In2.Cu")
		(net "P5E_CPU0_PE4_TX_DP<4>")
	)
	(segment
		(start 340.519766 -288.103056)
		(end 340.519766 -288.121598)
		(width 0.0889)
		(layer "In2.Cu")
		(net "P5E_CPU0_PE4_TX_DP<4>")
	)
	(segment
		(start 309.236618 -325.23303)
		(end 308.589172 -325.880476)
		(width 0.14732)
		(layer "In2.Cu")
		(net "P5E_CPU0_PE4_TX_DP<4>")
	)
	(segment
		(start 341.18296 -286.961326)
		(end 341.180674 -286.962596)
		(width 0.0889)
		(layer "In2.Cu")
		(net "P5E_CPU0_PE4_TX_DP<4>")
	)
	(segment
		(start 340.049866 -288.917126)
		(end 340.049612 -288.91738)
		(width 0.0889)
		(layer "In2.Cu")
		(net "P5E_CPU0_PE4_TX_DP<4>")
	)
	(segment
		(start 311.366916 -361.131866)
		(end 316.5856 -396.503652)
		(width 0.14732)
		(layer "In2.Cu")
		(net "P5E_CPU0_PE4_TX_DP<4>")
	)
	(segment
		(start 341.677752 -286.204406)
		(end 341.59952 -286.183578)
		(width 0.0889)
		(layer "In2.Cu")
		(net "P5E_CPU0_PE4_TX_DP<4>")
	)
	(segment
		(start 340.707218 -287.778698)
		(end 340.698328 -287.783778)
		(width 0.0889)
		(layer "In2.Cu")
		(net "P5E_CPU0_PE4_TX_DP<4>")
	)
	(segment
		(start 340.173818 -289.211004)
		(end 340.174072 -289.211004)
		(width 0.0889)
		(layer "In2.Cu")
		(net "P5E_CPU0_PE4_TX_DP<4>")
	)
	(segment
		(start 313.798458 -324.446646)
		(end 312.680604 -324.909688)
		(width 0.14732)
		(layer "In2.Cu")
		(net "P5E_CPU0_PE4_TX_DP<4>")
	)
	(segment
		(start 340.197694 -290.92906)
		(end 340.197694 -290.951158)
		(width 0.0889)
		(layer "In2.Cu")
		(net "P5E_CPU0_PE4_TX_DP<4>")
	)
	(segment
		(start 316.727078 -396.608554)
		(end 316.790832 -397.041116)
		(width 0.14732)
		(layer "In2.Cu")
		(net "P5E_CPU0_PE4_TX_DP<4>")
	)
	(segment
		(start 316.68593 -397.18234)
		(end 316.802008 -397.970502)
		(width 0.14732)
		(layer "In2.Cu")
		(net "P5E_CPU0_PE4_TX_DP<4>")
	)
	(segment
		(start 308.589172 -325.880476)
		(end 308.285642 -326.613012)
		(width 0.14732)
		(layer "In2.Cu")
		(net "P5E_CPU0_PE4_TX_DP<4>")
	)
	(segment
		(start 341.834216 -286.475424)
		(end 341.677752 -286.204406)
		(width 0.0889)
		(layer "In2.Cu")
		(net "P5E_CPU0_PE4_TX_DP<4>")
	)
	(segment
		(start 340.15553 -290.75126)
		(end 340.15553 -290.886896)
		(width 0.0889)
		(layer "In2.Cu")
		(net "P5E_CPU0_PE4_TX_DP<4>")
	)
	(segment
		(start 340.049612 -288.91738)
		(end 340.049612 -289.078162)
		(width 0.0889)
		(layer "In2.Cu")
		(net "P5E_CPU0_PE4_TX_DP<4>")
	)
	(segment
		(start 316.802008 -400.563588)
		(end 317.096648 -400.858228)
		(width 0.14732)
		(layer "In2.Cu")
		(net "P5E_CPU0_PE4_TX_DP<4>")
	)
	(segment
		(start 307.342286 -344.866468)
		(end 311.366916 -361.131866)
		(width 0.14732)
		(layer "In2.Cu")
		(net "P5E_CPU0_PE4_TX_DP<4>")
	)
	(segment
		(start 316.926468 -398.968722)
		(end 316.802008 -399.093182)
		(width 0.14732)
		(layer "In2.Cu")
		(net "P5E_CPU0_PE4_TX_DP<4>")
	)
	(arc
		(start 340.049612 -289.078162)
		(mid 340.101081 -289.154528)
		(end 340.173818 -289.211004)
		(width 0.0889)
		(layer "In2.Cu")
		(net "P5E_CPU0_PE4_TX_DP<4>")
	)
	(arc
		(start 341.459566 -286.475424)
		(mid 341.385575 -286.75499)
		(end 341.18296 -286.961326)
		(width 0.0889)
		(layer "In2.Cu")
		(net "P5E_CPU0_PE4_TX_DP<4>")
	)
	(arc
		(start 340.228428 -288.597848)
		(mid 340.097514 -288.734208)
		(end 340.049866 -288.917126)
		(width 0.0889)
		(layer "In2.Cu")
		(net "P5E_CPU0_PE4_TX_DP<4>")
	)
	(arc
		(start 340.242144 -289.248596)
		(mid 340.445142 -289.445909)
		(end 340.519766 -289.719004)
		(width 0.0889)
		(layer "In2.Cu")
		(net "P5E_CPU0_PE4_TX_DP<4>")
	)
	(arc
		(start 340.698328 -287.783778)
		(mid 340.567414 -287.920138)
		(end 340.519766 -288.103056)
		(width 0.0889)
		(layer "In2.Cu")
		(net "P5E_CPU0_PE4_TX_DP<4>")
	)
	(arc
		(start 341.176864 -286.964882)
		(mid 341.041931 -287.098236)
		(end 340.989666 -287.280604)
		(width 0.0889)
		(layer "In2.Cu")
		(net "P5E_CPU0_PE4_TX_DP<4>")
	)
	(arc
		(start 340.519766 -288.121598)
		(mid 340.439604 -288.393787)
		(end 340.237318 -288.592768)
		(width 0.0889)
		(layer "In2.Cu")
		(net "P5E_CPU0_PE4_TX_DP<4>")
	)
	(arc
		(start 341.59952 -286.183578)
		(mid 341.496375 -286.313603)
		(end 341.459566 -286.475424)
		(width 0.0889)
		(layer "In2.Cu")
		(net "P5E_CPU0_PE4_TX_DP<4>")
	)
	(arc
		(start 340.989666 -287.299146)
		(mid 340.911555 -287.576095)
		(end 340.707218 -287.778698)
		(width 0.0889)
		(layer "In2.Cu")
		(net "P5E_CPU0_PE4_TX_DP<4>")
	)
	(segment
		(start 340.894162 -284.847284)
		(end 340.894416 -284.847538)
		(width 0.13208)
		(layer "F.Cu")
		(net "P5E_CPU0_PE4_TX_DP<3>")
	)
	(segment
		(start 340.894162 -284.311598)
		(end 340.894162 -284.847284)
		(width 0.13208)
		(layer "F.Cu")
		(net "P5E_CPU0_PE4_TX_DP<3>")
	)
	(segment
		(start 313.73445 -401.157186)
		(end 313.73445 -401.779994)
		(width 0.13208)
		(layer "F.Cu")
		(net "P5E_CPU0_PE4_TX_DP<3>")
	)
	(segment
		(start 313.73445 -401.779994)
		(end 314.058808 -402.104352)
		(width 0.13208)
		(layer "F.Cu")
		(net "P5E_CPU0_PE4_TX_DP<3>")
	)
	(segment
		(start 314.033408 -400.858228)
		(end 313.73445 -401.157186)
		(width 0.13208)
		(layer "F.Cu")
		(net "P5E_CPU0_PE4_TX_DP<3>")
	)
	(segment
		(start 340.049866 -287.28924)
		(end 340.049866 -287.299146)
		(width 0.0889)
		(layer "In2.Cu")
		(net "P5E_CPU0_PE4_TX_DP<3>")
	)
	(segment
		(start 340.737952 -285.118556)
		(end 340.762082 -285.20771)
		(width 0.0889)
		(layer "In2.Cu")
		(net "P5E_CPU0_PE4_TX_DP<3>")
	)
	(segment
		(start 313.738768 -397.265652)
		(end 313.738768 -400.563588)
		(width 0.14732)
		(layer "In2.Cu")
		(net "P5E_CPU0_PE4_TX_DP<3>")
	)
	(segment
		(start 340.894416 -284.847538)
		(end 340.737952 -285.118556)
		(width 0.0889)
		(layer "In2.Cu")
		(net "P5E_CPU0_PE4_TX_DP<3>")
	)
	(segment
		(start 339.224112 -290.50869)
		(end 339.224112 -290.922202)
		(width 0.0889)
		(layer "In2.Cu")
		(net "P5E_CPU0_PE4_TX_DP<3>")
	)
	(segment
		(start 339.579712 -289.630612)
		(end 339.579712 -290.31311)
		(width 0.0889)
		(layer "In2.Cu")
		(net "P5E_CPU0_PE4_TX_DP<3>")
	)
	(segment
		(start 307.782468 -325.357236)
		(end 307.333396 -326.441308)
		(width 0.14732)
		(layer "In2.Cu")
		(net "P5E_CPU0_PE4_TX_DP<3>")
	)
	(segment
		(start 339.579712 -290.31311)
		(end 339.224112 -290.50869)
		(width 0.0889)
		(layer "In2.Cu")
		(net "P5E_CPU0_PE4_TX_DP<3>")
	)
	(segment
		(start 310.94172 -323.967348)
		(end 309.814722 -323.967348)
		(width 0.14732)
		(layer "In2.Cu")
		(net "P5E_CPU0_PE4_TX_DP<3>")
	)
	(segment
		(start 306.117244 -333.677514)
		(end 306.117244 -343.306908)
		(width 0.14732)
		(layer "In2.Cu")
		(net "P5E_CPU0_PE4_TX_DP<3>")
	)
	(segment
		(start 340.707218 -286.151066)
		(end 340.698328 -286.156146)
		(width 0.0889)
		(layer "In2.Cu")
		(net "P5E_CPU0_PE4_TX_DP<3>")
	)
	(segment
		(start 339.266276 -290.986464)
		(end 339.266276 -291.57549)
		(width 0.14732)
		(layer "In2.Cu")
		(net "P5E_CPU0_PE4_TX_DP<3>")
	)
	(segment
		(start 309.814722 -323.967348)
		(end 308.718204 -324.4215)
		(width 0.14732)
		(layer "In2.Cu")
		(net "P5E_CPU0_PE4_TX_DP<3>")
	)
	(segment
		(start 339.400896 -289.33394)
		(end 339.579712 -289.630612)
		(width 0.0889)
		(layer "In2.Cu")
		(net "P5E_CPU0_PE4_TX_DP<3>")
	)
	(segment
		(start 335.601818 -295.240202)
		(end 329.003406 -307.915056)
		(width 0.14732)
		(layer "In2.Cu")
		(net "P5E_CPU0_PE4_TX_DP<3>")
	)
	(segment
		(start 339.767418 -287.778698)
		(end 339.765132 -287.780222)
		(width 0.0889)
		(layer "In2.Cu")
		(net "P5E_CPU0_PE4_TX_DP<3>")
	)
	(segment
		(start 307.333396 -327.562972)
		(end 306.117244 -333.677514)
		(width 0.14732)
		(layer "In2.Cu")
		(net "P5E_CPU0_PE4_TX_DP<3>")
	)
	(segment
		(start 339.765132 -287.780222)
		(end 339.764116 -287.78073)
		(width 0.0889)
		(layer "In2.Cu")
		(net "P5E_CPU0_PE4_TX_DP<3>")
	)
	(segment
		(start 339.266276 -290.964366)
		(end 339.266276 -290.986464)
		(width 0.0889)
		(layer "In2.Cu")
		(net "P5E_CPU0_PE4_TX_DP<3>")
	)
	(segment
		(start 313.738768 -400.563588)
		(end 314.033408 -400.858228)
		(width 0.14732)
		(layer "In2.Cu")
		(net "P5E_CPU0_PE4_TX_DP<3>")
	)
	(segment
		(start 340.237318 -286.964882)
		(end 340.228428 -286.969962)
		(width 0.0889)
		(layer "In2.Cu")
		(net "P5E_CPU0_PE4_TX_DP<3>")
	)
	(segment
		(start 340.519766 -286.475424)
		(end 340.519766 -286.48533)
		(width 0.0889)
		(layer "In2.Cu")
		(net "P5E_CPU0_PE4_TX_DP<3>")
	)
	(segment
		(start 339.764116 -287.78073)
		(end 339.758528 -287.783778)
		(width 0.0889)
		(layer "In2.Cu")
		(net "P5E_CPU0_PE4_TX_DP<3>")
	)
	(segment
		(start 339.266276 -291.57549)
		(end 335.601818 -295.240202)
		(width 0.14732)
		(layer "In2.Cu")
		(net "P5E_CPU0_PE4_TX_DP<3>")
	)
	(segment
		(start 339.579966 -288.103056)
		(end 339.579966 -288.11728)
		(width 0.0889)
		(layer "In2.Cu")
		(net "P5E_CPU0_PE4_TX_DP<3>")
	)
	(segment
		(start 308.718204 -324.4215)
		(end 307.782468 -325.357236)
		(width 0.14732)
		(layer "In2.Cu")
		(net "P5E_CPU0_PE4_TX_DP<3>")
	)
	(segment
		(start 306.444396 -345.16314)
		(end 309.912258 -361.279948)
		(width 0.14732)
		(layer "In2.Cu")
		(net "P5E_CPU0_PE4_TX_DP<3>")
	)
	(segment
		(start 340.988396 -285.607252)
		(end 340.989412 -285.683452)
		(width 0.0889)
		(layer "In2.Cu")
		(net "P5E_CPU0_PE4_TX_DP<3>")
	)
	(segment
		(start 329.003406 -307.915056)
		(end 314.370466 -322.547234)
		(width 0.14732)
		(layer "In2.Cu")
		(net "P5E_CPU0_PE4_TX_DP<3>")
	)
	(segment
		(start 306.117244 -343.306908)
		(end 306.444396 -345.16314)
		(width 0.14732)
		(layer "In2.Cu")
		(net "P5E_CPU0_PE4_TX_DP<3>")
	)
	(segment
		(start 314.370466 -322.547234)
		(end 310.94172 -323.967348)
		(width 0.14732)
		(layer "In2.Cu")
		(net "P5E_CPU0_PE4_TX_DP<3>")
	)
	(segment
		(start 339.294216 -289.277806)
		(end 339.400896 -289.33394)
		(width 0.0889)
		(layer "In2.Cu")
		(net "P5E_CPU0_PE4_TX_DP<3>")
	)
	(segment
		(start 309.912258 -361.279948)
		(end 313.738768 -397.265652)
		(width 0.14732)
		(layer "In2.Cu")
		(net "P5E_CPU0_PE4_TX_DP<3>")
	)
	(segment
		(start 339.110066 -288.917126)
		(end 339.110066 -289.078416)
		(width 0.0889)
		(layer "In2.Cu")
		(net "P5E_CPU0_PE4_TX_DP<3>")
	)
	(segment
		(start 340.778846 -285.220664)
		(end 340.808818 -285.244794)
		(width 0.0889)
		(layer "In2.Cu")
		(net "P5E_CPU0_PE4_TX_DP<3>")
	)
	(segment
		(start 339.297518 -288.592768)
		(end 339.288628 -288.597848)
		(width 0.0889)
		(layer "In2.Cu")
		(net "P5E_CPU0_PE4_TX_DP<3>")
	)
	(segment
		(start 339.224112 -290.922202)
		(end 339.266276 -290.964366)
		(width 0.0889)
		(layer "In2.Cu")
		(net "P5E_CPU0_PE4_TX_DP<3>")
	)
	(segment
		(start 307.333396 -326.441308)
		(end 307.333396 -327.562972)
		(width 0.14732)
		(layer "In2.Cu")
		(net "P5E_CPU0_PE4_TX_DP<3>")
	)
	(arc
		(start 339.579966 -288.11728)
		(mid 339.500825 -288.391903)
		(end 339.297518 -288.592768)
		(width 0.0889)
		(layer "In2.Cu")
		(net "P5E_CPU0_PE4_TX_DP<3>")
	)
	(arc
		(start 340.698328 -286.156146)
		(mid 340.571074 -286.286112)
		(end 340.52002 -286.460692)
		(width 0.0889)
		(layer "In2.Cu")
		(net "P5E_CPU0_PE4_TX_DP<3>")
	)
	(arc
		(start 340.762082 -285.20771)
		(mid 340.770523 -285.21411)
		(end 340.778846 -285.220664)
		(width 0.0889)
		(layer "In2.Cu")
		(net "P5E_CPU0_PE4_TX_DP<3>")
	)
	(arc
		(start 340.808818 -285.244794)
		(mid 340.938449 -285.406278)
		(end 340.988396 -285.607252)
		(width 0.0889)
		(layer "In2.Cu")
		(net "P5E_CPU0_PE4_TX_DP<3>")
	)
	(arc
		(start 340.049866 -287.299146)
		(mid 339.971755 -287.576095)
		(end 339.767418 -287.778698)
		(width 0.0889)
		(layer "In2.Cu")
		(net "P5E_CPU0_PE4_TX_DP<3>")
	)
	(arc
		(start 340.989412 -285.683452)
		(mid 340.908501 -285.95358)
		(end 340.707218 -286.151066)
		(width 0.0889)
		(layer "In2.Cu")
		(net "P5E_CPU0_PE4_TX_DP<3>")
	)
	(arc
		(start 339.110066 -289.078416)
		(mid 339.185071 -289.193875)
		(end 339.294216 -289.277806)
		(width 0.0889)
		(layer "In2.Cu")
		(net "P5E_CPU0_PE4_TX_DP<3>")
	)
	(arc
		(start 339.758528 -287.783778)
		(mid 339.627614 -287.920138)
		(end 339.579966 -288.103056)
		(width 0.0889)
		(layer "In2.Cu")
		(net "P5E_CPU0_PE4_TX_DP<3>")
	)
	(arc
		(start 340.52002 -286.460692)
		(mid 340.519823 -286.468057)
		(end 340.519766 -286.475424)
		(width 0.0889)
		(layer "In2.Cu")
		(net "P5E_CPU0_PE4_TX_DP<3>")
	)
	(arc
		(start 340.519766 -286.48533)
		(mid 340.441655 -286.762279)
		(end 340.237318 -286.964882)
		(width 0.0889)
		(layer "In2.Cu")
		(net "P5E_CPU0_PE4_TX_DP<3>")
	)
	(arc
		(start 340.228428 -286.969962)
		(mid 340.097514 -287.106322)
		(end 340.049866 -287.28924)
		(width 0.0889)
		(layer "In2.Cu")
		(net "P5E_CPU0_PE4_TX_DP<3>")
	)
	(arc
		(start 339.288628 -288.597848)
		(mid 339.161374 -288.727814)
		(end 339.11032 -288.902394)
		(width 0.0889)
		(layer "In2.Cu")
		(net "P5E_CPU0_PE4_TX_DP<3>")
	)
	(arc
		(start 339.11032 -288.902394)
		(mid 339.110123 -288.909759)
		(end 339.110066 -288.917126)
		(width 0.0889)
		(layer "In2.Cu")
		(net "P5E_CPU0_PE4_TX_DP<3>")
	)
	(segment
		(start 339.954362 -285.939484)
		(end 339.954362 -286.47517)
		(width 0.13208)
		(layer "F.Cu")
		(net "P5E_CPU0_PE4_TX_DP<2>")
	)
	(segment
		(start 310.970168 -400.858228)
		(end 310.67121 -401.157186)
		(width 0.13208)
		(layer "F.Cu")
		(net "P5E_CPU0_PE4_TX_DP<2>")
	)
	(segment
		(start 339.954362 -286.47517)
		(end 339.954616 -286.475424)
		(width 0.13208)
		(layer "F.Cu")
		(net "P5E_CPU0_PE4_TX_DP<2>")
	)
	(segment
		(start 310.67121 -401.157186)
		(end 310.67121 -401.779994)
		(width 0.13208)
		(layer "F.Cu")
		(net "P5E_CPU0_PE4_TX_DP<2>")
	)
	(segment
		(start 310.67121 -401.779994)
		(end 310.995568 -402.104352)
		(width 0.13208)
		(layer "F.Cu")
		(net "P5E_CPU0_PE4_TX_DP<2>")
	)
	(segment
		(start 338.170012 -290.546536)
		(end 338.212176 -290.5887)
		(width 0.0889)
		(layer "In2.Cu")
		(net "P5E_CPU0_PE4_TX_DP<2>")
	)
	(segment
		(start 310.799988 -396.672308)
		(end 310.799988 -397.109188)
		(width 0.14732)
		(layer "In2.Cu")
		(net "P5E_CPU0_PE4_TX_DP<2>")
	)
	(segment
		(start 338.357718 -288.592768)
		(end 338.342732 -288.601404)
		(width 0.0889)
		(layer "In2.Cu")
		(net "P5E_CPU0_PE4_TX_DP<2>")
	)
	(segment
		(start 338.212176 -290.5887)
		(end 338.212176 -290.610798)
		(width 0.0889)
		(layer "In2.Cu")
		(net "P5E_CPU0_PE4_TX_DP<2>")
	)
	(segment
		(start 306.94122 -324.868286)
		(end 306.385468 -326.209914)
		(width 0.14732)
		(layer "In2.Cu")
		(net "P5E_CPU0_PE4_TX_DP<2>")
	)
	(segment
		(start 308.45887 -361.409488)
		(end 310.675528 -395.353794)
		(width 0.14732)
		(layer "In2.Cu")
		(net "P5E_CPU0_PE4_TX_DP<2>")
	)
	(segment
		(start 305.164998 -343.388442)
		(end 308.45887 -361.409488)
		(width 0.14732)
		(layer "In2.Cu")
		(net "P5E_CPU0_PE4_TX_DP<2>")
	)
	(segment
		(start 338.212176 -291.208714)
		(end 334.739996 -294.680894)
		(width 0.14732)
		(layer "In2.Cu")
		(net "P5E_CPU0_PE4_TX_DP<2>")
	)
	(segment
		(start 339.798152 -286.204406)
		(end 339.71992 -286.183578)
		(width 0.0889)
		(layer "In2.Cu")
		(net "P5E_CPU0_PE4_TX_DP<2>")
	)
	(segment
		(start 334.739996 -294.680894)
		(end 328.048112 -307.536596)
		(width 0.14732)
		(layer "In2.Cu")
		(net "P5E_CPU0_PE4_TX_DP<2>")
	)
	(segment
		(start 339.303614 -286.961326)
		(end 339.297518 -286.964882)
		(width 0.0889)
		(layer "In2.Cu")
		(net "P5E_CPU0_PE4_TX_DP<2>")
	)
	(segment
		(start 314.049918 -321.534536)
		(end 311.603644 -322.547488)
		(width 0.14732)
		(layer "In2.Cu")
		(net "P5E_CPU0_PE4_TX_DP<2>")
	)
	(segment
		(start 310.675528 -396.547848)
		(end 310.799988 -396.672308)
		(width 0.14732)
		(layer "In2.Cu")
		(net "P5E_CPU0_PE4_TX_DP<2>")
	)
	(segment
		(start 328.048112 -307.536596)
		(end 314.049918 -321.534536)
		(width 0.14732)
		(layer "In2.Cu")
		(net "P5E_CPU0_PE4_TX_DP<2>")
	)
	(segment
		(start 305.164998 -333.550006)
		(end 305.164998 -343.388442)
		(width 0.14732)
		(layer "In2.Cu")
		(net "P5E_CPU0_PE4_TX_DP<2>")
	)
	(segment
		(start 306.385468 -326.209914)
		(end 306.385468 -327.415144)
		(width 0.14732)
		(layer "In2.Cu")
		(net "P5E_CPU0_PE4_TX_DP<2>")
	)
	(segment
		(start 306.385468 -327.415144)
		(end 305.164998 -333.550006)
		(width 0.14732)
		(layer "In2.Cu")
		(net "P5E_CPU0_PE4_TX_DP<2>")
	)
	(segment
		(start 339.297518 -286.964882)
		(end 339.288628 -286.969962)
		(width 0.0889)
		(layer "In2.Cu")
		(net "P5E_CPU0_PE4_TX_DP<2>")
	)
	(segment
		(start 338.83346 -287.775142)
		(end 338.827364 -287.778698)
		(width 0.0889)
		(layer "In2.Cu")
		(net "P5E_CPU0_PE4_TX_DP<2>")
	)
	(segment
		(start 338.639912 -288.103056)
		(end 338.639912 -288.125154)
		(width 0.0889)
		(layer "In2.Cu")
		(net "P5E_CPU0_PE4_TX_DP<2>")
	)
	(segment
		(start 310.799988 -397.109188)
		(end 310.675528 -397.233648)
		(width 0.14732)
		(layer "In2.Cu")
		(net "P5E_CPU0_PE4_TX_DP<2>")
	)
	(segment
		(start 338.827364 -287.778698)
		(end 338.818474 -287.783778)
		(width 0.0889)
		(layer "In2.Cu")
		(net "P5E_CPU0_PE4_TX_DP<2>")
	)
	(segment
		(start 310.675528 -395.353794)
		(end 310.675528 -396.547848)
		(width 0.14732)
		(layer "In2.Cu")
		(net "P5E_CPU0_PE4_TX_DP<2>")
	)
	(segment
		(start 338.212176 -290.610798)
		(end 338.212176 -291.208714)
		(width 0.14732)
		(layer "In2.Cu")
		(net "P5E_CPU0_PE4_TX_DP<2>")
	)
	(segment
		(start 311.603644 -322.547488)
		(end 310.905906 -322.547488)
		(width 0.14732)
		(layer "In2.Cu")
		(net "P5E_CPU0_PE4_TX_DP<2>")
	)
	(segment
		(start 310.423306 -322.064888)
		(end 309.828438 -322.064888)
		(width 0.14732)
		(layer "In2.Cu")
		(net "P5E_CPU0_PE4_TX_DP<2>")
	)
	(segment
		(start 310.799988 -398.231868)
		(end 310.675528 -398.356328)
		(width 0.14732)
		(layer "In2.Cu")
		(net "P5E_CPU0_PE4_TX_DP<2>")
	)
	(segment
		(start 310.675528 -397.670528)
		(end 310.799988 -397.794988)
		(width 0.14732)
		(layer "In2.Cu")
		(net "P5E_CPU0_PE4_TX_DP<2>")
	)
	(segment
		(start 310.905906 -322.547488)
		(end 310.423306 -322.064888)
		(width 0.14732)
		(layer "In2.Cu")
		(net "P5E_CPU0_PE4_TX_DP<2>")
	)
	(segment
		(start 309.685182 -322.124324)
		(end 306.94122 -324.868286)
		(width 0.14732)
		(layer "In2.Cu")
		(net "P5E_CPU0_PE4_TX_DP<2>")
	)
	(segment
		(start 309.828438 -322.064888)
		(end 309.685182 -322.124324)
		(width 0.14732)
		(layer "In2.Cu")
		(net "P5E_CPU0_PE4_TX_DP<2>")
	)
	(segment
		(start 310.675528 -397.233648)
		(end 310.675528 -397.670528)
		(width 0.14732)
		(layer "In2.Cu")
		(net "P5E_CPU0_PE4_TX_DP<2>")
	)
	(segment
		(start 310.675528 -400.563588)
		(end 310.970168 -400.858228)
		(width 0.14732)
		(layer "In2.Cu")
		(net "P5E_CPU0_PE4_TX_DP<2>")
	)
	(segment
		(start 310.799988 -397.794988)
		(end 310.799988 -398.231868)
		(width 0.14732)
		(layer "In2.Cu")
		(net "P5E_CPU0_PE4_TX_DP<2>")
	)
	(segment
		(start 338.170012 -288.917126)
		(end 338.170012 -290.546536)
		(width 0.0889)
		(layer "In2.Cu")
		(net "P5E_CPU0_PE4_TX_DP<2>")
	)
	(segment
		(start 339.954616 -286.475424)
		(end 339.798152 -286.204406)
		(width 0.0889)
		(layer "In2.Cu")
		(net "P5E_CPU0_PE4_TX_DP<2>")
	)
	(segment
		(start 310.675528 -398.356328)
		(end 310.675528 -400.563588)
		(width 0.14732)
		(layer "In2.Cu")
		(net "P5E_CPU0_PE4_TX_DP<2>")
	)
	(arc
		(start 338.342732 -288.601404)
		(mid 338.216009 -288.737185)
		(end 338.170012 -288.917126)
		(width 0.0889)
		(layer "In2.Cu")
		(net "P5E_CPU0_PE4_TX_DP<2>")
	)
	(arc
		(start 339.71992 -286.183578)
		(mid 339.616775 -286.313603)
		(end 339.579966 -286.475424)
		(width 0.0889)
		(layer "In2.Cu")
		(net "P5E_CPU0_PE4_TX_DP<2>")
	)
	(arc
		(start 339.579966 -286.475424)
		(mid 339.50605 -286.754926)
		(end 339.303614 -286.961326)
		(width 0.0889)
		(layer "In2.Cu")
		(net "P5E_CPU0_PE4_TX_DP<2>")
	)
	(arc
		(start 339.110066 -287.28924)
		(mid 339.036075 -287.568806)
		(end 338.83346 -287.775142)
		(width 0.0889)
		(layer "In2.Cu")
		(net "P5E_CPU0_PE4_TX_DP<2>")
	)
	(arc
		(start 339.288628 -286.969962)
		(mid 339.157714 -287.106322)
		(end 339.110066 -287.28924)
		(width 0.0889)
		(layer "In2.Cu")
		(net "P5E_CPU0_PE4_TX_DP<2>")
	)
	(arc
		(start 338.639912 -288.125154)
		(mid 338.559001 -288.395282)
		(end 338.357718 -288.592768)
		(width 0.0889)
		(layer "In2.Cu")
		(net "P5E_CPU0_PE4_TX_DP<2>")
	)
	(arc
		(start 338.818474 -287.783778)
		(mid 338.68756 -287.920138)
		(end 338.639912 -288.103056)
		(width 0.0889)
		(layer "In2.Cu")
		(net "P5E_CPU0_PE4_TX_DP<2>")
	)
	(segment
		(start 338.544916 -285.125414)
		(end 338.544916 -285.661354)
		(width 0.13208)
		(layer "F.Cu")
		(net "P5E_CPU0_PE4_TX_DP<1>")
	)
	(segment
		(start 307.34889 -401.777962)
		(end 307.0225 -402.104352)
		(width 0.13208)
		(layer "F.Cu")
		(net "P5E_CPU0_PE4_TX_DP<1>")
	)
	(segment
		(start 307.34889 -401.16379)
		(end 307.34889 -401.777962)
		(width 0.13208)
		(layer "F.Cu")
		(net "P5E_CPU0_PE4_TX_DP<1>")
	)
	(segment
		(start 307.0225 -402.104352)
		(end 307.017928 -402.104352)
		(width 0.13208)
		(layer "F.Cu")
		(net "P5E_CPU0_PE4_TX_DP<1>")
	)
	(segment
		(start 307.043328 -400.858228)
		(end 307.34889 -401.16379)
		(width 0.13208)
		(layer "F.Cu")
		(net "P5E_CPU0_PE4_TX_DP<1>")
	)
	(segment
		(start 337.509612 -288.09315)
		(end 337.509612 -288.103056)
		(width 0.0889)
		(layer "In2.Cu")
		(net "P5E_CPU0_PE4_TX_DP<1>")
	)
	(segment
		(start 333.520288 -294.165528)
		(end 326.810878 -307.051964)
		(width 0.14732)
		(layer "In2.Cu")
		(net "P5E_CPU0_PE4_TX_DP<1>")
	)
	(segment
		(start 307.337968 -400.563588)
		(end 307.043328 -400.858228)
		(width 0.14732)
		(layer "In2.Cu")
		(net "P5E_CPU0_PE4_TX_DP<1>")
	)
	(segment
		(start 305.167284 -325.909686)
		(end 305.167284 -327.331324)
		(width 0.14732)
		(layer "In2.Cu")
		(net "P5E_CPU0_PE4_TX_DP<1>")
	)
	(segment
		(start 307.171598 -396.785592)
		(end 307.179218 -397.222726)
		(width 0.14732)
		(layer "In2.Cu")
		(net "P5E_CPU0_PE4_TX_DP<1>")
	)
	(segment
		(start 338.70138 -285.390336)
		(end 338.779612 -285.369508)
		(width 0.0889)
		(layer "In2.Cu")
		(net "P5E_CPU0_PE4_TX_DP<1>")
	)
	(segment
		(start 326.810878 -307.051964)
		(end 314.689236 -319.17386)
		(width 0.14732)
		(layer "In2.Cu")
		(net "P5E_CPU0_PE4_TX_DP<1>")
	)
	(segment
		(start 303.94275 -343.592658)
		(end 304.296064 -345.596718)
		(width 0.14732)
		(layer "In2.Cu")
		(net "P5E_CPU0_PE4_TX_DP<1>")
	)
	(segment
		(start 307.325268 -398.467834)
		(end 307.337968 -399.2118)
		(width 0.14732)
		(layer "In2.Cu")
		(net "P5E_CPU0_PE4_TX_DP<1>")
	)
	(segment
		(start 336.997548 -289.844988)
		(end 336.997548 -289.867086)
		(width 0.0889)
		(layer "In2.Cu")
		(net "P5E_CPU0_PE4_TX_DP<1>")
	)
	(segment
		(start 306.691284 -361.478068)
		(end 307.294026 -396.6591)
		(width 0.14732)
		(layer "In2.Cu")
		(net "P5E_CPU0_PE4_TX_DP<1>")
	)
	(segment
		(start 337.039458 -289.803078)
		(end 336.997548 -289.844988)
		(width 0.0889)
		(layer "In2.Cu")
		(net "P5E_CPU0_PE4_TX_DP<1>")
	)
	(segment
		(start 305.859434 -324.238366)
		(end 305.167284 -325.909686)
		(width 0.14732)
		(layer "In2.Cu")
		(net "P5E_CPU0_PE4_TX_DP<1>")
	)
	(segment
		(start 337.80095 -287.608518)
		(end 337.792822 -287.61309)
		(width 0.0889)
		(layer "In2.Cu")
		(net "P5E_CPU0_PE4_TX_DP<1>")
	)
	(segment
		(start 307.305964 -397.345154)
		(end 307.31333 -397.78178)
		(width 0.14732)
		(layer "In2.Cu")
		(net "P5E_CPU0_PE4_TX_DP<1>")
	)
	(segment
		(start 313.82716 -319.707006)
		(end 311.069228 -320.628264)
		(width 0.14732)
		(layer "In2.Cu")
		(net "P5E_CPU0_PE4_TX_DP<1>")
	)
	(segment
		(start 336.997548 -289.867086)
		(end 336.997548 -290.688268)
		(width 0.14732)
		(layer "In2.Cu")
		(net "P5E_CPU0_PE4_TX_DP<1>")
	)
	(segment
		(start 307.179218 -397.222726)
		(end 307.305964 -397.345154)
		(width 0.14732)
		(layer "In2.Cu")
		(net "P5E_CPU0_PE4_TX_DP<1>")
	)
	(segment
		(start 304.296064 -345.596718)
		(end 306.691284 -361.478068)
		(width 0.14732)
		(layer "In2.Cu")
		(net "P5E_CPU0_PE4_TX_DP<1>")
	)
	(segment
		(start 307.31333 -397.78178)
		(end 307.190902 -397.908526)
		(width 0.14732)
		(layer "In2.Cu")
		(net "P5E_CPU0_PE4_TX_DP<1>")
	)
	(segment
		(start 338.449412 -286.4612)
		(end 338.449412 -286.475424)
		(width 0.0889)
		(layer "In2.Cu")
		(net "P5E_CPU0_PE4_TX_DP<1>")
	)
	(segment
		(start 337.792822 -287.61309)
		(end 337.79206 -287.613598)
		(width 0.0889)
		(layer "In2.Cu")
		(net "P5E_CPU0_PE4_TX_DP<1>")
	)
	(segment
		(start 337.33105 -288.422334)
		(end 337.32216 -288.427414)
		(width 0.0889)
		(layer "In2.Cu")
		(net "P5E_CPU0_PE4_TX_DP<1>")
	)
	(segment
		(start 307.337968 -399.2118)
		(end 307.337968 -400.563588)
		(width 0.14732)
		(layer "In2.Cu")
		(net "P5E_CPU0_PE4_TX_DP<1>")
	)
	(segment
		(start 307.198522 -398.345406)
		(end 307.325268 -398.467834)
		(width 0.14732)
		(layer "In2.Cu")
		(net "P5E_CPU0_PE4_TX_DP<1>")
	)
	(segment
		(start 305.167284 -327.331324)
		(end 303.94275 -333.48803)
		(width 0.14732)
		(layer "In2.Cu")
		(net "P5E_CPU0_PE4_TX_DP<1>")
	)
	(segment
		(start 338.741004 -285.980632)
		(end 338.732114 -285.985712)
		(width 0.0889)
		(layer "In2.Cu")
		(net "P5E_CPU0_PE4_TX_DP<1>")
	)
	(segment
		(start 337.039458 -288.902902)
		(end 337.039458 -289.803078)
		(width 0.0889)
		(layer "In2.Cu")
		(net "P5E_CPU0_PE4_TX_DP<1>")
	)
	(segment
		(start 336.997548 -290.688268)
		(end 333.520288 -294.165528)
		(width 0.14732)
		(layer "In2.Cu")
		(net "P5E_CPU0_PE4_TX_DP<1>")
	)
	(segment
		(start 338.544916 -285.661354)
		(end 338.70138 -285.390336)
		(width 0.0889)
		(layer "In2.Cu")
		(net "P5E_CPU0_PE4_TX_DP<1>")
	)
	(segment
		(start 338.257134 -286.802576)
		(end 338.255864 -286.803338)
		(width 0.0889)
		(layer "In2.Cu")
		(net "P5E_CPU0_PE4_TX_DP<1>")
	)
	(segment
		(start 307.190902 -397.908526)
		(end 307.198522 -398.345406)
		(width 0.14732)
		(layer "In2.Cu")
		(net "P5E_CPU0_PE4_TX_DP<1>")
	)
	(segment
		(start 310.140096 -320.628264)
		(end 308.995572 -321.102228)
		(width 0.14732)
		(layer "In2.Cu")
		(net "P5E_CPU0_PE4_TX_DP<1>")
	)
	(segment
		(start 307.294026 -396.6591)
		(end 307.171598 -396.785592)
		(width 0.14732)
		(layer "In2.Cu")
		(net "P5E_CPU0_PE4_TX_DP<1>")
	)
	(segment
		(start 303.94275 -333.48803)
		(end 303.94275 -343.592658)
		(width 0.14732)
		(layer "In2.Cu")
		(net "P5E_CPU0_PE4_TX_DP<1>")
	)
	(segment
		(start 308.995572 -321.102228)
		(end 305.859434 -324.238366)
		(width 0.14732)
		(layer "In2.Cu")
		(net "P5E_CPU0_PE4_TX_DP<1>")
	)
	(segment
		(start 338.27085 -286.794702)
		(end 338.257134 -286.802576)
		(width 0.0889)
		(layer "In2.Cu")
		(net "P5E_CPU0_PE4_TX_DP<1>")
	)
	(segment
		(start 314.689236 -319.17386)
		(end 313.82716 -319.707006)
		(width 0.14732)
		(layer "In2.Cu")
		(net "P5E_CPU0_PE4_TX_DP<1>")
	)
	(segment
		(start 311.069228 -320.628264)
		(end 310.140096 -320.628264)
		(width 0.14732)
		(layer "In2.Cu")
		(net "P5E_CPU0_PE4_TX_DP<1>")
	)
	(arc
		(start 338.255864 -286.803338)
		(mid 338.053451 -287.009751)
		(end 337.979512 -287.28924)
		(width 0.0889)
		(layer "In2.Cu")
		(net "P5E_CPU0_PE4_TX_DP<1>")
	)
	(arc
		(start 337.979512 -287.28924)
		(mid 337.931833 -287.47214)
		(end 337.80095 -287.608518)
		(width 0.0889)
		(layer "In2.Cu")
		(net "P5E_CPU0_PE4_TX_DP<1>")
	)
	(arc
		(start 338.779612 -285.369508)
		(mid 338.918675 -285.685029)
		(end 338.741004 -285.980632)
		(width 0.0889)
		(layer "In2.Cu")
		(net "P5E_CPU0_PE4_TX_DP<1>")
	)
	(arc
		(start 338.449412 -286.475424)
		(mid 338.401733 -286.658324)
		(end 338.27085 -286.794702)
		(width 0.0889)
		(layer "In2.Cu")
		(net "P5E_CPU0_PE4_TX_DP<1>")
	)
	(arc
		(start 337.509612 -288.103056)
		(mid 337.461933 -288.285956)
		(end 337.33105 -288.422334)
		(width 0.0889)
		(layer "In2.Cu")
		(net "P5E_CPU0_PE4_TX_DP<1>")
	)
	(arc
		(start 337.79206 -287.613598)
		(mid 337.587725 -287.816203)
		(end 337.509612 -288.09315)
		(width 0.0889)
		(layer "In2.Cu")
		(net "P5E_CPU0_PE4_TX_DP<1>")
	)
	(arc
		(start 337.32216 -288.427414)
		(mid 337.118679 -288.628218)
		(end 337.039458 -288.902902)
		(width 0.0889)
		(layer "In2.Cu")
		(net "P5E_CPU0_PE4_TX_DP<1>")
	)
	(arc
		(start 338.732114 -285.985712)
		(mid 338.528633 -286.186516)
		(end 338.449412 -286.4612)
		(width 0.0889)
		(layer "In2.Cu")
		(net "P5E_CPU0_PE4_TX_DP<1>")
	)
	(segment
		(start 350.792288 -400.858228)
		(end 350.49333 -401.157186)
		(width 0.13208)
		(layer "F.Cu")
		(net "P5E_CPU0_PE4_TX_DP<15>")
	)
	(segment
		(start 352.171762 -284.311598)
		(end 352.171762 -284.847284)
		(width 0.13208)
		(layer "F.Cu")
		(net "P5E_CPU0_PE4_TX_DP<15>")
	)
	(segment
		(start 350.49333 -401.779994)
		(end 350.817688 -402.104352)
		(width 0.13208)
		(layer "F.Cu")
		(net "P5E_CPU0_PE4_TX_DP<15>")
	)
	(segment
		(start 350.49333 -401.157186)
		(end 350.49333 -401.779994)
		(width 0.13208)
		(layer "F.Cu")
		(net "P5E_CPU0_PE4_TX_DP<15>")
	)
	(segment
		(start 352.171762 -284.847284)
		(end 352.172016 -284.847538)
		(width 0.13208)
		(layer "F.Cu")
		(net "P5E_CPU0_PE4_TX_DP<15>")
	)
	(segment
		(start 352.039682 -285.20771)
		(end 352.015552 -285.118556)
		(width 0.0889)
		(layer "In2.Cu")
		(net "P5E_CPU0_PE4_TX_DP<15>")
	)
	(segment
		(start 351.056956 -290.568888)
		(end 351.056956 -290.33597)
		(width 0.0889)
		(layer "In2.Cu")
		(net "P5E_CPU0_PE4_TX_DP<15>")
	)
	(segment
		(start 317.466218 -335.956656)
		(end 317.881508 -334.953864)
		(width 0.14732)
		(layer "In2.Cu")
		(net "P5E_CPU0_PE4_TX_DP<15>")
	)
	(segment
		(start 350.566228 -288.597848)
		(end 350.575118 -288.592768)
		(width 0.0889)
		(layer "In2.Cu")
		(net "P5E_CPU0_PE4_TX_DP<15>")
	)
	(segment
		(start 351.036128 -287.783778)
		(end 351.045018 -287.778698)
		(width 0.0889)
		(layer "In2.Cu")
		(net "P5E_CPU0_PE4_TX_DP<15>")
	)
	(segment
		(start 350.460818 -399.609056)
		(end 317.583312 -342.93302)
		(width 0.14732)
		(layer "In2.Cu")
		(net "P5E_CPU0_PE4_TX_DP<15>")
	)
	(segment
		(start 317.466218 -342.268556)
		(end 317.466218 -335.956656)
		(width 0.14732)
		(layer "In2.Cu")
		(net "P5E_CPU0_PE4_TX_DP<15>")
	)
	(segment
		(start 351.09912 -290.63315)
		(end 351.09912 -290.611052)
		(width 0.0889)
		(layer "In2.Cu")
		(net "P5E_CPU0_PE4_TX_DP<15>")
	)
	(segment
		(start 351.327212 -287.304734)
		(end 351.327212 -287.28924)
		(width 0.0889)
		(layer "In2.Cu")
		(net "P5E_CPU0_PE4_TX_DP<15>")
	)
	(segment
		(start 338.520278 -314.935362)
		(end 348.834456 -304.621184)
		(width 0.14732)
		(layer "In2.Cu")
		(net "P5E_CPU0_PE4_TX_DP<15>")
	)
	(segment
		(start 351.505774 -286.969962)
		(end 351.508568 -286.968438)
		(width 0.0889)
		(layer "In2.Cu")
		(net "P5E_CPU0_PE4_TX_DP<15>")
	)
	(segment
		(start 350.857058 -290.136072)
		(end 350.857058 -289.65906)
		(width 0.0889)
		(layer "In2.Cu")
		(net "P5E_CPU0_PE4_TX_DP<15>")
	)
	(segment
		(start 317.881508 -334.953864)
		(end 336.6516 -316.184026)
		(width 0.14732)
		(layer "In2.Cu")
		(net "P5E_CPU0_PE4_TX_DP<15>")
	)
	(segment
		(start 351.09912 -290.611052)
		(end 351.056956 -290.568888)
		(width 0.0889)
		(layer "In2.Cu")
		(net "P5E_CPU0_PE4_TX_DP<15>")
	)
	(segment
		(start 317.583312 -342.93302)
		(end 317.466218 -342.268556)
		(width 0.14732)
		(layer "In2.Cu")
		(net "P5E_CPU0_PE4_TX_DP<15>")
	)
	(segment
		(start 352.015552 -285.118556)
		(end 352.172016 -284.847538)
		(width 0.0889)
		(layer "In2.Cu")
		(net "P5E_CPU0_PE4_TX_DP<15>")
	)
	(segment
		(start 351.056956 -290.33597)
		(end 350.857058 -290.136072)
		(width 0.0889)
		(layer "In2.Cu")
		(net "P5E_CPU0_PE4_TX_DP<15>")
	)
	(segment
		(start 350.497648 -399.645886)
		(end 350.460818 -399.609056)
		(width 0.14732)
		(layer "In2.Cu")
		(net "P5E_CPU0_PE4_TX_DP<15>")
	)
	(segment
		(start 348.834456 -304.621184)
		(end 350.432116 -301.552102)
		(width 0.14732)
		(layer "In2.Cu")
		(net "P5E_CPU0_PE4_TX_DP<15>")
	)
	(segment
		(start 351.09912 -297.768518)
		(end 351.09912 -290.63315)
		(width 0.14732)
		(layer "In2.Cu")
		(net "P5E_CPU0_PE4_TX_DP<15>")
	)
	(segment
		(start 350.857566 -288.121598)
		(end 350.857566 -288.103056)
		(width 0.0889)
		(layer "In2.Cu")
		(net "P5E_CPU0_PE4_TX_DP<15>")
	)
	(segment
		(start 336.6516 -316.184026)
		(end 338.520278 -314.935362)
		(width 0.14732)
		(layer "In2.Cu")
		(net "P5E_CPU0_PE4_TX_DP<15>")
	)
	(segment
		(start 350.497648 -400.563588)
		(end 350.497648 -399.645886)
		(width 0.14732)
		(layer "In2.Cu")
		(net "P5E_CPU0_PE4_TX_DP<15>")
	)
	(segment
		(start 351.508568 -286.968438)
		(end 351.50933 -286.96793)
		(width 0.0889)
		(layer "In2.Cu")
		(net "P5E_CPU0_PE4_TX_DP<15>")
	)
	(segment
		(start 351.797366 -286.475424)
		(end 351.797366 -286.466788)
		(width 0.0889)
		(layer "In2.Cu")
		(net "P5E_CPU0_PE4_TX_DP<15>")
	)
	(segment
		(start 350.792288 -400.858228)
		(end 350.497648 -400.563588)
		(width 0.14732)
		(layer "In2.Cu")
		(net "P5E_CPU0_PE4_TX_DP<15>")
	)
	(segment
		(start 350.432116 -301.552102)
		(end 351.09912 -297.768518)
		(width 0.14732)
		(layer "In2.Cu")
		(net "P5E_CPU0_PE4_TX_DP<15>")
	)
	(segment
		(start 351.50933 -286.96793)
		(end 351.52076 -286.961326)
		(width 0.0889)
		(layer "In2.Cu")
		(net "P5E_CPU0_PE4_TX_DP<15>")
	)
	(segment
		(start 352.267012 -285.679896)
		(end 352.267012 -285.64586)
		(width 0.0889)
		(layer "In2.Cu")
		(net "P5E_CPU0_PE4_TX_DP<15>")
	)
	(segment
		(start 350.387666 -289.078416)
		(end 350.387666 -288.917126)
		(width 0.0889)
		(layer "In2.Cu")
		(net "P5E_CPU0_PE4_TX_DP<15>")
	)
	(arc
		(start 350.834198 -289.55365)
		(mid 350.725506 -289.394334)
		(end 350.571816 -289.277806)
		(width 0.0889)
		(layer "In2.Cu")
		(net "P5E_CPU0_PE4_TX_DP<15>")
	)
	(arc
		(start 350.571816 -289.277806)
		(mid 350.462669 -289.193878)
		(end 350.387666 -289.078416)
		(width 0.0889)
		(layer "In2.Cu")
		(net "P5E_CPU0_PE4_TX_DP<15>")
	)
	(arc
		(start 351.52076 -286.961326)
		(mid 351.723347 -286.754975)
		(end 351.797366 -286.475424)
		(width 0.0889)
		(layer "In2.Cu")
		(net "P5E_CPU0_PE4_TX_DP<15>")
	)
	(arc
		(start 352.267012 -285.64586)
		(mid 352.208459 -285.41013)
		(end 352.056446 -285.220664)
		(width 0.0889)
		(layer "In2.Cu")
		(net "P5E_CPU0_PE4_TX_DP<15>")
	)
	(arc
		(start 352.056446 -285.220664)
		(mid 352.048126 -285.214107)
		(end 352.039682 -285.20771)
		(width 0.0889)
		(layer "In2.Cu")
		(net "P5E_CPU0_PE4_TX_DP<15>")
	)
	(arc
		(start 351.045018 -287.778698)
		(mid 351.247841 -287.578467)
		(end 351.327212 -287.304734)
		(width 0.0889)
		(layer "In2.Cu")
		(net "P5E_CPU0_PE4_TX_DP<15>")
	)
	(arc
		(start 350.857566 -288.103056)
		(mid 350.905245 -287.920156)
		(end 351.036128 -287.783778)
		(width 0.0889)
		(layer "In2.Cu")
		(net "P5E_CPU0_PE4_TX_DP<15>")
	)
	(arc
		(start 351.797366 -286.466788)
		(mid 351.849636 -286.284423)
		(end 351.984564 -286.151066)
		(width 0.0889)
		(layer "In2.Cu")
		(net "P5E_CPU0_PE4_TX_DP<15>")
	)
	(arc
		(start 350.575118 -288.592768)
		(mid 350.777404 -288.393787)
		(end 350.857566 -288.121598)
		(width 0.0889)
		(layer "In2.Cu")
		(net "P5E_CPU0_PE4_TX_DP<15>")
	)
	(arc
		(start 351.984564 -286.151066)
		(mid 352.18685 -285.952085)
		(end 352.267012 -285.679896)
		(width 0.0889)
		(layer "In2.Cu")
		(net "P5E_CPU0_PE4_TX_DP<15>")
	)
	(arc
		(start 350.857058 -289.65906)
		(mid 350.851446 -289.605092)
		(end 350.834198 -289.55365)
		(width 0.0889)
		(layer "In2.Cu")
		(net "P5E_CPU0_PE4_TX_DP<15>")
	)
	(arc
		(start 350.387666 -288.917126)
		(mid 350.435345 -288.734226)
		(end 350.566228 -288.597848)
		(width 0.0889)
		(layer "In2.Cu")
		(net "P5E_CPU0_PE4_TX_DP<15>")
	)
	(arc
		(start 351.327212 -287.28924)
		(mid 351.374891 -287.10634)
		(end 351.505774 -286.969962)
		(width 0.0889)
		(layer "In2.Cu")
		(net "P5E_CPU0_PE4_TX_DP<15>")
	)
	(segment
		(start 351.231962 -286.47517)
		(end 351.232216 -286.475424)
		(width 0.13208)
		(layer "F.Cu")
		(net "P5E_CPU0_PE4_TX_DP<14>")
	)
	(segment
		(start 351.231962 -285.939484)
		(end 351.231962 -286.47517)
		(width 0.13208)
		(layer "F.Cu")
		(net "P5E_CPU0_PE4_TX_DP<14>")
	)
	(segment
		(start 347.729048 -400.858228)
		(end 347.43009 -401.157186)
		(width 0.13208)
		(layer "F.Cu")
		(net "P5E_CPU0_PE4_TX_DP<14>")
	)
	(segment
		(start 347.43009 -401.779994)
		(end 347.754448 -402.104352)
		(width 0.13208)
		(layer "F.Cu")
		(net "P5E_CPU0_PE4_TX_DP<14>")
	)
	(segment
		(start 347.43009 -401.157186)
		(end 347.43009 -401.779994)
		(width 0.13208)
		(layer "F.Cu")
		(net "P5E_CPU0_PE4_TX_DP<14>")
	)
	(segment
		(start 350.114616 -290.60013)
		(end 350.114616 -291.013642)
		(width 0.0889)
		(layer "In2.Cu")
		(net "P5E_CPU0_PE4_TX_DP<14>")
	)
	(segment
		(start 336.076036 -315.394594)
		(end 317.067184 -334.403446)
		(width 0.14732)
		(layer "In2.Cu")
		(net "P5E_CPU0_PE4_TX_DP<14>")
	)
	(segment
		(start 350.15678 -291.055806)
		(end 350.15678 -291.077904)
		(width 0.0889)
		(layer "In2.Cu")
		(net "P5E_CPU0_PE4_TX_DP<14>")
	)
	(segment
		(start 316.536578 -342.393016)
		(end 316.689232 -343.258902)
		(width 0.14732)
		(layer "In2.Cu")
		(net "P5E_CPU0_PE4_TX_DP<14>")
	)
	(segment
		(start 317.067184 -334.403446)
		(end 316.536578 -335.684114)
		(width 0.14732)
		(layer "In2.Cu")
		(net "P5E_CPU0_PE4_TX_DP<14>")
	)
	(segment
		(start 351.075752 -286.204406)
		(end 350.99752 -286.183578)
		(width 0.0889)
		(layer "In2.Cu")
		(net "P5E_CPU0_PE4_TX_DP<14>")
	)
	(segment
		(start 348.004384 -304.107342)
		(end 338.008468 -314.103258)
		(width 0.14732)
		(layer "In2.Cu")
		(net "P5E_CPU0_PE4_TX_DP<14>")
	)
	(segment
		(start 349.917512 -289.60953)
		(end 349.917512 -290.495482)
		(width 0.0889)
		(layer "In2.Cu")
		(net "P5E_CPU0_PE4_TX_DP<14>")
	)
	(segment
		(start 347.434408 -399.60804)
		(end 347.434408 -400.563588)
		(width 0.14732)
		(layer "In2.Cu")
		(net "P5E_CPU0_PE4_TX_DP<14>")
	)
	(segment
		(start 346.492322 -397.908272)
		(end 346.701364 -398.291812)
		(width 0.14732)
		(layer "In2.Cu")
		(net "P5E_CPU0_PE4_TX_DP<14>")
	)
	(segment
		(start 351.232216 -286.475424)
		(end 351.075752 -286.204406)
		(width 0.0889)
		(layer "In2.Cu")
		(net "P5E_CPU0_PE4_TX_DP<14>")
	)
	(segment
		(start 347.434408 -400.563588)
		(end 347.729048 -400.858228)
		(width 0.14732)
		(layer "In2.Cu")
		(net "P5E_CPU0_PE4_TX_DP<14>")
	)
	(segment
		(start 350.574864 -286.964882)
		(end 350.565974 -286.969962)
		(width 0.0889)
		(layer "In2.Cu")
		(net "P5E_CPU0_PE4_TX_DP<14>")
	)
	(segment
		(start 346.163646 -397.306038)
		(end 346.33281 -397.355822)
		(width 0.14732)
		(layer "In2.Cu")
		(net "P5E_CPU0_PE4_TX_DP<14>")
	)
	(segment
		(start 346.542106 -397.739616)
		(end 346.492322 -397.908272)
		(width 0.14732)
		(layer "In2.Cu")
		(net "P5E_CPU0_PE4_TX_DP<14>")
	)
	(segment
		(start 316.689232 -343.259918)
		(end 346.1639 -397.305784)
		(width 0.14732)
		(layer "In2.Cu")
		(net "P5E_CPU0_PE4_TX_DP<14>")
	)
	(segment
		(start 349.447866 -288.917126)
		(end 349.447866 -289.078416)
		(width 0.0889)
		(layer "In2.Cu")
		(net "P5E_CPU0_PE4_TX_DP<14>")
	)
	(segment
		(start 346.701364 -398.291812)
		(end 346.870274 -398.341342)
		(width 0.14732)
		(layer "In2.Cu")
		(net "P5E_CPU0_PE4_TX_DP<14>")
	)
	(segment
		(start 338.008468 -314.103258)
		(end 336.076036 -315.394594)
		(width 0.14732)
		(layer "In2.Cu")
		(net "P5E_CPU0_PE4_TX_DP<14>")
	)
	(segment
		(start 346.1639 -397.305784)
		(end 346.163646 -397.306038)
		(width 0.14732)
		(layer "In2.Cu")
		(net "P5E_CPU0_PE4_TX_DP<14>")
	)
	(segment
		(start 347.07957 -398.725136)
		(end 347.029786 -398.894046)
		(width 0.14732)
		(layer "In2.Cu")
		(net "P5E_CPU0_PE4_TX_DP<14>")
	)
	(segment
		(start 346.870274 -398.341342)
		(end 347.07957 -398.725136)
		(width 0.14732)
		(layer "In2.Cu")
		(net "P5E_CPU0_PE4_TX_DP<14>")
	)
	(segment
		(start 316.536578 -335.684114)
		(end 316.536578 -342.393016)
		(width 0.14732)
		(layer "In2.Cu")
		(net "P5E_CPU0_PE4_TX_DP<14>")
	)
	(segment
		(start 350.15678 -297.268392)
		(end 349.435674 -301.357792)
		(width 0.14732)
		(layer "In2.Cu")
		(net "P5E_CPU0_PE4_TX_DP<14>")
	)
	(segment
		(start 350.15678 -291.077904)
		(end 350.15678 -297.268392)
		(width 0.14732)
		(layer "In2.Cu")
		(net "P5E_CPU0_PE4_TX_DP<14>")
	)
	(segment
		(start 349.917512 -290.495482)
		(end 350.114616 -290.60013)
		(width 0.0889)
		(layer "In2.Cu")
		(net "P5E_CPU0_PE4_TX_DP<14>")
	)
	(segment
		(start 347.029786 -398.894046)
		(end 347.40088 -399.574512)
		(width 0.14732)
		(layer "In2.Cu")
		(net "P5E_CPU0_PE4_TX_DP<14>")
	)
	(segment
		(start 350.114616 -291.013642)
		(end 350.15678 -291.055806)
		(width 0.0889)
		(layer "In2.Cu")
		(net "P5E_CPU0_PE4_TX_DP<14>")
	)
	(segment
		(start 316.689232 -343.258902)
		(end 316.689232 -343.259918)
		(width 0.14732)
		(layer "In2.Cu")
		(net "P5E_CPU0_PE4_TX_DP<14>")
	)
	(segment
		(start 349.435674 -301.357792)
		(end 348.004384 -304.107342)
		(width 0.14732)
		(layer "In2.Cu")
		(net "P5E_CPU0_PE4_TX_DP<14>")
	)
	(segment
		(start 347.40088 -399.574512)
		(end 347.434408 -399.60804)
		(width 0.14732)
		(layer "In2.Cu")
		(net "P5E_CPU0_PE4_TX_DP<14>")
	)
	(segment
		(start 349.917766 -288.103056)
		(end 349.917766 -288.121598)
		(width 0.0889)
		(layer "In2.Cu")
		(net "P5E_CPU0_PE4_TX_DP<14>")
	)
	(segment
		(start 350.387412 -287.28924)
		(end 350.387412 -287.304734)
		(width 0.0889)
		(layer "In2.Cu")
		(net "P5E_CPU0_PE4_TX_DP<14>")
	)
	(segment
		(start 350.587056 -286.95777)
		(end 350.574864 -286.964882)
		(width 0.0889)
		(layer "In2.Cu")
		(net "P5E_CPU0_PE4_TX_DP<14>")
	)
	(segment
		(start 349.635318 -288.592768)
		(end 349.626428 -288.597848)
		(width 0.0889)
		(layer "In2.Cu")
		(net "P5E_CPU0_PE4_TX_DP<14>")
	)
	(segment
		(start 346.33281 -397.355822)
		(end 346.542106 -397.739616)
		(width 0.14732)
		(layer "In2.Cu")
		(net "P5E_CPU0_PE4_TX_DP<14>")
	)
	(segment
		(start 350.105218 -287.778698)
		(end 350.096328 -287.783778)
		(width 0.0889)
		(layer "In2.Cu")
		(net "P5E_CPU0_PE4_TX_DP<14>")
	)
	(arc
		(start 349.632016 -289.277806)
		(mid 349.806148 -289.416653)
		(end 349.917512 -289.60953)
		(width 0.0889)
		(layer "In2.Cu")
		(net "P5E_CPU0_PE4_TX_DP<14>")
	)
	(arc
		(start 350.99752 -286.183578)
		(mid 350.894375 -286.313603)
		(end 350.857566 -286.475424)
		(width 0.0889)
		(layer "In2.Cu")
		(net "P5E_CPU0_PE4_TX_DP<14>")
	)
	(arc
		(start 350.857566 -286.475424)
		(mid 350.785331 -286.751948)
		(end 350.587056 -286.95777)
		(width 0.0889)
		(layer "In2.Cu")
		(net "P5E_CPU0_PE4_TX_DP<14>")
	)
	(arc
		(start 349.447866 -289.078416)
		(mid 349.522871 -289.193875)
		(end 349.632016 -289.277806)
		(width 0.0889)
		(layer "In2.Cu")
		(net "P5E_CPU0_PE4_TX_DP<14>")
	)
	(arc
		(start 349.626428 -288.597848)
		(mid 349.495514 -288.734208)
		(end 349.447866 -288.917126)
		(width 0.0889)
		(layer "In2.Cu")
		(net "P5E_CPU0_PE4_TX_DP<14>")
	)
	(arc
		(start 350.387412 -287.304734)
		(mid 350.308042 -287.578468)
		(end 350.105218 -287.778698)
		(width 0.0889)
		(layer "In2.Cu")
		(net "P5E_CPU0_PE4_TX_DP<14>")
	)
	(arc
		(start 350.096328 -287.783778)
		(mid 349.965414 -287.920138)
		(end 349.917766 -288.103056)
		(width 0.0889)
		(layer "In2.Cu")
		(net "P5E_CPU0_PE4_TX_DP<14>")
	)
	(arc
		(start 350.565974 -286.969962)
		(mid 350.43506 -287.106322)
		(end 350.387412 -287.28924)
		(width 0.0889)
		(layer "In2.Cu")
		(net "P5E_CPU0_PE4_TX_DP<14>")
	)
	(arc
		(start 349.917766 -288.121598)
		(mid 349.837604 -288.393787)
		(end 349.635318 -288.592768)
		(width 0.0889)
		(layer "In2.Cu")
		(net "P5E_CPU0_PE4_TX_DP<14>")
	)
	(segment
		(start 344.36685 -401.157186)
		(end 344.36685 -401.779994)
		(width 0.13208)
		(layer "F.Cu")
		(net "P5E_CPU0_PE4_TX_DP<13>")
	)
	(segment
		(start 344.36685 -401.779994)
		(end 344.691208 -402.104352)
		(width 0.13208)
		(layer "F.Cu")
		(net "P5E_CPU0_PE4_TX_DP<13>")
	)
	(segment
		(start 350.292162 -284.311598)
		(end 350.292162 -284.847284)
		(width 0.13208)
		(layer "F.Cu")
		(net "P5E_CPU0_PE4_TX_DP<13>")
	)
	(segment
		(start 350.292162 -284.847284)
		(end 350.292416 -284.847538)
		(width 0.13208)
		(layer "F.Cu")
		(net "P5E_CPU0_PE4_TX_DP<13>")
	)
	(segment
		(start 344.665808 -400.858228)
		(end 344.36685 -401.157186)
		(width 0.13208)
		(layer "F.Cu")
		(net "P5E_CPU0_PE4_TX_DP<13>")
	)
	(segment
		(start 349.019876 -291.350446)
		(end 348.601792 -291.76853)
		(width 0.14732)
		(layer "In2.Cu")
		(net "P5E_CPU0_PE4_TX_DP<13>")
	)
	(segment
		(start 344.371168 -400.563588)
		(end 344.665808 -400.858228)
		(width 0.14732)
		(layer "In2.Cu")
		(net "P5E_CPU0_PE4_TX_DP<13>")
	)
	(segment
		(start 348.601792 -300.251368)
		(end 347.251274 -303.511712)
		(width 0.14732)
		(layer "In2.Cu")
		(net "P5E_CPU0_PE4_TX_DP<13>")
	)
	(segment
		(start 348.977712 -290.840922)
		(end 349.019876 -290.883086)
		(width 0.0889)
		(layer "In2.Cu")
		(net "P5E_CPU0_PE4_TX_DP<13>")
	)
	(segment
		(start 349.635064 -286.964882)
		(end 349.63354 -286.965644)
		(width 0.0889)
		(layer "In2.Cu")
		(net "P5E_CPU0_PE4_TX_DP<13>")
	)
	(segment
		(start 348.977966 -288.103056)
		(end 348.977966 -288.121598)
		(width 0.0889)
		(layer "In2.Cu")
		(net "P5E_CPU0_PE4_TX_DP<13>")
	)
	(segment
		(start 316.225174 -333.923132)
		(end 315.571632 -335.500726)
		(width 0.14732)
		(layer "In2.Cu")
		(net "P5E_CPU0_PE4_TX_DP<13>")
	)
	(segment
		(start 350.385634 -285.579312)
		(end 350.387412 -285.679896)
		(width 0.0889)
		(layer "In2.Cu")
		(net "P5E_CPU0_PE4_TX_DP<13>")
	)
	(segment
		(start 348.695518 -288.592768)
		(end 348.686628 -288.597848)
		(width 0.0889)
		(layer "In2.Cu")
		(net "P5E_CPU0_PE4_TX_DP<13>")
	)
	(segment
		(start 315.571632 -342.477598)
		(end 315.75121 -343.497154)
		(width 0.14732)
		(layer "In2.Cu")
		(net "P5E_CPU0_PE4_TX_DP<13>")
	)
	(segment
		(start 350.292416 -284.847538)
		(end 350.135952 -285.118556)
		(width 0.0889)
		(layer "In2.Cu")
		(net "P5E_CPU0_PE4_TX_DP<13>")
	)
	(segment
		(start 347.251274 -303.511712)
		(end 337.428332 -313.334654)
		(width 0.14732)
		(layer "In2.Cu")
		(net "P5E_CPU0_PE4_TX_DP<13>")
	)
	(segment
		(start 337.428332 -313.334654)
		(end 335.575402 -314.572904)
		(width 0.14732)
		(layer "In2.Cu")
		(net "P5E_CPU0_PE4_TX_DP<13>")
	)
	(segment
		(start 323.44741 -357.78313)
		(end 344.371168 -399.527776)
		(width 0.14732)
		(layer "In2.Cu")
		(net "P5E_CPU0_PE4_TX_DP<13>")
	)
	(segment
		(start 348.601792 -291.76853)
		(end 348.601792 -300.251368)
		(width 0.14732)
		(layer "In2.Cu")
		(net "P5E_CPU0_PE4_TX_DP<13>")
	)
	(segment
		(start 344.371168 -399.527776)
		(end 344.371168 -400.563588)
		(width 0.14732)
		(layer "In2.Cu")
		(net "P5E_CPU0_PE4_TX_DP<13>")
	)
	(segment
		(start 349.64116 -286.961326)
		(end 349.635064 -286.964882)
		(width 0.0889)
		(layer "In2.Cu")
		(net "P5E_CPU0_PE4_TX_DP<13>")
	)
	(segment
		(start 348.977712 -289.60953)
		(end 348.977712 -290.840922)
		(width 0.0889)
		(layer "In2.Cu")
		(net "P5E_CPU0_PE4_TX_DP<13>")
	)
	(segment
		(start 315.75121 -343.497154)
		(end 323.44741 -357.78313)
		(width 0.14732)
		(layer "In2.Cu")
		(net "P5E_CPU0_PE4_TX_DP<13>")
	)
	(segment
		(start 315.571632 -335.500726)
		(end 315.571632 -342.477598)
		(width 0.14732)
		(layer "In2.Cu")
		(net "P5E_CPU0_PE4_TX_DP<13>")
	)
	(segment
		(start 349.917766 -286.466788)
		(end 349.917766 -286.475424)
		(width 0.0889)
		(layer "In2.Cu")
		(net "P5E_CPU0_PE4_TX_DP<13>")
	)
	(segment
		(start 335.575402 -314.572904)
		(end 316.225174 -333.923132)
		(width 0.14732)
		(layer "In2.Cu")
		(net "P5E_CPU0_PE4_TX_DP<13>")
	)
	(segment
		(start 349.019876 -290.905184)
		(end 349.019876 -291.350446)
		(width 0.14732)
		(layer "In2.Cu")
		(net "P5E_CPU0_PE4_TX_DP<13>")
	)
	(segment
		(start 350.176846 -285.220664)
		(end 350.228662 -285.26232)
		(width 0.0889)
		(layer "In2.Cu")
		(net "P5E_CPU0_PE4_TX_DP<13>")
	)
	(segment
		(start 349.019876 -290.883086)
		(end 349.019876 -290.905184)
		(width 0.0889)
		(layer "In2.Cu")
		(net "P5E_CPU0_PE4_TX_DP<13>")
	)
	(segment
		(start 350.135952 -285.118556)
		(end 350.160082 -285.20771)
		(width 0.0889)
		(layer "In2.Cu")
		(net "P5E_CPU0_PE4_TX_DP<13>")
	)
	(segment
		(start 349.165418 -287.778698)
		(end 349.156528 -287.783778)
		(width 0.0889)
		(layer "In2.Cu")
		(net "P5E_CPU0_PE4_TX_DP<13>")
	)
	(segment
		(start 348.508066 -288.917126)
		(end 348.508066 -289.078416)
		(width 0.0889)
		(layer "In2.Cu")
		(net "P5E_CPU0_PE4_TX_DP<13>")
	)
	(segment
		(start 349.63354 -286.965644)
		(end 349.626174 -286.969962)
		(width 0.0889)
		(layer "In2.Cu")
		(net "P5E_CPU0_PE4_TX_DP<13>")
	)
	(segment
		(start 349.447612 -287.28924)
		(end 349.447612 -287.304734)
		(width 0.0889)
		(layer "In2.Cu")
		(net "P5E_CPU0_PE4_TX_DP<13>")
	)
	(arc
		(start 349.447612 -287.304734)
		(mid 349.368242 -287.578468)
		(end 349.165418 -287.778698)
		(width 0.0889)
		(layer "In2.Cu")
		(net "P5E_CPU0_PE4_TX_DP<13>")
	)
	(arc
		(start 349.626174 -286.969962)
		(mid 349.49526 -287.106322)
		(end 349.447612 -287.28924)
		(width 0.0889)
		(layer "In2.Cu")
		(net "P5E_CPU0_PE4_TX_DP<13>")
	)
	(arc
		(start 348.508066 -289.078416)
		(mid 348.583071 -289.193875)
		(end 348.692216 -289.277806)
		(width 0.0889)
		(layer "In2.Cu")
		(net "P5E_CPU0_PE4_TX_DP<13>")
	)
	(arc
		(start 350.387412 -285.679896)
		(mid 350.30725 -285.952085)
		(end 350.104964 -286.151066)
		(width 0.0889)
		(layer "In2.Cu")
		(net "P5E_CPU0_PE4_TX_DP<13>")
	)
	(arc
		(start 348.977966 -288.121598)
		(mid 348.897804 -288.393787)
		(end 348.695518 -288.592768)
		(width 0.0889)
		(layer "In2.Cu")
		(net "P5E_CPU0_PE4_TX_DP<13>")
	)
	(arc
		(start 349.917766 -286.475424)
		(mid 349.843775 -286.75499)
		(end 349.64116 -286.961326)
		(width 0.0889)
		(layer "In2.Cu")
		(net "P5E_CPU0_PE4_TX_DP<13>")
	)
	(arc
		(start 349.156528 -287.783778)
		(mid 349.025614 -287.920138)
		(end 348.977966 -288.103056)
		(width 0.0889)
		(layer "In2.Cu")
		(net "P5E_CPU0_PE4_TX_DP<13>")
	)
	(arc
		(start 350.228662 -285.26232)
		(mid 350.341963 -285.403564)
		(end 350.385634 -285.579312)
		(width 0.0889)
		(layer "In2.Cu")
		(net "P5E_CPU0_PE4_TX_DP<13>")
	)
	(arc
		(start 350.104964 -286.151066)
		(mid 349.970031 -286.28442)
		(end 349.917766 -286.466788)
		(width 0.0889)
		(layer "In2.Cu")
		(net "P5E_CPU0_PE4_TX_DP<13>")
	)
	(arc
		(start 348.692216 -289.277806)
		(mid 348.851915 -289.400482)
		(end 348.961964 -289.569144)
		(width 0.0889)
		(layer "In2.Cu")
		(net "P5E_CPU0_PE4_TX_DP<13>")
	)
	(arc
		(start 348.961964 -289.569144)
		(mid 348.9702 -289.589196)
		(end 348.977712 -289.60953)
		(width 0.0889)
		(layer "In2.Cu")
		(net "P5E_CPU0_PE4_TX_DP<13>")
	)
	(arc
		(start 348.686628 -288.597848)
		(mid 348.555714 -288.734208)
		(end 348.508066 -288.917126)
		(width 0.0889)
		(layer "In2.Cu")
		(net "P5E_CPU0_PE4_TX_DP<13>")
	)
	(arc
		(start 350.160082 -285.20771)
		(mid 350.168523 -285.21411)
		(end 350.176846 -285.220664)
		(width 0.0889)
		(layer "In2.Cu")
		(net "P5E_CPU0_PE4_TX_DP<13>")
	)
	(segment
		(start 341.30361 -401.157186)
		(end 341.30361 -401.779994)
		(width 0.13208)
		(layer "F.Cu")
		(net "P5E_CPU0_PE4_TX_DP<12>")
	)
	(segment
		(start 349.352362 -286.47517)
		(end 349.352616 -286.475424)
		(width 0.13208)
		(layer "F.Cu")
		(net "P5E_CPU0_PE4_TX_DP<12>")
	)
	(segment
		(start 341.602568 -400.858228)
		(end 341.30361 -401.157186)
		(width 0.13208)
		(layer "F.Cu")
		(net "P5E_CPU0_PE4_TX_DP<12>")
	)
	(segment
		(start 341.30361 -401.779994)
		(end 341.627968 -402.104352)
		(width 0.13208)
		(layer "F.Cu")
		(net "P5E_CPU0_PE4_TX_DP<12>")
	)
	(segment
		(start 349.352362 -285.939484)
		(end 349.352362 -286.47517)
		(width 0.13208)
		(layer "F.Cu")
		(net "P5E_CPU0_PE4_TX_DP<12>")
	)
	(segment
		(start 336.875374 -312.554112)
		(end 335.05648 -313.769502)
		(width 0.14732)
		(layer "In2.Cu")
		(net "P5E_CPU0_PE4_TX_DP<12>")
	)
	(segment
		(start 340.041992 -396.771876)
		(end 340.207346 -396.832582)
		(width 0.14732)
		(layer "In2.Cu")
		(net "P5E_CPU0_PE4_TX_DP<12>")
	)
	(segment
		(start 346.460572 -302.968914)
		(end 336.875374 -312.554112)
		(width 0.14732)
		(layer "In2.Cu")
		(net "P5E_CPU0_PE4_TX_DP<12>")
	)
	(segment
		(start 340.33079 -397.394176)
		(end 340.514686 -397.790416)
		(width 0.14732)
		(layer "In2.Cu")
		(net "P5E_CPU0_PE4_TX_DP<12>")
	)
	(segment
		(start 347.671136 -290.959794)
		(end 347.671136 -290.981892)
		(width 0.0889)
		(layer "In2.Cu")
		(net "P5E_CPU0_PE4_TX_DP<12>")
	)
	(segment
		(start 348.707456 -286.95777)
		(end 348.686374 -286.969962)
		(width 0.0889)
		(layer "In2.Cu")
		(net "P5E_CPU0_PE4_TX_DP<12>")
	)
	(segment
		(start 340.207346 -396.832582)
		(end 340.391242 -397.229076)
		(width 0.14732)
		(layer "In2.Cu")
		(net "P5E_CPU0_PE4_TX_DP<12>")
	)
	(segment
		(start 348.038166 -288.103056)
		(end 348.038166 -288.121598)
		(width 0.0889)
		(layer "In2.Cu")
		(net "P5E_CPU0_PE4_TX_DP<12>")
	)
	(segment
		(start 314.637166 -335.303114)
		(end 314.637166 -342.55964)
		(width 0.14732)
		(layer "In2.Cu")
		(net "P5E_CPU0_PE4_TX_DP<12>")
	)
	(segment
		(start 348.037912 -290.373054)
		(end 347.628972 -290.781994)
		(width 0.0889)
		(layer "In2.Cu")
		(net "P5E_CPU0_PE4_TX_DP<12>")
	)
	(segment
		(start 340.514686 -397.790416)
		(end 340.680294 -397.850868)
		(width 0.14732)
		(layer "In2.Cu")
		(net "P5E_CPU0_PE4_TX_DP<12>")
	)
	(segment
		(start 340.803738 -398.412716)
		(end 341.307928 -399.499074)
		(width 0.14732)
		(layer "In2.Cu")
		(net "P5E_CPU0_PE4_TX_DP<12>")
	)
	(segment
		(start 315.425074 -333.400908)
		(end 314.637166 -335.303114)
		(width 0.14732)
		(layer "In2.Cu")
		(net "P5E_CPU0_PE4_TX_DP<12>")
	)
	(segment
		(start 322.217796 -358.377998)
		(end 340.041992 -396.771876)
		(width 0.14732)
		(layer "In2.Cu")
		(net "P5E_CPU0_PE4_TX_DP<12>")
	)
	(segment
		(start 348.037912 -289.60953)
		(end 348.037912 -290.373054)
		(width 0.0889)
		(layer "In2.Cu")
		(net "P5E_CPU0_PE4_TX_DP<12>")
	)
	(segment
		(start 347.568266 -288.917126)
		(end 347.568266 -289.078416)
		(width 0.0889)
		(layer "In2.Cu")
		(net "P5E_CPU0_PE4_TX_DP<12>")
	)
	(segment
		(start 314.86602 -343.857834)
		(end 322.217796 -358.377998)
		(width 0.14732)
		(layer "In2.Cu")
		(net "P5E_CPU0_PE4_TX_DP<12>")
	)
	(segment
		(start 347.628972 -290.91763)
		(end 347.671136 -290.959794)
		(width 0.0889)
		(layer "In2.Cu")
		(net "P5E_CPU0_PE4_TX_DP<12>")
	)
	(segment
		(start 347.671136 -290.981892)
		(end 347.671136 -300.045882)
		(width 0.14732)
		(layer "In2.Cu")
		(net "P5E_CPU0_PE4_TX_DP<12>")
	)
	(segment
		(start 340.391242 -397.229076)
		(end 340.33079 -397.394176)
		(width 0.14732)
		(layer "In2.Cu")
		(net "P5E_CPU0_PE4_TX_DP<12>")
	)
	(segment
		(start 347.755718 -288.592768)
		(end 347.746828 -288.597848)
		(width 0.0889)
		(layer "In2.Cu")
		(net "P5E_CPU0_PE4_TX_DP<12>")
	)
	(segment
		(start 347.671136 -300.045882)
		(end 346.460572 -302.968914)
		(width 0.14732)
		(layer "In2.Cu")
		(net "P5E_CPU0_PE4_TX_DP<12>")
	)
	(segment
		(start 348.225618 -287.778698)
		(end 348.216728 -287.783778)
		(width 0.0889)
		(layer "In2.Cu")
		(net "P5E_CPU0_PE4_TX_DP<12>")
	)
	(segment
		(start 347.628972 -290.781994)
		(end 347.628972 -290.91763)
		(width 0.0889)
		(layer "In2.Cu")
		(net "P5E_CPU0_PE4_TX_DP<12>")
	)
	(segment
		(start 349.196152 -286.204406)
		(end 349.11792 -286.183578)
		(width 0.0889)
		(layer "In2.Cu")
		(net "P5E_CPU0_PE4_TX_DP<12>")
	)
	(segment
		(start 349.352616 -286.475424)
		(end 349.196152 -286.204406)
		(width 0.0889)
		(layer "In2.Cu")
		(net "P5E_CPU0_PE4_TX_DP<12>")
	)
	(segment
		(start 348.507812 -287.28924)
		(end 348.507812 -287.304734)
		(width 0.0889)
		(layer "In2.Cu")
		(net "P5E_CPU0_PE4_TX_DP<12>")
	)
	(segment
		(start 335.05648 -313.769502)
		(end 315.425074 -333.400908)
		(width 0.14732)
		(layer "In2.Cu")
		(net "P5E_CPU0_PE4_TX_DP<12>")
	)
	(segment
		(start 340.86419 -398.247362)
		(end 340.803738 -398.412716)
		(width 0.14732)
		(layer "In2.Cu")
		(net "P5E_CPU0_PE4_TX_DP<12>")
	)
	(segment
		(start 314.637166 -342.55964)
		(end 314.86602 -343.857834)
		(width 0.14732)
		(layer "In2.Cu")
		(net "P5E_CPU0_PE4_TX_DP<12>")
	)
	(segment
		(start 341.307928 -399.499074)
		(end 341.307928 -400.563588)
		(width 0.14732)
		(layer "In2.Cu")
		(net "P5E_CPU0_PE4_TX_DP<12>")
	)
	(segment
		(start 340.680294 -397.850868)
		(end 340.86419 -398.247362)
		(width 0.14732)
		(layer "In2.Cu")
		(net "P5E_CPU0_PE4_TX_DP<12>")
	)
	(segment
		(start 341.307928 -400.563588)
		(end 341.602568 -400.858228)
		(width 0.14732)
		(layer "In2.Cu")
		(net "P5E_CPU0_PE4_TX_DP<12>")
	)
	(arc
		(start 348.977966 -286.475424)
		(mid 348.905731 -286.751948)
		(end 348.707456 -286.95777)
		(width 0.0889)
		(layer "In2.Cu")
		(net "P5E_CPU0_PE4_TX_DP<12>")
	)
	(arc
		(start 347.568266 -289.078416)
		(mid 347.643271 -289.193875)
		(end 347.752416 -289.277806)
		(width 0.0889)
		(layer "In2.Cu")
		(net "P5E_CPU0_PE4_TX_DP<12>")
	)
	(arc
		(start 347.752416 -289.277806)
		(mid 347.926548 -289.416653)
		(end 348.037912 -289.60953)
		(width 0.0889)
		(layer "In2.Cu")
		(net "P5E_CPU0_PE4_TX_DP<12>")
	)
	(arc
		(start 348.216728 -287.783778)
		(mid 348.085814 -287.920138)
		(end 348.038166 -288.103056)
		(width 0.0889)
		(layer "In2.Cu")
		(net "P5E_CPU0_PE4_TX_DP<12>")
	)
	(arc
		(start 348.686374 -286.969962)
		(mid 348.55546 -287.106322)
		(end 348.507812 -287.28924)
		(width 0.0889)
		(layer "In2.Cu")
		(net "P5E_CPU0_PE4_TX_DP<12>")
	)
	(arc
		(start 347.746828 -288.597848)
		(mid 347.615914 -288.734208)
		(end 347.568266 -288.917126)
		(width 0.0889)
		(layer "In2.Cu")
		(net "P5E_CPU0_PE4_TX_DP<12>")
	)
	(arc
		(start 348.038166 -288.121598)
		(mid 347.958004 -288.393787)
		(end 347.755718 -288.592768)
		(width 0.0889)
		(layer "In2.Cu")
		(net "P5E_CPU0_PE4_TX_DP<12>")
	)
	(arc
		(start 349.11792 -286.183578)
		(mid 349.014775 -286.313603)
		(end 348.977966 -286.475424)
		(width 0.0889)
		(layer "In2.Cu")
		(net "P5E_CPU0_PE4_TX_DP<12>")
	)
	(arc
		(start 348.507812 -287.304734)
		(mid 348.428442 -287.578468)
		(end 348.225618 -287.778698)
		(width 0.0889)
		(layer "In2.Cu")
		(net "P5E_CPU0_PE4_TX_DP<12>")
	)
	(segment
		(start 337.675728 -400.858228)
		(end 337.98129 -401.16379)
		(width 0.13208)
		(layer "F.Cu")
		(net "P5E_CPU0_PE4_TX_DP<11>")
	)
	(segment
		(start 347.942916 -285.6611)
		(end 347.942662 -285.661354)
		(width 0.13208)
		(layer "F.Cu")
		(net "P5E_CPU0_PE4_TX_DP<11>")
	)
	(segment
		(start 347.942916 -285.125414)
		(end 347.942916 -285.6611)
		(width 0.13208)
		(layer "F.Cu")
		(net "P5E_CPU0_PE4_TX_DP<11>")
	)
	(segment
		(start 337.98129 -401.777962)
		(end 337.6549 -402.104352)
		(width 0.13208)
		(layer "F.Cu")
		(net "P5E_CPU0_PE4_TX_DP<11>")
	)
	(segment
		(start 337.6549 -402.104352)
		(end 337.650328 -402.104352)
		(width 0.13208)
		(layer "F.Cu")
		(net "P5E_CPU0_PE4_TX_DP<11>")
	)
	(segment
		(start 337.98129 -401.16379)
		(end 337.98129 -401.777962)
		(width 0.13208)
		(layer "F.Cu")
		(net "P5E_CPU0_PE4_TX_DP<11>")
	)
	(segment
		(start 347.847412 -286.456882)
		(end 347.847412 -286.48406)
		(width 0.0889)
		(layer "In2.Cu")
		(net "P5E_CPU0_PE4_TX_DP<11>")
	)
	(segment
		(start 314.31865 -332.803754)
		(end 313.40425 -335.011522)
		(width 0.14732)
		(layer "In2.Cu")
		(net "P5E_CPU0_PE4_TX_DP<11>")
	)
	(segment
		(start 347.660214 -286.799782)
		(end 347.659452 -286.80029)
		(width 0.0889)
		(layer "In2.Cu")
		(net "P5E_CPU0_PE4_TX_DP<11>")
	)
	(segment
		(start 348.099126 -285.390336)
		(end 348.177358 -285.369508)
		(width 0.0889)
		(layer "In2.Cu")
		(net "P5E_CPU0_PE4_TX_DP<11>")
	)
	(segment
		(start 346.464636 -290.676076)
		(end 346.464636 -290.698174)
		(width 0.0889)
		(layer "In2.Cu")
		(net "P5E_CPU0_PE4_TX_DP<11>")
	)
	(segment
		(start 313.40425 -342.52662)
		(end 313.720734 -344.323416)
		(width 0.14732)
		(layer "In2.Cu")
		(net "P5E_CPU0_PE4_TX_DP<11>")
	)
	(segment
		(start 320.68897 -359.012236)
		(end 336.874866 -396.973298)
		(width 0.14732)
		(layer "In2.Cu")
		(net "P5E_CPU0_PE4_TX_DP<11>")
	)
	(segment
		(start 347.19895 -287.608518)
		(end 347.19006 -287.613598)
		(width 0.0889)
		(layer "In2.Cu")
		(net "P5E_CPU0_PE4_TX_DP<11>")
	)
	(segment
		(start 336.874866 -396.973298)
		(end 336.80908 -397.13662)
		(width 0.14732)
		(layer "In2.Cu")
		(net "P5E_CPU0_PE4_TX_DP<11>")
	)
	(segment
		(start 346.907612 -290.018216)
		(end 346.506546 -290.419282)
		(width 0.0889)
		(layer "In2.Cu")
		(net "P5E_CPU0_PE4_TX_DP<11>")
	)
	(segment
		(start 337.970114 -400.563842)
		(end 337.675728 -400.858228)
		(width 0.14732)
		(layer "In2.Cu")
		(net "P5E_CPU0_PE4_TX_DP<11>")
	)
	(segment
		(start 313.40425 -335.011522)
		(end 313.40425 -342.52662)
		(width 0.14732)
		(layer "In2.Cu")
		(net "P5E_CPU0_PE4_TX_DP<11>")
	)
	(segment
		(start 313.720734 -344.323416)
		(end 320.68897 -359.012236)
		(width 0.14732)
		(layer "In2.Cu")
		(net "P5E_CPU0_PE4_TX_DP<11>")
	)
	(segment
		(start 337.144106 -397.604234)
		(end 337.315302 -398.006062)
		(width 0.14732)
		(layer "In2.Cu")
		(net "P5E_CPU0_PE4_TX_DP<11>")
	)
	(segment
		(start 346.506546 -290.419282)
		(end 346.506546 -290.634166)
		(width 0.0889)
		(layer "In2.Cu")
		(net "P5E_CPU0_PE4_TX_DP<11>")
	)
	(segment
		(start 337.420966 -398.571466)
		(end 337.584542 -398.637252)
		(width 0.14732)
		(layer "In2.Cu")
		(net "P5E_CPU0_PE4_TX_DP<11>")
	)
	(segment
		(start 347.942662 -285.661354)
		(end 348.099126 -285.390336)
		(width 0.0889)
		(layer "In2.Cu")
		(net "P5E_CPU0_PE4_TX_DP<11>")
	)
	(segment
		(start 345.368626 -302.347376)
		(end 336.164936 -311.550812)
		(width 0.14732)
		(layer "In2.Cu")
		(net "P5E_CPU0_PE4_TX_DP<11>")
	)
	(segment
		(start 336.164936 -311.550812)
		(end 334.37576 -312.74639)
		(width 0.14732)
		(layer "In2.Cu")
		(net "P5E_CPU0_PE4_TX_DP<11>")
	)
	(segment
		(start 336.98053 -397.538702)
		(end 337.144106 -397.604234)
		(width 0.14732)
		(layer "In2.Cu")
		(net "P5E_CPU0_PE4_TX_DP<11>")
	)
	(segment
		(start 347.656658 -286.801814)
		(end 347.654118 -286.803338)
		(width 0.0889)
		(layer "In2.Cu")
		(net "P5E_CPU0_PE4_TX_DP<11>")
	)
	(segment
		(start 346.464636 -290.698174)
		(end 346.464636 -299.701712)
		(width 0.14732)
		(layer "In2.Cu")
		(net "P5E_CPU0_PE4_TX_DP<11>")
	)
	(segment
		(start 346.506546 -290.634166)
		(end 346.464636 -290.676076)
		(width 0.0889)
		(layer "In2.Cu")
		(net "P5E_CPU0_PE4_TX_DP<11>")
	)
	(segment
		(start 337.584542 -398.637252)
		(end 337.96986 -399.540984)
		(width 0.14732)
		(layer "In2.Cu")
		(net "P5E_CPU0_PE4_TX_DP<11>")
	)
	(segment
		(start 336.80908 -397.13662)
		(end 336.98053 -397.538702)
		(width 0.14732)
		(layer "In2.Cu")
		(net "P5E_CPU0_PE4_TX_DP<11>")
	)
	(segment
		(start 346.437966 -288.898584)
		(end 346.437966 -289.114738)
		(width 0.0889)
		(layer "In2.Cu")
		(net "P5E_CPU0_PE4_TX_DP<11>")
	)
	(segment
		(start 347.659452 -286.80029)
		(end 347.656658 -286.801814)
		(width 0.0889)
		(layer "In2.Cu")
		(net "P5E_CPU0_PE4_TX_DP<11>")
	)
	(segment
		(start 337.970114 -399.541238)
		(end 337.970114 -400.563842)
		(width 0.14732)
		(layer "In2.Cu")
		(net "P5E_CPU0_PE4_TX_DP<11>")
	)
	(segment
		(start 348.13875 -285.980632)
		(end 348.12986 -285.985712)
		(width 0.0889)
		(layer "In2.Cu")
		(net "P5E_CPU0_PE4_TX_DP<11>")
	)
	(segment
		(start 337.96986 -399.540984)
		(end 337.970114 -399.541238)
		(width 0.14732)
		(layer "In2.Cu")
		(net "P5E_CPU0_PE4_TX_DP<11>")
	)
	(segment
		(start 337.24977 -398.169384)
		(end 337.420966 -398.571466)
		(width 0.14732)
		(layer "In2.Cu")
		(net "P5E_CPU0_PE4_TX_DP<11>")
	)
	(segment
		(start 346.907612 -289.645852)
		(end 346.907612 -290.018216)
		(width 0.0889)
		(layer "In2.Cu")
		(net "P5E_CPU0_PE4_TX_DP<11>")
	)
	(segment
		(start 346.464636 -299.701712)
		(end 345.368626 -302.347376)
		(width 0.14732)
		(layer "In2.Cu")
		(net "P5E_CPU0_PE4_TX_DP<11>")
	)
	(segment
		(start 334.37576 -312.74639)
		(end 314.31865 -332.803754)
		(width 0.14732)
		(layer "In2.Cu")
		(net "P5E_CPU0_PE4_TX_DP<11>")
	)
	(segment
		(start 346.729304 -288.422334)
		(end 346.720414 -288.427414)
		(width 0.0889)
		(layer "In2.Cu")
		(net "P5E_CPU0_PE4_TX_DP<11>")
	)
	(segment
		(start 337.315302 -398.006062)
		(end 337.24977 -398.169384)
		(width 0.14732)
		(layer "In2.Cu")
		(net "P5E_CPU0_PE4_TX_DP<11>")
	)
	(segment
		(start 346.907866 -288.087562)
		(end 346.907866 -288.103056)
		(width 0.0889)
		(layer "In2.Cu")
		(net "P5E_CPU0_PE4_TX_DP<11>")
	)
	(arc
		(start 347.654118 -286.803338)
		(mid 347.451531 -287.009689)
		(end 347.377512 -287.28924)
		(width 0.0889)
		(layer "In2.Cu")
		(net "P5E_CPU0_PE4_TX_DP<11>")
	)
	(arc
		(start 347.377512 -287.28924)
		(mid 347.329833 -287.47214)
		(end 347.19895 -287.608518)
		(width 0.0889)
		(layer "In2.Cu")
		(net "P5E_CPU0_PE4_TX_DP<11>")
	)
	(arc
		(start 347.19006 -287.613598)
		(mid 346.987237 -287.813829)
		(end 346.907866 -288.087562)
		(width 0.0889)
		(layer "In2.Cu")
		(net "P5E_CPU0_PE4_TX_DP<11>")
	)
	(arc
		(start 346.907866 -288.103056)
		(mid 346.860187 -288.285956)
		(end 346.729304 -288.422334)
		(width 0.0889)
		(layer "In2.Cu")
		(net "P5E_CPU0_PE4_TX_DP<11>")
	)
	(arc
		(start 346.720414 -288.427414)
		(mid 346.518128 -288.626395)
		(end 346.437966 -288.898584)
		(width 0.0889)
		(layer "In2.Cu")
		(net "P5E_CPU0_PE4_TX_DP<11>")
	)
	(arc
		(start 348.177358 -285.369508)
		(mid 348.280503 -285.499533)
		(end 348.317312 -285.661354)
		(width 0.0889)
		(layer "In2.Cu")
		(net "P5E_CPU0_PE4_TX_DP<11>")
	)
	(arc
		(start 348.12986 -285.985712)
		(mid 347.927574 -286.184693)
		(end 347.847412 -286.456882)
		(width 0.0889)
		(layer "In2.Cu")
		(net "P5E_CPU0_PE4_TX_DP<11>")
	)
	(arc
		(start 347.847412 -286.48406)
		(mid 347.795142 -286.666425)
		(end 347.660214 -286.799782)
		(width 0.0889)
		(layer "In2.Cu")
		(net "P5E_CPU0_PE4_TX_DP<11>")
	)
	(arc
		(start 348.317312 -285.661354)
		(mid 348.269633 -285.844254)
		(end 348.13875 -285.980632)
		(width 0.0889)
		(layer "In2.Cu")
		(net "P5E_CPU0_PE4_TX_DP<11>")
	)
	(arc
		(start 346.723462 -289.446462)
		(mid 346.832609 -289.53039)
		(end 346.907612 -289.645852)
		(width 0.0889)
		(layer "In2.Cu")
		(net "P5E_CPU0_PE4_TX_DP<11>")
	)
	(arc
		(start 346.437966 -289.114738)
		(mid 346.549304 -289.307638)
		(end 346.723462 -289.446462)
		(width 0.0889)
		(layer "In2.Cu")
		(net "P5E_CPU0_PE4_TX_DP<11>")
	)
	(segment
		(start 347.472762 -286.47517)
		(end 347.473016 -286.475424)
		(width 0.13208)
		(layer "F.Cu")
		(net "P5E_CPU0_PE4_TX_DP<10>")
	)
	(segment
		(start 347.472762 -285.939484)
		(end 347.472762 -286.47517)
		(width 0.13208)
		(layer "F.Cu")
		(net "P5E_CPU0_PE4_TX_DP<10>")
	)
	(segment
		(start 335.17713 -401.779994)
		(end 335.501488 -402.104352)
		(width 0.13208)
		(layer "F.Cu")
		(net "P5E_CPU0_PE4_TX_DP<10>")
	)
	(segment
		(start 335.476088 -400.858228)
		(end 335.17713 -401.157186)
		(width 0.13208)
		(layer "F.Cu")
		(net "P5E_CPU0_PE4_TX_DP<10>")
	)
	(segment
		(start 335.17713 -401.157186)
		(end 335.17713 -401.779994)
		(width 0.13208)
		(layer "F.Cu")
		(net "P5E_CPU0_PE4_TX_DP<10>")
	)
	(segment
		(start 345.876118 -288.592768)
		(end 345.867228 -288.597848)
		(width 0.0889)
		(layer "In2.Cu")
		(net "P5E_CPU0_PE4_TX_DP<10>")
	)
	(segment
		(start 346.815664 -286.964882)
		(end 346.806774 -286.969962)
		(width 0.0889)
		(layer "In2.Cu")
		(net "P5E_CPU0_PE4_TX_DP<10>")
	)
	(segment
		(start 346.628212 -287.28924)
		(end 346.628212 -287.304734)
		(width 0.0889)
		(layer "In2.Cu")
		(net "P5E_CPU0_PE4_TX_DP<10>")
	)
	(segment
		(start 334.563974 -397.449294)
		(end 334.494378 -397.607028)
		(width 0.14732)
		(layer "In2.Cu")
		(net "P5E_CPU0_PE4_TX_DP<10>")
	)
	(segment
		(start 335.181448 -399.3769)
		(end 335.181448 -400.563588)
		(width 0.14732)
		(layer "In2.Cu")
		(net "P5E_CPU0_PE4_TX_DP<10>")
	)
	(segment
		(start 347.316552 -286.204406)
		(end 347.23832 -286.183578)
		(width 0.0889)
		(layer "In2.Cu")
		(net "P5E_CPU0_PE4_TX_DP<10>")
	)
	(segment
		(start 334.494378 -397.607028)
		(end 334.652366 -398.01419)
		(width 0.14732)
		(layer "In2.Cu")
		(net "P5E_CPU0_PE4_TX_DP<10>")
	)
	(segment
		(start 313.055762 -344.46591)
		(end 319.68948 -359.477564)
		(width 0.14732)
		(layer "In2.Cu")
		(net "P5E_CPU0_PE4_TX_DP<10>")
	)
	(segment
		(start 346.158312 -290.293298)
		(end 345.764612 -290.52647)
		(width 0.0889)
		(layer "In2.Cu")
		(net "P5E_CPU0_PE4_TX_DP<10>")
	)
	(segment
		(start 345.688666 -288.917126)
		(end 345.688666 -289.078416)
		(width 0.0889)
		(layer "In2.Cu")
		(net "P5E_CPU0_PE4_TX_DP<10>")
	)
	(segment
		(start 312.74893 -334.829658)
		(end 312.74893 -342.725248)
		(width 0.14732)
		(layer "In2.Cu")
		(net "P5E_CPU0_PE4_TX_DP<10>")
	)
	(segment
		(start 346.346018 -287.778698)
		(end 346.337128 -287.783778)
		(width 0.0889)
		(layer "In2.Cu")
		(net "P5E_CPU0_PE4_TX_DP<10>")
	)
	(segment
		(start 334.247744 -396.972282)
		(end 334.405732 -397.041878)
		(width 0.14732)
		(layer "In2.Cu")
		(net "P5E_CPU0_PE4_TX_DP<10>")
	)
	(segment
		(start 334.652366 -398.01419)
		(end 334.652366 -398.014444)
		(width 0.14732)
		(layer "In2.Cu")
		(net "P5E_CPU0_PE4_TX_DP<10>")
	)
	(segment
		(start 346.158566 -288.103056)
		(end 346.158566 -288.121598)
		(width 0.0889)
		(layer "In2.Cu")
		(net "P5E_CPU0_PE4_TX_DP<10>")
	)
	(segment
		(start 335.754472 -310.988202)
		(end 334.094836 -312.097166)
		(width 0.14732)
		(layer "In2.Cu")
		(net "P5E_CPU0_PE4_TX_DP<10>")
	)
	(segment
		(start 334.968596 -398.491456)
		(end 334.899 -398.64919)
		(width 0.14732)
		(layer "In2.Cu")
		(net "P5E_CPU0_PE4_TX_DP<10>")
	)
	(segment
		(start 345.764612 -290.939982)
		(end 345.806776 -290.982146)
		(width 0.0889)
		(layer "In2.Cu")
		(net "P5E_CPU0_PE4_TX_DP<10>")
	)
	(segment
		(start 346.158312 -289.60953)
		(end 346.158312 -290.293298)
		(width 0.0889)
		(layer "In2.Cu")
		(net "P5E_CPU0_PE4_TX_DP<10>")
	)
	(segment
		(start 345.806776 -299.563282)
		(end 344.83675 -301.90567)
		(width 0.14732)
		(layer "In2.Cu")
		(net "P5E_CPU0_PE4_TX_DP<10>")
	)
	(segment
		(start 345.806776 -290.982146)
		(end 345.806776 -291.004244)
		(width 0.0889)
		(layer "In2.Cu")
		(net "P5E_CPU0_PE4_TX_DP<10>")
	)
	(segment
		(start 334.652366 -398.014444)
		(end 334.810354 -398.08404)
		(width 0.14732)
		(layer "In2.Cu")
		(net "P5E_CPU0_PE4_TX_DP<10>")
	)
	(segment
		(start 334.094836 -312.097166)
		(end 313.729116 -332.46314)
		(width 0.14732)
		(layer "In2.Cu")
		(net "P5E_CPU0_PE4_TX_DP<10>")
	)
	(segment
		(start 334.405732 -397.041878)
		(end 334.563974 -397.449294)
		(width 0.14732)
		(layer "In2.Cu")
		(net "P5E_CPU0_PE4_TX_DP<10>")
	)
	(segment
		(start 344.83675 -301.90567)
		(end 335.754472 -310.988202)
		(width 0.14732)
		(layer "In2.Cu")
		(net "P5E_CPU0_PE4_TX_DP<10>")
	)
	(segment
		(start 334.899 -398.64919)
		(end 335.181448 -399.3769)
		(width 0.14732)
		(layer "In2.Cu")
		(net "P5E_CPU0_PE4_TX_DP<10>")
	)
	(segment
		(start 313.729116 -332.46314)
		(end 312.74893 -334.829658)
		(width 0.14732)
		(layer "In2.Cu")
		(net "P5E_CPU0_PE4_TX_DP<10>")
	)
	(segment
		(start 335.181448 -400.563588)
		(end 335.476088 -400.858228)
		(width 0.14732)
		(layer "In2.Cu")
		(net "P5E_CPU0_PE4_TX_DP<10>")
	)
	(segment
		(start 345.764612 -290.52647)
		(end 345.764612 -290.939982)
		(width 0.0889)
		(layer "In2.Cu")
		(net "P5E_CPU0_PE4_TX_DP<10>")
	)
	(segment
		(start 334.810354 -398.08404)
		(end 334.968596 -398.491456)
		(width 0.14732)
		(layer "In2.Cu")
		(net "P5E_CPU0_PE4_TX_DP<10>")
	)
	(segment
		(start 319.68948 -359.477564)
		(end 334.247744 -396.972282)
		(width 0.14732)
		(layer "In2.Cu")
		(net "P5E_CPU0_PE4_TX_DP<10>")
	)
	(segment
		(start 312.74893 -342.725248)
		(end 313.055762 -344.46591)
		(width 0.14732)
		(layer "In2.Cu")
		(net "P5E_CPU0_PE4_TX_DP<10>")
	)
	(segment
		(start 347.473016 -286.475424)
		(end 347.316552 -286.204406)
		(width 0.0889)
		(layer "In2.Cu")
		(net "P5E_CPU0_PE4_TX_DP<10>")
	)
	(segment
		(start 346.827856 -286.95777)
		(end 346.815664 -286.964882)
		(width 0.0889)
		(layer "In2.Cu")
		(net "P5E_CPU0_PE4_TX_DP<10>")
	)
	(segment
		(start 345.806776 -291.004244)
		(end 345.806776 -299.563282)
		(width 0.14732)
		(layer "In2.Cu")
		(net "P5E_CPU0_PE4_TX_DP<10>")
	)
	(arc
		(start 346.337128 -287.783778)
		(mid 346.206214 -287.920138)
		(end 346.158566 -288.103056)
		(width 0.0889)
		(layer "In2.Cu")
		(net "P5E_CPU0_PE4_TX_DP<10>")
	)
	(arc
		(start 346.628212 -287.304734)
		(mid 346.548842 -287.578468)
		(end 346.346018 -287.778698)
		(width 0.0889)
		(layer "In2.Cu")
		(net "P5E_CPU0_PE4_TX_DP<10>")
	)
	(arc
		(start 346.158566 -288.121598)
		(mid 346.078404 -288.393787)
		(end 345.876118 -288.592768)
		(width 0.0889)
		(layer "In2.Cu")
		(net "P5E_CPU0_PE4_TX_DP<10>")
	)
	(arc
		(start 345.867228 -288.597848)
		(mid 345.736314 -288.734208)
		(end 345.688666 -288.917126)
		(width 0.0889)
		(layer "In2.Cu")
		(net "P5E_CPU0_PE4_TX_DP<10>")
	)
	(arc
		(start 345.688666 -289.078416)
		(mid 345.763671 -289.193875)
		(end 345.872816 -289.277806)
		(width 0.0889)
		(layer "In2.Cu")
		(net "P5E_CPU0_PE4_TX_DP<10>")
	)
	(arc
		(start 345.872816 -289.277806)
		(mid 346.046948 -289.416653)
		(end 346.158312 -289.60953)
		(width 0.0889)
		(layer "In2.Cu")
		(net "P5E_CPU0_PE4_TX_DP<10>")
	)
	(arc
		(start 347.23832 -286.183578)
		(mid 347.135175 -286.313603)
		(end 347.098366 -286.475424)
		(width 0.0889)
		(layer "In2.Cu")
		(net "P5E_CPU0_PE4_TX_DP<10>")
	)
	(arc
		(start 347.098366 -286.475424)
		(mid 347.026131 -286.751948)
		(end 346.827856 -286.95777)
		(width 0.0889)
		(layer "In2.Cu")
		(net "P5E_CPU0_PE4_TX_DP<10>")
	)
	(arc
		(start 346.806774 -286.969962)
		(mid 346.67586 -287.106322)
		(end 346.628212 -287.28924)
		(width 0.0889)
		(layer "In2.Cu")
		(net "P5E_CPU0_PE4_TX_DP<10>")
	)
	(segment
		(start 304.54473 -401.779994)
		(end 304.869088 -402.104352)
		(width 0.13208)
		(layer "F.Cu")
		(net "P5E_CPU0_PE4_TX_DP<0>")
	)
	(segment
		(start 304.54473 -401.157186)
		(end 304.54473 -401.779994)
		(width 0.13208)
		(layer "F.Cu")
		(net "P5E_CPU0_PE4_TX_DP<0>")
	)
	(segment
		(start 338.074762 -285.939484)
		(end 338.074762 -286.475424)
		(width 0.13208)
		(layer "F.Cu")
		(net "P5E_CPU0_PE4_TX_DP<0>")
	)
	(segment
		(start 304.843688 -400.858228)
		(end 304.54473 -401.157186)
		(width 0.13208)
		(layer "F.Cu")
		(net "P5E_CPU0_PE4_TX_DP<0>")
	)
	(segment
		(start 305.246024 -397.358616)
		(end 305.325526 -397.515334)
		(width 0.14732)
		(layer "In2.Cu")
		(net "P5E_CPU0_PE4_TX_DP<0>")
	)
	(segment
		(start 301.592996 -327.879202)
		(end 303.276 -341.521288)
		(width 0.14732)
		(layer "In2.Cu")
		(net "P5E_CPU0_PE4_TX_DP<0>")
	)
	(segment
		(start 311.620662 -318.912748)
		(end 311.036462 -318.963802)
		(width 0.14732)
		(layer "In2.Cu")
		(net "P5E_CPU0_PE4_TX_DP<0>")
	)
	(segment
		(start 301.815246 -326.15886)
		(end 301.592996 -326.862948)
		(width 0.14732)
		(layer "In2.Cu")
		(net "P5E_CPU0_PE4_TX_DP<0>")
	)
	(segment
		(start 337.42376 -286.961326)
		(end 337.408774 -286.969962)
		(width 0.0889)
		(layer "In2.Cu")
		(net "P5E_CPU0_PE4_TX_DP<0>")
	)
	(segment
		(start 336.760312 -288.103056)
		(end 336.760312 -288.11728)
		(width 0.0889)
		(layer "In2.Cu")
		(net "P5E_CPU0_PE4_TX_DP<0>")
	)
	(segment
		(start 305.47818 -396.6464)
		(end 305.246024 -397.358616)
		(width 0.14732)
		(layer "In2.Cu")
		(net "P5E_CPU0_PE4_TX_DP<0>")
	)
	(segment
		(start 336.332576 -289.582606)
		(end 336.332576 -290.411154)
		(width 0.14732)
		(layer "In2.Cu")
		(net "P5E_CPU0_PE4_TX_DP<0>")
	)
	(segment
		(start 304.549048 -400.563588)
		(end 304.843688 -400.858228)
		(width 0.14732)
		(layer "In2.Cu")
		(net "P5E_CPU0_PE4_TX_DP<0>")
	)
	(segment
		(start 311.036462 -318.963802)
		(end 308.554374 -319.401698)
		(width 0.14732)
		(layer "In2.Cu")
		(net "P5E_CPU0_PE4_TX_DP<0>")
	)
	(segment
		(start 315.012324 -317.91783)
		(end 312.610246 -318.912748)
		(width 0.14732)
		(layer "In2.Cu")
		(net "P5E_CPU0_PE4_TX_DP<0>")
	)
	(segment
		(start 305.707034 -385.758182)
		(end 305.47818 -396.6464)
		(width 0.14732)
		(layer "In2.Cu")
		(net "P5E_CPU0_PE4_TX_DP<0>")
	)
	(segment
		(start 337.918298 -286.204406)
		(end 337.84032 -286.183578)
		(width 0.0889)
		(layer "In2.Cu")
		(net "P5E_CPU0_PE4_TX_DP<0>")
	)
	(segment
		(start 336.947764 -287.778698)
		(end 336.938874 -287.783778)
		(width 0.0889)
		(layer "In2.Cu")
		(net "P5E_CPU0_PE4_TX_DP<0>")
	)
	(segment
		(start 336.290412 -288.907728)
		(end 336.290412 -289.518344)
		(width 0.0889)
		(layer "In2.Cu")
		(net "P5E_CPU0_PE4_TX_DP<0>")
	)
	(segment
		(start 303.630076 -345.594178)
		(end 305.53406 -361.719622)
		(width 0.14732)
		(layer "In2.Cu")
		(net "P5E_CPU0_PE4_TX_DP<0>")
	)
	(segment
		(start 303.276 -343.5858)
		(end 303.630076 -345.594178)
		(width 0.14732)
		(layer "In2.Cu")
		(net "P5E_CPU0_PE4_TX_DP<0>")
	)
	(segment
		(start 336.290412 -289.518344)
		(end 336.332576 -289.560508)
		(width 0.0889)
		(layer "In2.Cu")
		(net "P5E_CPU0_PE4_TX_DP<0>")
	)
	(segment
		(start 305.190144 -397.931132)
		(end 305.032918 -398.010634)
		(width 0.14732)
		(layer "In2.Cu")
		(net "P5E_CPU0_PE4_TX_DP<0>")
	)
	(segment
		(start 305.325526 -397.515334)
		(end 305.190144 -397.931132)
		(width 0.14732)
		(layer "In2.Cu")
		(net "P5E_CPU0_PE4_TX_DP<0>")
	)
	(segment
		(start 336.332576 -289.560508)
		(end 336.332576 -289.582606)
		(width 0.0889)
		(layer "In2.Cu")
		(net "P5E_CPU0_PE4_TX_DP<0>")
	)
	(segment
		(start 337.230212 -287.28924)
		(end 337.230212 -287.299146)
		(width 0.0889)
		(layer "In2.Cu")
		(net "P5E_CPU0_PE4_TX_DP<0>")
	)
	(segment
		(start 304.615596 -322.159884)
		(end 301.815246 -326.15886)
		(width 0.14732)
		(layer "In2.Cu")
		(net "P5E_CPU0_PE4_TX_DP<0>")
	)
	(segment
		(start 303.276 -341.521288)
		(end 303.276 -343.5858)
		(width 0.14732)
		(layer "In2.Cu")
		(net "P5E_CPU0_PE4_TX_DP<0>")
	)
	(segment
		(start 301.592996 -326.862948)
		(end 301.592996 -327.879202)
		(width 0.14732)
		(layer "In2.Cu")
		(net "P5E_CPU0_PE4_TX_DP<0>")
	)
	(segment
		(start 304.549048 -399.493232)
		(end 304.549048 -400.563588)
		(width 0.14732)
		(layer "In2.Cu")
		(net "P5E_CPU0_PE4_TX_DP<0>")
	)
	(segment
		(start 308.554374 -319.401698)
		(end 304.615596 -322.159884)
		(width 0.14732)
		(layer "In2.Cu")
		(net "P5E_CPU0_PE4_TX_DP<0>")
	)
	(segment
		(start 336.332576 -290.411154)
		(end 332.950566 -293.793164)
		(width 0.14732)
		(layer "In2.Cu")
		(net "P5E_CPU0_PE4_TX_DP<0>")
	)
	(segment
		(start 337.700366 -286.466788)
		(end 337.700366 -286.475424)
		(width 0.0889)
		(layer "In2.Cu")
		(net "P5E_CPU0_PE4_TX_DP<0>")
	)
	(segment
		(start 304.977292 -398.582642)
		(end 304.841656 -398.99844)
		(width 0.14732)
		(layer "In2.Cu")
		(net "P5E_CPU0_PE4_TX_DP<0>")
	)
	(segment
		(start 304.897536 -398.425924)
		(end 304.977292 -398.582642)
		(width 0.14732)
		(layer "In2.Cu")
		(net "P5E_CPU0_PE4_TX_DP<0>")
	)
	(segment
		(start 336.47761 -288.592768)
		(end 336.46872 -288.597848)
		(width 0.0889)
		(layer "In2.Cu")
		(net "P5E_CPU0_PE4_TX_DP<0>")
	)
	(segment
		(start 304.841656 -398.99844)
		(end 304.68443 -399.077942)
		(width 0.14732)
		(layer "In2.Cu")
		(net "P5E_CPU0_PE4_TX_DP<0>")
	)
	(segment
		(start 304.68443 -399.077942)
		(end 304.549048 -399.493232)
		(width 0.14732)
		(layer "In2.Cu")
		(net "P5E_CPU0_PE4_TX_DP<0>")
	)
	(segment
		(start 338.074762 -286.475424)
		(end 337.918298 -286.204406)
		(width 0.0889)
		(layer "In2.Cu")
		(net "P5E_CPU0_PE4_TX_DP<0>")
	)
	(segment
		(start 312.610246 -318.912748)
		(end 311.620662 -318.912748)
		(width 0.14732)
		(layer "In2.Cu")
		(net "P5E_CPU0_PE4_TX_DP<0>")
	)
	(segment
		(start 305.53406 -361.719622)
		(end 305.707034 -385.758182)
		(width 0.14732)
		(layer "In2.Cu")
		(net "P5E_CPU0_PE4_TX_DP<0>")
	)
	(segment
		(start 326.22871 -306.701698)
		(end 315.012324 -317.91783)
		(width 0.14732)
		(layer "In2.Cu")
		(net "P5E_CPU0_PE4_TX_DP<0>")
	)
	(segment
		(start 332.950566 -293.793164)
		(end 326.22871 -306.701698)
		(width 0.14732)
		(layer "In2.Cu")
		(net "P5E_CPU0_PE4_TX_DP<0>")
	)
	(segment
		(start 305.032918 -398.010634)
		(end 304.897536 -398.425924)
		(width 0.14732)
		(layer "In2.Cu")
		(net "P5E_CPU0_PE4_TX_DP<0>")
	)
	(arc
		(start 337.700366 -286.475424)
		(mid 337.626375 -286.75499)
		(end 337.42376 -286.961326)
		(width 0.0889)
		(layer "In2.Cu")
		(net "P5E_CPU0_PE4_TX_DP<0>")
	)
	(arc
		(start 337.84032 -286.183578)
		(mid 337.738999 -286.309699)
		(end 337.700366 -286.466788)
		(width 0.0889)
		(layer "In2.Cu")
		(net "P5E_CPU0_PE4_TX_DP<0>")
	)
	(arc
		(start 336.760312 -288.11728)
		(mid 336.681093 -288.391965)
		(end 336.47761 -288.592768)
		(width 0.0889)
		(layer "In2.Cu")
		(net "P5E_CPU0_PE4_TX_DP<0>")
	)
	(arc
		(start 336.938874 -287.783778)
		(mid 336.80796 -287.920138)
		(end 336.760312 -288.103056)
		(width 0.0889)
		(layer "In2.Cu")
		(net "P5E_CPU0_PE4_TX_DP<0>")
	)
	(arc
		(start 336.46872 -288.597848)
		(mid 336.34021 -288.73015)
		(end 336.290412 -288.907728)
		(width 0.0889)
		(layer "In2.Cu")
		(net "P5E_CPU0_PE4_TX_DP<0>")
	)
	(arc
		(start 337.230212 -287.299146)
		(mid 337.152101 -287.576095)
		(end 336.947764 -287.778698)
		(width 0.0889)
		(layer "In2.Cu")
		(net "P5E_CPU0_PE4_TX_DP<0>")
	)
	(arc
		(start 337.408774 -286.969962)
		(mid 337.27786 -287.106322)
		(end 337.230212 -287.28924)
		(width 0.0889)
		(layer "In2.Cu")
		(net "P5E_CPU0_PE4_TX_DP<0>")
	)
	(segment
		(start 346.063316 -285.125414)
		(end 346.063316 -285.6611)
		(width 0.13208)
		(layer "F.Cu")
		(net "P5E_CPU0_PE4_TX_DN<9>")
	)
	(segment
		(start 331.85481 -401.777962)
		(end 331.52842 -402.104352)
		(width 0.13208)
		(layer "F.Cu")
		(net "P5E_CPU0_PE4_TX_DN<9>")
	)
	(segment
		(start 346.063316 -285.6611)
		(end 346.063062 -285.661354)
		(width 0.13208)
		(layer "F.Cu")
		(net "P5E_CPU0_PE4_TX_DN<9>")
	)
	(segment
		(start 331.549248 -400.858228)
		(end 331.85481 -401.16379)
		(width 0.13208)
		(layer "F.Cu")
		(net "P5E_CPU0_PE4_TX_DN<9>")
	)
	(segment
		(start 331.85481 -401.16379)
		(end 331.85481 -401.777962)
		(width 0.13208)
		(layer "F.Cu")
		(net "P5E_CPU0_PE4_TX_DN<9>")
	)
	(segment
		(start 331.52842 -402.104352)
		(end 331.523848 -402.104352)
		(width 0.13208)
		(layer "F.Cu")
		(net "P5E_CPU0_PE4_TX_DN<9>")
	)
	(segment
		(start 331.272896 -397.71955)
		(end 331.416914 -398.131792)
		(width 0.14732)
		(layer "In2.Cu")
		(net "P5E_CPU0_PE4_TX_DN<9>")
	)
	(segment
		(start 345.780614 -286.799782)
		(end 345.774518 -286.803338)
		(width 0.0889)
		(layer "In2.Cu")
		(net "P5E_CPU0_PE4_TX_DN<9>")
	)
	(segment
		(start 331.643482 -398.779238)
		(end 331.843634 -399.351754)
		(width 0.14732)
		(layer "In2.Cu")
		(net "P5E_CPU0_PE4_TX_DN<9>")
	)
	(segment
		(start 344.642186 -290.482274)
		(end 344.642186 -290.697158)
		(width 0.0889)
		(layer "In2.Cu")
		(net "P5E_CPU0_PE4_TX_DN<9>")
	)
	(segment
		(start 317.97117 -359.68813)
		(end 331.046074 -397.07185)
		(width 0.14732)
		(layer "In2.Cu")
		(net "P5E_CPU0_PE4_TX_DN<9>")
	)
	(segment
		(start 345.028012 -290.096448)
		(end 344.642186 -290.482274)
		(width 0.0889)
		(layer "In2.Cu")
		(net "P5E_CPU0_PE4_TX_DN<9>")
	)
	(segment
		(start 344.642186 -290.697158)
		(end 344.600276 -290.739068)
		(width 0.0889)
		(layer "In2.Cu")
		(net "P5E_CPU0_PE4_TX_DN<9>")
	)
	(segment
		(start 344.600276 -290.761166)
		(end 344.600276 -299.319188)
		(width 0.14732)
		(layer "In2.Cu")
		(net "P5E_CPU0_PE4_TX_DN<9>")
	)
	(segment
		(start 331.046074 -397.07185)
		(end 330.969874 -397.2306)
		(width 0.14732)
		(layer "In2.Cu")
		(net "P5E_CPU0_PE4_TX_DN<9>")
	)
	(segment
		(start 331.843888 -399.352008)
		(end 331.843888 -400.563588)
		(width 0.14732)
		(layer "In2.Cu")
		(net "P5E_CPU0_PE4_TX_DN<9>")
	)
	(segment
		(start 345.967812 -286.456882)
		(end 345.967812 -286.48406)
		(width 0.0889)
		(layer "In2.Cu")
		(net "P5E_CPU0_PE4_TX_DN<9>")
	)
	(segment
		(start 344.600276 -290.739068)
		(end 344.600276 -290.761166)
		(width 0.0889)
		(layer "In2.Cu")
		(net "P5E_CPU0_PE4_TX_DN<9>")
	)
	(segment
		(start 345.31935 -287.608518)
		(end 345.31046 -287.613598)
		(width 0.0889)
		(layer "In2.Cu")
		(net "P5E_CPU0_PE4_TX_DN<9>")
	)
	(segment
		(start 344.600276 -299.319188)
		(end 343.839546 -301.155608)
		(width 0.14732)
		(layer "In2.Cu")
		(net "P5E_CPU0_PE4_TX_DN<9>")
	)
	(segment
		(start 312.671206 -331.816964)
		(end 311.543192 -334.540352)
		(width 0.14732)
		(layer "In2.Cu")
		(net "P5E_CPU0_PE4_TX_DN<9>")
	)
	(segment
		(start 345.028266 -288.087562)
		(end 345.028266 -288.103056)
		(width 0.0889)
		(layer "In2.Cu")
		(net "P5E_CPU0_PE4_TX_DN<9>")
	)
	(segment
		(start 346.219526 -285.390336)
		(end 346.297758 -285.369508)
		(width 0.0889)
		(layer "In2.Cu")
		(net "P5E_CPU0_PE4_TX_DN<9>")
	)
	(segment
		(start 344.849704 -288.422334)
		(end 344.840814 -288.427414)
		(width 0.0889)
		(layer "In2.Cu")
		(net "P5E_CPU0_PE4_TX_DN<9>")
	)
	(segment
		(start 345.028012 -289.752024)
		(end 345.028012 -290.096448)
		(width 0.0889)
		(layer "In2.Cu")
		(net "P5E_CPU0_PE4_TX_DN<9>")
	)
	(segment
		(start 346.063062 -285.661354)
		(end 346.219526 -285.390336)
		(width 0.0889)
		(layer "In2.Cu")
		(net "P5E_CPU0_PE4_TX_DN<9>")
	)
	(segment
		(start 331.416914 -398.131792)
		(end 331.34046 -398.290288)
		(width 0.14732)
		(layer "In2.Cu")
		(net "P5E_CPU0_PE4_TX_DN<9>")
	)
	(segment
		(start 331.484732 -398.703038)
		(end 331.643482 -398.779238)
		(width 0.14732)
		(layer "In2.Cu")
		(net "P5E_CPU0_PE4_TX_DN<9>")
	)
	(segment
		(start 346.25915 -285.980632)
		(end 346.25026 -285.985712)
		(width 0.0889)
		(layer "In2.Cu")
		(net "P5E_CPU0_PE4_TX_DN<9>")
	)
	(segment
		(start 333.404464 -311.083452)
		(end 312.671206 -331.816964)
		(width 0.14732)
		(layer "In2.Cu")
		(net "P5E_CPU0_PE4_TX_DN<9>")
	)
	(segment
		(start 331.34046 -398.290288)
		(end 331.484732 -398.703038)
		(width 0.14732)
		(layer "In2.Cu")
		(net "P5E_CPU0_PE4_TX_DN<9>")
	)
	(segment
		(start 343.839546 -301.155608)
		(end 334.933544 -310.061864)
		(width 0.14732)
		(layer "In2.Cu")
		(net "P5E_CPU0_PE4_TX_DN<9>")
	)
	(segment
		(start 331.113892 -397.643096)
		(end 331.272896 -397.71955)
		(width 0.14732)
		(layer "In2.Cu")
		(net "P5E_CPU0_PE4_TX_DN<9>")
	)
	(segment
		(start 311.90184 -344.866722)
		(end 317.97117 -359.68813)
		(width 0.14732)
		(layer "In2.Cu")
		(net "P5E_CPU0_PE4_TX_DN<9>")
	)
	(segment
		(start 330.969874 -397.2306)
		(end 331.113892 -397.643096)
		(width 0.14732)
		(layer "In2.Cu")
		(net "P5E_CPU0_PE4_TX_DN<9>")
	)
	(segment
		(start 331.843888 -400.563588)
		(end 331.549248 -400.858228)
		(width 0.14732)
		(layer "In2.Cu")
		(net "P5E_CPU0_PE4_TX_DN<9>")
	)
	(segment
		(start 311.543192 -334.540352)
		(end 311.543192 -342.831166)
		(width 0.14732)
		(layer "In2.Cu")
		(net "P5E_CPU0_PE4_TX_DN<9>")
	)
	(segment
		(start 334.933544 -310.061864)
		(end 333.404464 -311.083452)
		(width 0.14732)
		(layer "In2.Cu")
		(net "P5E_CPU0_PE4_TX_DN<9>")
	)
	(segment
		(start 311.543192 -342.831166)
		(end 311.90184 -344.866722)
		(width 0.14732)
		(layer "In2.Cu")
		(net "P5E_CPU0_PE4_TX_DN<9>")
	)
	(segment
		(start 331.843634 -399.351754)
		(end 331.843888 -399.352008)
		(width 0.14732)
		(layer "In2.Cu")
		(net "P5E_CPU0_PE4_TX_DN<9>")
	)
	(segment
		(start 344.558366 -288.898584)
		(end 344.558366 -289.114738)
		(width 0.0889)
		(layer "In2.Cu")
		(net "P5E_CPU0_PE4_TX_DN<9>")
	)
	(arc
		(start 344.843862 -289.446462)
		(mid 344.97847 -289.573623)
		(end 345.028012 -289.752024)
		(width 0.0889)
		(layer "In2.Cu")
		(net "P5E_CPU0_PE4_TX_DN<9>")
	)
	(arc
		(start 346.437458 -285.6738)
		(mid 346.386908 -285.849638)
		(end 346.25915 -285.980632)
		(width 0.0889)
		(layer "In2.Cu")
		(net "P5E_CPU0_PE4_TX_DN<9>")
	)
	(arc
		(start 344.558366 -289.114738)
		(mid 344.669704 -289.307638)
		(end 344.843862 -289.446462)
		(width 0.0889)
		(layer "In2.Cu")
		(net "P5E_CPU0_PE4_TX_DN<9>")
	)
	(arc
		(start 346.297758 -285.369508)
		(mid 346.398587 -285.494984)
		(end 346.437458 -285.651194)
		(width 0.0889)
		(layer "In2.Cu")
		(net "P5E_CPU0_PE4_TX_DN<9>")
	)
	(arc
		(start 346.25026 -285.985712)
		(mid 346.047974 -286.184693)
		(end 345.967812 -286.456882)
		(width 0.0889)
		(layer "In2.Cu")
		(net "P5E_CPU0_PE4_TX_DN<9>")
	)
	(arc
		(start 344.840814 -288.427414)
		(mid 344.638528 -288.626395)
		(end 344.558366 -288.898584)
		(width 0.0889)
		(layer "In2.Cu")
		(net "P5E_CPU0_PE4_TX_DN<9>")
	)
	(arc
		(start 345.967812 -286.48406)
		(mid 345.915542 -286.666425)
		(end 345.780614 -286.799782)
		(width 0.0889)
		(layer "In2.Cu")
		(net "P5E_CPU0_PE4_TX_DN<9>")
	)
	(arc
		(start 346.437458 -285.651194)
		(mid 346.437632 -285.662497)
		(end 346.437458 -285.6738)
		(width 0.0889)
		(layer "In2.Cu")
		(net "P5E_CPU0_PE4_TX_DN<9>")
	)
	(arc
		(start 345.31046 -287.613598)
		(mid 345.107637 -287.813829)
		(end 345.028266 -288.087562)
		(width 0.0889)
		(layer "In2.Cu")
		(net "P5E_CPU0_PE4_TX_DN<9>")
	)
	(arc
		(start 345.497912 -287.28924)
		(mid 345.450233 -287.47214)
		(end 345.31935 -287.608518)
		(width 0.0889)
		(layer "In2.Cu")
		(net "P5E_CPU0_PE4_TX_DN<9>")
	)
	(arc
		(start 345.774518 -286.803338)
		(mid 345.571931 -287.009689)
		(end 345.497912 -287.28924)
		(width 0.0889)
		(layer "In2.Cu")
		(net "P5E_CPU0_PE4_TX_DN<9>")
	)
	(arc
		(start 345.028266 -288.103056)
		(mid 344.980587 -288.285956)
		(end 344.849704 -288.422334)
		(width 0.0889)
		(layer "In2.Cu")
		(net "P5E_CPU0_PE4_TX_DN<9>")
	)
	(segment
		(start 328.79157 -401.777962)
		(end 328.46518 -402.104352)
		(width 0.13208)
		(layer "F.Cu")
		(net "P5E_CPU0_PE4_TX_DN<8>")
	)
	(segment
		(start 328.79157 -401.16379)
		(end 328.79157 -401.777962)
		(width 0.13208)
		(layer "F.Cu")
		(net "P5E_CPU0_PE4_TX_DN<8>")
	)
	(segment
		(start 328.46518 -402.104352)
		(end 328.460608 -402.104352)
		(width 0.13208)
		(layer "F.Cu")
		(net "P5E_CPU0_PE4_TX_DN<8>")
	)
	(segment
		(start 345.123516 -285.125414)
		(end 345.123516 -285.6611)
		(width 0.13208)
		(layer "F.Cu")
		(net "P5E_CPU0_PE4_TX_DN<8>")
	)
	(segment
		(start 328.486008 -400.858228)
		(end 328.79157 -401.16379)
		(width 0.13208)
		(layer "F.Cu")
		(net "P5E_CPU0_PE4_TX_DN<8>")
	)
	(segment
		(start 345.123516 -285.6611)
		(end 345.123262 -285.661354)
		(width 0.13208)
		(layer "F.Cu")
		(net "P5E_CPU0_PE4_TX_DN<8>")
	)
	(segment
		(start 343.69756 -290.660328)
		(end 343.69756 -290.945316)
		(width 0.0889)
		(layer "In2.Cu")
		(net "P5E_CPU0_PE4_TX_DN<8>")
	)
	(segment
		(start 343.65565 -291.009324)
		(end 343.65565 -299.094906)
		(width 0.14732)
		(layer "In2.Cu")
		(net "P5E_CPU0_PE4_TX_DN<8>")
	)
	(segment
		(start 344.088466 -290.07816)
		(end 343.69756 -290.660328)
		(width 0.0889)
		(layer "In2.Cu")
		(net "P5E_CPU0_PE4_TX_DN<8>")
	)
	(segment
		(start 343.893394 -288.432494)
		(end 343.887806 -288.435796)
		(width 0.0889)
		(layer "In2.Cu")
		(net "P5E_CPU0_PE4_TX_DN<8>")
	)
	(segment
		(start 345.255596 -286.021526)
		(end 345.256104 -286.021272)
		(width 0.0889)
		(layer "In2.Cu")
		(net "P5E_CPU0_PE4_TX_DN<8>")
	)
	(segment
		(start 343.018872 -300.632368)
		(end 334.380586 -309.270908)
		(width 0.14732)
		(layer "In2.Cu")
		(net "P5E_CPU0_PE4_TX_DN<8>")
	)
	(segment
		(start 344.84183 -286.799528)
		(end 344.83294 -286.804608)
		(width 0.0889)
		(layer "In2.Cu")
		(net "P5E_CPU0_PE4_TX_DN<8>")
	)
	(segment
		(start 343.61882 -288.917126)
		(end 343.61882 -289.113976)
		(width 0.0889)
		(layer "In2.Cu")
		(net "P5E_CPU0_PE4_TX_DN<8>")
	)
	(segment
		(start 316.595252 -359.95356)
		(end 316.597284 -359.959656)
		(width 0.14732)
		(layer "In2.Cu")
		(net "P5E_CPU0_PE4_TX_DN<8>")
	)
	(segment
		(start 343.902284 -288.427414)
		(end 343.893394 -288.432494)
		(width 0.0889)
		(layer "In2.Cu")
		(net "P5E_CPU0_PE4_TX_DN<8>")
	)
	(segment
		(start 344.83294 -286.804608)
		(end 344.827352 -286.80791)
		(width 0.0889)
		(layer "In2.Cu")
		(net "P5E_CPU0_PE4_TX_DN<8>")
	)
	(segment
		(start 332.923642 -310.24449)
		(end 311.7723 -331.396086)
		(width 0.14732)
		(layer "In2.Cu")
		(net "P5E_CPU0_PE4_TX_DN<8>")
	)
	(segment
		(start 343.69756 -290.945316)
		(end 343.65565 -290.987226)
		(width 0.0889)
		(layer "In2.Cu")
		(net "P5E_CPU0_PE4_TX_DN<8>")
	)
	(segment
		(start 328.780648 -399.223738)
		(end 328.780648 -400.563588)
		(width 0.14732)
		(layer "In2.Cu")
		(net "P5E_CPU0_PE4_TX_DN<8>")
	)
	(segment
		(start 334.380586 -309.270908)
		(end 332.923642 -310.24449)
		(width 0.14732)
		(layer "In2.Cu")
		(net "P5E_CPU0_PE4_TX_DN<8>")
	)
	(segment
		(start 344.08872 -288.103056)
		(end 344.08872 -288.118042)
		(width 0.0889)
		(layer "In2.Cu")
		(net "P5E_CPU0_PE4_TX_DN<8>")
	)
	(segment
		(start 316.597538 -359.959656)
		(end 328.67219 -398.874234)
		(width 0.14732)
		(layer "In2.Cu")
		(net "P5E_CPU0_PE4_TX_DN<8>")
	)
	(segment
		(start 316.597284 -359.959656)
		(end 316.597538 -359.959656)
		(width 0.14732)
		(layer "In2.Cu")
		(net "P5E_CPU0_PE4_TX_DN<8>")
	)
	(segment
		(start 345.279726 -285.932372)
		(end 345.255596 -286.021526)
		(width 0.0889)
		(layer "In2.Cu")
		(net "P5E_CPU0_PE4_TX_DN<8>")
	)
	(segment
		(start 311.7723 -331.396086)
		(end 310.610504 -334.201262)
		(width 0.14732)
		(layer "In2.Cu")
		(net "P5E_CPU0_PE4_TX_DN<8>")
	)
	(segment
		(start 328.780648 -400.563588)
		(end 328.486008 -400.858228)
		(width 0.14732)
		(layer "In2.Cu")
		(net "P5E_CPU0_PE4_TX_DN<8>")
	)
	(segment
		(start 310.610504 -334.201262)
		(end 310.610504 -342.912954)
		(width 0.14732)
		(layer "In2.Cu")
		(net "P5E_CPU0_PE4_TX_DN<8>")
	)
	(segment
		(start 344.558366 -287.28924)
		(end 344.558366 -287.301686)
		(width 0.0889)
		(layer "In2.Cu")
		(net "P5E_CPU0_PE4_TX_DN<8>")
	)
	(segment
		(start 343.65565 -290.987226)
		(end 343.65565 -291.009324)
		(width 0.0889)
		(layer "In2.Cu")
		(net "P5E_CPU0_PE4_TX_DN<8>")
	)
	(segment
		(start 344.088466 -289.645344)
		(end 344.088466 -290.07816)
		(width 0.0889)
		(layer "In2.Cu")
		(net "P5E_CPU0_PE4_TX_DN<8>")
	)
	(segment
		(start 345.123262 -285.661354)
		(end 345.279726 -285.932372)
		(width 0.0889)
		(layer "In2.Cu")
		(net "P5E_CPU0_PE4_TX_DN<8>")
	)
	(segment
		(start 343.65565 -299.094906)
		(end 343.018872 -300.632368)
		(width 0.14732)
		(layer "In2.Cu")
		(net "P5E_CPU0_PE4_TX_DN<8>")
	)
	(segment
		(start 328.67219 -398.874234)
		(end 328.67219 -398.874488)
		(width 0.14732)
		(layer "In2.Cu")
		(net "P5E_CPU0_PE4_TX_DN<8>")
	)
	(segment
		(start 311.00014 -345.125548)
		(end 316.595252 -359.95356)
		(width 0.14732)
		(layer "In2.Cu")
		(net "P5E_CPU0_PE4_TX_DN<8>")
	)
	(segment
		(start 310.610504 -342.912954)
		(end 311.00014 -345.125548)
		(width 0.14732)
		(layer "In2.Cu")
		(net "P5E_CPU0_PE4_TX_DN<8>")
	)
	(segment
		(start 343.904316 -289.446208)
		(end 343.90457 -289.446208)
		(width 0.0889)
		(layer "In2.Cu")
		(net "P5E_CPU0_PE4_TX_DN<8>")
	)
	(segment
		(start 344.850466 -286.794194)
		(end 344.84183 -286.799528)
		(width 0.0889)
		(layer "In2.Cu")
		(net "P5E_CPU0_PE4_TX_DN<8>")
	)
	(segment
		(start 328.67219 -398.874488)
		(end 328.780648 -399.223738)
		(width 0.14732)
		(layer "In2.Cu")
		(net "P5E_CPU0_PE4_TX_DN<8>")
	)
	(segment
		(start 344.371422 -287.613598)
		(end 344.360754 -287.619948)
		(width 0.0889)
		(layer "In2.Cu")
		(net "P5E_CPU0_PE4_TX_DN<8>")
	)
	(arc
		(start 343.61882 -289.113976)
		(mid 343.73005 -289.30718)
		(end 343.904316 -289.446208)
		(width 0.0889)
		(layer "In2.Cu")
		(net "P5E_CPU0_PE4_TX_DN<8>")
	)
	(arc
		(start 344.558366 -287.301686)
		(mid 344.505224 -287.481816)
		(end 344.371422 -287.613598)
		(width 0.0889)
		(layer "In2.Cu")
		(net "P5E_CPU0_PE4_TX_DN<8>")
	)
	(arc
		(start 345.256104 -286.021272)
		(mid 345.247274 -286.027915)
		(end 345.238578 -286.034734)
		(width 0.0889)
		(layer "In2.Cu")
		(net "P5E_CPU0_PE4_TX_DN<8>")
	)
	(arc
		(start 344.827352 -286.80791)
		(mid 344.630176 -287.013545)
		(end 344.558366 -287.28924)
		(width 0.0889)
		(layer "In2.Cu")
		(net "P5E_CPU0_PE4_TX_DN<8>")
	)
	(arc
		(start 344.08872 -288.118042)
		(mid 344.035208 -288.296666)
		(end 343.902284 -288.427414)
		(width 0.0889)
		(layer "In2.Cu")
		(net "P5E_CPU0_PE4_TX_DN<8>")
	)
	(arc
		(start 343.90457 -289.446208)
		(mid 344.013537 -289.530063)
		(end 344.088466 -289.645344)
		(width 0.0889)
		(layer "In2.Cu")
		(net "P5E_CPU0_PE4_TX_DN<8>")
	)
	(arc
		(start 344.360754 -287.619948)
		(mid 344.16137 -287.825828)
		(end 344.08872 -288.103056)
		(width 0.0889)
		(layer "In2.Cu")
		(net "P5E_CPU0_PE4_TX_DN<8>")
	)
	(arc
		(start 345.028266 -286.475424)
		(mid 344.98081 -286.657925)
		(end 344.850466 -286.794194)
		(width 0.0889)
		(layer "In2.Cu")
		(net "P5E_CPU0_PE4_TX_DN<8>")
	)
	(arc
		(start 343.887806 -288.435796)
		(mid 343.69063 -288.641431)
		(end 343.61882 -288.917126)
		(width 0.0889)
		(layer "In2.Cu")
		(net "P5E_CPU0_PE4_TX_DN<8>")
	)
	(arc
		(start 345.238578 -286.034734)
		(mid 345.083417 -286.231209)
		(end 345.028266 -286.475424)
		(width 0.0889)
		(layer "In2.Cu")
		(net "P5E_CPU0_PE4_TX_DN<8>")
	)
	(segment
		(start 325.40194 -402.104352)
		(end 325.397368 -402.104352)
		(width 0.13208)
		(layer "F.Cu")
		(net "P5E_CPU0_PE4_TX_DN<7>")
	)
	(segment
		(start 325.422768 -400.858228)
		(end 325.72833 -401.16379)
		(width 0.13208)
		(layer "F.Cu")
		(net "P5E_CPU0_PE4_TX_DN<7>")
	)
	(segment
		(start 344.183716 -285.6611)
		(end 344.183462 -285.661354)
		(width 0.13208)
		(layer "F.Cu")
		(net "P5E_CPU0_PE4_TX_DN<7>")
	)
	(segment
		(start 344.183716 -285.125414)
		(end 344.183716 -285.6611)
		(width 0.13208)
		(layer "F.Cu")
		(net "P5E_CPU0_PE4_TX_DN<7>")
	)
	(segment
		(start 325.72833 -401.777962)
		(end 325.40194 -402.104352)
		(width 0.13208)
		(layer "F.Cu")
		(net "P5E_CPU0_PE4_TX_DN<7>")
	)
	(segment
		(start 325.72833 -401.16379)
		(end 325.72833 -401.777962)
		(width 0.13208)
		(layer "F.Cu")
		(net "P5E_CPU0_PE4_TX_DN<7>")
	)
	(segment
		(start 343.423494 -287.618424)
		(end 343.417906 -287.621726)
		(width 0.0889)
		(layer "In2.Cu")
		(net "P5E_CPU0_PE4_TX_DN<7>")
	)
	(segment
		(start 325.10476 -397.244316)
		(end 325.257922 -397.331946)
		(width 0.14732)
		(layer "In2.Cu")
		(net "P5E_CPU0_PE4_TX_DN<7>")
	)
	(segment
		(start 332.520544 -309.324248)
		(end 310.93791 -330.906882)
		(width 0.14732)
		(layer "In2.Cu")
		(net "P5E_CPU0_PE4_TX_DN<7>")
	)
	(segment
		(start 343.14892 -288.103056)
		(end 343.14892 -288.118042)
		(width 0.0889)
		(layer "In2.Cu")
		(net "P5E_CPU0_PE4_TX_DN<7>")
	)
	(segment
		(start 344.08872 -286.464756)
		(end 344.08872 -286.475424)
		(width 0.0889)
		(layer "In2.Cu")
		(net "P5E_CPU0_PE4_TX_DN<7>")
	)
	(segment
		(start 309.654702 -342.996774)
		(end 310.077866 -345.39809)
		(width 0.14732)
		(layer "In2.Cu")
		(net "P5E_CPU0_PE4_TX_DN<7>")
	)
	(segment
		(start 342.67902 -288.917126)
		(end 342.67902 -289.113976)
		(width 0.0889)
		(layer "In2.Cu")
		(net "P5E_CPU0_PE4_TX_DN<7>")
	)
	(segment
		(start 343.148666 -290.191698)
		(end 342.76792 -290.418266)
		(width 0.0889)
		(layer "In2.Cu")
		(net "P5E_CPU0_PE4_TX_DN<7>")
	)
	(segment
		(start 325.257922 -397.331946)
		(end 325.372222 -397.753332)
		(width 0.14732)
		(layer "In2.Cu")
		(net "P5E_CPU0_PE4_TX_DN<7>")
	)
	(segment
		(start 344.183462 -285.661354)
		(end 344.339926 -285.390336)
		(width 0.0889)
		(layer "In2.Cu")
		(net "P5E_CPU0_PE4_TX_DN<7>")
	)
	(segment
		(start 343.432384 -287.613344)
		(end 343.423494 -287.618424)
		(width 0.0889)
		(layer "In2.Cu")
		(net "P5E_CPU0_PE4_TX_DN<7>")
	)
	(segment
		(start 343.148666 -289.64509)
		(end 343.148666 -290.191698)
		(width 0.0889)
		(layer "In2.Cu")
		(net "P5E_CPU0_PE4_TX_DN<7>")
	)
	(segment
		(start 310.077866 -345.39809)
		(end 315.227208 -360.393234)
		(width 0.14732)
		(layer "In2.Cu")
		(net "P5E_CPU0_PE4_TX_DN<7>")
	)
	(segment
		(start 325.399146 -398.32788)
		(end 325.552054 -398.415256)
		(width 0.14732)
		(layer "In2.Cu")
		(net "P5E_CPU0_PE4_TX_DN<7>")
	)
	(segment
		(start 342.962484 -288.427414)
		(end 342.953594 -288.432494)
		(width 0.0889)
		(layer "In2.Cu")
		(net "P5E_CPU0_PE4_TX_DN<7>")
	)
	(segment
		(start 333.856076 -308.431692)
		(end 332.520544 -309.324248)
		(width 0.14732)
		(layer "In2.Cu")
		(net "P5E_CPU0_PE4_TX_DN<7>")
	)
	(segment
		(start 325.077836 -396.669768)
		(end 324.99046 -396.822422)
		(width 0.14732)
		(layer "In2.Cu")
		(net "P5E_CPU0_PE4_TX_DN<7>")
	)
	(segment
		(start 343.618566 -287.28924)
		(end 343.618566 -287.301686)
		(width 0.0889)
		(layer "In2.Cu")
		(net "P5E_CPU0_PE4_TX_DN<7>")
	)
	(segment
		(start 344.418158 -285.369508)
		(end 344.418666 -285.369)
		(width 0.0889)
		(layer "In2.Cu")
		(net "P5E_CPU0_PE4_TX_DN<7>")
	)
	(segment
		(start 324.99046 -396.822422)
		(end 325.10476 -397.244316)
		(width 0.14732)
		(layer "In2.Cu")
		(net "P5E_CPU0_PE4_TX_DN<7>")
	)
	(segment
		(start 343.906602 -286.796734)
		(end 343.899744 -286.800798)
		(width 0.0889)
		(layer "In2.Cu")
		(net "P5E_CPU0_PE4_TX_DN<7>")
	)
	(segment
		(start 342.76792 -290.418266)
		(end 342.76792 -290.940236)
		(width 0.0889)
		(layer "In2.Cu")
		(net "P5E_CPU0_PE4_TX_DN<7>")
	)
	(segment
		(start 342.17737 -300.110652)
		(end 333.856076 -308.431692)
		(width 0.14732)
		(layer "In2.Cu")
		(net "P5E_CPU0_PE4_TX_DN<7>")
	)
	(segment
		(start 344.418666 -285.369)
		(end 344.442034 -285.38805)
		(width 0.0889)
		(layer "In2.Cu")
		(net "P5E_CPU0_PE4_TX_DN<7>")
	)
	(segment
		(start 310.93791 -330.906882)
		(end 309.654702 -334.005174)
		(width 0.14732)
		(layer "In2.Cu")
		(net "P5E_CPU0_PE4_TX_DN<7>")
	)
	(segment
		(start 342.72601 -298.786296)
		(end 342.17737 -300.110652)
		(width 0.14732)
		(layer "In2.Cu")
		(net "P5E_CPU0_PE4_TX_DN<7>")
	)
	(segment
		(start 342.72601 -290.982146)
		(end 342.72601 -291.004244)
		(width 0.0889)
		(layer "In2.Cu")
		(net "P5E_CPU0_PE4_TX_DN<7>")
	)
	(segment
		(start 309.654702 -334.005174)
		(end 309.654702 -342.996774)
		(width 0.14732)
		(layer "In2.Cu")
		(net "P5E_CPU0_PE4_TX_DN<7>")
	)
	(segment
		(start 325.717408 -399.024602)
		(end 325.717408 -400.563588)
		(width 0.14732)
		(layer "In2.Cu")
		(net "P5E_CPU0_PE4_TX_DN<7>")
	)
	(segment
		(start 342.76792 -290.940236)
		(end 342.72601 -290.982146)
		(width 0.0889)
		(layer "In2.Cu")
		(net "P5E_CPU0_PE4_TX_DN<7>")
	)
	(segment
		(start 344.557604 -285.619444)
		(end 344.558112 -285.677356)
		(width 0.0889)
		(layer "In2.Cu")
		(net "P5E_CPU0_PE4_TX_DN<7>")
	)
	(segment
		(start 342.72601 -291.004244)
		(end 342.72601 -298.786296)
		(width 0.14732)
		(layer "In2.Cu")
		(net "P5E_CPU0_PE4_TX_DN<7>")
	)
	(segment
		(start 325.717408 -400.563588)
		(end 325.422768 -400.858228)
		(width 0.14732)
		(layer "In2.Cu")
		(net "P5E_CPU0_PE4_TX_DN<7>")
	)
	(segment
		(start 325.552054 -398.415256)
		(end 325.717408 -399.024602)
		(width 0.14732)
		(layer "In2.Cu")
		(net "P5E_CPU0_PE4_TX_DN<7>")
	)
	(segment
		(start 325.284592 -397.905986)
		(end 325.399146 -398.32788)
		(width 0.14732)
		(layer "In2.Cu")
		(net "P5E_CPU0_PE4_TX_DN<7>")
	)
	(segment
		(start 344.339926 -285.390336)
		(end 344.418158 -285.369508)
		(width 0.0889)
		(layer "In2.Cu")
		(net "P5E_CPU0_PE4_TX_DN<7>")
	)
	(segment
		(start 315.227208 -360.393234)
		(end 325.077836 -396.669768)
		(width 0.14732)
		(layer "In2.Cu")
		(net "P5E_CPU0_PE4_TX_DN<7>")
	)
	(segment
		(start 343.899744 -286.800798)
		(end 343.889584 -286.80664)
		(width 0.0889)
		(layer "In2.Cu")
		(net "P5E_CPU0_PE4_TX_DN<7>")
	)
	(segment
		(start 325.372222 -397.753332)
		(end 325.284592 -397.905986)
		(width 0.14732)
		(layer "In2.Cu")
		(net "P5E_CPU0_PE4_TX_DN<7>")
	)
	(segment
		(start 342.953594 -288.432494)
		(end 342.948006 -288.435796)
		(width 0.0889)
		(layer "In2.Cu")
		(net "P5E_CPU0_PE4_TX_DN<7>")
	)
	(arc
		(start 344.442034 -285.38805)
		(mid 344.525129 -285.491101)
		(end 344.557604 -285.619444)
		(width 0.0889)
		(layer "In2.Cu")
		(net "P5E_CPU0_PE4_TX_DN<7>")
	)
	(arc
		(start 344.370914 -285.98622)
		(mid 344.166936 -286.188396)
		(end 344.08872 -286.464756)
		(width 0.0889)
		(layer "In2.Cu")
		(net "P5E_CPU0_PE4_TX_DN<7>")
	)
	(arc
		(start 342.964516 -289.446208)
		(mid 343.073596 -289.529909)
		(end 343.148666 -289.64509)
		(width 0.0889)
		(layer "In2.Cu")
		(net "P5E_CPU0_PE4_TX_DN<7>")
	)
	(arc
		(start 342.67902 -289.113976)
		(mid 342.79025 -289.30718)
		(end 342.964516 -289.446208)
		(width 0.0889)
		(layer "In2.Cu")
		(net "P5E_CPU0_PE4_TX_DN<7>")
	)
	(arc
		(start 343.417906 -287.621726)
		(mid 343.22073 -287.827361)
		(end 343.14892 -288.103056)
		(width 0.0889)
		(layer "In2.Cu")
		(net "P5E_CPU0_PE4_TX_DN<7>")
	)
	(arc
		(start 343.14892 -288.118042)
		(mid 343.095408 -288.296666)
		(end 342.962484 -288.427414)
		(width 0.0889)
		(layer "In2.Cu")
		(net "P5E_CPU0_PE4_TX_DN<7>")
	)
	(arc
		(start 344.08872 -286.475424)
		(mid 344.040016 -286.660078)
		(end 343.906602 -286.796734)
		(width 0.0889)
		(layer "In2.Cu")
		(net "P5E_CPU0_PE4_TX_DN<7>")
	)
	(arc
		(start 343.889584 -286.80664)
		(mid 343.690943 -287.012489)
		(end 343.618566 -287.28924)
		(width 0.0889)
		(layer "In2.Cu")
		(net "P5E_CPU0_PE4_TX_DN<7>")
	)
	(arc
		(start 343.618566 -287.301686)
		(mid 343.565717 -287.481565)
		(end 343.432384 -287.613344)
		(width 0.0889)
		(layer "In2.Cu")
		(net "P5E_CPU0_PE4_TX_DN<7>")
	)
	(arc
		(start 342.948006 -288.435796)
		(mid 342.75083 -288.641431)
		(end 342.67902 -288.917126)
		(width 0.0889)
		(layer "In2.Cu")
		(net "P5E_CPU0_PE4_TX_DN<7>")
	)
	(arc
		(start 344.558112 -285.677356)
		(mid 344.504114 -285.855778)
		(end 344.370914 -285.98622)
		(width 0.0889)
		(layer "In2.Cu")
		(net "P5E_CPU0_PE4_TX_DN<7>")
	)
	(segment
		(start 343.243916 -285.6611)
		(end 343.243662 -285.661354)
		(width 0.13208)
		(layer "F.Cu")
		(net "P5E_CPU0_PE4_TX_DN<6>")
	)
	(segment
		(start 343.243916 -285.125414)
		(end 343.243916 -285.6611)
		(width 0.13208)
		(layer "F.Cu")
		(net "P5E_CPU0_PE4_TX_DN<6>")
	)
	(segment
		(start 322.66509 -401.777962)
		(end 322.3387 -402.104352)
		(width 0.13208)
		(layer "F.Cu")
		(net "P5E_CPU0_PE4_TX_DN<6>")
	)
	(segment
		(start 322.66509 -401.16379)
		(end 322.66509 -401.777962)
		(width 0.13208)
		(layer "F.Cu")
		(net "P5E_CPU0_PE4_TX_DN<6>")
	)
	(segment
		(start 322.3387 -402.104352)
		(end 322.334128 -402.104352)
		(width 0.13208)
		(layer "F.Cu")
		(net "P5E_CPU0_PE4_TX_DN<6>")
	)
	(segment
		(start 322.359528 -400.858228)
		(end 322.66509 -401.16379)
		(width 0.13208)
		(layer "F.Cu")
		(net "P5E_CPU0_PE4_TX_DN<6>")
	)
	(segment
		(start 342.96223 -286.799528)
		(end 342.95334 -286.804608)
		(width 0.0889)
		(layer "In2.Cu")
		(net "P5E_CPU0_PE4_TX_DN<6>")
	)
	(segment
		(start 341.83701 -290.41979)
		(end 341.83701 -290.940236)
		(width 0.0889)
		(layer "In2.Cu")
		(net "P5E_CPU0_PE4_TX_DN<6>")
	)
	(segment
		(start 342.970866 -286.794194)
		(end 342.96223 -286.799528)
		(width 0.0889)
		(layer "In2.Cu")
		(net "P5E_CPU0_PE4_TX_DN<6>")
	)
	(segment
		(start 341.83701 -290.940236)
		(end 341.7951 -290.982146)
		(width 0.0889)
		(layer "In2.Cu")
		(net "P5E_CPU0_PE4_TX_DN<6>")
	)
	(segment
		(start 341.7951 -298.493434)
		(end 341.329264 -299.618146)
		(width 0.14732)
		(layer "In2.Cu")
		(net "P5E_CPU0_PE4_TX_DN<6>")
	)
	(segment
		(start 342.20912 -288.103056)
		(end 342.20912 -288.118042)
		(width 0.0889)
		(layer "In2.Cu")
		(net "P5E_CPU0_PE4_TX_DN<6>")
	)
	(segment
		(start 343.400126 -285.932372)
		(end 343.375996 -286.021526)
		(width 0.0889)
		(layer "In2.Cu")
		(net "P5E_CPU0_PE4_TX_DN<6>")
	)
	(segment
		(start 308.71922 -333.788258)
		(end 308.71922 -343.078816)
		(width 0.14732)
		(layer "In2.Cu")
		(net "P5E_CPU0_PE4_TX_DN<6>")
	)
	(segment
		(start 342.208612 -289.751516)
		(end 342.208612 -290.192714)
		(width 0.0889)
		(layer "In2.Cu")
		(net "P5E_CPU0_PE4_TX_DN<6>")
	)
	(segment
		(start 341.7951 -290.982146)
		(end 341.7951 -291.004244)
		(width 0.0889)
		(layer "In2.Cu")
		(net "P5E_CPU0_PE4_TX_DN<6>")
	)
	(segment
		(start 343.243662 -285.661354)
		(end 343.400126 -285.932372)
		(width 0.0889)
		(layer "In2.Cu")
		(net "P5E_CPU0_PE4_TX_DN<6>")
	)
	(segment
		(start 341.329264 -299.618146)
		(end 333.304388 -307.642768)
		(width 0.14732)
		(layer "In2.Cu")
		(net "P5E_CPU0_PE4_TX_DN<6>")
	)
	(segment
		(start 342.013794 -288.432494)
		(end 342.008206 -288.435796)
		(width 0.0889)
		(layer "In2.Cu")
		(net "P5E_CPU0_PE4_TX_DN<6>")
	)
	(segment
		(start 333.304388 -307.642768)
		(end 331.977492 -308.529482)
		(width 0.14732)
		(layer "In2.Cu")
		(net "P5E_CPU0_PE4_TX_DN<6>")
	)
	(segment
		(start 309.161434 -345.588082)
		(end 313.821064 -360.572304)
		(width 0.14732)
		(layer "In2.Cu")
		(net "P5E_CPU0_PE4_TX_DN<6>")
	)
	(segment
		(start 331.977492 -308.529482)
		(end 310.133492 -330.373736)
		(width 0.14732)
		(layer "In2.Cu")
		(net "P5E_CPU0_PE4_TX_DN<6>")
	)
	(segment
		(start 342.208612 -290.192714)
		(end 341.83701 -290.41979)
		(width 0.0889)
		(layer "In2.Cu")
		(net "P5E_CPU0_PE4_TX_DN<6>")
	)
	(segment
		(start 308.71922 -343.078816)
		(end 309.161434 -345.588082)
		(width 0.14732)
		(layer "In2.Cu")
		(net "P5E_CPU0_PE4_TX_DN<6>")
	)
	(segment
		(start 342.678766 -287.28924)
		(end 342.678766 -287.301686)
		(width 0.0889)
		(layer "In2.Cu")
		(net "P5E_CPU0_PE4_TX_DN<6>")
	)
	(segment
		(start 313.821064 -360.572304)
		(end 322.654168 -398.936718)
		(width 0.14732)
		(layer "In2.Cu")
		(net "P5E_CPU0_PE4_TX_DN<6>")
	)
	(segment
		(start 342.95334 -286.804608)
		(end 342.947752 -286.80791)
		(width 0.0889)
		(layer "In2.Cu")
		(net "P5E_CPU0_PE4_TX_DN<6>")
	)
	(segment
		(start 341.73922 -288.917126)
		(end 341.73922 -289.113976)
		(width 0.0889)
		(layer "In2.Cu")
		(net "P5E_CPU0_PE4_TX_DN<6>")
	)
	(segment
		(start 342.491822 -287.613598)
		(end 342.481154 -287.619948)
		(width 0.0889)
		(layer "In2.Cu")
		(net "P5E_CPU0_PE4_TX_DN<6>")
	)
	(segment
		(start 310.133492 -330.373736)
		(end 308.71922 -333.788258)
		(width 0.14732)
		(layer "In2.Cu")
		(net "P5E_CPU0_PE4_TX_DN<6>")
	)
	(segment
		(start 322.654168 -398.936718)
		(end 322.654168 -400.563588)
		(width 0.14732)
		(layer "In2.Cu")
		(net "P5E_CPU0_PE4_TX_DN<6>")
	)
	(segment
		(start 322.654168 -400.563588)
		(end 322.359528 -400.858228)
		(width 0.14732)
		(layer "In2.Cu")
		(net "P5E_CPU0_PE4_TX_DN<6>")
	)
	(segment
		(start 343.375996 -286.021526)
		(end 343.376504 -286.021272)
		(width 0.0889)
		(layer "In2.Cu")
		(net "P5E_CPU0_PE4_TX_DN<6>")
	)
	(segment
		(start 342.022684 -288.427414)
		(end 342.013794 -288.432494)
		(width 0.0889)
		(layer "In2.Cu")
		(net "P5E_CPU0_PE4_TX_DN<6>")
	)
	(segment
		(start 341.7951 -291.004244)
		(end 341.7951 -298.493434)
		(width 0.14732)
		(layer "In2.Cu")
		(net "P5E_CPU0_PE4_TX_DN<6>")
	)
	(arc
		(start 342.678766 -287.301686)
		(mid 342.625624 -287.481816)
		(end 342.491822 -287.613598)
		(width 0.0889)
		(layer "In2.Cu")
		(net "P5E_CPU0_PE4_TX_DN<6>")
	)
	(arc
		(start 342.481154 -287.619948)
		(mid 342.28177 -287.825828)
		(end 342.20912 -288.103056)
		(width 0.0889)
		(layer "In2.Cu")
		(net "P5E_CPU0_PE4_TX_DN<6>")
	)
	(arc
		(start 342.947752 -286.80791)
		(mid 342.750576 -287.013545)
		(end 342.678766 -287.28924)
		(width 0.0889)
		(layer "In2.Cu")
		(net "P5E_CPU0_PE4_TX_DN<6>")
	)
	(arc
		(start 342.20912 -288.118042)
		(mid 342.155608 -288.296666)
		(end 342.022684 -288.427414)
		(width 0.0889)
		(layer "In2.Cu")
		(net "P5E_CPU0_PE4_TX_DN<6>")
	)
	(arc
		(start 342.024716 -289.446208)
		(mid 342.159066 -289.573303)
		(end 342.208612 -289.751516)
		(width 0.0889)
		(layer "In2.Cu")
		(net "P5E_CPU0_PE4_TX_DN<6>")
	)
	(arc
		(start 343.148666 -286.475424)
		(mid 343.10121 -286.657925)
		(end 342.970866 -286.794194)
		(width 0.0889)
		(layer "In2.Cu")
		(net "P5E_CPU0_PE4_TX_DN<6>")
	)
	(arc
		(start 342.008206 -288.435796)
		(mid 341.81103 -288.641431)
		(end 341.73922 -288.917126)
		(width 0.0889)
		(layer "In2.Cu")
		(net "P5E_CPU0_PE4_TX_DN<6>")
	)
	(arc
		(start 343.376504 -286.021272)
		(mid 343.208672 -286.221308)
		(end 343.148666 -286.475424)
		(width 0.0889)
		(layer "In2.Cu")
		(net "P5E_CPU0_PE4_TX_DN<6>")
	)
	(arc
		(start 341.73922 -289.113976)
		(mid 341.85045 -289.30718)
		(end 342.024716 -289.446208)
		(width 0.0889)
		(layer "In2.Cu")
		(net "P5E_CPU0_PE4_TX_DN<6>")
	)
	(segment
		(start 319.27546 -402.104352)
		(end 319.270888 -402.104352)
		(width 0.13208)
		(layer "F.Cu")
		(net "P5E_CPU0_PE4_TX_DN<5>")
	)
	(segment
		(start 342.304116 -285.6611)
		(end 342.303862 -285.661354)
		(width 0.13208)
		(layer "F.Cu")
		(net "P5E_CPU0_PE4_TX_DN<5>")
	)
	(segment
		(start 319.60185 -401.777962)
		(end 319.27546 -402.104352)
		(width 0.13208)
		(layer "F.Cu")
		(net "P5E_CPU0_PE4_TX_DN<5>")
	)
	(segment
		(start 319.296288 -400.858228)
		(end 319.60185 -401.16379)
		(width 0.13208)
		(layer "F.Cu")
		(net "P5E_CPU0_PE4_TX_DN<5>")
	)
	(segment
		(start 319.60185 -401.16379)
		(end 319.60185 -401.777962)
		(width 0.13208)
		(layer "F.Cu")
		(net "P5E_CPU0_PE4_TX_DN<5>")
	)
	(segment
		(start 342.304116 -285.125414)
		(end 342.304116 -285.6611)
		(width 0.13208)
		(layer "F.Cu")
		(net "P5E_CPU0_PE4_TX_DN<5>")
	)
	(segment
		(start 319.029334 -396.308072)
		(end 319.11036 -396.737586)
		(width 0.14732)
		(layer "In2.Cu")
		(net "P5E_CPU0_PE4_TX_DN<5>")
	)
	(segment
		(start 319.238122 -397.411448)
		(end 319.319148 -397.840962)
		(width 0.14732)
		(layer "In2.Cu")
		(net "P5E_CPU0_PE4_TX_DN<5>")
	)
	(segment
		(start 341.269066 -288.087562)
		(end 341.269066 -288.103056)
		(width 0.0889)
		(layer "In2.Cu")
		(net "P5E_CPU0_PE4_TX_DN<5>")
	)
	(segment
		(start 309.173372 -326.238362)
		(end 308.947058 -326.784716)
		(width 0.14732)
		(layer "In2.Cu")
		(net "P5E_CPU0_PE4_TX_DN<5>")
	)
	(segment
		(start 319.319148 -397.840962)
		(end 319.464944 -397.940022)
		(width 0.14732)
		(layer "In2.Cu")
		(net "P5E_CPU0_PE4_TX_DN<5>")
	)
	(segment
		(start 340.86546 -290.901882)
		(end 340.86546 -290.92398)
		(width 0.0889)
		(layer "In2.Cu")
		(net "P5E_CPU0_PE4_TX_DN<5>")
	)
	(segment
		(start 341.027512 -289.416236)
		(end 341.084916 -289.446462)
		(width 0.0889)
		(layer "In2.Cu")
		(net "P5E_CPU0_PE4_TX_DN<5>")
	)
	(segment
		(start 312.470546 -360.946954)
		(end 319.128394 -396.16253)
		(width 0.14732)
		(layer "In2.Cu")
		(net "P5E_CPU0_PE4_TX_DN<5>")
	)
	(segment
		(start 307.78323 -343.160858)
		(end 308.243478 -345.772232)
		(width 0.14732)
		(layer "In2.Cu")
		(net "P5E_CPU0_PE4_TX_DN<5>")
	)
	(segment
		(start 319.337182 -397.265906)
		(end 319.238122 -397.411448)
		(width 0.14732)
		(layer "In2.Cu")
		(net "P5E_CPU0_PE4_TX_DN<5>")
	)
	(segment
		(start 319.590674 -398.605756)
		(end 319.590928 -398.60601)
		(width 0.14732)
		(layer "In2.Cu")
		(net "P5E_CPU0_PE4_TX_DN<5>")
	)
	(segment
		(start 342.460326 -285.390336)
		(end 342.538558 -285.369508)
		(width 0.0889)
		(layer "In2.Cu")
		(net "P5E_CPU0_PE4_TX_DN<5>")
	)
	(segment
		(start 341.542878 -287.618424)
		(end 341.542878 -287.618678)
		(width 0.0889)
		(layer "In2.Cu")
		(net "P5E_CPU0_PE4_TX_DN<5>")
	)
	(segment
		(start 341.089234 -288.423096)
		(end 341.08009 -288.428176)
		(width 0.0889)
		(layer "In2.Cu")
		(net "P5E_CPU0_PE4_TX_DN<5>")
	)
	(segment
		(start 341.553546 -287.612328)
		(end 341.542878 -287.618424)
		(width 0.0889)
		(layer "In2.Cu")
		(net "P5E_CPU0_PE4_TX_DN<5>")
	)
	(segment
		(start 308.947058 -327.709276)
		(end 307.78323 -333.560928)
		(width 0.14732)
		(layer "In2.Cu")
		(net "P5E_CPU0_PE4_TX_DN<5>")
	)
	(segment
		(start 319.256156 -396.836646)
		(end 319.337182 -397.265906)
		(width 0.14732)
		(layer "In2.Cu")
		(net "P5E_CPU0_PE4_TX_DN<5>")
	)
	(segment
		(start 340.799166 -288.898584)
		(end 340.799166 -289.1155)
		(width 0.0889)
		(layer "In2.Cu")
		(net "P5E_CPU0_PE4_TX_DN<5>")
	)
	(segment
		(start 314.180728 -324.999858)
		(end 312.786014 -325.577708)
		(width 0.14732)
		(layer "In2.Cu")
		(net "P5E_CPU0_PE4_TX_DN<5>")
	)
	(segment
		(start 341.268558 -289.751262)
		(end 341.268558 -290.189158)
		(width 0.0889)
		(layer "In2.Cu")
		(net "P5E_CPU0_PE4_TX_DN<5>")
	)
	(segment
		(start 319.590928 -398.60601)
		(end 319.590928 -400.563588)
		(width 0.14732)
		(layer "In2.Cu")
		(net "P5E_CPU0_PE4_TX_DN<5>")
	)
	(segment
		(start 308.243478 -345.772232)
		(end 312.470546 -360.946954)
		(width 0.14732)
		(layer "In2.Cu")
		(net "P5E_CPU0_PE4_TX_DN<5>")
	)
	(segment
		(start 331.436726 -307.74386)
		(end 314.180728 -324.999858)
		(width 0.14732)
		(layer "In2.Cu")
		(net "P5E_CPU0_PE4_TX_DN<5>")
	)
	(segment
		(start 342.019382 -286.800798)
		(end 342.015318 -286.803084)
		(width 0.0889)
		(layer "In2.Cu")
		(net "P5E_CPU0_PE4_TX_DN<5>")
	)
	(segment
		(start 340.90737 -290.859972)
		(end 340.86546 -290.901882)
		(width 0.0889)
		(layer "In2.Cu")
		(net "P5E_CPU0_PE4_TX_DN<5>")
	)
	(segment
		(start 341.56142 -287.607502)
		(end 341.553546 -287.612328)
		(width 0.0889)
		(layer "In2.Cu")
		(net "P5E_CPU0_PE4_TX_DN<5>")
	)
	(segment
		(start 319.128394 -396.16253)
		(end 319.029334 -396.308072)
		(width 0.14732)
		(layer "In2.Cu")
		(net "P5E_CPU0_PE4_TX_DN<5>")
	)
	(segment
		(start 319.464944 -397.940022)
		(end 319.590674 -398.605756)
		(width 0.14732)
		(layer "In2.Cu")
		(net "P5E_CPU0_PE4_TX_DN<5>")
	)
	(segment
		(start 308.947058 -326.784716)
		(end 308.947058 -327.709276)
		(width 0.14732)
		(layer "In2.Cu")
		(net "P5E_CPU0_PE4_TX_DN<5>")
	)
	(segment
		(start 310.170322 -325.577708)
		(end 309.596282 -325.815452)
		(width 0.14732)
		(layer "In2.Cu")
		(net "P5E_CPU0_PE4_TX_DN<5>")
	)
	(segment
		(start 340.365842 -299.204634)
		(end 332.611222 -306.959)
		(width 0.14732)
		(layer "In2.Cu")
		(net "P5E_CPU0_PE4_TX_DN<5>")
	)
	(segment
		(start 319.11036 -396.737586)
		(end 319.256156 -396.836646)
		(width 0.14732)
		(layer "In2.Cu")
		(net "P5E_CPU0_PE4_TX_DN<5>")
	)
	(segment
		(start 342.029034 -286.79521)
		(end 342.019382 -286.800798)
		(width 0.0889)
		(layer "In2.Cu")
		(net "P5E_CPU0_PE4_TX_DN<5>")
	)
	(segment
		(start 340.86546 -290.92398)
		(end 340.86546 -297.998642)
		(width 0.14732)
		(layer "In2.Cu")
		(net "P5E_CPU0_PE4_TX_DN<5>")
	)
	(segment
		(start 340.90737 -290.422838)
		(end 340.90737 -290.859972)
		(width 0.0889)
		(layer "In2.Cu")
		(net "P5E_CPU0_PE4_TX_DN<5>")
	)
	(segment
		(start 340.799166 -289.1155)
		(end 340.820756 -289.17646)
		(width 0.0889)
		(layer "In2.Cu")
		(net "P5E_CPU0_PE4_TX_DN<5>")
	)
	(segment
		(start 332.611222 -306.959)
		(end 331.436726 -307.74386)
		(width 0.14732)
		(layer "In2.Cu")
		(net "P5E_CPU0_PE4_TX_DN<5>")
	)
	(segment
		(start 341.268558 -290.189158)
		(end 340.90737 -290.422838)
		(width 0.0889)
		(layer "In2.Cu")
		(net "P5E_CPU0_PE4_TX_DN<5>")
	)
	(segment
		(start 312.786014 -325.577708)
		(end 310.170322 -325.577708)
		(width 0.14732)
		(layer "In2.Cu")
		(net "P5E_CPU0_PE4_TX_DN<5>")
	)
	(segment
		(start 307.78323 -333.560928)
		(end 307.78323 -343.160858)
		(width 0.14732)
		(layer "In2.Cu")
		(net "P5E_CPU0_PE4_TX_DN<5>")
	)
	(segment
		(start 342.303862 -285.661354)
		(end 342.460326 -285.390336)
		(width 0.0889)
		(layer "In2.Cu")
		(net "P5E_CPU0_PE4_TX_DN<5>")
	)
	(segment
		(start 342.49995 -285.980632)
		(end 342.49106 -285.985712)
		(width 0.0889)
		(layer "In2.Cu")
		(net "P5E_CPU0_PE4_TX_DN<5>")
	)
	(segment
		(start 309.596282 -325.815452)
		(end 309.173372 -326.238362)
		(width 0.14732)
		(layer "In2.Cu")
		(net "P5E_CPU0_PE4_TX_DN<5>")
	)
	(segment
		(start 319.590928 -400.563588)
		(end 319.296288 -400.858228)
		(width 0.14732)
		(layer "In2.Cu")
		(net "P5E_CPU0_PE4_TX_DN<5>")
	)
	(segment
		(start 342.208612 -286.456882)
		(end 342.208612 -286.48406)
		(width 0.0889)
		(layer "In2.Cu")
		(net "P5E_CPU0_PE4_TX_DN<5>")
	)
	(segment
		(start 340.86546 -297.998642)
		(end 340.365842 -299.204634)
		(width 0.14732)
		(layer "In2.Cu")
		(net "P5E_CPU0_PE4_TX_DN<5>")
	)
	(arc
		(start 341.542878 -287.618678)
		(mid 341.34605 -287.81811)
		(end 341.269066 -288.087562)
		(width 0.0889)
		(layer "In2.Cu")
		(net "P5E_CPU0_PE4_TX_DN<5>")
	)
	(arc
		(start 341.738712 -287.28924)
		(mid 341.691332 -287.471351)
		(end 341.56142 -287.607502)
		(width 0.0889)
		(layer "In2.Cu")
		(net "P5E_CPU0_PE4_TX_DN<5>")
	)
	(arc
		(start 341.269066 -288.103056)
		(mid 341.221025 -288.286602)
		(end 341.089234 -288.423096)
		(width 0.0889)
		(layer "In2.Cu")
		(net "P5E_CPU0_PE4_TX_DN<5>")
	)
	(arc
		(start 342.678512 -285.661354)
		(mid 342.630833 -285.844254)
		(end 342.49995 -285.980632)
		(width 0.0889)
		(layer "In2.Cu")
		(net "P5E_CPU0_PE4_TX_DN<5>")
	)
	(arc
		(start 340.820756 -289.17646)
		(mid 340.901488 -289.315876)
		(end 341.027512 -289.416236)
		(width 0.0889)
		(layer "In2.Cu")
		(net "P5E_CPU0_PE4_TX_DN<5>")
	)
	(arc
		(start 341.08009 -288.428176)
		(mid 340.878801 -288.627071)
		(end 340.799166 -288.898584)
		(width 0.0889)
		(layer "In2.Cu")
		(net "P5E_CPU0_PE4_TX_DN<5>")
	)
	(arc
		(start 342.49106 -285.985712)
		(mid 342.288774 -286.184693)
		(end 342.208612 -286.456882)
		(width 0.0889)
		(layer "In2.Cu")
		(net "P5E_CPU0_PE4_TX_DN<5>")
	)
	(arc
		(start 342.538558 -285.369508)
		(mid 342.641703 -285.499533)
		(end 342.678512 -285.661354)
		(width 0.0889)
		(layer "In2.Cu")
		(net "P5E_CPU0_PE4_TX_DN<5>")
	)
	(arc
		(start 342.015318 -286.803084)
		(mid 341.812668 -287.009546)
		(end 341.738712 -287.28924)
		(width 0.0889)
		(layer "In2.Cu")
		(net "P5E_CPU0_PE4_TX_DN<5>")
	)
	(arc
		(start 342.208612 -286.48406)
		(mid 342.158586 -286.66259)
		(end 342.029034 -286.79521)
		(width 0.0889)
		(layer "In2.Cu")
		(net "P5E_CPU0_PE4_TX_DN<5>")
	)
	(arc
		(start 341.084916 -289.446462)
		(mid 341.219041 -289.573374)
		(end 341.268558 -289.751262)
		(width 0.0889)
		(layer "In2.Cu")
		(net "P5E_CPU0_PE4_TX_DN<5>")
	)
	(segment
		(start 316.53861 -401.16379)
		(end 316.53861 -401.777962)
		(width 0.13208)
		(layer "F.Cu")
		(net "P5E_CPU0_PE4_TX_DN<4>")
	)
	(segment
		(start 316.233048 -400.858228)
		(end 316.53861 -401.16379)
		(width 0.13208)
		(layer "F.Cu")
		(net "P5E_CPU0_PE4_TX_DN<4>")
	)
	(segment
		(start 316.21222 -402.104352)
		(end 316.207648 -402.104352)
		(width 0.13208)
		(layer "F.Cu")
		(net "P5E_CPU0_PE4_TX_DN<4>")
	)
	(segment
		(start 316.53861 -401.777962)
		(end 316.21222 -402.104352)
		(width 0.13208)
		(layer "F.Cu")
		(net "P5E_CPU0_PE4_TX_DN<4>")
	)
	(segment
		(start 341.364316 -285.6611)
		(end 341.364062 -285.661354)
		(width 0.13208)
		(layer "F.Cu")
		(net "P5E_CPU0_PE4_TX_DN<4>")
	)
	(segment
		(start 341.364316 -285.125414)
		(end 341.364316 -285.6611)
		(width 0.13208)
		(layer "F.Cu")
		(net "P5E_CPU0_PE4_TX_DN<4>")
	)
	(segment
		(start 341.268812 -286.4612)
		(end 341.268812 -286.475424)
		(width 0.0889)
		(layer "In2.Cu")
		(net "P5E_CPU0_PE4_TX_DN<4>")
	)
	(segment
		(start 340.798912 -287.28924)
		(end 340.798912 -287.297876)
		(width 0.0889)
		(layer "In2.Cu")
		(net "P5E_CPU0_PE4_TX_DN<4>")
	)
	(segment
		(start 339.859366 -288.898584)
		(end 339.859366 -289.114738)
		(width 0.0889)
		(layer "In2.Cu")
		(net "P5E_CPU0_PE4_TX_DN<4>")
	)
	(segment
		(start 309.08117 -325.000366)
		(end 308.356508 -325.725028)
		(width 0.14732)
		(layer "In2.Cu")
		(net "P5E_CPU0_PE4_TX_DN<4>")
	)
	(segment
		(start 311.097422 -361.184952)
		(end 316.527688 -397.990822)
		(width 0.14732)
		(layer "In2.Cu")
		(net "P5E_CPU0_PE4_TX_DN<4>")
	)
	(segment
		(start 340.32952 -290.30803)
		(end 339.965284 -290.672266)
		(width 0.0889)
		(layer "In2.Cu")
		(net "P5E_CPU0_PE4_TX_DN<4>")
	)
	(segment
		(start 307.073554 -344.923364)
		(end 311.097422 -361.184952)
		(width 0.14732)
		(layer "In2.Cu")
		(net "P5E_CPU0_PE4_TX_DN<4>")
	)
	(segment
		(start 339.923374 -290.951158)
		(end 339.923374 -291.958776)
		(width 0.14732)
		(layer "In2.Cu")
		(net "P5E_CPU0_PE4_TX_DN<4>")
	)
	(segment
		(start 336.305144 -295.577006)
		(end 329.817222 -308.03977)
		(width 0.14732)
		(layer "In2.Cu")
		(net "P5E_CPU0_PE4_TX_DN<4>")
	)
	(segment
		(start 340.32952 -289.719004)
		(end 340.32952 -290.30803)
		(width 0.0889)
		(layer "In2.Cu")
		(net "P5E_CPU0_PE4_TX_DN<4>")
	)
	(segment
		(start 340.082124 -289.377882)
		(end 340.150196 -289.415474)
		(width 0.0889)
		(layer "In2.Cu")
		(net "P5E_CPU0_PE4_TX_DN<4>")
	)
	(segment
		(start 341.520526 -285.932372)
		(end 341.496396 -286.021526)
		(width 0.0889)
		(layer "In2.Cu")
		(net "P5E_CPU0_PE4_TX_DN<4>")
	)
	(segment
		(start 313.64301 -324.213982)
		(end 312.625994 -324.635368)
		(width 0.14732)
		(layer "In2.Cu")
		(net "P5E_CPU0_PE4_TX_DN<4>")
	)
	(segment
		(start 316.527688 -400.563588)
		(end 316.233048 -400.858228)
		(width 0.14732)
		(layer "In2.Cu")
		(net "P5E_CPU0_PE4_TX_DN<4>")
	)
	(segment
		(start 339.923374 -290.92906)
		(end 339.923374 -290.951158)
		(width 0.0889)
		(layer "In2.Cu")
		(net "P5E_CPU0_PE4_TX_DN<4>")
	)
	(segment
		(start 312.625994 -324.635368)
		(end 309.962804 -324.635368)
		(width 0.14732)
		(layer "In2.Cu")
		(net "P5E_CPU0_PE4_TX_DN<4>")
	)
	(segment
		(start 329.817222 -308.03977)
		(end 313.64301 -324.213982)
		(width 0.14732)
		(layer "In2.Cu")
		(net "P5E_CPU0_PE4_TX_DN<4>")
	)
	(segment
		(start 308.011322 -327.582784)
		(end 306.77866 -333.780384)
		(width 0.14732)
		(layer "In2.Cu")
		(net "P5E_CPU0_PE4_TX_DN<4>")
	)
	(segment
		(start 340.329266 -288.09315)
		(end 340.329266 -288.103056)
		(width 0.0889)
		(layer "In2.Cu")
		(net "P5E_CPU0_PE4_TX_DN<4>")
	)
	(segment
		(start 339.965284 -290.672266)
		(end 339.965284 -290.88715)
		(width 0.0889)
		(layer "In2.Cu")
		(net "P5E_CPU0_PE4_TX_DN<4>")
	)
	(segment
		(start 341.364062 -285.661354)
		(end 341.520526 -285.932372)
		(width 0.0889)
		(layer "In2.Cu")
		(net "P5E_CPU0_PE4_TX_DN<4>")
	)
	(segment
		(start 308.011322 -326.558402)
		(end 308.011322 -327.582784)
		(width 0.14732)
		(layer "In2.Cu")
		(net "P5E_CPU0_PE4_TX_DN<4>")
	)
	(segment
		(start 339.965284 -290.88715)
		(end 339.923374 -290.92906)
		(width 0.0889)
		(layer "In2.Cu")
		(net "P5E_CPU0_PE4_TX_DN<4>")
	)
	(segment
		(start 306.77866 -333.780384)
		(end 306.77866 -343.248996)
		(width 0.14732)
		(layer "In2.Cu")
		(net "P5E_CPU0_PE4_TX_DN<4>")
	)
	(segment
		(start 340.150704 -288.422334)
		(end 340.141814 -288.427414)
		(width 0.0889)
		(layer "In2.Cu")
		(net "P5E_CPU0_PE4_TX_DN<4>")
	)
	(segment
		(start 339.923374 -291.958776)
		(end 336.305144 -295.577006)
		(width 0.14732)
		(layer "In2.Cu")
		(net "P5E_CPU0_PE4_TX_DN<4>")
	)
	(segment
		(start 341.090504 -286.794702)
		(end 341.075518 -286.803338)
		(width 0.0889)
		(layer "In2.Cu")
		(net "P5E_CPU0_PE4_TX_DN<4>")
	)
	(segment
		(start 308.356508 -325.725028)
		(end 308.011322 -326.558402)
		(width 0.14732)
		(layer "In2.Cu")
		(net "P5E_CPU0_PE4_TX_DN<4>")
	)
	(segment
		(start 306.77866 -343.248996)
		(end 307.073554 -344.923364)
		(width 0.14732)
		(layer "In2.Cu")
		(net "P5E_CPU0_PE4_TX_DN<4>")
	)
	(segment
		(start 341.268812 -286.475424)
		(end 341.269066 -286.475424)
		(width 0.0889)
		(layer "In2.Cu")
		(net "P5E_CPU0_PE4_TX_DN<4>")
	)
	(segment
		(start 309.962804 -324.635368)
		(end 309.08117 -325.000366)
		(width 0.14732)
		(layer "In2.Cu")
		(net "P5E_CPU0_PE4_TX_DN<4>")
	)
	(segment
		(start 316.527688 -397.990822)
		(end 316.527688 -400.563588)
		(width 0.14732)
		(layer "In2.Cu")
		(net "P5E_CPU0_PE4_TX_DN<4>")
	)
	(arc
		(start 339.859366 -289.114738)
		(mid 339.94639 -289.266928)
		(end 340.082124 -289.377882)
		(width 0.0889)
		(layer "In2.Cu")
		(net "P5E_CPU0_PE4_TX_DN<4>")
	)
	(arc
		(start 340.150196 -289.415474)
		(mid 340.281372 -289.54272)
		(end 340.32952 -289.719004)
		(width 0.0889)
		(layer "In2.Cu")
		(net "P5E_CPU0_PE4_TX_DN<4>")
	)
	(arc
		(start 340.141814 -288.427414)
		(mid 339.939528 -288.626395)
		(end 339.859366 -288.898584)
		(width 0.0889)
		(layer "In2.Cu")
		(net "P5E_CPU0_PE4_TX_DN<4>")
	)
	(arc
		(start 340.329266 -288.103056)
		(mid 340.281587 -288.285956)
		(end 340.150704 -288.422334)
		(width 0.0889)
		(layer "In2.Cu")
		(net "P5E_CPU0_PE4_TX_DN<4>")
	)
	(arc
		(start 340.798912 -287.297876)
		(mid 340.746642 -287.480241)
		(end 340.611714 -287.613598)
		(width 0.0889)
		(layer "In2.Cu")
		(net "P5E_CPU0_PE4_TX_DN<4>")
	)
	(arc
		(start 340.611714 -287.613598)
		(mid 340.407379 -287.816203)
		(end 340.329266 -288.09315)
		(width 0.0889)
		(layer "In2.Cu")
		(net "P5E_CPU0_PE4_TX_DN<4>")
	)
	(arc
		(start 341.496396 -286.021526)
		(mid 341.487953 -286.027924)
		(end 341.479632 -286.03448)
		(width 0.0889)
		(layer "In2.Cu")
		(net "P5E_CPU0_PE4_TX_DN<4>")
	)
	(arc
		(start 341.075518 -286.803338)
		(mid 340.872931 -287.009689)
		(end 340.798912 -287.28924)
		(width 0.0889)
		(layer "In2.Cu")
		(net "P5E_CPU0_PE4_TX_DN<4>")
	)
	(arc
		(start 341.269066 -286.475424)
		(mid 341.221387 -286.658324)
		(end 341.090504 -286.794702)
		(width 0.0889)
		(layer "In2.Cu")
		(net "P5E_CPU0_PE4_TX_DN<4>")
	)
	(arc
		(start 341.479632 -286.03448)
		(mid 341.327125 -286.224578)
		(end 341.268812 -286.4612)
		(width 0.0889)
		(layer "In2.Cu")
		(net "P5E_CPU0_PE4_TX_DN<4>")
	)
	(segment
		(start 340.424516 -285.125414)
		(end 340.424516 -285.6611)
		(width 0.13208)
		(layer "F.Cu")
		(net "P5E_CPU0_PE4_TX_DN<3>")
	)
	(segment
		(start 340.424516 -285.6611)
		(end 340.424262 -285.661354)
		(width 0.13208)
		(layer "F.Cu")
		(net "P5E_CPU0_PE4_TX_DN<3>")
	)
	(segment
		(start 313.47537 -401.777962)
		(end 313.14898 -402.104352)
		(width 0.13208)
		(layer "F.Cu")
		(net "P5E_CPU0_PE4_TX_DN<3>")
	)
	(segment
		(start 313.14898 -402.104352)
		(end 313.144408 -402.104352)
		(width 0.13208)
		(layer "F.Cu")
		(net "P5E_CPU0_PE4_TX_DN<3>")
	)
	(segment
		(start 313.47537 -401.16379)
		(end 313.47537 -401.777962)
		(width 0.13208)
		(layer "F.Cu")
		(net "P5E_CPU0_PE4_TX_DN<3>")
	)
	(segment
		(start 313.169808 -400.858228)
		(end 313.47537 -401.16379)
		(width 0.13208)
		(layer "F.Cu")
		(net "P5E_CPU0_PE4_TX_DN<3>")
	)
	(segment
		(start 339.26526 -289.477704)
		(end 339.389466 -289.683698)
		(width 0.0889)
		(layer "In2.Cu")
		(net "P5E_CPU0_PE4_TX_DN<3>")
	)
	(segment
		(start 307.059076 -326.386698)
		(end 307.059076 -327.535794)
		(width 0.14732)
		(layer "In2.Cu")
		(net "P5E_CPU0_PE4_TX_DN<3>")
	)
	(segment
		(start 309.640986 -361.323382)
		(end 313.345576 -396.1638)
		(width 0.14732)
		(layer "In2.Cu")
		(net "P5E_CPU0_PE4_TX_DN<3>")
	)
	(segment
		(start 339.033866 -290.396168)
		(end 339.033866 -290.922456)
		(width 0.0889)
		(layer "In2.Cu")
		(net "P5E_CPU0_PE4_TX_DN<3>")
	)
	(segment
		(start 313.464448 -398.661128)
		(end 313.464448 -400.563588)
		(width 0.14732)
		(layer "In2.Cu")
		(net "P5E_CPU0_PE4_TX_DN<3>")
	)
	(segment
		(start 314.215018 -322.31457)
		(end 310.88711 -323.693028)
		(width 0.14732)
		(layer "In2.Cu")
		(net "P5E_CPU0_PE4_TX_DN<3>")
	)
	(segment
		(start 340.32952 -286.475678)
		(end 340.32952 -286.481774)
		(width 0.0889)
		(layer "In2.Cu")
		(net "P5E_CPU0_PE4_TX_DN<3>")
	)
	(segment
		(start 340.142322 -286.799782)
		(end 340.131654 -286.806132)
		(width 0.0889)
		(layer "In2.Cu")
		(net "P5E_CPU0_PE4_TX_DN<3>")
	)
	(segment
		(start 328.779378 -307.750718)
		(end 314.215018 -322.31457)
		(width 0.14732)
		(layer "In2.Cu")
		(net "P5E_CPU0_PE4_TX_DN<3>")
	)
	(segment
		(start 313.345576 -396.1638)
		(end 313.235086 -396.300706)
		(width 0.14732)
		(layer "In2.Cu")
		(net "P5E_CPU0_PE4_TX_DN<3>")
	)
	(segment
		(start 307.059076 -327.535794)
		(end 305.842924 -333.650336)
		(width 0.14732)
		(layer "In2.Cu")
		(net "P5E_CPU0_PE4_TX_DN<3>")
	)
	(segment
		(start 313.464448 -400.563588)
		(end 313.169808 -400.858228)
		(width 0.14732)
		(layer "In2.Cu")
		(net "P5E_CPU0_PE4_TX_DN<3>")
	)
	(segment
		(start 313.464448 -397.280384)
		(end 313.464448 -397.975328)
		(width 0.14732)
		(layer "In2.Cu")
		(net "P5E_CPU0_PE4_TX_DN<3>")
	)
	(segment
		(start 340.580726 -285.390336)
		(end 340.658958 -285.369508)
		(width 0.0889)
		(layer "In2.Cu")
		(net "P5E_CPU0_PE4_TX_DN<3>")
	)
	(segment
		(start 340.424262 -285.661354)
		(end 340.580726 -285.390336)
		(width 0.0889)
		(layer "In2.Cu")
		(net "P5E_CPU0_PE4_TX_DN<3>")
	)
	(segment
		(start 339.20557 -289.446208)
		(end 339.26526 -289.477704)
		(width 0.0889)
		(layer "In2.Cu")
		(net "P5E_CPU0_PE4_TX_DN<3>")
	)
	(segment
		(start 338.91982 -288.91738)
		(end 338.91982 -289.113976)
		(width 0.0889)
		(layer "In2.Cu")
		(net "P5E_CPU0_PE4_TX_DN<3>")
	)
	(segment
		(start 338.991956 -291.461698)
		(end 335.37779 -295.075864)
		(width 0.14732)
		(layer "In2.Cu")
		(net "P5E_CPU0_PE4_TX_DN<3>")
	)
	(segment
		(start 338.991956 -290.986464)
		(end 338.991956 -291.461698)
		(width 0.14732)
		(layer "In2.Cu")
		(net "P5E_CPU0_PE4_TX_DN<3>")
	)
	(segment
		(start 339.38972 -288.103056)
		(end 339.38972 -288.114486)
		(width 0.0889)
		(layer "In2.Cu")
		(net "P5E_CPU0_PE4_TX_DN<3>")
	)
	(segment
		(start 340.79815 -285.611316)
		(end 340.798912 -285.680404)
		(width 0.0889)
		(layer "In2.Cu")
		(net "P5E_CPU0_PE4_TX_DN<3>")
	)
	(segment
		(start 306.174902 -345.215972)
		(end 309.640986 -361.323382)
		(width 0.14732)
		(layer "In2.Cu")
		(net "P5E_CPU0_PE4_TX_DN<3>")
	)
	(segment
		(start 339.667088 -287.6169)
		(end 339.663278 -287.618678)
		(width 0.0889)
		(layer "In2.Cu")
		(net "P5E_CPU0_PE4_TX_DN<3>")
	)
	(segment
		(start 340.329774 -286.453326)
		(end 340.329774 -286.453834)
		(width 0.0889)
		(layer "In2.Cu")
		(net "P5E_CPU0_PE4_TX_DN<3>")
	)
	(segment
		(start 340.612222 -285.985966)
		(end 340.601554 -285.992316)
		(width 0.0889)
		(layer "In2.Cu")
		(net "P5E_CPU0_PE4_TX_DN<3>")
	)
	(segment
		(start 339.672168 -287.613852)
		(end 339.668612 -287.615884)
		(width 0.0889)
		(layer "In2.Cu")
		(net "P5E_CPU0_PE4_TX_DN<3>")
	)
	(segment
		(start 339.202522 -288.427668)
		(end 339.191854 -288.434018)
		(width 0.0889)
		(layer "In2.Cu")
		(net "P5E_CPU0_PE4_TX_DN<3>")
	)
	(segment
		(start 307.549804 -325.201788)
		(end 307.059076 -326.386698)
		(width 0.14732)
		(layer "In2.Cu")
		(net "P5E_CPU0_PE4_TX_DN<3>")
	)
	(segment
		(start 310.88711 -323.693028)
		(end 309.760112 -323.693028)
		(width 0.14732)
		(layer "In2.Cu")
		(net "P5E_CPU0_PE4_TX_DN<3>")
	)
	(segment
		(start 339.85962 -287.28924)
		(end 339.85962 -287.297114)
		(width 0.0889)
		(layer "In2.Cu")
		(net "P5E_CPU0_PE4_TX_DN<3>")
	)
	(segment
		(start 339.033866 -290.922456)
		(end 338.991956 -290.964366)
		(width 0.0889)
		(layer "In2.Cu")
		(net "P5E_CPU0_PE4_TX_DN<3>")
	)
	(segment
		(start 340.658958 -285.369508)
		(end 340.659212 -285.368746)
		(width 0.0889)
		(layer "In2.Cu")
		(net "P5E_CPU0_PE4_TX_DN<3>")
	)
	(segment
		(start 313.41822 -396.84579)
		(end 313.464448 -397.280384)
		(width 0.14732)
		(layer "In2.Cu")
		(net "P5E_CPU0_PE4_TX_DN<3>")
	)
	(segment
		(start 313.339988 -398.536668)
		(end 313.464448 -398.661128)
		(width 0.14732)
		(layer "In2.Cu")
		(net "P5E_CPU0_PE4_TX_DN<3>")
	)
	(segment
		(start 313.281314 -396.735554)
		(end 313.41822 -396.84579)
		(width 0.14732)
		(layer "In2.Cu")
		(net "P5E_CPU0_PE4_TX_DN<3>")
	)
	(segment
		(start 313.339988 -398.099788)
		(end 313.339988 -398.536668)
		(width 0.14732)
		(layer "In2.Cu")
		(net "P5E_CPU0_PE4_TX_DN<3>")
	)
	(segment
		(start 313.464448 -397.975328)
		(end 313.339988 -398.099788)
		(width 0.14732)
		(layer "In2.Cu")
		(net "P5E_CPU0_PE4_TX_DN<3>")
	)
	(segment
		(start 313.235086 -396.300706)
		(end 313.281314 -396.735554)
		(width 0.14732)
		(layer "In2.Cu")
		(net "P5E_CPU0_PE4_TX_DN<3>")
	)
	(segment
		(start 338.991956 -290.964366)
		(end 338.991956 -290.986464)
		(width 0.0889)
		(layer "In2.Cu")
		(net "P5E_CPU0_PE4_TX_DN<3>")
	)
	(segment
		(start 335.37779 -295.075864)
		(end 328.779378 -307.750718)
		(width 0.14732)
		(layer "In2.Cu")
		(net "P5E_CPU0_PE4_TX_DN<3>")
	)
	(segment
		(start 305.842924 -333.650336)
		(end 305.842924 -343.331038)
		(width 0.14732)
		(layer "In2.Cu")
		(net "P5E_CPU0_PE4_TX_DN<3>")
	)
	(segment
		(start 339.389466 -289.683698)
		(end 339.389466 -290.200588)
		(width 0.0889)
		(layer "In2.Cu")
		(net "P5E_CPU0_PE4_TX_DN<3>")
	)
	(segment
		(start 339.668612 -287.615884)
		(end 339.667088 -287.6169)
		(width 0.0889)
		(layer "In2.Cu")
		(net "P5E_CPU0_PE4_TX_DN<3>")
	)
	(segment
		(start 308.562756 -324.188836)
		(end 307.549804 -325.201788)
		(width 0.14732)
		(layer "In2.Cu")
		(net "P5E_CPU0_PE4_TX_DN<3>")
	)
	(segment
		(start 340.65972 -285.369)
		(end 340.689438 -285.39313)
		(width 0.0889)
		(layer "In2.Cu")
		(net "P5E_CPU0_PE4_TX_DN<3>")
	)
	(segment
		(start 305.842924 -343.331038)
		(end 306.174902 -345.215972)
		(width 0.14732)
		(layer "In2.Cu")
		(net "P5E_CPU0_PE4_TX_DN<3>")
	)
	(segment
		(start 309.760112 -323.693028)
		(end 308.562756 -324.188836)
		(width 0.14732)
		(layer "In2.Cu")
		(net "P5E_CPU0_PE4_TX_DN<3>")
	)
	(segment
		(start 339.389466 -290.200588)
		(end 339.033866 -290.396168)
		(width 0.0889)
		(layer "In2.Cu")
		(net "P5E_CPU0_PE4_TX_DN<3>")
	)
	(segment
		(start 340.659212 -285.368746)
		(end 340.65972 -285.369)
		(width 0.0889)
		(layer "In2.Cu")
		(net "P5E_CPU0_PE4_TX_DN<3>")
	)
	(arc
		(start 339.191854 -288.434018)
		(mid 338.997897 -288.630302)
		(end 338.920074 -288.895028)
		(width 0.0889)
		(layer "In2.Cu")
		(net "P5E_CPU0_PE4_TX_DN<3>")
	)
	(arc
		(start 340.32952 -286.481774)
		(mid 340.277743 -286.665395)
		(end 340.142322 -286.799782)
		(width 0.0889)
		(layer "In2.Cu")
		(net "P5E_CPU0_PE4_TX_DN<3>")
	)
	(arc
		(start 338.920074 -288.895028)
		(mid 338.919838 -288.906203)
		(end 338.91982 -288.91738)
		(width 0.0889)
		(layer "In2.Cu")
		(net "P5E_CPU0_PE4_TX_DN<3>")
	)
	(arc
		(start 340.329774 -286.453834)
		(mid 340.329541 -286.464755)
		(end 340.32952 -286.475678)
		(width 0.0889)
		(layer "In2.Cu")
		(net "P5E_CPU0_PE4_TX_DN<3>")
	)
	(arc
		(start 339.85962 -287.297114)
		(mid 339.807393 -287.480032)
		(end 339.672168 -287.613852)
		(width 0.0889)
		(layer "In2.Cu")
		(net "P5E_CPU0_PE4_TX_DN<3>")
	)
	(arc
		(start 340.798912 -285.680404)
		(mid 340.744392 -285.856911)
		(end 340.612222 -285.985966)
		(width 0.0889)
		(layer "In2.Cu")
		(net "P5E_CPU0_PE4_TX_DN<3>")
	)
	(arc
		(start 339.663278 -287.618678)
		(mid 339.462772 -287.824878)
		(end 339.38972 -288.103056)
		(width 0.0889)
		(layer "In2.Cu")
		(net "P5E_CPU0_PE4_TX_DN<3>")
	)
	(arc
		(start 339.38972 -288.114486)
		(mid 339.336744 -288.295361)
		(end 339.202522 -288.427668)
		(width 0.0889)
		(layer "In2.Cu")
		(net "P5E_CPU0_PE4_TX_DN<3>")
	)
	(arc
		(start 340.601554 -285.992316)
		(mid 340.407597 -286.1886)
		(end 340.329774 -286.453326)
		(width 0.0889)
		(layer "In2.Cu")
		(net "P5E_CPU0_PE4_TX_DN<3>")
	)
	(arc
		(start 338.91982 -289.113976)
		(mid 339.031176 -289.307202)
		(end 339.20557 -289.446208)
		(width 0.0889)
		(layer "In2.Cu")
		(net "P5E_CPU0_PE4_TX_DN<3>")
	)
	(arc
		(start 340.689438 -285.39313)
		(mid 340.767686 -285.490322)
		(end 340.79815 -285.611316)
		(width 0.0889)
		(layer "In2.Cu")
		(net "P5E_CPU0_PE4_TX_DN<3>")
	)
	(arc
		(start 340.131654 -286.806132)
		(mid 339.93227 -287.012012)
		(end 339.85962 -287.28924)
		(width 0.0889)
		(layer "In2.Cu")
		(net "P5E_CPU0_PE4_TX_DN<3>")
	)
	(segment
		(start 310.08574 -402.104352)
		(end 310.081168 -402.104352)
		(width 0.13208)
		(layer "F.Cu")
		(net "P5E_CPU0_PE4_TX_DN<2>")
	)
	(segment
		(start 310.106568 -400.858228)
		(end 310.41213 -401.16379)
		(width 0.13208)
		(layer "F.Cu")
		(net "P5E_CPU0_PE4_TX_DN<2>")
	)
	(segment
		(start 310.41213 -401.777962)
		(end 310.08574 -402.104352)
		(width 0.13208)
		(layer "F.Cu")
		(net "P5E_CPU0_PE4_TX_DN<2>")
	)
	(segment
		(start 339.484716 -285.125414)
		(end 339.484716 -285.661354)
		(width 0.13208)
		(layer "F.Cu")
		(net "P5E_CPU0_PE4_TX_DN<2>")
	)
	(segment
		(start 310.41213 -401.16379)
		(end 310.41213 -401.777962)
		(width 0.13208)
		(layer "F.Cu")
		(net "P5E_CPU0_PE4_TX_DN<2>")
	)
	(segment
		(start 334.515968 -294.516556)
		(end 327.824084 -307.372258)
		(width 0.14732)
		(layer "In2.Cu")
		(net "P5E_CPU0_PE4_TX_DN<2>")
	)
	(segment
		(start 313.89447 -321.301872)
		(end 311.549034 -322.273168)
		(width 0.14732)
		(layer "In2.Cu")
		(net "P5E_CPU0_PE4_TX_DN<2>")
	)
	(segment
		(start 337.979766 -288.917126)
		(end 337.979766 -290.54679)
		(width 0.0889)
		(layer "In2.Cu")
		(net "P5E_CPU0_PE4_TX_DN<2>")
	)
	(segment
		(start 337.937856 -291.094922)
		(end 334.515968 -294.516556)
		(width 0.14732)
		(layer "In2.Cu")
		(net "P5E_CPU0_PE4_TX_DN<2>")
	)
	(segment
		(start 339.64118 -285.932372)
		(end 339.61705 -286.021526)
		(width 0.0889)
		(layer "In2.Cu")
		(net "P5E_CPU0_PE4_TX_DN<2>")
	)
	(segment
		(start 337.937856 -290.610798)
		(end 337.937856 -291.094922)
		(width 0.14732)
		(layer "In2.Cu")
		(net "P5E_CPU0_PE4_TX_DN<2>")
	)
	(segment
		(start 304.890678 -343.413334)
		(end 308.186074 -361.44327)
		(width 0.14732)
		(layer "In2.Cu")
		(net "P5E_CPU0_PE4_TX_DN<2>")
	)
	(segment
		(start 309.773574 -321.790568)
		(end 309.52948 -321.89166)
		(width 0.14732)
		(layer "In2.Cu")
		(net "P5E_CPU0_PE4_TX_DN<2>")
	)
	(segment
		(start 339.21065 -286.794702)
		(end 339.202776 -286.799274)
		(width 0.0889)
		(layer "In2.Cu")
		(net "P5E_CPU0_PE4_TX_DN<2>")
	)
	(segment
		(start 304.890678 -333.522828)
		(end 304.890678 -343.413334)
		(width 0.14732)
		(layer "In2.Cu")
		(net "P5E_CPU0_PE4_TX_DN<2>")
	)
	(segment
		(start 338.741004 -287.608518)
		(end 338.732114 -287.613598)
		(width 0.0889)
		(layer "In2.Cu")
		(net "P5E_CPU0_PE4_TX_DN<2>")
	)
	(segment
		(start 339.484716 -285.661354)
		(end 339.64118 -285.932372)
		(width 0.0889)
		(layer "In2.Cu")
		(net "P5E_CPU0_PE4_TX_DN<2>")
	)
	(segment
		(start 311.549034 -322.273168)
		(end 311.019698 -322.273168)
		(width 0.14732)
		(layer "In2.Cu")
		(net "P5E_CPU0_PE4_TX_DN<2>")
	)
	(segment
		(start 309.52948 -321.89166)
		(end 306.708556 -324.712838)
		(width 0.14732)
		(layer "In2.Cu")
		(net "P5E_CPU0_PE4_TX_DN<2>")
	)
	(segment
		(start 306.111148 -327.387966)
		(end 304.890678 -333.522828)
		(width 0.14732)
		(layer "In2.Cu")
		(net "P5E_CPU0_PE4_TX_DN<2>")
	)
	(segment
		(start 306.708556 -324.712838)
		(end 306.111148 -326.155304)
		(width 0.14732)
		(layer "In2.Cu")
		(net "P5E_CPU0_PE4_TX_DN<2>")
	)
	(segment
		(start 306.111148 -326.155304)
		(end 306.111148 -327.387966)
		(width 0.14732)
		(layer "In2.Cu")
		(net "P5E_CPU0_PE4_TX_DN<2>")
	)
	(segment
		(start 308.186074 -361.44327)
		(end 310.401208 -395.362938)
		(width 0.14732)
		(layer "In2.Cu")
		(net "P5E_CPU0_PE4_TX_DN<2>")
	)
	(segment
		(start 310.537098 -321.790568)
		(end 309.773574 -321.790568)
		(width 0.14732)
		(layer "In2.Cu")
		(net "P5E_CPU0_PE4_TX_DN<2>")
	)
	(segment
		(start 338.27085 -288.422334)
		(end 338.26196 -288.427414)
		(width 0.0889)
		(layer "In2.Cu")
		(net "P5E_CPU0_PE4_TX_DN<2>")
	)
	(segment
		(start 327.824084 -307.372258)
		(end 313.89447 -321.301872)
		(width 0.14732)
		(layer "In2.Cu")
		(net "P5E_CPU0_PE4_TX_DN<2>")
	)
	(segment
		(start 310.401208 -395.362938)
		(end 310.401208 -400.563588)
		(width 0.14732)
		(layer "In2.Cu")
		(net "P5E_CPU0_PE4_TX_DN<2>")
	)
	(segment
		(start 339.202776 -286.799274)
		(end 339.20176 -286.799782)
		(width 0.0889)
		(layer "In2.Cu")
		(net "P5E_CPU0_PE4_TX_DN<2>")
	)
	(segment
		(start 338.919566 -287.273746)
		(end 338.919566 -287.28924)
		(width 0.0889)
		(layer "In2.Cu")
		(net "P5E_CPU0_PE4_TX_DN<2>")
	)
	(segment
		(start 337.937856 -290.5887)
		(end 337.937856 -290.610798)
		(width 0.0889)
		(layer "In2.Cu")
		(net "P5E_CPU0_PE4_TX_DN<2>")
	)
	(segment
		(start 337.979766 -290.54679)
		(end 337.937856 -290.5887)
		(width 0.0889)
		(layer "In2.Cu")
		(net "P5E_CPU0_PE4_TX_DN<2>")
	)
	(segment
		(start 338.732114 -287.613598)
		(end 338.726018 -287.617154)
		(width 0.0889)
		(layer "In2.Cu")
		(net "P5E_CPU0_PE4_TX_DN<2>")
	)
	(segment
		(start 310.401208 -400.563588)
		(end 310.106568 -400.858228)
		(width 0.14732)
		(layer "In2.Cu")
		(net "P5E_CPU0_PE4_TX_DN<2>")
	)
	(segment
		(start 339.389212 -286.467804)
		(end 339.389212 -286.475424)
		(width 0.0889)
		(layer "In2.Cu")
		(net "P5E_CPU0_PE4_TX_DN<2>")
	)
	(segment
		(start 311.019698 -322.273168)
		(end 310.537098 -321.790568)
		(width 0.14732)
		(layer "In2.Cu")
		(net "P5E_CPU0_PE4_TX_DN<2>")
	)
	(arc
		(start 338.726018 -287.617154)
		(mid 338.523431 -287.823505)
		(end 338.449412 -288.103056)
		(width 0.0889)
		(layer "In2.Cu")
		(net "P5E_CPU0_PE4_TX_DN<2>")
	)
	(arc
		(start 338.240116 -288.44113)
		(mid 338.049138 -288.645865)
		(end 337.979766 -288.917126)
		(width 0.0889)
		(layer "In2.Cu")
		(net "P5E_CPU0_PE4_TX_DN<2>")
	)
	(arc
		(start 339.61705 -286.021526)
		(mid 339.608478 -286.028049)
		(end 339.600032 -286.034734)
		(width 0.0889)
		(layer "In2.Cu")
		(net "P5E_CPU0_PE4_TX_DN<2>")
	)
	(arc
		(start 338.26196 -288.427414)
		(mid 338.250958 -288.434145)
		(end 338.240116 -288.44113)
		(width 0.0889)
		(layer "In2.Cu")
		(net "P5E_CPU0_PE4_TX_DN<2>")
	)
	(arc
		(start 338.449412 -288.103056)
		(mid 338.44936 -288.110423)
		(end 338.449158 -288.117788)
		(width 0.0889)
		(layer "In2.Cu")
		(net "P5E_CPU0_PE4_TX_DN<2>")
	)
	(arc
		(start 338.919566 -287.28924)
		(mid 338.871887 -287.47214)
		(end 338.741004 -287.608518)
		(width 0.0889)
		(layer "In2.Cu")
		(net "P5E_CPU0_PE4_TX_DN<2>")
	)
	(arc
		(start 339.389212 -286.475424)
		(mid 339.341533 -286.658324)
		(end 339.21065 -286.794702)
		(width 0.0889)
		(layer "In2.Cu")
		(net "P5E_CPU0_PE4_TX_DN<2>")
	)
	(arc
		(start 339.600032 -286.034734)
		(mid 339.446214 -286.227701)
		(end 339.389212 -286.467804)
		(width 0.0889)
		(layer "In2.Cu")
		(net "P5E_CPU0_PE4_TX_DN<2>")
	)
	(arc
		(start 339.20176 -286.799782)
		(mid 338.998937 -287.000013)
		(end 338.919566 -287.273746)
		(width 0.0889)
		(layer "In2.Cu")
		(net "P5E_CPU0_PE4_TX_DN<2>")
	)
	(arc
		(start 338.449158 -288.117788)
		(mid 338.398104 -288.292368)
		(end 338.27085 -288.422334)
		(width 0.0889)
		(layer "In2.Cu")
		(net "P5E_CPU0_PE4_TX_DN<2>")
	)
	(segment
		(start 307.906928 -400.858228)
		(end 307.60797 -401.157186)
		(width 0.13208)
		(layer "F.Cu")
		(net "P5E_CPU0_PE4_TX_DN<1>")
	)
	(segment
		(start 307.60797 -401.157186)
		(end 307.60797 -401.779994)
		(width 0.13208)
		(layer "F.Cu")
		(net "P5E_CPU0_PE4_TX_DN<1>")
	)
	(segment
		(start 307.60797 -401.779994)
		(end 307.932328 -402.104352)
		(width 0.13208)
		(layer "F.Cu")
		(net "P5E_CPU0_PE4_TX_DN<1>")
	)
	(segment
		(start 339.014562 -284.311598)
		(end 339.014562 -284.847538)
		(width 0.13208)
		(layer "F.Cu")
		(net "P5E_CPU0_PE4_TX_DN<1>")
	)
	(segment
		(start 313.944254 -319.957196)
		(end 311.113932 -320.902584)
		(width 0.14732)
		(layer "In2.Cu")
		(net "P5E_CPU0_PE4_TX_DN<1>")
	)
	(segment
		(start 337.229704 -289.802824)
		(end 337.271868 -289.844988)
		(width 0.0889)
		(layer "In2.Cu")
		(net "P5E_CPU0_PE4_TX_DN<1>")
	)
	(segment
		(start 310.194706 -320.902584)
		(end 309.15102 -321.334892)
		(width 0.14732)
		(layer "In2.Cu")
		(net "P5E_CPU0_PE4_TX_DN<1>")
	)
	(segment
		(start 337.700112 -288.103056)
		(end 337.700112 -288.11728)
		(width 0.0889)
		(layer "In2.Cu")
		(net "P5E_CPU0_PE4_TX_DN<1>")
	)
	(segment
		(start 338.639912 -286.475424)
		(end 338.639912 -286.490918)
		(width 0.0889)
		(layer "In2.Cu")
		(net "P5E_CPU0_PE4_TX_DN<1>")
	)
	(segment
		(start 333.744316 -294.329866)
		(end 327.034398 -307.21681)
		(width 0.14732)
		(layer "In2.Cu")
		(net "P5E_CPU0_PE4_TX_DN<1>")
	)
	(segment
		(start 306.092098 -324.393814)
		(end 305.441604 -325.964296)
		(width 0.14732)
		(layer "In2.Cu")
		(net "P5E_CPU0_PE4_TX_DN<1>")
	)
	(segment
		(start 337.229704 -288.914078)
		(end 337.229704 -289.802824)
		(width 0.0889)
		(layer "In2.Cu")
		(net "P5E_CPU0_PE4_TX_DN<1>")
	)
	(segment
		(start 337.271868 -289.844988)
		(end 337.271868 -289.867086)
		(width 0.0889)
		(layer "In2.Cu")
		(net "P5E_CPU0_PE4_TX_DN<1>")
	)
	(segment
		(start 337.229958 -288.905696)
		(end 337.229704 -288.914078)
		(width 0.0889)
		(layer "In2.Cu")
		(net "P5E_CPU0_PE4_TX_DN<1>")
	)
	(segment
		(start 305.441604 -327.358502)
		(end 304.21707 -333.515208)
		(width 0.14732)
		(layer "In2.Cu")
		(net "P5E_CPU0_PE4_TX_DN<1>")
	)
	(segment
		(start 307.612288 -399.207228)
		(end 307.612288 -400.563588)
		(width 0.14732)
		(layer "In2.Cu")
		(net "P5E_CPU0_PE4_TX_DN<1>")
	)
	(segment
		(start 309.15102 -321.334892)
		(end 306.092098 -324.393814)
		(width 0.14732)
		(layer "In2.Cu")
		(net "P5E_CPU0_PE4_TX_DN<1>")
	)
	(segment
		(start 338.858098 -285.118556)
		(end 338.882228 -285.20771)
		(width 0.0889)
		(layer "In2.Cu")
		(net "P5E_CPU0_PE4_TX_DN<1>")
	)
	(segment
		(start 337.271868 -290.80206)
		(end 333.744316 -294.329866)
		(width 0.14732)
		(layer "In2.Cu")
		(net "P5E_CPU0_PE4_TX_DN<1>")
	)
	(segment
		(start 304.21707 -333.515208)
		(end 304.21707 -343.568528)
		(width 0.14732)
		(layer "In2.Cu")
		(net "P5E_CPU0_PE4_TX_DN<1>")
	)
	(segment
		(start 337.271868 -289.867086)
		(end 337.271868 -290.80206)
		(width 0.14732)
		(layer "In2.Cu")
		(net "P5E_CPU0_PE4_TX_DN<1>")
	)
	(segment
		(start 337.887564 -287.778698)
		(end 337.878674 -287.783778)
		(width 0.0889)
		(layer "In2.Cu")
		(net "P5E_CPU0_PE4_TX_DN<1>")
	)
	(segment
		(start 338.357718 -286.964882)
		(end 338.356702 -286.96539)
		(width 0.0889)
		(layer "In2.Cu")
		(net "P5E_CPU0_PE4_TX_DN<1>")
	)
	(segment
		(start 314.860686 -319.390522)
		(end 313.944254 -319.957196)
		(width 0.14732)
		(layer "In2.Cu")
		(net "P5E_CPU0_PE4_TX_DN<1>")
	)
	(segment
		(start 339.014562 -284.847538)
		(end 338.858098 -285.118556)
		(width 0.0889)
		(layer "In2.Cu")
		(net "P5E_CPU0_PE4_TX_DN<1>")
	)
	(segment
		(start 307.612288 -400.563588)
		(end 307.906928 -400.858228)
		(width 0.14732)
		(layer "In2.Cu")
		(net "P5E_CPU0_PE4_TX_DN<1>")
	)
	(segment
		(start 304.21707 -343.568528)
		(end 304.566828 -345.552522)
		(width 0.14732)
		(layer "In2.Cu")
		(net "P5E_CPU0_PE4_TX_DN<1>")
	)
	(segment
		(start 338.356702 -286.96539)
		(end 338.352892 -286.967676)
		(width 0.0889)
		(layer "In2.Cu")
		(net "P5E_CPU0_PE4_TX_DN<1>")
	)
	(segment
		(start 327.034398 -307.21681)
		(end 314.860686 -319.390522)
		(width 0.14732)
		(layer "In2.Cu")
		(net "P5E_CPU0_PE4_TX_DN<1>")
	)
	(segment
		(start 306.96535 -361.453938)
		(end 307.612288 -399.207228)
		(width 0.14732)
		(layer "In2.Cu")
		(net "P5E_CPU0_PE4_TX_DN<1>")
	)
	(segment
		(start 337.425792 -288.587942)
		(end 337.425792 -288.587688)
		(width 0.0889)
		(layer "In2.Cu")
		(net "P5E_CPU0_PE4_TX_DN<1>")
	)
	(segment
		(start 338.827364 -286.151066)
		(end 338.818474 -286.156146)
		(width 0.0889)
		(layer "In2.Cu")
		(net "P5E_CPU0_PE4_TX_DN<1>")
	)
	(segment
		(start 304.566828 -345.552522)
		(end 306.96535 -361.453938)
		(width 0.14732)
		(layer "In2.Cu")
		(net "P5E_CPU0_PE4_TX_DN<1>")
	)
	(segment
		(start 311.113932 -320.902584)
		(end 310.194706 -320.902584)
		(width 0.14732)
		(layer "In2.Cu")
		(net "P5E_CPU0_PE4_TX_DN<1>")
	)
	(segment
		(start 338.352892 -286.967676)
		(end 338.348828 -286.969962)
		(width 0.0889)
		(layer "In2.Cu")
		(net "P5E_CPU0_PE4_TX_DN<1>")
	)
	(segment
		(start 337.425792 -288.587688)
		(end 337.41741 -288.592514)
		(width 0.0889)
		(layer "In2.Cu")
		(net "P5E_CPU0_PE4_TX_DN<1>")
	)
	(segment
		(start 337.899756 -287.771586)
		(end 337.887564 -287.778698)
		(width 0.0889)
		(layer "In2.Cu")
		(net "P5E_CPU0_PE4_TX_DN<1>")
	)
	(segment
		(start 305.441604 -325.964296)
		(end 305.441604 -327.358502)
		(width 0.14732)
		(layer "In2.Cu")
		(net "P5E_CPU0_PE4_TX_DN<1>")
	)
	(arc
		(start 338.348828 -286.969962)
		(mid 338.217914 -287.106322)
		(end 338.170266 -287.28924)
		(width 0.0889)
		(layer "In2.Cu")
		(net "P5E_CPU0_PE4_TX_DN<1>")
	)
	(arc
		(start 338.639912 -286.490918)
		(mid 338.560542 -286.764652)
		(end 338.357718 -286.964882)
		(width 0.0889)
		(layer "In2.Cu")
		(net "P5E_CPU0_PE4_TX_DN<1>")
	)
	(arc
		(start 338.899246 -285.220918)
		(mid 339.108507 -285.704927)
		(end 338.827364 -286.151066)
		(width 0.0889)
		(layer "In2.Cu")
		(net "P5E_CPU0_PE4_TX_DN<1>")
	)
	(arc
		(start 338.170266 -287.28924)
		(mid 338.098031 -287.565764)
		(end 337.899756 -287.771586)
		(width 0.0889)
		(layer "In2.Cu")
		(net "P5E_CPU0_PE4_TX_DN<1>")
	)
	(arc
		(start 337.41741 -288.592514)
		(mid 337.283033 -288.724758)
		(end 337.229958 -288.905696)
		(width 0.0889)
		(layer "In2.Cu")
		(net "P5E_CPU0_PE4_TX_DN<1>")
	)
	(arc
		(start 337.878674 -287.783778)
		(mid 337.74776 -287.920138)
		(end 337.700112 -288.103056)
		(width 0.0889)
		(layer "In2.Cu")
		(net "P5E_CPU0_PE4_TX_DN<1>")
	)
	(arc
		(start 338.818474 -286.156146)
		(mid 338.68756 -286.292506)
		(end 338.639912 -286.475424)
		(width 0.0889)
		(layer "In2.Cu")
		(net "P5E_CPU0_PE4_TX_DN<1>")
	)
	(arc
		(start 338.882228 -285.20771)
		(mid 338.8908 -285.214232)
		(end 338.899246 -285.220918)
		(width 0.0889)
		(layer "In2.Cu")
		(net "P5E_CPU0_PE4_TX_DN<1>")
	)
	(arc
		(start 337.700112 -288.11728)
		(mid 337.623346 -288.387798)
		(end 337.425792 -288.587942)
		(width 0.0889)
		(layer "In2.Cu")
		(net "P5E_CPU0_PE4_TX_DN<1>")
	)
	(segment
		(start 350.23425 -401.16379)
		(end 350.23425 -401.777962)
		(width 0.13208)
		(layer "F.Cu")
		(net "P5E_CPU0_PE4_TX_DN<15>")
	)
	(segment
		(start 349.90786 -402.104352)
		(end 349.903288 -402.104352)
		(width 0.13208)
		(layer "F.Cu")
		(net "P5E_CPU0_PE4_TX_DN<15>")
	)
	(segment
		(start 351.702116 -285.6611)
		(end 351.701862 -285.661354)
		(width 0.13208)
		(layer "F.Cu")
		(net "P5E_CPU0_PE4_TX_DN<15>")
	)
	(segment
		(start 350.23425 -401.777962)
		(end 349.90786 -402.104352)
		(width 0.13208)
		(layer "F.Cu")
		(net "P5E_CPU0_PE4_TX_DN<15>")
	)
	(segment
		(start 349.928688 -400.858228)
		(end 350.23425 -401.16379)
		(width 0.13208)
		(layer "F.Cu")
		(net "P5E_CPU0_PE4_TX_DN<15>")
	)
	(segment
		(start 351.702116 -285.125414)
		(end 351.702116 -285.6611)
		(width 0.13208)
		(layer "F.Cu")
		(net "P5E_CPU0_PE4_TX_DN<15>")
	)
	(segment
		(start 349.928688 -400.858228)
		(end 350.223328 -400.563588)
		(width 0.14732)
		(layer "In2.Cu")
		(net "P5E_CPU0_PE4_TX_DN<15>")
	)
	(segment
		(start 350.8248 -290.611052)
		(end 350.86671 -290.569142)
		(width 0.0889)
		(layer "In2.Cu")
		(net "P5E_CPU0_PE4_TX_DN<15>")
	)
	(segment
		(start 317.321438 -343.028524)
		(end 317.191898 -342.292686)
		(width 0.14732)
		(layer "In2.Cu")
		(net "P5E_CPU0_PE4_TX_DN<15>")
	)
	(segment
		(start 351.936558 -285.369508)
		(end 351.858326 -285.390336)
		(width 0.0889)
		(layer "In2.Cu")
		(net "P5E_CPU0_PE4_TX_DN<15>")
	)
	(segment
		(start 350.480376 -288.426906)
		(end 350.488504 -288.422334)
		(width 0.0889)
		(layer "In2.Cu")
		(net "P5E_CPU0_PE4_TX_DN<15>")
	)
	(segment
		(start 349.572072 -398.871948)
		(end 349.352616 -398.493742)
		(width 0.14732)
		(layer "In2.Cu")
		(net "P5E_CPU0_PE4_TX_DN<15>")
	)
	(segment
		(start 350.94926 -287.613598)
		(end 350.95815 -287.608518)
		(width 0.0889)
		(layer "In2.Cu")
		(net "P5E_CPU0_PE4_TX_DN<15>")
	)
	(segment
		(start 350.86671 -290.569142)
		(end 350.86671 -290.414964)
		(width 0.0889)
		(layer "In2.Cu")
		(net "P5E_CPU0_PE4_TX_DN<15>")
	)
	(segment
		(start 351.413318 -286.803338)
		(end 351.415858 -286.802068)
		(width 0.0889)
		(layer "In2.Cu")
		(net "P5E_CPU0_PE4_TX_DN<15>")
	)
	(segment
		(start 350.666812 -290.215066)
		(end 350.666812 -289.658298)
		(width 0.0889)
		(layer "In2.Cu")
		(net "P5E_CPU0_PE4_TX_DN<15>")
	)
	(segment
		(start 350.667066 -288.103056)
		(end 350.667066 -288.087562)
		(width 0.0889)
		(layer "In2.Cu")
		(net "P5E_CPU0_PE4_TX_DN<15>")
	)
	(segment
		(start 350.86671 -290.414964)
		(end 350.666812 -290.215066)
		(width 0.0889)
		(layer "In2.Cu")
		(net "P5E_CPU0_PE4_TX_DN<15>")
	)
	(segment
		(start 349.742252 -398.91716)
		(end 349.572072 -398.871948)
		(width 0.14732)
		(layer "In2.Cu")
		(net "P5E_CPU0_PE4_TX_DN<15>")
	)
	(segment
		(start 350.8248 -290.63315)
		(end 350.8248 -290.611052)
		(width 0.0889)
		(layer "In2.Cu")
		(net "P5E_CPU0_PE4_TX_DN<15>")
	)
	(segment
		(start 350.479614 -288.427414)
		(end 350.480376 -288.426906)
		(width 0.0889)
		(layer "In2.Cu")
		(net "P5E_CPU0_PE4_TX_DN<15>")
	)
	(segment
		(start 349.0087 -397.900652)
		(end 348.789244 -397.522446)
		(width 0.14732)
		(layer "In2.Cu")
		(net "P5E_CPU0_PE4_TX_DN<15>")
	)
	(segment
		(start 338.345272 -314.722002)
		(end 348.610428 -304.456846)
		(width 0.14732)
		(layer "In2.Cu")
		(net "P5E_CPU0_PE4_TX_DN<15>")
	)
	(segment
		(start 349.352616 -398.493742)
		(end 349.397828 -398.323562)
		(width 0.14732)
		(layer "In2.Cu")
		(net "P5E_CPU0_PE4_TX_DN<15>")
	)
	(segment
		(start 348.789244 -397.522446)
		(end 348.834456 -397.352266)
		(width 0.14732)
		(layer "In2.Cu")
		(net "P5E_CPU0_PE4_TX_DN<15>")
	)
	(segment
		(start 349.397828 -398.323562)
		(end 349.178626 -397.945864)
		(width 0.14732)
		(layer "In2.Cu")
		(net "P5E_CPU0_PE4_TX_DN<15>")
	)
	(segment
		(start 350.197166 -289.114738)
		(end 350.197166 -288.898584)
		(width 0.0889)
		(layer "In2.Cu")
		(net "P5E_CPU0_PE4_TX_DN<15>")
	)
	(segment
		(start 351.88906 -285.985712)
		(end 351.89795 -285.980632)
		(width 0.0889)
		(layer "In2.Cu")
		(net "P5E_CPU0_PE4_TX_DN<15>")
	)
	(segment
		(start 350.8248 -297.744388)
		(end 350.8248 -290.63315)
		(width 0.14732)
		(layer "In2.Cu")
		(net "P5E_CPU0_PE4_TX_DN<15>")
	)
	(segment
		(start 317.648844 -334.798416)
		(end 336.476594 -315.970666)
		(width 0.14732)
		(layer "In2.Cu")
		(net "P5E_CPU0_PE4_TX_DN<15>")
	)
	(segment
		(start 349.178626 -397.945864)
		(end 349.0087 -397.900652)
		(width 0.14732)
		(layer "In2.Cu")
		(net "P5E_CPU0_PE4_TX_DN<15>")
	)
	(segment
		(start 350.223328 -399.74647)
		(end 349.742252 -398.91716)
		(width 0.14732)
		(layer "In2.Cu")
		(net "P5E_CPU0_PE4_TX_DN<15>")
	)
	(segment
		(start 351.418652 -286.80029)
		(end 351.419414 -286.799782)
		(width 0.0889)
		(layer "In2.Cu")
		(net "P5E_CPU0_PE4_TX_DN<15>")
	)
	(segment
		(start 317.191898 -335.902046)
		(end 317.648844 -334.798416)
		(width 0.14732)
		(layer "In2.Cu")
		(net "P5E_CPU0_PE4_TX_DN<15>")
	)
	(segment
		(start 351.606612 -286.48406)
		(end 351.606612 -286.456882)
		(width 0.0889)
		(layer "In2.Cu")
		(net "P5E_CPU0_PE4_TX_DN<15>")
	)
	(segment
		(start 336.476594 -315.970666)
		(end 338.345272 -314.722002)
		(width 0.14732)
		(layer "In2.Cu")
		(net "P5E_CPU0_PE4_TX_DN<15>")
	)
	(segment
		(start 348.834456 -397.352266)
		(end 317.321438 -343.028524)
		(width 0.14732)
		(layer "In2.Cu")
		(net "P5E_CPU0_PE4_TX_DN<15>")
	)
	(segment
		(start 351.415858 -286.802068)
		(end 351.418652 -286.80029)
		(width 0.0889)
		(layer "In2.Cu")
		(net "P5E_CPU0_PE4_TX_DN<15>")
	)
	(segment
		(start 348.610428 -304.456846)
		(end 350.169226 -301.462948)
		(width 0.14732)
		(layer "In2.Cu")
		(net "P5E_CPU0_PE4_TX_DN<15>")
	)
	(segment
		(start 350.169226 -301.462948)
		(end 350.8248 -297.744388)
		(width 0.14732)
		(layer "In2.Cu")
		(net "P5E_CPU0_PE4_TX_DN<15>")
	)
	(segment
		(start 351.858326 -285.390336)
		(end 351.701862 -285.661354)
		(width 0.0889)
		(layer "In2.Cu")
		(net "P5E_CPU0_PE4_TX_DN<15>")
	)
	(segment
		(start 350.223328 -400.563588)
		(end 350.223328 -399.74647)
		(width 0.14732)
		(layer "In2.Cu")
		(net "P5E_CPU0_PE4_TX_DN<15>")
	)
	(segment
		(start 317.191898 -342.292686)
		(end 317.191898 -335.902046)
		(width 0.14732)
		(layer "In2.Cu")
		(net "P5E_CPU0_PE4_TX_DN<15>")
	)
	(arc
		(start 351.136712 -287.28924)
		(mid 351.210703 -287.009674)
		(end 351.413318 -286.803338)
		(width 0.0889)
		(layer "In2.Cu")
		(net "P5E_CPU0_PE4_TX_DN<15>")
	)
	(arc
		(start 350.482662 -289.446462)
		(mid 350.30853 -289.307615)
		(end 350.197166 -289.114738)
		(width 0.0889)
		(layer "In2.Cu")
		(net "P5E_CPU0_PE4_TX_DN<15>")
	)
	(arc
		(start 351.606612 -286.456882)
		(mid 351.686774 -286.184693)
		(end 351.88906 -285.985712)
		(width 0.0889)
		(layer "In2.Cu")
		(net "P5E_CPU0_PE4_TX_DN<15>")
	)
	(arc
		(start 351.89795 -285.980632)
		(mid 352.028864 -285.844272)
		(end 352.076512 -285.661354)
		(width 0.0889)
		(layer "In2.Cu")
		(net "P5E_CPU0_PE4_TX_DN<15>")
	)
	(arc
		(start 352.076512 -285.661354)
		(mid 352.039652 -285.499557)
		(end 351.936558 -285.369508)
		(width 0.0889)
		(layer "In2.Cu")
		(net "P5E_CPU0_PE4_TX_DN<15>")
	)
	(arc
		(start 350.666812 -289.658298)
		(mid 350.665517 -289.645682)
		(end 350.661478 -289.63366)
		(width 0.0889)
		(layer "In2.Cu")
		(net "P5E_CPU0_PE4_TX_DN<15>")
	)
	(arc
		(start 351.419414 -286.799782)
		(mid 351.554347 -286.666428)
		(end 351.606612 -286.48406)
		(width 0.0889)
		(layer "In2.Cu")
		(net "P5E_CPU0_PE4_TX_DN<15>")
	)
	(arc
		(start 350.667066 -288.087562)
		(mid 350.746436 -287.813828)
		(end 350.94926 -287.613598)
		(width 0.0889)
		(layer "In2.Cu")
		(net "P5E_CPU0_PE4_TX_DN<15>")
	)
	(arc
		(start 350.488504 -288.422334)
		(mid 350.619418 -288.285974)
		(end 350.667066 -288.103056)
		(width 0.0889)
		(layer "In2.Cu")
		(net "P5E_CPU0_PE4_TX_DN<15>")
	)
	(arc
		(start 350.95815 -287.608518)
		(mid 351.089064 -287.472158)
		(end 351.136712 -287.28924)
		(width 0.0889)
		(layer "In2.Cu")
		(net "P5E_CPU0_PE4_TX_DN<15>")
	)
	(arc
		(start 350.197166 -288.898584)
		(mid 350.277328 -288.626395)
		(end 350.479614 -288.427414)
		(width 0.0889)
		(layer "In2.Cu")
		(net "P5E_CPU0_PE4_TX_DN<15>")
	)
	(arc
		(start 350.661478 -289.63366)
		(mid 350.587284 -289.525538)
		(end 350.482662 -289.446462)
		(width 0.0889)
		(layer "In2.Cu")
		(net "P5E_CPU0_PE4_TX_DN<15>")
	)
	(segment
		(start 347.17101 -401.16379)
		(end 347.17101 -401.777962)
		(width 0.13208)
		(layer "F.Cu")
		(net "P5E_CPU0_PE4_TX_DN<14>")
	)
	(segment
		(start 346.84462 -402.104352)
		(end 346.840048 -402.104352)
		(width 0.13208)
		(layer "F.Cu")
		(net "P5E_CPU0_PE4_TX_DN<14>")
	)
	(segment
		(start 347.17101 -401.777962)
		(end 346.84462 -402.104352)
		(width 0.13208)
		(layer "F.Cu")
		(net "P5E_CPU0_PE4_TX_DN<14>")
	)
	(segment
		(start 350.762316 -285.125414)
		(end 350.762316 -285.6611)
		(width 0.13208)
		(layer "F.Cu")
		(net "P5E_CPU0_PE4_TX_DN<14>")
	)
	(segment
		(start 346.865448 -400.858228)
		(end 347.17101 -401.16379)
		(width 0.13208)
		(layer "F.Cu")
		(net "P5E_CPU0_PE4_TX_DN<14>")
	)
	(segment
		(start 350.762316 -285.6611)
		(end 350.762062 -285.661354)
		(width 0.13208)
		(layer "F.Cu")
		(net "P5E_CPU0_PE4_TX_DN<14>")
	)
	(segment
		(start 350.489266 -286.794194)
		(end 350.48063 -286.799528)
		(width 0.0889)
		(layer "In2.Cu")
		(net "P5E_CPU0_PE4_TX_DN<14>")
	)
	(segment
		(start 349.92437 -290.714684)
		(end 349.92437 -291.013896)
		(width 0.0889)
		(layer "In2.Cu")
		(net "P5E_CPU0_PE4_TX_DN<14>")
	)
	(segment
		(start 349.727266 -290.610036)
		(end 349.92437 -290.714684)
		(width 0.0889)
		(layer "In2.Cu")
		(net "P5E_CPU0_PE4_TX_DN<14>")
	)
	(segment
		(start 335.90103 -315.181234)
		(end 316.83452 -334.247744)
		(width 0.14732)
		(layer "In2.Cu")
		(net "P5E_CPU0_PE4_TX_DN<14>")
	)
	(segment
		(start 316.83452 -334.247744)
		(end 316.262258 -335.629504)
		(width 0.14732)
		(layer "In2.Cu")
		(net "P5E_CPU0_PE4_TX_DN<14>")
	)
	(segment
		(start 316.262258 -335.629504)
		(end 316.262258 -342.417146)
		(width 0.14732)
		(layer "In2.Cu")
		(net "P5E_CPU0_PE4_TX_DN<14>")
	)
	(segment
		(start 349.88246 -291.077904)
		(end 349.88246 -297.244262)
		(width 0.14732)
		(layer "In2.Cu")
		(net "P5E_CPU0_PE4_TX_DN<14>")
	)
	(segment
		(start 316.42685 -343.351866)
		(end 347.160088 -399.706084)
		(width 0.14732)
		(layer "In2.Cu")
		(net "P5E_CPU0_PE4_TX_DN<14>")
	)
	(segment
		(start 347.160088 -399.706084)
		(end 347.160088 -400.563588)
		(width 0.14732)
		(layer "In2.Cu")
		(net "P5E_CPU0_PE4_TX_DN<14>")
	)
	(segment
		(start 350.918526 -285.932372)
		(end 350.894396 -286.021526)
		(width 0.0889)
		(layer "In2.Cu")
		(net "P5E_CPU0_PE4_TX_DN<14>")
	)
	(segment
		(start 350.010222 -287.613598)
		(end 349.999554 -287.619948)
		(width 0.0889)
		(layer "In2.Cu")
		(net "P5E_CPU0_PE4_TX_DN<14>")
	)
	(segment
		(start 350.197166 -287.28924)
		(end 350.197166 -287.301686)
		(width 0.0889)
		(layer "In2.Cu")
		(net "P5E_CPU0_PE4_TX_DN<14>")
	)
	(segment
		(start 350.762062 -285.661354)
		(end 350.918526 -285.932372)
		(width 0.0889)
		(layer "In2.Cu")
		(net "P5E_CPU0_PE4_TX_DN<14>")
	)
	(segment
		(start 350.48063 -286.799528)
		(end 350.47174 -286.804608)
		(width 0.0889)
		(layer "In2.Cu")
		(net "P5E_CPU0_PE4_TX_DN<14>")
	)
	(segment
		(start 316.262258 -342.417146)
		(end 316.42685 -343.351866)
		(width 0.14732)
		(layer "In2.Cu")
		(net "P5E_CPU0_PE4_TX_DN<14>")
	)
	(segment
		(start 349.72752 -288.103056)
		(end 349.72752 -288.118042)
		(width 0.0889)
		(layer "In2.Cu")
		(net "P5E_CPU0_PE4_TX_DN<14>")
	)
	(segment
		(start 350.47174 -286.804608)
		(end 350.466152 -286.80791)
		(width 0.0889)
		(layer "In2.Cu")
		(net "P5E_CPU0_PE4_TX_DN<14>")
	)
	(segment
		(start 349.727266 -289.645344)
		(end 349.727266 -290.610036)
		(width 0.0889)
		(layer "In2.Cu")
		(net "P5E_CPU0_PE4_TX_DN<14>")
	)
	(segment
		(start 337.833462 -313.889898)
		(end 335.90103 -315.181234)
		(width 0.14732)
		(layer "In2.Cu")
		(net "P5E_CPU0_PE4_TX_DN<14>")
	)
	(segment
		(start 349.172784 -301.268638)
		(end 347.780356 -303.943004)
		(width 0.14732)
		(layer "In2.Cu")
		(net "P5E_CPU0_PE4_TX_DN<14>")
	)
	(segment
		(start 347.780356 -303.943004)
		(end 337.833462 -313.889898)
		(width 0.14732)
		(layer "In2.Cu")
		(net "P5E_CPU0_PE4_TX_DN<14>")
	)
	(segment
		(start 349.88246 -297.244262)
		(end 349.172784 -301.268638)
		(width 0.14732)
		(layer "In2.Cu")
		(net "P5E_CPU0_PE4_TX_DN<14>")
	)
	(segment
		(start 347.160088 -400.563588)
		(end 346.865448 -400.858228)
		(width 0.14732)
		(layer "In2.Cu")
		(net "P5E_CPU0_PE4_TX_DN<14>")
	)
	(segment
		(start 349.92437 -291.013896)
		(end 349.88246 -291.055806)
		(width 0.0889)
		(layer "In2.Cu")
		(net "P5E_CPU0_PE4_TX_DN<14>")
	)
	(segment
		(start 349.25762 -288.917126)
		(end 349.25762 -289.113976)
		(width 0.0889)
		(layer "In2.Cu")
		(net "P5E_CPU0_PE4_TX_DN<14>")
	)
	(segment
		(start 349.88246 -291.055806)
		(end 349.88246 -291.077904)
		(width 0.0889)
		(layer "In2.Cu")
		(net "P5E_CPU0_PE4_TX_DN<14>")
	)
	(segment
		(start 350.894396 -286.021526)
		(end 350.894904 -286.021272)
		(width 0.0889)
		(layer "In2.Cu")
		(net "P5E_CPU0_PE4_TX_DN<14>")
	)
	(segment
		(start 349.540322 -288.427668)
		(end 349.529654 -288.434018)
		(width 0.0889)
		(layer "In2.Cu")
		(net "P5E_CPU0_PE4_TX_DN<14>")
	)
	(arc
		(start 349.25762 -289.113976)
		(mid 349.36885 -289.30718)
		(end 349.543116 -289.446208)
		(width 0.0889)
		(layer "In2.Cu")
		(net "P5E_CPU0_PE4_TX_DN<14>")
	)
	(arc
		(start 350.894904 -286.021272)
		(mid 350.727072 -286.221308)
		(end 350.667066 -286.475424)
		(width 0.0889)
		(layer "In2.Cu")
		(net "P5E_CPU0_PE4_TX_DN<14>")
	)
	(arc
		(start 349.543116 -289.446208)
		(mid 349.652219 -289.530034)
		(end 349.727266 -289.645344)
		(width 0.0889)
		(layer "In2.Cu")
		(net "P5E_CPU0_PE4_TX_DN<14>")
	)
	(arc
		(start 350.197166 -287.301686)
		(mid 350.144024 -287.481816)
		(end 350.010222 -287.613598)
		(width 0.0889)
		(layer "In2.Cu")
		(net "P5E_CPU0_PE4_TX_DN<14>")
	)
	(arc
		(start 349.999554 -287.619948)
		(mid 349.80017 -287.825828)
		(end 349.72752 -288.103056)
		(width 0.0889)
		(layer "In2.Cu")
		(net "P5E_CPU0_PE4_TX_DN<14>")
	)
	(arc
		(start 350.466152 -286.80791)
		(mid 350.268976 -287.013545)
		(end 350.197166 -287.28924)
		(width 0.0889)
		(layer "In2.Cu")
		(net "P5E_CPU0_PE4_TX_DN<14>")
	)
	(arc
		(start 349.529654 -288.434018)
		(mid 349.33027 -288.639898)
		(end 349.25762 -288.917126)
		(width 0.0889)
		(layer "In2.Cu")
		(net "P5E_CPU0_PE4_TX_DN<14>")
	)
	(arc
		(start 349.72752 -288.118042)
		(mid 349.673715 -288.296917)
		(end 349.540322 -288.427668)
		(width 0.0889)
		(layer "In2.Cu")
		(net "P5E_CPU0_PE4_TX_DN<14>")
	)
	(arc
		(start 350.667066 -286.475424)
		(mid 350.61961 -286.657925)
		(end 350.489266 -286.794194)
		(width 0.0889)
		(layer "In2.Cu")
		(net "P5E_CPU0_PE4_TX_DN<14>")
	)
	(segment
		(start 349.822516 -285.125414)
		(end 349.822516 -285.6611)
		(width 0.13208)
		(layer "F.Cu")
		(net "P5E_CPU0_PE4_TX_DN<13>")
	)
	(segment
		(start 343.802208 -400.858228)
		(end 344.10777 -401.16379)
		(width 0.13208)
		(layer "F.Cu")
		(net "P5E_CPU0_PE4_TX_DN<13>")
	)
	(segment
		(start 343.78138 -402.104352)
		(end 343.776808 -402.104352)
		(width 0.13208)
		(layer "F.Cu")
		(net "P5E_CPU0_PE4_TX_DN<13>")
	)
	(segment
		(start 344.10777 -401.777962)
		(end 343.78138 -402.104352)
		(width 0.13208)
		(layer "F.Cu")
		(net "P5E_CPU0_PE4_TX_DN<13>")
	)
	(segment
		(start 349.822516 -285.6611)
		(end 349.822262 -285.661354)
		(width 0.13208)
		(layer "F.Cu")
		(net "P5E_CPU0_PE4_TX_DN<13>")
	)
	(segment
		(start 344.10777 -401.16379)
		(end 344.10777 -401.777962)
		(width 0.13208)
		(layer "F.Cu")
		(net "P5E_CPU0_PE4_TX_DN<13>")
	)
	(segment
		(start 342.87841 -397.439896)
		(end 343.045796 -397.495522)
		(width 0.14732)
		(layer "In2.Cu")
		(net "P5E_CPU0_PE4_TX_DN<13>")
	)
	(segment
		(start 323.203824 -357.909876)
		(end 342.738202 -396.882112)
		(width 0.14732)
		(layer "In2.Cu")
		(net "P5E_CPU0_PE4_TX_DN<13>")
	)
	(segment
		(start 348.745556 -290.883086)
		(end 348.745556 -290.905184)
		(width 0.0889)
		(layer "In2.Cu")
		(net "P5E_CPU0_PE4_TX_DN<13>")
	)
	(segment
		(start 348.787212 -289.644836)
		(end 348.787466 -289.645344)
		(width 0.0889)
		(layer "In2.Cu")
		(net "P5E_CPU0_PE4_TX_DN<13>")
	)
	(segment
		(start 315.99251 -333.767684)
		(end 315.297312 -335.446116)
		(width 0.14732)
		(layer "In2.Cu")
		(net "P5E_CPU0_PE4_TX_DN<13>")
	)
	(segment
		(start 348.787466 -290.841176)
		(end 348.745556 -290.883086)
		(width 0.0889)
		(layer "In2.Cu")
		(net "P5E_CPU0_PE4_TX_DN<13>")
	)
	(segment
		(start 315.488574 -343.58834)
		(end 323.203824 -357.909876)
		(width 0.14732)
		(layer "In2.Cu")
		(net "P5E_CPU0_PE4_TX_DN<13>")
	)
	(segment
		(start 343.241376 -397.88592)
		(end 343.18575 -398.053052)
		(width 0.14732)
		(layer "In2.Cu")
		(net "P5E_CPU0_PE4_TX_DN<13>")
	)
	(segment
		(start 349.822262 -285.661354)
		(end 349.978726 -285.390336)
		(width 0.0889)
		(layer "In2.Cu")
		(net "P5E_CPU0_PE4_TX_DN<13>")
	)
	(segment
		(start 348.787466 -289.645344)
		(end 348.787466 -290.841176)
		(width 0.0889)
		(layer "In2.Cu")
		(net "P5E_CPU0_PE4_TX_DN<13>")
	)
	(segment
		(start 350.05772 -285.369)
		(end 350.109282 -285.410656)
		(width 0.0889)
		(layer "In2.Cu")
		(net "P5E_CPU0_PE4_TX_DN<13>")
	)
	(segment
		(start 343.18575 -398.053052)
		(end 343.381584 -398.443958)
		(width 0.14732)
		(layer "In2.Cu")
		(net "P5E_CPU0_PE4_TX_DN<13>")
	)
	(segment
		(start 337.253326 -313.121294)
		(end 335.400396 -314.359544)
		(width 0.14732)
		(layer "In2.Cu")
		(net "P5E_CPU0_PE4_TX_DN<13>")
	)
	(segment
		(start 343.045796 -397.495522)
		(end 343.241376 -397.88592)
		(width 0.14732)
		(layer "In2.Cu")
		(net "P5E_CPU0_PE4_TX_DN<13>")
	)
	(segment
		(start 349.257366 -287.28924)
		(end 349.257366 -287.301686)
		(width 0.0889)
		(layer "In2.Cu")
		(net "P5E_CPU0_PE4_TX_DN<13>")
	)
	(segment
		(start 342.682576 -397.049244)
		(end 342.87841 -397.439896)
		(width 0.14732)
		(layer "In2.Cu")
		(net "P5E_CPU0_PE4_TX_DN<13>")
	)
	(segment
		(start 343.381584 -398.443958)
		(end 343.548716 -398.49933)
		(width 0.14732)
		(layer "In2.Cu")
		(net "P5E_CPU0_PE4_TX_DN<13>")
	)
	(segment
		(start 349.070422 -287.613598)
		(end 349.059754 -287.619948)
		(width 0.0889)
		(layer "In2.Cu")
		(net "P5E_CPU0_PE4_TX_DN<13>")
	)
	(segment
		(start 349.539052 -286.800544)
		(end 349.537528 -286.801306)
		(width 0.0889)
		(layer "In2.Cu")
		(net "P5E_CPU0_PE4_TX_DN<13>")
	)
	(segment
		(start 348.78772 -288.103056)
		(end 348.78772 -288.118042)
		(width 0.0889)
		(layer "In2.Cu")
		(net "P5E_CPU0_PE4_TX_DN<13>")
	)
	(segment
		(start 348.31782 -288.917126)
		(end 348.31782 -289.113976)
		(width 0.0889)
		(layer "In2.Cu")
		(net "P5E_CPU0_PE4_TX_DN<13>")
	)
	(segment
		(start 348.600522 -288.427668)
		(end 348.589854 -288.434018)
		(width 0.0889)
		(layer "In2.Cu")
		(net "P5E_CPU0_PE4_TX_DN<13>")
	)
	(segment
		(start 348.745556 -291.236654)
		(end 348.327472 -291.654738)
		(width 0.14732)
		(layer "In2.Cu")
		(net "P5E_CPU0_PE4_TX_DN<13>")
	)
	(segment
		(start 315.297312 -335.446116)
		(end 315.297312 -342.501728)
		(width 0.14732)
		(layer "In2.Cu")
		(net "P5E_CPU0_PE4_TX_DN<13>")
	)
	(segment
		(start 349.537528 -286.801306)
		(end 349.528384 -286.80664)
		(width 0.0889)
		(layer "In2.Cu")
		(net "P5E_CPU0_PE4_TX_DN<13>")
	)
	(segment
		(start 350.056958 -285.369508)
		(end 350.057212 -285.368746)
		(width 0.0889)
		(layer "In2.Cu")
		(net "P5E_CPU0_PE4_TX_DN<13>")
	)
	(segment
		(start 347.01861 -303.356264)
		(end 337.253326 -313.121294)
		(width 0.14732)
		(layer "In2.Cu")
		(net "P5E_CPU0_PE4_TX_DN<13>")
	)
	(segment
		(start 348.327472 -291.654738)
		(end 348.327472 -300.196758)
		(width 0.14732)
		(layer "In2.Cu")
		(net "P5E_CPU0_PE4_TX_DN<13>")
	)
	(segment
		(start 348.327472 -300.196758)
		(end 347.01861 -303.356264)
		(width 0.14732)
		(layer "In2.Cu")
		(net "P5E_CPU0_PE4_TX_DN<13>")
	)
	(segment
		(start 350.057212 -285.368746)
		(end 350.05772 -285.369)
		(width 0.0889)
		(layer "In2.Cu")
		(net "P5E_CPU0_PE4_TX_DN<13>")
	)
	(segment
		(start 349.978726 -285.390336)
		(end 350.056958 -285.369508)
		(width 0.0889)
		(layer "In2.Cu")
		(net "P5E_CPU0_PE4_TX_DN<13>")
	)
	(segment
		(start 315.297312 -342.501728)
		(end 315.488574 -343.58834)
		(width 0.14732)
		(layer "In2.Cu")
		(net "P5E_CPU0_PE4_TX_DN<13>")
	)
	(segment
		(start 350.195388 -285.58363)
		(end 350.196912 -285.677864)
		(width 0.0889)
		(layer "In2.Cu")
		(net "P5E_CPU0_PE4_TX_DN<13>")
	)
	(segment
		(start 342.738202 -396.882112)
		(end 342.682576 -397.049244)
		(width 0.14732)
		(layer "In2.Cu")
		(net "P5E_CPU0_PE4_TX_DN<13>")
	)
	(segment
		(start 335.400396 -314.359544)
		(end 315.99251 -333.767684)
		(width 0.14732)
		(layer "In2.Cu")
		(net "P5E_CPU0_PE4_TX_DN<13>")
	)
	(segment
		(start 348.745556 -290.905184)
		(end 348.745556 -291.236654)
		(width 0.14732)
		(layer "In2.Cu")
		(net "P5E_CPU0_PE4_TX_DN<13>")
	)
	(segment
		(start 344.096848 -400.563588)
		(end 343.802208 -400.858228)
		(width 0.14732)
		(layer "In2.Cu")
		(net "P5E_CPU0_PE4_TX_DN<13>")
	)
	(segment
		(start 349.72752 -286.464756)
		(end 349.72752 -286.475424)
		(width 0.0889)
		(layer "In2.Cu")
		(net "P5E_CPU0_PE4_TX_DN<13>")
	)
	(segment
		(start 349.545148 -286.796988)
		(end 349.539052 -286.800544)
		(width 0.0889)
		(layer "In2.Cu")
		(net "P5E_CPU0_PE4_TX_DN<13>")
	)
	(segment
		(start 343.548716 -398.49933)
		(end 344.096848 -399.5928)
		(width 0.14732)
		(layer "In2.Cu")
		(net "P5E_CPU0_PE4_TX_DN<13>")
	)
	(segment
		(start 344.096848 -399.5928)
		(end 344.096848 -400.563588)
		(width 0.14732)
		(layer "In2.Cu")
		(net "P5E_CPU0_PE4_TX_DN<13>")
	)
	(arc
		(start 349.72752 -286.475424)
		(mid 349.678751 -286.66026)
		(end 349.545148 -286.796988)
		(width 0.0889)
		(layer "In2.Cu")
		(net "P5E_CPU0_PE4_TX_DN<13>")
	)
	(arc
		(start 348.31782 -289.113976)
		(mid 348.42905 -289.30718)
		(end 348.603316 -289.446208)
		(width 0.0889)
		(layer "In2.Cu")
		(net "P5E_CPU0_PE4_TX_DN<13>")
	)
	(arc
		(start 350.196912 -285.677864)
		(mid 350.142801 -285.856007)
		(end 350.009714 -285.98622)
		(width 0.0889)
		(layer "In2.Cu")
		(net "P5E_CPU0_PE4_TX_DN<13>")
	)
	(arc
		(start 349.528384 -286.80664)
		(mid 349.329743 -287.012489)
		(end 349.257366 -287.28924)
		(width 0.0889)
		(layer "In2.Cu")
		(net "P5E_CPU0_PE4_TX_DN<13>")
	)
	(arc
		(start 349.059754 -287.619948)
		(mid 348.86037 -287.825828)
		(end 348.78772 -288.103056)
		(width 0.0889)
		(layer "In2.Cu")
		(net "P5E_CPU0_PE4_TX_DN<13>")
	)
	(arc
		(start 350.009714 -285.98622)
		(mid 349.805736 -286.188396)
		(end 349.72752 -286.464756)
		(width 0.0889)
		(layer "In2.Cu")
		(net "P5E_CPU0_PE4_TX_DN<13>")
	)
	(arc
		(start 350.109282 -285.410656)
		(mid 350.171257 -285.487721)
		(end 350.195388 -285.58363)
		(width 0.0889)
		(layer "In2.Cu")
		(net "P5E_CPU0_PE4_TX_DN<13>")
	)
	(arc
		(start 348.603316 -289.446208)
		(mid 348.712181 -289.529853)
		(end 348.787212 -289.644836)
		(width 0.0889)
		(layer "In2.Cu")
		(net "P5E_CPU0_PE4_TX_DN<13>")
	)
	(arc
		(start 348.78772 -288.118042)
		(mid 348.733915 -288.296917)
		(end 348.600522 -288.427668)
		(width 0.0889)
		(layer "In2.Cu")
		(net "P5E_CPU0_PE4_TX_DN<13>")
	)
	(arc
		(start 349.257366 -287.301686)
		(mid 349.204224 -287.481816)
		(end 349.070422 -287.613598)
		(width 0.0889)
		(layer "In2.Cu")
		(net "P5E_CPU0_PE4_TX_DN<13>")
	)
	(arc
		(start 348.589854 -288.434018)
		(mid 348.39047 -288.639898)
		(end 348.31782 -288.917126)
		(width 0.0889)
		(layer "In2.Cu")
		(net "P5E_CPU0_PE4_TX_DN<13>")
	)
	(segment
		(start 341.04453 -401.16379)
		(end 341.04453 -401.777962)
		(width 0.13208)
		(layer "F.Cu")
		(net "P5E_CPU0_PE4_TX_DN<12>")
	)
	(segment
		(start 340.738968 -400.858228)
		(end 341.04453 -401.16379)
		(width 0.13208)
		(layer "F.Cu")
		(net "P5E_CPU0_PE4_TX_DN<12>")
	)
	(segment
		(start 340.71814 -402.104352)
		(end 340.713568 -402.104352)
		(width 0.13208)
		(layer "F.Cu")
		(net "P5E_CPU0_PE4_TX_DN<12>")
	)
	(segment
		(start 348.882716 -285.6611)
		(end 348.882462 -285.661354)
		(width 0.13208)
		(layer "F.Cu")
		(net "P5E_CPU0_PE4_TX_DN<12>")
	)
	(segment
		(start 341.04453 -401.777962)
		(end 340.71814 -402.104352)
		(width 0.13208)
		(layer "F.Cu")
		(net "P5E_CPU0_PE4_TX_DN<12>")
	)
	(segment
		(start 348.882716 -285.125414)
		(end 348.882716 -285.6611)
		(width 0.13208)
		(layer "F.Cu")
		(net "P5E_CPU0_PE4_TX_DN<12>")
	)
	(segment
		(start 347.669104 -288.422334)
		(end 347.660214 -288.427414)
		(width 0.0889)
		(layer "In2.Cu")
		(net "P5E_CPU0_PE4_TX_DN<12>")
	)
	(segment
		(start 347.847666 -290.29406)
		(end 347.438726 -290.703)
		(width 0.0889)
		(layer "In2.Cu")
		(net "P5E_CPU0_PE4_TX_DN<12>")
	)
	(segment
		(start 314.362846 -342.58377)
		(end 314.602876 -343.945464)
		(width 0.14732)
		(layer "In2.Cu")
		(net "P5E_CPU0_PE4_TX_DN<12>")
	)
	(segment
		(start 347.377766 -288.898584)
		(end 347.377766 -289.114738)
		(width 0.0889)
		(layer "In2.Cu")
		(net "P5E_CPU0_PE4_TX_DN<12>")
	)
	(segment
		(start 321.970654 -358.497886)
		(end 341.033608 -399.55978)
		(width 0.14732)
		(layer "In2.Cu")
		(net "P5E_CPU0_PE4_TX_DN<12>")
	)
	(segment
		(start 346.227908 -302.813466)
		(end 336.700368 -312.340752)
		(width 0.14732)
		(layer "In2.Cu")
		(net "P5E_CPU0_PE4_TX_DN<12>")
	)
	(segment
		(start 347.847412 -289.645852)
		(end 347.847666 -289.64636)
		(width 0.0889)
		(layer "In2.Cu")
		(net "P5E_CPU0_PE4_TX_DN<12>")
	)
	(segment
		(start 348.317312 -287.279334)
		(end 348.317312 -287.28924)
		(width 0.0889)
		(layer "In2.Cu")
		(net "P5E_CPU0_PE4_TX_DN<12>")
	)
	(segment
		(start 347.847666 -288.087562)
		(end 347.847666 -288.103056)
		(width 0.0889)
		(layer "In2.Cu")
		(net "P5E_CPU0_PE4_TX_DN<12>")
	)
	(segment
		(start 348.60865 -286.794702)
		(end 348.602554 -286.798258)
		(width 0.0889)
		(layer "In2.Cu")
		(net "P5E_CPU0_PE4_TX_DN<12>")
	)
	(segment
		(start 347.438726 -290.703)
		(end 347.438726 -290.917884)
		(width 0.0889)
		(layer "In2.Cu")
		(net "P5E_CPU0_PE4_TX_DN<12>")
	)
	(segment
		(start 334.881474 -313.556142)
		(end 315.19241 -333.24546)
		(width 0.14732)
		(layer "In2.Cu")
		(net "P5E_CPU0_PE4_TX_DN<12>")
	)
	(segment
		(start 348.787212 -286.4612)
		(end 348.787212 -286.475424)
		(width 0.0889)
		(layer "In2.Cu")
		(net "P5E_CPU0_PE4_TX_DN<12>")
	)
	(segment
		(start 348.600522 -286.799274)
		(end 348.59976 -286.799782)
		(width 0.0889)
		(layer "In2.Cu")
		(net "P5E_CPU0_PE4_TX_DN<12>")
	)
	(segment
		(start 314.362846 -335.248504)
		(end 314.362846 -342.58377)
		(width 0.14732)
		(layer "In2.Cu")
		(net "P5E_CPU0_PE4_TX_DN<12>")
	)
	(segment
		(start 315.19241 -333.24546)
		(end 314.362846 -335.248504)
		(width 0.14732)
		(layer "In2.Cu")
		(net "P5E_CPU0_PE4_TX_DN<12>")
	)
	(segment
		(start 347.396816 -290.959794)
		(end 347.396816 -290.981892)
		(width 0.0889)
		(layer "In2.Cu")
		(net "P5E_CPU0_PE4_TX_DN<12>")
	)
	(segment
		(start 347.396816 -290.981892)
		(end 347.396816 -299.991272)
		(width 0.14732)
		(layer "In2.Cu")
		(net "P5E_CPU0_PE4_TX_DN<12>")
	)
	(segment
		(start 347.396816 -299.991272)
		(end 346.227908 -302.813466)
		(width 0.14732)
		(layer "In2.Cu")
		(net "P5E_CPU0_PE4_TX_DN<12>")
	)
	(segment
		(start 341.033608 -400.563588)
		(end 340.738968 -400.858228)
		(width 0.14732)
		(layer "In2.Cu")
		(net "P5E_CPU0_PE4_TX_DN<12>")
	)
	(segment
		(start 336.700368 -312.340752)
		(end 334.881474 -313.556142)
		(width 0.14732)
		(layer "In2.Cu")
		(net "P5E_CPU0_PE4_TX_DN<12>")
	)
	(segment
		(start 348.13875 -287.608518)
		(end 348.12986 -287.613598)
		(width 0.0889)
		(layer "In2.Cu")
		(net "P5E_CPU0_PE4_TX_DN<12>")
	)
	(segment
		(start 348.602554 -286.798258)
		(end 348.600522 -286.799274)
		(width 0.0889)
		(layer "In2.Cu")
		(net "P5E_CPU0_PE4_TX_DN<12>")
	)
	(segment
		(start 347.438726 -290.917884)
		(end 347.396816 -290.959794)
		(width 0.0889)
		(layer "In2.Cu")
		(net "P5E_CPU0_PE4_TX_DN<12>")
	)
	(segment
		(start 314.602876 -343.945464)
		(end 321.970654 -358.497886)
		(width 0.14732)
		(layer "In2.Cu")
		(net "P5E_CPU0_PE4_TX_DN<12>")
	)
	(segment
		(start 349.038926 -285.932372)
		(end 349.014796 -286.021526)
		(width 0.0889)
		(layer "In2.Cu")
		(net "P5E_CPU0_PE4_TX_DN<12>")
	)
	(segment
		(start 341.033608 -399.55978)
		(end 341.033608 -400.563588)
		(width 0.14732)
		(layer "In2.Cu")
		(net "P5E_CPU0_PE4_TX_DN<12>")
	)
	(segment
		(start 347.847666 -289.64636)
		(end 347.847666 -290.29406)
		(width 0.0889)
		(layer "In2.Cu")
		(net "P5E_CPU0_PE4_TX_DN<12>")
	)
	(segment
		(start 348.882462 -285.661354)
		(end 349.038926 -285.932372)
		(width 0.0889)
		(layer "In2.Cu")
		(net "P5E_CPU0_PE4_TX_DN<12>")
	)
	(arc
		(start 348.787212 -286.475424)
		(mid 348.739533 -286.658324)
		(end 348.60865 -286.794702)
		(width 0.0889)
		(layer "In2.Cu")
		(net "P5E_CPU0_PE4_TX_DN<12>")
	)
	(arc
		(start 347.377766 -289.114738)
		(mid 347.489104 -289.307638)
		(end 347.663262 -289.446462)
		(width 0.0889)
		(layer "In2.Cu")
		(net "P5E_CPU0_PE4_TX_DN<12>")
	)
	(arc
		(start 348.12986 -287.613598)
		(mid 347.927037 -287.813829)
		(end 347.847666 -288.087562)
		(width 0.0889)
		(layer "In2.Cu")
		(net "P5E_CPU0_PE4_TX_DN<12>")
	)
	(arc
		(start 349.014796 -286.021526)
		(mid 349.006353 -286.027924)
		(end 348.998032 -286.03448)
		(width 0.0889)
		(layer "In2.Cu")
		(net "P5E_CPU0_PE4_TX_DN<12>")
	)
	(arc
		(start 347.660214 -288.427414)
		(mid 347.457928 -288.626395)
		(end 347.377766 -288.898584)
		(width 0.0889)
		(layer "In2.Cu")
		(net "P5E_CPU0_PE4_TX_DN<12>")
	)
	(arc
		(start 348.59976 -286.799782)
		(mid 348.395425 -287.002387)
		(end 348.317312 -287.279334)
		(width 0.0889)
		(layer "In2.Cu")
		(net "P5E_CPU0_PE4_TX_DN<12>")
	)
	(arc
		(start 347.847666 -288.103056)
		(mid 347.799987 -288.285956)
		(end 347.669104 -288.422334)
		(width 0.0889)
		(layer "In2.Cu")
		(net "P5E_CPU0_PE4_TX_DN<12>")
	)
	(arc
		(start 347.663262 -289.446462)
		(mid 347.772409 -289.53039)
		(end 347.847412 -289.645852)
		(width 0.0889)
		(layer "In2.Cu")
		(net "P5E_CPU0_PE4_TX_DN<12>")
	)
	(arc
		(start 348.317312 -287.28924)
		(mid 348.269633 -287.47214)
		(end 348.13875 -287.608518)
		(width 0.0889)
		(layer "In2.Cu")
		(net "P5E_CPU0_PE4_TX_DN<12>")
	)
	(arc
		(start 348.998032 -286.03448)
		(mid 348.845525 -286.224578)
		(end 348.787212 -286.4612)
		(width 0.0889)
		(layer "In2.Cu")
		(net "P5E_CPU0_PE4_TX_DN<12>")
	)
	(segment
		(start 338.24037 -401.157186)
		(end 338.24037 -401.779994)
		(width 0.13208)
		(layer "F.Cu")
		(net "P5E_CPU0_PE4_TX_DN<11>")
	)
	(segment
		(start 338.24037 -401.779994)
		(end 338.564728 -402.104352)
		(width 0.13208)
		(layer "F.Cu")
		(net "P5E_CPU0_PE4_TX_DN<11>")
	)
	(segment
		(start 338.539328 -400.858228)
		(end 338.24037 -401.157186)
		(width 0.13208)
		(layer "F.Cu")
		(net "P5E_CPU0_PE4_TX_DN<11>")
	)
	(segment
		(start 348.412562 -284.311598)
		(end 348.412562 -284.847284)
		(width 0.13208)
		(layer "F.Cu")
		(net "P5E_CPU0_PE4_TX_DN<11>")
	)
	(segment
		(start 348.412562 -284.847284)
		(end 348.412816 -284.847538)
		(width 0.13208)
		(layer "F.Cu")
		(net "P5E_CPU0_PE4_TX_DN<11>")
	)
	(segment
		(start 347.098112 -290.096956)
		(end 346.696792 -290.498276)
		(width 0.0889)
		(layer "In2.Cu")
		(net "P5E_CPU0_PE4_TX_DN<11>")
	)
	(segment
		(start 348.507812 -285.64586)
		(end 348.507812 -285.679896)
		(width 0.0889)
		(layer "In2.Cu")
		(net "P5E_CPU0_PE4_TX_DN<11>")
	)
	(segment
		(start 347.098366 -288.103056)
		(end 347.098366 -288.121598)
		(width 0.0889)
		(layer "In2.Cu")
		(net "P5E_CPU0_PE4_TX_DN<11>")
	)
	(segment
		(start 346.738956 -290.676076)
		(end 346.738956 -290.698174)
		(width 0.0889)
		(layer "In2.Cu")
		(net "P5E_CPU0_PE4_TX_DN<11>")
	)
	(segment
		(start 346.696792 -290.498276)
		(end 346.696792 -290.633912)
		(width 0.0889)
		(layer "In2.Cu")
		(net "P5E_CPU0_PE4_TX_DN<11>")
	)
	(segment
		(start 347.752416 -286.966914)
		(end 347.749876 -286.968184)
		(width 0.0889)
		(layer "In2.Cu")
		(net "P5E_CPU0_PE4_TX_DN<11>")
	)
	(segment
		(start 348.412816 -284.847538)
		(end 348.256352 -285.118556)
		(width 0.0889)
		(layer "In2.Cu")
		(net "P5E_CPU0_PE4_TX_DN<11>")
	)
	(segment
		(start 347.756734 -286.96412)
		(end 347.754448 -286.965644)
		(width 0.0889)
		(layer "In2.Cu")
		(net "P5E_CPU0_PE4_TX_DN<11>")
	)
	(segment
		(start 347.754448 -286.965644)
		(end 347.752416 -286.966914)
		(width 0.0889)
		(layer "In2.Cu")
		(net "P5E_CPU0_PE4_TX_DN<11>")
	)
	(segment
		(start 347.746574 -286.970216)
		(end 347.746574 -286.969962)
		(width 0.0889)
		(layer "In2.Cu")
		(net "P5E_CPU0_PE4_TX_DN<11>")
	)
	(segment
		(start 346.628466 -288.917126)
		(end 346.628466 -289.078416)
		(width 0.0889)
		(layer "In2.Cu")
		(net "P5E_CPU0_PE4_TX_DN<11>")
	)
	(segment
		(start 313.67857 -335.066132)
		(end 313.67857 -342.50249)
		(width 0.14732)
		(layer "In2.Cu")
		(net "P5E_CPU0_PE4_TX_DN<11>")
	)
	(segment
		(start 347.098112 -289.60953)
		(end 347.098112 -290.096956)
		(width 0.0889)
		(layer "In2.Cu")
		(net "P5E_CPU0_PE4_TX_DN<11>")
	)
	(segment
		(start 348.038166 -286.466788)
		(end 348.038166 -286.475424)
		(width 0.0889)
		(layer "In2.Cu")
		(net "P5E_CPU0_PE4_TX_DN<11>")
	)
	(segment
		(start 314.551314 -332.959202)
		(end 313.67857 -335.066132)
		(width 0.14732)
		(layer "In2.Cu")
		(net "P5E_CPU0_PE4_TX_DN<11>")
	)
	(segment
		(start 346.738956 -290.698174)
		(end 346.738956 -299.756322)
		(width 0.14732)
		(layer "In2.Cu")
		(net "P5E_CPU0_PE4_TX_DN<11>")
	)
	(segment
		(start 338.244434 -400.563334)
		(end 338.539328 -400.858228)
		(width 0.14732)
		(layer "In2.Cu")
		(net "P5E_CPU0_PE4_TX_DN<11>")
	)
	(segment
		(start 347.568012 -287.28924)
		(end 347.568012 -287.304734)
		(width 0.0889)
		(layer "In2.Cu")
		(net "P5E_CPU0_PE4_TX_DN<11>")
	)
	(segment
		(start 320.939414 -358.89946)
		(end 338.244434 -399.48485)
		(width 0.14732)
		(layer "In2.Cu")
		(net "P5E_CPU0_PE4_TX_DN<11>")
	)
	(segment
		(start 347.76156 -286.961326)
		(end 347.756734 -286.96412)
		(width 0.0889)
		(layer "In2.Cu")
		(net "P5E_CPU0_PE4_TX_DN<11>")
	)
	(segment
		(start 336.339942 -311.764172)
		(end 334.550766 -312.95975)
		(width 0.14732)
		(layer "In2.Cu")
		(net "P5E_CPU0_PE4_TX_DN<11>")
	)
	(segment
		(start 313.67857 -342.50249)
		(end 313.98464 -344.239342)
		(width 0.14732)
		(layer "In2.Cu")
		(net "P5E_CPU0_PE4_TX_DN<11>")
	)
	(segment
		(start 346.815918 -288.592768)
		(end 346.807028 -288.597848)
		(width 0.0889)
		(layer "In2.Cu")
		(net "P5E_CPU0_PE4_TX_DN<11>")
	)
	(segment
		(start 346.696792 -290.633912)
		(end 346.738956 -290.676076)
		(width 0.0889)
		(layer "In2.Cu")
		(net "P5E_CPU0_PE4_TX_DN<11>")
	)
	(segment
		(start 334.550766 -312.95975)
		(end 314.551314 -332.959202)
		(width 0.14732)
		(layer "In2.Cu")
		(net "P5E_CPU0_PE4_TX_DN<11>")
	)
	(segment
		(start 346.738956 -299.756322)
		(end 345.60129 -302.502824)
		(width 0.14732)
		(layer "In2.Cu")
		(net "P5E_CPU0_PE4_TX_DN<11>")
	)
	(segment
		(start 313.98464 -344.239342)
		(end 320.939414 -358.89946)
		(width 0.14732)
		(layer "In2.Cu")
		(net "P5E_CPU0_PE4_TX_DN<11>")
	)
	(segment
		(start 347.285818 -287.778698)
		(end 347.276928 -287.783778)
		(width 0.0889)
		(layer "In2.Cu")
		(net "P5E_CPU0_PE4_TX_DN<11>")
	)
	(segment
		(start 348.256352 -285.118556)
		(end 348.280482 -285.20771)
		(width 0.0889)
		(layer "In2.Cu")
		(net "P5E_CPU0_PE4_TX_DN<11>")
	)
	(segment
		(start 345.60129 -302.502824)
		(end 336.339942 -311.764172)
		(width 0.14732)
		(layer "In2.Cu")
		(net "P5E_CPU0_PE4_TX_DN<11>")
	)
	(segment
		(start 338.244434 -399.48485)
		(end 338.244434 -400.563334)
		(width 0.14732)
		(layer "In2.Cu")
		(net "P5E_CPU0_PE4_TX_DN<11>")
	)
	(segment
		(start 347.749876 -286.968184)
		(end 347.746574 -286.970216)
		(width 0.0889)
		(layer "In2.Cu")
		(net "P5E_CPU0_PE4_TX_DN<11>")
	)
	(arc
		(start 348.280482 -285.20771)
		(mid 348.288923 -285.21411)
		(end 348.297246 -285.220664)
		(width 0.0889)
		(layer "In2.Cu")
		(net "P5E_CPU0_PE4_TX_DN<11>")
	)
	(arc
		(start 348.507812 -285.679896)
		(mid 348.42765 -285.952085)
		(end 348.225364 -286.151066)
		(width 0.0889)
		(layer "In2.Cu")
		(net "P5E_CPU0_PE4_TX_DN<11>")
	)
	(arc
		(start 347.098366 -288.121598)
		(mid 347.018204 -288.393787)
		(end 346.815918 -288.592768)
		(width 0.0889)
		(layer "In2.Cu")
		(net "P5E_CPU0_PE4_TX_DN<11>")
	)
	(arc
		(start 348.297246 -285.220664)
		(mid 348.449328 -285.410096)
		(end 348.507812 -285.64586)
		(width 0.0889)
		(layer "In2.Cu")
		(net "P5E_CPU0_PE4_TX_DN<11>")
	)
	(arc
		(start 348.225364 -286.151066)
		(mid 348.090431 -286.28442)
		(end 348.038166 -286.466788)
		(width 0.0889)
		(layer "In2.Cu")
		(net "P5E_CPU0_PE4_TX_DN<11>")
	)
	(arc
		(start 346.628466 -289.078416)
		(mid 346.703471 -289.193875)
		(end 346.812616 -289.277806)
		(width 0.0889)
		(layer "In2.Cu")
		(net "P5E_CPU0_PE4_TX_DN<11>")
	)
	(arc
		(start 347.568012 -287.304734)
		(mid 347.488642 -287.578468)
		(end 347.285818 -287.778698)
		(width 0.0889)
		(layer "In2.Cu")
		(net "P5E_CPU0_PE4_TX_DN<11>")
	)
	(arc
		(start 347.746574 -286.969962)
		(mid 347.61566 -287.106322)
		(end 347.568012 -287.28924)
		(width 0.0889)
		(layer "In2.Cu")
		(net "P5E_CPU0_PE4_TX_DN<11>")
	)
	(arc
		(start 347.276928 -287.783778)
		(mid 347.146014 -287.920138)
		(end 347.098366 -288.103056)
		(width 0.0889)
		(layer "In2.Cu")
		(net "P5E_CPU0_PE4_TX_DN<11>")
	)
	(arc
		(start 346.812616 -289.277806)
		(mid 346.986748 -289.416653)
		(end 347.098112 -289.60953)
		(width 0.0889)
		(layer "In2.Cu")
		(net "P5E_CPU0_PE4_TX_DN<11>")
	)
	(arc
		(start 348.038166 -286.475424)
		(mid 347.964175 -286.75499)
		(end 347.76156 -286.961326)
		(width 0.0889)
		(layer "In2.Cu")
		(net "P5E_CPU0_PE4_TX_DN<11>")
	)
	(arc
		(start 346.807028 -288.597848)
		(mid 346.676114 -288.734208)
		(end 346.628466 -288.917126)
		(width 0.0889)
		(layer "In2.Cu")
		(net "P5E_CPU0_PE4_TX_DN<11>")
	)
	(segment
		(start 334.91805 -401.777962)
		(end 334.59166 -402.104352)
		(width 0.13208)
		(layer "F.Cu")
		(net "P5E_CPU0_PE4_TX_DN<10>")
	)
	(segment
		(start 334.59166 -402.104352)
		(end 334.587088 -402.104352)
		(width 0.13208)
		(layer "F.Cu")
		(net "P5E_CPU0_PE4_TX_DN<10>")
	)
	(segment
		(start 334.91805 -401.16379)
		(end 334.91805 -401.777962)
		(width 0.13208)
		(layer "F.Cu")
		(net "P5E_CPU0_PE4_TX_DN<10>")
	)
	(segment
		(start 347.003116 -285.125414)
		(end 347.003116 -285.6611)
		(width 0.13208)
		(layer "F.Cu")
		(net "P5E_CPU0_PE4_TX_DN<10>")
	)
	(segment
		(start 334.612488 -400.858228)
		(end 334.91805 -401.16379)
		(width 0.13208)
		(layer "F.Cu")
		(net "P5E_CPU0_PE4_TX_DN<10>")
	)
	(segment
		(start 347.003116 -285.6611)
		(end 347.002862 -285.661354)
		(width 0.13208)
		(layer "F.Cu")
		(net "P5E_CPU0_PE4_TX_DN<10>")
	)
	(segment
		(start 333.91983 -311.883806)
		(end 313.496452 -332.307692)
		(width 0.14732)
		(layer "In2.Cu")
		(net "P5E_CPU0_PE4_TX_DN<10>")
	)
	(segment
		(start 344.604086 -301.750222)
		(end 335.579466 -310.774842)
		(width 0.14732)
		(layer "In2.Cu")
		(net "P5E_CPU0_PE4_TX_DN<10>")
	)
	(segment
		(start 347.159326 -285.932372)
		(end 347.135196 -286.021526)
		(width 0.0889)
		(layer "In2.Cu")
		(net "P5E_CPU0_PE4_TX_DN<10>")
	)
	(segment
		(start 345.49842 -288.917126)
		(end 345.49842 -289.113976)
		(width 0.0889)
		(layer "In2.Cu")
		(net "P5E_CPU0_PE4_TX_DN<10>")
	)
	(segment
		(start 345.574366 -290.940236)
		(end 345.532456 -290.982146)
		(width 0.0889)
		(layer "In2.Cu")
		(net "P5E_CPU0_PE4_TX_DN<10>")
	)
	(segment
		(start 345.968066 -290.18484)
		(end 345.574366 -290.418012)
		(width 0.0889)
		(layer "In2.Cu")
		(net "P5E_CPU0_PE4_TX_DN<10>")
	)
	(segment
		(start 347.135196 -286.021526)
		(end 347.135704 -286.021272)
		(width 0.0889)
		(layer "In2.Cu")
		(net "P5E_CPU0_PE4_TX_DN<10>")
	)
	(segment
		(start 345.574366 -290.418012)
		(end 345.574366 -290.940236)
		(width 0.0889)
		(layer "In2.Cu")
		(net "P5E_CPU0_PE4_TX_DN<10>")
	)
	(segment
		(start 312.47461 -342.749378)
		(end 312.791348 -344.546428)
		(width 0.14732)
		(layer "In2.Cu")
		(net "P5E_CPU0_PE4_TX_DN<10>")
	)
	(segment
		(start 334.907128 -400.563588)
		(end 334.612488 -400.858228)
		(width 0.14732)
		(layer "In2.Cu")
		(net "P5E_CPU0_PE4_TX_DN<10>")
	)
	(segment
		(start 346.71254 -286.804608)
		(end 346.706952 -286.80791)
		(width 0.0889)
		(layer "In2.Cu")
		(net "P5E_CPU0_PE4_TX_DN<10>")
	)
	(segment
		(start 334.907128 -399.428462)
		(end 334.907128 -400.563588)
		(width 0.14732)
		(layer "In2.Cu")
		(net "P5E_CPU0_PE4_TX_DN<10>")
	)
	(segment
		(start 345.968066 -289.645344)
		(end 345.968066 -290.18484)
		(width 0.0889)
		(layer "In2.Cu")
		(net "P5E_CPU0_PE4_TX_DN<10>")
	)
	(segment
		(start 346.437966 -287.28924)
		(end 346.437966 -287.301686)
		(width 0.0889)
		(layer "In2.Cu")
		(net "P5E_CPU0_PE4_TX_DN<10>")
	)
	(segment
		(start 346.730066 -286.794194)
		(end 346.72143 -286.799528)
		(width 0.0889)
		(layer "In2.Cu")
		(net "P5E_CPU0_PE4_TX_DN<10>")
	)
	(segment
		(start 312.791348 -344.546428)
		(end 319.435988 -359.58272)
		(width 0.14732)
		(layer "In2.Cu")
		(net "P5E_CPU0_PE4_TX_DN<10>")
	)
	(segment
		(start 346.251022 -287.613598)
		(end 346.240354 -287.619948)
		(width 0.0889)
		(layer "In2.Cu")
		(net "P5E_CPU0_PE4_TX_DN<10>")
	)
	(segment
		(start 345.532456 -299.508672)
		(end 344.604086 -301.750222)
		(width 0.14732)
		(layer "In2.Cu")
		(net "P5E_CPU0_PE4_TX_DN<10>")
	)
	(segment
		(start 347.002862 -285.661354)
		(end 347.159326 -285.932372)
		(width 0.0889)
		(layer "In2.Cu")
		(net "P5E_CPU0_PE4_TX_DN<10>")
	)
	(segment
		(start 346.72143 -286.799528)
		(end 346.71254 -286.804608)
		(width 0.0889)
		(layer "In2.Cu")
		(net "P5E_CPU0_PE4_TX_DN<10>")
	)
	(segment
		(start 345.532456 -290.982146)
		(end 345.532456 -291.004244)
		(width 0.0889)
		(layer "In2.Cu")
		(net "P5E_CPU0_PE4_TX_DN<10>")
	)
	(segment
		(start 312.47461 -334.775048)
		(end 312.47461 -342.749378)
		(width 0.14732)
		(layer "In2.Cu")
		(net "P5E_CPU0_PE4_TX_DN<10>")
	)
	(segment
		(start 319.435988 -359.58272)
		(end 334.907128 -399.428462)
		(width 0.14732)
		(layer "In2.Cu")
		(net "P5E_CPU0_PE4_TX_DN<10>")
	)
	(segment
		(start 345.96832 -288.103056)
		(end 345.96832 -288.118042)
		(width 0.0889)
		(layer "In2.Cu")
		(net "P5E_CPU0_PE4_TX_DN<10>")
	)
	(segment
		(start 335.579466 -310.774842)
		(end 333.91983 -311.883806)
		(width 0.14732)
		(layer "In2.Cu")
		(net "P5E_CPU0_PE4_TX_DN<10>")
	)
	(segment
		(start 345.532456 -291.004244)
		(end 345.532456 -299.508672)
		(width 0.14732)
		(layer "In2.Cu")
		(net "P5E_CPU0_PE4_TX_DN<10>")
	)
	(segment
		(start 345.781122 -288.427668)
		(end 345.770454 -288.434018)
		(width 0.0889)
		(layer "In2.Cu")
		(net "P5E_CPU0_PE4_TX_DN<10>")
	)
	(segment
		(start 313.496452 -332.307692)
		(end 312.47461 -334.775048)
		(width 0.14732)
		(layer "In2.Cu")
		(net "P5E_CPU0_PE4_TX_DN<10>")
	)
	(arc
		(start 345.783916 -289.446208)
		(mid 345.893019 -289.530034)
		(end 345.968066 -289.645344)
		(width 0.0889)
		(layer "In2.Cu")
		(net "P5E_CPU0_PE4_TX_DN<10>")
	)
	(arc
		(start 347.118178 -286.034734)
		(mid 346.963017 -286.231209)
		(end 346.907866 -286.475424)
		(width 0.0889)
		(layer "In2.Cu")
		(net "P5E_CPU0_PE4_TX_DN<10>")
	)
	(arc
		(start 347.135704 -286.021272)
		(mid 347.126874 -286.027915)
		(end 347.118178 -286.034734)
		(width 0.0889)
		(layer "In2.Cu")
		(net "P5E_CPU0_PE4_TX_DN<10>")
	)
	(arc
		(start 345.770454 -288.434018)
		(mid 345.57107 -288.639898)
		(end 345.49842 -288.917126)
		(width 0.0889)
		(layer "In2.Cu")
		(net "P5E_CPU0_PE4_TX_DN<10>")
	)
	(arc
		(start 346.240354 -287.619948)
		(mid 346.04097 -287.825828)
		(end 345.96832 -288.103056)
		(width 0.0889)
		(layer "In2.Cu")
		(net "P5E_CPU0_PE4_TX_DN<10>")
	)
	(arc
		(start 345.49842 -289.113976)
		(mid 345.60965 -289.30718)
		(end 345.783916 -289.446208)
		(width 0.0889)
		(layer "In2.Cu")
		(net "P5E_CPU0_PE4_TX_DN<10>")
	)
	(arc
		(start 346.907866 -286.475424)
		(mid 346.86041 -286.657925)
		(end 346.730066 -286.794194)
		(width 0.0889)
		(layer "In2.Cu")
		(net "P5E_CPU0_PE4_TX_DN<10>")
	)
	(arc
		(start 346.437966 -287.301686)
		(mid 346.384824 -287.481816)
		(end 346.251022 -287.613598)
		(width 0.0889)
		(layer "In2.Cu")
		(net "P5E_CPU0_PE4_TX_DN<10>")
	)
	(arc
		(start 346.706952 -286.80791)
		(mid 346.509776 -287.013545)
		(end 346.437966 -287.28924)
		(width 0.0889)
		(layer "In2.Cu")
		(net "P5E_CPU0_PE4_TX_DN<10>")
	)
	(arc
		(start 345.96832 -288.118042)
		(mid 345.914515 -288.296917)
		(end 345.781122 -288.427668)
		(width 0.0889)
		(layer "In2.Cu")
		(net "P5E_CPU0_PE4_TX_DN<10>")
	)
	(segment
		(start 303.95926 -402.104352)
		(end 303.954688 -402.104352)
		(width 0.13208)
		(layer "F.Cu")
		(net "P5E_CPU0_PE4_TX_DN<0>")
	)
	(segment
		(start 303.980088 -400.858228)
		(end 304.28565 -401.16379)
		(width 0.13208)
		(layer "F.Cu")
		(net "P5E_CPU0_PE4_TX_DN<0>")
	)
	(segment
		(start 304.28565 -401.777962)
		(end 303.95926 -402.104352)
		(width 0.13208)
		(layer "F.Cu")
		(net "P5E_CPU0_PE4_TX_DN<0>")
	)
	(segment
		(start 304.28565 -401.16379)
		(end 304.28565 -401.777962)
		(width 0.13208)
		(layer "F.Cu")
		(net "P5E_CPU0_PE4_TX_DN<0>")
	)
	(segment
		(start 337.604862 -285.125414)
		(end 337.604862 -285.661354)
		(width 0.13208)
		(layer "F.Cu")
		(net "P5E_CPU0_PE4_TX_DN<0>")
	)
	(segment
		(start 311.60847 -318.638428)
		(end 311.000648 -318.691514)
		(width 0.14732)
		(layer "In2.Cu")
		(net "P5E_CPU0_PE4_TX_DN<0>")
	)
	(segment
		(start 311.000648 -318.691514)
		(end 308.446678 -319.141856)
		(width 0.14732)
		(layer "In2.Cu")
		(net "P5E_CPU0_PE4_TX_DN<0>")
	)
	(segment
		(start 336.386932 -288.424874)
		(end 336.38236 -288.427414)
		(width 0.0889)
		(layer "In2.Cu")
		(net "P5E_CPU0_PE4_TX_DN<0>")
	)
	(segment
		(start 303.35855 -345.634056)
		(end 305.25974 -361.73664)
		(width 0.14732)
		(layer "In2.Cu")
		(net "P5E_CPU0_PE4_TX_DN<0>")
	)
	(segment
		(start 326.004682 -306.53736)
		(end 314.856876 -317.685166)
		(width 0.14732)
		(layer "In2.Cu")
		(net "P5E_CPU0_PE4_TX_DN<0>")
	)
	(segment
		(start 308.446678 -319.141856)
		(end 304.418492 -321.96278)
		(width 0.14732)
		(layer "In2.Cu")
		(net "P5E_CPU0_PE4_TX_DN<0>")
	)
	(segment
		(start 336.058256 -289.560508)
		(end 336.058256 -289.582606)
		(width 0.0889)
		(layer "In2.Cu")
		(net "P5E_CPU0_PE4_TX_DN<0>")
	)
	(segment
		(start 314.856876 -317.685166)
		(end 312.555636 -318.638428)
		(width 0.14732)
		(layer "In2.Cu")
		(net "P5E_CPU0_PE4_TX_DN<0>")
	)
	(segment
		(start 301.566072 -326.035924)
		(end 301.318676 -326.82053)
		(width 0.14732)
		(layer "In2.Cu")
		(net "P5E_CPU0_PE4_TX_DN<0>")
	)
	(segment
		(start 337.604862 -285.661354)
		(end 337.761326 -285.932372)
		(width 0.0889)
		(layer "In2.Cu")
		(net "P5E_CPU0_PE4_TX_DN<0>")
	)
	(segment
		(start 336.380836 -288.428938)
		(end 336.372962 -288.433256)
		(width 0.0889)
		(layer "In2.Cu")
		(net "P5E_CPU0_PE4_TX_DN<0>")
	)
	(segment
		(start 304.274728 -399.449544)
		(end 304.274728 -400.563588)
		(width 0.14732)
		(layer "In2.Cu")
		(net "P5E_CPU0_PE4_TX_DN<0>")
	)
	(segment
		(start 336.058256 -289.582606)
		(end 336.058256 -290.297362)
		(width 0.14732)
		(layer "In2.Cu")
		(net "P5E_CPU0_PE4_TX_DN<0>")
	)
	(segment
		(start 304.274728 -400.563588)
		(end 303.980088 -400.858228)
		(width 0.14732)
		(layer "In2.Cu")
		(net "P5E_CPU0_PE4_TX_DN<0>")
	)
	(segment
		(start 335.808574 -290.547044)
		(end 332.726538 -293.628826)
		(width 0.14732)
		(layer "In2.Cu")
		(net "P5E_CPU0_PE4_TX_DN<0>")
	)
	(segment
		(start 337.509612 -286.456882)
		(end 337.509612 -286.48406)
		(width 0.0889)
		(layer "In2.Cu")
		(net "P5E_CPU0_PE4_TX_DN<0>")
	)
	(segment
		(start 305.25974 -361.73664)
		(end 305.43246 -385.756404)
		(width 0.14732)
		(layer "In2.Cu")
		(net "P5E_CPU0_PE4_TX_DN<0>")
	)
	(segment
		(start 301.318676 -327.89622)
		(end 303.00168 -341.538306)
		(width 0.14732)
		(layer "In2.Cu")
		(net "P5E_CPU0_PE4_TX_DN<0>")
	)
	(segment
		(start 337.322414 -286.799782)
		(end 337.321652 -286.80029)
		(width 0.0889)
		(layer "In2.Cu")
		(net "P5E_CPU0_PE4_TX_DN<0>")
	)
	(segment
		(start 337.761326 -285.932372)
		(end 337.737196 -286.021526)
		(width 0.0889)
		(layer "In2.Cu")
		(net "P5E_CPU0_PE4_TX_DN<0>")
	)
	(segment
		(start 336.39125 -288.422334)
		(end 336.386932 -288.424874)
		(width 0.0889)
		(layer "In2.Cu")
		(net "P5E_CPU0_PE4_TX_DN<0>")
	)
	(segment
		(start 337.321652 -286.80029)
		(end 337.316318 -286.803338)
		(width 0.0889)
		(layer "In2.Cu")
		(net "P5E_CPU0_PE4_TX_DN<0>")
	)
	(segment
		(start 305.43246 -385.756404)
		(end 305.204622 -396.599918)
		(width 0.14732)
		(layer "In2.Cu")
		(net "P5E_CPU0_PE4_TX_DN<0>")
	)
	(segment
		(start 305.204622 -396.599918)
		(end 304.274728 -399.449544)
		(width 0.14732)
		(layer "In2.Cu")
		(net "P5E_CPU0_PE4_TX_DN<0>")
	)
	(segment
		(start 336.86115 -287.608518)
		(end 336.85226 -287.613598)
		(width 0.0889)
		(layer "In2.Cu")
		(net "P5E_CPU0_PE4_TX_DN<0>")
	)
	(segment
		(start 304.418492 -321.96278)
		(end 301.566072 -326.035924)
		(width 0.14732)
		(layer "In2.Cu")
		(net "P5E_CPU0_PE4_TX_DN<0>")
	)
	(segment
		(start 301.318676 -326.82053)
		(end 301.318676 -327.89622)
		(width 0.14732)
		(layer "In2.Cu")
		(net "P5E_CPU0_PE4_TX_DN<0>")
	)
	(segment
		(start 336.569812 -288.09315)
		(end 336.569812 -288.103056)
		(width 0.0889)
		(layer "In2.Cu")
		(net "P5E_CPU0_PE4_TX_DN<0>")
	)
	(segment
		(start 336.100166 -288.905442)
		(end 336.100166 -289.518598)
		(width 0.0889)
		(layer "In2.Cu")
		(net "P5E_CPU0_PE4_TX_DN<0>")
	)
	(segment
		(start 303.00168 -341.538306)
		(end 303.00168 -343.60993)
		(width 0.14732)
		(layer "In2.Cu")
		(net "P5E_CPU0_PE4_TX_DN<0>")
	)
	(segment
		(start 303.00168 -343.60993)
		(end 303.35855 -345.634056)
		(width 0.14732)
		(layer "In2.Cu")
		(net "P5E_CPU0_PE4_TX_DN<0>")
	)
	(segment
		(start 336.100166 -289.518598)
		(end 336.058256 -289.560508)
		(width 0.0889)
		(layer "In2.Cu")
		(net "P5E_CPU0_PE4_TX_DN<0>")
	)
	(segment
		(start 312.555636 -318.638428)
		(end 311.60847 -318.638428)
		(width 0.14732)
		(layer "In2.Cu")
		(net "P5E_CPU0_PE4_TX_DN<0>")
	)
	(segment
		(start 332.726538 -293.628826)
		(end 326.004682 -306.53736)
		(width 0.14732)
		(layer "In2.Cu")
		(net "P5E_CPU0_PE4_TX_DN<0>")
	)
	(segment
		(start 336.058256 -290.297362)
		(end 335.808574 -290.547044)
		(width 0.14732)
		(layer "In2.Cu")
		(net "P5E_CPU0_PE4_TX_DN<0>")
	)
	(arc
		(start 336.372962 -288.433256)
		(mid 336.370927 -288.434522)
		(end 336.368898 -288.435796)
		(width 0.0889)
		(layer "In2.Cu")
		(net "P5E_CPU0_PE4_TX_DN<0>")
	)
	(arc
		(start 337.039712 -287.28924)
		(mid 336.992033 -287.47214)
		(end 336.86115 -287.608518)
		(width 0.0889)
		(layer "In2.Cu")
		(net "P5E_CPU0_PE4_TX_DN<0>")
	)
	(arc
		(start 337.509612 -286.48406)
		(mid 337.457342 -286.666425)
		(end 337.322414 -286.799782)
		(width 0.0889)
		(layer "In2.Cu")
		(net "P5E_CPU0_PE4_TX_DN<0>")
	)
	(arc
		(start 337.720686 -286.03448)
		(mid 337.568894 -286.222562)
		(end 337.509612 -286.456882)
		(width 0.0889)
		(layer "In2.Cu")
		(net "P5E_CPU0_PE4_TX_DN<0>")
	)
	(arc
		(start 336.38236 -288.427414)
		(mid 336.381597 -288.428175)
		(end 336.380836 -288.428938)
		(width 0.0889)
		(layer "In2.Cu")
		(net "P5E_CPU0_PE4_TX_DN<0>")
	)
	(arc
		(start 336.85226 -287.613598)
		(mid 336.647925 -287.816203)
		(end 336.569812 -288.09315)
		(width 0.0889)
		(layer "In2.Cu")
		(net "P5E_CPU0_PE4_TX_DN<0>")
	)
	(arc
		(start 337.316318 -286.803338)
		(mid 337.113731 -287.009689)
		(end 337.039712 -287.28924)
		(width 0.0889)
		(layer "In2.Cu")
		(net "P5E_CPU0_PE4_TX_DN<0>")
	)
	(arc
		(start 337.737196 -286.021526)
		(mid 337.728882 -286.027928)
		(end 337.720686 -286.03448)
		(width 0.0889)
		(layer "In2.Cu")
		(net "P5E_CPU0_PE4_TX_DN<0>")
	)
	(arc
		(start 336.368898 -288.435796)
		(mid 336.174691 -288.636366)
		(end 336.100166 -288.905442)
		(width 0.0889)
		(layer "In2.Cu")
		(net "P5E_CPU0_PE4_TX_DN<0>")
	)
	(arc
		(start 336.569812 -288.103056)
		(mid 336.522133 -288.285956)
		(end 336.39125 -288.422334)
		(width 0.0889)
		(layer "In2.Cu")
		(net "P5E_CPU0_PE4_TX_DN<0>")
	)
	(segment
		(start 332.11135 -402.96465)
		(end 332.438248 -402.637752)
		(width 0.13208)
		(layer "F.Cu")
		(net "P5E_CPU0_PE4_TX_C_DP<9>")
	)
	(segment
		(start 332.11135 -403.582378)
		(end 332.11135 -402.96465)
		(width 0.13208)
		(layer "F.Cu")
		(net "P5E_CPU0_PE4_TX_C_DP<9>")
	)
	(segment
		(start 332.412848 -403.883876)
		(end 332.11135 -403.582378)
		(width 0.13208)
		(layer "F.Cu")
		(net "P5E_CPU0_PE4_TX_C_DP<9>")
	)
	(segment
		(start 332.664562 -417.79444)
		(end 332.534514 -417.943284)
		(width 0.14732)
		(layer "In6.Cu")
		(net "P5E_CPU0_PE4_TX_C_DP<9>")
	)
	(segment
		(start 332.081378 -411.183328)
		(end 332.253336 -413.751014)
		(width 0.14732)
		(layer "In6.Cu")
		(net "P5E_CPU0_PE4_TX_C_DP<9>")
	)
	(segment
		(start 332.40218 -413.881062)
		(end 332.426818 -414.248854)
		(width 0.14732)
		(layer "In6.Cu")
		(net "P5E_CPU0_PE4_TX_C_DP<9>")
	)
	(segment
		(start 332.399132 -415.925254)
		(end 332.547976 -416.055302)
		(width 0.14732)
		(layer "In6.Cu")
		(net "P5E_CPU0_PE4_TX_C_DP<9>")
	)
	(segment
		(start 332.442566 -416.571684)
		(end 332.49108 -417.2966)
		(width 0.14732)
		(layer "In6.Cu")
		(net "P5E_CPU0_PE4_TX_C_DP<9>")
	)
	(segment
		(start 331.932788 -406.833324)
		(end 331.932788 -410.435806)
		(width 0.14732)
		(layer "In6.Cu")
		(net "P5E_CPU0_PE4_TX_C_DP<9>")
	)
	(segment
		(start 332.253336 -413.751014)
		(end 332.40218 -413.881062)
		(width 0.14732)
		(layer "In6.Cu")
		(net "P5E_CPU0_PE4_TX_C_DP<9>")
	)
	(segment
		(start 332.49489 -415.262822)
		(end 332.364842 -415.411666)
		(width 0.14732)
		(layer "In6.Cu")
		(net "P5E_CPU0_PE4_TX_C_DP<9>")
	)
	(segment
		(start 332.547976 -416.055302)
		(end 332.572614 -416.423094)
		(width 0.14732)
		(layer "In6.Cu")
		(net "P5E_CPU0_PE4_TX_C_DP<9>")
	)
	(segment
		(start 332.534514 -417.943284)
		(end 332.966822 -424.401488)
		(width 0.14732)
		(layer "In6.Cu")
		(net "P5E_CPU0_PE4_TX_C_DP<9>")
	)
	(segment
		(start 332.29677 -414.397698)
		(end 332.321154 -414.764982)
		(width 0.14732)
		(layer "In6.Cu")
		(net "P5E_CPU0_PE4_TX_C_DP<9>")
	)
	(segment
		(start 333.650082 -427.34103)
		(end 333.650082 -427.089824)
		(width 0.14732)
		(layer "In6.Cu")
		(net "P5E_CPU0_PE4_TX_C_DP<9>")
	)
	(segment
		(start 333.114142 -427.552612)
		(end 333.4385 -427.552612)
		(width 0.14732)
		(layer "In6.Cu")
		(net "P5E_CPU0_PE4_TX_C_DP<9>")
	)
	(segment
		(start 332.966822 -424.401488)
		(end 332.966822 -427.405292)
		(width 0.14732)
		(layer "In6.Cu")
		(net "P5E_CPU0_PE4_TX_C_DP<9>")
	)
	(segment
		(start 332.321154 -414.764982)
		(end 332.470252 -414.89503)
		(width 0.14732)
		(layer "In6.Cu")
		(net "P5E_CPU0_PE4_TX_C_DP<9>")
	)
	(segment
		(start 331.932788 -410.435806)
		(end 332.081378 -411.183328)
		(width 0.14732)
		(layer "In6.Cu")
		(net "P5E_CPU0_PE4_TX_C_DP<9>")
	)
	(segment
		(start 332.639924 -417.426648)
		(end 332.664562 -417.79444)
		(width 0.14732)
		(layer "In6.Cu")
		(net "P5E_CPU0_PE4_TX_C_DP<9>")
	)
	(segment
		(start 332.412848 -403.883876)
		(end 332.118208 -404.178516)
		(width 0.14732)
		(layer "In6.Cu")
		(net "P5E_CPU0_PE4_TX_C_DP<9>")
	)
	(segment
		(start 332.572614 -416.423094)
		(end 332.442566 -416.571684)
		(width 0.14732)
		(layer "In6.Cu")
		(net "P5E_CPU0_PE4_TX_C_DP<9>")
	)
	(segment
		(start 332.118208 -404.178516)
		(end 332.118208 -404.949914)
		(width 0.14732)
		(layer "In6.Cu")
		(net "P5E_CPU0_PE4_TX_C_DP<9>")
	)
	(segment
		(start 332.49108 -417.2966)
		(end 332.639924 -417.426648)
		(width 0.14732)
		(layer "In6.Cu")
		(net "P5E_CPU0_PE4_TX_C_DP<9>")
	)
	(segment
		(start 332.470252 -414.89503)
		(end 332.49489 -415.262822)
		(width 0.14732)
		(layer "In6.Cu")
		(net "P5E_CPU0_PE4_TX_C_DP<9>")
	)
	(segment
		(start 332.426818 -414.248854)
		(end 332.29677 -414.397698)
		(width 0.14732)
		(layer "In6.Cu")
		(net "P5E_CPU0_PE4_TX_C_DP<9>")
	)
	(segment
		(start 333.4385 -427.552612)
		(end 333.650082 -427.34103)
		(width 0.14732)
		(layer "In6.Cu")
		(net "P5E_CPU0_PE4_TX_C_DP<9>")
	)
	(segment
		(start 332.118208 -404.949914)
		(end 331.932788 -406.833324)
		(width 0.14732)
		(layer "In6.Cu")
		(net "P5E_CPU0_PE4_TX_C_DP<9>")
	)
	(segment
		(start 332.966822 -427.405292)
		(end 333.114142 -427.552612)
		(width 0.14732)
		(layer "In6.Cu")
		(net "P5E_CPU0_PE4_TX_C_DP<9>")
	)
	(segment
		(start 332.364842 -415.411666)
		(end 332.399132 -415.925254)
		(width 0.14732)
		(layer "In6.Cu")
		(net "P5E_CPU0_PE4_TX_C_DP<9>")
	)
	(segment
		(start 329.349608 -403.883876)
		(end 329.04811 -403.582378)
		(width 0.13208)
		(layer "F.Cu")
		(net "P5E_CPU0_PE4_TX_C_DP<8>")
	)
	(segment
		(start 329.04811 -403.582378)
		(end 329.04811 -402.96465)
		(width 0.13208)
		(layer "F.Cu")
		(net "P5E_CPU0_PE4_TX_C_DP<8>")
	)
	(segment
		(start 329.04811 -402.96465)
		(end 329.375008 -402.637752)
		(width 0.13208)
		(layer "F.Cu")
		(net "P5E_CPU0_PE4_TX_C_DP<8>")
	)
	(segment
		(start 329.61072 -415.055304)
		(end 329.76947 -415.17316)
		(width 0.14732)
		(layer "In6.Cu")
		(net "P5E_CPU0_PE4_TX_C_DP<8>")
	)
	(segment
		(start 330.307442 -418.827712)
		(end 330.361036 -419.192202)
		(width 0.14732)
		(layer "In6.Cu")
		(net "P5E_CPU0_PE4_TX_C_DP<8>")
	)
	(segment
		(start 329.792076 -416.287458)
		(end 329.950826 -416.405314)
		(width 0.14732)
		(layer "In6.Cu")
		(net "P5E_CPU0_PE4_TX_C_DP<8>")
	)
	(segment
		(start 328.869548 -410.271214)
		(end 329.012296 -410.989018)
		(width 0.14732)
		(layer "In6.Cu")
		(net "P5E_CPU0_PE4_TX_C_DP<8>")
	)
	(segment
		(start 329.823064 -415.537904)
		(end 329.705208 -415.6964)
		(width 0.14732)
		(layer "In6.Cu")
		(net "P5E_CPU0_PE4_TX_C_DP<8>")
	)
	(segment
		(start 329.054968 -404.949914)
		(end 328.869548 -406.833324)
		(width 0.14732)
		(layer "In6.Cu")
		(net "P5E_CPU0_PE4_TX_C_DP<8>")
	)
	(segment
		(start 330.24318 -419.350698)
		(end 330.966826 -424.271948)
		(width 0.14732)
		(layer "In6.Cu")
		(net "P5E_CPU0_PE4_TX_C_DP<8>")
	)
	(segment
		(start 329.705208 -415.6964)
		(end 329.792076 -416.287458)
		(width 0.14732)
		(layer "In6.Cu")
		(net "P5E_CPU0_PE4_TX_C_DP<8>")
	)
	(segment
		(start 331.650086 -426.341032)
		(end 331.650086 -426.089826)
		(width 0.14732)
		(layer "In6.Cu")
		(net "P5E_CPU0_PE4_TX_C_DP<8>")
	)
	(segment
		(start 330.966826 -426.405294)
		(end 331.114146 -426.552614)
		(width 0.14732)
		(layer "In6.Cu")
		(net "P5E_CPU0_PE4_TX_C_DP<8>")
	)
	(segment
		(start 328.869548 -406.833324)
		(end 328.869548 -410.271214)
		(width 0.14732)
		(layer "In6.Cu")
		(net "P5E_CPU0_PE4_TX_C_DP<8>")
	)
	(segment
		(start 329.886564 -416.9283)
		(end 329.957938 -417.414456)
		(width 0.14732)
		(layer "In6.Cu")
		(net "P5E_CPU0_PE4_TX_C_DP<8>")
	)
	(segment
		(start 331.438504 -426.552614)
		(end 331.650086 -426.341032)
		(width 0.14732)
		(layer "In6.Cu")
		(net "P5E_CPU0_PE4_TX_C_DP<8>")
	)
	(segment
		(start 329.950826 -416.405314)
		(end 330.00442 -416.769804)
		(width 0.14732)
		(layer "In6.Cu")
		(net "P5E_CPU0_PE4_TX_C_DP<8>")
	)
	(segment
		(start 331.114146 -426.552614)
		(end 331.438504 -426.552614)
		(width 0.14732)
		(layer "In6.Cu")
		(net "P5E_CPU0_PE4_TX_C_DP<8>")
	)
	(segment
		(start 330.052426 -418.055552)
		(end 330.148438 -418.709602)
		(width 0.14732)
		(layer "In6.Cu")
		(net "P5E_CPU0_PE4_TX_C_DP<8>")
	)
	(segment
		(start 330.116688 -417.532312)
		(end 330.170282 -417.897056)
		(width 0.14732)
		(layer "In6.Cu")
		(net "P5E_CPU0_PE4_TX_C_DP<8>")
	)
	(segment
		(start 330.148438 -418.709602)
		(end 330.307442 -418.827712)
		(width 0.14732)
		(layer "In6.Cu")
		(net "P5E_CPU0_PE4_TX_C_DP<8>")
	)
	(segment
		(start 329.674982 -414.532572)
		(end 329.557126 -414.691068)
		(width 0.14732)
		(layer "In6.Cu")
		(net "P5E_CPU0_PE4_TX_C_DP<8>")
	)
	(segment
		(start 330.361036 -419.192202)
		(end 330.24318 -419.350698)
		(width 0.14732)
		(layer "In6.Cu")
		(net "P5E_CPU0_PE4_TX_C_DP<8>")
	)
	(segment
		(start 330.966826 -424.271948)
		(end 330.966826 -426.405294)
		(width 0.14732)
		(layer "In6.Cu")
		(net "P5E_CPU0_PE4_TX_C_DP<8>")
	)
	(segment
		(start 330.00442 -416.769804)
		(end 329.886564 -416.9283)
		(width 0.14732)
		(layer "In6.Cu")
		(net "P5E_CPU0_PE4_TX_C_DP<8>")
	)
	(segment
		(start 330.170282 -417.897056)
		(end 330.052426 -418.055552)
		(width 0.14732)
		(layer "In6.Cu")
		(net "P5E_CPU0_PE4_TX_C_DP<8>")
	)
	(segment
		(start 329.349608 -403.883876)
		(end 329.054968 -404.178516)
		(width 0.14732)
		(layer "In6.Cu")
		(net "P5E_CPU0_PE4_TX_C_DP<8>")
	)
	(segment
		(start 329.76947 -415.17316)
		(end 329.823064 -415.537904)
		(width 0.14732)
		(layer "In6.Cu")
		(net "P5E_CPU0_PE4_TX_C_DP<8>")
	)
	(segment
		(start 329.957938 -417.414456)
		(end 330.116688 -417.532312)
		(width 0.14732)
		(layer "In6.Cu")
		(net "P5E_CPU0_PE4_TX_C_DP<8>")
	)
	(segment
		(start 329.462892 -414.050226)
		(end 329.621388 -414.167828)
		(width 0.14732)
		(layer "In6.Cu")
		(net "P5E_CPU0_PE4_TX_C_DP<8>")
	)
	(segment
		(start 329.621388 -414.167828)
		(end 329.674982 -414.532572)
		(width 0.14732)
		(layer "In6.Cu")
		(net "P5E_CPU0_PE4_TX_C_DP<8>")
	)
	(segment
		(start 329.054968 -404.178516)
		(end 329.054968 -404.949914)
		(width 0.14732)
		(layer "In6.Cu")
		(net "P5E_CPU0_PE4_TX_C_DP<8>")
	)
	(segment
		(start 329.012296 -410.989018)
		(end 329.462892 -414.050226)
		(width 0.14732)
		(layer "In6.Cu")
		(net "P5E_CPU0_PE4_TX_C_DP<8>")
	)
	(segment
		(start 329.557126 -414.691068)
		(end 329.61072 -415.055304)
		(width 0.14732)
		(layer "In6.Cu")
		(net "P5E_CPU0_PE4_TX_C_DP<8>")
	)
	(segment
		(start 325.98487 -402.96465)
		(end 326.311768 -402.637752)
		(width 0.13208)
		(layer "F.Cu")
		(net "P5E_CPU0_PE4_TX_C_DP<7>")
	)
	(segment
		(start 326.286368 -403.883876)
		(end 325.98487 -403.582378)
		(width 0.13208)
		(layer "F.Cu")
		(net "P5E_CPU0_PE4_TX_C_DP<7>")
	)
	(segment
		(start 325.98487 -403.582378)
		(end 325.98487 -402.96465)
		(width 0.13208)
		(layer "F.Cu")
		(net "P5E_CPU0_PE4_TX_C_DP<7>")
	)
	(segment
		(start 327.966832 -424.449748)
		(end 327.966832 -427.405292)
		(width 0.14732)
		(layer "In6.Cu")
		(net "P5E_CPU0_PE4_TX_C_DP<7>")
	)
	(segment
		(start 326.680322 -414.815528)
		(end 326.56272 -414.974278)
		(width 0.14732)
		(layer "In6.Cu")
		(net "P5E_CPU0_PE4_TX_C_DP<7>")
	)
	(segment
		(start 327.185528 -419.176708)
		(end 327.185528 -419.177216)
		(width 0.14732)
		(layer "In6.Cu")
		(net "P5E_CPU0_PE4_TX_C_DP<7>")
	)
	(segment
		(start 326.869044 -417.041584)
		(end 327.028048 -417.159186)
		(width 0.14732)
		(layer "In6.Cu")
		(net "P5E_CPU0_PE4_TX_C_DP<7>")
	)
	(segment
		(start 328.114152 -427.552612)
		(end 328.43851 -427.552612)
		(width 0.14732)
		(layer "In6.Cu")
		(net "P5E_CPU0_PE4_TX_C_DP<7>")
	)
	(segment
		(start 327.249536 -418.653214)
		(end 327.303384 -419.017958)
		(width 0.14732)
		(layer "In6.Cu")
		(net "P5E_CPU0_PE4_TX_C_DP<7>")
	)
	(segment
		(start 326.845676 -415.929064)
		(end 326.899524 -416.293808)
		(width 0.14732)
		(layer "In6.Cu")
		(net "P5E_CPU0_PE4_TX_C_DP<7>")
	)
	(segment
		(start 326.899524 -416.293808)
		(end 326.781922 -416.452304)
		(width 0.14732)
		(layer "In6.Cu")
		(net "P5E_CPU0_PE4_TX_C_DP<7>")
	)
	(segment
		(start 327.028048 -417.159186)
		(end 327.081896 -417.52393)
		(width 0.14732)
		(layer "In6.Cu")
		(net "P5E_CPU0_PE4_TX_C_DP<7>")
	)
	(segment
		(start 326.686672 -415.811462)
		(end 326.845676 -415.929064)
		(width 0.14732)
		(layer "In6.Cu")
		(net "P5E_CPU0_PE4_TX_C_DP<7>")
	)
	(segment
		(start 325.991728 -404.949914)
		(end 325.806308 -406.833324)
		(width 0.14732)
		(layer "In6.Cu")
		(net "P5E_CPU0_PE4_TX_C_DP<7>")
	)
	(segment
		(start 326.56272 -414.974278)
		(end 326.686672 -415.811462)
		(width 0.14732)
		(layer "In6.Cu")
		(net "P5E_CPU0_PE4_TX_C_DP<7>")
	)
	(segment
		(start 327.185782 -419.176454)
		(end 327.185528 -419.176708)
		(width 0.14732)
		(layer "In6.Cu")
		(net "P5E_CPU0_PE4_TX_C_DP<7>")
	)
	(segment
		(start 326.964294 -417.682426)
		(end 327.090532 -418.535612)
		(width 0.14732)
		(layer "In6.Cu")
		(net "P5E_CPU0_PE4_TX_C_DP<7>")
	)
	(segment
		(start 326.286368 -403.883876)
		(end 325.991728 -404.178516)
		(width 0.14732)
		(layer "In6.Cu")
		(net "P5E_CPU0_PE4_TX_C_DP<7>")
	)
	(segment
		(start 325.806308 -406.833324)
		(end 325.806308 -410.232098)
		(width 0.14732)
		(layer "In6.Cu")
		(net "P5E_CPU0_PE4_TX_C_DP<7>")
	)
	(segment
		(start 327.090532 -418.535612)
		(end 327.249536 -418.653214)
		(width 0.14732)
		(layer "In6.Cu")
		(net "P5E_CPU0_PE4_TX_C_DP<7>")
	)
	(segment
		(start 325.806308 -410.232098)
		(end 326.016112 -411.286706)
		(width 0.14732)
		(layer "In6.Cu")
		(net "P5E_CPU0_PE4_TX_C_DP<7>")
	)
	(segment
		(start 325.991728 -404.178516)
		(end 325.991728 -404.949914)
		(width 0.14732)
		(layer "In6.Cu")
		(net "P5E_CPU0_PE4_TX_C_DP<7>")
	)
	(segment
		(start 326.016112 -411.286706)
		(end 326.289416 -413.131762)
		(width 0.14732)
		(layer "In6.Cu")
		(net "P5E_CPU0_PE4_TX_C_DP<7>")
	)
	(segment
		(start 326.289924 -413.131762)
		(end 326.46747 -414.333182)
		(width 0.14732)
		(layer "In6.Cu")
		(net "P5E_CPU0_PE4_TX_C_DP<7>")
	)
	(segment
		(start 326.626474 -414.451038)
		(end 326.680322 -414.815528)
		(width 0.14732)
		(layer "In6.Cu")
		(net "P5E_CPU0_PE4_TX_C_DP<7>")
	)
	(segment
		(start 327.966832 -427.405292)
		(end 328.114152 -427.552612)
		(width 0.14732)
		(layer "In6.Cu")
		(net "P5E_CPU0_PE4_TX_C_DP<7>")
	)
	(segment
		(start 327.185528 -419.177216)
		(end 327.966832 -424.449748)
		(width 0.14732)
		(layer "In6.Cu")
		(net "P5E_CPU0_PE4_TX_C_DP<7>")
	)
	(segment
		(start 327.303384 -419.017958)
		(end 327.185782 -419.176454)
		(width 0.14732)
		(layer "In6.Cu")
		(net "P5E_CPU0_PE4_TX_C_DP<7>")
	)
	(segment
		(start 328.43851 -427.552612)
		(end 328.650092 -427.34103)
		(width 0.14732)
		(layer "In6.Cu")
		(net "P5E_CPU0_PE4_TX_C_DP<7>")
	)
	(segment
		(start 328.650092 -427.34103)
		(end 328.650092 -427.089824)
		(width 0.14732)
		(layer "In6.Cu")
		(net "P5E_CPU0_PE4_TX_C_DP<7>")
	)
	(segment
		(start 326.781922 -416.452304)
		(end 326.869044 -417.041584)
		(width 0.14732)
		(layer "In6.Cu")
		(net "P5E_CPU0_PE4_TX_C_DP<7>")
	)
	(segment
		(start 326.46747 -414.333182)
		(end 326.626474 -414.451038)
		(width 0.14732)
		(layer "In6.Cu")
		(net "P5E_CPU0_PE4_TX_C_DP<7>")
	)
	(segment
		(start 327.081896 -417.52393)
		(end 326.964294 -417.682426)
		(width 0.14732)
		(layer "In6.Cu")
		(net "P5E_CPU0_PE4_TX_C_DP<7>")
	)
	(segment
		(start 326.289416 -413.131762)
		(end 326.289924 -413.131762)
		(width 0.14732)
		(layer "In6.Cu")
		(net "P5E_CPU0_PE4_TX_C_DP<7>")
	)
	(segment
		(start 323.223128 -403.883876)
		(end 322.92163 -403.582378)
		(width 0.13208)
		(layer "F.Cu")
		(net "P5E_CPU0_PE4_TX_C_DP<6>")
	)
	(segment
		(start 322.92163 -403.582378)
		(end 322.92163 -402.96465)
		(width 0.13208)
		(layer "F.Cu")
		(net "P5E_CPU0_PE4_TX_C_DP<6>")
	)
	(segment
		(start 322.92163 -402.96465)
		(end 323.248528 -402.637752)
		(width 0.13208)
		(layer "F.Cu")
		(net "P5E_CPU0_PE4_TX_C_DP<6>")
	)
	(segment
		(start 326.42048 -426.570648)
		(end 326.650096 -426.341032)
		(width 0.14732)
		(layer "In6.Cu")
		(net "P5E_CPU0_PE4_TX_C_DP<6>")
	)
	(segment
		(start 324.650354 -417.805616)
		(end 324.54596 -417.97351)
		(width 0.14732)
		(layer "In6.Cu")
		(net "P5E_CPU0_PE4_TX_C_DP<6>")
	)
	(segment
		(start 324.208648 -416.528758)
		(end 324.39864 -417.342574)
		(width 0.14732)
		(layer "In6.Cu")
		(net "P5E_CPU0_PE4_TX_C_DP<6>")
	)
	(segment
		(start 326.157082 -426.570648)
		(end 326.42048 -426.570648)
		(width 0.14732)
		(layer "In6.Cu")
		(net "P5E_CPU0_PE4_TX_C_DP<6>")
	)
	(segment
		(start 324.954138 -419.106604)
		(end 324.849744 -419.274498)
		(width 0.14732)
		(layer "In6.Cu")
		(net "P5E_CPU0_PE4_TX_C_DP<6>")
	)
	(segment
		(start 324.870318 -418.747702)
		(end 324.954138 -419.106604)
		(width 0.14732)
		(layer "In6.Cu")
		(net "P5E_CPU0_PE4_TX_C_DP<6>")
	)
	(segment
		(start 326.650096 -426.341032)
		(end 326.650096 -426.089826)
		(width 0.14732)
		(layer "In6.Cu")
		(net "P5E_CPU0_PE4_TX_C_DP<6>")
	)
	(segment
		(start 325.94804 -426.361606)
		(end 326.157082 -426.570648)
		(width 0.14732)
		(layer "In6.Cu")
		(net "P5E_CPU0_PE4_TX_C_DP<6>")
	)
	(segment
		(start 325.94804 -423.978324)
		(end 325.94804 -426.361606)
		(width 0.14732)
		(layer "In6.Cu")
		(net "P5E_CPU0_PE4_TX_C_DP<6>")
	)
	(segment
		(start 324.313042 -416.361118)
		(end 324.208648 -416.528758)
		(width 0.14732)
		(layer "In6.Cu")
		(net "P5E_CPU0_PE4_TX_C_DP<6>")
	)
	(segment
		(start 324.566534 -417.446714)
		(end 324.650354 -417.805616)
		(width 0.14732)
		(layer "In6.Cu")
		(net "P5E_CPU0_PE4_TX_C_DP<6>")
	)
	(segment
		(start 324.39864 -417.342574)
		(end 324.566534 -417.446714)
		(width 0.14732)
		(layer "In6.Cu")
		(net "P5E_CPU0_PE4_TX_C_DP<6>")
	)
	(segment
		(start 323.789294 -414.735772)
		(end 323.789802 -414.736026)
		(width 0.14732)
		(layer "In6.Cu")
		(net "P5E_CPU0_PE4_TX_C_DP<6>")
	)
	(segment
		(start 323.957696 -414.84042)
		(end 324.041516 -415.199322)
		(width 0.14732)
		(layer "In6.Cu")
		(net "P5E_CPU0_PE4_TX_C_DP<6>")
	)
	(segment
		(start 322.743068 -406.833324)
		(end 322.743068 -410.252672)
		(width 0.14732)
		(layer "In6.Cu")
		(net "P5E_CPU0_PE4_TX_C_DP<6>")
	)
	(segment
		(start 322.928488 -404.178516)
		(end 322.928488 -404.949914)
		(width 0.14732)
		(layer "In6.Cu")
		(net "P5E_CPU0_PE4_TX_C_DP<6>")
	)
	(segment
		(start 324.061328 -415.897822)
		(end 324.229222 -416.002216)
		(width 0.14732)
		(layer "In6.Cu")
		(net "P5E_CPU0_PE4_TX_C_DP<6>")
	)
	(segment
		(start 323.937376 -415.366962)
		(end 324.061328 -415.897822)
		(width 0.14732)
		(layer "In6.Cu")
		(net "P5E_CPU0_PE4_TX_C_DP<6>")
	)
	(segment
		(start 325.021956 -420.012876)
		(end 325.190104 -420.11727)
		(width 0.14732)
		(layer "In6.Cu")
		(net "P5E_CPU0_PE4_TX_C_DP<6>")
	)
	(segment
		(start 324.229222 -416.002216)
		(end 324.313042 -416.361118)
		(width 0.14732)
		(layer "In6.Cu")
		(net "P5E_CPU0_PE4_TX_C_DP<6>")
	)
	(segment
		(start 325.190104 -420.11727)
		(end 325.273924 -420.476172)
		(width 0.14732)
		(layer "In6.Cu")
		(net "P5E_CPU0_PE4_TX_C_DP<6>")
	)
	(segment
		(start 323.789802 -414.736026)
		(end 323.957696 -414.84042)
		(width 0.14732)
		(layer "In6.Cu")
		(net "P5E_CPU0_PE4_TX_C_DP<6>")
	)
	(segment
		(start 325.16953 -420.644066)
		(end 325.94804 -423.978324)
		(width 0.14732)
		(layer "In6.Cu")
		(net "P5E_CPU0_PE4_TX_C_DP<6>")
	)
	(segment
		(start 322.743068 -410.252672)
		(end 323.789294 -414.735772)
		(width 0.14732)
		(layer "In6.Cu")
		(net "P5E_CPU0_PE4_TX_C_DP<6>")
	)
	(segment
		(start 324.54596 -417.97351)
		(end 324.70217 -418.643562)
		(width 0.14732)
		(layer "In6.Cu")
		(net "P5E_CPU0_PE4_TX_C_DP<6>")
	)
	(segment
		(start 325.273924 -420.476172)
		(end 325.16953 -420.644066)
		(width 0.14732)
		(layer "In6.Cu")
		(net "P5E_CPU0_PE4_TX_C_DP<6>")
	)
	(segment
		(start 324.70217 -418.643562)
		(end 324.870318 -418.747702)
		(width 0.14732)
		(layer "In6.Cu")
		(net "P5E_CPU0_PE4_TX_C_DP<6>")
	)
	(segment
		(start 324.849744 -419.274498)
		(end 325.021956 -420.012876)
		(width 0.14732)
		(layer "In6.Cu")
		(net "P5E_CPU0_PE4_TX_C_DP<6>")
	)
	(segment
		(start 322.928488 -404.949914)
		(end 322.743068 -406.833324)
		(width 0.14732)
		(layer "In6.Cu")
		(net "P5E_CPU0_PE4_TX_C_DP<6>")
	)
	(segment
		(start 323.223128 -403.883876)
		(end 322.928488 -404.178516)
		(width 0.14732)
		(layer "In6.Cu")
		(net "P5E_CPU0_PE4_TX_C_DP<6>")
	)
	(segment
		(start 324.041516 -415.199322)
		(end 323.937376 -415.366962)
		(width 0.14732)
		(layer "In6.Cu")
		(net "P5E_CPU0_PE4_TX_C_DP<6>")
	)
	(segment
		(start 320.159888 -403.883876)
		(end 319.85839 -403.582378)
		(width 0.13208)
		(layer "F.Cu")
		(net "P5E_CPU0_PE4_TX_C_DP<5>")
	)
	(segment
		(start 319.85839 -402.96465)
		(end 320.185288 -402.637752)
		(width 0.13208)
		(layer "F.Cu")
		(net "P5E_CPU0_PE4_TX_C_DP<5>")
	)
	(segment
		(start 319.85839 -403.582378)
		(end 319.85839 -402.96465)
		(width 0.13208)
		(layer "F.Cu")
		(net "P5E_CPU0_PE4_TX_C_DP<5>")
	)
	(segment
		(start 321.314826 -415.694876)
		(end 321.31508 -415.696146)
		(width 0.14732)
		(layer "In6.Cu")
		(net "P5E_CPU0_PE4_TX_C_DP<5>")
	)
	(segment
		(start 319.865248 -404.178516)
		(end 319.865248 -404.949914)
		(width 0.14732)
		(layer "In6.Cu")
		(net "P5E_CPU0_PE4_TX_C_DP<5>")
	)
	(segment
		(start 321.689222 -416.905694)
		(end 321.933062 -417.694364)
		(width 0.14732)
		(layer "In6.Cu")
		(net "P5E_CPU0_PE4_TX_C_DP<5>")
	)
	(segment
		(start 324.438518 -427.552612)
		(end 324.6501 -427.34103)
		(width 0.14732)
		(layer "In6.Cu")
		(net "P5E_CPU0_PE4_TX_C_DP<5>")
	)
	(segment
		(start 322.239386 -418.684456)
		(end 322.414392 -418.776658)
		(width 0.14732)
		(layer "In6.Cu")
		(net "P5E_CPU0_PE4_TX_C_DP<5>")
	)
	(segment
		(start 321.781424 -416.730942)
		(end 321.689222 -416.905694)
		(width 0.14732)
		(layer "In6.Cu")
		(net "P5E_CPU0_PE4_TX_C_DP<5>")
	)
	(segment
		(start 320.159888 -403.883876)
		(end 319.865248 -404.178516)
		(width 0.14732)
		(layer "In6.Cu")
		(net "P5E_CPU0_PE4_TX_C_DP<5>")
	)
	(segment
		(start 322.414392 -418.776658)
		(end 322.523104 -419.128702)
		(width 0.14732)
		(layer "In6.Cu")
		(net "P5E_CPU0_PE4_TX_C_DP<5>")
	)
	(segment
		(start 321.315334 -415.696654)
		(end 321.497706 -416.286696)
		(width 0.14732)
		(layer "In6.Cu")
		(net "P5E_CPU0_PE4_TX_C_DP<5>")
	)
	(segment
		(start 321.315588 -415.6964)
		(end 321.315334 -415.696654)
		(width 0.14732)
		(layer "In6.Cu")
		(net "P5E_CPU0_PE4_TX_C_DP<5>")
	)
	(segment
		(start 322.124832 -418.31387)
		(end 322.239386 -418.684456)
		(width 0.14732)
		(layer "In6.Cu")
		(net "P5E_CPU0_PE4_TX_C_DP<5>")
	)
	(segment
		(start 321.31508 -415.696146)
		(end 321.315588 -415.6964)
		(width 0.14732)
		(layer "In6.Cu")
		(net "P5E_CPU0_PE4_TX_C_DP<5>")
	)
	(segment
		(start 322.108068 -417.787074)
		(end 322.217034 -418.139118)
		(width 0.14732)
		(layer "In6.Cu")
		(net "P5E_CPU0_PE4_TX_C_DP<5>")
	)
	(segment
		(start 322.73748 -419.82136)
		(end 322.846192 -420.173404)
		(width 0.14732)
		(layer "In6.Cu")
		(net "P5E_CPU0_PE4_TX_C_DP<5>")
	)
	(segment
		(start 323.96684 -424.271948)
		(end 323.96684 -427.405292)
		(width 0.14732)
		(layer "In6.Cu")
		(net "P5E_CPU0_PE4_TX_C_DP<5>")
	)
	(segment
		(start 322.430902 -419.303454)
		(end 322.562474 -419.729158)
		(width 0.14732)
		(layer "In6.Cu")
		(net "P5E_CPU0_PE4_TX_C_DP<5>")
	)
	(segment
		(start 322.75399 -420.348156)
		(end 323.96684 -424.271948)
		(width 0.14732)
		(layer "In6.Cu")
		(net "P5E_CPU0_PE4_TX_C_DP<5>")
	)
	(segment
		(start 319.865248 -404.949914)
		(end 319.679828 -406.833324)
		(width 0.14732)
		(layer "In6.Cu")
		(net "P5E_CPU0_PE4_TX_C_DP<5>")
	)
	(segment
		(start 322.562474 -419.729158)
		(end 322.73748 -419.82136)
		(width 0.14732)
		(layer "In6.Cu")
		(net "P5E_CPU0_PE4_TX_C_DP<5>")
	)
	(segment
		(start 322.217034 -418.139118)
		(end 322.124832 -418.31387)
		(width 0.14732)
		(layer "In6.Cu")
		(net "P5E_CPU0_PE4_TX_C_DP<5>")
	)
	(segment
		(start 321.933316 -417.695126)
		(end 322.108068 -417.787074)
		(width 0.14732)
		(layer "In6.Cu")
		(net "P5E_CPU0_PE4_TX_C_DP<5>")
	)
	(segment
		(start 324.6501 -427.34103)
		(end 324.6501 -427.089824)
		(width 0.14732)
		(layer "In6.Cu")
		(net "P5E_CPU0_PE4_TX_C_DP<5>")
	)
	(segment
		(start 322.523104 -419.128702)
		(end 322.430902 -419.303454)
		(width 0.14732)
		(layer "In6.Cu")
		(net "P5E_CPU0_PE4_TX_C_DP<5>")
	)
	(segment
		(start 319.679828 -410.407358)
		(end 321.314826 -415.694876)
		(width 0.14732)
		(layer "In6.Cu")
		(net "P5E_CPU0_PE4_TX_C_DP<5>")
	)
	(segment
		(start 321.933062 -417.694364)
		(end 321.933316 -417.695126)
		(width 0.14732)
		(layer "In6.Cu")
		(net "P5E_CPU0_PE4_TX_C_DP<5>")
	)
	(segment
		(start 322.846192 -420.173404)
		(end 322.75399 -420.348156)
		(width 0.14732)
		(layer "In6.Cu")
		(net "P5E_CPU0_PE4_TX_C_DP<5>")
	)
	(segment
		(start 323.96684 -427.405292)
		(end 324.11416 -427.552612)
		(width 0.14732)
		(layer "In6.Cu")
		(net "P5E_CPU0_PE4_TX_C_DP<5>")
	)
	(segment
		(start 321.672712 -416.378898)
		(end 321.781424 -416.730942)
		(width 0.14732)
		(layer "In6.Cu")
		(net "P5E_CPU0_PE4_TX_C_DP<5>")
	)
	(segment
		(start 319.679828 -406.833324)
		(end 319.679828 -410.407358)
		(width 0.14732)
		(layer "In6.Cu")
		(net "P5E_CPU0_PE4_TX_C_DP<5>")
	)
	(segment
		(start 321.497706 -416.286696)
		(end 321.672712 -416.378898)
		(width 0.14732)
		(layer "In6.Cu")
		(net "P5E_CPU0_PE4_TX_C_DP<5>")
	)
	(segment
		(start 324.11416 -427.552612)
		(end 324.438518 -427.552612)
		(width 0.14732)
		(layer "In6.Cu")
		(net "P5E_CPU0_PE4_TX_C_DP<5>")
	)
	(segment
		(start 317.096648 -403.883876)
		(end 316.79515 -403.582378)
		(width 0.13208)
		(layer "F.Cu")
		(net "P5E_CPU0_PE4_TX_C_DP<4>")
	)
	(segment
		(start 316.79515 -402.96465)
		(end 317.122048 -402.637752)
		(width 0.13208)
		(layer "F.Cu")
		(net "P5E_CPU0_PE4_TX_C_DP<4>")
	)
	(segment
		(start 316.79515 -403.582378)
		(end 316.79515 -402.96465)
		(width 0.13208)
		(layer "F.Cu")
		(net "P5E_CPU0_PE4_TX_C_DP<4>")
	)
	(segment
		(start 319.072768 -416.887914)
		(end 319.630044 -418.337492)
		(width 0.14732)
		(layer "In6.Cu")
		(net "P5E_CPU0_PE4_TX_C_DP<4>")
	)
	(segment
		(start 320.189352 -419.45179)
		(end 320.34607 -419.859714)
		(width 0.14732)
		(layer "In6.Cu")
		(net "P5E_CPU0_PE4_TX_C_DP<4>")
	)
	(segment
		(start 318.828166 -416.252152)
		(end 318.986154 -416.322002)
		(width 0.14732)
		(layer "In6.Cu")
		(net "P5E_CPU0_PE4_TX_C_DP<4>")
	)
	(segment
		(start 320.590672 -420.495222)
		(end 320.74739 -420.903146)
		(width 0.14732)
		(layer "In6.Cu")
		(net "P5E_CPU0_PE4_TX_C_DP<4>")
	)
	(segment
		(start 317.096648 -403.883876)
		(end 316.802008 -404.178516)
		(width 0.14732)
		(layer "In6.Cu")
		(net "P5E_CPU0_PE4_TX_C_DP<4>")
	)
	(segment
		(start 320.34607 -419.859714)
		(end 320.27622 -420.017448)
		(width 0.14732)
		(layer "In6.Cu")
		(net "P5E_CPU0_PE4_TX_C_DP<4>")
	)
	(segment
		(start 319.630298 -418.338508)
		(end 319.788286 -418.408358)
		(width 0.14732)
		(layer "In6.Cu")
		(net "P5E_CPU0_PE4_TX_C_DP<4>")
	)
	(segment
		(start 319.945004 -418.816536)
		(end 319.8749 -418.974016)
		(width 0.14732)
		(layer "In6.Cu")
		(net "P5E_CPU0_PE4_TX_C_DP<4>")
	)
	(segment
		(start 318.828166 -416.251898)
		(end 318.828166 -416.252152)
		(width 0.14732)
		(layer "In6.Cu")
		(net "P5E_CPU0_PE4_TX_C_DP<4>")
	)
	(segment
		(start 320.27622 -420.017448)
		(end 320.432938 -420.425118)
		(width 0.14732)
		(layer "In6.Cu")
		(net "P5E_CPU0_PE4_TX_C_DP<4>")
	)
	(segment
		(start 319.788286 -418.408358)
		(end 319.945004 -418.816536)
		(width 0.14732)
		(layer "In6.Cu")
		(net "P5E_CPU0_PE4_TX_C_DP<4>")
	)
	(segment
		(start 318.340486 -414.64357)
		(end 318.270382 -414.80105)
		(width 0.14732)
		(layer "In6.Cu")
		(net "P5E_CPU0_PE4_TX_C_DP<4>")
	)
	(segment
		(start 319.142872 -416.73018)
		(end 319.072768 -416.88766)
		(width 0.14732)
		(layer "In6.Cu")
		(net "P5E_CPU0_PE4_TX_C_DP<4>")
	)
	(segment
		(start 319.630044 -418.337746)
		(end 319.630298 -418.338508)
		(width 0.14732)
		(layer "In6.Cu")
		(net "P5E_CPU0_PE4_TX_C_DP<4>")
	)
	(segment
		(start 319.630044 -418.337492)
		(end 319.630044 -418.337746)
		(width 0.14732)
		(layer "In6.Cu")
		(net "P5E_CPU0_PE4_TX_C_DP<4>")
	)
	(segment
		(start 318.986154 -416.322002)
		(end 319.142872 -416.73018)
		(width 0.14732)
		(layer "In6.Cu")
		(net "P5E_CPU0_PE4_TX_C_DP<4>")
	)
	(segment
		(start 318.025272 -414.164018)
		(end 318.02578 -414.165542)
		(width 0.14732)
		(layer "In6.Cu")
		(net "P5E_CPU0_PE4_TX_C_DP<4>")
	)
	(segment
		(start 318.741552 -415.686748)
		(end 318.671448 -415.844228)
		(width 0.14732)
		(layer "In6.Cu")
		(net "P5E_CPU0_PE4_TX_C_DP<4>")
	)
	(segment
		(start 318.4271 -415.20872)
		(end 318.426846 -415.20872)
		(width 0.14732)
		(layer "In6.Cu")
		(net "P5E_CPU0_PE4_TX_C_DP<4>")
	)
	(segment
		(start 320.67754 -421.060626)
		(end 321.962526 -424.403266)
		(width 0.14732)
		(layer "In6.Cu")
		(net "P5E_CPU0_PE4_TX_C_DP<4>")
	)
	(segment
		(start 318.183768 -414.235392)
		(end 318.340486 -414.64357)
		(width 0.14732)
		(layer "In6.Cu")
		(net "P5E_CPU0_PE4_TX_C_DP<4>")
	)
	(segment
		(start 318.671702 -415.84499)
		(end 318.828166 -416.251898)
		(width 0.14732)
		(layer "In6.Cu")
		(net "P5E_CPU0_PE4_TX_C_DP<4>")
	)
	(segment
		(start 320.74739 -420.903146)
		(end 320.67754 -421.060626)
		(width 0.14732)
		(layer "In6.Cu")
		(net "P5E_CPU0_PE4_TX_C_DP<4>")
	)
	(segment
		(start 316.616588 -410.500322)
		(end 318.025272 -414.164018)
		(width 0.14732)
		(layer "In6.Cu")
		(net "P5E_CPU0_PE4_TX_C_DP<4>")
	)
	(segment
		(start 322.650104 -426.341032)
		(end 322.650104 -426.089826)
		(width 0.14732)
		(layer "In6.Cu")
		(net "P5E_CPU0_PE4_TX_C_DP<4>")
	)
	(segment
		(start 318.426846 -415.20872)
		(end 318.584834 -415.27857)
		(width 0.14732)
		(layer "In6.Cu")
		(net "P5E_CPU0_PE4_TX_C_DP<4>")
	)
	(segment
		(start 319.875154 -418.974778)
		(end 320.031618 -419.381686)
		(width 0.14732)
		(layer "In6.Cu")
		(net "P5E_CPU0_PE4_TX_C_DP<4>")
	)
	(segment
		(start 316.802008 -404.178516)
		(end 316.802008 -404.949914)
		(width 0.14732)
		(layer "In6.Cu")
		(net "P5E_CPU0_PE4_TX_C_DP<4>")
	)
	(segment
		(start 316.616588 -406.833324)
		(end 316.616588 -410.500322)
		(width 0.14732)
		(layer "In6.Cu")
		(net "P5E_CPU0_PE4_TX_C_DP<4>")
	)
	(segment
		(start 319.072514 -416.887914)
		(end 319.072768 -416.887914)
		(width 0.14732)
		(layer "In6.Cu")
		(net "P5E_CPU0_PE4_TX_C_DP<4>")
	)
	(segment
		(start 320.031618 -419.381686)
		(end 320.189352 -419.45179)
		(width 0.14732)
		(layer "In6.Cu")
		(net "P5E_CPU0_PE4_TX_C_DP<4>")
	)
	(segment
		(start 322.114164 -426.552614)
		(end 322.438522 -426.552614)
		(width 0.14732)
		(layer "In6.Cu")
		(net "P5E_CPU0_PE4_TX_C_DP<4>")
	)
	(segment
		(start 321.966844 -426.405294)
		(end 322.114164 -426.552614)
		(width 0.14732)
		(layer "In6.Cu")
		(net "P5E_CPU0_PE4_TX_C_DP<4>")
	)
	(segment
		(start 318.584834 -415.27857)
		(end 318.741552 -415.686748)
		(width 0.14732)
		(layer "In6.Cu")
		(net "P5E_CPU0_PE4_TX_C_DP<4>")
	)
	(segment
		(start 321.966844 -424.404028)
		(end 321.966844 -426.405294)
		(width 0.14732)
		(layer "In6.Cu")
		(net "P5E_CPU0_PE4_TX_C_DP<4>")
	)
	(segment
		(start 321.962526 -424.403266)
		(end 321.966082 -424.403266)
		(width 0.14732)
		(layer "In6.Cu")
		(net "P5E_CPU0_PE4_TX_C_DP<4>")
	)
	(segment
		(start 320.432938 -420.425118)
		(end 320.590672 -420.495222)
		(width 0.14732)
		(layer "In6.Cu")
		(net "P5E_CPU0_PE4_TX_C_DP<4>")
	)
	(segment
		(start 318.270382 -414.80105)
		(end 318.4271 -415.20872)
		(width 0.14732)
		(layer "In6.Cu")
		(net "P5E_CPU0_PE4_TX_C_DP<4>")
	)
	(segment
		(start 322.438522 -426.552614)
		(end 322.650104 -426.341032)
		(width 0.14732)
		(layer "In6.Cu")
		(net "P5E_CPU0_PE4_TX_C_DP<4>")
	)
	(segment
		(start 321.966082 -424.403266)
		(end 321.966844 -424.404028)
		(width 0.14732)
		(layer "In6.Cu")
		(net "P5E_CPU0_PE4_TX_C_DP<4>")
	)
	(segment
		(start 318.671448 -415.844228)
		(end 318.671702 -415.84499)
		(width 0.14732)
		(layer "In6.Cu")
		(net "P5E_CPU0_PE4_TX_C_DP<4>")
	)
	(segment
		(start 319.8749 -418.974016)
		(end 319.875154 -418.974778)
		(width 0.14732)
		(layer "In6.Cu")
		(net "P5E_CPU0_PE4_TX_C_DP<4>")
	)
	(segment
		(start 319.072768 -416.88766)
		(end 319.072514 -416.887914)
		(width 0.14732)
		(layer "In6.Cu")
		(net "P5E_CPU0_PE4_TX_C_DP<4>")
	)
	(segment
		(start 318.02578 -414.165542)
		(end 318.183768 -414.235392)
		(width 0.14732)
		(layer "In6.Cu")
		(net "P5E_CPU0_PE4_TX_C_DP<4>")
	)
	(segment
		(start 316.802008 -404.949914)
		(end 316.616588 -406.833324)
		(width 0.14732)
		(layer "In6.Cu")
		(net "P5E_CPU0_PE4_TX_C_DP<4>")
	)
	(segment
		(start 313.73191 -402.96465)
		(end 314.058808 -402.637752)
		(width 0.13208)
		(layer "F.Cu")
		(net "P5E_CPU0_PE4_TX_C_DP<3>")
	)
	(segment
		(start 313.73191 -403.582378)
		(end 313.73191 -402.96465)
		(width 0.13208)
		(layer "F.Cu")
		(net "P5E_CPU0_PE4_TX_C_DP<3>")
	)
	(segment
		(start 314.033408 -403.883876)
		(end 313.73191 -403.582378)
		(width 0.13208)
		(layer "F.Cu")
		(net "P5E_CPU0_PE4_TX_C_DP<3>")
	)
	(segment
		(start 316.75832 -417.447984)
		(end 316.913768 -417.78174)
		(width 0.14732)
		(layer "In6.Cu")
		(net "P5E_CPU0_PE4_TX_C_DP<3>")
	)
	(segment
		(start 319.966848 -424.335448)
		(end 319.966848 -427.405292)
		(width 0.14732)
		(layer "In6.Cu")
		(net "P5E_CPU0_PE4_TX_C_DP<3>")
	)
	(segment
		(start 313.738768 -404.949914)
		(end 313.553348 -406.833324)
		(width 0.14732)
		(layer "In6.Cu")
		(net "P5E_CPU0_PE4_TX_C_DP<3>")
	)
	(segment
		(start 320.114168 -427.552612)
		(end 320.438526 -427.552612)
		(width 0.14732)
		(layer "In6.Cu")
		(net "P5E_CPU0_PE4_TX_C_DP<3>")
	)
	(segment
		(start 317.255144 -418.183568)
		(end 317.18758 -418.368988)
		(width 0.14732)
		(layer "In6.Cu")
		(net "P5E_CPU0_PE4_TX_C_DP<3>")
	)
	(segment
		(start 316.825884 -417.26231)
		(end 316.75832 -417.447984)
		(width 0.14732)
		(layer "In6.Cu")
		(net "P5E_CPU0_PE4_TX_C_DP<3>")
	)
	(segment
		(start 315.798708 -415.058352)
		(end 315.95441 -415.392362)
		(width 0.14732)
		(layer "In6.Cu")
		(net "P5E_CPU0_PE4_TX_C_DP<3>")
	)
	(segment
		(start 315.613034 -414.990788)
		(end 315.798708 -415.058352)
		(width 0.14732)
		(layer "In6.Cu")
		(net "P5E_CPU0_PE4_TX_C_DP<3>")
	)
	(segment
		(start 316.913768 -417.78174)
		(end 317.099696 -417.849304)
		(width 0.14732)
		(layer "In6.Cu")
		(net "P5E_CPU0_PE4_TX_C_DP<3>")
	)
	(segment
		(start 315.95441 -415.392362)
		(end 315.886846 -415.578036)
		(width 0.14732)
		(layer "In6.Cu")
		(net "P5E_CPU0_PE4_TX_C_DP<3>")
	)
	(segment
		(start 316.484508 -416.860482)
		(end 316.670436 -416.9283)
		(width 0.14732)
		(layer "In6.Cu")
		(net "P5E_CPU0_PE4_TX_C_DP<3>")
	)
	(segment
		(start 319.966848 -427.405292)
		(end 320.114168 -427.552612)
		(width 0.14732)
		(layer "In6.Cu")
		(net "P5E_CPU0_PE4_TX_C_DP<3>")
	)
	(segment
		(start 315.886846 -415.578036)
		(end 316.042294 -415.911792)
		(width 0.14732)
		(layer "In6.Cu")
		(net "P5E_CPU0_PE4_TX_C_DP<3>")
	)
	(segment
		(start 316.042294 -415.911792)
		(end 316.228222 -415.979356)
		(width 0.14732)
		(layer "In6.Cu")
		(net "P5E_CPU0_PE4_TX_C_DP<3>")
	)
	(segment
		(start 317.18758 -418.368988)
		(end 319.966848 -424.335448)
		(width 0.14732)
		(layer "In6.Cu")
		(net "P5E_CPU0_PE4_TX_C_DP<3>")
	)
	(segment
		(start 316.38367 -416.313366)
		(end 316.316106 -416.49904)
		(width 0.14732)
		(layer "In6.Cu")
		(net "P5E_CPU0_PE4_TX_C_DP<3>")
	)
	(segment
		(start 316.228222 -415.979356)
		(end 316.38367 -416.313366)
		(width 0.14732)
		(layer "In6.Cu")
		(net "P5E_CPU0_PE4_TX_C_DP<3>")
	)
	(segment
		(start 313.553348 -406.833324)
		(end 313.553348 -410.570426)
		(width 0.14732)
		(layer "In6.Cu")
		(net "P5E_CPU0_PE4_TX_C_DP<3>")
	)
	(segment
		(start 316.670436 -416.9283)
		(end 316.825884 -417.26231)
		(width 0.14732)
		(layer "In6.Cu")
		(net "P5E_CPU0_PE4_TX_C_DP<3>")
	)
	(segment
		(start 313.738768 -404.178516)
		(end 313.738768 -404.949914)
		(width 0.14732)
		(layer "In6.Cu")
		(net "P5E_CPU0_PE4_TX_C_DP<3>")
	)
	(segment
		(start 314.033408 -403.883876)
		(end 313.738768 -404.178516)
		(width 0.14732)
		(layer "In6.Cu")
		(net "P5E_CPU0_PE4_TX_C_DP<3>")
	)
	(segment
		(start 317.099696 -417.849304)
		(end 317.255144 -418.183568)
		(width 0.14732)
		(layer "In6.Cu")
		(net "P5E_CPU0_PE4_TX_C_DP<3>")
	)
	(segment
		(start 320.650108 -427.34103)
		(end 320.650108 -427.089824)
		(width 0.14732)
		(layer "In6.Cu")
		(net "P5E_CPU0_PE4_TX_C_DP<3>")
	)
	(segment
		(start 320.438526 -427.552612)
		(end 320.650108 -427.34103)
		(width 0.14732)
		(layer "In6.Cu")
		(net "P5E_CPU0_PE4_TX_C_DP<3>")
	)
	(segment
		(start 313.553348 -410.570426)
		(end 315.613034 -414.990788)
		(width 0.14732)
		(layer "In6.Cu")
		(net "P5E_CPU0_PE4_TX_C_DP<3>")
	)
	(segment
		(start 316.316106 -416.49904)
		(end 316.484508 -416.860482)
		(width 0.14732)
		(layer "In6.Cu")
		(net "P5E_CPU0_PE4_TX_C_DP<3>")
	)
	(segment
		(start 310.66867 -402.96465)
		(end 310.995568 -402.637752)
		(width 0.13208)
		(layer "F.Cu")
		(net "P5E_CPU0_PE4_TX_C_DP<2>")
	)
	(segment
		(start 310.970168 -403.883876)
		(end 310.66867 -403.582378)
		(width 0.13208)
		(layer "F.Cu")
		(net "P5E_CPU0_PE4_TX_C_DP<2>")
	)
	(segment
		(start 310.66867 -403.582378)
		(end 310.66867 -402.96465)
		(width 0.13208)
		(layer "F.Cu")
		(net "P5E_CPU0_PE4_TX_C_DP<2>")
	)
	(segment
		(start 315.397642 -419.691566)
		(end 315.572648 -420.015416)
		(width 0.14732)
		(layer "In6.Cu")
		(net "P5E_CPU0_PE4_TX_C_DP<2>")
	)
	(segment
		(start 315.572648 -420.015416)
		(end 315.762132 -420.071804)
		(width 0.14732)
		(layer "In6.Cu")
		(net "P5E_CPU0_PE4_TX_C_DP<2>")
	)
	(segment
		(start 315.762132 -420.071804)
		(end 315.937392 -420.396162)
		(width 0.14732)
		(layer "In6.Cu")
		(net "P5E_CPU0_PE4_TX_C_DP<2>")
	)
	(segment
		(start 317.966852 -426.405294)
		(end 318.114172 -426.552614)
		(width 0.14732)
		(layer "In6.Cu")
		(net "P5E_CPU0_PE4_TX_C_DP<2>")
	)
	(segment
		(start 314.860178 -418.403024)
		(end 314.803536 -418.592508)
		(width 0.14732)
		(layer "In6.Cu")
		(net "P5E_CPU0_PE4_TX_C_DP<2>")
	)
	(segment
		(start 313.465972 -415.823908)
		(end 313.641232 -416.148012)
		(width 0.14732)
		(layer "In6.Cu")
		(net "P5E_CPU0_PE4_TX_C_DP<2>")
	)
	(segment
		(start 314.684918 -418.07892)
		(end 314.860178 -418.403024)
		(width 0.14732)
		(layer "In6.Cu")
		(net "P5E_CPU0_PE4_TX_C_DP<2>")
	)
	(segment
		(start 315.45403 -419.502082)
		(end 315.397642 -419.691566)
		(width 0.14732)
		(layer "In6.Cu")
		(net "P5E_CPU0_PE4_TX_C_DP<2>")
	)
	(segment
		(start 315.089286 -419.121336)
		(end 315.279024 -419.177978)
		(width 0.14732)
		(layer "In6.Cu")
		(net "P5E_CPU0_PE4_TX_C_DP<2>")
	)
	(segment
		(start 313.276488 -415.767266)
		(end 313.465972 -415.823908)
		(width 0.14732)
		(layer "In6.Cu")
		(net "P5E_CPU0_PE4_TX_C_DP<2>")
	)
	(segment
		(start 310.675528 -404.949914)
		(end 310.490108 -406.833324)
		(width 0.14732)
		(layer "In6.Cu")
		(net "P5E_CPU0_PE4_TX_C_DP<2>")
	)
	(segment
		(start 313.58459 -416.337496)
		(end 313.858402 -416.844226)
		(width 0.14732)
		(layer "In6.Cu")
		(net "P5E_CPU0_PE4_TX_C_DP<2>")
	)
	(segment
		(start 318.114172 -426.552614)
		(end 318.43853 -426.552614)
		(width 0.14732)
		(layer "In6.Cu")
		(net "P5E_CPU0_PE4_TX_C_DP<2>")
	)
	(segment
		(start 318.43853 -426.552614)
		(end 318.650112 -426.341032)
		(width 0.14732)
		(layer "In6.Cu")
		(net "P5E_CPU0_PE4_TX_C_DP<2>")
	)
	(segment
		(start 314.223146 -417.224972)
		(end 314.166758 -417.414202)
		(width 0.14732)
		(layer "In6.Cu")
		(net "P5E_CPU0_PE4_TX_C_DP<2>")
	)
	(segment
		(start 310.490108 -406.833324)
		(end 310.490108 -410.612336)
		(width 0.14732)
		(layer "In6.Cu")
		(net "P5E_CPU0_PE4_TX_C_DP<2>")
	)
	(segment
		(start 314.047886 -416.900614)
		(end 314.223146 -417.224972)
		(width 0.14732)
		(layer "In6.Cu")
		(net "P5E_CPU0_PE4_TX_C_DP<2>")
	)
	(segment
		(start 314.166758 -417.414202)
		(end 314.495434 -418.022278)
		(width 0.14732)
		(layer "In6.Cu")
		(net "P5E_CPU0_PE4_TX_C_DP<2>")
	)
	(segment
		(start 310.675528 -404.178516)
		(end 310.675528 -404.949914)
		(width 0.14732)
		(layer "In6.Cu")
		(net "P5E_CPU0_PE4_TX_C_DP<2>")
	)
	(segment
		(start 315.881004 -420.585392)
		(end 317.966852 -424.444668)
		(width 0.14732)
		(layer "In6.Cu")
		(net "P5E_CPU0_PE4_TX_C_DP<2>")
	)
	(segment
		(start 314.495434 -418.022278)
		(end 314.684918 -418.07892)
		(width 0.14732)
		(layer "In6.Cu")
		(net "P5E_CPU0_PE4_TX_C_DP<2>")
	)
	(segment
		(start 318.650112 -426.341032)
		(end 318.650112 -426.089826)
		(width 0.14732)
		(layer "In6.Cu")
		(net "P5E_CPU0_PE4_TX_C_DP<2>")
	)
	(segment
		(start 313.641232 -416.148012)
		(end 313.58459 -416.337496)
		(width 0.14732)
		(layer "In6.Cu")
		(net "P5E_CPU0_PE4_TX_C_DP<2>")
	)
	(segment
		(start 317.966852 -424.444668)
		(end 317.966852 -426.405294)
		(width 0.14732)
		(layer "In6.Cu")
		(net "P5E_CPU0_PE4_TX_C_DP<2>")
	)
	(segment
		(start 314.803536 -418.592508)
		(end 315.089286 -419.121336)
		(width 0.14732)
		(layer "In6.Cu")
		(net "P5E_CPU0_PE4_TX_C_DP<2>")
	)
	(segment
		(start 313.858402 -416.844226)
		(end 314.047886 -416.900614)
		(width 0.14732)
		(layer "In6.Cu")
		(net "P5E_CPU0_PE4_TX_C_DP<2>")
	)
	(segment
		(start 310.970168 -403.883876)
		(end 310.675528 -404.178516)
		(width 0.14732)
		(layer "In6.Cu")
		(net "P5E_CPU0_PE4_TX_C_DP<2>")
	)
	(segment
		(start 315.937392 -420.396162)
		(end 315.881004 -420.585392)
		(width 0.14732)
		(layer "In6.Cu")
		(net "P5E_CPU0_PE4_TX_C_DP<2>")
	)
	(segment
		(start 315.279024 -419.177978)
		(end 315.45403 -419.502082)
		(width 0.14732)
		(layer "In6.Cu")
		(net "P5E_CPU0_PE4_TX_C_DP<2>")
	)
	(segment
		(start 310.490108 -410.612336)
		(end 313.276488 -415.767266)
		(width 0.14732)
		(layer "In6.Cu")
		(net "P5E_CPU0_PE4_TX_C_DP<2>")
	)
	(segment
		(start 307.34635 -403.580854)
		(end 307.34635 -402.962872)
		(width 0.13208)
		(layer "F.Cu")
		(net "P5E_CPU0_PE4_TX_C_DP<1>")
	)
	(segment
		(start 307.02123 -402.637752)
		(end 307.017928 -402.637752)
		(width 0.13208)
		(layer "F.Cu")
		(net "P5E_CPU0_PE4_TX_C_DP<1>")
	)
	(segment
		(start 307.34635 -402.962872)
		(end 307.02123 -402.637752)
		(width 0.13208)
		(layer "F.Cu")
		(net "P5E_CPU0_PE4_TX_C_DP<1>")
	)
	(segment
		(start 307.043328 -403.883876)
		(end 307.34635 -403.580854)
		(width 0.13208)
		(layer "F.Cu")
		(net "P5E_CPU0_PE4_TX_C_DP<1>")
	)
	(segment
		(start 316.000384 -427.826932)
		(end 315.692536 -427.519084)
		(width 0.14732)
		(layer "In6.Cu")
		(net "P5E_CPU0_PE4_TX_C_DP<1>")
	)
	(segment
		(start 316.650116 -428.28972)
		(end 316.650116 -427.974506)
		(width 0.14732)
		(layer "In6.Cu")
		(net "P5E_CPU0_PE4_TX_C_DP<1>")
	)
	(segment
		(start 316.650116 -427.974506)
		(end 316.502542 -427.826932)
		(width 0.14732)
		(layer "In6.Cu")
		(net "P5E_CPU0_PE4_TX_C_DP<1>")
	)
	(segment
		(start 315.692536 -427.519084)
		(end 315.692536 -424.887898)
		(width 0.14732)
		(layer "In6.Cu")
		(net "P5E_CPU0_PE4_TX_C_DP<1>")
	)
	(segment
		(start 316.502542 -427.826932)
		(end 316.000384 -427.826932)
		(width 0.14732)
		(layer "In6.Cu")
		(net "P5E_CPU0_PE4_TX_C_DP<1>")
	)
	(segment
		(start 307.337968 -404.178516)
		(end 307.043328 -403.883876)
		(width 0.14732)
		(layer "In6.Cu")
		(net "P5E_CPU0_PE4_TX_C_DP<1>")
	)
	(segment
		(start 315.692536 -424.887898)
		(end 307.152548 -410.709618)
		(width 0.14732)
		(layer "In6.Cu")
		(net "P5E_CPU0_PE4_TX_C_DP<1>")
	)
	(segment
		(start 307.152548 -406.819608)
		(end 307.337968 -404.936198)
		(width 0.14732)
		(layer "In6.Cu")
		(net "P5E_CPU0_PE4_TX_C_DP<1>")
	)
	(segment
		(start 307.337968 -404.936198)
		(end 307.337968 -404.178516)
		(width 0.14732)
		(layer "In6.Cu")
		(net "P5E_CPU0_PE4_TX_C_DP<1>")
	)
	(segment
		(start 307.152548 -410.709618)
		(end 307.152548 -406.819608)
		(width 0.14732)
		(layer "In6.Cu")
		(net "P5E_CPU0_PE4_TX_C_DP<1>")
	)
	(segment
		(start 350.49079 -402.96465)
		(end 350.817688 -402.637752)
		(width 0.13208)
		(layer "F.Cu")
		(net "P5E_CPU0_PE4_TX_C_DP<15>")
	)
	(segment
		(start 350.792288 -403.883876)
		(end 350.49079 -403.582378)
		(width 0.13208)
		(layer "F.Cu")
		(net "P5E_CPU0_PE4_TX_C_DP<15>")
	)
	(segment
		(start 350.49079 -403.582378)
		(end 350.49079 -402.96465)
		(width 0.13208)
		(layer "F.Cu")
		(net "P5E_CPU0_PE4_TX_C_DP<15>")
	)
	(segment
		(start 346.792296 -420.098728)
		(end 346.60967 -420.174928)
		(width 0.14732)
		(layer "In6.Cu")
		(net "P5E_CPU0_PE4_TX_C_DP<15>")
	)
	(segment
		(start 347.204792 -419.092634)
		(end 347.02242 -419.169088)
		(width 0.14732)
		(layer "In6.Cu")
		(net "P5E_CPU0_PE4_TX_C_DP<15>")
	)
	(segment
		(start 347.02242 -419.169088)
		(end 346.855796 -419.575488)
		(width 0.14732)
		(layer "In6.Cu")
		(net "P5E_CPU0_PE4_TX_C_DP<15>")
	)
	(segment
		(start 350.497648 -404.178516)
		(end 350.497648 -404.949914)
		(width 0.14732)
		(layer "In6.Cu")
		(net "P5E_CPU0_PE4_TX_C_DP<15>")
	)
	(segment
		(start 346.60967 -420.174928)
		(end 346.610178 -420.174928)
		(width 0.14732)
		(layer "In6.Cu")
		(net "P5E_CPU0_PE4_TX_C_DP<15>")
	)
	(segment
		(start 348.159578 -416.3949)
		(end 348.159832 -416.395154)
		(width 0.14732)
		(layer "In6.Cu")
		(net "P5E_CPU0_PE4_TX_C_DP<15>")
	)
	(segment
		(start 347.734128 -417.433506)
		(end 347.810328 -417.615624)
		(width 0.14732)
		(layer "In6.Cu")
		(net "P5E_CPU0_PE4_TX_C_DP<15>")
	)
	(segment
		(start 346.610178 -420.174928)
		(end 346.609924 -420.175182)
		(width 0.14732)
		(layer "In6.Cu")
		(net "P5E_CPU0_PE4_TX_C_DP<15>")
	)
	(segment
		(start 350.792288 -403.883876)
		(end 350.497648 -404.178516)
		(width 0.14732)
		(layer "In6.Cu")
		(net "P5E_CPU0_PE4_TX_C_DP<15>")
	)
	(segment
		(start 348.096332 -416.918394)
		(end 347.91396 -416.994594)
		(width 0.14732)
		(layer "In6.Cu")
		(net "P5E_CPU0_PE4_TX_C_DP<15>")
	)
	(segment
		(start 348.159832 -416.395154)
		(end 348.236032 -416.577272)
		(width 0.14732)
		(layer "In6.Cu")
		(net "P5E_CPU0_PE4_TX_C_DP<15>")
	)
	(segment
		(start 347.810328 -417.615624)
		(end 347.670628 -417.956746)
		(width 0.14732)
		(layer "In6.Cu")
		(net "P5E_CPU0_PE4_TX_C_DP<15>")
	)
	(segment
		(start 346.855796 -419.575488)
		(end 346.931996 -419.757606)
		(width 0.14732)
		(layer "In6.Cu")
		(net "P5E_CPU0_PE4_TX_C_DP<15>")
	)
	(segment
		(start 347.670628 -417.956746)
		(end 347.488256 -418.032946)
		(width 0.14732)
		(layer "In6.Cu")
		(net "P5E_CPU0_PE4_TX_C_DP<15>")
	)
	(segment
		(start 344.966798 -427.405292)
		(end 345.114118 -427.552612)
		(width 0.14732)
		(layer "In6.Cu")
		(net "P5E_CPU0_PE4_TX_C_DP<15>")
	)
	(segment
		(start 348.236032 -416.577272)
		(end 348.096332 -416.918394)
		(width 0.14732)
		(layer "In6.Cu")
		(net "P5E_CPU0_PE4_TX_C_DP<15>")
	)
	(segment
		(start 345.438476 -427.552612)
		(end 345.650058 -427.34103)
		(width 0.14732)
		(layer "In6.Cu")
		(net "P5E_CPU0_PE4_TX_C_DP<15>")
	)
	(segment
		(start 345.114118 -427.552612)
		(end 345.438476 -427.552612)
		(width 0.14732)
		(layer "In6.Cu")
		(net "P5E_CPU0_PE4_TX_C_DP<15>")
	)
	(segment
		(start 350.312228 -406.833324)
		(end 350.312228 -411.144466)
		(width 0.14732)
		(layer "In6.Cu")
		(net "P5E_CPU0_PE4_TX_C_DP<15>")
	)
	(segment
		(start 347.91396 -416.994594)
		(end 347.734128 -417.433506)
		(width 0.14732)
		(layer "In6.Cu")
		(net "P5E_CPU0_PE4_TX_C_DP<15>")
	)
	(segment
		(start 347.344492 -418.751766)
		(end 347.204792 -419.092634)
		(width 0.14732)
		(layer "In6.Cu")
		(net "P5E_CPU0_PE4_TX_C_DP<15>")
	)
	(segment
		(start 350.497648 -404.949914)
		(end 350.312228 -406.833324)
		(width 0.14732)
		(layer "In6.Cu")
		(net "P5E_CPU0_PE4_TX_C_DP<15>")
	)
	(segment
		(start 347.268292 -418.569394)
		(end 347.344492 -418.751766)
		(width 0.14732)
		(layer "In6.Cu")
		(net "P5E_CPU0_PE4_TX_C_DP<15>")
	)
	(segment
		(start 347.488256 -418.032946)
		(end 347.268292 -418.569394)
		(width 0.14732)
		(layer "In6.Cu")
		(net "P5E_CPU0_PE4_TX_C_DP<15>")
	)
	(segment
		(start 346.931996 -419.757606)
		(end 346.792296 -420.098728)
		(width 0.14732)
		(layer "In6.Cu")
		(net "P5E_CPU0_PE4_TX_C_DP<15>")
	)
	(segment
		(start 350.312228 -411.144466)
		(end 348.159578 -416.3949)
		(width 0.14732)
		(layer "In6.Cu")
		(net "P5E_CPU0_PE4_TX_C_DP<15>")
	)
	(segment
		(start 344.966798 -424.182286)
		(end 344.966798 -427.405292)
		(width 0.14732)
		(layer "In6.Cu")
		(net "P5E_CPU0_PE4_TX_C_DP<15>")
	)
	(segment
		(start 345.650058 -427.34103)
		(end 345.650058 -427.089824)
		(width 0.14732)
		(layer "In6.Cu")
		(net "P5E_CPU0_PE4_TX_C_DP<15>")
	)
	(segment
		(start 346.609924 -420.175182)
		(end 344.966798 -424.182286)
		(width 0.14732)
		(layer "In6.Cu")
		(net "P5E_CPU0_PE4_TX_C_DP<15>")
	)
	(segment
		(start 347.42755 -402.96465)
		(end 347.754448 -402.637752)
		(width 0.13208)
		(layer "F.Cu")
		(net "P5E_CPU0_PE4_TX_C_DP<14>")
	)
	(segment
		(start 347.42755 -403.582378)
		(end 347.42755 -402.96465)
		(width 0.13208)
		(layer "F.Cu")
		(net "P5E_CPU0_PE4_TX_C_DP<14>")
	)
	(segment
		(start 347.729048 -403.883876)
		(end 347.42755 -403.582378)
		(width 0.13208)
		(layer "F.Cu")
		(net "P5E_CPU0_PE4_TX_C_DP<14>")
	)
	(segment
		(start 344.270838 -420.423594)
		(end 344.156284 -420.77386)
		(width 0.14732)
		(layer "In6.Cu")
		(net "P5E_CPU0_PE4_TX_C_DP<14>")
	)
	(segment
		(start 347.729048 -403.883876)
		(end 347.434408 -404.178516)
		(width 0.14732)
		(layer "In6.Cu")
		(net "P5E_CPU0_PE4_TX_C_DP<14>")
	)
	(segment
		(start 343.580466 -422.066212)
		(end 343.580212 -422.066466)
		(width 0.14732)
		(layer "In6.Cu")
		(net "P5E_CPU0_PE4_TX_C_DP<14>")
	)
	(segment
		(start 342.966802 -423.9387)
		(end 342.966802 -426.351192)
		(width 0.14732)
		(layer "In6.Cu")
		(net "P5E_CPU0_PE4_TX_C_DP<14>")
	)
	(segment
		(start 343.466166 -426.524928)
		(end 343.650062 -426.341032)
		(width 0.14732)
		(layer "In6.Cu")
		(net "P5E_CPU0_PE4_TX_C_DP<14>")
	)
	(segment
		(start 343.580212 -422.066466)
		(end 342.966802 -423.9387)
		(width 0.14732)
		(layer "In6.Cu")
		(net "P5E_CPU0_PE4_TX_C_DP<14>")
	)
	(segment
		(start 344.36685 -419.665404)
		(end 344.178382 -420.240968)
		(width 0.14732)
		(layer "In6.Cu")
		(net "P5E_CPU0_PE4_TX_C_DP<14>")
	)
	(segment
		(start 345.63431 -415.795714)
		(end 345.72702 -415.97834)
		(width 0.14732)
		(layer "In6.Cu")
		(net "P5E_CPU0_PE4_TX_C_DP<14>")
	)
	(segment
		(start 346.219272 -414.474914)
		(end 346.104718 -414.82518)
		(width 0.14732)
		(layer "In6.Cu")
		(net "P5E_CPU0_PE4_TX_C_DP<14>")
	)
	(segment
		(start 344.664284 -419.222428)
		(end 344.54973 -419.572694)
		(width 0.14732)
		(layer "In6.Cu")
		(net "P5E_CPU0_PE4_TX_C_DP<14>")
	)
	(segment
		(start 347.434408 -404.178516)
		(end 347.434408 -404.949914)
		(width 0.14732)
		(layer "In6.Cu")
		(net "P5E_CPU0_PE4_TX_C_DP<14>")
	)
	(segment
		(start 343.762838 -421.973756)
		(end 343.579958 -422.066212)
		(width 0.14732)
		(layer "In6.Cu")
		(net "P5E_CPU0_PE4_TX_C_DP<14>")
	)
	(segment
		(start 344.156284 -420.77386)
		(end 343.973404 -420.866316)
		(width 0.14732)
		(layer "In6.Cu")
		(net "P5E_CPU0_PE4_TX_C_DP<14>")
	)
	(segment
		(start 343.78519 -421.440864)
		(end 343.877646 -421.62349)
		(width 0.14732)
		(layer "In6.Cu")
		(net "P5E_CPU0_PE4_TX_C_DP<14>")
	)
	(segment
		(start 345.612212 -416.328606)
		(end 345.429332 -416.421062)
		(width 0.14732)
		(layer "In6.Cu")
		(net "P5E_CPU0_PE4_TX_C_DP<14>")
	)
	(segment
		(start 346.104718 -414.82518)
		(end 345.921838 -414.917636)
		(width 0.14732)
		(layer "In6.Cu")
		(net "P5E_CPU0_PE4_TX_C_DP<14>")
	)
	(segment
		(start 343.877646 -421.62349)
		(end 343.762838 -421.973756)
		(width 0.14732)
		(layer "In6.Cu")
		(net "P5E_CPU0_PE4_TX_C_DP<14>")
	)
	(segment
		(start 347.248988 -406.833324)
		(end 347.248988 -410.86532)
		(width 0.14732)
		(layer "In6.Cu")
		(net "P5E_CPU0_PE4_TX_C_DP<14>")
	)
	(segment
		(start 344.54973 -419.572694)
		(end 344.36685 -419.665404)
		(width 0.14732)
		(layer "In6.Cu")
		(net "P5E_CPU0_PE4_TX_C_DP<14>")
	)
	(segment
		(start 346.126816 -414.292034)
		(end 346.219272 -414.474914)
		(width 0.14732)
		(layer "In6.Cu")
		(net "P5E_CPU0_PE4_TX_C_DP<14>")
	)
	(segment
		(start 343.650062 -426.341032)
		(end 343.650062 -426.089826)
		(width 0.14732)
		(layer "In6.Cu")
		(net "P5E_CPU0_PE4_TX_C_DP<14>")
	)
	(segment
		(start 342.966802 -426.351192)
		(end 343.140538 -426.524928)
		(width 0.14732)
		(layer "In6.Cu")
		(net "P5E_CPU0_PE4_TX_C_DP<14>")
	)
	(segment
		(start 345.72702 -415.97834)
		(end 345.612212 -416.328606)
		(width 0.14732)
		(layer "In6.Cu")
		(net "P5E_CPU0_PE4_TX_C_DP<14>")
	)
	(segment
		(start 347.434408 -404.949914)
		(end 347.248988 -406.833324)
		(width 0.14732)
		(layer "In6.Cu")
		(net "P5E_CPU0_PE4_TX_C_DP<14>")
	)
	(segment
		(start 345.429332 -416.421062)
		(end 344.571828 -419.039802)
		(width 0.14732)
		(layer "In6.Cu")
		(net "P5E_CPU0_PE4_TX_C_DP<14>")
	)
	(segment
		(start 344.178382 -420.240968)
		(end 344.270838 -420.423594)
		(width 0.14732)
		(layer "In6.Cu")
		(net "P5E_CPU0_PE4_TX_C_DP<14>")
	)
	(segment
		(start 343.140538 -426.524928)
		(end 343.466166 -426.524928)
		(width 0.14732)
		(layer "In6.Cu")
		(net "P5E_CPU0_PE4_TX_C_DP<14>")
	)
	(segment
		(start 347.248988 -410.86532)
		(end 346.126816 -414.292034)
		(width 0.14732)
		(layer "In6.Cu")
		(net "P5E_CPU0_PE4_TX_C_DP<14>")
	)
	(segment
		(start 345.921838 -414.917636)
		(end 345.63431 -415.795714)
		(width 0.14732)
		(layer "In6.Cu")
		(net "P5E_CPU0_PE4_TX_C_DP<14>")
	)
	(segment
		(start 343.973404 -420.866316)
		(end 343.78519 -421.440864)
		(width 0.14732)
		(layer "In6.Cu")
		(net "P5E_CPU0_PE4_TX_C_DP<14>")
	)
	(segment
		(start 343.579958 -422.066212)
		(end 343.580466 -422.066212)
		(width 0.14732)
		(layer "In6.Cu")
		(net "P5E_CPU0_PE4_TX_C_DP<14>")
	)
	(segment
		(start 344.571828 -419.039802)
		(end 344.664284 -419.222428)
		(width 0.14732)
		(layer "In6.Cu")
		(net "P5E_CPU0_PE4_TX_C_DP<14>")
	)
	(segment
		(start 344.36431 -402.96465)
		(end 344.691208 -402.637752)
		(width 0.13208)
		(layer "F.Cu")
		(net "P5E_CPU0_PE4_TX_C_DP<13>")
	)
	(segment
		(start 344.665808 -403.883876)
		(end 344.36431 -403.582378)
		(width 0.13208)
		(layer "F.Cu")
		(net "P5E_CPU0_PE4_TX_C_DP<13>")
	)
	(segment
		(start 344.36431 -403.582378)
		(end 344.36431 -402.96465)
		(width 0.13208)
		(layer "F.Cu")
		(net "P5E_CPU0_PE4_TX_C_DP<13>")
	)
	(segment
		(start 343.069164 -415.921698)
		(end 342.79205 -417.033202)
		(width 0.14732)
		(layer "In6.Cu")
		(net "P5E_CPU0_PE4_TX_C_DP<13>")
	)
	(segment
		(start 341.114126 -427.552612)
		(end 341.438484 -427.552612)
		(width 0.14732)
		(layer "In6.Cu")
		(net "P5E_CPU0_PE4_TX_C_DP<13>")
	)
	(segment
		(start 341.438484 -427.552612)
		(end 341.650066 -427.34103)
		(width 0.14732)
		(layer "In6.Cu")
		(net "P5E_CPU0_PE4_TX_C_DP<13>")
	)
	(segment
		(start 343.738454 -413.239458)
		(end 343.620344 -413.712914)
		(width 0.14732)
		(layer "In6.Cu")
		(net "P5E_CPU0_PE4_TX_C_DP<13>")
	)
	(segment
		(start 343.997026 -412.780226)
		(end 343.907872 -413.137858)
		(width 0.14732)
		(layer "In6.Cu")
		(net "P5E_CPU0_PE4_TX_C_DP<13>")
	)
	(segment
		(start 343.238582 -415.820352)
		(end 343.069164 -415.921698)
		(width 0.14732)
		(layer "In6.Cu")
		(net "P5E_CPU0_PE4_TX_C_DP<13>")
	)
	(segment
		(start 342.635078 -417.662106)
		(end 340.966806 -424.34891)
		(width 0.14732)
		(layer "In6.Cu")
		(net "P5E_CPU0_PE4_TX_C_DP<13>")
	)
	(segment
		(start 344.185748 -411.446218)
		(end 343.895426 -412.610808)
		(width 0.14732)
		(layer "In6.Cu")
		(net "P5E_CPU0_PE4_TX_C_DP<13>")
	)
	(segment
		(start 343.226136 -415.293302)
		(end 343.327736 -415.46272)
		(width 0.14732)
		(layer "In6.Cu")
		(net "P5E_CPU0_PE4_TX_C_DP<13>")
	)
	(segment
		(start 343.63279 -414.239964)
		(end 343.463372 -414.341564)
		(width 0.14732)
		(layer "In6.Cu")
		(net "P5E_CPU0_PE4_TX_C_DP<13>")
	)
	(segment
		(start 343.327736 -415.46272)
		(end 343.238582 -415.820352)
		(width 0.14732)
		(layer "In6.Cu")
		(net "P5E_CPU0_PE4_TX_C_DP<13>")
	)
	(segment
		(start 344.371168 -404.949914)
		(end 344.185748 -406.833324)
		(width 0.14732)
		(layer "In6.Cu")
		(net "P5E_CPU0_PE4_TX_C_DP<13>")
	)
	(segment
		(start 344.185748 -406.833324)
		(end 344.185748 -411.446218)
		(width 0.14732)
		(layer "In6.Cu")
		(net "P5E_CPU0_PE4_TX_C_DP<13>")
	)
	(segment
		(start 343.721944 -413.882332)
		(end 343.63279 -414.239964)
		(width 0.14732)
		(layer "In6.Cu")
		(net "P5E_CPU0_PE4_TX_C_DP<13>")
	)
	(segment
		(start 343.620344 -413.712914)
		(end 343.721944 -413.882332)
		(width 0.14732)
		(layer "In6.Cu")
		(net "P5E_CPU0_PE4_TX_C_DP<13>")
	)
	(segment
		(start 340.966806 -424.34891)
		(end 340.966806 -427.405292)
		(width 0.14732)
		(layer "In6.Cu")
		(net "P5E_CPU0_PE4_TX_C_DP<13>")
	)
	(segment
		(start 342.804496 -417.560252)
		(end 342.635078 -417.662106)
		(width 0.14732)
		(layer "In6.Cu")
		(net "P5E_CPU0_PE4_TX_C_DP<13>")
	)
	(segment
		(start 343.895426 -412.610808)
		(end 343.997026 -412.780226)
		(width 0.14732)
		(layer "In6.Cu")
		(net "P5E_CPU0_PE4_TX_C_DP<13>")
	)
	(segment
		(start 342.89365 -417.20262)
		(end 342.804496 -417.560252)
		(width 0.14732)
		(layer "In6.Cu")
		(net "P5E_CPU0_PE4_TX_C_DP<13>")
	)
	(segment
		(start 341.650066 -427.34103)
		(end 341.650066 -427.089824)
		(width 0.14732)
		(layer "In6.Cu")
		(net "P5E_CPU0_PE4_TX_C_DP<13>")
	)
	(segment
		(start 344.665808 -403.883876)
		(end 344.371168 -404.178516)
		(width 0.14732)
		(layer "In6.Cu")
		(net "P5E_CPU0_PE4_TX_C_DP<13>")
	)
	(segment
		(start 343.907872 -413.137858)
		(end 343.738454 -413.239458)
		(width 0.14732)
		(layer "In6.Cu")
		(net "P5E_CPU0_PE4_TX_C_DP<13>")
	)
	(segment
		(start 344.371168 -404.178516)
		(end 344.371168 -404.949914)
		(width 0.14732)
		(layer "In6.Cu")
		(net "P5E_CPU0_PE4_TX_C_DP<13>")
	)
	(segment
		(start 342.79205 -417.033202)
		(end 342.89365 -417.20262)
		(width 0.14732)
		(layer "In6.Cu")
		(net "P5E_CPU0_PE4_TX_C_DP<13>")
	)
	(segment
		(start 343.463372 -414.341564)
		(end 343.226136 -415.293302)
		(width 0.14732)
		(layer "In6.Cu")
		(net "P5E_CPU0_PE4_TX_C_DP<13>")
	)
	(segment
		(start 340.966806 -427.405292)
		(end 341.114126 -427.552612)
		(width 0.14732)
		(layer "In6.Cu")
		(net "P5E_CPU0_PE4_TX_C_DP<13>")
	)
	(segment
		(start 341.602568 -403.883876)
		(end 341.30107 -403.582378)
		(width 0.13208)
		(layer "F.Cu")
		(net "P5E_CPU0_PE4_TX_C_DP<12>")
	)
	(segment
		(start 341.30107 -402.96465)
		(end 341.627968 -402.637752)
		(width 0.13208)
		(layer "F.Cu")
		(net "P5E_CPU0_PE4_TX_C_DP<12>")
	)
	(segment
		(start 341.30107 -403.582378)
		(end 341.30107 -402.96465)
		(width 0.13208)
		(layer "F.Cu")
		(net "P5E_CPU0_PE4_TX_C_DP<12>")
	)
	(segment
		(start 340.537546 -415.977578)
		(end 340.376256 -416.092132)
		(width 0.14732)
		(layer "In6.Cu")
		(net "P5E_CPU0_PE4_TX_C_DP<12>")
	)
	(segment
		(start 339.895434 -419.772592)
		(end 339.833966 -420.136066)
		(width 0.14732)
		(layer "In6.Cu")
		(net "P5E_CPU0_PE4_TX_C_DP<12>")
	)
	(segment
		(start 339.833966 -420.136066)
		(end 339.67293 -420.250112)
		(width 0.14732)
		(layer "In6.Cu")
		(net "P5E_CPU0_PE4_TX_C_DP<12>")
	)
	(segment
		(start 340.08568 -417.810442)
		(end 340.19998 -417.971478)
		(width 0.14732)
		(layer "In6.Cu")
		(net "P5E_CPU0_PE4_TX_C_DP<12>")
	)
	(segment
		(start 339.67293 -420.250112)
		(end 338.96681 -424.424602)
		(width 0.14732)
		(layer "In6.Cu")
		(net "P5E_CPU0_PE4_TX_C_DP<12>")
	)
	(segment
		(start 339.977476 -418.449506)
		(end 339.78088 -419.611556)
		(width 0.14732)
		(layer "In6.Cu")
		(net "P5E_CPU0_PE4_TX_C_DP<12>")
	)
	(segment
		(start 338.96681 -424.424602)
		(end 338.96681 -426.405294)
		(width 0.14732)
		(layer "In6.Cu")
		(net "P5E_CPU0_PE4_TX_C_DP<12>")
	)
	(segment
		(start 340.336124 -417.168838)
		(end 340.174834 -417.283392)
		(width 0.14732)
		(layer "In6.Cu")
		(net "P5E_CPU0_PE4_TX_C_DP<12>")
	)
	(segment
		(start 340.554056 -415.042858)
		(end 340.484714 -415.453068)
		(width 0.14732)
		(layer "In6.Cu")
		(net "P5E_CPU0_PE4_TX_C_DP<12>")
	)
	(segment
		(start 340.484714 -415.453068)
		(end 340.599014 -415.614104)
		(width 0.14732)
		(layer "In6.Cu")
		(net "P5E_CPU0_PE4_TX_C_DP<12>")
	)
	(segment
		(start 340.599014 -415.614104)
		(end 340.537546 -415.977578)
		(width 0.14732)
		(layer "In6.Cu")
		(net "P5E_CPU0_PE4_TX_C_DP<12>")
	)
	(segment
		(start 340.174834 -417.283392)
		(end 340.08568 -417.810442)
		(width 0.14732)
		(layer "In6.Cu")
		(net "P5E_CPU0_PE4_TX_C_DP<12>")
	)
	(segment
		(start 341.122508 -406.833324)
		(end 341.122508 -411.67939)
		(width 0.14732)
		(layer "In6.Cu")
		(net "P5E_CPU0_PE4_TX_C_DP<12>")
	)
	(segment
		(start 340.397338 -416.805618)
		(end 340.336124 -417.168838)
		(width 0.14732)
		(layer "In6.Cu")
		(net "P5E_CPU0_PE4_TX_C_DP<12>")
	)
	(segment
		(start 341.307928 -404.949914)
		(end 341.122508 -406.833324)
		(width 0.14732)
		(layer "In6.Cu")
		(net "P5E_CPU0_PE4_TX_C_DP<12>")
	)
	(segment
		(start 340.77656 -414.565084)
		(end 340.715346 -414.928304)
		(width 0.14732)
		(layer "In6.Cu")
		(net "P5E_CPU0_PE4_TX_C_DP<12>")
	)
	(segment
		(start 340.19998 -417.971478)
		(end 340.138766 -418.334952)
		(width 0.14732)
		(layer "In6.Cu")
		(net "P5E_CPU0_PE4_TX_C_DP<12>")
	)
	(segment
		(start 339.438488 -426.552614)
		(end 339.65007 -426.341032)
		(width 0.14732)
		(layer "In6.Cu")
		(net "P5E_CPU0_PE4_TX_C_DP<12>")
	)
	(segment
		(start 340.661752 -414.40354)
		(end 340.66226 -414.404048)
		(width 0.14732)
		(layer "In6.Cu")
		(net "P5E_CPU0_PE4_TX_C_DP<12>")
	)
	(segment
		(start 340.376256 -416.092132)
		(end 340.283038 -416.644582)
		(width 0.14732)
		(layer "In6.Cu")
		(net "P5E_CPU0_PE4_TX_C_DP<12>")
	)
	(segment
		(start 338.96681 -426.405294)
		(end 339.11413 -426.552614)
		(width 0.14732)
		(layer "In6.Cu")
		(net "P5E_CPU0_PE4_TX_C_DP<12>")
	)
	(segment
		(start 339.65007 -426.341032)
		(end 339.65007 -426.089826)
		(width 0.14732)
		(layer "In6.Cu")
		(net "P5E_CPU0_PE4_TX_C_DP<12>")
	)
	(segment
		(start 340.66226 -414.404048)
		(end 340.77656 -414.565084)
		(width 0.14732)
		(layer "In6.Cu")
		(net "P5E_CPU0_PE4_TX_C_DP<12>")
	)
	(segment
		(start 339.11413 -426.552614)
		(end 339.438488 -426.552614)
		(width 0.14732)
		(layer "In6.Cu")
		(net "P5E_CPU0_PE4_TX_C_DP<12>")
	)
	(segment
		(start 341.307928 -404.178516)
		(end 341.307928 -404.949914)
		(width 0.14732)
		(layer "In6.Cu")
		(net "P5E_CPU0_PE4_TX_C_DP<12>")
	)
	(segment
		(start 339.97773 -418.449252)
		(end 339.977476 -418.449506)
		(width 0.14732)
		(layer "In6.Cu")
		(net "P5E_CPU0_PE4_TX_C_DP<12>")
	)
	(segment
		(start 339.977476 -418.449252)
		(end 339.97773 -418.449252)
		(width 0.14732)
		(layer "In6.Cu")
		(net "P5E_CPU0_PE4_TX_C_DP<12>")
	)
	(segment
		(start 340.138766 -418.334952)
		(end 339.977476 -418.449252)
		(width 0.14732)
		(layer "In6.Cu")
		(net "P5E_CPU0_PE4_TX_C_DP<12>")
	)
	(segment
		(start 339.78088 -419.611556)
		(end 339.895434 -419.772592)
		(width 0.14732)
		(layer "In6.Cu")
		(net "P5E_CPU0_PE4_TX_C_DP<12>")
	)
	(segment
		(start 340.283038 -416.644582)
		(end 340.397338 -416.805618)
		(width 0.14732)
		(layer "In6.Cu")
		(net "P5E_CPU0_PE4_TX_C_DP<12>")
	)
	(segment
		(start 340.715346 -414.928304)
		(end 340.554056 -415.042858)
		(width 0.14732)
		(layer "In6.Cu")
		(net "P5E_CPU0_PE4_TX_C_DP<12>")
	)
	(segment
		(start 341.602568 -403.883876)
		(end 341.307928 -404.178516)
		(width 0.14732)
		(layer "In6.Cu")
		(net "P5E_CPU0_PE4_TX_C_DP<12>")
	)
	(segment
		(start 341.122508 -411.67939)
		(end 340.661752 -414.40354)
		(width 0.14732)
		(layer "In6.Cu")
		(net "P5E_CPU0_PE4_TX_C_DP<12>")
	)
	(segment
		(start 337.97875 -402.962872)
		(end 337.65363 -402.637752)
		(width 0.13208)
		(layer "F.Cu")
		(net "P5E_CPU0_PE4_TX_C_DP<11>")
	)
	(segment
		(start 337.675728 -403.883876)
		(end 337.97875 -403.580854)
		(width 0.13208)
		(layer "F.Cu")
		(net "P5E_CPU0_PE4_TX_C_DP<11>")
	)
	(segment
		(start 337.97875 -403.580854)
		(end 337.97875 -402.962872)
		(width 0.13208)
		(layer "F.Cu")
		(net "P5E_CPU0_PE4_TX_C_DP<11>")
	)
	(segment
		(start 337.65363 -402.637752)
		(end 337.650328 -402.637752)
		(width 0.13208)
		(layer "F.Cu")
		(net "P5E_CPU0_PE4_TX_C_DP<11>")
	)
	(segment
		(start 337.650074 -427.974506)
		(end 337.5025 -427.826932)
		(width 0.14732)
		(layer "In6.Cu")
		(net "P5E_CPU0_PE4_TX_C_DP<11>")
	)
	(segment
		(start 336.692494 -424.358308)
		(end 337.784948 -412.317184)
		(width 0.14732)
		(layer "In6.Cu")
		(net "P5E_CPU0_PE4_TX_C_DP<11>")
	)
	(segment
		(start 337.784948 -412.317184)
		(end 337.784948 -406.819608)
		(width 0.14732)
		(layer "In6.Cu")
		(net "P5E_CPU0_PE4_TX_C_DP<11>")
	)
	(segment
		(start 337.970368 -404.178516)
		(end 337.675728 -403.883876)
		(width 0.14732)
		(layer "In6.Cu")
		(net "P5E_CPU0_PE4_TX_C_DP<11>")
	)
	(segment
		(start 336.692494 -427.519084)
		(end 336.692494 -424.358308)
		(width 0.14732)
		(layer "In6.Cu")
		(net "P5E_CPU0_PE4_TX_C_DP<11>")
	)
	(segment
		(start 337.650074 -428.28972)
		(end 337.650074 -427.974506)
		(width 0.14732)
		(layer "In6.Cu")
		(net "P5E_CPU0_PE4_TX_C_DP<11>")
	)
	(segment
		(start 337.784948 -406.819608)
		(end 337.970368 -404.936198)
		(width 0.14732)
		(layer "In6.Cu")
		(net "P5E_CPU0_PE4_TX_C_DP<11>")
	)
	(segment
		(start 337.5025 -427.826932)
		(end 337.000342 -427.826932)
		(width 0.14732)
		(layer "In6.Cu")
		(net "P5E_CPU0_PE4_TX_C_DP<11>")
	)
	(segment
		(start 337.970368 -404.936198)
		(end 337.970368 -404.178516)
		(width 0.14732)
		(layer "In6.Cu")
		(net "P5E_CPU0_PE4_TX_C_DP<11>")
	)
	(segment
		(start 337.000342 -427.826932)
		(end 336.692494 -427.519084)
		(width 0.14732)
		(layer "In6.Cu")
		(net "P5E_CPU0_PE4_TX_C_DP<11>")
	)
	(segment
		(start 335.476088 -403.883876)
		(end 335.17459 -403.582378)
		(width 0.13208)
		(layer "F.Cu")
		(net "P5E_CPU0_PE4_TX_C_DP<10>")
	)
	(segment
		(start 335.17459 -403.582378)
		(end 335.17459 -402.96465)
		(width 0.13208)
		(layer "F.Cu")
		(net "P5E_CPU0_PE4_TX_C_DP<10>")
	)
	(segment
		(start 335.17459 -402.96465)
		(end 335.501488 -402.637752)
		(width 0.13208)
		(layer "F.Cu")
		(net "P5E_CPU0_PE4_TX_C_DP<10>")
	)
	(segment
		(start 335.045558 -417.76904)
		(end 334.945482 -426.383958)
		(width 0.14732)
		(layer "In6.Cu")
		(net "P5E_CPU0_PE4_TX_C_DP<10>")
	)
	(segment
		(start 335.063592 -410.789882)
		(end 335.113122 -411.932628)
		(width 0.14732)
		(layer "In6.Cu")
		(net "P5E_CPU0_PE4_TX_C_DP<10>")
	)
	(segment
		(start 335.202276 -414.963102)
		(end 335.197196 -415.400236)
		(width 0.14732)
		(layer "In6.Cu")
		(net "P5E_CPU0_PE4_TX_C_DP<10>")
	)
	(segment
		(start 335.189576 -416.086036)
		(end 335.184496 -416.52317)
		(width 0.14732)
		(layer "In6.Cu")
		(net "P5E_CPU0_PE4_TX_C_DP<10>")
	)
	(segment
		(start 335.476088 -403.883876)
		(end 335.181448 -404.178516)
		(width 0.14732)
		(layer "In6.Cu")
		(net "P5E_CPU0_PE4_TX_C_DP<10>")
	)
	(segment
		(start 335.171288 -417.64585)
		(end 335.04505 -417.768786)
		(width 0.14732)
		(layer "In6.Cu")
		(net "P5E_CPU0_PE4_TX_C_DP<10>")
	)
	(segment
		(start 335.650078 -426.341032)
		(end 335.650078 -426.089826)
		(width 0.14732)
		(layer "In6.Cu")
		(net "P5E_CPU0_PE4_TX_C_DP<10>")
	)
	(segment
		(start 334.996028 -410.102812)
		(end 335.063592 -410.789882)
		(width 0.14732)
		(layer "In6.Cu")
		(net "P5E_CPU0_PE4_TX_C_DP<10>")
	)
	(segment
		(start 335.181448 -404.178516)
		(end 335.181448 -404.949914)
		(width 0.14732)
		(layer "In6.Cu")
		(net "P5E_CPU0_PE4_TX_C_DP<10>")
	)
	(segment
		(start 335.176368 -417.208716)
		(end 335.171288 -417.64585)
		(width 0.14732)
		(layer "In6.Cu")
		(net "P5E_CPU0_PE4_TX_C_DP<10>")
	)
	(segment
		(start 335.114138 -426.552614)
		(end 335.438496 -426.552614)
		(width 0.14732)
		(layer "In6.Cu")
		(net "P5E_CPU0_PE4_TX_C_DP<10>")
	)
	(segment
		(start 335.184496 -416.52317)
		(end 335.058258 -416.646106)
		(width 0.14732)
		(layer "In6.Cu")
		(net "P5E_CPU0_PE4_TX_C_DP<10>")
	)
	(segment
		(start 335.058258 -416.646106)
		(end 335.053432 -417.082732)
		(width 0.14732)
		(layer "In6.Cu")
		(net "P5E_CPU0_PE4_TX_C_DP<10>")
	)
	(segment
		(start 335.228692 -412.717742)
		(end 335.223612 -413.154876)
		(width 0.14732)
		(layer "In6.Cu")
		(net "P5E_CPU0_PE4_TX_C_DP<10>")
	)
	(segment
		(start 335.105502 -412.592012)
		(end 335.228692 -412.717742)
		(width 0.14732)
		(layer "In6.Cu")
		(net "P5E_CPU0_PE4_TX_C_DP<10>")
	)
	(segment
		(start 335.097374 -413.277812)
		(end 335.092548 -413.714438)
		(width 0.14732)
		(layer "In6.Cu")
		(net "P5E_CPU0_PE4_TX_C_DP<10>")
	)
	(segment
		(start 335.223612 -413.154876)
		(end 335.097374 -413.277812)
		(width 0.14732)
		(layer "In6.Cu")
		(net "P5E_CPU0_PE4_TX_C_DP<10>")
	)
	(segment
		(start 335.06664 -415.960052)
		(end 335.189576 -416.086036)
		(width 0.14732)
		(layer "In6.Cu")
		(net "P5E_CPU0_PE4_TX_C_DP<10>")
	)
	(segment
		(start 335.070958 -415.523172)
		(end 335.071466 -415.523426)
		(width 0.14732)
		(layer "In6.Cu")
		(net "P5E_CPU0_PE4_TX_C_DP<10>")
	)
	(segment
		(start 335.07934 -414.837118)
		(end 335.202276 -414.963102)
		(width 0.14732)
		(layer "In6.Cu")
		(net "P5E_CPU0_PE4_TX_C_DP<10>")
	)
	(segment
		(start 335.181448 -404.949914)
		(end 334.996028 -406.833324)
		(width 0.14732)
		(layer "In6.Cu")
		(net "P5E_CPU0_PE4_TX_C_DP<10>")
	)
	(segment
		(start 335.438496 -426.552614)
		(end 335.650078 -426.341032)
		(width 0.14732)
		(layer "In6.Cu")
		(net "P5E_CPU0_PE4_TX_C_DP<10>")
	)
	(segment
		(start 334.945482 -426.383958)
		(end 335.114138 -426.552614)
		(width 0.14732)
		(layer "In6.Cu")
		(net "P5E_CPU0_PE4_TX_C_DP<10>")
	)
	(segment
		(start 335.113122 -411.932628)
		(end 335.105502 -412.592012)
		(width 0.14732)
		(layer "In6.Cu")
		(net "P5E_CPU0_PE4_TX_C_DP<10>")
	)
	(segment
		(start 335.071466 -415.523426)
		(end 335.06664 -415.960052)
		(width 0.14732)
		(layer "In6.Cu")
		(net "P5E_CPU0_PE4_TX_C_DP<10>")
	)
	(segment
		(start 334.996028 -406.833324)
		(end 334.996028 -410.102812)
		(width 0.14732)
		(layer "In6.Cu")
		(net "P5E_CPU0_PE4_TX_C_DP<10>")
	)
	(segment
		(start 335.04505 -417.768786)
		(end 335.045558 -417.76904)
		(width 0.14732)
		(layer "In6.Cu")
		(net "P5E_CPU0_PE4_TX_C_DP<10>")
	)
	(segment
		(start 335.215484 -413.840422)
		(end 335.210404 -414.277556)
		(width 0.14732)
		(layer "In6.Cu")
		(net "P5E_CPU0_PE4_TX_C_DP<10>")
	)
	(segment
		(start 335.053432 -417.082732)
		(end 335.176368 -417.208716)
		(width 0.14732)
		(layer "In6.Cu")
		(net "P5E_CPU0_PE4_TX_C_DP<10>")
	)
	(segment
		(start 335.092548 -413.714438)
		(end 335.215484 -413.840422)
		(width 0.14732)
		(layer "In6.Cu")
		(net "P5E_CPU0_PE4_TX_C_DP<10>")
	)
	(segment
		(start 335.210404 -414.277556)
		(end 335.084166 -414.400492)
		(width 0.14732)
		(layer "In6.Cu")
		(net "P5E_CPU0_PE4_TX_C_DP<10>")
	)
	(segment
		(start 335.197196 -415.400236)
		(end 335.070958 -415.523172)
		(width 0.14732)
		(layer "In6.Cu")
		(net "P5E_CPU0_PE4_TX_C_DP<10>")
	)
	(segment
		(start 335.084166 -414.400492)
		(end 335.07934 -414.837118)
		(width 0.14732)
		(layer "In6.Cu")
		(net "P5E_CPU0_PE4_TX_C_DP<10>")
	)
	(segment
		(start 304.54219 -402.96465)
		(end 304.869088 -402.637752)
		(width 0.13208)
		(layer "F.Cu")
		(net "P5E_CPU0_PE4_TX_C_DP<0>")
	)
	(segment
		(start 304.843688 -403.883876)
		(end 304.54219 -403.582378)
		(width 0.13208)
		(layer "F.Cu")
		(net "P5E_CPU0_PE4_TX_C_DP<0>")
	)
	(segment
		(start 304.54219 -403.582378)
		(end 304.54219 -402.96465)
		(width 0.13208)
		(layer "F.Cu")
		(net "P5E_CPU0_PE4_TX_C_DP<0>")
	)
	(segment
		(start 314.65012 -426.341032)
		(end 314.65012 -426.089826)
		(width 0.14732)
		(layer "In6.Cu")
		(net "P5E_CPU0_PE4_TX_C_DP<0>")
	)
	(segment
		(start 311.662318 -422.47947)
		(end 311.61482 -422.67124)
		(width 0.14732)
		(layer "In6.Cu")
		(net "P5E_CPU0_PE4_TX_C_DP<0>")
	)
	(segment
		(start 308.452012 -417.160964)
		(end 308.404514 -417.352988)
		(width 0.14732)
		(layer "In6.Cu")
		(net "P5E_CPU0_PE4_TX_C_DP<0>")
	)
	(segment
		(start 308.404514 -417.352988)
		(end 308.834536 -418.065204)
		(width 0.14732)
		(layer "In6.Cu")
		(net "P5E_CPU0_PE4_TX_C_DP<0>")
	)
	(segment
		(start 310.33466 -420.550594)
		(end 310.526684 -420.598092)
		(width 0.14732)
		(layer "In6.Cu")
		(net "P5E_CPU0_PE4_TX_C_DP<0>")
	)
	(segment
		(start 309.169308 -418.61994)
		(end 309.617872 -419.36289)
		(width 0.14732)
		(layer "In6.Cu")
		(net "P5E_CPU0_PE4_TX_C_DP<0>")
	)
	(segment
		(start 314.438538 -426.552614)
		(end 314.65012 -426.341032)
		(width 0.14732)
		(layer "In6.Cu")
		(net "P5E_CPU0_PE4_TX_C_DP<0>")
	)
	(segment
		(start 309.617872 -419.36289)
		(end 309.809642 -419.410388)
		(width 0.14732)
		(layer "In6.Cu")
		(net "P5E_CPU0_PE4_TX_C_DP<0>")
	)
	(segment
		(start 310.526684 -420.598092)
		(end 310.717184 -420.91356)
		(width 0.14732)
		(layer "In6.Cu")
		(net "P5E_CPU0_PE4_TX_C_DP<0>")
	)
	(segment
		(start 304.549048 -404.949914)
		(end 304.363628 -406.833324)
		(width 0.14732)
		(layer "In6.Cu")
		(net "P5E_CPU0_PE4_TX_C_DP<0>")
	)
	(segment
		(start 313.719464 -426.157898)
		(end 314.11418 -426.552614)
		(width 0.14732)
		(layer "In6.Cu")
		(net "P5E_CPU0_PE4_TX_C_DP<0>")
	)
	(segment
		(start 311.280048 -422.116504)
		(end 311.471818 -422.163748)
		(width 0.14732)
		(layer "In6.Cu")
		(net "P5E_CPU0_PE4_TX_C_DP<0>")
	)
	(segment
		(start 310.669686 -421.10533)
		(end 311.280048 -422.116504)
		(width 0.14732)
		(layer "In6.Cu")
		(net "P5E_CPU0_PE4_TX_C_DP<0>")
	)
	(segment
		(start 309.952644 -419.917626)
		(end 310.33466 -420.550594)
		(width 0.14732)
		(layer "In6.Cu")
		(net "P5E_CPU0_PE4_TX_C_DP<0>")
	)
	(segment
		(start 304.363628 -406.833324)
		(end 304.363628 -410.658564)
		(width 0.14732)
		(layer "In6.Cu")
		(net "P5E_CPU0_PE4_TX_C_DP<0>")
	)
	(segment
		(start 309.216806 -418.42817)
		(end 309.169308 -418.61994)
		(width 0.14732)
		(layer "In6.Cu")
		(net "P5E_CPU0_PE4_TX_C_DP<0>")
	)
	(segment
		(start 310.000142 -419.725856)
		(end 309.952644 -419.917626)
		(width 0.14732)
		(layer "In6.Cu")
		(net "P5E_CPU0_PE4_TX_C_DP<0>")
	)
	(segment
		(start 314.11418 -426.552614)
		(end 314.438538 -426.552614)
		(width 0.14732)
		(layer "In6.Cu")
		(net "P5E_CPU0_PE4_TX_C_DP<0>")
	)
	(segment
		(start 308.834536 -418.065204)
		(end 309.02656 -418.112448)
		(width 0.14732)
		(layer "In6.Cu")
		(net "P5E_CPU0_PE4_TX_C_DP<0>")
	)
	(segment
		(start 311.61482 -422.67124)
		(end 313.719464 -426.157898)
		(width 0.14732)
		(layer "In6.Cu")
		(net "P5E_CPU0_PE4_TX_C_DP<0>")
	)
	(segment
		(start 304.843688 -403.883876)
		(end 304.549048 -404.178516)
		(width 0.14732)
		(layer "In6.Cu")
		(net "P5E_CPU0_PE4_TX_C_DP<0>")
	)
	(segment
		(start 304.363628 -410.658564)
		(end 308.069742 -416.797998)
		(width 0.14732)
		(layer "In6.Cu")
		(net "P5E_CPU0_PE4_TX_C_DP<0>")
	)
	(segment
		(start 309.809642 -419.410388)
		(end 310.000142 -419.725856)
		(width 0.14732)
		(layer "In6.Cu")
		(net "P5E_CPU0_PE4_TX_C_DP<0>")
	)
	(segment
		(start 308.069742 -416.797998)
		(end 308.261766 -416.845496)
		(width 0.14732)
		(layer "In6.Cu")
		(net "P5E_CPU0_PE4_TX_C_DP<0>")
	)
	(segment
		(start 308.261766 -416.845496)
		(end 308.452012 -417.160964)
		(width 0.14732)
		(layer "In6.Cu")
		(net "P5E_CPU0_PE4_TX_C_DP<0>")
	)
	(segment
		(start 309.02656 -418.112448)
		(end 309.216806 -418.42817)
		(width 0.14732)
		(layer "In6.Cu")
		(net "P5E_CPU0_PE4_TX_C_DP<0>")
	)
	(segment
		(start 304.549048 -404.178516)
		(end 304.549048 -404.949914)
		(width 0.14732)
		(layer "In6.Cu")
		(net "P5E_CPU0_PE4_TX_C_DP<0>")
	)
	(segment
		(start 310.717184 -420.91356)
		(end 310.669686 -421.10533)
		(width 0.14732)
		(layer "In6.Cu")
		(net "P5E_CPU0_PE4_TX_C_DP<0>")
	)
	(segment
		(start 311.471818 -422.163748)
		(end 311.662318 -422.47947)
		(width 0.14732)
		(layer "In6.Cu")
		(net "P5E_CPU0_PE4_TX_C_DP<0>")
	)
	(segment
		(start 331.85227 -402.962872)
		(end 331.52715 -402.637752)
		(width 0.13208)
		(layer "F.Cu")
		(net "P5E_CPU0_PE4_TX_C_DN<9>")
	)
	(segment
		(start 331.85227 -403.580854)
		(end 331.85227 -402.962872)
		(width 0.13208)
		(layer "F.Cu")
		(net "P5E_CPU0_PE4_TX_C_DN<9>")
	)
	(segment
		(start 331.52715 -402.637752)
		(end 331.523848 -402.637752)
		(width 0.13208)
		(layer "F.Cu")
		(net "P5E_CPU0_PE4_TX_C_DN<9>")
	)
	(segment
		(start 331.549248 -403.883876)
		(end 331.85227 -403.580854)
		(width 0.13208)
		(layer "F.Cu")
		(net "P5E_CPU0_PE4_TX_C_DN<9>")
	)
	(segment
		(start 331.808836 -411.219396)
		(end 331.658468 -410.462984)
		(width 0.14732)
		(layer "In6.Cu")
		(net "P5E_CPU0_PE4_TX_C_DN<9>")
	)
	(segment
		(start 331.658468 -406.819608)
		(end 331.843888 -404.936198)
		(width 0.14732)
		(layer "In6.Cu")
		(net "P5E_CPU0_PE4_TX_C_DN<9>")
	)
	(segment
		(start 332.692502 -424.410886)
		(end 331.808836 -411.219396)
		(width 0.14732)
		(layer "In6.Cu")
		(net "P5E_CPU0_PE4_TX_C_DN<9>")
	)
	(segment
		(start 331.843888 -404.178516)
		(end 331.549248 -403.883876)
		(width 0.14732)
		(layer "In6.Cu")
		(net "P5E_CPU0_PE4_TX_C_DN<9>")
	)
	(segment
		(start 333.00035 -427.826932)
		(end 332.692502 -427.519084)
		(width 0.14732)
		(layer "In6.Cu")
		(net "P5E_CPU0_PE4_TX_C_DN<9>")
	)
	(segment
		(start 333.650082 -428.28972)
		(end 333.650082 -427.974506)
		(width 0.14732)
		(layer "In6.Cu")
		(net "P5E_CPU0_PE4_TX_C_DN<9>")
	)
	(segment
		(start 333.650082 -427.974506)
		(end 333.502508 -427.826932)
		(width 0.14732)
		(layer "In6.Cu")
		(net "P5E_CPU0_PE4_TX_C_DN<9>")
	)
	(segment
		(start 331.658468 -410.462984)
		(end 331.658468 -406.819608)
		(width 0.14732)
		(layer "In6.Cu")
		(net "P5E_CPU0_PE4_TX_C_DN<9>")
	)
	(segment
		(start 333.502508 -427.826932)
		(end 333.00035 -427.826932)
		(width 0.14732)
		(layer "In6.Cu")
		(net "P5E_CPU0_PE4_TX_C_DN<9>")
	)
	(segment
		(start 332.692502 -427.519084)
		(end 332.692502 -424.410886)
		(width 0.14732)
		(layer "In6.Cu")
		(net "P5E_CPU0_PE4_TX_C_DN<9>")
	)
	(segment
		(start 331.843888 -404.936198)
		(end 331.843888 -404.178516)
		(width 0.14732)
		(layer "In6.Cu")
		(net "P5E_CPU0_PE4_TX_C_DN<9>")
	)
	(segment
		(start 328.78903 -403.580854)
		(end 328.78903 -402.962872)
		(width 0.13208)
		(layer "F.Cu")
		(net "P5E_CPU0_PE4_TX_C_DN<8>")
	)
	(segment
		(start 328.46391 -402.637752)
		(end 328.460608 -402.637752)
		(width 0.13208)
		(layer "F.Cu")
		(net "P5E_CPU0_PE4_TX_C_DN<8>")
	)
	(segment
		(start 328.486008 -403.883876)
		(end 328.78903 -403.580854)
		(width 0.13208)
		(layer "F.Cu")
		(net "P5E_CPU0_PE4_TX_C_DN<8>")
	)
	(segment
		(start 328.78903 -402.962872)
		(end 328.46391 -402.637752)
		(width 0.13208)
		(layer "F.Cu")
		(net "P5E_CPU0_PE4_TX_C_DN<8>")
	)
	(segment
		(start 331.502512 -426.826934)
		(end 331.000354 -426.826934)
		(width 0.14732)
		(layer "In6.Cu")
		(net "P5E_CPU0_PE4_TX_C_DN<8>")
	)
	(segment
		(start 330.692506 -426.519086)
		(end 330.692506 -424.292268)
		(width 0.14732)
		(layer "In6.Cu")
		(net "P5E_CPU0_PE4_TX_C_DN<8>")
	)
	(segment
		(start 331.650086 -426.974508)
		(end 331.502512 -426.826934)
		(width 0.14732)
		(layer "In6.Cu")
		(net "P5E_CPU0_PE4_TX_C_DN<8>")
	)
	(segment
		(start 328.741786 -411.035754)
		(end 328.595228 -410.298392)
		(width 0.14732)
		(layer "In6.Cu")
		(net "P5E_CPU0_PE4_TX_C_DN<8>")
	)
	(segment
		(start 328.780648 -404.178516)
		(end 328.486008 -403.883876)
		(width 0.14732)
		(layer "In6.Cu")
		(net "P5E_CPU0_PE4_TX_C_DN<8>")
	)
	(segment
		(start 328.595228 -406.819608)
		(end 328.780648 -404.936198)
		(width 0.14732)
		(layer "In6.Cu")
		(net "P5E_CPU0_PE4_TX_C_DN<8>")
	)
	(segment
		(start 331.000354 -426.826934)
		(end 330.692506 -426.519086)
		(width 0.14732)
		(layer "In6.Cu")
		(net "P5E_CPU0_PE4_TX_C_DN<8>")
	)
	(segment
		(start 328.595228 -410.298392)
		(end 328.595228 -406.819608)
		(width 0.14732)
		(layer "In6.Cu")
		(net "P5E_CPU0_PE4_TX_C_DN<8>")
	)
	(segment
		(start 331.650086 -427.289976)
		(end 331.650086 -426.974508)
		(width 0.14732)
		(layer "In6.Cu")
		(net "P5E_CPU0_PE4_TX_C_DN<8>")
	)
	(segment
		(start 330.692506 -424.292268)
		(end 328.741786 -411.035754)
		(width 0.14732)
		(layer "In6.Cu")
		(net "P5E_CPU0_PE4_TX_C_DN<8>")
	)
	(segment
		(start 328.780648 -404.936198)
		(end 328.780648 -404.178516)
		(width 0.14732)
		(layer "In6.Cu")
		(net "P5E_CPU0_PE4_TX_C_DN<8>")
	)
	(segment
		(start 325.72579 -403.580854)
		(end 325.72579 -402.962872)
		(width 0.13208)
		(layer "F.Cu")
		(net "P5E_CPU0_PE4_TX_C_DN<7>")
	)
	(segment
		(start 325.72579 -402.962872)
		(end 325.40067 -402.637752)
		(width 0.13208)
		(layer "F.Cu")
		(net "P5E_CPU0_PE4_TX_C_DN<7>")
	)
	(segment
		(start 325.40067 -402.637752)
		(end 325.397368 -402.637752)
		(width 0.13208)
		(layer "F.Cu")
		(net "P5E_CPU0_PE4_TX_C_DN<7>")
	)
	(segment
		(start 325.422768 -403.883876)
		(end 325.72579 -403.580854)
		(width 0.13208)
		(layer "F.Cu")
		(net "P5E_CPU0_PE4_TX_C_DN<7>")
	)
	(segment
		(start 325.531988 -406.819608)
		(end 325.717408 -404.936198)
		(width 0.14732)
		(layer "In6.Cu")
		(net "P5E_CPU0_PE4_TX_C_DN<7>")
	)
	(segment
		(start 325.531988 -410.259276)
		(end 325.531988 -406.819608)
		(width 0.14732)
		(layer "In6.Cu")
		(net "P5E_CPU0_PE4_TX_C_DN<7>")
	)
	(segment
		(start 328.650092 -428.28972)
		(end 328.650092 -427.974506)
		(width 0.14732)
		(layer "In6.Cu")
		(net "P5E_CPU0_PE4_TX_C_DN<7>")
	)
	(segment
		(start 325.717408 -404.936198)
		(end 325.717408 -404.178516)
		(width 0.14732)
		(layer "In6.Cu")
		(net "P5E_CPU0_PE4_TX_C_DN<7>")
	)
	(segment
		(start 328.650092 -427.974506)
		(end 328.502518 -427.826932)
		(width 0.14732)
		(layer "In6.Cu")
		(net "P5E_CPU0_PE4_TX_C_DN<7>")
	)
	(segment
		(start 328.00036 -427.826932)
		(end 327.692512 -427.519084)
		(width 0.14732)
		(layer "In6.Cu")
		(net "P5E_CPU0_PE4_TX_C_DN<7>")
	)
	(segment
		(start 326.01789 -413.171894)
		(end 325.745602 -411.333696)
		(width 0.14732)
		(layer "In6.Cu")
		(net "P5E_CPU0_PE4_TX_C_DN<7>")
	)
	(segment
		(start 327.692512 -424.470068)
		(end 326.018398 -413.172402)
		(width 0.14732)
		(layer "In6.Cu")
		(net "P5E_CPU0_PE4_TX_C_DN<7>")
	)
	(segment
		(start 325.717408 -404.178516)
		(end 325.422768 -403.883876)
		(width 0.14732)
		(layer "In6.Cu")
		(net "P5E_CPU0_PE4_TX_C_DN<7>")
	)
	(segment
		(start 325.745602 -411.333696)
		(end 325.531988 -410.259276)
		(width 0.14732)
		(layer "In6.Cu")
		(net "P5E_CPU0_PE4_TX_C_DN<7>")
	)
	(segment
		(start 327.692512 -427.519084)
		(end 327.692512 -424.470068)
		(width 0.14732)
		(layer "In6.Cu")
		(net "P5E_CPU0_PE4_TX_C_DN<7>")
	)
	(segment
		(start 326.018398 -413.172402)
		(end 326.01789 -413.171894)
		(width 0.14732)
		(layer "In6.Cu")
		(net "P5E_CPU0_PE4_TX_C_DN<7>")
	)
	(segment
		(start 328.502518 -427.826932)
		(end 328.00036 -427.826932)
		(width 0.14732)
		(layer "In6.Cu")
		(net "P5E_CPU0_PE4_TX_C_DN<7>")
	)
	(segment
		(start 322.359528 -403.883876)
		(end 322.66255 -403.580854)
		(width 0.13208)
		(layer "F.Cu")
		(net "P5E_CPU0_PE4_TX_C_DN<6>")
	)
	(segment
		(start 322.33743 -402.637752)
		(end 322.334128 -402.637752)
		(width 0.13208)
		(layer "F.Cu")
		(net "P5E_CPU0_PE4_TX_C_DN<6>")
	)
	(segment
		(start 322.66255 -402.962872)
		(end 322.33743 -402.637752)
		(width 0.13208)
		(layer "F.Cu")
		(net "P5E_CPU0_PE4_TX_C_DN<6>")
	)
	(segment
		(start 322.66255 -403.580854)
		(end 322.66255 -402.962872)
		(width 0.13208)
		(layer "F.Cu")
		(net "P5E_CPU0_PE4_TX_C_DN<6>")
	)
	(segment
		(start 326.520556 -426.844968)
		(end 326.04329 -426.844968)
		(width 0.14732)
		(layer "In6.Cu")
		(net "P5E_CPU0_PE4_TX_C_DN<6>")
	)
	(segment
		(start 325.67372 -424.010074)
		(end 323.522594 -414.798002)
		(width 0.14732)
		(layer "In6.Cu")
		(net "P5E_CPU0_PE4_TX_C_DN<6>")
	)
	(segment
		(start 322.468748 -410.284422)
		(end 322.468748 -406.819608)
		(width 0.14732)
		(layer "In6.Cu")
		(net "P5E_CPU0_PE4_TX_C_DN<6>")
	)
	(segment
		(start 323.522594 -414.798002)
		(end 323.522086 -414.798002)
		(width 0.14732)
		(layer "In6.Cu")
		(net "P5E_CPU0_PE4_TX_C_DN<6>")
	)
	(segment
		(start 325.67372 -426.475398)
		(end 325.67372 -424.010074)
		(width 0.14732)
		(layer "In6.Cu")
		(net "P5E_CPU0_PE4_TX_C_DN<6>")
	)
	(segment
		(start 322.468748 -406.819608)
		(end 322.654168 -404.936198)
		(width 0.14732)
		(layer "In6.Cu")
		(net "P5E_CPU0_PE4_TX_C_DN<6>")
	)
	(segment
		(start 322.654168 -404.178516)
		(end 322.359528 -403.883876)
		(width 0.14732)
		(layer "In6.Cu")
		(net "P5E_CPU0_PE4_TX_C_DN<6>")
	)
	(segment
		(start 323.522086 -414.798002)
		(end 322.468748 -410.284422)
		(width 0.14732)
		(layer "In6.Cu")
		(net "P5E_CPU0_PE4_TX_C_DN<6>")
	)
	(segment
		(start 322.654168 -404.936198)
		(end 322.654168 -404.178516)
		(width 0.14732)
		(layer "In6.Cu")
		(net "P5E_CPU0_PE4_TX_C_DN<6>")
	)
	(segment
		(start 326.650096 -426.974508)
		(end 326.520556 -426.844968)
		(width 0.14732)
		(layer "In6.Cu")
		(net "P5E_CPU0_PE4_TX_C_DN<6>")
	)
	(segment
		(start 326.04329 -426.844968)
		(end 325.67372 -426.475398)
		(width 0.14732)
		(layer "In6.Cu")
		(net "P5E_CPU0_PE4_TX_C_DN<6>")
	)
	(segment
		(start 326.650096 -427.289976)
		(end 326.650096 -426.974508)
		(width 0.14732)
		(layer "In6.Cu")
		(net "P5E_CPU0_PE4_TX_C_DN<6>")
	)
	(segment
		(start 319.59931 -403.580854)
		(end 319.59931 -402.962872)
		(width 0.13208)
		(layer "F.Cu")
		(net "P5E_CPU0_PE4_TX_C_DN<5>")
	)
	(segment
		(start 319.27419 -402.637752)
		(end 319.270888 -402.637752)
		(width 0.13208)
		(layer "F.Cu")
		(net "P5E_CPU0_PE4_TX_C_DN<5>")
	)
	(segment
		(start 319.296288 -403.883876)
		(end 319.59931 -403.580854)
		(width 0.13208)
		(layer "F.Cu")
		(net "P5E_CPU0_PE4_TX_C_DN<5>")
	)
	(segment
		(start 319.59931 -402.962872)
		(end 319.27419 -402.637752)
		(width 0.13208)
		(layer "F.Cu")
		(net "P5E_CPU0_PE4_TX_C_DN<5>")
	)
	(segment
		(start 319.590928 -404.936198)
		(end 319.590928 -404.178516)
		(width 0.14732)
		(layer "In6.Cu")
		(net "P5E_CPU0_PE4_TX_C_DN<5>")
	)
	(segment
		(start 319.405508 -406.819608)
		(end 319.590928 -404.936198)
		(width 0.14732)
		(layer "In6.Cu")
		(net "P5E_CPU0_PE4_TX_C_DN<5>")
	)
	(segment
		(start 324.6501 -428.28972)
		(end 324.6501 -427.974506)
		(width 0.14732)
		(layer "In6.Cu")
		(net "P5E_CPU0_PE4_TX_C_DN<5>")
	)
	(segment
		(start 323.69252 -427.519084)
		(end 323.69252 -424.313604)
		(width 0.14732)
		(layer "In6.Cu")
		(net "P5E_CPU0_PE4_TX_C_DN<5>")
	)
	(segment
		(start 324.000368 -427.826932)
		(end 323.69252 -427.519084)
		(width 0.14732)
		(layer "In6.Cu")
		(net "P5E_CPU0_PE4_TX_C_DN<5>")
	)
	(segment
		(start 324.6501 -427.974506)
		(end 324.502526 -427.826932)
		(width 0.14732)
		(layer "In6.Cu")
		(net "P5E_CPU0_PE4_TX_C_DN<5>")
	)
	(segment
		(start 319.405508 -410.449014)
		(end 319.405508 -406.819608)
		(width 0.14732)
		(layer "In6.Cu")
		(net "P5E_CPU0_PE4_TX_C_DN<5>")
	)
	(segment
		(start 321.053206 -415.77768)
		(end 321.052698 -415.776156)
		(width 0.14732)
		(layer "In6.Cu")
		(net "P5E_CPU0_PE4_TX_C_DN<5>")
	)
	(segment
		(start 319.590928 -404.178516)
		(end 319.296288 -403.883876)
		(width 0.14732)
		(layer "In6.Cu")
		(net "P5E_CPU0_PE4_TX_C_DN<5>")
	)
	(segment
		(start 321.052698 -415.776156)
		(end 321.052698 -415.775902)
		(width 0.14732)
		(layer "In6.Cu")
		(net "P5E_CPU0_PE4_TX_C_DN<5>")
	)
	(segment
		(start 323.69252 -424.313604)
		(end 321.671188 -417.776406)
		(width 0.14732)
		(layer "In6.Cu")
		(net "P5E_CPU0_PE4_TX_C_DN<5>")
	)
	(segment
		(start 321.671188 -417.776406)
		(end 321.670934 -417.775644)
		(width 0.14732)
		(layer "In6.Cu")
		(net "P5E_CPU0_PE4_TX_C_DN<5>")
	)
	(segment
		(start 324.502526 -427.826932)
		(end 324.000368 -427.826932)
		(width 0.14732)
		(layer "In6.Cu")
		(net "P5E_CPU0_PE4_TX_C_DN<5>")
	)
	(segment
		(start 321.670934 -417.775644)
		(end 321.053206 -415.77768)
		(width 0.14732)
		(layer "In6.Cu")
		(net "P5E_CPU0_PE4_TX_C_DN<5>")
	)
	(segment
		(start 321.052698 -415.775902)
		(end 319.405508 -410.449014)
		(width 0.14732)
		(layer "In6.Cu")
		(net "P5E_CPU0_PE4_TX_C_DN<5>")
	)
	(segment
		(start 316.233048 -403.883876)
		(end 316.53607 -403.580854)
		(width 0.13208)
		(layer "F.Cu")
		(net "P5E_CPU0_PE4_TX_C_DN<4>")
	)
	(segment
		(start 316.53607 -402.962872)
		(end 316.21095 -402.637752)
		(width 0.13208)
		(layer "F.Cu")
		(net "P5E_CPU0_PE4_TX_C_DN<4>")
	)
	(segment
		(start 316.21095 -402.637752)
		(end 316.207648 -402.637752)
		(width 0.13208)
		(layer "F.Cu")
		(net "P5E_CPU0_PE4_TX_C_DN<4>")
	)
	(segment
		(start 316.53607 -403.580854)
		(end 316.53607 -402.962872)
		(width 0.13208)
		(layer "F.Cu")
		(net "P5E_CPU0_PE4_TX_C_DN<4>")
	)
	(segment
		(start 316.342268 -406.819608)
		(end 316.527688 -404.936198)
		(width 0.14732)
		(layer "In6.Cu")
		(net "P5E_CPU0_PE4_TX_C_DN<4>")
	)
	(segment
		(start 316.527688 -404.178516)
		(end 316.233048 -403.883876)
		(width 0.14732)
		(layer "In6.Cu")
		(net "P5E_CPU0_PE4_TX_C_DN<4>")
	)
	(segment
		(start 322.50253 -426.826934)
		(end 322.000372 -426.826934)
		(width 0.14732)
		(layer "In6.Cu")
		(net "P5E_CPU0_PE4_TX_C_DN<4>")
	)
	(segment
		(start 318.415416 -415.943034)
		(end 316.342268 -410.551376)
		(width 0.14732)
		(layer "In6.Cu")
		(net "P5E_CPU0_PE4_TX_C_DN<4>")
	)
	(segment
		(start 322.650104 -427.289976)
		(end 322.650104 -426.974508)
		(width 0.14732)
		(layer "In6.Cu")
		(net "P5E_CPU0_PE4_TX_C_DN<4>")
	)
	(segment
		(start 316.527688 -404.936198)
		(end 316.527688 -404.178516)
		(width 0.14732)
		(layer "In6.Cu")
		(net "P5E_CPU0_PE4_TX_C_DN<4>")
	)
	(segment
		(start 321.692524 -426.519086)
		(end 321.692524 -424.46575)
		(width 0.14732)
		(layer "In6.Cu")
		(net "P5E_CPU0_PE4_TX_C_DN<4>")
	)
	(segment
		(start 316.342268 -410.551376)
		(end 316.342268 -406.819608)
		(width 0.14732)
		(layer "In6.Cu")
		(net "P5E_CPU0_PE4_TX_C_DN<4>")
	)
	(segment
		(start 318.41567 -415.943796)
		(end 318.415416 -415.943034)
		(width 0.14732)
		(layer "In6.Cu")
		(net "P5E_CPU0_PE4_TX_C_DN<4>")
	)
	(segment
		(start 322.000372 -426.826934)
		(end 321.692524 -426.519086)
		(width 0.14732)
		(layer "In6.Cu")
		(net "P5E_CPU0_PE4_TX_C_DN<4>")
	)
	(segment
		(start 321.692524 -424.46575)
		(end 318.41567 -415.943796)
		(width 0.14732)
		(layer "In6.Cu")
		(net "P5E_CPU0_PE4_TX_C_DN<4>")
	)
	(segment
		(start 322.650104 -426.974508)
		(end 322.50253 -426.826934)
		(width 0.14732)
		(layer "In6.Cu")
		(net "P5E_CPU0_PE4_TX_C_DN<4>")
	)
	(segment
		(start 313.14771 -402.637752)
		(end 313.144408 -402.637752)
		(width 0.13208)
		(layer "F.Cu")
		(net "P5E_CPU0_PE4_TX_C_DN<3>")
	)
	(segment
		(start 313.169808 -403.883876)
		(end 313.47283 -403.580854)
		(width 0.13208)
		(layer "F.Cu")
		(net "P5E_CPU0_PE4_TX_C_DN<3>")
	)
	(segment
		(start 313.47283 -402.962872)
		(end 313.14771 -402.637752)
		(width 0.13208)
		(layer "F.Cu")
		(net "P5E_CPU0_PE4_TX_C_DN<3>")
	)
	(segment
		(start 313.47283 -403.580854)
		(end 313.47283 -402.962872)
		(width 0.13208)
		(layer "F.Cu")
		(net "P5E_CPU0_PE4_TX_C_DN<3>")
	)
	(segment
		(start 320.502534 -427.826932)
		(end 320.000376 -427.826932)
		(width 0.14732)
		(layer "In6.Cu")
		(net "P5E_CPU0_PE4_TX_C_DN<3>")
	)
	(segment
		(start 313.464448 -404.936198)
		(end 313.464448 -404.178516)
		(width 0.14732)
		(layer "In6.Cu")
		(net "P5E_CPU0_PE4_TX_C_DN<3>")
	)
	(segment
		(start 320.650108 -427.974506)
		(end 320.502534 -427.826932)
		(width 0.14732)
		(layer "In6.Cu")
		(net "P5E_CPU0_PE4_TX_C_DN<3>")
	)
	(segment
		(start 319.692528 -424.396408)
		(end 313.279028 -410.631386)
		(width 0.14732)
		(layer "In6.Cu")
		(net "P5E_CPU0_PE4_TX_C_DN<3>")
	)
	(segment
		(start 319.692528 -427.519084)
		(end 319.692528 -424.396408)
		(width 0.14732)
		(layer "In6.Cu")
		(net "P5E_CPU0_PE4_TX_C_DN<3>")
	)
	(segment
		(start 313.279028 -410.631386)
		(end 313.279028 -406.819608)
		(width 0.14732)
		(layer "In6.Cu")
		(net "P5E_CPU0_PE4_TX_C_DN<3>")
	)
	(segment
		(start 313.464448 -404.178516)
		(end 313.169808 -403.883876)
		(width 0.14732)
		(layer "In6.Cu")
		(net "P5E_CPU0_PE4_TX_C_DN<3>")
	)
	(segment
		(start 313.279028 -406.819608)
		(end 313.464448 -404.936198)
		(width 0.14732)
		(layer "In6.Cu")
		(net "P5E_CPU0_PE4_TX_C_DN<3>")
	)
	(segment
		(start 320.000376 -427.826932)
		(end 319.692528 -427.519084)
		(width 0.14732)
		(layer "In6.Cu")
		(net "P5E_CPU0_PE4_TX_C_DN<3>")
	)
	(segment
		(start 320.650108 -428.28972)
		(end 320.650108 -427.974506)
		(width 0.14732)
		(layer "In6.Cu")
		(net "P5E_CPU0_PE4_TX_C_DN<3>")
	)
	(segment
		(start 310.106568 -403.883876)
		(end 310.40959 -403.580854)
		(width 0.13208)
		(layer "F.Cu")
		(net "P5E_CPU0_PE4_TX_C_DN<2>")
	)
	(segment
		(start 310.40959 -402.962872)
		(end 310.08447 -402.637752)
		(width 0.13208)
		(layer "F.Cu")
		(net "P5E_CPU0_PE4_TX_C_DN<2>")
	)
	(segment
		(start 310.40959 -403.580854)
		(end 310.40959 -402.962872)
		(width 0.13208)
		(layer "F.Cu")
		(net "P5E_CPU0_PE4_TX_C_DN<2>")
	)
	(segment
		(start 310.08447 -402.637752)
		(end 310.081168 -402.637752)
		(width 0.13208)
		(layer "F.Cu")
		(net "P5E_CPU0_PE4_TX_C_DN<2>")
	)
	(segment
		(start 310.215788 -410.681932)
		(end 310.215788 -406.819608)
		(width 0.14732)
		(layer "In6.Cu")
		(net "P5E_CPU0_PE4_TX_C_DN<2>")
	)
	(segment
		(start 310.215788 -406.819608)
		(end 310.401208 -404.936198)
		(width 0.14732)
		(layer "In6.Cu")
		(net "P5E_CPU0_PE4_TX_C_DN<2>")
	)
	(segment
		(start 318.502538 -426.826934)
		(end 318.00038 -426.826934)
		(width 0.14732)
		(layer "In6.Cu")
		(net "P5E_CPU0_PE4_TX_C_DN<2>")
	)
	(segment
		(start 310.401208 -404.936198)
		(end 310.401208 -404.178516)
		(width 0.14732)
		(layer "In6.Cu")
		(net "P5E_CPU0_PE4_TX_C_DN<2>")
	)
	(segment
		(start 318.650112 -427.289976)
		(end 318.650112 -426.974508)
		(width 0.14732)
		(layer "In6.Cu")
		(net "P5E_CPU0_PE4_TX_C_DN<2>")
	)
	(segment
		(start 310.401208 -404.178516)
		(end 310.106568 -403.883876)
		(width 0.14732)
		(layer "In6.Cu")
		(net "P5E_CPU0_PE4_TX_C_DN<2>")
	)
	(segment
		(start 317.692532 -424.514264)
		(end 310.215788 -410.681932)
		(width 0.14732)
		(layer "In6.Cu")
		(net "P5E_CPU0_PE4_TX_C_DN<2>")
	)
	(segment
		(start 317.692532 -426.519086)
		(end 317.692532 -424.514264)
		(width 0.14732)
		(layer "In6.Cu")
		(net "P5E_CPU0_PE4_TX_C_DN<2>")
	)
	(segment
		(start 318.00038 -426.826934)
		(end 317.692532 -426.519086)
		(width 0.14732)
		(layer "In6.Cu")
		(net "P5E_CPU0_PE4_TX_C_DN<2>")
	)
	(segment
		(start 318.650112 -426.974508)
		(end 318.502538 -426.826934)
		(width 0.14732)
		(layer "In6.Cu")
		(net "P5E_CPU0_PE4_TX_C_DN<2>")
	)
	(segment
		(start 307.906928 -403.883876)
		(end 307.60543 -403.582378)
		(width 0.13208)
		(layer "F.Cu")
		(net "P5E_CPU0_PE4_TX_C_DN<1>")
	)
	(segment
		(start 307.60543 -403.582378)
		(end 307.60543 -402.96465)
		(width 0.13208)
		(layer "F.Cu")
		(net "P5E_CPU0_PE4_TX_C_DN<1>")
	)
	(segment
		(start 307.60543 -402.96465)
		(end 307.932328 -402.637752)
		(width 0.13208)
		(layer "F.Cu")
		(net "P5E_CPU0_PE4_TX_C_DN<1>")
	)
	(segment
		(start 315.966856 -427.405292)
		(end 316.114176 -427.552612)
		(width 0.14732)
		(layer "In6.Cu")
		(net "P5E_CPU0_PE4_TX_C_DN<1>")
	)
	(segment
		(start 307.906928 -403.883876)
		(end 307.612288 -404.178516)
		(width 0.14732)
		(layer "In6.Cu")
		(net "P5E_CPU0_PE4_TX_C_DN<1>")
	)
	(segment
		(start 311.396888 -417.223702)
		(end 311.698894 -417.725098)
		(width 0.14732)
		(layer "In6.Cu")
		(net "P5E_CPU0_PE4_TX_C_DN<1>")
	)
	(segment
		(start 312.415428 -418.643054)
		(end 312.60542 -418.958776)
		(width 0.14732)
		(layer "In6.Cu")
		(net "P5E_CPU0_PE4_TX_C_DN<1>")
	)
	(segment
		(start 307.612288 -404.949914)
		(end 307.426868 -406.833324)
		(width 0.14732)
		(layer "In6.Cu")
		(net "P5E_CPU0_PE4_TX_C_DN<1>")
	)
	(segment
		(start 315.966856 -424.810428)
		(end 315.966856 -427.405292)
		(width 0.14732)
		(layer "In6.Cu")
		(net "P5E_CPU0_PE4_TX_C_DN<1>")
	)
	(segment
		(start 312.60542 -418.958776)
		(end 312.557668 -419.150546)
		(width 0.14732)
		(layer "In6.Cu")
		(net "P5E_CPU0_PE4_TX_C_DN<1>")
	)
	(segment
		(start 311.698894 -417.725098)
		(end 311.890918 -417.772596)
		(width 0.14732)
		(layer "In6.Cu")
		(net "P5E_CPU0_PE4_TX_C_DN<1>")
	)
	(segment
		(start 316.438534 -427.552612)
		(end 316.650116 -427.34103)
		(width 0.14732)
		(layer "In6.Cu")
		(net "P5E_CPU0_PE4_TX_C_DN<1>")
	)
	(segment
		(start 312.223404 -418.595556)
		(end 312.415428 -418.643054)
		(width 0.14732)
		(layer "In6.Cu")
		(net "P5E_CPU0_PE4_TX_C_DN<1>")
	)
	(segment
		(start 310.730138 -415.845752)
		(end 310.92013 -416.161474)
		(width 0.14732)
		(layer "In6.Cu")
		(net "P5E_CPU0_PE4_TX_C_DN<1>")
	)
	(segment
		(start 310.872632 -416.353244)
		(end 311.062624 -416.668712)
		(width 0.14732)
		(layer "In6.Cu")
		(net "P5E_CPU0_PE4_TX_C_DN<1>")
	)
	(segment
		(start 311.44464 -417.031932)
		(end 311.396888 -417.223702)
		(width 0.14732)
		(layer "In6.Cu")
		(net "P5E_CPU0_PE4_TX_C_DN<1>")
	)
	(segment
		(start 312.557668 -419.150546)
		(end 315.966856 -424.810428)
		(width 0.14732)
		(layer "In6.Cu")
		(net "P5E_CPU0_PE4_TX_C_DN<1>")
	)
	(segment
		(start 312.08091 -418.088318)
		(end 312.033412 -418.280088)
		(width 0.14732)
		(layer "In6.Cu")
		(net "P5E_CPU0_PE4_TX_C_DN<1>")
	)
	(segment
		(start 307.612288 -404.178516)
		(end 307.612288 -404.949914)
		(width 0.14732)
		(layer "In6.Cu")
		(net "P5E_CPU0_PE4_TX_C_DN<1>")
	)
	(segment
		(start 311.062624 -416.668712)
		(end 311.254648 -416.71621)
		(width 0.14732)
		(layer "In6.Cu")
		(net "P5E_CPU0_PE4_TX_C_DN<1>")
	)
	(segment
		(start 316.114176 -427.552612)
		(end 316.438534 -427.552612)
		(width 0.14732)
		(layer "In6.Cu")
		(net "P5E_CPU0_PE4_TX_C_DN<1>")
	)
	(segment
		(start 307.426868 -406.833324)
		(end 307.426868 -410.633164)
		(width 0.14732)
		(layer "In6.Cu")
		(net "P5E_CPU0_PE4_TX_C_DN<1>")
	)
	(segment
		(start 307.426868 -410.633164)
		(end 310.538114 -415.798)
		(width 0.14732)
		(layer "In6.Cu")
		(net "P5E_CPU0_PE4_TX_C_DN<1>")
	)
	(segment
		(start 311.254648 -416.71621)
		(end 311.44464 -417.031932)
		(width 0.14732)
		(layer "In6.Cu")
		(net "P5E_CPU0_PE4_TX_C_DN<1>")
	)
	(segment
		(start 310.92013 -416.161474)
		(end 310.872632 -416.353244)
		(width 0.14732)
		(layer "In6.Cu")
		(net "P5E_CPU0_PE4_TX_C_DN<1>")
	)
	(segment
		(start 311.890918 -417.772596)
		(end 312.08091 -418.088318)
		(width 0.14732)
		(layer "In6.Cu")
		(net "P5E_CPU0_PE4_TX_C_DN<1>")
	)
	(segment
		(start 310.538114 -415.798)
		(end 310.730138 -415.845752)
		(width 0.14732)
		(layer "In6.Cu")
		(net "P5E_CPU0_PE4_TX_C_DN<1>")
	)
	(segment
		(start 312.033412 -418.280088)
		(end 312.223404 -418.595556)
		(width 0.14732)
		(layer "In6.Cu")
		(net "P5E_CPU0_PE4_TX_C_DN<1>")
	)
	(segment
		(start 316.650116 -427.34103)
		(end 316.650116 -427.089824)
		(width 0.14732)
		(layer "In6.Cu")
		(net "P5E_CPU0_PE4_TX_C_DN<1>")
	)
	(segment
		(start 350.23171 -402.962872)
		(end 349.90659 -402.637752)
		(width 0.13208)
		(layer "F.Cu")
		(net "P5E_CPU0_PE4_TX_C_DN<15>")
	)
	(segment
		(start 349.928688 -403.883876)
		(end 350.23171 -403.580854)
		(width 0.13208)
		(layer "F.Cu")
		(net "P5E_CPU0_PE4_TX_C_DN<15>")
	)
	(segment
		(start 350.23171 -403.580854)
		(end 350.23171 -402.962872)
		(width 0.13208)
		(layer "F.Cu")
		(net "P5E_CPU0_PE4_TX_C_DN<15>")
	)
	(segment
		(start 349.90659 -402.637752)
		(end 349.903288 -402.637752)
		(width 0.13208)
		(layer "F.Cu")
		(net "P5E_CPU0_PE4_TX_C_DN<15>")
	)
	(segment
		(start 344.692478 -427.519084)
		(end 344.692478 -424.128184)
		(width 0.14732)
		(layer "In6.Cu")
		(net "P5E_CPU0_PE4_TX_C_DN<15>")
	)
	(segment
		(start 345.650058 -428.28972)
		(end 345.650058 -427.974506)
		(width 0.14732)
		(layer "In6.Cu")
		(net "P5E_CPU0_PE4_TX_C_DN<15>")
	)
	(segment
		(start 344.692478 -424.128184)
		(end 350.037908 -411.090364)
		(width 0.14732)
		(layer "In6.Cu")
		(net "P5E_CPU0_PE4_TX_C_DN<15>")
	)
	(segment
		(start 350.223328 -404.178516)
		(end 349.928688 -403.883876)
		(width 0.14732)
		(layer "In6.Cu")
		(net "P5E_CPU0_PE4_TX_C_DN<15>")
	)
	(segment
		(start 350.223328 -404.936198)
		(end 350.223328 -404.178516)
		(width 0.14732)
		(layer "In6.Cu")
		(net "P5E_CPU0_PE4_TX_C_DN<15>")
	)
	(segment
		(start 350.037908 -411.090364)
		(end 350.037908 -406.819608)
		(width 0.14732)
		(layer "In6.Cu")
		(net "P5E_CPU0_PE4_TX_C_DN<15>")
	)
	(segment
		(start 345.000326 -427.826932)
		(end 344.692478 -427.519084)
		(width 0.14732)
		(layer "In6.Cu")
		(net "P5E_CPU0_PE4_TX_C_DN<15>")
	)
	(segment
		(start 345.502484 -427.826932)
		(end 345.000326 -427.826932)
		(width 0.14732)
		(layer "In6.Cu")
		(net "P5E_CPU0_PE4_TX_C_DN<15>")
	)
	(segment
		(start 345.650058 -427.974506)
		(end 345.502484 -427.826932)
		(width 0.14732)
		(layer "In6.Cu")
		(net "P5E_CPU0_PE4_TX_C_DN<15>")
	)
	(segment
		(start 350.037908 -406.819608)
		(end 350.223328 -404.936198)
		(width 0.14732)
		(layer "In6.Cu")
		(net "P5E_CPU0_PE4_TX_C_DN<15>")
	)
	(segment
		(start 347.16847 -403.580854)
		(end 347.16847 -402.962872)
		(width 0.13208)
		(layer "F.Cu")
		(net "P5E_CPU0_PE4_TX_C_DN<14>")
	)
	(segment
		(start 346.84335 -402.637752)
		(end 346.840048 -402.637752)
		(width 0.13208)
		(layer "F.Cu")
		(net "P5E_CPU0_PE4_TX_C_DN<14>")
	)
	(segment
		(start 347.16847 -402.962872)
		(end 346.84335 -402.637752)
		(width 0.13208)
		(layer "F.Cu")
		(net "P5E_CPU0_PE4_TX_C_DN<14>")
	)
	(segment
		(start 346.865448 -403.883876)
		(end 347.16847 -403.580854)
		(width 0.13208)
		(layer "F.Cu")
		(net "P5E_CPU0_PE4_TX_C_DN<14>")
	)
	(segment
		(start 346.974668 -410.821378)
		(end 346.974668 -406.819608)
		(width 0.14732)
		(layer "In6.Cu")
		(net "P5E_CPU0_PE4_TX_C_DN<14>")
	)
	(segment
		(start 342.692482 -426.464984)
		(end 342.692482 -423.894758)
		(width 0.14732)
		(layer "In6.Cu")
		(net "P5E_CPU0_PE4_TX_C_DN<14>")
	)
	(segment
		(start 346.974668 -406.819608)
		(end 347.160088 -404.936198)
		(width 0.14732)
		(layer "In6.Cu")
		(net "P5E_CPU0_PE4_TX_C_DN<14>")
	)
	(segment
		(start 343.650062 -427.289976)
		(end 343.650062 -426.974508)
		(width 0.14732)
		(layer "In6.Cu")
		(net "P5E_CPU0_PE4_TX_C_DN<14>")
	)
	(segment
		(start 343.650062 -426.974508)
		(end 343.474802 -426.799248)
		(width 0.14732)
		(layer "In6.Cu")
		(net "P5E_CPU0_PE4_TX_C_DN<14>")
	)
	(segment
		(start 347.160088 -404.936198)
		(end 347.160088 -404.178516)
		(width 0.14732)
		(layer "In6.Cu")
		(net "P5E_CPU0_PE4_TX_C_DN<14>")
	)
	(segment
		(start 343.474802 -426.799248)
		(end 343.026746 -426.799248)
		(width 0.14732)
		(layer "In6.Cu")
		(net "P5E_CPU0_PE4_TX_C_DN<14>")
	)
	(segment
		(start 342.692482 -423.894758)
		(end 346.974668 -410.821378)
		(width 0.14732)
		(layer "In6.Cu")
		(net "P5E_CPU0_PE4_TX_C_DN<14>")
	)
	(segment
		(start 347.160088 -404.178516)
		(end 346.865448 -403.883876)
		(width 0.14732)
		(layer "In6.Cu")
		(net "P5E_CPU0_PE4_TX_C_DN<14>")
	)
	(segment
		(start 343.026746 -426.799248)
		(end 342.692482 -426.464984)
		(width 0.14732)
		(layer "In6.Cu")
		(net "P5E_CPU0_PE4_TX_C_DN<14>")
	)
	(segment
		(start 344.10523 -402.962872)
		(end 343.78011 -402.637752)
		(width 0.13208)
		(layer "F.Cu")
		(net "P5E_CPU0_PE4_TX_C_DN<13>")
	)
	(segment
		(start 343.78011 -402.637752)
		(end 343.776808 -402.637752)
		(width 0.13208)
		(layer "F.Cu")
		(net "P5E_CPU0_PE4_TX_C_DN<13>")
	)
	(segment
		(start 344.10523 -403.580854)
		(end 344.10523 -402.962872)
		(width 0.13208)
		(layer "F.Cu")
		(net "P5E_CPU0_PE4_TX_C_DN<13>")
	)
	(segment
		(start 343.802208 -403.883876)
		(end 344.10523 -403.580854)
		(width 0.13208)
		(layer "F.Cu")
		(net "P5E_CPU0_PE4_TX_C_DN<13>")
	)
	(segment
		(start 344.096848 -404.936198)
		(end 344.096848 -404.178516)
		(width 0.14732)
		(layer "In6.Cu")
		(net "P5E_CPU0_PE4_TX_C_DN<13>")
	)
	(segment
		(start 340.692486 -427.519084)
		(end 340.692486 -424.315128)
		(width 0.14732)
		(layer "In6.Cu")
		(net "P5E_CPU0_PE4_TX_C_DN<13>")
	)
	(segment
		(start 341.000334 -427.826932)
		(end 340.692486 -427.519084)
		(width 0.14732)
		(layer "In6.Cu")
		(net "P5E_CPU0_PE4_TX_C_DN<13>")
	)
	(segment
		(start 343.911428 -406.819608)
		(end 344.096848 -404.936198)
		(width 0.14732)
		(layer "In6.Cu")
		(net "P5E_CPU0_PE4_TX_C_DN<13>")
	)
	(segment
		(start 341.650066 -428.28972)
		(end 341.650066 -427.974506)
		(width 0.14732)
		(layer "In6.Cu")
		(net "P5E_CPU0_PE4_TX_C_DN<13>")
	)
	(segment
		(start 343.911428 -411.412436)
		(end 343.911428 -406.819608)
		(width 0.14732)
		(layer "In6.Cu")
		(net "P5E_CPU0_PE4_TX_C_DN<13>")
	)
	(segment
		(start 341.650066 -427.974506)
		(end 341.502492 -427.826932)
		(width 0.14732)
		(layer "In6.Cu")
		(net "P5E_CPU0_PE4_TX_C_DN<13>")
	)
	(segment
		(start 340.692486 -424.315128)
		(end 343.911428 -411.412436)
		(width 0.14732)
		(layer "In6.Cu")
		(net "P5E_CPU0_PE4_TX_C_DN<13>")
	)
	(segment
		(start 341.502492 -427.826932)
		(end 341.000334 -427.826932)
		(width 0.14732)
		(layer "In6.Cu")
		(net "P5E_CPU0_PE4_TX_C_DN<13>")
	)
	(segment
		(start 344.096848 -404.178516)
		(end 343.802208 -403.883876)
		(width 0.14732)
		(layer "In6.Cu")
		(net "P5E_CPU0_PE4_TX_C_DN<13>")
	)
	(segment
		(start 340.71687 -402.637752)
		(end 340.713568 -402.637752)
		(width 0.13208)
		(layer "F.Cu")
		(net "P5E_CPU0_PE4_TX_C_DN<12>")
	)
	(segment
		(start 341.04199 -403.580854)
		(end 341.04199 -402.962872)
		(width 0.13208)
		(layer "F.Cu")
		(net "P5E_CPU0_PE4_TX_C_DN<12>")
	)
	(segment
		(start 341.04199 -402.962872)
		(end 340.71687 -402.637752)
		(width 0.13208)
		(layer "F.Cu")
		(net "P5E_CPU0_PE4_TX_C_DN<12>")
	)
	(segment
		(start 340.738968 -403.883876)
		(end 341.04199 -403.580854)
		(width 0.13208)
		(layer "F.Cu")
		(net "P5E_CPU0_PE4_TX_C_DN<12>")
	)
	(segment
		(start 341.033608 -404.936198)
		(end 341.033608 -404.178516)
		(width 0.14732)
		(layer "In6.Cu")
		(net "P5E_CPU0_PE4_TX_C_DN<12>")
	)
	(segment
		(start 338.69249 -426.519086)
		(end 338.69249 -424.401488)
		(width 0.14732)
		(layer "In6.Cu")
		(net "P5E_CPU0_PE4_TX_C_DN<12>")
	)
	(segment
		(start 341.033608 -404.178516)
		(end 340.738968 -403.883876)
		(width 0.14732)
		(layer "In6.Cu")
		(net "P5E_CPU0_PE4_TX_C_DN<12>")
	)
	(segment
		(start 339.65007 -426.974508)
		(end 339.502496 -426.826934)
		(width 0.14732)
		(layer "In6.Cu")
		(net "P5E_CPU0_PE4_TX_C_DN<12>")
	)
	(segment
		(start 339.65007 -427.289976)
		(end 339.65007 -426.974508)
		(width 0.14732)
		(layer "In6.Cu")
		(net "P5E_CPU0_PE4_TX_C_DN<12>")
	)
	(segment
		(start 338.69249 -424.401488)
		(end 340.848188 -411.656276)
		(width 0.14732)
		(layer "In6.Cu")
		(net "P5E_CPU0_PE4_TX_C_DN<12>")
	)
	(segment
		(start 340.848188 -411.656276)
		(end 340.848188 -406.819608)
		(width 0.14732)
		(layer "In6.Cu")
		(net "P5E_CPU0_PE4_TX_C_DN<12>")
	)
	(segment
		(start 340.848188 -406.819608)
		(end 341.033608 -404.936198)
		(width 0.14732)
		(layer "In6.Cu")
		(net "P5E_CPU0_PE4_TX_C_DN<12>")
	)
	(segment
		(start 339.000338 -426.826934)
		(end 338.69249 -426.519086)
		(width 0.14732)
		(layer "In6.Cu")
		(net "P5E_CPU0_PE4_TX_C_DN<12>")
	)
	(segment
		(start 339.502496 -426.826934)
		(end 339.000338 -426.826934)
		(width 0.14732)
		(layer "In6.Cu")
		(net "P5E_CPU0_PE4_TX_C_DN<12>")
	)
	(segment
		(start 338.539328 -403.883876)
		(end 338.23783 -403.582378)
		(width 0.13208)
		(layer "F.Cu")
		(net "P5E_CPU0_PE4_TX_C_DN<11>")
	)
	(segment
		(start 338.23783 -402.96465)
		(end 338.564728 -402.637752)
		(width 0.13208)
		(layer "F.Cu")
		(net "P5E_CPU0_PE4_TX_C_DN<11>")
	)
	(segment
		(start 338.23783 -403.582378)
		(end 338.23783 -402.96465)
		(width 0.13208)
		(layer "F.Cu")
		(net "P5E_CPU0_PE4_TX_C_DN<11>")
	)
	(segment
		(start 337.689444 -416.39998)
		(end 337.63712 -416.978592)
		(width 0.14732)
		(layer "In6.Cu")
		(net "P5E_CPU0_PE4_TX_C_DN<11>")
	)
	(segment
		(start 337.578446 -417.623752)
		(end 337.579208 -417.623752)
		(width 0.14732)
		(layer "In6.Cu")
		(net "P5E_CPU0_PE4_TX_C_DN<11>")
	)
	(segment
		(start 337.650074 -427.34103)
		(end 337.650074 -427.089824)
		(width 0.14732)
		(layer "In6.Cu")
		(net "P5E_CPU0_PE4_TX_C_DN<11>")
	)
	(segment
		(start 336.966814 -427.405292)
		(end 337.114134 -427.552612)
		(width 0.14732)
		(layer "In6.Cu")
		(net "P5E_CPU0_PE4_TX_C_DN<11>")
	)
	(segment
		(start 337.874864 -415.906458)
		(end 337.84159 -416.273488)
		(width 0.14732)
		(layer "In6.Cu")
		(net "P5E_CPU0_PE4_TX_C_DN<11>")
	)
	(segment
		(start 337.781392 -415.388044)
		(end 337.748372 -415.75482)
		(width 0.14732)
		(layer "In6.Cu")
		(net "P5E_CPU0_PE4_TX_C_DN<11>")
	)
	(segment
		(start 338.005674 -412.92272)
		(end 338.132166 -413.074358)
		(width 0.14732)
		(layer "In6.Cu")
		(net "P5E_CPU0_PE4_TX_C_DN<11>")
	)
	(segment
		(start 337.933538 -415.261552)
		(end 337.781392 -415.388044)
		(width 0.14732)
		(layer "In6.Cu")
		(net "P5E_CPU0_PE4_TX_C_DN<11>")
	)
	(segment
		(start 338.244688 -404.178516)
		(end 338.244688 -404.949914)
		(width 0.14732)
		(layer "In6.Cu")
		(net "P5E_CPU0_PE4_TX_C_DN<11>")
	)
	(segment
		(start 337.84032 -414.742884)
		(end 337.966812 -414.894522)
		(width 0.14732)
		(layer "In6.Cu")
		(net "P5E_CPU0_PE4_TX_C_DN<11>")
	)
	(segment
		(start 337.579208 -417.623752)
		(end 336.966814 -424.370754)
		(width 0.14732)
		(layer "In6.Cu")
		(net "P5E_CPU0_PE4_TX_C_DN<11>")
	)
	(segment
		(start 337.748372 -415.75482)
		(end 337.874864 -415.906458)
		(width 0.14732)
		(layer "In6.Cu")
		(net "P5E_CPU0_PE4_TX_C_DN<11>")
	)
	(segment
		(start 338.539328 -403.883876)
		(end 338.244688 -404.178516)
		(width 0.14732)
		(layer "In6.Cu")
		(net "P5E_CPU0_PE4_TX_C_DN<11>")
	)
	(segment
		(start 337.763612 -417.13023)
		(end 337.730338 -417.49726)
		(width 0.14732)
		(layer "In6.Cu")
		(net "P5E_CPU0_PE4_TX_C_DN<11>")
	)
	(segment
		(start 337.114134 -427.552612)
		(end 337.438492 -427.552612)
		(width 0.14732)
		(layer "In6.Cu")
		(net "P5E_CPU0_PE4_TX_C_DN<11>")
	)
	(segment
		(start 337.966812 -414.894522)
		(end 337.933538 -415.261552)
		(width 0.14732)
		(layer "In6.Cu")
		(net "P5E_CPU0_PE4_TX_C_DN<11>")
	)
	(segment
		(start 337.63712 -416.978592)
		(end 337.763612 -417.13023)
		(width 0.14732)
		(layer "In6.Cu")
		(net "P5E_CPU0_PE4_TX_C_DN<11>")
	)
	(segment
		(start 338.098892 -413.441388)
		(end 337.946746 -413.56788)
		(width 0.14732)
		(layer "In6.Cu")
		(net "P5E_CPU0_PE4_TX_C_DN<11>")
	)
	(segment
		(start 337.730338 -417.49726)
		(end 337.578446 -417.623752)
		(width 0.14732)
		(layer "In6.Cu")
		(net "P5E_CPU0_PE4_TX_C_DN<11>")
	)
	(segment
		(start 338.059268 -412.32963)
		(end 338.005674 -412.92272)
		(width 0.14732)
		(layer "In6.Cu")
		(net "P5E_CPU0_PE4_TX_C_DN<11>")
	)
	(segment
		(start 338.132166 -413.074358)
		(end 338.098892 -413.441388)
		(width 0.14732)
		(layer "In6.Cu")
		(net "P5E_CPU0_PE4_TX_C_DN<11>")
	)
	(segment
		(start 337.946746 -413.56788)
		(end 337.84032 -414.742884)
		(width 0.14732)
		(layer "In6.Cu")
		(net "P5E_CPU0_PE4_TX_C_DN<11>")
	)
	(segment
		(start 336.966814 -424.370754)
		(end 336.966814 -427.405292)
		(width 0.14732)
		(layer "In6.Cu")
		(net "P5E_CPU0_PE4_TX_C_DN<11>")
	)
	(segment
		(start 337.438492 -427.552612)
		(end 337.650074 -427.34103)
		(width 0.14732)
		(layer "In6.Cu")
		(net "P5E_CPU0_PE4_TX_C_DN<11>")
	)
	(segment
		(start 338.244688 -404.949914)
		(end 338.059268 -406.833324)
		(width 0.14732)
		(layer "In6.Cu")
		(net "P5E_CPU0_PE4_TX_C_DN<11>")
	)
	(segment
		(start 337.84159 -416.273488)
		(end 337.689444 -416.39998)
		(width 0.14732)
		(layer "In6.Cu")
		(net "P5E_CPU0_PE4_TX_C_DN<11>")
	)
	(segment
		(start 338.059268 -406.833324)
		(end 338.059268 -412.32963)
		(width 0.14732)
		(layer "In6.Cu")
		(net "P5E_CPU0_PE4_TX_C_DN<11>")
	)
	(segment
		(start 334.59039 -402.637752)
		(end 334.587088 -402.637752)
		(width 0.13208)
		(layer "F.Cu")
		(net "P5E_CPU0_PE4_TX_C_DN<10>")
	)
	(segment
		(start 334.612488 -403.883876)
		(end 334.91551 -403.580854)
		(width 0.13208)
		(layer "F.Cu")
		(net "P5E_CPU0_PE4_TX_C_DN<10>")
	)
	(segment
		(start 334.91551 -402.962872)
		(end 334.59039 -402.637752)
		(width 0.13208)
		(layer "F.Cu")
		(net "P5E_CPU0_PE4_TX_C_DN<10>")
	)
	(segment
		(start 334.91551 -403.580854)
		(end 334.91551 -402.962872)
		(width 0.13208)
		(layer "F.Cu")
		(net "P5E_CPU0_PE4_TX_C_DN<10>")
	)
	(segment
		(start 334.907128 -404.936198)
		(end 334.907128 -404.178516)
		(width 0.14732)
		(layer "In6.Cu")
		(net "P5E_CPU0_PE4_TX_C_DN<10>")
	)
	(segment
		(start 334.721708 -406.819608)
		(end 334.907128 -404.936198)
		(width 0.14732)
		(layer "In6.Cu")
		(net "P5E_CPU0_PE4_TX_C_DN<10>")
	)
	(segment
		(start 335.000346 -426.826934)
		(end 334.681576 -426.508164)
		(width 0.14732)
		(layer "In6.Cu")
		(net "P5E_CPU0_PE4_TX_C_DN<10>")
	)
	(segment
		(start 334.907128 -404.178516)
		(end 334.612488 -403.883876)
		(width 0.14732)
		(layer "In6.Cu")
		(net "P5E_CPU0_PE4_TX_C_DN<10>")
	)
	(segment
		(start 334.681576 -425.471844)
		(end 334.838548 -411.936946)
		(width 0.14732)
		(layer "In6.Cu")
		(net "P5E_CPU0_PE4_TX_C_DN<10>")
	)
	(segment
		(start 335.650078 -427.289976)
		(end 335.650078 -426.974508)
		(width 0.14732)
		(layer "In6.Cu")
		(net "P5E_CPU0_PE4_TX_C_DN<10>")
	)
	(segment
		(start 334.78978 -410.809186)
		(end 334.721708 -410.116274)
		(width 0.14732)
		(layer "In6.Cu")
		(net "P5E_CPU0_PE4_TX_C_DN<10>")
	)
	(segment
		(start 334.721708 -410.116274)
		(end 334.721708 -406.819608)
		(width 0.14732)
		(layer "In6.Cu")
		(net "P5E_CPU0_PE4_TX_C_DN<10>")
	)
	(segment
		(start 334.838548 -411.936946)
		(end 334.78978 -410.809186)
		(width 0.14732)
		(layer "In6.Cu")
		(net "P5E_CPU0_PE4_TX_C_DN<10>")
	)
	(segment
		(start 334.681576 -426.508164)
		(end 334.681576 -425.471844)
		(width 0.14732)
		(layer "In6.Cu")
		(net "P5E_CPU0_PE4_TX_C_DN<10>")
	)
	(segment
		(start 335.650078 -426.974508)
		(end 335.502504 -426.826934)
		(width 0.14732)
		(layer "In6.Cu")
		(net "P5E_CPU0_PE4_TX_C_DN<10>")
	)
	(segment
		(start 335.502504 -426.826934)
		(end 335.000346 -426.826934)
		(width 0.14732)
		(layer "In6.Cu")
		(net "P5E_CPU0_PE4_TX_C_DN<10>")
	)
	(segment
		(start 304.28311 -402.962872)
		(end 303.95799 -402.637752)
		(width 0.13208)
		(layer "F.Cu")
		(net "P5E_CPU0_PE4_TX_C_DN<0>")
	)
	(segment
		(start 303.95799 -402.637752)
		(end 303.954688 -402.637752)
		(width 0.13208)
		(layer "F.Cu")
		(net "P5E_CPU0_PE4_TX_C_DN<0>")
	)
	(segment
		(start 303.980088 -403.883876)
		(end 304.28311 -403.580854)
		(width 0.13208)
		(layer "F.Cu")
		(net "P5E_CPU0_PE4_TX_C_DN<0>")
	)
	(segment
		(start 304.28311 -403.580854)
		(end 304.28311 -402.962872)
		(width 0.13208)
		(layer "F.Cu")
		(net "P5E_CPU0_PE4_TX_C_DN<0>")
	)
	(segment
		(start 314.65012 -427.289976)
		(end 314.65012 -426.974508)
		(width 0.14732)
		(layer "In6.Cu")
		(net "P5E_CPU0_PE4_TX_C_DN<0>")
	)
	(segment
		(start 304.089308 -406.819608)
		(end 304.274728 -404.936198)
		(width 0.14732)
		(layer "In6.Cu")
		(net "P5E_CPU0_PE4_TX_C_DN<0>")
	)
	(segment
		(start 314.65012 -426.974508)
		(end 314.502546 -426.826934)
		(width 0.14732)
		(layer "In6.Cu")
		(net "P5E_CPU0_PE4_TX_C_DN<0>")
	)
	(segment
		(start 314.000388 -426.826934)
		(end 313.501786 -426.328332)
		(width 0.14732)
		(layer "In6.Cu")
		(net "P5E_CPU0_PE4_TX_C_DN<0>")
	)
	(segment
		(start 314.502546 -426.826934)
		(end 314.000388 -426.826934)
		(width 0.14732)
		(layer "In6.Cu")
		(net "P5E_CPU0_PE4_TX_C_DN<0>")
	)
	(segment
		(start 304.089308 -410.735018)
		(end 304.089308 -406.819608)
		(width 0.14732)
		(layer "In6.Cu")
		(net "P5E_CPU0_PE4_TX_C_DN<0>")
	)
	(segment
		(start 313.501786 -426.328332)
		(end 304.089308 -410.735018)
		(width 0.14732)
		(layer "In6.Cu")
		(net "P5E_CPU0_PE4_TX_C_DN<0>")
	)
	(segment
		(start 304.274728 -404.936198)
		(end 304.274728 -404.178516)
		(width 0.14732)
		(layer "In6.Cu")
		(net "P5E_CPU0_PE4_TX_C_DN<0>")
	)
	(segment
		(start 304.274728 -404.178516)
		(end 303.980088 -403.883876)
		(width 0.14732)
		(layer "In6.Cu")
		(net "P5E_CPU0_PE4_TX_C_DN<0>")
	)
	(segment
		(start 346.063316 -288.381186)
		(end 346.063316 -288.917126)
		(width 0.13208)
		(layer "F.Cu")
		(net "P5E_CPU0_PE4_RX_DP<9>")
	)
	(segment
		(start 333.650082 -435.489858)
		(end 333.650082 -435.174644)
		(width 0.14732)
		(layer "In4.Cu")
		(net "P5E_CPU0_PE4_RX_DP<9>")
	)
	(segment
		(start 334.721708 -406.130252)
		(end 333.375508 -404.784052)
		(width 0.14732)
		(layer "In4.Cu")
		(net "P5E_CPU0_PE4_RX_DP<9>")
	)
	(segment
		(start 344.57132 -292.86327)
		(end 344.61323 -292.82136)
		(width 0.0889)
		(layer "In4.Cu")
		(net "P5E_CPU0_PE4_RX_DP<9>")
	)
	(segment
		(start 344.57132 -292.885368)
		(end 344.57132 -292.86327)
		(width 0.0889)
		(layer "In4.Cu")
		(net "P5E_CPU0_PE4_RX_DP<9>")
	)
	(segment
		(start 311.543192 -343.770204)
		(end 311.543192 -334.051402)
		(width 0.14732)
		(layer "In4.Cu")
		(net "P5E_CPU0_PE4_RX_DP<9>")
	)
	(segment
		(start 334.721708 -411.500066)
		(end 334.721708 -406.130252)
		(width 0.14732)
		(layer "In4.Cu")
		(net "P5E_CPU0_PE4_RX_DP<9>")
	)
	(segment
		(start 333.375508 -404.784052)
		(end 333.375508 -399.81505)
		(width 0.14732)
		(layer "In4.Cu")
		(net "P5E_CPU0_PE4_RX_DP<9>")
	)
	(segment
		(start 343.72042 -301.873158)
		(end 344.57132 -297.054778)
		(width 0.14732)
		(layer "In4.Cu")
		(net "P5E_CPU0_PE4_RX_DP<9>")
	)
	(segment
		(start 344.57132 -297.054778)
		(end 344.57132 -292.885368)
		(width 0.14732)
		(layer "In4.Cu")
		(net "P5E_CPU0_PE4_RX_DP<9>")
	)
	(segment
		(start 332.692502 -424.654218)
		(end 334.721708 -411.500066)
		(width 0.14732)
		(layer "In4.Cu")
		(net "P5E_CPU0_PE4_RX_DP<9>")
	)
	(segment
		(start 311.543192 -334.051402)
		(end 343.72042 -301.873158)
		(width 0.14732)
		(layer "In4.Cu")
		(net "P5E_CPU0_PE4_RX_DP<9>")
	)
	(segment
		(start 346.907612 -290.222178)
		(end 346.907612 -289.645852)
		(width 0.0889)
		(layer "In4.Cu")
		(net "P5E_CPU0_PE4_RX_DP<9>")
	)
	(segment
		(start 346.298012 -288.62528)
		(end 346.21978 -288.646108)
		(width 0.0889)
		(layer "In4.Cu")
		(net "P5E_CPU0_PE4_RX_DP<9>")
	)
	(segment
		(start 333.00035 -435.02707)
		(end 332.692502 -434.719222)
		(width 0.14732)
		(layer "In4.Cu")
		(net "P5E_CPU0_PE4_RX_DP<9>")
	)
	(segment
		(start 333.502508 -435.02707)
		(end 333.00035 -435.02707)
		(width 0.14732)
		(layer "In4.Cu")
		(net "P5E_CPU0_PE4_RX_DP<9>")
	)
	(segment
		(start 346.21978 -288.646108)
		(end 346.063316 -288.917126)
		(width 0.0889)
		(layer "In4.Cu")
		(net "P5E_CPU0_PE4_RX_DP<9>")
	)
	(segment
		(start 333.375508 -399.81505)
		(end 311.543192 -343.770204)
		(width 0.14732)
		(layer "In4.Cu")
		(net "P5E_CPU0_PE4_RX_DP<9>")
	)
	(segment
		(start 344.61323 -292.82136)
		(end 344.61323 -292.51656)
		(width 0.0889)
		(layer "In4.Cu")
		(net "P5E_CPU0_PE4_RX_DP<9>")
	)
	(segment
		(start 332.692502 -434.719222)
		(end 332.692502 -424.654218)
		(width 0.14732)
		(layer "In4.Cu")
		(net "P5E_CPU0_PE4_RX_DP<9>")
	)
	(segment
		(start 346.437966 -289.114738)
		(end 346.437966 -288.917126)
		(width 0.0889)
		(layer "In4.Cu")
		(net "P5E_CPU0_PE4_RX_DP<9>")
	)
	(segment
		(start 344.61323 -292.51656)
		(end 346.907612 -290.222178)
		(width 0.0889)
		(layer "In4.Cu")
		(net "P5E_CPU0_PE4_RX_DP<9>")
	)
	(segment
		(start 333.650082 -435.174644)
		(end 333.502508 -435.02707)
		(width 0.14732)
		(layer "In4.Cu")
		(net "P5E_CPU0_PE4_RX_DP<9>")
	)
	(arc
		(start 346.907612 -289.645852)
		(mid 346.832607 -289.530393)
		(end 346.723462 -289.446462)
		(width 0.0889)
		(layer "In4.Cu")
		(net "P5E_CPU0_PE4_RX_DP<9>")
	)
	(arc
		(start 346.437966 -288.917126)
		(mid 346.401106 -288.755329)
		(end 346.298012 -288.62528)
		(width 0.0889)
		(layer "In4.Cu")
		(net "P5E_CPU0_PE4_RX_DP<9>")
	)
	(arc
		(start 346.723462 -289.446462)
		(mid 346.54933 -289.307615)
		(end 346.437966 -289.114738)
		(width 0.0889)
		(layer "In4.Cu")
		(net "P5E_CPU0_PE4_RX_DP<9>")
	)
	(segment
		(start 345.123516 -288.381186)
		(end 345.123516 -288.917126)
		(width 0.13208)
		(layer "F.Cu")
		(net "P5E_CPU0_PE4_RX_DP<8>")
	)
	(segment
		(start 331.38999 -418.996368)
		(end 331.322934 -419.842696)
		(width 0.14732)
		(layer "In4.Cu")
		(net "P5E_CPU0_PE4_RX_DP<8>")
	)
	(segment
		(start 310.884824 -333.778606)
		(end 310.884824 -343.914984)
		(width 0.14732)
		(layer "In4.Cu")
		(net "P5E_CPU0_PE4_RX_DP<8>")
	)
	(segment
		(start 330.966826 -424.323764)
		(end 330.966826 -433.605432)
		(width 0.14732)
		(layer "In4.Cu")
		(net "P5E_CPU0_PE4_RX_DP<8>")
	)
	(segment
		(start 343.91219 -297.01236)
		(end 343.111074 -301.55134)
		(width 0.14732)
		(layer "In4.Cu")
		(net "P5E_CPU0_PE4_RX_DP<8>")
	)
	(segment
		(start 331.166724 -421.809418)
		(end 330.966826 -424.323764)
		(width 0.14732)
		(layer "In4.Cu")
		(net "P5E_CPU0_PE4_RX_DP<8>")
	)
	(segment
		(start 331.540612 -418.868098)
		(end 331.38999 -418.996368)
		(width 0.14732)
		(layer "In4.Cu")
		(net "P5E_CPU0_PE4_RX_DP<8>")
	)
	(segment
		(start 345.282266 -289.218116)
		(end 345.37904 -289.247834)
		(width 0.0889)
		(layer "In4.Cu")
		(net "P5E_CPU0_PE4_RX_DP<8>")
	)
	(segment
		(start 331.346302 -421.31234)
		(end 331.317092 -421.679878)
		(width 0.14732)
		(layer "In4.Cu")
		(net "P5E_CPU0_PE4_RX_DP<8>")
	)
	(segment
		(start 331.421994 -420.360348)
		(end 331.271372 -420.488618)
		(width 0.14732)
		(layer "In4.Cu")
		(net "P5E_CPU0_PE4_RX_DP<8>")
	)
	(segment
		(start 331.650086 -433.54117)
		(end 331.650086 -433.289964)
		(width 0.14732)
		(layer "In4.Cu")
		(net "P5E_CPU0_PE4_RX_DP<8>")
	)
	(segment
		(start 346.158312 -289.60953)
		(end 346.158312 -290.229798)
		(width 0.0889)
		(layer "In4.Cu")
		(net "P5E_CPU0_PE4_RX_DP<8>")
	)
	(segment
		(start 330.586588 -400.054064)
		(end 330.586588 -404.67026)
		(width 0.14732)
		(layer "In4.Cu")
		(net "P5E_CPU0_PE4_RX_DP<8>")
	)
	(segment
		(start 343.111074 -301.55134)
		(end 310.884824 -333.778606)
		(width 0.14732)
		(layer "In4.Cu")
		(net "P5E_CPU0_PE4_RX_DP<8>")
	)
	(segment
		(start 330.586588 -404.67026)
		(end 331.932788 -406.01646)
		(width 0.14732)
		(layer "In4.Cu")
		(net "P5E_CPU0_PE4_RX_DP<8>")
	)
	(segment
		(start 331.317092 -421.679878)
		(end 331.16647 -421.807894)
		(width 0.14732)
		(layer "In4.Cu")
		(net "P5E_CPU0_PE4_RX_DP<8>")
	)
	(segment
		(start 331.932788 -412.165546)
		(end 331.441552 -418.350446)
		(width 0.14732)
		(layer "In4.Cu")
		(net "P5E_CPU0_PE4_RX_DP<8>")
	)
	(segment
		(start 346.158312 -290.229798)
		(end 343.870788 -292.517322)
		(width 0.0889)
		(layer "In4.Cu")
		(net "P5E_CPU0_PE4_RX_DP<8>")
	)
	(segment
		(start 331.218032 -421.161972)
		(end 331.346302 -421.31234)
		(width 0.14732)
		(layer "In4.Cu")
		(net "P5E_CPU0_PE4_RX_DP<8>")
	)
	(segment
		(start 343.870788 -292.517322)
		(end 343.870788 -292.821106)
		(width 0.0889)
		(layer "In4.Cu")
		(net "P5E_CPU0_PE4_RX_DP<8>")
	)
	(segment
		(start 331.114146 -433.752752)
		(end 331.438504 -433.752752)
		(width 0.14732)
		(layer "In4.Cu")
		(net "P5E_CPU0_PE4_RX_DP<8>")
	)
	(segment
		(start 345.123516 -288.917126)
		(end 345.282266 -289.218116)
		(width 0.0889)
		(layer "In4.Cu")
		(net "P5E_CPU0_PE4_RX_DP<8>")
	)
	(segment
		(start 331.16647 -421.807894)
		(end 331.166724 -421.809418)
		(width 0.14732)
		(layer "In4.Cu")
		(net "P5E_CPU0_PE4_RX_DP<8>")
	)
	(segment
		(start 343.870788 -292.821106)
		(end 343.912952 -292.86327)
		(width 0.0889)
		(layer "In4.Cu")
		(net "P5E_CPU0_PE4_RX_DP<8>")
	)
	(segment
		(start 331.451204 -419.993064)
		(end 331.421994 -420.360348)
		(width 0.14732)
		(layer "In4.Cu")
		(net "P5E_CPU0_PE4_RX_DP<8>")
	)
	(segment
		(start 343.912952 -292.885368)
		(end 343.912952 -297.011598)
		(width 0.14732)
		(layer "In4.Cu")
		(net "P5E_CPU0_PE4_RX_DP<8>")
	)
	(segment
		(start 331.441552 -418.350446)
		(end 331.569822 -418.500814)
		(width 0.14732)
		(layer "In4.Cu")
		(net "P5E_CPU0_PE4_RX_DP<8>")
	)
	(segment
		(start 343.912952 -297.011598)
		(end 343.91219 -297.01236)
		(width 0.14732)
		(layer "In4.Cu")
		(net "P5E_CPU0_PE4_RX_DP<8>")
	)
	(segment
		(start 331.322934 -419.842696)
		(end 331.451204 -419.993064)
		(width 0.14732)
		(layer "In4.Cu")
		(net "P5E_CPU0_PE4_RX_DP<8>")
	)
	(segment
		(start 331.569822 -418.500814)
		(end 331.540612 -418.868098)
		(width 0.14732)
		(layer "In4.Cu")
		(net "P5E_CPU0_PE4_RX_DP<8>")
	)
	(segment
		(start 331.932788 -406.01646)
		(end 331.932788 -412.165546)
		(width 0.14732)
		(layer "In4.Cu")
		(net "P5E_CPU0_PE4_RX_DP<8>")
	)
	(segment
		(start 330.966826 -433.605432)
		(end 331.114146 -433.752752)
		(width 0.14732)
		(layer "In4.Cu")
		(net "P5E_CPU0_PE4_RX_DP<8>")
	)
	(segment
		(start 310.884824 -343.914984)
		(end 330.586588 -400.054064)
		(width 0.14732)
		(layer "In4.Cu")
		(net "P5E_CPU0_PE4_RX_DP<8>")
	)
	(segment
		(start 331.438504 -433.752752)
		(end 331.650086 -433.54117)
		(width 0.14732)
		(layer "In4.Cu")
		(net "P5E_CPU0_PE4_RX_DP<8>")
	)
	(segment
		(start 331.271372 -420.488618)
		(end 331.218032 -421.161972)
		(width 0.14732)
		(layer "In4.Cu")
		(net "P5E_CPU0_PE4_RX_DP<8>")
	)
	(segment
		(start 343.912952 -292.86327)
		(end 343.912952 -292.885368)
		(width 0.0889)
		(layer "In4.Cu")
		(net "P5E_CPU0_PE4_RX_DP<8>")
	)
	(arc
		(start 345.398852 -289.240722)
		(mid 345.854694 -289.26845)
		(end 346.158312 -289.60953)
		(width 0.0889)
		(layer "In4.Cu")
		(net "P5E_CPU0_PE4_RX_DP<8>")
	)
	(arc
		(start 345.37904 -289.247834)
		(mid 345.388915 -289.244192)
		(end 345.398852 -289.240722)
		(width 0.0889)
		(layer "In4.Cu")
		(net "P5E_CPU0_PE4_RX_DP<8>")
	)
	(segment
		(start 344.183716 -288.381186)
		(end 344.183716 -288.917126)
		(width 0.13208)
		(layer "F.Cu")
		(net "P5E_CPU0_PE4_RX_DP<7>")
	)
	(segment
		(start 327.69429 -424.41495)
		(end 328.595228 -412.827216)
		(width 0.14732)
		(layer "In4.Cu")
		(net "P5E_CPU0_PE4_RX_DP<7>")
	)
	(segment
		(start 342.747854 -292.82136)
		(end 342.747854 -292.327076)
		(width 0.0889)
		(layer "In4.Cu")
		(net "P5E_CPU0_PE4_RX_DP<7>")
	)
	(segment
		(start 342.705944 -292.885368)
		(end 342.705944 -292.86327)
		(width 0.0889)
		(layer "In4.Cu")
		(net "P5E_CPU0_PE4_RX_DP<7>")
	)
	(segment
		(start 328.595228 -406.130252)
		(end 327.249028 -404.784052)
		(width 0.14732)
		(layer "In4.Cu")
		(net "P5E_CPU0_PE4_RX_DP<7>")
	)
	(segment
		(start 328.650092 -435.174644)
		(end 328.502518 -435.02707)
		(width 0.14732)
		(layer "In4.Cu")
		(net "P5E_CPU0_PE4_RX_DP<7>")
	)
	(segment
		(start 342.705944 -296.906442)
		(end 342.705944 -292.885368)
		(width 0.14732)
		(layer "In4.Cu")
		(net "P5E_CPU0_PE4_RX_DP<7>")
	)
	(segment
		(start 344.418412 -288.62528)
		(end 344.34018 -288.646108)
		(width 0.0889)
		(layer "In4.Cu")
		(net "P5E_CPU0_PE4_RX_DP<7>")
	)
	(segment
		(start 327.249028 -399.315432)
		(end 309.654702 -344.05062)
		(width 0.14732)
		(layer "In4.Cu")
		(net "P5E_CPU0_PE4_RX_DP<7>")
	)
	(segment
		(start 328.595228 -412.827216)
		(end 328.595228 -406.130252)
		(width 0.14732)
		(layer "In4.Cu")
		(net "P5E_CPU0_PE4_RX_DP<7>")
	)
	(segment
		(start 327.249028 -404.784052)
		(end 327.249028 -399.315432)
		(width 0.14732)
		(layer "In4.Cu")
		(net "P5E_CPU0_PE4_RX_DP<7>")
	)
	(segment
		(start 345.028012 -290.046918)
		(end 345.028012 -289.645852)
		(width 0.0889)
		(layer "In4.Cu")
		(net "P5E_CPU0_PE4_RX_DP<7>")
	)
	(segment
		(start 342.747854 -292.327076)
		(end 345.028012 -290.046918)
		(width 0.0889)
		(layer "In4.Cu")
		(net "P5E_CPU0_PE4_RX_DP<7>")
	)
	(segment
		(start 341.987632 -300.969934)
		(end 342.704674 -296.906188)
		(width 0.14732)
		(layer "In4.Cu")
		(net "P5E_CPU0_PE4_RX_DP<7>")
	)
	(segment
		(start 344.558366 -289.114738)
		(end 344.558366 -288.917126)
		(width 0.0889)
		(layer "In4.Cu")
		(net "P5E_CPU0_PE4_RX_DP<7>")
	)
	(segment
		(start 328.502518 -435.02707)
		(end 328.00036 -435.02707)
		(width 0.14732)
		(layer "In4.Cu")
		(net "P5E_CPU0_PE4_RX_DP<7>")
	)
	(segment
		(start 342.705944 -292.86327)
		(end 342.747854 -292.82136)
		(width 0.0889)
		(layer "In4.Cu")
		(net "P5E_CPU0_PE4_RX_DP<7>")
	)
	(segment
		(start 328.650092 -435.489858)
		(end 328.650092 -435.174644)
		(width 0.14732)
		(layer "In4.Cu")
		(net "P5E_CPU0_PE4_RX_DP<7>")
	)
	(segment
		(start 328.00036 -435.02707)
		(end 327.692512 -434.719222)
		(width 0.14732)
		(layer "In4.Cu")
		(net "P5E_CPU0_PE4_RX_DP<7>")
	)
	(segment
		(start 327.692512 -424.416728)
		(end 327.69429 -424.41495)
		(width 0.14732)
		(layer "In4.Cu")
		(net "P5E_CPU0_PE4_RX_DP<7>")
	)
	(segment
		(start 327.692512 -434.719222)
		(end 327.692512 -424.416728)
		(width 0.14732)
		(layer "In4.Cu")
		(net "P5E_CPU0_PE4_RX_DP<7>")
	)
	(segment
		(start 342.704674 -296.906188)
		(end 342.70569 -296.906188)
		(width 0.14732)
		(layer "In4.Cu")
		(net "P5E_CPU0_PE4_RX_DP<7>")
	)
	(segment
		(start 344.34018 -288.646108)
		(end 344.183716 -288.917126)
		(width 0.0889)
		(layer "In4.Cu")
		(net "P5E_CPU0_PE4_RX_DP<7>")
	)
	(segment
		(start 309.654702 -344.05062)
		(end 309.654702 -333.302864)
		(width 0.14732)
		(layer "In4.Cu")
		(net "P5E_CPU0_PE4_RX_DP<7>")
	)
	(segment
		(start 342.70569 -296.906188)
		(end 342.705944 -296.906442)
		(width 0.14732)
		(layer "In4.Cu")
		(net "P5E_CPU0_PE4_RX_DP<7>")
	)
	(segment
		(start 309.654702 -333.302864)
		(end 341.987632 -300.969934)
		(width 0.14732)
		(layer "In4.Cu")
		(net "P5E_CPU0_PE4_RX_DP<7>")
	)
	(arc
		(start 345.028012 -289.645852)
		(mid 344.953007 -289.530393)
		(end 344.843862 -289.446462)
		(width 0.0889)
		(layer "In4.Cu")
		(net "P5E_CPU0_PE4_RX_DP<7>")
	)
	(arc
		(start 344.843862 -289.446462)
		(mid 344.66973 -289.307615)
		(end 344.558366 -289.114738)
		(width 0.0889)
		(layer "In4.Cu")
		(net "P5E_CPU0_PE4_RX_DP<7>")
	)
	(arc
		(start 344.558366 -288.917126)
		(mid 344.521506 -288.755329)
		(end 344.418412 -288.62528)
		(width 0.0889)
		(layer "In4.Cu")
		(net "P5E_CPU0_PE4_RX_DP<7>")
	)
	(segment
		(start 343.243916 -288.381186)
		(end 343.243916 -288.917126)
		(width 0.13208)
		(layer "F.Cu")
		(net "P5E_CPU0_PE4_RX_DP<6>")
	)
	(segment
		(start 326.140318 -417.844478)
		(end 326.000618 -417.984178)
		(width 0.14732)
		(layer "In4.Cu")
		(net "P5E_CPU0_PE4_RX_DP<6>")
	)
	(segment
		(start 342.04656 -296.744898)
		(end 341.41791 -300.305724)
		(width 0.14732)
		(layer "In4.Cu")
		(net "P5E_CPU0_PE4_RX_DP<6>")
	)
	(segment
		(start 326.140318 -418.769038)
		(end 326.140318 -419.137338)
		(width 0.14732)
		(layer "In4.Cu")
		(net "P5E_CPU0_PE4_RX_DP<6>")
	)
	(segment
		(start 341.41791 -300.305724)
		(end 317.607188 -324.116446)
		(width 0.14732)
		(layer "In4.Cu")
		(net "P5E_CPU0_PE4_RX_DP<6>")
	)
	(segment
		(start 326.000618 -417.336478)
		(end 326.140318 -417.476178)
		(width 0.14732)
		(layer "In4.Cu")
		(net "P5E_CPU0_PE4_RX_DP<6>")
	)
	(segment
		(start 326.140318 -420.521638)
		(end 325.953628 -420.708328)
		(width 0.14732)
		(layer "In4.Cu")
		(net "P5E_CPU0_PE4_RX_DP<6>")
	)
	(segment
		(start 326.103996 -433.752752)
		(end 326.438514 -433.752752)
		(width 0.14732)
		(layer "In4.Cu")
		(net "P5E_CPU0_PE4_RX_DP<6>")
	)
	(segment
		(start 344.278458 -289.610292)
		(end 344.278458 -290.130992)
		(width 0.0889)
		(layer "In4.Cu")
		(net "P5E_CPU0_PE4_RX_DP<6>")
	)
	(segment
		(start 343.402666 -289.218116)
		(end 343.49944 -289.247834)
		(width 0.0889)
		(layer "In4.Cu")
		(net "P5E_CPU0_PE4_RX_DP<6>")
	)
	(segment
		(start 343.243916 -288.917126)
		(end 343.402666 -289.218116)
		(width 0.0889)
		(layer "In4.Cu")
		(net "P5E_CPU0_PE4_RX_DP<6>")
	)
	(segment
		(start 326.000618 -417.984178)
		(end 326.000618 -418.629338)
		(width 0.14732)
		(layer "In4.Cu")
		(net "P5E_CPU0_PE4_RX_DP<6>")
	)
	(segment
		(start 326.650096 -433.54117)
		(end 326.650096 -433.289964)
		(width 0.14732)
		(layer "In4.Cu")
		(net "P5E_CPU0_PE4_RX_DP<6>")
	)
	(segment
		(start 344.278458 -290.130992)
		(end 342.004396 -292.405054)
		(width 0.0889)
		(layer "In4.Cu")
		(net "P5E_CPU0_PE4_RX_DP<6>")
	)
	(segment
		(start 325.953628 -420.708328)
		(end 325.953628 -433.602384)
		(width 0.14732)
		(layer "In4.Cu")
		(net "P5E_CPU0_PE4_RX_DP<6>")
	)
	(segment
		(start 324.460108 -398.8308)
		(end 324.460108 -404.67026)
		(width 0.14732)
		(layer "In4.Cu")
		(net "P5E_CPU0_PE4_RX_DP<6>")
	)
	(segment
		(start 325.806308 -406.01646)
		(end 325.806308 -409.902914)
		(width 0.14732)
		(layer "In4.Cu")
		(net "P5E_CPU0_PE4_RX_DP<6>")
	)
	(segment
		(start 308.99354 -333.028798)
		(end 308.99354 -344.356436)
		(width 0.14732)
		(layer "In4.Cu")
		(net "P5E_CPU0_PE4_RX_DP<6>")
	)
	(segment
		(start 342.004396 -292.405054)
		(end 342.004396 -292.821106)
		(width 0.0889)
		(layer "In4.Cu")
		(net "P5E_CPU0_PE4_RX_DP<6>")
	)
	(segment
		(start 325.953628 -433.602384)
		(end 326.103996 -433.752752)
		(width 0.14732)
		(layer "In4.Cu")
		(net "P5E_CPU0_PE4_RX_DP<6>")
	)
	(segment
		(start 342.004396 -292.821106)
		(end 342.04656 -292.86327)
		(width 0.0889)
		(layer "In4.Cu")
		(net "P5E_CPU0_PE4_RX_DP<6>")
	)
	(segment
		(start 324.460108 -404.67026)
		(end 325.806308 -406.01646)
		(width 0.14732)
		(layer "In4.Cu")
		(net "P5E_CPU0_PE4_RX_DP<6>")
	)
	(segment
		(start 326.000618 -412.827724)
		(end 326.000618 -417.336478)
		(width 0.14732)
		(layer "In4.Cu")
		(net "P5E_CPU0_PE4_RX_DP<6>")
	)
	(segment
		(start 326.140318 -419.137338)
		(end 326.000618 -419.277038)
		(width 0.14732)
		(layer "In4.Cu")
		(net "P5E_CPU0_PE4_RX_DP<6>")
	)
	(segment
		(start 325.806308 -409.902914)
		(end 326.000618 -412.827724)
		(width 0.14732)
		(layer "In4.Cu")
		(net "P5E_CPU0_PE4_RX_DP<6>")
	)
	(segment
		(start 308.99354 -344.356436)
		(end 324.460108 -398.8308)
		(width 0.14732)
		(layer "In4.Cu")
		(net "P5E_CPU0_PE4_RX_DP<6>")
	)
	(segment
		(start 326.000618 -420.013638)
		(end 326.140318 -420.153338)
		(width 0.14732)
		(layer "In4.Cu")
		(net "P5E_CPU0_PE4_RX_DP<6>")
	)
	(segment
		(start 326.000618 -419.277038)
		(end 326.000618 -420.013638)
		(width 0.14732)
		(layer "In4.Cu")
		(net "P5E_CPU0_PE4_RX_DP<6>")
	)
	(segment
		(start 326.000618 -418.629338)
		(end 326.140318 -418.769038)
		(width 0.14732)
		(layer "In4.Cu")
		(net "P5E_CPU0_PE4_RX_DP<6>")
	)
	(segment
		(start 326.140318 -420.153338)
		(end 326.140318 -420.521638)
		(width 0.14732)
		(layer "In4.Cu")
		(net "P5E_CPU0_PE4_RX_DP<6>")
	)
	(segment
		(start 317.607188 -324.116446)
		(end 317.607188 -324.41515)
		(width 0.14732)
		(layer "In4.Cu")
		(net "P5E_CPU0_PE4_RX_DP<6>")
	)
	(segment
		(start 342.04656 -292.86327)
		(end 342.04656 -292.885368)
		(width 0.0889)
		(layer "In4.Cu")
		(net "P5E_CPU0_PE4_RX_DP<6>")
	)
	(segment
		(start 342.04656 -292.885368)
		(end 342.04656 -296.744898)
		(width 0.14732)
		(layer "In4.Cu")
		(net "P5E_CPU0_PE4_RX_DP<6>")
	)
	(segment
		(start 326.140318 -417.476178)
		(end 326.140318 -417.844478)
		(width 0.14732)
		(layer "In4.Cu")
		(net "P5E_CPU0_PE4_RX_DP<6>")
	)
	(segment
		(start 317.607188 -324.41515)
		(end 308.99354 -333.028798)
		(width 0.14732)
		(layer "In4.Cu")
		(net "P5E_CPU0_PE4_RX_DP<6>")
	)
	(segment
		(start 326.438514 -433.752752)
		(end 326.650096 -433.54117)
		(width 0.14732)
		(layer "In4.Cu")
		(net "P5E_CPU0_PE4_RX_DP<6>")
	)
	(arc
		(start 343.519506 -289.241484)
		(mid 343.975026 -289.26931)
		(end 344.278458 -289.610292)
		(width 0.0889)
		(layer "In4.Cu")
		(net "P5E_CPU0_PE4_RX_DP<6>")
	)
	(arc
		(start 343.49944 -289.247834)
		(mid 343.509315 -289.244192)
		(end 343.519252 -289.240722)
		(width 0.0889)
		(layer "In4.Cu")
		(net "P5E_CPU0_PE4_RX_DP<6>")
	)
	(arc
		(start 343.519252 -289.240722)
		(mid 343.519359 -289.24111)
		(end 343.519506 -289.241484)
		(width 0.0889)
		(layer "In4.Cu")
		(net "P5E_CPU0_PE4_RX_DP<6>")
	)
	(segment
		(start 342.304116 -288.381186)
		(end 342.304116 -288.917126)
		(width 0.13208)
		(layer "F.Cu")
		(net "P5E_CPU0_PE4_RX_DP<5>")
	)
	(segment
		(start 322.468748 -411.355032)
		(end 322.468748 -406.130252)
		(width 0.14732)
		(layer "In4.Cu")
		(net "P5E_CPU0_PE4_RX_DP<5>")
	)
	(segment
		(start 337.25612 -294.767508)
		(end 339.176614 -294.767508)
		(width 0.14732)
		(layer "In4.Cu")
		(net "P5E_CPU0_PE4_RX_DP<5>")
	)
	(segment
		(start 324.6501 -435.174644)
		(end 324.502526 -435.02707)
		(width 0.14732)
		(layer "In4.Cu")
		(net "P5E_CPU0_PE4_RX_DP<5>")
	)
	(segment
		(start 316.179454 -323.822822)
		(end 334.3656 -305.636676)
		(width 0.14732)
		(layer "In4.Cu")
		(net "P5E_CPU0_PE4_RX_DP<5>")
	)
	(segment
		(start 307.78323 -332.526894)
		(end 316.179454 -324.13067)
		(width 0.14732)
		(layer "In4.Cu")
		(net "P5E_CPU0_PE4_RX_DP<5>")
	)
	(segment
		(start 334.3656 -305.636676)
		(end 335.580482 -298.747942)
		(width 0.14732)
		(layer "In4.Cu")
		(net "P5E_CPU0_PE4_RX_DP<5>")
	)
	(segment
		(start 321.122548 -398.662906)
		(end 307.78323 -344.633804)
		(width 0.14732)
		(layer "In4.Cu")
		(net "P5E_CPU0_PE4_RX_DP<5>")
	)
	(segment
		(start 322.468748 -406.130252)
		(end 321.122548 -404.784052)
		(width 0.14732)
		(layer "In4.Cu")
		(net "P5E_CPU0_PE4_RX_DP<5>")
	)
	(segment
		(start 324.000368 -435.02707)
		(end 323.69252 -434.719222)
		(width 0.14732)
		(layer "In4.Cu")
		(net "P5E_CPU0_PE4_RX_DP<5>")
	)
	(segment
		(start 335.85531 -296.168318)
		(end 337.25612 -294.767508)
		(width 0.14732)
		(layer "In4.Cu")
		(net "P5E_CPU0_PE4_RX_DP<5>")
	)
	(segment
		(start 340.834726 -292.885368)
		(end 340.834726 -292.86327)
		(width 0.0889)
		(layer "In4.Cu")
		(net "P5E_CPU0_PE4_RX_DP<5>")
	)
	(segment
		(start 321.122548 -404.784052)
		(end 321.122548 -398.662906)
		(width 0.14732)
		(layer "In4.Cu")
		(net "P5E_CPU0_PE4_RX_DP<5>")
	)
	(segment
		(start 343.148412 -289.998658)
		(end 343.148412 -289.645852)
		(width 0.0889)
		(layer "In4.Cu")
		(net "P5E_CPU0_PE4_RX_DP<5>")
	)
	(segment
		(start 340.876636 -292.270434)
		(end 343.148412 -289.998658)
		(width 0.0889)
		(layer "In4.Cu")
		(net "P5E_CPU0_PE4_RX_DP<5>")
	)
	(segment
		(start 323.69252 -434.719222)
		(end 323.69252 -425.039028)
		(width 0.14732)
		(layer "In4.Cu")
		(net "P5E_CPU0_PE4_RX_DP<5>")
	)
	(segment
		(start 340.834726 -293.109396)
		(end 340.834726 -292.885368)
		(width 0.14732)
		(layer "In4.Cu")
		(net "P5E_CPU0_PE4_RX_DP<5>")
	)
	(segment
		(start 340.876636 -292.82136)
		(end 340.876636 -292.270434)
		(width 0.0889)
		(layer "In4.Cu")
		(net "P5E_CPU0_PE4_RX_DP<5>")
	)
	(segment
		(start 323.665596 -424.650662)
		(end 322.468748 -411.355032)
		(width 0.14732)
		(layer "In4.Cu")
		(net "P5E_CPU0_PE4_RX_DP<5>")
	)
	(segment
		(start 342.46058 -288.646108)
		(end 342.304116 -288.917126)
		(width 0.0889)
		(layer "In4.Cu")
		(net "P5E_CPU0_PE4_RX_DP<5>")
	)
	(segment
		(start 339.176614 -294.767508)
		(end 340.834726 -293.109396)
		(width 0.14732)
		(layer "In4.Cu")
		(net "P5E_CPU0_PE4_RX_DP<5>")
	)
	(segment
		(start 307.78323 -344.633804)
		(end 307.78323 -332.526894)
		(width 0.14732)
		(layer "In4.Cu")
		(net "P5E_CPU0_PE4_RX_DP<5>")
	)
	(segment
		(start 342.678766 -289.114738)
		(end 342.678766 -288.917126)
		(width 0.0889)
		(layer "In4.Cu")
		(net "P5E_CPU0_PE4_RX_DP<5>")
	)
	(segment
		(start 323.69252 -425.039028)
		(end 323.665596 -424.650662)
		(width 0.14732)
		(layer "In4.Cu")
		(net "P5E_CPU0_PE4_RX_DP<5>")
	)
	(segment
		(start 324.502526 -435.02707)
		(end 324.000368 -435.02707)
		(width 0.14732)
		(layer "In4.Cu")
		(net "P5E_CPU0_PE4_RX_DP<5>")
	)
	(segment
		(start 335.580482 -296.831258)
		(end 335.85531 -296.168318)
		(width 0.14732)
		(layer "In4.Cu")
		(net "P5E_CPU0_PE4_RX_DP<5>")
	)
	(segment
		(start 324.6501 -435.489858)
		(end 324.6501 -435.174644)
		(width 0.14732)
		(layer "In4.Cu")
		(net "P5E_CPU0_PE4_RX_DP<5>")
	)
	(segment
		(start 316.179454 -324.13067)
		(end 316.179454 -323.822822)
		(width 0.14732)
		(layer "In4.Cu")
		(net "P5E_CPU0_PE4_RX_DP<5>")
	)
	(segment
		(start 335.580482 -298.747942)
		(end 335.580482 -296.831258)
		(width 0.14732)
		(layer "In4.Cu")
		(net "P5E_CPU0_PE4_RX_DP<5>")
	)
	(segment
		(start 342.538812 -288.62528)
		(end 342.46058 -288.646108)
		(width 0.0889)
		(layer "In4.Cu")
		(net "P5E_CPU0_PE4_RX_DP<5>")
	)
	(segment
		(start 340.834726 -292.86327)
		(end 340.876636 -292.82136)
		(width 0.0889)
		(layer "In4.Cu")
		(net "P5E_CPU0_PE4_RX_DP<5>")
	)
	(arc
		(start 343.148412 -289.645852)
		(mid 343.073407 -289.530393)
		(end 342.964262 -289.446462)
		(width 0.0889)
		(layer "In4.Cu")
		(net "P5E_CPU0_PE4_RX_DP<5>")
	)
	(arc
		(start 342.964262 -289.446462)
		(mid 342.79013 -289.307615)
		(end 342.678766 -289.114738)
		(width 0.0889)
		(layer "In4.Cu")
		(net "P5E_CPU0_PE4_RX_DP<5>")
	)
	(arc
		(start 342.678766 -288.917126)
		(mid 342.641906 -288.755329)
		(end 342.538812 -288.62528)
		(width 0.0889)
		(layer "In4.Cu")
		(net "P5E_CPU0_PE4_RX_DP<5>")
	)
	(segment
		(start 341.364316 -288.381186)
		(end 341.364316 -288.917126)
		(width 0.13208)
		(layer "F.Cu")
		(net "P5E_CPU0_PE4_RX_DP<4>")
	)
	(segment
		(start 319.679828 -406.01646)
		(end 319.679828 -410.704792)
		(width 0.14732)
		(layer "In4.Cu")
		(net "P5E_CPU0_PE4_RX_DP<4>")
	)
	(segment
		(start 340.426802 -292.104318)
		(end 338.433156 -294.097964)
		(width 0.14732)
		(layer "In4.Cu")
		(net "P5E_CPU0_PE4_RX_DP<4>")
	)
	(segment
		(start 338.433156 -294.097964)
		(end 336.978752 -294.097964)
		(width 0.14732)
		(layer "In4.Cu")
		(net "P5E_CPU0_PE4_RX_DP<4>")
	)
	(segment
		(start 334.925162 -298.608496)
		(end 333.747364 -305.28768)
		(width 0.14732)
		(layer "In4.Cu")
		(net "P5E_CPU0_PE4_RX_DP<4>")
	)
	(segment
		(start 320.435732 -414.500822)
		(end 320.50736 -414.93186)
		(width 0.14732)
		(layer "In4.Cu")
		(net "P5E_CPU0_PE4_RX_DP<4>")
	)
	(segment
		(start 320.139822 -412.716726)
		(end 320.037206 -412.859728)
		(width 0.14732)
		(layer "In4.Cu")
		(net "P5E_CPU0_PE4_RX_DP<4>")
	)
	(segment
		(start 320.10858 -413.290512)
		(end 320.251836 -413.393128)
		(width 0.14732)
		(layer "In4.Cu")
		(net "P5E_CPU0_PE4_RX_DP<4>")
	)
	(segment
		(start 320.251836 -413.393128)
		(end 320.323464 -413.824166)
		(width 0.14732)
		(layer "In4.Cu")
		(net "P5E_CPU0_PE4_RX_DP<4>")
	)
	(segment
		(start 322.114164 -433.752752)
		(end 322.438522 -433.752752)
		(width 0.14732)
		(layer "In4.Cu")
		(net "P5E_CPU0_PE4_RX_DP<4>")
	)
	(segment
		(start 315.352684 -324.005448)
		(end 313.506104 -325.852028)
		(width 0.14732)
		(layer "In4.Cu")
		(net "P5E_CPU0_PE4_RX_DP<4>")
	)
	(segment
		(start 320.221102 -413.967422)
		(end 320.292476 -414.398206)
		(width 0.14732)
		(layer "In4.Cu")
		(net "P5E_CPU0_PE4_RX_DP<4>")
	)
	(segment
		(start 309.221378 -326.578468)
		(end 309.221378 -328.623168)
		(width 0.14732)
		(layer "In4.Cu")
		(net "P5E_CPU0_PE4_RX_DP<4>")
	)
	(segment
		(start 319.924938 -412.183072)
		(end 320.068194 -412.285434)
		(width 0.14732)
		(layer "In4.Cu")
		(net "P5E_CPU0_PE4_RX_DP<4>")
	)
	(segment
		(start 320.404998 -415.075116)
		(end 320.476372 -415.5059)
		(width 0.14732)
		(layer "In4.Cu")
		(net "P5E_CPU0_PE4_RX_DP<4>")
	)
	(segment
		(start 340.442296 -292.02888)
		(end 340.442296 -292.088824)
		(width 0.0889)
		(layer "In4.Cu")
		(net "P5E_CPU0_PE4_RX_DP<4>")
	)
	(segment
		(start 320.50736 -414.93186)
		(end 320.404998 -415.075116)
		(width 0.14732)
		(layer "In4.Cu")
		(net "P5E_CPU0_PE4_RX_DP<4>")
	)
	(segment
		(start 320.292476 -414.398206)
		(end 320.435732 -414.500822)
		(width 0.14732)
		(layer "In4.Cu")
		(net "P5E_CPU0_PE4_RX_DP<4>")
	)
	(segment
		(start 320.691256 -416.039554)
		(end 320.58864 -416.18281)
		(width 0.14732)
		(layer "In4.Cu")
		(net "P5E_CPU0_PE4_RX_DP<4>")
	)
	(segment
		(start 318.333628 -404.67026)
		(end 319.679828 -406.01646)
		(width 0.14732)
		(layer "In4.Cu")
		(net "P5E_CPU0_PE4_RX_DP<4>")
	)
	(segment
		(start 309.221378 -328.623168)
		(end 308.133496 -331.249782)
		(width 0.14732)
		(layer "In4.Cu")
		(net "P5E_CPU0_PE4_RX_DP<4>")
	)
	(segment
		(start 335.313782 -295.762934)
		(end 334.925162 -296.700702)
		(width 0.14732)
		(layer "In4.Cu")
		(net "P5E_CPU0_PE4_RX_DP<4>")
	)
	(segment
		(start 342.381078 -289.56508)
		(end 342.399112 -289.601402)
		(width 0.0889)
		(layer "In4.Cu")
		(net "P5E_CPU0_PE4_RX_DP<4>")
	)
	(segment
		(start 322.650104 -433.54117)
		(end 322.650104 -433.289964)
		(width 0.14732)
		(layer "In4.Cu")
		(net "P5E_CPU0_PE4_RX_DP<4>")
	)
	(segment
		(start 319.679828 -410.704792)
		(end 319.925192 -412.183072)
		(width 0.14732)
		(layer "In4.Cu")
		(net "P5E_CPU0_PE4_RX_DP<4>")
	)
	(segment
		(start 319.925192 -412.183072)
		(end 319.924938 -412.183072)
		(width 0.14732)
		(layer "In4.Cu")
		(net "P5E_CPU0_PE4_RX_DP<4>")
	)
	(segment
		(start 342.399112 -290.072318)
		(end 340.538054 -291.933122)
		(width 0.0889)
		(layer "In4.Cu")
		(net "P5E_CPU0_PE4_RX_DP<4>")
	)
	(segment
		(start 308.133496 -331.249782)
		(end 307.05298 -332.330298)
		(width 0.14732)
		(layer "In4.Cu")
		(net "P5E_CPU0_PE4_RX_DP<4>")
	)
	(segment
		(start 307.05298 -332.330298)
		(end 307.05298 -344.466418)
		(width 0.14732)
		(layer "In4.Cu")
		(net "P5E_CPU0_PE4_RX_DP<4>")
	)
	(segment
		(start 320.619628 -415.608516)
		(end 320.691256 -416.039554)
		(width 0.14732)
		(layer "In4.Cu")
		(net "P5E_CPU0_PE4_RX_DP<4>")
	)
	(segment
		(start 320.068194 -412.285434)
		(end 320.139822 -412.716726)
		(width 0.14732)
		(layer "In4.Cu")
		(net "P5E_CPU0_PE4_RX_DP<4>")
	)
	(segment
		(start 313.506104 -325.852028)
		(end 309.947818 -325.852028)
		(width 0.14732)
		(layer "In4.Cu")
		(net "P5E_CPU0_PE4_RX_DP<4>")
	)
	(segment
		(start 322.438522 -433.752752)
		(end 322.650104 -433.54117)
		(width 0.14732)
		(layer "In4.Cu")
		(net "P5E_CPU0_PE4_RX_DP<4>")
	)
	(segment
		(start 320.476372 -415.5059)
		(end 320.619628 -415.608516)
		(width 0.14732)
		(layer "In4.Cu")
		(net "P5E_CPU0_PE4_RX_DP<4>")
	)
	(segment
		(start 307.05298 -344.466418)
		(end 318.333628 -398.527778)
		(width 0.14732)
		(layer "In4.Cu")
		(net "P5E_CPU0_PE4_RX_DP<4>")
	)
	(segment
		(start 333.747364 -305.28768)
		(end 315.352684 -323.68236)
		(width 0.14732)
		(layer "In4.Cu")
		(net "P5E_CPU0_PE4_RX_DP<4>")
	)
	(segment
		(start 321.966844 -424.495722)
		(end 321.966844 -433.605432)
		(width 0.14732)
		(layer "In4.Cu")
		(net "P5E_CPU0_PE4_RX_DP<4>")
	)
	(segment
		(start 318.333628 -398.527778)
		(end 318.333628 -404.67026)
		(width 0.14732)
		(layer "In4.Cu")
		(net "P5E_CPU0_PE4_RX_DP<4>")
	)
	(segment
		(start 340.538054 -291.933122)
		(end 340.442296 -292.02888)
		(width 0.0889)
		(layer "In4.Cu")
		(net "P5E_CPU0_PE4_RX_DP<4>")
	)
	(segment
		(start 320.58864 -416.18281)
		(end 321.966844 -424.495722)
		(width 0.14732)
		(layer "In4.Cu")
		(net "P5E_CPU0_PE4_RX_DP<4>")
	)
	(segment
		(start 334.925162 -296.700702)
		(end 334.925162 -298.608496)
		(width 0.14732)
		(layer "In4.Cu")
		(net "P5E_CPU0_PE4_RX_DP<4>")
	)
	(segment
		(start 315.352684 -323.68236)
		(end 315.352684 -324.005448)
		(width 0.14732)
		(layer "In4.Cu")
		(net "P5E_CPU0_PE4_RX_DP<4>")
	)
	(segment
		(start 342.399112 -289.601402)
		(end 342.399112 -290.072318)
		(width 0.0889)
		(layer "In4.Cu")
		(net "P5E_CPU0_PE4_RX_DP<4>")
	)
	(segment
		(start 340.442296 -292.088824)
		(end 340.426802 -292.104318)
		(width 0.0889)
		(layer "In4.Cu")
		(net "P5E_CPU0_PE4_RX_DP<4>")
	)
	(segment
		(start 320.323464 -413.824166)
		(end 320.221102 -413.967422)
		(width 0.14732)
		(layer "In4.Cu")
		(net "P5E_CPU0_PE4_RX_DP<4>")
	)
	(segment
		(start 341.639652 -289.240722)
		(end 341.639906 -289.241484)
		(width 0.0889)
		(layer "In4.Cu")
		(net "P5E_CPU0_PE4_RX_DP<4>")
	)
	(segment
		(start 336.978752 -294.097964)
		(end 335.313782 -295.762934)
		(width 0.14732)
		(layer "In4.Cu")
		(net "P5E_CPU0_PE4_RX_DP<4>")
	)
	(segment
		(start 341.523066 -289.218116)
		(end 341.61984 -289.247834)
		(width 0.0889)
		(layer "In4.Cu")
		(net "P5E_CPU0_PE4_RX_DP<4>")
	)
	(segment
		(start 321.966844 -433.605432)
		(end 322.114164 -433.752752)
		(width 0.14732)
		(layer "In4.Cu")
		(net "P5E_CPU0_PE4_RX_DP<4>")
	)
	(segment
		(start 320.037206 -412.859728)
		(end 320.10858 -413.290512)
		(width 0.14732)
		(layer "In4.Cu")
		(net "P5E_CPU0_PE4_RX_DP<4>")
	)
	(segment
		(start 341.364316 -288.917126)
		(end 341.523066 -289.218116)
		(width 0.0889)
		(layer "In4.Cu")
		(net "P5E_CPU0_PE4_RX_DP<4>")
	)
	(segment
		(start 309.947818 -325.852028)
		(end 309.221378 -326.578468)
		(width 0.14732)
		(layer "In4.Cu")
		(net "P5E_CPU0_PE4_RX_DP<4>")
	)
	(arc
		(start 341.639906 -289.241484)
		(mid 342.073502 -289.258993)
		(end 342.381078 -289.56508)
		(width 0.0889)
		(layer "In4.Cu")
		(net "P5E_CPU0_PE4_RX_DP<4>")
	)
	(arc
		(start 341.61984 -289.247834)
		(mid 341.629715 -289.244192)
		(end 341.639652 -289.240722)
		(width 0.0889)
		(layer "In4.Cu")
		(net "P5E_CPU0_PE4_RX_DP<4>")
	)
	(segment
		(start 340.424516 -288.381186)
		(end 340.424516 -288.917126)
		(width 0.13208)
		(layer "F.Cu")
		(net "P5E_CPU0_PE4_RX_DP<3>")
	)
	(segment
		(start 341.181436 -290.068)
		(end 341.268812 -289.902138)
		(width 0.0889)
		(layer "In4.Cu")
		(net "P5E_CPU0_PE4_RX_DP<3>")
	)
	(segment
		(start 320.650108 -435.174644)
		(end 320.502534 -435.02707)
		(width 0.14732)
		(layer "In4.Cu")
		(net "P5E_CPU0_PE4_RX_DP<3>")
	)
	(segment
		(start 308.011322 -328.34072)
		(end 308.011322 -326.070214)
		(width 0.14732)
		(layer "In4.Cu")
		(net "P5E_CPU0_PE4_RX_DP<3>")
	)
	(segment
		(start 333.656432 -296.617136)
		(end 334.357726 -294.924226)
		(width 0.14732)
		(layer "In4.Cu")
		(net "P5E_CPU0_PE4_RX_DP<3>")
	)
	(segment
		(start 309.439564 -324.641972)
		(end 313.004454 -324.641972)
		(width 0.14732)
		(layer "In4.Cu")
		(net "P5E_CPU0_PE4_RX_DP<3>")
	)
	(segment
		(start 339.577934 -291.188902)
		(end 339.636862 -291.188902)
		(width 0.0889)
		(layer "In4.Cu")
		(net "P5E_CPU0_PE4_RX_DP<3>")
	)
	(segment
		(start 307.278532 -330.109576)
		(end 308.011322 -328.34072)
		(width 0.14732)
		(layer "In4.Cu")
		(net "P5E_CPU0_PE4_RX_DP<3>")
	)
	(segment
		(start 314.996068 -404.784052)
		(end 314.996068 -398.404842)
		(width 0.14732)
		(layer "In4.Cu")
		(net "P5E_CPU0_PE4_RX_DP<3>")
	)
	(segment
		(start 314.083954 -323.156326)
		(end 332.646782 -304.593498)
		(width 0.14732)
		(layer "In4.Cu")
		(net "P5E_CPU0_PE4_RX_DP<3>")
	)
	(segment
		(start 340.659212 -288.62528)
		(end 340.58098 -288.646108)
		(width 0.0889)
		(layer "In4.Cu")
		(net "P5E_CPU0_PE4_RX_DP<3>")
	)
	(segment
		(start 308.011322 -326.070214)
		(end 309.439564 -324.641972)
		(width 0.14732)
		(layer "In4.Cu")
		(net "P5E_CPU0_PE4_RX_DP<3>")
	)
	(segment
		(start 340.799166 -289.114738)
		(end 340.799166 -288.917126)
		(width 0.0889)
		(layer "In4.Cu")
		(net "P5E_CPU0_PE4_RX_DP<3>")
	)
	(segment
		(start 320.000376 -435.02707)
		(end 319.692528 -434.719222)
		(width 0.14732)
		(layer "In4.Cu")
		(net "P5E_CPU0_PE4_RX_DP<3>")
	)
	(segment
		(start 339.830664 -290.9951)
		(end 341.181436 -290.068)
		(width 0.0889)
		(layer "In4.Cu")
		(net "P5E_CPU0_PE4_RX_DP<3>")
	)
	(segment
		(start 340.58098 -288.646108)
		(end 340.424516 -288.917126)
		(width 0.0889)
		(layer "In4.Cu")
		(net "P5E_CPU0_PE4_RX_DP<3>")
	)
	(segment
		(start 314.996068 -398.404842)
		(end 305.842924 -344.718132)
		(width 0.14732)
		(layer "In4.Cu")
		(net "P5E_CPU0_PE4_RX_DP<3>")
	)
	(segment
		(start 334.357726 -294.924226)
		(end 336.452718 -292.829234)
		(width 0.14732)
		(layer "In4.Cu")
		(net "P5E_CPU0_PE4_RX_DP<3>")
	)
	(segment
		(start 341.268812 -289.902138)
		(end 341.268812 -289.645852)
		(width 0.0889)
		(layer "In4.Cu")
		(net "P5E_CPU0_PE4_RX_DP<3>")
	)
	(segment
		(start 305.842924 -331.545184)
		(end 307.278532 -330.109576)
		(width 0.14732)
		(layer "In4.Cu")
		(net "P5E_CPU0_PE4_RX_DP<3>")
	)
	(segment
		(start 305.842924 -344.718132)
		(end 305.842924 -331.545184)
		(width 0.14732)
		(layer "In4.Cu")
		(net "P5E_CPU0_PE4_RX_DP<3>")
	)
	(segment
		(start 339.56244 -291.204396)
		(end 339.577934 -291.188902)
		(width 0.0889)
		(layer "In4.Cu")
		(net "P5E_CPU0_PE4_RX_DP<3>")
	)
	(segment
		(start 319.692528 -434.719222)
		(end 319.692528 -424.518328)
		(width 0.14732)
		(layer "In4.Cu")
		(net "P5E_CPU0_PE4_RX_DP<3>")
	)
	(segment
		(start 313.004454 -324.641972)
		(end 314.083954 -323.562472)
		(width 0.14732)
		(layer "In4.Cu")
		(net "P5E_CPU0_PE4_RX_DP<3>")
	)
	(segment
		(start 337.937602 -292.829234)
		(end 339.56244 -291.204396)
		(width 0.14732)
		(layer "In4.Cu")
		(net "P5E_CPU0_PE4_RX_DP<3>")
	)
	(segment
		(start 316.342268 -406.130252)
		(end 314.996068 -404.784052)
		(width 0.14732)
		(layer "In4.Cu")
		(net "P5E_CPU0_PE4_RX_DP<3>")
	)
	(segment
		(start 314.083954 -323.562472)
		(end 314.083954 -323.156326)
		(width 0.14732)
		(layer "In4.Cu")
		(net "P5E_CPU0_PE4_RX_DP<3>")
	)
	(segment
		(start 320.502534 -435.02707)
		(end 320.000376 -435.02707)
		(width 0.14732)
		(layer "In4.Cu")
		(net "P5E_CPU0_PE4_RX_DP<3>")
	)
	(segment
		(start 336.452718 -292.829234)
		(end 337.937602 -292.829234)
		(width 0.14732)
		(layer "In4.Cu")
		(net "P5E_CPU0_PE4_RX_DP<3>")
	)
	(segment
		(start 339.636862 -291.188902)
		(end 339.830664 -290.9951)
		(width 0.0889)
		(layer "In4.Cu")
		(net "P5E_CPU0_PE4_RX_DP<3>")
	)
	(segment
		(start 316.342268 -410.719524)
		(end 316.342268 -406.130252)
		(width 0.14732)
		(layer "In4.Cu")
		(net "P5E_CPU0_PE4_RX_DP<3>")
	)
	(segment
		(start 319.692528 -424.518328)
		(end 316.342268 -410.719524)
		(width 0.14732)
		(layer "In4.Cu")
		(net "P5E_CPU0_PE4_RX_DP<3>")
	)
	(segment
		(start 333.656432 -298.869608)
		(end 333.656432 -296.617136)
		(width 0.14732)
		(layer "In4.Cu")
		(net "P5E_CPU0_PE4_RX_DP<3>")
	)
	(segment
		(start 320.650108 -435.489858)
		(end 320.650108 -435.174644)
		(width 0.14732)
		(layer "In4.Cu")
		(net "P5E_CPU0_PE4_RX_DP<3>")
	)
	(segment
		(start 332.646782 -304.593498)
		(end 333.656432 -298.869608)
		(width 0.14732)
		(layer "In4.Cu")
		(net "P5E_CPU0_PE4_RX_DP<3>")
	)
	(arc
		(start 340.799166 -288.917126)
		(mid 340.762306 -288.755329)
		(end 340.659212 -288.62528)
		(width 0.0889)
		(layer "In4.Cu")
		(net "P5E_CPU0_PE4_RX_DP<3>")
	)
	(arc
		(start 341.084662 -289.446462)
		(mid 340.91053 -289.307615)
		(end 340.799166 -289.114738)
		(width 0.0889)
		(layer "In4.Cu")
		(net "P5E_CPU0_PE4_RX_DP<3>")
	)
	(arc
		(start 341.268812 -289.645852)
		(mid 341.193807 -289.530393)
		(end 341.084662 -289.446462)
		(width 0.0889)
		(layer "In4.Cu")
		(net "P5E_CPU0_PE4_RX_DP<3>")
	)
	(segment
		(start 339.484716 -288.381186)
		(end 339.484716 -288.917126)
		(width 0.13208)
		(layer "F.Cu")
		(net "P5E_CPU0_PE4_RX_DP<2>")
	)
	(segment
		(start 307.333396 -325.806308)
		(end 307.333396 -328.111358)
		(width 0.14732)
		(layer "In4.Cu")
		(net "P5E_CPU0_PE4_RX_DP<2>")
	)
	(segment
		(start 340.082632 -290.509198)
		(end 339.240368 -290.432236)
		(width 0.0889)
		(layer "In4.Cu")
		(net "P5E_CPU0_PE4_RX_DP<2>")
	)
	(segment
		(start 314.851542 -414.490916)
		(end 314.77204 -414.647888)
		(width 0.14732)
		(layer "In4.Cu")
		(net "P5E_CPU0_PE4_RX_DP<2>")
	)
	(segment
		(start 340.519512 -290.072318)
		(end 340.082632 -290.509198)
		(width 0.0889)
		(layer "In4.Cu")
		(net "P5E_CPU0_PE4_RX_DP<2>")
	)
	(segment
		(start 314.208668 -412.928816)
		(end 314.365894 -413.008318)
		(width 0.14732)
		(layer "In4.Cu")
		(net "P5E_CPU0_PE4_RX_DP<2>")
	)
	(segment
		(start 315.551058 -416.625024)
		(end 315.471556 -416.781996)
		(width 0.14732)
		(layer "In4.Cu")
		(net "P5E_CPU0_PE4_RX_DP<2>")
	)
	(segment
		(start 339.484716 -288.917126)
		(end 339.643466 -289.218116)
		(width 0.0889)
		(layer "In4.Cu")
		(net "P5E_CPU0_PE4_RX_DP<2>")
	)
	(segment
		(start 333.820516 -294.447722)
		(end 332.984856 -296.465244)
		(width 0.14732)
		(layer "In4.Cu")
		(net "P5E_CPU0_PE4_RX_DP<2>")
	)
	(segment
		(start 317.966852 -433.605432)
		(end 318.114172 -433.752752)
		(width 0.14732)
		(layer "In4.Cu")
		(net "P5E_CPU0_PE4_RX_DP<2>")
	)
	(segment
		(start 306.637182 -329.792076)
		(end 305.164998 -331.26426)
		(width 0.14732)
		(layer "In4.Cu")
		(net "P5E_CPU0_PE4_RX_DP<2>")
	)
	(segment
		(start 314.365894 -413.008318)
		(end 314.501784 -413.423608)
		(width 0.14732)
		(layer "In4.Cu")
		(net "P5E_CPU0_PE4_RX_DP<2>")
	)
	(segment
		(start 314.715398 -414.075372)
		(end 314.851542 -414.490916)
		(width 0.14732)
		(layer "In4.Cu")
		(net "P5E_CPU0_PE4_RX_DP<2>")
	)
	(segment
		(start 315.257688 -416.129978)
		(end 315.414914 -416.20948)
		(width 0.14732)
		(layer "In4.Cu")
		(net "P5E_CPU0_PE4_RX_DP<2>")
	)
	(segment
		(start 315.414914 -416.20948)
		(end 315.551058 -416.625024)
		(width 0.14732)
		(layer "In4.Cu")
		(net "P5E_CPU0_PE4_RX_DP<2>")
	)
	(segment
		(start 305.164998 -344.728038)
		(end 312.207148 -397.745712)
		(width 0.14732)
		(layer "In4.Cu")
		(net "P5E_CPU0_PE4_RX_DP<2>")
	)
	(segment
		(start 305.164998 -331.26426)
		(end 305.164998 -344.728038)
		(width 0.14732)
		(layer "In4.Cu")
		(net "P5E_CPU0_PE4_RX_DP<2>")
	)
	(segment
		(start 313.430158 -322.860416)
		(end 311.214516 -323.77761)
		(width 0.14732)
		(layer "In4.Cu")
		(net "P5E_CPU0_PE4_RX_DP<2>")
	)
	(segment
		(start 314.558172 -413.99587)
		(end 314.715398 -414.075372)
		(width 0.14732)
		(layer "In4.Cu")
		(net "P5E_CPU0_PE4_RX_DP<2>")
	)
	(segment
		(start 318.43853 -433.752752)
		(end 318.650112 -433.54117)
		(width 0.14732)
		(layer "In4.Cu")
		(net "P5E_CPU0_PE4_RX_DP<2>")
	)
	(segment
		(start 318.650112 -433.54117)
		(end 318.650112 -433.289964)
		(width 0.14732)
		(layer "In4.Cu")
		(net "P5E_CPU0_PE4_RX_DP<2>")
	)
	(segment
		(start 313.553348 -406.01646)
		(end 313.553348 -410.92882)
		(width 0.14732)
		(layer "In4.Cu")
		(net "P5E_CPU0_PE4_RX_DP<2>")
	)
	(segment
		(start 313.553348 -410.92882)
		(end 314.208668 -412.928816)
		(width 0.14732)
		(layer "In4.Cu")
		(net "P5E_CPU0_PE4_RX_DP<2>")
	)
	(segment
		(start 314.422282 -413.580834)
		(end 314.558172 -413.99587)
		(width 0.14732)
		(layer "In4.Cu")
		(net "P5E_CPU0_PE4_RX_DP<2>")
	)
	(segment
		(start 307.333396 -328.111358)
		(end 306.637182 -329.792076)
		(width 0.14732)
		(layer "In4.Cu")
		(net "P5E_CPU0_PE4_RX_DP<2>")
	)
	(segment
		(start 309.362094 -323.77761)
		(end 307.333396 -325.806308)
		(width 0.14732)
		(layer "In4.Cu")
		(net "P5E_CPU0_PE4_RX_DP<2>")
	)
	(segment
		(start 312.207148 -404.67026)
		(end 313.553348 -406.01646)
		(width 0.14732)
		(layer "In4.Cu")
		(net "P5E_CPU0_PE4_RX_DP<2>")
	)
	(segment
		(start 339.012784 -290.719764)
		(end 338.99729 -290.735258)
		(width 0.0889)
		(layer "In4.Cu")
		(net "P5E_CPU0_PE4_RX_DP<2>")
	)
	(segment
		(start 312.207148 -397.745712)
		(end 312.207148 -404.67026)
		(width 0.14732)
		(layer "In4.Cu")
		(net "P5E_CPU0_PE4_RX_DP<2>")
	)
	(segment
		(start 315.121798 -415.714942)
		(end 315.257688 -416.129978)
		(width 0.14732)
		(layer "In4.Cu")
		(net "P5E_CPU0_PE4_RX_DP<2>")
	)
	(segment
		(start 317.966852 -424.398186)
		(end 317.966852 -433.605432)
		(width 0.14732)
		(layer "In4.Cu")
		(net "P5E_CPU0_PE4_RX_DP<2>")
	)
	(segment
		(start 315.2013 -415.55797)
		(end 315.121798 -415.714942)
		(width 0.14732)
		(layer "In4.Cu")
		(net "P5E_CPU0_PE4_RX_DP<2>")
	)
	(segment
		(start 314.90793 -415.062924)
		(end 315.065156 -415.142426)
		(width 0.14732)
		(layer "In4.Cu")
		(net "P5E_CPU0_PE4_RX_DP<2>")
	)
	(segment
		(start 332.984856 -296.465244)
		(end 332.984856 -298.438062)
		(width 0.14732)
		(layer "In4.Cu")
		(net "P5E_CPU0_PE4_RX_DP<2>")
	)
	(segment
		(start 338.99729 -290.735258)
		(end 337.660234 -292.072314)
		(width 0.14732)
		(layer "In4.Cu")
		(net "P5E_CPU0_PE4_RX_DP<2>")
	)
	(segment
		(start 337.660234 -292.072314)
		(end 336.195924 -292.072314)
		(width 0.14732)
		(layer "In4.Cu")
		(net "P5E_CPU0_PE4_RX_DP<2>")
	)
	(segment
		(start 339.012784 -290.65982)
		(end 339.012784 -290.719764)
		(width 0.0889)
		(layer "In4.Cu")
		(net "P5E_CPU0_PE4_RX_DP<2>")
	)
	(segment
		(start 331.942186 -304.34788)
		(end 313.430158 -322.860416)
		(width 0.14732)
		(layer "In4.Cu")
		(net "P5E_CPU0_PE4_RX_DP<2>")
	)
	(segment
		(start 332.984856 -298.438062)
		(end 331.942186 -304.34788)
		(width 0.14732)
		(layer "In4.Cu")
		(net "P5E_CPU0_PE4_RX_DP<2>")
	)
	(segment
		(start 314.501784 -413.423608)
		(end 314.422282 -413.580834)
		(width 0.14732)
		(layer "In4.Cu")
		(net "P5E_CPU0_PE4_RX_DP<2>")
	)
	(segment
		(start 340.519512 -289.60953)
		(end 340.519512 -290.072318)
		(width 0.0889)
		(layer "In4.Cu")
		(net "P5E_CPU0_PE4_RX_DP<2>")
	)
	(segment
		(start 315.471556 -416.781996)
		(end 317.966852 -424.398186)
		(width 0.14732)
		(layer "In4.Cu")
		(net "P5E_CPU0_PE4_RX_DP<2>")
	)
	(segment
		(start 339.643466 -289.218116)
		(end 339.74024 -289.247834)
		(width 0.0889)
		(layer "In4.Cu")
		(net "P5E_CPU0_PE4_RX_DP<2>")
	)
	(segment
		(start 336.195924 -292.072314)
		(end 333.820516 -294.447722)
		(width 0.14732)
		(layer "In4.Cu")
		(net "P5E_CPU0_PE4_RX_DP<2>")
	)
	(segment
		(start 314.77204 -414.647888)
		(end 314.90793 -415.062924)
		(width 0.14732)
		(layer "In4.Cu")
		(net "P5E_CPU0_PE4_RX_DP<2>")
	)
	(segment
		(start 318.114172 -433.752752)
		(end 318.43853 -433.752752)
		(width 0.14732)
		(layer "In4.Cu")
		(net "P5E_CPU0_PE4_RX_DP<2>")
	)
	(segment
		(start 339.240368 -290.432236)
		(end 339.012784 -290.65982)
		(width 0.0889)
		(layer "In4.Cu")
		(net "P5E_CPU0_PE4_RX_DP<2>")
	)
	(segment
		(start 315.065156 -415.142426)
		(end 315.2013 -415.55797)
		(width 0.14732)
		(layer "In4.Cu")
		(net "P5E_CPU0_PE4_RX_DP<2>")
	)
	(segment
		(start 311.214516 -323.77761)
		(end 309.362094 -323.77761)
		(width 0.14732)
		(layer "In4.Cu")
		(net "P5E_CPU0_PE4_RX_DP<2>")
	)
	(arc
		(start 339.74024 -289.247834)
		(mid 339.750115 -289.244192)
		(end 339.760052 -289.240722)
		(width 0.0889)
		(layer "In4.Cu")
		(net "P5E_CPU0_PE4_RX_DP<2>")
	)
	(arc
		(start 339.760052 -289.240722)
		(mid 340.21575 -289.268595)
		(end 340.519512 -289.60953)
		(width 0.0889)
		(layer "In4.Cu")
		(net "P5E_CPU0_PE4_RX_DP<2>")
	)
	(segment
		(start 338.544916 -288.381186)
		(end 338.544916 -288.917126)
		(width 0.13208)
		(layer "F.Cu")
		(net "P5E_CPU0_PE4_RX_DP<1>")
	)
	(segment
		(start 310.36133 -321.68084)
		(end 311.001918 -322.321428)
		(width 0.14732)
		(layer "In4.Cu")
		(net "P5E_CPU0_PE4_RX_DP<1>")
	)
	(segment
		(start 306.111148 -325.310246)
		(end 309.529734 -321.89166)
		(width 0.14732)
		(layer "In4.Cu")
		(net "P5E_CPU0_PE4_RX_DP<1>")
	)
	(segment
		(start 332.801976 -293.748714)
		(end 335.764632 -290.786058)
		(width 0.14732)
		(layer "In4.Cu")
		(net "P5E_CPU0_PE4_RX_DP<1>")
	)
	(segment
		(start 316.000384 -435.02707)
		(end 315.692536 -434.719222)
		(width 0.14732)
		(layer "In4.Cu")
		(net "P5E_CPU0_PE4_RX_DP<1>")
	)
	(segment
		(start 315.692536 -424.492928)
		(end 310.215788 -410.699204)
		(width 0.14732)
		(layer "In4.Cu")
		(net "P5E_CPU0_PE4_RX_DP<1>")
	)
	(segment
		(start 316.650116 -435.174644)
		(end 316.502542 -435.02707)
		(width 0.14732)
		(layer "In4.Cu")
		(net "P5E_CPU0_PE4_RX_DP<1>")
	)
	(segment
		(start 305.5239 -329.17638)
		(end 306.111148 -327.758806)
		(width 0.14732)
		(layer "In4.Cu")
		(net "P5E_CPU0_PE4_RX_DP<1>")
	)
	(segment
		(start 337.167982 -290.786058)
		(end 338.007452 -289.946588)
		(width 0.14732)
		(layer "In4.Cu")
		(net "P5E_CPU0_PE4_RX_DP<1>")
	)
	(segment
		(start 316.650116 -435.489858)
		(end 316.650116 -435.174644)
		(width 0.14732)
		(layer "In4.Cu")
		(net "P5E_CPU0_PE4_RX_DP<1>")
	)
	(segment
		(start 311.001918 -322.321428)
		(end 311.49544 -322.321428)
		(width 0.14732)
		(layer "In4.Cu")
		(net "P5E_CPU0_PE4_RX_DP<1>")
	)
	(segment
		(start 338.70138 -288.646108)
		(end 338.544916 -288.917126)
		(width 0.0889)
		(layer "In4.Cu")
		(net "P5E_CPU0_PE4_RX_DP<1>")
	)
	(segment
		(start 316.502542 -435.02707)
		(end 316.000384 -435.02707)
		(width 0.14732)
		(layer "In4.Cu")
		(net "P5E_CPU0_PE4_RX_DP<1>")
	)
	(segment
		(start 315.692536 -434.719222)
		(end 315.692536 -424.492928)
		(width 0.14732)
		(layer "In4.Cu")
		(net "P5E_CPU0_PE4_RX_DP<1>")
	)
	(segment
		(start 307.235606 -370.869464)
		(end 303.94275 -344.795856)
		(width 0.14732)
		(layer "In4.Cu")
		(net "P5E_CPU0_PE4_RX_DP<1>")
	)
	(segment
		(start 310.215788 -406.130252)
		(end 308.869588 -404.784052)
		(width 0.14732)
		(layer "In4.Cu")
		(net "P5E_CPU0_PE4_RX_DP<1>")
	)
	(segment
		(start 303.94275 -344.795856)
		(end 303.94275 -330.75753)
		(width 0.14732)
		(layer "In4.Cu")
		(net "P5E_CPU0_PE4_RX_DP<1>")
	)
	(segment
		(start 330.805282 -303.75606)
		(end 331.762862 -298.33062)
		(width 0.14732)
		(layer "In4.Cu")
		(net "P5E_CPU0_PE4_RX_DP<1>")
	)
	(segment
		(start 311.49544 -322.321428)
		(end 312.765948 -321.795394)
		(width 0.14732)
		(layer "In4.Cu")
		(net "P5E_CPU0_PE4_RX_DP<1>")
	)
	(segment
		(start 306.111148 -327.758806)
		(end 306.111148 -325.310246)
		(width 0.14732)
		(layer "In4.Cu")
		(net "P5E_CPU0_PE4_RX_DP<1>")
	)
	(segment
		(start 309.529734 -321.89166)
		(end 310.038242 -321.68084)
		(width 0.14732)
		(layer "In4.Cu")
		(net "P5E_CPU0_PE4_RX_DP<1>")
	)
	(segment
		(start 335.764632 -290.786058)
		(end 337.167982 -290.786058)
		(width 0.14732)
		(layer "In4.Cu")
		(net "P5E_CPU0_PE4_RX_DP<1>")
	)
	(segment
		(start 303.94275 -330.75753)
		(end 305.5239 -329.17638)
		(width 0.14732)
		(layer "In4.Cu")
		(net "P5E_CPU0_PE4_RX_DP<1>")
	)
	(segment
		(start 307.235606 -370.87048)
		(end 307.235606 -370.869464)
		(width 0.14732)
		(layer "In4.Cu")
		(net "P5E_CPU0_PE4_RX_DP<1>")
	)
	(segment
		(start 338.081874 -289.931094)
		(end 338.735162 -289.277806)
		(width 0.0889)
		(layer "In4.Cu")
		(net "P5E_CPU0_PE4_RX_DP<1>")
	)
	(segment
		(start 338.022946 -289.931094)
		(end 338.081874 -289.931094)
		(width 0.0889)
		(layer "In4.Cu")
		(net "P5E_CPU0_PE4_RX_DP<1>")
	)
	(segment
		(start 331.762862 -298.33062)
		(end 331.762862 -296.257218)
		(width 0.14732)
		(layer "In4.Cu")
		(net "P5E_CPU0_PE4_RX_DP<1>")
	)
	(segment
		(start 338.919566 -289.077908)
		(end 338.919566 -288.917126)
		(width 0.0889)
		(layer "In4.Cu")
		(net "P5E_CPU0_PE4_RX_DP<1>")
	)
	(segment
		(start 308.869588 -404.784052)
		(end 308.869588 -399.782284)
		(width 0.14732)
		(layer "In4.Cu")
		(net "P5E_CPU0_PE4_RX_DP<1>")
	)
	(segment
		(start 310.215788 -410.699204)
		(end 310.215788 -406.130252)
		(width 0.14732)
		(layer "In4.Cu")
		(net "P5E_CPU0_PE4_RX_DP<1>")
	)
	(segment
		(start 308.869588 -399.782284)
		(end 307.235606 -370.87048)
		(width 0.14732)
		(layer "In4.Cu")
		(net "P5E_CPU0_PE4_RX_DP<1>")
	)
	(segment
		(start 310.038242 -321.68084)
		(end 310.36133 -321.68084)
		(width 0.14732)
		(layer "In4.Cu")
		(net "P5E_CPU0_PE4_RX_DP<1>")
	)
	(segment
		(start 338.007452 -289.946588)
		(end 338.022946 -289.931094)
		(width 0.0889)
		(layer "In4.Cu")
		(net "P5E_CPU0_PE4_RX_DP<1>")
	)
	(segment
		(start 331.762862 -296.257218)
		(end 332.801976 -293.748714)
		(width 0.14732)
		(layer "In4.Cu")
		(net "P5E_CPU0_PE4_RX_DP<1>")
	)
	(segment
		(start 338.779612 -288.62528)
		(end 338.70138 -288.646108)
		(width 0.0889)
		(layer "In4.Cu")
		(net "P5E_CPU0_PE4_RX_DP<1>")
	)
	(segment
		(start 312.765948 -321.795394)
		(end 330.805282 -303.75606)
		(width 0.14732)
		(layer "In4.Cu")
		(net "P5E_CPU0_PE4_RX_DP<1>")
	)
	(arc
		(start 338.919566 -288.917126)
		(mid 338.882706 -288.755329)
		(end 338.779612 -288.62528)
		(width 0.0889)
		(layer "In4.Cu")
		(net "P5E_CPU0_PE4_RX_DP<1>")
	)
	(arc
		(start 338.735162 -289.277806)
		(mid 338.844558 -289.193709)
		(end 338.919566 -289.077908)
		(width 0.0889)
		(layer "In4.Cu")
		(net "P5E_CPU0_PE4_RX_DP<1>")
	)
	(segment
		(start 351.702116 -288.381186)
		(end 351.702116 -288.917126)
		(width 0.13208)
		(layer "F.Cu")
		(net "P5E_CPU0_PE4_RX_DP<15>")
	)
	(segment
		(start 351.85858 -288.646108)
		(end 351.702116 -288.917126)
		(width 0.0889)
		(layer "In4.Cu")
		(net "P5E_CPU0_PE4_RX_DP<15>")
	)
	(segment
		(start 351.936812 -288.62528)
		(end 351.85858 -288.646108)
		(width 0.0889)
		(layer "In4.Cu")
		(net "P5E_CPU0_PE4_RX_DP<15>")
	)
	(segment
		(start 344.692224 -434.718714)
		(end 344.692224 -424.348402)
		(width 0.14732)
		(layer "In4.Cu")
		(net "P5E_CPU0_PE4_RX_DP<15>")
	)
	(segment
		(start 317.191898 -336.359754)
		(end 349.674942 -303.87671)
		(width 0.14732)
		(layer "In4.Cu")
		(net "P5E_CPU0_PE4_RX_DP<15>")
	)
	(segment
		(start 347.060266 -420.351712)
		(end 353.101148 -410.483558)
		(width 0.14732)
		(layer "In4.Cu")
		(net "P5E_CPU0_PE4_RX_DP<15>")
	)
	(segment
		(start 344.692224 -424.348402)
		(end 344.936318 -423.820336)
		(width 0.14732)
		(layer "In4.Cu")
		(net "P5E_CPU0_PE4_RX_DP<15>")
	)
	(segment
		(start 352.546412 -291.060124)
		(end 352.546412 -289.645852)
		(width 0.0889)
		(layer "In4.Cu")
		(net "P5E_CPU0_PE4_RX_DP<15>")
	)
	(segment
		(start 349.674942 -303.87671)
		(end 350.7994 -297.499278)
		(width 0.14732)
		(layer "In4.Cu")
		(net "P5E_CPU0_PE4_RX_DP<15>")
	)
	(segment
		(start 347.059758 -420.351458)
		(end 347.060266 -420.351712)
		(width 0.14732)
		(layer "In4.Cu")
		(net "P5E_CPU0_PE4_RX_DP<15>")
	)
	(segment
		(start 317.191898 -342.268048)
		(end 317.191898 -336.359754)
		(width 0.14732)
		(layer "In4.Cu")
		(net "P5E_CPU0_PE4_RX_DP<15>")
	)
	(segment
		(start 344.936318 -423.820336)
		(end 347.059758 -420.351458)
		(width 0.14732)
		(layer "In4.Cu")
		(net "P5E_CPU0_PE4_RX_DP<15>")
	)
	(segment
		(start 345.502484 -435.02707)
		(end 345.00058 -435.02707)
		(width 0.14732)
		(layer "In4.Cu")
		(net "P5E_CPU0_PE4_RX_DP<15>")
	)
	(segment
		(start 350.7994 -297.499278)
		(end 350.7994 -293.633906)
		(width 0.14732)
		(layer "In4.Cu")
		(net "P5E_CPU0_PE4_RX_DP<15>")
	)
	(segment
		(start 352.076766 -289.114738)
		(end 352.076766 -288.917126)
		(width 0.0889)
		(layer "In4.Cu")
		(net "P5E_CPU0_PE4_RX_DP<15>")
	)
	(segment
		(start 350.84131 -293.569898)
		(end 350.84131 -292.765226)
		(width 0.0889)
		(layer "In4.Cu")
		(net "P5E_CPU0_PE4_RX_DP<15>")
	)
	(segment
		(start 345.00058 -435.02707)
		(end 344.692224 -434.718714)
		(width 0.14732)
		(layer "In4.Cu")
		(net "P5E_CPU0_PE4_RX_DP<15>")
	)
	(segment
		(start 345.650058 -435.489858)
		(end 345.650058 -435.174644)
		(width 0.14732)
		(layer "In4.Cu")
		(net "P5E_CPU0_PE4_RX_DP<15>")
	)
	(segment
		(start 351.57918 -400.012662)
		(end 350.088962 -397.900144)
		(width 0.14732)
		(layer "In4.Cu")
		(net "P5E_CPU0_PE4_RX_DP<15>")
	)
	(segment
		(start 345.650058 -435.174644)
		(end 345.502484 -435.02707)
		(width 0.14732)
		(layer "In4.Cu")
		(net "P5E_CPU0_PE4_RX_DP<15>")
	)
	(segment
		(start 350.7994 -293.633906)
		(end 350.7994 -293.611808)
		(width 0.0889)
		(layer "In4.Cu")
		(net "P5E_CPU0_PE4_RX_DP<15>")
	)
	(segment
		(start 350.84131 -292.765226)
		(end 352.546412 -291.060124)
		(width 0.0889)
		(layer "In4.Cu")
		(net "P5E_CPU0_PE4_RX_DP<15>")
	)
	(segment
		(start 352.006916 -401.193254)
		(end 351.57918 -400.012662)
		(width 0.14732)
		(layer "In4.Cu")
		(net "P5E_CPU0_PE4_RX_DP<15>")
	)
	(segment
		(start 353.101148 -410.483558)
		(end 353.101148 -406.694132)
		(width 0.14732)
		(layer "In4.Cu")
		(net "P5E_CPU0_PE4_RX_DP<15>")
	)
	(segment
		(start 353.101148 -406.694132)
		(end 352.006916 -401.193254)
		(width 0.14732)
		(layer "In4.Cu")
		(net "P5E_CPU0_PE4_RX_DP<15>")
	)
	(segment
		(start 350.088962 -397.900144)
		(end 317.191898 -342.268048)
		(width 0.14732)
		(layer "In4.Cu")
		(net "P5E_CPU0_PE4_RX_DP<15>")
	)
	(segment
		(start 350.7994 -293.611808)
		(end 350.84131 -293.569898)
		(width 0.0889)
		(layer "In4.Cu")
		(net "P5E_CPU0_PE4_RX_DP<15>")
	)
	(arc
		(start 352.362262 -289.446462)
		(mid 352.18813 -289.307615)
		(end 352.076766 -289.114738)
		(width 0.0889)
		(layer "In4.Cu")
		(net "P5E_CPU0_PE4_RX_DP<15>")
	)
	(arc
		(start 352.076766 -288.917126)
		(mid 352.039906 -288.755329)
		(end 351.936812 -288.62528)
		(width 0.0889)
		(layer "In4.Cu")
		(net "P5E_CPU0_PE4_RX_DP<15>")
	)
	(arc
		(start 352.546412 -289.645852)
		(mid 352.471407 -289.530393)
		(end 352.362262 -289.446462)
		(width 0.0889)
		(layer "In4.Cu")
		(net "P5E_CPU0_PE4_RX_DP<15>")
	)
	(segment
		(start 350.762316 -288.381186)
		(end 350.762316 -288.917126)
		(width 0.13208)
		(layer "F.Cu")
		(net "P5E_CPU0_PE4_RX_DP<14>")
	)
	(segment
		(start 345.304872 -420.129716)
		(end 345.363292 -420.318438)
		(width 0.14732)
		(layer "In4.Cu")
		(net "P5E_CPU0_PE4_RX_DP<14>")
	)
	(segment
		(start 345.191588 -420.644574)
		(end 345.002612 -420.702994)
		(width 0.14732)
		(layer "In4.Cu")
		(net "P5E_CPU0_PE4_RX_DP<14>")
	)
	(segment
		(start 345.363292 -420.318438)
		(end 345.191588 -420.644574)
		(width 0.14732)
		(layer "In4.Cu")
		(net "P5E_CPU0_PE4_RX_DP<14>")
	)
	(segment
		(start 345.002612 -420.702994)
		(end 344.830908 -421.028622)
		(width 0.14732)
		(layer "In4.Cu")
		(net "P5E_CPU0_PE4_RX_DP<14>")
	)
	(segment
		(start 351.796858 -289.610292)
		(end 351.796858 -290.852352)
		(width 0.0889)
		(layer "In4.Cu")
		(net "P5E_CPU0_PE4_RX_DP<14>")
	)
	(segment
		(start 343.650062 -433.54117)
		(end 343.650062 -433.289964)
		(width 0.14732)
		(layer "In4.Cu")
		(net "P5E_CPU0_PE4_RX_DP<14>")
	)
	(segment
		(start 344.528648 -421.601646)
		(end 343.912952 -422.769284)
		(width 0.14732)
		(layer "In4.Cu")
		(net "P5E_CPU0_PE4_RX_DP<14>")
	)
	(segment
		(start 350.101916 -293.569644)
		(end 350.14408 -293.611808)
		(width 0.0889)
		(layer "In4.Cu")
		(net "P5E_CPU0_PE4_RX_DP<14>")
	)
	(segment
		(start 343.43848 -433.752752)
		(end 343.650062 -433.54117)
		(width 0.14732)
		(layer "In4.Cu")
		(net "P5E_CPU0_PE4_RX_DP<14>")
	)
	(segment
		(start 343.912952 -422.769284)
		(end 343.971372 -422.958006)
		(width 0.14732)
		(layer "In4.Cu")
		(net "P5E_CPU0_PE4_RX_DP<14>")
	)
	(segment
		(start 351.796858 -290.852352)
		(end 350.101916 -292.547294)
		(width 0.0889)
		(layer "In4.Cu")
		(net "P5E_CPU0_PE4_RX_DP<14>")
	)
	(segment
		(start 350.14408 -297.283124)
		(end 349.031814 -303.592992)
		(width 0.14732)
		(layer "In4.Cu")
		(net "P5E_CPU0_PE4_RX_DP<14>")
	)
	(segment
		(start 350.921066 -289.218116)
		(end 351.01784 -289.247834)
		(width 0.0889)
		(layer "In4.Cu")
		(net "P5E_CPU0_PE4_RX_DP<14>")
	)
	(segment
		(start 342.967056 -433.572412)
		(end 343.147396 -433.752752)
		(width 0.14732)
		(layer "In4.Cu")
		(net "P5E_CPU0_PE4_RX_DP<14>")
	)
	(segment
		(start 342.967056 -424.563032)
		(end 342.967056 -433.572412)
		(width 0.14732)
		(layer "In4.Cu")
		(net "P5E_CPU0_PE4_RX_DP<14>")
	)
	(segment
		(start 350.762316 -288.917126)
		(end 350.921066 -289.218116)
		(width 0.0889)
		(layer "In4.Cu")
		(net "P5E_CPU0_PE4_RX_DP<14>")
	)
	(segment
		(start 316.536578 -342.553036)
		(end 348.295976 -399.06448)
		(width 0.14732)
		(layer "In4.Cu")
		(net "P5E_CPU0_PE4_RX_DP<14>")
	)
	(segment
		(start 343.147396 -433.752752)
		(end 343.43848 -433.752752)
		(width 0.14732)
		(layer "In4.Cu")
		(net "P5E_CPU0_PE4_RX_DP<14>")
	)
	(segment
		(start 350.312228 -410.634434)
		(end 345.304872 -420.129716)
		(width 0.14732)
		(layer "In4.Cu")
		(net "P5E_CPU0_PE4_RX_DP<14>")
	)
	(segment
		(start 350.14408 -293.633906)
		(end 350.14408 -297.283124)
		(width 0.14732)
		(layer "In4.Cu")
		(net "P5E_CPU0_PE4_RX_DP<14>")
	)
	(segment
		(start 343.971372 -422.958006)
		(end 343.799668 -423.284142)
		(width 0.14732)
		(layer "In4.Cu")
		(net "P5E_CPU0_PE4_RX_DP<14>")
	)
	(segment
		(start 344.717624 -421.543226)
		(end 344.528648 -421.601646)
		(width 0.14732)
		(layer "In4.Cu")
		(net "P5E_CPU0_PE4_RX_DP<14>")
	)
	(segment
		(start 343.610692 -423.342562)
		(end 342.967056 -424.563032)
		(width 0.14732)
		(layer "In4.Cu")
		(net "P5E_CPU0_PE4_RX_DP<14>")
	)
	(segment
		(start 348.295976 -399.06448)
		(end 348.966028 -400.365468)
		(width 0.14732)
		(layer "In4.Cu")
		(net "P5E_CPU0_PE4_RX_DP<14>")
	)
	(segment
		(start 344.830908 -421.028622)
		(end 344.889328 -421.217344)
		(width 0.14732)
		(layer "In4.Cu")
		(net "P5E_CPU0_PE4_RX_DP<14>")
	)
	(segment
		(start 350.14408 -293.611808)
		(end 350.14408 -293.633906)
		(width 0.0889)
		(layer "In4.Cu")
		(net "P5E_CPU0_PE4_RX_DP<14>")
	)
	(segment
		(start 350.312228 -406.01646)
		(end 350.312228 -410.634434)
		(width 0.14732)
		(layer "In4.Cu")
		(net "P5E_CPU0_PE4_RX_DP<14>")
	)
	(segment
		(start 348.966028 -400.365468)
		(end 348.966028 -404.67026)
		(width 0.14732)
		(layer "In4.Cu")
		(net "P5E_CPU0_PE4_RX_DP<14>")
	)
	(segment
		(start 348.966028 -404.67026)
		(end 350.312228 -406.01646)
		(width 0.14732)
		(layer "In4.Cu")
		(net "P5E_CPU0_PE4_RX_DP<14>")
	)
	(segment
		(start 349.031814 -303.592992)
		(end 316.536578 -336.088228)
		(width 0.14732)
		(layer "In4.Cu")
		(net "P5E_CPU0_PE4_RX_DP<14>")
	)
	(segment
		(start 350.101916 -292.547294)
		(end 350.101916 -293.569644)
		(width 0.0889)
		(layer "In4.Cu")
		(net "P5E_CPU0_PE4_RX_DP<14>")
	)
	(segment
		(start 344.889328 -421.217344)
		(end 344.717624 -421.543226)
		(width 0.14732)
		(layer "In4.Cu")
		(net "P5E_CPU0_PE4_RX_DP<14>")
	)
	(segment
		(start 343.799668 -423.284142)
		(end 343.610692 -423.342562)
		(width 0.14732)
		(layer "In4.Cu")
		(net "P5E_CPU0_PE4_RX_DP<14>")
	)
	(segment
		(start 316.536578 -336.088228)
		(end 316.536578 -342.553036)
		(width 0.14732)
		(layer "In4.Cu")
		(net "P5E_CPU0_PE4_RX_DP<14>")
	)
	(arc
		(start 351.037906 -289.241484)
		(mid 351.493426 -289.26931)
		(end 351.796858 -289.610292)
		(width 0.0889)
		(layer "In4.Cu")
		(net "P5E_CPU0_PE4_RX_DP<14>")
	)
	(arc
		(start 351.01784 -289.247834)
		(mid 351.027715 -289.244192)
		(end 351.037652 -289.240722)
		(width 0.0889)
		(layer "In4.Cu")
		(net "P5E_CPU0_PE4_RX_DP<14>")
	)
	(arc
		(start 351.037652 -289.240722)
		(mid 351.037759 -289.24111)
		(end 351.037906 -289.241484)
		(width 0.0889)
		(layer "In4.Cu")
		(net "P5E_CPU0_PE4_RX_DP<14>")
	)
	(segment
		(start 349.822516 -288.381186)
		(end 349.822516 -288.917126)
		(width 0.13208)
		(layer "F.Cu")
		(net "P5E_CPU0_PE4_RX_DP<13>")
	)
	(segment
		(start 350.197166 -289.114738)
		(end 350.197166 -288.917126)
		(width 0.0889)
		(layer "In4.Cu")
		(net "P5E_CPU0_PE4_RX_DP<13>")
	)
	(segment
		(start 341.502492 -435.02707)
		(end 341.000588 -435.02707)
		(width 0.14732)
		(layer "In4.Cu")
		(net "P5E_CPU0_PE4_RX_DP<13>")
	)
	(segment
		(start 347.194632 -303.677066)
		(end 348.302326 -297.397424)
		(width 0.14732)
		(layer "In4.Cu")
		(net "P5E_CPU0_PE4_RX_DP<13>")
	)
	(segment
		(start 345.162632 -399.639028)
		(end 315.297312 -342.94445)
		(width 0.14732)
		(layer "In4.Cu")
		(net "P5E_CPU0_PE4_RX_DP<13>")
	)
	(segment
		(start 348.302326 -292.983666)
		(end 348.302326 -292.961568)
		(width 0.0889)
		(layer "In4.Cu")
		(net "P5E_CPU0_PE4_RX_DP<13>")
	)
	(segment
		(start 348.344236 -292.919658)
		(end 348.344236 -292.704774)
		(width 0.0889)
		(layer "In4.Cu")
		(net "P5E_CPU0_PE4_RX_DP<13>")
	)
	(segment
		(start 350.057212 -288.62528)
		(end 349.97898 -288.646108)
		(width 0.0889)
		(layer "In4.Cu")
		(net "P5E_CPU0_PE4_RX_DP<13>")
	)
	(segment
		(start 315.297312 -342.94445)
		(end 315.297312 -335.574386)
		(width 0.14732)
		(layer "In4.Cu")
		(net "P5E_CPU0_PE4_RX_DP<13>")
	)
	(segment
		(start 346.974668 -410.735526)
		(end 346.974668 -406.130252)
		(width 0.14732)
		(layer "In4.Cu")
		(net "P5E_CPU0_PE4_RX_DP<13>")
	)
	(segment
		(start 340.692232 -424.377358)
		(end 346.974668 -410.735526)
		(width 0.14732)
		(layer "In4.Cu")
		(net "P5E_CPU0_PE4_RX_DP<13>")
	)
	(segment
		(start 349.97898 -288.646108)
		(end 349.822516 -288.917126)
		(width 0.0889)
		(layer "In4.Cu")
		(net "P5E_CPU0_PE4_RX_DP<13>")
	)
	(segment
		(start 348.344236 -292.704774)
		(end 350.666812 -290.382198)
		(width 0.0889)
		(layer "In4.Cu")
		(net "P5E_CPU0_PE4_RX_DP<13>")
	)
	(segment
		(start 341.650066 -435.489858)
		(end 341.650066 -435.174644)
		(width 0.14732)
		(layer "In4.Cu")
		(net "P5E_CPU0_PE4_RX_DP<13>")
	)
	(segment
		(start 345.628468 -404.784052)
		(end 345.628468 -400.380454)
		(width 0.14732)
		(layer "In4.Cu")
		(net "P5E_CPU0_PE4_RX_DP<13>")
	)
	(segment
		(start 348.302326 -297.397424)
		(end 348.302326 -292.983666)
		(width 0.14732)
		(layer "In4.Cu")
		(net "P5E_CPU0_PE4_RX_DP<13>")
	)
	(segment
		(start 315.297312 -335.574386)
		(end 347.194632 -303.677066)
		(width 0.14732)
		(layer "In4.Cu")
		(net "P5E_CPU0_PE4_RX_DP<13>")
	)
	(segment
		(start 348.302326 -292.961568)
		(end 348.344236 -292.919658)
		(width 0.0889)
		(layer "In4.Cu")
		(net "P5E_CPU0_PE4_RX_DP<13>")
	)
	(segment
		(start 346.974668 -406.130252)
		(end 345.628468 -404.784052)
		(width 0.14732)
		(layer "In4.Cu")
		(net "P5E_CPU0_PE4_RX_DP<13>")
	)
	(segment
		(start 350.666812 -290.382198)
		(end 350.666812 -289.645852)
		(width 0.0889)
		(layer "In4.Cu")
		(net "P5E_CPU0_PE4_RX_DP<13>")
	)
	(segment
		(start 340.692232 -434.718714)
		(end 340.692232 -424.377358)
		(width 0.14732)
		(layer "In4.Cu")
		(net "P5E_CPU0_PE4_RX_DP<13>")
	)
	(segment
		(start 341.000588 -435.02707)
		(end 340.692232 -434.718714)
		(width 0.14732)
		(layer "In4.Cu")
		(net "P5E_CPU0_PE4_RX_DP<13>")
	)
	(segment
		(start 341.650066 -435.174644)
		(end 341.502492 -435.02707)
		(width 0.14732)
		(layer "In4.Cu")
		(net "P5E_CPU0_PE4_RX_DP<13>")
	)
	(segment
		(start 345.628468 -400.380454)
		(end 345.162632 -399.639028)
		(width 0.14732)
		(layer "In4.Cu")
		(net "P5E_CPU0_PE4_RX_DP<13>")
	)
	(arc
		(start 350.666812 -289.645852)
		(mid 350.591807 -289.530393)
		(end 350.482662 -289.446462)
		(width 0.0889)
		(layer "In4.Cu")
		(net "P5E_CPU0_PE4_RX_DP<13>")
	)
	(arc
		(start 350.197166 -288.917126)
		(mid 350.160306 -288.755329)
		(end 350.057212 -288.62528)
		(width 0.0889)
		(layer "In4.Cu")
		(net "P5E_CPU0_PE4_RX_DP<13>")
	)
	(arc
		(start 350.482662 -289.446462)
		(mid 350.30853 -289.307615)
		(end 350.197166 -289.114738)
		(width 0.0889)
		(layer "In4.Cu")
		(net "P5E_CPU0_PE4_RX_DP<13>")
	)
	(segment
		(start 348.882716 -288.381186)
		(end 348.882716 -288.917126)
		(width 0.13208)
		(layer "F.Cu")
		(net "P5E_CPU0_PE4_RX_DP<12>")
	)
	(segment
		(start 338.96681 -424.552872)
		(end 338.96681 -433.585112)
		(width 0.14732)
		(layer "In4.Cu")
		(net "P5E_CPU0_PE4_RX_DP<12>")
	)
	(segment
		(start 339.13445 -433.752752)
		(end 339.472016 -433.752752)
		(width 0.14732)
		(layer "In4.Cu")
		(net "P5E_CPU0_PE4_RX_DP<12>")
	)
	(segment
		(start 314.636912 -343.09558)
		(end 342.839548 -399.950432)
		(width 0.14732)
		(layer "In4.Cu")
		(net "P5E_CPU0_PE4_RX_DP<12>")
	)
	(segment
		(start 340.379812 -420.801292)
		(end 340.109556 -421.51935)
		(width 0.14732)
		(layer "In4.Cu")
		(net "P5E_CPU0_PE4_RX_DP<12>")
	)
	(segment
		(start 342.839548 -404.67026)
		(end 344.185748 -406.01646)
		(width 0.14732)
		(layer "In4.Cu")
		(net "P5E_CPU0_PE4_RX_DP<12>")
	)
	(segment
		(start 339.472016 -433.752752)
		(end 339.65007 -433.574698)
		(width 0.14732)
		(layer "In4.Cu")
		(net "P5E_CPU0_PE4_RX_DP<12>")
	)
	(segment
		(start 347.599762 -292.901624)
		(end 347.641926 -292.943788)
		(width 0.0889)
		(layer "In4.Cu")
		(net "P5E_CPU0_PE4_RX_DP<12>")
	)
	(segment
		(start 347.599762 -292.765988)
		(end 347.599762 -292.901624)
		(width 0.0889)
		(layer "In4.Cu")
		(net "P5E_CPU0_PE4_RX_DP<12>")
	)
	(segment
		(start 347.641926 -292.943788)
		(end 347.641926 -292.965886)
		(width 0.0889)
		(layer "In4.Cu")
		(net "P5E_CPU0_PE4_RX_DP<12>")
	)
	(segment
		(start 347.641926 -297.339512)
		(end 346.580206 -303.35728)
		(width 0.14732)
		(layer "In4.Cu")
		(net "P5E_CPU0_PE4_RX_DP<12>")
	)
	(segment
		(start 339.504528 -423.125138)
		(end 338.96681 -424.552872)
		(width 0.14732)
		(layer "In4.Cu")
		(net "P5E_CPU0_PE4_RX_DP<12>")
	)
	(segment
		(start 339.65007 -433.574698)
		(end 339.65007 -433.289964)
		(width 0.14732)
		(layer "In4.Cu")
		(net "P5E_CPU0_PE4_RX_DP<12>")
	)
	(segment
		(start 346.580206 -303.35728)
		(end 314.636912 -335.300574)
		(width 0.14732)
		(layer "In4.Cu")
		(net "P5E_CPU0_PE4_RX_DP<12>")
	)
	(segment
		(start 339.814408 -422.698672)
		(end 339.684614 -423.043604)
		(width 0.14732)
		(layer "In4.Cu")
		(net "P5E_CPU0_PE4_RX_DP<12>")
	)
	(segment
		(start 344.185748 -410.696664)
		(end 340.608412 -420.194994)
		(width 0.14732)
		(layer "In4.Cu")
		(net "P5E_CPU0_PE4_RX_DP<12>")
	)
	(segment
		(start 339.88121 -422.125648)
		(end 339.733128 -422.51884)
		(width 0.14732)
		(layer "In4.Cu")
		(net "P5E_CPU0_PE4_RX_DP<12>")
	)
	(segment
		(start 344.185748 -406.01646)
		(end 344.185748 -410.696664)
		(width 0.14732)
		(layer "In4.Cu")
		(net "P5E_CPU0_PE4_RX_DP<12>")
	)
	(segment
		(start 339.733128 -422.51884)
		(end 339.814408 -422.698672)
		(width 0.14732)
		(layer "In4.Cu")
		(net "P5E_CPU0_PE4_RX_DP<12>")
	)
	(segment
		(start 348.882716 -288.917126)
		(end 349.041466 -289.218116)
		(width 0.0889)
		(layer "In4.Cu")
		(net "P5E_CPU0_PE4_RX_DP<12>")
	)
	(segment
		(start 340.560152 -420.720012)
		(end 340.379812 -420.801292)
		(width 0.14732)
		(layer "In4.Cu")
		(net "P5E_CPU0_PE4_RX_DP<12>")
	)
	(segment
		(start 340.689946 -420.37508)
		(end 340.560152 -420.720012)
		(width 0.14732)
		(layer "In4.Cu")
		(net "P5E_CPU0_PE4_RX_DP<12>")
	)
	(segment
		(start 340.19109 -421.699182)
		(end 340.061296 -422.044114)
		(width 0.14732)
		(layer "In4.Cu")
		(net "P5E_CPU0_PE4_RX_DP<12>")
	)
	(segment
		(start 340.109556 -421.51935)
		(end 340.19109 -421.699182)
		(width 0.14732)
		(layer "In4.Cu")
		(net "P5E_CPU0_PE4_RX_DP<12>")
	)
	(segment
		(start 347.641926 -292.965886)
		(end 347.641926 -297.339512)
		(width 0.14732)
		(layer "In4.Cu")
		(net "P5E_CPU0_PE4_RX_DP<12>")
	)
	(segment
		(start 349.041466 -289.218116)
		(end 349.13824 -289.247834)
		(width 0.0889)
		(layer "In4.Cu")
		(net "P5E_CPU0_PE4_RX_DP<12>")
	)
	(segment
		(start 342.839548 -399.950432)
		(end 342.839548 -404.67026)
		(width 0.14732)
		(layer "In4.Cu")
		(net "P5E_CPU0_PE4_RX_DP<12>")
	)
	(segment
		(start 338.96681 -433.585112)
		(end 339.13445 -433.752752)
		(width 0.14732)
		(layer "In4.Cu")
		(net "P5E_CPU0_PE4_RX_DP<12>")
	)
	(segment
		(start 340.608412 -420.194994)
		(end 340.689946 -420.37508)
		(width 0.14732)
		(layer "In4.Cu")
		(net "P5E_CPU0_PE4_RX_DP<12>")
	)
	(segment
		(start 349.917512 -290.448238)
		(end 347.599762 -292.765988)
		(width 0.0889)
		(layer "In4.Cu")
		(net "P5E_CPU0_PE4_RX_DP<12>")
	)
	(segment
		(start 314.636912 -335.300574)
		(end 314.636912 -343.09558)
		(width 0.14732)
		(layer "In4.Cu")
		(net "P5E_CPU0_PE4_RX_DP<12>")
	)
	(segment
		(start 349.917512 -289.60953)
		(end 349.917512 -290.448238)
		(width 0.0889)
		(layer "In4.Cu")
		(net "P5E_CPU0_PE4_RX_DP<12>")
	)
	(segment
		(start 339.684614 -423.043604)
		(end 339.504528 -423.125138)
		(width 0.14732)
		(layer "In4.Cu")
		(net "P5E_CPU0_PE4_RX_DP<12>")
	)
	(segment
		(start 340.061296 -422.044114)
		(end 339.88121 -422.125648)
		(width 0.14732)
		(layer "In4.Cu")
		(net "P5E_CPU0_PE4_RX_DP<12>")
	)
	(arc
		(start 349.13824 -289.247834)
		(mid 349.148115 -289.244192)
		(end 349.158052 -289.240722)
		(width 0.0889)
		(layer "In4.Cu")
		(net "P5E_CPU0_PE4_RX_DP<12>")
	)
	(arc
		(start 349.158052 -289.240722)
		(mid 349.613894 -289.26845)
		(end 349.917512 -289.60953)
		(width 0.0889)
		(layer "In4.Cu")
		(net "P5E_CPU0_PE4_RX_DP<12>")
	)
	(segment
		(start 347.942916 -288.381186)
		(end 347.942916 -288.917126)
		(width 0.13208)
		(layer "F.Cu")
		(net "P5E_CPU0_PE4_RX_DP<11>")
	)
	(segment
		(start 340.848188 -406.130252)
		(end 339.501988 -404.784052)
		(width 0.14732)
		(layer "In4.Cu")
		(net "P5E_CPU0_PE4_RX_DP<11>")
	)
	(segment
		(start 345.45524 -302.77181)
		(end 346.432886 -297.23334)
		(width 0.14732)
		(layer "In4.Cu")
		(net "P5E_CPU0_PE4_RX_DP<11>")
	)
	(segment
		(start 337.5025 -435.02707)
		(end 337.074002 -435.02707)
		(width 0.14732)
		(layer "In4.Cu")
		(net "P5E_CPU0_PE4_RX_DP<11>")
	)
	(segment
		(start 348.09938 -288.646108)
		(end 347.942916 -288.917126)
		(width 0.0889)
		(layer "In4.Cu")
		(net "P5E_CPU0_PE4_RX_DP<11>")
	)
	(segment
		(start 348.787212 -290.326318)
		(end 348.787212 -289.645852)
		(width 0.0889)
		(layer "In4.Cu")
		(net "P5E_CPU0_PE4_RX_DP<11>")
	)
	(segment
		(start 313.40425 -334.8228)
		(end 345.45524 -302.77181)
		(width 0.14732)
		(layer "In4.Cu")
		(net "P5E_CPU0_PE4_RX_DP<11>")
	)
	(segment
		(start 339.501988 -400.128232)
		(end 313.40425 -343.341452)
		(width 0.14732)
		(layer "In4.Cu")
		(net "P5E_CPU0_PE4_RX_DP<11>")
	)
	(segment
		(start 346.432886 -292.895528)
		(end 346.474796 -292.853618)
		(width 0.0889)
		(layer "In4.Cu")
		(net "P5E_CPU0_PE4_RX_DP<11>")
	)
	(segment
		(start 313.40425 -343.341452)
		(end 313.40425 -334.8228)
		(width 0.14732)
		(layer "In4.Cu")
		(net "P5E_CPU0_PE4_RX_DP<11>")
	)
	(segment
		(start 336.692494 -434.645562)
		(end 336.692494 -424.501564)
		(width 0.14732)
		(layer "In4.Cu")
		(net "P5E_CPU0_PE4_RX_DP<11>")
	)
	(segment
		(start 346.432886 -297.23334)
		(end 346.432886 -292.917626)
		(width 0.14732)
		(layer "In4.Cu")
		(net "P5E_CPU0_PE4_RX_DP<11>")
	)
	(segment
		(start 337.650074 -435.489858)
		(end 337.650074 -435.174644)
		(width 0.14732)
		(layer "In4.Cu")
		(net "P5E_CPU0_PE4_RX_DP<11>")
	)
	(segment
		(start 340.848188 -410.855414)
		(end 340.848188 -406.130252)
		(width 0.14732)
		(layer "In4.Cu")
		(net "P5E_CPU0_PE4_RX_DP<11>")
	)
	(segment
		(start 346.432886 -292.917626)
		(end 346.432886 -292.895528)
		(width 0.0889)
		(layer "In4.Cu")
		(net "P5E_CPU0_PE4_RX_DP<11>")
	)
	(segment
		(start 337.650074 -435.174644)
		(end 337.5025 -435.02707)
		(width 0.14732)
		(layer "In4.Cu")
		(net "P5E_CPU0_PE4_RX_DP<11>")
	)
	(segment
		(start 346.474796 -292.638734)
		(end 348.787212 -290.326318)
		(width 0.0889)
		(layer "In4.Cu")
		(net "P5E_CPU0_PE4_RX_DP<11>")
	)
	(segment
		(start 348.317566 -289.114738)
		(end 348.317566 -288.917126)
		(width 0.0889)
		(layer "In4.Cu")
		(net "P5E_CPU0_PE4_RX_DP<11>")
	)
	(segment
		(start 339.501988 -404.784052)
		(end 339.501988 -400.128232)
		(width 0.14732)
		(layer "In4.Cu")
		(net "P5E_CPU0_PE4_RX_DP<11>")
	)
	(segment
		(start 337.074002 -435.02707)
		(end 336.692494 -434.645562)
		(width 0.14732)
		(layer "In4.Cu")
		(net "P5E_CPU0_PE4_RX_DP<11>")
	)
	(segment
		(start 346.474796 -292.853618)
		(end 346.474796 -292.638734)
		(width 0.0889)
		(layer "In4.Cu")
		(net "P5E_CPU0_PE4_RX_DP<11>")
	)
	(segment
		(start 348.177612 -288.62528)
		(end 348.09938 -288.646108)
		(width 0.0889)
		(layer "In4.Cu")
		(net "P5E_CPU0_PE4_RX_DP<11>")
	)
	(segment
		(start 336.692494 -424.501564)
		(end 340.848188 -410.855414)
		(width 0.14732)
		(layer "In4.Cu")
		(net "P5E_CPU0_PE4_RX_DP<11>")
	)
	(arc
		(start 348.317566 -288.917126)
		(mid 348.280706 -288.755329)
		(end 348.177612 -288.62528)
		(width 0.0889)
		(layer "In4.Cu")
		(net "P5E_CPU0_PE4_RX_DP<11>")
	)
	(arc
		(start 348.787212 -289.645852)
		(mid 348.712207 -289.530393)
		(end 348.603062 -289.446462)
		(width 0.0889)
		(layer "In4.Cu")
		(net "P5E_CPU0_PE4_RX_DP<11>")
	)
	(arc
		(start 348.603062 -289.446462)
		(mid 348.42893 -289.307615)
		(end 348.317566 -289.114738)
		(width 0.0889)
		(layer "In4.Cu")
		(net "P5E_CPU0_PE4_RX_DP<11>")
	)
	(segment
		(start 347.003116 -288.381186)
		(end 347.003116 -288.917126)
		(width 0.13208)
		(layer "F.Cu")
		(net "P5E_CPU0_PE4_RX_DP<10>")
	)
	(segment
		(start 335.438496 -433.752752)
		(end 335.650078 -433.54117)
		(width 0.14732)
		(layer "In4.Cu")
		(net "P5E_CPU0_PE4_RX_DP<10>")
	)
	(segment
		(start 335.854294 -421.407336)
		(end 335.686654 -421.512492)
		(width 0.14732)
		(layer "In4.Cu")
		(net "P5E_CPU0_PE4_RX_DP<10>")
	)
	(segment
		(start 345.777058 -297.175682)
		(end 344.845132 -302.454056)
		(width 0.14732)
		(layer "In4.Cu")
		(net "P5E_CPU0_PE4_RX_DP<10>")
	)
	(segment
		(start 345.777058 -292.86327)
		(end 345.777058 -292.885368)
		(width 0.0889)
		(layer "In4.Cu")
		(net "P5E_CPU0_PE4_RX_DP<10>")
	)
	(segment
		(start 335.604866 -421.871394)
		(end 335.710022 -422.03878)
		(width 0.14732)
		(layer "In4.Cu")
		(net "P5E_CPU0_PE4_RX_DP<10>")
	)
	(segment
		(start 336.713068 -404.67026)
		(end 338.059268 -406.01646)
		(width 0.14732)
		(layer "In4.Cu")
		(net "P5E_CPU0_PE4_RX_DP<10>")
	)
	(segment
		(start 347.003116 -288.917126)
		(end 347.161866 -289.218116)
		(width 0.0889)
		(layer "In4.Cu")
		(net "P5E_CPU0_PE4_RX_DP<10>")
	)
	(segment
		(start 345.777058 -292.885368)
		(end 345.777058 -297.175682)
		(width 0.14732)
		(layer "In4.Cu")
		(net "P5E_CPU0_PE4_RX_DP<10>")
	)
	(segment
		(start 334.966818 -433.605432)
		(end 335.114138 -433.752752)
		(width 0.14732)
		(layer "In4.Cu")
		(net "P5E_CPU0_PE4_RX_DP<10>")
	)
	(segment
		(start 336.175096 -419.935152)
		(end 336.07756 -420.361364)
		(width 0.14732)
		(layer "In4.Cu")
		(net "P5E_CPU0_PE4_RX_DP<10>")
	)
	(segment
		(start 336.07756 -420.361364)
		(end 335.928462 -420.45509)
		(width 0.14732)
		(layer "In4.Cu")
		(net "P5E_CPU0_PE4_RX_DP<10>")
	)
	(segment
		(start 345.734894 -292.821106)
		(end 345.777058 -292.86327)
		(width 0.0889)
		(layer "In4.Cu")
		(net "P5E_CPU0_PE4_RX_DP<10>")
	)
	(segment
		(start 338.059268 -406.01646)
		(end 338.059268 -411.128972)
		(width 0.14732)
		(layer "In4.Cu")
		(net "P5E_CPU0_PE4_RX_DP<10>")
	)
	(segment
		(start 335.62798 -422.397936)
		(end 335.460594 -422.502838)
		(width 0.14732)
		(layer "In4.Cu")
		(net "P5E_CPU0_PE4_RX_DP<10>")
	)
	(segment
		(start 335.686654 -421.512492)
		(end 335.604866 -421.871394)
		(width 0.14732)
		(layer "In4.Cu")
		(net "P5E_CPU0_PE4_RX_DP<10>")
	)
	(segment
		(start 348.037912 -290.336478)
		(end 345.734894 -292.639496)
		(width 0.0889)
		(layer "In4.Cu")
		(net "P5E_CPU0_PE4_RX_DP<10>")
	)
	(segment
		(start 338.059268 -411.128972)
		(end 336.081624 -419.785292)
		(width 0.14732)
		(layer "In4.Cu")
		(net "P5E_CPU0_PE4_RX_DP<10>")
	)
	(segment
		(start 336.713068 -400.138392)
		(end 336.713068 -404.67026)
		(width 0.14732)
		(layer "In4.Cu")
		(net "P5E_CPU0_PE4_RX_DP<10>")
	)
	(segment
		(start 335.83118 -420.880794)
		(end 335.936336 -421.04818)
		(width 0.14732)
		(layer "In4.Cu")
		(net "P5E_CPU0_PE4_RX_DP<10>")
	)
	(segment
		(start 335.460594 -422.502838)
		(end 334.966818 -424.66387)
		(width 0.14732)
		(layer "In4.Cu")
		(net "P5E_CPU0_PE4_RX_DP<10>")
	)
	(segment
		(start 312.74893 -334.551274)
		(end 312.74893 -343.514426)
		(width 0.14732)
		(layer "In4.Cu")
		(net "P5E_CPU0_PE4_RX_DP<10>")
	)
	(segment
		(start 312.74893 -343.514426)
		(end 336.713068 -400.138392)
		(width 0.14732)
		(layer "In4.Cu")
		(net "P5E_CPU0_PE4_RX_DP<10>")
	)
	(segment
		(start 347.161866 -289.218116)
		(end 347.25864 -289.247834)
		(width 0.0889)
		(layer "In4.Cu")
		(net "P5E_CPU0_PE4_RX_DP<10>")
	)
	(segment
		(start 335.710022 -422.03878)
		(end 335.62798 -422.397936)
		(width 0.14732)
		(layer "In4.Cu")
		(net "P5E_CPU0_PE4_RX_DP<10>")
	)
	(segment
		(start 345.734894 -292.639496)
		(end 345.734894 -292.821106)
		(width 0.0889)
		(layer "In4.Cu")
		(net "P5E_CPU0_PE4_RX_DP<10>")
	)
	(segment
		(start 335.650078 -433.54117)
		(end 335.650078 -433.289964)
		(width 0.14732)
		(layer "In4.Cu")
		(net "P5E_CPU0_PE4_RX_DP<10>")
	)
	(segment
		(start 334.966818 -424.66387)
		(end 334.966818 -433.605432)
		(width 0.14732)
		(layer "In4.Cu")
		(net "P5E_CPU0_PE4_RX_DP<10>")
	)
	(segment
		(start 335.928462 -420.45509)
		(end 335.83118 -420.880794)
		(width 0.14732)
		(layer "In4.Cu")
		(net "P5E_CPU0_PE4_RX_DP<10>")
	)
	(segment
		(start 335.936336 -421.04818)
		(end 335.854294 -421.407336)
		(width 0.14732)
		(layer "In4.Cu")
		(net "P5E_CPU0_PE4_RX_DP<10>")
	)
	(segment
		(start 336.08137 -419.786308)
		(end 336.175096 -419.935152)
		(width 0.14732)
		(layer "In4.Cu")
		(net "P5E_CPU0_PE4_RX_DP<10>")
	)
	(segment
		(start 344.845132 -302.454056)
		(end 312.74893 -334.551274)
		(width 0.14732)
		(layer "In4.Cu")
		(net "P5E_CPU0_PE4_RX_DP<10>")
	)
	(segment
		(start 348.037912 -289.60953)
		(end 348.037912 -290.336478)
		(width 0.0889)
		(layer "In4.Cu")
		(net "P5E_CPU0_PE4_RX_DP<10>")
	)
	(segment
		(start 335.114138 -433.752752)
		(end 335.438496 -433.752752)
		(width 0.14732)
		(layer "In4.Cu")
		(net "P5E_CPU0_PE4_RX_DP<10>")
	)
	(segment
		(start 336.081624 -419.785292)
		(end 336.08137 -419.786308)
		(width 0.14732)
		(layer "In4.Cu")
		(net "P5E_CPU0_PE4_RX_DP<10>")
	)
	(arc
		(start 347.25864 -289.247834)
		(mid 347.268515 -289.244192)
		(end 347.278452 -289.240722)
		(width 0.0889)
		(layer "In4.Cu")
		(net "P5E_CPU0_PE4_RX_DP<10>")
	)
	(arc
		(start 347.278452 -289.240722)
		(mid 347.734294 -289.26845)
		(end 348.037912 -289.60953)
		(width 0.0889)
		(layer "In4.Cu")
		(net "P5E_CPU0_PE4_RX_DP<10>")
	)
	(segment
		(start 337.134962 -287.567116)
		(end 337.134962 -288.103056)
		(width 0.13208)
		(layer "F.Cu")
		(net "P5E_CPU0_PE4_RX_DP<0>")
	)
	(segment
		(start 330.183236 -303.430686)
		(end 312.897774 -320.716148)
		(width 0.14732)
		(layer "In4.Cu")
		(net "P5E_CPU0_PE4_RX_DP<0>")
	)
	(segment
		(start 304.982372 -328.770996)
		(end 303.273206 -330.480162)
		(width 0.14732)
		(layer "In4.Cu")
		(net "P5E_CPU0_PE4_RX_DP<0>")
	)
	(segment
		(start 336.773012 -289.726116)
		(end 336.773012 -289.78606)
		(width 0.0889)
		(layer "In4.Cu")
		(net "P5E_CPU0_PE4_RX_DP<0>")
	)
	(segment
		(start 308.35219 -413.33674)
		(end 308.470554 -413.757618)
		(width 0.14732)
		(layer "In4.Cu")
		(net "P5E_CPU0_PE4_RX_DP<0>")
	)
	(segment
		(start 308.807612 -415.41573)
		(end 308.961536 -415.501836)
		(width 0.14732)
		(layer "In4.Cu")
		(net "P5E_CPU0_PE4_RX_DP<0>")
	)
	(segment
		(start 311.870344 -320.716148)
		(end 310.932576 -320.902584)
		(width 0.14732)
		(layer "In4.Cu")
		(net "P5E_CPU0_PE4_RX_DP<0>")
	)
	(segment
		(start 308.961536 -415.501836)
		(end 309.079646 -415.922714)
		(width 0.14732)
		(layer "In4.Cu")
		(net "P5E_CPU0_PE4_RX_DP<0>")
	)
	(segment
		(start 332.199234 -293.37889)
		(end 331.093064 -296.049192)
		(width 0.14732)
		(layer "In4.Cu")
		(net "P5E_CPU0_PE4_RX_DP<0>")
	)
	(segment
		(start 308.99354 -416.07613)
		(end 309.11165 -416.4965)
		(width 0.14732)
		(layer "In4.Cu")
		(net "P5E_CPU0_PE4_RX_DP<0>")
	)
	(segment
		(start 314.65012 -433.54117)
		(end 314.65012 -433.289964)
		(width 0.14732)
		(layer "In4.Cu")
		(net "P5E_CPU0_PE4_RX_DP<0>")
	)
	(segment
		(start 308.470554 -413.757618)
		(end 308.384448 -413.911034)
		(width 0.14732)
		(layer "In4.Cu")
		(net "P5E_CPU0_PE4_RX_DP<0>")
	)
	(segment
		(start 308.036976 -412.67634)
		(end 308.19852 -413.250634)
		(width 0.14732)
		(layer "In4.Cu")
		(net "P5E_CPU0_PE4_RX_DP<0>")
	)
	(segment
		(start 336.378804 -290.180268)
		(end 335.397856 -290.180268)
		(width 0.14732)
		(layer "In4.Cu")
		(net "P5E_CPU0_PE4_RX_DP<0>")
	)
	(segment
		(start 308.503574 -414.334452)
		(end 308.657244 -414.420558)
		(width 0.14732)
		(layer "In4.Cu")
		(net "P5E_CPU0_PE4_RX_DP<0>")
	)
	(segment
		(start 336.773012 -289.78606)
		(end 336.757518 -289.801554)
		(width 0.0889)
		(layer "In4.Cu")
		(net "P5E_CPU0_PE4_RX_DP<0>")
	)
	(segment
		(start 337.134962 -288.103056)
		(end 336.978498 -288.374074)
		(width 0.0889)
		(layer "In4.Cu")
		(net "P5E_CPU0_PE4_RX_DP<0>")
	)
	(segment
		(start 306.080668 -400.369024)
		(end 306.080668 -404.67026)
		(width 0.14732)
		(layer "In4.Cu")
		(net "P5E_CPU0_PE4_RX_DP<0>")
	)
	(segment
		(start 305.441604 -327.662286)
		(end 304.982372 -328.770996)
		(width 0.14732)
		(layer "In4.Cu")
		(net "P5E_CPU0_PE4_RX_DP<0>")
	)
	(segment
		(start 308.775608 -414.841436)
		(end 308.689502 -414.995106)
		(width 0.14732)
		(layer "In4.Cu")
		(net "P5E_CPU0_PE4_RX_DP<0>")
	)
	(segment
		(start 305.441604 -325.044308)
		(end 305.441604 -327.662286)
		(width 0.14732)
		(layer "In4.Cu")
		(net "P5E_CPU0_PE4_RX_DP<0>")
	)
	(segment
		(start 309.11165 -416.4965)
		(end 309.265574 -416.582606)
		(width 0.14732)
		(layer "In4.Cu")
		(net "P5E_CPU0_PE4_RX_DP<0>")
	)
	(segment
		(start 307.426868 -410.507434)
		(end 307.851302 -412.016194)
		(width 0.14732)
		(layer "In4.Cu")
		(net "P5E_CPU0_PE4_RX_DP<0>")
	)
	(segment
		(start 310.194706 -320.902584)
		(end 309.15102 -321.334892)
		(width 0.14732)
		(layer "In4.Cu")
		(net "P5E_CPU0_PE4_RX_DP<0>")
	)
	(segment
		(start 314.438538 -433.752752)
		(end 314.65012 -433.54117)
		(width 0.14732)
		(layer "In4.Cu")
		(net "P5E_CPU0_PE4_RX_DP<0>")
	)
	(segment
		(start 307.426868 -406.01646)
		(end 307.426868 -410.507434)
		(width 0.14732)
		(layer "In4.Cu")
		(net "P5E_CPU0_PE4_RX_DP<0>")
	)
	(segment
		(start 307.851302 -412.016194)
		(end 308.004972 -412.102046)
		(width 0.14732)
		(layer "In4.Cu")
		(net "P5E_CPU0_PE4_RX_DP<0>")
	)
	(segment
		(start 303.273206 -330.480162)
		(end 303.273206 -344.758264)
		(width 0.14732)
		(layer "In4.Cu")
		(net "P5E_CPU0_PE4_RX_DP<0>")
	)
	(segment
		(start 308.19852 -413.250634)
		(end 308.35219 -413.33674)
		(width 0.14732)
		(layer "In4.Cu")
		(net "P5E_CPU0_PE4_RX_DP<0>")
	)
	(segment
		(start 309.15102 -321.334892)
		(end 305.441604 -325.044308)
		(width 0.14732)
		(layer "In4.Cu")
		(net "P5E_CPU0_PE4_RX_DP<0>")
	)
	(segment
		(start 305.670204 -370.647976)
		(end 306.276756 -394.767562)
		(width 0.14732)
		(layer "In4.Cu")
		(net "P5E_CPU0_PE4_RX_DP<0>")
	)
	(segment
		(start 308.384448 -413.911034)
		(end 308.503574 -414.334452)
		(width 0.14732)
		(layer "In4.Cu")
		(net "P5E_CPU0_PE4_RX_DP<0>")
	)
	(segment
		(start 306.080668 -404.67026)
		(end 307.426868 -406.01646)
		(width 0.14732)
		(layer "In4.Cu")
		(net "P5E_CPU0_PE4_RX_DP<0>")
	)
	(segment
		(start 308.004972 -412.102046)
		(end 308.123082 -412.52267)
		(width 0.14732)
		(layer "In4.Cu")
		(net "P5E_CPU0_PE4_RX_DP<0>")
	)
	(segment
		(start 306.276756 -394.767562)
		(end 306.080668 -400.369024)
		(width 0.14732)
		(layer "In4.Cu")
		(net "P5E_CPU0_PE4_RX_DP<0>")
	)
	(segment
		(start 331.093064 -296.049192)
		(end 331.093064 -298.271946)
		(width 0.14732)
		(layer "In4.Cu")
		(net "P5E_CPU0_PE4_RX_DP<0>")
	)
	(segment
		(start 331.093064 -298.271946)
		(end 330.183236 -303.430686)
		(width 0.14732)
		(layer "In4.Cu")
		(net "P5E_CPU0_PE4_RX_DP<0>")
	)
	(segment
		(start 303.273206 -344.758264)
		(end 305.670204 -370.647976)
		(width 0.14732)
		(layer "In4.Cu")
		(net "P5E_CPU0_PE4_RX_DP<0>")
	)
	(segment
		(start 309.079646 -415.922714)
		(end 308.99354 -416.07613)
		(width 0.14732)
		(layer "In4.Cu")
		(net "P5E_CPU0_PE4_RX_DP<0>")
	)
	(segment
		(start 312.897774 -320.716148)
		(end 311.870344 -320.716148)
		(width 0.14732)
		(layer "In4.Cu")
		(net "P5E_CPU0_PE4_RX_DP<0>")
	)
	(segment
		(start 309.265574 -416.582606)
		(end 309.383684 -417.003484)
		(width 0.14732)
		(layer "In4.Cu")
		(net "P5E_CPU0_PE4_RX_DP<0>")
	)
	(segment
		(start 335.397856 -290.180268)
		(end 332.199234 -293.37889)
		(width 0.14732)
		(layer "In4.Cu")
		(net "P5E_CPU0_PE4_RX_DP<0>")
	)
	(segment
		(start 308.123082 -412.52267)
		(end 308.036976 -412.67634)
		(width 0.14732)
		(layer "In4.Cu")
		(net "P5E_CPU0_PE4_RX_DP<0>")
	)
	(segment
		(start 337.230466 -288.902902)
		(end 337.229958 -288.901886)
		(width 0.0889)
		(layer "In4.Cu")
		(net "P5E_CPU0_PE4_RX_DP<0>")
	)
	(segment
		(start 313.907678 -433.54625)
		(end 314.11418 -433.752752)
		(width 0.14732)
		(layer "In4.Cu")
		(net "P5E_CPU0_PE4_RX_DP<0>")
	)
	(segment
		(start 337.229958 -288.901886)
		(end 337.229958 -289.26917)
		(width 0.0889)
		(layer "In4.Cu")
		(net "P5E_CPU0_PE4_RX_DP<0>")
	)
	(segment
		(start 309.383684 -417.003484)
		(end 309.297578 -417.1569)
		(width 0.14732)
		(layer "In4.Cu")
		(net "P5E_CPU0_PE4_RX_DP<0>")
	)
	(segment
		(start 309.297578 -417.1569)
		(end 313.907678 -433.54625)
		(width 0.14732)
		(layer "In4.Cu")
		(net "P5E_CPU0_PE4_RX_DP<0>")
	)
	(segment
		(start 336.978498 -288.374074)
		(end 337.002628 -288.463228)
		(width 0.0889)
		(layer "In4.Cu")
		(net "P5E_CPU0_PE4_RX_DP<0>")
	)
	(segment
		(start 336.757518 -289.801554)
		(end 336.378804 -290.180268)
		(width 0.14732)
		(layer "In4.Cu")
		(net "P5E_CPU0_PE4_RX_DP<0>")
	)
	(segment
		(start 314.11418 -433.752752)
		(end 314.438538 -433.752752)
		(width 0.14732)
		(layer "In4.Cu")
		(net "P5E_CPU0_PE4_RX_DP<0>")
	)
	(segment
		(start 308.689502 -414.995106)
		(end 308.807612 -415.41573)
		(width 0.14732)
		(layer "In4.Cu")
		(net "P5E_CPU0_PE4_RX_DP<0>")
	)
	(segment
		(start 310.932576 -320.902584)
		(end 310.194706 -320.902584)
		(width 0.14732)
		(layer "In4.Cu")
		(net "P5E_CPU0_PE4_RX_DP<0>")
	)
	(segment
		(start 308.657244 -414.420558)
		(end 308.775608 -414.841436)
		(width 0.14732)
		(layer "In4.Cu")
		(net "P5E_CPU0_PE4_RX_DP<0>")
	)
	(segment
		(start 337.229958 -289.26917)
		(end 336.773012 -289.726116)
		(width 0.0889)
		(layer "In4.Cu")
		(net "P5E_CPU0_PE4_RX_DP<0>")
	)
	(arc
		(start 337.019646 -288.476182)
		(mid 337.172133 -288.666278)
		(end 337.230466 -288.902902)
		(width 0.0889)
		(layer "In4.Cu")
		(net "P5E_CPU0_PE4_RX_DP<0>")
	)
	(arc
		(start 337.002628 -288.463228)
		(mid 337.011199 -288.469624)
		(end 337.019646 -288.476182)
		(width 0.0889)
		(layer "In4.Cu")
		(net "P5E_CPU0_PE4_RX_DP<0>")
	)
	(segment
		(start 346.532962 -288.102802)
		(end 346.533216 -288.103056)
		(width 0.13208)
		(layer "F.Cu")
		(net "P5E_CPU0_PE4_RX_DN<9>")
	)
	(segment
		(start 346.532962 -287.567116)
		(end 346.532962 -288.102802)
		(width 0.13208)
		(layer "F.Cu")
		(net "P5E_CPU0_PE4_RX_DN<9>")
	)
	(segment
		(start 332.966822 -434.60543)
		(end 333.114142 -434.75275)
		(width 0.14732)
		(layer "In4.Cu")
		(net "P5E_CPU0_PE4_RX_DN<9>")
	)
	(segment
		(start 344.84564 -292.86327)
		(end 344.84564 -292.885368)
		(width 0.0889)
		(layer "In4.Cu")
		(net "P5E_CPU0_PE4_RX_DN<9>")
	)
	(segment
		(start 346.628466 -288.898584)
		(end 346.628466 -289.078416)
		(width 0.0889)
		(layer "In4.Cu")
		(net "P5E_CPU0_PE4_RX_DN<9>")
	)
	(segment
		(start 333.773018 -420.366698)
		(end 333.716884 -420.730934)
		(width 0.14732)
		(layer "In4.Cu")
		(net "P5E_CPU0_PE4_RX_DN<9>")
	)
	(segment
		(start 333.36611 -422.08831)
		(end 332.96733 -424.673268)
		(width 0.14732)
		(layer "In4.Cu")
		(net "P5E_CPU0_PE4_RX_DN<9>")
	)
	(segment
		(start 333.649828 -404.67026)
		(end 334.996028 -406.01646)
		(width 0.14732)
		(layer "In4.Cu")
		(net "P5E_CPU0_PE4_RX_DN<9>")
	)
	(segment
		(start 347.097858 -290.301172)
		(end 344.803476 -292.595554)
		(width 0.0889)
		(layer "In4.Cu")
		(net "P5E_CPU0_PE4_RX_DN<9>")
	)
	(segment
		(start 333.716884 -420.730934)
		(end 333.557372 -420.847266)
		(width 0.14732)
		(layer "In4.Cu")
		(net "P5E_CPU0_PE4_RX_DN<9>")
	)
	(segment
		(start 346.533216 -288.103056)
		(end 346.376752 -288.374074)
		(width 0.0889)
		(layer "In4.Cu")
		(net "P5E_CPU0_PE4_RX_DN<9>")
	)
	(segment
		(start 311.817512 -343.718642)
		(end 333.649828 -399.763488)
		(width 0.14732)
		(layer "In4.Cu")
		(net "P5E_CPU0_PE4_RX_DN<9>")
	)
	(segment
		(start 333.885794 -419.636702)
		(end 333.726028 -419.753542)
		(width 0.14732)
		(layer "In4.Cu")
		(net "P5E_CPU0_PE4_RX_DN<9>")
	)
	(segment
		(start 347.098112 -289.60953)
		(end 347.097858 -289.609276)
		(width 0.0889)
		(layer "In4.Cu")
		(net "P5E_CPU0_PE4_RX_DN<9>")
	)
	(segment
		(start 333.726028 -419.754558)
		(end 333.656178 -420.207186)
		(width 0.14732)
		(layer "In4.Cu")
		(net "P5E_CPU0_PE4_RX_DN<9>")
	)
	(segment
		(start 332.966822 -424.673776)
		(end 332.966822 -434.60543)
		(width 0.14732)
		(layer "In4.Cu")
		(net "P5E_CPU0_PE4_RX_DN<9>")
	)
	(segment
		(start 333.4385 -434.75275)
		(end 333.650082 -434.541168)
		(width 0.14732)
		(layer "In4.Cu")
		(net "P5E_CPU0_PE4_RX_DN<9>")
	)
	(segment
		(start 333.114142 -434.75275)
		(end 333.4385 -434.75275)
		(width 0.14732)
		(layer "In4.Cu")
		(net "P5E_CPU0_PE4_RX_DN<9>")
	)
	(segment
		(start 333.649828 -399.763488)
		(end 333.649828 -404.67026)
		(width 0.14732)
		(layer "In4.Cu")
		(net "P5E_CPU0_PE4_RX_DN<9>")
	)
	(segment
		(start 333.464662 -421.44823)
		(end 333.581248 -421.607488)
		(width 0.14732)
		(layer "In4.Cu")
		(net "P5E_CPU0_PE4_RX_DN<9>")
	)
	(segment
		(start 333.656178 -420.207186)
		(end 333.773018 -420.366698)
		(width 0.14732)
		(layer "In4.Cu")
		(net "P5E_CPU0_PE4_RX_DN<9>")
	)
	(segment
		(start 346.376752 -288.374074)
		(end 346.400882 -288.463228)
		(width 0.0889)
		(layer "In4.Cu")
		(net "P5E_CPU0_PE4_RX_DN<9>")
	)
	(segment
		(start 333.365856 -422.08831)
		(end 333.36611 -422.08831)
		(width 0.14732)
		(layer "In4.Cu")
		(net "P5E_CPU0_PE4_RX_DN<9>")
	)
	(segment
		(start 334.996028 -406.01646)
		(end 334.996028 -411.521148)
		(width 0.14732)
		(layer "In4.Cu")
		(net "P5E_CPU0_PE4_RX_DN<9>")
	)
	(segment
		(start 347.097858 -289.609276)
		(end 347.097858 -290.301172)
		(width 0.0889)
		(layer "In4.Cu")
		(net "P5E_CPU0_PE4_RX_DN<9>")
	)
	(segment
		(start 333.941928 -419.272466)
		(end 333.885794 -419.636702)
		(width 0.14732)
		(layer "In4.Cu")
		(net "P5E_CPU0_PE4_RX_DN<9>")
	)
	(segment
		(start 333.650082 -434.541168)
		(end 333.650082 -434.289962)
		(width 0.14732)
		(layer "In4.Cu")
		(net "P5E_CPU0_PE4_RX_DN<9>")
	)
	(segment
		(start 311.817512 -334.165194)
		(end 311.817512 -343.718642)
		(width 0.14732)
		(layer "In4.Cu")
		(net "P5E_CPU0_PE4_RX_DN<9>")
	)
	(segment
		(start 333.557372 -420.847266)
		(end 333.464662 -421.44823)
		(width 0.14732)
		(layer "In4.Cu")
		(net "P5E_CPU0_PE4_RX_DN<9>")
	)
	(segment
		(start 344.84564 -297.078908)
		(end 343.97569 -302.006)
		(width 0.14732)
		(layer "In4.Cu")
		(net "P5E_CPU0_PE4_RX_DN<9>")
	)
	(segment
		(start 333.825088 -419.113208)
		(end 333.941928 -419.272466)
		(width 0.14732)
		(layer "In4.Cu")
		(net "P5E_CPU0_PE4_RX_DN<9>")
	)
	(segment
		(start 344.803476 -292.821106)
		(end 344.84564 -292.86327)
		(width 0.0889)
		(layer "In4.Cu")
		(net "P5E_CPU0_PE4_RX_DN<9>")
	)
	(segment
		(start 334.996028 -411.521148)
		(end 333.825088 -419.113208)
		(width 0.14732)
		(layer "In4.Cu")
		(net "P5E_CPU0_PE4_RX_DN<9>")
	)
	(segment
		(start 344.84564 -292.885368)
		(end 344.84564 -297.078908)
		(width 0.14732)
		(layer "In4.Cu")
		(net "P5E_CPU0_PE4_RX_DN<9>")
	)
	(segment
		(start 333.581248 -421.607488)
		(end 333.525114 -421.971724)
		(width 0.14732)
		(layer "In4.Cu")
		(net "P5E_CPU0_PE4_RX_DN<9>")
	)
	(segment
		(start 343.97569 -302.006)
		(end 311.817512 -334.165194)
		(width 0.14732)
		(layer "In4.Cu")
		(net "P5E_CPU0_PE4_RX_DN<9>")
	)
	(segment
		(start 333.525114 -421.971724)
		(end 333.365856 -422.08831)
		(width 0.14732)
		(layer "In4.Cu")
		(net "P5E_CPU0_PE4_RX_DN<9>")
	)
	(segment
		(start 332.96733 -424.673268)
		(end 332.966822 -424.673776)
		(width 0.14732)
		(layer "In4.Cu")
		(net "P5E_CPU0_PE4_RX_DN<9>")
	)
	(segment
		(start 333.726028 -419.753542)
		(end 333.726028 -419.754558)
		(width 0.14732)
		(layer "In4.Cu")
		(net "P5E_CPU0_PE4_RX_DN<9>")
	)
	(segment
		(start 344.803476 -292.595554)
		(end 344.803476 -292.821106)
		(width 0.0889)
		(layer "In4.Cu")
		(net "P5E_CPU0_PE4_RX_DN<9>")
	)
	(arc
		(start 346.400882 -288.463228)
		(mid 346.409454 -288.469751)
		(end 346.4179 -288.476436)
		(width 0.0889)
		(layer "In4.Cu")
		(net "P5E_CPU0_PE4_RX_DN<9>")
	)
	(arc
		(start 346.628466 -289.078416)
		(mid 346.703471 -289.193875)
		(end 346.812616 -289.277806)
		(width 0.0889)
		(layer "In4.Cu")
		(net "P5E_CPU0_PE4_RX_DN<9>")
	)
	(arc
		(start 346.812616 -289.277806)
		(mid 346.986748 -289.416653)
		(end 347.098112 -289.60953)
		(width 0.0889)
		(layer "In4.Cu")
		(net "P5E_CPU0_PE4_RX_DN<9>")
	)
	(arc
		(start 346.4179 -288.476436)
		(mid 346.569304 -288.664503)
		(end 346.628466 -288.898584)
		(width 0.0889)
		(layer "In4.Cu")
		(net "P5E_CPU0_PE4_RX_DN<9>")
	)
	(segment
		(start 345.593162 -289.195002)
		(end 345.593162 -289.807142)
		(width 0.13208)
		(layer "F.Cu")
		(net "P5E_CPU0_PE4_RX_DN<8>")
	)
	(segment
		(start 343.638378 -296.987976)
		(end 343.638632 -296.98823)
		(width 0.14732)
		(layer "In4.Cu")
		(net "P5E_CPU0_PE4_RX_DN<8>")
	)
	(segment
		(start 331.502512 -434.027072)
		(end 331.000354 -434.027072)
		(width 0.14732)
		(layer "In4.Cu")
		(net "P5E_CPU0_PE4_RX_DN<8>")
	)
	(segment
		(start 310.610504 -343.961974)
		(end 310.610504 -333.664814)
		(width 0.14732)
		(layer "In4.Cu")
		(net "P5E_CPU0_PE4_RX_DN<8>")
	)
	(segment
		(start 345.434412 -289.506152)
		(end 345.593162 -289.807142)
		(width 0.0889)
		(layer "In4.Cu")
		(net "P5E_CPU0_PE4_RX_DN<8>")
	)
	(segment
		(start 330.312268 -400.101054)
		(end 310.610504 -343.961974)
		(width 0.14732)
		(layer "In4.Cu")
		(net "P5E_CPU0_PE4_RX_DN<8>")
	)
	(segment
		(start 345.968066 -290.150804)
		(end 345.968066 -289.64509)
		(width 0.0889)
		(layer "In4.Cu")
		(net "P5E_CPU0_PE4_RX_DN<8>")
	)
	(segment
		(start 345.460828 -289.42157)
		(end 345.434412 -289.506152)
		(width 0.0889)
		(layer "In4.Cu")
		(net "P5E_CPU0_PE4_RX_DN<8>")
	)
	(segment
		(start 310.610504 -333.664814)
		(end 342.855804 -301.418498)
		(width 0.14732)
		(layer "In4.Cu")
		(net "P5E_CPU0_PE4_RX_DN<8>")
	)
	(segment
		(start 330.312268 -404.784052)
		(end 330.312268 -400.101054)
		(width 0.14732)
		(layer "In4.Cu")
		(net "P5E_CPU0_PE4_RX_DN<8>")
	)
	(segment
		(start 330.692506 -424.312842)
		(end 331.16774 -418.329618)
		(width 0.14732)
		(layer "In4.Cu")
		(net "P5E_CPU0_PE4_RX_DN<8>")
	)
	(segment
		(start 331.658468 -406.130252)
		(end 330.312268 -404.784052)
		(width 0.14732)
		(layer "In4.Cu")
		(net "P5E_CPU0_PE4_RX_DN<8>")
	)
	(segment
		(start 331.16774 -418.329618)
		(end 331.167994 -418.328856)
		(width 0.14732)
		(layer "In4.Cu")
		(net "P5E_CPU0_PE4_RX_DN<8>")
	)
	(segment
		(start 331.000354 -434.027072)
		(end 330.692506 -433.719224)
		(width 0.14732)
		(layer "In4.Cu")
		(net "P5E_CPU0_PE4_RX_DN<8>")
	)
	(segment
		(start 343.638632 -292.885368)
		(end 343.638632 -292.86327)
		(width 0.0889)
		(layer "In4.Cu")
		(net "P5E_CPU0_PE4_RX_DN<8>")
	)
	(segment
		(start 331.658468 -412.154624)
		(end 331.658468 -406.130252)
		(width 0.14732)
		(layer "In4.Cu")
		(net "P5E_CPU0_PE4_RX_DN<8>")
	)
	(segment
		(start 343.638632 -292.86327)
		(end 343.680542 -292.82136)
		(width 0.0889)
		(layer "In4.Cu")
		(net "P5E_CPU0_PE4_RX_DN<8>")
	)
	(segment
		(start 331.167994 -418.328856)
		(end 331.658468 -412.154624)
		(width 0.14732)
		(layer "In4.Cu")
		(net "P5E_CPU0_PE4_RX_DN<8>")
	)
	(segment
		(start 331.650086 -434.174646)
		(end 331.502512 -434.027072)
		(width 0.14732)
		(layer "In4.Cu")
		(net "P5E_CPU0_PE4_RX_DN<8>")
	)
	(segment
		(start 343.680542 -292.82136)
		(end 343.680542 -292.438328)
		(width 0.0889)
		(layer "In4.Cu")
		(net "P5E_CPU0_PE4_RX_DN<8>")
	)
	(segment
		(start 343.638632 -296.98823)
		(end 343.638632 -292.885368)
		(width 0.14732)
		(layer "In4.Cu")
		(net "P5E_CPU0_PE4_RX_DN<8>")
	)
	(segment
		(start 331.650086 -434.48986)
		(end 331.650086 -434.174646)
		(width 0.14732)
		(layer "In4.Cu")
		(net "P5E_CPU0_PE4_RX_DN<8>")
	)
	(segment
		(start 343.63787 -296.987976)
		(end 343.638378 -296.987976)
		(width 0.14732)
		(layer "In4.Cu")
		(net "P5E_CPU0_PE4_RX_DN<8>")
	)
	(segment
		(start 342.855804 -301.418498)
		(end 343.63787 -296.987976)
		(width 0.14732)
		(layer "In4.Cu")
		(net "P5E_CPU0_PE4_RX_DN<8>")
	)
	(segment
		(start 330.692506 -433.719224)
		(end 330.692506 -424.312842)
		(width 0.14732)
		(layer "In4.Cu")
		(net "P5E_CPU0_PE4_RX_DN<8>")
	)
	(segment
		(start 343.680542 -292.438328)
		(end 345.968066 -290.150804)
		(width 0.0889)
		(layer "In4.Cu")
		(net "P5E_CPU0_PE4_RX_DN<8>")
	)
	(arc
		(start 345.46032 -289.420808)
		(mid 345.460575 -289.421188)
		(end 345.460828 -289.42157)
		(width 0.0889)
		(layer "In4.Cu")
		(net "P5E_CPU0_PE4_RX_DN<8>")
	)
	(arc
		(start 345.968066 -289.64509)
		(mid 345.758138 -289.433515)
		(end 345.46032 -289.420808)
		(width 0.0889)
		(layer "In4.Cu")
		(net "P5E_CPU0_PE4_RX_DN<8>")
	)
	(segment
		(start 344.653362 -287.567116)
		(end 344.653362 -288.102802)
		(width 0.13208)
		(layer "F.Cu")
		(net "P5E_CPU0_PE4_RX_DN<7>")
	)
	(segment
		(start 344.653362 -288.102802)
		(end 344.653616 -288.103056)
		(width 0.13208)
		(layer "F.Cu")
		(net "P5E_CPU0_PE4_RX_DN<7>")
	)
	(segment
		(start 328.535538 -418.935662)
		(end 328.50709 -419.302946)
		(width 0.14732)
		(layer "In4.Cu")
		(net "P5E_CPU0_PE4_RX_DN<7>")
	)
	(segment
		(start 342.979248 -296.930318)
		(end 342.242902 -301.102776)
		(width 0.14732)
		(layer "In4.Cu")
		(net "P5E_CPU0_PE4_RX_DN<7>")
	)
	(segment
		(start 328.221086 -421.173148)
		(end 328.221594 -421.173402)
		(width 0.14732)
		(layer "In4.Cu")
		(net "P5E_CPU0_PE4_RX_DN<7>")
	)
	(segment
		(start 327.967848 -424.437048)
		(end 327.966832 -424.438064)
		(width 0.14732)
		(layer "In4.Cu")
		(net "P5E_CPU0_PE4_RX_DN<7>")
	)
	(segment
		(start 342.242902 -301.102776)
		(end 309.929022 -333.416656)
		(width 0.14732)
		(layer "In4.Cu")
		(net "P5E_CPU0_PE4_RX_DN<7>")
	)
	(segment
		(start 328.271378 -420.52748)
		(end 328.399902 -420.677594)
		(width 0.14732)
		(layer "In4.Cu")
		(net "P5E_CPU0_PE4_RX_DN<7>")
	)
	(segment
		(start 342.980264 -296.930572)
		(end 342.98001 -296.930318)
		(width 0.14732)
		(layer "In4.Cu")
		(net "P5E_CPU0_PE4_RX_DN<7>")
	)
	(segment
		(start 342.98001 -296.930318)
		(end 342.979248 -296.930318)
		(width 0.14732)
		(layer "In4.Cu")
		(net "P5E_CPU0_PE4_RX_DN<7>")
	)
	(segment
		(start 327.966832 -424.438064)
		(end 327.966832 -434.60543)
		(width 0.14732)
		(layer "In4.Cu")
		(net "P5E_CPU0_PE4_RX_DN<7>")
	)
	(segment
		(start 345.218512 -289.60953)
		(end 345.218258 -289.609276)
		(width 0.0889)
		(layer "In4.Cu")
		(net "P5E_CPU0_PE4_RX_DN<7>")
	)
	(segment
		(start 345.218258 -289.609276)
		(end 345.218258 -290.125912)
		(width 0.0889)
		(layer "In4.Cu")
		(net "P5E_CPU0_PE4_RX_DN<7>")
	)
	(segment
		(start 328.356722 -419.43147)
		(end 328.271378 -420.52748)
		(width 0.14732)
		(layer "In4.Cu")
		(net "P5E_CPU0_PE4_RX_DN<7>")
	)
	(segment
		(start 342.980264 -292.885368)
		(end 342.980264 -296.930572)
		(width 0.14732)
		(layer "In4.Cu")
		(net "P5E_CPU0_PE4_RX_DN<7>")
	)
	(segment
		(start 328.650092 -434.541168)
		(end 328.650092 -434.289962)
		(width 0.14732)
		(layer "In4.Cu")
		(net "P5E_CPU0_PE4_RX_DN<7>")
	)
	(segment
		(start 327.966832 -434.60543)
		(end 328.114152 -434.75275)
		(width 0.14732)
		(layer "In4.Cu")
		(net "P5E_CPU0_PE4_RX_DN<7>")
	)
	(segment
		(start 327.523348 -404.67026)
		(end 328.869548 -406.01646)
		(width 0.14732)
		(layer "In4.Cu")
		(net "P5E_CPU0_PE4_RX_DN<7>")
	)
	(segment
		(start 344.653616 -288.103056)
		(end 344.497152 -288.374074)
		(width 0.0889)
		(layer "In4.Cu")
		(net "P5E_CPU0_PE4_RX_DN<7>")
	)
	(segment
		(start 342.9381 -292.40607)
		(end 342.9381 -292.821106)
		(width 0.0889)
		(layer "In4.Cu")
		(net "P5E_CPU0_PE4_RX_DN<7>")
	)
	(segment
		(start 344.748866 -288.898584)
		(end 344.748866 -289.078416)
		(width 0.0889)
		(layer "In4.Cu")
		(net "P5E_CPU0_PE4_RX_DN<7>")
	)
	(segment
		(start 328.869548 -412.837884)
		(end 328.564748 -416.759644)
		(width 0.14732)
		(layer "In4.Cu")
		(net "P5E_CPU0_PE4_RX_DN<7>")
	)
	(segment
		(start 328.564748 -416.759644)
		(end 328.565002 -416.759898)
		(width 0.14732)
		(layer "In4.Cu")
		(net "P5E_CPU0_PE4_RX_DN<7>")
	)
	(segment
		(start 328.869548 -406.01646)
		(end 328.869548 -412.837884)
		(width 0.14732)
		(layer "In4.Cu")
		(net "P5E_CPU0_PE4_RX_DN<7>")
	)
	(segment
		(start 328.693526 -416.910012)
		(end 328.664824 -417.27755)
		(width 0.14732)
		(layer "In4.Cu")
		(net "P5E_CPU0_PE4_RX_DN<7>")
	)
	(segment
		(start 328.221594 -421.173402)
		(end 327.967848 -424.437048)
		(width 0.14732)
		(layer "In4.Cu")
		(net "P5E_CPU0_PE4_RX_DN<7>")
	)
	(segment
		(start 344.497152 -288.374074)
		(end 344.521282 -288.463228)
		(width 0.0889)
		(layer "In4.Cu")
		(net "P5E_CPU0_PE4_RX_DN<7>")
	)
	(segment
		(start 309.929022 -344.007948)
		(end 327.523348 -399.27276)
		(width 0.14732)
		(layer "In4.Cu")
		(net "P5E_CPU0_PE4_RX_DN<7>")
	)
	(segment
		(start 345.218258 -290.125912)
		(end 342.9381 -292.40607)
		(width 0.0889)
		(layer "In4.Cu")
		(net "P5E_CPU0_PE4_RX_DN<7>")
	)
	(segment
		(start 328.399902 -420.677594)
		(end 328.3712 -421.045132)
		(width 0.14732)
		(layer "In4.Cu")
		(net "P5E_CPU0_PE4_RX_DN<7>")
	)
	(segment
		(start 328.514456 -417.40582)
		(end 328.407268 -418.785548)
		(width 0.14732)
		(layer "In4.Cu")
		(net "P5E_CPU0_PE4_RX_DN<7>")
	)
	(segment
		(start 328.565002 -416.759898)
		(end 328.693526 -416.910012)
		(width 0.14732)
		(layer "In4.Cu")
		(net "P5E_CPU0_PE4_RX_DN<7>")
	)
	(segment
		(start 342.9381 -292.821106)
		(end 342.980264 -292.86327)
		(width 0.0889)
		(layer "In4.Cu")
		(net "P5E_CPU0_PE4_RX_DN<7>")
	)
	(segment
		(start 342.980264 -292.86327)
		(end 342.980264 -292.885368)
		(width 0.0889)
		(layer "In4.Cu")
		(net "P5E_CPU0_PE4_RX_DN<7>")
	)
	(segment
		(start 328.50709 -419.302946)
		(end 328.356722 -419.43147)
		(width 0.14732)
		(layer "In4.Cu")
		(net "P5E_CPU0_PE4_RX_DN<7>")
	)
	(segment
		(start 328.407268 -418.785548)
		(end 328.535538 -418.935662)
		(width 0.14732)
		(layer "In4.Cu")
		(net "P5E_CPU0_PE4_RX_DN<7>")
	)
	(segment
		(start 328.43851 -434.75275)
		(end 328.650092 -434.541168)
		(width 0.14732)
		(layer "In4.Cu")
		(net "P5E_CPU0_PE4_RX_DN<7>")
	)
	(segment
		(start 328.664824 -417.27755)
		(end 328.514456 -417.40582)
		(width 0.14732)
		(layer "In4.Cu")
		(net "P5E_CPU0_PE4_RX_DN<7>")
	)
	(segment
		(start 327.523348 -399.27276)
		(end 327.523348 -404.67026)
		(width 0.14732)
		(layer "In4.Cu")
		(net "P5E_CPU0_PE4_RX_DN<7>")
	)
	(segment
		(start 309.929022 -333.416656)
		(end 309.929022 -344.007948)
		(width 0.14732)
		(layer "In4.Cu")
		(net "P5E_CPU0_PE4_RX_DN<7>")
	)
	(segment
		(start 328.3712 -421.045132)
		(end 328.221086 -421.173148)
		(width 0.14732)
		(layer "In4.Cu")
		(net "P5E_CPU0_PE4_RX_DN<7>")
	)
	(segment
		(start 328.114152 -434.75275)
		(end 328.43851 -434.75275)
		(width 0.14732)
		(layer "In4.Cu")
		(net "P5E_CPU0_PE4_RX_DN<7>")
	)
	(arc
		(start 344.521282 -288.463228)
		(mid 344.529854 -288.469751)
		(end 344.5383 -288.476436)
		(width 0.0889)
		(layer "In4.Cu")
		(net "P5E_CPU0_PE4_RX_DN<7>")
	)
	(arc
		(start 344.5383 -288.476436)
		(mid 344.689704 -288.664503)
		(end 344.748866 -288.898584)
		(width 0.0889)
		(layer "In4.Cu")
		(net "P5E_CPU0_PE4_RX_DN<7>")
	)
	(arc
		(start 344.748866 -289.078416)
		(mid 344.823871 -289.193875)
		(end 344.933016 -289.277806)
		(width 0.0889)
		(layer "In4.Cu")
		(net "P5E_CPU0_PE4_RX_DN<7>")
	)
	(arc
		(start 344.933016 -289.277806)
		(mid 345.107148 -289.416653)
		(end 345.218512 -289.60953)
		(width 0.0889)
		(layer "In4.Cu")
		(net "P5E_CPU0_PE4_RX_DN<7>")
	)
	(segment
		(start 343.713562 -289.195002)
		(end 343.713562 -289.807142)
		(width 0.13208)
		(layer "F.Cu")
		(net "P5E_CPU0_PE4_RX_DN<6>")
	)
	(segment
		(start 341.77224 -292.885368)
		(end 341.77224 -292.86327)
		(width 0.0889)
		(layer "In4.Cu")
		(net "P5E_CPU0_PE4_RX_DN<6>")
	)
	(segment
		(start 308.71922 -332.915006)
		(end 317.332868 -324.301358)
		(width 0.14732)
		(layer "In4.Cu")
		(net "P5E_CPU0_PE4_RX_DN<6>")
	)
	(segment
		(start 326.650096 -434.48986)
		(end 326.650096 -434.174646)
		(width 0.14732)
		(layer "In4.Cu")
		(net "P5E_CPU0_PE4_RX_DN<6>")
	)
	(segment
		(start 324.185788 -404.784052)
		(end 324.185788 -398.869154)
		(width 0.14732)
		(layer "In4.Cu")
		(net "P5E_CPU0_PE4_RX_DN<6>")
	)
	(segment
		(start 344.088212 -290.051998)
		(end 344.088212 -289.645852)
		(width 0.0889)
		(layer "In4.Cu")
		(net "P5E_CPU0_PE4_RX_DN<6>")
	)
	(segment
		(start 326.502522 -434.027072)
		(end 325.990204 -434.027072)
		(width 0.14732)
		(layer "In4.Cu")
		(net "P5E_CPU0_PE4_RX_DN<6>")
	)
	(segment
		(start 317.332868 -324.301358)
		(end 317.332868 -324.002654)
		(width 0.14732)
		(layer "In4.Cu")
		(net "P5E_CPU0_PE4_RX_DN<6>")
	)
	(segment
		(start 341.77224 -292.86327)
		(end 341.81415 -292.82136)
		(width 0.0889)
		(layer "In4.Cu")
		(net "P5E_CPU0_PE4_RX_DN<6>")
	)
	(segment
		(start 343.554812 -289.506152)
		(end 343.713562 -289.807142)
		(width 0.0889)
		(layer "In4.Cu")
		(net "P5E_CPU0_PE4_RX_DN<6>")
	)
	(segment
		(start 324.185788 -398.869154)
		(end 308.71922 -344.39479)
		(width 0.14732)
		(layer "In4.Cu")
		(net "P5E_CPU0_PE4_RX_DN<6>")
	)
	(segment
		(start 341.16264 -300.172882)
		(end 341.77224 -296.720768)
		(width 0.14732)
		(layer "In4.Cu")
		(net "P5E_CPU0_PE4_RX_DN<6>")
	)
	(segment
		(start 326.650096 -434.174646)
		(end 326.502522 -434.027072)
		(width 0.14732)
		(layer "In4.Cu")
		(net "P5E_CPU0_PE4_RX_DN<6>")
	)
	(segment
		(start 341.81415 -292.82136)
		(end 341.81415 -292.32606)
		(width 0.0889)
		(layer "In4.Cu")
		(net "P5E_CPU0_PE4_RX_DN<6>")
	)
	(segment
		(start 308.71922 -344.39479)
		(end 308.71922 -332.915006)
		(width 0.14732)
		(layer "In4.Cu")
		(net "P5E_CPU0_PE4_RX_DN<6>")
	)
	(segment
		(start 325.679308 -433.716176)
		(end 325.679308 -420.594536)
		(width 0.14732)
		(layer "In4.Cu")
		(net "P5E_CPU0_PE4_RX_DN<6>")
	)
	(segment
		(start 325.726298 -420.547546)
		(end 325.726298 -412.836868)
		(width 0.14732)
		(layer "In4.Cu")
		(net "P5E_CPU0_PE4_RX_DN<6>")
	)
	(segment
		(start 325.531988 -409.912058)
		(end 325.531988 -406.130252)
		(width 0.14732)
		(layer "In4.Cu")
		(net "P5E_CPU0_PE4_RX_DN<6>")
	)
	(segment
		(start 341.77224 -296.720768)
		(end 341.77224 -292.885368)
		(width 0.14732)
		(layer "In4.Cu")
		(net "P5E_CPU0_PE4_RX_DN<6>")
	)
	(segment
		(start 325.990204 -434.027072)
		(end 325.679308 -433.716176)
		(width 0.14732)
		(layer "In4.Cu")
		(net "P5E_CPU0_PE4_RX_DN<6>")
	)
	(segment
		(start 325.679308 -420.594536)
		(end 325.726298 -420.547546)
		(width 0.14732)
		(layer "In4.Cu")
		(net "P5E_CPU0_PE4_RX_DN<6>")
	)
	(segment
		(start 325.531988 -406.130252)
		(end 324.185788 -404.784052)
		(width 0.14732)
		(layer "In4.Cu")
		(net "P5E_CPU0_PE4_RX_DN<6>")
	)
	(segment
		(start 341.81415 -292.32606)
		(end 344.088212 -290.051998)
		(width 0.0889)
		(layer "In4.Cu")
		(net "P5E_CPU0_PE4_RX_DN<6>")
	)
	(segment
		(start 317.332868 -324.002654)
		(end 341.16264 -300.172882)
		(width 0.14732)
		(layer "In4.Cu")
		(net "P5E_CPU0_PE4_RX_DN<6>")
	)
	(segment
		(start 325.726298 -412.836868)
		(end 325.531988 -409.912058)
		(width 0.14732)
		(layer "In4.Cu")
		(net "P5E_CPU0_PE4_RX_DN<6>")
	)
	(segment
		(start 343.581228 -289.42157)
		(end 343.554812 -289.506152)
		(width 0.0889)
		(layer "In4.Cu")
		(net "P5E_CPU0_PE4_RX_DN<6>")
	)
	(arc
		(start 344.088212 -289.645852)
		(mid 343.878677 -289.434449)
		(end 343.581228 -289.42157)
		(width 0.0889)
		(layer "In4.Cu")
		(net "P5E_CPU0_PE4_RX_DN<6>")
	)
	(segment
		(start 342.773762 -287.567116)
		(end 342.773762 -288.102802)
		(width 0.13208)
		(layer "F.Cu")
		(net "P5E_CPU0_PE4_RX_DN<5>")
	)
	(segment
		(start 342.773762 -288.102802)
		(end 342.774016 -288.103056)
		(width 0.13208)
		(layer "F.Cu")
		(net "P5E_CPU0_PE4_RX_DN<5>")
	)
	(segment
		(start 323.205856 -415.088578)
		(end 323.244972 -415.523934)
		(width 0.14732)
		(layer "In4.Cu")
		(net "P5E_CPU0_PE4_RX_DN<5>")
	)
	(segment
		(start 316.453774 -324.244462)
		(end 308.05755 -332.640686)
		(width 0.14732)
		(layer "In4.Cu")
		(net "P5E_CPU0_PE4_RX_DN<5>")
	)
	(segment
		(start 323.244972 -415.523934)
		(end 323.132196 -415.659062)
		(width 0.14732)
		(layer "In4.Cu")
		(net "P5E_CPU0_PE4_RX_DN<5>")
	)
	(segment
		(start 335.854802 -296.886122)
		(end 335.854802 -298.772072)
		(width 0.14732)
		(layer "In4.Cu")
		(net "P5E_CPU0_PE4_RX_DN<5>")
	)
	(segment
		(start 341.109046 -292.86327)
		(end 341.109046 -292.885368)
		(width 0.0889)
		(layer "In4.Cu")
		(net "P5E_CPU0_PE4_RX_DN<5>")
	)
	(segment
		(start 323.96684 -425.029376)
		(end 323.96684 -434.60543)
		(width 0.14732)
		(layer "In4.Cu")
		(net "P5E_CPU0_PE4_RX_DN<5>")
	)
	(segment
		(start 322.93052 -413.422338)
		(end 322.969636 -413.85744)
		(width 0.14732)
		(layer "In4.Cu")
		(net "P5E_CPU0_PE4_RX_DN<5>")
	)
	(segment
		(start 323.144134 -414.405572)
		(end 323.031358 -414.5407)
		(width 0.14732)
		(layer "In4.Cu")
		(net "P5E_CPU0_PE4_RX_DN<5>")
	)
	(segment
		(start 343.338912 -289.60953)
		(end 343.338658 -289.609276)
		(width 0.0889)
		(layer "In4.Cu")
		(net "P5E_CPU0_PE4_RX_DN<5>")
	)
	(segment
		(start 322.969636 -413.85744)
		(end 323.105018 -413.970216)
		(width 0.14732)
		(layer "In4.Cu")
		(net "P5E_CPU0_PE4_RX_DN<5>")
	)
	(segment
		(start 339.290406 -295.041828)
		(end 337.369912 -295.041828)
		(width 0.14732)
		(layer "In4.Cu")
		(net "P5E_CPU0_PE4_RX_DN<5>")
	)
	(segment
		(start 342.617552 -288.374074)
		(end 342.641682 -288.463228)
		(width 0.0889)
		(layer "In4.Cu")
		(net "P5E_CPU0_PE4_RX_DN<5>")
	)
	(segment
		(start 342.774016 -288.103056)
		(end 342.617552 -288.374074)
		(width 0.0889)
		(layer "In4.Cu")
		(net "P5E_CPU0_PE4_RX_DN<5>")
	)
	(segment
		(start 341.066882 -292.349428)
		(end 341.066882 -292.821106)
		(width 0.0889)
		(layer "In4.Cu")
		(net "P5E_CPU0_PE4_RX_DN<5>")
	)
	(segment
		(start 343.338658 -290.077652)
		(end 341.066882 -292.349428)
		(width 0.0889)
		(layer "In4.Cu")
		(net "P5E_CPU0_PE4_RX_DN<5>")
	)
	(segment
		(start 336.087974 -296.323766)
		(end 335.854802 -296.886122)
		(width 0.14732)
		(layer "In4.Cu")
		(net "P5E_CPU0_PE4_RX_DN<5>")
	)
	(segment
		(start 321.396868 -398.629378)
		(end 321.396868 -404.67026)
		(width 0.14732)
		(layer "In4.Cu")
		(net "P5E_CPU0_PE4_RX_DN<5>")
	)
	(segment
		(start 321.396868 -404.67026)
		(end 322.743068 -406.01646)
		(width 0.14732)
		(layer "In4.Cu")
		(net "P5E_CPU0_PE4_RX_DN<5>")
	)
	(segment
		(start 323.939154 -424.628818)
		(end 323.96684 -425.029376)
		(width 0.14732)
		(layer "In4.Cu")
		(net "P5E_CPU0_PE4_RX_DN<5>")
	)
	(segment
		(start 308.05755 -344.600276)
		(end 321.396868 -398.629378)
		(width 0.14732)
		(layer "In4.Cu")
		(net "P5E_CPU0_PE4_RX_DN<5>")
	)
	(segment
		(start 323.96684 -434.60543)
		(end 324.11416 -434.75275)
		(width 0.14732)
		(layer "In4.Cu")
		(net "P5E_CPU0_PE4_RX_DN<5>")
	)
	(segment
		(start 323.031358 -414.5407)
		(end 323.070474 -414.975802)
		(width 0.14732)
		(layer "In4.Cu")
		(net "P5E_CPU0_PE4_RX_DN<5>")
	)
	(segment
		(start 341.109046 -292.885368)
		(end 341.109046 -293.223188)
		(width 0.14732)
		(layer "In4.Cu")
		(net "P5E_CPU0_PE4_RX_DN<5>")
	)
	(segment
		(start 341.066882 -292.821106)
		(end 341.109046 -292.86327)
		(width 0.0889)
		(layer "In4.Cu")
		(net "P5E_CPU0_PE4_RX_DN<5>")
	)
	(segment
		(start 335.854802 -298.772072)
		(end 334.62087 -305.769518)
		(width 0.14732)
		(layer "In4.Cu")
		(net "P5E_CPU0_PE4_RX_DN<5>")
	)
	(segment
		(start 323.043296 -413.28721)
		(end 322.93052 -413.422338)
		(width 0.14732)
		(layer "In4.Cu")
		(net "P5E_CPU0_PE4_RX_DN<5>")
	)
	(segment
		(start 341.109046 -293.223188)
		(end 339.290406 -295.041828)
		(width 0.14732)
		(layer "In4.Cu")
		(net "P5E_CPU0_PE4_RX_DN<5>")
	)
	(segment
		(start 334.62087 -305.769518)
		(end 316.453774 -323.936614)
		(width 0.14732)
		(layer "In4.Cu")
		(net "P5E_CPU0_PE4_RX_DN<5>")
	)
	(segment
		(start 324.438518 -434.75275)
		(end 324.6501 -434.541168)
		(width 0.14732)
		(layer "In4.Cu")
		(net "P5E_CPU0_PE4_RX_DN<5>")
	)
	(segment
		(start 316.453774 -323.936614)
		(end 316.453774 -324.244462)
		(width 0.14732)
		(layer "In4.Cu")
		(net "P5E_CPU0_PE4_RX_DN<5>")
	)
	(segment
		(start 342.869266 -288.898584)
		(end 342.869266 -289.078416)
		(width 0.0889)
		(layer "In4.Cu")
		(net "P5E_CPU0_PE4_RX_DN<5>")
	)
	(segment
		(start 323.003926 -412.851854)
		(end 323.043296 -413.28721)
		(width 0.14732)
		(layer "In4.Cu")
		(net "P5E_CPU0_PE4_RX_DN<5>")
	)
	(segment
		(start 324.11416 -434.75275)
		(end 324.438518 -434.75275)
		(width 0.14732)
		(layer "In4.Cu")
		(net "P5E_CPU0_PE4_RX_DN<5>")
	)
	(segment
		(start 322.743068 -406.01646)
		(end 322.743068 -411.342586)
		(width 0.14732)
		(layer "In4.Cu")
		(net "P5E_CPU0_PE4_RX_DN<5>")
	)
	(segment
		(start 343.338658 -289.609276)
		(end 343.338658 -290.077652)
		(width 0.0889)
		(layer "In4.Cu")
		(net "P5E_CPU0_PE4_RX_DN<5>")
	)
	(segment
		(start 324.6501 -434.541168)
		(end 324.6501 -434.289962)
		(width 0.14732)
		(layer "In4.Cu")
		(net "P5E_CPU0_PE4_RX_DN<5>")
	)
	(segment
		(start 322.868798 -412.739078)
		(end 323.003926 -412.851854)
		(width 0.14732)
		(layer "In4.Cu")
		(net "P5E_CPU0_PE4_RX_DN<5>")
	)
	(segment
		(start 323.132196 -415.659062)
		(end 323.939154 -424.628818)
		(width 0.14732)
		(layer "In4.Cu")
		(net "P5E_CPU0_PE4_RX_DN<5>")
	)
	(segment
		(start 337.369912 -295.041828)
		(end 336.087974 -296.323766)
		(width 0.14732)
		(layer "In4.Cu")
		(net "P5E_CPU0_PE4_RX_DN<5>")
	)
	(segment
		(start 322.743068 -411.342586)
		(end 322.868798 -412.739078)
		(width 0.14732)
		(layer "In4.Cu")
		(net "P5E_CPU0_PE4_RX_DN<5>")
	)
	(segment
		(start 323.105018 -413.970216)
		(end 323.144134 -414.405572)
		(width 0.14732)
		(layer "In4.Cu")
		(net "P5E_CPU0_PE4_RX_DN<5>")
	)
	(segment
		(start 323.070474 -414.975802)
		(end 323.205856 -415.088578)
		(width 0.14732)
		(layer "In4.Cu")
		(net "P5E_CPU0_PE4_RX_DN<5>")
	)
	(segment
		(start 308.05755 -332.640686)
		(end 308.05755 -344.600276)
		(width 0.14732)
		(layer "In4.Cu")
		(net "P5E_CPU0_PE4_RX_DN<5>")
	)
	(arc
		(start 342.641682 -288.463228)
		(mid 342.650254 -288.469751)
		(end 342.6587 -288.476436)
		(width 0.0889)
		(layer "In4.Cu")
		(net "P5E_CPU0_PE4_RX_DN<5>")
	)
	(arc
		(start 342.6587 -288.476436)
		(mid 342.810104 -288.664503)
		(end 342.869266 -288.898584)
		(width 0.0889)
		(layer "In4.Cu")
		(net "P5E_CPU0_PE4_RX_DN<5>")
	)
	(arc
		(start 342.869266 -289.078416)
		(mid 342.944271 -289.193875)
		(end 343.053416 -289.277806)
		(width 0.0889)
		(layer "In4.Cu")
		(net "P5E_CPU0_PE4_RX_DN<5>")
	)
	(arc
		(start 343.053416 -289.277806)
		(mid 343.227548 -289.416653)
		(end 343.338912 -289.60953)
		(width 0.0889)
		(layer "In4.Cu")
		(net "P5E_CPU0_PE4_RX_DN<5>")
	)
	(segment
		(start 341.833962 -289.195002)
		(end 341.833962 -289.807142)
		(width 0.13208)
		(layer "F.Cu")
		(net "P5E_CPU0_PE4_RX_DN<4>")
	)
	(segment
		(start 340.307168 -291.894768)
		(end 340.403434 -291.798502)
		(width 0.0889)
		(layer "In4.Cu")
		(net "P5E_CPU0_PE4_RX_DN<4>")
	)
	(segment
		(start 340.24824 -291.894768)
		(end 340.307168 -291.894768)
		(width 0.0889)
		(layer "In4.Cu")
		(net "P5E_CPU0_PE4_RX_DN<4>")
	)
	(segment
		(start 321.692524 -424.518328)
		(end 319.405508 -410.727398)
		(width 0.14732)
		(layer "In4.Cu")
		(net "P5E_CPU0_PE4_RX_DN<4>")
	)
	(segment
		(start 340.403434 -291.798502)
		(end 342.208866 -289.993324)
		(width 0.0889)
		(layer "In4.Cu")
		(net "P5E_CPU0_PE4_RX_DN<4>")
	)
	(segment
		(start 322.650104 -434.48986)
		(end 322.650104 -434.174646)
		(width 0.14732)
		(layer "In4.Cu")
		(net "P5E_CPU0_PE4_RX_DN<4>")
	)
	(segment
		(start 335.081118 -295.607486)
		(end 336.86496 -293.823644)
		(width 0.14732)
		(layer "In4.Cu")
		(net "P5E_CPU0_PE4_RX_DN<4>")
	)
	(segment
		(start 341.701628 -289.42157)
		(end 341.675212 -289.506152)
		(width 0.0889)
		(layer "In4.Cu")
		(net "P5E_CPU0_PE4_RX_DN<4>")
	)
	(segment
		(start 315.078364 -323.568568)
		(end 333.492094 -305.154838)
		(width 0.14732)
		(layer "In4.Cu")
		(net "P5E_CPU0_PE4_RX_DN<4>")
	)
	(segment
		(start 322.650104 -434.174646)
		(end 322.50253 -434.027072)
		(width 0.14732)
		(layer "In4.Cu")
		(net "P5E_CPU0_PE4_RX_DN<4>")
	)
	(segment
		(start 308.947058 -328.568558)
		(end 308.947058 -326.464676)
		(width 0.14732)
		(layer "In4.Cu")
		(net "P5E_CPU0_PE4_RX_DN<4>")
	)
	(segment
		(start 319.405508 -410.727398)
		(end 319.405508 -406.130252)
		(width 0.14732)
		(layer "In4.Cu")
		(net "P5E_CPU0_PE4_RX_DN<4>")
	)
	(segment
		(start 318.059308 -398.556226)
		(end 306.77866 -344.494866)
		(width 0.14732)
		(layer "In4.Cu")
		(net "P5E_CPU0_PE4_RX_DN<4>")
	)
	(segment
		(start 309.834026 -325.577708)
		(end 313.392312 -325.577708)
		(width 0.14732)
		(layer "In4.Cu")
		(net "P5E_CPU0_PE4_RX_DN<4>")
	)
	(segment
		(start 336.86496 -293.823644)
		(end 338.319364 -293.823644)
		(width 0.14732)
		(layer "In4.Cu")
		(net "P5E_CPU0_PE4_RX_DN<4>")
	)
	(segment
		(start 319.405508 -406.130252)
		(end 318.059308 -404.784052)
		(width 0.14732)
		(layer "In4.Cu")
		(net "P5E_CPU0_PE4_RX_DN<4>")
	)
	(segment
		(start 308.947058 -326.464676)
		(end 309.834026 -325.577708)
		(width 0.14732)
		(layer "In4.Cu")
		(net "P5E_CPU0_PE4_RX_DN<4>")
	)
	(segment
		(start 338.319364 -293.823644)
		(end 340.232746 -291.910262)
		(width 0.14732)
		(layer "In4.Cu")
		(net "P5E_CPU0_PE4_RX_DN<4>")
	)
	(segment
		(start 322.50253 -434.027072)
		(end 322.000372 -434.027072)
		(width 0.14732)
		(layer "In4.Cu")
		(net "P5E_CPU0_PE4_RX_DN<4>")
	)
	(segment
		(start 307.900832 -331.094334)
		(end 308.947058 -328.568558)
		(width 0.14732)
		(layer "In4.Cu")
		(net "P5E_CPU0_PE4_RX_DN<4>")
	)
	(segment
		(start 315.078364 -323.891656)
		(end 315.078364 -323.568568)
		(width 0.14732)
		(layer "In4.Cu")
		(net "P5E_CPU0_PE4_RX_DN<4>")
	)
	(segment
		(start 306.77866 -332.216506)
		(end 307.900832 -331.094334)
		(width 0.14732)
		(layer "In4.Cu")
		(net "P5E_CPU0_PE4_RX_DN<4>")
	)
	(segment
		(start 313.392312 -325.577708)
		(end 315.078364 -323.891656)
		(width 0.14732)
		(layer "In4.Cu")
		(net "P5E_CPU0_PE4_RX_DN<4>")
	)
	(segment
		(start 334.650842 -296.646092)
		(end 335.081118 -295.607486)
		(width 0.14732)
		(layer "In4.Cu")
		(net "P5E_CPU0_PE4_RX_DN<4>")
	)
	(segment
		(start 340.232746 -291.910262)
		(end 340.24824 -291.894768)
		(width 0.0889)
		(layer "In4.Cu")
		(net "P5E_CPU0_PE4_RX_DN<4>")
	)
	(segment
		(start 341.675212 -289.506152)
		(end 341.833962 -289.807142)
		(width 0.0889)
		(layer "In4.Cu")
		(net "P5E_CPU0_PE4_RX_DN<4>")
	)
	(segment
		(start 342.208866 -289.64636)
		(end 342.208612 -289.645852)
		(width 0.0889)
		(layer "In4.Cu")
		(net "P5E_CPU0_PE4_RX_DN<4>")
	)
	(segment
		(start 306.77866 -344.494866)
		(end 306.77866 -332.216506)
		(width 0.14732)
		(layer "In4.Cu")
		(net "P5E_CPU0_PE4_RX_DN<4>")
	)
	(segment
		(start 318.059308 -404.784052)
		(end 318.059308 -398.556226)
		(width 0.14732)
		(layer "In4.Cu")
		(net "P5E_CPU0_PE4_RX_DN<4>")
	)
	(segment
		(start 342.208866 -289.993324)
		(end 342.208866 -289.64636)
		(width 0.0889)
		(layer "In4.Cu")
		(net "P5E_CPU0_PE4_RX_DN<4>")
	)
	(segment
		(start 333.492094 -305.154838)
		(end 334.650842 -298.584366)
		(width 0.14732)
		(layer "In4.Cu")
		(net "P5E_CPU0_PE4_RX_DN<4>")
	)
	(segment
		(start 321.692524 -433.719224)
		(end 321.692524 -424.518328)
		(width 0.14732)
		(layer "In4.Cu")
		(net "P5E_CPU0_PE4_RX_DN<4>")
	)
	(segment
		(start 322.000372 -434.027072)
		(end 321.692524 -433.719224)
		(width 0.14732)
		(layer "In4.Cu")
		(net "P5E_CPU0_PE4_RX_DN<4>")
	)
	(segment
		(start 334.650842 -298.584366)
		(end 334.650842 -296.646092)
		(width 0.14732)
		(layer "In4.Cu")
		(net "P5E_CPU0_PE4_RX_DN<4>")
	)
	(arc
		(start 342.208612 -289.645852)
		(mid 341.999077 -289.434449)
		(end 341.701628 -289.42157)
		(width 0.0889)
		(layer "In4.Cu")
		(net "P5E_CPU0_PE4_RX_DN<4>")
	)
	(segment
		(start 340.894162 -288.102802)
		(end 340.894416 -288.103056)
		(width 0.13208)
		(layer "F.Cu")
		(net "P5E_CPU0_PE4_RX_DN<3>")
	)
	(segment
		(start 340.894162 -287.567116)
		(end 340.894162 -288.102802)
		(width 0.13208)
		(layer "F.Cu")
		(net "P5E_CPU0_PE4_RX_DN<3>")
	)
	(segment
		(start 317.323216 -413.596328)
		(end 317.426086 -414.020762)
		(width 0.14732)
		(layer "In4.Cu")
		(net "P5E_CPU0_PE4_RX_DN<3>")
	)
	(segment
		(start 316.616588 -410.686504)
		(end 317.161164 -412.929578)
		(width 0.14732)
		(layer "In4.Cu")
		(net "P5E_CPU0_PE4_RX_DN<3>")
	)
	(segment
		(start 333.930752 -296.671746)
		(end 333.930752 -298.893738)
		(width 0.14732)
		(layer "In4.Cu")
		(net "P5E_CPU0_PE4_RX_DN<3>")
	)
	(segment
		(start 339.77199 -291.382958)
		(end 339.756496 -291.398452)
		(width 0.0889)
		(layer "In4.Cu")
		(net "P5E_CPU0_PE4_RX_DN<3>")
	)
	(segment
		(start 341.459312 -289.60953)
		(end 341.459058 -289.609276)
		(width 0.0889)
		(layer "In4.Cu")
		(net "P5E_CPU0_PE4_RX_DN<3>")
	)
	(segment
		(start 317.84163 -415.20364)
		(end 317.944754 -415.628328)
		(width 0.14732)
		(layer "In4.Cu")
		(net "P5E_CPU0_PE4_RX_DN<3>")
	)
	(segment
		(start 340.894416 -288.103056)
		(end 340.737952 -288.374074)
		(width 0.0889)
		(layer "In4.Cu")
		(net "P5E_CPU0_PE4_RX_DN<3>")
	)
	(segment
		(start 332.902052 -304.72634)
		(end 314.358274 -323.270118)
		(width 0.14732)
		(layer "In4.Cu")
		(net "P5E_CPU0_PE4_RX_DN<3>")
	)
	(segment
		(start 317.414656 -413.44596)
		(end 317.323216 -413.596328)
		(width 0.14732)
		(layer "In4.Cu")
		(net "P5E_CPU0_PE4_RX_DN<3>")
	)
	(segment
		(start 315.270388 -404.67026)
		(end 316.616588 -406.01646)
		(width 0.14732)
		(layer "In4.Cu")
		(net "P5E_CPU0_PE4_RX_DN<3>")
	)
	(segment
		(start 339.756496 -291.398452)
		(end 338.051394 -293.103554)
		(width 0.14732)
		(layer "In4.Cu")
		(net "P5E_CPU0_PE4_RX_DN<3>")
	)
	(segment
		(start 306.117244 -331.658976)
		(end 306.117244 -344.694764)
		(width 0.14732)
		(layer "In4.Cu")
		(net "P5E_CPU0_PE4_RX_DN<3>")
	)
	(segment
		(start 340.989666 -288.898584)
		(end 340.989666 -289.078416)
		(width 0.0889)
		(layer "In4.Cu")
		(net "P5E_CPU0_PE4_RX_DN<3>")
	)
	(segment
		(start 308.285642 -326.184006)
		(end 308.285642 -328.39533)
		(width 0.14732)
		(layer "In4.Cu")
		(net "P5E_CPU0_PE4_RX_DN<3>")
	)
	(segment
		(start 339.952838 -291.142166)
		(end 339.77199 -291.323014)
		(width 0.0889)
		(layer "In4.Cu")
		(net "P5E_CPU0_PE4_RX_DN<3>")
	)
	(segment
		(start 307.511196 -330.265024)
		(end 306.117244 -331.658976)
		(width 0.14732)
		(layer "In4.Cu")
		(net "P5E_CPU0_PE4_RX_DN<3>")
	)
	(segment
		(start 308.285642 -328.39533)
		(end 307.511196 -330.265024)
		(width 0.14732)
		(layer "In4.Cu")
		(net "P5E_CPU0_PE4_RX_DN<3>")
	)
	(segment
		(start 317.426086 -414.020762)
		(end 317.576708 -414.112456)
		(width 0.14732)
		(layer "In4.Cu")
		(net "P5E_CPU0_PE4_RX_DN<3>")
	)
	(segment
		(start 317.691008 -415.111946)
		(end 317.84163 -415.20364)
		(width 0.14732)
		(layer "In4.Cu")
		(net "P5E_CPU0_PE4_RX_DN<3>")
	)
	(segment
		(start 317.588138 -414.687512)
		(end 317.691008 -415.111946)
		(width 0.14732)
		(layer "In4.Cu")
		(net "P5E_CPU0_PE4_RX_DN<3>")
	)
	(segment
		(start 320.438526 -434.75275)
		(end 320.650108 -434.541168)
		(width 0.14732)
		(layer "In4.Cu")
		(net "P5E_CPU0_PE4_RX_DN<3>")
	)
	(segment
		(start 317.679832 -414.537144)
		(end 317.588138 -414.687512)
		(width 0.14732)
		(layer "In4.Cu")
		(net "P5E_CPU0_PE4_RX_DN<3>")
	)
	(segment
		(start 314.358274 -323.270118)
		(end 314.358274 -323.676264)
		(width 0.14732)
		(layer "In4.Cu")
		(net "P5E_CPU0_PE4_RX_DN<3>")
	)
	(segment
		(start 320.650108 -434.541168)
		(end 320.650108 -434.289962)
		(width 0.14732)
		(layer "In4.Cu")
		(net "P5E_CPU0_PE4_RX_DN<3>")
	)
	(segment
		(start 317.576708 -414.112456)
		(end 317.679832 -414.537144)
		(width 0.14732)
		(layer "In4.Cu")
		(net "P5E_CPU0_PE4_RX_DN<3>")
	)
	(segment
		(start 317.85306 -415.778696)
		(end 317.95593 -416.20313)
		(width 0.14732)
		(layer "In4.Cu")
		(net "P5E_CPU0_PE4_RX_DN<3>")
	)
	(segment
		(start 341.327994 -290.198302)
		(end 339.952838 -291.142166)
		(width 0.0889)
		(layer "In4.Cu")
		(net "P5E_CPU0_PE4_RX_DN<3>")
	)
	(segment
		(start 338.051394 -293.103554)
		(end 336.56651 -293.103554)
		(width 0.14732)
		(layer "In4.Cu")
		(net "P5E_CPU0_PE4_RX_DN<3>")
	)
	(segment
		(start 318.209676 -416.719512)
		(end 318.117982 -416.86988)
		(width 0.14732)
		(layer "In4.Cu")
		(net "P5E_CPU0_PE4_RX_DN<3>")
	)
	(segment
		(start 341.459058 -289.609276)
		(end 341.459058 -289.949128)
		(width 0.0889)
		(layer "In4.Cu")
		(net "P5E_CPU0_PE4_RX_DN<3>")
	)
	(segment
		(start 306.117244 -344.694764)
		(end 315.270388 -398.381474)
		(width 0.14732)
		(layer "In4.Cu")
		(net "P5E_CPU0_PE4_RX_DN<3>")
	)
	(segment
		(start 340.737952 -288.374074)
		(end 340.762082 -288.463228)
		(width 0.0889)
		(layer "In4.Cu")
		(net "P5E_CPU0_PE4_RX_DN<3>")
	)
	(segment
		(start 317.161164 -412.929578)
		(end 317.311786 -413.021272)
		(width 0.14732)
		(layer "In4.Cu")
		(net "P5E_CPU0_PE4_RX_DN<3>")
	)
	(segment
		(start 315.270388 -398.381474)
		(end 315.270388 -404.67026)
		(width 0.14732)
		(layer "In4.Cu")
		(net "P5E_CPU0_PE4_RX_DN<3>")
	)
	(segment
		(start 320.114168 -434.75275)
		(end 320.438526 -434.75275)
		(width 0.14732)
		(layer "In4.Cu")
		(net "P5E_CPU0_PE4_RX_DN<3>")
	)
	(segment
		(start 318.106552 -416.294824)
		(end 318.209676 -416.719512)
		(width 0.14732)
		(layer "In4.Cu")
		(net "P5E_CPU0_PE4_RX_DN<3>")
	)
	(segment
		(start 341.459058 -289.949128)
		(end 341.327994 -290.198302)
		(width 0.0889)
		(layer "In4.Cu")
		(net "P5E_CPU0_PE4_RX_DN<3>")
	)
	(segment
		(start 318.117982 -416.86988)
		(end 319.966848 -424.485308)
		(width 0.14732)
		(layer "In4.Cu")
		(net "P5E_CPU0_PE4_RX_DN<3>")
	)
	(segment
		(start 317.95593 -416.20313)
		(end 318.106552 -416.294824)
		(width 0.14732)
		(layer "In4.Cu")
		(net "P5E_CPU0_PE4_RX_DN<3>")
	)
	(segment
		(start 316.616588 -406.01646)
		(end 316.616588 -410.686504)
		(width 0.14732)
		(layer "In4.Cu")
		(net "P5E_CPU0_PE4_RX_DN<3>")
	)
	(segment
		(start 336.56651 -293.103554)
		(end 334.59039 -295.079674)
		(width 0.14732)
		(layer "In4.Cu")
		(net "P5E_CPU0_PE4_RX_DN<3>")
	)
	(segment
		(start 339.77199 -291.323014)
		(end 339.77199 -291.382958)
		(width 0.0889)
		(layer "In4.Cu")
		(net "P5E_CPU0_PE4_RX_DN<3>")
	)
	(segment
		(start 334.59039 -295.079674)
		(end 333.930752 -296.671746)
		(width 0.14732)
		(layer "In4.Cu")
		(net "P5E_CPU0_PE4_RX_DN<3>")
	)
	(segment
		(start 314.358274 -323.676264)
		(end 313.118246 -324.916292)
		(width 0.14732)
		(layer "In4.Cu")
		(net "P5E_CPU0_PE4_RX_DN<3>")
	)
	(segment
		(start 309.553356 -324.916292)
		(end 308.285642 -326.184006)
		(width 0.14732)
		(layer "In4.Cu")
		(net "P5E_CPU0_PE4_RX_DN<3>")
	)
	(segment
		(start 313.118246 -324.916292)
		(end 309.553356 -324.916292)
		(width 0.14732)
		(layer "In4.Cu")
		(net "P5E_CPU0_PE4_RX_DN<3>")
	)
	(segment
		(start 333.930752 -298.893738)
		(end 332.902052 -304.72634)
		(width 0.14732)
		(layer "In4.Cu")
		(net "P5E_CPU0_PE4_RX_DN<3>")
	)
	(segment
		(start 317.944754 -415.628328)
		(end 317.85306 -415.778696)
		(width 0.14732)
		(layer "In4.Cu")
		(net "P5E_CPU0_PE4_RX_DN<3>")
	)
	(segment
		(start 317.311786 -413.021272)
		(end 317.414656 -413.44596)
		(width 0.14732)
		(layer "In4.Cu")
		(net "P5E_CPU0_PE4_RX_DN<3>")
	)
	(segment
		(start 319.966848 -434.60543)
		(end 320.114168 -434.75275)
		(width 0.14732)
		(layer "In4.Cu")
		(net "P5E_CPU0_PE4_RX_DN<3>")
	)
	(segment
		(start 319.966848 -424.485308)
		(end 319.966848 -434.60543)
		(width 0.14732)
		(layer "In4.Cu")
		(net "P5E_CPU0_PE4_RX_DN<3>")
	)
	(arc
		(start 340.762082 -288.463228)
		(mid 340.770654 -288.469751)
		(end 340.7791 -288.476436)
		(width 0.0889)
		(layer "In4.Cu")
		(net "P5E_CPU0_PE4_RX_DN<3>")
	)
	(arc
		(start 340.7791 -288.476436)
		(mid 340.930504 -288.664503)
		(end 340.989666 -288.898584)
		(width 0.0889)
		(layer "In4.Cu")
		(net "P5E_CPU0_PE4_RX_DN<3>")
	)
	(arc
		(start 341.173816 -289.277806)
		(mid 341.347948 -289.416653)
		(end 341.459312 -289.60953)
		(width 0.0889)
		(layer "In4.Cu")
		(net "P5E_CPU0_PE4_RX_DN<3>")
	)
	(arc
		(start 340.989666 -289.078416)
		(mid 341.064671 -289.193875)
		(end 341.173816 -289.277806)
		(width 0.0889)
		(layer "In4.Cu")
		(net "P5E_CPU0_PE4_RX_DN<3>")
	)
	(segment
		(start 339.954362 -289.195002)
		(end 339.954362 -289.807142)
		(width 0.13208)
		(layer "F.Cu")
		(net "P5E_CPU0_PE4_RX_DN<2>")
	)
	(segment
		(start 307.059076 -328.056748)
		(end 307.059076 -325.692516)
		(width 0.14732)
		(layer "In4.Cu")
		(net "P5E_CPU0_PE4_RX_DN<2>")
	)
	(segment
		(start 340.011004 -290.311332)
		(end 340.329266 -289.993324)
		(width 0.0889)
		(layer "In4.Cu")
		(net "P5E_CPU0_PE4_RX_DN<2>")
	)
	(segment
		(start 338.877656 -290.525708)
		(end 339.16874 -290.23437)
		(width 0.0889)
		(layer "In4.Cu")
		(net "P5E_CPU0_PE4_RX_DN<2>")
	)
	(segment
		(start 339.821774 -289.421062)
		(end 339.822028 -289.42157)
		(width 0.0889)
		(layer "In4.Cu")
		(net "P5E_CPU0_PE4_RX_DN<2>")
	)
	(segment
		(start 313.279028 -406.130252)
		(end 311.932828 -404.784052)
		(width 0.14732)
		(layer "In4.Cu")
		(net "P5E_CPU0_PE4_RX_DN<2>")
	)
	(segment
		(start 339.795612 -289.506152)
		(end 339.954362 -289.807142)
		(width 0.0889)
		(layer "In4.Cu")
		(net "P5E_CPU0_PE4_RX_DN<2>")
	)
	(segment
		(start 340.329266 -289.993324)
		(end 340.329266 -289.64509)
		(width 0.0889)
		(layer "In4.Cu")
		(net "P5E_CPU0_PE4_RX_DN<2>")
	)
	(segment
		(start 304.890678 -331.150468)
		(end 306.404518 -329.636628)
		(width 0.14732)
		(layer "In4.Cu")
		(net "P5E_CPU0_PE4_RX_DN<2>")
	)
	(segment
		(start 307.059076 -325.692516)
		(end 309.248302 -323.50329)
		(width 0.14732)
		(layer "In4.Cu")
		(net "P5E_CPU0_PE4_RX_DN<2>")
	)
	(segment
		(start 336.082132 -291.797994)
		(end 337.546442 -291.797994)
		(width 0.14732)
		(layer "In4.Cu")
		(net "P5E_CPU0_PE4_RX_DN<2>")
	)
	(segment
		(start 311.932828 -397.764)
		(end 304.890678 -344.746326)
		(width 0.14732)
		(layer "In4.Cu")
		(net "P5E_CPU0_PE4_RX_DN<2>")
	)
	(segment
		(start 306.404518 -329.636628)
		(end 307.059076 -328.056748)
		(width 0.14732)
		(layer "In4.Cu")
		(net "P5E_CPU0_PE4_RX_DN<2>")
	)
	(segment
		(start 332.710536 -296.410634)
		(end 333.587852 -294.292274)
		(width 0.14732)
		(layer "In4.Cu")
		(net "P5E_CPU0_PE4_RX_DN<2>")
	)
	(segment
		(start 318.650112 -434.174646)
		(end 318.502538 -434.027072)
		(width 0.14732)
		(layer "In4.Cu")
		(net "P5E_CPU0_PE4_RX_DN<2>")
	)
	(segment
		(start 313.279028 -410.972762)
		(end 313.279028 -406.130252)
		(width 0.14732)
		(layer "In4.Cu")
		(net "P5E_CPU0_PE4_RX_DN<2>")
	)
	(segment
		(start 332.710536 -298.413932)
		(end 332.710536 -296.410634)
		(width 0.14732)
		(layer "In4.Cu")
		(net "P5E_CPU0_PE4_RX_DN<2>")
	)
	(segment
		(start 331.686916 -304.215038)
		(end 332.710536 -298.413932)
		(width 0.14732)
		(layer "In4.Cu")
		(net "P5E_CPU0_PE4_RX_DN<2>")
	)
	(segment
		(start 313.27471 -322.627752)
		(end 331.686916 -304.215038)
		(width 0.14732)
		(layer "In4.Cu")
		(net "P5E_CPU0_PE4_RX_DN<2>")
	)
	(segment
		(start 318.502538 -434.027072)
		(end 318.00038 -434.027072)
		(width 0.14732)
		(layer "In4.Cu")
		(net "P5E_CPU0_PE4_RX_DN<2>")
	)
	(segment
		(start 338.818728 -290.525708)
		(end 338.877656 -290.525708)
		(width 0.0889)
		(layer "In4.Cu")
		(net "P5E_CPU0_PE4_RX_DN<2>")
	)
	(segment
		(start 311.159906 -323.50329)
		(end 313.27471 -322.627752)
		(width 0.14732)
		(layer "In4.Cu")
		(net "P5E_CPU0_PE4_RX_DN<2>")
	)
	(segment
		(start 338.803234 -290.541202)
		(end 338.818728 -290.525708)
		(width 0.0889)
		(layer "In4.Cu")
		(net "P5E_CPU0_PE4_RX_DN<2>")
	)
	(segment
		(start 317.692532 -424.442128)
		(end 313.279028 -410.972762)
		(width 0.14732)
		(layer "In4.Cu")
		(net "P5E_CPU0_PE4_RX_DN<2>")
	)
	(segment
		(start 339.16874 -290.23437)
		(end 340.011004 -290.311332)
		(width 0.0889)
		(layer "In4.Cu")
		(net "P5E_CPU0_PE4_RX_DN<2>")
	)
	(segment
		(start 318.00038 -434.027072)
		(end 317.692532 -433.719224)
		(width 0.14732)
		(layer "In4.Cu")
		(net "P5E_CPU0_PE4_RX_DN<2>")
	)
	(segment
		(start 304.890678 -344.746326)
		(end 304.890678 -331.150468)
		(width 0.14732)
		(layer "In4.Cu")
		(net "P5E_CPU0_PE4_RX_DN<2>")
	)
	(segment
		(start 333.587852 -294.292274)
		(end 336.082132 -291.797994)
		(width 0.14732)
		(layer "In4.Cu")
		(net "P5E_CPU0_PE4_RX_DN<2>")
	)
	(segment
		(start 309.248302 -323.50329)
		(end 311.159906 -323.50329)
		(width 0.14732)
		(layer "In4.Cu")
		(net "P5E_CPU0_PE4_RX_DN<2>")
	)
	(segment
		(start 311.932828 -404.784052)
		(end 311.932828 -397.764)
		(width 0.14732)
		(layer "In4.Cu")
		(net "P5E_CPU0_PE4_RX_DN<2>")
	)
	(segment
		(start 339.822028 -289.42157)
		(end 339.795612 -289.506152)
		(width 0.0889)
		(layer "In4.Cu")
		(net "P5E_CPU0_PE4_RX_DN<2>")
	)
	(segment
		(start 318.650112 -434.48986)
		(end 318.650112 -434.174646)
		(width 0.14732)
		(layer "In4.Cu")
		(net "P5E_CPU0_PE4_RX_DN<2>")
	)
	(segment
		(start 337.546442 -291.797994)
		(end 338.803234 -290.541202)
		(width 0.14732)
		(layer "In4.Cu")
		(net "P5E_CPU0_PE4_RX_DN<2>")
	)
	(segment
		(start 317.692532 -433.719224)
		(end 317.692532 -424.442128)
		(width 0.14732)
		(layer "In4.Cu")
		(net "P5E_CPU0_PE4_RX_DN<2>")
	)
	(arc
		(start 340.329266 -289.64509)
		(mid 340.119382 -289.433679)
		(end 339.821774 -289.421062)
		(width 0.0889)
		(layer "In4.Cu")
		(net "P5E_CPU0_PE4_RX_DN<2>")
	)
	(segment
		(start 339.014562 -287.567116)
		(end 339.014562 -288.103056)
		(width 0.13208)
		(layer "F.Cu")
		(net "P5E_CPU0_PE4_RX_DN<1>")
	)
	(segment
		(start 332.037182 -296.311828)
		(end 332.037182 -298.35475)
		(width 0.14732)
		(layer "In4.Cu")
		(net "P5E_CPU0_PE4_RX_DN<1>")
	)
	(segment
		(start 338.217002 -290.12515)
		(end 338.201508 -290.140644)
		(width 0.0889)
		(layer "In4.Cu")
		(net "P5E_CPU0_PE4_RX_DN<1>")
	)
	(segment
		(start 338.217002 -290.065206)
		(end 338.217002 -290.12515)
		(width 0.0889)
		(layer "In4.Cu")
		(net "P5E_CPU0_PE4_RX_DN<1>")
	)
	(segment
		(start 312.63717 -415.716212)
		(end 312.56732 -415.87801)
		(width 0.14732)
		(layer "In4.Cu")
		(net "P5E_CPU0_PE4_RX_DN<1>")
	)
	(segment
		(start 339.014562 -288.103056)
		(end 338.858098 -288.374074)
		(width 0.0889)
		(layer "In4.Cu")
		(net "P5E_CPU0_PE4_RX_DN<1>")
	)
	(segment
		(start 335.878424 -291.060378)
		(end 333.03464 -293.904162)
		(width 0.14732)
		(layer "In4.Cu")
		(net "P5E_CPU0_PE4_RX_DN<1>")
	)
	(segment
		(start 310.093106 -321.95516)
		(end 309.685182 -322.124324)
		(width 0.14732)
		(layer "In4.Cu")
		(net "P5E_CPU0_PE4_RX_DN<1>")
	)
	(segment
		(start 331.060552 -303.888902)
		(end 312.921396 -322.028058)
		(width 0.14732)
		(layer "In4.Cu")
		(net "P5E_CPU0_PE4_RX_DN<1>")
	)
	(segment
		(start 312.56732 -415.87801)
		(end 312.728356 -416.283902)
		(width 0.14732)
		(layer "In4.Cu")
		(net "P5E_CPU0_PE4_RX_DN<1>")
	)
	(segment
		(start 305.756564 -329.331828)
		(end 304.21707 -330.871322)
		(width 0.14732)
		(layer "In4.Cu")
		(net "P5E_CPU0_PE4_RX_DN<1>")
	)
	(segment
		(start 338.31276 -289.969448)
		(end 338.217002 -290.065206)
		(width 0.0889)
		(layer "In4.Cu")
		(net "P5E_CPU0_PE4_RX_DN<1>")
	)
	(segment
		(start 338.858098 -288.374074)
		(end 338.882228 -288.463228)
		(width 0.0889)
		(layer "In4.Cu")
		(net "P5E_CPU0_PE4_RX_DN<1>")
	)
	(segment
		(start 311.55005 -322.595748)
		(end 310.888126 -322.595748)
		(width 0.14732)
		(layer "In4.Cu")
		(net "P5E_CPU0_PE4_RX_DN<1>")
	)
	(segment
		(start 316.438534 -434.75275)
		(end 316.650116 -434.541168)
		(width 0.14732)
		(layer "In4.Cu")
		(net "P5E_CPU0_PE4_RX_DN<1>")
	)
	(segment
		(start 316.650116 -434.541168)
		(end 316.650116 -434.289962)
		(width 0.14732)
		(layer "In4.Cu")
		(net "P5E_CPU0_PE4_RX_DN<1>")
	)
	(segment
		(start 306.385468 -325.424038)
		(end 306.385468 -327.813416)
		(width 0.14732)
		(layer "In4.Cu")
		(net "P5E_CPU0_PE4_RX_DN<1>")
	)
	(segment
		(start 306.385468 -327.813416)
		(end 305.756564 -329.331828)
		(width 0.14732)
		(layer "In4.Cu")
		(net "P5E_CPU0_PE4_RX_DN<1>")
	)
	(segment
		(start 310.888126 -322.595748)
		(end 310.247538 -321.95516)
		(width 0.14732)
		(layer "In4.Cu")
		(net "P5E_CPU0_PE4_RX_DN<1>")
	)
	(segment
		(start 310.490108 -406.01646)
		(end 310.490108 -410.646626)
		(width 0.14732)
		(layer "In4.Cu")
		(net "P5E_CPU0_PE4_RX_DN<1>")
	)
	(segment
		(start 312.47588 -415.310066)
		(end 312.63717 -415.716212)
		(width 0.14732)
		(layer "In4.Cu")
		(net "P5E_CPU0_PE4_RX_DN<1>")
	)
	(segment
		(start 311.738518 -413.790638)
		(end 311.899554 -414.19653)
		(width 0.14732)
		(layer "In4.Cu")
		(net "P5E_CPU0_PE4_RX_DN<1>")
	)
	(segment
		(start 315.966856 -434.60543)
		(end 316.114176 -434.75275)
		(width 0.14732)
		(layer "In4.Cu")
		(net "P5E_CPU0_PE4_RX_DN<1>")
	)
	(segment
		(start 338.850986 -289.431476)
		(end 338.31276 -289.969448)
		(width 0.0889)
		(layer "In4.Cu")
		(net "P5E_CPU0_PE4_RX_DN<1>")
	)
	(segment
		(start 309.685182 -322.124324)
		(end 306.385468 -325.424038)
		(width 0.14732)
		(layer "In4.Cu")
		(net "P5E_CPU0_PE4_RX_DN<1>")
	)
	(segment
		(start 311.647078 -413.222694)
		(end 311.808368 -413.629094)
		(width 0.14732)
		(layer "In4.Cu")
		(net "P5E_CPU0_PE4_RX_DN<1>")
	)
	(segment
		(start 309.143908 -399.77441)
		(end 309.143908 -404.67026)
		(width 0.14732)
		(layer "In4.Cu")
		(net "P5E_CPU0_PE4_RX_DN<1>")
	)
	(segment
		(start 312.222642 -414.672526)
		(end 312.153046 -414.834324)
		(width 0.14732)
		(layer "In4.Cu")
		(net "P5E_CPU0_PE4_RX_DN<1>")
	)
	(segment
		(start 307.509926 -370.862606)
		(end 309.143908 -399.77441)
		(width 0.14732)
		(layer "In4.Cu")
		(net "P5E_CPU0_PE4_RX_DN<1>")
	)
	(segment
		(start 312.921396 -322.028058)
		(end 311.55005 -322.595748)
		(width 0.14732)
		(layer "In4.Cu")
		(net "P5E_CPU0_PE4_RX_DN<1>")
	)
	(segment
		(start 309.143908 -404.67026)
		(end 310.490108 -406.01646)
		(width 0.14732)
		(layer "In4.Cu")
		(net "P5E_CPU0_PE4_RX_DN<1>")
	)
	(segment
		(start 312.890154 -416.353752)
		(end 313.051444 -416.759898)
		(width 0.14732)
		(layer "In4.Cu")
		(net "P5E_CPU0_PE4_RX_DN<1>")
	)
	(segment
		(start 333.03464 -293.904162)
		(end 332.037182 -296.311828)
		(width 0.14732)
		(layer "In4.Cu")
		(net "P5E_CPU0_PE4_RX_DN<1>")
	)
	(segment
		(start 312.314082 -415.240216)
		(end 312.47588 -415.310066)
		(width 0.14732)
		(layer "In4.Cu")
		(net "P5E_CPU0_PE4_RX_DN<1>")
	)
	(segment
		(start 311.48528 -413.153098)
		(end 311.647078 -413.222694)
		(width 0.14732)
		(layer "In4.Cu")
		(net "P5E_CPU0_PE4_RX_DN<1>")
	)
	(segment
		(start 310.247538 -321.95516)
		(end 310.093106 -321.95516)
		(width 0.14732)
		(layer "In4.Cu")
		(net "P5E_CPU0_PE4_RX_DN<1>")
	)
	(segment
		(start 311.808368 -413.629094)
		(end 311.738518 -413.790638)
		(width 0.14732)
		(layer "In4.Cu")
		(net "P5E_CPU0_PE4_RX_DN<1>")
	)
	(segment
		(start 304.21707 -344.778584)
		(end 307.509926 -370.852192)
		(width 0.14732)
		(layer "In4.Cu")
		(net "P5E_CPU0_PE4_RX_DN<1>")
	)
	(segment
		(start 312.061352 -414.26638)
		(end 312.222642 -414.672526)
		(width 0.14732)
		(layer "In4.Cu")
		(net "P5E_CPU0_PE4_RX_DN<1>")
	)
	(segment
		(start 312.153046 -414.834324)
		(end 312.314082 -415.240216)
		(width 0.14732)
		(layer "In4.Cu")
		(net "P5E_CPU0_PE4_RX_DN<1>")
	)
	(segment
		(start 332.037182 -298.35475)
		(end 331.060552 -303.888902)
		(width 0.14732)
		(layer "In4.Cu")
		(net "P5E_CPU0_PE4_RX_DN<1>")
	)
	(segment
		(start 316.114176 -434.75275)
		(end 316.438534 -434.75275)
		(width 0.14732)
		(layer "In4.Cu")
		(net "P5E_CPU0_PE4_RX_DN<1>")
	)
	(segment
		(start 310.490108 -410.646626)
		(end 311.48528 -413.153098)
		(width 0.14732)
		(layer "In4.Cu")
		(net "P5E_CPU0_PE4_RX_DN<1>")
	)
	(segment
		(start 338.201508 -290.140644)
		(end 337.281774 -291.060378)
		(width 0.14732)
		(layer "In4.Cu")
		(net "P5E_CPU0_PE4_RX_DN<1>")
	)
	(segment
		(start 307.509926 -370.852192)
		(end 307.509926 -370.862606)
		(width 0.14732)
		(layer "In4.Cu")
		(net "P5E_CPU0_PE4_RX_DN<1>")
	)
	(segment
		(start 313.051444 -416.759898)
		(end 312.981848 -416.921696)
		(width 0.14732)
		(layer "In4.Cu")
		(net "P5E_CPU0_PE4_RX_DN<1>")
	)
	(segment
		(start 337.281774 -291.060378)
		(end 335.878424 -291.060378)
		(width 0.14732)
		(layer "In4.Cu")
		(net "P5E_CPU0_PE4_RX_DN<1>")
	)
	(segment
		(start 304.21707 -330.871322)
		(end 304.21707 -344.778584)
		(width 0.14732)
		(layer "In4.Cu")
		(net "P5E_CPU0_PE4_RX_DN<1>")
	)
	(segment
		(start 315.966856 -424.44035)
		(end 315.966856 -434.60543)
		(width 0.14732)
		(layer "In4.Cu")
		(net "P5E_CPU0_PE4_RX_DN<1>")
	)
	(segment
		(start 339.110066 -288.902902)
		(end 339.110066 -289.114484)
		(width 0.0889)
		(layer "In4.Cu")
		(net "P5E_CPU0_PE4_RX_DN<1>")
	)
	(segment
		(start 312.728356 -416.283902)
		(end 312.890154 -416.353752)
		(width 0.14732)
		(layer "In4.Cu")
		(net "P5E_CPU0_PE4_RX_DN<1>")
	)
	(segment
		(start 312.981848 -416.921696)
		(end 315.966856 -424.44035)
		(width 0.14732)
		(layer "In4.Cu")
		(net "P5E_CPU0_PE4_RX_DN<1>")
	)
	(segment
		(start 311.899554 -414.19653)
		(end 312.061352 -414.26638)
		(width 0.14732)
		(layer "In4.Cu")
		(net "P5E_CPU0_PE4_RX_DN<1>")
	)
	(arc
		(start 338.882228 -288.463228)
		(mid 338.8908 -288.469751)
		(end 338.899246 -288.476436)
		(width 0.0889)
		(layer "In4.Cu")
		(net "P5E_CPU0_PE4_RX_DN<1>")
	)
	(arc
		(start 339.110066 -289.114484)
		(mid 339.0085 -289.295854)
		(end 338.850986 -289.431476)
		(width 0.0889)
		(layer "In4.Cu")
		(net "P5E_CPU0_PE4_RX_DN<1>")
	)
	(arc
		(start 338.899246 -288.476436)
		(mid 339.051677 -288.666418)
		(end 339.110066 -288.902902)
		(width 0.0889)
		(layer "In4.Cu")
		(net "P5E_CPU0_PE4_RX_DN<1>")
	)
	(segment
		(start 352.171762 -288.102802)
		(end 352.172016 -288.103056)
		(width 0.13208)
		(layer "F.Cu")
		(net "P5E_CPU0_PE4_RX_DN<15>")
	)
	(segment
		(start 352.171762 -287.567116)
		(end 352.171762 -288.102802)
		(width 0.13208)
		(layer "F.Cu")
		(net "P5E_CPU0_PE4_RX_DN<15>")
	)
	(segment
		(start 351.031556 -292.84422)
		(end 351.031556 -293.569644)
		(width 0.0889)
		(layer "In4.Cu")
		(net "P5E_CPU0_PE4_RX_DN<15>")
	)
	(segment
		(start 352.272092 -401.11934)
		(end 353.375468 -406.666954)
		(width 0.14732)
		(layer "In4.Cu")
		(net "P5E_CPU0_PE4_RX_DN<15>")
	)
	(segment
		(start 346.136468 -422.386252)
		(end 346.182696 -422.578276)
		(width 0.14732)
		(layer "In4.Cu")
		(net "P5E_CPU0_PE4_RX_DN<15>")
	)
	(segment
		(start 347.294454 -420.494714)
		(end 347.340682 -420.686992)
		(width 0.14732)
		(layer "In4.Cu")
		(net "P5E_CPU0_PE4_RX_DN<15>")
	)
	(segment
		(start 346.667074 -421.519604)
		(end 346.713302 -421.711628)
		(width 0.14732)
		(layer "In4.Cu")
		(net "P5E_CPU0_PE4_RX_DN<15>")
	)
	(segment
		(start 351.07372 -293.633906)
		(end 351.07372 -297.523408)
		(width 0.14732)
		(layer "In4.Cu")
		(net "P5E_CPU0_PE4_RX_DN<15>")
	)
	(segment
		(start 317.466218 -336.473546)
		(end 317.466218 -342.192864)
		(width 0.14732)
		(layer "In4.Cu")
		(net "P5E_CPU0_PE4_RX_DN<15>")
	)
	(segment
		(start 344.966544 -434.604922)
		(end 345.114372 -434.75275)
		(width 0.14732)
		(layer "In4.Cu")
		(net "P5E_CPU0_PE4_RX_DN<15>")
	)
	(segment
		(start 345.797886 -422.938702)
		(end 345.178888 -423.95013)
		(width 0.14732)
		(layer "In4.Cu")
		(net "P5E_CPU0_PE4_RX_DN<15>")
	)
	(segment
		(start 347.148404 -421.00119)
		(end 346.956126 -421.047418)
		(width 0.14732)
		(layer "In4.Cu")
		(net "P5E_CPU0_PE4_RX_DN<15>")
	)
	(segment
		(start 351.824798 -399.884392)
		(end 352.272092 -401.11934)
		(width 0.14732)
		(layer "In4.Cu")
		(net "P5E_CPU0_PE4_RX_DN<15>")
	)
	(segment
		(start 346.521024 -422.02608)
		(end 346.328746 -422.072308)
		(width 0.14732)
		(layer "In4.Cu")
		(net "P5E_CPU0_PE4_RX_DN<15>")
	)
	(segment
		(start 344.966544 -424.408854)
		(end 344.966544 -434.604922)
		(width 0.14732)
		(layer "In4.Cu")
		(net "P5E_CPU0_PE4_RX_DN<15>")
	)
	(segment
		(start 351.07372 -297.523408)
		(end 349.930212 -304.009552)
		(width 0.14732)
		(layer "In4.Cu")
		(net "P5E_CPU0_PE4_RX_DN<15>")
	)
	(segment
		(start 352.736658 -289.610292)
		(end 352.736658 -291.139118)
		(width 0.0889)
		(layer "In4.Cu")
		(net "P5E_CPU0_PE4_RX_DN<15>")
	)
	(segment
		(start 353.375468 -406.666954)
		(end 353.375468 -410.561028)
		(width 0.14732)
		(layer "In4.Cu")
		(net "P5E_CPU0_PE4_RX_DN<15>")
	)
	(segment
		(start 352.451416 -289.277806)
		(end 352.451162 -289.27806)
		(width 0.0889)
		(layer "In4.Cu")
		(net "P5E_CPU0_PE4_RX_DN<15>")
	)
	(segment
		(start 352.736658 -291.139118)
		(end 351.031556 -292.84422)
		(width 0.0889)
		(layer "In4.Cu")
		(net "P5E_CPU0_PE4_RX_DN<15>")
	)
	(segment
		(start 345.990164 -422.892728)
		(end 345.797886 -422.938702)
		(width 0.14732)
		(layer "In4.Cu")
		(net "P5E_CPU0_PE4_RX_DN<15>")
	)
	(segment
		(start 349.930212 -304.009552)
		(end 317.466218 -336.473546)
		(width 0.14732)
		(layer "In4.Cu")
		(net "P5E_CPU0_PE4_RX_DN<15>")
	)
	(segment
		(start 317.466218 -342.192864)
		(end 350.319594 -397.751046)
		(width 0.14732)
		(layer "In4.Cu")
		(net "P5E_CPU0_PE4_RX_DN<15>")
	)
	(segment
		(start 345.114372 -434.75275)
		(end 345.438476 -434.75275)
		(width 0.14732)
		(layer "In4.Cu")
		(net "P5E_CPU0_PE4_RX_DN<15>")
	)
	(segment
		(start 345.650058 -434.541168)
		(end 345.650058 -434.289962)
		(width 0.14732)
		(layer "In4.Cu")
		(net "P5E_CPU0_PE4_RX_DN<15>")
	)
	(segment
		(start 347.340682 -420.686992)
		(end 347.148404 -421.00119)
		(width 0.14732)
		(layer "In4.Cu")
		(net "P5E_CPU0_PE4_RX_DN<15>")
	)
	(segment
		(start 351.07372 -293.611808)
		(end 351.07372 -293.633906)
		(width 0.0889)
		(layer "In4.Cu")
		(net "P5E_CPU0_PE4_RX_DN<15>")
	)
	(segment
		(start 352.267266 -288.898584)
		(end 352.267266 -289.078416)
		(width 0.0889)
		(layer "In4.Cu")
		(net "P5E_CPU0_PE4_RX_DN<15>")
	)
	(segment
		(start 345.178888 -423.95013)
		(end 344.966544 -424.408854)
		(width 0.14732)
		(layer "In4.Cu")
		(net "P5E_CPU0_PE4_RX_DN<15>")
	)
	(segment
		(start 351.031556 -293.569644)
		(end 351.07372 -293.611808)
		(width 0.0889)
		(layer "In4.Cu")
		(net "P5E_CPU0_PE4_RX_DN<15>")
	)
	(segment
		(start 350.319594 -397.751046)
		(end 351.824798 -399.884392)
		(width 0.14732)
		(layer "In4.Cu")
		(net "P5E_CPU0_PE4_RX_DN<15>")
	)
	(segment
		(start 346.956126 -421.047418)
		(end 346.667074 -421.519604)
		(width 0.14732)
		(layer "In4.Cu")
		(net "P5E_CPU0_PE4_RX_DN<15>")
	)
	(segment
		(start 353.375468 -410.561028)
		(end 347.294454 -420.494714)
		(width 0.14732)
		(layer "In4.Cu")
		(net "P5E_CPU0_PE4_RX_DN<15>")
	)
	(segment
		(start 352.172016 -288.103056)
		(end 352.015552 -288.374074)
		(width 0.0889)
		(layer "In4.Cu")
		(net "P5E_CPU0_PE4_RX_DN<15>")
	)
	(segment
		(start 346.713302 -421.711628)
		(end 346.521024 -422.02608)
		(width 0.14732)
		(layer "In4.Cu")
		(net "P5E_CPU0_PE4_RX_DN<15>")
	)
	(segment
		(start 345.438476 -434.75275)
		(end 345.650058 -434.541168)
		(width 0.14732)
		(layer "In4.Cu")
		(net "P5E_CPU0_PE4_RX_DN<15>")
	)
	(segment
		(start 346.182696 -422.578276)
		(end 345.990164 -422.892728)
		(width 0.14732)
		(layer "In4.Cu")
		(net "P5E_CPU0_PE4_RX_DN<15>")
	)
	(segment
		(start 352.015552 -288.374074)
		(end 352.039682 -288.463228)
		(width 0.0889)
		(layer "In4.Cu")
		(net "P5E_CPU0_PE4_RX_DN<15>")
	)
	(segment
		(start 346.328746 -422.072308)
		(end 346.136468 -422.386252)
		(width 0.14732)
		(layer "In4.Cu")
		(net "P5E_CPU0_PE4_RX_DN<15>")
	)
	(arc
		(start 352.267266 -289.078416)
		(mid 352.342271 -289.193875)
		(end 352.451416 -289.277806)
		(width 0.0889)
		(layer "In4.Cu")
		(net "P5E_CPU0_PE4_RX_DN<15>")
	)
	(arc
		(start 352.0567 -288.476436)
		(mid 352.208104 -288.664503)
		(end 352.267266 -288.898584)
		(width 0.0889)
		(layer "In4.Cu")
		(net "P5E_CPU0_PE4_RX_DN<15>")
	)
	(arc
		(start 352.039682 -288.463228)
		(mid 352.048254 -288.469751)
		(end 352.0567 -288.476436)
		(width 0.0889)
		(layer "In4.Cu")
		(net "P5E_CPU0_PE4_RX_DN<15>")
	)
	(arc
		(start 352.451162 -289.27806)
		(mid 352.625407 -289.417106)
		(end 352.736658 -289.610292)
		(width 0.0889)
		(layer "In4.Cu")
		(net "P5E_CPU0_PE4_RX_DN<15>")
	)
	(segment
		(start 351.231962 -289.195002)
		(end 351.231962 -289.807142)
		(width 0.13208)
		(layer "F.Cu")
		(net "P5E_CPU0_PE4_RX_DN<14>")
	)
	(segment
		(start 351.099628 -289.42157)
		(end 351.073212 -289.506152)
		(width 0.0889)
		(layer "In4.Cu")
		(net "P5E_CPU0_PE4_RX_DN<14>")
	)
	(segment
		(start 316.262258 -342.624918)
		(end 316.262258 -335.974436)
		(width 0.14732)
		(layer "In4.Cu")
		(net "P5E_CPU0_PE4_RX_DN<14>")
	)
	(segment
		(start 343.502488 -434.027072)
		(end 343.033604 -434.027072)
		(width 0.14732)
		(layer "In4.Cu")
		(net "P5E_CPU0_PE4_RX_DN<14>")
	)
	(segment
		(start 350.037908 -410.566362)
		(end 350.037908 -406.130252)
		(width 0.14732)
		(layer "In4.Cu")
		(net "P5E_CPU0_PE4_RX_DN<14>")
	)
	(segment
		(start 343.650062 -434.48986)
		(end 343.650062 -434.174646)
		(width 0.14732)
		(layer "In4.Cu")
		(net "P5E_CPU0_PE4_RX_DN<14>")
	)
	(segment
		(start 349.86976 -293.611808)
		(end 349.91167 -293.569898)
		(width 0.0889)
		(layer "In4.Cu")
		(net "P5E_CPU0_PE4_RX_DN<14>")
	)
	(segment
		(start 348.776544 -303.46015)
		(end 349.86976 -297.258994)
		(width 0.14732)
		(layer "In4.Cu")
		(net "P5E_CPU0_PE4_RX_DN<14>")
	)
	(segment
		(start 342.692736 -424.49496)
		(end 350.037908 -410.566362)
		(width 0.14732)
		(layer "In4.Cu")
		(net "P5E_CPU0_PE4_RX_DN<14>")
	)
	(segment
		(start 342.692736 -433.686204)
		(end 342.692736 -424.49496)
		(width 0.14732)
		(layer "In4.Cu")
		(net "P5E_CPU0_PE4_RX_DN<14>")
	)
	(segment
		(start 349.86976 -297.258994)
		(end 349.86976 -293.633906)
		(width 0.14732)
		(layer "In4.Cu")
		(net "P5E_CPU0_PE4_RX_DN<14>")
	)
	(segment
		(start 348.054168 -399.194528)
		(end 316.262258 -342.624918)
		(width 0.14732)
		(layer "In4.Cu")
		(net "P5E_CPU0_PE4_RX_DN<14>")
	)
	(segment
		(start 349.91167 -293.569898)
		(end 349.91167 -292.4683)
		(width 0.0889)
		(layer "In4.Cu")
		(net "P5E_CPU0_PE4_RX_DN<14>")
	)
	(segment
		(start 343.033604 -434.027072)
		(end 342.692736 -433.686204)
		(width 0.14732)
		(layer "In4.Cu")
		(net "P5E_CPU0_PE4_RX_DN<14>")
	)
	(segment
		(start 351.073212 -289.506152)
		(end 351.231962 -289.807142)
		(width 0.0889)
		(layer "In4.Cu")
		(net "P5E_CPU0_PE4_RX_DN<14>")
	)
	(segment
		(start 343.650062 -434.174646)
		(end 343.502488 -434.027072)
		(width 0.14732)
		(layer "In4.Cu")
		(net "P5E_CPU0_PE4_RX_DN<14>")
	)
	(segment
		(start 348.691708 -404.784052)
		(end 348.691708 -400.432016)
		(width 0.14732)
		(layer "In4.Cu")
		(net "P5E_CPU0_PE4_RX_DN<14>")
	)
	(segment
		(start 349.91167 -292.4683)
		(end 351.606612 -290.773358)
		(width 0.0889)
		(layer "In4.Cu")
		(net "P5E_CPU0_PE4_RX_DN<14>")
	)
	(segment
		(start 350.037908 -406.130252)
		(end 348.691708 -404.784052)
		(width 0.14732)
		(layer "In4.Cu")
		(net "P5E_CPU0_PE4_RX_DN<14>")
	)
	(segment
		(start 349.86976 -293.633906)
		(end 349.86976 -293.611808)
		(width 0.0889)
		(layer "In4.Cu")
		(net "P5E_CPU0_PE4_RX_DN<14>")
	)
	(segment
		(start 348.691708 -400.432016)
		(end 348.054168 -399.194528)
		(width 0.14732)
		(layer "In4.Cu")
		(net "P5E_CPU0_PE4_RX_DN<14>")
	)
	(segment
		(start 316.262258 -335.974436)
		(end 348.776544 -303.46015)
		(width 0.14732)
		(layer "In4.Cu")
		(net "P5E_CPU0_PE4_RX_DN<14>")
	)
	(segment
		(start 351.606612 -290.773358)
		(end 351.606612 -289.645852)
		(width 0.0889)
		(layer "In4.Cu")
		(net "P5E_CPU0_PE4_RX_DN<14>")
	)
	(arc
		(start 351.606612 -289.645852)
		(mid 351.397077 -289.434449)
		(end 351.099628 -289.42157)
		(width 0.0889)
		(layer "In4.Cu")
		(net "P5E_CPU0_PE4_RX_DN<14>")
	)
	(segment
		(start 350.292162 -288.102802)
		(end 350.292416 -288.103056)
		(width 0.13208)
		(layer "F.Cu")
		(net "P5E_CPU0_PE4_RX_DN<13>")
	)
	(segment
		(start 350.292162 -287.567116)
		(end 350.292162 -288.102802)
		(width 0.13208)
		(layer "F.Cu")
		(net "P5E_CPU0_PE4_RX_DN<13>")
	)
	(segment
		(start 348.576646 -292.983666)
		(end 348.576646 -297.421554)
		(width 0.14732)
		(layer "In4.Cu")
		(net "P5E_CPU0_PE4_RX_DN<13>")
	)
	(segment
		(start 345.902788 -404.67026)
		(end 347.248988 -406.01646)
		(width 0.14732)
		(layer "In4.Cu")
		(net "P5E_CPU0_PE4_RX_DN<13>")
	)
	(segment
		(start 342.786716 -420.48557)
		(end 342.855042 -420.67099)
		(width 0.14732)
		(layer "In4.Cu")
		(net "P5E_CPU0_PE4_RX_DN<13>")
	)
	(segment
		(start 342.701118 -421.005762)
		(end 342.515444 -421.074088)
		(width 0.14732)
		(layer "In4.Cu")
		(net "P5E_CPU0_PE4_RX_DN<13>")
	)
	(segment
		(start 347.248988 -410.795724)
		(end 342.786716 -420.48557)
		(width 0.14732)
		(layer "In4.Cu")
		(net "P5E_CPU0_PE4_RX_DN<13>")
	)
	(segment
		(start 348.576646 -292.961568)
		(end 348.576646 -292.983666)
		(width 0.0889)
		(layer "In4.Cu")
		(net "P5E_CPU0_PE4_RX_DN<13>")
	)
	(segment
		(start 350.292416 -288.103056)
		(end 350.135952 -288.374074)
		(width 0.0889)
		(layer "In4.Cu")
		(net "P5E_CPU0_PE4_RX_DN<13>")
	)
	(segment
		(start 315.571632 -335.688178)
		(end 315.571632 -342.876378)
		(width 0.14732)
		(layer "In4.Cu")
		(net "P5E_CPU0_PE4_RX_DN<13>")
	)
	(segment
		(start 341.56523 -423.137584)
		(end 340.966552 -424.437556)
		(width 0.14732)
		(layer "In4.Cu")
		(net "P5E_CPU0_PE4_RX_DN<13>")
	)
	(segment
		(start 348.534482 -292.783768)
		(end 348.534482 -292.919404)
		(width 0.0889)
		(layer "In4.Cu")
		(net "P5E_CPU0_PE4_RX_DN<13>")
	)
	(segment
		(start 350.857312 -289.60953)
		(end 350.857058 -289.609276)
		(width 0.0889)
		(layer "In4.Cu")
		(net "P5E_CPU0_PE4_RX_DN<13>")
	)
	(segment
		(start 348.576646 -297.421554)
		(end 347.449902 -303.809908)
		(width 0.14732)
		(layer "In4.Cu")
		(net "P5E_CPU0_PE4_RX_DN<13>")
	)
	(segment
		(start 347.248988 -406.01646)
		(end 347.248988 -410.795724)
		(width 0.14732)
		(layer "In4.Cu")
		(net "P5E_CPU0_PE4_RX_DN<13>")
	)
	(segment
		(start 342.349836 -421.768016)
		(end 342.195658 -422.103042)
		(width 0.14732)
		(layer "In4.Cu")
		(net "P5E_CPU0_PE4_RX_DN<13>")
	)
	(segment
		(start 345.902788 -400.301206)
		(end 345.902788 -404.67026)
		(width 0.14732)
		(layer "In4.Cu")
		(net "P5E_CPU0_PE4_RX_DN<13>")
	)
	(segment
		(start 341.565484 -423.136822)
		(end 341.56523 -423.137584)
		(width 0.14732)
		(layer "In4.Cu")
		(net "P5E_CPU0_PE4_RX_DN<13>")
	)
	(segment
		(start 342.855042 -420.67099)
		(end 342.701118 -421.005762)
		(width 0.14732)
		(layer "In4.Cu")
		(net "P5E_CPU0_PE4_RX_DN<13>")
	)
	(segment
		(start 345.40063 -399.501868)
		(end 345.902788 -400.301206)
		(width 0.14732)
		(layer "In4.Cu")
		(net "P5E_CPU0_PE4_RX_DN<13>")
	)
	(segment
		(start 348.534482 -292.919404)
		(end 348.576646 -292.961568)
		(width 0.0889)
		(layer "In4.Cu")
		(net "P5E_CPU0_PE4_RX_DN<13>")
	)
	(segment
		(start 340.966552 -434.604922)
		(end 341.11438 -434.75275)
		(width 0.14732)
		(layer "In4.Cu")
		(net "P5E_CPU0_PE4_RX_DN<13>")
	)
	(segment
		(start 340.966552 -424.437556)
		(end 340.966552 -434.604922)
		(width 0.14732)
		(layer "In4.Cu")
		(net "P5E_CPU0_PE4_RX_DN<13>")
	)
	(segment
		(start 341.905082 -422.73347)
		(end 341.751158 -423.068242)
		(width 0.14732)
		(layer "In4.Cu")
		(net "P5E_CPU0_PE4_RX_DN<13>")
	)
	(segment
		(start 350.857058 -289.609276)
		(end 350.857058 -290.461192)
		(width 0.0889)
		(layer "In4.Cu")
		(net "P5E_CPU0_PE4_RX_DN<13>")
	)
	(segment
		(start 341.650066 -434.571648)
		(end 341.650066 -434.289962)
		(width 0.14732)
		(layer "In4.Cu")
		(net "P5E_CPU0_PE4_RX_DN<13>")
	)
	(segment
		(start 350.857058 -290.461192)
		(end 348.534482 -292.783768)
		(width 0.0889)
		(layer "In4.Cu")
		(net "P5E_CPU0_PE4_RX_DN<13>")
	)
	(segment
		(start 341.836756 -422.54805)
		(end 341.905082 -422.73347)
		(width 0.14732)
		(layer "In4.Cu")
		(net "P5E_CPU0_PE4_RX_DN<13>")
	)
	(segment
		(start 342.195658 -422.103042)
		(end 342.010238 -422.171368)
		(width 0.14732)
		(layer "In4.Cu")
		(net "P5E_CPU0_PE4_RX_DN<13>")
	)
	(segment
		(start 350.387666 -288.898584)
		(end 350.387666 -289.078416)
		(width 0.0889)
		(layer "In4.Cu")
		(net "P5E_CPU0_PE4_RX_DN<13>")
	)
	(segment
		(start 342.515444 -421.074088)
		(end 342.281256 -421.58285)
		(width 0.14732)
		(layer "In4.Cu")
		(net "P5E_CPU0_PE4_RX_DN<13>")
	)
	(segment
		(start 342.281256 -421.58285)
		(end 342.349836 -421.768016)
		(width 0.14732)
		(layer "In4.Cu")
		(net "P5E_CPU0_PE4_RX_DN<13>")
	)
	(segment
		(start 341.468964 -434.75275)
		(end 341.650066 -434.571648)
		(width 0.14732)
		(layer "In4.Cu")
		(net "P5E_CPU0_PE4_RX_DN<13>")
	)
	(segment
		(start 347.449902 -303.809908)
		(end 315.571632 -335.688178)
		(width 0.14732)
		(layer "In4.Cu")
		(net "P5E_CPU0_PE4_RX_DN<13>")
	)
	(segment
		(start 341.751158 -423.068242)
		(end 341.565484 -423.136822)
		(width 0.14732)
		(layer "In4.Cu")
		(net "P5E_CPU0_PE4_RX_DN<13>")
	)
	(segment
		(start 350.135952 -288.374074)
		(end 350.160082 -288.463228)
		(width 0.0889)
		(layer "In4.Cu")
		(net "P5E_CPU0_PE4_RX_DN<13>")
	)
	(segment
		(start 342.010238 -422.171368)
		(end 341.836756 -422.54805)
		(width 0.14732)
		(layer "In4.Cu")
		(net "P5E_CPU0_PE4_RX_DN<13>")
	)
	(segment
		(start 315.571632 -342.876378)
		(end 345.40063 -399.501868)
		(width 0.14732)
		(layer "In4.Cu")
		(net "P5E_CPU0_PE4_RX_DN<13>")
	)
	(segment
		(start 341.11438 -434.75275)
		(end 341.468964 -434.75275)
		(width 0.14732)
		(layer "In4.Cu")
		(net "P5E_CPU0_PE4_RX_DN<13>")
	)
	(arc
		(start 350.387666 -289.078416)
		(mid 350.462671 -289.193875)
		(end 350.571816 -289.277806)
		(width 0.0889)
		(layer "In4.Cu")
		(net "P5E_CPU0_PE4_RX_DN<13>")
	)
	(arc
		(start 350.160082 -288.463228)
		(mid 350.168654 -288.469751)
		(end 350.1771 -288.476436)
		(width 0.0889)
		(layer "In4.Cu")
		(net "P5E_CPU0_PE4_RX_DN<13>")
	)
	(arc
		(start 350.1771 -288.476436)
		(mid 350.328504 -288.664503)
		(end 350.387666 -288.898584)
		(width 0.0889)
		(layer "In4.Cu")
		(net "P5E_CPU0_PE4_RX_DN<13>")
	)
	(arc
		(start 350.571816 -289.277806)
		(mid 350.745948 -289.416653)
		(end 350.857312 -289.60953)
		(width 0.0889)
		(layer "In4.Cu")
		(net "P5E_CPU0_PE4_RX_DN<13>")
	)
	(segment
		(start 349.352362 -289.195002)
		(end 349.352362 -289.807142)
		(width 0.13208)
		(layer "F.Cu")
		(net "P5E_CPU0_PE4_RX_DN<12>")
	)
	(segment
		(start 347.367606 -297.315382)
		(end 347.367606 -292.965886)
		(width 0.14732)
		(layer "In4.Cu")
		(net "P5E_CPU0_PE4_RX_DN<12>")
	)
	(segment
		(start 349.193612 -289.506152)
		(end 349.352362 -289.807142)
		(width 0.0889)
		(layer "In4.Cu")
		(net "P5E_CPU0_PE4_RX_DN<12>")
	)
	(segment
		(start 343.911428 -406.130252)
		(end 342.565228 -404.784052)
		(width 0.14732)
		(layer "In4.Cu")
		(net "P5E_CPU0_PE4_RX_DN<12>")
	)
	(segment
		(start 347.409516 -292.901878)
		(end 347.409516 -292.686994)
		(width 0.0889)
		(layer "In4.Cu")
		(net "P5E_CPU0_PE4_RX_DN<12>")
	)
	(segment
		(start 314.362592 -343.160096)
		(end 314.362592 -335.186782)
		(width 0.14732)
		(layer "In4.Cu")
		(net "P5E_CPU0_PE4_RX_DN<12>")
	)
	(segment
		(start 338.69249 -424.502834)
		(end 343.911428 -410.646626)
		(width 0.14732)
		(layer "In4.Cu")
		(net "P5E_CPU0_PE4_RX_DN<12>")
	)
	(segment
		(start 347.367606 -292.965886)
		(end 347.367606 -292.943788)
		(width 0.0889)
		(layer "In4.Cu")
		(net "P5E_CPU0_PE4_RX_DN<12>")
	)
	(segment
		(start 338.69249 -433.698904)
		(end 338.69249 -424.502834)
		(width 0.14732)
		(layer "In4.Cu")
		(net "P5E_CPU0_PE4_RX_DN<12>")
	)
	(segment
		(start 339.65007 -434.48986)
		(end 339.65007 -434.174646)
		(width 0.14732)
		(layer "In4.Cu")
		(net "P5E_CPU0_PE4_RX_DN<12>")
	)
	(segment
		(start 346.324936 -303.224438)
		(end 347.367606 -297.315382)
		(width 0.14732)
		(layer "In4.Cu")
		(net "P5E_CPU0_PE4_RX_DN<12>")
	)
	(segment
		(start 347.367606 -292.943788)
		(end 347.409516 -292.901878)
		(width 0.0889)
		(layer "In4.Cu")
		(net "P5E_CPU0_PE4_RX_DN<12>")
	)
	(segment
		(start 342.565228 -400.014948)
		(end 314.362592 -343.160096)
		(width 0.14732)
		(layer "In4.Cu")
		(net "P5E_CPU0_PE4_RX_DN<12>")
	)
	(segment
		(start 349.220028 -289.42157)
		(end 349.193612 -289.506152)
		(width 0.0889)
		(layer "In4.Cu")
		(net "P5E_CPU0_PE4_RX_DN<12>")
	)
	(segment
		(start 347.409516 -292.686994)
		(end 349.727012 -290.369498)
		(width 0.0889)
		(layer "In4.Cu")
		(net "P5E_CPU0_PE4_RX_DN<12>")
	)
	(segment
		(start 339.65007 -434.174646)
		(end 339.502496 -434.027072)
		(width 0.14732)
		(layer "In4.Cu")
		(net "P5E_CPU0_PE4_RX_DN<12>")
	)
	(segment
		(start 339.502496 -434.027072)
		(end 339.020658 -434.027072)
		(width 0.14732)
		(layer "In4.Cu")
		(net "P5E_CPU0_PE4_RX_DN<12>")
	)
	(segment
		(start 343.911428 -410.646626)
		(end 343.911428 -406.130252)
		(width 0.14732)
		(layer "In4.Cu")
		(net "P5E_CPU0_PE4_RX_DN<12>")
	)
	(segment
		(start 342.565228 -404.784052)
		(end 342.565228 -400.014948)
		(width 0.14732)
		(layer "In4.Cu")
		(net "P5E_CPU0_PE4_RX_DN<12>")
	)
	(segment
		(start 314.362592 -335.186782)
		(end 346.324936 -303.224438)
		(width 0.14732)
		(layer "In4.Cu")
		(net "P5E_CPU0_PE4_RX_DN<12>")
	)
	(segment
		(start 349.727012 -290.369498)
		(end 349.727012 -289.645852)
		(width 0.0889)
		(layer "In4.Cu")
		(net "P5E_CPU0_PE4_RX_DN<12>")
	)
	(segment
		(start 339.020658 -434.027072)
		(end 338.69249 -433.698904)
		(width 0.14732)
		(layer "In4.Cu")
		(net "P5E_CPU0_PE4_RX_DN<12>")
	)
	(arc
		(start 349.727012 -289.645852)
		(mid 349.517477 -289.434449)
		(end 349.220028 -289.42157)
		(width 0.0889)
		(layer "In4.Cu")
		(net "P5E_CPU0_PE4_RX_DN<12>")
	)
	(segment
		(start 348.412562 -288.102802)
		(end 348.412816 -288.103056)
		(width 0.13208)
		(layer "F.Cu")
		(net "P5E_CPU0_PE4_RX_DN<11>")
	)
	(segment
		(start 348.412562 -287.567116)
		(end 348.412562 -288.102802)
		(width 0.13208)
		(layer "F.Cu")
		(net "P5E_CPU0_PE4_RX_DN<11>")
	)
	(segment
		(start 346.214446 -300.0502)
		(end 345.71051 -302.904652)
		(width 0.14732)
		(layer "In4.Cu")
		(net "P5E_CPU0_PE4_RX_DN<11>")
	)
	(segment
		(start 346.707206 -292.895528)
		(end 346.707206 -292.917626)
		(width 0.0889)
		(layer "In4.Cu")
		(net "P5E_CPU0_PE4_RX_DN<11>")
	)
	(segment
		(start 338.259928 -420.297356)
		(end 338.352892 -420.4716)
		(width 0.14732)
		(layer "In4.Cu")
		(net "P5E_CPU0_PE4_RX_DN<11>")
	)
	(segment
		(start 336.966814 -434.53177)
		(end 337.187794 -434.75275)
		(width 0.14732)
		(layer "In4.Cu")
		(net "P5E_CPU0_PE4_RX_DN<11>")
	)
	(segment
		(start 346.707206 -292.917626)
		(end 346.707206 -297.25747)
		(width 0.14732)
		(layer "In4.Cu")
		(net "P5E_CPU0_PE4_RX_DN<11>")
	)
	(segment
		(start 341.122508 -410.896308)
		(end 338.260182 -420.296848)
		(width 0.14732)
		(layer "In4.Cu")
		(net "P5E_CPU0_PE4_RX_DN<11>")
	)
	(segment
		(start 313.67857 -343.281254)
		(end 339.776308 -400.068034)
		(width 0.14732)
		(layer "In4.Cu")
		(net "P5E_CPU0_PE4_RX_DN<11>")
	)
	(segment
		(start 348.508066 -288.898584)
		(end 348.508066 -289.078416)
		(width 0.0889)
		(layer "In4.Cu")
		(net "P5E_CPU0_PE4_RX_DN<11>")
	)
	(segment
		(start 337.619086 -422.401238)
		(end 337.711796 -422.575482)
		(width 0.14732)
		(layer "In4.Cu")
		(net "P5E_CPU0_PE4_RX_DN<11>")
	)
	(segment
		(start 348.977458 -290.405312)
		(end 346.665042 -292.717728)
		(width 0.0889)
		(layer "In4.Cu")
		(net "P5E_CPU0_PE4_RX_DN<11>")
	)
	(segment
		(start 345.71051 -302.904652)
		(end 313.67857 -334.936592)
		(width 0.14732)
		(layer "In4.Cu")
		(net "P5E_CPU0_PE4_RX_DN<11>")
	)
	(segment
		(start 338.245704 -420.824152)
		(end 338.070952 -420.917116)
		(width 0.14732)
		(layer "In4.Cu")
		(net "P5E_CPU0_PE4_RX_DN<11>")
	)
	(segment
		(start 336.966814 -424.542458)
		(end 336.966814 -434.53177)
		(width 0.14732)
		(layer "In4.Cu")
		(net "P5E_CPU0_PE4_RX_DN<11>")
	)
	(segment
		(start 348.977712 -289.60953)
		(end 348.977458 -289.609276)
		(width 0.0889)
		(layer "In4.Cu")
		(net "P5E_CPU0_PE4_RX_DN<11>")
	)
	(segment
		(start 337.187794 -434.75275)
		(end 337.438492 -434.75275)
		(width 0.14732)
		(layer "In4.Cu")
		(net "P5E_CPU0_PE4_RX_DN<11>")
	)
	(segment
		(start 337.43011 -423.020998)
		(end 336.966814 -424.542458)
		(width 0.14732)
		(layer "In4.Cu")
		(net "P5E_CPU0_PE4_RX_DN<11>")
	)
	(segment
		(start 339.776308 -404.67026)
		(end 341.122508 -406.01646)
		(width 0.14732)
		(layer "In4.Cu")
		(net "P5E_CPU0_PE4_RX_DN<11>")
	)
	(segment
		(start 348.977458 -289.609276)
		(end 348.977458 -290.405312)
		(width 0.0889)
		(layer "In4.Cu")
		(net "P5E_CPU0_PE4_RX_DN<11>")
	)
	(segment
		(start 341.122508 -406.01646)
		(end 341.122508 -410.896308)
		(width 0.14732)
		(layer "In4.Cu")
		(net "P5E_CPU0_PE4_RX_DN<11>")
	)
	(segment
		(start 339.776308 -400.068034)
		(end 339.776308 -404.67026)
		(width 0.14732)
		(layer "In4.Cu")
		(net "P5E_CPU0_PE4_RX_DN<11>")
	)
	(segment
		(start 338.352892 -420.4716)
		(end 338.245704 -420.824152)
		(width 0.14732)
		(layer "In4.Cu")
		(net "P5E_CPU0_PE4_RX_DN<11>")
	)
	(segment
		(start 337.711796 -422.575482)
		(end 337.604608 -422.928034)
		(width 0.14732)
		(layer "In4.Cu")
		(net "P5E_CPU0_PE4_RX_DN<11>")
	)
	(segment
		(start 338.259674 -420.296848)
		(end 338.259928 -420.297356)
		(width 0.14732)
		(layer "In4.Cu")
		(net "P5E_CPU0_PE4_RX_DN<11>")
	)
	(segment
		(start 348.412816 -288.103056)
		(end 348.256352 -288.374074)
		(width 0.0889)
		(layer "In4.Cu")
		(net "P5E_CPU0_PE4_RX_DN<11>")
	)
	(segment
		(start 346.665042 -292.853364)
		(end 346.707206 -292.895528)
		(width 0.0889)
		(layer "In4.Cu")
		(net "P5E_CPU0_PE4_RX_DN<11>")
	)
	(segment
		(start 348.256352 -288.374074)
		(end 348.280482 -288.463228)
		(width 0.0889)
		(layer "In4.Cu")
		(net "P5E_CPU0_PE4_RX_DN<11>")
	)
	(segment
		(start 337.438492 -434.75275)
		(end 337.650074 -434.541168)
		(width 0.14732)
		(layer "In4.Cu")
		(net "P5E_CPU0_PE4_RX_DN<11>")
	)
	(segment
		(start 338.260182 -420.296848)
		(end 338.259674 -420.296848)
		(width 0.14732)
		(layer "In4.Cu")
		(net "P5E_CPU0_PE4_RX_DN<11>")
	)
	(segment
		(start 338.013548 -421.585898)
		(end 337.906106 -421.93845)
		(width 0.14732)
		(layer "In4.Cu")
		(net "P5E_CPU0_PE4_RX_DN<11>")
	)
	(segment
		(start 313.67857 -334.936592)
		(end 313.67857 -343.281254)
		(width 0.14732)
		(layer "In4.Cu")
		(net "P5E_CPU0_PE4_RX_DN<11>")
	)
	(segment
		(start 346.665042 -292.717728)
		(end 346.665042 -292.853364)
		(width 0.0889)
		(layer "In4.Cu")
		(net "P5E_CPU0_PE4_RX_DN<11>")
	)
	(segment
		(start 337.650074 -434.541168)
		(end 337.650074 -434.289962)
		(width 0.14732)
		(layer "In4.Cu")
		(net "P5E_CPU0_PE4_RX_DN<11>")
	)
	(segment
		(start 337.731608 -422.031414)
		(end 337.619086 -422.401238)
		(width 0.14732)
		(layer "In4.Cu")
		(net "P5E_CPU0_PE4_RX_DN<11>")
	)
	(segment
		(start 337.906106 -421.93845)
		(end 337.731608 -422.031414)
		(width 0.14732)
		(layer "In4.Cu")
		(net "P5E_CPU0_PE4_RX_DN<11>")
	)
	(segment
		(start 338.070952 -420.917116)
		(end 337.920584 -421.411654)
		(width 0.14732)
		(layer "In4.Cu")
		(net "P5E_CPU0_PE4_RX_DN<11>")
	)
	(segment
		(start 346.707206 -297.25747)
		(end 346.214446 -300.0502)
		(width 0.14732)
		(layer "In4.Cu")
		(net "P5E_CPU0_PE4_RX_DN<11>")
	)
	(segment
		(start 337.604608 -422.928034)
		(end 337.43011 -423.020998)
		(width 0.14732)
		(layer "In4.Cu")
		(net "P5E_CPU0_PE4_RX_DN<11>")
	)
	(segment
		(start 337.920584 -421.411654)
		(end 338.013548 -421.585898)
		(width 0.14732)
		(layer "In4.Cu")
		(net "P5E_CPU0_PE4_RX_DN<11>")
	)
	(arc
		(start 348.280482 -288.463228)
		(mid 348.289054 -288.469751)
		(end 348.2975 -288.476436)
		(width 0.0889)
		(layer "In4.Cu")
		(net "P5E_CPU0_PE4_RX_DN<11>")
	)
	(arc
		(start 348.692216 -289.277806)
		(mid 348.866348 -289.416653)
		(end 348.977712 -289.60953)
		(width 0.0889)
		(layer "In4.Cu")
		(net "P5E_CPU0_PE4_RX_DN<11>")
	)
	(arc
		(start 348.2975 -288.476436)
		(mid 348.448904 -288.664503)
		(end 348.508066 -288.898584)
		(width 0.0889)
		(layer "In4.Cu")
		(net "P5E_CPU0_PE4_RX_DN<11>")
	)
	(arc
		(start 348.508066 -289.078416)
		(mid 348.583071 -289.193875)
		(end 348.692216 -289.277806)
		(width 0.0889)
		(layer "In4.Cu")
		(net "P5E_CPU0_PE4_RX_DN<11>")
	)
	(segment
		(start 347.472762 -289.195002)
		(end 347.472762 -289.807142)
		(width 0.13208)
		(layer "F.Cu")
		(net "P5E_CPU0_PE4_RX_DN<10>")
	)
	(segment
		(start 337.784948 -411.097984)
		(end 337.784948 -406.130252)
		(width 0.14732)
		(layer "In4.Cu")
		(net "P5E_CPU0_PE4_RX_DN<10>")
	)
	(segment
		(start 347.847666 -290.257484)
		(end 347.847666 -289.64509)
		(width 0.0889)
		(layer "In4.Cu")
		(net "P5E_CPU0_PE4_RX_DN<10>")
	)
	(segment
		(start 335.502504 -434.027072)
		(end 335.000346 -434.027072)
		(width 0.14732)
		(layer "In4.Cu")
		(net "P5E_CPU0_PE4_RX_DN<10>")
	)
	(segment
		(start 345.502738 -297.151552)
		(end 345.502738 -292.885368)
		(width 0.14732)
		(layer "In4.Cu")
		(net "P5E_CPU0_PE4_RX_DN<10>")
	)
	(segment
		(start 336.438748 -404.784052)
		(end 336.438748 -400.194272)
		(width 0.14732)
		(layer "In4.Cu")
		(net "P5E_CPU0_PE4_RX_DN<10>")
	)
	(segment
		(start 335.650078 -434.174646)
		(end 335.502504 -434.027072)
		(width 0.14732)
		(layer "In4.Cu")
		(net "P5E_CPU0_PE4_RX_DN<10>")
	)
	(segment
		(start 312.47461 -334.437482)
		(end 344.589862 -302.321214)
		(width 0.14732)
		(layer "In4.Cu")
		(net "P5E_CPU0_PE4_RX_DN<10>")
	)
	(segment
		(start 345.544648 -292.560502)
		(end 347.847666 -290.257484)
		(width 0.0889)
		(layer "In4.Cu")
		(net "P5E_CPU0_PE4_RX_DN<10>")
	)
	(segment
		(start 335.813908 -419.724586)
		(end 337.784948 -411.097984)
		(width 0.14732)
		(layer "In4.Cu")
		(net "P5E_CPU0_PE4_RX_DN<10>")
	)
	(segment
		(start 345.544648 -292.82136)
		(end 345.544648 -292.560502)
		(width 0.0889)
		(layer "In4.Cu")
		(net "P5E_CPU0_PE4_RX_DN<10>")
	)
	(segment
		(start 345.502738 -292.86327)
		(end 345.544648 -292.82136)
		(width 0.0889)
		(layer "In4.Cu")
		(net "P5E_CPU0_PE4_RX_DN<10>")
	)
	(segment
		(start 334.692498 -424.632882)
		(end 335.813654 -419.725602)
		(width 0.14732)
		(layer "In4.Cu")
		(net "P5E_CPU0_PE4_RX_DN<10>")
	)
	(segment
		(start 336.438748 -400.194272)
		(end 312.47461 -343.570306)
		(width 0.14732)
		(layer "In4.Cu")
		(net "P5E_CPU0_PE4_RX_DN<10>")
	)
	(segment
		(start 335.650078 -434.48986)
		(end 335.650078 -434.174646)
		(width 0.14732)
		(layer "In4.Cu")
		(net "P5E_CPU0_PE4_RX_DN<10>")
	)
	(segment
		(start 347.314012 -289.506152)
		(end 347.472762 -289.807142)
		(width 0.0889)
		(layer "In4.Cu")
		(net "P5E_CPU0_PE4_RX_DN<10>")
	)
	(segment
		(start 337.784948 -406.130252)
		(end 336.438748 -404.784052)
		(width 0.14732)
		(layer "In4.Cu")
		(net "P5E_CPU0_PE4_RX_DN<10>")
	)
	(segment
		(start 334.692498 -433.719224)
		(end 334.692498 -424.632882)
		(width 0.14732)
		(layer "In4.Cu")
		(net "P5E_CPU0_PE4_RX_DN<10>")
	)
	(segment
		(start 347.340428 -289.42157)
		(end 347.314012 -289.506152)
		(width 0.0889)
		(layer "In4.Cu")
		(net "P5E_CPU0_PE4_RX_DN<10>")
	)
	(segment
		(start 344.589862 -302.321214)
		(end 345.502738 -297.151552)
		(width 0.14732)
		(layer "In4.Cu")
		(net "P5E_CPU0_PE4_RX_DN<10>")
	)
	(segment
		(start 345.502738 -292.885368)
		(end 345.502738 -292.86327)
		(width 0.0889)
		(layer "In4.Cu")
		(net "P5E_CPU0_PE4_RX_DN<10>")
	)
	(segment
		(start 335.813654 -419.725602)
		(end 335.813908 -419.724586)
		(width 0.14732)
		(layer "In4.Cu")
		(net "P5E_CPU0_PE4_RX_DN<10>")
	)
	(segment
		(start 335.000346 -434.027072)
		(end 334.692498 -433.719224)
		(width 0.14732)
		(layer "In4.Cu")
		(net "P5E_CPU0_PE4_RX_DN<10>")
	)
	(segment
		(start 312.47461 -343.570306)
		(end 312.47461 -334.437482)
		(width 0.14732)
		(layer "In4.Cu")
		(net "P5E_CPU0_PE4_RX_DN<10>")
	)
	(arc
		(start 347.847666 -289.64509)
		(mid 347.637738 -289.433515)
		(end 347.33992 -289.420808)
		(width 0.0889)
		(layer "In4.Cu")
		(net "P5E_CPU0_PE4_RX_DN<10>")
	)
	(arc
		(start 347.33992 -289.420808)
		(mid 347.340175 -289.421188)
		(end 347.340428 -289.42157)
		(width 0.0889)
		(layer "In4.Cu")
		(net "P5E_CPU0_PE4_RX_DN<10>")
	)
	(segment
		(start 336.665316 -288.916618)
		(end 336.664808 -288.917126)
		(width 0.13208)
		(layer "F.Cu")
		(net "P5E_CPU0_PE4_RX_DN<0>")
	)
	(segment
		(start 336.665316 -288.381186)
		(end 336.665316 -288.916618)
		(width 0.13208)
		(layer "F.Cu")
		(net "P5E_CPU0_PE4_RX_DN<0>")
	)
	(segment
		(start 310.140096 -320.628264)
		(end 310.905398 -320.628264)
		(width 0.14732)
		(layer "In4.Cu")
		(net "P5E_CPU0_PE4_RX_DN<0>")
	)
	(segment
		(start 305.806348 -404.784052)
		(end 305.806348 -400.364198)
		(width 0.14732)
		(layer "In4.Cu")
		(net "P5E_CPU0_PE4_RX_DN<0>")
	)
	(segment
		(start 302.998886 -330.36637)
		(end 304.749708 -328.615548)
		(width 0.14732)
		(layer "In4.Cu")
		(net "P5E_CPU0_PE4_RX_DN<0>")
	)
	(segment
		(start 314.502546 -434.027072)
		(end 314.000388 -434.027072)
		(width 0.14732)
		(layer "In4.Cu")
		(net "P5E_CPU0_PE4_RX_DN<0>")
	)
	(segment
		(start 336.637884 -289.592004)
		(end 337.039712 -289.190176)
		(width 0.0889)
		(layer "In4.Cu")
		(net "P5E_CPU0_PE4_RX_DN<0>")
	)
	(segment
		(start 305.806348 -400.364198)
		(end 306.002182 -394.766292)
		(width 0.14732)
		(layer "In4.Cu")
		(net "P5E_CPU0_PE4_RX_DN<0>")
	)
	(segment
		(start 313.662822 -433.68976)
		(end 307.152548 -410.545534)
		(width 0.14732)
		(layer "In4.Cu")
		(net "P5E_CPU0_PE4_RX_DN<0>")
	)
	(segment
		(start 336.563462 -289.607498)
		(end 336.578956 -289.592004)
		(width 0.0889)
		(layer "In4.Cu")
		(net "P5E_CPU0_PE4_RX_DN<0>")
	)
	(segment
		(start 330.818744 -298.247816)
		(end 330.818744 -295.994582)
		(width 0.14732)
		(layer "In4.Cu")
		(net "P5E_CPU0_PE4_RX_DN<0>")
	)
	(segment
		(start 314.65012 -434.48986)
		(end 314.65012 -434.174646)
		(width 0.14732)
		(layer "In4.Cu")
		(net "P5E_CPU0_PE4_RX_DN<0>")
	)
	(segment
		(start 305.167284 -327.607676)
		(end 305.167284 -324.930516)
		(width 0.14732)
		(layer "In4.Cu")
		(net "P5E_CPU0_PE4_RX_DN<0>")
	)
	(segment
		(start 336.578956 -289.592004)
		(end 336.637884 -289.592004)
		(width 0.0889)
		(layer "In4.Cu")
		(net "P5E_CPU0_PE4_RX_DN<0>")
	)
	(segment
		(start 307.152548 -406.130252)
		(end 305.806348 -404.784052)
		(width 0.14732)
		(layer "In4.Cu")
		(net "P5E_CPU0_PE4_RX_DN<0>")
	)
	(segment
		(start 329.92695 -303.29886)
		(end 330.818744 -298.247816)
		(width 0.14732)
		(layer "In4.Cu")
		(net "P5E_CPU0_PE4_RX_DN<0>")
	)
	(segment
		(start 305.167284 -324.930516)
		(end 308.995572 -321.102228)
		(width 0.14732)
		(layer "In4.Cu")
		(net "P5E_CPU0_PE4_RX_DN<0>")
	)
	(segment
		(start 312.783982 -320.441828)
		(end 329.92695 -303.29886)
		(width 0.14732)
		(layer "In4.Cu")
		(net "P5E_CPU0_PE4_RX_DN<0>")
	)
	(segment
		(start 336.82178 -288.646108)
		(end 336.664808 -288.917126)
		(width 0.0889)
		(layer "In4.Cu")
		(net "P5E_CPU0_PE4_RX_DN<0>")
	)
	(segment
		(start 304.749708 -328.615548)
		(end 305.167284 -327.607676)
		(width 0.14732)
		(layer "In4.Cu")
		(net "P5E_CPU0_PE4_RX_DN<0>")
	)
	(segment
		(start 336.899758 -288.62528)
		(end 336.82178 -288.646108)
		(width 0.0889)
		(layer "In4.Cu")
		(net "P5E_CPU0_PE4_RX_DN<0>")
	)
	(segment
		(start 335.284064 -289.905948)
		(end 336.265012 -289.905948)
		(width 0.14732)
		(layer "In4.Cu")
		(net "P5E_CPU0_PE4_RX_DN<0>")
	)
	(segment
		(start 337.039712 -289.190176)
		(end 337.039712 -288.90849)
		(width 0.0889)
		(layer "In4.Cu")
		(net "P5E_CPU0_PE4_RX_DN<0>")
	)
	(segment
		(start 336.265012 -289.905948)
		(end 336.563462 -289.607498)
		(width 0.14732)
		(layer "In4.Cu")
		(net "P5E_CPU0_PE4_RX_DN<0>")
	)
	(segment
		(start 306.002182 -394.766292)
		(end 305.396138 -370.663978)
		(width 0.14732)
		(layer "In4.Cu")
		(net "P5E_CPU0_PE4_RX_DN<0>")
	)
	(segment
		(start 302.998886 -344.770964)
		(end 302.998886 -330.36637)
		(width 0.14732)
		(layer "In4.Cu")
		(net "P5E_CPU0_PE4_RX_DN<0>")
	)
	(segment
		(start 305.396138 -370.663978)
		(end 302.998886 -344.770964)
		(width 0.14732)
		(layer "In4.Cu")
		(net "P5E_CPU0_PE4_RX_DN<0>")
	)
	(segment
		(start 311.843166 -320.441828)
		(end 312.783982 -320.441828)
		(width 0.14732)
		(layer "In4.Cu")
		(net "P5E_CPU0_PE4_RX_DN<0>")
	)
	(segment
		(start 330.818744 -295.994582)
		(end 331.96657 -293.223442)
		(width 0.14732)
		(layer "In4.Cu")
		(net "P5E_CPU0_PE4_RX_DN<0>")
	)
	(segment
		(start 308.995572 -321.102228)
		(end 310.140096 -320.628264)
		(width 0.14732)
		(layer "In4.Cu")
		(net "P5E_CPU0_PE4_RX_DN<0>")
	)
	(segment
		(start 314.65012 -434.174646)
		(end 314.502546 -434.027072)
		(width 0.14732)
		(layer "In4.Cu")
		(net "P5E_CPU0_PE4_RX_DN<0>")
	)
	(segment
		(start 314.000388 -434.027072)
		(end 313.662822 -433.68976)
		(width 0.14732)
		(layer "In4.Cu")
		(net "P5E_CPU0_PE4_RX_DN<0>")
	)
	(segment
		(start 307.152548 -410.545534)
		(end 307.152548 -406.130252)
		(width 0.14732)
		(layer "In4.Cu")
		(net "P5E_CPU0_PE4_RX_DN<0>")
	)
	(segment
		(start 331.96657 -293.223442)
		(end 335.284064 -289.905948)
		(width 0.14732)
		(layer "In4.Cu")
		(net "P5E_CPU0_PE4_RX_DN<0>")
	)
	(segment
		(start 310.905398 -320.628264)
		(end 311.843166 -320.441828)
		(width 0.14732)
		(layer "In4.Cu")
		(net "P5E_CPU0_PE4_RX_DN<0>")
	)
	(arc
		(start 337.039712 -288.90849)
		(mid 337.001038 -288.751422)
		(end 336.899758 -288.62528)
		(width 0.0889)
		(layer "In4.Cu")
		(net "P5E_CPU0_PE4_RX_DN<0>")
	)
	(segment
		(start 391.713212 -407.303478)
		(end 391.713212 -407.926286)
		(width 0.13208)
		(layer "F.Cu")
		(net "P5E_CPU0_PE3_TX_DP<9>")
	)
	(segment
		(start 373.317516 -285.125414)
		(end 373.317516 -285.6611)
		(width 0.13208)
		(layer "F.Cu")
		(net "P5E_CPU0_PE3_TX_DP<9>")
	)
	(segment
		(start 392.01217 -407.00452)
		(end 391.713212 -407.303478)
		(width 0.13208)
		(layer "F.Cu")
		(net "P5E_CPU0_PE3_TX_DP<9>")
	)
	(segment
		(start 391.713212 -407.926286)
		(end 392.03757 -408.250644)
		(width 0.13208)
		(layer "F.Cu")
		(net "P5E_CPU0_PE3_TX_DP<9>")
	)
	(segment
		(start 373.317516 -285.6611)
		(end 373.317262 -285.661354)
		(width 0.13208)
		(layer "F.Cu")
		(net "P5E_CPU0_PE3_TX_DP<9>")
	)
	(segment
		(start 392.241278 -397.391382)
		(end 392.115294 -397.230092)
		(width 0.14732)
		(layer "In2.Cu")
		(net "P5E_CPU0_PE3_TX_DP<9>")
	)
	(segment
		(start 392.253978 -396.101824)
		(end 398.036034 -349.039688)
		(width 0.14732)
		(layer "In2.Cu")
		(net "P5E_CPU0_PE3_TX_DP<9>")
	)
	(segment
		(start 396.849854 -326.549004)
		(end 376.241056 -300.154848)
		(width 0.14732)
		(layer "In2.Cu")
		(net "P5E_CPU0_PE3_TX_DP<9>")
	)
	(segment
		(start 392.309096 -396.67434)
		(end 392.362436 -396.240508)
		(width 0.14732)
		(layer "In2.Cu")
		(net "P5E_CPU0_PE3_TX_DP<9>")
	)
	(segment
		(start 373.882412 -287.28924)
		(end 373.882412 -287.273746)
		(width 0.0889)
		(layer "In2.Cu")
		(net "P5E_CPU0_PE3_TX_DP<9>")
	)
	(segment
		(start 374.069864 -287.613598)
		(end 374.060974 -287.608518)
		(width 0.0889)
		(layer "In2.Cu")
		(net "P5E_CPU0_PE3_TX_DP<9>")
	)
	(segment
		(start 374.540018 -288.427414)
		(end 374.531128 -288.422334)
		(width 0.0889)
		(layer "In2.Cu")
		(net "P5E_CPU0_PE3_TX_DP<9>")
	)
	(segment
		(start 391.90295 -398.957546)
		(end 392.03503 -397.882872)
		(width 0.14732)
		(layer "In2.Cu")
		(net "P5E_CPU0_PE3_TX_DP<9>")
	)
	(segment
		(start 374.600978 -298.088812)
		(end 374.39854 -296.853102)
		(width 0.14732)
		(layer "In2.Cu")
		(net "P5E_CPU0_PE3_TX_DP<9>")
	)
	(segment
		(start 391.71753 -406.002236)
		(end 391.90295 -404.118572)
		(width 0.14732)
		(layer "In2.Cu")
		(net "P5E_CPU0_PE3_TX_DP<9>")
	)
	(segment
		(start 398.036034 -333.276448)
		(end 396.849854 -326.549004)
		(width 0.14732)
		(layer "In2.Cu")
		(net "P5E_CPU0_PE3_TX_DP<9>")
	)
	(segment
		(start 373.599202 -286.799274)
		(end 373.591328 -286.794702)
		(width 0.0889)
		(layer "In2.Cu")
		(net "P5E_CPU0_PE3_TX_DP<9>")
	)
	(segment
		(start 374.394476 -290.115752)
		(end 374.352312 -290.073588)
		(width 0.0889)
		(layer "In2.Cu")
		(net "P5E_CPU0_PE3_TX_DP<9>")
	)
	(segment
		(start 392.196574 -397.757142)
		(end 392.241278 -397.391382)
		(width 0.14732)
		(layer "In2.Cu")
		(net "P5E_CPU0_PE3_TX_DP<9>")
	)
	(segment
		(start 373.082566 -285.369508)
		(end 373.160798 -285.390336)
		(width 0.0889)
		(layer "In2.Cu")
		(net "P5E_CPU0_PE3_TX_DP<9>")
	)
	(segment
		(start 392.01217 -407.00452)
		(end 391.71753 -406.70988)
		(width 0.14732)
		(layer "In2.Cu")
		(net "P5E_CPU0_PE3_TX_DP<9>")
	)
	(segment
		(start 391.90295 -404.118572)
		(end 391.90295 -398.957546)
		(width 0.14732)
		(layer "In2.Cu")
		(net "P5E_CPU0_PE3_TX_DP<9>")
	)
	(segment
		(start 374.822466 -289.114484)
		(end 374.822466 -288.898584)
		(width 0.0889)
		(layer "In2.Cu")
		(net "P5E_CPU0_PE3_TX_DP<9>")
	)
	(segment
		(start 373.600218 -286.799782)
		(end 373.599202 -286.799274)
		(width 0.0889)
		(layer "In2.Cu")
		(net "P5E_CPU0_PE3_TX_DP<9>")
	)
	(segment
		(start 373.130064 -285.985712)
		(end 373.129302 -285.985204)
		(width 0.0889)
		(layer "In2.Cu")
		(net "P5E_CPU0_PE3_TX_DP<9>")
	)
	(segment
		(start 374.39854 -296.853102)
		(end 374.394476 -290.286694)
		(width 0.14732)
		(layer "In2.Cu")
		(net "P5E_CPU0_PE3_TX_DP<9>")
	)
	(segment
		(start 392.115294 -397.230092)
		(end 392.170158 -396.782798)
		(width 0.14732)
		(layer "In2.Cu")
		(net "P5E_CPU0_PE3_TX_DP<9>")
	)
	(segment
		(start 374.352312 -290.073588)
		(end 374.352312 -289.64636)
		(width 0.0889)
		(layer "In2.Cu")
		(net "P5E_CPU0_PE3_TX_DP<9>")
	)
	(segment
		(start 374.394476 -290.286694)
		(end 374.394476 -290.13785)
		(width 0.14732)
		(layer "In2.Cu")
		(net "P5E_CPU0_PE3_TX_DP<9>")
	)
	(segment
		(start 392.170158 -396.782798)
		(end 392.309096 -396.67434)
		(width 0.14732)
		(layer "In2.Cu")
		(net "P5E_CPU0_PE3_TX_DP<9>")
	)
	(segment
		(start 391.71753 -406.70988)
		(end 391.71753 -406.002236)
		(width 0.14732)
		(layer "In2.Cu")
		(net "P5E_CPU0_PE3_TX_DP<9>")
	)
	(segment
		(start 373.160798 -285.390336)
		(end 373.317262 -285.661354)
		(width 0.0889)
		(layer "In2.Cu")
		(net "P5E_CPU0_PE3_TX_DP<9>")
	)
	(segment
		(start 375.922032 -299.835824)
		(end 374.600978 -298.088812)
		(width 0.14732)
		(layer "In2.Cu")
		(net "P5E_CPU0_PE3_TX_DP<9>")
	)
	(segment
		(start 373.129302 -285.985204)
		(end 373.121174 -285.980632)
		(width 0.0889)
		(layer "In2.Cu")
		(net "P5E_CPU0_PE3_TX_DP<9>")
	)
	(segment
		(start 374.07596 -287.617154)
		(end 374.069864 -287.613598)
		(width 0.0889)
		(layer "In2.Cu")
		(net "P5E_CPU0_PE3_TX_DP<9>")
	)
	(segment
		(start 392.362436 -396.240508)
		(end 392.253978 -396.101824)
		(width 0.14732)
		(layer "In2.Cu")
		(net "P5E_CPU0_PE3_TX_DP<9>")
	)
	(segment
		(start 398.036034 -349.039688)
		(end 398.036034 -333.276448)
		(width 0.14732)
		(layer "In2.Cu")
		(net "P5E_CPU0_PE3_TX_DP<9>")
	)
	(segment
		(start 392.03503 -397.882872)
		(end 392.196574 -397.757142)
		(width 0.14732)
		(layer "In2.Cu")
		(net "P5E_CPU0_PE3_TX_DP<9>")
	)
	(segment
		(start 374.394476 -290.13785)
		(end 374.394476 -290.115752)
		(width 0.0889)
		(layer "In2.Cu")
		(net "P5E_CPU0_PE3_TX_DP<9>")
	)
	(segment
		(start 376.241056 -300.154848)
		(end 375.922032 -299.835824)
		(width 0.14732)
		(layer "In2.Cu")
		(net "P5E_CPU0_PE3_TX_DP<9>")
	)
	(segment
		(start 373.412766 -286.475424)
		(end 373.412766 -286.467804)
		(width 0.0889)
		(layer "In2.Cu")
		(net "P5E_CPU0_PE3_TX_DP<9>")
	)
	(arc
		(start 374.352312 -289.64636)
		(mid 374.427383 -289.530618)
		(end 374.536716 -289.446462)
		(width 0.0889)
		(layer "In2.Cu")
		(net "P5E_CPU0_PE3_TX_DP<9>")
	)
	(arc
		(start 373.412766 -286.467804)
		(mid 373.335137 -286.189391)
		(end 373.130064 -285.985712)
		(width 0.0889)
		(layer "In2.Cu")
		(net "P5E_CPU0_PE3_TX_DP<9>")
	)
	(arc
		(start 373.882412 -287.273746)
		(mid 373.803042 -287.000012)
		(end 373.600218 -286.799782)
		(width 0.0889)
		(layer "In2.Cu")
		(net "P5E_CPU0_PE3_TX_DP<9>")
	)
	(arc
		(start 374.060974 -287.608518)
		(mid 373.93006 -287.472158)
		(end 373.882412 -287.28924)
		(width 0.0889)
		(layer "In2.Cu")
		(net "P5E_CPU0_PE3_TX_DP<9>")
	)
	(arc
		(start 374.531128 -288.422334)
		(mid 374.400214 -288.285974)
		(end 374.352566 -288.103056)
		(width 0.0889)
		(layer "In2.Cu")
		(net "P5E_CPU0_PE3_TX_DP<9>")
	)
	(arc
		(start 374.822466 -288.898584)
		(mid 374.742304 -288.626395)
		(end 374.540018 -288.427414)
		(width 0.0889)
		(layer "In2.Cu")
		(net "P5E_CPU0_PE3_TX_DP<9>")
	)
	(arc
		(start 372.942612 -285.661354)
		(mid 372.979472 -285.499557)
		(end 373.082566 -285.369508)
		(width 0.0889)
		(layer "In2.Cu")
		(net "P5E_CPU0_PE3_TX_DP<9>")
	)
	(arc
		(start 374.352566 -288.103056)
		(mid 374.278575 -287.82349)
		(end 374.07596 -287.617154)
		(width 0.0889)
		(layer "In2.Cu")
		(net "P5E_CPU0_PE3_TX_DP<9>")
	)
	(arc
		(start 373.591328 -286.794702)
		(mid 373.460414 -286.658342)
		(end 373.412766 -286.475424)
		(width 0.0889)
		(layer "In2.Cu")
		(net "P5E_CPU0_PE3_TX_DP<9>")
	)
	(arc
		(start 374.536716 -289.446462)
		(mid 374.711017 -289.307532)
		(end 374.822466 -289.114484)
		(width 0.0889)
		(layer "In2.Cu")
		(net "P5E_CPU0_PE3_TX_DP<9>")
	)
	(arc
		(start 373.121174 -285.980632)
		(mid 372.99026 -285.844272)
		(end 372.942612 -285.661354)
		(width 0.0889)
		(layer "In2.Cu")
		(net "P5E_CPU0_PE3_TX_DP<9>")
	)
	(segment
		(start 394.776452 -407.926286)
		(end 395.10081 -408.250644)
		(width 0.13208)
		(layer "F.Cu")
		(net "P5E_CPU0_PE3_TX_DP<8>")
	)
	(segment
		(start 374.257316 -285.6611)
		(end 374.257062 -285.661354)
		(width 0.13208)
		(layer "F.Cu")
		(net "P5E_CPU0_PE3_TX_DP<8>")
	)
	(segment
		(start 395.07541 -407.00452)
		(end 394.776452 -407.303478)
		(width 0.13208)
		(layer "F.Cu")
		(net "P5E_CPU0_PE3_TX_DP<8>")
	)
	(segment
		(start 374.257316 -285.125414)
		(end 374.257316 -285.6611)
		(width 0.13208)
		(layer "F.Cu")
		(net "P5E_CPU0_PE3_TX_DP<8>")
	)
	(segment
		(start 394.776452 -407.303478)
		(end 394.776452 -407.926286)
		(width 0.13208)
		(layer "F.Cu")
		(net "P5E_CPU0_PE3_TX_DP<8>")
	)
	(segment
		(start 375.01576 -287.617154)
		(end 375.011188 -287.614614)
		(width 0.0889)
		(layer "In2.Cu")
		(net "P5E_CPU0_PE3_TX_DP<8>")
	)
	(segment
		(start 394.96619 -398.08531)
		(end 398.991836 -349.192088)
		(width 0.14732)
		(layer "In2.Cu")
		(net "P5E_CPU0_PE3_TX_DP<8>")
	)
	(segment
		(start 375.334022 -295.993058)
		(end 375.334022 -290.139882)
		(width 0.14732)
		(layer "In2.Cu")
		(net "P5E_CPU0_PE3_TX_DP<8>")
	)
	(segment
		(start 394.78077 -406.002236)
		(end 394.96619 -404.118572)
		(width 0.14732)
		(layer "In2.Cu")
		(net "P5E_CPU0_PE3_TX_DP<8>")
	)
	(segment
		(start 374.100598 -285.932372)
		(end 374.257062 -285.661354)
		(width 0.0889)
		(layer "In2.Cu")
		(net "P5E_CPU0_PE3_TX_DP<8>")
	)
	(segment
		(start 398.991836 -349.192088)
		(end 398.991836 -332.58506)
		(width 0.14732)
		(layer "In2.Cu")
		(net "P5E_CPU0_PE3_TX_DP<8>")
	)
	(segment
		(start 375.762266 -289.114484)
		(end 375.762266 -288.898584)
		(width 0.0889)
		(layer "In2.Cu")
		(net "P5E_CPU0_PE3_TX_DP<8>")
	)
	(segment
		(start 397.86687 -326.206358)
		(end 377.510294 -300.14799)
		(width 0.14732)
		(layer "In2.Cu")
		(net "P5E_CPU0_PE3_TX_DP<8>")
	)
	(segment
		(start 375.009664 -287.613598)
		(end 375.00814 -287.612836)
		(width 0.0889)
		(layer "In2.Cu")
		(net "P5E_CPU0_PE3_TX_DP<8>")
	)
	(segment
		(start 398.991836 -332.58506)
		(end 397.86687 -326.206358)
		(width 0.14732)
		(layer "In2.Cu")
		(net "P5E_CPU0_PE3_TX_DP<8>")
	)
	(segment
		(start 374.124728 -286.021526)
		(end 374.100598 -285.932372)
		(width 0.0889)
		(layer "In2.Cu")
		(net "P5E_CPU0_PE3_TX_DP<8>")
	)
	(segment
		(start 375.581418 -297.394376)
		(end 375.334022 -295.993058)
		(width 0.14732)
		(layer "In2.Cu")
		(net "P5E_CPU0_PE3_TX_DP<8>")
	)
	(segment
		(start 377.510294 -300.14799)
		(end 375.581418 -297.394376)
		(width 0.14732)
		(layer "In2.Cu")
		(net "P5E_CPU0_PE3_TX_DP<8>")
	)
	(segment
		(start 375.291858 -290.07562)
		(end 375.291858 -289.752786)
		(width 0.0889)
		(layer "In2.Cu")
		(net "P5E_CPU0_PE3_TX_DP<8>")
	)
	(segment
		(start 375.4755 -288.424874)
		(end 375.470928 -288.422334)
		(width 0.0889)
		(layer "In2.Cu")
		(net "P5E_CPU0_PE3_TX_DP<8>")
	)
	(segment
		(start 394.96619 -404.118572)
		(end 394.96619 -398.08531)
		(width 0.14732)
		(layer "In2.Cu")
		(net "P5E_CPU0_PE3_TX_DP<8>")
	)
	(segment
		(start 375.011188 -287.614614)
		(end 375.009664 -287.613598)
		(width 0.0889)
		(layer "In2.Cu")
		(net "P5E_CPU0_PE3_TX_DP<8>")
	)
	(segment
		(start 375.479818 -288.427414)
		(end 375.4755 -288.424874)
		(width 0.0889)
		(layer "In2.Cu")
		(net "P5E_CPU0_PE3_TX_DP<8>")
	)
	(segment
		(start 374.822212 -287.28924)
		(end 374.822212 -287.279334)
		(width 0.0889)
		(layer "In2.Cu")
		(net "P5E_CPU0_PE3_TX_DP<8>")
	)
	(segment
		(start 375.00814 -287.612836)
		(end 375.000774 -287.608518)
		(width 0.0889)
		(layer "In2.Cu")
		(net "P5E_CPU0_PE3_TX_DP<8>")
	)
	(segment
		(start 375.334022 -290.139882)
		(end 375.334022 -290.117784)
		(width 0.0889)
		(layer "In2.Cu")
		(net "P5E_CPU0_PE3_TX_DP<8>")
	)
	(segment
		(start 394.78077 -406.70988)
		(end 394.78077 -406.002236)
		(width 0.14732)
		(layer "In2.Cu")
		(net "P5E_CPU0_PE3_TX_DP<8>")
	)
	(segment
		(start 395.07541 -407.00452)
		(end 394.78077 -406.70988)
		(width 0.14732)
		(layer "In2.Cu")
		(net "P5E_CPU0_PE3_TX_DP<8>")
	)
	(segment
		(start 374.352566 -286.48406)
		(end 374.352566 -286.4612)
		(width 0.0889)
		(layer "In2.Cu")
		(net "P5E_CPU0_PE3_TX_DP<8>")
	)
	(segment
		(start 375.334022 -290.117784)
		(end 375.291858 -290.07562)
		(width 0.0889)
		(layer "In2.Cu")
		(net "P5E_CPU0_PE3_TX_DP<8>")
	)
	(arc
		(start 375.292366 -288.103056)
		(mid 375.218375 -287.82349)
		(end 375.01576 -287.617154)
		(width 0.0889)
		(layer "In2.Cu")
		(net "P5E_CPU0_PE3_TX_DP<8>")
	)
	(arc
		(start 374.822212 -287.279334)
		(mid 374.744101 -287.002385)
		(end 374.539764 -286.799782)
		(width 0.0889)
		(layer "In2.Cu")
		(net "P5E_CPU0_PE3_TX_DP<8>")
	)
	(arc
		(start 375.000774 -287.608518)
		(mid 374.86986 -287.472158)
		(end 374.822212 -287.28924)
		(width 0.0889)
		(layer "In2.Cu")
		(net "P5E_CPU0_PE3_TX_DP<8>")
	)
	(arc
		(start 374.539764 -286.799782)
		(mid 374.404831 -286.666428)
		(end 374.352566 -286.48406)
		(width 0.0889)
		(layer "In2.Cu")
		(net "P5E_CPU0_PE3_TX_DP<8>")
	)
	(arc
		(start 375.470928 -288.422334)
		(mid 375.340014 -288.285974)
		(end 375.292366 -288.103056)
		(width 0.0889)
		(layer "In2.Cu")
		(net "P5E_CPU0_PE3_TX_DP<8>")
	)
	(arc
		(start 374.352566 -286.4612)
		(mid 374.289337 -286.215107)
		(end 374.124728 -286.021526)
		(width 0.0889)
		(layer "In2.Cu")
		(net "P5E_CPU0_PE3_TX_DP<8>")
	)
	(arc
		(start 375.291858 -289.752786)
		(mid 375.34161 -289.573975)
		(end 375.476516 -289.446462)
		(width 0.0889)
		(layer "In2.Cu")
		(net "P5E_CPU0_PE3_TX_DP<8>")
	)
	(arc
		(start 375.762266 -288.898584)
		(mid 375.682104 -288.626395)
		(end 375.479818 -288.427414)
		(width 0.0889)
		(layer "In2.Cu")
		(net "P5E_CPU0_PE3_TX_DP<8>")
	)
	(arc
		(start 375.476516 -289.446462)
		(mid 375.650817 -289.307532)
		(end 375.762266 -289.114484)
		(width 0.0889)
		(layer "In2.Cu")
		(net "P5E_CPU0_PE3_TX_DP<8>")
	)
	(segment
		(start 375.197116 -285.6611)
		(end 375.196862 -285.661354)
		(width 0.13208)
		(layer "F.Cu")
		(net "P5E_CPU0_PE3_TX_DP<7>")
	)
	(segment
		(start 375.197116 -285.125414)
		(end 375.197116 -285.6611)
		(width 0.13208)
		(layer "F.Cu")
		(net "P5E_CPU0_PE3_TX_DP<7>")
	)
	(segment
		(start 397.839692 -407.926286)
		(end 398.16405 -408.250644)
		(width 0.13208)
		(layer "F.Cu")
		(net "P5E_CPU0_PE3_TX_DP<7>")
	)
	(segment
		(start 398.13865 -407.00452)
		(end 397.839692 -407.303478)
		(width 0.13208)
		(layer "F.Cu")
		(net "P5E_CPU0_PE3_TX_DP<7>")
	)
	(segment
		(start 397.839692 -407.303478)
		(end 397.839692 -407.926286)
		(width 0.13208)
		(layer "F.Cu")
		(net "P5E_CPU0_PE3_TX_DP<7>")
	)
	(segment
		(start 398.02943 -397.556228)
		(end 398.02943 -396.967456)
		(width 0.14732)
		(layer "In2.Cu")
		(net "P5E_CPU0_PE3_TX_DP<7>")
	)
	(segment
		(start 376.273822 -290.117784)
		(end 376.231658 -290.07562)
		(width 0.0889)
		(layer "In2.Cu")
		(net "P5E_CPU0_PE3_TX_DP<7>")
	)
	(segment
		(start 398.02943 -404.118572)
		(end 398.02943 -399.364708)
		(width 0.14732)
		(layer "In2.Cu")
		(net "P5E_CPU0_PE3_TX_DP<7>")
	)
	(segment
		(start 397.84401 -406.70988)
		(end 397.84401 -406.002236)
		(width 0.14732)
		(layer "In2.Cu")
		(net "P5E_CPU0_PE3_TX_DP<7>")
	)
	(segment
		(start 375.950988 -287.614614)
		(end 375.949464 -287.613598)
		(width 0.0889)
		(layer "In2.Cu")
		(net "P5E_CPU0_PE3_TX_DP<7>")
	)
	(segment
		(start 400.124422 -335.333086)
		(end 400.045682 -333.148432)
		(width 0.14732)
		(layer "In2.Cu")
		(net "P5E_CPU0_PE3_TX_DP<7>")
	)
	(segment
		(start 398.02943 -399.364708)
		(end 398.15389 -399.240248)
		(width 0.14732)
		(layer "In2.Cu")
		(net "P5E_CPU0_PE3_TX_DP<7>")
	)
	(segment
		(start 375.040398 -285.390336)
		(end 375.196862 -285.661354)
		(width 0.0889)
		(layer "In2.Cu")
		(net "P5E_CPU0_PE3_TX_DP<7>")
	)
	(segment
		(start 375.95556 -287.617154)
		(end 375.950988 -287.614614)
		(width 0.0889)
		(layer "In2.Cu")
		(net "P5E_CPU0_PE3_TX_DP<7>")
	)
	(segment
		(start 374.962166 -285.369508)
		(end 375.040398 -285.390336)
		(width 0.0889)
		(layer "In2.Cu")
		(net "P5E_CPU0_PE3_TX_DP<7>")
	)
	(segment
		(start 376.273822 -295.445942)
		(end 376.273822 -290.139882)
		(width 0.14732)
		(layer "In2.Cu")
		(net "P5E_CPU0_PE3_TX_DP<7>")
	)
	(segment
		(start 378.26188 -299.58284)
		(end 376.5804 -297.181524)
		(width 0.14732)
		(layer "In2.Cu")
		(net "P5E_CPU0_PE3_TX_DP<7>")
	)
	(segment
		(start 400.045682 -333.148432)
		(end 398.751806 -325.812404)
		(width 0.14732)
		(layer "In2.Cu")
		(net "P5E_CPU0_PE3_TX_DP<7>")
	)
	(segment
		(start 398.751806 -325.812404)
		(end 378.26188 -299.58284)
		(width 0.14732)
		(layer "In2.Cu")
		(net "P5E_CPU0_PE3_TX_DP<7>")
	)
	(segment
		(start 399.76171 -368.346482)
		(end 400.124422 -335.333086)
		(width 0.14732)
		(layer "In2.Cu")
		(net "P5E_CPU0_PE3_TX_DP<7>")
	)
	(segment
		(start 375.762012 -287.28924)
		(end 375.762012 -287.273746)
		(width 0.0889)
		(layer "In2.Cu")
		(net "P5E_CPU0_PE3_TX_DP<7>")
	)
	(segment
		(start 376.701812 -289.037268)
		(end 376.702066 -288.898584)
		(width 0.0889)
		(layer "In2.Cu")
		(net "P5E_CPU0_PE3_TX_DP<7>")
	)
	(segment
		(start 376.419618 -288.427414)
		(end 376.410728 -288.422334)
		(width 0.0889)
		(layer "In2.Cu")
		(net "P5E_CPU0_PE3_TX_DP<7>")
	)
	(segment
		(start 398.15389 -397.680688)
		(end 398.02943 -397.556228)
		(width 0.14732)
		(layer "In2.Cu")
		(net "P5E_CPU0_PE3_TX_DP<7>")
	)
	(segment
		(start 398.02943 -396.967456)
		(end 399.76171 -368.346482)
		(width 0.14732)
		(layer "In2.Cu")
		(net "P5E_CPU0_PE3_TX_DP<7>")
	)
	(segment
		(start 397.84401 -406.002236)
		(end 398.02943 -404.118572)
		(width 0.14732)
		(layer "In2.Cu")
		(net "P5E_CPU0_PE3_TX_DP<7>")
	)
	(segment
		(start 398.02943 -398.678908)
		(end 398.02943 -398.242028)
		(width 0.14732)
		(layer "In2.Cu")
		(net "P5E_CPU0_PE3_TX_DP<7>")
	)
	(segment
		(start 375.009664 -285.985712)
		(end 375.008902 -285.985204)
		(width 0.0889)
		(layer "In2.Cu")
		(net "P5E_CPU0_PE3_TX_DP<7>")
	)
	(segment
		(start 376.5804 -297.181524)
		(end 376.273822 -295.445942)
		(width 0.14732)
		(layer "In2.Cu")
		(net "P5E_CPU0_PE3_TX_DP<7>")
	)
	(segment
		(start 375.292366 -286.475424)
		(end 375.292366 -286.467804)
		(width 0.0889)
		(layer "In2.Cu")
		(net "P5E_CPU0_PE3_TX_DP<7>")
	)
	(segment
		(start 398.15389 -398.117568)
		(end 398.15389 -397.680688)
		(width 0.14732)
		(layer "In2.Cu")
		(net "P5E_CPU0_PE3_TX_DP<7>")
	)
	(segment
		(start 376.231658 -290.07562)
		(end 376.231658 -289.70732)
		(width 0.0889)
		(layer "In2.Cu")
		(net "P5E_CPU0_PE3_TX_DP<7>")
	)
	(segment
		(start 375.008902 -285.985204)
		(end 375.000774 -285.980632)
		(width 0.0889)
		(layer "In2.Cu")
		(net "P5E_CPU0_PE3_TX_DP<7>")
	)
	(segment
		(start 398.15389 -399.240248)
		(end 398.15389 -398.803368)
		(width 0.14732)
		(layer "In2.Cu")
		(net "P5E_CPU0_PE3_TX_DP<7>")
	)
	(segment
		(start 376.273822 -290.139882)
		(end 376.273822 -290.117784)
		(width 0.0889)
		(layer "In2.Cu")
		(net "P5E_CPU0_PE3_TX_DP<7>")
	)
	(segment
		(start 375.478802 -286.799274)
		(end 375.470928 -286.794702)
		(width 0.0889)
		(layer "In2.Cu")
		(net "P5E_CPU0_PE3_TX_DP<7>")
	)
	(segment
		(start 375.949464 -287.613598)
		(end 375.940574 -287.608518)
		(width 0.0889)
		(layer "In2.Cu")
		(net "P5E_CPU0_PE3_TX_DP<7>")
	)
	(segment
		(start 398.15389 -398.803368)
		(end 398.02943 -398.678908)
		(width 0.14732)
		(layer "In2.Cu")
		(net "P5E_CPU0_PE3_TX_DP<7>")
	)
	(segment
		(start 398.13865 -407.00452)
		(end 397.84401 -406.70988)
		(width 0.14732)
		(layer "In2.Cu")
		(net "P5E_CPU0_PE3_TX_DP<7>")
	)
	(segment
		(start 375.479818 -286.799782)
		(end 375.478802 -286.799274)
		(width 0.0889)
		(layer "In2.Cu")
		(net "P5E_CPU0_PE3_TX_DP<7>")
	)
	(segment
		(start 398.02943 -398.242028)
		(end 398.15389 -398.117568)
		(width 0.14732)
		(layer "In2.Cu")
		(net "P5E_CPU0_PE3_TX_DP<7>")
	)
	(arc
		(start 376.410728 -288.422334)
		(mid 376.279814 -288.285974)
		(end 376.232166 -288.103056)
		(width 0.0889)
		(layer "In2.Cu")
		(net "P5E_CPU0_PE3_TX_DP<7>")
	)
	(arc
		(start 374.822212 -285.661354)
		(mid 374.859072 -285.499557)
		(end 374.962166 -285.369508)
		(width 0.0889)
		(layer "In2.Cu")
		(net "P5E_CPU0_PE3_TX_DP<7>")
	)
	(arc
		(start 375.292366 -286.467804)
		(mid 375.214737 -286.189391)
		(end 375.009664 -285.985712)
		(width 0.0889)
		(layer "In2.Cu")
		(net "P5E_CPU0_PE3_TX_DP<7>")
	)
	(arc
		(start 376.467116 -289.415982)
		(mid 376.570949 -289.329017)
		(end 376.652536 -289.22091)
		(width 0.0889)
		(layer "In2.Cu")
		(net "P5E_CPU0_PE3_TX_DP<7>")
	)
	(arc
		(start 375.940574 -287.608518)
		(mid 375.80966 -287.472158)
		(end 375.762012 -287.28924)
		(width 0.0889)
		(layer "In2.Cu")
		(net "P5E_CPU0_PE3_TX_DP<7>")
	)
	(arc
		(start 376.652536 -289.22091)
		(mid 376.689543 -289.132411)
		(end 376.701812 -289.037268)
		(width 0.0889)
		(layer "In2.Cu")
		(net "P5E_CPU0_PE3_TX_DP<7>")
	)
	(arc
		(start 376.25782 -289.62223)
		(mid 376.352425 -289.508917)
		(end 376.467116 -289.415982)
		(width 0.0889)
		(layer "In2.Cu")
		(net "P5E_CPU0_PE3_TX_DP<7>")
	)
	(arc
		(start 375.470928 -286.794702)
		(mid 375.340014 -286.658342)
		(end 375.292366 -286.475424)
		(width 0.0889)
		(layer "In2.Cu")
		(net "P5E_CPU0_PE3_TX_DP<7>")
	)
	(arc
		(start 376.232166 -288.103056)
		(mid 376.158175 -287.82349)
		(end 375.95556 -287.617154)
		(width 0.0889)
		(layer "In2.Cu")
		(net "P5E_CPU0_PE3_TX_DP<7>")
	)
	(arc
		(start 375.762012 -287.273746)
		(mid 375.682642 -287.000012)
		(end 375.479818 -286.799782)
		(width 0.0889)
		(layer "In2.Cu")
		(net "P5E_CPU0_PE3_TX_DP<7>")
	)
	(arc
		(start 376.231658 -289.70732)
		(mid 376.2383 -289.662792)
		(end 376.25782 -289.62223)
		(width 0.0889)
		(layer "In2.Cu")
		(net "P5E_CPU0_PE3_TX_DP<7>")
	)
	(arc
		(start 375.000774 -285.980632)
		(mid 374.86986 -285.844272)
		(end 374.822212 -285.661354)
		(width 0.0889)
		(layer "In2.Cu")
		(net "P5E_CPU0_PE3_TX_DP<7>")
	)
	(arc
		(start 376.702066 -288.898584)
		(mid 376.621904 -288.626395)
		(end 376.419618 -288.427414)
		(width 0.0889)
		(layer "In2.Cu")
		(net "P5E_CPU0_PE3_TX_DP<7>")
	)
	(segment
		(start 376.136916 -285.6611)
		(end 376.136662 -285.661354)
		(width 0.13208)
		(layer "F.Cu")
		(net "P5E_CPU0_PE3_TX_DP<6>")
	)
	(segment
		(start 400.902932 -407.926286)
		(end 401.22729 -408.250644)
		(width 0.13208)
		(layer "F.Cu")
		(net "P5E_CPU0_PE3_TX_DP<6>")
	)
	(segment
		(start 400.902932 -407.303478)
		(end 400.902932 -407.926286)
		(width 0.13208)
		(layer "F.Cu")
		(net "P5E_CPU0_PE3_TX_DP<6>")
	)
	(segment
		(start 401.20189 -407.00452)
		(end 400.902932 -407.303478)
		(width 0.13208)
		(layer "F.Cu")
		(net "P5E_CPU0_PE3_TX_DP<6>")
	)
	(segment
		(start 376.136916 -285.125414)
		(end 376.136916 -285.6611)
		(width 0.13208)
		(layer "F.Cu")
		(net "P5E_CPU0_PE3_TX_DP<6>")
	)
	(segment
		(start 377.171712 -290.086542)
		(end 377.171712 -289.64636)
		(width 0.0889)
		(layer "In2.Cu")
		(net "P5E_CPU0_PE3_TX_DP<6>")
	)
	(segment
		(start 401.20189 -407.00452)
		(end 400.90725 -406.70988)
		(width 0.14732)
		(layer "In2.Cu")
		(net "P5E_CPU0_PE3_TX_DP<6>")
	)
	(segment
		(start 376.89536 -287.617154)
		(end 376.880374 -287.608518)
		(width 0.0889)
		(layer "In2.Cu")
		(net "P5E_CPU0_PE3_TX_DP<6>")
	)
	(segment
		(start 377.213876 -295.33977)
		(end 377.213876 -290.139882)
		(width 0.14732)
		(layer "In2.Cu")
		(net "P5E_CPU0_PE3_TX_DP<6>")
	)
	(segment
		(start 376.004328 -286.021526)
		(end 375.980198 -285.932372)
		(width 0.0889)
		(layer "In2.Cu")
		(net "P5E_CPU0_PE3_TX_DP<6>")
	)
	(segment
		(start 400.90725 -406.002236)
		(end 401.09267 -404.118572)
		(width 0.14732)
		(layer "In2.Cu")
		(net "P5E_CPU0_PE3_TX_DP<6>")
	)
	(segment
		(start 377.828302 -297.307254)
		(end 377.213876 -295.33977)
		(width 0.14732)
		(layer "In2.Cu")
		(net "P5E_CPU0_PE3_TX_DP<6>")
	)
	(segment
		(start 377.213876 -290.128706)
		(end 377.171712 -290.086542)
		(width 0.0889)
		(layer "In2.Cu")
		(net "P5E_CPU0_PE3_TX_DP<6>")
	)
	(segment
		(start 401.09267 -400.010376)
		(end 400.81962 -368.234468)
		(width 0.14732)
		(layer "In2.Cu")
		(net "P5E_CPU0_PE3_TX_DP<6>")
	)
	(segment
		(start 375.980198 -285.932372)
		(end 376.136662 -285.661354)
		(width 0.0889)
		(layer "In2.Cu")
		(net "P5E_CPU0_PE3_TX_DP<6>")
	)
	(segment
		(start 377.359418 -288.427414)
		(end 377.350528 -288.422334)
		(width 0.0889)
		(layer "In2.Cu")
		(net "P5E_CPU0_PE3_TX_DP<6>")
	)
	(segment
		(start 377.213876 -290.139882)
		(end 377.213876 -290.128706)
		(width 0.0889)
		(layer "In2.Cu")
		(net "P5E_CPU0_PE3_TX_DP<6>")
	)
	(segment
		(start 401.17522 -335.037176)
		(end 401.16125 -334.762856)
		(width 0.14732)
		(layer "In2.Cu")
		(net "P5E_CPU0_PE3_TX_DP<6>")
	)
	(segment
		(start 376.701812 -287.28924)
		(end 376.701812 -287.279334)
		(width 0.0889)
		(layer "In2.Cu")
		(net "P5E_CPU0_PE3_TX_DP<6>")
	)
	(segment
		(start 376.232166 -286.48406)
		(end 376.232166 -286.4612)
		(width 0.0889)
		(layer "In2.Cu")
		(net "P5E_CPU0_PE3_TX_DP<6>")
	)
	(segment
		(start 400.81962 -368.234468)
		(end 401.17522 -335.037176)
		(width 0.14732)
		(layer "In2.Cu")
		(net "P5E_CPU0_PE3_TX_DP<6>")
	)
	(segment
		(start 377.641866 -289.114484)
		(end 377.641866 -288.898584)
		(width 0.0889)
		(layer "In2.Cu")
		(net "P5E_CPU0_PE3_TX_DP<6>")
	)
	(segment
		(start 401.09267 -404.118572)
		(end 401.09267 -400.010376)
		(width 0.14732)
		(layer "In2.Cu")
		(net "P5E_CPU0_PE3_TX_DP<6>")
	)
	(segment
		(start 401.16125 -334.762856)
		(end 400.983958 -333.056484)
		(width 0.14732)
		(layer "In2.Cu")
		(net "P5E_CPU0_PE3_TX_DP<6>")
	)
	(segment
		(start 379.002036 -299.003212)
		(end 377.828302 -297.307254)
		(width 0.14732)
		(layer "In2.Cu")
		(net "P5E_CPU0_PE3_TX_DP<6>")
	)
	(segment
		(start 400.983958 -333.056484)
		(end 399.636742 -325.41845)
		(width 0.14732)
		(layer "In2.Cu")
		(net "P5E_CPU0_PE3_TX_DP<6>")
	)
	(segment
		(start 400.90725 -406.70988)
		(end 400.90725 -406.002236)
		(width 0.14732)
		(layer "In2.Cu")
		(net "P5E_CPU0_PE3_TX_DP<6>")
	)
	(segment
		(start 399.636742 -325.41845)
		(end 379.002036 -299.003212)
		(width 0.14732)
		(layer "In2.Cu")
		(net "P5E_CPU0_PE3_TX_DP<6>")
	)
	(arc
		(start 377.350528 -288.422334)
		(mid 377.219614 -288.285974)
		(end 377.171966 -288.103056)
		(width 0.0889)
		(layer "In2.Cu")
		(net "P5E_CPU0_PE3_TX_DP<6>")
	)
	(arc
		(start 377.171712 -289.64636)
		(mid 377.246783 -289.530618)
		(end 377.356116 -289.446462)
		(width 0.0889)
		(layer "In2.Cu")
		(net "P5E_CPU0_PE3_TX_DP<6>")
	)
	(arc
		(start 377.641866 -288.898584)
		(mid 377.561704 -288.626395)
		(end 377.359418 -288.427414)
		(width 0.0889)
		(layer "In2.Cu")
		(net "P5E_CPU0_PE3_TX_DP<6>")
	)
	(arc
		(start 377.171966 -288.103056)
		(mid 377.097975 -287.82349)
		(end 376.89536 -287.617154)
		(width 0.0889)
		(layer "In2.Cu")
		(net "P5E_CPU0_PE3_TX_DP<6>")
	)
	(arc
		(start 376.021346 -286.03448)
		(mid 376.012898 -286.027923)
		(end 376.004328 -286.021526)
		(width 0.0889)
		(layer "In2.Cu")
		(net "P5E_CPU0_PE3_TX_DP<6>")
	)
	(arc
		(start 376.232166 -286.4612)
		(mid 376.173872 -286.224557)
		(end 376.021346 -286.03448)
		(width 0.0889)
		(layer "In2.Cu")
		(net "P5E_CPU0_PE3_TX_DP<6>")
	)
	(arc
		(start 376.880374 -287.608518)
		(mid 376.74946 -287.472158)
		(end 376.701812 -287.28924)
		(width 0.0889)
		(layer "In2.Cu")
		(net "P5E_CPU0_PE3_TX_DP<6>")
	)
	(arc
		(start 376.419364 -286.799782)
		(mid 376.284431 -286.666428)
		(end 376.232166 -286.48406)
		(width 0.0889)
		(layer "In2.Cu")
		(net "P5E_CPU0_PE3_TX_DP<6>")
	)
	(arc
		(start 376.701812 -287.279334)
		(mid 376.623701 -287.002385)
		(end 376.419364 -286.799782)
		(width 0.0889)
		(layer "In2.Cu")
		(net "P5E_CPU0_PE3_TX_DP<6>")
	)
	(arc
		(start 377.356116 -289.446462)
		(mid 377.530417 -289.307532)
		(end 377.641866 -289.114484)
		(width 0.0889)
		(layer "In2.Cu")
		(net "P5E_CPU0_PE3_TX_DP<6>")
	)
	(segment
		(start 403.966172 -407.926286)
		(end 404.29053 -408.250644)
		(width 0.13208)
		(layer "F.Cu")
		(net "P5E_CPU0_PE3_TX_DP<5>")
	)
	(segment
		(start 377.076716 -285.6611)
		(end 377.076462 -285.661354)
		(width 0.13208)
		(layer "F.Cu")
		(net "P5E_CPU0_PE3_TX_DP<5>")
	)
	(segment
		(start 403.966172 -407.303478)
		(end 403.966172 -407.926286)
		(width 0.13208)
		(layer "F.Cu")
		(net "P5E_CPU0_PE3_TX_DP<5>")
	)
	(segment
		(start 404.26513 -407.00452)
		(end 403.966172 -407.303478)
		(width 0.13208)
		(layer "F.Cu")
		(net "P5E_CPU0_PE3_TX_DP<5>")
	)
	(segment
		(start 377.076716 -285.125414)
		(end 377.076716 -285.6611)
		(width 0.13208)
		(layer "F.Cu")
		(net "P5E_CPU0_PE3_TX_DP<5>")
	)
	(segment
		(start 403.97049 -406.70988)
		(end 403.97049 -406.001982)
		(width 0.14732)
		(layer "In2.Cu")
		(net "P5E_CPU0_PE3_TX_DP<5>")
	)
	(segment
		(start 377.171966 -286.475424)
		(end 377.171966 -286.467804)
		(width 0.0889)
		(layer "In2.Cu")
		(net "P5E_CPU0_PE3_TX_DP<5>")
	)
	(segment
		(start 377.358402 -286.799274)
		(end 377.350528 -286.794702)
		(width 0.0889)
		(layer "In2.Cu")
		(net "P5E_CPU0_PE3_TX_DP<5>")
	)
	(segment
		(start 404.164546 -398.56791)
		(end 404.134574 -398.131792)
		(width 0.14732)
		(layer "In2.Cu")
		(net "P5E_CPU0_PE3_TX_DP<5>")
	)
	(segment
		(start 404.15591 -404.118572)
		(end 404.15591 -400.259296)
		(width 0.14732)
		(layer "In2.Cu")
		(net "P5E_CPU0_PE3_TX_DP<5>")
	)
	(segment
		(start 377.641612 -287.28924)
		(end 377.641612 -287.273746)
		(width 0.0889)
		(layer "In2.Cu")
		(net "P5E_CPU0_PE3_TX_DP<5>")
	)
	(segment
		(start 378.153676 -290.13785)
		(end 378.153676 -290.115752)
		(width 0.0889)
		(layer "In2.Cu")
		(net "P5E_CPU0_PE3_TX_DP<5>")
	)
	(segment
		(start 404.26513 -407.00452)
		(end 403.97049 -406.70988)
		(width 0.14732)
		(layer "In2.Cu")
		(net "P5E_CPU0_PE3_TX_DP<5>")
	)
	(segment
		(start 383.076196 -295.114218)
		(end 379.270514 -293.53764)
		(width 0.14732)
		(layer "In2.Cu")
		(net "P5E_CPU0_PE3_TX_DP<5>")
	)
	(segment
		(start 377.359418 -286.799782)
		(end 377.358402 -286.799274)
		(width 0.0889)
		(layer "In2.Cu")
		(net "P5E_CPU0_PE3_TX_DP<5>")
	)
	(segment
		(start 378.153676 -290.115752)
		(end 378.111512 -290.073588)
		(width 0.0889)
		(layer "In2.Cu")
		(net "P5E_CPU0_PE3_TX_DP<5>")
	)
	(segment
		(start 377.83516 -287.617154)
		(end 377.829064 -287.613598)
		(width 0.0889)
		(layer "In2.Cu")
		(net "P5E_CPU0_PE3_TX_DP<5>")
	)
	(segment
		(start 403.92477 -396.895828)
		(end 401.946872 -368.126518)
		(width 0.14732)
		(layer "In2.Cu")
		(net "P5E_CPU0_PE3_TX_DP<5>")
	)
	(segment
		(start 378.299218 -288.427414)
		(end 378.290328 -288.422334)
		(width 0.0889)
		(layer "In2.Cu")
		(net "P5E_CPU0_PE3_TX_DP<5>")
	)
	(segment
		(start 384.174238 -297.023282)
		(end 383.60096 -295.638982)
		(width 0.14732)
		(layer "In2.Cu")
		(net "P5E_CPU0_PE3_TX_DP<5>")
	)
	(segment
		(start 376.841766 -285.369508)
		(end 376.919998 -285.390336)
		(width 0.0889)
		(layer "In2.Cu")
		(net "P5E_CPU0_PE3_TX_DP<5>")
	)
	(segment
		(start 401.946872 -368.126518)
		(end 401.946618 -368.126518)
		(width 0.14732)
		(layer "In2.Cu")
		(net "P5E_CPU0_PE3_TX_DP<5>")
	)
	(segment
		(start 402.193506 -334.931004)
		(end 402.013166 -333.237586)
		(width 0.14732)
		(layer "In2.Cu")
		(net "P5E_CPU0_PE3_TX_DP<5>")
	)
	(segment
		(start 404.001478 -398.016222)
		(end 403.97176 -397.580612)
		(width 0.14732)
		(layer "In2.Cu")
		(net "P5E_CPU0_PE3_TX_DP<5>")
	)
	(segment
		(start 376.919998 -285.390336)
		(end 377.076462 -285.661354)
		(width 0.0889)
		(layer "In2.Cu")
		(net "P5E_CPU0_PE3_TX_DP<5>")
	)
	(segment
		(start 404.08733 -397.44777)
		(end 404.057358 -397.011652)
		(width 0.14732)
		(layer "In2.Cu")
		(net "P5E_CPU0_PE3_TX_DP<5>")
	)
	(segment
		(start 403.97176 -397.580612)
		(end 404.08733 -397.44777)
		(width 0.14732)
		(layer "In2.Cu")
		(net "P5E_CPU0_PE3_TX_DP<5>")
	)
	(segment
		(start 378.581666 -289.114484)
		(end 378.581666 -288.898584)
		(width 0.0889)
		(layer "In2.Cu")
		(net "P5E_CPU0_PE3_TX_DP<5>")
	)
	(segment
		(start 379.270514 -293.53764)
		(end 378.153676 -292.420802)
		(width 0.14732)
		(layer "In2.Cu")
		(net "P5E_CPU0_PE3_TX_DP<5>")
	)
	(segment
		(start 400.531076 -324.83552)
		(end 385.746244 -305.846988)
		(width 0.14732)
		(layer "In2.Cu")
		(net "P5E_CPU0_PE3_TX_DP<5>")
	)
	(segment
		(start 377.829064 -287.613598)
		(end 377.820174 -287.608518)
		(width 0.0889)
		(layer "In2.Cu")
		(net "P5E_CPU0_PE3_TX_DP<5>")
	)
	(segment
		(start 404.134574 -398.131792)
		(end 404.001478 -398.016222)
		(width 0.14732)
		(layer "In2.Cu")
		(net "P5E_CPU0_PE3_TX_DP<5>")
	)
	(segment
		(start 404.048976 -398.700752)
		(end 404.164546 -398.56791)
		(width 0.14732)
		(layer "In2.Cu")
		(net "P5E_CPU0_PE3_TX_DP<5>")
	)
	(segment
		(start 404.057358 -397.011652)
		(end 403.924262 -396.896082)
		(width 0.14732)
		(layer "In2.Cu")
		(net "P5E_CPU0_PE3_TX_DP<5>")
	)
	(segment
		(start 376.889264 -285.985712)
		(end 376.880374 -285.980632)
		(width 0.0889)
		(layer "In2.Cu")
		(net "P5E_CPU0_PE3_TX_DP<5>")
	)
	(segment
		(start 403.97049 -406.001982)
		(end 404.15591 -404.118572)
		(width 0.14732)
		(layer "In2.Cu")
		(net "P5E_CPU0_PE3_TX_DP<5>")
	)
	(segment
		(start 378.111512 -290.073588)
		(end 378.111512 -289.64636)
		(width 0.0889)
		(layer "In2.Cu")
		(net "P5E_CPU0_PE3_TX_DP<5>")
	)
	(segment
		(start 385.746244 -305.846988)
		(end 384.174238 -297.023282)
		(width 0.14732)
		(layer "In2.Cu")
		(net "P5E_CPU0_PE3_TX_DP<5>")
	)
	(segment
		(start 403.924262 -396.896082)
		(end 403.92477 -396.895828)
		(width 0.14732)
		(layer "In2.Cu")
		(net "P5E_CPU0_PE3_TX_DP<5>")
	)
	(segment
		(start 401.946618 -368.126518)
		(end 402.193506 -334.931004)
		(width 0.14732)
		(layer "In2.Cu")
		(net "P5E_CPU0_PE3_TX_DP<5>")
	)
	(segment
		(start 378.153676 -292.420802)
		(end 378.153676 -290.13785)
		(width 0.14732)
		(layer "In2.Cu")
		(net "P5E_CPU0_PE3_TX_DP<5>")
	)
	(segment
		(start 404.15591 -400.259296)
		(end 404.048976 -398.700752)
		(width 0.14732)
		(layer "In2.Cu")
		(net "P5E_CPU0_PE3_TX_DP<5>")
	)
	(segment
		(start 383.60096 -295.638982)
		(end 383.076196 -295.114218)
		(width 0.14732)
		(layer "In2.Cu")
		(net "P5E_CPU0_PE3_TX_DP<5>")
	)
	(segment
		(start 402.013166 -333.237586)
		(end 400.531076 -324.83552)
		(width 0.14732)
		(layer "In2.Cu")
		(net "P5E_CPU0_PE3_TX_DP<5>")
	)
	(arc
		(start 376.880374 -285.980632)
		(mid 376.74946 -285.844272)
		(end 376.701812 -285.661354)
		(width 0.0889)
		(layer "In2.Cu")
		(net "P5E_CPU0_PE3_TX_DP<5>")
	)
	(arc
		(start 378.581666 -288.898584)
		(mid 378.501504 -288.626395)
		(end 378.299218 -288.427414)
		(width 0.0889)
		(layer "In2.Cu")
		(net "P5E_CPU0_PE3_TX_DP<5>")
	)
	(arc
		(start 378.295916 -289.446462)
		(mid 378.470217 -289.307532)
		(end 378.581666 -289.114484)
		(width 0.0889)
		(layer "In2.Cu")
		(net "P5E_CPU0_PE3_TX_DP<5>")
	)
	(arc
		(start 377.641612 -287.273746)
		(mid 377.562242 -287.000012)
		(end 377.359418 -286.799782)
		(width 0.0889)
		(layer "In2.Cu")
		(net "P5E_CPU0_PE3_TX_DP<5>")
	)
	(arc
		(start 378.111766 -288.103056)
		(mid 378.037775 -287.82349)
		(end 377.83516 -287.617154)
		(width 0.0889)
		(layer "In2.Cu")
		(net "P5E_CPU0_PE3_TX_DP<5>")
	)
	(arc
		(start 377.171966 -286.467804)
		(mid 377.094337 -286.189391)
		(end 376.889264 -285.985712)
		(width 0.0889)
		(layer "In2.Cu")
		(net "P5E_CPU0_PE3_TX_DP<5>")
	)
	(arc
		(start 377.350528 -286.794702)
		(mid 377.219614 -286.658342)
		(end 377.171966 -286.475424)
		(width 0.0889)
		(layer "In2.Cu")
		(net "P5E_CPU0_PE3_TX_DP<5>")
	)
	(arc
		(start 377.820174 -287.608518)
		(mid 377.68926 -287.472158)
		(end 377.641612 -287.28924)
		(width 0.0889)
		(layer "In2.Cu")
		(net "P5E_CPU0_PE3_TX_DP<5>")
	)
	(arc
		(start 376.701812 -285.661354)
		(mid 376.738672 -285.499557)
		(end 376.841766 -285.369508)
		(width 0.0889)
		(layer "In2.Cu")
		(net "P5E_CPU0_PE3_TX_DP<5>")
	)
	(arc
		(start 378.111512 -289.64636)
		(mid 378.186583 -289.530618)
		(end 378.295916 -289.446462)
		(width 0.0889)
		(layer "In2.Cu")
		(net "P5E_CPU0_PE3_TX_DP<5>")
	)
	(arc
		(start 378.290328 -288.422334)
		(mid 378.159414 -288.285974)
		(end 378.111766 -288.103056)
		(width 0.0889)
		(layer "In2.Cu")
		(net "P5E_CPU0_PE3_TX_DP<5>")
	)
	(segment
		(start 378.016516 -285.6611)
		(end 378.016262 -285.661354)
		(width 0.13208)
		(layer "F.Cu")
		(net "P5E_CPU0_PE3_TX_DP<4>")
	)
	(segment
		(start 407.32837 -407.00452)
		(end 407.029412 -407.303478)
		(width 0.13208)
		(layer "F.Cu")
		(net "P5E_CPU0_PE3_TX_DP<4>")
	)
	(segment
		(start 407.029412 -407.926286)
		(end 407.35377 -408.250644)
		(width 0.13208)
		(layer "F.Cu")
		(net "P5E_CPU0_PE3_TX_DP<4>")
	)
	(segment
		(start 378.016516 -285.125414)
		(end 378.016516 -285.6611)
		(width 0.13208)
		(layer "F.Cu")
		(net "P5E_CPU0_PE3_TX_DP<4>")
	)
	(segment
		(start 407.029412 -407.303478)
		(end 407.029412 -407.926286)
		(width 0.13208)
		(layer "F.Cu")
		(net "P5E_CPU0_PE3_TX_DP<4>")
	)
	(segment
		(start 379.521466 -289.114484)
		(end 379.521466 -288.898584)
		(width 0.0889)
		(layer "In2.Cu")
		(net "P5E_CPU0_PE3_TX_DP<4>")
	)
	(segment
		(start 401.412964 -324.443344)
		(end 386.653786 -305.487832)
		(width 0.14732)
		(layer "In2.Cu")
		(net "P5E_CPU0_PE3_TX_DP<4>")
	)
	(segment
		(start 379.093476 -290.13785)
		(end 379.093476 -290.115752)
		(width 0.0889)
		(layer "In2.Cu")
		(net "P5E_CPU0_PE3_TX_DP<4>")
	)
	(segment
		(start 377.859798 -285.932372)
		(end 378.016262 -285.661354)
		(width 0.0889)
		(layer "In2.Cu")
		(net "P5E_CPU0_PE3_TX_DP<4>")
	)
	(segment
		(start 378.581412 -287.28924)
		(end 378.581412 -287.279334)
		(width 0.0889)
		(layer "In2.Cu")
		(net "P5E_CPU0_PE3_TX_DP<4>")
	)
	(segment
		(start 379.704854 -292.62197)
		(end 379.093476 -292.010592)
		(width 0.14732)
		(layer "In2.Cu")
		(net "P5E_CPU0_PE3_TX_DP<4>")
	)
	(segment
		(start 385.110736 -296.830242)
		(end 384.929888 -296.393362)
		(width 0.14732)
		(layer "In2.Cu")
		(net "P5E_CPU0_PE3_TX_DP<4>")
	)
	(segment
		(start 407.21915 -404.118572)
		(end 407.21915 -400.433286)
		(width 0.14732)
		(layer "In2.Cu")
		(net "P5E_CPU0_PE3_TX_DP<4>")
	)
	(segment
		(start 379.051312 -290.073588)
		(end 379.051312 -289.64636)
		(width 0.0889)
		(layer "In2.Cu")
		(net "P5E_CPU0_PE3_TX_DP<4>")
	)
	(segment
		(start 379.238256 -288.426906)
		(end 379.230128 -288.422334)
		(width 0.0889)
		(layer "In2.Cu")
		(net "P5E_CPU0_PE3_TX_DP<4>")
	)
	(segment
		(start 402.92274 -368.230404)
		(end 403.223222 -334.709008)
		(width 0.14732)
		(layer "In2.Cu")
		(net "P5E_CPU0_PE3_TX_DP<4>")
	)
	(segment
		(start 378.111766 -286.48406)
		(end 378.111766 -286.4612)
		(width 0.0889)
		(layer "In2.Cu")
		(net "P5E_CPU0_PE3_TX_DP<4>")
	)
	(segment
		(start 379.239018 -288.427414)
		(end 379.238256 -288.426906)
		(width 0.0889)
		(layer "In2.Cu")
		(net "P5E_CPU0_PE3_TX_DP<4>")
	)
	(segment
		(start 407.21915 -400.433286)
		(end 402.92274 -368.230404)
		(width 0.14732)
		(layer "In2.Cu")
		(net "P5E_CPU0_PE3_TX_DP<4>")
	)
	(segment
		(start 377.883928 -286.021526)
		(end 377.859798 -285.932372)
		(width 0.0889)
		(layer "In2.Cu")
		(net "P5E_CPU0_PE3_TX_DP<4>")
	)
	(segment
		(start 407.32837 -407.00452)
		(end 407.03373 -406.70988)
		(width 0.14732)
		(layer "In2.Cu")
		(net "P5E_CPU0_PE3_TX_DP<4>")
	)
	(segment
		(start 384.399536 -295.112948)
		(end 383.465832 -294.179244)
		(width 0.14732)
		(layer "In2.Cu")
		(net "P5E_CPU0_PE3_TX_DP<4>")
	)
	(segment
		(start 403.223222 -334.709008)
		(end 401.412964 -324.443344)
		(width 0.14732)
		(layer "In2.Cu")
		(net "P5E_CPU0_PE3_TX_DP<4>")
	)
	(segment
		(start 407.03373 -406.70988)
		(end 407.03373 -406.001982)
		(width 0.14732)
		(layer "In2.Cu")
		(net "P5E_CPU0_PE3_TX_DP<4>")
	)
	(segment
		(start 383.465832 -294.179244)
		(end 379.704854 -292.62197)
		(width 0.14732)
		(layer "In2.Cu")
		(net "P5E_CPU0_PE3_TX_DP<4>")
	)
	(segment
		(start 378.771658 -287.615376)
		(end 378.759974 -287.608518)
		(width 0.0889)
		(layer "In2.Cu")
		(net "P5E_CPU0_PE3_TX_DP<4>")
	)
	(segment
		(start 386.653786 -305.487832)
		(end 385.110736 -296.830242)
		(width 0.14732)
		(layer "In2.Cu")
		(net "P5E_CPU0_PE3_TX_DP<4>")
	)
	(segment
		(start 379.093476 -292.010592)
		(end 379.093476 -290.13785)
		(width 0.14732)
		(layer "In2.Cu")
		(net "P5E_CPU0_PE3_TX_DP<4>")
	)
	(segment
		(start 384.929888 -296.393362)
		(end 384.399536 -295.112948)
		(width 0.14732)
		(layer "In2.Cu")
		(net "P5E_CPU0_PE3_TX_DP<4>")
	)
	(segment
		(start 379.093476 -290.115752)
		(end 379.051312 -290.073588)
		(width 0.0889)
		(layer "In2.Cu")
		(net "P5E_CPU0_PE3_TX_DP<4>")
	)
	(segment
		(start 378.77496 -287.617154)
		(end 378.771658 -287.615376)
		(width 0.0889)
		(layer "In2.Cu")
		(net "P5E_CPU0_PE3_TX_DP<4>")
	)
	(segment
		(start 407.03373 -406.001982)
		(end 407.21915 -404.118572)
		(width 0.14732)
		(layer "In2.Cu")
		(net "P5E_CPU0_PE3_TX_DP<4>")
	)
	(arc
		(start 378.298964 -286.799782)
		(mid 378.164031 -286.666428)
		(end 378.111766 -286.48406)
		(width 0.0889)
		(layer "In2.Cu")
		(net "P5E_CPU0_PE3_TX_DP<4>")
	)
	(arc
		(start 379.051312 -289.64636)
		(mid 379.126383 -289.530618)
		(end 379.235716 -289.446462)
		(width 0.0889)
		(layer "In2.Cu")
		(net "P5E_CPU0_PE3_TX_DP<4>")
	)
	(arc
		(start 378.111766 -286.4612)
		(mid 378.053472 -286.224557)
		(end 377.900946 -286.03448)
		(width 0.0889)
		(layer "In2.Cu")
		(net "P5E_CPU0_PE3_TX_DP<4>")
	)
	(arc
		(start 377.900946 -286.03448)
		(mid 377.892498 -286.027923)
		(end 377.883928 -286.021526)
		(width 0.0889)
		(layer "In2.Cu")
		(net "P5E_CPU0_PE3_TX_DP<4>")
	)
	(arc
		(start 379.230128 -288.422334)
		(mid 379.099214 -288.285974)
		(end 379.051566 -288.103056)
		(width 0.0889)
		(layer "In2.Cu")
		(net "P5E_CPU0_PE3_TX_DP<4>")
	)
	(arc
		(start 378.759974 -287.608518)
		(mid 378.62906 -287.472158)
		(end 378.581412 -287.28924)
		(width 0.0889)
		(layer "In2.Cu")
		(net "P5E_CPU0_PE3_TX_DP<4>")
	)
	(arc
		(start 379.521466 -288.898584)
		(mid 379.441304 -288.626395)
		(end 379.239018 -288.427414)
		(width 0.0889)
		(layer "In2.Cu")
		(net "P5E_CPU0_PE3_TX_DP<4>")
	)
	(arc
		(start 379.051566 -288.103056)
		(mid 378.977575 -287.82349)
		(end 378.77496 -287.617154)
		(width 0.0889)
		(layer "In2.Cu")
		(net "P5E_CPU0_PE3_TX_DP<4>")
	)
	(arc
		(start 379.235716 -289.446462)
		(mid 379.410017 -289.307532)
		(end 379.521466 -289.114484)
		(width 0.0889)
		(layer "In2.Cu")
		(net "P5E_CPU0_PE3_TX_DP<4>")
	)
	(arc
		(start 378.581412 -287.279334)
		(mid 378.503301 -287.002385)
		(end 378.298964 -286.799782)
		(width 0.0889)
		(layer "In2.Cu")
		(net "P5E_CPU0_PE3_TX_DP<4>")
	)
	(segment
		(start 410.39161 -407.00452)
		(end 410.092652 -407.303478)
		(width 0.13208)
		(layer "F.Cu")
		(net "P5E_CPU0_PE3_TX_DP<3>")
	)
	(segment
		(start 378.956316 -285.6611)
		(end 378.956062 -285.661354)
		(width 0.13208)
		(layer "F.Cu")
		(net "P5E_CPU0_PE3_TX_DP<3>")
	)
	(segment
		(start 410.092652 -407.303478)
		(end 410.092652 -407.926286)
		(width 0.13208)
		(layer "F.Cu")
		(net "P5E_CPU0_PE3_TX_DP<3>")
	)
	(segment
		(start 378.956316 -285.125414)
		(end 378.956316 -285.6611)
		(width 0.13208)
		(layer "F.Cu")
		(net "P5E_CPU0_PE3_TX_DP<3>")
	)
	(segment
		(start 410.092652 -407.926286)
		(end 410.41701 -408.250644)
		(width 0.13208)
		(layer "F.Cu")
		(net "P5E_CPU0_PE3_TX_DP<3>")
	)
	(segment
		(start 380.175008 -289.446462)
		(end 380.175516 -289.446462)
		(width 0.0889)
		(layer "In2.Cu")
		(net "P5E_CPU0_PE3_TX_DP<3>")
	)
	(segment
		(start 410.28239 -404.118572)
		(end 410.28239 -400.489674)
		(width 0.14732)
		(layer "In2.Cu")
		(net "P5E_CPU0_PE3_TX_DP<3>")
	)
	(segment
		(start 380.033276 -290.13785)
		(end 380.033276 -290.115752)
		(width 0.0889)
		(layer "In2.Cu")
		(net "P5E_CPU0_PE3_TX_DP<3>")
	)
	(segment
		(start 378.721366 -285.369508)
		(end 378.799598 -285.390336)
		(width 0.0889)
		(layer "In2.Cu")
		(net "P5E_CPU0_PE3_TX_DP<3>")
	)
	(segment
		(start 380.033276 -290.115752)
		(end 379.991112 -290.073588)
		(width 0.0889)
		(layer "In2.Cu")
		(net "P5E_CPU0_PE3_TX_DP<3>")
	)
	(segment
		(start 409.911296 -398.015206)
		(end 409.764484 -397.917924)
		(width 0.14732)
		(layer "In2.Cu")
		(net "P5E_CPU0_PE3_TX_DP<3>")
	)
	(segment
		(start 410.09697 -406.001982)
		(end 410.28239 -404.118572)
		(width 0.14732)
		(layer "In2.Cu")
		(net "P5E_CPU0_PE3_TX_DP<3>")
	)
	(segment
		(start 379.239018 -286.799782)
		(end 379.238002 -286.799274)
		(width 0.0889)
		(layer "In2.Cu")
		(net "P5E_CPU0_PE3_TX_DP<3>")
	)
	(segment
		(start 409.764484 -397.917924)
		(end 409.678378 -397.48968)
		(width 0.14732)
		(layer "In2.Cu")
		(net "P5E_CPU0_PE3_TX_DP<3>")
	)
	(segment
		(start 410.28239 -400.489674)
		(end 409.90012 -398.590516)
		(width 0.14732)
		(layer "In2.Cu")
		(net "P5E_CPU0_PE3_TX_DP<3>")
	)
	(segment
		(start 379.710696 -287.614868)
		(end 379.699774 -287.608518)
		(width 0.0889)
		(layer "In2.Cu")
		(net "P5E_CPU0_PE3_TX_DP<3>")
	)
	(segment
		(start 409.997656 -398.443958)
		(end 409.911296 -398.015206)
		(width 0.14732)
		(layer "In2.Cu")
		(net "P5E_CPU0_PE3_TX_DP<3>")
	)
	(segment
		(start 380.368048 -291.875464)
		(end 380.033276 -291.540692)
		(width 0.14732)
		(layer "In2.Cu")
		(net "P5E_CPU0_PE3_TX_DP<3>")
	)
	(segment
		(start 379.051566 -286.475424)
		(end 379.051566 -286.467804)
		(width 0.0889)
		(layer "In2.Cu")
		(net "P5E_CPU0_PE3_TX_DP<3>")
	)
	(segment
		(start 409.689554 -396.914624)
		(end 409.542742 -396.817088)
		(width 0.14732)
		(layer "In2.Cu")
		(net "P5E_CPU0_PE3_TX_DP<3>")
	)
	(segment
		(start 378.768102 -285.985204)
		(end 378.759974 -285.980632)
		(width 0.0889)
		(layer "In2.Cu")
		(net "P5E_CPU0_PE3_TX_DP<3>")
	)
	(segment
		(start 410.39161 -407.00452)
		(end 410.09697 -406.70988)
		(width 0.14732)
		(layer "In2.Cu")
		(net "P5E_CPU0_PE3_TX_DP<3>")
	)
	(segment
		(start 379.991112 -290.073588)
		(end 379.991112 -289.644582)
		(width 0.0889)
		(layer "In2.Cu")
		(net "P5E_CPU0_PE3_TX_DP<3>")
	)
	(segment
		(start 380.175008 -289.446208)
		(end 380.175008 -289.446462)
		(width 0.0889)
		(layer "In2.Cu")
		(net "P5E_CPU0_PE3_TX_DP<3>")
	)
	(segment
		(start 378.799598 -285.390336)
		(end 378.956062 -285.661354)
		(width 0.0889)
		(layer "In2.Cu")
		(net "P5E_CPU0_PE3_TX_DP<3>")
	)
	(segment
		(start 409.542742 -396.817088)
		(end 409.542996 -396.816326)
		(width 0.14732)
		(layer "In2.Cu")
		(net "P5E_CPU0_PE3_TX_DP<3>")
	)
	(segment
		(start 409.542996 -396.816326)
		(end 404.138384 -369.968526)
		(width 0.14732)
		(layer "In2.Cu")
		(net "P5E_CPU0_PE3_TX_DP<3>")
	)
	(segment
		(start 404.267416 -334.814418)
		(end 403.90826 -333.084932)
		(width 0.14732)
		(layer "In2.Cu")
		(net "P5E_CPU0_PE3_TX_DP<3>")
	)
	(segment
		(start 379.238002 -286.799274)
		(end 379.230128 -286.794702)
		(width 0.0889)
		(layer "In2.Cu")
		(net "P5E_CPU0_PE3_TX_DP<3>")
	)
	(segment
		(start 403.90826 -333.084932)
		(end 402.313648 -324.043294)
		(width 0.14732)
		(layer "In2.Cu")
		(net "P5E_CPU0_PE3_TX_DP<3>")
	)
	(segment
		(start 387.5786 -305.118516)
		(end 386.067046 -296.642028)
		(width 0.14732)
		(layer "In2.Cu")
		(net "P5E_CPU0_PE3_TX_DP<3>")
	)
	(segment
		(start 379.521212 -287.28924)
		(end 379.521212 -287.273746)
		(width 0.0889)
		(layer "In2.Cu")
		(net "P5E_CPU0_PE3_TX_DP<3>")
	)
	(segment
		(start 403.873208 -367.991136)
		(end 404.267416 -334.814418)
		(width 0.14732)
		(layer "In2.Cu")
		(net "P5E_CPU0_PE3_TX_DP<3>")
	)
	(segment
		(start 410.09697 -406.70988)
		(end 410.09697 -406.001982)
		(width 0.14732)
		(layer "In2.Cu")
		(net "P5E_CPU0_PE3_TX_DP<3>")
	)
	(segment
		(start 386.067046 -296.642028)
		(end 385.208526 -294.569134)
		(width 0.14732)
		(layer "In2.Cu")
		(net "P5E_CPU0_PE3_TX_DP<3>")
	)
	(segment
		(start 379.71476 -287.617154)
		(end 379.711458 -287.615376)
		(width 0.0889)
		(layer "In2.Cu")
		(net "P5E_CPU0_PE3_TX_DP<3>")
	)
	(segment
		(start 379.711458 -287.615376)
		(end 379.710696 -287.614868)
		(width 0.0889)
		(layer "In2.Cu")
		(net "P5E_CPU0_PE3_TX_DP<3>")
	)
	(segment
		(start 385.208526 -294.569134)
		(end 384.033014 -293.393622)
		(width 0.14732)
		(layer "In2.Cu")
		(net "P5E_CPU0_PE3_TX_DP<3>")
	)
	(segment
		(start 404.138384 -369.968526)
		(end 403.873208 -367.991136)
		(width 0.14732)
		(layer "In2.Cu")
		(net "P5E_CPU0_PE3_TX_DP<3>")
	)
	(segment
		(start 409.775914 -397.343122)
		(end 409.689554 -396.914624)
		(width 0.14732)
		(layer "In2.Cu")
		(net "P5E_CPU0_PE3_TX_DP<3>")
	)
	(segment
		(start 384.033014 -293.393622)
		(end 380.368048 -291.875464)
		(width 0.14732)
		(layer "In2.Cu")
		(net "P5E_CPU0_PE3_TX_DP<3>")
	)
	(segment
		(start 409.90012 -398.590516)
		(end 409.997656 -398.443958)
		(width 0.14732)
		(layer "In2.Cu")
		(net "P5E_CPU0_PE3_TX_DP<3>")
	)
	(segment
		(start 380.461266 -289.114484)
		(end 380.461266 -288.898584)
		(width 0.0889)
		(layer "In2.Cu")
		(net "P5E_CPU0_PE3_TX_DP<3>")
	)
	(segment
		(start 380.033276 -291.540692)
		(end 380.033276 -290.13785)
		(width 0.14732)
		(layer "In2.Cu")
		(net "P5E_CPU0_PE3_TX_DP<3>")
	)
	(segment
		(start 378.768864 -285.985712)
		(end 378.768102 -285.985204)
		(width 0.0889)
		(layer "In2.Cu")
		(net "P5E_CPU0_PE3_TX_DP<3>")
	)
	(segment
		(start 380.178818 -288.427414)
		(end 380.169928 -288.422334)
		(width 0.0889)
		(layer "In2.Cu")
		(net "P5E_CPU0_PE3_TX_DP<3>")
	)
	(segment
		(start 402.313648 -324.043294)
		(end 387.5786 -305.118516)
		(width 0.14732)
		(layer "In2.Cu")
		(net "P5E_CPU0_PE3_TX_DP<3>")
	)
	(segment
		(start 409.678378 -397.48968)
		(end 409.775914 -397.343122)
		(width 0.14732)
		(layer "In2.Cu")
		(net "P5E_CPU0_PE3_TX_DP<3>")
	)
	(arc
		(start 379.699774 -287.608518)
		(mid 379.56886 -287.472158)
		(end 379.521212 -287.28924)
		(width 0.0889)
		(layer "In2.Cu")
		(net "P5E_CPU0_PE3_TX_DP<3>")
	)
	(arc
		(start 379.051566 -286.467804)
		(mid 378.973937 -286.189391)
		(end 378.768864 -285.985712)
		(width 0.0889)
		(layer "In2.Cu")
		(net "P5E_CPU0_PE3_TX_DP<3>")
	)
	(arc
		(start 379.991366 -288.103056)
		(mid 379.917375 -287.82349)
		(end 379.71476 -287.617154)
		(width 0.0889)
		(layer "In2.Cu")
		(net "P5E_CPU0_PE3_TX_DP<3>")
	)
	(arc
		(start 380.169928 -288.422334)
		(mid 380.039014 -288.285974)
		(end 379.991366 -288.103056)
		(width 0.0889)
		(layer "In2.Cu")
		(net "P5E_CPU0_PE3_TX_DP<3>")
	)
	(arc
		(start 379.521212 -287.273746)
		(mid 379.441842 -287.000012)
		(end 379.239018 -286.799782)
		(width 0.0889)
		(layer "In2.Cu")
		(net "P5E_CPU0_PE3_TX_DP<3>")
	)
	(arc
		(start 378.759974 -285.980632)
		(mid 378.582126 -285.68504)
		(end 378.721366 -285.369508)
		(width 0.0889)
		(layer "In2.Cu")
		(net "P5E_CPU0_PE3_TX_DP<3>")
	)
	(arc
		(start 379.230128 -286.794702)
		(mid 379.099214 -286.658342)
		(end 379.051566 -286.475424)
		(width 0.0889)
		(layer "In2.Cu")
		(net "P5E_CPU0_PE3_TX_DP<3>")
	)
	(arc
		(start 380.175516 -289.446462)
		(mid 380.349817 -289.307532)
		(end 380.461266 -289.114484)
		(width 0.0889)
		(layer "In2.Cu")
		(net "P5E_CPU0_PE3_TX_DP<3>")
	)
	(arc
		(start 379.991112 -289.644582)
		(mid 380.06618 -289.529757)
		(end 380.175008 -289.446208)
		(width 0.0889)
		(layer "In2.Cu")
		(net "P5E_CPU0_PE3_TX_DP<3>")
	)
	(arc
		(start 380.461266 -288.898584)
		(mid 380.381104 -288.626395)
		(end 380.178818 -288.427414)
		(width 0.0889)
		(layer "In2.Cu")
		(net "P5E_CPU0_PE3_TX_DP<3>")
	)
	(segment
		(start 379.896116 -285.6611)
		(end 379.895862 -285.661354)
		(width 0.13208)
		(layer "F.Cu")
		(net "P5E_CPU0_PE3_TX_DP<2>")
	)
	(segment
		(start 413.155892 -407.303478)
		(end 413.155892 -407.926286)
		(width 0.13208)
		(layer "F.Cu")
		(net "P5E_CPU0_PE3_TX_DP<2>")
	)
	(segment
		(start 379.896116 -285.125414)
		(end 379.896116 -285.6611)
		(width 0.13208)
		(layer "F.Cu")
		(net "P5E_CPU0_PE3_TX_DP<2>")
	)
	(segment
		(start 413.155892 -407.926286)
		(end 413.48025 -408.250644)
		(width 0.13208)
		(layer "F.Cu")
		(net "P5E_CPU0_PE3_TX_DP<2>")
	)
	(segment
		(start 413.45485 -407.00452)
		(end 413.155892 -407.303478)
		(width 0.13208)
		(layer "F.Cu")
		(net "P5E_CPU0_PE3_TX_DP<2>")
	)
	(segment
		(start 381.114808 -289.446462)
		(end 381.115316 -289.446462)
		(width 0.0889)
		(layer "In2.Cu")
		(net "P5E_CPU0_PE3_TX_DP<2>")
	)
	(segment
		(start 384.706114 -292.555168)
		(end 381.41275 -291.190934)
		(width 0.14732)
		(layer "In2.Cu")
		(net "P5E_CPU0_PE3_TX_DP<2>")
	)
	(segment
		(start 413.34563 -400.230848)
		(end 405.11222 -369.72367)
		(width 0.14732)
		(layer "In2.Cu")
		(net "P5E_CPU0_PE3_TX_DP<2>")
	)
	(segment
		(start 413.34563 -404.118572)
		(end 413.34563 -400.230848)
		(width 0.14732)
		(layer "In2.Cu")
		(net "P5E_CPU0_PE3_TX_DP<2>")
	)
	(segment
		(start 388.505192 -304.764948)
		(end 387.015228 -296.413428)
		(width 0.14732)
		(layer "In2.Cu")
		(net "P5E_CPU0_PE3_TX_DP<2>")
	)
	(segment
		(start 413.16021 -406.70988)
		(end 413.16021 -406.001982)
		(width 0.14732)
		(layer "In2.Cu")
		(net "P5E_CPU0_PE3_TX_DP<2>")
	)
	(segment
		(start 379.763528 -286.021526)
		(end 379.739398 -285.932372)
		(width 0.0889)
		(layer "In2.Cu")
		(net "P5E_CPU0_PE3_TX_DP<2>")
	)
	(segment
		(start 380.973076 -290.75126)
		(end 380.973076 -290.13785)
		(width 0.14732)
		(layer "In2.Cu")
		(net "P5E_CPU0_PE3_TX_DP<2>")
	)
	(segment
		(start 385.91998 -293.769034)
		(end 384.706114 -292.555168)
		(width 0.14732)
		(layer "In2.Cu")
		(net "P5E_CPU0_PE3_TX_DP<2>")
	)
	(segment
		(start 404.856442 -333.067152)
		(end 403.191726 -323.627496)
		(width 0.14732)
		(layer "In2.Cu")
		(net "P5E_CPU0_PE3_TX_DP<2>")
	)
	(segment
		(start 380.930912 -290.073588)
		(end 380.930912 -289.645344)
		(width 0.0889)
		(layer "In2.Cu")
		(net "P5E_CPU0_PE3_TX_DP<2>")
	)
	(segment
		(start 379.991366 -286.48406)
		(end 379.991366 -286.4612)
		(width 0.0889)
		(layer "In2.Cu")
		(net "P5E_CPU0_PE3_TX_DP<2>")
	)
	(segment
		(start 380.973076 -290.115752)
		(end 380.930912 -290.073588)
		(width 0.0889)
		(layer "In2.Cu")
		(net "P5E_CPU0_PE3_TX_DP<2>")
	)
	(segment
		(start 381.117094 -288.426652)
		(end 381.116078 -288.426144)
		(width 0.0889)
		(layer "In2.Cu")
		(net "P5E_CPU0_PE3_TX_DP<2>")
	)
	(segment
		(start 403.191726 -323.627496)
		(end 388.505192 -304.764948)
		(width 0.14732)
		(layer "In2.Cu")
		(net "P5E_CPU0_PE3_TX_DP<2>")
	)
	(segment
		(start 413.16021 -406.001982)
		(end 413.34563 -404.118572)
		(width 0.14732)
		(layer "In2.Cu")
		(net "P5E_CPU0_PE3_TX_DP<2>")
	)
	(segment
		(start 380.461012 -287.28924)
		(end 380.461012 -287.279334)
		(width 0.0889)
		(layer "In2.Cu")
		(net "P5E_CPU0_PE3_TX_DP<2>")
	)
	(segment
		(start 381.41275 -291.190934)
		(end 380.973076 -290.75126)
		(width 0.14732)
		(layer "In2.Cu")
		(net "P5E_CPU0_PE3_TX_DP<2>")
	)
	(segment
		(start 404.89886 -367.923064)
		(end 405.293322 -334.849216)
		(width 0.14732)
		(layer "In2.Cu")
		(net "P5E_CPU0_PE3_TX_DP<2>")
	)
	(segment
		(start 380.973076 -290.13785)
		(end 380.973076 -290.115752)
		(width 0.0889)
		(layer "In2.Cu")
		(net "P5E_CPU0_PE3_TX_DP<2>")
	)
	(segment
		(start 379.739398 -285.932372)
		(end 379.895862 -285.661354)
		(width 0.0889)
		(layer "In2.Cu")
		(net "P5E_CPU0_PE3_TX_DP<2>")
	)
	(segment
		(start 405.293322 -334.849216)
		(end 404.856442 -333.067152)
		(width 0.14732)
		(layer "In2.Cu")
		(net "P5E_CPU0_PE3_TX_DP<2>")
	)
	(segment
		(start 380.65456 -287.617154)
		(end 380.639574 -287.608518)
		(width 0.0889)
		(layer "In2.Cu")
		(net "P5E_CPU0_PE3_TX_DP<2>")
	)
	(segment
		(start 381.116078 -288.426144)
		(end 381.109728 -288.422334)
		(width 0.0889)
		(layer "In2.Cu")
		(net "P5E_CPU0_PE3_TX_DP<2>")
	)
	(segment
		(start 405.11222 -369.72367)
		(end 404.89886 -367.923064)
		(width 0.14732)
		(layer "In2.Cu")
		(net "P5E_CPU0_PE3_TX_DP<2>")
	)
	(segment
		(start 387.015228 -296.413428)
		(end 385.91998 -293.769034)
		(width 0.14732)
		(layer "In2.Cu")
		(net "P5E_CPU0_PE3_TX_DP<2>")
	)
	(segment
		(start 381.395732 -289.021774)
		(end 381.40005 -288.957512)
		(width 0.0889)
		(layer "In2.Cu")
		(net "P5E_CPU0_PE3_TX_DP<2>")
	)
	(segment
		(start 413.45485 -407.00452)
		(end 413.16021 -406.70988)
		(width 0.14732)
		(layer "In2.Cu")
		(net "P5E_CPU0_PE3_TX_DP<2>")
	)
	(arc
		(start 380.461012 -287.279334)
		(mid 380.382901 -287.002385)
		(end 380.178564 -286.799782)
		(width 0.0889)
		(layer "In2.Cu")
		(net "P5E_CPU0_PE3_TX_DP<2>")
	)
	(arc
		(start 379.991366 -286.4612)
		(mid 379.933072 -286.224557)
		(end 379.780546 -286.03448)
		(width 0.0889)
		(layer "In2.Cu")
		(net "P5E_CPU0_PE3_TX_DP<2>")
	)
	(arc
		(start 381.115316 -289.446462)
		(mid 381.142529 -289.431157)
		(end 381.16891 -289.414458)
		(width 0.0889)
		(layer "In2.Cu")
		(net "P5E_CPU0_PE3_TX_DP<2>")
	)
	(arc
		(start 381.40005 -288.957512)
		(mid 381.334577 -288.651558)
		(end 381.117094 -288.426652)
		(width 0.0889)
		(layer "In2.Cu")
		(net "P5E_CPU0_PE3_TX_DP<2>")
	)
	(arc
		(start 381.16891 -289.414458)
		(mid 381.327954 -289.244472)
		(end 381.395732 -289.021774)
		(width 0.0889)
		(layer "In2.Cu")
		(net "P5E_CPU0_PE3_TX_DP<2>")
	)
	(arc
		(start 380.930912 -289.645344)
		(mid 381.005852 -289.530167)
		(end 381.114808 -289.446462)
		(width 0.0889)
		(layer "In2.Cu")
		(net "P5E_CPU0_PE3_TX_DP<2>")
	)
	(arc
		(start 380.639574 -287.608518)
		(mid 380.50866 -287.472158)
		(end 380.461012 -287.28924)
		(width 0.0889)
		(layer "In2.Cu")
		(net "P5E_CPU0_PE3_TX_DP<2>")
	)
	(arc
		(start 380.178564 -286.799782)
		(mid 380.043631 -286.666428)
		(end 379.991366 -286.48406)
		(width 0.0889)
		(layer "In2.Cu")
		(net "P5E_CPU0_PE3_TX_DP<2>")
	)
	(arc
		(start 380.931166 -288.103056)
		(mid 380.857175 -287.82349)
		(end 380.65456 -287.617154)
		(width 0.0889)
		(layer "In2.Cu")
		(net "P5E_CPU0_PE3_TX_DP<2>")
	)
	(arc
		(start 381.109728 -288.422334)
		(mid 380.978814 -288.285974)
		(end 380.931166 -288.103056)
		(width 0.0889)
		(layer "In2.Cu")
		(net "P5E_CPU0_PE3_TX_DP<2>")
	)
	(arc
		(start 379.780546 -286.03448)
		(mid 379.772098 -286.027923)
		(end 379.763528 -286.021526)
		(width 0.0889)
		(layer "In2.Cu")
		(net "P5E_CPU0_PE3_TX_DP<2>")
	)
	(segment
		(start 416.219132 -407.926286)
		(end 416.54349 -408.250644)
		(width 0.13208)
		(layer "F.Cu")
		(net "P5E_CPU0_PE3_TX_DP<1>")
	)
	(segment
		(start 416.51809 -407.00452)
		(end 416.219132 -407.303478)
		(width 0.13208)
		(layer "F.Cu")
		(net "P5E_CPU0_PE3_TX_DP<1>")
	)
	(segment
		(start 380.835916 -285.125414)
		(end 380.835916 -285.6611)
		(width 0.13208)
		(layer "F.Cu")
		(net "P5E_CPU0_PE3_TX_DP<1>")
	)
	(segment
		(start 380.835916 -285.6611)
		(end 380.835662 -285.661354)
		(width 0.13208)
		(layer "F.Cu")
		(net "P5E_CPU0_PE3_TX_DP<1>")
	)
	(segment
		(start 416.219132 -407.303478)
		(end 416.219132 -407.926286)
		(width 0.13208)
		(layer "F.Cu")
		(net "P5E_CPU0_PE3_TX_DP<1>")
	)
	(segment
		(start 381.586232 -287.612328)
		(end 381.58293 -287.61055)
		(width 0.0889)
		(layer "In2.Cu")
		(net "P5E_CPU0_PE3_TX_DP<1>")
	)
	(segment
		(start 380.931166 -286.475424)
		(end 380.931166 -286.467804)
		(width 0.0889)
		(layer "In2.Cu")
		(net "P5E_CPU0_PE3_TX_DP<1>")
	)
	(segment
		(start 416.40887 -400.401536)
		(end 415.830512 -398.671796)
		(width 0.14732)
		(layer "In2.Cu")
		(net "P5E_CPU0_PE3_TX_DP<1>")
	)
	(segment
		(start 382.810258 -289.552126)
		(end 382.536192 -289.27806)
		(width 0.0889)
		(layer "In2.Cu")
		(net "P5E_CPU0_PE3_TX_DP<1>")
	)
	(segment
		(start 416.51809 -407.00452)
		(end 416.22345 -406.70988)
		(width 0.14732)
		(layer "In2.Cu")
		(net "P5E_CPU0_PE3_TX_DP<1>")
	)
	(segment
		(start 405.89835 -367.871502)
		(end 406.270968 -334.793082)
		(width 0.14732)
		(layer "In2.Cu")
		(net "P5E_CPU0_PE3_TX_DP<1>")
	)
	(segment
		(start 416.22345 -406.001982)
		(end 416.40887 -404.118572)
		(width 0.14732)
		(layer "In2.Cu")
		(net "P5E_CPU0_PE3_TX_DP<1>")
	)
	(segment
		(start 416.40887 -404.118572)
		(end 416.40887 -400.401536)
		(width 0.14732)
		(layer "In2.Cu")
		(net "P5E_CPU0_PE3_TX_DP<1>")
	)
	(segment
		(start 380.679198 -285.390336)
		(end 380.835662 -285.661354)
		(width 0.0889)
		(layer "In2.Cu")
		(net "P5E_CPU0_PE3_TX_DP<1>")
	)
	(segment
		(start 381.870966 -288.111692)
		(end 381.870966 -288.103056)
		(width 0.0889)
		(layer "In2.Cu")
		(net "P5E_CPU0_PE3_TX_DP<1>")
	)
	(segment
		(start 382.340866 -289.077654)
		(end 382.340866 -288.917634)
		(width 0.0889)
		(layer "In2.Cu")
		(net "P5E_CPU0_PE3_TX_DP<1>")
	)
	(segment
		(start 406.270968 -334.793082)
		(end 405.789638 -332.665324)
		(width 0.14732)
		(layer "In2.Cu")
		(net "P5E_CPU0_PE3_TX_DP<1>")
	)
	(segment
		(start 382.973326 -290.18865)
		(end 382.913382 -290.18865)
		(width 0.0889)
		(layer "In2.Cu")
		(net "P5E_CPU0_PE3_TX_DP<1>")
	)
	(segment
		(start 381.58293 -287.61055)
		(end 381.581406 -287.609534)
		(width 0.0889)
		(layer "In2.Cu")
		(net "P5E_CPU0_PE3_TX_DP<1>")
	)
	(segment
		(start 389.398002 -304.392076)
		(end 387.948424 -296.16908)
		(width 0.14732)
		(layer "In2.Cu")
		(net "P5E_CPU0_PE3_TX_DP<1>")
	)
	(segment
		(start 380.647702 -285.985204)
		(end 380.639574 -285.980632)
		(width 0.0889)
		(layer "In2.Cu")
		(net "P5E_CPU0_PE3_TX_DP<1>")
	)
	(segment
		(start 387.948424 -296.16908)
		(end 386.678678 -293.103046)
		(width 0.14732)
		(layer "In2.Cu")
		(net "P5E_CPU0_PE3_TX_DP<1>")
	)
	(segment
		(start 415.830512 -398.671796)
		(end 415.908998 -398.514316)
		(width 0.14732)
		(layer "In2.Cu")
		(net "P5E_CPU0_PE3_TX_DP<1>")
	)
	(segment
		(start 415.612834 -398.021048)
		(end 406.155652 -369.74272)
		(width 0.14732)
		(layer "In2.Cu")
		(net "P5E_CPU0_PE3_TX_DP<1>")
	)
	(segment
		(start 382.913382 -290.18865)
		(end 382.810258 -290.085526)
		(width 0.0889)
		(layer "In2.Cu")
		(net "P5E_CPU0_PE3_TX_DP<1>")
	)
	(segment
		(start 382.810258 -290.085526)
		(end 382.810258 -289.552126)
		(width 0.0889)
		(layer "In2.Cu")
		(net "P5E_CPU0_PE3_TX_DP<1>")
	)
	(segment
		(start 382.981454 -290.196778)
		(end 382.973326 -290.18865)
		(width 0.0889)
		(layer "In2.Cu")
		(net "P5E_CPU0_PE3_TX_DP<1>")
	)
	(segment
		(start 386.678678 -293.103046)
		(end 385.358386 -291.782754)
		(width 0.14732)
		(layer "In2.Cu")
		(net "P5E_CPU0_PE3_TX_DP<1>")
	)
	(segment
		(start 382.340866 -288.917634)
		(end 382.34112 -288.90341)
		(width 0.0889)
		(layer "In2.Cu")
		(net "P5E_CPU0_PE3_TX_DP<1>")
	)
	(segment
		(start 405.789638 -332.665324)
		(end 404.143464 -323.33057)
		(width 0.14732)
		(layer "In2.Cu")
		(net "P5E_CPU0_PE3_TX_DP<1>")
	)
	(segment
		(start 384.008122 -291.223446)
		(end 382.981454 -290.196778)
		(width 0.14732)
		(layer "In2.Cu")
		(net "P5E_CPU0_PE3_TX_DP<1>")
	)
	(segment
		(start 415.770568 -398.099788)
		(end 415.612834 -398.021048)
		(width 0.14732)
		(layer "In2.Cu")
		(net "P5E_CPU0_PE3_TX_DP<1>")
	)
	(segment
		(start 381.581406 -287.609534)
		(end 381.579628 -287.608518)
		(width 0.0889)
		(layer "In2.Cu")
		(net "P5E_CPU0_PE3_TX_DP<1>")
	)
	(segment
		(start 380.648464 -285.985712)
		(end 380.647702 -285.985204)
		(width 0.0889)
		(layer "In2.Cu")
		(net "P5E_CPU0_PE3_TX_DP<1>")
	)
	(segment
		(start 385.358386 -291.782754)
		(end 384.008122 -291.223446)
		(width 0.14732)
		(layer "In2.Cu")
		(net "P5E_CPU0_PE3_TX_DP<1>")
	)
	(segment
		(start 381.124714 -286.803338)
		(end 381.109728 -286.794702)
		(width 0.0889)
		(layer "In2.Cu")
		(net "P5E_CPU0_PE3_TX_DP<1>")
	)
	(segment
		(start 404.143464 -323.33057)
		(end 389.398002 -304.392076)
		(width 0.14732)
		(layer "In2.Cu")
		(net "P5E_CPU0_PE3_TX_DP<1>")
	)
	(segment
		(start 382.536192 -289.27806)
		(end 382.525016 -289.27806)
		(width 0.0889)
		(layer "In2.Cu")
		(net "P5E_CPU0_PE3_TX_DP<1>")
	)
	(segment
		(start 406.155652 -369.74272)
		(end 405.89835 -367.871502)
		(width 0.14732)
		(layer "In2.Cu")
		(net "P5E_CPU0_PE3_TX_DP<1>")
	)
	(segment
		(start 416.22345 -406.70988)
		(end 416.22345 -406.001982)
		(width 0.14732)
		(layer "In2.Cu")
		(net "P5E_CPU0_PE3_TX_DP<1>")
	)
	(segment
		(start 380.600966 -285.369508)
		(end 380.679198 -285.390336)
		(width 0.0889)
		(layer "In2.Cu")
		(net "P5E_CPU0_PE3_TX_DP<1>")
	)
	(segment
		(start 415.908998 -398.514316)
		(end 415.770568 -398.099788)
		(width 0.14732)
		(layer "In2.Cu")
		(net "P5E_CPU0_PE3_TX_DP<1>")
	)
	(arc
		(start 381.579628 -287.608518)
		(mid 381.448714 -287.472158)
		(end 381.401066 -287.28924)
		(width 0.0889)
		(layer "In2.Cu")
		(net "P5E_CPU0_PE3_TX_DP<1>")
	)
	(arc
		(start 381.870966 -288.103056)
		(mid 381.79462 -287.819392)
		(end 381.586232 -287.612328)
		(width 0.0889)
		(layer "In2.Cu")
		(net "P5E_CPU0_PE3_TX_DP<1>")
	)
	(arc
		(start 382.34112 -288.90341)
		(mid 382.261871 -288.628435)
		(end 382.058164 -288.427414)
		(width 0.0889)
		(layer "In2.Cu")
		(net "P5E_CPU0_PE3_TX_DP<1>")
	)
	(arc
		(start 382.525016 -289.27806)
		(mid 382.415746 -289.193667)
		(end 382.340866 -289.077654)
		(width 0.0889)
		(layer "In2.Cu")
		(net "P5E_CPU0_PE3_TX_DP<1>")
	)
	(arc
		(start 382.058164 -288.427414)
		(mid 381.923231 -288.29406)
		(end 381.870966 -288.111692)
		(width 0.0889)
		(layer "In2.Cu")
		(net "P5E_CPU0_PE3_TX_DP<1>")
	)
	(arc
		(start 380.931166 -286.467804)
		(mid 380.853537 -286.189391)
		(end 380.648464 -285.985712)
		(width 0.0889)
		(layer "In2.Cu")
		(net "P5E_CPU0_PE3_TX_DP<1>")
	)
	(arc
		(start 381.401066 -287.28924)
		(mid 381.32715 -287.009738)
		(end 381.124714 -286.803338)
		(width 0.0889)
		(layer "In2.Cu")
		(net "P5E_CPU0_PE3_TX_DP<1>")
	)
	(arc
		(start 380.639574 -285.980632)
		(mid 380.461726 -285.68504)
		(end 380.600966 -285.369508)
		(width 0.0889)
		(layer "In2.Cu")
		(net "P5E_CPU0_PE3_TX_DP<1>")
	)
	(arc
		(start 381.109728 -286.794702)
		(mid 380.978814 -286.658342)
		(end 380.931166 -286.475424)
		(width 0.0889)
		(layer "In2.Cu")
		(net "P5E_CPU0_PE3_TX_DP<1>")
	)
	(segment
		(start 373.333772 -407.926286)
		(end 373.65813 -408.250644)
		(width 0.13208)
		(layer "F.Cu")
		(net "P5E_CPU0_PE3_TX_DP<15>")
	)
	(segment
		(start 373.333772 -407.303478)
		(end 373.333772 -407.926286)
		(width 0.13208)
		(layer "F.Cu")
		(net "P5E_CPU0_PE3_TX_DP<15>")
	)
	(segment
		(start 373.63273 -407.00452)
		(end 373.333772 -407.303478)
		(width 0.13208)
		(layer "F.Cu")
		(net "P5E_CPU0_PE3_TX_DP<15>")
	)
	(segment
		(start 367.678716 -285.125414)
		(end 367.678462 -285.661354)
		(width 0.13208)
		(layer "F.Cu")
		(net "P5E_CPU0_PE3_TX_DP<15>")
	)
	(segment
		(start 368.243866 -287.297876)
		(end 368.243866 -287.279334)
		(width 0.0889)
		(layer "In2.Cu")
		(net "P5E_CPU0_PE3_TX_DP<15>")
	)
	(segment
		(start 391.631424 -329.423268)
		(end 367.834418 -299.000418)
		(width 0.14732)
		(layer "In2.Cu")
		(net "P5E_CPU0_PE3_TX_DP<15>")
	)
	(segment
		(start 374.766332 -396.90929)
		(end 374.692164 -396.749524)
		(width 0.14732)
		(layer "In2.Cu")
		(net "P5E_CPU0_PE3_TX_DP<15>")
	)
	(segment
		(start 374.456452 -397.393922)
		(end 374.616472 -397.319754)
		(width 0.14732)
		(layer "In2.Cu")
		(net "P5E_CPU0_PE3_TX_DP<15>")
	)
	(segment
		(start 367.045748 -297.873928)
		(end 366.792256 -296.437558)
		(width 0.14732)
		(layer "In2.Cu")
		(net "P5E_CPU0_PE3_TX_DP<15>")
	)
	(segment
		(start 374.2309 -398.374362)
		(end 374.38076 -397.963644)
		(width 0.14732)
		(layer "In2.Cu")
		(net "P5E_CPU0_PE3_TX_DP<15>")
	)
	(segment
		(start 367.834418 -299.000418)
		(end 367.045748 -297.873928)
		(width 0.14732)
		(layer "In2.Cu")
		(net "P5E_CPU0_PE3_TX_DP<15>")
	)
	(segment
		(start 367.773712 -290.351464)
		(end 367.773712 -289.64636)
		(width 0.0889)
		(layer "In2.Cu")
		(net "P5E_CPU0_PE3_TX_DP<15>")
	)
	(segment
		(start 367.521998 -285.390336)
		(end 367.678462 -285.661354)
		(width 0.0889)
		(layer "In2.Cu")
		(net "P5E_CPU0_PE3_TX_DP<15>")
	)
	(segment
		(start 368.422428 -288.597848)
		(end 368.431318 -288.592768)
		(width 0.0889)
		(layer "In2.Cu")
		(net "P5E_CPU0_PE3_TX_DP<15>")
	)
	(segment
		(start 366.792256 -296.437558)
		(end 366.792256 -292.357048)
		(width 0.14732)
		(layer "In2.Cu")
		(net "P5E_CPU0_PE3_TX_DP<15>")
	)
	(segment
		(start 392.336274 -333.420466)
		(end 391.631424 -329.423268)
		(width 0.14732)
		(layer "In2.Cu")
		(net "P5E_CPU0_PE3_TX_DP<15>")
	)
	(segment
		(start 373.63273 -407.00452)
		(end 373.33809 -406.70988)
		(width 0.14732)
		(layer "In2.Cu")
		(net "P5E_CPU0_PE3_TX_DP<15>")
	)
	(segment
		(start 367.961418 -286.799782)
		(end 367.952528 -286.794702)
		(width 0.0889)
		(layer "In2.Cu")
		(net "P5E_CPU0_PE3_TX_DP<15>")
	)
	(segment
		(start 367.815876 -291.333428)
		(end 367.815876 -290.415726)
		(width 0.14732)
		(layer "In2.Cu")
		(net "P5E_CPU0_PE3_TX_DP<15>")
	)
	(segment
		(start 366.792256 -292.357048)
		(end 367.815876 -291.333428)
		(width 0.14732)
		(layer "In2.Cu")
		(net "P5E_CPU0_PE3_TX_DP<15>")
	)
	(segment
		(start 367.773966 -286.475424)
		(end 367.773966 -286.4612)
		(width 0.0889)
		(layer "In2.Cu")
		(net "P5E_CPU0_PE3_TX_DP<15>")
	)
	(segment
		(start 374.692164 -396.749524)
		(end 392.336274 -348.48419)
		(width 0.14732)
		(layer "In2.Cu")
		(net "P5E_CPU0_PE3_TX_DP<15>")
	)
	(segment
		(start 373.33809 -406.70988)
		(end 373.33809 -406.001982)
		(width 0.14732)
		(layer "In2.Cu")
		(net "P5E_CPU0_PE3_TX_DP<15>")
	)
	(segment
		(start 368.443256 -287.62071)
		(end 368.431064 -287.613598)
		(width 0.0889)
		(layer "In2.Cu")
		(net "P5E_CPU0_PE3_TX_DP<15>")
	)
	(segment
		(start 367.815876 -290.393628)
		(end 367.773712 -290.351464)
		(width 0.0889)
		(layer "In2.Cu")
		(net "P5E_CPU0_PE3_TX_DP<15>")
	)
	(segment
		(start 374.38076 -397.963644)
		(end 374.306592 -397.804132)
		(width 0.14732)
		(layer "In2.Cu")
		(net "P5E_CPU0_PE3_TX_DP<15>")
	)
	(segment
		(start 392.336274 -348.48419)
		(end 392.336274 -333.420466)
		(width 0.14732)
		(layer "In2.Cu")
		(net "P5E_CPU0_PE3_TX_DP<15>")
	)
	(segment
		(start 373.52351 -399.946114)
		(end 374.07088 -398.44853)
		(width 0.14732)
		(layer "In2.Cu")
		(net "P5E_CPU0_PE3_TX_DP<15>")
	)
	(segment
		(start 367.815876 -290.415726)
		(end 367.815876 -290.393628)
		(width 0.0889)
		(layer "In2.Cu")
		(net "P5E_CPU0_PE3_TX_DP<15>")
	)
	(segment
		(start 367.44402 -285.369508)
		(end 367.521998 -285.390336)
		(width 0.0889)
		(layer "In2.Cu")
		(net "P5E_CPU0_PE3_TX_DP<15>")
	)
	(segment
		(start 367.304066 -285.66999)
		(end 367.304066 -285.652718)
		(width 0.0889)
		(layer "In2.Cu")
		(net "P5E_CPU0_PE3_TX_DP<15>")
	)
	(segment
		(start 374.616472 -397.319754)
		(end 374.766332 -396.90929)
		(width 0.14732)
		(layer "In2.Cu")
		(net "P5E_CPU0_PE3_TX_DP<15>")
	)
	(segment
		(start 368.713766 -288.11728)
		(end 368.713766 -288.103056)
		(width 0.0889)
		(layer "In2.Cu")
		(net "P5E_CPU0_PE3_TX_DP<15>")
	)
	(segment
		(start 368.243866 -289.114484)
		(end 368.243866 -288.917126)
		(width 0.0889)
		(layer "In2.Cu")
		(net "P5E_CPU0_PE3_TX_DP<15>")
	)
	(segment
		(start 374.07088 -398.44853)
		(end 374.2309 -398.374362)
		(width 0.14732)
		(layer "In2.Cu")
		(net "P5E_CPU0_PE3_TX_DP<15>")
	)
	(segment
		(start 373.52351 -404.118572)
		(end 373.52351 -399.946114)
		(width 0.14732)
		(layer "In2.Cu")
		(net "P5E_CPU0_PE3_TX_DP<15>")
	)
	(segment
		(start 373.33809 -406.001982)
		(end 373.52351 -404.118572)
		(width 0.14732)
		(layer "In2.Cu")
		(net "P5E_CPU0_PE3_TX_DP<15>")
	)
	(segment
		(start 374.306592 -397.804132)
		(end 374.456452 -397.393922)
		(width 0.14732)
		(layer "In2.Cu")
		(net "P5E_CPU0_PE3_TX_DP<15>")
	)
	(arc
		(start 367.773966 -286.4612)
		(mid 367.694747 -286.186515)
		(end 367.491264 -285.985712)
		(width 0.0889)
		(layer "In2.Cu")
		(net "P5E_CPU0_PE3_TX_DP<15>")
	)
	(arc
		(start 368.431064 -287.613598)
		(mid 368.296131 -287.480244)
		(end 368.243866 -287.297876)
		(width 0.0889)
		(layer "In2.Cu")
		(net "P5E_CPU0_PE3_TX_DP<15>")
	)
	(arc
		(start 367.491264 -285.985712)
		(mid 367.356331 -285.852358)
		(end 367.304066 -285.66999)
		(width 0.0889)
		(layer "In2.Cu")
		(net "P5E_CPU0_PE3_TX_DP<15>")
	)
	(arc
		(start 367.304066 -285.652718)
		(mid 367.34274 -285.49565)
		(end 367.44402 -285.369508)
		(width 0.0889)
		(layer "In2.Cu")
		(net "P5E_CPU0_PE3_TX_DP<15>")
	)
	(arc
		(start 368.243866 -288.917126)
		(mid 368.291545 -288.734226)
		(end 368.422428 -288.597848)
		(width 0.0889)
		(layer "In2.Cu")
		(net "P5E_CPU0_PE3_TX_DP<15>")
	)
	(arc
		(start 367.952528 -286.794702)
		(mid 367.821614 -286.658342)
		(end 367.773966 -286.475424)
		(width 0.0889)
		(layer "In2.Cu")
		(net "P5E_CPU0_PE3_TX_DP<15>")
	)
	(arc
		(start 368.713766 -288.103056)
		(mid 368.641531 -287.826532)
		(end 368.443256 -287.62071)
		(width 0.0889)
		(layer "In2.Cu")
		(net "P5E_CPU0_PE3_TX_DP<15>")
	)
	(arc
		(start 367.773712 -289.64636)
		(mid 367.848783 -289.530618)
		(end 367.958116 -289.446462)
		(width 0.0889)
		(layer "In2.Cu")
		(net "P5E_CPU0_PE3_TX_DP<15>")
	)
	(arc
		(start 368.431318 -288.592768)
		(mid 368.634623 -288.391902)
		(end 368.713766 -288.11728)
		(width 0.0889)
		(layer "In2.Cu")
		(net "P5E_CPU0_PE3_TX_DP<15>")
	)
	(arc
		(start 368.243866 -287.279334)
		(mid 368.165755 -287.002385)
		(end 367.961418 -286.799782)
		(width 0.0889)
		(layer "In2.Cu")
		(net "P5E_CPU0_PE3_TX_DP<15>")
	)
	(arc
		(start 367.958116 -289.446462)
		(mid 368.132417 -289.307532)
		(end 368.243866 -289.114484)
		(width 0.0889)
		(layer "In2.Cu")
		(net "P5E_CPU0_PE3_TX_DP<15>")
	)
	(segment
		(start 368.618516 -285.125414)
		(end 368.618516 -285.6611)
		(width 0.13208)
		(layer "F.Cu")
		(net "P5E_CPU0_PE3_TX_DP<14>")
	)
	(segment
		(start 376.397012 -407.926286)
		(end 376.72137 -408.250644)
		(width 0.13208)
		(layer "F.Cu")
		(net "P5E_CPU0_PE3_TX_DP<14>")
	)
	(segment
		(start 376.397012 -407.303478)
		(end 376.397012 -407.926286)
		(width 0.13208)
		(layer "F.Cu")
		(net "P5E_CPU0_PE3_TX_DP<14>")
	)
	(segment
		(start 368.618516 -285.6611)
		(end 368.618262 -285.661354)
		(width 0.13208)
		(layer "F.Cu")
		(net "P5E_CPU0_PE3_TX_DP<14>")
	)
	(segment
		(start 376.69597 -407.00452)
		(end 376.397012 -407.303478)
		(width 0.13208)
		(layer "F.Cu")
		(net "P5E_CPU0_PE3_TX_DP<14>")
	)
	(segment
		(start 369.653058 -290.07562)
		(end 369.653058 -289.699192)
		(width 0.0889)
		(layer "In2.Cu")
		(net "P5E_CPU0_PE3_TX_DP<14>")
	)
	(segment
		(start 393.306554 -333.526638)
		(end 392.507978 -328.997564)
		(width 0.14732)
		(layer "In2.Cu")
		(net "P5E_CPU0_PE3_TX_DP<14>")
	)
	(segment
		(start 376.69597 -407.00452)
		(end 376.40133 -406.70988)
		(width 0.14732)
		(layer "In2.Cu")
		(net "P5E_CPU0_PE3_TX_DP<14>")
	)
	(segment
		(start 368.485928 -286.021526)
		(end 368.461798 -285.932372)
		(width 0.0889)
		(layer "In2.Cu")
		(net "P5E_CPU0_PE3_TX_DP<14>")
	)
	(segment
		(start 376.40133 -406.001982)
		(end 376.58675 -404.118572)
		(width 0.14732)
		(layer "In2.Cu")
		(net "P5E_CPU0_PE3_TX_DP<14>")
	)
	(segment
		(start 369.373404 -287.614868)
		(end 369.36553 -287.61055)
		(width 0.0889)
		(layer "In2.Cu")
		(net "P5E_CPU0_PE3_TX_DP<14>")
	)
	(segment
		(start 369.695222 -290.117784)
		(end 369.653058 -290.07562)
		(width 0.0889)
		(layer "In2.Cu")
		(net "P5E_CPU0_PE3_TX_DP<14>")
	)
	(segment
		(start 369.982242 -300.087538)
		(end 369.380262 -299.228764)
		(width 0.14732)
		(layer "In2.Cu")
		(net "P5E_CPU0_PE3_TX_DP<14>")
	)
	(segment
		(start 369.183412 -287.28924)
		(end 369.183412 -287.279334)
		(width 0.0889)
		(layer "In2.Cu")
		(net "P5E_CPU0_PE3_TX_DP<14>")
	)
	(segment
		(start 370.123212 -289.036252)
		(end 370.123466 -288.898584)
		(width 0.0889)
		(layer "In2.Cu")
		(net "P5E_CPU0_PE3_TX_DP<14>")
	)
	(segment
		(start 393.306554 -348.507558)
		(end 393.306554 -333.526638)
		(width 0.14732)
		(layer "In2.Cu")
		(net "P5E_CPU0_PE3_TX_DP<14>")
	)
	(segment
		(start 369.695222 -292.866826)
		(end 369.695222 -290.139882)
		(width 0.14732)
		(layer "In2.Cu")
		(net "P5E_CPU0_PE3_TX_DP<14>")
	)
	(segment
		(start 369.840256 -288.426906)
		(end 369.832128 -288.422334)
		(width 0.0889)
		(layer "In2.Cu")
		(net "P5E_CPU0_PE3_TX_DP<14>")
	)
	(segment
		(start 369.1382 -297.852338)
		(end 369.1382 -293.423848)
		(width 0.14732)
		(layer "In2.Cu")
		(net "P5E_CPU0_PE3_TX_DP<14>")
	)
	(segment
		(start 369.37696 -287.617154)
		(end 369.373404 -287.614868)
		(width 0.0889)
		(layer "In2.Cu")
		(net "P5E_CPU0_PE3_TX_DP<14>")
	)
	(segment
		(start 368.461798 -285.932372)
		(end 368.618262 -285.661354)
		(width 0.0889)
		(layer "In2.Cu")
		(net "P5E_CPU0_PE3_TX_DP<14>")
	)
	(segment
		(start 369.36553 -287.61055)
		(end 369.361974 -287.608518)
		(width 0.0889)
		(layer "In2.Cu")
		(net "P5E_CPU0_PE3_TX_DP<14>")
	)
	(segment
		(start 369.653566 -288.072068)
		(end 369.65001 -288.040318)
		(width 0.0889)
		(layer "In2.Cu")
		(net "P5E_CPU0_PE3_TX_DP<14>")
	)
	(segment
		(start 369.841018 -288.427414)
		(end 369.840256 -288.426906)
		(width 0.0889)
		(layer "In2.Cu")
		(net "P5E_CPU0_PE3_TX_DP<14>")
	)
	(segment
		(start 369.380262 -299.228764)
		(end 369.1382 -297.852338)
		(width 0.14732)
		(layer "In2.Cu")
		(net "P5E_CPU0_PE3_TX_DP<14>")
	)
	(segment
		(start 392.507978 -328.997564)
		(end 369.982242 -300.087538)
		(width 0.14732)
		(layer "In2.Cu")
		(net "P5E_CPU0_PE3_TX_DP<14>")
	)
	(segment
		(start 369.653566 -288.103056)
		(end 369.653566 -288.072068)
		(width 0.0889)
		(layer "In2.Cu")
		(net "P5E_CPU0_PE3_TX_DP<14>")
	)
	(segment
		(start 369.695222 -290.139882)
		(end 369.695222 -290.117784)
		(width 0.0889)
		(layer "In2.Cu")
		(net "P5E_CPU0_PE3_TX_DP<14>")
	)
	(segment
		(start 376.40133 -406.70988)
		(end 376.40133 -406.001982)
		(width 0.14732)
		(layer "In2.Cu")
		(net "P5E_CPU0_PE3_TX_DP<14>")
	)
	(segment
		(start 368.713766 -286.48406)
		(end 368.713766 -286.4612)
		(width 0.0889)
		(layer "In2.Cu")
		(net "P5E_CPU0_PE3_TX_DP<14>")
	)
	(segment
		(start 376.58675 -399.90014)
		(end 393.306554 -348.507558)
		(width 0.14732)
		(layer "In2.Cu")
		(net "P5E_CPU0_PE3_TX_DP<14>")
	)
	(segment
		(start 369.1382 -293.423848)
		(end 369.695222 -292.866826)
		(width 0.14732)
		(layer "In2.Cu")
		(net "P5E_CPU0_PE3_TX_DP<14>")
	)
	(segment
		(start 376.58675 -404.118572)
		(end 376.58675 -399.90014)
		(width 0.14732)
		(layer "In2.Cu")
		(net "P5E_CPU0_PE3_TX_DP<14>")
	)
	(arc
		(start 370.123466 -288.898584)
		(mid 370.043304 -288.626395)
		(end 369.841018 -288.427414)
		(width 0.0889)
		(layer "In2.Cu")
		(net "P5E_CPU0_PE3_TX_DP<14>")
	)
	(arc
		(start 369.814856 -289.472878)
		(mid 369.848855 -289.444053)
		(end 369.885214 -289.418268)
		(width 0.0889)
		(layer "In2.Cu")
		(net "P5E_CPU0_PE3_TX_DP<14>")
	)
	(arc
		(start 368.900964 -286.799782)
		(mid 368.766031 -286.666428)
		(end 368.713766 -286.48406)
		(width 0.0889)
		(layer "In2.Cu")
		(net "P5E_CPU0_PE3_TX_DP<14>")
	)
	(arc
		(start 369.183412 -287.279334)
		(mid 369.105301 -287.002385)
		(end 368.900964 -286.799782)
		(width 0.0889)
		(layer "In2.Cu")
		(net "P5E_CPU0_PE3_TX_DP<14>")
	)
	(arc
		(start 368.502946 -286.03448)
		(mid 368.494498 -286.027923)
		(end 368.485928 -286.021526)
		(width 0.0889)
		(layer "In2.Cu")
		(net "P5E_CPU0_PE3_TX_DP<14>")
	)
	(arc
		(start 369.653058 -289.699192)
		(mid 369.660549 -289.654615)
		(end 369.682522 -289.615118)
		(width 0.0889)
		(layer "In2.Cu")
		(net "P5E_CPU0_PE3_TX_DP<14>")
	)
	(arc
		(start 369.361974 -287.608518)
		(mid 369.23106 -287.472158)
		(end 369.183412 -287.28924)
		(width 0.0889)
		(layer "In2.Cu")
		(net "P5E_CPU0_PE3_TX_DP<14>")
	)
	(arc
		(start 369.384326 -287.621726)
		(mid 369.380652 -287.619425)
		(end 369.37696 -287.617154)
		(width 0.0889)
		(layer "In2.Cu")
		(net "P5E_CPU0_PE3_TX_DP<14>")
	)
	(arc
		(start 370.074698 -289.218878)
		(mid 370.111145 -289.130806)
		(end 370.123212 -289.036252)
		(width 0.0889)
		(layer "In2.Cu")
		(net "P5E_CPU0_PE3_TX_DP<14>")
	)
	(arc
		(start 369.682522 -289.615118)
		(mid 369.746211 -289.541692)
		(end 369.814856 -289.472878)
		(width 0.0889)
		(layer "In2.Cu")
		(net "P5E_CPU0_PE3_TX_DP<14>")
	)
	(arc
		(start 369.832128 -288.422334)
		(mid 369.701214 -288.285974)
		(end 369.653566 -288.103056)
		(width 0.0889)
		(layer "In2.Cu")
		(net "P5E_CPU0_PE3_TX_DP<14>")
	)
	(arc
		(start 369.885214 -289.418268)
		(mid 369.991576 -289.329615)
		(end 370.074698 -289.218878)
		(width 0.0889)
		(layer "In2.Cu")
		(net "P5E_CPU0_PE3_TX_DP<14>")
	)
	(arc
		(start 368.713766 -286.4612)
		(mid 368.655472 -286.224557)
		(end 368.502946 -286.03448)
		(width 0.0889)
		(layer "In2.Cu")
		(net "P5E_CPU0_PE3_TX_DP<14>")
	)
	(arc
		(start 369.65001 -288.040318)
		(mid 369.565477 -287.800376)
		(end 369.384326 -287.621726)
		(width 0.0889)
		(layer "In2.Cu")
		(net "P5E_CPU0_PE3_TX_DP<14>")
	)
	(segment
		(start 379.75921 -407.00452)
		(end 379.460252 -407.303478)
		(width 0.13208)
		(layer "F.Cu")
		(net "P5E_CPU0_PE3_TX_DP<13>")
	)
	(segment
		(start 369.558316 -285.6611)
		(end 369.558062 -285.661354)
		(width 0.13208)
		(layer "F.Cu")
		(net "P5E_CPU0_PE3_TX_DP<13>")
	)
	(segment
		(start 379.460252 -407.303478)
		(end 379.460252 -407.926286)
		(width 0.13208)
		(layer "F.Cu")
		(net "P5E_CPU0_PE3_TX_DP<13>")
	)
	(segment
		(start 369.558316 -285.125414)
		(end 369.558316 -285.6611)
		(width 0.13208)
		(layer "F.Cu")
		(net "P5E_CPU0_PE3_TX_DP<13>")
	)
	(segment
		(start 379.460252 -407.926286)
		(end 379.78461 -408.250644)
		(width 0.13208)
		(layer "F.Cu")
		(net "P5E_CPU0_PE3_TX_DP<13>")
	)
	(segment
		(start 380.675134 -396.415514)
		(end 394.246354 -348.76359)
		(width 0.14732)
		(layer "In2.Cu")
		(net "P5E_CPU0_PE3_TX_DP<13>")
	)
	(segment
		(start 370.31676 -287.617154)
		(end 370.310664 -287.613598)
		(width 0.0889)
		(layer "In2.Cu")
		(net "P5E_CPU0_PE3_TX_DP<13>")
	)
	(segment
		(start 370.7384 -299.528738)
		(end 370.271548 -298.861988)
		(width 0.14732)
		(layer "In2.Cu")
		(net "P5E_CPU0_PE3_TX_DP<13>")
	)
	(segment
		(start 370.635276 -290.115752)
		(end 370.593112 -290.073588)
		(width 0.0889)
		(layer "In2.Cu")
		(net "P5E_CPU0_PE3_TX_DP<13>")
	)
	(segment
		(start 370.780818 -288.427414)
		(end 370.780056 -288.426906)
		(width 0.0889)
		(layer "In2.Cu")
		(net "P5E_CPU0_PE3_TX_DP<13>")
	)
	(segment
		(start 394.246354 -333.443326)
		(end 393.393168 -328.604118)
		(width 0.14732)
		(layer "In2.Cu")
		(net "P5E_CPU0_PE3_TX_DP<13>")
	)
	(segment
		(start 370.780056 -288.426906)
		(end 370.771928 -288.422334)
		(width 0.0889)
		(layer "In2.Cu")
		(net "P5E_CPU0_PE3_TX_DP<13>")
	)
	(segment
		(start 379.64999 -404.118572)
		(end 379.64999 -400.01444)
		(width 0.14732)
		(layer "In2.Cu")
		(net "P5E_CPU0_PE3_TX_DP<13>")
	)
	(segment
		(start 379.75921 -407.00452)
		(end 379.46457 -406.70988)
		(width 0.14732)
		(layer "In2.Cu")
		(net "P5E_CPU0_PE3_TX_DP<13>")
	)
	(segment
		(start 370.593112 -290.073588)
		(end 370.593112 -289.64636)
		(width 0.0889)
		(layer "In2.Cu")
		(net "P5E_CPU0_PE3_TX_DP<13>")
	)
	(segment
		(start 369.841018 -286.799782)
		(end 369.840002 -286.799274)
		(width 0.0889)
		(layer "In2.Cu")
		(net "P5E_CPU0_PE3_TX_DP<13>")
	)
	(segment
		(start 379.64999 -400.01444)
		(end 380.176786 -398.164812)
		(width 0.14732)
		(layer "In2.Cu")
		(net "P5E_CPU0_PE3_TX_DP<13>")
	)
	(segment
		(start 380.450344 -397.658844)
		(end 380.364746 -397.50492)
		(width 0.14732)
		(layer "In2.Cu")
		(net "P5E_CPU0_PE3_TX_DP<13>")
	)
	(segment
		(start 371.063266 -289.114484)
		(end 371.063266 -288.898584)
		(width 0.0889)
		(layer "In2.Cu")
		(net "P5E_CPU0_PE3_TX_DP<13>")
	)
	(segment
		(start 370.078 -297.763946)
		(end 370.078 -293.978584)
		(width 0.14732)
		(layer "In2.Cu")
		(net "P5E_CPU0_PE3_TX_DP<13>")
	)
	(segment
		(start 380.641098 -396.989808)
		(end 380.760732 -396.569438)
		(width 0.14732)
		(layer "In2.Cu")
		(net "P5E_CPU0_PE3_TX_DP<13>")
	)
	(segment
		(start 380.33071 -398.079214)
		(end 380.450344 -397.658844)
		(width 0.14732)
		(layer "In2.Cu")
		(net "P5E_CPU0_PE3_TX_DP<13>")
	)
	(segment
		(start 369.370864 -285.985712)
		(end 369.361974 -285.980632)
		(width 0.0889)
		(layer "In2.Cu")
		(net "P5E_CPU0_PE3_TX_DP<13>")
	)
	(segment
		(start 369.653566 -286.475424)
		(end 369.653566 -286.467804)
		(width 0.0889)
		(layer "In2.Cu")
		(net "P5E_CPU0_PE3_TX_DP<13>")
	)
	(segment
		(start 370.123212 -287.28924)
		(end 370.123212 -287.273746)
		(width 0.0889)
		(layer "In2.Cu")
		(net "P5E_CPU0_PE3_TX_DP<13>")
	)
	(segment
		(start 380.48692 -397.075406)
		(end 380.641098 -396.989808)
		(width 0.14732)
		(layer "In2.Cu")
		(net "P5E_CPU0_PE3_TX_DP<13>")
	)
	(segment
		(start 380.176786 -398.164812)
		(end 380.33071 -398.079214)
		(width 0.14732)
		(layer "In2.Cu")
		(net "P5E_CPU0_PE3_TX_DP<13>")
	)
	(segment
		(start 380.364746 -397.50492)
		(end 380.48692 -397.075406)
		(width 0.14732)
		(layer "In2.Cu")
		(net "P5E_CPU0_PE3_TX_DP<13>")
	)
	(segment
		(start 369.323366 -285.369508)
		(end 369.401598 -285.390336)
		(width 0.0889)
		(layer "In2.Cu")
		(net "P5E_CPU0_PE3_TX_DP<13>")
	)
	(segment
		(start 379.46457 -406.70988)
		(end 379.46457 -406.001982)
		(width 0.14732)
		(layer "In2.Cu")
		(net "P5E_CPU0_PE3_TX_DP<13>")
	)
	(segment
		(start 370.271548 -298.861988)
		(end 370.078 -297.763946)
		(width 0.14732)
		(layer "In2.Cu")
		(net "P5E_CPU0_PE3_TX_DP<13>")
	)
	(segment
		(start 370.635276 -293.421308)
		(end 370.635276 -290.13785)
		(width 0.14732)
		(layer "In2.Cu")
		(net "P5E_CPU0_PE3_TX_DP<13>")
	)
	(segment
		(start 370.310664 -287.613598)
		(end 370.301774 -287.608518)
		(width 0.0889)
		(layer "In2.Cu")
		(net "P5E_CPU0_PE3_TX_DP<13>")
	)
	(segment
		(start 369.840002 -286.799274)
		(end 369.832128 -286.794702)
		(width 0.0889)
		(layer "In2.Cu")
		(net "P5E_CPU0_PE3_TX_DP<13>")
	)
	(segment
		(start 370.635276 -290.13785)
		(end 370.635276 -290.115752)
		(width 0.0889)
		(layer "In2.Cu")
		(net "P5E_CPU0_PE3_TX_DP<13>")
	)
	(segment
		(start 393.393168 -328.604118)
		(end 370.7384 -299.528738)
		(width 0.14732)
		(layer "In2.Cu")
		(net "P5E_CPU0_PE3_TX_DP<13>")
	)
	(segment
		(start 394.246354 -348.76359)
		(end 394.246354 -333.443326)
		(width 0.14732)
		(layer "In2.Cu")
		(net "P5E_CPU0_PE3_TX_DP<13>")
	)
	(segment
		(start 370.078 -293.978584)
		(end 370.635276 -293.421308)
		(width 0.14732)
		(layer "In2.Cu")
		(net "P5E_CPU0_PE3_TX_DP<13>")
	)
	(segment
		(start 379.46457 -406.001982)
		(end 379.64999 -404.118572)
		(width 0.14732)
		(layer "In2.Cu")
		(net "P5E_CPU0_PE3_TX_DP<13>")
	)
	(segment
		(start 380.760732 -396.569438)
		(end 380.675134 -396.415514)
		(width 0.14732)
		(layer "In2.Cu")
		(net "P5E_CPU0_PE3_TX_DP<13>")
	)
	(segment
		(start 369.401598 -285.390336)
		(end 369.558062 -285.661354)
		(width 0.0889)
		(layer "In2.Cu")
		(net "P5E_CPU0_PE3_TX_DP<13>")
	)
	(arc
		(start 370.593112 -289.64636)
		(mid 370.668183 -289.530618)
		(end 370.777516 -289.446462)
		(width 0.0889)
		(layer "In2.Cu")
		(net "P5E_CPU0_PE3_TX_DP<13>")
	)
	(arc
		(start 369.361974 -285.980632)
		(mid 369.23106 -285.844272)
		(end 369.183412 -285.661354)
		(width 0.0889)
		(layer "In2.Cu")
		(net "P5E_CPU0_PE3_TX_DP<13>")
	)
	(arc
		(start 370.771928 -288.422334)
		(mid 370.641014 -288.285974)
		(end 370.593366 -288.103056)
		(width 0.0889)
		(layer "In2.Cu")
		(net "P5E_CPU0_PE3_TX_DP<13>")
	)
	(arc
		(start 369.183412 -285.661354)
		(mid 369.220272 -285.499557)
		(end 369.323366 -285.369508)
		(width 0.0889)
		(layer "In2.Cu")
		(net "P5E_CPU0_PE3_TX_DP<13>")
	)
	(arc
		(start 370.123212 -287.273746)
		(mid 370.043842 -287.000012)
		(end 369.841018 -286.799782)
		(width 0.0889)
		(layer "In2.Cu")
		(net "P5E_CPU0_PE3_TX_DP<13>")
	)
	(arc
		(start 369.653566 -286.467804)
		(mid 369.575937 -286.189391)
		(end 369.370864 -285.985712)
		(width 0.0889)
		(layer "In2.Cu")
		(net "P5E_CPU0_PE3_TX_DP<13>")
	)
	(arc
		(start 369.832128 -286.794702)
		(mid 369.701214 -286.658342)
		(end 369.653566 -286.475424)
		(width 0.0889)
		(layer "In2.Cu")
		(net "P5E_CPU0_PE3_TX_DP<13>")
	)
	(arc
		(start 370.593366 -288.103056)
		(mid 370.519375 -287.82349)
		(end 370.31676 -287.617154)
		(width 0.0889)
		(layer "In2.Cu")
		(net "P5E_CPU0_PE3_TX_DP<13>")
	)
	(arc
		(start 371.063266 -288.898584)
		(mid 370.983104 -288.626395)
		(end 370.780818 -288.427414)
		(width 0.0889)
		(layer "In2.Cu")
		(net "P5E_CPU0_PE3_TX_DP<13>")
	)
	(arc
		(start 370.777516 -289.446462)
		(mid 370.951817 -289.307532)
		(end 371.063266 -289.114484)
		(width 0.0889)
		(layer "In2.Cu")
		(net "P5E_CPU0_PE3_TX_DP<13>")
	)
	(arc
		(start 370.301774 -287.608518)
		(mid 370.17086 -287.472158)
		(end 370.123212 -287.28924)
		(width 0.0889)
		(layer "In2.Cu")
		(net "P5E_CPU0_PE3_TX_DP<13>")
	)
	(segment
		(start 382.82245 -407.00452)
		(end 382.523492 -407.303478)
		(width 0.13208)
		(layer "F.Cu")
		(net "P5E_CPU0_PE3_TX_DP<12>")
	)
	(segment
		(start 382.523492 -407.926286)
		(end 382.84785 -408.250644)
		(width 0.13208)
		(layer "F.Cu")
		(net "P5E_CPU0_PE3_TX_DP<12>")
	)
	(segment
		(start 370.498116 -285.6611)
		(end 370.497862 -285.661354)
		(width 0.13208)
		(layer "F.Cu")
		(net "P5E_CPU0_PE3_TX_DP<12>")
	)
	(segment
		(start 370.498116 -285.125414)
		(end 370.498116 -285.6611)
		(width 0.13208)
		(layer "F.Cu")
		(net "P5E_CPU0_PE3_TX_DP<12>")
	)
	(segment
		(start 382.523492 -407.303478)
		(end 382.523492 -407.926286)
		(width 0.13208)
		(layer "F.Cu")
		(net "P5E_CPU0_PE3_TX_DP<12>")
	)
	(segment
		(start 370.365528 -286.021526)
		(end 370.341398 -285.932372)
		(width 0.0889)
		(layer "In2.Cu")
		(net "P5E_CPU0_PE3_TX_DP<12>")
	)
	(segment
		(start 382.52781 -406.001982)
		(end 382.71323 -404.118572)
		(width 0.14732)
		(layer "In2.Cu")
		(net "P5E_CPU0_PE3_TX_DP<12>")
	)
	(segment
		(start 374.123966 -302.028098)
		(end 373.745506 -301.649384)
		(width 0.14732)
		(layer "In2.Cu")
		(net "P5E_CPU0_PE3_TX_DP<12>")
	)
	(segment
		(start 373.745506 -301.649384)
		(end 373.366792 -301.27067)
		(width 0.14732)
		(layer "In2.Cu")
		(net "P5E_CPU0_PE3_TX_DP<12>")
	)
	(segment
		(start 371.575076 -290.13785)
		(end 371.575076 -290.115752)
		(width 0.0889)
		(layer "In2.Cu")
		(net "P5E_CPU0_PE3_TX_DP<12>")
	)
	(segment
		(start 371.532912 -290.073588)
		(end 371.532912 -289.64636)
		(width 0.0889)
		(layer "In2.Cu")
		(net "P5E_CPU0_PE3_TX_DP<12>")
	)
	(segment
		(start 370.593366 -286.48406)
		(end 370.593366 -286.4612)
		(width 0.0889)
		(layer "In2.Cu")
		(net "P5E_CPU0_PE3_TX_DP<12>")
	)
	(segment
		(start 373.366792 -301.27067)
		(end 371.89791 -299.327316)
		(width 0.14732)
		(layer "In2.Cu")
		(net "P5E_CPU0_PE3_TX_DP<12>")
	)
	(segment
		(start 395.216126 -333.545942)
		(end 394.189712 -327.725024)
		(width 0.14732)
		(layer "In2.Cu")
		(net "P5E_CPU0_PE3_TX_DP<12>")
	)
	(segment
		(start 382.52781 -406.70988)
		(end 382.52781 -406.001982)
		(width 0.14732)
		(layer "In2.Cu")
		(net "P5E_CPU0_PE3_TX_DP<12>")
	)
	(segment
		(start 382.82245 -407.00452)
		(end 382.52781 -406.70988)
		(width 0.14732)
		(layer "In2.Cu")
		(net "P5E_CPU0_PE3_TX_DP<12>")
	)
	(segment
		(start 371.89791 -299.327316)
		(end 371.575076 -297.49242)
		(width 0.14732)
		(layer "In2.Cu")
		(net "P5E_CPU0_PE3_TX_DP<12>")
	)
	(segment
		(start 382.71323 -399.897346)
		(end 395.216126 -348.719394)
		(width 0.14732)
		(layer "In2.Cu")
		(net "P5E_CPU0_PE3_TX_DP<12>")
	)
	(segment
		(start 371.250464 -287.613598)
		(end 371.241574 -287.608518)
		(width 0.0889)
		(layer "In2.Cu")
		(net "P5E_CPU0_PE3_TX_DP<12>")
	)
	(segment
		(start 371.720618 -288.427414)
		(end 371.711728 -288.422334)
		(width 0.0889)
		(layer "In2.Cu")
		(net "P5E_CPU0_PE3_TX_DP<12>")
	)
	(segment
		(start 371.063012 -287.28924)
		(end 371.063012 -287.279334)
		(width 0.0889)
		(layer "In2.Cu")
		(net "P5E_CPU0_PE3_TX_DP<12>")
	)
	(segment
		(start 394.189712 -327.725024)
		(end 374.123966 -302.028098)
		(width 0.14732)
		(layer "In2.Cu")
		(net "P5E_CPU0_PE3_TX_DP<12>")
	)
	(segment
		(start 372.003066 -289.114484)
		(end 372.003066 -288.898584)
		(width 0.0889)
		(layer "In2.Cu")
		(net "P5E_CPU0_PE3_TX_DP<12>")
	)
	(segment
		(start 371.575076 -290.115752)
		(end 371.532912 -290.073588)
		(width 0.0889)
		(layer "In2.Cu")
		(net "P5E_CPU0_PE3_TX_DP<12>")
	)
	(segment
		(start 371.25656 -287.617154)
		(end 371.250464 -287.613598)
		(width 0.0889)
		(layer "In2.Cu")
		(net "P5E_CPU0_PE3_TX_DP<12>")
	)
	(segment
		(start 371.575076 -297.49242)
		(end 371.575076 -290.13785)
		(width 0.14732)
		(layer "In2.Cu")
		(net "P5E_CPU0_PE3_TX_DP<12>")
	)
	(segment
		(start 395.216126 -348.719394)
		(end 395.216126 -333.545942)
		(width 0.14732)
		(layer "In2.Cu")
		(net "P5E_CPU0_PE3_TX_DP<12>")
	)
	(segment
		(start 370.341398 -285.932372)
		(end 370.497862 -285.661354)
		(width 0.0889)
		(layer "In2.Cu")
		(net "P5E_CPU0_PE3_TX_DP<12>")
	)
	(segment
		(start 382.71323 -404.118572)
		(end 382.71323 -399.897346)
		(width 0.14732)
		(layer "In2.Cu")
		(net "P5E_CPU0_PE3_TX_DP<12>")
	)
	(arc
		(start 371.063012 -287.279334)
		(mid 370.984901 -287.002385)
		(end 370.780564 -286.799782)
		(width 0.0889)
		(layer "In2.Cu")
		(net "P5E_CPU0_PE3_TX_DP<12>")
	)
	(arc
		(start 370.382546 -286.03448)
		(mid 370.374098 -286.027923)
		(end 370.365528 -286.021526)
		(width 0.0889)
		(layer "In2.Cu")
		(net "P5E_CPU0_PE3_TX_DP<12>")
	)
	(arc
		(start 371.241574 -287.608518)
		(mid 371.11066 -287.472158)
		(end 371.063012 -287.28924)
		(width 0.0889)
		(layer "In2.Cu")
		(net "P5E_CPU0_PE3_TX_DP<12>")
	)
	(arc
		(start 372.003066 -288.898584)
		(mid 371.922904 -288.626395)
		(end 371.720618 -288.427414)
		(width 0.0889)
		(layer "In2.Cu")
		(net "P5E_CPU0_PE3_TX_DP<12>")
	)
	(arc
		(start 370.780564 -286.799782)
		(mid 370.645631 -286.666428)
		(end 370.593366 -286.48406)
		(width 0.0889)
		(layer "In2.Cu")
		(net "P5E_CPU0_PE3_TX_DP<12>")
	)
	(arc
		(start 371.533166 -288.103056)
		(mid 371.459175 -287.82349)
		(end 371.25656 -287.617154)
		(width 0.0889)
		(layer "In2.Cu")
		(net "P5E_CPU0_PE3_TX_DP<12>")
	)
	(arc
		(start 371.711728 -288.422334)
		(mid 371.580814 -288.285974)
		(end 371.533166 -288.103056)
		(width 0.0889)
		(layer "In2.Cu")
		(net "P5E_CPU0_PE3_TX_DP<12>")
	)
	(arc
		(start 371.532912 -289.64636)
		(mid 371.607983 -289.530618)
		(end 371.717316 -289.446462)
		(width 0.0889)
		(layer "In2.Cu")
		(net "P5E_CPU0_PE3_TX_DP<12>")
	)
	(arc
		(start 370.593366 -286.4612)
		(mid 370.535072 -286.224557)
		(end 370.382546 -286.03448)
		(width 0.0889)
		(layer "In2.Cu")
		(net "P5E_CPU0_PE3_TX_DP<12>")
	)
	(arc
		(start 371.717316 -289.446462)
		(mid 371.891617 -289.307532)
		(end 372.003066 -289.114484)
		(width 0.0889)
		(layer "In2.Cu")
		(net "P5E_CPU0_PE3_TX_DP<12>")
	)
	(segment
		(start 371.437916 -285.6611)
		(end 371.437662 -285.661354)
		(width 0.13208)
		(layer "F.Cu")
		(net "P5E_CPU0_PE3_TX_DP<11>")
	)
	(segment
		(start 371.437916 -285.125414)
		(end 371.437916 -285.6611)
		(width 0.13208)
		(layer "F.Cu")
		(net "P5E_CPU0_PE3_TX_DP<11>")
	)
	(segment
		(start 385.88569 -407.00452)
		(end 385.586732 -407.303478)
		(width 0.13208)
		(layer "F.Cu")
		(net "P5E_CPU0_PE3_TX_DP<11>")
	)
	(segment
		(start 385.586732 -407.303478)
		(end 385.586732 -407.926286)
		(width 0.13208)
		(layer "F.Cu")
		(net "P5E_CPU0_PE3_TX_DP<11>")
	)
	(segment
		(start 385.586732 -407.926286)
		(end 385.91109 -408.250644)
		(width 0.13208)
		(layer "F.Cu")
		(net "P5E_CPU0_PE3_TX_DP<11>")
	)
	(segment
		(start 385.59105 -406.001982)
		(end 385.77647 -404.118572)
		(width 0.14732)
		(layer "In2.Cu")
		(net "P5E_CPU0_PE3_TX_DP<11>")
	)
	(segment
		(start 372.191788 -287.614614)
		(end 372.190264 -287.613598)
		(width 0.0889)
		(layer "In2.Cu")
		(net "P5E_CPU0_PE3_TX_DP<11>")
	)
	(segment
		(start 372.002812 -287.28924)
		(end 372.002812 -287.273746)
		(width 0.0889)
		(layer "In2.Cu")
		(net "P5E_CPU0_PE3_TX_DP<11>")
	)
	(segment
		(start 386.231892 -398.289018)
		(end 386.319014 -397.86052)
		(width 0.14732)
		(layer "In2.Cu")
		(net "P5E_CPU0_PE3_TX_DP<11>")
	)
	(segment
		(start 386.319014 -397.86052)
		(end 386.221986 -397.713708)
		(width 0.14732)
		(layer "In2.Cu")
		(net "P5E_CPU0_PE3_TX_DP<11>")
	)
	(segment
		(start 386.221986 -397.713708)
		(end 386.327904 -397.1925)
		(width 0.14732)
		(layer "In2.Cu")
		(net "P5E_CPU0_PE3_TX_DP<11>")
	)
	(segment
		(start 386.465064 -396.520162)
		(end 396.155926 -348.896178)
		(width 0.14732)
		(layer "In2.Cu")
		(net "P5E_CPU0_PE3_TX_DP<11>")
	)
	(segment
		(start 372.19636 -287.617154)
		(end 372.191788 -287.614614)
		(width 0.0889)
		(layer "In2.Cu")
		(net "P5E_CPU0_PE3_TX_DP<11>")
	)
	(segment
		(start 385.77647 -399.90268)
		(end 386.08508 -398.386046)
		(width 0.14732)
		(layer "In2.Cu")
		(net "P5E_CPU0_PE3_TX_DP<11>")
	)
	(segment
		(start 396.155926 -348.896178)
		(end 396.155926 -333.463138)
		(width 0.14732)
		(layer "In2.Cu")
		(net "P5E_CPU0_PE3_TX_DP<11>")
	)
	(segment
		(start 372.514876 -290.13785)
		(end 372.514876 -290.115752)
		(width 0.0889)
		(layer "In2.Cu")
		(net "P5E_CPU0_PE3_TX_DP<11>")
	)
	(segment
		(start 371.720618 -286.799782)
		(end 371.719602 -286.799274)
		(width 0.0889)
		(layer "In2.Cu")
		(net "P5E_CPU0_PE3_TX_DP<11>")
	)
	(segment
		(start 372.514876 -290.115752)
		(end 372.472712 -290.073588)
		(width 0.0889)
		(layer "In2.Cu")
		(net "P5E_CPU0_PE3_TX_DP<11>")
	)
	(segment
		(start 371.533166 -286.475424)
		(end 371.533166 -286.467804)
		(width 0.0889)
		(layer "In2.Cu")
		(net "P5E_CPU0_PE3_TX_DP<11>")
	)
	(segment
		(start 371.250464 -285.985712)
		(end 371.241574 -285.980632)
		(width 0.0889)
		(layer "In2.Cu")
		(net "P5E_CPU0_PE3_TX_DP<11>")
	)
	(segment
		(start 385.59105 -406.70988)
		(end 385.59105 -406.001982)
		(width 0.14732)
		(layer "In2.Cu")
		(net "P5E_CPU0_PE3_TX_DP<11>")
	)
	(segment
		(start 372.942866 -289.114484)
		(end 372.942866 -288.898584)
		(width 0.0889)
		(layer "In2.Cu")
		(net "P5E_CPU0_PE3_TX_DP<11>")
	)
	(segment
		(start 385.77647 -404.118572)
		(end 385.77647 -399.90268)
		(width 0.14732)
		(layer "In2.Cu")
		(net "P5E_CPU0_PE3_TX_DP<11>")
	)
	(segment
		(start 395.07668 -327.34377)
		(end 374.794018 -301.36846)
		(width 0.14732)
		(layer "In2.Cu")
		(net "P5E_CPU0_PE3_TX_DP<11>")
	)
	(segment
		(start 371.281198 -285.390336)
		(end 371.437662 -285.661354)
		(width 0.0889)
		(layer "In2.Cu")
		(net "P5E_CPU0_PE3_TX_DP<11>")
	)
	(segment
		(start 386.327904 -397.1925)
		(end 386.47497 -397.095218)
		(width 0.14732)
		(layer "In2.Cu")
		(net "P5E_CPU0_PE3_TX_DP<11>")
	)
	(segment
		(start 374.077738 -300.651926)
		(end 372.81739 -298.984416)
		(width 0.14732)
		(layer "In2.Cu")
		(net "P5E_CPU0_PE3_TX_DP<11>")
	)
	(segment
		(start 372.660418 -288.427414)
		(end 372.651528 -288.422334)
		(width 0.0889)
		(layer "In2.Cu")
		(net "P5E_CPU0_PE3_TX_DP<11>")
	)
	(segment
		(start 374.794018 -301.36846)
		(end 374.077738 -300.651926)
		(width 0.14732)
		(layer "In2.Cu")
		(net "P5E_CPU0_PE3_TX_DP<11>")
	)
	(segment
		(start 372.81739 -298.984416)
		(end 372.514876 -297.266614)
		(width 0.14732)
		(layer "In2.Cu")
		(net "P5E_CPU0_PE3_TX_DP<11>")
	)
	(segment
		(start 372.514876 -297.266614)
		(end 372.514876 -290.13785)
		(width 0.14732)
		(layer "In2.Cu")
		(net "P5E_CPU0_PE3_TX_DP<11>")
	)
	(segment
		(start 386.47497 -397.095218)
		(end 386.562092 -396.666974)
		(width 0.14732)
		(layer "In2.Cu")
		(net "P5E_CPU0_PE3_TX_DP<11>")
	)
	(segment
		(start 371.719602 -286.799274)
		(end 371.711728 -286.794702)
		(width 0.0889)
		(layer "In2.Cu")
		(net "P5E_CPU0_PE3_TX_DP<11>")
	)
	(segment
		(start 372.190264 -287.613598)
		(end 372.18874 -287.612836)
		(width 0.0889)
		(layer "In2.Cu")
		(net "P5E_CPU0_PE3_TX_DP<11>")
	)
	(segment
		(start 372.18874 -287.612836)
		(end 372.181374 -287.608518)
		(width 0.0889)
		(layer "In2.Cu")
		(net "P5E_CPU0_PE3_TX_DP<11>")
	)
	(segment
		(start 385.88569 -407.00452)
		(end 385.59105 -406.70988)
		(width 0.14732)
		(layer "In2.Cu")
		(net "P5E_CPU0_PE3_TX_DP<11>")
	)
	(segment
		(start 386.08508 -398.386046)
		(end 386.231892 -398.289018)
		(width 0.14732)
		(layer "In2.Cu")
		(net "P5E_CPU0_PE3_TX_DP<11>")
	)
	(segment
		(start 372.472712 -290.073588)
		(end 372.472712 -289.64636)
		(width 0.0889)
		(layer "In2.Cu")
		(net "P5E_CPU0_PE3_TX_DP<11>")
	)
	(segment
		(start 386.562092 -396.666974)
		(end 386.465064 -396.520162)
		(width 0.14732)
		(layer "In2.Cu")
		(net "P5E_CPU0_PE3_TX_DP<11>")
	)
	(segment
		(start 371.202966 -285.369508)
		(end 371.281198 -285.390336)
		(width 0.0889)
		(layer "In2.Cu")
		(net "P5E_CPU0_PE3_TX_DP<11>")
	)
	(segment
		(start 396.155926 -333.463138)
		(end 395.07668 -327.34377)
		(width 0.14732)
		(layer "In2.Cu")
		(net "P5E_CPU0_PE3_TX_DP<11>")
	)
	(arc
		(start 372.472966 -288.103056)
		(mid 372.398975 -287.82349)
		(end 372.19636 -287.617154)
		(width 0.0889)
		(layer "In2.Cu")
		(net "P5E_CPU0_PE3_TX_DP<11>")
	)
	(arc
		(start 371.711728 -286.794702)
		(mid 371.580814 -286.658342)
		(end 371.533166 -286.475424)
		(width 0.0889)
		(layer "In2.Cu")
		(net "P5E_CPU0_PE3_TX_DP<11>")
	)
	(arc
		(start 371.533166 -286.467804)
		(mid 371.455537 -286.189391)
		(end 371.250464 -285.985712)
		(width 0.0889)
		(layer "In2.Cu")
		(net "P5E_CPU0_PE3_TX_DP<11>")
	)
	(arc
		(start 372.942866 -288.898584)
		(mid 372.862704 -288.626395)
		(end 372.660418 -288.427414)
		(width 0.0889)
		(layer "In2.Cu")
		(net "P5E_CPU0_PE3_TX_DP<11>")
	)
	(arc
		(start 371.241574 -285.980632)
		(mid 371.063726 -285.68504)
		(end 371.202966 -285.369508)
		(width 0.0889)
		(layer "In2.Cu")
		(net "P5E_CPU0_PE3_TX_DP<11>")
	)
	(arc
		(start 372.657116 -289.446462)
		(mid 372.831417 -289.307532)
		(end 372.942866 -289.114484)
		(width 0.0889)
		(layer "In2.Cu")
		(net "P5E_CPU0_PE3_TX_DP<11>")
	)
	(arc
		(start 372.472712 -289.64636)
		(mid 372.547783 -289.530618)
		(end 372.657116 -289.446462)
		(width 0.0889)
		(layer "In2.Cu")
		(net "P5E_CPU0_PE3_TX_DP<11>")
	)
	(arc
		(start 372.651528 -288.422334)
		(mid 372.520614 -288.285974)
		(end 372.472966 -288.103056)
		(width 0.0889)
		(layer "In2.Cu")
		(net "P5E_CPU0_PE3_TX_DP<11>")
	)
	(arc
		(start 372.181374 -287.608518)
		(mid 372.05046 -287.472158)
		(end 372.002812 -287.28924)
		(width 0.0889)
		(layer "In2.Cu")
		(net "P5E_CPU0_PE3_TX_DP<11>")
	)
	(arc
		(start 372.002812 -287.273746)
		(mid 371.923442 -287.000012)
		(end 371.720618 -286.799782)
		(width 0.0889)
		(layer "In2.Cu")
		(net "P5E_CPU0_PE3_TX_DP<11>")
	)
	(segment
		(start 388.649972 -407.303478)
		(end 388.649972 -407.926286)
		(width 0.13208)
		(layer "F.Cu")
		(net "P5E_CPU0_PE3_TX_DP<10>")
	)
	(segment
		(start 388.94893 -407.00452)
		(end 388.649972 -407.303478)
		(width 0.13208)
		(layer "F.Cu")
		(net "P5E_CPU0_PE3_TX_DP<10>")
	)
	(segment
		(start 388.649972 -407.926286)
		(end 388.97433 -408.250644)
		(width 0.13208)
		(layer "F.Cu")
		(net "P5E_CPU0_PE3_TX_DP<10>")
	)
	(segment
		(start 372.377716 -285.6611)
		(end 372.377462 -285.661354)
		(width 0.13208)
		(layer "F.Cu")
		(net "P5E_CPU0_PE3_TX_DP<10>")
	)
	(segment
		(start 372.377716 -285.125414)
		(end 372.377716 -285.6611)
		(width 0.13208)
		(layer "F.Cu")
		(net "P5E_CPU0_PE3_TX_DP<10>")
	)
	(segment
		(start 375.53519 -300.779434)
		(end 374.78843 -300.032928)
		(width 0.14732)
		(layer "In2.Cu")
		(net "P5E_CPU0_PE3_TX_DP<10>")
	)
	(segment
		(start 372.245128 -286.021526)
		(end 372.220998 -285.932372)
		(width 0.0889)
		(layer "In2.Cu")
		(net "P5E_CPU0_PE3_TX_DP<10>")
	)
	(segment
		(start 388.83971 -399.652744)
		(end 397.095726 -348.909386)
		(width 0.14732)
		(layer "In2.Cu")
		(net "P5E_CPU0_PE3_TX_DP<10>")
	)
	(segment
		(start 373.703342 -298.597574)
		(end 373.454422 -297.184572)
		(width 0.14732)
		(layer "In2.Cu")
		(net "P5E_CPU0_PE3_TX_DP<10>")
	)
	(segment
		(start 372.472966 -286.48406)
		(end 372.472966 -286.4612)
		(width 0.0889)
		(layer "In2.Cu")
		(net "P5E_CPU0_PE3_TX_DP<10>")
	)
	(segment
		(start 373.600218 -288.427414)
		(end 373.591328 -288.422334)
		(width 0.0889)
		(layer "In2.Cu")
		(net "P5E_CPU0_PE3_TX_DP<10>")
	)
	(segment
		(start 373.454422 -297.184572)
		(end 373.454422 -290.13785)
		(width 0.14732)
		(layer "In2.Cu")
		(net "P5E_CPU0_PE3_TX_DP<10>")
	)
	(segment
		(start 397.095726 -333.380588)
		(end 395.959584 -326.937116)
		(width 0.14732)
		(layer "In2.Cu")
		(net "P5E_CPU0_PE3_TX_DP<10>")
	)
	(segment
		(start 388.65429 -406.70988)
		(end 388.65429 -406.001982)
		(width 0.14732)
		(layer "In2.Cu")
		(net "P5E_CPU0_PE3_TX_DP<10>")
	)
	(segment
		(start 373.454422 -290.13785)
		(end 373.454422 -290.115752)
		(width 0.0889)
		(layer "In2.Cu")
		(net "P5E_CPU0_PE3_TX_DP<10>")
	)
	(segment
		(start 373.454422 -290.115752)
		(end 373.412258 -290.073588)
		(width 0.0889)
		(layer "In2.Cu")
		(net "P5E_CPU0_PE3_TX_DP<10>")
	)
	(segment
		(start 374.78843 -300.032928)
		(end 373.703342 -298.597574)
		(width 0.14732)
		(layer "In2.Cu")
		(net "P5E_CPU0_PE3_TX_DP<10>")
	)
	(segment
		(start 373.412258 -290.073588)
		(end 373.412258 -289.64636)
		(width 0.0889)
		(layer "In2.Cu")
		(net "P5E_CPU0_PE3_TX_DP<10>")
	)
	(segment
		(start 372.220998 -285.932372)
		(end 372.377462 -285.661354)
		(width 0.0889)
		(layer "In2.Cu")
		(net "P5E_CPU0_PE3_TX_DP<10>")
	)
	(segment
		(start 373.412258 -289.64636)
		(end 373.412512 -289.64636)
		(width 0.0889)
		(layer "In2.Cu")
		(net "P5E_CPU0_PE3_TX_DP<10>")
	)
	(segment
		(start 395.959584 -326.937116)
		(end 375.53519 -300.779434)
		(width 0.14732)
		(layer "In2.Cu")
		(net "P5E_CPU0_PE3_TX_DP<10>")
	)
	(segment
		(start 373.13616 -287.617154)
		(end 373.130064 -287.613598)
		(width 0.0889)
		(layer "In2.Cu")
		(net "P5E_CPU0_PE3_TX_DP<10>")
	)
	(segment
		(start 373.882666 -289.114484)
		(end 373.882666 -288.898584)
		(width 0.0889)
		(layer "In2.Cu")
		(net "P5E_CPU0_PE3_TX_DP<10>")
	)
	(segment
		(start 388.94893 -407.00452)
		(end 388.65429 -406.70988)
		(width 0.14732)
		(layer "In2.Cu")
		(net "P5E_CPU0_PE3_TX_DP<10>")
	)
	(segment
		(start 372.942612 -287.28924)
		(end 372.942612 -287.279334)
		(width 0.0889)
		(layer "In2.Cu")
		(net "P5E_CPU0_PE3_TX_DP<10>")
	)
	(segment
		(start 397.095726 -348.909386)
		(end 397.095726 -333.380588)
		(width 0.14732)
		(layer "In2.Cu")
		(net "P5E_CPU0_PE3_TX_DP<10>")
	)
	(segment
		(start 373.130064 -287.613598)
		(end 373.121174 -287.608518)
		(width 0.0889)
		(layer "In2.Cu")
		(net "P5E_CPU0_PE3_TX_DP<10>")
	)
	(segment
		(start 388.65429 -406.001982)
		(end 388.83971 -404.118572)
		(width 0.14732)
		(layer "In2.Cu")
		(net "P5E_CPU0_PE3_TX_DP<10>")
	)
	(segment
		(start 388.83971 -404.118572)
		(end 388.83971 -399.652744)
		(width 0.14732)
		(layer "In2.Cu")
		(net "P5E_CPU0_PE3_TX_DP<10>")
	)
	(arc
		(start 373.591328 -288.422334)
		(mid 373.460414 -288.285974)
		(end 373.412766 -288.103056)
		(width 0.0889)
		(layer "In2.Cu")
		(net "P5E_CPU0_PE3_TX_DP<10>")
	)
	(arc
		(start 373.882666 -288.898584)
		(mid 373.802504 -288.626395)
		(end 373.600218 -288.427414)
		(width 0.0889)
		(layer "In2.Cu")
		(net "P5E_CPU0_PE3_TX_DP<10>")
	)
	(arc
		(start 373.596916 -289.446462)
		(mid 373.771217 -289.307532)
		(end 373.882666 -289.114484)
		(width 0.0889)
		(layer "In2.Cu")
		(net "P5E_CPU0_PE3_TX_DP<10>")
	)
	(arc
		(start 372.262146 -286.03448)
		(mid 372.253698 -286.027923)
		(end 372.245128 -286.021526)
		(width 0.0889)
		(layer "In2.Cu")
		(net "P5E_CPU0_PE3_TX_DP<10>")
	)
	(arc
		(start 373.121174 -287.608518)
		(mid 372.99026 -287.472158)
		(end 372.942612 -287.28924)
		(width 0.0889)
		(layer "In2.Cu")
		(net "P5E_CPU0_PE3_TX_DP<10>")
	)
	(arc
		(start 373.412766 -288.103056)
		(mid 373.338775 -287.82349)
		(end 373.13616 -287.617154)
		(width 0.0889)
		(layer "In2.Cu")
		(net "P5E_CPU0_PE3_TX_DP<10>")
	)
	(arc
		(start 373.412512 -289.64636)
		(mid 373.487583 -289.530618)
		(end 373.596916 -289.446462)
		(width 0.0889)
		(layer "In2.Cu")
		(net "P5E_CPU0_PE3_TX_DP<10>")
	)
	(arc
		(start 372.660164 -286.799782)
		(mid 372.525231 -286.666428)
		(end 372.472966 -286.48406)
		(width 0.0889)
		(layer "In2.Cu")
		(net "P5E_CPU0_PE3_TX_DP<10>")
	)
	(arc
		(start 372.472966 -286.4612)
		(mid 372.414672 -286.224557)
		(end 372.262146 -286.03448)
		(width 0.0889)
		(layer "In2.Cu")
		(net "P5E_CPU0_PE3_TX_DP<10>")
	)
	(arc
		(start 372.942612 -287.279334)
		(mid 372.864501 -287.002385)
		(end 372.660164 -286.799782)
		(width 0.0889)
		(layer "In2.Cu")
		(net "P5E_CPU0_PE3_TX_DP<10>")
	)
	(segment
		(start 381.305562 -286.47517)
		(end 381.305816 -286.475424)
		(width 0.13208)
		(layer "F.Cu")
		(net "P5E_CPU0_PE3_TX_DP<0>")
	)
	(segment
		(start 418.696902 -408.250644)
		(end 418.69233 -408.250644)
		(width 0.13208)
		(layer "F.Cu")
		(net "P5E_CPU0_PE3_TX_DP<0>")
	)
	(segment
		(start 419.023292 -407.924254)
		(end 418.696902 -408.250644)
		(width 0.13208)
		(layer "F.Cu")
		(net "P5E_CPU0_PE3_TX_DP<0>")
	)
	(segment
		(start 381.305562 -285.939484)
		(end 381.305562 -286.47517)
		(width 0.13208)
		(layer "F.Cu")
		(net "P5E_CPU0_PE3_TX_DP<0>")
	)
	(segment
		(start 418.71773 -407.00452)
		(end 419.023292 -407.310082)
		(width 0.13208)
		(layer "F.Cu")
		(net "P5E_CPU0_PE3_TX_DP<0>")
	)
	(segment
		(start 419.023292 -407.310082)
		(end 419.023292 -407.924254)
		(width 0.13208)
		(layer "F.Cu")
		(net "P5E_CPU0_PE3_TX_DP<0>")
	)
	(segment
		(start 419.19779 -400.520916)
		(end 418.280596 -398.224502)
		(width 0.14732)
		(layer "In2.Cu")
		(net "P5E_CPU0_PE3_TX_DP<0>")
	)
	(segment
		(start 382.441704 -287.783778)
		(end 382.432814 -287.778698)
		(width 0.0889)
		(layer "In2.Cu")
		(net "P5E_CPU0_PE3_TX_DP<0>")
	)
	(segment
		(start 419.01237 -405.988266)
		(end 419.19779 -404.104856)
		(width 0.14732)
		(layer "In2.Cu")
		(net "P5E_CPU0_PE3_TX_DP<0>")
	)
	(segment
		(start 417.956746 -397.749268)
		(end 418.026088 -397.58747)
		(width 0.14732)
		(layer "In2.Cu")
		(net "P5E_CPU0_PE3_TX_DP<0>")
	)
	(segment
		(start 387.330696 -292.802056)
		(end 385.687062 -291.158422)
		(width 0.14732)
		(layer "In2.Cu")
		(net "P5E_CPU0_PE3_TX_DP<0>")
	)
	(segment
		(start 418.026088 -397.58747)
		(end 417.86429 -397.181832)
		(width 0.14732)
		(layer "In2.Cu")
		(net "P5E_CPU0_PE3_TX_DP<0>")
	)
	(segment
		(start 383.383536 -289.412934)
		(end 383.34823 -289.392614)
		(width 0.0889)
		(layer "In2.Cu")
		(net "P5E_CPU0_PE3_TX_DP<0>")
	)
	(segment
		(start 384.070098 -290.06546)
		(end 383.973832 -289.969194)
		(width 0.0889)
		(layer "In2.Cu")
		(net "P5E_CPU0_PE3_TX_DP<0>")
	)
	(segment
		(start 417.540186 -396.706598)
		(end 417.609528 -396.5448)
		(width 0.14732)
		(layer "In2.Cu")
		(net "P5E_CPU0_PE3_TX_DP<0>")
	)
	(segment
		(start 417.609528 -396.5448)
		(end 406.847548 -369.598956)
		(width 0.14732)
		(layer "In2.Cu")
		(net "P5E_CPU0_PE3_TX_DP<0>")
	)
	(segment
		(start 381.46228 -286.204406)
		(end 381.305816 -286.475424)
		(width 0.0889)
		(layer "In2.Cu")
		(net "P5E_CPU0_PE3_TX_DP<0>")
	)
	(segment
		(start 406.847548 -369.598956)
		(end 406.596342 -367.853722)
		(width 0.14732)
		(layer "In2.Cu")
		(net "P5E_CPU0_PE3_TX_DP<0>")
	)
	(segment
		(start 419.01237 -406.70988)
		(end 419.01237 -405.988266)
		(width 0.14732)
		(layer "In2.Cu")
		(net "P5E_CPU0_PE3_TX_DP<0>")
	)
	(segment
		(start 417.86429 -397.181832)
		(end 417.702238 -397.11249)
		(width 0.14732)
		(layer "In2.Cu")
		(net "P5E_CPU0_PE3_TX_DP<0>")
	)
	(segment
		(start 383.532888 -289.528504)
		(end 383.383536 -289.412934)
		(width 0.0889)
		(layer "In2.Cu")
		(net "P5E_CPU0_PE3_TX_DP<0>")
	)
	(segment
		(start 388.63397 -295.948862)
		(end 387.330696 -292.802056)
		(width 0.14732)
		(layer "In2.Cu")
		(net "P5E_CPU0_PE3_TX_DP<0>")
	)
	(segment
		(start 381.680466 -286.490918)
		(end 381.680466 -286.475424)
		(width 0.0889)
		(layer "In2.Cu")
		(net "P5E_CPU0_PE3_TX_DP<0>")
	)
	(segment
		(start 383.090674 -288.95929)
		(end 383.089912 -288.908236)
		(width 0.0889)
		(layer "In2.Cu")
		(net "P5E_CPU0_PE3_TX_DP<0>")
	)
	(segment
		(start 419.19779 -404.104856)
		(end 419.19779 -400.520916)
		(width 0.14732)
		(layer "In2.Cu")
		(net "P5E_CPU0_PE3_TX_DP<0>")
	)
	(segment
		(start 384.070098 -290.124388)
		(end 384.070098 -290.06546)
		(width 0.0889)
		(layer "In2.Cu")
		(net "P5E_CPU0_PE3_TX_DP<0>")
	)
	(segment
		(start 417.702238 -397.11249)
		(end 417.540186 -396.706598)
		(width 0.14732)
		(layer "In2.Cu")
		(net "P5E_CPU0_PE3_TX_DP<0>")
	)
	(segment
		(start 406.596342 -367.853722)
		(end 406.990296 -334.815688)
		(width 0.14732)
		(layer "In2.Cu")
		(net "P5E_CPU0_PE3_TX_DP<0>")
	)
	(segment
		(start 383.973832 -289.969194)
		(end 383.532888 -289.528504)
		(width 0.0889)
		(layer "In2.Cu")
		(net "P5E_CPU0_PE3_TX_DP<0>")
	)
	(segment
		(start 418.280596 -398.224502)
		(end 418.118798 -398.15516)
		(width 0.14732)
		(layer "In2.Cu")
		(net "P5E_CPU0_PE3_TX_DP<0>")
	)
	(segment
		(start 406.990296 -334.815688)
		(end 406.471374 -332.637384)
		(width 0.14732)
		(layer "In2.Cu")
		(net "P5E_CPU0_PE3_TX_DP<0>")
	)
	(segment
		(start 418.71773 -407.00452)
		(end 419.01237 -406.70988)
		(width 0.14732)
		(layer "In2.Cu")
		(net "P5E_CPU0_PE3_TX_DP<0>")
	)
	(segment
		(start 406.471374 -332.637384)
		(end 404.780496 -323.047614)
		(width 0.14732)
		(layer "In2.Cu")
		(net "P5E_CPU0_PE3_TX_DP<0>")
	)
	(segment
		(start 381.540512 -286.183578)
		(end 381.46228 -286.204406)
		(width 0.0889)
		(layer "In2.Cu")
		(net "P5E_CPU0_PE3_TX_DP<0>")
	)
	(segment
		(start 404.780496 -323.047614)
		(end 390.08431 -304.171858)
		(width 0.14732)
		(layer "In2.Cu")
		(net "P5E_CPU0_PE3_TX_DP<0>")
	)
	(segment
		(start 381.97155 -286.969962)
		(end 381.96266 -286.964882)
		(width 0.0889)
		(layer "In2.Cu")
		(net "P5E_CPU0_PE3_TX_DP<0>")
	)
	(segment
		(start 382.432814 -287.778698)
		(end 382.426718 -287.775142)
		(width 0.0889)
		(layer "In2.Cu")
		(net "P5E_CPU0_PE3_TX_DP<0>")
	)
	(segment
		(start 384.69189 -290.74618)
		(end 384.085592 -290.139882)
		(width 0.14732)
		(layer "In2.Cu")
		(net "P5E_CPU0_PE3_TX_DP<0>")
	)
	(segment
		(start 418.118798 -398.15516)
		(end 417.956746 -397.749268)
		(width 0.14732)
		(layer "In2.Cu")
		(net "P5E_CPU0_PE3_TX_DP<0>")
	)
	(segment
		(start 382.620266 -288.112962)
		(end 382.620266 -288.103056)
		(width 0.0889)
		(layer "In2.Cu")
		(net "P5E_CPU0_PE3_TX_DP<0>")
	)
	(segment
		(start 385.687062 -291.158422)
		(end 384.69189 -290.74618)
		(width 0.14732)
		(layer "In2.Cu")
		(net "P5E_CPU0_PE3_TX_DP<0>")
	)
	(segment
		(start 390.08431 -304.171858)
		(end 388.63397 -295.948862)
		(width 0.14732)
		(layer "In2.Cu")
		(net "P5E_CPU0_PE3_TX_DP<0>")
	)
	(segment
		(start 384.085592 -290.139882)
		(end 384.070098 -290.124388)
		(width 0.0889)
		(layer "In2.Cu")
		(net "P5E_CPU0_PE3_TX_DP<0>")
	)
	(arc
		(start 382.426718 -287.775142)
		(mid 382.224131 -287.568791)
		(end 382.150112 -287.28924)
		(width 0.0889)
		(layer "In2.Cu")
		(net "P5E_CPU0_PE3_TX_DP<0>")
	)
	(arc
		(start 383.34823 -289.392614)
		(mid 383.162849 -289.209597)
		(end 383.090674 -288.95929)
		(width 0.0889)
		(layer "In2.Cu")
		(net "P5E_CPU0_PE3_TX_DP<0>")
	)
	(arc
		(start 381.680466 -286.475424)
		(mid 381.643606 -286.313627)
		(end 381.540512 -286.183578)
		(width 0.0889)
		(layer "In2.Cu")
		(net "P5E_CPU0_PE3_TX_DP<0>")
	)
	(arc
		(start 382.150112 -287.28924)
		(mid 382.102433 -287.10634)
		(end 381.97155 -286.969962)
		(width 0.0889)
		(layer "In2.Cu")
		(net "P5E_CPU0_PE3_TX_DP<0>")
	)
	(arc
		(start 381.96266 -286.964882)
		(mid 381.759837 -286.764651)
		(end 381.680466 -286.490918)
		(width 0.0889)
		(layer "In2.Cu")
		(net "P5E_CPU0_PE3_TX_DP<0>")
	)
	(arc
		(start 383.089912 -288.908236)
		(mid 383.037642 -288.725871)
		(end 382.902714 -288.592514)
		(width 0.0889)
		(layer "In2.Cu")
		(net "P5E_CPU0_PE3_TX_DP<0>")
	)
	(arc
		(start 382.902714 -288.592514)
		(mid 382.698379 -288.389909)
		(end 382.620266 -288.112962)
		(width 0.0889)
		(layer "In2.Cu")
		(net "P5E_CPU0_PE3_TX_DP<0>")
	)
	(arc
		(start 382.620266 -288.103056)
		(mid 382.572587 -287.920156)
		(end 382.441704 -287.783778)
		(width 0.0889)
		(layer "In2.Cu")
		(net "P5E_CPU0_PE3_TX_DP<0>")
	)
	(segment
		(start 391.127742 -408.250644)
		(end 391.12317 -408.250644)
		(width 0.13208)
		(layer "F.Cu")
		(net "P5E_CPU0_PE3_TX_DN<9>")
	)
	(segment
		(start 391.454132 -407.310082)
		(end 391.454132 -407.924254)
		(width 0.13208)
		(layer "F.Cu")
		(net "P5E_CPU0_PE3_TX_DN<9>")
	)
	(segment
		(start 391.14857 -407.00452)
		(end 391.454132 -407.310082)
		(width 0.13208)
		(layer "F.Cu")
		(net "P5E_CPU0_PE3_TX_DN<9>")
	)
	(segment
		(start 372.847362 -284.311598)
		(end 372.847616 -284.847538)
		(width 0.13208)
		(layer "F.Cu")
		(net "P5E_CPU0_PE3_TX_DN<9>")
	)
	(segment
		(start 391.454132 -407.924254)
		(end 391.127742 -408.250644)
		(width 0.13208)
		(layer "F.Cu")
		(net "P5E_CPU0_PE3_TX_DN<9>")
	)
	(segment
		(start 374.120156 -290.286948)
		(end 374.120156 -290.13785)
		(width 0.14732)
		(layer "In2.Cu")
		(net "P5E_CPU0_PE3_TX_DN<9>")
	)
	(segment
		(start 373.04345 -286.156146)
		(end 373.03456 -286.151066)
		(width 0.0889)
		(layer "In2.Cu")
		(net "P5E_CPU0_PE3_TX_DN<9>")
	)
	(segment
		(start 375.714514 -300.016672)
		(end 374.341136 -298.200064)
		(width 0.14732)
		(layer "In2.Cu")
		(net "P5E_CPU0_PE3_TX_DN<9>")
	)
	(segment
		(start 373.983504 -287.783778)
		(end 373.968518 -287.775142)
		(width 0.0889)
		(layer "In2.Cu")
		(net "P5E_CPU0_PE3_TX_DN<9>")
	)
	(segment
		(start 396.591536 -326.664066)
		(end 376.035062 -300.33722)
		(width 0.14732)
		(layer "In2.Cu")
		(net "P5E_CPU0_PE3_TX_DN<9>")
	)
	(segment
		(start 397.761714 -349.02267)
		(end 397.761714 -333.300578)
		(width 0.14732)
		(layer "In2.Cu")
		(net "P5E_CPU0_PE3_TX_DN<9>")
	)
	(segment
		(start 391.14857 -407.00452)
		(end 391.44321 -406.70988)
		(width 0.14732)
		(layer "In2.Cu")
		(net "P5E_CPU0_PE3_TX_DN<9>")
	)
	(segment
		(start 374.162066 -288.121598)
		(end 374.162066 -288.103056)
		(width 0.0889)
		(layer "In2.Cu")
		(net "P5E_CPU0_PE3_TX_DN<9>")
	)
	(segment
		(start 374.162066 -290.073842)
		(end 374.162066 -289.610038)
		(width 0.0889)
		(layer "In2.Cu")
		(net "P5E_CPU0_PE3_TX_DN<9>")
	)
	(segment
		(start 372.97995 -285.20771)
		(end 373.00408 -285.118556)
		(width 0.0889)
		(layer "In2.Cu")
		(net "P5E_CPU0_PE3_TX_DN<9>")
	)
	(segment
		(start 391.62863 -398.940528)
		(end 397.761714 -349.02267)
		(width 0.14732)
		(layer "In2.Cu")
		(net "P5E_CPU0_PE3_TX_DN<9>")
	)
	(segment
		(start 391.62863 -404.104856)
		(end 391.62863 -398.940528)
		(width 0.14732)
		(layer "In2.Cu")
		(net "P5E_CPU0_PE3_TX_DN<9>")
	)
	(segment
		(start 397.761714 -333.300578)
		(end 396.591282 -326.663812)
		(width 0.14732)
		(layer "In2.Cu")
		(net "P5E_CPU0_PE3_TX_DN<9>")
	)
	(segment
		(start 374.453404 -288.597848)
		(end 374.444514 -288.592768)
		(width 0.0889)
		(layer "In2.Cu")
		(net "P5E_CPU0_PE3_TX_DN<9>")
	)
	(segment
		(start 373.51335 -286.969962)
		(end 373.50446 -286.964882)
		(width 0.0889)
		(layer "In2.Cu")
		(net "P5E_CPU0_PE3_TX_DN<9>")
	)
	(segment
		(start 374.341136 -298.200064)
		(end 374.12422 -296.875454)
		(width 0.14732)
		(layer "In2.Cu")
		(net "P5E_CPU0_PE3_TX_DN<9>")
	)
	(segment
		(start 373.50446 -286.964882)
		(end 373.498364 -286.961326)
		(width 0.0889)
		(layer "In2.Cu")
		(net "P5E_CPU0_PE3_TX_DN<9>")
	)
	(segment
		(start 374.120156 -290.13785)
		(end 374.120156 -290.115752)
		(width 0.0889)
		(layer "In2.Cu")
		(net "P5E_CPU0_PE3_TX_DN<9>")
	)
	(segment
		(start 396.591282 -326.663812)
		(end 396.591536 -326.664066)
		(width 0.14732)
		(layer "In2.Cu")
		(net "P5E_CPU0_PE3_TX_DN<9>")
	)
	(segment
		(start 391.44321 -406.70988)
		(end 391.44321 -405.988266)
		(width 0.14732)
		(layer "In2.Cu")
		(net "P5E_CPU0_PE3_TX_DN<9>")
	)
	(segment
		(start 374.120156 -290.115752)
		(end 374.162066 -290.073842)
		(width 0.0889)
		(layer "In2.Cu")
		(net "P5E_CPU0_PE3_TX_DN<9>")
	)
	(segment
		(start 373.00408 -285.118556)
		(end 372.847616 -284.847538)
		(width 0.0889)
		(layer "In2.Cu")
		(net "P5E_CPU0_PE3_TX_DN<9>")
	)
	(segment
		(start 374.12422 -296.875454)
		(end 374.120156 -290.286948)
		(width 0.14732)
		(layer "In2.Cu")
		(net "P5E_CPU0_PE3_TX_DN<9>")
	)
	(segment
		(start 374.631966 -289.077908)
		(end 374.631966 -288.917126)
		(width 0.0889)
		(layer "In2.Cu")
		(net "P5E_CPU0_PE3_TX_DN<9>")
	)
	(segment
		(start 376.035062 -300.33722)
		(end 375.714514 -300.016672)
		(width 0.14732)
		(layer "In2.Cu")
		(net "P5E_CPU0_PE3_TX_DN<9>")
	)
	(segment
		(start 391.44321 -405.988266)
		(end 391.62863 -404.104856)
		(width 0.14732)
		(layer "In2.Cu")
		(net "P5E_CPU0_PE3_TX_DN<9>")
	)
	(segment
		(start 374.162066 -289.610038)
		(end 374.161812 -289.609784)
		(width 0.0889)
		(layer "In2.Cu")
		(net "P5E_CPU0_PE3_TX_DN<9>")
	)
	(arc
		(start 374.176798 -289.570922)
		(mid 374.287055 -289.401162)
		(end 374.447562 -289.277806)
		(width 0.0889)
		(layer "In2.Cu")
		(net "P5E_CPU0_PE3_TX_DN<9>")
	)
	(arc
		(start 373.968518 -287.775142)
		(mid 373.765931 -287.568791)
		(end 373.691912 -287.28924)
		(width 0.0889)
		(layer "In2.Cu")
		(net "P5E_CPU0_PE3_TX_DN<9>")
	)
	(arc
		(start 372.962932 -285.220918)
		(mid 372.971378 -285.214233)
		(end 372.97995 -285.20771)
		(width 0.0889)
		(layer "In2.Cu")
		(net "P5E_CPU0_PE3_TX_DN<9>")
	)
	(arc
		(start 374.447562 -289.277806)
		(mid 374.556958 -289.193709)
		(end 374.631966 -289.077908)
		(width 0.0889)
		(layer "In2.Cu")
		(net "P5E_CPU0_PE3_TX_DN<9>")
	)
	(arc
		(start 373.498364 -286.961326)
		(mid 373.295951 -286.754913)
		(end 373.222012 -286.475424)
		(width 0.0889)
		(layer "In2.Cu")
		(net "P5E_CPU0_PE3_TX_DN<9>")
	)
	(arc
		(start 373.691912 -287.28924)
		(mid 373.644233 -287.10634)
		(end 373.51335 -286.969962)
		(width 0.0889)
		(layer "In2.Cu")
		(net "P5E_CPU0_PE3_TX_DN<9>")
	)
	(arc
		(start 373.222012 -286.475424)
		(mid 373.174333 -286.292524)
		(end 373.04345 -286.156146)
		(width 0.0889)
		(layer "In2.Cu")
		(net "P5E_CPU0_PE3_TX_DN<9>")
	)
	(arc
		(start 374.161812 -289.609784)
		(mid 374.168968 -289.590223)
		(end 374.176798 -289.570922)
		(width 0.0889)
		(layer "In2.Cu")
		(net "P5E_CPU0_PE3_TX_DN<9>")
	)
	(arc
		(start 374.631966 -288.917126)
		(mid 374.584287 -288.734226)
		(end 374.453404 -288.597848)
		(width 0.0889)
		(layer "In2.Cu")
		(net "P5E_CPU0_PE3_TX_DN<9>")
	)
	(arc
		(start 374.162066 -288.103056)
		(mid 374.114387 -287.920156)
		(end 373.983504 -287.783778)
		(width 0.0889)
		(layer "In2.Cu")
		(net "P5E_CPU0_PE3_TX_DN<9>")
	)
	(arc
		(start 374.444514 -288.592768)
		(mid 374.242228 -288.393787)
		(end 374.162066 -288.121598)
		(width 0.0889)
		(layer "In2.Cu")
		(net "P5E_CPU0_PE3_TX_DN<9>")
	)
	(arc
		(start 373.03456 -286.151066)
		(mid 372.753482 -285.704831)
		(end 372.962932 -285.220918)
		(width 0.0889)
		(layer "In2.Cu")
		(net "P5E_CPU0_PE3_TX_DN<9>")
	)
	(segment
		(start 394.21181 -407.00452)
		(end 394.517372 -407.310082)
		(width 0.13208)
		(layer "F.Cu")
		(net "P5E_CPU0_PE3_TX_DN<8>")
	)
	(segment
		(start 373.787162 -286.47517)
		(end 373.787416 -286.475424)
		(width 0.13208)
		(layer "F.Cu")
		(net "P5E_CPU0_PE3_TX_DN<8>")
	)
	(segment
		(start 394.517372 -407.924254)
		(end 394.190982 -408.250644)
		(width 0.13208)
		(layer "F.Cu")
		(net "P5E_CPU0_PE3_TX_DN<8>")
	)
	(segment
		(start 394.517372 -407.310082)
		(end 394.517372 -407.924254)
		(width 0.13208)
		(layer "F.Cu")
		(net "P5E_CPU0_PE3_TX_DN<8>")
	)
	(segment
		(start 394.190982 -408.250644)
		(end 394.18641 -408.250644)
		(width 0.13208)
		(layer "F.Cu")
		(net "P5E_CPU0_PE3_TX_DN<8>")
	)
	(segment
		(start 373.787162 -285.939484)
		(end 373.787162 -286.47517)
		(width 0.13208)
		(layer "F.Cu")
		(net "P5E_CPU0_PE3_TX_DN<8>")
	)
	(segment
		(start 394.768324 -397.149574)
		(end 394.767816 -397.149574)
		(width 0.14732)
		(layer "In2.Cu")
		(net "P5E_CPU0_PE3_TX_DN<8>")
	)
	(segment
		(start 374.631712 -287.28924)
		(end 374.631712 -287.281366)
		(width 0.0889)
		(layer "In2.Cu")
		(net "P5E_CPU0_PE3_TX_DN<8>")
	)
	(segment
		(start 377.289568 -300.311312)
		(end 375.32183 -297.502072)
		(width 0.14732)
		(layer "In2.Cu")
		(net "P5E_CPU0_PE3_TX_DN<8>")
	)
	(segment
		(start 375.059702 -290.139882)
		(end 375.059702 -290.117784)
		(width 0.0889)
		(layer "In2.Cu")
		(net "P5E_CPU0_PE3_TX_DN<8>")
	)
	(segment
		(start 375.32183 -297.502072)
		(end 375.059702 -296.017188)
		(width 0.14732)
		(layer "In2.Cu")
		(net "P5E_CPU0_PE3_TX_DN<8>")
	)
	(segment
		(start 398.717516 -349.180658)
		(end 398.717516 -332.60919)
		(width 0.14732)
		(layer "In2.Cu")
		(net "P5E_CPU0_PE3_TX_DN<8>")
	)
	(segment
		(start 375.384822 -288.592768)
		(end 375.3739 -288.586672)
		(width 0.0889)
		(layer "In2.Cu")
		(net "P5E_CPU0_PE3_TX_DN<8>")
	)
	(segment
		(start 394.69187 -398.07388)
		(end 394.713968 -397.805402)
		(width 0.14732)
		(layer "In2.Cu")
		(net "P5E_CPU0_PE3_TX_DN<8>")
	)
	(segment
		(start 394.50645 -406.70988)
		(end 394.50645 -405.988266)
		(width 0.14732)
		(layer "In2.Cu")
		(net "P5E_CPU0_PE3_TX_DN<8>")
	)
	(segment
		(start 374.022112 -286.18307)
		(end 374.021858 -286.183578)
		(width 0.0889)
		(layer "In2.Cu")
		(net "P5E_CPU0_PE3_TX_DN<8>")
	)
	(segment
		(start 374.923304 -287.783778)
		(end 374.916192 -287.779714)
		(width 0.0889)
		(layer "In2.Cu")
		(net "P5E_CPU0_PE3_TX_DN<8>")
	)
	(segment
		(start 394.61186 -397.281908)
		(end 394.768324 -397.149574)
		(width 0.14732)
		(layer "In2.Cu")
		(net "P5E_CPU0_PE3_TX_DN<8>")
	)
	(segment
		(start 394.21181 -407.00452)
		(end 394.50645 -406.70988)
		(width 0.14732)
		(layer "In2.Cu")
		(net "P5E_CPU0_PE3_TX_DN<8>")
	)
	(segment
		(start 375.059702 -290.117784)
		(end 375.101612 -290.075874)
		(width 0.0889)
		(layer "In2.Cu")
		(net "P5E_CPU0_PE3_TX_DN<8>")
	)
	(segment
		(start 375.101612 -290.075874)
		(end 375.101612 -289.75304)
		(width 0.0889)
		(layer "In2.Cu")
		(net "P5E_CPU0_PE3_TX_DN<8>")
	)
	(segment
		(start 397.608552 -326.32142)
		(end 377.289568 -300.311312)
		(width 0.14732)
		(layer "In2.Cu")
		(net "P5E_CPU0_PE3_TX_DN<8>")
	)
	(segment
		(start 394.767816 -397.149574)
		(end 394.80363 -396.714218)
		(width 0.14732)
		(layer "In2.Cu")
		(net "P5E_CPU0_PE3_TX_DN<8>")
	)
	(segment
		(start 394.581634 -397.649446)
		(end 394.61186 -397.281908)
		(width 0.14732)
		(layer "In2.Cu")
		(net "P5E_CPU0_PE3_TX_DN<8>")
	)
	(segment
		(start 375.059702 -296.017188)
		(end 375.059702 -290.139882)
		(width 0.14732)
		(layer "In2.Cu")
		(net "P5E_CPU0_PE3_TX_DN<8>")
	)
	(segment
		(start 394.713968 -397.805402)
		(end 394.581634 -397.649446)
		(width 0.14732)
		(layer "In2.Cu")
		(net "P5E_CPU0_PE3_TX_DN<8>")
	)
	(segment
		(start 374.916192 -287.779714)
		(end 374.915176 -287.779206)
		(width 0.0889)
		(layer "In2.Cu")
		(net "P5E_CPU0_PE3_TX_DN<8>")
	)
	(segment
		(start 375.57202 -289.078924)
		(end 375.57202 -288.90849)
		(width 0.0889)
		(layer "In2.Cu")
		(net "P5E_CPU0_PE3_TX_DN<8>")
	)
	(segment
		(start 394.80363 -396.714218)
		(end 394.689838 -396.580106)
		(width 0.14732)
		(layer "In2.Cu")
		(net "P5E_CPU0_PE3_TX_DN<8>")
	)
	(segment
		(start 374.913652 -287.77819)
		(end 374.908318 -287.775142)
		(width 0.0889)
		(layer "In2.Cu")
		(net "P5E_CPU0_PE3_TX_DN<8>")
	)
	(segment
		(start 394.689838 -396.580106)
		(end 394.725652 -396.144496)
		(width 0.14732)
		(layer "In2.Cu")
		(net "P5E_CPU0_PE3_TX_DN<8>")
	)
	(segment
		(start 394.69187 -404.104856)
		(end 394.69187 -398.07388)
		(width 0.14732)
		(layer "In2.Cu")
		(net "P5E_CPU0_PE3_TX_DN<8>")
	)
	(segment
		(start 394.860018 -396.03045)
		(end 398.717516 -349.180658)
		(width 0.14732)
		(layer "In2.Cu")
		(net "P5E_CPU0_PE3_TX_DN<8>")
	)
	(segment
		(start 374.162066 -286.486092)
		(end 374.162066 -286.463994)
		(width 0.0889)
		(layer "In2.Cu")
		(net "P5E_CPU0_PE3_TX_DN<8>")
	)
	(segment
		(start 375.57202 -288.90849)
		(end 375.571766 -288.90214)
		(width 0.0889)
		(layer "In2.Cu")
		(net "P5E_CPU0_PE3_TX_DN<8>")
	)
	(segment
		(start 394.50645 -405.988266)
		(end 394.69187 -404.104856)
		(width 0.14732)
		(layer "In2.Cu")
		(net "P5E_CPU0_PE3_TX_DN<8>")
	)
	(segment
		(start 374.021858 -286.183578)
		(end 373.94388 -286.204406)
		(width 0.0889)
		(layer "In2.Cu")
		(net "P5E_CPU0_PE3_TX_DN<8>")
	)
	(segment
		(start 394.725652 -396.144496)
		(end 394.860018 -396.03045)
		(width 0.14732)
		(layer "In2.Cu")
		(net "P5E_CPU0_PE3_TX_DN<8>")
	)
	(segment
		(start 373.94388 -286.204406)
		(end 373.787416 -286.475424)
		(width 0.0889)
		(layer "In2.Cu")
		(net "P5E_CPU0_PE3_TX_DN<8>")
	)
	(segment
		(start 374.915176 -287.779206)
		(end 374.913652 -287.77819)
		(width 0.0889)
		(layer "In2.Cu")
		(net "P5E_CPU0_PE3_TX_DN<8>")
	)
	(segment
		(start 398.717516 -332.60919)
		(end 397.608552 -326.32142)
		(width 0.14732)
		(layer "In2.Cu")
		(net "P5E_CPU0_PE3_TX_DN<8>")
	)
	(arc
		(start 374.162066 -286.463994)
		(mid 374.122873 -286.308206)
		(end 374.022112 -286.18307)
		(width 0.0889)
		(layer "In2.Cu")
		(net "P5E_CPU0_PE3_TX_DN<8>")
	)
	(arc
		(start 375.571766 -288.90214)
		(mid 375.518028 -288.723446)
		(end 375.384822 -288.592768)
		(width 0.0889)
		(layer "In2.Cu")
		(net "P5E_CPU0_PE3_TX_DN<8>")
	)
	(arc
		(start 375.101866 -288.103056)
		(mid 375.054187 -287.920156)
		(end 374.923304 -287.783778)
		(width 0.0889)
		(layer "In2.Cu")
		(net "P5E_CPU0_PE3_TX_DN<8>")
	)
	(arc
		(start 374.444514 -286.964882)
		(mid 374.240285 -286.762638)
		(end 374.162066 -286.486092)
		(width 0.0889)
		(layer "In2.Cu")
		(net "P5E_CPU0_PE3_TX_DN<8>")
	)
	(arc
		(start 374.631712 -287.281366)
		(mid 374.579644 -287.098543)
		(end 374.444514 -286.964882)
		(width 0.0889)
		(layer "In2.Cu")
		(net "P5E_CPU0_PE3_TX_DN<8>")
	)
	(arc
		(start 375.3739 -288.586672)
		(mid 375.174469 -288.380531)
		(end 375.101866 -288.103056)
		(width 0.0889)
		(layer "In2.Cu")
		(net "P5E_CPU0_PE3_TX_DN<8>")
	)
	(arc
		(start 375.387616 -289.27806)
		(mid 375.496866 -289.194275)
		(end 375.57202 -289.078924)
		(width 0.0889)
		(layer "In2.Cu")
		(net "P5E_CPU0_PE3_TX_DN<8>")
	)
	(arc
		(start 374.908318 -287.775142)
		(mid 374.705731 -287.568791)
		(end 374.631712 -287.28924)
		(width 0.0889)
		(layer "In2.Cu")
		(net "P5E_CPU0_PE3_TX_DN<8>")
	)
	(arc
		(start 375.101612 -289.75304)
		(mid 375.178521 -289.475763)
		(end 375.387616 -289.27806)
		(width 0.0889)
		(layer "In2.Cu")
		(net "P5E_CPU0_PE3_TX_DN<8>")
	)
	(segment
		(start 397.254222 -408.250644)
		(end 397.24965 -408.250644)
		(width 0.13208)
		(layer "F.Cu")
		(net "P5E_CPU0_PE3_TX_DN<7>")
	)
	(segment
		(start 374.726962 -284.311598)
		(end 374.727216 -284.847538)
		(width 0.13208)
		(layer "F.Cu")
		(net "P5E_CPU0_PE3_TX_DN<7>")
	)
	(segment
		(start 397.580612 -407.924254)
		(end 397.254222 -408.250644)
		(width 0.13208)
		(layer "F.Cu")
		(net "P5E_CPU0_PE3_TX_DN<7>")
	)
	(segment
		(start 397.27505 -407.00452)
		(end 397.580612 -407.310082)
		(width 0.13208)
		(layer "F.Cu")
		(net "P5E_CPU0_PE3_TX_DN<7>")
	)
	(segment
		(start 397.580612 -407.310082)
		(end 397.580612 -407.924254)
		(width 0.13208)
		(layer "F.Cu")
		(net "P5E_CPU0_PE3_TX_DN<7>")
	)
	(segment
		(start 399.48739 -368.336576)
		(end 399.849848 -335.336642)
		(width 0.14732)
		(layer "In2.Cu")
		(net "P5E_CPU0_PE3_TX_DN<7>")
	)
	(segment
		(start 375.863104 -287.783778)
		(end 375.855992 -287.779714)
		(width 0.0889)
		(layer "In2.Cu")
		(net "P5E_CPU0_PE3_TX_DN<7>")
	)
	(segment
		(start 376.320558 -297.28922)
		(end 375.999502 -295.470072)
		(width 0.14732)
		(layer "In2.Cu")
		(net "P5E_CPU0_PE3_TX_DN<7>")
	)
	(segment
		(start 375.999502 -290.117784)
		(end 376.041412 -290.075874)
		(width 0.0889)
		(layer "In2.Cu")
		(net "P5E_CPU0_PE3_TX_DN<7>")
	)
	(segment
		(start 375.999502 -295.470072)
		(end 375.999502 -290.139882)
		(width 0.14732)
		(layer "In2.Cu")
		(net "P5E_CPU0_PE3_TX_DN<7>")
	)
	(segment
		(start 374.85955 -285.20771)
		(end 374.88368 -285.118556)
		(width 0.0889)
		(layer "In2.Cu")
		(net "P5E_CPU0_PE3_TX_DN<7>")
	)
	(segment
		(start 378.041154 -299.746162)
		(end 376.320558 -297.28922)
		(width 0.14732)
		(layer "In2.Cu")
		(net "P5E_CPU0_PE3_TX_DN<7>")
	)
	(segment
		(start 376.041412 -290.075874)
		(end 376.041412 -289.707066)
		(width 0.0889)
		(layer "In2.Cu")
		(net "P5E_CPU0_PE3_TX_DN<7>")
	)
	(segment
		(start 399.849848 -335.336642)
		(end 399.772124 -333.177388)
		(width 0.14732)
		(layer "In2.Cu")
		(net "P5E_CPU0_PE3_TX_DN<7>")
	)
	(segment
		(start 397.56969 -405.988266)
		(end 397.75511 -404.104856)
		(width 0.14732)
		(layer "In2.Cu")
		(net "P5E_CPU0_PE3_TX_DN<7>")
	)
	(segment
		(start 374.88368 -285.118556)
		(end 374.727216 -284.847538)
		(width 0.0889)
		(layer "In2.Cu")
		(net "P5E_CPU0_PE3_TX_DN<7>")
	)
	(segment
		(start 376.333004 -288.597848)
		(end 376.324114 -288.592768)
		(width 0.0889)
		(layer "In2.Cu")
		(net "P5E_CPU0_PE3_TX_DN<7>")
	)
	(segment
		(start 397.27505 -407.00452)
		(end 397.56969 -406.70988)
		(width 0.14732)
		(layer "In2.Cu")
		(net "P5E_CPU0_PE3_TX_DN<7>")
	)
	(segment
		(start 375.855992 -287.779714)
		(end 375.854976 -287.779206)
		(width 0.0889)
		(layer "In2.Cu")
		(net "P5E_CPU0_PE3_TX_DN<7>")
	)
	(segment
		(start 375.999502 -290.139882)
		(end 375.999502 -290.117784)
		(width 0.0889)
		(layer "In2.Cu")
		(net "P5E_CPU0_PE3_TX_DN<7>")
	)
	(segment
		(start 397.75511 -404.104856)
		(end 397.75511 -396.959074)
		(width 0.14732)
		(layer "In2.Cu")
		(net "P5E_CPU0_PE3_TX_DN<7>")
	)
	(segment
		(start 376.511566 -289.038284)
		(end 376.511566 -288.917126)
		(width 0.0889)
		(layer "In2.Cu")
		(net "P5E_CPU0_PE3_TX_DN<7>")
	)
	(segment
		(start 398.493488 -325.927466)
		(end 378.041154 -299.746162)
		(width 0.14732)
		(layer "In2.Cu")
		(net "P5E_CPU0_PE3_TX_DN<7>")
	)
	(segment
		(start 374.92305 -286.156146)
		(end 374.91416 -286.151066)
		(width 0.0889)
		(layer "In2.Cu")
		(net "P5E_CPU0_PE3_TX_DN<7>")
	)
	(segment
		(start 375.853452 -287.77819)
		(end 375.848118 -287.775142)
		(width 0.0889)
		(layer "In2.Cu")
		(net "P5E_CPU0_PE3_TX_DN<7>")
	)
	(segment
		(start 376.041666 -288.121598)
		(end 376.041666 -288.103056)
		(width 0.0889)
		(layer "In2.Cu")
		(net "P5E_CPU0_PE3_TX_DN<7>")
	)
	(segment
		(start 375.38406 -286.964882)
		(end 375.377964 -286.961326)
		(width 0.0889)
		(layer "In2.Cu")
		(net "P5E_CPU0_PE3_TX_DN<7>")
	)
	(segment
		(start 375.39295 -286.969962)
		(end 375.38406 -286.964882)
		(width 0.0889)
		(layer "In2.Cu")
		(net "P5E_CPU0_PE3_TX_DN<7>")
	)
	(segment
		(start 375.854976 -287.779206)
		(end 375.853452 -287.77819)
		(width 0.0889)
		(layer "In2.Cu")
		(net "P5E_CPU0_PE3_TX_DN<7>")
	)
	(segment
		(start 399.772124 -333.177388)
		(end 398.493488 -325.927466)
		(width 0.14732)
		(layer "In2.Cu")
		(net "P5E_CPU0_PE3_TX_DN<7>")
	)
	(segment
		(start 397.56969 -406.70988)
		(end 397.56969 -405.988266)
		(width 0.14732)
		(layer "In2.Cu")
		(net "P5E_CPU0_PE3_TX_DN<7>")
	)
	(segment
		(start 397.75511 -396.959074)
		(end 399.48739 -368.336576)
		(width 0.14732)
		(layer "In2.Cu")
		(net "P5E_CPU0_PE3_TX_DN<7>")
	)
	(arc
		(start 374.91416 -286.151066)
		(mid 374.633082 -285.704831)
		(end 374.842532 -285.220918)
		(width 0.0889)
		(layer "In2.Cu")
		(net "P5E_CPU0_PE3_TX_DN<7>")
	)
	(arc
		(start 376.100594 -289.515042)
		(mid 376.218846 -289.373396)
		(end 376.362214 -289.257232)
		(width 0.0889)
		(layer "In2.Cu")
		(net "P5E_CPU0_PE3_TX_DN<7>")
	)
	(arc
		(start 375.571512 -287.28924)
		(mid 375.523833 -287.10634)
		(end 375.39295 -286.969962)
		(width 0.0889)
		(layer "In2.Cu")
		(net "P5E_CPU0_PE3_TX_DN<7>")
	)
	(arc
		(start 376.041412 -289.707066)
		(mid 376.056494 -289.606578)
		(end 376.100594 -289.515042)
		(width 0.0889)
		(layer "In2.Cu")
		(net "P5E_CPU0_PE3_TX_DN<7>")
	)
	(arc
		(start 375.848118 -287.775142)
		(mid 375.645531 -287.568791)
		(end 375.571512 -287.28924)
		(width 0.0889)
		(layer "In2.Cu")
		(net "P5E_CPU0_PE3_TX_DN<7>")
	)
	(arc
		(start 376.041666 -288.103056)
		(mid 375.993987 -287.920156)
		(end 375.863104 -287.783778)
		(width 0.0889)
		(layer "In2.Cu")
		(net "P5E_CPU0_PE3_TX_DN<7>")
	)
	(arc
		(start 376.324114 -288.592768)
		(mid 376.121828 -288.393787)
		(end 376.041666 -288.121598)
		(width 0.0889)
		(layer "In2.Cu")
		(net "P5E_CPU0_PE3_TX_DN<7>")
	)
	(arc
		(start 375.377964 -286.961326)
		(mid 375.175551 -286.754913)
		(end 375.101612 -286.475424)
		(width 0.0889)
		(layer "In2.Cu")
		(net "P5E_CPU0_PE3_TX_DN<7>")
	)
	(arc
		(start 375.101612 -286.475424)
		(mid 375.053933 -286.292524)
		(end 374.92305 -286.156146)
		(width 0.0889)
		(layer "In2.Cu")
		(net "P5E_CPU0_PE3_TX_DN<7>")
	)
	(arc
		(start 376.362214 -289.257232)
		(mid 376.432871 -289.197978)
		(end 376.488452 -289.12439)
		(width 0.0889)
		(layer "In2.Cu")
		(net "P5E_CPU0_PE3_TX_DN<7>")
	)
	(arc
		(start 376.488452 -289.12439)
		(mid 376.505794 -289.082892)
		(end 376.511566 -289.038284)
		(width 0.0889)
		(layer "In2.Cu")
		(net "P5E_CPU0_PE3_TX_DN<7>")
	)
	(arc
		(start 376.511566 -288.917126)
		(mid 376.463887 -288.734226)
		(end 376.333004 -288.597848)
		(width 0.0889)
		(layer "In2.Cu")
		(net "P5E_CPU0_PE3_TX_DN<7>")
	)
	(arc
		(start 374.842532 -285.220918)
		(mid 374.850978 -285.214233)
		(end 374.85955 -285.20771)
		(width 0.0889)
		(layer "In2.Cu")
		(net "P5E_CPU0_PE3_TX_DN<7>")
	)
	(segment
		(start 400.643852 -407.924254)
		(end 400.317462 -408.250644)
		(width 0.13208)
		(layer "F.Cu")
		(net "P5E_CPU0_PE3_TX_DN<6>")
	)
	(segment
		(start 375.666762 -286.47517)
		(end 375.667016 -286.475424)
		(width 0.13208)
		(layer "F.Cu")
		(net "P5E_CPU0_PE3_TX_DN<6>")
	)
	(segment
		(start 400.33829 -407.00452)
		(end 400.643852 -407.310082)
		(width 0.13208)
		(layer "F.Cu")
		(net "P5E_CPU0_PE3_TX_DN<6>")
	)
	(segment
		(start 375.666762 -285.939484)
		(end 375.666762 -286.47517)
		(width 0.13208)
		(layer "F.Cu")
		(net "P5E_CPU0_PE3_TX_DN<6>")
	)
	(segment
		(start 400.643852 -407.310082)
		(end 400.643852 -407.924254)
		(width 0.13208)
		(layer "F.Cu")
		(net "P5E_CPU0_PE3_TX_DN<6>")
	)
	(segment
		(start 400.317462 -408.250644)
		(end 400.31289 -408.250644)
		(width 0.13208)
		(layer "F.Cu")
		(net "P5E_CPU0_PE3_TX_DN<6>")
	)
	(segment
		(start 377.451366 -289.077908)
		(end 377.451366 -288.917126)
		(width 0.0889)
		(layer "In2.Cu")
		(net "P5E_CPU0_PE3_TX_DN<6>")
	)
	(segment
		(start 400.81835 -400.011646)
		(end 400.811746 -399.235422)
		(width 0.14732)
		(layer "In2.Cu")
		(net "P5E_CPU0_PE3_TX_DN<6>")
	)
	(segment
		(start 376.939556 -295.38168)
		(end 376.939556 -290.139882)
		(width 0.14732)
		(layer "In2.Cu")
		(net "P5E_CPU0_PE3_TX_DN<6>")
	)
	(segment
		(start 400.672554 -397.552164)
		(end 400.795998 -397.426688)
		(width 0.14732)
		(layer "In2.Cu")
		(net "P5E_CPU0_PE3_TX_DN<6>")
	)
	(segment
		(start 376.939556 -290.139882)
		(end 376.939556 -290.117784)
		(width 0.0889)
		(layer "In2.Cu")
		(net "P5E_CPU0_PE3_TX_DN<6>")
	)
	(segment
		(start 376.981466 -288.121598)
		(end 376.981466 -288.103056)
		(width 0.0889)
		(layer "In2.Cu")
		(net "P5E_CPU0_PE3_TX_DN<6>")
	)
	(segment
		(start 377.272804 -288.597848)
		(end 377.263914 -288.592768)
		(width 0.0889)
		(layer "In2.Cu")
		(net "P5E_CPU0_PE3_TX_DN<6>")
	)
	(segment
		(start 400.63293 -405.988266)
		(end 400.81835 -404.104856)
		(width 0.14732)
		(layer "In2.Cu")
		(net "P5E_CPU0_PE3_TX_DN<6>")
	)
	(segment
		(start 400.887438 -334.783938)
		(end 400.886676 -334.776826)
		(width 0.14732)
		(layer "In2.Cu")
		(net "P5E_CPU0_PE3_TX_DN<6>")
	)
	(segment
		(start 400.900646 -335.042764)
		(end 400.887438 -334.783938)
		(width 0.14732)
		(layer "In2.Cu")
		(net "P5E_CPU0_PE3_TX_DN<6>")
	)
	(segment
		(start 376.33275 -286.969962)
		(end 376.32386 -286.964882)
		(width 0.0889)
		(layer "In2.Cu")
		(net "P5E_CPU0_PE3_TX_DN<6>")
	)
	(segment
		(start 400.886676 -334.776826)
		(end 400.886422 -334.776318)
		(width 0.14732)
		(layer "In2.Cu")
		(net "P5E_CPU0_PE3_TX_DN<6>")
	)
	(segment
		(start 378.780802 -299.166026)
		(end 377.578874 -297.42892)
		(width 0.14732)
		(layer "In2.Cu")
		(net "P5E_CPU0_PE3_TX_DN<6>")
	)
	(segment
		(start 376.939556 -290.117784)
		(end 376.981466 -290.075874)
		(width 0.0889)
		(layer "In2.Cu")
		(net "P5E_CPU0_PE3_TX_DN<6>")
	)
	(segment
		(start 377.578874 -297.42892)
		(end 376.939556 -295.38168)
		(width 0.14732)
		(layer "In2.Cu")
		(net "P5E_CPU0_PE3_TX_DN<6>")
	)
	(segment
		(start 400.80565 -398.549368)
		(end 400.802094 -398.112742)
		(width 0.14732)
		(layer "In2.Cu")
		(net "P5E_CPU0_PE3_TX_DN<6>")
	)
	(segment
		(start 400.676364 -397.989298)
		(end 400.672554 -397.552164)
		(width 0.14732)
		(layer "In2.Cu")
		(net "P5E_CPU0_PE3_TX_DN<6>")
	)
	(segment
		(start 400.886676 -334.776318)
		(end 400.711924 -333.094584)
		(width 0.14732)
		(layer "In2.Cu")
		(net "P5E_CPU0_PE3_TX_DN<6>")
	)
	(segment
		(start 400.802094 -398.112742)
		(end 400.676364 -397.989298)
		(width 0.14732)
		(layer "In2.Cu")
		(net "P5E_CPU0_PE3_TX_DN<6>")
	)
	(segment
		(start 376.981466 -289.586924)
		(end 376.996198 -289.570922)
		(width 0.0889)
		(layer "In2.Cu")
		(net "P5E_CPU0_PE3_TX_DN<6>")
	)
	(segment
		(start 400.811746 -399.235422)
		(end 400.686016 -399.111978)
		(width 0.14732)
		(layer "In2.Cu")
		(net "P5E_CPU0_PE3_TX_DN<6>")
	)
	(segment
		(start 375.82348 -286.204406)
		(end 375.667016 -286.475424)
		(width 0.0889)
		(layer "In2.Cu")
		(net "P5E_CPU0_PE3_TX_DN<6>")
	)
	(segment
		(start 400.63293 -406.70988)
		(end 400.63293 -405.988266)
		(width 0.14732)
		(layer "In2.Cu")
		(net "P5E_CPU0_PE3_TX_DN<6>")
	)
	(segment
		(start 400.682206 -398.674844)
		(end 400.80565 -398.549368)
		(width 0.14732)
		(layer "In2.Cu")
		(net "P5E_CPU0_PE3_TX_DN<6>")
	)
	(segment
		(start 400.686016 -399.111978)
		(end 400.682206 -398.674844)
		(width 0.14732)
		(layer "In2.Cu")
		(net "P5E_CPU0_PE3_TX_DN<6>")
	)
	(segment
		(start 400.5453 -368.231674)
		(end 400.900646 -335.042764)
		(width 0.14732)
		(layer "In2.Cu")
		(net "P5E_CPU0_PE3_TX_DN<6>")
	)
	(segment
		(start 400.795998 -397.426688)
		(end 400.545046 -368.234214)
		(width 0.14732)
		(layer "In2.Cu")
		(net "P5E_CPU0_PE3_TX_DN<6>")
	)
	(segment
		(start 375.901458 -286.183578)
		(end 375.82348 -286.204406)
		(width 0.0889)
		(layer "In2.Cu")
		(net "P5E_CPU0_PE3_TX_DN<6>")
	)
	(segment
		(start 376.041412 -286.48533)
		(end 376.041412 -286.466788)
		(width 0.0889)
		(layer "In2.Cu")
		(net "P5E_CPU0_PE3_TX_DN<6>")
	)
	(segment
		(start 400.711924 -333.094584)
		(end 399.378424 -325.533512)
		(width 0.14732)
		(layer "In2.Cu")
		(net "P5E_CPU0_PE3_TX_DN<6>")
	)
	(segment
		(start 400.886422 -334.776318)
		(end 400.886676 -334.776318)
		(width 0.14732)
		(layer "In2.Cu")
		(net "P5E_CPU0_PE3_TX_DN<6>")
	)
	(segment
		(start 400.33829 -407.00452)
		(end 400.63293 -406.70988)
		(width 0.14732)
		(layer "In2.Cu")
		(net "P5E_CPU0_PE3_TX_DN<6>")
	)
	(segment
		(start 400.81835 -404.104856)
		(end 400.81835 -400.011646)
		(width 0.14732)
		(layer "In2.Cu")
		(net "P5E_CPU0_PE3_TX_DN<6>")
	)
	(segment
		(start 376.802904 -287.783778)
		(end 376.787918 -287.775142)
		(width 0.0889)
		(layer "In2.Cu")
		(net "P5E_CPU0_PE3_TX_DN<6>")
	)
	(segment
		(start 376.981466 -290.075874)
		(end 376.981466 -289.586924)
		(width 0.0889)
		(layer "In2.Cu")
		(net "P5E_CPU0_PE3_TX_DN<6>")
	)
	(segment
		(start 400.545046 -368.234214)
		(end 400.5453 -368.231674)
		(width 0.14732)
		(layer "In2.Cu")
		(net "P5E_CPU0_PE3_TX_DN<6>")
	)
	(segment
		(start 399.378424 -325.533512)
		(end 378.780802 -299.166026)
		(width 0.14732)
		(layer "In2.Cu")
		(net "P5E_CPU0_PE3_TX_DN<6>")
	)
	(arc
		(start 377.266962 -289.277806)
		(mid 377.376358 -289.193709)
		(end 377.451366 -289.077908)
		(width 0.0889)
		(layer "In2.Cu")
		(net "P5E_CPU0_PE3_TX_DN<6>")
	)
	(arc
		(start 376.32386 -286.964882)
		(mid 376.119525 -286.762277)
		(end 376.041412 -286.48533)
		(width 0.0889)
		(layer "In2.Cu")
		(net "P5E_CPU0_PE3_TX_DN<6>")
	)
	(arc
		(start 376.787918 -287.775142)
		(mid 376.585331 -287.568791)
		(end 376.511312 -287.28924)
		(width 0.0889)
		(layer "In2.Cu")
		(net "P5E_CPU0_PE3_TX_DN<6>")
	)
	(arc
		(start 377.263914 -288.592768)
		(mid 377.061628 -288.393787)
		(end 376.981466 -288.121598)
		(width 0.0889)
		(layer "In2.Cu")
		(net "P5E_CPU0_PE3_TX_DN<6>")
	)
	(arc
		(start 376.996198 -289.570922)
		(mid 377.106455 -289.401162)
		(end 377.266962 -289.277806)
		(width 0.0889)
		(layer "In2.Cu")
		(net "P5E_CPU0_PE3_TX_DN<6>")
	)
	(arc
		(start 376.981466 -288.103056)
		(mid 376.933787 -287.920156)
		(end 376.802904 -287.783778)
		(width 0.0889)
		(layer "In2.Cu")
		(net "P5E_CPU0_PE3_TX_DN<6>")
	)
	(arc
		(start 377.451366 -288.917126)
		(mid 377.403687 -288.734226)
		(end 377.272804 -288.597848)
		(width 0.0889)
		(layer "In2.Cu")
		(net "P5E_CPU0_PE3_TX_DN<6>")
	)
	(arc
		(start 376.041412 -286.466788)
		(mid 376.002738 -286.30972)
		(end 375.901458 -286.183578)
		(width 0.0889)
		(layer "In2.Cu")
		(net "P5E_CPU0_PE3_TX_DN<6>")
	)
	(arc
		(start 376.511312 -287.28924)
		(mid 376.463633 -287.10634)
		(end 376.33275 -286.969962)
		(width 0.0889)
		(layer "In2.Cu")
		(net "P5E_CPU0_PE3_TX_DN<6>")
	)
	(segment
		(start 403.707092 -407.310082)
		(end 403.707092 -407.924254)
		(width 0.13208)
		(layer "F.Cu")
		(net "P5E_CPU0_PE3_TX_DN<5>")
	)
	(segment
		(start 403.707092 -407.924254)
		(end 403.380702 -408.250644)
		(width 0.13208)
		(layer "F.Cu")
		(net "P5E_CPU0_PE3_TX_DN<5>")
	)
	(segment
		(start 403.40153 -407.00452)
		(end 403.707092 -407.310082)
		(width 0.13208)
		(layer "F.Cu")
		(net "P5E_CPU0_PE3_TX_DN<5>")
	)
	(segment
		(start 376.606562 -284.311598)
		(end 376.606816 -284.847538)
		(width 0.13208)
		(layer "F.Cu")
		(net "P5E_CPU0_PE3_TX_DN<5>")
	)
	(segment
		(start 403.380702 -408.250644)
		(end 403.37613 -408.250644)
		(width 0.13208)
		(layer "F.Cu")
		(net "P5E_CPU0_PE3_TX_DN<5>")
	)
	(segment
		(start 401.672044 -368.133884)
		(end 401.918932 -334.944466)
		(width 0.14732)
		(layer "In2.Cu")
		(net "P5E_CPU0_PE3_TX_DN<5>")
	)
	(segment
		(start 377.26366 -286.964882)
		(end 377.257564 -286.961326)
		(width 0.0889)
		(layer "In2.Cu")
		(net "P5E_CPU0_PE3_TX_DN<5>")
	)
	(segment
		(start 377.879356 -290.115752)
		(end 377.921012 -290.074096)
		(width 0.0889)
		(layer "In2.Cu")
		(net "P5E_CPU0_PE3_TX_DN<5>")
	)
	(segment
		(start 403.69617 -406.70988)
		(end 403.69617 -405.988266)
		(width 0.14732)
		(layer "In2.Cu")
		(net "P5E_CPU0_PE3_TX_DN<5>")
	)
	(segment
		(start 376.73915 -285.20771)
		(end 376.76328 -285.118556)
		(width 0.0889)
		(layer "In2.Cu")
		(net "P5E_CPU0_PE3_TX_DN<5>")
	)
	(segment
		(start 382.920748 -295.346882)
		(end 379.115066 -293.770304)
		(width 0.14732)
		(layer "In2.Cu")
		(net "P5E_CPU0_PE3_TX_DN<5>")
	)
	(segment
		(start 379.115066 -293.770304)
		(end 377.879356 -292.534594)
		(width 0.14732)
		(layer "In2.Cu")
		(net "P5E_CPU0_PE3_TX_DN<5>")
	)
	(segment
		(start 377.921012 -290.074096)
		(end 377.921012 -289.609784)
		(width 0.0889)
		(layer "In2.Cu")
		(net "P5E_CPU0_PE3_TX_DN<5>")
	)
	(segment
		(start 377.742704 -287.783778)
		(end 377.733814 -287.778698)
		(width 0.0889)
		(layer "In2.Cu")
		(net "P5E_CPU0_PE3_TX_DN<5>")
	)
	(segment
		(start 377.879356 -292.534594)
		(end 377.879356 -290.13785)
		(width 0.14732)
		(layer "In2.Cu")
		(net "P5E_CPU0_PE3_TX_DN<5>")
	)
	(segment
		(start 377.921266 -288.121598)
		(end 377.921266 -288.103056)
		(width 0.0889)
		(layer "In2.Cu")
		(net "P5E_CPU0_PE3_TX_DN<5>")
	)
	(segment
		(start 376.76328 -285.118556)
		(end 376.606816 -284.847538)
		(width 0.0889)
		(layer "In2.Cu")
		(net "P5E_CPU0_PE3_TX_DN<5>")
	)
	(segment
		(start 377.27255 -286.969962)
		(end 377.26366 -286.964882)
		(width 0.0889)
		(layer "In2.Cu")
		(net "P5E_CPU0_PE3_TX_DN<5>")
	)
	(segment
		(start 385.487926 -305.96205)
		(end 383.909316 -297.100752)
		(width 0.14732)
		(layer "In2.Cu")
		(net "P5E_CPU0_PE3_TX_DN<5>")
	)
	(segment
		(start 378.212604 -288.597848)
		(end 378.203714 -288.592768)
		(width 0.0889)
		(layer "In2.Cu")
		(net "P5E_CPU0_PE3_TX_DN<5>")
	)
	(segment
		(start 376.80265 -286.156146)
		(end 376.79376 -286.151066)
		(width 0.0889)
		(layer "In2.Cu")
		(net "P5E_CPU0_PE3_TX_DN<5>")
	)
	(segment
		(start 401.918932 -334.944466)
		(end 401.741132 -333.27594)
		(width 0.14732)
		(layer "In2.Cu")
		(net "P5E_CPU0_PE3_TX_DN<5>")
	)
	(segment
		(start 403.69617 -405.988266)
		(end 403.88159 -404.104856)
		(width 0.14732)
		(layer "In2.Cu")
		(net "P5E_CPU0_PE3_TX_DN<5>")
	)
	(segment
		(start 403.88159 -404.104856)
		(end 403.88159 -400.268948)
		(width 0.14732)
		(layer "In2.Cu")
		(net "P5E_CPU0_PE3_TX_DN<5>")
	)
	(segment
		(start 376.511312 -285.679896)
		(end 376.511312 -285.661354)
		(width 0.0889)
		(layer "In2.Cu")
		(net "P5E_CPU0_PE3_TX_DN<5>")
	)
	(segment
		(start 378.391166 -289.077908)
		(end 378.391166 -288.917126)
		(width 0.0889)
		(layer "In2.Cu")
		(net "P5E_CPU0_PE3_TX_DN<5>")
	)
	(segment
		(start 403.88159 -400.268948)
		(end 401.672044 -368.133884)
		(width 0.14732)
		(layer "In2.Cu")
		(net "P5E_CPU0_PE3_TX_DN<5>")
	)
	(segment
		(start 403.40153 -407.00452)
		(end 403.69617 -406.70988)
		(width 0.14732)
		(layer "In2.Cu")
		(net "P5E_CPU0_PE3_TX_DN<5>")
	)
	(segment
		(start 383.368296 -295.79443)
		(end 382.920748 -295.346882)
		(width 0.14732)
		(layer "In2.Cu")
		(net "P5E_CPU0_PE3_TX_DN<5>")
	)
	(segment
		(start 377.733814 -287.778698)
		(end 377.727718 -287.775142)
		(width 0.0889)
		(layer "In2.Cu")
		(net "P5E_CPU0_PE3_TX_DN<5>")
	)
	(segment
		(start 401.741132 -333.27594)
		(end 400.272758 -324.950328)
		(width 0.14732)
		(layer "In2.Cu")
		(net "P5E_CPU0_PE3_TX_DN<5>")
	)
	(segment
		(start 383.909316 -297.100752)
		(end 383.368296 -295.79443)
		(width 0.14732)
		(layer "In2.Cu")
		(net "P5E_CPU0_PE3_TX_DN<5>")
	)
	(segment
		(start 377.879356 -290.13785)
		(end 377.879356 -290.115752)
		(width 0.0889)
		(layer "In2.Cu")
		(net "P5E_CPU0_PE3_TX_DN<5>")
	)
	(segment
		(start 400.272758 -324.950328)
		(end 385.487926 -305.96205)
		(width 0.14732)
		(layer "In2.Cu")
		(net "P5E_CPU0_PE3_TX_DN<5>")
	)
	(arc
		(start 377.727718 -287.775142)
		(mid 377.525131 -287.568791)
		(end 377.451112 -287.28924)
		(width 0.0889)
		(layer "In2.Cu")
		(net "P5E_CPU0_PE3_TX_DN<5>")
	)
	(arc
		(start 377.921012 -289.609784)
		(mid 377.928168 -289.590223)
		(end 377.935998 -289.570922)
		(width 0.0889)
		(layer "In2.Cu")
		(net "P5E_CPU0_PE3_TX_DN<5>")
	)
	(arc
		(start 377.935998 -289.570922)
		(mid 378.046255 -289.401162)
		(end 378.206762 -289.277806)
		(width 0.0889)
		(layer "In2.Cu")
		(net "P5E_CPU0_PE3_TX_DN<5>")
	)
	(arc
		(start 376.511312 -285.661354)
		(mid 376.566667 -285.417167)
		(end 376.722132 -285.220918)
		(width 0.0889)
		(layer "In2.Cu")
		(net "P5E_CPU0_PE3_TX_DN<5>")
	)
	(arc
		(start 378.206762 -289.277806)
		(mid 378.316158 -289.193709)
		(end 378.391166 -289.077908)
		(width 0.0889)
		(layer "In2.Cu")
		(net "P5E_CPU0_PE3_TX_DN<5>")
	)
	(arc
		(start 377.257564 -286.961326)
		(mid 377.055151 -286.754913)
		(end 376.981212 -286.475424)
		(width 0.0889)
		(layer "In2.Cu")
		(net "P5E_CPU0_PE3_TX_DN<5>")
	)
	(arc
		(start 376.79376 -286.151066)
		(mid 376.591474 -285.952085)
		(end 376.511312 -285.679896)
		(width 0.0889)
		(layer "In2.Cu")
		(net "P5E_CPU0_PE3_TX_DN<5>")
	)
	(arc
		(start 378.203714 -288.592768)
		(mid 378.001428 -288.393787)
		(end 377.921266 -288.121598)
		(width 0.0889)
		(layer "In2.Cu")
		(net "P5E_CPU0_PE3_TX_DN<5>")
	)
	(arc
		(start 377.921266 -288.103056)
		(mid 377.873587 -287.920156)
		(end 377.742704 -287.783778)
		(width 0.0889)
		(layer "In2.Cu")
		(net "P5E_CPU0_PE3_TX_DN<5>")
	)
	(arc
		(start 377.451112 -287.28924)
		(mid 377.403433 -287.10634)
		(end 377.27255 -286.969962)
		(width 0.0889)
		(layer "In2.Cu")
		(net "P5E_CPU0_PE3_TX_DN<5>")
	)
	(arc
		(start 376.981212 -286.475424)
		(mid 376.933533 -286.292524)
		(end 376.80265 -286.156146)
		(width 0.0889)
		(layer "In2.Cu")
		(net "P5E_CPU0_PE3_TX_DN<5>")
	)
	(arc
		(start 376.722132 -285.220918)
		(mid 376.730578 -285.214233)
		(end 376.73915 -285.20771)
		(width 0.0889)
		(layer "In2.Cu")
		(net "P5E_CPU0_PE3_TX_DN<5>")
	)
	(arc
		(start 378.391166 -288.917126)
		(mid 378.343487 -288.734226)
		(end 378.212604 -288.597848)
		(width 0.0889)
		(layer "In2.Cu")
		(net "P5E_CPU0_PE3_TX_DN<5>")
	)
	(segment
		(start 377.546362 -285.939484)
		(end 377.546362 -286.47517)
		(width 0.13208)
		(layer "F.Cu")
		(net "P5E_CPU0_PE3_TX_DN<4>")
	)
	(segment
		(start 377.546362 -286.47517)
		(end 377.546616 -286.475424)
		(width 0.13208)
		(layer "F.Cu")
		(net "P5E_CPU0_PE3_TX_DN<4>")
	)
	(segment
		(start 406.443942 -408.250644)
		(end 406.43937 -408.250644)
		(width 0.13208)
		(layer "F.Cu")
		(net "P5E_CPU0_PE3_TX_DN<4>")
	)
	(segment
		(start 406.46477 -407.00452)
		(end 406.770332 -407.310082)
		(width 0.13208)
		(layer "F.Cu")
		(net "P5E_CPU0_PE3_TX_DN<4>")
	)
	(segment
		(start 406.770332 -407.310082)
		(end 406.770332 -407.924254)
		(width 0.13208)
		(layer "F.Cu")
		(net "P5E_CPU0_PE3_TX_DN<4>")
	)
	(segment
		(start 406.770332 -407.924254)
		(end 406.443942 -408.250644)
		(width 0.13208)
		(layer "F.Cu")
		(net "P5E_CPU0_PE3_TX_DN<4>")
	)
	(segment
		(start 377.92152 -286.486092)
		(end 377.92152 -286.463994)
		(width 0.0889)
		(layer "In2.Cu")
		(net "P5E_CPU0_PE3_TX_DN<4>")
	)
	(segment
		(start 406.75941 -405.988266)
		(end 406.94483 -404.104856)
		(width 0.14732)
		(layer "In2.Cu")
		(net "P5E_CPU0_PE3_TX_DN<4>")
	)
	(segment
		(start 406.455118 -396.781274)
		(end 402.648166 -368.247422)
		(width 0.14732)
		(layer "In2.Cu")
		(net "P5E_CPU0_PE3_TX_DN<4>")
	)
	(segment
		(start 383.310384 -294.411908)
		(end 379.549406 -292.854634)
		(width 0.14732)
		(layer "In2.Cu")
		(net "P5E_CPU0_PE3_TX_DN<4>")
	)
	(segment
		(start 406.46477 -407.00452)
		(end 406.75941 -406.70988)
		(width 0.14732)
		(layer "In2.Cu")
		(net "P5E_CPU0_PE3_TX_DN<4>")
	)
	(segment
		(start 378.819156 -290.13785)
		(end 378.819156 -290.115752)
		(width 0.0889)
		(layer "In2.Cu")
		(net "P5E_CPU0_PE3_TX_DN<4>")
	)
	(segment
		(start 402.948648 -334.731868)
		(end 401.154646 -324.558152)
		(width 0.14732)
		(layer "In2.Cu")
		(net "P5E_CPU0_PE3_TX_DN<4>")
	)
	(segment
		(start 378.673614 -287.778698)
		(end 378.67082 -287.777174)
		(width 0.0889)
		(layer "In2.Cu")
		(net "P5E_CPU0_PE3_TX_DN<4>")
	)
	(segment
		(start 377.782074 -286.183324)
		(end 377.781566 -286.18307)
		(width 0.0889)
		(layer "In2.Cu")
		(net "P5E_CPU0_PE3_TX_DN<4>")
	)
	(segment
		(start 378.391166 -287.28924)
		(end 378.391166 -287.281366)
		(width 0.0889)
		(layer "In2.Cu")
		(net "P5E_CPU0_PE3_TX_DN<4>")
	)
	(segment
		(start 379.152404 -288.597848)
		(end 379.143514 -288.592768)
		(width 0.0889)
		(layer "In2.Cu")
		(net "P5E_CPU0_PE3_TX_DN<4>")
	)
	(segment
		(start 401.154646 -324.558152)
		(end 386.395468 -305.602894)
		(width 0.14732)
		(layer "In2.Cu")
		(net "P5E_CPU0_PE3_TX_DN<4>")
	)
	(segment
		(start 378.819156 -292.124384)
		(end 378.819156 -290.13785)
		(width 0.14732)
		(layer "In2.Cu")
		(net "P5E_CPU0_PE3_TX_DN<4>")
	)
	(segment
		(start 377.781566 -286.18307)
		(end 377.781058 -286.183578)
		(width 0.0889)
		(layer "In2.Cu")
		(net "P5E_CPU0_PE3_TX_DN<4>")
	)
	(segment
		(start 377.70308 -286.204406)
		(end 377.546616 -286.475424)
		(width 0.0889)
		(layer "In2.Cu")
		(net "P5E_CPU0_PE3_TX_DN<4>")
	)
	(segment
		(start 378.674376 -287.779206)
		(end 378.673614 -287.778698)
		(width 0.0889)
		(layer "In2.Cu")
		(net "P5E_CPU0_PE3_TX_DN<4>")
	)
	(segment
		(start 378.67082 -287.777174)
		(end 378.662184 -287.77184)
		(width 0.0889)
		(layer "In2.Cu")
		(net "P5E_CPU0_PE3_TX_DN<4>")
	)
	(segment
		(start 406.503378 -398.08404)
		(end 406.610312 -397.94434)
		(width 0.14732)
		(layer "In2.Cu")
		(net "P5E_CPU0_PE3_TX_DN<4>")
	)
	(segment
		(start 378.683266 -287.78454)
		(end 378.674376 -287.779206)
		(width 0.0889)
		(layer "In2.Cu")
		(net "P5E_CPU0_PE3_TX_DN<4>")
	)
	(segment
		(start 406.610312 -397.94434)
		(end 406.54605 -397.461486)
		(width 0.14732)
		(layer "In2.Cu")
		(net "P5E_CPU0_PE3_TX_DN<4>")
	)
	(segment
		(start 386.395468 -305.602894)
		(end 384.845814 -296.907712)
		(width 0.14732)
		(layer "In2.Cu")
		(net "P5E_CPU0_PE3_TX_DN<4>")
	)
	(segment
		(start 378.860812 -290.074096)
		(end 378.860812 -289.609784)
		(width 0.0889)
		(layer "In2.Cu")
		(net "P5E_CPU0_PE3_TX_DN<4>")
	)
	(segment
		(start 406.348184 -396.921228)
		(end 406.455118 -396.781274)
		(width 0.14732)
		(layer "In2.Cu")
		(net "P5E_CPU0_PE3_TX_DN<4>")
	)
	(segment
		(start 378.682504 -287.783778)
		(end 378.683266 -287.78454)
		(width 0.0889)
		(layer "In2.Cu")
		(net "P5E_CPU0_PE3_TX_DN<4>")
	)
	(segment
		(start 406.94483 -400.451574)
		(end 406.701244 -398.624298)
		(width 0.14732)
		(layer "In2.Cu")
		(net "P5E_CPU0_PE3_TX_DN<4>")
	)
	(segment
		(start 384.166872 -295.268396)
		(end 383.310384 -294.411908)
		(width 0.14732)
		(layer "In2.Cu")
		(net "P5E_CPU0_PE3_TX_DN<4>")
	)
	(segment
		(start 377.781058 -286.183578)
		(end 377.70308 -286.204406)
		(width 0.0889)
		(layer "In2.Cu")
		(net "P5E_CPU0_PE3_TX_DN<4>")
	)
	(segment
		(start 378.861066 -288.121598)
		(end 378.861066 -288.103056)
		(width 0.0889)
		(layer "In2.Cu")
		(net "P5E_CPU0_PE3_TX_DN<4>")
	)
	(segment
		(start 406.561036 -398.517364)
		(end 406.503378 -398.08404)
		(width 0.14732)
		(layer "In2.Cu")
		(net "P5E_CPU0_PE3_TX_DN<4>")
	)
	(segment
		(start 402.648166 -368.247422)
		(end 402.948648 -334.731868)
		(width 0.14732)
		(layer "In2.Cu")
		(net "P5E_CPU0_PE3_TX_DN<4>")
	)
	(segment
		(start 406.54605 -397.461486)
		(end 406.405842 -397.354552)
		(width 0.14732)
		(layer "In2.Cu")
		(net "P5E_CPU0_PE3_TX_DN<4>")
	)
	(segment
		(start 379.549406 -292.854634)
		(end 378.819156 -292.124384)
		(width 0.14732)
		(layer "In2.Cu")
		(net "P5E_CPU0_PE3_TX_DN<4>")
	)
	(segment
		(start 406.701244 -398.624298)
		(end 406.561036 -398.517364)
		(width 0.14732)
		(layer "In2.Cu")
		(net "P5E_CPU0_PE3_TX_DN<4>")
	)
	(segment
		(start 384.845814 -296.907712)
		(end 384.166872 -295.268396)
		(width 0.14732)
		(layer "In2.Cu")
		(net "P5E_CPU0_PE3_TX_DN<4>")
	)
	(segment
		(start 379.330966 -289.077908)
		(end 379.330966 -288.917126)
		(width 0.0889)
		(layer "In2.Cu")
		(net "P5E_CPU0_PE3_TX_DN<4>")
	)
	(segment
		(start 406.405842 -397.354552)
		(end 406.348184 -396.921228)
		(width 0.14732)
		(layer "In2.Cu")
		(net "P5E_CPU0_PE3_TX_DN<4>")
	)
	(segment
		(start 406.75941 -406.70988)
		(end 406.75941 -405.988266)
		(width 0.14732)
		(layer "In2.Cu")
		(net "P5E_CPU0_PE3_TX_DN<4>")
	)
	(segment
		(start 378.819156 -290.115752)
		(end 378.860812 -290.074096)
		(width 0.0889)
		(layer "In2.Cu")
		(net "P5E_CPU0_PE3_TX_DN<4>")
	)
	(segment
		(start 406.94483 -404.104856)
		(end 406.94483 -400.451574)
		(width 0.14732)
		(layer "In2.Cu")
		(net "P5E_CPU0_PE3_TX_DN<4>")
	)
	(arc
		(start 378.860812 -289.609784)
		(mid 378.867968 -289.590223)
		(end 378.875798 -289.570922)
		(width 0.0889)
		(layer "In2.Cu")
		(net "P5E_CPU0_PE3_TX_DN<4>")
	)
	(arc
		(start 378.203714 -286.964628)
		(mid 377.999736 -286.762452)
		(end 377.92152 -286.486092)
		(width 0.0889)
		(layer "In2.Cu")
		(net "P5E_CPU0_PE3_TX_DN<4>")
	)
	(arc
		(start 378.391166 -287.281366)
		(mid 378.338939 -287.098448)
		(end 378.203714 -286.964628)
		(width 0.0889)
		(layer "In2.Cu")
		(net "P5E_CPU0_PE3_TX_DN<4>")
	)
	(arc
		(start 377.92152 -286.463994)
		(mid 377.882555 -286.308367)
		(end 377.782074 -286.183324)
		(width 0.0889)
		(layer "In2.Cu")
		(net "P5E_CPU0_PE3_TX_DN<4>")
	)
	(arc
		(start 379.146562 -289.277806)
		(mid 379.255958 -289.193709)
		(end 379.330966 -289.077908)
		(width 0.0889)
		(layer "In2.Cu")
		(net "P5E_CPU0_PE3_TX_DN<4>")
	)
	(arc
		(start 379.330966 -288.917126)
		(mid 379.283287 -288.734226)
		(end 379.152404 -288.597848)
		(width 0.0889)
		(layer "In2.Cu")
		(net "P5E_CPU0_PE3_TX_DN<4>")
	)
	(arc
		(start 379.143514 -288.592768)
		(mid 378.941228 -288.393787)
		(end 378.861066 -288.121598)
		(width 0.0889)
		(layer "In2.Cu")
		(net "P5E_CPU0_PE3_TX_DN<4>")
	)
	(arc
		(start 378.662184 -287.77184)
		(mid 378.463543 -287.565991)
		(end 378.391166 -287.28924)
		(width 0.0889)
		(layer "In2.Cu")
		(net "P5E_CPU0_PE3_TX_DN<4>")
	)
	(arc
		(start 378.861066 -288.103056)
		(mid 378.813387 -287.920156)
		(end 378.682504 -287.783778)
		(width 0.0889)
		(layer "In2.Cu")
		(net "P5E_CPU0_PE3_TX_DN<4>")
	)
	(arc
		(start 378.875798 -289.570922)
		(mid 378.986055 -289.401162)
		(end 379.146562 -289.277806)
		(width 0.0889)
		(layer "In2.Cu")
		(net "P5E_CPU0_PE3_TX_DN<4>")
	)
	(segment
		(start 378.486162 -284.311598)
		(end 378.486416 -284.847538)
		(width 0.13208)
		(layer "F.Cu")
		(net "P5E_CPU0_PE3_TX_DN<3>")
	)
	(segment
		(start 409.833572 -407.924254)
		(end 409.507182 -408.250644)
		(width 0.13208)
		(layer "F.Cu")
		(net "P5E_CPU0_PE3_TX_DN<3>")
	)
	(segment
		(start 409.52801 -407.00452)
		(end 409.833572 -407.310082)
		(width 0.13208)
		(layer "F.Cu")
		(net "P5E_CPU0_PE3_TX_DN<3>")
	)
	(segment
		(start 409.507182 -408.250644)
		(end 409.50261 -408.250644)
		(width 0.13208)
		(layer "F.Cu")
		(net "P5E_CPU0_PE3_TX_DN<3>")
	)
	(segment
		(start 409.833572 -407.310082)
		(end 409.833572 -407.924254)
		(width 0.13208)
		(layer "F.Cu")
		(net "P5E_CPU0_PE3_TX_DN<3>")
	)
	(segment
		(start 380.2126 -292.108128)
		(end 379.758956 -291.654484)
		(width 0.14732)
		(layer "In2.Cu")
		(net "P5E_CPU0_PE3_TX_DN<3>")
	)
	(segment
		(start 409.82265 -405.988266)
		(end 410.00807 -404.104856)
		(width 0.14732)
		(layer "In2.Cu")
		(net "P5E_CPU0_PE3_TX_DN<3>")
	)
	(segment
		(start 379.800866 -289.645344)
		(end 379.800612 -289.609784)
		(width 0.0889)
		(layer "In2.Cu")
		(net "P5E_CPU0_PE3_TX_DN<3>")
	)
	(segment
		(start 379.758956 -290.13785)
		(end 379.758956 -290.115752)
		(width 0.0889)
		(layer "In2.Cu")
		(net "P5E_CPU0_PE3_TX_DN<3>")
	)
	(segment
		(start 379.14326 -286.964882)
		(end 379.137164 -286.961326)
		(width 0.0889)
		(layer "In2.Cu")
		(net "P5E_CPU0_PE3_TX_DN<3>")
	)
	(segment
		(start 385.802124 -296.719498)
		(end 384.975862 -294.724582)
		(width 0.14732)
		(layer "In2.Cu")
		(net "P5E_CPU0_PE3_TX_DN<3>")
	)
	(segment
		(start 403.992588 -334.841088)
		(end 403.638766 -333.136748)
		(width 0.14732)
		(layer "In2.Cu")
		(net "P5E_CPU0_PE3_TX_DN<3>")
	)
	(segment
		(start 378.64288 -285.118556)
		(end 378.486416 -284.847538)
		(width 0.0889)
		(layer "In2.Cu")
		(net "P5E_CPU0_PE3_TX_DN<3>")
	)
	(segment
		(start 410.00807 -400.517106)
		(end 403.867366 -370.012976)
		(width 0.14732)
		(layer "In2.Cu")
		(net "P5E_CPU0_PE3_TX_DN<3>")
	)
	(segment
		(start 380.270766 -289.077908)
		(end 380.270766 -288.917126)
		(width 0.0889)
		(layer "In2.Cu")
		(net "P5E_CPU0_PE3_TX_DN<3>")
	)
	(segment
		(start 378.68225 -286.156146)
		(end 378.67336 -286.151066)
		(width 0.0889)
		(layer "In2.Cu")
		(net "P5E_CPU0_PE3_TX_DN<3>")
	)
	(segment
		(start 409.52801 -407.00452)
		(end 409.82265 -406.70988)
		(width 0.14732)
		(layer "In2.Cu")
		(net "P5E_CPU0_PE3_TX_DN<3>")
	)
	(segment
		(start 402.05533 -324.158102)
		(end 387.320282 -305.233578)
		(width 0.14732)
		(layer "In2.Cu")
		(net "P5E_CPU0_PE3_TX_DN<3>")
	)
	(segment
		(start 379.758956 -290.115752)
		(end 379.800866 -290.073842)
		(width 0.0889)
		(layer "In2.Cu")
		(net "P5E_CPU0_PE3_TX_DN<3>")
	)
	(segment
		(start 387.320282 -305.233578)
		(end 385.802124 -296.719498)
		(width 0.14732)
		(layer "In2.Cu")
		(net "P5E_CPU0_PE3_TX_DN<3>")
	)
	(segment
		(start 383.877566 -293.626286)
		(end 380.2126 -292.108128)
		(width 0.14732)
		(layer "In2.Cu")
		(net "P5E_CPU0_PE3_TX_DN<3>")
	)
	(segment
		(start 378.390912 -285.679896)
		(end 378.390912 -285.661354)
		(width 0.0889)
		(layer "In2.Cu")
		(net "P5E_CPU0_PE3_TX_DN<3>")
	)
	(segment
		(start 379.15215 -286.969962)
		(end 379.14326 -286.964882)
		(width 0.0889)
		(layer "In2.Cu")
		(net "P5E_CPU0_PE3_TX_DN<3>")
	)
	(segment
		(start 379.758956 -291.654484)
		(end 379.758956 -290.13785)
		(width 0.14732)
		(layer "In2.Cu")
		(net "P5E_CPU0_PE3_TX_DN<3>")
	)
	(segment
		(start 379.622304 -287.783778)
		(end 379.607318 -287.775142)
		(width 0.0889)
		(layer "In2.Cu")
		(net "P5E_CPU0_PE3_TX_DN<3>")
	)
	(segment
		(start 409.82265 -406.70988)
		(end 409.82265 -405.988266)
		(width 0.14732)
		(layer "In2.Cu")
		(net "P5E_CPU0_PE3_TX_DN<3>")
	)
	(segment
		(start 410.00807 -404.104856)
		(end 410.00807 -400.517106)
		(width 0.14732)
		(layer "In2.Cu")
		(net "P5E_CPU0_PE3_TX_DN<3>")
	)
	(segment
		(start 378.61875 -285.20771)
		(end 378.64288 -285.118556)
		(width 0.0889)
		(layer "In2.Cu")
		(net "P5E_CPU0_PE3_TX_DN<3>")
	)
	(segment
		(start 403.598634 -368.0079)
		(end 403.992588 -334.841088)
		(width 0.14732)
		(layer "In2.Cu")
		(net "P5E_CPU0_PE3_TX_DN<3>")
	)
	(segment
		(start 403.867366 -370.012468)
		(end 403.598634 -368.0079)
		(width 0.14732)
		(layer "In2.Cu")
		(net "P5E_CPU0_PE3_TX_DN<3>")
	)
	(segment
		(start 384.975862 -294.724582)
		(end 383.877566 -293.626286)
		(width 0.14732)
		(layer "In2.Cu")
		(net "P5E_CPU0_PE3_TX_DN<3>")
	)
	(segment
		(start 403.638766 -333.136748)
		(end 402.05533 -324.158102)
		(width 0.14732)
		(layer "In2.Cu")
		(net "P5E_CPU0_PE3_TX_DN<3>")
	)
	(segment
		(start 380.092204 -288.597848)
		(end 380.083314 -288.592768)
		(width 0.0889)
		(layer "In2.Cu")
		(net "P5E_CPU0_PE3_TX_DN<3>")
	)
	(segment
		(start 403.867366 -370.012976)
		(end 403.867366 -370.012468)
		(width 0.14732)
		(layer "In2.Cu")
		(net "P5E_CPU0_PE3_TX_DN<3>")
	)
	(segment
		(start 379.800866 -290.073842)
		(end 379.800866 -289.645344)
		(width 0.0889)
		(layer "In2.Cu")
		(net "P5E_CPU0_PE3_TX_DN<3>")
	)
	(segment
		(start 379.800866 -288.121598)
		(end 379.800866 -288.103056)
		(width 0.0889)
		(layer "In2.Cu")
		(net "P5E_CPU0_PE3_TX_DN<3>")
	)
	(arc
		(start 380.086362 -289.277806)
		(mid 380.195758 -289.193709)
		(end 380.270766 -289.077908)
		(width 0.0889)
		(layer "In2.Cu")
		(net "P5E_CPU0_PE3_TX_DN<3>")
	)
	(arc
		(start 378.390912 -285.661354)
		(mid 378.446267 -285.417167)
		(end 378.601732 -285.220918)
		(width 0.0889)
		(layer "In2.Cu")
		(net "P5E_CPU0_PE3_TX_DN<3>")
	)
	(arc
		(start 378.67336 -286.151066)
		(mid 378.471074 -285.952085)
		(end 378.390912 -285.679896)
		(width 0.0889)
		(layer "In2.Cu")
		(net "P5E_CPU0_PE3_TX_DN<3>")
	)
	(arc
		(start 380.270766 -288.917126)
		(mid 380.223087 -288.734226)
		(end 380.092204 -288.597848)
		(width 0.0889)
		(layer "In2.Cu")
		(net "P5E_CPU0_PE3_TX_DN<3>")
	)
	(arc
		(start 378.601732 -285.220918)
		(mid 378.610178 -285.214233)
		(end 378.61875 -285.20771)
		(width 0.0889)
		(layer "In2.Cu")
		(net "P5E_CPU0_PE3_TX_DN<3>")
	)
	(arc
		(start 379.137164 -286.961326)
		(mid 378.934751 -286.754913)
		(end 378.860812 -286.475424)
		(width 0.0889)
		(layer "In2.Cu")
		(net "P5E_CPU0_PE3_TX_DN<3>")
	)
	(arc
		(start 379.800612 -289.609784)
		(mid 379.807995 -289.589577)
		(end 379.816106 -289.569652)
		(width 0.0889)
		(layer "In2.Cu")
		(net "P5E_CPU0_PE3_TX_DN<3>")
	)
	(arc
		(start 379.330712 -287.28924)
		(mid 379.283033 -287.10634)
		(end 379.15215 -286.969962)
		(width 0.0889)
		(layer "In2.Cu")
		(net "P5E_CPU0_PE3_TX_DN<3>")
	)
	(arc
		(start 378.860812 -286.475424)
		(mid 378.813133 -286.292524)
		(end 378.68225 -286.156146)
		(width 0.0889)
		(layer "In2.Cu")
		(net "P5E_CPU0_PE3_TX_DN<3>")
	)
	(arc
		(start 380.083314 -288.592768)
		(mid 379.881028 -288.393787)
		(end 379.800866 -288.121598)
		(width 0.0889)
		(layer "In2.Cu")
		(net "P5E_CPU0_PE3_TX_DN<3>")
	)
	(arc
		(start 379.816106 -289.569652)
		(mid 379.926293 -289.400635)
		(end 380.086362 -289.277806)
		(width 0.0889)
		(layer "In2.Cu")
		(net "P5E_CPU0_PE3_TX_DN<3>")
	)
	(arc
		(start 379.607318 -287.775142)
		(mid 379.404731 -287.568791)
		(end 379.330712 -287.28924)
		(width 0.0889)
		(layer "In2.Cu")
		(net "P5E_CPU0_PE3_TX_DN<3>")
	)
	(arc
		(start 379.800866 -288.103056)
		(mid 379.753187 -287.920156)
		(end 379.622304 -287.783778)
		(width 0.0889)
		(layer "In2.Cu")
		(net "P5E_CPU0_PE3_TX_DN<3>")
	)
	(segment
		(start 412.59125 -407.00452)
		(end 412.896812 -407.310082)
		(width 0.13208)
		(layer "F.Cu")
		(net "P5E_CPU0_PE3_TX_DN<2>")
	)
	(segment
		(start 379.425962 -286.47517)
		(end 379.426216 -286.475424)
		(width 0.13208)
		(layer "F.Cu")
		(net "P5E_CPU0_PE3_TX_DN<2>")
	)
	(segment
		(start 412.570422 -408.250644)
		(end 412.56585 -408.250644)
		(width 0.13208)
		(layer "F.Cu")
		(net "P5E_CPU0_PE3_TX_DN<2>")
	)
	(segment
		(start 412.896812 -407.310082)
		(end 412.896812 -407.924254)
		(width 0.13208)
		(layer "F.Cu")
		(net "P5E_CPU0_PE3_TX_DN<2>")
	)
	(segment
		(start 379.425962 -285.939484)
		(end 379.425962 -286.47517)
		(width 0.13208)
		(layer "F.Cu")
		(net "P5E_CPU0_PE3_TX_DN<2>")
	)
	(segment
		(start 412.896812 -407.924254)
		(end 412.570422 -408.250644)
		(width 0.13208)
		(layer "F.Cu")
		(net "P5E_CPU0_PE3_TX_DN<2>")
	)
	(segment
		(start 380.698756 -290.13785)
		(end 380.698756 -290.115752)
		(width 0.0889)
		(layer "In2.Cu")
		(net "P5E_CPU0_PE3_TX_DN<2>")
	)
	(segment
		(start 379.800612 -286.48533)
		(end 379.800612 -286.466788)
		(width 0.0889)
		(layer "In2.Cu")
		(net "P5E_CPU0_PE3_TX_DN<2>")
	)
	(segment
		(start 412.88589 -405.988266)
		(end 413.07131 -404.104856)
		(width 0.14732)
		(layer "In2.Cu")
		(net "P5E_CPU0_PE3_TX_DN<2>")
	)
	(segment
		(start 380.698756 -290.115752)
		(end 380.740666 -290.073842)
		(width 0.0889)
		(layer "In2.Cu")
		(net "P5E_CPU0_PE3_TX_DN<2>")
	)
	(segment
		(start 404.58771 -333.123794)
		(end 402.933408 -323.742304)
		(width 0.14732)
		(layer "In2.Cu")
		(net "P5E_CPU0_PE3_TX_DN<2>")
	)
	(segment
		(start 388.246874 -304.88001)
		(end 386.750306 -296.490898)
		(width 0.14732)
		(layer "In2.Cu")
		(net "P5E_CPU0_PE3_TX_DN<2>")
	)
	(segment
		(start 405.018494 -334.880712)
		(end 404.58771 -333.123794)
		(width 0.14732)
		(layer "In2.Cu")
		(net "P5E_CPU0_PE3_TX_DN<2>")
	)
	(segment
		(start 412.079948 -396.59433)
		(end 404.841964 -369.775994)
		(width 0.14732)
		(layer "In2.Cu")
		(net "P5E_CPU0_PE3_TX_DN<2>")
	)
	(segment
		(start 404.841964 -369.775994)
		(end 404.624286 -367.937542)
		(width 0.14732)
		(layer "In2.Cu")
		(net "P5E_CPU0_PE3_TX_DN<2>")
	)
	(segment
		(start 381.025654 -289.278314)
		(end 381.025654 -289.27806)
		(width 0.0889)
		(layer "In2.Cu")
		(net "P5E_CPU0_PE3_TX_DN<2>")
	)
	(segment
		(start 412.88589 -406.70988)
		(end 412.88589 -405.988266)
		(width 0.14732)
		(layer "In2.Cu")
		(net "P5E_CPU0_PE3_TX_DN<2>")
	)
	(segment
		(start 381.257302 -291.423598)
		(end 380.698756 -290.865052)
		(width 0.14732)
		(layer "In2.Cu")
		(net "P5E_CPU0_PE3_TX_DN<2>")
	)
	(segment
		(start 412.10611 -397.169132)
		(end 411.992064 -396.746984)
		(width 0.14732)
		(layer "In2.Cu")
		(net "P5E_CPU0_PE3_TX_DN<2>")
	)
	(segment
		(start 412.551372 -398.340834)
		(end 412.398464 -398.25295)
		(width 0.14732)
		(layer "In2.Cu")
		(net "P5E_CPU0_PE3_TX_DN<2>")
	)
	(segment
		(start 381.021844 -288.591498)
		(end 381.021336 -288.591244)
		(width 0.0889)
		(layer "In2.Cu")
		(net "P5E_CPU0_PE3_TX_DN<2>")
	)
	(segment
		(start 380.698756 -290.865052)
		(end 380.698756 -290.13785)
		(width 0.14732)
		(layer "In2.Cu")
		(net "P5E_CPU0_PE3_TX_DN<2>")
	)
	(segment
		(start 380.557786 -287.781492)
		(end 380.553214 -287.778698)
		(width 0.0889)
		(layer "In2.Cu")
		(net "P5E_CPU0_PE3_TX_DN<2>")
	)
	(segment
		(start 381.021336 -288.591244)
		(end 381.011938 -288.585656)
		(width 0.0889)
		(layer "In2.Cu")
		(net "P5E_CPU0_PE3_TX_DN<2>")
	)
	(segment
		(start 412.372556 -397.678402)
		(end 412.258764 -397.256762)
		(width 0.14732)
		(layer "In2.Cu")
		(net "P5E_CPU0_PE3_TX_DN<2>")
	)
	(segment
		(start 381.062992 -289.255962)
		(end 381.063246 -289.256216)
		(width 0.0889)
		(layer "In2.Cu")
		(net "P5E_CPU0_PE3_TX_DN<2>")
	)
	(segment
		(start 412.59125 -407.00452)
		(end 412.88589 -406.70988)
		(width 0.14732)
		(layer "In2.Cu")
		(net "P5E_CPU0_PE3_TX_DN<2>")
	)
	(segment
		(start 380.740666 -290.073842)
		(end 380.740666 -289.609784)
		(width 0.0889)
		(layer "In2.Cu")
		(net "P5E_CPU0_PE3_TX_DN<2>")
	)
	(segment
		(start 379.660658 -286.183578)
		(end 379.58268 -286.204406)
		(width 0.0889)
		(layer "In2.Cu")
		(net "P5E_CPU0_PE3_TX_DN<2>")
	)
	(segment
		(start 413.07131 -400.267424)
		(end 412.551372 -398.340834)
		(width 0.14732)
		(layer "In2.Cu")
		(net "P5E_CPU0_PE3_TX_DN<2>")
	)
	(segment
		(start 381.20574 -289.00882)
		(end 381.210058 -288.944558)
		(width 0.0889)
		(layer "In2.Cu")
		(net "P5E_CPU0_PE3_TX_DN<2>")
	)
	(segment
		(start 385.687316 -293.924482)
		(end 384.550666 -292.787832)
		(width 0.14732)
		(layer "In2.Cu")
		(net "P5E_CPU0_PE3_TX_DN<2>")
	)
	(segment
		(start 412.398464 -398.25295)
		(end 412.284672 -397.831056)
		(width 0.14732)
		(layer "In2.Cu")
		(net "P5E_CPU0_PE3_TX_DN<2>")
	)
	(segment
		(start 412.284672 -397.831056)
		(end 412.372556 -397.678402)
		(width 0.14732)
		(layer "In2.Cu")
		(net "P5E_CPU0_PE3_TX_DN<2>")
	)
	(segment
		(start 412.258764 -397.256762)
		(end 412.10611 -397.169132)
		(width 0.14732)
		(layer "In2.Cu")
		(net "P5E_CPU0_PE3_TX_DN<2>")
	)
	(segment
		(start 380.083314 -286.964882)
		(end 380.08306 -286.964882)
		(width 0.0889)
		(layer "In2.Cu")
		(net "P5E_CPU0_PE3_TX_DN<2>")
	)
	(segment
		(start 413.07131 -404.104856)
		(end 413.07131 -400.267424)
		(width 0.14732)
		(layer "In2.Cu")
		(net "P5E_CPU0_PE3_TX_DN<2>")
	)
	(segment
		(start 386.750306 -296.490898)
		(end 385.687316 -293.924482)
		(width 0.14732)
		(layer "In2.Cu")
		(net "P5E_CPU0_PE3_TX_DN<2>")
	)
	(segment
		(start 381.047752 -289.255962)
		(end 381.062992 -289.255962)
		(width 0.0889)
		(layer "In2.Cu")
		(net "P5E_CPU0_PE3_TX_DN<2>")
	)
	(segment
		(start 402.933408 -323.742304)
		(end 388.246874 -304.88001)
		(width 0.14732)
		(layer "In2.Cu")
		(net "P5E_CPU0_PE3_TX_DN<2>")
	)
	(segment
		(start 411.992064 -396.746984)
		(end 412.079948 -396.59433)
		(width 0.14732)
		(layer "In2.Cu")
		(net "P5E_CPU0_PE3_TX_DN<2>")
	)
	(segment
		(start 404.624286 -367.937542)
		(end 405.018494 -334.880712)
		(width 0.14732)
		(layer "In2.Cu")
		(net "P5E_CPU0_PE3_TX_DN<2>")
	)
	(segment
		(start 381.025654 -289.27806)
		(end 381.047752 -289.255962)
		(width 0.0889)
		(layer "In2.Cu")
		(net "P5E_CPU0_PE3_TX_DN<2>")
	)
	(segment
		(start 379.58268 -286.204406)
		(end 379.426216 -286.475424)
		(width 0.0889)
		(layer "In2.Cu")
		(net "P5E_CPU0_PE3_TX_DN<2>")
	)
	(segment
		(start 380.74092 -288.103056)
		(end 380.740666 -288.103056)
		(width 0.0889)
		(layer "In2.Cu")
		(net "P5E_CPU0_PE3_TX_DN<2>")
	)
	(segment
		(start 384.550666 -292.787832)
		(end 381.257302 -291.423598)
		(width 0.14732)
		(layer "In2.Cu")
		(net "P5E_CPU0_PE3_TX_DN<2>")
	)
	(segment
		(start 380.553214 -287.778698)
		(end 380.542546 -287.772856)
		(width 0.0889)
		(layer "In2.Cu")
		(net "P5E_CPU0_PE3_TX_DN<2>")
	)
	(segment
		(start 380.270512 -287.28924)
		(end 380.270512 -287.281366)
		(width 0.0889)
		(layer "In2.Cu")
		(net "P5E_CPU0_PE3_TX_DN<2>")
	)
	(arc
		(start 381.063246 -289.256216)
		(mid 381.163225 -289.149069)
		(end 381.20574 -289.00882)
		(width 0.0889)
		(layer "In2.Cu")
		(net "P5E_CPU0_PE3_TX_DN<2>")
	)
	(arc
		(start 381.011938 -288.585656)
		(mid 380.813297 -288.379807)
		(end 380.74092 -288.103056)
		(width 0.0889)
		(layer "In2.Cu")
		(net "P5E_CPU0_PE3_TX_DN<2>")
	)
	(arc
		(start 380.542546 -287.772856)
		(mid 380.343115 -287.566715)
		(end 380.270512 -287.28924)
		(width 0.0889)
		(layer "In2.Cu")
		(net "P5E_CPU0_PE3_TX_DN<2>")
	)
	(arc
		(start 380.740666 -288.103056)
		(mid 380.691674 -287.918148)
		(end 380.557786 -287.781492)
		(width 0.0889)
		(layer "In2.Cu")
		(net "P5E_CPU0_PE3_TX_DN<2>")
	)
	(arc
		(start 379.800612 -286.466788)
		(mid 379.761938 -286.30972)
		(end 379.660658 -286.183578)
		(width 0.0889)
		(layer "In2.Cu")
		(net "P5E_CPU0_PE3_TX_DN<2>")
	)
	(arc
		(start 380.270512 -287.281366)
		(mid 380.218444 -287.098543)
		(end 380.083314 -286.964882)
		(width 0.0889)
		(layer "In2.Cu")
		(net "P5E_CPU0_PE3_TX_DN<2>")
	)
	(arc
		(start 380.740666 -289.609784)
		(mid 380.748055 -289.589706)
		(end 380.75616 -289.569906)
		(width 0.0889)
		(layer "In2.Cu")
		(net "P5E_CPU0_PE3_TX_DN<2>")
	)
	(arc
		(start 381.210058 -288.944558)
		(mid 381.166497 -288.741077)
		(end 381.021844 -288.591498)
		(width 0.0889)
		(layer "In2.Cu")
		(net "P5E_CPU0_PE3_TX_DN<2>")
	)
	(arc
		(start 380.75616 -289.569906)
		(mid 380.865987 -289.401067)
		(end 381.025654 -289.278314)
		(width 0.0889)
		(layer "In2.Cu")
		(net "P5E_CPU0_PE3_TX_DN<2>")
	)
	(arc
		(start 380.08306 -286.964882)
		(mid 379.878725 -286.762277)
		(end 379.800612 -286.48533)
		(width 0.0889)
		(layer "In2.Cu")
		(net "P5E_CPU0_PE3_TX_DN<2>")
	)
	(segment
		(start 415.960052 -407.924254)
		(end 415.633662 -408.250644)
		(width 0.13208)
		(layer "F.Cu")
		(net "P5E_CPU0_PE3_TX_DN<1>")
	)
	(segment
		(start 415.633662 -408.250644)
		(end 415.62909 -408.250644)
		(width 0.13208)
		(layer "F.Cu")
		(net "P5E_CPU0_PE3_TX_DN<1>")
	)
	(segment
		(start 415.960052 -407.310082)
		(end 415.960052 -407.924254)
		(width 0.13208)
		(layer "F.Cu")
		(net "P5E_CPU0_PE3_TX_DN<1>")
	)
	(segment
		(start 380.365762 -284.311598)
		(end 380.366016 -284.847538)
		(width 0.13208)
		(layer "F.Cu")
		(net "P5E_CPU0_PE3_TX_DN<1>")
	)
	(segment
		(start 415.65449 -407.00452)
		(end 415.960052 -407.310082)
		(width 0.13208)
		(layer "F.Cu")
		(net "P5E_CPU0_PE3_TX_DN<1>")
	)
	(segment
		(start 383.852674 -291.45611)
		(end 382.787398 -290.390834)
		(width 0.14732)
		(layer "In2.Cu")
		(net "P5E_CPU0_PE3_TX_DN<1>")
	)
	(segment
		(start 382.771904 -290.316412)
		(end 382.620012 -290.16452)
		(width 0.0889)
		(layer "In2.Cu")
		(net "P5E_CPU0_PE3_TX_DN<1>")
	)
	(segment
		(start 389.139684 -304.506884)
		(end 387.683248 -296.246296)
		(width 0.14732)
		(layer "In2.Cu")
		(net "P5E_CPU0_PE3_TX_DN<1>")
	)
	(segment
		(start 385.202938 -292.015418)
		(end 383.852674 -291.45611)
		(width 0.14732)
		(layer "In2.Cu")
		(net "P5E_CPU0_PE3_TX_DN<1>")
	)
	(segment
		(start 415.94913 -405.988266)
		(end 416.13455 -404.104856)
		(width 0.14732)
		(layer "In2.Cu")
		(net "P5E_CPU0_PE3_TX_DN<1>")
	)
	(segment
		(start 380.56185 -286.156146)
		(end 380.55296 -286.151066)
		(width 0.0889)
		(layer "In2.Cu")
		(net "P5E_CPU0_PE3_TX_DN<1>")
	)
	(segment
		(start 382.150112 -289.11423)
		(end 382.150366 -288.91738)
		(width 0.0889)
		(layer "In2.Cu")
		(net "P5E_CPU0_PE3_TX_DN<1>")
	)
	(segment
		(start 415.65449 -407.00452)
		(end 415.94913 -406.70988)
		(width 0.14732)
		(layer "In2.Cu")
		(net "P5E_CPU0_PE3_TX_DN<1>")
	)
	(segment
		(start 381.480822 -287.771586)
		(end 381.479806 -287.770824)
		(width 0.0889)
		(layer "In2.Cu")
		(net "P5E_CPU0_PE3_TX_DN<1>")
	)
	(segment
		(start 405.887174 -369.805458)
		(end 405.623776 -367.888774)
		(width 0.14732)
		(layer "In2.Cu")
		(net "P5E_CPU0_PE3_TX_DN<1>")
	)
	(segment
		(start 416.13455 -404.104856)
		(end 416.13455 -400.44624)
		(width 0.14732)
		(layer "In2.Cu")
		(net "P5E_CPU0_PE3_TX_DN<1>")
	)
	(segment
		(start 415.94913 -406.70988)
		(end 415.94913 -405.988266)
		(width 0.14732)
		(layer "In2.Cu")
		(net "P5E_CPU0_PE3_TX_DN<1>")
	)
	(segment
		(start 380.270512 -285.679896)
		(end 380.270512 -285.661354)
		(width 0.0889)
		(layer "In2.Cu")
		(net "P5E_CPU0_PE3_TX_DN<1>")
	)
	(segment
		(start 382.787398 -290.390834)
		(end 382.771904 -290.37534)
		(width 0.0889)
		(layer "In2.Cu")
		(net "P5E_CPU0_PE3_TX_DN<1>")
	)
	(segment
		(start 382.771904 -290.37534)
		(end 382.771904 -290.316412)
		(width 0.0889)
		(layer "In2.Cu")
		(net "P5E_CPU0_PE3_TX_DN<1>")
	)
	(segment
		(start 381.68072 -288.113724)
		(end 381.68072 -288.103056)
		(width 0.0889)
		(layer "In2.Cu")
		(net "P5E_CPU0_PE3_TX_DN<1>")
	)
	(segment
		(start 380.52248 -285.118556)
		(end 380.366016 -284.847538)
		(width 0.0889)
		(layer "In2.Cu")
		(net "P5E_CPU0_PE3_TX_DN<1>")
	)
	(segment
		(start 380.49835 -285.20771)
		(end 380.52248 -285.118556)
		(width 0.0889)
		(layer "In2.Cu")
		(net "P5E_CPU0_PE3_TX_DN<1>")
	)
	(segment
		(start 381.028194 -286.967676)
		(end 381.016764 -286.960818)
		(width 0.0889)
		(layer "In2.Cu")
		(net "P5E_CPU0_PE3_TX_DN<1>")
	)
	(segment
		(start 386.446014 -293.258494)
		(end 385.202938 -292.015418)
		(width 0.14732)
		(layer "In2.Cu")
		(net "P5E_CPU0_PE3_TX_DN<1>")
	)
	(segment
		(start 381.972058 -288.597848)
		(end 381.963168 -288.593022)
		(width 0.0889)
		(layer "In2.Cu")
		(net "P5E_CPU0_PE3_TX_DN<1>")
	)
	(segment
		(start 381.016764 -286.960818)
		(end 381.016764 -286.961326)
		(width 0.0889)
		(layer "In2.Cu")
		(net "P5E_CPU0_PE3_TX_DN<1>")
	)
	(segment
		(start 387.683248 -296.246296)
		(end 386.446014 -293.258494)
		(width 0.14732)
		(layer "In2.Cu")
		(net "P5E_CPU0_PE3_TX_DN<1>")
	)
	(segment
		(start 405.520398 -332.719426)
		(end 403.885146 -323.445378)
		(width 0.14732)
		(layer "In2.Cu")
		(net "P5E_CPU0_PE3_TX_DN<1>")
	)
	(segment
		(start 381.963168 -288.593022)
		(end 381.963168 -288.59226)
		(width 0.0889)
		(layer "In2.Cu")
		(net "P5E_CPU0_PE3_TX_DN<1>")
	)
	(segment
		(start 405.99614 -334.822292)
		(end 405.520398 -332.719426)
		(width 0.14732)
		(layer "In2.Cu")
		(net "P5E_CPU0_PE3_TX_DN<1>")
	)
	(segment
		(start 382.620012 -290.16452)
		(end 382.620012 -289.63112)
		(width 0.0889)
		(layer "In2.Cu")
		(net "P5E_CPU0_PE3_TX_DN<1>")
	)
	(segment
		(start 381.496316 -287.780222)
		(end 381.480822 -287.771586)
		(width 0.0889)
		(layer "In2.Cu")
		(net "P5E_CPU0_PE3_TX_DN<1>")
	)
	(segment
		(start 405.623776 -367.888774)
		(end 405.99614 -334.822292)
		(width 0.14732)
		(layer "In2.Cu")
		(net "P5E_CPU0_PE3_TX_DN<1>")
	)
	(segment
		(start 403.885146 -323.445378)
		(end 389.139684 -304.506884)
		(width 0.14732)
		(layer "In2.Cu")
		(net "P5E_CPU0_PE3_TX_DN<1>")
	)
	(segment
		(start 382.620012 -289.63112)
		(end 382.435862 -289.44697)
		(width 0.0889)
		(layer "In2.Cu")
		(net "P5E_CPU0_PE3_TX_DN<1>")
	)
	(segment
		(start 416.13455 -400.44624)
		(end 405.887174 -369.805458)
		(width 0.14732)
		(layer "In2.Cu")
		(net "P5E_CPU0_PE3_TX_DN<1>")
	)
	(arc
		(start 381.016764 -286.961326)
		(mid 380.814351 -286.754913)
		(end 380.740412 -286.475424)
		(width 0.0889)
		(layer "In2.Cu")
		(net "P5E_CPU0_PE3_TX_DN<1>")
	)
	(arc
		(start 382.435862 -289.44697)
		(mid 382.261444 -289.307699)
		(end 382.150112 -289.11423)
		(width 0.0889)
		(layer "In2.Cu")
		(net "P5E_CPU0_PE3_TX_DN<1>")
	)
	(arc
		(start 381.479806 -287.770824)
		(mid 381.282568 -287.565078)
		(end 381.21082 -287.28924)
		(width 0.0889)
		(layer "In2.Cu")
		(net "P5E_CPU0_PE3_TX_DN<1>")
	)
	(arc
		(start 381.21082 -287.28924)
		(mid 381.161923 -287.104366)
		(end 381.028194 -286.967676)
		(width 0.0889)
		(layer "In2.Cu")
		(net "P5E_CPU0_PE3_TX_DN<1>")
	)
	(arc
		(start 380.55296 -286.151066)
		(mid 380.350674 -285.952085)
		(end 380.270512 -285.679896)
		(width 0.0889)
		(layer "In2.Cu")
		(net "P5E_CPU0_PE3_TX_DN<1>")
	)
	(arc
		(start 380.740412 -286.475424)
		(mid 380.692733 -286.292524)
		(end 380.56185 -286.156146)
		(width 0.0889)
		(layer "In2.Cu")
		(net "P5E_CPU0_PE3_TX_DN<1>")
	)
	(arc
		(start 381.963168 -288.59226)
		(mid 381.759009 -288.390136)
		(end 381.68072 -288.113724)
		(width 0.0889)
		(layer "In2.Cu")
		(net "P5E_CPU0_PE3_TX_DN<1>")
	)
	(arc
		(start 381.68072 -288.103056)
		(mid 381.631379 -287.917148)
		(end 381.496316 -287.780222)
		(width 0.0889)
		(layer "In2.Cu")
		(net "P5E_CPU0_PE3_TX_DN<1>")
	)
	(arc
		(start 380.481332 -285.220918)
		(mid 380.489778 -285.214233)
		(end 380.49835 -285.20771)
		(width 0.0889)
		(layer "In2.Cu")
		(net "P5E_CPU0_PE3_TX_DN<1>")
	)
	(arc
		(start 382.150366 -288.91738)
		(mid 382.102896 -288.734346)
		(end 381.972058 -288.597848)
		(width 0.0889)
		(layer "In2.Cu")
		(net "P5E_CPU0_PE3_TX_DN<1>")
	)
	(arc
		(start 380.270512 -285.661354)
		(mid 380.325867 -285.417167)
		(end 380.481332 -285.220918)
		(width 0.0889)
		(layer "In2.Cu")
		(net "P5E_CPU0_PE3_TX_DN<1>")
	)
	(segment
		(start 372.76913 -407.00452)
		(end 373.074692 -407.310082)
		(width 0.13208)
		(layer "F.Cu")
		(net "P5E_CPU0_PE3_TX_DN<15>")
	)
	(segment
		(start 373.074692 -407.924254)
		(end 372.748302 -408.250644)
		(width 0.13208)
		(layer "F.Cu")
		(net "P5E_CPU0_PE3_TX_DN<15>")
	)
	(segment
		(start 372.748302 -408.250644)
		(end 372.74373 -408.250644)
		(width 0.13208)
		(layer "F.Cu")
		(net "P5E_CPU0_PE3_TX_DN<15>")
	)
	(segment
		(start 373.074692 -407.310082)
		(end 373.074692 -407.924254)
		(width 0.13208)
		(layer "F.Cu")
		(net "P5E_CPU0_PE3_TX_DN<15>")
	)
	(segment
		(start 367.208562 -284.311598)
		(end 367.208816 -284.847538)
		(width 0.13208)
		(layer "F.Cu")
		(net "P5E_CPU0_PE3_TX_DN<15>")
	)
	(segment
		(start 366.517936 -292.243256)
		(end 367.541556 -291.219636)
		(width 0.14732)
		(layer "In2.Cu")
		(net "P5E_CPU0_PE3_TX_DN<15>")
	)
	(segment
		(start 367.541556 -290.393628)
		(end 367.583466 -290.351718)
		(width 0.0889)
		(layer "In2.Cu")
		(net "P5E_CPU0_PE3_TX_DN<15>")
	)
	(segment
		(start 368.34445 -287.783778)
		(end 368.33556 -287.778698)
		(width 0.0889)
		(layer "In2.Cu")
		(net "P5E_CPU0_PE3_TX_DN<15>")
	)
	(segment
		(start 368.33556 -288.427414)
		(end 368.34445 -288.422334)
		(width 0.0889)
		(layer "In2.Cu")
		(net "P5E_CPU0_PE3_TX_DN<15>")
	)
	(segment
		(start 367.404904 -286.156146)
		(end 367.396014 -286.151066)
		(width 0.0889)
		(layer "In2.Cu")
		(net "P5E_CPU0_PE3_TX_DN<15>")
	)
	(segment
		(start 372.76913 -407.00452)
		(end 373.06377 -406.70988)
		(width 0.14732)
		(layer "In2.Cu")
		(net "P5E_CPU0_PE3_TX_DN<15>")
	)
	(segment
		(start 367.36528 -285.118556)
		(end 367.208816 -284.847538)
		(width 0.0889)
		(layer "In2.Cu")
		(net "P5E_CPU0_PE3_TX_DN<15>")
	)
	(segment
		(start 367.583466 -290.351718)
		(end 367.583466 -289.611054)
		(width 0.0889)
		(layer "In2.Cu")
		(net "P5E_CPU0_PE3_TX_DN<15>")
	)
	(segment
		(start 373.24919 -404.104856)
		(end 373.24919 -399.897346)
		(width 0.14732)
		(layer "In2.Cu")
		(net "P5E_CPU0_PE3_TX_DN<15>")
	)
	(segment
		(start 366.517936 -296.461688)
		(end 366.517936 -292.243256)
		(width 0.14732)
		(layer "In2.Cu")
		(net "P5E_CPU0_PE3_TX_DN<15>")
	)
	(segment
		(start 368.053112 -287.299146)
		(end 368.053112 -287.280604)
		(width 0.0889)
		(layer "In2.Cu")
		(net "P5E_CPU0_PE3_TX_DN<15>")
	)
	(segment
		(start 366.785906 -297.981624)
		(end 366.517936 -296.461688)
		(width 0.14732)
		(layer "In2.Cu")
		(net "P5E_CPU0_PE3_TX_DN<15>")
	)
	(segment
		(start 373.24919 -399.897346)
		(end 392.061954 -348.435422)
		(width 0.14732)
		(layer "In2.Cu")
		(net "P5E_CPU0_PE3_TX_DN<15>")
	)
	(segment
		(start 373.06377 -406.70988)
		(end 373.06377 -405.988266)
		(width 0.14732)
		(layer "In2.Cu")
		(net "P5E_CPU0_PE3_TX_DN<15>")
	)
	(segment
		(start 392.061954 -348.435422)
		(end 392.061954 -333.444596)
		(width 0.14732)
		(layer "In2.Cu")
		(net "P5E_CPU0_PE3_TX_DN<15>")
	)
	(segment
		(start 367.34115 -285.20771)
		(end 367.36528 -285.118556)
		(width 0.0889)
		(layer "In2.Cu")
		(net "P5E_CPU0_PE3_TX_DN<15>")
	)
	(segment
		(start 367.613692 -299.16374)
		(end 366.785906 -297.981624)
		(width 0.14732)
		(layer "In2.Cu")
		(net "P5E_CPU0_PE3_TX_DN<15>")
	)
	(segment
		(start 391.373106 -329.53833)
		(end 367.613692 -299.16374)
		(width 0.14732)
		(layer "In2.Cu")
		(net "P5E_CPU0_PE3_TX_DN<15>")
	)
	(segment
		(start 392.061954 -333.444596)
		(end 391.373106 -329.53833)
		(width 0.14732)
		(layer "In2.Cu")
		(net "P5E_CPU0_PE3_TX_DN<15>")
	)
	(segment
		(start 367.113312 -285.675578)
		(end 367.113312 -285.661354)
		(width 0.0889)
		(layer "In2.Cu")
		(net "P5E_CPU0_PE3_TX_DN<15>")
	)
	(segment
		(start 367.583466 -289.611054)
		(end 367.583212 -289.6108)
		(width 0.0889)
		(layer "In2.Cu")
		(net "P5E_CPU0_PE3_TX_DN<15>")
	)
	(segment
		(start 368.053366 -289.077908)
		(end 368.053366 -288.895028)
		(width 0.0889)
		(layer "In2.Cu")
		(net "P5E_CPU0_PE3_TX_DN<15>")
	)
	(segment
		(start 367.583466 -286.48533)
		(end 367.583466 -286.475424)
		(width 0.0889)
		(layer "In2.Cu")
		(net "P5E_CPU0_PE3_TX_DN<15>")
	)
	(segment
		(start 373.06377 -405.988266)
		(end 373.24919 -404.104856)
		(width 0.14732)
		(layer "In2.Cu")
		(net "P5E_CPU0_PE3_TX_DN<15>")
	)
	(segment
		(start 367.541556 -291.219636)
		(end 367.541556 -290.415726)
		(width 0.14732)
		(layer "In2.Cu")
		(net "P5E_CPU0_PE3_TX_DN<15>")
	)
	(segment
		(start 367.583212 -289.6108)
		(end 367.583212 -289.609784)
		(width 0.0889)
		(layer "In2.Cu")
		(net "P5E_CPU0_PE3_TX_DN<15>")
	)
	(segment
		(start 367.541556 -290.415726)
		(end 367.541556 -290.393628)
		(width 0.0889)
		(layer "In2.Cu")
		(net "P5E_CPU0_PE3_TX_DN<15>")
	)
	(arc
		(start 367.865914 -286.964882)
		(mid 367.661579 -286.762277)
		(end 367.583466 -286.48533)
		(width 0.0889)
		(layer "In2.Cu")
		(net "P5E_CPU0_PE3_TX_DN<15>")
	)
	(arc
		(start 368.33556 -287.778698)
		(mid 368.131225 -287.576093)
		(end 368.053112 -287.299146)
		(width 0.0889)
		(layer "In2.Cu")
		(net "P5E_CPU0_PE3_TX_DN<15>")
	)
	(arc
		(start 368.053366 -288.895028)
		(mid 368.134277 -288.6249)
		(end 368.33556 -288.427414)
		(width 0.0889)
		(layer "In2.Cu")
		(net "P5E_CPU0_PE3_TX_DN<15>")
	)
	(arc
		(start 367.113312 -285.661354)
		(mid 367.173428 -285.407517)
		(end 367.34115 -285.20771)
		(width 0.0889)
		(layer "In2.Cu")
		(net "P5E_CPU0_PE3_TX_DN<15>")
	)
	(arc
		(start 367.583212 -289.609784)
		(mid 367.590368 -289.590223)
		(end 367.598198 -289.570922)
		(width 0.0889)
		(layer "In2.Cu")
		(net "P5E_CPU0_PE3_TX_DN<15>")
	)
	(arc
		(start 368.053112 -287.280604)
		(mid 368.000842 -287.098239)
		(end 367.865914 -286.964882)
		(width 0.0889)
		(layer "In2.Cu")
		(net "P5E_CPU0_PE3_TX_DN<15>")
	)
	(arc
		(start 367.868962 -289.277806)
		(mid 367.978358 -289.193709)
		(end 368.053366 -289.077908)
		(width 0.0889)
		(layer "In2.Cu")
		(net "P5E_CPU0_PE3_TX_DN<15>")
	)
	(arc
		(start 367.583466 -286.475424)
		(mid 367.535787 -286.292524)
		(end 367.404904 -286.156146)
		(width 0.0889)
		(layer "In2.Cu")
		(net "P5E_CPU0_PE3_TX_DN<15>")
	)
	(arc
		(start 367.598198 -289.570922)
		(mid 367.708455 -289.401162)
		(end 367.868962 -289.277806)
		(width 0.0889)
		(layer "In2.Cu")
		(net "P5E_CPU0_PE3_TX_DN<15>")
	)
	(arc
		(start 367.396014 -286.151066)
		(mid 367.192533 -285.950262)
		(end 367.113312 -285.675578)
		(width 0.0889)
		(layer "In2.Cu")
		(net "P5E_CPU0_PE3_TX_DN<15>")
	)
	(arc
		(start 368.34445 -288.422334)
		(mid 368.523047 -288.103056)
		(end 368.34445 -287.783778)
		(width 0.0889)
		(layer "In2.Cu")
		(net "P5E_CPU0_PE3_TX_DN<15>")
	)
	(segment
		(start 368.148362 -285.939484)
		(end 368.148362 -286.47517)
		(width 0.13208)
		(layer "F.Cu")
		(net "P5E_CPU0_PE3_TX_DN<14>")
	)
	(segment
		(start 376.137932 -407.924254)
		(end 375.811542 -408.250644)
		(width 0.13208)
		(layer "F.Cu")
		(net "P5E_CPU0_PE3_TX_DN<14>")
	)
	(segment
		(start 375.811542 -408.250644)
		(end 375.80697 -408.250644)
		(width 0.13208)
		(layer "F.Cu")
		(net "P5E_CPU0_PE3_TX_DN<14>")
	)
	(segment
		(start 375.83237 -407.00452)
		(end 376.137932 -407.310082)
		(width 0.13208)
		(layer "F.Cu")
		(net "P5E_CPU0_PE3_TX_DN<14>")
	)
	(segment
		(start 376.137932 -407.310082)
		(end 376.137932 -407.924254)
		(width 0.13208)
		(layer "F.Cu")
		(net "P5E_CPU0_PE3_TX_DN<14>")
	)
	(segment
		(start 368.148362 -286.47517)
		(end 368.148616 -286.475424)
		(width 0.13208)
		(layer "F.Cu")
		(net "P5E_CPU0_PE3_TX_DN<14>")
	)
	(segment
		(start 369.420902 -290.117784)
		(end 369.462812 -290.075874)
		(width 0.0889)
		(layer "In2.Cu")
		(net "P5E_CPU0_PE3_TX_DN<14>")
	)
	(segment
		(start 393.032234 -333.550768)
		(end 392.24966 -329.112372)
		(width 0.14732)
		(layer "In2.Cu")
		(net "P5E_CPU0_PE3_TX_DN<14>")
	)
	(segment
		(start 368.81435 -286.969962)
		(end 368.80546 -286.964882)
		(width 0.0889)
		(layer "In2.Cu")
		(net "P5E_CPU0_PE3_TX_DN<14>")
	)
	(segment
		(start 369.754404 -288.597848)
		(end 369.745514 -288.592768)
		(width 0.0889)
		(layer "In2.Cu")
		(net "P5E_CPU0_PE3_TX_DN<14>")
	)
	(segment
		(start 369.463066 -288.121598)
		(end 369.463066 -288.081466)
		(width 0.0889)
		(layer "In2.Cu")
		(net "P5E_CPU0_PE3_TX_DN<14>")
	)
	(segment
		(start 369.269518 -287.774888)
		(end 369.269518 -287.775142)
		(width 0.0889)
		(layer "In2.Cu")
		(net "P5E_CPU0_PE3_TX_DN<14>")
	)
	(segment
		(start 369.278916 -287.78073)
		(end 369.276376 -287.779206)
		(width 0.0889)
		(layer "In2.Cu")
		(net "P5E_CPU0_PE3_TX_DN<14>")
	)
	(segment
		(start 377.386342 -396.555976)
		(end 377.386342 -396.555468)
		(width 0.14732)
		(layer "In2.Cu")
		(net "P5E_CPU0_PE3_TX_DN<14>")
	)
	(segment
		(start 392.24966 -329.112372)
		(end 369.761516 -300.250606)
		(width 0.14732)
		(layer "In2.Cu")
		(net "P5E_CPU0_PE3_TX_DN<14>")
	)
	(segment
		(start 375.83237 -407.00452)
		(end 376.12701 -406.70988)
		(width 0.14732)
		(layer "In2.Cu")
		(net "P5E_CPU0_PE3_TX_DN<14>")
	)
	(segment
		(start 369.420902 -290.139882)
		(end 369.420902 -290.117784)
		(width 0.0889)
		(layer "In2.Cu")
		(net "P5E_CPU0_PE3_TX_DN<14>")
	)
	(segment
		(start 369.275614 -287.778698)
		(end 369.269518 -287.774888)
		(width 0.0889)
		(layer "In2.Cu")
		(net "P5E_CPU0_PE3_TX_DN<14>")
	)
	(segment
		(start 377.386342 -396.555468)
		(end 393.032234 -348.46387)
		(width 0.14732)
		(layer "In2.Cu")
		(net "P5E_CPU0_PE3_TX_DN<14>")
	)
	(segment
		(start 369.420902 -292.753034)
		(end 369.420902 -290.139882)
		(width 0.14732)
		(layer "In2.Cu")
		(net "P5E_CPU0_PE3_TX_DN<14>")
	)
	(segment
		(start 376.31243 -404.104856)
		(end 376.31243 -399.856452)
		(width 0.14732)
		(layer "In2.Cu")
		(net "P5E_CPU0_PE3_TX_DN<14>")
	)
	(segment
		(start 376.881644 -397.703802)
		(end 377.03887 -397.623792)
		(width 0.14732)
		(layer "In2.Cu")
		(net "P5E_CPU0_PE3_TX_DN<14>")
	)
	(segment
		(start 368.86388 -293.310056)
		(end 369.420902 -292.753034)
		(width 0.14732)
		(layer "In2.Cu")
		(net "P5E_CPU0_PE3_TX_DN<14>")
	)
	(segment
		(start 376.746516 -398.119346)
		(end 376.881644 -397.703802)
		(width 0.14732)
		(layer "In2.Cu")
		(net "P5E_CPU0_PE3_TX_DN<14>")
	)
	(segment
		(start 377.093988 -397.05153)
		(end 377.229116 -396.635986)
		(width 0.14732)
		(layer "In2.Cu")
		(net "P5E_CPU0_PE3_TX_DN<14>")
	)
	(segment
		(start 377.229116 -396.635986)
		(end 377.386342 -396.555976)
		(width 0.14732)
		(layer "In2.Cu")
		(net "P5E_CPU0_PE3_TX_DN<14>")
	)
	(segment
		(start 368.383058 -286.183578)
		(end 368.30508 -286.204406)
		(width 0.0889)
		(layer "In2.Cu")
		(net "P5E_CPU0_PE3_TX_DN<14>")
	)
	(segment
		(start 376.31243 -399.856452)
		(end 376.826526 -398.276318)
		(width 0.14732)
		(layer "In2.Cu")
		(net "P5E_CPU0_PE3_TX_DN<14>")
	)
	(segment
		(start 393.032234 -348.46387)
		(end 393.032234 -333.550768)
		(width 0.14732)
		(layer "In2.Cu")
		(net "P5E_CPU0_PE3_TX_DN<14>")
	)
	(segment
		(start 377.173998 -397.208502)
		(end 377.093988 -397.05153)
		(width 0.14732)
		(layer "In2.Cu")
		(net "P5E_CPU0_PE3_TX_DN<14>")
	)
	(segment
		(start 369.276376 -287.779206)
		(end 369.275614 -287.778698)
		(width 0.0889)
		(layer "In2.Cu")
		(net "P5E_CPU0_PE3_TX_DN<14>")
	)
	(segment
		(start 369.761516 -300.250606)
		(end 369.12042 -299.336206)
		(width 0.14732)
		(layer "In2.Cu")
		(net "P5E_CPU0_PE3_TX_DN<14>")
	)
	(segment
		(start 376.12701 -405.988266)
		(end 376.31243 -404.104856)
		(width 0.14732)
		(layer "In2.Cu")
		(net "P5E_CPU0_PE3_TX_DN<14>")
	)
	(segment
		(start 369.932966 -289.037268)
		(end 369.932966 -288.917126)
		(width 0.0889)
		(layer "In2.Cu")
		(net "P5E_CPU0_PE3_TX_DN<14>")
	)
	(segment
		(start 369.463066 -288.081466)
		(end 369.46078 -288.061146)
		(width 0.0889)
		(layer "In2.Cu")
		(net "P5E_CPU0_PE3_TX_DN<14>")
	)
	(segment
		(start 369.284758 -287.784032)
		(end 369.279932 -287.781238)
		(width 0.0889)
		(layer "In2.Cu")
		(net "P5E_CPU0_PE3_TX_DN<14>")
	)
	(segment
		(start 368.30508 -286.204406)
		(end 368.148616 -286.475424)
		(width 0.0889)
		(layer "In2.Cu")
		(net "P5E_CPU0_PE3_TX_DN<14>")
	)
	(segment
		(start 369.12042 -299.336206)
		(end 368.86388 -297.876468)
		(width 0.14732)
		(layer "In2.Cu")
		(net "P5E_CPU0_PE3_TX_DN<14>")
	)
	(segment
		(start 376.12701 -406.70988)
		(end 376.12701 -405.988266)
		(width 0.14732)
		(layer "In2.Cu")
		(net "P5E_CPU0_PE3_TX_DN<14>")
	)
	(segment
		(start 368.86388 -297.876468)
		(end 368.86388 -293.310056)
		(width 0.14732)
		(layer "In2.Cu")
		(net "P5E_CPU0_PE3_TX_DN<14>")
	)
	(segment
		(start 369.279932 -287.781238)
		(end 369.278916 -287.78073)
		(width 0.0889)
		(layer "In2.Cu")
		(net "P5E_CPU0_PE3_TX_DN<14>")
	)
	(segment
		(start 369.462812 -290.075874)
		(end 369.462812 -289.6997)
		(width 0.0889)
		(layer "In2.Cu")
		(net "P5E_CPU0_PE3_TX_DN<14>")
	)
	(segment
		(start 376.826526 -398.276318)
		(end 376.746516 -398.119346)
		(width 0.14732)
		(layer "In2.Cu")
		(net "P5E_CPU0_PE3_TX_DN<14>")
	)
	(segment
		(start 369.284504 -287.783778)
		(end 369.284758 -287.784032)
		(width 0.0889)
		(layer "In2.Cu")
		(net "P5E_CPU0_PE3_TX_DN<14>")
	)
	(segment
		(start 377.03887 -397.623792)
		(end 377.173998 -397.208502)
		(width 0.14732)
		(layer "In2.Cu")
		(net "P5E_CPU0_PE3_TX_DN<14>")
	)
	(segment
		(start 369.684808 -289.33394)
		(end 369.68557 -289.333178)
		(width 0.0889)
		(layer "In2.Cu")
		(net "P5E_CPU0_PE3_TX_DN<14>")
	)
	(segment
		(start 368.523012 -286.48533)
		(end 368.523012 -286.466788)
		(width 0.0889)
		(layer "In2.Cu")
		(net "P5E_CPU0_PE3_TX_DN<14>")
	)
	(arc
		(start 369.534186 -289.495484)
		(mid 369.606687 -289.412092)
		(end 369.684808 -289.33394)
		(width 0.0889)
		(layer "In2.Cu")
		(net "P5E_CPU0_PE3_TX_DN<14>")
	)
	(arc
		(start 369.269518 -287.775142)
		(mid 369.066931 -287.568791)
		(end 368.992912 -287.28924)
		(width 0.0889)
		(layer "In2.Cu")
		(net "P5E_CPU0_PE3_TX_DN<14>")
	)
	(arc
		(start 368.523012 -286.466788)
		(mid 368.484338 -286.30972)
		(end 368.383058 -286.183578)
		(width 0.0889)
		(layer "In2.Cu")
		(net "P5E_CPU0_PE3_TX_DN<14>")
	)
	(arc
		(start 369.462812 -289.6997)
		(mid 369.480905 -289.591435)
		(end 369.534186 -289.495484)
		(width 0.0889)
		(layer "In2.Cu")
		(net "P5E_CPU0_PE3_TX_DN<14>")
	)
	(arc
		(start 369.46078 -288.061146)
		(mid 369.404684 -287.902094)
		(end 369.284504 -287.783778)
		(width 0.0889)
		(layer "In2.Cu")
		(net "P5E_CPU0_PE3_TX_DN<14>")
	)
	(arc
		(start 369.932966 -288.917126)
		(mid 369.885287 -288.734226)
		(end 369.754404 -288.597848)
		(width 0.0889)
		(layer "In2.Cu")
		(net "P5E_CPU0_PE3_TX_DN<14>")
	)
	(arc
		(start 368.992912 -287.28924)
		(mid 368.945233 -287.10634)
		(end 368.81435 -286.969962)
		(width 0.0889)
		(layer "In2.Cu")
		(net "P5E_CPU0_PE3_TX_DN<14>")
	)
	(arc
		(start 369.68557 -289.333178)
		(mid 369.731844 -289.293783)
		(end 369.781328 -289.258502)
		(width 0.0889)
		(layer "In2.Cu")
		(net "P5E_CPU0_PE3_TX_DN<14>")
	)
	(arc
		(start 369.781328 -289.258502)
		(mid 369.853542 -289.198397)
		(end 369.910106 -289.123374)
		(width 0.0889)
		(layer "In2.Cu")
		(net "P5E_CPU0_PE3_TX_DN<14>")
	)
	(arc
		(start 368.80546 -286.964882)
		(mid 368.601125 -286.762277)
		(end 368.523012 -286.48533)
		(width 0.0889)
		(layer "In2.Cu")
		(net "P5E_CPU0_PE3_TX_DN<14>")
	)
	(arc
		(start 369.910106 -289.123374)
		(mid 369.92732 -289.081853)
		(end 369.932966 -289.037268)
		(width 0.0889)
		(layer "In2.Cu")
		(net "P5E_CPU0_PE3_TX_DN<14>")
	)
	(arc
		(start 369.745514 -288.592768)
		(mid 369.543228 -288.393787)
		(end 369.463066 -288.121598)
		(width 0.0889)
		(layer "In2.Cu")
		(net "P5E_CPU0_PE3_TX_DN<14>")
	)
	(segment
		(start 379.201172 -407.924254)
		(end 378.874782 -408.250644)
		(width 0.13208)
		(layer "F.Cu")
		(net "P5E_CPU0_PE3_TX_DN<13>")
	)
	(segment
		(start 378.874782 -408.250644)
		(end 378.87021 -408.250644)
		(width 0.13208)
		(layer "F.Cu")
		(net "P5E_CPU0_PE3_TX_DN<13>")
	)
	(segment
		(start 379.201172 -407.310082)
		(end 379.201172 -407.924254)
		(width 0.13208)
		(layer "F.Cu")
		(net "P5E_CPU0_PE3_TX_DN<13>")
	)
	(segment
		(start 369.088162 -284.311598)
		(end 369.088416 -284.847538)
		(width 0.13208)
		(layer "F.Cu")
		(net "P5E_CPU0_PE3_TX_DN<13>")
	)
	(segment
		(start 378.89561 -407.00452)
		(end 379.201172 -407.310082)
		(width 0.13208)
		(layer "F.Cu")
		(net "P5E_CPU0_PE3_TX_DN<13>")
	)
	(segment
		(start 393.13485 -328.718926)
		(end 370.517674 -299.691806)
		(width 0.14732)
		(layer "In2.Cu")
		(net "P5E_CPU0_PE3_TX_DN<13>")
	)
	(segment
		(start 370.402866 -290.073842)
		(end 370.402866 -289.609022)
		(width 0.0889)
		(layer "In2.Cu")
		(net "P5E_CPU0_PE3_TX_DN<13>")
	)
	(segment
		(start 370.402866 -289.609022)
		(end 370.402612 -289.609784)
		(width 0.0889)
		(layer "In2.Cu")
		(net "P5E_CPU0_PE3_TX_DN<13>")
	)
	(segment
		(start 379.37567 -399.976086)
		(end 393.972034 -348.725236)
		(width 0.14732)
		(layer "In2.Cu")
		(net "P5E_CPU0_PE3_TX_DN<13>")
	)
	(segment
		(start 369.22075 -285.20771)
		(end 369.24488 -285.118556)
		(width 0.0889)
		(layer "In2.Cu")
		(net "P5E_CPU0_PE3_TX_DN<13>")
	)
	(segment
		(start 379.37567 -404.104856)
		(end 379.37567 -399.976086)
		(width 0.14732)
		(layer "In2.Cu")
		(net "P5E_CPU0_PE3_TX_DN<13>")
	)
	(segment
		(start 369.80368 -297.788076)
		(end 369.80368 -293.864792)
		(width 0.14732)
		(layer "In2.Cu")
		(net "P5E_CPU0_PE3_TX_DN<13>")
	)
	(segment
		(start 370.011706 -298.969684)
		(end 369.80368 -297.788076)
		(width 0.14732)
		(layer "In2.Cu")
		(net "P5E_CPU0_PE3_TX_DN<13>")
	)
	(segment
		(start 378.89561 -407.00452)
		(end 379.19025 -406.70988)
		(width 0.14732)
		(layer "In2.Cu")
		(net "P5E_CPU0_PE3_TX_DN<13>")
	)
	(segment
		(start 368.992912 -285.679896)
		(end 368.992912 -285.661354)
		(width 0.0889)
		(layer "In2.Cu")
		(net "P5E_CPU0_PE3_TX_DN<13>")
	)
	(segment
		(start 369.75415 -286.969962)
		(end 369.74526 -286.964882)
		(width 0.0889)
		(layer "In2.Cu")
		(net "P5E_CPU0_PE3_TX_DN<13>")
	)
	(segment
		(start 369.74526 -286.964882)
		(end 369.739164 -286.961326)
		(width 0.0889)
		(layer "In2.Cu")
		(net "P5E_CPU0_PE3_TX_DN<13>")
	)
	(segment
		(start 370.694204 -288.597848)
		(end 370.685314 -288.592768)
		(width 0.0889)
		(layer "In2.Cu")
		(net "P5E_CPU0_PE3_TX_DN<13>")
	)
	(segment
		(start 370.360956 -290.115752)
		(end 370.402866 -290.073842)
		(width 0.0889)
		(layer "In2.Cu")
		(net "P5E_CPU0_PE3_TX_DN<13>")
	)
	(segment
		(start 370.872766 -289.077908)
		(end 370.872766 -288.917126)
		(width 0.0889)
		(layer "In2.Cu")
		(net "P5E_CPU0_PE3_TX_DN<13>")
	)
	(segment
		(start 370.360956 -290.13785)
		(end 370.360956 -290.115752)
		(width 0.0889)
		(layer "In2.Cu")
		(net "P5E_CPU0_PE3_TX_DN<13>")
	)
	(segment
		(start 369.24488 -285.118556)
		(end 369.088416 -284.847538)
		(width 0.0889)
		(layer "In2.Cu")
		(net "P5E_CPU0_PE3_TX_DN<13>")
	)
	(segment
		(start 370.402866 -288.121598)
		(end 370.402866 -288.103056)
		(width 0.0889)
		(layer "In2.Cu")
		(net "P5E_CPU0_PE3_TX_DN<13>")
	)
	(segment
		(start 369.80368 -293.864792)
		(end 370.360956 -293.307516)
		(width 0.14732)
		(layer "In2.Cu")
		(net "P5E_CPU0_PE3_TX_DN<13>")
	)
	(segment
		(start 379.19025 -405.988266)
		(end 379.37567 -404.104856)
		(width 0.14732)
		(layer "In2.Cu")
		(net "P5E_CPU0_PE3_TX_DN<13>")
	)
	(segment
		(start 393.972034 -333.467456)
		(end 393.13485 -328.718926)
		(width 0.14732)
		(layer "In2.Cu")
		(net "P5E_CPU0_PE3_TX_DN<13>")
	)
	(segment
		(start 370.215414 -287.778698)
		(end 370.209318 -287.775142)
		(width 0.0889)
		(layer "In2.Cu")
		(net "P5E_CPU0_PE3_TX_DN<13>")
	)
	(segment
		(start 393.972034 -348.725236)
		(end 393.972034 -333.467456)
		(width 0.14732)
		(layer "In2.Cu")
		(net "P5E_CPU0_PE3_TX_DN<13>")
	)
	(segment
		(start 370.517674 -299.691806)
		(end 370.011706 -298.969684)
		(width 0.14732)
		(layer "In2.Cu")
		(net "P5E_CPU0_PE3_TX_DN<13>")
	)
	(segment
		(start 370.224304 -287.783778)
		(end 370.215414 -287.778698)
		(width 0.0889)
		(layer "In2.Cu")
		(net "P5E_CPU0_PE3_TX_DN<13>")
	)
	(segment
		(start 379.19025 -406.70988)
		(end 379.19025 -405.988266)
		(width 0.14732)
		(layer "In2.Cu")
		(net "P5E_CPU0_PE3_TX_DN<13>")
	)
	(segment
		(start 370.360956 -293.307516)
		(end 370.360956 -290.13785)
		(width 0.14732)
		(layer "In2.Cu")
		(net "P5E_CPU0_PE3_TX_DN<13>")
	)
	(segment
		(start 369.28425 -286.156146)
		(end 369.27536 -286.151066)
		(width 0.0889)
		(layer "In2.Cu")
		(net "P5E_CPU0_PE3_TX_DN<13>")
	)
	(arc
		(start 370.402612 -289.609784)
		(mid 370.409768 -289.590223)
		(end 370.417598 -289.570922)
		(width 0.0889)
		(layer "In2.Cu")
		(net "P5E_CPU0_PE3_TX_DN<13>")
	)
	(arc
		(start 369.932712 -287.28924)
		(mid 369.885033 -287.10634)
		(end 369.75415 -286.969962)
		(width 0.0889)
		(layer "In2.Cu")
		(net "P5E_CPU0_PE3_TX_DN<13>")
	)
	(arc
		(start 370.685314 -288.592768)
		(mid 370.483028 -288.393787)
		(end 370.402866 -288.121598)
		(width 0.0889)
		(layer "In2.Cu")
		(net "P5E_CPU0_PE3_TX_DN<13>")
	)
	(arc
		(start 369.462812 -286.475424)
		(mid 369.415133 -286.292524)
		(end 369.28425 -286.156146)
		(width 0.0889)
		(layer "In2.Cu")
		(net "P5E_CPU0_PE3_TX_DN<13>")
	)
	(arc
		(start 370.209318 -287.775142)
		(mid 370.006731 -287.568791)
		(end 369.932712 -287.28924)
		(width 0.0889)
		(layer "In2.Cu")
		(net "P5E_CPU0_PE3_TX_DN<13>")
	)
	(arc
		(start 369.203732 -285.220918)
		(mid 369.212178 -285.214233)
		(end 369.22075 -285.20771)
		(width 0.0889)
		(layer "In2.Cu")
		(net "P5E_CPU0_PE3_TX_DN<13>")
	)
	(arc
		(start 370.688362 -289.277806)
		(mid 370.797758 -289.193709)
		(end 370.872766 -289.077908)
		(width 0.0889)
		(layer "In2.Cu")
		(net "P5E_CPU0_PE3_TX_DN<13>")
	)
	(arc
		(start 370.417598 -289.570922)
		(mid 370.527855 -289.401162)
		(end 370.688362 -289.277806)
		(width 0.0889)
		(layer "In2.Cu")
		(net "P5E_CPU0_PE3_TX_DN<13>")
	)
	(arc
		(start 370.872766 -288.917126)
		(mid 370.825087 -288.734226)
		(end 370.694204 -288.597848)
		(width 0.0889)
		(layer "In2.Cu")
		(net "P5E_CPU0_PE3_TX_DN<13>")
	)
	(arc
		(start 370.402866 -288.103056)
		(mid 370.355187 -287.920156)
		(end 370.224304 -287.783778)
		(width 0.0889)
		(layer "In2.Cu")
		(net "P5E_CPU0_PE3_TX_DN<13>")
	)
	(arc
		(start 369.27536 -286.151066)
		(mid 369.073074 -285.952085)
		(end 368.992912 -285.679896)
		(width 0.0889)
		(layer "In2.Cu")
		(net "P5E_CPU0_PE3_TX_DN<13>")
	)
	(arc
		(start 368.992912 -285.661354)
		(mid 369.048267 -285.417167)
		(end 369.203732 -285.220918)
		(width 0.0889)
		(layer "In2.Cu")
		(net "P5E_CPU0_PE3_TX_DN<13>")
	)
	(arc
		(start 369.739164 -286.961326)
		(mid 369.536751 -286.754913)
		(end 369.462812 -286.475424)
		(width 0.0889)
		(layer "In2.Cu")
		(net "P5E_CPU0_PE3_TX_DN<13>")
	)
	(segment
		(start 382.264412 -407.924254)
		(end 381.938022 -408.250644)
		(width 0.13208)
		(layer "F.Cu")
		(net "P5E_CPU0_PE3_TX_DN<12>")
	)
	(segment
		(start 381.938022 -408.250644)
		(end 381.93345 -408.250644)
		(width 0.13208)
		(layer "F.Cu")
		(net "P5E_CPU0_PE3_TX_DN<12>")
	)
	(segment
		(start 370.027962 -285.939484)
		(end 370.027962 -286.47517)
		(width 0.13208)
		(layer "F.Cu")
		(net "P5E_CPU0_PE3_TX_DN<12>")
	)
	(segment
		(start 382.264412 -407.310082)
		(end 382.264412 -407.924254)
		(width 0.13208)
		(layer "F.Cu")
		(net "P5E_CPU0_PE3_TX_DN<12>")
	)
	(segment
		(start 381.95885 -407.00452)
		(end 382.264412 -407.310082)
		(width 0.13208)
		(layer "F.Cu")
		(net "P5E_CPU0_PE3_TX_DN<12>")
	)
	(segment
		(start 370.027962 -286.47517)
		(end 370.028216 -286.475424)
		(width 0.13208)
		(layer "F.Cu")
		(net "P5E_CPU0_PE3_TX_DN<12>")
	)
	(segment
		(start 382.25349 -406.70988)
		(end 382.25349 -405.988266)
		(width 0.14732)
		(layer "In2.Cu")
		(net "P5E_CPU0_PE3_TX_DN<12>")
	)
	(segment
		(start 371.155214 -287.778698)
		(end 371.149118 -287.775142)
		(width 0.0889)
		(layer "In2.Cu")
		(net "P5E_CPU0_PE3_TX_DN<12>")
	)
	(segment
		(start 383.280412 -396.42034)
		(end 383.280666 -396.418816)
		(width 0.14732)
		(layer "In2.Cu")
		(net "P5E_CPU0_PE3_TX_DN<12>")
	)
	(segment
		(start 370.262658 -286.183578)
		(end 370.18468 -286.204406)
		(width 0.0889)
		(layer "In2.Cu")
		(net "P5E_CPU0_PE3_TX_DN<12>")
	)
	(segment
		(start 383.013966 -397.511016)
		(end 383.117598 -397.086836)
		(width 0.14732)
		(layer "In2.Cu")
		(net "P5E_CPU0_PE3_TX_DN<12>")
	)
	(segment
		(start 382.86309 -397.602456)
		(end 383.013966 -397.511016)
		(width 0.14732)
		(layer "In2.Cu")
		(net "P5E_CPU0_PE3_TX_DN<12>")
	)
	(segment
		(start 382.850898 -398.177512)
		(end 382.759458 -398.027144)
		(width 0.14732)
		(layer "In2.Cu")
		(net "P5E_CPU0_PE3_TX_DN<12>")
	)
	(segment
		(start 383.280412 -396.418816)
		(end 394.941806 -348.68612)
		(width 0.14732)
		(layer "In2.Cu")
		(net "P5E_CPU0_PE3_TX_DN<12>")
	)
	(segment
		(start 371.300756 -297.51655)
		(end 371.300756 -290.13785)
		(width 0.14732)
		(layer "In2.Cu")
		(net "P5E_CPU0_PE3_TX_DN<12>")
	)
	(segment
		(start 370.69395 -286.969962)
		(end 370.68506 -286.964882)
		(width 0.0889)
		(layer "In2.Cu")
		(net "P5E_CPU0_PE3_TX_DN<12>")
	)
	(segment
		(start 373.159274 -301.451264)
		(end 371.639084 -299.440092)
		(width 0.14732)
		(layer "In2.Cu")
		(net "P5E_CPU0_PE3_TX_DN<12>")
	)
	(segment
		(start 371.634004 -288.597848)
		(end 371.625114 -288.592768)
		(width 0.0889)
		(layer "In2.Cu")
		(net "P5E_CPU0_PE3_TX_DN<12>")
	)
	(segment
		(start 371.342412 -290.074096)
		(end 371.342412 -289.609784)
		(width 0.0889)
		(layer "In2.Cu")
		(net "P5E_CPU0_PE3_TX_DN<12>")
	)
	(segment
		(start 383.12979 -396.511526)
		(end 383.280412 -396.42034)
		(width 0.14732)
		(layer "In2.Cu")
		(net "P5E_CPU0_PE3_TX_DN<12>")
	)
	(segment
		(start 383.026158 -396.936214)
		(end 383.12979 -396.511526)
		(width 0.14732)
		(layer "In2.Cu")
		(net "P5E_CPU0_PE3_TX_DN<12>")
	)
	(segment
		(start 371.300756 -290.13785)
		(end 371.300756 -290.115752)
		(width 0.0889)
		(layer "In2.Cu")
		(net "P5E_CPU0_PE3_TX_DN<12>")
	)
	(segment
		(start 371.342666 -288.121598)
		(end 371.342666 -288.103056)
		(width 0.0889)
		(layer "In2.Cu")
		(net "P5E_CPU0_PE3_TX_DN<12>")
	)
	(segment
		(start 382.759458 -398.027144)
		(end 382.86309 -397.602456)
		(width 0.14732)
		(layer "In2.Cu")
		(net "P5E_CPU0_PE3_TX_DN<12>")
	)
	(segment
		(start 394.941806 -333.570072)
		(end 393.931394 -327.840086)
		(width 0.14732)
		(layer "In2.Cu")
		(net "P5E_CPU0_PE3_TX_DN<12>")
	)
	(segment
		(start 394.941806 -348.68612)
		(end 394.941806 -333.570072)
		(width 0.14732)
		(layer "In2.Cu")
		(net "P5E_CPU0_PE3_TX_DN<12>")
	)
	(segment
		(start 382.43891 -399.864072)
		(end 382.850898 -398.177512)
		(width 0.14732)
		(layer "In2.Cu")
		(net "P5E_CPU0_PE3_TX_DN<12>")
	)
	(segment
		(start 373.917972 -302.210216)
		(end 373.159274 -301.451264)
		(width 0.14732)
		(layer "In2.Cu")
		(net "P5E_CPU0_PE3_TX_DN<12>")
	)
	(segment
		(start 370.402612 -286.48533)
		(end 370.402612 -286.466788)
		(width 0.0889)
		(layer "In2.Cu")
		(net "P5E_CPU0_PE3_TX_DN<12>")
	)
	(segment
		(start 371.812566 -289.077908)
		(end 371.812566 -288.917126)
		(width 0.0889)
		(layer "In2.Cu")
		(net "P5E_CPU0_PE3_TX_DN<12>")
	)
	(segment
		(start 371.164104 -287.783778)
		(end 371.155214 -287.778698)
		(width 0.0889)
		(layer "In2.Cu")
		(net "P5E_CPU0_PE3_TX_DN<12>")
	)
	(segment
		(start 393.931394 -327.840086)
		(end 373.917972 -302.210216)
		(width 0.14732)
		(layer "In2.Cu")
		(net "P5E_CPU0_PE3_TX_DN<12>")
	)
	(segment
		(start 370.18468 -286.204406)
		(end 370.028216 -286.475424)
		(width 0.0889)
		(layer "In2.Cu")
		(net "P5E_CPU0_PE3_TX_DN<12>")
	)
	(segment
		(start 382.25349 -405.988266)
		(end 382.43891 -404.104856)
		(width 0.14732)
		(layer "In2.Cu")
		(net "P5E_CPU0_PE3_TX_DN<12>")
	)
	(segment
		(start 383.117598 -397.086836)
		(end 383.026158 -396.936214)
		(width 0.14732)
		(layer "In2.Cu")
		(net "P5E_CPU0_PE3_TX_DN<12>")
	)
	(segment
		(start 382.43891 -404.104856)
		(end 382.43891 -399.864072)
		(width 0.14732)
		(layer "In2.Cu")
		(net "P5E_CPU0_PE3_TX_DN<12>")
	)
	(segment
		(start 383.280666 -396.418816)
		(end 383.280412 -396.418816)
		(width 0.14732)
		(layer "In2.Cu")
		(net "P5E_CPU0_PE3_TX_DN<12>")
	)
	(segment
		(start 371.300756 -290.115752)
		(end 371.342412 -290.074096)
		(width 0.0889)
		(layer "In2.Cu")
		(net "P5E_CPU0_PE3_TX_DN<12>")
	)
	(segment
		(start 381.95885 -407.00452)
		(end 382.25349 -406.70988)
		(width 0.14732)
		(layer "In2.Cu")
		(net "P5E_CPU0_PE3_TX_DN<12>")
	)
	(segment
		(start 371.639084 -299.440092)
		(end 371.300756 -297.51655)
		(width 0.14732)
		(layer "In2.Cu")
		(net "P5E_CPU0_PE3_TX_DN<12>")
	)
	(arc
		(start 371.357398 -289.570922)
		(mid 371.467655 -289.401162)
		(end 371.628162 -289.277806)
		(width 0.0889)
		(layer "In2.Cu")
		(net "P5E_CPU0_PE3_TX_DN<12>")
	)
	(arc
		(start 371.342666 -288.103056)
		(mid 371.294987 -287.920156)
		(end 371.164104 -287.783778)
		(width 0.0889)
		(layer "In2.Cu")
		(net "P5E_CPU0_PE3_TX_DN<12>")
	)
	(arc
		(start 370.402612 -286.466788)
		(mid 370.363938 -286.30972)
		(end 370.262658 -286.183578)
		(width 0.0889)
		(layer "In2.Cu")
		(net "P5E_CPU0_PE3_TX_DN<12>")
	)
	(arc
		(start 371.625114 -288.592768)
		(mid 371.422828 -288.393787)
		(end 371.342666 -288.121598)
		(width 0.0889)
		(layer "In2.Cu")
		(net "P5E_CPU0_PE3_TX_DN<12>")
	)
	(arc
		(start 371.628162 -289.277806)
		(mid 371.737558 -289.193709)
		(end 371.812566 -289.077908)
		(width 0.0889)
		(layer "In2.Cu")
		(net "P5E_CPU0_PE3_TX_DN<12>")
	)
	(arc
		(start 371.812566 -288.917126)
		(mid 371.764887 -288.734226)
		(end 371.634004 -288.597848)
		(width 0.0889)
		(layer "In2.Cu")
		(net "P5E_CPU0_PE3_TX_DN<12>")
	)
	(arc
		(start 371.149118 -287.775142)
		(mid 370.946531 -287.568791)
		(end 370.872512 -287.28924)
		(width 0.0889)
		(layer "In2.Cu")
		(net "P5E_CPU0_PE3_TX_DN<12>")
	)
	(arc
		(start 371.342412 -289.609784)
		(mid 371.349568 -289.590223)
		(end 371.357398 -289.570922)
		(width 0.0889)
		(layer "In2.Cu")
		(net "P5E_CPU0_PE3_TX_DN<12>")
	)
	(arc
		(start 370.872512 -287.28924)
		(mid 370.824833 -287.10634)
		(end 370.69395 -286.969962)
		(width 0.0889)
		(layer "In2.Cu")
		(net "P5E_CPU0_PE3_TX_DN<12>")
	)
	(arc
		(start 370.68506 -286.964882)
		(mid 370.480725 -286.762277)
		(end 370.402612 -286.48533)
		(width 0.0889)
		(layer "In2.Cu")
		(net "P5E_CPU0_PE3_TX_DN<12>")
	)
	(segment
		(start 385.327652 -407.924254)
		(end 385.001262 -408.250644)
		(width 0.13208)
		(layer "F.Cu")
		(net "P5E_CPU0_PE3_TX_DN<11>")
	)
	(segment
		(start 385.327652 -407.310082)
		(end 385.327652 -407.924254)
		(width 0.13208)
		(layer "F.Cu")
		(net "P5E_CPU0_PE3_TX_DN<11>")
	)
	(segment
		(start 385.02209 -407.00452)
		(end 385.327652 -407.310082)
		(width 0.13208)
		(layer "F.Cu")
		(net "P5E_CPU0_PE3_TX_DN<11>")
	)
	(segment
		(start 370.967762 -284.311598)
		(end 370.968016 -284.847538)
		(width 0.13208)
		(layer "F.Cu")
		(net "P5E_CPU0_PE3_TX_DN<11>")
	)
	(segment
		(start 385.001262 -408.250644)
		(end 384.99669 -408.250644)
		(width 0.13208)
		(layer "F.Cu")
		(net "P5E_CPU0_PE3_TX_DN<11>")
	)
	(segment
		(start 385.50215 -399.874994)
		(end 395.881606 -348.868492)
		(width 0.14732)
		(layer "In2.Cu")
		(net "P5E_CPU0_PE3_TX_DN<11>")
	)
	(segment
		(start 372.240556 -290.13785)
		(end 372.240556 -290.115752)
		(width 0.0889)
		(layer "In2.Cu")
		(net "P5E_CPU0_PE3_TX_DN<11>")
	)
	(segment
		(start 371.63375 -286.969962)
		(end 371.62486 -286.964882)
		(width 0.0889)
		(layer "In2.Cu")
		(net "P5E_CPU0_PE3_TX_DN<11>")
	)
	(segment
		(start 395.881606 -348.868492)
		(end 395.881606 -333.487268)
		(width 0.14732)
		(layer "In2.Cu")
		(net "P5E_CPU0_PE3_TX_DN<11>")
	)
	(segment
		(start 372.094252 -287.77819)
		(end 372.088918 -287.775142)
		(width 0.0889)
		(layer "In2.Cu")
		(net "P5E_CPU0_PE3_TX_DN<11>")
	)
	(segment
		(start 372.103904 -287.783778)
		(end 372.096792 -287.779714)
		(width 0.0889)
		(layer "In2.Cu")
		(net "P5E_CPU0_PE3_TX_DN<11>")
	)
	(segment
		(start 372.282466 -289.611308)
		(end 372.282212 -289.611054)
		(width 0.0889)
		(layer "In2.Cu")
		(net "P5E_CPU0_PE3_TX_DN<11>")
	)
	(segment
		(start 385.02209 -407.00452)
		(end 385.31673 -406.70988)
		(width 0.14732)
		(layer "In2.Cu")
		(net "P5E_CPU0_PE3_TX_DN<11>")
	)
	(segment
		(start 385.31673 -406.70988)
		(end 385.31673 -405.988266)
		(width 0.14732)
		(layer "In2.Cu")
		(net "P5E_CPU0_PE3_TX_DN<11>")
	)
	(segment
		(start 394.818362 -327.458832)
		(end 374.588024 -301.550578)
		(width 0.14732)
		(layer "In2.Cu")
		(net "P5E_CPU0_PE3_TX_DN<11>")
	)
	(segment
		(start 395.881606 -333.487268)
		(end 394.818362 -327.458832)
		(width 0.14732)
		(layer "In2.Cu")
		(net "P5E_CPU0_PE3_TX_DN<11>")
	)
	(segment
		(start 371.10035 -285.20771)
		(end 371.12448 -285.118556)
		(width 0.0889)
		(layer "In2.Cu")
		(net "P5E_CPU0_PE3_TX_DN<11>")
	)
	(segment
		(start 372.282466 -288.121598)
		(end 372.282466 -288.103056)
		(width 0.0889)
		(layer "In2.Cu")
		(net "P5E_CPU0_PE3_TX_DN<11>")
	)
	(segment
		(start 373.87022 -300.83252)
		(end 372.558564 -299.097192)
		(width 0.14732)
		(layer "In2.Cu")
		(net "P5E_CPU0_PE3_TX_DN<11>")
	)
	(segment
		(start 372.240556 -297.290744)
		(end 372.240556 -290.13785)
		(width 0.14732)
		(layer "In2.Cu")
		(net "P5E_CPU0_PE3_TX_DN<11>")
	)
	(segment
		(start 372.558564 -299.097192)
		(end 372.240556 -297.290744)
		(width 0.14732)
		(layer "In2.Cu")
		(net "P5E_CPU0_PE3_TX_DN<11>")
	)
	(segment
		(start 385.31673 -405.988266)
		(end 385.50215 -404.104856)
		(width 0.14732)
		(layer "In2.Cu")
		(net "P5E_CPU0_PE3_TX_DN<11>")
	)
	(segment
		(start 372.752366 -289.077908)
		(end 372.752366 -288.917126)
		(width 0.0889)
		(layer "In2.Cu")
		(net "P5E_CPU0_PE3_TX_DN<11>")
	)
	(segment
		(start 372.573804 -288.597848)
		(end 372.564914 -288.592768)
		(width 0.0889)
		(layer "In2.Cu")
		(net "P5E_CPU0_PE3_TX_DN<11>")
	)
	(segment
		(start 371.12448 -285.118556)
		(end 370.968016 -284.847538)
		(width 0.0889)
		(layer "In2.Cu")
		(net "P5E_CPU0_PE3_TX_DN<11>")
	)
	(segment
		(start 385.50215 -404.104856)
		(end 385.50215 -399.874994)
		(width 0.14732)
		(layer "In2.Cu")
		(net "P5E_CPU0_PE3_TX_DN<11>")
	)
	(segment
		(start 372.282466 -290.073842)
		(end 372.282466 -289.611308)
		(width 0.0889)
		(layer "In2.Cu")
		(net "P5E_CPU0_PE3_TX_DN<11>")
	)
	(segment
		(start 372.567962 -289.27806)
		(end 372.567962 -289.277806)
		(width 0.0889)
		(layer "In2.Cu")
		(net "P5E_CPU0_PE3_TX_DN<11>")
	)
	(segment
		(start 371.16385 -286.156146)
		(end 371.15496 -286.151066)
		(width 0.0889)
		(layer "In2.Cu")
		(net "P5E_CPU0_PE3_TX_DN<11>")
	)
	(segment
		(start 371.62486 -286.964882)
		(end 371.618764 -286.961326)
		(width 0.0889)
		(layer "In2.Cu")
		(net "P5E_CPU0_PE3_TX_DN<11>")
	)
	(segment
		(start 372.240556 -290.115752)
		(end 372.282466 -290.073842)
		(width 0.0889)
		(layer "In2.Cu")
		(net "P5E_CPU0_PE3_TX_DN<11>")
	)
	(segment
		(start 374.588024 -301.550578)
		(end 373.87022 -300.83252)
		(width 0.14732)
		(layer "In2.Cu")
		(net "P5E_CPU0_PE3_TX_DN<11>")
	)
	(segment
		(start 372.095776 -287.779206)
		(end 372.094252 -287.77819)
		(width 0.0889)
		(layer "In2.Cu")
		(net "P5E_CPU0_PE3_TX_DN<11>")
	)
	(segment
		(start 372.096792 -287.779714)
		(end 372.095776 -287.779206)
		(width 0.0889)
		(layer "In2.Cu")
		(net "P5E_CPU0_PE3_TX_DN<11>")
	)
	(arc
		(start 372.088918 -287.775142)
		(mid 371.886331 -287.568791)
		(end 371.812312 -287.28924)
		(width 0.0889)
		(layer "In2.Cu")
		(net "P5E_CPU0_PE3_TX_DN<11>")
	)
	(arc
		(start 372.752366 -288.917126)
		(mid 372.704687 -288.734226)
		(end 372.573804 -288.597848)
		(width 0.0889)
		(layer "In2.Cu")
		(net "P5E_CPU0_PE3_TX_DN<11>")
	)
	(arc
		(start 371.342412 -286.475424)
		(mid 371.294733 -286.292524)
		(end 371.16385 -286.156146)
		(width 0.0889)
		(layer "In2.Cu")
		(net "P5E_CPU0_PE3_TX_DN<11>")
	)
	(arc
		(start 371.618764 -286.961326)
		(mid 371.416351 -286.754913)
		(end 371.342412 -286.475424)
		(width 0.0889)
		(layer "In2.Cu")
		(net "P5E_CPU0_PE3_TX_DN<11>")
	)
	(arc
		(start 372.282212 -289.611054)
		(mid 372.289601 -289.590976)
		(end 372.297706 -289.571176)
		(width 0.0889)
		(layer "In2.Cu")
		(net "P5E_CPU0_PE3_TX_DN<11>")
	)
	(arc
		(start 371.083332 -285.220918)
		(mid 371.091778 -285.214233)
		(end 371.10035 -285.20771)
		(width 0.0889)
		(layer "In2.Cu")
		(net "P5E_CPU0_PE3_TX_DN<11>")
	)
	(arc
		(start 372.282466 -288.103056)
		(mid 372.234787 -287.920156)
		(end 372.103904 -287.783778)
		(width 0.0889)
		(layer "In2.Cu")
		(net "P5E_CPU0_PE3_TX_DN<11>")
	)
	(arc
		(start 371.812312 -287.28924)
		(mid 371.764633 -287.10634)
		(end 371.63375 -286.969962)
		(width 0.0889)
		(layer "In2.Cu")
		(net "P5E_CPU0_PE3_TX_DN<11>")
	)
	(arc
		(start 372.564914 -288.592768)
		(mid 372.362628 -288.393787)
		(end 372.282466 -288.121598)
		(width 0.0889)
		(layer "In2.Cu")
		(net "P5E_CPU0_PE3_TX_DN<11>")
	)
	(arc
		(start 372.297706 -289.571176)
		(mid 372.407674 -289.401411)
		(end 372.567962 -289.27806)
		(width 0.0889)
		(layer "In2.Cu")
		(net "P5E_CPU0_PE3_TX_DN<11>")
	)
	(arc
		(start 372.567962 -289.277806)
		(mid 372.677358 -289.193709)
		(end 372.752366 -289.077908)
		(width 0.0889)
		(layer "In2.Cu")
		(net "P5E_CPU0_PE3_TX_DN<11>")
	)
	(arc
		(start 371.15496 -286.151066)
		(mid 370.873882 -285.704831)
		(end 371.083332 -285.220918)
		(width 0.0889)
		(layer "In2.Cu")
		(net "P5E_CPU0_PE3_TX_DN<11>")
	)
	(segment
		(start 388.08533 -407.00452)
		(end 388.390892 -407.310082)
		(width 0.13208)
		(layer "F.Cu")
		(net "P5E_CPU0_PE3_TX_DN<10>")
	)
	(segment
		(start 388.390892 -407.310082)
		(end 388.390892 -407.924254)
		(width 0.13208)
		(layer "F.Cu")
		(net "P5E_CPU0_PE3_TX_DN<10>")
	)
	(segment
		(start 388.064502 -408.250644)
		(end 388.05993 -408.250644)
		(width 0.13208)
		(layer "F.Cu")
		(net "P5E_CPU0_PE3_TX_DN<10>")
	)
	(segment
		(start 388.390892 -407.924254)
		(end 388.064502 -408.250644)
		(width 0.13208)
		(layer "F.Cu")
		(net "P5E_CPU0_PE3_TX_DN<10>")
	)
	(segment
		(start 371.907562 -286.47517)
		(end 371.907816 -286.475424)
		(width 0.13208)
		(layer "F.Cu")
		(net "P5E_CPU0_PE3_TX_DN<10>")
	)
	(segment
		(start 371.907562 -285.939484)
		(end 371.907562 -286.47517)
		(width 0.13208)
		(layer "F.Cu")
		(net "P5E_CPU0_PE3_TX_DN<10>")
	)
	(segment
		(start 388.37997 -406.70988)
		(end 388.37997 -405.988266)
		(width 0.14732)
		(layer "In2.Cu")
		(net "P5E_CPU0_PE3_TX_DN<10>")
	)
	(segment
		(start 389.109712 -396.286228)
		(end 389.109204 -396.286228)
		(width 0.14732)
		(layer "In2.Cu")
		(net "P5E_CPU0_PE3_TX_DN<10>")
	)
	(segment
		(start 388.08533 -407.00452)
		(end 388.37997 -406.70988)
		(width 0.14732)
		(layer "In2.Cu")
		(net "P5E_CPU0_PE3_TX_DN<10>")
	)
	(segment
		(start 389.109204 -396.286228)
		(end 396.821406 -348.887034)
		(width 0.14732)
		(layer "In2.Cu")
		(net "P5E_CPU0_PE3_TX_DN<10>")
	)
	(segment
		(start 388.96671 -396.389098)
		(end 389.109712 -396.286228)
		(width 0.14732)
		(layer "In2.Cu")
		(net "P5E_CPU0_PE3_TX_DN<10>")
	)
	(segment
		(start 388.56539 -399.630392)
		(end 388.817612 -398.07896)
		(width 0.14732)
		(layer "In2.Cu")
		(net "P5E_CPU0_PE3_TX_DN<10>")
	)
	(segment
		(start 373.043704 -287.783778)
		(end 373.034814 -287.778698)
		(width 0.0889)
		(layer "In2.Cu")
		(net "P5E_CPU0_PE3_TX_DN<10>")
	)
	(segment
		(start 374.580912 -300.213776)
		(end 373.444516 -298.71035)
		(width 0.14732)
		(layer "In2.Cu")
		(net "P5E_CPU0_PE3_TX_DN<10>")
	)
	(segment
		(start 388.7851 -397.504666)
		(end 388.928102 -397.401796)
		(width 0.14732)
		(layer "In2.Cu")
		(net "P5E_CPU0_PE3_TX_DN<10>")
	)
	(segment
		(start 373.034814 -287.778698)
		(end 373.028718 -287.775142)
		(width 0.0889)
		(layer "In2.Cu")
		(net "P5E_CPU0_PE3_TX_DN<10>")
	)
	(segment
		(start 388.999222 -396.963392)
		(end 388.896352 -396.820644)
		(width 0.14732)
		(layer "In2.Cu")
		(net "P5E_CPU0_PE3_TX_DN<10>")
	)
	(segment
		(start 373.692166 -289.077908)
		(end 373.692166 -288.917126)
		(width 0.0889)
		(layer "In2.Cu")
		(net "P5E_CPU0_PE3_TX_DN<10>")
	)
	(segment
		(start 372.57355 -286.969962)
		(end 372.56466 -286.964882)
		(width 0.0889)
		(layer "In2.Cu")
		(net "P5E_CPU0_PE3_TX_DN<10>")
	)
	(segment
		(start 372.142258 -286.183578)
		(end 372.06428 -286.204406)
		(width 0.0889)
		(layer "In2.Cu")
		(net "P5E_CPU0_PE3_TX_DN<10>")
	)
	(segment
		(start 388.928102 -397.401796)
		(end 388.999222 -396.963392)
		(width 0.14732)
		(layer "In2.Cu")
		(net "P5E_CPU0_PE3_TX_DN<10>")
	)
	(segment
		(start 396.821406 -348.887034)
		(end 396.821406 -333.404718)
		(width 0.14732)
		(layer "In2.Cu")
		(net "P5E_CPU0_PE3_TX_DN<10>")
	)
	(segment
		(start 373.513604 -288.597848)
		(end 373.504714 -288.592768)
		(width 0.0889)
		(layer "In2.Cu")
		(net "P5E_CPU0_PE3_TX_DN<10>")
	)
	(segment
		(start 373.444516 -298.71035)
		(end 373.180102 -297.208702)
		(width 0.14732)
		(layer "In2.Cu")
		(net "P5E_CPU0_PE3_TX_DN<10>")
	)
	(segment
		(start 372.06428 -286.204406)
		(end 371.907816 -286.475424)
		(width 0.0889)
		(layer "In2.Cu")
		(net "P5E_CPU0_PE3_TX_DN<10>")
	)
	(segment
		(start 388.817612 -398.07896)
		(end 388.714742 -397.935958)
		(width 0.14732)
		(layer "In2.Cu")
		(net "P5E_CPU0_PE3_TX_DN<10>")
	)
	(segment
		(start 373.222266 -288.121598)
		(end 373.222266 -288.103056)
		(width 0.0889)
		(layer "In2.Cu")
		(net "P5E_CPU0_PE3_TX_DN<10>")
	)
	(segment
		(start 388.896352 -396.820644)
		(end 388.96671 -396.389098)
		(width 0.14732)
		(layer "In2.Cu")
		(net "P5E_CPU0_PE3_TX_DN<10>")
	)
	(segment
		(start 388.37997 -405.988266)
		(end 388.56539 -404.104856)
		(width 0.14732)
		(layer "In2.Cu")
		(net "P5E_CPU0_PE3_TX_DN<10>")
	)
	(segment
		(start 388.56539 -404.104856)
		(end 388.56539 -399.630392)
		(width 0.14732)
		(layer "In2.Cu")
		(net "P5E_CPU0_PE3_TX_DN<10>")
	)
	(segment
		(start 375.329196 -300.961806)
		(end 374.580912 -300.213776)
		(width 0.14732)
		(layer "In2.Cu")
		(net "P5E_CPU0_PE3_TX_DN<10>")
	)
	(segment
		(start 373.180102 -297.208702)
		(end 373.180102 -290.13785)
		(width 0.14732)
		(layer "In2.Cu")
		(net "P5E_CPU0_PE3_TX_DN<10>")
	)
	(segment
		(start 388.714742 -397.935958)
		(end 388.7851 -397.504666)
		(width 0.14732)
		(layer "In2.Cu")
		(net "P5E_CPU0_PE3_TX_DN<10>")
	)
	(segment
		(start 372.282212 -286.48533)
		(end 372.282212 -286.466788)
		(width 0.0889)
		(layer "In2.Cu")
		(net "P5E_CPU0_PE3_TX_DN<10>")
	)
	(segment
		(start 396.821406 -333.404718)
		(end 395.701266 -327.052178)
		(width 0.14732)
		(layer "In2.Cu")
		(net "P5E_CPU0_PE3_TX_DN<10>")
	)
	(segment
		(start 373.180102 -290.13785)
		(end 373.180102 -290.115752)
		(width 0.0889)
		(layer "In2.Cu")
		(net "P5E_CPU0_PE3_TX_DN<10>")
	)
	(segment
		(start 373.222012 -290.073842)
		(end 373.222012 -289.609784)
		(width 0.0889)
		(layer "In2.Cu")
		(net "P5E_CPU0_PE3_TX_DN<10>")
	)
	(segment
		(start 395.701266 -327.052178)
		(end 375.329196 -300.961806)
		(width 0.14732)
		(layer "In2.Cu")
		(net "P5E_CPU0_PE3_TX_DN<10>")
	)
	(segment
		(start 373.180102 -290.115752)
		(end 373.222012 -290.073842)
		(width 0.0889)
		(layer "In2.Cu")
		(net "P5E_CPU0_PE3_TX_DN<10>")
	)
	(arc
		(start 372.282212 -286.466788)
		(mid 372.243538 -286.30972)
		(end 372.142258 -286.183578)
		(width 0.0889)
		(layer "In2.Cu")
		(net "P5E_CPU0_PE3_TX_DN<10>")
	)
	(arc
		(start 373.507762 -289.277806)
		(mid 373.617158 -289.193709)
		(end 373.692166 -289.077908)
		(width 0.0889)
		(layer "In2.Cu")
		(net "P5E_CPU0_PE3_TX_DN<10>")
	)
	(arc
		(start 373.692166 -288.917126)
		(mid 373.644487 -288.734226)
		(end 373.513604 -288.597848)
		(width 0.0889)
		(layer "In2.Cu")
		(net "P5E_CPU0_PE3_TX_DN<10>")
	)
	(arc
		(start 373.222266 -288.103056)
		(mid 373.174587 -287.920156)
		(end 373.043704 -287.783778)
		(width 0.0889)
		(layer "In2.Cu")
		(net "P5E_CPU0_PE3_TX_DN<10>")
	)
	(arc
		(start 372.752112 -287.28924)
		(mid 372.704433 -287.10634)
		(end 372.57355 -286.969962)
		(width 0.0889)
		(layer "In2.Cu")
		(net "P5E_CPU0_PE3_TX_DN<10>")
	)
	(arc
		(start 373.028718 -287.775142)
		(mid 372.826131 -287.568791)
		(end 372.752112 -287.28924)
		(width 0.0889)
		(layer "In2.Cu")
		(net "P5E_CPU0_PE3_TX_DN<10>")
	)
	(arc
		(start 373.222012 -289.609784)
		(mid 373.229168 -289.590223)
		(end 373.236998 -289.570922)
		(width 0.0889)
		(layer "In2.Cu")
		(net "P5E_CPU0_PE3_TX_DN<10>")
	)
	(arc
		(start 373.236998 -289.570922)
		(mid 373.347255 -289.401162)
		(end 373.507762 -289.277806)
		(width 0.0889)
		(layer "In2.Cu")
		(net "P5E_CPU0_PE3_TX_DN<10>")
	)
	(arc
		(start 373.504714 -288.592768)
		(mid 373.302428 -288.393787)
		(end 373.222266 -288.121598)
		(width 0.0889)
		(layer "In2.Cu")
		(net "P5E_CPU0_PE3_TX_DN<10>")
	)
	(arc
		(start 372.56466 -286.964882)
		(mid 372.360325 -286.762277)
		(end 372.282212 -286.48533)
		(width 0.0889)
		(layer "In2.Cu")
		(net "P5E_CPU0_PE3_TX_DN<10>")
	)
	(segment
		(start 419.282372 -407.926286)
		(end 419.60673 -408.250644)
		(width 0.13208)
		(layer "F.Cu")
		(net "P5E_CPU0_PE3_TX_DN<0>")
	)
	(segment
		(start 381.775716 -285.6611)
		(end 381.775462 -285.661354)
		(width 0.13208)
		(layer "F.Cu")
		(net "P5E_CPU0_PE3_TX_DN<0>")
	)
	(segment
		(start 381.775716 -285.125414)
		(end 381.775716 -285.6611)
		(width 0.13208)
		(layer "F.Cu")
		(net "P5E_CPU0_PE3_TX_DN<0>")
	)
	(segment
		(start 419.58133 -407.00452)
		(end 419.282372 -407.303478)
		(width 0.13208)
		(layer "F.Cu")
		(net "P5E_CPU0_PE3_TX_DN<0>")
	)
	(segment
		(start 419.282372 -407.303478)
		(end 419.282372 -407.926286)
		(width 0.13208)
		(layer "F.Cu")
		(net "P5E_CPU0_PE3_TX_DN<0>")
	)
	(segment
		(start 384.264154 -289.930332)
		(end 384.20421 -289.930332)
		(width 0.0889)
		(layer "In2.Cu")
		(net "P5E_CPU0_PE3_TX_DN<0>")
	)
	(segment
		(start 382.340612 -287.28924)
		(end 382.340612 -287.273746)
		(width 0.0889)
		(layer "In2.Cu")
		(net "P5E_CPU0_PE3_TX_DN<0>")
	)
	(segment
		(start 384.279648 -289.945826)
		(end 384.264154 -289.930332)
		(width 0.0889)
		(layer "In2.Cu")
		(net "P5E_CPU0_PE3_TX_DN<0>")
	)
	(segment
		(start 389.982964 -302.018192)
		(end 389.623554 -299.979588)
		(width 0.14732)
		(layer "In2.Cu")
		(net "P5E_CPU0_PE3_TX_DN<0>")
	)
	(segment
		(start 387.56336 -292.646608)
		(end 385.84251 -290.925758)
		(width 0.14732)
		(layer "In2.Cu")
		(net "P5E_CPU0_PE3_TX_DN<0>")
	)
	(segment
		(start 381.643128 -286.021526)
		(end 381.618998 -285.932372)
		(width 0.0889)
		(layer "In2.Cu")
		(net "P5E_CPU0_PE3_TX_DN<0>")
	)
	(segment
		(start 389.623808 -299.979588)
		(end 388.899146 -295.871646)
		(width 0.14732)
		(layer "In2.Cu")
		(net "P5E_CPU0_PE3_TX_DN<0>")
	)
	(segment
		(start 382.528064 -287.613598)
		(end 382.519174 -287.608518)
		(width 0.0889)
		(layer "In2.Cu")
		(net "P5E_CPU0_PE3_TX_DN<0>")
	)
	(segment
		(start 407.114502 -369.527582)
		(end 406.870916 -367.835688)
		(width 0.14732)
		(layer "In2.Cu")
		(net "P5E_CPU0_PE3_TX_DN<0>")
	)
	(segment
		(start 407.265124 -334.785208)
		(end 406.74036 -332.581758)
		(width 0.14732)
		(layer "In2.Cu")
		(net "P5E_CPU0_PE3_TX_DN<0>")
	)
	(segment
		(start 382.058418 -286.799782)
		(end 382.049528 -286.794702)
		(width 0.0889)
		(layer "In2.Cu")
		(net "P5E_CPU0_PE3_TX_DN<0>")
	)
	(segment
		(start 382.99771 -288.427668)
		(end 382.99771 -288.426906)
		(width 0.0889)
		(layer "In2.Cu")
		(net "P5E_CPU0_PE3_TX_DN<0>")
	)
	(segment
		(start 389.623554 -299.979588)
		(end 389.623808 -299.979588)
		(width 0.14732)
		(layer "In2.Cu")
		(net "P5E_CPU0_PE3_TX_DN<0>")
	)
	(segment
		(start 405.038814 -322.932806)
		(end 390.342628 -304.05705)
		(width 0.14732)
		(layer "In2.Cu")
		(net "P5E_CPU0_PE3_TX_DN<0>")
	)
	(segment
		(start 406.74036 -332.581758)
		(end 405.038814 -322.932806)
		(width 0.14732)
		(layer "In2.Cu")
		(net "P5E_CPU0_PE3_TX_DN<0>")
	)
	(segment
		(start 384.847338 -290.513516)
		(end 384.279648 -289.945826)
		(width 0.14732)
		(layer "In2.Cu")
		(net "P5E_CPU0_PE3_TX_DN<0>")
	)
	(segment
		(start 383.489454 -289.25393)
		(end 383.443226 -289.227514)
		(width 0.0889)
		(layer "In2.Cu")
		(net "P5E_CPU0_PE3_TX_DN<0>")
	)
	(segment
		(start 384.20421 -289.930332)
		(end 383.659126 -289.385248)
		(width 0.0889)
		(layer "In2.Cu")
		(net "P5E_CPU0_PE3_TX_DN<0>")
	)
	(segment
		(start 382.53416 -287.617154)
		(end 382.528064 -287.613598)
		(width 0.0889)
		(layer "In2.Cu")
		(net "P5E_CPU0_PE3_TX_DN<0>")
	)
	(segment
		(start 381.870966 -286.475424)
		(end 381.870966 -286.4612)
		(width 0.0889)
		(layer "In2.Cu")
		(net "P5E_CPU0_PE3_TX_DN<0>")
	)
	(segment
		(start 419.47211 -404.118572)
		(end 419.47211 -400.468084)
		(width 0.14732)
		(layer "In2.Cu")
		(net "P5E_CPU0_PE3_TX_DN<0>")
	)
	(segment
		(start 383.659126 -289.385248)
		(end 383.489454 -289.25393)
		(width 0.0889)
		(layer "In2.Cu")
		(net "P5E_CPU0_PE3_TX_DN<0>")
	)
	(segment
		(start 381.618998 -285.932372)
		(end 381.775462 -285.661354)
		(width 0.0889)
		(layer "In2.Cu")
		(net "P5E_CPU0_PE3_TX_DN<0>")
	)
	(segment
		(start 419.58133 -407.00452)
		(end 419.28669 -406.70988)
		(width 0.14732)
		(layer "In2.Cu")
		(net "P5E_CPU0_PE3_TX_DN<0>")
	)
	(segment
		(start 406.870916 -367.835688)
		(end 407.265124 -334.785208)
		(width 0.14732)
		(layer "In2.Cu")
		(net "P5E_CPU0_PE3_TX_DN<0>")
	)
	(segment
		(start 419.28669 -406.70988)
		(end 419.28669 -406.001982)
		(width 0.14732)
		(layer "In2.Cu")
		(net "P5E_CPU0_PE3_TX_DN<0>")
	)
	(segment
		(start 419.28669 -406.001982)
		(end 419.47211 -404.118572)
		(width 0.14732)
		(layer "In2.Cu")
		(net "P5E_CPU0_PE3_TX_DN<0>")
	)
	(segment
		(start 390.342628 -304.05705)
		(end 389.982964 -302.018192)
		(width 0.14732)
		(layer "In2.Cu")
		(net "P5E_CPU0_PE3_TX_DN<0>")
	)
	(segment
		(start 383.281174 -288.955226)
		(end 383.280158 -288.90468)
		(width 0.0889)
		(layer "In2.Cu")
		(net "P5E_CPU0_PE3_TX_DN<0>")
	)
	(segment
		(start 419.47211 -400.468084)
		(end 407.114502 -369.527582)
		(width 0.14732)
		(layer "In2.Cu")
		(net "P5E_CPU0_PE3_TX_DN<0>")
	)
	(segment
		(start 388.899146 -295.871646)
		(end 387.56336 -292.646608)
		(width 0.14732)
		(layer "In2.Cu")
		(net "P5E_CPU0_PE3_TX_DN<0>")
	)
	(segment
		(start 385.84251 -290.925758)
		(end 384.847338 -290.513516)
		(width 0.14732)
		(layer "In2.Cu")
		(net "P5E_CPU0_PE3_TX_DN<0>")
	)
	(segment
		(start 382.99771 -288.426906)
		(end 382.989328 -288.422334)
		(width 0.0889)
		(layer "In2.Cu")
		(net "P5E_CPU0_PE3_TX_DN<0>")
	)
	(arc
		(start 382.049528 -286.794702)
		(mid 381.918614 -286.658342)
		(end 381.870966 -286.475424)
		(width 0.0889)
		(layer "In2.Cu")
		(net "P5E_CPU0_PE3_TX_DN<0>")
	)
	(arc
		(start 382.810766 -288.103056)
		(mid 382.736775 -287.82349)
		(end 382.53416 -287.617154)
		(width 0.0889)
		(layer "In2.Cu")
		(net "P5E_CPU0_PE3_TX_DN<0>")
	)
	(arc
		(start 381.870966 -286.4612)
		(mid 381.812621 -286.224695)
		(end 381.660146 -286.034734)
		(width 0.0889)
		(layer "In2.Cu")
		(net "P5E_CPU0_PE3_TX_DN<0>")
	)
	(arc
		(start 383.280158 -288.90468)
		(mid 383.201493 -288.62913)
		(end 382.99771 -288.427668)
		(width 0.0889)
		(layer "In2.Cu")
		(net "P5E_CPU0_PE3_TX_DN<0>")
	)
	(arc
		(start 381.660146 -286.034734)
		(mid 381.6517 -286.028049)
		(end 381.643128 -286.021526)
		(width 0.0889)
		(layer "In2.Cu")
		(net "P5E_CPU0_PE3_TX_DN<0>")
	)
	(arc
		(start 382.989328 -288.422334)
		(mid 382.858414 -288.285974)
		(end 382.810766 -288.103056)
		(width 0.0889)
		(layer "In2.Cu")
		(net "P5E_CPU0_PE3_TX_DN<0>")
	)
	(arc
		(start 383.443226 -289.227514)
		(mid 383.326712 -289.112482)
		(end 383.281174 -288.955226)
		(width 0.0889)
		(layer "In2.Cu")
		(net "P5E_CPU0_PE3_TX_DN<0>")
	)
	(arc
		(start 382.519174 -287.608518)
		(mid 382.38826 -287.472158)
		(end 382.340612 -287.28924)
		(width 0.0889)
		(layer "In2.Cu")
		(net "P5E_CPU0_PE3_TX_DN<0>")
	)
	(arc
		(start 382.340612 -287.273746)
		(mid 382.261242 -287.000012)
		(end 382.058418 -286.799782)
		(width 0.0889)
		(layer "In2.Cu")
		(net "P5E_CPU0_PE3_TX_DN<0>")
	)
	(segment
		(start 391.710672 -409.110942)
		(end 392.03757 -408.784044)
		(width 0.13208)
		(layer "F.Cu")
		(net "P5E_CPU0_PE3_TX_C_DP<9>")
	)
	(segment
		(start 392.01217 -410.030168)
		(end 391.710672 -409.72867)
		(width 0.13208)
		(layer "F.Cu")
		(net "P5E_CPU0_PE3_TX_C_DP<9>")
	)
	(segment
		(start 391.710672 -409.72867)
		(end 391.710672 -409.110942)
		(width 0.13208)
		(layer "F.Cu")
		(net "P5E_CPU0_PE3_TX_C_DP<9>")
	)
	(segment
		(start 392.025378 -413.81045)
		(end 391.897108 -413.969962)
		(width 0.14732)
		(layer "In6.Cu")
		(net "P5E_CPU0_PE3_TX_C_DP<9>")
	)
	(segment
		(start 391.93724 -414.335976)
		(end 392.097006 -414.463992)
		(width 0.14732)
		(layer "In6.Cu")
		(net "P5E_CPU0_PE3_TX_C_DP<9>")
	)
	(segment
		(start 392.097006 -414.463992)
		(end 392.137392 -414.830514)
		(width 0.14732)
		(layer "In6.Cu")
		(net "P5E_CPU0_PE3_TX_C_DP<9>")
	)
	(segment
		(start 392.009122 -414.990026)
		(end 392.05662 -415.424112)
		(width 0.14732)
		(layer "In6.Cu")
		(net "P5E_CPU0_PE3_TX_C_DP<9>")
	)
	(segment
		(start 391.71753 -410.324808)
		(end 391.71753 -412.336488)
		(width 0.14732)
		(layer "In6.Cu")
		(net "P5E_CPU0_PE3_TX_C_DP<9>")
	)
	(segment
		(start 392.05662 -415.424112)
		(end 392.194288 -415.534348)
		(width 0.14732)
		(layer "In6.Cu")
		(net "P5E_CPU0_PE3_TX_C_DP<9>")
	)
	(segment
		(start 392.254232 -417.222178)
		(end 393.066778 -424.630088)
		(width 0.14732)
		(layer "In6.Cu")
		(net "P5E_CPU0_PE3_TX_C_DP<9>")
	)
	(segment
		(start 392.364468 -417.085018)
		(end 392.254232 -417.222178)
		(width 0.14732)
		(layer "In6.Cu")
		(net "P5E_CPU0_PE3_TX_C_DP<9>")
	)
	(segment
		(start 392.241786 -415.968942)
		(end 392.131804 -416.106102)
		(width 0.14732)
		(layer "In6.Cu")
		(net "P5E_CPU0_PE3_TX_C_DP<9>")
	)
	(segment
		(start 392.194288 -415.534348)
		(end 392.241786 -415.968942)
		(width 0.14732)
		(layer "In6.Cu")
		(net "P5E_CPU0_PE3_TX_C_DP<9>")
	)
	(segment
		(start 391.71753 -412.336488)
		(end 391.825226 -413.315912)
		(width 0.14732)
		(layer "In6.Cu")
		(net "P5E_CPU0_PE3_TX_C_DP<9>")
	)
	(segment
		(start 391.984992 -413.443928)
		(end 392.025378 -413.81045)
		(width 0.14732)
		(layer "In6.Cu")
		(net "P5E_CPU0_PE3_TX_C_DP<9>")
	)
	(segment
		(start 393.529058 -430.162208)
		(end 393.750038 -429.941228)
		(width 0.14732)
		(layer "In6.Cu")
		(net "P5E_CPU0_PE3_TX_C_DP<9>")
	)
	(segment
		(start 391.825226 -413.315912)
		(end 391.984992 -413.443928)
		(width 0.14732)
		(layer "In6.Cu")
		(net "P5E_CPU0_PE3_TX_C_DP<9>")
	)
	(segment
		(start 392.01217 -410.030168)
		(end 391.71753 -410.324808)
		(width 0.14732)
		(layer "In6.Cu")
		(net "P5E_CPU0_PE3_TX_C_DP<9>")
	)
	(segment
		(start 391.897108 -413.969962)
		(end 391.93724 -414.335976)
		(width 0.14732)
		(layer "In6.Cu")
		(net "P5E_CPU0_PE3_TX_C_DP<9>")
	)
	(segment
		(start 393.066778 -430.00549)
		(end 393.223496 -430.162208)
		(width 0.14732)
		(layer "In6.Cu")
		(net "P5E_CPU0_PE3_TX_C_DP<9>")
	)
	(segment
		(start 393.223496 -430.162208)
		(end 393.529058 -430.162208)
		(width 0.14732)
		(layer "In6.Cu")
		(net "P5E_CPU0_PE3_TX_C_DP<9>")
	)
	(segment
		(start 392.137392 -414.830514)
		(end 392.009122 -414.990026)
		(width 0.14732)
		(layer "In6.Cu")
		(net "P5E_CPU0_PE3_TX_C_DP<9>")
	)
	(segment
		(start 392.31697 -416.650424)
		(end 392.364468 -417.085018)
		(width 0.14732)
		(layer "In6.Cu")
		(net "P5E_CPU0_PE3_TX_C_DP<9>")
	)
	(segment
		(start 393.066778 -424.630088)
		(end 393.066778 -430.00549)
		(width 0.14732)
		(layer "In6.Cu")
		(net "P5E_CPU0_PE3_TX_C_DP<9>")
	)
	(segment
		(start 392.131804 -416.106102)
		(end 392.179302 -416.540188)
		(width 0.14732)
		(layer "In6.Cu")
		(net "P5E_CPU0_PE3_TX_C_DP<9>")
	)
	(segment
		(start 392.179302 -416.540188)
		(end 392.31697 -416.650424)
		(width 0.14732)
		(layer "In6.Cu")
		(net "P5E_CPU0_PE3_TX_C_DP<9>")
	)
	(segment
		(start 393.750038 -429.941228)
		(end 393.750038 -429.689768)
		(width 0.14732)
		(layer "In6.Cu")
		(net "P5E_CPU0_PE3_TX_C_DP<9>")
	)
	(segment
		(start 394.773912 -409.110942)
		(end 395.10081 -408.784044)
		(width 0.13208)
		(layer "F.Cu")
		(net "P5E_CPU0_PE3_TX_C_DP<8>")
	)
	(segment
		(start 395.07541 -410.030168)
		(end 394.773912 -409.72867)
		(width 0.13208)
		(layer "F.Cu")
		(net "P5E_CPU0_PE3_TX_C_DP<8>")
	)
	(segment
		(start 394.773912 -409.72867)
		(end 394.773912 -409.110942)
		(width 0.13208)
		(layer "F.Cu")
		(net "P5E_CPU0_PE3_TX_C_DP<8>")
	)
	(segment
		(start 395.546072 -431.145188)
		(end 395.750034 -430.941226)
		(width 0.14732)
		(layer "In6.Cu")
		(net "P5E_CPU0_PE3_TX_C_DP<8>")
	)
	(segment
		(start 394.795248 -412.004256)
		(end 394.922502 -412.125922)
		(width 0.14732)
		(layer "In6.Cu")
		(net "P5E_CPU0_PE3_TX_C_DP<8>")
	)
	(segment
		(start 394.77188 -410.333698)
		(end 394.77188 -410.8704)
		(width 0.14732)
		(layer "In6.Cu")
		(net "P5E_CPU0_PE3_TX_C_DP<8>")
	)
	(segment
		(start 394.955014 -413.685482)
		(end 394.833094 -413.812736)
		(width 0.14732)
		(layer "In6.Cu")
		(net "P5E_CPU0_PE3_TX_C_DP<8>")
	)
	(segment
		(start 395.057884 -430.951894)
		(end 395.251178 -431.145188)
		(width 0.14732)
		(layer "In6.Cu")
		(net "P5E_CPU0_PE3_TX_C_DP<8>")
	)
	(segment
		(start 394.931646 -412.563056)
		(end 394.809726 -412.690056)
		(width 0.14732)
		(layer "In6.Cu")
		(net "P5E_CPU0_PE3_TX_C_DP<8>")
	)
	(segment
		(start 394.969238 -414.371282)
		(end 394.978382 -414.808162)
		(width 0.14732)
		(layer "In6.Cu")
		(net "P5E_CPU0_PE3_TX_C_DP<8>")
	)
	(segment
		(start 394.856462 -414.935416)
		(end 394.856462 -414.938972)
		(width 0.14732)
		(layer "In6.Cu")
		(net "P5E_CPU0_PE3_TX_C_DP<8>")
	)
	(segment
		(start 394.833094 -413.812736)
		(end 394.841984 -414.249362)
		(width 0.14732)
		(layer "In6.Cu")
		(net "P5E_CPU0_PE3_TX_C_DP<8>")
	)
	(segment
		(start 394.841984 -414.249362)
		(end 394.969238 -414.371282)
		(width 0.14732)
		(layer "In6.Cu")
		(net "P5E_CPU0_PE3_TX_C_DP<8>")
	)
	(segment
		(start 395.750034 -430.941226)
		(end 395.750034 -430.689766)
		(width 0.14732)
		(layer "In6.Cu")
		(net "P5E_CPU0_PE3_TX_C_DP<8>")
	)
	(segment
		(start 395.251178 -431.145188)
		(end 395.546072 -431.145188)
		(width 0.14732)
		(layer "In6.Cu")
		(net "P5E_CPU0_PE3_TX_C_DP<8>")
	)
	(segment
		(start 394.94587 -413.248602)
		(end 394.955014 -413.685482)
		(width 0.14732)
		(layer "In6.Cu")
		(net "P5E_CPU0_PE3_TX_C_DP<8>")
	)
	(segment
		(start 394.809726 -412.690056)
		(end 394.818616 -413.126682)
		(width 0.14732)
		(layer "In6.Cu")
		(net "P5E_CPU0_PE3_TX_C_DP<8>")
	)
	(segment
		(start 395.07541 -410.030168)
		(end 394.77188 -410.333698)
		(width 0.14732)
		(layer "In6.Cu")
		(net "P5E_CPU0_PE3_TX_C_DP<8>")
	)
	(segment
		(start 394.856462 -414.938972)
		(end 395.057884 -424.634152)
		(width 0.14732)
		(layer "In6.Cu")
		(net "P5E_CPU0_PE3_TX_C_DP<8>")
	)
	(segment
		(start 394.922502 -412.125922)
		(end 394.931646 -412.563056)
		(width 0.14732)
		(layer "In6.Cu")
		(net "P5E_CPU0_PE3_TX_C_DP<8>")
	)
	(segment
		(start 394.978382 -414.808162)
		(end 394.856462 -414.935416)
		(width 0.14732)
		(layer "In6.Cu")
		(net "P5E_CPU0_PE3_TX_C_DP<8>")
	)
	(segment
		(start 395.057884 -424.634152)
		(end 395.057884 -430.951894)
		(width 0.14732)
		(layer "In6.Cu")
		(net "P5E_CPU0_PE3_TX_C_DP<8>")
	)
	(segment
		(start 394.77188 -410.8704)
		(end 394.795248 -412.004256)
		(width 0.14732)
		(layer "In6.Cu")
		(net "P5E_CPU0_PE3_TX_C_DP<8>")
	)
	(segment
		(start 394.818616 -413.126682)
		(end 394.94587 -413.248602)
		(width 0.14732)
		(layer "In6.Cu")
		(net "P5E_CPU0_PE3_TX_C_DP<8>")
	)
	(segment
		(start 398.13865 -410.030168)
		(end 397.837152 -409.72867)
		(width 0.13208)
		(layer "F.Cu")
		(net "P5E_CPU0_PE3_TX_C_DP<7>")
	)
	(segment
		(start 397.837152 -409.72867)
		(end 397.837152 -409.110942)
		(width 0.13208)
		(layer "F.Cu")
		(net "P5E_CPU0_PE3_TX_C_DP<7>")
	)
	(segment
		(start 397.837152 -409.110942)
		(end 398.16405 -408.784044)
		(width 0.13208)
		(layer "F.Cu")
		(net "P5E_CPU0_PE3_TX_C_DP<7>")
	)
	(segment
		(start 398.003776 -413.825436)
		(end 397.881348 -413.951674)
		(width 0.14732)
		(layer "In6.Cu")
		(net "P5E_CPU0_PE3_TX_C_DP<7>")
	)
	(segment
		(start 398.750028 -429.941228)
		(end 398.750028 -429.689768)
		(width 0.14732)
		(layer "In6.Cu")
		(net "P5E_CPU0_PE3_TX_C_DP<7>")
	)
	(segment
		(start 397.997426 -413.388302)
		(end 398.003776 -413.825436)
		(width 0.14732)
		(layer "In6.Cu")
		(net "P5E_CPU0_PE3_TX_C_DP<7>")
	)
	(segment
		(start 397.904208 -415.51098)
		(end 398.0307 -415.633662)
		(width 0.14732)
		(layer "In6.Cu")
		(net "P5E_CPU0_PE3_TX_C_DP<7>")
	)
	(segment
		(start 397.864584 -412.828994)
		(end 397.870934 -413.26562)
		(width 0.14732)
		(layer "In6.Cu")
		(net "P5E_CPU0_PE3_TX_C_DP<7>")
	)
	(segment
		(start 398.538446 -430.15281)
		(end 398.750028 -429.941228)
		(width 0.14732)
		(layer "In6.Cu")
		(net "P5E_CPU0_PE3_TX_C_DP<7>")
	)
	(segment
		(start 398.01419 -414.510982)
		(end 398.02054 -414.948116)
		(width 0.14732)
		(layer "In6.Cu")
		(net "P5E_CPU0_PE3_TX_C_DP<7>")
	)
	(segment
		(start 397.83512 -410.333698)
		(end 397.83512 -410.835348)
		(width 0.14732)
		(layer "In6.Cu")
		(net "P5E_CPU0_PE3_TX_C_DP<7>")
	)
	(segment
		(start 398.03705 -416.070796)
		(end 397.914368 -416.197034)
		(width 0.14732)
		(layer "In6.Cu")
		(net "P5E_CPU0_PE3_TX_C_DP<7>")
	)
	(segment
		(start 397.980662 -412.265622)
		(end 397.987266 -412.702756)
		(width 0.14732)
		(layer "In6.Cu")
		(net "P5E_CPU0_PE3_TX_C_DP<7>")
	)
	(segment
		(start 397.914368 -416.197034)
		(end 397.914114 -416.197288)
		(width 0.14732)
		(layer "In6.Cu")
		(net "P5E_CPU0_PE3_TX_C_DP<7>")
	)
	(segment
		(start 397.881348 -413.951674)
		(end 397.887698 -414.3883)
		(width 0.14732)
		(layer "In6.Cu")
		(net "P5E_CPU0_PE3_TX_C_DP<7>")
	)
	(segment
		(start 398.214088 -430.15281)
		(end 398.538446 -430.15281)
		(width 0.14732)
		(layer "In6.Cu")
		(net "P5E_CPU0_PE3_TX_C_DP<7>")
	)
	(segment
		(start 397.897858 -415.074354)
		(end 397.904208 -415.51098)
		(width 0.14732)
		(layer "In6.Cu")
		(net "P5E_CPU0_PE3_TX_C_DP<7>")
	)
	(segment
		(start 397.854424 -412.143448)
		(end 397.980662 -412.265622)
		(width 0.14732)
		(layer "In6.Cu")
		(net "P5E_CPU0_PE3_TX_C_DP<7>")
	)
	(segment
		(start 397.987266 -412.702756)
		(end 397.864584 -412.828994)
		(width 0.14732)
		(layer "In6.Cu")
		(net "P5E_CPU0_PE3_TX_C_DP<7>")
	)
	(segment
		(start 398.0307 -415.633662)
		(end 398.03705 -416.070796)
		(width 0.14732)
		(layer "In6.Cu")
		(net "P5E_CPU0_PE3_TX_C_DP<7>")
	)
	(segment
		(start 398.13865 -410.030168)
		(end 397.83512 -410.333698)
		(width 0.14732)
		(layer "In6.Cu")
		(net "P5E_CPU0_PE3_TX_C_DP<7>")
	)
	(segment
		(start 397.914114 -416.197288)
		(end 398.03197 -424.206924)
		(width 0.14732)
		(layer "In6.Cu")
		(net "P5E_CPU0_PE3_TX_C_DP<7>")
	)
	(segment
		(start 398.02054 -414.948116)
		(end 397.897858 -415.074354)
		(width 0.14732)
		(layer "In6.Cu")
		(net "P5E_CPU0_PE3_TX_C_DP<7>")
	)
	(segment
		(start 397.887698 -414.3883)
		(end 398.01419 -414.510982)
		(width 0.14732)
		(layer "In6.Cu")
		(net "P5E_CPU0_PE3_TX_C_DP<7>")
	)
	(segment
		(start 397.83512 -410.835348)
		(end 397.854424 -412.143448)
		(width 0.14732)
		(layer "In6.Cu")
		(net "P5E_CPU0_PE3_TX_C_DP<7>")
	)
	(segment
		(start 398.03197 -429.970692)
		(end 398.214088 -430.15281)
		(width 0.14732)
		(layer "In6.Cu")
		(net "P5E_CPU0_PE3_TX_C_DP<7>")
	)
	(segment
		(start 397.870934 -413.26562)
		(end 397.997426 -413.388302)
		(width 0.14732)
		(layer "In6.Cu")
		(net "P5E_CPU0_PE3_TX_C_DP<7>")
	)
	(segment
		(start 398.03197 -424.206924)
		(end 398.03197 -429.970692)
		(width 0.14732)
		(layer "In6.Cu")
		(net "P5E_CPU0_PE3_TX_C_DP<7>")
	)
	(segment
		(start 400.900392 -409.72867)
		(end 400.900392 -409.110942)
		(width 0.13208)
		(layer "F.Cu")
		(net "P5E_CPU0_PE3_TX_C_DP<6>")
	)
	(segment
		(start 401.20189 -410.030168)
		(end 400.900392 -409.72867)
		(width 0.13208)
		(layer "F.Cu")
		(net "P5E_CPU0_PE3_TX_C_DP<6>")
	)
	(segment
		(start 400.900392 -409.110942)
		(end 401.22729 -408.784044)
		(width 0.13208)
		(layer "F.Cu")
		(net "P5E_CPU0_PE3_TX_C_DP<6>")
	)
	(segment
		(start 400.94027 -412.191962)
		(end 400.9136 -412.628334)
		(width 0.14732)
		(layer "In6.Cu")
		(net "P5E_CPU0_PE3_TX_C_DP<6>")
	)
	(segment
		(start 400.78152 -412.74492)
		(end 400.755104 -413.180784)
		(width 0.14732)
		(layer "In6.Cu")
		(net "P5E_CPU0_PE3_TX_C_DP<6>")
	)
	(segment
		(start 400.87169 -413.31261)
		(end 400.845274 -413.748982)
		(width 0.14732)
		(layer "In6.Cu")
		(net "P5E_CPU0_PE3_TX_C_DP<6>")
	)
	(segment
		(start 400.89836 -410.333698)
		(end 400.89836 -410.828744)
		(width 0.14732)
		(layer "In6.Cu")
		(net "P5E_CPU0_PE3_TX_C_DP<6>")
	)
	(segment
		(start 400.066764 -430.98212)
		(end 400.237452 -431.152808)
		(width 0.14732)
		(layer "In6.Cu")
		(net "P5E_CPU0_PE3_TX_C_DP<6>")
	)
	(segment
		(start 400.713194 -413.865568)
		(end 400.713702 -413.865822)
		(width 0.14732)
		(layer "In6.Cu")
		(net "P5E_CPU0_PE3_TX_C_DP<6>")
	)
	(segment
		(start 400.755104 -413.180784)
		(end 400.87169 -413.31261)
		(width 0.14732)
		(layer "In6.Cu")
		(net "P5E_CPU0_PE3_TX_C_DP<6>")
	)
	(segment
		(start 400.713702 -413.865822)
		(end 400.066764 -424.491404)
		(width 0.14732)
		(layer "In6.Cu")
		(net "P5E_CPU0_PE3_TX_C_DP<6>")
	)
	(segment
		(start 400.845274 -413.748982)
		(end 400.713194 -413.865568)
		(width 0.14732)
		(layer "In6.Cu")
		(net "P5E_CPU0_PE3_TX_C_DP<6>")
	)
	(segment
		(start 400.066764 -424.491404)
		(end 400.066764 -430.98212)
		(width 0.14732)
		(layer "In6.Cu")
		(net "P5E_CPU0_PE3_TX_C_DP<6>")
	)
	(segment
		(start 400.237452 -431.152808)
		(end 400.538442 -431.152808)
		(width 0.14732)
		(layer "In6.Cu")
		(net "P5E_CPU0_PE3_TX_C_DP<6>")
	)
	(segment
		(start 400.82343 -412.060136)
		(end 400.94027 -412.191962)
		(width 0.14732)
		(layer "In6.Cu")
		(net "P5E_CPU0_PE3_TX_C_DP<6>")
	)
	(segment
		(start 401.20189 -410.030168)
		(end 400.89836 -410.333698)
		(width 0.14732)
		(layer "In6.Cu")
		(net "P5E_CPU0_PE3_TX_C_DP<6>")
	)
	(segment
		(start 400.750024 -430.941226)
		(end 400.750024 -430.689766)
		(width 0.14732)
		(layer "In6.Cu")
		(net "P5E_CPU0_PE3_TX_C_DP<6>")
	)
	(segment
		(start 400.9136 -412.628334)
		(end 400.78152 -412.74492)
		(width 0.14732)
		(layer "In6.Cu")
		(net "P5E_CPU0_PE3_TX_C_DP<6>")
	)
	(segment
		(start 400.538442 -431.152808)
		(end 400.750024 -430.941226)
		(width 0.14732)
		(layer "In6.Cu")
		(net "P5E_CPU0_PE3_TX_C_DP<6>")
	)
	(segment
		(start 400.89836 -410.828744)
		(end 400.82343 -412.060136)
		(width 0.14732)
		(layer "In6.Cu")
		(net "P5E_CPU0_PE3_TX_C_DP<6>")
	)
	(segment
		(start 403.963632 -409.110942)
		(end 404.29053 -408.784044)
		(width 0.13208)
		(layer "F.Cu")
		(net "P5E_CPU0_PE3_TX_C_DP<5>")
	)
	(segment
		(start 404.26513 -410.030168)
		(end 403.963632 -409.72867)
		(width 0.13208)
		(layer "F.Cu")
		(net "P5E_CPU0_PE3_TX_C_DP<5>")
	)
	(segment
		(start 403.963632 -409.72867)
		(end 403.963632 -409.110942)
		(width 0.13208)
		(layer "F.Cu")
		(net "P5E_CPU0_PE3_TX_C_DP<5>")
	)
	(segment
		(start 403.902164 -412.350966)
		(end 403.842728 -412.784036)
		(width 0.14732)
		(layer "In6.Cu")
		(net "P5E_CPU0_PE3_TX_C_DP<5>")
	)
	(segment
		(start 403.526752 -415.07918)
		(end 403.386036 -415.185352)
		(width 0.14732)
		(layer "In6.Cu")
		(net "P5E_CPU0_PE3_TX_C_DP<5>")
	)
	(segment
		(start 402.226018 -430.164748)
		(end 402.5265 -430.164748)
		(width 0.14732)
		(layer "In6.Cu")
		(net "P5E_CPU0_PE3_TX_C_DP<5>")
	)
	(segment
		(start 403.539706 -414.073086)
		(end 403.48027 -414.505648)
		(width 0.14732)
		(layer "In6.Cu")
		(net "P5E_CPU0_PE3_TX_C_DP<5>")
	)
	(segment
		(start 403.9616 -410.333698)
		(end 403.9616 -411.004258)
		(width 0.14732)
		(layer "In6.Cu")
		(net "P5E_CPU0_PE3_TX_C_DP<5>")
	)
	(segment
		(start 404.26513 -410.030168)
		(end 403.9616 -410.333698)
		(width 0.14732)
		(layer "In6.Cu")
		(net "P5E_CPU0_PE3_TX_C_DP<5>")
	)
	(segment
		(start 403.386798 -415.185352)
		(end 403.327362 -415.617914)
		(width 0.14732)
		(layer "In6.Cu")
		(net "P5E_CPU0_PE3_TX_C_DP<5>")
	)
	(segment
		(start 402.06676 -430.00549)
		(end 402.226018 -430.164748)
		(width 0.14732)
		(layer "In6.Cu")
		(net "P5E_CPU0_PE3_TX_C_DP<5>")
	)
	(segment
		(start 403.586188 -414.64611)
		(end 403.526752 -415.07918)
		(width 0.14732)
		(layer "In6.Cu")
		(net "P5E_CPU0_PE3_TX_C_DP<5>")
	)
	(segment
		(start 403.327362 -415.617914)
		(end 403.433788 -415.758376)
		(width 0.14732)
		(layer "In6.Cu")
		(net "P5E_CPU0_PE3_TX_C_DP<5>")
	)
	(segment
		(start 403.386036 -415.185352)
		(end 403.386798 -415.185352)
		(width 0.14732)
		(layer "In6.Cu")
		(net "P5E_CPU0_PE3_TX_C_DP<5>")
	)
	(segment
		(start 402.5265 -430.164748)
		(end 402.75002 -429.941228)
		(width 0.14732)
		(layer "In6.Cu")
		(net "P5E_CPU0_PE3_TX_C_DP<5>")
	)
	(segment
		(start 403.633178 -413.393382)
		(end 403.739604 -413.53359)
		(width 0.14732)
		(layer "In6.Cu")
		(net "P5E_CPU0_PE3_TX_C_DP<5>")
	)
	(segment
		(start 403.795992 -412.210758)
		(end 403.902164 -412.350966)
		(width 0.14732)
		(layer "In6.Cu")
		(net "P5E_CPU0_PE3_TX_C_DP<5>")
	)
	(segment
		(start 403.702266 -412.890462)
		(end 403.633178 -413.393382)
		(width 0.14732)
		(layer "In6.Cu")
		(net "P5E_CPU0_PE3_TX_C_DP<5>")
	)
	(segment
		(start 403.842728 -412.784036)
		(end 403.702266 -412.890462)
		(width 0.14732)
		(layer "In6.Cu")
		(net "P5E_CPU0_PE3_TX_C_DP<5>")
	)
	(segment
		(start 403.433788 -415.758376)
		(end 403.374098 -416.191446)
		(width 0.14732)
		(layer "In6.Cu")
		(net "P5E_CPU0_PE3_TX_C_DP<5>")
	)
	(segment
		(start 403.48027 -414.505648)
		(end 403.479762 -414.505648)
		(width 0.14732)
		(layer "In6.Cu")
		(net "P5E_CPU0_PE3_TX_C_DP<5>")
	)
	(segment
		(start 403.680168 -413.96666)
		(end 403.539706 -414.073086)
		(width 0.14732)
		(layer "In6.Cu")
		(net "P5E_CPU0_PE3_TX_C_DP<5>")
	)
	(segment
		(start 403.739604 -413.53359)
		(end 403.680168 -413.96666)
		(width 0.14732)
		(layer "In6.Cu")
		(net "P5E_CPU0_PE3_TX_C_DP<5>")
	)
	(segment
		(start 403.479762 -414.505648)
		(end 403.586188 -414.64611)
		(width 0.14732)
		(layer "In6.Cu")
		(net "P5E_CPU0_PE3_TX_C_DP<5>")
	)
	(segment
		(start 403.9616 -411.004258)
		(end 403.795992 -412.210758)
		(width 0.14732)
		(layer "In6.Cu")
		(net "P5E_CPU0_PE3_TX_C_DP<5>")
	)
	(segment
		(start 402.75002 -429.941228)
		(end 402.75002 -429.689768)
		(width 0.14732)
		(layer "In6.Cu")
		(net "P5E_CPU0_PE3_TX_C_DP<5>")
	)
	(segment
		(start 403.374098 -416.191446)
		(end 403.233636 -416.297618)
		(width 0.14732)
		(layer "In6.Cu")
		(net "P5E_CPU0_PE3_TX_C_DP<5>")
	)
	(segment
		(start 402.06676 -424.782488)
		(end 402.06676 -430.00549)
		(width 0.14732)
		(layer "In6.Cu")
		(net "P5E_CPU0_PE3_TX_C_DP<5>")
	)
	(segment
		(start 403.233636 -416.297618)
		(end 402.06676 -424.782488)
		(width 0.14732)
		(layer "In6.Cu")
		(net "P5E_CPU0_PE3_TX_C_DP<5>")
	)
	(segment
		(start 407.026872 -409.110942)
		(end 407.35377 -408.784044)
		(width 0.13208)
		(layer "F.Cu")
		(net "P5E_CPU0_PE3_TX_C_DP<4>")
	)
	(segment
		(start 407.026872 -409.72867)
		(end 407.026872 -409.110942)
		(width 0.13208)
		(layer "F.Cu")
		(net "P5E_CPU0_PE3_TX_C_DP<4>")
	)
	(segment
		(start 407.32837 -410.030168)
		(end 407.026872 -409.72867)
		(width 0.13208)
		(layer "F.Cu")
		(net "P5E_CPU0_PE3_TX_C_DP<4>")
	)
	(segment
		(start 406.531826 -413.132524)
		(end 406.421844 -413.644334)
		(width 0.14732)
		(layer "In6.Cu")
		(net "P5E_CPU0_PE3_TX_C_DP<4>")
	)
	(segment
		(start 406.679908 -413.03702)
		(end 406.531826 -413.132524)
		(width 0.14732)
		(layer "In6.Cu")
		(net "P5E_CPU0_PE3_TX_C_DP<4>")
	)
	(segment
		(start 407.02484 -410.842206)
		(end 406.676352 -412.461964)
		(width 0.14732)
		(layer "In6.Cu")
		(net "P5E_CPU0_PE3_TX_C_DP<4>")
	)
	(segment
		(start 404.066756 -431.005488)
		(end 404.196296 -431.135028)
		(width 0.14732)
		(layer "In6.Cu")
		(net "P5E_CPU0_PE3_TX_C_DP<4>")
	)
	(segment
		(start 406.771856 -412.609792)
		(end 406.679908 -413.03702)
		(width 0.14732)
		(layer "In6.Cu")
		(net "P5E_CPU0_PE3_TX_C_DP<4>")
	)
	(segment
		(start 406.169876 -415.405824)
		(end 406.022048 -415.50082)
		(width 0.14732)
		(layer "In6.Cu")
		(net "P5E_CPU0_PE3_TX_C_DP<4>")
	)
	(segment
		(start 407.02484 -410.333698)
		(end 407.02484 -410.842206)
		(width 0.14732)
		(layer "In6.Cu")
		(net "P5E_CPU0_PE3_TX_C_DP<4>")
	)
	(segment
		(start 404.066756 -424.583098)
		(end 404.066756 -431.005488)
		(width 0.14732)
		(layer "In6.Cu")
		(net "P5E_CPU0_PE3_TX_C_DP<4>")
	)
	(segment
		(start 406.022048 -415.50082)
		(end 404.066756 -424.583098)
		(width 0.14732)
		(layer "In6.Cu")
		(net "P5E_CPU0_PE3_TX_C_DP<4>")
	)
	(segment
		(start 406.261824 -414.978342)
		(end 406.169876 -415.405824)
		(width 0.14732)
		(layer "In6.Cu")
		(net "P5E_CPU0_PE3_TX_C_DP<4>")
	)
	(segment
		(start 406.517094 -413.792162)
		(end 406.425146 -414.21939)
		(width 0.14732)
		(layer "In6.Cu")
		(net "P5E_CPU0_PE3_TX_C_DP<4>")
	)
	(segment
		(start 404.750016 -430.941226)
		(end 404.750016 -430.689766)
		(width 0.14732)
		(layer "In6.Cu")
		(net "P5E_CPU0_PE3_TX_C_DP<4>")
	)
	(segment
		(start 404.556214 -431.135028)
		(end 404.750016 -430.941226)
		(width 0.14732)
		(layer "In6.Cu")
		(net "P5E_CPU0_PE3_TX_C_DP<4>")
	)
	(segment
		(start 406.676352 -412.461964)
		(end 406.771856 -412.609792)
		(width 0.14732)
		(layer "In6.Cu")
		(net "P5E_CPU0_PE3_TX_C_DP<4>")
	)
	(segment
		(start 406.16632 -414.830514)
		(end 406.261824 -414.978342)
		(width 0.14732)
		(layer "In6.Cu")
		(net "P5E_CPU0_PE3_TX_C_DP<4>")
	)
	(segment
		(start 406.425146 -414.21939)
		(end 406.277318 -414.31464)
		(width 0.14732)
		(layer "In6.Cu")
		(net "P5E_CPU0_PE3_TX_C_DP<4>")
	)
	(segment
		(start 406.277318 -414.31464)
		(end 406.16632 -414.830514)
		(width 0.14732)
		(layer "In6.Cu")
		(net "P5E_CPU0_PE3_TX_C_DP<4>")
	)
	(segment
		(start 404.196296 -431.135028)
		(end 404.556214 -431.135028)
		(width 0.14732)
		(layer "In6.Cu")
		(net "P5E_CPU0_PE3_TX_C_DP<4>")
	)
	(segment
		(start 407.32837 -410.030168)
		(end 407.02484 -410.333698)
		(width 0.14732)
		(layer "In6.Cu")
		(net "P5E_CPU0_PE3_TX_C_DP<4>")
	)
	(segment
		(start 406.421844 -413.644334)
		(end 406.517094 -413.792162)
		(width 0.14732)
		(layer "In6.Cu")
		(net "P5E_CPU0_PE3_TX_C_DP<4>")
	)
	(segment
		(start 410.39161 -410.030168)
		(end 410.090112 -409.72867)
		(width 0.13208)
		(layer "F.Cu")
		(net "P5E_CPU0_PE3_TX_C_DP<3>")
	)
	(segment
		(start 410.090112 -409.72867)
		(end 410.090112 -409.110942)
		(width 0.13208)
		(layer "F.Cu")
		(net "P5E_CPU0_PE3_TX_C_DP<3>")
	)
	(segment
		(start 410.090112 -409.110942)
		(end 410.41701 -408.784044)
		(width 0.13208)
		(layer "F.Cu")
		(net "P5E_CPU0_PE3_TX_C_DP<3>")
	)
	(segment
		(start 408.50566 -416.296602)
		(end 408.590496 -416.45078)
		(width 0.14732)
		(layer "In6.Cu")
		(net "P5E_CPU0_PE3_TX_C_DP<3>")
	)
	(segment
		(start 409.40863 -413.635952)
		(end 409.254198 -413.720788)
		(width 0.14732)
		(layer "In6.Cu")
		(net "P5E_CPU0_PE3_TX_C_DP<3>")
	)
	(segment
		(start 406.214072 -430.15281)
		(end 406.53843 -430.15281)
		(width 0.14732)
		(layer "In6.Cu")
		(net "P5E_CPU0_PE3_TX_C_DP<3>")
	)
	(segment
		(start 408.314398 -416.955224)
		(end 406.066752 -424.687492)
		(width 0.14732)
		(layer "In6.Cu")
		(net "P5E_CPU0_PE3_TX_C_DP<3>")
	)
	(segment
		(start 409.217114 -414.29432)
		(end 409.095194 -414.714182)
		(width 0.14732)
		(layer "In6.Cu")
		(net "P5E_CPU0_PE3_TX_C_DP<3>")
	)
	(segment
		(start 409.254198 -413.720788)
		(end 409.132278 -414.140142)
		(width 0.14732)
		(layer "In6.Cu")
		(net "P5E_CPU0_PE3_TX_C_DP<3>")
	)
	(segment
		(start 408.782012 -415.792412)
		(end 408.62758 -415.877248)
		(width 0.14732)
		(layer "In6.Cu")
		(net "P5E_CPU0_PE3_TX_C_DP<3>")
	)
	(segment
		(start 410.08808 -410.333698)
		(end 410.08808 -410.851604)
		(width 0.14732)
		(layer "In6.Cu")
		(net "P5E_CPU0_PE3_TX_C_DP<3>")
	)
	(segment
		(start 409.445714 -413.061912)
		(end 409.53055 -413.21609)
		(width 0.14732)
		(layer "In6.Cu")
		(net "P5E_CPU0_PE3_TX_C_DP<3>")
	)
	(segment
		(start 408.903932 -415.37255)
		(end 408.782012 -415.792412)
		(width 0.14732)
		(layer "In6.Cu")
		(net "P5E_CPU0_PE3_TX_C_DP<3>")
	)
	(segment
		(start 409.132278 -414.140142)
		(end 409.217114 -414.29432)
		(width 0.14732)
		(layer "In6.Cu")
		(net "P5E_CPU0_PE3_TX_C_DP<3>")
	)
	(segment
		(start 409.095194 -414.714182)
		(end 408.941016 -414.798764)
		(width 0.14732)
		(layer "In6.Cu")
		(net "P5E_CPU0_PE3_TX_C_DP<3>")
	)
	(segment
		(start 408.819096 -415.218372)
		(end 408.903932 -415.37255)
		(width 0.14732)
		(layer "In6.Cu")
		(net "P5E_CPU0_PE3_TX_C_DP<3>")
	)
	(segment
		(start 406.066752 -430.00549)
		(end 406.214072 -430.15281)
		(width 0.14732)
		(layer "In6.Cu")
		(net "P5E_CPU0_PE3_TX_C_DP<3>")
	)
	(segment
		(start 410.39161 -410.030168)
		(end 410.08808 -410.333698)
		(width 0.14732)
		(layer "In6.Cu")
		(net "P5E_CPU0_PE3_TX_C_DP<3>")
	)
	(segment
		(start 410.08808 -410.851604)
		(end 409.445714 -413.061912)
		(width 0.14732)
		(layer "In6.Cu")
		(net "P5E_CPU0_PE3_TX_C_DP<3>")
	)
	(segment
		(start 408.590496 -416.45078)
		(end 408.468576 -416.870642)
		(width 0.14732)
		(layer "In6.Cu")
		(net "P5E_CPU0_PE3_TX_C_DP<3>")
	)
	(segment
		(start 408.62758 -415.877248)
		(end 408.50566 -416.296602)
		(width 0.14732)
		(layer "In6.Cu")
		(net "P5E_CPU0_PE3_TX_C_DP<3>")
	)
	(segment
		(start 406.066752 -424.687492)
		(end 406.066752 -430.00549)
		(width 0.14732)
		(layer "In6.Cu")
		(net "P5E_CPU0_PE3_TX_C_DP<3>")
	)
	(segment
		(start 408.468576 -416.870642)
		(end 408.314398 -416.955224)
		(width 0.14732)
		(layer "In6.Cu")
		(net "P5E_CPU0_PE3_TX_C_DP<3>")
	)
	(segment
		(start 406.750012 -429.941228)
		(end 406.750012 -429.689768)
		(width 0.14732)
		(layer "In6.Cu")
		(net "P5E_CPU0_PE3_TX_C_DP<3>")
	)
	(segment
		(start 408.941016 -414.798764)
		(end 408.819096 -415.218372)
		(width 0.14732)
		(layer "In6.Cu")
		(net "P5E_CPU0_PE3_TX_C_DP<3>")
	)
	(segment
		(start 406.53843 -430.15281)
		(end 406.750012 -429.941228)
		(width 0.14732)
		(layer "In6.Cu")
		(net "P5E_CPU0_PE3_TX_C_DP<3>")
	)
	(segment
		(start 409.53055 -413.21609)
		(end 409.40863 -413.635952)
		(width 0.14732)
		(layer "In6.Cu")
		(net "P5E_CPU0_PE3_TX_C_DP<3>")
	)
	(segment
		(start 413.153352 -409.72867)
		(end 413.153352 -409.110942)
		(width 0.13208)
		(layer "F.Cu")
		(net "P5E_CPU0_PE3_TX_C_DP<2>")
	)
	(segment
		(start 413.153352 -409.110942)
		(end 413.48025 -408.784044)
		(width 0.13208)
		(layer "F.Cu")
		(net "P5E_CPU0_PE3_TX_C_DP<2>")
	)
	(segment
		(start 413.45485 -410.030168)
		(end 413.153352 -409.72867)
		(width 0.13208)
		(layer "F.Cu")
		(net "P5E_CPU0_PE3_TX_C_DP<2>")
	)
	(segment
		(start 408.538426 -431.152808)
		(end 408.750008 -430.941226)
		(width 0.14732)
		(layer "In6.Cu")
		(net "P5E_CPU0_PE3_TX_C_DP<2>")
	)
	(segment
		(start 411.787848 -414.768792)
		(end 411.627574 -414.841182)
		(width 0.14732)
		(layer "In6.Cu")
		(net "P5E_CPU0_PE3_TX_C_DP<2>")
	)
	(segment
		(start 413.15132 -410.333698)
		(end 413.15132 -410.7942)
		(width 0.14732)
		(layer "In6.Cu")
		(net "P5E_CPU0_PE3_TX_C_DP<2>")
	)
	(segment
		(start 412.337504 -413.3088)
		(end 412.18358 -413.717994)
		(width 0.14732)
		(layer "In6.Cu")
		(net "P5E_CPU0_PE3_TX_C_DP<2>")
	)
	(segment
		(start 412.023052 -413.790638)
		(end 411.869128 -414.199324)
		(width 0.14732)
		(layer "In6.Cu")
		(net "P5E_CPU0_PE3_TX_C_DP<2>")
	)
	(segment
		(start 413.45485 -410.030168)
		(end 413.15132 -410.333698)
		(width 0.14732)
		(layer "In6.Cu")
		(net "P5E_CPU0_PE3_TX_C_DP<2>")
	)
	(segment
		(start 411.627574 -414.841182)
		(end 408.066748 -424.29811)
		(width 0.14732)
		(layer "In6.Cu")
		(net "P5E_CPU0_PE3_TX_C_DP<2>")
	)
	(segment
		(start 412.18358 -413.717994)
		(end 412.023052 -413.790638)
		(width 0.14732)
		(layer "In6.Cu")
		(net "P5E_CPU0_PE3_TX_C_DP<2>")
	)
	(segment
		(start 408.750008 -430.941226)
		(end 408.750008 -430.689766)
		(width 0.14732)
		(layer "In6.Cu")
		(net "P5E_CPU0_PE3_TX_C_DP<2>")
	)
	(segment
		(start 408.213052 -431.152808)
		(end 408.538426 -431.152808)
		(width 0.14732)
		(layer "In6.Cu")
		(net "P5E_CPU0_PE3_TX_C_DP<2>")
	)
	(segment
		(start 413.15132 -410.7942)
		(end 412.26486 -413.148526)
		(width 0.14732)
		(layer "In6.Cu")
		(net "P5E_CPU0_PE3_TX_C_DP<2>")
	)
	(segment
		(start 412.26486 -413.148526)
		(end 412.337504 -413.3088)
		(width 0.14732)
		(layer "In6.Cu")
		(net "P5E_CPU0_PE3_TX_C_DP<2>")
	)
	(segment
		(start 408.066748 -424.29811)
		(end 408.066748 -431.006504)
		(width 0.14732)
		(layer "In6.Cu")
		(net "P5E_CPU0_PE3_TX_C_DP<2>")
	)
	(segment
		(start 411.941772 -414.359598)
		(end 411.787848 -414.768792)
		(width 0.14732)
		(layer "In6.Cu")
		(net "P5E_CPU0_PE3_TX_C_DP<2>")
	)
	(segment
		(start 411.869128 -414.199324)
		(end 411.941772 -414.359598)
		(width 0.14732)
		(layer "In6.Cu")
		(net "P5E_CPU0_PE3_TX_C_DP<2>")
	)
	(segment
		(start 408.066748 -431.006504)
		(end 408.213052 -431.152808)
		(width 0.14732)
		(layer "In6.Cu")
		(net "P5E_CPU0_PE3_TX_C_DP<2>")
	)
	(segment
		(start 416.51809 -410.030168)
		(end 416.216592 -409.72867)
		(width 0.13208)
		(layer "F.Cu")
		(net "P5E_CPU0_PE3_TX_C_DP<1>")
	)
	(segment
		(start 416.216592 -409.110942)
		(end 416.54349 -408.784044)
		(width 0.13208)
		(layer "F.Cu")
		(net "P5E_CPU0_PE3_TX_C_DP<1>")
	)
	(segment
		(start 416.216592 -409.72867)
		(end 416.216592 -409.110942)
		(width 0.13208)
		(layer "F.Cu")
		(net "P5E_CPU0_PE3_TX_C_DP<1>")
	)
	(segment
		(start 414.124902 -415.574734)
		(end 414.187894 -415.739072)
		(width 0.14732)
		(layer "In6.Cu")
		(net "P5E_CPU0_PE3_TX_C_DP<1>")
	)
	(segment
		(start 414.644078 -414.712912)
		(end 414.466532 -415.112454)
		(width 0.14732)
		(layer "In6.Cu")
		(net "P5E_CPU0_PE3_TX_C_DP<1>")
	)
	(segment
		(start 416.21456 -410.87548)
		(end 415.03727 -413.522668)
		(width 0.14732)
		(layer "In6.Cu")
		(net "P5E_CPU0_PE3_TX_C_DP<1>")
	)
	(segment
		(start 413.554164 -417.164266)
		(end 413.389572 -417.227512)
		(width 0.14732)
		(layer "In6.Cu")
		(net "P5E_CPU0_PE3_TX_C_DP<1>")
	)
	(segment
		(start 413.668718 -416.60064)
		(end 413.73171 -416.764978)
		(width 0.14732)
		(layer "In6.Cu")
		(net "P5E_CPU0_PE3_TX_C_DP<1>")
	)
	(segment
		(start 415.03727 -413.522668)
		(end 415.100516 -413.687006)
		(width 0.14732)
		(layer "In6.Cu")
		(net "P5E_CPU0_PE3_TX_C_DP<1>")
	)
	(segment
		(start 413.389572 -417.227512)
		(end 410.066744 -424.699176)
		(width 0.14732)
		(layer "In6.Cu")
		(net "P5E_CPU0_PE3_TX_C_DP<1>")
	)
	(segment
		(start 414.92297 -414.086294)
		(end 414.758378 -414.14954)
		(width 0.14732)
		(layer "In6.Cu")
		(net "P5E_CPU0_PE3_TX_C_DP<1>")
	)
	(segment
		(start 414.30194 -415.175446)
		(end 414.302194 -415.1757)
		(width 0.14732)
		(layer "In6.Cu")
		(net "P5E_CPU0_PE3_TX_C_DP<1>")
	)
	(segment
		(start 413.73171 -416.764978)
		(end 413.554164 -417.164266)
		(width 0.14732)
		(layer "In6.Cu")
		(net "P5E_CPU0_PE3_TX_C_DP<1>")
	)
	(segment
		(start 414.187894 -415.739072)
		(end 414.010348 -416.138614)
		(width 0.14732)
		(layer "In6.Cu")
		(net "P5E_CPU0_PE3_TX_C_DP<1>")
	)
	(segment
		(start 413.84601 -416.201606)
		(end 413.668718 -416.60064)
		(width 0.14732)
		(layer "In6.Cu")
		(net "P5E_CPU0_PE3_TX_C_DP<1>")
	)
	(segment
		(start 416.51809 -410.030168)
		(end 416.21456 -410.333698)
		(width 0.14732)
		(layer "In6.Cu")
		(net "P5E_CPU0_PE3_TX_C_DP<1>")
	)
	(segment
		(start 410.538422 -430.15281)
		(end 410.750004 -429.941228)
		(width 0.14732)
		(layer "In6.Cu")
		(net "P5E_CPU0_PE3_TX_C_DP<1>")
	)
	(segment
		(start 414.302194 -415.1757)
		(end 414.124902 -415.574734)
		(width 0.14732)
		(layer "In6.Cu")
		(net "P5E_CPU0_PE3_TX_C_DP<1>")
	)
	(segment
		(start 410.066744 -430.00549)
		(end 410.214064 -430.15281)
		(width 0.14732)
		(layer "In6.Cu")
		(net "P5E_CPU0_PE3_TX_C_DP<1>")
	)
	(segment
		(start 410.066744 -424.699176)
		(end 410.066744 -430.00549)
		(width 0.14732)
		(layer "In6.Cu")
		(net "P5E_CPU0_PE3_TX_C_DP<1>")
	)
	(segment
		(start 410.214064 -430.15281)
		(end 410.538422 -430.15281)
		(width 0.14732)
		(layer "In6.Cu")
		(net "P5E_CPU0_PE3_TX_C_DP<1>")
	)
	(segment
		(start 414.758378 -414.14954)
		(end 414.581086 -414.548574)
		(width 0.14732)
		(layer "In6.Cu")
		(net "P5E_CPU0_PE3_TX_C_DP<1>")
	)
	(segment
		(start 414.581086 -414.548574)
		(end 414.644078 -414.712912)
		(width 0.14732)
		(layer "In6.Cu")
		(net "P5E_CPU0_PE3_TX_C_DP<1>")
	)
	(segment
		(start 410.750004 -429.941228)
		(end 410.750004 -429.689768)
		(width 0.14732)
		(layer "In6.Cu")
		(net "P5E_CPU0_PE3_TX_C_DP<1>")
	)
	(segment
		(start 415.100516 -413.687006)
		(end 414.92297 -414.086294)
		(width 0.14732)
		(layer "In6.Cu")
		(net "P5E_CPU0_PE3_TX_C_DP<1>")
	)
	(segment
		(start 414.010348 -416.138614)
		(end 413.84601 -416.201606)
		(width 0.14732)
		(layer "In6.Cu")
		(net "P5E_CPU0_PE3_TX_C_DP<1>")
	)
	(segment
		(start 414.466532 -415.112454)
		(end 414.30194 -415.175446)
		(width 0.14732)
		(layer "In6.Cu")
		(net "P5E_CPU0_PE3_TX_C_DP<1>")
	)
	(segment
		(start 416.21456 -410.333698)
		(end 416.21456 -410.87548)
		(width 0.14732)
		(layer "In6.Cu")
		(net "P5E_CPU0_PE3_TX_C_DP<1>")
	)
	(segment
		(start 373.63273 -410.030168)
		(end 373.331232 -409.72867)
		(width 0.13208)
		(layer "F.Cu")
		(net "P5E_CPU0_PE3_TX_C_DP<15>")
	)
	(segment
		(start 373.331232 -409.72867)
		(end 373.331232 -409.110942)
		(width 0.13208)
		(layer "F.Cu")
		(net "P5E_CPU0_PE3_TX_C_DP<15>")
	)
	(segment
		(start 373.331232 -409.110942)
		(end 373.65813 -408.784044)
		(width 0.13208)
		(layer "F.Cu")
		(net "P5E_CPU0_PE3_TX_C_DP<15>")
	)
	(segment
		(start 373.866918 -413.620458)
		(end 374.015508 -413.95777)
		(width 0.14732)
		(layer "In6.Cu")
		(net "P5E_CPU0_PE3_TX_C_DP<15>")
	)
	(segment
		(start 380.81585 -429.754538)
		(end 381.214122 -430.15281)
		(width 0.14732)
		(layer "In6.Cu")
		(net "P5E_CPU0_PE3_TX_C_DP<15>")
	)
	(segment
		(start 375.256806 -416.775392)
		(end 375.182638 -416.9664)
		(width 0.14732)
		(layer "In6.Cu")
		(net "P5E_CPU0_PE3_TX_C_DP<15>")
	)
	(segment
		(start 374.69445 -415.498788)
		(end 374.84304 -415.8361)
		(width 0.14732)
		(layer "In6.Cu")
		(net "P5E_CPU0_PE3_TX_C_DP<15>")
	)
	(segment
		(start 373.33809 -410.324808)
		(end 373.33809 -412.779464)
		(width 0.14732)
		(layer "In6.Cu")
		(net "P5E_CPU0_PE3_TX_C_DP<15>")
	)
	(segment
		(start 373.63273 -410.030168)
		(end 373.33809 -410.324808)
		(width 0.14732)
		(layer "In6.Cu")
		(net "P5E_CPU0_PE3_TX_C_DP<15>")
	)
	(segment
		(start 381.750062 -429.941228)
		(end 381.750062 -429.689768)
		(width 0.14732)
		(layer "In6.Cu")
		(net "P5E_CPU0_PE3_TX_C_DP<15>")
	)
	(segment
		(start 374.089676 -414.485328)
		(end 374.280684 -414.559496)
		(width 0.14732)
		(layer "In6.Cu")
		(net "P5E_CPU0_PE3_TX_C_DP<15>")
	)
	(segment
		(start 375.182638 -416.9664)
		(end 380.81585 -429.754538)
		(width 0.14732)
		(layer "In6.Cu")
		(net "P5E_CPU0_PE3_TX_C_DP<15>")
	)
	(segment
		(start 373.94134 -414.148524)
		(end 374.089676 -414.485328)
		(width 0.14732)
		(layer "In6.Cu")
		(net "P5E_CPU0_PE3_TX_C_DP<15>")
	)
	(segment
		(start 374.84304 -415.8361)
		(end 374.768872 -416.027108)
		(width 0.14732)
		(layer "In6.Cu")
		(net "P5E_CPU0_PE3_TX_C_DP<15>")
	)
	(segment
		(start 374.355106 -415.087816)
		(end 374.503442 -415.42462)
		(width 0.14732)
		(layer "In6.Cu")
		(net "P5E_CPU0_PE3_TX_C_DP<15>")
	)
	(segment
		(start 381.214122 -430.15281)
		(end 381.53848 -430.15281)
		(width 0.14732)
		(layer "In6.Cu")
		(net "P5E_CPU0_PE3_TX_C_DP<15>")
	)
	(segment
		(start 373.33809 -412.779464)
		(end 373.67591 -413.54629)
		(width 0.14732)
		(layer "In6.Cu")
		(net "P5E_CPU0_PE3_TX_C_DP<15>")
	)
	(segment
		(start 373.67591 -413.54629)
		(end 373.866918 -413.620458)
		(width 0.14732)
		(layer "In6.Cu")
		(net "P5E_CPU0_PE3_TX_C_DP<15>")
	)
	(segment
		(start 374.503442 -415.42462)
		(end 374.69445 -415.498788)
		(width 0.14732)
		(layer "In6.Cu")
		(net "P5E_CPU0_PE3_TX_C_DP<15>")
	)
	(segment
		(start 374.280684 -414.559496)
		(end 374.429274 -414.896808)
		(width 0.14732)
		(layer "In6.Cu")
		(net "P5E_CPU0_PE3_TX_C_DP<15>")
	)
	(segment
		(start 374.917208 -416.363912)
		(end 375.108216 -416.43808)
		(width 0.14732)
		(layer "In6.Cu")
		(net "P5E_CPU0_PE3_TX_C_DP<15>")
	)
	(segment
		(start 375.108216 -416.43808)
		(end 375.256806 -416.775392)
		(width 0.14732)
		(layer "In6.Cu")
		(net "P5E_CPU0_PE3_TX_C_DP<15>")
	)
	(segment
		(start 381.53848 -430.15281)
		(end 381.750062 -429.941228)
		(width 0.14732)
		(layer "In6.Cu")
		(net "P5E_CPU0_PE3_TX_C_DP<15>")
	)
	(segment
		(start 374.768872 -416.027108)
		(end 374.917208 -416.363912)
		(width 0.14732)
		(layer "In6.Cu")
		(net "P5E_CPU0_PE3_TX_C_DP<15>")
	)
	(segment
		(start 374.429274 -414.896808)
		(end 374.355106 -415.087816)
		(width 0.14732)
		(layer "In6.Cu")
		(net "P5E_CPU0_PE3_TX_C_DP<15>")
	)
	(segment
		(start 374.015508 -413.95777)
		(end 373.94134 -414.148524)
		(width 0.14732)
		(layer "In6.Cu")
		(net "P5E_CPU0_PE3_TX_C_DP<15>")
	)
	(segment
		(start 376.394472 -409.72867)
		(end 376.394472 -409.110942)
		(width 0.13208)
		(layer "F.Cu")
		(net "P5E_CPU0_PE3_TX_C_DP<14>")
	)
	(segment
		(start 376.394472 -409.110942)
		(end 376.72137 -408.784044)
		(width 0.13208)
		(layer "F.Cu")
		(net "P5E_CPU0_PE3_TX_C_DP<14>")
	)
	(segment
		(start 376.69597 -410.030168)
		(end 376.394472 -409.72867)
		(width 0.13208)
		(layer "F.Cu")
		(net "P5E_CPU0_PE3_TX_C_DP<14>")
	)
	(segment
		(start 377.214892 -412.504382)
		(end 377.377706 -412.83509)
		(width 0.14732)
		(layer "In6.Cu")
		(net "P5E_CPU0_PE3_TX_C_DP<14>")
	)
	(segment
		(start 383.538476 -431.152808)
		(end 383.750058 -430.941226)
		(width 0.14732)
		(layer "In6.Cu")
		(net "P5E_CPU0_PE3_TX_C_DP<14>")
	)
	(segment
		(start 377.31192 -413.028892)
		(end 377.474734 -413.359092)
		(width 0.14732)
		(layer "In6.Cu")
		(net "P5E_CPU0_PE3_TX_C_DP<14>")
	)
	(segment
		(start 377.66879 -413.424878)
		(end 377.831604 -413.755586)
		(width 0.14732)
		(layer "In6.Cu")
		(net "P5E_CPU0_PE3_TX_C_DP<14>")
	)
	(segment
		(start 376.40133 -410.324808)
		(end 376.40133 -411.182566)
		(width 0.14732)
		(layer "In6.Cu")
		(net "P5E_CPU0_PE3_TX_C_DP<14>")
	)
	(segment
		(start 376.40133 -411.182566)
		(end 377.020836 -412.438596)
		(width 0.14732)
		(layer "In6.Cu")
		(net "P5E_CPU0_PE3_TX_C_DP<14>")
	)
	(segment
		(start 377.020836 -412.438596)
		(end 377.214892 -412.504382)
		(width 0.14732)
		(layer "In6.Cu")
		(net "P5E_CPU0_PE3_TX_C_DP<14>")
	)
	(segment
		(start 377.474734 -413.359092)
		(end 377.66879 -413.424878)
		(width 0.14732)
		(layer "In6.Cu")
		(net "P5E_CPU0_PE3_TX_C_DP<14>")
	)
	(segment
		(start 377.765818 -413.949388)
		(end 383.066798 -424.701716)
		(width 0.14732)
		(layer "In6.Cu")
		(net "P5E_CPU0_PE3_TX_C_DP<14>")
	)
	(segment
		(start 377.831604 -413.755586)
		(end 377.765818 -413.949388)
		(width 0.14732)
		(layer "In6.Cu")
		(net "P5E_CPU0_PE3_TX_C_DP<14>")
	)
	(segment
		(start 383.066798 -424.701716)
		(end 383.066798 -431.051208)
		(width 0.14732)
		(layer "In6.Cu")
		(net "P5E_CPU0_PE3_TX_C_DP<14>")
	)
	(segment
		(start 383.066798 -431.051208)
		(end 383.168398 -431.152808)
		(width 0.14732)
		(layer "In6.Cu")
		(net "P5E_CPU0_PE3_TX_C_DP<14>")
	)
	(segment
		(start 383.168398 -431.152808)
		(end 383.538476 -431.152808)
		(width 0.14732)
		(layer "In6.Cu")
		(net "P5E_CPU0_PE3_TX_C_DP<14>")
	)
	(segment
		(start 376.69597 -410.030168)
		(end 376.40133 -410.324808)
		(width 0.14732)
		(layer "In6.Cu")
		(net "P5E_CPU0_PE3_TX_C_DP<14>")
	)
	(segment
		(start 383.750058 -430.941226)
		(end 383.750058 -430.689766)
		(width 0.14732)
		(layer "In6.Cu")
		(net "P5E_CPU0_PE3_TX_C_DP<14>")
	)
	(segment
		(start 377.377706 -412.83509)
		(end 377.31192 -413.028892)
		(width 0.14732)
		(layer "In6.Cu")
		(net "P5E_CPU0_PE3_TX_C_DP<14>")
	)
	(segment
		(start 379.75921 -410.030168)
		(end 379.457712 -409.72867)
		(width 0.13208)
		(layer "F.Cu")
		(net "P5E_CPU0_PE3_TX_C_DP<13>")
	)
	(segment
		(start 379.457712 -409.110942)
		(end 379.78461 -408.784044)
		(width 0.13208)
		(layer "F.Cu")
		(net "P5E_CPU0_PE3_TX_C_DP<13>")
	)
	(segment
		(start 379.457712 -409.72867)
		(end 379.457712 -409.110942)
		(width 0.13208)
		(layer "F.Cu")
		(net "P5E_CPU0_PE3_TX_C_DP<13>")
	)
	(segment
		(start 381.121158 -415.126678)
		(end 381.28448 -415.192972)
		(width 0.14732)
		(layer "In6.Cu")
		(net "P5E_CPU0_PE3_TX_C_DP<13>")
	)
	(segment
		(start 380.591314 -413.500062)
		(end 380.514352 -413.690054)
		(width 0.14732)
		(layer "In6.Cu")
		(net "P5E_CPU0_PE3_TX_C_DP<13>")
	)
	(segment
		(start 380.11481 -412.744412)
		(end 380.258066 -413.083502)
		(width 0.14732)
		(layer "In6.Cu")
		(net "P5E_CPU0_PE3_TX_C_DP<13>")
	)
	(segment
		(start 381.28448 -415.192972)
		(end 381.454406 -415.595562)
		(width 0.14732)
		(layer "In6.Cu")
		(net "P5E_CPU0_PE3_TX_C_DP<13>")
	)
	(segment
		(start 380.191772 -412.554928)
		(end 380.11481 -412.744412)
		(width 0.14732)
		(layer "In6.Cu")
		(net "P5E_CPU0_PE3_TX_C_DP<13>")
	)
	(segment
		(start 380.684278 -414.09239)
		(end 380.8476 -414.158684)
		(width 0.14732)
		(layer "In6.Cu")
		(net "P5E_CPU0_PE3_TX_C_DP<13>")
	)
	(segment
		(start 380.951232 -414.724342)
		(end 381.121158 -415.126678)
		(width 0.14732)
		(layer "In6.Cu")
		(net "P5E_CPU0_PE3_TX_C_DP<13>")
	)
	(segment
		(start 385.529074 -430.162208)
		(end 385.750054 -429.941228)
		(width 0.14732)
		(layer "In6.Cu")
		(net "P5E_CPU0_PE3_TX_C_DP<13>")
	)
	(segment
		(start 379.46457 -410.324808)
		(end 379.46457 -411.205426)
		(width 0.14732)
		(layer "In6.Cu")
		(net "P5E_CPU0_PE3_TX_C_DP<13>")
	)
	(segment
		(start 385.066794 -424.467782)
		(end 385.066794 -430.00549)
		(width 0.14732)
		(layer "In6.Cu")
		(net "P5E_CPU0_PE3_TX_C_DP<13>")
	)
	(segment
		(start 381.454406 -415.595562)
		(end 381.388112 -415.75863)
		(width 0.14732)
		(layer "In6.Cu")
		(net "P5E_CPU0_PE3_TX_C_DP<13>")
	)
	(segment
		(start 380.258066 -413.083502)
		(end 380.448058 -413.160718)
		(width 0.14732)
		(layer "In6.Cu")
		(net "P5E_CPU0_PE3_TX_C_DP<13>")
	)
	(segment
		(start 379.46457 -411.205426)
		(end 379.858778 -412.138368)
		(width 0.14732)
		(layer "In6.Cu")
		(net "P5E_CPU0_PE3_TX_C_DP<13>")
	)
	(segment
		(start 381.388112 -415.75863)
		(end 385.066794 -424.467782)
		(width 0.14732)
		(layer "In6.Cu")
		(net "P5E_CPU0_PE3_TX_C_DP<13>")
	)
	(segment
		(start 380.514352 -413.690054)
		(end 380.684278 -414.09239)
		(width 0.14732)
		(layer "In6.Cu")
		(net "P5E_CPU0_PE3_TX_C_DP<13>")
	)
	(segment
		(start 381.017526 -414.561274)
		(end 380.951232 -414.724342)
		(width 0.14732)
		(layer "In6.Cu")
		(net "P5E_CPU0_PE3_TX_C_DP<13>")
	)
	(segment
		(start 385.223512 -430.162208)
		(end 385.529074 -430.162208)
		(width 0.14732)
		(layer "In6.Cu")
		(net "P5E_CPU0_PE3_TX_C_DP<13>")
	)
	(segment
		(start 379.75921 -410.030168)
		(end 379.46457 -410.324808)
		(width 0.14732)
		(layer "In6.Cu")
		(net "P5E_CPU0_PE3_TX_C_DP<13>")
	)
	(segment
		(start 379.858778 -412.138368)
		(end 380.048516 -412.21533)
		(width 0.14732)
		(layer "In6.Cu")
		(net "P5E_CPU0_PE3_TX_C_DP<13>")
	)
	(segment
		(start 380.8476 -414.158684)
		(end 381.017526 -414.561274)
		(width 0.14732)
		(layer "In6.Cu")
		(net "P5E_CPU0_PE3_TX_C_DP<13>")
	)
	(segment
		(start 380.448058 -413.160718)
		(end 380.591314 -413.500062)
		(width 0.14732)
		(layer "In6.Cu")
		(net "P5E_CPU0_PE3_TX_C_DP<13>")
	)
	(segment
		(start 380.048516 -412.21533)
		(end 380.191772 -412.554928)
		(width 0.14732)
		(layer "In6.Cu")
		(net "P5E_CPU0_PE3_TX_C_DP<13>")
	)
	(segment
		(start 385.750054 -429.941228)
		(end 385.750054 -429.689768)
		(width 0.14732)
		(layer "In6.Cu")
		(net "P5E_CPU0_PE3_TX_C_DP<13>")
	)
	(segment
		(start 385.066794 -430.00549)
		(end 385.223512 -430.162208)
		(width 0.14732)
		(layer "In6.Cu")
		(net "P5E_CPU0_PE3_TX_C_DP<13>")
	)
	(segment
		(start 382.520952 -409.72867)
		(end 382.520952 -409.110942)
		(width 0.13208)
		(layer "F.Cu")
		(net "P5E_CPU0_PE3_TX_C_DP<12>")
	)
	(segment
		(start 382.82245 -410.030168)
		(end 382.520952 -409.72867)
		(width 0.13208)
		(layer "F.Cu")
		(net "P5E_CPU0_PE3_TX_C_DP<12>")
	)
	(segment
		(start 382.520952 -409.110942)
		(end 382.84785 -408.784044)
		(width 0.13208)
		(layer "F.Cu")
		(net "P5E_CPU0_PE3_TX_C_DP<12>")
	)
	(segment
		(start 383.595372 -414.47974)
		(end 383.595626 -414.479486)
		(width 0.14732)
		(layer "In6.Cu")
		(net "P5E_CPU0_PE3_TX_C_DP<12>")
	)
	(segment
		(start 387.75005 -430.941226)
		(end 387.75005 -430.689766)
		(width 0.14732)
		(layer "In6.Cu")
		(net "P5E_CPU0_PE3_TX_C_DP<12>")
	)
	(segment
		(start 384.033776 -415.38525)
		(end 383.955798 -415.542984)
		(width 0.14732)
		(layer "In6.Cu")
		(net "P5E_CPU0_PE3_TX_C_DP<12>")
	)
	(segment
		(start 387.06679 -430.9872)
		(end 387.224778 -431.145188)
		(width 0.14732)
		(layer "In6.Cu")
		(net "P5E_CPU0_PE3_TX_C_DP<12>")
	)
	(segment
		(start 382.82245 -410.030168)
		(end 382.52781 -410.324808)
		(width 0.14732)
		(layer "In6.Cu")
		(net "P5E_CPU0_PE3_TX_C_DP<12>")
	)
	(segment
		(start 383.893568 -414.97123)
		(end 384.033776 -415.38525)
		(width 0.14732)
		(layer "In6.Cu")
		(net "P5E_CPU0_PE3_TX_C_DP<12>")
	)
	(segment
		(start 383.533396 -413.907732)
		(end 383.67335 -414.322006)
		(width 0.14732)
		(layer "In6.Cu")
		(net "P5E_CPU0_PE3_TX_C_DP<12>")
	)
	(segment
		(start 387.06679 -424.70324)
		(end 387.06679 -430.9872)
		(width 0.14732)
		(layer "In6.Cu")
		(net "P5E_CPU0_PE3_TX_C_DP<12>")
	)
	(segment
		(start 383.375408 -413.830008)
		(end 383.533396 -413.907732)
		(width 0.14732)
		(layer "In6.Cu")
		(net "P5E_CPU0_PE3_TX_C_DP<12>")
	)
	(segment
		(start 382.52781 -411.326584)
		(end 383.015236 -412.766256)
		(width 0.14732)
		(layer "In6.Cu")
		(net "P5E_CPU0_PE3_TX_C_DP<12>")
	)
	(segment
		(start 383.955544 -415.543238)
		(end 387.052312 -424.688762)
		(width 0.14732)
		(layer "In6.Cu")
		(net "P5E_CPU0_PE3_TX_C_DP<12>")
	)
	(segment
		(start 387.052312 -424.688762)
		(end 387.06679 -424.70324)
		(width 0.14732)
		(layer "In6.Cu")
		(net "P5E_CPU0_PE3_TX_C_DP<12>")
	)
	(segment
		(start 383.235454 -413.415988)
		(end 383.375408 -413.830008)
		(width 0.14732)
		(layer "In6.Cu")
		(net "P5E_CPU0_PE3_TX_C_DP<12>")
	)
	(segment
		(start 383.955798 -415.542984)
		(end 383.955544 -415.543238)
		(width 0.14732)
		(layer "In6.Cu")
		(net "P5E_CPU0_PE3_TX_C_DP<12>")
	)
	(segment
		(start 387.546088 -431.145188)
		(end 387.75005 -430.941226)
		(width 0.14732)
		(layer "In6.Cu")
		(net "P5E_CPU0_PE3_TX_C_DP<12>")
	)
	(segment
		(start 387.224778 -431.145188)
		(end 387.546088 -431.145188)
		(width 0.14732)
		(layer "In6.Cu")
		(net "P5E_CPU0_PE3_TX_C_DP<12>")
	)
	(segment
		(start 383.73558 -414.893252)
		(end 383.893568 -414.97123)
		(width 0.14732)
		(layer "In6.Cu")
		(net "P5E_CPU0_PE3_TX_C_DP<12>")
	)
	(segment
		(start 383.015236 -412.766256)
		(end 383.173224 -412.844234)
		(width 0.14732)
		(layer "In6.Cu")
		(net "P5E_CPU0_PE3_TX_C_DP<12>")
	)
	(segment
		(start 383.67335 -414.322006)
		(end 383.595372 -414.47974)
		(width 0.14732)
		(layer "In6.Cu")
		(net "P5E_CPU0_PE3_TX_C_DP<12>")
	)
	(segment
		(start 383.173224 -412.844234)
		(end 383.313432 -413.258254)
		(width 0.14732)
		(layer "In6.Cu")
		(net "P5E_CPU0_PE3_TX_C_DP<12>")
	)
	(segment
		(start 383.595626 -414.479486)
		(end 383.73558 -414.893252)
		(width 0.14732)
		(layer "In6.Cu")
		(net "P5E_CPU0_PE3_TX_C_DP<12>")
	)
	(segment
		(start 382.52781 -410.324808)
		(end 382.52781 -411.326584)
		(width 0.14732)
		(layer "In6.Cu")
		(net "P5E_CPU0_PE3_TX_C_DP<12>")
	)
	(segment
		(start 383.313432 -413.258254)
		(end 383.235454 -413.415988)
		(width 0.14732)
		(layer "In6.Cu")
		(net "P5E_CPU0_PE3_TX_C_DP<12>")
	)
	(segment
		(start 385.584192 -409.110942)
		(end 385.91109 -408.784044)
		(width 0.13208)
		(layer "F.Cu")
		(net "P5E_CPU0_PE3_TX_C_DP<11>")
	)
	(segment
		(start 385.88569 -410.030168)
		(end 385.584192 -409.72867)
		(width 0.13208)
		(layer "F.Cu")
		(net "P5E_CPU0_PE3_TX_C_DP<11>")
	)
	(segment
		(start 385.584192 -409.72867)
		(end 385.584192 -409.110942)
		(width 0.13208)
		(layer "F.Cu")
		(net "P5E_CPU0_PE3_TX_C_DP<11>")
	)
	(segment
		(start 386.340858 -414.551622)
		(end 386.4356 -414.907222)
		(width 0.14732)
		(layer "In6.Cu")
		(net "P5E_CPU0_PE3_TX_C_DP<11>")
	)
	(segment
		(start 385.59105 -410.324808)
		(end 385.59105 -411.742382)
		(width 0.14732)
		(layer "In6.Cu")
		(net "P5E_CPU0_PE3_TX_C_DP<11>")
	)
	(segment
		(start 386.870194 -416.534854)
		(end 389.067548 -424.770296)
		(width 0.14732)
		(layer "In6.Cu")
		(net "P5E_CPU0_PE3_TX_C_DP<11>")
	)
	(segment
		(start 386.708142 -415.365946)
		(end 386.605526 -415.543238)
		(width 0.14732)
		(layer "In6.Cu")
		(net "P5E_CPU0_PE3_TX_C_DP<11>")
	)
	(segment
		(start 386.4356 -414.907222)
		(end 386.613146 -415.009838)
		(width 0.14732)
		(layer "In6.Cu")
		(net "P5E_CPU0_PE3_TX_C_DP<11>")
	)
	(segment
		(start 389.538464 -430.15281)
		(end 389.750046 -429.941228)
		(width 0.14732)
		(layer "In6.Cu")
		(net "P5E_CPU0_PE3_TX_C_DP<11>")
	)
	(segment
		(start 385.88569 -410.030168)
		(end 385.59105 -410.324808)
		(width 0.14732)
		(layer "In6.Cu")
		(net "P5E_CPU0_PE3_TX_C_DP<11>")
	)
	(segment
		(start 386.700268 -415.898838)
		(end 386.877814 -416.001454)
		(width 0.14732)
		(layer "In6.Cu")
		(net "P5E_CPU0_PE3_TX_C_DP<11>")
	)
	(segment
		(start 386.443474 -414.37433)
		(end 386.340858 -414.551622)
		(width 0.14732)
		(layer "In6.Cu")
		(net "P5E_CPU0_PE3_TX_C_DP<11>")
	)
	(segment
		(start 386.07619 -413.560006)
		(end 386.170932 -413.915606)
		(width 0.14732)
		(layer "In6.Cu")
		(net "P5E_CPU0_PE3_TX_C_DP<11>")
	)
	(segment
		(start 386.877814 -416.001454)
		(end 386.97281 -416.357562)
		(width 0.14732)
		(layer "In6.Cu")
		(net "P5E_CPU0_PE3_TX_C_DP<11>")
	)
	(segment
		(start 389.750046 -429.941228)
		(end 389.750046 -429.689768)
		(width 0.14732)
		(layer "In6.Cu")
		(net "P5E_CPU0_PE3_TX_C_DP<11>")
	)
	(segment
		(start 389.214106 -430.15281)
		(end 389.538464 -430.15281)
		(width 0.14732)
		(layer "In6.Cu")
		(net "P5E_CPU0_PE3_TX_C_DP<11>")
	)
	(segment
		(start 386.613146 -415.009838)
		(end 386.708142 -415.365946)
		(width 0.14732)
		(layer "In6.Cu")
		(net "P5E_CPU0_PE3_TX_C_DP<11>")
	)
	(segment
		(start 386.08381 -413.026606)
		(end 386.178806 -413.382714)
		(width 0.14732)
		(layer "In6.Cu")
		(net "P5E_CPU0_PE3_TX_C_DP<11>")
	)
	(segment
		(start 386.178806 -413.382714)
		(end 386.07619 -413.560006)
		(width 0.14732)
		(layer "In6.Cu")
		(net "P5E_CPU0_PE3_TX_C_DP<11>")
	)
	(segment
		(start 386.348478 -414.018222)
		(end 386.443474 -414.37433)
		(width 0.14732)
		(layer "In6.Cu")
		(net "P5E_CPU0_PE3_TX_C_DP<11>")
	)
	(segment
		(start 385.906518 -412.924244)
		(end 386.08381 -413.026606)
		(width 0.14732)
		(layer "In6.Cu")
		(net "P5E_CPU0_PE3_TX_C_DP<11>")
	)
	(segment
		(start 389.067548 -430.006252)
		(end 389.214106 -430.15281)
		(width 0.14732)
		(layer "In6.Cu")
		(net "P5E_CPU0_PE3_TX_C_DP<11>")
	)
	(segment
		(start 385.59105 -411.742382)
		(end 385.906518 -412.924244)
		(width 0.14732)
		(layer "In6.Cu")
		(net "P5E_CPU0_PE3_TX_C_DP<11>")
	)
	(segment
		(start 386.605526 -415.543238)
		(end 386.700268 -415.898838)
		(width 0.14732)
		(layer "In6.Cu")
		(net "P5E_CPU0_PE3_TX_C_DP<11>")
	)
	(segment
		(start 386.170932 -413.915606)
		(end 386.348478 -414.018222)
		(width 0.14732)
		(layer "In6.Cu")
		(net "P5E_CPU0_PE3_TX_C_DP<11>")
	)
	(segment
		(start 389.067548 -424.770296)
		(end 389.067548 -430.006252)
		(width 0.14732)
		(layer "In6.Cu")
		(net "P5E_CPU0_PE3_TX_C_DP<11>")
	)
	(segment
		(start 386.97281 -416.357562)
		(end 386.870194 -416.534854)
		(width 0.14732)
		(layer "In6.Cu")
		(net "P5E_CPU0_PE3_TX_C_DP<11>")
	)
	(segment
		(start 388.94893 -410.030168)
		(end 388.647432 -409.72867)
		(width 0.13208)
		(layer "F.Cu")
		(net "P5E_CPU0_PE3_TX_C_DP<10>")
	)
	(segment
		(start 388.647432 -409.110942)
		(end 388.97433 -408.784044)
		(width 0.13208)
		(layer "F.Cu")
		(net "P5E_CPU0_PE3_TX_C_DP<10>")
	)
	(segment
		(start 388.647432 -409.72867)
		(end 388.647432 -409.110942)
		(width 0.13208)
		(layer "F.Cu")
		(net "P5E_CPU0_PE3_TX_C_DP<10>")
	)
	(segment
		(start 389.067802 -413.069278)
		(end 389.135366 -413.431736)
		(width 0.14732)
		(layer "In6.Cu")
		(net "P5E_CPU0_PE3_TX_C_DP<10>")
	)
	(segment
		(start 388.709916 -411.94482)
		(end 388.87908 -412.060644)
		(width 0.14732)
		(layer "In6.Cu")
		(net "P5E_CPU0_PE3_TX_C_DP<10>")
	)
	(segment
		(start 388.65429 -410.324808)
		(end 388.65429 -411.646878)
		(width 0.14732)
		(layer "In6.Cu")
		(net "P5E_CPU0_PE3_TX_C_DP<10>")
	)
	(segment
		(start 391.750042 -430.941226)
		(end 391.750042 -430.689766)
		(width 0.14732)
		(layer "In6.Cu")
		(net "P5E_CPU0_PE3_TX_C_DP<10>")
	)
	(segment
		(start 391.066782 -431.024792)
		(end 391.194798 -431.152808)
		(width 0.14732)
		(layer "In6.Cu")
		(net "P5E_CPU0_PE3_TX_C_DP<10>")
	)
	(segment
		(start 389.019542 -413.600646)
		(end 391.066782 -424.557698)
		(width 0.14732)
		(layer "In6.Cu")
		(net "P5E_CPU0_PE3_TX_C_DP<10>")
	)
	(segment
		(start 391.066782 -424.557698)
		(end 391.066782 -431.024792)
		(width 0.14732)
		(layer "In6.Cu")
		(net "P5E_CPU0_PE3_TX_C_DP<10>")
	)
	(segment
		(start 388.94893 -410.030168)
		(end 388.65429 -410.324808)
		(width 0.14732)
		(layer "In6.Cu")
		(net "P5E_CPU0_PE3_TX_C_DP<10>")
	)
	(segment
		(start 391.194798 -431.152808)
		(end 391.53846 -431.152808)
		(width 0.14732)
		(layer "In6.Cu")
		(net "P5E_CPU0_PE3_TX_C_DP<10>")
	)
	(segment
		(start 388.87908 -412.060644)
		(end 388.946644 -412.422848)
		(width 0.14732)
		(layer "In6.Cu")
		(net "P5E_CPU0_PE3_TX_C_DP<10>")
	)
	(segment
		(start 388.831074 -412.591758)
		(end 388.898638 -412.953708)
		(width 0.14732)
		(layer "In6.Cu")
		(net "P5E_CPU0_PE3_TX_C_DP<10>")
	)
	(segment
		(start 389.135366 -413.431736)
		(end 389.019542 -413.600646)
		(width 0.14732)
		(layer "In6.Cu")
		(net "P5E_CPU0_PE3_TX_C_DP<10>")
	)
	(segment
		(start 388.898638 -412.953708)
		(end 389.067802 -413.069278)
		(width 0.14732)
		(layer "In6.Cu")
		(net "P5E_CPU0_PE3_TX_C_DP<10>")
	)
	(segment
		(start 388.946644 -412.422848)
		(end 388.831074 -412.591758)
		(width 0.14732)
		(layer "In6.Cu")
		(net "P5E_CPU0_PE3_TX_C_DP<10>")
	)
	(segment
		(start 391.53846 -431.152808)
		(end 391.750042 -430.941226)
		(width 0.14732)
		(layer "In6.Cu")
		(net "P5E_CPU0_PE3_TX_C_DP<10>")
	)
	(segment
		(start 388.65429 -411.646878)
		(end 388.709916 -411.94482)
		(width 0.14732)
		(layer "In6.Cu")
		(net "P5E_CPU0_PE3_TX_C_DP<10>")
	)
	(segment
		(start 419.020752 -409.109164)
		(end 418.695632 -408.784044)
		(width 0.13208)
		(layer "F.Cu")
		(net "P5E_CPU0_PE3_TX_C_DP<0>")
	)
	(segment
		(start 418.695632 -408.784044)
		(end 418.69233 -408.784044)
		(width 0.13208)
		(layer "F.Cu")
		(net "P5E_CPU0_PE3_TX_C_DP<0>")
	)
	(segment
		(start 419.020752 -409.727146)
		(end 419.020752 -409.109164)
		(width 0.13208)
		(layer "F.Cu")
		(net "P5E_CPU0_PE3_TX_C_DP<0>")
	)
	(segment
		(start 418.71773 -410.030168)
		(end 419.020752 -409.727146)
		(width 0.13208)
		(layer "F.Cu")
		(net "P5E_CPU0_PE3_TX_C_DP<0>")
	)
	(segment
		(start 411.79242 -431.11928)
		(end 411.79242 -424.236896)
		(width 0.14732)
		(layer "In6.Cu")
		(net "P5E_CPU0_PE3_TX_C_DP<0>")
	)
	(segment
		(start 412.75 -431.574702)
		(end 412.602426 -431.427128)
		(width 0.14732)
		(layer "In6.Cu")
		(net "P5E_CPU0_PE3_TX_C_DP<0>")
	)
	(segment
		(start 411.79242 -424.236896)
		(end 419.00348 -410.898086)
		(width 0.14732)
		(layer "In6.Cu")
		(net "P5E_CPU0_PE3_TX_C_DP<0>")
	)
	(segment
		(start 419.00348 -410.898086)
		(end 419.00348 -410.315918)
		(width 0.14732)
		(layer "In6.Cu")
		(net "P5E_CPU0_PE3_TX_C_DP<0>")
	)
	(segment
		(start 412.75 -431.889916)
		(end 412.75 -431.574702)
		(width 0.14732)
		(layer "In6.Cu")
		(net "P5E_CPU0_PE3_TX_C_DP<0>")
	)
	(segment
		(start 412.602426 -431.427128)
		(end 412.100268 -431.427128)
		(width 0.14732)
		(layer "In6.Cu")
		(net "P5E_CPU0_PE3_TX_C_DP<0>")
	)
	(segment
		(start 419.00348 -410.315918)
		(end 418.71773 -410.030168)
		(width 0.14732)
		(layer "In6.Cu")
		(net "P5E_CPU0_PE3_TX_C_DP<0>")
	)
	(segment
		(start 412.100268 -431.427128)
		(end 411.79242 -431.11928)
		(width 0.14732)
		(layer "In6.Cu")
		(net "P5E_CPU0_PE3_TX_C_DP<0>")
	)
	(segment
		(start 391.451592 -409.727146)
		(end 391.451592 -409.109164)
		(width 0.13208)
		(layer "F.Cu")
		(net "P5E_CPU0_PE3_TX_C_DN<9>")
	)
	(segment
		(start 391.451592 -409.109164)
		(end 391.126472 -408.784044)
		(width 0.13208)
		(layer "F.Cu")
		(net "P5E_CPU0_PE3_TX_C_DN<9>")
	)
	(segment
		(start 391.14857 -410.030168)
		(end 391.451592 -409.727146)
		(width 0.13208)
		(layer "F.Cu")
		(net "P5E_CPU0_PE3_TX_C_DN<9>")
	)
	(segment
		(start 391.126472 -408.784044)
		(end 391.12317 -408.784044)
		(width 0.13208)
		(layer "F.Cu")
		(net "P5E_CPU0_PE3_TX_C_DN<9>")
	)
	(segment
		(start 393.611862 -430.436528)
		(end 393.109704 -430.436528)
		(width 0.14732)
		(layer "In6.Cu")
		(net "P5E_CPU0_PE3_TX_C_DN<9>")
	)
	(segment
		(start 393.750038 -430.889918)
		(end 393.750038 -430.574704)
		(width 0.14732)
		(layer "In6.Cu")
		(net "P5E_CPU0_PE3_TX_C_DN<9>")
	)
	(segment
		(start 393.109704 -430.436528)
		(end 392.792458 -430.119282)
		(width 0.14732)
		(layer "In6.Cu")
		(net "P5E_CPU0_PE3_TX_C_DN<9>")
	)
	(segment
		(start 392.792458 -430.119282)
		(end 392.792458 -424.645328)
		(width 0.14732)
		(layer "In6.Cu")
		(net "P5E_CPU0_PE3_TX_C_DN<9>")
	)
	(segment
		(start 391.44321 -410.324808)
		(end 391.14857 -410.030168)
		(width 0.14732)
		(layer "In6.Cu")
		(net "P5E_CPU0_PE3_TX_C_DN<9>")
	)
	(segment
		(start 391.44321 -412.351728)
		(end 391.44321 -410.324808)
		(width 0.14732)
		(layer "In6.Cu")
		(net "P5E_CPU0_PE3_TX_C_DN<9>")
	)
	(segment
		(start 392.792458 -424.645328)
		(end 391.44321 -412.351728)
		(width 0.14732)
		(layer "In6.Cu")
		(net "P5E_CPU0_PE3_TX_C_DN<9>")
	)
	(segment
		(start 393.750038 -430.574704)
		(end 393.611862 -430.436528)
		(width 0.14732)
		(layer "In6.Cu")
		(net "P5E_CPU0_PE3_TX_C_DN<9>")
	)
	(segment
		(start 394.21181 -410.030168)
		(end 394.514832 -409.727146)
		(width 0.13208)
		(layer "F.Cu")
		(net "P5E_CPU0_PE3_TX_C_DN<8>")
	)
	(segment
		(start 394.514832 -409.109164)
		(end 394.189712 -408.784044)
		(width 0.13208)
		(layer "F.Cu")
		(net "P5E_CPU0_PE3_TX_C_DN<8>")
	)
	(segment
		(start 394.189712 -408.784044)
		(end 394.18641 -408.784044)
		(width 0.13208)
		(layer "F.Cu")
		(net "P5E_CPU0_PE3_TX_C_DN<8>")
	)
	(segment
		(start 394.514832 -409.727146)
		(end 394.514832 -409.109164)
		(width 0.13208)
		(layer "F.Cu")
		(net "P5E_CPU0_PE3_TX_C_DN<8>")
	)
	(segment
		(start 394.49756 -410.315918)
		(end 394.21181 -410.030168)
		(width 0.14732)
		(layer "In6.Cu")
		(net "P5E_CPU0_PE3_TX_C_DN<8>")
	)
	(segment
		(start 394.783564 -424.63974)
		(end 394.49756 -410.873448)
		(width 0.14732)
		(layer "In6.Cu")
		(net "P5E_CPU0_PE3_TX_C_DN<8>")
	)
	(segment
		(start 395.137386 -431.419508)
		(end 394.783564 -431.065686)
		(width 0.14732)
		(layer "In6.Cu")
		(net "P5E_CPU0_PE3_TX_C_DN<8>")
	)
	(segment
		(start 395.750034 -431.889916)
		(end 395.750034 -431.574702)
		(width 0.14732)
		(layer "In6.Cu")
		(net "P5E_CPU0_PE3_TX_C_DN<8>")
	)
	(segment
		(start 395.750034 -431.574702)
		(end 395.59484 -431.419508)
		(width 0.14732)
		(layer "In6.Cu")
		(net "P5E_CPU0_PE3_TX_C_DN<8>")
	)
	(segment
		(start 394.783564 -431.065686)
		(end 394.783564 -424.63974)
		(width 0.14732)
		(layer "In6.Cu")
		(net "P5E_CPU0_PE3_TX_C_DN<8>")
	)
	(segment
		(start 395.59484 -431.419508)
		(end 395.137386 -431.419508)
		(width 0.14732)
		(layer "In6.Cu")
		(net "P5E_CPU0_PE3_TX_C_DN<8>")
	)
	(segment
		(start 394.49756 -410.873448)
		(end 394.49756 -410.315918)
		(width 0.14732)
		(layer "In6.Cu")
		(net "P5E_CPU0_PE3_TX_C_DN<8>")
	)
	(segment
		(start 397.578072 -409.109164)
		(end 397.252952 -408.784044)
		(width 0.13208)
		(layer "F.Cu")
		(net "P5E_CPU0_PE3_TX_C_DN<7>")
	)
	(segment
		(start 397.252952 -408.784044)
		(end 397.24965 -408.784044)
		(width 0.13208)
		(layer "F.Cu")
		(net "P5E_CPU0_PE3_TX_C_DN<7>")
	)
	(segment
		(start 397.27505 -410.030168)
		(end 397.578072 -409.727146)
		(width 0.13208)
		(layer "F.Cu")
		(net "P5E_CPU0_PE3_TX_C_DN<7>")
	)
	(segment
		(start 397.578072 -409.727146)
		(end 397.578072 -409.109164)
		(width 0.13208)
		(layer "F.Cu")
		(net "P5E_CPU0_PE3_TX_C_DN<7>")
	)
	(segment
		(start 397.75765 -424.210734)
		(end 397.5608 -410.83738)
		(width 0.14732)
		(layer "In6.Cu")
		(net "P5E_CPU0_PE3_TX_C_DN<7>")
	)
	(segment
		(start 398.750028 -430.889918)
		(end 398.750028 -430.574704)
		(width 0.14732)
		(layer "In6.Cu")
		(net "P5E_CPU0_PE3_TX_C_DN<7>")
	)
	(segment
		(start 397.5608 -410.315918)
		(end 397.27505 -410.030168)
		(width 0.14732)
		(layer "In6.Cu")
		(net "P5E_CPU0_PE3_TX_C_DN<7>")
	)
	(segment
		(start 397.75765 -430.084484)
		(end 397.75765 -424.210734)
		(width 0.14732)
		(layer "In6.Cu")
		(net "P5E_CPU0_PE3_TX_C_DN<7>")
	)
	(segment
		(start 398.100296 -430.42713)
		(end 397.75765 -430.084484)
		(width 0.14732)
		(layer "In6.Cu")
		(net "P5E_CPU0_PE3_TX_C_DN<7>")
	)
	(segment
		(start 397.5608 -410.83738)
		(end 397.5608 -410.315918)
		(width 0.14732)
		(layer "In6.Cu")
		(net "P5E_CPU0_PE3_TX_C_DN<7>")
	)
	(segment
		(start 398.602454 -430.42713)
		(end 398.100296 -430.42713)
		(width 0.14732)
		(layer "In6.Cu")
		(net "P5E_CPU0_PE3_TX_C_DN<7>")
	)
	(segment
		(start 398.750028 -430.574704)
		(end 398.602454 -430.42713)
		(width 0.14732)
		(layer "In6.Cu")
		(net "P5E_CPU0_PE3_TX_C_DN<7>")
	)
	(segment
		(start 400.33829 -410.030168)
		(end 400.641312 -409.727146)
		(width 0.13208)
		(layer "F.Cu")
		(net "P5E_CPU0_PE3_TX_C_DN<6>")
	)
	(segment
		(start 400.641312 -409.727146)
		(end 400.641312 -409.109164)
		(width 0.13208)
		(layer "F.Cu")
		(net "P5E_CPU0_PE3_TX_C_DN<6>")
	)
	(segment
		(start 400.316192 -408.784044)
		(end 400.31289 -408.784044)
		(width 0.13208)
		(layer "F.Cu")
		(net "P5E_CPU0_PE3_TX_C_DN<6>")
	)
	(segment
		(start 400.641312 -409.109164)
		(end 400.316192 -408.784044)
		(width 0.13208)
		(layer "F.Cu")
		(net "P5E_CPU0_PE3_TX_C_DN<6>")
	)
	(segment
		(start 400.62404 -410.315918)
		(end 400.33829 -410.030168)
		(width 0.14732)
		(layer "In6.Cu")
		(net "P5E_CPU0_PE3_TX_C_DN<6>")
	)
	(segment
		(start 400.750024 -431.889916)
		(end 400.750024 -431.574702)
		(width 0.14732)
		(layer "In6.Cu")
		(net "P5E_CPU0_PE3_TX_C_DN<6>")
	)
	(segment
		(start 400.60245 -431.427128)
		(end 400.12366 -431.427128)
		(width 0.14732)
		(layer "In6.Cu")
		(net "P5E_CPU0_PE3_TX_C_DN<6>")
	)
	(segment
		(start 399.792444 -424.483022)
		(end 400.62404 -410.820362)
		(width 0.14732)
		(layer "In6.Cu")
		(net "P5E_CPU0_PE3_TX_C_DN<6>")
	)
	(segment
		(start 399.792444 -431.095912)
		(end 399.792444 -424.483022)
		(width 0.14732)
		(layer "In6.Cu")
		(net "P5E_CPU0_PE3_TX_C_DN<6>")
	)
	(segment
		(start 400.12366 -431.427128)
		(end 399.792444 -431.095912)
		(width 0.14732)
		(layer "In6.Cu")
		(net "P5E_CPU0_PE3_TX_C_DN<6>")
	)
	(segment
		(start 400.62404 -410.820362)
		(end 400.62404 -410.315918)
		(width 0.14732)
		(layer "In6.Cu")
		(net "P5E_CPU0_PE3_TX_C_DN<6>")
	)
	(segment
		(start 400.750024 -431.574702)
		(end 400.60245 -431.427128)
		(width 0.14732)
		(layer "In6.Cu")
		(net "P5E_CPU0_PE3_TX_C_DN<6>")
	)
	(segment
		(start 403.379432 -408.784044)
		(end 403.37613 -408.784044)
		(width 0.13208)
		(layer "F.Cu")
		(net "P5E_CPU0_PE3_TX_C_DN<5>")
	)
	(segment
		(start 403.40153 -410.030168)
		(end 403.704552 -409.727146)
		(width 0.13208)
		(layer "F.Cu")
		(net "P5E_CPU0_PE3_TX_C_DN<5>")
	)
	(segment
		(start 403.704552 -409.109164)
		(end 403.379432 -408.784044)
		(width 0.13208)
		(layer "F.Cu")
		(net "P5E_CPU0_PE3_TX_C_DN<5>")
	)
	(segment
		(start 403.704552 -409.727146)
		(end 403.704552 -409.109164)
		(width 0.13208)
		(layer "F.Cu")
		(net "P5E_CPU0_PE3_TX_C_DN<5>")
	)
	(segment
		(start 402.112226 -430.439068)
		(end 401.79244 -430.119282)
		(width 0.14732)
		(layer "In6.Cu")
		(net "P5E_CPU0_PE3_TX_C_DN<5>")
	)
	(segment
		(start 402.75002 -430.889918)
		(end 402.75002 -430.574704)
		(width 0.14732)
		(layer "In6.Cu")
		(net "P5E_CPU0_PE3_TX_C_DN<5>")
	)
	(segment
		(start 402.75002 -430.574704)
		(end 402.614384 -430.439068)
		(width 0.14732)
		(layer "In6.Cu")
		(net "P5E_CPU0_PE3_TX_C_DN<5>")
	)
	(segment
		(start 401.79244 -424.763692)
		(end 403.68728 -410.985462)
		(width 0.14732)
		(layer "In6.Cu")
		(net "P5E_CPU0_PE3_TX_C_DN<5>")
	)
	(segment
		(start 403.68728 -410.315918)
		(end 403.40153 -410.030168)
		(width 0.14732)
		(layer "In6.Cu")
		(net "P5E_CPU0_PE3_TX_C_DN<5>")
	)
	(segment
		(start 401.79244 -430.119282)
		(end 401.79244 -424.763692)
		(width 0.14732)
		(layer "In6.Cu")
		(net "P5E_CPU0_PE3_TX_C_DN<5>")
	)
	(segment
		(start 403.68728 -410.985462)
		(end 403.68728 -410.315918)
		(width 0.14732)
		(layer "In6.Cu")
		(net "P5E_CPU0_PE3_TX_C_DN<5>")
	)
	(segment
		(start 402.614384 -430.439068)
		(end 402.112226 -430.439068)
		(width 0.14732)
		(layer "In6.Cu")
		(net "P5E_CPU0_PE3_TX_C_DN<5>")
	)
	(segment
		(start 406.767792 -409.727146)
		(end 406.767792 -409.109164)
		(width 0.13208)
		(layer "F.Cu")
		(net "P5E_CPU0_PE3_TX_C_DN<4>")
	)
	(segment
		(start 406.442672 -408.784044)
		(end 406.43937 -408.784044)
		(width 0.13208)
		(layer "F.Cu")
		(net "P5E_CPU0_PE3_TX_C_DN<4>")
	)
	(segment
		(start 406.767792 -409.109164)
		(end 406.442672 -408.784044)
		(width 0.13208)
		(layer "F.Cu")
		(net "P5E_CPU0_PE3_TX_C_DN<4>")
	)
	(segment
		(start 406.46477 -410.030168)
		(end 406.767792 -409.727146)
		(width 0.13208)
		(layer "F.Cu")
		(net "P5E_CPU0_PE3_TX_C_DN<4>")
	)
	(segment
		(start 404.082504 -431.409348)
		(end 403.792436 -431.11928)
		(width 0.14732)
		(layer "In6.Cu")
		(net "P5E_CPU0_PE3_TX_C_DN<4>")
	)
	(segment
		(start 403.792436 -424.553888)
		(end 406.75052 -410.812996)
		(width 0.14732)
		(layer "In6.Cu")
		(net "P5E_CPU0_PE3_TX_C_DN<4>")
	)
	(segment
		(start 406.75052 -410.315918)
		(end 406.46477 -410.030168)
		(width 0.14732)
		(layer "In6.Cu")
		(net "P5E_CPU0_PE3_TX_C_DN<4>")
	)
	(segment
		(start 406.75052 -410.812996)
		(end 406.75052 -410.315918)
		(width 0.14732)
		(layer "In6.Cu")
		(net "P5E_CPU0_PE3_TX_C_DN<4>")
	)
	(segment
		(start 404.584662 -431.409348)
		(end 404.082504 -431.409348)
		(width 0.14732)
		(layer "In6.Cu")
		(net "P5E_CPU0_PE3_TX_C_DN<4>")
	)
	(segment
		(start 404.750016 -431.574702)
		(end 404.584662 -431.409348)
		(width 0.14732)
		(layer "In6.Cu")
		(net "P5E_CPU0_PE3_TX_C_DN<4>")
	)
	(segment
		(start 404.750016 -431.889916)
		(end 404.750016 -431.574702)
		(width 0.14732)
		(layer "In6.Cu")
		(net "P5E_CPU0_PE3_TX_C_DN<4>")
	)
	(segment
		(start 403.792436 -431.11928)
		(end 403.792436 -424.553888)
		(width 0.14732)
		(layer "In6.Cu")
		(net "P5E_CPU0_PE3_TX_C_DN<4>")
	)
	(segment
		(start 409.831032 -409.109164)
		(end 409.505912 -408.784044)
		(width 0.13208)
		(layer "F.Cu")
		(net "P5E_CPU0_PE3_TX_C_DN<3>")
	)
	(segment
		(start 409.52801 -410.030168)
		(end 409.831032 -409.727146)
		(width 0.13208)
		(layer "F.Cu")
		(net "P5E_CPU0_PE3_TX_C_DN<3>")
	)
	(segment
		(start 409.505912 -408.784044)
		(end 409.50261 -408.784044)
		(width 0.13208)
		(layer "F.Cu")
		(net "P5E_CPU0_PE3_TX_C_DN<3>")
	)
	(segment
		(start 409.831032 -409.727146)
		(end 409.831032 -409.109164)
		(width 0.13208)
		(layer "F.Cu")
		(net "P5E_CPU0_PE3_TX_C_DN<3>")
	)
	(segment
		(start 406.750012 -430.574704)
		(end 406.602438 -430.42713)
		(width 0.14732)
		(layer "In6.Cu")
		(net "P5E_CPU0_PE3_TX_C_DN<3>")
	)
	(segment
		(start 409.81376 -410.315918)
		(end 409.52801 -410.030168)
		(width 0.14732)
		(layer "In6.Cu")
		(net "P5E_CPU0_PE3_TX_C_DN<3>")
	)
	(segment
		(start 405.792432 -424.648376)
		(end 409.81376 -410.812488)
		(width 0.14732)
		(layer "In6.Cu")
		(net "P5E_CPU0_PE3_TX_C_DN<3>")
	)
	(segment
		(start 406.602438 -430.42713)
		(end 406.10028 -430.42713)
		(width 0.14732)
		(layer "In6.Cu")
		(net "P5E_CPU0_PE3_TX_C_DN<3>")
	)
	(segment
		(start 409.81376 -410.812488)
		(end 409.81376 -410.315918)
		(width 0.14732)
		(layer "In6.Cu")
		(net "P5E_CPU0_PE3_TX_C_DN<3>")
	)
	(segment
		(start 405.792432 -430.119282)
		(end 405.792432 -424.648376)
		(width 0.14732)
		(layer "In6.Cu")
		(net "P5E_CPU0_PE3_TX_C_DN<3>")
	)
	(segment
		(start 406.10028 -430.42713)
		(end 405.792432 -430.119282)
		(width 0.14732)
		(layer "In6.Cu")
		(net "P5E_CPU0_PE3_TX_C_DN<3>")
	)
	(segment
		(start 406.750012 -430.889918)
		(end 406.750012 -430.574704)
		(width 0.14732)
		(layer "In6.Cu")
		(net "P5E_CPU0_PE3_TX_C_DN<3>")
	)
	(segment
		(start 412.59125 -410.030168)
		(end 412.894272 -409.727146)
		(width 0.13208)
		(layer "F.Cu")
		(net "P5E_CPU0_PE3_TX_C_DN<2>")
	)
	(segment
		(start 412.569152 -408.784044)
		(end 412.56585 -408.784044)
		(width 0.13208)
		(layer "F.Cu")
		(net "P5E_CPU0_PE3_TX_C_DN<2>")
	)
	(segment
		(start 412.894272 -409.727146)
		(end 412.894272 -409.109164)
		(width 0.13208)
		(layer "F.Cu")
		(net "P5E_CPU0_PE3_TX_C_DN<2>")
	)
	(segment
		(start 412.894272 -409.109164)
		(end 412.569152 -408.784044)
		(width 0.13208)
		(layer "F.Cu")
		(net "P5E_CPU0_PE3_TX_C_DN<2>")
	)
	(segment
		(start 407.792428 -431.120296)
		(end 407.792428 -424.248072)
		(width 0.14732)
		(layer "In6.Cu")
		(net "P5E_CPU0_PE3_TX_C_DN<2>")
	)
	(segment
		(start 407.792428 -424.248072)
		(end 412.877 -410.744162)
		(width 0.14732)
		(layer "In6.Cu")
		(net "P5E_CPU0_PE3_TX_C_DN<2>")
	)
	(segment
		(start 412.877 -410.744162)
		(end 412.877 -410.315918)
		(width 0.14732)
		(layer "In6.Cu")
		(net "P5E_CPU0_PE3_TX_C_DN<2>")
	)
	(segment
		(start 412.877 -410.315918)
		(end 412.59125 -410.030168)
		(width 0.14732)
		(layer "In6.Cu")
		(net "P5E_CPU0_PE3_TX_C_DN<2>")
	)
	(segment
		(start 408.750008 -431.574702)
		(end 408.602434 -431.427128)
		(width 0.14732)
		(layer "In6.Cu")
		(net "P5E_CPU0_PE3_TX_C_DN<2>")
	)
	(segment
		(start 408.09926 -431.427128)
		(end 407.792428 -431.120296)
		(width 0.14732)
		(layer "In6.Cu")
		(net "P5E_CPU0_PE3_TX_C_DN<2>")
	)
	(segment
		(start 408.750008 -431.889916)
		(end 408.750008 -431.574702)
		(width 0.14732)
		(layer "In6.Cu")
		(net "P5E_CPU0_PE3_TX_C_DN<2>")
	)
	(segment
		(start 408.602434 -431.427128)
		(end 408.09926 -431.427128)
		(width 0.14732)
		(layer "In6.Cu")
		(net "P5E_CPU0_PE3_TX_C_DN<2>")
	)
	(segment
		(start 415.632392 -408.784044)
		(end 415.62909 -408.784044)
		(width 0.13208)
		(layer "F.Cu")
		(net "P5E_CPU0_PE3_TX_C_DN<1>")
	)
	(segment
		(start 415.957512 -409.727146)
		(end 415.957512 -409.109164)
		(width 0.13208)
		(layer "F.Cu")
		(net "P5E_CPU0_PE3_TX_C_DN<1>")
	)
	(segment
		(start 415.65449 -410.030168)
		(end 415.957512 -409.727146)
		(width 0.13208)
		(layer "F.Cu")
		(net "P5E_CPU0_PE3_TX_C_DN<1>")
	)
	(segment
		(start 415.957512 -409.109164)
		(end 415.632392 -408.784044)
		(width 0.13208)
		(layer "F.Cu")
		(net "P5E_CPU0_PE3_TX_C_DN<1>")
	)
	(segment
		(start 410.60243 -430.42713)
		(end 410.100272 -430.42713)
		(width 0.14732)
		(layer "In6.Cu")
		(net "P5E_CPU0_PE3_TX_C_DN<1>")
	)
	(segment
		(start 409.792424 -424.640756)
		(end 415.94024 -410.81706)
		(width 0.14732)
		(layer "In6.Cu")
		(net "P5E_CPU0_PE3_TX_C_DN<1>")
	)
	(segment
		(start 410.100272 -430.42713)
		(end 409.792424 -430.119282)
		(width 0.14732)
		(layer "In6.Cu")
		(net "P5E_CPU0_PE3_TX_C_DN<1>")
	)
	(segment
		(start 415.94024 -410.81706)
		(end 415.94024 -410.315918)
		(width 0.14732)
		(layer "In6.Cu")
		(net "P5E_CPU0_PE3_TX_C_DN<1>")
	)
	(segment
		(start 415.94024 -410.315918)
		(end 415.65449 -410.030168)
		(width 0.14732)
		(layer "In6.Cu")
		(net "P5E_CPU0_PE3_TX_C_DN<1>")
	)
	(segment
		(start 410.750004 -430.574704)
		(end 410.60243 -430.42713)
		(width 0.14732)
		(layer "In6.Cu")
		(net "P5E_CPU0_PE3_TX_C_DN<1>")
	)
	(segment
		(start 409.792424 -430.119282)
		(end 409.792424 -424.640756)
		(width 0.14732)
		(layer "In6.Cu")
		(net "P5E_CPU0_PE3_TX_C_DN<1>")
	)
	(segment
		(start 410.750004 -430.889918)
		(end 410.750004 -430.574704)
		(width 0.14732)
		(layer "In6.Cu")
		(net "P5E_CPU0_PE3_TX_C_DN<1>")
	)
	(segment
		(start 373.072152 -409.727146)
		(end 373.072152 -409.109164)
		(width 0.13208)
		(layer "F.Cu")
		(net "P5E_CPU0_PE3_TX_C_DN<15>")
	)
	(segment
		(start 373.072152 -409.109164)
		(end 372.747032 -408.784044)
		(width 0.13208)
		(layer "F.Cu")
		(net "P5E_CPU0_PE3_TX_C_DN<15>")
	)
	(segment
		(start 372.76913 -410.030168)
		(end 373.072152 -409.727146)
		(width 0.13208)
		(layer "F.Cu")
		(net "P5E_CPU0_PE3_TX_C_DN<15>")
	)
	(segment
		(start 372.747032 -408.784044)
		(end 372.74373 -408.784044)
		(width 0.13208)
		(layer "F.Cu")
		(net "P5E_CPU0_PE3_TX_C_DN<15>")
	)
	(segment
		(start 381.10033 -430.42713)
		(end 380.585472 -429.912272)
		(width 0.14732)
		(layer "In6.Cu")
		(net "P5E_CPU0_PE3_TX_C_DN<15>")
	)
	(segment
		(start 373.06377 -410.324808)
		(end 372.76913 -410.030168)
		(width 0.14732)
		(layer "In6.Cu")
		(net "P5E_CPU0_PE3_TX_C_DN<15>")
	)
	(segment
		(start 381.750062 -430.574704)
		(end 381.602488 -430.42713)
		(width 0.14732)
		(layer "In6.Cu")
		(net "P5E_CPU0_PE3_TX_C_DN<15>")
	)
	(segment
		(start 381.750062 -430.889918)
		(end 381.750062 -430.574704)
		(width 0.14732)
		(layer "In6.Cu")
		(net "P5E_CPU0_PE3_TX_C_DN<15>")
	)
	(segment
		(start 373.06377 -412.837376)
		(end 373.06377 -410.324808)
		(width 0.14732)
		(layer "In6.Cu")
		(net "P5E_CPU0_PE3_TX_C_DN<15>")
	)
	(segment
		(start 381.602488 -430.42713)
		(end 381.10033 -430.42713)
		(width 0.14732)
		(layer "In6.Cu")
		(net "P5E_CPU0_PE3_TX_C_DN<15>")
	)
	(segment
		(start 380.585472 -429.912272)
		(end 373.06377 -412.837376)
		(width 0.14732)
		(layer "In6.Cu")
		(net "P5E_CPU0_PE3_TX_C_DN<15>")
	)
	(segment
		(start 375.810272 -408.784044)
		(end 375.80697 -408.784044)
		(width 0.13208)
		(layer "F.Cu")
		(net "P5E_CPU0_PE3_TX_C_DN<14>")
	)
	(segment
		(start 375.83237 -410.030168)
		(end 376.135392 -409.727146)
		(width 0.13208)
		(layer "F.Cu")
		(net "P5E_CPU0_PE3_TX_C_DN<14>")
	)
	(segment
		(start 376.135392 -409.727146)
		(end 376.135392 -409.109164)
		(width 0.13208)
		(layer "F.Cu")
		(net "P5E_CPU0_PE3_TX_C_DN<14>")
	)
	(segment
		(start 376.135392 -409.109164)
		(end 375.810272 -408.784044)
		(width 0.13208)
		(layer "F.Cu")
		(net "P5E_CPU0_PE3_TX_C_DN<14>")
	)
	(segment
		(start 383.750058 -431.574702)
		(end 383.602484 -431.427128)
		(width 0.14732)
		(layer "In6.Cu")
		(net "P5E_CPU0_PE3_TX_C_DN<14>")
	)
	(segment
		(start 382.792478 -431.165)
		(end 382.792478 -424.765724)
		(width 0.14732)
		(layer "In6.Cu")
		(net "P5E_CPU0_PE3_TX_C_DN<14>")
	)
	(segment
		(start 383.054606 -431.427128)
		(end 382.792478 -431.165)
		(width 0.14732)
		(layer "In6.Cu")
		(net "P5E_CPU0_PE3_TX_C_DN<14>")
	)
	(segment
		(start 383.750058 -431.889916)
		(end 383.750058 -431.574702)
		(width 0.14732)
		(layer "In6.Cu")
		(net "P5E_CPU0_PE3_TX_C_DN<14>")
	)
	(segment
		(start 383.602484 -431.427128)
		(end 383.054606 -431.427128)
		(width 0.14732)
		(layer "In6.Cu")
		(net "P5E_CPU0_PE3_TX_C_DN<14>")
	)
	(segment
		(start 382.792478 -424.765724)
		(end 376.12701 -411.246574)
		(width 0.14732)
		(layer "In6.Cu")
		(net "P5E_CPU0_PE3_TX_C_DN<14>")
	)
	(segment
		(start 376.12701 -410.324808)
		(end 375.83237 -410.030168)
		(width 0.14732)
		(layer "In6.Cu")
		(net "P5E_CPU0_PE3_TX_C_DN<14>")
	)
	(segment
		(start 376.12701 -411.246574)
		(end 376.12701 -410.324808)
		(width 0.14732)
		(layer "In6.Cu")
		(net "P5E_CPU0_PE3_TX_C_DN<14>")
	)
	(segment
		(start 378.89561 -410.030168)
		(end 379.198632 -409.727146)
		(width 0.13208)
		(layer "F.Cu")
		(net "P5E_CPU0_PE3_TX_C_DN<13>")
	)
	(segment
		(start 379.198632 -409.727146)
		(end 379.198632 -409.109164)
		(width 0.13208)
		(layer "F.Cu")
		(net "P5E_CPU0_PE3_TX_C_DN<13>")
	)
	(segment
		(start 379.198632 -409.109164)
		(end 378.873512 -408.784044)
		(width 0.13208)
		(layer "F.Cu")
		(net "P5E_CPU0_PE3_TX_C_DN<13>")
	)
	(segment
		(start 378.873512 -408.784044)
		(end 378.87021 -408.784044)
		(width 0.13208)
		(layer "F.Cu")
		(net "P5E_CPU0_PE3_TX_C_DN<13>")
	)
	(segment
		(start 385.611878 -430.436528)
		(end 385.10972 -430.436528)
		(width 0.14732)
		(layer "In6.Cu")
		(net "P5E_CPU0_PE3_TX_C_DN<13>")
	)
	(segment
		(start 379.19025 -410.324808)
		(end 378.89561 -410.030168)
		(width 0.14732)
		(layer "In6.Cu")
		(net "P5E_CPU0_PE3_TX_C_DN<13>")
	)
	(segment
		(start 379.19025 -411.261052)
		(end 379.19025 -410.324808)
		(width 0.14732)
		(layer "In6.Cu")
		(net "P5E_CPU0_PE3_TX_C_DN<13>")
	)
	(segment
		(start 384.792474 -424.523408)
		(end 379.19025 -411.261052)
		(width 0.14732)
		(layer "In6.Cu")
		(net "P5E_CPU0_PE3_TX_C_DN<13>")
	)
	(segment
		(start 384.792474 -430.119282)
		(end 384.792474 -424.523408)
		(width 0.14732)
		(layer "In6.Cu")
		(net "P5E_CPU0_PE3_TX_C_DN<13>")
	)
	(segment
		(start 385.750054 -430.889918)
		(end 385.750054 -430.574704)
		(width 0.14732)
		(layer "In6.Cu")
		(net "P5E_CPU0_PE3_TX_C_DN<13>")
	)
	(segment
		(start 385.10972 -430.436528)
		(end 384.792474 -430.119282)
		(width 0.14732)
		(layer "In6.Cu")
		(net "P5E_CPU0_PE3_TX_C_DN<13>")
	)
	(segment
		(start 385.750054 -430.574704)
		(end 385.611878 -430.436528)
		(width 0.14732)
		(layer "In6.Cu")
		(net "P5E_CPU0_PE3_TX_C_DN<13>")
	)
	(segment
		(start 381.936752 -408.784044)
		(end 381.93345 -408.784044)
		(width 0.13208)
		(layer "F.Cu")
		(net "P5E_CPU0_PE3_TX_C_DN<12>")
	)
	(segment
		(start 381.95885 -410.030168)
		(end 382.261872 -409.727146)
		(width 0.13208)
		(layer "F.Cu")
		(net "P5E_CPU0_PE3_TX_C_DN<12>")
	)
	(segment
		(start 382.261872 -409.109164)
		(end 381.936752 -408.784044)
		(width 0.13208)
		(layer "F.Cu")
		(net "P5E_CPU0_PE3_TX_C_DN<12>")
	)
	(segment
		(start 382.261872 -409.727146)
		(end 382.261872 -409.109164)
		(width 0.13208)
		(layer "F.Cu")
		(net "P5E_CPU0_PE3_TX_C_DN<12>")
	)
	(segment
		(start 386.79247 -431.100992)
		(end 386.79247 -424.7769)
		(width 0.14732)
		(layer "In6.Cu")
		(net "P5E_CPU0_PE3_TX_C_DN<12>")
	)
	(segment
		(start 382.25349 -411.37205)
		(end 382.25349 -410.324808)
		(width 0.14732)
		(layer "In6.Cu")
		(net "P5E_CPU0_PE3_TX_C_DN<12>")
	)
	(segment
		(start 387.110986 -431.419508)
		(end 386.79247 -431.100992)
		(width 0.14732)
		(layer "In6.Cu")
		(net "P5E_CPU0_PE3_TX_C_DN<12>")
	)
	(segment
		(start 387.594856 -431.419508)
		(end 387.110986 -431.419508)
		(width 0.14732)
		(layer "In6.Cu")
		(net "P5E_CPU0_PE3_TX_C_DN<12>")
	)
	(segment
		(start 387.75005 -431.889916)
		(end 387.75005 -431.574702)
		(width 0.14732)
		(layer "In6.Cu")
		(net "P5E_CPU0_PE3_TX_C_DN<12>")
	)
	(segment
		(start 382.25349 -410.324808)
		(end 381.95885 -410.030168)
		(width 0.14732)
		(layer "In6.Cu")
		(net "P5E_CPU0_PE3_TX_C_DN<12>")
	)
	(segment
		(start 386.79247 -424.7769)
		(end 382.25349 -411.37205)
		(width 0.14732)
		(layer "In6.Cu")
		(net "P5E_CPU0_PE3_TX_C_DN<12>")
	)
	(segment
		(start 387.75005 -431.574702)
		(end 387.594856 -431.419508)
		(width 0.14732)
		(layer "In6.Cu")
		(net "P5E_CPU0_PE3_TX_C_DN<12>")
	)
	(segment
		(start 385.325112 -409.727146)
		(end 385.325112 -409.109164)
		(width 0.13208)
		(layer "F.Cu")
		(net "P5E_CPU0_PE3_TX_C_DN<11>")
	)
	(segment
		(start 385.02209 -410.030168)
		(end 385.325112 -409.727146)
		(width 0.13208)
		(layer "F.Cu")
		(net "P5E_CPU0_PE3_TX_C_DN<11>")
	)
	(segment
		(start 385.325112 -409.109164)
		(end 384.999992 -408.784044)
		(width 0.13208)
		(layer "F.Cu")
		(net "P5E_CPU0_PE3_TX_C_DN<11>")
	)
	(segment
		(start 384.999992 -408.784044)
		(end 384.99669 -408.784044)
		(width 0.13208)
		(layer "F.Cu")
		(net "P5E_CPU0_PE3_TX_C_DN<11>")
	)
	(segment
		(start 388.793228 -424.806364)
		(end 385.31673 -411.77845)
		(width 0.14732)
		(layer "In6.Cu")
		(net "P5E_CPU0_PE3_TX_C_DN<11>")
	)
	(segment
		(start 385.31673 -411.77845)
		(end 385.31673 -410.324808)
		(width 0.14732)
		(layer "In6.Cu")
		(net "P5E_CPU0_PE3_TX_C_DN<11>")
	)
	(segment
		(start 389.750046 -430.574704)
		(end 389.602472 -430.42713)
		(width 0.14732)
		(layer "In6.Cu")
		(net "P5E_CPU0_PE3_TX_C_DN<11>")
	)
	(segment
		(start 389.750046 -430.889918)
		(end 389.750046 -430.574704)
		(width 0.14732)
		(layer "In6.Cu")
		(net "P5E_CPU0_PE3_TX_C_DN<11>")
	)
	(segment
		(start 385.31673 -410.324808)
		(end 385.02209 -410.030168)
		(width 0.14732)
		(layer "In6.Cu")
		(net "P5E_CPU0_PE3_TX_C_DN<11>")
	)
	(segment
		(start 389.100314 -430.42713)
		(end 388.793228 -430.120044)
		(width 0.14732)
		(layer "In6.Cu")
		(net "P5E_CPU0_PE3_TX_C_DN<11>")
	)
	(segment
		(start 388.793228 -430.120044)
		(end 388.793228 -424.806364)
		(width 0.14732)
		(layer "In6.Cu")
		(net "P5E_CPU0_PE3_TX_C_DN<11>")
	)
	(segment
		(start 389.602472 -430.42713)
		(end 389.100314 -430.42713)
		(width 0.14732)
		(layer "In6.Cu")
		(net "P5E_CPU0_PE3_TX_C_DN<11>")
	)
	(segment
		(start 388.388352 -409.727146)
		(end 388.388352 -409.109164)
		(width 0.13208)
		(layer "F.Cu")
		(net "P5E_CPU0_PE3_TX_C_DN<10>")
	)
	(segment
		(start 388.08533 -410.030168)
		(end 388.388352 -409.727146)
		(width 0.13208)
		(layer "F.Cu")
		(net "P5E_CPU0_PE3_TX_C_DN<10>")
	)
	(segment
		(start 388.063232 -408.784044)
		(end 388.05993 -408.784044)
		(width 0.13208)
		(layer "F.Cu")
		(net "P5E_CPU0_PE3_TX_C_DN<10>")
	)
	(segment
		(start 388.388352 -409.109164)
		(end 388.063232 -408.784044)
		(width 0.13208)
		(layer "F.Cu")
		(net "P5E_CPU0_PE3_TX_C_DN<10>")
	)
	(segment
		(start 388.37997 -411.672278)
		(end 388.37997 -410.324808)
		(width 0.14732)
		(layer "In6.Cu")
		(net "P5E_CPU0_PE3_TX_C_DN<10>")
	)
	(segment
		(start 390.792462 -424.583352)
		(end 388.440422 -411.99562)
		(width 0.14732)
		(layer "In6.Cu")
		(net "P5E_CPU0_PE3_TX_C_DN<10>")
	)
	(segment
		(start 391.750042 -431.889916)
		(end 391.750042 -431.574702)
		(width 0.14732)
		(layer "In6.Cu")
		(net "P5E_CPU0_PE3_TX_C_DN<10>")
	)
	(segment
		(start 391.750042 -431.574702)
		(end 391.602468 -431.427128)
		(width 0.14732)
		(layer "In6.Cu")
		(net "P5E_CPU0_PE3_TX_C_DN<10>")
	)
	(segment
		(start 388.440168 -411.995112)
		(end 388.37997 -411.672278)
		(width 0.14732)
		(layer "In6.Cu")
		(net "P5E_CPU0_PE3_TX_C_DN<10>")
	)
	(segment
		(start 391.602468 -431.427128)
		(end 391.081006 -431.427128)
		(width 0.14732)
		(layer "In6.Cu")
		(net "P5E_CPU0_PE3_TX_C_DN<10>")
	)
	(segment
		(start 388.37997 -410.324808)
		(end 388.08533 -410.030168)
		(width 0.14732)
		(layer "In6.Cu")
		(net "P5E_CPU0_PE3_TX_C_DN<10>")
	)
	(segment
		(start 391.081006 -431.427128)
		(end 390.792462 -431.138584)
		(width 0.14732)
		(layer "In6.Cu")
		(net "P5E_CPU0_PE3_TX_C_DN<10>")
	)
	(segment
		(start 388.440422 -411.99562)
		(end 388.440168 -411.995112)
		(width 0.14732)
		(layer "In6.Cu")
		(net "P5E_CPU0_PE3_TX_C_DN<10>")
	)
	(segment
		(start 390.792462 -431.138584)
		(end 390.792462 -424.583352)
		(width 0.14732)
		(layer "In6.Cu")
		(net "P5E_CPU0_PE3_TX_C_DN<10>")
	)
	(segment
		(start 419.58133 -410.030168)
		(end 419.279832 -409.72867)
		(width 0.13208)
		(layer "F.Cu")
		(net "P5E_CPU0_PE3_TX_C_DN<0>")
	)
	(segment
		(start 419.279832 -409.72867)
		(end 419.279832 -409.110942)
		(width 0.13208)
		(layer "F.Cu")
		(net "P5E_CPU0_PE3_TX_C_DN<0>")
	)
	(segment
		(start 419.279832 -409.110942)
		(end 419.60673 -408.784044)
		(width 0.13208)
		(layer "F.Cu")
		(net "P5E_CPU0_PE3_TX_C_DN<0>")
	)
	(segment
		(start 417.09721 -415.001456)
		(end 412.06674 -424.306492)
		(width 0.14732)
		(layer "In6.Cu")
		(net "P5E_CPU0_PE3_TX_C_DN<0>")
	)
	(segment
		(start 417.957508 -413.410146)
		(end 418.0078 -413.578802)
		(width 0.14732)
		(layer "In6.Cu")
		(net "P5E_CPU0_PE3_TX_C_DN<0>")
	)
	(segment
		(start 417.800028 -413.963358)
		(end 417.631118 -414.01365)
		(width 0.14732)
		(layer "In6.Cu")
		(net "P5E_CPU0_PE3_TX_C_DN<0>")
	)
	(segment
		(start 418.0078 -413.578802)
		(end 417.800028 -413.963358)
		(width 0.14732)
		(layer "In6.Cu")
		(net "P5E_CPU0_PE3_TX_C_DN<0>")
	)
	(segment
		(start 412.538418 -431.152808)
		(end 412.75 -430.941226)
		(width 0.14732)
		(layer "In6.Cu")
		(net "P5E_CPU0_PE3_TX_C_DN<0>")
	)
	(segment
		(start 417.631118 -414.01365)
		(end 417.4236 -414.397952)
		(width 0.14732)
		(layer "In6.Cu")
		(net "P5E_CPU0_PE3_TX_C_DN<0>")
	)
	(segment
		(start 419.58133 -410.030168)
		(end 419.2778 -410.333698)
		(width 0.14732)
		(layer "In6.Cu")
		(net "P5E_CPU0_PE3_TX_C_DN<0>")
	)
	(segment
		(start 412.21406 -431.152808)
		(end 412.538418 -431.152808)
		(width 0.14732)
		(layer "In6.Cu")
		(net "P5E_CPU0_PE3_TX_C_DN<0>")
	)
	(segment
		(start 419.2778 -410.967682)
		(end 417.957508 -413.410146)
		(width 0.14732)
		(layer "In6.Cu")
		(net "P5E_CPU0_PE3_TX_C_DN<0>")
	)
	(segment
		(start 412.06674 -424.306492)
		(end 412.06674 -431.005488)
		(width 0.14732)
		(layer "In6.Cu")
		(net "P5E_CPU0_PE3_TX_C_DN<0>")
	)
	(segment
		(start 417.4236 -414.397952)
		(end 417.473892 -414.566608)
		(width 0.14732)
		(layer "In6.Cu")
		(net "P5E_CPU0_PE3_TX_C_DN<0>")
	)
	(segment
		(start 417.26612 -414.951164)
		(end 417.09721 -415.001456)
		(width 0.14732)
		(layer "In6.Cu")
		(net "P5E_CPU0_PE3_TX_C_DN<0>")
	)
	(segment
		(start 417.473892 -414.566608)
		(end 417.26612 -414.951164)
		(width 0.14732)
		(layer "In6.Cu")
		(net "P5E_CPU0_PE3_TX_C_DN<0>")
	)
	(segment
		(start 419.2778 -410.333698)
		(end 419.2778 -410.967682)
		(width 0.14732)
		(layer "In6.Cu")
		(net "P5E_CPU0_PE3_TX_C_DN<0>")
	)
	(segment
		(start 412.06674 -431.005488)
		(end 412.21406 -431.152808)
		(width 0.14732)
		(layer "In6.Cu")
		(net "P5E_CPU0_PE3_TX_C_DN<0>")
	)
	(segment
		(start 412.75 -430.941226)
		(end 412.75 -430.689766)
		(width 0.14732)
		(layer "In6.Cu")
		(net "P5E_CPU0_PE3_TX_C_DN<0>")
	)
	(segment
		(start 374.257316 -288.381186)
		(end 374.257316 -288.917126)
		(width 0.13208)
		(layer "F.Cu")
		(net "P5E_CPU0_PE3_RX_DP<9>")
	)
	(segment
		(start 393.077446 -420.10457)
		(end 393.216638 -420.244778)
		(width 0.14732)
		(layer "In4.Cu")
		(net "P5E_CPU0_PE3_RX_DP<9>")
	)
	(segment
		(start 391.90295 -399.374614)
		(end 391.90295 -404.716996)
		(width 0.14732)
		(layer "In4.Cu")
		(net "P5E_CPU0_PE3_RX_DP<9>")
	)
	(segment
		(start 393.066778 -437.205374)
		(end 393.214098 -437.352694)
		(width 0.14732)
		(layer "In4.Cu")
		(net "P5E_CPU0_PE3_RX_DP<9>")
	)
	(segment
		(start 393.24915 -406.063196)
		(end 393.24915 -410.35478)
		(width 0.14732)
		(layer "In4.Cu")
		(net "P5E_CPU0_PE3_RX_DP<9>")
	)
	(segment
		(start 393.075668 -420.75227)
		(end 393.066778 -424.210988)
		(width 0.14732)
		(layer "In4.Cu")
		(net "P5E_CPU0_PE3_RX_DP<9>")
	)
	(segment
		(start 393.750038 -437.18099)
		(end 393.750038 -436.889906)
		(width 0.14732)
		(layer "In4.Cu")
		(net "P5E_CPU0_PE3_RX_DP<9>")
	)
	(segment
		(start 396.344394 -376.871738)
		(end 391.90295 -399.374614)
		(width 0.14732)
		(layer "In4.Cu")
		(net "P5E_CPU0_PE3_RX_DP<9>")
	)
	(segment
		(start 393.080494 -418.98189)
		(end 393.2047 -419.106604)
		(width 0.14732)
		(layer "In4.Cu")
		(net "P5E_CPU0_PE3_RX_DP<9>")
	)
	(segment
		(start 374.394476 -290.124388)
		(end 374.394476 -290.146486)
		(width 0.0889)
		(layer "In4.Cu")
		(net "P5E_CPU0_PE3_RX_DP<9>")
	)
	(segment
		(start 393.24915 -410.35478)
		(end 393.098274 -411.945074)
		(width 0.14732)
		(layer "In4.Cu")
		(net "P5E_CPU0_PE3_RX_DP<9>")
	)
	(segment
		(start 374.948704 -298.431458)
		(end 396.849092 -326.54367)
		(width 0.14732)
		(layer "In4.Cu")
		(net "P5E_CPU0_PE3_RX_DP<9>")
	)
	(segment
		(start 398.373346 -360.327448)
		(end 396.344394 -376.871738)
		(width 0.14732)
		(layer "In4.Cu")
		(net "P5E_CPU0_PE3_RX_DP<9>")
	)
	(segment
		(start 398.03578 -333.273908)
		(end 398.373346 -360.327448)
		(width 0.14732)
		(layer "In4.Cu")
		(net "P5E_CPU0_PE3_RX_DP<9>")
	)
	(segment
		(start 393.215876 -420.613332)
		(end 393.075668 -420.75227)
		(width 0.14732)
		(layer "In4.Cu")
		(net "P5E_CPU0_PE3_RX_DP<9>")
	)
	(segment
		(start 374.394476 -290.146486)
		(end 374.394476 -295.286938)
		(width 0.14732)
		(layer "In4.Cu")
		(net "P5E_CPU0_PE3_RX_DP<9>")
	)
	(segment
		(start 393.066778 -424.210988)
		(end 393.066778 -437.205374)
		(width 0.14732)
		(layer "In4.Cu")
		(net "P5E_CPU0_PE3_RX_DP<9>")
	)
	(segment
		(start 393.2047 -419.106604)
		(end 393.20343 -419.543738)
		(width 0.14732)
		(layer "In4.Cu")
		(net "P5E_CPU0_PE3_RX_DP<9>")
	)
	(segment
		(start 374.352312 -290.082224)
		(end 374.394476 -290.124388)
		(width 0.0889)
		(layer "In4.Cu")
		(net "P5E_CPU0_PE3_RX_DP<9>")
	)
	(segment
		(start 374.098312 -289.218116)
		(end 374.128284 -289.315144)
		(width 0.0889)
		(layer "In4.Cu")
		(net "P5E_CPU0_PE3_RX_DP<9>")
	)
	(segment
		(start 391.90295 -404.716996)
		(end 393.24915 -406.063196)
		(width 0.14732)
		(layer "In4.Cu")
		(net "P5E_CPU0_PE3_RX_DP<9>")
	)
	(segment
		(start 374.352312 -289.741102)
		(end 374.352312 -290.082224)
		(width 0.0889)
		(layer "In4.Cu")
		(net "P5E_CPU0_PE3_RX_DP<9>")
	)
	(segment
		(start 393.078462 -419.667944)
		(end 393.077446 -420.10457)
		(width 0.14732)
		(layer "In4.Cu")
		(net "P5E_CPU0_PE3_RX_DP<9>")
	)
	(segment
		(start 393.216638 -420.244778)
		(end 393.215876 -420.613332)
		(width 0.14732)
		(layer "In4.Cu")
		(net "P5E_CPU0_PE3_RX_DP<9>")
	)
	(segment
		(start 374.257316 -288.917126)
		(end 374.098312 -289.218116)
		(width 0.0889)
		(layer "In4.Cu")
		(net "P5E_CPU0_PE3_RX_DP<9>")
	)
	(segment
		(start 393.214098 -437.352694)
		(end 393.578334 -437.352694)
		(width 0.14732)
		(layer "In4.Cu")
		(net "P5E_CPU0_PE3_RX_DP<9>")
	)
	(segment
		(start 393.098274 -411.945074)
		(end 393.080494 -418.98189)
		(width 0.14732)
		(layer "In4.Cu")
		(net "P5E_CPU0_PE3_RX_DP<9>")
	)
	(segment
		(start 393.20343 -419.543738)
		(end 393.078462 -419.667944)
		(width 0.14732)
		(layer "In4.Cu")
		(net "P5E_CPU0_PE3_RX_DP<9>")
	)
	(segment
		(start 374.145048 -289.327336)
		(end 374.144794 -289.32759)
		(width 0.0889)
		(layer "In4.Cu")
		(net "P5E_CPU0_PE3_RX_DP<9>")
	)
	(segment
		(start 396.849092 -326.54367)
		(end 398.03578 -333.273908)
		(width 0.14732)
		(layer "In4.Cu")
		(net "P5E_CPU0_PE3_RX_DP<9>")
	)
	(segment
		(start 393.578334 -437.352694)
		(end 393.750038 -437.18099)
		(width 0.14732)
		(layer "In4.Cu")
		(net "P5E_CPU0_PE3_RX_DP<9>")
	)
	(segment
		(start 374.394476 -295.286938)
		(end 374.948704 -298.431458)
		(width 0.14732)
		(layer "In4.Cu")
		(net "P5E_CPU0_PE3_RX_DP<9>")
	)
	(arc
		(start 374.128284 -289.315144)
		(mid 374.136719 -289.321167)
		(end 374.145048 -289.327336)
		(width 0.0889)
		(layer "In4.Cu")
		(net "P5E_CPU0_PE3_RX_DP<9>")
	)
	(arc
		(start 374.144794 -289.32759)
		(mid 374.297542 -289.509755)
		(end 374.352312 -289.741102)
		(width 0.0889)
		(layer "In4.Cu")
		(net "P5E_CPU0_PE3_RX_DP<9>")
	)
	(segment
		(start 374.726962 -287.567116)
		(end 374.726962 -288.102802)
		(width 0.13208)
		(layer "F.Cu")
		(net "P5E_CPU0_PE3_RX_DP<8>")
	)
	(segment
		(start 374.726962 -288.102802)
		(end 374.727216 -288.103056)
		(width 0.13208)
		(layer "F.Cu")
		(net "P5E_CPU0_PE3_RX_DP<8>")
	)
	(segment
		(start 395.066774 -438.205372)
		(end 395.214094 -438.352692)
		(width 0.14732)
		(layer "In4.Cu")
		(net "P5E_CPU0_PE3_RX_DP<8>")
	)
	(segment
		(start 395.538706 -438.352692)
		(end 395.750034 -438.141364)
		(width 0.14732)
		(layer "In4.Cu")
		(net "P5E_CPU0_PE3_RX_DP<8>")
	)
	(segment
		(start 394.96619 -398.820894)
		(end 394.96619 -404.716996)
		(width 0.14732)
		(layer "In4.Cu")
		(net "P5E_CPU0_PE3_RX_DP<8>")
	)
	(segment
		(start 374.727216 -288.103056)
		(end 374.88368 -288.374074)
		(width 0.0889)
		(layer "In4.Cu")
		(net "P5E_CPU0_PE3_RX_DP<8>")
	)
	(segment
		(start 375.756932 -297.644566)
		(end 377.510294 -300.14799)
		(width 0.14732)
		(layer "In4.Cu")
		(net "P5E_CPU0_PE3_RX_DP<8>")
	)
	(segment
		(start 395.919198 -414.035748)
		(end 395.066774 -424.813222)
		(width 0.14732)
		(layer "In4.Cu")
		(net "P5E_CPU0_PE3_RX_DP<8>")
	)
	(segment
		(start 399.753074 -358.294432)
		(end 397.898366 -376.052588)
		(width 0.14732)
		(layer "In4.Cu")
		(net "P5E_CPU0_PE3_RX_DP<8>")
	)
	(segment
		(start 399.057114 -332.954376)
		(end 399.753074 -358.294432)
		(width 0.14732)
		(layer "In4.Cu")
		(net "P5E_CPU0_PE3_RX_DP<8>")
	)
	(segment
		(start 396.31239 -406.063196)
		(end 396.31239 -410.656786)
		(width 0.14732)
		(layer "In4.Cu")
		(net "P5E_CPU0_PE3_RX_DP<8>")
	)
	(segment
		(start 395.066774 -424.813222)
		(end 395.066774 -438.205372)
		(width 0.14732)
		(layer "In4.Cu")
		(net "P5E_CPU0_PE3_RX_DP<8>")
	)
	(segment
		(start 394.96619 -404.716996)
		(end 396.31239 -406.063196)
		(width 0.14732)
		(layer "In4.Cu")
		(net "P5E_CPU0_PE3_RX_DP<8>")
	)
	(segment
		(start 397.86687 -326.206358)
		(end 399.057114 -332.954376)
		(width 0.14732)
		(layer "In4.Cu")
		(net "P5E_CPU0_PE3_RX_DP<8>")
	)
	(segment
		(start 375.292112 -290.082224)
		(end 375.334276 -290.124388)
		(width 0.0889)
		(layer "In4.Cu")
		(net "P5E_CPU0_PE3_RX_DP<8>")
	)
	(segment
		(start 395.214094 -438.352692)
		(end 395.538706 -438.352692)
		(width 0.14732)
		(layer "In4.Cu")
		(net "P5E_CPU0_PE3_RX_DP<8>")
	)
	(segment
		(start 397.898366 -376.052588)
		(end 394.96619 -398.820894)
		(width 0.14732)
		(layer "In4.Cu")
		(net "P5E_CPU0_PE3_RX_DP<8>")
	)
	(segment
		(start 375.762266 -288.898584)
		(end 375.762266 -289.114484)
		(width 0.0889)
		(layer "In4.Cu")
		(net "P5E_CPU0_PE3_RX_DP<8>")
	)
	(segment
		(start 395.750034 -438.141364)
		(end 395.750034 -437.889904)
		(width 0.14732)
		(layer "In4.Cu")
		(net "P5E_CPU0_PE3_RX_DP<8>")
	)
	(segment
		(start 374.88368 -288.374074)
		(end 374.972834 -288.39795)
		(width 0.0889)
		(layer "In4.Cu")
		(net "P5E_CPU0_PE3_RX_DP<8>")
	)
	(segment
		(start 375.292366 -289.752278)
		(end 375.292112 -289.752024)
		(width 0.0889)
		(layer "In4.Cu")
		(net "P5E_CPU0_PE3_RX_DP<8>")
	)
	(segment
		(start 377.510294 -300.14799)
		(end 397.86687 -326.206358)
		(width 0.14732)
		(layer "In4.Cu")
		(net "P5E_CPU0_PE3_RX_DP<8>")
	)
	(segment
		(start 375.334276 -295.244012)
		(end 375.756932 -297.644566)
		(width 0.14732)
		(layer "In4.Cu")
		(net "P5E_CPU0_PE3_RX_DP<8>")
	)
	(segment
		(start 375.334276 -290.124388)
		(end 375.334276 -290.146486)
		(width 0.0889)
		(layer "In4.Cu")
		(net "P5E_CPU0_PE3_RX_DP<8>")
	)
	(segment
		(start 396.31239 -410.656786)
		(end 395.919198 -414.035748)
		(width 0.14732)
		(layer "In4.Cu")
		(net "P5E_CPU0_PE3_RX_DP<8>")
	)
	(segment
		(start 375.334276 -290.146486)
		(end 375.334276 -295.244012)
		(width 0.14732)
		(layer "In4.Cu")
		(net "P5E_CPU0_PE3_RX_DP<8>")
	)
	(segment
		(start 375.292112 -289.752024)
		(end 375.292112 -290.082224)
		(width 0.0889)
		(layer "In4.Cu")
		(net "P5E_CPU0_PE3_RX_DP<8>")
	)
	(arc
		(start 375.762266 -289.114484)
		(mid 375.65087 -289.307577)
		(end 375.476516 -289.446462)
		(width 0.0889)
		(layer "In4.Cu")
		(net "P5E_CPU0_PE3_RX_DP<8>")
	)
	(arc
		(start 375.479818 -288.427414)
		(mid 375.682104 -288.626395)
		(end 375.762266 -288.898584)
		(width 0.0889)
		(layer "In4.Cu")
		(net "P5E_CPU0_PE3_RX_DP<8>")
	)
	(arc
		(start 374.992392 -288.389822)
		(mid 375.240372 -288.35321)
		(end 375.479818 -288.427414)
		(width 0.0889)
		(layer "In4.Cu")
		(net "P5E_CPU0_PE3_RX_DP<8>")
	)
	(arc
		(start 375.476516 -289.446462)
		(mid 375.341937 -289.573766)
		(end 375.292366 -289.752278)
		(width 0.0889)
		(layer "In4.Cu")
		(net "P5E_CPU0_PE3_RX_DP<8>")
	)
	(arc
		(start 374.972834 -288.39795)
		(mid 374.982575 -288.393795)
		(end 374.992392 -288.389822)
		(width 0.0889)
		(layer "In4.Cu")
		(net "P5E_CPU0_PE3_RX_DP<8>")
	)
	(segment
		(start 375.666762 -289.195002)
		(end 375.666762 -289.807142)
		(width 0.13208)
		(layer "F.Cu")
		(net "P5E_CPU0_PE3_RX_DP<7>")
	)
	(segment
		(start 378.025406 -299.723302)
		(end 376.42165 -297.433746)
		(width 0.14732)
		(layer "In4.Cu")
		(net "P5E_CPU0_PE3_RX_DP<7>")
	)
	(segment
		(start 397.80464 -424.61942)
		(end 399.102834 -411.03423)
		(width 0.14732)
		(layer "In4.Cu")
		(net "P5E_CPU0_PE3_RX_DP<7>")
	)
	(segment
		(start 397.75511 -404.830788)
		(end 397.75511 -399.82521)
		(width 0.14732)
		(layer "In4.Cu")
		(net "P5E_CPU0_PE3_RX_DP<7>")
	)
	(segment
		(start 397.792448 -437.319166)
		(end 397.792448 -424.796204)
		(width 0.14732)
		(layer "In4.Cu")
		(net "P5E_CPU0_PE3_RX_DP<7>")
	)
	(segment
		(start 376.041666 -289.645344)
		(end 376.041412 -289.644836)
		(width 0.0889)
		(layer "In4.Cu")
		(net "P5E_CPU0_PE3_RX_DP<7>")
	)
	(segment
		(start 398.602708 -437.627014)
		(end 398.100296 -437.627014)
		(width 0.14732)
		(layer "In4.Cu")
		(net "P5E_CPU0_PE3_RX_DP<7>")
	)
	(segment
		(start 398.750028 -437.774334)
		(end 398.602708 -437.627014)
		(width 0.14732)
		(layer "In4.Cu")
		(net "P5E_CPU0_PE3_RX_DP<7>")
	)
	(segment
		(start 399.772886 -333.182214)
		(end 398.492726 -325.923656)
		(width 0.14732)
		(layer "In4.Cu")
		(net "P5E_CPU0_PE3_RX_DP<7>")
	)
	(segment
		(start 375.825766 -289.506152)
		(end 375.666762 -289.807142)
		(width 0.0889)
		(layer "In4.Cu")
		(net "P5E_CPU0_PE3_RX_DP<7>")
	)
	(segment
		(start 399.10131 -406.176988)
		(end 397.75511 -404.830788)
		(width 0.14732)
		(layer "In4.Cu")
		(net "P5E_CPU0_PE3_RX_DP<7>")
	)
	(segment
		(start 399.10131 -410.672788)
		(end 399.10131 -406.176988)
		(width 0.14732)
		(layer "In4.Cu")
		(net "P5E_CPU0_PE3_RX_DP<7>")
	)
	(segment
		(start 376.42165 -297.433746)
		(end 375.999502 -295.035478)
		(width 0.14732)
		(layer "In4.Cu")
		(net "P5E_CPU0_PE3_RX_DP<7>")
	)
	(segment
		(start 397.75511 -399.82521)
		(end 398.99971 -376.24893)
		(width 0.14732)
		(layer "In4.Cu")
		(net "P5E_CPU0_PE3_RX_DP<7>")
	)
	(segment
		(start 375.910602 -289.479736)
		(end 375.910602 -289.47999)
		(width 0.0889)
		(layer "In4.Cu")
		(net "P5E_CPU0_PE3_RX_DP<7>")
	)
	(segment
		(start 398.99971 -376.24893)
		(end 400.668744 -357.258366)
		(width 0.14732)
		(layer "In4.Cu")
		(net "P5E_CPU0_PE3_RX_DP<7>")
	)
	(segment
		(start 398.100296 -437.627014)
		(end 397.792448 -437.319166)
		(width 0.14732)
		(layer "In4.Cu")
		(net "P5E_CPU0_PE3_RX_DP<7>")
	)
	(segment
		(start 376.041412 -289.645598)
		(end 376.041666 -289.645344)
		(width 0.0889)
		(layer "In4.Cu")
		(net "P5E_CPU0_PE3_RX_DP<7>")
	)
	(segment
		(start 400.668744 -357.258366)
		(end 399.772886 -333.182214)
		(width 0.14732)
		(layer "In4.Cu")
		(net "P5E_CPU0_PE3_RX_DP<7>")
	)
	(segment
		(start 375.999502 -295.035478)
		(end 375.999502 -290.146486)
		(width 0.14732)
		(layer "In4.Cu")
		(net "P5E_CPU0_PE3_RX_DP<7>")
	)
	(segment
		(start 398.750028 -438.089802)
		(end 398.750028 -437.774334)
		(width 0.14732)
		(layer "In4.Cu")
		(net "P5E_CPU0_PE3_RX_DP<7>")
	)
	(segment
		(start 375.910348 -289.480244)
		(end 375.825766 -289.506152)
		(width 0.0889)
		(layer "In4.Cu")
		(net "P5E_CPU0_PE3_RX_DP<7>")
	)
	(segment
		(start 376.041412 -290.082478)
		(end 376.041412 -289.645598)
		(width 0.0889)
		(layer "In4.Cu")
		(net "P5E_CPU0_PE3_RX_DP<7>")
	)
	(segment
		(start 375.999502 -290.124388)
		(end 376.041412 -290.082478)
		(width 0.0889)
		(layer "In4.Cu")
		(net "P5E_CPU0_PE3_RX_DP<7>")
	)
	(segment
		(start 399.102834 -411.03423)
		(end 399.10131 -410.672788)
		(width 0.14732)
		(layer "In4.Cu")
		(net "P5E_CPU0_PE3_RX_DP<7>")
	)
	(segment
		(start 375.910602 -289.47999)
		(end 375.910348 -289.480244)
		(width 0.0889)
		(layer "In4.Cu")
		(net "P5E_CPU0_PE3_RX_DP<7>")
	)
	(segment
		(start 397.792448 -424.796204)
		(end 397.80464 -424.61942)
		(width 0.14732)
		(layer "In4.Cu")
		(net "P5E_CPU0_PE3_RX_DP<7>")
	)
	(segment
		(start 375.999502 -290.146486)
		(end 375.999502 -290.124388)
		(width 0.0889)
		(layer "In4.Cu")
		(net "P5E_CPU0_PE3_RX_DP<7>")
	)
	(segment
		(start 398.492726 -325.923656)
		(end 378.025406 -299.723302)
		(width 0.14732)
		(layer "In4.Cu")
		(net "P5E_CPU0_PE3_RX_DP<7>")
	)
	(arc
		(start 376.041412 -289.644836)
		(mid 375.986861 -289.553681)
		(end 375.910602 -289.479736)
		(width 0.0889)
		(layer "In4.Cu")
		(net "P5E_CPU0_PE3_RX_DP<7>")
	)
	(segment
		(start 377.076716 -288.381186)
		(end 377.076716 -288.917126)
		(width 0.13208)
		(layer "F.Cu")
		(net "P5E_CPU0_PE3_RX_DP<6>")
	)
	(segment
		(start 378.801376 -299.192696)
		(end 377.316746 -297.072812)
		(width 0.14732)
		(layer "In4.Cu")
		(net "P5E_CPU0_PE3_RX_DP<6>")
	)
	(segment
		(start 402.16455 -406.176988)
		(end 400.81835 -404.830788)
		(width 0.14732)
		(layer "In4.Cu")
		(net "P5E_CPU0_PE3_RX_DP<6>")
	)
	(segment
		(start 376.920252 -288.646108)
		(end 377.076716 -288.917126)
		(width 0.0889)
		(layer "In4.Cu")
		(net "P5E_CPU0_PE3_RX_DP<6>")
	)
	(segment
		(start 377.266962 -289.278314)
		(end 377.266962 -289.277806)
		(width 0.0889)
		(layer "In4.Cu")
		(net "P5E_CPU0_PE3_RX_DP<6>")
	)
	(segment
		(start 376.941334 -288.56813)
		(end 376.920252 -288.646108)
		(width 0.0889)
		(layer "In4.Cu")
		(net "P5E_CPU0_PE3_RX_DP<6>")
	)
	(segment
		(start 400.750024 -438.774332)
		(end 400.602704 -438.627012)
		(width 0.14732)
		(layer "In4.Cu")
		(net "P5E_CPU0_PE3_RX_DP<6>")
	)
	(segment
		(start 400.76882 -333.417418)
		(end 399.378424 -325.533512)
		(width 0.14732)
		(layer "In4.Cu")
		(net "P5E_CPU0_PE3_RX_DP<6>")
	)
	(segment
		(start 377.316746 -297.072812)
		(end 376.939556 -294.932608)
		(width 0.14732)
		(layer "In4.Cu")
		(net "P5E_CPU0_PE3_RX_DP<6>")
	)
	(segment
		(start 400.750024 -439.0898)
		(end 400.750024 -438.774332)
		(width 0.14732)
		(layer "In4.Cu")
		(net "P5E_CPU0_PE3_RX_DP<6>")
	)
	(segment
		(start 376.939556 -294.932608)
		(end 376.939556 -290.146486)
		(width 0.14732)
		(layer "In4.Cu")
		(net "P5E_CPU0_PE3_RX_DP<6>")
	)
	(segment
		(start 401.933664 -356.63505)
		(end 400.76882 -333.417418)
		(width 0.14732)
		(layer "In4.Cu")
		(net "P5E_CPU0_PE3_RX_DP<6>")
	)
	(segment
		(start 376.939556 -290.124388)
		(end 376.981466 -290.082478)
		(width 0.0889)
		(layer "In4.Cu")
		(net "P5E_CPU0_PE3_RX_DP<6>")
	)
	(segment
		(start 376.939556 -290.146486)
		(end 376.939556 -290.124388)
		(width 0.0889)
		(layer "In4.Cu")
		(net "P5E_CPU0_PE3_RX_DP<6>")
	)
	(segment
		(start 400.81835 -404.830788)
		(end 400.81835 -400.16049)
		(width 0.14732)
		(layer "In4.Cu")
		(net "P5E_CPU0_PE3_RX_DP<6>")
	)
	(segment
		(start 389.0899 -312.363104)
		(end 389.0899 -312.36285)
		(width 0.14732)
		(layer "In4.Cu")
		(net "P5E_CPU0_PE3_RX_DP<6>")
	)
	(segment
		(start 389.0899 -312.36285)
		(end 378.801376 -299.192696)
		(width 0.14732)
		(layer "In4.Cu")
		(net "P5E_CPU0_PE3_RX_DP<6>")
	)
	(segment
		(start 399.378424 -325.533512)
		(end 389.0899 -312.363104)
		(width 0.14732)
		(layer "In4.Cu")
		(net "P5E_CPU0_PE3_RX_DP<6>")
	)
	(segment
		(start 400.100292 -438.627012)
		(end 399.792444 -438.319164)
		(width 0.14732)
		(layer "In4.Cu")
		(net "P5E_CPU0_PE3_RX_DP<6>")
	)
	(segment
		(start 377.272804 -288.597848)
		(end 377.263914 -288.592768)
		(width 0.0889)
		(layer "In4.Cu")
		(net "P5E_CPU0_PE3_RX_DP<6>")
	)
	(segment
		(start 399.792444 -424.545252)
		(end 402.16455 -410.69768)
		(width 0.14732)
		(layer "In4.Cu")
		(net "P5E_CPU0_PE3_RX_DP<6>")
	)
	(segment
		(start 377.451366 -289.077908)
		(end 377.451366 -288.917126)
		(width 0.0889)
		(layer "In4.Cu")
		(net "P5E_CPU0_PE3_RX_DP<6>")
	)
	(segment
		(start 402.16455 -410.69768)
		(end 402.16455 -406.176988)
		(width 0.14732)
		(layer "In4.Cu")
		(net "P5E_CPU0_PE3_RX_DP<6>")
	)
	(segment
		(start 400.602704 -438.627012)
		(end 400.100292 -438.627012)
		(width 0.14732)
		(layer "In4.Cu")
		(net "P5E_CPU0_PE3_RX_DP<6>")
	)
	(segment
		(start 400.81835 -400.16049)
		(end 401.933664 -356.63505)
		(width 0.14732)
		(layer "In4.Cu")
		(net "P5E_CPU0_PE3_RX_DP<6>")
	)
	(segment
		(start 399.792444 -438.319164)
		(end 399.792444 -424.545252)
		(width 0.14732)
		(layer "In4.Cu")
		(net "P5E_CPU0_PE3_RX_DP<6>")
	)
	(segment
		(start 376.981466 -290.082478)
		(end 376.981466 -289.752024)
		(width 0.0889)
		(layer "In4.Cu")
		(net "P5E_CPU0_PE3_RX_DP<6>")
	)
	(arc
		(start 377.266962 -289.277806)
		(mid 377.376358 -289.193709)
		(end 377.451366 -289.077908)
		(width 0.0889)
		(layer "In4.Cu")
		(net "P5E_CPU0_PE3_RX_DP<6>")
	)
	(arc
		(start 376.981466 -289.752024)
		(mid 377.058416 -289.475512)
		(end 377.266962 -289.278314)
		(width 0.0889)
		(layer "In4.Cu")
		(net "P5E_CPU0_PE3_RX_DP<6>")
	)
	(arc
		(start 377.263914 -288.592768)
		(mid 377.105426 -288.543835)
		(end 376.941334 -288.56813)
		(width 0.0889)
		(layer "In4.Cu")
		(net "P5E_CPU0_PE3_RX_DP<6>")
	)
	(arc
		(start 377.451366 -288.917126)
		(mid 377.403687 -288.734226)
		(end 377.272804 -288.597848)
		(width 0.0889)
		(layer "In4.Cu")
		(net "P5E_CPU0_PE3_RX_DP<6>")
	)
	(segment
		(start 377.546362 -289.195002)
		(end 377.546362 -289.807142)
		(width 0.13208)
		(layer "F.Cu")
		(net "P5E_CPU0_PE3_RX_DP<5>")
	)
	(segment
		(start 401.67814 -332.918816)
		(end 400.272758 -324.950328)
		(width 0.14732)
		(layer "In4.Cu")
		(net "P5E_CPU0_PE3_RX_DP<5>")
	)
	(segment
		(start 402.891498 -356.72268)
		(end 401.67814 -332.918816)
		(width 0.14732)
		(layer "In4.Cu")
		(net "P5E_CPU0_PE3_RX_DP<5>")
	)
	(segment
		(start 401.79244 -437.337454)
		(end 401.79244 -424.514264)
		(width 0.14732)
		(layer "In4.Cu")
		(net "P5E_CPU0_PE3_RX_DP<5>")
	)
	(segment
		(start 382.634744 -295.060878)
		(end 381.155702 -295.060878)
		(width 0.14732)
		(layer "In4.Cu")
		(net "P5E_CPU0_PE3_RX_DP<5>")
	)
	(segment
		(start 377.705366 -289.506152)
		(end 377.546362 -289.807142)
		(width 0.0889)
		(layer "In4.Cu")
		(net "P5E_CPU0_PE3_RX_DP<5>")
	)
	(segment
		(start 402.75002 -438.089802)
		(end 402.75002 -437.774334)
		(width 0.14732)
		(layer "In4.Cu")
		(net "P5E_CPU0_PE3_RX_DP<5>")
	)
	(segment
		(start 377.789948 -289.480244)
		(end 377.705366 -289.506152)
		(width 0.0889)
		(layer "In4.Cu")
		(net "P5E_CPU0_PE3_RX_DP<5>")
	)
	(segment
		(start 381.155702 -295.060878)
		(end 377.878848 -291.784024)
		(width 0.14732)
		(layer "In4.Cu")
		(net "P5E_CPU0_PE3_RX_DP<5>")
	)
	(segment
		(start 377.878848 -290.192206)
		(end 377.878848 -290.170108)
		(width 0.0889)
		(layer "In4.Cu")
		(net "P5E_CPU0_PE3_RX_DP<5>")
	)
	(segment
		(start 405.22779 -410.738066)
		(end 405.22779 -406.176988)
		(width 0.14732)
		(layer "In4.Cu")
		(net "P5E_CPU0_PE3_RX_DP<5>")
	)
	(segment
		(start 403.88159 -400.014948)
		(end 402.891498 -356.72268)
		(width 0.14732)
		(layer "In4.Cu")
		(net "P5E_CPU0_PE3_RX_DP<5>")
	)
	(segment
		(start 377.878848 -291.784024)
		(end 377.878848 -290.192206)
		(width 0.14732)
		(layer "In4.Cu")
		(net "P5E_CPU0_PE3_RX_DP<5>")
	)
	(segment
		(start 402.75002 -437.774334)
		(end 402.6027 -437.627014)
		(width 0.14732)
		(layer "In4.Cu")
		(net "P5E_CPU0_PE3_RX_DP<5>")
	)
	(segment
		(start 402.082 -437.627014)
		(end 401.79244 -437.337454)
		(width 0.14732)
		(layer "In4.Cu")
		(net "P5E_CPU0_PE3_RX_DP<5>")
	)
	(segment
		(start 377.878848 -290.170108)
		(end 377.920758 -290.128198)
		(width 0.0889)
		(layer "In4.Cu")
		(net "P5E_CPU0_PE3_RX_DP<5>")
	)
	(segment
		(start 402.6027 -437.627014)
		(end 402.082 -437.627014)
		(width 0.14732)
		(layer "In4.Cu")
		(net "P5E_CPU0_PE3_RX_DP<5>")
	)
	(segment
		(start 383.899918 -299.64888)
		(end 383.899918 -297.077892)
		(width 0.14732)
		(layer "In4.Cu")
		(net "P5E_CPU0_PE3_RX_DP<5>")
	)
	(segment
		(start 383.899918 -297.077892)
		(end 383.368296 -295.79443)
		(width 0.14732)
		(layer "In4.Cu")
		(net "P5E_CPU0_PE3_RX_DP<5>")
	)
	(segment
		(start 400.272758 -324.950328)
		(end 384.886962 -305.190398)
		(width 0.14732)
		(layer "In4.Cu")
		(net "P5E_CPU0_PE3_RX_DP<5>")
	)
	(segment
		(start 405.22779 -406.176988)
		(end 403.88159 -404.830788)
		(width 0.14732)
		(layer "In4.Cu")
		(net "P5E_CPU0_PE3_RX_DP<5>")
	)
	(segment
		(start 377.920758 -290.128198)
		(end 377.920758 -289.740086)
		(width 0.0889)
		(layer "In4.Cu")
		(net "P5E_CPU0_PE3_RX_DP<5>")
	)
	(segment
		(start 384.885692 -305.188874)
		(end 383.899918 -299.64888)
		(width 0.14732)
		(layer "In4.Cu")
		(net "P5E_CPU0_PE3_RX_DP<5>")
	)
	(segment
		(start 403.88159 -404.830788)
		(end 403.88159 -400.014948)
		(width 0.14732)
		(layer "In4.Cu")
		(net "P5E_CPU0_PE3_RX_DP<5>")
	)
	(segment
		(start 384.886962 -305.190398)
		(end 384.885692 -305.188874)
		(width 0.14732)
		(layer "In4.Cu")
		(net "P5E_CPU0_PE3_RX_DP<5>")
	)
	(segment
		(start 401.79244 -424.514264)
		(end 405.22779 -410.738066)
		(width 0.14732)
		(layer "In4.Cu")
		(net "P5E_CPU0_PE3_RX_DP<5>")
	)
	(segment
		(start 383.368296 -295.79443)
		(end 382.634744 -295.060878)
		(width 0.14732)
		(layer "In4.Cu")
		(net "P5E_CPU0_PE3_RX_DP<5>")
	)
	(segment
		(start 377.920758 -289.740086)
		(end 377.920504 -289.74034)
		(width 0.0889)
		(layer "In4.Cu")
		(net "P5E_CPU0_PE3_RX_DP<5>")
	)
	(arc
		(start 377.920504 -289.74034)
		(mid 377.886033 -289.594829)
		(end 377.789948 -289.480244)
		(width 0.0889)
		(layer "In4.Cu")
		(net "P5E_CPU0_PE3_RX_DP<5>")
	)
	(segment
		(start 378.956316 -288.381186)
		(end 378.956316 -288.917126)
		(width 0.13208)
		(layer "F.Cu")
		(net "P5E_CPU0_PE3_RX_DP<4>")
	)
	(segment
		(start 408.29103 -406.176988)
		(end 406.94483 -404.830788)
		(width 0.14732)
		(layer "In4.Cu")
		(net "P5E_CPU0_PE3_RX_DP<4>")
	)
	(segment
		(start 379.330966 -289.077908)
		(end 379.330966 -288.917126)
		(width 0.0889)
		(layer "In4.Cu")
		(net "P5E_CPU0_PE3_RX_DP<4>")
	)
	(segment
		(start 402.624036 -332.887574)
		(end 401.154646 -324.558152)
		(width 0.14732)
		(layer "In4.Cu")
		(net "P5E_CPU0_PE3_RX_DP<4>")
	)
	(segment
		(start 379.146562 -289.278314)
		(end 379.146562 -289.277806)
		(width 0.0889)
		(layer "In4.Cu")
		(net "P5E_CPU0_PE3_RX_DP<4>")
	)
	(segment
		(start 404.100284 -438.627012)
		(end 403.792436 -438.319164)
		(width 0.14732)
		(layer "In4.Cu")
		(net "P5E_CPU0_PE3_RX_DP<4>")
	)
	(segment
		(start 385.768596 -304.797714)
		(end 384.836416 -299.566838)
		(width 0.14732)
		(layer "In4.Cu")
		(net "P5E_CPU0_PE3_RX_DP<4>")
	)
	(segment
		(start 403.792436 -424.430952)
		(end 408.29103 -410.753052)
		(width 0.14732)
		(layer "In4.Cu")
		(net "P5E_CPU0_PE3_RX_DP<4>")
	)
	(segment
		(start 384.166872 -295.268396)
		(end 383.022856 -294.12438)
		(width 0.14732)
		(layer "In4.Cu")
		(net "P5E_CPU0_PE3_RX_DP<4>")
	)
	(segment
		(start 406.94483 -404.830788)
		(end 406.94483 -399.923)
		(width 0.14732)
		(layer "In4.Cu")
		(net "P5E_CPU0_PE3_RX_DP<4>")
	)
	(segment
		(start 408.29103 -410.753052)
		(end 408.29103 -406.176988)
		(width 0.14732)
		(layer "In4.Cu")
		(net "P5E_CPU0_PE3_RX_DP<4>")
	)
	(segment
		(start 378.818902 -290.182046)
		(end 378.818902 -290.159948)
		(width 0.0889)
		(layer "In4.Cu")
		(net "P5E_CPU0_PE3_RX_DP<4>")
	)
	(segment
		(start 403.792436 -438.319164)
		(end 403.792436 -424.430952)
		(width 0.14732)
		(layer "In4.Cu")
		(net "P5E_CPU0_PE3_RX_DP<4>")
	)
	(segment
		(start 404.750016 -438.774332)
		(end 404.602696 -438.627012)
		(width 0.14732)
		(layer "In4.Cu")
		(net "P5E_CPU0_PE3_RX_DP<4>")
	)
	(segment
		(start 383.022856 -294.12438)
		(end 381.645668 -294.12438)
		(width 0.14732)
		(layer "In4.Cu")
		(net "P5E_CPU0_PE3_RX_DP<4>")
	)
	(segment
		(start 404.602696 -438.627012)
		(end 404.100284 -438.627012)
		(width 0.14732)
		(layer "In4.Cu")
		(net "P5E_CPU0_PE3_RX_DP<4>")
	)
	(segment
		(start 384.836416 -299.566838)
		(end 384.836416 -296.884852)
		(width 0.14732)
		(layer "In4.Cu")
		(net "P5E_CPU0_PE3_RX_DP<4>")
	)
	(segment
		(start 378.818902 -290.159948)
		(end 378.860812 -290.118038)
		(width 0.0889)
		(layer "In4.Cu")
		(net "P5E_CPU0_PE3_RX_DP<4>")
	)
	(segment
		(start 401.154646 -324.558152)
		(end 385.768596 -304.797714)
		(width 0.14732)
		(layer "In4.Cu")
		(net "P5E_CPU0_PE3_RX_DP<4>")
	)
	(segment
		(start 406.94483 -399.923)
		(end 402.624036 -332.887574)
		(width 0.14732)
		(layer "In4.Cu")
		(net "P5E_CPU0_PE3_RX_DP<4>")
	)
	(segment
		(start 384.836416 -296.884852)
		(end 384.166872 -295.268396)
		(width 0.14732)
		(layer "In4.Cu")
		(net "P5E_CPU0_PE3_RX_DP<4>")
	)
	(segment
		(start 378.820934 -288.56813)
		(end 378.799852 -288.646108)
		(width 0.0889)
		(layer "In4.Cu")
		(net "P5E_CPU0_PE3_RX_DP<4>")
	)
	(segment
		(start 378.799852 -288.646108)
		(end 378.956316 -288.917126)
		(width 0.0889)
		(layer "In4.Cu")
		(net "P5E_CPU0_PE3_RX_DP<4>")
	)
	(segment
		(start 404.750016 -439.0898)
		(end 404.750016 -438.774332)
		(width 0.14732)
		(layer "In4.Cu")
		(net "P5E_CPU0_PE3_RX_DP<4>")
	)
	(segment
		(start 378.818902 -291.297614)
		(end 378.818902 -290.182046)
		(width 0.14732)
		(layer "In4.Cu")
		(net "P5E_CPU0_PE3_RX_DP<4>")
	)
	(segment
		(start 379.152404 -288.597848)
		(end 379.143514 -288.592768)
		(width 0.0889)
		(layer "In4.Cu")
		(net "P5E_CPU0_PE3_RX_DP<4>")
	)
	(segment
		(start 381.645668 -294.12438)
		(end 378.818902 -291.297614)
		(width 0.14732)
		(layer "In4.Cu")
		(net "P5E_CPU0_PE3_RX_DP<4>")
	)
	(segment
		(start 378.860812 -290.118038)
		(end 378.860812 -289.752786)
		(width 0.0889)
		(layer "In4.Cu")
		(net "P5E_CPU0_PE3_RX_DP<4>")
	)
	(arc
		(start 379.146562 -289.277806)
		(mid 379.255958 -289.193709)
		(end 379.330966 -289.077908)
		(width 0.0889)
		(layer "In4.Cu")
		(net "P5E_CPU0_PE3_RX_DP<4>")
	)
	(arc
		(start 379.143514 -288.592768)
		(mid 378.985026 -288.543835)
		(end 378.820934 -288.56813)
		(width 0.0889)
		(layer "In4.Cu")
		(net "P5E_CPU0_PE3_RX_DP<4>")
	)
	(arc
		(start 379.330966 -288.917126)
		(mid 379.283287 -288.734226)
		(end 379.152404 -288.597848)
		(width 0.0889)
		(layer "In4.Cu")
		(net "P5E_CPU0_PE3_RX_DP<4>")
	)
	(arc
		(start 378.860812 -289.752786)
		(mid 378.937698 -289.475802)
		(end 379.146562 -289.278314)
		(width 0.0889)
		(layer "In4.Cu")
		(net "P5E_CPU0_PE3_RX_DP<4>")
	)
	(segment
		(start 379.896116 -288.381186)
		(end 379.896116 -288.917126)
		(width 0.13208)
		(layer "F.Cu")
		(net "P5E_CPU0_PE3_RX_DP<3>")
	)
	(segment
		(start 408.656536 -418.581332)
		(end 408.490928 -418.985954)
		(width 0.14732)
		(layer "In4.Cu")
		(net "P5E_CPU0_PE3_RX_DP<3>")
	)
	(segment
		(start 406.214072 -437.352694)
		(end 406.538684 -437.352694)
		(width 0.14732)
		(layer "In4.Cu")
		(net "P5E_CPU0_PE3_RX_DP<3>")
	)
	(segment
		(start 386.067046 -299.45838)
		(end 386.0673 -299.458634)
		(width 0.14732)
		(layer "In4.Cu")
		(net "P5E_CPU0_PE3_RX_DP<3>")
	)
	(segment
		(start 408.328368 -419.053772)
		(end 408.16276 -419.457886)
		(width 0.14732)
		(layer "In4.Cu")
		(net "P5E_CPU0_PE3_RX_DP<3>")
	)
	(segment
		(start 386.92709 -304.28184)
		(end 402.313648 -324.043294)
		(width 0.14732)
		(layer "In4.Cu")
		(net "P5E_CPU0_PE3_RX_DP<3>")
	)
	(segment
		(start 410.28239 -404.716996)
		(end 411.62859 -406.063196)
		(width 0.14732)
		(layer "In4.Cu")
		(net "P5E_CPU0_PE3_RX_DP<3>")
	)
	(segment
		(start 406.066752 -437.205374)
		(end 406.214072 -437.352694)
		(width 0.14732)
		(layer "In4.Cu")
		(net "P5E_CPU0_PE3_RX_DP<3>")
	)
	(segment
		(start 408.588718 -418.419026)
		(end 408.656536 -418.581332)
		(width 0.14732)
		(layer "In4.Cu")
		(net "P5E_CPU0_PE3_RX_DP<3>")
	)
	(segment
		(start 409.104084 -417.489894)
		(end 408.938222 -417.894262)
		(width 0.14732)
		(layer "In4.Cu")
		(net "P5E_CPU0_PE3_RX_DP<3>")
	)
	(segment
		(start 406.750012 -437.141366)
		(end 406.750012 -436.889906)
		(width 0.14732)
		(layer "In4.Cu")
		(net "P5E_CPU0_PE3_RX_DP<3>")
	)
	(segment
		(start 408.16276 -419.457886)
		(end 408.230832 -419.620192)
		(width 0.14732)
		(layer "In4.Cu")
		(net "P5E_CPU0_PE3_RX_DP<3>")
	)
	(segment
		(start 386.067046 -296.617644)
		(end 386.067046 -299.45838)
		(width 0.14732)
		(layer "In4.Cu")
		(net "P5E_CPU0_PE3_RX_DP<3>")
	)
	(segment
		(start 408.775662 -417.962334)
		(end 408.588718 -418.419026)
		(width 0.14732)
		(layer "In4.Cu")
		(net "P5E_CPU0_PE3_RX_DP<3>")
	)
	(segment
		(start 380.033276 -290.778692)
		(end 382.148334 -292.89375)
		(width 0.14732)
		(layer "In4.Cu")
		(net "P5E_CPU0_PE3_RX_DP<3>")
	)
	(segment
		(start 406.538684 -437.352694)
		(end 406.750012 -437.141366)
		(width 0.14732)
		(layer "In4.Cu")
		(net "P5E_CPU0_PE3_RX_DP<3>")
	)
	(segment
		(start 411.62859 -411.000956)
		(end 409.036012 -417.327334)
		(width 0.14732)
		(layer "In4.Cu")
		(net "P5E_CPU0_PE3_RX_DP<3>")
	)
	(segment
		(start 379.767084 -289.315144)
		(end 379.78334 -289.327082)
		(width 0.0889)
		(layer "In4.Cu")
		(net "P5E_CPU0_PE3_RX_DP<3>")
	)
	(segment
		(start 411.62859 -406.063196)
		(end 411.62859 -411.000956)
		(width 0.14732)
		(layer "In4.Cu")
		(net "P5E_CPU0_PE3_RX_DP<3>")
	)
	(segment
		(start 379.896116 -288.917126)
		(end 379.737112 -289.218116)
		(width 0.0889)
		(layer "In4.Cu")
		(net "P5E_CPU0_PE3_RX_DP<3>")
	)
	(segment
		(start 409.036012 -417.327334)
		(end 409.104084 -417.489894)
		(width 0.14732)
		(layer "In4.Cu")
		(net "P5E_CPU0_PE3_RX_DP<3>")
	)
	(segment
		(start 380.033276 -290.20389)
		(end 380.033276 -290.215066)
		(width 0.0889)
		(layer "In4.Cu")
		(net "P5E_CPU0_PE3_RX_DP<3>")
	)
	(segment
		(start 379.991112 -290.161726)
		(end 380.033276 -290.20389)
		(width 0.0889)
		(layer "In4.Cu")
		(net "P5E_CPU0_PE3_RX_DP<3>")
	)
	(segment
		(start 385.236466 -294.612314)
		(end 386.067046 -296.617644)
		(width 0.14732)
		(layer "In4.Cu")
		(net "P5E_CPU0_PE3_RX_DP<3>")
	)
	(segment
		(start 408.938222 -417.894262)
		(end 408.775662 -417.962334)
		(width 0.14732)
		(layer "In4.Cu")
		(net "P5E_CPU0_PE3_RX_DP<3>")
	)
	(segment
		(start 382.148334 -292.89375)
		(end 383.517902 -292.89375)
		(width 0.14732)
		(layer "In4.Cu")
		(net "P5E_CPU0_PE3_RX_DP<3>")
	)
	(segment
		(start 386.0673 -299.458634)
		(end 386.92709 -304.28184)
		(width 0.14732)
		(layer "In4.Cu")
		(net "P5E_CPU0_PE3_RX_DP<3>")
	)
	(segment
		(start 407.90241 -420.092632)
		(end 407.902918 -420.092632)
		(width 0.14732)
		(layer "In4.Cu")
		(net "P5E_CPU0_PE3_RX_DP<3>")
	)
	(segment
		(start 380.033276 -290.215066)
		(end 380.033276 -290.778692)
		(width 0.14732)
		(layer "In4.Cu")
		(net "P5E_CPU0_PE3_RX_DP<3>")
	)
	(segment
		(start 383.517902 -292.89375)
		(end 385.236466 -294.612314)
		(width 0.14732)
		(layer "In4.Cu")
		(net "P5E_CPU0_PE3_RX_DP<3>")
	)
	(segment
		(start 410.28239 -400.206718)
		(end 410.28239 -404.716996)
		(width 0.14732)
		(layer "In4.Cu")
		(net "P5E_CPU0_PE3_RX_DP<3>")
	)
	(segment
		(start 408.065224 -420.024814)
		(end 407.90241 -420.092632)
		(width 0.14732)
		(layer "In4.Cu")
		(net "P5E_CPU0_PE3_RX_DP<3>")
	)
	(segment
		(start 408.230832 -419.620192)
		(end 408.065224 -420.024814)
		(width 0.14732)
		(layer "In4.Cu")
		(net "P5E_CPU0_PE3_RX_DP<3>")
	)
	(segment
		(start 379.991112 -289.740594)
		(end 379.991112 -290.161726)
		(width 0.0889)
		(layer "In4.Cu")
		(net "P5E_CPU0_PE3_RX_DP<3>")
	)
	(segment
		(start 379.737112 -289.218116)
		(end 379.767084 -289.315144)
		(width 0.0889)
		(layer "In4.Cu")
		(net "P5E_CPU0_PE3_RX_DP<3>")
	)
	(segment
		(start 406.066752 -424.57243)
		(end 406.066752 -437.205374)
		(width 0.14732)
		(layer "In4.Cu")
		(net "P5E_CPU0_PE3_RX_DP<3>")
	)
	(segment
		(start 408.490928 -418.985954)
		(end 408.328368 -419.053772)
		(width 0.14732)
		(layer "In4.Cu")
		(net "P5E_CPU0_PE3_RX_DP<3>")
	)
	(segment
		(start 402.313648 -324.043294)
		(end 403.890734 -332.988666)
		(width 0.14732)
		(layer "In4.Cu")
		(net "P5E_CPU0_PE3_RX_DP<3>")
	)
	(segment
		(start 403.890734 -332.988666)
		(end 405.655526 -361.089702)
		(width 0.14732)
		(layer "In4.Cu")
		(net "P5E_CPU0_PE3_RX_DP<3>")
	)
	(segment
		(start 405.655526 -361.089702)
		(end 410.28239 -400.206718)
		(width 0.14732)
		(layer "In4.Cu")
		(net "P5E_CPU0_PE3_RX_DP<3>")
	)
	(segment
		(start 407.902918 -420.092632)
		(end 406.066752 -424.57243)
		(width 0.14732)
		(layer "In4.Cu")
		(net "P5E_CPU0_PE3_RX_DP<3>")
	)
	(arc
		(start 379.78334 -289.327082)
		(mid 379.936324 -289.509182)
		(end 379.991112 -289.740594)
		(width 0.0889)
		(layer "In4.Cu")
		(net "P5E_CPU0_PE3_RX_DP<3>")
	)
	(segment
		(start 380.365762 -287.567116)
		(end 380.365762 -288.102802)
		(width 0.13208)
		(layer "F.Cu")
		(net "P5E_CPU0_PE3_RX_DP<2>")
	)
	(segment
		(start 380.365762 -288.102802)
		(end 380.366016 -288.103056)
		(width 0.13208)
		(layer "F.Cu")
		(net "P5E_CPU0_PE3_RX_DP<2>")
	)
	(segment
		(start 383.740914 -291.589968)
		(end 385.91998 -293.769034)
		(width 0.14732)
		(layer "In4.Cu")
		(net "P5E_CPU0_PE3_RX_DP<2>")
	)
	(segment
		(start 380.52248 -288.374074)
		(end 380.611634 -288.39795)
		(width 0.0889)
		(layer "In4.Cu")
		(net "P5E_CPU0_PE3_RX_DP<2>")
	)
	(segment
		(start 381.401066 -288.898584)
		(end 381.401066 -289.114484)
		(width 0.0889)
		(layer "In4.Cu")
		(net "P5E_CPU0_PE3_RX_DP<2>")
	)
	(segment
		(start 413.34563 -404.716996)
		(end 414.69183 -406.063196)
		(width 0.14732)
		(layer "In4.Cu")
		(net "P5E_CPU0_PE3_RX_DP<2>")
	)
	(segment
		(start 408.214068 -438.352692)
		(end 408.53868 -438.352692)
		(width 0.14732)
		(layer "In4.Cu")
		(net "P5E_CPU0_PE3_RX_DP<2>")
	)
	(segment
		(start 385.91998 -293.769034)
		(end 387.015228 -296.413428)
		(width 0.14732)
		(layer "In4.Cu")
		(net "P5E_CPU0_PE3_RX_DP<2>")
	)
	(segment
		(start 414.69183 -406.063196)
		(end 414.69183 -410.953204)
		(width 0.14732)
		(layer "In4.Cu")
		(net "P5E_CPU0_PE3_RX_DP<2>")
	)
	(segment
		(start 408.066494 -424.3197)
		(end 408.066494 -438.205118)
		(width 0.14732)
		(layer "In4.Cu")
		(net "P5E_CPU0_PE3_RX_DP<2>")
	)
	(segment
		(start 408.066494 -438.205118)
		(end 408.214068 -438.352692)
		(width 0.14732)
		(layer "In4.Cu")
		(net "P5E_CPU0_PE3_RX_DP<2>")
	)
	(segment
		(start 387.015228 -296.413428)
		(end 387.015228 -299.375576)
		(width 0.14732)
		(layer "In4.Cu")
		(net "P5E_CPU0_PE3_RX_DP<2>")
	)
	(segment
		(start 408.750008 -438.141364)
		(end 408.750008 -437.889904)
		(width 0.14732)
		(layer "In4.Cu")
		(net "P5E_CPU0_PE3_RX_DP<2>")
	)
	(segment
		(start 413.34563 -400.357848)
		(end 413.34563 -404.716996)
		(width 0.14732)
		(layer "In4.Cu")
		(net "P5E_CPU0_PE3_RX_DP<2>")
	)
	(segment
		(start 406.585928 -360.636058)
		(end 407.810716 -369.81892)
		(width 0.14732)
		(layer "In4.Cu")
		(net "P5E_CPU0_PE3_RX_DP<2>")
	)
	(segment
		(start 387.819646 -303.88433)
		(end 403.191726 -323.627496)
		(width 0.14732)
		(layer "In4.Cu")
		(net "P5E_CPU0_PE3_RX_DP<2>")
	)
	(segment
		(start 403.191726 -323.627496)
		(end 404.86711 -333.127604)
		(width 0.14732)
		(layer "In4.Cu")
		(net "P5E_CPU0_PE3_RX_DP<2>")
	)
	(segment
		(start 382.12268 -291.589968)
		(end 383.740914 -291.589968)
		(width 0.14732)
		(layer "In4.Cu")
		(net "P5E_CPU0_PE3_RX_DP<2>")
	)
	(segment
		(start 381.066548 -290.500054)
		(end 381.255778 -290.782756)
		(width 0.0889)
		(layer "In4.Cu")
		(net "P5E_CPU0_PE3_RX_DP<2>")
	)
	(segment
		(start 407.810716 -369.81892)
		(end 413.34563 -400.357848)
		(width 0.14732)
		(layer "In4.Cu")
		(net "P5E_CPU0_PE3_RX_DP<2>")
	)
	(segment
		(start 408.53868 -438.352692)
		(end 408.750008 -438.141364)
		(width 0.14732)
		(layer "In4.Cu")
		(net "P5E_CPU0_PE3_RX_DP<2>")
	)
	(segment
		(start 381.50546 -290.972748)
		(end 381.520954 -290.988242)
		(width 0.0889)
		(layer "In4.Cu")
		(net "P5E_CPU0_PE3_RX_DP<2>")
	)
	(segment
		(start 380.366016 -288.103056)
		(end 380.52248 -288.374074)
		(width 0.0889)
		(layer "In4.Cu")
		(net "P5E_CPU0_PE3_RX_DP<2>")
	)
	(segment
		(start 381.520954 -290.988242)
		(end 382.12268 -291.589968)
		(width 0.14732)
		(layer "In4.Cu")
		(net "P5E_CPU0_PE3_RX_DP<2>")
	)
	(segment
		(start 381.255778 -290.782756)
		(end 381.445516 -290.972748)
		(width 0.0889)
		(layer "In4.Cu")
		(net "P5E_CPU0_PE3_RX_DP<2>")
	)
	(segment
		(start 414.69183 -410.953204)
		(end 408.066494 -424.3197)
		(width 0.14732)
		(layer "In4.Cu")
		(net "P5E_CPU0_PE3_RX_DP<2>")
	)
	(segment
		(start 404.86711 -333.127604)
		(end 406.585928 -360.636058)
		(width 0.14732)
		(layer "In4.Cu")
		(net "P5E_CPU0_PE3_RX_DP<2>")
	)
	(segment
		(start 380.930912 -289.64636)
		(end 380.930912 -290.172648)
		(width 0.0889)
		(layer "In4.Cu")
		(net "P5E_CPU0_PE3_RX_DP<2>")
	)
	(segment
		(start 387.015228 -299.375576)
		(end 387.819646 -303.88433)
		(width 0.14732)
		(layer "In4.Cu")
		(net "P5E_CPU0_PE3_RX_DP<2>")
	)
	(segment
		(start 380.930912 -290.172648)
		(end 381.066548 -290.500054)
		(width 0.0889)
		(layer "In4.Cu")
		(net "P5E_CPU0_PE3_RX_DP<2>")
	)
	(segment
		(start 381.445516 -290.972748)
		(end 381.50546 -290.972748)
		(width 0.0889)
		(layer "In4.Cu")
		(net "P5E_CPU0_PE3_RX_DP<2>")
	)
	(arc
		(start 380.631192 -288.389822)
		(mid 380.879172 -288.35321)
		(end 381.118618 -288.427414)
		(width 0.0889)
		(layer "In4.Cu")
		(net "P5E_CPU0_PE3_RX_DP<2>")
	)
	(arc
		(start 381.401066 -289.114484)
		(mid 381.28967 -289.307577)
		(end 381.115316 -289.446462)
		(width 0.0889)
		(layer "In4.Cu")
		(net "P5E_CPU0_PE3_RX_DP<2>")
	)
	(arc
		(start 380.611634 -288.39795)
		(mid 380.621375 -288.393795)
		(end 380.631192 -288.389822)
		(width 0.0889)
		(layer "In4.Cu")
		(net "P5E_CPU0_PE3_RX_DP<2>")
	)
	(arc
		(start 381.115316 -289.446462)
		(mid 381.00592 -289.530559)
		(end 380.930912 -289.64636)
		(width 0.0889)
		(layer "In4.Cu")
		(net "P5E_CPU0_PE3_RX_DP<2>")
	)
	(arc
		(start 381.118618 -288.427414)
		(mid 381.320904 -288.626395)
		(end 381.401066 -288.898584)
		(width 0.0889)
		(layer "In4.Cu")
		(net "P5E_CPU0_PE3_RX_DP<2>")
	)
	(segment
		(start 381.775716 -288.381186)
		(end 381.775716 -288.917126)
		(width 0.13208)
		(layer "F.Cu")
		(net "P5E_CPU0_PE3_RX_DP<1>")
	)
	(segment
		(start 381.852678 -289.56508)
		(end 381.870712 -289.601402)
		(width 0.0889)
		(layer "In4.Cu")
		(net "P5E_CPU0_PE3_RX_DP<1>")
	)
	(segment
		(start 387.948424 -296.16908)
		(end 387.948424 -299.235876)
		(width 0.14732)
		(layer "In4.Cu")
		(net "P5E_CPU0_PE3_RX_DP<1>")
	)
	(segment
		(start 381.616712 -289.218116)
		(end 381.646684 -289.315144)
		(width 0.0889)
		(layer "In4.Cu")
		(net "P5E_CPU0_PE3_RX_DP<1>")
	)
	(segment
		(start 410.06649 -424.3578)
		(end 410.06649 -437.20512)
		(width 0.14732)
		(layer "In4.Cu")
		(net "P5E_CPU0_PE3_RX_DP<1>")
	)
	(segment
		(start 413.446214 -418.702998)
		(end 413.229044 -419.082474)
		(width 0.14732)
		(layer "In4.Cu")
		(net "P5E_CPU0_PE3_RX_DP<1>")
	)
	(segment
		(start 405.789638 -332.665324)
		(end 406.54859 -344.702638)
		(width 0.14732)
		(layer "In4.Cu")
		(net "P5E_CPU0_PE3_RX_DP<1>")
	)
	(segment
		(start 386.678678 -293.103046)
		(end 387.948424 -296.16908)
		(width 0.14732)
		(layer "In4.Cu")
		(net "P5E_CPU0_PE3_RX_DP<1>")
	)
	(segment
		(start 404.143464 -323.33057)
		(end 405.789638 -332.665324)
		(width 0.14732)
		(layer "In4.Cu")
		(net "P5E_CPU0_PE3_RX_DP<1>")
	)
	(segment
		(start 381.646684 -289.315144)
		(end 381.64643 -289.315652)
		(width 0.0889)
		(layer "In4.Cu")
		(net "P5E_CPU0_PE3_RX_DP<1>")
	)
	(segment
		(start 413.059118 -419.128702)
		(end 412.842202 -419.50767)
		(width 0.14732)
		(layer "In4.Cu")
		(net "P5E_CPU0_PE3_RX_DP<1>")
	)
	(segment
		(start 381.870712 -289.994086)
		(end 382.27508 -290.398454)
		(width 0.0889)
		(layer "In4.Cu")
		(net "P5E_CPU0_PE3_RX_DP<1>")
	)
	(segment
		(start 410.214064 -437.352694)
		(end 410.538676 -437.352694)
		(width 0.14732)
		(layer "In4.Cu")
		(net "P5E_CPU0_PE3_RX_DP<1>")
	)
	(segment
		(start 412.842202 -419.50767)
		(end 412.88843 -419.677596)
		(width 0.14732)
		(layer "In4.Cu")
		(net "P5E_CPU0_PE3_RX_DP<1>")
	)
	(segment
		(start 410.750004 -437.141366)
		(end 410.750004 -436.889906)
		(width 0.14732)
		(layer "In4.Cu")
		(net "P5E_CPU0_PE3_RX_DP<1>")
	)
	(segment
		(start 410.538676 -437.352694)
		(end 410.750004 -437.141366)
		(width 0.14732)
		(layer "In4.Cu")
		(net "P5E_CPU0_PE3_RX_DP<1>")
	)
	(segment
		(start 382.27508 -290.398454)
		(end 382.334008 -290.398454)
		(width 0.0889)
		(layer "In4.Cu")
		(net "P5E_CPU0_PE3_RX_DP<1>")
	)
	(segment
		(start 382.349502 -290.413948)
		(end 382.753616 -290.818062)
		(width 0.14732)
		(layer "In4.Cu")
		(net "P5E_CPU0_PE3_RX_DP<1>")
	)
	(segment
		(start 387.948424 -299.235876)
		(end 388.699502 -303.494948)
		(width 0.14732)
		(layer "In4.Cu")
		(net "P5E_CPU0_PE3_RX_DP<1>")
	)
	(segment
		(start 406.548082 -344.702892)
		(end 407.307796 -356.740714)
		(width 0.14732)
		(layer "In4.Cu")
		(net "P5E_CPU0_PE3_RX_DP<1>")
	)
	(segment
		(start 407.307796 -356.740714)
		(end 409.070556 -368.826034)
		(width 0.14732)
		(layer "In4.Cu")
		(net "P5E_CPU0_PE3_RX_DP<1>")
	)
	(segment
		(start 381.775716 -288.917126)
		(end 381.616712 -289.218116)
		(width 0.0889)
		(layer "In4.Cu")
		(net "P5E_CPU0_PE3_RX_DP<1>")
	)
	(segment
		(start 417.75507 -410.92374)
		(end 413.399986 -418.533326)
		(width 0.14732)
		(layer "In4.Cu")
		(net "P5E_CPU0_PE3_RX_DP<1>")
	)
	(segment
		(start 381.870712 -289.601402)
		(end 381.870712 -289.994086)
		(width 0.0889)
		(layer "In4.Cu")
		(net "P5E_CPU0_PE3_RX_DP<1>")
	)
	(segment
		(start 413.399986 -418.533326)
		(end 413.446214 -418.702998)
		(width 0.14732)
		(layer "In4.Cu")
		(net "P5E_CPU0_PE3_RX_DP<1>")
	)
	(segment
		(start 416.40887 -404.69312)
		(end 417.75507 -406.03932)
		(width 0.14732)
		(layer "In4.Cu")
		(net "P5E_CPU0_PE3_RX_DP<1>")
	)
	(segment
		(start 412.88843 -419.677596)
		(end 412.67126 -420.057072)
		(width 0.14732)
		(layer "In4.Cu")
		(net "P5E_CPU0_PE3_RX_DP<1>")
	)
	(segment
		(start 416.40887 -400.309842)
		(end 416.40887 -404.69312)
		(width 0.14732)
		(layer "In4.Cu")
		(net "P5E_CPU0_PE3_RX_DP<1>")
	)
	(segment
		(start 409.070556 -368.826034)
		(end 416.40887 -400.309842)
		(width 0.14732)
		(layer "In4.Cu")
		(net "P5E_CPU0_PE3_RX_DP<1>")
	)
	(segment
		(start 413.229044 -419.082474)
		(end 413.059118 -419.128702)
		(width 0.14732)
		(layer "In4.Cu")
		(net "P5E_CPU0_PE3_RX_DP<1>")
	)
	(segment
		(start 382.753616 -290.818062)
		(end 384.393694 -290.818062)
		(width 0.14732)
		(layer "In4.Cu")
		(net "P5E_CPU0_PE3_RX_DP<1>")
	)
	(segment
		(start 412.501334 -420.1033)
		(end 410.06649 -424.3578)
		(width 0.14732)
		(layer "In4.Cu")
		(net "P5E_CPU0_PE3_RX_DP<1>")
	)
	(segment
		(start 388.699502 -303.494948)
		(end 404.143464 -323.33057)
		(width 0.14732)
		(layer "In4.Cu")
		(net "P5E_CPU0_PE3_RX_DP<1>")
	)
	(segment
		(start 384.393694 -290.818062)
		(end 386.678678 -293.103046)
		(width 0.14732)
		(layer "In4.Cu")
		(net "P5E_CPU0_PE3_RX_DP<1>")
	)
	(segment
		(start 382.334008 -290.398454)
		(end 382.349502 -290.413948)
		(width 0.0889)
		(layer "In4.Cu")
		(net "P5E_CPU0_PE3_RX_DP<1>")
	)
	(segment
		(start 412.67126 -420.057072)
		(end 412.501334 -420.1033)
		(width 0.14732)
		(layer "In4.Cu")
		(net "P5E_CPU0_PE3_RX_DP<1>")
	)
	(segment
		(start 410.06649 -437.20512)
		(end 410.214064 -437.352694)
		(width 0.14732)
		(layer "In4.Cu")
		(net "P5E_CPU0_PE3_RX_DP<1>")
	)
	(segment
		(start 417.75507 -406.03932)
		(end 417.75507 -410.92374)
		(width 0.14732)
		(layer "In4.Cu")
		(net "P5E_CPU0_PE3_RX_DP<1>")
	)
	(segment
		(start 406.54859 -344.702638)
		(end 406.548082 -344.702892)
		(width 0.14732)
		(layer "In4.Cu")
		(net "P5E_CPU0_PE3_RX_DP<1>")
	)
	(arc
		(start 381.64643 -289.315652)
		(mid 381.766721 -289.426167)
		(end 381.852678 -289.56508)
		(width 0.0889)
		(layer "In4.Cu")
		(net "P5E_CPU0_PE3_RX_DP<1>")
	)
	(segment
		(start 368.148362 -289.195002)
		(end 368.148362 -289.807142)
		(width 0.13208)
		(layer "F.Cu")
		(net "P5E_CPU0_PE3_RX_DP<15>")
	)
	(segment
		(start 391.498328 -360.068114)
		(end 392.048746 -334.064102)
		(width 0.14732)
		(layer "In4.Cu")
		(net "P5E_CPU0_PE3_RX_DP<15>")
	)
	(segment
		(start 388.121144 -375.035064)
		(end 391.498328 -360.068114)
		(width 0.14732)
		(layer "In4.Cu")
		(net "P5E_CPU0_PE3_RX_DP<15>")
	)
	(segment
		(start 373.24919 -400.083782)
		(end 388.121144 -375.035064)
		(width 0.14732)
		(layer "In4.Cu")
		(net "P5E_CPU0_PE3_RX_DP<15>")
	)
	(segment
		(start 381.602742 -437.627014)
		(end 381.10033 -437.627014)
		(width 0.14732)
		(layer "In4.Cu")
		(net "P5E_CPU0_PE3_RX_DP<15>")
	)
	(segment
		(start 368.481356 -290.143438)
		(end 368.481356 -290.12134)
		(width 0.0889)
		(layer "In4.Cu")
		(net "P5E_CPU0_PE3_RX_DP<15>")
	)
	(segment
		(start 381.750062 -437.774334)
		(end 381.602742 -437.627014)
		(width 0.14732)
		(layer "In4.Cu")
		(net "P5E_CPU0_PE3_RX_DP<15>")
	)
	(segment
		(start 367.613692 -299.16374)
		(end 366.785906 -297.981624)
		(width 0.14732)
		(layer "In4.Cu")
		(net "P5E_CPU0_PE3_RX_DP<15>")
	)
	(segment
		(start 374.59539 -406.176988)
		(end 373.24919 -404.830788)
		(width 0.14732)
		(layer "In4.Cu")
		(net "P5E_CPU0_PE3_RX_DP<15>")
	)
	(segment
		(start 366.785906 -297.981624)
		(end 366.517936 -296.461688)
		(width 0.14732)
		(layer "In4.Cu")
		(net "P5E_CPU0_PE3_RX_DP<15>")
	)
	(segment
		(start 391.215118 -329.3364)
		(end 391.215118 -329.336908)
		(width 0.14732)
		(layer "In4.Cu")
		(net "P5E_CPU0_PE3_RX_DP<15>")
	)
	(segment
		(start 391.215118 -329.336908)
		(end 367.613692 -299.16374)
		(width 0.14732)
		(layer "In4.Cu")
		(net "P5E_CPU0_PE3_RX_DP<15>")
	)
	(segment
		(start 391.631932 -331.700124)
		(end 391.215118 -329.3364)
		(width 0.14732)
		(layer "In4.Cu")
		(net "P5E_CPU0_PE3_RX_DP<15>")
	)
	(segment
		(start 368.481356 -290.12134)
		(end 368.523266 -290.07943)
		(width 0.0889)
		(layer "In4.Cu")
		(net "P5E_CPU0_PE3_RX_DP<15>")
	)
	(segment
		(start 368.523266 -290.07943)
		(end 368.523266 -289.645344)
		(width 0.0889)
		(layer "In4.Cu")
		(net "P5E_CPU0_PE3_RX_DP<15>")
	)
	(segment
		(start 376.136154 -414.22574)
		(end 374.59539 -410.504894)
		(width 0.14732)
		(layer "In4.Cu")
		(net "P5E_CPU0_PE3_RX_DP<15>")
	)
	(segment
		(start 368.481356 -290.73602)
		(end 368.481356 -290.143438)
		(width 0.14732)
		(layer "In4.Cu")
		(net "P5E_CPU0_PE3_RX_DP<15>")
	)
	(segment
		(start 366.517936 -292.69944)
		(end 368.481356 -290.73602)
		(width 0.14732)
		(layer "In4.Cu")
		(net "P5E_CPU0_PE3_RX_DP<15>")
	)
	(segment
		(start 381.10033 -437.627014)
		(end 380.802642 -437.32958)
		(width 0.14732)
		(layer "In4.Cu")
		(net "P5E_CPU0_PE3_RX_DP<15>")
	)
	(segment
		(start 368.392202 -289.479736)
		(end 368.391948 -289.480244)
		(width 0.0889)
		(layer "In4.Cu")
		(net "P5E_CPU0_PE3_RX_DP<15>")
	)
	(segment
		(start 380.802642 -437.32958)
		(end 376.136154 -414.22574)
		(width 0.14732)
		(layer "In4.Cu")
		(net "P5E_CPU0_PE3_RX_DP<15>")
	)
	(segment
		(start 392.048746 -334.064102)
		(end 391.631932 -331.700124)
		(width 0.14732)
		(layer "In4.Cu")
		(net "P5E_CPU0_PE3_RX_DP<15>")
	)
	(segment
		(start 368.307366 -289.506152)
		(end 368.148362 -289.807142)
		(width 0.0889)
		(layer "In4.Cu")
		(net "P5E_CPU0_PE3_RX_DP<15>")
	)
	(segment
		(start 366.517936 -296.461688)
		(end 366.517936 -292.69944)
		(width 0.14732)
		(layer "In4.Cu")
		(net "P5E_CPU0_PE3_RX_DP<15>")
	)
	(segment
		(start 373.24919 -404.830788)
		(end 373.24919 -400.083782)
		(width 0.14732)
		(layer "In4.Cu")
		(net "P5E_CPU0_PE3_RX_DP<15>")
	)
	(segment
		(start 381.750062 -438.089802)
		(end 381.750062 -437.774334)
		(width 0.14732)
		(layer "In4.Cu")
		(net "P5E_CPU0_PE3_RX_DP<15>")
	)
	(segment
		(start 368.391948 -289.480244)
		(end 368.307366 -289.506152)
		(width 0.0889)
		(layer "In4.Cu")
		(net "P5E_CPU0_PE3_RX_DP<15>")
	)
	(segment
		(start 374.59539 -410.504894)
		(end 374.59539 -406.176988)
		(width 0.14732)
		(layer "In4.Cu")
		(net "P5E_CPU0_PE3_RX_DP<15>")
	)
	(arc
		(start 368.523266 -289.645344)
		(mid 368.468621 -289.553924)
		(end 368.392202 -289.479736)
		(width 0.0889)
		(layer "In4.Cu")
		(net "P5E_CPU0_PE3_RX_DP<15>")
	)
	(segment
		(start 369.558316 -288.381186)
		(end 369.558316 -288.917126)
		(width 0.13208)
		(layer "F.Cu")
		(net "P5E_CPU0_PE3_RX_DP<14>")
	)
	(segment
		(start 369.421156 -292.91788)
		(end 369.421156 -290.182046)
		(width 0.14732)
		(layer "In4.Cu")
		(net "P5E_CPU0_PE3_RX_DP<14>")
	)
	(segment
		(start 383.602738 -438.627012)
		(end 383.100326 -438.627012)
		(width 0.14732)
		(layer "In4.Cu")
		(net "P5E_CPU0_PE3_RX_DP<14>")
	)
	(segment
		(start 369.754404 -288.597848)
		(end 369.745514 -288.592768)
		(width 0.0889)
		(layer "In4.Cu")
		(net "P5E_CPU0_PE3_RX_DP<14>")
	)
	(segment
		(start 393.032234 -333.859886)
		(end 392.179302 -329.021948)
		(width 0.14732)
		(layer "In4.Cu")
		(net "P5E_CPU0_PE3_RX_DP<14>")
	)
	(segment
		(start 382.792478 -438.319164)
		(end 382.792478 -424.736768)
		(width 0.14732)
		(layer "In4.Cu")
		(net "P5E_CPU0_PE3_RX_DP<14>")
	)
	(segment
		(start 383.750058 -439.0898)
		(end 383.750058 -438.774332)
		(width 0.14732)
		(layer "In4.Cu")
		(net "P5E_CPU0_PE3_RX_DP<14>")
	)
	(segment
		(start 369.739418 -289.282886)
		(end 369.784376 -289.255962)
		(width 0.0889)
		(layer "In4.Cu")
		(net "P5E_CPU0_PE3_RX_DP<14>")
	)
	(segment
		(start 383.750058 -438.774332)
		(end 383.602738 -438.627012)
		(width 0.14732)
		(layer "In4.Cu")
		(net "P5E_CPU0_PE3_RX_DP<14>")
	)
	(segment
		(start 369.784376 -289.255962)
		(end 369.785138 -289.255962)
		(width 0.0889)
		(layer "In4.Cu")
		(net "P5E_CPU0_PE3_RX_DP<14>")
	)
	(segment
		(start 369.422934 -288.56813)
		(end 369.401852 -288.646108)
		(width 0.0889)
		(layer "In4.Cu")
		(net "P5E_CPU0_PE3_RX_DP<14>")
	)
	(segment
		(start 381.590296 -421.457628)
		(end 381.589534 -421.455342)
		(width 0.14732)
		(layer "In4.Cu")
		(net "P5E_CPU0_PE3_RX_DP<14>")
	)
	(segment
		(start 381.997966 -422.570402)
		(end 381.997712 -422.56964)
		(width 0.14732)
		(layer "In4.Cu")
		(net "P5E_CPU0_PE3_RX_DP<14>")
	)
	(segment
		(start 369.932966 -289.077908)
		(end 369.932966 -288.917126)
		(width 0.0889)
		(layer "In4.Cu")
		(net "P5E_CPU0_PE3_RX_DP<14>")
	)
	(segment
		(start 369.421156 -290.182046)
		(end 369.421156 -290.159948)
		(width 0.0889)
		(layer "In4.Cu")
		(net "P5E_CPU0_PE3_RX_DP<14>")
	)
	(segment
		(start 377.65863 -410.737558)
		(end 377.65863 -406.176988)
		(width 0.14732)
		(layer "In4.Cu")
		(net "P5E_CPU0_PE3_RX_DP<14>")
	)
	(segment
		(start 392.179302 -329.021948)
		(end 369.761516 -300.250606)
		(width 0.14732)
		(layer "In4.Cu")
		(net "P5E_CPU0_PE3_RX_DP<14>")
	)
	(segment
		(start 369.536218 -289.404552)
		(end 369.739418 -289.28314)
		(width 0.0889)
		(layer "In4.Cu")
		(net "P5E_CPU0_PE3_RX_DP<14>")
	)
	(segment
		(start 377.65863 -406.176988)
		(end 376.31243 -404.830788)
		(width 0.14732)
		(layer "In4.Cu")
		(net "P5E_CPU0_PE3_RX_DP<14>")
	)
	(segment
		(start 368.86388 -297.870372)
		(end 368.86388 -293.475156)
		(width 0.14732)
		(layer "In4.Cu")
		(net "P5E_CPU0_PE3_RX_DP<14>")
	)
	(segment
		(start 369.421156 -290.159948)
		(end 369.463066 -290.118038)
		(width 0.0889)
		(layer "In4.Cu")
		(net "P5E_CPU0_PE3_RX_DP<14>")
	)
	(segment
		(start 369.121944 -299.338238)
		(end 368.86388 -297.870372)
		(width 0.14732)
		(layer "In4.Cu")
		(net "P5E_CPU0_PE3_RX_DP<14>")
	)
	(segment
		(start 376.31243 -400.003772)
		(end 389.078724 -375.434352)
		(width 0.14732)
		(layer "In4.Cu")
		(net "P5E_CPU0_PE3_RX_DP<14>")
	)
	(segment
		(start 369.761516 -300.250606)
		(end 369.121944 -299.338238)
		(width 0.14732)
		(layer "In4.Cu")
		(net "P5E_CPU0_PE3_RX_DP<14>")
	)
	(segment
		(start 376.31243 -404.830788)
		(end 376.31243 -400.003772)
		(width 0.14732)
		(layer "In4.Cu")
		(net "P5E_CPU0_PE3_RX_DP<14>")
	)
	(segment
		(start 381.589534 -421.455342)
		(end 377.65863 -410.737558)
		(width 0.14732)
		(layer "In4.Cu")
		(net "P5E_CPU0_PE3_RX_DP<14>")
	)
	(segment
		(start 368.86388 -293.475156)
		(end 369.421156 -292.91788)
		(width 0.14732)
		(layer "In4.Cu")
		(net "P5E_CPU0_PE3_RX_DP<14>")
	)
	(segment
		(start 369.463066 -289.477958)
		(end 369.536218 -289.404552)
		(width 0.0889)
		(layer "In4.Cu")
		(net "P5E_CPU0_PE3_RX_DP<14>")
	)
	(segment
		(start 369.463066 -290.118038)
		(end 369.463066 -289.477958)
		(width 0.0889)
		(layer "In4.Cu")
		(net "P5E_CPU0_PE3_RX_DP<14>")
	)
	(segment
		(start 381.997712 -422.56964)
		(end 381.590296 -421.457628)
		(width 0.14732)
		(layer "In4.Cu")
		(net "P5E_CPU0_PE3_RX_DP<14>")
	)
	(segment
		(start 369.401852 -288.646108)
		(end 369.558316 -288.917126)
		(width 0.0889)
		(layer "In4.Cu")
		(net "P5E_CPU0_PE3_RX_DP<14>")
	)
	(segment
		(start 389.078724 -375.434352)
		(end 392.67003 -360.046016)
		(width 0.14732)
		(layer "In4.Cu")
		(net "P5E_CPU0_PE3_RX_DP<14>")
	)
	(segment
		(start 382.792478 -424.736768)
		(end 381.997966 -422.570402)
		(width 0.14732)
		(layer "In4.Cu")
		(net "P5E_CPU0_PE3_RX_DP<14>")
	)
	(segment
		(start 369.739418 -289.28314)
		(end 369.739418 -289.282886)
		(width 0.0889)
		(layer "In4.Cu")
		(net "P5E_CPU0_PE3_RX_DP<14>")
	)
	(segment
		(start 383.100326 -438.627012)
		(end 382.792478 -438.319164)
		(width 0.14732)
		(layer "In4.Cu")
		(net "P5E_CPU0_PE3_RX_DP<14>")
	)
	(segment
		(start 392.67003 -360.046016)
		(end 393.032234 -333.859886)
		(width 0.14732)
		(layer "In4.Cu")
		(net "P5E_CPU0_PE3_RX_DP<14>")
	)
	(arc
		(start 369.932966 -288.917126)
		(mid 369.885287 -288.734226)
		(end 369.754404 -288.597848)
		(width 0.0889)
		(layer "In4.Cu")
		(net "P5E_CPU0_PE3_RX_DP<14>")
	)
	(arc
		(start 369.745514 -288.592768)
		(mid 369.587026 -288.543835)
		(end 369.422934 -288.56813)
		(width 0.0889)
		(layer "In4.Cu")
		(net "P5E_CPU0_PE3_RX_DP<14>")
	)
	(arc
		(start 369.785138 -289.255962)
		(mid 369.871974 -289.177658)
		(end 369.932966 -289.077908)
		(width 0.0889)
		(layer "In4.Cu")
		(net "P5E_CPU0_PE3_RX_DP<14>")
	)
	(segment
		(start 370.027962 -289.195002)
		(end 370.027962 -289.807142)
		(width 0.13208)
		(layer "F.Cu")
		(net "P5E_CPU0_PE3_RX_DP<13>")
	)
	(segment
		(start 393.107672 -328.684128)
		(end 370.517674 -299.691806)
		(width 0.14732)
		(layer "In4.Cu")
		(net "P5E_CPU0_PE3_RX_DP<13>")
	)
	(segment
		(start 384.792474 -424.500548)
		(end 383.876804 -421.455342)
		(width 0.14732)
		(layer "In4.Cu")
		(net "P5E_CPU0_PE3_RX_DP<13>")
	)
	(segment
		(start 390.67486 -375.716038)
		(end 393.751816 -360.7562)
		(width 0.14732)
		(layer "In4.Cu")
		(net "P5E_CPU0_PE3_RX_DP<13>")
	)
	(segment
		(start 370.271802 -289.479736)
		(end 370.271548 -289.480244)
		(width 0.0889)
		(layer "In4.Cu")
		(net "P5E_CPU0_PE3_RX_DP<13>")
	)
	(segment
		(start 383.87655 -421.45458)
		(end 380.72187 -410.965904)
		(width 0.14732)
		(layer "In4.Cu")
		(net "P5E_CPU0_PE3_RX_DP<13>")
	)
	(segment
		(start 384.792474 -437.319166)
		(end 384.792474 -424.500548)
		(width 0.14732)
		(layer "In4.Cu")
		(net "P5E_CPU0_PE3_RX_DP<13>")
	)
	(segment
		(start 385.750054 -438.089802)
		(end 385.750054 -437.774334)
		(width 0.14732)
		(layer "In4.Cu")
		(net "P5E_CPU0_PE3_RX_DP<13>")
	)
	(segment
		(start 370.517674 -299.691806)
		(end 370.011706 -298.969684)
		(width 0.14732)
		(layer "In4.Cu")
		(net "P5E_CPU0_PE3_RX_DP<13>")
	)
	(segment
		(start 385.100322 -437.627014)
		(end 384.792474 -437.319166)
		(width 0.14732)
		(layer "In4.Cu")
		(net "P5E_CPU0_PE3_RX_DP<13>")
	)
	(segment
		(start 380.72187 -406.176988)
		(end 379.37567 -404.830788)
		(width 0.14732)
		(layer "In4.Cu")
		(net "P5E_CPU0_PE3_RX_DP<13>")
	)
	(segment
		(start 393.751816 -360.7562)
		(end 393.989052 -333.68361)
		(width 0.14732)
		(layer "In4.Cu")
		(net "P5E_CPU0_PE3_RX_DP<13>")
	)
	(segment
		(start 370.360956 -290.159948)
		(end 370.402866 -290.118038)
		(width 0.0889)
		(layer "In4.Cu")
		(net "P5E_CPU0_PE3_RX_DP<13>")
	)
	(segment
		(start 370.402866 -290.118038)
		(end 370.402866 -289.74288)
		(width 0.0889)
		(layer "In4.Cu")
		(net "P5E_CPU0_PE3_RX_DP<13>")
	)
	(segment
		(start 385.602734 -437.627014)
		(end 385.100322 -437.627014)
		(width 0.14732)
		(layer "In4.Cu")
		(net "P5E_CPU0_PE3_RX_DP<13>")
	)
	(segment
		(start 369.80368 -293.864792)
		(end 370.360956 -293.307516)
		(width 0.14732)
		(layer "In4.Cu")
		(net "P5E_CPU0_PE3_RX_DP<13>")
	)
	(segment
		(start 370.011706 -298.969684)
		(end 369.80368 -297.788076)
		(width 0.14732)
		(layer "In4.Cu")
		(net "P5E_CPU0_PE3_RX_DP<13>")
	)
	(segment
		(start 370.360956 -293.307516)
		(end 370.360956 -290.182046)
		(width 0.14732)
		(layer "In4.Cu")
		(net "P5E_CPU0_PE3_RX_DP<13>")
	)
	(segment
		(start 380.72187 -410.965904)
		(end 380.72187 -406.176988)
		(width 0.14732)
		(layer "In4.Cu")
		(net "P5E_CPU0_PE3_RX_DP<13>")
	)
	(segment
		(start 379.37567 -404.830788)
		(end 379.37567 -399.961608)
		(width 0.14732)
		(layer "In4.Cu")
		(net "P5E_CPU0_PE3_RX_DP<13>")
	)
	(segment
		(start 370.360956 -290.182046)
		(end 370.360956 -290.159948)
		(width 0.0889)
		(layer "In4.Cu")
		(net "P5E_CPU0_PE3_RX_DP<13>")
	)
	(segment
		(start 370.271548 -289.480244)
		(end 370.186966 -289.506152)
		(width 0.0889)
		(layer "In4.Cu")
		(net "P5E_CPU0_PE3_RX_DP<13>")
	)
	(segment
		(start 379.37567 -399.961608)
		(end 390.67486 -375.716038)
		(width 0.14732)
		(layer "In4.Cu")
		(net "P5E_CPU0_PE3_RX_DP<13>")
	)
	(segment
		(start 385.750054 -437.774334)
		(end 385.602734 -437.627014)
		(width 0.14732)
		(layer "In4.Cu")
		(net "P5E_CPU0_PE3_RX_DP<13>")
	)
	(segment
		(start 369.80368 -297.788076)
		(end 369.80368 -293.864792)
		(width 0.14732)
		(layer "In4.Cu")
		(net "P5E_CPU0_PE3_RX_DP<13>")
	)
	(segment
		(start 370.186966 -289.506152)
		(end 370.027962 -289.807142)
		(width 0.0889)
		(layer "In4.Cu")
		(net "P5E_CPU0_PE3_RX_DP<13>")
	)
	(segment
		(start 383.876804 -421.455342)
		(end 383.87655 -421.45458)
		(width 0.14732)
		(layer "In4.Cu")
		(net "P5E_CPU0_PE3_RX_DP<13>")
	)
	(segment
		(start 393.989052 -333.68361)
		(end 393.107672 -328.684128)
		(width 0.14732)
		(layer "In4.Cu")
		(net "P5E_CPU0_PE3_RX_DP<13>")
	)
	(arc
		(start 370.402866 -289.74288)
		(mid 370.368251 -289.595896)
		(end 370.271802 -289.479736)
		(width 0.0889)
		(layer "In4.Cu")
		(net "P5E_CPU0_PE3_RX_DP<13>")
	)
	(segment
		(start 371.437916 -288.381186)
		(end 371.437916 -288.917126)
		(width 0.13208)
		(layer "F.Cu")
		(net "P5E_CPU0_PE3_RX_DP<12>")
	)
	(segment
		(start 371.300502 -290.146486)
		(end 371.300502 -290.124388)
		(width 0.0889)
		(layer "In4.Cu")
		(net "P5E_CPU0_PE3_RX_DP<12>")
	)
	(segment
		(start 394.941044 -333.68742)
		(end 394.427202 -330.773278)
		(width 0.14732)
		(layer "In4.Cu")
		(net "P5E_CPU0_PE3_RX_DP<12>")
	)
	(segment
		(start 371.342412 -290.082478)
		(end 371.342412 -289.644328)
		(width 0.0889)
		(layer "In4.Cu")
		(net "P5E_CPU0_PE3_RX_DP<12>")
	)
	(segment
		(start 394.426948 -330.773024)
		(end 393.91336 -327.859136)
		(width 0.14732)
		(layer "In4.Cu")
		(net "P5E_CPU0_PE3_RX_DP<12>")
	)
	(segment
		(start 383.78511 -411.244542)
		(end 383.78511 -406.176988)
		(width 0.14732)
		(layer "In4.Cu")
		(net "P5E_CPU0_PE3_RX_DP<12>")
	)
	(segment
		(start 386.79247 -424.845988)
		(end 383.78511 -411.244542)
		(width 0.14732)
		(layer "In4.Cu")
		(net "P5E_CPU0_PE3_RX_DP<12>")
	)
	(segment
		(start 391.79119 -376.179588)
		(end 394.753846 -361.287822)
		(width 0.14732)
		(layer "In4.Cu")
		(net "P5E_CPU0_PE3_RX_DP<12>")
	)
	(segment
		(start 371.300502 -290.124388)
		(end 371.342412 -290.082478)
		(width 0.0889)
		(layer "In4.Cu")
		(net "P5E_CPU0_PE3_RX_DP<12>")
	)
	(segment
		(start 371.634004 -288.597848)
		(end 371.625114 -288.592768)
		(width 0.0889)
		(layer "In4.Cu")
		(net "P5E_CPU0_PE3_RX_DP<12>")
	)
	(segment
		(start 371.300502 -295.797224)
		(end 371.300502 -290.146486)
		(width 0.14732)
		(layer "In4.Cu")
		(net "P5E_CPU0_PE3_RX_DP<12>")
	)
	(segment
		(start 382.43891 -404.830788)
		(end 382.43891 -399.928842)
		(width 0.14732)
		(layer "In4.Cu")
		(net "P5E_CPU0_PE3_RX_DP<12>")
	)
	(segment
		(start 387.75005 -439.0898)
		(end 387.75005 -438.774332)
		(width 0.14732)
		(layer "In4.Cu")
		(net "P5E_CPU0_PE3_RX_DP<12>")
	)
	(segment
		(start 382.43891 -399.928842)
		(end 391.79119 -376.179588)
		(width 0.14732)
		(layer "In4.Cu")
		(net "P5E_CPU0_PE3_RX_DP<12>")
	)
	(segment
		(start 394.753846 -361.287822)
		(end 394.941044 -333.68742)
		(width 0.14732)
		(layer "In4.Cu")
		(net "P5E_CPU0_PE3_RX_DP<12>")
	)
	(segment
		(start 371.302534 -288.56813)
		(end 371.281452 -288.646108)
		(width 0.0889)
		(layer "In4.Cu")
		(net "P5E_CPU0_PE3_RX_DP<12>")
	)
	(segment
		(start 393.91336 -327.859136)
		(end 371.984524 -299.68317)
		(width 0.14732)
		(layer "In4.Cu")
		(net "P5E_CPU0_PE3_RX_DP<12>")
	)
	(segment
		(start 386.79247 -438.319164)
		(end 386.79247 -424.845988)
		(width 0.14732)
		(layer "In4.Cu")
		(net "P5E_CPU0_PE3_RX_DP<12>")
	)
	(segment
		(start 387.75005 -438.774332)
		(end 387.60273 -438.627012)
		(width 0.14732)
		(layer "In4.Cu")
		(net "P5E_CPU0_PE3_RX_DP<12>")
	)
	(segment
		(start 387.60273 -438.627012)
		(end 387.100318 -438.627012)
		(width 0.14732)
		(layer "In4.Cu")
		(net "P5E_CPU0_PE3_RX_DP<12>")
	)
	(segment
		(start 383.78511 -406.176988)
		(end 382.43891 -404.830788)
		(width 0.14732)
		(layer "In4.Cu")
		(net "P5E_CPU0_PE3_RX_DP<12>")
	)
	(segment
		(start 371.812566 -289.077908)
		(end 371.812566 -288.917126)
		(width 0.0889)
		(layer "In4.Cu")
		(net "P5E_CPU0_PE3_RX_DP<12>")
	)
	(segment
		(start 371.281452 -288.646108)
		(end 371.437916 -288.917126)
		(width 0.0889)
		(layer "In4.Cu")
		(net "P5E_CPU0_PE3_RX_DP<12>")
	)
	(segment
		(start 394.427202 -330.773278)
		(end 394.426948 -330.773024)
		(width 0.14732)
		(layer "In4.Cu")
		(net "P5E_CPU0_PE3_RX_DP<12>")
	)
	(segment
		(start 387.100318 -438.627012)
		(end 386.79247 -438.319164)
		(width 0.14732)
		(layer "In4.Cu")
		(net "P5E_CPU0_PE3_RX_DP<12>")
	)
	(segment
		(start 371.984524 -299.68317)
		(end 371.300502 -295.797224)
		(width 0.14732)
		(layer "In4.Cu")
		(net "P5E_CPU0_PE3_RX_DP<12>")
	)
	(arc
		(start 371.812566 -288.917126)
		(mid 371.764887 -288.734226)
		(end 371.634004 -288.597848)
		(width 0.0889)
		(layer "In4.Cu")
		(net "P5E_CPU0_PE3_RX_DP<12>")
	)
	(arc
		(start 371.625114 -288.592768)
		(mid 371.466626 -288.543835)
		(end 371.302534 -288.56813)
		(width 0.0889)
		(layer "In4.Cu")
		(net "P5E_CPU0_PE3_RX_DP<12>")
	)
	(arc
		(start 371.342412 -289.644328)
		(mid 371.346198 -289.606869)
		(end 371.357398 -289.570922)
		(width 0.0889)
		(layer "In4.Cu")
		(net "P5E_CPU0_PE3_RX_DP<12>")
	)
	(arc
		(start 371.628162 -289.277806)
		(mid 371.737558 -289.193709)
		(end 371.812566 -289.077908)
		(width 0.0889)
		(layer "In4.Cu")
		(net "P5E_CPU0_PE3_RX_DP<12>")
	)
	(arc
		(start 371.357398 -289.570922)
		(mid 371.467655 -289.401162)
		(end 371.628162 -289.277806)
		(width 0.0889)
		(layer "In4.Cu")
		(net "P5E_CPU0_PE3_RX_DP<12>")
	)
	(segment
		(start 372.377716 -288.381186)
		(end 372.377716 -288.917126)
		(width 0.13208)
		(layer "F.Cu")
		(net "P5E_CPU0_PE3_RX_DP<11>")
	)
	(segment
		(start 372.252748 -289.315652)
		(end 372.264686 -289.32759)
		(width 0.0889)
		(layer "In4.Cu")
		(net "P5E_CPU0_PE3_RX_DP<11>")
	)
	(segment
		(start 372.514622 -290.146486)
		(end 372.514622 -295.60901)
		(width 0.14732)
		(layer "In4.Cu")
		(net "P5E_CPU0_PE3_RX_DP<11>")
	)
	(segment
		(start 389.750046 -437.141366)
		(end 389.750046 -436.889906)
		(width 0.14732)
		(layer "In4.Cu")
		(net "P5E_CPU0_PE3_RX_DP<11>")
	)
	(segment
		(start 388.498334 -420.735506)
		(end 389.066786 -424.632882)
		(width 0.14732)
		(layer "In4.Cu")
		(net "P5E_CPU0_PE3_RX_DP<11>")
	)
	(segment
		(start 388.208774 -418.75456)
		(end 388.367524 -418.87267)
		(width 0.14732)
		(layer "In4.Cu")
		(net "P5E_CPU0_PE3_RX_DP<11>")
	)
	(segment
		(start 388.563104 -420.21252)
		(end 388.61619 -420.577264)
		(width 0.14732)
		(layer "In4.Cu")
		(net "P5E_CPU0_PE3_RX_DP<11>")
	)
	(segment
		(start 372.514622 -295.60901)
		(end 373.140224 -299.160184)
		(width 0.14732)
		(layer "In4.Cu")
		(net "P5E_CPU0_PE3_RX_DP<11>")
	)
	(segment
		(start 372.472458 -289.741102)
		(end 372.472458 -290.082224)
		(width 0.0889)
		(layer "In4.Cu")
		(net "P5E_CPU0_PE3_RX_DP<11>")
	)
	(segment
		(start 387.12267 -411.303724)
		(end 388.209028 -418.754306)
		(width 0.14732)
		(layer "In4.Cu")
		(net "P5E_CPU0_PE3_RX_DP<11>")
	)
	(segment
		(start 373.140224 -299.160184)
		(end 395.076426 -327.34123)
		(width 0.14732)
		(layer "In4.Cu")
		(net "P5E_CPU0_PE3_RX_DP<11>")
	)
	(segment
		(start 396.155926 -333.462376)
		(end 396.32382 -360.54157)
		(width 0.14732)
		(layer "In4.Cu")
		(net "P5E_CPU0_PE3_RX_DP<11>")
	)
	(segment
		(start 393.243562 -376.739658)
		(end 385.77647 -399.845022)
		(width 0.14732)
		(layer "In4.Cu")
		(net "P5E_CPU0_PE3_RX_DP<11>")
	)
	(segment
		(start 388.61619 -420.577264)
		(end 388.498334 -420.735506)
		(width 0.14732)
		(layer "In4.Cu")
		(net "P5E_CPU0_PE3_RX_DP<11>")
	)
	(segment
		(start 387.12267 -406.063196)
		(end 387.12267 -411.303724)
		(width 0.14732)
		(layer "In4.Cu")
		(net "P5E_CPU0_PE3_RX_DP<11>")
	)
	(segment
		(start 372.514622 -290.124388)
		(end 372.514622 -290.146486)
		(width 0.0889)
		(layer "In4.Cu")
		(net "P5E_CPU0_PE3_RX_DP<11>")
	)
	(segment
		(start 388.367524 -418.87267)
		(end 388.42061 -419.237414)
		(width 0.14732)
		(layer "In4.Cu")
		(net "P5E_CPU0_PE3_RX_DP<11>")
	)
	(segment
		(start 389.538718 -437.352694)
		(end 389.750046 -437.141366)
		(width 0.14732)
		(layer "In4.Cu")
		(net "P5E_CPU0_PE3_RX_DP<11>")
	)
	(segment
		(start 372.472458 -290.082224)
		(end 372.514622 -290.124388)
		(width 0.0889)
		(layer "In4.Cu")
		(net "P5E_CPU0_PE3_RX_DP<11>")
	)
	(segment
		(start 372.24843 -289.315652)
		(end 372.252748 -289.315652)
		(width 0.0889)
		(layer "In4.Cu")
		(net "P5E_CPU0_PE3_RX_DP<11>")
	)
	(segment
		(start 389.066786 -424.632882)
		(end 389.066786 -437.205374)
		(width 0.14732)
		(layer "In4.Cu")
		(net "P5E_CPU0_PE3_RX_DP<11>")
	)
	(segment
		(start 372.24843 -289.315398)
		(end 372.24843 -289.315652)
		(width 0.0889)
		(layer "In4.Cu")
		(net "P5E_CPU0_PE3_RX_DP<11>")
	)
	(segment
		(start 396.32382 -360.54157)
		(end 393.243562 -376.739658)
		(width 0.14732)
		(layer "In4.Cu")
		(net "P5E_CPU0_PE3_RX_DP<11>")
	)
	(segment
		(start 388.404608 -420.094664)
		(end 388.563104 -420.21252)
		(width 0.14732)
		(layer "In4.Cu")
		(net "P5E_CPU0_PE3_RX_DP<11>")
	)
	(segment
		(start 389.066786 -437.205374)
		(end 389.214106 -437.352694)
		(width 0.14732)
		(layer "In4.Cu")
		(net "P5E_CPU0_PE3_RX_DP<11>")
	)
	(segment
		(start 372.248684 -289.315144)
		(end 372.24843 -289.315398)
		(width 0.0889)
		(layer "In4.Cu")
		(net "P5E_CPU0_PE3_RX_DP<11>")
	)
	(segment
		(start 388.302754 -419.395402)
		(end 388.404608 -420.094664)
		(width 0.14732)
		(layer "In4.Cu")
		(net "P5E_CPU0_PE3_RX_DP<11>")
	)
	(segment
		(start 388.209028 -418.754306)
		(end 388.208774 -418.75456)
		(width 0.14732)
		(layer "In4.Cu")
		(net "P5E_CPU0_PE3_RX_DP<11>")
	)
	(segment
		(start 372.377716 -288.917126)
		(end 372.218712 -289.218116)
		(width 0.0889)
		(layer "In4.Cu")
		(net "P5E_CPU0_PE3_RX_DP<11>")
	)
	(segment
		(start 388.42061 -419.237414)
		(end 388.302754 -419.395402)
		(width 0.14732)
		(layer "In4.Cu")
		(net "P5E_CPU0_PE3_RX_DP<11>")
	)
	(segment
		(start 385.77647 -404.716996)
		(end 387.12267 -406.063196)
		(width 0.14732)
		(layer "In4.Cu")
		(net "P5E_CPU0_PE3_RX_DP<11>")
	)
	(segment
		(start 385.77647 -399.845022)
		(end 385.77647 -404.716996)
		(width 0.14732)
		(layer "In4.Cu")
		(net "P5E_CPU0_PE3_RX_DP<11>")
	)
	(segment
		(start 395.076426 -327.34123)
		(end 396.155926 -333.462376)
		(width 0.14732)
		(layer "In4.Cu")
		(net "P5E_CPU0_PE3_RX_DP<11>")
	)
	(segment
		(start 389.214106 -437.352694)
		(end 389.538718 -437.352694)
		(width 0.14732)
		(layer "In4.Cu")
		(net "P5E_CPU0_PE3_RX_DP<11>")
	)
	(segment
		(start 372.218712 -289.218116)
		(end 372.248684 -289.315144)
		(width 0.0889)
		(layer "In4.Cu")
		(net "P5E_CPU0_PE3_RX_DP<11>")
	)
	(arc
		(start 372.264686 -289.32759)
		(mid 372.417598 -289.509713)
		(end 372.472458 -289.741102)
		(width 0.0889)
		(layer "In4.Cu")
		(net "P5E_CPU0_PE3_RX_DP<11>")
	)
	(segment
		(start 372.847362 -287.567116)
		(end 372.847362 -288.102802)
		(width 0.13208)
		(layer "F.Cu")
		(net "P5E_CPU0_PE3_RX_DP<10>")
	)
	(segment
		(start 372.847362 -288.102802)
		(end 372.847616 -288.103056)
		(width 0.13208)
		(layer "F.Cu")
		(net "P5E_CPU0_PE3_RX_DP<10>")
	)
	(segment
		(start 397.095726 -333.379318)
		(end 397.351504 -360.582464)
		(width 0.14732)
		(layer "In4.Cu")
		(net "P5E_CPU0_PE3_RX_DP<10>")
	)
	(segment
		(start 373.623078 -289.43173)
		(end 373.412258 -289.64255)
		(width 0.0889)
		(layer "In4.Cu")
		(net "P5E_CPU0_PE3_RX_DP<10>")
	)
	(segment
		(start 391.066782 -424.824652)
		(end 391.066782 -438.205372)
		(width 0.14732)
		(layer "In4.Cu")
		(net "P5E_CPU0_PE3_RX_DP<10>")
	)
	(segment
		(start 390.18591 -406.063196)
		(end 390.18591 -412.359348)
		(width 0.14732)
		(layer "In4.Cu")
		(net "P5E_CPU0_PE3_RX_DP<10>")
	)
	(segment
		(start 395.95933 -326.936608)
		(end 397.095726 -333.379318)
		(width 0.14732)
		(layer "In4.Cu")
		(net "P5E_CPU0_PE3_RX_DP<10>")
	)
	(segment
		(start 373.454422 -290.146486)
		(end 373.454422 -295.368726)
		(width 0.14732)
		(layer "In4.Cu")
		(net "P5E_CPU0_PE3_RX_DP<10>")
	)
	(segment
		(start 390.18591 -412.359348)
		(end 391.067544 -424.760136)
		(width 0.14732)
		(layer "In4.Cu")
		(net "P5E_CPU0_PE3_RX_DP<10>")
	)
	(segment
		(start 391.57529 -438.352692)
		(end 391.750042 -438.17794)
		(width 0.14732)
		(layer "In4.Cu")
		(net "P5E_CPU0_PE3_RX_DP<10>")
	)
	(segment
		(start 397.351504 -360.582464)
		(end 394.8811 -376.759216)
		(width 0.14732)
		(layer "In4.Cu")
		(net "P5E_CPU0_PE3_RX_DP<10>")
	)
	(segment
		(start 374.064276 -298.831508)
		(end 395.95933 -326.936608)
		(width 0.14732)
		(layer "In4.Cu")
		(net "P5E_CPU0_PE3_RX_DP<10>")
	)
	(segment
		(start 391.067544 -424.760136)
		(end 391.066782 -424.824652)
		(width 0.14732)
		(layer "In4.Cu")
		(net "P5E_CPU0_PE3_RX_DP<10>")
	)
	(segment
		(start 373.00408 -288.374074)
		(end 373.093234 -288.39795)
		(width 0.0889)
		(layer "In4.Cu")
		(net "P5E_CPU0_PE3_RX_DP<10>")
	)
	(segment
		(start 388.846568 -404.723854)
		(end 390.18591 -406.063196)
		(width 0.14732)
		(layer "In4.Cu")
		(net "P5E_CPU0_PE3_RX_DP<10>")
	)
	(segment
		(start 391.066782 -438.205372)
		(end 391.214102 -438.352692)
		(width 0.14732)
		(layer "In4.Cu")
		(net "P5E_CPU0_PE3_RX_DP<10>")
	)
	(segment
		(start 373.882666 -288.898584)
		(end 373.882666 -289.114484)
		(width 0.0889)
		(layer "In4.Cu")
		(net "P5E_CPU0_PE3_RX_DP<10>")
	)
	(segment
		(start 372.847616 -288.103056)
		(end 373.00408 -288.374074)
		(width 0.0889)
		(layer "In4.Cu")
		(net "P5E_CPU0_PE3_RX_DP<10>")
	)
	(segment
		(start 391.750042 -438.17794)
		(end 391.750042 -437.889904)
		(width 0.14732)
		(layer "In4.Cu")
		(net "P5E_CPU0_PE3_RX_DP<10>")
	)
	(segment
		(start 373.454422 -290.13531)
		(end 373.454422 -290.146486)
		(width 0.0889)
		(layer "In4.Cu")
		(net "P5E_CPU0_PE3_RX_DP<10>")
	)
	(segment
		(start 373.412258 -290.093146)
		(end 373.454422 -290.13531)
		(width 0.0889)
		(layer "In4.Cu")
		(net "P5E_CPU0_PE3_RX_DP<10>")
	)
	(segment
		(start 373.412258 -289.64255)
		(end 373.412258 -290.093146)
		(width 0.0889)
		(layer "In4.Cu")
		(net "P5E_CPU0_PE3_RX_DP<10>")
	)
	(segment
		(start 391.214102 -438.352692)
		(end 391.57529 -438.352692)
		(width 0.14732)
		(layer "In4.Cu")
		(net "P5E_CPU0_PE3_RX_DP<10>")
	)
	(segment
		(start 388.846568 -399.684748)
		(end 388.846568 -404.723854)
		(width 0.14732)
		(layer "In4.Cu")
		(net "P5E_CPU0_PE3_RX_DP<10>")
	)
	(segment
		(start 373.454422 -295.368726)
		(end 374.064276 -298.831508)
		(width 0.14732)
		(layer "In4.Cu")
		(net "P5E_CPU0_PE3_RX_DP<10>")
	)
	(segment
		(start 394.8811 -376.759216)
		(end 388.846568 -399.684748)
		(width 0.14732)
		(layer "In4.Cu")
		(net "P5E_CPU0_PE3_RX_DP<10>")
	)
	(segment
		(start 373.623586 -289.431476)
		(end 373.623078 -289.43173)
		(width 0.0889)
		(layer "In4.Cu")
		(net "P5E_CPU0_PE3_RX_DP<10>")
	)
	(arc
		(start 373.600218 -288.427414)
		(mid 373.802504 -288.626395)
		(end 373.882666 -288.898584)
		(width 0.0889)
		(layer "In4.Cu")
		(net "P5E_CPU0_PE3_RX_DP<10>")
	)
	(arc
		(start 373.093234 -288.39795)
		(mid 373.102975 -288.393795)
		(end 373.112792 -288.389822)
		(width 0.0889)
		(layer "In4.Cu")
		(net "P5E_CPU0_PE3_RX_DP<10>")
	)
	(arc
		(start 373.882666 -289.114484)
		(mid 373.7811 -289.295854)
		(end 373.623586 -289.431476)
		(width 0.0889)
		(layer "In4.Cu")
		(net "P5E_CPU0_PE3_RX_DP<10>")
	)
	(arc
		(start 373.112792 -288.389822)
		(mid 373.360772 -288.35321)
		(end 373.600218 -288.427414)
		(width 0.0889)
		(layer "In4.Cu")
		(net "P5E_CPU0_PE3_RX_DP<10>")
	)
	(segment
		(start 383.655062 -288.916872)
		(end 383.655316 -288.917126)
		(width 0.13208)
		(layer "F.Cu")
		(net "P5E_CPU0_PE3_RX_DP<0>")
	)
	(segment
		(start 383.655062 -288.381186)
		(end 383.655062 -288.916872)
		(width 0.13208)
		(layer "F.Cu")
		(net "P5E_CPU0_PE3_RX_DP<0>")
	)
	(segment
		(start 411.792166 -438.31891)
		(end 411.792166 -424.348656)
		(width 0.14732)
		(layer "In4.Cu")
		(net "P5E_CPU0_PE3_RX_DP<0>")
	)
	(segment
		(start 384.0988 -288.830258)
		(end 383.920492 -288.65195)
		(width 0.0889)
		(layer "In4.Cu")
		(net "P5E_CPU0_PE3_RX_DP<0>")
	)
	(segment
		(start 386.181092 -291.64534)
		(end 385.920488 -291.384736)
		(width 0.14732)
		(layer "In4.Cu")
		(net "P5E_CPU0_PE3_RX_DP<0>")
	)
	(segment
		(start 384.779266 -290.045902)
		(end 384.779266 -289.986974)
		(width 0.0889)
		(layer "In4.Cu")
		(net "P5E_CPU0_PE3_RX_DP<0>")
	)
	(segment
		(start 412.100268 -438.627012)
		(end 411.792166 -438.31891)
		(width 0.14732)
		(layer "In4.Cu")
		(net "P5E_CPU0_PE3_RX_DP<0>")
	)
	(segment
		(start 389.322818 -303.192942)
		(end 388.624826 -299.234606)
		(width 0.14732)
		(layer "In4.Cu")
		(net "P5E_CPU0_PE3_RX_DP<0>")
	)
	(segment
		(start 419.19779 -400.036538)
		(end 409.692602 -368.440716)
		(width 0.14732)
		(layer "In4.Cu")
		(net "P5E_CPU0_PE3_RX_DP<0>")
	)
	(segment
		(start 385.920488 -291.384736)
		(end 385.920488 -291.187124)
		(width 0.14732)
		(layer "In4.Cu")
		(net "P5E_CPU0_PE3_RX_DP<0>")
	)
	(segment
		(start 384.779266 -289.986974)
		(end 384.308604 -289.516312)
		(width 0.0889)
		(layer "In4.Cu")
		(net "P5E_CPU0_PE3_RX_DP<0>")
	)
	(segment
		(start 388.624826 -299.234606)
		(end 388.624826 -295.926256)
		(width 0.14732)
		(layer "In4.Cu")
		(net "P5E_CPU0_PE3_RX_DP<0>")
	)
	(segment
		(start 385.920488 -291.187124)
		(end 384.79476 -290.061396)
		(width 0.14732)
		(layer "In4.Cu")
		(net "P5E_CPU0_PE3_RX_DP<0>")
	)
	(segment
		(start 387.185916 -292.452552)
		(end 386.378704 -291.64534)
		(width 0.14732)
		(layer "In4.Cu")
		(net "P5E_CPU0_PE3_RX_DP<0>")
	)
	(segment
		(start 411.792166 -424.348656)
		(end 420.54399 -410.434028)
		(width 0.14732)
		(layer "In4.Cu")
		(net "P5E_CPU0_PE3_RX_DP<0>")
	)
	(segment
		(start 386.378704 -291.64534)
		(end 386.181092 -291.64534)
		(width 0.14732)
		(layer "In4.Cu")
		(net "P5E_CPU0_PE3_RX_DP<0>")
	)
	(segment
		(start 404.780496 -323.047614)
		(end 389.323072 -303.194212)
		(width 0.14732)
		(layer "In4.Cu")
		(net "P5E_CPU0_PE3_RX_DP<0>")
	)
	(segment
		(start 412.75 -439.0898)
		(end 412.75 -438.774332)
		(width 0.14732)
		(layer "In4.Cu")
		(net "P5E_CPU0_PE3_RX_DP<0>")
	)
	(segment
		(start 383.51968 -288.567368)
		(end 383.519934 -288.56813)
		(width 0.0889)
		(layer "In4.Cu")
		(net "P5E_CPU0_PE3_RX_DP<0>")
	)
	(segment
		(start 384.79476 -290.061396)
		(end 384.779266 -290.045902)
		(width 0.0889)
		(layer "In4.Cu")
		(net "P5E_CPU0_PE3_RX_DP<0>")
	)
	(segment
		(start 412.75 -438.774332)
		(end 412.60268 -438.627012)
		(width 0.14732)
		(layer "In4.Cu")
		(net "P5E_CPU0_PE3_RX_DP<0>")
	)
	(segment
		(start 407.95956 -355.757988)
		(end 406.600914 -333.36611)
		(width 0.14732)
		(layer "In4.Cu")
		(net "P5E_CPU0_PE3_RX_DP<0>")
	)
	(segment
		(start 389.323072 -303.194212)
		(end 389.322818 -303.192942)
		(width 0.14732)
		(layer "In4.Cu")
		(net "P5E_CPU0_PE3_RX_DP<0>")
	)
	(segment
		(start 406.600914 -333.36611)
		(end 406.601422 -333.375508)
		(width 0.14732)
		(layer "In4.Cu")
		(net "P5E_CPU0_PE3_RX_DP<0>")
	)
	(segment
		(start 409.692602 -368.440716)
		(end 408.044396 -357.147368)
		(width 0.14732)
		(layer "In4.Cu")
		(net "P5E_CPU0_PE3_RX_DP<0>")
	)
	(segment
		(start 412.60268 -438.627012)
		(end 412.100268 -438.627012)
		(width 0.14732)
		(layer "In4.Cu")
		(net "P5E_CPU0_PE3_RX_DP<0>")
	)
	(segment
		(start 406.601422 -333.375508)
		(end 404.780496 -323.047614)
		(width 0.14732)
		(layer "In4.Cu")
		(net "P5E_CPU0_PE3_RX_DP<0>")
	)
	(segment
		(start 420.54399 -410.434028)
		(end 420.54399 -406.176988)
		(width 0.14732)
		(layer "In4.Cu")
		(net "P5E_CPU0_PE3_RX_DP<0>")
	)
	(segment
		(start 384.308604 -289.516312)
		(end 384.0988 -288.830258)
		(width 0.0889)
		(layer "In4.Cu")
		(net "P5E_CPU0_PE3_RX_DP<0>")
	)
	(segment
		(start 419.19779 -404.830788)
		(end 419.19779 -400.036538)
		(width 0.14732)
		(layer "In4.Cu")
		(net "P5E_CPU0_PE3_RX_DP<0>")
	)
	(segment
		(start 420.54399 -406.176988)
		(end 419.19779 -404.830788)
		(width 0.14732)
		(layer "In4.Cu")
		(net "P5E_CPU0_PE3_RX_DP<0>")
	)
	(segment
		(start 388.624826 -295.926256)
		(end 387.185916 -292.452552)
		(width 0.14732)
		(layer "In4.Cu")
		(net "P5E_CPU0_PE3_RX_DP<0>")
	)
	(segment
		(start 383.519934 -288.56813)
		(end 383.498852 -288.646108)
		(width 0.0889)
		(layer "In4.Cu")
		(net "P5E_CPU0_PE3_RX_DP<0>")
	)
	(segment
		(start 408.016964 -356.697534)
		(end 407.95956 -355.757988)
		(width 0.14732)
		(layer "In4.Cu")
		(net "P5E_CPU0_PE3_RX_DP<0>")
	)
	(segment
		(start 383.498852 -288.646108)
		(end 383.655316 -288.917126)
		(width 0.0889)
		(layer "In4.Cu")
		(net "P5E_CPU0_PE3_RX_DP<0>")
	)
	(segment
		(start 408.044396 -357.147368)
		(end 408.016964 -356.697534)
		(width 0.14732)
		(layer "In4.Cu")
		(net "P5E_CPU0_PE3_RX_DP<0>")
	)
	(arc
		(start 383.920492 -288.65195)
		(mid 383.883587 -288.619556)
		(end 383.842768 -288.59226)
		(width 0.0889)
		(layer "In4.Cu")
		(net "P5E_CPU0_PE3_RX_DP<0>")
	)
	(arc
		(start 383.842768 -288.59226)
		(mid 383.684057 -288.543094)
		(end 383.51968 -288.567368)
		(width 0.0889)
		(layer "In4.Cu")
		(net "P5E_CPU0_PE3_RX_DP<0>")
	)
	(segment
		(start 373.787162 -289.195002)
		(end 373.787162 -289.807142)
		(width 0.13208)
		(layer "F.Cu")
		(net "P5E_CPU0_PE3_RX_DN<9>")
	)
	(segment
		(start 397.761714 -333.299562)
		(end 396.590774 -326.658478)
		(width 0.14732)
		(layer "In4.Cu")
		(net "P5E_CPU0_PE3_RX_DN<9>")
	)
	(segment
		(start 391.62863 -404.830788)
		(end 391.62863 -399.34769)
		(width 0.14732)
		(layer "In4.Cu")
		(net "P5E_CPU0_PE3_RX_DN<9>")
	)
	(segment
		(start 373.946166 -289.506152)
		(end 373.787162 -289.807142)
		(width 0.0889)
		(layer "In4.Cu")
		(net "P5E_CPU0_PE3_RX_DN<9>")
	)
	(segment
		(start 393.750038 -438.089802)
		(end 393.750038 -437.774334)
		(width 0.14732)
		(layer "In4.Cu")
		(net "P5E_CPU0_PE3_RX_DN<9>")
	)
	(segment
		(start 398.098772 -360.312462)
		(end 397.761714 -333.299562)
		(width 0.14732)
		(layer "In4.Cu")
		(net "P5E_CPU0_PE3_RX_DN<9>")
	)
	(segment
		(start 374.690386 -298.546266)
		(end 374.120156 -295.311068)
		(width 0.14732)
		(layer "In4.Cu")
		(net "P5E_CPU0_PE3_RX_DN<9>")
	)
	(segment
		(start 374.030748 -289.480244)
		(end 373.946166 -289.506152)
		(width 0.0889)
		(layer "In4.Cu")
		(net "P5E_CPU0_PE3_RX_DN<9>")
	)
	(segment
		(start 392.97483 -406.176988)
		(end 391.62863 -404.830788)
		(width 0.14732)
		(layer "In4.Cu")
		(net "P5E_CPU0_PE3_RX_DN<9>")
	)
	(segment
		(start 393.100306 -437.627014)
		(end 392.792458 -437.319166)
		(width 0.14732)
		(layer "In4.Cu")
		(net "P5E_CPU0_PE3_RX_DN<9>")
	)
	(segment
		(start 396.590774 -326.658478)
		(end 374.690386 -298.546266)
		(width 0.14732)
		(layer "In4.Cu")
		(net "P5E_CPU0_PE3_RX_DN<9>")
	)
	(segment
		(start 393.750038 -437.774334)
		(end 393.602718 -437.627014)
		(width 0.14732)
		(layer "In4.Cu")
		(net "P5E_CPU0_PE3_RX_DN<9>")
	)
	(segment
		(start 374.120156 -290.146486)
		(end 374.120156 -290.124388)
		(width 0.0889)
		(layer "In4.Cu")
		(net "P5E_CPU0_PE3_RX_DN<9>")
	)
	(segment
		(start 374.162066 -290.082478)
		(end 374.162066 -289.741102)
		(width 0.0889)
		(layer "In4.Cu")
		(net "P5E_CPU0_PE3_RX_DN<9>")
	)
	(segment
		(start 391.62863 -399.34769)
		(end 396.073122 -376.828304)
		(width 0.14732)
		(layer "In4.Cu")
		(net "P5E_CPU0_PE3_RX_DN<9>")
	)
	(segment
		(start 392.97483 -410.341572)
		(end 392.97483 -406.176988)
		(width 0.14732)
		(layer "In4.Cu")
		(net "P5E_CPU0_PE3_RX_DN<9>")
	)
	(segment
		(start 393.602718 -437.627014)
		(end 393.100306 -437.627014)
		(width 0.14732)
		(layer "In4.Cu")
		(net "P5E_CPU0_PE3_RX_DN<9>")
	)
	(segment
		(start 392.823954 -411.931866)
		(end 392.97483 -410.341572)
		(width 0.14732)
		(layer "In4.Cu")
		(net "P5E_CPU0_PE3_RX_DN<9>")
	)
	(segment
		(start 374.120156 -290.124388)
		(end 374.162066 -290.082478)
		(width 0.0889)
		(layer "In4.Cu")
		(net "P5E_CPU0_PE3_RX_DN<9>")
	)
	(segment
		(start 392.792458 -424.21048)
		(end 392.823954 -411.931866)
		(width 0.14732)
		(layer "In4.Cu")
		(net "P5E_CPU0_PE3_RX_DN<9>")
	)
	(segment
		(start 396.073122 -376.828304)
		(end 398.098772 -360.312462)
		(width 0.14732)
		(layer "In4.Cu")
		(net "P5E_CPU0_PE3_RX_DN<9>")
	)
	(segment
		(start 374.120156 -295.311068)
		(end 374.120156 -290.146486)
		(width 0.14732)
		(layer "In4.Cu")
		(net "P5E_CPU0_PE3_RX_DN<9>")
	)
	(segment
		(start 374.031002 -289.480244)
		(end 374.030748 -289.480244)
		(width 0.0889)
		(layer "In4.Cu")
		(net "P5E_CPU0_PE3_RX_DN<9>")
	)
	(segment
		(start 392.792458 -437.319166)
		(end 392.792458 -424.21048)
		(width 0.14732)
		(layer "In4.Cu")
		(net "P5E_CPU0_PE3_RX_DN<9>")
	)
	(arc
		(start 374.162066 -289.741102)
		(mid 374.127458 -289.595136)
		(end 374.031002 -289.480244)
		(width 0.0889)
		(layer "In4.Cu")
		(net "P5E_CPU0_PE3_RX_DN<9>")
	)
	(segment
		(start 375.197116 -288.381186)
		(end 375.197116 -288.917126)
		(width 0.13208)
		(layer "F.Cu")
		(net "P5E_CPU0_PE3_RX_DN<8>")
	)
	(segment
		(start 398.783302 -332.982062)
		(end 397.608552 -326.32142)
		(width 0.14732)
		(layer "In4.Cu")
		(net "P5E_CPU0_PE3_RX_DN<8>")
	)
	(segment
		(start 375.059956 -290.146486)
		(end 375.059956 -290.124388)
		(width 0.0889)
		(layer "In4.Cu")
		(net "P5E_CPU0_PE3_RX_DN<8>")
	)
	(segment
		(start 395.750034 -438.774332)
		(end 395.602714 -438.627012)
		(width 0.14732)
		(layer "In4.Cu")
		(net "P5E_CPU0_PE3_RX_DN<8>")
	)
	(segment
		(start 395.645894 -414.009078)
		(end 396.03807 -410.640784)
		(width 0.14732)
		(layer "In4.Cu")
		(net "P5E_CPU0_PE3_RX_DN<8>")
	)
	(segment
		(start 394.792454 -424.8023)
		(end 395.645894 -414.009078)
		(width 0.14732)
		(layer "In4.Cu")
		(net "P5E_CPU0_PE3_RX_DN<8>")
	)
	(segment
		(start 375.040652 -288.646108)
		(end 375.197116 -288.917126)
		(width 0.0889)
		(layer "In4.Cu")
		(net "P5E_CPU0_PE3_RX_DN<8>")
	)
	(segment
		(start 375.49709 -297.752262)
		(end 375.059956 -295.268142)
		(width 0.14732)
		(layer "In4.Cu")
		(net "P5E_CPU0_PE3_RX_DN<8>")
	)
	(segment
		(start 395.100302 -438.627012)
		(end 394.792454 -438.319164)
		(width 0.14732)
		(layer "In4.Cu")
		(net "P5E_CPU0_PE3_RX_DN<8>")
	)
	(segment
		(start 399.478246 -358.284018)
		(end 398.783302 -332.982062)
		(width 0.14732)
		(layer "In4.Cu")
		(net "P5E_CPU0_PE3_RX_DN<8>")
	)
	(segment
		(start 394.69187 -404.830788)
		(end 394.69187 -398.803114)
		(width 0.14732)
		(layer "In4.Cu")
		(net "P5E_CPU0_PE3_RX_DN<8>")
	)
	(segment
		(start 375.061734 -288.56813)
		(end 375.040652 -288.646108)
		(width 0.0889)
		(layer "In4.Cu")
		(net "P5E_CPU0_PE3_RX_DN<8>")
	)
	(segment
		(start 395.750034 -439.0898)
		(end 395.750034 -438.774332)
		(width 0.14732)
		(layer "In4.Cu")
		(net "P5E_CPU0_PE3_RX_DN<8>")
	)
	(segment
		(start 396.03807 -406.176988)
		(end 394.69187 -404.830788)
		(width 0.14732)
		(layer "In4.Cu")
		(net "P5E_CPU0_PE3_RX_DN<8>")
	)
	(segment
		(start 377.289568 -300.311312)
		(end 375.49709 -297.752262)
		(width 0.14732)
		(layer "In4.Cu")
		(net "P5E_CPU0_PE3_RX_DN<8>")
	)
	(segment
		(start 394.69187 -398.803114)
		(end 397.625824 -376.020838)
		(width 0.14732)
		(layer "In4.Cu")
		(net "P5E_CPU0_PE3_RX_DN<8>")
	)
	(segment
		(start 375.571766 -289.077908)
		(end 375.571766 -288.917126)
		(width 0.0889)
		(layer "In4.Cu")
		(net "P5E_CPU0_PE3_RX_DN<8>")
	)
	(segment
		(start 397.625824 -376.020838)
		(end 399.478246 -358.284018)
		(width 0.14732)
		(layer "In4.Cu")
		(net "P5E_CPU0_PE3_RX_DN<8>")
	)
	(segment
		(start 375.059956 -290.124388)
		(end 375.101866 -290.082478)
		(width 0.0889)
		(layer "In4.Cu")
		(net "P5E_CPU0_PE3_RX_DN<8>")
	)
	(segment
		(start 396.03807 -410.640784)
		(end 396.03807 -406.176988)
		(width 0.14732)
		(layer "In4.Cu")
		(net "P5E_CPU0_PE3_RX_DN<8>")
	)
	(segment
		(start 375.393204 -288.597848)
		(end 375.384314 -288.592768)
		(width 0.0889)
		(layer "In4.Cu")
		(net "P5E_CPU0_PE3_RX_DN<8>")
	)
	(segment
		(start 375.101866 -290.082478)
		(end 375.101866 -289.752278)
		(width 0.0889)
		(layer "In4.Cu")
		(net "P5E_CPU0_PE3_RX_DN<8>")
	)
	(segment
		(start 394.792454 -438.319164)
		(end 394.792454 -424.8023)
		(width 0.14732)
		(layer "In4.Cu")
		(net "P5E_CPU0_PE3_RX_DN<8>")
	)
	(segment
		(start 375.059956 -295.268142)
		(end 375.059956 -290.146486)
		(width 0.14732)
		(layer "In4.Cu")
		(net "P5E_CPU0_PE3_RX_DN<8>")
	)
	(segment
		(start 397.608552 -326.32142)
		(end 377.289568 -300.311312)
		(width 0.14732)
		(layer "In4.Cu")
		(net "P5E_CPU0_PE3_RX_DN<8>")
	)
	(segment
		(start 375.387362 -289.278314)
		(end 375.387362 -289.277806)
		(width 0.0889)
		(layer "In4.Cu")
		(net "P5E_CPU0_PE3_RX_DN<8>")
	)
	(segment
		(start 395.602714 -438.627012)
		(end 395.100302 -438.627012)
		(width 0.14732)
		(layer "In4.Cu")
		(net "P5E_CPU0_PE3_RX_DN<8>")
	)
	(arc
		(start 375.571766 -288.917126)
		(mid 375.524087 -288.734226)
		(end 375.393204 -288.597848)
		(width 0.0889)
		(layer "In4.Cu")
		(net "P5E_CPU0_PE3_RX_DN<8>")
	)
	(arc
		(start 375.101866 -289.752278)
		(mid 375.178772 -289.475656)
		(end 375.387362 -289.278314)
		(width 0.0889)
		(layer "In4.Cu")
		(net "P5E_CPU0_PE3_RX_DN<8>")
	)
	(arc
		(start 375.387362 -289.277806)
		(mid 375.496758 -289.193709)
		(end 375.571766 -289.077908)
		(width 0.0889)
		(layer "In4.Cu")
		(net "P5E_CPU0_PE3_RX_DN<8>")
	)
	(arc
		(start 375.384314 -288.592768)
		(mid 375.225826 -288.543835)
		(end 375.061734 -288.56813)
		(width 0.0889)
		(layer "In4.Cu")
		(net "P5E_CPU0_PE3_RX_DN<8>")
	)
	(segment
		(start 376.136916 -288.381186)
		(end 376.136916 -288.917126)
		(width 0.13208)
		(layer "F.Cu")
		(net "P5E_CPU0_PE3_RX_DN<7>")
	)
	(segment
		(start 376.273822 -290.146486)
		(end 376.273822 -295.011348)
		(width 0.14732)
		(layer "In4.Cu")
		(net "P5E_CPU0_PE3_RX_DN<7>")
	)
	(segment
		(start 398.078198 -424.642026)
		(end 398.066768 -424.805856)
		(width 0.14732)
		(layer "In4.Cu")
		(net "P5E_CPU0_PE3_RX_DN<7>")
	)
	(segment
		(start 398.667986 -419.77945)
		(end 398.531842 -419.891464)
		(width 0.14732)
		(layer "In4.Cu")
		(net "P5E_CPU0_PE3_RX_DN<7>")
	)
	(segment
		(start 378.246132 -299.55998)
		(end 398.751044 -325.808594)
		(width 0.14732)
		(layer "In4.Cu")
		(net "P5E_CPU0_PE3_RX_DN<7>")
	)
	(segment
		(start 376.273822 -295.011348)
		(end 376.681492 -297.32605)
		(width 0.14732)
		(layer "In4.Cu")
		(net "P5E_CPU0_PE3_RX_DN<7>")
	)
	(segment
		(start 398.704308 -418.090858)
		(end 398.816322 -418.226494)
		(width 0.14732)
		(layer "In4.Cu")
		(net "P5E_CPU0_PE3_RX_DN<7>")
	)
	(segment
		(start 400.943572 -357.265224)
		(end 399.273522 -376.268234)
		(width 0.14732)
		(layer "In4.Cu")
		(net "P5E_CPU0_PE3_RX_DN<7>")
	)
	(segment
		(start 376.136916 -288.917126)
		(end 375.977912 -289.218116)
		(width 0.0889)
		(layer "In4.Cu")
		(net "P5E_CPU0_PE3_RX_DN<7>")
	)
	(segment
		(start 400.046444 -333.153004)
		(end 400.943572 -357.265224)
		(width 0.14732)
		(layer "In4.Cu")
		(net "P5E_CPU0_PE3_RX_DN<7>")
	)
	(segment
		(start 398.02943 -399.832576)
		(end 398.02943 -404.716996)
		(width 0.14732)
		(layer "In4.Cu")
		(net "P5E_CPU0_PE3_RX_DN<7>")
	)
	(segment
		(start 398.531842 -419.891464)
		(end 398.53235 -419.891464)
		(width 0.14732)
		(layer "In4.Cu")
		(net "P5E_CPU0_PE3_RX_DN<7>")
	)
	(segment
		(start 398.77492 -418.66185)
		(end 398.638776 -418.773864)
		(width 0.14732)
		(layer "In4.Cu")
		(net "P5E_CPU0_PE3_RX_DN<7>")
	)
	(segment
		(start 375.977912 -289.218116)
		(end 376.007884 -289.315144)
		(width 0.0889)
		(layer "In4.Cu")
		(net "P5E_CPU0_PE3_RX_DN<7>")
	)
	(segment
		(start 398.066768 -424.805856)
		(end 398.066768 -437.205374)
		(width 0.14732)
		(layer "In4.Cu")
		(net "P5E_CPU0_PE3_RX_DN<7>")
	)
	(segment
		(start 398.709388 -419.344348)
		(end 398.667986 -419.77945)
		(width 0.14732)
		(layer "In4.Cu")
		(net "P5E_CPU0_PE3_RX_DN<7>")
	)
	(segment
		(start 376.231912 -289.60953)
		(end 376.231658 -289.609784)
		(width 0.0889)
		(layer "In4.Cu")
		(net "P5E_CPU0_PE3_RX_DN<7>")
	)
	(segment
		(start 376.273822 -290.124388)
		(end 376.273822 -290.146486)
		(width 0.0889)
		(layer "In4.Cu")
		(net "P5E_CPU0_PE3_RX_DN<7>")
	)
	(segment
		(start 398.816322 -418.226494)
		(end 398.77492 -418.66185)
		(width 0.14732)
		(layer "In4.Cu")
		(net "P5E_CPU0_PE3_RX_DN<7>")
	)
	(segment
		(start 398.02943 -404.716996)
		(end 399.37563 -406.063196)
		(width 0.14732)
		(layer "In4.Cu")
		(net "P5E_CPU0_PE3_RX_DN<7>")
	)
	(segment
		(start 399.37563 -410.672026)
		(end 399.377408 -411.046676)
		(width 0.14732)
		(layer "In4.Cu")
		(net "P5E_CPU0_PE3_RX_DN<7>")
	)
	(segment
		(start 399.273522 -376.268234)
		(end 398.02943 -399.832576)
		(width 0.14732)
		(layer "In4.Cu")
		(net "P5E_CPU0_PE3_RX_DN<7>")
	)
	(segment
		(start 376.231658 -289.609784)
		(end 376.231658 -290.082224)
		(width 0.0889)
		(layer "In4.Cu")
		(net "P5E_CPU0_PE3_RX_DN<7>")
	)
	(segment
		(start 398.53235 -419.891464)
		(end 398.078198 -424.642026)
		(width 0.14732)
		(layer "In4.Cu")
		(net "P5E_CPU0_PE3_RX_DN<7>")
	)
	(segment
		(start 398.214088 -437.352694)
		(end 398.57934 -437.352694)
		(width 0.14732)
		(layer "In4.Cu")
		(net "P5E_CPU0_PE3_RX_DN<7>")
	)
	(segment
		(start 376.681492 -297.32605)
		(end 378.246132 -299.55998)
		(width 0.14732)
		(layer "In4.Cu")
		(net "P5E_CPU0_PE3_RX_DN<7>")
	)
	(segment
		(start 376.231658 -290.082224)
		(end 376.273822 -290.124388)
		(width 0.0889)
		(layer "In4.Cu")
		(net "P5E_CPU0_PE3_RX_DN<7>")
	)
	(segment
		(start 398.750028 -437.182006)
		(end 398.750028 -436.889906)
		(width 0.14732)
		(layer "In4.Cu")
		(net "P5E_CPU0_PE3_RX_DN<7>")
	)
	(segment
		(start 398.57934 -437.352694)
		(end 398.750028 -437.182006)
		(width 0.14732)
		(layer "In4.Cu")
		(net "P5E_CPU0_PE3_RX_DN<7>")
	)
	(segment
		(start 398.066768 -437.205374)
		(end 398.214088 -437.352694)
		(width 0.14732)
		(layer "In4.Cu")
		(net "P5E_CPU0_PE3_RX_DN<7>")
	)
	(segment
		(start 398.597374 -419.208712)
		(end 398.709388 -419.344348)
		(width 0.14732)
		(layer "In4.Cu")
		(net "P5E_CPU0_PE3_RX_DN<7>")
	)
	(segment
		(start 399.377408 -411.046676)
		(end 398.704308 -418.090858)
		(width 0.14732)
		(layer "In4.Cu")
		(net "P5E_CPU0_PE3_RX_DN<7>")
	)
	(segment
		(start 398.751044 -325.808594)
		(end 400.046444 -333.153004)
		(width 0.14732)
		(layer "In4.Cu")
		(net "P5E_CPU0_PE3_RX_DN<7>")
	)
	(segment
		(start 398.638776 -418.773864)
		(end 398.597374 -419.208712)
		(width 0.14732)
		(layer "In4.Cu")
		(net "P5E_CPU0_PE3_RX_DN<7>")
	)
	(segment
		(start 399.37563 -406.063196)
		(end 399.37563 -410.672026)
		(width 0.14732)
		(layer "In4.Cu")
		(net "P5E_CPU0_PE3_RX_DN<7>")
	)
	(arc
		(start 376.007884 -289.315144)
		(mid 376.129836 -289.427684)
		(end 376.216164 -289.569398)
		(width 0.0889)
		(layer "In4.Cu")
		(net "P5E_CPU0_PE3_RX_DN<7>")
	)
	(arc
		(start 376.216164 -289.569398)
		(mid 376.224395 -289.589324)
		(end 376.231912 -289.60953)
		(width 0.0889)
		(layer "In4.Cu")
		(net "P5E_CPU0_PE3_RX_DN<7>")
	)
	(segment
		(start 376.606562 -287.567116)
		(end 376.606562 -288.102802)
		(width 0.13208)
		(layer "F.Cu")
		(net "P5E_CPU0_PE3_RX_DN<6>")
	)
	(segment
		(start 376.606562 -288.102802)
		(end 376.606816 -288.103056)
		(width 0.13208)
		(layer "F.Cu")
		(net "P5E_CPU0_PE3_RX_DN<6>")
	)
	(segment
		(start 376.606816 -288.103056)
		(end 376.76328 -288.374074)
		(width 0.0889)
		(layer "In4.Cu")
		(net "P5E_CPU0_PE3_RX_DN<6>")
	)
	(segment
		(start 377.213876 -290.146486)
		(end 377.213876 -294.908478)
		(width 0.14732)
		(layer "In4.Cu")
		(net "P5E_CPU0_PE3_RX_DN<6>")
	)
	(segment
		(start 400.066764 -424.56862)
		(end 400.066764 -438.205372)
		(width 0.14732)
		(layer "In4.Cu")
		(net "P5E_CPU0_PE3_RX_DN<6>")
	)
	(segment
		(start 401.09267 -400.167348)
		(end 401.09267 -404.716996)
		(width 0.14732)
		(layer "In4.Cu")
		(net "P5E_CPU0_PE3_RX_DN<6>")
	)
	(segment
		(start 400.538696 -438.352692)
		(end 400.750024 -438.141364)
		(width 0.14732)
		(layer "In4.Cu")
		(net "P5E_CPU0_PE3_RX_DN<6>")
	)
	(segment
		(start 399.636742 -325.41845)
		(end 401.04187 -333.382874)
		(width 0.14732)
		(layer "In4.Cu")
		(net "P5E_CPU0_PE3_RX_DN<6>")
	)
	(segment
		(start 402.43887 -410.721048)
		(end 400.066764 -424.56862)
		(width 0.14732)
		(layer "In4.Cu")
		(net "P5E_CPU0_PE3_RX_DN<6>")
	)
	(segment
		(start 377.213876 -294.908478)
		(end 377.576588 -296.965116)
		(width 0.14732)
		(layer "In4.Cu")
		(net "P5E_CPU0_PE3_RX_DN<6>")
	)
	(segment
		(start 377.641866 -288.898584)
		(end 377.641866 -289.114484)
		(width 0.0889)
		(layer "In4.Cu")
		(net "P5E_CPU0_PE3_RX_DN<6>")
	)
	(segment
		(start 377.171712 -289.752278)
		(end 377.171712 -290.093146)
		(width 0.0889)
		(layer "In4.Cu")
		(net "P5E_CPU0_PE3_RX_DN<6>")
	)
	(segment
		(start 401.042124 -333.386684)
		(end 402.208238 -356.63251)
		(width 0.14732)
		(layer "In4.Cu")
		(net "P5E_CPU0_PE3_RX_DN<6>")
	)
	(segment
		(start 402.43887 -406.063196)
		(end 402.43887 -410.721048)
		(width 0.14732)
		(layer "In4.Cu")
		(net "P5E_CPU0_PE3_RX_DN<6>")
	)
	(segment
		(start 379.022102 -299.029374)
		(end 399.636742 -325.41845)
		(width 0.14732)
		(layer "In4.Cu")
		(net "P5E_CPU0_PE3_RX_DN<6>")
	)
	(segment
		(start 401.04187 -333.382874)
		(end 401.042124 -333.386684)
		(width 0.14732)
		(layer "In4.Cu")
		(net "P5E_CPU0_PE3_RX_DN<6>")
	)
	(segment
		(start 377.213876 -290.13531)
		(end 377.213876 -290.146486)
		(width 0.0889)
		(layer "In4.Cu")
		(net "P5E_CPU0_PE3_RX_DN<6>")
	)
	(segment
		(start 402.208238 -356.63251)
		(end 401.09267 -400.167348)
		(width 0.14732)
		(layer "In4.Cu")
		(net "P5E_CPU0_PE3_RX_DN<6>")
	)
	(segment
		(start 400.066764 -438.205372)
		(end 400.214084 -438.352692)
		(width 0.14732)
		(layer "In4.Cu")
		(net "P5E_CPU0_PE3_RX_DN<6>")
	)
	(segment
		(start 401.09267 -404.716996)
		(end 402.43887 -406.063196)
		(width 0.14732)
		(layer "In4.Cu")
		(net "P5E_CPU0_PE3_RX_DN<6>")
	)
	(segment
		(start 377.171712 -290.093146)
		(end 377.213876 -290.13531)
		(width 0.0889)
		(layer "In4.Cu")
		(net "P5E_CPU0_PE3_RX_DN<6>")
	)
	(segment
		(start 400.750024 -438.141364)
		(end 400.750024 -437.889904)
		(width 0.14732)
		(layer "In4.Cu")
		(net "P5E_CPU0_PE3_RX_DN<6>")
	)
	(segment
		(start 376.76328 -288.374074)
		(end 376.852434 -288.39795)
		(width 0.0889)
		(layer "In4.Cu")
		(net "P5E_CPU0_PE3_RX_DN<6>")
	)
	(segment
		(start 400.214084 -438.352692)
		(end 400.538696 -438.352692)
		(width 0.14732)
		(layer "In4.Cu")
		(net "P5E_CPU0_PE3_RX_DN<6>")
	)
	(segment
		(start 377.576588 -296.965116)
		(end 379.022102 -299.029374)
		(width 0.14732)
		(layer "In4.Cu")
		(net "P5E_CPU0_PE3_RX_DN<6>")
	)
	(arc
		(start 377.356116 -289.446462)
		(mid 377.221441 -289.573745)
		(end 377.171712 -289.752278)
		(width 0.0889)
		(layer "In4.Cu")
		(net "P5E_CPU0_PE3_RX_DN<6>")
	)
	(arc
		(start 376.871992 -288.389822)
		(mid 377.119972 -288.35321)
		(end 377.359418 -288.427414)
		(width 0.0889)
		(layer "In4.Cu")
		(net "P5E_CPU0_PE3_RX_DN<6>")
	)
	(arc
		(start 377.641866 -289.114484)
		(mid 377.53047 -289.307577)
		(end 377.356116 -289.446462)
		(width 0.0889)
		(layer "In4.Cu")
		(net "P5E_CPU0_PE3_RX_DN<6>")
	)
	(arc
		(start 376.852434 -288.39795)
		(mid 376.862175 -288.393795)
		(end 376.871992 -288.389822)
		(width 0.0889)
		(layer "In4.Cu")
		(net "P5E_CPU0_PE3_RX_DN<6>")
	)
	(arc
		(start 377.359418 -288.427414)
		(mid 377.561704 -288.626395)
		(end 377.641866 -288.898584)
		(width 0.0889)
		(layer "In4.Cu")
		(net "P5E_CPU0_PE3_RX_DN<6>")
	)
	(segment
		(start 378.016516 -288.381186)
		(end 378.016516 -288.917126)
		(width 0.13208)
		(layer "F.Cu")
		(net "P5E_CPU0_PE3_RX_DN<5>")
	)
	(segment
		(start 378.111004 -290.138866)
		(end 378.153168 -290.18103)
		(width 0.0889)
		(layer "In4.Cu")
		(net "P5E_CPU0_PE3_RX_DN<5>")
	)
	(segment
		(start 378.111004 -289.74034)
		(end 378.111004 -290.138866)
		(width 0.0889)
		(layer "In4.Cu")
		(net "P5E_CPU0_PE3_RX_DN<5>")
	)
	(segment
		(start 378.153168 -291.670232)
		(end 381.269494 -294.786558)
		(width 0.14732)
		(layer "In4.Cu")
		(net "P5E_CPU0_PE3_RX_DN<5>")
	)
	(segment
		(start 403.648672 -418.719762)
		(end 403.497542 -418.81044)
		(width 0.14732)
		(layer "In4.Cu")
		(net "P5E_CPU0_PE3_RX_DN<5>")
	)
	(segment
		(start 402.538692 -437.352694)
		(end 402.75002 -437.141366)
		(width 0.14732)
		(layer "In4.Cu")
		(net "P5E_CPU0_PE3_RX_DN<5>")
	)
	(segment
		(start 403.497542 -418.81044)
		(end 403.391878 -419.234112)
		(width 0.14732)
		(layer "In4.Cu")
		(net "P5E_CPU0_PE3_RX_DN<5>")
	)
	(segment
		(start 403.166072 -356.716584)
		(end 404.15591 -400.011646)
		(width 0.14732)
		(layer "In4.Cu")
		(net "P5E_CPU0_PE3_RX_DN<5>")
	)
	(segment
		(start 384.174238 -299.624496)
		(end 385.14528 -305.075336)
		(width 0.14732)
		(layer "In4.Cu")
		(net "P5E_CPU0_PE3_RX_DN<5>")
	)
	(segment
		(start 403.165818 -356.71633)
		(end 403.166072 -356.716584)
		(width 0.14732)
		(layer "In4.Cu")
		(net "P5E_CPU0_PE3_RX_DN<5>")
	)
	(segment
		(start 403.920452 -417.630356)
		(end 403.769322 -417.721034)
		(width 0.14732)
		(layer "In4.Cu")
		(net "P5E_CPU0_PE3_RX_DN<5>")
	)
	(segment
		(start 381.269494 -294.786558)
		(end 382.748536 -294.786558)
		(width 0.14732)
		(layer "In4.Cu")
		(net "P5E_CPU0_PE3_RX_DN<5>")
	)
	(segment
		(start 384.174238 -297.023282)
		(end 384.174238 -299.624496)
		(width 0.14732)
		(layer "In4.Cu")
		(net "P5E_CPU0_PE3_RX_DN<5>")
	)
	(segment
		(start 402.195792 -437.352694)
		(end 402.538692 -437.352694)
		(width 0.14732)
		(layer "In4.Cu")
		(net "P5E_CPU0_PE3_RX_DN<5>")
	)
	(segment
		(start 404.15591 -404.716996)
		(end 405.50211 -406.063196)
		(width 0.14732)
		(layer "In4.Cu")
		(net "P5E_CPU0_PE3_RX_DN<5>")
	)
	(segment
		(start 402.75002 -437.141366)
		(end 402.75002 -436.889906)
		(width 0.14732)
		(layer "In4.Cu")
		(net "P5E_CPU0_PE3_RX_DN<5>")
	)
	(segment
		(start 403.482556 -419.384988)
		(end 403.376892 -419.809168)
		(width 0.14732)
		(layer "In4.Cu")
		(net "P5E_CPU0_PE3_RX_DN<5>")
	)
	(segment
		(start 385.14528 -305.075336)
		(end 400.531076 -324.83552)
		(width 0.14732)
		(layer "In4.Cu")
		(net "P5E_CPU0_PE3_RX_DN<5>")
	)
	(segment
		(start 403.165818 -356.713282)
		(end 403.165818 -356.71633)
		(width 0.14732)
		(layer "In4.Cu")
		(net "P5E_CPU0_PE3_RX_DN<5>")
	)
	(segment
		(start 382.748536 -294.786558)
		(end 383.60096 -295.638982)
		(width 0.14732)
		(layer "In4.Cu")
		(net "P5E_CPU0_PE3_RX_DN<5>")
	)
	(segment
		(start 403.376892 -419.809168)
		(end 403.226016 -419.899592)
		(width 0.14732)
		(layer "In4.Cu")
		(net "P5E_CPU0_PE3_RX_DN<5>")
	)
	(segment
		(start 377.887484 -289.315144)
		(end 377.88723 -289.315652)
		(width 0.0889)
		(layer "In4.Cu")
		(net "P5E_CPU0_PE3_RX_DN<5>")
	)
	(segment
		(start 405.50211 -410.771848)
		(end 403.935438 -417.0553)
		(width 0.14732)
		(layer "In4.Cu")
		(net "P5E_CPU0_PE3_RX_DN<5>")
	)
	(segment
		(start 378.153168 -290.192206)
		(end 378.153168 -291.670232)
		(width 0.14732)
		(layer "In4.Cu")
		(net "P5E_CPU0_PE3_RX_DN<5>")
	)
	(segment
		(start 405.50211 -406.063196)
		(end 405.50211 -410.771848)
		(width 0.14732)
		(layer "In4.Cu")
		(net "P5E_CPU0_PE3_RX_DN<5>")
	)
	(segment
		(start 401.951444 -332.887828)
		(end 403.165818 -356.713282)
		(width 0.14732)
		(layer "In4.Cu")
		(net "P5E_CPU0_PE3_RX_DN<5>")
	)
	(segment
		(start 403.226016 -419.899592)
		(end 402.06676 -424.548046)
		(width 0.14732)
		(layer "In4.Cu")
		(net "P5E_CPU0_PE3_RX_DN<5>")
	)
	(segment
		(start 378.016516 -288.917126)
		(end 377.857512 -289.218116)
		(width 0.0889)
		(layer "In4.Cu")
		(net "P5E_CPU0_PE3_RX_DN<5>")
	)
	(segment
		(start 377.857512 -289.218116)
		(end 377.887484 -289.315144)
		(width 0.0889)
		(layer "In4.Cu")
		(net "P5E_CPU0_PE3_RX_DN<5>")
	)
	(segment
		(start 378.153168 -290.18103)
		(end 378.153168 -290.192206)
		(width 0.0889)
		(layer "In4.Cu")
		(net "P5E_CPU0_PE3_RX_DN<5>")
	)
	(segment
		(start 400.531076 -324.83552)
		(end 401.951444 -332.887828)
		(width 0.14732)
		(layer "In4.Cu")
		(net "P5E_CPU0_PE3_RX_DN<5>")
	)
	(segment
		(start 402.06676 -437.223662)
		(end 402.195792 -437.352694)
		(width 0.14732)
		(layer "In4.Cu")
		(net "P5E_CPU0_PE3_RX_DN<5>")
	)
	(segment
		(start 402.06676 -424.548046)
		(end 402.06676 -437.223662)
		(width 0.14732)
		(layer "In4.Cu")
		(net "P5E_CPU0_PE3_RX_DN<5>")
	)
	(segment
		(start 404.026116 -417.206176)
		(end 403.920452 -417.630356)
		(width 0.14732)
		(layer "In4.Cu")
		(net "P5E_CPU0_PE3_RX_DN<5>")
	)
	(segment
		(start 403.769322 -417.721034)
		(end 403.663658 -418.144706)
		(width 0.14732)
		(layer "In4.Cu")
		(net "P5E_CPU0_PE3_RX_DN<5>")
	)
	(segment
		(start 404.15591 -400.011646)
		(end 404.15591 -404.716996)
		(width 0.14732)
		(layer "In4.Cu")
		(net "P5E_CPU0_PE3_RX_DN<5>")
	)
	(segment
		(start 403.391878 -419.234112)
		(end 403.482556 -419.384988)
		(width 0.14732)
		(layer "In4.Cu")
		(net "P5E_CPU0_PE3_RX_DN<5>")
	)
	(segment
		(start 403.663658 -418.144706)
		(end 403.754336 -418.295582)
		(width 0.14732)
		(layer "In4.Cu")
		(net "P5E_CPU0_PE3_RX_DN<5>")
	)
	(segment
		(start 403.754336 -418.295582)
		(end 403.648672 -418.719762)
		(width 0.14732)
		(layer "In4.Cu")
		(net "P5E_CPU0_PE3_RX_DN<5>")
	)
	(segment
		(start 383.60096 -295.638982)
		(end 384.174238 -297.023282)
		(width 0.14732)
		(layer "In4.Cu")
		(net "P5E_CPU0_PE3_RX_DN<5>")
	)
	(segment
		(start 403.935438 -417.0553)
		(end 404.026116 -417.206176)
		(width 0.14732)
		(layer "In4.Cu")
		(net "P5E_CPU0_PE3_RX_DN<5>")
	)
	(arc
		(start 377.88723 -289.315652)
		(mid 378.051646 -289.500319)
		(end 378.111004 -289.74034)
		(width 0.0889)
		(layer "In4.Cu")
		(net "P5E_CPU0_PE3_RX_DN<5>")
	)
	(segment
		(start 378.486162 -288.102802)
		(end 378.486416 -288.103056)
		(width 0.13208)
		(layer "F.Cu")
		(net "P5E_CPU0_PE3_RX_DN<4>")
	)
	(segment
		(start 378.486162 -287.567116)
		(end 378.486162 -288.102802)
		(width 0.13208)
		(layer "F.Cu")
		(net "P5E_CPU0_PE3_RX_DN<4>")
	)
	(segment
		(start 379.093222 -290.182046)
		(end 379.093222 -291.183822)
		(width 0.14732)
		(layer "In4.Cu")
		(net "P5E_CPU0_PE3_RX_DN<4>")
	)
	(segment
		(start 383.136648 -293.85006)
		(end 384.399536 -295.112948)
		(width 0.14732)
		(layer "In4.Cu")
		(net "P5E_CPU0_PE3_RX_DN<4>")
	)
	(segment
		(start 404.750016 -438.141364)
		(end 404.750016 -437.889904)
		(width 0.14732)
		(layer "In4.Cu")
		(net "P5E_CPU0_PE3_RX_DN<4>")
	)
	(segment
		(start 407.21915 -404.716996)
		(end 408.56535 -406.063196)
		(width 0.14732)
		(layer "In4.Cu")
		(net "P5E_CPU0_PE3_RX_DN<4>")
	)
	(segment
		(start 384.399536 -295.112948)
		(end 385.110736 -296.830242)
		(width 0.14732)
		(layer "In4.Cu")
		(net "P5E_CPU0_PE3_RX_DN<4>")
	)
	(segment
		(start 379.521466 -288.898584)
		(end 379.521466 -289.114484)
		(width 0.0889)
		(layer "In4.Cu")
		(net "P5E_CPU0_PE3_RX_DN<4>")
	)
	(segment
		(start 408.56535 -406.063196)
		(end 408.56535 -410.797248)
		(width 0.14732)
		(layer "In4.Cu")
		(net "P5E_CPU0_PE3_RX_DN<4>")
	)
	(segment
		(start 402.896832 -332.854808)
		(end 407.21915 -399.91411)
		(width 0.14732)
		(layer "In4.Cu")
		(net "P5E_CPU0_PE3_RX_DN<4>")
	)
	(segment
		(start 385.110736 -299.542454)
		(end 386.026914 -304.682652)
		(width 0.14732)
		(layer "In4.Cu")
		(net "P5E_CPU0_PE3_RX_DN<4>")
	)
	(segment
		(start 404.538688 -438.352692)
		(end 404.750016 -438.141364)
		(width 0.14732)
		(layer "In4.Cu")
		(net "P5E_CPU0_PE3_RX_DN<4>")
	)
	(segment
		(start 379.093222 -290.159948)
		(end 379.093222 -290.182046)
		(width 0.0889)
		(layer "In4.Cu")
		(net "P5E_CPU0_PE3_RX_DN<4>")
	)
	(segment
		(start 378.64288 -288.374074)
		(end 378.732034 -288.39795)
		(width 0.0889)
		(layer "In4.Cu")
		(net "P5E_CPU0_PE3_RX_DN<4>")
	)
	(segment
		(start 404.214076 -438.352692)
		(end 404.538688 -438.352692)
		(width 0.14732)
		(layer "In4.Cu")
		(net "P5E_CPU0_PE3_RX_DN<4>")
	)
	(segment
		(start 379.093222 -291.183822)
		(end 381.75946 -293.85006)
		(width 0.14732)
		(layer "In4.Cu")
		(net "P5E_CPU0_PE3_RX_DN<4>")
	)
	(segment
		(start 404.066756 -424.475148)
		(end 404.066756 -438.205372)
		(width 0.14732)
		(layer "In4.Cu")
		(net "P5E_CPU0_PE3_RX_DN<4>")
	)
	(segment
		(start 379.051058 -290.117784)
		(end 379.093222 -290.159948)
		(width 0.0889)
		(layer "In4.Cu")
		(net "P5E_CPU0_PE3_RX_DN<4>")
	)
	(segment
		(start 385.110736 -296.830242)
		(end 385.110736 -299.542454)
		(width 0.14732)
		(layer "In4.Cu")
		(net "P5E_CPU0_PE3_RX_DN<4>")
	)
	(segment
		(start 401.412964 -324.443344)
		(end 402.896832 -332.854808)
		(width 0.14732)
		(layer "In4.Cu")
		(net "P5E_CPU0_PE3_RX_DN<4>")
	)
	(segment
		(start 408.56535 -410.797248)
		(end 404.066756 -424.475148)
		(width 0.14732)
		(layer "In4.Cu")
		(net "P5E_CPU0_PE3_RX_DN<4>")
	)
	(segment
		(start 386.026914 -304.682652)
		(end 401.412964 -324.443344)
		(width 0.14732)
		(layer "In4.Cu")
		(net "P5E_CPU0_PE3_RX_DN<4>")
	)
	(segment
		(start 404.066756 -438.205372)
		(end 404.214076 -438.352692)
		(width 0.14732)
		(layer "In4.Cu")
		(net "P5E_CPU0_PE3_RX_DN<4>")
	)
	(segment
		(start 379.051058 -289.752786)
		(end 379.051058 -290.117784)
		(width 0.0889)
		(layer "In4.Cu")
		(net "P5E_CPU0_PE3_RX_DN<4>")
	)
	(segment
		(start 378.486416 -288.103056)
		(end 378.64288 -288.374074)
		(width 0.0889)
		(layer "In4.Cu")
		(net "P5E_CPU0_PE3_RX_DN<4>")
	)
	(segment
		(start 407.21915 -399.91411)
		(end 407.21915 -404.716996)
		(width 0.14732)
		(layer "In4.Cu")
		(net "P5E_CPU0_PE3_RX_DN<4>")
	)
	(segment
		(start 381.75946 -293.85006)
		(end 383.136648 -293.85006)
		(width 0.14732)
		(layer "In4.Cu")
		(net "P5E_CPU0_PE3_RX_DN<4>")
	)
	(arc
		(start 379.239018 -288.427414)
		(mid 379.441304 -288.626395)
		(end 379.521466 -288.898584)
		(width 0.0889)
		(layer "In4.Cu")
		(net "P5E_CPU0_PE3_RX_DN<4>")
	)
	(arc
		(start 379.235716 -289.446462)
		(mid 379.100717 -289.573919)
		(end 379.051058 -289.752786)
		(width 0.0889)
		(layer "In4.Cu")
		(net "P5E_CPU0_PE3_RX_DN<4>")
	)
	(arc
		(start 379.521466 -289.114484)
		(mid 379.41007 -289.307577)
		(end 379.235716 -289.446462)
		(width 0.0889)
		(layer "In4.Cu")
		(net "P5E_CPU0_PE3_RX_DN<4>")
	)
	(arc
		(start 378.751592 -288.389822)
		(mid 378.999572 -288.35321)
		(end 379.239018 -288.427414)
		(width 0.0889)
		(layer "In4.Cu")
		(net "P5E_CPU0_PE3_RX_DN<4>")
	)
	(arc
		(start 378.732034 -288.39795)
		(mid 378.741775 -288.393795)
		(end 378.751592 -288.389822)
		(width 0.0889)
		(layer "In4.Cu")
		(net "P5E_CPU0_PE3_RX_DN<4>")
	)
	(segment
		(start 379.425962 -289.195002)
		(end 379.425962 -289.807142)
		(width 0.13208)
		(layer "F.Cu")
		(net "P5E_CPU0_PE3_RX_DN<3>")
	)
	(segment
		(start 379.584966 -289.506152)
		(end 379.425962 -289.807142)
		(width 0.0889)
		(layer "In4.Cu")
		(net "P5E_CPU0_PE3_RX_DN<3>")
	)
	(segment
		(start 379.669802 -289.479736)
		(end 379.669548 -289.480244)
		(width 0.0889)
		(layer "In4.Cu")
		(net "P5E_CPU0_PE3_RX_DN<3>")
	)
	(segment
		(start 405.792432 -437.319166)
		(end 405.792432 -424.518328)
		(width 0.14732)
		(layer "In4.Cu")
		(net "P5E_CPU0_PE3_RX_DN<3>")
	)
	(segment
		(start 385.003802 -294.767762)
		(end 383.40411 -293.16807)
		(width 0.14732)
		(layer "In4.Cu")
		(net "P5E_CPU0_PE3_RX_DN<3>")
	)
	(segment
		(start 406.750012 -437.774334)
		(end 406.602692 -437.627014)
		(width 0.14732)
		(layer "In4.Cu")
		(net "P5E_CPU0_PE3_RX_DN<3>")
	)
	(segment
		(start 379.669548 -289.480244)
		(end 379.584966 -289.506152)
		(width 0.0889)
		(layer "In4.Cu")
		(net "P5E_CPU0_PE3_RX_DN<3>")
	)
	(segment
		(start 411.35427 -410.946854)
		(end 411.35427 -406.176988)
		(width 0.14732)
		(layer "In4.Cu")
		(net "P5E_CPU0_PE3_RX_DN<3>")
	)
	(segment
		(start 406.10028 -437.627014)
		(end 405.792432 -437.319166)
		(width 0.14732)
		(layer "In4.Cu")
		(net "P5E_CPU0_PE3_RX_DN<3>")
	)
	(segment
		(start 385.792726 -296.672254)
		(end 385.003802 -294.767762)
		(width 0.14732)
		(layer "In4.Cu")
		(net "P5E_CPU0_PE3_RX_DN<3>")
	)
	(segment
		(start 379.800866 -290.151058)
		(end 379.800866 -289.740594)
		(width 0.0889)
		(layer "In4.Cu")
		(net "P5E_CPU0_PE3_RX_DN<3>")
	)
	(segment
		(start 379.758956 -290.215066)
		(end 379.758956 -290.192968)
		(width 0.0889)
		(layer "In4.Cu")
		(net "P5E_CPU0_PE3_RX_DN<3>")
	)
	(segment
		(start 405.381968 -361.11434)
		(end 403.617684 -333.021178)
		(width 0.14732)
		(layer "In4.Cu")
		(net "P5E_CPU0_PE3_RX_DN<3>")
	)
	(segment
		(start 410.00807 -400.222974)
		(end 405.381968 -361.11434)
		(width 0.14732)
		(layer "In4.Cu")
		(net "P5E_CPU0_PE3_RX_DN<3>")
	)
	(segment
		(start 385.792726 -299.483018)
		(end 385.792726 -296.672254)
		(width 0.14732)
		(layer "In4.Cu")
		(net "P5E_CPU0_PE3_RX_DN<3>")
	)
	(segment
		(start 405.792432 -424.518328)
		(end 411.35427 -410.946854)
		(width 0.14732)
		(layer "In4.Cu")
		(net "P5E_CPU0_PE3_RX_DN<3>")
	)
	(segment
		(start 411.35427 -406.176988)
		(end 410.00807 -404.830788)
		(width 0.14732)
		(layer "In4.Cu")
		(net "P5E_CPU0_PE3_RX_DN<3>")
	)
	(segment
		(start 403.617684 -333.021178)
		(end 402.05533 -324.158102)
		(width 0.14732)
		(layer "In4.Cu")
		(net "P5E_CPU0_PE3_RX_DN<3>")
	)
	(segment
		(start 402.05533 -324.158102)
		(end 386.668772 -304.396902)
		(width 0.14732)
		(layer "In4.Cu")
		(net "P5E_CPU0_PE3_RX_DN<3>")
	)
	(segment
		(start 383.40411 -293.16807)
		(end 382.034542 -293.16807)
		(width 0.14732)
		(layer "In4.Cu")
		(net "P5E_CPU0_PE3_RX_DN<3>")
	)
	(segment
		(start 379.758956 -290.892484)
		(end 379.758956 -290.215066)
		(width 0.14732)
		(layer "In4.Cu")
		(net "P5E_CPU0_PE3_RX_DN<3>")
	)
	(segment
		(start 410.00807 -404.830788)
		(end 410.00807 -400.222974)
		(width 0.14732)
		(layer "In4.Cu")
		(net "P5E_CPU0_PE3_RX_DN<3>")
	)
	(segment
		(start 386.668772 -304.396902)
		(end 385.792726 -299.483018)
		(width 0.14732)
		(layer "In4.Cu")
		(net "P5E_CPU0_PE3_RX_DN<3>")
	)
	(segment
		(start 379.758956 -290.192968)
		(end 379.800866 -290.151058)
		(width 0.0889)
		(layer "In4.Cu")
		(net "P5E_CPU0_PE3_RX_DN<3>")
	)
	(segment
		(start 406.602692 -437.627014)
		(end 406.10028 -437.627014)
		(width 0.14732)
		(layer "In4.Cu")
		(net "P5E_CPU0_PE3_RX_DN<3>")
	)
	(segment
		(start 406.750012 -438.089802)
		(end 406.750012 -437.774334)
		(width 0.14732)
		(layer "In4.Cu")
		(net "P5E_CPU0_PE3_RX_DN<3>")
	)
	(segment
		(start 382.034542 -293.16807)
		(end 379.758956 -290.892484)
		(width 0.14732)
		(layer "In4.Cu")
		(net "P5E_CPU0_PE3_RX_DN<3>")
	)
	(arc
		(start 379.800866 -289.740594)
		(mid 379.766239 -289.594651)
		(end 379.669802 -289.479736)
		(width 0.0889)
		(layer "In4.Cu")
		(net "P5E_CPU0_PE3_RX_DN<3>")
	)
	(segment
		(start 380.835916 -288.381186)
		(end 380.835916 -288.917126)
		(width 0.13208)
		(layer "F.Cu")
		(net "P5E_CPU0_PE3_RX_DN<2>")
	)
	(segment
		(start 408.602688 -438.627012)
		(end 408.100276 -438.627012)
		(width 0.14732)
		(layer "In4.Cu")
		(net "P5E_CPU0_PE3_RX_DN<2>")
	)
	(segment
		(start 407.792174 -424.255438)
		(end 414.41751 -410.888942)
		(width 0.14732)
		(layer "In4.Cu")
		(net "P5E_CPU0_PE3_RX_DN<2>")
	)
	(segment
		(start 386.740908 -296.468038)
		(end 385.687316 -293.924482)
		(width 0.14732)
		(layer "In4.Cu")
		(net "P5E_CPU0_PE3_RX_DN<2>")
	)
	(segment
		(start 381.326898 -291.182298)
		(end 381.311404 -291.166804)
		(width 0.0889)
		(layer "In4.Cu")
		(net "P5E_CPU0_PE3_RX_DN<2>")
	)
	(segment
		(start 407.792174 -438.31891)
		(end 407.792174 -424.255438)
		(width 0.14732)
		(layer "In4.Cu")
		(net "P5E_CPU0_PE3_RX_DN<2>")
	)
	(segment
		(start 402.933408 -323.742304)
		(end 387.561328 -303.999392)
		(width 0.14732)
		(layer "In4.Cu")
		(net "P5E_CPU0_PE3_RX_DN<2>")
	)
	(segment
		(start 380.679452 -288.646108)
		(end 380.835916 -288.917126)
		(width 0.0889)
		(layer "In4.Cu")
		(net "P5E_CPU0_PE3_RX_DN<2>")
	)
	(segment
		(start 387.561328 -303.999392)
		(end 386.740908 -299.39996)
		(width 0.14732)
		(layer "In4.Cu")
		(net "P5E_CPU0_PE3_RX_DN<2>")
	)
	(segment
		(start 381.032004 -288.597848)
		(end 381.023114 -288.592768)
		(width 0.0889)
		(layer "In4.Cu")
		(net "P5E_CPU0_PE3_RX_DN<2>")
	)
	(segment
		(start 408.100276 -438.627012)
		(end 407.792174 -438.31891)
		(width 0.14732)
		(layer "In4.Cu")
		(net "P5E_CPU0_PE3_RX_DN<2>")
	)
	(segment
		(start 404.59406 -333.160116)
		(end 402.933408 -323.742304)
		(width 0.14732)
		(layer "In4.Cu")
		(net "P5E_CPU0_PE3_RX_DN<2>")
	)
	(segment
		(start 413.07131 -404.830788)
		(end 413.07131 -400.38274)
		(width 0.14732)
		(layer "In4.Cu")
		(net "P5E_CPU0_PE3_RX_DN<2>")
	)
	(segment
		(start 408.750008 -438.774332)
		(end 408.602688 -438.627012)
		(width 0.14732)
		(layer "In4.Cu")
		(net "P5E_CPU0_PE3_RX_DN<2>")
	)
	(segment
		(start 414.41751 -406.176988)
		(end 413.07131 -404.830788)
		(width 0.14732)
		(layer "In4.Cu")
		(net "P5E_CPU0_PE3_RX_DN<2>")
	)
	(segment
		(start 381.311404 -291.166804)
		(end 381.311404 -291.107876)
		(width 0.0889)
		(layer "In4.Cu")
		(net "P5E_CPU0_PE3_RX_DN<2>")
	)
	(segment
		(start 383.627122 -291.864288)
		(end 382.008888 -291.864288)
		(width 0.14732)
		(layer "In4.Cu")
		(net "P5E_CPU0_PE3_RX_DN<2>")
	)
	(segment
		(start 413.07131 -400.38274)
		(end 407.539444 -369.861592)
		(width 0.14732)
		(layer "In4.Cu")
		(net "P5E_CPU0_PE3_RX_DN<2>")
	)
	(segment
		(start 381.107696 -290.904168)
		(end 380.897892 -290.590224)
		(width 0.0889)
		(layer "In4.Cu")
		(net "P5E_CPU0_PE3_RX_DN<2>")
	)
	(segment
		(start 384.409696 -292.646862)
		(end 384.212084 -292.646862)
		(width 0.14732)
		(layer "In4.Cu")
		(net "P5E_CPU0_PE3_RX_DN<2>")
	)
	(segment
		(start 380.700534 -288.56813)
		(end 380.679452 -288.646108)
		(width 0.0889)
		(layer "In4.Cu")
		(net "P5E_CPU0_PE3_RX_DN<2>")
	)
	(segment
		(start 380.897892 -290.590224)
		(end 380.740666 -290.210748)
		(width 0.0889)
		(layer "In4.Cu")
		(net "P5E_CPU0_PE3_RX_DN<2>")
	)
	(segment
		(start 407.539444 -369.861592)
		(end 406.312624 -360.662728)
		(width 0.14732)
		(layer "In4.Cu")
		(net "P5E_CPU0_PE3_RX_DN<2>")
	)
	(segment
		(start 383.951226 -292.386004)
		(end 383.951226 -292.188392)
		(width 0.14732)
		(layer "In4.Cu")
		(net "P5E_CPU0_PE3_RX_DN<2>")
	)
	(segment
		(start 414.41751 -410.888942)
		(end 414.41751 -406.176988)
		(width 0.14732)
		(layer "In4.Cu")
		(net "P5E_CPU0_PE3_RX_DN<2>")
	)
	(segment
		(start 381.210566 -289.077908)
		(end 381.210566 -288.917126)
		(width 0.0889)
		(layer "In4.Cu")
		(net "P5E_CPU0_PE3_RX_DN<2>")
	)
	(segment
		(start 384.212084 -292.646862)
		(end 383.951226 -292.386004)
		(width 0.14732)
		(layer "In4.Cu")
		(net "P5E_CPU0_PE3_RX_DN<2>")
	)
	(segment
		(start 408.750008 -439.0898)
		(end 408.750008 -438.774332)
		(width 0.14732)
		(layer "In4.Cu")
		(net "P5E_CPU0_PE3_RX_DN<2>")
	)
	(segment
		(start 383.951226 -292.188392)
		(end 383.627122 -291.864288)
		(width 0.14732)
		(layer "In4.Cu")
		(net "P5E_CPU0_PE3_RX_DN<2>")
	)
	(segment
		(start 406.312624 -360.662728)
		(end 404.59406 -333.160116)
		(width 0.14732)
		(layer "In4.Cu")
		(net "P5E_CPU0_PE3_RX_DN<2>")
	)
	(segment
		(start 381.311404 -291.107876)
		(end 381.107696 -290.904168)
		(width 0.0889)
		(layer "In4.Cu")
		(net "P5E_CPU0_PE3_RX_DN<2>")
	)
	(segment
		(start 380.740666 -289.609022)
		(end 380.740412 -289.609784)
		(width 0.0889)
		(layer "In4.Cu")
		(net "P5E_CPU0_PE3_RX_DN<2>")
	)
	(segment
		(start 382.008888 -291.864288)
		(end 381.326898 -291.182298)
		(width 0.14732)
		(layer "In4.Cu")
		(net "P5E_CPU0_PE3_RX_DN<2>")
	)
	(segment
		(start 385.687316 -293.924482)
		(end 384.409696 -292.646862)
		(width 0.14732)
		(layer "In4.Cu")
		(net "P5E_CPU0_PE3_RX_DN<2>")
	)
	(segment
		(start 386.740908 -299.39996)
		(end 386.740908 -296.468038)
		(width 0.14732)
		(layer "In4.Cu")
		(net "P5E_CPU0_PE3_RX_DN<2>")
	)
	(segment
		(start 380.740666 -290.210748)
		(end 380.740666 -289.609022)
		(width 0.0889)
		(layer "In4.Cu")
		(net "P5E_CPU0_PE3_RX_DN<2>")
	)
	(arc
		(start 381.210566 -288.917126)
		(mid 381.162887 -288.734226)
		(end 381.032004 -288.597848)
		(width 0.0889)
		(layer "In4.Cu")
		(net "P5E_CPU0_PE3_RX_DN<2>")
	)
	(arc
		(start 381.026162 -289.277806)
		(mid 381.135558 -289.193709)
		(end 381.210566 -289.077908)
		(width 0.0889)
		(layer "In4.Cu")
		(net "P5E_CPU0_PE3_RX_DN<2>")
	)
	(arc
		(start 380.755398 -289.570922)
		(mid 380.865655 -289.401162)
		(end 381.026162 -289.277806)
		(width 0.0889)
		(layer "In4.Cu")
		(net "P5E_CPU0_PE3_RX_DN<2>")
	)
	(arc
		(start 380.740412 -289.609784)
		(mid 380.747568 -289.590223)
		(end 380.755398 -289.570922)
		(width 0.0889)
		(layer "In4.Cu")
		(net "P5E_CPU0_PE3_RX_DN<2>")
	)
	(arc
		(start 381.023114 -288.592768)
		(mid 380.864626 -288.543835)
		(end 380.700534 -288.56813)
		(width 0.0889)
		(layer "In4.Cu")
		(net "P5E_CPU0_PE3_RX_DN<2>")
	)
	(segment
		(start 381.305562 -289.195002)
		(end 381.305562 -289.807142)
		(width 0.13208)
		(layer "F.Cu")
		(net "P5E_CPU0_PE3_RX_DN<1>")
	)
	(segment
		(start 403.885146 -323.445378)
		(end 388.441184 -303.609756)
		(width 0.14732)
		(layer "In4.Cu")
		(net "P5E_CPU0_PE3_RX_DN<1>")
	)
	(segment
		(start 381.680466 -289.64636)
		(end 381.680212 -289.645852)
		(width 0.0889)
		(layer "In4.Cu")
		(net "P5E_CPU0_PE3_RX_DN<1>")
	)
	(segment
		(start 384.279902 -291.092382)
		(end 382.639824 -291.092382)
		(width 0.14732)
		(layer "In4.Cu")
		(net "P5E_CPU0_PE3_RX_DN<1>")
	)
	(segment
		(start 381.464566 -289.506152)
		(end 381.305562 -289.807142)
		(width 0.0889)
		(layer "In4.Cu")
		(net "P5E_CPU0_PE3_RX_DN<1>")
	)
	(segment
		(start 410.100272 -437.627014)
		(end 409.79217 -437.318912)
		(width 0.14732)
		(layer "In4.Cu")
		(net "P5E_CPU0_PE3_RX_DN<1>")
	)
	(segment
		(start 409.79217 -424.284648)
		(end 417.48075 -410.850588)
		(width 0.14732)
		(layer "In4.Cu")
		(net "P5E_CPU0_PE3_RX_DN<1>")
	)
	(segment
		(start 387.674104 -296.22369)
		(end 386.446014 -293.258494)
		(width 0.14732)
		(layer "In4.Cu")
		(net "P5E_CPU0_PE3_RX_DN<1>")
	)
	(segment
		(start 386.446014 -293.258494)
		(end 384.279902 -291.092382)
		(width 0.14732)
		(layer "In4.Cu")
		(net "P5E_CPU0_PE3_RX_DN<1>")
	)
	(segment
		(start 382.639824 -291.092382)
		(end 382.155446 -290.608004)
		(width 0.14732)
		(layer "In4.Cu")
		(net "P5E_CPU0_PE3_RX_DN<1>")
	)
	(segment
		(start 416.13455 -400.341592)
		(end 408.800554 -368.877088)
		(width 0.14732)
		(layer "In4.Cu")
		(net "P5E_CPU0_PE3_RX_DN<1>")
	)
	(segment
		(start 410.750004 -438.089802)
		(end 410.750004 -437.774334)
		(width 0.14732)
		(layer "In4.Cu")
		(net "P5E_CPU0_PE3_RX_DN<1>")
	)
	(segment
		(start 382.139952 -290.59251)
		(end 382.139952 -290.532566)
		(width 0.0889)
		(layer "In4.Cu")
		(net "P5E_CPU0_PE3_RX_DN<1>")
	)
	(segment
		(start 416.13455 -404.806912)
		(end 416.13455 -400.341592)
		(width 0.14732)
		(layer "In4.Cu")
		(net "P5E_CPU0_PE3_RX_DN<1>")
	)
	(segment
		(start 417.48075 -406.153112)
		(end 416.13455 -404.806912)
		(width 0.14732)
		(layer "In4.Cu")
		(net "P5E_CPU0_PE3_RX_DN<1>")
	)
	(segment
		(start 382.155446 -290.608004)
		(end 382.139952 -290.59251)
		(width 0.0889)
		(layer "In4.Cu")
		(net "P5E_CPU0_PE3_RX_DN<1>")
	)
	(segment
		(start 408.800554 -368.877088)
		(end 407.034492 -356.769162)
		(width 0.14732)
		(layer "In4.Cu")
		(net "P5E_CPU0_PE3_RX_DN<1>")
	)
	(segment
		(start 409.79217 -437.318912)
		(end 409.79217 -424.284648)
		(width 0.14732)
		(layer "In4.Cu")
		(net "P5E_CPU0_PE3_RX_DN<1>")
	)
	(segment
		(start 381.680466 -290.07308)
		(end 381.680466 -289.64636)
		(width 0.0889)
		(layer "In4.Cu")
		(net "P5E_CPU0_PE3_RX_DN<1>")
	)
	(segment
		(start 382.139952 -290.532566)
		(end 381.680466 -290.07308)
		(width 0.0889)
		(layer "In4.Cu")
		(net "P5E_CPU0_PE3_RX_DN<1>")
	)
	(segment
		(start 388.441184 -303.609756)
		(end 387.674104 -299.260006)
		(width 0.14732)
		(layer "In4.Cu")
		(net "P5E_CPU0_PE3_RX_DN<1>")
	)
	(segment
		(start 410.602684 -437.627014)
		(end 410.100272 -437.627014)
		(width 0.14732)
		(layer "In4.Cu")
		(net "P5E_CPU0_PE3_RX_DN<1>")
	)
	(segment
		(start 381.549148 -289.480244)
		(end 381.464566 -289.506152)
		(width 0.0889)
		(layer "In4.Cu")
		(net "P5E_CPU0_PE3_RX_DN<1>")
	)
	(segment
		(start 417.48075 -410.850588)
		(end 417.48075 -406.153112)
		(width 0.14732)
		(layer "In4.Cu")
		(net "P5E_CPU0_PE3_RX_DN<1>")
	)
	(segment
		(start 387.674104 -299.260006)
		(end 387.674104 -296.22369)
		(width 0.14732)
		(layer "In4.Cu")
		(net "P5E_CPU0_PE3_RX_DN<1>")
	)
	(segment
		(start 407.034492 -356.769162)
		(end 405.515318 -332.689454)
		(width 0.14732)
		(layer "In4.Cu")
		(net "P5E_CPU0_PE3_RX_DN<1>")
	)
	(segment
		(start 405.515318 -332.689454)
		(end 403.885146 -323.445378)
		(width 0.14732)
		(layer "In4.Cu")
		(net "P5E_CPU0_PE3_RX_DN<1>")
	)
	(segment
		(start 410.750004 -437.774334)
		(end 410.602684 -437.627014)
		(width 0.14732)
		(layer "In4.Cu")
		(net "P5E_CPU0_PE3_RX_DN<1>")
	)
	(arc
		(start 381.680212 -289.645852)
		(mid 381.625561 -289.554442)
		(end 381.549148 -289.480244)
		(width 0.0889)
		(layer "In4.Cu")
		(net "P5E_CPU0_PE3_RX_DN<1>")
	)
	(segment
		(start 368.618516 -288.381186)
		(end 368.618516 -288.917126)
		(width 0.13208)
		(layer "F.Cu")
		(net "P5E_CPU0_PE3_RX_DN<15>")
	)
	(segment
		(start 374.86971 -406.063196)
		(end 374.86971 -410.450284)
		(width 0.14732)
		(layer "In4.Cu")
		(net "P5E_CPU0_PE3_RX_DN<15>")
	)
	(segment
		(start 366.792256 -292.813232)
		(end 366.792256 -296.437558)
		(width 0.14732)
		(layer "In4.Cu")
		(net "P5E_CPU0_PE3_RX_DN<15>")
	)
	(segment
		(start 368.713512 -290.079176)
		(end 368.755676 -290.12134)
		(width 0.0889)
		(layer "In4.Cu")
		(net "P5E_CPU0_PE3_RX_DN<15>")
	)
	(segment
		(start 377.974352 -421.234616)
		(end 378.047504 -421.595804)
		(width 0.14732)
		(layer "In4.Cu")
		(net "P5E_CPU0_PE3_RX_DN<15>")
	)
	(segment
		(start 366.792256 -296.437558)
		(end 367.045748 -297.873928)
		(width 0.14732)
		(layer "In4.Cu")
		(net "P5E_CPU0_PE3_RX_DN<15>")
	)
	(segment
		(start 377.608846 -420.129462)
		(end 377.608338 -420.129462)
		(width 0.14732)
		(layer "In4.Cu")
		(net "P5E_CPU0_PE3_RX_DN<15>")
	)
	(segment
		(start 373.52351 -404.716996)
		(end 374.86971 -406.063196)
		(width 0.14732)
		(layer "In4.Cu")
		(net "P5E_CPU0_PE3_RX_DN<15>")
	)
	(segment
		(start 388.379716 -375.136918)
		(end 373.52351 -400.15922)
		(width 0.14732)
		(layer "In4.Cu")
		(net "P5E_CPU0_PE3_RX_DN<15>")
	)
	(segment
		(start 381.750062 -437.141366)
		(end 381.750062 -436.889906)
		(width 0.14732)
		(layer "In4.Cu")
		(net "P5E_CPU0_PE3_RX_DN<15>")
	)
	(segment
		(start 368.755676 -290.12134)
		(end 368.755676 -290.143438)
		(width 0.0889)
		(layer "In4.Cu")
		(net "P5E_CPU0_PE3_RX_DN<15>")
	)
	(segment
		(start 377.773184 -420.238682)
		(end 377.846082 -420.59987)
		(width 0.14732)
		(layer "In4.Cu")
		(net "P5E_CPU0_PE3_RX_DN<15>")
	)
	(segment
		(start 377.608338 -420.129462)
		(end 377.773184 -420.238682)
		(width 0.14732)
		(layer "In4.Cu")
		(net "P5E_CPU0_PE3_RX_DN<15>")
	)
	(segment
		(start 377.810014 -421.125396)
		(end 377.809506 -421.125396)
		(width 0.14732)
		(layer "In4.Cu")
		(net "P5E_CPU0_PE3_RX_DN<15>")
	)
	(segment
		(start 378.047504 -421.595804)
		(end 377.93803 -421.760396)
		(width 0.14732)
		(layer "In4.Cu")
		(net "P5E_CPU0_PE3_RX_DN<15>")
	)
	(segment
		(start 377.93803 -421.760396)
		(end 381.055372 -437.193944)
		(width 0.14732)
		(layer "In4.Cu")
		(net "P5E_CPU0_PE3_RX_DN<15>")
	)
	(segment
		(start 377.846082 -420.59987)
		(end 377.736862 -420.764208)
		(width 0.14732)
		(layer "In4.Cu")
		(net "P5E_CPU0_PE3_RX_DN<15>")
	)
	(segment
		(start 368.618516 -288.917126)
		(end 368.459512 -289.218116)
		(width 0.0889)
		(layer "In4.Cu")
		(net "P5E_CPU0_PE3_RX_DN<15>")
	)
	(segment
		(start 368.713512 -289.60953)
		(end 368.713512 -290.079176)
		(width 0.0889)
		(layer "In4.Cu")
		(net "P5E_CPU0_PE3_RX_DN<15>")
	)
	(segment
		(start 391.473436 -329.221338)
		(end 392.323828 -334.04302)
		(width 0.14732)
		(layer "In4.Cu")
		(net "P5E_CPU0_PE3_RX_DN<15>")
	)
	(segment
		(start 368.459512 -289.218116)
		(end 368.489484 -289.315144)
		(width 0.0889)
		(layer "In4.Cu")
		(net "P5E_CPU0_PE3_RX_DN<15>")
	)
	(segment
		(start 381.214122 -437.352694)
		(end 381.538734 -437.352694)
		(width 0.14732)
		(layer "In4.Cu")
		(net "P5E_CPU0_PE3_RX_DN<15>")
	)
	(segment
		(start 374.86971 -410.450284)
		(end 376.40006 -414.145222)
		(width 0.14732)
		(layer "In4.Cu")
		(net "P5E_CPU0_PE3_RX_DN<15>")
	)
	(segment
		(start 377.809506 -421.125396)
		(end 377.974352 -421.234616)
		(width 0.14732)
		(layer "In4.Cu")
		(net "P5E_CPU0_PE3_RX_DN<15>")
	)
	(segment
		(start 376.40006 -414.145222)
		(end 377.608846 -420.129462)
		(width 0.14732)
		(layer "In4.Cu")
		(net "P5E_CPU0_PE3_RX_DN<15>")
	)
	(segment
		(start 373.52351 -400.15922)
		(end 373.52351 -404.716996)
		(width 0.14732)
		(layer "In4.Cu")
		(net "P5E_CPU0_PE3_RX_DN<15>")
	)
	(segment
		(start 368.755676 -290.143438)
		(end 368.755676 -290.849812)
		(width 0.14732)
		(layer "In4.Cu")
		(net "P5E_CPU0_PE3_RX_DN<15>")
	)
	(segment
		(start 377.736862 -420.764208)
		(end 377.810014 -421.125396)
		(width 0.14732)
		(layer "In4.Cu")
		(net "P5E_CPU0_PE3_RX_DN<15>")
	)
	(segment
		(start 368.755676 -290.849812)
		(end 366.792256 -292.813232)
		(width 0.14732)
		(layer "In4.Cu")
		(net "P5E_CPU0_PE3_RX_DN<15>")
	)
	(segment
		(start 392.323828 -334.04302)
		(end 391.77214 -360.101642)
		(width 0.14732)
		(layer "In4.Cu")
		(net "P5E_CPU0_PE3_RX_DN<15>")
	)
	(segment
		(start 381.538734 -437.352694)
		(end 381.750062 -437.141366)
		(width 0.14732)
		(layer "In4.Cu")
		(net "P5E_CPU0_PE3_RX_DN<15>")
	)
	(segment
		(start 367.045748 -297.873928)
		(end 367.834418 -299.000418)
		(width 0.14732)
		(layer "In4.Cu")
		(net "P5E_CPU0_PE3_RX_DN<15>")
	)
	(segment
		(start 381.055372 -437.193944)
		(end 381.214122 -437.352694)
		(width 0.14732)
		(layer "In4.Cu")
		(net "P5E_CPU0_PE3_RX_DN<15>")
	)
	(segment
		(start 391.77214 -360.101642)
		(end 388.379716 -375.136918)
		(width 0.14732)
		(layer "In4.Cu")
		(net "P5E_CPU0_PE3_RX_DN<15>")
	)
	(segment
		(start 367.834418 -299.000418)
		(end 391.473436 -329.221338)
		(width 0.14732)
		(layer "In4.Cu")
		(net "P5E_CPU0_PE3_RX_DN<15>")
	)
	(arc
		(start 368.489484 -289.315144)
		(mid 368.611616 -289.427903)
		(end 368.698018 -289.569906)
		(width 0.0889)
		(layer "In4.Cu")
		(net "P5E_CPU0_PE3_RX_DN<15>")
	)
	(arc
		(start 368.698018 -289.569906)
		(mid 368.706119 -289.589579)
		(end 368.713512 -289.60953)
		(width 0.0889)
		(layer "In4.Cu")
		(net "P5E_CPU0_PE3_RX_DN<15>")
	)
	(segment
		(start 369.088162 -287.567116)
		(end 369.088162 -288.102802)
		(width 0.13208)
		(layer "F.Cu")
		(net "P5E_CPU0_PE3_RX_DN<14>")
	)
	(segment
		(start 369.088162 -288.102802)
		(end 369.088416 -288.103056)
		(width 0.13208)
		(layer "F.Cu")
		(net "P5E_CPU0_PE3_RX_DN<14>")
	)
	(segment
		(start 393.307062 -333.837788)
		(end 392.944096 -360.079544)
		(width 0.14732)
		(layer "In4.Cu")
		(net "P5E_CPU0_PE3_RX_DN<14>")
	)
	(segment
		(start 381.847598 -421.362124)
		(end 381.847852 -421.36314)
		(width 0.14732)
		(layer "In4.Cu")
		(net "P5E_CPU0_PE3_RX_DN<14>")
	)
	(segment
		(start 369.653312 -290.117784)
		(end 369.695476 -290.159948)
		(width 0.0889)
		(layer "In4.Cu")
		(net "P5E_CPU0_PE3_RX_DN<14>")
	)
	(segment
		(start 376.58675 -400.070828)
		(end 376.58675 -404.716996)
		(width 0.14732)
		(layer "In4.Cu")
		(net "P5E_CPU0_PE3_RX_DN<14>")
	)
	(segment
		(start 369.1382 -297.846242)
		(end 369.381786 -299.230542)
		(width 0.14732)
		(layer "In4.Cu")
		(net "P5E_CPU0_PE3_RX_DN<14>")
	)
	(segment
		(start 377.93295 -406.063196)
		(end 377.93295 -410.68879)
		(width 0.14732)
		(layer "In4.Cu")
		(net "P5E_CPU0_PE3_RX_DN<14>")
	)
	(segment
		(start 383.066798 -438.205372)
		(end 383.214118 -438.352692)
		(width 0.14732)
		(layer "In4.Cu")
		(net "P5E_CPU0_PE3_RX_DN<14>")
	)
	(segment
		(start 369.695476 -290.159948)
		(end 369.695476 -290.182046)
		(width 0.0889)
		(layer "In4.Cu")
		(net "P5E_CPU0_PE3_RX_DN<14>")
	)
	(segment
		(start 381.847852 -421.36314)
		(end 382.255522 -422.474898)
		(width 0.14732)
		(layer "In4.Cu")
		(net "P5E_CPU0_PE3_RX_DN<14>")
	)
	(segment
		(start 369.695476 -290.182046)
		(end 369.695476 -293.031672)
		(width 0.14732)
		(layer "In4.Cu")
		(net "P5E_CPU0_PE3_RX_DN<14>")
	)
	(segment
		(start 389.338058 -375.530364)
		(end 376.58675 -400.070828)
		(width 0.14732)
		(layer "In4.Cu")
		(net "P5E_CPU0_PE3_RX_DN<14>")
	)
	(segment
		(start 370.123466 -288.898584)
		(end 370.123466 -289.114484)
		(width 0.0889)
		(layer "In4.Cu")
		(net "P5E_CPU0_PE3_RX_DN<14>")
	)
	(segment
		(start 369.653312 -289.556952)
		(end 369.653312 -290.117784)
		(width 0.0889)
		(layer "In4.Cu")
		(net "P5E_CPU0_PE3_RX_DN<14>")
	)
	(segment
		(start 369.982242 -300.087538)
		(end 392.43762 -328.90714)
		(width 0.14732)
		(layer "In4.Cu")
		(net "P5E_CPU0_PE3_RX_DN<14>")
	)
	(segment
		(start 381.84709 -421.361108)
		(end 381.847598 -421.362124)
		(width 0.14732)
		(layer "In4.Cu")
		(net "P5E_CPU0_PE3_RX_DN<14>")
	)
	(segment
		(start 377.93295 -410.68879)
		(end 381.84709 -421.360854)
		(width 0.14732)
		(layer "In4.Cu")
		(net "P5E_CPU0_PE3_RX_DN<14>")
	)
	(segment
		(start 369.837716 -289.446462)
		(end 369.837462 -289.446208)
		(width 0.0889)
		(layer "In4.Cu")
		(net "P5E_CPU0_PE3_RX_DN<14>")
	)
	(segment
		(start 381.84709 -421.360854)
		(end 381.84709 -421.361108)
		(width 0.14732)
		(layer "In4.Cu")
		(net "P5E_CPU0_PE3_RX_DN<14>")
	)
	(segment
		(start 369.24488 -288.374074)
		(end 369.334034 -288.39795)
		(width 0.0889)
		(layer "In4.Cu")
		(net "P5E_CPU0_PE3_RX_DN<14>")
	)
	(segment
		(start 383.214118 -438.352692)
		(end 383.53873 -438.352692)
		(width 0.14732)
		(layer "In4.Cu")
		(net "P5E_CPU0_PE3_RX_DN<14>")
	)
	(segment
		(start 382.255522 -422.474898)
		(end 382.255776 -422.47566)
		(width 0.14732)
		(layer "In4.Cu")
		(net "P5E_CPU0_PE3_RX_DN<14>")
	)
	(segment
		(start 383.750058 -438.141364)
		(end 383.750058 -437.889904)
		(width 0.14732)
		(layer "In4.Cu")
		(net "P5E_CPU0_PE3_RX_DN<14>")
	)
	(segment
		(start 392.944096 -360.079544)
		(end 389.338058 -375.530364)
		(width 0.14732)
		(layer "In4.Cu")
		(net "P5E_CPU0_PE3_RX_DN<14>")
	)
	(segment
		(start 376.58675 -404.716996)
		(end 377.93295 -406.063196)
		(width 0.14732)
		(layer "In4.Cu")
		(net "P5E_CPU0_PE3_RX_DN<14>")
	)
	(segment
		(start 369.381786 -299.230542)
		(end 369.982242 -300.087538)
		(width 0.14732)
		(layer "In4.Cu")
		(net "P5E_CPU0_PE3_RX_DN<14>")
	)
	(segment
		(start 383.066798 -424.688)
		(end 383.066798 -438.205372)
		(width 0.14732)
		(layer "In4.Cu")
		(net "P5E_CPU0_PE3_RX_DN<14>")
	)
	(segment
		(start 382.255776 -422.47566)
		(end 383.066798 -424.688)
		(width 0.14732)
		(layer "In4.Cu")
		(net "P5E_CPU0_PE3_RX_DN<14>")
	)
	(segment
		(start 369.695476 -293.031672)
		(end 369.1382 -293.588948)
		(width 0.14732)
		(layer "In4.Cu")
		(net "P5E_CPU0_PE3_RX_DN<14>")
	)
	(segment
		(start 369.654328 -289.555936)
		(end 369.653312 -289.556952)
		(width 0.0889)
		(layer "In4.Cu")
		(net "P5E_CPU0_PE3_RX_DN<14>")
	)
	(segment
		(start 392.43762 -328.90714)
		(end 393.307062 -333.837788)
		(width 0.14732)
		(layer "In4.Cu")
		(net "P5E_CPU0_PE3_RX_DN<14>")
	)
	(segment
		(start 369.837462 -289.446208)
		(end 369.654328 -289.555936)
		(width 0.0889)
		(layer "In4.Cu")
		(net "P5E_CPU0_PE3_RX_DN<14>")
	)
	(segment
		(start 369.1382 -293.588948)
		(end 369.1382 -297.846242)
		(width 0.14732)
		(layer "In4.Cu")
		(net "P5E_CPU0_PE3_RX_DN<14>")
	)
	(segment
		(start 383.53873 -438.352692)
		(end 383.750058 -438.141364)
		(width 0.14732)
		(layer "In4.Cu")
		(net "P5E_CPU0_PE3_RX_DN<14>")
	)
	(segment
		(start 369.088416 -288.103056)
		(end 369.24488 -288.374074)
		(width 0.0889)
		(layer "In4.Cu")
		(net "P5E_CPU0_PE3_RX_DN<14>")
	)
	(arc
		(start 369.334034 -288.39795)
		(mid 369.591033 -288.352483)
		(end 369.841018 -288.427414)
		(width 0.0889)
		(layer "In4.Cu")
		(net "P5E_CPU0_PE3_RX_DN<14>")
	)
	(arc
		(start 370.123466 -289.114484)
		(mid 370.031813 -289.283384)
		(end 369.89131 -289.414458)
		(width 0.0889)
		(layer "In4.Cu")
		(net "P5E_CPU0_PE3_RX_DN<14>")
	)
	(arc
		(start 369.89131 -289.414458)
		(mid 369.864932 -289.431162)
		(end 369.837716 -289.446462)
		(width 0.0889)
		(layer "In4.Cu")
		(net "P5E_CPU0_PE3_RX_DN<14>")
	)
	(arc
		(start 369.841018 -288.427414)
		(mid 370.043304 -288.626395)
		(end 370.123466 -288.898584)
		(width 0.0889)
		(layer "In4.Cu")
		(net "P5E_CPU0_PE3_RX_DN<14>")
	)
	(segment
		(start 370.498116 -288.381186)
		(end 370.498116 -288.917126)
		(width 0.13208)
		(layer "F.Cu")
		(net "P5E_CPU0_PE3_RX_DN<13>")
	)
	(segment
		(start 383.60731 -419.606984)
		(end 383.7813 -419.700202)
		(width 0.14732)
		(layer "In4.Cu")
		(net "P5E_CPU0_PE3_RX_DN<13>")
	)
	(segment
		(start 385.750054 -437.141366)
		(end 385.750054 -436.889906)
		(width 0.14732)
		(layer "In4.Cu")
		(net "P5E_CPU0_PE3_RX_DN<13>")
	)
	(segment
		(start 390.937242 -375.802906)
		(end 379.64999 -400.022568)
		(width 0.14732)
		(layer "In4.Cu")
		(net "P5E_CPU0_PE3_RX_DN<13>")
	)
	(segment
		(start 370.635276 -293.421308)
		(end 370.078 -293.978584)
		(width 0.14732)
		(layer "In4.Cu")
		(net "P5E_CPU0_PE3_RX_DN<13>")
	)
	(segment
		(start 380.99619 -410.925518)
		(end 383.60731 -419.606984)
		(width 0.14732)
		(layer "In4.Cu")
		(net "P5E_CPU0_PE3_RX_DN<13>")
	)
	(segment
		(start 370.7384 -299.528738)
		(end 393.36599 -328.56932)
		(width 0.14732)
		(layer "In4.Cu")
		(net "P5E_CPU0_PE3_RX_DN<13>")
	)
	(segment
		(start 383.952496 -420.75481)
		(end 384.12674 -420.848282)
		(width 0.14732)
		(layer "In4.Cu")
		(net "P5E_CPU0_PE3_RX_DN<13>")
	)
	(segment
		(start 394.026136 -360.78541)
		(end 390.937242 -375.802906)
		(width 0.14732)
		(layer "In4.Cu")
		(net "P5E_CPU0_PE3_RX_DN<13>")
	)
	(segment
		(start 385.066794 -424.460162)
		(end 385.066794 -437.205374)
		(width 0.14732)
		(layer "In4.Cu")
		(net "P5E_CPU0_PE3_RX_DN<13>")
	)
	(segment
		(start 383.887472 -420.053262)
		(end 383.794 -420.227252)
		(width 0.14732)
		(layer "In4.Cu")
		(net "P5E_CPU0_PE3_RX_DN<13>")
	)
	(segment
		(start 385.214114 -437.352694)
		(end 385.538726 -437.352694)
		(width 0.14732)
		(layer "In4.Cu")
		(net "P5E_CPU0_PE3_RX_DN<13>")
	)
	(segment
		(start 370.078 -297.763946)
		(end 370.271548 -298.861988)
		(width 0.14732)
		(layer "In4.Cu")
		(net "P5E_CPU0_PE3_RX_DN<13>")
	)
	(segment
		(start 383.7813 -419.700202)
		(end 383.887472 -420.053262)
		(width 0.14732)
		(layer "In4.Cu")
		(net "P5E_CPU0_PE3_RX_DN<13>")
	)
	(segment
		(start 384.139186 -421.375332)
		(end 384.13944 -421.376094)
		(width 0.14732)
		(layer "In4.Cu")
		(net "P5E_CPU0_PE3_RX_DN<13>")
	)
	(segment
		(start 370.271548 -298.861988)
		(end 370.7384 -299.528738)
		(width 0.14732)
		(layer "In4.Cu")
		(net "P5E_CPU0_PE3_RX_DN<13>")
	)
	(segment
		(start 370.593112 -289.743134)
		(end 370.593112 -290.117784)
		(width 0.0889)
		(layer "In4.Cu")
		(net "P5E_CPU0_PE3_RX_DN<13>")
	)
	(segment
		(start 385.066794 -437.205374)
		(end 385.214114 -437.352694)
		(width 0.14732)
		(layer "In4.Cu")
		(net "P5E_CPU0_PE3_RX_DN<13>")
	)
	(segment
		(start 394.263626 -333.66075)
		(end 394.026136 -360.78541)
		(width 0.14732)
		(layer "In4.Cu")
		(net "P5E_CPU0_PE3_RX_DN<13>")
	)
	(segment
		(start 385.538726 -437.352694)
		(end 385.750054 -437.141366)
		(width 0.14732)
		(layer "In4.Cu")
		(net "P5E_CPU0_PE3_RX_DN<13>")
	)
	(segment
		(start 380.99619 -406.063196)
		(end 380.99619 -410.925518)
		(width 0.14732)
		(layer "In4.Cu")
		(net "P5E_CPU0_PE3_RX_DN<13>")
	)
	(segment
		(start 370.078 -293.978584)
		(end 370.078 -297.763946)
		(width 0.14732)
		(layer "In4.Cu")
		(net "P5E_CPU0_PE3_RX_DN<13>")
	)
	(segment
		(start 370.593112 -290.117784)
		(end 370.635276 -290.159948)
		(width 0.0889)
		(layer "In4.Cu")
		(net "P5E_CPU0_PE3_RX_DN<13>")
	)
	(segment
		(start 370.635276 -290.182046)
		(end 370.635276 -293.421308)
		(width 0.14732)
		(layer "In4.Cu")
		(net "P5E_CPU0_PE3_RX_DN<13>")
	)
	(segment
		(start 384.232658 -421.201342)
		(end 384.139186 -421.375332)
		(width 0.14732)
		(layer "In4.Cu")
		(net "P5E_CPU0_PE3_RX_DN<13>")
	)
	(segment
		(start 379.64999 -404.716996)
		(end 380.99619 -406.063196)
		(width 0.14732)
		(layer "In4.Cu")
		(net "P5E_CPU0_PE3_RX_DN<13>")
	)
	(segment
		(start 370.339112 -289.218116)
		(end 370.369084 -289.315144)
		(width 0.0889)
		(layer "In4.Cu")
		(net "P5E_CPU0_PE3_RX_DN<13>")
	)
	(segment
		(start 383.794 -420.227252)
		(end 383.952496 -420.75481)
		(width 0.14732)
		(layer "In4.Cu")
		(net "P5E_CPU0_PE3_RX_DN<13>")
	)
	(segment
		(start 370.498116 -288.917126)
		(end 370.339112 -289.218116)
		(width 0.0889)
		(layer "In4.Cu")
		(net "P5E_CPU0_PE3_RX_DN<13>")
	)
	(segment
		(start 379.64999 -400.022568)
		(end 379.64999 -404.716996)
		(width 0.14732)
		(layer "In4.Cu")
		(net "P5E_CPU0_PE3_RX_DN<13>")
	)
	(segment
		(start 384.12674 -420.848282)
		(end 384.232658 -421.201342)
		(width 0.14732)
		(layer "In4.Cu")
		(net "P5E_CPU0_PE3_RX_DN<13>")
	)
	(segment
		(start 370.635276 -290.159948)
		(end 370.635276 -290.182046)
		(width 0.0889)
		(layer "In4.Cu")
		(net "P5E_CPU0_PE3_RX_DN<13>")
	)
	(segment
		(start 384.13944 -421.376094)
		(end 385.066794 -424.460162)
		(width 0.14732)
		(layer "In4.Cu")
		(net "P5E_CPU0_PE3_RX_DN<13>")
	)
	(segment
		(start 393.36599 -328.56932)
		(end 394.263626 -333.66075)
		(width 0.14732)
		(layer "In4.Cu")
		(net "P5E_CPU0_PE3_RX_DN<13>")
	)
	(arc
		(start 370.369084 -289.315144)
		(mid 370.378042 -289.321399)
		(end 370.386864 -289.327844)
		(width 0.0889)
		(layer "In4.Cu")
		(net "P5E_CPU0_PE3_RX_DN<13>")
	)
	(arc
		(start 370.386864 -289.327844)
		(mid 370.538769 -289.511263)
		(end 370.593112 -289.743134)
		(width 0.0889)
		(layer "In4.Cu")
		(net "P5E_CPU0_PE3_RX_DN<13>")
	)
	(segment
		(start 370.967762 -287.567116)
		(end 370.967762 -288.102802)
		(width 0.13208)
		(layer "F.Cu")
		(net "P5E_CPU0_PE3_RX_DN<12>")
	)
	(segment
		(start 370.967762 -288.102802)
		(end 370.968016 -288.103056)
		(width 0.13208)
		(layer "F.Cu")
		(net "P5E_CPU0_PE3_RX_DN<12>")
	)
	(segment
		(start 394.171678 -327.744328)
		(end 395.215618 -333.664306)
		(width 0.14732)
		(layer "In4.Cu")
		(net "P5E_CPU0_PE3_RX_DN<12>")
	)
	(segment
		(start 382.71323 -399.980912)
		(end 382.71323 -404.716996)
		(width 0.14732)
		(layer "In4.Cu")
		(net "P5E_CPU0_PE3_RX_DN<12>")
	)
	(segment
		(start 387.538722 -438.352692)
		(end 387.75005 -438.141364)
		(width 0.14732)
		(layer "In4.Cu")
		(net "P5E_CPU0_PE3_RX_DN<12>")
	)
	(segment
		(start 387.21411 -438.352692)
		(end 387.538722 -438.352692)
		(width 0.14732)
		(layer "In4.Cu")
		(net "P5E_CPU0_PE3_RX_DN<12>")
	)
	(segment
		(start 392.055604 -376.257312)
		(end 382.71323 -399.980912)
		(width 0.14732)
		(layer "In4.Cu")
		(net "P5E_CPU0_PE3_RX_DN<12>")
	)
	(segment
		(start 384.05943 -411.21457)
		(end 387.06679 -424.816016)
		(width 0.14732)
		(layer "In4.Cu")
		(net "P5E_CPU0_PE3_RX_DN<12>")
	)
	(segment
		(start 387.75005 -438.141364)
		(end 387.75005 -437.889904)
		(width 0.14732)
		(layer "In4.Cu")
		(net "P5E_CPU0_PE3_RX_DN<12>")
	)
	(segment
		(start 387.06679 -424.816016)
		(end 387.06679 -438.205372)
		(width 0.14732)
		(layer "In4.Cu")
		(net "P5E_CPU0_PE3_RX_DN<12>")
	)
	(segment
		(start 371.574822 -295.773094)
		(end 372.243096 -299.568362)
		(width 0.14732)
		(layer "In4.Cu")
		(net "P5E_CPU0_PE3_RX_DN<12>")
	)
	(segment
		(start 371.574822 -290.13531)
		(end 371.574822 -290.146486)
		(width 0.0889)
		(layer "In4.Cu")
		(net "P5E_CPU0_PE3_RX_DN<12>")
	)
	(segment
		(start 370.968016 -288.103056)
		(end 371.12448 -288.374074)
		(width 0.0889)
		(layer "In4.Cu")
		(net "P5E_CPU0_PE3_RX_DN<12>")
	)
	(segment
		(start 371.532912 -289.64636)
		(end 371.532658 -289.646614)
		(width 0.0889)
		(layer "In4.Cu")
		(net "P5E_CPU0_PE3_RX_DN<12>")
	)
	(segment
		(start 395.215618 -333.664306)
		(end 395.028166 -361.315762)
		(width 0.14732)
		(layer "In4.Cu")
		(net "P5E_CPU0_PE3_RX_DN<12>")
	)
	(segment
		(start 371.532658 -290.093146)
		(end 371.574822 -290.13531)
		(width 0.0889)
		(layer "In4.Cu")
		(net "P5E_CPU0_PE3_RX_DN<12>")
	)
	(segment
		(start 371.574822 -290.146486)
		(end 371.574822 -295.773094)
		(width 0.14732)
		(layer "In4.Cu")
		(net "P5E_CPU0_PE3_RX_DN<12>")
	)
	(segment
		(start 382.71323 -404.716996)
		(end 384.05943 -406.063196)
		(width 0.14732)
		(layer "In4.Cu")
		(net "P5E_CPU0_PE3_RX_DN<12>")
	)
	(segment
		(start 371.12448 -288.374074)
		(end 371.213634 -288.39795)
		(width 0.0889)
		(layer "In4.Cu")
		(net "P5E_CPU0_PE3_RX_DN<12>")
	)
	(segment
		(start 384.05943 -406.063196)
		(end 384.05943 -411.21457)
		(width 0.14732)
		(layer "In4.Cu")
		(net "P5E_CPU0_PE3_RX_DN<12>")
	)
	(segment
		(start 371.532658 -289.646614)
		(end 371.532658 -290.093146)
		(width 0.0889)
		(layer "In4.Cu")
		(net "P5E_CPU0_PE3_RX_DN<12>")
	)
	(segment
		(start 387.06679 -438.205372)
		(end 387.21411 -438.352692)
		(width 0.14732)
		(layer "In4.Cu")
		(net "P5E_CPU0_PE3_RX_DN<12>")
	)
	(segment
		(start 372.243096 -299.568362)
		(end 394.171678 -327.744328)
		(width 0.14732)
		(layer "In4.Cu")
		(net "P5E_CPU0_PE3_RX_DN<12>")
	)
	(segment
		(start 372.003066 -288.898584)
		(end 372.003066 -289.114484)
		(width 0.0889)
		(layer "In4.Cu")
		(net "P5E_CPU0_PE3_RX_DN<12>")
	)
	(segment
		(start 395.028166 -361.315762)
		(end 392.055604 -376.257312)
		(width 0.14732)
		(layer "In4.Cu")
		(net "P5E_CPU0_PE3_RX_DN<12>")
	)
	(arc
		(start 371.717316 -289.446462)
		(mid 371.60792 -289.530559)
		(end 371.532912 -289.64636)
		(width 0.0889)
		(layer "In4.Cu")
		(net "P5E_CPU0_PE3_RX_DN<12>")
	)
	(arc
		(start 372.003066 -289.114484)
		(mid 371.89167 -289.307577)
		(end 371.717316 -289.446462)
		(width 0.0889)
		(layer "In4.Cu")
		(net "P5E_CPU0_PE3_RX_DN<12>")
	)
	(arc
		(start 371.233192 -288.389822)
		(mid 371.481172 -288.35321)
		(end 371.720618 -288.427414)
		(width 0.0889)
		(layer "In4.Cu")
		(net "P5E_CPU0_PE3_RX_DN<12>")
	)
	(arc
		(start 371.720618 -288.427414)
		(mid 371.922904 -288.626395)
		(end 372.003066 -288.898584)
		(width 0.0889)
		(layer "In4.Cu")
		(net "P5E_CPU0_PE3_RX_DN<12>")
	)
	(arc
		(start 371.213634 -288.39795)
		(mid 371.223375 -288.393795)
		(end 371.233192 -288.389822)
		(width 0.0889)
		(layer "In4.Cu")
		(net "P5E_CPU0_PE3_RX_DN<12>")
	)
	(segment
		(start 371.907562 -289.195002)
		(end 371.907562 -289.807142)
		(width 0.13208)
		(layer "F.Cu")
		(net "P5E_CPU0_PE3_RX_DN<11>")
	)
	(segment
		(start 386.84835 -406.176988)
		(end 385.50215 -404.830788)
		(width 0.14732)
		(layer "In4.Cu")
		(net "P5E_CPU0_PE3_RX_DN<11>")
	)
	(segment
		(start 372.240302 -290.146486)
		(end 372.240302 -290.124388)
		(width 0.0889)
		(layer "In4.Cu")
		(net "P5E_CPU0_PE3_RX_DN<11>")
	)
	(segment
		(start 389.750046 -438.089802)
		(end 389.750046 -437.774334)
		(width 0.14732)
		(layer "In4.Cu")
		(net "P5E_CPU0_PE3_RX_DN<11>")
	)
	(segment
		(start 372.881652 -299.274992)
		(end 372.240302 -295.63314)
		(width 0.14732)
		(layer "In4.Cu")
		(net "P5E_CPU0_PE3_RX_DN<11>")
	)
	(segment
		(start 395.881606 -333.487268)
		(end 394.818108 -327.456038)
		(width 0.14732)
		(layer "In4.Cu")
		(net "P5E_CPU0_PE3_RX_DN<11>")
	)
	(segment
		(start 386.84835 -411.32379)
		(end 386.84835 -406.176988)
		(width 0.14732)
		(layer "In4.Cu")
		(net "P5E_CPU0_PE3_RX_DN<11>")
	)
	(segment
		(start 385.50215 -399.801588)
		(end 392.977116 -376.671586)
		(width 0.14732)
		(layer "In4.Cu")
		(net "P5E_CPU0_PE3_RX_DN<11>")
	)
	(segment
		(start 372.066566 -289.506152)
		(end 371.907562 -289.807142)
		(width 0.0889)
		(layer "In4.Cu")
		(net "P5E_CPU0_PE3_RX_DN<11>")
	)
	(segment
		(start 389.100314 -437.627014)
		(end 388.792466 -437.319166)
		(width 0.14732)
		(layer "In4.Cu")
		(net "P5E_CPU0_PE3_RX_DN<11>")
	)
	(segment
		(start 389.750046 -437.774334)
		(end 389.602726 -437.627014)
		(width 0.14732)
		(layer "In4.Cu")
		(net "P5E_CPU0_PE3_RX_DN<11>")
	)
	(segment
		(start 372.240302 -290.124388)
		(end 372.282212 -290.082478)
		(width 0.0889)
		(layer "In4.Cu")
		(net "P5E_CPU0_PE3_RX_DN<11>")
	)
	(segment
		(start 392.977116 -376.671586)
		(end 396.049246 -360.516678)
		(width 0.14732)
		(layer "In4.Cu")
		(net "P5E_CPU0_PE3_RX_DN<11>")
	)
	(segment
		(start 389.602726 -437.627014)
		(end 389.100314 -437.627014)
		(width 0.14732)
		(layer "In4.Cu")
		(net "P5E_CPU0_PE3_RX_DN<11>")
	)
	(segment
		(start 372.151148 -289.480244)
		(end 372.066566 -289.506152)
		(width 0.0889)
		(layer "In4.Cu")
		(net "P5E_CPU0_PE3_RX_DN<11>")
	)
	(segment
		(start 394.818108 -327.456038)
		(end 372.881652 -299.274992)
		(width 0.14732)
		(layer "In4.Cu")
		(net "P5E_CPU0_PE3_RX_DN<11>")
	)
	(segment
		(start 372.282212 -290.082478)
		(end 372.282212 -289.741102)
		(width 0.0889)
		(layer "In4.Cu")
		(net "P5E_CPU0_PE3_RX_DN<11>")
	)
	(segment
		(start 388.792466 -424.65752)
		(end 386.84835 -411.32379)
		(width 0.14732)
		(layer "In4.Cu")
		(net "P5E_CPU0_PE3_RX_DN<11>")
	)
	(segment
		(start 385.50215 -404.830788)
		(end 385.50215 -399.801588)
		(width 0.14732)
		(layer "In4.Cu")
		(net "P5E_CPU0_PE3_RX_DN<11>")
	)
	(segment
		(start 396.049246 -360.516678)
		(end 395.881606 -333.487268)
		(width 0.14732)
		(layer "In4.Cu")
		(net "P5E_CPU0_PE3_RX_DN<11>")
	)
	(segment
		(start 388.792466 -437.319166)
		(end 388.792466 -424.65752)
		(width 0.14732)
		(layer "In4.Cu")
		(net "P5E_CPU0_PE3_RX_DN<11>")
	)
	(segment
		(start 372.240302 -295.63314)
		(end 372.240302 -290.146486)
		(width 0.14732)
		(layer "In4.Cu")
		(net "P5E_CPU0_PE3_RX_DN<11>")
	)
	(arc
		(start 372.282212 -289.741102)
		(mid 372.247604 -289.595136)
		(end 372.151148 -289.480244)
		(width 0.0889)
		(layer "In4.Cu")
		(net "P5E_CPU0_PE3_RX_DN<11>")
	)
	(segment
		(start 373.317516 -288.381186)
		(end 373.317516 -288.917126)
		(width 0.13208)
		(layer "F.Cu")
		(net "P5E_CPU0_PE3_RX_DN<10>")
	)
	(segment
		(start 373.513604 -288.597848)
		(end 373.504714 -288.592768)
		(width 0.0889)
		(layer "In4.Cu")
		(net "P5E_CPU0_PE3_RX_DN<10>")
	)
	(segment
		(start 390.792462 -438.319164)
		(end 390.792462 -424.822874)
		(width 0.14732)
		(layer "In4.Cu")
		(net "P5E_CPU0_PE3_RX_DN<10>")
	)
	(segment
		(start 391.10031 -438.627012)
		(end 390.792462 -438.319164)
		(width 0.14732)
		(layer "In4.Cu")
		(net "P5E_CPU0_PE3_RX_DN<10>")
	)
	(segment
		(start 388.572248 -404.837646)
		(end 388.572248 -399.694146)
		(width 0.14732)
		(layer "In4.Cu")
		(net "P5E_CPU0_PE3_RX_DN<10>")
	)
	(segment
		(start 373.180102 -290.146486)
		(end 373.180102 -290.124388)
		(width 0.0889)
		(layer "In4.Cu")
		(net "P5E_CPU0_PE3_RX_DN<10>")
	)
	(segment
		(start 390.792462 -424.822874)
		(end 390.79297 -424.768264)
		(width 0.14732)
		(layer "In4.Cu")
		(net "P5E_CPU0_PE3_RX_DN<10>")
	)
	(segment
		(start 373.805704 -298.946316)
		(end 373.180102 -295.392856)
		(width 0.14732)
		(layer "In4.Cu")
		(net "P5E_CPU0_PE3_RX_DN<10>")
	)
	(segment
		(start 388.56285 -399.684748)
		(end 394.612114 -376.703336)
		(width 0.14732)
		(layer "In4.Cu")
		(net "P5E_CPU0_PE3_RX_DN<10>")
	)
	(segment
		(start 395.701012 -327.051416)
		(end 373.805704 -298.946316)
		(width 0.14732)
		(layer "In4.Cu")
		(net "P5E_CPU0_PE3_RX_DN<10>")
	)
	(segment
		(start 388.572248 -399.694146)
		(end 388.56285 -399.684748)
		(width 0.14732)
		(layer "In4.Cu")
		(net "P5E_CPU0_PE3_RX_DN<10>")
	)
	(segment
		(start 373.161052 -288.646108)
		(end 373.317516 -288.917126)
		(width 0.0889)
		(layer "In4.Cu")
		(net "P5E_CPU0_PE3_RX_DN<10>")
	)
	(segment
		(start 394.612114 -376.703336)
		(end 397.07693 -360.562906)
		(width 0.14732)
		(layer "In4.Cu")
		(net "P5E_CPU0_PE3_RX_DN<10>")
	)
	(segment
		(start 373.180102 -295.392856)
		(end 373.180102 -290.146486)
		(width 0.14732)
		(layer "In4.Cu")
		(net "P5E_CPU0_PE3_RX_DN<10>")
	)
	(segment
		(start 396.821406 -333.404718)
		(end 395.701012 -327.051416)
		(width 0.14732)
		(layer "In4.Cu")
		(net "P5E_CPU0_PE3_RX_DN<10>")
	)
	(segment
		(start 391.750042 -438.774332)
		(end 391.602722 -438.627012)
		(width 0.14732)
		(layer "In4.Cu")
		(net "P5E_CPU0_PE3_RX_DN<10>")
	)
	(segment
		(start 397.07693 -360.562906)
		(end 396.821406 -333.404718)
		(width 0.14732)
		(layer "In4.Cu")
		(net "P5E_CPU0_PE3_RX_DN<10>")
	)
	(segment
		(start 389.91159 -406.176988)
		(end 388.572248 -404.837646)
		(width 0.14732)
		(layer "In4.Cu")
		(net "P5E_CPU0_PE3_RX_DN<10>")
	)
	(segment
		(start 391.750042 -439.0898)
		(end 391.750042 -438.774332)
		(width 0.14732)
		(layer "In4.Cu")
		(net "P5E_CPU0_PE3_RX_DN<10>")
	)
	(segment
		(start 373.50573 -289.279838)
		(end 373.521986 -289.27044)
		(width 0.0889)
		(layer "In4.Cu")
		(net "P5E_CPU0_PE3_RX_DN<10>")
	)
	(segment
		(start 391.602722 -438.627012)
		(end 391.10031 -438.627012)
		(width 0.14732)
		(layer "In4.Cu")
		(net "P5E_CPU0_PE3_RX_DN<10>")
	)
	(segment
		(start 373.692166 -289.077908)
		(end 373.692166 -288.917126)
		(width 0.0889)
		(layer "In4.Cu")
		(net "P5E_CPU0_PE3_RX_DN<10>")
	)
	(segment
		(start 373.222012 -289.563556)
		(end 373.50573 -289.279838)
		(width 0.0889)
		(layer "In4.Cu")
		(net "P5E_CPU0_PE3_RX_DN<10>")
	)
	(segment
		(start 390.79297 -424.768264)
		(end 389.91159 -412.369254)
		(width 0.14732)
		(layer "In4.Cu")
		(net "P5E_CPU0_PE3_RX_DN<10>")
	)
	(segment
		(start 373.521986 -289.27044)
		(end 373.521986 -289.269678)
		(width 0.0889)
		(layer "In4.Cu")
		(net "P5E_CPU0_PE3_RX_DN<10>")
	)
	(segment
		(start 373.182134 -288.56813)
		(end 373.161052 -288.646108)
		(width 0.0889)
		(layer "In4.Cu")
		(net "P5E_CPU0_PE3_RX_DN<10>")
	)
	(segment
		(start 389.91159 -412.369254)
		(end 389.91159 -406.176988)
		(width 0.14732)
		(layer "In4.Cu")
		(net "P5E_CPU0_PE3_RX_DN<10>")
	)
	(segment
		(start 373.222012 -290.082478)
		(end 373.222012 -289.563556)
		(width 0.0889)
		(layer "In4.Cu")
		(net "P5E_CPU0_PE3_RX_DN<10>")
	)
	(segment
		(start 373.180102 -290.124388)
		(end 373.222012 -290.082478)
		(width 0.0889)
		(layer "In4.Cu")
		(net "P5E_CPU0_PE3_RX_DN<10>")
	)
	(arc
		(start 373.504714 -288.592768)
		(mid 373.346226 -288.543835)
		(end 373.182134 -288.56813)
		(width 0.0889)
		(layer "In4.Cu")
		(net "P5E_CPU0_PE3_RX_DN<10>")
	)
	(arc
		(start 373.521986 -289.269678)
		(mid 373.622532 -289.187511)
		(end 373.692166 -289.077908)
		(width 0.0889)
		(layer "In4.Cu")
		(net "P5E_CPU0_PE3_RX_DN<10>")
	)
	(arc
		(start 373.692166 -288.917126)
		(mid 373.644487 -288.734226)
		(end 373.513604 -288.597848)
		(width 0.0889)
		(layer "In4.Cu")
		(net "P5E_CPU0_PE3_RX_DN<10>")
	)
	(segment
		(start 383.185162 -287.567116)
		(end 383.185162 -288.102802)
		(width 0.13208)
		(layer "F.Cu")
		(net "P5E_CPU0_PE3_RX_DN<0>")
	)
	(segment
		(start 383.185162 -288.102802)
		(end 383.185416 -288.103056)
		(width 0.13208)
		(layer "F.Cu")
		(net "P5E_CPU0_PE3_RX_DN<0>")
	)
	(segment
		(start 412.75 -438.141364)
		(end 412.75 -437.889904)
		(width 0.14732)
		(layer "In4.Cu")
		(net "P5E_CPU0_PE3_RX_DN<0>")
	)
	(segment
		(start 412.066486 -424.427904)
		(end 412.066486 -438.205118)
		(width 0.14732)
		(layer "In4.Cu")
		(net "P5E_CPU0_PE3_RX_DN<0>")
	)
	(segment
		(start 383.185416 -288.103056)
		(end 383.34188 -288.374074)
		(width 0.0889)
		(layer "In4.Cu")
		(net "P5E_CPU0_PE3_RX_DN<0>")
	)
	(segment
		(start 383.34188 -288.374074)
		(end 383.431034 -288.39795)
		(width 0.0889)
		(layer "In4.Cu")
		(net "P5E_CPU0_PE3_RX_DN<0>")
	)
	(segment
		(start 384.055112 -288.51733)
		(end 384.266948 -288.729166)
		(width 0.0889)
		(layer "In4.Cu")
		(net "P5E_CPU0_PE3_RX_DN<0>")
	)
	(segment
		(start 412.538672 -438.352692)
		(end 412.75 -438.141364)
		(width 0.14732)
		(layer "In4.Cu")
		(net "P5E_CPU0_PE3_RX_DN<0>")
	)
	(segment
		(start 420.81831 -406.063196)
		(end 420.81831 -410.513276)
		(width 0.14732)
		(layer "In4.Cu")
		(net "P5E_CPU0_PE3_RX_DN<0>")
	)
	(segment
		(start 387.41858 -292.297104)
		(end 388.899146 -295.871646)
		(width 0.14732)
		(layer "In4.Cu")
		(net "P5E_CPU0_PE3_RX_DN<0>")
	)
	(segment
		(start 409.961334 -368.381026)
		(end 419.47211 -399.996152)
		(width 0.14732)
		(layer "In4.Cu")
		(net "P5E_CPU0_PE3_RX_DN<0>")
	)
	(segment
		(start 388.899146 -299.210476)
		(end 389.58139 -303.079404)
		(width 0.14732)
		(layer "In4.Cu")
		(net "P5E_CPU0_PE3_RX_DN<0>")
	)
	(segment
		(start 384.973322 -289.851846)
		(end 384.988816 -289.86734)
		(width 0.0889)
		(layer "In4.Cu")
		(net "P5E_CPU0_PE3_RX_DN<0>")
	)
	(segment
		(start 384.988816 -289.86734)
		(end 387.41858 -292.297104)
		(width 0.14732)
		(layer "In4.Cu")
		(net "P5E_CPU0_PE3_RX_DN<0>")
	)
	(segment
		(start 384.913378 -289.851846)
		(end 384.973322 -289.851846)
		(width 0.0889)
		(layer "In4.Cu")
		(net "P5E_CPU0_PE3_RX_DN<0>")
	)
	(segment
		(start 419.47211 -399.996152)
		(end 419.47211 -404.716996)
		(width 0.14732)
		(layer "In4.Cu")
		(net "P5E_CPU0_PE3_RX_DN<0>")
	)
	(segment
		(start 409.961334 -368.38128)
		(end 409.961334 -368.381026)
		(width 0.14732)
		(layer "In4.Cu")
		(net "P5E_CPU0_PE3_RX_DN<0>")
	)
	(segment
		(start 419.47211 -404.716996)
		(end 420.81831 -406.063196)
		(width 0.14732)
		(layer "In4.Cu")
		(net "P5E_CPU0_PE3_RX_DN<0>")
	)
	(segment
		(start 420.81831 -410.513276)
		(end 412.066486 -424.427904)
		(width 0.14732)
		(layer "In4.Cu")
		(net "P5E_CPU0_PE3_RX_DN<0>")
	)
	(segment
		(start 406.873964 -333.333598)
		(end 408.3177 -357.119174)
		(width 0.14732)
		(layer "In4.Cu")
		(net "P5E_CPU0_PE3_RX_DN<0>")
	)
	(segment
		(start 388.899146 -295.871646)
		(end 388.899146 -299.210476)
		(width 0.14732)
		(layer "In4.Cu")
		(net "P5E_CPU0_PE3_RX_DN<0>")
	)
	(segment
		(start 408.3177 -357.119174)
		(end 408.3177 -357.12019)
		(width 0.14732)
		(layer "In4.Cu")
		(net "P5E_CPU0_PE3_RX_DN<0>")
	)
	(segment
		(start 384.476752 -289.41522)
		(end 384.913378 -289.851846)
		(width 0.0889)
		(layer "In4.Cu")
		(net "P5E_CPU0_PE3_RX_DN<0>")
	)
	(segment
		(start 412.21406 -438.352692)
		(end 412.538672 -438.352692)
		(width 0.14732)
		(layer "In4.Cu")
		(net "P5E_CPU0_PE3_RX_DN<0>")
	)
	(segment
		(start 389.58139 -303.079404)
		(end 405.038814 -322.932806)
		(width 0.14732)
		(layer "In4.Cu")
		(net "P5E_CPU0_PE3_RX_DN<0>")
	)
	(segment
		(start 408.3177 -357.12019)
		(end 409.961334 -368.38128)
		(width 0.14732)
		(layer "In4.Cu")
		(net "P5E_CPU0_PE3_RX_DN<0>")
	)
	(segment
		(start 406.74036 -332.582012)
		(end 406.873964 -333.333598)
		(width 0.14732)
		(layer "In4.Cu")
		(net "P5E_CPU0_PE3_RX_DN<0>")
	)
	(segment
		(start 412.066486 -438.205118)
		(end 412.21406 -438.352692)
		(width 0.14732)
		(layer "In4.Cu")
		(net "P5E_CPU0_PE3_RX_DN<0>")
	)
	(segment
		(start 405.038814 -322.932806)
		(end 406.74036 -332.582012)
		(width 0.14732)
		(layer "In4.Cu")
		(net "P5E_CPU0_PE3_RX_DN<0>")
	)
	(segment
		(start 384.266948 -288.729166)
		(end 384.476752 -289.41522)
		(width 0.0889)
		(layer "In4.Cu")
		(net "P5E_CPU0_PE3_RX_DN<0>")
	)
	(arc
		(start 383.431034 -288.39795)
		(mid 383.688033 -288.352483)
		(end 383.938018 -288.427414)
		(width 0.0889)
		(layer "In4.Cu")
		(net "P5E_CPU0_PE3_RX_DN<0>")
	)
	(arc
		(start 383.938018 -288.427414)
		(mid 383.999513 -288.468533)
		(end 384.055112 -288.51733)
		(width 0.0889)
		(layer "In4.Cu")
		(net "P5E_CPU0_PE3_RX_DN<0>")
	)
	(segment
		(start 390.107932 -401.16379)
		(end 390.107932 -401.777962)
		(width 0.13208)
		(layer "F.Cu")
		(net "P5E_CPU0_PE2_TX_DP<9>")
	)
	(segment
		(start 376.966734 -225.203512)
		(end 376.96648 -225.203258)
		(width 0.13208)
		(layer "F.Cu")
		(net "P5E_CPU0_PE2_TX_DP<9>")
	)
	(segment
		(start 389.781542 -402.104352)
		(end 389.77697 -402.104352)
		(width 0.13208)
		(layer "F.Cu")
		(net "P5E_CPU0_PE2_TX_DP<9>")
	)
	(segment
		(start 389.80237 -400.858228)
		(end 390.107932 -401.16379)
		(width 0.13208)
		(layer "F.Cu")
		(net "P5E_CPU0_PE2_TX_DP<9>")
	)
	(segment
		(start 376.966734 -225.739198)
		(end 376.966734 -225.203512)
		(width 0.13208)
		(layer "F.Cu")
		(net "P5E_CPU0_PE2_TX_DP<9>")
	)
	(segment
		(start 390.107932 -401.777962)
		(end 389.781542 -402.104352)
		(width 0.13208)
		(layer "F.Cu")
		(net "P5E_CPU0_PE2_TX_DP<9>")
	)
	(segment
		(start 390.59485 -396.70736)
		(end 390.43102 -396.829788)
		(width 0.14732)
		(layer "In15.Cu")
		(net "P5E_CPU0_PE2_TX_DP<9>")
	)
	(segment
		(start 377.531884 -223.585532)
		(end 377.531884 -223.56699)
		(width 0.0889)
		(layer "In15.Cu")
		(net "P5E_CPU0_PE2_TX_DP<9>")
	)
	(segment
		(start 386.601462 -218.054428)
		(end 386.601462 -218.113356)
		(width 0.0889)
		(layer "In15.Cu")
		(net "P5E_CPU0_PE2_TX_DP<9>")
	)
	(segment
		(start 390.09701 -400.174206)
		(end 390.09701 -400.563588)
		(width 0.14732)
		(layer "In15.Cu")
		(net "P5E_CPU0_PE2_TX_DP<9>")
	)
	(segment
		(start 385.612132 -216.739978)
		(end 385.621022 -216.745058)
		(width 0.0889)
		(layer "In15.Cu")
		(net "P5E_CPU0_PE2_TX_DP<9>")
	)
	(segment
		(start 390.08685 -399.226278)
		(end 390.209532 -399.390108)
		(width 0.14732)
		(layer "In15.Cu")
		(net "P5E_CPU0_PE2_TX_DP<9>")
	)
	(segment
		(start 396.352268 -253.148846)
		(end 392.039602 -309.461916)
		(width 0.14732)
		(layer "In15.Cu")
		(net "P5E_CPU0_PE2_TX_DP<9>")
	)
	(segment
		(start 378.941584 -221.133924)
		(end 378.941584 -221.115382)
		(width 0.0889)
		(layer "In15.Cu")
		(net "P5E_CPU0_PE2_TX_DP<9>")
	)
	(segment
		(start 380.538482 -218.367864)
		(end 380.544578 -218.364308)
		(width 0.0889)
		(layer "In15.Cu")
		(net "P5E_CPU0_PE2_TX_DP<9>")
	)
	(segment
		(start 379.503432 -219.18168)
		(end 379.518164 -219.190316)
		(width 0.0889)
		(layer "In15.Cu")
		(net "P5E_CPU0_PE2_TX_DP<9>")
	)
	(segment
		(start 381.291084 -217.082878)
		(end 381.291084 -217.0557)
		(width 0.0889)
		(layer "In15.Cu")
		(net "P5E_CPU0_PE2_TX_DP<9>")
	)
	(segment
		(start 385.799584 -217.064336)
		(end 385.799584 -217.07856)
		(width 0.0889)
		(layer "In15.Cu")
		(net "P5E_CPU0_PE2_TX_DP<9>")
	)
	(segment
		(start 399.200624 -339.50656)
		(end 396.6083 -354.489004)
		(width 0.14732)
		(layer "In15.Cu")
		(net "P5E_CPU0_PE2_TX_DP<9>")
	)
	(segment
		(start 390.303258 -398.738598)
		(end 390.139174 -398.86128)
		(width 0.14732)
		(layer "In15.Cu")
		(net "P5E_CPU0_PE2_TX_DP<9>")
	)
	(segment
		(start 386.616956 -218.12885)
		(end 389.221472 -220.73362)
		(width 0.14732)
		(layer "In15.Cu")
		(net "P5E_CPU0_PE2_TX_DP<9>")
	)
	(segment
		(start 391.771632 -224.101914)
		(end 392.283696 -225.870516)
		(width 0.14732)
		(layer "In15.Cu")
		(net "P5E_CPU0_PE2_TX_DP<9>")
	)
	(segment
		(start 390.449054 -397.723106)
		(end 390.285224 -397.845534)
		(width 0.14732)
		(layer "In15.Cu")
		(net "P5E_CPU0_PE2_TX_DP<9>")
	)
	(segment
		(start 390.378696 -397.194532)
		(end 390.501378 -397.358362)
		(width 0.14732)
		(layer "In15.Cu")
		(net "P5E_CPU0_PE2_TX_DP<9>")
	)
	(segment
		(start 386.601462 -218.113356)
		(end 386.616956 -218.12885)
		(width 0.0889)
		(layer "In15.Cu")
		(net "P5E_CPU0_PE2_TX_DP<9>")
	)
	(segment
		(start 378.941584 -219.515944)
		(end 378.941584 -219.506038)
		(width 0.0889)
		(layer "In15.Cu")
		(net "P5E_CPU0_PE2_TX_DP<9>")
	)
	(segment
		(start 390.355582 -398.374108)
		(end 390.303258 -398.738598)
		(width 0.14732)
		(layer "In15.Cu")
		(net "P5E_CPU0_PE2_TX_DP<9>")
	)
	(segment
		(start 378.001784 -222.77578)
		(end 378.001784 -222.761556)
		(width 0.0889)
		(layer "In15.Cu")
		(net "P5E_CPU0_PE2_TX_DP<9>")
	)
	(segment
		(start 378.180346 -222.442278)
		(end 378.189236 -222.437198)
		(width 0.0889)
		(layer "In15.Cu")
		(net "P5E_CPU0_PE2_TX_DP<9>")
	)
	(segment
		(start 376.96648 -225.203258)
		(end 376.810016 -224.93224)
		(width 0.0889)
		(layer "In15.Cu")
		(net "P5E_CPU0_PE2_TX_DP<9>")
	)
	(segment
		(start 390.43102 -396.829788)
		(end 390.378696 -397.194532)
		(width 0.14732)
		(layer "In15.Cu")
		(net "P5E_CPU0_PE2_TX_DP<9>")
	)
	(segment
		(start 380.999746 -217.559128)
		(end 381.008636 -217.554048)
		(width 0.0889)
		(layer "In15.Cu")
		(net "P5E_CPU0_PE2_TX_DP<9>")
	)
	(segment
		(start 389.221472 -220.73362)
		(end 391.771632 -224.101914)
		(width 0.14732)
		(layer "In15.Cu")
		(net "P5E_CPU0_PE2_TX_DP<9>")
	)
	(segment
		(start 380.35103 -218.707716)
		(end 380.35103 -218.692222)
		(width 0.0889)
		(layer "In15.Cu")
		(net "P5E_CPU0_PE2_TX_DP<9>")
	)
	(segment
		(start 390.209532 -399.390108)
		(end 390.09701 -400.174206)
		(width 0.14732)
		(layer "In15.Cu")
		(net "P5E_CPU0_PE2_TX_DP<9>")
	)
	(segment
		(start 390.501378 -397.358362)
		(end 390.449054 -397.723106)
		(width 0.14732)
		(layer "In15.Cu")
		(net "P5E_CPU0_PE2_TX_DP<9>")
	)
	(segment
		(start 390.2329 -398.210278)
		(end 390.355582 -398.374108)
		(width 0.14732)
		(layer "In15.Cu")
		(net "P5E_CPU0_PE2_TX_DP<9>")
	)
	(segment
		(start 382.407922 -216.746074)
		(end 382.418336 -216.739978)
		(width 0.0889)
		(layer "In15.Cu")
		(net "P5E_CPU0_PE2_TX_DP<9>")
	)
	(segment
		(start 379.120146 -219.18676)
		(end 379.129036 -219.18168)
		(width 0.0889)
		(layer "In15.Cu")
		(net "P5E_CPU0_PE2_TX_DP<9>")
	)
	(segment
		(start 390.139174 -398.86128)
		(end 390.08685 -399.226278)
		(width 0.14732)
		(layer "In15.Cu")
		(net "P5E_CPU0_PE2_TX_DP<9>")
	)
	(segment
		(start 377.240546 -224.070164)
		(end 377.249436 -224.065084)
		(width 0.0889)
		(layer "In15.Cu")
		(net "P5E_CPU0_PE2_TX_DP<9>")
	)
	(segment
		(start 396.6083 -354.489004)
		(end 394.733018 -367.899188)
		(width 0.14732)
		(layer "In15.Cu")
		(net "P5E_CPU0_PE2_TX_DP<9>")
	)
	(segment
		(start 378.658882 -221.623382)
		(end 378.664978 -221.619826)
		(width 0.0889)
		(layer "In15.Cu")
		(net "P5E_CPU0_PE2_TX_DP<9>")
	)
	(segment
		(start 392.039602 -309.461916)
		(end 399.200624 -339.50656)
		(width 0.14732)
		(layer "In15.Cu")
		(net "P5E_CPU0_PE2_TX_DP<9>")
	)
	(segment
		(start 390.09701 -400.563588)
		(end 389.80237 -400.858228)
		(width 0.14732)
		(layer "In15.Cu")
		(net "P5E_CPU0_PE2_TX_DP<9>")
	)
	(segment
		(start 394.733018 -367.899188)
		(end 390.59485 -396.70736)
		(width 0.14732)
		(layer "In15.Cu")
		(net "P5E_CPU0_PE2_TX_DP<9>")
	)
	(segment
		(start 386.160264 -217.61323)
		(end 386.601462 -218.054428)
		(width 0.0889)
		(layer "In15.Cu")
		(net "P5E_CPU0_PE2_TX_DP<9>")
	)
	(segment
		(start 378.655834 -219.997528)
		(end 378.658374 -219.996004)
		(width 0.0889)
		(layer "In15.Cu")
		(net "P5E_CPU0_PE2_TX_DP<9>")
	)
	(segment
		(start 378.650246 -220.000576)
		(end 378.655834 -219.997528)
		(width 0.0889)
		(layer "In15.Cu")
		(net "P5E_CPU0_PE2_TX_DP<9>")
	)
	(segment
		(start 378.47143 -221.963234)
		(end 378.47143 -221.94774)
		(width 0.0889)
		(layer "In15.Cu")
		(net "P5E_CPU0_PE2_TX_DP<9>")
	)
	(segment
		(start 380.529592 -218.372944)
		(end 380.538482 -218.367864)
		(width 0.0889)
		(layer "In15.Cu")
		(net "P5E_CPU0_PE2_TX_DP<9>")
	)
	(segment
		(start 376.810016 -224.93224)
		(end 376.834146 -224.843086)
		(width 0.0889)
		(layer "In15.Cu")
		(net "P5E_CPU0_PE2_TX_DP<9>")
	)
	(segment
		(start 378.649992 -221.628462)
		(end 378.658882 -221.623382)
		(width 0.0889)
		(layer "In15.Cu")
		(net "P5E_CPU0_PE2_TX_DP<9>")
	)
	(segment
		(start 393.045188 -229.720648)
		(end 396.256764 -250.312428)
		(width 0.14732)
		(layer "In15.Cu")
		(net "P5E_CPU0_PE2_TX_DP<9>")
	)
	(segment
		(start 396.256764 -250.312428)
		(end 396.352268 -253.148846)
		(width 0.14732)
		(layer "In15.Cu")
		(net "P5E_CPU0_PE2_TX_DP<9>")
	)
	(segment
		(start 378.659136 -220.644212)
		(end 378.650246 -220.639132)
		(width 0.0889)
		(layer "In15.Cu")
		(net "P5E_CPU0_PE2_TX_DP<9>")
	)
	(segment
		(start 390.285224 -397.845534)
		(end 390.2329 -398.210278)
		(width 0.14732)
		(layer "In15.Cu")
		(net "P5E_CPU0_PE2_TX_DP<9>")
	)
	(segment
		(start 378.658374 -219.996004)
		(end 378.659136 -219.995496)
		(width 0.0889)
		(layer "In15.Cu")
		(net "P5E_CPU0_PE2_TX_DP<9>")
	)
	(segment
		(start 392.283696 -225.870516)
		(end 393.045188 -229.720648)
		(width 0.14732)
		(layer "In15.Cu")
		(net "P5E_CPU0_PE2_TX_DP<9>")
	)
	(arc
		(start 377.531884 -223.56699)
		(mid 377.584154 -223.384625)
		(end 377.719082 -223.251268)
		(width 0.0889)
		(layer "In15.Cu")
		(net "P5E_CPU0_PE2_TX_DP<9>")
	)
	(arc
		(start 381.852678 -216.739978)
		(mid 382.129491 -216.815848)
		(end 382.407922 -216.746074)
		(width 0.0889)
		(layer "In15.Cu")
		(net "P5E_CPU0_PE2_TX_DP<9>")
	)
	(arc
		(start 376.851164 -224.829878)
		(mid 377.006562 -224.633597)
		(end 377.061984 -224.389442)
		(width 0.0889)
		(layer "In15.Cu")
		(net "P5E_CPU0_PE2_TX_DP<9>")
	)
	(arc
		(start 378.659136 -219.995496)
		(mid 378.863471 -219.792891)
		(end 378.941584 -219.515944)
		(width 0.0889)
		(layer "In15.Cu")
		(net "P5E_CPU0_PE2_TX_DP<9>")
	)
	(arc
		(start 378.001784 -222.761556)
		(mid 378.049463 -222.578656)
		(end 378.180346 -222.442278)
		(width 0.0889)
		(layer "In15.Cu")
		(net "P5E_CPU0_PE2_TX_DP<9>")
	)
	(arc
		(start 377.719082 -223.251268)
		(mid 377.922563 -223.050464)
		(end 378.001784 -222.77578)
		(width 0.0889)
		(layer "In15.Cu")
		(net "P5E_CPU0_PE2_TX_DP<9>")
	)
	(arc
		(start 384.297936 -216.739978)
		(mid 384.485134 -216.689835)
		(end 384.672332 -216.739978)
		(width 0.0889)
		(layer "In15.Cu")
		(net "P5E_CPU0_PE2_TX_DP<9>")
	)
	(arc
		(start 380.35103 -218.692222)
		(mid 380.398709 -218.509322)
		(end 380.529592 -218.372944)
		(width 0.0889)
		(layer "In15.Cu")
		(net "P5E_CPU0_PE2_TX_DP<9>")
	)
	(arc
		(start 386.082286 -217.554048)
		(mid 386.123216 -217.581081)
		(end 386.160264 -217.61323)
		(width 0.0889)
		(layer "In15.Cu")
		(net "P5E_CPU0_PE2_TX_DP<9>")
	)
	(arc
		(start 379.129036 -219.18168)
		(mid 379.316234 -219.131537)
		(end 379.503432 -219.18168)
		(width 0.0889)
		(layer "In15.Cu")
		(net "P5E_CPU0_PE2_TX_DP<9>")
	)
	(arc
		(start 380.068836 -219.18168)
		(mid 380.271659 -218.981449)
		(end 380.35103 -218.707716)
		(width 0.0889)
		(layer "In15.Cu")
		(net "P5E_CPU0_PE2_TX_DP<9>")
	)
	(arc
		(start 385.237736 -216.739978)
		(mid 385.424934 -216.689835)
		(end 385.612132 -216.739978)
		(width 0.0889)
		(layer "In15.Cu")
		(net "P5E_CPU0_PE2_TX_DP<9>")
	)
	(arc
		(start 381.008636 -217.554048)
		(mid 381.210922 -217.355067)
		(end 381.291084 -217.082878)
		(width 0.0889)
		(layer "In15.Cu")
		(net "P5E_CPU0_PE2_TX_DP<9>")
	)
	(arc
		(start 377.061984 -224.389442)
		(mid 377.109663 -224.206542)
		(end 377.240546 -224.070164)
		(width 0.0889)
		(layer "In15.Cu")
		(net "P5E_CPU0_PE2_TX_DP<9>")
	)
	(arc
		(start 381.291084 -217.0557)
		(mid 381.343354 -216.873335)
		(end 381.478282 -216.739978)
		(width 0.0889)
		(layer "In15.Cu")
		(net "P5E_CPU0_PE2_TX_DP<9>")
	)
	(arc
		(start 382.418336 -216.739978)
		(mid 382.605534 -216.689835)
		(end 382.792732 -216.739978)
		(width 0.0889)
		(layer "In15.Cu")
		(net "P5E_CPU0_PE2_TX_DP<9>")
	)
	(arc
		(start 385.799584 -217.07856)
		(mid 385.878803 -217.353245)
		(end 386.082286 -217.554048)
		(width 0.0889)
		(layer "In15.Cu")
		(net "P5E_CPU0_PE2_TX_DP<9>")
	)
	(arc
		(start 380.821184 -217.878406)
		(mid 380.868863 -217.695506)
		(end 380.999746 -217.559128)
		(width 0.0889)
		(layer "In15.Cu")
		(net "P5E_CPU0_PE2_TX_DP<9>")
	)
	(arc
		(start 376.834146 -224.843086)
		(mid 376.842718 -224.836564)
		(end 376.851164 -224.829878)
		(width 0.0889)
		(layer "In15.Cu")
		(net "P5E_CPU0_PE2_TX_DP<9>")
	)
	(arc
		(start 378.664978 -221.619826)
		(mid 378.867565 -221.413475)
		(end 378.941584 -221.133924)
		(width 0.0889)
		(layer "In15.Cu")
		(net "P5E_CPU0_PE2_TX_DP<9>")
	)
	(arc
		(start 382.792732 -216.739978)
		(mid 383.075434 -216.815754)
		(end 383.358136 -216.739978)
		(width 0.0889)
		(layer "In15.Cu")
		(net "P5E_CPU0_PE2_TX_DP<9>")
	)
	(arc
		(start 377.249436 -224.065084)
		(mid 377.453771 -223.862479)
		(end 377.531884 -223.585532)
		(width 0.0889)
		(layer "In15.Cu")
		(net "P5E_CPU0_PE2_TX_DP<9>")
	)
	(arc
		(start 379.518164 -219.190316)
		(mid 379.794639 -219.257636)
		(end 380.068836 -219.18168)
		(width 0.0889)
		(layer "In15.Cu")
		(net "P5E_CPU0_PE2_TX_DP<9>")
	)
	(arc
		(start 378.650246 -220.639132)
		(mid 378.471649 -220.319854)
		(end 378.650246 -220.000576)
		(width 0.0889)
		(layer "In15.Cu")
		(net "P5E_CPU0_PE2_TX_DP<9>")
	)
	(arc
		(start 380.544578 -218.364308)
		(mid 380.747165 -218.157957)
		(end 380.821184 -217.878406)
		(width 0.0889)
		(layer "In15.Cu")
		(net "P5E_CPU0_PE2_TX_DP<9>")
	)
	(arc
		(start 383.732532 -216.739978)
		(mid 384.015234 -216.815754)
		(end 384.297936 -216.739978)
		(width 0.0889)
		(layer "In15.Cu")
		(net "P5E_CPU0_PE2_TX_DP<9>")
	)
	(arc
		(start 381.478282 -216.739978)
		(mid 381.66548 -216.689835)
		(end 381.852678 -216.739978)
		(width 0.0889)
		(layer "In15.Cu")
		(net "P5E_CPU0_PE2_TX_DP<9>")
	)
	(arc
		(start 378.189236 -222.437198)
		(mid 378.392059 -222.236967)
		(end 378.47143 -221.963234)
		(width 0.0889)
		(layer "In15.Cu")
		(net "P5E_CPU0_PE2_TX_DP<9>")
	)
	(arc
		(start 378.47143 -221.94774)
		(mid 378.519109 -221.76484)
		(end 378.649992 -221.628462)
		(width 0.0889)
		(layer "In15.Cu")
		(net "P5E_CPU0_PE2_TX_DP<9>")
	)
	(arc
		(start 385.621022 -216.745058)
		(mid 385.751936 -216.881418)
		(end 385.799584 -217.064336)
		(width 0.0889)
		(layer "In15.Cu")
		(net "P5E_CPU0_PE2_TX_DP<9>")
	)
	(arc
		(start 383.358136 -216.739978)
		(mid 383.545334 -216.689835)
		(end 383.732532 -216.739978)
		(width 0.0889)
		(layer "In15.Cu")
		(net "P5E_CPU0_PE2_TX_DP<9>")
	)
	(arc
		(start 384.672332 -216.739978)
		(mid 384.955034 -216.815754)
		(end 385.237736 -216.739978)
		(width 0.0889)
		(layer "In15.Cu")
		(net "P5E_CPU0_PE2_TX_DP<9>")
	)
	(arc
		(start 378.941584 -221.115382)
		(mid 378.861422 -220.843193)
		(end 378.659136 -220.644212)
		(width 0.0889)
		(layer "In15.Cu")
		(net "P5E_CPU0_PE2_TX_DP<9>")
	)
	(arc
		(start 378.941584 -219.506038)
		(mid 378.989263 -219.323138)
		(end 379.120146 -219.18676)
		(width 0.0889)
		(layer "In15.Cu")
		(net "P5E_CPU0_PE2_TX_DP<9>")
	)
	(segment
		(start 393.171172 -401.777962)
		(end 392.844782 -402.104352)
		(width 0.13208)
		(layer "F.Cu")
		(net "P5E_CPU0_PE2_TX_DP<8>")
	)
	(segment
		(start 375.55678 -224.925382)
		(end 375.55678 -224.389696)
		(width 0.13208)
		(layer "F.Cu")
		(net "P5E_CPU0_PE2_TX_DP<8>")
	)
	(segment
		(start 392.86561 -400.858228)
		(end 393.171172 -401.16379)
		(width 0.13208)
		(layer "F.Cu")
		(net "P5E_CPU0_PE2_TX_DP<8>")
	)
	(segment
		(start 375.55678 -224.389696)
		(end 375.557034 -224.389442)
		(width 0.13208)
		(layer "F.Cu")
		(net "P5E_CPU0_PE2_TX_DP<8>")
	)
	(segment
		(start 393.171172 -401.16379)
		(end 393.171172 -401.777962)
		(width 0.13208)
		(layer "F.Cu")
		(net "P5E_CPU0_PE2_TX_DP<8>")
	)
	(segment
		(start 392.844782 -402.104352)
		(end 392.84021 -402.104352)
		(width 0.13208)
		(layer "F.Cu")
		(net "P5E_CPU0_PE2_TX_DP<8>")
	)
	(segment
		(start 380.538736 -216.739978)
		(end 380.528322 -216.746074)
		(width 0.0889)
		(layer "In15.Cu")
		(net "P5E_CPU0_PE2_TX_DP<8>")
	)
	(segment
		(start 379.129036 -217.554048)
		(end 379.120146 -217.559128)
		(width 0.0889)
		(layer "In15.Cu")
		(net "P5E_CPU0_PE2_TX_DP<8>")
	)
	(segment
		(start 386.496814 -216.32164)
		(end 386.160264 -215.98509)
		(width 0.0889)
		(layer "In15.Cu")
		(net "P5E_CPU0_PE2_TX_DP<8>")
	)
	(segment
		(start 393.16025 -400.04746)
		(end 393.222988 -399.40865)
		(width 0.14732)
		(layer "In15.Cu")
		(net "P5E_CPU0_PE2_TX_DP<8>")
	)
	(segment
		(start 377.249436 -222.437198)
		(end 377.240546 -222.442278)
		(width 0.0889)
		(layer "In15.Cu")
		(net "P5E_CPU0_PE2_TX_DP<8>")
	)
	(segment
		(start 384.776218 -215.921336)
		(end 384.767836 -215.926162)
		(width 0.0889)
		(layer "In15.Cu")
		(net "P5E_CPU0_PE2_TX_DP<8>")
	)
	(segment
		(start 393.294108 -397.20774)
		(end 393.330176 -396.840964)
		(width 0.14732)
		(layer "In15.Cu")
		(net "P5E_CPU0_PE2_TX_DP<8>")
	)
	(segment
		(start 393.193524 -398.229074)
		(end 393.229592 -397.862298)
		(width 0.14732)
		(layer "In15.Cu")
		(net "P5E_CPU0_PE2_TX_DP<8>")
	)
	(segment
		(start 377.725178 -221.619826)
		(end 377.719082 -221.623382)
		(width 0.0889)
		(layer "In15.Cu")
		(net "P5E_CPU0_PE2_TX_DP<8>")
	)
	(segment
		(start 393.16025 -400.563588)
		(end 393.16025 -400.04746)
		(width 0.14732)
		(layer "In15.Cu")
		(net "P5E_CPU0_PE2_TX_DP<8>")
	)
	(segment
		(start 393.423902 -397.365982)
		(end 393.294108 -397.20774)
		(width 0.14732)
		(layer "In15.Cu")
		(net "P5E_CPU0_PE2_TX_DP<8>")
	)
	(segment
		(start 396.292324 -368.20729)
		(end 398.663414 -348.568264)
		(width 0.14732)
		(layer "In15.Cu")
		(net "P5E_CPU0_PE2_TX_DP<8>")
	)
	(segment
		(start 393.022074 -309.279798)
		(end 397.285972 -253.2126)
		(width 0.14732)
		(layer "In15.Cu")
		(net "P5E_CPU0_PE2_TX_DP<8>")
	)
	(segment
		(start 379.411484 -217.0557)
		(end 379.411484 -217.082878)
		(width 0.0889)
		(layer "In15.Cu")
		(net "P5E_CPU0_PE2_TX_DP<8>")
	)
	(segment
		(start 376.315732 -224.061528)
		(end 376.309636 -224.065084)
		(width 0.0889)
		(layer "In15.Cu")
		(net "P5E_CPU0_PE2_TX_DP<8>")
	)
	(segment
		(start 393.09294 -399.250408)
		(end 393.129008 -398.883632)
		(width 0.14732)
		(layer "In15.Cu")
		(net "P5E_CPU0_PE2_TX_DP<8>")
	)
	(segment
		(start 395.574012 -239.764062)
		(end 395.573758 -239.764062)
		(width 0.14732)
		(layer "In15.Cu")
		(net "P5E_CPU0_PE2_TX_DP<8>")
	)
	(segment
		(start 393.229592 -397.862298)
		(end 393.388088 -397.732504)
		(width 0.14732)
		(layer "In15.Cu")
		(net "P5E_CPU0_PE2_TX_DP<8>")
	)
	(segment
		(start 393.388088 -397.732504)
		(end 393.423902 -397.365982)
		(width 0.14732)
		(layer "In15.Cu")
		(net "P5E_CPU0_PE2_TX_DP<8>")
	)
	(segment
		(start 378.001784 -221.1197)
		(end 378.001784 -221.133924)
		(width 0.0889)
		(layer "In15.Cu")
		(net "P5E_CPU0_PE2_TX_DP<8>")
	)
	(segment
		(start 393.222988 -399.40865)
		(end 393.09294 -399.250408)
		(width 0.14732)
		(layer "In15.Cu")
		(net "P5E_CPU0_PE2_TX_DP<8>")
	)
	(segment
		(start 376.779536 -223.251268)
		(end 376.770646 -223.256348)
		(width 0.0889)
		(layer "In15.Cu")
		(net "P5E_CPU0_PE2_TX_DP<8>")
	)
	(segment
		(start 378.189236 -219.18168)
		(end 378.180346 -219.18676)
		(width 0.0889)
		(layer "In15.Cu")
		(net "P5E_CPU0_PE2_TX_DP<8>")
	)
	(segment
		(start 393.488672 -396.71117)
		(end 393.488418 -396.710916)
		(width 0.14732)
		(layer "In15.Cu")
		(net "P5E_CPU0_PE2_TX_DP<8>")
	)
	(segment
		(start 397.285972 -253.2126)
		(end 397.177006 -249.976386)
		(width 0.14732)
		(layer "In15.Cu")
		(net "P5E_CPU0_PE2_TX_DP<8>")
	)
	(segment
		(start 384.015234 -215.875362)
		(end 381.195834 -215.875362)
		(width 0.0889)
		(layer "In15.Cu")
		(net "P5E_CPU0_PE2_TX_DP<8>")
	)
	(segment
		(start 385.70789 -215.926162)
		(end 385.687062 -215.938354)
		(width 0.0889)
		(layer "In15.Cu")
		(net "P5E_CPU0_PE2_TX_DP<8>")
	)
	(segment
		(start 375.713498 -224.118424)
		(end 375.557034 -224.389442)
		(width 0.0889)
		(layer "In15.Cu")
		(net "P5E_CPU0_PE2_TX_DP<8>")
	)
	(segment
		(start 377.719082 -221.623382)
		(end 377.710192 -221.628462)
		(width 0.0889)
		(layer "In15.Cu")
		(net "P5E_CPU0_PE2_TX_DP<8>")
	)
	(segment
		(start 393.129008 -398.883632)
		(end 393.287504 -398.753838)
		(width 0.14732)
		(layer "In15.Cu")
		(net "P5E_CPU0_PE2_TX_DP<8>")
	)
	(segment
		(start 386.496814 -216.381584)
		(end 386.496814 -216.32164)
		(width 0.0889)
		(layer "In15.Cu")
		(net "P5E_CPU0_PE2_TX_DP<8>")
	)
	(segment
		(start 393.287504 -398.753838)
		(end 393.323318 -398.387316)
		(width 0.14732)
		(layer "In15.Cu")
		(net "P5E_CPU0_PE2_TX_DP<8>")
	)
	(segment
		(start 375.802398 -224.094802)
		(end 375.713498 -224.118424)
		(width 0.0889)
		(layer "In15.Cu")
		(net "P5E_CPU0_PE2_TX_DP<8>")
	)
	(segment
		(start 393.265406 -225.886518)
		(end 392.69924 -223.748346)
		(width 0.14732)
		(layer "In15.Cu")
		(net "P5E_CPU0_PE2_TX_DP<8>")
	)
	(segment
		(start 377.725178 -219.99194)
		(end 377.719844 -219.994988)
		(width 0.0889)
		(layer "In15.Cu")
		(net "P5E_CPU0_PE2_TX_DP<8>")
	)
	(segment
		(start 385.722368 -215.91778)
		(end 385.70789 -215.926162)
		(width 0.0889)
		(layer "In15.Cu")
		(net "P5E_CPU0_PE2_TX_DP<8>")
	)
	(segment
		(start 395.573758 -239.764062)
		(end 393.971018 -229.551484)
		(width 0.14732)
		(layer "In15.Cu")
		(net "P5E_CPU0_PE2_TX_DP<8>")
	)
	(segment
		(start 377.531884 -220.311218)
		(end 377.531884 -220.32849)
		(width 0.0889)
		(layer "In15.Cu")
		(net "P5E_CPU0_PE2_TX_DP<8>")
	)
	(segment
		(start 392.69924 -223.748346)
		(end 388.925562 -218.810586)
		(width 0.14732)
		(layer "In15.Cu")
		(net "P5E_CPU0_PE2_TX_DP<8>")
	)
	(segment
		(start 378.664978 -218.364308)
		(end 378.658882 -218.367864)
		(width 0.0889)
		(layer "In15.Cu")
		(net "P5E_CPU0_PE2_TX_DP<8>")
	)
	(segment
		(start 386.512308 -216.397078)
		(end 386.496814 -216.381584)
		(width 0.0889)
		(layer "In15.Cu")
		(net "P5E_CPU0_PE2_TX_DP<8>")
	)
	(segment
		(start 393.323318 -398.387316)
		(end 393.193524 -398.229074)
		(width 0.14732)
		(layer "In15.Cu")
		(net "P5E_CPU0_PE2_TX_DP<8>")
	)
	(segment
		(start 384.767836 -215.926162)
		(end 384.753104 -215.934798)
		(width 0.0889)
		(layer "In15.Cu")
		(net "P5E_CPU0_PE2_TX_DP<8>")
	)
	(segment
		(start 400.21129 -339.622892)
		(end 393.022074 -309.279798)
		(width 0.14732)
		(layer "In15.Cu")
		(net "P5E_CPU0_PE2_TX_DP<8>")
	)
	(segment
		(start 377.061984 -222.761556)
		(end 377.061984 -222.780098)
		(width 0.0889)
		(layer "In15.Cu")
		(net "P5E_CPU0_PE2_TX_DP<8>")
	)
	(segment
		(start 396.291562 -368.217196)
		(end 396.292324 -368.20729)
		(width 0.14732)
		(layer "In15.Cu")
		(net "P5E_CPU0_PE2_TX_DP<8>")
	)
	(segment
		(start 397.177006 -249.976386)
		(end 395.574012 -239.764062)
		(width 0.14732)
		(layer "In15.Cu")
		(net "P5E_CPU0_PE2_TX_DP<8>")
	)
	(segment
		(start 378.47143 -218.692222)
		(end 378.47143 -218.707716)
		(width 0.0889)
		(layer "In15.Cu")
		(net "P5E_CPU0_PE2_TX_DP<8>")
	)
	(segment
		(start 388.925562 -218.810586)
		(end 386.512308 -216.397078)
		(width 0.14732)
		(layer "In15.Cu")
		(net "P5E_CPU0_PE2_TX_DP<8>")
	)
	(segment
		(start 393.971018 -229.551484)
		(end 393.265406 -225.886518)
		(width 0.14732)
		(layer "In15.Cu")
		(net "P5E_CPU0_PE2_TX_DP<8>")
	)
	(segment
		(start 392.86561 -400.858228)
		(end 393.16025 -400.563588)
		(width 0.14732)
		(layer "In15.Cu")
		(net "P5E_CPU0_PE2_TX_DP<8>")
	)
	(segment
		(start 393.488418 -396.710916)
		(end 396.291562 -368.217196)
		(width 0.14732)
		(layer "In15.Cu")
		(net "P5E_CPU0_PE2_TX_DP<8>")
	)
	(segment
		(start 378.658882 -218.367864)
		(end 378.649992 -218.372944)
		(width 0.0889)
		(layer "In15.Cu")
		(net "P5E_CPU0_PE2_TX_DP<8>")
	)
	(segment
		(start 398.663414 -348.568264)
		(end 400.21129 -339.622892)
		(width 0.14732)
		(layer "In15.Cu")
		(net "P5E_CPU0_PE2_TX_DP<8>")
	)
	(segment
		(start 381.008636 -215.926162)
		(end 380.999746 -215.931242)
		(width 0.0889)
		(layer "In15.Cu")
		(net "P5E_CPU0_PE2_TX_DP<8>")
	)
	(segment
		(start 377.53163 -221.94774)
		(end 377.53163 -221.963234)
		(width 0.0889)
		(layer "In15.Cu")
		(net "P5E_CPU0_PE2_TX_DP<8>")
	)
	(segment
		(start 380.821184 -216.25052)
		(end 380.821184 -216.260426)
		(width 0.0889)
		(layer "In15.Cu")
		(net "P5E_CPU0_PE2_TX_DP<8>")
	)
	(segment
		(start 377.719844 -219.994988)
		(end 377.719082 -219.995496)
		(width 0.0889)
		(layer "In15.Cu")
		(net "P5E_CPU0_PE2_TX_DP<8>")
	)
	(segment
		(start 393.330176 -396.840964)
		(end 393.488672 -396.71117)
		(width 0.14732)
		(layer "In15.Cu")
		(net "P5E_CPU0_PE2_TX_DP<8>")
	)
	(arc
		(start 378.649992 -218.372944)
		(mid 378.519078 -218.509304)
		(end 378.47143 -218.692222)
		(width 0.0889)
		(layer "In15.Cu")
		(net "P5E_CPU0_PE2_TX_DP<8>")
	)
	(arc
		(start 380.528322 -216.746074)
		(mid 380.24989 -216.81592)
		(end 379.973078 -216.739978)
		(width 0.0889)
		(layer "In15.Cu")
		(net "P5E_CPU0_PE2_TX_DP<8>")
	)
	(arc
		(start 378.001784 -221.133924)
		(mid 377.927793 -221.41349)
		(end 377.725178 -221.619826)
		(width 0.0889)
		(layer "In15.Cu")
		(net "P5E_CPU0_PE2_TX_DP<8>")
	)
	(arc
		(start 379.411484 -217.082878)
		(mid 379.331322 -217.355067)
		(end 379.129036 -217.554048)
		(width 0.0889)
		(layer "In15.Cu")
		(net "P5E_CPU0_PE2_TX_DP<8>")
	)
	(arc
		(start 378.941584 -217.878406)
		(mid 378.867593 -218.157972)
		(end 378.664978 -218.364308)
		(width 0.0889)
		(layer "In15.Cu")
		(net "P5E_CPU0_PE2_TX_DP<8>")
	)
	(arc
		(start 375.82221 -224.10293)
		(mid 375.812266 -224.098959)
		(end 375.802398 -224.094802)
		(width 0.0889)
		(layer "In15.Cu")
		(net "P5E_CPU0_PE2_TX_DP<8>")
	)
	(arc
		(start 386.08254 -215.926162)
		(mid 385.90353 -215.875865)
		(end 385.722368 -215.91778)
		(width 0.0889)
		(layer "In15.Cu")
		(net "P5E_CPU0_PE2_TX_DP<8>")
	)
	(arc
		(start 386.160264 -215.98509)
		(mid 386.143931 -215.969991)
		(end 386.126736 -215.95588)
		(width 0.0889)
		(layer "In15.Cu")
		(net "P5E_CPU0_PE2_TX_DP<8>")
	)
	(arc
		(start 377.719082 -220.644212)
		(mid 377.922563 -220.845016)
		(end 378.001784 -221.1197)
		(width 0.0889)
		(layer "In15.Cu")
		(net "P5E_CPU0_PE2_TX_DP<8>")
	)
	(arc
		(start 384.202432 -215.926162)
		(mid 384.112176 -215.88844)
		(end 384.015234 -215.875362)
		(width 0.0889)
		(layer "In15.Cu")
		(net "P5E_CPU0_PE2_TX_DP<8>")
	)
	(arc
		(start 381.195834 -215.875362)
		(mid 381.098895 -215.888452)
		(end 381.008636 -215.926162)
		(width 0.0889)
		(layer "In15.Cu")
		(net "P5E_CPU0_PE2_TX_DP<8>")
	)
	(arc
		(start 379.598682 -216.739978)
		(mid 379.463749 -216.873332)
		(end 379.411484 -217.0557)
		(width 0.0889)
		(layer "In15.Cu")
		(net "P5E_CPU0_PE2_TX_DP<8>")
	)
	(arc
		(start 379.120146 -217.559128)
		(mid 378.989232 -217.695488)
		(end 378.941584 -217.878406)
		(width 0.0889)
		(layer "In15.Cu")
		(net "P5E_CPU0_PE2_TX_DP<8>")
	)
	(arc
		(start 386.126736 -215.95588)
		(mid 386.105166 -215.940236)
		(end 386.08254 -215.926162)
		(width 0.0889)
		(layer "In15.Cu")
		(net "P5E_CPU0_PE2_TX_DP<8>")
	)
	(arc
		(start 384.753104 -215.934798)
		(mid 384.476629 -216.002118)
		(end 384.202432 -215.926162)
		(width 0.0889)
		(layer "In15.Cu")
		(net "P5E_CPU0_PE2_TX_DP<8>")
	)
	(arc
		(start 376.592084 -223.575626)
		(mid 376.518168 -223.855128)
		(end 376.315732 -224.061528)
		(width 0.0889)
		(layer "In15.Cu")
		(net "P5E_CPU0_PE2_TX_DP<8>")
	)
	(arc
		(start 378.180346 -219.18676)
		(mid 378.049432 -219.32312)
		(end 378.001784 -219.506038)
		(width 0.0889)
		(layer "In15.Cu")
		(net "P5E_CPU0_PE2_TX_DP<8>")
	)
	(arc
		(start 377.240546 -222.442278)
		(mid 377.109632 -222.578638)
		(end 377.061984 -222.761556)
		(width 0.0889)
		(layer "In15.Cu")
		(net "P5E_CPU0_PE2_TX_DP<8>")
	)
	(arc
		(start 385.687062 -215.938354)
		(mid 385.413221 -216.002098)
		(end 385.142486 -215.926162)
		(width 0.0889)
		(layer "In15.Cu")
		(net "P5E_CPU0_PE2_TX_DP<8>")
	)
	(arc
		(start 380.821184 -216.260426)
		(mid 380.743073 -216.537375)
		(end 380.538736 -216.739978)
		(width 0.0889)
		(layer "In15.Cu")
		(net "P5E_CPU0_PE2_TX_DP<8>")
	)
	(arc
		(start 377.710192 -221.628462)
		(mid 377.579278 -221.764822)
		(end 377.53163 -221.94774)
		(width 0.0889)
		(layer "In15.Cu")
		(net "P5E_CPU0_PE2_TX_DP<8>")
	)
	(arc
		(start 385.142486 -215.926162)
		(mid 384.959981 -215.875924)
		(end 384.776218 -215.921336)
		(width 0.0889)
		(layer "In15.Cu")
		(net "P5E_CPU0_PE2_TX_DP<8>")
	)
	(arc
		(start 376.309636 -224.065084)
		(mid 376.070223 -224.139416)
		(end 375.82221 -224.10293)
		(width 0.0889)
		(layer "In15.Cu")
		(net "P5E_CPU0_PE2_TX_DP<8>")
	)
	(arc
		(start 379.973078 -216.739978)
		(mid 379.78588 -216.689835)
		(end 379.598682 -216.739978)
		(width 0.0889)
		(layer "In15.Cu")
		(net "P5E_CPU0_PE2_TX_DP<8>")
	)
	(arc
		(start 380.999746 -215.931242)
		(mid 380.868832 -216.067602)
		(end 380.821184 -216.25052)
		(width 0.0889)
		(layer "In15.Cu")
		(net "P5E_CPU0_PE2_TX_DP<8>")
	)
	(arc
		(start 377.719082 -219.995496)
		(mid 377.584149 -220.12885)
		(end 377.531884 -220.311218)
		(width 0.0889)
		(layer "In15.Cu")
		(net "P5E_CPU0_PE2_TX_DP<8>")
	)
	(arc
		(start 378.001784 -219.506038)
		(mid 377.927793 -219.785604)
		(end 377.725178 -219.99194)
		(width 0.0889)
		(layer "In15.Cu")
		(net "P5E_CPU0_PE2_TX_DP<8>")
	)
	(arc
		(start 377.53163 -221.963234)
		(mid 377.45226 -222.236968)
		(end 377.249436 -222.437198)
		(width 0.0889)
		(layer "In15.Cu")
		(net "P5E_CPU0_PE2_TX_DP<8>")
	)
	(arc
		(start 377.531884 -220.32849)
		(mid 377.584154 -220.510855)
		(end 377.719082 -220.644212)
		(width 0.0889)
		(layer "In15.Cu")
		(net "P5E_CPU0_PE2_TX_DP<8>")
	)
	(arc
		(start 378.47143 -218.707716)
		(mid 378.39206 -218.98145)
		(end 378.189236 -219.18168)
		(width 0.0889)
		(layer "In15.Cu")
		(net "P5E_CPU0_PE2_TX_DP<8>")
	)
	(arc
		(start 377.061984 -222.780098)
		(mid 376.981822 -223.052287)
		(end 376.779536 -223.251268)
		(width 0.0889)
		(layer "In15.Cu")
		(net "P5E_CPU0_PE2_TX_DP<8>")
	)
	(arc
		(start 376.770646 -223.256348)
		(mid 376.639732 -223.392708)
		(end 376.592084 -223.575626)
		(width 0.0889)
		(layer "In15.Cu")
		(net "P5E_CPU0_PE2_TX_DP<8>")
	)
	(segment
		(start 396.234412 -401.16379)
		(end 396.234412 -401.777962)
		(width 0.13208)
		(layer "F.Cu")
		(net "P5E_CPU0_PE2_TX_DP<7>")
	)
	(segment
		(start 395.908022 -402.104352)
		(end 395.90345 -402.104352)
		(width 0.13208)
		(layer "F.Cu")
		(net "P5E_CPU0_PE2_TX_DP<7>")
	)
	(segment
		(start 396.234412 -401.777962)
		(end 395.908022 -402.104352)
		(width 0.13208)
		(layer "F.Cu")
		(net "P5E_CPU0_PE2_TX_DP<7>")
	)
	(segment
		(start 395.92885 -400.858228)
		(end 396.234412 -401.16379)
		(width 0.13208)
		(layer "F.Cu")
		(net "P5E_CPU0_PE2_TX_DP<7>")
	)
	(segment
		(start 375.087134 -225.739198)
		(end 375.087134 -225.203512)
		(width 0.13208)
		(layer "F.Cu")
		(net "P5E_CPU0_PE2_TX_DP<7>")
	)
	(segment
		(start 375.087134 -225.203512)
		(end 375.08688 -225.203258)
		(width 0.13208)
		(layer "F.Cu")
		(net "P5E_CPU0_PE2_TX_DP<7>")
	)
	(segment
		(start 399.60042 -348.640654)
		(end 397.969994 -368.052858)
		(width 0.14732)
		(layer "In15.Cu")
		(net "P5E_CPU0_PE2_TX_DP<7>")
	)
	(segment
		(start 378.001784 -217.878406)
		(end 378.001784 -217.864182)
		(width 0.0889)
		(layer "In15.Cu")
		(net "P5E_CPU0_PE2_TX_DP<7>")
	)
	(segment
		(start 398.218406 -253.245874)
		(end 394.001244 -308.966616)
		(width 0.14732)
		(layer "In15.Cu")
		(net "P5E_CPU0_PE2_TX_DP<7>")
	)
	(segment
		(start 394.001244 -308.966616)
		(end 401.183348 -339.51291)
		(width 0.14732)
		(layer "In15.Cu")
		(net "P5E_CPU0_PE2_TX_DP<7>")
	)
	(segment
		(start 396.292832 -398.6911)
		(end 396.139924 -398.827752)
		(width 0.14732)
		(layer "In15.Cu")
		(net "P5E_CPU0_PE2_TX_DP<7>")
	)
	(segment
		(start 396.22349 -399.954242)
		(end 396.22349 -400.563588)
		(width 0.14732)
		(layer "In15.Cu")
		(net "P5E_CPU0_PE2_TX_DP<7>")
	)
	(segment
		(start 387.255512 -215.418416)
		(end 387.658864 -215.585548)
		(width 0.14732)
		(layer "In15.Cu")
		(net "P5E_CPU0_PE2_TX_DP<7>")
	)
	(segment
		(start 396.23238 -397.146272)
		(end 396.369032 -397.298926)
		(width 0.14732)
		(layer "In15.Cu")
		(net "P5E_CPU0_PE2_TX_DP<7>")
	)
	(segment
		(start 377.240546 -219.18676)
		(end 377.249436 -219.18168)
		(width 0.0889)
		(layer "In15.Cu")
		(net "P5E_CPU0_PE2_TX_DP<7>")
	)
	(segment
		(start 396.19936 -237.522766)
		(end 398.083532 -249.23877)
		(width 0.14732)
		(layer "In15.Cu")
		(net "P5E_CPU0_PE2_TX_DP<7>")
	)
	(segment
		(start 396.196312 -397.803116)
		(end 396.176246 -398.170908)
		(width 0.14732)
		(layer "In15.Cu")
		(net "P5E_CPU0_PE2_TX_DP<7>")
	)
	(segment
		(start 377.721876 -218.366086)
		(end 377.725178 -218.364308)
		(width 0.0889)
		(layer "In15.Cu")
		(net "P5E_CPU0_PE2_TX_DP<7>")
	)
	(segment
		(start 377.531884 -217.072972)
		(end 377.531884 -217.0557)
		(width 0.0889)
		(layer "In15.Cu")
		(net "P5E_CPU0_PE2_TX_DP<7>")
	)
	(segment
		(start 376.779536 -220.644212)
		(end 376.770646 -220.639132)
		(width 0.0889)
		(layer "In15.Cu")
		(net "P5E_CPU0_PE2_TX_DP<7>")
	)
	(segment
		(start 384.526282 -214.288116)
		(end 384.526282 -214.287862)
		(width 0.14732)
		(layer "In15.Cu")
		(net "P5E_CPU0_PE2_TX_DP<7>")
	)
	(segment
		(start 396.404846 -396.642082)
		(end 396.252446 -396.77848)
		(width 0.14732)
		(layer "In15.Cu")
		(net "P5E_CPU0_PE2_TX_DP<7>")
	)
	(segment
		(start 375.360946 -224.070164)
		(end 375.369836 -224.065084)
		(width 0.0889)
		(layer "In15.Cu")
		(net "P5E_CPU0_PE2_TX_DP<7>")
	)
	(segment
		(start 376.778774 -219.996004)
		(end 376.779536 -219.995496)
		(width 0.0889)
		(layer "In15.Cu")
		(net "P5E_CPU0_PE2_TX_DP<7>")
	)
	(segment
		(start 376.770392 -221.628462)
		(end 376.779282 -221.623382)
		(width 0.0889)
		(layer "In15.Cu")
		(net "P5E_CPU0_PE2_TX_DP<7>")
	)
	(segment
		(start 379.635258 -215.01989)
		(end 379.695202 -215.01989)
		(width 0.0889)
		(layer "In15.Cu")
		(net "P5E_CPU0_PE2_TX_DP<7>")
	)
	(segment
		(start 377.061984 -219.515944)
		(end 377.061984 -219.506038)
		(width 0.0889)
		(layer "In15.Cu")
		(net "P5E_CPU0_PE2_TX_DP<7>")
	)
	(segment
		(start 379.848872 -214.86622)
		(end 381.865378 -214.031068)
		(width 0.14732)
		(layer "In15.Cu")
		(net "P5E_CPU0_PE2_TX_DP<7>")
	)
	(segment
		(start 377.720606 -218.366848)
		(end 377.721876 -218.366086)
		(width 0.0889)
		(layer "In15.Cu")
		(net "P5E_CPU0_PE2_TX_DP<7>")
	)
	(segment
		(start 396.176246 -398.170908)
		(end 396.312898 -398.323562)
		(width 0.14732)
		(layer "In15.Cu")
		(net "P5E_CPU0_PE2_TX_DP<7>")
	)
	(segment
		(start 386.620512 -215.155526)
		(end 386.626354 -215.157812)
		(width 0.14732)
		(layer "In15.Cu")
		(net "P5E_CPU0_PE2_TX_DP<7>")
	)
	(segment
		(start 385.7752 -214.80526)
		(end 386.620512 -215.155526)
		(width 0.14732)
		(layer "In15.Cu")
		(net "P5E_CPU0_PE2_TX_DP<7>")
	)
	(segment
		(start 385.212082 -214.704168)
		(end 385.615942 -214.8713)
		(width 0.14732)
		(layer "In15.Cu")
		(net "P5E_CPU0_PE2_TX_DP<7>")
	)
	(segment
		(start 401.183348 -339.51291)
		(end 399.60042 -348.640654)
		(width 0.14732)
		(layer "In15.Cu")
		(net "P5E_CPU0_PE2_TX_DP<7>")
	)
	(segment
		(start 377.53163 -218.707716)
		(end 377.53163 -218.692222)
		(width 0.0889)
		(layer "In15.Cu")
		(net "P5E_CPU0_PE2_TX_DP<7>")
	)
	(segment
		(start 396.119858 -399.195798)
		(end 396.25651 -399.348198)
		(width 0.14732)
		(layer "In15.Cu")
		(net "P5E_CPU0_PE2_TX_DP<7>")
	)
	(segment
		(start 396.19936 -237.52302)
		(end 396.19936 -237.522766)
		(width 0.14732)
		(layer "In15.Cu")
		(net "P5E_CPU0_PE2_TX_DP<7>")
	)
	(segment
		(start 383.906522 -214.031068)
		(end 384.526282 -214.288116)
		(width 0.14732)
		(layer "In15.Cu")
		(net "P5E_CPU0_PE2_TX_DP<7>")
	)
	(segment
		(start 378.180346 -215.931242)
		(end 378.189236 -215.926162)
		(width 0.0889)
		(layer "In15.Cu")
		(net "P5E_CPU0_PE2_TX_DP<7>")
	)
	(segment
		(start 387.658864 -215.585548)
		(end 393.580112 -223.283526)
		(width 0.14732)
		(layer "In15.Cu")
		(net "P5E_CPU0_PE2_TX_DP<7>")
	)
	(segment
		(start 396.139924 -398.827752)
		(end 396.119858 -399.195798)
		(width 0.14732)
		(layer "In15.Cu")
		(net "P5E_CPU0_PE2_TX_DP<7>")
	)
	(segment
		(start 396.312898 -398.323562)
		(end 396.292832 -398.6911)
		(width 0.14732)
		(layer "In15.Cu")
		(net "P5E_CPU0_PE2_TX_DP<7>")
	)
	(segment
		(start 396.22349 -400.563588)
		(end 395.92885 -400.858228)
		(width 0.14732)
		(layer "In15.Cu")
		(net "P5E_CPU0_PE2_TX_DP<7>")
	)
	(segment
		(start 379.710696 -215.004396)
		(end 379.848872 -214.86622)
		(width 0.14732)
		(layer "In15.Cu")
		(net "P5E_CPU0_PE2_TX_DP<7>")
	)
	(segment
		(start 377.719082 -216.739978)
		(end 377.719844 -216.73947)
		(width 0.0889)
		(layer "In15.Cu")
		(net "P5E_CPU0_PE2_TX_DP<7>")
	)
	(segment
		(start 387.096 -215.484456)
		(end 387.255512 -215.418416)
		(width 0.14732)
		(layer "In15.Cu")
		(net "P5E_CPU0_PE2_TX_DP<7>")
	)
	(segment
		(start 377.71832 -218.368372)
		(end 377.720606 -218.366848)
		(width 0.0889)
		(layer "In15.Cu")
		(net "P5E_CPU0_PE2_TX_DP<7>")
	)
	(segment
		(start 377.719844 -216.73947)
		(end 377.725178 -216.736422)
		(width 0.0889)
		(layer "In15.Cu")
		(net "P5E_CPU0_PE2_TX_DP<7>")
	)
	(segment
		(start 385.615942 -214.8713)
		(end 385.7752 -214.80526)
		(width 0.14732)
		(layer "In15.Cu")
		(net "P5E_CPU0_PE2_TX_DP<7>")
	)
	(segment
		(start 386.69214 -215.31707)
		(end 387.096 -215.484456)
		(width 0.14732)
		(layer "In15.Cu")
		(net "P5E_CPU0_PE2_TX_DP<7>")
	)
	(segment
		(start 396.348966 -397.666464)
		(end 396.196312 -397.803116)
		(width 0.14732)
		(layer "In15.Cu")
		(net "P5E_CPU0_PE2_TX_DP<7>")
	)
	(segment
		(start 398.083532 -249.23877)
		(end 398.218406 -253.24562)
		(width 0.14732)
		(layer "In15.Cu")
		(net "P5E_CPU0_PE2_TX_DP<7>")
	)
	(segment
		(start 386.626354 -215.157812)
		(end 386.626354 -215.157558)
		(width 0.14732)
		(layer "In15.Cu")
		(net "P5E_CPU0_PE2_TX_DP<7>")
	)
	(segment
		(start 378.924312 -215.730836)
		(end 379.635258 -215.01989)
		(width 0.0889)
		(layer "In15.Cu")
		(net "P5E_CPU0_PE2_TX_DP<7>")
	)
	(segment
		(start 385.146042 -214.544656)
		(end 385.212082 -214.704168)
		(width 0.14732)
		(layer "In15.Cu")
		(net "P5E_CPU0_PE2_TX_DP<7>")
	)
	(segment
		(start 396.252446 -396.77848)
		(end 396.23238 -397.146272)
		(width 0.14732)
		(layer "In15.Cu")
		(net "P5E_CPU0_PE2_TX_DP<7>")
	)
	(segment
		(start 375.652284 -223.585532)
		(end 375.652284 -223.56699)
		(width 0.0889)
		(layer "In15.Cu")
		(net "P5E_CPU0_PE2_TX_DP<7>")
	)
	(segment
		(start 396.25651 -399.348198)
		(end 396.22349 -399.954242)
		(width 0.14732)
		(layer "In15.Cu")
		(net "P5E_CPU0_PE2_TX_DP<7>")
	)
	(segment
		(start 377.710192 -218.372944)
		(end 377.71832 -218.368372)
		(width 0.0889)
		(layer "In15.Cu")
		(net "P5E_CPU0_PE2_TX_DP<7>")
	)
	(segment
		(start 377.061984 -221.133924)
		(end 377.061984 -221.115382)
		(width 0.0889)
		(layer "In15.Cu")
		(net "P5E_CPU0_PE2_TX_DP<7>")
	)
	(segment
		(start 396.369032 -397.298926)
		(end 396.348966 -397.666464)
		(width 0.14732)
		(layer "In15.Cu")
		(net "P5E_CPU0_PE2_TX_DP<7>")
	)
	(segment
		(start 384.526282 -214.287862)
		(end 385.146042 -214.544656)
		(width 0.14732)
		(layer "In15.Cu")
		(net "P5E_CPU0_PE2_TX_DP<7>")
	)
	(segment
		(start 376.300746 -222.442278)
		(end 376.309636 -222.437198)
		(width 0.0889)
		(layer "In15.Cu")
		(net "P5E_CPU0_PE2_TX_DP<7>")
	)
	(segment
		(start 397.969994 -368.052858)
		(end 396.404846 -396.642082)
		(width 0.14732)
		(layer "In15.Cu")
		(net "P5E_CPU0_PE2_TX_DP<7>")
	)
	(segment
		(start 393.580112 -223.283526)
		(end 394.312394 -225.789998)
		(width 0.14732)
		(layer "In15.Cu")
		(net "P5E_CPU0_PE2_TX_DP<7>")
	)
	(segment
		(start 378.376434 -215.875362)
		(end 378.575316 -215.875362)
		(width 0.0889)
		(layer "In15.Cu")
		(net "P5E_CPU0_PE2_TX_DP<7>")
	)
	(segment
		(start 375.08688 -225.203258)
		(end 374.930416 -224.93224)
		(width 0.0889)
		(layer "In15.Cu")
		(net "P5E_CPU0_PE2_TX_DP<7>")
	)
	(segment
		(start 374.930416 -224.93224)
		(end 374.954546 -224.843086)
		(width 0.0889)
		(layer "In15.Cu")
		(net "P5E_CPU0_PE2_TX_DP<7>")
	)
	(segment
		(start 376.122184 -222.77578)
		(end 376.122184 -222.761556)
		(width 0.0889)
		(layer "In15.Cu")
		(net "P5E_CPU0_PE2_TX_DP<7>")
	)
	(segment
		(start 386.626354 -215.157558)
		(end 386.69214 -215.31707)
		(width 0.14732)
		(layer "In15.Cu")
		(net "P5E_CPU0_PE2_TX_DP<7>")
	)
	(segment
		(start 381.865378 -214.031068)
		(end 383.906522 -214.031068)
		(width 0.14732)
		(layer "In15.Cu")
		(net "P5E_CPU0_PE2_TX_DP<7>")
	)
	(segment
		(start 378.575316 -215.875362)
		(end 378.924312 -215.730836)
		(width 0.0889)
		(layer "In15.Cu")
		(net "P5E_CPU0_PE2_TX_DP<7>")
	)
	(segment
		(start 379.695202 -215.01989)
		(end 379.710696 -215.004396)
		(width 0.0889)
		(layer "In15.Cu")
		(net "P5E_CPU0_PE2_TX_DP<7>")
	)
	(segment
		(start 376.779282 -221.623382)
		(end 376.785378 -221.619826)
		(width 0.0889)
		(layer "In15.Cu")
		(net "P5E_CPU0_PE2_TX_DP<7>")
	)
	(segment
		(start 376.59183 -221.963234)
		(end 376.59183 -221.94774)
		(width 0.0889)
		(layer "In15.Cu")
		(net "P5E_CPU0_PE2_TX_DP<7>")
	)
	(segment
		(start 398.218406 -253.24562)
		(end 398.218406 -253.245874)
		(width 0.14732)
		(layer "In15.Cu")
		(net "P5E_CPU0_PE2_TX_DP<7>")
	)
	(segment
		(start 376.770646 -220.000576)
		(end 376.778774 -219.996004)
		(width 0.0889)
		(layer "In15.Cu")
		(net "P5E_CPU0_PE2_TX_DP<7>")
	)
	(segment
		(start 394.312394 -225.789998)
		(end 396.19936 -237.52302)
		(width 0.14732)
		(layer "In15.Cu")
		(net "P5E_CPU0_PE2_TX_DP<7>")
	)
	(arc
		(start 377.53163 -218.692222)
		(mid 377.579309 -218.509322)
		(end 377.710192 -218.372944)
		(width 0.0889)
		(layer "In15.Cu")
		(net "P5E_CPU0_PE2_TX_DP<7>")
	)
	(arc
		(start 374.971564 -224.829878)
		(mid 375.126962 -224.633597)
		(end 375.182384 -224.389442)
		(width 0.0889)
		(layer "In15.Cu")
		(net "P5E_CPU0_PE2_TX_DP<7>")
	)
	(arc
		(start 378.001784 -217.864182)
		(mid 377.922565 -217.589497)
		(end 377.719082 -217.388694)
		(width 0.0889)
		(layer "In15.Cu")
		(net "P5E_CPU0_PE2_TX_DP<7>")
	)
	(arc
		(start 376.309636 -222.437198)
		(mid 376.512459 -222.236967)
		(end 376.59183 -221.963234)
		(width 0.0889)
		(layer "In15.Cu")
		(net "P5E_CPU0_PE2_TX_DP<7>")
	)
	(arc
		(start 377.719082 -217.388694)
		(mid 377.584149 -217.25534)
		(end 377.531884 -217.072972)
		(width 0.0889)
		(layer "In15.Cu")
		(net "P5E_CPU0_PE2_TX_DP<7>")
	)
	(arc
		(start 377.249436 -219.18168)
		(mid 377.452259 -218.981449)
		(end 377.53163 -218.707716)
		(width 0.0889)
		(layer "In15.Cu")
		(net "P5E_CPU0_PE2_TX_DP<7>")
	)
	(arc
		(start 375.652284 -223.56699)
		(mid 375.704554 -223.384625)
		(end 375.839482 -223.251268)
		(width 0.0889)
		(layer "In15.Cu")
		(net "P5E_CPU0_PE2_TX_DP<7>")
	)
	(arc
		(start 376.785378 -221.619826)
		(mid 376.987965 -221.413475)
		(end 377.061984 -221.133924)
		(width 0.0889)
		(layer "In15.Cu")
		(net "P5E_CPU0_PE2_TX_DP<7>")
	)
	(arc
		(start 377.531884 -217.0557)
		(mid 377.584154 -216.873335)
		(end 377.719082 -216.739978)
		(width 0.0889)
		(layer "In15.Cu")
		(net "P5E_CPU0_PE2_TX_DP<7>")
	)
	(arc
		(start 375.369836 -224.065084)
		(mid 375.574171 -223.862479)
		(end 375.652284 -223.585532)
		(width 0.0889)
		(layer "In15.Cu")
		(net "P5E_CPU0_PE2_TX_DP<7>")
	)
	(arc
		(start 376.592084 -220.319854)
		(mid 376.639763 -220.136954)
		(end 376.770646 -220.000576)
		(width 0.0889)
		(layer "In15.Cu")
		(net "P5E_CPU0_PE2_TX_DP<7>")
	)
	(arc
		(start 377.061984 -221.115382)
		(mid 376.981822 -220.843193)
		(end 376.779536 -220.644212)
		(width 0.0889)
		(layer "In15.Cu")
		(net "P5E_CPU0_PE2_TX_DP<7>")
	)
	(arc
		(start 378.189236 -215.926162)
		(mid 378.279492 -215.88844)
		(end 378.376434 -215.875362)
		(width 0.0889)
		(layer "In15.Cu")
		(net "P5E_CPU0_PE2_TX_DP<7>")
	)
	(arc
		(start 374.954546 -224.843086)
		(mid 374.963118 -224.836564)
		(end 374.971564 -224.829878)
		(width 0.0889)
		(layer "In15.Cu")
		(net "P5E_CPU0_PE2_TX_DP<7>")
	)
	(arc
		(start 376.59183 -221.94774)
		(mid 376.639509 -221.76484)
		(end 376.770392 -221.628462)
		(width 0.0889)
		(layer "In15.Cu")
		(net "P5E_CPU0_PE2_TX_DP<7>")
	)
	(arc
		(start 375.182384 -224.389442)
		(mid 375.230063 -224.206542)
		(end 375.360946 -224.070164)
		(width 0.0889)
		(layer "In15.Cu")
		(net "P5E_CPU0_PE2_TX_DP<7>")
	)
	(arc
		(start 377.061984 -219.506038)
		(mid 377.109663 -219.323138)
		(end 377.240546 -219.18676)
		(width 0.0889)
		(layer "In15.Cu")
		(net "P5E_CPU0_PE2_TX_DP<7>")
	)
	(arc
		(start 377.725178 -218.364308)
		(mid 377.927765 -218.157957)
		(end 378.001784 -217.878406)
		(width 0.0889)
		(layer "In15.Cu")
		(net "P5E_CPU0_PE2_TX_DP<7>")
	)
	(arc
		(start 376.779536 -219.995496)
		(mid 376.983871 -219.792891)
		(end 377.061984 -219.515944)
		(width 0.0889)
		(layer "In15.Cu")
		(net "P5E_CPU0_PE2_TX_DP<7>")
	)
	(arc
		(start 378.001784 -216.25052)
		(mid 378.049463 -216.06762)
		(end 378.180346 -215.931242)
		(width 0.0889)
		(layer "In15.Cu")
		(net "P5E_CPU0_PE2_TX_DP<7>")
	)
	(arc
		(start 377.725178 -216.736422)
		(mid 377.927765 -216.530071)
		(end 378.001784 -216.25052)
		(width 0.0889)
		(layer "In15.Cu")
		(net "P5E_CPU0_PE2_TX_DP<7>")
	)
	(arc
		(start 375.839482 -223.251268)
		(mid 376.042963 -223.050464)
		(end 376.122184 -222.77578)
		(width 0.0889)
		(layer "In15.Cu")
		(net "P5E_CPU0_PE2_TX_DP<7>")
	)
	(arc
		(start 376.122184 -222.761556)
		(mid 376.169863 -222.578656)
		(end 376.300746 -222.442278)
		(width 0.0889)
		(layer "In15.Cu")
		(net "P5E_CPU0_PE2_TX_DP<7>")
	)
	(arc
		(start 376.770646 -220.639132)
		(mid 376.639732 -220.502772)
		(end 376.592084 -220.319854)
		(width 0.0889)
		(layer "In15.Cu")
		(net "P5E_CPU0_PE2_TX_DP<7>")
	)
	(segment
		(start 398.971262 -402.104352)
		(end 398.96669 -402.104352)
		(width 0.13208)
		(layer "F.Cu")
		(net "P5E_CPU0_PE2_TX_DP<6>")
	)
	(segment
		(start 373.67718 -224.389696)
		(end 373.677434 -224.389442)
		(width 0.13208)
		(layer "F.Cu")
		(net "P5E_CPU0_PE2_TX_DP<6>")
	)
	(segment
		(start 398.99209 -400.858228)
		(end 399.297652 -401.16379)
		(width 0.13208)
		(layer "F.Cu")
		(net "P5E_CPU0_PE2_TX_DP<6>")
	)
	(segment
		(start 399.297652 -401.777962)
		(end 398.971262 -402.104352)
		(width 0.13208)
		(layer "F.Cu")
		(net "P5E_CPU0_PE2_TX_DP<6>")
	)
	(segment
		(start 399.297652 -401.16379)
		(end 399.297652 -401.777962)
		(width 0.13208)
		(layer "F.Cu")
		(net "P5E_CPU0_PE2_TX_DP<6>")
	)
	(segment
		(start 373.67718 -224.925382)
		(end 373.67718 -224.389696)
		(width 0.13208)
		(layer "F.Cu")
		(net "P5E_CPU0_PE2_TX_DP<6>")
	)
	(segment
		(start 376.770392 -218.372944)
		(end 376.779282 -218.367864)
		(width 0.0889)
		(layer "In15.Cu")
		(net "P5E_CPU0_PE2_TX_DP<6>")
	)
	(segment
		(start 399.016474 -248.92)
		(end 399.165064 -253.339854)
		(width 0.14732)
		(layer "In15.Cu")
		(net "P5E_CPU0_PE2_TX_DP<6>")
	)
	(segment
		(start 399.294096 -397.802608)
		(end 399.292826 -398.239234)
		(width 0.14732)
		(layer "In15.Cu")
		(net "P5E_CPU0_PE2_TX_DP<6>")
	)
	(segment
		(start 375.840244 -219.994988)
		(end 375.845578 -219.99194)
		(width 0.0889)
		(layer "In15.Cu")
		(net "P5E_CPU0_PE2_TX_DP<6>")
	)
	(segment
		(start 375.65203 -221.963234)
		(end 375.65203 -221.94774)
		(width 0.0889)
		(layer "In15.Cu")
		(net "P5E_CPU0_PE2_TX_DP<6>")
	)
	(segment
		(start 399.167858 -398.36344)
		(end 399.166334 -398.800574)
		(width 0.14732)
		(layer "In15.Cu")
		(net "P5E_CPU0_PE2_TX_DP<6>")
	)
	(segment
		(start 379.677168 -213.77021)
		(end 379.692662 -213.754716)
		(width 0.0889)
		(layer "In15.Cu")
		(net "P5E_CPU0_PE2_TX_DP<6>")
	)
	(segment
		(start 380.355094 -213.092284)
		(end 384.216148 -213.092284)
		(width 0.14732)
		(layer "In15.Cu")
		(net "P5E_CPU0_PE2_TX_DP<6>")
	)
	(segment
		(start 376.122184 -221.133924)
		(end 376.122184 -221.1197)
		(width 0.0889)
		(layer "In15.Cu")
		(net "P5E_CPU0_PE2_TX_DP<6>")
	)
	(segment
		(start 379.61697 -213.77021)
		(end 379.677168 -213.77021)
		(width 0.0889)
		(layer "In15.Cu")
		(net "P5E_CPU0_PE2_TX_DP<6>")
	)
	(segment
		(start 399.300954 -395.993874)
		(end 399.175732 -396.117826)
		(width 0.14732)
		(layer "In15.Cu")
		(net "P5E_CPU0_PE2_TX_DP<6>")
	)
	(segment
		(start 399.28673 -399.99412)
		(end 399.28673 -400.563588)
		(width 0.14732)
		(layer "In15.Cu")
		(net "P5E_CPU0_PE2_TX_DP<6>")
	)
	(segment
		(start 399.290286 -398.925288)
		(end 399.28673 -399.99412)
		(width 0.14732)
		(layer "In15.Cu")
		(net "P5E_CPU0_PE2_TX_DP<6>")
	)
	(segment
		(start 399.178272 -395.43228)
		(end 399.302224 -395.557248)
		(width 0.14732)
		(layer "In15.Cu")
		(net "P5E_CPU0_PE2_TX_DP<6>")
	)
	(segment
		(start 375.360946 -222.442278)
		(end 375.369836 -222.437198)
		(width 0.0889)
		(layer "In15.Cu")
		(net "P5E_CPU0_PE2_TX_DP<6>")
	)
	(segment
		(start 375.652284 -220.32849)
		(end 375.652284 -220.311218)
		(width 0.0889)
		(layer "In15.Cu")
		(net "P5E_CPU0_PE2_TX_DP<6>")
	)
	(segment
		(start 377.710192 -215.117426)
		(end 377.719082 -215.112346)
		(width 0.0889)
		(layer "In15.Cu")
		(net "P5E_CPU0_PE2_TX_DP<6>")
	)
	(segment
		(start 395.264894 -225.59264)
		(end 399.016474 -248.92)
		(width 0.14732)
		(layer "In15.Cu")
		(net "P5E_CPU0_PE2_TX_DP<6>")
	)
	(segment
		(start 378.622814 -214.764366)
		(end 379.61697 -213.77021)
		(width 0.0889)
		(layer "In15.Cu")
		(net "P5E_CPU0_PE2_TX_DP<6>")
	)
	(segment
		(start 399.179796 -394.995146)
		(end 399.178272 -395.43228)
		(width 0.14732)
		(layer "In15.Cu")
		(net "P5E_CPU0_PE2_TX_DP<6>")
	)
	(segment
		(start 376.779282 -218.367864)
		(end 376.785378 -218.364308)
		(width 0.0889)
		(layer "In15.Cu")
		(net "P5E_CPU0_PE2_TX_DP<6>")
	)
	(segment
		(start 375.839482 -219.995496)
		(end 375.840244 -219.994988)
		(width 0.0889)
		(layer "In15.Cu")
		(net "P5E_CPU0_PE2_TX_DP<6>")
	)
	(segment
		(start 375.830592 -221.628462)
		(end 375.839482 -221.623382)
		(width 0.0889)
		(layer "In15.Cu")
		(net "P5E_CPU0_PE2_TX_DP<6>")
	)
	(segment
		(start 375.839482 -221.623382)
		(end 375.845578 -221.619826)
		(width 0.0889)
		(layer "In15.Cu")
		(net "P5E_CPU0_PE2_TX_DP<6>")
	)
	(segment
		(start 377.061984 -216.260426)
		(end 377.061984 -216.25052)
		(width 0.0889)
		(layer "In15.Cu")
		(net "P5E_CPU0_PE2_TX_DP<6>")
	)
	(segment
		(start 402.20011 -339.53831)
		(end 400.631152 -348.67723)
		(width 0.14732)
		(layer "In15.Cu")
		(net "P5E_CPU0_PE2_TX_DP<6>")
	)
	(segment
		(start 376.59183 -218.707716)
		(end 376.59183 -218.692222)
		(width 0.0889)
		(layer "In15.Cu")
		(net "P5E_CPU0_PE2_TX_DP<6>")
	)
	(segment
		(start 377.53163 -215.452198)
		(end 377.53163 -215.436704)
		(width 0.0889)
		(layer "In15.Cu")
		(net "P5E_CPU0_PE2_TX_DP<6>")
	)
	(segment
		(start 399.29689 -397.116554)
		(end 399.171668 -397.240506)
		(width 0.14732)
		(layer "In15.Cu")
		(net "P5E_CPU0_PE2_TX_DP<6>")
	)
	(segment
		(start 376.778774 -216.740486)
		(end 376.779536 -216.739978)
		(width 0.0889)
		(layer "In15.Cu")
		(net "P5E_CPU0_PE2_TX_DP<6>")
	)
	(segment
		(start 399.304256 -394.870686)
		(end 399.305018 -394.871194)
		(width 0.14732)
		(layer "In15.Cu")
		(net "P5E_CPU0_PE2_TX_DP<6>")
	)
	(segment
		(start 399.302224 -395.557248)
		(end 399.300954 -395.993874)
		(width 0.14732)
		(layer "In15.Cu")
		(net "P5E_CPU0_PE2_TX_DP<6>")
	)
	(segment
		(start 394.965682 -308.624732)
		(end 402.20011 -339.53831)
		(width 0.14732)
		(layer "In15.Cu")
		(net "P5E_CPU0_PE2_TX_DP<6>")
	)
	(segment
		(start 399.171668 -397.240506)
		(end 399.170144 -397.67764)
		(width 0.14732)
		(layer "In15.Cu")
		(net "P5E_CPU0_PE2_TX_DP<6>")
	)
	(segment
		(start 399.166334 -398.800574)
		(end 399.290286 -398.925288)
		(width 0.14732)
		(layer "In15.Cu")
		(net "P5E_CPU0_PE2_TX_DP<6>")
	)
	(segment
		(start 399.292826 -398.239234)
		(end 399.167858 -398.36344)
		(width 0.14732)
		(layer "In15.Cu")
		(net "P5E_CPU0_PE2_TX_DP<6>")
	)
	(segment
		(start 374.430036 -224.065084)
		(end 374.436132 -224.061528)
		(width 0.0889)
		(layer "In15.Cu")
		(net "P5E_CPU0_PE2_TX_DP<6>")
	)
	(segment
		(start 376.300746 -219.18676)
		(end 376.309636 -219.18168)
		(width 0.0889)
		(layer "In15.Cu")
		(net "P5E_CPU0_PE2_TX_DP<6>")
	)
	(segment
		(start 400.631152 -348.67723)
		(end 399.392648 -369.377722)
		(width 0.14732)
		(layer "In15.Cu")
		(net "P5E_CPU0_PE2_TX_DP<6>")
	)
	(segment
		(start 377.240546 -215.931242)
		(end 377.249436 -215.926162)
		(width 0.0889)
		(layer "In15.Cu")
		(net "P5E_CPU0_PE2_TX_DP<6>")
	)
	(segment
		(start 379.692662 -213.754716)
		(end 380.355094 -213.092284)
		(width 0.14732)
		(layer "In15.Cu")
		(net "P5E_CPU0_PE2_TX_DP<6>")
	)
	(segment
		(start 394.487654 -222.926402)
		(end 395.264894 -225.59264)
		(width 0.14732)
		(layer "In15.Cu")
		(net "P5E_CPU0_PE2_TX_DP<6>")
	)
	(segment
		(start 375.182384 -222.780098)
		(end 375.182384 -222.761556)
		(width 0.0889)
		(layer "In15.Cu")
		(net "P5E_CPU0_PE2_TX_DP<6>")
	)
	(segment
		(start 399.165064 -253.339854)
		(end 399.165064 -253.340108)
		(width 0.14732)
		(layer "In15.Cu")
		(net "P5E_CPU0_PE2_TX_DP<6>")
	)
	(segment
		(start 376.779536 -217.388694)
		(end 376.770646 -217.383614)
		(width 0.0889)
		(layer "In15.Cu")
		(net "P5E_CPU0_PE2_TX_DP<6>")
	)
	(segment
		(start 377.90628 -215.061292)
		(end 378.622814 -214.764366)
		(width 0.0889)
		(layer "In15.Cu")
		(net "P5E_CPU0_PE2_TX_DP<6>")
	)
	(segment
		(start 399.29816 -396.679928)
		(end 399.29689 -397.116554)
		(width 0.14732)
		(layer "In15.Cu")
		(net "P5E_CPU0_PE2_TX_DP<6>")
	)
	(segment
		(start 384.216148 -213.092284)
		(end 388.345934 -214.80272)
		(width 0.14732)
		(layer "In15.Cu")
		(net "P5E_CPU0_PE2_TX_DP<6>")
	)
	(segment
		(start 399.170144 -397.67764)
		(end 399.294096 -397.802608)
		(width 0.14732)
		(layer "In15.Cu")
		(net "P5E_CPU0_PE2_TX_DP<6>")
	)
	(segment
		(start 388.345934 -214.80272)
		(end 394.487654 -222.926402)
		(width 0.14732)
		(layer "In15.Cu")
		(net "P5E_CPU0_PE2_TX_DP<6>")
	)
	(segment
		(start 373.833898 -224.118424)
		(end 373.922798 -224.094802)
		(width 0.0889)
		(layer "In15.Cu")
		(net "P5E_CPU0_PE2_TX_DP<6>")
	)
	(segment
		(start 399.392648 -369.377722)
		(end 399.304256 -394.870686)
		(width 0.14732)
		(layer "In15.Cu")
		(net "P5E_CPU0_PE2_TX_DP<6>")
	)
	(segment
		(start 399.305018 -394.871194)
		(end 399.179796 -394.995146)
		(width 0.14732)
		(layer "In15.Cu")
		(net "P5E_CPU0_PE2_TX_DP<6>")
	)
	(segment
		(start 399.175732 -396.117826)
		(end 399.174208 -396.55496)
		(width 0.14732)
		(layer "In15.Cu")
		(net "P5E_CPU0_PE2_TX_DP<6>")
	)
	(segment
		(start 399.174208 -396.55496)
		(end 399.29816 -396.679928)
		(width 0.14732)
		(layer "In15.Cu")
		(net "P5E_CPU0_PE2_TX_DP<6>")
	)
	(segment
		(start 373.677434 -224.389442)
		(end 373.833898 -224.118424)
		(width 0.0889)
		(layer "In15.Cu")
		(net "P5E_CPU0_PE2_TX_DP<6>")
	)
	(segment
		(start 399.28673 -400.563588)
		(end 398.99209 -400.858228)
		(width 0.14732)
		(layer "In15.Cu")
		(net "P5E_CPU0_PE2_TX_DP<6>")
	)
	(segment
		(start 377.061984 -217.878406)
		(end 377.061984 -217.859864)
		(width 0.0889)
		(layer "In15.Cu")
		(net "P5E_CPU0_PE2_TX_DP<6>")
	)
	(segment
		(start 399.165064 -253.340108)
		(end 394.965682 -308.624732)
		(width 0.14732)
		(layer "In15.Cu")
		(net "P5E_CPU0_PE2_TX_DP<6>")
	)
	(segment
		(start 376.770646 -216.745058)
		(end 376.778774 -216.740486)
		(width 0.0889)
		(layer "In15.Cu")
		(net "P5E_CPU0_PE2_TX_DP<6>")
	)
	(segment
		(start 374.891046 -223.256348)
		(end 374.899936 -223.251268)
		(width 0.0889)
		(layer "In15.Cu")
		(net "P5E_CPU0_PE2_TX_DP<6>")
	)
	(arc
		(start 374.712484 -223.575626)
		(mid 374.760163 -223.392726)
		(end 374.891046 -223.256348)
		(width 0.0889)
		(layer "In15.Cu")
		(net "P5E_CPU0_PE2_TX_DP<6>")
	)
	(arc
		(start 376.122184 -221.1197)
		(mid 376.042965 -220.845015)
		(end 375.839482 -220.644212)
		(width 0.0889)
		(layer "In15.Cu")
		(net "P5E_CPU0_PE2_TX_DP<6>")
	)
	(arc
		(start 376.309636 -219.18168)
		(mid 376.512459 -218.981449)
		(end 376.59183 -218.707716)
		(width 0.0889)
		(layer "In15.Cu")
		(net "P5E_CPU0_PE2_TX_DP<6>")
	)
	(arc
		(start 377.249436 -215.926162)
		(mid 377.452259 -215.725931)
		(end 377.53163 -215.452198)
		(width 0.0889)
		(layer "In15.Cu")
		(net "P5E_CPU0_PE2_TX_DP<6>")
	)
	(arc
		(start 375.845578 -221.619826)
		(mid 376.048165 -221.413475)
		(end 376.122184 -221.133924)
		(width 0.0889)
		(layer "In15.Cu")
		(net "P5E_CPU0_PE2_TX_DP<6>")
	)
	(arc
		(start 375.369836 -222.437198)
		(mid 375.572659 -222.236967)
		(end 375.65203 -221.963234)
		(width 0.0889)
		(layer "In15.Cu")
		(net "P5E_CPU0_PE2_TX_DP<6>")
	)
	(arc
		(start 377.719082 -215.112346)
		(mid 377.809318 -215.074476)
		(end 377.90628 -215.061292)
		(width 0.0889)
		(layer "In15.Cu")
		(net "P5E_CPU0_PE2_TX_DP<6>")
	)
	(arc
		(start 377.061984 -216.25052)
		(mid 377.109663 -216.06762)
		(end 377.240546 -215.931242)
		(width 0.0889)
		(layer "In15.Cu")
		(net "P5E_CPU0_PE2_TX_DP<6>")
	)
	(arc
		(start 377.53163 -215.436704)
		(mid 377.531682 -215.429337)
		(end 377.531884 -215.421972)
		(width 0.0889)
		(layer "In15.Cu")
		(net "P5E_CPU0_PE2_TX_DP<6>")
	)
	(arc
		(start 375.652284 -220.311218)
		(mid 375.704554 -220.128853)
		(end 375.839482 -219.995496)
		(width 0.0889)
		(layer "In15.Cu")
		(net "P5E_CPU0_PE2_TX_DP<6>")
	)
	(arc
		(start 377.061984 -217.859864)
		(mid 376.981822 -217.587675)
		(end 376.779536 -217.388694)
		(width 0.0889)
		(layer "In15.Cu")
		(net "P5E_CPU0_PE2_TX_DP<6>")
	)
	(arc
		(start 376.59183 -218.692222)
		(mid 376.639509 -218.509322)
		(end 376.770392 -218.372944)
		(width 0.0889)
		(layer "In15.Cu")
		(net "P5E_CPU0_PE2_TX_DP<6>")
	)
	(arc
		(start 376.770646 -217.383614)
		(mid 376.592049 -217.064336)
		(end 376.770646 -216.745058)
		(width 0.0889)
		(layer "In15.Cu")
		(net "P5E_CPU0_PE2_TX_DP<6>")
	)
	(arc
		(start 375.839482 -220.644212)
		(mid 375.704549 -220.510858)
		(end 375.652284 -220.32849)
		(width 0.0889)
		(layer "In15.Cu")
		(net "P5E_CPU0_PE2_TX_DP<6>")
	)
	(arc
		(start 373.922798 -224.094802)
		(mid 373.932665 -224.098961)
		(end 373.94261 -224.10293)
		(width 0.0889)
		(layer "In15.Cu")
		(net "P5E_CPU0_PE2_TX_DP<6>")
	)
	(arc
		(start 376.785378 -218.364308)
		(mid 376.987965 -218.157957)
		(end 377.061984 -217.878406)
		(width 0.0889)
		(layer "In15.Cu")
		(net "P5E_CPU0_PE2_TX_DP<6>")
	)
	(arc
		(start 374.436132 -224.061528)
		(mid 374.638545 -223.855115)
		(end 374.712484 -223.575626)
		(width 0.0889)
		(layer "In15.Cu")
		(net "P5E_CPU0_PE2_TX_DP<6>")
	)
	(arc
		(start 377.531884 -215.421972)
		(mid 377.582938 -215.247392)
		(end 377.710192 -215.117426)
		(width 0.0889)
		(layer "In15.Cu")
		(net "P5E_CPU0_PE2_TX_DP<6>")
	)
	(arc
		(start 375.65203 -221.94774)
		(mid 375.699709 -221.76484)
		(end 375.830592 -221.628462)
		(width 0.0889)
		(layer "In15.Cu")
		(net "P5E_CPU0_PE2_TX_DP<6>")
	)
	(arc
		(start 375.182384 -222.761556)
		(mid 375.230063 -222.578656)
		(end 375.360946 -222.442278)
		(width 0.0889)
		(layer "In15.Cu")
		(net "P5E_CPU0_PE2_TX_DP<6>")
	)
	(arc
		(start 375.845578 -219.99194)
		(mid 376.048165 -219.785589)
		(end 376.122184 -219.506038)
		(width 0.0889)
		(layer "In15.Cu")
		(net "P5E_CPU0_PE2_TX_DP<6>")
	)
	(arc
		(start 374.899936 -223.251268)
		(mid 375.102222 -223.052287)
		(end 375.182384 -222.780098)
		(width 0.0889)
		(layer "In15.Cu")
		(net "P5E_CPU0_PE2_TX_DP<6>")
	)
	(arc
		(start 373.94261 -224.10293)
		(mid 374.190621 -224.139395)
		(end 374.430036 -224.065084)
		(width 0.0889)
		(layer "In15.Cu")
		(net "P5E_CPU0_PE2_TX_DP<6>")
	)
	(arc
		(start 376.779536 -216.739978)
		(mid 376.983871 -216.537373)
		(end 377.061984 -216.260426)
		(width 0.0889)
		(layer "In15.Cu")
		(net "P5E_CPU0_PE2_TX_DP<6>")
	)
	(arc
		(start 376.122184 -219.506038)
		(mid 376.169863 -219.323138)
		(end 376.300746 -219.18676)
		(width 0.0889)
		(layer "In15.Cu")
		(net "P5E_CPU0_PE2_TX_DP<6>")
	)
	(segment
		(start 373.207534 -225.203512)
		(end 373.20728 -225.203258)
		(width 0.13208)
		(layer "F.Cu")
		(net "P5E_CPU0_PE2_TX_DP<5>")
	)
	(segment
		(start 402.05533 -400.858228)
		(end 402.360892 -401.16379)
		(width 0.13208)
		(layer "F.Cu")
		(net "P5E_CPU0_PE2_TX_DP<5>")
	)
	(segment
		(start 402.034502 -402.104352)
		(end 402.02993 -402.104352)
		(width 0.13208)
		(layer "F.Cu")
		(net "P5E_CPU0_PE2_TX_DP<5>")
	)
	(segment
		(start 402.360892 -401.777962)
		(end 402.034502 -402.104352)
		(width 0.13208)
		(layer "F.Cu")
		(net "P5E_CPU0_PE2_TX_DP<5>")
	)
	(segment
		(start 402.360892 -401.16379)
		(end 402.360892 -401.777962)
		(width 0.13208)
		(layer "F.Cu")
		(net "P5E_CPU0_PE2_TX_DP<5>")
	)
	(segment
		(start 373.207534 -225.739198)
		(end 373.207534 -225.203512)
		(width 0.13208)
		(layer "F.Cu")
		(net "P5E_CPU0_PE2_TX_DP<5>")
	)
	(segment
		(start 375.837958 -218.368626)
		(end 375.839482 -218.367864)
		(width 0.0889)
		(layer "In15.Cu")
		(net "P5E_CPU0_PE2_TX_DP<5>")
	)
	(segment
		(start 402.310346 -399.119344)
		(end 402.349716 -399.854928)
		(width 0.14732)
		(layer "In15.Cu")
		(net "P5E_CPU0_PE2_TX_DP<5>")
	)
	(segment
		(start 374.891046 -220.000576)
		(end 374.899174 -219.996004)
		(width 0.0889)
		(layer "In15.Cu")
		(net "P5E_CPU0_PE2_TX_DP<5>")
	)
	(segment
		(start 396.191994 -225.405188)
		(end 399.940018 -248.69013)
		(width 0.14732)
		(layer "In15.Cu")
		(net "P5E_CPU0_PE2_TX_DP<5>")
	)
	(segment
		(start 402.034248 -396.253462)
		(end 402.057616 -396.689834)
		(width 0.14732)
		(layer "In15.Cu")
		(net "P5E_CPU0_PE2_TX_DP<5>")
	)
	(segment
		(start 400.098768 -253.406656)
		(end 395.92123 -308.497986)
		(width 0.14732)
		(layer "In15.Cu")
		(net "P5E_CPU0_PE2_TX_DP<5>")
	)
	(segment
		(start 401.974304 -395.137386)
		(end 401.997672 -395.573758)
		(width 0.14732)
		(layer "In15.Cu")
		(net "P5E_CPU0_PE2_TX_DP<5>")
	)
	(segment
		(start 376.592084 -215.26246)
		(end 376.837448 -214.670386)
		(width 0.0889)
		(layer "In15.Cu")
		(net "P5E_CPU0_PE2_TX_DP<5>")
	)
	(segment
		(start 374.899936 -220.644212)
		(end 374.891046 -220.639132)
		(width 0.0889)
		(layer "In15.Cu")
		(net "P5E_CPU0_PE2_TX_DP<5>")
	)
	(segment
		(start 402.18614 -396.80515)
		(end 402.209508 -397.241268)
		(width 0.14732)
		(layer "In15.Cu")
		(net "P5E_CPU0_PE2_TX_DP<5>")
	)
	(segment
		(start 376.59183 -215.452198)
		(end 376.59183 -215.436704)
		(width 0.0889)
		(layer "In15.Cu")
		(net "P5E_CPU0_PE2_TX_DP<5>")
	)
	(segment
		(start 402.34997 -399.857468)
		(end 402.34997 -400.563588)
		(width 0.14732)
		(layer "In15.Cu")
		(net "P5E_CPU0_PE2_TX_DP<5>")
	)
	(segment
		(start 402.08962 -395.009116)
		(end 401.974304 -395.137386)
		(width 0.14732)
		(layer "In15.Cu")
		(net "P5E_CPU0_PE2_TX_DP<5>")
	)
	(segment
		(start 402.057616 -396.689834)
		(end 402.18614 -396.80515)
		(width 0.14732)
		(layer "In15.Cu")
		(net "P5E_CPU0_PE2_TX_DP<5>")
	)
	(segment
		(start 384.388614 -212.146388)
		(end 389.156194 -214.121238)
		(width 0.14732)
		(layer "In15.Cu")
		(net "P5E_CPU0_PE2_TX_DP<5>")
	)
	(segment
		(start 376.592084 -215.421972)
		(end 376.592084 -215.26246)
		(width 0.0889)
		(layer "In15.Cu")
		(net "P5E_CPU0_PE2_TX_DP<5>")
	)
	(segment
		(start 375.839482 -218.367864)
		(end 375.840244 -218.367356)
		(width 0.0889)
		(layer "In15.Cu")
		(net "P5E_CPU0_PE2_TX_DP<5>")
	)
	(segment
		(start 402.181822 -399.004028)
		(end 402.310346 -399.119344)
		(width 0.14732)
		(layer "In15.Cu")
		(net "P5E_CPU0_PE2_TX_DP<5>")
	)
	(segment
		(start 375.840244 -218.367356)
		(end 375.845578 -218.364308)
		(width 0.0889)
		(layer "In15.Cu")
		(net "P5E_CPU0_PE2_TX_DP<5>")
	)
	(segment
		(start 400.727418 -369.610894)
		(end 402.089874 -395.008862)
		(width 0.14732)
		(layer "In15.Cu")
		(net "P5E_CPU0_PE2_TX_DP<5>")
	)
	(segment
		(start 375.360946 -219.18676)
		(end 375.369836 -219.18168)
		(width 0.0889)
		(layer "In15.Cu")
		(net "P5E_CPU0_PE2_TX_DP<5>")
	)
	(segment
		(start 402.349716 -399.854928)
		(end 402.349716 -399.857214)
		(width 0.14732)
		(layer "In15.Cu")
		(net "P5E_CPU0_PE2_TX_DP<5>")
	)
	(segment
		(start 375.182384 -219.515944)
		(end 375.182384 -219.506038)
		(width 0.0889)
		(layer "In15.Cu")
		(net "P5E_CPU0_PE2_TX_DP<5>")
	)
	(segment
		(start 402.094192 -397.369538)
		(end 402.11756 -397.80591)
		(width 0.14732)
		(layer "In15.Cu")
		(net "P5E_CPU0_PE2_TX_DP<5>")
	)
	(segment
		(start 395.92123 -308.497986)
		(end 403.196298 -339.696806)
		(width 0.14732)
		(layer "In15.Cu")
		(net "P5E_CPU0_PE2_TX_DP<5>")
	)
	(segment
		(start 377.844304 -213.66353)
		(end 377.904248 -213.66353)
		(width 0.0889)
		(layer "In15.Cu")
		(net "P5E_CPU0_PE2_TX_DP<5>")
	)
	(segment
		(start 373.20728 -225.203258)
		(end 373.050816 -224.93224)
		(width 0.0889)
		(layer "In15.Cu")
		(net "P5E_CPU0_PE2_TX_DP<5>")
	)
	(segment
		(start 402.246084 -397.921226)
		(end 402.27377 -398.439132)
		(width 0.14732)
		(layer "In15.Cu")
		(net "P5E_CPU0_PE2_TX_DP<5>")
	)
	(segment
		(start 375.830592 -218.372944)
		(end 375.837958 -218.368626)
		(width 0.0889)
		(layer "In15.Cu")
		(net "P5E_CPU0_PE2_TX_DP<5>")
	)
	(segment
		(start 399.940018 -248.69013)
		(end 400.098768 -253.406402)
		(width 0.14732)
		(layer "In15.Cu")
		(net "P5E_CPU0_PE2_TX_DP<5>")
	)
	(segment
		(start 390.491472 -215.885268)
		(end 390.46785 -216.055956)
		(width 0.14732)
		(layer "In15.Cu")
		(net "P5E_CPU0_PE2_TX_DP<5>")
	)
	(segment
		(start 374.890792 -221.628462)
		(end 374.899682 -221.623382)
		(width 0.0889)
		(layer "In15.Cu")
		(net "P5E_CPU0_PE2_TX_DP<5>")
	)
	(segment
		(start 375.652284 -217.072972)
		(end 375.652284 -217.0557)
		(width 0.0889)
		(layer "In15.Cu")
		(net "P5E_CPU0_PE2_TX_DP<5>")
	)
	(segment
		(start 374.242584 -222.77578)
		(end 374.242584 -222.761556)
		(width 0.0889)
		(layer "In15.Cu")
		(net "P5E_CPU0_PE2_TX_DP<5>")
	)
	(segment
		(start 380.006352 -212.146388)
		(end 384.388614 -212.146388)
		(width 0.14732)
		(layer "In15.Cu")
		(net "P5E_CPU0_PE2_TX_DP<5>")
	)
	(segment
		(start 402.34997 -400.563588)
		(end 402.05533 -400.858228)
		(width 0.14732)
		(layer "In15.Cu")
		(net "P5E_CPU0_PE2_TX_DP<5>")
	)
	(segment
		(start 373.481346 -224.070164)
		(end 373.490236 -224.065084)
		(width 0.0889)
		(layer "In15.Cu")
		(net "P5E_CPU0_PE2_TX_DP<5>")
	)
	(segment
		(start 390.46785 -216.055956)
		(end 390.731756 -216.404698)
		(width 0.14732)
		(layer "In15.Cu")
		(net "P5E_CPU0_PE2_TX_DP<5>")
	)
	(segment
		(start 395.263624 -222.189294)
		(end 396.191994 -225.405188)
		(width 0.14732)
		(layer "In15.Cu")
		(net "P5E_CPU0_PE2_TX_DP<5>")
	)
	(segment
		(start 402.149564 -396.125192)
		(end 402.034248 -396.253462)
		(width 0.14732)
		(layer "In15.Cu")
		(net "P5E_CPU0_PE2_TX_DP<5>")
	)
	(segment
		(start 376.837448 -214.670386)
		(end 377.844304 -213.66353)
		(width 0.0889)
		(layer "In15.Cu")
		(net "P5E_CPU0_PE2_TX_DP<5>")
	)
	(segment
		(start 373.050816 -224.93224)
		(end 373.074946 -224.843086)
		(width 0.0889)
		(layer "In15.Cu")
		(net "P5E_CPU0_PE2_TX_DP<5>")
	)
	(segment
		(start 373.772684 -223.585532)
		(end 373.772684 -223.56699)
		(width 0.0889)
		(layer "In15.Cu")
		(net "P5E_CPU0_PE2_TX_DP<5>")
	)
	(segment
		(start 375.182384 -221.133924)
		(end 375.182384 -221.115382)
		(width 0.0889)
		(layer "In15.Cu")
		(net "P5E_CPU0_PE2_TX_DP<5>")
	)
	(segment
		(start 377.919742 -213.648036)
		(end 379.007624 -212.560154)
		(width 0.14732)
		(layer "In15.Cu")
		(net "P5E_CPU0_PE2_TX_DP<5>")
	)
	(segment
		(start 402.158454 -398.567402)
		(end 402.181822 -399.004028)
		(width 0.14732)
		(layer "In15.Cu")
		(net "P5E_CPU0_PE2_TX_DP<5>")
	)
	(segment
		(start 402.27377 -398.439132)
		(end 402.158454 -398.567402)
		(width 0.14732)
		(layer "In15.Cu")
		(net "P5E_CPU0_PE2_TX_DP<5>")
	)
	(segment
		(start 401.712684 -348.249494)
		(end 400.727418 -369.610894)
		(width 0.14732)
		(layer "In15.Cu")
		(net "P5E_CPU0_PE2_TX_DP<5>")
	)
	(segment
		(start 402.089874 -395.008862)
		(end 402.08962 -395.009116)
		(width 0.14732)
		(layer "In15.Cu")
		(net "P5E_CPU0_PE2_TX_DP<5>")
	)
	(segment
		(start 390.731756 -216.404698)
		(end 390.902698 -216.42832)
		(width 0.14732)
		(layer "In15.Cu")
		(net "P5E_CPU0_PE2_TX_DP<5>")
	)
	(segment
		(start 377.904248 -213.66353)
		(end 377.919742 -213.648036)
		(width 0.0889)
		(layer "In15.Cu")
		(net "P5E_CPU0_PE2_TX_DP<5>")
	)
	(segment
		(start 374.421146 -222.442278)
		(end 374.430036 -222.437198)
		(width 0.0889)
		(layer "In15.Cu")
		(net "P5E_CPU0_PE2_TX_DP<5>")
	)
	(segment
		(start 379.007624 -212.560154)
		(end 380.006352 -212.146388)
		(width 0.14732)
		(layer "In15.Cu")
		(net "P5E_CPU0_PE2_TX_DP<5>")
	)
	(segment
		(start 401.997672 -395.573758)
		(end 402.126196 -395.689074)
		(width 0.14732)
		(layer "In15.Cu")
		(net "P5E_CPU0_PE2_TX_DP<5>")
	)
	(segment
		(start 375.65203 -218.707716)
		(end 375.65203 -218.692222)
		(width 0.0889)
		(layer "In15.Cu")
		(net "P5E_CPU0_PE2_TX_DP<5>")
	)
	(segment
		(start 390.902698 -216.42832)
		(end 395.263624 -222.189294)
		(width 0.14732)
		(layer "In15.Cu")
		(net "P5E_CPU0_PE2_TX_DP<5>")
	)
	(segment
		(start 400.098768 -253.406402)
		(end 400.098768 -253.406656)
		(width 0.14732)
		(layer "In15.Cu")
		(net "P5E_CPU0_PE2_TX_DP<5>")
	)
	(segment
		(start 376.300746 -215.931242)
		(end 376.309636 -215.926162)
		(width 0.0889)
		(layer "In15.Cu")
		(net "P5E_CPU0_PE2_TX_DP<5>")
	)
	(segment
		(start 403.196298 -339.696806)
		(end 401.712684 -348.249494)
		(width 0.14732)
		(layer "In15.Cu")
		(net "P5E_CPU0_PE2_TX_DP<5>")
	)
	(segment
		(start 402.209508 -397.241268)
		(end 402.094192 -397.369538)
		(width 0.14732)
		(layer "In15.Cu")
		(net "P5E_CPU0_PE2_TX_DP<5>")
	)
	(segment
		(start 374.899174 -219.996004)
		(end 374.899936 -219.995496)
		(width 0.0889)
		(layer "In15.Cu")
		(net "P5E_CPU0_PE2_TX_DP<5>")
	)
	(segment
		(start 374.71223 -221.963234)
		(end 374.71223 -221.94774)
		(width 0.0889)
		(layer "In15.Cu")
		(net "P5E_CPU0_PE2_TX_DP<5>")
	)
	(segment
		(start 402.11756 -397.80591)
		(end 402.246084 -397.921226)
		(width 0.14732)
		(layer "In15.Cu")
		(net "P5E_CPU0_PE2_TX_DP<5>")
	)
	(segment
		(start 374.899682 -221.623382)
		(end 374.905778 -221.619826)
		(width 0.0889)
		(layer "In15.Cu")
		(net "P5E_CPU0_PE2_TX_DP<5>")
	)
	(segment
		(start 376.122184 -217.878406)
		(end 376.122184 -217.864182)
		(width 0.0889)
		(layer "In15.Cu")
		(net "P5E_CPU0_PE2_TX_DP<5>")
	)
	(segment
		(start 389.156194 -214.121238)
		(end 390.491472 -215.885268)
		(width 0.14732)
		(layer "In15.Cu")
		(net "P5E_CPU0_PE2_TX_DP<5>")
	)
	(segment
		(start 402.126196 -395.689074)
		(end 402.149564 -396.125192)
		(width 0.14732)
		(layer "In15.Cu")
		(net "P5E_CPU0_PE2_TX_DP<5>")
	)
	(segment
		(start 375.840244 -216.73947)
		(end 375.845578 -216.736422)
		(width 0.0889)
		(layer "In15.Cu")
		(net "P5E_CPU0_PE2_TX_DP<5>")
	)
	(segment
		(start 375.839482 -216.739978)
		(end 375.840244 -216.73947)
		(width 0.0889)
		(layer "In15.Cu")
		(net "P5E_CPU0_PE2_TX_DP<5>")
	)
	(segment
		(start 402.349716 -399.857214)
		(end 402.34997 -399.857468)
		(width 0.14732)
		(layer "In15.Cu")
		(net "P5E_CPU0_PE2_TX_DP<5>")
	)
	(arc
		(start 374.71223 -221.94774)
		(mid 374.759909 -221.76484)
		(end 374.890792 -221.628462)
		(width 0.0889)
		(layer "In15.Cu")
		(net "P5E_CPU0_PE2_TX_DP<5>")
	)
	(arc
		(start 376.59183 -215.436704)
		(mid 376.591882 -215.429337)
		(end 376.592084 -215.421972)
		(width 0.0889)
		(layer "In15.Cu")
		(net "P5E_CPU0_PE2_TX_DP<5>")
	)
	(arc
		(start 376.122184 -217.864182)
		(mid 376.042965 -217.589497)
		(end 375.839482 -217.388694)
		(width 0.0889)
		(layer "In15.Cu")
		(net "P5E_CPU0_PE2_TX_DP<5>")
	)
	(arc
		(start 375.369836 -219.18168)
		(mid 375.572659 -218.981449)
		(end 375.65203 -218.707716)
		(width 0.0889)
		(layer "In15.Cu")
		(net "P5E_CPU0_PE2_TX_DP<5>")
	)
	(arc
		(start 375.182384 -221.115382)
		(mid 375.102222 -220.843193)
		(end 374.899936 -220.644212)
		(width 0.0889)
		(layer "In15.Cu")
		(net "P5E_CPU0_PE2_TX_DP<5>")
	)
	(arc
		(start 373.074946 -224.843086)
		(mid 373.083518 -224.836564)
		(end 373.091964 -224.829878)
		(width 0.0889)
		(layer "In15.Cu")
		(net "P5E_CPU0_PE2_TX_DP<5>")
	)
	(arc
		(start 373.959882 -223.251268)
		(mid 374.163363 -223.050464)
		(end 374.242584 -222.77578)
		(width 0.0889)
		(layer "In15.Cu")
		(net "P5E_CPU0_PE2_TX_DP<5>")
	)
	(arc
		(start 373.772684 -223.56699)
		(mid 373.824954 -223.384625)
		(end 373.959882 -223.251268)
		(width 0.0889)
		(layer "In15.Cu")
		(net "P5E_CPU0_PE2_TX_DP<5>")
	)
	(arc
		(start 374.905778 -221.619826)
		(mid 375.108365 -221.413475)
		(end 375.182384 -221.133924)
		(width 0.0889)
		(layer "In15.Cu")
		(net "P5E_CPU0_PE2_TX_DP<5>")
	)
	(arc
		(start 376.309636 -215.926162)
		(mid 376.512459 -215.725931)
		(end 376.59183 -215.452198)
		(width 0.0889)
		(layer "In15.Cu")
		(net "P5E_CPU0_PE2_TX_DP<5>")
	)
	(arc
		(start 374.899936 -219.995496)
		(mid 375.104271 -219.792891)
		(end 375.182384 -219.515944)
		(width 0.0889)
		(layer "In15.Cu")
		(net "P5E_CPU0_PE2_TX_DP<5>")
	)
	(arc
		(start 375.845578 -218.364308)
		(mid 376.048165 -218.157957)
		(end 376.122184 -217.878406)
		(width 0.0889)
		(layer "In15.Cu")
		(net "P5E_CPU0_PE2_TX_DP<5>")
	)
	(arc
		(start 374.430036 -222.437198)
		(mid 374.632859 -222.236967)
		(end 374.71223 -221.963234)
		(width 0.0889)
		(layer "In15.Cu")
		(net "P5E_CPU0_PE2_TX_DP<5>")
	)
	(arc
		(start 374.712484 -220.319854)
		(mid 374.760163 -220.136954)
		(end 374.891046 -220.000576)
		(width 0.0889)
		(layer "In15.Cu")
		(net "P5E_CPU0_PE2_TX_DP<5>")
	)
	(arc
		(start 374.891046 -220.639132)
		(mid 374.760132 -220.502772)
		(end 374.712484 -220.319854)
		(width 0.0889)
		(layer "In15.Cu")
		(net "P5E_CPU0_PE2_TX_DP<5>")
	)
	(arc
		(start 375.182384 -219.506038)
		(mid 375.230063 -219.323138)
		(end 375.360946 -219.18676)
		(width 0.0889)
		(layer "In15.Cu")
		(net "P5E_CPU0_PE2_TX_DP<5>")
	)
	(arc
		(start 375.839482 -217.388694)
		(mid 375.704549 -217.25534)
		(end 375.652284 -217.072972)
		(width 0.0889)
		(layer "In15.Cu")
		(net "P5E_CPU0_PE2_TX_DP<5>")
	)
	(arc
		(start 375.652284 -217.0557)
		(mid 375.704554 -216.873335)
		(end 375.839482 -216.739978)
		(width 0.0889)
		(layer "In15.Cu")
		(net "P5E_CPU0_PE2_TX_DP<5>")
	)
	(arc
		(start 373.490236 -224.065084)
		(mid 373.694571 -223.862479)
		(end 373.772684 -223.585532)
		(width 0.0889)
		(layer "In15.Cu")
		(net "P5E_CPU0_PE2_TX_DP<5>")
	)
	(arc
		(start 373.302784 -224.389442)
		(mid 373.350463 -224.206542)
		(end 373.481346 -224.070164)
		(width 0.0889)
		(layer "In15.Cu")
		(net "P5E_CPU0_PE2_TX_DP<5>")
	)
	(arc
		(start 375.845578 -216.736422)
		(mid 376.048165 -216.530071)
		(end 376.122184 -216.25052)
		(width 0.0889)
		(layer "In15.Cu")
		(net "P5E_CPU0_PE2_TX_DP<5>")
	)
	(arc
		(start 375.65203 -218.692222)
		(mid 375.699709 -218.509322)
		(end 375.830592 -218.372944)
		(width 0.0889)
		(layer "In15.Cu")
		(net "P5E_CPU0_PE2_TX_DP<5>")
	)
	(arc
		(start 373.091964 -224.829878)
		(mid 373.247362 -224.633597)
		(end 373.302784 -224.389442)
		(width 0.0889)
		(layer "In15.Cu")
		(net "P5E_CPU0_PE2_TX_DP<5>")
	)
	(arc
		(start 376.122184 -216.25052)
		(mid 376.169863 -216.06762)
		(end 376.300746 -215.931242)
		(width 0.0889)
		(layer "In15.Cu")
		(net "P5E_CPU0_PE2_TX_DP<5>")
	)
	(arc
		(start 374.242584 -222.761556)
		(mid 374.290263 -222.578656)
		(end 374.421146 -222.442278)
		(width 0.0889)
		(layer "In15.Cu")
		(net "P5E_CPU0_PE2_TX_DP<5>")
	)
	(segment
		(start 371.79758 -224.925382)
		(end 371.79758 -224.389696)
		(width 0.13208)
		(layer "F.Cu")
		(net "P5E_CPU0_PE2_TX_DP<4>")
	)
	(segment
		(start 405.11857 -400.858228)
		(end 405.424132 -401.16379)
		(width 0.13208)
		(layer "F.Cu")
		(net "P5E_CPU0_PE2_TX_DP<4>")
	)
	(segment
		(start 405.424132 -401.777962)
		(end 405.097742 -402.104352)
		(width 0.13208)
		(layer "F.Cu")
		(net "P5E_CPU0_PE2_TX_DP<4>")
	)
	(segment
		(start 371.79758 -224.389696)
		(end 371.797834 -224.389442)
		(width 0.13208)
		(layer "F.Cu")
		(net "P5E_CPU0_PE2_TX_DP<4>")
	)
	(segment
		(start 405.097742 -402.104352)
		(end 405.09317 -402.104352)
		(width 0.13208)
		(layer "F.Cu")
		(net "P5E_CPU0_PE2_TX_DP<4>")
	)
	(segment
		(start 405.424132 -401.16379)
		(end 405.424132 -401.777962)
		(width 0.13208)
		(layer "F.Cu")
		(net "P5E_CPU0_PE2_TX_DP<4>")
	)
	(segment
		(start 401.030186 -253.435612)
		(end 396.893796 -308.176422)
		(width 0.14732)
		(layer "In15.Cu")
		(net "P5E_CPU0_PE2_TX_DP<4>")
	)
	(segment
		(start 379.790452 -211.209636)
		(end 384.590544 -211.209636)
		(width 0.14732)
		(layer "In15.Cu")
		(net "P5E_CPU0_PE2_TX_DP<4>")
	)
	(segment
		(start 373.302784 -222.780098)
		(end 373.302784 -222.761556)
		(width 0.0889)
		(layer "In15.Cu")
		(net "P5E_CPU0_PE2_TX_DP<4>")
	)
	(segment
		(start 405.029162 -397.425164)
		(end 405.16683 -397.535146)
		(width 0.14732)
		(layer "In15.Cu")
		(net "P5E_CPU0_PE2_TX_DP<4>")
	)
	(segment
		(start 373.959882 -221.623382)
		(end 373.965978 -221.619826)
		(width 0.0889)
		(layer "In15.Cu")
		(net "P5E_CPU0_PE2_TX_DP<4>")
	)
	(segment
		(start 376.63374 -213.322916)
		(end 376.63374 -213.045548)
		(width 0.14732)
		(layer "In15.Cu")
		(net "P5E_CPU0_PE2_TX_DP<4>")
	)
	(segment
		(start 397.580866 -226.604322)
		(end 400.858228 -248.316496)
		(width 0.14732)
		(layer "In15.Cu")
		(net "P5E_CPU0_PE2_TX_DP<4>")
	)
	(segment
		(start 372.550436 -224.065084)
		(end 372.556532 -224.061528)
		(width 0.0889)
		(layer "In15.Cu")
		(net "P5E_CPU0_PE2_TX_DP<4>")
	)
	(segment
		(start 373.77243 -221.963234)
		(end 373.77243 -221.94774)
		(width 0.0889)
		(layer "In15.Cu")
		(net "P5E_CPU0_PE2_TX_DP<4>")
	)
	(segment
		(start 375.182384 -217.878406)
		(end 375.182384 -217.859864)
		(width 0.0889)
		(layer "In15.Cu")
		(net "P5E_CPU0_PE2_TX_DP<4>")
	)
	(segment
		(start 402.070062 -369.570254)
		(end 404.843996 -394.62075)
		(width 0.14732)
		(layer "In15.Cu")
		(net "P5E_CPU0_PE2_TX_DP<4>")
	)
	(segment
		(start 374.421146 -219.18676)
		(end 374.430036 -219.18168)
		(width 0.0889)
		(layer "In15.Cu")
		(net "P5E_CPU0_PE2_TX_DP<4>")
	)
	(segment
		(start 374.899936 -217.388694)
		(end 374.891046 -217.383614)
		(width 0.0889)
		(layer "In15.Cu")
		(net "P5E_CPU0_PE2_TX_DP<4>")
	)
	(segment
		(start 374.71223 -218.707716)
		(end 374.71223 -218.692222)
		(width 0.0889)
		(layer "In15.Cu")
		(net "P5E_CPU0_PE2_TX_DP<4>")
	)
	(segment
		(start 404.843996 -394.62075)
		(end 404.843742 -394.621004)
		(width 0.14732)
		(layer "In15.Cu")
		(net "P5E_CPU0_PE2_TX_DP<4>")
	)
	(segment
		(start 396.893796 -308.176422)
		(end 404.23338 -339.663024)
		(width 0.14732)
		(layer "In15.Cu")
		(net "P5E_CPU0_PE2_TX_DP<4>")
	)
	(segment
		(start 389.776208 -213.35746)
		(end 396.212822 -221.872556)
		(width 0.14732)
		(layer "In15.Cu")
		(net "P5E_CPU0_PE2_TX_DP<4>")
	)
	(segment
		(start 376.59183 -213.386924)
		(end 376.63374 -213.345014)
		(width 0.0889)
		(layer "In15.Cu")
		(net "P5E_CPU0_PE2_TX_DP<4>")
	)
	(segment
		(start 376.354848 -214.32774)
		(end 376.59183 -213.755478)
		(width 0.0889)
		(layer "In15.Cu")
		(net "P5E_CPU0_PE2_TX_DP<4>")
	)
	(segment
		(start 404.919434 -395.302994)
		(end 404.96744 -395.73708)
		(width 0.14732)
		(layer "In15.Cu")
		(net "P5E_CPU0_PE2_TX_DP<4>")
	)
	(segment
		(start 375.826274 -214.856314)
		(end 376.354848 -214.32774)
		(width 0.0889)
		(layer "In15.Cu")
		(net "P5E_CPU0_PE2_TX_DP<4>")
	)
	(segment
		(start 377.535694 -212.143594)
		(end 379.790452 -211.209636)
		(width 0.14732)
		(layer "In15.Cu")
		(net "P5E_CPU0_PE2_TX_DP<4>")
	)
	(segment
		(start 404.857458 -395.874494)
		(end 404.905464 -396.309088)
		(width 0.14732)
		(layer "In15.Cu")
		(net "P5E_CPU0_PE2_TX_DP<4>")
	)
	(segment
		(start 375.360946 -215.931242)
		(end 375.369836 -215.926162)
		(width 0.0889)
		(layer "In15.Cu")
		(net "P5E_CPU0_PE2_TX_DP<4>")
	)
	(segment
		(start 373.960644 -219.994988)
		(end 373.965978 -219.99194)
		(width 0.0889)
		(layer "In15.Cu")
		(net "P5E_CPU0_PE2_TX_DP<4>")
	)
	(segment
		(start 374.890792 -218.372944)
		(end 374.899682 -218.367864)
		(width 0.0889)
		(layer "In15.Cu")
		(net "P5E_CPU0_PE2_TX_DP<4>")
	)
	(segment
		(start 405.41321 -399.758408)
		(end 405.41321 -400.563588)
		(width 0.14732)
		(layer "In15.Cu")
		(net "P5E_CPU0_PE2_TX_DP<4>")
	)
	(segment
		(start 405.104854 -398.106646)
		(end 405.153114 -398.54124)
		(width 0.14732)
		(layer "In15.Cu")
		(net "P5E_CPU0_PE2_TX_DP<4>")
	)
	(segment
		(start 373.011446 -223.256348)
		(end 373.020336 -223.251268)
		(width 0.0889)
		(layer "In15.Cu")
		(net "P5E_CPU0_PE2_TX_DP<4>")
	)
	(segment
		(start 405.091138 -396.853156)
		(end 404.981156 -396.99057)
		(width 0.14732)
		(layer "In15.Cu")
		(net "P5E_CPU0_PE2_TX_DP<4>")
	)
	(segment
		(start 373.950992 -221.628462)
		(end 373.959882 -221.623382)
		(width 0.0889)
		(layer "In15.Cu")
		(net "P5E_CPU0_PE2_TX_DP<4>")
	)
	(segment
		(start 373.772684 -220.32849)
		(end 373.772684 -220.311218)
		(width 0.0889)
		(layer "In15.Cu")
		(net "P5E_CPU0_PE2_TX_DP<4>")
	)
	(segment
		(start 404.781766 -395.193012)
		(end 404.919434 -395.302994)
		(width 0.14732)
		(layer "In15.Cu")
		(net "P5E_CPU0_PE2_TX_DP<4>")
	)
	(segment
		(start 404.73376 -394.758418)
		(end 404.781766 -395.193012)
		(width 0.14732)
		(layer "In15.Cu")
		(net "P5E_CPU0_PE2_TX_DP<4>")
	)
	(segment
		(start 404.905464 -396.309088)
		(end 405.043132 -396.41907)
		(width 0.14732)
		(layer "In15.Cu")
		(net "P5E_CPU0_PE2_TX_DP<4>")
	)
	(segment
		(start 373.959882 -219.995496)
		(end 373.960644 -219.994988)
		(width 0.0889)
		(layer "In15.Cu")
		(net "P5E_CPU0_PE2_TX_DP<4>")
	)
	(segment
		(start 375.182384 -216.260426)
		(end 375.182384 -216.25052)
		(width 0.0889)
		(layer "In15.Cu")
		(net "P5E_CPU0_PE2_TX_DP<4>")
	)
	(segment
		(start 376.63374 -213.045548)
		(end 377.535694 -212.143594)
		(width 0.14732)
		(layer "In15.Cu")
		(net "P5E_CPU0_PE2_TX_DP<4>")
	)
	(segment
		(start 405.214836 -397.969232)
		(end 405.104854 -398.106646)
		(width 0.14732)
		(layer "In15.Cu")
		(net "P5E_CPU0_PE2_TX_DP<4>")
	)
	(segment
		(start 396.212822 -221.872556)
		(end 397.580866 -226.604322)
		(width 0.14732)
		(layer "In15.Cu")
		(net "P5E_CPU0_PE2_TX_DP<4>")
	)
	(segment
		(start 405.16683 -397.535146)
		(end 405.214836 -397.969232)
		(width 0.14732)
		(layer "In15.Cu")
		(net "P5E_CPU0_PE2_TX_DP<4>")
	)
	(segment
		(start 405.043132 -396.41907)
		(end 405.091138 -396.853156)
		(width 0.14732)
		(layer "In15.Cu")
		(net "P5E_CPU0_PE2_TX_DP<4>")
	)
	(segment
		(start 375.652284 -215.44661)
		(end 375.652284 -215.27643)
		(width 0.0889)
		(layer "In15.Cu")
		(net "P5E_CPU0_PE2_TX_DP<4>")
	)
	(segment
		(start 405.153114 -398.54124)
		(end 405.290782 -398.651222)
		(width 0.14732)
		(layer "In15.Cu")
		(net "P5E_CPU0_PE2_TX_DP<4>")
	)
	(segment
		(start 404.96744 -395.73708)
		(end 404.857458 -395.874494)
		(width 0.14732)
		(layer "In15.Cu")
		(net "P5E_CPU0_PE2_TX_DP<4>")
	)
	(segment
		(start 405.290782 -398.651222)
		(end 405.41321 -399.758408)
		(width 0.14732)
		(layer "In15.Cu")
		(net "P5E_CPU0_PE2_TX_DP<4>")
	)
	(segment
		(start 404.843742 -394.621004)
		(end 404.73376 -394.758418)
		(width 0.14732)
		(layer "In15.Cu")
		(net "P5E_CPU0_PE2_TX_DP<4>")
	)
	(segment
		(start 402.695156 -348.200218)
		(end 402.070062 -369.570254)
		(width 0.14732)
		(layer "In15.Cu")
		(net "P5E_CPU0_PE2_TX_DP<4>")
	)
	(segment
		(start 404.23338 -339.663532)
		(end 402.695156 -348.200218)
		(width 0.14732)
		(layer "In15.Cu")
		(net "P5E_CPU0_PE2_TX_DP<4>")
	)
	(segment
		(start 374.899682 -218.367864)
		(end 374.905778 -218.364308)
		(width 0.0889)
		(layer "In15.Cu")
		(net "P5E_CPU0_PE2_TX_DP<4>")
	)
	(segment
		(start 404.23338 -339.663024)
		(end 404.23338 -339.663532)
		(width 0.14732)
		(layer "In15.Cu")
		(net "P5E_CPU0_PE2_TX_DP<4>")
	)
	(segment
		(start 374.899174 -216.740486)
		(end 374.899936 -216.739978)
		(width 0.0889)
		(layer "In15.Cu")
		(net "P5E_CPU0_PE2_TX_DP<4>")
	)
	(segment
		(start 376.59183 -213.755478)
		(end 376.59183 -213.386924)
		(width 0.0889)
		(layer "In15.Cu")
		(net "P5E_CPU0_PE2_TX_DP<4>")
	)
	(segment
		(start 371.954298 -224.118424)
		(end 372.043198 -224.094802)
		(width 0.0889)
		(layer "In15.Cu")
		(net "P5E_CPU0_PE2_TX_DP<4>")
	)
	(segment
		(start 374.242584 -221.133924)
		(end 374.242584 -221.1197)
		(width 0.0889)
		(layer "In15.Cu")
		(net "P5E_CPU0_PE2_TX_DP<4>")
	)
	(segment
		(start 384.590544 -211.209636)
		(end 389.776208 -213.35746)
		(width 0.14732)
		(layer "In15.Cu")
		(net "P5E_CPU0_PE2_TX_DP<4>")
	)
	(segment
		(start 404.981156 -396.99057)
		(end 405.029162 -397.425164)
		(width 0.14732)
		(layer "In15.Cu")
		(net "P5E_CPU0_PE2_TX_DP<4>")
	)
	(segment
		(start 371.797834 -224.389442)
		(end 371.954298 -224.118424)
		(width 0.0889)
		(layer "In15.Cu")
		(net "P5E_CPU0_PE2_TX_DP<4>")
	)
	(segment
		(start 376.63374 -213.345014)
		(end 376.63374 -213.322916)
		(width 0.0889)
		(layer "In15.Cu")
		(net "P5E_CPU0_PE2_TX_DP<4>")
	)
	(segment
		(start 373.481346 -222.442278)
		(end 373.490236 -222.437198)
		(width 0.0889)
		(layer "In15.Cu")
		(net "P5E_CPU0_PE2_TX_DP<4>")
	)
	(segment
		(start 375.652284 -215.27643)
		(end 375.826274 -214.856314)
		(width 0.0889)
		(layer "In15.Cu")
		(net "P5E_CPU0_PE2_TX_DP<4>")
	)
	(segment
		(start 374.891046 -216.745058)
		(end 374.899174 -216.740486)
		(width 0.0889)
		(layer "In15.Cu")
		(net "P5E_CPU0_PE2_TX_DP<4>")
	)
	(segment
		(start 400.858228 -248.316496)
		(end 401.030186 -253.435612)
		(width 0.14732)
		(layer "In15.Cu")
		(net "P5E_CPU0_PE2_TX_DP<4>")
	)
	(segment
		(start 405.41321 -400.563588)
		(end 405.11857 -400.858228)
		(width 0.14732)
		(layer "In15.Cu")
		(net "P5E_CPU0_PE2_TX_DP<4>")
	)
	(arc
		(start 373.772684 -220.311218)
		(mid 373.824954 -220.128853)
		(end 373.959882 -219.995496)
		(width 0.0889)
		(layer "In15.Cu")
		(net "P5E_CPU0_PE2_TX_DP<4>")
	)
	(arc
		(start 374.905778 -218.364308)
		(mid 375.108365 -218.157957)
		(end 375.182384 -217.878406)
		(width 0.0889)
		(layer "In15.Cu")
		(net "P5E_CPU0_PE2_TX_DP<4>")
	)
	(arc
		(start 373.77243 -221.94774)
		(mid 373.820109 -221.76484)
		(end 373.950992 -221.628462)
		(width 0.0889)
		(layer "In15.Cu")
		(net "P5E_CPU0_PE2_TX_DP<4>")
	)
	(arc
		(start 374.242584 -221.1197)
		(mid 374.163365 -220.845015)
		(end 373.959882 -220.644212)
		(width 0.0889)
		(layer "In15.Cu")
		(net "P5E_CPU0_PE2_TX_DP<4>")
	)
	(arc
		(start 373.959882 -220.644212)
		(mid 373.824949 -220.510858)
		(end 373.772684 -220.32849)
		(width 0.0889)
		(layer "In15.Cu")
		(net "P5E_CPU0_PE2_TX_DP<4>")
	)
	(arc
		(start 375.369836 -215.926162)
		(mid 375.574171 -215.723557)
		(end 375.652284 -215.44661)
		(width 0.0889)
		(layer "In15.Cu")
		(net "P5E_CPU0_PE2_TX_DP<4>")
	)
	(arc
		(start 372.832884 -223.575626)
		(mid 372.880563 -223.392726)
		(end 373.011446 -223.256348)
		(width 0.0889)
		(layer "In15.Cu")
		(net "P5E_CPU0_PE2_TX_DP<4>")
	)
	(arc
		(start 374.891046 -217.383614)
		(mid 374.712449 -217.064336)
		(end 374.891046 -216.745058)
		(width 0.0889)
		(layer "In15.Cu")
		(net "P5E_CPU0_PE2_TX_DP<4>")
	)
	(arc
		(start 372.06301 -224.10293)
		(mid 372.311021 -224.139395)
		(end 372.550436 -224.065084)
		(width 0.0889)
		(layer "In15.Cu")
		(net "P5E_CPU0_PE2_TX_DP<4>")
	)
	(arc
		(start 375.182384 -217.859864)
		(mid 375.102222 -217.587675)
		(end 374.899936 -217.388694)
		(width 0.0889)
		(layer "In15.Cu")
		(net "P5E_CPU0_PE2_TX_DP<4>")
	)
	(arc
		(start 374.899936 -216.739978)
		(mid 375.104271 -216.537373)
		(end 375.182384 -216.260426)
		(width 0.0889)
		(layer "In15.Cu")
		(net "P5E_CPU0_PE2_TX_DP<4>")
	)
	(arc
		(start 374.242584 -219.506038)
		(mid 374.290263 -219.323138)
		(end 374.421146 -219.18676)
		(width 0.0889)
		(layer "In15.Cu")
		(net "P5E_CPU0_PE2_TX_DP<4>")
	)
	(arc
		(start 373.490236 -222.437198)
		(mid 373.693059 -222.236967)
		(end 373.77243 -221.963234)
		(width 0.0889)
		(layer "In15.Cu")
		(net "P5E_CPU0_PE2_TX_DP<4>")
	)
	(arc
		(start 373.965978 -221.619826)
		(mid 374.168565 -221.413475)
		(end 374.242584 -221.133924)
		(width 0.0889)
		(layer "In15.Cu")
		(net "P5E_CPU0_PE2_TX_DP<4>")
	)
	(arc
		(start 373.965978 -219.99194)
		(mid 374.168565 -219.785589)
		(end 374.242584 -219.506038)
		(width 0.0889)
		(layer "In15.Cu")
		(net "P5E_CPU0_PE2_TX_DP<4>")
	)
	(arc
		(start 374.71223 -218.692222)
		(mid 374.759909 -218.509322)
		(end 374.890792 -218.372944)
		(width 0.0889)
		(layer "In15.Cu")
		(net "P5E_CPU0_PE2_TX_DP<4>")
	)
	(arc
		(start 372.556532 -224.061528)
		(mid 372.758945 -223.855115)
		(end 372.832884 -223.575626)
		(width 0.0889)
		(layer "In15.Cu")
		(net "P5E_CPU0_PE2_TX_DP<4>")
	)
	(arc
		(start 375.182384 -216.25052)
		(mid 375.230063 -216.06762)
		(end 375.360946 -215.931242)
		(width 0.0889)
		(layer "In15.Cu")
		(net "P5E_CPU0_PE2_TX_DP<4>")
	)
	(arc
		(start 374.430036 -219.18168)
		(mid 374.632859 -218.981449)
		(end 374.71223 -218.707716)
		(width 0.0889)
		(layer "In15.Cu")
		(net "P5E_CPU0_PE2_TX_DP<4>")
	)
	(arc
		(start 372.043198 -224.094802)
		(mid 372.053065 -224.098961)
		(end 372.06301 -224.10293)
		(width 0.0889)
		(layer "In15.Cu")
		(net "P5E_CPU0_PE2_TX_DP<4>")
	)
	(arc
		(start 373.020336 -223.251268)
		(mid 373.222622 -223.052287)
		(end 373.302784 -222.780098)
		(width 0.0889)
		(layer "In15.Cu")
		(net "P5E_CPU0_PE2_TX_DP<4>")
	)
	(arc
		(start 373.302784 -222.761556)
		(mid 373.350463 -222.578656)
		(end 373.481346 -222.442278)
		(width 0.0889)
		(layer "In15.Cu")
		(net "P5E_CPU0_PE2_TX_DP<4>")
	)
	(segment
		(start 408.487372 -401.16379)
		(end 408.487372 -401.777962)
		(width 0.13208)
		(layer "F.Cu")
		(net "P5E_CPU0_PE2_TX_DP<3>")
	)
	(segment
		(start 371.327934 -225.739198)
		(end 371.327934 -225.203512)
		(width 0.13208)
		(layer "F.Cu")
		(net "P5E_CPU0_PE2_TX_DP<3>")
	)
	(segment
		(start 408.160982 -402.104352)
		(end 408.15641 -402.104352)
		(width 0.13208)
		(layer "F.Cu")
		(net "P5E_CPU0_PE2_TX_DP<3>")
	)
	(segment
		(start 371.327934 -225.203512)
		(end 371.32768 -225.203258)
		(width 0.13208)
		(layer "F.Cu")
		(net "P5E_CPU0_PE2_TX_DP<3>")
	)
	(segment
		(start 408.487372 -401.777962)
		(end 408.160982 -402.104352)
		(width 0.13208)
		(layer "F.Cu")
		(net "P5E_CPU0_PE2_TX_DP<3>")
	)
	(segment
		(start 408.18181 -400.858228)
		(end 408.487372 -401.16379)
		(width 0.13208)
		(layer "F.Cu")
		(net "P5E_CPU0_PE2_TX_DP<3>")
	)
	(segment
		(start 373.959882 -216.739978)
		(end 373.960644 -216.73947)
		(width 0.0889)
		(layer "In15.Cu")
		(net "P5E_CPU0_PE2_TX_DP<3>")
	)
	(segment
		(start 407.424636 -394.576554)
		(end 407.568654 -394.678408)
		(width 0.14732)
		(layer "In15.Cu")
		(net "P5E_CPU0_PE2_TX_DP<3>")
	)
	(segment
		(start 408.47645 -400.563588)
		(end 408.18181 -400.858228)
		(width 0.14732)
		(layer "In15.Cu")
		(net "P5E_CPU0_PE2_TX_DP<3>")
	)
	(segment
		(start 408.103578 -398.573244)
		(end 408.17673 -399.004282)
		(width 0.14732)
		(layer "In15.Cu")
		(net "P5E_CPU0_PE2_TX_DP<3>")
	)
	(segment
		(start 407.988516 -397.89735)
		(end 408.132534 -397.999204)
		(width 0.14732)
		(layer "In15.Cu")
		(net "P5E_CPU0_PE2_TX_DP<3>")
	)
	(segment
		(start 375.651522 -213.878414)
		(end 375.651522 -213.386924)
		(width 0.0889)
		(layer "In15.Cu")
		(net "P5E_CPU0_PE2_TX_DP<3>")
	)
	(segment
		(start 375.693432 -213.322916)
		(end 375.693432 -212.611716)
		(width 0.14732)
		(layer "In15.Cu")
		(net "P5E_CPU0_PE2_TX_DP<3>")
	)
	(segment
		(start 375.651522 -213.386924)
		(end 375.693432 -213.345014)
		(width 0.0889)
		(layer "In15.Cu")
		(net "P5E_CPU0_PE2_TX_DP<3>")
	)
	(segment
		(start 373.019574 -219.996004)
		(end 373.020336 -219.995496)
		(width 0.0889)
		(layer "In15.Cu")
		(net "P5E_CPU0_PE2_TX_DP<3>")
	)
	(segment
		(start 390.646666 -212.682074)
		(end 391.199116 -213.412578)
		(width 0.14732)
		(layer "In15.Cu")
		(net "P5E_CPU0_PE2_TX_DP<3>")
	)
	(segment
		(start 373.302784 -221.133924)
		(end 373.302784 -221.115382)
		(width 0.0889)
		(layer "In15.Cu")
		(net "P5E_CPU0_PE2_TX_DP<3>")
	)
	(segment
		(start 408.132534 -397.999204)
		(end 408.132026 -397.999458)
		(width 0.14732)
		(layer "In15.Cu")
		(net "P5E_CPU0_PE2_TX_DP<3>")
	)
	(segment
		(start 384.822192 -210.269836)
		(end 390.646666 -212.682074)
		(width 0.14732)
		(layer "In15.Cu")
		(net "P5E_CPU0_PE2_TX_DP<3>")
	)
	(segment
		(start 391.72769 -214.314024)
		(end 391.991342 -214.662766)
		(width 0.14732)
		(layer "In15.Cu")
		(net "P5E_CPU0_PE2_TX_DP<3>")
	)
	(segment
		(start 373.77243 -218.707716)
		(end 373.77243 -218.692222)
		(width 0.0889)
		(layer "In15.Cu")
		(net "P5E_CPU0_PE2_TX_DP<3>")
	)
	(segment
		(start 372.362984 -222.77578)
		(end 372.362984 -222.761556)
		(width 0.0889)
		(layer "In15.Cu")
		(net "P5E_CPU0_PE2_TX_DP<3>")
	)
	(segment
		(start 407.800556 -396.790418)
		(end 407.94432 -396.892018)
		(width 0.14732)
		(layer "In15.Cu")
		(net "P5E_CPU0_PE2_TX_DP<3>")
	)
	(segment
		(start 373.020082 -221.623382)
		(end 373.026178 -221.619826)
		(width 0.0889)
		(layer "In15.Cu")
		(net "P5E_CPU0_PE2_TX_DP<3>")
	)
	(segment
		(start 407.727658 -396.35938)
		(end 407.800556 -396.790418)
		(width 0.14732)
		(layer "In15.Cu")
		(net "P5E_CPU0_PE2_TX_DP<3>")
	)
	(segment
		(start 374.242584 -217.878406)
		(end 374.242584 -217.864182)
		(width 0.0889)
		(layer "In15.Cu")
		(net "P5E_CPU0_PE2_TX_DP<3>")
	)
	(segment
		(start 403.31136 -369.607846)
		(end 407.453592 -394.002006)
		(width 0.14732)
		(layer "In15.Cu")
		(net "P5E_CPU0_PE2_TX_DP<3>")
	)
	(segment
		(start 374.71223 -215.436704)
		(end 374.71223 -215.286082)
		(width 0.0889)
		(layer "In15.Cu")
		(net "P5E_CPU0_PE2_TX_DP<3>")
	)
	(segment
		(start 372.83263 -221.963234)
		(end 372.83263 -221.94774)
		(width 0.0889)
		(layer "In15.Cu")
		(net "P5E_CPU0_PE2_TX_DP<3>")
	)
	(segment
		(start 407.612596 -395.683486)
		(end 407.75636 -395.785086)
		(width 0.14732)
		(layer "In15.Cu")
		(net "P5E_CPU0_PE2_TX_DP<3>")
	)
	(segment
		(start 408.17673 -399.004282)
		(end 408.32024 -399.105882)
		(width 0.14732)
		(layer "In15.Cu")
		(net "P5E_CPU0_PE2_TX_DP<3>")
	)
	(segment
		(start 373.950992 -218.372944)
		(end 373.959882 -218.367864)
		(width 0.0889)
		(layer "In15.Cu")
		(net "P5E_CPU0_PE2_TX_DP<3>")
	)
	(segment
		(start 371.893084 -223.585532)
		(end 371.893084 -223.56699)
		(width 0.0889)
		(layer "In15.Cu")
		(net "P5E_CPU0_PE2_TX_DP<3>")
	)
	(segment
		(start 408.132026 -397.999458)
		(end 408.205432 -398.429734)
		(width 0.14732)
		(layer "In15.Cu")
		(net "P5E_CPU0_PE2_TX_DP<3>")
	)
	(segment
		(start 407.351738 -394.145516)
		(end 407.424636 -394.576554)
		(width 0.14732)
		(layer "In15.Cu")
		(net "P5E_CPU0_PE2_TX_DP<3>")
	)
	(segment
		(start 374.880632 -214.88019)
		(end 375.488962 -214.27186)
		(width 0.0889)
		(layer "In15.Cu")
		(net "P5E_CPU0_PE2_TX_DP<3>")
	)
	(segment
		(start 398.569688 -226.681792)
		(end 401.784566 -247.986296)
		(width 0.14732)
		(layer "In15.Cu")
		(net "P5E_CPU0_PE2_TX_DP<3>")
	)
	(segment
		(start 401.784566 -247.986296)
		(end 401.976844 -253.69901)
		(width 0.14732)
		(layer "In15.Cu")
		(net "P5E_CPU0_PE2_TX_DP<3>")
	)
	(segment
		(start 376.934984 -211.370164)
		(end 379.59157 -210.269836)
		(width 0.14732)
		(layer "In15.Cu")
		(net "P5E_CPU0_PE2_TX_DP<3>")
	)
	(segment
		(start 407.75636 -395.785086)
		(end 407.829512 -396.21587)
		(width 0.14732)
		(layer "In15.Cu")
		(net "P5E_CPU0_PE2_TX_DP<3>")
	)
	(segment
		(start 397.866362 -307.856382)
		(end 405.205692 -339.692742)
		(width 0.14732)
		(layer "In15.Cu")
		(net "P5E_CPU0_PE2_TX_DP<3>")
	)
	(segment
		(start 372.541546 -222.442278)
		(end 372.550436 -222.437198)
		(width 0.0889)
		(layer "In15.Cu")
		(net "P5E_CPU0_PE2_TX_DP<3>")
	)
	(segment
		(start 373.011192 -221.628462)
		(end 373.020082 -221.623382)
		(width 0.0889)
		(layer "In15.Cu")
		(net "P5E_CPU0_PE2_TX_DP<3>")
	)
	(segment
		(start 407.539698 -395.252448)
		(end 407.612596 -395.683486)
		(width 0.14732)
		(layer "In15.Cu")
		(net "P5E_CPU0_PE2_TX_DP<3>")
	)
	(segment
		(start 391.199116 -213.412578)
		(end 391.199116 -213.412832)
		(width 0.14732)
		(layer "In15.Cu")
		(net "P5E_CPU0_PE2_TX_DP<3>")
	)
	(segment
		(start 371.32768 -225.203258)
		(end 371.171216 -224.93224)
		(width 0.0889)
		(layer "In15.Cu")
		(net "P5E_CPU0_PE2_TX_DP<3>")
	)
	(segment
		(start 373.302784 -219.515944)
		(end 373.302784 -219.506038)
		(width 0.0889)
		(layer "In15.Cu")
		(net "P5E_CPU0_PE2_TX_DP<3>")
	)
	(segment
		(start 373.960644 -216.73947)
		(end 373.965978 -216.736422)
		(width 0.0889)
		(layer "In15.Cu")
		(net "P5E_CPU0_PE2_TX_DP<3>")
	)
	(segment
		(start 403.688296 -348.07652)
		(end 403.31136 -369.607846)
		(width 0.14732)
		(layer "In15.Cu")
		(net "P5E_CPU0_PE2_TX_DP<3>")
	)
	(segment
		(start 407.453592 -394.002006)
		(end 407.351738 -394.145516)
		(width 0.14732)
		(layer "In15.Cu")
		(net "P5E_CPU0_PE2_TX_DP<3>")
	)
	(segment
		(start 391.199116 -213.412832)
		(end 391.751566 -214.143336)
		(width 0.14732)
		(layer "In15.Cu")
		(net "P5E_CPU0_PE2_TX_DP<3>")
	)
	(segment
		(start 371.171216 -224.93224)
		(end 371.195346 -224.843086)
		(width 0.0889)
		(layer "In15.Cu")
		(net "P5E_CPU0_PE2_TX_DP<3>")
	)
	(segment
		(start 407.568146 -394.678662)
		(end 407.641552 -395.108938)
		(width 0.14732)
		(layer "In15.Cu")
		(net "P5E_CPU0_PE2_TX_DP<3>")
	)
	(segment
		(start 407.915618 -397.466312)
		(end 407.988516 -397.89735)
		(width 0.14732)
		(layer "In15.Cu")
		(net "P5E_CPU0_PE2_TX_DP<3>")
	)
	(segment
		(start 391.991342 -214.662766)
		(end 392.162284 -214.686642)
		(width 0.14732)
		(layer "In15.Cu")
		(net "P5E_CPU0_PE2_TX_DP<3>")
	)
	(segment
		(start 405.205692 -339.692742)
		(end 403.688296 -348.07652)
		(width 0.14732)
		(layer "In15.Cu")
		(net "P5E_CPU0_PE2_TX_DP<3>")
	)
	(segment
		(start 373.772684 -217.072972)
		(end 373.772684 -217.0557)
		(width 0.0889)
		(layer "In15.Cu")
		(net "P5E_CPU0_PE2_TX_DP<3>")
	)
	(segment
		(start 371.601746 -224.070164)
		(end 371.610636 -224.065084)
		(width 0.0889)
		(layer "In15.Cu")
		(net "P5E_CPU0_PE2_TX_DP<3>")
	)
	(segment
		(start 408.32024 -399.105882)
		(end 408.47645 -400.025616)
		(width 0.14732)
		(layer "In15.Cu")
		(net "P5E_CPU0_PE2_TX_DP<3>")
	)
	(segment
		(start 397.06169 -221.166944)
		(end 398.569688 -226.681792)
		(width 0.14732)
		(layer "In15.Cu")
		(net "P5E_CPU0_PE2_TX_DP<3>")
	)
	(segment
		(start 373.481346 -219.18676)
		(end 373.490236 -219.18168)
		(width 0.0889)
		(layer "In15.Cu")
		(net "P5E_CPU0_PE2_TX_DP<3>")
	)
	(segment
		(start 374.71223 -215.452198)
		(end 374.71223 -215.437212)
		(width 0.0889)
		(layer "In15.Cu")
		(net "P5E_CPU0_PE2_TX_DP<3>")
	)
	(segment
		(start 374.71223 -215.286082)
		(end 374.880632 -214.88019)
		(width 0.0889)
		(layer "In15.Cu")
		(net "P5E_CPU0_PE2_TX_DP<3>")
	)
	(segment
		(start 407.94432 -396.892018)
		(end 408.017472 -397.322802)
		(width 0.14732)
		(layer "In15.Cu")
		(net "P5E_CPU0_PE2_TX_DP<3>")
	)
	(segment
		(start 408.205432 -398.429734)
		(end 408.103578 -398.573244)
		(width 0.14732)
		(layer "In15.Cu")
		(net "P5E_CPU0_PE2_TX_DP<3>")
	)
	(segment
		(start 408.47645 -400.025616)
		(end 408.47645 -400.563588)
		(width 0.14732)
		(layer "In15.Cu")
		(net "P5E_CPU0_PE2_TX_DP<3>")
	)
	(segment
		(start 408.017472 -397.322802)
		(end 407.915618 -397.466312)
		(width 0.14732)
		(layer "In15.Cu")
		(net "P5E_CPU0_PE2_TX_DP<3>")
	)
	(segment
		(start 407.568654 -394.678408)
		(end 407.568146 -394.678662)
		(width 0.14732)
		(layer "In15.Cu")
		(net "P5E_CPU0_PE2_TX_DP<3>")
	)
	(segment
		(start 373.020336 -220.644212)
		(end 373.011446 -220.639132)
		(width 0.0889)
		(layer "In15.Cu")
		(net "P5E_CPU0_PE2_TX_DP<3>")
	)
	(segment
		(start 392.162284 -214.686642)
		(end 397.06169 -221.166944)
		(width 0.14732)
		(layer "In15.Cu")
		(net "P5E_CPU0_PE2_TX_DP<3>")
	)
	(segment
		(start 375.693432 -212.611716)
		(end 376.934984 -211.370164)
		(width 0.14732)
		(layer "In15.Cu")
		(net "P5E_CPU0_PE2_TX_DP<3>")
	)
	(segment
		(start 375.693432 -213.345014)
		(end 375.693432 -213.322916)
		(width 0.0889)
		(layer "In15.Cu")
		(net "P5E_CPU0_PE2_TX_DP<3>")
	)
	(segment
		(start 373.011446 -220.000576)
		(end 373.019574 -219.996004)
		(width 0.0889)
		(layer "In15.Cu")
		(net "P5E_CPU0_PE2_TX_DP<3>")
	)
	(segment
		(start 401.976844 -253.69901)
		(end 397.866362 -307.856382)
		(width 0.14732)
		(layer "In15.Cu")
		(net "P5E_CPU0_PE2_TX_DP<3>")
	)
	(segment
		(start 379.59157 -210.269836)
		(end 384.822192 -210.269836)
		(width 0.14732)
		(layer "In15.Cu")
		(net "P5E_CPU0_PE2_TX_DP<3>")
	)
	(segment
		(start 407.829512 -396.21587)
		(end 407.727658 -396.35938)
		(width 0.14732)
		(layer "In15.Cu")
		(net "P5E_CPU0_PE2_TX_DP<3>")
	)
	(segment
		(start 407.641552 -395.108938)
		(end 407.539698 -395.252448)
		(width 0.14732)
		(layer "In15.Cu")
		(net "P5E_CPU0_PE2_TX_DP<3>")
	)
	(segment
		(start 375.488962 -214.27186)
		(end 375.651522 -213.878414)
		(width 0.0889)
		(layer "In15.Cu")
		(net "P5E_CPU0_PE2_TX_DP<3>")
	)
	(segment
		(start 391.751566 -214.143336)
		(end 391.72769 -214.314024)
		(width 0.14732)
		(layer "In15.Cu")
		(net "P5E_CPU0_PE2_TX_DP<3>")
	)
	(segment
		(start 374.421146 -215.931242)
		(end 374.430036 -215.926162)
		(width 0.0889)
		(layer "In15.Cu")
		(net "P5E_CPU0_PE2_TX_DP<3>")
	)
	(segment
		(start 373.959882 -218.367864)
		(end 373.965978 -218.364308)
		(width 0.0889)
		(layer "In15.Cu")
		(net "P5E_CPU0_PE2_TX_DP<3>")
	)
	(arc
		(start 372.080282 -223.251268)
		(mid 372.283763 -223.050464)
		(end 372.362984 -222.77578)
		(width 0.0889)
		(layer "In15.Cu")
		(net "P5E_CPU0_PE2_TX_DP<3>")
	)
	(arc
		(start 371.610636 -224.065084)
		(mid 371.814971 -223.862479)
		(end 371.893084 -223.585532)
		(width 0.0889)
		(layer "In15.Cu")
		(net "P5E_CPU0_PE2_TX_DP<3>")
	)
	(arc
		(start 372.83263 -221.94774)
		(mid 372.880309 -221.76484)
		(end 373.011192 -221.628462)
		(width 0.0889)
		(layer "In15.Cu")
		(net "P5E_CPU0_PE2_TX_DP<3>")
	)
	(arc
		(start 373.965978 -218.364308)
		(mid 374.168565 -218.157957)
		(end 374.242584 -217.878406)
		(width 0.0889)
		(layer "In15.Cu")
		(net "P5E_CPU0_PE2_TX_DP<3>")
	)
	(arc
		(start 374.242584 -216.25052)
		(mid 374.290263 -216.06762)
		(end 374.421146 -215.931242)
		(width 0.0889)
		(layer "In15.Cu")
		(net "P5E_CPU0_PE2_TX_DP<3>")
	)
	(arc
		(start 373.490236 -219.18168)
		(mid 373.693059 -218.981449)
		(end 373.77243 -218.707716)
		(width 0.0889)
		(layer "In15.Cu")
		(net "P5E_CPU0_PE2_TX_DP<3>")
	)
	(arc
		(start 374.242584 -217.864182)
		(mid 374.163365 -217.589497)
		(end 373.959882 -217.388694)
		(width 0.0889)
		(layer "In15.Cu")
		(net "P5E_CPU0_PE2_TX_DP<3>")
	)
	(arc
		(start 372.362984 -222.761556)
		(mid 372.410663 -222.578656)
		(end 372.541546 -222.442278)
		(width 0.0889)
		(layer "In15.Cu")
		(net "P5E_CPU0_PE2_TX_DP<3>")
	)
	(arc
		(start 374.430036 -215.926162)
		(mid 374.632859 -215.725931)
		(end 374.71223 -215.452198)
		(width 0.0889)
		(layer "In15.Cu")
		(net "P5E_CPU0_PE2_TX_DP<3>")
	)
	(arc
		(start 373.302784 -221.115382)
		(mid 373.222622 -220.843193)
		(end 373.020336 -220.644212)
		(width 0.0889)
		(layer "In15.Cu")
		(net "P5E_CPU0_PE2_TX_DP<3>")
	)
	(arc
		(start 373.011446 -220.639132)
		(mid 372.880532 -220.502772)
		(end 372.832884 -220.319854)
		(width 0.0889)
		(layer "In15.Cu")
		(net "P5E_CPU0_PE2_TX_DP<3>")
	)
	(arc
		(start 374.71223 -215.437212)
		(mid 374.71223 -215.436958)
		(end 374.71223 -215.436704)
		(width 0.0889)
		(layer "In15.Cu")
		(net "P5E_CPU0_PE2_TX_DP<3>")
	)
	(arc
		(start 373.965978 -216.736422)
		(mid 374.168565 -216.530071)
		(end 374.242584 -216.25052)
		(width 0.0889)
		(layer "In15.Cu")
		(net "P5E_CPU0_PE2_TX_DP<3>")
	)
	(arc
		(start 373.77243 -218.692222)
		(mid 373.820109 -218.509322)
		(end 373.950992 -218.372944)
		(width 0.0889)
		(layer "In15.Cu")
		(net "P5E_CPU0_PE2_TX_DP<3>")
	)
	(arc
		(start 371.195346 -224.843086)
		(mid 371.203918 -224.836564)
		(end 371.212364 -224.829878)
		(width 0.0889)
		(layer "In15.Cu")
		(net "P5E_CPU0_PE2_TX_DP<3>")
	)
	(arc
		(start 373.772684 -217.0557)
		(mid 373.824954 -216.873335)
		(end 373.959882 -216.739978)
		(width 0.0889)
		(layer "In15.Cu")
		(net "P5E_CPU0_PE2_TX_DP<3>")
	)
	(arc
		(start 371.423184 -224.389442)
		(mid 371.470863 -224.206542)
		(end 371.601746 -224.070164)
		(width 0.0889)
		(layer "In15.Cu")
		(net "P5E_CPU0_PE2_TX_DP<3>")
	)
	(arc
		(start 371.212364 -224.829878)
		(mid 371.367762 -224.633597)
		(end 371.423184 -224.389442)
		(width 0.0889)
		(layer "In15.Cu")
		(net "P5E_CPU0_PE2_TX_DP<3>")
	)
	(arc
		(start 373.959882 -217.388694)
		(mid 373.824949 -217.25534)
		(end 373.772684 -217.072972)
		(width 0.0889)
		(layer "In15.Cu")
		(net "P5E_CPU0_PE2_TX_DP<3>")
	)
	(arc
		(start 371.893084 -223.56699)
		(mid 371.945354 -223.384625)
		(end 372.080282 -223.251268)
		(width 0.0889)
		(layer "In15.Cu")
		(net "P5E_CPU0_PE2_TX_DP<3>")
	)
	(arc
		(start 372.832884 -220.319854)
		(mid 372.880563 -220.136954)
		(end 373.011446 -220.000576)
		(width 0.0889)
		(layer "In15.Cu")
		(net "P5E_CPU0_PE2_TX_DP<3>")
	)
	(arc
		(start 372.550436 -222.437198)
		(mid 372.753259 -222.236967)
		(end 372.83263 -221.963234)
		(width 0.0889)
		(layer "In15.Cu")
		(net "P5E_CPU0_PE2_TX_DP<3>")
	)
	(arc
		(start 373.026178 -221.619826)
		(mid 373.228765 -221.413475)
		(end 373.302784 -221.133924)
		(width 0.0889)
		(layer "In15.Cu")
		(net "P5E_CPU0_PE2_TX_DP<3>")
	)
	(arc
		(start 373.020336 -219.995496)
		(mid 373.224671 -219.792891)
		(end 373.302784 -219.515944)
		(width 0.0889)
		(layer "In15.Cu")
		(net "P5E_CPU0_PE2_TX_DP<3>")
	)
	(arc
		(start 373.302784 -219.506038)
		(mid 373.350463 -219.323138)
		(end 373.481346 -219.18676)
		(width 0.0889)
		(layer "In15.Cu")
		(net "P5E_CPU0_PE2_TX_DP<3>")
	)
	(segment
		(start 411.24505 -400.858228)
		(end 411.550612 -401.16379)
		(width 0.13208)
		(layer "F.Cu")
		(net "P5E_CPU0_PE2_TX_DP<2>")
	)
	(segment
		(start 411.550612 -401.16379)
		(end 411.550612 -401.777962)
		(width 0.13208)
		(layer "F.Cu")
		(net "P5E_CPU0_PE2_TX_DP<2>")
	)
	(segment
		(start 369.91798 -224.925382)
		(end 369.91798 -224.389696)
		(width 0.13208)
		(layer "F.Cu")
		(net "P5E_CPU0_PE2_TX_DP<2>")
	)
	(segment
		(start 411.550612 -401.777962)
		(end 411.224222 -402.104352)
		(width 0.13208)
		(layer "F.Cu")
		(net "P5E_CPU0_PE2_TX_DP<2>")
	)
	(segment
		(start 369.91798 -224.389696)
		(end 369.918234 -224.389442)
		(width 0.13208)
		(layer "F.Cu")
		(net "P5E_CPU0_PE2_TX_DP<2>")
	)
	(segment
		(start 411.224222 -402.104352)
		(end 411.21965 -402.104352)
		(width 0.13208)
		(layer "F.Cu")
		(net "P5E_CPU0_PE2_TX_DP<2>")
	)
	(segment
		(start 371.893084 -220.32849)
		(end 371.893084 -220.311218)
		(width 0.0889)
		(layer "In15.Cu")
		(net "P5E_CPU0_PE2_TX_DP<2>")
	)
	(segment
		(start 372.080282 -221.623382)
		(end 372.086378 -221.619826)
		(width 0.0889)
		(layer "In15.Cu")
		(net "P5E_CPU0_PE2_TX_DP<2>")
	)
	(segment
		(start 410.402278 -394.975334)
		(end 410.308552 -395.124432)
		(width 0.14732)
		(layer "In15.Cu")
		(net "P5E_CPU0_PE2_TX_DP<2>")
	)
	(segment
		(start 402.926296 -253.490476)
		(end 398.846802 -307.733954)
		(width 0.14732)
		(layer "In15.Cu")
		(net "P5E_CPU0_PE2_TX_DP<2>")
	)
	(segment
		(start 372.080282 -219.995496)
		(end 372.081044 -219.994988)
		(width 0.0889)
		(layer "In15.Cu")
		(net "P5E_CPU0_PE2_TX_DP<2>")
	)
	(segment
		(start 410.405834 -395.550644)
		(end 410.555186 -395.64437)
		(width 0.14732)
		(layer "In15.Cu")
		(net "P5E_CPU0_PE2_TX_DP<2>")
	)
	(segment
		(start 410.555694 -395.648434)
		(end 410.652214 -396.070074)
		(width 0.14732)
		(layer "In15.Cu")
		(net "P5E_CPU0_PE2_TX_DP<2>")
	)
	(segment
		(start 373.302784 -217.878406)
		(end 373.302784 -217.859864)
		(width 0.0889)
		(layer "In15.Cu")
		(net "P5E_CPU0_PE2_TX_DP<2>")
	)
	(segment
		(start 410.805122 -396.73911)
		(end 410.804614 -396.73911)
		(width 0.14732)
		(layer "In15.Cu")
		(net "P5E_CPU0_PE2_TX_DP<2>")
	)
	(segment
		(start 410.308552 -395.124432)
		(end 410.405834 -395.550644)
		(width 0.14732)
		(layer "In15.Cu")
		(net "P5E_CPU0_PE2_TX_DP<2>")
	)
	(segment
		(start 371.601746 -222.442278)
		(end 371.610636 -222.437198)
		(width 0.0889)
		(layer "In15.Cu")
		(net "P5E_CPU0_PE2_TX_DP<2>")
	)
	(segment
		(start 402.706332 -246.95531)
		(end 402.926296 -253.490476)
		(width 0.14732)
		(layer "In15.Cu")
		(net "P5E_CPU0_PE2_TX_DP<2>")
	)
	(segment
		(start 410.808424 -397.313912)
		(end 410.905706 -397.740124)
		(width 0.14732)
		(layer "In15.Cu")
		(net "P5E_CPU0_PE2_TX_DP<2>")
	)
	(segment
		(start 394.61694 -216.31783)
		(end 398.06372 -220.81871)
		(width 0.14732)
		(layer "In15.Cu")
		(net "P5E_CPU0_PE2_TX_DP<2>")
	)
	(segment
		(start 406.168606 -339.686646)
		(end 404.69566 -348.006416)
		(width 0.14732)
		(layer "In15.Cu")
		(net "P5E_CPU0_PE2_TX_DP<2>")
	)
	(segment
		(start 374.71223 -213.753954)
		(end 374.71223 -213.387178)
		(width 0.0889)
		(layer "In15.Cu")
		(net "P5E_CPU0_PE2_TX_DP<2>")
	)
	(segment
		(start 394.617194 -216.317576)
		(end 394.61694 -216.31783)
		(width 0.14732)
		(layer "In15.Cu")
		(net "P5E_CPU0_PE2_TX_DP<2>")
	)
	(segment
		(start 373.481346 -215.931242)
		(end 373.490236 -215.926162)
		(width 0.0889)
		(layer "In15.Cu")
		(net "P5E_CPU0_PE2_TX_DP<2>")
	)
	(segment
		(start 374.754394 -213.345014)
		(end 374.754394 -213.322916)
		(width 0.0889)
		(layer "In15.Cu")
		(net "P5E_CPU0_PE2_TX_DP<2>")
	)
	(segment
		(start 410.555186 -395.64437)
		(end 410.554678 -395.64437)
		(width 0.14732)
		(layer "In15.Cu")
		(net "P5E_CPU0_PE2_TX_DP<2>")
	)
	(segment
		(start 411.055058 -397.83385)
		(end 411.05455 -397.83385)
		(width 0.14732)
		(layer "In15.Cu")
		(net "P5E_CPU0_PE2_TX_DP<2>")
	)
	(segment
		(start 410.905706 -397.740124)
		(end 411.055058 -397.83385)
		(width 0.14732)
		(layer "In15.Cu")
		(net "P5E_CPU0_PE2_TX_DP<2>")
	)
	(segment
		(start 411.155642 -398.834864)
		(end 411.304994 -398.928336)
		(width 0.14732)
		(layer "In15.Cu")
		(net "P5E_CPU0_PE2_TX_DP<2>")
	)
	(segment
		(start 411.53969 -399.957036)
		(end 411.53969 -400.563588)
		(width 0.14732)
		(layer "In15.Cu")
		(net "P5E_CPU0_PE2_TX_DP<2>")
	)
	(segment
		(start 372.83263 -218.707716)
		(end 372.83263 -218.692222)
		(width 0.0889)
		(layer "In15.Cu")
		(net "P5E_CPU0_PE2_TX_DP<2>")
	)
	(segment
		(start 374.71223 -213.387178)
		(end 374.754394 -213.345014)
		(width 0.0889)
		(layer "In15.Cu")
		(net "P5E_CPU0_PE2_TX_DP<2>")
	)
	(segment
		(start 398.846802 -307.733954)
		(end 406.168606 -339.686646)
		(width 0.14732)
		(layer "In15.Cu")
		(net "P5E_CPU0_PE2_TX_DP<2>")
	)
	(segment
		(start 371.423184 -222.780098)
		(end 371.423184 -222.761556)
		(width 0.0889)
		(layer "In15.Cu")
		(net "P5E_CPU0_PE2_TX_DP<2>")
	)
	(segment
		(start 410.90215 -397.164814)
		(end 410.808424 -397.313912)
		(width 0.14732)
		(layer "In15.Cu")
		(net "P5E_CPU0_PE2_TX_DP<2>")
	)
	(segment
		(start 373.949468 -214.846154)
		(end 374.47982 -214.315802)
		(width 0.0889)
		(layer "In15.Cu")
		(net "P5E_CPU0_PE2_TX_DP<2>")
	)
	(segment
		(start 411.152086 -398.259554)
		(end 411.05836 -398.408652)
		(width 0.14732)
		(layer "In15.Cu")
		(net "P5E_CPU0_PE2_TX_DP<2>")
	)
	(segment
		(start 374.754394 -212.22208)
		(end 376.458988 -210.517486)
		(width 0.14732)
		(layer "In15.Cu")
		(net "P5E_CPU0_PE2_TX_DP<2>")
	)
	(segment
		(start 373.772684 -215.272112)
		(end 373.949468 -214.846154)
		(width 0.0889)
		(layer "In15.Cu")
		(net "P5E_CPU0_PE2_TX_DP<2>")
	)
	(segment
		(start 372.541546 -219.18676)
		(end 372.550436 -219.18168)
		(width 0.0889)
		(layer "In15.Cu")
		(net "P5E_CPU0_PE2_TX_DP<2>")
	)
	(segment
		(start 376.458988 -210.517486)
		(end 379.509782 -209.253836)
		(width 0.14732)
		(layer "In15.Cu")
		(net "P5E_CPU0_PE2_TX_DP<2>")
	)
	(segment
		(start 372.362984 -221.133924)
		(end 372.362984 -221.1197)
		(width 0.0889)
		(layer "In15.Cu")
		(net "P5E_CPU0_PE2_TX_DP<2>")
	)
	(segment
		(start 411.05582 -397.83893)
		(end 411.152086 -398.259554)
		(width 0.14732)
		(layer "In15.Cu")
		(net "P5E_CPU0_PE2_TX_DP<2>")
	)
	(segment
		(start 373.011192 -218.372944)
		(end 373.020082 -218.367864)
		(width 0.0889)
		(layer "In15.Cu")
		(net "P5E_CPU0_PE2_TX_DP<2>")
	)
	(segment
		(start 374.47982 -214.315802)
		(end 374.71223 -213.753954)
		(width 0.0889)
		(layer "In15.Cu")
		(net "P5E_CPU0_PE2_TX_DP<2>")
	)
	(segment
		(start 410.554678 -395.64437)
		(end 410.555694 -395.648434)
		(width 0.14732)
		(layer "In15.Cu")
		(net "P5E_CPU0_PE2_TX_DP<2>")
	)
	(segment
		(start 374.754394 -213.322916)
		(end 374.754394 -212.22208)
		(width 0.14732)
		(layer "In15.Cu")
		(net "P5E_CPU0_PE2_TX_DP<2>")
	)
	(segment
		(start 410.558488 -396.219172)
		(end 410.65577 -396.645384)
		(width 0.14732)
		(layer "In15.Cu")
		(net "P5E_CPU0_PE2_TX_DP<2>")
	)
	(segment
		(start 391.17016 -211.816696)
		(end 394.617194 -216.317576)
		(width 0.14732)
		(layer "In15.Cu")
		(net "P5E_CPU0_PE2_TX_DP<2>")
	)
	(segment
		(start 399.662396 -226.783392)
		(end 402.706332 -246.95531)
		(width 0.14732)
		(layer "In15.Cu")
		(net "P5E_CPU0_PE2_TX_DP<2>")
	)
	(segment
		(start 370.074698 -224.118424)
		(end 370.163598 -224.094802)
		(width 0.0889)
		(layer "In15.Cu")
		(net "P5E_CPU0_PE2_TX_DP<2>")
	)
	(segment
		(start 411.05455 -397.83385)
		(end 411.05582 -397.83893)
		(width 0.14732)
		(layer "In15.Cu")
		(net "P5E_CPU0_PE2_TX_DP<2>")
	)
	(segment
		(start 371.89283 -221.963234)
		(end 371.89283 -221.94774)
		(width 0.0889)
		(layer "In15.Cu")
		(net "P5E_CPU0_PE2_TX_DP<2>")
	)
	(segment
		(start 369.918234 -224.389442)
		(end 370.074698 -224.118424)
		(width 0.0889)
		(layer "In15.Cu")
		(net "P5E_CPU0_PE2_TX_DP<2>")
	)
	(segment
		(start 404.69566 -348.006416)
		(end 404.60422 -369.579652)
		(width 0.14732)
		(layer "In15.Cu")
		(net "P5E_CPU0_PE2_TX_DP<2>")
	)
	(segment
		(start 404.60422 -369.579652)
		(end 410.402278 -394.975334)
		(width 0.14732)
		(layer "In15.Cu")
		(net "P5E_CPU0_PE2_TX_DP<2>")
	)
	(segment
		(start 370.670836 -224.065084)
		(end 370.676932 -224.061528)
		(width 0.0889)
		(layer "In15.Cu")
		(net "P5E_CPU0_PE2_TX_DP<2>")
	)
	(segment
		(start 372.071392 -221.628462)
		(end 372.080282 -221.623382)
		(width 0.0889)
		(layer "In15.Cu")
		(net "P5E_CPU0_PE2_TX_DP<2>")
	)
	(segment
		(start 398.06372 -220.81871)
		(end 399.662396 -226.783392)
		(width 0.14732)
		(layer "In15.Cu")
		(net "P5E_CPU0_PE2_TX_DP<2>")
	)
	(segment
		(start 411.30474 -398.928336)
		(end 411.53969 -399.957036)
		(width 0.14732)
		(layer "In15.Cu")
		(net "P5E_CPU0_PE2_TX_DP<2>")
	)
	(segment
		(start 373.020082 -218.367864)
		(end 373.026178 -218.364308)
		(width 0.0889)
		(layer "In15.Cu")
		(net "P5E_CPU0_PE2_TX_DP<2>")
	)
	(segment
		(start 371.131846 -223.256348)
		(end 371.140736 -223.251268)
		(width 0.0889)
		(layer "In15.Cu")
		(net "P5E_CPU0_PE2_TX_DP<2>")
	)
	(segment
		(start 379.509782 -209.253836)
		(end 384.983482 -209.253836)
		(width 0.14732)
		(layer "In15.Cu")
		(net "P5E_CPU0_PE2_TX_DP<2>")
	)
	(segment
		(start 384.983482 -209.253836)
		(end 391.17016 -211.816696)
		(width 0.14732)
		(layer "In15.Cu")
		(net "P5E_CPU0_PE2_TX_DP<2>")
	)
	(segment
		(start 411.53969 -400.563588)
		(end 411.24505 -400.858228)
		(width 0.14732)
		(layer "In15.Cu")
		(net "P5E_CPU0_PE2_TX_DP<2>")
	)
	(segment
		(start 411.05836 -398.408652)
		(end 411.155642 -398.834864)
		(width 0.14732)
		(layer "In15.Cu")
		(net "P5E_CPU0_PE2_TX_DP<2>")
	)
	(segment
		(start 410.80563 -396.743174)
		(end 410.90215 -397.164814)
		(width 0.14732)
		(layer "In15.Cu")
		(net "P5E_CPU0_PE2_TX_DP<2>")
	)
	(segment
		(start 411.304994 -398.928336)
		(end 411.30474 -398.928336)
		(width 0.14732)
		(layer "In15.Cu")
		(net "P5E_CPU0_PE2_TX_DP<2>")
	)
	(segment
		(start 410.65577 -396.645384)
		(end 410.805122 -396.73911)
		(width 0.14732)
		(layer "In15.Cu")
		(net "P5E_CPU0_PE2_TX_DP<2>")
	)
	(segment
		(start 410.804614 -396.73911)
		(end 410.80563 -396.743174)
		(width 0.14732)
		(layer "In15.Cu")
		(net "P5E_CPU0_PE2_TX_DP<2>")
	)
	(segment
		(start 373.020336 -217.388694)
		(end 373.011446 -217.383614)
		(width 0.0889)
		(layer "In15.Cu")
		(net "P5E_CPU0_PE2_TX_DP<2>")
	)
	(segment
		(start 373.772684 -215.44661)
		(end 373.772684 -215.272112)
		(width 0.0889)
		(layer "In15.Cu")
		(net "P5E_CPU0_PE2_TX_DP<2>")
	)
	(segment
		(start 373.302784 -216.260426)
		(end 373.302784 -216.25052)
		(width 0.0889)
		(layer "In15.Cu")
		(net "P5E_CPU0_PE2_TX_DP<2>")
	)
	(segment
		(start 372.081044 -219.994988)
		(end 372.086378 -219.99194)
		(width 0.0889)
		(layer "In15.Cu")
		(net "P5E_CPU0_PE2_TX_DP<2>")
	)
	(segment
		(start 373.011446 -216.745058)
		(end 373.019574 -216.740486)
		(width 0.0889)
		(layer "In15.Cu")
		(net "P5E_CPU0_PE2_TX_DP<2>")
	)
	(segment
		(start 410.652214 -396.070074)
		(end 410.558488 -396.219172)
		(width 0.14732)
		(layer "In15.Cu")
		(net "P5E_CPU0_PE2_TX_DP<2>")
	)
	(segment
		(start 373.019574 -216.740486)
		(end 373.020336 -216.739978)
		(width 0.0889)
		(layer "In15.Cu")
		(net "P5E_CPU0_PE2_TX_DP<2>")
	)
	(arc
		(start 373.490236 -215.926162)
		(mid 373.694571 -215.723557)
		(end 373.772684 -215.44661)
		(width 0.0889)
		(layer "In15.Cu")
		(net "P5E_CPU0_PE2_TX_DP<2>")
	)
	(arc
		(start 372.086378 -221.619826)
		(mid 372.288965 -221.413475)
		(end 372.362984 -221.133924)
		(width 0.0889)
		(layer "In15.Cu")
		(net "P5E_CPU0_PE2_TX_DP<2>")
	)
	(arc
		(start 370.18341 -224.10293)
		(mid 370.431421 -224.139395)
		(end 370.670836 -224.065084)
		(width 0.0889)
		(layer "In15.Cu")
		(net "P5E_CPU0_PE2_TX_DP<2>")
	)
	(arc
		(start 373.011446 -217.383614)
		(mid 372.832849 -217.064336)
		(end 373.011446 -216.745058)
		(width 0.0889)
		(layer "In15.Cu")
		(net "P5E_CPU0_PE2_TX_DP<2>")
	)
	(arc
		(start 371.140736 -223.251268)
		(mid 371.343022 -223.052287)
		(end 371.423184 -222.780098)
		(width 0.0889)
		(layer "In15.Cu")
		(net "P5E_CPU0_PE2_TX_DP<2>")
	)
	(arc
		(start 372.362984 -221.1197)
		(mid 372.283765 -220.845015)
		(end 372.080282 -220.644212)
		(width 0.0889)
		(layer "In15.Cu")
		(net "P5E_CPU0_PE2_TX_DP<2>")
	)
	(arc
		(start 372.83263 -218.692222)
		(mid 372.880309 -218.509322)
		(end 373.011192 -218.372944)
		(width 0.0889)
		(layer "In15.Cu")
		(net "P5E_CPU0_PE2_TX_DP<2>")
	)
	(arc
		(start 370.953284 -223.575626)
		(mid 371.000963 -223.392726)
		(end 371.131846 -223.256348)
		(width 0.0889)
		(layer "In15.Cu")
		(net "P5E_CPU0_PE2_TX_DP<2>")
	)
	(arc
		(start 371.89283 -221.94774)
		(mid 371.940509 -221.76484)
		(end 372.071392 -221.628462)
		(width 0.0889)
		(layer "In15.Cu")
		(net "P5E_CPU0_PE2_TX_DP<2>")
	)
	(arc
		(start 372.550436 -219.18168)
		(mid 372.753259 -218.981449)
		(end 372.83263 -218.707716)
		(width 0.0889)
		(layer "In15.Cu")
		(net "P5E_CPU0_PE2_TX_DP<2>")
	)
	(arc
		(start 373.026178 -218.364308)
		(mid 373.228765 -218.157957)
		(end 373.302784 -217.878406)
		(width 0.0889)
		(layer "In15.Cu")
		(net "P5E_CPU0_PE2_TX_DP<2>")
	)
	(arc
		(start 371.893084 -220.311218)
		(mid 371.945354 -220.128853)
		(end 372.080282 -219.995496)
		(width 0.0889)
		(layer "In15.Cu")
		(net "P5E_CPU0_PE2_TX_DP<2>")
	)
	(arc
		(start 373.302784 -217.859864)
		(mid 373.222622 -217.587675)
		(end 373.020336 -217.388694)
		(width 0.0889)
		(layer "In15.Cu")
		(net "P5E_CPU0_PE2_TX_DP<2>")
	)
	(arc
		(start 372.362984 -219.506038)
		(mid 372.410663 -219.323138)
		(end 372.541546 -219.18676)
		(width 0.0889)
		(layer "In15.Cu")
		(net "P5E_CPU0_PE2_TX_DP<2>")
	)
	(arc
		(start 373.302784 -216.25052)
		(mid 373.350463 -216.06762)
		(end 373.481346 -215.931242)
		(width 0.0889)
		(layer "In15.Cu")
		(net "P5E_CPU0_PE2_TX_DP<2>")
	)
	(arc
		(start 371.423184 -222.761556)
		(mid 371.470863 -222.578656)
		(end 371.601746 -222.442278)
		(width 0.0889)
		(layer "In15.Cu")
		(net "P5E_CPU0_PE2_TX_DP<2>")
	)
	(arc
		(start 370.676932 -224.061528)
		(mid 370.879345 -223.855115)
		(end 370.953284 -223.575626)
		(width 0.0889)
		(layer "In15.Cu")
		(net "P5E_CPU0_PE2_TX_DP<2>")
	)
	(arc
		(start 372.086378 -219.99194)
		(mid 372.288965 -219.785589)
		(end 372.362984 -219.506038)
		(width 0.0889)
		(layer "In15.Cu")
		(net "P5E_CPU0_PE2_TX_DP<2>")
	)
	(arc
		(start 373.020336 -216.739978)
		(mid 373.224671 -216.537373)
		(end 373.302784 -216.260426)
		(width 0.0889)
		(layer "In15.Cu")
		(net "P5E_CPU0_PE2_TX_DP<2>")
	)
	(arc
		(start 372.080282 -220.644212)
		(mid 371.945349 -220.510858)
		(end 371.893084 -220.32849)
		(width 0.0889)
		(layer "In15.Cu")
		(net "P5E_CPU0_PE2_TX_DP<2>")
	)
	(arc
		(start 371.610636 -222.437198)
		(mid 371.813459 -222.236967)
		(end 371.89283 -221.963234)
		(width 0.0889)
		(layer "In15.Cu")
		(net "P5E_CPU0_PE2_TX_DP<2>")
	)
	(arc
		(start 370.163598 -224.094802)
		(mid 370.173465 -224.098961)
		(end 370.18341 -224.10293)
		(width 0.0889)
		(layer "In15.Cu")
		(net "P5E_CPU0_PE2_TX_DP<2>")
	)
	(segment
		(start 414.613852 -401.777962)
		(end 414.287462 -402.104352)
		(width 0.13208)
		(layer "F.Cu")
		(net "P5E_CPU0_PE2_TX_DP<1>")
	)
	(segment
		(start 414.613852 -401.16379)
		(end 414.613852 -401.777962)
		(width 0.13208)
		(layer "F.Cu")
		(net "P5E_CPU0_PE2_TX_DP<1>")
	)
	(segment
		(start 414.30829 -400.858228)
		(end 414.613852 -401.16379)
		(width 0.13208)
		(layer "F.Cu")
		(net "P5E_CPU0_PE2_TX_DP<1>")
	)
	(segment
		(start 369.448334 -225.203512)
		(end 369.44808 -225.203258)
		(width 0.13208)
		(layer "F.Cu")
		(net "P5E_CPU0_PE2_TX_DP<1>")
	)
	(segment
		(start 369.448334 -225.739198)
		(end 369.448334 -225.203512)
		(width 0.13208)
		(layer "F.Cu")
		(net "P5E_CPU0_PE2_TX_DP<1>")
	)
	(segment
		(start 414.287462 -402.104352)
		(end 414.28289 -402.104352)
		(width 0.13208)
		(layer "F.Cu")
		(net "P5E_CPU0_PE2_TX_DP<1>")
	)
	(segment
		(start 407.143966 -339.690456)
		(end 405.649938 -348.001844)
		(width 0.14732)
		(layer "In15.Cu")
		(net "P5E_CPU0_PE2_TX_DP<1>")
	)
	(segment
		(start 370.483384 -222.77578)
		(end 370.483384 -222.761556)
		(width 0.0889)
		(layer "In15.Cu")
		(net "P5E_CPU0_PE2_TX_DP<1>")
	)
	(segment
		(start 371.139974 -219.996004)
		(end 371.140736 -219.995496)
		(width 0.0889)
		(layer "In15.Cu")
		(net "P5E_CPU0_PE2_TX_DP<1>")
	)
	(segment
		(start 403.700996 -247.251982)
		(end 403.910292 -253.48057)
		(width 0.14732)
		(layer "In15.Cu")
		(net "P5E_CPU0_PE2_TX_DP<1>")
	)
	(segment
		(start 382.916176 -202.27544)
		(end 384.53822 -203.623418)
		(width 0.14732)
		(layer "In15.Cu")
		(net "P5E_CPU0_PE2_TX_DP<1>")
	)
	(segment
		(start 399.792952 -307.585364)
		(end 407.143966 -339.690456)
		(width 0.14732)
		(layer "In15.Cu")
		(net "P5E_CPU0_PE2_TX_DP<1>")
	)
	(segment
		(start 373.105934 -214.711788)
		(end 373.669306 -214.148416)
		(width 0.0889)
		(layer "In15.Cu")
		(net "P5E_CPU0_PE2_TX_DP<1>")
	)
	(segment
		(start 371.423184 -219.515944)
		(end 371.423184 -219.506038)
		(width 0.0889)
		(layer "In15.Cu")
		(net "P5E_CPU0_PE2_TX_DP<1>")
	)
	(segment
		(start 371.140482 -221.623382)
		(end 371.146578 -221.619826)
		(width 0.0889)
		(layer "In15.Cu")
		(net "P5E_CPU0_PE2_TX_DP<1>")
	)
	(segment
		(start 372.83263 -215.370664)
		(end 373.105934 -214.711788)
		(width 0.0889)
		(layer "In15.Cu")
		(net "P5E_CPU0_PE2_TX_DP<1>")
	)
	(segment
		(start 405.866346 -369.461288)
		(end 412.998412 -394.310362)
		(width 0.14732)
		(layer "In15.Cu")
		(net "P5E_CPU0_PE2_TX_DP<1>")
	)
	(segment
		(start 373.771922 -213.89975)
		(end 373.771922 -213.387178)
		(width 0.0889)
		(layer "In15.Cu")
		(net "P5E_CPU0_PE2_TX_DP<1>")
	)
	(segment
		(start 414.420304 -399.2626)
		(end 414.419796 -399.2626)
		(width 0.14732)
		(layer "In15.Cu")
		(net "P5E_CPU0_PE2_TX_DP<1>")
	)
	(segment
		(start 373.814086 -213.322916)
		(end 373.814086 -211.96935)
		(width 0.14732)
		(layer "In15.Cu")
		(net "P5E_CPU0_PE2_TX_DP<1>")
	)
	(segment
		(start 413.223456 -395.535658)
		(end 413.343852 -395.955774)
		(width 0.14732)
		(layer "In15.Cu")
		(net "P5E_CPU0_PE2_TX_DP<1>")
	)
	(segment
		(start 413.923734 -397.533622)
		(end 413.840168 -397.684498)
		(width 0.14732)
		(layer "In15.Cu")
		(net "P5E_CPU0_PE2_TX_DP<1>")
	)
	(segment
		(start 372.080282 -218.367864)
		(end 372.086378 -218.364308)
		(width 0.0889)
		(layer "In15.Cu")
		(net "P5E_CPU0_PE2_TX_DP<1>")
	)
	(segment
		(start 381.720852 -201.971402)
		(end 382.172972 -201.98969)
		(width 0.14732)
		(layer "In15.Cu")
		(net "P5E_CPU0_PE2_TX_DP<1>")
	)
	(segment
		(start 413.343852 -395.955774)
		(end 413.494982 -396.03934)
		(width 0.14732)
		(layer "In15.Cu")
		(net "P5E_CPU0_PE2_TX_DP<1>")
	)
	(segment
		(start 384.53822 -203.623418)
		(end 391.99185 -211.00796)
		(width 0.14732)
		(layer "In15.Cu")
		(net "P5E_CPU0_PE2_TX_DP<1>")
	)
	(segment
		(start 382.172972 -201.98969)
		(end 382.916176 -202.27544)
		(width 0.14732)
		(layer "In15.Cu")
		(net "P5E_CPU0_PE2_TX_DP<1>")
	)
	(segment
		(start 405.649938 -348.001844)
		(end 405.866346 -369.461288)
		(width 0.14732)
		(layer "In15.Cu")
		(net "P5E_CPU0_PE2_TX_DP<1>")
	)
	(segment
		(start 396.96009 -217.604086)
		(end 396.959836 -217.604086)
		(width 0.14732)
		(layer "In15.Cu")
		(net "P5E_CPU0_PE2_TX_DP<1>")
	)
	(segment
		(start 372.081044 -216.73947)
		(end 372.086378 -216.736422)
		(width 0.0889)
		(layer "In15.Cu")
		(net "P5E_CPU0_PE2_TX_DP<1>")
	)
	(segment
		(start 372.362984 -217.878406)
		(end 372.362984 -217.864182)
		(width 0.0889)
		(layer "In15.Cu")
		(net "P5E_CPU0_PE2_TX_DP<1>")
	)
	(segment
		(start 371.601746 -219.18676)
		(end 371.610636 -219.18168)
		(width 0.0889)
		(layer "In15.Cu")
		(net "P5E_CPU0_PE2_TX_DP<1>")
	)
	(segment
		(start 413.652208 -397.030194)
		(end 413.803338 -397.11376)
		(width 0.14732)
		(layer "In15.Cu")
		(net "P5E_CPU0_PE2_TX_DP<1>")
	)
	(segment
		(start 414.148524 -398.758918)
		(end 414.269174 -399.179034)
		(width 0.14732)
		(layer "In15.Cu")
		(net "P5E_CPU0_PE2_TX_DP<1>")
	)
	(segment
		(start 413.960564 -398.104614)
		(end 414.111694 -398.18818)
		(width 0.14732)
		(layer "In15.Cu")
		(net "P5E_CPU0_PE2_TX_DP<1>")
	)
	(segment
		(start 369.291616 -224.93224)
		(end 369.315746 -224.843086)
		(width 0.0889)
		(layer "In15.Cu")
		(net "P5E_CPU0_PE2_TX_DP<1>")
	)
	(segment
		(start 371.89283 -218.707716)
		(end 371.89283 -218.692222)
		(width 0.0889)
		(layer "In15.Cu")
		(net "P5E_CPU0_PE2_TX_DP<1>")
	)
	(segment
		(start 371.131592 -221.628462)
		(end 371.140482 -221.623382)
		(width 0.0889)
		(layer "In15.Cu")
		(net "P5E_CPU0_PE2_TX_DP<1>")
	)
	(segment
		(start 371.893084 -217.072972)
		(end 371.893084 -217.0557)
		(width 0.0889)
		(layer "In15.Cu")
		(net "P5E_CPU0_PE2_TX_DP<1>")
	)
	(segment
		(start 414.269174 -399.179034)
		(end 414.420304 -399.2626)
		(width 0.14732)
		(layer "In15.Cu")
		(net "P5E_CPU0_PE2_TX_DP<1>")
	)
	(segment
		(start 413.615378 -396.459202)
		(end 413.531812 -396.610078)
		(width 0.14732)
		(layer "In15.Cu")
		(net "P5E_CPU0_PE2_TX_DP<1>")
	)
	(segment
		(start 413.615124 -396.45844)
		(end 413.615378 -396.459202)
		(width 0.14732)
		(layer "In15.Cu")
		(net "P5E_CPU0_PE2_TX_DP<1>")
	)
	(segment
		(start 414.602422 -399.898616)
		(end 414.602676 -399.89887)
		(width 0.14732)
		(layer "In15.Cu")
		(net "P5E_CPU0_PE2_TX_DP<1>")
	)
	(segment
		(start 371.423184 -221.133924)
		(end 371.423184 -221.115382)
		(width 0.0889)
		(layer "In15.Cu")
		(net "P5E_CPU0_PE2_TX_DP<1>")
	)
	(segment
		(start 413.92348 -397.53286)
		(end 413.923734 -397.533622)
		(width 0.14732)
		(layer "In15.Cu")
		(net "P5E_CPU0_PE2_TX_DP<1>")
	)
	(segment
		(start 412.998412 -394.310362)
		(end 412.998666 -394.310362)
		(width 0.14732)
		(layer "In15.Cu")
		(net "P5E_CPU0_PE2_TX_DP<1>")
	)
	(segment
		(start 369.44808 -225.203258)
		(end 369.291616 -224.93224)
		(width 0.0889)
		(layer "In15.Cu")
		(net "P5E_CPU0_PE2_TX_DP<1>")
	)
	(segment
		(start 396.959836 -217.604086)
		(end 398.943576 -220.237812)
		(width 0.14732)
		(layer "In15.Cu")
		(net "P5E_CPU0_PE2_TX_DP<1>")
	)
	(segment
		(start 373.814086 -211.96935)
		(end 374.171464 -211.10702)
		(width 0.14732)
		(layer "In15.Cu")
		(net "P5E_CPU0_PE2_TX_DP<1>")
	)
	(segment
		(start 372.541546 -215.931242)
		(end 372.550436 -215.926162)
		(width 0.0889)
		(layer "In15.Cu")
		(net "P5E_CPU0_PE2_TX_DP<1>")
	)
	(segment
		(start 371.140736 -220.644212)
		(end 371.131846 -220.639132)
		(width 0.0889)
		(layer "In15.Cu")
		(net "P5E_CPU0_PE2_TX_DP<1>")
	)
	(segment
		(start 396.789402 -217.58021)
		(end 396.96009 -217.604086)
		(width 0.14732)
		(layer "In15.Cu")
		(net "P5E_CPU0_PE2_TX_DP<1>")
	)
	(segment
		(start 413.307022 -395.384782)
		(end 413.223456 -395.535658)
		(width 0.14732)
		(layer "In15.Cu")
		(net "P5E_CPU0_PE2_TX_DP<1>")
	)
	(segment
		(start 396.526258 -217.23096)
		(end 396.789402 -217.58021)
		(width 0.14732)
		(layer "In15.Cu")
		(net "P5E_CPU0_PE2_TX_DP<1>")
	)
	(segment
		(start 396.550388 -217.060272)
		(end 396.526258 -217.23096)
		(width 0.14732)
		(layer "In15.Cu")
		(net "P5E_CPU0_PE2_TX_DP<1>")
	)
	(segment
		(start 373.814086 -213.345014)
		(end 373.814086 -213.322916)
		(width 0.0889)
		(layer "In15.Cu")
		(net "P5E_CPU0_PE2_TX_DP<1>")
	)
	(segment
		(start 371.131846 -220.000576)
		(end 371.139974 -219.996004)
		(width 0.0889)
		(layer "In15.Cu")
		(net "P5E_CPU0_PE2_TX_DP<1>")
	)
	(segment
		(start 370.95303 -221.963234)
		(end 370.95303 -221.94774)
		(width 0.0889)
		(layer "In15.Cu")
		(net "P5E_CPU0_PE2_TX_DP<1>")
	)
	(segment
		(start 414.23209 -398.608042)
		(end 414.148524 -398.758918)
		(width 0.14732)
		(layer "In15.Cu")
		(net "P5E_CPU0_PE2_TX_DP<1>")
	)
	(segment
		(start 373.669306 -214.148416)
		(end 373.771922 -213.89975)
		(width 0.0889)
		(layer "In15.Cu")
		(net "P5E_CPU0_PE2_TX_DP<1>")
	)
	(segment
		(start 374.171464 -211.10702)
		(end 381.19304 -202.34783)
		(width 0.14732)
		(layer "In15.Cu")
		(net "P5E_CPU0_PE2_TX_DP<1>")
	)
	(segment
		(start 412.9151 -394.461238)
		(end 413.035496 -394.881354)
		(width 0.14732)
		(layer "In15.Cu")
		(net "P5E_CPU0_PE2_TX_DP<1>")
	)
	(segment
		(start 370.661946 -222.442278)
		(end 370.670836 -222.437198)
		(width 0.0889)
		(layer "In15.Cu")
		(net "P5E_CPU0_PE2_TX_DP<1>")
	)
	(segment
		(start 381.454914 -202.085702)
		(end 381.720852 -201.971402)
		(width 0.14732)
		(layer "In15.Cu")
		(net "P5E_CPU0_PE2_TX_DP<1>")
	)
	(segment
		(start 372.83263 -215.436704)
		(end 372.83263 -215.370664)
		(width 0.0889)
		(layer "In15.Cu")
		(net "P5E_CPU0_PE2_TX_DP<1>")
	)
	(segment
		(start 413.035496 -394.881354)
		(end 413.186626 -394.96492)
		(width 0.14732)
		(layer "In15.Cu")
		(net "P5E_CPU0_PE2_TX_DP<1>")
	)
	(segment
		(start 369.722146 -224.070164)
		(end 369.731036 -224.065084)
		(width 0.0889)
		(layer "In15.Cu")
		(net "P5E_CPU0_PE2_TX_DP<1>")
	)
	(segment
		(start 372.080282 -216.739978)
		(end 372.081044 -216.73947)
		(width 0.0889)
		(layer "In15.Cu")
		(net "P5E_CPU0_PE2_TX_DP<1>")
	)
	(segment
		(start 413.531812 -396.610078)
		(end 413.652208 -397.030194)
		(width 0.14732)
		(layer "In15.Cu")
		(net "P5E_CPU0_PE2_TX_DP<1>")
	)
	(segment
		(start 414.419796 -399.2626)
		(end 414.602422 -399.898616)
		(width 0.14732)
		(layer "In15.Cu")
		(net "P5E_CPU0_PE2_TX_DP<1>")
	)
	(segment
		(start 414.602676 -400.563842)
		(end 414.30829 -400.858228)
		(width 0.14732)
		(layer "In15.Cu")
		(net "P5E_CPU0_PE2_TX_DP<1>")
	)
	(segment
		(start 413.803338 -397.11376)
		(end 413.92348 -397.53286)
		(width 0.14732)
		(layer "In15.Cu")
		(net "P5E_CPU0_PE2_TX_DP<1>")
	)
	(segment
		(start 400.566128 -226.476306)
		(end 403.700996 -247.251982)
		(width 0.14732)
		(layer "In15.Cu")
		(net "P5E_CPU0_PE2_TX_DP<1>")
	)
	(segment
		(start 413.840168 -397.684498)
		(end 413.960564 -398.104614)
		(width 0.14732)
		(layer "In15.Cu")
		(net "P5E_CPU0_PE2_TX_DP<1>")
	)
	(segment
		(start 414.602676 -399.89887)
		(end 414.602676 -400.563842)
		(width 0.14732)
		(layer "In15.Cu")
		(net "P5E_CPU0_PE2_TX_DP<1>")
	)
	(segment
		(start 413.186626 -394.96492)
		(end 413.307022 -395.384782)
		(width 0.14732)
		(layer "In15.Cu")
		(net "P5E_CPU0_PE2_TX_DP<1>")
	)
	(segment
		(start 412.998666 -394.310362)
		(end 412.9151 -394.461238)
		(width 0.14732)
		(layer "In15.Cu")
		(net "P5E_CPU0_PE2_TX_DP<1>")
	)
	(segment
		(start 414.111694 -398.18818)
		(end 414.23209 -398.608042)
		(width 0.14732)
		(layer "In15.Cu")
		(net "P5E_CPU0_PE2_TX_DP<1>")
	)
	(segment
		(start 413.494982 -396.03934)
		(end 413.615124 -396.45844)
		(width 0.14732)
		(layer "In15.Cu")
		(net "P5E_CPU0_PE2_TX_DP<1>")
	)
	(segment
		(start 403.910292 -253.48057)
		(end 399.792952 -307.585364)
		(width 0.14732)
		(layer "In15.Cu")
		(net "P5E_CPU0_PE2_TX_DP<1>")
	)
	(segment
		(start 373.771922 -213.387178)
		(end 373.814086 -213.345014)
		(width 0.0889)
		(layer "In15.Cu")
		(net "P5E_CPU0_PE2_TX_DP<1>")
	)
	(segment
		(start 391.99185 -211.00796)
		(end 396.550388 -217.060272)
		(width 0.14732)
		(layer "In15.Cu")
		(net "P5E_CPU0_PE2_TX_DP<1>")
	)
	(segment
		(start 381.19304 -202.34783)
		(end 381.454914 -202.085702)
		(width 0.14732)
		(layer "In15.Cu")
		(net "P5E_CPU0_PE2_TX_DP<1>")
	)
	(segment
		(start 370.013484 -223.585532)
		(end 370.013484 -223.56699)
		(width 0.0889)
		(layer "In15.Cu")
		(net "P5E_CPU0_PE2_TX_DP<1>")
	)
	(segment
		(start 372.83263 -215.452198)
		(end 372.83263 -215.437212)
		(width 0.0889)
		(layer "In15.Cu")
		(net "P5E_CPU0_PE2_TX_DP<1>")
	)
	(segment
		(start 398.943576 -220.237812)
		(end 400.566128 -226.476306)
		(width 0.14732)
		(layer "In15.Cu")
		(net "P5E_CPU0_PE2_TX_DP<1>")
	)
	(segment
		(start 372.071392 -218.372944)
		(end 372.080282 -218.367864)
		(width 0.0889)
		(layer "In15.Cu")
		(net "P5E_CPU0_PE2_TX_DP<1>")
	)
	(arc
		(start 371.610636 -219.18168)
		(mid 371.813459 -218.981449)
		(end 371.89283 -218.707716)
		(width 0.0889)
		(layer "In15.Cu")
		(net "P5E_CPU0_PE2_TX_DP<1>")
	)
	(arc
		(start 372.086378 -216.736422)
		(mid 372.288965 -216.530071)
		(end 372.362984 -216.25052)
		(width 0.0889)
		(layer "In15.Cu")
		(net "P5E_CPU0_PE2_TX_DP<1>")
	)
	(arc
		(start 370.95303 -221.94774)
		(mid 371.000709 -221.76484)
		(end 371.131592 -221.628462)
		(width 0.0889)
		(layer "In15.Cu")
		(net "P5E_CPU0_PE2_TX_DP<1>")
	)
	(arc
		(start 372.83263 -215.437212)
		(mid 372.83263 -215.436958)
		(end 372.83263 -215.436704)
		(width 0.0889)
		(layer "In15.Cu")
		(net "P5E_CPU0_PE2_TX_DP<1>")
	)
	(arc
		(start 371.423184 -219.506038)
		(mid 371.470863 -219.323138)
		(end 371.601746 -219.18676)
		(width 0.0889)
		(layer "In15.Cu")
		(net "P5E_CPU0_PE2_TX_DP<1>")
	)
	(arc
		(start 370.200682 -223.251268)
		(mid 370.404163 -223.050464)
		(end 370.483384 -222.77578)
		(width 0.0889)
		(layer "In15.Cu")
		(net "P5E_CPU0_PE2_TX_DP<1>")
	)
	(arc
		(start 371.140736 -219.995496)
		(mid 371.345071 -219.792891)
		(end 371.423184 -219.515944)
		(width 0.0889)
		(layer "In15.Cu")
		(net "P5E_CPU0_PE2_TX_DP<1>")
	)
	(arc
		(start 371.146578 -221.619826)
		(mid 371.349165 -221.413475)
		(end 371.423184 -221.133924)
		(width 0.0889)
		(layer "In15.Cu")
		(net "P5E_CPU0_PE2_TX_DP<1>")
	)
	(arc
		(start 369.731036 -224.065084)
		(mid 369.935371 -223.862479)
		(end 370.013484 -223.585532)
		(width 0.0889)
		(layer "In15.Cu")
		(net "P5E_CPU0_PE2_TX_DP<1>")
	)
	(arc
		(start 372.080282 -217.388694)
		(mid 371.945349 -217.25534)
		(end 371.893084 -217.072972)
		(width 0.0889)
		(layer "In15.Cu")
		(net "P5E_CPU0_PE2_TX_DP<1>")
	)
	(arc
		(start 371.131846 -220.639132)
		(mid 371.000932 -220.502772)
		(end 370.953284 -220.319854)
		(width 0.0889)
		(layer "In15.Cu")
		(net "P5E_CPU0_PE2_TX_DP<1>")
	)
	(arc
		(start 369.315746 -224.843086)
		(mid 369.324318 -224.836564)
		(end 369.332764 -224.829878)
		(width 0.0889)
		(layer "In15.Cu")
		(net "P5E_CPU0_PE2_TX_DP<1>")
	)
	(arc
		(start 370.483384 -222.761556)
		(mid 370.531063 -222.578656)
		(end 370.661946 -222.442278)
		(width 0.0889)
		(layer "In15.Cu")
		(net "P5E_CPU0_PE2_TX_DP<1>")
	)
	(arc
		(start 369.543584 -224.389442)
		(mid 369.591263 -224.206542)
		(end 369.722146 -224.070164)
		(width 0.0889)
		(layer "In15.Cu")
		(net "P5E_CPU0_PE2_TX_DP<1>")
	)
	(arc
		(start 372.086378 -218.364308)
		(mid 372.288965 -218.157957)
		(end 372.362984 -217.878406)
		(width 0.0889)
		(layer "In15.Cu")
		(net "P5E_CPU0_PE2_TX_DP<1>")
	)
	(arc
		(start 371.89283 -218.692222)
		(mid 371.940509 -218.509322)
		(end 372.071392 -218.372944)
		(width 0.0889)
		(layer "In15.Cu")
		(net "P5E_CPU0_PE2_TX_DP<1>")
	)
	(arc
		(start 370.953284 -220.319854)
		(mid 371.000963 -220.136954)
		(end 371.131846 -220.000576)
		(width 0.0889)
		(layer "In15.Cu")
		(net "P5E_CPU0_PE2_TX_DP<1>")
	)
	(arc
		(start 370.670836 -222.437198)
		(mid 370.873659 -222.236967)
		(end 370.95303 -221.963234)
		(width 0.0889)
		(layer "In15.Cu")
		(net "P5E_CPU0_PE2_TX_DP<1>")
	)
	(arc
		(start 369.332764 -224.829878)
		(mid 369.488162 -224.633597)
		(end 369.543584 -224.389442)
		(width 0.0889)
		(layer "In15.Cu")
		(net "P5E_CPU0_PE2_TX_DP<1>")
	)
	(arc
		(start 372.362984 -217.864182)
		(mid 372.283765 -217.589497)
		(end 372.080282 -217.388694)
		(width 0.0889)
		(layer "In15.Cu")
		(net "P5E_CPU0_PE2_TX_DP<1>")
	)
	(arc
		(start 372.550436 -215.926162)
		(mid 372.753259 -215.725931)
		(end 372.83263 -215.452198)
		(width 0.0889)
		(layer "In15.Cu")
		(net "P5E_CPU0_PE2_TX_DP<1>")
	)
	(arc
		(start 371.893084 -217.0557)
		(mid 371.945354 -216.873335)
		(end 372.080282 -216.739978)
		(width 0.0889)
		(layer "In15.Cu")
		(net "P5E_CPU0_PE2_TX_DP<1>")
	)
	(arc
		(start 370.013484 -223.56699)
		(mid 370.065754 -223.384625)
		(end 370.200682 -223.251268)
		(width 0.0889)
		(layer "In15.Cu")
		(net "P5E_CPU0_PE2_TX_DP<1>")
	)
	(arc
		(start 372.362984 -216.25052)
		(mid 372.410663 -216.06762)
		(end 372.541546 -215.931242)
		(width 0.0889)
		(layer "In15.Cu")
		(net "P5E_CPU0_PE2_TX_DP<1>")
	)
	(arc
		(start 371.423184 -221.115382)
		(mid 371.343022 -220.843193)
		(end 371.140736 -220.644212)
		(width 0.0889)
		(layer "In15.Cu")
		(net "P5E_CPU0_PE2_TX_DP<1>")
	)
	(segment
		(start 371.987572 -401.157186)
		(end 371.987572 -401.779994)
		(width 0.13208)
		(layer "F.Cu")
		(net "P5E_CPU0_PE2_TX_DP<15>")
	)
	(segment
		(start 382.605534 -225.739198)
		(end 382.605534 -225.203258)
		(width 0.13208)
		(layer "F.Cu")
		(net "P5E_CPU0_PE2_TX_DP<15>")
	)
	(segment
		(start 372.28653 -400.858228)
		(end 371.987572 -401.157186)
		(width 0.13208)
		(layer "F.Cu")
		(net "P5E_CPU0_PE2_TX_DP<15>")
	)
	(segment
		(start 371.987572 -401.779994)
		(end 372.31193 -402.104352)
		(width 0.13208)
		(layer "F.Cu")
		(net "P5E_CPU0_PE2_TX_DP<15>")
	)
	(segment
		(start 382.409446 -225.522536)
		(end 382.418336 -225.527616)
		(width 0.0889)
		(layer "In15.Cu")
		(net "P5E_CPU0_PE2_TX_DP<15>")
	)
	(segment
		(start 386.350256 -253.397258)
		(end 386.950966 -254.84709)
		(width 0.14732)
		(layer "In15.Cu")
		(net "P5E_CPU0_PE2_TX_DP<15>")
	)
	(segment
		(start 387.44017 -366.948466)
		(end 387.439916 -366.948466)
		(width 0.14732)
		(layer "In15.Cu")
		(net "P5E_CPU0_PE2_TX_DP<15>")
	)
	(segment
		(start 387.439662 -366.948974)
		(end 372.135908 -399.465292)
		(width 0.14732)
		(layer "In15.Cu")
		(net "P5E_CPU0_PE2_TX_DP<15>")
	)
	(segment
		(start 386.760212 -233.276902)
		(end 386.520436 -246.008398)
		(width 0.14732)
		(layer "In15.Cu")
		(net "P5E_CPU0_PE2_TX_DP<15>")
	)
	(segment
		(start 393.479782 -339.30844)
		(end 391.13587 -353.675696)
		(width 0.14732)
		(layer "In15.Cu")
		(net "P5E_CPU0_PE2_TX_DP<15>")
	)
	(segment
		(start 384.854196 -227.733606)
		(end 385.566666 -228.447854)
		(width 0.14732)
		(layer "In15.Cu")
		(net "P5E_CPU0_PE2_TX_DP<15>")
	)
	(segment
		(start 387.449822 -366.927892)
		(end 387.44017 -366.948466)
		(width 0.14732)
		(layer "In15.Cu")
		(net "P5E_CPU0_PE2_TX_DP<15>")
	)
	(segment
		(start 385.452112 -250.579636)
		(end 385.814062 -252.631194)
		(width 0.14732)
		(layer "In15.Cu")
		(net "P5E_CPU0_PE2_TX_DP<15>")
	)
	(segment
		(start 385.814062 -252.631194)
		(end 386.350256 -253.397258)
		(width 0.14732)
		(layer "In15.Cu")
		(net "P5E_CPU0_PE2_TX_DP<15>")
	)
	(segment
		(start 389.264906 -259.66928)
		(end 388.4041 -271.523714)
		(width 0.14732)
		(layer "In15.Cu")
		(net "P5E_CPU0_PE2_TX_DP<15>")
	)
	(segment
		(start 386.772912 -232.595928)
		(end 386.892546 -232.720134)
		(width 0.14732)
		(layer "In15.Cu")
		(net "P5E_CPU0_PE2_TX_DP<15>")
	)
	(segment
		(start 386.520436 -246.008398)
		(end 385.891532 -248.087896)
		(width 0.14732)
		(layer "In15.Cu")
		(net "P5E_CPU0_PE2_TX_DP<15>")
	)
	(segment
		(start 382.44907 -224.93224)
		(end 382.370838 -224.911412)
		(width 0.0889)
		(layer "In15.Cu")
		(net "P5E_CPU0_PE2_TX_DP<15>")
	)
	(segment
		(start 384.838702 -227.718112)
		(end 384.854196 -227.733606)
		(width 0.0889)
		(layer "In15.Cu")
		(net "P5E_CPU0_PE2_TX_DP<15>")
	)
	(segment
		(start 383.670556 -227.269294)
		(end 384.469894 -227.408994)
		(width 0.0889)
		(layer "In15.Cu")
		(net "P5E_CPU0_PE2_TX_DP<15>")
	)
	(segment
		(start 385.566666 -228.447854)
		(end 386.676392 -230.542338)
		(width 0.14732)
		(layer "In15.Cu")
		(net "P5E_CPU0_PE2_TX_DP<15>")
	)
	(segment
		(start 386.884418 -233.157268)
		(end 386.759958 -233.276902)
		(width 0.14732)
		(layer "In15.Cu")
		(net "P5E_CPU0_PE2_TX_DP<15>")
	)
	(segment
		(start 386.950966 -254.84709)
		(end 388.377176 -256.883662)
		(width 0.14732)
		(layer "In15.Cu")
		(net "P5E_CPU0_PE2_TX_DP<15>")
	)
	(segment
		(start 382.605534 -225.203258)
		(end 382.44907 -224.93224)
		(width 0.0889)
		(layer "In15.Cu")
		(net "P5E_CPU0_PE2_TX_DP<15>")
	)
	(segment
		(start 384.779012 -227.718112)
		(end 384.838702 -227.718112)
		(width 0.0889)
		(layer "In15.Cu")
		(net "P5E_CPU0_PE2_TX_DP<15>")
	)
	(segment
		(start 388.377176 -256.883662)
		(end 389.264906 -259.66928)
		(width 0.14732)
		(layer "In15.Cu")
		(net "P5E_CPU0_PE2_TX_DP<15>")
	)
	(segment
		(start 386.676392 -230.542338)
		(end 386.780786 -232.157778)
		(width 0.14732)
		(layer "In15.Cu")
		(net "P5E_CPU0_PE2_TX_DP<15>")
	)
	(segment
		(start 386.892546 -232.720134)
		(end 386.884418 -233.157268)
		(width 0.14732)
		(layer "In15.Cu")
		(net "P5E_CPU0_PE2_TX_DP<15>")
	)
	(segment
		(start 372.135908 -399.465292)
		(end 371.99189 -400.142202)
		(width 0.14732)
		(layer "In15.Cu")
		(net "P5E_CPU0_PE2_TX_DP<15>")
	)
	(segment
		(start 384.469894 -227.408994)
		(end 384.779012 -227.718112)
		(width 0.0889)
		(layer "In15.Cu")
		(net "P5E_CPU0_PE2_TX_DP<15>")
	)
	(segment
		(start 386.759958 -233.276902)
		(end 386.760212 -233.276902)
		(width 0.14732)
		(layer "In15.Cu")
		(net "P5E_CPU0_PE2_TX_DP<15>")
	)
	(segment
		(start 387.439916 -366.948466)
		(end 387.439662 -366.948974)
		(width 0.14732)
		(layer "In15.Cu")
		(net "P5E_CPU0_PE2_TX_DP<15>")
	)
	(segment
		(start 386.780786 -232.157778)
		(end 386.78104 -232.159302)
		(width 0.14732)
		(layer "In15.Cu")
		(net "P5E_CPU0_PE2_TX_DP<15>")
	)
	(segment
		(start 383.349246 -227.150422)
		(end 383.359152 -227.156518)
		(width 0.0889)
		(layer "In15.Cu")
		(net "P5E_CPU0_PE2_TX_DP<15>")
	)
	(segment
		(start 388.4041 -271.523714)
		(end 386.502402 -310.488584)
		(width 0.14732)
		(layer "In15.Cu")
		(net "P5E_CPU0_PE2_TX_DP<15>")
	)
	(segment
		(start 382.700784 -225.998786)
		(end 382.700784 -226.017328)
		(width 0.0889)
		(layer "In15.Cu")
		(net "P5E_CPU0_PE2_TX_DP<15>")
	)
	(segment
		(start 391.13587 -353.675696)
		(end 387.449822 -366.927892)
		(width 0.14732)
		(layer "In15.Cu")
		(net "P5E_CPU0_PE2_TX_DP<15>")
	)
	(segment
		(start 382.879346 -226.336606)
		(end 382.888236 -226.341686)
		(width 0.0889)
		(layer "In15.Cu")
		(net "P5E_CPU0_PE2_TX_DP<15>")
	)
	(segment
		(start 371.99189 -400.142202)
		(end 371.99189 -400.563588)
		(width 0.14732)
		(layer "In15.Cu")
		(net "P5E_CPU0_PE2_TX_DP<15>")
	)
	(segment
		(start 371.99189 -400.563588)
		(end 372.28653 -400.858228)
		(width 0.14732)
		(layer "In15.Cu")
		(net "P5E_CPU0_PE2_TX_DP<15>")
	)
	(segment
		(start 385.891532 -248.087896)
		(end 385.452112 -250.579636)
		(width 0.14732)
		(layer "In15.Cu")
		(net "P5E_CPU0_PE2_TX_DP<15>")
	)
	(segment
		(start 382.888236 -226.341686)
		(end 382.894332 -226.345242)
		(width 0.0889)
		(layer "In15.Cu")
		(net "P5E_CPU0_PE2_TX_DP<15>")
	)
	(segment
		(start 386.78104 -232.159302)
		(end 386.772912 -232.595928)
		(width 0.14732)
		(layer "In15.Cu")
		(net "P5E_CPU0_PE2_TX_DP<15>")
	)
	(segment
		(start 386.502402 -310.488584)
		(end 393.479782 -339.30844)
		(width 0.14732)
		(layer "In15.Cu")
		(net "P5E_CPU0_PE2_TX_DP<15>")
	)
	(arc
		(start 382.894332 -226.345242)
		(mid 383.096745 -226.551655)
		(end 383.170684 -226.831144)
		(width 0.0889)
		(layer "In15.Cu")
		(net "P5E_CPU0_PE2_TX_DP<15>")
	)
	(arc
		(start 382.230884 -225.203258)
		(mid 382.278563 -225.386158)
		(end 382.409446 -225.522536)
		(width 0.0889)
		(layer "In15.Cu")
		(net "P5E_CPU0_PE2_TX_DP<15>")
	)
	(arc
		(start 383.359152 -227.156518)
		(mid 383.509918 -227.226539)
		(end 383.670556 -227.269294)
		(width 0.0889)
		(layer "In15.Cu")
		(net "P5E_CPU0_PE2_TX_DP<15>")
	)
	(arc
		(start 382.700784 -226.017328)
		(mid 382.748463 -226.200228)
		(end 382.879346 -226.336606)
		(width 0.0889)
		(layer "In15.Cu")
		(net "P5E_CPU0_PE2_TX_DP<15>")
	)
	(arc
		(start 382.370838 -224.911412)
		(mid 382.267693 -225.041437)
		(end 382.230884 -225.203258)
		(width 0.0889)
		(layer "In15.Cu")
		(net "P5E_CPU0_PE2_TX_DP<15>")
	)
	(arc
		(start 383.170684 -226.831144)
		(mid 383.218363 -227.014044)
		(end 383.349246 -227.150422)
		(width 0.0889)
		(layer "In15.Cu")
		(net "P5E_CPU0_PE2_TX_DP<15>")
	)
	(arc
		(start 382.418336 -225.527616)
		(mid 382.620622 -225.726597)
		(end 382.700784 -225.998786)
		(width 0.0889)
		(layer "In15.Cu")
		(net "P5E_CPU0_PE2_TX_DP<15>")
	)
	(segment
		(start 374.791732 -401.16379)
		(end 374.791732 -401.777962)
		(width 0.13208)
		(layer "F.Cu")
		(net "P5E_CPU0_PE2_TX_DP<14>")
	)
	(segment
		(start 374.48617 -400.858228)
		(end 374.791732 -401.16379)
		(width 0.13208)
		(layer "F.Cu")
		(net "P5E_CPU0_PE2_TX_DP<14>")
	)
	(segment
		(start 374.465342 -402.104352)
		(end 374.46077 -402.104352)
		(width 0.13208)
		(layer "F.Cu")
		(net "P5E_CPU0_PE2_TX_DP<14>")
	)
	(segment
		(start 381.19558 -224.389696)
		(end 381.195834 -224.389442)
		(width 0.13208)
		(layer "F.Cu")
		(net "P5E_CPU0_PE2_TX_DP<14>")
	)
	(segment
		(start 374.791732 -401.777962)
		(end 374.465342 -402.104352)
		(width 0.13208)
		(layer "F.Cu")
		(net "P5E_CPU0_PE2_TX_DP<14>")
	)
	(segment
		(start 381.19558 -224.925382)
		(end 381.19558 -224.389696)
		(width 0.13208)
		(layer "F.Cu")
		(net "P5E_CPU0_PE2_TX_DP<14>")
	)
	(segment
		(start 388.444486 -366.908588)
		(end 376.323098 -396.365222)
		(width 0.14732)
		(layer "In15.Cu")
		(net "P5E_CPU0_PE2_TX_DP<14>")
	)
	(segment
		(start 375.29135 -398.872456)
		(end 374.78081 -400.113246)
		(width 0.14732)
		(layer "In15.Cu")
		(net "P5E_CPU0_PE2_TX_DP<14>")
	)
	(segment
		(start 386.904484 -249.065796)
		(end 386.904484 -251.254514)
		(width 0.14732)
		(layer "In15.Cu")
		(net "P5E_CPU0_PE2_TX_DP<14>")
	)
	(segment
		(start 387.181852 -310.41086)
		(end 394.205714 -339.28939)
		(width 0.14732)
		(layer "In15.Cu")
		(net "P5E_CPU0_PE2_TX_DP<14>")
	)
	(segment
		(start 375.932446 -397.314674)
		(end 375.74347 -397.393414)
		(width 0.14732)
		(layer "In15.Cu")
		(net "P5E_CPU0_PE2_TX_DP<14>")
	)
	(segment
		(start 384.202432 -225.69297)
		(end 384.211322 -225.69805)
		(width 0.0889)
		(layer "In15.Cu")
		(net "P5E_CPU0_PE2_TX_DP<14>")
	)
	(segment
		(start 385.225798 -227.056696)
		(end 385.225798 -227.116386)
		(width 0.0889)
		(layer "In15.Cu")
		(net "P5E_CPU0_PE2_TX_DP<14>")
	)
	(segment
		(start 383.919984 -225.203258)
		(end 383.919984 -225.2218)
		(width 0.0889)
		(layer "In15.Cu")
		(net "P5E_CPU0_PE2_TX_DP<14>")
	)
	(segment
		(start 383.732532 -224.8789)
		(end 383.741422 -224.88398)
		(width 0.0889)
		(layer "In15.Cu")
		(net "P5E_CPU0_PE2_TX_DP<14>")
	)
	(segment
		(start 376.323098 -396.365222)
		(end 376.133868 -396.444216)
		(width 0.14732)
		(layer "In15.Cu")
		(net "P5E_CPU0_PE2_TX_DP<14>")
	)
	(segment
		(start 376.0724 -396.97406)
		(end 375.932446 -397.314674)
		(width 0.14732)
		(layer "In15.Cu")
		(net "P5E_CPU0_PE2_TX_DP<14>")
	)
	(segment
		(start 375.99366 -396.785084)
		(end 376.0724 -396.97406)
		(width 0.14732)
		(layer "In15.Cu")
		(net "P5E_CPU0_PE2_TX_DP<14>")
	)
	(segment
		(start 388.627874 -255.888236)
		(end 389.24738 -256.750566)
		(width 0.14732)
		(layer "In15.Cu")
		(net "P5E_CPU0_PE2_TX_DP<14>")
	)
	(segment
		(start 387.585204 -229.475792)
		(end 388.282942 -231.006142)
		(width 0.14732)
		(layer "In15.Cu")
		(net "P5E_CPU0_PE2_TX_DP<14>")
	)
	(segment
		(start 386.904484 -251.254514)
		(end 387.935216 -254.252476)
		(width 0.14732)
		(layer "In15.Cu")
		(net "P5E_CPU0_PE2_TX_DP<14>")
	)
	(segment
		(start 384.681476 -226.512374)
		(end 385.225798 -227.056696)
		(width 0.0889)
		(layer "In15.Cu")
		(net "P5E_CPU0_PE2_TX_DP<14>")
	)
	(segment
		(start 390.012936 -259.517896)
		(end 387.181852 -310.41086)
		(width 0.14732)
		(layer "In15.Cu")
		(net "P5E_CPU0_PE2_TX_DP<14>")
	)
	(segment
		(start 384.672332 -226.506786)
		(end 384.673094 -226.507294)
		(width 0.0889)
		(layer "In15.Cu")
		(net "P5E_CPU0_PE2_TX_DP<14>")
	)
	(segment
		(start 385.225798 -227.116386)
		(end 385.241292 -227.13188)
		(width 0.0889)
		(layer "In15.Cu")
		(net "P5E_CPU0_PE2_TX_DP<14>")
	)
	(segment
		(start 389.24738 -256.750566)
		(end 390.012936 -259.517896)
		(width 0.14732)
		(layer "In15.Cu")
		(net "P5E_CPU0_PE2_TX_DP<14>")
	)
	(segment
		(start 375.603262 -397.734282)
		(end 375.682002 -397.923258)
		(width 0.14732)
		(layer "In15.Cu")
		(net "P5E_CPU0_PE2_TX_DP<14>")
	)
	(segment
		(start 375.682002 -397.923258)
		(end 375.542048 -398.263618)
		(width 0.14732)
		(layer "In15.Cu")
		(net "P5E_CPU0_PE2_TX_DP<14>")
	)
	(segment
		(start 384.673094 -226.507294)
		(end 384.681222 -226.511866)
		(width 0.0889)
		(layer "In15.Cu")
		(net "P5E_CPU0_PE2_TX_DP<14>")
	)
	(segment
		(start 394.205714 -339.28939)
		(end 391.894822 -353.547934)
		(width 0.14732)
		(layer "In15.Cu")
		(net "P5E_CPU0_PE2_TX_DP<14>")
	)
	(segment
		(start 384.389884 -226.017328)
		(end 384.390138 -226.03587)
		(width 0.0889)
		(layer "In15.Cu")
		(net "P5E_CPU0_PE2_TX_DP<14>")
	)
	(segment
		(start 381.195834 -224.389442)
		(end 381.352298 -224.118424)
		(width 0.0889)
		(layer "In15.Cu")
		(net "P5E_CPU0_PE2_TX_DP<14>")
	)
	(segment
		(start 391.894822 -353.547934)
		(end 388.444486 -366.908588)
		(width 0.14732)
		(layer "In15.Cu")
		(net "P5E_CPU0_PE2_TX_DP<14>")
	)
	(segment
		(start 374.78081 -400.113246)
		(end 374.78081 -400.563588)
		(width 0.14732)
		(layer "In15.Cu")
		(net "P5E_CPU0_PE2_TX_DP<14>")
	)
	(segment
		(start 383.72034 -224.871788)
		(end 383.732532 -224.8789)
		(width 0.0889)
		(layer "In15.Cu")
		(net "P5E_CPU0_PE2_TX_DP<14>")
	)
	(segment
		(start 376.133868 -396.444216)
		(end 375.99366 -396.785084)
		(width 0.14732)
		(layer "In15.Cu")
		(net "P5E_CPU0_PE2_TX_DP<14>")
	)
	(segment
		(start 384.680968 -226.51212)
		(end 384.681476 -226.512374)
		(width 0.0889)
		(layer "In15.Cu")
		(net "P5E_CPU0_PE2_TX_DP<14>")
	)
	(segment
		(start 375.74347 -397.393414)
		(end 375.603262 -397.734282)
		(width 0.14732)
		(layer "In15.Cu")
		(net "P5E_CPU0_PE2_TX_DP<14>")
	)
	(segment
		(start 389.217662 -244.310154)
		(end 388.342632 -247.048782)
		(width 0.14732)
		(layer "In15.Cu")
		(net "P5E_CPU0_PE2_TX_DP<14>")
	)
	(segment
		(start 387.935216 -254.252476)
		(end 388.627874 -255.888236)
		(width 0.14732)
		(layer "In15.Cu")
		(net "P5E_CPU0_PE2_TX_DP<14>")
	)
	(segment
		(start 375.21261 -398.68348)
		(end 375.29135 -398.872456)
		(width 0.14732)
		(layer "In15.Cu")
		(net "P5E_CPU0_PE2_TX_DP<14>")
	)
	(segment
		(start 375.352818 -398.342612)
		(end 375.21261 -398.68348)
		(width 0.14732)
		(layer "In15.Cu")
		(net "P5E_CPU0_PE2_TX_DP<14>")
	)
	(segment
		(start 387.935724 -247.601486)
		(end 387.337554 -248.019824)
		(width 0.14732)
		(layer "In15.Cu")
		(net "P5E_CPU0_PE2_TX_DP<14>")
	)
	(segment
		(start 388.342632 -247.048782)
		(end 387.935724 -247.601486)
		(width 0.14732)
		(layer "In15.Cu")
		(net "P5E_CPU0_PE2_TX_DP<14>")
	)
	(segment
		(start 384.681222 -226.511866)
		(end 384.680968 -226.51212)
		(width 0.0889)
		(layer "In15.Cu")
		(net "P5E_CPU0_PE2_TX_DP<14>")
	)
	(segment
		(start 374.78081 -400.563588)
		(end 374.48617 -400.858228)
		(width 0.14732)
		(layer "In15.Cu")
		(net "P5E_CPU0_PE2_TX_DP<14>")
	)
	(segment
		(start 375.542048 -398.263618)
		(end 375.352818 -398.342612)
		(width 0.14732)
		(layer "In15.Cu")
		(net "P5E_CPU0_PE2_TX_DP<14>")
	)
	(segment
		(start 383.263394 -224.065592)
		(end 383.271268 -224.070164)
		(width 0.0889)
		(layer "In15.Cu")
		(net "P5E_CPU0_PE2_TX_DP<14>")
	)
	(segment
		(start 388.282942 -231.006142)
		(end 389.217662 -244.310154)
		(width 0.14732)
		(layer "In15.Cu")
		(net "P5E_CPU0_PE2_TX_DP<14>")
	)
	(segment
		(start 383.262378 -224.065084)
		(end 383.263394 -224.065592)
		(width 0.0889)
		(layer "In15.Cu")
		(net "P5E_CPU0_PE2_TX_DP<14>")
	)
	(segment
		(start 382.877568 -224.07118)
		(end 382.887982 -224.065084)
		(width 0.0889)
		(layer "In15.Cu")
		(net "P5E_CPU0_PE2_TX_DP<14>")
	)
	(segment
		(start 387.337554 -248.019824)
		(end 386.904484 -249.065796)
		(width 0.14732)
		(layer "In15.Cu")
		(net "P5E_CPU0_PE2_TX_DP<14>")
	)
	(segment
		(start 381.352298 -224.118424)
		(end 381.441452 -224.094548)
		(width 0.0889)
		(layer "In15.Cu")
		(net "P5E_CPU0_PE2_TX_DP<14>")
	)
	(segment
		(start 385.241292 -227.13188)
		(end 387.585204 -229.475792)
		(width 0.14732)
		(layer "In15.Cu")
		(net "P5E_CPU0_PE2_TX_DP<14>")
	)
	(arc
		(start 384.211322 -225.69805)
		(mid 384.342236 -225.83441)
		(end 384.389884 -226.017328)
		(width 0.0889)
		(layer "In15.Cu")
		(net "P5E_CPU0_PE2_TX_DP<14>")
	)
	(arc
		(start 383.919984 -225.2218)
		(mid 384.000146 -225.493989)
		(end 384.202432 -225.69297)
		(width 0.0889)
		(layer "In15.Cu")
		(net "P5E_CPU0_PE2_TX_DP<14>")
	)
	(arc
		(start 383.741422 -224.88398)
		(mid 383.872336 -225.02034)
		(end 383.919984 -225.203258)
		(width 0.0889)
		(layer "In15.Cu")
		(net "P5E_CPU0_PE2_TX_DP<14>")
	)
	(arc
		(start 383.44983 -224.389442)
		(mid 383.522065 -224.665966)
		(end 383.72034 -224.871788)
		(width 0.0889)
		(layer "In15.Cu")
		(net "P5E_CPU0_PE2_TX_DP<14>")
	)
	(arc
		(start 381.441452 -224.094548)
		(mid 381.69845 -224.140036)
		(end 381.948436 -224.065084)
		(width 0.0889)
		(layer "In15.Cu")
		(net "P5E_CPU0_PE2_TX_DP<14>")
	)
	(arc
		(start 383.271268 -224.070164)
		(mid 383.402182 -224.206524)
		(end 383.44983 -224.389442)
		(width 0.0889)
		(layer "In15.Cu")
		(net "P5E_CPU0_PE2_TX_DP<14>")
	)
	(arc
		(start 382.322832 -224.065084)
		(mid 382.599391 -224.140827)
		(end 382.877568 -224.07118)
		(width 0.0889)
		(layer "In15.Cu")
		(net "P5E_CPU0_PE2_TX_DP<14>")
	)
	(arc
		(start 382.887982 -224.065084)
		(mid 383.07518 -224.014941)
		(end 383.262378 -224.065084)
		(width 0.0889)
		(layer "In15.Cu")
		(net "P5E_CPU0_PE2_TX_DP<14>")
	)
	(arc
		(start 384.390138 -226.03587)
		(mid 384.470211 -226.307911)
		(end 384.672332 -226.506786)
		(width 0.0889)
		(layer "In15.Cu")
		(net "P5E_CPU0_PE2_TX_DP<14>")
	)
	(arc
		(start 381.948436 -224.065084)
		(mid 382.135634 -224.014941)
		(end 382.322832 -224.065084)
		(width 0.0889)
		(layer "In15.Cu")
		(net "P5E_CPU0_PE2_TX_DP<14>")
	)
	(segment
		(start 377.528582 -402.104352)
		(end 377.52401 -402.104352)
		(width 0.13208)
		(layer "F.Cu")
		(net "P5E_CPU0_PE2_TX_DP<13>")
	)
	(segment
		(start 377.854972 -401.777962)
		(end 377.528582 -402.104352)
		(width 0.13208)
		(layer "F.Cu")
		(net "P5E_CPU0_PE2_TX_DP<13>")
	)
	(segment
		(start 380.725934 -225.203512)
		(end 380.72568 -225.203258)
		(width 0.13208)
		(layer "F.Cu")
		(net "P5E_CPU0_PE2_TX_DP<13>")
	)
	(segment
		(start 377.54941 -400.858228)
		(end 377.854972 -401.16379)
		(width 0.13208)
		(layer "F.Cu")
		(net "P5E_CPU0_PE2_TX_DP<13>")
	)
	(segment
		(start 377.854972 -401.16379)
		(end 377.854972 -401.777962)
		(width 0.13208)
		(layer "F.Cu")
		(net "P5E_CPU0_PE2_TX_DP<13>")
	)
	(segment
		(start 380.725934 -225.739198)
		(end 380.725934 -225.203512)
		(width 0.13208)
		(layer "F.Cu")
		(net "P5E_CPU0_PE2_TX_DP<13>")
	)
	(segment
		(start 381.291084 -223.585532)
		(end 381.291084 -223.575626)
		(width 0.0889)
		(layer "In15.Cu")
		(net "P5E_CPU0_PE2_TX_DP<13>")
	)
	(segment
		(start 385.04495 -225.649536)
		(end 385.391152 -225.995738)
		(width 0.0889)
		(layer "In15.Cu")
		(net "P5E_CPU0_PE2_TX_DP<13>")
	)
	(segment
		(start 384.389884 -224.389442)
		(end 384.389884 -224.399348)
		(width 0.0889)
		(layer "In15.Cu")
		(net "P5E_CPU0_PE2_TX_DP<13>")
	)
	(segment
		(start 384.672332 -224.8789)
		(end 384.681222 -224.88398)
		(width 0.0889)
		(layer "In15.Cu")
		(net "P5E_CPU0_PE2_TX_DP<13>")
	)
	(segment
		(start 384.196336 -224.061528)
		(end 384.202432 -224.065084)
		(width 0.0889)
		(layer "In15.Cu")
		(net "P5E_CPU0_PE2_TX_DP<13>")
	)
	(segment
		(start 388.471918 -370.04625)
		(end 388.287006 -370.134134)
		(width 0.14732)
		(layer "In15.Cu")
		(net "P5E_CPU0_PE2_TX_DP<13>")
	)
	(segment
		(start 395.186408 -339.353398)
		(end 392.82624 -353.903534)
		(width 0.14732)
		(layer "In15.Cu")
		(net "P5E_CPU0_PE2_TX_DP<13>")
	)
	(segment
		(start 378.397262 -398.548606)
		(end 378.27458 -398.895824)
		(width 0.14732)
		(layer "In15.Cu")
		(net "P5E_CPU0_PE2_TX_DP<13>")
	)
	(segment
		(start 388.266686 -252.182884)
		(end 388.596378 -253.31547)
		(width 0.14732)
		(layer "In15.Cu")
		(net "P5E_CPU0_PE2_TX_DP<13>")
	)
	(segment
		(start 380.569216 -224.93224)
		(end 380.593346 -224.843086)
		(width 0.0889)
		(layer "In15.Cu")
		(net "P5E_CPU0_PE2_TX_DP<13>")
	)
	(segment
		(start 385.391152 -225.995738)
		(end 385.845812 -225.995738)
		(width 0.0889)
		(layer "In15.Cu")
		(net "P5E_CPU0_PE2_TX_DP<13>")
	)
	(segment
		(start 390.308084 -256.528062)
		(end 391.039604 -259.378704)
		(width 0.14732)
		(layer "In15.Cu")
		(net "P5E_CPU0_PE2_TX_DP<13>")
	)
	(segment
		(start 386.190236 -226.400106)
		(end 386.20573 -226.4156)
		(width 0.0889)
		(layer "In15.Cu")
		(net "P5E_CPU0_PE2_TX_DP<13>")
	)
	(segment
		(start 388.164832 -250.344686)
		(end 388.266686 -252.182884)
		(width 0.14732)
		(layer "In15.Cu")
		(net "P5E_CPU0_PE2_TX_DP<13>")
	)
	(segment
		(start 384.859784 -225.203258)
		(end 384.859784 -225.213164)
		(width 0.0889)
		(layer "In15.Cu")
		(net "P5E_CPU0_PE2_TX_DP<13>")
	)
	(segment
		(start 388.287006 -370.134134)
		(end 388.164324 -370.481606)
		(width 0.14732)
		(layer "In15.Cu")
		(net "P5E_CPU0_PE2_TX_DP<13>")
	)
	(segment
		(start 377.84405 -400.563588)
		(end 377.54941 -400.858228)
		(width 0.14732)
		(layer "In15.Cu")
		(net "P5E_CPU0_PE2_TX_DP<13>")
	)
	(segment
		(start 383.91973 -223.56699)
		(end 383.91973 -223.575626)
		(width 0.0889)
		(layer "In15.Cu")
		(net "P5E_CPU0_PE2_TX_DP<13>")
	)
	(segment
		(start 378.089414 -398.983962)
		(end 377.966732 -399.331434)
		(width 0.14732)
		(layer "In15.Cu")
		(net "P5E_CPU0_PE2_TX_DP<13>")
	)
	(segment
		(start 378.431552 -398.016476)
		(end 378.30887 -398.363948)
		(width 0.14732)
		(layer "In15.Cu")
		(net "P5E_CPU0_PE2_TX_DP<13>")
	)
	(segment
		(start 378.616718 -397.928084)
		(end 378.431552 -398.016476)
		(width 0.14732)
		(layer "In15.Cu")
		(net "P5E_CPU0_PE2_TX_DP<13>")
	)
	(segment
		(start 381.469646 -223.256348)
		(end 381.478536 -223.251268)
		(width 0.0889)
		(layer "In15.Cu")
		(net "P5E_CPU0_PE2_TX_DP<13>")
	)
	(segment
		(start 386.20573 -226.4156)
		(end 388.145274 -228.355398)
		(width 0.14732)
		(layer "In15.Cu")
		(net "P5E_CPU0_PE2_TX_DP<13>")
	)
	(segment
		(start 384.203956 -224.065846)
		(end 384.211322 -224.070164)
		(width 0.0889)
		(layer "In15.Cu")
		(net "P5E_CPU0_PE2_TX_DP<13>")
	)
	(segment
		(start 390.213596 -244.346476)
		(end 389.549132 -246.386604)
		(width 0.14732)
		(layer "In15.Cu")
		(net "P5E_CPU0_PE2_TX_DP<13>")
	)
	(segment
		(start 389.324596 -255.123188)
		(end 390.308084 -256.528062)
		(width 0.14732)
		(layer "In15.Cu")
		(net "P5E_CPU0_PE2_TX_DP<13>")
	)
	(segment
		(start 389.362696 -367.525808)
		(end 388.471918 -370.04625)
		(width 0.14732)
		(layer "In15.Cu")
		(net "P5E_CPU0_PE2_TX_DP<13>")
	)
	(segment
		(start 388.164324 -370.481606)
		(end 388.252462 -370.666518)
		(width 0.14732)
		(layer "In15.Cu")
		(net "P5E_CPU0_PE2_TX_DP<13>")
	)
	(segment
		(start 391.039604 -259.378704)
		(end 388.188454 -310.274208)
		(width 0.14732)
		(layer "In15.Cu")
		(net "P5E_CPU0_PE2_TX_DP<13>")
	)
	(segment
		(start 378.055124 -399.516092)
		(end 377.84405 -400.113246)
		(width 0.14732)
		(layer "In15.Cu")
		(net "P5E_CPU0_PE2_TX_DP<13>")
	)
	(segment
		(start 388.375144 -249.154442)
		(end 388.164832 -250.344686)
		(width 0.14732)
		(layer "In15.Cu")
		(net "P5E_CPU0_PE2_TX_DP<13>")
	)
	(segment
		(start 389.548878 -246.386604)
		(end 388.884414 -248.426732)
		(width 0.14732)
		(layer "In15.Cu")
		(net "P5E_CPU0_PE2_TX_DP<13>")
	)
	(segment
		(start 388.188454 -310.274208)
		(end 395.186408 -339.353398)
		(width 0.14732)
		(layer "In15.Cu")
		(net "P5E_CPU0_PE2_TX_DP<13>")
	)
	(segment
		(start 388.596378 -253.31547)
		(end 388.713218 -253.64821)
		(width 0.14732)
		(layer "In15.Cu")
		(net "P5E_CPU0_PE2_TX_DP<13>")
	)
	(segment
		(start 386.190236 -226.340162)
		(end 386.190236 -226.400106)
		(width 0.0889)
		(layer "In15.Cu")
		(net "P5E_CPU0_PE2_TX_DP<13>")
	)
	(segment
		(start 378.61621 -397.928084)
		(end 378.616718 -397.928084)
		(width 0.14732)
		(layer "In15.Cu")
		(net "P5E_CPU0_PE2_TX_DP<13>")
	)
	(segment
		(start 388.884414 -248.426732)
		(end 388.375144 -249.154442)
		(width 0.14732)
		(layer "In15.Cu")
		(net "P5E_CPU0_PE2_TX_DP<13>")
	)
	(segment
		(start 378.27458 -398.895824)
		(end 378.089414 -398.983962)
		(width 0.14732)
		(layer "In15.Cu")
		(net "P5E_CPU0_PE2_TX_DP<13>")
	)
	(segment
		(start 384.202432 -224.065084)
		(end 384.203956 -224.065846)
		(width 0.0889)
		(layer "In15.Cu")
		(net "P5E_CPU0_PE2_TX_DP<13>")
	)
	(segment
		(start 389.256016 -230.790242)
		(end 390.213596 -244.346476)
		(width 0.14732)
		(layer "In15.Cu")
		(net "P5E_CPU0_PE2_TX_DP<13>")
	)
	(segment
		(start 392.82624 -353.903534)
		(end 389.362696 -367.525808)
		(width 0.14732)
		(layer "In15.Cu")
		(net "P5E_CPU0_PE2_TX_DP<13>")
	)
	(segment
		(start 388.145274 -228.355398)
		(end 389.256016 -230.790242)
		(width 0.14732)
		(layer "In15.Cu")
		(net "P5E_CPU0_PE2_TX_DP<13>")
	)
	(segment
		(start 389.549132 -246.386604)
		(end 389.548878 -246.386604)
		(width 0.14732)
		(layer "In15.Cu")
		(net "P5E_CPU0_PE2_TX_DP<13>")
	)
	(segment
		(start 378.30887 -398.363948)
		(end 378.397262 -398.548606)
		(width 0.14732)
		(layer "In15.Cu")
		(net "P5E_CPU0_PE2_TX_DP<13>")
	)
	(segment
		(start 377.84405 -400.113246)
		(end 377.84405 -400.563588)
		(width 0.14732)
		(layer "In15.Cu")
		(net "P5E_CPU0_PE2_TX_DP<13>")
	)
	(segment
		(start 385.845812 -225.995738)
		(end 386.190236 -226.340162)
		(width 0.0889)
		(layer "In15.Cu")
		(net "P5E_CPU0_PE2_TX_DP<13>")
	)
	(segment
		(start 377.966732 -399.331434)
		(end 378.055124 -399.516092)
		(width 0.14732)
		(layer "In15.Cu")
		(net "P5E_CPU0_PE2_TX_DP<13>")
	)
	(segment
		(start 380.72568 -225.203258)
		(end 380.569216 -224.93224)
		(width 0.0889)
		(layer "In15.Cu")
		(net "P5E_CPU0_PE2_TX_DP<13>")
	)
	(segment
		(start 388.713218 -253.64821)
		(end 389.324596 -255.123188)
		(width 0.14732)
		(layer "In15.Cu")
		(net "P5E_CPU0_PE2_TX_DP<13>")
	)
	(segment
		(start 380.999746 -224.070164)
		(end 381.008636 -224.065084)
		(width 0.0889)
		(layer "In15.Cu")
		(net "P5E_CPU0_PE2_TX_DP<13>")
	)
	(segment
		(start 388.252462 -370.666518)
		(end 378.61621 -397.928084)
		(width 0.14732)
		(layer "In15.Cu")
		(net "P5E_CPU0_PE2_TX_DP<13>")
	)
	(arc
		(start 381.852932 -223.251268)
		(mid 382.135634 -223.32701)
		(end 382.418336 -223.251268)
		(width 0.0889)
		(layer "In15.Cu")
		(net "P5E_CPU0_PE2_TX_DP<13>")
	)
	(arc
		(start 381.291084 -223.575626)
		(mid 381.338763 -223.392726)
		(end 381.469646 -223.256348)
		(width 0.0889)
		(layer "In15.Cu")
		(net "P5E_CPU0_PE2_TX_DP<13>")
	)
	(arc
		(start 380.593346 -224.843086)
		(mid 380.601918 -224.836564)
		(end 380.610364 -224.829878)
		(width 0.0889)
		(layer "In15.Cu")
		(net "P5E_CPU0_PE2_TX_DP<13>")
	)
	(arc
		(start 380.821184 -224.389442)
		(mid 380.868863 -224.206542)
		(end 380.999746 -224.070164)
		(width 0.0889)
		(layer "In15.Cu")
		(net "P5E_CPU0_PE2_TX_DP<13>")
	)
	(arc
		(start 381.478536 -223.251268)
		(mid 381.665734 -223.201125)
		(end 381.852932 -223.251268)
		(width 0.0889)
		(layer "In15.Cu")
		(net "P5E_CPU0_PE2_TX_DP<13>")
	)
	(arc
		(start 384.859784 -225.213164)
		(mid 384.910017 -225.449308)
		(end 385.04495 -225.649536)
		(width 0.0889)
		(layer "In15.Cu")
		(net "P5E_CPU0_PE2_TX_DP<13>")
	)
	(arc
		(start 384.211322 -224.070164)
		(mid 384.342236 -224.206524)
		(end 384.389884 -224.389442)
		(width 0.0889)
		(layer "In15.Cu")
		(net "P5E_CPU0_PE2_TX_DP<13>")
	)
	(arc
		(start 383.358136 -223.251268)
		(mid 383.545334 -223.201125)
		(end 383.732532 -223.251268)
		(width 0.0889)
		(layer "In15.Cu")
		(net "P5E_CPU0_PE2_TX_DP<13>")
	)
	(arc
		(start 382.792732 -223.251268)
		(mid 383.075434 -223.32701)
		(end 383.358136 -223.251268)
		(width 0.0889)
		(layer "In15.Cu")
		(net "P5E_CPU0_PE2_TX_DP<13>")
	)
	(arc
		(start 381.008636 -224.065084)
		(mid 381.212971 -223.862479)
		(end 381.291084 -223.585532)
		(width 0.0889)
		(layer "In15.Cu")
		(net "P5E_CPU0_PE2_TX_DP<13>")
	)
	(arc
		(start 383.91973 -223.575626)
		(mid 383.993721 -223.855192)
		(end 384.196336 -224.061528)
		(width 0.0889)
		(layer "In15.Cu")
		(net "P5E_CPU0_PE2_TX_DP<13>")
	)
	(arc
		(start 382.418336 -223.251268)
		(mid 382.605534 -223.201125)
		(end 382.792732 -223.251268)
		(width 0.0889)
		(layer "In15.Cu")
		(net "P5E_CPU0_PE2_TX_DP<13>")
	)
	(arc
		(start 380.610364 -224.829878)
		(mid 380.765762 -224.633597)
		(end 380.821184 -224.389442)
		(width 0.0889)
		(layer "In15.Cu")
		(net "P5E_CPU0_PE2_TX_DP<13>")
	)
	(arc
		(start 383.732532 -223.251268)
		(mid 383.867465 -223.384622)
		(end 383.91973 -223.56699)
		(width 0.0889)
		(layer "In15.Cu")
		(net "P5E_CPU0_PE2_TX_DP<13>")
	)
	(arc
		(start 384.389884 -224.399348)
		(mid 384.467995 -224.676297)
		(end 384.672332 -224.8789)
		(width 0.0889)
		(layer "In15.Cu")
		(net "P5E_CPU0_PE2_TX_DP<13>")
	)
	(arc
		(start 384.681222 -224.88398)
		(mid 384.812136 -225.02034)
		(end 384.859784 -225.203258)
		(width 0.0889)
		(layer "In15.Cu")
		(net "P5E_CPU0_PE2_TX_DP<13>")
	)
	(segment
		(start 379.31598 -224.389696)
		(end 379.316234 -224.389442)
		(width 0.13208)
		(layer "F.Cu")
		(net "P5E_CPU0_PE2_TX_DP<12>")
	)
	(segment
		(start 379.31598 -224.925382)
		(end 379.31598 -224.389696)
		(width 0.13208)
		(layer "F.Cu")
		(net "P5E_CPU0_PE2_TX_DP<12>")
	)
	(segment
		(start 380.591822 -402.104352)
		(end 380.58725 -402.104352)
		(width 0.13208)
		(layer "F.Cu")
		(net "P5E_CPU0_PE2_TX_DP<12>")
	)
	(segment
		(start 380.918212 -401.777962)
		(end 380.591822 -402.104352)
		(width 0.13208)
		(layer "F.Cu")
		(net "P5E_CPU0_PE2_TX_DP<12>")
	)
	(segment
		(start 380.61265 -400.858228)
		(end 380.918212 -401.16379)
		(width 0.13208)
		(layer "F.Cu")
		(net "P5E_CPU0_PE2_TX_DP<12>")
	)
	(segment
		(start 380.918212 -401.16379)
		(end 380.918212 -401.777962)
		(width 0.13208)
		(layer "F.Cu")
		(net "P5E_CPU0_PE2_TX_DP<12>")
	)
	(segment
		(start 381.29718 -398.786604)
		(end 381.117348 -398.884648)
		(width 0.14732)
		(layer "In15.Cu")
		(net "P5E_CPU0_PE2_TX_DP<12>")
	)
	(segment
		(start 389.859774 -369.646454)
		(end 381.875792 -396.817088)
		(width 0.14732)
		(layer "In15.Cu")
		(net "P5E_CPU0_PE2_TX_DP<12>")
	)
	(segment
		(start 391.269728 -256.280158)
		(end 392.018774 -259.28701)
		(width 0.14732)
		(layer "In15.Cu")
		(net "P5E_CPU0_PE2_TX_DP<12>")
	)
	(segment
		(start 380.537974 -223.251776)
		(end 380.538736 -223.251268)
		(width 0.0889)
		(layer "In15.Cu")
		(net "P5E_CPU0_PE2_TX_DP<12>")
	)
	(segment
		(start 379.316234 -224.389442)
		(end 379.472698 -224.118424)
		(width 0.0889)
		(layer "In15.Cu")
		(net "P5E_CPU0_PE2_TX_DP<12>")
	)
	(segment
		(start 389.432292 -249.266456)
		(end 389.225028 -250.44146)
		(width 0.14732)
		(layer "In15.Cu")
		(net "P5E_CPU0_PE2_TX_DP<12>")
	)
	(segment
		(start 381.406654 -397.900144)
		(end 381.302768 -398.253712)
		(width 0.14732)
		(layer "In15.Cu")
		(net "P5E_CPU0_PE2_TX_DP<12>")
	)
	(segment
		(start 380.529846 -223.256348)
		(end 380.537974 -223.251776)
		(width 0.0889)
		(layer "In15.Cu")
		(net "P5E_CPU0_PE2_TX_DP<12>")
	)
	(segment
		(start 392.018774 -259.28701)
		(end 389.13689 -310.033162)
		(width 0.14732)
		(layer "In15.Cu")
		(net "P5E_CPU0_PE2_TX_DP<12>")
	)
	(segment
		(start 393.736068 -354.199952)
		(end 389.859774 -369.646454)
		(width 0.14732)
		(layer "In15.Cu")
		(net "P5E_CPU0_PE2_TX_DP<12>")
	)
	(segment
		(start 381.690118 -397.448532)
		(end 381.586486 -397.801846)
		(width 0.14732)
		(layer "In15.Cu")
		(net "P5E_CPU0_PE2_TX_DP<12>")
	)
	(segment
		(start 381.875792 -396.817088)
		(end 381.69596 -396.915386)
		(width 0.14732)
		(layer "In15.Cu")
		(net "P5E_CPU0_PE2_TX_DP<12>")
	)
	(segment
		(start 386.977636 -223.71812)
		(end 386.985764 -223.726248)
		(width 0.0889)
		(layer "In15.Cu")
		(net "P5E_CPU0_PE2_TX_DP<12>")
	)
	(segment
		(start 381.013462 -399.238216)
		(end 381.111506 -399.418048)
		(width 0.14732)
		(layer "In15.Cu")
		(net "P5E_CPU0_PE2_TX_DP<12>")
	)
	(segment
		(start 379.472698 -224.118424)
		(end 379.561598 -224.094802)
		(width 0.0889)
		(layer "In15.Cu")
		(net "P5E_CPU0_PE2_TX_DP<12>")
	)
	(segment
		(start 380.90729 -400.113246)
		(end 380.90729 -400.563588)
		(width 0.14732)
		(layer "In15.Cu")
		(net "P5E_CPU0_PE2_TX_DP<12>")
	)
	(segment
		(start 381.111506 -399.418048)
		(end 380.90729 -400.113246)
		(width 0.14732)
		(layer "In15.Cu")
		(net "P5E_CPU0_PE2_TX_DP<12>")
	)
	(segment
		(start 396.149322 -339.367114)
		(end 393.73683 -354.194364)
		(width 0.14732)
		(layer "In15.Cu")
		(net "P5E_CPU0_PE2_TX_DP<12>")
	)
	(segment
		(start 390.18464 -230.525066)
		(end 391.174478 -244.452902)
		(width 0.14732)
		(layer "In15.Cu")
		(net "P5E_CPU0_PE2_TX_DP<12>")
	)
	(segment
		(start 380.068836 -224.065084)
		(end 380.074932 -224.061528)
		(width 0.0889)
		(layer "In15.Cu")
		(net "P5E_CPU0_PE2_TX_DP<12>")
	)
	(segment
		(start 381.69596 -396.915386)
		(end 381.592074 -397.268954)
		(width 0.14732)
		(layer "In15.Cu")
		(net "P5E_CPU0_PE2_TX_DP<12>")
	)
	(segment
		(start 386.985764 -223.726248)
		(end 387.201156 -223.94164)
		(width 0.14732)
		(layer "In15.Cu")
		(net "P5E_CPU0_PE2_TX_DP<12>")
	)
	(segment
		(start 389.63346 -228.442266)
		(end 390.18464 -230.525066)
		(width 0.14732)
		(layer "In15.Cu")
		(net "P5E_CPU0_PE2_TX_DP<12>")
	)
	(segment
		(start 381.586486 -397.801846)
		(end 381.406654 -397.900144)
		(width 0.14732)
		(layer "In15.Cu")
		(net "P5E_CPU0_PE2_TX_DP<12>")
	)
	(segment
		(start 387.201156 -223.94164)
		(end 389.63346 -228.442266)
		(width 0.14732)
		(layer "In15.Cu")
		(net "P5E_CPU0_PE2_TX_DP<12>")
	)
	(segment
		(start 386.977636 -223.658176)
		(end 386.977636 -223.71812)
		(width 0.0889)
		(layer "In15.Cu")
		(net "P5E_CPU0_PE2_TX_DP<12>")
	)
	(segment
		(start 380.90729 -400.563588)
		(end 380.61265 -400.858228)
		(width 0.14732)
		(layer "In15.Cu")
		(net "P5E_CPU0_PE2_TX_DP<12>")
	)
	(segment
		(start 389.13689 -310.033162)
		(end 396.149322 -339.367114)
		(width 0.14732)
		(layer "In15.Cu")
		(net "P5E_CPU0_PE2_TX_DP<12>")
	)
	(segment
		(start 391.174478 -244.452902)
		(end 389.757158 -248.802144)
		(width 0.14732)
		(layer "In15.Cu")
		(net "P5E_CPU0_PE2_TX_DP<12>")
	)
	(segment
		(start 382.322832 -222.437198)
		(end 382.337564 -222.445834)
		(width 0.0889)
		(layer "In15.Cu")
		(net "P5E_CPU0_PE2_TX_DP<12>")
	)
	(segment
		(start 385.32943 -222.761556)
		(end 385.32943 -222.769176)
		(width 0.0889)
		(layer "In15.Cu")
		(net "P5E_CPU0_PE2_TX_DP<12>")
	)
	(segment
		(start 389.225028 -252.137418)
		(end 389.50265 -253.08941)
		(width 0.14732)
		(layer "In15.Cu")
		(net "P5E_CPU0_PE2_TX_DP<12>")
	)
	(segment
		(start 389.225028 -250.44146)
		(end 389.225028 -252.137418)
		(width 0.14732)
		(layer "In15.Cu")
		(net "P5E_CPU0_PE2_TX_DP<12>")
	)
	(segment
		(start 385.141978 -222.437198)
		(end 385.142994 -222.437706)
		(width 0.0889)
		(layer "In15.Cu")
		(net "P5E_CPU0_PE2_TX_DP<12>")
	)
	(segment
		(start 381.117348 -398.884648)
		(end 381.013462 -399.238216)
		(width 0.14732)
		(layer "In15.Cu")
		(net "P5E_CPU0_PE2_TX_DP<12>")
	)
	(segment
		(start 385.142994 -222.437706)
		(end 385.150868 -222.442278)
		(width 0.0889)
		(layer "In15.Cu")
		(net "P5E_CPU0_PE2_TX_DP<12>")
	)
	(segment
		(start 389.573516 -253.29134)
		(end 390.148318 -254.67818)
		(width 0.14732)
		(layer "In15.Cu")
		(net "P5E_CPU0_PE2_TX_DP<12>")
	)
	(segment
		(start 389.50265 -253.08941)
		(end 389.573516 -253.29134)
		(width 0.14732)
		(layer "In15.Cu")
		(net "P5E_CPU0_PE2_TX_DP<12>")
	)
	(segment
		(start 381.400812 -398.43329)
		(end 381.29718 -398.786604)
		(width 0.14732)
		(layer "In15.Cu")
		(net "P5E_CPU0_PE2_TX_DP<12>")
	)
	(segment
		(start 393.73683 -354.194364)
		(end 393.736068 -354.199952)
		(width 0.14732)
		(layer "In15.Cu")
		(net "P5E_CPU0_PE2_TX_DP<12>")
	)
	(segment
		(start 389.757158 -248.802144)
		(end 389.432292 -249.266456)
		(width 0.14732)
		(layer "In15.Cu")
		(net "P5E_CPU0_PE2_TX_DP<12>")
	)
	(segment
		(start 381.302768 -398.253712)
		(end 381.400812 -398.43329)
		(width 0.14732)
		(layer "In15.Cu")
		(net "P5E_CPU0_PE2_TX_DP<12>")
	)
	(segment
		(start 384.202432 -222.437198)
		(end 384.212846 -222.443294)
		(width 0.0889)
		(layer "In15.Cu")
		(net "P5E_CPU0_PE2_TX_DP<12>")
	)
	(segment
		(start 386.62991 -223.31045)
		(end 386.977636 -223.658176)
		(width 0.0889)
		(layer "In15.Cu")
		(net "P5E_CPU0_PE2_TX_DP<12>")
	)
	(segment
		(start 390.148318 -254.67818)
		(end 391.269728 -256.280158)
		(width 0.14732)
		(layer "In15.Cu")
		(net "P5E_CPU0_PE2_TX_DP<12>")
	)
	(segment
		(start 381.592074 -397.268954)
		(end 381.690118 -397.448532)
		(width 0.14732)
		(layer "In15.Cu")
		(net "P5E_CPU0_PE2_TX_DP<12>")
	)
	(segment
		(start 380.821184 -222.780098)
		(end 380.821184 -222.761556)
		(width 0.0889)
		(layer "In15.Cu")
		(net "P5E_CPU0_PE2_TX_DP<12>")
	)
	(segment
		(start 380.999746 -222.442278)
		(end 381.008636 -222.437198)
		(width 0.0889)
		(layer "In15.Cu")
		(net "P5E_CPU0_PE2_TX_DP<12>")
	)
	(arc
		(start 381.008636 -222.437198)
		(mid 381.195834 -222.387055)
		(end 381.383032 -222.437198)
		(width 0.0889)
		(layer "In15.Cu")
		(net "P5E_CPU0_PE2_TX_DP<12>")
	)
	(arc
		(start 385.32943 -222.769176)
		(mid 385.407059 -223.047589)
		(end 385.612132 -223.251268)
		(width 0.0889)
		(layer "In15.Cu")
		(net "P5E_CPU0_PE2_TX_DP<12>")
	)
	(arc
		(start 383.828036 -222.437198)
		(mid 384.015234 -222.387055)
		(end 384.202432 -222.437198)
		(width 0.0889)
		(layer "In15.Cu")
		(net "P5E_CPU0_PE2_TX_DP<12>")
	)
	(arc
		(start 381.383032 -222.437198)
		(mid 381.665734 -222.512974)
		(end 381.948436 -222.437198)
		(width 0.0889)
		(layer "In15.Cu")
		(net "P5E_CPU0_PE2_TX_DP<12>")
	)
	(arc
		(start 386.177536 -223.251268)
		(mid 386.364734 -223.201125)
		(end 386.551932 -223.251268)
		(width 0.0889)
		(layer "In15.Cu")
		(net "P5E_CPU0_PE2_TX_DP<12>")
	)
	(arc
		(start 384.767582 -222.437198)
		(mid 384.95478 -222.387055)
		(end 385.141978 -222.437198)
		(width 0.0889)
		(layer "In15.Cu")
		(net "P5E_CPU0_PE2_TX_DP<12>")
	)
	(arc
		(start 386.551932 -223.251268)
		(mid 386.592862 -223.278301)
		(end 386.62991 -223.31045)
		(width 0.0889)
		(layer "In15.Cu")
		(net "P5E_CPU0_PE2_TX_DP<12>")
	)
	(arc
		(start 380.538736 -223.251268)
		(mid 380.741022 -223.052287)
		(end 380.821184 -222.780098)
		(width 0.0889)
		(layer "In15.Cu")
		(net "P5E_CPU0_PE2_TX_DP<12>")
	)
	(arc
		(start 379.561598 -224.094802)
		(mid 379.571465 -224.098961)
		(end 379.58141 -224.10293)
		(width 0.0889)
		(layer "In15.Cu")
		(net "P5E_CPU0_PE2_TX_DP<12>")
	)
	(arc
		(start 385.612132 -223.251268)
		(mid 385.894834 -223.32701)
		(end 386.177536 -223.251268)
		(width 0.0889)
		(layer "In15.Cu")
		(net "P5E_CPU0_PE2_TX_DP<12>")
	)
	(arc
		(start 382.337564 -222.445834)
		(mid 382.614039 -222.513154)
		(end 382.888236 -222.437198)
		(width 0.0889)
		(layer "In15.Cu")
		(net "P5E_CPU0_PE2_TX_DP<12>")
	)
	(arc
		(start 381.948436 -222.437198)
		(mid 382.135634 -222.387055)
		(end 382.322832 -222.437198)
		(width 0.0889)
		(layer "In15.Cu")
		(net "P5E_CPU0_PE2_TX_DP<12>")
	)
	(arc
		(start 382.888236 -222.437198)
		(mid 383.075434 -222.387055)
		(end 383.262632 -222.437198)
		(width 0.0889)
		(layer "In15.Cu")
		(net "P5E_CPU0_PE2_TX_DP<12>")
	)
	(arc
		(start 379.58141 -224.10293)
		(mid 379.829421 -224.139395)
		(end 380.068836 -224.065084)
		(width 0.0889)
		(layer "In15.Cu")
		(net "P5E_CPU0_PE2_TX_DP<12>")
	)
	(arc
		(start 384.212846 -222.443294)
		(mid 384.491024 -222.513017)
		(end 384.767582 -222.437198)
		(width 0.0889)
		(layer "In15.Cu")
		(net "P5E_CPU0_PE2_TX_DP<12>")
	)
	(arc
		(start 380.351284 -223.575626)
		(mid 380.398963 -223.392726)
		(end 380.529846 -223.256348)
		(width 0.0889)
		(layer "In15.Cu")
		(net "P5E_CPU0_PE2_TX_DP<12>")
	)
	(arc
		(start 383.262632 -222.437198)
		(mid 383.545334 -222.512974)
		(end 383.828036 -222.437198)
		(width 0.0889)
		(layer "In15.Cu")
		(net "P5E_CPU0_PE2_TX_DP<12>")
	)
	(arc
		(start 380.074932 -224.061528)
		(mid 380.277345 -223.855115)
		(end 380.351284 -223.575626)
		(width 0.0889)
		(layer "In15.Cu")
		(net "P5E_CPU0_PE2_TX_DP<12>")
	)
	(arc
		(start 380.821184 -222.761556)
		(mid 380.868863 -222.578656)
		(end 380.999746 -222.442278)
		(width 0.0889)
		(layer "In15.Cu")
		(net "P5E_CPU0_PE2_TX_DP<12>")
	)
	(arc
		(start 385.150868 -222.442278)
		(mid 385.281782 -222.578638)
		(end 385.32943 -222.761556)
		(width 0.0889)
		(layer "In15.Cu")
		(net "P5E_CPU0_PE2_TX_DP<12>")
	)
	(segment
		(start 383.655062 -402.104352)
		(end 383.65049 -402.104352)
		(width 0.13208)
		(layer "F.Cu")
		(net "P5E_CPU0_PE2_TX_DP<11>")
	)
	(segment
		(start 383.67589 -400.858228)
		(end 383.981452 -401.16379)
		(width 0.13208)
		(layer "F.Cu")
		(net "P5E_CPU0_PE2_TX_DP<11>")
	)
	(segment
		(start 378.846334 -225.203512)
		(end 378.84608 -225.203258)
		(width 0.13208)
		(layer "F.Cu")
		(net "P5E_CPU0_PE2_TX_DP<11>")
	)
	(segment
		(start 383.981452 -401.16379)
		(end 383.981452 -401.777962)
		(width 0.13208)
		(layer "F.Cu")
		(net "P5E_CPU0_PE2_TX_DP<11>")
	)
	(segment
		(start 378.846334 -225.739198)
		(end 378.846334 -225.203512)
		(width 0.13208)
		(layer "F.Cu")
		(net "P5E_CPU0_PE2_TX_DP<11>")
	)
	(segment
		(start 383.981452 -401.777962)
		(end 383.655062 -402.104352)
		(width 0.13208)
		(layer "F.Cu")
		(net "P5E_CPU0_PE2_TX_DP<11>")
	)
	(segment
		(start 392.371072 -256.06883)
		(end 393.062714 -259.19303)
		(width 0.14732)
		(layer "In15.Cu")
		(net "P5E_CPU0_PE2_TX_DP<11>")
	)
	(segment
		(start 379.881384 -222.77578)
		(end 379.881384 -222.761556)
		(width 0.0889)
		(layer "In15.Cu")
		(net "P5E_CPU0_PE2_TX_DP<11>")
	)
	(segment
		(start 380.536958 -221.624144)
		(end 380.538482 -221.623382)
		(width 0.0889)
		(layer "In15.Cu")
		(net "P5E_CPU0_PE2_TX_DP<11>")
	)
	(segment
		(start 384.247136 -398.381474)
		(end 384.338068 -398.528032)
		(width 0.14732)
		(layer "In15.Cu")
		(net "P5E_CPU0_PE2_TX_DP<11>")
	)
	(segment
		(start 394.646658 -354.462588)
		(end 385.002532 -395.688058)
		(width 0.14732)
		(layer "In15.Cu")
		(net "P5E_CPU0_PE2_TX_DP<11>")
	)
	(segment
		(start 384.08356 -399.616422)
		(end 383.984246 -400.041618)
		(width 0.14732)
		(layer "In15.Cu")
		(net "P5E_CPU0_PE2_TX_DP<11>")
	)
	(segment
		(start 384.672332 -219.995496)
		(end 384.673856 -219.996258)
		(width 0.0889)
		(layer "In15.Cu")
		(net "P5E_CPU0_PE2_TX_DP<11>")
	)
	(segment
		(start 386.082032 -220.809566)
		(end 386.090922 -220.814646)
		(width 0.0889)
		(layer "In15.Cu")
		(net "P5E_CPU0_PE2_TX_DP<11>")
	)
	(segment
		(start 390.624822 -249.184414)
		(end 390.439402 -249.44959)
		(width 0.14732)
		(layer "In15.Cu")
		(net "P5E_CPU0_PE2_TX_DP<11>")
	)
	(segment
		(start 384.338068 -398.528032)
		(end 384.238754 -398.953228)
		(width 0.14732)
		(layer "In15.Cu")
		(net "P5E_CPU0_PE2_TX_DP<11>")
	)
	(segment
		(start 380.999746 -220.814646)
		(end 381.008636 -220.809566)
		(width 0.0889)
		(layer "In15.Cu")
		(net "P5E_CPU0_PE2_TX_DP<11>")
	)
	(segment
		(start 383.984246 -400.041618)
		(end 383.984246 -400.549872)
		(width 0.14732)
		(layer "In15.Cu")
		(net "P5E_CPU0_PE2_TX_DP<11>")
	)
	(segment
		(start 390.096756 -309.94985)
		(end 397.18742 -339.399118)
		(width 0.14732)
		(layer "In15.Cu")
		(net "P5E_CPU0_PE2_TX_DP<11>")
	)
	(segment
		(start 378.84608 -225.203258)
		(end 378.689616 -224.93224)
		(width 0.0889)
		(layer "In15.Cu")
		(net "P5E_CPU0_PE2_TX_DP<11>")
	)
	(segment
		(start 386.62991 -221.682564)
		(end 386.62991 -221.682818)
		(width 0.0889)
		(layer "In15.Cu")
		(net "P5E_CPU0_PE2_TX_DP<11>")
	)
	(segment
		(start 386.269484 -221.133924)
		(end 386.269484 -221.14383)
		(width 0.0889)
		(layer "In15.Cu")
		(net "P5E_CPU0_PE2_TX_DP<11>")
	)
	(segment
		(start 384.501644 -397.293084)
		(end 384.592576 -397.439642)
		(width 0.14732)
		(layer "In15.Cu")
		(net "P5E_CPU0_PE2_TX_DP<11>")
	)
	(segment
		(start 387.380226 -222.43288)
		(end 387.476492 -222.529146)
		(width 0.0889)
		(layer "In15.Cu")
		(net "P5E_CPU0_PE2_TX_DP<11>")
	)
	(segment
		(start 384.092196 -399.04416)
		(end 383.992628 -399.469864)
		(width 0.14732)
		(layer "In15.Cu")
		(net "P5E_CPU0_PE2_TX_DP<11>")
	)
	(segment
		(start 382.407668 -220.001592)
		(end 382.418082 -219.995496)
		(width 0.0889)
		(layer "In15.Cu")
		(net "P5E_CPU0_PE2_TX_DP<11>")
	)
	(segment
		(start 393.06246 -259.19303)
		(end 390.096756 -309.94985)
		(width 0.14732)
		(layer "In15.Cu")
		(net "P5E_CPU0_PE2_TX_DP<11>")
	)
	(segment
		(start 390.353296 -252.661166)
		(end 390.457182 -252.994668)
		(width 0.14732)
		(layer "In15.Cu")
		(net "P5E_CPU0_PE2_TX_DP<11>")
	)
	(segment
		(start 384.592576 -397.439642)
		(end 384.493262 -397.864838)
		(width 0.14732)
		(layer "In15.Cu")
		(net "P5E_CPU0_PE2_TX_DP<11>")
	)
	(segment
		(start 390.241028 -252.300232)
		(end 390.353296 -252.661166)
		(width 0.14732)
		(layer "In15.Cu")
		(net "P5E_CPU0_PE2_TX_DP<11>")
	)
	(segment
		(start 378.689616 -224.93224)
		(end 378.713746 -224.843086)
		(width 0.0889)
		(layer "In15.Cu")
		(net "P5E_CPU0_PE2_TX_DP<11>")
	)
	(segment
		(start 384.493262 -397.864838)
		(end 384.493516 -397.864838)
		(width 0.14732)
		(layer "In15.Cu")
		(net "P5E_CPU0_PE2_TX_DP<11>")
	)
	(segment
		(start 391.174732 -230.621078)
		(end 392.134598 -244.545104)
		(width 0.14732)
		(layer "In15.Cu")
		(net "P5E_CPU0_PE2_TX_DP<11>")
	)
	(segment
		(start 384.601212 -396.86738)
		(end 384.501644 -397.293084)
		(width 0.14732)
		(layer "In15.Cu")
		(net "P5E_CPU0_PE2_TX_DP<11>")
	)
	(segment
		(start 381.469646 -220.000576)
		(end 381.478536 -219.995496)
		(width 0.0889)
		(layer "In15.Cu")
		(net "P5E_CPU0_PE2_TX_DP<11>")
	)
	(segment
		(start 384.859784 -220.319854)
		(end 384.859784 -220.338396)
		(width 0.0889)
		(layer "In15.Cu")
		(net "P5E_CPU0_PE2_TX_DP<11>")
	)
	(segment
		(start 380.538482 -221.623382)
		(end 380.539244 -221.622874)
		(width 0.0889)
		(layer "In15.Cu")
		(net "P5E_CPU0_PE2_TX_DP<11>")
	)
	(segment
		(start 390.241028 -250.57481)
		(end 390.241028 -252.300232)
		(width 0.14732)
		(layer "In15.Cu")
		(net "P5E_CPU0_PE2_TX_DP<11>")
	)
	(segment
		(start 390.439402 -249.44959)
		(end 390.241028 -250.57481)
		(width 0.14732)
		(layer "In15.Cu")
		(net "P5E_CPU0_PE2_TX_DP<11>")
	)
	(segment
		(start 387.476492 -222.529146)
		(end 387.476492 -222.588074)
		(width 0.0889)
		(layer "In15.Cu")
		(net "P5E_CPU0_PE2_TX_DP<11>")
	)
	(segment
		(start 380.539244 -221.622874)
		(end 380.544578 -221.619826)
		(width 0.0889)
		(layer "In15.Cu")
		(net "P5E_CPU0_PE2_TX_DP<11>")
	)
	(segment
		(start 387.476492 -222.588074)
		(end 387.491986 -222.603568)
		(width 0.0889)
		(layer "In15.Cu")
		(net "P5E_CPU0_PE2_TX_DP<11>")
	)
	(segment
		(start 392.134598 -244.545104)
		(end 390.624822 -249.184414)
		(width 0.14732)
		(layer "In15.Cu")
		(net "P5E_CPU0_PE2_TX_DP<11>")
	)
	(segment
		(start 390.803638 -253.830074)
		(end 392.371072 -256.06883)
		(width 0.14732)
		(layer "In15.Cu")
		(net "P5E_CPU0_PE2_TX_DP<11>")
	)
	(segment
		(start 384.493516 -397.864838)
		(end 384.346704 -397.95577)
		(width 0.14732)
		(layer "In15.Cu")
		(net "P5E_CPU0_PE2_TX_DP<11>")
	)
	(segment
		(start 390.457182 -252.994668)
		(end 390.803638 -253.830074)
		(width 0.14732)
		(layer "In15.Cu")
		(net "P5E_CPU0_PE2_TX_DP<11>")
	)
	(segment
		(start 387.829044 -222.940626)
		(end 390.23163 -227.029264)
		(width 0.14732)
		(layer "In15.Cu")
		(net "P5E_CPU0_PE2_TX_DP<11>")
	)
	(segment
		(start 384.239008 -398.953228)
		(end 384.092196 -399.04416)
		(width 0.14732)
		(layer "In15.Cu")
		(net "P5E_CPU0_PE2_TX_DP<11>")
	)
	(segment
		(start 383.984246 -400.549872)
		(end 383.67589 -400.858228)
		(width 0.14732)
		(layer "In15.Cu")
		(net "P5E_CPU0_PE2_TX_DP<11>")
	)
	(segment
		(start 384.748024 -396.776448)
		(end 384.601212 -396.86738)
		(width 0.14732)
		(layer "In15.Cu")
		(net "P5E_CPU0_PE2_TX_DP<11>")
	)
	(segment
		(start 385.002786 -395.688058)
		(end 384.855974 -395.77899)
		(width 0.14732)
		(layer "In15.Cu")
		(net "P5E_CPU0_PE2_TX_DP<11>")
	)
	(segment
		(start 380.059946 -222.442278)
		(end 380.068836 -222.437198)
		(width 0.0889)
		(layer "In15.Cu")
		(net "P5E_CPU0_PE2_TX_DP<11>")
	)
	(segment
		(start 383.347722 -220.001592)
		(end 383.358136 -219.995496)
		(width 0.0889)
		(layer "In15.Cu")
		(net "P5E_CPU0_PE2_TX_DP<11>")
	)
	(segment
		(start 384.673856 -219.996258)
		(end 384.681222 -220.000576)
		(width 0.0889)
		(layer "In15.Cu")
		(net "P5E_CPU0_PE2_TX_DP<11>")
	)
	(segment
		(start 380.529592 -221.628462)
		(end 380.536958 -221.624144)
		(width 0.0889)
		(layer "In15.Cu")
		(net "P5E_CPU0_PE2_TX_DP<11>")
	)
	(segment
		(start 385.002532 -395.688058)
		(end 385.002786 -395.688058)
		(width 0.14732)
		(layer "In15.Cu")
		(net "P5E_CPU0_PE2_TX_DP<11>")
	)
	(segment
		(start 387.491986 -222.603568)
		(end 387.829044 -222.940626)
		(width 0.14732)
		(layer "In15.Cu")
		(net "P5E_CPU0_PE2_TX_DP<11>")
	)
	(segment
		(start 384.346704 -397.95577)
		(end 384.247136 -398.381474)
		(width 0.14732)
		(layer "In15.Cu")
		(net "P5E_CPU0_PE2_TX_DP<11>")
	)
	(segment
		(start 390.23163 -227.029264)
		(end 390.43737 -227.753164)
		(width 0.14732)
		(layer "In15.Cu")
		(net "P5E_CPU0_PE2_TX_DP<11>")
	)
	(segment
		(start 397.18742 -339.399118)
		(end 394.646658 -354.462588)
		(width 0.14732)
		(layer "In15.Cu")
		(net "P5E_CPU0_PE2_TX_DP<11>")
	)
	(segment
		(start 379.411484 -223.585532)
		(end 379.411484 -223.56699)
		(width 0.0889)
		(layer "In15.Cu")
		(net "P5E_CPU0_PE2_TX_DP<11>")
	)
	(segment
		(start 383.992628 -399.469864)
		(end 384.08356 -399.616422)
		(width 0.14732)
		(layer "In15.Cu")
		(net "P5E_CPU0_PE2_TX_DP<11>")
	)
	(segment
		(start 384.847338 -396.351252)
		(end 384.748024 -396.776448)
		(width 0.14732)
		(layer "In15.Cu")
		(net "P5E_CPU0_PE2_TX_DP<11>")
	)
	(segment
		(start 380.35103 -221.963234)
		(end 380.35103 -221.94774)
		(width 0.0889)
		(layer "In15.Cu")
		(net "P5E_CPU0_PE2_TX_DP<11>")
	)
	(segment
		(start 381.291084 -220.338396)
		(end 381.291084 -220.319854)
		(width 0.0889)
		(layer "In15.Cu")
		(net "P5E_CPU0_PE2_TX_DP<11>")
	)
	(segment
		(start 379.120146 -224.070164)
		(end 379.129036 -224.065084)
		(width 0.0889)
		(layer "In15.Cu")
		(net "P5E_CPU0_PE2_TX_DP<11>")
	)
	(segment
		(start 384.238754 -398.953228)
		(end 384.239008 -398.953228)
		(width 0.14732)
		(layer "In15.Cu")
		(net "P5E_CPU0_PE2_TX_DP<11>")
	)
	(segment
		(start 386.62991 -221.682818)
		(end 387.380226 -222.43288)
		(width 0.0889)
		(layer "In15.Cu")
		(net "P5E_CPU0_PE2_TX_DP<11>")
	)
	(segment
		(start 390.43737 -227.753164)
		(end 391.174732 -230.621078)
		(width 0.14732)
		(layer "In15.Cu")
		(net "P5E_CPU0_PE2_TX_DP<11>")
	)
	(segment
		(start 384.855974 -395.77899)
		(end 384.756406 -396.204694)
		(width 0.14732)
		(layer "In15.Cu")
		(net "P5E_CPU0_PE2_TX_DP<11>")
	)
	(segment
		(start 393.062714 -259.19303)
		(end 393.06246 -259.19303)
		(width 0.14732)
		(layer "In15.Cu")
		(net "P5E_CPU0_PE2_TX_DP<11>")
	)
	(segment
		(start 384.756406 -396.204694)
		(end 384.847338 -396.351252)
		(width 0.14732)
		(layer "In15.Cu")
		(net "P5E_CPU0_PE2_TX_DP<11>")
	)
	(arc
		(start 379.129036 -224.065084)
		(mid 379.333371 -223.862479)
		(end 379.411484 -223.585532)
		(width 0.0889)
		(layer "In15.Cu")
		(net "P5E_CPU0_PE2_TX_DP<11>")
	)
	(arc
		(start 378.941584 -224.389442)
		(mid 378.989263 -224.206542)
		(end 379.120146 -224.070164)
		(width 0.0889)
		(layer "In15.Cu")
		(net "P5E_CPU0_PE2_TX_DP<11>")
	)
	(arc
		(start 379.598682 -223.251268)
		(mid 379.802163 -223.050464)
		(end 379.881384 -222.77578)
		(width 0.0889)
		(layer "In15.Cu")
		(net "P5E_CPU0_PE2_TX_DP<11>")
	)
	(arc
		(start 384.297936 -219.995496)
		(mid 384.485134 -219.945353)
		(end 384.672332 -219.995496)
		(width 0.0889)
		(layer "In15.Cu")
		(net "P5E_CPU0_PE2_TX_DP<11>")
	)
	(arc
		(start 382.792478 -219.995496)
		(mid 383.069291 -220.071366)
		(end 383.347722 -220.001592)
		(width 0.0889)
		(layer "In15.Cu")
		(net "P5E_CPU0_PE2_TX_DP<11>")
	)
	(arc
		(start 383.358136 -219.995496)
		(mid 383.545334 -219.945353)
		(end 383.732532 -219.995496)
		(width 0.0889)
		(layer "In15.Cu")
		(net "P5E_CPU0_PE2_TX_DP<11>")
	)
	(arc
		(start 378.713746 -224.843086)
		(mid 378.722318 -224.836564)
		(end 378.730764 -224.829878)
		(width 0.0889)
		(layer "In15.Cu")
		(net "P5E_CPU0_PE2_TX_DP<11>")
	)
	(arc
		(start 380.821184 -221.133924)
		(mid 380.868863 -220.951024)
		(end 380.999746 -220.814646)
		(width 0.0889)
		(layer "In15.Cu")
		(net "P5E_CPU0_PE2_TX_DP<11>")
	)
	(arc
		(start 381.478536 -219.995496)
		(mid 381.665734 -219.945353)
		(end 381.852932 -219.995496)
		(width 0.0889)
		(layer "In15.Cu")
		(net "P5E_CPU0_PE2_TX_DP<11>")
	)
	(arc
		(start 385.142232 -220.809566)
		(mid 385.424934 -220.885308)
		(end 385.707636 -220.809566)
		(width 0.0889)
		(layer "In15.Cu")
		(net "P5E_CPU0_PE2_TX_DP<11>")
	)
	(arc
		(start 380.544578 -221.619826)
		(mid 380.747165 -221.413475)
		(end 380.821184 -221.133924)
		(width 0.0889)
		(layer "In15.Cu")
		(net "P5E_CPU0_PE2_TX_DP<11>")
	)
	(arc
		(start 380.068836 -222.437198)
		(mid 380.271659 -222.236967)
		(end 380.35103 -221.963234)
		(width 0.0889)
		(layer "In15.Cu")
		(net "P5E_CPU0_PE2_TX_DP<11>")
	)
	(arc
		(start 384.681222 -220.000576)
		(mid 384.812136 -220.136936)
		(end 384.859784 -220.319854)
		(width 0.0889)
		(layer "In15.Cu")
		(net "P5E_CPU0_PE2_TX_DP<11>")
	)
	(arc
		(start 382.418082 -219.995496)
		(mid 382.60528 -219.945353)
		(end 382.792478 -219.995496)
		(width 0.0889)
		(layer "In15.Cu")
		(net "P5E_CPU0_PE2_TX_DP<11>")
	)
	(arc
		(start 386.269484 -221.14383)
		(mid 386.347595 -221.420779)
		(end 386.551932 -221.623382)
		(width 0.0889)
		(layer "In15.Cu")
		(net "P5E_CPU0_PE2_TX_DP<11>")
	)
	(arc
		(start 381.852932 -219.995496)
		(mid 382.129491 -220.071239)
		(end 382.407668 -220.001592)
		(width 0.0889)
		(layer "In15.Cu")
		(net "P5E_CPU0_PE2_TX_DP<11>")
	)
	(arc
		(start 378.730764 -224.829878)
		(mid 378.886162 -224.633597)
		(end 378.941584 -224.389442)
		(width 0.0889)
		(layer "In15.Cu")
		(net "P5E_CPU0_PE2_TX_DP<11>")
	)
	(arc
		(start 384.859784 -220.338396)
		(mid 384.939946 -220.610585)
		(end 385.142232 -220.809566)
		(width 0.0889)
		(layer "In15.Cu")
		(net "P5E_CPU0_PE2_TX_DP<11>")
	)
	(arc
		(start 383.732532 -219.995496)
		(mid 384.015234 -220.071272)
		(end 384.297936 -219.995496)
		(width 0.0889)
		(layer "In15.Cu")
		(net "P5E_CPU0_PE2_TX_DP<11>")
	)
	(arc
		(start 379.411484 -223.56699)
		(mid 379.463754 -223.384625)
		(end 379.598682 -223.251268)
		(width 0.0889)
		(layer "In15.Cu")
		(net "P5E_CPU0_PE2_TX_DP<11>")
	)
	(arc
		(start 380.35103 -221.94774)
		(mid 380.398709 -221.76484)
		(end 380.529592 -221.628462)
		(width 0.0889)
		(layer "In15.Cu")
		(net "P5E_CPU0_PE2_TX_DP<11>")
	)
	(arc
		(start 385.707636 -220.809566)
		(mid 385.894834 -220.759423)
		(end 386.082032 -220.809566)
		(width 0.0889)
		(layer "In15.Cu")
		(net "P5E_CPU0_PE2_TX_DP<11>")
	)
	(arc
		(start 386.551932 -221.623382)
		(mid 386.592862 -221.650415)
		(end 386.62991 -221.682564)
		(width 0.0889)
		(layer "In15.Cu")
		(net "P5E_CPU0_PE2_TX_DP<11>")
	)
	(arc
		(start 379.881384 -222.761556)
		(mid 379.929063 -222.578656)
		(end 380.059946 -222.442278)
		(width 0.0889)
		(layer "In15.Cu")
		(net "P5E_CPU0_PE2_TX_DP<11>")
	)
	(arc
		(start 386.090922 -220.814646)
		(mid 386.221836 -220.951006)
		(end 386.269484 -221.133924)
		(width 0.0889)
		(layer "In15.Cu")
		(net "P5E_CPU0_PE2_TX_DP<11>")
	)
	(arc
		(start 381.291084 -220.319854)
		(mid 381.338763 -220.136954)
		(end 381.469646 -220.000576)
		(width 0.0889)
		(layer "In15.Cu")
		(net "P5E_CPU0_PE2_TX_DP<11>")
	)
	(arc
		(start 381.008636 -220.809566)
		(mid 381.210922 -220.610585)
		(end 381.291084 -220.338396)
		(width 0.0889)
		(layer "In15.Cu")
		(net "P5E_CPU0_PE2_TX_DP<11>")
	)
	(segment
		(start 386.73913 -400.858228)
		(end 387.044692 -401.16379)
		(width 0.13208)
		(layer "F.Cu")
		(net "P5E_CPU0_PE2_TX_DP<10>")
	)
	(segment
		(start 377.43638 -224.389696)
		(end 377.436634 -224.389442)
		(width 0.13208)
		(layer "F.Cu")
		(net "P5E_CPU0_PE2_TX_DP<10>")
	)
	(segment
		(start 377.43638 -224.925382)
		(end 377.43638 -224.389696)
		(width 0.13208)
		(layer "F.Cu")
		(net "P5E_CPU0_PE2_TX_DP<10>")
	)
	(segment
		(start 386.718302 -402.104352)
		(end 386.71373 -402.104352)
		(width 0.13208)
		(layer "F.Cu")
		(net "P5E_CPU0_PE2_TX_DP<10>")
	)
	(segment
		(start 387.044692 -401.16379)
		(end 387.044692 -401.777962)
		(width 0.13208)
		(layer "F.Cu")
		(net "P5E_CPU0_PE2_TX_DP<10>")
	)
	(segment
		(start 387.044692 -401.777962)
		(end 386.718302 -402.104352)
		(width 0.13208)
		(layer "F.Cu")
		(net "P5E_CPU0_PE2_TX_DP<10>")
	)
	(segment
		(start 379.59792 -221.62389)
		(end 379.600206 -221.622366)
		(width 0.0889)
		(layer "In15.Cu")
		(net "P5E_CPU0_PE2_TX_DP<10>")
	)
	(segment
		(start 391.180828 -251.128022)
		(end 391.180828 -252.157992)
		(width 0.14732)
		(layer "In15.Cu")
		(net "P5E_CPU0_PE2_TX_DP<10>")
	)
	(segment
		(start 390.324848 -223.810068)
		(end 391.399014 -227.531168)
		(width 0.14732)
		(layer "In15.Cu")
		(net "P5E_CPU0_PE2_TX_DP<10>")
	)
	(segment
		(start 392.124184 -230.424482)
		(end 393.087352 -244.737382)
		(width 0.14732)
		(layer "In15.Cu")
		(net "P5E_CPU0_PE2_TX_DP<10>")
	)
	(segment
		(start 386.629656 -220.054932)
		(end 386.893562 -220.318838)
		(width 0.0889)
		(layer "In15.Cu")
		(net "P5E_CPU0_PE2_TX_DP<10>")
	)
	(segment
		(start 379.600206 -221.622366)
		(end 379.601476 -221.621604)
		(width 0.0889)
		(layer "In15.Cu")
		(net "P5E_CPU0_PE2_TX_DP<10>")
	)
	(segment
		(start 379.881384 -221.133924)
		(end 379.881384 -221.1197)
		(width 0.0889)
		(layer "In15.Cu")
		(net "P5E_CPU0_PE2_TX_DP<10>")
	)
	(segment
		(start 378.941584 -222.780098)
		(end 378.941584 -222.761556)
		(width 0.0889)
		(layer "In15.Cu")
		(net "P5E_CPU0_PE2_TX_DP<10>")
	)
	(segment
		(start 385.607814 -219.992956)
		(end 385.609846 -219.994226)
		(width 0.0889)
		(layer "In15.Cu")
		(net "P5E_CPU0_PE2_TX_DP<10>")
	)
	(segment
		(start 379.589792 -221.628462)
		(end 379.596904 -221.624398)
		(width 0.0889)
		(layer "In15.Cu")
		(net "P5E_CPU0_PE2_TX_DP<10>")
	)
	(segment
		(start 391.180828 -252.157992)
		(end 391.331196 -252.673866)
		(width 0.14732)
		(layer "In15.Cu")
		(net "P5E_CPU0_PE2_TX_DP<10>")
	)
	(segment
		(start 387.26237 -398.245076)
		(end 387.36016 -398.387062)
		(width 0.14732)
		(layer "In15.Cu")
		(net "P5E_CPU0_PE2_TX_DP<10>")
	)
	(segment
		(start 387.484112 -397.716502)
		(end 387.484112 -397.717518)
		(width 0.14732)
		(layer "In15.Cu")
		(net "P5E_CPU0_PE2_TX_DP<10>")
	)
	(segment
		(start 391.60958 -253.345696)
		(end 393.268454 -255.715008)
		(width 0.14732)
		(layer "In15.Cu")
		(net "P5E_CPU0_PE2_TX_DP<10>")
	)
	(segment
		(start 395.08303 -357.578914)
		(end 394.60805 -359.176828)
		(width 0.14732)
		(layer "In15.Cu")
		(net "P5E_CPU0_PE2_TX_DP<10>")
	)
	(segment
		(start 394.069062 -259.091938)
		(end 391.0584 -309.793132)
		(width 0.14732)
		(layer "In15.Cu")
		(net "P5E_CPU0_PE2_TX_DP<10>")
	)
	(segment
		(start 380.999746 -219.18676)
		(end 381.008636 -219.18168)
		(width 0.0889)
		(layer "In15.Cu")
		(net "P5E_CPU0_PE2_TX_DP<10>")
	)
	(segment
		(start 385.606036 -219.99194)
		(end 385.607814 -219.992956)
		(width 0.0889)
		(layer "In15.Cu")
		(net "P5E_CPU0_PE2_TX_DP<10>")
	)
	(segment
		(start 387.341872 -397.815308)
		(end 387.26237 -398.245076)
		(width 0.14732)
		(layer "In15.Cu")
		(net "P5E_CPU0_PE2_TX_DP<10>")
	)
	(segment
		(start 387.03377 -400.153632)
		(end 387.03377 -400.563588)
		(width 0.14732)
		(layer "In15.Cu")
		(net "P5E_CPU0_PE2_TX_DP<10>")
	)
	(segment
		(start 387.36016 -398.387062)
		(end 387.280912 -398.816576)
		(width 0.14732)
		(layer "In15.Cu")
		(net "P5E_CPU0_PE2_TX_DP<10>")
	)
	(segment
		(start 387.484112 -397.717518)
		(end 387.341872 -397.815308)
		(width 0.14732)
		(layer "In15.Cu")
		(net "P5E_CPU0_PE2_TX_DP<10>")
	)
	(segment
		(start 384.757168 -219.187776)
		(end 384.767582 -219.18168)
		(width 0.0889)
		(layer "In15.Cu")
		(net "P5E_CPU0_PE2_TX_DP<10>")
	)
	(segment
		(start 377.593098 -224.118424)
		(end 377.681998 -224.094802)
		(width 0.0889)
		(layer "In15.Cu")
		(net "P5E_CPU0_PE2_TX_DP<10>")
	)
	(segment
		(start 380.528322 -220.001592)
		(end 380.538736 -219.995496)
		(width 0.0889)
		(layer "In15.Cu")
		(net "P5E_CPU0_PE2_TX_DP<10>")
	)
	(segment
		(start 391.331196 -252.673866)
		(end 391.60958 -253.345696)
		(width 0.14732)
		(layer "In15.Cu")
		(net "P5E_CPU0_PE2_TX_DP<10>")
	)
	(segment
		(start 391.519918 -249.529092)
		(end 391.519156 -249.530108)
		(width 0.14732)
		(layer "In15.Cu")
		(net "P5E_CPU0_PE2_TX_DP<10>")
	)
	(segment
		(start 387.138672 -398.91462)
		(end 387.05917 -399.344388)
		(width 0.14732)
		(layer "In15.Cu")
		(net "P5E_CPU0_PE2_TX_DP<10>")
	)
	(segment
		(start 391.53592 -249.506232)
		(end 391.52576 -249.520964)
		(width 0.14732)
		(layer "In15.Cu")
		(net "P5E_CPU0_PE2_TX_DP<10>")
	)
	(segment
		(start 379.411484 -220.32849)
		(end 379.411484 -220.311218)
		(width 0.0889)
		(layer "In15.Cu")
		(net "P5E_CPU0_PE2_TX_DP<10>")
	)
	(segment
		(start 385.612132 -219.995496)
		(end 385.626864 -220.004132)
		(width 0.0889)
		(layer "In15.Cu")
		(net "P5E_CPU0_PE2_TX_DP<10>")
	)
	(segment
		(start 387.280912 -398.816576)
		(end 387.280912 -398.81683)
		(width 0.14732)
		(layer "In15.Cu")
		(net "P5E_CPU0_PE2_TX_DP<10>")
	)
	(segment
		(start 378.189236 -224.065084)
		(end 378.195332 -224.061528)
		(width 0.0889)
		(layer "In15.Cu")
		(net "P5E_CPU0_PE2_TX_DP<10>")
	)
	(segment
		(start 386.893562 -220.378782)
		(end 386.909056 -220.394276)
		(width 0.0889)
		(layer "In15.Cu")
		(net "P5E_CPU0_PE2_TX_DP<10>")
	)
	(segment
		(start 385.141978 -219.18168)
		(end 385.150868 -219.18676)
		(width 0.0889)
		(layer "In15.Cu")
		(net "P5E_CPU0_PE2_TX_DP<10>")
	)
	(segment
		(start 391.522458 -249.525536)
		(end 391.521696 -249.526552)
		(width 0.14732)
		(layer "In15.Cu")
		(net "P5E_CPU0_PE2_TX_DP<10>")
	)
	(segment
		(start 391.0584 -309.793132)
		(end 398.187926 -339.41385)
		(width 0.14732)
		(layer "In15.Cu")
		(net "P5E_CPU0_PE2_TX_DP<10>")
	)
	(segment
		(start 379.601476 -221.621604)
		(end 379.604778 -221.619826)
		(width 0.0889)
		(layer "In15.Cu")
		(net "P5E_CPU0_PE2_TX_DP<10>")
	)
	(segment
		(start 391.520426 -249.52833)
		(end 391.519918 -249.529092)
		(width 0.14732)
		(layer "In15.Cu")
		(net "P5E_CPU0_PE2_TX_DP<10>")
	)
	(segment
		(start 398.187926 -339.41385)
		(end 395.08303 -357.578914)
		(width 0.14732)
		(layer "In15.Cu")
		(net "P5E_CPU0_PE2_TX_DP<10>")
	)
	(segment
		(start 378.650246 -223.256348)
		(end 378.659136 -223.251268)
		(width 0.0889)
		(layer "In15.Cu")
		(net "P5E_CPU0_PE2_TX_DP<10>")
	)
	(segment
		(start 391.521696 -249.526552)
		(end 391.521188 -249.527314)
		(width 0.14732)
		(layer "In15.Cu")
		(net "P5E_CPU0_PE2_TX_DP<10>")
	)
	(segment
		(start 391.399014 -227.531168)
		(end 392.124184 -230.424482)
		(width 0.14732)
		(layer "In15.Cu")
		(net "P5E_CPU0_PE2_TX_DP<10>")
	)
	(segment
		(start 391.521188 -249.527314)
		(end 391.520426 -249.52833)
		(width 0.14732)
		(layer "In15.Cu")
		(net "P5E_CPU0_PE2_TX_DP<10>")
	)
	(segment
		(start 391.523728 -249.523758)
		(end 391.522966 -249.524774)
		(width 0.14732)
		(layer "In15.Cu")
		(net "P5E_CPU0_PE2_TX_DP<10>")
	)
	(segment
		(start 380.821184 -219.515944)
		(end 380.821184 -219.506038)
		(width 0.0889)
		(layer "In15.Cu")
		(net "P5E_CPU0_PE2_TX_DP<10>")
	)
	(segment
		(start 379.596904 -221.624398)
		(end 379.59792 -221.62389)
		(width 0.0889)
		(layer "In15.Cu")
		(net "P5E_CPU0_PE2_TX_DP<10>")
	)
	(segment
		(start 386.909056 -220.394276)
		(end 390.324848 -223.810068)
		(width 0.14732)
		(layer "In15.Cu")
		(net "P5E_CPU0_PE2_TX_DP<10>")
	)
	(segment
		(start 393.087352 -244.737382)
		(end 391.53592 -249.506232)
		(width 0.14732)
		(layer "In15.Cu")
		(net "P5E_CPU0_PE2_TX_DP<10>")
	)
	(segment
		(start 391.443972 -249.63755)
		(end 391.180828 -251.128022)
		(width 0.14732)
		(layer "In15.Cu")
		(net "P5E_CPU0_PE2_TX_DP<10>")
	)
	(segment
		(start 391.522966 -249.524774)
		(end 391.522458 -249.525536)
		(width 0.14732)
		(layer "In15.Cu")
		(net "P5E_CPU0_PE2_TX_DP<10>")
	)
	(segment
		(start 379.41123 -221.963234)
		(end 379.41123 -221.94774)
		(width 0.0889)
		(layer "In15.Cu")
		(net "P5E_CPU0_PE2_TX_DP<10>")
	)
	(segment
		(start 387.03377 -400.563588)
		(end 386.73913 -400.858228)
		(width 0.14732)
		(layer "In15.Cu")
		(net "P5E_CPU0_PE2_TX_DP<10>")
	)
	(segment
		(start 387.15696 -399.486628)
		(end 387.03377 -400.153632)
		(width 0.14732)
		(layer "In15.Cu")
		(net "P5E_CPU0_PE2_TX_DP<10>")
	)
	(segment
		(start 386.893562 -220.318838)
		(end 386.893562 -220.378782)
		(width 0.0889)
		(layer "In15.Cu")
		(net "P5E_CPU0_PE2_TX_DP<10>")
	)
	(segment
		(start 385.609846 -219.994226)
		(end 385.612132 -219.995496)
		(width 0.0889)
		(layer "In15.Cu")
		(net "P5E_CPU0_PE2_TX_DP<10>")
	)
	(segment
		(start 377.436634 -224.389442)
		(end 377.593098 -224.118424)
		(width 0.0889)
		(layer "In15.Cu")
		(net "P5E_CPU0_PE2_TX_DP<10>")
	)
	(segment
		(start 391.519156 -249.530108)
		(end 391.443972 -249.63755)
		(width 0.14732)
		(layer "In15.Cu")
		(net "P5E_CPU0_PE2_TX_DP<10>")
	)
	(segment
		(start 391.524236 -249.522996)
		(end 391.523728 -249.523758)
		(width 0.14732)
		(layer "In15.Cu")
		(net "P5E_CPU0_PE2_TX_DP<10>")
	)
	(segment
		(start 391.52576 -249.520964)
		(end 391.524236 -249.522996)
		(width 0.14732)
		(layer "In15.Cu")
		(net "P5E_CPU0_PE2_TX_DP<10>")
	)
	(segment
		(start 387.05917 -399.344388)
		(end 387.15696 -399.486628)
		(width 0.14732)
		(layer "In15.Cu")
		(net "P5E_CPU0_PE2_TX_DP<10>")
	)
	(segment
		(start 387.280912 -398.81683)
		(end 387.138672 -398.91462)
		(width 0.14732)
		(layer "In15.Cu")
		(net "P5E_CPU0_PE2_TX_DP<10>")
	)
	(segment
		(start 379.120146 -222.442278)
		(end 379.129036 -222.437198)
		(width 0.0889)
		(layer "In15.Cu")
		(net "P5E_CPU0_PE2_TX_DP<10>")
	)
	(segment
		(start 393.268454 -255.715008)
		(end 394.069062 -259.091938)
		(width 0.14732)
		(layer "In15.Cu")
		(net "P5E_CPU0_PE2_TX_DP<10>")
	)
	(segment
		(start 394.60805 -359.176828)
		(end 387.484112 -397.716502)
		(width 0.14732)
		(layer "In15.Cu")
		(net "P5E_CPU0_PE2_TX_DP<10>")
	)
	(arc
		(start 379.598682 -220.644212)
		(mid 379.463749 -220.510858)
		(end 379.411484 -220.32849)
		(width 0.0889)
		(layer "In15.Cu")
		(net "P5E_CPU0_PE2_TX_DP<10>")
	)
	(arc
		(start 382.322832 -219.18168)
		(mid 382.605534 -219.257456)
		(end 382.888236 -219.18168)
		(width 0.0889)
		(layer "In15.Cu")
		(net "P5E_CPU0_PE2_TX_DP<10>")
	)
	(arc
		(start 380.821184 -219.506038)
		(mid 380.868863 -219.323138)
		(end 380.999746 -219.18676)
		(width 0.0889)
		(layer "In15.Cu")
		(net "P5E_CPU0_PE2_TX_DP<10>")
	)
	(arc
		(start 379.598682 -219.995496)
		(mid 379.78588 -219.945353)
		(end 379.973078 -219.995496)
		(width 0.0889)
		(layer "In15.Cu")
		(net "P5E_CPU0_PE2_TX_DP<10>")
	)
	(arc
		(start 381.008636 -219.18168)
		(mid 381.195834 -219.131537)
		(end 381.383032 -219.18168)
		(width 0.0889)
		(layer "In15.Cu")
		(net "P5E_CPU0_PE2_TX_DP<10>")
	)
	(arc
		(start 380.538736 -219.995496)
		(mid 380.743071 -219.792891)
		(end 380.821184 -219.515944)
		(width 0.0889)
		(layer "In15.Cu")
		(net "P5E_CPU0_PE2_TX_DP<10>")
	)
	(arc
		(start 379.881384 -221.1197)
		(mid 379.802165 -220.845015)
		(end 379.598682 -220.644212)
		(width 0.0889)
		(layer "In15.Cu")
		(net "P5E_CPU0_PE2_TX_DP<10>")
	)
	(arc
		(start 379.604778 -221.619826)
		(mid 379.807365 -221.413475)
		(end 379.881384 -221.133924)
		(width 0.0889)
		(layer "In15.Cu")
		(net "P5E_CPU0_PE2_TX_DP<10>")
	)
	(arc
		(start 379.411484 -220.311218)
		(mid 379.463754 -220.128853)
		(end 379.598682 -219.995496)
		(width 0.0889)
		(layer "In15.Cu")
		(net "P5E_CPU0_PE2_TX_DP<10>")
	)
	(arc
		(start 384.202432 -219.18168)
		(mid 384.478991 -219.257423)
		(end 384.757168 -219.187776)
		(width 0.0889)
		(layer "In15.Cu")
		(net "P5E_CPU0_PE2_TX_DP<10>")
	)
	(arc
		(start 381.383032 -219.18168)
		(mid 381.665734 -219.257456)
		(end 381.948436 -219.18168)
		(width 0.0889)
		(layer "In15.Cu")
		(net "P5E_CPU0_PE2_TX_DP<10>")
	)
	(arc
		(start 386.612384 -220.038676)
		(mid 386.621148 -220.046668)
		(end 386.629656 -220.054932)
		(width 0.0889)
		(layer "In15.Cu")
		(net "P5E_CPU0_PE2_TX_DP<10>")
	)
	(arc
		(start 386.177536 -219.995496)
		(mid 386.364734 -219.945353)
		(end 386.551932 -219.995496)
		(width 0.0889)
		(layer "In15.Cu")
		(net "P5E_CPU0_PE2_TX_DP<10>")
	)
	(arc
		(start 378.195332 -224.061528)
		(mid 378.397745 -223.855115)
		(end 378.471684 -223.575626)
		(width 0.0889)
		(layer "In15.Cu")
		(net "P5E_CPU0_PE2_TX_DP<10>")
	)
	(arc
		(start 379.973078 -219.995496)
		(mid 380.249891 -220.071366)
		(end 380.528322 -220.001592)
		(width 0.0889)
		(layer "In15.Cu")
		(net "P5E_CPU0_PE2_TX_DP<10>")
	)
	(arc
		(start 378.941584 -222.761556)
		(mid 378.989263 -222.578656)
		(end 379.120146 -222.442278)
		(width 0.0889)
		(layer "In15.Cu")
		(net "P5E_CPU0_PE2_TX_DP<10>")
	)
	(arc
		(start 383.828036 -219.18168)
		(mid 384.015234 -219.131537)
		(end 384.202432 -219.18168)
		(width 0.0889)
		(layer "In15.Cu")
		(net "P5E_CPU0_PE2_TX_DP<10>")
	)
	(arc
		(start 385.32943 -219.506038)
		(mid 385.403421 -219.785604)
		(end 385.606036 -219.99194)
		(width 0.0889)
		(layer "In15.Cu")
		(net "P5E_CPU0_PE2_TX_DP<10>")
	)
	(arc
		(start 382.888236 -219.18168)
		(mid 383.075434 -219.131537)
		(end 383.262632 -219.18168)
		(width 0.0889)
		(layer "In15.Cu")
		(net "P5E_CPU0_PE2_TX_DP<10>")
	)
	(arc
		(start 385.150868 -219.18676)
		(mid 385.281782 -219.32312)
		(end 385.32943 -219.506038)
		(width 0.0889)
		(layer "In15.Cu")
		(net "P5E_CPU0_PE2_TX_DP<10>")
	)
	(arc
		(start 378.659136 -223.251268)
		(mid 378.861422 -223.052287)
		(end 378.941584 -222.780098)
		(width 0.0889)
		(layer "In15.Cu")
		(net "P5E_CPU0_PE2_TX_DP<10>")
	)
	(arc
		(start 379.41123 -221.94774)
		(mid 379.458909 -221.76484)
		(end 379.589792 -221.628462)
		(width 0.0889)
		(layer "In15.Cu")
		(net "P5E_CPU0_PE2_TX_DP<10>")
	)
	(arc
		(start 381.948436 -219.18168)
		(mid 382.135634 -219.131537)
		(end 382.322832 -219.18168)
		(width 0.0889)
		(layer "In15.Cu")
		(net "P5E_CPU0_PE2_TX_DP<10>")
	)
	(arc
		(start 385.626864 -220.004132)
		(mid 385.903339 -220.071452)
		(end 386.177536 -219.995496)
		(width 0.0889)
		(layer "In15.Cu")
		(net "P5E_CPU0_PE2_TX_DP<10>")
	)
	(arc
		(start 377.70181 -224.10293)
		(mid 377.949821 -224.139395)
		(end 378.189236 -224.065084)
		(width 0.0889)
		(layer "In15.Cu")
		(net "P5E_CPU0_PE2_TX_DP<10>")
	)
	(arc
		(start 379.129036 -222.437198)
		(mid 379.331859 -222.236967)
		(end 379.41123 -221.963234)
		(width 0.0889)
		(layer "In15.Cu")
		(net "P5E_CPU0_PE2_TX_DP<10>")
	)
	(arc
		(start 378.471684 -223.575626)
		(mid 378.519363 -223.392726)
		(end 378.650246 -223.256348)
		(width 0.0889)
		(layer "In15.Cu")
		(net "P5E_CPU0_PE2_TX_DP<10>")
	)
	(arc
		(start 377.681998 -224.094802)
		(mid 377.691865 -224.098961)
		(end 377.70181 -224.10293)
		(width 0.0889)
		(layer "In15.Cu")
		(net "P5E_CPU0_PE2_TX_DP<10>")
	)
	(arc
		(start 383.262632 -219.18168)
		(mid 383.545334 -219.257456)
		(end 383.828036 -219.18168)
		(width 0.0889)
		(layer "In15.Cu")
		(net "P5E_CPU0_PE2_TX_DP<10>")
	)
	(arc
		(start 384.767582 -219.18168)
		(mid 384.95478 -219.131537)
		(end 385.141978 -219.18168)
		(width 0.0889)
		(layer "In15.Cu")
		(net "P5E_CPU0_PE2_TX_DP<10>")
	)
	(arc
		(start 386.551932 -219.995496)
		(mid 386.583229 -220.015586)
		(end 386.612384 -220.038676)
		(width 0.0889)
		(layer "In15.Cu")
		(net "P5E_CPU0_PE2_TX_DP<10>")
	)
	(segment
		(start 417.677092 -401.777962)
		(end 417.350702 -402.104352)
		(width 0.13208)
		(layer "F.Cu")
		(net "P5E_CPU0_PE2_TX_DP<0>")
	)
	(segment
		(start 417.677092 -401.16379)
		(end 417.677092 -401.777962)
		(width 0.13208)
		(layer "F.Cu")
		(net "P5E_CPU0_PE2_TX_DP<0>")
	)
	(segment
		(start 368.03838 -224.389696)
		(end 368.038634 -224.389442)
		(width 0.13208)
		(layer "F.Cu")
		(net "P5E_CPU0_PE2_TX_DP<0>")
	)
	(segment
		(start 417.37153 -400.858228)
		(end 417.677092 -401.16379)
		(width 0.13208)
		(layer "F.Cu")
		(net "P5E_CPU0_PE2_TX_DP<0>")
	)
	(segment
		(start 368.03838 -224.925382)
		(end 368.03838 -224.389696)
		(width 0.13208)
		(layer "F.Cu")
		(net "P5E_CPU0_PE2_TX_DP<0>")
	)
	(segment
		(start 417.350702 -402.104352)
		(end 417.34613 -402.104352)
		(width 0.13208)
		(layer "F.Cu")
		(net "P5E_CPU0_PE2_TX_DP<0>")
	)
	(segment
		(start 415.880042 -395.551914)
		(end 416.022282 -395.965426)
		(width 0.14732)
		(layer "In15.Cu")
		(net "P5E_CPU0_PE2_TX_DP<0>")
	)
	(segment
		(start 407.017474 -369.441476)
		(end 411.23362 -381.68072)
		(width 0.14732)
		(layer "In15.Cu")
		(net "P5E_CPU0_PE2_TX_DP<0>")
	)
	(segment
		(start 417.054538 -398.578832)
		(end 416.977322 -398.737074)
		(width 0.14732)
		(layer "In15.Cu")
		(net "P5E_CPU0_PE2_TX_DP<0>")
	)
	(segment
		(start 370.013484 -220.32849)
		(end 370.013484 -220.311218)
		(width 0.0889)
		(layer "In15.Cu")
		(net "P5E_CPU0_PE2_TX_DP<0>")
	)
	(segment
		(start 381.239014 -200.960228)
		(end 382.673606 -200.960228)
		(width 0.14732)
		(layer "In15.Cu")
		(net "P5E_CPU0_PE2_TX_DP<0>")
	)
	(segment
		(start 370.201444 -219.994988)
		(end 370.206778 -219.99194)
		(width 0.0889)
		(layer "In15.Cu")
		(net "P5E_CPU0_PE2_TX_DP<0>")
	)
	(segment
		(start 400.756374 -307.485288)
		(end 408.176222 -339.779102)
		(width 0.14732)
		(layer "In15.Cu")
		(net "P5E_CPU0_PE2_TX_DP<0>")
	)
	(segment
		(start 417.278058 -399.227548)
		(end 417.66617 -400.354546)
		(width 0.14732)
		(layer "In15.Cu")
		(net "P5E_CPU0_PE2_TX_DP<0>")
	)
	(segment
		(start 380.392432 -201.80681)
		(end 381.239014 -200.960228)
		(width 0.14732)
		(layer "In15.Cu")
		(net "P5E_CPU0_PE2_TX_DP<0>")
	)
	(segment
		(start 370.200682 -221.623382)
		(end 370.206778 -221.619826)
		(width 0.0889)
		(layer "In15.Cu")
		(net "P5E_CPU0_PE2_TX_DP<0>")
	)
	(segment
		(start 370.191792 -221.628462)
		(end 370.200682 -221.623382)
		(width 0.0889)
		(layer "In15.Cu")
		(net "P5E_CPU0_PE2_TX_DP<0>")
	)
	(segment
		(start 417.66617 -400.354546)
		(end 417.66617 -400.563588)
		(width 0.14732)
		(layer "In15.Cu")
		(net "P5E_CPU0_PE2_TX_DP<0>")
	)
	(segment
		(start 371.140482 -218.367864)
		(end 371.146578 -218.364308)
		(width 0.0889)
		(layer "In15.Cu")
		(net "P5E_CPU0_PE2_TX_DP<0>")
	)
	(segment
		(start 411.23362 -381.68072)
		(end 411.233366 -381.68072)
		(width 0.14732)
		(layer "In15.Cu")
		(net "P5E_CPU0_PE2_TX_DP<0>")
	)
	(segment
		(start 416.753802 -398.088866)
		(end 416.912298 -398.165828)
		(width 0.14732)
		(layer "In15.Cu")
		(net "P5E_CPU0_PE2_TX_DP<0>")
	)
	(segment
		(start 372.741952 -212.301328)
		(end 372.874794 -211.633308)
		(width 0.14732)
		(layer "In15.Cu")
		(net "P5E_CPU0_PE2_TX_DP<0>")
	)
	(segment
		(start 370.661946 -219.18676)
		(end 370.670836 -219.18168)
		(width 0.0889)
		(layer "In15.Cu")
		(net "P5E_CPU0_PE2_TX_DP<0>")
	)
	(segment
		(start 385.267962 -201.576432)
		(end 385.926584 -201.907902)
		(width 0.14732)
		(layer "In15.Cu")
		(net "P5E_CPU0_PE2_TX_DP<0>")
	)
	(segment
		(start 416.323018 -396.455392)
		(end 416.245802 -396.613634)
		(width 0.14732)
		(layer "In15.Cu")
		(net "P5E_CPU0_PE2_TX_DP<0>")
	)
	(segment
		(start 368.195098 -224.118424)
		(end 368.283998 -224.094802)
		(width 0.0889)
		(layer "In15.Cu")
		(net "P5E_CPU0_PE2_TX_DP<0>")
	)
	(segment
		(start 399.881344 -219.898214)
		(end 401.506436 -226.15779)
		(width 0.14732)
		(layer "In15.Cu")
		(net "P5E_CPU0_PE2_TX_DP<0>")
	)
	(segment
		(start 393.121134 -210.78444)
		(end 399.881344 -219.898214)
		(width 0.14732)
		(layer "In15.Cu")
		(net "P5E_CPU0_PE2_TX_DP<0>")
	)
	(segment
		(start 415.957258 -395.393672)
		(end 415.880042 -395.551914)
		(width 0.14732)
		(layer "In15.Cu")
		(net "P5E_CPU0_PE2_TX_DP<0>")
	)
	(segment
		(start 416.022282 -395.965426)
		(end 416.180778 -396.042388)
		(width 0.14732)
		(layer "In15.Cu")
		(net "P5E_CPU0_PE2_TX_DP<0>")
	)
	(segment
		(start 371.423184 -215.736932)
		(end 371.465348 -215.694768)
		(width 0.0889)
		(layer "In15.Cu")
		(net "P5E_CPU0_PE2_TX_DP<0>")
	)
	(segment
		(start 370.95303 -218.707716)
		(end 370.95303 -218.692222)
		(width 0.0889)
		(layer "In15.Cu")
		(net "P5E_CPU0_PE2_TX_DP<0>")
	)
	(segment
		(start 372.874794 -211.633308)
		(end 373.306594 -210.591146)
		(width 0.14732)
		(layer "In15.Cu")
		(net "P5E_CPU0_PE2_TX_DP<0>")
	)
	(segment
		(start 369.252246 -223.256348)
		(end 369.261136 -223.251268)
		(width 0.0889)
		(layer "In15.Cu")
		(net "P5E_CPU0_PE2_TX_DP<0>")
	)
	(segment
		(start 417.119562 -399.150332)
		(end 417.278058 -399.227548)
		(width 0.14732)
		(layer "In15.Cu")
		(net "P5E_CPU0_PE2_TX_DP<0>")
	)
	(segment
		(start 416.245802 -396.613634)
		(end 416.388042 -397.027146)
		(width 0.14732)
		(layer "In15.Cu")
		(net "P5E_CPU0_PE2_TX_DP<0>")
	)
	(segment
		(start 404.94331 -253.498604)
		(end 400.756374 -307.485288)
		(width 0.14732)
		(layer "In15.Cu")
		(net "P5E_CPU0_PE2_TX_DP<0>")
	)
	(segment
		(start 416.688778 -397.517112)
		(end 416.611562 -397.675354)
		(width 0.14732)
		(layer "In15.Cu")
		(net "P5E_CPU0_PE2_TX_DP<0>")
	)
	(segment
		(start 371.423184 -216.260426)
		(end 371.423184 -215.736932)
		(width 0.0889)
		(layer "In15.Cu")
		(net "P5E_CPU0_PE2_TX_DP<0>")
	)
	(segment
		(start 416.977322 -398.737074)
		(end 417.119562 -399.150332)
		(width 0.14732)
		(layer "In15.Cu")
		(net "P5E_CPU0_PE2_TX_DP<0>")
	)
	(segment
		(start 416.180778 -396.042388)
		(end 416.323018 -396.455392)
		(width 0.14732)
		(layer "In15.Cu")
		(net "P5E_CPU0_PE2_TX_DP<0>")
	)
	(segment
		(start 371.139974 -216.740486)
		(end 371.140736 -216.739978)
		(width 0.0889)
		(layer "In15.Cu")
		(net "P5E_CPU0_PE2_TX_DP<0>")
	)
	(segment
		(start 417.66617 -400.563588)
		(end 417.37153 -400.858228)
		(width 0.14732)
		(layer "In15.Cu")
		(net "P5E_CPU0_PE2_TX_DP<0>")
	)
	(segment
		(start 416.912298 -398.165828)
		(end 417.054538 -398.578832)
		(width 0.14732)
		(layer "In15.Cu")
		(net "P5E_CPU0_PE2_TX_DP<0>")
	)
	(segment
		(start 373.306594 -210.591146)
		(end 380.392432 -201.80681)
		(width 0.14732)
		(layer "In15.Cu")
		(net "P5E_CPU0_PE2_TX_DP<0>")
	)
	(segment
		(start 371.423184 -217.878406)
		(end 371.423184 -217.859864)
		(width 0.0889)
		(layer "In15.Cu")
		(net "P5E_CPU0_PE2_TX_DP<0>")
	)
	(segment
		(start 406.617678 -348.086934)
		(end 407.017474 -369.441476)
		(width 0.14732)
		(layer "In15.Cu")
		(net "P5E_CPU0_PE2_TX_DP<0>")
	)
	(segment
		(start 416.388042 -397.027146)
		(end 416.546538 -397.104108)
		(width 0.14732)
		(layer "In15.Cu")
		(net "P5E_CPU0_PE2_TX_DP<0>")
	)
	(segment
		(start 371.955822 -214.1982)
		(end 372.741952 -212.301328)
		(width 0.14732)
		(layer "In15.Cu")
		(net "P5E_CPU0_PE2_TX_DP<0>")
	)
	(segment
		(start 385.926584 -201.907902)
		(end 393.121134 -210.78444)
		(width 0.14732)
		(layer "In15.Cu")
		(net "P5E_CPU0_PE2_TX_DP<0>")
	)
	(segment
		(start 371.131846 -216.745058)
		(end 371.139974 -216.740486)
		(width 0.0889)
		(layer "In15.Cu")
		(net "P5E_CPU0_PE2_TX_DP<0>")
	)
	(segment
		(start 371.465348 -214.932514)
		(end 371.955822 -214.1982)
		(width 0.14732)
		(layer "In15.Cu")
		(net "P5E_CPU0_PE2_TX_DP<0>")
	)
	(segment
		(start 382.673606 -200.960228)
		(end 385.267962 -201.576432)
		(width 0.14732)
		(layer "In15.Cu")
		(net "P5E_CPU0_PE2_TX_DP<0>")
	)
	(segment
		(start 371.140736 -217.388694)
		(end 371.131846 -217.383614)
		(width 0.0889)
		(layer "In15.Cu")
		(net "P5E_CPU0_PE2_TX_DP<0>")
	)
	(segment
		(start 369.722146 -222.442278)
		(end 369.731036 -222.437198)
		(width 0.0889)
		(layer "In15.Cu")
		(net "P5E_CPU0_PE2_TX_DP<0>")
	)
	(segment
		(start 404.74646 -247.631712)
		(end 404.94331 -253.498604)
		(width 0.14732)
		(layer "In15.Cu")
		(net "P5E_CPU0_PE2_TX_DP<0>")
	)
	(segment
		(start 415.957004 -395.393672)
		(end 415.957258 -395.393672)
		(width 0.14732)
		(layer "In15.Cu")
		(net "P5E_CPU0_PE2_TX_DP<0>")
	)
	(segment
		(start 371.465348 -215.694768)
		(end 371.465348 -215.67267)
		(width 0.0889)
		(layer "In15.Cu")
		(net "P5E_CPU0_PE2_TX_DP<0>")
	)
	(segment
		(start 369.543584 -222.780098)
		(end 369.543584 -222.761556)
		(width 0.0889)
		(layer "In15.Cu")
		(net "P5E_CPU0_PE2_TX_DP<0>")
	)
	(segment
		(start 416.611562 -397.675354)
		(end 416.753802 -398.088866)
		(width 0.14732)
		(layer "In15.Cu")
		(net "P5E_CPU0_PE2_TX_DP<0>")
	)
	(segment
		(start 370.200682 -219.995496)
		(end 370.201444 -219.994988)
		(width 0.0889)
		(layer "In15.Cu")
		(net "P5E_CPU0_PE2_TX_DP<0>")
	)
	(segment
		(start 401.506436 -226.15779)
		(end 404.74646 -247.631712)
		(width 0.14732)
		(layer "In15.Cu")
		(net "P5E_CPU0_PE2_TX_DP<0>")
	)
	(segment
		(start 370.483384 -221.133924)
		(end 370.483384 -221.1197)
		(width 0.0889)
		(layer "In15.Cu")
		(net "P5E_CPU0_PE2_TX_DP<0>")
	)
	(segment
		(start 408.176222 -339.779102)
		(end 406.617678 -348.086934)
		(width 0.14732)
		(layer "In15.Cu")
		(net "P5E_CPU0_PE2_TX_DP<0>")
	)
	(segment
		(start 371.131592 -218.372944)
		(end 371.140482 -218.367864)
		(width 0.0889)
		(layer "In15.Cu")
		(net "P5E_CPU0_PE2_TX_DP<0>")
	)
	(segment
		(start 368.038634 -224.389442)
		(end 368.195098 -224.118424)
		(width 0.0889)
		(layer "In15.Cu")
		(net "P5E_CPU0_PE2_TX_DP<0>")
	)
	(segment
		(start 368.791236 -224.065084)
		(end 368.797332 -224.061528)
		(width 0.0889)
		(layer "In15.Cu")
		(net "P5E_CPU0_PE2_TX_DP<0>")
	)
	(segment
		(start 370.01323 -221.963234)
		(end 370.01323 -221.94774)
		(width 0.0889)
		(layer "In15.Cu")
		(net "P5E_CPU0_PE2_TX_DP<0>")
	)
	(segment
		(start 371.465348 -215.67267)
		(end 371.465348 -214.932514)
		(width 0.14732)
		(layer "In15.Cu")
		(net "P5E_CPU0_PE2_TX_DP<0>")
	)
	(segment
		(start 416.546538 -397.104108)
		(end 416.688778 -397.517112)
		(width 0.14732)
		(layer "In15.Cu")
		(net "P5E_CPU0_PE2_TX_DP<0>")
	)
	(segment
		(start 411.233366 -381.68072)
		(end 415.957004 -395.393672)
		(width 0.14732)
		(layer "In15.Cu")
		(net "P5E_CPU0_PE2_TX_DP<0>")
	)
	(arc
		(start 368.797332 -224.061528)
		(mid 368.999745 -223.855115)
		(end 369.073684 -223.575626)
		(width 0.0889)
		(layer "In15.Cu")
		(net "P5E_CPU0_PE2_TX_DP<0>")
	)
	(arc
		(start 370.483384 -221.1197)
		(mid 370.404165 -220.845015)
		(end 370.200682 -220.644212)
		(width 0.0889)
		(layer "In15.Cu")
		(net "P5E_CPU0_PE2_TX_DP<0>")
	)
	(arc
		(start 371.146578 -218.364308)
		(mid 371.349165 -218.157957)
		(end 371.423184 -217.878406)
		(width 0.0889)
		(layer "In15.Cu")
		(net "P5E_CPU0_PE2_TX_DP<0>")
	)
	(arc
		(start 370.206778 -221.619826)
		(mid 370.409365 -221.413475)
		(end 370.483384 -221.133924)
		(width 0.0889)
		(layer "In15.Cu")
		(net "P5E_CPU0_PE2_TX_DP<0>")
	)
	(arc
		(start 370.95303 -218.692222)
		(mid 371.000709 -218.509322)
		(end 371.131592 -218.372944)
		(width 0.0889)
		(layer "In15.Cu")
		(net "P5E_CPU0_PE2_TX_DP<0>")
	)
	(arc
		(start 371.140736 -216.739978)
		(mid 371.345071 -216.537373)
		(end 371.423184 -216.260426)
		(width 0.0889)
		(layer "In15.Cu")
		(net "P5E_CPU0_PE2_TX_DP<0>")
	)
	(arc
		(start 369.731036 -222.437198)
		(mid 369.933859 -222.236967)
		(end 370.01323 -221.963234)
		(width 0.0889)
		(layer "In15.Cu")
		(net "P5E_CPU0_PE2_TX_DP<0>")
	)
	(arc
		(start 370.200682 -220.644212)
		(mid 370.065749 -220.510858)
		(end 370.013484 -220.32849)
		(width 0.0889)
		(layer "In15.Cu")
		(net "P5E_CPU0_PE2_TX_DP<0>")
	)
	(arc
		(start 371.131846 -217.383614)
		(mid 370.953249 -217.064336)
		(end 371.131846 -216.745058)
		(width 0.0889)
		(layer "In15.Cu")
		(net "P5E_CPU0_PE2_TX_DP<0>")
	)
	(arc
		(start 369.073684 -223.575626)
		(mid 369.121363 -223.392726)
		(end 369.252246 -223.256348)
		(width 0.0889)
		(layer "In15.Cu")
		(net "P5E_CPU0_PE2_TX_DP<0>")
	)
	(arc
		(start 370.013484 -220.311218)
		(mid 370.065754 -220.128853)
		(end 370.200682 -219.995496)
		(width 0.0889)
		(layer "In15.Cu")
		(net "P5E_CPU0_PE2_TX_DP<0>")
	)
	(arc
		(start 368.283998 -224.094802)
		(mid 368.293865 -224.098961)
		(end 368.30381 -224.10293)
		(width 0.0889)
		(layer "In15.Cu")
		(net "P5E_CPU0_PE2_TX_DP<0>")
	)
	(arc
		(start 370.483384 -219.506038)
		(mid 370.531063 -219.323138)
		(end 370.661946 -219.18676)
		(width 0.0889)
		(layer "In15.Cu")
		(net "P5E_CPU0_PE2_TX_DP<0>")
	)
	(arc
		(start 370.206778 -219.99194)
		(mid 370.409365 -219.785589)
		(end 370.483384 -219.506038)
		(width 0.0889)
		(layer "In15.Cu")
		(net "P5E_CPU0_PE2_TX_DP<0>")
	)
	(arc
		(start 368.30381 -224.10293)
		(mid 368.551821 -224.139395)
		(end 368.791236 -224.065084)
		(width 0.0889)
		(layer "In15.Cu")
		(net "P5E_CPU0_PE2_TX_DP<0>")
	)
	(arc
		(start 370.670836 -219.18168)
		(mid 370.873659 -218.981449)
		(end 370.95303 -218.707716)
		(width 0.0889)
		(layer "In15.Cu")
		(net "P5E_CPU0_PE2_TX_DP<0>")
	)
	(arc
		(start 369.261136 -223.251268)
		(mid 369.463422 -223.052287)
		(end 369.543584 -222.780098)
		(width 0.0889)
		(layer "In15.Cu")
		(net "P5E_CPU0_PE2_TX_DP<0>")
	)
	(arc
		(start 369.543584 -222.761556)
		(mid 369.591263 -222.578656)
		(end 369.722146 -222.442278)
		(width 0.0889)
		(layer "In15.Cu")
		(net "P5E_CPU0_PE2_TX_DP<0>")
	)
	(arc
		(start 370.01323 -221.94774)
		(mid 370.060909 -221.76484)
		(end 370.191792 -221.628462)
		(width 0.0889)
		(layer "In15.Cu")
		(net "P5E_CPU0_PE2_TX_DP<0>")
	)
	(arc
		(start 371.423184 -217.859864)
		(mid 371.343022 -217.587675)
		(end 371.140736 -217.388694)
		(width 0.0889)
		(layer "In15.Cu")
		(net "P5E_CPU0_PE2_TX_DP<0>")
	)
	(segment
		(start 390.66597 -400.858228)
		(end 390.367012 -401.157186)
		(width 0.13208)
		(layer "F.Cu")
		(net "P5E_CPU0_PE2_TX_DN<9>")
	)
	(segment
		(start 376.49658 -224.389696)
		(end 376.496834 -224.389442)
		(width 0.13208)
		(layer "F.Cu")
		(net "P5E_CPU0_PE2_TX_DN<9>")
	)
	(segment
		(start 390.367012 -401.779994)
		(end 390.69137 -402.104352)
		(width 0.13208)
		(layer "F.Cu")
		(net "P5E_CPU0_PE2_TX_DN<9>")
	)
	(segment
		(start 376.49658 -224.925382)
		(end 376.49658 -224.389696)
		(width 0.13208)
		(layer "F.Cu")
		(net "P5E_CPU0_PE2_TX_DN<9>")
	)
	(segment
		(start 390.367012 -401.157186)
		(end 390.367012 -401.779994)
		(width 0.13208)
		(layer "F.Cu")
		(net "P5E_CPU0_PE2_TX_DN<9>")
	)
	(segment
		(start 378.55144 -219.837508)
		(end 378.562362 -219.831158)
		(width 0.0889)
		(layer "In15.Cu")
		(net "P5E_CPU0_PE2_TX_DN<9>")
	)
	(segment
		(start 390.37133 -400.563588)
		(end 390.66597 -400.858228)
		(width 0.14732)
		(layer "In15.Cu")
		(net "P5E_CPU0_PE2_TX_DN<9>")
	)
	(segment
		(start 378.751084 -219.506038)
		(end 378.751084 -219.490544)
		(width 0.0889)
		(layer "In15.Cu")
		(net "P5E_CPU0_PE2_TX_DN<9>")
	)
	(segment
		(start 381.376936 -216.578434)
		(end 381.383032 -216.574878)
		(width 0.0889)
		(layer "In15.Cu")
		(net "P5E_CPU0_PE2_TX_DN<9>")
	)
	(segment
		(start 377.811284 -222.761556)
		(end 377.811284 -222.746062)
		(width 0.0889)
		(layer "In15.Cu")
		(net "P5E_CPU0_PE2_TX_DN<9>")
	)
	(segment
		(start 393.315444 -229.672896)
		(end 396.530576 -250.28652)
		(width 0.14732)
		(layer "In15.Cu")
		(net "P5E_CPU0_PE2_TX_DN<9>")
	)
	(segment
		(start 381.10033 -217.072972)
		(end 381.10033 -217.064336)
		(width 0.0889)
		(layer "In15.Cu")
		(net "P5E_CPU0_PE2_TX_DN<9>")
	)
	(segment
		(start 380.437136 -218.20632)
		(end 380.443232 -218.202764)
		(width 0.0889)
		(layer "In15.Cu")
		(net "P5E_CPU0_PE2_TX_DN<9>")
	)
	(segment
		(start 389.42899 -220.552772)
		(end 392.021314 -223.976692)
		(width 0.14732)
		(layer "In15.Cu")
		(net "P5E_CPU0_PE2_TX_DN<9>")
	)
	(segment
		(start 376.496834 -224.389442)
		(end 376.653298 -224.66046)
		(width 0.0889)
		(layer "In15.Cu")
		(net "P5E_CPU0_PE2_TX_DN<9>")
	)
	(segment
		(start 396.627096 -253.154688)
		(end 392.316462 -309.440072)
		(width 0.14732)
		(layer "In15.Cu")
		(net "P5E_CPU0_PE2_TX_DN<9>")
	)
	(segment
		(start 378.093478 -222.272098)
		(end 378.102368 -222.267018)
		(width 0.0889)
		(layer "In15.Cu")
		(net "P5E_CPU0_PE2_TX_DN<9>")
	)
	(segment
		(start 377.34113 -223.584262)
		(end 377.34113 -223.561402)
		(width 0.0889)
		(layer "In15.Cu")
		(net "P5E_CPU0_PE2_TX_DN<9>")
	)
	(segment
		(start 386.811012 -217.934794)
		(end 389.42899 -220.552772)
		(width 0.14732)
		(layer "In15.Cu")
		(net "P5E_CPU0_PE2_TX_DN<9>")
	)
	(segment
		(start 378.563632 -221.458282)
		(end 378.572522 -221.453202)
		(width 0.0889)
		(layer "In15.Cu")
		(net "P5E_CPU0_PE2_TX_DN<9>")
	)
	(segment
		(start 390.37133 -400.194018)
		(end 390.37133 -400.563588)
		(width 0.14732)
		(layer "In15.Cu")
		(net "P5E_CPU0_PE2_TX_DN<9>")
	)
	(segment
		(start 380.443232 -218.202764)
		(end 380.452122 -218.197684)
		(width 0.0889)
		(layer "In15.Cu")
		(net "P5E_CPU0_PE2_TX_DN<9>")
	)
	(segment
		(start 378.563632 -219.830396)
		(end 378.572522 -219.825316)
		(width 0.0889)
		(layer "In15.Cu")
		(net "P5E_CPU0_PE2_TX_DN<9>")
	)
	(segment
		(start 378.28093 -220.327474)
		(end 378.28093 -220.319854)
		(width 0.0889)
		(layer "In15.Cu")
		(net "P5E_CPU0_PE2_TX_DN<9>")
	)
	(segment
		(start 392.55065 -225.805492)
		(end 393.315444 -229.672896)
		(width 0.14732)
		(layer "In15.Cu")
		(net "P5E_CPU0_PE2_TX_DN<9>")
	)
	(segment
		(start 396.530576 -250.28652)
		(end 396.627096 -253.154688)
		(width 0.14732)
		(layer "In15.Cu")
		(net "P5E_CPU0_PE2_TX_DN<9>")
	)
	(segment
		(start 386.294884 -217.47861)
		(end 386.735574 -217.9193)
		(width 0.0889)
		(layer "In15.Cu")
		(net "P5E_CPU0_PE2_TX_DN<9>")
	)
	(segment
		(start 379.58395 -219.007944)
		(end 379.598682 -219.01658)
		(width 0.0889)
		(layer "In15.Cu")
		(net "P5E_CPU0_PE2_TX_DN<9>")
	)
	(segment
		(start 378.557536 -221.461838)
		(end 378.563632 -221.458282)
		(width 0.0889)
		(layer "In15.Cu")
		(net "P5E_CPU0_PE2_TX_DN<9>")
	)
	(segment
		(start 378.562362 -219.831158)
		(end 378.563632 -219.830396)
		(width 0.0889)
		(layer "In15.Cu")
		(net "P5E_CPU0_PE2_TX_DN<9>")
	)
	(segment
		(start 379.973078 -219.01658)
		(end 379.981968 -219.0115)
		(width 0.0889)
		(layer "In15.Cu")
		(net "P5E_CPU0_PE2_TX_DN<9>")
	)
	(segment
		(start 381.383032 -216.574878)
		(end 381.397764 -216.566242)
		(width 0.0889)
		(layer "In15.Cu")
		(net "P5E_CPU0_PE2_TX_DN<9>")
	)
	(segment
		(start 376.871484 -224.389442)
		(end 376.871484 -224.379536)
		(width 0.0889)
		(layer "In15.Cu")
		(net "P5E_CPU0_PE2_TX_DN<9>")
	)
	(segment
		(start 380.630684 -217.878406)
		(end 380.630684 -217.859864)
		(width 0.0889)
		(layer "In15.Cu")
		(net "P5E_CPU0_PE2_TX_DN<9>")
	)
	(segment
		(start 378.572522 -220.814646)
		(end 378.564394 -220.810074)
		(width 0.0889)
		(layer "In15.Cu")
		(net "P5E_CPU0_PE2_TX_DN<9>")
	)
	(segment
		(start 386.795518 -217.9193)
		(end 386.811012 -217.934794)
		(width 0.0889)
		(layer "In15.Cu")
		(net "P5E_CPU0_PE2_TX_DN<9>")
	)
	(segment
		(start 376.653298 -224.66046)
		(end 376.73153 -224.681288)
		(width 0.0889)
		(layer "In15.Cu")
		(net "P5E_CPU0_PE2_TX_DN<9>")
	)
	(segment
		(start 399.480786 -339.49767)
		(end 396.879572 -354.531422)
		(width 0.14732)
		(layer "In15.Cu")
		(net "P5E_CPU0_PE2_TX_DN<9>")
	)
	(segment
		(start 378.564394 -220.810074)
		(end 378.563632 -220.809566)
		(width 0.0889)
		(layer "In15.Cu")
		(net "P5E_CPU0_PE2_TX_DN<9>")
	)
	(segment
		(start 392.316462 -309.440072)
		(end 399.480786 -339.49767)
		(width 0.14732)
		(layer "In15.Cu")
		(net "P5E_CPU0_PE2_TX_DN<9>")
	)
	(segment
		(start 385.990084 -217.05443)
		(end 385.990084 -217.064336)
		(width 0.0889)
		(layer "In15.Cu")
		(net "P5E_CPU0_PE2_TX_DN<9>")
	)
	(segment
		(start 386.168646 -217.383614)
		(end 386.177536 -217.388694)
		(width 0.0889)
		(layer "In15.Cu")
		(net "P5E_CPU0_PE2_TX_DN<9>")
	)
	(segment
		(start 395.003528 -367.945924)
		(end 390.37133 -400.194018)
		(width 0.14732)
		(layer "In15.Cu")
		(net "P5E_CPU0_PE2_TX_DN<9>")
	)
	(segment
		(start 396.879572 -354.531422)
		(end 395.003528 -367.945924)
		(width 0.14732)
		(layer "In15.Cu")
		(net "P5E_CPU0_PE2_TX_DN<9>")
	)
	(segment
		(start 392.021314 -223.976692)
		(end 392.55065 -225.805492)
		(width 0.14732)
		(layer "In15.Cu")
		(net "P5E_CPU0_PE2_TX_DN<9>")
	)
	(segment
		(start 377.623832 -223.085914)
		(end 377.632722 -223.080834)
		(width 0.0889)
		(layer "In15.Cu")
		(net "P5E_CPU0_PE2_TX_DN<9>")
	)
	(segment
		(start 386.735574 -217.9193)
		(end 386.795518 -217.9193)
		(width 0.0889)
		(layer "In15.Cu")
		(net "P5E_CPU0_PE2_TX_DN<9>")
	)
	(arc
		(start 377.811284 -222.746062)
		(mid 377.890654 -222.472328)
		(end 378.093478 -222.272098)
		(width 0.0889)
		(layer "In15.Cu")
		(net "P5E_CPU0_PE2_TX_DN<9>")
	)
	(arc
		(start 383.828036 -216.574878)
		(mid 384.015234 -216.625021)
		(end 384.202432 -216.574878)
		(width 0.0889)
		(layer "In15.Cu")
		(net "P5E_CPU0_PE2_TX_DN<9>")
	)
	(arc
		(start 384.202432 -216.574878)
		(mid 384.485134 -216.499102)
		(end 384.767836 -216.574878)
		(width 0.0889)
		(layer "In15.Cu")
		(net "P5E_CPU0_PE2_TX_DN<9>")
	)
	(arc
		(start 379.981968 -219.0115)
		(mid 380.112882 -218.87514)
		(end 380.16053 -218.692222)
		(width 0.0889)
		(layer "In15.Cu")
		(net "P5E_CPU0_PE2_TX_DN<9>")
	)
	(arc
		(start 378.28093 -221.94774)
		(mid 378.354921 -221.668174)
		(end 378.557536 -221.461838)
		(width 0.0889)
		(layer "In15.Cu")
		(net "P5E_CPU0_PE2_TX_DN<9>")
	)
	(arc
		(start 383.262632 -216.574878)
		(mid 383.545334 -216.499102)
		(end 383.828036 -216.574878)
		(width 0.0889)
		(layer "In15.Cu")
		(net "P5E_CPU0_PE2_TX_DN<9>")
	)
	(arc
		(start 386.177536 -217.388694)
		(mid 386.239169 -217.429791)
		(end 386.294884 -217.47861)
		(width 0.0889)
		(layer "In15.Cu")
		(net "P5E_CPU0_PE2_TX_DN<9>")
	)
	(arc
		(start 377.632722 -223.080834)
		(mid 377.763636 -222.944474)
		(end 377.811284 -222.761556)
		(width 0.0889)
		(layer "In15.Cu")
		(net "P5E_CPU0_PE2_TX_DN<9>")
	)
	(arc
		(start 378.751084 -219.490544)
		(mid 378.830454 -219.21681)
		(end 379.033278 -219.01658)
		(width 0.0889)
		(layer "In15.Cu")
		(net "P5E_CPU0_PE2_TX_DN<9>")
	)
	(arc
		(start 381.10033 -217.064336)
		(mid 381.174321 -216.78477)
		(end 381.376936 -216.578434)
		(width 0.0889)
		(layer "In15.Cu")
		(net "P5E_CPU0_PE2_TX_DN<9>")
	)
	(arc
		(start 376.871484 -224.379536)
		(mid 376.949595 -224.102587)
		(end 377.153932 -223.899984)
		(width 0.0889)
		(layer "In15.Cu")
		(net "P5E_CPU0_PE2_TX_DN<9>")
	)
	(arc
		(start 378.572522 -219.825316)
		(mid 378.703436 -219.688956)
		(end 378.751084 -219.506038)
		(width 0.0889)
		(layer "In15.Cu")
		(net "P5E_CPU0_PE2_TX_DN<9>")
	)
	(arc
		(start 385.142232 -216.574878)
		(mid 385.424934 -216.499102)
		(end 385.707636 -216.574878)
		(width 0.0889)
		(layer "In15.Cu")
		(net "P5E_CPU0_PE2_TX_DN<9>")
	)
	(arc
		(start 380.16053 -218.692222)
		(mid 380.234521 -218.412656)
		(end 380.437136 -218.20632)
		(width 0.0889)
		(layer "In15.Cu")
		(net "P5E_CPU0_PE2_TX_DN<9>")
	)
	(arc
		(start 378.572522 -221.453202)
		(mid 378.751119 -221.133924)
		(end 378.572522 -220.814646)
		(width 0.0889)
		(layer "In15.Cu")
		(net "P5E_CPU0_PE2_TX_DN<9>")
	)
	(arc
		(start 378.28093 -220.319854)
		(mid 378.353165 -220.04333)
		(end 378.55144 -219.837508)
		(width 0.0889)
		(layer "In15.Cu")
		(net "P5E_CPU0_PE2_TX_DN<9>")
	)
	(arc
		(start 380.913132 -217.388694)
		(mid 381.048065 -217.25534)
		(end 381.10033 -217.072972)
		(width 0.0889)
		(layer "In15.Cu")
		(net "P5E_CPU0_PE2_TX_DN<9>")
	)
	(arc
		(start 379.033278 -219.01658)
		(mid 379.307477 -218.940745)
		(end 379.58395 -219.007944)
		(width 0.0889)
		(layer "In15.Cu")
		(net "P5E_CPU0_PE2_TX_DN<9>")
	)
	(arc
		(start 380.630684 -217.859864)
		(mid 380.710846 -217.587675)
		(end 380.913132 -217.388694)
		(width 0.0889)
		(layer "In15.Cu")
		(net "P5E_CPU0_PE2_TX_DN<9>")
	)
	(arc
		(start 380.452122 -218.197684)
		(mid 380.583036 -218.061324)
		(end 380.630684 -217.878406)
		(width 0.0889)
		(layer "In15.Cu")
		(net "P5E_CPU0_PE2_TX_DN<9>")
	)
	(arc
		(start 377.34113 -223.561402)
		(mid 377.420349 -223.286717)
		(end 377.623832 -223.085914)
		(width 0.0889)
		(layer "In15.Cu")
		(net "P5E_CPU0_PE2_TX_DN<9>")
	)
	(arc
		(start 378.563632 -220.809566)
		(mid 378.35856 -220.605887)
		(end 378.28093 -220.327474)
		(width 0.0889)
		(layer "In15.Cu")
		(net "P5E_CPU0_PE2_TX_DN<9>")
	)
	(arc
		(start 378.102368 -222.267018)
		(mid 378.233282 -222.130658)
		(end 378.28093 -221.94774)
		(width 0.0889)
		(layer "In15.Cu")
		(net "P5E_CPU0_PE2_TX_DN<9>")
	)
	(arc
		(start 381.397764 -216.566242)
		(mid 381.674239 -216.498922)
		(end 381.948436 -216.574878)
		(width 0.0889)
		(layer "In15.Cu")
		(net "P5E_CPU0_PE2_TX_DN<9>")
	)
	(arc
		(start 384.767836 -216.574878)
		(mid 384.955034 -216.625021)
		(end 385.142232 -216.574878)
		(width 0.0889)
		(layer "In15.Cu")
		(net "P5E_CPU0_PE2_TX_DN<9>")
	)
	(arc
		(start 385.990084 -217.064336)
		(mid 386.037763 -217.247236)
		(end 386.168646 -217.383614)
		(width 0.0889)
		(layer "In15.Cu")
		(net "P5E_CPU0_PE2_TX_DN<9>")
	)
	(arc
		(start 382.322832 -216.574878)
		(mid 382.605534 -216.499102)
		(end 382.888236 -216.574878)
		(width 0.0889)
		(layer "In15.Cu")
		(net "P5E_CPU0_PE2_TX_DN<9>")
	)
	(arc
		(start 377.153932 -223.899984)
		(mid 377.288865 -223.76663)
		(end 377.34113 -223.584262)
		(width 0.0889)
		(layer "In15.Cu")
		(net "P5E_CPU0_PE2_TX_DN<9>")
	)
	(arc
		(start 379.598682 -219.01658)
		(mid 379.78588 -219.066723)
		(end 379.973078 -219.01658)
		(width 0.0889)
		(layer "In15.Cu")
		(net "P5E_CPU0_PE2_TX_DN<9>")
	)
	(arc
		(start 376.73153 -224.681288)
		(mid 376.834675 -224.551263)
		(end 376.871484 -224.389442)
		(width 0.0889)
		(layer "In15.Cu")
		(net "P5E_CPU0_PE2_TX_DN<9>")
	)
	(arc
		(start 381.948436 -216.574878)
		(mid 382.135634 -216.625021)
		(end 382.322832 -216.574878)
		(width 0.0889)
		(layer "In15.Cu")
		(net "P5E_CPU0_PE2_TX_DN<9>")
	)
	(arc
		(start 385.707636 -216.574878)
		(mid 385.911971 -216.777483)
		(end 385.990084 -217.05443)
		(width 0.0889)
		(layer "In15.Cu")
		(net "P5E_CPU0_PE2_TX_DN<9>")
	)
	(arc
		(start 382.888236 -216.574878)
		(mid 383.075434 -216.625021)
		(end 383.262632 -216.574878)
		(width 0.0889)
		(layer "In15.Cu")
		(net "P5E_CPU0_PE2_TX_DN<9>")
	)
	(segment
		(start 376.026934 -224.111566)
		(end 376.026934 -223.57588)
		(width 0.13208)
		(layer "F.Cu")
		(net "P5E_CPU0_PE2_TX_DN<8>")
	)
	(segment
		(start 393.72921 -400.858228)
		(end 393.430252 -401.157186)
		(width 0.13208)
		(layer "F.Cu")
		(net "P5E_CPU0_PE2_TX_DN<8>")
	)
	(segment
		(start 393.430252 -401.779994)
		(end 393.75461 -402.104352)
		(width 0.13208)
		(layer "F.Cu")
		(net "P5E_CPU0_PE2_TX_DN<8>")
	)
	(segment
		(start 393.430252 -401.157186)
		(end 393.430252 -401.779994)
		(width 0.13208)
		(layer "F.Cu")
		(net "P5E_CPU0_PE2_TX_DN<8>")
	)
	(segment
		(start 376.026934 -223.57588)
		(end 376.02668 -223.575626)
		(width 0.13208)
		(layer "F.Cu")
		(net "P5E_CPU0_PE2_TX_DN<8>")
	)
	(segment
		(start 380.630684 -216.235026)
		(end 380.630684 -216.25052)
		(width 0.0889)
		(layer "In15.Cu")
		(net "P5E_CPU0_PE2_TX_DN<8>")
	)
	(segment
		(start 380.452122 -216.569798)
		(end 380.443232 -216.574878)
		(width 0.0889)
		(layer "In15.Cu")
		(net "P5E_CPU0_PE2_TX_DN<8>")
	)
	(segment
		(start 379.518164 -216.566242)
		(end 379.503432 -216.574878)
		(width 0.0889)
		(layer "In15.Cu")
		(net "P5E_CPU0_PE2_TX_DN<8>")
	)
	(segment
		(start 386.631942 -216.187528)
		(end 386.535676 -216.091262)
		(width 0.0889)
		(layer "In15.Cu")
		(net "P5E_CPU0_PE2_TX_DN<8>")
	)
	(segment
		(start 395.844776 -239.72139)
		(end 394.241528 -229.50424)
		(width 0.14732)
		(layer "In15.Cu")
		(net "P5E_CPU0_PE2_TX_DN<8>")
	)
	(segment
		(start 387.408928 -216.905586)
		(end 386.706364 -216.203022)
		(width 0.14732)
		(layer "In15.Cu")
		(net "P5E_CPU0_PE2_TX_DN<8>")
	)
	(segment
		(start 388.681214 -218.177872)
		(end 388.681214 -218.005406)
		(width 0.14732)
		(layer "In15.Cu")
		(net "P5E_CPU0_PE2_TX_DN<8>")
	)
	(segment
		(start 376.40133 -223.568006)
		(end 376.40133 -223.575626)
		(width 0.0889)
		(layer "In15.Cu")
		(net "P5E_CPU0_PE2_TX_DN<8>")
	)
	(segment
		(start 376.871484 -222.746062)
		(end 376.871484 -222.761556)
		(width 0.0889)
		(layer "In15.Cu")
		(net "P5E_CPU0_PE2_TX_DN<8>")
	)
	(segment
		(start 378.751084 -217.859864)
		(end 378.751084 -217.878406)
		(width 0.0889)
		(layer "In15.Cu")
		(net "P5E_CPU0_PE2_TX_DN<8>")
	)
	(segment
		(start 393.298934 -309.257954)
		(end 397.5608 -253.218442)
		(width 0.14732)
		(layer "In15.Cu")
		(net "P5E_CPU0_PE2_TX_DN<8>")
	)
	(segment
		(start 393.43457 -400.563588)
		(end 393.43457 -400.060922)
		(width 0.14732)
		(layer "In15.Cu")
		(net "P5E_CPU0_PE2_TX_DN<8>")
	)
	(segment
		(start 376.222768 -223.894904)
		(end 376.214894 -223.899476)
		(width 0.0889)
		(layer "In15.Cu")
		(net "P5E_CPU0_PE2_TX_DN<8>")
	)
	(segment
		(start 393.72921 -400.858228)
		(end 393.43457 -400.563588)
		(width 0.14732)
		(layer "In15.Cu")
		(net "P5E_CPU0_PE2_TX_DN<8>")
	)
	(segment
		(start 386.535676 -216.091262)
		(end 386.29463 -215.849962)
		(width 0.0889)
		(layer "In15.Cu")
		(net "P5E_CPU0_PE2_TX_DN<8>")
	)
	(segment
		(start 377.632722 -221.453202)
		(end 377.623832 -221.458282)
		(width 0.0889)
		(layer "In15.Cu")
		(net "P5E_CPU0_PE2_TX_DN<8>")
	)
	(segment
		(start 389.132572 -218.62923)
		(end 388.681214 -218.177872)
		(width 0.14732)
		(layer "In15.Cu")
		(net "P5E_CPU0_PE2_TX_DN<8>")
	)
	(segment
		(start 397.450818 -249.950478)
		(end 395.845284 -239.721644)
		(width 0.14732)
		(layer "In15.Cu")
		(net "P5E_CPU0_PE2_TX_DN<8>")
	)
	(segment
		(start 377.623832 -221.458282)
		(end 377.617736 -221.461838)
		(width 0.0889)
		(layer "In15.Cu")
		(net "P5E_CPU0_PE2_TX_DN<8>")
	)
	(segment
		(start 393.43457 -400.060922)
		(end 396.564612 -368.243866)
		(width 0.14732)
		(layer "In15.Cu")
		(net "P5E_CPU0_PE2_TX_DN<8>")
	)
	(segment
		(start 386.69087 -216.187528)
		(end 386.631942 -216.187528)
		(width 0.0889)
		(layer "In15.Cu")
		(net "P5E_CPU0_PE2_TX_DN<8>")
	)
	(segment
		(start 377.632722 -219.825316)
		(end 377.625356 -219.829634)
		(width 0.0889)
		(layer "In15.Cu")
		(net "P5E_CPU0_PE2_TX_DN<8>")
	)
	(segment
		(start 385.61264 -215.761062)
		(end 385.600702 -215.76792)
		(width 0.0889)
		(layer "In15.Cu")
		(net "P5E_CPU0_PE2_TX_DN<8>")
	)
	(segment
		(start 379.503432 -216.574878)
		(end 379.497336 -216.578434)
		(width 0.0889)
		(layer "In15.Cu")
		(net "P5E_CPU0_PE2_TX_DN<8>")
	)
	(segment
		(start 377.34113 -220.319854)
		(end 377.34113 -220.334078)
		(width 0.0889)
		(layer "In15.Cu")
		(net "P5E_CPU0_PE2_TX_DN<8>")
	)
	(segment
		(start 375.891298 -223.924622)
		(end 375.870216 -223.846644)
		(width 0.0889)
		(layer "In15.Cu")
		(net "P5E_CPU0_PE2_TX_DN<8>")
	)
	(segment
		(start 387.890512 -217.214704)
		(end 387.581394 -216.905586)
		(width 0.14732)
		(layer "In15.Cu")
		(net "P5E_CPU0_PE2_TX_DN<8>")
	)
	(segment
		(start 378.572522 -218.197684)
		(end 378.563632 -218.202764)
		(width 0.0889)
		(layer "In15.Cu")
		(net "P5E_CPU0_PE2_TX_DN<8>")
	)
	(segment
		(start 384.015234 -215.685116)
		(end 381.195326 -215.685116)
		(width 0.0889)
		(layer "In15.Cu")
		(net "P5E_CPU0_PE2_TX_DN<8>")
	)
	(segment
		(start 388.681214 -218.005406)
		(end 388.371842 -217.696034)
		(width 0.14732)
		(layer "In15.Cu")
		(net "P5E_CPU0_PE2_TX_DN<8>")
	)
	(segment
		(start 379.22073 -217.064336)
		(end 379.22073 -217.072972)
		(width 0.0889)
		(layer "In15.Cu")
		(net "P5E_CPU0_PE2_TX_DN<8>")
	)
	(segment
		(start 388.199376 -217.696034)
		(end 387.890512 -217.38717)
		(width 0.14732)
		(layer "In15.Cu")
		(net "P5E_CPU0_PE2_TX_DN<8>")
	)
	(segment
		(start 377.623832 -220.809566)
		(end 377.632722 -220.814646)
		(width 0.0889)
		(layer "In15.Cu")
		(net "P5E_CPU0_PE2_TX_DN<8>")
	)
	(segment
		(start 377.625356 -219.829634)
		(end 377.623832 -219.830396)
		(width 0.0889)
		(layer "In15.Cu")
		(net "P5E_CPU0_PE2_TX_DN<8>")
	)
	(segment
		(start 394.241528 -229.50424)
		(end 393.533122 -225.825304)
		(width 0.14732)
		(layer "In15.Cu")
		(net "P5E_CPU0_PE2_TX_DN<8>")
	)
	(segment
		(start 377.623832 -219.830396)
		(end 377.617736 -219.833952)
		(width 0.0889)
		(layer "In15.Cu")
		(net "P5E_CPU0_PE2_TX_DN<8>")
	)
	(segment
		(start 377.162568 -222.267018)
		(end 377.153678 -222.272098)
		(width 0.0889)
		(layer "In15.Cu")
		(net "P5E_CPU0_PE2_TX_DN<8>")
	)
	(segment
		(start 384.69062 -215.750648)
		(end 384.672586 -215.761062)
		(width 0.0889)
		(layer "In15.Cu")
		(net "P5E_CPU0_PE2_TX_DN<8>")
	)
	(segment
		(start 400.491198 -339.614256)
		(end 393.298934 -309.257954)
		(width 0.14732)
		(layer "In15.Cu")
		(net "P5E_CPU0_PE2_TX_DN<8>")
	)
	(segment
		(start 377.811284 -219.490544)
		(end 377.811284 -219.506038)
		(width 0.0889)
		(layer "In15.Cu")
		(net "P5E_CPU0_PE2_TX_DN<8>")
	)
	(segment
		(start 387.581394 -216.905586)
		(end 387.408928 -216.905586)
		(width 0.14732)
		(layer "In15.Cu")
		(net "P5E_CPU0_PE2_TX_DN<8>")
	)
	(segment
		(start 385.636008 -215.7476)
		(end 385.61264 -215.761062)
		(width 0.0889)
		(layer "In15.Cu")
		(net "P5E_CPU0_PE2_TX_DN<8>")
	)
	(segment
		(start 395.845284 -239.721644)
		(end 395.844776 -239.72139)
		(width 0.14732)
		(layer "In15.Cu")
		(net "P5E_CPU0_PE2_TX_DN<8>")
	)
	(segment
		(start 393.533122 -225.825304)
		(end 392.950446 -223.625156)
		(width 0.14732)
		(layer "In15.Cu")
		(net "P5E_CPU0_PE2_TX_DN<8>")
	)
	(segment
		(start 375.870216 -223.846644)
		(end 376.02668 -223.575626)
		(width 0.0889)
		(layer "In15.Cu")
		(net "P5E_CPU0_PE2_TX_DN<8>")
	)
	(segment
		(start 392.950446 -223.625156)
		(end 389.132572 -218.62923)
		(width 0.14732)
		(layer "In15.Cu")
		(net "P5E_CPU0_PE2_TX_DN<8>")
	)
	(segment
		(start 396.564612 -368.243866)
		(end 398.93494 -348.608142)
		(width 0.14732)
		(layer "In15.Cu")
		(net "P5E_CPU0_PE2_TX_DN<8>")
	)
	(segment
		(start 386.706364 -216.203022)
		(end 386.69087 -216.187528)
		(width 0.0889)
		(layer "In15.Cu")
		(net "P5E_CPU0_PE2_TX_DN<8>")
	)
	(segment
		(start 378.563632 -218.202764)
		(end 378.557536 -218.20632)
		(width 0.0889)
		(layer "In15.Cu")
		(net "P5E_CPU0_PE2_TX_DN<8>")
	)
	(segment
		(start 398.93494 -348.608142)
		(end 400.491198 -339.614256)
		(width 0.14732)
		(layer "In15.Cu")
		(net "P5E_CPU0_PE2_TX_DN<8>")
	)
	(segment
		(start 387.890512 -217.38717)
		(end 387.890512 -217.214704)
		(width 0.14732)
		(layer "In15.Cu")
		(net "P5E_CPU0_PE2_TX_DN<8>")
	)
	(segment
		(start 388.371842 -217.696034)
		(end 388.199376 -217.696034)
		(width 0.14732)
		(layer "In15.Cu")
		(net "P5E_CPU0_PE2_TX_DN<8>")
	)
	(segment
		(start 397.5608 -253.218442)
		(end 397.450818 -249.950478)
		(width 0.14732)
		(layer "In15.Cu")
		(net "P5E_CPU0_PE2_TX_DN<8>")
	)
	(segment
		(start 376.692922 -223.080834)
		(end 376.684032 -223.085914)
		(width 0.0889)
		(layer "In15.Cu")
		(net "P5E_CPU0_PE2_TX_DN<8>")
	)
	(segment
		(start 378.102368 -219.0115)
		(end 378.093478 -219.01658)
		(width 0.0889)
		(layer "In15.Cu")
		(net "P5E_CPU0_PE2_TX_DN<8>")
	)
	(segment
		(start 376.214894 -223.899476)
		(end 376.213878 -223.899984)
		(width 0.0889)
		(layer "In15.Cu")
		(net "P5E_CPU0_PE2_TX_DN<8>")
	)
	(arc
		(start 377.811284 -219.506038)
		(mid 377.763605 -219.688938)
		(end 377.632722 -219.825316)
		(width 0.0889)
		(layer "In15.Cu")
		(net "P5E_CPU0_PE2_TX_DN<8>")
	)
	(arc
		(start 385.238244 -215.761062)
		(mid 384.965778 -215.685134)
		(end 384.69062 -215.750648)
		(width 0.0889)
		(layer "In15.Cu")
		(net "P5E_CPU0_PE2_TX_DN<8>")
	)
	(arc
		(start 379.033532 -217.388694)
		(mid 378.831246 -217.587675)
		(end 378.751084 -217.859864)
		(width 0.0889)
		(layer "In15.Cu")
		(net "P5E_CPU0_PE2_TX_DN<8>")
	)
	(arc
		(start 381.164846 -215.685878)
		(mid 380.790527 -215.856176)
		(end 380.630684 -216.235026)
		(width 0.0889)
		(layer "In15.Cu")
		(net "P5E_CPU0_PE2_TX_DN<8>")
	)
	(arc
		(start 381.195326 -215.685116)
		(mid 381.180081 -215.685294)
		(end 381.164846 -215.685878)
		(width 0.0889)
		(layer "In15.Cu")
		(net "P5E_CPU0_PE2_TX_DN<8>")
	)
	(arc
		(start 380.443232 -216.574878)
		(mid 380.256034 -216.625021)
		(end 380.068836 -216.574878)
		(width 0.0889)
		(layer "In15.Cu")
		(net "P5E_CPU0_PE2_TX_DN<8>")
	)
	(arc
		(start 377.153678 -222.272098)
		(mid 376.950855 -222.472329)
		(end 376.871484 -222.746062)
		(width 0.0889)
		(layer "In15.Cu")
		(net "P5E_CPU0_PE2_TX_DN<8>")
	)
	(arc
		(start 380.630684 -216.25052)
		(mid 380.583005 -216.43342)
		(end 380.452122 -216.569798)
		(width 0.0889)
		(layer "In15.Cu")
		(net "P5E_CPU0_PE2_TX_DN<8>")
	)
	(arc
		(start 378.557536 -218.20632)
		(mid 378.354949 -218.412671)
		(end 378.28093 -218.692222)
		(width 0.0889)
		(layer "In15.Cu")
		(net "P5E_CPU0_PE2_TX_DN<8>")
	)
	(arc
		(start 379.497336 -216.578434)
		(mid 379.294749 -216.784785)
		(end 379.22073 -217.064336)
		(width 0.0889)
		(layer "In15.Cu")
		(net "P5E_CPU0_PE2_TX_DN<8>")
	)
	(arc
		(start 386.24383 -215.805258)
		(mid 386.211835 -215.782017)
		(end 386.178298 -215.761062)
		(width 0.0889)
		(layer "In15.Cu")
		(net "P5E_CPU0_PE2_TX_DN<8>")
	)
	(arc
		(start 379.22073 -217.072972)
		(mid 379.16846 -217.255337)
		(end 379.033532 -217.388694)
		(width 0.0889)
		(layer "In15.Cu")
		(net "P5E_CPU0_PE2_TX_DN<8>")
	)
	(arc
		(start 376.213878 -223.899984)
		(mid 376.05539 -223.948917)
		(end 375.891298 -223.924622)
		(width 0.0889)
		(layer "In15.Cu")
		(net "P5E_CPU0_PE2_TX_DN<8>")
	)
	(arc
		(start 378.093478 -219.01658)
		(mid 377.890655 -219.216811)
		(end 377.811284 -219.490544)
		(width 0.0889)
		(layer "In15.Cu")
		(net "P5E_CPU0_PE2_TX_DN<8>")
	)
	(arc
		(start 376.40133 -223.575626)
		(mid 376.353651 -223.758526)
		(end 376.222768 -223.894904)
		(width 0.0889)
		(layer "In15.Cu")
		(net "P5E_CPU0_PE2_TX_DN<8>")
	)
	(arc
		(start 386.178298 -215.761062)
		(mid 385.908872 -215.685079)
		(end 385.636008 -215.7476)
		(width 0.0889)
		(layer "In15.Cu")
		(net "P5E_CPU0_PE2_TX_DN<8>")
	)
	(arc
		(start 377.617736 -219.833952)
		(mid 377.415149 -220.040303)
		(end 377.34113 -220.319854)
		(width 0.0889)
		(layer "In15.Cu")
		(net "P5E_CPU0_PE2_TX_DN<8>")
	)
	(arc
		(start 378.751084 -217.878406)
		(mid 378.703405 -218.061306)
		(end 378.572522 -218.197684)
		(width 0.0889)
		(layer "In15.Cu")
		(net "P5E_CPU0_PE2_TX_DN<8>")
	)
	(arc
		(start 377.34113 -221.94774)
		(mid 377.293451 -222.13064)
		(end 377.162568 -222.267018)
		(width 0.0889)
		(layer "In15.Cu")
		(net "P5E_CPU0_PE2_TX_DN<8>")
	)
	(arc
		(start 377.617736 -221.461838)
		(mid 377.415149 -221.668189)
		(end 377.34113 -221.94774)
		(width 0.0889)
		(layer "In15.Cu")
		(net "P5E_CPU0_PE2_TX_DN<8>")
	)
	(arc
		(start 376.871484 -222.761556)
		(mid 376.823805 -222.944456)
		(end 376.692922 -223.080834)
		(width 0.0889)
		(layer "In15.Cu")
		(net "P5E_CPU0_PE2_TX_DN<8>")
	)
	(arc
		(start 377.632722 -220.814646)
		(mid 377.811319 -221.133924)
		(end 377.632722 -221.453202)
		(width 0.0889)
		(layer "In15.Cu")
		(net "P5E_CPU0_PE2_TX_DN<8>")
	)
	(arc
		(start 376.684032 -223.085914)
		(mid 376.47896 -223.289593)
		(end 376.40133 -223.568006)
		(width 0.0889)
		(layer "In15.Cu")
		(net "P5E_CPU0_PE2_TX_DN<8>")
	)
	(arc
		(start 378.28093 -218.692222)
		(mid 378.233251 -218.875122)
		(end 378.102368 -219.0115)
		(width 0.0889)
		(layer "In15.Cu")
		(net "P5E_CPU0_PE2_TX_DN<8>")
	)
	(arc
		(start 384.672586 -215.761062)
		(mid 384.485388 -215.811205)
		(end 384.29819 -215.761062)
		(width 0.0889)
		(layer "In15.Cu")
		(net "P5E_CPU0_PE2_TX_DN<8>")
	)
	(arc
		(start 377.34113 -220.334078)
		(mid 377.420349 -220.608763)
		(end 377.623832 -220.809566)
		(width 0.0889)
		(layer "In15.Cu")
		(net "P5E_CPU0_PE2_TX_DN<8>")
	)
	(arc
		(start 380.068836 -216.574878)
		(mid 379.794637 -216.499043)
		(end 379.518164 -216.566242)
		(width 0.0889)
		(layer "In15.Cu")
		(net "P5E_CPU0_PE2_TX_DN<8>")
	)
	(arc
		(start 384.29819 -215.761062)
		(mid 384.161718 -215.704439)
		(end 384.015234 -215.685116)
		(width 0.0889)
		(layer "In15.Cu")
		(net "P5E_CPU0_PE2_TX_DN<8>")
	)
	(arc
		(start 386.29463 -215.849962)
		(mid 386.269901 -215.826848)
		(end 386.24383 -215.805258)
		(width 0.0889)
		(layer "In15.Cu")
		(net "P5E_CPU0_PE2_TX_DN<8>")
	)
	(arc
		(start 385.600702 -215.76792)
		(mid 385.418591 -215.811245)
		(end 385.238244 -215.761062)
		(width 0.0889)
		(layer "In15.Cu")
		(net "P5E_CPU0_PE2_TX_DN<8>")
	)
	(segment
		(start 396.79245 -400.858228)
		(end 396.493492 -401.157186)
		(width 0.13208)
		(layer "F.Cu")
		(net "P5E_CPU0_PE2_TX_DN<7>")
	)
	(segment
		(start 396.493492 -401.157186)
		(end 396.493492 -401.779994)
		(width 0.13208)
		(layer "F.Cu")
		(net "P5E_CPU0_PE2_TX_DN<7>")
	)
	(segment
		(start 374.61698 -224.389696)
		(end 374.617234 -224.389442)
		(width 0.13208)
		(layer "F.Cu")
		(net "P5E_CPU0_PE2_TX_DN<7>")
	)
	(segment
		(start 396.493492 -401.779994)
		(end 396.81785 -402.104352)
		(width 0.13208)
		(layer "F.Cu")
		(net "P5E_CPU0_PE2_TX_DN<7>")
	)
	(segment
		(start 374.61698 -224.925382)
		(end 374.61698 -224.389696)
		(width 0.13208)
		(layer "F.Cu")
		(net "P5E_CPU0_PE2_TX_DN<7>")
	)
	(segment
		(start 376.401584 -221.960186)
		(end 376.401584 -221.94774)
		(width 0.0889)
		(layer "In15.Cu")
		(net "P5E_CPU0_PE2_TX_DN<7>")
	)
	(segment
		(start 377.624594 -218.202256)
		(end 377.627134 -218.200732)
		(width 0.0889)
		(layer "In15.Cu")
		(net "P5E_CPU0_PE2_TX_DN<7>")
	)
	(segment
		(start 401.463256 -339.504528)
		(end 399.872962 -348.675706)
		(width 0.14732)
		(layer "In15.Cu")
		(net "P5E_CPU0_PE2_TX_DN<7>")
	)
	(segment
		(start 398.493234 -253.251716)
		(end 398.492218 -253.266448)
		(width 0.14732)
		(layer "In15.Cu")
		(net "P5E_CPU0_PE2_TX_DN<7>")
	)
	(segment
		(start 376.684032 -221.458536)
		(end 376.688604 -221.455742)
		(width 0.0889)
		(layer "In15.Cu")
		(net "P5E_CPU0_PE2_TX_DN<7>")
	)
	(segment
		(start 376.871484 -219.506038)
		(end 376.871484 -219.490544)
		(width 0.0889)
		(layer "In15.Cu")
		(net "P5E_CPU0_PE2_TX_DN<7>")
	)
	(segment
		(start 399.872962 -348.675706)
		(end 398.243552 -368.076988)
		(width 0.14732)
		(layer "In15.Cu")
		(net "P5E_CPU0_PE2_TX_DN<7>")
	)
	(segment
		(start 377.617736 -218.20632)
		(end 377.621038 -218.204288)
		(width 0.0889)
		(layer "In15.Cu")
		(net "P5E_CPU0_PE2_TX_DN<7>")
	)
	(segment
		(start 396.470378 -237.479586)
		(end 396.470632 -237.479586)
		(width 0.14732)
		(layer "In15.Cu")
		(net "P5E_CPU0_PE2_TX_DN<7>")
	)
	(segment
		(start 374.85193 -224.681288)
		(end 374.85193 -224.681542)
		(width 0.0889)
		(layer "In15.Cu")
		(net "P5E_CPU0_PE2_TX_DN<7>")
	)
	(segment
		(start 377.621038 -218.204288)
		(end 377.623832 -218.202764)
		(width 0.0889)
		(layer "In15.Cu")
		(net "P5E_CPU0_PE2_TX_DN<7>")
	)
	(segment
		(start 398.492726 -253.23673)
		(end 398.493234 -253.251716)
		(width 0.14732)
		(layer "In15.Cu")
		(net "P5E_CPU0_PE2_TX_DN<7>")
	)
	(segment
		(start 377.153678 -219.01658)
		(end 377.162568 -219.0115)
		(width 0.0889)
		(layer "In15.Cu")
		(net "P5E_CPU0_PE2_TX_DN<7>")
	)
	(segment
		(start 398.243552 -368.076988)
		(end 396.498064 -399.961608)
		(width 0.14732)
		(layer "In15.Cu")
		(net "P5E_CPU0_PE2_TX_DN<7>")
	)
	(segment
		(start 383.961386 -213.756748)
		(end 384.631184 -214.034624)
		(width 0.14732)
		(layer "In15.Cu")
		(net "P5E_CPU0_PE2_TX_DN<7>")
	)
	(segment
		(start 377.811284 -216.25052)
		(end 377.811284 -216.235026)
		(width 0.0889)
		(layer "In15.Cu")
		(net "P5E_CPU0_PE2_TX_DN<7>")
	)
	(segment
		(start 376.673618 -221.464632)
		(end 376.684032 -221.458536)
		(width 0.0889)
		(layer "In15.Cu")
		(net "P5E_CPU0_PE2_TX_DN<7>")
	)
	(segment
		(start 376.203972 -222.278448)
		(end 376.21464 -222.272098)
		(width 0.0889)
		(layer "In15.Cu")
		(net "P5E_CPU0_PE2_TX_DN<7>")
	)
	(segment
		(start 398.357344 -249.212354)
		(end 398.492726 -253.236476)
		(width 0.14732)
		(layer "In15.Cu")
		(net "P5E_CPU0_PE2_TX_DN<7>")
	)
	(segment
		(start 377.62942 -218.199462)
		(end 377.631452 -218.198446)
		(width 0.0889)
		(layer "In15.Cu")
		(net "P5E_CPU0_PE2_TX_DN<7>")
	)
	(segment
		(start 379.501146 -214.884762)
		(end 379.501146 -214.825834)
		(width 0.0889)
		(layer "In15.Cu")
		(net "P5E_CPU0_PE2_TX_DN<7>")
	)
	(segment
		(start 384.631438 -214.03437)
		(end 385.250944 -214.291164)
		(width 0.14732)
		(layer "In15.Cu")
		(net "P5E_CPU0_PE2_TX_DN<7>")
	)
	(segment
		(start 375.462038 -223.5835)
		(end 375.462038 -223.564958)
		(width 0.0889)
		(layer "In15.Cu")
		(net "P5E_CPU0_PE2_TX_DN<7>")
	)
	(segment
		(start 377.632722 -217.559128)
		(end 377.623832 -217.554048)
		(width 0.0889)
		(layer "In15.Cu")
		(net "P5E_CPU0_PE2_TX_DN<7>")
	)
	(segment
		(start 398.491964 -253.266448)
		(end 394.278104 -308.945026)
		(width 0.14732)
		(layer "In15.Cu")
		(net "P5E_CPU0_PE2_TX_DN<7>")
	)
	(segment
		(start 396.498064 -399.961608)
		(end 396.49781 -399.961862)
		(width 0.14732)
		(layer "In15.Cu")
		(net "P5E_CPU0_PE2_TX_DN<7>")
	)
	(segment
		(start 378.816362 -215.569292)
		(end 379.501146 -214.884762)
		(width 0.0889)
		(layer "In15.Cu")
		(net "P5E_CPU0_PE2_TX_DN<7>")
	)
	(segment
		(start 378.53747 -215.685116)
		(end 378.816362 -215.569292)
		(width 0.0889)
		(layer "In15.Cu")
		(net "P5E_CPU0_PE2_TX_DN<7>")
	)
	(segment
		(start 394.580618 -225.729546)
		(end 396.470378 -237.479586)
		(width 0.14732)
		(layer "In15.Cu")
		(net "P5E_CPU0_PE2_TX_DN<7>")
	)
	(segment
		(start 377.62815 -218.200224)
		(end 377.62942 -218.199462)
		(width 0.0889)
		(layer "In15.Cu")
		(net "P5E_CPU0_PE2_TX_DN<7>")
	)
	(segment
		(start 377.625356 -216.574116)
		(end 377.632722 -216.569798)
		(width 0.0889)
		(layer "In15.Cu")
		(net "P5E_CPU0_PE2_TX_DN<7>")
	)
	(segment
		(start 396.49781 -399.961862)
		(end 396.49781 -400.563588)
		(width 0.14732)
		(layer "In15.Cu")
		(net "P5E_CPU0_PE2_TX_DN<7>")
	)
	(segment
		(start 374.773698 -224.66046)
		(end 374.85193 -224.681288)
		(width 0.0889)
		(layer "In15.Cu")
		(net "P5E_CPU0_PE2_TX_DN<7>")
	)
	(segment
		(start 377.627134 -218.200732)
		(end 377.62815 -218.200224)
		(width 0.0889)
		(layer "In15.Cu")
		(net "P5E_CPU0_PE2_TX_DN<7>")
	)
	(segment
		(start 376.67184 -219.837508)
		(end 376.684032 -219.830396)
		(width 0.0889)
		(layer "In15.Cu")
		(net "P5E_CPU0_PE2_TX_DN<7>")
	)
	(segment
		(start 376.685302 -220.809566)
		(end 376.676412 -220.804486)
		(width 0.0889)
		(layer "In15.Cu")
		(net "P5E_CPU0_PE2_TX_DN<7>")
	)
	(segment
		(start 379.501146 -214.825834)
		(end 379.51664 -214.81034)
		(width 0.0889)
		(layer "In15.Cu")
		(net "P5E_CPU0_PE2_TX_DN<7>")
	)
	(segment
		(start 377.617736 -216.578434)
		(end 377.623832 -216.574878)
		(width 0.0889)
		(layer "In15.Cu")
		(net "P5E_CPU0_PE2_TX_DN<7>")
	)
	(segment
		(start 376.684032 -219.830396)
		(end 376.692922 -219.825316)
		(width 0.0889)
		(layer "In15.Cu")
		(net "P5E_CPU0_PE2_TX_DN<7>")
	)
	(segment
		(start 376.676412 -220.804486)
		(end 376.670824 -220.801184)
		(width 0.0889)
		(layer "In15.Cu")
		(net "P5E_CPU0_PE2_TX_DN<7>")
	)
	(segment
		(start 376.401838 -220.319854)
		(end 376.40133 -220.319854)
		(width 0.0889)
		(layer "In15.Cu")
		(net "P5E_CPU0_PE2_TX_DN<7>")
	)
	(segment
		(start 385.251198 -214.291164)
		(end 387.831838 -215.359996)
		(width 0.14732)
		(layer "In15.Cu")
		(net "P5E_CPU0_PE2_TX_DN<7>")
	)
	(segment
		(start 379.693424 -214.633556)
		(end 381.810768 -213.756748)
		(width 0.14732)
		(layer "In15.Cu")
		(net "P5E_CPU0_PE2_TX_DN<7>")
	)
	(segment
		(start 394.278104 -308.945026)
		(end 401.463256 -339.504528)
		(width 0.14732)
		(layer "In15.Cu")
		(net "P5E_CPU0_PE2_TX_DN<7>")
	)
	(segment
		(start 376.871738 -221.133924)
		(end 376.871738 -221.118938)
		(width 0.0889)
		(layer "In15.Cu")
		(net "P5E_CPU0_PE2_TX_DN<7>")
	)
	(segment
		(start 393.829032 -223.157034)
		(end 394.580618 -225.729546)
		(width 0.14732)
		(layer "In15.Cu")
		(net "P5E_CPU0_PE2_TX_DN<7>")
	)
	(segment
		(start 377.631452 -218.198446)
		(end 377.632722 -218.197684)
		(width 0.0889)
		(layer "In15.Cu")
		(net "P5E_CPU0_PE2_TX_DN<7>")
	)
	(segment
		(start 398.492726 -253.236476)
		(end 398.492726 -253.23673)
		(width 0.14732)
		(layer "In15.Cu")
		(net "P5E_CPU0_PE2_TX_DN<7>")
	)
	(segment
		(start 377.623832 -218.202764)
		(end 377.624594 -218.202256)
		(width 0.0889)
		(layer "In15.Cu")
		(net "P5E_CPU0_PE2_TX_DN<7>")
	)
	(segment
		(start 396.49781 -400.563588)
		(end 396.79245 -400.858228)
		(width 0.14732)
		(layer "In15.Cu")
		(net "P5E_CPU0_PE2_TX_DN<7>")
	)
	(segment
		(start 375.931938 -222.772986)
		(end 375.931938 -222.761556)
		(width 0.0889)
		(layer "In15.Cu")
		(net "P5E_CPU0_PE2_TX_DN<7>")
	)
	(segment
		(start 396.470632 -237.479586)
		(end 398.357344 -249.212354)
		(width 0.14732)
		(layer "In15.Cu")
		(net "P5E_CPU0_PE2_TX_DN<7>")
	)
	(segment
		(start 398.492218 -253.266448)
		(end 398.491964 -253.266448)
		(width 0.14732)
		(layer "In15.Cu")
		(net "P5E_CPU0_PE2_TX_DN<7>")
	)
	(segment
		(start 378.375926 -215.685116)
		(end 378.53747 -215.685116)
		(width 0.0889)
		(layer "In15.Cu")
		(net "P5E_CPU0_PE2_TX_DN<7>")
	)
	(segment
		(start 375.264172 -223.906334)
		(end 375.27484 -223.899984)
		(width 0.0889)
		(layer "In15.Cu")
		(net "P5E_CPU0_PE2_TX_DN<7>")
	)
	(segment
		(start 384.631184 -214.034624)
		(end 384.631438 -214.03437)
		(width 0.14732)
		(layer "In15.Cu")
		(net "P5E_CPU0_PE2_TX_DN<7>")
	)
	(segment
		(start 381.810768 -213.756748)
		(end 383.961386 -213.756748)
		(width 0.14732)
		(layer "In15.Cu")
		(net "P5E_CPU0_PE2_TX_DN<7>")
	)
	(segment
		(start 374.617234 -224.389442)
		(end 374.773698 -224.66046)
		(width 0.0889)
		(layer "In15.Cu")
		(net "P5E_CPU0_PE2_TX_DN<7>")
	)
	(segment
		(start 387.831838 -215.359996)
		(end 393.829032 -223.157034)
		(width 0.14732)
		(layer "In15.Cu")
		(net "P5E_CPU0_PE2_TX_DN<7>")
	)
	(segment
		(start 385.250944 -214.29091)
		(end 385.251198 -214.291164)
		(width 0.14732)
		(layer "In15.Cu")
		(net "P5E_CPU0_PE2_TX_DN<7>")
	)
	(segment
		(start 385.250944 -214.291164)
		(end 385.250944 -214.29091)
		(width 0.14732)
		(layer "In15.Cu")
		(net "P5E_CPU0_PE2_TX_DN<7>")
	)
	(segment
		(start 379.51664 -214.81034)
		(end 379.693424 -214.633556)
		(width 0.14732)
		(layer "In15.Cu")
		(net "P5E_CPU0_PE2_TX_DN<7>")
	)
	(segment
		(start 377.623832 -216.574878)
		(end 377.625356 -216.574116)
		(width 0.0889)
		(layer "In15.Cu")
		(net "P5E_CPU0_PE2_TX_DN<7>")
	)
	(segment
		(start 377.34113 -217.07856)
		(end 377.34113 -217.064336)
		(width 0.0889)
		(layer "In15.Cu")
		(net "P5E_CPU0_PE2_TX_DN<7>")
	)
	(arc
		(start 377.632722 -216.569798)
		(mid 377.763636 -216.433438)
		(end 377.811284 -216.25052)
		(width 0.0889)
		(layer "In15.Cu")
		(net "P5E_CPU0_PE2_TX_DN<7>")
	)
	(arc
		(start 374.991884 -224.389442)
		(mid 375.064703 -224.112199)
		(end 375.264172 -223.906334)
		(width 0.0889)
		(layer "In15.Cu")
		(net "P5E_CPU0_PE2_TX_DN<7>")
	)
	(arc
		(start 377.34113 -217.064336)
		(mid 377.415121 -216.78477)
		(end 377.617736 -216.578434)
		(width 0.0889)
		(layer "In15.Cu")
		(net "P5E_CPU0_PE2_TX_DN<7>")
	)
	(arc
		(start 376.40133 -220.319854)
		(mid 376.473565 -220.04333)
		(end 376.67184 -219.837508)
		(width 0.0889)
		(layer "In15.Cu")
		(net "P5E_CPU0_PE2_TX_DN<7>")
	)
	(arc
		(start 376.670824 -220.801184)
		(mid 376.473648 -220.595549)
		(end 376.401838 -220.319854)
		(width 0.0889)
		(layer "In15.Cu")
		(net "P5E_CPU0_PE2_TX_DN<7>")
	)
	(arc
		(start 378.345446 -215.685878)
		(mid 378.360681 -215.685289)
		(end 378.375926 -215.685116)
		(width 0.0889)
		(layer "In15.Cu")
		(net "P5E_CPU0_PE2_TX_DN<7>")
	)
	(arc
		(start 375.462038 -223.564958)
		(mid 375.540193 -223.288562)
		(end 375.744232 -223.086422)
		(width 0.0889)
		(layer "In15.Cu")
		(net "P5E_CPU0_PE2_TX_DN<7>")
	)
	(arc
		(start 375.27484 -223.899984)
		(mid 375.409885 -223.76626)
		(end 375.462038 -223.5835)
		(width 0.0889)
		(layer "In15.Cu")
		(net "P5E_CPU0_PE2_TX_DN<7>")
	)
	(arc
		(start 377.811284 -216.235026)
		(mid 377.97122 -215.856266)
		(end 378.345446 -215.685878)
		(width 0.0889)
		(layer "In15.Cu")
		(net "P5E_CPU0_PE2_TX_DN<7>")
	)
	(arc
		(start 376.21464 -222.272098)
		(mid 376.348428 -222.140308)
		(end 376.401584 -221.960186)
		(width 0.0889)
		(layer "In15.Cu")
		(net "P5E_CPU0_PE2_TX_DN<7>")
	)
	(arc
		(start 376.688604 -221.455742)
		(mid 376.822734 -221.319044)
		(end 376.871738 -221.133924)
		(width 0.0889)
		(layer "In15.Cu")
		(net "P5E_CPU0_PE2_TX_DN<7>")
	)
	(arc
		(start 377.632722 -218.197684)
		(mid 377.811319 -217.878406)
		(end 377.632722 -217.559128)
		(width 0.0889)
		(layer "In15.Cu")
		(net "P5E_CPU0_PE2_TX_DN<7>")
	)
	(arc
		(start 376.401584 -221.94774)
		(mid 376.474276 -221.670535)
		(end 376.673618 -221.464632)
		(width 0.0889)
		(layer "In15.Cu")
		(net "P5E_CPU0_PE2_TX_DN<7>")
	)
	(arc
		(start 375.744232 -223.086422)
		(mid 375.878859 -222.95411)
		(end 375.931938 -222.772986)
		(width 0.0889)
		(layer "In15.Cu")
		(net "P5E_CPU0_PE2_TX_DN<7>")
	)
	(arc
		(start 376.692922 -219.825316)
		(mid 376.823836 -219.688956)
		(end 376.871484 -219.506038)
		(width 0.0889)
		(layer "In15.Cu")
		(net "P5E_CPU0_PE2_TX_DN<7>")
	)
	(arc
		(start 374.85193 -224.681542)
		(mid 374.955129 -224.551403)
		(end 374.991884 -224.389442)
		(width 0.0889)
		(layer "In15.Cu")
		(net "P5E_CPU0_PE2_TX_DN<7>")
	)
	(arc
		(start 376.871738 -221.118938)
		(mid 376.818226 -220.940314)
		(end 376.685302 -220.809566)
		(width 0.0889)
		(layer "In15.Cu")
		(net "P5E_CPU0_PE2_TX_DN<7>")
	)
	(arc
		(start 376.871484 -219.490544)
		(mid 376.950854 -219.21681)
		(end 377.153678 -219.01658)
		(width 0.0889)
		(layer "In15.Cu")
		(net "P5E_CPU0_PE2_TX_DN<7>")
	)
	(arc
		(start 377.34113 -218.692222)
		(mid 377.415121 -218.412656)
		(end 377.617736 -218.20632)
		(width 0.0889)
		(layer "In15.Cu")
		(net "P5E_CPU0_PE2_TX_DN<7>")
	)
	(arc
		(start 377.623832 -217.554048)
		(mid 377.420351 -217.353244)
		(end 377.34113 -217.07856)
		(width 0.0889)
		(layer "In15.Cu")
		(net "P5E_CPU0_PE2_TX_DN<7>")
	)
	(arc
		(start 377.162568 -219.0115)
		(mid 377.293482 -218.87514)
		(end 377.34113 -218.692222)
		(width 0.0889)
		(layer "In15.Cu")
		(net "P5E_CPU0_PE2_TX_DN<7>")
	)
	(arc
		(start 375.931938 -222.761556)
		(mid 376.00463 -222.484351)
		(end 376.203972 -222.278448)
		(width 0.0889)
		(layer "In15.Cu")
		(net "P5E_CPU0_PE2_TX_DN<7>")
	)
	(segment
		(start 399.556732 -401.779994)
		(end 399.88109 -402.104352)
		(width 0.13208)
		(layer "F.Cu")
		(net "P5E_CPU0_PE2_TX_DN<6>")
	)
	(segment
		(start 399.85569 -400.858228)
		(end 399.556732 -401.157186)
		(width 0.13208)
		(layer "F.Cu")
		(net "P5E_CPU0_PE2_TX_DN<6>")
	)
	(segment
		(start 374.147334 -223.57588)
		(end 374.14708 -223.575626)
		(width 0.13208)
		(layer "F.Cu")
		(net "P5E_CPU0_PE2_TX_DN<6>")
	)
	(segment
		(start 374.147334 -224.111566)
		(end 374.147334 -223.57588)
		(width 0.13208)
		(layer "F.Cu")
		(net "P5E_CPU0_PE2_TX_DN<6>")
	)
	(segment
		(start 399.556732 -401.157186)
		(end 399.556732 -401.779994)
		(width 0.13208)
		(layer "F.Cu")
		(net "P5E_CPU0_PE2_TX_DN<6>")
	)
	(segment
		(start 375.738136 -219.833952)
		(end 375.744232 -219.830396)
		(width 0.0889)
		(layer "In15.Cu")
		(net "P5E_CPU0_PE2_TX_DN<6>")
	)
	(segment
		(start 376.692922 -217.559128)
		(end 376.684794 -217.554556)
		(width 0.0889)
		(layer "In15.Cu")
		(net "P5E_CPU0_PE2_TX_DN<6>")
	)
	(segment
		(start 375.274078 -222.272098)
		(end 375.282968 -222.267018)
		(width 0.0889)
		(layer "In15.Cu")
		(net "P5E_CPU0_PE2_TX_DN<6>")
	)
	(segment
		(start 375.744232 -219.830396)
		(end 375.745756 -219.829634)
		(width 0.0889)
		(layer "In15.Cu")
		(net "P5E_CPU0_PE2_TX_DN<6>")
	)
	(segment
		(start 395.528292 -225.515932)
		(end 395.528546 -225.515932)
		(width 0.14732)
		(layer "In15.Cu")
		(net "P5E_CPU0_PE2_TX_DN<6>")
	)
	(segment
		(start 377.153678 -215.761062)
		(end 377.162568 -215.755982)
		(width 0.0889)
		(layer "In15.Cu")
		(net "P5E_CPU0_PE2_TX_DN<6>")
	)
	(segment
		(start 388.519924 -214.577676)
		(end 394.737082 -222.80118)
		(width 0.14732)
		(layer "In15.Cu")
		(net "P5E_CPU0_PE2_TX_DN<6>")
	)
	(segment
		(start 402.480018 -339.529928)
		(end 400.904202 -348.708726)
		(width 0.14732)
		(layer "In15.Cu")
		(net "P5E_CPU0_PE2_TX_DN<6>")
	)
	(segment
		(start 379.483112 -213.634828)
		(end 379.483112 -213.576154)
		(width 0.0889)
		(layer "In15.Cu")
		(net "P5E_CPU0_PE2_TX_DN<6>")
	)
	(segment
		(start 380.241302 -212.817964)
		(end 384.270758 -212.817964)
		(width 0.14732)
		(layer "In15.Cu")
		(net "P5E_CPU0_PE2_TX_DN<6>")
	)
	(segment
		(start 376.40133 -217.071956)
		(end 376.40133 -217.064336)
		(width 0.0889)
		(layer "In15.Cu")
		(net "P5E_CPU0_PE2_TX_DN<6>")
	)
	(segment
		(start 376.871484 -216.25052)
		(end 376.871484 -216.235026)
		(width 0.0889)
		(layer "In15.Cu")
		(net "P5E_CPU0_PE2_TX_DN<6>")
	)
	(segment
		(start 379.498606 -213.56066)
		(end 380.241302 -212.817964)
		(width 0.14732)
		(layer "In15.Cu")
		(net "P5E_CPU0_PE2_TX_DN<6>")
	)
	(segment
		(start 395.528546 -225.515932)
		(end 395.533118 -225.532188)
		(width 0.14732)
		(layer "In15.Cu")
		(net "P5E_CPU0_PE2_TX_DN<6>")
	)
	(segment
		(start 399.56105 -399.994628)
		(end 399.56105 -400.563588)
		(width 0.14732)
		(layer "In15.Cu")
		(net "P5E_CPU0_PE2_TX_DN<6>")
	)
	(segment
		(start 375.745756 -219.829634)
		(end 375.753122 -219.825316)
		(width 0.0889)
		(layer "In15.Cu")
		(net "P5E_CPU0_PE2_TX_DN<6>")
	)
	(segment
		(start 374.335294 -223.899476)
		(end 374.343168 -223.894904)
		(width 0.0889)
		(layer "In15.Cu")
		(net "P5E_CPU0_PE2_TX_DN<6>")
	)
	(segment
		(start 375.744232 -221.458282)
		(end 375.753122 -221.453202)
		(width 0.0889)
		(layer "In15.Cu")
		(net "P5E_CPU0_PE2_TX_DN<6>")
	)
	(segment
		(start 395.533118 -225.532188)
		(end 399.290286 -248.893584)
		(width 0.14732)
		(layer "In15.Cu")
		(net "P5E_CPU0_PE2_TX_DN<6>")
	)
	(segment
		(start 376.684794 -217.554556)
		(end 376.684032 -217.554048)
		(width 0.0889)
		(layer "In15.Cu")
		(net "P5E_CPU0_PE2_TX_DN<6>")
	)
	(segment
		(start 378.514864 -214.602822)
		(end 379.483112 -213.634828)
		(width 0.0889)
		(layer "In15.Cu")
		(net "P5E_CPU0_PE2_TX_DN<6>")
	)
	(segment
		(start 374.804432 -223.085914)
		(end 374.813322 -223.080834)
		(width 0.0889)
		(layer "In15.Cu")
		(net "P5E_CPU0_PE2_TX_DN<6>")
	)
	(segment
		(start 399.438876 -253.360682)
		(end 399.438622 -253.360682)
		(width 0.14732)
		(layer "In15.Cu")
		(net "P5E_CPU0_PE2_TX_DN<6>")
	)
	(segment
		(start 375.753122 -220.814646)
		(end 375.744232 -220.809566)
		(width 0.0889)
		(layer "In15.Cu")
		(net "P5E_CPU0_PE2_TX_DN<6>")
	)
	(segment
		(start 399.666968 -369.386358)
		(end 399.56105 -399.994628)
		(width 0.14732)
		(layer "In15.Cu")
		(net "P5E_CPU0_PE2_TX_DN<6>")
	)
	(segment
		(start 373.990616 -223.846644)
		(end 374.011698 -223.924622)
		(width 0.0889)
		(layer "In15.Cu")
		(net "P5E_CPU0_PE2_TX_DN<6>")
	)
	(segment
		(start 375.931684 -219.506038)
		(end 375.931684 -219.490544)
		(width 0.0889)
		(layer "In15.Cu")
		(net "P5E_CPU0_PE2_TX_DN<6>")
	)
	(segment
		(start 394.737082 -222.80118)
		(end 395.528292 -225.515932)
		(width 0.14732)
		(layer "In15.Cu")
		(net "P5E_CPU0_PE2_TX_DN<6>")
	)
	(segment
		(start 374.52173 -223.575626)
		(end 374.52173 -223.568006)
		(width 0.0889)
		(layer "In15.Cu")
		(net "P5E_CPU0_PE2_TX_DN<6>")
	)
	(segment
		(start 400.904202 -348.708726)
		(end 399.666968 -369.386358)
		(width 0.14732)
		(layer "In15.Cu")
		(net "P5E_CPU0_PE2_TX_DN<6>")
	)
	(segment
		(start 399.439384 -253.330964)
		(end 399.439892 -253.34595)
		(width 0.14732)
		(layer "In15.Cu")
		(net "P5E_CPU0_PE2_TX_DN<6>")
	)
	(segment
		(start 374.991884 -222.761556)
		(end 374.991884 -222.746062)
		(width 0.0889)
		(layer "In15.Cu")
		(net "P5E_CPU0_PE2_TX_DN<6>")
	)
	(segment
		(start 375.738136 -221.461838)
		(end 375.744232 -221.458282)
		(width 0.0889)
		(layer "In15.Cu")
		(net "P5E_CPU0_PE2_TX_DN<6>")
	)
	(segment
		(start 376.684032 -218.202764)
		(end 376.692922 -218.197684)
		(width 0.0889)
		(layer "In15.Cu")
		(net "P5E_CPU0_PE2_TX_DN<6>")
	)
	(segment
		(start 374.334278 -223.899984)
		(end 374.335294 -223.899476)
		(width 0.0889)
		(layer "In15.Cu")
		(net "P5E_CPU0_PE2_TX_DN<6>")
	)
	(segment
		(start 399.56105 -400.563588)
		(end 399.85569 -400.858228)
		(width 0.14732)
		(layer "In15.Cu")
		(net "P5E_CPU0_PE2_TX_DN<6>")
	)
	(segment
		(start 399.439384 -253.33071)
		(end 399.439384 -253.330964)
		(width 0.14732)
		(layer "In15.Cu")
		(net "P5E_CPU0_PE2_TX_DN<6>")
	)
	(segment
		(start 375.46153 -220.334078)
		(end 375.46153 -220.319854)
		(width 0.0889)
		(layer "In15.Cu")
		(net "P5E_CPU0_PE2_TX_DN<6>")
	)
	(segment
		(start 377.86437 -214.87257)
		(end 378.514864 -214.602822)
		(width 0.0889)
		(layer "In15.Cu")
		(net "P5E_CPU0_PE2_TX_DN<6>")
	)
	(segment
		(start 374.14708 -223.575626)
		(end 373.990616 -223.846644)
		(width 0.0889)
		(layer "In15.Cu")
		(net "P5E_CPU0_PE2_TX_DN<6>")
	)
	(segment
		(start 399.439892 -253.34595)
		(end 399.438876 -253.360682)
		(width 0.14732)
		(layer "In15.Cu")
		(net "P5E_CPU0_PE2_TX_DN<6>")
	)
	(segment
		(start 379.483112 -213.576154)
		(end 379.498606 -213.56066)
		(width 0.0889)
		(layer "In15.Cu")
		(net "P5E_CPU0_PE2_TX_DN<6>")
	)
	(segment
		(start 376.213878 -219.01658)
		(end 376.222768 -219.0115)
		(width 0.0889)
		(layer "In15.Cu")
		(net "P5E_CPU0_PE2_TX_DN<6>")
	)
	(segment
		(start 376.67184 -216.58199)
		(end 376.684032 -216.574878)
		(width 0.0889)
		(layer "In15.Cu")
		(net "P5E_CPU0_PE2_TX_DN<6>")
	)
	(segment
		(start 377.34113 -215.436704)
		(end 377.34113 -215.414606)
		(width 0.0889)
		(layer "In15.Cu")
		(net "P5E_CPU0_PE2_TX_DN<6>")
	)
	(segment
		(start 376.677936 -218.20632)
		(end 376.684032 -218.202764)
		(width 0.0889)
		(layer "In15.Cu")
		(net "P5E_CPU0_PE2_TX_DN<6>")
	)
	(segment
		(start 399.438622 -253.360682)
		(end 395.242542 -308.603396)
		(width 0.14732)
		(layer "In15.Cu")
		(net "P5E_CPU0_PE2_TX_DN<6>")
	)
	(segment
		(start 399.290286 -248.893584)
		(end 399.439384 -253.33071)
		(width 0.14732)
		(layer "In15.Cu")
		(net "P5E_CPU0_PE2_TX_DN<6>")
	)
	(segment
		(start 384.270758 -212.817964)
		(end 388.519924 -214.577676)
		(width 0.14732)
		(layer "In15.Cu")
		(net "P5E_CPU0_PE2_TX_DN<6>")
	)
	(segment
		(start 395.242542 -308.603396)
		(end 402.480018 -339.529928)
		(width 0.14732)
		(layer "In15.Cu")
		(net "P5E_CPU0_PE2_TX_DN<6>")
	)
	(segment
		(start 376.684032 -216.574878)
		(end 376.692922 -216.569798)
		(width 0.0889)
		(layer "In15.Cu")
		(net "P5E_CPU0_PE2_TX_DN<6>")
	)
	(arc
		(start 376.692922 -216.569798)
		(mid 376.823836 -216.433438)
		(end 376.871484 -216.25052)
		(width 0.0889)
		(layer "In15.Cu")
		(net "P5E_CPU0_PE2_TX_DN<6>")
	)
	(arc
		(start 376.871484 -216.235026)
		(mid 376.950854 -215.961292)
		(end 377.153678 -215.761062)
		(width 0.0889)
		(layer "In15.Cu")
		(net "P5E_CPU0_PE2_TX_DN<6>")
	)
	(arc
		(start 374.011698 -223.924622)
		(mid 374.175794 -223.948969)
		(end 374.334278 -223.899984)
		(width 0.0889)
		(layer "In15.Cu")
		(net "P5E_CPU0_PE2_TX_DN<6>")
	)
	(arc
		(start 374.343168 -223.894904)
		(mid 374.474082 -223.758544)
		(end 374.52173 -223.575626)
		(width 0.0889)
		(layer "In15.Cu")
		(net "P5E_CPU0_PE2_TX_DN<6>")
	)
	(arc
		(start 376.684032 -217.554048)
		(mid 376.47896 -217.350369)
		(end 376.40133 -217.071956)
		(width 0.0889)
		(layer "In15.Cu")
		(net "P5E_CPU0_PE2_TX_DN<6>")
	)
	(arc
		(start 377.623324 -214.946992)
		(mid 377.733074 -214.898171)
		(end 377.850654 -214.873586)
		(width 0.0889)
		(layer "In15.Cu")
		(net "P5E_CPU0_PE2_TX_DN<6>")
	)
	(arc
		(start 375.753122 -219.825316)
		(mid 375.884036 -219.688956)
		(end 375.931684 -219.506038)
		(width 0.0889)
		(layer "In15.Cu")
		(net "P5E_CPU0_PE2_TX_DN<6>")
	)
	(arc
		(start 375.744232 -220.809566)
		(mid 375.540751 -220.608762)
		(end 375.46153 -220.334078)
		(width 0.0889)
		(layer "In15.Cu")
		(net "P5E_CPU0_PE2_TX_DN<6>")
	)
	(arc
		(start 376.40133 -217.064336)
		(mid 376.473565 -216.787812)
		(end 376.67184 -216.58199)
		(width 0.0889)
		(layer "In15.Cu")
		(net "P5E_CPU0_PE2_TX_DN<6>")
	)
	(arc
		(start 375.282968 -222.267018)
		(mid 375.413882 -222.130658)
		(end 375.46153 -221.94774)
		(width 0.0889)
		(layer "In15.Cu")
		(net "P5E_CPU0_PE2_TX_DN<6>")
	)
	(arc
		(start 377.34113 -215.414606)
		(mid 377.422041 -215.144478)
		(end 377.623324 -214.946992)
		(width 0.0889)
		(layer "In15.Cu")
		(net "P5E_CPU0_PE2_TX_DN<6>")
	)
	(arc
		(start 374.52173 -223.568006)
		(mid 374.599359 -223.289593)
		(end 374.804432 -223.085914)
		(width 0.0889)
		(layer "In15.Cu")
		(net "P5E_CPU0_PE2_TX_DN<6>")
	)
	(arc
		(start 375.931684 -219.490544)
		(mid 376.011054 -219.21681)
		(end 376.213878 -219.01658)
		(width 0.0889)
		(layer "In15.Cu")
		(net "P5E_CPU0_PE2_TX_DN<6>")
	)
	(arc
		(start 376.40133 -218.692222)
		(mid 376.475321 -218.412656)
		(end 376.677936 -218.20632)
		(width 0.0889)
		(layer "In15.Cu")
		(net "P5E_CPU0_PE2_TX_DN<6>")
	)
	(arc
		(start 377.850654 -214.873586)
		(mid 377.857509 -214.873037)
		(end 377.86437 -214.87257)
		(width 0.0889)
		(layer "In15.Cu")
		(net "P5E_CPU0_PE2_TX_DN<6>")
	)
	(arc
		(start 375.46153 -220.319854)
		(mid 375.535521 -220.040288)
		(end 375.738136 -219.833952)
		(width 0.0889)
		(layer "In15.Cu")
		(net "P5E_CPU0_PE2_TX_DN<6>")
	)
	(arc
		(start 377.162568 -215.755982)
		(mid 377.293482 -215.619622)
		(end 377.34113 -215.436704)
		(width 0.0889)
		(layer "In15.Cu")
		(net "P5E_CPU0_PE2_TX_DN<6>")
	)
	(arc
		(start 376.222768 -219.0115)
		(mid 376.353682 -218.87514)
		(end 376.40133 -218.692222)
		(width 0.0889)
		(layer "In15.Cu")
		(net "P5E_CPU0_PE2_TX_DN<6>")
	)
	(arc
		(start 375.753122 -221.453202)
		(mid 375.931719 -221.133924)
		(end 375.753122 -220.814646)
		(width 0.0889)
		(layer "In15.Cu")
		(net "P5E_CPU0_PE2_TX_DN<6>")
	)
	(arc
		(start 375.46153 -221.94774)
		(mid 375.535521 -221.668174)
		(end 375.738136 -221.461838)
		(width 0.0889)
		(layer "In15.Cu")
		(net "P5E_CPU0_PE2_TX_DN<6>")
	)
	(arc
		(start 376.692922 -218.197684)
		(mid 376.871519 -217.878406)
		(end 376.692922 -217.559128)
		(width 0.0889)
		(layer "In15.Cu")
		(net "P5E_CPU0_PE2_TX_DN<6>")
	)
	(arc
		(start 374.991884 -222.746062)
		(mid 375.071254 -222.472328)
		(end 375.274078 -222.272098)
		(width 0.0889)
		(layer "In15.Cu")
		(net "P5E_CPU0_PE2_TX_DN<6>")
	)
	(arc
		(start 374.813322 -223.080834)
		(mid 374.944236 -222.944474)
		(end 374.991884 -222.761556)
		(width 0.0889)
		(layer "In15.Cu")
		(net "P5E_CPU0_PE2_TX_DN<6>")
	)
	(segment
		(start 402.619972 -401.779994)
		(end 402.94433 -402.104352)
		(width 0.13208)
		(layer "F.Cu")
		(net "P5E_CPU0_PE2_TX_DN<5>")
	)
	(segment
		(start 372.73738 -224.925382)
		(end 372.73738 -224.389696)
		(width 0.13208)
		(layer "F.Cu")
		(net "P5E_CPU0_PE2_TX_DN<5>")
	)
	(segment
		(start 372.73738 -224.389696)
		(end 372.737634 -224.389442)
		(width 0.13208)
		(layer "F.Cu")
		(net "P5E_CPU0_PE2_TX_DN<5>")
	)
	(segment
		(start 402.91893 -400.858228)
		(end 402.619972 -401.157186)
		(width 0.13208)
		(layer "F.Cu")
		(net "P5E_CPU0_PE2_TX_DN<5>")
	)
	(segment
		(start 402.619972 -401.157186)
		(end 402.619972 -401.779994)
		(width 0.13208)
		(layer "F.Cu")
		(net "P5E_CPU0_PE2_TX_DN<5>")
	)
	(segment
		(start 377.725686 -213.45398)
		(end 378.852176 -212.32749)
		(width 0.14732)
		(layer "In15.Cu")
		(net "P5E_CPU0_PE2_TX_DN<5>")
	)
	(segment
		(start 400.373088 -253.397512)
		(end 400.373596 -253.412498)
		(width 0.14732)
		(layer "In15.Cu")
		(net "P5E_CPU0_PE2_TX_DN<5>")
	)
	(segment
		(start 373.864632 -223.085914)
		(end 373.873522 -223.080834)
		(width 0.0889)
		(layer "In15.Cu")
		(net "P5E_CPU0_PE2_TX_DN<5>")
	)
	(segment
		(start 400.372326 -253.42723)
		(end 396.19809 -308.47665)
		(width 0.14732)
		(layer "In15.Cu")
		(net "P5E_CPU0_PE2_TX_DN<5>")
	)
	(segment
		(start 389.32993 -213.896194)
		(end 390.710166 -215.71966)
		(width 0.14732)
		(layer "In15.Cu")
		(net "P5E_CPU0_PE2_TX_DN<5>")
	)
	(segment
		(start 374.804432 -221.458282)
		(end 374.813322 -221.453202)
		(width 0.0889)
		(layer "In15.Cu")
		(net "P5E_CPU0_PE2_TX_DN<5>")
	)
	(segment
		(start 378.852176 -212.32749)
		(end 379.951742 -211.872068)
		(width 0.14732)
		(layer "In15.Cu")
		(net "P5E_CPU0_PE2_TX_DN<5>")
	)
	(segment
		(start 377.710192 -213.469474)
		(end 377.725686 -213.45398)
		(width 0.0889)
		(layer "In15.Cu")
		(net "P5E_CPU0_PE2_TX_DN<5>")
	)
	(segment
		(start 375.741438 -218.204288)
		(end 375.744232 -218.202764)
		(width 0.0889)
		(layer "In15.Cu")
		(net "P5E_CPU0_PE2_TX_DN<5>")
	)
	(segment
		(start 376.401838 -215.41867)
		(end 376.401838 -215.224614)
		(width 0.0889)
		(layer "In15.Cu")
		(net "P5E_CPU0_PE2_TX_DN<5>")
	)
	(segment
		(start 375.744232 -216.574878)
		(end 375.745756 -216.574116)
		(width 0.0889)
		(layer "In15.Cu")
		(net "P5E_CPU0_PE2_TX_DN<5>")
	)
	(segment
		(start 402.62429 -400.563588)
		(end 402.91893 -400.858228)
		(width 0.14732)
		(layer "In15.Cu")
		(net "P5E_CPU0_PE2_TX_DN<5>")
	)
	(segment
		(start 400.373596 -253.412498)
		(end 400.37258 -253.42723)
		(width 0.14732)
		(layer "In15.Cu")
		(net "P5E_CPU0_PE2_TX_DN<5>")
	)
	(segment
		(start 401.985988 -348.279466)
		(end 401.002246 -369.609878)
		(width 0.14732)
		(layer "In15.Cu")
		(net "P5E_CPU0_PE2_TX_DN<5>")
	)
	(segment
		(start 376.401838 -215.224614)
		(end 376.675904 -214.562436)
		(width 0.0889)
		(layer "In15.Cu")
		(net "P5E_CPU0_PE2_TX_DN<5>")
	)
	(segment
		(start 375.46153 -217.07856)
		(end 375.46153 -217.064336)
		(width 0.0889)
		(layer "In15.Cu")
		(net "P5E_CPU0_PE2_TX_DN<5>")
	)
	(segment
		(start 374.804432 -219.830396)
		(end 374.813322 -219.825316)
		(width 0.0889)
		(layer "In15.Cu")
		(net "P5E_CPU0_PE2_TX_DN<5>")
	)
	(segment
		(start 374.991884 -219.506038)
		(end 374.991884 -219.490544)
		(width 0.0889)
		(layer "In15.Cu")
		(net "P5E_CPU0_PE2_TX_DN<5>")
	)
	(segment
		(start 402.62429 -399.849848)
		(end 402.62429 -400.563588)
		(width 0.14732)
		(layer "In15.Cu")
		(net "P5E_CPU0_PE2_TX_DN<5>")
	)
	(segment
		(start 376.213878 -215.761062)
		(end 376.222768 -215.755982)
		(width 0.0889)
		(layer "In15.Cu")
		(net "P5E_CPU0_PE2_TX_DN<5>")
	)
	(segment
		(start 390.710166 -215.71966)
		(end 390.710166 -215.719406)
		(width 0.14732)
		(layer "In15.Cu")
		(net "P5E_CPU0_PE2_TX_DN<5>")
	)
	(segment
		(start 374.052084 -222.761556)
		(end 374.052084 -222.746062)
		(width 0.0889)
		(layer "In15.Cu")
		(net "P5E_CPU0_PE2_TX_DN<5>")
	)
	(segment
		(start 374.79224 -219.837508)
		(end 374.804432 -219.830396)
		(width 0.0889)
		(layer "In15.Cu")
		(net "P5E_CPU0_PE2_TX_DN<5>")
	)
	(segment
		(start 375.931684 -216.25052)
		(end 375.931684 -216.235026)
		(width 0.0889)
		(layer "In15.Cu")
		(net "P5E_CPU0_PE2_TX_DN<5>")
	)
	(segment
		(start 374.805194 -220.810074)
		(end 374.804432 -220.809566)
		(width 0.0889)
		(layer "In15.Cu")
		(net "P5E_CPU0_PE2_TX_DN<5>")
	)
	(segment
		(start 375.745756 -216.574116)
		(end 375.753122 -216.569798)
		(width 0.0889)
		(layer "In15.Cu")
		(net "P5E_CPU0_PE2_TX_DN<5>")
	)
	(segment
		(start 403.476206 -339.688678)
		(end 401.985988 -348.279466)
		(width 0.14732)
		(layer "In15.Cu")
		(net "P5E_CPU0_PE2_TX_DN<5>")
	)
	(segment
		(start 375.744232 -218.202764)
		(end 375.745756 -218.202002)
		(width 0.0889)
		(layer "In15.Cu")
		(net "P5E_CPU0_PE2_TX_DN<5>")
	)
	(segment
		(start 375.738136 -218.20632)
		(end 375.741438 -218.204288)
		(width 0.0889)
		(layer "In15.Cu")
		(net "P5E_CPU0_PE2_TX_DN<5>")
	)
	(segment
		(start 373.112284 -224.389442)
		(end 373.112284 -224.379536)
		(width 0.0889)
		(layer "In15.Cu")
		(net "P5E_CPU0_PE2_TX_DN<5>")
	)
	(segment
		(start 372.894098 -224.66046)
		(end 372.97233 -224.681288)
		(width 0.0889)
		(layer "In15.Cu")
		(net "P5E_CPU0_PE2_TX_DN<5>")
	)
	(segment
		(start 400.373088 -253.397258)
		(end 400.373088 -253.397512)
		(width 0.14732)
		(layer "In15.Cu")
		(net "P5E_CPU0_PE2_TX_DN<5>")
	)
	(segment
		(start 384.443224 -211.872068)
		(end 389.32993 -213.896194)
		(width 0.14732)
		(layer "In15.Cu")
		(net "P5E_CPU0_PE2_TX_DN<5>")
	)
	(segment
		(start 395.513306 -222.064326)
		(end 396.460218 -225.345244)
		(width 0.14732)
		(layer "In15.Cu")
		(net "P5E_CPU0_PE2_TX_DN<5>")
	)
	(segment
		(start 376.675904 -214.562436)
		(end 377.710192 -213.528402)
		(width 0.0889)
		(layer "In15.Cu")
		(net "P5E_CPU0_PE2_TX_DN<5>")
	)
	(segment
		(start 401.002246 -369.609878)
		(end 402.62429 -399.849848)
		(width 0.14732)
		(layer "In15.Cu")
		(net "P5E_CPU0_PE2_TX_DN<5>")
	)
	(segment
		(start 400.37258 -253.42723)
		(end 400.372326 -253.42723)
		(width 0.14732)
		(layer "In15.Cu")
		(net "P5E_CPU0_PE2_TX_DN<5>")
	)
	(segment
		(start 373.58193 -223.584262)
		(end 373.58193 -223.561402)
		(width 0.0889)
		(layer "In15.Cu")
		(net "P5E_CPU0_PE2_TX_DN<5>")
	)
	(segment
		(start 374.52173 -220.327474)
		(end 374.52173 -220.319854)
		(width 0.0889)
		(layer "In15.Cu")
		(net "P5E_CPU0_PE2_TX_DN<5>")
	)
	(segment
		(start 376.40133 -215.436704)
		(end 376.40133 -215.435688)
		(width 0.0889)
		(layer "In15.Cu")
		(net "P5E_CPU0_PE2_TX_DN<5>")
	)
	(segment
		(start 375.745756 -218.202002)
		(end 375.753122 -218.197684)
		(width 0.0889)
		(layer "In15.Cu")
		(net "P5E_CPU0_PE2_TX_DN<5>")
	)
	(segment
		(start 400.21383 -248.663714)
		(end 400.373088 -253.397258)
		(width 0.14732)
		(layer "In15.Cu")
		(net "P5E_CPU0_PE2_TX_DN<5>")
	)
	(segment
		(start 374.798336 -221.461838)
		(end 374.804432 -221.458282)
		(width 0.0889)
		(layer "In15.Cu")
		(net "P5E_CPU0_PE2_TX_DN<5>")
	)
	(segment
		(start 372.737634 -224.389442)
		(end 372.894098 -224.66046)
		(width 0.0889)
		(layer "In15.Cu")
		(net "P5E_CPU0_PE2_TX_DN<5>")
	)
	(segment
		(start 375.274078 -219.01658)
		(end 375.282968 -219.0115)
		(width 0.0889)
		(layer "In15.Cu")
		(net "P5E_CPU0_PE2_TX_DN<5>")
	)
	(segment
		(start 375.753122 -217.559128)
		(end 375.744232 -217.554048)
		(width 0.0889)
		(layer "In15.Cu")
		(net "P5E_CPU0_PE2_TX_DN<5>")
	)
	(segment
		(start 374.813322 -220.814646)
		(end 374.805194 -220.810074)
		(width 0.0889)
		(layer "In15.Cu")
		(net "P5E_CPU0_PE2_TX_DN<5>")
	)
	(segment
		(start 374.334278 -222.272098)
		(end 374.343168 -222.267018)
		(width 0.0889)
		(layer "In15.Cu")
		(net "P5E_CPU0_PE2_TX_DN<5>")
	)
	(segment
		(start 390.710166 -215.719406)
		(end 395.513306 -222.064326)
		(width 0.14732)
		(layer "In15.Cu")
		(net "P5E_CPU0_PE2_TX_DN<5>")
	)
	(segment
		(start 396.19809 -308.47665)
		(end 403.476206 -339.688678)
		(width 0.14732)
		(layer "In15.Cu")
		(net "P5E_CPU0_PE2_TX_DN<5>")
	)
	(segment
		(start 375.738136 -216.578434)
		(end 375.744232 -216.574878)
		(width 0.0889)
		(layer "In15.Cu")
		(net "P5E_CPU0_PE2_TX_DN<5>")
	)
	(segment
		(start 377.710192 -213.528402)
		(end 377.710192 -213.469474)
		(width 0.0889)
		(layer "In15.Cu")
		(net "P5E_CPU0_PE2_TX_DN<5>")
	)
	(segment
		(start 396.460218 -225.345244)
		(end 400.21383 -248.663714)
		(width 0.14732)
		(layer "In15.Cu")
		(net "P5E_CPU0_PE2_TX_DN<5>")
	)
	(segment
		(start 379.951742 -211.872068)
		(end 384.443224 -211.872068)
		(width 0.14732)
		(layer "In15.Cu")
		(net "P5E_CPU0_PE2_TX_DN<5>")
	)
	(arc
		(start 375.744232 -217.554048)
		(mid 375.540751 -217.353244)
		(end 375.46153 -217.07856)
		(width 0.0889)
		(layer "In15.Cu")
		(net "P5E_CPU0_PE2_TX_DN<5>")
	)
	(arc
		(start 374.343168 -222.267018)
		(mid 374.474082 -222.130658)
		(end 374.52173 -221.94774)
		(width 0.0889)
		(layer "In15.Cu")
		(net "P5E_CPU0_PE2_TX_DN<5>")
	)
	(arc
		(start 375.46153 -218.692222)
		(mid 375.535521 -218.412656)
		(end 375.738136 -218.20632)
		(width 0.0889)
		(layer "In15.Cu")
		(net "P5E_CPU0_PE2_TX_DN<5>")
	)
	(arc
		(start 375.931684 -216.235026)
		(mid 376.011054 -215.961292)
		(end 376.213878 -215.761062)
		(width 0.0889)
		(layer "In15.Cu")
		(net "P5E_CPU0_PE2_TX_DN<5>")
	)
	(arc
		(start 375.46153 -217.064336)
		(mid 375.535521 -216.78477)
		(end 375.738136 -216.578434)
		(width 0.0889)
		(layer "In15.Cu")
		(net "P5E_CPU0_PE2_TX_DN<5>")
	)
	(arc
		(start 375.282968 -219.0115)
		(mid 375.413882 -218.87514)
		(end 375.46153 -218.692222)
		(width 0.0889)
		(layer "In15.Cu")
		(net "P5E_CPU0_PE2_TX_DN<5>")
	)
	(arc
		(start 373.873522 -223.080834)
		(mid 374.004436 -222.944474)
		(end 374.052084 -222.761556)
		(width 0.0889)
		(layer "In15.Cu")
		(net "P5E_CPU0_PE2_TX_DN<5>")
	)
	(arc
		(start 374.052084 -222.746062)
		(mid 374.131454 -222.472328)
		(end 374.334278 -222.272098)
		(width 0.0889)
		(layer "In15.Cu")
		(net "P5E_CPU0_PE2_TX_DN<5>")
	)
	(arc
		(start 374.52173 -221.94774)
		(mid 374.595721 -221.668174)
		(end 374.798336 -221.461838)
		(width 0.0889)
		(layer "In15.Cu")
		(net "P5E_CPU0_PE2_TX_DN<5>")
	)
	(arc
		(start 373.58193 -223.561402)
		(mid 373.661149 -223.286717)
		(end 373.864632 -223.085914)
		(width 0.0889)
		(layer "In15.Cu")
		(net "P5E_CPU0_PE2_TX_DN<5>")
	)
	(arc
		(start 374.804432 -220.809566)
		(mid 374.59936 -220.605887)
		(end 374.52173 -220.327474)
		(width 0.0889)
		(layer "In15.Cu")
		(net "P5E_CPU0_PE2_TX_DN<5>")
	)
	(arc
		(start 373.112284 -224.379536)
		(mid 373.190395 -224.102587)
		(end 373.394732 -223.899984)
		(width 0.0889)
		(layer "In15.Cu")
		(net "P5E_CPU0_PE2_TX_DN<5>")
	)
	(arc
		(start 372.97233 -224.681288)
		(mid 373.075475 -224.551263)
		(end 373.112284 -224.389442)
		(width 0.0889)
		(layer "In15.Cu")
		(net "P5E_CPU0_PE2_TX_DN<5>")
	)
	(arc
		(start 375.753122 -216.569798)
		(mid 375.884036 -216.433438)
		(end 375.931684 -216.25052)
		(width 0.0889)
		(layer "In15.Cu")
		(net "P5E_CPU0_PE2_TX_DN<5>")
	)
	(arc
		(start 374.52173 -220.319854)
		(mid 374.593965 -220.04333)
		(end 374.79224 -219.837508)
		(width 0.0889)
		(layer "In15.Cu")
		(net "P5E_CPU0_PE2_TX_DN<5>")
	)
	(arc
		(start 375.753122 -218.197684)
		(mid 375.931719 -217.878406)
		(end 375.753122 -217.559128)
		(width 0.0889)
		(layer "In15.Cu")
		(net "P5E_CPU0_PE2_TX_DN<5>")
	)
	(arc
		(start 374.991884 -219.490544)
		(mid 375.071254 -219.21681)
		(end 375.274078 -219.01658)
		(width 0.0889)
		(layer "In15.Cu")
		(net "P5E_CPU0_PE2_TX_DN<5>")
	)
	(arc
		(start 374.813322 -219.825316)
		(mid 374.944236 -219.688956)
		(end 374.991884 -219.506038)
		(width 0.0889)
		(layer "In15.Cu")
		(net "P5E_CPU0_PE2_TX_DN<5>")
	)
	(arc
		(start 373.394732 -223.899984)
		(mid 373.529665 -223.76663)
		(end 373.58193 -223.584262)
		(width 0.0889)
		(layer "In15.Cu")
		(net "P5E_CPU0_PE2_TX_DN<5>")
	)
	(arc
		(start 374.813322 -221.453202)
		(mid 374.991919 -221.133924)
		(end 374.813322 -220.814646)
		(width 0.0889)
		(layer "In15.Cu")
		(net "P5E_CPU0_PE2_TX_DN<5>")
	)
	(arc
		(start 376.40133 -215.435688)
		(mid 376.40152 -215.427177)
		(end 376.401838 -215.41867)
		(width 0.0889)
		(layer "In15.Cu")
		(net "P5E_CPU0_PE2_TX_DN<5>")
	)
	(arc
		(start 376.222768 -215.755982)
		(mid 376.353682 -215.619622)
		(end 376.40133 -215.436704)
		(width 0.0889)
		(layer "In15.Cu")
		(net "P5E_CPU0_PE2_TX_DN<5>")
	)
	(segment
		(start 372.267734 -223.57588)
		(end 372.26748 -223.575626)
		(width 0.13208)
		(layer "F.Cu")
		(net "P5E_CPU0_PE2_TX_DN<4>")
	)
	(segment
		(start 372.267734 -224.111566)
		(end 372.267734 -223.57588)
		(width 0.13208)
		(layer "F.Cu")
		(net "P5E_CPU0_PE2_TX_DN<4>")
	)
	(segment
		(start 405.683212 -401.779994)
		(end 406.00757 -402.104352)
		(width 0.13208)
		(layer "F.Cu")
		(net "P5E_CPU0_PE2_TX_DN<4>")
	)
	(segment
		(start 405.683212 -401.157186)
		(end 405.683212 -401.779994)
		(width 0.13208)
		(layer "F.Cu")
		(net "P5E_CPU0_PE2_TX_DN<4>")
	)
	(segment
		(start 405.98217 -400.858228)
		(end 405.683212 -401.157186)
		(width 0.13208)
		(layer "F.Cu")
		(net "P5E_CPU0_PE2_TX_DN<4>")
	)
	(segment
		(start 372.454678 -223.899984)
		(end 372.455694 -223.899476)
		(width 0.0889)
		(layer "In15.Cu")
		(net "P5E_CPU0_PE2_TX_DN<4>")
	)
	(segment
		(start 405.68753 -399.743168)
		(end 405.68753 -400.563588)
		(width 0.14732)
		(layer "In15.Cu")
		(net "P5E_CPU0_PE2_TX_DN<4>")
	)
	(segment
		(start 374.813322 -217.559128)
		(end 374.805194 -217.554556)
		(width 0.0889)
		(layer "In15.Cu")
		(net "P5E_CPU0_PE2_TX_DN<4>")
	)
	(segment
		(start 373.864632 -219.830396)
		(end 373.866156 -219.829634)
		(width 0.0889)
		(layer "In15.Cu")
		(net "P5E_CPU0_PE2_TX_DN<4>")
	)
	(segment
		(start 374.798336 -218.20632)
		(end 374.804432 -218.202764)
		(width 0.0889)
		(layer "In15.Cu")
		(net "P5E_CPU0_PE2_TX_DN<4>")
	)
	(segment
		(start 376.401584 -213.387178)
		(end 376.35942 -213.345014)
		(width 0.0889)
		(layer "In15.Cu")
		(net "P5E_CPU0_PE2_TX_DN<4>")
	)
	(segment
		(start 376.35942 -212.931756)
		(end 377.380246 -211.91093)
		(width 0.14732)
		(layer "In15.Cu")
		(net "P5E_CPU0_PE2_TX_DN<4>")
	)
	(segment
		(start 376.35942 -213.345014)
		(end 376.35942 -213.322916)
		(width 0.0889)
		(layer "In15.Cu")
		(net "P5E_CPU0_PE2_TX_DN<4>")
	)
	(segment
		(start 373.112284 -222.761556)
		(end 373.112284 -222.746062)
		(width 0.0889)
		(layer "In15.Cu")
		(net "P5E_CPU0_PE2_TX_DN<4>")
	)
	(segment
		(start 402.968968 -348.228666)
		(end 402.34489 -369.559078)
		(width 0.14732)
		(layer "In15.Cu")
		(net "P5E_CPU0_PE2_TX_DN<4>")
	)
	(segment
		(start 374.805194 -217.554556)
		(end 374.804432 -217.554048)
		(width 0.0889)
		(layer "In15.Cu")
		(net "P5E_CPU0_PE2_TX_DN<4>")
	)
	(segment
		(start 396.46225 -221.747588)
		(end 397.849598 -226.545394)
		(width 0.14732)
		(layer "In15.Cu")
		(net "P5E_CPU0_PE2_TX_DN<4>")
	)
	(segment
		(start 379.735842 -210.935316)
		(end 384.645154 -210.935316)
		(width 0.14732)
		(layer "In15.Cu")
		(net "P5E_CPU0_PE2_TX_DN<4>")
	)
	(segment
		(start 404.500588 -339.600794)
		(end 404.500842 -339.600794)
		(width 0.14732)
		(layer "In15.Cu")
		(net "P5E_CPU0_PE2_TX_DN<4>")
	)
	(segment
		(start 372.64213 -223.575626)
		(end 372.64213 -223.568006)
		(width 0.0889)
		(layer "In15.Cu")
		(net "P5E_CPU0_PE2_TX_DN<4>")
	)
	(segment
		(start 374.334278 -219.01658)
		(end 374.343168 -219.0115)
		(width 0.0889)
		(layer "In15.Cu")
		(net "P5E_CPU0_PE2_TX_DN<4>")
	)
	(segment
		(start 373.858536 -219.833952)
		(end 373.864632 -219.830396)
		(width 0.0889)
		(layer "In15.Cu")
		(net "P5E_CPU0_PE2_TX_DN<4>")
	)
	(segment
		(start 374.79224 -216.58199)
		(end 374.804432 -216.574878)
		(width 0.0889)
		(layer "In15.Cu")
		(net "P5E_CPU0_PE2_TX_DN<4>")
	)
	(segment
		(start 373.866156 -219.829634)
		(end 373.873522 -219.825316)
		(width 0.0889)
		(layer "In15.Cu")
		(net "P5E_CPU0_PE2_TX_DN<4>")
	)
	(segment
		(start 404.513542 -339.655912)
		(end 402.968968 -348.228666)
		(width 0.14732)
		(layer "In15.Cu")
		(net "P5E_CPU0_PE2_TX_DN<4>")
	)
	(segment
		(start 374.52173 -217.071956)
		(end 374.52173 -217.064336)
		(width 0.0889)
		(layer "In15.Cu")
		(net "P5E_CPU0_PE2_TX_DN<4>")
	)
	(segment
		(start 373.864632 -221.458282)
		(end 373.873522 -221.453202)
		(width 0.0889)
		(layer "In15.Cu")
		(net "P5E_CPU0_PE2_TX_DN<4>")
	)
	(segment
		(start 373.873522 -220.814646)
		(end 373.864632 -220.809566)
		(width 0.0889)
		(layer "In15.Cu")
		(net "P5E_CPU0_PE2_TX_DN<4>")
	)
	(segment
		(start 374.804432 -218.202764)
		(end 374.813322 -218.197684)
		(width 0.0889)
		(layer "In15.Cu")
		(net "P5E_CPU0_PE2_TX_DN<4>")
	)
	(segment
		(start 402.34489 -369.559078)
		(end 405.68753 -399.743168)
		(width 0.14732)
		(layer "In15.Cu")
		(net "P5E_CPU0_PE2_TX_DN<4>")
	)
	(segment
		(start 397.170656 -308.155086)
		(end 404.500588 -339.600794)
		(width 0.14732)
		(layer "In15.Cu")
		(net "P5E_CPU0_PE2_TX_DN<4>")
	)
	(segment
		(start 389.950198 -213.132416)
		(end 396.46225 -221.747588)
		(width 0.14732)
		(layer "In15.Cu")
		(net "P5E_CPU0_PE2_TX_DN<4>")
	)
	(segment
		(start 384.645154 -210.935316)
		(end 389.950198 -213.132416)
		(width 0.14732)
		(layer "In15.Cu")
		(net "P5E_CPU0_PE2_TX_DN<4>")
	)
	(segment
		(start 374.991884 -216.25052)
		(end 374.991884 -216.240614)
		(width 0.0889)
		(layer "In15.Cu")
		(net "P5E_CPU0_PE2_TX_DN<4>")
	)
	(segment
		(start 374.052084 -219.506038)
		(end 374.052084 -219.490544)
		(width 0.0889)
		(layer "In15.Cu")
		(net "P5E_CPU0_PE2_TX_DN<4>")
	)
	(segment
		(start 375.462038 -215.238584)
		(end 375.66473 -214.748364)
		(width 0.0889)
		(layer "In15.Cu")
		(net "P5E_CPU0_PE2_TX_DN<4>")
	)
	(segment
		(start 375.462038 -215.423242)
		(end 375.462038 -215.238584)
		(width 0.0889)
		(layer "In15.Cu")
		(net "P5E_CPU0_PE2_TX_DN<4>")
	)
	(segment
		(start 373.58193 -220.334078)
		(end 373.58193 -220.319854)
		(width 0.0889)
		(layer "In15.Cu")
		(net "P5E_CPU0_PE2_TX_DN<4>")
	)
	(segment
		(start 401.1295 -248.275602)
		(end 401.129754 -248.275602)
		(width 0.14732)
		(layer "In15.Cu")
		(net "P5E_CPU0_PE2_TX_DN<4>")
	)
	(segment
		(start 373.858536 -221.461838)
		(end 373.864632 -221.458282)
		(width 0.0889)
		(layer "In15.Cu")
		(net "P5E_CPU0_PE2_TX_DN<4>")
	)
	(segment
		(start 376.193304 -214.21979)
		(end 376.401584 -213.717632)
		(width 0.0889)
		(layer "In15.Cu")
		(net "P5E_CPU0_PE2_TX_DN<4>")
	)
	(segment
		(start 401.13204 -248.29135)
		(end 401.305014 -253.441454)
		(width 0.14732)
		(layer "In15.Cu")
		(net "P5E_CPU0_PE2_TX_DN<4>")
	)
	(segment
		(start 377.380246 -211.91093)
		(end 379.735842 -210.935316)
		(width 0.14732)
		(layer "In15.Cu")
		(net "P5E_CPU0_PE2_TX_DN<4>")
	)
	(segment
		(start 401.129754 -248.275602)
		(end 401.13204 -248.29135)
		(width 0.14732)
		(layer "In15.Cu")
		(net "P5E_CPU0_PE2_TX_DN<4>")
	)
	(segment
		(start 404.500842 -339.600794)
		(end 404.513542 -339.655912)
		(width 0.14732)
		(layer "In15.Cu")
		(net "P5E_CPU0_PE2_TX_DN<4>")
	)
	(segment
		(start 372.455694 -223.899476)
		(end 372.463568 -223.894904)
		(width 0.0889)
		(layer "In15.Cu")
		(net "P5E_CPU0_PE2_TX_DN<4>")
	)
	(segment
		(start 401.305014 -253.441454)
		(end 397.170656 -308.155086)
		(width 0.14732)
		(layer "In15.Cu")
		(net "P5E_CPU0_PE2_TX_DN<4>")
	)
	(segment
		(start 373.394478 -222.272098)
		(end 373.403368 -222.267018)
		(width 0.0889)
		(layer "In15.Cu")
		(net "P5E_CPU0_PE2_TX_DN<4>")
	)
	(segment
		(start 375.46153 -215.44534)
		(end 375.462038 -215.423242)
		(width 0.0889)
		(layer "In15.Cu")
		(net "P5E_CPU0_PE2_TX_DN<4>")
	)
	(segment
		(start 372.924832 -223.085914)
		(end 372.933722 -223.080834)
		(width 0.0889)
		(layer "In15.Cu")
		(net "P5E_CPU0_PE2_TX_DN<4>")
	)
	(segment
		(start 372.111016 -223.846644)
		(end 372.132098 -223.924622)
		(width 0.0889)
		(layer "In15.Cu")
		(net "P5E_CPU0_PE2_TX_DN<4>")
	)
	(segment
		(start 376.35942 -213.322916)
		(end 376.35942 -212.931756)
		(width 0.14732)
		(layer "In15.Cu")
		(net "P5E_CPU0_PE2_TX_DN<4>")
	)
	(segment
		(start 405.68753 -400.563588)
		(end 405.98217 -400.858228)
		(width 0.14732)
		(layer "In15.Cu")
		(net "P5E_CPU0_PE2_TX_DN<4>")
	)
	(segment
		(start 372.26748 -223.575626)
		(end 372.111016 -223.846644)
		(width 0.0889)
		(layer "In15.Cu")
		(net "P5E_CPU0_PE2_TX_DN<4>")
	)
	(segment
		(start 374.804432 -216.574878)
		(end 374.813322 -216.569798)
		(width 0.0889)
		(layer "In15.Cu")
		(net "P5E_CPU0_PE2_TX_DN<4>")
	)
	(segment
		(start 375.66473 -214.748364)
		(end 376.193304 -214.21979)
		(width 0.0889)
		(layer "In15.Cu")
		(net "P5E_CPU0_PE2_TX_DN<4>")
	)
	(segment
		(start 397.849598 -226.545394)
		(end 401.1295 -248.275602)
		(width 0.14732)
		(layer "In15.Cu")
		(net "P5E_CPU0_PE2_TX_DN<4>")
	)
	(segment
		(start 376.401584 -213.717632)
		(end 376.401584 -213.387178)
		(width 0.0889)
		(layer "In15.Cu")
		(net "P5E_CPU0_PE2_TX_DN<4>")
	)
	(arc
		(start 374.991884 -216.240614)
		(mid 375.069995 -215.963665)
		(end 375.274332 -215.761062)
		(width 0.0889)
		(layer "In15.Cu")
		(net "P5E_CPU0_PE2_TX_DN<4>")
	)
	(arc
		(start 373.58193 -221.94774)
		(mid 373.655921 -221.668174)
		(end 373.858536 -221.461838)
		(width 0.0889)
		(layer "In15.Cu")
		(net "P5E_CPU0_PE2_TX_DN<4>")
	)
	(arc
		(start 373.403368 -222.267018)
		(mid 373.534282 -222.130658)
		(end 373.58193 -221.94774)
		(width 0.0889)
		(layer "In15.Cu")
		(net "P5E_CPU0_PE2_TX_DN<4>")
	)
	(arc
		(start 373.864632 -220.809566)
		(mid 373.661151 -220.608762)
		(end 373.58193 -220.334078)
		(width 0.0889)
		(layer "In15.Cu")
		(net "P5E_CPU0_PE2_TX_DN<4>")
	)
	(arc
		(start 374.52173 -217.064336)
		(mid 374.593965 -216.787812)
		(end 374.79224 -216.58199)
		(width 0.0889)
		(layer "In15.Cu")
		(net "P5E_CPU0_PE2_TX_DN<4>")
	)
	(arc
		(start 373.58193 -220.319854)
		(mid 373.655921 -220.040288)
		(end 373.858536 -219.833952)
		(width 0.0889)
		(layer "In15.Cu")
		(net "P5E_CPU0_PE2_TX_DN<4>")
	)
	(arc
		(start 372.132098 -223.924622)
		(mid 372.296194 -223.948969)
		(end 372.454678 -223.899984)
		(width 0.0889)
		(layer "In15.Cu")
		(net "P5E_CPU0_PE2_TX_DN<4>")
	)
	(arc
		(start 372.64213 -223.568006)
		(mid 372.719759 -223.289593)
		(end 372.924832 -223.085914)
		(width 0.0889)
		(layer "In15.Cu")
		(net "P5E_CPU0_PE2_TX_DN<4>")
	)
	(arc
		(start 374.813322 -218.197684)
		(mid 374.991919 -217.878406)
		(end 374.813322 -217.559128)
		(width 0.0889)
		(layer "In15.Cu")
		(net "P5E_CPU0_PE2_TX_DN<4>")
	)
	(arc
		(start 373.873522 -221.453202)
		(mid 374.052119 -221.133924)
		(end 373.873522 -220.814646)
		(width 0.0889)
		(layer "In15.Cu")
		(net "P5E_CPU0_PE2_TX_DN<4>")
	)
	(arc
		(start 372.463568 -223.894904)
		(mid 372.594482 -223.758544)
		(end 372.64213 -223.575626)
		(width 0.0889)
		(layer "In15.Cu")
		(net "P5E_CPU0_PE2_TX_DN<4>")
	)
	(arc
		(start 374.052084 -219.490544)
		(mid 374.131454 -219.21681)
		(end 374.334278 -219.01658)
		(width 0.0889)
		(layer "In15.Cu")
		(net "P5E_CPU0_PE2_TX_DN<4>")
	)
	(arc
		(start 374.52173 -218.692222)
		(mid 374.595721 -218.412656)
		(end 374.798336 -218.20632)
		(width 0.0889)
		(layer "In15.Cu")
		(net "P5E_CPU0_PE2_TX_DN<4>")
	)
	(arc
		(start 373.873522 -219.825316)
		(mid 374.004436 -219.688956)
		(end 374.052084 -219.506038)
		(width 0.0889)
		(layer "In15.Cu")
		(net "P5E_CPU0_PE2_TX_DN<4>")
	)
	(arc
		(start 373.112284 -222.746062)
		(mid 373.191654 -222.472328)
		(end 373.394478 -222.272098)
		(width 0.0889)
		(layer "In15.Cu")
		(net "P5E_CPU0_PE2_TX_DN<4>")
	)
	(arc
		(start 372.933722 -223.080834)
		(mid 373.064636 -222.944474)
		(end 373.112284 -222.761556)
		(width 0.0889)
		(layer "In15.Cu")
		(net "P5E_CPU0_PE2_TX_DN<4>")
	)
	(arc
		(start 375.274332 -215.761062)
		(mid 375.409265 -215.627708)
		(end 375.46153 -215.44534)
		(width 0.0889)
		(layer "In15.Cu")
		(net "P5E_CPU0_PE2_TX_DN<4>")
	)
	(arc
		(start 374.343168 -219.0115)
		(mid 374.474082 -218.87514)
		(end 374.52173 -218.692222)
		(width 0.0889)
		(layer "In15.Cu")
		(net "P5E_CPU0_PE2_TX_DN<4>")
	)
	(arc
		(start 374.813322 -216.569798)
		(mid 374.944236 -216.433438)
		(end 374.991884 -216.25052)
		(width 0.0889)
		(layer "In15.Cu")
		(net "P5E_CPU0_PE2_TX_DN<4>")
	)
	(arc
		(start 374.804432 -217.554048)
		(mid 374.59936 -217.350369)
		(end 374.52173 -217.071956)
		(width 0.0889)
		(layer "In15.Cu")
		(net "P5E_CPU0_PE2_TX_DN<4>")
	)
	(segment
		(start 408.746452 -401.157186)
		(end 408.746452 -401.779994)
		(width 0.13208)
		(layer "F.Cu")
		(net "P5E_CPU0_PE2_TX_DN<3>")
	)
	(segment
		(start 409.04541 -400.858228)
		(end 408.746452 -401.157186)
		(width 0.13208)
		(layer "F.Cu")
		(net "P5E_CPU0_PE2_TX_DN<3>")
	)
	(segment
		(start 408.746452 -401.779994)
		(end 409.07081 -402.104352)
		(width 0.13208)
		(layer "F.Cu")
		(net "P5E_CPU0_PE2_TX_DN<3>")
	)
	(segment
		(start 370.85778 -224.389696)
		(end 370.858034 -224.389442)
		(width 0.13208)
		(layer "F.Cu")
		(net "P5E_CPU0_PE2_TX_DN<3>")
	)
	(segment
		(start 370.85778 -224.925382)
		(end 370.85778 -224.389696)
		(width 0.13208)
		(layer "F.Cu")
		(net "P5E_CPU0_PE2_TX_DN<3>")
	)
	(segment
		(start 371.70233 -223.584262)
		(end 371.70233 -223.561402)
		(width 0.0889)
		(layer "In15.Cu")
		(net "P5E_CPU0_PE2_TX_DN<3>")
	)
	(segment
		(start 403.586188 -369.587018)
		(end 408.75077 -400.002248)
		(width 0.14732)
		(layer "In15.Cu")
		(net "P5E_CPU0_PE2_TX_DN<3>")
	)
	(segment
		(start 402.251672 -253.704852)
		(end 398.143222 -307.835554)
		(width 0.14732)
		(layer "In15.Cu")
		(net "P5E_CPU0_PE2_TX_DN<3>")
	)
	(segment
		(start 408.75077 -400.002248)
		(end 408.75077 -400.563588)
		(width 0.14732)
		(layer "In15.Cu")
		(net "P5E_CPU0_PE2_TX_DN<3>")
	)
	(segment
		(start 372.454678 -222.272098)
		(end 372.463568 -222.267018)
		(width 0.0889)
		(layer "In15.Cu")
		(net "P5E_CPU0_PE2_TX_DN<3>")
	)
	(segment
		(start 374.052084 -216.25052)
		(end 374.052084 -216.235026)
		(width 0.0889)
		(layer "In15.Cu")
		(net "P5E_CPU0_PE2_TX_DN<3>")
	)
	(segment
		(start 370.858034 -224.389442)
		(end 371.014498 -224.66046)
		(width 0.0889)
		(layer "In15.Cu")
		(net "P5E_CPU0_PE2_TX_DN<3>")
	)
	(segment
		(start 392.039094 -214.06866)
		(end 392.039094 -214.068406)
		(width 0.14732)
		(layer "In15.Cu")
		(net "P5E_CPU0_PE2_TX_DN<3>")
	)
	(segment
		(start 387.839712 -211.22259)
		(end 390.820656 -212.45703)
		(width 0.14732)
		(layer "In15.Cu")
		(net "P5E_CPU0_PE2_TX_DN<3>")
	)
	(segment
		(start 372.924832 -219.830396)
		(end 372.933722 -219.825316)
		(width 0.0889)
		(layer "In15.Cu")
		(net "P5E_CPU0_PE2_TX_DN<3>")
	)
	(segment
		(start 387.839712 -211.222336)
		(end 387.839712 -211.22259)
		(width 0.14732)
		(layer "In15.Cu")
		(net "P5E_CPU0_PE2_TX_DN<3>")
	)
	(segment
		(start 373.864632 -218.202764)
		(end 373.873522 -218.197684)
		(width 0.0889)
		(layer "In15.Cu")
		(net "P5E_CPU0_PE2_TX_DN<3>")
	)
	(segment
		(start 373.873522 -217.559128)
		(end 373.864632 -217.554048)
		(width 0.0889)
		(layer "In15.Cu")
		(net "P5E_CPU0_PE2_TX_DN<3>")
	)
	(segment
		(start 403.962362 -348.103444)
		(end 403.586188 -369.587018)
		(width 0.14732)
		(layer "In15.Cu")
		(net "P5E_CPU0_PE2_TX_DN<3>")
	)
	(segment
		(start 373.394478 -219.01658)
		(end 373.403368 -219.0115)
		(width 0.0889)
		(layer "In15.Cu")
		(net "P5E_CPU0_PE2_TX_DN<3>")
	)
	(segment
		(start 373.858536 -216.578434)
		(end 373.864632 -216.574878)
		(width 0.0889)
		(layer "In15.Cu")
		(net "P5E_CPU0_PE2_TX_DN<3>")
	)
	(segment
		(start 372.925594 -220.810074)
		(end 372.924832 -220.809566)
		(width 0.0889)
		(layer "In15.Cu")
		(net "P5E_CPU0_PE2_TX_DN<3>")
	)
	(segment
		(start 374.52173 -215.436704)
		(end 374.521984 -215.43645)
		(width 0.0889)
		(layer "In15.Cu")
		(net "P5E_CPU0_PE2_TX_DN<3>")
	)
	(segment
		(start 408.75077 -400.563588)
		(end 409.04541 -400.858228)
		(width 0.14732)
		(layer "In15.Cu")
		(net "P5E_CPU0_PE2_TX_DN<3>")
	)
	(segment
		(start 374.334278 -215.761062)
		(end 374.343168 -215.755982)
		(width 0.0889)
		(layer "In15.Cu")
		(net "P5E_CPU0_PE2_TX_DN<3>")
	)
	(segment
		(start 374.719088 -214.77224)
		(end 375.327418 -214.16391)
		(width 0.0889)
		(layer "In15.Cu")
		(net "P5E_CPU0_PE2_TX_DN<3>")
	)
	(segment
		(start 375.327418 -214.16391)
		(end 375.461276 -213.840568)
		(width 0.0889)
		(layer "In15.Cu")
		(net "P5E_CPU0_PE2_TX_DN<3>")
	)
	(segment
		(start 375.419112 -213.322916)
		(end 375.419112 -212.497924)
		(width 0.14732)
		(layer "In15.Cu")
		(net "P5E_CPU0_PE2_TX_DN<3>")
	)
	(segment
		(start 392.039094 -214.068406)
		(end 397.312642 -221.0435)
		(width 0.14732)
		(layer "In15.Cu")
		(net "P5E_CPU0_PE2_TX_DN<3>")
	)
	(segment
		(start 373.858536 -218.20632)
		(end 373.864632 -218.202764)
		(width 0.0889)
		(layer "In15.Cu")
		(net "P5E_CPU0_PE2_TX_DN<3>")
	)
	(segment
		(start 371.232684 -224.389442)
		(end 371.232684 -224.379536)
		(width 0.0889)
		(layer "In15.Cu")
		(net "P5E_CPU0_PE2_TX_DN<3>")
	)
	(segment
		(start 372.933722 -220.814646)
		(end 372.925594 -220.810074)
		(width 0.0889)
		(layer "In15.Cu")
		(net "P5E_CPU0_PE2_TX_DN<3>")
	)
	(segment
		(start 375.461276 -213.387178)
		(end 375.419112 -213.345014)
		(width 0.0889)
		(layer "In15.Cu")
		(net "P5E_CPU0_PE2_TX_DN<3>")
	)
	(segment
		(start 372.918736 -221.461838)
		(end 372.924832 -221.458282)
		(width 0.0889)
		(layer "In15.Cu")
		(net "P5E_CPU0_PE2_TX_DN<3>")
	)
	(segment
		(start 405.485854 -339.686138)
		(end 403.962362 -348.103444)
		(width 0.14732)
		(layer "In15.Cu")
		(net "P5E_CPU0_PE2_TX_DN<3>")
	)
	(segment
		(start 372.172484 -222.761556)
		(end 372.172484 -222.746062)
		(width 0.0889)
		(layer "In15.Cu")
		(net "P5E_CPU0_PE2_TX_DN<3>")
	)
	(segment
		(start 402.058378 -247.96115)
		(end 402.251672 -253.704852)
		(width 0.14732)
		(layer "In15.Cu")
		(net "P5E_CPU0_PE2_TX_DN<3>")
	)
	(segment
		(start 371.014498 -224.66046)
		(end 371.09273 -224.681288)
		(width 0.0889)
		(layer "In15.Cu")
		(net "P5E_CPU0_PE2_TX_DN<3>")
	)
	(segment
		(start 398.838674 -226.624896)
		(end 402.058378 -247.96115)
		(width 0.14732)
		(layer "In15.Cu")
		(net "P5E_CPU0_PE2_TX_DN<3>")
	)
	(segment
		(start 379.53696 -209.995516)
		(end 384.876802 -209.995516)
		(width 0.14732)
		(layer "In15.Cu")
		(net "P5E_CPU0_PE2_TX_DN<3>")
	)
	(segment
		(start 375.419112 -213.345014)
		(end 375.419112 -213.322916)
		(width 0.0889)
		(layer "In15.Cu")
		(net "P5E_CPU0_PE2_TX_DN<3>")
	)
	(segment
		(start 371.985032 -223.085914)
		(end 371.993922 -223.080834)
		(width 0.0889)
		(layer "In15.Cu")
		(net "P5E_CPU0_PE2_TX_DN<3>")
	)
	(segment
		(start 390.820656 -212.45703)
		(end 392.039094 -214.06866)
		(width 0.14732)
		(layer "In15.Cu")
		(net "P5E_CPU0_PE2_TX_DN<3>")
	)
	(segment
		(start 372.91264 -219.837508)
		(end 372.924832 -219.830396)
		(width 0.0889)
		(layer "In15.Cu")
		(net "P5E_CPU0_PE2_TX_DN<3>")
	)
	(segment
		(start 398.143222 -307.835554)
		(end 405.485854 -339.686138)
		(width 0.14732)
		(layer "In15.Cu")
		(net "P5E_CPU0_PE2_TX_DN<3>")
	)
	(segment
		(start 373.112284 -219.506038)
		(end 373.112284 -219.490544)
		(width 0.0889)
		(layer "In15.Cu")
		(net "P5E_CPU0_PE2_TX_DN<3>")
	)
	(segment
		(start 375.461276 -213.840568)
		(end 375.461276 -213.387178)
		(width 0.0889)
		(layer "In15.Cu")
		(net "P5E_CPU0_PE2_TX_DN<3>")
	)
	(segment
		(start 374.521984 -215.247982)
		(end 374.719088 -214.77224)
		(width 0.0889)
		(layer "In15.Cu")
		(net "P5E_CPU0_PE2_TX_DN<3>")
	)
	(segment
		(start 372.64213 -220.327474)
		(end 372.64213 -220.319854)
		(width 0.0889)
		(layer "In15.Cu")
		(net "P5E_CPU0_PE2_TX_DN<3>")
	)
	(segment
		(start 373.864632 -216.574878)
		(end 373.866156 -216.574116)
		(width 0.0889)
		(layer "In15.Cu")
		(net "P5E_CPU0_PE2_TX_DN<3>")
	)
	(segment
		(start 374.521984 -215.43645)
		(end 374.521984 -215.247982)
		(width 0.0889)
		(layer "In15.Cu")
		(net "P5E_CPU0_PE2_TX_DN<3>")
	)
	(segment
		(start 375.419112 -212.497924)
		(end 376.779536 -211.1375)
		(width 0.14732)
		(layer "In15.Cu")
		(net "P5E_CPU0_PE2_TX_DN<3>")
	)
	(segment
		(start 373.58193 -217.07856)
		(end 373.58193 -217.064336)
		(width 0.0889)
		(layer "In15.Cu")
		(net "P5E_CPU0_PE2_TX_DN<3>")
	)
	(segment
		(start 372.924832 -221.458282)
		(end 372.933722 -221.453202)
		(width 0.0889)
		(layer "In15.Cu")
		(net "P5E_CPU0_PE2_TX_DN<3>")
	)
	(segment
		(start 376.779536 -211.1375)
		(end 379.53696 -209.995516)
		(width 0.14732)
		(layer "In15.Cu")
		(net "P5E_CPU0_PE2_TX_DN<3>")
	)
	(segment
		(start 373.866156 -216.574116)
		(end 373.873522 -216.569798)
		(width 0.0889)
		(layer "In15.Cu")
		(net "P5E_CPU0_PE2_TX_DN<3>")
	)
	(segment
		(start 397.312642 -221.0435)
		(end 398.838674 -226.624896)
		(width 0.14732)
		(layer "In15.Cu")
		(net "P5E_CPU0_PE2_TX_DN<3>")
	)
	(segment
		(start 384.876802 -209.995516)
		(end 387.839712 -211.222336)
		(width 0.14732)
		(layer "In15.Cu")
		(net "P5E_CPU0_PE2_TX_DN<3>")
	)
	(arc
		(start 373.58193 -217.064336)
		(mid 373.655921 -216.78477)
		(end 373.858536 -216.578434)
		(width 0.0889)
		(layer "In15.Cu")
		(net "P5E_CPU0_PE2_TX_DN<3>")
	)
	(arc
		(start 373.864632 -217.554048)
		(mid 373.661151 -217.353244)
		(end 373.58193 -217.07856)
		(width 0.0889)
		(layer "In15.Cu")
		(net "P5E_CPU0_PE2_TX_DN<3>")
	)
	(arc
		(start 372.933722 -219.825316)
		(mid 373.064636 -219.688956)
		(end 373.112284 -219.506038)
		(width 0.0889)
		(layer "In15.Cu")
		(net "P5E_CPU0_PE2_TX_DN<3>")
	)
	(arc
		(start 371.232684 -224.379536)
		(mid 371.310795 -224.102587)
		(end 371.515132 -223.899984)
		(width 0.0889)
		(layer "In15.Cu")
		(net "P5E_CPU0_PE2_TX_DN<3>")
	)
	(arc
		(start 373.58193 -218.692222)
		(mid 373.655921 -218.412656)
		(end 373.858536 -218.20632)
		(width 0.0889)
		(layer "In15.Cu")
		(net "P5E_CPU0_PE2_TX_DN<3>")
	)
	(arc
		(start 371.70233 -223.561402)
		(mid 371.781549 -223.286717)
		(end 371.985032 -223.085914)
		(width 0.0889)
		(layer "In15.Cu")
		(net "P5E_CPU0_PE2_TX_DN<3>")
	)
	(arc
		(start 371.993922 -223.080834)
		(mid 372.124836 -222.944474)
		(end 372.172484 -222.761556)
		(width 0.0889)
		(layer "In15.Cu")
		(net "P5E_CPU0_PE2_TX_DN<3>")
	)
	(arc
		(start 373.873522 -218.197684)
		(mid 374.052119 -217.878406)
		(end 373.873522 -217.559128)
		(width 0.0889)
		(layer "In15.Cu")
		(net "P5E_CPU0_PE2_TX_DN<3>")
	)
	(arc
		(start 372.463568 -222.267018)
		(mid 372.594482 -222.130658)
		(end 372.64213 -221.94774)
		(width 0.0889)
		(layer "In15.Cu")
		(net "P5E_CPU0_PE2_TX_DN<3>")
	)
	(arc
		(start 372.933722 -221.453202)
		(mid 373.112319 -221.133924)
		(end 372.933722 -220.814646)
		(width 0.0889)
		(layer "In15.Cu")
		(net "P5E_CPU0_PE2_TX_DN<3>")
	)
	(arc
		(start 372.172484 -222.746062)
		(mid 372.251854 -222.472328)
		(end 372.454678 -222.272098)
		(width 0.0889)
		(layer "In15.Cu")
		(net "P5E_CPU0_PE2_TX_DN<3>")
	)
	(arc
		(start 372.64213 -221.94774)
		(mid 372.716121 -221.668174)
		(end 372.918736 -221.461838)
		(width 0.0889)
		(layer "In15.Cu")
		(net "P5E_CPU0_PE2_TX_DN<3>")
	)
	(arc
		(start 373.873522 -216.569798)
		(mid 374.004436 -216.433438)
		(end 374.052084 -216.25052)
		(width 0.0889)
		(layer "In15.Cu")
		(net "P5E_CPU0_PE2_TX_DN<3>")
	)
	(arc
		(start 372.64213 -220.319854)
		(mid 372.714365 -220.04333)
		(end 372.91264 -219.837508)
		(width 0.0889)
		(layer "In15.Cu")
		(net "P5E_CPU0_PE2_TX_DN<3>")
	)
	(arc
		(start 371.515132 -223.899984)
		(mid 371.650065 -223.76663)
		(end 371.70233 -223.584262)
		(width 0.0889)
		(layer "In15.Cu")
		(net "P5E_CPU0_PE2_TX_DN<3>")
	)
	(arc
		(start 374.343168 -215.755982)
		(mid 374.474082 -215.619622)
		(end 374.52173 -215.436704)
		(width 0.0889)
		(layer "In15.Cu")
		(net "P5E_CPU0_PE2_TX_DN<3>")
	)
	(arc
		(start 371.09273 -224.681288)
		(mid 371.195875 -224.551263)
		(end 371.232684 -224.389442)
		(width 0.0889)
		(layer "In15.Cu")
		(net "P5E_CPU0_PE2_TX_DN<3>")
	)
	(arc
		(start 373.112284 -219.490544)
		(mid 373.191654 -219.21681)
		(end 373.394478 -219.01658)
		(width 0.0889)
		(layer "In15.Cu")
		(net "P5E_CPU0_PE2_TX_DN<3>")
	)
	(arc
		(start 372.924832 -220.809566)
		(mid 372.71976 -220.605887)
		(end 372.64213 -220.327474)
		(width 0.0889)
		(layer "In15.Cu")
		(net "P5E_CPU0_PE2_TX_DN<3>")
	)
	(arc
		(start 373.403368 -219.0115)
		(mid 373.534282 -218.87514)
		(end 373.58193 -218.692222)
		(width 0.0889)
		(layer "In15.Cu")
		(net "P5E_CPU0_PE2_TX_DN<3>")
	)
	(arc
		(start 374.052084 -216.235026)
		(mid 374.131454 -215.961292)
		(end 374.334278 -215.761062)
		(width 0.0889)
		(layer "In15.Cu")
		(net "P5E_CPU0_PE2_TX_DN<3>")
	)
	(segment
		(start 411.809692 -401.779994)
		(end 412.13405 -402.104352)
		(width 0.13208)
		(layer "F.Cu")
		(net "P5E_CPU0_PE2_TX_DN<2>")
	)
	(segment
		(start 370.388134 -224.111566)
		(end 370.388134 -223.57588)
		(width 0.13208)
		(layer "F.Cu")
		(net "P5E_CPU0_PE2_TX_DN<2>")
	)
	(segment
		(start 370.388134 -223.57588)
		(end 370.38788 -223.575626)
		(width 0.13208)
		(layer "F.Cu")
		(net "P5E_CPU0_PE2_TX_DN<2>")
	)
	(segment
		(start 412.10865 -400.858228)
		(end 411.809692 -401.157186)
		(width 0.13208)
		(layer "F.Cu")
		(net "P5E_CPU0_PE2_TX_DN<2>")
	)
	(segment
		(start 411.809692 -401.157186)
		(end 411.809692 -401.779994)
		(width 0.13208)
		(layer "F.Cu")
		(net "P5E_CPU0_PE2_TX_DN<2>")
	)
	(segment
		(start 372.172484 -219.506038)
		(end 372.172484 -219.490544)
		(width 0.0889)
		(layer "In15.Cu")
		(net "P5E_CPU0_PE2_TX_DN<2>")
	)
	(segment
		(start 411.07233 -396.677388)
		(end 411.072838 -396.67942)
		(width 0.14732)
		(layer "In15.Cu")
		(net "P5E_CPU0_PE2_TX_DN<2>")
	)
	(segment
		(start 372.91264 -216.58199)
		(end 372.924832 -216.574878)
		(width 0.0889)
		(layer "In15.Cu")
		(net "P5E_CPU0_PE2_TX_DN<2>")
	)
	(segment
		(start 411.072838 -396.67942)
		(end 411.322266 -397.772128)
		(width 0.14732)
		(layer "In15.Cu")
		(net "P5E_CPU0_PE2_TX_DN<2>")
	)
	(segment
		(start 388.182104 -210.281774)
		(end 391.343388 -211.591144)
		(width 0.14732)
		(layer "In15.Cu")
		(net "P5E_CPU0_PE2_TX_DN<2>")
	)
	(segment
		(start 385.038092 -208.979516)
		(end 388.182104 -210.28152)
		(width 0.14732)
		(layer "In15.Cu")
		(net "P5E_CPU0_PE2_TX_DN<2>")
	)
	(segment
		(start 370.575078 -223.899984)
		(end 370.576094 -223.899476)
		(width 0.0889)
		(layer "In15.Cu")
		(net "P5E_CPU0_PE2_TX_DN<2>")
	)
	(segment
		(start 371.978936 -221.461838)
		(end 371.985032 -221.458282)
		(width 0.0889)
		(layer "In15.Cu")
		(net "P5E_CPU0_PE2_TX_DN<2>")
	)
	(segment
		(start 399.123662 -307.713126)
		(end 406.448514 -339.679534)
		(width 0.14732)
		(layer "In15.Cu")
		(net "P5E_CPU0_PE2_TX_DN<2>")
	)
	(segment
		(start 391.343388 -211.591144)
		(end 398.281652 -220.652086)
		(width 0.14732)
		(layer "In15.Cu")
		(net "P5E_CPU0_PE2_TX_DN<2>")
	)
	(segment
		(start 371.70233 -220.334078)
		(end 371.70233 -220.319854)
		(width 0.0889)
		(layer "In15.Cu")
		(net "P5E_CPU0_PE2_TX_DN<2>")
	)
	(segment
		(start 371.993922 -220.814646)
		(end 371.985032 -220.809566)
		(width 0.0889)
		(layer "In15.Cu")
		(net "P5E_CPU0_PE2_TX_DN<2>")
	)
	(segment
		(start 371.045232 -223.085914)
		(end 371.054122 -223.080834)
		(width 0.0889)
		(layer "In15.Cu")
		(net "P5E_CPU0_PE2_TX_DN<2>")
	)
	(segment
		(start 370.231416 -223.846644)
		(end 370.252498 -223.924622)
		(width 0.0889)
		(layer "In15.Cu")
		(net "P5E_CPU0_PE2_TX_DN<2>")
	)
	(segment
		(start 372.925594 -217.554556)
		(end 372.924832 -217.554048)
		(width 0.0889)
		(layer "In15.Cu")
		(net "P5E_CPU0_PE2_TX_DN<2>")
	)
	(segment
		(start 376.30354 -210.284822)
		(end 379.455172 -208.979516)
		(width 0.14732)
		(layer "In15.Cu")
		(net "P5E_CPU0_PE2_TX_DN<2>")
	)
	(segment
		(start 370.576094 -223.899476)
		(end 370.583968 -223.894904)
		(width 0.0889)
		(layer "In15.Cu")
		(net "P5E_CPU0_PE2_TX_DN<2>")
	)
	(segment
		(start 374.521984 -213.716108)
		(end 374.521984 -213.386924)
		(width 0.0889)
		(layer "In15.Cu")
		(net "P5E_CPU0_PE2_TX_DN<2>")
	)
	(segment
		(start 373.112284 -216.25052)
		(end 373.112284 -216.240614)
		(width 0.0889)
		(layer "In15.Cu")
		(net "P5E_CPU0_PE2_TX_DN<2>")
	)
	(segment
		(start 371.985032 -221.458282)
		(end 371.993922 -221.453202)
		(width 0.0889)
		(layer "In15.Cu")
		(net "P5E_CPU0_PE2_TX_DN<2>")
	)
	(segment
		(start 374.480074 -212.108288)
		(end 376.30354 -210.284822)
		(width 0.14732)
		(layer "In15.Cu")
		(net "P5E_CPU0_PE2_TX_DN<2>")
	)
	(segment
		(start 372.454678 -219.01658)
		(end 372.463568 -219.0115)
		(width 0.0889)
		(layer "In15.Cu")
		(net "P5E_CPU0_PE2_TX_DN<2>")
	)
	(segment
		(start 373.582438 -215.423242)
		(end 373.582438 -215.234012)
		(width 0.0889)
		(layer "In15.Cu")
		(net "P5E_CPU0_PE2_TX_DN<2>")
	)
	(segment
		(start 371.232684 -222.761556)
		(end 371.232684 -222.746062)
		(width 0.0889)
		(layer "In15.Cu")
		(net "P5E_CPU0_PE2_TX_DN<2>")
	)
	(segment
		(start 372.918736 -218.20632)
		(end 372.924832 -218.202764)
		(width 0.0889)
		(layer "In15.Cu")
		(net "P5E_CPU0_PE2_TX_DN<2>")
	)
	(segment
		(start 374.480074 -213.345014)
		(end 374.480074 -213.322916)
		(width 0.0889)
		(layer "In15.Cu")
		(net "P5E_CPU0_PE2_TX_DN<2>")
	)
	(segment
		(start 374.318276 -214.207852)
		(end 374.521984 -213.716108)
		(width 0.0889)
		(layer "In15.Cu")
		(net "P5E_CPU0_PE2_TX_DN<2>")
	)
	(segment
		(start 398.281652 -220.652086)
		(end 398.281652 -220.651832)
		(width 0.14732)
		(layer "In15.Cu")
		(net "P5E_CPU0_PE2_TX_DN<2>")
	)
	(segment
		(start 379.455172 -208.979516)
		(end 385.038092 -208.979516)
		(width 0.14732)
		(layer "In15.Cu")
		(net "P5E_CPU0_PE2_TX_DN<2>")
	)
	(segment
		(start 411.81401 -399.926048)
		(end 411.81401 -400.563588)
		(width 0.14732)
		(layer "In15.Cu")
		(net "P5E_CPU0_PE2_TX_DN<2>")
	)
	(segment
		(start 403.201124 -253.496064)
		(end 399.123662 -307.713126)
		(width 0.14732)
		(layer "In15.Cu")
		(net "P5E_CPU0_PE2_TX_DN<2>")
	)
	(segment
		(start 398.314672 -220.695012)
		(end 399.931382 -226.727258)
		(width 0.14732)
		(layer "In15.Cu")
		(net "P5E_CPU0_PE2_TX_DN<2>")
	)
	(segment
		(start 371.514878 -222.272098)
		(end 371.523768 -222.267018)
		(width 0.0889)
		(layer "In15.Cu")
		(net "P5E_CPU0_PE2_TX_DN<2>")
	)
	(segment
		(start 372.64213 -217.071956)
		(end 372.64213 -217.064336)
		(width 0.0889)
		(layer "In15.Cu")
		(net "P5E_CPU0_PE2_TX_DN<2>")
	)
	(segment
		(start 411.322266 -397.772128)
		(end 411.323028 -397.775176)
		(width 0.14732)
		(layer "In15.Cu")
		(net "P5E_CPU0_PE2_TX_DN<2>")
	)
	(segment
		(start 402.977858 -246.914416)
		(end 402.980144 -246.930164)
		(width 0.14732)
		(layer "In15.Cu")
		(net "P5E_CPU0_PE2_TX_DN<2>")
	)
	(segment
		(start 411.323028 -397.775176)
		(end 411.81401 -399.926048)
		(width 0.14732)
		(layer "In15.Cu")
		(net "P5E_CPU0_PE2_TX_DN<2>")
	)
	(segment
		(start 404.96998 -348.031054)
		(end 404.878794 -369.549426)
		(width 0.14732)
		(layer "In15.Cu")
		(net "P5E_CPU0_PE2_TX_DN<2>")
	)
	(segment
		(start 374.480074 -213.322916)
		(end 374.480074 -212.108288)
		(width 0.14732)
		(layer "In15.Cu")
		(net "P5E_CPU0_PE2_TX_DN<2>")
	)
	(segment
		(start 399.931382 -226.727258)
		(end 402.977604 -246.914416)
		(width 0.14732)
		(layer "In15.Cu")
		(net "P5E_CPU0_PE2_TX_DN<2>")
	)
	(segment
		(start 371.978936 -219.833952)
		(end 371.985032 -219.830396)
		(width 0.0889)
		(layer "In15.Cu")
		(net "P5E_CPU0_PE2_TX_DN<2>")
	)
	(segment
		(start 374.521984 -213.386924)
		(end 374.480074 -213.345014)
		(width 0.0889)
		(layer "In15.Cu")
		(net "P5E_CPU0_PE2_TX_DN<2>")
	)
	(segment
		(start 373.582438 -215.234012)
		(end 373.787924 -214.738204)
		(width 0.0889)
		(layer "In15.Cu")
		(net "P5E_CPU0_PE2_TX_DN<2>")
	)
	(segment
		(start 388.182104 -210.28152)
		(end 388.182104 -210.281774)
		(width 0.14732)
		(layer "In15.Cu")
		(net "P5E_CPU0_PE2_TX_DN<2>")
	)
	(segment
		(start 371.986556 -219.829634)
		(end 371.993922 -219.825316)
		(width 0.0889)
		(layer "In15.Cu")
		(net "P5E_CPU0_PE2_TX_DN<2>")
	)
	(segment
		(start 406.448514 -339.679534)
		(end 404.96998 -348.031054)
		(width 0.14732)
		(layer "In15.Cu")
		(net "P5E_CPU0_PE2_TX_DN<2>")
	)
	(segment
		(start 372.933722 -217.559128)
		(end 372.925594 -217.554556)
		(width 0.0889)
		(layer "In15.Cu")
		(net "P5E_CPU0_PE2_TX_DN<2>")
	)
	(segment
		(start 370.76253 -223.575626)
		(end 370.76253 -223.568006)
		(width 0.0889)
		(layer "In15.Cu")
		(net "P5E_CPU0_PE2_TX_DN<2>")
	)
	(segment
		(start 410.822902 -395.58468)
		(end 411.07233 -396.677388)
		(width 0.14732)
		(layer "In15.Cu")
		(net "P5E_CPU0_PE2_TX_DN<2>")
	)
	(segment
		(start 402.980144 -246.930164)
		(end 403.201124 -253.496064)
		(width 0.14732)
		(layer "In15.Cu")
		(net "P5E_CPU0_PE2_TX_DN<2>")
	)
	(segment
		(start 373.58193 -215.44534)
		(end 373.582438 -215.423242)
		(width 0.0889)
		(layer "In15.Cu")
		(net "P5E_CPU0_PE2_TX_DN<2>")
	)
	(segment
		(start 410.822394 -395.582648)
		(end 410.822902 -395.58468)
		(width 0.14732)
		(layer "In15.Cu")
		(net "P5E_CPU0_PE2_TX_DN<2>")
	)
	(segment
		(start 370.38788 -223.575626)
		(end 370.231416 -223.846644)
		(width 0.0889)
		(layer "In15.Cu")
		(net "P5E_CPU0_PE2_TX_DN<2>")
	)
	(segment
		(start 373.787924 -214.738204)
		(end 374.318276 -214.207852)
		(width 0.0889)
		(layer "In15.Cu")
		(net "P5E_CPU0_PE2_TX_DN<2>")
	)
	(segment
		(start 411.81401 -400.563588)
		(end 412.10865 -400.858228)
		(width 0.14732)
		(layer "In15.Cu")
		(net "P5E_CPU0_PE2_TX_DN<2>")
	)
	(segment
		(start 371.985032 -219.830396)
		(end 371.986556 -219.829634)
		(width 0.0889)
		(layer "In15.Cu")
		(net "P5E_CPU0_PE2_TX_DN<2>")
	)
	(segment
		(start 402.977604 -246.914416)
		(end 402.977858 -246.914416)
		(width 0.14732)
		(layer "In15.Cu")
		(net "P5E_CPU0_PE2_TX_DN<2>")
	)
	(segment
		(start 372.924832 -216.574878)
		(end 372.933722 -216.569798)
		(width 0.0889)
		(layer "In15.Cu")
		(net "P5E_CPU0_PE2_TX_DN<2>")
	)
	(segment
		(start 372.924832 -218.202764)
		(end 372.933722 -218.197684)
		(width 0.0889)
		(layer "In15.Cu")
		(net "P5E_CPU0_PE2_TX_DN<2>")
	)
	(segment
		(start 404.878794 -369.549426)
		(end 410.822394 -395.582648)
		(width 0.14732)
		(layer "In15.Cu")
		(net "P5E_CPU0_PE2_TX_DN<2>")
	)
	(segment
		(start 398.281652 -220.651832)
		(end 398.314672 -220.695012)
		(width 0.14732)
		(layer "In15.Cu")
		(net "P5E_CPU0_PE2_TX_DN<2>")
	)
	(arc
		(start 371.523768 -222.267018)
		(mid 371.654682 -222.130658)
		(end 371.70233 -221.94774)
		(width 0.0889)
		(layer "In15.Cu")
		(net "P5E_CPU0_PE2_TX_DN<2>")
	)
	(arc
		(start 371.70233 -221.94774)
		(mid 371.776321 -221.668174)
		(end 371.978936 -221.461838)
		(width 0.0889)
		(layer "In15.Cu")
		(net "P5E_CPU0_PE2_TX_DN<2>")
	)
	(arc
		(start 372.64213 -217.064336)
		(mid 372.714365 -216.787812)
		(end 372.91264 -216.58199)
		(width 0.0889)
		(layer "In15.Cu")
		(net "P5E_CPU0_PE2_TX_DN<2>")
	)
	(arc
		(start 371.232684 -222.746062)
		(mid 371.312054 -222.472328)
		(end 371.514878 -222.272098)
		(width 0.0889)
		(layer "In15.Cu")
		(net "P5E_CPU0_PE2_TX_DN<2>")
	)
	(arc
		(start 370.76253 -223.568006)
		(mid 370.840159 -223.289593)
		(end 371.045232 -223.085914)
		(width 0.0889)
		(layer "In15.Cu")
		(net "P5E_CPU0_PE2_TX_DN<2>")
	)
	(arc
		(start 370.252498 -223.924622)
		(mid 370.416594 -223.948969)
		(end 370.575078 -223.899984)
		(width 0.0889)
		(layer "In15.Cu")
		(net "P5E_CPU0_PE2_TX_DN<2>")
	)
	(arc
		(start 371.70233 -220.319854)
		(mid 371.776321 -220.040288)
		(end 371.978936 -219.833952)
		(width 0.0889)
		(layer "In15.Cu")
		(net "P5E_CPU0_PE2_TX_DN<2>")
	)
	(arc
		(start 372.924832 -217.554048)
		(mid 372.71976 -217.350369)
		(end 372.64213 -217.071956)
		(width 0.0889)
		(layer "In15.Cu")
		(net "P5E_CPU0_PE2_TX_DN<2>")
	)
	(arc
		(start 372.933722 -218.197684)
		(mid 373.112319 -217.878406)
		(end 372.933722 -217.559128)
		(width 0.0889)
		(layer "In15.Cu")
		(net "P5E_CPU0_PE2_TX_DN<2>")
	)
	(arc
		(start 371.993922 -219.825316)
		(mid 372.124836 -219.688956)
		(end 372.172484 -219.506038)
		(width 0.0889)
		(layer "In15.Cu")
		(net "P5E_CPU0_PE2_TX_DN<2>")
	)
	(arc
		(start 373.112284 -216.240614)
		(mid 373.190395 -215.963665)
		(end 373.394732 -215.761062)
		(width 0.0889)
		(layer "In15.Cu")
		(net "P5E_CPU0_PE2_TX_DN<2>")
	)
	(arc
		(start 373.394732 -215.761062)
		(mid 373.529665 -215.627708)
		(end 373.58193 -215.44534)
		(width 0.0889)
		(layer "In15.Cu")
		(net "P5E_CPU0_PE2_TX_DN<2>")
	)
	(arc
		(start 371.054122 -223.080834)
		(mid 371.185036 -222.944474)
		(end 371.232684 -222.761556)
		(width 0.0889)
		(layer "In15.Cu")
		(net "P5E_CPU0_PE2_TX_DN<2>")
	)
	(arc
		(start 370.583968 -223.894904)
		(mid 370.714882 -223.758544)
		(end 370.76253 -223.575626)
		(width 0.0889)
		(layer "In15.Cu")
		(net "P5E_CPU0_PE2_TX_DN<2>")
	)
	(arc
		(start 372.64213 -218.692222)
		(mid 372.716121 -218.412656)
		(end 372.918736 -218.20632)
		(width 0.0889)
		(layer "In15.Cu")
		(net "P5E_CPU0_PE2_TX_DN<2>")
	)
	(arc
		(start 371.993922 -221.453202)
		(mid 372.172519 -221.133924)
		(end 371.993922 -220.814646)
		(width 0.0889)
		(layer "In15.Cu")
		(net "P5E_CPU0_PE2_TX_DN<2>")
	)
	(arc
		(start 372.933722 -216.569798)
		(mid 373.064636 -216.433438)
		(end 373.112284 -216.25052)
		(width 0.0889)
		(layer "In15.Cu")
		(net "P5E_CPU0_PE2_TX_DN<2>")
	)
	(arc
		(start 371.985032 -220.809566)
		(mid 371.781551 -220.608762)
		(end 371.70233 -220.334078)
		(width 0.0889)
		(layer "In15.Cu")
		(net "P5E_CPU0_PE2_TX_DN<2>")
	)
	(arc
		(start 372.172484 -219.490544)
		(mid 372.251854 -219.21681)
		(end 372.454678 -219.01658)
		(width 0.0889)
		(layer "In15.Cu")
		(net "P5E_CPU0_PE2_TX_DN<2>")
	)
	(arc
		(start 372.463568 -219.0115)
		(mid 372.594482 -218.87514)
		(end 372.64213 -218.692222)
		(width 0.0889)
		(layer "In15.Cu")
		(net "P5E_CPU0_PE2_TX_DN<2>")
	)
	(segment
		(start 414.872932 -401.779994)
		(end 415.19729 -402.104352)
		(width 0.13208)
		(layer "F.Cu")
		(net "P5E_CPU0_PE2_TX_DN<1>")
	)
	(segment
		(start 368.97818 -224.925382)
		(end 368.97818 -224.389696)
		(width 0.13208)
		(layer "F.Cu")
		(net "P5E_CPU0_PE2_TX_DN<1>")
	)
	(segment
		(start 414.872932 -401.157186)
		(end 414.872932 -401.779994)
		(width 0.13208)
		(layer "F.Cu")
		(net "P5E_CPU0_PE2_TX_DN<1>")
	)
	(segment
		(start 368.97818 -224.389696)
		(end 368.978434 -224.389442)
		(width 0.13208)
		(layer "F.Cu")
		(net "P5E_CPU0_PE2_TX_DN<1>")
	)
	(segment
		(start 415.17189 -400.858228)
		(end 414.872932 -401.157186)
		(width 0.13208)
		(layer "F.Cu")
		(net "P5E_CPU0_PE2_TX_DN<1>")
	)
	(segment
		(start 370.575078 -222.272098)
		(end 370.583968 -222.267018)
		(width 0.0889)
		(layer "In15.Cu")
		(net "P5E_CPU0_PE2_TX_DN<1>")
	)
	(segment
		(start 400.835368 -226.421188)
		(end 403.974808 -247.226836)
		(width 0.14732)
		(layer "In15.Cu")
		(net "P5E_CPU0_PE2_TX_DN<1>")
	)
	(segment
		(start 383.056892 -202.03541)
		(end 384.722878 -203.419964)
		(width 0.14732)
		(layer "In15.Cu")
		(net "P5E_CPU0_PE2_TX_DN<1>")
	)
	(segment
		(start 406.140412 -369.42141)
		(end 414.187386 -397.457422)
		(width 0.14732)
		(layer "In15.Cu")
		(net "P5E_CPU0_PE2_TX_DN<1>")
	)
	(segment
		(start 371.993922 -217.559128)
		(end 371.985032 -217.554048)
		(width 0.0889)
		(layer "In15.Cu")
		(net "P5E_CPU0_PE2_TX_DN<1>")
	)
	(segment
		(start 373.507762 -214.040466)
		(end 373.581676 -213.861904)
		(width 0.0889)
		(layer "In15.Cu")
		(net "P5E_CPU0_PE2_TX_DN<1>")
	)
	(segment
		(start 370.76253 -220.327474)
		(end 370.76253 -220.319854)
		(width 0.0889)
		(layer "In15.Cu")
		(net "P5E_CPU0_PE2_TX_DN<1>")
	)
	(segment
		(start 414.187386 -397.457422)
		(end 414.18764 -397.458184)
		(width 0.14732)
		(layer "In15.Cu")
		(net "P5E_CPU0_PE2_TX_DN<1>")
	)
	(segment
		(start 371.232684 -219.506038)
		(end 371.232684 -219.490544)
		(width 0.0889)
		(layer "In15.Cu")
		(net "P5E_CPU0_PE2_TX_DN<1>")
	)
	(segment
		(start 372.642384 -215.43645)
		(end 372.642384 -215.332564)
		(width 0.0889)
		(layer "In15.Cu")
		(net "P5E_CPU0_PE2_TX_DN<1>")
	)
	(segment
		(start 381.297942 -201.854562)
		(end 381.669544 -201.694542)
		(width 0.14732)
		(layer "In15.Cu")
		(net "P5E_CPU0_PE2_TX_DN<1>")
	)
	(segment
		(start 371.054122 -220.814646)
		(end 371.045994 -220.810074)
		(width 0.0889)
		(layer "In15.Cu")
		(net "P5E_CPU0_PE2_TX_DN<1>")
	)
	(segment
		(start 372.94439 -214.603838)
		(end 373.507762 -214.040466)
		(width 0.0889)
		(layer "In15.Cu")
		(net "P5E_CPU0_PE2_TX_DN<1>")
	)
	(segment
		(start 371.045232 -219.830396)
		(end 371.054122 -219.825316)
		(width 0.0889)
		(layer "In15.Cu")
		(net "P5E_CPU0_PE2_TX_DN<1>")
	)
	(segment
		(start 371.978936 -218.20632)
		(end 371.985032 -218.202764)
		(width 0.0889)
		(layer "In15.Cu")
		(net "P5E_CPU0_PE2_TX_DN<1>")
	)
	(segment
		(start 392.199114 -210.827112)
		(end 399.195544 -220.116146)
		(width 0.14732)
		(layer "In15.Cu")
		(net "P5E_CPU0_PE2_TX_DN<1>")
	)
	(segment
		(start 372.642384 -215.332564)
		(end 372.94439 -214.603838)
		(width 0.0889)
		(layer "In15.Cu")
		(net "P5E_CPU0_PE2_TX_DN<1>")
	)
	(segment
		(start 404.079964 -250.357132)
		(end 404.080218 -250.357132)
		(width 0.14732)
		(layer "In15.Cu")
		(net "P5E_CPU0_PE2_TX_DN<1>")
	)
	(segment
		(start 399.195544 -220.116146)
		(end 400.835368 -226.421188)
		(width 0.14732)
		(layer "In15.Cu")
		(net "P5E_CPU0_PE2_TX_DN<1>")
	)
	(segment
		(start 404.18512 -253.486412)
		(end 400.069812 -307.56479)
		(width 0.14732)
		(layer "In15.Cu")
		(net "P5E_CPU0_PE2_TX_DN<1>")
	)
	(segment
		(start 369.134898 -224.66046)
		(end 369.21313 -224.681288)
		(width 0.0889)
		(layer "In15.Cu")
		(net "P5E_CPU0_PE2_TX_DN<1>")
	)
	(segment
		(start 371.045994 -220.810074)
		(end 371.045232 -220.809566)
		(width 0.0889)
		(layer "In15.Cu")
		(net "P5E_CPU0_PE2_TX_DN<1>")
	)
	(segment
		(start 371.045232 -221.458282)
		(end 371.054122 -221.453202)
		(width 0.0889)
		(layer "In15.Cu")
		(net "P5E_CPU0_PE2_TX_DN<1>")
	)
	(segment
		(start 405.924512 -348.024958)
		(end 406.140412 -369.42141)
		(width 0.14732)
		(layer "In15.Cu")
		(net "P5E_CPU0_PE2_TX_DN<1>")
	)
	(segment
		(start 373.539766 -213.345014)
		(end 373.539766 -213.322916)
		(width 0.0889)
		(layer "In15.Cu")
		(net "P5E_CPU0_PE2_TX_DN<1>")
	)
	(segment
		(start 369.353084 -224.389442)
		(end 369.353084 -224.379536)
		(width 0.0889)
		(layer "In15.Cu")
		(net "P5E_CPU0_PE2_TX_DN<1>")
	)
	(segment
		(start 368.978434 -224.389442)
		(end 369.134898 -224.66046)
		(width 0.0889)
		(layer "In15.Cu")
		(net "P5E_CPU0_PE2_TX_DN<1>")
	)
	(segment
		(start 373.581676 -213.386924)
		(end 373.539766 -213.345014)
		(width 0.0889)
		(layer "In15.Cu")
		(net "P5E_CPU0_PE2_TX_DN<1>")
	)
	(segment
		(start 371.70233 -217.07856)
		(end 371.70233 -217.064336)
		(width 0.0889)
		(layer "In15.Cu")
		(net "P5E_CPU0_PE2_TX_DN<1>")
	)
	(segment
		(start 407.423874 -339.683852)
		(end 405.924512 -348.024958)
		(width 0.14732)
		(layer "In15.Cu")
		(net "P5E_CPU0_PE2_TX_DN<1>")
	)
	(segment
		(start 370.292884 -222.761556)
		(end 370.292884 -222.746062)
		(width 0.0889)
		(layer "In15.Cu")
		(net "P5E_CPU0_PE2_TX_DN<1>")
	)
	(segment
		(start 373.539766 -213.322916)
		(end 373.539766 -211.91474)
		(width 0.14732)
		(layer "In15.Cu")
		(net "P5E_CPU0_PE2_TX_DN<1>")
	)
	(segment
		(start 371.978936 -216.578434)
		(end 371.985032 -216.574878)
		(width 0.0889)
		(layer "In15.Cu")
		(net "P5E_CPU0_PE2_TX_DN<1>")
	)
	(segment
		(start 371.514878 -219.01658)
		(end 371.523768 -219.0115)
		(width 0.0889)
		(layer "In15.Cu")
		(net "P5E_CPU0_PE2_TX_DN<1>")
	)
	(segment
		(start 370.105432 -223.085914)
		(end 370.114322 -223.080834)
		(width 0.0889)
		(layer "In15.Cu")
		(net "P5E_CPU0_PE2_TX_DN<1>")
	)
	(segment
		(start 373.932958 -210.965796)
		(end 380.988316 -202.164442)
		(width 0.14732)
		(layer "In15.Cu")
		(net "P5E_CPU0_PE2_TX_DN<1>")
	)
	(segment
		(start 372.172484 -216.25052)
		(end 372.172484 -216.235026)
		(width 0.0889)
		(layer "In15.Cu")
		(net "P5E_CPU0_PE2_TX_DN<1>")
	)
	(segment
		(start 371.03304 -219.837508)
		(end 371.045232 -219.830396)
		(width 0.0889)
		(layer "In15.Cu")
		(net "P5E_CPU0_PE2_TX_DN<1>")
	)
	(segment
		(start 373.581676 -213.861904)
		(end 373.581676 -213.386924)
		(width 0.0889)
		(layer "In15.Cu")
		(net "P5E_CPU0_PE2_TX_DN<1>")
	)
	(segment
		(start 404.080218 -250.357132)
		(end 404.18512 -253.486412)
		(width 0.14732)
		(layer "In15.Cu")
		(net "P5E_CPU0_PE2_TX_DN<1>")
	)
	(segment
		(start 371.039136 -221.461838)
		(end 371.045232 -221.458282)
		(width 0.0889)
		(layer "In15.Cu")
		(net "P5E_CPU0_PE2_TX_DN<1>")
	)
	(segment
		(start 371.985032 -216.574878)
		(end 371.986556 -216.574116)
		(width 0.0889)
		(layer "In15.Cu")
		(net "P5E_CPU0_PE2_TX_DN<1>")
	)
	(segment
		(start 369.82273 -223.584262)
		(end 369.82273 -223.561402)
		(width 0.0889)
		(layer "In15.Cu")
		(net "P5E_CPU0_PE2_TX_DN<1>")
	)
	(segment
		(start 372.64213 -215.436704)
		(end 372.642384 -215.43645)
		(width 0.0889)
		(layer "In15.Cu")
		(net "P5E_CPU0_PE2_TX_DN<1>")
	)
	(segment
		(start 380.988316 -202.164442)
		(end 381.297942 -201.854562)
		(width 0.14732)
		(layer "In15.Cu")
		(net "P5E_CPU0_PE2_TX_DN<1>")
	)
	(segment
		(start 414.876996 -399.860008)
		(end 414.876996 -400.563334)
		(width 0.14732)
		(layer "In15.Cu")
		(net "P5E_CPU0_PE2_TX_DN<1>")
	)
	(segment
		(start 403.974808 -247.226836)
		(end 404.079964 -250.357132)
		(width 0.14732)
		(layer "In15.Cu")
		(net "P5E_CPU0_PE2_TX_DN<1>")
	)
	(segment
		(start 414.18764 -397.458184)
		(end 414.876996 -399.860008)
		(width 0.14732)
		(layer "In15.Cu")
		(net "P5E_CPU0_PE2_TX_DN<1>")
	)
	(segment
		(start 381.669544 -201.694542)
		(end 382.22936 -201.717148)
		(width 0.14732)
		(layer "In15.Cu")
		(net "P5E_CPU0_PE2_TX_DN<1>")
	)
	(segment
		(start 384.722878 -203.419964)
		(end 392.199114 -210.827112)
		(width 0.14732)
		(layer "In15.Cu")
		(net "P5E_CPU0_PE2_TX_DN<1>")
	)
	(segment
		(start 372.454678 -215.761062)
		(end 372.463568 -215.755982)
		(width 0.0889)
		(layer "In15.Cu")
		(net "P5E_CPU0_PE2_TX_DN<1>")
	)
	(segment
		(start 371.986556 -216.574116)
		(end 371.993922 -216.569798)
		(width 0.0889)
		(layer "In15.Cu")
		(net "P5E_CPU0_PE2_TX_DN<1>")
	)
	(segment
		(start 414.876996 -400.563334)
		(end 415.17189 -400.858228)
		(width 0.14732)
		(layer "In15.Cu")
		(net "P5E_CPU0_PE2_TX_DN<1>")
	)
	(segment
		(start 371.985032 -218.202764)
		(end 371.993922 -218.197684)
		(width 0.0889)
		(layer "In15.Cu")
		(net "P5E_CPU0_PE2_TX_DN<1>")
	)
	(segment
		(start 382.22936 -201.717148)
		(end 383.056892 -202.03541)
		(width 0.14732)
		(layer "In15.Cu")
		(net "P5E_CPU0_PE2_TX_DN<1>")
	)
	(segment
		(start 400.069812 -307.56479)
		(end 407.423874 -339.683852)
		(width 0.14732)
		(layer "In15.Cu")
		(net "P5E_CPU0_PE2_TX_DN<1>")
	)
	(segment
		(start 373.539766 -211.91474)
		(end 373.932958 -210.965796)
		(width 0.14732)
		(layer "In15.Cu")
		(net "P5E_CPU0_PE2_TX_DN<1>")
	)
	(arc
		(start 371.523768 -219.0115)
		(mid 371.654682 -218.87514)
		(end 371.70233 -218.692222)
		(width 0.0889)
		(layer "In15.Cu")
		(net "P5E_CPU0_PE2_TX_DN<1>")
	)
	(arc
		(start 372.463568 -215.755982)
		(mid 372.594482 -215.619622)
		(end 372.64213 -215.436704)
		(width 0.0889)
		(layer "In15.Cu")
		(net "P5E_CPU0_PE2_TX_DN<1>")
	)
	(arc
		(start 371.993922 -216.569798)
		(mid 372.124836 -216.433438)
		(end 372.172484 -216.25052)
		(width 0.0889)
		(layer "In15.Cu")
		(net "P5E_CPU0_PE2_TX_DN<1>")
	)
	(arc
		(start 369.21313 -224.681288)
		(mid 369.316275 -224.551263)
		(end 369.353084 -224.389442)
		(width 0.0889)
		(layer "In15.Cu")
		(net "P5E_CPU0_PE2_TX_DN<1>")
	)
	(arc
		(start 369.635532 -223.899984)
		(mid 369.770465 -223.76663)
		(end 369.82273 -223.584262)
		(width 0.0889)
		(layer "In15.Cu")
		(net "P5E_CPU0_PE2_TX_DN<1>")
	)
	(arc
		(start 370.114322 -223.080834)
		(mid 370.245236 -222.944474)
		(end 370.292884 -222.761556)
		(width 0.0889)
		(layer "In15.Cu")
		(net "P5E_CPU0_PE2_TX_DN<1>")
	)
	(arc
		(start 372.172484 -216.235026)
		(mid 372.251854 -215.961292)
		(end 372.454678 -215.761062)
		(width 0.0889)
		(layer "In15.Cu")
		(net "P5E_CPU0_PE2_TX_DN<1>")
	)
	(arc
		(start 370.292884 -222.746062)
		(mid 370.372254 -222.472328)
		(end 370.575078 -222.272098)
		(width 0.0889)
		(layer "In15.Cu")
		(net "P5E_CPU0_PE2_TX_DN<1>")
	)
	(arc
		(start 371.993922 -218.197684)
		(mid 372.172519 -217.878406)
		(end 371.993922 -217.559128)
		(width 0.0889)
		(layer "In15.Cu")
		(net "P5E_CPU0_PE2_TX_DN<1>")
	)
	(arc
		(start 370.76253 -221.94774)
		(mid 370.836521 -221.668174)
		(end 371.039136 -221.461838)
		(width 0.0889)
		(layer "In15.Cu")
		(net "P5E_CPU0_PE2_TX_DN<1>")
	)
	(arc
		(start 370.583968 -222.267018)
		(mid 370.714882 -222.130658)
		(end 370.76253 -221.94774)
		(width 0.0889)
		(layer "In15.Cu")
		(net "P5E_CPU0_PE2_TX_DN<1>")
	)
	(arc
		(start 371.232684 -219.490544)
		(mid 371.312054 -219.21681)
		(end 371.514878 -219.01658)
		(width 0.0889)
		(layer "In15.Cu")
		(net "P5E_CPU0_PE2_TX_DN<1>")
	)
	(arc
		(start 370.76253 -220.319854)
		(mid 370.834765 -220.04333)
		(end 371.03304 -219.837508)
		(width 0.0889)
		(layer "In15.Cu")
		(net "P5E_CPU0_PE2_TX_DN<1>")
	)
	(arc
		(start 369.82273 -223.561402)
		(mid 369.901949 -223.286717)
		(end 370.105432 -223.085914)
		(width 0.0889)
		(layer "In15.Cu")
		(net "P5E_CPU0_PE2_TX_DN<1>")
	)
	(arc
		(start 371.70233 -218.692222)
		(mid 371.776321 -218.412656)
		(end 371.978936 -218.20632)
		(width 0.0889)
		(layer "In15.Cu")
		(net "P5E_CPU0_PE2_TX_DN<1>")
	)
	(arc
		(start 369.353084 -224.379536)
		(mid 369.431195 -224.102587)
		(end 369.635532 -223.899984)
		(width 0.0889)
		(layer "In15.Cu")
		(net "P5E_CPU0_PE2_TX_DN<1>")
	)
	(arc
		(start 371.045232 -220.809566)
		(mid 370.84016 -220.605887)
		(end 370.76253 -220.327474)
		(width 0.0889)
		(layer "In15.Cu")
		(net "P5E_CPU0_PE2_TX_DN<1>")
	)
	(arc
		(start 371.70233 -217.064336)
		(mid 371.776321 -216.78477)
		(end 371.978936 -216.578434)
		(width 0.0889)
		(layer "In15.Cu")
		(net "P5E_CPU0_PE2_TX_DN<1>")
	)
	(arc
		(start 371.985032 -217.554048)
		(mid 371.781551 -217.353244)
		(end 371.70233 -217.07856)
		(width 0.0889)
		(layer "In15.Cu")
		(net "P5E_CPU0_PE2_TX_DN<1>")
	)
	(arc
		(start 371.054122 -221.453202)
		(mid 371.232719 -221.133924)
		(end 371.054122 -220.814646)
		(width 0.0889)
		(layer "In15.Cu")
		(net "P5E_CPU0_PE2_TX_DN<1>")
	)
	(arc
		(start 371.054122 -219.825316)
		(mid 371.185036 -219.688956)
		(end 371.232684 -219.506038)
		(width 0.0889)
		(layer "In15.Cu")
		(net "P5E_CPU0_PE2_TX_DN<1>")
	)
	(segment
		(start 382.135634 -224.925382)
		(end 382.135634 -224.389442)
		(width 0.13208)
		(layer "F.Cu")
		(net "P5E_CPU0_PE2_TX_DN<15>")
	)
	(segment
		(start 371.402102 -402.104352)
		(end 371.39753 -402.104352)
		(width 0.13208)
		(layer "F.Cu")
		(net "P5E_CPU0_PE2_TX_DN<15>")
	)
	(segment
		(start 371.728492 -401.777962)
		(end 371.402102 -402.104352)
		(width 0.13208)
		(layer "F.Cu")
		(net "P5E_CPU0_PE2_TX_DN<15>")
	)
	(segment
		(start 371.42293 -400.858228)
		(end 371.728492 -401.16379)
		(width 0.13208)
		(layer "F.Cu")
		(net "P5E_CPU0_PE2_TX_DN<15>")
	)
	(segment
		(start 371.728492 -401.16379)
		(end 371.728492 -401.777962)
		(width 0.13208)
		(layer "F.Cu")
		(net "P5E_CPU0_PE2_TX_DN<15>")
	)
	(segment
		(start 382.040384 -225.193352)
		(end 382.040384 -225.2218)
		(width 0.0889)
		(layer "In15.Cu")
		(net "P5E_CPU0_PE2_TX_DN<15>")
	)
	(segment
		(start 371.71757 -400.113246)
		(end 371.71757 -400.563588)
		(width 0.14732)
		(layer "In15.Cu")
		(net "P5E_CPU0_PE2_TX_DN<15>")
	)
	(segment
		(start 386.708904 -254.979932)
		(end 388.12851 -257.006852)
		(width 0.14732)
		(layer "In15.Cu")
		(net "P5E_CPU0_PE2_TX_DN<15>")
	)
	(segment
		(start 371.874034 -399.377154)
		(end 371.71757 -400.113246)
		(width 0.14732)
		(layer "In15.Cu")
		(net "P5E_CPU0_PE2_TX_DN<15>")
	)
	(segment
		(start 384.51155 -227.71989)
		(end 384.511296 -227.71989)
		(width 0.0889)
		(layer "In15.Cu")
		(net "P5E_CPU0_PE2_TX_DN<15>")
	)
	(segment
		(start 384.644646 -227.85324)
		(end 384.644646 -227.912168)
		(width 0.0889)
		(layer "In15.Cu")
		(net "P5E_CPU0_PE2_TX_DN<15>")
	)
	(segment
		(start 382.792478 -226.506786)
		(end 382.793494 -226.507294)
		(width 0.0889)
		(layer "In15.Cu")
		(net "P5E_CPU0_PE2_TX_DN<15>")
	)
	(segment
		(start 383.25044 -227.31349)
		(end 383.264156 -227.321364)
		(width 0.0889)
		(layer "In15.Cu")
		(net "P5E_CPU0_PE2_TX_DN<15>")
	)
	(segment
		(start 387.191504 -366.83188)
		(end 371.874034 -399.377154)
		(width 0.14732)
		(layer "In15.Cu")
		(net "P5E_CPU0_PE2_TX_DN<15>")
	)
	(segment
		(start 382.510284 -226.017328)
		(end 382.510284 -226.032822)
		(width 0.0889)
		(layer "In15.Cu")
		(net "P5E_CPU0_PE2_TX_DN<15>")
	)
	(segment
		(start 390.869424 -353.604322)
		(end 387.191504 -366.83188)
		(width 0.14732)
		(layer "In15.Cu")
		(net "P5E_CPU0_PE2_TX_DN<15>")
	)
	(segment
		(start 382.793494 -226.507294)
		(end 382.801368 -226.511866)
		(width 0.0889)
		(layer "In15.Cu")
		(net "P5E_CPU0_PE2_TX_DN<15>")
	)
	(segment
		(start 382.135634 -224.389442)
		(end 382.292098 -224.66046)
		(width 0.0889)
		(layer "In15.Cu")
		(net "P5E_CPU0_PE2_TX_DN<15>")
	)
	(segment
		(start 385.3434 -228.6127)
		(end 386.40639 -230.618792)
		(width 0.14732)
		(layer "In15.Cu")
		(net "P5E_CPU0_PE2_TX_DN<15>")
	)
	(segment
		(start 384.659886 -227.927408)
		(end 385.3434 -228.6127)
		(width 0.14732)
		(layer "In15.Cu")
		(net "P5E_CPU0_PE2_TX_DN<15>")
	)
	(segment
		(start 385.173474 -250.579636)
		(end 385.55422 -252.73889)
		(width 0.14732)
		(layer "In15.Cu")
		(net "P5E_CPU0_PE2_TX_DN<15>")
	)
	(segment
		(start 384.644646 -227.912168)
		(end 384.659886 -227.927408)
		(width 0.0889)
		(layer "In15.Cu")
		(net "P5E_CPU0_PE2_TX_DN<15>")
	)
	(segment
		(start 393.199874 -339.319108)
		(end 390.869424 -353.604322)
		(width 0.14732)
		(layer "In15.Cu")
		(net "P5E_CPU0_PE2_TX_DN<15>")
	)
	(segment
		(start 385.55422 -252.73889)
		(end 386.108194 -253.529846)
		(width 0.14732)
		(layer "In15.Cu")
		(net "P5E_CPU0_PE2_TX_DN<15>")
	)
	(segment
		(start 371.71757 -400.563588)
		(end 371.42293 -400.858228)
		(width 0.14732)
		(layer "In15.Cu")
		(net "P5E_CPU0_PE2_TX_DN<15>")
	)
	(segment
		(start 386.40639 -230.618792)
		(end 386.506466 -232.16743)
		(width 0.14732)
		(layer "In15.Cu")
		(net "P5E_CPU0_PE2_TX_DN<15>")
	)
	(segment
		(start 386.506466 -232.16743)
		(end 386.246878 -245.965218)
		(width 0.14732)
		(layer "In15.Cu")
		(net "P5E_CPU0_PE2_TX_DN<15>")
	)
	(segment
		(start 386.108194 -253.529846)
		(end 386.708904 -254.979932)
		(width 0.14732)
		(layer "In15.Cu")
		(net "P5E_CPU0_PE2_TX_DN<15>")
	)
	(segment
		(start 388.987284 -259.7023)
		(end 388.130034 -271.507204)
		(width 0.14732)
		(layer "In15.Cu")
		(net "P5E_CPU0_PE2_TX_DN<15>")
	)
	(segment
		(start 382.292098 -224.66046)
		(end 382.267968 -224.749614)
		(width 0.0889)
		(layer "In15.Cu")
		(net "P5E_CPU0_PE2_TX_DN<15>")
	)
	(segment
		(start 383.63779 -227.456746)
		(end 384.377692 -227.586286)
		(width 0.0889)
		(layer "In15.Cu")
		(net "P5E_CPU0_PE2_TX_DN<15>")
	)
	(segment
		(start 388.130034 -271.507204)
		(end 388.130034 -271.50695)
		(width 0.14732)
		(layer "In15.Cu")
		(net "P5E_CPU0_PE2_TX_DN<15>")
	)
	(segment
		(start 384.377692 -227.586286)
		(end 384.51155 -227.71989)
		(width 0.0889)
		(layer "In15.Cu")
		(net "P5E_CPU0_PE2_TX_DN<15>")
	)
	(segment
		(start 386.246878 -245.965218)
		(end 385.62407 -248.024142)
		(width 0.14732)
		(layer "In15.Cu")
		(net "P5E_CPU0_PE2_TX_DN<15>")
	)
	(segment
		(start 382.322832 -225.69297)
		(end 382.331722 -225.69805)
		(width 0.0889)
		(layer "In15.Cu")
		(net "P5E_CPU0_PE2_TX_DN<15>")
	)
	(segment
		(start 385.62407 -248.024142)
		(end 385.173474 -250.579636)
		(width 0.14732)
		(layer "In15.Cu")
		(net "P5E_CPU0_PE2_TX_DN<15>")
	)
	(segment
		(start 388.130034 -271.50695)
		(end 386.226304 -310.514746)
		(width 0.14732)
		(layer "In15.Cu")
		(net "P5E_CPU0_PE2_TX_DN<15>")
	)
	(segment
		(start 388.12851 -257.006852)
		(end 388.987284 -259.7023)
		(width 0.14732)
		(layer "In15.Cu")
		(net "P5E_CPU0_PE2_TX_DN<15>")
	)
	(segment
		(start 384.511296 -227.71989)
		(end 384.644646 -227.85324)
		(width 0.0889)
		(layer "In15.Cu")
		(net "P5E_CPU0_PE2_TX_DN<15>")
	)
	(segment
		(start 386.226304 -310.514746)
		(end 393.199874 -339.319108)
		(width 0.14732)
		(layer "In15.Cu")
		(net "P5E_CPU0_PE2_TX_DN<15>")
	)
	(arc
		(start 382.040384 -225.2218)
		(mid 382.120546 -225.493989)
		(end 382.322832 -225.69297)
		(width 0.0889)
		(layer "In15.Cu")
		(net "P5E_CPU0_PE2_TX_DN<15>")
	)
	(arc
		(start 382.510284 -226.032822)
		(mid 382.589654 -226.306556)
		(end 382.792478 -226.506786)
		(width 0.0889)
		(layer "In15.Cu")
		(net "P5E_CPU0_PE2_TX_DN<15>")
	)
	(arc
		(start 382.97993 -226.831144)
		(mid 383.052165 -227.107668)
		(end 383.25044 -227.31349)
		(width 0.0889)
		(layer "In15.Cu")
		(net "P5E_CPU0_PE2_TX_DN<15>")
	)
	(arc
		(start 382.267968 -224.749614)
		(mid 382.259524 -224.756011)
		(end 382.251204 -224.762568)
		(width 0.0889)
		(layer "In15.Cu")
		(net "P5E_CPU0_PE2_TX_DN<15>")
	)
	(arc
		(start 382.251204 -224.762568)
		(mid 382.09782 -224.954487)
		(end 382.040384 -225.193352)
		(width 0.0889)
		(layer "In15.Cu")
		(net "P5E_CPU0_PE2_TX_DN<15>")
	)
	(arc
		(start 382.331722 -225.69805)
		(mid 382.462636 -225.83441)
		(end 382.510284 -226.017328)
		(width 0.0889)
		(layer "In15.Cu")
		(net "P5E_CPU0_PE2_TX_DN<15>")
	)
	(arc
		(start 383.264156 -227.321364)
		(mid 383.445051 -227.405399)
		(end 383.63779 -227.456746)
		(width 0.0889)
		(layer "In15.Cu")
		(net "P5E_CPU0_PE2_TX_DN<15>")
	)
	(arc
		(start 382.801368 -226.511866)
		(mid 382.932282 -226.648226)
		(end 382.97993 -226.831144)
		(width 0.0889)
		(layer "In15.Cu")
		(net "P5E_CPU0_PE2_TX_DN<15>")
	)
	(segment
		(start 375.050812 -401.779994)
		(end 375.37517 -402.104352)
		(width 0.13208)
		(layer "F.Cu")
		(net "P5E_CPU0_PE2_TX_DN<14>")
	)
	(segment
		(start 381.665734 -224.111566)
		(end 381.665734 -223.575626)
		(width 0.13208)
		(layer "F.Cu")
		(net "P5E_CPU0_PE2_TX_DN<14>")
	)
	(segment
		(start 375.34977 -400.858228)
		(end 375.050812 -401.157186)
		(width 0.13208)
		(layer "F.Cu")
		(net "P5E_CPU0_PE2_TX_DN<14>")
	)
	(segment
		(start 375.050812 -401.157186)
		(end 375.050812 -401.779994)
		(width 0.13208)
		(layer "F.Cu")
		(net "P5E_CPU0_PE2_TX_DN<14>")
	)
	(segment
		(start 387.178804 -249.120406)
		(end 387.178804 -251.20854)
		(width 0.14732)
		(layer "In15.Cu")
		(net "P5E_CPU0_PE2_TX_DN<14>")
	)
	(segment
		(start 389.49503 -244.343428)
		(end 388.590282 -247.175274)
		(width 0.14732)
		(layer "In15.Cu")
		(net "P5E_CPU0_PE2_TX_DN<14>")
	)
	(segment
		(start 375.05513 -400.563588)
		(end 375.34977 -400.858228)
		(width 0.14732)
		(layer "In15.Cu")
		(net "P5E_CPU0_PE2_TX_DN<14>")
	)
	(segment
		(start 388.705344 -366.995964)
		(end 375.05513 -400.167602)
		(width 0.14732)
		(layer "In15.Cu")
		(net "P5E_CPU0_PE2_TX_DN<14>")
	)
	(segment
		(start 394.485622 -339.278468)
		(end 392.163808 -353.604322)
		(width 0.14732)
		(layer "In15.Cu")
		(net "P5E_CPU0_PE2_TX_DN<14>")
	)
	(segment
		(start 387.458204 -310.38546)
		(end 394.485622 -339.278468)
		(width 0.14732)
		(layer "In15.Cu")
		(net "P5E_CPU0_PE2_TX_DN<14>")
	)
	(segment
		(start 375.05513 -400.167602)
		(end 375.05513 -400.563588)
		(width 0.14732)
		(layer "In15.Cu")
		(net "P5E_CPU0_PE2_TX_DN<14>")
	)
	(segment
		(start 384.110484 -225.193352)
		(end 384.110484 -225.203258)
		(width 0.0889)
		(layer "In15.Cu")
		(net "P5E_CPU0_PE2_TX_DN<14>")
	)
	(segment
		(start 389.49884 -256.63017)
		(end 390.289542 -259.488178)
		(width 0.14732)
		(layer "In15.Cu")
		(net "P5E_CPU0_PE2_TX_DN<14>")
	)
	(segment
		(start 388.553198 -230.937562)
		(end 389.49503 -244.343428)
		(width 0.14732)
		(layer "In15.Cu")
		(net "P5E_CPU0_PE2_TX_DN<14>")
	)
	(segment
		(start 387.814312 -229.316788)
		(end 388.553198 -230.937562)
		(width 0.14732)
		(layer "In15.Cu")
		(net "P5E_CPU0_PE2_TX_DN<14>")
	)
	(segment
		(start 390.289542 -259.488178)
		(end 387.458204 -310.38546)
		(width 0.14732)
		(layer "In15.Cu")
		(net "P5E_CPU0_PE2_TX_DN<14>")
	)
	(segment
		(start 384.798062 -226.359466)
		(end 385.360926 -226.92233)
		(width 0.0889)
		(layer "In15.Cu")
		(net "P5E_CPU0_PE2_TX_DN<14>")
	)
	(segment
		(start 382.792732 -223.899984)
		(end 382.807464 -223.891348)
		(width 0.0889)
		(layer "In15.Cu")
		(net "P5E_CPU0_PE2_TX_DN<14>")
	)
	(segment
		(start 387.560566 -248.198894)
		(end 387.178804 -249.120406)
		(width 0.14732)
		(layer "In15.Cu")
		(net "P5E_CPU0_PE2_TX_DN<14>")
	)
	(segment
		(start 387.178804 -251.20854)
		(end 388.191502 -254.154178)
		(width 0.14732)
		(layer "In15.Cu")
		(net "P5E_CPU0_PE2_TX_DN<14>")
	)
	(segment
		(start 388.191502 -254.154178)
		(end 388.868666 -255.752854)
		(width 0.14732)
		(layer "In15.Cu")
		(net "P5E_CPU0_PE2_TX_DN<14>")
	)
	(segment
		(start 381.50927 -223.846644)
		(end 381.530352 -223.924622)
		(width 0.0889)
		(layer "In15.Cu")
		(net "P5E_CPU0_PE2_TX_DN<14>")
	)
	(segment
		(start 385.435348 -226.937824)
		(end 386.655564 -228.15804)
		(width 0.14732)
		(layer "In15.Cu")
		(net "P5E_CPU0_PE2_TX_DN<14>")
	)
	(segment
		(start 388.590282 -247.175274)
		(end 388.130034 -247.800368)
		(width 0.14732)
		(layer "In15.Cu")
		(net "P5E_CPU0_PE2_TX_DN<14>")
	)
	(segment
		(start 388.868666 -255.752854)
		(end 389.49884 -256.63017)
		(width 0.14732)
		(layer "In15.Cu")
		(net "P5E_CPU0_PE2_TX_DN<14>")
	)
	(segment
		(start 384.289046 -225.522536)
		(end 384.297936 -225.527616)
		(width 0.0889)
		(layer "In15.Cu")
		(net "P5E_CPU0_PE2_TX_DN<14>")
	)
	(segment
		(start 385.360926 -226.92233)
		(end 385.419854 -226.92233)
		(width 0.0889)
		(layer "In15.Cu")
		(net "P5E_CPU0_PE2_TX_DN<14>")
	)
	(segment
		(start 388.130034 -247.800368)
		(end 387.560566 -248.198894)
		(width 0.14732)
		(layer "In15.Cu")
		(net "P5E_CPU0_PE2_TX_DN<14>")
	)
	(segment
		(start 384.767328 -226.34194)
		(end 384.798062 -226.359466)
		(width 0.0889)
		(layer "In15.Cu")
		(net "P5E_CPU0_PE2_TX_DN<14>")
	)
	(segment
		(start 388.705852 -366.995456)
		(end 388.705344 -366.995964)
		(width 0.14732)
		(layer "In15.Cu")
		(net "P5E_CPU0_PE2_TX_DN<14>")
	)
	(segment
		(start 385.419854 -226.92233)
		(end 385.435348 -226.937824)
		(width 0.0889)
		(layer "In15.Cu")
		(net "P5E_CPU0_PE2_TX_DN<14>")
	)
	(segment
		(start 386.82803 -228.15804)
		(end 387.137148 -228.467158)
		(width 0.14732)
		(layer "In15.Cu")
		(net "P5E_CPU0_PE2_TX_DN<14>")
	)
	(segment
		(start 381.665734 -223.575626)
		(end 381.50927 -223.846644)
		(width 0.0889)
		(layer "In15.Cu")
		(net "P5E_CPU0_PE2_TX_DN<14>")
	)
	(segment
		(start 387.137148 -228.467158)
		(end 387.137148 -228.639624)
		(width 0.14732)
		(layer "In15.Cu")
		(net "P5E_CPU0_PE2_TX_DN<14>")
	)
	(segment
		(start 384.58013 -225.998532)
		(end 384.580384 -226.017074)
		(width 0.0889)
		(layer "In15.Cu")
		(net "P5E_CPU0_PE2_TX_DN<14>")
	)
	(segment
		(start 383.827274 -224.713292)
		(end 383.828036 -224.7138)
		(width 0.0889)
		(layer "In15.Cu")
		(net "P5E_CPU0_PE2_TX_DN<14>")
	)
	(segment
		(start 392.163808 -353.604322)
		(end 388.705852 -366.995456)
		(width 0.14732)
		(layer "In15.Cu")
		(net "P5E_CPU0_PE2_TX_DN<14>")
	)
	(segment
		(start 383.819146 -224.70872)
		(end 383.827274 -224.713292)
		(width 0.0889)
		(layer "In15.Cu")
		(net "P5E_CPU0_PE2_TX_DN<14>")
	)
	(segment
		(start 383.358136 -223.899984)
		(end 383.364232 -223.90354)
		(width 0.0889)
		(layer "In15.Cu")
		(net "P5E_CPU0_PE2_TX_DN<14>")
	)
	(segment
		(start 387.137148 -228.639624)
		(end 387.814312 -229.316788)
		(width 0.14732)
		(layer "In15.Cu")
		(net "P5E_CPU0_PE2_TX_DN<14>")
	)
	(segment
		(start 386.655564 -228.15804)
		(end 386.82803 -228.15804)
		(width 0.14732)
		(layer "In15.Cu")
		(net "P5E_CPU0_PE2_TX_DN<14>")
	)
	(arc
		(start 384.110484 -225.203258)
		(mid 384.158163 -225.386158)
		(end 384.289046 -225.522536)
		(width 0.0889)
		(layer "In15.Cu")
		(net "P5E_CPU0_PE2_TX_DN<14>")
	)
	(arc
		(start 383.640584 -224.389442)
		(mid 383.688263 -224.572342)
		(end 383.819146 -224.70872)
		(width 0.0889)
		(layer "In15.Cu")
		(net "P5E_CPU0_PE2_TX_DN<14>")
	)
	(arc
		(start 383.364232 -223.90354)
		(mid 383.566645 -224.109953)
		(end 383.640584 -224.389442)
		(width 0.0889)
		(layer "In15.Cu")
		(net "P5E_CPU0_PE2_TX_DN<14>")
	)
	(arc
		(start 382.807464 -223.891348)
		(mid 383.083939 -223.824028)
		(end 383.358136 -223.899984)
		(width 0.0889)
		(layer "In15.Cu")
		(net "P5E_CPU0_PE2_TX_DN<14>")
	)
	(arc
		(start 381.852932 -223.899984)
		(mid 382.135634 -223.824208)
		(end 382.418336 -223.899984)
		(width 0.0889)
		(layer "In15.Cu")
		(net "P5E_CPU0_PE2_TX_DN<14>")
	)
	(arc
		(start 383.828036 -224.7138)
		(mid 384.032371 -224.916405)
		(end 384.110484 -225.193352)
		(width 0.0889)
		(layer "In15.Cu")
		(net "P5E_CPU0_PE2_TX_DN<14>")
	)
	(arc
		(start 384.297936 -225.527616)
		(mid 384.499978 -225.726539)
		(end 384.58013 -225.998532)
		(width 0.0889)
		(layer "In15.Cu")
		(net "P5E_CPU0_PE2_TX_DN<14>")
	)
	(arc
		(start 384.580384 -226.029774)
		(mid 384.633468 -226.210045)
		(end 384.767328 -226.34194)
		(width 0.0889)
		(layer "In15.Cu")
		(net "P5E_CPU0_PE2_TX_DN<14>")
	)
	(arc
		(start 381.530352 -223.924622)
		(mid 381.694448 -223.948969)
		(end 381.852932 -223.899984)
		(width 0.0889)
		(layer "In15.Cu")
		(net "P5E_CPU0_PE2_TX_DN<14>")
	)
	(arc
		(start 384.580384 -226.017074)
		(mid 384.58033 -226.023424)
		(end 384.580384 -226.029774)
		(width 0.0889)
		(layer "In15.Cu")
		(net "P5E_CPU0_PE2_TX_DN<14>")
	)
	(arc
		(start 382.418336 -223.899984)
		(mid 382.605534 -223.950127)
		(end 382.792732 -223.899984)
		(width 0.0889)
		(layer "In15.Cu")
		(net "P5E_CPU0_PE2_TX_DN<14>")
	)
	(segment
		(start 378.114052 -401.779994)
		(end 378.43841 -402.104352)
		(width 0.13208)
		(layer "F.Cu")
		(net "P5E_CPU0_PE2_TX_DN<13>")
	)
	(segment
		(start 380.25578 -224.925382)
		(end 380.25578 -224.389696)
		(width 0.13208)
		(layer "F.Cu")
		(net "P5E_CPU0_PE2_TX_DN<13>")
	)
	(segment
		(start 378.114052 -401.157186)
		(end 378.114052 -401.779994)
		(width 0.13208)
		(layer "F.Cu")
		(net "P5E_CPU0_PE2_TX_DN<13>")
	)
	(segment
		(start 378.41301 -400.858228)
		(end 378.114052 -401.157186)
		(width 0.13208)
		(layer "F.Cu")
		(net "P5E_CPU0_PE2_TX_DN<13>")
	)
	(segment
		(start 380.25578 -224.389696)
		(end 380.256034 -224.389442)
		(width 0.13208)
		(layer "F.Cu")
		(net "P5E_CPU0_PE2_TX_DN<13>")
	)
	(segment
		(start 388.634986 -249.262138)
		(end 388.440676 -250.361196)
		(width 0.14732)
		(layer "In15.Cu")
		(net "P5E_CPU0_PE2_TX_DN<13>")
	)
	(segment
		(start 380.412498 -224.66046)
		(end 380.49073 -224.681288)
		(width 0.0889)
		(layer "In15.Cu")
		(net "P5E_CPU0_PE2_TX_DN<13>")
	)
	(segment
		(start 391.315956 -259.351526)
		(end 388.464806 -310.249316)
		(width 0.14732)
		(layer "In15.Cu")
		(net "P5E_CPU0_PE2_TX_DN<13>")
	)
	(segment
		(start 384.110484 -223.557084)
		(end 384.110484 -223.584262)
		(width 0.0889)
		(layer "In15.Cu")
		(net "P5E_CPU0_PE2_TX_DN<13>")
	)
	(segment
		(start 385.05003 -225.203258)
		(end 385.05003 -225.211132)
		(width 0.0889)
		(layer "In15.Cu")
		(net "P5E_CPU0_PE2_TX_DN<13>")
	)
	(segment
		(start 388.730744 -370.137436)
		(end 388.73049 -370.138198)
		(width 0.14732)
		(layer "In15.Cu")
		(net "P5E_CPU0_PE2_TX_DN<13>")
	)
	(segment
		(start 388.464806 -310.249316)
		(end 395.466062 -339.342984)
		(width 0.14732)
		(layer "In15.Cu")
		(net "P5E_CPU0_PE2_TX_DN<13>")
	)
	(segment
		(start 389.625586 -367.605564)
		(end 388.730744 -370.137436)
		(width 0.14732)
		(layer "In15.Cu")
		(net "P5E_CPU0_PE2_TX_DN<13>")
	)
	(segment
		(start 388.73049 -370.138198)
		(end 388.73049 -370.137944)
		(width 0.14732)
		(layer "In15.Cu")
		(net "P5E_CPU0_PE2_TX_DN<13>")
	)
	(segment
		(start 389.132826 -248.550684)
		(end 388.634986 -249.262138)
		(width 0.14732)
		(layer "In15.Cu")
		(net "P5E_CPU0_PE2_TX_DN<13>")
	)
	(segment
		(start 380.256034 -224.389442)
		(end 380.412498 -224.66046)
		(width 0.0889)
		(layer "In15.Cu")
		(net "P5E_CPU0_PE2_TX_DN<13>")
	)
	(segment
		(start 386.325364 -226.20605)
		(end 386.384292 -226.20605)
		(width 0.0889)
		(layer "In15.Cu")
		(net "P5E_CPU0_PE2_TX_DN<13>")
	)
	(segment
		(start 388.489952 -251.24918)
		(end 388.490206 -251.24918)
		(width 0.14732)
		(layer "In15.Cu")
		(net "P5E_CPU0_PE2_TX_DN<13>")
	)
	(segment
		(start 384.758946 -224.70872)
		(end 384.767074 -224.713292)
		(width 0.0889)
		(layer "In15.Cu")
		(net "P5E_CPU0_PE2_TX_DN<13>")
	)
	(segment
		(start 388.490206 -251.24918)
		(end 388.538974 -252.136402)
		(width 0.14732)
		(layer "In15.Cu")
		(net "P5E_CPU0_PE2_TX_DN<13>")
	)
	(segment
		(start 388.440676 -250.361196)
		(end 388.489952 -251.24918)
		(width 0.14732)
		(layer "In15.Cu")
		(net "P5E_CPU0_PE2_TX_DN<13>")
	)
	(segment
		(start 385.924806 -225.805492)
		(end 386.325364 -226.20605)
		(width 0.0889)
		(layer "In15.Cu")
		(net "P5E_CPU0_PE2_TX_DN<13>")
	)
	(segment
		(start 388.969758 -253.549912)
		(end 389.566658 -254.990346)
		(width 0.14732)
		(layer "In15.Cu")
		(net "P5E_CPU0_PE2_TX_DN<13>")
	)
	(segment
		(start 386.384292 -226.20605)
		(end 386.399786 -226.221544)
		(width 0.0889)
		(layer "In15.Cu")
		(net "P5E_CPU0_PE2_TX_DN<13>")
	)
	(segment
		(start 385.470146 -225.805492)
		(end 385.924806 -225.805492)
		(width 0.0889)
		(layer "In15.Cu")
		(net "P5E_CPU0_PE2_TX_DN<13>")
	)
	(segment
		(start 378.11837 -400.16049)
		(end 378.11837 -400.563588)
		(width 0.14732)
		(layer "In15.Cu")
		(net "P5E_CPU0_PE2_TX_DN<13>")
	)
	(segment
		(start 381.100584 -223.575626)
		(end 381.100584 -223.557084)
		(width 0.0889)
		(layer "In15.Cu")
		(net "P5E_CPU0_PE2_TX_DN<13>")
	)
	(segment
		(start 384.298444 -223.900492)
		(end 384.303778 -223.90354)
		(width 0.0889)
		(layer "In15.Cu")
		(net "P5E_CPU0_PE2_TX_DN<13>")
	)
	(segment
		(start 385.17957 -225.514916)
		(end 385.470146 -225.805492)
		(width 0.0889)
		(layer "In15.Cu")
		(net "P5E_CPU0_PE2_TX_DN<13>")
	)
	(segment
		(start 390.491218 -244.380512)
		(end 389.132826 -248.550684)
		(width 0.14732)
		(layer "In15.Cu")
		(net "P5E_CPU0_PE2_TX_DN<13>")
	)
	(segment
		(start 388.73049 -370.137944)
		(end 378.11837 -400.16049)
		(width 0.14732)
		(layer "In15.Cu")
		(net "P5E_CPU0_PE2_TX_DN<13>")
	)
	(segment
		(start 390.561576 -256.411476)
		(end 391.315956 -259.351526)
		(width 0.14732)
		(layer "In15.Cu")
		(net "P5E_CPU0_PE2_TX_DN<13>")
	)
	(segment
		(start 386.399786 -226.221544)
		(end 388.374382 -228.196394)
		(width 0.14732)
		(layer "In15.Cu")
		(net "P5E_CPU0_PE2_TX_DN<13>")
	)
	(segment
		(start 384.767074 -224.713292)
		(end 384.767836 -224.7138)
		(width 0.0889)
		(layer "In15.Cu")
		(net "P5E_CPU0_PE2_TX_DN<13>")
	)
	(segment
		(start 393.095226 -353.959414)
		(end 389.625586 -367.605564)
		(width 0.14732)
		(layer "In15.Cu")
		(net "P5E_CPU0_PE2_TX_DN<13>")
	)
	(segment
		(start 388.857744 -253.23165)
		(end 388.969758 -253.549912)
		(width 0.14732)
		(layer "In15.Cu")
		(net "P5E_CPU0_PE2_TX_DN<13>")
	)
	(segment
		(start 378.11837 -400.563588)
		(end 378.41301 -400.858228)
		(width 0.14732)
		(layer "In15.Cu")
		(net "P5E_CPU0_PE2_TX_DN<13>")
	)
	(segment
		(start 380.630684 -224.389442)
		(end 380.630684 -224.379536)
		(width 0.0889)
		(layer "In15.Cu")
		(net "P5E_CPU0_PE2_TX_DN<13>")
	)
	(segment
		(start 384.297682 -223.899984)
		(end 384.298444 -223.900492)
		(width 0.0889)
		(layer "In15.Cu")
		(net "P5E_CPU0_PE2_TX_DN<13>")
	)
	(segment
		(start 389.566658 -254.990346)
		(end 390.561576 -256.411476)
		(width 0.14732)
		(layer "In15.Cu")
		(net "P5E_CPU0_PE2_TX_DN<13>")
	)
	(segment
		(start 388.374382 -228.196394)
		(end 389.526272 -230.721408)
		(width 0.14732)
		(layer "In15.Cu")
		(net "P5E_CPU0_PE2_TX_DN<13>")
	)
	(segment
		(start 395.466062 -339.342984)
		(end 393.095226 -353.959414)
		(width 0.14732)
		(layer "In15.Cu")
		(net "P5E_CPU0_PE2_TX_DN<13>")
	)
	(segment
		(start 389.526272 -230.721408)
		(end 390.491218 -244.380512)
		(width 0.14732)
		(layer "In15.Cu")
		(net "P5E_CPU0_PE2_TX_DN<13>")
	)
	(segment
		(start 388.538974 -252.136402)
		(end 388.857744 -253.23165)
		(width 0.14732)
		(layer "In15.Cu")
		(net "P5E_CPU0_PE2_TX_DN<13>")
	)
	(segment
		(start 380.913132 -223.899984)
		(end 380.922022 -223.894904)
		(width 0.0889)
		(layer "In15.Cu")
		(net "P5E_CPU0_PE2_TX_DN<13>")
	)
	(arc
		(start 383.828036 -223.085914)
		(mid 384.030322 -223.284895)
		(end 384.110484 -223.557084)
		(width 0.0889)
		(layer "In15.Cu")
		(net "P5E_CPU0_PE2_TX_DN<13>")
	)
	(arc
		(start 381.383032 -223.085914)
		(mid 381.665734 -223.010172)
		(end 381.948436 -223.085914)
		(width 0.0889)
		(layer "In15.Cu")
		(net "P5E_CPU0_PE2_TX_DN<13>")
	)
	(arc
		(start 382.888236 -223.085914)
		(mid 383.075434 -223.136057)
		(end 383.262632 -223.085914)
		(width 0.0889)
		(layer "In15.Cu")
		(net "P5E_CPU0_PE2_TX_DN<13>")
	)
	(arc
		(start 385.05003 -225.211132)
		(mid 385.085395 -225.375564)
		(end 385.17957 -225.514916)
		(width 0.0889)
		(layer "In15.Cu")
		(net "P5E_CPU0_PE2_TX_DN<13>")
	)
	(arc
		(start 384.580384 -224.389442)
		(mid 384.628063 -224.572342)
		(end 384.758946 -224.70872)
		(width 0.0889)
		(layer "In15.Cu")
		(net "P5E_CPU0_PE2_TX_DN<13>")
	)
	(arc
		(start 382.322832 -223.085914)
		(mid 382.605534 -223.010172)
		(end 382.888236 -223.085914)
		(width 0.0889)
		(layer "In15.Cu")
		(net "P5E_CPU0_PE2_TX_DN<13>")
	)
	(arc
		(start 384.303778 -223.90354)
		(mid 384.506365 -224.109891)
		(end 384.580384 -224.389442)
		(width 0.0889)
		(layer "In15.Cu")
		(net "P5E_CPU0_PE2_TX_DN<13>")
	)
	(arc
		(start 384.781044 -224.721928)
		(mid 384.97822 -224.927563)
		(end 385.05003 -225.203258)
		(width 0.0889)
		(layer "In15.Cu")
		(net "P5E_CPU0_PE2_TX_DN<13>")
	)
	(arc
		(start 381.948436 -223.085914)
		(mid 382.135634 -223.136057)
		(end 382.322832 -223.085914)
		(width 0.0889)
		(layer "In15.Cu")
		(net "P5E_CPU0_PE2_TX_DN<13>")
	)
	(arc
		(start 384.110484 -223.584262)
		(mid 384.162754 -223.766627)
		(end 384.297682 -223.899984)
		(width 0.0889)
		(layer "In15.Cu")
		(net "P5E_CPU0_PE2_TX_DN<13>")
	)
	(arc
		(start 380.49073 -224.681288)
		(mid 380.593875 -224.551263)
		(end 380.630684 -224.389442)
		(width 0.0889)
		(layer "In15.Cu")
		(net "P5E_CPU0_PE2_TX_DN<13>")
	)
	(arc
		(start 384.767836 -224.7138)
		(mid 384.774467 -224.71782)
		(end 384.781044 -224.721928)
		(width 0.0889)
		(layer "In15.Cu")
		(net "P5E_CPU0_PE2_TX_DN<13>")
	)
	(arc
		(start 380.630684 -224.379536)
		(mid 380.708795 -224.102587)
		(end 380.913132 -223.899984)
		(width 0.0889)
		(layer "In15.Cu")
		(net "P5E_CPU0_PE2_TX_DN<13>")
	)
	(arc
		(start 381.100584 -223.557084)
		(mid 381.180746 -223.284895)
		(end 381.383032 -223.085914)
		(width 0.0889)
		(layer "In15.Cu")
		(net "P5E_CPU0_PE2_TX_DN<13>")
	)
	(arc
		(start 380.922022 -223.894904)
		(mid 381.052936 -223.758544)
		(end 381.100584 -223.575626)
		(width 0.0889)
		(layer "In15.Cu")
		(net "P5E_CPU0_PE2_TX_DN<13>")
	)
	(arc
		(start 383.262632 -223.085914)
		(mid 383.545334 -223.010172)
		(end 383.828036 -223.085914)
		(width 0.0889)
		(layer "In15.Cu")
		(net "P5E_CPU0_PE2_TX_DN<13>")
	)
	(segment
		(start 381.177292 -401.157186)
		(end 381.177292 -401.779994)
		(width 0.13208)
		(layer "F.Cu")
		(net "P5E_CPU0_PE2_TX_DN<12>")
	)
	(segment
		(start 379.786134 -224.111566)
		(end 379.786134 -223.57588)
		(width 0.13208)
		(layer "F.Cu")
		(net "P5E_CPU0_PE2_TX_DN<12>")
	)
	(segment
		(start 381.177292 -401.779994)
		(end 381.50165 -402.104352)
		(width 0.13208)
		(layer "F.Cu")
		(net "P5E_CPU0_PE2_TX_DN<12>")
	)
	(segment
		(start 381.47625 -400.858228)
		(end 381.177292 -401.157186)
		(width 0.13208)
		(layer "F.Cu")
		(net "P5E_CPU0_PE2_TX_DN<12>")
	)
	(segment
		(start 379.786134 -223.57588)
		(end 379.78588 -223.575626)
		(width 0.13208)
		(layer "F.Cu")
		(net "P5E_CPU0_PE2_TX_DN<12>")
	)
	(segment
		(start 394.00607 -354.252022)
		(end 390.124696 -369.71859)
		(width 0.14732)
		(layer "In15.Cu")
		(net "P5E_CPU0_PE2_TX_DN<12>")
	)
	(segment
		(start 390.39038 -254.545338)
		(end 390.93394 -255.321562)
		(width 0.14732)
		(layer "In15.Cu")
		(net "P5E_CPU0_PE2_TX_DN<12>")
	)
	(segment
		(start 385.237736 -222.272098)
		(end 385.243832 -222.275654)
		(width 0.0889)
		(layer "In15.Cu")
		(net "P5E_CPU0_PE2_TX_DN<12>")
	)
	(segment
		(start 390.93394 -255.321816)
		(end 391.523728 -256.164588)
		(width 0.14732)
		(layer "In15.Cu")
		(net "P5E_CPU0_PE2_TX_DN<12>")
	)
	(segment
		(start 387.17982 -223.532192)
		(end 387.42366 -223.775778)
		(width 0.14732)
		(layer "In15.Cu")
		(net "P5E_CPU0_PE2_TX_DN<12>")
	)
	(segment
		(start 381.18161 -400.563588)
		(end 381.47625 -400.858228)
		(width 0.14732)
		(layer "In15.Cu")
		(net "P5E_CPU0_PE2_TX_DN<12>")
	)
	(segment
		(start 385.698746 -223.080834)
		(end 385.707636 -223.085914)
		(width 0.0889)
		(layer "In15.Cu")
		(net "P5E_CPU0_PE2_TX_DN<12>")
	)
	(segment
		(start 381.18161 -400.15287)
		(end 381.18161 -400.563588)
		(width 0.14732)
		(layer "In15.Cu")
		(net "P5E_CPU0_PE2_TX_DN<12>")
	)
	(segment
		(start 390.124696 -369.71859)
		(end 381.18161 -400.15287)
		(width 0.14732)
		(layer "In15.Cu")
		(net "P5E_CPU0_PE2_TX_DN<12>")
	)
	(segment
		(start 387.164326 -223.516698)
		(end 387.17982 -223.532192)
		(width 0.0889)
		(layer "In15.Cu")
		(net "P5E_CPU0_PE2_TX_DN<12>")
	)
	(segment
		(start 390.726676 -246.71274)
		(end 390.00557 -248.926096)
		(width 0.14732)
		(layer "In15.Cu")
		(net "P5E_CPU0_PE2_TX_DN<12>")
	)
	(segment
		(start 394.008356 -354.235004)
		(end 394.00607 -354.252022)
		(width 0.14732)
		(layer "In15.Cu")
		(net "P5E_CPU0_PE2_TX_DN<12>")
	)
	(segment
		(start 389.413242 -310.008524)
		(end 396.428976 -339.356954)
		(width 0.14732)
		(layer "In15.Cu")
		(net "P5E_CPU0_PE2_TX_DN<12>")
	)
	(segment
		(start 380.630684 -222.761556)
		(end 380.630684 -222.746062)
		(width 0.0889)
		(layer "In15.Cu")
		(net "P5E_CPU0_PE2_TX_DN<12>")
	)
	(segment
		(start 390.00557 -248.926096)
		(end 389.692134 -249.374152)
		(width 0.14732)
		(layer "In15.Cu")
		(net "P5E_CPU0_PE2_TX_DN<12>")
	)
	(segment
		(start 389.692134 -249.374152)
		(end 389.499348 -250.46559)
		(width 0.14732)
		(layer "In15.Cu")
		(net "P5E_CPU0_PE2_TX_DN<12>")
	)
	(segment
		(start 391.523728 -256.164588)
		(end 392.295126 -259.261102)
		(width 0.14732)
		(layer "In15.Cu")
		(net "P5E_CPU0_PE2_TX_DN<12>")
	)
	(segment
		(start 387.42366 -223.775778)
		(end 389.890508 -228.340412)
		(width 0.14732)
		(layer "In15.Cu")
		(net "P5E_CPU0_PE2_TX_DN<12>")
	)
	(segment
		(start 389.499348 -252.098048)
		(end 389.764016 -253.00559)
		(width 0.14732)
		(layer "In15.Cu")
		(net "P5E_CPU0_PE2_TX_DN<12>")
	)
	(segment
		(start 379.78588 -223.575626)
		(end 379.629416 -223.846644)
		(width 0.0889)
		(layer "In15.Cu")
		(net "P5E_CPU0_PE2_TX_DN<12>")
	)
	(segment
		(start 390.93394 -255.321562)
		(end 390.93394 -255.321816)
		(width 0.14732)
		(layer "In15.Cu")
		(net "P5E_CPU0_PE2_TX_DN<12>")
	)
	(segment
		(start 382.407668 -222.266002)
		(end 382.418082 -222.272098)
		(width 0.0889)
		(layer "In15.Cu")
		(net "P5E_CPU0_PE2_TX_DN<12>")
	)
	(segment
		(start 380.16053 -223.575626)
		(end 380.16053 -223.568006)
		(width 0.0889)
		(layer "In15.Cu")
		(net "P5E_CPU0_PE2_TX_DN<12>")
	)
	(segment
		(start 389.829802 -253.193042)
		(end 390.39038 -254.545338)
		(width 0.14732)
		(layer "In15.Cu")
		(net "P5E_CPU0_PE2_TX_DN<12>")
	)
	(segment
		(start 391.4521 -244.486938)
		(end 390.726676 -246.71274)
		(width 0.14732)
		(layer "In15.Cu")
		(net "P5E_CPU0_PE2_TX_DN<12>")
	)
	(segment
		(start 379.973078 -223.899984)
		(end 379.974094 -223.899476)
		(width 0.0889)
		(layer "In15.Cu")
		(net "P5E_CPU0_PE2_TX_DN<12>")
	)
	(segment
		(start 384.672078 -222.272098)
		(end 384.682492 -222.266002)
		(width 0.0889)
		(layer "In15.Cu")
		(net "P5E_CPU0_PE2_TX_DN<12>")
	)
	(segment
		(start 380.443232 -223.085914)
		(end 380.452122 -223.080834)
		(width 0.0889)
		(layer "In15.Cu")
		(net "P5E_CPU0_PE2_TX_DN<12>")
	)
	(segment
		(start 389.890508 -228.340412)
		(end 390.456674 -230.479854)
		(width 0.14732)
		(layer "In15.Cu")
		(net "P5E_CPU0_PE2_TX_DN<12>")
	)
	(segment
		(start 396.428976 -339.356954)
		(end 394.008356 -354.235004)
		(width 0.14732)
		(layer "In15.Cu")
		(net "P5E_CPU0_PE2_TX_DN<12>")
	)
	(segment
		(start 379.629416 -223.846644)
		(end 379.650498 -223.924622)
		(width 0.0889)
		(layer "In15.Cu")
		(net "P5E_CPU0_PE2_TX_DN<12>")
	)
	(segment
		(start 381.468122 -222.266002)
		(end 381.478536 -222.272098)
		(width 0.0889)
		(layer "In15.Cu")
		(net "P5E_CPU0_PE2_TX_DN<12>")
	)
	(segment
		(start 383.347722 -222.266002)
		(end 383.358136 -222.272098)
		(width 0.0889)
		(layer "In15.Cu")
		(net "P5E_CPU0_PE2_TX_DN<12>")
	)
	(segment
		(start 387.105398 -223.516698)
		(end 387.164326 -223.516698)
		(width 0.0889)
		(layer "In15.Cu")
		(net "P5E_CPU0_PE2_TX_DN<12>")
	)
	(segment
		(start 386.76453 -223.17583)
		(end 387.105398 -223.516698)
		(width 0.0889)
		(layer "In15.Cu")
		(net "P5E_CPU0_PE2_TX_DN<12>")
	)
	(segment
		(start 389.499348 -250.46559)
		(end 389.499348 -252.098048)
		(width 0.14732)
		(layer "In15.Cu")
		(net "P5E_CPU0_PE2_TX_DN<12>")
	)
	(segment
		(start 390.456674 -230.479854)
		(end 391.4521 -244.486938)
		(width 0.14732)
		(layer "In15.Cu")
		(net "P5E_CPU0_PE2_TX_DN<12>")
	)
	(segment
		(start 379.974094 -223.899476)
		(end 379.981968 -223.894904)
		(width 0.0889)
		(layer "In15.Cu")
		(net "P5E_CPU0_PE2_TX_DN<12>")
	)
	(segment
		(start 384.287268 -222.266002)
		(end 384.297682 -222.272098)
		(width 0.0889)
		(layer "In15.Cu")
		(net "P5E_CPU0_PE2_TX_DN<12>")
	)
	(segment
		(start 392.295126 -259.261102)
		(end 389.413242 -310.008524)
		(width 0.14732)
		(layer "In15.Cu")
		(net "P5E_CPU0_PE2_TX_DN<12>")
	)
	(segment
		(start 389.764016 -253.00559)
		(end 389.829802 -253.193042)
		(width 0.14732)
		(layer "In15.Cu")
		(net "P5E_CPU0_PE2_TX_DN<12>")
	)
	(arc
		(start 382.792478 -222.272098)
		(mid 383.069291 -222.196228)
		(end 383.347722 -222.266002)
		(width 0.0889)
		(layer "In15.Cu")
		(net "P5E_CPU0_PE2_TX_DN<12>")
	)
	(arc
		(start 379.981968 -223.894904)
		(mid 380.112882 -223.758544)
		(end 380.16053 -223.575626)
		(width 0.0889)
		(layer "In15.Cu")
		(net "P5E_CPU0_PE2_TX_DN<12>")
	)
	(arc
		(start 381.852932 -222.272098)
		(mid 382.129491 -222.196355)
		(end 382.407668 -222.266002)
		(width 0.0889)
		(layer "In15.Cu")
		(net "P5E_CPU0_PE2_TX_DN<12>")
	)
	(arc
		(start 384.297682 -222.272098)
		(mid 384.48488 -222.322241)
		(end 384.672078 -222.272098)
		(width 0.0889)
		(layer "In15.Cu")
		(net "P5E_CPU0_PE2_TX_DN<12>")
	)
	(arc
		(start 386.082032 -223.085914)
		(mid 386.438555 -223.015011)
		(end 386.76453 -223.17583)
		(width 0.0889)
		(layer "In15.Cu")
		(net "P5E_CPU0_PE2_TX_DN<12>")
	)
	(arc
		(start 384.682492 -222.266002)
		(mid 384.960924 -222.196156)
		(end 385.237736 -222.272098)
		(width 0.0889)
		(layer "In15.Cu")
		(net "P5E_CPU0_PE2_TX_DN<12>")
	)
	(arc
		(start 380.912878 -222.272098)
		(mid 381.189691 -222.196228)
		(end 381.468122 -222.266002)
		(width 0.0889)
		(layer "In15.Cu")
		(net "P5E_CPU0_PE2_TX_DN<12>")
	)
	(arc
		(start 383.358136 -222.272098)
		(mid 383.545334 -222.322241)
		(end 383.732532 -222.272098)
		(width 0.0889)
		(layer "In15.Cu")
		(net "P5E_CPU0_PE2_TX_DN<12>")
	)
	(arc
		(start 379.650498 -223.924622)
		(mid 379.814594 -223.948969)
		(end 379.973078 -223.899984)
		(width 0.0889)
		(layer "In15.Cu")
		(net "P5E_CPU0_PE2_TX_DN<12>")
	)
	(arc
		(start 380.16053 -223.568006)
		(mid 380.238159 -223.289593)
		(end 380.443232 -223.085914)
		(width 0.0889)
		(layer "In15.Cu")
		(net "P5E_CPU0_PE2_TX_DN<12>")
	)
	(arc
		(start 382.418082 -222.272098)
		(mid 382.60528 -222.322241)
		(end 382.792478 -222.272098)
		(width 0.0889)
		(layer "In15.Cu")
		(net "P5E_CPU0_PE2_TX_DN<12>")
	)
	(arc
		(start 385.520184 -222.761556)
		(mid 385.567863 -222.944456)
		(end 385.698746 -223.080834)
		(width 0.0889)
		(layer "In15.Cu")
		(net "P5E_CPU0_PE2_TX_DN<12>")
	)
	(arc
		(start 385.707636 -223.085914)
		(mid 385.894834 -223.136057)
		(end 386.082032 -223.085914)
		(width 0.0889)
		(layer "In15.Cu")
		(net "P5E_CPU0_PE2_TX_DN<12>")
	)
	(arc
		(start 381.478536 -222.272098)
		(mid 381.665734 -222.322241)
		(end 381.852932 -222.272098)
		(width 0.0889)
		(layer "In15.Cu")
		(net "P5E_CPU0_PE2_TX_DN<12>")
	)
	(arc
		(start 383.732532 -222.272098)
		(mid 384.009091 -222.196355)
		(end 384.287268 -222.266002)
		(width 0.0889)
		(layer "In15.Cu")
		(net "P5E_CPU0_PE2_TX_DN<12>")
	)
	(arc
		(start 380.630684 -222.746062)
		(mid 380.710054 -222.472328)
		(end 380.912878 -222.272098)
		(width 0.0889)
		(layer "In15.Cu")
		(net "P5E_CPU0_PE2_TX_DN<12>")
	)
	(arc
		(start 385.243832 -222.275654)
		(mid 385.446245 -222.482067)
		(end 385.520184 -222.761556)
		(width 0.0889)
		(layer "In15.Cu")
		(net "P5E_CPU0_PE2_TX_DN<12>")
	)
	(arc
		(start 380.452122 -223.080834)
		(mid 380.583036 -222.944474)
		(end 380.630684 -222.761556)
		(width 0.0889)
		(layer "In15.Cu")
		(net "P5E_CPU0_PE2_TX_DN<12>")
	)
	(segment
		(start 378.37618 -224.389696)
		(end 378.376434 -224.389442)
		(width 0.13208)
		(layer "F.Cu")
		(net "P5E_CPU0_PE2_TX_DN<11>")
	)
	(segment
		(start 384.53949 -400.858228)
		(end 384.240532 -401.157186)
		(width 0.13208)
		(layer "F.Cu")
		(net "P5E_CPU0_PE2_TX_DN<11>")
	)
	(segment
		(start 384.240532 -401.157186)
		(end 384.240532 -401.779994)
		(width 0.13208)
		(layer "F.Cu")
		(net "P5E_CPU0_PE2_TX_DN<11>")
	)
	(segment
		(start 378.37618 -224.925382)
		(end 378.37618 -224.389696)
		(width 0.13208)
		(layer "F.Cu")
		(net "P5E_CPU0_PE2_TX_DN<11>")
	)
	(segment
		(start 384.240532 -401.779994)
		(end 384.56489 -402.104352)
		(width 0.13208)
		(layer "F.Cu")
		(net "P5E_CPU0_PE2_TX_DN<11>")
	)
	(segment
		(start 390.515348 -250.59894)
		(end 390.515348 -252.258322)
		(width 0.14732)
		(layer "In15.Cu")
		(net "P5E_CPU0_PE2_TX_DN<11>")
	)
	(segment
		(start 381.100584 -220.319854)
		(end 381.100584 -220.309948)
		(width 0.0889)
		(layer "In15.Cu")
		(net "P5E_CPU0_PE2_TX_DN<11>")
	)
	(segment
		(start 394.915898 -354.51669)
		(end 384.258566 -400.073368)
		(width 0.14732)
		(layer "In15.Cu")
		(net "P5E_CPU0_PE2_TX_DN<11>")
	)
	(segment
		(start 386.459984 -221.115382)
		(end 386.459984 -221.133924)
		(width 0.0889)
		(layer "In15.Cu")
		(net "P5E_CPU0_PE2_TX_DN<11>")
	)
	(segment
		(start 390.7155 -252.901196)
		(end 391.0457 -253.697232)
		(width 0.14732)
		(layer "In15.Cu")
		(net "P5E_CPU0_PE2_TX_DN<11>")
	)
	(segment
		(start 392.411966 -244.579394)
		(end 390.873234 -249.308366)
		(width 0.14732)
		(layer "In15.Cu")
		(net "P5E_CPU0_PE2_TX_DN<11>")
	)
	(segment
		(start 390.702292 -227.681536)
		(end 391.446766 -230.577136)
		(width 0.14732)
		(layer "In15.Cu")
		(net "P5E_CPU0_PE2_TX_DN<11>")
	)
	(segment
		(start 384.757168 -219.8243)
		(end 384.767582 -219.830396)
		(width 0.0889)
		(layer "In15.Cu")
		(net "P5E_CPU0_PE2_TX_DN<11>")
	)
	(segment
		(start 378.751084 -224.389442)
		(end 378.751084 -224.379536)
		(width 0.0889)
		(layer "In15.Cu")
		(net "P5E_CPU0_PE2_TX_DN<11>")
	)
	(segment
		(start 387.686042 -222.409512)
		(end 388.047992 -222.771208)
		(width 0.14732)
		(layer "In15.Cu")
		(net "P5E_CPU0_PE2_TX_DN<11>")
	)
	(segment
		(start 380.443232 -221.458282)
		(end 380.444756 -221.45752)
		(width 0.0889)
		(layer "In15.Cu")
		(net "P5E_CPU0_PE2_TX_DN<11>")
	)
	(segment
		(start 384.258566 -400.577304)
		(end 384.53949 -400.858228)
		(width 0.14732)
		(layer "In15.Cu")
		(net "P5E_CPU0_PE2_TX_DN<11>")
	)
	(segment
		(start 378.376434 -224.389442)
		(end 378.532898 -224.66046)
		(width 0.0889)
		(layer "In15.Cu")
		(net "P5E_CPU0_PE2_TX_DN<11>")
	)
	(segment
		(start 379.690884 -222.761556)
		(end 379.690884 -222.746062)
		(width 0.0889)
		(layer "In15.Cu")
		(net "P5E_CPU0_PE2_TX_DN<11>")
	)
	(segment
		(start 391.0457 -253.697232)
		(end 392.627358 -255.956054)
		(width 0.14732)
		(layer "In15.Cu")
		(net "P5E_CPU0_PE2_TX_DN<11>")
	)
	(segment
		(start 391.446766 -230.577136)
		(end 391.928604 -237.564422)
		(width 0.14732)
		(layer "In15.Cu")
		(net "P5E_CPU0_PE2_TX_DN<11>")
	)
	(segment
		(start 390.699244 -249.557286)
		(end 390.515348 -250.59894)
		(width 0.14732)
		(layer "In15.Cu")
		(net "P5E_CPU0_PE2_TX_DN<11>")
	)
	(segment
		(start 390.486138 -226.920552)
		(end 390.702292 -227.681536)
		(width 0.14732)
		(layer "In15.Cu")
		(net "P5E_CPU0_PE2_TX_DN<11>")
	)
	(segment
		(start 380.444756 -221.45752)
		(end 380.452122 -221.453202)
		(width 0.0889)
		(layer "In15.Cu")
		(net "P5E_CPU0_PE2_TX_DN<11>")
	)
	(segment
		(start 384.768344 -219.830904)
		(end 384.773678 -219.833952)
		(width 0.0889)
		(layer "In15.Cu")
		(net "P5E_CPU0_PE2_TX_DN<11>")
	)
	(segment
		(start 379.973078 -222.272098)
		(end 379.981968 -222.267018)
		(width 0.0889)
		(layer "In15.Cu")
		(net "P5E_CPU0_PE2_TX_DN<11>")
	)
	(segment
		(start 379.503432 -223.085914)
		(end 379.512322 -223.080834)
		(width 0.0889)
		(layer "In15.Cu")
		(net "P5E_CPU0_PE2_TX_DN<11>")
	)
	(segment
		(start 388.047992 -222.771208)
		(end 390.486138 -226.920552)
		(width 0.14732)
		(layer "In15.Cu")
		(net "P5E_CPU0_PE2_TX_DN<11>")
	)
	(segment
		(start 379.22073 -223.584262)
		(end 379.22073 -223.561402)
		(width 0.0889)
		(layer "In15.Cu")
		(net "P5E_CPU0_PE2_TX_DN<11>")
	)
	(segment
		(start 380.913132 -220.644212)
		(end 380.922022 -220.639132)
		(width 0.0889)
		(layer "In15.Cu")
		(net "P5E_CPU0_PE2_TX_DN<11>")
	)
	(segment
		(start 392.627358 -255.956054)
		(end 393.338812 -259.170932)
		(width 0.14732)
		(layer "In15.Cu")
		(net "P5E_CPU0_PE2_TX_DN<11>")
	)
	(segment
		(start 390.373108 -309.925212)
		(end 397.467328 -339.389466)
		(width 0.14732)
		(layer "In15.Cu")
		(net "P5E_CPU0_PE2_TX_DN<11>")
	)
	(segment
		(start 387.670548 -222.394018)
		(end 387.686042 -222.409512)
		(width 0.0889)
		(layer "In15.Cu")
		(net "P5E_CPU0_PE2_TX_DN<11>")
	)
	(segment
		(start 390.515348 -252.258322)
		(end 390.7155 -252.901196)
		(width 0.14732)
		(layer "In15.Cu")
		(net "P5E_CPU0_PE2_TX_DN<11>")
	)
	(segment
		(start 380.630684 -221.133924)
		(end 380.630684 -221.115382)
		(width 0.0889)
		(layer "In15.Cu")
		(net "P5E_CPU0_PE2_TX_DN<11>")
	)
	(segment
		(start 378.532898 -224.66046)
		(end 378.61113 -224.681288)
		(width 0.0889)
		(layer "In15.Cu")
		(net "P5E_CPU0_PE2_TX_DN<11>")
	)
	(segment
		(start 386.76453 -221.547944)
		(end 387.610604 -222.394018)
		(width 0.0889)
		(layer "In15.Cu")
		(net "P5E_CPU0_PE2_TX_DN<11>")
	)
	(segment
		(start 384.258566 -400.073368)
		(end 384.258566 -400.577304)
		(width 0.14732)
		(layer "In15.Cu")
		(net "P5E_CPU0_PE2_TX_DN<11>")
	)
	(segment
		(start 380.437136 -221.461838)
		(end 380.440438 -221.459806)
		(width 0.0889)
		(layer "In15.Cu")
		(net "P5E_CPU0_PE2_TX_DN<11>")
	)
	(segment
		(start 390.873234 -249.308366)
		(end 390.699244 -249.557286)
		(width 0.14732)
		(layer "In15.Cu")
		(net "P5E_CPU0_PE2_TX_DN<11>")
	)
	(segment
		(start 384.767582 -219.830396)
		(end 384.768344 -219.830904)
		(width 0.0889)
		(layer "In15.Cu")
		(net "P5E_CPU0_PE2_TX_DN<11>")
	)
	(segment
		(start 387.610604 -222.394018)
		(end 387.670548 -222.394018)
		(width 0.0889)
		(layer "In15.Cu")
		(net "P5E_CPU0_PE2_TX_DN<11>")
	)
	(segment
		(start 385.228846 -220.639132)
		(end 385.237736 -220.644212)
		(width 0.0889)
		(layer "In15.Cu")
		(net "P5E_CPU0_PE2_TX_DN<11>")
	)
	(segment
		(start 382.322832 -219.830396)
		(end 382.337564 -219.82176)
		(width 0.0889)
		(layer "In15.Cu")
		(net "P5E_CPU0_PE2_TX_DN<11>")
	)
	(segment
		(start 391.928604 -237.564422)
		(end 392.411966 -244.579394)
		(width 0.14732)
		(layer "In15.Cu")
		(net "P5E_CPU0_PE2_TX_DN<11>")
	)
	(segment
		(start 393.338812 -259.170932)
		(end 390.373108 -309.925212)
		(width 0.14732)
		(layer "In15.Cu")
		(net "P5E_CPU0_PE2_TX_DN<11>")
	)
	(segment
		(start 397.467328 -339.389466)
		(end 394.915898 -354.51669)
		(width 0.14732)
		(layer "In15.Cu")
		(net "P5E_CPU0_PE2_TX_DN<11>")
	)
	(segment
		(start 380.440438 -221.459806)
		(end 380.443232 -221.458282)
		(width 0.0889)
		(layer "In15.Cu")
		(net "P5E_CPU0_PE2_TX_DN<11>")
	)
	(arc
		(start 379.690884 -222.746062)
		(mid 379.770254 -222.472328)
		(end 379.973078 -222.272098)
		(width 0.0889)
		(layer "In15.Cu")
		(net "P5E_CPU0_PE2_TX_DN<11>")
	)
	(arc
		(start 380.16053 -221.94774)
		(mid 380.234521 -221.668174)
		(end 380.437136 -221.461838)
		(width 0.0889)
		(layer "In15.Cu")
		(net "P5E_CPU0_PE2_TX_DN<11>")
	)
	(arc
		(start 380.452122 -221.453202)
		(mid 380.583036 -221.316842)
		(end 380.630684 -221.133924)
		(width 0.0889)
		(layer "In15.Cu")
		(net "P5E_CPU0_PE2_TX_DN<11>")
	)
	(arc
		(start 378.61113 -224.681288)
		(mid 378.714275 -224.551263)
		(end 378.751084 -224.389442)
		(width 0.0889)
		(layer "In15.Cu")
		(net "P5E_CPU0_PE2_TX_DN<11>")
	)
	(arc
		(start 380.922022 -220.639132)
		(mid 381.052936 -220.502772)
		(end 381.100584 -220.319854)
		(width 0.0889)
		(layer "In15.Cu")
		(net "P5E_CPU0_PE2_TX_DN<11>")
	)
	(arc
		(start 384.202432 -219.830396)
		(mid 384.478991 -219.754653)
		(end 384.757168 -219.8243)
		(width 0.0889)
		(layer "In15.Cu")
		(net "P5E_CPU0_PE2_TX_DN<11>")
	)
	(arc
		(start 380.630684 -221.115382)
		(mid 380.710846 -220.843193)
		(end 380.913132 -220.644212)
		(width 0.0889)
		(layer "In15.Cu")
		(net "P5E_CPU0_PE2_TX_DN<11>")
	)
	(arc
		(start 386.177536 -220.644212)
		(mid 386.379822 -220.843193)
		(end 386.459984 -221.115382)
		(width 0.0889)
		(layer "In15.Cu")
		(net "P5E_CPU0_PE2_TX_DN<11>")
	)
	(arc
		(start 386.459984 -221.133924)
		(mid 386.507663 -221.316824)
		(end 386.638546 -221.453202)
		(width 0.0889)
		(layer "In15.Cu")
		(net "P5E_CPU0_PE2_TX_DN<11>")
	)
	(arc
		(start 382.337564 -219.82176)
		(mid 382.614039 -219.75444)
		(end 382.888236 -219.830396)
		(width 0.0889)
		(layer "In15.Cu")
		(net "P5E_CPU0_PE2_TX_DN<11>")
	)
	(arc
		(start 379.22073 -223.561402)
		(mid 379.299949 -223.286717)
		(end 379.503432 -223.085914)
		(width 0.0889)
		(layer "In15.Cu")
		(net "P5E_CPU0_PE2_TX_DN<11>")
	)
	(arc
		(start 381.383032 -219.830396)
		(mid 381.665734 -219.75462)
		(end 381.948436 -219.830396)
		(width 0.0889)
		(layer "In15.Cu")
		(net "P5E_CPU0_PE2_TX_DN<11>")
	)
	(arc
		(start 385.237736 -220.644212)
		(mid 385.424934 -220.694355)
		(end 385.612132 -220.644212)
		(width 0.0889)
		(layer "In15.Cu")
		(net "P5E_CPU0_PE2_TX_DN<11>")
	)
	(arc
		(start 386.638546 -221.453202)
		(mid 386.70485 -221.496168)
		(end 386.76453 -221.547944)
		(width 0.0889)
		(layer "In15.Cu")
		(net "P5E_CPU0_PE2_TX_DN<11>")
	)
	(arc
		(start 379.512322 -223.080834)
		(mid 379.643236 -222.944474)
		(end 379.690884 -222.761556)
		(width 0.0889)
		(layer "In15.Cu")
		(net "P5E_CPU0_PE2_TX_DN<11>")
	)
	(arc
		(start 385.050284 -220.319854)
		(mid 385.097963 -220.502754)
		(end 385.228846 -220.639132)
		(width 0.0889)
		(layer "In15.Cu")
		(net "P5E_CPU0_PE2_TX_DN<11>")
	)
	(arc
		(start 385.612132 -220.644212)
		(mid 385.894834 -220.56847)
		(end 386.177536 -220.644212)
		(width 0.0889)
		(layer "In15.Cu")
		(net "P5E_CPU0_PE2_TX_DN<11>")
	)
	(arc
		(start 379.981968 -222.267018)
		(mid 380.112882 -222.130658)
		(end 380.16053 -221.94774)
		(width 0.0889)
		(layer "In15.Cu")
		(net "P5E_CPU0_PE2_TX_DN<11>")
	)
	(arc
		(start 379.033532 -223.899984)
		(mid 379.168465 -223.76663)
		(end 379.22073 -223.584262)
		(width 0.0889)
		(layer "In15.Cu")
		(net "P5E_CPU0_PE2_TX_DN<11>")
	)
	(arc
		(start 382.888236 -219.830396)
		(mid 383.075434 -219.880539)
		(end 383.262632 -219.830396)
		(width 0.0889)
		(layer "In15.Cu")
		(net "P5E_CPU0_PE2_TX_DN<11>")
	)
	(arc
		(start 378.751084 -224.379536)
		(mid 378.829195 -224.102587)
		(end 379.033532 -223.899984)
		(width 0.0889)
		(layer "In15.Cu")
		(net "P5E_CPU0_PE2_TX_DN<11>")
	)
	(arc
		(start 384.773678 -219.833952)
		(mid 384.976265 -220.040303)
		(end 385.050284 -220.319854)
		(width 0.0889)
		(layer "In15.Cu")
		(net "P5E_CPU0_PE2_TX_DN<11>")
	)
	(arc
		(start 381.948436 -219.830396)
		(mid 382.135634 -219.880539)
		(end 382.322832 -219.830396)
		(width 0.0889)
		(layer "In15.Cu")
		(net "P5E_CPU0_PE2_TX_DN<11>")
	)
	(arc
		(start 383.262632 -219.830396)
		(mid 383.545334 -219.75462)
		(end 383.828036 -219.830396)
		(width 0.0889)
		(layer "In15.Cu")
		(net "P5E_CPU0_PE2_TX_DN<11>")
	)
	(arc
		(start 381.100584 -220.309948)
		(mid 381.178695 -220.032999)
		(end 381.383032 -219.830396)
		(width 0.0889)
		(layer "In15.Cu")
		(net "P5E_CPU0_PE2_TX_DN<11>")
	)
	(arc
		(start 383.828036 -219.830396)
		(mid 384.015234 -219.880539)
		(end 384.202432 -219.830396)
		(width 0.0889)
		(layer "In15.Cu")
		(net "P5E_CPU0_PE2_TX_DN<11>")
	)
	(segment
		(start 387.60273 -400.858228)
		(end 387.303772 -401.157186)
		(width 0.13208)
		(layer "F.Cu")
		(net "P5E_CPU0_PE2_TX_DN<10>")
	)
	(segment
		(start 377.906534 -223.57588)
		(end 377.90628 -223.575626)
		(width 0.13208)
		(layer "F.Cu")
		(net "P5E_CPU0_PE2_TX_DN<10>")
	)
	(segment
		(start 377.906534 -224.111566)
		(end 377.906534 -223.57588)
		(width 0.13208)
		(layer "F.Cu")
		(net "P5E_CPU0_PE2_TX_DN<10>")
	)
	(segment
		(start 387.303772 -401.779994)
		(end 387.62813 -402.104352)
		(width 0.13208)
		(layer "F.Cu")
		(net "P5E_CPU0_PE2_TX_DN<10>")
	)
	(segment
		(start 387.303772 -401.157186)
		(end 387.303772 -401.779994)
		(width 0.13208)
		(layer "F.Cu")
		(net "P5E_CPU0_PE2_TX_DN<10>")
	)
	(segment
		(start 391.455148 -252.118622)
		(end 391.59053 -252.582426)
		(width 0.14732)
		(layer "In15.Cu")
		(net "P5E_CPU0_PE2_TX_DN<10>")
	)
	(segment
		(start 393.361164 -244.71884)
		(end 393.36472 -244.771926)
		(width 0.14732)
		(layer "In15.Cu")
		(net "P5E_CPU0_PE2_TX_DN<10>")
	)
	(segment
		(start 387.02869 -220.184726)
		(end 387.087618 -220.184726)
		(width 0.0889)
		(layer "In15.Cu")
		(net "P5E_CPU0_PE2_TX_DN<10>")
	)
	(segment
		(start 387.087618 -220.184726)
		(end 387.103112 -220.20022)
		(width 0.0889)
		(layer "In15.Cu")
		(net "P5E_CPU0_PE2_TX_DN<10>")
	)
	(segment
		(start 379.497336 -221.461838)
		(end 379.500638 -221.459806)
		(width 0.0889)
		(layer "In15.Cu")
		(net "P5E_CPU0_PE2_TX_DN<10>")
	)
	(segment
		(start 386.932424 -220.08846)
		(end 387.02869 -220.184726)
		(width 0.0889)
		(layer "In15.Cu")
		(net "P5E_CPU0_PE2_TX_DN<10>")
	)
	(segment
		(start 391.59053 -252.582426)
		(end 391.851642 -253.212854)
		(width 0.14732)
		(layer "In15.Cu")
		(net "P5E_CPU0_PE2_TX_DN<10>")
	)
	(segment
		(start 391.744708 -249.686826)
		(end 391.7442 -249.687588)
		(width 0.14732)
		(layer "In15.Cu")
		(net "P5E_CPU0_PE2_TX_DN<10>")
	)
	(segment
		(start 391.75055 -249.678952)
		(end 391.745978 -249.685048)
		(width 0.14732)
		(layer "In15.Cu")
		(net "P5E_CPU0_PE2_TX_DN<10>")
	)
	(segment
		(start 394.345414 -259.067808)
		(end 391.334752 -309.768748)
		(width 0.14732)
		(layer "In15.Cu")
		(net "P5E_CPU0_PE2_TX_DN<10>")
	)
	(segment
		(start 391.334752 -309.768748)
		(end 398.467834 -339.404452)
		(width 0.14732)
		(layer "In15.Cu")
		(net "P5E_CPU0_PE2_TX_DN<10>")
	)
	(segment
		(start 379.22073 -220.334078)
		(end 379.22073 -220.319854)
		(width 0.0889)
		(layer "In15.Cu")
		(net "P5E_CPU0_PE2_TX_DN<10>")
	)
	(segment
		(start 391.703814 -249.745246)
		(end 391.455148 -251.152152)
		(width 0.14732)
		(layer "In15.Cu")
		(net "P5E_CPU0_PE2_TX_DN<10>")
	)
	(segment
		(start 391.74547 -249.68581)
		(end 391.744708 -249.686826)
		(width 0.14732)
		(layer "In15.Cu")
		(net "P5E_CPU0_PE2_TX_DN<10>")
	)
	(segment
		(start 387.30809 -400.178778)
		(end 387.30809 -400.563588)
		(width 0.14732)
		(layer "In15.Cu")
		(net "P5E_CPU0_PE2_TX_DN<10>")
	)
	(segment
		(start 381.468122 -219.010484)
		(end 381.478536 -219.01658)
		(width 0.0889)
		(layer "In15.Cu")
		(net "P5E_CPU0_PE2_TX_DN<10>")
	)
	(segment
		(start 378.28093 -223.575626)
		(end 378.28093 -223.568006)
		(width 0.0889)
		(layer "In15.Cu")
		(net "P5E_CPU0_PE2_TX_DN<10>")
	)
	(segment
		(start 379.503432 -219.830396)
		(end 379.518164 -219.82176)
		(width 0.0889)
		(layer "In15.Cu")
		(net "P5E_CPU0_PE2_TX_DN<10>")
	)
	(segment
		(start 387.30809 -400.563588)
		(end 387.60273 -400.858228)
		(width 0.14732)
		(layer "In15.Cu")
		(net "P5E_CPU0_PE2_TX_DN<10>")
	)
	(segment
		(start 378.094494 -223.899476)
		(end 378.102368 -223.894904)
		(width 0.0889)
		(layer "In15.Cu")
		(net "P5E_CPU0_PE2_TX_DN<10>")
	)
	(segment
		(start 391.745978 -249.685048)
		(end 391.74547 -249.68581)
		(width 0.14732)
		(layer "In15.Cu")
		(net "P5E_CPU0_PE2_TX_DN<10>")
	)
	(segment
		(start 379.503686 -221.458282)
		(end 379.512322 -221.453202)
		(width 0.0889)
		(layer "In15.Cu")
		(net "P5E_CPU0_PE2_TX_DN<10>")
	)
	(segment
		(start 378.751084 -222.761556)
		(end 378.751084 -222.746062)
		(width 0.0889)
		(layer "In15.Cu")
		(net "P5E_CPU0_PE2_TX_DN<10>")
	)
	(segment
		(start 391.663936 -227.459794)
		(end 392.396472 -230.381556)
		(width 0.14732)
		(layer "In15.Cu")
		(net "P5E_CPU0_PE2_TX_DN<10>")
	)
	(segment
		(start 387.103112 -220.20022)
		(end 390.568942 -223.66605)
		(width 0.14732)
		(layer "In15.Cu")
		(net "P5E_CPU0_PE2_TX_DN<10>")
	)
	(segment
		(start 385.698492 -219.825316)
		(end 385.705858 -219.829634)
		(width 0.0889)
		(layer "In15.Cu")
		(net "P5E_CPU0_PE2_TX_DN<10>")
	)
	(segment
		(start 379.497336 -219.833952)
		(end 379.503432 -219.830396)
		(width 0.0889)
		(layer "In15.Cu")
		(net "P5E_CPU0_PE2_TX_DN<10>")
	)
	(segment
		(start 393.361164 -244.719094)
		(end 393.361164 -244.71884)
		(width 0.14732)
		(layer "In15.Cu")
		(net "P5E_CPU0_PE2_TX_DN<10>")
	)
	(segment
		(start 392.396472 -230.381556)
		(end 393.361164 -244.719094)
		(width 0.14732)
		(layer "In15.Cu")
		(net "P5E_CPU0_PE2_TX_DN<10>")
	)
	(segment
		(start 380.443232 -219.830396)
		(end 380.452122 -219.825316)
		(width 0.0889)
		(layer "In15.Cu")
		(net "P5E_CPU0_PE2_TX_DN<10>")
	)
	(segment
		(start 379.503432 -221.458282)
		(end 379.499622 -221.460822)
		(width 0.0889)
		(layer "In15.Cu")
		(net "P5E_CPU0_PE2_TX_DN<10>")
	)
	(segment
		(start 394.875258 -359.24109)
		(end 387.30809 -400.178778)
		(width 0.14732)
		(layer "In15.Cu")
		(net "P5E_CPU0_PE2_TX_DN<10>")
	)
	(segment
		(start 379.512322 -220.814646)
		(end 379.503432 -220.809566)
		(width 0.0889)
		(layer "In15.Cu")
		(net "P5E_CPU0_PE2_TX_DN<10>")
	)
	(segment
		(start 379.499622 -221.460822)
		(end 379.503686 -221.458282)
		(width 0.0889)
		(layer "In15.Cu")
		(net "P5E_CPU0_PE2_TX_DN<10>")
	)
	(segment
		(start 385.51993 -219.490544)
		(end 385.51993 -219.506038)
		(width 0.0889)
		(layer "In15.Cu")
		(net "P5E_CPU0_PE2_TX_DN<10>")
	)
	(segment
		(start 393.52347 -255.600454)
		(end 394.345414 -259.067808)
		(width 0.14732)
		(layer "In15.Cu")
		(net "P5E_CPU0_PE2_TX_DN<10>")
	)
	(segment
		(start 378.093478 -223.899984)
		(end 378.094494 -223.899476)
		(width 0.0889)
		(layer "In15.Cu")
		(net "P5E_CPU0_PE2_TX_DN<10>")
	)
	(segment
		(start 398.467834 -339.404452)
		(end 395.350746 -357.641398)
		(width 0.14732)
		(layer "In15.Cu")
		(net "P5E_CPU0_PE2_TX_DN<10>")
	)
	(segment
		(start 380.630684 -219.506038)
		(end 380.630684 -219.490544)
		(width 0.0889)
		(layer "In15.Cu")
		(net "P5E_CPU0_PE2_TX_DN<10>")
	)
	(segment
		(start 377.749816 -223.846644)
		(end 377.770898 -223.924622)
		(width 0.0889)
		(layer "In15.Cu")
		(net "P5E_CPU0_PE2_TX_DN<10>")
	)
	(segment
		(start 391.851642 -253.212854)
		(end 393.52347 -255.600454)
		(width 0.14732)
		(layer "In15.Cu")
		(net "P5E_CPU0_PE2_TX_DN<10>")
	)
	(segment
		(start 379.033278 -222.272098)
		(end 379.042168 -222.267018)
		(width 0.0889)
		(layer "In15.Cu")
		(net "P5E_CPU0_PE2_TX_DN<10>")
	)
	(segment
		(start 386.764276 -219.920058)
		(end 386.932424 -220.08846)
		(width 0.0889)
		(layer "In15.Cu")
		(net "P5E_CPU0_PE2_TX_DN<10>")
	)
	(segment
		(start 391.784078 -249.630184)
		(end 391.75055 -249.678952)
		(width 0.14732)
		(layer "In15.Cu")
		(net "P5E_CPU0_PE2_TX_DN<10>")
	)
	(segment
		(start 395.350746 -357.641398)
		(end 394.875258 -359.24109)
		(width 0.14732)
		(layer "In15.Cu")
		(net "P5E_CPU0_PE2_TX_DN<10>")
	)
	(segment
		(start 391.7442 -249.687588)
		(end 391.743946 -249.687588)
		(width 0.14732)
		(layer "In15.Cu")
		(net "P5E_CPU0_PE2_TX_DN<10>")
	)
	(segment
		(start 393.36472 -244.771926)
		(end 391.784078 -249.630184)
		(width 0.14732)
		(layer "In15.Cu")
		(net "P5E_CPU0_PE2_TX_DN<10>")
	)
	(segment
		(start 378.563632 -223.085914)
		(end 378.572522 -223.080834)
		(width 0.0889)
		(layer "In15.Cu")
		(net "P5E_CPU0_PE2_TX_DN<10>")
	)
	(segment
		(start 385.705858 -219.829634)
		(end 385.707382 -219.830396)
		(width 0.0889)
		(layer "In15.Cu")
		(net "P5E_CPU0_PE2_TX_DN<10>")
	)
	(segment
		(start 390.568942 -223.66605)
		(end 391.663936 -227.459794)
		(width 0.14732)
		(layer "In15.Cu")
		(net "P5E_CPU0_PE2_TX_DN<10>")
	)
	(segment
		(start 379.500638 -221.459806)
		(end 379.503432 -221.458282)
		(width 0.0889)
		(layer "In15.Cu")
		(net "P5E_CPU0_PE2_TX_DN<10>")
	)
	(segment
		(start 391.743946 -249.687588)
		(end 391.703814 -249.745246)
		(width 0.14732)
		(layer "In15.Cu")
		(net "P5E_CPU0_PE2_TX_DN<10>")
	)
	(segment
		(start 384.672332 -219.01658)
		(end 384.687064 -219.007944)
		(width 0.0889)
		(layer "In15.Cu")
		(net "P5E_CPU0_PE2_TX_DN<10>")
	)
	(segment
		(start 386.63245 -219.82176)
		(end 386.647182 -219.830396)
		(width 0.0889)
		(layer "In15.Cu")
		(net "P5E_CPU0_PE2_TX_DN<10>")
	)
	(segment
		(start 377.90628 -223.575626)
		(end 377.749816 -223.846644)
		(width 0.0889)
		(layer "In15.Cu")
		(net "P5E_CPU0_PE2_TX_DN<10>")
	)
	(segment
		(start 391.455148 -251.152152)
		(end 391.455148 -252.118622)
		(width 0.14732)
		(layer "In15.Cu")
		(net "P5E_CPU0_PE2_TX_DN<10>")
	)
	(arc
		(start 378.751084 -222.746062)
		(mid 378.830454 -222.472328)
		(end 379.033278 -222.272098)
		(width 0.0889)
		(layer "In15.Cu")
		(net "P5E_CPU0_PE2_TX_DN<10>")
	)
	(arc
		(start 380.912878 -219.01658)
		(mid 381.189691 -218.94071)
		(end 381.468122 -219.010484)
		(width 0.0889)
		(layer "In15.Cu")
		(net "P5E_CPU0_PE2_TX_DN<10>")
	)
	(arc
		(start 379.22073 -220.319854)
		(mid 379.294721 -220.040288)
		(end 379.497336 -219.833952)
		(width 0.0889)
		(layer "In15.Cu")
		(net "P5E_CPU0_PE2_TX_DN<10>")
	)
	(arc
		(start 380.452122 -219.825316)
		(mid 380.583036 -219.688956)
		(end 380.630684 -219.506038)
		(width 0.0889)
		(layer "In15.Cu")
		(net "P5E_CPU0_PE2_TX_DN<10>")
	)
	(arc
		(start 384.687064 -219.007944)
		(mid 384.963539 -218.940624)
		(end 385.237736 -219.01658)
		(width 0.0889)
		(layer "In15.Cu")
		(net "P5E_CPU0_PE2_TX_DN<10>")
	)
	(arc
		(start 379.518164 -219.82176)
		(mid 379.794639 -219.75444)
		(end 380.068836 -219.830396)
		(width 0.0889)
		(layer "In15.Cu")
		(net "P5E_CPU0_PE2_TX_DN<10>")
	)
	(arc
		(start 378.102368 -223.894904)
		(mid 378.233282 -223.758544)
		(end 378.28093 -223.575626)
		(width 0.0889)
		(layer "In15.Cu")
		(net "P5E_CPU0_PE2_TX_DN<10>")
	)
	(arc
		(start 379.042168 -222.267018)
		(mid 379.173082 -222.130658)
		(end 379.22073 -221.94774)
		(width 0.0889)
		(layer "In15.Cu")
		(net "P5E_CPU0_PE2_TX_DN<10>")
	)
	(arc
		(start 386.738114 -219.89542)
		(mid 386.75139 -219.907532)
		(end 386.764276 -219.920058)
		(width 0.0889)
		(layer "In15.Cu")
		(net "P5E_CPU0_PE2_TX_DN<10>")
	)
	(arc
		(start 379.503432 -220.809566)
		(mid 379.299951 -220.608762)
		(end 379.22073 -220.334078)
		(width 0.0889)
		(layer "In15.Cu")
		(net "P5E_CPU0_PE2_TX_DN<10>")
	)
	(arc
		(start 380.630684 -219.490544)
		(mid 380.710054 -219.21681)
		(end 380.912878 -219.01658)
		(width 0.0889)
		(layer "In15.Cu")
		(net "P5E_CPU0_PE2_TX_DN<10>")
	)
	(arc
		(start 386.647182 -219.830396)
		(mid 386.694258 -219.860656)
		(end 386.738114 -219.89542)
		(width 0.0889)
		(layer "In15.Cu")
		(net "P5E_CPU0_PE2_TX_DN<10>")
	)
	(arc
		(start 381.478536 -219.01658)
		(mid 381.665734 -219.066723)
		(end 381.852932 -219.01658)
		(width 0.0889)
		(layer "In15.Cu")
		(net "P5E_CPU0_PE2_TX_DN<10>")
	)
	(arc
		(start 382.418336 -219.01658)
		(mid 382.605534 -219.066723)
		(end 382.792732 -219.01658)
		(width 0.0889)
		(layer "In15.Cu")
		(net "P5E_CPU0_PE2_TX_DN<10>")
	)
	(arc
		(start 379.22073 -221.94774)
		(mid 379.294721 -221.668174)
		(end 379.497336 -221.461838)
		(width 0.0889)
		(layer "In15.Cu")
		(net "P5E_CPU0_PE2_TX_DN<10>")
	)
	(arc
		(start 384.297936 -219.01658)
		(mid 384.485134 -219.066723)
		(end 384.672332 -219.01658)
		(width 0.0889)
		(layer "In15.Cu")
		(net "P5E_CPU0_PE2_TX_DN<10>")
	)
	(arc
		(start 383.732532 -219.01658)
		(mid 384.015234 -218.940804)
		(end 384.297936 -219.01658)
		(width 0.0889)
		(layer "In15.Cu")
		(net "P5E_CPU0_PE2_TX_DN<10>")
	)
	(arc
		(start 385.707382 -219.830396)
		(mid 385.89458 -219.880539)
		(end 386.081778 -219.830396)
		(width 0.0889)
		(layer "In15.Cu")
		(net "P5E_CPU0_PE2_TX_DN<10>")
	)
	(arc
		(start 378.572522 -223.080834)
		(mid 378.703436 -222.944474)
		(end 378.751084 -222.761556)
		(width 0.0889)
		(layer "In15.Cu")
		(net "P5E_CPU0_PE2_TX_DN<10>")
	)
	(arc
		(start 378.28093 -223.568006)
		(mid 378.358559 -223.289593)
		(end 378.563632 -223.085914)
		(width 0.0889)
		(layer "In15.Cu")
		(net "P5E_CPU0_PE2_TX_DN<10>")
	)
	(arc
		(start 385.237736 -219.01658)
		(mid 385.440559 -219.216811)
		(end 385.51993 -219.490544)
		(width 0.0889)
		(layer "In15.Cu")
		(net "P5E_CPU0_PE2_TX_DN<10>")
	)
	(arc
		(start 379.512322 -221.453202)
		(mid 379.690919 -221.133924)
		(end 379.512322 -220.814646)
		(width 0.0889)
		(layer "In15.Cu")
		(net "P5E_CPU0_PE2_TX_DN<10>")
	)
	(arc
		(start 380.068836 -219.830396)
		(mid 380.256034 -219.880539)
		(end 380.443232 -219.830396)
		(width 0.0889)
		(layer "In15.Cu")
		(net "P5E_CPU0_PE2_TX_DN<10>")
	)
	(arc
		(start 385.51993 -219.506038)
		(mid 385.567609 -219.688938)
		(end 385.698492 -219.825316)
		(width 0.0889)
		(layer "In15.Cu")
		(net "P5E_CPU0_PE2_TX_DN<10>")
	)
	(arc
		(start 377.770898 -223.924622)
		(mid 377.934994 -223.948969)
		(end 378.093478 -223.899984)
		(width 0.0889)
		(layer "In15.Cu")
		(net "P5E_CPU0_PE2_TX_DN<10>")
	)
	(arc
		(start 382.792732 -219.01658)
		(mid 383.075434 -218.940804)
		(end 383.358136 -219.01658)
		(width 0.0889)
		(layer "In15.Cu")
		(net "P5E_CPU0_PE2_TX_DN<10>")
	)
	(arc
		(start 381.852932 -219.01658)
		(mid 382.135634 -218.940804)
		(end 382.418336 -219.01658)
		(width 0.0889)
		(layer "In15.Cu")
		(net "P5E_CPU0_PE2_TX_DN<10>")
	)
	(arc
		(start 386.081778 -219.830396)
		(mid 386.355977 -219.754561)
		(end 386.63245 -219.82176)
		(width 0.0889)
		(layer "In15.Cu")
		(net "P5E_CPU0_PE2_TX_DN<10>")
	)
	(arc
		(start 383.358136 -219.01658)
		(mid 383.545334 -219.066723)
		(end 383.732532 -219.01658)
		(width 0.0889)
		(layer "In15.Cu")
		(net "P5E_CPU0_PE2_TX_DN<10>")
	)
	(segment
		(start 368.508534 -223.57588)
		(end 368.50828 -223.575626)
		(width 0.13208)
		(layer "F.Cu")
		(net "P5E_CPU0_PE2_TX_DN<0>")
	)
	(segment
		(start 368.508534 -224.111566)
		(end 368.508534 -223.57588)
		(width 0.13208)
		(layer "F.Cu")
		(net "P5E_CPU0_PE2_TX_DN<0>")
	)
	(segment
		(start 417.936172 -401.157186)
		(end 417.936172 -401.779994)
		(width 0.13208)
		(layer "F.Cu")
		(net "P5E_CPU0_PE2_TX_DN<0>")
	)
	(segment
		(start 417.936172 -401.779994)
		(end 418.26053 -402.104352)
		(width 0.13208)
		(layer "F.Cu")
		(net "P5E_CPU0_PE2_TX_DN<0>")
	)
	(segment
		(start 418.23513 -400.858228)
		(end 417.936172 -401.157186)
		(width 0.13208)
		(layer "F.Cu")
		(net "P5E_CPU0_PE2_TX_DN<0>")
	)
	(segment
		(start 368.696494 -223.899476)
		(end 368.704368 -223.894904)
		(width 0.0889)
		(layer "In15.Cu")
		(net "P5E_CPU0_PE2_TX_DN<0>")
	)
	(segment
		(start 372.837202 -211.006944)
		(end 373.068088 -210.449414)
		(width 0.14732)
		(layer "In15.Cu")
		(net "P5E_CPU0_PE2_TX_DN<0>")
	)
	(segment
		(start 368.50828 -223.575626)
		(end 368.351816 -223.846644)
		(width 0.0889)
		(layer "In15.Cu")
		(net "P5E_CPU0_PE2_TX_DN<0>")
	)
	(segment
		(start 386.102606 -201.689208)
		(end 393.33805 -210.616292)
		(width 0.14732)
		(layer "In15.Cu")
		(net "P5E_CPU0_PE2_TX_DN<0>")
	)
	(segment
		(start 368.695478 -223.899984)
		(end 368.696494 -223.899476)
		(width 0.0889)
		(layer "In15.Cu")
		(net "P5E_CPU0_PE2_TX_DN<0>")
	)
	(segment
		(start 368.351816 -223.846644)
		(end 368.372898 -223.924622)
		(width 0.0889)
		(layer "In15.Cu")
		(net "P5E_CPU0_PE2_TX_DN<0>")
	)
	(segment
		(start 369.635278 -222.272098)
		(end 369.644168 -222.267018)
		(width 0.0889)
		(layer "In15.Cu")
		(net "P5E_CPU0_PE2_TX_DN<0>")
	)
	(segment
		(start 370.099336 -221.461838)
		(end 370.105432 -221.458282)
		(width 0.0889)
		(layer "In15.Cu")
		(net "P5E_CPU0_PE2_TX_DN<0>")
	)
	(segment
		(start 370.292884 -219.506038)
		(end 370.292884 -219.490544)
		(width 0.0889)
		(layer "In15.Cu")
		(net "P5E_CPU0_PE2_TX_DN<0>")
	)
	(segment
		(start 403.803358 -239.54105)
		(end 403.803358 -239.541558)
		(width 0.14732)
		(layer "In15.Cu")
		(net "P5E_CPU0_PE2_TX_DN<0>")
	)
	(segment
		(start 380.187962 -201.622914)
		(end 381.125222 -200.685908)
		(width 0.14732)
		(layer "In15.Cu")
		(net "P5E_CPU0_PE2_TX_DN<0>")
	)
	(segment
		(start 371.045232 -216.574878)
		(end 371.054122 -216.569798)
		(width 0.0889)
		(layer "In15.Cu")
		(net "P5E_CPU0_PE2_TX_DN<0>")
	)
	(segment
		(start 403.397974 -236.853984)
		(end 403.803358 -239.54105)
		(width 0.14732)
		(layer "In15.Cu")
		(net "P5E_CPU0_PE2_TX_DN<0>")
	)
	(segment
		(start 370.575078 -219.01658)
		(end 370.583968 -219.0115)
		(width 0.0889)
		(layer "In15.Cu")
		(net "P5E_CPU0_PE2_TX_DN<0>")
	)
	(segment
		(start 385.362704 -201.316844)
		(end 386.102606 -201.689208)
		(width 0.14732)
		(layer "In15.Cu")
		(net "P5E_CPU0_PE2_TX_DN<0>")
	)
	(segment
		(start 373.068088 -210.449414)
		(end 380.179072 -201.634344)
		(width 0.14732)
		(layer "In15.Cu")
		(net "P5E_CPU0_PE2_TX_DN<0>")
	)
	(segment
		(start 402.586698 -231.478328)
		(end 402.992336 -234.166156)
		(width 0.14732)
		(layer "In15.Cu")
		(net "P5E_CPU0_PE2_TX_DN<0>")
	)
	(segment
		(start 408.456638 -339.773514)
		(end 406.892506 -348.109794)
		(width 0.14732)
		(layer "In15.Cu")
		(net "P5E_CPU0_PE2_TX_DN<0>")
	)
	(segment
		(start 371.191028 -215.67267)
		(end 371.191028 -214.849202)
		(width 0.14732)
		(layer "In15.Cu")
		(net "P5E_CPU0_PE2_TX_DN<0>")
	)
	(segment
		(start 405.218138 -253.5047)
		(end 401.033234 -307.464714)
		(width 0.14732)
		(layer "In15.Cu")
		(net "P5E_CPU0_PE2_TX_DN<0>")
	)
	(segment
		(start 407.291032 -369.392962)
		(end 411.61843 -381.95504)
		(width 0.14732)
		(layer "In15.Cu")
		(net "P5E_CPU0_PE2_TX_DN<0>")
	)
	(segment
		(start 371.045232 -218.202764)
		(end 371.054122 -218.197684)
		(width 0.0889)
		(layer "In15.Cu")
		(net "P5E_CPU0_PE2_TX_DN<0>")
	)
	(segment
		(start 372.478046 -212.221318)
		(end 372.610888 -211.553298)
		(width 0.14732)
		(layer "In15.Cu")
		(net "P5E_CPU0_PE2_TX_DN<0>")
	)
	(segment
		(start 402.992336 -234.166156)
		(end 403.39772 -236.853984)
		(width 0.14732)
		(layer "In15.Cu")
		(net "P5E_CPU0_PE2_TX_DN<0>")
	)
	(segment
		(start 417.94049 -400.563588)
		(end 418.23513 -400.858228)
		(width 0.14732)
		(layer "In15.Cu")
		(net "P5E_CPU0_PE2_TX_DN<0>")
	)
	(segment
		(start 370.114322 -220.814646)
		(end 370.105432 -220.809566)
		(width 0.0889)
		(layer "In15.Cu")
		(net "P5E_CPU0_PE2_TX_DN<0>")
	)
	(segment
		(start 370.105432 -219.830396)
		(end 370.106956 -219.829634)
		(width 0.0889)
		(layer "In15.Cu")
		(net "P5E_CPU0_PE2_TX_DN<0>")
	)
	(segment
		(start 372.610888 -211.553298)
		(end 372.836948 -211.006944)
		(width 0.14732)
		(layer "In15.Cu")
		(net "P5E_CPU0_PE2_TX_DN<0>")
	)
	(segment
		(start 380.179072 -201.634344)
		(end 380.178818 -201.63409)
		(width 0.14732)
		(layer "In15.Cu")
		(net "P5E_CPU0_PE2_TX_DN<0>")
	)
	(segment
		(start 368.88293 -223.575626)
		(end 368.88293 -223.568006)
		(width 0.0889)
		(layer "In15.Cu")
		(net "P5E_CPU0_PE2_TX_DN<0>")
	)
	(segment
		(start 417.94049 -400.308572)
		(end 417.94049 -400.563588)
		(width 0.14732)
		(layer "In15.Cu")
		(net "P5E_CPU0_PE2_TX_DN<0>")
	)
	(segment
		(start 370.105432 -221.458282)
		(end 370.114322 -221.453202)
		(width 0.0889)
		(layer "In15.Cu")
		(net "P5E_CPU0_PE2_TX_DN<0>")
	)
	(segment
		(start 401.775676 -226.102672)
		(end 402.586952 -231.478328)
		(width 0.14732)
		(layer "In15.Cu")
		(net "P5E_CPU0_PE2_TX_DN<0>")
	)
	(segment
		(start 371.191028 -215.694768)
		(end 371.191028 -215.67267)
		(width 0.0889)
		(layer "In15.Cu")
		(net "P5E_CPU0_PE2_TX_DN<0>")
	)
	(segment
		(start 405.020272 -247.606566)
		(end 405.218138 -253.5047)
		(width 0.14732)
		(layer "In15.Cu")
		(net "P5E_CPU0_PE2_TX_DN<0>")
	)
	(segment
		(start 371.191028 -214.849202)
		(end 371.712744 -214.068152)
		(width 0.14732)
		(layer "In15.Cu")
		(net "P5E_CPU0_PE2_TX_DN<0>")
	)
	(segment
		(start 369.353084 -222.761556)
		(end 369.353084 -222.746062)
		(width 0.0889)
		(layer "In15.Cu")
		(net "P5E_CPU0_PE2_TX_DN<0>")
	)
	(segment
		(start 371.232938 -215.736678)
		(end 371.191028 -215.694768)
		(width 0.0889)
		(layer "In15.Cu")
		(net "P5E_CPU0_PE2_TX_DN<0>")
	)
	(segment
		(start 371.03304 -216.58199)
		(end 371.045232 -216.574878)
		(width 0.0889)
		(layer "In15.Cu")
		(net "P5E_CPU0_PE2_TX_DN<0>")
	)
	(segment
		(start 382.705864 -200.685908)
		(end 385.362704 -201.316844)
		(width 0.14732)
		(layer "In15.Cu")
		(net "P5E_CPU0_PE2_TX_DN<0>")
	)
	(segment
		(start 411.61843 -381.95504)
		(end 411.618176 -381.95504)
		(width 0.14732)
		(layer "In15.Cu")
		(net "P5E_CPU0_PE2_TX_DN<0>")
	)
	(segment
		(start 370.106956 -219.829634)
		(end 370.114322 -219.825316)
		(width 0.0889)
		(layer "In15.Cu")
		(net "P5E_CPU0_PE2_TX_DN<0>")
	)
	(segment
		(start 371.039136 -218.20632)
		(end 371.045232 -218.202764)
		(width 0.0889)
		(layer "In15.Cu")
		(net "P5E_CPU0_PE2_TX_DN<0>")
	)
	(segment
		(start 393.33805 -210.616292)
		(end 400.133566 -219.777564)
		(width 0.14732)
		(layer "In15.Cu")
		(net "P5E_CPU0_PE2_TX_DN<0>")
	)
	(segment
		(start 370.099336 -219.833952)
		(end 370.105432 -219.830396)
		(width 0.0889)
		(layer "In15.Cu")
		(net "P5E_CPU0_PE2_TX_DN<0>")
	)
	(segment
		(start 371.232938 -216.250266)
		(end 371.232938 -215.736678)
		(width 0.0889)
		(layer "In15.Cu")
		(net "P5E_CPU0_PE2_TX_DN<0>")
	)
	(segment
		(start 411.618176 -381.95504)
		(end 417.94049 -400.308572)
		(width 0.14732)
		(layer "In15.Cu")
		(net "P5E_CPU0_PE2_TX_DN<0>")
	)
	(segment
		(start 380.178818 -201.63409)
		(end 380.187962 -201.622914)
		(width 0.14732)
		(layer "In15.Cu")
		(net "P5E_CPU0_PE2_TX_DN<0>")
	)
	(segment
		(start 402.586952 -231.478328)
		(end 402.586698 -231.478328)
		(width 0.14732)
		(layer "In15.Cu")
		(net "P5E_CPU0_PE2_TX_DN<0>")
	)
	(segment
		(start 369.165632 -223.085914)
		(end 369.174522 -223.080834)
		(width 0.0889)
		(layer "In15.Cu")
		(net "P5E_CPU0_PE2_TX_DN<0>")
	)
	(segment
		(start 406.892506 -348.109794)
		(end 407.291032 -369.392962)
		(width 0.14732)
		(layer "In15.Cu")
		(net "P5E_CPU0_PE2_TX_DN<0>")
	)
	(segment
		(start 371.045994 -217.554556)
		(end 371.045232 -217.554048)
		(width 0.0889)
		(layer "In15.Cu")
		(net "P5E_CPU0_PE2_TX_DN<0>")
	)
	(segment
		(start 403.39772 -236.853984)
		(end 403.397974 -236.853984)
		(width 0.14732)
		(layer "In15.Cu")
		(net "P5E_CPU0_PE2_TX_DN<0>")
	)
	(segment
		(start 371.232684 -216.25052)
		(end 371.232938 -216.250266)
		(width 0.0889)
		(layer "In15.Cu")
		(net "P5E_CPU0_PE2_TX_DN<0>")
	)
	(segment
		(start 403.803358 -239.541558)
		(end 405.020272 -247.606566)
		(width 0.14732)
		(layer "In15.Cu")
		(net "P5E_CPU0_PE2_TX_DN<0>")
	)
	(segment
		(start 370.76253 -217.071956)
		(end 370.76253 -217.064336)
		(width 0.0889)
		(layer "In15.Cu")
		(net "P5E_CPU0_PE2_TX_DN<0>")
	)
	(segment
		(start 371.712744 -214.068152)
		(end 372.478046 -212.221318)
		(width 0.14732)
		(layer "In15.Cu")
		(net "P5E_CPU0_PE2_TX_DN<0>")
	)
	(segment
		(start 372.836948 -211.006944)
		(end 372.837202 -211.006944)
		(width 0.14732)
		(layer "In15.Cu")
		(net "P5E_CPU0_PE2_TX_DN<0>")
	)
	(segment
		(start 381.125222 -200.685908)
		(end 382.705864 -200.685908)
		(width 0.14732)
		(layer "In15.Cu")
		(net "P5E_CPU0_PE2_TX_DN<0>")
	)
	(segment
		(start 400.133566 -219.777564)
		(end 401.775676 -226.102672)
		(width 0.14732)
		(layer "In15.Cu")
		(net "P5E_CPU0_PE2_TX_DN<0>")
	)
	(segment
		(start 371.054122 -217.559128)
		(end 371.045994 -217.554556)
		(width 0.0889)
		(layer "In15.Cu")
		(net "P5E_CPU0_PE2_TX_DN<0>")
	)
	(segment
		(start 369.82273 -220.334078)
		(end 369.82273 -220.319854)
		(width 0.0889)
		(layer "In15.Cu")
		(net "P5E_CPU0_PE2_TX_DN<0>")
	)
	(segment
		(start 401.033234 -307.464714)
		(end 408.456638 -339.773514)
		(width 0.14732)
		(layer "In15.Cu")
		(net "P5E_CPU0_PE2_TX_DN<0>")
	)
	(arc
		(start 369.353084 -222.746062)
		(mid 369.432454 -222.472328)
		(end 369.635278 -222.272098)
		(width 0.0889)
		(layer "In15.Cu")
		(net "P5E_CPU0_PE2_TX_DN<0>")
	)
	(arc
		(start 370.76253 -217.064336)
		(mid 370.834765 -216.787812)
		(end 371.03304 -216.58199)
		(width 0.0889)
		(layer "In15.Cu")
		(net "P5E_CPU0_PE2_TX_DN<0>")
	)
	(arc
		(start 370.105432 -220.809566)
		(mid 369.901951 -220.608762)
		(end 369.82273 -220.334078)
		(width 0.0889)
		(layer "In15.Cu")
		(net "P5E_CPU0_PE2_TX_DN<0>")
	)
	(arc
		(start 370.583968 -219.0115)
		(mid 370.714882 -218.87514)
		(end 370.76253 -218.692222)
		(width 0.0889)
		(layer "In15.Cu")
		(net "P5E_CPU0_PE2_TX_DN<0>")
	)
	(arc
		(start 368.88293 -223.568006)
		(mid 368.960559 -223.289593)
		(end 369.165632 -223.085914)
		(width 0.0889)
		(layer "In15.Cu")
		(net "P5E_CPU0_PE2_TX_DN<0>")
	)
	(arc
		(start 371.054122 -218.197684)
		(mid 371.232719 -217.878406)
		(end 371.054122 -217.559128)
		(width 0.0889)
		(layer "In15.Cu")
		(net "P5E_CPU0_PE2_TX_DN<0>")
	)
	(arc
		(start 370.76253 -218.692222)
		(mid 370.836521 -218.412656)
		(end 371.039136 -218.20632)
		(width 0.0889)
		(layer "In15.Cu")
		(net "P5E_CPU0_PE2_TX_DN<0>")
	)
	(arc
		(start 371.054122 -216.569798)
		(mid 371.185036 -216.433438)
		(end 371.232684 -216.25052)
		(width 0.0889)
		(layer "In15.Cu")
		(net "P5E_CPU0_PE2_TX_DN<0>")
	)
	(arc
		(start 370.114322 -219.825316)
		(mid 370.245236 -219.688956)
		(end 370.292884 -219.506038)
		(width 0.0889)
		(layer "In15.Cu")
		(net "P5E_CPU0_PE2_TX_DN<0>")
	)
	(arc
		(start 369.644168 -222.267018)
		(mid 369.775082 -222.130658)
		(end 369.82273 -221.94774)
		(width 0.0889)
		(layer "In15.Cu")
		(net "P5E_CPU0_PE2_TX_DN<0>")
	)
	(arc
		(start 368.704368 -223.894904)
		(mid 368.835282 -223.758544)
		(end 368.88293 -223.575626)
		(width 0.0889)
		(layer "In15.Cu")
		(net "P5E_CPU0_PE2_TX_DN<0>")
	)
	(arc
		(start 370.114322 -221.453202)
		(mid 370.292919 -221.133924)
		(end 370.114322 -220.814646)
		(width 0.0889)
		(layer "In15.Cu")
		(net "P5E_CPU0_PE2_TX_DN<0>")
	)
	(arc
		(start 371.045232 -217.554048)
		(mid 370.84016 -217.350369)
		(end 370.76253 -217.071956)
		(width 0.0889)
		(layer "In15.Cu")
		(net "P5E_CPU0_PE2_TX_DN<0>")
	)
	(arc
		(start 369.82273 -220.319854)
		(mid 369.896721 -220.040288)
		(end 370.099336 -219.833952)
		(width 0.0889)
		(layer "In15.Cu")
		(net "P5E_CPU0_PE2_TX_DN<0>")
	)
	(arc
		(start 370.292884 -219.490544)
		(mid 370.372254 -219.21681)
		(end 370.575078 -219.01658)
		(width 0.0889)
		(layer "In15.Cu")
		(net "P5E_CPU0_PE2_TX_DN<0>")
	)
	(arc
		(start 369.82273 -221.94774)
		(mid 369.896721 -221.668174)
		(end 370.099336 -221.461838)
		(width 0.0889)
		(layer "In15.Cu")
		(net "P5E_CPU0_PE2_TX_DN<0>")
	)
	(arc
		(start 368.372898 -223.924622)
		(mid 368.536994 -223.948969)
		(end 368.695478 -223.899984)
		(width 0.0889)
		(layer "In15.Cu")
		(net "P5E_CPU0_PE2_TX_DN<0>")
	)
	(arc
		(start 369.174522 -223.080834)
		(mid 369.305436 -222.944474)
		(end 369.353084 -222.761556)
		(width 0.0889)
		(layer "In15.Cu")
		(net "P5E_CPU0_PE2_TX_DN<0>")
	)
	(segment
		(start 389.780272 -402.637752)
		(end 389.77697 -402.637752)
		(width 0.13208)
		(layer "F.Cu")
		(net "P5E_CPU0_PE2_TX_C_DP<9>")
	)
	(segment
		(start 390.105392 -403.580854)
		(end 390.105392 -402.962872)
		(width 0.13208)
		(layer "F.Cu")
		(net "P5E_CPU0_PE2_TX_C_DP<9>")
	)
	(segment
		(start 390.105392 -402.962872)
		(end 389.780272 -402.637752)
		(width 0.13208)
		(layer "F.Cu")
		(net "P5E_CPU0_PE2_TX_C_DP<9>")
	)
	(segment
		(start 389.80237 -403.883876)
		(end 390.105392 -403.580854)
		(width 0.13208)
		(layer "F.Cu")
		(net "P5E_CPU0_PE2_TX_C_DP<9>")
	)
	(segment
		(start 393.750038 -427.289976)
		(end 393.750038 -426.980604)
		(width 0.14732)
		(layer "In11.Cu")
		(net "P5E_CPU0_PE2_TX_C_DP<9>")
	)
	(segment
		(start 389.91159 -411.28569)
		(end 389.91159 -406.517602)
		(width 0.14732)
		(layer "In11.Cu")
		(net "P5E_CPU0_PE2_TX_C_DP<9>")
	)
	(segment
		(start 392.77036 -424.684698)
		(end 389.91159 -411.28569)
		(width 0.14732)
		(layer "In11.Cu")
		(net "P5E_CPU0_PE2_TX_C_DP<9>")
	)
	(segment
		(start 389.91159 -406.517602)
		(end 390.09701 -404.633684)
		(width 0.14732)
		(layer "In11.Cu")
		(net "P5E_CPU0_PE2_TX_C_DP<9>")
	)
	(segment
		(start 392.77036 -426.440346)
		(end 392.77036 -424.684698)
		(width 0.14732)
		(layer "In11.Cu")
		(net "P5E_CPU0_PE2_TX_C_DP<9>")
	)
	(segment
		(start 393.123674 -426.79366)
		(end 392.77036 -426.440346)
		(width 0.14732)
		(layer "In11.Cu")
		(net "P5E_CPU0_PE2_TX_C_DP<9>")
	)
	(segment
		(start 393.563094 -426.79366)
		(end 393.123674 -426.79366)
		(width 0.14732)
		(layer "In11.Cu")
		(net "P5E_CPU0_PE2_TX_C_DP<9>")
	)
	(segment
		(start 390.09701 -404.633684)
		(end 390.09701 -404.178516)
		(width 0.14732)
		(layer "In11.Cu")
		(net "P5E_CPU0_PE2_TX_C_DP<9>")
	)
	(segment
		(start 393.750038 -426.980604)
		(end 393.563094 -426.79366)
		(width 0.14732)
		(layer "In11.Cu")
		(net "P5E_CPU0_PE2_TX_C_DP<9>")
	)
	(segment
		(start 390.09701 -404.178516)
		(end 389.80237 -403.883876)
		(width 0.14732)
		(layer "In11.Cu")
		(net "P5E_CPU0_PE2_TX_C_DP<9>")
	)
	(segment
		(start 392.86561 -403.883876)
		(end 393.168632 -403.580854)
		(width 0.13208)
		(layer "F.Cu")
		(net "P5E_CPU0_PE2_TX_C_DP<8>")
	)
	(segment
		(start 393.168632 -403.580854)
		(end 393.168632 -402.962872)
		(width 0.13208)
		(layer "F.Cu")
		(net "P5E_CPU0_PE2_TX_C_DP<8>")
	)
	(segment
		(start 392.843512 -402.637752)
		(end 392.84021 -402.637752)
		(width 0.13208)
		(layer "F.Cu")
		(net "P5E_CPU0_PE2_TX_C_DP<8>")
	)
	(segment
		(start 393.168632 -402.962872)
		(end 392.843512 -402.637752)
		(width 0.13208)
		(layer "F.Cu")
		(net "P5E_CPU0_PE2_TX_C_DP<8>")
	)
	(segment
		(start 395.750034 -428.28972)
		(end 395.750034 -427.980602)
		(width 0.14732)
		(layer "In11.Cu")
		(net "P5E_CPU0_PE2_TX_C_DP<8>")
	)
	(segment
		(start 392.97483 -411.909768)
		(end 392.97483 -406.517602)
		(width 0.14732)
		(layer "In11.Cu")
		(net "P5E_CPU0_PE2_TX_C_DP<8>")
	)
	(segment
		(start 393.16025 -404.178516)
		(end 392.86561 -403.883876)
		(width 0.14732)
		(layer "In11.Cu")
		(net "P5E_CPU0_PE2_TX_C_DP<8>")
	)
	(segment
		(start 394.792454 -424.79595)
		(end 392.97483 -411.909768)
		(width 0.14732)
		(layer "In11.Cu")
		(net "P5E_CPU0_PE2_TX_C_DP<8>")
	)
	(segment
		(start 395.750034 -427.980602)
		(end 395.56309 -427.793658)
		(width 0.14732)
		(layer "In11.Cu")
		(net "P5E_CPU0_PE2_TX_C_DP<8>")
	)
	(segment
		(start 394.792454 -427.509178)
		(end 394.792454 -424.79595)
		(width 0.14732)
		(layer "In11.Cu")
		(net "P5E_CPU0_PE2_TX_C_DP<8>")
	)
	(segment
		(start 395.56309 -427.793658)
		(end 395.076934 -427.793658)
		(width 0.14732)
		(layer "In11.Cu")
		(net "P5E_CPU0_PE2_TX_C_DP<8>")
	)
	(segment
		(start 392.97483 -406.517602)
		(end 393.16025 -404.633684)
		(width 0.14732)
		(layer "In11.Cu")
		(net "P5E_CPU0_PE2_TX_C_DP<8>")
	)
	(segment
		(start 393.16025 -404.633684)
		(end 393.16025 -404.178516)
		(width 0.14732)
		(layer "In11.Cu")
		(net "P5E_CPU0_PE2_TX_C_DP<8>")
	)
	(segment
		(start 395.076934 -427.793658)
		(end 394.792454 -427.509178)
		(width 0.14732)
		(layer "In11.Cu")
		(net "P5E_CPU0_PE2_TX_C_DP<8>")
	)
	(segment
		(start 395.92885 -403.883876)
		(end 396.231872 -403.580854)
		(width 0.13208)
		(layer "F.Cu")
		(net "P5E_CPU0_PE2_TX_C_DP<7>")
	)
	(segment
		(start 396.231872 -402.962872)
		(end 395.906752 -402.637752)
		(width 0.13208)
		(layer "F.Cu")
		(net "P5E_CPU0_PE2_TX_C_DP<7>")
	)
	(segment
		(start 395.906752 -402.637752)
		(end 395.90345 -402.637752)
		(width 0.13208)
		(layer "F.Cu")
		(net "P5E_CPU0_PE2_TX_C_DP<7>")
	)
	(segment
		(start 396.231872 -403.580854)
		(end 396.231872 -402.962872)
		(width 0.13208)
		(layer "F.Cu")
		(net "P5E_CPU0_PE2_TX_C_DP<7>")
	)
	(segment
		(start 396.03807 -412.097474)
		(end 396.03807 -406.517602)
		(width 0.14732)
		(layer "In11.Cu")
		(net "P5E_CPU0_PE2_TX_C_DP<7>")
	)
	(segment
		(start 398.076928 -426.79366)
		(end 397.792448 -426.50918)
		(width 0.14732)
		(layer "In11.Cu")
		(net "P5E_CPU0_PE2_TX_C_DP<7>")
	)
	(segment
		(start 398.563084 -426.79366)
		(end 398.076928 -426.79366)
		(width 0.14732)
		(layer "In11.Cu")
		(net "P5E_CPU0_PE2_TX_C_DP<7>")
	)
	(segment
		(start 398.750028 -426.980604)
		(end 398.563084 -426.79366)
		(width 0.14732)
		(layer "In11.Cu")
		(net "P5E_CPU0_PE2_TX_C_DP<7>")
	)
	(segment
		(start 396.03807 -406.517602)
		(end 396.22349 -404.633684)
		(width 0.14732)
		(layer "In11.Cu")
		(net "P5E_CPU0_PE2_TX_C_DP<7>")
	)
	(segment
		(start 396.22349 -404.633684)
		(end 396.22349 -404.178516)
		(width 0.14732)
		(layer "In11.Cu")
		(net "P5E_CPU0_PE2_TX_C_DP<7>")
	)
	(segment
		(start 396.22349 -404.178516)
		(end 395.92885 -403.883876)
		(width 0.14732)
		(layer "In11.Cu")
		(net "P5E_CPU0_PE2_TX_C_DP<7>")
	)
	(segment
		(start 397.792448 -424.776138)
		(end 396.03807 -412.097474)
		(width 0.14732)
		(layer "In11.Cu")
		(net "P5E_CPU0_PE2_TX_C_DP<7>")
	)
	(segment
		(start 397.792448 -426.50918)
		(end 397.792448 -424.776138)
		(width 0.14732)
		(layer "In11.Cu")
		(net "P5E_CPU0_PE2_TX_C_DP<7>")
	)
	(segment
		(start 398.750028 -427.289976)
		(end 398.750028 -426.980604)
		(width 0.14732)
		(layer "In11.Cu")
		(net "P5E_CPU0_PE2_TX_C_DP<7>")
	)
	(segment
		(start 399.295112 -403.580854)
		(end 399.295112 -402.962872)
		(width 0.13208)
		(layer "F.Cu")
		(net "P5E_CPU0_PE2_TX_C_DP<6>")
	)
	(segment
		(start 398.99209 -403.883876)
		(end 399.295112 -403.580854)
		(width 0.13208)
		(layer "F.Cu")
		(net "P5E_CPU0_PE2_TX_C_DP<6>")
	)
	(segment
		(start 399.295112 -402.962872)
		(end 398.969992 -402.637752)
		(width 0.13208)
		(layer "F.Cu")
		(net "P5E_CPU0_PE2_TX_C_DP<6>")
	)
	(segment
		(start 398.969992 -402.637752)
		(end 398.96669 -402.637752)
		(width 0.13208)
		(layer "F.Cu")
		(net "P5E_CPU0_PE2_TX_C_DP<6>")
	)
	(segment
		(start 399.792444 -427.509178)
		(end 399.792444 -424.765978)
		(width 0.14732)
		(layer "In11.Cu")
		(net "P5E_CPU0_PE2_TX_C_DP<6>")
	)
	(segment
		(start 399.10131 -410.218128)
		(end 399.10131 -406.517602)
		(width 0.14732)
		(layer "In11.Cu")
		(net "P5E_CPU0_PE2_TX_C_DP<6>")
	)
	(segment
		(start 399.28673 -404.178516)
		(end 398.99209 -403.883876)
		(width 0.14732)
		(layer "In11.Cu")
		(net "P5E_CPU0_PE2_TX_C_DP<6>")
	)
	(segment
		(start 399.10131 -406.517602)
		(end 399.28673 -404.633684)
		(width 0.14732)
		(layer "In11.Cu")
		(net "P5E_CPU0_PE2_TX_C_DP<6>")
	)
	(segment
		(start 399.010124 -412.470092)
		(end 399.10131 -410.218128)
		(width 0.14732)
		(layer "In11.Cu")
		(net "P5E_CPU0_PE2_TX_C_DP<6>")
	)
	(segment
		(start 399.792444 -424.765978)
		(end 399.010124 -412.470092)
		(width 0.14732)
		(layer "In11.Cu")
		(net "P5E_CPU0_PE2_TX_C_DP<6>")
	)
	(segment
		(start 400.750024 -427.980602)
		(end 400.56308 -427.793658)
		(width 0.14732)
		(layer "In11.Cu")
		(net "P5E_CPU0_PE2_TX_C_DP<6>")
	)
	(segment
		(start 399.28673 -404.633684)
		(end 399.28673 -404.178516)
		(width 0.14732)
		(layer "In11.Cu")
		(net "P5E_CPU0_PE2_TX_C_DP<6>")
	)
	(segment
		(start 400.56308 -427.793658)
		(end 400.076924 -427.793658)
		(width 0.14732)
		(layer "In11.Cu")
		(net "P5E_CPU0_PE2_TX_C_DP<6>")
	)
	(segment
		(start 400.076924 -427.793658)
		(end 399.792444 -427.509178)
		(width 0.14732)
		(layer "In11.Cu")
		(net "P5E_CPU0_PE2_TX_C_DP<6>")
	)
	(segment
		(start 400.750024 -428.28972)
		(end 400.750024 -427.980602)
		(width 0.14732)
		(layer "In11.Cu")
		(net "P5E_CPU0_PE2_TX_C_DP<6>")
	)
	(segment
		(start 402.358352 -403.580854)
		(end 402.358352 -402.962872)
		(width 0.13208)
		(layer "F.Cu")
		(net "P5E_CPU0_PE2_TX_C_DP<5>")
	)
	(segment
		(start 402.358352 -402.962872)
		(end 402.033232 -402.637752)
		(width 0.13208)
		(layer "F.Cu")
		(net "P5E_CPU0_PE2_TX_C_DP<5>")
	)
	(segment
		(start 402.033232 -402.637752)
		(end 402.02993 -402.637752)
		(width 0.13208)
		(layer "F.Cu")
		(net "P5E_CPU0_PE2_TX_C_DP<5>")
	)
	(segment
		(start 402.05533 -403.883876)
		(end 402.358352 -403.580854)
		(width 0.13208)
		(layer "F.Cu")
		(net "P5E_CPU0_PE2_TX_C_DP<5>")
	)
	(segment
		(start 402.75002 -427.289976)
		(end 402.75002 -426.980604)
		(width 0.14732)
		(layer "In11.Cu")
		(net "P5E_CPU0_PE2_TX_C_DP<5>")
	)
	(segment
		(start 401.79244 -424.757088)
		(end 401.93722 -411.723332)
		(width 0.14732)
		(layer "In11.Cu")
		(net "P5E_CPU0_PE2_TX_C_DP<5>")
	)
	(segment
		(start 402.563076 -426.79366)
		(end 402.07692 -426.79366)
		(width 0.14732)
		(layer "In11.Cu")
		(net "P5E_CPU0_PE2_TX_C_DP<5>")
	)
	(segment
		(start 402.07692 -426.79366)
		(end 401.79244 -426.50918)
		(width 0.14732)
		(layer "In11.Cu")
		(net "P5E_CPU0_PE2_TX_C_DP<5>")
	)
	(segment
		(start 402.34997 -404.633684)
		(end 402.34997 -404.178516)
		(width 0.14732)
		(layer "In11.Cu")
		(net "P5E_CPU0_PE2_TX_C_DP<5>")
	)
	(segment
		(start 402.16455 -410.165042)
		(end 402.16455 -406.517602)
		(width 0.14732)
		(layer "In11.Cu")
		(net "P5E_CPU0_PE2_TX_C_DP<5>")
	)
	(segment
		(start 401.93722 -411.723332)
		(end 402.16455 -410.165042)
		(width 0.14732)
		(layer "In11.Cu")
		(net "P5E_CPU0_PE2_TX_C_DP<5>")
	)
	(segment
		(start 401.79244 -426.50918)
		(end 401.79244 -424.757088)
		(width 0.14732)
		(layer "In11.Cu")
		(net "P5E_CPU0_PE2_TX_C_DP<5>")
	)
	(segment
		(start 402.75002 -426.980604)
		(end 402.563076 -426.79366)
		(width 0.14732)
		(layer "In11.Cu")
		(net "P5E_CPU0_PE2_TX_C_DP<5>")
	)
	(segment
		(start 402.34997 -404.178516)
		(end 402.05533 -403.883876)
		(width 0.14732)
		(layer "In11.Cu")
		(net "P5E_CPU0_PE2_TX_C_DP<5>")
	)
	(segment
		(start 402.16455 -406.517602)
		(end 402.34997 -404.633684)
		(width 0.14732)
		(layer "In11.Cu")
		(net "P5E_CPU0_PE2_TX_C_DP<5>")
	)
	(segment
		(start 405.096472 -402.637752)
		(end 405.09317 -402.637752)
		(width 0.13208)
		(layer "F.Cu")
		(net "P5E_CPU0_PE2_TX_C_DP<4>")
	)
	(segment
		(start 405.421592 -403.580854)
		(end 405.421592 -402.962872)
		(width 0.13208)
		(layer "F.Cu")
		(net "P5E_CPU0_PE2_TX_C_DP<4>")
	)
	(segment
		(start 405.11857 -403.883876)
		(end 405.421592 -403.580854)
		(width 0.13208)
		(layer "F.Cu")
		(net "P5E_CPU0_PE2_TX_C_DP<4>")
	)
	(segment
		(start 405.421592 -402.962872)
		(end 405.096472 -402.637752)
		(width 0.13208)
		(layer "F.Cu")
		(net "P5E_CPU0_PE2_TX_C_DP<4>")
	)
	(segment
		(start 405.41321 -404.633684)
		(end 405.41321 -404.178516)
		(width 0.14732)
		(layer "In11.Cu")
		(net "P5E_CPU0_PE2_TX_C_DP<4>")
	)
	(segment
		(start 403.792436 -427.509178)
		(end 403.792436 -424.757088)
		(width 0.14732)
		(layer "In11.Cu")
		(net "P5E_CPU0_PE2_TX_C_DP<4>")
	)
	(segment
		(start 404.949914 -411.278832)
		(end 405.22779 -410.171138)
		(width 0.14732)
		(layer "In11.Cu")
		(net "P5E_CPU0_PE2_TX_C_DP<4>")
	)
	(segment
		(start 405.22779 -410.171138)
		(end 405.22779 -406.517602)
		(width 0.14732)
		(layer "In11.Cu")
		(net "P5E_CPU0_PE2_TX_C_DP<4>")
	)
	(segment
		(start 404.563072 -427.793658)
		(end 404.076916 -427.793658)
		(width 0.14732)
		(layer "In11.Cu")
		(net "P5E_CPU0_PE2_TX_C_DP<4>")
	)
	(segment
		(start 403.792436 -424.757088)
		(end 404.949914 -411.278832)
		(width 0.14732)
		(layer "In11.Cu")
		(net "P5E_CPU0_PE2_TX_C_DP<4>")
	)
	(segment
		(start 404.750016 -427.980602)
		(end 404.563072 -427.793658)
		(width 0.14732)
		(layer "In11.Cu")
		(net "P5E_CPU0_PE2_TX_C_DP<4>")
	)
	(segment
		(start 405.22779 -406.517602)
		(end 405.41321 -404.633684)
		(width 0.14732)
		(layer "In11.Cu")
		(net "P5E_CPU0_PE2_TX_C_DP<4>")
	)
	(segment
		(start 404.750016 -428.28972)
		(end 404.750016 -427.980602)
		(width 0.14732)
		(layer "In11.Cu")
		(net "P5E_CPU0_PE2_TX_C_DP<4>")
	)
	(segment
		(start 405.41321 -404.178516)
		(end 405.11857 -403.883876)
		(width 0.14732)
		(layer "In11.Cu")
		(net "P5E_CPU0_PE2_TX_C_DP<4>")
	)
	(segment
		(start 404.076916 -427.793658)
		(end 403.792436 -427.509178)
		(width 0.14732)
		(layer "In11.Cu")
		(net "P5E_CPU0_PE2_TX_C_DP<4>")
	)
	(segment
		(start 408.18181 -403.883876)
		(end 408.484832 -403.580854)
		(width 0.13208)
		(layer "F.Cu")
		(net "P5E_CPU0_PE2_TX_C_DP<3>")
	)
	(segment
		(start 408.484832 -403.580854)
		(end 408.484832 -402.962872)
		(width 0.13208)
		(layer "F.Cu")
		(net "P5E_CPU0_PE2_TX_C_DP<3>")
	)
	(segment
		(start 408.484832 -402.962872)
		(end 408.159712 -402.637752)
		(width 0.13208)
		(layer "F.Cu")
		(net "P5E_CPU0_PE2_TX_C_DP<3>")
	)
	(segment
		(start 408.159712 -402.637752)
		(end 408.15641 -402.637752)
		(width 0.13208)
		(layer "F.Cu")
		(net "P5E_CPU0_PE2_TX_C_DP<3>")
	)
	(segment
		(start 406.750012 -427.289976)
		(end 406.750012 -426.980604)
		(width 0.14732)
		(layer "In11.Cu")
		(net "P5E_CPU0_PE2_TX_C_DP<3>")
	)
	(segment
		(start 405.792432 -426.50918)
		(end 405.792432 -424.757088)
		(width 0.14732)
		(layer "In11.Cu")
		(net "P5E_CPU0_PE2_TX_C_DP<3>")
	)
	(segment
		(start 406.563068 -426.79366)
		(end 406.076912 -426.79366)
		(width 0.14732)
		(layer "In11.Cu")
		(net "P5E_CPU0_PE2_TX_C_DP<3>")
	)
	(segment
		(start 407.988008 -411.089348)
		(end 408.29103 -410.174186)
		(width 0.14732)
		(layer "In11.Cu")
		(net "P5E_CPU0_PE2_TX_C_DP<3>")
	)
	(segment
		(start 408.47645 -404.178516)
		(end 408.18181 -403.883876)
		(width 0.14732)
		(layer "In11.Cu")
		(net "P5E_CPU0_PE2_TX_C_DP<3>")
	)
	(segment
		(start 405.792432 -424.757088)
		(end 407.988008 -411.089348)
		(width 0.14732)
		(layer "In11.Cu")
		(net "P5E_CPU0_PE2_TX_C_DP<3>")
	)
	(segment
		(start 406.076912 -426.79366)
		(end 405.792432 -426.50918)
		(width 0.14732)
		(layer "In11.Cu")
		(net "P5E_CPU0_PE2_TX_C_DP<3>")
	)
	(segment
		(start 408.29103 -410.174186)
		(end 408.29103 -406.517602)
		(width 0.14732)
		(layer "In11.Cu")
		(net "P5E_CPU0_PE2_TX_C_DP<3>")
	)
	(segment
		(start 408.29103 -406.517602)
		(end 408.47645 -404.633684)
		(width 0.14732)
		(layer "In11.Cu")
		(net "P5E_CPU0_PE2_TX_C_DP<3>")
	)
	(segment
		(start 408.47645 -404.633684)
		(end 408.47645 -404.178516)
		(width 0.14732)
		(layer "In11.Cu")
		(net "P5E_CPU0_PE2_TX_C_DP<3>")
	)
	(segment
		(start 406.750012 -426.980604)
		(end 406.563068 -426.79366)
		(width 0.14732)
		(layer "In11.Cu")
		(net "P5E_CPU0_PE2_TX_C_DP<3>")
	)
	(segment
		(start 411.548072 -403.580854)
		(end 411.548072 -402.962872)
		(width 0.13208)
		(layer "F.Cu")
		(net "P5E_CPU0_PE2_TX_C_DP<2>")
	)
	(segment
		(start 411.24505 -403.883876)
		(end 411.548072 -403.580854)
		(width 0.13208)
		(layer "F.Cu")
		(net "P5E_CPU0_PE2_TX_C_DP<2>")
	)
	(segment
		(start 411.548072 -402.962872)
		(end 411.222952 -402.637752)
		(width 0.13208)
		(layer "F.Cu")
		(net "P5E_CPU0_PE2_TX_C_DP<2>")
	)
	(segment
		(start 411.222952 -402.637752)
		(end 411.21965 -402.637752)
		(width 0.13208)
		(layer "F.Cu")
		(net "P5E_CPU0_PE2_TX_C_DP<2>")
	)
	(segment
		(start 408.750008 -428.28972)
		(end 408.750008 -427.94301)
		(width 0.14732)
		(layer "In11.Cu")
		(net "P5E_CPU0_PE2_TX_C_DP<2>")
	)
	(segment
		(start 410.873448 -411.669738)
		(end 411.35427 -410.27731)
		(width 0.14732)
		(layer "In11.Cu")
		(net "P5E_CPU0_PE2_TX_C_DP<2>")
	)
	(segment
		(start 408.750008 -427.94301)
		(end 408.600656 -427.793658)
		(width 0.14732)
		(layer "In11.Cu")
		(net "P5E_CPU0_PE2_TX_C_DP<2>")
	)
	(segment
		(start 408.076908 -427.793658)
		(end 407.792428 -427.509178)
		(width 0.14732)
		(layer "In11.Cu")
		(net "P5E_CPU0_PE2_TX_C_DP<2>")
	)
	(segment
		(start 411.35427 -406.517602)
		(end 411.53969 -404.633684)
		(width 0.14732)
		(layer "In11.Cu")
		(net "P5E_CPU0_PE2_TX_C_DP<2>")
	)
	(segment
		(start 411.53969 -404.178516)
		(end 411.24505 -403.883876)
		(width 0.14732)
		(layer "In11.Cu")
		(net "P5E_CPU0_PE2_TX_C_DP<2>")
	)
	(segment
		(start 407.792428 -424.757596)
		(end 410.873448 -411.669738)
		(width 0.14732)
		(layer "In11.Cu")
		(net "P5E_CPU0_PE2_TX_C_DP<2>")
	)
	(segment
		(start 407.792428 -427.509178)
		(end 407.792428 -424.757596)
		(width 0.14732)
		(layer "In11.Cu")
		(net "P5E_CPU0_PE2_TX_C_DP<2>")
	)
	(segment
		(start 411.35427 -410.27731)
		(end 411.35427 -406.517602)
		(width 0.14732)
		(layer "In11.Cu")
		(net "P5E_CPU0_PE2_TX_C_DP<2>")
	)
	(segment
		(start 411.53969 -404.633684)
		(end 411.53969 -404.178516)
		(width 0.14732)
		(layer "In11.Cu")
		(net "P5E_CPU0_PE2_TX_C_DP<2>")
	)
	(segment
		(start 408.600656 -427.793658)
		(end 408.076908 -427.793658)
		(width 0.14732)
		(layer "In11.Cu")
		(net "P5E_CPU0_PE2_TX_C_DP<2>")
	)
	(segment
		(start 414.611312 -403.580854)
		(end 414.611312 -402.962872)
		(width 0.13208)
		(layer "F.Cu")
		(net "P5E_CPU0_PE2_TX_C_DP<1>")
	)
	(segment
		(start 414.611312 -402.962872)
		(end 414.286192 -402.637752)
		(width 0.13208)
		(layer "F.Cu")
		(net "P5E_CPU0_PE2_TX_C_DP<1>")
	)
	(segment
		(start 414.30829 -403.883876)
		(end 414.611312 -403.580854)
		(width 0.13208)
		(layer "F.Cu")
		(net "P5E_CPU0_PE2_TX_C_DP<1>")
	)
	(segment
		(start 414.286192 -402.637752)
		(end 414.28289 -402.637752)
		(width 0.13208)
		(layer "F.Cu")
		(net "P5E_CPU0_PE2_TX_C_DP<1>")
	)
	(segment
		(start 409.792424 -426.50918)
		(end 409.792424 -424.757088)
		(width 0.14732)
		(layer "In11.Cu")
		(net "P5E_CPU0_PE2_TX_C_DP<1>")
	)
	(segment
		(start 414.60293 -404.178516)
		(end 414.30829 -403.883876)
		(width 0.14732)
		(layer "In11.Cu")
		(net "P5E_CPU0_PE2_TX_C_DP<1>")
	)
	(segment
		(start 414.41751 -410.22143)
		(end 414.41751 -406.517602)
		(width 0.14732)
		(layer "In11.Cu")
		(net "P5E_CPU0_PE2_TX_C_DP<1>")
	)
	(segment
		(start 414.60293 -404.633684)
		(end 414.60293 -404.178516)
		(width 0.14732)
		(layer "In11.Cu")
		(net "P5E_CPU0_PE2_TX_C_DP<1>")
	)
	(segment
		(start 410.750004 -427.289976)
		(end 410.750004 -426.980604)
		(width 0.14732)
		(layer "In11.Cu")
		(net "P5E_CPU0_PE2_TX_C_DP<1>")
	)
	(segment
		(start 410.56306 -426.79366)
		(end 410.076904 -426.79366)
		(width 0.14732)
		(layer "In11.Cu")
		(net "P5E_CPU0_PE2_TX_C_DP<1>")
	)
	(segment
		(start 409.792424 -424.757088)
		(end 413.881062 -411.574996)
		(width 0.14732)
		(layer "In11.Cu")
		(net "P5E_CPU0_PE2_TX_C_DP<1>")
	)
	(segment
		(start 410.076904 -426.79366)
		(end 409.792424 -426.50918)
		(width 0.14732)
		(layer "In11.Cu")
		(net "P5E_CPU0_PE2_TX_C_DP<1>")
	)
	(segment
		(start 410.750004 -426.980604)
		(end 410.56306 -426.79366)
		(width 0.14732)
		(layer "In11.Cu")
		(net "P5E_CPU0_PE2_TX_C_DP<1>")
	)
	(segment
		(start 413.881062 -411.574996)
		(end 414.41751 -410.22143)
		(width 0.14732)
		(layer "In11.Cu")
		(net "P5E_CPU0_PE2_TX_C_DP<1>")
	)
	(segment
		(start 414.41751 -406.517602)
		(end 414.60293 -404.633684)
		(width 0.14732)
		(layer "In11.Cu")
		(net "P5E_CPU0_PE2_TX_C_DP<1>")
	)
	(segment
		(start 372.28653 -403.883876)
		(end 371.985032 -403.582378)
		(width 0.13208)
		(layer "F.Cu")
		(net "P5E_CPU0_PE2_TX_C_DP<15>")
	)
	(segment
		(start 371.985032 -403.582378)
		(end 371.985032 -402.96465)
		(width 0.13208)
		(layer "F.Cu")
		(net "P5E_CPU0_PE2_TX_C_DP<15>")
	)
	(segment
		(start 371.985032 -402.96465)
		(end 372.31193 -402.637752)
		(width 0.13208)
		(layer "F.Cu")
		(net "P5E_CPU0_PE2_TX_C_DP<15>")
	)
	(segment
		(start 381.007112 -426.335698)
		(end 381.190754 -426.51934)
		(width 0.14732)
		(layer "In11.Cu")
		(net "P5E_CPU0_PE2_TX_C_DP<15>")
	)
	(segment
		(start 371.99189 -404.178516)
		(end 371.99189 -404.6474)
		(width 0.14732)
		(layer "In11.Cu")
		(net "P5E_CPU0_PE2_TX_C_DP<15>")
	)
	(segment
		(start 373.210328 -413.208978)
		(end 373.398288 -413.525462)
		(width 0.14732)
		(layer "In11.Cu")
		(net "P5E_CPU0_PE2_TX_C_DP<15>")
	)
	(segment
		(start 372.28653 -403.883876)
		(end 371.99189 -404.178516)
		(width 0.14732)
		(layer "In11.Cu")
		(net "P5E_CPU0_PE2_TX_C_DP<15>")
	)
	(segment
		(start 374.309386 -414.775396)
		(end 374.25884 -414.97377)
		(width 0.14732)
		(layer "In11.Cu")
		(net "P5E_CPU0_PE2_TX_C_DP<15>")
	)
	(segment
		(start 374.971056 -416.17265)
		(end 375.169684 -416.223196)
		(width 0.14732)
		(layer "In11.Cu")
		(net "P5E_CPU0_PE2_TX_C_DP<15>")
	)
	(segment
		(start 372.874032 -412.643066)
		(end 373.07266 -412.693612)
		(width 0.14732)
		(layer "In11.Cu")
		(net "P5E_CPU0_PE2_TX_C_DP<15>")
	)
	(segment
		(start 381.190754 -426.51934)
		(end 381.602234 -426.51934)
		(width 0.14732)
		(layer "In11.Cu")
		(net "P5E_CPU0_PE2_TX_C_DP<15>")
	)
	(segment
		(start 374.121172 -414.458404)
		(end 374.309386 -414.775396)
		(width 0.14732)
		(layer "In11.Cu")
		(net "P5E_CPU0_PE2_TX_C_DP<15>")
	)
	(segment
		(start 371.80647 -410.845762)
		(end 372.874032 -412.643066)
		(width 0.14732)
		(layer "In11.Cu")
		(net "P5E_CPU0_PE2_TX_C_DP<15>")
	)
	(segment
		(start 373.398288 -413.525462)
		(end 373.596916 -413.576008)
		(width 0.14732)
		(layer "In11.Cu")
		(net "P5E_CPU0_PE2_TX_C_DP<15>")
	)
	(segment
		(start 374.833642 -415.657792)
		(end 374.783096 -415.856166)
		(width 0.14732)
		(layer "In11.Cu")
		(net "P5E_CPU0_PE2_TX_C_DP<15>")
	)
	(segment
		(start 374.4468 -415.290254)
		(end 374.645428 -415.3408)
		(width 0.14732)
		(layer "In11.Cu")
		(net "P5E_CPU0_PE2_TX_C_DP<15>")
	)
	(segment
		(start 375.169684 -416.223196)
		(end 375.357898 -416.540188)
		(width 0.14732)
		(layer "In11.Cu")
		(net "P5E_CPU0_PE2_TX_C_DP<15>")
	)
	(segment
		(start 381.750062 -426.371512)
		(end 381.750062 -426.089826)
		(width 0.14732)
		(layer "In11.Cu")
		(net "P5E_CPU0_PE2_TX_C_DP<15>")
	)
	(segment
		(start 374.783096 -415.856166)
		(end 374.971056 -416.17265)
		(width 0.14732)
		(layer "In11.Cu")
		(net "P5E_CPU0_PE2_TX_C_DP<15>")
	)
	(segment
		(start 373.734584 -414.091374)
		(end 373.922544 -414.407858)
		(width 0.14732)
		(layer "In11.Cu")
		(net "P5E_CPU0_PE2_TX_C_DP<15>")
	)
	(segment
		(start 381.602234 -426.51934)
		(end 381.750062 -426.371512)
		(width 0.14732)
		(layer "In11.Cu")
		(net "P5E_CPU0_PE2_TX_C_DP<15>")
	)
	(segment
		(start 374.645428 -415.3408)
		(end 374.833642 -415.657792)
		(width 0.14732)
		(layer "In11.Cu")
		(net "P5E_CPU0_PE2_TX_C_DP<15>")
	)
	(segment
		(start 374.25884 -414.97377)
		(end 374.4468 -415.290254)
		(width 0.14732)
		(layer "In11.Cu")
		(net "P5E_CPU0_PE2_TX_C_DP<15>")
	)
	(segment
		(start 375.357898 -416.540188)
		(end 375.307352 -416.738562)
		(width 0.14732)
		(layer "In11.Cu")
		(net "P5E_CPU0_PE2_TX_C_DP<15>")
	)
	(segment
		(start 373.78513 -413.893)
		(end 373.734584 -414.091374)
		(width 0.14732)
		(layer "In11.Cu")
		(net "P5E_CPU0_PE2_TX_C_DP<15>")
	)
	(segment
		(start 371.80647 -406.531318)
		(end 371.80647 -410.845762)
		(width 0.14732)
		(layer "In11.Cu")
		(net "P5E_CPU0_PE2_TX_C_DP<15>")
	)
	(segment
		(start 373.260874 -413.010604)
		(end 373.210328 -413.208978)
		(width 0.14732)
		(layer "In11.Cu")
		(net "P5E_CPU0_PE2_TX_C_DP<15>")
	)
	(segment
		(start 373.596916 -413.576008)
		(end 373.78513 -413.893)
		(width 0.14732)
		(layer "In11.Cu")
		(net "P5E_CPU0_PE2_TX_C_DP<15>")
	)
	(segment
		(start 375.307352 -416.738562)
		(end 381.007112 -426.335698)
		(width 0.14732)
		(layer "In11.Cu")
		(net "P5E_CPU0_PE2_TX_C_DP<15>")
	)
	(segment
		(start 373.922544 -414.407858)
		(end 374.121172 -414.458404)
		(width 0.14732)
		(layer "In11.Cu")
		(net "P5E_CPU0_PE2_TX_C_DP<15>")
	)
	(segment
		(start 371.99189 -404.6474)
		(end 371.80647 -406.531318)
		(width 0.14732)
		(layer "In11.Cu")
		(net "P5E_CPU0_PE2_TX_C_DP<15>")
	)
	(segment
		(start 373.07266 -412.693612)
		(end 373.260874 -413.010604)
		(width 0.14732)
		(layer "In11.Cu")
		(net "P5E_CPU0_PE2_TX_C_DP<15>")
	)
	(segment
		(start 374.464072 -402.637752)
		(end 374.46077 -402.637752)
		(width 0.13208)
		(layer "F.Cu")
		(net "P5E_CPU0_PE2_TX_C_DP<14>")
	)
	(segment
		(start 374.789192 -403.580854)
		(end 374.789192 -402.962872)
		(width 0.13208)
		(layer "F.Cu")
		(net "P5E_CPU0_PE2_TX_C_DP<14>")
	)
	(segment
		(start 374.789192 -402.962872)
		(end 374.464072 -402.637752)
		(width 0.13208)
		(layer "F.Cu")
		(net "P5E_CPU0_PE2_TX_C_DP<14>")
	)
	(segment
		(start 374.48617 -403.883876)
		(end 374.789192 -403.580854)
		(width 0.13208)
		(layer "F.Cu")
		(net "P5E_CPU0_PE2_TX_C_DP<14>")
	)
	(segment
		(start 374.78081 -404.633684)
		(end 374.78081 -404.178516)
		(width 0.14732)
		(layer "In11.Cu")
		(net "P5E_CPU0_PE2_TX_C_DP<14>")
	)
	(segment
		(start 374.59539 -411.001972)
		(end 374.59539 -406.517602)
		(width 0.14732)
		(layer "In11.Cu")
		(net "P5E_CPU0_PE2_TX_C_DP<14>")
	)
	(segment
		(start 382.792478 -424.899328)
		(end 374.59539 -411.001972)
		(width 0.14732)
		(layer "In11.Cu")
		(net "P5E_CPU0_PE2_TX_C_DP<14>")
	)
	(segment
		(start 374.78081 -404.178516)
		(end 374.48617 -403.883876)
		(width 0.14732)
		(layer "In11.Cu")
		(net "P5E_CPU0_PE2_TX_C_DP<14>")
	)
	(segment
		(start 383.563114 -427.793658)
		(end 383.076958 -427.793658)
		(width 0.14732)
		(layer "In11.Cu")
		(net "P5E_CPU0_PE2_TX_C_DP<14>")
	)
	(segment
		(start 383.750058 -428.28972)
		(end 383.750058 -427.980602)
		(width 0.14732)
		(layer "In11.Cu")
		(net "P5E_CPU0_PE2_TX_C_DP<14>")
	)
	(segment
		(start 374.59539 -406.517602)
		(end 374.78081 -404.633684)
		(width 0.14732)
		(layer "In11.Cu")
		(net "P5E_CPU0_PE2_TX_C_DP<14>")
	)
	(segment
		(start 382.792478 -427.509178)
		(end 382.792478 -424.899328)
		(width 0.14732)
		(layer "In11.Cu")
		(net "P5E_CPU0_PE2_TX_C_DP<14>")
	)
	(segment
		(start 383.076958 -427.793658)
		(end 382.792478 -427.509178)
		(width 0.14732)
		(layer "In11.Cu")
		(net "P5E_CPU0_PE2_TX_C_DP<14>")
	)
	(segment
		(start 383.750058 -427.980602)
		(end 383.563114 -427.793658)
		(width 0.14732)
		(layer "In11.Cu")
		(net "P5E_CPU0_PE2_TX_C_DP<14>")
	)
	(segment
		(start 377.527312 -402.637752)
		(end 377.52401 -402.637752)
		(width 0.13208)
		(layer "F.Cu")
		(net "P5E_CPU0_PE2_TX_C_DP<13>")
	)
	(segment
		(start 377.852432 -402.962872)
		(end 377.527312 -402.637752)
		(width 0.13208)
		(layer "F.Cu")
		(net "P5E_CPU0_PE2_TX_C_DP<13>")
	)
	(segment
		(start 377.852432 -403.580854)
		(end 377.852432 -402.962872)
		(width 0.13208)
		(layer "F.Cu")
		(net "P5E_CPU0_PE2_TX_C_DP<13>")
	)
	(segment
		(start 377.54941 -403.883876)
		(end 377.852432 -403.580854)
		(width 0.13208)
		(layer "F.Cu")
		(net "P5E_CPU0_PE2_TX_C_DP<13>")
	)
	(segment
		(start 377.84405 -404.633684)
		(end 377.84405 -404.178516)
		(width 0.14732)
		(layer "In11.Cu")
		(net "P5E_CPU0_PE2_TX_C_DP<13>")
	)
	(segment
		(start 385.750054 -426.980604)
		(end 385.56311 -426.79366)
		(width 0.14732)
		(layer "In11.Cu")
		(net "P5E_CPU0_PE2_TX_C_DP<13>")
	)
	(segment
		(start 385.56311 -426.79366)
		(end 385.076954 -426.79366)
		(width 0.14732)
		(layer "In11.Cu")
		(net "P5E_CPU0_PE2_TX_C_DP<13>")
	)
	(segment
		(start 377.65863 -406.517602)
		(end 377.84405 -404.633684)
		(width 0.14732)
		(layer "In11.Cu")
		(net "P5E_CPU0_PE2_TX_C_DP<13>")
	)
	(segment
		(start 384.792474 -426.50918)
		(end 384.792474 -424.823636)
		(width 0.14732)
		(layer "In11.Cu")
		(net "P5E_CPU0_PE2_TX_C_DP<13>")
	)
	(segment
		(start 384.792474 -424.823636)
		(end 378.109226 -411.8483)
		(width 0.14732)
		(layer "In11.Cu")
		(net "P5E_CPU0_PE2_TX_C_DP<13>")
	)
	(segment
		(start 377.65863 -410.973524)
		(end 377.65863 -406.517602)
		(width 0.14732)
		(layer "In11.Cu")
		(net "P5E_CPU0_PE2_TX_C_DP<13>")
	)
	(segment
		(start 378.109226 -411.8483)
		(end 377.65863 -410.973524)
		(width 0.14732)
		(layer "In11.Cu")
		(net "P5E_CPU0_PE2_TX_C_DP<13>")
	)
	(segment
		(start 385.750054 -427.289976)
		(end 385.750054 -426.980604)
		(width 0.14732)
		(layer "In11.Cu")
		(net "P5E_CPU0_PE2_TX_C_DP<13>")
	)
	(segment
		(start 377.84405 -404.178516)
		(end 377.54941 -403.883876)
		(width 0.14732)
		(layer "In11.Cu")
		(net "P5E_CPU0_PE2_TX_C_DP<13>")
	)
	(segment
		(start 385.076954 -426.79366)
		(end 384.792474 -426.50918)
		(width 0.14732)
		(layer "In11.Cu")
		(net "P5E_CPU0_PE2_TX_C_DP<13>")
	)
	(segment
		(start 380.61265 -403.883876)
		(end 380.915672 -403.580854)
		(width 0.13208)
		(layer "F.Cu")
		(net "P5E_CPU0_PE2_TX_C_DP<12>")
	)
	(segment
		(start 380.915672 -402.962872)
		(end 380.590552 -402.637752)
		(width 0.13208)
		(layer "F.Cu")
		(net "P5E_CPU0_PE2_TX_C_DP<12>")
	)
	(segment
		(start 380.915672 -403.580854)
		(end 380.915672 -402.962872)
		(width 0.13208)
		(layer "F.Cu")
		(net "P5E_CPU0_PE2_TX_C_DP<12>")
	)
	(segment
		(start 380.590552 -402.637752)
		(end 380.58725 -402.637752)
		(width 0.13208)
		(layer "F.Cu")
		(net "P5E_CPU0_PE2_TX_C_DP<12>")
	)
	(segment
		(start 387.07695 -427.793658)
		(end 386.79247 -427.509178)
		(width 0.14732)
		(layer "In11.Cu")
		(net "P5E_CPU0_PE2_TX_C_DP<12>")
	)
	(segment
		(start 387.75005 -428.28972)
		(end 387.75005 -427.980602)
		(width 0.14732)
		(layer "In11.Cu")
		(net "P5E_CPU0_PE2_TX_C_DP<12>")
	)
	(segment
		(start 380.90729 -404.178516)
		(end 380.61265 -403.883876)
		(width 0.14732)
		(layer "In11.Cu")
		(net "P5E_CPU0_PE2_TX_C_DP<12>")
	)
	(segment
		(start 387.75005 -427.980602)
		(end 387.563106 -427.793658)
		(width 0.14732)
		(layer "In11.Cu")
		(net "P5E_CPU0_PE2_TX_C_DP<12>")
	)
	(segment
		(start 386.79247 -427.509178)
		(end 386.79247 -424.815)
		(width 0.14732)
		(layer "In11.Cu")
		(net "P5E_CPU0_PE2_TX_C_DP<12>")
	)
	(segment
		(start 387.563106 -427.793658)
		(end 387.07695 -427.793658)
		(width 0.14732)
		(layer "In11.Cu")
		(net "P5E_CPU0_PE2_TX_C_DP<12>")
	)
	(segment
		(start 380.72187 -411.028134)
		(end 380.72187 -406.517602)
		(width 0.14732)
		(layer "In11.Cu")
		(net "P5E_CPU0_PE2_TX_C_DP<12>")
	)
	(segment
		(start 380.90729 -404.633684)
		(end 380.90729 -404.178516)
		(width 0.14732)
		(layer "In11.Cu")
		(net "P5E_CPU0_PE2_TX_C_DP<12>")
	)
	(segment
		(start 386.79247 -424.815)
		(end 380.72187 -411.028134)
		(width 0.14732)
		(layer "In11.Cu")
		(net "P5E_CPU0_PE2_TX_C_DP<12>")
	)
	(segment
		(start 380.72187 -406.517602)
		(end 380.90729 -404.633684)
		(width 0.14732)
		(layer "In11.Cu")
		(net "P5E_CPU0_PE2_TX_C_DP<12>")
	)
	(segment
		(start 383.67589 -403.883876)
		(end 383.978912 -403.580854)
		(width 0.13208)
		(layer "F.Cu")
		(net "P5E_CPU0_PE2_TX_C_DP<11>")
	)
	(segment
		(start 383.978912 -403.580854)
		(end 383.978912 -402.962872)
		(width 0.13208)
		(layer "F.Cu")
		(net "P5E_CPU0_PE2_TX_C_DP<11>")
	)
	(segment
		(start 383.978912 -402.962872)
		(end 383.653792 -402.637752)
		(width 0.13208)
		(layer "F.Cu")
		(net "P5E_CPU0_PE2_TX_C_DP<11>")
	)
	(segment
		(start 383.653792 -402.637752)
		(end 383.65049 -402.637752)
		(width 0.13208)
		(layer "F.Cu")
		(net "P5E_CPU0_PE2_TX_C_DP<11>")
	)
	(segment
		(start 389.750046 -427.289976)
		(end 389.750046 -426.980604)
		(width 0.14732)
		(layer "In11.Cu")
		(net "P5E_CPU0_PE2_TX_C_DP<11>")
	)
	(segment
		(start 383.78511 -411.108144)
		(end 383.78511 -406.517602)
		(width 0.14732)
		(layer "In11.Cu")
		(net "P5E_CPU0_PE2_TX_C_DP<11>")
	)
	(segment
		(start 388.792466 -426.50918)
		(end 388.792466 -424.805856)
		(width 0.14732)
		(layer "In11.Cu")
		(net "P5E_CPU0_PE2_TX_C_DP<11>")
	)
	(segment
		(start 388.792466 -424.805856)
		(end 383.78511 -411.108144)
		(width 0.14732)
		(layer "In11.Cu")
		(net "P5E_CPU0_PE2_TX_C_DP<11>")
	)
	(segment
		(start 389.750046 -426.980604)
		(end 389.563102 -426.79366)
		(width 0.14732)
		(layer "In11.Cu")
		(net "P5E_CPU0_PE2_TX_C_DP<11>")
	)
	(segment
		(start 383.78511 -406.517602)
		(end 383.97053 -404.633684)
		(width 0.14732)
		(layer "In11.Cu")
		(net "P5E_CPU0_PE2_TX_C_DP<11>")
	)
	(segment
		(start 383.97053 -404.633684)
		(end 383.97053 -404.178516)
		(width 0.14732)
		(layer "In11.Cu")
		(net "P5E_CPU0_PE2_TX_C_DP<11>")
	)
	(segment
		(start 389.563102 -426.79366)
		(end 389.076946 -426.79366)
		(width 0.14732)
		(layer "In11.Cu")
		(net "P5E_CPU0_PE2_TX_C_DP<11>")
	)
	(segment
		(start 383.97053 -404.178516)
		(end 383.67589 -403.883876)
		(width 0.14732)
		(layer "In11.Cu")
		(net "P5E_CPU0_PE2_TX_C_DP<11>")
	)
	(segment
		(start 389.076946 -426.79366)
		(end 388.792466 -426.50918)
		(width 0.14732)
		(layer "In11.Cu")
		(net "P5E_CPU0_PE2_TX_C_DP<11>")
	)
	(segment
		(start 387.042152 -403.580854)
		(end 387.042152 -402.962872)
		(width 0.13208)
		(layer "F.Cu")
		(net "P5E_CPU0_PE2_TX_C_DP<10>")
	)
	(segment
		(start 387.042152 -402.962872)
		(end 386.717032 -402.637752)
		(width 0.13208)
		(layer "F.Cu")
		(net "P5E_CPU0_PE2_TX_C_DP<10>")
	)
	(segment
		(start 386.717032 -402.637752)
		(end 386.71373 -402.637752)
		(width 0.13208)
		(layer "F.Cu")
		(net "P5E_CPU0_PE2_TX_C_DP<10>")
	)
	(segment
		(start 386.73913 -403.883876)
		(end 387.042152 -403.580854)
		(width 0.13208)
		(layer "F.Cu")
		(net "P5E_CPU0_PE2_TX_C_DP<10>")
	)
	(segment
		(start 386.84835 -411.234128)
		(end 386.84835 -406.517602)
		(width 0.14732)
		(layer "In11.Cu")
		(net "P5E_CPU0_PE2_TX_C_DP<10>")
	)
	(segment
		(start 387.03377 -404.633684)
		(end 387.03377 -404.178516)
		(width 0.14732)
		(layer "In11.Cu")
		(net "P5E_CPU0_PE2_TX_C_DP<10>")
	)
	(segment
		(start 390.78154 -424.796204)
		(end 387.299454 -412.789624)
		(width 0.14732)
		(layer "In11.Cu")
		(net "P5E_CPU0_PE2_TX_C_DP<10>")
	)
	(segment
		(start 387.2992 -412.789116)
		(end 386.84835 -411.234128)
		(width 0.14732)
		(layer "In11.Cu")
		(net "P5E_CPU0_PE2_TX_C_DP<10>")
	)
	(segment
		(start 391.563098 -427.793658)
		(end 391.076942 -427.793658)
		(width 0.14732)
		(layer "In11.Cu")
		(net "P5E_CPU0_PE2_TX_C_DP<10>")
	)
	(segment
		(start 387.299454 -412.789624)
		(end 387.2992 -412.789116)
		(width 0.14732)
		(layer "In11.Cu")
		(net "P5E_CPU0_PE2_TX_C_DP<10>")
	)
	(segment
		(start 387.03377 -404.178516)
		(end 386.73913 -403.883876)
		(width 0.14732)
		(layer "In11.Cu")
		(net "P5E_CPU0_PE2_TX_C_DP<10>")
	)
	(segment
		(start 386.84835 -406.517602)
		(end 387.03377 -404.633684)
		(width 0.14732)
		(layer "In11.Cu")
		(net "P5E_CPU0_PE2_TX_C_DP<10>")
	)
	(segment
		(start 391.750042 -428.28972)
		(end 391.750042 -427.980602)
		(width 0.14732)
		(layer "In11.Cu")
		(net "P5E_CPU0_PE2_TX_C_DP<10>")
	)
	(segment
		(start 390.78154 -427.498256)
		(end 390.78154 -424.796204)
		(width 0.14732)
		(layer "In11.Cu")
		(net "P5E_CPU0_PE2_TX_C_DP<10>")
	)
	(segment
		(start 391.750042 -427.980602)
		(end 391.563098 -427.793658)
		(width 0.14732)
		(layer "In11.Cu")
		(net "P5E_CPU0_PE2_TX_C_DP<10>")
	)
	(segment
		(start 391.076942 -427.793658)
		(end 390.78154 -427.498256)
		(width 0.14732)
		(layer "In11.Cu")
		(net "P5E_CPU0_PE2_TX_C_DP<10>")
	)
	(segment
		(start 417.37153 -403.883876)
		(end 417.674552 -403.580854)
		(width 0.13208)
		(layer "F.Cu")
		(net "P5E_CPU0_PE2_TX_C_DP<0>")
	)
	(segment
		(start 417.674552 -402.962872)
		(end 417.349432 -402.637752)
		(width 0.13208)
		(layer "F.Cu")
		(net "P5E_CPU0_PE2_TX_C_DP<0>")
	)
	(segment
		(start 417.349432 -402.637752)
		(end 417.34613 -402.637752)
		(width 0.13208)
		(layer "F.Cu")
		(net "P5E_CPU0_PE2_TX_C_DP<0>")
	)
	(segment
		(start 417.674552 -403.580854)
		(end 417.674552 -402.962872)
		(width 0.13208)
		(layer "F.Cu")
		(net "P5E_CPU0_PE2_TX_C_DP<0>")
	)
	(segment
		(start 412.75 -428.28972)
		(end 412.75 -427.980602)
		(width 0.14732)
		(layer "In11.Cu")
		(net "P5E_CPU0_PE2_TX_C_DP<0>")
	)
	(segment
		(start 412.75 -427.980602)
		(end 412.563056 -427.793658)
		(width 0.14732)
		(layer "In11.Cu")
		(net "P5E_CPU0_PE2_TX_C_DP<0>")
	)
	(segment
		(start 416.87115 -411.542992)
		(end 417.48075 -410.206952)
		(width 0.14732)
		(layer "In11.Cu")
		(net "P5E_CPU0_PE2_TX_C_DP<0>")
	)
	(segment
		(start 417.48075 -410.206952)
		(end 417.48075 -406.517602)
		(width 0.14732)
		(layer "In11.Cu")
		(net "P5E_CPU0_PE2_TX_C_DP<0>")
	)
	(segment
		(start 411.79242 -427.509178)
		(end 411.79242 -424.378628)
		(width 0.14732)
		(layer "In11.Cu")
		(net "P5E_CPU0_PE2_TX_C_DP<0>")
	)
	(segment
		(start 417.48075 -406.517602)
		(end 417.66617 -404.633684)
		(width 0.14732)
		(layer "In11.Cu")
		(net "P5E_CPU0_PE2_TX_C_DP<0>")
	)
	(segment
		(start 415.738056 -414.407096)
		(end 415.738564 -414.405572)
		(width 0.14732)
		(layer "In11.Cu")
		(net "P5E_CPU0_PE2_TX_C_DP<0>")
	)
	(segment
		(start 412.563056 -427.793658)
		(end 412.0769 -427.793658)
		(width 0.14732)
		(layer "In11.Cu")
		(net "P5E_CPU0_PE2_TX_C_DP<0>")
	)
	(segment
		(start 412.0769 -427.793658)
		(end 411.79242 -427.509178)
		(width 0.14732)
		(layer "In11.Cu")
		(net "P5E_CPU0_PE2_TX_C_DP<0>")
	)
	(segment
		(start 411.79242 -424.378628)
		(end 415.738056 -414.407096)
		(width 0.14732)
		(layer "In11.Cu")
		(net "P5E_CPU0_PE2_TX_C_DP<0>")
	)
	(segment
		(start 415.738564 -414.405572)
		(end 416.87115 -411.542992)
		(width 0.14732)
		(layer "In11.Cu")
		(net "P5E_CPU0_PE2_TX_C_DP<0>")
	)
	(segment
		(start 417.66617 -404.633684)
		(end 417.66617 -404.178516)
		(width 0.14732)
		(layer "In11.Cu")
		(net "P5E_CPU0_PE2_TX_C_DP<0>")
	)
	(segment
		(start 417.66617 -404.178516)
		(end 417.37153 -403.883876)
		(width 0.14732)
		(layer "In11.Cu")
		(net "P5E_CPU0_PE2_TX_C_DP<0>")
	)
	(segment
		(start 390.364472 -402.96465)
		(end 390.69137 -402.637752)
		(width 0.13208)
		(layer "F.Cu")
		(net "P5E_CPU0_PE2_TX_C_DN<9>")
	)
	(segment
		(start 390.364472 -403.582378)
		(end 390.364472 -402.96465)
		(width 0.13208)
		(layer "F.Cu")
		(net "P5E_CPU0_PE2_TX_C_DN<9>")
	)
	(segment
		(start 390.66597 -403.883876)
		(end 390.364472 -403.582378)
		(width 0.13208)
		(layer "F.Cu")
		(net "P5E_CPU0_PE2_TX_C_DN<9>")
	)
	(segment
		(start 390.37133 -404.178516)
		(end 390.37133 -404.6474)
		(width 0.14732)
		(layer "In11.Cu")
		(net "P5E_CPU0_PE2_TX_C_DN<9>")
	)
	(segment
		(start 390.802114 -413.450024)
		(end 390.879076 -413.81045)
		(width 0.14732)
		(layer "In11.Cu")
		(net "P5E_CPU0_PE2_TX_C_DN<9>")
	)
	(segment
		(start 390.66597 -403.883876)
		(end 390.37133 -404.178516)
		(width 0.14732)
		(layer "In11.Cu")
		(net "P5E_CPU0_PE2_TX_C_DN<9>")
	)
	(segment
		(start 391.195814 -415.990024)
		(end 393.04468 -424.655742)
		(width 0.14732)
		(layer "In11.Cu")
		(net "P5E_CPU0_PE2_TX_C_DN<9>")
	)
	(segment
		(start 390.630156 -413.338772)
		(end 390.802114 -413.450024)
		(width 0.14732)
		(layer "In11.Cu")
		(net "P5E_CPU0_PE2_TX_C_DN<9>")
	)
	(segment
		(start 391.093198 -414.814258)
		(end 390.981692 -414.986216)
		(width 0.14732)
		(layer "In11.Cu")
		(net "P5E_CPU0_PE2_TX_C_DN<9>")
	)
	(segment
		(start 393.237466 -426.51934)
		(end 393.60221 -426.51934)
		(width 0.14732)
		(layer "In11.Cu")
		(net "P5E_CPU0_PE2_TX_C_DN<9>")
	)
	(segment
		(start 390.416034 -412.335218)
		(end 390.587992 -412.446216)
		(width 0.14732)
		(layer "In11.Cu")
		(net "P5E_CPU0_PE2_TX_C_DN<9>")
	)
	(segment
		(start 390.879076 -413.81045)
		(end 390.76757 -413.982408)
		(width 0.14732)
		(layer "In11.Cu")
		(net "P5E_CPU0_PE2_TX_C_DN<9>")
	)
	(segment
		(start 390.587992 -412.446216)
		(end 390.6647 -412.806642)
		(width 0.14732)
		(layer "In11.Cu")
		(net "P5E_CPU0_PE2_TX_C_DN<9>")
	)
	(segment
		(start 393.60221 -426.51934)
		(end 393.750038 -426.371512)
		(width 0.14732)
		(layer "In11.Cu")
		(net "P5E_CPU0_PE2_TX_C_DN<9>")
	)
	(segment
		(start 390.981692 -414.986216)
		(end 391.0584 -415.346388)
		(width 0.14732)
		(layer "In11.Cu")
		(net "P5E_CPU0_PE2_TX_C_DN<9>")
	)
	(segment
		(start 393.750038 -426.371512)
		(end 393.750038 -426.089826)
		(width 0.14732)
		(layer "In11.Cu")
		(net "P5E_CPU0_PE2_TX_C_DN<9>")
	)
	(segment
		(start 391.016236 -414.453832)
		(end 391.093198 -414.814258)
		(width 0.14732)
		(layer "In11.Cu")
		(net "P5E_CPU0_PE2_TX_C_DN<9>")
	)
	(segment
		(start 390.37133 -404.6474)
		(end 390.18591 -406.531318)
		(width 0.14732)
		(layer "In11.Cu")
		(net "P5E_CPU0_PE2_TX_C_DN<9>")
	)
	(segment
		(start 390.76757 -413.982408)
		(end 390.844278 -414.34258)
		(width 0.14732)
		(layer "In11.Cu")
		(net "P5E_CPU0_PE2_TX_C_DN<9>")
	)
	(segment
		(start 393.04468 -424.655742)
		(end 393.04468 -426.326554)
		(width 0.14732)
		(layer "In11.Cu")
		(net "P5E_CPU0_PE2_TX_C_DN<9>")
	)
	(segment
		(start 391.0584 -415.346388)
		(end 391.230358 -415.45764)
		(width 0.14732)
		(layer "In11.Cu")
		(net "P5E_CPU0_PE2_TX_C_DN<9>")
	)
	(segment
		(start 391.230358 -415.45764)
		(end 391.30732 -415.818066)
		(width 0.14732)
		(layer "In11.Cu")
		(net "P5E_CPU0_PE2_TX_C_DN<9>")
	)
	(segment
		(start 390.18591 -411.256734)
		(end 390.416034 -412.335218)
		(width 0.14732)
		(layer "In11.Cu")
		(net "P5E_CPU0_PE2_TX_C_DN<9>")
	)
	(segment
		(start 390.844278 -414.34258)
		(end 391.016236 -414.453832)
		(width 0.14732)
		(layer "In11.Cu")
		(net "P5E_CPU0_PE2_TX_C_DN<9>")
	)
	(segment
		(start 390.553448 -412.9786)
		(end 390.630156 -413.338772)
		(width 0.14732)
		(layer "In11.Cu")
		(net "P5E_CPU0_PE2_TX_C_DN<9>")
	)
	(segment
		(start 390.18591 -406.531318)
		(end 390.18591 -411.256734)
		(width 0.14732)
		(layer "In11.Cu")
		(net "P5E_CPU0_PE2_TX_C_DN<9>")
	)
	(segment
		(start 393.04468 -426.326554)
		(end 393.237466 -426.51934)
		(width 0.14732)
		(layer "In11.Cu")
		(net "P5E_CPU0_PE2_TX_C_DN<9>")
	)
	(segment
		(start 391.30732 -415.818066)
		(end 391.195814 -415.990024)
		(width 0.14732)
		(layer "In11.Cu")
		(net "P5E_CPU0_PE2_TX_C_DN<9>")
	)
	(segment
		(start 390.6647 -412.806642)
		(end 390.553448 -412.9786)
		(width 0.14732)
		(layer "In11.Cu")
		(net "P5E_CPU0_PE2_TX_C_DN<9>")
	)
	(segment
		(start 393.72921 -403.883876)
		(end 393.427712 -403.582378)
		(width 0.13208)
		(layer "F.Cu")
		(net "P5E_CPU0_PE2_TX_C_DN<8>")
	)
	(segment
		(start 393.427712 -402.96465)
		(end 393.75461 -402.637752)
		(width 0.13208)
		(layer "F.Cu")
		(net "P5E_CPU0_PE2_TX_C_DN<8>")
	)
	(segment
		(start 393.427712 -403.582378)
		(end 393.427712 -402.96465)
		(width 0.13208)
		(layer "F.Cu")
		(net "P5E_CPU0_PE2_TX_C_DN<8>")
	)
	(segment
		(start 395.190726 -427.519338)
		(end 395.602206 -427.519338)
		(width 0.14732)
		(layer "In11.Cu")
		(net "P5E_CPU0_PE2_TX_C_DN<8>")
	)
	(segment
		(start 393.721844 -414.200594)
		(end 393.598908 -414.36417)
		(width 0.14732)
		(layer "In11.Cu")
		(net "P5E_CPU0_PE2_TX_C_DN<8>")
	)
	(segment
		(start 393.455144 -413.347916)
		(end 393.506452 -413.712406)
		(width 0.14732)
		(layer "In11.Cu")
		(net "P5E_CPU0_PE2_TX_C_DN<8>")
	)
	(segment
		(start 393.650216 -414.72866)
		(end 393.814046 -414.85185)
		(width 0.14732)
		(layer "In11.Cu")
		(net "P5E_CPU0_PE2_TX_C_DN<8>")
	)
	(segment
		(start 395.066774 -424.75912)
		(end 395.066774 -427.395386)
		(width 0.14732)
		(layer "In11.Cu")
		(net "P5E_CPU0_PE2_TX_C_DN<8>")
	)
	(segment
		(start 393.362942 -412.696406)
		(end 393.526518 -412.819342)
		(width 0.14732)
		(layer "In11.Cu")
		(net "P5E_CPU0_PE2_TX_C_DN<8>")
	)
	(segment
		(start 393.24915 -411.890464)
		(end 393.362942 -412.696406)
		(width 0.14732)
		(layer "In11.Cu")
		(net "P5E_CPU0_PE2_TX_C_DN<8>")
	)
	(segment
		(start 393.43457 -404.6474)
		(end 393.24915 -406.531318)
		(width 0.14732)
		(layer "In11.Cu")
		(net "P5E_CPU0_PE2_TX_C_DN<8>")
	)
	(segment
		(start 395.602206 -427.519338)
		(end 395.750034 -427.37151)
		(width 0.14732)
		(layer "In11.Cu")
		(net "P5E_CPU0_PE2_TX_C_DN<8>")
	)
	(segment
		(start 393.72921 -403.883876)
		(end 393.43457 -404.178516)
		(width 0.14732)
		(layer "In11.Cu")
		(net "P5E_CPU0_PE2_TX_C_DN<8>")
	)
	(segment
		(start 393.865608 -415.216848)
		(end 393.742418 -415.380424)
		(width 0.14732)
		(layer "In11.Cu")
		(net "P5E_CPU0_PE2_TX_C_DN<8>")
	)
	(segment
		(start 393.742418 -415.380424)
		(end 393.741656 -415.38144)
		(width 0.14732)
		(layer "In11.Cu")
		(net "P5E_CPU0_PE2_TX_C_DN<8>")
	)
	(segment
		(start 393.43457 -404.178516)
		(end 393.43457 -404.6474)
		(width 0.14732)
		(layer "In11.Cu")
		(net "P5E_CPU0_PE2_TX_C_DN<8>")
	)
	(segment
		(start 393.526518 -412.819342)
		(end 393.57808 -413.18434)
		(width 0.14732)
		(layer "In11.Cu")
		(net "P5E_CPU0_PE2_TX_C_DN<8>")
	)
	(segment
		(start 395.750034 -427.37151)
		(end 395.750034 -427.089824)
		(width 0.14732)
		(layer "In11.Cu")
		(net "P5E_CPU0_PE2_TX_C_DN<8>")
	)
	(segment
		(start 393.814046 -414.85185)
		(end 393.865608 -415.216848)
		(width 0.14732)
		(layer "In11.Cu")
		(net "P5E_CPU0_PE2_TX_C_DN<8>")
	)
	(segment
		(start 393.598908 -414.36417)
		(end 393.650216 -414.72866)
		(width 0.14732)
		(layer "In11.Cu")
		(net "P5E_CPU0_PE2_TX_C_DN<8>")
	)
	(segment
		(start 393.24915 -406.531318)
		(end 393.24915 -411.890464)
		(width 0.14732)
		(layer "In11.Cu")
		(net "P5E_CPU0_PE2_TX_C_DN<8>")
	)
	(segment
		(start 395.06525 -424.757596)
		(end 395.066774 -424.75912)
		(width 0.14732)
		(layer "In11.Cu")
		(net "P5E_CPU0_PE2_TX_C_DN<8>")
	)
	(segment
		(start 393.741656 -415.38144)
		(end 395.064234 -424.757596)
		(width 0.14732)
		(layer "In11.Cu")
		(net "P5E_CPU0_PE2_TX_C_DN<8>")
	)
	(segment
		(start 393.57808 -413.18434)
		(end 393.455144 -413.347916)
		(width 0.14732)
		(layer "In11.Cu")
		(net "P5E_CPU0_PE2_TX_C_DN<8>")
	)
	(segment
		(start 395.066774 -427.395386)
		(end 395.190726 -427.519338)
		(width 0.14732)
		(layer "In11.Cu")
		(net "P5E_CPU0_PE2_TX_C_DN<8>")
	)
	(segment
		(start 393.506452 -413.712406)
		(end 393.670282 -413.835596)
		(width 0.14732)
		(layer "In11.Cu")
		(net "P5E_CPU0_PE2_TX_C_DN<8>")
	)
	(segment
		(start 393.670282 -413.835596)
		(end 393.721844 -414.200594)
		(width 0.14732)
		(layer "In11.Cu")
		(net "P5E_CPU0_PE2_TX_C_DN<8>")
	)
	(segment
		(start 395.064234 -424.757596)
		(end 395.06525 -424.757596)
		(width 0.14732)
		(layer "In11.Cu")
		(net "P5E_CPU0_PE2_TX_C_DN<8>")
	)
	(segment
		(start 396.79245 -403.883876)
		(end 396.490952 -403.582378)
		(width 0.13208)
		(layer "F.Cu")
		(net "P5E_CPU0_PE2_TX_C_DN<7>")
	)
	(segment
		(start 396.490952 -402.96465)
		(end 396.81785 -402.637752)
		(width 0.13208)
		(layer "F.Cu")
		(net "P5E_CPU0_PE2_TX_C_DN<7>")
	)
	(segment
		(start 396.490952 -403.582378)
		(end 396.490952 -402.96465)
		(width 0.13208)
		(layer "F.Cu")
		(net "P5E_CPU0_PE2_TX_C_DN<7>")
	)
	(segment
		(start 396.984728 -416.934396)
		(end 397.03502 -417.29914)
		(width 0.14732)
		(layer "In11.Cu")
		(net "P5E_CPU0_PE2_TX_C_DN<7>")
	)
	(segment
		(start 396.49781 -404.6474)
		(end 396.31239 -406.531318)
		(width 0.14732)
		(layer "In11.Cu")
		(net "P5E_CPU0_PE2_TX_C_DN<7>")
	)
	(segment
		(start 397.05788 -416.406076)
		(end 397.108426 -416.771328)
		(width 0.14732)
		(layer "In11.Cu")
		(net "P5E_CPU0_PE2_TX_C_DN<7>")
	)
	(segment
		(start 397.12519 -417.951158)
		(end 398.066768 -424.757088)
		(width 0.14732)
		(layer "In11.Cu")
		(net "P5E_CPU0_PE2_TX_C_DN<7>")
	)
	(segment
		(start 396.703296 -414.90138)
		(end 396.753588 -415.266124)
		(width 0.14732)
		(layer "In11.Cu")
		(net "P5E_CPU0_PE2_TX_C_DN<7>")
	)
	(segment
		(start 396.753588 -415.266124)
		(end 396.917164 -415.389568)
		(width 0.14732)
		(layer "In11.Cu")
		(net "P5E_CPU0_PE2_TX_C_DN<7>")
	)
	(segment
		(start 396.31239 -406.531318)
		(end 396.31239 -412.078424)
		(width 0.14732)
		(layer "In11.Cu")
		(net "P5E_CPU0_PE2_TX_C_DN<7>")
	)
	(segment
		(start 396.776448 -414.37306)
		(end 396.826994 -414.738312)
		(width 0.14732)
		(layer "In11.Cu")
		(net "P5E_CPU0_PE2_TX_C_DN<7>")
	)
	(segment
		(start 397.249142 -417.787836)
		(end 397.125444 -417.950904)
		(width 0.14732)
		(layer "In11.Cu")
		(net "P5E_CPU0_PE2_TX_C_DN<7>")
	)
	(segment
		(start 396.635478 -413.356552)
		(end 396.686024 -413.72155)
		(width 0.14732)
		(layer "In11.Cu")
		(net "P5E_CPU0_PE2_TX_C_DN<7>")
	)
	(segment
		(start 398.066768 -426.395388)
		(end 398.19072 -426.51934)
		(width 0.14732)
		(layer "In11.Cu")
		(net "P5E_CPU0_PE2_TX_C_DN<7>")
	)
	(segment
		(start 398.6022 -426.51934)
		(end 398.750028 -426.371512)
		(width 0.14732)
		(layer "In11.Cu")
		(net "P5E_CPU0_PE2_TX_C_DN<7>")
	)
	(segment
		(start 396.56258 -413.884872)
		(end 396.612872 -414.249616)
		(width 0.14732)
		(layer "In11.Cu")
		(net "P5E_CPU0_PE2_TX_C_DN<7>")
	)
	(segment
		(start 397.125444 -417.950904)
		(end 397.12519 -417.951158)
		(width 0.14732)
		(layer "In11.Cu")
		(net "P5E_CPU0_PE2_TX_C_DN<7>")
	)
	(segment
		(start 397.108426 -416.771328)
		(end 396.984728 -416.934396)
		(width 0.14732)
		(layer "In11.Cu")
		(net "P5E_CPU0_PE2_TX_C_DN<7>")
	)
	(segment
		(start 398.750028 -426.371512)
		(end 398.750028 -426.089826)
		(width 0.14732)
		(layer "In11.Cu")
		(net "P5E_CPU0_PE2_TX_C_DN<7>")
	)
	(segment
		(start 396.844012 -415.917888)
		(end 396.894304 -416.282632)
		(width 0.14732)
		(layer "In11.Cu")
		(net "P5E_CPU0_PE2_TX_C_DN<7>")
	)
	(segment
		(start 396.472156 -413.233108)
		(end 396.635478 -413.356552)
		(width 0.14732)
		(layer "In11.Cu")
		(net "P5E_CPU0_PE2_TX_C_DN<7>")
	)
	(segment
		(start 396.826994 -414.738312)
		(end 396.703296 -414.90138)
		(width 0.14732)
		(layer "In11.Cu")
		(net "P5E_CPU0_PE2_TX_C_DN<7>")
	)
	(segment
		(start 396.894304 -416.282632)
		(end 397.05788 -416.406076)
		(width 0.14732)
		(layer "In11.Cu")
		(net "P5E_CPU0_PE2_TX_C_DN<7>")
	)
	(segment
		(start 396.96771 -415.75482)
		(end 396.844012 -415.917888)
		(width 0.14732)
		(layer "In11.Cu")
		(net "P5E_CPU0_PE2_TX_C_DN<7>")
	)
	(segment
		(start 396.79245 -403.883876)
		(end 396.49781 -404.178516)
		(width 0.14732)
		(layer "In11.Cu")
		(net "P5E_CPU0_PE2_TX_C_DN<7>")
	)
	(segment
		(start 398.066768 -424.757088)
		(end 398.066768 -426.395388)
		(width 0.14732)
		(layer "In11.Cu")
		(net "P5E_CPU0_PE2_TX_C_DN<7>")
	)
	(segment
		(start 396.31239 -412.078424)
		(end 396.472156 -413.233108)
		(width 0.14732)
		(layer "In11.Cu")
		(net "P5E_CPU0_PE2_TX_C_DN<7>")
	)
	(segment
		(start 397.198596 -417.422584)
		(end 397.249142 -417.787836)
		(width 0.14732)
		(layer "In11.Cu")
		(net "P5E_CPU0_PE2_TX_C_DN<7>")
	)
	(segment
		(start 398.19072 -426.51934)
		(end 398.6022 -426.51934)
		(width 0.14732)
		(layer "In11.Cu")
		(net "P5E_CPU0_PE2_TX_C_DN<7>")
	)
	(segment
		(start 396.917164 -415.389568)
		(end 396.96771 -415.75482)
		(width 0.14732)
		(layer "In11.Cu")
		(net "P5E_CPU0_PE2_TX_C_DN<7>")
	)
	(segment
		(start 396.612872 -414.249616)
		(end 396.776448 -414.37306)
		(width 0.14732)
		(layer "In11.Cu")
		(net "P5E_CPU0_PE2_TX_C_DN<7>")
	)
	(segment
		(start 396.49781 -404.178516)
		(end 396.49781 -404.6474)
		(width 0.14732)
		(layer "In11.Cu")
		(net "P5E_CPU0_PE2_TX_C_DN<7>")
	)
	(segment
		(start 397.03502 -417.29914)
		(end 397.198596 -417.422584)
		(width 0.14732)
		(layer "In11.Cu")
		(net "P5E_CPU0_PE2_TX_C_DN<7>")
	)
	(segment
		(start 396.686024 -413.72155)
		(end 396.56258 -413.884872)
		(width 0.14732)
		(layer "In11.Cu")
		(net "P5E_CPU0_PE2_TX_C_DN<7>")
	)
	(segment
		(start 399.85569 -403.883876)
		(end 399.554192 -403.582378)
		(width 0.13208)
		(layer "F.Cu")
		(net "P5E_CPU0_PE2_TX_C_DN<6>")
	)
	(segment
		(start 399.554192 -402.96465)
		(end 399.88109 -402.637752)
		(width 0.13208)
		(layer "F.Cu")
		(net "P5E_CPU0_PE2_TX_C_DN<6>")
	)
	(segment
		(start 399.554192 -403.582378)
		(end 399.554192 -402.96465)
		(width 0.13208)
		(layer "F.Cu")
		(net "P5E_CPU0_PE2_TX_C_DN<6>")
	)
	(segment
		(start 400.066256 -424.748706)
		(end 400.066764 -424.749214)
		(width 0.14732)
		(layer "In11.Cu")
		(net "P5E_CPU0_PE2_TX_C_DN<6>")
	)
	(segment
		(start 399.531586 -414.058354)
		(end 399.554954 -414.426146)
		(width 0.14732)
		(layer "In11.Cu")
		(net "P5E_CPU0_PE2_TX_C_DN<6>")
	)
	(segment
		(start 399.37563 -406.531318)
		(end 399.37563 -410.223716)
		(width 0.14732)
		(layer "In11.Cu")
		(net "P5E_CPU0_PE2_TX_C_DN<6>")
	)
	(segment
		(start 399.85569 -403.883876)
		(end 399.56105 -404.178516)
		(width 0.14732)
		(layer "In11.Cu")
		(net "P5E_CPU0_PE2_TX_C_DN<6>")
	)
	(segment
		(start 400.066764 -424.749214)
		(end 400.066764 -427.395386)
		(width 0.14732)
		(layer "In11.Cu")
		(net "P5E_CPU0_PE2_TX_C_DN<6>")
	)
	(segment
		(start 399.620232 -415.450274)
		(end 399.48485 -415.603944)
		(width 0.14732)
		(layer "In11.Cu")
		(net "P5E_CPU0_PE2_TX_C_DN<6>")
	)
	(segment
		(start 400.066764 -427.395386)
		(end 400.190716 -427.519338)
		(width 0.14732)
		(layer "In11.Cu")
		(net "P5E_CPU0_PE2_TX_C_DN<6>")
	)
	(segment
		(start 399.56105 -404.178516)
		(end 399.56105 -404.6474)
		(width 0.14732)
		(layer "In11.Cu")
		(net "P5E_CPU0_PE2_TX_C_DN<6>")
	)
	(segment
		(start 399.317718 -412.90367)
		(end 399.312384 -412.899098)
		(width 0.14732)
		(layer "In11.Cu")
		(net "P5E_CPU0_PE2_TX_C_DN<6>")
	)
	(segment
		(start 399.284952 -412.467044)
		(end 399.317718 -412.90367)
		(width 0.14732)
		(layer "In11.Cu")
		(net "P5E_CPU0_PE2_TX_C_DN<6>")
	)
	(segment
		(start 399.312384 -412.899098)
		(end 399.466308 -413.034226)
		(width 0.14732)
		(layer "In11.Cu")
		(net "P5E_CPU0_PE2_TX_C_DN<6>")
	)
	(segment
		(start 399.554954 -414.426146)
		(end 399.419572 -414.579816)
		(width 0.14732)
		(layer "In11.Cu")
		(net "P5E_CPU0_PE2_TX_C_DN<6>")
	)
	(segment
		(start 399.466308 -413.034226)
		(end 399.489676 -413.402018)
		(width 0.14732)
		(layer "In11.Cu")
		(net "P5E_CPU0_PE2_TX_C_DN<6>")
	)
	(segment
		(start 399.354294 -413.555688)
		(end 399.377662 -413.923226)
		(width 0.14732)
		(layer "In11.Cu")
		(net "P5E_CPU0_PE2_TX_C_DN<6>")
	)
	(segment
		(start 400.190716 -427.519338)
		(end 400.602196 -427.519338)
		(width 0.14732)
		(layer "In11.Cu")
		(net "P5E_CPU0_PE2_TX_C_DN<6>")
	)
	(segment
		(start 399.419572 -414.579816)
		(end 399.44294 -414.947354)
		(width 0.14732)
		(layer "In11.Cu")
		(net "P5E_CPU0_PE2_TX_C_DN<6>")
	)
	(segment
		(start 399.596864 -415.082482)
		(end 399.620232 -415.450274)
		(width 0.14732)
		(layer "In11.Cu")
		(net "P5E_CPU0_PE2_TX_C_DN<6>")
	)
	(segment
		(start 399.377662 -413.923226)
		(end 399.531586 -414.058354)
		(width 0.14732)
		(layer "In11.Cu")
		(net "P5E_CPU0_PE2_TX_C_DN<6>")
	)
	(segment
		(start 399.48485 -415.603944)
		(end 400.066256 -424.748706)
		(width 0.14732)
		(layer "In11.Cu")
		(net "P5E_CPU0_PE2_TX_C_DN<6>")
	)
	(segment
		(start 400.602196 -427.519338)
		(end 400.750024 -427.37151)
		(width 0.14732)
		(layer "In11.Cu")
		(net "P5E_CPU0_PE2_TX_C_DN<6>")
	)
	(segment
		(start 399.44294 -414.947354)
		(end 399.596864 -415.082482)
		(width 0.14732)
		(layer "In11.Cu")
		(net "P5E_CPU0_PE2_TX_C_DN<6>")
	)
	(segment
		(start 399.56105 -404.6474)
		(end 399.37563 -406.531318)
		(width 0.14732)
		(layer "In11.Cu")
		(net "P5E_CPU0_PE2_TX_C_DN<6>")
	)
	(segment
		(start 399.489676 -413.402018)
		(end 399.354294 -413.555688)
		(width 0.14732)
		(layer "In11.Cu")
		(net "P5E_CPU0_PE2_TX_C_DN<6>")
	)
	(segment
		(start 399.37563 -410.223716)
		(end 399.284952 -412.467044)
		(width 0.14732)
		(layer "In11.Cu")
		(net "P5E_CPU0_PE2_TX_C_DN<6>")
	)
	(segment
		(start 400.750024 -427.37151)
		(end 400.750024 -427.089824)
		(width 0.14732)
		(layer "In11.Cu")
		(net "P5E_CPU0_PE2_TX_C_DN<6>")
	)
	(segment
		(start 402.617432 -403.582378)
		(end 402.617432 -402.96465)
		(width 0.13208)
		(layer "F.Cu")
		(net "P5E_CPU0_PE2_TX_C_DN<5>")
	)
	(segment
		(start 402.91893 -403.883876)
		(end 402.617432 -403.582378)
		(width 0.13208)
		(layer "F.Cu")
		(net "P5E_CPU0_PE2_TX_C_DN<5>")
	)
	(segment
		(start 402.617432 -402.96465)
		(end 402.94433 -402.637752)
		(width 0.13208)
		(layer "F.Cu")
		(net "P5E_CPU0_PE2_TX_C_DN<5>")
	)
	(segment
		(start 402.14931 -417.332922)
		(end 402.06676 -424.758612)
		(width 0.14732)
		(layer "In11.Cu")
		(net "P5E_CPU0_PE2_TX_C_DN<5>")
	)
	(segment
		(start 402.290026 -415.657792)
		(end 402.2852 -416.094926)
		(width 0.14732)
		(layer "In11.Cu")
		(net "P5E_CPU0_PE2_TX_C_DN<5>")
	)
	(segment
		(start 402.27758 -416.775392)
		(end 402.272754 -417.212526)
		(width 0.14732)
		(layer "In11.Cu")
		(net "P5E_CPU0_PE2_TX_C_DN<5>")
	)
	(segment
		(start 402.327364 -412.304738)
		(end 402.322538 -412.741872)
		(width 0.14732)
		(layer "In11.Cu")
		(net "P5E_CPU0_PE2_TX_C_DN<5>")
	)
	(segment
		(start 402.91893 -403.883876)
		(end 402.62429 -404.178516)
		(width 0.14732)
		(layer "In11.Cu")
		(net "P5E_CPU0_PE2_TX_C_DN<5>")
	)
	(segment
		(start 402.62429 -404.178516)
		(end 402.62429 -404.6474)
		(width 0.14732)
		(layer "In11.Cu")
		(net "P5E_CPU0_PE2_TX_C_DN<5>")
	)
	(segment
		(start 402.06676 -426.395388)
		(end 402.190712 -426.51934)
		(width 0.14732)
		(layer "In11.Cu")
		(net "P5E_CPU0_PE2_TX_C_DN<5>")
	)
	(segment
		(start 402.602192 -426.51934)
		(end 402.75002 -426.371512)
		(width 0.14732)
		(layer "In11.Cu")
		(net "P5E_CPU0_PE2_TX_C_DN<5>")
	)
	(segment
		(start 402.190712 -426.51934)
		(end 402.602192 -426.51934)
		(width 0.14732)
		(layer "In11.Cu")
		(net "P5E_CPU0_PE2_TX_C_DN<5>")
	)
	(segment
		(start 402.75002 -426.371512)
		(end 402.75002 -426.089826)
		(width 0.14732)
		(layer "In11.Cu")
		(net "P5E_CPU0_PE2_TX_C_DN<5>")
	)
	(segment
		(start 402.322538 -412.741872)
		(end 402.19884 -412.862268)
		(width 0.14732)
		(layer "In11.Cu")
		(net "P5E_CPU0_PE2_TX_C_DN<5>")
	)
	(segment
		(start 402.62429 -404.6474)
		(end 402.43887 -406.531318)
		(width 0.14732)
		(layer "In11.Cu")
		(net "P5E_CPU0_PE2_TX_C_DN<5>")
	)
	(segment
		(start 402.186648 -413.980122)
		(end 402.181822 -414.416748)
		(width 0.14732)
		(layer "In11.Cu")
		(net "P5E_CPU0_PE2_TX_C_DN<5>")
	)
	(segment
		(start 402.181822 -414.416748)
		(end 402.302472 -414.540192)
		(width 0.14732)
		(layer "In11.Cu")
		(net "P5E_CPU0_PE2_TX_C_DN<5>")
	)
	(segment
		(start 402.206714 -412.181294)
		(end 402.327364 -412.304738)
		(width 0.14732)
		(layer "In11.Cu")
		(net "P5E_CPU0_PE2_TX_C_DN<5>")
	)
	(segment
		(start 402.199348 -412.862522)
		(end 402.194522 -413.299148)
		(width 0.14732)
		(layer "In11.Cu")
		(net "P5E_CPU0_PE2_TX_C_DN<5>")
	)
	(segment
		(start 402.43887 -406.531318)
		(end 402.43887 -410.185108)
		(width 0.14732)
		(layer "In11.Cu")
		(net "P5E_CPU0_PE2_TX_C_DN<5>")
	)
	(segment
		(start 402.161756 -416.215322)
		(end 402.15693 -416.651948)
		(width 0.14732)
		(layer "In11.Cu")
		(net "P5E_CPU0_PE2_TX_C_DN<5>")
	)
	(segment
		(start 402.21154 -411.744668)
		(end 402.206714 -412.181294)
		(width 0.14732)
		(layer "In11.Cu")
		(net "P5E_CPU0_PE2_TX_C_DN<5>")
	)
	(segment
		(start 402.302472 -414.540192)
		(end 402.297646 -414.977326)
		(width 0.14732)
		(layer "In11.Cu")
		(net "P5E_CPU0_PE2_TX_C_DN<5>")
	)
	(segment
		(start 402.174202 -415.097722)
		(end 402.169376 -415.534348)
		(width 0.14732)
		(layer "In11.Cu")
		(net "P5E_CPU0_PE2_TX_C_DN<5>")
	)
	(segment
		(start 402.315172 -413.422592)
		(end 402.310346 -413.859726)
		(width 0.14732)
		(layer "In11.Cu")
		(net "P5E_CPU0_PE2_TX_C_DN<5>")
	)
	(segment
		(start 402.310346 -413.859726)
		(end 402.186648 -413.980122)
		(width 0.14732)
		(layer "In11.Cu")
		(net "P5E_CPU0_PE2_TX_C_DN<5>")
	)
	(segment
		(start 402.06676 -424.758612)
		(end 402.06676 -426.395388)
		(width 0.14732)
		(layer "In11.Cu")
		(net "P5E_CPU0_PE2_TX_C_DN<5>")
	)
	(segment
		(start 402.2852 -416.094926)
		(end 402.161756 -416.215322)
		(width 0.14732)
		(layer "In11.Cu")
		(net "P5E_CPU0_PE2_TX_C_DN<5>")
	)
	(segment
		(start 402.15693 -416.651948)
		(end 402.27758 -416.775392)
		(width 0.14732)
		(layer "In11.Cu")
		(net "P5E_CPU0_PE2_TX_C_DN<5>")
	)
	(segment
		(start 402.297646 -414.977326)
		(end 402.174202 -415.097722)
		(width 0.14732)
		(layer "In11.Cu")
		(net "P5E_CPU0_PE2_TX_C_DN<5>")
	)
	(segment
		(start 402.272754 -417.212526)
		(end 402.14931 -417.332922)
		(width 0.14732)
		(layer "In11.Cu")
		(net "P5E_CPU0_PE2_TX_C_DN<5>")
	)
	(segment
		(start 402.19884 -412.862268)
		(end 402.199348 -412.862522)
		(width 0.14732)
		(layer "In11.Cu")
		(net "P5E_CPU0_PE2_TX_C_DN<5>")
	)
	(segment
		(start 402.194522 -413.299148)
		(end 402.315172 -413.422592)
		(width 0.14732)
		(layer "In11.Cu")
		(net "P5E_CPU0_PE2_TX_C_DN<5>")
	)
	(segment
		(start 402.43887 -410.185108)
		(end 402.21154 -411.744668)
		(width 0.14732)
		(layer "In11.Cu")
		(net "P5E_CPU0_PE2_TX_C_DN<5>")
	)
	(segment
		(start 402.169376 -415.534348)
		(end 402.290026 -415.657792)
		(width 0.14732)
		(layer "In11.Cu")
		(net "P5E_CPU0_PE2_TX_C_DN<5>")
	)
	(segment
		(start 405.680672 -402.96465)
		(end 406.00757 -402.637752)
		(width 0.13208)
		(layer "F.Cu")
		(net "P5E_CPU0_PE2_TX_C_DN<4>")
	)
	(segment
		(start 405.98217 -403.883876)
		(end 405.680672 -403.582378)
		(width 0.13208)
		(layer "F.Cu")
		(net "P5E_CPU0_PE2_TX_C_DN<4>")
	)
	(segment
		(start 405.680672 -403.582378)
		(end 405.680672 -402.96465)
		(width 0.13208)
		(layer "F.Cu")
		(net "P5E_CPU0_PE2_TX_C_DN<4>")
	)
	(segment
		(start 405.68753 -404.178516)
		(end 405.68753 -404.6474)
		(width 0.14732)
		(layer "In11.Cu")
		(net "P5E_CPU0_PE2_TX_C_DN<4>")
	)
	(segment
		(start 405.092408 -412.82747)
		(end 405.224488 -412.984188)
		(width 0.14732)
		(layer "In11.Cu")
		(net "P5E_CPU0_PE2_TX_C_DN<4>")
	)
	(segment
		(start 405.280622 -412.328868)
		(end 405.123904 -412.460694)
		(width 0.14732)
		(layer "In11.Cu")
		(net "P5E_CPU0_PE2_TX_C_DN<4>")
	)
	(segment
		(start 405.03602 -413.483298)
		(end 405.004524 -413.850074)
		(width 0.14732)
		(layer "In11.Cu")
		(net "P5E_CPU0_PE2_TX_C_DN<4>")
	)
	(segment
		(start 405.50211 -406.531318)
		(end 405.50211 -410.205174)
		(width 0.14732)
		(layer "In11.Cu")
		(net "P5E_CPU0_PE2_TX_C_DN<4>")
	)
	(segment
		(start 405.22144 -411.324298)
		(end 405.180292 -411.80512)
		(width 0.14732)
		(layer "In11.Cu")
		(net "P5E_CPU0_PE2_TX_C_DN<4>")
	)
	(segment
		(start 404.947882 -414.509458)
		(end 404.066756 -424.769026)
		(width 0.14732)
		(layer "In11.Cu")
		(net "P5E_CPU0_PE2_TX_C_DN<4>")
	)
	(segment
		(start 405.50211 -410.205174)
		(end 405.22144 -411.324298)
		(width 0.14732)
		(layer "In11.Cu")
		(net "P5E_CPU0_PE2_TX_C_DN<4>")
	)
	(segment
		(start 404.750016 -427.37151)
		(end 404.750016 -427.089824)
		(width 0.14732)
		(layer "In11.Cu")
		(net "P5E_CPU0_PE2_TX_C_DN<4>")
	)
	(segment
		(start 405.68753 -404.6474)
		(end 405.50211 -406.531318)
		(width 0.14732)
		(layer "In11.Cu")
		(net "P5E_CPU0_PE2_TX_C_DN<4>")
	)
	(segment
		(start 404.066756 -424.769026)
		(end 404.066756 -427.395386)
		(width 0.14732)
		(layer "In11.Cu")
		(net "P5E_CPU0_PE2_TX_C_DN<4>")
	)
	(segment
		(start 404.602188 -427.519338)
		(end 404.750016 -427.37151)
		(width 0.14732)
		(layer "In11.Cu")
		(net "P5E_CPU0_PE2_TX_C_DN<4>")
	)
	(segment
		(start 404.948644 -414.505902)
		(end 404.94839 -414.507172)
		(width 0.14732)
		(layer "In11.Cu")
		(net "P5E_CPU0_PE2_TX_C_DN<4>")
	)
	(segment
		(start 405.004524 -413.850074)
		(end 405.136604 -414.006792)
		(width 0.14732)
		(layer "In11.Cu")
		(net "P5E_CPU0_PE2_TX_C_DN<4>")
	)
	(segment
		(start 405.180292 -411.80512)
		(end 405.312118 -411.961584)
		(width 0.14732)
		(layer "In11.Cu")
		(net "P5E_CPU0_PE2_TX_C_DN<4>")
	)
	(segment
		(start 405.123904 -412.460694)
		(end 405.092408 -412.82747)
		(width 0.14732)
		(layer "In11.Cu")
		(net "P5E_CPU0_PE2_TX_C_DN<4>")
	)
	(segment
		(start 404.190708 -427.519338)
		(end 404.602188 -427.519338)
		(width 0.14732)
		(layer "In11.Cu")
		(net "P5E_CPU0_PE2_TX_C_DN<4>")
	)
	(segment
		(start 405.136604 -414.006792)
		(end 405.104854 -414.374076)
		(width 0.14732)
		(layer "In11.Cu")
		(net "P5E_CPU0_PE2_TX_C_DN<4>")
	)
	(segment
		(start 405.192738 -413.351472)
		(end 405.03602 -413.483298)
		(width 0.14732)
		(layer "In11.Cu")
		(net "P5E_CPU0_PE2_TX_C_DN<4>")
	)
	(segment
		(start 405.312118 -411.961584)
		(end 405.280622 -412.328868)
		(width 0.14732)
		(layer "In11.Cu")
		(net "P5E_CPU0_PE2_TX_C_DN<4>")
	)
	(segment
		(start 404.066756 -427.395386)
		(end 404.190708 -427.519338)
		(width 0.14732)
		(layer "In11.Cu")
		(net "P5E_CPU0_PE2_TX_C_DN<4>")
	)
	(segment
		(start 404.94839 -414.507172)
		(end 404.947882 -414.509458)
		(width 0.14732)
		(layer "In11.Cu")
		(net "P5E_CPU0_PE2_TX_C_DN<4>")
	)
	(segment
		(start 404.948136 -414.505902)
		(end 404.948644 -414.505902)
		(width 0.14732)
		(layer "In11.Cu")
		(net "P5E_CPU0_PE2_TX_C_DN<4>")
	)
	(segment
		(start 405.104854 -414.374076)
		(end 404.948136 -414.505902)
		(width 0.14732)
		(layer "In11.Cu")
		(net "P5E_CPU0_PE2_TX_C_DN<4>")
	)
	(segment
		(start 405.224488 -412.984188)
		(end 405.192738 -413.351472)
		(width 0.14732)
		(layer "In11.Cu")
		(net "P5E_CPU0_PE2_TX_C_DN<4>")
	)
	(segment
		(start 405.98217 -403.883876)
		(end 405.68753 -404.178516)
		(width 0.14732)
		(layer "In11.Cu")
		(net "P5E_CPU0_PE2_TX_C_DN<4>")
	)
	(segment
		(start 408.743912 -402.96465)
		(end 409.07081 -402.637752)
		(width 0.13208)
		(layer "F.Cu")
		(net "P5E_CPU0_PE2_TX_C_DN<3>")
	)
	(segment
		(start 409.04541 -403.883876)
		(end 408.743912 -403.582378)
		(width 0.13208)
		(layer "F.Cu")
		(net "P5E_CPU0_PE2_TX_C_DN<3>")
	)
	(segment
		(start 408.743912 -403.582378)
		(end 408.743912 -402.96465)
		(width 0.13208)
		(layer "F.Cu")
		(net "P5E_CPU0_PE2_TX_C_DN<3>")
	)
	(segment
		(start 408.75077 -404.178516)
		(end 408.75077 -404.6474)
		(width 0.14732)
		(layer "In11.Cu")
		(net "P5E_CPU0_PE2_TX_C_DN<3>")
	)
	(segment
		(start 407.857198 -413.63392)
		(end 407.977086 -413.799782)
		(width 0.14732)
		(layer "In11.Cu")
		(net "P5E_CPU0_PE2_TX_C_DN<3>")
	)
	(segment
		(start 406.066752 -424.779186)
		(end 406.066752 -426.395388)
		(width 0.14732)
		(layer "In11.Cu")
		(net "P5E_CPU0_PE2_TX_C_DN<3>")
	)
	(segment
		(start 407.814272 -414.812988)
		(end 407.755852 -415.17697)
		(width 0.14732)
		(layer "In11.Cu")
		(net "P5E_CPU0_PE2_TX_C_DN<3>")
	)
	(segment
		(start 408.56535 -410.218636)
		(end 408.25547 -411.154626)
		(width 0.14732)
		(layer "In11.Cu")
		(net "P5E_CPU0_PE2_TX_C_DN<3>")
	)
	(segment
		(start 409.04541 -403.883876)
		(end 408.75077 -404.178516)
		(width 0.14732)
		(layer "In11.Cu")
		(net "P5E_CPU0_PE2_TX_C_DN<3>")
	)
	(segment
		(start 407.42743 -416.310064)
		(end 406.066752 -424.779186)
		(width 0.14732)
		(layer "In11.Cu")
		(net "P5E_CPU0_PE2_TX_C_DN<3>")
	)
	(segment
		(start 408.1399 -412.786576)
		(end 408.08148 -413.150558)
		(width 0.14732)
		(layer "In11.Cu")
		(net "P5E_CPU0_PE2_TX_C_DN<3>")
	)
	(segment
		(start 407.755852 -415.17697)
		(end 407.589736 -415.296858)
		(width 0.14732)
		(layer "In11.Cu")
		(net "P5E_CPU0_PE2_TX_C_DN<3>")
	)
	(segment
		(start 408.078178 -412.25724)
		(end 408.020012 -412.620714)
		(width 0.14732)
		(layer "In11.Cu")
		(net "P5E_CPU0_PE2_TX_C_DN<3>")
	)
	(segment
		(start 407.977086 -413.799782)
		(end 407.918666 -414.163764)
		(width 0.14732)
		(layer "In11.Cu")
		(net "P5E_CPU0_PE2_TX_C_DN<3>")
	)
	(segment
		(start 407.589736 -415.296858)
		(end 407.590244 -415.296858)
		(width 0.14732)
		(layer "In11.Cu")
		(net "P5E_CPU0_PE2_TX_C_DN<3>")
	)
	(segment
		(start 408.08148 -413.150558)
		(end 407.915364 -413.270446)
		(width 0.14732)
		(layer "In11.Cu")
		(net "P5E_CPU0_PE2_TX_C_DN<3>")
	)
	(segment
		(start 408.020012 -412.620714)
		(end 408.1399 -412.786576)
		(width 0.14732)
		(layer "In11.Cu")
		(net "P5E_CPU0_PE2_TX_C_DN<3>")
	)
	(segment
		(start 408.25547 -411.154626)
		(end 408.182826 -411.607508)
		(width 0.14732)
		(layer "In11.Cu")
		(net "P5E_CPU0_PE2_TX_C_DN<3>")
	)
	(segment
		(start 406.750012 -426.371512)
		(end 406.750012 -426.089826)
		(width 0.14732)
		(layer "In11.Cu")
		(net "P5E_CPU0_PE2_TX_C_DN<3>")
	)
	(segment
		(start 407.651966 -415.826194)
		(end 407.593546 -416.190176)
		(width 0.14732)
		(layer "In11.Cu")
		(net "P5E_CPU0_PE2_TX_C_DN<3>")
	)
	(segment
		(start 407.75255 -414.283652)
		(end 407.694384 -414.647126)
		(width 0.14732)
		(layer "In11.Cu")
		(net "P5E_CPU0_PE2_TX_C_DN<3>")
	)
	(segment
		(start 406.066752 -426.395388)
		(end 406.190704 -426.51934)
		(width 0.14732)
		(layer "In11.Cu")
		(net "P5E_CPU0_PE2_TX_C_DN<3>")
	)
	(segment
		(start 408.302968 -411.77337)
		(end 408.244548 -412.137352)
		(width 0.14732)
		(layer "In11.Cu")
		(net "P5E_CPU0_PE2_TX_C_DN<3>")
	)
	(segment
		(start 408.182826 -411.607508)
		(end 408.302968 -411.77337)
		(width 0.14732)
		(layer "In11.Cu")
		(net "P5E_CPU0_PE2_TX_C_DN<3>")
	)
	(segment
		(start 408.56535 -406.531318)
		(end 408.56535 -410.218636)
		(width 0.14732)
		(layer "In11.Cu")
		(net "P5E_CPU0_PE2_TX_C_DN<3>")
	)
	(segment
		(start 407.915364 -413.270446)
		(end 407.857198 -413.63392)
		(width 0.14732)
		(layer "In11.Cu")
		(net "P5E_CPU0_PE2_TX_C_DN<3>")
	)
	(segment
		(start 407.593546 -416.190176)
		(end 407.42743 -416.310064)
		(width 0.14732)
		(layer "In11.Cu")
		(net "P5E_CPU0_PE2_TX_C_DN<3>")
	)
	(segment
		(start 408.75077 -404.6474)
		(end 408.56535 -406.531318)
		(width 0.14732)
		(layer "In11.Cu")
		(net "P5E_CPU0_PE2_TX_C_DN<3>")
	)
	(segment
		(start 407.918666 -414.163764)
		(end 407.75255 -414.283652)
		(width 0.14732)
		(layer "In11.Cu")
		(net "P5E_CPU0_PE2_TX_C_DN<3>")
	)
	(segment
		(start 406.602184 -426.51934)
		(end 406.750012 -426.371512)
		(width 0.14732)
		(layer "In11.Cu")
		(net "P5E_CPU0_PE2_TX_C_DN<3>")
	)
	(segment
		(start 407.694384 -414.647126)
		(end 407.814272 -414.812988)
		(width 0.14732)
		(layer "In11.Cu")
		(net "P5E_CPU0_PE2_TX_C_DN<3>")
	)
	(segment
		(start 408.244548 -412.137352)
		(end 408.078178 -412.25724)
		(width 0.14732)
		(layer "In11.Cu")
		(net "P5E_CPU0_PE2_TX_C_DN<3>")
	)
	(segment
		(start 407.590244 -415.296858)
		(end 407.531824 -415.660332)
		(width 0.14732)
		(layer "In11.Cu")
		(net "P5E_CPU0_PE2_TX_C_DN<3>")
	)
	(segment
		(start 406.190704 -426.51934)
		(end 406.602184 -426.51934)
		(width 0.14732)
		(layer "In11.Cu")
		(net "P5E_CPU0_PE2_TX_C_DN<3>")
	)
	(segment
		(start 407.531824 -415.660332)
		(end 407.651966 -415.826194)
		(width 0.14732)
		(layer "In11.Cu")
		(net "P5E_CPU0_PE2_TX_C_DN<3>")
	)
	(segment
		(start 411.807152 -402.96465)
		(end 412.13405 -402.637752)
		(width 0.13208)
		(layer "F.Cu")
		(net "P5E_CPU0_PE2_TX_C_DN<2>")
	)
	(segment
		(start 411.807152 -403.582378)
		(end 411.807152 -402.96465)
		(width 0.13208)
		(layer "F.Cu")
		(net "P5E_CPU0_PE2_TX_C_DN<2>")
	)
	(segment
		(start 412.10865 -403.883876)
		(end 411.807152 -403.582378)
		(width 0.13208)
		(layer "F.Cu")
		(net "P5E_CPU0_PE2_TX_C_DN<2>")
	)
	(segment
		(start 408.066748 -427.395386)
		(end 408.1907 -427.519338)
		(width 0.14732)
		(layer "In11.Cu")
		(net "P5E_CPU0_PE2_TX_C_DN<2>")
	)
	(segment
		(start 410.962348 -413.022288)
		(end 410.815536 -413.112966)
		(width 0.14732)
		(layer "In11.Cu")
		(net "P5E_CPU0_PE2_TX_C_DN<2>")
	)
	(segment
		(start 408.067002 -424.789092)
		(end 408.066748 -424.789346)
		(width 0.14732)
		(layer "In11.Cu")
		(net "P5E_CPU0_PE2_TX_C_DN<2>")
	)
	(segment
		(start 411.137354 -411.746192)
		(end 410.971746 -412.45028)
		(width 0.14732)
		(layer "In11.Cu")
		(net "P5E_CPU0_PE2_TX_C_DN<2>")
	)
	(segment
		(start 408.750008 -427.40834)
		(end 408.750008 -427.089824)
		(width 0.14732)
		(layer "In11.Cu")
		(net "P5E_CPU0_PE2_TX_C_DN<2>")
	)
	(segment
		(start 408.067002 -424.789346)
		(end 408.067002 -424.789092)
		(width 0.14732)
		(layer "In11.Cu")
		(net "P5E_CPU0_PE2_TX_C_DN<2>")
	)
	(segment
		(start 410.459174 -414.626044)
		(end 410.550106 -414.772602)
		(width 0.14732)
		(layer "In11.Cu")
		(net "P5E_CPU0_PE2_TX_C_DN<2>")
	)
	(segment
		(start 410.706316 -414.11017)
		(end 410.55925 -414.200848)
		(width 0.14732)
		(layer "In11.Cu")
		(net "P5E_CPU0_PE2_TX_C_DN<2>")
	)
	(segment
		(start 411.62859 -406.531318)
		(end 411.62859 -410.323538)
		(width 0.14732)
		(layer "In11.Cu")
		(net "P5E_CPU0_PE2_TX_C_DN<2>")
	)
	(segment
		(start 410.550106 -414.772602)
		(end 410.45003 -415.198052)
		(width 0.14732)
		(layer "In11.Cu")
		(net "P5E_CPU0_PE2_TX_C_DN<2>")
	)
	(segment
		(start 411.62859 -410.323538)
		(end 411.137354 -411.746192)
		(width 0.14732)
		(layer "In11.Cu")
		(net "P5E_CPU0_PE2_TX_C_DN<2>")
	)
	(segment
		(start 408.066748 -424.789346)
		(end 408.066748 -427.395386)
		(width 0.14732)
		(layer "In11.Cu")
		(net "P5E_CPU0_PE2_TX_C_DN<2>")
	)
	(segment
		(start 408.1907 -427.519338)
		(end 408.63901 -427.519338)
		(width 0.14732)
		(layer "In11.Cu")
		(net "P5E_CPU0_PE2_TX_C_DN<2>")
	)
	(segment
		(start 410.45003 -415.198052)
		(end 410.302964 -415.28873)
		(width 0.14732)
		(layer "In11.Cu")
		(net "P5E_CPU0_PE2_TX_C_DN<2>")
	)
	(segment
		(start 410.971746 -412.45028)
		(end 411.062424 -412.596838)
		(width 0.14732)
		(layer "In11.Cu")
		(net "P5E_CPU0_PE2_TX_C_DN<2>")
	)
	(segment
		(start 408.63901 -427.519338)
		(end 408.750008 -427.40834)
		(width 0.14732)
		(layer "In11.Cu")
		(net "P5E_CPU0_PE2_TX_C_DN<2>")
	)
	(segment
		(start 411.81401 -404.6474)
		(end 411.62859 -406.531318)
		(width 0.14732)
		(layer "In11.Cu")
		(net "P5E_CPU0_PE2_TX_C_DN<2>")
	)
	(segment
		(start 410.71546 -413.538162)
		(end 410.806392 -413.68472)
		(width 0.14732)
		(layer "In11.Cu")
		(net "P5E_CPU0_PE2_TX_C_DN<2>")
	)
	(segment
		(start 410.55925 -414.200848)
		(end 410.459174 -414.626044)
		(width 0.14732)
		(layer "In11.Cu")
		(net "P5E_CPU0_PE2_TX_C_DN<2>")
	)
	(segment
		(start 411.062424 -412.596838)
		(end 410.962348 -413.022288)
		(width 0.14732)
		(layer "In11.Cu")
		(net "P5E_CPU0_PE2_TX_C_DN<2>")
	)
	(segment
		(start 410.303472 -415.28873)
		(end 408.067002 -424.789346)
		(width 0.14732)
		(layer "In11.Cu")
		(net "P5E_CPU0_PE2_TX_C_DN<2>")
	)
	(segment
		(start 412.10865 -403.883876)
		(end 411.81401 -404.178516)
		(width 0.14732)
		(layer "In11.Cu")
		(net "P5E_CPU0_PE2_TX_C_DN<2>")
	)
	(segment
		(start 411.81401 -404.178516)
		(end 411.81401 -404.6474)
		(width 0.14732)
		(layer "In11.Cu")
		(net "P5E_CPU0_PE2_TX_C_DN<2>")
	)
	(segment
		(start 410.806392 -413.68472)
		(end 410.706316 -414.11017)
		(width 0.14732)
		(layer "In11.Cu")
		(net "P5E_CPU0_PE2_TX_C_DN<2>")
	)
	(segment
		(start 410.302964 -415.28873)
		(end 410.303472 -415.28873)
		(width 0.14732)
		(layer "In11.Cu")
		(net "P5E_CPU0_PE2_TX_C_DN<2>")
	)
	(segment
		(start 410.815536 -413.112966)
		(end 410.71546 -413.538162)
		(width 0.14732)
		(layer "In11.Cu")
		(net "P5E_CPU0_PE2_TX_C_DN<2>")
	)
	(segment
		(start 415.17189 -403.883876)
		(end 414.870392 -403.582378)
		(width 0.13208)
		(layer "F.Cu")
		(net "P5E_CPU0_PE2_TX_C_DN<1>")
	)
	(segment
		(start 414.870392 -403.582378)
		(end 414.870392 -402.96465)
		(width 0.13208)
		(layer "F.Cu")
		(net "P5E_CPU0_PE2_TX_C_DN<1>")
	)
	(segment
		(start 414.870392 -402.96465)
		(end 415.19729 -402.637752)
		(width 0.13208)
		(layer "F.Cu")
		(net "P5E_CPU0_PE2_TX_C_DN<1>")
	)
	(segment
		(start 413.023558 -415.266124)
		(end 413.1056 -415.421826)
		(width 0.14732)
		(layer "In11.Cu")
		(net "P5E_CPU0_PE2_TX_C_DN<1>")
	)
	(segment
		(start 412.155132 -418.065966)
		(end 410.066744 -424.798744)
		(width 0.14732)
		(layer "In11.Cu")
		(net "P5E_CPU0_PE2_TX_C_DN<1>")
	)
	(segment
		(start 413.688784 -413.121602)
		(end 413.770826 -413.277304)
		(width 0.14732)
		(layer "In11.Cu")
		(net "P5E_CPU0_PE2_TX_C_DN<1>")
	)
	(segment
		(start 412.820358 -415.92119)
		(end 412.691326 -416.33775)
		(width 0.14732)
		(layer "In11.Cu")
		(net "P5E_CPU0_PE2_TX_C_DN<1>")
	)
	(segment
		(start 413.3088 -414.767014)
		(end 413.152844 -414.849056)
		(width 0.14732)
		(layer "In11.Cu")
		(net "P5E_CPU0_PE2_TX_C_DN<1>")
	)
	(segment
		(start 415.17189 -403.883876)
		(end 414.87725 -404.178516)
		(width 0.14732)
		(layer "In11.Cu")
		(net "P5E_CPU0_PE2_TX_C_DN<1>")
	)
	(segment
		(start 412.440374 -417.566602)
		(end 412.310834 -417.984178)
		(width 0.14732)
		(layer "In11.Cu")
		(net "P5E_CPU0_PE2_TX_C_DN<1>")
	)
	(segment
		(start 413.356552 -414.192974)
		(end 413.356298 -414.193736)
		(width 0.14732)
		(layer "In11.Cu")
		(net "P5E_CPU0_PE2_TX_C_DN<1>")
	)
	(segment
		(start 414.69183 -406.531318)
		(end 414.69183 -410.274008)
		(width 0.14732)
		(layer "In11.Cu")
		(net "P5E_CPU0_PE2_TX_C_DN<1>")
	)
	(segment
		(start 412.487618 -416.993832)
		(end 412.358332 -417.4109)
		(width 0.14732)
		(layer "In11.Cu")
		(net "P5E_CPU0_PE2_TX_C_DN<1>")
	)
	(segment
		(start 414.69183 -410.274008)
		(end 414.14065 -411.665166)
		(width 0.14732)
		(layer "In11.Cu")
		(net "P5E_CPU0_PE2_TX_C_DN<1>")
	)
	(segment
		(start 412.773114 -416.494214)
		(end 412.643574 -416.91179)
		(width 0.14732)
		(layer "In11.Cu")
		(net "P5E_CPU0_PE2_TX_C_DN<1>")
	)
	(segment
		(start 414.87725 -404.6474)
		(end 414.69183 -406.531318)
		(width 0.14732)
		(layer "In11.Cu")
		(net "P5E_CPU0_PE2_TX_C_DN<1>")
	)
	(segment
		(start 413.152844 -414.849056)
		(end 413.023558 -415.266124)
		(width 0.14732)
		(layer "In11.Cu")
		(net "P5E_CPU0_PE2_TX_C_DN<1>")
	)
	(segment
		(start 412.691072 -416.338512)
		(end 412.773114 -416.494214)
		(width 0.14732)
		(layer "In11.Cu")
		(net "P5E_CPU0_PE2_TX_C_DN<1>")
	)
	(segment
		(start 413.356298 -414.193736)
		(end 413.43834 -414.349438)
		(width 0.14732)
		(layer "In11.Cu")
		(net "P5E_CPU0_PE2_TX_C_DN<1>")
	)
	(segment
		(start 414.87725 -404.178516)
		(end 414.87725 -404.6474)
		(width 0.14732)
		(layer "In11.Cu")
		(net "P5E_CPU0_PE2_TX_C_DN<1>")
	)
	(segment
		(start 410.750004 -426.371512)
		(end 410.750004 -426.089826)
		(width 0.14732)
		(layer "In11.Cu")
		(net "P5E_CPU0_PE2_TX_C_DN<1>")
	)
	(segment
		(start 413.485584 -413.776414)
		(end 413.356552 -414.192974)
		(width 0.14732)
		(layer "In11.Cu")
		(net "P5E_CPU0_PE2_TX_C_DN<1>")
	)
	(segment
		(start 410.066744 -426.395388)
		(end 410.190696 -426.51934)
		(width 0.14732)
		(layer "In11.Cu")
		(net "P5E_CPU0_PE2_TX_C_DN<1>")
	)
	(segment
		(start 414.140142 -411.666182)
		(end 413.688784 -413.121602)
		(width 0.14732)
		(layer "In11.Cu")
		(net "P5E_CPU0_PE2_TX_C_DN<1>")
	)
	(segment
		(start 412.691326 -416.33775)
		(end 412.691072 -416.338512)
		(width 0.14732)
		(layer "In11.Cu")
		(net "P5E_CPU0_PE2_TX_C_DN<1>")
	)
	(segment
		(start 414.140396 -411.665928)
		(end 414.140142 -411.666182)
		(width 0.14732)
		(layer "In11.Cu")
		(net "P5E_CPU0_PE2_TX_C_DN<1>")
	)
	(segment
		(start 412.310834 -417.984178)
		(end 412.155132 -418.065966)
		(width 0.14732)
		(layer "In11.Cu")
		(net "P5E_CPU0_PE2_TX_C_DN<1>")
	)
	(segment
		(start 413.641286 -413.694626)
		(end 413.485584 -413.776414)
		(width 0.14732)
		(layer "In11.Cu")
		(net "P5E_CPU0_PE2_TX_C_DN<1>")
	)
	(segment
		(start 410.066744 -424.798744)
		(end 410.066744 -426.395388)
		(width 0.14732)
		(layer "In11.Cu")
		(net "P5E_CPU0_PE2_TX_C_DN<1>")
	)
	(segment
		(start 412.643574 -416.91179)
		(end 412.487618 -416.993832)
		(width 0.14732)
		(layer "In11.Cu")
		(net "P5E_CPU0_PE2_TX_C_DN<1>")
	)
	(segment
		(start 413.770826 -413.277304)
		(end 413.641286 -413.694626)
		(width 0.14732)
		(layer "In11.Cu")
		(net "P5E_CPU0_PE2_TX_C_DN<1>")
	)
	(segment
		(start 410.602176 -426.51934)
		(end 410.750004 -426.371512)
		(width 0.14732)
		(layer "In11.Cu")
		(net "P5E_CPU0_PE2_TX_C_DN<1>")
	)
	(segment
		(start 413.1056 -415.421826)
		(end 412.97606 -415.839402)
		(width 0.14732)
		(layer "In11.Cu")
		(net "P5E_CPU0_PE2_TX_C_DN<1>")
	)
	(segment
		(start 413.43834 -414.349438)
		(end 413.3088 -414.767014)
		(width 0.14732)
		(layer "In11.Cu")
		(net "P5E_CPU0_PE2_TX_C_DN<1>")
	)
	(segment
		(start 412.97606 -415.839402)
		(end 412.820358 -415.92119)
		(width 0.14732)
		(layer "In11.Cu")
		(net "P5E_CPU0_PE2_TX_C_DN<1>")
	)
	(segment
		(start 412.358332 -417.4109)
		(end 412.440374 -417.566602)
		(width 0.14732)
		(layer "In11.Cu")
		(net "P5E_CPU0_PE2_TX_C_DN<1>")
	)
	(segment
		(start 410.190696 -426.51934)
		(end 410.602176 -426.51934)
		(width 0.14732)
		(layer "In11.Cu")
		(net "P5E_CPU0_PE2_TX_C_DN<1>")
	)
	(segment
		(start 414.14065 -411.665166)
		(end 414.140396 -411.665928)
		(width 0.14732)
		(layer "In11.Cu")
		(net "P5E_CPU0_PE2_TX_C_DN<1>")
	)
	(segment
		(start 371.400832 -402.637752)
		(end 371.39753 -402.637752)
		(width 0.13208)
		(layer "F.Cu")
		(net "P5E_CPU0_PE2_TX_C_DN<15>")
	)
	(segment
		(start 371.725952 -403.580854)
		(end 371.725952 -402.962872)
		(width 0.13208)
		(layer "F.Cu")
		(net "P5E_CPU0_PE2_TX_C_DN<15>")
	)
	(segment
		(start 371.42293 -403.883876)
		(end 371.725952 -403.580854)
		(width 0.13208)
		(layer "F.Cu")
		(net "P5E_CPU0_PE2_TX_C_DN<15>")
	)
	(segment
		(start 371.725952 -402.962872)
		(end 371.400832 -402.637752)
		(width 0.13208)
		(layer "F.Cu")
		(net "P5E_CPU0_PE2_TX_C_DN<15>")
	)
	(segment
		(start 371.71757 -404.178516)
		(end 371.42293 -403.883876)
		(width 0.14732)
		(layer "In11.Cu")
		(net "P5E_CPU0_PE2_TX_C_DN<15>")
	)
	(segment
		(start 381.750062 -427.289976)
		(end 381.750062 -426.980604)
		(width 0.14732)
		(layer "In11.Cu")
		(net "P5E_CPU0_PE2_TX_C_DN<15>")
	)
	(segment
		(start 371.53215 -410.9212)
		(end 371.53215 -406.517602)
		(width 0.14732)
		(layer "In11.Cu")
		(net "P5E_CPU0_PE2_TX_C_DN<15>")
	)
	(segment
		(start 381.563118 -426.79366)
		(end 381.076962 -426.79366)
		(width 0.14732)
		(layer "In11.Cu")
		(net "P5E_CPU0_PE2_TX_C_DN<15>")
	)
	(segment
		(start 380.788672 -426.505624)
		(end 371.53215 -410.9212)
		(width 0.14732)
		(layer "In11.Cu")
		(net "P5E_CPU0_PE2_TX_C_DN<15>")
	)
	(segment
		(start 371.71757 -404.633684)
		(end 371.71757 -404.178516)
		(width 0.14732)
		(layer "In11.Cu")
		(net "P5E_CPU0_PE2_TX_C_DN<15>")
	)
	(segment
		(start 381.750062 -426.980604)
		(end 381.563118 -426.79366)
		(width 0.14732)
		(layer "In11.Cu")
		(net "P5E_CPU0_PE2_TX_C_DN<15>")
	)
	(segment
		(start 371.53215 -406.517602)
		(end 371.71757 -404.633684)
		(width 0.14732)
		(layer "In11.Cu")
		(net "P5E_CPU0_PE2_TX_C_DN<15>")
	)
	(segment
		(start 381.076962 -426.79366)
		(end 380.788672 -426.505624)
		(width 0.14732)
		(layer "In11.Cu")
		(net "P5E_CPU0_PE2_TX_C_DN<15>")
	)
	(segment
		(start 375.048272 -402.96465)
		(end 375.37517 -402.637752)
		(width 0.13208)
		(layer "F.Cu")
		(net "P5E_CPU0_PE2_TX_C_DN<14>")
	)
	(segment
		(start 375.048272 -403.582378)
		(end 375.048272 -402.96465)
		(width 0.13208)
		(layer "F.Cu")
		(net "P5E_CPU0_PE2_TX_C_DN<14>")
	)
	(segment
		(start 375.34977 -403.883876)
		(end 375.048272 -403.582378)
		(width 0.13208)
		(layer "F.Cu")
		(net "P5E_CPU0_PE2_TX_C_DN<14>")
	)
	(segment
		(start 375.34977 -403.883876)
		(end 375.05513 -404.178516)
		(width 0.14732)
		(layer "In11.Cu")
		(net "P5E_CPU0_PE2_TX_C_DN<14>")
	)
	(segment
		(start 383.19075 -427.519338)
		(end 383.60223 -427.519338)
		(width 0.14732)
		(layer "In11.Cu")
		(net "P5E_CPU0_PE2_TX_C_DN<14>")
	)
	(segment
		(start 375.05513 -404.6474)
		(end 374.86971 -406.531318)
		(width 0.14732)
		(layer "In11.Cu")
		(net "P5E_CPU0_PE2_TX_C_DN<14>")
	)
	(segment
		(start 376.508264 -413.419544)
		(end 376.695208 -413.737044)
		(width 0.14732)
		(layer "In11.Cu")
		(net "P5E_CPU0_PE2_TX_C_DN<14>")
	)
	(segment
		(start 376.309636 -413.368236)
		(end 376.508264 -413.419544)
		(width 0.14732)
		(layer "In11.Cu")
		(net "P5E_CPU0_PE2_TX_C_DN<14>")
	)
	(segment
		(start 374.86971 -406.531318)
		(end 374.86971 -410.927042)
		(width 0.14732)
		(layer "In11.Cu")
		(net "P5E_CPU0_PE2_TX_C_DN<14>")
	)
	(segment
		(start 377.029726 -414.303464)
		(end 377.21667 -414.620964)
		(width 0.14732)
		(layer "In11.Cu")
		(net "P5E_CPU0_PE2_TX_C_DN<14>")
	)
	(segment
		(start 375.788428 -412.484316)
		(end 375.986802 -412.535624)
		(width 0.14732)
		(layer "In11.Cu")
		(net "P5E_CPU0_PE2_TX_C_DN<14>")
	)
	(segment
		(start 376.122692 -413.051244)
		(end 376.309636 -413.368236)
		(width 0.14732)
		(layer "In11.Cu")
		(net "P5E_CPU0_PE2_TX_C_DN<14>")
	)
	(segment
		(start 376.173746 -412.853124)
		(end 376.122692 -413.051244)
		(width 0.14732)
		(layer "In11.Cu")
		(net "P5E_CPU0_PE2_TX_C_DN<14>")
	)
	(segment
		(start 375.05513 -404.178516)
		(end 375.05513 -404.6474)
		(width 0.14732)
		(layer "In11.Cu")
		(net "P5E_CPU0_PE2_TX_C_DN<14>")
	)
	(segment
		(start 375.986802 -412.535624)
		(end 376.173746 -412.853124)
		(width 0.14732)
		(layer "In11.Cu")
		(net "P5E_CPU0_PE2_TX_C_DN<14>")
	)
	(segment
		(start 383.60223 -427.519338)
		(end 383.750058 -427.37151)
		(width 0.14732)
		(layer "In11.Cu")
		(net "P5E_CPU0_PE2_TX_C_DN<14>")
	)
	(segment
		(start 383.066798 -427.395386)
		(end 383.19075 -427.519338)
		(width 0.14732)
		(layer "In11.Cu")
		(net "P5E_CPU0_PE2_TX_C_DN<14>")
	)
	(segment
		(start 376.644154 -413.935164)
		(end 376.831098 -414.252156)
		(width 0.14732)
		(layer "In11.Cu")
		(net "P5E_CPU0_PE2_TX_C_DN<14>")
	)
	(segment
		(start 376.831098 -414.252156)
		(end 377.029726 -414.303464)
		(width 0.14732)
		(layer "In11.Cu")
		(net "P5E_CPU0_PE2_TX_C_DN<14>")
	)
	(segment
		(start 383.066798 -424.824398)
		(end 383.066798 -427.395386)
		(width 0.14732)
		(layer "In11.Cu")
		(net "P5E_CPU0_PE2_TX_C_DN<14>")
	)
	(segment
		(start 377.21667 -414.620964)
		(end 377.165616 -414.819084)
		(width 0.14732)
		(layer "In11.Cu")
		(net "P5E_CPU0_PE2_TX_C_DN<14>")
	)
	(segment
		(start 377.165616 -414.819084)
		(end 383.066798 -424.824398)
		(width 0.14732)
		(layer "In11.Cu")
		(net "P5E_CPU0_PE2_TX_C_DN<14>")
	)
	(segment
		(start 374.86971 -410.927042)
		(end 375.788428 -412.484316)
		(width 0.14732)
		(layer "In11.Cu")
		(net "P5E_CPU0_PE2_TX_C_DN<14>")
	)
	(segment
		(start 376.695208 -413.737044)
		(end 376.644154 -413.935164)
		(width 0.14732)
		(layer "In11.Cu")
		(net "P5E_CPU0_PE2_TX_C_DN<14>")
	)
	(segment
		(start 383.750058 -427.37151)
		(end 383.750058 -427.089824)
		(width 0.14732)
		(layer "In11.Cu")
		(net "P5E_CPU0_PE2_TX_C_DN<14>")
	)
	(segment
		(start 378.41301 -403.883876)
		(end 378.111512 -403.582378)
		(width 0.13208)
		(layer "F.Cu")
		(net "P5E_CPU0_PE2_TX_C_DN<13>")
	)
	(segment
		(start 378.111512 -402.96465)
		(end 378.43841 -402.637752)
		(width 0.13208)
		(layer "F.Cu")
		(net "P5E_CPU0_PE2_TX_C_DN<13>")
	)
	(segment
		(start 378.111512 -403.582378)
		(end 378.111512 -402.96465)
		(width 0.13208)
		(layer "F.Cu")
		(net "P5E_CPU0_PE2_TX_C_DN<13>")
	)
	(segment
		(start 380.377954 -415.33699)
		(end 380.54661 -415.66465)
		(width 0.14732)
		(layer "In11.Cu")
		(net "P5E_CPU0_PE2_TX_C_DN<13>")
	)
	(segment
		(start 385.750054 -426.371512)
		(end 385.750054 -426.089826)
		(width 0.14732)
		(layer "In11.Cu")
		(net "P5E_CPU0_PE2_TX_C_DN<13>")
	)
	(segment
		(start 378.41301 -403.883876)
		(end 378.11837 -404.178516)
		(width 0.14732)
		(layer "In11.Cu")
		(net "P5E_CPU0_PE2_TX_C_DN<13>")
	)
	(segment
		(start 379.074426 -413.123126)
		(end 379.242828 -413.450532)
		(width 0.14732)
		(layer "In11.Cu")
		(net "P5E_CPU0_PE2_TX_C_DN<13>")
	)
	(segment
		(start 379.712728 -414.362646)
		(end 379.908054 -414.424876)
		(width 0.14732)
		(layer "In11.Cu")
		(net "P5E_CPU0_PE2_TX_C_DN<13>")
	)
	(segment
		(start 377.93295 -410.906976)
		(end 378.773182 -412.53791)
		(width 0.14732)
		(layer "In11.Cu")
		(net "P5E_CPU0_PE2_TX_C_DN<13>")
	)
	(segment
		(start 379.544326 -414.03524)
		(end 379.712728 -414.362646)
		(width 0.14732)
		(layer "In11.Cu")
		(net "P5E_CPU0_PE2_TX_C_DN<13>")
	)
	(segment
		(start 385.602226 -426.51934)
		(end 385.750054 -426.371512)
		(width 0.14732)
		(layer "In11.Cu")
		(net "P5E_CPU0_PE2_TX_C_DN<13>")
	)
	(segment
		(start 380.54661 -415.66465)
		(end 380.484126 -415.859722)
		(width 0.14732)
		(layer "In11.Cu")
		(net "P5E_CPU0_PE2_TX_C_DN<13>")
	)
	(segment
		(start 385.190746 -426.51934)
		(end 385.602226 -426.51934)
		(width 0.14732)
		(layer "In11.Cu")
		(net "P5E_CPU0_PE2_TX_C_DN<13>")
	)
	(segment
		(start 385.066794 -426.395388)
		(end 385.190746 -426.51934)
		(width 0.14732)
		(layer "In11.Cu")
		(net "P5E_CPU0_PE2_TX_C_DN<13>")
	)
	(segment
		(start 380.014226 -414.947354)
		(end 380.182628 -415.27476)
		(width 0.14732)
		(layer "In11.Cu")
		(net "P5E_CPU0_PE2_TX_C_DN<13>")
	)
	(segment
		(start 378.11837 -404.178516)
		(end 378.11837 -404.6474)
		(width 0.14732)
		(layer "In11.Cu")
		(net "P5E_CPU0_PE2_TX_C_DN<13>")
	)
	(segment
		(start 378.773182 -412.53791)
		(end 378.968254 -412.600394)
		(width 0.14732)
		(layer "In11.Cu")
		(net "P5E_CPU0_PE2_TX_C_DN<13>")
	)
	(segment
		(start 385.066794 -424.757088)
		(end 385.066794 -426.395388)
		(width 0.14732)
		(layer "In11.Cu")
		(net "P5E_CPU0_PE2_TX_C_DN<13>")
	)
	(segment
		(start 379.13691 -412.928054)
		(end 379.074426 -413.123126)
		(width 0.14732)
		(layer "In11.Cu")
		(net "P5E_CPU0_PE2_TX_C_DN<13>")
	)
	(segment
		(start 377.93295 -406.531318)
		(end 377.93295 -410.906976)
		(width 0.14732)
		(layer "In11.Cu")
		(net "P5E_CPU0_PE2_TX_C_DN<13>")
	)
	(segment
		(start 380.07671 -414.752536)
		(end 380.014226 -414.947354)
		(width 0.14732)
		(layer "In11.Cu")
		(net "P5E_CPU0_PE2_TX_C_DN<13>")
	)
	(segment
		(start 379.908054 -414.424876)
		(end 380.07671 -414.752536)
		(width 0.14732)
		(layer "In11.Cu")
		(net "P5E_CPU0_PE2_TX_C_DN<13>")
	)
	(segment
		(start 379.242828 -413.450532)
		(end 379.438154 -413.512762)
		(width 0.14732)
		(layer "In11.Cu")
		(net "P5E_CPU0_PE2_TX_C_DN<13>")
	)
	(segment
		(start 380.182628 -415.27476)
		(end 380.377954 -415.33699)
		(width 0.14732)
		(layer "In11.Cu")
		(net "P5E_CPU0_PE2_TX_C_DN<13>")
	)
	(segment
		(start 378.968254 -412.600394)
		(end 379.13691 -412.928054)
		(width 0.14732)
		(layer "In11.Cu")
		(net "P5E_CPU0_PE2_TX_C_DN<13>")
	)
	(segment
		(start 379.438154 -413.512762)
		(end 379.60681 -413.840422)
		(width 0.14732)
		(layer "In11.Cu")
		(net "P5E_CPU0_PE2_TX_C_DN<13>")
	)
	(segment
		(start 379.60681 -413.840422)
		(end 379.544326 -414.03524)
		(width 0.14732)
		(layer "In11.Cu")
		(net "P5E_CPU0_PE2_TX_C_DN<13>")
	)
	(segment
		(start 380.484126 -415.859722)
		(end 385.066794 -424.757088)
		(width 0.14732)
		(layer "In11.Cu")
		(net "P5E_CPU0_PE2_TX_C_DN<13>")
	)
	(segment
		(start 378.11837 -404.6474)
		(end 377.93295 -406.531318)
		(width 0.14732)
		(layer "In11.Cu")
		(net "P5E_CPU0_PE2_TX_C_DN<13>")
	)
	(segment
		(start 381.174752 -402.96465)
		(end 381.50165 -402.637752)
		(width 0.13208)
		(layer "F.Cu")
		(net "P5E_CPU0_PE2_TX_C_DN<12>")
	)
	(segment
		(start 381.174752 -403.582378)
		(end 381.174752 -402.96465)
		(width 0.13208)
		(layer "F.Cu")
		(net "P5E_CPU0_PE2_TX_C_DN<12>")
	)
	(segment
		(start 381.47625 -403.883876)
		(end 381.174752 -403.582378)
		(width 0.13208)
		(layer "F.Cu")
		(net "P5E_CPU0_PE2_TX_C_DN<12>")
	)
	(segment
		(start 382.964182 -415.439606)
		(end 383.15519 -415.513774)
		(width 0.14732)
		(layer "In11.Cu")
		(net "P5E_CPU0_PE2_TX_C_DN<12>")
	)
	(segment
		(start 382.815846 -415.102548)
		(end 382.964182 -415.439606)
		(width 0.14732)
		(layer "In11.Cu")
		(net "P5E_CPU0_PE2_TX_C_DN<12>")
	)
	(segment
		(start 387.602222 -427.519338)
		(end 387.75005 -427.37151)
		(width 0.14732)
		(layer "In11.Cu")
		(net "P5E_CPU0_PE2_TX_C_DN<12>")
	)
	(segment
		(start 381.9144 -412.695898)
		(end 382.062736 -413.03321)
		(width 0.14732)
		(layer "In11.Cu")
		(net "P5E_CPU0_PE2_TX_C_DN<12>")
	)
	(segment
		(start 383.303526 -415.851086)
		(end 383.229612 -416.04184)
		(width 0.14732)
		(layer "In11.Cu")
		(net "P5E_CPU0_PE2_TX_C_DN<12>")
	)
	(segment
		(start 383.15519 -415.513774)
		(end 383.303526 -415.851086)
		(width 0.14732)
		(layer "In11.Cu")
		(net "P5E_CPU0_PE2_TX_C_DN<12>")
	)
	(segment
		(start 380.99619 -410.970222)
		(end 381.723392 -412.62173)
		(width 0.14732)
		(layer "In11.Cu")
		(net "P5E_CPU0_PE2_TX_C_DN<12>")
	)
	(segment
		(start 387.06679 -427.395386)
		(end 387.190742 -427.519338)
		(width 0.14732)
		(layer "In11.Cu")
		(net "P5E_CPU0_PE2_TX_C_DN<12>")
	)
	(segment
		(start 381.18161 -404.178516)
		(end 381.18161 -404.6474)
		(width 0.14732)
		(layer "In11.Cu")
		(net "P5E_CPU0_PE2_TX_C_DN<12>")
	)
	(segment
		(start 380.99619 -406.531318)
		(end 380.99619 -410.970222)
		(width 0.14732)
		(layer "In11.Cu")
		(net "P5E_CPU0_PE2_TX_C_DN<12>")
	)
	(segment
		(start 382.476502 -413.972502)
		(end 382.402334 -414.163256)
		(width 0.14732)
		(layer "In11.Cu")
		(net "P5E_CPU0_PE2_TX_C_DN<12>")
	)
	(segment
		(start 381.723392 -412.62173)
		(end 381.9144 -412.695898)
		(width 0.14732)
		(layer "In11.Cu")
		(net "P5E_CPU0_PE2_TX_C_DN<12>")
	)
	(segment
		(start 381.47625 -403.883876)
		(end 381.18161 -404.178516)
		(width 0.14732)
		(layer "In11.Cu")
		(net "P5E_CPU0_PE2_TX_C_DN<12>")
	)
	(segment
		(start 382.890014 -414.911794)
		(end 382.815846 -415.102548)
		(width 0.14732)
		(layer "In11.Cu")
		(net "P5E_CPU0_PE2_TX_C_DN<12>")
	)
	(segment
		(start 387.06679 -424.757088)
		(end 387.06679 -427.395386)
		(width 0.14732)
		(layer "In11.Cu")
		(net "P5E_CPU0_PE2_TX_C_DN<12>")
	)
	(segment
		(start 382.137158 -413.561022)
		(end 382.328166 -413.63519)
		(width 0.14732)
		(layer "In11.Cu")
		(net "P5E_CPU0_PE2_TX_C_DN<12>")
	)
	(segment
		(start 382.328166 -413.63519)
		(end 382.476502 -413.972502)
		(width 0.14732)
		(layer "In11.Cu")
		(net "P5E_CPU0_PE2_TX_C_DN<12>")
	)
	(segment
		(start 381.18161 -404.6474)
		(end 380.99619 -406.531318)
		(width 0.14732)
		(layer "In11.Cu")
		(net "P5E_CPU0_PE2_TX_C_DN<12>")
	)
	(segment
		(start 382.741678 -414.574482)
		(end 382.890014 -414.911794)
		(width 0.14732)
		(layer "In11.Cu")
		(net "P5E_CPU0_PE2_TX_C_DN<12>")
	)
	(segment
		(start 382.55067 -414.500314)
		(end 382.741678 -414.574482)
		(width 0.14732)
		(layer "In11.Cu")
		(net "P5E_CPU0_PE2_TX_C_DN<12>")
	)
	(segment
		(start 382.062736 -413.03321)
		(end 381.988822 -413.223964)
		(width 0.14732)
		(layer "In11.Cu")
		(net "P5E_CPU0_PE2_TX_C_DN<12>")
	)
	(segment
		(start 383.229612 -416.04184)
		(end 387.06679 -424.757088)
		(width 0.14732)
		(layer "In11.Cu")
		(net "P5E_CPU0_PE2_TX_C_DN<12>")
	)
	(segment
		(start 387.190742 -427.519338)
		(end 387.602222 -427.519338)
		(width 0.14732)
		(layer "In11.Cu")
		(net "P5E_CPU0_PE2_TX_C_DN<12>")
	)
	(segment
		(start 381.988822 -413.223964)
		(end 382.137158 -413.561022)
		(width 0.14732)
		(layer "In11.Cu")
		(net "P5E_CPU0_PE2_TX_C_DN<12>")
	)
	(segment
		(start 382.402334 -414.163256)
		(end 382.55067 -414.500314)
		(width 0.14732)
		(layer "In11.Cu")
		(net "P5E_CPU0_PE2_TX_C_DN<12>")
	)
	(segment
		(start 387.75005 -427.37151)
		(end 387.75005 -427.089824)
		(width 0.14732)
		(layer "In11.Cu")
		(net "P5E_CPU0_PE2_TX_C_DN<12>")
	)
	(segment
		(start 384.237992 -402.96465)
		(end 384.56489 -402.637752)
		(width 0.13208)
		(layer "F.Cu")
		(net "P5E_CPU0_PE2_TX_C_DN<11>")
	)
	(segment
		(start 384.237992 -403.582378)
		(end 384.237992 -402.96465)
		(width 0.13208)
		(layer "F.Cu")
		(net "P5E_CPU0_PE2_TX_C_DN<11>")
	)
	(segment
		(start 384.53949 -403.883876)
		(end 384.237992 -403.582378)
		(width 0.13208)
		(layer "F.Cu")
		(net "P5E_CPU0_PE2_TX_C_DN<11>")
	)
	(segment
		(start 384.53949 -403.883876)
		(end 384.24485 -404.178516)
		(width 0.14732)
		(layer "In11.Cu")
		(net "P5E_CPU0_PE2_TX_C_DN<11>")
	)
	(segment
		(start 385.958842 -416.254438)
		(end 386.14477 -416.340798)
		(width 0.14732)
		(layer "In11.Cu")
		(net "P5E_CPU0_PE2_TX_C_DN<11>")
	)
	(segment
		(start 385.087622 -413.449008)
		(end 385.214114 -413.79521)
		(width 0.14732)
		(layer "In11.Cu")
		(net "P5E_CPU0_PE2_TX_C_DN<11>")
	)
	(segment
		(start 385.792218 -415.376868)
		(end 385.91871 -415.72307)
		(width 0.14732)
		(layer "In11.Cu")
		(net "P5E_CPU0_PE2_TX_C_DN<11>")
	)
	(segment
		(start 384.73507 -412.485078)
		(end 384.861562 -412.83128)
		(width 0.14732)
		(layer "In11.Cu")
		(net "P5E_CPU0_PE2_TX_C_DN<11>")
	)
	(segment
		(start 384.775456 -413.016954)
		(end 384.901694 -413.362648)
		(width 0.14732)
		(layer "In11.Cu")
		(net "P5E_CPU0_PE2_TX_C_DN<11>")
	)
	(segment
		(start 386.14477 -416.340798)
		(end 386.271262 -416.687)
		(width 0.14732)
		(layer "In11.Cu")
		(net "P5E_CPU0_PE2_TX_C_DN<11>")
	)
	(segment
		(start 389.066786 -426.395388)
		(end 389.190738 -426.51934)
		(width 0.14732)
		(layer "In11.Cu")
		(net "P5E_CPU0_PE2_TX_C_DN<11>")
	)
	(segment
		(start 389.066786 -424.757088)
		(end 389.066786 -426.395388)
		(width 0.14732)
		(layer "In11.Cu")
		(net "P5E_CPU0_PE2_TX_C_DN<11>")
	)
	(segment
		(start 389.598154 -426.51934)
		(end 389.750046 -426.367448)
		(width 0.14732)
		(layer "In11.Cu")
		(net "P5E_CPU0_PE2_TX_C_DN<11>")
	)
	(segment
		(start 385.127754 -413.980884)
		(end 385.253992 -414.326578)
		(width 0.14732)
		(layer "In11.Cu")
		(net "P5E_CPU0_PE2_TX_C_DN<11>")
	)
	(segment
		(start 384.24485 -404.6474)
		(end 384.05943 -406.531318)
		(width 0.14732)
		(layer "In11.Cu")
		(net "P5E_CPU0_PE2_TX_C_DN<11>")
	)
	(segment
		(start 384.05943 -406.531318)
		(end 384.05943 -411.059376)
		(width 0.14732)
		(layer "In11.Cu")
		(net "P5E_CPU0_PE2_TX_C_DN<11>")
	)
	(segment
		(start 385.832604 -415.908744)
		(end 385.958842 -416.254438)
		(width 0.14732)
		(layer "In11.Cu")
		(net "P5E_CPU0_PE2_TX_C_DN<11>")
	)
	(segment
		(start 385.214114 -413.79521)
		(end 385.127754 -413.980884)
		(width 0.14732)
		(layer "In11.Cu")
		(net "P5E_CPU0_PE2_TX_C_DN<11>")
	)
	(segment
		(start 385.253992 -414.326578)
		(end 385.43992 -414.412938)
		(width 0.14732)
		(layer "In11.Cu")
		(net "P5E_CPU0_PE2_TX_C_DN<11>")
	)
	(segment
		(start 384.24485 -404.178516)
		(end 384.24485 -404.6474)
		(width 0.14732)
		(layer "In11.Cu")
		(net "P5E_CPU0_PE2_TX_C_DN<11>")
	)
	(segment
		(start 385.43992 -414.412938)
		(end 385.566412 -414.75914)
		(width 0.14732)
		(layer "In11.Cu")
		(net "P5E_CPU0_PE2_TX_C_DN<11>")
	)
	(segment
		(start 386.271262 -416.687)
		(end 386.184902 -416.872674)
		(width 0.14732)
		(layer "In11.Cu")
		(net "P5E_CPU0_PE2_TX_C_DN<11>")
	)
	(segment
		(start 385.480052 -414.944814)
		(end 385.60629 -415.290508)
		(width 0.14732)
		(layer "In11.Cu")
		(net "P5E_CPU0_PE2_TX_C_DN<11>")
	)
	(segment
		(start 386.184902 -416.872674)
		(end 389.066786 -424.757088)
		(width 0.14732)
		(layer "In11.Cu")
		(net "P5E_CPU0_PE2_TX_C_DN<11>")
	)
	(segment
		(start 384.901694 -413.362648)
		(end 385.087622 -413.449008)
		(width 0.14732)
		(layer "In11.Cu")
		(net "P5E_CPU0_PE2_TX_C_DN<11>")
	)
	(segment
		(start 385.566412 -414.75914)
		(end 385.480052 -414.944814)
		(width 0.14732)
		(layer "In11.Cu")
		(net "P5E_CPU0_PE2_TX_C_DN<11>")
	)
	(segment
		(start 389.190738 -426.51934)
		(end 389.598154 -426.51934)
		(width 0.14732)
		(layer "In11.Cu")
		(net "P5E_CPU0_PE2_TX_C_DN<11>")
	)
	(segment
		(start 384.549142 -412.398718)
		(end 384.73507 -412.485078)
		(width 0.14732)
		(layer "In11.Cu")
		(net "P5E_CPU0_PE2_TX_C_DN<11>")
	)
	(segment
		(start 389.750046 -426.367448)
		(end 389.750046 -426.089826)
		(width 0.14732)
		(layer "In11.Cu")
		(net "P5E_CPU0_PE2_TX_C_DN<11>")
	)
	(segment
		(start 385.60629 -415.290508)
		(end 385.792218 -415.376868)
		(width 0.14732)
		(layer "In11.Cu")
		(net "P5E_CPU0_PE2_TX_C_DN<11>")
	)
	(segment
		(start 385.91871 -415.72307)
		(end 385.832604 -415.908744)
		(width 0.14732)
		(layer "In11.Cu")
		(net "P5E_CPU0_PE2_TX_C_DN<11>")
	)
	(segment
		(start 384.05943 -411.059376)
		(end 384.549142 -412.398718)
		(width 0.14732)
		(layer "In11.Cu")
		(net "P5E_CPU0_PE2_TX_C_DN<11>")
	)
	(segment
		(start 384.861562 -412.83128)
		(end 384.775456 -413.016954)
		(width 0.14732)
		(layer "In11.Cu")
		(net "P5E_CPU0_PE2_TX_C_DN<11>")
	)
	(segment
		(start 387.301232 -403.582378)
		(end 387.301232 -402.96465)
		(width 0.13208)
		(layer "F.Cu")
		(net "P5E_CPU0_PE2_TX_C_DN<10>")
	)
	(segment
		(start 387.60273 -403.883876)
		(end 387.301232 -403.582378)
		(width 0.13208)
		(layer "F.Cu")
		(net "P5E_CPU0_PE2_TX_C_DN<10>")
	)
	(segment
		(start 387.301232 -402.96465)
		(end 387.62813 -402.637752)
		(width 0.13208)
		(layer "F.Cu")
		(net "P5E_CPU0_PE2_TX_C_DN<10>")
	)
	(segment
		(start 387.742938 -412.812738)
		(end 387.8453 -413.16656)
		(width 0.14732)
		(layer "In11.Cu")
		(net "P5E_CPU0_PE2_TX_C_DN<10>")
	)
	(segment
		(start 387.84911 -413.699706)
		(end 388.028942 -413.798512)
		(width 0.14732)
		(layer "In11.Cu")
		(net "P5E_CPU0_PE2_TX_C_DN<10>")
	)
	(segment
		(start 387.30809 -404.6474)
		(end 387.12267 -406.531318)
		(width 0.14732)
		(layer "In11.Cu")
		(net "P5E_CPU0_PE2_TX_C_DN<10>")
	)
	(segment
		(start 388.314946 -414.784286)
		(end 388.417308 -415.138108)
		(width 0.14732)
		(layer "In11.Cu")
		(net "P5E_CPU0_PE2_TX_C_DN<10>")
	)
	(segment
		(start 388.028942 -413.798512)
		(end 388.131304 -414.152334)
		(width 0.14732)
		(layer "In11.Cu")
		(net "P5E_CPU0_PE2_TX_C_DN<10>")
	)
	(segment
		(start 391.750042 -427.37151)
		(end 391.750042 -427.089824)
		(width 0.14732)
		(layer "In11.Cu")
		(net "P5E_CPU0_PE2_TX_C_DN<10>")
	)
	(segment
		(start 391.05586 -424.757088)
		(end 391.05586 -427.384464)
		(width 0.14732)
		(layer "In11.Cu")
		(net "P5E_CPU0_PE2_TX_C_DN<10>")
	)
	(segment
		(start 388.318756 -415.317686)
		(end 391.05586 -424.757088)
		(width 0.14732)
		(layer "In11.Cu")
		(net "P5E_CPU0_PE2_TX_C_DN<10>")
	)
	(segment
		(start 388.135114 -414.68548)
		(end 388.314946 -414.784286)
		(width 0.14732)
		(layer "In11.Cu")
		(net "P5E_CPU0_PE2_TX_C_DN<10>")
	)
	(segment
		(start 391.190734 -427.519338)
		(end 391.602214 -427.519338)
		(width 0.14732)
		(layer "In11.Cu")
		(net "P5E_CPU0_PE2_TX_C_DN<10>")
	)
	(segment
		(start 388.032752 -414.331912)
		(end 388.135114 -414.68548)
		(width 0.14732)
		(layer "In11.Cu")
		(net "P5E_CPU0_PE2_TX_C_DN<10>")
	)
	(segment
		(start 388.417308 -415.138108)
		(end 388.318756 -415.317686)
		(width 0.14732)
		(layer "In11.Cu")
		(net "P5E_CPU0_PE2_TX_C_DN<10>")
	)
	(segment
		(start 387.12267 -411.195012)
		(end 387.562852 -412.712916)
		(width 0.14732)
		(layer "In11.Cu")
		(net "P5E_CPU0_PE2_TX_C_DN<10>")
	)
	(segment
		(start 391.602214 -427.519338)
		(end 391.750042 -427.37151)
		(width 0.14732)
		(layer "In11.Cu")
		(net "P5E_CPU0_PE2_TX_C_DN<10>")
	)
	(segment
		(start 387.8453 -413.16656)
		(end 387.746748 -413.346138)
		(width 0.14732)
		(layer "In11.Cu")
		(net "P5E_CPU0_PE2_TX_C_DN<10>")
	)
	(segment
		(start 387.746748 -413.346138)
		(end 387.84911 -413.699706)
		(width 0.14732)
		(layer "In11.Cu")
		(net "P5E_CPU0_PE2_TX_C_DN<10>")
	)
	(segment
		(start 387.60273 -403.883876)
		(end 387.30809 -404.178516)
		(width 0.14732)
		(layer "In11.Cu")
		(net "P5E_CPU0_PE2_TX_C_DN<10>")
	)
	(segment
		(start 387.30809 -404.178516)
		(end 387.30809 -404.6474)
		(width 0.14732)
		(layer "In11.Cu")
		(net "P5E_CPU0_PE2_TX_C_DN<10>")
	)
	(segment
		(start 387.562852 -412.712916)
		(end 387.563106 -412.713932)
		(width 0.14732)
		(layer "In11.Cu")
		(net "P5E_CPU0_PE2_TX_C_DN<10>")
	)
	(segment
		(start 388.131304 -414.152334)
		(end 388.032752 -414.331912)
		(width 0.14732)
		(layer "In11.Cu")
		(net "P5E_CPU0_PE2_TX_C_DN<10>")
	)
	(segment
		(start 391.05586 -427.384464)
		(end 391.190734 -427.519338)
		(width 0.14732)
		(layer "In11.Cu")
		(net "P5E_CPU0_PE2_TX_C_DN<10>")
	)
	(segment
		(start 387.12267 -406.531318)
		(end 387.12267 -411.195012)
		(width 0.14732)
		(layer "In11.Cu")
		(net "P5E_CPU0_PE2_TX_C_DN<10>")
	)
	(segment
		(start 387.563106 -412.713932)
		(end 387.742938 -412.812738)
		(width 0.14732)
		(layer "In11.Cu")
		(net "P5E_CPU0_PE2_TX_C_DN<10>")
	)
	(segment
		(start 417.933632 -403.582378)
		(end 417.933632 -402.96465)
		(width 0.13208)
		(layer "F.Cu")
		(net "P5E_CPU0_PE2_TX_C_DN<0>")
	)
	(segment
		(start 418.23513 -403.883876)
		(end 417.933632 -403.582378)
		(width 0.13208)
		(layer "F.Cu")
		(net "P5E_CPU0_PE2_TX_C_DN<0>")
	)
	(segment
		(start 417.933632 -402.96465)
		(end 418.26053 -402.637752)
		(width 0.13208)
		(layer "F.Cu")
		(net "P5E_CPU0_PE2_TX_C_DN<0>")
	)
	(segment
		(start 415.857944 -414.850072)
		(end 415.939224 -415.038032)
		(width 0.14732)
		(layer "In11.Cu")
		(net "P5E_CPU0_PE2_TX_C_DN<0>")
	)
	(segment
		(start 417.94049 -404.6474)
		(end 417.75507 -406.531318)
		(width 0.14732)
		(layer "In11.Cu")
		(net "P5E_CPU0_PE2_TX_C_DN<0>")
	)
	(segment
		(start 417.12388 -411.650434)
		(end 416.61334 -412.9405)
		(width 0.14732)
		(layer "In11.Cu")
		(net "P5E_CPU0_PE2_TX_C_DN<0>")
	)
	(segment
		(start 415.803842 -415.380678)
		(end 415.615628 -415.461958)
		(width 0.14732)
		(layer "In11.Cu")
		(net "P5E_CPU0_PE2_TX_C_DN<0>")
	)
	(segment
		(start 415.615628 -415.461958)
		(end 415.615882 -415.462212)
		(width 0.14732)
		(layer "In11.Cu")
		(net "P5E_CPU0_PE2_TX_C_DN<0>")
	)
	(segment
		(start 412.75 -427.37151)
		(end 412.75 -427.089824)
		(width 0.14732)
		(layer "In11.Cu")
		(net "P5E_CPU0_PE2_TX_C_DN<0>")
	)
	(segment
		(start 415.993326 -414.50768)
		(end 415.857944 -414.850072)
		(width 0.14732)
		(layer "In11.Cu")
		(net "P5E_CPU0_PE2_TX_C_DN<0>")
	)
	(segment
		(start 412.06674 -424.430952)
		(end 412.06674 -427.395386)
		(width 0.14732)
		(layer "In11.Cu")
		(net "P5E_CPU0_PE2_TX_C_DN<0>")
	)
	(segment
		(start 416.559238 -413.471106)
		(end 416.371024 -413.552386)
		(width 0.14732)
		(layer "In11.Cu")
		(net "P5E_CPU0_PE2_TX_C_DN<0>")
	)
	(segment
		(start 412.602172 -427.519338)
		(end 412.75 -427.37151)
		(width 0.14732)
		(layer "In11.Cu")
		(net "P5E_CPU0_PE2_TX_C_DN<0>")
	)
	(segment
		(start 415.939224 -415.038032)
		(end 415.803842 -415.380678)
		(width 0.14732)
		(layer "In11.Cu")
		(net "P5E_CPU0_PE2_TX_C_DN<0>")
	)
	(segment
		(start 417.75507 -406.531318)
		(end 417.75507 -410.266642)
		(width 0.14732)
		(layer "In11.Cu")
		(net "P5E_CPU0_PE2_TX_C_DN<0>")
	)
	(segment
		(start 415.99358 -414.506918)
		(end 415.993326 -414.50768)
		(width 0.14732)
		(layer "In11.Cu")
		(net "P5E_CPU0_PE2_TX_C_DN<0>")
	)
	(segment
		(start 416.18154 -414.425384)
		(end 415.993326 -414.506664)
		(width 0.14732)
		(layer "In11.Cu")
		(net "P5E_CPU0_PE2_TX_C_DN<0>")
	)
	(segment
		(start 416.316922 -414.082738)
		(end 416.18154 -414.425384)
		(width 0.14732)
		(layer "In11.Cu")
		(net "P5E_CPU0_PE2_TX_C_DN<0>")
	)
	(segment
		(start 412.190692 -427.519338)
		(end 412.602172 -427.519338)
		(width 0.14732)
		(layer "In11.Cu")
		(net "P5E_CPU0_PE2_TX_C_DN<0>")
	)
	(segment
		(start 416.61334 -412.9405)
		(end 416.69462 -413.12846)
		(width 0.14732)
		(layer "In11.Cu")
		(net "P5E_CPU0_PE2_TX_C_DN<0>")
	)
	(segment
		(start 417.75507 -410.266642)
		(end 417.12388 -411.650434)
		(width 0.14732)
		(layer "In11.Cu")
		(net "P5E_CPU0_PE2_TX_C_DN<0>")
	)
	(segment
		(start 415.615882 -415.462212)
		(end 412.06674 -424.430952)
		(width 0.14732)
		(layer "In11.Cu")
		(net "P5E_CPU0_PE2_TX_C_DN<0>")
	)
	(segment
		(start 416.69462 -413.12846)
		(end 416.559238 -413.471106)
		(width 0.14732)
		(layer "In11.Cu")
		(net "P5E_CPU0_PE2_TX_C_DN<0>")
	)
	(segment
		(start 416.235642 -413.894778)
		(end 416.316922 -414.082738)
		(width 0.14732)
		(layer "In11.Cu")
		(net "P5E_CPU0_PE2_TX_C_DN<0>")
	)
	(segment
		(start 417.94049 -404.178516)
		(end 417.94049 -404.6474)
		(width 0.14732)
		(layer "In11.Cu")
		(net "P5E_CPU0_PE2_TX_C_DN<0>")
	)
	(segment
		(start 416.371024 -413.552386)
		(end 416.235642 -413.894778)
		(width 0.14732)
		(layer "In11.Cu")
		(net "P5E_CPU0_PE2_TX_C_DN<0>")
	)
	(segment
		(start 412.06674 -427.395386)
		(end 412.190692 -427.519338)
		(width 0.14732)
		(layer "In11.Cu")
		(net "P5E_CPU0_PE2_TX_C_DN<0>")
	)
	(segment
		(start 415.993326 -414.506664)
		(end 415.99358 -414.506918)
		(width 0.14732)
		(layer "In11.Cu")
		(net "P5E_CPU0_PE2_TX_C_DN<0>")
	)
	(segment
		(start 418.23513 -403.883876)
		(end 417.94049 -404.178516)
		(width 0.14732)
		(layer "In11.Cu")
		(net "P5E_CPU0_PE2_TX_C_DN<0>")
	)
	(segment
		(start 376.966734 -222.48368)
		(end 376.966734 -221.947994)
		(width 0.13208)
		(layer "F.Cu")
		(net "P5E_CPU0_PE2_RX_DP<9>")
	)
	(segment
		(start 376.966734 -221.947994)
		(end 376.96648 -221.94774)
		(width 0.13208)
		(layer "F.Cu")
		(net "P5E_CPU0_PE2_RX_DP<9>")
	)
	(segment
		(start 377.725178 -218.364308)
		(end 377.719844 -218.367356)
		(width 0.0889)
		(layer "In13.Cu")
		(net "P5E_CPU0_PE2_RX_DP<9>")
	)
	(segment
		(start 377.717558 -218.368626)
		(end 377.710192 -218.372944)
		(width 0.0889)
		(layer "In13.Cu")
		(net "P5E_CPU0_PE2_RX_DP<9>")
	)
	(segment
		(start 391.62863 -404.819358)
		(end 391.62863 -399.502884)
		(width 0.14732)
		(layer "In13.Cu")
		(net "P5E_CPU0_PE2_RX_DP<9>")
	)
	(segment
		(start 377.531884 -220.311218)
		(end 377.531884 -220.32849)
		(width 0.0889)
		(layer "In13.Cu")
		(net "P5E_CPU0_PE2_RX_DP<9>")
	)
	(segment
		(start 388.20725 -214.679784)
		(end 387.855968 -214.534496)
		(width 0.14732)
		(layer "In13.Cu")
		(net "P5E_CPU0_PE2_RX_DP<9>")
	)
	(segment
		(start 378.577348 -215.774524)
		(end 378.55779 -215.78443)
		(width 0.0889)
		(layer "In13.Cu")
		(net "P5E_CPU0_PE2_RX_DP<9>")
	)
	(segment
		(start 393.102338 -433.993798)
		(end 392.80592 -433.69738)
		(width 0.14732)
		(layer "In13.Cu")
		(net "P5E_CPU0_PE2_RX_DP<9>")
	)
	(segment
		(start 377.719844 -218.367356)
		(end 377.717558 -218.368626)
		(width 0.0889)
		(layer "In13.Cu")
		(net "P5E_CPU0_PE2_RX_DP<9>")
	)
	(segment
		(start 392.80592 -433.69738)
		(end 392.80592 -424.223942)
		(width 0.14732)
		(layer "In13.Cu")
		(net "P5E_CPU0_PE2_RX_DP<9>")
	)
	(segment
		(start 393.329922 -433.993798)
		(end 393.102338 -433.993798)
		(width 0.14732)
		(layer "In13.Cu")
		(net "P5E_CPU0_PE2_RX_DP<9>")
	)
	(segment
		(start 377.719844 -216.73947)
		(end 377.719082 -216.739978)
		(width 0.0889)
		(layer "In13.Cu")
		(net "P5E_CPU0_PE2_RX_DP<9>")
	)
	(segment
		(start 391.62863 -399.502884)
		(end 396.609062 -354.484686)
		(width 0.14732)
		(layer "In13.Cu")
		(net "P5E_CPU0_PE2_RX_DP<9>")
	)
	(segment
		(start 396.352014 -253.148846)
		(end 396.352268 -253.148846)
		(width 0.14732)
		(layer "In13.Cu")
		(net "P5E_CPU0_PE2_RX_DP<9>")
	)
	(segment
		(start 377.212098 -221.652846)
		(end 377.122944 -221.676722)
		(width 0.0889)
		(layer "In13.Cu")
		(net "P5E_CPU0_PE2_RX_DP<9>")
	)
	(segment
		(start 396.256764 -250.312428)
		(end 393.045188 -229.720648)
		(width 0.14732)
		(layer "In13.Cu")
		(net "P5E_CPU0_PE2_RX_DP<9>")
	)
	(segment
		(start 392.80592 -424.223942)
		(end 392.836654 -412.14802)
		(width 0.14732)
		(layer "In13.Cu")
		(net "P5E_CPU0_PE2_RX_DP<9>")
	)
	(segment
		(start 377.719082 -219.01658)
		(end 377.725178 -219.020136)
		(width 0.0889)
		(layer "In13.Cu")
		(net "P5E_CPU0_PE2_RX_DP<9>")
	)
	(segment
		(start 392.97483 -406.165558)
		(end 391.62863 -404.819358)
		(width 0.14732)
		(layer "In13.Cu")
		(net "P5E_CPU0_PE2_RX_DP<9>")
	)
	(segment
		(start 378.55779 -215.78443)
		(end 378.501402 -215.765888)
		(width 0.0889)
		(layer "In13.Cu")
		(net "P5E_CPU0_PE2_RX_DP<9>")
	)
	(segment
		(start 396.352268 -253.148846)
		(end 396.256764 -250.312428)
		(width 0.14732)
		(layer "In13.Cu")
		(net "P5E_CPU0_PE2_RX_DP<9>")
	)
	(segment
		(start 378.70892 -215.707214)
		(end 378.577348 -215.774524)
		(width 0.14732)
		(layer "In13.Cu")
		(net "P5E_CPU0_PE2_RX_DP<9>")
	)
	(segment
		(start 377.531884 -217.0557)
		(end 377.531884 -217.072972)
		(width 0.0889)
		(layer "In13.Cu")
		(net "P5E_CPU0_PE2_RX_DP<9>")
	)
	(segment
		(start 384.515106 -213.992968)
		(end 382.089152 -213.992968)
		(width 0.14732)
		(layer "In13.Cu")
		(net "P5E_CPU0_PE2_RX_DP<9>")
	)
	(segment
		(start 377.725178 -221.619826)
		(end 377.70435 -221.632018)
		(width 0.0889)
		(layer "In13.Cu")
		(net "P5E_CPU0_PE2_RX_DP<9>")
	)
	(segment
		(start 378.001784 -221.1197)
		(end 378.001784 -221.133924)
		(width 0.0889)
		(layer "In13.Cu")
		(net "P5E_CPU0_PE2_RX_DP<9>")
	)
	(segment
		(start 387.855968 -214.534496)
		(end 384.515106 -213.992968)
		(width 0.14732)
		(layer "In13.Cu")
		(net "P5E_CPU0_PE2_RX_DP<9>")
	)
	(segment
		(start 378.501402 -215.765888)
		(end 378.380244 -215.827864)
		(width 0.0889)
		(layer "In13.Cu")
		(net "P5E_CPU0_PE2_RX_DP<9>")
	)
	(segment
		(start 392.191748 -225.405188)
		(end 389.336534 -215.809068)
		(width 0.14732)
		(layer "In13.Cu")
		(net "P5E_CPU0_PE2_RX_DP<9>")
	)
	(segment
		(start 378.189236 -215.926162)
		(end 378.180346 -215.931242)
		(width 0.0889)
		(layer "In13.Cu")
		(net "P5E_CPU0_PE2_RX_DP<9>")
	)
	(segment
		(start 393.750038 -434.48986)
		(end 393.750038 -434.413914)
		(width 0.14732)
		(layer "In13.Cu")
		(net "P5E_CPU0_PE2_RX_DP<9>")
	)
	(segment
		(start 393.045188 -229.720648)
		(end 392.191748 -225.405188)
		(width 0.14732)
		(layer "In13.Cu")
		(net "P5E_CPU0_PE2_RX_DP<9>")
	)
	(segment
		(start 389.336534 -215.809068)
		(end 388.20725 -214.679784)
		(width 0.14732)
		(layer "In13.Cu")
		(net "P5E_CPU0_PE2_RX_DP<9>")
	)
	(segment
		(start 399.201386 -339.501734)
		(end 392.041126 -309.439818)
		(width 0.14732)
		(layer "In13.Cu")
		(net "P5E_CPU0_PE2_RX_DP<9>")
	)
	(segment
		(start 392.836654 -412.14802)
		(end 392.836908 -412.14802)
		(width 0.14732)
		(layer "In13.Cu")
		(net "P5E_CPU0_PE2_RX_DP<9>")
	)
	(segment
		(start 379.245114 -215.17102)
		(end 378.70892 -215.707214)
		(width 0.14732)
		(layer "In13.Cu")
		(net "P5E_CPU0_PE2_RX_DP<9>")
	)
	(segment
		(start 393.750038 -434.413914)
		(end 393.329922 -433.993798)
		(width 0.14732)
		(layer "In13.Cu")
		(net "P5E_CPU0_PE2_RX_DP<9>")
	)
	(segment
		(start 378.380244 -215.827864)
		(end 378.189236 -215.926162)
		(width 0.0889)
		(layer "In13.Cu")
		(net "P5E_CPU0_PE2_RX_DP<9>")
	)
	(segment
		(start 392.836908 -412.14802)
		(end 392.97483 -410.42336)
		(width 0.14732)
		(layer "In13.Cu")
		(net "P5E_CPU0_PE2_RX_DP<9>")
	)
	(segment
		(start 377.710192 -219.0115)
		(end 377.719082 -219.01658)
		(width 0.0889)
		(layer "In13.Cu")
		(net "P5E_CPU0_PE2_RX_DP<9>")
	)
	(segment
		(start 377.719844 -219.994988)
		(end 377.719082 -219.995496)
		(width 0.0889)
		(layer "In13.Cu")
		(net "P5E_CPU0_PE2_RX_DP<9>")
	)
	(segment
		(start 392.97483 -410.42336)
		(end 392.97483 -406.165558)
		(width 0.14732)
		(layer "In13.Cu")
		(net "P5E_CPU0_PE2_RX_DP<9>")
	)
	(segment
		(start 382.089152 -213.992968)
		(end 379.245114 -215.17102)
		(width 0.14732)
		(layer "In13.Cu")
		(net "P5E_CPU0_PE2_RX_DP<9>")
	)
	(segment
		(start 377.122944 -221.676722)
		(end 376.96648 -221.94774)
		(width 0.0889)
		(layer "In13.Cu")
		(net "P5E_CPU0_PE2_RX_DP<9>")
	)
	(segment
		(start 377.725178 -216.736422)
		(end 377.719844 -216.73947)
		(width 0.0889)
		(layer "In13.Cu")
		(net "P5E_CPU0_PE2_RX_DP<9>")
	)
	(segment
		(start 396.609062 -354.484686)
		(end 399.201386 -339.501734)
		(width 0.14732)
		(layer "In13.Cu")
		(net "P5E_CPU0_PE2_RX_DP<9>")
	)
	(segment
		(start 377.725178 -219.99194)
		(end 377.719844 -219.994988)
		(width 0.0889)
		(layer "In13.Cu")
		(net "P5E_CPU0_PE2_RX_DP<9>")
	)
	(segment
		(start 392.041126 -309.439818)
		(end 396.352014 -253.148846)
		(width 0.14732)
		(layer "In13.Cu")
		(net "P5E_CPU0_PE2_RX_DP<9>")
	)
	(arc
		(start 377.719082 -219.995496)
		(mid 377.584149 -220.12885)
		(end 377.531884 -220.311218)
		(width 0.0889)
		(layer "In13.Cu")
		(net "P5E_CPU0_PE2_RX_DP<9>")
	)
	(arc
		(start 377.70435 -221.632018)
		(mid 377.471435 -221.698229)
		(end 377.232164 -221.660974)
		(width 0.0889)
		(layer "In13.Cu")
		(net "P5E_CPU0_PE2_RX_DP<9>")
	)
	(arc
		(start 377.531884 -217.072972)
		(mid 377.584154 -217.255337)
		(end 377.719082 -217.388694)
		(width 0.0889)
		(layer "In13.Cu")
		(net "P5E_CPU0_PE2_RX_DP<9>")
	)
	(arc
		(start 377.232164 -221.660974)
		(mid 377.222093 -221.657005)
		(end 377.212098 -221.652846)
		(width 0.0889)
		(layer "In13.Cu")
		(net "P5E_CPU0_PE2_RX_DP<9>")
	)
	(arc
		(start 377.719082 -216.739978)
		(mid 377.584149 -216.873332)
		(end 377.531884 -217.0557)
		(width 0.0889)
		(layer "In13.Cu")
		(net "P5E_CPU0_PE2_RX_DP<9>")
	)
	(arc
		(start 377.719082 -220.644212)
		(mid 377.922563 -220.845016)
		(end 378.001784 -221.1197)
		(width 0.0889)
		(layer "In13.Cu")
		(net "P5E_CPU0_PE2_RX_DP<9>")
	)
	(arc
		(start 378.001784 -216.25052)
		(mid 377.927793 -216.530086)
		(end 377.725178 -216.736422)
		(width 0.0889)
		(layer "In13.Cu")
		(net "P5E_CPU0_PE2_RX_DP<9>")
	)
	(arc
		(start 377.531884 -220.32849)
		(mid 377.584154 -220.510855)
		(end 377.719082 -220.644212)
		(width 0.0889)
		(layer "In13.Cu")
		(net "P5E_CPU0_PE2_RX_DP<9>")
	)
	(arc
		(start 378.180346 -215.931242)
		(mid 378.049432 -216.067602)
		(end 378.001784 -216.25052)
		(width 0.0889)
		(layer "In13.Cu")
		(net "P5E_CPU0_PE2_RX_DP<9>")
	)
	(arc
		(start 378.001784 -221.133924)
		(mid 377.927793 -221.41349)
		(end 377.725178 -221.619826)
		(width 0.0889)
		(layer "In13.Cu")
		(net "P5E_CPU0_PE2_RX_DP<9>")
	)
	(arc
		(start 377.725178 -219.020136)
		(mid 378.001752 -219.506038)
		(end 377.725178 -219.99194)
		(width 0.0889)
		(layer "In13.Cu")
		(net "P5E_CPU0_PE2_RX_DP<9>")
	)
	(arc
		(start 377.719082 -217.388694)
		(mid 378.002077 -217.874813)
		(end 377.725178 -218.364308)
		(width 0.0889)
		(layer "In13.Cu")
		(net "P5E_CPU0_PE2_RX_DP<9>")
	)
	(arc
		(start 377.710192 -218.372944)
		(mid 377.531595 -218.692222)
		(end 377.710192 -219.0115)
		(width 0.0889)
		(layer "In13.Cu")
		(net "P5E_CPU0_PE2_RX_DP<9>")
	)
	(segment
		(start 376.49658 -221.669864)
		(end 376.49658 -221.134178)
		(width 0.13208)
		(layer "F.Cu")
		(net "P5E_CPU0_PE2_RX_DP<8>")
	)
	(segment
		(start 376.49658 -221.134178)
		(end 376.496834 -221.133924)
		(width 0.13208)
		(layer "F.Cu")
		(net "P5E_CPU0_PE2_RX_DP<8>")
	)
	(segment
		(start 394.69187 -404.819358)
		(end 394.69187 -399.524474)
		(width 0.14732)
		(layer "In13.Cu")
		(net "P5E_CPU0_PE2_RX_DP<8>")
	)
	(segment
		(start 380.70536 -212.812884)
		(end 380.58344 -212.934804)
		(width 0.14732)
		(layer "In13.Cu")
		(net "P5E_CPU0_PE2_RX_DP<8>")
	)
	(segment
		(start 395.109446 -434.947314)
		(end 394.791946 -434.629814)
		(width 0.14732)
		(layer "In13.Cu")
		(net "P5E_CPU0_PE2_RX_DP<8>")
	)
	(segment
		(start 376.3645 -220.773752)
		(end 376.34037 -220.862906)
		(width 0.0889)
		(layer "In13.Cu")
		(net "P5E_CPU0_PE2_RX_DP<8>")
	)
	(segment
		(start 394.69187 -399.524474)
		(end 397.49476 -355.077014)
		(width 0.14732)
		(layer "In13.Cu")
		(net "P5E_CPU0_PE2_RX_DP<8>")
	)
	(segment
		(start 380.58344 -212.934804)
		(end 380.14656 -212.934804)
		(width 0.14732)
		(layer "In13.Cu")
		(net "P5E_CPU0_PE2_RX_DP<8>")
	)
	(segment
		(start 378.47143 -213.734396)
		(end 378.183394 -214.429594)
		(width 0.0889)
		(layer "In13.Cu")
		(net "P5E_CPU0_PE2_RX_DP<8>")
	)
	(segment
		(start 393.971018 -229.551484)
		(end 393.142724 -225.248724)
		(width 0.14732)
		(layer "In13.Cu")
		(net "P5E_CPU0_PE2_RX_DP<8>")
	)
	(segment
		(start 388.57809 -213.708996)
		(end 384.073908 -212.812884)
		(width 0.14732)
		(layer "In13.Cu")
		(net "P5E_CPU0_PE2_RX_DP<8>")
	)
	(segment
		(start 376.770392 -219.0115)
		(end 376.777758 -219.015818)
		(width 0.0889)
		(layer "In13.Cu")
		(net "P5E_CPU0_PE2_RX_DP<8>")
	)
	(segment
		(start 376.780044 -218.367356)
		(end 376.779282 -218.367864)
		(width 0.0889)
		(layer "In13.Cu")
		(net "P5E_CPU0_PE2_RX_DP<8>")
	)
	(segment
		(start 384.073908 -212.812884)
		(end 380.70536 -212.812884)
		(width 0.14732)
		(layer "In13.Cu")
		(net "P5E_CPU0_PE2_RX_DP<8>")
	)
	(segment
		(start 378.51334 -213.142068)
		(end 378.51334 -213.164166)
		(width 0.0889)
		(layer "In13.Cu")
		(net "P5E_CPU0_PE2_RX_DP<8>")
	)
	(segment
		(start 378.183394 -214.429594)
		(end 377.669044 -214.944198)
		(width 0.0889)
		(layer "In13.Cu")
		(net "P5E_CPU0_PE2_RX_DP<8>")
	)
	(segment
		(start 376.778774 -219.996004)
		(end 376.776234 -219.997528)
		(width 0.0889)
		(layer "In13.Cu")
		(net "P5E_CPU0_PE2_RX_DP<8>")
	)
	(segment
		(start 376.777758 -219.015818)
		(end 376.779282 -219.01658)
		(width 0.0889)
		(layer "In13.Cu")
		(net "P5E_CPU0_PE2_RX_DP<8>")
	)
	(segment
		(start 400.183096 -339.542374)
		(end 393.018264 -309.328058)
		(width 0.14732)
		(layer "In13.Cu")
		(net "P5E_CPU0_PE2_RX_DP<8>")
	)
	(segment
		(start 397.177006 -249.976386)
		(end 393.971018 -229.551484)
		(width 0.14732)
		(layer "In13.Cu")
		(net "P5E_CPU0_PE2_RX_DP<8>")
	)
	(segment
		(start 394.791946 -424.607228)
		(end 395.694916 -413.187642)
		(width 0.14732)
		(layer "In13.Cu")
		(net "P5E_CPU0_PE2_RX_DP<8>")
	)
	(segment
		(start 376.782076 -219.018104)
		(end 376.785378 -219.020136)
		(width 0.0889)
		(layer "In13.Cu")
		(net "P5E_CPU0_PE2_RX_DP<8>")
	)
	(segment
		(start 393.018264 -309.328058)
		(end 397.285972 -253.2126)
		(width 0.14732)
		(layer "In13.Cu")
		(net "P5E_CPU0_PE2_RX_DP<8>")
	)
	(segment
		(start 378.47143 -213.206076)
		(end 378.47143 -213.734396)
		(width 0.0889)
		(layer "In13.Cu")
		(net "P5E_CPU0_PE2_RX_DP<8>")
	)
	(segment
		(start 376.34037 -220.862906)
		(end 376.496834 -221.133924)
		(width 0.0889)
		(layer "In13.Cu")
		(net "P5E_CPU0_PE2_RX_DP<8>")
	)
	(segment
		(start 376.779282 -219.01658)
		(end 376.782076 -219.018104)
		(width 0.0889)
		(layer "In13.Cu")
		(net "P5E_CPU0_PE2_RX_DP<8>")
	)
	(segment
		(start 397.285972 -253.2126)
		(end 397.177006 -249.976386)
		(width 0.14732)
		(layer "In13.Cu")
		(net "P5E_CPU0_PE2_RX_DP<8>")
	)
	(segment
		(start 378.51334 -212.97011)
		(end 378.51334 -213.142068)
		(width 0.14732)
		(layer "In13.Cu")
		(net "P5E_CPU0_PE2_RX_DP<8>")
	)
	(segment
		(start 377.249436 -215.926162)
		(end 377.240546 -215.931242)
		(width 0.0889)
		(layer "In13.Cu")
		(net "P5E_CPU0_PE2_RX_DP<8>")
	)
	(segment
		(start 376.779536 -219.995496)
		(end 376.778774 -219.996004)
		(width 0.0889)
		(layer "In13.Cu")
		(net "P5E_CPU0_PE2_RX_DP<8>")
	)
	(segment
		(start 376.770646 -217.383614)
		(end 376.779536 -217.388694)
		(width 0.0889)
		(layer "In13.Cu")
		(net "P5E_CPU0_PE2_RX_DP<8>")
	)
	(segment
		(start 377.531884 -215.274652)
		(end 377.531884 -215.44661)
		(width 0.0889)
		(layer "In13.Cu")
		(net "P5E_CPU0_PE2_RX_DP<8>")
	)
	(segment
		(start 377.061984 -217.859864)
		(end 377.061984 -217.878406)
		(width 0.0889)
		(layer "In13.Cu")
		(net "P5E_CPU0_PE2_RX_DP<8>")
	)
	(segment
		(start 378.670566 -212.812884)
		(end 378.51334 -212.97011)
		(width 0.14732)
		(layer "In13.Cu")
		(net "P5E_CPU0_PE2_RX_DP<8>")
	)
	(segment
		(start 395.750034 -435.413658)
		(end 395.28369 -434.947314)
		(width 0.14732)
		(layer "In13.Cu")
		(net "P5E_CPU0_PE2_RX_DP<8>")
	)
	(segment
		(start 377.061984 -219.506038)
		(end 377.061984 -219.515944)
		(width 0.0889)
		(layer "In13.Cu")
		(net "P5E_CPU0_PE2_RX_DP<8>")
	)
	(segment
		(start 395.750034 -435.489858)
		(end 395.750034 -435.413658)
		(width 0.14732)
		(layer "In13.Cu")
		(net "P5E_CPU0_PE2_RX_DP<8>")
	)
	(segment
		(start 394.791946 -434.629814)
		(end 394.791946 -424.607228)
		(width 0.14732)
		(layer "In13.Cu")
		(net "P5E_CPU0_PE2_RX_DP<8>")
	)
	(segment
		(start 397.49476 -355.077014)
		(end 400.183096 -339.542374)
		(width 0.14732)
		(layer "In13.Cu")
		(net "P5E_CPU0_PE2_RX_DP<8>")
	)
	(segment
		(start 376.776234 -219.997528)
		(end 376.770646 -220.000576)
		(width 0.0889)
		(layer "In13.Cu")
		(net "P5E_CPU0_PE2_RX_DP<8>")
	)
	(segment
		(start 378.51334 -213.164166)
		(end 378.47143 -213.206076)
		(width 0.0889)
		(layer "In13.Cu")
		(net "P5E_CPU0_PE2_RX_DP<8>")
	)
	(segment
		(start 393.142724 -225.248724)
		(end 391.679938 -220.298264)
		(width 0.14732)
		(layer "In13.Cu")
		(net "P5E_CPU0_PE2_RX_DP<8>")
	)
	(segment
		(start 377.061984 -216.25052)
		(end 377.061984 -216.260426)
		(width 0.0889)
		(layer "In13.Cu")
		(net "P5E_CPU0_PE2_RX_DP<8>")
	)
	(segment
		(start 376.778774 -216.740486)
		(end 376.776234 -216.74201)
		(width 0.0889)
		(layer "In13.Cu")
		(net "P5E_CPU0_PE2_RX_DP<8>")
	)
	(segment
		(start 376.776234 -216.74201)
		(end 376.770646 -216.745058)
		(width 0.0889)
		(layer "In13.Cu")
		(net "P5E_CPU0_PE2_RX_DP<8>")
	)
	(segment
		(start 377.669044 -214.944198)
		(end 377.531884 -215.274652)
		(width 0.0889)
		(layer "In13.Cu")
		(net "P5E_CPU0_PE2_RX_DP<8>")
	)
	(segment
		(start 376.592084 -220.319854)
		(end 376.592084 -220.334078)
		(width 0.0889)
		(layer "In13.Cu")
		(net "P5E_CPU0_PE2_RX_DP<8>")
	)
	(segment
		(start 391.679938 -220.298264)
		(end 391.679938 -220.29801)
		(width 0.14732)
		(layer "In13.Cu")
		(net "P5E_CPU0_PE2_RX_DP<8>")
	)
	(segment
		(start 395.694916 -413.187642)
		(end 396.03807 -410.667454)
		(width 0.14732)
		(layer "In13.Cu")
		(net "P5E_CPU0_PE2_RX_DP<8>")
	)
	(segment
		(start 380.02464 -212.812884)
		(end 378.670566 -212.812884)
		(width 0.14732)
		(layer "In13.Cu")
		(net "P5E_CPU0_PE2_RX_DP<8>")
	)
	(segment
		(start 390.948672 -217.82278)
		(end 390.948418 -217.822526)
		(width 0.14732)
		(layer "In13.Cu")
		(net "P5E_CPU0_PE2_RX_DP<8>")
	)
	(segment
		(start 391.679938 -220.29801)
		(end 390.948672 -217.82278)
		(width 0.14732)
		(layer "In13.Cu")
		(net "P5E_CPU0_PE2_RX_DP<8>")
	)
	(segment
		(start 390.948418 -217.822526)
		(end 390.217152 -215.347804)
		(width 0.14732)
		(layer "In13.Cu")
		(net "P5E_CPU0_PE2_RX_DP<8>")
	)
	(segment
		(start 390.217152 -215.347804)
		(end 388.57809 -213.708996)
		(width 0.14732)
		(layer "In13.Cu")
		(net "P5E_CPU0_PE2_RX_DP<8>")
	)
	(segment
		(start 376.779536 -216.739978)
		(end 376.778774 -216.740486)
		(width 0.0889)
		(layer "In13.Cu")
		(net "P5E_CPU0_PE2_RX_DP<8>")
	)
	(segment
		(start 396.03807 -406.165558)
		(end 394.69187 -404.819358)
		(width 0.14732)
		(layer "In13.Cu")
		(net "P5E_CPU0_PE2_RX_DP<8>")
	)
	(segment
		(start 395.28369 -434.947314)
		(end 395.109446 -434.947314)
		(width 0.14732)
		(layer "In13.Cu")
		(net "P5E_CPU0_PE2_RX_DP<8>")
	)
	(segment
		(start 380.14656 -212.934804)
		(end 380.02464 -212.812884)
		(width 0.14732)
		(layer "In13.Cu")
		(net "P5E_CPU0_PE2_RX_DP<8>")
	)
	(segment
		(start 396.03807 -410.667454)
		(end 396.03807 -406.165558)
		(width 0.14732)
		(layer "In13.Cu")
		(net "P5E_CPU0_PE2_RX_DP<8>")
	)
	(segment
		(start 376.785378 -218.364308)
		(end 376.780044 -218.367356)
		(width 0.0889)
		(layer "In13.Cu")
		(net "P5E_CPU0_PE2_RX_DP<8>")
	)
	(segment
		(start 376.779282 -218.367864)
		(end 376.770392 -218.372944)
		(width 0.0889)
		(layer "In13.Cu")
		(net "P5E_CPU0_PE2_RX_DP<8>")
	)
	(arc
		(start 376.770392 -218.372944)
		(mid 376.591795 -218.692222)
		(end 376.770392 -219.0115)
		(width 0.0889)
		(layer "In13.Cu")
		(net "P5E_CPU0_PE2_RX_DP<8>")
	)
	(arc
		(start 376.785378 -219.020136)
		(mid 376.987965 -219.226487)
		(end 377.061984 -219.506038)
		(width 0.0889)
		(layer "In13.Cu")
		(net "P5E_CPU0_PE2_RX_DP<8>")
	)
	(arc
		(start 377.061984 -217.878406)
		(mid 376.987993 -218.157972)
		(end 376.785378 -218.364308)
		(width 0.0889)
		(layer "In13.Cu")
		(net "P5E_CPU0_PE2_RX_DP<8>")
	)
	(arc
		(start 376.592084 -220.334078)
		(mid 376.533723 -220.570676)
		(end 376.381264 -220.760798)
		(width 0.0889)
		(layer "In13.Cu")
		(net "P5E_CPU0_PE2_RX_DP<8>")
	)
	(arc
		(start 377.531884 -215.44661)
		(mid 377.453773 -215.723559)
		(end 377.249436 -215.926162)
		(width 0.0889)
		(layer "In13.Cu")
		(net "P5E_CPU0_PE2_RX_DP<8>")
	)
	(arc
		(start 376.770646 -216.745058)
		(mid 376.592049 -217.064336)
		(end 376.770646 -217.383614)
		(width 0.0889)
		(layer "In13.Cu")
		(net "P5E_CPU0_PE2_RX_DP<8>")
	)
	(arc
		(start 377.061984 -216.260426)
		(mid 376.983873 -216.537375)
		(end 376.779536 -216.739978)
		(width 0.0889)
		(layer "In13.Cu")
		(net "P5E_CPU0_PE2_RX_DP<8>")
	)
	(arc
		(start 376.381264 -220.760798)
		(mid 376.372942 -220.767353)
		(end 376.3645 -220.773752)
		(width 0.0889)
		(layer "In13.Cu")
		(net "P5E_CPU0_PE2_RX_DP<8>")
	)
	(arc
		(start 377.061984 -219.515944)
		(mid 376.983873 -219.792893)
		(end 376.779536 -219.995496)
		(width 0.0889)
		(layer "In13.Cu")
		(net "P5E_CPU0_PE2_RX_DP<8>")
	)
	(arc
		(start 377.240546 -215.931242)
		(mid 377.109632 -216.067602)
		(end 377.061984 -216.25052)
		(width 0.0889)
		(layer "In13.Cu")
		(net "P5E_CPU0_PE2_RX_DP<8>")
	)
	(arc
		(start 376.770646 -220.000576)
		(mid 376.639732 -220.136936)
		(end 376.592084 -220.319854)
		(width 0.0889)
		(layer "In13.Cu")
		(net "P5E_CPU0_PE2_RX_DP<8>")
	)
	(arc
		(start 376.779536 -217.388694)
		(mid 376.981822 -217.587675)
		(end 377.061984 -217.859864)
		(width 0.0889)
		(layer "In13.Cu")
		(net "P5E_CPU0_PE2_RX_DP<8>")
	)
	(segment
		(start 375.087134 -221.947994)
		(end 375.08688 -221.94774)
		(width 0.13208)
		(layer "F.Cu")
		(net "P5E_CPU0_PE2_RX_DP<7>")
	)
	(segment
		(start 375.087134 -222.48368)
		(end 375.087134 -221.947994)
		(width 0.13208)
		(layer "F.Cu")
		(net "P5E_CPU0_PE2_RX_DP<7>")
	)
	(segment
		(start 375.845578 -219.99194)
		(end 375.840244 -219.994988)
		(width 0.0889)
		(layer "In13.Cu")
		(net "P5E_CPU0_PE2_RX_DP<7>")
	)
	(segment
		(start 375.840244 -219.994988)
		(end 375.839482 -219.995496)
		(width 0.0889)
		(layer "In13.Cu")
		(net "P5E_CPU0_PE2_RX_DP<7>")
	)
	(segment
		(start 376.122184 -217.864182)
		(end 376.122184 -217.878406)
		(width 0.0889)
		(layer "In13.Cu")
		(net "P5E_CPU0_PE2_RX_DP<7>")
	)
	(segment
		(start 391.095738 -214.761318)
		(end 389.140192 -212.805772)
		(width 0.14732)
		(layer "In13.Cu")
		(net "P5E_CPU0_PE2_RX_DP<7>")
	)
	(segment
		(start 375.837958 -218.368626)
		(end 375.830592 -218.372944)
		(width 0.0889)
		(layer "In13.Cu")
		(net "P5E_CPU0_PE2_RX_DP<7>")
	)
	(segment
		(start 377.572778 -212.671914)
		(end 377.572778 -213.142068)
		(width 0.14732)
		(layer "In13.Cu")
		(net "P5E_CPU0_PE2_RX_DP<7>")
	)
	(segment
		(start 375.845578 -216.736422)
		(end 375.840244 -216.73947)
		(width 0.0889)
		(layer "In13.Cu")
		(net "P5E_CPU0_PE2_RX_DP<7>")
	)
	(segment
		(start 398.750028 -434.48986)
		(end 398.750028 -434.41366)
		(width 0.14732)
		(layer "In13.Cu")
		(net "P5E_CPU0_PE2_RX_DP<7>")
	)
	(segment
		(start 378.212858 -211.943188)
		(end 377.635516 -212.52053)
		(width 0.14732)
		(layer "In13.Cu")
		(net "P5E_CPU0_PE2_RX_DP<7>")
	)
	(segment
		(start 397.60779 -397.812768)
		(end 398.398746 -355.98227)
		(width 0.14732)
		(layer "In13.Cu")
		(net "P5E_CPU0_PE2_RX_DP<7>")
	)
	(segment
		(start 389.140192 -212.805772)
		(end 383.92608 -211.768944)
		(width 0.14732)
		(layer "In13.Cu")
		(net "P5E_CPU0_PE2_RX_DP<7>")
	)
	(segment
		(start 376.801634 -214.851234)
		(end 376.601228 -215.335104)
		(width 0.0889)
		(layer "In13.Cu")
		(net "P5E_CPU0_PE2_RX_DP<7>")
	)
	(segment
		(start 376.122184 -221.1197)
		(end 376.122184 -221.133924)
		(width 0.0889)
		(layer "In13.Cu")
		(net "P5E_CPU0_PE2_RX_DP<7>")
	)
	(segment
		(start 398.695164 -413.624776)
		(end 399.10131 -410.406342)
		(width 0.14732)
		(layer "In13.Cu")
		(net "P5E_CPU0_PE2_RX_DP<7>")
	)
	(segment
		(start 375.839482 -219.01658)
		(end 375.845578 -219.020136)
		(width 0.0889)
		(layer "In13.Cu")
		(net "P5E_CPU0_PE2_RX_DP<7>")
	)
	(segment
		(start 375.652284 -220.311218)
		(end 375.652284 -220.32849)
		(width 0.0889)
		(layer "In13.Cu")
		(net "P5E_CPU0_PE2_RX_DP<7>")
	)
	(segment
		(start 398.330166 -433.993798)
		(end 398.042384 -433.993798)
		(width 0.14732)
		(layer "In13.Cu")
		(net "P5E_CPU0_PE2_RX_DP<7>")
	)
	(segment
		(start 396.111222 -281.085036)
		(end 396.11173 -281.085036)
		(width 0.14732)
		(layer "In13.Cu")
		(net "P5E_CPU0_PE2_RX_DP<7>")
	)
	(segment
		(start 377.530868 -213.881462)
		(end 377.360688 -214.29218)
		(width 0.0889)
		(layer "In13.Cu")
		(net "P5E_CPU0_PE2_RX_DP<7>")
	)
	(segment
		(start 397.75511 -404.819358)
		(end 397.75511 -400.502628)
		(width 0.14732)
		(layer "In13.Cu")
		(net "P5E_CPU0_PE2_RX_DP<7>")
	)
	(segment
		(start 376.601228 -215.335104)
		(end 376.59183 -215.452198)
		(width 0.0889)
		(layer "In13.Cu")
		(net "P5E_CPU0_PE2_RX_DP<7>")
	)
	(segment
		(start 394.001244 -308.966362)
		(end 396.111222 -281.085036)
		(width 0.14732)
		(layer "In13.Cu")
		(net "P5E_CPU0_PE2_RX_DP<7>")
	)
	(segment
		(start 383.92608 -211.768944)
		(end 378.633482 -211.768944)
		(width 0.14732)
		(layer "In13.Cu")
		(net "P5E_CPU0_PE2_RX_DP<7>")
	)
	(segment
		(start 377.635516 -212.52053)
		(end 377.572778 -212.671914)
		(width 0.14732)
		(layer "In13.Cu")
		(net "P5E_CPU0_PE2_RX_DP<7>")
	)
	(segment
		(start 399.10131 -406.165558)
		(end 397.75511 -404.819358)
		(width 0.14732)
		(layer "In13.Cu")
		(net "P5E_CPU0_PE2_RX_DP<7>")
	)
	(segment
		(start 394.315188 -225.806508)
		(end 392.705336 -220.283786)
		(width 0.14732)
		(layer "In13.Cu")
		(net "P5E_CPU0_PE2_RX_DP<7>")
	)
	(segment
		(start 398.436084 -355.366066)
		(end 398.436084 -355.159056)
		(width 0.14732)
		(layer "In13.Cu")
		(net "P5E_CPU0_PE2_RX_DP<7>")
	)
	(segment
		(start 398.042384 -433.993798)
		(end 397.79194 -433.743354)
		(width 0.14732)
		(layer "In13.Cu")
		(net "P5E_CPU0_PE2_RX_DP<7>")
	)
	(segment
		(start 397.75511 -400.502628)
		(end 397.60779 -397.812768)
		(width 0.14732)
		(layer "In13.Cu")
		(net "P5E_CPU0_PE2_RX_DP<7>")
	)
	(segment
		(start 376.309636 -215.926162)
		(end 376.300746 -215.931242)
		(width 0.0889)
		(layer "In13.Cu")
		(net "P5E_CPU0_PE2_RX_DP<7>")
	)
	(segment
		(start 398.398746 -355.98227)
		(end 398.435322 -355.374702)
		(width 0.14732)
		(layer "In13.Cu")
		(net "P5E_CPU0_PE2_RX_DP<7>")
	)
	(segment
		(start 375.243344 -221.676722)
		(end 375.08688 -221.94774)
		(width 0.0889)
		(layer "In13.Cu")
		(net "P5E_CPU0_PE2_RX_DP<7>")
	)
	(segment
		(start 375.332498 -221.652846)
		(end 375.243344 -221.676722)
		(width 0.0889)
		(layer "In13.Cu")
		(net "P5E_CPU0_PE2_RX_DP<7>")
	)
	(segment
		(start 375.840244 -218.367356)
		(end 375.839482 -218.367864)
		(width 0.0889)
		(layer "In13.Cu")
		(net "P5E_CPU0_PE2_RX_DP<7>")
	)
	(segment
		(start 392.705336 -220.283532)
		(end 391.095738 -214.761318)
		(width 0.14732)
		(layer "In13.Cu")
		(net "P5E_CPU0_PE2_RX_DP<7>")
	)
	(segment
		(start 375.652284 -217.0557)
		(end 375.652284 -217.072972)
		(width 0.0889)
		(layer "In13.Cu")
		(net "P5E_CPU0_PE2_RX_DP<7>")
	)
	(segment
		(start 396.11173 -281.085036)
		(end 398.218406 -253.24562)
		(width 0.14732)
		(layer "In13.Cu")
		(net "P5E_CPU0_PE2_RX_DP<7>")
	)
	(segment
		(start 375.845578 -221.619826)
		(end 375.82475 -221.632018)
		(width 0.0889)
		(layer "In13.Cu")
		(net "P5E_CPU0_PE2_RX_DP<7>")
	)
	(segment
		(start 377.572778 -213.164166)
		(end 377.530868 -213.206076)
		(width 0.0889)
		(layer "In13.Cu")
		(net "P5E_CPU0_PE2_RX_DP<7>")
	)
	(segment
		(start 397.79194 -433.743354)
		(end 397.79194 -424.785028)
		(width 0.14732)
		(layer "In13.Cu")
		(net "P5E_CPU0_PE2_RX_DP<7>")
	)
	(segment
		(start 377.572778 -213.142068)
		(end 377.572778 -213.164166)
		(width 0.0889)
		(layer "In13.Cu")
		(net "P5E_CPU0_PE2_RX_DP<7>")
	)
	(segment
		(start 401.164044 -339.43036)
		(end 394.001244 -308.966362)
		(width 0.14732)
		(layer "In13.Cu")
		(net "P5E_CPU0_PE2_RX_DP<7>")
	)
	(segment
		(start 375.839482 -218.367864)
		(end 375.837958 -218.368626)
		(width 0.0889)
		(layer "In13.Cu")
		(net "P5E_CPU0_PE2_RX_DP<7>")
	)
	(segment
		(start 375.845578 -218.364308)
		(end 375.840244 -218.367356)
		(width 0.0889)
		(layer "In13.Cu")
		(net "P5E_CPU0_PE2_RX_DP<7>")
	)
	(segment
		(start 378.633482 -211.768944)
		(end 378.212858 -211.943188)
		(width 0.14732)
		(layer "In13.Cu")
		(net "P5E_CPU0_PE2_RX_DP<7>")
	)
	(segment
		(start 399.10131 -410.406342)
		(end 399.10131 -406.165558)
		(width 0.14732)
		(layer "In13.Cu")
		(net "P5E_CPU0_PE2_RX_DP<7>")
	)
	(segment
		(start 375.830592 -219.0115)
		(end 375.839482 -219.01658)
		(width 0.0889)
		(layer "In13.Cu")
		(net "P5E_CPU0_PE2_RX_DP<7>")
	)
	(segment
		(start 398.083532 -249.23877)
		(end 394.315188 -225.806508)
		(width 0.14732)
		(layer "In13.Cu")
		(net "P5E_CPU0_PE2_RX_DP<7>")
	)
	(segment
		(start 377.360688 -214.29218)
		(end 376.801634 -214.851234)
		(width 0.0889)
		(layer "In13.Cu")
		(net "P5E_CPU0_PE2_RX_DP<7>")
	)
	(segment
		(start 397.79194 -424.785028)
		(end 398.695164 -413.624776)
		(width 0.14732)
		(layer "In13.Cu")
		(net "P5E_CPU0_PE2_RX_DP<7>")
	)
	(segment
		(start 398.436084 -355.159056)
		(end 401.164044 -339.43036)
		(width 0.14732)
		(layer "In13.Cu")
		(net "P5E_CPU0_PE2_RX_DP<7>")
	)
	(segment
		(start 398.750028 -434.41366)
		(end 398.330166 -433.993798)
		(width 0.14732)
		(layer "In13.Cu")
		(net "P5E_CPU0_PE2_RX_DP<7>")
	)
	(segment
		(start 392.705336 -220.283786)
		(end 392.705336 -220.283532)
		(width 0.14732)
		(layer "In13.Cu")
		(net "P5E_CPU0_PE2_RX_DP<7>")
	)
	(segment
		(start 375.840244 -216.73947)
		(end 375.839482 -216.739978)
		(width 0.0889)
		(layer "In13.Cu")
		(net "P5E_CPU0_PE2_RX_DP<7>")
	)
	(segment
		(start 377.530868 -213.206076)
		(end 377.530868 -213.881462)
		(width 0.0889)
		(layer "In13.Cu")
		(net "P5E_CPU0_PE2_RX_DP<7>")
	)
	(segment
		(start 398.435322 -355.374702)
		(end 398.436084 -355.366066)
		(width 0.14732)
		(layer "In13.Cu")
		(net "P5E_CPU0_PE2_RX_DP<7>")
	)
	(segment
		(start 398.218406 -253.24562)
		(end 398.083532 -249.23877)
		(width 0.14732)
		(layer "In13.Cu")
		(net "P5E_CPU0_PE2_RX_DP<7>")
	)
	(arc
		(start 375.839482 -216.739978)
		(mid 375.704549 -216.873332)
		(end 375.652284 -217.0557)
		(width 0.0889)
		(layer "In13.Cu")
		(net "P5E_CPU0_PE2_RX_DP<7>")
	)
	(arc
		(start 376.122184 -221.133924)
		(mid 376.048193 -221.41349)
		(end 375.845578 -221.619826)
		(width 0.0889)
		(layer "In13.Cu")
		(net "P5E_CPU0_PE2_RX_DP<7>")
	)
	(arc
		(start 375.830592 -218.372944)
		(mid 375.651995 -218.692222)
		(end 375.830592 -219.0115)
		(width 0.0889)
		(layer "In13.Cu")
		(net "P5E_CPU0_PE2_RX_DP<7>")
	)
	(arc
		(start 375.352564 -221.660974)
		(mid 375.342493 -221.657005)
		(end 375.332498 -221.652846)
		(width 0.0889)
		(layer "In13.Cu")
		(net "P5E_CPU0_PE2_RX_DP<7>")
	)
	(arc
		(start 376.300746 -215.931242)
		(mid 376.169832 -216.067602)
		(end 376.122184 -216.25052)
		(width 0.0889)
		(layer "In13.Cu")
		(net "P5E_CPU0_PE2_RX_DP<7>")
	)
	(arc
		(start 376.59183 -215.452198)
		(mid 376.51246 -215.725932)
		(end 376.309636 -215.926162)
		(width 0.0889)
		(layer "In13.Cu")
		(net "P5E_CPU0_PE2_RX_DP<7>")
	)
	(arc
		(start 375.839482 -219.995496)
		(mid 375.704549 -220.12885)
		(end 375.652284 -220.311218)
		(width 0.0889)
		(layer "In13.Cu")
		(net "P5E_CPU0_PE2_RX_DP<7>")
	)
	(arc
		(start 376.122184 -217.878406)
		(mid 376.048193 -218.157972)
		(end 375.845578 -218.364308)
		(width 0.0889)
		(layer "In13.Cu")
		(net "P5E_CPU0_PE2_RX_DP<7>")
	)
	(arc
		(start 375.82475 -221.632018)
		(mid 375.591835 -221.698229)
		(end 375.352564 -221.660974)
		(width 0.0889)
		(layer "In13.Cu")
		(net "P5E_CPU0_PE2_RX_DP<7>")
	)
	(arc
		(start 375.652284 -220.32849)
		(mid 375.704554 -220.510855)
		(end 375.839482 -220.644212)
		(width 0.0889)
		(layer "In13.Cu")
		(net "P5E_CPU0_PE2_RX_DP<7>")
	)
	(arc
		(start 375.839482 -220.644212)
		(mid 376.042963 -220.845016)
		(end 376.122184 -221.1197)
		(width 0.0889)
		(layer "In13.Cu")
		(net "P5E_CPU0_PE2_RX_DP<7>")
	)
	(arc
		(start 376.122184 -216.25052)
		(mid 376.048193 -216.530086)
		(end 375.845578 -216.736422)
		(width 0.0889)
		(layer "In13.Cu")
		(net "P5E_CPU0_PE2_RX_DP<7>")
	)
	(arc
		(start 375.845578 -219.020136)
		(mid 376.122152 -219.506038)
		(end 375.845578 -219.99194)
		(width 0.0889)
		(layer "In13.Cu")
		(net "P5E_CPU0_PE2_RX_DP<7>")
	)
	(arc
		(start 375.839482 -217.388694)
		(mid 376.042963 -217.589498)
		(end 376.122184 -217.864182)
		(width 0.0889)
		(layer "In13.Cu")
		(net "P5E_CPU0_PE2_RX_DP<7>")
	)
	(arc
		(start 375.652284 -217.072972)
		(mid 375.704554 -217.255337)
		(end 375.839482 -217.388694)
		(width 0.0889)
		(layer "In13.Cu")
		(net "P5E_CPU0_PE2_RX_DP<7>")
	)
	(segment
		(start 374.61698 -221.669864)
		(end 374.61698 -221.134178)
		(width 0.13208)
		(layer "F.Cu")
		(net "P5E_CPU0_PE2_RX_DP<6>")
	)
	(segment
		(start 374.61698 -221.134178)
		(end 374.617234 -221.133924)
		(width 0.13208)
		(layer "F.Cu")
		(net "P5E_CPU0_PE2_RX_DP<6>")
	)
	(segment
		(start 374.896634 -219.997528)
		(end 374.891046 -220.000576)
		(width 0.0889)
		(layer "In13.Cu")
		(net "P5E_CPU0_PE2_RX_DP<6>")
	)
	(segment
		(start 400.750024 -435.489858)
		(end 400.750024 -435.423818)
		(width 0.14732)
		(layer "In13.Cu")
		(net "P5E_CPU0_PE2_RX_DP<6>")
	)
	(segment
		(start 376.59183 -213.731856)
		(end 376.325384 -214.374984)
		(width 0.0889)
		(layer "In13.Cu")
		(net "P5E_CPU0_PE2_RX_DP<6>")
	)
	(segment
		(start 400.076924 -434.993796)
		(end 399.791936 -434.708808)
		(width 0.14732)
		(layer "In13.Cu")
		(net "P5E_CPU0_PE2_RX_DP<6>")
	)
	(segment
		(start 379.54204 -210.744308)
		(end 379.42012 -210.622388)
		(width 0.14732)
		(layer "In13.Cu")
		(net "P5E_CPU0_PE2_RX_DP<6>")
	)
	(segment
		(start 400.81835 -400.502628)
		(end 400.520662 -397.808704)
		(width 0.14732)
		(layer "In13.Cu")
		(net "P5E_CPU0_PE2_RX_DP<6>")
	)
	(segment
		(start 380.53772 -210.622388)
		(end 380.10084 -210.622388)
		(width 0.14732)
		(layer "In13.Cu")
		(net "P5E_CPU0_PE2_RX_DP<6>")
	)
	(segment
		(start 376.59183 -213.206076)
		(end 376.59183 -213.731856)
		(width 0.0889)
		(layer "In13.Cu")
		(net "P5E_CPU0_PE2_RX_DP<6>")
	)
	(segment
		(start 374.712484 -220.319854)
		(end 374.712484 -220.334078)
		(width 0.0889)
		(layer "In13.Cu")
		(net "P5E_CPU0_PE2_RX_DP<6>")
	)
	(segment
		(start 379.42012 -210.622388)
		(end 378.900436 -210.622388)
		(width 0.14732)
		(layer "In13.Cu")
		(net "P5E_CPU0_PE2_RX_DP<6>")
	)
	(segment
		(start 400.520662 -397.808704)
		(end 399.18894 -368.671348)
		(width 0.14732)
		(layer "In13.Cu")
		(net "P5E_CPU0_PE2_RX_DP<6>")
	)
	(segment
		(start 374.899174 -219.996004)
		(end 374.896634 -219.997528)
		(width 0.0889)
		(layer "In13.Cu")
		(net "P5E_CPU0_PE2_RX_DP<6>")
	)
	(segment
		(start 380.10084 -210.622388)
		(end 379.97892 -210.744308)
		(width 0.14732)
		(layer "In13.Cu")
		(net "P5E_CPU0_PE2_RX_DP<6>")
	)
	(segment
		(start 394.965682 -308.624478)
		(end 399.16481 -253.340108)
		(width 0.14732)
		(layer "In13.Cu")
		(net "P5E_CPU0_PE2_RX_DP<6>")
	)
	(segment
		(start 400.750024 -435.423818)
		(end 400.320002 -434.993796)
		(width 0.14732)
		(layer "In13.Cu")
		(net "P5E_CPU0_PE2_RX_DP<6>")
	)
	(segment
		(start 376.325384 -214.374984)
		(end 375.768362 -214.932006)
		(width 0.0889)
		(layer "In13.Cu")
		(net "P5E_CPU0_PE2_RX_DP<6>")
	)
	(segment
		(start 374.898158 -219.015818)
		(end 374.899682 -219.01658)
		(width 0.0889)
		(layer "In13.Cu")
		(net "P5E_CPU0_PE2_RX_DP<6>")
	)
	(segment
		(start 374.899174 -216.740486)
		(end 374.896634 -216.74201)
		(width 0.0889)
		(layer "In13.Cu")
		(net "P5E_CPU0_PE2_RX_DP<6>")
	)
	(segment
		(start 402.16455 -410.674058)
		(end 402.16455 -406.165558)
		(width 0.14732)
		(layer "In13.Cu")
		(net "P5E_CPU0_PE2_RX_DP<6>")
	)
	(segment
		(start 377.732798 -211.106004)
		(end 376.834146 -212.004656)
		(width 0.14732)
		(layer "In13.Cu")
		(net "P5E_CPU0_PE2_RX_DP<6>")
	)
	(segment
		(start 399.18894 -368.671348)
		(end 399.796508 -353.538028)
		(width 0.14732)
		(layer "In13.Cu")
		(net "P5E_CPU0_PE2_RX_DP<6>")
	)
	(segment
		(start 374.896634 -216.74201)
		(end 374.891046 -216.745058)
		(width 0.0889)
		(layer "In13.Cu")
		(net "P5E_CPU0_PE2_RX_DP<6>")
	)
	(segment
		(start 376.63374 -212.488526)
		(end 376.63374 -213.142068)
		(width 0.14732)
		(layer "In13.Cu")
		(net "P5E_CPU0_PE2_RX_DP<6>")
	)
	(segment
		(start 380.65964 -210.744308)
		(end 380.53772 -210.622388)
		(width 0.14732)
		(layer "In13.Cu")
		(net "P5E_CPU0_PE2_RX_DP<6>")
	)
	(segment
		(start 375.768362 -214.932006)
		(end 375.652284 -215.212168)
		(width 0.0889)
		(layer "In13.Cu")
		(net "P5E_CPU0_PE2_RX_DP<6>")
	)
	(segment
		(start 383.549906 -210.622388)
		(end 381.21844 -210.622388)
		(width 0.14732)
		(layer "In13.Cu")
		(net "P5E_CPU0_PE2_RX_DP<6>")
	)
	(segment
		(start 400.320002 -434.993796)
		(end 400.076924 -434.993796)
		(width 0.14732)
		(layer "In13.Cu")
		(net "P5E_CPU0_PE2_RX_DP<6>")
	)
	(segment
		(start 399.791936 -424.070526)
		(end 401.41144 -413.968184)
		(width 0.14732)
		(layer "In13.Cu")
		(net "P5E_CPU0_PE2_RX_DP<6>")
	)
	(segment
		(start 399.016474 -248.92)
		(end 395.264894 -225.59264)
		(width 0.14732)
		(layer "In13.Cu")
		(net "P5E_CPU0_PE2_RX_DP<6>")
	)
	(segment
		(start 399.16481 -253.340108)
		(end 399.165064 -253.340108)
		(width 0.14732)
		(layer "In13.Cu")
		(net "P5E_CPU0_PE2_RX_DP<6>")
	)
	(segment
		(start 399.165064 -253.340108)
		(end 399.165064 -253.339854)
		(width 0.14732)
		(layer "In13.Cu")
		(net "P5E_CPU0_PE2_RX_DP<6>")
	)
	(segment
		(start 399.796508 -353.538028)
		(end 402.20011 -339.53831)
		(width 0.14732)
		(layer "In13.Cu")
		(net "P5E_CPU0_PE2_RX_DP<6>")
	)
	(segment
		(start 375.182384 -219.506038)
		(end 375.182384 -219.515944)
		(width 0.0889)
		(layer "In13.Cu")
		(net "P5E_CPU0_PE2_RX_DP<6>")
	)
	(segment
		(start 374.905778 -218.364308)
		(end 374.905524 -218.364562)
		(width 0.0889)
		(layer "In13.Cu")
		(net "P5E_CPU0_PE2_RX_DP<6>")
	)
	(segment
		(start 374.899936 -219.995496)
		(end 374.899174 -219.996004)
		(width 0.0889)
		(layer "In13.Cu")
		(net "P5E_CPU0_PE2_RX_DP<6>")
	)
	(segment
		(start 374.891046 -217.383614)
		(end 374.899936 -217.388694)
		(width 0.0889)
		(layer "In13.Cu")
		(net "P5E_CPU0_PE2_RX_DP<6>")
	)
	(segment
		(start 399.791936 -434.708808)
		(end 399.791936 -424.070526)
		(width 0.14732)
		(layer "In13.Cu")
		(net "P5E_CPU0_PE2_RX_DP<6>")
	)
	(segment
		(start 374.890792 -219.0115)
		(end 374.898158 -219.015818)
		(width 0.0889)
		(layer "In13.Cu")
		(net "P5E_CPU0_PE2_RX_DP<6>")
	)
	(segment
		(start 381.09652 -210.744308)
		(end 380.65964 -210.744308)
		(width 0.14732)
		(layer "In13.Cu")
		(net "P5E_CPU0_PE2_RX_DP<6>")
	)
	(segment
		(start 374.905524 -218.364562)
		(end 374.892824 -218.371674)
		(width 0.0889)
		(layer "In13.Cu")
		(net "P5E_CPU0_PE2_RX_DP<6>")
	)
	(segment
		(start 399.165064 -253.339854)
		(end 399.016474 -248.92)
		(width 0.14732)
		(layer "In13.Cu")
		(net "P5E_CPU0_PE2_RX_DP<6>")
	)
	(segment
		(start 374.46077 -220.862906)
		(end 374.617234 -221.133924)
		(width 0.0889)
		(layer "In13.Cu")
		(net "P5E_CPU0_PE2_RX_DP<6>")
	)
	(segment
		(start 375.652284 -215.212168)
		(end 375.652284 -215.44661)
		(width 0.0889)
		(layer "In13.Cu")
		(net "P5E_CPU0_PE2_RX_DP<6>")
	)
	(segment
		(start 395.264894 -225.59264)
		(end 391.95883 -214.250524)
		(width 0.14732)
		(layer "In13.Cu")
		(net "P5E_CPU0_PE2_RX_DP<6>")
	)
	(segment
		(start 400.81835 -404.819358)
		(end 400.81835 -400.502628)
		(width 0.14732)
		(layer "In13.Cu")
		(net "P5E_CPU0_PE2_RX_DP<6>")
	)
	(segment
		(start 381.21844 -210.622388)
		(end 381.09652 -210.744308)
		(width 0.14732)
		(layer "In13.Cu")
		(net "P5E_CPU0_PE2_RX_DP<6>")
	)
	(segment
		(start 402.20011 -339.53831)
		(end 394.965682 -308.624478)
		(width 0.14732)
		(layer "In13.Cu")
		(net "P5E_CPU0_PE2_RX_DP<6>")
	)
	(segment
		(start 402.16455 -406.165558)
		(end 400.81835 -404.819358)
		(width 0.14732)
		(layer "In13.Cu")
		(net "P5E_CPU0_PE2_RX_DP<6>")
	)
	(segment
		(start 374.902476 -219.018104)
		(end 374.905778 -219.020136)
		(width 0.0889)
		(layer "In13.Cu")
		(net "P5E_CPU0_PE2_RX_DP<6>")
	)
	(segment
		(start 374.899936 -216.739978)
		(end 374.899174 -216.740486)
		(width 0.0889)
		(layer "In13.Cu")
		(net "P5E_CPU0_PE2_RX_DP<6>")
	)
	(segment
		(start 401.41144 -413.968184)
		(end 402.16455 -410.674058)
		(width 0.14732)
		(layer "In13.Cu")
		(net "P5E_CPU0_PE2_RX_DP<6>")
	)
	(segment
		(start 374.4849 -220.773752)
		(end 374.46077 -220.862906)
		(width 0.0889)
		(layer "In13.Cu")
		(net "P5E_CPU0_PE2_RX_DP<6>")
	)
	(segment
		(start 391.95883 -214.250524)
		(end 389.612886 -211.90458)
		(width 0.14732)
		(layer "In13.Cu")
		(net "P5E_CPU0_PE2_RX_DP<6>")
	)
	(segment
		(start 389.612886 -211.90458)
		(end 389.25881 -211.757768)
		(width 0.14732)
		(layer "In13.Cu")
		(net "P5E_CPU0_PE2_RX_DP<6>")
	)
	(segment
		(start 378.900436 -210.622388)
		(end 377.732798 -211.106004)
		(width 0.14732)
		(layer "In13.Cu")
		(net "P5E_CPU0_PE2_RX_DP<6>")
	)
	(segment
		(start 376.834146 -212.004656)
		(end 376.63374 -212.488526)
		(width 0.14732)
		(layer "In13.Cu")
		(net "P5E_CPU0_PE2_RX_DP<6>")
	)
	(segment
		(start 389.25881 -211.757768)
		(end 383.549906 -210.622388)
		(width 0.14732)
		(layer "In13.Cu")
		(net "P5E_CPU0_PE2_RX_DP<6>")
	)
	(segment
		(start 375.182384 -217.859864)
		(end 375.182384 -217.878406)
		(width 0.0889)
		(layer "In13.Cu")
		(net "P5E_CPU0_PE2_RX_DP<6>")
	)
	(segment
		(start 375.182384 -216.25052)
		(end 375.182384 -216.260426)
		(width 0.0889)
		(layer "In13.Cu")
		(net "P5E_CPU0_PE2_RX_DP<6>")
	)
	(segment
		(start 379.97892 -210.744308)
		(end 379.54204 -210.744308)
		(width 0.14732)
		(layer "In13.Cu")
		(net "P5E_CPU0_PE2_RX_DP<6>")
	)
	(segment
		(start 376.63374 -213.164166)
		(end 376.59183 -213.206076)
		(width 0.0889)
		(layer "In13.Cu")
		(net "P5E_CPU0_PE2_RX_DP<6>")
	)
	(segment
		(start 374.899682 -219.01658)
		(end 374.902476 -219.018104)
		(width 0.0889)
		(layer "In13.Cu")
		(net "P5E_CPU0_PE2_RX_DP<6>")
	)
	(segment
		(start 375.369836 -215.926162)
		(end 375.360946 -215.931242)
		(width 0.0889)
		(layer "In13.Cu")
		(net "P5E_CPU0_PE2_RX_DP<6>")
	)
	(segment
		(start 376.63374 -213.142068)
		(end 376.63374 -213.164166)
		(width 0.0889)
		(layer "In13.Cu")
		(net "P5E_CPU0_PE2_RX_DP<6>")
	)
	(segment
		(start 374.892824 -218.371674)
		(end 374.890792 -218.372944)
		(width 0.0889)
		(layer "In13.Cu")
		(net "P5E_CPU0_PE2_RX_DP<6>")
	)
	(arc
		(start 374.899936 -217.388694)
		(mid 375.102222 -217.587675)
		(end 375.182384 -217.859864)
		(width 0.0889)
		(layer "In13.Cu")
		(net "P5E_CPU0_PE2_RX_DP<6>")
	)
	(arc
		(start 374.891046 -220.000576)
		(mid 374.760132 -220.136936)
		(end 374.712484 -220.319854)
		(width 0.0889)
		(layer "In13.Cu")
		(net "P5E_CPU0_PE2_RX_DP<6>")
	)
	(arc
		(start 375.652284 -215.44661)
		(mid 375.574173 -215.723559)
		(end 375.369836 -215.926162)
		(width 0.0889)
		(layer "In13.Cu")
		(net "P5E_CPU0_PE2_RX_DP<6>")
	)
	(arc
		(start 375.182384 -217.878406)
		(mid 375.108393 -218.157972)
		(end 374.905778 -218.364308)
		(width 0.0889)
		(layer "In13.Cu")
		(net "P5E_CPU0_PE2_RX_DP<6>")
	)
	(arc
		(start 375.182384 -216.260426)
		(mid 375.104273 -216.537375)
		(end 374.899936 -216.739978)
		(width 0.0889)
		(layer "In13.Cu")
		(net "P5E_CPU0_PE2_RX_DP<6>")
	)
	(arc
		(start 374.712484 -220.334078)
		(mid 374.654123 -220.570676)
		(end 374.501664 -220.760798)
		(width 0.0889)
		(layer "In13.Cu")
		(net "P5E_CPU0_PE2_RX_DP<6>")
	)
	(arc
		(start 374.891046 -216.745058)
		(mid 374.760132 -216.881418)
		(end 374.712484 -217.064336)
		(width 0.0889)
		(layer "In13.Cu")
		(net "P5E_CPU0_PE2_RX_DP<6>")
	)
	(arc
		(start 374.712484 -217.064336)
		(mid 374.760163 -217.247236)
		(end 374.891046 -217.383614)
		(width 0.0889)
		(layer "In13.Cu")
		(net "P5E_CPU0_PE2_RX_DP<6>")
	)
	(arc
		(start 375.182384 -219.515944)
		(mid 375.104273 -219.792893)
		(end 374.899936 -219.995496)
		(width 0.0889)
		(layer "In13.Cu")
		(net "P5E_CPU0_PE2_RX_DP<6>")
	)
	(arc
		(start 374.890792 -218.372944)
		(mid 374.712195 -218.692222)
		(end 374.890792 -219.0115)
		(width 0.0889)
		(layer "In13.Cu")
		(net "P5E_CPU0_PE2_RX_DP<6>")
	)
	(arc
		(start 375.360946 -215.931242)
		(mid 375.230032 -216.067602)
		(end 375.182384 -216.25052)
		(width 0.0889)
		(layer "In13.Cu")
		(net "P5E_CPU0_PE2_RX_DP<6>")
	)
	(arc
		(start 374.905778 -219.020136)
		(mid 375.108365 -219.226487)
		(end 375.182384 -219.506038)
		(width 0.0889)
		(layer "In13.Cu")
		(net "P5E_CPU0_PE2_RX_DP<6>")
	)
	(arc
		(start 374.501664 -220.760798)
		(mid 374.493342 -220.767353)
		(end 374.4849 -220.773752)
		(width 0.0889)
		(layer "In13.Cu")
		(net "P5E_CPU0_PE2_RX_DP<6>")
	)
	(segment
		(start 373.207534 -222.48368)
		(end 373.207534 -221.947994)
		(width 0.13208)
		(layer "F.Cu")
		(net "P5E_CPU0_PE2_RX_DP<5>")
	)
	(segment
		(start 373.207534 -221.947994)
		(end 373.20728 -221.94774)
		(width 0.13208)
		(layer "F.Cu")
		(net "P5E_CPU0_PE2_RX_DP<5>")
	)
	(segment
		(start 405.22779 -410.609288)
		(end 405.22779 -406.165558)
		(width 0.14732)
		(layer "In13.Cu")
		(net "P5E_CPU0_PE2_RX_DP<5>")
	)
	(segment
		(start 373.965724 -218.364562)
		(end 373.953024 -218.371674)
		(width 0.0889)
		(layer "In13.Cu")
		(net "P5E_CPU0_PE2_RX_DP<5>")
	)
	(segment
		(start 400.098768 -253.406402)
		(end 399.93824 -248.63425)
		(width 0.14732)
		(layer "In13.Cu")
		(net "P5E_CPU0_PE2_RX_DP<5>")
	)
	(segment
		(start 375.693178 -212.224112)
		(end 375.693178 -213.142068)
		(width 0.14732)
		(layer "In13.Cu")
		(net "P5E_CPU0_PE2_RX_DP<5>")
	)
	(segment
		(start 402.75002 -434.47208)
		(end 402.271738 -433.993798)
		(width 0.14732)
		(layer "In13.Cu")
		(net "P5E_CPU0_PE2_RX_DP<5>")
	)
	(segment
		(start 373.962676 -219.018104)
		(end 373.965978 -219.020136)
		(width 0.0889)
		(layer "In13.Cu")
		(net "P5E_CPU0_PE2_RX_DP<5>")
	)
	(segment
		(start 373.965978 -218.364308)
		(end 373.965724 -218.364562)
		(width 0.0889)
		(layer "In13.Cu")
		(net "P5E_CPU0_PE2_RX_DP<5>")
	)
	(segment
		(start 405.22779 -406.165558)
		(end 403.88159 -404.819358)
		(width 0.14732)
		(layer "In13.Cu")
		(net "P5E_CPU0_PE2_RX_DP<5>")
	)
	(segment
		(start 402.271738 -433.993798)
		(end 402.055584 -433.993798)
		(width 0.14732)
		(layer "In13.Cu")
		(net "P5E_CPU0_PE2_RX_DP<5>")
	)
	(segment
		(start 402.75002 -434.48986)
		(end 402.75002 -434.47208)
		(width 0.14732)
		(layer "In13.Cu")
		(net "P5E_CPU0_PE2_RX_DP<5>")
	)
	(segment
		(start 375.50852 -214.241888)
		(end 374.90273 -214.847678)
		(width 0.0889)
		(layer "In13.Cu")
		(net "P5E_CPU0_PE2_RX_DP<5>")
	)
	(segment
		(start 403.384004 -397.783812)
		(end 400.522948 -368.786664)
		(width 0.14732)
		(layer "In13.Cu")
		(net "P5E_CPU0_PE2_RX_DP<5>")
	)
	(segment
		(start 374.90273 -214.847678)
		(end 374.71223 -215.307418)
		(width 0.0889)
		(layer "In13.Cu")
		(net "P5E_CPU0_PE2_RX_DP<5>")
	)
	(segment
		(start 376.056398 -211.347304)
		(end 375.693178 -212.224112)
		(width 0.14732)
		(layer "In13.Cu")
		(net "P5E_CPU0_PE2_RX_DP<5>")
	)
	(segment
		(start 399.93824 -248.63425)
		(end 396.198852 -225.382328)
		(width 0.14732)
		(layer "In13.Cu")
		(net "P5E_CPU0_PE2_RX_DP<5>")
	)
	(segment
		(start 373.965978 -216.736422)
		(end 373.960644 -216.73947)
		(width 0.0889)
		(layer "In13.Cu")
		(net "P5E_CPU0_PE2_RX_DP<5>")
	)
	(segment
		(start 395.92123 -308.498494)
		(end 400.098514 -253.406402)
		(width 0.14732)
		(layer "In13.Cu")
		(net "P5E_CPU0_PE2_RX_DP<5>")
	)
	(segment
		(start 401.791932 -433.730146)
		(end 401.791932 -424.769788)
		(width 0.14732)
		(layer "In13.Cu")
		(net "P5E_CPU0_PE2_RX_DP<5>")
	)
	(segment
		(start 374.71223 -215.437212)
		(end 374.71223 -215.452198)
		(width 0.0889)
		(layer "In13.Cu")
		(net "P5E_CPU0_PE2_RX_DP<5>")
	)
	(segment
		(start 392.807698 -213.748112)
		(end 390.199626 -211.139786)
		(width 0.14732)
		(layer "In13.Cu")
		(net "P5E_CPU0_PE2_RX_DP<5>")
	)
	(segment
		(start 375.651268 -213.206076)
		(end 375.651268 -213.89721)
		(width 0.0889)
		(layer "In13.Cu")
		(net "P5E_CPU0_PE2_RX_DP<5>")
	)
	(segment
		(start 401.791932 -424.769788)
		(end 404.461218 -413.527748)
		(width 0.14732)
		(layer "In13.Cu")
		(net "P5E_CPU0_PE2_RX_DP<5>")
	)
	(segment
		(start 396.198852 -225.382328)
		(end 392.807698 -213.748112)
		(width 0.14732)
		(layer "In13.Cu")
		(net "P5E_CPU0_PE2_RX_DP<5>")
	)
	(segment
		(start 373.772684 -220.311218)
		(end 373.772684 -220.32849)
		(width 0.0889)
		(layer "In13.Cu")
		(net "P5E_CPU0_PE2_RX_DP<5>")
	)
	(segment
		(start 375.693178 -213.164166)
		(end 375.651268 -213.206076)
		(width 0.0889)
		(layer "In13.Cu")
		(net "P5E_CPU0_PE2_RX_DP<5>")
	)
	(segment
		(start 375.693178 -213.142068)
		(end 375.693178 -213.164166)
		(width 0.0889)
		(layer "In13.Cu")
		(net "P5E_CPU0_PE2_RX_DP<5>")
	)
	(segment
		(start 374.430036 -215.926162)
		(end 374.421146 -215.931242)
		(width 0.0889)
		(layer "In13.Cu")
		(net "P5E_CPU0_PE2_RX_DP<5>")
	)
	(segment
		(start 374.71223 -215.307418)
		(end 374.71223 -215.436704)
		(width 0.0889)
		(layer "In13.Cu")
		(net "P5E_CPU0_PE2_RX_DP<5>")
	)
	(segment
		(start 403.88159 -400.502628)
		(end 403.384004 -397.783812)
		(width 0.14732)
		(layer "In13.Cu")
		(net "P5E_CPU0_PE2_RX_DP<5>")
	)
	(segment
		(start 403.88159 -404.819358)
		(end 403.88159 -400.502628)
		(width 0.14732)
		(layer "In13.Cu")
		(net "P5E_CPU0_PE2_RX_DP<5>")
	)
	(segment
		(start 403.166072 -339.56752)
		(end 395.92123 -308.498494)
		(width 0.14732)
		(layer "In13.Cu")
		(net "P5E_CPU0_PE2_RX_DP<5>")
	)
	(segment
		(start 373.965978 -221.619826)
		(end 373.94515 -221.632018)
		(width 0.0889)
		(layer "In13.Cu")
		(net "P5E_CPU0_PE2_RX_DP<5>")
	)
	(segment
		(start 373.960644 -219.994988)
		(end 373.959882 -219.995496)
		(width 0.0889)
		(layer "In13.Cu")
		(net "P5E_CPU0_PE2_RX_DP<5>")
	)
	(segment
		(start 373.452898 -221.652846)
		(end 373.363744 -221.676722)
		(width 0.0889)
		(layer "In13.Cu")
		(net "P5E_CPU0_PE2_RX_DP<5>")
	)
	(segment
		(start 374.242584 -221.1197)
		(end 374.242584 -221.133924)
		(width 0.0889)
		(layer "In13.Cu")
		(net "P5E_CPU0_PE2_RX_DP<5>")
	)
	(segment
		(start 373.960644 -216.73947)
		(end 373.959882 -216.739978)
		(width 0.0889)
		(layer "In13.Cu")
		(net "P5E_CPU0_PE2_RX_DP<5>")
	)
	(segment
		(start 377.030488 -210.373214)
		(end 376.056398 -211.347304)
		(width 0.14732)
		(layer "In13.Cu")
		(net "P5E_CPU0_PE2_RX_DP<5>")
	)
	(segment
		(start 404.461218 -413.527748)
		(end 405.22779 -410.609288)
		(width 0.14732)
		(layer "In13.Cu")
		(net "P5E_CPU0_PE2_RX_DP<5>")
	)
	(segment
		(start 378.67336 -209.692748)
		(end 377.030488 -210.373214)
		(width 0.14732)
		(layer "In13.Cu")
		(net "P5E_CPU0_PE2_RX_DP<5>")
	)
	(segment
		(start 373.950992 -219.0115)
		(end 373.958358 -219.015818)
		(width 0.0889)
		(layer "In13.Cu")
		(net "P5E_CPU0_PE2_RX_DP<5>")
	)
	(segment
		(start 374.242584 -217.864182)
		(end 374.242584 -217.878406)
		(width 0.0889)
		(layer "In13.Cu")
		(net "P5E_CPU0_PE2_RX_DP<5>")
	)
	(segment
		(start 390.199626 -211.139786)
		(end 389.405368 -210.810856)
		(width 0.14732)
		(layer "In13.Cu")
		(net "P5E_CPU0_PE2_RX_DP<5>")
	)
	(segment
		(start 400.522948 -368.786664)
		(end 401.017994 -351.951544)
		(width 0.14732)
		(layer "In13.Cu")
		(net "P5E_CPU0_PE2_RX_DP<5>")
	)
	(segment
		(start 383.784094 -209.692748)
		(end 378.67336 -209.692748)
		(width 0.14732)
		(layer "In13.Cu")
		(net "P5E_CPU0_PE2_RX_DP<5>")
	)
	(segment
		(start 400.098514 -253.406402)
		(end 400.098768 -253.406402)
		(width 0.14732)
		(layer "In13.Cu")
		(net "P5E_CPU0_PE2_RX_DP<5>")
	)
	(segment
		(start 373.959882 -219.01658)
		(end 373.962676 -219.018104)
		(width 0.0889)
		(layer "In13.Cu")
		(net "P5E_CPU0_PE2_RX_DP<5>")
	)
	(segment
		(start 401.017994 -351.951544)
		(end 403.166072 -339.56752)
		(width 0.14732)
		(layer "In13.Cu")
		(net "P5E_CPU0_PE2_RX_DP<5>")
	)
	(segment
		(start 373.772684 -217.0557)
		(end 373.772684 -217.072972)
		(width 0.0889)
		(layer "In13.Cu")
		(net "P5E_CPU0_PE2_RX_DP<5>")
	)
	(segment
		(start 373.363744 -221.676722)
		(end 373.20728 -221.94774)
		(width 0.0889)
		(layer "In13.Cu")
		(net "P5E_CPU0_PE2_RX_DP<5>")
	)
	(segment
		(start 402.055584 -433.993798)
		(end 401.791932 -433.730146)
		(width 0.14732)
		(layer "In13.Cu")
		(net "P5E_CPU0_PE2_RX_DP<5>")
	)
	(segment
		(start 389.405368 -210.810856)
		(end 383.784094 -209.692748)
		(width 0.14732)
		(layer "In13.Cu")
		(net "P5E_CPU0_PE2_RX_DP<5>")
	)
	(segment
		(start 373.953024 -218.371674)
		(end 373.950992 -218.372944)
		(width 0.0889)
		(layer "In13.Cu")
		(net "P5E_CPU0_PE2_RX_DP<5>")
	)
	(segment
		(start 373.965978 -219.99194)
		(end 373.960644 -219.994988)
		(width 0.0889)
		(layer "In13.Cu")
		(net "P5E_CPU0_PE2_RX_DP<5>")
	)
	(segment
		(start 373.958358 -219.015818)
		(end 373.959882 -219.01658)
		(width 0.0889)
		(layer "In13.Cu")
		(net "P5E_CPU0_PE2_RX_DP<5>")
	)
	(segment
		(start 375.651268 -213.89721)
		(end 375.50852 -214.241888)
		(width 0.0889)
		(layer "In13.Cu")
		(net "P5E_CPU0_PE2_RX_DP<5>")
	)
	(arc
		(start 373.772684 -220.32849)
		(mid 373.824954 -220.510855)
		(end 373.959882 -220.644212)
		(width 0.0889)
		(layer "In13.Cu")
		(net "P5E_CPU0_PE2_RX_DP<5>")
	)
	(arc
		(start 373.472964 -221.660974)
		(mid 373.462893 -221.657005)
		(end 373.452898 -221.652846)
		(width 0.0889)
		(layer "In13.Cu")
		(net "P5E_CPU0_PE2_RX_DP<5>")
	)
	(arc
		(start 373.959882 -216.739978)
		(mid 373.824949 -216.873332)
		(end 373.772684 -217.0557)
		(width 0.0889)
		(layer "In13.Cu")
		(net "P5E_CPU0_PE2_RX_DP<5>")
	)
	(arc
		(start 374.242584 -216.25052)
		(mid 374.168593 -216.530086)
		(end 373.965978 -216.736422)
		(width 0.0889)
		(layer "In13.Cu")
		(net "P5E_CPU0_PE2_RX_DP<5>")
	)
	(arc
		(start 374.421146 -215.931242)
		(mid 374.290232 -216.067602)
		(end 374.242584 -216.25052)
		(width 0.0889)
		(layer "In13.Cu")
		(net "P5E_CPU0_PE2_RX_DP<5>")
	)
	(arc
		(start 373.772684 -217.072972)
		(mid 373.824954 -217.255337)
		(end 373.959882 -217.388694)
		(width 0.0889)
		(layer "In13.Cu")
		(net "P5E_CPU0_PE2_RX_DP<5>")
	)
	(arc
		(start 374.71223 -215.436704)
		(mid 374.71223 -215.436958)
		(end 374.71223 -215.437212)
		(width 0.0889)
		(layer "In13.Cu")
		(net "P5E_CPU0_PE2_RX_DP<5>")
	)
	(arc
		(start 374.71223 -215.452198)
		(mid 374.63286 -215.725932)
		(end 374.430036 -215.926162)
		(width 0.0889)
		(layer "In13.Cu")
		(net "P5E_CPU0_PE2_RX_DP<5>")
	)
	(arc
		(start 373.959882 -217.388694)
		(mid 374.163363 -217.589498)
		(end 374.242584 -217.864182)
		(width 0.0889)
		(layer "In13.Cu")
		(net "P5E_CPU0_PE2_RX_DP<5>")
	)
	(arc
		(start 374.242584 -217.878406)
		(mid 374.168593 -218.157972)
		(end 373.965978 -218.364308)
		(width 0.0889)
		(layer "In13.Cu")
		(net "P5E_CPU0_PE2_RX_DP<5>")
	)
	(arc
		(start 373.950992 -218.372944)
		(mid 373.772395 -218.692222)
		(end 373.950992 -219.0115)
		(width 0.0889)
		(layer "In13.Cu")
		(net "P5E_CPU0_PE2_RX_DP<5>")
	)
	(arc
		(start 373.965978 -219.020136)
		(mid 374.242552 -219.506038)
		(end 373.965978 -219.99194)
		(width 0.0889)
		(layer "In13.Cu")
		(net "P5E_CPU0_PE2_RX_DP<5>")
	)
	(arc
		(start 373.94515 -221.632018)
		(mid 373.712235 -221.698229)
		(end 373.472964 -221.660974)
		(width 0.0889)
		(layer "In13.Cu")
		(net "P5E_CPU0_PE2_RX_DP<5>")
	)
	(arc
		(start 374.242584 -221.133924)
		(mid 374.168593 -221.41349)
		(end 373.965978 -221.619826)
		(width 0.0889)
		(layer "In13.Cu")
		(net "P5E_CPU0_PE2_RX_DP<5>")
	)
	(arc
		(start 373.959882 -219.995496)
		(mid 373.824949 -220.12885)
		(end 373.772684 -220.311218)
		(width 0.0889)
		(layer "In13.Cu")
		(net "P5E_CPU0_PE2_RX_DP<5>")
	)
	(arc
		(start 373.959882 -220.644212)
		(mid 374.163363 -220.845016)
		(end 374.242584 -221.1197)
		(width 0.0889)
		(layer "In13.Cu")
		(net "P5E_CPU0_PE2_RX_DP<5>")
	)
	(segment
		(start 372.73738 -221.669864)
		(end 372.73738 -221.134178)
		(width 0.13208)
		(layer "F.Cu")
		(net "P5E_CPU0_PE2_RX_DP<4>")
	)
	(segment
		(start 372.73738 -221.134178)
		(end 372.737634 -221.133924)
		(width 0.13208)
		(layer "F.Cu")
		(net "P5E_CPU0_PE2_RX_DP<4>")
	)
	(segment
		(start 396.893796 -308.176676)
		(end 401.030186 -253.435612)
		(width 0.14732)
		(layer "In13.Cu")
		(net "P5E_CPU0_PE2_RX_DP<4>")
	)
	(segment
		(start 376.40387 -209.615532)
		(end 375.24563 -210.773772)
		(width 0.14732)
		(layer "In13.Cu")
		(net "P5E_CPU0_PE2_RX_DP<4>")
	)
	(segment
		(start 404.330154 -434.993796)
		(end 404.076916 -434.993796)
		(width 0.14732)
		(layer "In13.Cu")
		(net "P5E_CPU0_PE2_RX_DP<4>")
	)
	(segment
		(start 401.030186 -253.435612)
		(end 400.858228 -248.316496)
		(width 0.14732)
		(layer "In13.Cu")
		(net "P5E_CPU0_PE2_RX_DP<4>")
	)
	(segment
		(start 404.21687 -339.592666)
		(end 396.893796 -308.176676)
		(width 0.14732)
		(layer "In13.Cu")
		(net "P5E_CPU0_PE2_RX_DP<4>")
	)
	(segment
		(start 389.142478 -209.67319)
		(end 388.998968 -209.768948)
		(width 0.14732)
		(layer "In13.Cu")
		(net "P5E_CPU0_PE2_RX_DP<4>")
	)
	(segment
		(start 404.750016 -435.489858)
		(end 404.750016 -435.413658)
		(width 0.14732)
		(layer "In13.Cu")
		(net "P5E_CPU0_PE2_RX_DP<4>")
	)
	(segment
		(start 404.076916 -434.993796)
		(end 403.791928 -434.708808)
		(width 0.14732)
		(layer "In13.Cu")
		(net "P5E_CPU0_PE2_RX_DP<4>")
	)
	(segment
		(start 406.94483 -400.502628)
		(end 406.315418 -397.780002)
		(width 0.14732)
		(layer "In13.Cu")
		(net "P5E_CPU0_PE2_RX_DP<4>")
	)
	(segment
		(start 407.320496 -413.352996)
		(end 408.29103 -410.943552)
		(width 0.14732)
		(layer "In13.Cu")
		(net "P5E_CPU0_PE2_RX_DP<4>")
	)
	(segment
		(start 373.018558 -219.015818)
		(end 373.020082 -219.01658)
		(width 0.0889)
		(layer "In13.Cu")
		(net "P5E_CPU0_PE2_RX_DP<4>")
	)
	(segment
		(start 374.75414 -213.164166)
		(end 374.71223 -213.206076)
		(width 0.0889)
		(layer "In13.Cu")
		(net "P5E_CPU0_PE2_RX_DP<4>")
	)
	(segment
		(start 373.017034 -216.74201)
		(end 373.011446 -216.745058)
		(width 0.0889)
		(layer "In13.Cu")
		(net "P5E_CPU0_PE2_RX_DP<4>")
	)
	(segment
		(start 373.011446 -217.383614)
		(end 373.020336 -217.388694)
		(width 0.0889)
		(layer "In13.Cu")
		(net "P5E_CPU0_PE2_RX_DP<4>")
	)
	(segment
		(start 373.888 -215.029542)
		(end 373.772684 -215.307164)
		(width 0.0889)
		(layer "In13.Cu")
		(net "P5E_CPU0_PE2_RX_DP<4>")
	)
	(segment
		(start 387.473952 -209.465672)
		(end 387.378194 -209.321908)
		(width 0.14732)
		(layer "In13.Cu")
		(net "P5E_CPU0_PE2_RX_DP<4>")
	)
	(segment
		(start 372.58117 -220.862906)
		(end 372.737634 -221.133924)
		(width 0.0889)
		(layer "In13.Cu")
		(net "P5E_CPU0_PE2_RX_DP<4>")
	)
	(segment
		(start 373.017034 -219.997528)
		(end 373.011446 -220.000576)
		(width 0.0889)
		(layer "In13.Cu")
		(net "P5E_CPU0_PE2_RX_DP<4>")
	)
	(segment
		(start 372.6053 -220.773752)
		(end 372.58117 -220.862906)
		(width 0.0889)
		(layer "In13.Cu")
		(net "P5E_CPU0_PE2_RX_DP<4>")
	)
	(segment
		(start 402.311108 -350.171258)
		(end 404.21687 -339.592666)
		(width 0.14732)
		(layer "In13.Cu")
		(net "P5E_CPU0_PE2_RX_DP<4>")
	)
	(segment
		(start 388.570216 -209.683604)
		(end 388.474458 -209.540094)
		(width 0.14732)
		(layer "In13.Cu")
		(net "P5E_CPU0_PE2_RX_DP<4>")
	)
	(segment
		(start 378.461778 -208.763108)
		(end 376.40387 -209.615532)
		(width 0.14732)
		(layer "In13.Cu")
		(net "P5E_CPU0_PE2_RX_DP<4>")
	)
	(segment
		(start 373.011192 -219.0115)
		(end 373.018558 -219.015818)
		(width 0.0889)
		(layer "In13.Cu")
		(net "P5E_CPU0_PE2_RX_DP<4>")
	)
	(segment
		(start 375.24563 -210.773772)
		(end 374.75414 -211.960206)
		(width 0.14732)
		(layer "In13.Cu")
		(net "P5E_CPU0_PE2_RX_DP<4>")
	)
	(segment
		(start 374.71223 -213.206076)
		(end 374.71223 -213.890606)
		(width 0.0889)
		(layer "In13.Cu")
		(net "P5E_CPU0_PE2_RX_DP<4>")
	)
	(segment
		(start 373.302784 -219.506038)
		(end 373.302784 -219.515944)
		(width 0.0889)
		(layer "In13.Cu")
		(net "P5E_CPU0_PE2_RX_DP<4>")
	)
	(segment
		(start 387.902704 -209.550762)
		(end 387.473952 -209.465672)
		(width 0.14732)
		(layer "In13.Cu")
		(net "P5E_CPU0_PE2_RX_DP<4>")
	)
	(segment
		(start 402.28393 -371.507512)
		(end 401.944078 -366.27689)
		(width 0.14732)
		(layer "In13.Cu")
		(net "P5E_CPU0_PE2_RX_DP<4>")
	)
	(segment
		(start 373.020844 -218.367356)
		(end 373.011192 -218.372944)
		(width 0.0889)
		(layer "In13.Cu")
		(net "P5E_CPU0_PE2_RX_DP<4>")
	)
	(segment
		(start 373.020336 -216.739978)
		(end 373.019574 -216.740486)
		(width 0.0889)
		(layer "In13.Cu")
		(net "P5E_CPU0_PE2_RX_DP<4>")
	)
	(segment
		(start 400.858228 -248.316496)
		(end 397.375888 -225.245168)
		(width 0.14732)
		(layer "In13.Cu")
		(net "P5E_CPU0_PE2_RX_DP<4>")
	)
	(segment
		(start 374.75414 -213.142068)
		(end 374.75414 -213.164166)
		(width 0.0889)
		(layer "In13.Cu")
		(net "P5E_CPU0_PE2_RX_DP<4>")
	)
	(segment
		(start 374.75414 -211.960206)
		(end 374.75414 -213.142068)
		(width 0.14732)
		(layer "In13.Cu")
		(net "P5E_CPU0_PE2_RX_DP<4>")
	)
	(segment
		(start 388.998968 -209.768948)
		(end 388.570216 -209.683604)
		(width 0.14732)
		(layer "In13.Cu")
		(net "P5E_CPU0_PE2_RX_DP<4>")
	)
	(segment
		(start 393.964922 -213.503256)
		(end 390.680194 -210.217766)
		(width 0.14732)
		(layer "In13.Cu")
		(net "P5E_CPU0_PE2_RX_DP<4>")
	)
	(segment
		(start 384.568192 -208.763108)
		(end 378.461778 -208.763108)
		(width 0.14732)
		(layer "In13.Cu")
		(net "P5E_CPU0_PE2_RX_DP<4>")
	)
	(segment
		(start 406.315418 -397.780002)
		(end 402.28393 -371.507512)
		(width 0.14732)
		(layer "In13.Cu")
		(net "P5E_CPU0_PE2_RX_DP<4>")
	)
	(segment
		(start 373.026178 -218.364308)
		(end 373.020844 -218.367356)
		(width 0.0889)
		(layer "In13.Cu")
		(net "P5E_CPU0_PE2_RX_DP<4>")
	)
	(segment
		(start 373.302784 -216.25052)
		(end 373.302784 -216.260426)
		(width 0.0889)
		(layer "In13.Cu")
		(net "P5E_CPU0_PE2_RX_DP<4>")
	)
	(segment
		(start 387.378194 -209.322162)
		(end 384.568192 -208.763108)
		(width 0.14732)
		(layer "In13.Cu")
		(net "P5E_CPU0_PE2_RX_DP<4>")
	)
	(segment
		(start 397.375888 -225.245168)
		(end 393.964922 -213.503256)
		(width 0.14732)
		(layer "In13.Cu")
		(net "P5E_CPU0_PE2_RX_DP<4>")
	)
	(segment
		(start 404.750016 -435.413658)
		(end 404.330154 -434.993796)
		(width 0.14732)
		(layer "In13.Cu")
		(net "P5E_CPU0_PE2_RX_DP<4>")
	)
	(segment
		(start 372.832884 -220.319854)
		(end 372.832884 -220.334078)
		(width 0.0889)
		(layer "In13.Cu")
		(net "P5E_CPU0_PE2_RX_DP<4>")
	)
	(segment
		(start 373.020336 -219.995496)
		(end 373.019574 -219.996004)
		(width 0.0889)
		(layer "In13.Cu")
		(net "P5E_CPU0_PE2_RX_DP<4>")
	)
	(segment
		(start 388.474458 -209.540094)
		(end 388.046214 -209.455004)
		(width 0.14732)
		(layer "In13.Cu")
		(net "P5E_CPU0_PE2_RX_DP<4>")
	)
	(segment
		(start 374.71223 -213.890606)
		(end 374.489726 -214.427562)
		(width 0.0889)
		(layer "In13.Cu")
		(net "P5E_CPU0_PE2_RX_DP<4>")
	)
	(segment
		(start 406.94483 -404.819358)
		(end 406.94483 -400.502628)
		(width 0.14732)
		(layer "In13.Cu")
		(net "P5E_CPU0_PE2_RX_DP<4>")
	)
	(segment
		(start 401.944078 -366.27689)
		(end 402.311108 -350.171258)
		(width 0.14732)
		(layer "In13.Cu")
		(net "P5E_CPU0_PE2_RX_DP<4>")
	)
	(segment
		(start 374.489726 -214.427562)
		(end 373.888 -215.029542)
		(width 0.0889)
		(layer "In13.Cu")
		(net "P5E_CPU0_PE2_RX_DP<4>")
	)
	(segment
		(start 387.378194 -209.321908)
		(end 387.378194 -209.322162)
		(width 0.14732)
		(layer "In13.Cu")
		(net "P5E_CPU0_PE2_RX_DP<4>")
	)
	(segment
		(start 390.680194 -210.217766)
		(end 389.570468 -209.75828)
		(width 0.14732)
		(layer "In13.Cu")
		(net "P5E_CPU0_PE2_RX_DP<4>")
	)
	(segment
		(start 373.019574 -219.996004)
		(end 373.017034 -219.997528)
		(width 0.0889)
		(layer "In13.Cu")
		(net "P5E_CPU0_PE2_RX_DP<4>")
	)
	(segment
		(start 373.490236 -215.926162)
		(end 373.481346 -215.931242)
		(width 0.0889)
		(layer "In13.Cu")
		(net "P5E_CPU0_PE2_RX_DP<4>")
	)
	(segment
		(start 388.046214 -209.455004)
		(end 387.902704 -209.550762)
		(width 0.14732)
		(layer "In13.Cu")
		(net "P5E_CPU0_PE2_RX_DP<4>")
	)
	(segment
		(start 403.791928 -434.708808)
		(end 403.791928 -424.584368)
		(width 0.14732)
		(layer "In13.Cu")
		(net "P5E_CPU0_PE2_RX_DP<4>")
	)
	(segment
		(start 373.019574 -216.740486)
		(end 373.017034 -216.74201)
		(width 0.0889)
		(layer "In13.Cu")
		(net "P5E_CPU0_PE2_RX_DP<4>")
	)
	(segment
		(start 408.29103 -406.165558)
		(end 406.94483 -404.819358)
		(width 0.14732)
		(layer "In13.Cu")
		(net "P5E_CPU0_PE2_RX_DP<4>")
	)
	(segment
		(start 403.791928 -424.584368)
		(end 407.320496 -413.352996)
		(width 0.14732)
		(layer "In13.Cu")
		(net "P5E_CPU0_PE2_RX_DP<4>")
	)
	(segment
		(start 373.020082 -219.01658)
		(end 373.022876 -219.018104)
		(width 0.0889)
		(layer "In13.Cu")
		(net "P5E_CPU0_PE2_RX_DP<4>")
	)
	(segment
		(start 389.570468 -209.75828)
		(end 389.142478 -209.67319)
		(width 0.14732)
		(layer "In13.Cu")
		(net "P5E_CPU0_PE2_RX_DP<4>")
	)
	(segment
		(start 408.29103 -410.943552)
		(end 408.29103 -406.165558)
		(width 0.14732)
		(layer "In13.Cu")
		(net "P5E_CPU0_PE2_RX_DP<4>")
	)
	(segment
		(start 373.772684 -215.307164)
		(end 373.772684 -215.44661)
		(width 0.0889)
		(layer "In13.Cu")
		(net "P5E_CPU0_PE2_RX_DP<4>")
	)
	(segment
		(start 373.022876 -219.018104)
		(end 373.026178 -219.020136)
		(width 0.0889)
		(layer "In13.Cu")
		(net "P5E_CPU0_PE2_RX_DP<4>")
	)
	(arc
		(start 373.302784 -216.260426)
		(mid 373.224673 -216.537375)
		(end 373.020336 -216.739978)
		(width 0.0889)
		(layer "In13.Cu")
		(net "P5E_CPU0_PE2_RX_DP<4>")
	)
	(arc
		(start 372.832884 -217.064336)
		(mid 372.880563 -217.247236)
		(end 373.011446 -217.383614)
		(width 0.0889)
		(layer "In13.Cu")
		(net "P5E_CPU0_PE2_RX_DP<4>")
	)
	(arc
		(start 372.622064 -220.760798)
		(mid 372.613742 -220.767353)
		(end 372.6053 -220.773752)
		(width 0.0889)
		(layer "In13.Cu")
		(net "P5E_CPU0_PE2_RX_DP<4>")
	)
	(arc
		(start 373.020336 -217.388694)
		(mid 373.302985 -217.874797)
		(end 373.026178 -218.364308)
		(width 0.0889)
		(layer "In13.Cu")
		(net "P5E_CPU0_PE2_RX_DP<4>")
	)
	(arc
		(start 373.481346 -215.931242)
		(mid 373.350432 -216.067602)
		(end 373.302784 -216.25052)
		(width 0.0889)
		(layer "In13.Cu")
		(net "P5E_CPU0_PE2_RX_DP<4>")
	)
	(arc
		(start 373.302784 -219.515944)
		(mid 373.224673 -219.792893)
		(end 373.020336 -219.995496)
		(width 0.0889)
		(layer "In13.Cu")
		(net "P5E_CPU0_PE2_RX_DP<4>")
	)
	(arc
		(start 373.011192 -218.372944)
		(mid 372.832595 -218.692222)
		(end 373.011192 -219.0115)
		(width 0.0889)
		(layer "In13.Cu")
		(net "P5E_CPU0_PE2_RX_DP<4>")
	)
	(arc
		(start 373.011446 -220.000576)
		(mid 372.880532 -220.136936)
		(end 372.832884 -220.319854)
		(width 0.0889)
		(layer "In13.Cu")
		(net "P5E_CPU0_PE2_RX_DP<4>")
	)
	(arc
		(start 373.026178 -219.020136)
		(mid 373.228765 -219.226487)
		(end 373.302784 -219.506038)
		(width 0.0889)
		(layer "In13.Cu")
		(net "P5E_CPU0_PE2_RX_DP<4>")
	)
	(arc
		(start 373.011446 -216.745058)
		(mid 372.880532 -216.881418)
		(end 372.832884 -217.064336)
		(width 0.0889)
		(layer "In13.Cu")
		(net "P5E_CPU0_PE2_RX_DP<4>")
	)
	(arc
		(start 372.832884 -220.334078)
		(mid 372.774523 -220.570676)
		(end 372.622064 -220.760798)
		(width 0.0889)
		(layer "In13.Cu")
		(net "P5E_CPU0_PE2_RX_DP<4>")
	)
	(arc
		(start 373.772684 -215.44661)
		(mid 373.694573 -215.723559)
		(end 373.490236 -215.926162)
		(width 0.0889)
		(layer "In13.Cu")
		(net "P5E_CPU0_PE2_RX_DP<4>")
	)
	(segment
		(start 371.327934 -221.947994)
		(end 371.32768 -221.94774)
		(width 0.13208)
		(layer "F.Cu")
		(net "P5E_CPU0_PE2_RX_DP<3>")
	)
	(segment
		(start 371.327934 -222.48368)
		(end 371.327934 -221.947994)
		(width 0.13208)
		(layer "F.Cu")
		(net "P5E_CPU0_PE2_RX_DP<3>")
	)
	(segment
		(start 390.345168 -208.665826)
		(end 390.002014 -208.394808)
		(width 0.14732)
		(layer "In13.Cu")
		(net "P5E_CPU0_PE2_RX_DP<3>")
	)
	(segment
		(start 372.071392 -219.0115)
		(end 372.078758 -219.015818)
		(width 0.0889)
		(layer "In13.Cu")
		(net "P5E_CPU0_PE2_RX_DP<3>")
	)
	(segment
		(start 372.080282 -219.01658)
		(end 372.083076 -219.018104)
		(width 0.0889)
		(layer "In13.Cu")
		(net "P5E_CPU0_PE2_RX_DP<3>")
	)
	(segment
		(start 373.571262 -214.339932)
		(end 373.006366 -214.904828)
		(width 0.0889)
		(layer "In13.Cu")
		(net "P5E_CPU0_PE2_RX_DP<3>")
	)
	(segment
		(start 394.838174 -213.04631)
		(end 390.85901 -208.916524)
		(width 0.14732)
		(layer "In13.Cu")
		(net "P5E_CPU0_PE2_RX_DP<3>")
	)
	(segment
		(start 372.081044 -216.73947)
		(end 372.080282 -216.739978)
		(width 0.0889)
		(layer "In13.Cu")
		(net "P5E_CPU0_PE2_RX_DP<3>")
	)
	(segment
		(start 372.83263 -215.323166)
		(end 372.83263 -215.436704)
		(width 0.0889)
		(layer "In13.Cu")
		(net "P5E_CPU0_PE2_RX_DP<3>")
	)
	(segment
		(start 373.006366 -214.904828)
		(end 372.83263 -215.323166)
		(width 0.0889)
		(layer "In13.Cu")
		(net "P5E_CPU0_PE2_RX_DP<3>")
	)
	(segment
		(start 381.793242 -202.0316)
		(end 381.509524 -202.13955)
		(width 0.14732)
		(layer "In13.Cu")
		(net "P5E_CPU0_PE2_RX_DP<3>")
	)
	(segment
		(start 372.086378 -219.99194)
		(end 372.081044 -219.994988)
		(width 0.0889)
		(layer "In13.Cu")
		(net "P5E_CPU0_PE2_RX_DP<3>")
	)
	(segment
		(start 411.35427 -410.411422)
		(end 411.35427 -406.165558)
		(width 0.14732)
		(layer "In13.Cu")
		(net "P5E_CPU0_PE2_RX_DP<3>")
	)
	(segment
		(start 372.83263 -215.437212)
		(end 372.83263 -215.452198)
		(width 0.0889)
		(layer "In13.Cu")
		(net "P5E_CPU0_PE2_RX_DP<3>")
	)
	(segment
		(start 411.35427 -406.165558)
		(end 410.00807 -404.819358)
		(width 0.14732)
		(layer "In13.Cu")
		(net "P5E_CPU0_PE2_RX_DP<3>")
	)
	(segment
		(start 372.078758 -219.015818)
		(end 372.080282 -219.01658)
		(width 0.0889)
		(layer "In13.Cu")
		(net "P5E_CPU0_PE2_RX_DP<3>")
	)
	(segment
		(start 409.421076 -415.019998)
		(end 411.35427 -410.411422)
		(width 0.14732)
		(layer "In13.Cu")
		(net "P5E_CPU0_PE2_RX_DP<3>")
	)
	(segment
		(start 373.771668 -213.854792)
		(end 373.571262 -214.339932)
		(width 0.0889)
		(layer "In13.Cu")
		(net "P5E_CPU0_PE2_RX_DP<3>")
	)
	(segment
		(start 410.00807 -404.819358)
		(end 410.00807 -400.48053)
		(width 0.14732)
		(layer "In13.Cu")
		(net "P5E_CPU0_PE2_RX_DP<3>")
	)
	(segment
		(start 403.409404 -349.469202)
		(end 405.190706 -339.627464)
		(width 0.14732)
		(layer "In13.Cu")
		(net "P5E_CPU0_PE2_RX_DP<3>")
	)
	(segment
		(start 409.181554 -397.684498)
		(end 403.548088 -371.435376)
		(width 0.14732)
		(layer "In13.Cu")
		(net "P5E_CPU0_PE2_RX_DP<3>")
	)
	(segment
		(start 372.086378 -218.364308)
		(end 372.081044 -218.367356)
		(width 0.0889)
		(layer "In13.Cu")
		(net "P5E_CPU0_PE2_RX_DP<3>")
	)
	(segment
		(start 371.893084 -217.0557)
		(end 371.893084 -217.072972)
		(width 0.0889)
		(layer "In13.Cu")
		(net "P5E_CPU0_PE2_RX_DP<3>")
	)
	(segment
		(start 389.981948 -208.223612)
		(end 382.22936 -202.098148)
		(width 0.14732)
		(layer "In13.Cu")
		(net "P5E_CPU0_PE2_RX_DP<3>")
	)
	(segment
		(start 371.893084 -220.311218)
		(end 371.893084 -220.32849)
		(width 0.0889)
		(layer "In13.Cu")
		(net "P5E_CPU0_PE2_RX_DP<3>")
	)
	(segment
		(start 372.086378 -216.736422)
		(end 372.081044 -216.73947)
		(width 0.0889)
		(layer "In13.Cu")
		(net "P5E_CPU0_PE2_RX_DP<3>")
	)
	(segment
		(start 371.573298 -221.652846)
		(end 371.484144 -221.676722)
		(width 0.0889)
		(layer "In13.Cu")
		(net "P5E_CPU0_PE2_RX_DP<3>")
	)
	(segment
		(start 390.516364 -208.64576)
		(end 390.345168 -208.665826)
		(width 0.14732)
		(layer "In13.Cu")
		(net "P5E_CPU0_PE2_RX_DP<3>")
	)
	(segment
		(start 406.750012 -434.309266)
		(end 406.426162 -433.985416)
		(width 0.14732)
		(layer "In13.Cu")
		(net "P5E_CPU0_PE2_RX_DP<3>")
	)
	(segment
		(start 372.083076 -219.018104)
		(end 372.086378 -219.020136)
		(width 0.0889)
		(layer "In13.Cu")
		(net "P5E_CPU0_PE2_RX_DP<3>")
	)
	(segment
		(start 400.053048 -236.511592)
		(end 398.32153 -225.037396)
		(width 0.14732)
		(layer "In13.Cu")
		(net "P5E_CPU0_PE2_RX_DP<3>")
	)
	(segment
		(start 406.750012 -434.48986)
		(end 406.750012 -434.309266)
		(width 0.14732)
		(layer "In13.Cu")
		(net "P5E_CPU0_PE2_RX_DP<3>")
	)
	(segment
		(start 373.813578 -213.164166)
		(end 373.771668 -213.206076)
		(width 0.0889)
		(layer "In13.Cu")
		(net "P5E_CPU0_PE2_RX_DP<3>")
	)
	(segment
		(start 398.32153 -225.037396)
		(end 394.838174 -213.04631)
		(width 0.14732)
		(layer "In13.Cu")
		(net "P5E_CPU0_PE2_RX_DP<3>")
	)
	(segment
		(start 400.053048 -236.511846)
		(end 400.053048 -236.511592)
		(width 0.14732)
		(layer "In13.Cu")
		(net "P5E_CPU0_PE2_RX_DP<3>")
	)
	(segment
		(start 371.484144 -221.676722)
		(end 371.32768 -221.94774)
		(width 0.0889)
		(layer "In13.Cu")
		(net "P5E_CPU0_PE2_RX_DP<3>")
	)
	(segment
		(start 372.550436 -215.926162)
		(end 372.541546 -215.931242)
		(width 0.0889)
		(layer "In13.Cu")
		(net "P5E_CPU0_PE2_RX_DP<3>")
	)
	(segment
		(start 401.784566 -247.986296)
		(end 400.053048 -236.511846)
		(width 0.14732)
		(layer "In13.Cu")
		(net "P5E_CPU0_PE2_RX_DP<3>")
	)
	(segment
		(start 410.00807 -400.48053)
		(end 409.181554 -397.684498)
		(width 0.14732)
		(layer "In13.Cu")
		(net "P5E_CPU0_PE2_RX_DP<3>")
	)
	(segment
		(start 405.791924 -424.464734)
		(end 409.421076 -415.019998)
		(width 0.14732)
		(layer "In13.Cu")
		(net "P5E_CPU0_PE2_RX_DP<3>")
	)
	(segment
		(start 403.080474 -366.583976)
		(end 403.409404 -349.469202)
		(width 0.14732)
		(layer "In13.Cu")
		(net "P5E_CPU0_PE2_RX_DP<3>")
	)
	(segment
		(start 401.976844 -253.69901)
		(end 401.784566 -247.986296)
		(width 0.14732)
		(layer "In13.Cu")
		(net "P5E_CPU0_PE2_RX_DP<3>")
	)
	(segment
		(start 381.509524 -202.13955)
		(end 380.731268 -202.917806)
		(width 0.14732)
		(layer "In13.Cu")
		(net "P5E_CPU0_PE2_RX_DP<3>")
	)
	(segment
		(start 406.085548 -433.985416)
		(end 405.791924 -433.691792)
		(width 0.14732)
		(layer "In13.Cu")
		(net "P5E_CPU0_PE2_RX_DP<3>")
	)
	(segment
		(start 405.791924 -433.691792)
		(end 405.791924 -424.464734)
		(width 0.14732)
		(layer "In13.Cu")
		(net "P5E_CPU0_PE2_RX_DP<3>")
	)
	(segment
		(start 373.813578 -211.7344)
		(end 373.813578 -213.142068)
		(width 0.14732)
		(layer "In13.Cu")
		(net "P5E_CPU0_PE2_RX_DP<3>")
	)
	(segment
		(start 372.081044 -218.367356)
		(end 372.071392 -218.372944)
		(width 0.0889)
		(layer "In13.Cu")
		(net "P5E_CPU0_PE2_RX_DP<3>")
	)
	(segment
		(start 382.22936 -202.098148)
		(end 381.793242 -202.0316)
		(width 0.14732)
		(layer "In13.Cu")
		(net "P5E_CPU0_PE2_RX_DP<3>")
	)
	(segment
		(start 397.867378 -307.842412)
		(end 401.976844 -253.69901)
		(width 0.14732)
		(layer "In13.Cu")
		(net "P5E_CPU0_PE2_RX_DP<3>")
	)
	(segment
		(start 403.548088 -371.435376)
		(end 403.080474 -366.583976)
		(width 0.14732)
		(layer "In13.Cu")
		(net "P5E_CPU0_PE2_RX_DP<3>")
	)
	(segment
		(start 406.426162 -433.985416)
		(end 406.085548 -433.985416)
		(width 0.14732)
		(layer "In13.Cu")
		(net "P5E_CPU0_PE2_RX_DP<3>")
	)
	(segment
		(start 397.869918 -307.85308)
		(end 397.869664 -307.85308)
		(width 0.14732)
		(layer "In13.Cu")
		(net "P5E_CPU0_PE2_RX_DP<3>")
	)
	(segment
		(start 390.002014 -208.394808)
		(end 389.981948 -208.223612)
		(width 0.14732)
		(layer "In13.Cu")
		(net "P5E_CPU0_PE2_RX_DP<3>")
	)
	(segment
		(start 372.086378 -221.619826)
		(end 372.06555 -221.632018)
		(width 0.0889)
		(layer "In13.Cu")
		(net "P5E_CPU0_PE2_RX_DP<3>")
	)
	(segment
		(start 372.081044 -219.994988)
		(end 372.080282 -219.995496)
		(width 0.0889)
		(layer "In13.Cu")
		(net "P5E_CPU0_PE2_RX_DP<3>")
	)
	(segment
		(start 397.869664 -307.85308)
		(end 397.867378 -307.842412)
		(width 0.14732)
		(layer "In13.Cu")
		(net "P5E_CPU0_PE2_RX_DP<3>")
	)
	(segment
		(start 390.85901 -208.916524)
		(end 390.516364 -208.64576)
		(width 0.14732)
		(layer "In13.Cu")
		(net "P5E_CPU0_PE2_RX_DP<3>")
	)
	(segment
		(start 374.426734 -210.105498)
		(end 373.813578 -211.7344)
		(width 0.14732)
		(layer "In13.Cu")
		(net "P5E_CPU0_PE2_RX_DP<3>")
	)
	(segment
		(start 405.190706 -339.627464)
		(end 397.869918 -307.85308)
		(width 0.14732)
		(layer "In13.Cu")
		(net "P5E_CPU0_PE2_RX_DP<3>")
	)
	(segment
		(start 372.362984 -221.1197)
		(end 372.362984 -221.133924)
		(width 0.0889)
		(layer "In13.Cu")
		(net "P5E_CPU0_PE2_RX_DP<3>")
	)
	(segment
		(start 380.731268 -202.917806)
		(end 374.426734 -210.105498)
		(width 0.14732)
		(layer "In13.Cu")
		(net "P5E_CPU0_PE2_RX_DP<3>")
	)
	(segment
		(start 373.771668 -213.206076)
		(end 373.771668 -213.854792)
		(width 0.0889)
		(layer "In13.Cu")
		(net "P5E_CPU0_PE2_RX_DP<3>")
	)
	(segment
		(start 373.813578 -213.142068)
		(end 373.813578 -213.164166)
		(width 0.0889)
		(layer "In13.Cu")
		(net "P5E_CPU0_PE2_RX_DP<3>")
	)
	(arc
		(start 372.071392 -218.372944)
		(mid 371.892795 -218.692222)
		(end 372.071392 -219.0115)
		(width 0.0889)
		(layer "In13.Cu")
		(net "P5E_CPU0_PE2_RX_DP<3>")
	)
	(arc
		(start 372.086378 -219.020136)
		(mid 372.362952 -219.506038)
		(end 372.086378 -219.99194)
		(width 0.0889)
		(layer "In13.Cu")
		(net "P5E_CPU0_PE2_RX_DP<3>")
	)
	(arc
		(start 372.080282 -219.995496)
		(mid 371.945349 -220.12885)
		(end 371.893084 -220.311218)
		(width 0.0889)
		(layer "In13.Cu")
		(net "P5E_CPU0_PE2_RX_DP<3>")
	)
	(arc
		(start 372.362984 -221.133924)
		(mid 372.288993 -221.41349)
		(end 372.086378 -221.619826)
		(width 0.0889)
		(layer "In13.Cu")
		(net "P5E_CPU0_PE2_RX_DP<3>")
	)
	(arc
		(start 372.362984 -216.25052)
		(mid 372.288993 -216.530086)
		(end 372.086378 -216.736422)
		(width 0.0889)
		(layer "In13.Cu")
		(net "P5E_CPU0_PE2_RX_DP<3>")
	)
	(arc
		(start 372.080282 -220.644212)
		(mid 372.283763 -220.845016)
		(end 372.362984 -221.1197)
		(width 0.0889)
		(layer "In13.Cu")
		(net "P5E_CPU0_PE2_RX_DP<3>")
	)
	(arc
		(start 372.06555 -221.632018)
		(mid 371.832635 -221.698229)
		(end 371.593364 -221.660974)
		(width 0.0889)
		(layer "In13.Cu")
		(net "P5E_CPU0_PE2_RX_DP<3>")
	)
	(arc
		(start 371.893084 -217.072972)
		(mid 371.945354 -217.255337)
		(end 372.080282 -217.388694)
		(width 0.0889)
		(layer "In13.Cu")
		(net "P5E_CPU0_PE2_RX_DP<3>")
	)
	(arc
		(start 372.83263 -215.452198)
		(mid 372.75326 -215.725932)
		(end 372.550436 -215.926162)
		(width 0.0889)
		(layer "In13.Cu")
		(net "P5E_CPU0_PE2_RX_DP<3>")
	)
	(arc
		(start 372.080282 -217.388694)
		(mid 372.363277 -217.874813)
		(end 372.086378 -218.364308)
		(width 0.0889)
		(layer "In13.Cu")
		(net "P5E_CPU0_PE2_RX_DP<3>")
	)
	(arc
		(start 371.593364 -221.660974)
		(mid 371.583293 -221.657005)
		(end 371.573298 -221.652846)
		(width 0.0889)
		(layer "In13.Cu")
		(net "P5E_CPU0_PE2_RX_DP<3>")
	)
	(arc
		(start 372.83263 -215.436704)
		(mid 372.83263 -215.436958)
		(end 372.83263 -215.437212)
		(width 0.0889)
		(layer "In13.Cu")
		(net "P5E_CPU0_PE2_RX_DP<3>")
	)
	(arc
		(start 372.080282 -216.739978)
		(mid 371.945349 -216.873332)
		(end 371.893084 -217.0557)
		(width 0.0889)
		(layer "In13.Cu")
		(net "P5E_CPU0_PE2_RX_DP<3>")
	)
	(arc
		(start 371.893084 -220.32849)
		(mid 371.945354 -220.510855)
		(end 372.080282 -220.644212)
		(width 0.0889)
		(layer "In13.Cu")
		(net "P5E_CPU0_PE2_RX_DP<3>")
	)
	(arc
		(start 372.541546 -215.931242)
		(mid 372.410632 -216.067602)
		(end 372.362984 -216.25052)
		(width 0.0889)
		(layer "In13.Cu")
		(net "P5E_CPU0_PE2_RX_DP<3>")
	)
	(segment
		(start 370.85778 -221.669864)
		(end 370.85778 -221.134178)
		(width 0.13208)
		(layer "F.Cu")
		(net "P5E_CPU0_PE2_RX_DP<2>")
	)
	(segment
		(start 370.85778 -221.134178)
		(end 370.858034 -221.133924)
		(width 0.13208)
		(layer "F.Cu")
		(net "P5E_CPU0_PE2_RX_DP<2>")
	)
	(segment
		(start 401.035266 -235.881672)
		(end 401.03552 -235.881418)
		(width 0.14732)
		(layer "In13.Cu")
		(net "P5E_CPU0_PE2_RX_DP<2>")
	)
	(segment
		(start 371.423184 -216.25052)
		(end 371.423184 -216.260426)
		(width 0.0889)
		(layer "In13.Cu")
		(net "P5E_CPU0_PE2_RX_DP<2>")
	)
	(segment
		(start 371.131846 -217.383614)
		(end 371.140736 -217.388694)
		(width 0.0889)
		(layer "In13.Cu")
		(net "P5E_CPU0_PE2_RX_DP<2>")
	)
	(segment
		(start 410.643832 -418.120068)
		(end 414.41751 -411.222952)
		(width 0.14732)
		(layer "In13.Cu")
		(net "P5E_CPU0_PE2_RX_DP<2>")
	)
	(segment
		(start 372.83263 -213.869778)
		(end 372.665498 -214.27313)
		(width 0.0889)
		(layer "In13.Cu")
		(net "P5E_CPU0_PE2_RX_DP<2>")
	)
	(segment
		(start 371.610636 -215.926162)
		(end 371.601746 -215.931242)
		(width 0.0889)
		(layer "In13.Cu")
		(net "P5E_CPU0_PE2_RX_DP<2>")
	)
	(segment
		(start 402.926296 -253.490476)
		(end 402.816314 -250.222512)
		(width 0.14732)
		(layer "In13.Cu")
		(net "P5E_CPU0_PE2_RX_DP<2>")
	)
	(segment
		(start 411.900878 -397.002254)
		(end 404.772114 -370.915438)
		(width 0.14732)
		(layer "In13.Cu")
		(net "P5E_CPU0_PE2_RX_DP<2>")
	)
	(segment
		(start 371.137434 -219.997528)
		(end 371.131846 -220.000576)
		(width 0.0889)
		(layer "In13.Cu")
		(net "P5E_CPU0_PE2_RX_DP<2>")
	)
	(segment
		(start 390.347454 -206.88427)
		(end 390.043162 -206.570072)
		(width 0.14732)
		(layer "In13.Cu")
		(net "P5E_CPU0_PE2_RX_DP<2>")
	)
	(segment
		(start 408.750008 -435.489858)
		(end 408.750008 -435.413658)
		(width 0.14732)
		(layer "In13.Cu")
		(net "P5E_CPU0_PE2_RX_DP<2>")
	)
	(segment
		(start 414.41751 -406.165558)
		(end 413.07131 -404.819358)
		(width 0.14732)
		(layer "In13.Cu")
		(net "P5E_CPU0_PE2_RX_DP<2>")
	)
	(segment
		(start 372.87454 -213.142068)
		(end 372.87454 -213.164166)
		(width 0.0889)
		(layer "In13.Cu")
		(net "P5E_CPU0_PE2_RX_DP<2>")
	)
	(segment
		(start 371.999764 -214.939118)
		(end 371.893084 -215.195912)
		(width 0.0889)
		(layer "In13.Cu")
		(net "P5E_CPU0_PE2_RX_DP<2>")
	)
	(segment
		(start 372.665498 -214.27313)
		(end 371.999764 -214.939118)
		(width 0.0889)
		(layer "In13.Cu")
		(net "P5E_CPU0_PE2_RX_DP<2>")
	)
	(segment
		(start 371.140482 -219.01658)
		(end 371.143276 -219.018104)
		(width 0.0889)
		(layer "In13.Cu")
		(net "P5E_CPU0_PE2_RX_DP<2>")
	)
	(segment
		(start 371.140736 -216.739978)
		(end 371.139974 -216.740486)
		(width 0.0889)
		(layer "In13.Cu")
		(net "P5E_CPU0_PE2_RX_DP<2>")
	)
	(segment
		(start 408.283664 -434.947314)
		(end 408.1145 -434.947314)
		(width 0.14732)
		(layer "In13.Cu")
		(net "P5E_CPU0_PE2_RX_DP<2>")
	)
	(segment
		(start 372.87454 -213.164166)
		(end 372.83263 -213.206076)
		(width 0.0889)
		(layer "In13.Cu")
		(net "P5E_CPU0_PE2_RX_DP<2>")
	)
	(segment
		(start 399.364454 -224.808288)
		(end 395.718284 -212.257894)
		(width 0.14732)
		(layer "In13.Cu")
		(net "P5E_CPU0_PE2_RX_DP<2>")
	)
	(segment
		(start 371.137434 -216.74201)
		(end 371.131846 -216.745058)
		(width 0.0889)
		(layer "In13.Cu")
		(net "P5E_CPU0_PE2_RX_DP<2>")
	)
	(segment
		(start 391.124694 -207.687418)
		(end 390.820656 -207.37322)
		(width 0.14732)
		(layer "In13.Cu")
		(net "P5E_CPU0_PE2_RX_DP<2>")
	)
	(segment
		(start 390.519666 -206.887064)
		(end 390.347454 -206.88427)
		(width 0.14732)
		(layer "In13.Cu")
		(net "P5E_CPU0_PE2_RX_DP<2>")
	)
	(segment
		(start 402.706332 -246.95531)
		(end 401.035266 -235.881672)
		(width 0.14732)
		(layer "In13.Cu")
		(net "P5E_CPU0_PE2_RX_DP<2>")
	)
	(segment
		(start 409.092654 -421.529002)
		(end 409.092908 -421.529002)
		(width 0.14732)
		(layer "In13.Cu")
		(net "P5E_CPU0_PE2_RX_DP<2>")
	)
	(segment
		(start 408.750008 -435.413658)
		(end 408.283664 -434.947314)
		(width 0.14732)
		(layer "In13.Cu")
		(net "P5E_CPU0_PE2_RX_DP<2>")
	)
	(segment
		(start 371.139974 -216.740486)
		(end 371.137434 -216.74201)
		(width 0.0889)
		(layer "In13.Cu")
		(net "P5E_CPU0_PE2_RX_DP<2>")
	)
	(segment
		(start 371.133624 -218.371674)
		(end 371.131592 -218.372944)
		(width 0.0889)
		(layer "In13.Cu")
		(net "P5E_CPU0_PE2_RX_DP<2>")
	)
	(segment
		(start 370.7257 -220.773752)
		(end 370.70157 -220.862906)
		(width 0.0889)
		(layer "In13.Cu")
		(net "P5E_CPU0_PE2_RX_DP<2>")
	)
	(segment
		(start 371.143276 -219.018104)
		(end 371.146578 -219.020136)
		(width 0.0889)
		(layer "In13.Cu")
		(net "P5E_CPU0_PE2_RX_DP<2>")
	)
	(segment
		(start 390.82345 -207.200754)
		(end 390.519666 -206.887064)
		(width 0.14732)
		(layer "In13.Cu")
		(net "P5E_CPU0_PE2_RX_DP<2>")
	)
	(segment
		(start 371.131592 -219.0115)
		(end 371.138958 -219.015818)
		(width 0.0889)
		(layer "In13.Cu")
		(net "P5E_CPU0_PE2_RX_DP<2>")
	)
	(segment
		(start 371.146578 -218.364308)
		(end 371.133624 -218.371674)
		(width 0.0889)
		(layer "In13.Cu")
		(net "P5E_CPU0_PE2_RX_DP<2>")
	)
	(segment
		(start 401.03552 -235.881418)
		(end 399.364454 -224.808288)
		(width 0.14732)
		(layer "In13.Cu")
		(net "P5E_CPU0_PE2_RX_DP<2>")
	)
	(segment
		(start 385.553712 -201.756264)
		(end 385.121912 -201.577448)
		(width 0.14732)
		(layer "In13.Cu")
		(net "P5E_CPU0_PE2_RX_DP<2>")
	)
	(segment
		(start 409.092908 -421.529002)
		(end 409.581096 -420.456106)
		(width 0.14732)
		(layer "In13.Cu")
		(net "P5E_CPU0_PE2_RX_DP<2>")
	)
	(segment
		(start 414.41751 -411.222952)
		(end 414.41751 -406.165558)
		(width 0.14732)
		(layer "In13.Cu")
		(net "P5E_CPU0_PE2_RX_DP<2>")
	)
	(segment
		(start 390.043162 -206.570072)
		(end 390.045956 -206.397606)
		(width 0.14732)
		(layer "In13.Cu")
		(net "P5E_CPU0_PE2_RX_DP<2>")
	)
	(segment
		(start 404.273004 -367.00841)
		(end 404.500588 -349.087694)
		(width 0.14732)
		(layer "In13.Cu")
		(net "P5E_CPU0_PE2_RX_DP<2>")
	)
	(segment
		(start 381.530098 -201.07021)
		(end 381.0508 -201.268838)
		(width 0.14732)
		(layer "In13.Cu")
		(net "P5E_CPU0_PE2_RX_DP<2>")
	)
	(segment
		(start 371.140736 -219.995496)
		(end 371.139974 -219.996004)
		(width 0.0889)
		(layer "In13.Cu")
		(net "P5E_CPU0_PE2_RX_DP<2>")
	)
	(segment
		(start 407.79192 -424.388534)
		(end 409.092654 -421.529002)
		(width 0.14732)
		(layer "In13.Cu")
		(net "P5E_CPU0_PE2_RX_DP<2>")
	)
	(segment
		(start 385.121912 -201.577448)
		(end 381.912114 -201.07021)
		(width 0.14732)
		(layer "In13.Cu")
		(net "P5E_CPU0_PE2_RX_DP<2>")
	)
	(segment
		(start 391.29716 -207.690212)
		(end 391.124694 -207.687418)
		(width 0.14732)
		(layer "In13.Cu")
		(net "P5E_CPU0_PE2_RX_DP<2>")
	)
	(segment
		(start 404.772114 -370.915438)
		(end 404.273004 -367.00841)
		(width 0.14732)
		(layer "In13.Cu")
		(net "P5E_CPU0_PE2_RX_DP<2>")
	)
	(segment
		(start 381.0508 -201.268838)
		(end 379.915674 -202.403964)
		(width 0.14732)
		(layer "In13.Cu")
		(net "P5E_CPU0_PE2_RX_DP<2>")
	)
	(segment
		(start 404.500588 -349.087694)
		(end 406.166574 -339.677756)
		(width 0.14732)
		(layer "In13.Cu")
		(net "P5E_CPU0_PE2_RX_DP<2>")
	)
	(segment
		(start 407.79192 -434.624734)
		(end 407.79192 -424.388534)
		(width 0.14732)
		(layer "In13.Cu")
		(net "P5E_CPU0_PE2_RX_DP<2>")
	)
	(segment
		(start 390.045956 -206.397606)
		(end 385.553712 -201.756264)
		(width 0.14732)
		(layer "In13.Cu")
		(net "P5E_CPU0_PE2_RX_DP<2>")
	)
	(segment
		(start 413.07131 -400.63166)
		(end 411.900878 -397.002254)
		(width 0.14732)
		(layer "In13.Cu")
		(net "P5E_CPU0_PE2_RX_DP<2>")
	)
	(segment
		(start 370.953284 -220.319854)
		(end 370.953284 -220.334078)
		(width 0.0889)
		(layer "In13.Cu")
		(net "P5E_CPU0_PE2_RX_DP<2>")
	)
	(segment
		(start 390.820656 -207.37322)
		(end 390.82345 -207.200754)
		(width 0.14732)
		(layer "In13.Cu")
		(net "P5E_CPU0_PE2_RX_DP<2>")
	)
	(segment
		(start 371.139974 -219.996004)
		(end 371.137434 -219.997528)
		(width 0.0889)
		(layer "In13.Cu")
		(net "P5E_CPU0_PE2_RX_DP<2>")
	)
	(segment
		(start 402.816314 -250.222512)
		(end 402.816314 -250.222766)
		(width 0.14732)
		(layer "In13.Cu")
		(net "P5E_CPU0_PE2_RX_DP<2>")
	)
	(segment
		(start 379.915674 -202.403964)
		(end 373.582946 -209.630772)
		(width 0.14732)
		(layer "In13.Cu")
		(net "P5E_CPU0_PE2_RX_DP<2>")
	)
	(segment
		(start 408.1145 -434.947314)
		(end 407.79192 -434.624734)
		(width 0.14732)
		(layer "In13.Cu")
		(net "P5E_CPU0_PE2_RX_DP<2>")
	)
	(segment
		(start 409.581096 -420.456106)
		(end 409.581096 -420.455852)
		(width 0.14732)
		(layer "In13.Cu")
		(net "P5E_CPU0_PE2_RX_DP<2>")
	)
	(segment
		(start 406.166574 -339.677756)
		(end 398.846802 -307.73497)
		(width 0.14732)
		(layer "In13.Cu")
		(net "P5E_CPU0_PE2_RX_DP<2>")
	)
	(segment
		(start 413.07131 -404.819358)
		(end 413.07131 -400.63166)
		(width 0.14732)
		(layer "In13.Cu")
		(net "P5E_CPU0_PE2_RX_DP<2>")
	)
	(segment
		(start 371.893084 -215.195912)
		(end 371.893084 -215.44661)
		(width 0.0889)
		(layer "In13.Cu")
		(net "P5E_CPU0_PE2_RX_DP<2>")
	)
	(segment
		(start 373.582946 -209.630772)
		(end 372.87454 -211.514182)
		(width 0.14732)
		(layer "In13.Cu")
		(net "P5E_CPU0_PE2_RX_DP<2>")
	)
	(segment
		(start 409.581096 -420.455852)
		(end 410.643832 -418.120068)
		(width 0.14732)
		(layer "In13.Cu")
		(net "P5E_CPU0_PE2_RX_DP<2>")
	)
	(segment
		(start 381.912114 -201.07021)
		(end 381.530098 -201.07021)
		(width 0.14732)
		(layer "In13.Cu")
		(net "P5E_CPU0_PE2_RX_DP<2>")
	)
	(segment
		(start 370.70157 -220.862906)
		(end 370.858034 -221.133924)
		(width 0.0889)
		(layer "In13.Cu")
		(net "P5E_CPU0_PE2_RX_DP<2>")
	)
	(segment
		(start 372.87454 -211.514182)
		(end 372.87454 -213.142068)
		(width 0.14732)
		(layer "In13.Cu")
		(net "P5E_CPU0_PE2_RX_DP<2>")
	)
	(segment
		(start 371.138958 -219.015818)
		(end 371.140482 -219.01658)
		(width 0.0889)
		(layer "In13.Cu")
		(net "P5E_CPU0_PE2_RX_DP<2>")
	)
	(segment
		(start 402.816314 -250.222766)
		(end 402.706332 -246.95531)
		(width 0.14732)
		(layer "In13.Cu")
		(net "P5E_CPU0_PE2_RX_DP<2>")
	)
	(segment
		(start 372.83263 -213.206076)
		(end 372.83263 -213.869778)
		(width 0.0889)
		(layer "In13.Cu")
		(net "P5E_CPU0_PE2_RX_DP<2>")
	)
	(segment
		(start 371.423184 -219.506038)
		(end 371.423184 -219.515944)
		(width 0.0889)
		(layer "In13.Cu")
		(net "P5E_CPU0_PE2_RX_DP<2>")
	)
	(segment
		(start 398.846802 -307.73497)
		(end 402.926296 -253.490476)
		(width 0.14732)
		(layer "In13.Cu")
		(net "P5E_CPU0_PE2_RX_DP<2>")
	)
	(segment
		(start 395.718284 -212.257894)
		(end 391.29716 -207.690212)
		(width 0.14732)
		(layer "In13.Cu")
		(net "P5E_CPU0_PE2_RX_DP<2>")
	)
	(arc
		(start 371.131846 -216.745058)
		(mid 371.000932 -216.881418)
		(end 370.953284 -217.064336)
		(width 0.0889)
		(layer "In13.Cu")
		(net "P5E_CPU0_PE2_RX_DP<2>")
	)
	(arc
		(start 371.131592 -218.372944)
		(mid 370.952995 -218.692222)
		(end 371.131592 -219.0115)
		(width 0.0889)
		(layer "In13.Cu")
		(net "P5E_CPU0_PE2_RX_DP<2>")
	)
	(arc
		(start 371.131846 -220.000576)
		(mid 371.000932 -220.136936)
		(end 370.953284 -220.319854)
		(width 0.0889)
		(layer "In13.Cu")
		(net "P5E_CPU0_PE2_RX_DP<2>")
	)
	(arc
		(start 371.893084 -215.44661)
		(mid 371.814973 -215.723559)
		(end 371.610636 -215.926162)
		(width 0.0889)
		(layer "In13.Cu")
		(net "P5E_CPU0_PE2_RX_DP<2>")
	)
	(arc
		(start 370.953284 -220.334078)
		(mid 370.894923 -220.570676)
		(end 370.742464 -220.760798)
		(width 0.0889)
		(layer "In13.Cu")
		(net "P5E_CPU0_PE2_RX_DP<2>")
	)
	(arc
		(start 371.146578 -219.020136)
		(mid 371.349165 -219.226487)
		(end 371.423184 -219.506038)
		(width 0.0889)
		(layer "In13.Cu")
		(net "P5E_CPU0_PE2_RX_DP<2>")
	)
	(arc
		(start 371.423184 -219.515944)
		(mid 371.345073 -219.792893)
		(end 371.140736 -219.995496)
		(width 0.0889)
		(layer "In13.Cu")
		(net "P5E_CPU0_PE2_RX_DP<2>")
	)
	(arc
		(start 370.953284 -217.064336)
		(mid 371.000963 -217.247236)
		(end 371.131846 -217.383614)
		(width 0.0889)
		(layer "In13.Cu")
		(net "P5E_CPU0_PE2_RX_DP<2>")
	)
	(arc
		(start 371.140736 -217.388694)
		(mid 371.423385 -217.874797)
		(end 371.146578 -218.364308)
		(width 0.0889)
		(layer "In13.Cu")
		(net "P5E_CPU0_PE2_RX_DP<2>")
	)
	(arc
		(start 371.423184 -216.260426)
		(mid 371.345073 -216.537375)
		(end 371.140736 -216.739978)
		(width 0.0889)
		(layer "In13.Cu")
		(net "P5E_CPU0_PE2_RX_DP<2>")
	)
	(arc
		(start 370.742464 -220.760798)
		(mid 370.734142 -220.767353)
		(end 370.7257 -220.773752)
		(width 0.0889)
		(layer "In13.Cu")
		(net "P5E_CPU0_PE2_RX_DP<2>")
	)
	(arc
		(start 371.601746 -215.931242)
		(mid 371.470832 -216.067602)
		(end 371.423184 -216.25052)
		(width 0.0889)
		(layer "In13.Cu")
		(net "P5E_CPU0_PE2_RX_DP<2>")
	)
	(segment
		(start 369.448334 -222.48368)
		(end 369.448334 -221.947994)
		(width 0.13208)
		(layer "F.Cu")
		(net "P5E_CPU0_PE2_RX_DP<1>")
	)
	(segment
		(start 369.448334 -221.947994)
		(end 369.44808 -221.94774)
		(width 0.13208)
		(layer "F.Cu")
		(net "P5E_CPU0_PE2_RX_DP<1>")
	)
	(segment
		(start 381.283972 -200.13041)
		(end 380.559818 -200.430384)
		(width 0.14732)
		(layer "In13.Cu")
		(net "P5E_CPU0_PE2_RX_DP<1>")
	)
	(segment
		(start 405.543004 -348.624144)
		(end 407.14676 -339.702648)
		(width 0.14732)
		(layer "In13.Cu")
		(net "P5E_CPU0_PE2_RX_DP<1>")
	)
	(segment
		(start 370.95303 -215.437212)
		(end 370.95303 -215.452198)
		(width 0.0889)
		(layer "In13.Cu")
		(net "P5E_CPU0_PE2_RX_DP<1>")
	)
	(segment
		(start 380.559818 -200.430384)
		(end 379.26899 -201.721212)
		(width 0.14732)
		(layer "In13.Cu")
		(net "P5E_CPU0_PE2_RX_DP<1>")
	)
	(segment
		(start 410.283406 -433.947316)
		(end 410.060648 -433.947316)
		(width 0.14732)
		(layer "In13.Cu")
		(net "P5E_CPU0_PE2_RX_DP<1>")
	)
	(segment
		(start 411.458664 -421.284654)
		(end 411.458918 -421.284146)
		(width 0.14732)
		(layer "In13.Cu")
		(net "P5E_CPU0_PE2_RX_DP<1>")
	)
	(segment
		(start 371.077744 -214.921084)
		(end 370.95303 -215.222074)
		(width 0.0889)
		(layer "In13.Cu")
		(net "P5E_CPU0_PE2_RX_DP<1>")
	)
	(segment
		(start 417.48075 -406.141682)
		(end 416.13455 -404.795482)
		(width 0.14732)
		(layer "In13.Cu")
		(net "P5E_CPU0_PE2_RX_DP<1>")
	)
	(segment
		(start 405.780748 -370.078762)
		(end 405.303736 -367.012474)
		(width 0.14732)
		(layer "In13.Cu")
		(net "P5E_CPU0_PE2_RX_DP<1>")
	)
	(segment
		(start 371.892068 -213.206076)
		(end 371.892068 -213.896702)
		(width 0.0889)
		(layer "In13.Cu")
		(net "P5E_CPU0_PE2_RX_DP<1>")
	)
	(segment
		(start 407.14676 -339.702648)
		(end 399.792952 -307.585364)
		(width 0.14732)
		(layer "In13.Cu")
		(net "P5E_CPU0_PE2_RX_DP<1>")
	)
	(segment
		(start 371.743478 -214.25535)
		(end 371.077744 -214.921084)
		(width 0.0889)
		(layer "In13.Cu")
		(net "P5E_CPU0_PE2_RX_DP<1>")
	)
	(segment
		(start 371.933978 -211.330286)
		(end 371.933978 -213.142068)
		(width 0.14732)
		(layer "In13.Cu")
		(net "P5E_CPU0_PE2_RX_DP<1>")
	)
	(segment
		(start 403.700996 -247.251982)
		(end 400.283934 -224.606358)
		(width 0.14732)
		(layer "In13.Cu")
		(net "P5E_CPU0_PE2_RX_DP<1>")
	)
	(segment
		(start 379.26899 -201.721212)
		(end 372.756938 -209.144362)
		(width 0.14732)
		(layer "In13.Cu")
		(net "P5E_CPU0_PE2_RX_DP<1>")
	)
	(segment
		(start 370.206778 -219.99194)
		(end 370.201444 -219.994988)
		(width 0.0889)
		(layer "In13.Cu")
		(net "P5E_CPU0_PE2_RX_DP<1>")
	)
	(segment
		(start 369.693698 -221.652846)
		(end 369.604544 -221.676722)
		(width 0.0889)
		(layer "In13.Cu")
		(net "P5E_CPU0_PE2_RX_DP<1>")
	)
	(segment
		(start 410.750004 -434.413914)
		(end 410.283406 -433.947316)
		(width 0.14732)
		(layer "In13.Cu")
		(net "P5E_CPU0_PE2_RX_DP<1>")
	)
	(segment
		(start 386.018532 -200.90003)
		(end 385.459732 -200.668636)
		(width 0.14732)
		(layer "In13.Cu")
		(net "P5E_CPU0_PE2_RX_DP<1>")
	)
	(segment
		(start 370.013484 -220.311218)
		(end 370.013484 -220.32849)
		(width 0.0889)
		(layer "In13.Cu")
		(net "P5E_CPU0_PE2_RX_DP<1>")
	)
	(segment
		(start 370.206524 -218.364562)
		(end 370.193824 -218.371674)
		(width 0.0889)
		(layer "In13.Cu")
		(net "P5E_CPU0_PE2_RX_DP<1>")
	)
	(segment
		(start 370.206778 -221.619826)
		(end 370.18595 -221.632018)
		(width 0.0889)
		(layer "In13.Cu")
		(net "P5E_CPU0_PE2_RX_DP<1>")
	)
	(segment
		(start 370.483384 -221.1197)
		(end 370.483384 -221.133924)
		(width 0.0889)
		(layer "In13.Cu")
		(net "P5E_CPU0_PE2_RX_DP<1>")
	)
	(segment
		(start 417.48075 -411.206696)
		(end 417.48075 -406.141682)
		(width 0.14732)
		(layer "In13.Cu")
		(net "P5E_CPU0_PE2_RX_DP<1>")
	)
	(segment
		(start 399.792952 -307.585364)
		(end 403.910292 -253.48057)
		(width 0.14732)
		(layer "In13.Cu")
		(net "P5E_CPU0_PE2_RX_DP<1>")
	)
	(segment
		(start 370.483384 -217.864182)
		(end 370.483384 -217.878406)
		(width 0.0889)
		(layer "In13.Cu")
		(net "P5E_CPU0_PE2_RX_DP<1>")
	)
	(segment
		(start 410.92374 -422.288208)
		(end 411.411166 -421.373808)
		(width 0.14732)
		(layer "In13.Cu")
		(net "P5E_CPU0_PE2_RX_DP<1>")
	)
	(segment
		(start 409.791916 -433.678584)
		(end 409.791916 -424.411902)
		(width 0.14732)
		(layer "In13.Cu")
		(net "P5E_CPU0_PE2_RX_DP<1>")
	)
	(segment
		(start 416.13455 -400.101562)
		(end 415.101024 -398.050258)
		(width 0.14732)
		(layer "In13.Cu")
		(net "P5E_CPU0_PE2_RX_DP<1>")
	)
	(segment
		(start 410.750004 -434.48986)
		(end 410.750004 -434.413914)
		(width 0.14732)
		(layer "In13.Cu")
		(net "P5E_CPU0_PE2_RX_DP<1>")
	)
	(segment
		(start 372.756938 -209.144362)
		(end 371.933978 -211.330286)
		(width 0.14732)
		(layer "In13.Cu")
		(net "P5E_CPU0_PE2_RX_DP<1>")
	)
	(segment
		(start 369.604544 -221.676722)
		(end 369.44808 -221.94774)
		(width 0.0889)
		(layer "In13.Cu")
		(net "P5E_CPU0_PE2_RX_DP<1>")
	)
	(segment
		(start 416.13455 -404.795482)
		(end 416.13455 -400.101562)
		(width 0.14732)
		(layer "In13.Cu")
		(net "P5E_CPU0_PE2_RX_DP<1>")
	)
	(segment
		(start 403.910292 -253.48057)
		(end 403.805644 -250.366276)
		(width 0.14732)
		(layer "In13.Cu")
		(net "P5E_CPU0_PE2_RX_DP<1>")
	)
	(segment
		(start 370.201444 -216.73947)
		(end 370.200682 -216.739978)
		(width 0.0889)
		(layer "In13.Cu")
		(net "P5E_CPU0_PE2_RX_DP<1>")
	)
	(segment
		(start 370.201444 -219.994988)
		(end 370.200682 -219.995496)
		(width 0.0889)
		(layer "In13.Cu")
		(net "P5E_CPU0_PE2_RX_DP<1>")
	)
	(segment
		(start 403.805644 -250.366276)
		(end 403.805644 -250.366022)
		(width 0.14732)
		(layer "In13.Cu")
		(net "P5E_CPU0_PE2_RX_DP<1>")
	)
	(segment
		(start 382.035558 -200.13041)
		(end 381.283972 -200.13041)
		(width 0.14732)
		(layer "In13.Cu")
		(net "P5E_CPU0_PE2_RX_DP<1>")
	)
	(segment
		(start 370.193824 -218.371674)
		(end 370.191792 -218.372944)
		(width 0.0889)
		(layer "In13.Cu")
		(net "P5E_CPU0_PE2_RX_DP<1>")
	)
	(segment
		(start 410.92374 -422.288462)
		(end 410.92374 -422.288208)
		(width 0.14732)
		(layer "In13.Cu")
		(net "P5E_CPU0_PE2_RX_DP<1>")
	)
	(segment
		(start 371.892068 -213.896702)
		(end 371.743478 -214.25535)
		(width 0.0889)
		(layer "In13.Cu")
		(net "P5E_CPU0_PE2_RX_DP<1>")
	)
	(segment
		(start 370.670836 -215.926162)
		(end 370.661946 -215.931242)
		(width 0.0889)
		(layer "In13.Cu")
		(net "P5E_CPU0_PE2_RX_DP<1>")
	)
	(segment
		(start 400.283934 -224.606358)
		(end 396.533624 -211.697062)
		(width 0.14732)
		(layer "In13.Cu")
		(net "P5E_CPU0_PE2_RX_DP<1>")
	)
	(segment
		(start 370.206778 -216.736422)
		(end 370.201444 -216.73947)
		(width 0.0889)
		(layer "In13.Cu")
		(net "P5E_CPU0_PE2_RX_DP<1>")
	)
	(segment
		(start 412.838138 -418.69868)
		(end 417.48075 -411.206696)
		(width 0.14732)
		(layer "In13.Cu")
		(net "P5E_CPU0_PE2_RX_DP<1>")
	)
	(segment
		(start 405.303736 -367.012474)
		(end 405.543004 -348.624144)
		(width 0.14732)
		(layer "In13.Cu")
		(net "P5E_CPU0_PE2_RX_DP<1>")
	)
	(segment
		(start 411.411166 -421.373808)
		(end 411.458664 -421.284654)
		(width 0.14732)
		(layer "In13.Cu")
		(net "P5E_CPU0_PE2_RX_DP<1>")
	)
	(segment
		(start 370.013484 -217.0557)
		(end 370.013484 -217.072972)
		(width 0.0889)
		(layer "In13.Cu")
		(net "P5E_CPU0_PE2_RX_DP<1>")
	)
	(segment
		(start 411.458918 -421.284146)
		(end 412.838138 -418.69868)
		(width 0.14732)
		(layer "In13.Cu")
		(net "P5E_CPU0_PE2_RX_DP<1>")
	)
	(segment
		(start 396.533624 -211.697062)
		(end 386.018532 -200.90003)
		(width 0.14732)
		(layer "In13.Cu")
		(net "P5E_CPU0_PE2_RX_DP<1>")
	)
	(segment
		(start 370.206778 -218.364308)
		(end 370.206524 -218.364562)
		(width 0.0889)
		(layer "In13.Cu")
		(net "P5E_CPU0_PE2_RX_DP<1>")
	)
	(segment
		(start 370.95303 -215.222074)
		(end 370.95303 -215.436704)
		(width 0.0889)
		(layer "In13.Cu")
		(net "P5E_CPU0_PE2_RX_DP<1>")
	)
	(segment
		(start 410.060648 -433.947316)
		(end 409.791916 -433.678584)
		(width 0.14732)
		(layer "In13.Cu")
		(net "P5E_CPU0_PE2_RX_DP<1>")
	)
	(segment
		(start 415.101024 -398.050258)
		(end 405.780748 -370.078762)
		(width 0.14732)
		(layer "In13.Cu")
		(net "P5E_CPU0_PE2_RX_DP<1>")
	)
	(segment
		(start 370.200682 -219.01658)
		(end 370.206778 -219.020136)
		(width 0.0889)
		(layer "In13.Cu")
		(net "P5E_CPU0_PE2_RX_DP<1>")
	)
	(segment
		(start 385.459732 -200.668636)
		(end 382.035558 -200.13041)
		(width 0.14732)
		(layer "In13.Cu")
		(net "P5E_CPU0_PE2_RX_DP<1>")
	)
	(segment
		(start 403.805644 -250.366022)
		(end 403.700996 -247.251982)
		(width 0.14732)
		(layer "In13.Cu")
		(net "P5E_CPU0_PE2_RX_DP<1>")
	)
	(segment
		(start 371.933978 -213.164166)
		(end 371.892068 -213.206076)
		(width 0.0889)
		(layer "In13.Cu")
		(net "P5E_CPU0_PE2_RX_DP<1>")
	)
	(segment
		(start 371.933978 -213.142068)
		(end 371.933978 -213.164166)
		(width 0.0889)
		(layer "In13.Cu")
		(net "P5E_CPU0_PE2_RX_DP<1>")
	)
	(segment
		(start 370.191792 -219.0115)
		(end 370.200682 -219.01658)
		(width 0.0889)
		(layer "In13.Cu")
		(net "P5E_CPU0_PE2_RX_DP<1>")
	)
	(segment
		(start 409.791916 -424.411902)
		(end 410.92374 -422.288462)
		(width 0.14732)
		(layer "In13.Cu")
		(net "P5E_CPU0_PE2_RX_DP<1>")
	)
	(arc
		(start 370.200682 -219.995496)
		(mid 370.065749 -220.12885)
		(end 370.013484 -220.311218)
		(width 0.0889)
		(layer "In13.Cu")
		(net "P5E_CPU0_PE2_RX_DP<1>")
	)
	(arc
		(start 370.483384 -217.878406)
		(mid 370.409393 -218.157972)
		(end 370.206778 -218.364308)
		(width 0.0889)
		(layer "In13.Cu")
		(net "P5E_CPU0_PE2_RX_DP<1>")
	)
	(arc
		(start 370.191792 -218.372944)
		(mid 370.013195 -218.692222)
		(end 370.191792 -219.0115)
		(width 0.0889)
		(layer "In13.Cu")
		(net "P5E_CPU0_PE2_RX_DP<1>")
	)
	(arc
		(start 370.200682 -216.739978)
		(mid 370.065749 -216.873332)
		(end 370.013484 -217.0557)
		(width 0.0889)
		(layer "In13.Cu")
		(net "P5E_CPU0_PE2_RX_DP<1>")
	)
	(arc
		(start 370.013484 -220.32849)
		(mid 370.065754 -220.510855)
		(end 370.200682 -220.644212)
		(width 0.0889)
		(layer "In13.Cu")
		(net "P5E_CPU0_PE2_RX_DP<1>")
	)
	(arc
		(start 370.18595 -221.632018)
		(mid 369.953035 -221.698229)
		(end 369.713764 -221.660974)
		(width 0.0889)
		(layer "In13.Cu")
		(net "P5E_CPU0_PE2_RX_DP<1>")
	)
	(arc
		(start 370.483384 -221.133924)
		(mid 370.409393 -221.41349)
		(end 370.206778 -221.619826)
		(width 0.0889)
		(layer "In13.Cu")
		(net "P5E_CPU0_PE2_RX_DP<1>")
	)
	(arc
		(start 370.95303 -215.436704)
		(mid 370.95303 -215.436958)
		(end 370.95303 -215.437212)
		(width 0.0889)
		(layer "In13.Cu")
		(net "P5E_CPU0_PE2_RX_DP<1>")
	)
	(arc
		(start 370.661946 -215.931242)
		(mid 370.531032 -216.067602)
		(end 370.483384 -216.25052)
		(width 0.0889)
		(layer "In13.Cu")
		(net "P5E_CPU0_PE2_RX_DP<1>")
	)
	(arc
		(start 370.200682 -220.644212)
		(mid 370.404163 -220.845016)
		(end 370.483384 -221.1197)
		(width 0.0889)
		(layer "In13.Cu")
		(net "P5E_CPU0_PE2_RX_DP<1>")
	)
	(arc
		(start 370.200682 -217.388694)
		(mid 370.404163 -217.589498)
		(end 370.483384 -217.864182)
		(width 0.0889)
		(layer "In13.Cu")
		(net "P5E_CPU0_PE2_RX_DP<1>")
	)
	(arc
		(start 370.483384 -216.25052)
		(mid 370.409393 -216.530086)
		(end 370.206778 -216.736422)
		(width 0.0889)
		(layer "In13.Cu")
		(net "P5E_CPU0_PE2_RX_DP<1>")
	)
	(arc
		(start 370.206778 -219.020136)
		(mid 370.483352 -219.506038)
		(end 370.206778 -219.99194)
		(width 0.0889)
		(layer "In13.Cu")
		(net "P5E_CPU0_PE2_RX_DP<1>")
	)
	(arc
		(start 369.713764 -221.660974)
		(mid 369.703693 -221.657005)
		(end 369.693698 -221.652846)
		(width 0.0889)
		(layer "In13.Cu")
		(net "P5E_CPU0_PE2_RX_DP<1>")
	)
	(arc
		(start 370.013484 -217.072972)
		(mid 370.065754 -217.255337)
		(end 370.200682 -217.388694)
		(width 0.0889)
		(layer "In13.Cu")
		(net "P5E_CPU0_PE2_RX_DP<1>")
	)
	(arc
		(start 370.95303 -215.452198)
		(mid 370.87366 -215.725932)
		(end 370.670836 -215.926162)
		(width 0.0889)
		(layer "In13.Cu")
		(net "P5E_CPU0_PE2_RX_DP<1>")
	)
	(segment
		(start 382.605534 -222.48368)
		(end 382.605534 -221.94774)
		(width 0.13208)
		(layer "F.Cu")
		(net "P5E_CPU0_PE2_RX_DP<15>")
	)
	(segment
		(start 384.390138 -224.399348)
		(end 384.390138 -224.389442)
		(width 0.0889)
		(layer "In13.Cu")
		(net "P5E_CPU0_PE2_RX_DP<15>")
	)
	(segment
		(start 393.199874 -339.319108)
		(end 386.225796 -310.52262)
		(width 0.14732)
		(layer "In13.Cu")
		(net "P5E_CPU0_PE2_RX_DP<15>")
	)
	(segment
		(start 385.624324 -248.024142)
		(end 386.247132 -245.965218)
		(width 0.14732)
		(layer "In13.Cu")
		(net "P5E_CPU0_PE2_RX_DP<15>")
	)
	(segment
		(start 386.510784 -231.951276)
		(end 386.052314 -226.643692)
		(width 0.14732)
		(layer "In13.Cu")
		(net "P5E_CPU0_PE2_RX_DP<15>")
	)
	(segment
		(start 384.211576 -224.070418)
		(end 384.208274 -224.068386)
		(width 0.0889)
		(layer "In13.Cu")
		(net "P5E_CPU0_PE2_RX_DP<15>")
	)
	(segment
		(start 386.052314 -226.643692)
		(end 385.631182 -226.22256)
		(width 0.14732)
		(layer "In13.Cu")
		(net "P5E_CPU0_PE2_RX_DP<15>")
	)
	(segment
		(start 376.136154 -414.22574)
		(end 374.59539 -410.506418)
		(width 0.14732)
		(layer "In13.Cu")
		(net "P5E_CPU0_PE2_RX_DP<15>")
	)
	(segment
		(start 384.681476 -224.88398)
		(end 384.672586 -224.8789)
		(width 0.0889)
		(layer "In13.Cu")
		(net "P5E_CPU0_PE2_RX_DP<15>")
	)
	(segment
		(start 382.84023 -221.655894)
		(end 382.761998 -221.676722)
		(width 0.0889)
		(layer "In13.Cu")
		(net "P5E_CPU0_PE2_RX_DP<15>")
	)
	(segment
		(start 374.59539 -410.506418)
		(end 374.59539 -406.165558)
		(width 0.14732)
		(layer "In13.Cu")
		(net "P5E_CPU0_PE2_RX_DP<15>")
	)
	(segment
		(start 374.59539 -406.165558)
		(end 373.24919 -404.819358)
		(width 0.14732)
		(layer "In13.Cu")
		(net "P5E_CPU0_PE2_RX_DP<15>")
	)
	(segment
		(start 383.919984 -223.575626)
		(end 383.919984 -223.56699)
		(width 0.0889)
		(layer "In13.Cu")
		(net "P5E_CPU0_PE2_RX_DP<15>")
	)
	(segment
		(start 385.57073 -252.83287)
		(end 385.173474 -250.579636)
		(width 0.14732)
		(layer "In13.Cu")
		(net "P5E_CPU0_PE2_RX_DP<15>")
	)
	(segment
		(start 388.987284 -259.7023)
		(end 388.203694 -257.242564)
		(width 0.14732)
		(layer "In13.Cu")
		(net "P5E_CPU0_PE2_RX_DP<15>")
	)
	(segment
		(start 385.631182 -226.22256)
		(end 385.615688 -226.207066)
		(width 0.0889)
		(layer "In13.Cu")
		(net "P5E_CPU0_PE2_RX_DP<15>")
	)
	(segment
		(start 373.60225 -399.168874)
		(end 390.869424 -353.604322)
		(width 0.14732)
		(layer "In13.Cu")
		(net "P5E_CPU0_PE2_RX_DP<15>")
	)
	(segment
		(start 385.615688 -226.207066)
		(end 385.615688 -226.147122)
		(width 0.0889)
		(layer "In13.Cu")
		(net "P5E_CPU0_PE2_RX_DP<15>")
	)
	(segment
		(start 383.259076 -222.434912)
		(end 383.255266 -222.43288)
		(width 0.0889)
		(layer "In13.Cu")
		(net "P5E_CPU0_PE2_RX_DP<15>")
	)
	(segment
		(start 386.179568 -253.702312)
		(end 385.57073 -252.83287)
		(width 0.14732)
		(layer "In13.Cu")
		(net "P5E_CPU0_PE2_RX_DP<15>")
	)
	(segment
		(start 373.24919 -400.432524)
		(end 373.60225 -399.168874)
		(width 0.14732)
		(layer "In13.Cu")
		(net "P5E_CPU0_PE2_RX_DP<15>")
	)
	(segment
		(start 384.860038 -225.213164)
		(end 384.860038 -225.203258)
		(width 0.0889)
		(layer "In13.Cu")
		(net "P5E_CPU0_PE2_RX_DP<15>")
	)
	(segment
		(start 381.28702 -434.027072)
		(end 380.95555 -434.027072)
		(width 0.14732)
		(layer "In13.Cu")
		(net "P5E_CPU0_PE2_RX_DP<15>")
	)
	(segment
		(start 384.211576 -224.070164)
		(end 384.211576 -224.070418)
		(width 0.0889)
		(layer "In13.Cu")
		(net "P5E_CPU0_PE2_RX_DP<15>")
	)
	(segment
		(start 382.761998 -221.676722)
		(end 382.605534 -221.94774)
		(width 0.0889)
		(layer "In13.Cu")
		(net "P5E_CPU0_PE2_RX_DP<15>")
	)
	(segment
		(start 388.130034 -271.51203)
		(end 388.130288 -271.50695)
		(width 0.14732)
		(layer "In13.Cu")
		(net "P5E_CPU0_PE2_RX_DP<15>")
	)
	(segment
		(start 388.12978 -271.51203)
		(end 388.130034 -271.51203)
		(width 0.14732)
		(layer "In13.Cu")
		(net "P5E_CPU0_PE2_RX_DP<15>")
	)
	(segment
		(start 384.201416 -224.064322)
		(end 384.19659 -224.061528)
		(width 0.0889)
		(layer "In13.Cu")
		(net "P5E_CPU0_PE2_RX_DP<15>")
	)
	(segment
		(start 386.225796 -310.52262)
		(end 388.12978 -271.51203)
		(width 0.14732)
		(layer "In13.Cu")
		(net "P5E_CPU0_PE2_RX_DP<15>")
	)
	(segment
		(start 381.750062 -434.48986)
		(end 381.749808 -434.48986)
		(width 0.14732)
		(layer "In13.Cu")
		(net "P5E_CPU0_PE2_RX_DP<15>")
	)
	(segment
		(start 383.271776 -222.442278)
		(end 383.262886 -222.437198)
		(width 0.0889)
		(layer "In13.Cu")
		(net "P5E_CPU0_PE2_RX_DP<15>")
	)
	(segment
		(start 384.205734 -224.067116)
		(end 384.203702 -224.065846)
		(width 0.0889)
		(layer "In13.Cu")
		(net "P5E_CPU0_PE2_RX_DP<15>")
	)
	(segment
		(start 383.262886 -222.437198)
		(end 383.259076 -222.434912)
		(width 0.0889)
		(layer "In13.Cu")
		(net "P5E_CPU0_PE2_RX_DP<15>")
	)
	(segment
		(start 386.839206 -255.294638)
		(end 386.179568 -253.702312)
		(width 0.14732)
		(layer "In13.Cu")
		(net "P5E_CPU0_PE2_RX_DP<15>")
	)
	(segment
		(start 385.173474 -250.579636)
		(end 385.624324 -248.024142)
		(width 0.14732)
		(layer "In13.Cu")
		(net "P5E_CPU0_PE2_RX_DP<15>")
	)
	(segment
		(start 383.450338 -222.780098)
		(end 383.450338 -222.761556)
		(width 0.0889)
		(layer "In13.Cu")
		(net "P5E_CPU0_PE2_RX_DP<15>")
	)
	(segment
		(start 385.615688 -226.147122)
		(end 385.220464 -225.751898)
		(width 0.0889)
		(layer "In13.Cu")
		(net "P5E_CPU0_PE2_RX_DP<15>")
	)
	(segment
		(start 380.542546 -433.614068)
		(end 376.136154 -414.22574)
		(width 0.14732)
		(layer "In13.Cu")
		(net "P5E_CPU0_PE2_RX_DP<15>")
	)
	(segment
		(start 373.24919 -404.819358)
		(end 373.24919 -400.432524)
		(width 0.14732)
		(layer "In13.Cu")
		(net "P5E_CPU0_PE2_RX_DP<15>")
	)
	(segment
		(start 390.869424 -353.604322)
		(end 393.199874 -339.319108)
		(width 0.14732)
		(layer "In13.Cu")
		(net "P5E_CPU0_PE2_RX_DP<15>")
	)
	(segment
		(start 384.208274 -224.068386)
		(end 384.205734 -224.067116)
		(width 0.0889)
		(layer "In13.Cu")
		(net "P5E_CPU0_PE2_RX_DP<15>")
	)
	(segment
		(start 384.203702 -224.065846)
		(end 384.201416 -224.064322)
		(width 0.0889)
		(layer "In13.Cu")
		(net "P5E_CPU0_PE2_RX_DP<15>")
	)
	(segment
		(start 383.255266 -222.43288)
		(end 383.250694 -222.430086)
		(width 0.0889)
		(layer "In13.Cu")
		(net "P5E_CPU0_PE2_RX_DP<15>")
	)
	(segment
		(start 380.95555 -434.027072)
		(end 380.542546 -433.614068)
		(width 0.14732)
		(layer "In13.Cu")
		(net "P5E_CPU0_PE2_RX_DP<15>")
	)
	(segment
		(start 381.749808 -434.48986)
		(end 381.28702 -434.027072)
		(width 0.14732)
		(layer "In13.Cu")
		(net "P5E_CPU0_PE2_RX_DP<15>")
	)
	(segment
		(start 388.203694 -257.242564)
		(end 386.839206 -255.294638)
		(width 0.14732)
		(layer "In13.Cu")
		(net "P5E_CPU0_PE2_RX_DP<15>")
	)
	(segment
		(start 386.247132 -245.965218)
		(end 386.510784 -231.951276)
		(width 0.14732)
		(layer "In13.Cu")
		(net "P5E_CPU0_PE2_RX_DP<15>")
	)
	(segment
		(start 388.130288 -271.50695)
		(end 388.130034 -271.50695)
		(width 0.14732)
		(layer "In13.Cu")
		(net "P5E_CPU0_PE2_RX_DP<15>")
	)
	(segment
		(start 388.130034 -271.50695)
		(end 388.987284 -259.7023)
		(width 0.14732)
		(layer "In13.Cu")
		(net "P5E_CPU0_PE2_RX_DP<15>")
	)
	(arc
		(start 384.672586 -224.8789)
		(mid 384.468251 -224.676295)
		(end 384.390138 -224.399348)
		(width 0.0889)
		(layer "In13.Cu")
		(net "P5E_CPU0_PE2_RX_DP<15>")
	)
	(arc
		(start 385.121404 -225.679762)
		(mid 384.932012 -225.479338)
		(end 384.860038 -225.213164)
		(width 0.0889)
		(layer "In13.Cu")
		(net "P5E_CPU0_PE2_RX_DP<15>")
	)
	(arc
		(start 385.220464 -225.751898)
		(mid 385.183414 -225.719752)
		(end 385.142486 -225.692716)
		(width 0.0889)
		(layer "In13.Cu")
		(net "P5E_CPU0_PE2_RX_DP<15>")
	)
	(arc
		(start 383.732786 -223.251268)
		(mid 383.5305 -223.052287)
		(end 383.450338 -222.780098)
		(width 0.0889)
		(layer "In13.Cu")
		(net "P5E_CPU0_PE2_RX_DP<15>")
	)
	(arc
		(start 383.919984 -223.56699)
		(mid 383.867714 -223.384625)
		(end 383.732786 -223.251268)
		(width 0.0889)
		(layer "In13.Cu")
		(net "P5E_CPU0_PE2_RX_DP<15>")
	)
	(arc
		(start 382.980184 -221.94774)
		(mid 382.943324 -221.785943)
		(end 382.84023 -221.655894)
		(width 0.0889)
		(layer "In13.Cu")
		(net "P5E_CPU0_PE2_RX_DP<15>")
	)
	(arc
		(start 384.390138 -224.389442)
		(mid 384.342459 -224.206542)
		(end 384.211576 -224.070164)
		(width 0.0889)
		(layer "In13.Cu")
		(net "P5E_CPU0_PE2_RX_DP<15>")
	)
	(arc
		(start 383.250694 -222.430086)
		(mid 383.052466 -222.224238)
		(end 382.980184 -221.94774)
		(width 0.0889)
		(layer "In13.Cu")
		(net "P5E_CPU0_PE2_RX_DP<15>")
	)
	(arc
		(start 383.450338 -222.761556)
		(mid 383.402659 -222.578656)
		(end 383.271776 -222.442278)
		(width 0.0889)
		(layer "In13.Cu")
		(net "P5E_CPU0_PE2_RX_DP<15>")
	)
	(arc
		(start 385.142486 -225.692716)
		(mid 385.131874 -225.686355)
		(end 385.121404 -225.679762)
		(width 0.0889)
		(layer "In13.Cu")
		(net "P5E_CPU0_PE2_RX_DP<15>")
	)
	(arc
		(start 384.19659 -224.061528)
		(mid 383.994003 -223.855177)
		(end 383.919984 -223.575626)
		(width 0.0889)
		(layer "In13.Cu")
		(net "P5E_CPU0_PE2_RX_DP<15>")
	)
	(arc
		(start 384.860038 -225.203258)
		(mid 384.812359 -225.020358)
		(end 384.681476 -224.88398)
		(width 0.0889)
		(layer "In13.Cu")
		(net "P5E_CPU0_PE2_RX_DP<15>")
	)
	(segment
		(start 382.135634 -221.133924)
		(end 382.135634 -221.669864)
		(width 0.13208)
		(layer "F.Cu")
		(net "P5E_CPU0_PE2_RX_DP<14>")
	)
	(segment
		(start 390.012936 -259.517896)
		(end 389.247126 -256.750312)
		(width 0.14732)
		(layer "In13.Cu")
		(net "P5E_CPU0_PE2_RX_DP<14>")
	)
	(segment
		(start 386.904484 -248.390664)
		(end 387.295136 -247.999758)
		(width 0.14732)
		(layer "In13.Cu")
		(net "P5E_CPU0_PE2_RX_DP<14>")
	)
	(segment
		(start 387.030722 -225.697796)
		(end 387.021832 -225.692716)
		(width 0.0889)
		(layer "In13.Cu")
		(net "P5E_CPU0_PE2_RX_DP<14>")
	)
	(segment
		(start 385.151122 -224.070164)
		(end 385.142232 -224.065084)
		(width 0.0889)
		(layer "In13.Cu")
		(net "P5E_CPU0_PE2_RX_DP<14>")
	)
	(segment
		(start 387.697218 -247.718326)
		(end 388.238492 -247.374156)
		(width 0.14732)
		(layer "In13.Cu")
		(net "P5E_CPU0_PE2_RX_DP<14>")
	)
	(segment
		(start 387.935216 -254.252476)
		(end 386.904484 -251.254514)
		(width 0.14732)
		(layer "In13.Cu")
		(net "P5E_CPU0_PE2_RX_DP<14>")
	)
	(segment
		(start 383.076958 -434.993796)
		(end 382.79197 -434.708808)
		(width 0.14732)
		(layer "In13.Cu")
		(net "P5E_CPU0_PE2_RX_DP<14>")
	)
	(segment
		(start 391.867898 -353.714558)
		(end 394.205714 -339.28939)
		(width 0.14732)
		(layer "In13.Cu")
		(net "P5E_CPU0_PE2_RX_DP<14>")
	)
	(segment
		(start 384.680968 -223.256348)
		(end 384.672078 -223.251268)
		(width 0.0889)
		(layer "In13.Cu")
		(net "P5E_CPU0_PE2_RX_DP<14>")
	)
	(segment
		(start 387.16712 -226.407218)
		(end 387.16712 -226.38512)
		(width 0.0889)
		(layer "In13.Cu")
		(net "P5E_CPU0_PE2_RX_DP<14>")
	)
	(segment
		(start 389.247126 -256.750312)
		(end 388.627874 -255.888236)
		(width 0.14732)
		(layer "In13.Cu")
		(net "P5E_CPU0_PE2_RX_DP<14>")
	)
	(segment
		(start 383.271522 -220.814646)
		(end 383.262632 -220.809566)
		(width 0.0889)
		(layer "In13.Cu")
		(net "P5E_CPU0_PE2_RX_DP<14>")
	)
	(segment
		(start 385.329684 -224.399348)
		(end 385.329684 -224.389442)
		(width 0.0889)
		(layer "In13.Cu")
		(net "P5E_CPU0_PE2_RX_DP<14>")
	)
	(segment
		(start 386.560822 -224.88398)
		(end 386.551932 -224.8789)
		(width 0.0889)
		(layer "In13.Cu")
		(net "P5E_CPU0_PE2_RX_DP<14>")
	)
	(segment
		(start 383.750058 -435.423818)
		(end 383.320036 -434.993796)
		(width 0.14732)
		(layer "In13.Cu")
		(net "P5E_CPU0_PE2_RX_DP<14>")
	)
	(segment
		(start 386.904484 -251.254514)
		(end 386.904484 -248.390664)
		(width 0.14732)
		(layer "In13.Cu")
		(net "P5E_CPU0_PE2_RX_DP<14>")
	)
	(segment
		(start 383.320036 -434.993796)
		(end 383.076958 -434.993796)
		(width 0.14732)
		(layer "In13.Cu")
		(net "P5E_CPU0_PE2_RX_DP<14>")
	)
	(segment
		(start 387.951472 -230.589836)
		(end 387.16712 -226.890072)
		(width 0.14732)
		(layer "In13.Cu")
		(net "P5E_CPU0_PE2_RX_DP<14>")
	)
	(segment
		(start 388.2771 -255.06045)
		(end 388.277354 -255.06045)
		(width 0.14732)
		(layer "In13.Cu")
		(net "P5E_CPU0_PE2_RX_DP<14>")
	)
	(segment
		(start 387.16712 -226.38512)
		(end 387.209284 -226.342956)
		(width 0.0889)
		(layer "In13.Cu")
		(net "P5E_CPU0_PE2_RX_DP<14>")
	)
	(segment
		(start 387.16712 -226.890072)
		(end 387.16712 -226.407218)
		(width 0.14732)
		(layer "In13.Cu")
		(net "P5E_CPU0_PE2_RX_DP<14>")
	)
	(segment
		(start 383.450084 -221.14383)
		(end 383.450084 -221.133924)
		(width 0.0889)
		(layer "In13.Cu")
		(net "P5E_CPU0_PE2_RX_DP<14>")
	)
	(segment
		(start 385.142232 -224.065084)
		(end 385.13004 -224.057972)
		(width 0.0889)
		(layer "In13.Cu")
		(net "P5E_CPU0_PE2_RX_DP<14>")
	)
	(segment
		(start 382.000252 -220.784928)
		(end 381.97917 -220.862906)
		(width 0.0889)
		(layer "In13.Cu")
		(net "P5E_CPU0_PE2_RX_DP<14>")
	)
	(segment
		(start 389.217662 -244.310154)
		(end 387.951472 -230.589836)
		(width 0.14732)
		(layer "In13.Cu")
		(net "P5E_CPU0_PE2_RX_DP<14>")
	)
	(segment
		(start 384.202432 -222.437198)
		(end 384.196336 -222.433642)
		(width 0.0889)
		(layer "In13.Cu")
		(net "P5E_CPU0_PE2_RX_DP<14>")
	)
	(segment
		(start 376.585988 -399.042636)
		(end 391.867898 -353.714558)
		(width 0.14732)
		(layer "In13.Cu")
		(net "P5E_CPU0_PE2_RX_DP<14>")
	)
	(segment
		(start 382.79197 -434.708808)
		(end 382.79197 -424.714924)
		(width 0.14732)
		(layer "In13.Cu")
		(net "P5E_CPU0_PE2_RX_DP<14>")
	)
	(segment
		(start 394.205714 -339.28939)
		(end 387.181598 -310.410098)
		(width 0.14732)
		(layer "In13.Cu")
		(net "P5E_CPU0_PE2_RX_DP<14>")
	)
	(segment
		(start 377.65863 -406.165558)
		(end 376.31243 -404.819358)
		(width 0.14732)
		(layer "In13.Cu")
		(net "P5E_CPU0_PE2_RX_DP<14>")
	)
	(segment
		(start 383.91973 -221.94774)
		(end 383.91973 -221.939104)
		(width 0.0889)
		(layer "In13.Cu")
		(net "P5E_CPU0_PE2_RX_DP<14>")
	)
	(segment
		(start 376.31243 -400.5199)
		(end 376.585988 -399.042636)
		(width 0.14732)
		(layer "In13.Cu")
		(net "P5E_CPU0_PE2_RX_DP<14>")
	)
	(segment
		(start 388.277354 -255.06045)
		(end 387.935216 -254.252476)
		(width 0.14732)
		(layer "In13.Cu")
		(net "P5E_CPU0_PE2_RX_DP<14>")
	)
	(segment
		(start 382.337564 -220.818202)
		(end 382.322832 -220.809566)
		(width 0.0889)
		(layer "In13.Cu")
		(net "P5E_CPU0_PE2_RX_DP<14>")
	)
	(segment
		(start 376.31243 -404.819358)
		(end 376.31243 -400.5199)
		(width 0.14732)
		(layer "In13.Cu")
		(net "P5E_CPU0_PE2_RX_DP<14>")
	)
	(segment
		(start 388.627874 -255.888236)
		(end 388.2771 -255.06045)
		(width 0.14732)
		(layer "In13.Cu")
		(net "P5E_CPU0_PE2_RX_DP<14>")
	)
	(segment
		(start 387.209284 -226.342956)
		(end 387.209284 -226.017074)
		(width 0.0889)
		(layer "In13.Cu")
		(net "P5E_CPU0_PE2_RX_DP<14>")
	)
	(segment
		(start 382.79197 -424.714924)
		(end 381.001016 -419.83152)
		(width 0.14732)
		(layer "In13.Cu")
		(net "P5E_CPU0_PE2_RX_DP<14>")
	)
	(segment
		(start 387.295136 -247.999758)
		(end 387.697218 -247.718326)
		(width 0.14732)
		(layer "In13.Cu")
		(net "P5E_CPU0_PE2_RX_DP<14>")
	)
	(segment
		(start 387.181598 -310.410098)
		(end 390.012936 -259.517896)
		(width 0.14732)
		(layer "In13.Cu")
		(net "P5E_CPU0_PE2_RX_DP<14>")
	)
	(segment
		(start 377.65863 -410.717746)
		(end 377.65863 -406.165558)
		(width 0.14732)
		(layer "In13.Cu")
		(net "P5E_CPU0_PE2_RX_DP<14>")
	)
	(segment
		(start 386.739384 -225.213164)
		(end 386.739384 -225.203258)
		(width 0.0889)
		(layer "In13.Cu")
		(net "P5E_CPU0_PE2_RX_DP<14>")
	)
	(segment
		(start 384.38963 -222.780098)
		(end 384.38963 -222.75292)
		(width 0.0889)
		(layer "In13.Cu")
		(net "P5E_CPU0_PE2_RX_DP<14>")
	)
	(segment
		(start 381.001016 -419.83152)
		(end 381.001016 -419.831774)
		(width 0.14732)
		(layer "In13.Cu")
		(net "P5E_CPU0_PE2_RX_DP<14>")
	)
	(segment
		(start 383.750058 -435.489858)
		(end 383.750058 -435.423818)
		(width 0.14732)
		(layer "In13.Cu")
		(net "P5E_CPU0_PE2_RX_DP<14>")
	)
	(segment
		(start 381.001016 -419.831774)
		(end 377.65863 -410.717746)
		(width 0.14732)
		(layer "In13.Cu")
		(net "P5E_CPU0_PE2_RX_DP<14>")
	)
	(segment
		(start 381.97917 -220.862906)
		(end 382.135634 -221.133924)
		(width 0.0889)
		(layer "In13.Cu")
		(net "P5E_CPU0_PE2_RX_DP<14>")
	)
	(segment
		(start 388.238492 -247.374156)
		(end 389.217662 -244.310154)
		(width 0.14732)
		(layer "In13.Cu")
		(net "P5E_CPU0_PE2_RX_DP<14>")
	)
	(arc
		(start 383.91973 -221.939104)
		(mid 383.86746 -221.756739)
		(end 383.732532 -221.623382)
		(width 0.0889)
		(layer "In13.Cu")
		(net "P5E_CPU0_PE2_RX_DP<14>")
	)
	(arc
		(start 386.177536 -224.8789)
		(mid 385.894834 -224.954676)
		(end 385.612132 -224.8789)
		(width 0.0889)
		(layer "In13.Cu")
		(net "P5E_CPU0_PE2_RX_DP<14>")
	)
	(arc
		(start 384.38963 -222.75292)
		(mid 384.33736 -222.570555)
		(end 384.202432 -222.437198)
		(width 0.0889)
		(layer "In13.Cu")
		(net "P5E_CPU0_PE2_RX_DP<14>")
	)
	(arc
		(start 382.322832 -220.809566)
		(mid 382.164344 -220.760633)
		(end 382.000252 -220.784928)
		(width 0.0889)
		(layer "In13.Cu")
		(net "P5E_CPU0_PE2_RX_DP<14>")
	)
	(arc
		(start 387.209284 -226.017074)
		(mid 387.161605 -225.834174)
		(end 387.030722 -225.697796)
		(width 0.0889)
		(layer "In13.Cu")
		(net "P5E_CPU0_PE2_RX_DP<14>")
	)
	(arc
		(start 384.196336 -222.433642)
		(mid 383.993749 -222.227291)
		(end 383.91973 -221.94774)
		(width 0.0889)
		(layer "In13.Cu")
		(net "P5E_CPU0_PE2_RX_DP<14>")
	)
	(arc
		(start 383.262632 -220.809566)
		(mid 383.075434 -220.759423)
		(end 382.888236 -220.809566)
		(width 0.0889)
		(layer "In13.Cu")
		(net "P5E_CPU0_PE2_RX_DP<14>")
	)
	(arc
		(start 387.021832 -225.692716)
		(mid 386.817497 -225.490111)
		(end 386.739384 -225.213164)
		(width 0.0889)
		(layer "In13.Cu")
		(net "P5E_CPU0_PE2_RX_DP<14>")
	)
	(arc
		(start 382.888236 -220.809566)
		(mid 382.614007 -220.885491)
		(end 382.337564 -220.818202)
		(width 0.0889)
		(layer "In13.Cu")
		(net "P5E_CPU0_PE2_RX_DP<14>")
	)
	(arc
		(start 384.85953 -223.575626)
		(mid 384.811851 -223.392726)
		(end 384.680968 -223.256348)
		(width 0.0889)
		(layer "In13.Cu")
		(net "P5E_CPU0_PE2_RX_DP<14>")
	)
	(arc
		(start 386.551932 -224.8789)
		(mid 386.364734 -224.828757)
		(end 386.177536 -224.8789)
		(width 0.0889)
		(layer "In13.Cu")
		(net "P5E_CPU0_PE2_RX_DP<14>")
	)
	(arc
		(start 386.739384 -225.203258)
		(mid 386.691705 -225.020358)
		(end 386.560822 -224.88398)
		(width 0.0889)
		(layer "In13.Cu")
		(net "P5E_CPU0_PE2_RX_DP<14>")
	)
	(arc
		(start 383.732532 -221.623382)
		(mid 383.528197 -221.420777)
		(end 383.450084 -221.14383)
		(width 0.0889)
		(layer "In13.Cu")
		(net "P5E_CPU0_PE2_RX_DP<14>")
	)
	(arc
		(start 384.672078 -223.251268)
		(mid 384.469792 -223.052287)
		(end 384.38963 -222.780098)
		(width 0.0889)
		(layer "In13.Cu")
		(net "P5E_CPU0_PE2_RX_DP<14>")
	)
	(arc
		(start 385.612132 -224.8789)
		(mid 385.407797 -224.676295)
		(end 385.329684 -224.399348)
		(width 0.0889)
		(layer "In13.Cu")
		(net "P5E_CPU0_PE2_RX_DP<14>")
	)
	(arc
		(start 385.329684 -224.389442)
		(mid 385.282005 -224.206542)
		(end 385.151122 -224.070164)
		(width 0.0889)
		(layer "In13.Cu")
		(net "P5E_CPU0_PE2_RX_DP<14>")
	)
	(arc
		(start 385.13004 -224.057972)
		(mid 384.931812 -223.852124)
		(end 384.85953 -223.575626)
		(width 0.0889)
		(layer "In13.Cu")
		(net "P5E_CPU0_PE2_RX_DP<14>")
	)
	(arc
		(start 383.450084 -221.133924)
		(mid 383.402405 -220.951024)
		(end 383.271522 -220.814646)
		(width 0.0889)
		(layer "In13.Cu")
		(net "P5E_CPU0_PE2_RX_DP<14>")
	)
	(segment
		(start 380.725934 -221.947994)
		(end 380.72568 -221.94774)
		(width 0.13208)
		(layer "F.Cu")
		(net "P5E_CPU0_PE2_RX_DP<13>")
	)
	(segment
		(start 380.725934 -222.48368)
		(end 380.725934 -221.947994)
		(width 0.13208)
		(layer "F.Cu")
		(net "P5E_CPU0_PE2_RX_DP<13>")
	)
	(segment
		(start 385.271772 -433.993798)
		(end 385.076954 -433.993798)
		(width 0.14732)
		(layer "In13.Cu")
		(net "P5E_CPU0_PE2_RX_DP<13>")
	)
	(segment
		(start 380.971298 -221.652846)
		(end 380.882144 -221.676722)
		(width 0.0889)
		(layer "In13.Cu")
		(net "P5E_CPU0_PE2_RX_DP<13>")
	)
	(segment
		(start 381.469646 -220.639132)
		(end 381.478536 -220.644212)
		(width 0.0889)
		(layer "In13.Cu")
		(net "P5E_CPU0_PE2_RX_DP<13>")
	)
	(segment
		(start 379.37567 -400.392392)
		(end 379.57633 -399.226278)
		(width 0.14732)
		(layer "In13.Cu")
		(net "P5E_CPU0_PE2_RX_DP<13>")
	)
	(segment
		(start 385.076954 -433.993798)
		(end 384.791966 -433.70881)
		(width 0.14732)
		(layer "In13.Cu")
		(net "P5E_CPU0_PE2_RX_DP<13>")
	)
	(segment
		(start 388.713218 -253.64821)
		(end 388.596378 -253.31547)
		(width 0.14732)
		(layer "In13.Cu")
		(net "P5E_CPU0_PE2_RX_DP<13>")
	)
	(segment
		(start 390.308084 -256.528062)
		(end 389.324596 -255.123188)
		(width 0.14732)
		(layer "In13.Cu")
		(net "P5E_CPU0_PE2_RX_DP<13>")
	)
	(segment
		(start 381.478536 -221.623382)
		(end 381.468122 -221.629478)
		(width 0.0889)
		(layer "In13.Cu")
		(net "P5E_CPU0_PE2_RX_DP<13>")
	)
	(segment
		(start 390.213596 -244.346476)
		(end 389.225028 -230.350568)
		(width 0.14732)
		(layer "In13.Cu")
		(net "P5E_CPU0_PE2_RX_DP<13>")
	)
	(segment
		(start 388.596378 -253.31547)
		(end 388.266686 -252.182884)
		(width 0.14732)
		(layer "In13.Cu")
		(net "P5E_CPU0_PE2_RX_DP<13>")
	)
	(segment
		(start 379.57633 -399.226278)
		(end 392.828018 -353.89185)
		(width 0.14732)
		(layer "In13.Cu")
		(net "P5E_CPU0_PE2_RX_DP<13>")
	)
	(segment
		(start 385.141978 -222.437198)
		(end 385.135882 -222.433642)
		(width 0.0889)
		(layer "In13.Cu")
		(net "P5E_CPU0_PE2_RX_DP<13>")
	)
	(segment
		(start 392.828018 -353.89185)
		(end 395.186408 -339.353398)
		(width 0.14732)
		(layer "In13.Cu")
		(net "P5E_CPU0_PE2_RX_DP<13>")
	)
	(segment
		(start 380.72187 -410.963872)
		(end 380.72187 -406.165558)
		(width 0.14732)
		(layer "In13.Cu")
		(net "P5E_CPU0_PE2_RX_DP<13>")
	)
	(segment
		(start 379.37567 -404.819358)
		(end 379.37567 -400.392392)
		(width 0.14732)
		(layer "In13.Cu")
		(net "P5E_CPU0_PE2_RX_DP<13>")
	)
	(segment
		(start 384.791966 -424.498008)
		(end 380.72187 -410.963872)
		(width 0.14732)
		(layer "In13.Cu")
		(net "P5E_CPU0_PE2_RX_DP<13>")
	)
	(segment
		(start 387.542278 -224.626678)
		(end 387.542278 -224.566734)
		(width 0.0889)
		(layer "In13.Cu")
		(net "P5E_CPU0_PE2_RX_DP<13>")
	)
	(segment
		(start 383.358136 -219.995496)
		(end 383.347722 -220.001592)
		(width 0.0889)
		(layer "In13.Cu")
		(net "P5E_CPU0_PE2_RX_DP<13>")
	)
	(segment
		(start 385.32943 -222.769176)
		(end 385.32943 -222.761556)
		(width 0.0889)
		(layer "In13.Cu")
		(net "P5E_CPU0_PE2_RX_DP<13>")
	)
	(segment
		(start 391.039604 -259.378958)
		(end 390.308084 -256.528062)
		(width 0.14732)
		(layer "In13.Cu")
		(net "P5E_CPU0_PE2_RX_DP<13>")
	)
	(segment
		(start 387.824218 -224.908618)
		(end 387.557772 -224.642172)
		(width 0.14732)
		(layer "In13.Cu")
		(net "P5E_CPU0_PE2_RX_DP<13>")
	)
	(segment
		(start 395.186408 -339.353398)
		(end 388.1882 -310.271668)
		(width 0.14732)
		(layer "In13.Cu")
		(net "P5E_CPU0_PE2_RX_DP<13>")
	)
	(segment
		(start 381.478536 -219.995496)
		(end 381.469646 -220.000576)
		(width 0.0889)
		(layer "In13.Cu")
		(net "P5E_CPU0_PE2_RX_DP<13>")
	)
	(segment
		(start 388.1882 -310.271668)
		(end 391.039604 -259.378958)
		(width 0.14732)
		(layer "In13.Cu")
		(net "P5E_CPU0_PE2_RX_DP<13>")
	)
	(segment
		(start 389.324596 -255.123188)
		(end 388.713218 -253.64821)
		(width 0.14732)
		(layer "In13.Cu")
		(net "P5E_CPU0_PE2_RX_DP<13>")
	)
	(segment
		(start 385.621022 -223.256348)
		(end 385.612132 -223.251268)
		(width 0.0889)
		(layer "In13.Cu")
		(net "P5E_CPU0_PE2_RX_DP<13>")
	)
	(segment
		(start 388.266686 -252.182884)
		(end 388.164832 -250.344686)
		(width 0.14732)
		(layer "In13.Cu")
		(net "P5E_CPU0_PE2_RX_DP<13>")
	)
	(segment
		(start 383.919984 -220.338396)
		(end 383.919984 -220.319854)
		(width 0.0889)
		(layer "In13.Cu")
		(net "P5E_CPU0_PE2_RX_DP<13>")
	)
	(segment
		(start 384.211322 -220.814646)
		(end 384.202432 -220.809566)
		(width 0.0889)
		(layer "In13.Cu")
		(net "P5E_CPU0_PE2_RX_DP<13>")
	)
	(segment
		(start 385.750054 -434.48986)
		(end 385.750054 -434.47208)
		(width 0.14732)
		(layer "In13.Cu")
		(net "P5E_CPU0_PE2_RX_DP<13>")
	)
	(segment
		(start 384.791966 -433.70881)
		(end 384.791966 -424.498008)
		(width 0.14732)
		(layer "In13.Cu")
		(net "P5E_CPU0_PE2_RX_DP<13>")
	)
	(segment
		(start 384.389884 -221.149418)
		(end 384.389884 -221.133924)
		(width 0.0889)
		(layer "In13.Cu")
		(net "P5E_CPU0_PE2_RX_DP<13>")
	)
	(segment
		(start 387.557772 -224.642172)
		(end 387.542278 -224.626678)
		(width 0.0889)
		(layer "In13.Cu")
		(net "P5E_CPU0_PE2_RX_DP<13>")
	)
	(segment
		(start 388.336028 -226.073208)
		(end 387.824218 -224.908618)
		(width 0.14732)
		(layer "In13.Cu")
		(net "P5E_CPU0_PE2_RX_DP<13>")
	)
	(segment
		(start 388.375144 -249.154442)
		(end 388.884414 -248.426732)
		(width 0.14732)
		(layer "In13.Cu")
		(net "P5E_CPU0_PE2_RX_DP<13>")
	)
	(segment
		(start 387.542278 -224.566734)
		(end 387.09981 -224.124266)
		(width 0.0889)
		(layer "In13.Cu")
		(net "P5E_CPU0_PE2_RX_DP<13>")
	)
	(segment
		(start 383.741422 -220.000576)
		(end 383.732532 -219.995496)
		(width 0.0889)
		(layer "In13.Cu")
		(net "P5E_CPU0_PE2_RX_DP<13>")
	)
	(segment
		(start 385.799584 -223.585532)
		(end 385.799584 -223.575626)
		(width 0.0889)
		(layer "In13.Cu")
		(net "P5E_CPU0_PE2_RX_DP<13>")
	)
	(segment
		(start 389.225028 -230.350568)
		(end 388.336028 -226.073208)
		(width 0.14732)
		(layer "In13.Cu")
		(net "P5E_CPU0_PE2_RX_DP<13>")
	)
	(segment
		(start 388.884414 -248.426732)
		(end 390.213596 -244.346476)
		(width 0.14732)
		(layer "In13.Cu")
		(net "P5E_CPU0_PE2_RX_DP<13>")
	)
	(segment
		(start 385.150868 -222.442278)
		(end 385.141978 -222.437198)
		(width 0.0889)
		(layer "In13.Cu")
		(net "P5E_CPU0_PE2_RX_DP<13>")
	)
	(segment
		(start 380.882144 -221.676722)
		(end 380.72568 -221.94774)
		(width 0.0889)
		(layer "In13.Cu")
		(net "P5E_CPU0_PE2_RX_DP<13>")
	)
	(segment
		(start 382.418082 -219.995496)
		(end 382.407668 -220.001592)
		(width 0.0889)
		(layer "In13.Cu")
		(net "P5E_CPU0_PE2_RX_DP<13>")
	)
	(segment
		(start 385.750054 -434.47208)
		(end 385.271772 -433.993798)
		(width 0.14732)
		(layer "In13.Cu")
		(net "P5E_CPU0_PE2_RX_DP<13>")
	)
	(segment
		(start 388.164832 -250.344686)
		(end 388.375144 -249.154442)
		(width 0.14732)
		(layer "In13.Cu")
		(net "P5E_CPU0_PE2_RX_DP<13>")
	)
	(segment
		(start 380.72187 -406.165558)
		(end 379.37567 -404.819358)
		(width 0.14732)
		(layer "In13.Cu")
		(net "P5E_CPU0_PE2_RX_DP<13>")
	)
	(segment
		(start 381.760984 -221.115382)
		(end 381.760984 -221.14383)
		(width 0.0889)
		(layer "In13.Cu")
		(net "P5E_CPU0_PE2_RX_DP<13>")
	)
	(segment
		(start 384.680968 -221.628462)
		(end 384.673094 -221.62389)
		(width 0.0889)
		(layer "In13.Cu")
		(net "P5E_CPU0_PE2_RX_DP<13>")
	)
	(segment
		(start 384.673094 -221.62389)
		(end 384.672078 -221.623382)
		(width 0.0889)
		(layer "In13.Cu")
		(net "P5E_CPU0_PE2_RX_DP<13>")
	)
	(arc
		(start 384.85953 -221.94774)
		(mid 384.811851 -221.76484)
		(end 384.680968 -221.628462)
		(width 0.0889)
		(layer "In13.Cu")
		(net "P5E_CPU0_PE2_RX_DP<13>")
	)
	(arc
		(start 381.478536 -220.644212)
		(mid 381.680822 -220.843193)
		(end 381.760984 -221.115382)
		(width 0.0889)
		(layer "In13.Cu")
		(net "P5E_CPU0_PE2_RX_DP<13>")
	)
	(arc
		(start 385.799584 -223.575626)
		(mid 385.751905 -223.392726)
		(end 385.621022 -223.256348)
		(width 0.0889)
		(layer "In13.Cu")
		(net "P5E_CPU0_PE2_RX_DP<13>")
	)
	(arc
		(start 387.021832 -224.065084)
		(mid 386.834634 -224.014941)
		(end 386.647436 -224.065084)
		(width 0.0889)
		(layer "In13.Cu")
		(net "P5E_CPU0_PE2_RX_DP<13>")
	)
	(arc
		(start 383.919984 -220.319854)
		(mid 383.872305 -220.136954)
		(end 383.741422 -220.000576)
		(width 0.0889)
		(layer "In13.Cu")
		(net "P5E_CPU0_PE2_RX_DP<13>")
	)
	(arc
		(start 381.291338 -220.332046)
		(mid 381.341831 -220.508024)
		(end 381.469646 -220.639132)
		(width 0.0889)
		(layer "In13.Cu")
		(net "P5E_CPU0_PE2_RX_DP<13>")
	)
	(arc
		(start 387.09981 -224.124266)
		(mid 387.06276 -224.09212)
		(end 387.021832 -224.065084)
		(width 0.0889)
		(layer "In13.Cu")
		(net "P5E_CPU0_PE2_RX_DP<13>")
	)
	(arc
		(start 382.407668 -220.001592)
		(mid 382.12949 -220.071315)
		(end 381.852932 -219.995496)
		(width 0.0889)
		(layer "In13.Cu")
		(net "P5E_CPU0_PE2_RX_DP<13>")
	)
	(arc
		(start 381.291084 -220.31325)
		(mid 381.291094 -220.32265)
		(end 381.291338 -220.332046)
		(width 0.0889)
		(layer "In13.Cu")
		(net "P5E_CPU0_PE2_RX_DP<13>")
	)
	(arc
		(start 384.672078 -221.623382)
		(mid 384.469255 -221.423151)
		(end 384.389884 -221.149418)
		(width 0.0889)
		(layer "In13.Cu")
		(net "P5E_CPU0_PE2_RX_DP<13>")
	)
	(arc
		(start 383.732532 -219.995496)
		(mid 383.545334 -219.945353)
		(end 383.358136 -219.995496)
		(width 0.0889)
		(layer "In13.Cu")
		(net "P5E_CPU0_PE2_RX_DP<13>")
	)
	(arc
		(start 384.389884 -221.133924)
		(mid 384.342205 -220.951024)
		(end 384.211322 -220.814646)
		(width 0.0889)
		(layer "In13.Cu")
		(net "P5E_CPU0_PE2_RX_DP<13>")
	)
	(arc
		(start 382.792478 -219.995496)
		(mid 382.60528 -219.945353)
		(end 382.418082 -219.995496)
		(width 0.0889)
		(layer "In13.Cu")
		(net "P5E_CPU0_PE2_RX_DP<13>")
	)
	(arc
		(start 381.852932 -219.995496)
		(mid 381.665734 -219.945353)
		(end 381.478536 -219.995496)
		(width 0.0889)
		(layer "In13.Cu")
		(net "P5E_CPU0_PE2_RX_DP<13>")
	)
	(arc
		(start 386.647436 -224.065084)
		(mid 386.364734 -224.14086)
		(end 386.082032 -224.065084)
		(width 0.0889)
		(layer "In13.Cu")
		(net "P5E_CPU0_PE2_RX_DP<13>")
	)
	(arc
		(start 385.32943 -222.761556)
		(mid 385.281751 -222.578656)
		(end 385.150868 -222.442278)
		(width 0.0889)
		(layer "In13.Cu")
		(net "P5E_CPU0_PE2_RX_DP<13>")
	)
	(arc
		(start 383.347722 -220.001592)
		(mid 383.06929 -220.071438)
		(end 382.792478 -219.995496)
		(width 0.0889)
		(layer "In13.Cu")
		(net "P5E_CPU0_PE2_RX_DP<13>")
	)
	(arc
		(start 381.468122 -221.629478)
		(mid 381.233242 -221.698013)
		(end 380.991364 -221.660974)
		(width 0.0889)
		(layer "In13.Cu")
		(net "P5E_CPU0_PE2_RX_DP<13>")
	)
	(arc
		(start 381.760984 -221.14383)
		(mid 381.682873 -221.420779)
		(end 381.478536 -221.623382)
		(width 0.0889)
		(layer "In13.Cu")
		(net "P5E_CPU0_PE2_RX_DP<13>")
	)
	(arc
		(start 384.202432 -220.809566)
		(mid 384.000146 -220.610585)
		(end 383.919984 -220.338396)
		(width 0.0889)
		(layer "In13.Cu")
		(net "P5E_CPU0_PE2_RX_DP<13>")
	)
	(arc
		(start 380.991364 -221.660974)
		(mid 380.981293 -221.657005)
		(end 380.971298 -221.652846)
		(width 0.0889)
		(layer "In13.Cu")
		(net "P5E_CPU0_PE2_RX_DP<13>")
	)
	(arc
		(start 386.082032 -224.065084)
		(mid 385.877697 -223.862479)
		(end 385.799584 -223.585532)
		(width 0.0889)
		(layer "In13.Cu")
		(net "P5E_CPU0_PE2_RX_DP<13>")
	)
	(arc
		(start 385.612132 -223.251268)
		(mid 385.40706 -223.047589)
		(end 385.32943 -222.769176)
		(width 0.0889)
		(layer "In13.Cu")
		(net "P5E_CPU0_PE2_RX_DP<13>")
	)
	(arc
		(start 381.469646 -220.000576)
		(mid 381.340357 -220.134062)
		(end 381.291084 -220.31325)
		(width 0.0889)
		(layer "In13.Cu")
		(net "P5E_CPU0_PE2_RX_DP<13>")
	)
	(arc
		(start 385.135882 -222.433642)
		(mid 384.933469 -222.227229)
		(end 384.85953 -221.94774)
		(width 0.0889)
		(layer "In13.Cu")
		(net "P5E_CPU0_PE2_RX_DP<13>")
	)
	(segment
		(start 380.25578 -221.134178)
		(end 380.256034 -221.133924)
		(width 0.13208)
		(layer "F.Cu")
		(net "P5E_CPU0_PE2_RX_DP<12>")
	)
	(segment
		(start 380.25578 -221.669864)
		(end 380.25578 -221.134178)
		(width 0.13208)
		(layer "F.Cu")
		(net "P5E_CPU0_PE2_RX_DP<12>")
	)
	(segment
		(start 387.857238 -223.482662)
		(end 387.857238 -223.422718)
		(width 0.0889)
		(layer "In13.Cu")
		(net "P5E_CPU0_PE2_RX_DP<12>")
	)
	(segment
		(start 386.791962 -434.662326)
		(end 386.791962 -424.962828)
		(width 0.14732)
		(layer "In13.Cu")
		(net "P5E_CPU0_PE2_RX_DP<12>")
	)
	(segment
		(start 385.621022 -221.628462)
		(end 385.612132 -221.623382)
		(width 0.0889)
		(layer "In13.Cu")
		(net "P5E_CPU0_PE2_RX_DP<12>")
	)
	(segment
		(start 386.791962 -424.962828)
		(end 386.79247 -424.96232)
		(width 0.14732)
		(layer "In13.Cu")
		(net "P5E_CPU0_PE2_RX_DP<12>")
	)
	(segment
		(start 380.538736 -219.995496)
		(end 380.537974 -219.996004)
		(width 0.0889)
		(layer "In13.Cu")
		(net "P5E_CPU0_PE2_RX_DP<12>")
	)
	(segment
		(start 384.673856 -219.996258)
		(end 384.672332 -219.995496)
		(width 0.0889)
		(layer "In13.Cu")
		(net "P5E_CPU0_PE2_RX_DP<12>")
	)
	(segment
		(start 389.432292 -249.266456)
		(end 389.757158 -248.802144)
		(width 0.14732)
		(layer "In13.Cu")
		(net "P5E_CPU0_PE2_RX_DP<12>")
	)
	(segment
		(start 380.09957 -220.862906)
		(end 380.256034 -221.133924)
		(width 0.0889)
		(layer "In13.Cu")
		(net "P5E_CPU0_PE2_RX_DP<12>")
	)
	(segment
		(start 380.537974 -219.996004)
		(end 380.535434 -219.997528)
		(width 0.0889)
		(layer "In13.Cu")
		(net "P5E_CPU0_PE2_RX_DP<12>")
	)
	(segment
		(start 387.75005 -435.413658)
		(end 387.283706 -434.947314)
		(width 0.14732)
		(layer "In13.Cu")
		(net "P5E_CPU0_PE2_RX_DP<12>")
	)
	(segment
		(start 385.151122 -220.814646)
		(end 385.142232 -220.809566)
		(width 0.0889)
		(layer "In13.Cu")
		(net "P5E_CPU0_PE2_RX_DP<12>")
	)
	(segment
		(start 391.269728 -256.280158)
		(end 390.148318 -254.67818)
		(width 0.14732)
		(layer "In13.Cu")
		(net "P5E_CPU0_PE2_RX_DP<12>")
	)
	(segment
		(start 383.78511 -411.245304)
		(end 383.78511 -406.165558)
		(width 0.14732)
		(layer "In13.Cu")
		(net "P5E_CPU0_PE2_RX_DP<12>")
	)
	(segment
		(start 382.636522 -399.000472)
		(end 388.200392 -376.43943)
		(width 0.14732)
		(layer "In13.Cu")
		(net "P5E_CPU0_PE2_RX_DP<12>")
	)
	(segment
		(start 396.149322 -339.367114)
		(end 389.13689 -310.033162)
		(width 0.14732)
		(layer "In13.Cu")
		(net "P5E_CPU0_PE2_RX_DP<12>")
	)
	(segment
		(start 389.265668 -225.834448)
		(end 388.643876 -224.2693)
		(width 0.14732)
		(layer "In13.Cu")
		(net "P5E_CPU0_PE2_RX_DP<12>")
	)
	(segment
		(start 384.859784 -220.338396)
		(end 384.859784 -220.319854)
		(width 0.0889)
		(layer "In13.Cu")
		(net "P5E_CPU0_PE2_RX_DP<12>")
	)
	(segment
		(start 389.225028 -252.137418)
		(end 389.225028 -250.44146)
		(width 0.14732)
		(layer "In13.Cu")
		(net "P5E_CPU0_PE2_RX_DP<12>")
	)
	(segment
		(start 383.78511 -406.165558)
		(end 382.43891 -404.819358)
		(width 0.14732)
		(layer "In13.Cu")
		(net "P5E_CPU0_PE2_RX_DP<12>")
	)
	(segment
		(start 391.644124 -257.78333)
		(end 391.644124 -257.783584)
		(width 0.14732)
		(layer "In13.Cu")
		(net "P5E_CPU0_PE2_RX_DP<12>")
	)
	(segment
		(start 389.50265 -253.08941)
		(end 389.225028 -252.137418)
		(width 0.14732)
		(layer "In13.Cu")
		(net "P5E_CPU0_PE2_RX_DP<12>")
	)
	(segment
		(start 392.018774 -259.28701)
		(end 391.644124 -257.78333)
		(width 0.14732)
		(layer "In13.Cu")
		(net "P5E_CPU0_PE2_RX_DP<12>")
	)
	(segment
		(start 391.644124 -257.783584)
		(end 391.269728 -256.280158)
		(width 0.14732)
		(layer "In13.Cu")
		(net "P5E_CPU0_PE2_RX_DP<12>")
	)
	(segment
		(start 385.329684 -221.14383)
		(end 385.329684 -221.133924)
		(width 0.0889)
		(layer "In13.Cu")
		(net "P5E_CPU0_PE2_RX_DP<12>")
	)
	(segment
		(start 384.672332 -219.995496)
		(end 384.666236 -219.99194)
		(width 0.0889)
		(layer "In13.Cu")
		(net "P5E_CPU0_PE2_RX_DP<12>")
	)
	(segment
		(start 387.857238 -223.422718)
		(end 387.76148 -223.32696)
		(width 0.0889)
		(layer "In13.Cu")
		(net "P5E_CPU0_PE2_RX_DP<12>")
	)
	(segment
		(start 385.799584 -221.957646)
		(end 385.799584 -221.94774)
		(width 0.0889)
		(layer "In13.Cu")
		(net "P5E_CPU0_PE2_RX_DP<12>")
	)
	(segment
		(start 380.821184 -219.506038)
		(end 380.821184 -219.515944)
		(width 0.0889)
		(layer "In13.Cu")
		(net "P5E_CPU0_PE2_RX_DP<12>")
	)
	(segment
		(start 385.7879 -420.303452)
		(end 383.78511 -411.245304)
		(width 0.14732)
		(layer "In13.Cu")
		(net "P5E_CPU0_PE2_RX_DP<12>")
	)
	(segment
		(start 387.283706 -434.947314)
		(end 387.07695 -434.947314)
		(width 0.14732)
		(layer "In13.Cu")
		(net "P5E_CPU0_PE2_RX_DP<12>")
	)
	(segment
		(start 389.225028 -250.44146)
		(end 389.432292 -249.266456)
		(width 0.14732)
		(layer "In13.Cu")
		(net "P5E_CPU0_PE2_RX_DP<12>")
	)
	(segment
		(start 388.643876 -224.2693)
		(end 387.872732 -223.498156)
		(width 0.14732)
		(layer "In13.Cu")
		(net "P5E_CPU0_PE2_RX_DP<12>")
	)
	(segment
		(start 382.43891 -404.819358)
		(end 382.43891 -400.598132)
		(width 0.14732)
		(layer "In13.Cu")
		(net "P5E_CPU0_PE2_RX_DP<12>")
	)
	(segment
		(start 386.79247 -424.845988)
		(end 385.788916 -420.308532)
		(width 0.14732)
		(layer "In13.Cu")
		(net "P5E_CPU0_PE2_RX_DP<12>")
	)
	(segment
		(start 387.76148 -223.32696)
		(end 386.83438 -223.32696)
		(width 0.0889)
		(layer "In13.Cu")
		(net "P5E_CPU0_PE2_RX_DP<12>")
	)
	(segment
		(start 391.174478 -244.452902)
		(end 390.159748 -230.175308)
		(width 0.14732)
		(layer "In13.Cu")
		(net "P5E_CPU0_PE2_RX_DP<12>")
	)
	(segment
		(start 387.07695 -434.947314)
		(end 386.791962 -434.662326)
		(width 0.14732)
		(layer "In13.Cu")
		(net "P5E_CPU0_PE2_RX_DP<12>")
	)
	(segment
		(start 384.38963 -219.506038)
		(end 384.38963 -219.497402)
		(width 0.0889)
		(layer "In13.Cu")
		(net "P5E_CPU0_PE2_RX_DP<12>")
	)
	(segment
		(start 393.73683 -354.194364)
		(end 396.149322 -339.367114)
		(width 0.14732)
		(layer "In13.Cu")
		(net "P5E_CPU0_PE2_RX_DP<12>")
	)
	(segment
		(start 386.26923 -222.77578)
		(end 386.26923 -222.75292)
		(width 0.0889)
		(layer "In13.Cu")
		(net "P5E_CPU0_PE2_RX_DP<12>")
	)
	(segment
		(start 389.13689 -310.033162)
		(end 392.018774 -259.28701)
		(width 0.14732)
		(layer "In13.Cu")
		(net "P5E_CPU0_PE2_RX_DP<12>")
	)
	(segment
		(start 387.872732 -223.498156)
		(end 387.857238 -223.482662)
		(width 0.0889)
		(layer "In13.Cu")
		(net "P5E_CPU0_PE2_RX_DP<12>")
	)
	(segment
		(start 385.788916 -420.308532)
		(end 385.7879 -420.303452)
		(width 0.14732)
		(layer "In13.Cu")
		(net "P5E_CPU0_PE2_RX_DP<12>")
	)
	(segment
		(start 390.148318 -254.67818)
		(end 389.573516 -253.29134)
		(width 0.14732)
		(layer "In13.Cu")
		(net "P5E_CPU0_PE2_RX_DP<12>")
	)
	(segment
		(start 384.681222 -220.000576)
		(end 384.673856 -219.996258)
		(width 0.0889)
		(layer "In13.Cu")
		(net "P5E_CPU0_PE2_RX_DP<12>")
	)
	(segment
		(start 390.159748 -230.175308)
		(end 389.265668 -225.834448)
		(width 0.14732)
		(layer "In13.Cu")
		(net "P5E_CPU0_PE2_RX_DP<12>")
	)
	(segment
		(start 388.25043 -376.43943)
		(end 393.73683 -354.194364)
		(width 0.14732)
		(layer "In13.Cu")
		(net "P5E_CPU0_PE2_RX_DP<12>")
	)
	(segment
		(start 386.79247 -424.96232)
		(end 386.79247 -424.845988)
		(width 0.14732)
		(layer "In13.Cu")
		(net "P5E_CPU0_PE2_RX_DP<12>")
	)
	(segment
		(start 388.200392 -376.43943)
		(end 388.25043 -376.43943)
		(width 0.14732)
		(layer "In13.Cu")
		(net "P5E_CPU0_PE2_RX_DP<12>")
	)
	(segment
		(start 389.573516 -253.29134)
		(end 389.50265 -253.08941)
		(width 0.14732)
		(layer "In13.Cu")
		(net "P5E_CPU0_PE2_RX_DP<12>")
	)
	(segment
		(start 380.351284 -220.319854)
		(end 380.351284 -220.334078)
		(width 0.0889)
		(layer "In13.Cu")
		(net "P5E_CPU0_PE2_RX_DP<12>")
	)
	(segment
		(start 387.75005 -435.489858)
		(end 387.75005 -435.413658)
		(width 0.14732)
		(layer "In13.Cu")
		(net "P5E_CPU0_PE2_RX_DP<12>")
	)
	(segment
		(start 382.43891 -400.598132)
		(end 382.636522 -399.000472)
		(width 0.14732)
		(layer "In13.Cu")
		(net "P5E_CPU0_PE2_RX_DP<12>")
	)
	(segment
		(start 389.757158 -248.802144)
		(end 391.174478 -244.452902)
		(width 0.14732)
		(layer "In13.Cu")
		(net "P5E_CPU0_PE2_RX_DP<12>")
	)
	(segment
		(start 380.1237 -220.773752)
		(end 380.09957 -220.862906)
		(width 0.0889)
		(layer "In13.Cu")
		(net "P5E_CPU0_PE2_RX_DP<12>")
	)
	(segment
		(start 380.535434 -219.997528)
		(end 380.529846 -220.000576)
		(width 0.0889)
		(layer "In13.Cu")
		(net "P5E_CPU0_PE2_RX_DP<12>")
	)
	(segment
		(start 381.008636 -219.18168)
		(end 380.999746 -219.18676)
		(width 0.0889)
		(layer "In13.Cu")
		(net "P5E_CPU0_PE2_RX_DP<12>")
	)
	(arc
		(start 380.529846 -220.000576)
		(mid 380.398932 -220.136936)
		(end 380.351284 -220.319854)
		(width 0.0889)
		(layer "In13.Cu")
		(net "P5E_CPU0_PE2_RX_DP<12>")
	)
	(arc
		(start 385.329684 -221.133924)
		(mid 385.282005 -220.951024)
		(end 385.151122 -220.814646)
		(width 0.0889)
		(layer "In13.Cu")
		(net "P5E_CPU0_PE2_RX_DP<12>")
	)
	(arc
		(start 384.666236 -219.99194)
		(mid 384.463649 -219.785589)
		(end 384.38963 -219.506038)
		(width 0.0889)
		(layer "In13.Cu")
		(net "P5E_CPU0_PE2_RX_DP<12>")
	)
	(arc
		(start 385.142232 -220.809566)
		(mid 384.939946 -220.610585)
		(end 384.859784 -220.338396)
		(width 0.0889)
		(layer "In13.Cu")
		(net "P5E_CPU0_PE2_RX_DP<12>")
	)
	(arc
		(start 381.948436 -219.18168)
		(mid 381.665734 -219.257456)
		(end 381.383032 -219.18168)
		(width 0.0889)
		(layer "In13.Cu")
		(net "P5E_CPU0_PE2_RX_DP<12>")
	)
	(arc
		(start 386.26923 -222.75292)
		(mid 386.21696 -222.570555)
		(end 386.082032 -222.437198)
		(width 0.0889)
		(layer "In13.Cu")
		(net "P5E_CPU0_PE2_RX_DP<12>")
	)
	(arc
		(start 386.83438 -223.32696)
		(mid 386.688188 -223.307665)
		(end 386.551932 -223.251268)
		(width 0.0889)
		(layer "In13.Cu")
		(net "P5E_CPU0_PE2_RX_DP<12>")
	)
	(arc
		(start 384.859784 -220.319854)
		(mid 384.812105 -220.136954)
		(end 384.681222 -220.000576)
		(width 0.0889)
		(layer "In13.Cu")
		(net "P5E_CPU0_PE2_RX_DP<12>")
	)
	(arc
		(start 380.351284 -220.334078)
		(mid 380.292923 -220.570676)
		(end 380.140464 -220.760798)
		(width 0.0889)
		(layer "In13.Cu")
		(net "P5E_CPU0_PE2_RX_DP<12>")
	)
	(arc
		(start 380.821184 -219.515944)
		(mid 380.743073 -219.792893)
		(end 380.538736 -219.995496)
		(width 0.0889)
		(layer "In13.Cu")
		(net "P5E_CPU0_PE2_RX_DP<12>")
	)
	(arc
		(start 383.828036 -219.18168)
		(mid 383.545334 -219.257456)
		(end 383.262632 -219.18168)
		(width 0.0889)
		(layer "In13.Cu")
		(net "P5E_CPU0_PE2_RX_DP<12>")
	)
	(arc
		(start 381.383032 -219.18168)
		(mid 381.195834 -219.131537)
		(end 381.008636 -219.18168)
		(width 0.0889)
		(layer "In13.Cu")
		(net "P5E_CPU0_PE2_RX_DP<12>")
	)
	(arc
		(start 380.999746 -219.18676)
		(mid 380.868832 -219.32312)
		(end 380.821184 -219.506038)
		(width 0.0889)
		(layer "In13.Cu")
		(net "P5E_CPU0_PE2_RX_DP<12>")
	)
	(arc
		(start 383.262632 -219.18168)
		(mid 383.075434 -219.131537)
		(end 382.888236 -219.18168)
		(width 0.0889)
		(layer "In13.Cu")
		(net "P5E_CPU0_PE2_RX_DP<12>")
	)
	(arc
		(start 386.082032 -222.437198)
		(mid 385.877697 -222.234593)
		(end 385.799584 -221.957646)
		(width 0.0889)
		(layer "In13.Cu")
		(net "P5E_CPU0_PE2_RX_DP<12>")
	)
	(arc
		(start 382.888236 -219.18168)
		(mid 382.605534 -219.257456)
		(end 382.322832 -219.18168)
		(width 0.0889)
		(layer "In13.Cu")
		(net "P5E_CPU0_PE2_RX_DP<12>")
	)
	(arc
		(start 385.612132 -221.623382)
		(mid 385.407797 -221.420777)
		(end 385.329684 -221.14383)
		(width 0.0889)
		(layer "In13.Cu")
		(net "P5E_CPU0_PE2_RX_DP<12>")
	)
	(arc
		(start 380.140464 -220.760798)
		(mid 380.132142 -220.767353)
		(end 380.1237 -220.773752)
		(width 0.0889)
		(layer "In13.Cu")
		(net "P5E_CPU0_PE2_RX_DP<12>")
	)
	(arc
		(start 384.38963 -219.497402)
		(mid 384.33736 -219.315037)
		(end 384.202432 -219.18168)
		(width 0.0889)
		(layer "In13.Cu")
		(net "P5E_CPU0_PE2_RX_DP<12>")
	)
	(arc
		(start 386.551932 -223.251268)
		(mid 386.348451 -223.050464)
		(end 386.26923 -222.77578)
		(width 0.0889)
		(layer "In13.Cu")
		(net "P5E_CPU0_PE2_RX_DP<12>")
	)
	(arc
		(start 385.799584 -221.94774)
		(mid 385.751905 -221.76484)
		(end 385.621022 -221.628462)
		(width 0.0889)
		(layer "In13.Cu")
		(net "P5E_CPU0_PE2_RX_DP<12>")
	)
	(arc
		(start 382.322832 -219.18168)
		(mid 382.135634 -219.131537)
		(end 381.948436 -219.18168)
		(width 0.0889)
		(layer "In13.Cu")
		(net "P5E_CPU0_PE2_RX_DP<12>")
	)
	(arc
		(start 384.202432 -219.18168)
		(mid 384.015234 -219.131537)
		(end 383.828036 -219.18168)
		(width 0.0889)
		(layer "In13.Cu")
		(net "P5E_CPU0_PE2_RX_DP<12>")
	)
	(segment
		(start 378.846334 -221.947994)
		(end 378.84608 -221.94774)
		(width 0.13208)
		(layer "F.Cu")
		(net "P5E_CPU0_PE2_RX_DP<11>")
	)
	(segment
		(start 378.846334 -222.48368)
		(end 378.846334 -221.947994)
		(width 0.13208)
		(layer "F.Cu")
		(net "P5E_CPU0_PE2_RX_DP<11>")
	)
	(segment
		(start 393.062714 -259.19303)
		(end 392.371072 -256.06883)
		(width 0.14732)
		(layer "In13.Cu")
		(net "P5E_CPU0_PE2_RX_DP<11>")
	)
	(segment
		(start 390.439402 -249.44959)
		(end 390.625076 -249.184414)
		(width 0.14732)
		(layer "In13.Cu")
		(net "P5E_CPU0_PE2_RX_DP<11>")
	)
	(segment
		(start 386.954268 -216.818464)
		(end 386.893308 -216.818464)
		(width 0.0889)
		(layer "In13.Cu")
		(net "P5E_CPU0_PE2_RX_DP<11>")
	)
	(segment
		(start 379.599444 -219.994988)
		(end 379.598682 -219.995496)
		(width 0.0889)
		(layer "In13.Cu")
		(net "P5E_CPU0_PE2_RX_DP<11>")
	)
	(segment
		(start 381.008636 -217.554048)
		(end 380.999746 -217.559128)
		(width 0.0889)
		(layer "In13.Cu")
		(net "P5E_CPU0_PE2_RX_DP<11>")
	)
	(segment
		(start 392.134598 -244.545104)
		(end 391.135108 -230.043228)
		(width 0.14732)
		(layer "In13.Cu")
		(net "P5E_CPU0_PE2_RX_DP<11>")
	)
	(segment
		(start 390.241028 -252.300232)
		(end 390.241028 -250.57481)
		(width 0.14732)
		(layer "In13.Cu")
		(net "P5E_CPU0_PE2_RX_DP<11>")
	)
	(segment
		(start 394.718794 -354.12934)
		(end 397.19504 -339.430868)
		(width 0.14732)
		(layer "In13.Cu")
		(net "P5E_CPU0_PE2_RX_DP<11>")
	)
	(segment
		(start 382.418336 -216.739978)
		(end 382.407922 -216.746074)
		(width 0.0889)
		(layer "In13.Cu")
		(net "P5E_CPU0_PE2_RX_DP<11>")
	)
	(segment
		(start 387.01853 -216.860628)
		(end 386.996432 -216.860628)
		(width 0.0889)
		(layer "In13.Cu")
		(net "P5E_CPU0_PE2_RX_DP<11>")
	)
	(segment
		(start 389.750046 -434.423566)
		(end 389.320278 -433.993798)
		(width 0.14732)
		(layer "In13.Cu")
		(net "P5E_CPU0_PE2_RX_DP<11>")
	)
	(segment
		(start 380.068836 -219.18168)
		(end 380.059946 -219.18676)
		(width 0.0889)
		(layer "In13.Cu")
		(net "P5E_CPU0_PE2_RX_DP<11>")
	)
	(segment
		(start 388.791958 -424.653456)
		(end 386.84835 -411.334458)
		(width 0.14732)
		(layer "In13.Cu")
		(net "P5E_CPU0_PE2_RX_DP<11>")
	)
	(segment
		(start 386.996432 -216.860628)
		(end 386.954268 -216.818464)
		(width 0.0889)
		(layer "In13.Cu")
		(net "P5E_CPU0_PE2_RX_DP<11>")
	)
	(segment
		(start 389.320278 -433.993798)
		(end 389.02513 -433.993798)
		(width 0.14732)
		(layer "In13.Cu")
		(net "P5E_CPU0_PE2_RX_DP<11>")
	)
	(segment
		(start 390.353296 -252.661166)
		(end 390.241028 -252.300232)
		(width 0.14732)
		(layer "In13.Cu")
		(net "P5E_CPU0_PE2_RX_DP<11>")
	)
	(segment
		(start 388.791958 -433.760626)
		(end 388.791958 -424.653456)
		(width 0.14732)
		(layer "In13.Cu")
		(net "P5E_CPU0_PE2_RX_DP<11>")
	)
	(segment
		(start 379.091698 -221.652846)
		(end 379.002544 -221.676722)
		(width 0.0889)
		(layer "In13.Cu")
		(net "P5E_CPU0_PE2_RX_DP<11>")
	)
	(segment
		(start 389.02513 -433.993798)
		(end 388.791958 -433.760626)
		(width 0.14732)
		(layer "In13.Cu")
		(net "P5E_CPU0_PE2_RX_DP<11>")
	)
	(segment
		(start 380.35103 -218.692222)
		(end 380.35103 -218.707716)
		(width 0.0889)
		(layer "In13.Cu")
		(net "P5E_CPU0_PE2_RX_DP<11>")
	)
	(segment
		(start 390.625076 -249.184414)
		(end 392.134598 -244.545104)
		(width 0.14732)
		(layer "In13.Cu")
		(net "P5E_CPU0_PE2_RX_DP<11>")
	)
	(segment
		(start 397.19504 -339.430868)
		(end 390.096502 -309.949342)
		(width 0.14732)
		(layer "In13.Cu")
		(net "P5E_CPU0_PE2_RX_DP<11>")
	)
	(segment
		(start 387.424168 -216.860628)
		(end 387.01853 -216.860628)
		(width 0.14732)
		(layer "In13.Cu")
		(net "P5E_CPU0_PE2_RX_DP<11>")
	)
	(segment
		(start 392.371072 -256.06883)
		(end 390.803638 -253.830074)
		(width 0.14732)
		(layer "In13.Cu")
		(net "P5E_CPU0_PE2_RX_DP<11>")
	)
	(segment
		(start 379.599444 -221.622874)
		(end 379.58395 -221.632018)
		(width 0.0889)
		(layer "In13.Cu")
		(net "P5E_CPU0_PE2_RX_DP<11>")
	)
	(segment
		(start 379.002544 -221.676722)
		(end 378.84608 -221.94774)
		(width 0.0889)
		(layer "In13.Cu")
		(net "P5E_CPU0_PE2_RX_DP<11>")
	)
	(segment
		(start 387.734048 -217.170508)
		(end 387.424168 -216.860628)
		(width 0.14732)
		(layer "In13.Cu")
		(net "P5E_CPU0_PE2_RX_DP<11>")
	)
	(segment
		(start 385.50215 -404.819358)
		(end 385.50215 -399.85315)
		(width 0.14732)
		(layer "In13.Cu")
		(net "P5E_CPU0_PE2_RX_DP<11>")
	)
	(segment
		(start 386.84835 -406.165558)
		(end 385.50215 -404.819358)
		(width 0.14732)
		(layer "In13.Cu")
		(net "P5E_CPU0_PE2_RX_DP<11>")
	)
	(segment
		(start 390.096502 -309.949342)
		(end 393.06246 -259.19303)
		(width 0.14732)
		(layer "In13.Cu")
		(net "P5E_CPU0_PE2_RX_DP<11>")
	)
	(segment
		(start 379.604778 -221.619826)
		(end 379.599444 -221.622874)
		(width 0.0889)
		(layer "In13.Cu")
		(net "P5E_CPU0_PE2_RX_DP<11>")
	)
	(segment
		(start 380.544578 -218.364308)
		(end 380.529592 -218.372944)
		(width 0.0889)
		(layer "In13.Cu")
		(net "P5E_CPU0_PE2_RX_DP<11>")
	)
	(segment
		(start 393.06246 -259.19303)
		(end 393.062714 -259.19303)
		(width 0.14732)
		(layer "In13.Cu")
		(net "P5E_CPU0_PE2_RX_DP<11>")
	)
	(segment
		(start 379.604778 -219.99194)
		(end 379.599444 -219.994988)
		(width 0.0889)
		(layer "In13.Cu")
		(net "P5E_CPU0_PE2_RX_DP<11>")
	)
	(segment
		(start 386.84835 -411.334458)
		(end 386.84835 -406.165558)
		(width 0.14732)
		(layer "In13.Cu")
		(net "P5E_CPU0_PE2_RX_DP<11>")
	)
	(segment
		(start 391.135108 -230.043228)
		(end 390.225788 -225.565208)
		(width 0.14732)
		(layer "In13.Cu")
		(net "P5E_CPU0_PE2_RX_DP<11>")
	)
	(segment
		(start 390.225788 -225.565208)
		(end 387.734048 -217.170508)
		(width 0.14732)
		(layer "In13.Cu")
		(net "P5E_CPU0_PE2_RX_DP<11>")
	)
	(segment
		(start 390.803638 -253.830074)
		(end 390.457182 -252.994668)
		(width 0.14732)
		(layer "In13.Cu")
		(net "P5E_CPU0_PE2_RX_DP<11>")
	)
	(segment
		(start 385.50215 -399.85315)
		(end 394.718794 -354.12934)
		(width 0.14732)
		(layer "In13.Cu")
		(net "P5E_CPU0_PE2_RX_DP<11>")
	)
	(segment
		(start 390.457182 -252.994668)
		(end 390.353296 -252.661166)
		(width 0.14732)
		(layer "In13.Cu")
		(net "P5E_CPU0_PE2_RX_DP<11>")
	)
	(segment
		(start 390.241028 -250.57481)
		(end 390.439402 -249.44959)
		(width 0.14732)
		(layer "In13.Cu")
		(net "P5E_CPU0_PE2_RX_DP<11>")
	)
	(segment
		(start 381.291084 -217.0557)
		(end 381.291084 -217.082878)
		(width 0.0889)
		(layer "In13.Cu")
		(net "P5E_CPU0_PE2_RX_DP<11>")
	)
	(segment
		(start 389.750046 -434.48986)
		(end 389.750046 -434.423566)
		(width 0.14732)
		(layer "In13.Cu")
		(net "P5E_CPU0_PE2_RX_DP<11>")
	)
	(arc
		(start 379.58395 -221.632018)
		(mid 379.351035 -221.698229)
		(end 379.111764 -221.660974)
		(width 0.0889)
		(layer "In13.Cu")
		(net "P5E_CPU0_PE2_RX_DP<11>")
	)
	(arc
		(start 379.598682 -220.644212)
		(mid 379.881677 -221.130331)
		(end 379.604778 -221.619826)
		(width 0.0889)
		(layer "In13.Cu")
		(net "P5E_CPU0_PE2_RX_DP<11>")
	)
	(arc
		(start 381.291084 -217.082878)
		(mid 381.210922 -217.355067)
		(end 381.008636 -217.554048)
		(width 0.0889)
		(layer "In13.Cu")
		(net "P5E_CPU0_PE2_RX_DP<11>")
	)
	(arc
		(start 380.35103 -218.707716)
		(mid 380.27166 -218.98145)
		(end 380.068836 -219.18168)
		(width 0.0889)
		(layer "In13.Cu")
		(net "P5E_CPU0_PE2_RX_DP<11>")
	)
	(arc
		(start 379.881384 -219.506038)
		(mid 379.807393 -219.785604)
		(end 379.604778 -219.99194)
		(width 0.0889)
		(layer "In13.Cu")
		(net "P5E_CPU0_PE2_RX_DP<11>")
	)
	(arc
		(start 386.177536 -216.739978)
		(mid 385.894834 -216.815754)
		(end 385.612132 -216.739978)
		(width 0.0889)
		(layer "In13.Cu")
		(net "P5E_CPU0_PE2_RX_DP<11>")
	)
	(arc
		(start 385.612132 -216.739978)
		(mid 385.424934 -216.689835)
		(end 385.237736 -216.739978)
		(width 0.0889)
		(layer "In13.Cu")
		(net "P5E_CPU0_PE2_RX_DP<11>")
	)
	(arc
		(start 386.551932 -216.739978)
		(mid 386.364734 -216.689835)
		(end 386.177536 -216.739978)
		(width 0.0889)
		(layer "In13.Cu")
		(net "P5E_CPU0_PE2_RX_DP<11>")
	)
	(arc
		(start 380.059946 -219.18676)
		(mid 379.929032 -219.32312)
		(end 379.881384 -219.506038)
		(width 0.0889)
		(layer "In13.Cu")
		(net "P5E_CPU0_PE2_RX_DP<11>")
	)
	(arc
		(start 386.785612 -216.813892)
		(mid 386.664713 -216.789763)
		(end 386.551932 -216.739978)
		(width 0.0889)
		(layer "In13.Cu")
		(net "P5E_CPU0_PE2_RX_DP<11>")
	)
	(arc
		(start 383.732532 -216.739978)
		(mid 383.545334 -216.689835)
		(end 383.358136 -216.739978)
		(width 0.0889)
		(layer "In13.Cu")
		(net "P5E_CPU0_PE2_RX_DP<11>")
	)
	(arc
		(start 386.893308 -216.818464)
		(mid 386.839411 -216.817321)
		(end 386.785612 -216.813892)
		(width 0.0889)
		(layer "In13.Cu")
		(net "P5E_CPU0_PE2_RX_DP<11>")
	)
	(arc
		(start 380.529592 -218.372944)
		(mid 380.398678 -218.509304)
		(end 380.35103 -218.692222)
		(width 0.0889)
		(layer "In13.Cu")
		(net "P5E_CPU0_PE2_RX_DP<11>")
	)
	(arc
		(start 385.237736 -216.739978)
		(mid 384.955034 -216.815754)
		(end 384.672332 -216.739978)
		(width 0.0889)
		(layer "In13.Cu")
		(net "P5E_CPU0_PE2_RX_DP<11>")
	)
	(arc
		(start 382.792732 -216.739978)
		(mid 382.605534 -216.689835)
		(end 382.418336 -216.739978)
		(width 0.0889)
		(layer "In13.Cu")
		(net "P5E_CPU0_PE2_RX_DP<11>")
	)
	(arc
		(start 380.821184 -217.878406)
		(mid 380.747193 -218.157972)
		(end 380.544578 -218.364308)
		(width 0.0889)
		(layer "In13.Cu")
		(net "P5E_CPU0_PE2_RX_DP<11>")
	)
	(arc
		(start 382.407922 -216.746074)
		(mid 382.12949 -216.81592)
		(end 381.852678 -216.739978)
		(width 0.0889)
		(layer "In13.Cu")
		(net "P5E_CPU0_PE2_RX_DP<11>")
	)
	(arc
		(start 379.111764 -221.660974)
		(mid 379.101693 -221.657005)
		(end 379.091698 -221.652846)
		(width 0.0889)
		(layer "In13.Cu")
		(net "P5E_CPU0_PE2_RX_DP<11>")
	)
	(arc
		(start 383.358136 -216.739978)
		(mid 383.075434 -216.815754)
		(end 382.792732 -216.739978)
		(width 0.0889)
		(layer "In13.Cu")
		(net "P5E_CPU0_PE2_RX_DP<11>")
	)
	(arc
		(start 380.999746 -217.559128)
		(mid 380.868832 -217.695488)
		(end 380.821184 -217.878406)
		(width 0.0889)
		(layer "In13.Cu")
		(net "P5E_CPU0_PE2_RX_DP<11>")
	)
	(arc
		(start 379.598682 -219.995496)
		(mid 379.411379 -220.319854)
		(end 379.598682 -220.644212)
		(width 0.0889)
		(layer "In13.Cu")
		(net "P5E_CPU0_PE2_RX_DP<11>")
	)
	(arc
		(start 381.852678 -216.739978)
		(mid 381.482008 -216.737854)
		(end 381.291084 -217.0557)
		(width 0.0889)
		(layer "In13.Cu")
		(net "P5E_CPU0_PE2_RX_DP<11>")
	)
	(arc
		(start 384.672332 -216.739978)
		(mid 384.485134 -216.689835)
		(end 384.297936 -216.739978)
		(width 0.0889)
		(layer "In13.Cu")
		(net "P5E_CPU0_PE2_RX_DP<11>")
	)
	(arc
		(start 384.297936 -216.739978)
		(mid 384.015234 -216.815754)
		(end 383.732532 -216.739978)
		(width 0.0889)
		(layer "In13.Cu")
		(net "P5E_CPU0_PE2_RX_DP<11>")
	)
	(segment
		(start 378.37618 -221.134178)
		(end 378.376434 -221.133924)
		(width 0.13208)
		(layer "F.Cu")
		(net "P5E_CPU0_PE2_RX_DP<10>")
	)
	(segment
		(start 378.37618 -221.669864)
		(end 378.37618 -221.134178)
		(width 0.13208)
		(layer "F.Cu")
		(net "P5E_CPU0_PE2_RX_DP<10>")
	)
	(segment
		(start 379.129036 -217.554048)
		(end 379.120146 -217.559128)
		(width 0.0889)
		(layer "In13.Cu")
		(net "P5E_CPU0_PE2_RX_DP<10>")
	)
	(segment
		(start 391.53592 -249.506232)
		(end 393.087352 -244.737382)
		(width 0.14732)
		(layer "In13.Cu")
		(net "P5E_CPU0_PE2_RX_DP<10>")
	)
	(segment
		(start 386.627878 -215.638126)
		(end 386.503418 -215.513666)
		(width 0.14732)
		(layer "In13.Cu")
		(net "P5E_CPU0_PE2_RX_DP<10>")
	)
	(segment
		(start 389.91159 -412.313882)
		(end 389.91159 -406.165558)
		(width 0.14732)
		(layer "In13.Cu")
		(net "P5E_CPU0_PE2_RX_DP<10>")
	)
	(segment
		(start 391.443972 -249.63755)
		(end 391.53592 -249.506232)
		(width 0.14732)
		(layer "In13.Cu")
		(net "P5E_CPU0_PE2_RX_DP<10>")
	)
	(segment
		(start 390.421368 -419.393878)
		(end 389.91159 -412.313882)
		(width 0.14732)
		(layer "In13.Cu")
		(net "P5E_CPU0_PE2_RX_DP<10>")
	)
	(segment
		(start 379.411484 -217.0557)
		(end 379.411484 -217.082878)
		(width 0.0889)
		(layer "In13.Cu")
		(net "P5E_CPU0_PE2_RX_DP<10>")
	)
	(segment
		(start 387.191758 -215.513666)
		(end 387.067298 -215.638126)
		(width 0.14732)
		(layer "In13.Cu")
		(net "P5E_CPU0_PE2_RX_DP<10>")
	)
	(segment
		(start 391.062972 -309.714392)
		(end 394.069062 -259.091938)
		(width 0.14732)
		(layer "In13.Cu")
		(net "P5E_CPU0_PE2_RX_DP<10>")
	)
	(segment
		(start 378.21997 -220.862906)
		(end 378.376434 -221.133924)
		(width 0.0889)
		(layer "In13.Cu")
		(net "P5E_CPU0_PE2_RX_DP<10>")
	)
	(segment
		(start 395.649196 -354.312982)
		(end 398.235678 -339.51545)
		(width 0.14732)
		(layer "In13.Cu")
		(net "P5E_CPU0_PE2_RX_DP<10>")
	)
	(segment
		(start 378.941584 -219.506038)
		(end 378.941584 -219.515944)
		(width 0.0889)
		(layer "In13.Cu")
		(net "P5E_CPU0_PE2_RX_DP<10>")
	)
	(segment
		(start 391.283444 -434.94706)
		(end 391.080752 -434.94706)
		(width 0.14732)
		(layer "In13.Cu")
		(net "P5E_CPU0_PE2_RX_DP<10>")
	)
	(segment
		(start 378.655834 -219.997528)
		(end 378.650246 -220.000576)
		(width 0.0889)
		(layer "In13.Cu")
		(net "P5E_CPU0_PE2_RX_DP<10>")
	)
	(segment
		(start 390.421622 -419.394894)
		(end 390.421368 -419.393878)
		(width 0.14732)
		(layer "In13.Cu")
		(net "P5E_CPU0_PE2_RX_DP<10>")
	)
	(segment
		(start 386.503418 -215.513666)
		(end 385.906772 -215.513666)
		(width 0.14732)
		(layer "In13.Cu")
		(net "P5E_CPU0_PE2_RX_DP<10>")
	)
	(segment
		(start 378.2441 -220.773752)
		(end 378.21997 -220.862906)
		(width 0.0889)
		(layer "In13.Cu")
		(net "P5E_CPU0_PE2_RX_DP<10>")
	)
	(segment
		(start 393.087352 -244.737382)
		(end 392.085068 -229.844854)
		(width 0.14732)
		(layer "In13.Cu")
		(net "P5E_CPU0_PE2_RX_DP<10>")
	)
	(segment
		(start 378.649992 -219.0115)
		(end 378.657358 -219.015818)
		(width 0.0889)
		(layer "In13.Cu")
		(net "P5E_CPU0_PE2_RX_DP<10>")
	)
	(segment
		(start 391.080752 -434.94706)
		(end 390.779254 -434.645562)
		(width 0.14732)
		(layer "In13.Cu")
		(net "P5E_CPU0_PE2_RX_DP<10>")
	)
	(segment
		(start 391.750042 -435.413658)
		(end 391.283444 -434.94706)
		(width 0.14732)
		(layer "In13.Cu")
		(net "P5E_CPU0_PE2_RX_DP<10>")
	)
	(segment
		(start 378.658882 -219.01658)
		(end 378.661676 -219.018104)
		(width 0.0889)
		(layer "In13.Cu")
		(net "P5E_CPU0_PE2_RX_DP<10>")
	)
	(segment
		(start 391.750042 -435.489858)
		(end 391.750042 -435.413658)
		(width 0.14732)
		(layer "In13.Cu")
		(net "P5E_CPU0_PE2_RX_DP<10>")
	)
	(segment
		(start 378.658882 -218.367864)
		(end 378.652024 -218.371674)
		(width 0.0889)
		(layer "In13.Cu")
		(net "P5E_CPU0_PE2_RX_DP<10>")
	)
	(segment
		(start 378.659644 -218.367356)
		(end 378.658882 -218.367864)
		(width 0.0889)
		(layer "In13.Cu")
		(net "P5E_CPU0_PE2_RX_DP<10>")
	)
	(segment
		(start 385.249674 -215.471502)
		(end 384.88493 -215.8365)
		(width 0.0889)
		(layer "In13.Cu")
		(net "P5E_CPU0_PE2_RX_DP<10>")
	)
	(segment
		(start 388.56539 -399.733262)
		(end 395.649196 -354.312982)
		(width 0.14732)
		(layer "In13.Cu")
		(net "P5E_CPU0_PE2_RX_DP<10>")
	)
	(segment
		(start 378.657358 -219.015818)
		(end 378.658882 -219.01658)
		(width 0.0889)
		(layer "In13.Cu")
		(net "P5E_CPU0_PE2_RX_DP<10>")
	)
	(segment
		(start 387.591046 -215.513666)
		(end 387.191758 -215.513666)
		(width 0.14732)
		(layer "In13.Cu")
		(net "P5E_CPU0_PE2_RX_DP<10>")
	)
	(segment
		(start 380.068836 -215.926162)
		(end 380.059946 -215.931242)
		(width 0.0889)
		(layer "In13.Cu")
		(net "P5E_CPU0_PE2_RX_DP<10>")
	)
	(segment
		(start 391.180828 -251.128022)
		(end 391.443972 -249.63755)
		(width 0.14732)
		(layer "In13.Cu")
		(net "P5E_CPU0_PE2_RX_DP<10>")
	)
	(segment
		(start 391.60958 -253.345696)
		(end 391.331196 -252.673866)
		(width 0.14732)
		(layer "In13.Cu")
		(net "P5E_CPU0_PE2_RX_DP<10>")
	)
	(segment
		(start 389.91159 -406.165558)
		(end 388.56539 -404.819358)
		(width 0.14732)
		(layer "In13.Cu")
		(net "P5E_CPU0_PE2_RX_DP<10>")
	)
	(segment
		(start 390.779254 -434.645562)
		(end 390.779254 -424.361356)
		(width 0.14732)
		(layer "In13.Cu")
		(net "P5E_CPU0_PE2_RX_DP<10>")
	)
	(segment
		(start 378.471684 -220.319854)
		(end 378.471684 -220.334078)
		(width 0.0889)
		(layer "In13.Cu")
		(net "P5E_CPU0_PE2_RX_DP<10>")
	)
	(segment
		(start 378.664978 -218.364308)
		(end 378.659644 -218.367356)
		(width 0.0889)
		(layer "In13.Cu")
		(net "P5E_CPU0_PE2_RX_DP<10>")
	)
	(segment
		(start 387.067298 -215.638126)
		(end 386.627878 -215.638126)
		(width 0.14732)
		(layer "In13.Cu")
		(net "P5E_CPU0_PE2_RX_DP<10>")
	)
	(segment
		(start 378.652024 -218.371674)
		(end 378.649992 -218.372944)
		(width 0.0889)
		(layer "In13.Cu")
		(net "P5E_CPU0_PE2_RX_DP<10>")
	)
	(segment
		(start 388.494016 -216.416636)
		(end 387.591046 -215.513666)
		(width 0.14732)
		(layer "In13.Cu")
		(net "P5E_CPU0_PE2_RX_DP<10>")
	)
	(segment
		(start 385.884674 -215.513666)
		(end 385.84251 -215.471502)
		(width 0.0889)
		(layer "In13.Cu")
		(net "P5E_CPU0_PE2_RX_DP<10>")
	)
	(segment
		(start 388.56539 -404.819358)
		(end 388.56539 -399.733262)
		(width 0.14732)
		(layer "In13.Cu")
		(net "P5E_CPU0_PE2_RX_DP<10>")
	)
	(segment
		(start 379.603 -216.737438)
		(end 379.602238 -216.737946)
		(width 0.0889)
		(layer "In13.Cu")
		(net "P5E_CPU0_PE2_RX_DP<10>")
	)
	(segment
		(start 391.180828 -252.157992)
		(end 391.180828 -251.128022)
		(width 0.14732)
		(layer "In13.Cu")
		(net "P5E_CPU0_PE2_RX_DP<10>")
	)
	(segment
		(start 383.882138 -215.837008)
		(end 380.399544 -215.837008)
		(width 0.0889)
		(layer "In13.Cu")
		(net "P5E_CPU0_PE2_RX_DP<10>")
	)
	(segment
		(start 378.658374 -219.996004)
		(end 378.655834 -219.997528)
		(width 0.0889)
		(layer "In13.Cu")
		(net "P5E_CPU0_PE2_RX_DP<10>")
	)
	(segment
		(start 385.84251 -215.471502)
		(end 385.249674 -215.471502)
		(width 0.0889)
		(layer "In13.Cu")
		(net "P5E_CPU0_PE2_RX_DP<10>")
	)
	(segment
		(start 398.235678 -339.51545)
		(end 391.062972 -309.714392)
		(width 0.14732)
		(layer "In13.Cu")
		(net "P5E_CPU0_PE2_RX_DP<10>")
	)
	(segment
		(start 379.602238 -216.737946)
		(end 379.599444 -216.73947)
		(width 0.0889)
		(layer "In13.Cu")
		(net "P5E_CPU0_PE2_RX_DP<10>")
	)
	(segment
		(start 378.661676 -219.018104)
		(end 378.664978 -219.020136)
		(width 0.0889)
		(layer "In13.Cu")
		(net "P5E_CPU0_PE2_RX_DP<10>")
	)
	(segment
		(start 391.331196 -252.673866)
		(end 391.180828 -252.157992)
		(width 0.14732)
		(layer "In13.Cu")
		(net "P5E_CPU0_PE2_RX_DP<10>")
	)
	(segment
		(start 379.604778 -216.736422)
		(end 379.603 -216.737438)
		(width 0.0889)
		(layer "In13.Cu")
		(net "P5E_CPU0_PE2_RX_DP<10>")
	)
	(segment
		(start 390.779254 -424.361356)
		(end 390.421622 -419.394894)
		(width 0.14732)
		(layer "In13.Cu")
		(net "P5E_CPU0_PE2_RX_DP<10>")
	)
	(segment
		(start 394.069062 -259.091938)
		(end 393.268454 -255.715008)
		(width 0.14732)
		(layer "In13.Cu")
		(net "P5E_CPU0_PE2_RX_DP<10>")
	)
	(segment
		(start 391.254488 -225.601784)
		(end 388.494016 -216.416636)
		(width 0.14732)
		(layer "In13.Cu")
		(net "P5E_CPU0_PE2_RX_DP<10>")
	)
	(segment
		(start 385.906772 -215.513666)
		(end 385.884674 -215.513666)
		(width 0.0889)
		(layer "In13.Cu")
		(net "P5E_CPU0_PE2_RX_DP<10>")
	)
	(segment
		(start 393.268454 -255.715008)
		(end 391.60958 -253.345696)
		(width 0.14732)
		(layer "In13.Cu")
		(net "P5E_CPU0_PE2_RX_DP<10>")
	)
	(segment
		(start 378.659136 -219.995496)
		(end 378.658374 -219.996004)
		(width 0.0889)
		(layer "In13.Cu")
		(net "P5E_CPU0_PE2_RX_DP<10>")
	)
	(segment
		(start 392.085068 -229.844854)
		(end 391.254488 -225.601784)
		(width 0.14732)
		(layer "In13.Cu")
		(net "P5E_CPU0_PE2_RX_DP<10>")
	)
	(segment
		(start 384.767836 -215.926162)
		(end 384.767582 -215.925908)
		(width 0.0889)
		(layer "In13.Cu")
		(net "P5E_CPU0_PE2_RX_DP<10>")
	)
	(segment
		(start 379.599444 -216.73947)
		(end 379.598682 -216.739978)
		(width 0.0889)
		(layer "In13.Cu")
		(net "P5E_CPU0_PE2_RX_DP<10>")
	)
	(arc
		(start 384.858768 -215.861138)
		(mid 384.814915 -215.895906)
		(end 384.767836 -215.926162)
		(width 0.0889)
		(layer "In13.Cu")
		(net "P5E_CPU0_PE2_RX_DP<10>")
	)
	(arc
		(start 384.88493 -215.8365)
		(mid 384.872046 -215.849028)
		(end 384.858768 -215.861138)
		(width 0.0889)
		(layer "In13.Cu")
		(net "P5E_CPU0_PE2_RX_DP<10>")
	)
	(arc
		(start 378.941584 -219.515944)
		(mid 378.863473 -219.792893)
		(end 378.659136 -219.995496)
		(width 0.0889)
		(layer "In13.Cu")
		(net "P5E_CPU0_PE2_RX_DP<10>")
	)
	(arc
		(start 380.099824 -215.909398)
		(mid 380.084218 -215.917573)
		(end 380.068836 -215.926162)
		(width 0.0889)
		(layer "In13.Cu")
		(net "P5E_CPU0_PE2_RX_DP<10>")
	)
	(arc
		(start 378.471684 -220.334078)
		(mid 378.413323 -220.570676)
		(end 378.260864 -220.760798)
		(width 0.0889)
		(layer "In13.Cu")
		(net "P5E_CPU0_PE2_RX_DP<10>")
	)
	(arc
		(start 378.649992 -218.372944)
		(mid 378.471395 -218.692222)
		(end 378.649992 -219.0115)
		(width 0.0889)
		(layer "In13.Cu")
		(net "P5E_CPU0_PE2_RX_DP<10>")
	)
	(arc
		(start 378.260864 -220.760798)
		(mid 378.252542 -220.767353)
		(end 378.2441 -220.773752)
		(width 0.0889)
		(layer "In13.Cu")
		(net "P5E_CPU0_PE2_RX_DP<10>")
	)
	(arc
		(start 378.941584 -217.878406)
		(mid 378.867593 -218.157972)
		(end 378.664978 -218.364308)
		(width 0.0889)
		(layer "In13.Cu")
		(net "P5E_CPU0_PE2_RX_DP<10>")
	)
	(arc
		(start 379.411484 -217.082878)
		(mid 379.331322 -217.355067)
		(end 379.129036 -217.554048)
		(width 0.0889)
		(layer "In13.Cu")
		(net "P5E_CPU0_PE2_RX_DP<10>")
	)
	(arc
		(start 378.664978 -219.020136)
		(mid 378.867565 -219.226487)
		(end 378.941584 -219.506038)
		(width 0.0889)
		(layer "In13.Cu")
		(net "P5E_CPU0_PE2_RX_DP<10>")
	)
	(arc
		(start 378.650246 -220.000576)
		(mid 378.519332 -220.136936)
		(end 378.471684 -220.319854)
		(width 0.0889)
		(layer "In13.Cu")
		(net "P5E_CPU0_PE2_RX_DP<10>")
	)
	(arc
		(start 379.881384 -216.25052)
		(mid 379.807393 -216.530086)
		(end 379.604778 -216.736422)
		(width 0.0889)
		(layer "In13.Cu")
		(net "P5E_CPU0_PE2_RX_DP<10>")
	)
	(arc
		(start 379.120146 -217.559128)
		(mid 378.989232 -217.695488)
		(end 378.941584 -217.878406)
		(width 0.0889)
		(layer "In13.Cu")
		(net "P5E_CPU0_PE2_RX_DP<10>")
	)
	(arc
		(start 380.399544 -215.837008)
		(mid 380.24538 -215.855388)
		(end 380.099824 -215.909398)
		(width 0.0889)
		(layer "In13.Cu")
		(net "P5E_CPU0_PE2_RX_DP<10>")
	)
	(arc
		(start 384.214878 -215.932766)
		(mid 384.055263 -215.86141)
		(end 383.882138 -215.837008)
		(width 0.0889)
		(layer "In13.Cu")
		(net "P5E_CPU0_PE2_RX_DP<10>")
	)
	(arc
		(start 379.598682 -216.739978)
		(mid 379.463749 -216.873332)
		(end 379.411484 -217.0557)
		(width 0.0889)
		(layer "In13.Cu")
		(net "P5E_CPU0_PE2_RX_DP<10>")
	)
	(arc
		(start 380.059946 -215.931242)
		(mid 379.929032 -216.067602)
		(end 379.881384 -216.25052)
		(width 0.0889)
		(layer "In13.Cu")
		(net "P5E_CPU0_PE2_RX_DP<10>")
	)
	(arc
		(start 384.767582 -215.925908)
		(mid 384.492128 -216.001548)
		(end 384.214878 -215.932766)
		(width 0.0889)
		(layer "In13.Cu")
		(net "P5E_CPU0_PE2_RX_DP<10>")
	)
	(segment
		(start 368.97818 -221.669864)
		(end 368.97818 -221.134178)
		(width 0.13208)
		(layer "F.Cu")
		(net "P5E_CPU0_PE2_RX_DP<0>")
	)
	(segment
		(start 368.97818 -221.134178)
		(end 368.978434 -221.133924)
		(width 0.13208)
		(layer "F.Cu")
		(net "P5E_CPU0_PE2_RX_DP<0>")
	)
	(segment
		(start 416.967162 -395.06652)
		(end 417.037266 -394.90523)
		(width 0.14732)
		(layer "In13.Cu")
		(net "P5E_CPU0_PE2_RX_DP<0>")
	)
	(segment
		(start 417.289234 -395.543278)
		(end 417.12769 -395.473174)
		(width 0.14732)
		(layer "In13.Cu")
		(net "P5E_CPU0_PE2_RX_DP<0>")
	)
	(segment
		(start 369.266978 -218.364308)
		(end 369.266724 -218.364562)
		(width 0.0889)
		(layer "In13.Cu")
		(net "P5E_CPU0_PE2_RX_DP<0>")
	)
	(segment
		(start 368.8461 -220.773752)
		(end 368.82197 -220.862906)
		(width 0.0889)
		(layer "In13.Cu")
		(net "P5E_CPU0_PE2_RX_DP<0>")
	)
	(segment
		(start 378.299218 -201.33691)
		(end 371.948456 -208.598516)
		(width 0.14732)
		(layer "In13.Cu")
		(net "P5E_CPU0_PE2_RX_DP<0>")
	)
	(segment
		(start 369.543584 -219.506038)
		(end 369.543584 -219.515944)
		(width 0.0889)
		(layer "In13.Cu")
		(net "P5E_CPU0_PE2_RX_DP<0>")
	)
	(segment
		(start 400.756374 -307.48478)
		(end 404.94331 -253.498604)
		(width 0.14732)
		(layer "In13.Cu")
		(net "P5E_CPU0_PE2_RX_DP<0>")
	)
	(segment
		(start 369.543584 -217.859864)
		(end 369.543584 -217.878406)
		(width 0.0889)
		(layer "In13.Cu")
		(net "P5E_CPU0_PE2_RX_DP<0>")
	)
	(segment
		(start 412.75 -435.413404)
		(end 412.330646 -434.99405)
		(width 0.14732)
		(layer "In13.Cu")
		(net "P5E_CPU0_PE2_RX_DP<0>")
	)
	(segment
		(start 368.82197 -220.862906)
		(end 368.978434 -221.133924)
		(width 0.0889)
		(layer "In13.Cu")
		(net "P5E_CPU0_PE2_RX_DP<0>")
	)
	(segment
		(start 371.948456 -208.598516)
		(end 370.833904 -211.565744)
		(width 0.14732)
		(layer "In13.Cu")
		(net "P5E_CPU0_PE2_RX_DP<0>")
	)
	(segment
		(start 382.072642 -199.173084)
		(end 381.090424 -199.173084)
		(width 0.14732)
		(layer "In13.Cu")
		(net "P5E_CPU0_PE2_RX_DP<0>")
	)
	(segment
		(start 380.019052 -199.617076)
		(end 378.299218 -201.33691)
		(width 0.14732)
		(layer "In13.Cu")
		(net "P5E_CPU0_PE2_RX_DP<0>")
	)
	(segment
		(start 381.090424 -199.173084)
		(end 380.019052 -199.617076)
		(width 0.14732)
		(layer "In13.Cu")
		(net "P5E_CPU0_PE2_RX_DP<0>")
	)
	(segment
		(start 369.261136 -219.995496)
		(end 369.260374 -219.996004)
		(width 0.0889)
		(layer "In13.Cu")
		(net "P5E_CPU0_PE2_RX_DP<0>")
	)
	(segment
		(start 420.54399 -406.74925)
		(end 419.35654 -400.78025)
		(width 0.14732)
		(layer "In13.Cu")
		(net "P5E_CPU0_PE2_RX_DP<0>")
	)
	(segment
		(start 369.257834 -219.997528)
		(end 369.252246 -220.000576)
		(width 0.0889)
		(layer "In13.Cu")
		(net "P5E_CPU0_PE2_RX_DP<0>")
	)
	(segment
		(start 369.260882 -219.01658)
		(end 369.266978 -219.020136)
		(width 0.0889)
		(layer "In13.Cu")
		(net "P5E_CPU0_PE2_RX_DP<0>")
	)
	(segment
		(start 369.073684 -220.319854)
		(end 369.073684 -220.334078)
		(width 0.0889)
		(layer "In13.Cu")
		(net "P5E_CPU0_PE2_RX_DP<0>")
	)
	(segment
		(start 396.154148 -209.814668)
		(end 395.848586 -209.501994)
		(width 0.14732)
		(layer "In13.Cu")
		(net "P5E_CPU0_PE2_RX_DP<0>")
	)
	(segment
		(start 401.10537 -223.49968)
		(end 397.46936 -210.9851)
		(width 0.14732)
		(layer "In13.Cu")
		(net "P5E_CPU0_PE2_RX_DP<0>")
	)
	(segment
		(start 412.077154 -434.99405)
		(end 411.791912 -434.708808)
		(width 0.14732)
		(layer "In13.Cu")
		(net "P5E_CPU0_PE2_RX_DP<0>")
	)
	(segment
		(start 395.850364 -209.329528)
		(end 386.977128 -200.255886)
		(width 0.14732)
		(layer "In13.Cu")
		(net "P5E_CPU0_PE2_RX_DP<0>")
	)
	(segment
		(start 396.326614 -209.8167)
		(end 396.154148 -209.814668)
		(width 0.14732)
		(layer "In13.Cu")
		(net "P5E_CPU0_PE2_RX_DP<0>")
	)
	(segment
		(start 386.977128 -200.255886)
		(end 385.707636 -199.729852)
		(width 0.14732)
		(layer "In13.Cu")
		(net "P5E_CPU0_PE2_RX_DP<0>")
	)
	(segment
		(start 419.35654 -400.78025)
		(end 417.289234 -395.543278)
		(width 0.14732)
		(layer "In13.Cu")
		(net "P5E_CPU0_PE2_RX_DP<0>")
	)
	(segment
		(start 369.585748 -215.68283)
		(end 369.585748 -215.694006)
		(width 0.0889)
		(layer "In13.Cu")
		(net "P5E_CPU0_PE2_RX_DP<0>")
	)
	(segment
		(start 395.848586 -209.501994)
		(end 395.850364 -209.329528)
		(width 0.14732)
		(layer "In13.Cu")
		(net "P5E_CPU0_PE2_RX_DP<0>")
	)
	(segment
		(start 406.312116 -366.18799)
		(end 406.613614 -348.108016)
		(width 0.14732)
		(layer "In13.Cu")
		(net "P5E_CPU0_PE2_RX_DP<0>")
	)
	(segment
		(start 406.613614 -348.108016)
		(end 408.176222 -339.779102)
		(width 0.14732)
		(layer "In13.Cu")
		(net "P5E_CPU0_PE2_RX_DP<0>")
	)
	(segment
		(start 408.176222 -339.779102)
		(end 400.756374 -307.48478)
		(width 0.14732)
		(layer "In13.Cu")
		(net "P5E_CPU0_PE2_RX_DP<0>")
	)
	(segment
		(start 370.833904 -211.565744)
		(end 370.412518 -213.687152)
		(width 0.14732)
		(layer "In13.Cu")
		(net "P5E_CPU0_PE2_RX_DP<0>")
	)
	(segment
		(start 369.260374 -219.996004)
		(end 369.257834 -219.997528)
		(width 0.0889)
		(layer "In13.Cu")
		(net "P5E_CPU0_PE2_RX_DP<0>")
	)
	(segment
		(start 397.46936 -210.9851)
		(end 396.326614 -209.8167)
		(width 0.14732)
		(layer "In13.Cu")
		(net "P5E_CPU0_PE2_RX_DP<0>")
	)
	(segment
		(start 411.791912 -424.194732)
		(end 420.54399 -410.668978)
		(width 0.14732)
		(layer "In13.Cu")
		(net "P5E_CPU0_PE2_RX_DP<0>")
	)
	(segment
		(start 369.261136 -216.739978)
		(end 369.260374 -216.740486)
		(width 0.0889)
		(layer "In13.Cu")
		(net "P5E_CPU0_PE2_RX_DP<0>")
	)
	(segment
		(start 369.257834 -216.74201)
		(end 369.252246 -216.745058)
		(width 0.0889)
		(layer "In13.Cu")
		(net "P5E_CPU0_PE2_RX_DP<0>")
	)
	(segment
		(start 369.266724 -218.364562)
		(end 369.254024 -218.371674)
		(width 0.0889)
		(layer "In13.Cu")
		(net "P5E_CPU0_PE2_RX_DP<0>")
	)
	(segment
		(start 411.791912 -434.708808)
		(end 411.791912 -424.194732)
		(width 0.14732)
		(layer "In13.Cu")
		(net "P5E_CPU0_PE2_RX_DP<0>")
	)
	(segment
		(start 369.543584 -215.73617)
		(end 369.543584 -216.260426)
		(width 0.0889)
		(layer "In13.Cu")
		(net "P5E_CPU0_PE2_RX_DP<0>")
	)
	(segment
		(start 404.844758 -250.564904)
		(end 404.74646 -247.631712)
		(width 0.14732)
		(layer "In13.Cu")
		(net "P5E_CPU0_PE2_RX_DP<0>")
	)
	(segment
		(start 420.54399 -410.668978)
		(end 420.54399 -406.74925)
		(width 0.14732)
		(layer "In13.Cu")
		(net "P5E_CPU0_PE2_RX_DP<0>")
	)
	(segment
		(start 369.260374 -216.740486)
		(end 369.257834 -216.74201)
		(width 0.0889)
		(layer "In13.Cu")
		(net "P5E_CPU0_PE2_RX_DP<0>")
	)
	(segment
		(start 412.330646 -434.99405)
		(end 412.077154 -434.99405)
		(width 0.14732)
		(layer "In13.Cu")
		(net "P5E_CPU0_PE2_RX_DP<0>")
	)
	(segment
		(start 404.74646 -247.631712)
		(end 401.10537 -223.49968)
		(width 0.14732)
		(layer "In13.Cu")
		(net "P5E_CPU0_PE2_RX_DP<0>")
	)
	(segment
		(start 369.252246 -217.383614)
		(end 369.261136 -217.388694)
		(width 0.0889)
		(layer "In13.Cu")
		(net "P5E_CPU0_PE2_RX_DP<0>")
	)
	(segment
		(start 404.94331 -253.498604)
		(end 404.844758 -250.565158)
		(width 0.14732)
		(layer "In13.Cu")
		(net "P5E_CPU0_PE2_RX_DP<0>")
	)
	(segment
		(start 369.585748 -215.694006)
		(end 369.543584 -215.73617)
		(width 0.0889)
		(layer "In13.Cu")
		(net "P5E_CPU0_PE2_RX_DP<0>")
	)
	(segment
		(start 412.75 -435.489858)
		(end 412.75 -435.413404)
		(width 0.14732)
		(layer "In13.Cu")
		(net "P5E_CPU0_PE2_RX_DP<0>")
	)
	(segment
		(start 385.707636 -199.729852)
		(end 382.072642 -199.173084)
		(width 0.14732)
		(layer "In13.Cu")
		(net "P5E_CPU0_PE2_RX_DP<0>")
	)
	(segment
		(start 369.254024 -218.371674)
		(end 369.251992 -218.372944)
		(width 0.0889)
		(layer "In13.Cu")
		(net "P5E_CPU0_PE2_RX_DP<0>")
	)
	(segment
		(start 369.585748 -215.234266)
		(end 369.585748 -215.68283)
		(width 0.14732)
		(layer "In13.Cu")
		(net "P5E_CPU0_PE2_RX_DP<0>")
	)
	(segment
		(start 369.251992 -219.0115)
		(end 369.260882 -219.01658)
		(width 0.0889)
		(layer "In13.Cu")
		(net "P5E_CPU0_PE2_RX_DP<0>")
	)
	(segment
		(start 404.844758 -250.565158)
		(end 404.844758 -250.564904)
		(width 0.14732)
		(layer "In13.Cu")
		(net "P5E_CPU0_PE2_RX_DP<0>")
	)
	(segment
		(start 417.12769 -395.473174)
		(end 416.967162 -395.06652)
		(width 0.14732)
		(layer "In13.Cu")
		(net "P5E_CPU0_PE2_RX_DP<0>")
	)
	(segment
		(start 370.412518 -213.687152)
		(end 369.585748 -215.234266)
		(width 0.14732)
		(layer "In13.Cu")
		(net "P5E_CPU0_PE2_RX_DP<0>")
	)
	(segment
		(start 406.810972 -368.999262)
		(end 406.312116 -366.18799)
		(width 0.14732)
		(layer "In13.Cu")
		(net "P5E_CPU0_PE2_RX_DP<0>")
	)
	(segment
		(start 417.037266 -394.90523)
		(end 406.810972 -368.999262)
		(width 0.14732)
		(layer "In13.Cu")
		(net "P5E_CPU0_PE2_RX_DP<0>")
	)
	(arc
		(start 369.073684 -217.064336)
		(mid 369.121363 -217.247236)
		(end 369.252246 -217.383614)
		(width 0.0889)
		(layer "In13.Cu")
		(net "P5E_CPU0_PE2_RX_DP<0>")
	)
	(arc
		(start 369.543584 -217.878406)
		(mid 369.469593 -218.157972)
		(end 369.266978 -218.364308)
		(width 0.0889)
		(layer "In13.Cu")
		(net "P5E_CPU0_PE2_RX_DP<0>")
	)
	(arc
		(start 369.252246 -216.745058)
		(mid 369.121332 -216.881418)
		(end 369.073684 -217.064336)
		(width 0.0889)
		(layer "In13.Cu")
		(net "P5E_CPU0_PE2_RX_DP<0>")
	)
	(arc
		(start 369.251992 -218.372944)
		(mid 369.073395 -218.692222)
		(end 369.251992 -219.0115)
		(width 0.0889)
		(layer "In13.Cu")
		(net "P5E_CPU0_PE2_RX_DP<0>")
	)
	(arc
		(start 369.261136 -217.388694)
		(mid 369.463422 -217.587675)
		(end 369.543584 -217.859864)
		(width 0.0889)
		(layer "In13.Cu")
		(net "P5E_CPU0_PE2_RX_DP<0>")
	)
	(arc
		(start 369.073684 -220.334078)
		(mid 369.015323 -220.570676)
		(end 368.862864 -220.760798)
		(width 0.0889)
		(layer "In13.Cu")
		(net "P5E_CPU0_PE2_RX_DP<0>")
	)
	(arc
		(start 369.266978 -219.020136)
		(mid 369.469565 -219.226487)
		(end 369.543584 -219.506038)
		(width 0.0889)
		(layer "In13.Cu")
		(net "P5E_CPU0_PE2_RX_DP<0>")
	)
	(arc
		(start 369.543584 -219.515944)
		(mid 369.465473 -219.792893)
		(end 369.261136 -219.995496)
		(width 0.0889)
		(layer "In13.Cu")
		(net "P5E_CPU0_PE2_RX_DP<0>")
	)
	(arc
		(start 368.862864 -220.760798)
		(mid 368.854542 -220.767353)
		(end 368.8461 -220.773752)
		(width 0.0889)
		(layer "In13.Cu")
		(net "P5E_CPU0_PE2_RX_DP<0>")
	)
	(arc
		(start 369.543584 -216.260426)
		(mid 369.465473 -216.537375)
		(end 369.261136 -216.739978)
		(width 0.0889)
		(layer "In13.Cu")
		(net "P5E_CPU0_PE2_RX_DP<0>")
	)
	(arc
		(start 369.252246 -220.000576)
		(mid 369.121332 -220.136936)
		(end 369.073684 -220.319854)
		(width 0.0889)
		(layer "In13.Cu")
		(net "P5E_CPU0_PE2_RX_DP<0>")
	)
	(segment
		(start 377.43638 -221.669864)
		(end 377.43638 -221.134178)
		(width 0.13208)
		(layer "F.Cu")
		(net "P5E_CPU0_PE2_RX_DN<9>")
	)
	(segment
		(start 377.43638 -221.134178)
		(end 377.436634 -221.133924)
		(width 0.13208)
		(layer "F.Cu")
		(net "P5E_CPU0_PE2_RX_DN<9>")
	)
	(segment
		(start 378.29363 -215.658192)
		(end 378.415042 -215.596216)
		(width 0.0889)
		(layer "In13.Cu")
		(net "P5E_CPU0_PE2_RX_DN<9>")
	)
	(segment
		(start 377.632722 -220.814646)
		(end 377.623832 -220.809566)
		(width 0.0889)
		(layer "In13.Cu")
		(net "P5E_CPU0_PE2_RX_DN<9>")
	)
	(segment
		(start 393.24915 -410.434536)
		(end 393.111228 -412.16072)
		(width 0.14732)
		(layer "In13.Cu")
		(net "P5E_CPU0_PE2_RX_DN<9>")
	)
	(segment
		(start 377.28017 -221.404942)
		(end 377.301252 -221.48292)
		(width 0.0889)
		(layer "In13.Cu")
		(net "P5E_CPU0_PE2_RX_DN<9>")
	)
	(segment
		(start 393.094718 -418.543232)
		(end 393.093448 -419.139878)
		(width 0.14732)
		(layer "In13.Cu")
		(net "P5E_CPU0_PE2_RX_DN<9>")
	)
	(segment
		(start 377.625356 -218.202002)
		(end 377.632722 -218.197684)
		(width 0.0889)
		(layer "In13.Cu")
		(net "P5E_CPU0_PE2_RX_DN<9>")
	)
	(segment
		(start 396.880842 -354.523294)
		(end 391.90295 -399.518124)
		(width 0.14732)
		(layer "In13.Cu")
		(net "P5E_CPU0_PE2_RX_DN<9>")
	)
	(segment
		(start 393.231878 -419.648386)
		(end 393.09167 -419.787578)
		(width 0.14732)
		(layer "In13.Cu")
		(net "P5E_CPU0_PE2_RX_DN<9>")
	)
	(segment
		(start 377.34113 -220.334078)
		(end 377.34113 -220.319854)
		(width 0.0889)
		(layer "In13.Cu")
		(net "P5E_CPU0_PE2_RX_DN<9>")
	)
	(segment
		(start 377.623832 -221.458282)
		(end 377.625356 -221.45752)
		(width 0.0889)
		(layer "In13.Cu")
		(net "P5E_CPU0_PE2_RX_DN<9>")
	)
	(segment
		(start 388.362698 -214.44712)
		(end 389.579866 -215.664034)
		(width 0.14732)
		(layer "In13.Cu")
		(net "P5E_CPU0_PE2_RX_DN<9>")
	)
	(segment
		(start 377.623832 -219.18168)
		(end 377.617736 -219.178124)
		(width 0.0889)
		(layer "In13.Cu")
		(net "P5E_CPU0_PE2_RX_DN<9>")
	)
	(segment
		(start 377.617736 -218.20632)
		(end 377.62307 -218.203272)
		(width 0.0889)
		(layer "In13.Cu")
		(net "P5E_CPU0_PE2_RX_DN<9>")
	)
	(segment
		(start 378.452634 -215.530176)
		(end 378.545852 -215.48217)
		(width 0.14732)
		(layer "In13.Cu")
		(net "P5E_CPU0_PE2_RX_DN<9>")
	)
	(segment
		(start 393.093448 -419.139878)
		(end 393.23264 -419.279832)
		(width 0.14732)
		(layer "In13.Cu")
		(net "P5E_CPU0_PE2_RX_DN<9>")
	)
	(segment
		(start 392.458448 -225.339402)
		(end 393.315444 -229.672896)
		(width 0.14732)
		(layer "In13.Cu")
		(net "P5E_CPU0_PE2_RX_DN<9>")
	)
	(segment
		(start 377.623832 -218.202764)
		(end 377.625356 -218.202002)
		(width 0.0889)
		(layer "In13.Cu")
		(net "P5E_CPU0_PE2_RX_DN<9>")
	)
	(segment
		(start 399.481548 -339.493098)
		(end 396.880842 -354.523294)
		(width 0.14732)
		(layer "In13.Cu")
		(net "P5E_CPU0_PE2_RX_DN<9>")
	)
	(segment
		(start 396.530576 -250.28652)
		(end 396.531592 -250.312428)
		(width 0.14732)
		(layer "In13.Cu")
		(net "P5E_CPU0_PE2_RX_DN<9>")
	)
	(segment
		(start 378.102368 -215.755982)
		(end 378.29363 -215.658192)
		(width 0.0889)
		(layer "In13.Cu")
		(net "P5E_CPU0_PE2_RX_DN<9>")
	)
	(segment
		(start 389.579866 -215.664034)
		(end 392.458448 -225.339402)
		(width 0.14732)
		(layer "In13.Cu")
		(net "P5E_CPU0_PE2_RX_DN<9>")
	)
	(segment
		(start 377.617736 -219.833952)
		(end 377.621038 -219.83192)
		(width 0.0889)
		(layer "In13.Cu")
		(net "P5E_CPU0_PE2_RX_DN<9>")
	)
	(segment
		(start 377.62307 -218.203272)
		(end 377.623832 -218.202764)
		(width 0.0889)
		(layer "In13.Cu")
		(net "P5E_CPU0_PE2_RX_DN<9>")
	)
	(segment
		(start 396.531592 -250.312428)
		(end 396.627096 -253.154688)
		(width 0.14732)
		(layer "In13.Cu")
		(net "P5E_CPU0_PE2_RX_DN<9>")
	)
	(segment
		(start 377.623832 -216.574878)
		(end 377.625356 -216.574116)
		(width 0.0889)
		(layer "In13.Cu")
		(net "P5E_CPU0_PE2_RX_DN<9>")
	)
	(segment
		(start 377.621038 -219.83192)
		(end 377.623832 -219.830396)
		(width 0.0889)
		(layer "In13.Cu")
		(net "P5E_CPU0_PE2_RX_DN<9>")
	)
	(segment
		(start 377.625356 -219.829634)
		(end 377.632722 -219.825316)
		(width 0.0889)
		(layer "In13.Cu")
		(net "P5E_CPU0_PE2_RX_DN<9>")
	)
	(segment
		(start 377.625356 -221.45752)
		(end 377.632722 -221.453202)
		(width 0.0889)
		(layer "In13.Cu")
		(net "P5E_CPU0_PE2_RX_DN<9>")
	)
	(segment
		(start 393.09675 -417.895278)
		(end 393.236196 -418.035232)
		(width 0.14732)
		(layer "In13.Cu")
		(net "P5E_CPU0_PE2_RX_DN<9>")
	)
	(segment
		(start 377.632722 -219.18676)
		(end 377.623832 -219.18168)
		(width 0.0889)
		(layer "In13.Cu")
		(net "P5E_CPU0_PE2_RX_DN<9>")
	)
	(segment
		(start 379.089666 -214.938356)
		(end 382.034542 -213.718648)
		(width 0.14732)
		(layer "In13.Cu")
		(net "P5E_CPU0_PE2_RX_DN<9>")
	)
	(segment
		(start 377.34113 -217.07856)
		(end 377.34113 -217.064336)
		(width 0.0889)
		(layer "In13.Cu")
		(net "P5E_CPU0_PE2_RX_DN<9>")
	)
	(segment
		(start 393.24915 -406.051766)
		(end 393.24915 -410.434536)
		(width 0.14732)
		(layer "In13.Cu")
		(net "P5E_CPU0_PE2_RX_DN<9>")
	)
	(segment
		(start 377.623832 -219.830396)
		(end 377.625356 -219.829634)
		(width 0.0889)
		(layer "In13.Cu")
		(net "P5E_CPU0_PE2_RX_DN<9>")
	)
	(segment
		(start 393.236196 -418.035232)
		(end 393.23518 -418.403786)
		(width 0.14732)
		(layer "In13.Cu")
		(net "P5E_CPU0_PE2_RX_DN<9>")
	)
	(segment
		(start 378.433076 -215.539828)
		(end 378.452634 -215.529922)
		(width 0.0889)
		(layer "In13.Cu")
		(net "P5E_CPU0_PE2_RX_DN<9>")
	)
	(segment
		(start 396.627096 -253.154688)
		(end 396.62608 -253.169674)
		(width 0.14732)
		(layer "In13.Cu")
		(net "P5E_CPU0_PE2_RX_DN<9>")
	)
	(segment
		(start 393.111228 -412.16072)
		(end 393.09675 -417.895278)
		(width 0.14732)
		(layer "In13.Cu")
		(net "P5E_CPU0_PE2_RX_DN<9>")
	)
	(segment
		(start 384.537204 -213.718648)
		(end 387.931406 -214.268812)
		(width 0.14732)
		(layer "In13.Cu")
		(net "P5E_CPU0_PE2_RX_DN<9>")
	)
	(segment
		(start 393.315444 -229.672896)
		(end 396.530576 -250.28652)
		(width 0.14732)
		(layer "In13.Cu")
		(net "P5E_CPU0_PE2_RX_DN<9>")
	)
	(segment
		(start 378.545852 -215.48217)
		(end 379.089666 -214.938356)
		(width 0.14732)
		(layer "In13.Cu")
		(net "P5E_CPU0_PE2_RX_DN<9>")
	)
	(segment
		(start 387.931406 -214.268812)
		(end 388.362698 -214.44712)
		(width 0.14732)
		(layer "In13.Cu")
		(net "P5E_CPU0_PE2_RX_DN<9>")
	)
	(segment
		(start 391.90295 -404.705566)
		(end 393.24915 -406.051766)
		(width 0.14732)
		(layer "In13.Cu")
		(net "P5E_CPU0_PE2_RX_DN<9>")
	)
	(segment
		(start 393.21613 -433.719478)
		(end 393.411964 -433.719478)
		(width 0.14732)
		(layer "In13.Cu")
		(net "P5E_CPU0_PE2_RX_DN<9>")
	)
	(segment
		(start 399.46834 -339.438234)
		(end 399.481548 -339.493098)
		(width 0.14732)
		(layer "In13.Cu")
		(net "P5E_CPU0_PE2_RX_DN<9>")
	)
	(segment
		(start 378.093478 -215.761062)
		(end 378.102368 -215.755982)
		(width 0.0889)
		(layer "In13.Cu")
		(net "P5E_CPU0_PE2_RX_DN<9>")
	)
	(segment
		(start 382.034542 -213.718648)
		(end 384.537204 -213.718648)
		(width 0.14732)
		(layer "In13.Cu")
		(net "P5E_CPU0_PE2_RX_DN<9>")
	)
	(segment
		(start 393.23518 -418.403786)
		(end 393.094718 -418.543232)
		(width 0.14732)
		(layer "In13.Cu")
		(net "P5E_CPU0_PE2_RX_DN<9>")
	)
	(segment
		(start 393.08024 -433.583588)
		(end 393.21613 -433.719478)
		(width 0.14732)
		(layer "In13.Cu")
		(net "P5E_CPU0_PE2_RX_DN<9>")
	)
	(segment
		(start 396.625826 -253.169674)
		(end 392.317986 -309.417974)
		(width 0.14732)
		(layer "In13.Cu")
		(net "P5E_CPU0_PE2_RX_DN<9>")
	)
	(segment
		(start 377.625356 -216.574116)
		(end 377.632722 -216.569798)
		(width 0.0889)
		(layer "In13.Cu")
		(net "P5E_CPU0_PE2_RX_DN<9>")
	)
	(segment
		(start 391.90295 -399.518124)
		(end 391.90295 -404.705566)
		(width 0.14732)
		(layer "In13.Cu")
		(net "P5E_CPU0_PE2_RX_DN<9>")
	)
	(segment
		(start 392.317986 -309.417974)
		(end 399.46834 -339.438234)
		(width 0.14732)
		(layer "In13.Cu")
		(net "P5E_CPU0_PE2_RX_DN<9>")
	)
	(segment
		(start 393.09167 -419.787578)
		(end 393.08024 -424.22445)
		(width 0.14732)
		(layer "In13.Cu")
		(net "P5E_CPU0_PE2_RX_DN<9>")
	)
	(segment
		(start 393.750038 -433.381404)
		(end 393.750038 -433.289964)
		(width 0.14732)
		(layer "In13.Cu")
		(net "P5E_CPU0_PE2_RX_DN<9>")
	)
	(segment
		(start 377.436634 -221.133924)
		(end 377.28017 -221.404942)
		(width 0.0889)
		(layer "In13.Cu")
		(net "P5E_CPU0_PE2_RX_DN<9>")
	)
	(segment
		(start 378.452634 -215.529922)
		(end 378.452634 -215.530176)
		(width 0.0889)
		(layer "In13.Cu")
		(net "P5E_CPU0_PE2_RX_DN<9>")
	)
	(segment
		(start 378.415042 -215.596216)
		(end 378.433076 -215.539828)
		(width 0.0889)
		(layer "In13.Cu")
		(net "P5E_CPU0_PE2_RX_DN<9>")
	)
	(segment
		(start 396.62608 -253.169674)
		(end 396.625826 -253.169674)
		(width 0.14732)
		(layer "In13.Cu")
		(net "P5E_CPU0_PE2_RX_DN<9>")
	)
	(segment
		(start 393.411964 -433.719478)
		(end 393.750038 -433.381404)
		(width 0.14732)
		(layer "In13.Cu")
		(net "P5E_CPU0_PE2_RX_DN<9>")
	)
	(segment
		(start 377.617736 -216.578434)
		(end 377.623832 -216.574878)
		(width 0.0889)
		(layer "In13.Cu")
		(net "P5E_CPU0_PE2_RX_DN<9>")
	)
	(segment
		(start 377.632722 -217.559128)
		(end 377.623832 -217.554048)
		(width 0.0889)
		(layer "In13.Cu")
		(net "P5E_CPU0_PE2_RX_DN<9>")
	)
	(segment
		(start 393.23264 -419.279832)
		(end 393.231878 -419.648386)
		(width 0.14732)
		(layer "In13.Cu")
		(net "P5E_CPU0_PE2_RX_DN<9>")
	)
	(segment
		(start 393.08024 -424.22445)
		(end 393.08024 -433.583588)
		(width 0.14732)
		(layer "In13.Cu")
		(net "P5E_CPU0_PE2_RX_DN<9>")
	)
	(segment
		(start 377.811284 -216.25052)
		(end 377.811284 -216.235026)
		(width 0.0889)
		(layer "In13.Cu")
		(net "P5E_CPU0_PE2_RX_DN<9>")
	)
	(arc
		(start 377.811284 -216.235026)
		(mid 377.890654 -215.961292)
		(end 378.093478 -215.761062)
		(width 0.0889)
		(layer "In13.Cu")
		(net "P5E_CPU0_PE2_RX_DN<9>")
	)
	(arc
		(start 377.632722 -219.825316)
		(mid 377.811319 -219.506038)
		(end 377.632722 -219.18676)
		(width 0.0889)
		(layer "In13.Cu")
		(net "P5E_CPU0_PE2_RX_DN<9>")
	)
	(arc
		(start 377.34113 -217.064336)
		(mid 377.415121 -216.78477)
		(end 377.617736 -216.578434)
		(width 0.0889)
		(layer "In13.Cu")
		(net "P5E_CPU0_PE2_RX_DN<9>")
	)
	(arc
		(start 377.301252 -221.48292)
		(mid 377.465348 -221.507267)
		(end 377.623832 -221.458282)
		(width 0.0889)
		(layer "In13.Cu")
		(net "P5E_CPU0_PE2_RX_DN<9>")
	)
	(arc
		(start 377.632722 -221.453202)
		(mid 377.81144 -221.133924)
		(end 377.632722 -220.814646)
		(width 0.0889)
		(layer "In13.Cu")
		(net "P5E_CPU0_PE2_RX_DN<9>")
	)
	(arc
		(start 377.617736 -219.178124)
		(mid 377.341162 -218.692222)
		(end 377.617736 -218.20632)
		(width 0.0889)
		(layer "In13.Cu")
		(net "P5E_CPU0_PE2_RX_DN<9>")
	)
	(arc
		(start 377.623832 -220.809566)
		(mid 377.420351 -220.608762)
		(end 377.34113 -220.334078)
		(width 0.0889)
		(layer "In13.Cu")
		(net "P5E_CPU0_PE2_RX_DN<9>")
	)
	(arc
		(start 377.623832 -217.554048)
		(mid 377.420351 -217.353244)
		(end 377.34113 -217.07856)
		(width 0.0889)
		(layer "In13.Cu")
		(net "P5E_CPU0_PE2_RX_DN<9>")
	)
	(arc
		(start 377.34113 -220.319854)
		(mid 377.415121 -220.040288)
		(end 377.617736 -219.833952)
		(width 0.0889)
		(layer "In13.Cu")
		(net "P5E_CPU0_PE2_RX_DN<9>")
	)
	(arc
		(start 377.632722 -218.197684)
		(mid 377.81144 -217.878406)
		(end 377.632722 -217.559128)
		(width 0.0889)
		(layer "In13.Cu")
		(net "P5E_CPU0_PE2_RX_DN<9>")
	)
	(arc
		(start 377.632722 -216.569798)
		(mid 377.763636 -216.433438)
		(end 377.811284 -216.25052)
		(width 0.0889)
		(layer "In13.Cu")
		(net "P5E_CPU0_PE2_RX_DN<9>")
	)
	(segment
		(start 376.026934 -220.320108)
		(end 376.02668 -220.319854)
		(width 0.13208)
		(layer "F.Cu")
		(net "P5E_CPU0_PE2_RX_DN<8>")
	)
	(segment
		(start 376.026934 -220.855794)
		(end 376.026934 -220.320108)
		(width 0.13208)
		(layer "F.Cu")
		(net "P5E_CPU0_PE2_RX_DN<8>")
	)
	(segment
		(start 376.183144 -220.590872)
		(end 376.02668 -220.319854)
		(width 0.0889)
		(layer "In13.Cu")
		(net "P5E_CPU0_PE2_RX_DN<8>")
	)
	(segment
		(start 378.23902 -212.856318)
		(end 378.23902 -213.142068)
		(width 0.14732)
		(layer "In13.Cu")
		(net "P5E_CPU0_PE2_RX_DN<8>")
	)
	(segment
		(start 394.96619 -404.705566)
		(end 394.96619 -399.533364)
		(width 0.14732)
		(layer "In13.Cu")
		(net "P5E_CPU0_PE2_RX_DN<8>")
	)
	(segment
		(start 394.241528 -229.50424)
		(end 393.409678 -225.1837)
		(width 0.14732)
		(layer "In13.Cu")
		(net "P5E_CPU0_PE2_RX_DN<8>")
	)
	(segment
		(start 393.295124 -309.306214)
		(end 397.5608 -253.218442)
		(width 0.14732)
		(layer "In13.Cu")
		(net "P5E_CPU0_PE2_RX_DN<8>")
	)
	(segment
		(start 377.341638 -215.236552)
		(end 377.341638 -215.444578)
		(width 0.0889)
		(layer "In13.Cu")
		(net "P5E_CPU0_PE2_RX_DN<8>")
	)
	(segment
		(start 391.211562 -217.744802)
		(end 390.460484 -215.203024)
		(width 0.14732)
		(layer "In13.Cu")
		(net "P5E_CPU0_PE2_RX_DN<8>")
	)
	(segment
		(start 376.684794 -217.554556)
		(end 376.692922 -217.559128)
		(width 0.0889)
		(layer "In13.Cu")
		(net "P5E_CPU0_PE2_RX_DN<8>")
	)
	(segment
		(start 395.554454 -420.217854)
		(end 395.426184 -420.067486)
		(width 0.14732)
		(layer "In13.Cu")
		(net "P5E_CPU0_PE2_RX_DN<8>")
	)
	(segment
		(start 378.02185 -214.321644)
		(end 377.5075 -214.836248)
		(width 0.0889)
		(layer "In13.Cu")
		(net "P5E_CPU0_PE2_RX_DN<8>")
	)
	(segment
		(start 378.23902 -213.142068)
		(end 378.23902 -213.164166)
		(width 0.0889)
		(layer "In13.Cu")
		(net "P5E_CPU0_PE2_RX_DN<8>")
	)
	(segment
		(start 397.450818 -249.950478)
		(end 394.241528 -229.50424)
		(width 0.14732)
		(layer "In13.Cu")
		(net "P5E_CPU0_PE2_RX_DN<8>")
	)
	(segment
		(start 384.101086 -212.538564)
		(end 378.556774 -212.538564)
		(width 0.14732)
		(layer "In13.Cu")
		(net "P5E_CPU0_PE2_RX_DN<8>")
	)
	(segment
		(start 376.692922 -216.569798)
		(end 376.684032 -216.574878)
		(width 0.0889)
		(layer "In13.Cu")
		(net "P5E_CPU0_PE2_RX_DN<8>")
	)
	(segment
		(start 397.5608 -253.218442)
		(end 397.450818 -249.950478)
		(width 0.14732)
		(layer "In13.Cu")
		(net "P5E_CPU0_PE2_RX_DN<8>")
	)
	(segment
		(start 376.684032 -216.574878)
		(end 376.680222 -216.577164)
		(width 0.0889)
		(layer "In13.Cu")
		(net "P5E_CPU0_PE2_RX_DN<8>")
	)
	(segment
		(start 397.76781 -355.109272)
		(end 400.463004 -339.533738)
		(width 0.14732)
		(layer "In13.Cu")
		(net "P5E_CPU0_PE2_RX_DN<8>")
	)
	(segment
		(start 376.684032 -219.830396)
		(end 376.680222 -219.832682)
		(width 0.0889)
		(layer "In13.Cu")
		(net "P5E_CPU0_PE2_RX_DN<8>")
	)
	(segment
		(start 376.261376 -220.6117)
		(end 376.183144 -220.590872)
		(width 0.0889)
		(layer "In13.Cu")
		(net "P5E_CPU0_PE2_RX_DN<8>")
	)
	(segment
		(start 376.684032 -217.554048)
		(end 376.684794 -217.554556)
		(width 0.0889)
		(layer "In13.Cu")
		(net "P5E_CPU0_PE2_RX_DN<8>")
	)
	(segment
		(start 396.31239 -406.051766)
		(end 394.96619 -404.705566)
		(width 0.14732)
		(layer "In13.Cu")
		(net "P5E_CPU0_PE2_RX_DN<8>")
	)
	(segment
		(start 377.5075 -214.836248)
		(end 377.341638 -215.236552)
		(width 0.0889)
		(layer "In13.Cu")
		(net "P5E_CPU0_PE2_RX_DN<8>")
	)
	(segment
		(start 376.692922 -219.825316)
		(end 376.684032 -219.830396)
		(width 0.0889)
		(layer "In13.Cu")
		(net "P5E_CPU0_PE2_RX_DN<8>")
	)
	(segment
		(start 395.37513 -420.713916)
		(end 395.374876 -420.713408)
		(width 0.14732)
		(layer "In13.Cu")
		(net "P5E_CPU0_PE2_RX_DN<8>")
	)
	(segment
		(start 388.713218 -213.456012)
		(end 384.101086 -212.538564)
		(width 0.14732)
		(layer "In13.Cu")
		(net "P5E_CPU0_PE2_RX_DN<8>")
	)
	(segment
		(start 376.677936 -219.178124)
		(end 376.68327 -219.181172)
		(width 0.0889)
		(layer "In13.Cu")
		(net "P5E_CPU0_PE2_RX_DN<8>")
	)
	(segment
		(start 395.426184 -420.067486)
		(end 395.967966 -413.217106)
		(width 0.14732)
		(layer "In13.Cu")
		(net "P5E_CPU0_PE2_RX_DN<8>")
	)
	(segment
		(start 395.066266 -424.61815)
		(end 395.37513 -420.713916)
		(width 0.14732)
		(layer "In13.Cu")
		(net "P5E_CPU0_PE2_RX_DN<8>")
	)
	(segment
		(start 376.68327 -219.181172)
		(end 376.684032 -219.18168)
		(width 0.0889)
		(layer "In13.Cu")
		(net "P5E_CPU0_PE2_RX_DN<8>")
	)
	(segment
		(start 390.460484 -215.203024)
		(end 388.713218 -213.456012)
		(width 0.14732)
		(layer "In13.Cu")
		(net "P5E_CPU0_PE2_RX_DN<8>")
	)
	(segment
		(start 395.374876 -420.713408)
		(end 395.525498 -420.585138)
		(width 0.14732)
		(layer "In13.Cu")
		(net "P5E_CPU0_PE2_RX_DN<8>")
	)
	(segment
		(start 376.685556 -218.202002)
		(end 376.684032 -218.202764)
		(width 0.0889)
		(layer "In13.Cu")
		(net "P5E_CPU0_PE2_RX_DN<8>")
	)
	(segment
		(start 378.281184 -213.696296)
		(end 378.02185 -214.321644)
		(width 0.0889)
		(layer "In13.Cu")
		(net "P5E_CPU0_PE2_RX_DN<8>")
	)
	(segment
		(start 395.525498 -420.585138)
		(end 395.554454 -420.217854)
		(width 0.14732)
		(layer "In13.Cu")
		(net "P5E_CPU0_PE2_RX_DN<8>")
	)
	(segment
		(start 376.680222 -216.577164)
		(end 376.67184 -216.58199)
		(width 0.0889)
		(layer "In13.Cu")
		(net "P5E_CPU0_PE2_RX_DN<8>")
	)
	(segment
		(start 376.685556 -219.182442)
		(end 376.692922 -219.18676)
		(width 0.0889)
		(layer "In13.Cu")
		(net "P5E_CPU0_PE2_RX_DN<8>")
	)
	(segment
		(start 395.223238 -434.672994)
		(end 395.066266 -434.516022)
		(width 0.14732)
		(layer "In13.Cu")
		(net "P5E_CPU0_PE2_RX_DN<8>")
	)
	(segment
		(start 395.367002 -434.672994)
		(end 395.223238 -434.672994)
		(width 0.14732)
		(layer "In13.Cu")
		(net "P5E_CPU0_PE2_RX_DN<8>")
	)
	(segment
		(start 393.409678 -225.1837)
		(end 391.943336 -220.220794)
		(width 0.14732)
		(layer "In13.Cu")
		(net "P5E_CPU0_PE2_RX_DN<8>")
	)
	(segment
		(start 391.211816 -217.745056)
		(end 391.211562 -217.744802)
		(width 0.14732)
		(layer "In13.Cu")
		(net "P5E_CPU0_PE2_RX_DN<8>")
	)
	(segment
		(start 400.463004 -339.533738)
		(end 393.295124 -309.306214)
		(width 0.14732)
		(layer "In13.Cu")
		(net "P5E_CPU0_PE2_RX_DN<8>")
	)
	(segment
		(start 395.750034 -434.289962)
		(end 395.367002 -434.672994)
		(width 0.14732)
		(layer "In13.Cu")
		(net "P5E_CPU0_PE2_RX_DN<8>")
	)
	(segment
		(start 378.556774 -212.538564)
		(end 378.23902 -212.856318)
		(width 0.14732)
		(layer "In13.Cu")
		(net "P5E_CPU0_PE2_RX_DN<8>")
	)
	(segment
		(start 395.066266 -434.516022)
		(end 395.066266 -424.61815)
		(width 0.14732)
		(layer "In13.Cu")
		(net "P5E_CPU0_PE2_RX_DN<8>")
	)
	(segment
		(start 376.684032 -219.18168)
		(end 376.685556 -219.182442)
		(width 0.0889)
		(layer "In13.Cu")
		(net "P5E_CPU0_PE2_RX_DN<8>")
	)
	(segment
		(start 377.15444 -215.761062)
		(end 377.154186 -215.760808)
		(width 0.0889)
		(layer "In13.Cu")
		(net "P5E_CPU0_PE2_RX_DN<8>")
	)
	(segment
		(start 376.681238 -218.204288)
		(end 376.677936 -218.20632)
		(width 0.0889)
		(layer "In13.Cu")
		(net "P5E_CPU0_PE2_RX_DN<8>")
	)
	(segment
		(start 391.943082 -220.220032)
		(end 391.211816 -217.745056)
		(width 0.14732)
		(layer "In13.Cu")
		(net "P5E_CPU0_PE2_RX_DN<8>")
	)
	(segment
		(start 396.31239 -410.68625)
		(end 396.31239 -406.051766)
		(width 0.14732)
		(layer "In13.Cu")
		(net "P5E_CPU0_PE2_RX_DN<8>")
	)
	(segment
		(start 376.40133 -217.064336)
		(end 376.40133 -217.071956)
		(width 0.0889)
		(layer "In13.Cu")
		(net "P5E_CPU0_PE2_RX_DN<8>")
	)
	(segment
		(start 377.154186 -215.760808)
		(end 377.153932 -215.761062)
		(width 0.0889)
		(layer "In13.Cu")
		(net "P5E_CPU0_PE2_RX_DN<8>")
	)
	(segment
		(start 378.23902 -213.164166)
		(end 378.281184 -213.20633)
		(width 0.0889)
		(layer "In13.Cu")
		(net "P5E_CPU0_PE2_RX_DN<8>")
	)
	(segment
		(start 376.871484 -216.240614)
		(end 376.871484 -216.25052)
		(width 0.0889)
		(layer "In13.Cu")
		(net "P5E_CPU0_PE2_RX_DN<8>")
	)
	(segment
		(start 376.680222 -219.832682)
		(end 376.67184 -219.837508)
		(width 0.0889)
		(layer "In13.Cu")
		(net "P5E_CPU0_PE2_RX_DN<8>")
	)
	(segment
		(start 376.684032 -218.202764)
		(end 376.681238 -218.204288)
		(width 0.0889)
		(layer "In13.Cu")
		(net "P5E_CPU0_PE2_RX_DN<8>")
	)
	(segment
		(start 395.967966 -413.217106)
		(end 396.31239 -410.68625)
		(width 0.14732)
		(layer "In13.Cu")
		(net "P5E_CPU0_PE2_RX_DN<8>")
	)
	(segment
		(start 394.96619 -399.533364)
		(end 397.76781 -355.109272)
		(width 0.14732)
		(layer "In13.Cu")
		(net "P5E_CPU0_PE2_RX_DN<8>")
	)
	(segment
		(start 378.281184 -213.20633)
		(end 378.281184 -213.696296)
		(width 0.0889)
		(layer "In13.Cu")
		(net "P5E_CPU0_PE2_RX_DN<8>")
	)
	(segment
		(start 376.692922 -218.197684)
		(end 376.685556 -218.202002)
		(width 0.0889)
		(layer "In13.Cu")
		(net "P5E_CPU0_PE2_RX_DN<8>")
	)
	(segment
		(start 391.943336 -220.220794)
		(end 391.943082 -220.220032)
		(width 0.14732)
		(layer "In13.Cu")
		(net "P5E_CPU0_PE2_RX_DN<8>")
	)
	(arc
		(start 376.677936 -218.20632)
		(mid 376.401362 -218.692222)
		(end 376.677936 -219.178124)
		(width 0.0889)
		(layer "In13.Cu")
		(net "P5E_CPU0_PE2_RX_DN<8>")
	)
	(arc
		(start 376.67184 -216.58199)
		(mid 376.473612 -216.787838)
		(end 376.40133 -217.064336)
		(width 0.0889)
		(layer "In13.Cu")
		(net "P5E_CPU0_PE2_RX_DN<8>")
	)
	(arc
		(start 376.871484 -216.25052)
		(mid 376.823805 -216.43342)
		(end 376.692922 -216.569798)
		(width 0.0889)
		(layer "In13.Cu")
		(net "P5E_CPU0_PE2_RX_DN<8>")
	)
	(arc
		(start 376.40133 -220.319854)
		(mid 376.36447 -220.481651)
		(end 376.261376 -220.6117)
		(width 0.0889)
		(layer "In13.Cu")
		(net "P5E_CPU0_PE2_RX_DN<8>")
	)
	(arc
		(start 376.40133 -217.071956)
		(mid 376.478959 -217.350369)
		(end 376.684032 -217.554048)
		(width 0.0889)
		(layer "In13.Cu")
		(net "P5E_CPU0_PE2_RX_DN<8>")
	)
	(arc
		(start 376.67184 -219.837508)
		(mid 376.473612 -220.043356)
		(end 376.40133 -220.319854)
		(width 0.0889)
		(layer "In13.Cu")
		(net "P5E_CPU0_PE2_RX_DN<8>")
	)
	(arc
		(start 377.341638 -215.444578)
		(mid 377.2895 -215.627346)
		(end 377.15444 -215.761062)
		(width 0.0889)
		(layer "In13.Cu")
		(net "P5E_CPU0_PE2_RX_DN<8>")
	)
	(arc
		(start 377.153932 -215.761062)
		(mid 376.949597 -215.963667)
		(end 376.871484 -216.240614)
		(width 0.0889)
		(layer "In13.Cu")
		(net "P5E_CPU0_PE2_RX_DN<8>")
	)
	(arc
		(start 376.692922 -217.559128)
		(mid 376.871398 -217.878406)
		(end 376.692922 -218.197684)
		(width 0.0889)
		(layer "In13.Cu")
		(net "P5E_CPU0_PE2_RX_DN<8>")
	)
	(arc
		(start 376.692922 -219.18676)
		(mid 376.871519 -219.506038)
		(end 376.692922 -219.825316)
		(width 0.0889)
		(layer "In13.Cu")
		(net "P5E_CPU0_PE2_RX_DN<8>")
	)
	(segment
		(start 375.55678 -221.134178)
		(end 375.557034 -221.133924)
		(width 0.13208)
		(layer "F.Cu")
		(net "P5E_CPU0_PE2_RX_DN<7>")
	)
	(segment
		(start 375.55678 -221.669864)
		(end 375.55678 -221.134178)
		(width 0.13208)
		(layer "F.Cu")
		(net "P5E_CPU0_PE2_RX_DN<7>")
	)
	(segment
		(start 377.402852 -212.365082)
		(end 377.298458 -212.617304)
		(width 0.14732)
		(layer "In13.Cu")
		(net "P5E_CPU0_PE2_RX_DN<7>")
	)
	(segment
		(start 376.64009 -214.743284)
		(end 376.413776 -215.289892)
		(width 0.0889)
		(layer "In13.Cu")
		(net "P5E_CPU0_PE2_RX_DN<7>")
	)
	(segment
		(start 389.27532 -212.552788)
		(end 383.953258 -211.494624)
		(width 0.14732)
		(layer "In13.Cu")
		(net "P5E_CPU0_PE2_RX_DN<7>")
	)
	(segment
		(start 398.493234 -253.251462)
		(end 398.357344 -249.212354)
		(width 0.14732)
		(layer "In13.Cu")
		(net "P5E_CPU0_PE2_RX_DN<7>")
	)
	(segment
		(start 391.339578 -214.617046)
		(end 389.27532 -212.552788)
		(width 0.14732)
		(layer "In13.Cu")
		(net "P5E_CPU0_PE2_RX_DN<7>")
	)
	(segment
		(start 377.298458 -213.142068)
		(end 377.298458 -213.164166)
		(width 0.0889)
		(layer "In13.Cu")
		(net "P5E_CPU0_PE2_RX_DN<7>")
	)
	(segment
		(start 375.421652 -221.48292)
		(end 375.40057 -221.404942)
		(width 0.0889)
		(layer "In13.Cu")
		(net "P5E_CPU0_PE2_RX_DN<7>")
	)
	(segment
		(start 375.74347 -218.203272)
		(end 375.738136 -218.20632)
		(width 0.0889)
		(layer "In13.Cu")
		(net "P5E_CPU0_PE2_RX_DN<7>")
	)
	(segment
		(start 375.744232 -219.18168)
		(end 375.753122 -219.18676)
		(width 0.0889)
		(layer "In13.Cu")
		(net "P5E_CPU0_PE2_RX_DN<7>")
	)
	(segment
		(start 375.46153 -220.319854)
		(end 375.46153 -220.334078)
		(width 0.0889)
		(layer "In13.Cu")
		(net "P5E_CPU0_PE2_RX_DN<7>")
	)
	(segment
		(start 375.753122 -216.569798)
		(end 375.745756 -216.574116)
		(width 0.0889)
		(layer "In13.Cu")
		(net "P5E_CPU0_PE2_RX_DN<7>")
	)
	(segment
		(start 375.46153 -217.064336)
		(end 375.46153 -217.07856)
		(width 0.0889)
		(layer "In13.Cu")
		(net "P5E_CPU0_PE2_RX_DN<7>")
	)
	(segment
		(start 398.361916 -421.144192)
		(end 398.512284 -421.01643)
		(width 0.14732)
		(layer "In13.Cu")
		(net "P5E_CPU0_PE2_RX_DN<7>")
	)
	(segment
		(start 375.753122 -219.825316)
		(end 375.738136 -219.833952)
		(width 0.0889)
		(layer "In13.Cu")
		(net "P5E_CPU0_PE2_RX_DN<7>")
	)
	(segment
		(start 375.40057 -221.404942)
		(end 375.557034 -221.133924)
		(width 0.0889)
		(layer "In13.Cu")
		(net "P5E_CPU0_PE2_RX_DN<7>")
	)
	(segment
		(start 377.298458 -213.164166)
		(end 377.340622 -213.20633)
		(width 0.0889)
		(layer "In13.Cu")
		(net "P5E_CPU0_PE2_RX_DN<7>")
	)
	(segment
		(start 394.583412 -225.746056)
		(end 392.968988 -220.207332)
		(width 0.14732)
		(layer "In13.Cu")
		(net "P5E_CPU0_PE2_RX_DN<7>")
	)
	(segment
		(start 376.413776 -215.289892)
		(end 376.401584 -215.442038)
		(width 0.0889)
		(layer "In13.Cu")
		(net "P5E_CPU0_PE2_RX_DN<7>")
	)
	(segment
		(start 398.710404 -355.182678)
		(end 401.443952 -339.421978)
		(width 0.14732)
		(layer "In13.Cu")
		(net "P5E_CPU0_PE2_RX_DN<7>")
	)
	(segment
		(start 377.199144 -214.18423)
		(end 376.64009 -214.743284)
		(width 0.0889)
		(layer "In13.Cu")
		(net "P5E_CPU0_PE2_RX_DN<7>")
	)
	(segment
		(start 398.41424 -420.498524)
		(end 398.521174 -419.176454)
		(width 0.14732)
		(layer "In13.Cu")
		(net "P5E_CPU0_PE2_RX_DN<7>")
	)
	(segment
		(start 376.222768 -215.755982)
		(end 376.213878 -215.761062)
		(width 0.0889)
		(layer "In13.Cu")
		(net "P5E_CPU0_PE2_RX_DN<7>")
	)
	(segment
		(start 398.156176 -433.719478)
		(end 398.06626 -433.629562)
		(width 0.14732)
		(layer "In13.Cu")
		(net "P5E_CPU0_PE2_RX_DN<7>")
	)
	(segment
		(start 398.701514 -418.681154)
		(end 398.573498 -418.530786)
		(width 0.14732)
		(layer "In13.Cu")
		(net "P5E_CPU0_PE2_RX_DN<7>")
	)
	(segment
		(start 375.745756 -216.574116)
		(end 375.744232 -216.574878)
		(width 0.0889)
		(layer "In13.Cu")
		(net "P5E_CPU0_PE2_RX_DN<7>")
	)
	(segment
		(start 394.278104 -308.944772)
		(end 396.36573 -281.359356)
		(width 0.14732)
		(layer "In13.Cu")
		(net "P5E_CPU0_PE2_RX_DN<7>")
	)
	(segment
		(start 398.968214 -413.65297)
		(end 399.37563 -410.423614)
		(width 0.14732)
		(layer "In13.Cu")
		(net "P5E_CPU0_PE2_RX_DN<7>")
	)
	(segment
		(start 398.573498 -418.530786)
		(end 398.968214 -413.65297)
		(width 0.14732)
		(layer "In13.Cu")
		(net "P5E_CPU0_PE2_RX_DN<7>")
	)
	(segment
		(start 377.298458 -212.617304)
		(end 377.298458 -213.142068)
		(width 0.14732)
		(layer "In13.Cu")
		(net "P5E_CPU0_PE2_RX_DN<7>")
	)
	(segment
		(start 376.401584 -215.442038)
		(end 376.401076 -215.442038)
		(width 0.0889)
		(layer "In13.Cu")
		(net "P5E_CPU0_PE2_RX_DN<7>")
	)
	(segment
		(start 383.953258 -211.494624)
		(end 378.578872 -211.494624)
		(width 0.14732)
		(layer "In13.Cu")
		(net "P5E_CPU0_PE2_RX_DN<7>")
	)
	(segment
		(start 397.882364 -397.807942)
		(end 398.673066 -355.993192)
		(width 0.14732)
		(layer "In13.Cu")
		(net "P5E_CPU0_PE2_RX_DN<7>")
	)
	(segment
		(start 377.340622 -213.20633)
		(end 377.340622 -213.843362)
		(width 0.0889)
		(layer "In13.Cu")
		(net "P5E_CPU0_PE2_RX_DN<7>")
	)
	(segment
		(start 375.744232 -216.574878)
		(end 375.738136 -216.578434)
		(width 0.0889)
		(layer "In13.Cu")
		(net "P5E_CPU0_PE2_RX_DN<7>")
	)
	(segment
		(start 375.753122 -218.197684)
		(end 375.745756 -218.202002)
		(width 0.0889)
		(layer "In13.Cu")
		(net "P5E_CPU0_PE2_RX_DN<7>")
	)
	(segment
		(start 399.37563 -410.423614)
		(end 399.37563 -406.051766)
		(width 0.14732)
		(layer "In13.Cu")
		(net "P5E_CPU0_PE2_RX_DN<7>")
	)
	(segment
		(start 375.931684 -216.235026)
		(end 375.931684 -216.25052)
		(width 0.0889)
		(layer "In13.Cu")
		(net "P5E_CPU0_PE2_RX_DN<7>")
	)
	(segment
		(start 399.37563 -406.051766)
		(end 398.02943 -404.705566)
		(width 0.14732)
		(layer "In13.Cu")
		(net "P5E_CPU0_PE2_RX_DN<7>")
	)
	(segment
		(start 375.744232 -218.202764)
		(end 375.74347 -218.203272)
		(width 0.0889)
		(layer "In13.Cu")
		(net "P5E_CPU0_PE2_RX_DN<7>")
	)
	(segment
		(start 378.05741 -211.710524)
		(end 377.402852 -212.365082)
		(width 0.14732)
		(layer "In13.Cu")
		(net "P5E_CPU0_PE2_RX_DN<7>")
	)
	(segment
		(start 398.671796 -419.048438)
		(end 398.701514 -418.681154)
		(width 0.14732)
		(layer "In13.Cu")
		(net "P5E_CPU0_PE2_RX_DN<7>")
	)
	(segment
		(start 392.968988 -220.207332)
		(end 392.968734 -220.20657)
		(width 0.14732)
		(layer "In13.Cu")
		(net "P5E_CPU0_PE2_RX_DN<7>")
	)
	(segment
		(start 398.512284 -421.01643)
		(end 398.542002 -420.649146)
		(width 0.14732)
		(layer "In13.Cu")
		(net "P5E_CPU0_PE2_RX_DN<7>")
	)
	(segment
		(start 398.710404 -355.374448)
		(end 398.710404 -355.182678)
		(width 0.14732)
		(layer "In13.Cu")
		(net "P5E_CPU0_PE2_RX_DN<7>")
	)
	(segment
		(start 375.738136 -219.178124)
		(end 375.744232 -219.18168)
		(width 0.0889)
		(layer "In13.Cu")
		(net "P5E_CPU0_PE2_RX_DN<7>")
	)
	(segment
		(start 375.745756 -218.202002)
		(end 375.744232 -218.202764)
		(width 0.0889)
		(layer "In13.Cu")
		(net "P5E_CPU0_PE2_RX_DN<7>")
	)
	(segment
		(start 398.06626 -433.629562)
		(end 398.06626 -424.796204)
		(width 0.14732)
		(layer "In13.Cu")
		(net "P5E_CPU0_PE2_RX_DN<7>")
	)
	(segment
		(start 398.320514 -433.719478)
		(end 398.156176 -433.719478)
		(width 0.14732)
		(layer "In13.Cu")
		(net "P5E_CPU0_PE2_RX_DN<7>")
	)
	(segment
		(start 396.366238 -281.359356)
		(end 398.493234 -253.251462)
		(width 0.14732)
		(layer "In13.Cu")
		(net "P5E_CPU0_PE2_RX_DN<7>")
	)
	(segment
		(start 375.744232 -220.809566)
		(end 375.753122 -220.814646)
		(width 0.0889)
		(layer "In13.Cu")
		(net "P5E_CPU0_PE2_RX_DN<7>")
	)
	(segment
		(start 375.753122 -221.453202)
		(end 375.745756 -221.45752)
		(width 0.0889)
		(layer "In13.Cu")
		(net "P5E_CPU0_PE2_RX_DN<7>")
	)
	(segment
		(start 398.542002 -420.649146)
		(end 398.41424 -420.498524)
		(width 0.14732)
		(layer "In13.Cu")
		(net "P5E_CPU0_PE2_RX_DN<7>")
	)
	(segment
		(start 392.968734 -220.20657)
		(end 391.339578 -214.617046)
		(width 0.14732)
		(layer "In13.Cu")
		(net "P5E_CPU0_PE2_RX_DN<7>")
	)
	(segment
		(start 375.744232 -217.554048)
		(end 375.753122 -217.559128)
		(width 0.0889)
		(layer "In13.Cu")
		(net "P5E_CPU0_PE2_RX_DN<7>")
	)
	(segment
		(start 398.02943 -404.705566)
		(end 398.02943 -400.495008)
		(width 0.14732)
		(layer "In13.Cu")
		(net "P5E_CPU0_PE2_RX_DN<7>")
	)
	(segment
		(start 375.745756 -221.45752)
		(end 375.744232 -221.458282)
		(width 0.0889)
		(layer "In13.Cu")
		(net "P5E_CPU0_PE2_RX_DN<7>")
	)
	(segment
		(start 377.340622 -213.843362)
		(end 377.199144 -214.18423)
		(width 0.0889)
		(layer "In13.Cu")
		(net "P5E_CPU0_PE2_RX_DN<7>")
	)
	(segment
		(start 398.521174 -419.176454)
		(end 398.671796 -419.048438)
		(width 0.14732)
		(layer "In13.Cu")
		(net "P5E_CPU0_PE2_RX_DN<7>")
	)
	(segment
		(start 398.673066 -355.993192)
		(end 398.710404 -355.374448)
		(width 0.14732)
		(layer "In13.Cu")
		(net "P5E_CPU0_PE2_RX_DN<7>")
	)
	(segment
		(start 398.02943 -400.495008)
		(end 397.882364 -397.807942)
		(width 0.14732)
		(layer "In13.Cu")
		(net "P5E_CPU0_PE2_RX_DN<7>")
	)
	(segment
		(start 398.750028 -433.289964)
		(end 398.320514 -433.719478)
		(width 0.14732)
		(layer "In13.Cu")
		(net "P5E_CPU0_PE2_RX_DN<7>")
	)
	(segment
		(start 396.36573 -281.359356)
		(end 396.366238 -281.359356)
		(width 0.14732)
		(layer "In13.Cu")
		(net "P5E_CPU0_PE2_RX_DN<7>")
	)
	(segment
		(start 398.06626 -424.796204)
		(end 398.361916 -421.144192)
		(width 0.14732)
		(layer "In13.Cu")
		(net "P5E_CPU0_PE2_RX_DN<7>")
	)
	(segment
		(start 398.357344 -249.212354)
		(end 394.583412 -225.746056)
		(width 0.14732)
		(layer "In13.Cu")
		(net "P5E_CPU0_PE2_RX_DN<7>")
	)
	(segment
		(start 378.578872 -211.494624)
		(end 378.05741 -211.710524)
		(width 0.14732)
		(layer "In13.Cu")
		(net "P5E_CPU0_PE2_RX_DN<7>")
	)
	(segment
		(start 401.443952 -339.421978)
		(end 394.278104 -308.944772)
		(width 0.14732)
		(layer "In13.Cu")
		(net "P5E_CPU0_PE2_RX_DN<7>")
	)
	(arc
		(start 375.46153 -217.07856)
		(mid 375.540749 -217.353245)
		(end 375.744232 -217.554048)
		(width 0.0889)
		(layer "In13.Cu")
		(net "P5E_CPU0_PE2_RX_DN<7>")
	)
	(arc
		(start 375.738136 -218.20632)
		(mid 375.461562 -218.692222)
		(end 375.738136 -219.178124)
		(width 0.0889)
		(layer "In13.Cu")
		(net "P5E_CPU0_PE2_RX_DN<7>")
	)
	(arc
		(start 375.753122 -219.18676)
		(mid 375.931719 -219.506038)
		(end 375.753122 -219.825316)
		(width 0.0889)
		(layer "In13.Cu")
		(net "P5E_CPU0_PE2_RX_DN<7>")
	)
	(arc
		(start 375.931684 -216.25052)
		(mid 375.884005 -216.43342)
		(end 375.753122 -216.569798)
		(width 0.0889)
		(layer "In13.Cu")
		(net "P5E_CPU0_PE2_RX_DN<7>")
	)
	(arc
		(start 375.753122 -217.559128)
		(mid 375.93184 -217.878406)
		(end 375.753122 -218.197684)
		(width 0.0889)
		(layer "In13.Cu")
		(net "P5E_CPU0_PE2_RX_DN<7>")
	)
	(arc
		(start 375.738136 -219.833952)
		(mid 375.535549 -220.040303)
		(end 375.46153 -220.319854)
		(width 0.0889)
		(layer "In13.Cu")
		(net "P5E_CPU0_PE2_RX_DN<7>")
	)
	(arc
		(start 375.744232 -221.458282)
		(mid 375.585744 -221.507215)
		(end 375.421652 -221.48292)
		(width 0.0889)
		(layer "In13.Cu")
		(net "P5E_CPU0_PE2_RX_DN<7>")
	)
	(arc
		(start 376.401076 -215.442038)
		(mid 376.352266 -215.621936)
		(end 376.222768 -215.755982)
		(width 0.0889)
		(layer "In13.Cu")
		(net "P5E_CPU0_PE2_RX_DN<7>")
	)
	(arc
		(start 376.213878 -215.761062)
		(mid 376.011055 -215.961293)
		(end 375.931684 -216.235026)
		(width 0.0889)
		(layer "In13.Cu")
		(net "P5E_CPU0_PE2_RX_DN<7>")
	)
	(arc
		(start 375.738136 -216.578434)
		(mid 375.535549 -216.784785)
		(end 375.46153 -217.064336)
		(width 0.0889)
		(layer "In13.Cu")
		(net "P5E_CPU0_PE2_RX_DN<7>")
	)
	(arc
		(start 375.753122 -220.814646)
		(mid 375.93184 -221.133924)
		(end 375.753122 -221.453202)
		(width 0.0889)
		(layer "In13.Cu")
		(net "P5E_CPU0_PE2_RX_DN<7>")
	)
	(arc
		(start 375.46153 -220.334078)
		(mid 375.540749 -220.608763)
		(end 375.744232 -220.809566)
		(width 0.0889)
		(layer "In13.Cu")
		(net "P5E_CPU0_PE2_RX_DN<7>")
	)
	(segment
		(start 374.147334 -220.855794)
		(end 374.147334 -220.320108)
		(width 0.13208)
		(layer "F.Cu")
		(net "P5E_CPU0_PE2_RX_DN<6>")
	)
	(segment
		(start 374.147334 -220.320108)
		(end 374.14708 -220.319854)
		(width 0.13208)
		(layer "F.Cu")
		(net "P5E_CPU0_PE2_RX_DN<6>")
	)
	(segment
		(start 374.800622 -216.577164)
		(end 374.79224 -216.58199)
		(width 0.0889)
		(layer "In13.Cu")
		(net "P5E_CPU0_PE2_RX_DN<6>")
	)
	(segment
		(start 402.43887 -410.705046)
		(end 402.43887 -406.051766)
		(width 0.14732)
		(layer "In13.Cu")
		(net "P5E_CPU0_PE2_RX_DN<6>")
	)
	(segment
		(start 389.902446 -211.805774)
		(end 389.822182 -211.72551)
		(width 0.14732)
		(layer "In13.Cu")
		(net "P5E_CPU0_PE2_RX_DN<6>")
	)
	(segment
		(start 376.16384 -214.267034)
		(end 375.606818 -214.824056)
		(width 0.0889)
		(layer "In13.Cu")
		(net "P5E_CPU0_PE2_RX_DN<6>")
	)
	(segment
		(start 376.601482 -211.849208)
		(end 376.35942 -212.433916)
		(width 0.14732)
		(layer "In13.Cu")
		(net "P5E_CPU0_PE2_RX_DN<6>")
	)
	(segment
		(start 400.190716 -434.719476)
		(end 400.066256 -434.595016)
		(width 0.14732)
		(layer "In13.Cu")
		(net "P5E_CPU0_PE2_RX_DN<6>")
	)
	(segment
		(start 375.462038 -215.174068)
		(end 375.462038 -215.423242)
		(width 0.0889)
		(layer "In13.Cu")
		(net "P5E_CPU0_PE2_RX_DN<6>")
	)
	(segment
		(start 395.242542 -308.603142)
		(end 399.438622 -253.360682)
		(width 0.14732)
		(layer "In13.Cu")
		(net "P5E_CPU0_PE2_RX_DN<6>")
	)
	(segment
		(start 374.800622 -219.832682)
		(end 374.79224 -219.837508)
		(width 0.0889)
		(layer "In13.Cu")
		(net "P5E_CPU0_PE2_RX_DN<6>")
	)
	(segment
		(start 374.813322 -219.825316)
		(end 374.804432 -219.830396)
		(width 0.0889)
		(layer "In13.Cu")
		(net "P5E_CPU0_PE2_RX_DN<6>")
	)
	(segment
		(start 401.680934 -414.020508)
		(end 402.43887 -410.705046)
		(width 0.14732)
		(layer "In13.Cu")
		(net "P5E_CPU0_PE2_RX_DN<6>")
	)
	(segment
		(start 374.804432 -217.554048)
		(end 374.813322 -217.559128)
		(width 0.0889)
		(layer "In13.Cu")
		(net "P5E_CPU0_PE2_RX_DN<6>")
	)
	(segment
		(start 401.09267 -404.705566)
		(end 401.09267 -400.487388)
		(width 0.14732)
		(layer "In13.Cu")
		(net "P5E_CPU0_PE2_RX_DN<6>")
	)
	(segment
		(start 402.480018 -339.529928)
		(end 402.467318 -339.475826)
		(width 0.14732)
		(layer "In13.Cu")
		(net "P5E_CPU0_PE2_RX_DN<6>")
	)
	(segment
		(start 399.290286 -248.893584)
		(end 395.533118 -225.532188)
		(width 0.14732)
		(layer "In13.Cu")
		(net "P5E_CPU0_PE2_RX_DN<6>")
	)
	(segment
		(start 402.43887 -406.051766)
		(end 401.09267 -404.705566)
		(width 0.14732)
		(layer "In13.Cu")
		(net "P5E_CPU0_PE2_RX_DN<6>")
	)
	(segment
		(start 376.401584 -213.20633)
		(end 376.401584 -213.693756)
		(width 0.0889)
		(layer "In13.Cu")
		(net "P5E_CPU0_PE2_RX_DN<6>")
	)
	(segment
		(start 389.821928 -211.72551)
		(end 389.768334 -211.671916)
		(width 0.14732)
		(layer "In13.Cu")
		(net "P5E_CPU0_PE2_RX_DN<6>")
	)
	(segment
		(start 395.533118 -225.532188)
		(end 392.20267 -214.106252)
		(width 0.14732)
		(layer "In13.Cu")
		(net "P5E_CPU0_PE2_RX_DN<6>")
	)
	(segment
		(start 400.070066 -353.566984)
		(end 402.480018 -339.529928)
		(width 0.14732)
		(layer "In13.Cu")
		(net "P5E_CPU0_PE2_RX_DN<6>")
	)
	(segment
		(start 401.032472 -418.853112)
		(end 401.10156 -418.421312)
		(width 0.14732)
		(layer "In13.Cu")
		(net "P5E_CPU0_PE2_RX_DN<6>")
	)
	(segment
		(start 400.794474 -397.787368)
		(end 399.463514 -368.670586)
		(width 0.14732)
		(layer "In13.Cu")
		(net "P5E_CPU0_PE2_RX_DN<6>")
	)
	(segment
		(start 375.462038 -215.423242)
		(end 375.46153 -215.44534)
		(width 0.0889)
		(layer "In13.Cu")
		(net "P5E_CPU0_PE2_RX_DN<6>")
	)
	(segment
		(start 399.463514 -368.670586)
		(end 400.070066 -353.566984)
		(width 0.14732)
		(layer "In13.Cu")
		(net "P5E_CPU0_PE2_RX_DN<6>")
	)
	(segment
		(start 399.438622 -253.360682)
		(end 399.438876 -253.360682)
		(width 0.14732)
		(layer "In13.Cu")
		(net "P5E_CPU0_PE2_RX_DN<6>")
	)
	(segment
		(start 400.889724 -418.95649)
		(end 400.88947 -418.956236)
		(width 0.14732)
		(layer "In13.Cu")
		(net "P5E_CPU0_PE2_RX_DN<6>")
	)
	(segment
		(start 401.09267 -400.487388)
		(end 400.794474 -397.787368)
		(width 0.14732)
		(layer "In13.Cu")
		(net "P5E_CPU0_PE2_RX_DN<6>")
	)
	(segment
		(start 400.750024 -434.289962)
		(end 400.32051 -434.719476)
		(width 0.14732)
		(layer "In13.Cu")
		(net "P5E_CPU0_PE2_RX_DN<6>")
	)
	(segment
		(start 374.805956 -219.182442)
		(end 374.813322 -219.18676)
		(width 0.0889)
		(layer "In13.Cu")
		(net "P5E_CPU0_PE2_RX_DN<6>")
	)
	(segment
		(start 374.991884 -216.240614)
		(end 374.991884 -216.25052)
		(width 0.0889)
		(layer "In13.Cu")
		(net "P5E_CPU0_PE2_RX_DN<6>")
	)
	(segment
		(start 376.35942 -212.433916)
		(end 376.35942 -213.142068)
		(width 0.14732)
		(layer "In13.Cu")
		(net "P5E_CPU0_PE2_RX_DN<6>")
	)
	(segment
		(start 402.467318 -339.475826)
		(end 395.242542 -308.603142)
		(width 0.14732)
		(layer "In13.Cu")
		(net "P5E_CPU0_PE2_RX_DN<6>")
	)
	(segment
		(start 389.822182 -211.72551)
		(end 389.821928 -211.72551)
		(width 0.14732)
		(layer "In13.Cu")
		(net "P5E_CPU0_PE2_RX_DN<6>")
	)
	(segment
		(start 374.80367 -219.181172)
		(end 374.804432 -219.18168)
		(width 0.0889)
		(layer "In13.Cu")
		(net "P5E_CPU0_PE2_RX_DN<6>")
	)
	(segment
		(start 400.066256 -434.595016)
		(end 400.066256 -424.092624)
		(width 0.14732)
		(layer "In13.Cu")
		(net "P5E_CPU0_PE2_RX_DN<6>")
	)
	(segment
		(start 399.439892 -253.34595)
		(end 399.439384 -253.330964)
		(width 0.14732)
		(layer "In13.Cu")
		(net "P5E_CPU0_PE2_RX_DN<6>")
	)
	(segment
		(start 375.606818 -214.824056)
		(end 375.462038 -215.174068)
		(width 0.0889)
		(layer "In13.Cu")
		(net "P5E_CPU0_PE2_RX_DN<6>")
	)
	(segment
		(start 376.35942 -213.142068)
		(end 376.35942 -213.164166)
		(width 0.0889)
		(layer "In13.Cu")
		(net "P5E_CPU0_PE2_RX_DN<6>")
	)
	(segment
		(start 374.52173 -217.064336)
		(end 374.52173 -217.071956)
		(width 0.0889)
		(layer "In13.Cu")
		(net "P5E_CPU0_PE2_RX_DN<6>")
	)
	(segment
		(start 374.798336 -219.178124)
		(end 374.80367 -219.181172)
		(width 0.0889)
		(layer "In13.Cu")
		(net "P5E_CPU0_PE2_RX_DN<6>")
	)
	(segment
		(start 374.804432 -219.830396)
		(end 374.800622 -219.832682)
		(width 0.0889)
		(layer "In13.Cu")
		(net "P5E_CPU0_PE2_RX_DN<6>")
	)
	(segment
		(start 392.20267 -214.106252)
		(end 389.902192 -211.805774)
		(width 0.14732)
		(layer "In13.Cu")
		(net "P5E_CPU0_PE2_RX_DN<6>")
	)
	(segment
		(start 374.804432 -216.574878)
		(end 374.800622 -216.577164)
		(width 0.0889)
		(layer "In13.Cu")
		(net "P5E_CPU0_PE2_RX_DN<6>")
	)
	(segment
		(start 400.32051 -434.719476)
		(end 400.190716 -434.719476)
		(width 0.14732)
		(layer "In13.Cu")
		(net "P5E_CPU0_PE2_RX_DN<6>")
	)
	(segment
		(start 400.066256 -424.092624)
		(end 400.889724 -418.95649)
		(width 0.14732)
		(layer "In13.Cu")
		(net "P5E_CPU0_PE2_RX_DN<6>")
	)
	(segment
		(start 374.813322 -216.569798)
		(end 374.804432 -216.574878)
		(width 0.0889)
		(layer "In13.Cu")
		(net "P5E_CPU0_PE2_RX_DN<6>")
	)
	(segment
		(start 376.35942 -213.164166)
		(end 376.401584 -213.20633)
		(width 0.0889)
		(layer "In13.Cu")
		(net "P5E_CPU0_PE2_RX_DN<6>")
	)
	(segment
		(start 374.381776 -220.6117)
		(end 374.303544 -220.590872)
		(width 0.0889)
		(layer "In13.Cu")
		(net "P5E_CPU0_PE2_RX_DN<6>")
	)
	(segment
		(start 374.303544 -220.590872)
		(end 374.14708 -220.319854)
		(width 0.0889)
		(layer "In13.Cu")
		(net "P5E_CPU0_PE2_RX_DN<6>")
	)
	(segment
		(start 389.902192 -211.805774)
		(end 389.902446 -211.805774)
		(width 0.14732)
		(layer "In13.Cu")
		(net "P5E_CPU0_PE2_RX_DN<6>")
	)
	(segment
		(start 376.401584 -213.693756)
		(end 376.16384 -214.267034)
		(width 0.0889)
		(layer "In13.Cu")
		(net "P5E_CPU0_PE2_RX_DN<6>")
	)
	(segment
		(start 399.439384 -253.33071)
		(end 399.290286 -248.893584)
		(width 0.14732)
		(layer "In13.Cu")
		(net "P5E_CPU0_PE2_RX_DN<6>")
	)
	(segment
		(start 389.768334 -211.671916)
		(end 389.33882 -211.493862)
		(width 0.14732)
		(layer "In13.Cu")
		(net "P5E_CPU0_PE2_RX_DN<6>")
	)
	(segment
		(start 401.10156 -418.421312)
		(end 400.998436 -418.278818)
		(width 0.14732)
		(layer "In13.Cu")
		(net "P5E_CPU0_PE2_RX_DN<6>")
	)
	(segment
		(start 389.33882 -211.493862)
		(end 383.577084 -210.348068)
		(width 0.14732)
		(layer "In13.Cu")
		(net "P5E_CPU0_PE2_RX_DN<6>")
	)
	(segment
		(start 374.804432 -219.18168)
		(end 374.805956 -219.182442)
		(width 0.0889)
		(layer "In13.Cu")
		(net "P5E_CPU0_PE2_RX_DN<6>")
	)
	(segment
		(start 400.998436 -418.278818)
		(end 401.680934 -414.020508)
		(width 0.14732)
		(layer "In13.Cu")
		(net "P5E_CPU0_PE2_RX_DN<6>")
	)
	(segment
		(start 377.57735 -210.87334)
		(end 376.601482 -211.849208)
		(width 0.14732)
		(layer "In13.Cu")
		(net "P5E_CPU0_PE2_RX_DN<6>")
	)
	(segment
		(start 399.439384 -253.330964)
		(end 399.439384 -253.33071)
		(width 0.14732)
		(layer "In13.Cu")
		(net "P5E_CPU0_PE2_RX_DN<6>")
	)
	(segment
		(start 374.813322 -218.197684)
		(end 374.798336 -218.20632)
		(width 0.0889)
		(layer "In13.Cu")
		(net "P5E_CPU0_PE2_RX_DN<6>")
	)
	(segment
		(start 399.438876 -253.360682)
		(end 399.439892 -253.34595)
		(width 0.14732)
		(layer "In13.Cu")
		(net "P5E_CPU0_PE2_RX_DN<6>")
	)
	(segment
		(start 383.577084 -210.348068)
		(end 378.845826 -210.348068)
		(width 0.14732)
		(layer "In13.Cu")
		(net "P5E_CPU0_PE2_RX_DN<6>")
	)
	(segment
		(start 378.845826 -210.348068)
		(end 377.57735 -210.87334)
		(width 0.14732)
		(layer "In13.Cu")
		(net "P5E_CPU0_PE2_RX_DN<6>")
	)
	(segment
		(start 400.88947 -418.956236)
		(end 401.032472 -418.853112)
		(width 0.14732)
		(layer "In13.Cu")
		(net "P5E_CPU0_PE2_RX_DN<6>")
	)
	(arc
		(start 374.79224 -216.58199)
		(mid 374.594012 -216.787838)
		(end 374.52173 -217.064336)
		(width 0.0889)
		(layer "In13.Cu")
		(net "P5E_CPU0_PE2_RX_DN<6>")
	)
	(arc
		(start 375.46153 -215.44534)
		(mid 375.40926 -215.627705)
		(end 375.274332 -215.761062)
		(width 0.0889)
		(layer "In13.Cu")
		(net "P5E_CPU0_PE2_RX_DN<6>")
	)
	(arc
		(start 375.274332 -215.761062)
		(mid 375.069997 -215.963667)
		(end 374.991884 -216.240614)
		(width 0.0889)
		(layer "In13.Cu")
		(net "P5E_CPU0_PE2_RX_DN<6>")
	)
	(arc
		(start 374.79224 -219.837508)
		(mid 374.594012 -220.043356)
		(end 374.52173 -220.319854)
		(width 0.0889)
		(layer "In13.Cu")
		(net "P5E_CPU0_PE2_RX_DN<6>")
	)
	(arc
		(start 374.52173 -217.071956)
		(mid 374.599359 -217.350369)
		(end 374.804432 -217.554048)
		(width 0.0889)
		(layer "In13.Cu")
		(net "P5E_CPU0_PE2_RX_DN<6>")
	)
	(arc
		(start 374.813322 -219.18676)
		(mid 374.991919 -219.506038)
		(end 374.813322 -219.825316)
		(width 0.0889)
		(layer "In13.Cu")
		(net "P5E_CPU0_PE2_RX_DN<6>")
	)
	(arc
		(start 374.52173 -220.319854)
		(mid 374.48487 -220.481651)
		(end 374.381776 -220.6117)
		(width 0.0889)
		(layer "In13.Cu")
		(net "P5E_CPU0_PE2_RX_DN<6>")
	)
	(arc
		(start 374.991884 -216.25052)
		(mid 374.944205 -216.43342)
		(end 374.813322 -216.569798)
		(width 0.0889)
		(layer "In13.Cu")
		(net "P5E_CPU0_PE2_RX_DN<6>")
	)
	(arc
		(start 374.813322 -217.559128)
		(mid 374.991798 -217.878406)
		(end 374.813322 -218.197684)
		(width 0.0889)
		(layer "In13.Cu")
		(net "P5E_CPU0_PE2_RX_DN<6>")
	)
	(arc
		(start 374.798336 -218.20632)
		(mid 374.521762 -218.692222)
		(end 374.798336 -219.178124)
		(width 0.0889)
		(layer "In13.Cu")
		(net "P5E_CPU0_PE2_RX_DN<6>")
	)
	(segment
		(start 373.67718 -221.134178)
		(end 373.677434 -221.133924)
		(width 0.13208)
		(layer "F.Cu")
		(net "P5E_CPU0_PE2_RX_DN<5>")
	)
	(segment
		(start 373.67718 -221.669864)
		(end 373.67718 -221.134178)
		(width 0.13208)
		(layer "F.Cu")
		(net "P5E_CPU0_PE2_RX_DN<5>")
	)
	(segment
		(start 405.50211 -410.644848)
		(end 405.50211 -406.051766)
		(width 0.14732)
		(layer "In13.Cu")
		(net "P5E_CPU0_PE2_RX_DN<5>")
	)
	(segment
		(start 373.866156 -216.574116)
		(end 373.864632 -216.574878)
		(width 0.0889)
		(layer "In13.Cu")
		(net "P5E_CPU0_PE2_RX_DN<5>")
	)
	(segment
		(start 375.823734 -211.191856)
		(end 375.418858 -212.169502)
		(width 0.14732)
		(layer "In13.Cu")
		(net "P5E_CPU0_PE2_RX_DN<5>")
	)
	(segment
		(start 403.026372 -421.298116)
		(end 403.12721 -420.872666)
		(width 0.14732)
		(layer "In13.Cu")
		(net "P5E_CPU0_PE2_RX_DN<5>")
	)
	(segment
		(start 403.44598 -339.559392)
		(end 396.19809 -308.477158)
		(width 0.14732)
		(layer "In13.Cu")
		(net "P5E_CPU0_PE2_RX_DN<5>")
	)
	(segment
		(start 373.873522 -216.569798)
		(end 373.866156 -216.574116)
		(width 0.0889)
		(layer "In13.Cu")
		(net "P5E_CPU0_PE2_RX_DN<5>")
	)
	(segment
		(start 373.858536 -219.178124)
		(end 373.86387 -219.181172)
		(width 0.0889)
		(layer "In13.Cu")
		(net "P5E_CPU0_PE2_RX_DN<5>")
	)
	(segment
		(start 403.035008 -420.722806)
		(end 404.72741 -413.594296)
		(width 0.14732)
		(layer "In13.Cu")
		(net "P5E_CPU0_PE2_RX_DN<5>")
	)
	(segment
		(start 378.61875 -209.418428)
		(end 376.87504 -210.14055)
		(width 0.14732)
		(layer "In13.Cu")
		(net "P5E_CPU0_PE2_RX_DN<5>")
	)
	(segment
		(start 393.051538 -213.60384)
		(end 390.355074 -210.907122)
		(width 0.14732)
		(layer "In13.Cu")
		(net "P5E_CPU0_PE2_RX_DN<5>")
	)
	(segment
		(start 373.873522 -218.197684)
		(end 373.858536 -218.20632)
		(width 0.0889)
		(layer "In13.Cu")
		(net "P5E_CPU0_PE2_RX_DN<5>")
	)
	(segment
		(start 402.320506 -433.719478)
		(end 402.169376 -433.719478)
		(width 0.14732)
		(layer "In13.Cu")
		(net "P5E_CPU0_PE2_RX_DN<5>")
	)
	(segment
		(start 373.861838 -219.83192)
		(end 373.858536 -219.833952)
		(width 0.0889)
		(layer "In13.Cu")
		(net "P5E_CPU0_PE2_RX_DN<5>")
	)
	(segment
		(start 396.19809 -308.477158)
		(end 400.372326 -253.42723)
		(width 0.14732)
		(layer "In13.Cu")
		(net "P5E_CPU0_PE2_RX_DN<5>")
	)
	(segment
		(start 373.873522 -219.825316)
		(end 373.866156 -219.829634)
		(width 0.0889)
		(layer "In13.Cu")
		(net "P5E_CPU0_PE2_RX_DN<5>")
	)
	(segment
		(start 373.864632 -217.554048)
		(end 373.873522 -217.559128)
		(width 0.0889)
		(layer "In13.Cu")
		(net "P5E_CPU0_PE2_RX_DN<5>")
	)
	(segment
		(start 374.521984 -215.43645)
		(end 374.52173 -215.436704)
		(width 0.0889)
		(layer "In13.Cu")
		(net "P5E_CPU0_PE2_RX_DN<5>")
	)
	(segment
		(start 389.485378 -210.54695)
		(end 383.811272 -209.418428)
		(width 0.14732)
		(layer "In13.Cu")
		(net "P5E_CPU0_PE2_RX_DN<5>")
	)
	(segment
		(start 374.74144 -214.739728)
		(end 374.521984 -215.269318)
		(width 0.0889)
		(layer "In13.Cu")
		(net "P5E_CPU0_PE2_RX_DN<5>")
	)
	(segment
		(start 373.873522 -221.453202)
		(end 373.866156 -221.45752)
		(width 0.0889)
		(layer "In13.Cu")
		(net "P5E_CPU0_PE2_RX_DN<5>")
	)
	(segment
		(start 375.34723 -214.133684)
		(end 374.74144 -214.739728)
		(width 0.0889)
		(layer "In13.Cu")
		(net "P5E_CPU0_PE2_RX_DN<5>")
	)
	(segment
		(start 402.876258 -421.390318)
		(end 403.026372 -421.298116)
		(width 0.14732)
		(layer "In13.Cu")
		(net "P5E_CPU0_PE2_RX_DN<5>")
	)
	(segment
		(start 402.066252 -424.802046)
		(end 402.876258 -421.39108)
		(width 0.14732)
		(layer "In13.Cu")
		(net "P5E_CPU0_PE2_RX_DN<5>")
	)
	(segment
		(start 373.866156 -219.829634)
		(end 373.864632 -219.830396)
		(width 0.0889)
		(layer "In13.Cu")
		(net "P5E_CPU0_PE2_RX_DN<5>")
	)
	(segment
		(start 400.373088 -253.397512)
		(end 400.373088 -253.397258)
		(width 0.14732)
		(layer "In13.Cu")
		(net "P5E_CPU0_PE2_RX_DN<5>")
	)
	(segment
		(start 373.864632 -219.830396)
		(end 373.861838 -219.83192)
		(width 0.0889)
		(layer "In13.Cu")
		(net "P5E_CPU0_PE2_RX_DN<5>")
	)
	(segment
		(start 400.797776 -368.777266)
		(end 401.291806 -351.97923)
		(width 0.14732)
		(layer "In13.Cu")
		(net "P5E_CPU0_PE2_RX_DN<5>")
	)
	(segment
		(start 375.461022 -213.859364)
		(end 375.34723 -214.133684)
		(width 0.0889)
		(layer "In13.Cu")
		(net "P5E_CPU0_PE2_RX_DN<5>")
	)
	(segment
		(start 373.866156 -221.45752)
		(end 373.864632 -221.458282)
		(width 0.0889)
		(layer "In13.Cu")
		(net "P5E_CPU0_PE2_RX_DN<5>")
	)
	(segment
		(start 402.169376 -433.719478)
		(end 402.066252 -433.616354)
		(width 0.14732)
		(layer "In13.Cu")
		(net "P5E_CPU0_PE2_RX_DN<5>")
	)
	(segment
		(start 375.461022 -213.20633)
		(end 375.461022 -213.859364)
		(width 0.0889)
		(layer "In13.Cu")
		(net "P5E_CPU0_PE2_RX_DN<5>")
	)
	(segment
		(start 404.15591 -404.705566)
		(end 404.15591 -400.477482)
		(width 0.14732)
		(layer "In13.Cu")
		(net "P5E_CPU0_PE2_RX_DN<5>")
	)
	(segment
		(start 374.521984 -215.269318)
		(end 374.521984 -215.43645)
		(width 0.0889)
		(layer "In13.Cu")
		(net "P5E_CPU0_PE2_RX_DN<5>")
	)
	(segment
		(start 375.418858 -213.164166)
		(end 375.461022 -213.20633)
		(width 0.0889)
		(layer "In13.Cu")
		(net "P5E_CPU0_PE2_RX_DN<5>")
	)
	(segment
		(start 402.75002 -433.289964)
		(end 402.320506 -433.719478)
		(width 0.14732)
		(layer "In13.Cu")
		(net "P5E_CPU0_PE2_RX_DN<5>")
	)
	(segment
		(start 374.052084 -216.235026)
		(end 374.052084 -216.25052)
		(width 0.0889)
		(layer "In13.Cu")
		(net "P5E_CPU0_PE2_RX_DN<5>")
	)
	(segment
		(start 373.864632 -216.574878)
		(end 373.858536 -216.578434)
		(width 0.0889)
		(layer "In13.Cu")
		(net "P5E_CPU0_PE2_RX_DN<5>")
	)
	(segment
		(start 402.066252 -433.616354)
		(end 402.066252 -424.802046)
		(width 0.14732)
		(layer "In13.Cu")
		(net "P5E_CPU0_PE2_RX_DN<5>")
	)
	(segment
		(start 373.86387 -219.181172)
		(end 373.864632 -219.18168)
		(width 0.0889)
		(layer "In13.Cu")
		(net "P5E_CPU0_PE2_RX_DN<5>")
	)
	(segment
		(start 373.52097 -221.404942)
		(end 373.677434 -221.133924)
		(width 0.0889)
		(layer "In13.Cu")
		(net "P5E_CPU0_PE2_RX_DN<5>")
	)
	(segment
		(start 376.87504 -210.14055)
		(end 375.823734 -211.191856)
		(width 0.14732)
		(layer "In13.Cu")
		(net "P5E_CPU0_PE2_RX_DN<5>")
	)
	(segment
		(start 400.373596 -253.412498)
		(end 400.373088 -253.397512)
		(width 0.14732)
		(layer "In13.Cu")
		(net "P5E_CPU0_PE2_RX_DN<5>")
	)
	(segment
		(start 373.58193 -220.319854)
		(end 373.58193 -220.334078)
		(width 0.0889)
		(layer "In13.Cu")
		(net "P5E_CPU0_PE2_RX_DN<5>")
	)
	(segment
		(start 390.355074 -210.907122)
		(end 389.485378 -210.54695)
		(width 0.14732)
		(layer "In13.Cu")
		(net "P5E_CPU0_PE2_RX_DN<5>")
	)
	(segment
		(start 404.15591 -400.477482)
		(end 403.656038 -397.745458)
		(width 0.14732)
		(layer "In13.Cu")
		(net "P5E_CPU0_PE2_RX_DN<5>")
	)
	(segment
		(start 373.542052 -221.48292)
		(end 373.52097 -221.404942)
		(width 0.0889)
		(layer "In13.Cu")
		(net "P5E_CPU0_PE2_RX_DN<5>")
	)
	(segment
		(start 375.418858 -213.142068)
		(end 375.418858 -213.164166)
		(width 0.0889)
		(layer "In13.Cu")
		(net "P5E_CPU0_PE2_RX_DN<5>")
	)
	(segment
		(start 374.343168 -215.755982)
		(end 374.334278 -215.761062)
		(width 0.0889)
		(layer "In13.Cu")
		(net "P5E_CPU0_PE2_RX_DN<5>")
	)
	(segment
		(start 400.37258 -253.42723)
		(end 400.373596 -253.412498)
		(width 0.14732)
		(layer "In13.Cu")
		(net "P5E_CPU0_PE2_RX_DN<5>")
	)
	(segment
		(start 403.656038 -397.745458)
		(end 400.797776 -368.777266)
		(width 0.14732)
		(layer "In13.Cu")
		(net "P5E_CPU0_PE2_RX_DN<5>")
	)
	(segment
		(start 375.418858 -212.169502)
		(end 375.418858 -213.142068)
		(width 0.14732)
		(layer "In13.Cu")
		(net "P5E_CPU0_PE2_RX_DN<5>")
	)
	(segment
		(start 396.467076 -225.321876)
		(end 393.051538 -213.60384)
		(width 0.14732)
		(layer "In13.Cu")
		(net "P5E_CPU0_PE2_RX_DN<5>")
	)
	(segment
		(start 404.72741 -413.594296)
		(end 405.50211 -410.644848)
		(width 0.14732)
		(layer "In13.Cu")
		(net "P5E_CPU0_PE2_RX_DN<5>")
	)
	(segment
		(start 400.212052 -248.607834)
		(end 396.467076 -225.321876)
		(width 0.14732)
		(layer "In13.Cu")
		(net "P5E_CPU0_PE2_RX_DN<5>")
	)
	(segment
		(start 373.866156 -219.182442)
		(end 373.873522 -219.18676)
		(width 0.0889)
		(layer "In13.Cu")
		(net "P5E_CPU0_PE2_RX_DN<5>")
	)
	(segment
		(start 403.12721 -420.872666)
		(end 403.035008 -420.722806)
		(width 0.14732)
		(layer "In13.Cu")
		(net "P5E_CPU0_PE2_RX_DN<5>")
	)
	(segment
		(start 373.864632 -219.18168)
		(end 373.866156 -219.182442)
		(width 0.0889)
		(layer "In13.Cu")
		(net "P5E_CPU0_PE2_RX_DN<5>")
	)
	(segment
		(start 400.373088 -253.397258)
		(end 400.212052 -248.607834)
		(width 0.14732)
		(layer "In13.Cu")
		(net "P5E_CPU0_PE2_RX_DN<5>")
	)
	(segment
		(start 373.58193 -217.064336)
		(end 373.58193 -217.07856)
		(width 0.0889)
		(layer "In13.Cu")
		(net "P5E_CPU0_PE2_RX_DN<5>")
	)
	(segment
		(start 405.50211 -406.051766)
		(end 404.15591 -404.705566)
		(width 0.14732)
		(layer "In13.Cu")
		(net "P5E_CPU0_PE2_RX_DN<5>")
	)
	(segment
		(start 401.291806 -351.97923)
		(end 403.44598 -339.559392)
		(width 0.14732)
		(layer "In13.Cu")
		(net "P5E_CPU0_PE2_RX_DN<5>")
	)
	(segment
		(start 373.864632 -220.809566)
		(end 373.873522 -220.814646)
		(width 0.0889)
		(layer "In13.Cu")
		(net "P5E_CPU0_PE2_RX_DN<5>")
	)
	(segment
		(start 400.372326 -253.42723)
		(end 400.37258 -253.42723)
		(width 0.14732)
		(layer "In13.Cu")
		(net "P5E_CPU0_PE2_RX_DN<5>")
	)
	(segment
		(start 383.811272 -209.418428)
		(end 378.61875 -209.418428)
		(width 0.14732)
		(layer "In13.Cu")
		(net "P5E_CPU0_PE2_RX_DN<5>")
	)
	(segment
		(start 402.876258 -421.39108)
		(end 402.876258 -421.390318)
		(width 0.14732)
		(layer "In13.Cu")
		(net "P5E_CPU0_PE2_RX_DN<5>")
	)
	(arc
		(start 374.052084 -216.25052)
		(mid 374.004405 -216.43342)
		(end 373.873522 -216.569798)
		(width 0.0889)
		(layer "In13.Cu")
		(net "P5E_CPU0_PE2_RX_DN<5>")
	)
	(arc
		(start 373.58193 -217.07856)
		(mid 373.661149 -217.353245)
		(end 373.864632 -217.554048)
		(width 0.0889)
		(layer "In13.Cu")
		(net "P5E_CPU0_PE2_RX_DN<5>")
	)
	(arc
		(start 373.858536 -219.833952)
		(mid 373.655949 -220.040303)
		(end 373.58193 -220.319854)
		(width 0.0889)
		(layer "In13.Cu")
		(net "P5E_CPU0_PE2_RX_DN<5>")
	)
	(arc
		(start 373.858536 -218.20632)
		(mid 373.581962 -218.692222)
		(end 373.858536 -219.178124)
		(width 0.0889)
		(layer "In13.Cu")
		(net "P5E_CPU0_PE2_RX_DN<5>")
	)
	(arc
		(start 374.334278 -215.761062)
		(mid 374.131455 -215.961293)
		(end 374.052084 -216.235026)
		(width 0.0889)
		(layer "In13.Cu")
		(net "P5E_CPU0_PE2_RX_DN<5>")
	)
	(arc
		(start 373.873522 -219.18676)
		(mid 374.052119 -219.506038)
		(end 373.873522 -219.825316)
		(width 0.0889)
		(layer "In13.Cu")
		(net "P5E_CPU0_PE2_RX_DN<5>")
	)
	(arc
		(start 374.52173 -215.436704)
		(mid 374.474051 -215.619604)
		(end 374.343168 -215.755982)
		(width 0.0889)
		(layer "In13.Cu")
		(net "P5E_CPU0_PE2_RX_DN<5>")
	)
	(arc
		(start 373.873522 -217.559128)
		(mid 374.05224 -217.878406)
		(end 373.873522 -218.197684)
		(width 0.0889)
		(layer "In13.Cu")
		(net "P5E_CPU0_PE2_RX_DN<5>")
	)
	(arc
		(start 373.858536 -216.578434)
		(mid 373.655949 -216.784785)
		(end 373.58193 -217.064336)
		(width 0.0889)
		(layer "In13.Cu")
		(net "P5E_CPU0_PE2_RX_DN<5>")
	)
	(arc
		(start 373.864632 -221.458282)
		(mid 373.706144 -221.507215)
		(end 373.542052 -221.48292)
		(width 0.0889)
		(layer "In13.Cu")
		(net "P5E_CPU0_PE2_RX_DN<5>")
	)
	(arc
		(start 373.873522 -220.814646)
		(mid 374.05224 -221.133924)
		(end 373.873522 -221.453202)
		(width 0.0889)
		(layer "In13.Cu")
		(net "P5E_CPU0_PE2_RX_DN<5>")
	)
	(arc
		(start 373.58193 -220.334078)
		(mid 373.661149 -220.608763)
		(end 373.864632 -220.809566)
		(width 0.0889)
		(layer "In13.Cu")
		(net "P5E_CPU0_PE2_RX_DN<5>")
	)
	(segment
		(start 372.267734 -220.855794)
		(end 372.267734 -220.320108)
		(width 0.13208)
		(layer "F.Cu")
		(net "P5E_CPU0_PE2_RX_DN<4>")
	)
	(segment
		(start 372.267734 -220.320108)
		(end 372.26748 -220.319854)
		(width 0.13208)
		(layer "F.Cu")
		(net "P5E_CPU0_PE2_RX_DN<4>")
	)
	(segment
		(start 402.55698 -371.477794)
		(end 402.218652 -366.271048)
		(width 0.14732)
		(layer "In13.Cu")
		(net "P5E_CPU0_PE2_RX_DN<4>")
	)
	(segment
		(start 390.835642 -209.985102)
		(end 389.650732 -209.494374)
		(width 0.14732)
		(layer "In13.Cu")
		(net "P5E_CPU0_PE2_RX_DN<4>")
	)
	(segment
		(start 372.502176 -220.6117)
		(end 372.423944 -220.590872)
		(width 0.0889)
		(layer "In13.Cu")
		(net "P5E_CPU0_PE2_RX_DN<4>")
	)
	(segment
		(start 372.64213 -217.064336)
		(end 372.64213 -217.071956)
		(width 0.0889)
		(layer "In13.Cu")
		(net "P5E_CPU0_PE2_RX_DN<4>")
	)
	(segment
		(start 406.585166 -397.728186)
		(end 402.55698 -371.477794)
		(width 0.14732)
		(layer "In13.Cu")
		(net "P5E_CPU0_PE2_RX_DN<4>")
	)
	(segment
		(start 373.582438 -215.269064)
		(end 373.582438 -215.423242)
		(width 0.0889)
		(layer "In13.Cu")
		(net "P5E_CPU0_PE2_RX_DN<4>")
	)
	(segment
		(start 404.066248 -434.595016)
		(end 404.066248 -424.626532)
		(width 0.14732)
		(layer "In13.Cu")
		(net "P5E_CPU0_PE2_RX_DN<4>")
	)
	(segment
		(start 401.303998 -253.456186)
		(end 401.305014 -253.441454)
		(width 0.14732)
		(layer "In13.Cu")
		(net "P5E_CPU0_PE2_RX_DN<4>")
	)
	(segment
		(start 408.56535 -410.996892)
		(end 408.56535 -406.051766)
		(width 0.14732)
		(layer "In13.Cu")
		(net "P5E_CPU0_PE2_RX_DN<4>")
	)
	(segment
		(start 404.940516 -421.84447)
		(end 407.579068 -413.445452)
		(width 0.14732)
		(layer "In13.Cu")
		(net "P5E_CPU0_PE2_RX_DN<4>")
	)
	(segment
		(start 372.921022 -219.832682)
		(end 372.91264 -219.837508)
		(width 0.0889)
		(layer "In13.Cu")
		(net "P5E_CPU0_PE2_RX_DN<4>")
	)
	(segment
		(start 372.924832 -216.574878)
		(end 372.921022 -216.577164)
		(width 0.0889)
		(layer "In13.Cu")
		(net "P5E_CPU0_PE2_RX_DN<4>")
	)
	(segment
		(start 373.112284 -216.240614)
		(end 373.112284 -216.25052)
		(width 0.0889)
		(layer "In13.Cu")
		(net "P5E_CPU0_PE2_RX_DN<4>")
	)
	(segment
		(start 397.64462 -225.18624)
		(end 394.208762 -213.358984)
		(width 0.14732)
		(layer "In13.Cu")
		(net "P5E_CPU0_PE2_RX_DN<4>")
	)
	(segment
		(start 374.521984 -213.20633)
		(end 374.521984 -213.852506)
		(width 0.0889)
		(layer "In13.Cu")
		(net "P5E_CPU0_PE2_RX_DN<4>")
	)
	(segment
		(start 405.031702 -422.019476)
		(end 404.940516 -421.84447)
		(width 0.14732)
		(layer "In13.Cu")
		(net "P5E_CPU0_PE2_RX_DN<4>")
	)
	(segment
		(start 401.305014 -253.441454)
		(end 401.13204 -248.29135)
		(width 0.14732)
		(layer "In13.Cu")
		(net "P5E_CPU0_PE2_RX_DN<4>")
	)
	(segment
		(start 397.170656 -308.15534)
		(end 401.303744 -253.456186)
		(width 0.14732)
		(layer "In13.Cu")
		(net "P5E_CPU0_PE2_RX_DN<4>")
	)
	(segment
		(start 389.650732 -209.494374)
		(end 384.59537 -208.488788)
		(width 0.14732)
		(layer "In13.Cu")
		(net "P5E_CPU0_PE2_RX_DN<4>")
	)
	(segment
		(start 372.92407 -219.181172)
		(end 372.924832 -219.18168)
		(width 0.0889)
		(layer "In13.Cu")
		(net "P5E_CPU0_PE2_RX_DN<4>")
	)
	(segment
		(start 372.924832 -219.830396)
		(end 372.921022 -219.832682)
		(width 0.0889)
		(layer "In13.Cu")
		(net "P5E_CPU0_PE2_RX_DN<4>")
	)
	(segment
		(start 372.933722 -218.197684)
		(end 372.926356 -218.202002)
		(width 0.0889)
		(layer "In13.Cu")
		(net "P5E_CPU0_PE2_RX_DN<4>")
	)
	(segment
		(start 407.21915 -400.471132)
		(end 406.585166 -397.728186)
		(width 0.14732)
		(layer "In13.Cu")
		(net "P5E_CPU0_PE2_RX_DN<4>")
	)
	(segment
		(start 372.918736 -219.178124)
		(end 372.92407 -219.181172)
		(width 0.0889)
		(layer "In13.Cu")
		(net "P5E_CPU0_PE2_RX_DN<4>")
	)
	(segment
		(start 404.497032 -339.585554)
		(end 397.170656 -308.15534)
		(width 0.14732)
		(layer "In13.Cu")
		(net "P5E_CPU0_PE2_RX_DN<4>")
	)
	(segment
		(start 402.58492 -350.198944)
		(end 404.497032 -339.585554)
		(width 0.14732)
		(layer "In13.Cu")
		(net "P5E_CPU0_PE2_RX_DN<4>")
	)
	(segment
		(start 404.921466 -422.371012)
		(end 405.031702 -422.019476)
		(width 0.14732)
		(layer "In13.Cu")
		(net "P5E_CPU0_PE2_RX_DN<4>")
	)
	(segment
		(start 372.926356 -219.182442)
		(end 372.933722 -219.18676)
		(width 0.0889)
		(layer "In13.Cu")
		(net "P5E_CPU0_PE2_RX_DN<4>")
	)
	(segment
		(start 372.933722 -219.825316)
		(end 372.924832 -219.830396)
		(width 0.0889)
		(layer "In13.Cu")
		(net "P5E_CPU0_PE2_RX_DN<4>")
	)
	(segment
		(start 372.924832 -219.18168)
		(end 372.926356 -219.182442)
		(width 0.0889)
		(layer "In13.Cu")
		(net "P5E_CPU0_PE2_RX_DN<4>")
	)
	(segment
		(start 372.926356 -218.202002)
		(end 372.918736 -218.20632)
		(width 0.0889)
		(layer "In13.Cu")
		(net "P5E_CPU0_PE2_RX_DN<4>")
	)
	(segment
		(start 407.579068 -413.445452)
		(end 408.56535 -410.996892)
		(width 0.14732)
		(layer "In13.Cu")
		(net "P5E_CPU0_PE2_RX_DN<4>")
	)
	(segment
		(start 404.190708 -434.719476)
		(end 404.066248 -434.595016)
		(width 0.14732)
		(layer "In13.Cu")
		(net "P5E_CPU0_PE2_RX_DN<4>")
	)
	(segment
		(start 372.933722 -216.569798)
		(end 372.924832 -216.574878)
		(width 0.0889)
		(layer "In13.Cu")
		(net "P5E_CPU0_PE2_RX_DN<4>")
	)
	(segment
		(start 394.208762 -213.358984)
		(end 390.835642 -209.985102)
		(width 0.14732)
		(layer "In13.Cu")
		(net "P5E_CPU0_PE2_RX_DN<4>")
	)
	(segment
		(start 373.726456 -214.921592)
		(end 373.582438 -215.269064)
		(width 0.0889)
		(layer "In13.Cu")
		(net "P5E_CPU0_PE2_RX_DN<4>")
	)
	(segment
		(start 384.59537 -208.488788)
		(end 378.407168 -208.488788)
		(width 0.14732)
		(layer "In13.Cu")
		(net "P5E_CPU0_PE2_RX_DN<4>")
	)
	(segment
		(start 372.924832 -217.554048)
		(end 372.933722 -217.559128)
		(width 0.0889)
		(layer "In13.Cu")
		(net "P5E_CPU0_PE2_RX_DN<4>")
	)
	(segment
		(start 401.303744 -253.456186)
		(end 401.303998 -253.456186)
		(width 0.14732)
		(layer "In13.Cu")
		(net "P5E_CPU0_PE2_RX_DN<4>")
	)
	(segment
		(start 404.066248 -424.626532)
		(end 404.745952 -422.46296)
		(width 0.14732)
		(layer "In13.Cu")
		(net "P5E_CPU0_PE2_RX_DN<4>")
	)
	(segment
		(start 404.320502 -434.719476)
		(end 404.190708 -434.719476)
		(width 0.14732)
		(layer "In13.Cu")
		(net "P5E_CPU0_PE2_RX_DN<4>")
	)
	(segment
		(start 374.328182 -214.319612)
		(end 373.726456 -214.921592)
		(width 0.0889)
		(layer "In13.Cu")
		(net "P5E_CPU0_PE2_RX_DN<4>")
	)
	(segment
		(start 402.218652 -366.271048)
		(end 402.58492 -350.198944)
		(width 0.14732)
		(layer "In13.Cu")
		(net "P5E_CPU0_PE2_RX_DN<4>")
	)
	(segment
		(start 408.56535 -406.051766)
		(end 407.21915 -404.705566)
		(width 0.14732)
		(layer "In13.Cu")
		(net "P5E_CPU0_PE2_RX_DN<4>")
	)
	(segment
		(start 374.47982 -211.905596)
		(end 374.47982 -213.142068)
		(width 0.14732)
		(layer "In13.Cu")
		(net "P5E_CPU0_PE2_RX_DN<4>")
	)
	(segment
		(start 375.012966 -210.618324)
		(end 374.47982 -211.905596)
		(width 0.14732)
		(layer "In13.Cu")
		(net "P5E_CPU0_PE2_RX_DN<4>")
	)
	(segment
		(start 401.13204 -248.29135)
		(end 397.64462 -225.18624)
		(width 0.14732)
		(layer "In13.Cu")
		(net "P5E_CPU0_PE2_RX_DN<4>")
	)
	(segment
		(start 404.750016 -434.289962)
		(end 404.320502 -434.719476)
		(width 0.14732)
		(layer "In13.Cu")
		(net "P5E_CPU0_PE2_RX_DN<4>")
	)
	(segment
		(start 407.21915 -404.705566)
		(end 407.21915 -400.471132)
		(width 0.14732)
		(layer "In13.Cu")
		(net "P5E_CPU0_PE2_RX_DN<4>")
	)
	(segment
		(start 374.47982 -213.142068)
		(end 374.47982 -213.164166)
		(width 0.0889)
		(layer "In13.Cu")
		(net "P5E_CPU0_PE2_RX_DN<4>")
	)
	(segment
		(start 372.423944 -220.590872)
		(end 372.26748 -220.319854)
		(width 0.0889)
		(layer "In13.Cu")
		(net "P5E_CPU0_PE2_RX_DN<4>")
	)
	(segment
		(start 378.407168 -208.488788)
		(end 376.248422 -209.382868)
		(width 0.14732)
		(layer "In13.Cu")
		(net "P5E_CPU0_PE2_RX_DN<4>")
	)
	(segment
		(start 374.47982 -213.164166)
		(end 374.521984 -213.20633)
		(width 0.0889)
		(layer "In13.Cu")
		(net "P5E_CPU0_PE2_RX_DN<4>")
	)
	(segment
		(start 374.521984 -213.852506)
		(end 374.328182 -214.319612)
		(width 0.0889)
		(layer "In13.Cu")
		(net "P5E_CPU0_PE2_RX_DN<4>")
	)
	(segment
		(start 404.745952 -422.46296)
		(end 404.745952 -422.462452)
		(width 0.14732)
		(layer "In13.Cu")
		(net "P5E_CPU0_PE2_RX_DN<4>")
	)
	(segment
		(start 404.745952 -422.462452)
		(end 404.921466 -422.371012)
		(width 0.14732)
		(layer "In13.Cu")
		(net "P5E_CPU0_PE2_RX_DN<4>")
	)
	(segment
		(start 373.582438 -215.423242)
		(end 373.58193 -215.44534)
		(width 0.0889)
		(layer "In13.Cu")
		(net "P5E_CPU0_PE2_RX_DN<4>")
	)
	(segment
		(start 372.921022 -216.577164)
		(end 372.91264 -216.58199)
		(width 0.0889)
		(layer "In13.Cu")
		(net "P5E_CPU0_PE2_RX_DN<4>")
	)
	(segment
		(start 376.248422 -209.382868)
		(end 375.012966 -210.618324)
		(width 0.14732)
		(layer "In13.Cu")
		(net "P5E_CPU0_PE2_RX_DN<4>")
	)
	(arc
		(start 372.91264 -219.837508)
		(mid 372.714412 -220.043356)
		(end 372.64213 -220.319854)
		(width 0.0889)
		(layer "In13.Cu")
		(net "P5E_CPU0_PE2_RX_DN<4>")
	)
	(arc
		(start 373.112284 -216.25052)
		(mid 373.064605 -216.43342)
		(end 372.933722 -216.569798)
		(width 0.0889)
		(layer "In13.Cu")
		(net "P5E_CPU0_PE2_RX_DN<4>")
	)
	(arc
		(start 372.918736 -218.20632)
		(mid 372.642162 -218.692222)
		(end 372.918736 -219.178124)
		(width 0.0889)
		(layer "In13.Cu")
		(net "P5E_CPU0_PE2_RX_DN<4>")
	)
	(arc
		(start 372.91264 -216.58199)
		(mid 372.714412 -216.787838)
		(end 372.64213 -217.064336)
		(width 0.0889)
		(layer "In13.Cu")
		(net "P5E_CPU0_PE2_RX_DN<4>")
	)
	(arc
		(start 373.58193 -215.44534)
		(mid 373.52966 -215.627705)
		(end 373.394732 -215.761062)
		(width 0.0889)
		(layer "In13.Cu")
		(net "P5E_CPU0_PE2_RX_DN<4>")
	)
	(arc
		(start 373.394732 -215.761062)
		(mid 373.190397 -215.963667)
		(end 373.112284 -216.240614)
		(width 0.0889)
		(layer "In13.Cu")
		(net "P5E_CPU0_PE2_RX_DN<4>")
	)
	(arc
		(start 372.64213 -217.071956)
		(mid 372.719759 -217.350369)
		(end 372.924832 -217.554048)
		(width 0.0889)
		(layer "In13.Cu")
		(net "P5E_CPU0_PE2_RX_DN<4>")
	)
	(arc
		(start 372.933722 -219.18676)
		(mid 373.112319 -219.506038)
		(end 372.933722 -219.825316)
		(width 0.0889)
		(layer "In13.Cu")
		(net "P5E_CPU0_PE2_RX_DN<4>")
	)
	(arc
		(start 372.933722 -217.559128)
		(mid 373.112198 -217.878406)
		(end 372.933722 -218.197684)
		(width 0.0889)
		(layer "In13.Cu")
		(net "P5E_CPU0_PE2_RX_DN<4>")
	)
	(arc
		(start 372.64213 -220.319854)
		(mid 372.60527 -220.481651)
		(end 372.502176 -220.6117)
		(width 0.0889)
		(layer "In13.Cu")
		(net "P5E_CPU0_PE2_RX_DN<4>")
	)
	(segment
		(start 371.79758 -221.669864)
		(end 371.79758 -221.134178)
		(width 0.13208)
		(layer "F.Cu")
		(net "P5E_CPU0_PE2_RX_DN<3>")
	)
	(segment
		(start 371.79758 -221.134178)
		(end 371.797834 -221.133924)
		(width 0.13208)
		(layer "F.Cu")
		(net "P5E_CPU0_PE2_RX_DN<3>")
	)
	(segment
		(start 407.146252 -422.052496)
		(end 406.985216 -422.12387)
		(width 0.14732)
		(layer "In13.Cu")
		(net "P5E_CPU0_PE2_RX_DN<3>")
	)
	(segment
		(start 371.986556 -218.202002)
		(end 371.993922 -218.197684)
		(width 0.0889)
		(layer "In13.Cu")
		(net "P5E_CPU0_PE2_RX_DN<3>")
	)
	(segment
		(start 371.986556 -216.574116)
		(end 371.993922 -216.569798)
		(width 0.0889)
		(layer "In13.Cu")
		(net "P5E_CPU0_PE2_RX_DN<3>")
	)
	(segment
		(start 371.978936 -219.833952)
		(end 371.993922 -219.825316)
		(width 0.0889)
		(layer "In13.Cu")
		(net "P5E_CPU0_PE2_RX_DN<3>")
	)
	(segment
		(start 402.251672 -253.704852)
		(end 398.144238 -307.82133)
		(width 0.14732)
		(layer "In13.Cu")
		(net "P5E_CPU0_PE2_RX_DN<3>")
	)
	(segment
		(start 371.797834 -221.133924)
		(end 371.64137 -221.404942)
		(width 0.0889)
		(layer "In13.Cu")
		(net "P5E_CPU0_PE2_RX_DN<3>")
	)
	(segment
		(start 409.675838 -415.12236)
		(end 407.231596 -421.483282)
		(width 0.14732)
		(layer "In13.Cu")
		(net "P5E_CPU0_PE2_RX_DN<3>")
	)
	(segment
		(start 398.144492 -307.822854)
		(end 405.470868 -339.62086)
		(width 0.14732)
		(layer "In13.Cu")
		(net "P5E_CPU0_PE2_RX_DN<3>")
	)
	(segment
		(start 371.986556 -219.182442)
		(end 371.985032 -219.18168)
		(width 0.0889)
		(layer "In13.Cu")
		(net "P5E_CPU0_PE2_RX_DN<3>")
	)
	(segment
		(start 372.454678 -215.761062)
		(end 372.463568 -215.755982)
		(width 0.0889)
		(layer "In13.Cu")
		(net "P5E_CPU0_PE2_RX_DN<3>")
	)
	(segment
		(start 411.62859 -410.466794)
		(end 409.675838 -415.12236)
		(width 0.14732)
		(layer "In13.Cu")
		(net "P5E_CPU0_PE2_RX_DN<3>")
	)
	(segment
		(start 398.144238 -307.821838)
		(end 398.144492 -307.822854)
		(width 0.14732)
		(layer "In13.Cu")
		(net "P5E_CPU0_PE2_RX_DN<3>")
	)
	(segment
		(start 406.066244 -433.578)
		(end 406.19934 -433.711096)
		(width 0.14732)
		(layer "In13.Cu")
		(net "P5E_CPU0_PE2_RX_DN<3>")
	)
	(segment
		(start 403.68347 -349.49638)
		(end 403.355302 -366.573308)
		(width 0.14732)
		(layer "In13.Cu")
		(net "P5E_CPU0_PE2_RX_DN<3>")
	)
	(segment
		(start 398.144238 -307.82133)
		(end 398.144238 -307.821838)
		(width 0.14732)
		(layer "In13.Cu")
		(net "P5E_CPU0_PE2_RX_DN<3>")
	)
	(segment
		(start 372.172484 -216.25052)
		(end 372.172484 -216.235026)
		(width 0.0889)
		(layer "In13.Cu")
		(net "P5E_CPU0_PE2_RX_DN<3>")
	)
	(segment
		(start 381.55372 -201.829162)
		(end 381.763016 -201.749406)
		(width 0.14732)
		(layer "In13.Cu")
		(net "P5E_CPU0_PE2_RX_DN<3>")
	)
	(segment
		(start 406.750012 -433.434236)
		(end 406.750012 -433.289964)
		(width 0.14732)
		(layer "In13.Cu")
		(net "P5E_CPU0_PE2_RX_DN<3>")
	)
	(segment
		(start 398.590262 -224.978468)
		(end 400.32432 -236.470698)
		(width 0.14732)
		(layer "In13.Cu")
		(net "P5E_CPU0_PE2_RX_DN<3>")
	)
	(segment
		(start 406.19934 -433.711096)
		(end 406.473152 -433.711096)
		(width 0.14732)
		(layer "In13.Cu")
		(net "P5E_CPU0_PE2_RX_DN<3>")
	)
	(segment
		(start 373.539258 -213.142068)
		(end 373.539258 -211.684362)
		(width 0.14732)
		(layer "In13.Cu")
		(net "P5E_CPU0_PE2_RX_DN<3>")
	)
	(segment
		(start 406.473152 -433.711096)
		(end 406.750012 -433.434236)
		(width 0.14732)
		(layer "In13.Cu")
		(net "P5E_CPU0_PE2_RX_DN<3>")
	)
	(segment
		(start 403.819868 -371.393212)
		(end 409.045918 -395.743684)
		(width 0.14732)
		(layer "In13.Cu")
		(net "P5E_CPU0_PE2_RX_DN<3>")
	)
	(segment
		(start 374.187466 -209.962242)
		(end 380.530862 -202.7301)
		(width 0.14732)
		(layer "In13.Cu")
		(net "P5E_CPU0_PE2_RX_DN<3>")
	)
	(segment
		(start 382.34239 -201.837798)
		(end 391.043922 -208.712562)
		(width 0.14732)
		(layer "In13.Cu")
		(net "P5E_CPU0_PE2_RX_DN<3>")
	)
	(segment
		(start 406.900126 -422.692322)
		(end 406.743662 -423.1005)
		(width 0.14732)
		(layer "In13.Cu")
		(net "P5E_CPU0_PE2_RX_DN<3>")
	)
	(segment
		(start 371.993922 -219.18676)
		(end 371.986556 -219.182442)
		(width 0.0889)
		(layer "In13.Cu")
		(net "P5E_CPU0_PE2_RX_DN<3>")
	)
	(segment
		(start 406.582626 -423.172382)
		(end 406.066244 -424.516042)
		(width 0.14732)
		(layer "In13.Cu")
		(net "P5E_CPU0_PE2_RX_DN<3>")
	)
	(segment
		(start 371.98427 -219.181172)
		(end 371.978936 -219.178124)
		(width 0.0889)
		(layer "In13.Cu")
		(net "P5E_CPU0_PE2_RX_DN<3>")
	)
	(segment
		(start 400.32432 -236.470698)
		(end 400.324574 -236.47146)
		(width 0.14732)
		(layer "In13.Cu")
		(net "P5E_CPU0_PE2_RX_DN<3>")
	)
	(segment
		(start 371.985032 -216.574878)
		(end 371.986556 -216.574116)
		(width 0.0889)
		(layer "In13.Cu")
		(net "P5E_CPU0_PE2_RX_DN<3>")
	)
	(segment
		(start 380.530862 -202.7301)
		(end 381.35687 -201.903838)
		(width 0.14732)
		(layer "In13.Cu")
		(net "P5E_CPU0_PE2_RX_DN<3>")
	)
	(segment
		(start 410.28239 -404.705566)
		(end 411.62859 -406.051766)
		(width 0.14732)
		(layer "In13.Cu")
		(net "P5E_CPU0_PE2_RX_DN<3>")
	)
	(segment
		(start 371.978936 -218.20632)
		(end 371.986556 -218.202002)
		(width 0.0889)
		(layer "In13.Cu")
		(net "P5E_CPU0_PE2_RX_DN<3>")
	)
	(segment
		(start 406.066244 -424.516042)
		(end 406.066244 -433.578)
		(width 0.14732)
		(layer "In13.Cu")
		(net "P5E_CPU0_PE2_RX_DN<3>")
	)
	(segment
		(start 406.985216 -422.12387)
		(end 406.828752 -422.53154)
		(width 0.14732)
		(layer "In13.Cu")
		(net "P5E_CPU0_PE2_RX_DN<3>")
	)
	(segment
		(start 371.985032 -219.18168)
		(end 371.98427 -219.181172)
		(width 0.0889)
		(layer "In13.Cu")
		(net "P5E_CPU0_PE2_RX_DN<3>")
	)
	(segment
		(start 403.355302 -366.573308)
		(end 403.819868 -371.393212)
		(width 0.14732)
		(layer "In13.Cu")
		(net "P5E_CPU0_PE2_RX_DN<3>")
	)
	(segment
		(start 371.978936 -216.578434)
		(end 371.985032 -216.574878)
		(width 0.0889)
		(layer "In13.Cu")
		(net "P5E_CPU0_PE2_RX_DN<3>")
	)
	(segment
		(start 371.70233 -220.334078)
		(end 371.70233 -220.319854)
		(width 0.0889)
		(layer "In13.Cu")
		(net "P5E_CPU0_PE2_RX_DN<3>")
	)
	(segment
		(start 391.043922 -208.712562)
		(end 395.08303 -212.904578)
		(width 0.14732)
		(layer "In13.Cu")
		(net "P5E_CPU0_PE2_RX_DN<3>")
	)
	(segment
		(start 371.70233 -217.07856)
		(end 371.70233 -217.064336)
		(width 0.0889)
		(layer "In13.Cu")
		(net "P5E_CPU0_PE2_RX_DN<3>")
	)
	(segment
		(start 410.28239 -400.440652)
		(end 410.28239 -404.705566)
		(width 0.14732)
		(layer "In13.Cu")
		(net "P5E_CPU0_PE2_RX_DN<3>")
	)
	(segment
		(start 400.324574 -236.47146)
		(end 402.058378 -247.96115)
		(width 0.14732)
		(layer "In13.Cu")
		(net "P5E_CPU0_PE2_RX_DN<3>")
	)
	(segment
		(start 373.409718 -214.231982)
		(end 373.581422 -213.816946)
		(width 0.0889)
		(layer "In13.Cu")
		(net "P5E_CPU0_PE2_RX_DN<3>")
	)
	(segment
		(start 407.30297 -421.644318)
		(end 407.146252 -422.052496)
		(width 0.14732)
		(layer "In13.Cu")
		(net "P5E_CPU0_PE2_RX_DN<3>")
	)
	(segment
		(start 395.08303 -212.904578)
		(end 398.590262 -224.978468)
		(width 0.14732)
		(layer "In13.Cu")
		(net "P5E_CPU0_PE2_RX_DN<3>")
	)
	(segment
		(start 406.828752 -422.53154)
		(end 406.900126 -422.692322)
		(width 0.14732)
		(layer "In13.Cu")
		(net "P5E_CPU0_PE2_RX_DN<3>")
	)
	(segment
		(start 372.64213 -215.436704)
		(end 372.642384 -215.43645)
		(width 0.0889)
		(layer "In13.Cu")
		(net "P5E_CPU0_PE2_RX_DN<3>")
	)
	(segment
		(start 407.231596 -421.483282)
		(end 407.231596 -421.483536)
		(width 0.14732)
		(layer "In13.Cu")
		(net "P5E_CPU0_PE2_RX_DN<3>")
	)
	(segment
		(start 373.581422 -213.816946)
		(end 373.581422 -213.20633)
		(width 0.0889)
		(layer "In13.Cu")
		(net "P5E_CPU0_PE2_RX_DN<3>")
	)
	(segment
		(start 373.581422 -213.20633)
		(end 373.539258 -213.164166)
		(width 0.0889)
		(layer "In13.Cu")
		(net "P5E_CPU0_PE2_RX_DN<3>")
	)
	(segment
		(start 371.986556 -221.45752)
		(end 371.993922 -221.453202)
		(width 0.0889)
		(layer "In13.Cu")
		(net "P5E_CPU0_PE2_RX_DN<3>")
	)
	(segment
		(start 409.189682 -396.414244)
		(end 409.447746 -397.61668)
		(width 0.14732)
		(layer "In13.Cu")
		(net "P5E_CPU0_PE2_RX_DN<3>")
	)
	(segment
		(start 372.642384 -215.285066)
		(end 372.845076 -214.796878)
		(width 0.0889)
		(layer "In13.Cu")
		(net "P5E_CPU0_PE2_RX_DN<3>")
	)
	(segment
		(start 406.582372 -423.172128)
		(end 406.582626 -423.172382)
		(width 0.14732)
		(layer "In13.Cu")
		(net "P5E_CPU0_PE2_RX_DN<3>")
	)
	(segment
		(start 411.62859 -406.051766)
		(end 411.62859 -410.466794)
		(width 0.14732)
		(layer "In13.Cu")
		(net "P5E_CPU0_PE2_RX_DN<3>")
	)
	(segment
		(start 409.193746 -395.838934)
		(end 409.28544 -396.266416)
		(width 0.14732)
		(layer "In13.Cu")
		(net "P5E_CPU0_PE2_RX_DN<3>")
	)
	(segment
		(start 371.993922 -217.559128)
		(end 371.985032 -217.554048)
		(width 0.0889)
		(layer "In13.Cu")
		(net "P5E_CPU0_PE2_RX_DN<3>")
	)
	(segment
		(start 371.985032 -221.458282)
		(end 371.986556 -221.45752)
		(width 0.0889)
		(layer "In13.Cu")
		(net "P5E_CPU0_PE2_RX_DN<3>")
	)
	(segment
		(start 409.045918 -395.743684)
		(end 409.193746 -395.838934)
		(width 0.14732)
		(layer "In13.Cu")
		(net "P5E_CPU0_PE2_RX_DN<3>")
	)
	(segment
		(start 402.058378 -247.96115)
		(end 402.251672 -253.704852)
		(width 0.14732)
		(layer "In13.Cu")
		(net "P5E_CPU0_PE2_RX_DN<3>")
	)
	(segment
		(start 409.28544 -396.266416)
		(end 409.189682 -396.414244)
		(width 0.14732)
		(layer "In13.Cu")
		(net "P5E_CPU0_PE2_RX_DN<3>")
	)
	(segment
		(start 407.231596 -421.483536)
		(end 407.30297 -421.644318)
		(width 0.14732)
		(layer "In13.Cu")
		(net "P5E_CPU0_PE2_RX_DN<3>")
	)
	(segment
		(start 373.539258 -213.164166)
		(end 373.539258 -213.142068)
		(width 0.0889)
		(layer "In13.Cu")
		(net "P5E_CPU0_PE2_RX_DN<3>")
	)
	(segment
		(start 372.845076 -214.796878)
		(end 373.409718 -214.231982)
		(width 0.0889)
		(layer "In13.Cu")
		(net "P5E_CPU0_PE2_RX_DN<3>")
	)
	(segment
		(start 371.64137 -221.404942)
		(end 371.662452 -221.48292)
		(width 0.0889)
		(layer "In13.Cu")
		(net "P5E_CPU0_PE2_RX_DN<3>")
	)
	(segment
		(start 409.447746 -397.61668)
		(end 410.28239 -400.440652)
		(width 0.14732)
		(layer "In13.Cu")
		(net "P5E_CPU0_PE2_RX_DN<3>")
	)
	(segment
		(start 371.993922 -220.814646)
		(end 371.985032 -220.809566)
		(width 0.0889)
		(layer "In13.Cu")
		(net "P5E_CPU0_PE2_RX_DN<3>")
	)
	(segment
		(start 373.539258 -211.684362)
		(end 374.187466 -209.962242)
		(width 0.14732)
		(layer "In13.Cu")
		(net "P5E_CPU0_PE2_RX_DN<3>")
	)
	(segment
		(start 405.470868 -339.62086)
		(end 403.68347 -349.49638)
		(width 0.14732)
		(layer "In13.Cu")
		(net "P5E_CPU0_PE2_RX_DN<3>")
	)
	(segment
		(start 381.763016 -201.749406)
		(end 382.34239 -201.837798)
		(width 0.14732)
		(layer "In13.Cu")
		(net "P5E_CPU0_PE2_RX_DN<3>")
	)
	(segment
		(start 406.743662 -423.1005)
		(end 406.582372 -423.172128)
		(width 0.14732)
		(layer "In13.Cu")
		(net "P5E_CPU0_PE2_RX_DN<3>")
	)
	(segment
		(start 372.642384 -215.43645)
		(end 372.642384 -215.285066)
		(width 0.0889)
		(layer "In13.Cu")
		(net "P5E_CPU0_PE2_RX_DN<3>")
	)
	(segment
		(start 381.35687 -201.903838)
		(end 381.55372 -201.829162)
		(width 0.14732)
		(layer "In13.Cu")
		(net "P5E_CPU0_PE2_RX_DN<3>")
	)
	(arc
		(start 372.172484 -216.235026)
		(mid 372.251854 -215.961292)
		(end 372.454678 -215.761062)
		(width 0.0889)
		(layer "In13.Cu")
		(net "P5E_CPU0_PE2_RX_DN<3>")
	)
	(arc
		(start 371.70233 -220.319854)
		(mid 371.776321 -220.040288)
		(end 371.978936 -219.833952)
		(width 0.0889)
		(layer "In13.Cu")
		(net "P5E_CPU0_PE2_RX_DN<3>")
	)
	(arc
		(start 371.70233 -217.064336)
		(mid 371.776321 -216.78477)
		(end 371.978936 -216.578434)
		(width 0.0889)
		(layer "In13.Cu")
		(net "P5E_CPU0_PE2_RX_DN<3>")
	)
	(arc
		(start 371.993922 -221.453202)
		(mid 372.17264 -221.133924)
		(end 371.993922 -220.814646)
		(width 0.0889)
		(layer "In13.Cu")
		(net "P5E_CPU0_PE2_RX_DN<3>")
	)
	(arc
		(start 371.993922 -219.825316)
		(mid 372.172519 -219.506038)
		(end 371.993922 -219.18676)
		(width 0.0889)
		(layer "In13.Cu")
		(net "P5E_CPU0_PE2_RX_DN<3>")
	)
	(arc
		(start 371.662452 -221.48292)
		(mid 371.826548 -221.507267)
		(end 371.985032 -221.458282)
		(width 0.0889)
		(layer "In13.Cu")
		(net "P5E_CPU0_PE2_RX_DN<3>")
	)
	(arc
		(start 371.993922 -216.569798)
		(mid 372.124836 -216.433438)
		(end 372.172484 -216.25052)
		(width 0.0889)
		(layer "In13.Cu")
		(net "P5E_CPU0_PE2_RX_DN<3>")
	)
	(arc
		(start 371.985032 -217.554048)
		(mid 371.781551 -217.353244)
		(end 371.70233 -217.07856)
		(width 0.0889)
		(layer "In13.Cu")
		(net "P5E_CPU0_PE2_RX_DN<3>")
	)
	(arc
		(start 372.463568 -215.755982)
		(mid 372.594482 -215.619622)
		(end 372.64213 -215.436704)
		(width 0.0889)
		(layer "In13.Cu")
		(net "P5E_CPU0_PE2_RX_DN<3>")
	)
	(arc
		(start 371.978936 -219.178124)
		(mid 371.702362 -218.692222)
		(end 371.978936 -218.20632)
		(width 0.0889)
		(layer "In13.Cu")
		(net "P5E_CPU0_PE2_RX_DN<3>")
	)
	(arc
		(start 371.993922 -218.197684)
		(mid 372.17264 -217.878406)
		(end 371.993922 -217.559128)
		(width 0.0889)
		(layer "In13.Cu")
		(net "P5E_CPU0_PE2_RX_DN<3>")
	)
	(arc
		(start 371.985032 -220.809566)
		(mid 371.781551 -220.608762)
		(end 371.70233 -220.334078)
		(width 0.0889)
		(layer "In13.Cu")
		(net "P5E_CPU0_PE2_RX_DN<3>")
	)
	(segment
		(start 370.388134 -220.320108)
		(end 370.38788 -220.319854)
		(width 0.13208)
		(layer "F.Cu")
		(net "P5E_CPU0_PE2_RX_DN<2>")
	)
	(segment
		(start 370.388134 -220.855794)
		(end 370.388134 -220.320108)
		(width 0.13208)
		(layer "F.Cu")
		(net "P5E_CPU0_PE2_RX_DN<2>")
	)
	(segment
		(start 408.06624 -424.448224)
		(end 409.074112 -422.232582)
		(width 0.14732)
		(layer "In13.Cu")
		(net "P5E_CPU0_PE2_RX_DN<2>")
	)
	(segment
		(start 370.622576 -220.6117)
		(end 370.544344 -220.590872)
		(width 0.0889)
		(layer "In13.Cu")
		(net "P5E_CPU0_PE2_RX_DN<2>")
	)
	(segment
		(start 406.446482 -339.670644)
		(end 399.123662 -307.714142)
		(width 0.14732)
		(layer "In13.Cu")
		(net "P5E_CPU0_PE2_RX_DN<2>")
	)
	(segment
		(start 399.123662 -307.714142)
		(end 403.199854 -253.51105)
		(width 0.14732)
		(layer "In13.Cu")
		(net "P5E_CPU0_PE2_RX_DN<2>")
	)
	(segment
		(start 395.962886 -212.115908)
		(end 385.711446 -201.524362)
		(width 0.14732)
		(layer "In13.Cu")
		(net "P5E_CPU0_PE2_RX_DN<2>")
	)
	(segment
		(start 372.503954 -214.16518)
		(end 371.83822 -214.831168)
		(width 0.0889)
		(layer "In13.Cu")
		(net "P5E_CPU0_PE2_RX_DN<2>")
	)
	(segment
		(start 370.544344 -220.590872)
		(end 370.38788 -220.319854)
		(width 0.0889)
		(layer "In13.Cu")
		(net "P5E_CPU0_PE2_RX_DN<2>")
	)
	(segment
		(start 385.711446 -201.524362)
		(end 385.196842 -201.31151)
		(width 0.14732)
		(layer "In13.Cu")
		(net "P5E_CPU0_PE2_RX_DN<2>")
	)
	(segment
		(start 371.054122 -218.197684)
		(end 371.039136 -218.20632)
		(width 0.0889)
		(layer "In13.Cu")
		(net "P5E_CPU0_PE2_RX_DN<2>")
	)
	(segment
		(start 372.60022 -211.464144)
		(end 372.60022 -213.142068)
		(width 0.14732)
		(layer "In13.Cu")
		(net "P5E_CPU0_PE2_RX_DN<2>")
	)
	(segment
		(start 403.199854 -253.51105)
		(end 403.200108 -253.51105)
		(width 0.14732)
		(layer "In13.Cu")
		(net "P5E_CPU0_PE2_RX_DN<2>")
	)
	(segment
		(start 409.5623 -421.159432)
		(end 409.74772 -421.09009)
		(width 0.14732)
		(layer "In13.Cu")
		(net "P5E_CPU0_PE2_RX_DN<2>")
	)
	(segment
		(start 413.34563 -404.705566)
		(end 413.34563 -400.58848)
		(width 0.14732)
		(layer "In13.Cu")
		(net "P5E_CPU0_PE2_RX_DN<2>")
	)
	(segment
		(start 403.200108 -253.51105)
		(end 403.201124 -253.496064)
		(width 0.14732)
		(layer "In13.Cu")
		(net "P5E_CPU0_PE2_RX_DN<2>")
	)
	(segment
		(start 370.76253 -217.064336)
		(end 370.76253 -217.071956)
		(width 0.0889)
		(layer "In13.Cu")
		(net "P5E_CPU0_PE2_RX_DN<2>")
	)
	(segment
		(start 371.232684 -216.240614)
		(end 371.232684 -216.25052)
		(width 0.0889)
		(layer "In13.Cu")
		(net "P5E_CPU0_PE2_RX_DN<2>")
	)
	(segment
		(start 409.90012 -420.754556)
		(end 409.830778 -420.569644)
		(width 0.14732)
		(layer "In13.Cu")
		(net "P5E_CPU0_PE2_RX_DN<2>")
	)
	(segment
		(start 408.750008 -434.289962)
		(end 408.749754 -434.289962)
		(width 0.14732)
		(layer "In13.Cu")
		(net "P5E_CPU0_PE2_RX_DN<2>")
	)
	(segment
		(start 371.702838 -215.423242)
		(end 371.70233 -215.44534)
		(width 0.0889)
		(layer "In13.Cu")
		(net "P5E_CPU0_PE2_RX_DN<2>")
	)
	(segment
		(start 399.633186 -224.74936)
		(end 395.962886 -212.115908)
		(width 0.14732)
		(layer "In13.Cu")
		(net "P5E_CPU0_PE2_RX_DN<2>")
	)
	(segment
		(start 385.196842 -201.31151)
		(end 381.933704 -200.79589)
		(width 0.14732)
		(layer "In13.Cu")
		(net "P5E_CPU0_PE2_RX_DN<2>")
	)
	(segment
		(start 371.045232 -219.830396)
		(end 371.041422 -219.832682)
		(width 0.0889)
		(layer "In13.Cu")
		(net "P5E_CPU0_PE2_RX_DN<2>")
	)
	(segment
		(start 371.054122 -216.569798)
		(end 371.045232 -216.574878)
		(width 0.0889)
		(layer "In13.Cu")
		(net "P5E_CPU0_PE2_RX_DN<2>")
	)
	(segment
		(start 371.039136 -219.178124)
		(end 371.04447 -219.181172)
		(width 0.0889)
		(layer "In13.Cu")
		(net "P5E_CPU0_PE2_RX_DN<2>")
	)
	(segment
		(start 408.366722 -434.672994)
		(end 408.228292 -434.672994)
		(width 0.14732)
		(layer "In13.Cu")
		(net "P5E_CPU0_PE2_RX_DN<2>")
	)
	(segment
		(start 402.980144 -246.930164)
		(end 399.633186 -224.74936)
		(width 0.14732)
		(layer "In13.Cu")
		(net "P5E_CPU0_PE2_RX_DN<2>")
	)
	(segment
		(start 372.60022 -213.142068)
		(end 372.60022 -213.164166)
		(width 0.0889)
		(layer "In13.Cu")
		(net "P5E_CPU0_PE2_RX_DN<2>")
	)
	(segment
		(start 409.830778 -420.569644)
		(end 410.88945 -418.24275)
		(width 0.14732)
		(layer "In13.Cu")
		(net "P5E_CPU0_PE2_RX_DN<2>")
	)
	(segment
		(start 371.041422 -216.577164)
		(end 371.03304 -216.58199)
		(width 0.0889)
		(layer "In13.Cu")
		(net "P5E_CPU0_PE2_RX_DN<2>")
	)
	(segment
		(start 403.201124 -253.496064)
		(end 402.980144 -246.930164)
		(width 0.14732)
		(layer "In13.Cu")
		(net "P5E_CPU0_PE2_RX_DN<2>")
	)
	(segment
		(start 408.228292 -434.672994)
		(end 408.06624 -434.510942)
		(width 0.14732)
		(layer "In13.Cu")
		(net "P5E_CPU0_PE2_RX_DN<2>")
	)
	(segment
		(start 414.69183 -411.29331)
		(end 414.69183 -406.051766)
		(width 0.14732)
		(layer "In13.Cu")
		(net "P5E_CPU0_PE2_RX_DN<2>")
	)
	(segment
		(start 381.475488 -200.79589)
		(end 380.895352 -201.036174)
		(width 0.14732)
		(layer "In13.Cu")
		(net "P5E_CPU0_PE2_RX_DN<2>")
	)
	(segment
		(start 410.88945 -418.24275)
		(end 414.69183 -411.29331)
		(width 0.14732)
		(layer "In13.Cu")
		(net "P5E_CPU0_PE2_RX_DN<2>")
	)
	(segment
		(start 371.045232 -216.574878)
		(end 371.041422 -216.577164)
		(width 0.0889)
		(layer "In13.Cu")
		(net "P5E_CPU0_PE2_RX_DN<2>")
	)
	(segment
		(start 409.411932 -421.82796)
		(end 409.34259 -421.642794)
		(width 0.14732)
		(layer "In13.Cu")
		(net "P5E_CPU0_PE2_RX_DN<2>")
	)
	(segment
		(start 409.74772 -421.09009)
		(end 409.90012 -420.754556)
		(width 0.14732)
		(layer "In13.Cu")
		(net "P5E_CPU0_PE2_RX_DN<2>")
	)
	(segment
		(start 371.046756 -219.182442)
		(end 371.054122 -219.18676)
		(width 0.0889)
		(layer "In13.Cu")
		(net "P5E_CPU0_PE2_RX_DN<2>")
	)
	(segment
		(start 408.749754 -434.289962)
		(end 408.366722 -434.672994)
		(width 0.14732)
		(layer "In13.Cu")
		(net "P5E_CPU0_PE2_RX_DN<2>")
	)
	(segment
		(start 409.259532 -422.163494)
		(end 409.411932 -421.82796)
		(width 0.14732)
		(layer "In13.Cu")
		(net "P5E_CPU0_PE2_RX_DN<2>")
	)
	(segment
		(start 371.045232 -219.18168)
		(end 371.046756 -219.182442)
		(width 0.0889)
		(layer "In13.Cu")
		(net "P5E_CPU0_PE2_RX_DN<2>")
	)
	(segment
		(start 371.83822 -214.831168)
		(end 371.702838 -215.157812)
		(width 0.0889)
		(layer "In13.Cu")
		(net "P5E_CPU0_PE2_RX_DN<2>")
	)
	(segment
		(start 412.164022 -396.923768)
		(end 405.041862 -370.86159)
		(width 0.14732)
		(layer "In13.Cu")
		(net "P5E_CPU0_PE2_RX_DN<2>")
	)
	(segment
		(start 413.34563 -400.58848)
		(end 412.164022 -396.923768)
		(width 0.14732)
		(layer "In13.Cu")
		(net "P5E_CPU0_PE2_RX_DN<2>")
	)
	(segment
		(start 381.933704 -200.79589)
		(end 381.475488 -200.79589)
		(width 0.14732)
		(layer "In13.Cu")
		(net "P5E_CPU0_PE2_RX_DN<2>")
	)
	(segment
		(start 372.642384 -213.831678)
		(end 372.503954 -214.16518)
		(width 0.0889)
		(layer "In13.Cu")
		(net "P5E_CPU0_PE2_RX_DN<2>")
	)
	(segment
		(start 414.69183 -406.051766)
		(end 413.34563 -404.705566)
		(width 0.14732)
		(layer "In13.Cu")
		(net "P5E_CPU0_PE2_RX_DN<2>")
	)
	(segment
		(start 408.06624 -434.510942)
		(end 408.06624 -424.448224)
		(width 0.14732)
		(layer "In13.Cu")
		(net "P5E_CPU0_PE2_RX_DN<2>")
	)
	(segment
		(start 371.702838 -215.157812)
		(end 371.702838 -215.423242)
		(width 0.0889)
		(layer "In13.Cu")
		(net "P5E_CPU0_PE2_RX_DN<2>")
	)
	(segment
		(start 380.895352 -201.036174)
		(end 379.715268 -202.216258)
		(width 0.14732)
		(layer "In13.Cu")
		(net "P5E_CPU0_PE2_RX_DN<2>")
	)
	(segment
		(start 409.074112 -422.232582)
		(end 409.259532 -422.163494)
		(width 0.14732)
		(layer "In13.Cu")
		(net "P5E_CPU0_PE2_RX_DN<2>")
	)
	(segment
		(start 372.60022 -213.164166)
		(end 372.642384 -213.20633)
		(width 0.0889)
		(layer "In13.Cu")
		(net "P5E_CPU0_PE2_RX_DN<2>")
	)
	(segment
		(start 371.04447 -219.181172)
		(end 371.045232 -219.18168)
		(width 0.0889)
		(layer "In13.Cu")
		(net "P5E_CPU0_PE2_RX_DN<2>")
	)
	(segment
		(start 371.041422 -219.832682)
		(end 371.03304 -219.837508)
		(width 0.0889)
		(layer "In13.Cu")
		(net "P5E_CPU0_PE2_RX_DN<2>")
	)
	(segment
		(start 373.343678 -209.487516)
		(end 372.60022 -211.464144)
		(width 0.14732)
		(layer "In13.Cu")
		(net "P5E_CPU0_PE2_RX_DN<2>")
	)
	(segment
		(start 409.34259 -421.642794)
		(end 409.5623 -421.159432)
		(width 0.14732)
		(layer "In13.Cu")
		(net "P5E_CPU0_PE2_RX_DN<2>")
	)
	(segment
		(start 372.642384 -213.20633)
		(end 372.642384 -213.831678)
		(width 0.0889)
		(layer "In13.Cu")
		(net "P5E_CPU0_PE2_RX_DN<2>")
	)
	(segment
		(start 371.054122 -219.825316)
		(end 371.045232 -219.830396)
		(width 0.0889)
		(layer "In13.Cu")
		(net "P5E_CPU0_PE2_RX_DN<2>")
	)
	(segment
		(start 379.715268 -202.216258)
		(end 373.343678 -209.487516)
		(width 0.14732)
		(layer "In13.Cu")
		(net "P5E_CPU0_PE2_RX_DN<2>")
	)
	(segment
		(start 404.547578 -366.992662)
		(end 404.774654 -349.113602)
		(width 0.14732)
		(layer "In13.Cu")
		(net "P5E_CPU0_PE2_RX_DN<2>")
	)
	(segment
		(start 405.041862 -370.86159)
		(end 404.547578 -366.992662)
		(width 0.14732)
		(layer "In13.Cu")
		(net "P5E_CPU0_PE2_RX_DN<2>")
	)
	(segment
		(start 371.045232 -217.554048)
		(end 371.054122 -217.559128)
		(width 0.0889)
		(layer "In13.Cu")
		(net "P5E_CPU0_PE2_RX_DN<2>")
	)
	(segment
		(start 404.774654 -349.113602)
		(end 406.446482 -339.670644)
		(width 0.14732)
		(layer "In13.Cu")
		(net "P5E_CPU0_PE2_RX_DN<2>")
	)
	(arc
		(start 371.039136 -218.20632)
		(mid 370.762562 -218.692222)
		(end 371.039136 -219.178124)
		(width 0.0889)
		(layer "In13.Cu")
		(net "P5E_CPU0_PE2_RX_DN<2>")
	)
	(arc
		(start 371.70233 -215.44534)
		(mid 371.65006 -215.627705)
		(end 371.515132 -215.761062)
		(width 0.0889)
		(layer "In13.Cu")
		(net "P5E_CPU0_PE2_RX_DN<2>")
	)
	(arc
		(start 371.03304 -219.837508)
		(mid 370.834812 -220.043356)
		(end 370.76253 -220.319854)
		(width 0.0889)
		(layer "In13.Cu")
		(net "P5E_CPU0_PE2_RX_DN<2>")
	)
	(arc
		(start 371.232684 -216.25052)
		(mid 371.185005 -216.43342)
		(end 371.054122 -216.569798)
		(width 0.0889)
		(layer "In13.Cu")
		(net "P5E_CPU0_PE2_RX_DN<2>")
	)
	(arc
		(start 371.054122 -219.18676)
		(mid 371.232719 -219.506038)
		(end 371.054122 -219.825316)
		(width 0.0889)
		(layer "In13.Cu")
		(net "P5E_CPU0_PE2_RX_DN<2>")
	)
	(arc
		(start 370.76253 -220.319854)
		(mid 370.72567 -220.481651)
		(end 370.622576 -220.6117)
		(width 0.0889)
		(layer "In13.Cu")
		(net "P5E_CPU0_PE2_RX_DN<2>")
	)
	(arc
		(start 371.054122 -217.559128)
		(mid 371.232598 -217.878406)
		(end 371.054122 -218.197684)
		(width 0.0889)
		(layer "In13.Cu")
		(net "P5E_CPU0_PE2_RX_DN<2>")
	)
	(arc
		(start 371.515132 -215.761062)
		(mid 371.310797 -215.963667)
		(end 371.232684 -216.240614)
		(width 0.0889)
		(layer "In13.Cu")
		(net "P5E_CPU0_PE2_RX_DN<2>")
	)
	(arc
		(start 370.76253 -217.071956)
		(mid 370.840159 -217.350369)
		(end 371.045232 -217.554048)
		(width 0.0889)
		(layer "In13.Cu")
		(net "P5E_CPU0_PE2_RX_DN<2>")
	)
	(arc
		(start 371.03304 -216.58199)
		(mid 370.834812 -216.787838)
		(end 370.76253 -217.064336)
		(width 0.0889)
		(layer "In13.Cu")
		(net "P5E_CPU0_PE2_RX_DN<2>")
	)
	(segment
		(start 369.91798 -221.134178)
		(end 369.918234 -221.133924)
		(width 0.13208)
		(layer "F.Cu")
		(net "P5E_CPU0_PE2_RX_DN<1>")
	)
	(segment
		(start 369.91798 -221.669864)
		(end 369.91798 -221.134178)
		(width 0.13208)
		(layer "F.Cu")
		(net "P5E_CPU0_PE2_RX_DN<1>")
	)
	(segment
		(start 411.22346 -422.60647)
		(end 411.165802 -422.417494)
		(width 0.14732)
		(layer "In13.Cu")
		(net "P5E_CPU0_PE2_RX_DN<1>")
	)
	(segment
		(start 370.762784 -215.43645)
		(end 370.76253 -215.436704)
		(width 0.0889)
		(layer "In13.Cu")
		(net "P5E_CPU0_PE2_RX_DN<1>")
	)
	(segment
		(start 410.74975 -433.289964)
		(end 410.366718 -433.672996)
		(width 0.14732)
		(layer "In13.Cu")
		(net "P5E_CPU0_PE2_RX_DN<1>")
	)
	(segment
		(start 369.782852 -221.48292)
		(end 369.76177 -221.404942)
		(width 0.0889)
		(layer "In13.Cu")
		(net "P5E_CPU0_PE2_RX_DN<1>")
	)
	(segment
		(start 411.76067 -421.609266)
		(end 411.70098 -421.413432)
		(width 0.14732)
		(layer "In13.Cu")
		(net "P5E_CPU0_PE2_RX_DN<1>")
	)
	(segment
		(start 410.066236 -424.480482)
		(end 410.861002 -422.989502)
		(width 0.14732)
		(layer "In13.Cu")
		(net "P5E_CPU0_PE2_RX_DN<1>")
	)
	(segment
		(start 372.51767 -209.000852)
		(end 371.659658 -211.280248)
		(width 0.14732)
		(layer "In13.Cu")
		(net "P5E_CPU0_PE2_RX_DN<1>")
	)
	(segment
		(start 400.552666 -224.54743)
		(end 396.778226 -211.554568)
		(width 0.14732)
		(layer "In13.Cu")
		(net "P5E_CPU0_PE2_RX_DN<1>")
	)
	(segment
		(start 416.40887 -400.036284)
		(end 415.355024 -397.944594)
		(width 0.14732)
		(layer "In13.Cu")
		(net "P5E_CPU0_PE2_RX_DN<1>")
	)
	(segment
		(start 369.82273 -217.064336)
		(end 369.82273 -217.07856)
		(width 0.0889)
		(layer "In13.Cu")
		(net "P5E_CPU0_PE2_RX_DN<1>")
	)
	(segment
		(start 410.366718 -433.672996)
		(end 410.17444 -433.672996)
		(width 0.14732)
		(layer "In13.Cu")
		(net "P5E_CPU0_PE2_RX_DN<1>")
	)
	(segment
		(start 371.659658 -213.164166)
		(end 371.701822 -213.20633)
		(width 0.0889)
		(layer "In13.Cu")
		(net "P5E_CPU0_PE2_RX_DN<1>")
	)
	(segment
		(start 370.114322 -218.197684)
		(end 370.099336 -218.20632)
		(width 0.0889)
		(layer "In13.Cu")
		(net "P5E_CPU0_PE2_RX_DN<1>")
	)
	(segment
		(start 400.069812 -307.56479)
		(end 400.069812 -307.564536)
		(width 0.14732)
		(layer "In13.Cu")
		(net "P5E_CPU0_PE2_RX_DN<1>")
	)
	(segment
		(start 370.114322 -219.825316)
		(end 370.106956 -219.829634)
		(width 0.0889)
		(layer "In13.Cu")
		(net "P5E_CPU0_PE2_RX_DN<1>")
	)
	(segment
		(start 370.099336 -219.178124)
		(end 370.105432 -219.18168)
		(width 0.0889)
		(layer "In13.Cu")
		(net "P5E_CPU0_PE2_RX_DN<1>")
	)
	(segment
		(start 415.355024 -397.944594)
		(end 406.048464 -370.013738)
		(width 0.14732)
		(layer "In13.Cu")
		(net "P5E_CPU0_PE2_RX_DN<1>")
	)
	(segment
		(start 403.974808 -247.226836)
		(end 400.552666 -224.54743)
		(width 0.14732)
		(layer "In13.Cu")
		(net "P5E_CPU0_PE2_RX_DN<1>")
	)
	(segment
		(start 370.114322 -216.569798)
		(end 370.106956 -216.574116)
		(width 0.0889)
		(layer "In13.Cu")
		(net "P5E_CPU0_PE2_RX_DN<1>")
	)
	(segment
		(start 410.861002 -422.989502)
		(end 411.050232 -422.931844)
		(width 0.14732)
		(layer "In13.Cu")
		(net "P5E_CPU0_PE2_RX_DN<1>")
	)
	(segment
		(start 400.069812 -307.564536)
		(end 404.18512 -253.486412)
		(width 0.14732)
		(layer "In13.Cu")
		(net "P5E_CPU0_PE2_RX_DN<1>")
	)
	(segment
		(start 370.105432 -220.809566)
		(end 370.114322 -220.814646)
		(width 0.0889)
		(layer "In13.Cu")
		(net "P5E_CPU0_PE2_RX_DN<1>")
	)
	(segment
		(start 369.76177 -221.404942)
		(end 369.918234 -221.133924)
		(width 0.0889)
		(layer "In13.Cu")
		(net "P5E_CPU0_PE2_RX_DN<1>")
	)
	(segment
		(start 370.105432 -219.830396)
		(end 370.102638 -219.83192)
		(width 0.0889)
		(layer "In13.Cu")
		(net "P5E_CPU0_PE2_RX_DN<1>")
	)
	(segment
		(start 371.58168 -214.147654)
		(end 370.916454 -214.813134)
		(width 0.0889)
		(layer "In13.Cu")
		(net "P5E_CPU0_PE2_RX_DN<1>")
	)
	(segment
		(start 370.102638 -219.83192)
		(end 370.099336 -219.833952)
		(width 0.0889)
		(layer "In13.Cu")
		(net "P5E_CPU0_PE2_RX_DN<1>")
	)
	(segment
		(start 411.391354 -421.99433)
		(end 411.587442 -421.93464)
		(width 0.14732)
		(layer "In13.Cu")
		(net "P5E_CPU0_PE2_RX_DN<1>")
	)
	(segment
		(start 411.050232 -422.931844)
		(end 411.22346 -422.60647)
		(width 0.14732)
		(layer "In13.Cu")
		(net "P5E_CPU0_PE2_RX_DN<1>")
	)
	(segment
		(start 386.175758 -200.668128)
		(end 385.534662 -200.402698)
		(width 0.14732)
		(layer "In13.Cu")
		(net "P5E_CPU0_PE2_RX_DN<1>")
	)
	(segment
		(start 385.534662 -200.402698)
		(end 382.057148 -199.85609)
		(width 0.14732)
		(layer "In13.Cu")
		(net "P5E_CPU0_PE2_RX_DN<1>")
	)
	(segment
		(start 417.75507 -406.02789)
		(end 416.40887 -404.68169)
		(width 0.14732)
		(layer "In13.Cu")
		(net "P5E_CPU0_PE2_RX_DN<1>")
	)
	(segment
		(start 416.40887 -404.68169)
		(end 416.40887 -400.036284)
		(width 0.14732)
		(layer "In13.Cu")
		(net "P5E_CPU0_PE2_RX_DN<1>")
	)
	(segment
		(start 370.106956 -219.829634)
		(end 370.105432 -219.830396)
		(width 0.0889)
		(layer "In13.Cu")
		(net "P5E_CPU0_PE2_RX_DN<1>")
	)
	(segment
		(start 411.587442 -421.93464)
		(end 411.76067 -421.609266)
		(width 0.14732)
		(layer "In13.Cu")
		(net "P5E_CPU0_PE2_RX_DN<1>")
	)
	(segment
		(start 371.659658 -213.142068)
		(end 371.659658 -213.164166)
		(width 0.0889)
		(layer "In13.Cu")
		(net "P5E_CPU0_PE2_RX_DN<1>")
	)
	(segment
		(start 370.106956 -221.45752)
		(end 370.105432 -221.458282)
		(width 0.0889)
		(layer "In13.Cu")
		(net "P5E_CPU0_PE2_RX_DN<1>")
	)
	(segment
		(start 382.057148 -199.85609)
		(end 381.229362 -199.85609)
		(width 0.14732)
		(layer "In13.Cu")
		(net "P5E_CPU0_PE2_RX_DN<1>")
	)
	(segment
		(start 404.18512 -253.486412)
		(end 403.974808 -247.226836)
		(width 0.14732)
		(layer "In13.Cu")
		(net "P5E_CPU0_PE2_RX_DN<1>")
	)
	(segment
		(start 411.70098 -421.413432)
		(end 413.076136 -418.83584)
		(width 0.14732)
		(layer "In13.Cu")
		(net "P5E_CPU0_PE2_RX_DN<1>")
	)
	(segment
		(start 370.105432 -217.554048)
		(end 370.114322 -217.559128)
		(width 0.0889)
		(layer "In13.Cu")
		(net "P5E_CPU0_PE2_RX_DN<1>")
	)
	(segment
		(start 371.701822 -213.20633)
		(end 371.701822 -213.858602)
		(width 0.0889)
		(layer "In13.Cu")
		(net "P5E_CPU0_PE2_RX_DN<1>")
	)
	(segment
		(start 370.916454 -214.813134)
		(end 370.762784 -215.183974)
		(width 0.0889)
		(layer "In13.Cu")
		(net "P5E_CPU0_PE2_RX_DN<1>")
	)
	(segment
		(start 417.75507 -411.284928)
		(end 417.75507 -406.02789)
		(width 0.14732)
		(layer "In13.Cu")
		(net "P5E_CPU0_PE2_RX_DN<1>")
	)
	(segment
		(start 410.066236 -433.564792)
		(end 410.066236 -424.480482)
		(width 0.14732)
		(layer "In13.Cu")
		(net "P5E_CPU0_PE2_RX_DN<1>")
	)
	(segment
		(start 371.659658 -211.280248)
		(end 371.659658 -213.142068)
		(width 0.14732)
		(layer "In13.Cu")
		(net "P5E_CPU0_PE2_RX_DN<1>")
	)
	(segment
		(start 405.81707 -348.650306)
		(end 407.426668 -339.696044)
		(width 0.14732)
		(layer "In13.Cu")
		(net "P5E_CPU0_PE2_RX_DN<1>")
	)
	(segment
		(start 380.40437 -200.19772)
		(end 379.068584 -201.533506)
		(width 0.14732)
		(layer "In13.Cu")
		(net "P5E_CPU0_PE2_RX_DN<1>")
	)
	(segment
		(start 410.750004 -433.289964)
		(end 410.74975 -433.289964)
		(width 0.14732)
		(layer "In13.Cu")
		(net "P5E_CPU0_PE2_RX_DN<1>")
	)
	(segment
		(start 370.114322 -221.453202)
		(end 370.106956 -221.45752)
		(width 0.0889)
		(layer "In13.Cu")
		(net "P5E_CPU0_PE2_RX_DN<1>")
	)
	(segment
		(start 370.762784 -215.183974)
		(end 370.762784 -215.43645)
		(width 0.0889)
		(layer "In13.Cu")
		(net "P5E_CPU0_PE2_RX_DN<1>")
	)
	(segment
		(start 379.068584 -201.533506)
		(end 372.51767 -209.000852)
		(width 0.14732)
		(layer "In13.Cu")
		(net "P5E_CPU0_PE2_RX_DN<1>")
	)
	(segment
		(start 411.166056 -422.416986)
		(end 411.391354 -421.99433)
		(width 0.14732)
		(layer "In13.Cu")
		(net "P5E_CPU0_PE2_RX_DN<1>")
	)
	(segment
		(start 371.701822 -213.858602)
		(end 371.58168 -214.147654)
		(width 0.0889)
		(layer "In13.Cu")
		(net "P5E_CPU0_PE2_RX_DN<1>")
	)
	(segment
		(start 370.105432 -219.18168)
		(end 370.114322 -219.18676)
		(width 0.0889)
		(layer "In13.Cu")
		(net "P5E_CPU0_PE2_RX_DN<1>")
	)
	(segment
		(start 396.778226 -211.554568)
		(end 386.175758 -200.668128)
		(width 0.14732)
		(layer "In13.Cu")
		(net "P5E_CPU0_PE2_RX_DN<1>")
	)
	(segment
		(start 405.578564 -366.992916)
		(end 405.81707 -348.650306)
		(width 0.14732)
		(layer "In13.Cu")
		(net "P5E_CPU0_PE2_RX_DN<1>")
	)
	(segment
		(start 410.17444 -433.672996)
		(end 410.066236 -433.564792)
		(width 0.14732)
		(layer "In13.Cu")
		(net "P5E_CPU0_PE2_RX_DN<1>")
	)
	(segment
		(start 381.229362 -199.85609)
		(end 380.40437 -200.19772)
		(width 0.14732)
		(layer "In13.Cu")
		(net "P5E_CPU0_PE2_RX_DN<1>")
	)
	(segment
		(start 370.292884 -216.235026)
		(end 370.292884 -216.25052)
		(width 0.0889)
		(layer "In13.Cu")
		(net "P5E_CPU0_PE2_RX_DN<1>")
	)
	(segment
		(start 370.583968 -215.755982)
		(end 370.575078 -215.761062)
		(width 0.0889)
		(layer "In13.Cu")
		(net "P5E_CPU0_PE2_RX_DN<1>")
	)
	(segment
		(start 413.076136 -418.83584)
		(end 417.75507 -411.284928)
		(width 0.14732)
		(layer "In13.Cu")
		(net "P5E_CPU0_PE2_RX_DN<1>")
	)
	(segment
		(start 407.426668 -339.696044)
		(end 400.069812 -307.56479)
		(width 0.14732)
		(layer "In13.Cu")
		(net "P5E_CPU0_PE2_RX_DN<1>")
	)
	(segment
		(start 411.165802 -422.417494)
		(end 411.166056 -422.416986)
		(width 0.14732)
		(layer "In13.Cu")
		(net "P5E_CPU0_PE2_RX_DN<1>")
	)
	(segment
		(start 406.048464 -370.013738)
		(end 405.578564 -366.992916)
		(width 0.14732)
		(layer "In13.Cu")
		(net "P5E_CPU0_PE2_RX_DN<1>")
	)
	(segment
		(start 370.106956 -216.574116)
		(end 370.105432 -216.574878)
		(width 0.0889)
		(layer "In13.Cu")
		(net "P5E_CPU0_PE2_RX_DN<1>")
	)
	(segment
		(start 369.82273 -220.319854)
		(end 369.82273 -220.334078)
		(width 0.0889)
		(layer "In13.Cu")
		(net "P5E_CPU0_PE2_RX_DN<1>")
	)
	(segment
		(start 370.105432 -216.574878)
		(end 370.099336 -216.578434)
		(width 0.0889)
		(layer "In13.Cu")
		(net "P5E_CPU0_PE2_RX_DN<1>")
	)
	(arc
		(start 370.114322 -220.814646)
		(mid 370.29304 -221.133924)
		(end 370.114322 -221.453202)
		(width 0.0889)
		(layer "In13.Cu")
		(net "P5E_CPU0_PE2_RX_DN<1>")
	)
	(arc
		(start 370.099336 -216.578434)
		(mid 369.896749 -216.784785)
		(end 369.82273 -217.064336)
		(width 0.0889)
		(layer "In13.Cu")
		(net "P5E_CPU0_PE2_RX_DN<1>")
	)
	(arc
		(start 370.76253 -215.436704)
		(mid 370.714851 -215.619604)
		(end 370.583968 -215.755982)
		(width 0.0889)
		(layer "In13.Cu")
		(net "P5E_CPU0_PE2_RX_DN<1>")
	)
	(arc
		(start 370.292884 -216.25052)
		(mid 370.245205 -216.43342)
		(end 370.114322 -216.569798)
		(width 0.0889)
		(layer "In13.Cu")
		(net "P5E_CPU0_PE2_RX_DN<1>")
	)
	(arc
		(start 369.82273 -220.334078)
		(mid 369.901949 -220.608763)
		(end 370.105432 -220.809566)
		(width 0.0889)
		(layer "In13.Cu")
		(net "P5E_CPU0_PE2_RX_DN<1>")
	)
	(arc
		(start 370.105432 -221.458282)
		(mid 369.946944 -221.507215)
		(end 369.782852 -221.48292)
		(width 0.0889)
		(layer "In13.Cu")
		(net "P5E_CPU0_PE2_RX_DN<1>")
	)
	(arc
		(start 369.82273 -217.07856)
		(mid 369.901949 -217.353245)
		(end 370.105432 -217.554048)
		(width 0.0889)
		(layer "In13.Cu")
		(net "P5E_CPU0_PE2_RX_DN<1>")
	)
	(arc
		(start 370.114322 -217.559128)
		(mid 370.29304 -217.878406)
		(end 370.114322 -218.197684)
		(width 0.0889)
		(layer "In13.Cu")
		(net "P5E_CPU0_PE2_RX_DN<1>")
	)
	(arc
		(start 370.099336 -219.833952)
		(mid 369.896749 -220.040303)
		(end 369.82273 -220.319854)
		(width 0.0889)
		(layer "In13.Cu")
		(net "P5E_CPU0_PE2_RX_DN<1>")
	)
	(arc
		(start 370.099336 -218.20632)
		(mid 369.822762 -218.692222)
		(end 370.099336 -219.178124)
		(width 0.0889)
		(layer "In13.Cu")
		(net "P5E_CPU0_PE2_RX_DN<1>")
	)
	(arc
		(start 370.114322 -219.18676)
		(mid 370.292919 -219.506038)
		(end 370.114322 -219.825316)
		(width 0.0889)
		(layer "In13.Cu")
		(net "P5E_CPU0_PE2_RX_DN<1>")
	)
	(arc
		(start 370.575078 -215.761062)
		(mid 370.372255 -215.961293)
		(end 370.292884 -216.235026)
		(width 0.0889)
		(layer "In13.Cu")
		(net "P5E_CPU0_PE2_RX_DN<1>")
	)
	(segment
		(start 383.07518 -221.669864)
		(end 383.07518 -221.134178)
		(width 0.13208)
		(layer "F.Cu")
		(net "P5E_CPU0_PE2_RX_DN<15>")
	)
	(segment
		(start 383.07518 -221.134178)
		(end 383.075434 -221.133924)
		(width 0.13208)
		(layer "F.Cu")
		(net "P5E_CPU0_PE2_RX_DN<15>")
	)
	(segment
		(start 377.620022 -419.516814)
		(end 377.725432 -419.349682)
		(width 0.14732)
		(layer "In13.Cu")
		(net "P5E_CPU0_PE2_RX_DN<15>")
	)
	(segment
		(start 377.901708 -420.12489)
		(end 377.734322 -420.019734)
		(width 0.14732)
		(layer "In13.Cu")
		(net "P5E_CPU0_PE2_RX_DN<15>")
	)
	(segment
		(start 389.264906 -259.66928)
		(end 388.45236 -257.119374)
		(width 0.14732)
		(layer "In13.Cu")
		(net "P5E_CPU0_PE2_RX_DN<15>")
	)
	(segment
		(start 385.354576 -225.616516)
		(end 385.354576 -225.61677)
		(width 0.0889)
		(layer "In13.Cu")
		(net "P5E_CPU0_PE2_RX_DN<15>")
	)
	(segment
		(start 384.301238 -223.902016)
		(end 384.298444 -223.900492)
		(width 0.0889)
		(layer "In13.Cu")
		(net "P5E_CPU0_PE2_RX_DN<15>")
	)
	(segment
		(start 385.750308 -226.012502)
		(end 385.35483 -225.61677)
		(width 0.0889)
		(layer "In13.Cu")
		(net "P5E_CPU0_PE2_RX_DN<15>")
	)
	(segment
		(start 377.643898 -418.990272)
		(end 377.476258 -418.885116)
		(width 0.14732)
		(layer "In13.Cu")
		(net "P5E_CPU0_PE2_RX_DN<15>")
	)
	(segment
		(start 380.792736 -433.475892)
		(end 377.878086 -420.651432)
		(width 0.14732)
		(layer "In13.Cu")
		(net "P5E_CPU0_PE2_RX_DN<15>")
	)
	(segment
		(start 373.52351 -404.705566)
		(end 373.52351 -400.47037)
		(width 0.14732)
		(layer "In13.Cu")
		(net "P5E_CPU0_PE2_RX_DN<15>")
	)
	(segment
		(start 393.479782 -339.30844)
		(end 386.501894 -310.496458)
		(width 0.14732)
		(layer "In13.Cu")
		(net "P5E_CPU0_PE2_RX_DN<15>")
	)
	(segment
		(start 373.863362 -399.254726)
		(end 391.13587 -353.675696)
		(width 0.14732)
		(layer "In13.Cu")
		(net "P5E_CPU0_PE2_RX_DN<15>")
	)
	(segment
		(start 386.501894 -310.496458)
		(end 388.403592 -271.531334)
		(width 0.14732)
		(layer "In13.Cu")
		(net "P5E_CPU0_PE2_RX_DN<15>")
	)
	(segment
		(start 383.352294 -222.268796)
		(end 383.349246 -222.267018)
		(width 0.0889)
		(layer "In13.Cu")
		(net "P5E_CPU0_PE2_RX_DN<15>")
	)
	(segment
		(start 376.398536 -414.142174)
		(end 374.86971 -410.451808)
		(width 0.14732)
		(layer "In13.Cu")
		(net "P5E_CPU0_PE2_RX_DN<15>")
	)
	(segment
		(start 386.317236 -226.520248)
		(end 385.825238 -226.028504)
		(width 0.14732)
		(layer "In13.Cu")
		(net "P5E_CPU0_PE2_RX_DN<15>")
	)
	(segment
		(start 384.303778 -223.90354)
		(end 384.301238 -223.902016)
		(width 0.0889)
		(layer "In13.Cu")
		(net "P5E_CPU0_PE2_RX_DN<15>")
	)
	(segment
		(start 384.767836 -224.7138)
		(end 384.758946 -224.70872)
		(width 0.0889)
		(layer "In13.Cu")
		(net "P5E_CPU0_PE2_RX_DN<15>")
	)
	(segment
		(start 381.069342 -433.752752)
		(end 380.792736 -433.475892)
		(width 0.14732)
		(layer "In13.Cu")
		(net "P5E_CPU0_PE2_RX_DN<15>")
	)
	(segment
		(start 391.13587 -353.675696)
		(end 393.479782 -339.30844)
		(width 0.14732)
		(layer "In13.Cu")
		(net "P5E_CPU0_PE2_RX_DN<15>")
	)
	(segment
		(start 385.237736 -225.527362)
		(end 385.223512 -225.519234)
		(width 0.0889)
		(layer "In13.Cu")
		(net "P5E_CPU0_PE2_RX_DN<15>")
	)
	(segment
		(start 385.825238 -226.028504)
		(end 385.824984 -226.028504)
		(width 0.0889)
		(layer "In13.Cu")
		(net "P5E_CPU0_PE2_RX_DN<15>")
	)
	(segment
		(start 387.081268 -255.161796)
		(end 386.42163 -253.56947)
		(width 0.14732)
		(layer "In13.Cu")
		(net "P5E_CPU0_PE2_RX_DN<15>")
	)
	(segment
		(start 377.734322 -420.019734)
		(end 377.620022 -419.516814)
		(width 0.14732)
		(layer "In13.Cu")
		(net "P5E_CPU0_PE2_RX_DN<15>")
	)
	(segment
		(start 385.050284 -225.203258)
		(end 385.050284 -225.193352)
		(width 0.0889)
		(layer "In13.Cu")
		(net "P5E_CPU0_PE2_RX_DN<15>")
	)
	(segment
		(start 377.340622 -418.286692)
		(end 377.446032 -418.11956)
		(width 0.14732)
		(layer "In13.Cu")
		(net "P5E_CPU0_PE2_RX_DN<15>")
	)
	(segment
		(start 382.9431 -221.494096)
		(end 382.91897 -221.404942)
		(width 0.0889)
		(layer "In13.Cu")
		(net "P5E_CPU0_PE2_RX_DN<15>")
	)
	(segment
		(start 388.45236 -257.119374)
		(end 387.081268 -255.161796)
		(width 0.14732)
		(layer "In13.Cu")
		(net "P5E_CPU0_PE2_RX_DN<15>")
	)
	(segment
		(start 383.640584 -222.761556)
		(end 383.640584 -222.75165)
		(width 0.0889)
		(layer "In13.Cu")
		(net "P5E_CPU0_PE2_RX_DN<15>")
	)
	(segment
		(start 381.287274 -433.752752)
		(end 381.069342 -433.752752)
		(width 0.14732)
		(layer "In13.Cu")
		(net "P5E_CPU0_PE2_RX_DN<15>")
	)
	(segment
		(start 386.52069 -246.008398)
		(end 386.785358 -231.942132)
		(width 0.14732)
		(layer "In13.Cu")
		(net "P5E_CPU0_PE2_RX_DN<15>")
	)
	(segment
		(start 382.91897 -221.404942)
		(end 383.075434 -221.133924)
		(width 0.0889)
		(layer "In13.Cu")
		(net "P5E_CPU0_PE2_RX_DN<15>")
	)
	(segment
		(start 388.403592 -271.531334)
		(end 389.264906 -259.66928)
		(width 0.14732)
		(layer "In13.Cu")
		(net "P5E_CPU0_PE2_RX_DN<15>")
	)
	(segment
		(start 385.35483 -225.61677)
		(end 385.354576 -225.616516)
		(width 0.0889)
		(layer "In13.Cu")
		(net "P5E_CPU0_PE2_RX_DN<15>")
	)
	(segment
		(start 374.86971 -406.051766)
		(end 373.52351 -404.705566)
		(width 0.14732)
		(layer "In13.Cu")
		(net "P5E_CPU0_PE2_RX_DN<15>")
	)
	(segment
		(start 373.52351 -400.47037)
		(end 373.863362 -399.254726)
		(width 0.14732)
		(layer "In13.Cu")
		(net "P5E_CPU0_PE2_RX_DN<15>")
	)
	(segment
		(start 377.196858 -417.654994)
		(end 376.398536 -414.142174)
		(width 0.14732)
		(layer "In13.Cu")
		(net "P5E_CPU0_PE2_RX_DN<15>")
	)
	(segment
		(start 384.298444 -223.900492)
		(end 384.297682 -223.899984)
		(width 0.0889)
		(layer "In13.Cu")
		(net "P5E_CPU0_PE2_RX_DN<15>")
	)
	(segment
		(start 385.750816 -226.01301)
		(end 385.750308 -226.012502)
		(width 0.0889)
		(layer "In13.Cu")
		(net "P5E_CPU0_PE2_RX_DN<15>")
	)
	(segment
		(start 381.750062 -433.289964)
		(end 381.287274 -433.752752)
		(width 0.14732)
		(layer "In13.Cu")
		(net "P5E_CPU0_PE2_RX_DN<15>")
	)
	(segment
		(start 386.785358 -231.942132)
		(end 386.317236 -226.520248)
		(width 0.14732)
		(layer "In13.Cu")
		(net "P5E_CPU0_PE2_RX_DN<15>")
	)
	(segment
		(start 377.725432 -419.349682)
		(end 377.643898 -418.990272)
		(width 0.14732)
		(layer "In13.Cu")
		(net "P5E_CPU0_PE2_RX_DN<15>")
	)
	(segment
		(start 385.824984 -226.028504)
		(end 385.80949 -226.01301)
		(width 0.0889)
		(layer "In13.Cu")
		(net "P5E_CPU0_PE2_RX_DN<15>")
	)
	(segment
		(start 377.364244 -417.76015)
		(end 377.196858 -417.654994)
		(width 0.14732)
		(layer "In13.Cu")
		(net "P5E_CPU0_PE2_RX_DN<15>")
	)
	(segment
		(start 383.357374 -222.27159)
		(end 383.352294 -222.268796)
		(width 0.0889)
		(layer "In13.Cu")
		(net "P5E_CPU0_PE2_RX_DN<15>")
	)
	(segment
		(start 377.878086 -420.651432)
		(end 377.983242 -420.4843)
		(width 0.14732)
		(layer "In13.Cu")
		(net "P5E_CPU0_PE2_RX_DN<15>")
	)
	(segment
		(start 383.828036 -223.085914)
		(end 383.819146 -223.080834)
		(width 0.0889)
		(layer "In13.Cu")
		(net "P5E_CPU0_PE2_RX_DN<15>")
	)
	(segment
		(start 385.452112 -250.579636)
		(end 385.891786 -248.087896)
		(width 0.14732)
		(layer "In13.Cu")
		(net "P5E_CPU0_PE2_RX_DN<15>")
	)
	(segment
		(start 385.80949 -226.01301)
		(end 385.750816 -226.01301)
		(width 0.0889)
		(layer "In13.Cu")
		(net "P5E_CPU0_PE2_RX_DN<15>")
	)
	(segment
		(start 385.830572 -252.725174)
		(end 385.452112 -250.579636)
		(width 0.14732)
		(layer "In13.Cu")
		(net "P5E_CPU0_PE2_RX_DN<15>")
	)
	(segment
		(start 377.476512 -418.884862)
		(end 377.340622 -418.286692)
		(width 0.14732)
		(layer "In13.Cu")
		(net "P5E_CPU0_PE2_RX_DN<15>")
	)
	(segment
		(start 377.983242 -420.4843)
		(end 377.901708 -420.12489)
		(width 0.14732)
		(layer "In13.Cu")
		(net "P5E_CPU0_PE2_RX_DN<15>")
	)
	(segment
		(start 374.86971 -410.451808)
		(end 374.86971 -406.051766)
		(width 0.14732)
		(layer "In13.Cu")
		(net "P5E_CPU0_PE2_RX_DN<15>")
	)
	(segment
		(start 386.42163 -253.56947)
		(end 385.830572 -252.725174)
		(width 0.14732)
		(layer "In13.Cu")
		(net "P5E_CPU0_PE2_RX_DN<15>")
	)
	(segment
		(start 383.358136 -222.272098)
		(end 383.357374 -222.27159)
		(width 0.0889)
		(layer "In13.Cu")
		(net "P5E_CPU0_PE2_RX_DN<15>")
	)
	(segment
		(start 384.110484 -223.584262)
		(end 384.110484 -223.557084)
		(width 0.0889)
		(layer "In13.Cu")
		(net "P5E_CPU0_PE2_RX_DN<15>")
	)
	(segment
		(start 377.446032 -418.11956)
		(end 377.364244 -417.76015)
		(width 0.14732)
		(layer "In13.Cu")
		(net "P5E_CPU0_PE2_RX_DN<15>")
	)
	(segment
		(start 385.891786 -248.087896)
		(end 386.52069 -246.008398)
		(width 0.14732)
		(layer "In13.Cu")
		(net "P5E_CPU0_PE2_RX_DN<15>")
	)
	(segment
		(start 377.476258 -418.885116)
		(end 377.476512 -418.884862)
		(width 0.14732)
		(layer "In13.Cu")
		(net "P5E_CPU0_PE2_RX_DN<15>")
	)
	(arc
		(start 385.050284 -225.193352)
		(mid 384.972173 -224.916403)
		(end 384.767836 -224.7138)
		(width 0.0889)
		(layer "In13.Cu")
		(net "P5E_CPU0_PE2_RX_DN<15>")
	)
	(arc
		(start 384.110484 -223.557084)
		(mid 384.030322 -223.284895)
		(end 383.828036 -223.085914)
		(width 0.0889)
		(layer "In13.Cu")
		(net "P5E_CPU0_PE2_RX_DN<15>")
	)
	(arc
		(start 383.640584 -222.75165)
		(mid 383.562473 -222.474701)
		(end 383.358136 -222.272098)
		(width 0.0889)
		(layer "In13.Cu")
		(net "P5E_CPU0_PE2_RX_DN<15>")
	)
	(arc
		(start 384.758946 -224.70872)
		(mid 384.628032 -224.57236)
		(end 384.580384 -224.389442)
		(width 0.0889)
		(layer "In13.Cu")
		(net "P5E_CPU0_PE2_RX_DN<15>")
	)
	(arc
		(start 383.170684 -221.94774)
		(mid 383.115313 -221.703461)
		(end 382.959864 -221.50705)
		(width 0.0889)
		(layer "In13.Cu")
		(net "P5E_CPU0_PE2_RX_DN<15>")
	)
	(arc
		(start 384.297682 -223.899984)
		(mid 384.162749 -223.76663)
		(end 384.110484 -223.584262)
		(width 0.0889)
		(layer "In13.Cu")
		(net "P5E_CPU0_PE2_RX_DN<15>")
	)
	(arc
		(start 385.354576 -225.61677)
		(mid 385.342922 -225.605553)
		(end 385.330954 -225.594672)
		(width 0.0889)
		(layer "In13.Cu")
		(net "P5E_CPU0_PE2_RX_DN<15>")
	)
	(arc
		(start 382.959864 -221.50705)
		(mid 382.951542 -221.500495)
		(end 382.9431 -221.494096)
		(width 0.0889)
		(layer "In13.Cu")
		(net "P5E_CPU0_PE2_RX_DN<15>")
	)
	(arc
		(start 385.330954 -225.594672)
		(mid 385.286061 -225.558641)
		(end 385.237736 -225.527362)
		(width 0.0889)
		(layer "In13.Cu")
		(net "P5E_CPU0_PE2_RX_DN<15>")
	)
	(arc
		(start 383.819146 -223.080834)
		(mid 383.688232 -222.944474)
		(end 383.640584 -222.761556)
		(width 0.0889)
		(layer "In13.Cu")
		(net "P5E_CPU0_PE2_RX_DN<15>")
	)
	(arc
		(start 384.580384 -224.389442)
		(mid 384.506393 -224.109876)
		(end 384.303778 -223.90354)
		(width 0.0889)
		(layer "In13.Cu")
		(net "P5E_CPU0_PE2_RX_DN<15>")
	)
	(arc
		(start 385.223512 -225.519234)
		(mid 385.096469 -225.383418)
		(end 385.050284 -225.203258)
		(width 0.0889)
		(layer "In13.Cu")
		(net "P5E_CPU0_PE2_RX_DN<15>")
	)
	(arc
		(start 383.349246 -222.267018)
		(mid 383.218332 -222.130658)
		(end 383.170684 -221.94774)
		(width 0.0889)
		(layer "In13.Cu")
		(net "P5E_CPU0_PE2_RX_DN<15>")
	)
	(segment
		(start 381.665734 -220.855794)
		(end 381.665734 -220.319854)
		(width 0.13208)
		(layer "F.Cu")
		(net "P5E_CPU0_PE2_RX_DN<14>")
	)
	(segment
		(start 382.430528 -220.651832)
		(end 382.41859 -220.644974)
		(width 0.0889)
		(layer "In13.Cu")
		(net "P5E_CPU0_PE2_RX_DN<14>")
	)
	(segment
		(start 387.44144 -226.38512)
		(end 387.39953 -226.34321)
		(width 0.0889)
		(layer "In13.Cu")
		(net "P5E_CPU0_PE2_RX_DN<14>")
	)
	(segment
		(start 385.245356 -223.90481)
		(end 385.236466 -223.89973)
		(width 0.0889)
		(layer "In13.Cu")
		(net "P5E_CPU0_PE2_RX_DN<14>")
	)
	(segment
		(start 389.512048 -256.677414)
		(end 389.49884 -256.63017)
		(width 0.14732)
		(layer "In13.Cu")
		(net "P5E_CPU0_PE2_RX_DN<14>")
	)
	(segment
		(start 387.849618 -247.946672)
		(end 388.469632 -247.552464)
		(width 0.14732)
		(layer "In13.Cu")
		(net "P5E_CPU0_PE2_RX_DN<14>")
	)
	(segment
		(start 376.852434 -399.111724)
		(end 392.135106 -353.780852)
		(width 0.14732)
		(layer "In13.Cu")
		(net "P5E_CPU0_PE2_RX_DN<14>")
	)
	(segment
		(start 387.178804 -251.20854)
		(end 387.178804 -248.504456)
		(width 0.14732)
		(layer "In13.Cu")
		(net "P5E_CPU0_PE2_RX_DN<14>")
	)
	(segment
		(start 394.485622 -339.278468)
		(end 387.45795 -310.384698)
		(width 0.14732)
		(layer "In13.Cu")
		(net "P5E_CPU0_PE2_RX_DN<14>")
	)
	(segment
		(start 387.472428 -248.210832)
		(end 387.849618 -247.946672)
		(width 0.14732)
		(layer "In13.Cu")
		(net "P5E_CPU0_PE2_RX_DN<14>")
	)
	(segment
		(start 387.800596 -227.967032)
		(end 387.709918 -227.53955)
		(width 0.14732)
		(layer "In13.Cu")
		(net "P5E_CPU0_PE2_RX_DN<14>")
	)
	(segment
		(start 377.93295 -410.668978)
		(end 377.93295 -406.051766)
		(width 0.14732)
		(layer "In13.Cu")
		(net "P5E_CPU0_PE2_RX_DN<14>")
	)
	(segment
		(start 392.135106 -353.780852)
		(end 394.485622 -339.278468)
		(width 0.14732)
		(layer "In13.Cu")
		(net "P5E_CPU0_PE2_RX_DN<14>")
	)
	(segment
		(start 383.368296 -220.650816)
		(end 383.357374 -220.644466)
		(width 0.0889)
		(layer "In13.Cu")
		(net "P5E_CPU0_PE2_RX_DN<14>")
	)
	(segment
		(start 381.822198 -220.590872)
		(end 381.665734 -220.319854)
		(width 0.0889)
		(layer "In13.Cu")
		(net "P5E_CPU0_PE2_RX_DN<14>")
	)
	(segment
		(start 383.06629 -434.595016)
		(end 383.06629 -424.666156)
		(width 0.14732)
		(layer "In13.Cu")
		(net "P5E_CPU0_PE2_RX_DN<14>")
	)
	(segment
		(start 387.127496 -225.533966)
		(end 387.116828 -225.527616)
		(width 0.0889)
		(layer "In13.Cu")
		(net "P5E_CPU0_PE2_RX_DN<14>")
	)
	(segment
		(start 387.178804 -248.504456)
		(end 387.472428 -248.210832)
		(width 0.14732)
		(layer "In13.Cu")
		(net "P5E_CPU0_PE2_RX_DN<14>")
	)
	(segment
		(start 384.297936 -222.272606)
		(end 384.29311 -222.269558)
		(width 0.0889)
		(layer "In13.Cu")
		(net "P5E_CPU0_PE2_RX_DN<14>")
	)
	(segment
		(start 388.191502 -254.154178)
		(end 387.178804 -251.20854)
		(width 0.14732)
		(layer "In13.Cu")
		(net "P5E_CPU0_PE2_RX_DN<14>")
	)
	(segment
		(start 377.93295 -406.051766)
		(end 376.58675 -404.705566)
		(width 0.14732)
		(layer "In13.Cu")
		(net "P5E_CPU0_PE2_RX_DN<14>")
	)
	(segment
		(start 386.92963 -225.211132)
		(end 386.92963 -225.203258)
		(width 0.0889)
		(layer "In13.Cu")
		(net "P5E_CPU0_PE2_RX_DN<14>")
	)
	(segment
		(start 388.469632 -247.552464)
		(end 389.496046 -244.340634)
		(width 0.14732)
		(layer "In13.Cu")
		(net "P5E_CPU0_PE2_RX_DN<14>")
	)
	(segment
		(start 381.43815 -419.820344)
		(end 381.258572 -419.737286)
		(width 0.14732)
		(layer "In13.Cu")
		(net "P5E_CPU0_PE2_RX_DN<14>")
	)
	(segment
		(start 387.45795 -310.384698)
		(end 390.289542 -259.488178)
		(width 0.14732)
		(layer "In13.Cu")
		(net "P5E_CPU0_PE2_RX_DN<14>")
	)
	(segment
		(start 383.06629 -424.666156)
		(end 381.481838 -420.345616)
		(width 0.14732)
		(layer "In13.Cu")
		(net "P5E_CPU0_PE2_RX_DN<14>")
	)
	(segment
		(start 387.706616 -228.111558)
		(end 387.800596 -227.967032)
		(width 0.14732)
		(layer "In13.Cu")
		(net "P5E_CPU0_PE2_RX_DN<14>")
	)
	(segment
		(start 384.109976 -221.94774)
		(end 384.109976 -221.937072)
		(width 0.0889)
		(layer "In13.Cu")
		(net "P5E_CPU0_PE2_RX_DN<14>")
	)
	(segment
		(start 383.19075 -434.719476)
		(end 383.06629 -434.595016)
		(width 0.14732)
		(layer "In13.Cu")
		(net "P5E_CPU0_PE2_RX_DN<14>")
	)
	(segment
		(start 381.911352 -220.614748)
		(end 381.822198 -220.590872)
		(width 0.0889)
		(layer "In13.Cu")
		(net "P5E_CPU0_PE2_RX_DN<14>")
	)
	(segment
		(start 385.236466 -223.89973)
		(end 385.22783 -223.894396)
		(width 0.0889)
		(layer "In13.Cu")
		(net "P5E_CPU0_PE2_RX_DN<14>")
	)
	(segment
		(start 384.777742 -223.092518)
		(end 384.767074 -223.086168)
		(width 0.0889)
		(layer "In13.Cu")
		(net "P5E_CPU0_PE2_RX_DN<14>")
	)
	(segment
		(start 376.58675 -404.705566)
		(end 376.58675 -400.5453)
		(width 0.14732)
		(layer "In13.Cu")
		(net "P5E_CPU0_PE2_RX_DN<14>")
	)
	(segment
		(start 387.709918 -227.53955)
		(end 387.565138 -227.44557)
		(width 0.14732)
		(layer "In13.Cu")
		(net "P5E_CPU0_PE2_RX_DN<14>")
	)
	(segment
		(start 383.64033 -221.141798)
		(end 383.64033 -221.133924)
		(width 0.0889)
		(layer "In13.Cu")
		(net "P5E_CPU0_PE2_RX_DN<14>")
	)
	(segment
		(start 389.511794 -256.677414)
		(end 389.512048 -256.677414)
		(width 0.14732)
		(layer "In13.Cu")
		(net "P5E_CPU0_PE2_RX_DN<14>")
	)
	(segment
		(start 389.496046 -244.340634)
		(end 388.223252 -230.548688)
		(width 0.14732)
		(layer "In13.Cu")
		(net "P5E_CPU0_PE2_RX_DN<14>")
	)
	(segment
		(start 385.51993 -224.397316)
		(end 385.51993 -224.389442)
		(width 0.0889)
		(layer "In13.Cu")
		(net "P5E_CPU0_PE2_RX_DN<14>")
	)
	(segment
		(start 388.868666 -255.752854)
		(end 388.191502 -254.154178)
		(width 0.14732)
		(layer "In13.Cu")
		(net "P5E_CPU0_PE2_RX_DN<14>")
	)
	(segment
		(start 387.44144 -226.861116)
		(end 387.44144 -226.407218)
		(width 0.14732)
		(layer "In13.Cu")
		(net "P5E_CPU0_PE2_RX_DN<14>")
	)
	(segment
		(start 387.565138 -227.44557)
		(end 387.44144 -226.861116)
		(width 0.14732)
		(layer "In13.Cu")
		(net "P5E_CPU0_PE2_RX_DN<14>")
	)
	(segment
		(start 381.911606 -220.615256)
		(end 381.911352 -220.614748)
		(width 0.0889)
		(layer "In13.Cu")
		(net "P5E_CPU0_PE2_RX_DN<14>")
	)
	(segment
		(start 384.579876 -222.776542)
		(end 384.579876 -222.750888)
		(width 0.0889)
		(layer "In13.Cu")
		(net "P5E_CPU0_PE2_RX_DN<14>")
	)
	(segment
		(start 383.750058 -434.289962)
		(end 383.320544 -434.719476)
		(width 0.14732)
		(layer "In13.Cu")
		(net "P5E_CPU0_PE2_RX_DN<14>")
	)
	(segment
		(start 386.657596 -224.72015)
		(end 386.646674 -224.7138)
		(width 0.0889)
		(layer "In13.Cu")
		(net "P5E_CPU0_PE2_RX_DN<14>")
	)
	(segment
		(start 387.39953 -226.34321)
		(end 387.39953 -226.01682)
		(width 0.0889)
		(layer "In13.Cu")
		(net "P5E_CPU0_PE2_RX_DN<14>")
	)
	(segment
		(start 385.250944 -223.908112)
		(end 385.245356 -223.90481)
		(width 0.0889)
		(layer "In13.Cu")
		(net "P5E_CPU0_PE2_RX_DN<14>")
	)
	(segment
		(start 383.320544 -434.719476)
		(end 383.19075 -434.719476)
		(width 0.14732)
		(layer "In13.Cu")
		(net "P5E_CPU0_PE2_RX_DN<14>")
	)
	(segment
		(start 388.223252 -230.548688)
		(end 387.706616 -228.111558)
		(width 0.14732)
		(layer "In13.Cu")
		(net "P5E_CPU0_PE2_RX_DN<14>")
	)
	(segment
		(start 381.481838 -420.345616)
		(end 381.564896 -420.166292)
		(width 0.14732)
		(layer "In13.Cu")
		(net "P5E_CPU0_PE2_RX_DN<14>")
	)
	(segment
		(start 387.44144 -226.407218)
		(end 387.44144 -226.38512)
		(width 0.0889)
		(layer "In13.Cu")
		(net "P5E_CPU0_PE2_RX_DN<14>")
	)
	(segment
		(start 389.49884 -256.63017)
		(end 388.868666 -255.752854)
		(width 0.14732)
		(layer "In13.Cu")
		(net "P5E_CPU0_PE2_RX_DN<14>")
	)
	(segment
		(start 390.289542 -259.488178)
		(end 389.511794 -256.677414)
		(width 0.14732)
		(layer "In13.Cu")
		(net "P5E_CPU0_PE2_RX_DN<14>")
	)
	(segment
		(start 376.58675 -400.5453)
		(end 376.852434 -399.111724)
		(width 0.14732)
		(layer "In13.Cu")
		(net "P5E_CPU0_PE2_RX_DN<14>")
	)
	(segment
		(start 381.564896 -420.166292)
		(end 381.43815 -419.820344)
		(width 0.14732)
		(layer "In13.Cu")
		(net "P5E_CPU0_PE2_RX_DN<14>")
	)
	(segment
		(start 381.258572 -419.737286)
		(end 377.93295 -410.668978)
		(width 0.14732)
		(layer "In13.Cu")
		(net "P5E_CPU0_PE2_RX_DN<14>")
	)
	(arc
		(start 385.22783 -223.894396)
		(mid 385.09739 -223.758148)
		(end 385.049776 -223.575626)
		(width 0.0889)
		(layer "In13.Cu")
		(net "P5E_CPU0_PE2_RX_DN<14>")
	)
	(arc
		(start 386.082286 -224.714054)
		(mid 385.894834 -224.76429)
		(end 385.707382 -224.714054)
		(width 0.0889)
		(layer "In13.Cu")
		(net "P5E_CPU0_PE2_RX_DN<14>")
	)
	(arc
		(start 383.357374 -220.644466)
		(mid 383.075151 -220.569071)
		(end 382.792986 -220.64472)
		(width 0.0889)
		(layer "In13.Cu")
		(net "P5E_CPU0_PE2_RX_DN<14>")
	)
	(arc
		(start 384.109976 -221.937072)
		(mid 384.031821 -221.660676)
		(end 383.827782 -221.458536)
		(width 0.0889)
		(layer "In13.Cu")
		(net "P5E_CPU0_PE2_RX_DN<14>")
	)
	(arc
		(start 385.51993 -224.389442)
		(mid 385.448122 -224.113746)
		(end 385.250944 -223.908112)
		(width 0.0889)
		(layer "In13.Cu")
		(net "P5E_CPU0_PE2_RX_DN<14>")
	)
	(arc
		(start 387.39953 -226.01682)
		(mid 387.326776 -225.739759)
		(end 387.127496 -225.533966)
		(width 0.0889)
		(layer "In13.Cu")
		(net "P5E_CPU0_PE2_RX_DN<14>")
	)
	(arc
		(start 385.707382 -224.714054)
		(mid 385.572091 -224.580272)
		(end 385.51993 -224.397316)
		(width 0.0889)
		(layer "In13.Cu")
		(net "P5E_CPU0_PE2_RX_DN<14>")
	)
	(arc
		(start 385.049776 -223.575626)
		(mid 384.977084 -223.298421)
		(end 384.777742 -223.092518)
		(width 0.0889)
		(layer "In13.Cu")
		(net "P5E_CPU0_PE2_RX_DN<14>")
	)
	(arc
		(start 381.931418 -220.607128)
		(mid 381.921474 -220.611099)
		(end 381.911606 -220.615256)
		(width 0.0889)
		(layer "In13.Cu")
		(net "P5E_CPU0_PE2_RX_DN<14>")
	)
	(arc
		(start 387.116828 -225.527616)
		(mid 386.981783 -225.393892)
		(end 386.92963 -225.211132)
		(width 0.0889)
		(layer "In13.Cu")
		(net "P5E_CPU0_PE2_RX_DN<14>")
	)
	(arc
		(start 384.767074 -223.086168)
		(mid 384.633697 -222.955408)
		(end 384.579876 -222.776542)
		(width 0.0889)
		(layer "In13.Cu")
		(net "P5E_CPU0_PE2_RX_DN<14>")
	)
	(arc
		(start 382.41859 -220.644974)
		(mid 382.179313 -220.570694)
		(end 381.931418 -220.607128)
		(width 0.0889)
		(layer "In13.Cu")
		(net "P5E_CPU0_PE2_RX_DN<14>")
	)
	(arc
		(start 384.29311 -222.269558)
		(mid 384.15898 -222.13286)
		(end 384.109976 -221.94774)
		(width 0.0889)
		(layer "In13.Cu")
		(net "P5E_CPU0_PE2_RX_DN<14>")
	)
	(arc
		(start 383.827782 -221.458536)
		(mid 383.692491 -221.324754)
		(end 383.64033 -221.141798)
		(width 0.0889)
		(layer "In13.Cu")
		(net "P5E_CPU0_PE2_RX_DN<14>")
	)
	(arc
		(start 384.579876 -222.750888)
		(mid 384.501716 -222.474729)
		(end 384.297936 -222.272606)
		(width 0.0889)
		(layer "In13.Cu")
		(net "P5E_CPU0_PE2_RX_DN<14>")
	)
	(arc
		(start 383.64033 -221.133924)
		(mid 383.567638 -220.856719)
		(end 383.368296 -220.650816)
		(width 0.0889)
		(layer "In13.Cu")
		(net "P5E_CPU0_PE2_RX_DN<14>")
	)
	(arc
		(start 386.92963 -225.203258)
		(mid 386.856938 -224.926053)
		(end 386.657596 -224.72015)
		(width 0.0889)
		(layer "In13.Cu")
		(net "P5E_CPU0_PE2_RX_DN<14>")
	)
	(arc
		(start 382.792986 -220.64472)
		(mid 382.612669 -220.694976)
		(end 382.430528 -220.651832)
		(width 0.0889)
		(layer "In13.Cu")
		(net "P5E_CPU0_PE2_RX_DN<14>")
	)
	(arc
		(start 386.646674 -224.7138)
		(mid 386.364451 -224.638405)
		(end 386.082286 -224.714054)
		(width 0.0889)
		(layer "In13.Cu")
		(net "P5E_CPU0_PE2_RX_DN<14>")
	)
	(segment
		(start 381.19558 -221.669864)
		(end 381.19558 -221.134178)
		(width 0.13208)
		(layer "F.Cu")
		(net "P5E_CPU0_PE2_RX_DN<13>")
	)
	(segment
		(start 381.19558 -221.134178)
		(end 381.195834 -221.133924)
		(width 0.13208)
		(layer "F.Cu")
		(net "P5E_CPU0_PE2_RX_DN<13>")
	)
	(segment
		(start 385.990084 -223.575626)
		(end 385.990084 -223.557084)
		(width 0.0889)
		(layer "In13.Cu")
		(net "P5E_CPU0_PE2_RX_DN<13>")
	)
	(segment
		(start 383.65684 -419.770814)
		(end 383.463546 -419.127686)
		(width 0.14732)
		(layer "In13.Cu")
		(net "P5E_CPU0_PE2_RX_DN<13>")
	)
	(segment
		(start 381.060452 -221.48292)
		(end 381.03937 -221.404942)
		(width 0.0889)
		(layer "In13.Cu")
		(net "P5E_CPU0_PE2_RX_DN<13>")
	)
	(segment
		(start 383.557018 -418.953696)
		(end 383.4511 -418.60089)
		(width 0.14732)
		(layer "In13.Cu")
		(net "P5E_CPU0_PE2_RX_DN<13>")
	)
	(segment
		(start 381.383032 -220.809566)
		(end 381.383794 -220.810074)
		(width 0.0889)
		(layer "In13.Cu")
		(net "P5E_CPU0_PE2_RX_DN<13>")
	)
	(segment
		(start 384.297936 -220.644212)
		(end 384.289046 -220.639132)
		(width 0.0889)
		(layer "In13.Cu")
		(net "P5E_CPU0_PE2_RX_DN<13>")
	)
	(segment
		(start 383.276856 -418.507164)
		(end 383.033016 -417.696396)
		(width 0.14732)
		(layer "In13.Cu")
		(net "P5E_CPU0_PE2_RX_DN<13>")
	)
	(segment
		(start 388.05485 -224.750884)
		(end 387.751828 -224.448116)
		(width 0.14732)
		(layer "In13.Cu")
		(net "P5E_CPU0_PE2_RX_DN<13>")
	)
	(segment
		(start 379.844046 -399.288254)
		(end 393.096242 -353.952556)
		(width 0.14732)
		(layer "In13.Cu")
		(net "P5E_CPU0_PE2_RX_DN<13>")
	)
	(segment
		(start 386.177536 -223.899984)
		(end 386.168646 -223.894904)
		(width 0.0889)
		(layer "In13.Cu")
		(net "P5E_CPU0_PE2_RX_DN<13>")
	)
	(segment
		(start 390.561576 -256.411476)
		(end 389.566658 -254.990346)
		(width 0.14732)
		(layer "In13.Cu")
		(net "P5E_CPU0_PE2_RX_DN<13>")
	)
	(segment
		(start 388.634986 -249.262138)
		(end 389.132826 -248.550684)
		(width 0.14732)
		(layer "In13.Cu")
		(net "P5E_CPU0_PE2_RX_DN<13>")
	)
	(segment
		(start 385.066286 -433.595018)
		(end 385.066286 -424.457622)
		(width 0.14732)
		(layer "In13.Cu")
		(net "P5E_CPU0_PE2_RX_DN<13>")
	)
	(segment
		(start 388.969758 -253.549912)
		(end 388.857744 -253.23165)
		(width 0.14732)
		(layer "In13.Cu")
		(net "P5E_CPU0_PE2_RX_DN<13>")
	)
	(segment
		(start 383.463546 -419.127686)
		(end 383.557018 -418.953696)
		(width 0.14732)
		(layer "In13.Cu")
		(net "P5E_CPU0_PE2_RX_DN<13>")
	)
	(segment
		(start 388.538974 -252.136402)
		(end 388.490206 -251.24918)
		(width 0.14732)
		(layer "In13.Cu")
		(net "P5E_CPU0_PE2_RX_DN<13>")
	)
	(segment
		(start 388.440676 -250.361196)
		(end 388.634986 -249.262138)
		(width 0.14732)
		(layer "In13.Cu")
		(net "P5E_CPU0_PE2_RX_DN<13>")
	)
	(segment
		(start 388.490206 -251.24918)
		(end 388.489952 -251.24918)
		(width 0.14732)
		(layer "In13.Cu")
		(net "P5E_CPU0_PE2_RX_DN<13>")
	)
	(segment
		(start 385.237736 -222.272098)
		(end 385.228846 -222.267018)
		(width 0.0889)
		(layer "In13.Cu")
		(net "P5E_CPU0_PE2_RX_DN<13>")
	)
	(segment
		(start 389.566658 -254.990346)
		(end 388.969758 -253.549912)
		(width 0.14732)
		(layer "In13.Cu")
		(net "P5E_CPU0_PE2_RX_DN<13>")
	)
	(segment
		(start 384.767836 -221.458282)
		(end 384.758946 -221.453202)
		(width 0.0889)
		(layer "In13.Cu")
		(net "P5E_CPU0_PE2_RX_DN<13>")
	)
	(segment
		(start 385.32054 -433.719478)
		(end 385.190746 -433.719478)
		(width 0.14732)
		(layer "In13.Cu")
		(net "P5E_CPU0_PE2_RX_DN<13>")
	)
	(segment
		(start 381.03937 -221.404942)
		(end 381.195834 -221.133924)
		(width 0.0889)
		(layer "In13.Cu")
		(net "P5E_CPU0_PE2_RX_DN<13>")
	)
	(segment
		(start 379.64999 -404.705566)
		(end 379.64999 -400.416014)
		(width 0.14732)
		(layer "In13.Cu")
		(net "P5E_CPU0_PE2_RX_DN<13>")
	)
	(segment
		(start 385.750054 -433.289964)
		(end 385.32054 -433.719478)
		(width 0.14732)
		(layer "In13.Cu")
		(net "P5E_CPU0_PE2_RX_DN<13>")
	)
	(segment
		(start 388.857744 -253.23165)
		(end 388.538974 -252.136402)
		(width 0.14732)
		(layer "In13.Cu")
		(net "P5E_CPU0_PE2_RX_DN<13>")
	)
	(segment
		(start 384.110484 -220.319854)
		(end 384.110484 -220.309948)
		(width 0.0889)
		(layer "In13.Cu")
		(net "P5E_CPU0_PE2_RX_DN<13>")
	)
	(segment
		(start 390.491218 -244.380512)
		(end 389.49757 -230.312722)
		(width 0.14732)
		(layer "In13.Cu")
		(net "P5E_CPU0_PE2_RX_DN<13>")
	)
	(segment
		(start 387.751828 -224.448116)
		(end 387.736334 -224.432622)
		(width 0.0889)
		(layer "In13.Cu")
		(net "P5E_CPU0_PE2_RX_DN<13>")
	)
	(segment
		(start 383.84353 -420.391336)
		(end 383.937256 -420.217346)
		(width 0.14732)
		(layer "In13.Cu")
		(net "P5E_CPU0_PE2_RX_DN<13>")
	)
	(segment
		(start 388.33171 -225.38055)
		(end 388.05485 -224.750884)
		(width 0.14732)
		(layer "In13.Cu")
		(net "P5E_CPU0_PE2_RX_DN<13>")
	)
	(segment
		(start 380.99619 -410.923486)
		(end 380.99619 -406.051766)
		(width 0.14732)
		(layer "In13.Cu")
		(net "P5E_CPU0_PE2_RX_DN<13>")
	)
	(segment
		(start 385.066286 -424.457622)
		(end 383.84353 -420.391336)
		(width 0.14732)
		(layer "In13.Cu")
		(net "P5E_CPU0_PE2_RX_DN<13>")
	)
	(segment
		(start 381.391922 -221.453202)
		(end 381.383032 -221.458282)
		(width 0.0889)
		(layer "In13.Cu")
		(net "P5E_CPU0_PE2_RX_DN<13>")
	)
	(segment
		(start 393.096242 -353.952556)
		(end 395.466062 -339.342984)
		(width 0.14732)
		(layer "In13.Cu")
		(net "P5E_CPU0_PE2_RX_DN<13>")
	)
	(segment
		(start 395.466062 -339.342984)
		(end 388.464552 -310.246776)
		(width 0.14732)
		(layer "In13.Cu")
		(net "P5E_CPU0_PE2_RX_DN<13>")
	)
	(segment
		(start 387.677406 -224.432622)
		(end 387.58114 -224.336356)
		(width 0.0889)
		(layer "In13.Cu")
		(net "P5E_CPU0_PE2_RX_DN<13>")
	)
	(segment
		(start 391.315956 -259.352034)
		(end 390.561576 -256.411476)
		(width 0.14732)
		(layer "In13.Cu")
		(net "P5E_CPU0_PE2_RX_DN<13>")
	)
	(segment
		(start 383.937256 -420.217346)
		(end 383.831084 -419.86454)
		(width 0.14732)
		(layer "In13.Cu")
		(net "P5E_CPU0_PE2_RX_DN<13>")
	)
	(segment
		(start 383.831084 -419.86454)
		(end 383.65684 -419.770814)
		(width 0.14732)
		(layer "In13.Cu")
		(net "P5E_CPU0_PE2_RX_DN<13>")
	)
	(segment
		(start 383.02057 -417.169346)
		(end 382.84658 -417.076128)
		(width 0.14732)
		(layer "In13.Cu")
		(net "P5E_CPU0_PE2_RX_DN<13>")
	)
	(segment
		(start 379.64999 -400.416014)
		(end 379.844046 -399.288254)
		(width 0.14732)
		(layer "In13.Cu")
		(net "P5E_CPU0_PE2_RX_DN<13>")
	)
	(segment
		(start 382.337564 -219.82176)
		(end 382.322832 -219.830396)
		(width 0.0889)
		(layer "In13.Cu")
		(net "P5E_CPU0_PE2_RX_DN<13>")
	)
	(segment
		(start 388.331456 -225.38055)
		(end 388.33171 -225.38055)
		(width 0.14732)
		(layer "In13.Cu")
		(net "P5E_CPU0_PE2_RX_DN<13>")
	)
	(segment
		(start 383.033016 -417.696396)
		(end 383.126742 -417.522406)
		(width 0.14732)
		(layer "In13.Cu")
		(net "P5E_CPU0_PE2_RX_DN<13>")
	)
	(segment
		(start 383.4511 -418.60089)
		(end 383.276856 -418.507164)
		(width 0.14732)
		(layer "In13.Cu")
		(net "P5E_CPU0_PE2_RX_DN<13>")
	)
	(segment
		(start 380.99619 -406.051766)
		(end 379.64999 -404.705566)
		(width 0.14732)
		(layer "In13.Cu")
		(net "P5E_CPU0_PE2_RX_DN<13>")
	)
	(segment
		(start 387.736334 -224.432622)
		(end 387.677406 -224.432622)
		(width 0.0889)
		(layer "In13.Cu")
		(net "P5E_CPU0_PE2_RX_DN<13>")
	)
	(segment
		(start 384.773932 -221.461838)
		(end 384.767836 -221.458282)
		(width 0.0889)
		(layer "In13.Cu")
		(net "P5E_CPU0_PE2_RX_DN<13>")
	)
	(segment
		(start 381.383794 -220.810074)
		(end 381.391922 -220.814646)
		(width 0.0889)
		(layer "In13.Cu")
		(net "P5E_CPU0_PE2_RX_DN<13>")
	)
	(segment
		(start 388.598918 -225.989134)
		(end 388.331456 -225.38055)
		(width 0.14732)
		(layer "In13.Cu")
		(net "P5E_CPU0_PE2_RX_DN<13>")
	)
	(segment
		(start 387.58114 -224.336356)
		(end 387.234176 -223.989138)
		(width 0.0889)
		(layer "In13.Cu")
		(net "P5E_CPU0_PE2_RX_DN<13>")
	)
	(segment
		(start 385.190746 -433.719478)
		(end 385.066286 -433.595018)
		(width 0.14732)
		(layer "In13.Cu")
		(net "P5E_CPU0_PE2_RX_DN<13>")
	)
	(segment
		(start 384.580384 -221.133924)
		(end 384.580384 -221.115382)
		(width 0.0889)
		(layer "In13.Cu")
		(net "P5E_CPU0_PE2_RX_DN<13>")
	)
	(segment
		(start 385.243832 -222.275654)
		(end 385.237736 -222.272098)
		(width 0.0889)
		(layer "In13.Cu")
		(net "P5E_CPU0_PE2_RX_DN<13>")
	)
	(segment
		(start 385.707636 -223.085914)
		(end 385.698746 -223.080834)
		(width 0.0889)
		(layer "In13.Cu")
		(net "P5E_CPU0_PE2_RX_DN<13>")
	)
	(segment
		(start 388.464552 -310.246776)
		(end 391.315956 -259.352034)
		(width 0.14732)
		(layer "In13.Cu")
		(net "P5E_CPU0_PE2_RX_DN<13>")
	)
	(segment
		(start 389.132826 -248.550684)
		(end 390.491218 -244.380512)
		(width 0.14732)
		(layer "In13.Cu")
		(net "P5E_CPU0_PE2_RX_DN<13>")
	)
	(segment
		(start 388.489952 -251.24918)
		(end 388.440676 -250.361196)
		(width 0.14732)
		(layer "In13.Cu")
		(net "P5E_CPU0_PE2_RX_DN<13>")
	)
	(segment
		(start 383.126742 -417.522406)
		(end 383.02057 -417.169346)
		(width 0.14732)
		(layer "In13.Cu")
		(net "P5E_CPU0_PE2_RX_DN<13>")
	)
	(segment
		(start 382.84658 -417.076128)
		(end 380.99619 -410.923486)
		(width 0.14732)
		(layer "In13.Cu")
		(net "P5E_CPU0_PE2_RX_DN<13>")
	)
	(segment
		(start 381.100584 -220.309948)
		(end 381.100584 -220.338396)
		(width 0.0889)
		(layer "In13.Cu")
		(net "P5E_CPU0_PE2_RX_DN<13>")
	)
	(segment
		(start 389.49757 -230.312722)
		(end 388.598918 -225.989134)
		(width 0.14732)
		(layer "In13.Cu")
		(net "P5E_CPU0_PE2_RX_DN<13>")
	)
	(arc
		(start 385.228846 -222.267018)
		(mid 385.097932 -222.130658)
		(end 385.050284 -221.94774)
		(width 0.0889)
		(layer "In13.Cu")
		(net "P5E_CPU0_PE2_RX_DN<13>")
	)
	(arc
		(start 386.551932 -223.899984)
		(mid 386.364734 -223.950127)
		(end 386.177536 -223.899984)
		(width 0.0889)
		(layer "In13.Cu")
		(net "P5E_CPU0_PE2_RX_DN<13>")
	)
	(arc
		(start 385.698746 -223.080834)
		(mid 385.567832 -222.944474)
		(end 385.520184 -222.761556)
		(width 0.0889)
		(layer "In13.Cu")
		(net "P5E_CPU0_PE2_RX_DN<13>")
	)
	(arc
		(start 381.57023 -221.121732)
		(mid 381.570475 -221.131128)
		(end 381.570484 -221.140528)
		(width 0.0889)
		(layer "In13.Cu")
		(net "P5E_CPU0_PE2_RX_DN<13>")
	)
	(arc
		(start 382.888236 -219.830396)
		(mid 382.614037 -219.754561)
		(end 382.337564 -219.82176)
		(width 0.0889)
		(layer "In13.Cu")
		(net "P5E_CPU0_PE2_RX_DN<13>")
	)
	(arc
		(start 382.322832 -219.830396)
		(mid 382.135634 -219.880539)
		(end 381.948436 -219.830396)
		(width 0.0889)
		(layer "In13.Cu")
		(net "P5E_CPU0_PE2_RX_DN<13>")
	)
	(arc
		(start 387.181344 -223.94291)
		(mid 387.150072 -223.920355)
		(end 387.117336 -223.899984)
		(width 0.0889)
		(layer "In13.Cu")
		(net "P5E_CPU0_PE2_RX_DN<13>")
	)
	(arc
		(start 385.520184 -222.761556)
		(mid 385.446268 -222.482054)
		(end 385.243832 -222.275654)
		(width 0.0889)
		(layer "In13.Cu")
		(net "P5E_CPU0_PE2_RX_DN<13>")
	)
	(arc
		(start 384.580384 -221.115382)
		(mid 384.500222 -220.843193)
		(end 384.297936 -220.644212)
		(width 0.0889)
		(layer "In13.Cu")
		(net "P5E_CPU0_PE2_RX_DN<13>")
	)
	(arc
		(start 383.828036 -219.830396)
		(mid 383.545334 -219.75462)
		(end 383.262632 -219.830396)
		(width 0.0889)
		(layer "In13.Cu")
		(net "P5E_CPU0_PE2_RX_DN<13>")
	)
	(arc
		(start 381.100584 -220.338396)
		(mid 381.180746 -220.610585)
		(end 381.383032 -220.809566)
		(width 0.0889)
		(layer "In13.Cu")
		(net "P5E_CPU0_PE2_RX_DN<13>")
	)
	(arc
		(start 381.570484 -221.140528)
		(mid 381.521231 -221.319728)
		(end 381.391922 -221.453202)
		(width 0.0889)
		(layer "In13.Cu")
		(net "P5E_CPU0_PE2_RX_DN<13>")
	)
	(arc
		(start 386.168646 -223.894904)
		(mid 386.037732 -223.758544)
		(end 385.990084 -223.575626)
		(width 0.0889)
		(layer "In13.Cu")
		(net "P5E_CPU0_PE2_RX_DN<13>")
	)
	(arc
		(start 384.110484 -220.309948)
		(mid 384.032373 -220.032999)
		(end 383.828036 -219.830396)
		(width 0.0889)
		(layer "In13.Cu")
		(net "P5E_CPU0_PE2_RX_DN<13>")
	)
	(arc
		(start 384.289046 -220.639132)
		(mid 384.158132 -220.502772)
		(end 384.110484 -220.319854)
		(width 0.0889)
		(layer "In13.Cu")
		(net "P5E_CPU0_PE2_RX_DN<13>")
	)
	(arc
		(start 385.990084 -223.557084)
		(mid 385.909922 -223.284895)
		(end 385.707636 -223.085914)
		(width 0.0889)
		(layer "In13.Cu")
		(net "P5E_CPU0_PE2_RX_DN<13>")
	)
	(arc
		(start 381.383032 -221.458282)
		(mid 381.224544 -221.507215)
		(end 381.060452 -221.48292)
		(width 0.0889)
		(layer "In13.Cu")
		(net "P5E_CPU0_PE2_RX_DN<13>")
	)
	(arc
		(start 383.262632 -219.830396)
		(mid 383.075434 -219.880539)
		(end 382.888236 -219.830396)
		(width 0.0889)
		(layer "In13.Cu")
		(net "P5E_CPU0_PE2_RX_DN<13>")
	)
	(arc
		(start 385.050284 -221.94774)
		(mid 384.976368 -221.668238)
		(end 384.773932 -221.461838)
		(width 0.0889)
		(layer "In13.Cu")
		(net "P5E_CPU0_PE2_RX_DN<13>")
	)
	(arc
		(start 381.383032 -219.830396)
		(mid 381.178697 -220.033001)
		(end 381.100584 -220.309948)
		(width 0.0889)
		(layer "In13.Cu")
		(net "P5E_CPU0_PE2_RX_DN<13>")
	)
	(arc
		(start 384.758946 -221.453202)
		(mid 384.628032 -221.316842)
		(end 384.580384 -221.133924)
		(width 0.0889)
		(layer "In13.Cu")
		(net "P5E_CPU0_PE2_RX_DN<13>")
	)
	(arc
		(start 387.117336 -223.899984)
		(mid 386.834634 -223.824208)
		(end 386.551932 -223.899984)
		(width 0.0889)
		(layer "In13.Cu")
		(net "P5E_CPU0_PE2_RX_DN<13>")
	)
	(arc
		(start 387.234176 -223.989138)
		(mid 387.208478 -223.965204)
		(end 387.181344 -223.94291)
		(width 0.0889)
		(layer "In13.Cu")
		(net "P5E_CPU0_PE2_RX_DN<13>")
	)
	(arc
		(start 381.948436 -219.830396)
		(mid 381.665734 -219.75462)
		(end 381.383032 -219.830396)
		(width 0.0889)
		(layer "In13.Cu")
		(net "P5E_CPU0_PE2_RX_DN<13>")
	)
	(arc
		(start 381.391922 -220.814646)
		(mid 381.519815 -220.945708)
		(end 381.57023 -221.121732)
		(width 0.0889)
		(layer "In13.Cu")
		(net "P5E_CPU0_PE2_RX_DN<13>")
	)
	(segment
		(start 379.786134 -220.320108)
		(end 379.78588 -220.319854)
		(width 0.13208)
		(layer "F.Cu")
		(net "P5E_CPU0_PE2_RX_DN<12>")
	)
	(segment
		(start 379.786134 -220.855794)
		(end 379.786134 -220.320108)
		(width 0.13208)
		(layer "F.Cu")
		(net "P5E_CPU0_PE2_RX_DN<12>")
	)
	(segment
		(start 386.162296 -420.078154)
		(end 386.082794 -419.71849)
		(width 0.14732)
		(layer "In13.Cu")
		(net "P5E_CPU0_PE2_RX_DN<12>")
	)
	(segment
		(start 385.990084 -221.94774)
		(end 385.990084 -221.937834)
		(width 0.0889)
		(layer "In13.Cu")
		(net "P5E_CPU0_PE2_RX_DN<12>")
	)
	(segment
		(start 387.06679 -424.91406)
		(end 387.06679 -424.816016)
		(width 0.14732)
		(layer "In13.Cu")
		(net "P5E_CPU0_PE2_RX_DN<12>")
	)
	(segment
		(start 384.773678 -219.833952)
		(end 384.768344 -219.830904)
		(width 0.0889)
		(layer "In13.Cu")
		(net "P5E_CPU0_PE2_RX_DN<12>")
	)
	(segment
		(start 396.428976 -339.356954)
		(end 389.413242 -310.008524)
		(width 0.14732)
		(layer "In13.Cu")
		(net "P5E_CPU0_PE2_RX_DN<12>")
	)
	(segment
		(start 391.4521 -244.486938)
		(end 390.43229 -230.137716)
		(width 0.14732)
		(layer "In13.Cu")
		(net "P5E_CPU0_PE2_RX_DN<12>")
	)
	(segment
		(start 379.942344 -220.590872)
		(end 379.78588 -220.319854)
		(width 0.0889)
		(layer "In13.Cu")
		(net "P5E_CPU0_PE2_RX_DN<12>")
	)
	(segment
		(start 388.51713 -376.504708)
		(end 394.00607 -354.249482)
		(width 0.14732)
		(layer "In13.Cu")
		(net "P5E_CPU0_PE2_RX_DN<12>")
	)
	(segment
		(start 380.439422 -219.832682)
		(end 380.43104 -219.837508)
		(width 0.0889)
		(layer "In13.Cu")
		(net "P5E_CPU0_PE2_RX_DN<12>")
	)
	(segment
		(start 392.295126 -259.261102)
		(end 391.523728 -256.164588)
		(width 0.14732)
		(layer "In13.Cu")
		(net "P5E_CPU0_PE2_RX_DN<12>")
	)
	(segment
		(start 386.05714 -420.249858)
		(end 386.056124 -420.244778)
		(width 0.14732)
		(layer "In13.Cu")
		(net "P5E_CPU0_PE2_RX_DN<12>")
	)
	(segment
		(start 385.237736 -220.644212)
		(end 385.228846 -220.639132)
		(width 0.0889)
		(layer "In13.Cu")
		(net "P5E_CPU0_PE2_RX_DN<12>")
	)
	(segment
		(start 390.00557 -248.926096)
		(end 391.4521 -244.486938)
		(width 0.14732)
		(layer "In13.Cu")
		(net "P5E_CPU0_PE2_RX_DN<12>")
	)
	(segment
		(start 387.367018 -434.672994)
		(end 387.190742 -434.672994)
		(width 0.14732)
		(layer "In13.Cu")
		(net "P5E_CPU0_PE2_RX_DN<12>")
	)
	(segment
		(start 380.630684 -219.490544)
		(end 380.630684 -219.506038)
		(width 0.0889)
		(layer "In13.Cu")
		(net "P5E_CPU0_PE2_RX_DN<12>")
	)
	(segment
		(start 389.413242 -310.008524)
		(end 392.295126 -259.261102)
		(width 0.14732)
		(layer "In13.Cu")
		(net "P5E_CPU0_PE2_RX_DN<12>")
	)
	(segment
		(start 390.43229 -230.137716)
		(end 389.5344 -225.77933)
		(width 0.14732)
		(layer "In13.Cu")
		(net "P5E_CPU0_PE2_RX_DN<12>")
	)
	(segment
		(start 391.523728 -256.164588)
		(end 390.39038 -254.545338)
		(width 0.14732)
		(layer "In13.Cu")
		(net "P5E_CPU0_PE2_RX_DN<12>")
	)
	(segment
		(start 387.190742 -434.672994)
		(end 387.066282 -434.548534)
		(width 0.14732)
		(layer "In13.Cu")
		(net "P5E_CPU0_PE2_RX_DN<12>")
	)
	(segment
		(start 382.907032 -399.05051)
		(end 388.41553 -376.71375)
		(width 0.14732)
		(layer "In13.Cu")
		(net "P5E_CPU0_PE2_RX_DN<12>")
	)
	(segment
		(start 389.499348 -250.46559)
		(end 389.692134 -249.374152)
		(width 0.14732)
		(layer "In13.Cu")
		(net "P5E_CPU0_PE2_RX_DN<12>")
	)
	(segment
		(start 389.764016 -253.00559)
		(end 389.499348 -252.098048)
		(width 0.14732)
		(layer "In13.Cu")
		(net "P5E_CPU0_PE2_RX_DN<12>")
	)
	(segment
		(start 386.082794 -419.71849)
		(end 385.91617 -419.612318)
		(width 0.14732)
		(layer "In13.Cu")
		(net "P5E_CPU0_PE2_RX_DN<12>")
	)
	(segment
		(start 385.520184 -221.133924)
		(end 385.520184 -221.115382)
		(width 0.0889)
		(layer "In13.Cu")
		(net "P5E_CPU0_PE2_RX_DN<12>")
	)
	(segment
		(start 387.840474 -223.136714)
		(end 386.834634 -223.136714)
		(width 0.0889)
		(layer "In13.Cu")
		(net "P5E_CPU0_PE2_RX_DN<12>")
	)
	(segment
		(start 382.71323 -404.705566)
		(end 382.71323 -400.61515)
		(width 0.14732)
		(layer "In13.Cu")
		(net "P5E_CPU0_PE2_RX_DN<12>")
	)
	(segment
		(start 380.452122 -219.825316)
		(end 380.443232 -219.830396)
		(width 0.0889)
		(layer "In13.Cu")
		(net "P5E_CPU0_PE2_RX_DN<12>")
	)
	(segment
		(start 387.066282 -434.548534)
		(end 387.066282 -424.914568)
		(width 0.14732)
		(layer "In13.Cu")
		(net "P5E_CPU0_PE2_RX_DN<12>")
	)
	(segment
		(start 389.499348 -252.098048)
		(end 389.499348 -250.46559)
		(width 0.14732)
		(layer "In13.Cu")
		(net "P5E_CPU0_PE2_RX_DN<12>")
	)
	(segment
		(start 386.177536 -222.272098)
		(end 386.168646 -222.267018)
		(width 0.0889)
		(layer "In13.Cu")
		(net "P5E_CPU0_PE2_RX_DN<12>")
	)
	(segment
		(start 386.056124 -420.244778)
		(end 386.162296 -420.078154)
		(width 0.14732)
		(layer "In13.Cu")
		(net "P5E_CPU0_PE2_RX_DN<12>")
	)
	(segment
		(start 387.75005 -434.289962)
		(end 387.367018 -434.672994)
		(width 0.14732)
		(layer "In13.Cu")
		(net "P5E_CPU0_PE2_RX_DN<12>")
	)
	(segment
		(start 388.41553 -376.71375)
		(end 388.465314 -376.71375)
		(width 0.14732)
		(layer "In13.Cu")
		(net "P5E_CPU0_PE2_RX_DN<12>")
	)
	(segment
		(start 384.05943 -406.051766)
		(end 382.71323 -404.705566)
		(width 0.14732)
		(layer "In13.Cu")
		(net "P5E_CPU0_PE2_RX_DN<12>")
	)
	(segment
		(start 388.465314 -376.71375)
		(end 388.516876 -376.504708)
		(width 0.14732)
		(layer "In13.Cu")
		(net "P5E_CPU0_PE2_RX_DN<12>")
	)
	(segment
		(start 390.39038 -254.545338)
		(end 389.829802 -253.193042)
		(width 0.14732)
		(layer "In13.Cu")
		(net "P5E_CPU0_PE2_RX_DN<12>")
	)
	(segment
		(start 382.71323 -400.61515)
		(end 382.907032 -399.05051)
		(width 0.14732)
		(layer "In13.Cu")
		(net "P5E_CPU0_PE2_RX_DN<12>")
	)
	(segment
		(start 387.06679 -424.816016)
		(end 386.05714 -420.249858)
		(width 0.14732)
		(layer "In13.Cu")
		(net "P5E_CPU0_PE2_RX_DN<12>")
	)
	(segment
		(start 385.707636 -221.458282)
		(end 385.698746 -221.453202)
		(width 0.0889)
		(layer "In13.Cu")
		(net "P5E_CPU0_PE2_RX_DN<12>")
	)
	(segment
		(start 387.992366 -223.288606)
		(end 387.840474 -223.136714)
		(width 0.0889)
		(layer "In13.Cu")
		(net "P5E_CPU0_PE2_RX_DN<12>")
	)
	(segment
		(start 389.692134 -249.374152)
		(end 390.00557 -248.926096)
		(width 0.14732)
		(layer "In13.Cu")
		(net "P5E_CPU0_PE2_RX_DN<12>")
	)
	(segment
		(start 389.829802 -253.193042)
		(end 389.764016 -253.00559)
		(width 0.14732)
		(layer "In13.Cu")
		(net "P5E_CPU0_PE2_RX_DN<12>")
	)
	(segment
		(start 381.478536 -219.01658)
		(end 381.468122 -219.010484)
		(width 0.0889)
		(layer "In13.Cu")
		(net "P5E_CPU0_PE2_RX_DN<12>")
	)
	(segment
		(start 389.534654 -225.77933)
		(end 389.529574 -225.755454)
		(width 0.14732)
		(layer "In13.Cu")
		(net "P5E_CPU0_PE2_RX_DN<12>")
	)
	(segment
		(start 388.516876 -376.504708)
		(end 388.51713 -376.504708)
		(width 0.14732)
		(layer "In13.Cu")
		(net "P5E_CPU0_PE2_RX_DN<12>")
	)
	(segment
		(start 386.459984 -222.770192)
		(end 386.459984 -222.75165)
		(width 0.0889)
		(layer "In13.Cu")
		(net "P5E_CPU0_PE2_RX_DN<12>")
	)
	(segment
		(start 394.00607 -354.249482)
		(end 396.428976 -339.356954)
		(width 0.14732)
		(layer "In13.Cu")
		(net "P5E_CPU0_PE2_RX_DN<12>")
	)
	(segment
		(start 388.066788 -223.3041)
		(end 388.051294 -223.288606)
		(width 0.0889)
		(layer "In13.Cu")
		(net "P5E_CPU0_PE2_RX_DN<12>")
	)
	(segment
		(start 384.05943 -411.215332)
		(end 384.05943 -406.051766)
		(width 0.14732)
		(layer "In13.Cu")
		(net "P5E_CPU0_PE2_RX_DN<12>")
	)
	(segment
		(start 387.066282 -424.914568)
		(end 387.06679 -424.91406)
		(width 0.14732)
		(layer "In13.Cu")
		(net "P5E_CPU0_PE2_RX_DN<12>")
	)
	(segment
		(start 385.91617 -419.612318)
		(end 384.05943 -411.215332)
		(width 0.14732)
		(layer "In13.Cu")
		(net "P5E_CPU0_PE2_RX_DN<12>")
	)
	(segment
		(start 380.020576 -220.6117)
		(end 379.942344 -220.590872)
		(width 0.0889)
		(layer "In13.Cu")
		(net "P5E_CPU0_PE2_RX_DN<12>")
	)
	(segment
		(start 384.768344 -219.830904)
		(end 384.767582 -219.830396)
		(width 0.0889)
		(layer "In13.Cu")
		(net "P5E_CPU0_PE2_RX_DN<12>")
	)
	(segment
		(start 389.529574 -225.755454)
		(end 388.878064 -224.115122)
		(width 0.14732)
		(layer "In13.Cu")
		(net "P5E_CPU0_PE2_RX_DN<12>")
	)
	(segment
		(start 389.5344 -225.77933)
		(end 389.534654 -225.77933)
		(width 0.14732)
		(layer "In13.Cu")
		(net "P5E_CPU0_PE2_RX_DN<12>")
	)
	(segment
		(start 384.580384 -219.514674)
		(end 384.580384 -219.496132)
		(width 0.0889)
		(layer "In13.Cu")
		(net "P5E_CPU0_PE2_RX_DN<12>")
	)
	(segment
		(start 388.051294 -223.288606)
		(end 387.992366 -223.288606)
		(width 0.0889)
		(layer "In13.Cu")
		(net "P5E_CPU0_PE2_RX_DN<12>")
	)
	(segment
		(start 380.443232 -219.830396)
		(end 380.439422 -219.832682)
		(width 0.0889)
		(layer "In13.Cu")
		(net "P5E_CPU0_PE2_RX_DN<12>")
	)
	(segment
		(start 388.878064 -224.115122)
		(end 388.066788 -223.3041)
		(width 0.14732)
		(layer "In13.Cu")
		(net "P5E_CPU0_PE2_RX_DN<12>")
	)
	(arc
		(start 386.168646 -222.267018)
		(mid 386.037732 -222.130658)
		(end 385.990084 -221.94774)
		(width 0.0889)
		(layer "In13.Cu")
		(net "P5E_CPU0_PE2_RX_DN<12>")
	)
	(arc
		(start 382.792732 -219.01658)
		(mid 382.605534 -219.066723)
		(end 382.418336 -219.01658)
		(width 0.0889)
		(layer "In13.Cu")
		(net "P5E_CPU0_PE2_RX_DN<12>")
	)
	(arc
		(start 380.912878 -219.01658)
		(mid 380.710055 -219.216811)
		(end 380.630684 -219.490544)
		(width 0.0889)
		(layer "In13.Cu")
		(net "P5E_CPU0_PE2_RX_DN<12>")
	)
	(arc
		(start 381.468122 -219.010484)
		(mid 381.18969 -218.940638)
		(end 380.912878 -219.01658)
		(width 0.0889)
		(layer "In13.Cu")
		(net "P5E_CPU0_PE2_RX_DN<12>")
	)
	(arc
		(start 380.630684 -219.506038)
		(mid 380.583005 -219.688938)
		(end 380.452122 -219.825316)
		(width 0.0889)
		(layer "In13.Cu")
		(net "P5E_CPU0_PE2_RX_DN<12>")
	)
	(arc
		(start 381.852932 -219.01658)
		(mid 381.665734 -219.066723)
		(end 381.478536 -219.01658)
		(width 0.0889)
		(layer "In13.Cu")
		(net "P5E_CPU0_PE2_RX_DN<12>")
	)
	(arc
		(start 386.647182 -223.085914)
		(mid 386.512249 -222.95256)
		(end 386.459984 -222.770192)
		(width 0.0889)
		(layer "In13.Cu")
		(net "P5E_CPU0_PE2_RX_DN<12>")
	)
	(arc
		(start 385.228846 -220.639132)
		(mid 385.097932 -220.502772)
		(end 385.050284 -220.319854)
		(width 0.0889)
		(layer "In13.Cu")
		(net "P5E_CPU0_PE2_RX_DN<12>")
	)
	(arc
		(start 384.580384 -219.496132)
		(mid 384.502273 -219.219183)
		(end 384.297936 -219.01658)
		(width 0.0889)
		(layer "In13.Cu")
		(net "P5E_CPU0_PE2_RX_DN<12>")
	)
	(arc
		(start 380.43104 -219.837508)
		(mid 380.232812 -220.043356)
		(end 380.16053 -220.319854)
		(width 0.0889)
		(layer "In13.Cu")
		(net "P5E_CPU0_PE2_RX_DN<12>")
	)
	(arc
		(start 385.520184 -221.115382)
		(mid 385.440022 -220.843193)
		(end 385.237736 -220.644212)
		(width 0.0889)
		(layer "In13.Cu")
		(net "P5E_CPU0_PE2_RX_DN<12>")
	)
	(arc
		(start 385.050284 -220.319854)
		(mid 384.976293 -220.040288)
		(end 384.773678 -219.833952)
		(width 0.0889)
		(layer "In13.Cu")
		(net "P5E_CPU0_PE2_RX_DN<12>")
	)
	(arc
		(start 382.418336 -219.01658)
		(mid 382.135634 -218.940804)
		(end 381.852932 -219.01658)
		(width 0.0889)
		(layer "In13.Cu")
		(net "P5E_CPU0_PE2_RX_DN<12>")
	)
	(arc
		(start 380.16053 -220.319854)
		(mid 380.12367 -220.481651)
		(end 380.020576 -220.6117)
		(width 0.0889)
		(layer "In13.Cu")
		(net "P5E_CPU0_PE2_RX_DN<12>")
	)
	(arc
		(start 384.767582 -219.830396)
		(mid 384.632649 -219.697042)
		(end 384.580384 -219.514674)
		(width 0.0889)
		(layer "In13.Cu")
		(net "P5E_CPU0_PE2_RX_DN<12>")
	)
	(arc
		(start 383.732532 -219.01658)
		(mid 383.545334 -219.066723)
		(end 383.358136 -219.01658)
		(width 0.0889)
		(layer "In13.Cu")
		(net "P5E_CPU0_PE2_RX_DN<12>")
	)
	(arc
		(start 385.698746 -221.453202)
		(mid 385.567832 -221.316842)
		(end 385.520184 -221.133924)
		(width 0.0889)
		(layer "In13.Cu")
		(net "P5E_CPU0_PE2_RX_DN<12>")
	)
	(arc
		(start 386.459984 -222.75165)
		(mid 386.381873 -222.474701)
		(end 386.177536 -222.272098)
		(width 0.0889)
		(layer "In13.Cu")
		(net "P5E_CPU0_PE2_RX_DN<12>")
	)
	(arc
		(start 385.990084 -221.937834)
		(mid 385.911973 -221.660885)
		(end 385.707636 -221.458282)
		(width 0.0889)
		(layer "In13.Cu")
		(net "P5E_CPU0_PE2_RX_DN<12>")
	)
	(arc
		(start 384.297936 -219.01658)
		(mid 384.015234 -218.940804)
		(end 383.732532 -219.01658)
		(width 0.0889)
		(layer "In13.Cu")
		(net "P5E_CPU0_PE2_RX_DN<12>")
	)
	(arc
		(start 386.834634 -223.136714)
		(mid 386.737564 -223.123657)
		(end 386.647182 -223.085914)
		(width 0.0889)
		(layer "In13.Cu")
		(net "P5E_CPU0_PE2_RX_DN<12>")
	)
	(arc
		(start 383.358136 -219.01658)
		(mid 383.075434 -218.940804)
		(end 382.792732 -219.01658)
		(width 0.0889)
		(layer "In13.Cu")
		(net "P5E_CPU0_PE2_RX_DN<12>")
	)
	(segment
		(start 379.31598 -221.669864)
		(end 379.31598 -221.134178)
		(width 0.13208)
		(layer "F.Cu")
		(net "P5E_CPU0_PE2_RX_DN<11>")
	)
	(segment
		(start 379.31598 -221.134178)
		(end 379.316234 -221.133924)
		(width 0.13208)
		(layer "F.Cu")
		(net "P5E_CPU0_PE2_RX_DN<11>")
	)
	(segment
		(start 386.954522 -216.628218)
		(end 386.996432 -216.586308)
		(width 0.0889)
		(layer "In13.Cu")
		(net "P5E_CPU0_PE2_RX_DN<11>")
	)
	(segment
		(start 380.630684 -217.878406)
		(end 380.630684 -217.859864)
		(width 0.0889)
		(layer "In13.Cu")
		(net "P5E_CPU0_PE2_RX_DN<11>")
	)
	(segment
		(start 387.12267 -411.314138)
		(end 388.135368 -418.25291)
		(width 0.14732)
		(layer "In13.Cu")
		(net "P5E_CPU0_PE2_RX_DN<11>")
	)
	(segment
		(start 388.293864 -418.370766)
		(end 388.34695 -418.73551)
		(width 0.14732)
		(layer "In13.Cu")
		(net "P5E_CPU0_PE2_RX_DN<11>")
	)
	(segment
		(start 387.53796 -216.586308)
		(end 387.97738 -217.025728)
		(width 0.14732)
		(layer "In13.Cu")
		(net "P5E_CPU0_PE2_RX_DN<11>")
	)
	(segment
		(start 390.873488 -249.308366)
		(end 390.699244 -249.557286)
		(width 0.14732)
		(layer "In13.Cu")
		(net "P5E_CPU0_PE2_RX_DN<11>")
	)
	(segment
		(start 392.627358 -255.956054)
		(end 393.338812 -259.170932)
		(width 0.14732)
		(layer "In13.Cu")
		(net "P5E_CPU0_PE2_RX_DN<11>")
	)
	(segment
		(start 388.375652 -419.899338)
		(end 389.066278 -424.63339)
		(width 0.14732)
		(layer "In13.Cu")
		(net "P5E_CPU0_PE2_RX_DN<11>")
	)
	(segment
		(start 397.474948 -339.421216)
		(end 394.988796 -354.179378)
		(width 0.14732)
		(layer "In13.Cu")
		(net "P5E_CPU0_PE2_RX_DN<11>")
	)
	(segment
		(start 379.973078 -219.01658)
		(end 379.981968 -219.0115)
		(width 0.0889)
		(layer "In13.Cu")
		(net "P5E_CPU0_PE2_RX_DN<11>")
	)
	(segment
		(start 379.497336 -219.833952)
		(end 379.504956 -219.829634)
		(width 0.0889)
		(layer "In13.Cu")
		(net "P5E_CPU0_PE2_RX_DN<11>")
	)
	(segment
		(start 393.336526 -259.210048)
		(end 393.336272 -259.210556)
		(width 0.14732)
		(layer "In13.Cu")
		(net "P5E_CPU0_PE2_RX_DN<11>")
	)
	(segment
		(start 388.281926 -419.258242)
		(end 388.440422 -419.376352)
		(width 0.14732)
		(layer "In13.Cu")
		(net "P5E_CPU0_PE2_RX_DN<11>")
	)
	(segment
		(start 391.0457 -253.697232)
		(end 392.627358 -255.956054)
		(width 0.14732)
		(layer "In13.Cu")
		(net "P5E_CPU0_PE2_RX_DN<11>")
	)
	(segment
		(start 388.135368 -418.25291)
		(end 388.293864 -418.370766)
		(width 0.14732)
		(layer "In13.Cu")
		(net "P5E_CPU0_PE2_RX_DN<11>")
	)
	(segment
		(start 388.493762 -419.740842)
		(end 388.375652 -419.899338)
		(width 0.14732)
		(layer "In13.Cu")
		(net "P5E_CPU0_PE2_RX_DN<11>")
	)
	(segment
		(start 392.411966 -244.579394)
		(end 390.873488 -249.308366)
		(width 0.14732)
		(layer "In13.Cu")
		(net "P5E_CPU0_PE2_RX_DN<11>")
	)
	(segment
		(start 385.77647 -404.705566)
		(end 387.12267 -406.051766)
		(width 0.14732)
		(layer "In13.Cu")
		(net "P5E_CPU0_PE2_RX_DN<11>")
	)
	(segment
		(start 385.77647 -399.880582)
		(end 385.77647 -404.705566)
		(width 0.14732)
		(layer "In13.Cu")
		(net "P5E_CPU0_PE2_RX_DN<11>")
	)
	(segment
		(start 390.372854 -309.924704)
		(end 397.474948 -339.421216)
		(width 0.14732)
		(layer "In13.Cu")
		(net "P5E_CPU0_PE2_RX_DN<11>")
	)
	(segment
		(start 379.15977 -221.404942)
		(end 379.180852 -221.48292)
		(width 0.0889)
		(layer "In13.Cu")
		(net "P5E_CPU0_PE2_RX_DN<11>")
	)
	(segment
		(start 389.066278 -424.63339)
		(end 389.066278 -433.646834)
		(width 0.14732)
		(layer "In13.Cu")
		(net "P5E_CPU0_PE2_RX_DN<11>")
	)
	(segment
		(start 379.504956 -221.45752)
		(end 379.512322 -221.453202)
		(width 0.0889)
		(layer "In13.Cu")
		(net "P5E_CPU0_PE2_RX_DN<11>")
	)
	(segment
		(start 381.10033 -217.072972)
		(end 381.10033 -217.064336)
		(width 0.0889)
		(layer "In13.Cu")
		(net "P5E_CPU0_PE2_RX_DN<11>")
	)
	(segment
		(start 386.893562 -216.628218)
		(end 386.954522 -216.628218)
		(width 0.0889)
		(layer "In13.Cu")
		(net "P5E_CPU0_PE2_RX_DN<11>")
	)
	(segment
		(start 393.336272 -259.210556)
		(end 390.372854 -309.924704)
		(width 0.14732)
		(layer "In13.Cu")
		(net "P5E_CPU0_PE2_RX_DN<11>")
	)
	(segment
		(start 388.440422 -419.376352)
		(end 388.493762 -419.740842)
		(width 0.14732)
		(layer "In13.Cu")
		(net "P5E_CPU0_PE2_RX_DN<11>")
	)
	(segment
		(start 379.316234 -221.133924)
		(end 379.15977 -221.404942)
		(width 0.0889)
		(layer "In13.Cu")
		(net "P5E_CPU0_PE2_RX_DN<11>")
	)
	(segment
		(start 387.12267 -406.051766)
		(end 387.12267 -411.314138)
		(width 0.14732)
		(layer "In13.Cu")
		(net "P5E_CPU0_PE2_RX_DN<11>")
	)
	(segment
		(start 390.492234 -225.49866)
		(end 391.40765 -230.006398)
		(width 0.14732)
		(layer "In13.Cu")
		(net "P5E_CPU0_PE2_RX_DN<11>")
	)
	(segment
		(start 379.504956 -219.829634)
		(end 379.512322 -219.825316)
		(width 0.0889)
		(layer "In13.Cu")
		(net "P5E_CPU0_PE2_RX_DN<11>")
	)
	(segment
		(start 388.34695 -418.73551)
		(end 388.22884 -418.894006)
		(width 0.14732)
		(layer "In13.Cu")
		(net "P5E_CPU0_PE2_RX_DN<11>")
	)
	(segment
		(start 379.512322 -220.814646)
		(end 379.503432 -220.809566)
		(width 0.0889)
		(layer "In13.Cu")
		(net "P5E_CPU0_PE2_RX_DN<11>")
	)
	(segment
		(start 379.503432 -221.458282)
		(end 379.504956 -221.45752)
		(width 0.0889)
		(layer "In13.Cu")
		(net "P5E_CPU0_PE2_RX_DN<11>")
	)
	(segment
		(start 389.066278 -433.646834)
		(end 389.138922 -433.719478)
		(width 0.14732)
		(layer "In13.Cu")
		(net "P5E_CPU0_PE2_RX_DN<11>")
	)
	(segment
		(start 379.690884 -219.506038)
		(end 379.690884 -219.490544)
		(width 0.0889)
		(layer "In13.Cu")
		(net "P5E_CPU0_PE2_RX_DN<11>")
	)
	(segment
		(start 387.01853 -216.586308)
		(end 387.53796 -216.586308)
		(width 0.14732)
		(layer "In13.Cu")
		(net "P5E_CPU0_PE2_RX_DN<11>")
	)
	(segment
		(start 387.97738 -217.025728)
		(end 390.492234 -225.49866)
		(width 0.14732)
		(layer "In13.Cu")
		(net "P5E_CPU0_PE2_RX_DN<11>")
	)
	(segment
		(start 388.22884 -418.894006)
		(end 388.281926 -419.258242)
		(width 0.14732)
		(layer "In13.Cu")
		(net "P5E_CPU0_PE2_RX_DN<11>")
	)
	(segment
		(start 393.337542 -259.19049)
		(end 393.336526 -259.210048)
		(width 0.14732)
		(layer "In13.Cu")
		(net "P5E_CPU0_PE2_RX_DN<11>")
	)
	(segment
		(start 394.988796 -354.179378)
		(end 385.77647 -399.880582)
		(width 0.14732)
		(layer "In13.Cu")
		(net "P5E_CPU0_PE2_RX_DN<11>")
	)
	(segment
		(start 390.515348 -250.59894)
		(end 390.515348 -252.258322)
		(width 0.14732)
		(layer "In13.Cu")
		(net "P5E_CPU0_PE2_RX_DN<11>")
	)
	(segment
		(start 389.138922 -433.719478)
		(end 389.444484 -433.719478)
		(width 0.14732)
		(layer "In13.Cu")
		(net "P5E_CPU0_PE2_RX_DN<11>")
	)
	(segment
		(start 393.338812 -259.170932)
		(end 393.337542 -259.19049)
		(width 0.14732)
		(layer "In13.Cu")
		(net "P5E_CPU0_PE2_RX_DN<11>")
	)
	(segment
		(start 390.699244 -249.557286)
		(end 390.515348 -250.59894)
		(width 0.14732)
		(layer "In13.Cu")
		(net "P5E_CPU0_PE2_RX_DN<11>")
	)
	(segment
		(start 390.515348 -252.258322)
		(end 390.7155 -252.901196)
		(width 0.14732)
		(layer "In13.Cu")
		(net "P5E_CPU0_PE2_RX_DN<11>")
	)
	(segment
		(start 391.40765 -230.006398)
		(end 392.411966 -244.579394)
		(width 0.14732)
		(layer "In13.Cu")
		(net "P5E_CPU0_PE2_RX_DN<11>")
	)
	(segment
		(start 389.750046 -433.413916)
		(end 389.750046 -433.289964)
		(width 0.14732)
		(layer "In13.Cu")
		(net "P5E_CPU0_PE2_RX_DN<11>")
	)
	(segment
		(start 389.444484 -433.719478)
		(end 389.750046 -433.413916)
		(width 0.14732)
		(layer "In13.Cu")
		(net "P5E_CPU0_PE2_RX_DN<11>")
	)
	(segment
		(start 381.376936 -216.578434)
		(end 381.397764 -216.566242)
		(width 0.0889)
		(layer "In13.Cu")
		(net "P5E_CPU0_PE2_RX_DN<11>")
	)
	(segment
		(start 380.437136 -218.20632)
		(end 380.452122 -218.197684)
		(width 0.0889)
		(layer "In13.Cu")
		(net "P5E_CPU0_PE2_RX_DN<11>")
	)
	(segment
		(start 386.996432 -216.586308)
		(end 387.01853 -216.586308)
		(width 0.0889)
		(layer "In13.Cu")
		(net "P5E_CPU0_PE2_RX_DN<11>")
	)
	(segment
		(start 390.7155 -252.901196)
		(end 391.0457 -253.697232)
		(width 0.14732)
		(layer "In13.Cu")
		(net "P5E_CPU0_PE2_RX_DN<11>")
	)
	(arc
		(start 386.082032 -216.574878)
		(mid 386.364734 -216.499102)
		(end 386.647436 -216.574878)
		(width 0.0889)
		(layer "In13.Cu")
		(net "P5E_CPU0_PE2_RX_DN<11>")
	)
	(arc
		(start 384.767836 -216.574878)
		(mid 384.955034 -216.625021)
		(end 385.142232 -216.574878)
		(width 0.0889)
		(layer "In13.Cu")
		(net "P5E_CPU0_PE2_RX_DN<11>")
	)
	(arc
		(start 379.512322 -219.825316)
		(mid 379.643236 -219.688956)
		(end 379.690884 -219.506038)
		(width 0.0889)
		(layer "In13.Cu")
		(net "P5E_CPU0_PE2_RX_DN<11>")
	)
	(arc
		(start 381.397764 -216.566242)
		(mid 381.674239 -216.498922)
		(end 381.948436 -216.574878)
		(width 0.0889)
		(layer "In13.Cu")
		(net "P5E_CPU0_PE2_RX_DN<11>")
	)
	(arc
		(start 381.948436 -216.574878)
		(mid 382.135634 -216.625021)
		(end 382.322832 -216.574878)
		(width 0.0889)
		(layer "In13.Cu")
		(net "P5E_CPU0_PE2_RX_DN<11>")
	)
	(arc
		(start 383.262632 -216.574878)
		(mid 383.545334 -216.499102)
		(end 383.828036 -216.574878)
		(width 0.0889)
		(layer "In13.Cu")
		(net "P5E_CPU0_PE2_RX_DN<11>")
	)
	(arc
		(start 383.828036 -216.574878)
		(mid 384.015234 -216.625021)
		(end 384.202432 -216.574878)
		(width 0.0889)
		(layer "In13.Cu")
		(net "P5E_CPU0_PE2_RX_DN<11>")
	)
	(arc
		(start 381.10033 -217.064336)
		(mid 381.174321 -216.78477)
		(end 381.376936 -216.578434)
		(width 0.0889)
		(layer "In13.Cu")
		(net "P5E_CPU0_PE2_RX_DN<11>")
	)
	(arc
		(start 385.142232 -216.574878)
		(mid 385.424934 -216.499102)
		(end 385.707636 -216.574878)
		(width 0.0889)
		(layer "In13.Cu")
		(net "P5E_CPU0_PE2_RX_DN<11>")
	)
	(arc
		(start 379.180852 -221.48292)
		(mid 379.344948 -221.507267)
		(end 379.503432 -221.458282)
		(width 0.0889)
		(layer "In13.Cu")
		(net "P5E_CPU0_PE2_RX_DN<11>")
	)
	(arc
		(start 379.512322 -221.453202)
		(mid 379.69104 -221.133924)
		(end 379.512322 -220.814646)
		(width 0.0889)
		(layer "In13.Cu")
		(net "P5E_CPU0_PE2_RX_DN<11>")
	)
	(arc
		(start 386.80263 -216.624154)
		(mid 386.848053 -216.627145)
		(end 386.893562 -216.628218)
		(width 0.0889)
		(layer "In13.Cu")
		(net "P5E_CPU0_PE2_RX_DN<11>")
	)
	(arc
		(start 382.888236 -216.574878)
		(mid 383.075434 -216.625021)
		(end 383.262632 -216.574878)
		(width 0.0889)
		(layer "In13.Cu")
		(net "P5E_CPU0_PE2_RX_DN<11>")
	)
	(arc
		(start 379.981968 -219.0115)
		(mid 380.112882 -218.87514)
		(end 380.16053 -218.692222)
		(width 0.0889)
		(layer "In13.Cu")
		(net "P5E_CPU0_PE2_RX_DN<11>")
	)
	(arc
		(start 379.690884 -219.490544)
		(mid 379.770254 -219.21681)
		(end 379.973078 -219.01658)
		(width 0.0889)
		(layer "In13.Cu")
		(net "P5E_CPU0_PE2_RX_DN<11>")
	)
	(arc
		(start 385.707636 -216.574878)
		(mid 385.894834 -216.625021)
		(end 386.082032 -216.574878)
		(width 0.0889)
		(layer "In13.Cu")
		(net "P5E_CPU0_PE2_RX_DN<11>")
	)
	(arc
		(start 380.913132 -217.388694)
		(mid 381.048065 -217.25534)
		(end 381.10033 -217.072972)
		(width 0.0889)
		(layer "In13.Cu")
		(net "P5E_CPU0_PE2_RX_DN<11>")
	)
	(arc
		(start 379.503432 -220.809566)
		(mid 379.220564 -220.323447)
		(end 379.497336 -219.833952)
		(width 0.0889)
		(layer "In13.Cu")
		(net "P5E_CPU0_PE2_RX_DN<11>")
	)
	(arc
		(start 380.452122 -218.197684)
		(mid 380.583036 -218.061324)
		(end 380.630684 -217.878406)
		(width 0.0889)
		(layer "In13.Cu")
		(net "P5E_CPU0_PE2_RX_DN<11>")
	)
	(arc
		(start 380.630684 -217.859864)
		(mid 380.710846 -217.587675)
		(end 380.913132 -217.388694)
		(width 0.0889)
		(layer "In13.Cu")
		(net "P5E_CPU0_PE2_RX_DN<11>")
	)
	(arc
		(start 382.322832 -216.574878)
		(mid 382.605534 -216.499102)
		(end 382.888236 -216.574878)
		(width 0.0889)
		(layer "In13.Cu")
		(net "P5E_CPU0_PE2_RX_DN<11>")
	)
	(arc
		(start 384.202432 -216.574878)
		(mid 384.485134 -216.499102)
		(end 384.767836 -216.574878)
		(width 0.0889)
		(layer "In13.Cu")
		(net "P5E_CPU0_PE2_RX_DN<11>")
	)
	(arc
		(start 380.16053 -218.692222)
		(mid 380.234521 -218.412656)
		(end 380.437136 -218.20632)
		(width 0.0889)
		(layer "In13.Cu")
		(net "P5E_CPU0_PE2_RX_DN<11>")
	)
	(arc
		(start 386.647436 -216.574878)
		(mid 386.722329 -216.608022)
		(end 386.80263 -216.624154)
		(width 0.0889)
		(layer "In13.Cu")
		(net "P5E_CPU0_PE2_RX_DN<11>")
	)
	(segment
		(start 377.906534 -220.320108)
		(end 377.90628 -220.319854)
		(width 0.13208)
		(layer "F.Cu")
		(net "P5E_CPU0_PE2_RX_DN<10>")
	)
	(segment
		(start 377.906534 -220.855794)
		(end 377.906534 -220.320108)
		(width 0.13208)
		(layer "F.Cu")
		(net "P5E_CPU0_PE2_RX_DN<10>")
	)
	(segment
		(start 385.17068 -215.281256)
		(end 384.75031 -215.701626)
		(width 0.0889)
		(layer "In13.Cu")
		(net "P5E_CPU0_PE2_RX_DN<10>")
	)
	(segment
		(start 388.83971 -399.754598)
		(end 395.91996 -354.357686)
		(width 0.14732)
		(layer "In13.Cu")
		(net "P5E_CPU0_PE2_RX_DN<10>")
	)
	(segment
		(start 391.455148 -252.118622)
		(end 391.455148 -251.152152)
		(width 0.14732)
		(layer "In13.Cu")
		(net "P5E_CPU0_PE2_RX_DN<10>")
	)
	(segment
		(start 378.563632 -219.830396)
		(end 378.559822 -219.832682)
		(width 0.0889)
		(layer "In13.Cu")
		(net "P5E_CPU0_PE2_RX_DN<10>")
	)
	(segment
		(start 379.22073 -217.064336)
		(end 379.22073 -217.072972)
		(width 0.0889)
		(layer "In13.Cu")
		(net "P5E_CPU0_PE2_RX_DN<10>")
	)
	(segment
		(start 394.345414 -259.067808)
		(end 393.52347 -255.600454)
		(width 0.14732)
		(layer "In13.Cu")
		(net "P5E_CPU0_PE2_RX_DN<10>")
	)
	(segment
		(start 391.455148 -251.152152)
		(end 391.703814 -249.745246)
		(width 0.14732)
		(layer "In13.Cu")
		(net "P5E_CPU0_PE2_RX_DN<10>")
	)
	(segment
		(start 378.559822 -219.832682)
		(end 378.55144 -219.837508)
		(width 0.0889)
		(layer "In13.Cu")
		(net "P5E_CPU0_PE2_RX_DN<10>")
	)
	(segment
		(start 378.562108 -218.203526)
		(end 378.560838 -218.204288)
		(width 0.0889)
		(layer "In13.Cu")
		(net "P5E_CPU0_PE2_RX_DN<10>")
	)
	(segment
		(start 391.59053 -252.582426)
		(end 391.455148 -252.118622)
		(width 0.14732)
		(layer "In13.Cu")
		(net "P5E_CPU0_PE2_RX_DN<10>")
	)
	(segment
		(start 398.51584 -339.50656)
		(end 391.339324 -309.690008)
		(width 0.14732)
		(layer "In13.Cu")
		(net "P5E_CPU0_PE2_RX_DN<10>")
	)
	(segment
		(start 378.140976 -220.6117)
		(end 378.062744 -220.590872)
		(width 0.0889)
		(layer "In13.Cu")
		(net "P5E_CPU0_PE2_RX_DN<10>")
	)
	(segment
		(start 390.871202 -419.871398)
		(end 390.844786 -419.503606)
		(width 0.14732)
		(layer "In13.Cu")
		(net "P5E_CPU0_PE2_RX_DN<10>")
	)
	(segment
		(start 378.572522 -219.825316)
		(end 378.563632 -219.830396)
		(width 0.0889)
		(layer "In13.Cu")
		(net "P5E_CPU0_PE2_RX_DN<10>")
	)
	(segment
		(start 383.881884 -215.646762)
		(end 380.399798 -215.646762)
		(width 0.0889)
		(layer "In13.Cu")
		(net "P5E_CPU0_PE2_RX_DN<10>")
	)
	(segment
		(start 391.053574 -434.53177)
		(end 391.053574 -424.35145)
		(width 0.14732)
		(layer "In13.Cu")
		(net "P5E_CPU0_PE2_RX_DN<10>")
	)
	(segment
		(start 391.750042 -434.289962)
		(end 391.367264 -434.67274)
		(width 0.14732)
		(layer "In13.Cu")
		(net "P5E_CPU0_PE2_RX_DN<10>")
	)
	(segment
		(start 392.35761 -229.80904)
		(end 391.521188 -225.535744)
		(width 0.14732)
		(layer "In13.Cu")
		(net "P5E_CPU0_PE2_RX_DN<10>")
	)
	(segment
		(start 378.565156 -219.182442)
		(end 378.572522 -219.18676)
		(width 0.0889)
		(layer "In13.Cu")
		(net "P5E_CPU0_PE2_RX_DN<10>")
	)
	(segment
		(start 391.784332 -249.62993)
		(end 393.36472 -244.771926)
		(width 0.14732)
		(layer "In13.Cu")
		(net "P5E_CPU0_PE2_RX_DN<10>")
	)
	(segment
		(start 390.779 -418.805614)
		(end 390.747758 -418.369496)
		(width 0.14732)
		(layer "In13.Cu")
		(net "P5E_CPU0_PE2_RX_DN<10>")
	)
	(segment
		(start 387.704838 -215.239346)
		(end 385.906772 -215.239346)
		(width 0.14732)
		(layer "In13.Cu")
		(net "P5E_CPU0_PE2_RX_DN<10>")
	)
	(segment
		(start 391.703814 -249.745246)
		(end 391.784332 -249.62993)
		(width 0.14732)
		(layer "In13.Cu")
		(net "P5E_CPU0_PE2_RX_DN<10>")
	)
	(segment
		(start 378.572522 -218.197684)
		(end 378.565156 -218.202002)
		(width 0.0889)
		(layer "In13.Cu")
		(net "P5E_CPU0_PE2_RX_DN<10>")
	)
	(segment
		(start 390.18591 -406.051766)
		(end 388.83971 -404.705566)
		(width 0.14732)
		(layer "In13.Cu")
		(net "P5E_CPU0_PE2_RX_DN<10>")
	)
	(segment
		(start 391.053574 -424.35145)
		(end 390.741916 -420.02075)
		(width 0.14732)
		(layer "In13.Cu")
		(net "P5E_CPU0_PE2_RX_DN<10>")
	)
	(segment
		(start 391.367264 -434.67274)
		(end 391.194544 -434.67274)
		(width 0.14732)
		(layer "In13.Cu")
		(net "P5E_CPU0_PE2_RX_DN<10>")
	)
	(segment
		(start 390.18591 -412.303976)
		(end 390.18591 -406.051766)
		(width 0.14732)
		(layer "In13.Cu")
		(net "P5E_CPU0_PE2_RX_DN<10>")
	)
	(segment
		(start 385.906772 -215.239346)
		(end 385.884674 -215.239346)
		(width 0.0889)
		(layer "In13.Cu")
		(net "P5E_CPU0_PE2_RX_DN<10>")
	)
	(segment
		(start 378.56287 -219.181172)
		(end 378.563632 -219.18168)
		(width 0.0889)
		(layer "In13.Cu")
		(net "P5E_CPU0_PE2_RX_DN<10>")
	)
	(segment
		(start 391.339324 -309.690008)
		(end 394.345414 -259.067808)
		(width 0.14732)
		(layer "In13.Cu")
		(net "P5E_CPU0_PE2_RX_DN<10>")
	)
	(segment
		(start 393.36472 -244.771926)
		(end 392.35761 -229.80904)
		(width 0.14732)
		(layer "In13.Cu")
		(net "P5E_CPU0_PE2_RX_DN<10>")
	)
	(segment
		(start 379.506734 -216.572846)
		(end 379.504956 -216.573862)
		(width 0.0889)
		(layer "In13.Cu")
		(net "P5E_CPU0_PE2_RX_DN<10>")
	)
	(segment
		(start 378.751084 -217.859864)
		(end 378.751084 -217.878406)
		(width 0.0889)
		(layer "In13.Cu")
		(net "P5E_CPU0_PE2_RX_DN<10>")
	)
	(segment
		(start 391.851642 -253.212854)
		(end 391.59053 -252.582426)
		(width 0.14732)
		(layer "In13.Cu")
		(net "P5E_CPU0_PE2_RX_DN<10>")
	)
	(segment
		(start 395.91996 -354.357686)
		(end 398.51584 -339.50656)
		(width 0.14732)
		(layer "In13.Cu")
		(net "P5E_CPU0_PE2_RX_DN<10>")
	)
	(segment
		(start 390.614662 -418.254688)
		(end 390.18591 -412.303976)
		(width 0.14732)
		(layer "In13.Cu")
		(net "P5E_CPU0_PE2_RX_DN<10>")
	)
	(segment
		(start 378.565156 -218.202002)
		(end 378.562108 -218.203526)
		(width 0.0889)
		(layer "In13.Cu")
		(net "P5E_CPU0_PE2_RX_DN<10>")
	)
	(segment
		(start 378.062744 -220.590872)
		(end 377.90628 -220.319854)
		(width 0.0889)
		(layer "In13.Cu")
		(net "P5E_CPU0_PE2_RX_DN<10>")
	)
	(segment
		(start 385.884674 -215.239346)
		(end 385.842764 -215.281256)
		(width 0.0889)
		(layer "In13.Cu")
		(net "P5E_CPU0_PE2_RX_DN<10>")
	)
	(segment
		(start 393.52347 -255.600454)
		(end 391.851642 -253.212854)
		(width 0.14732)
		(layer "In13.Cu")
		(net "P5E_CPU0_PE2_RX_DN<10>")
	)
	(segment
		(start 379.512322 -216.569544)
		(end 379.511306 -216.570052)
		(width 0.0889)
		(layer "In13.Cu")
		(net "P5E_CPU0_PE2_RX_DN<10>")
	)
	(segment
		(start 390.844786 -419.503606)
		(end 390.69518 -419.37432)
		(width 0.14732)
		(layer "In13.Cu")
		(net "P5E_CPU0_PE2_RX_DN<10>")
	)
	(segment
		(start 379.690884 -216.235026)
		(end 379.690884 -216.25052)
		(width 0.0889)
		(layer "In13.Cu")
		(net "P5E_CPU0_PE2_RX_DN<10>")
	)
	(segment
		(start 378.560838 -218.204288)
		(end 378.557536 -218.20632)
		(width 0.0889)
		(layer "In13.Cu")
		(net "P5E_CPU0_PE2_RX_DN<10>")
	)
	(segment
		(start 379.512322 -216.569798)
		(end 379.512322 -216.569544)
		(width 0.0889)
		(layer "In13.Cu")
		(net "P5E_CPU0_PE2_RX_DN<10>")
	)
	(segment
		(start 379.504956 -216.573862)
		(end 379.497336 -216.578434)
		(width 0.0889)
		(layer "In13.Cu")
		(net "P5E_CPU0_PE2_RX_DN<10>")
	)
	(segment
		(start 385.842764 -215.281256)
		(end 385.17068 -215.281256)
		(width 0.0889)
		(layer "In13.Cu")
		(net "P5E_CPU0_PE2_RX_DN<10>")
	)
	(segment
		(start 391.521188 -225.535744)
		(end 388.737094 -216.271348)
		(width 0.14732)
		(layer "In13.Cu")
		(net "P5E_CPU0_PE2_RX_DN<10>")
	)
	(segment
		(start 390.69518 -419.37432)
		(end 390.663938 -418.93871)
		(width 0.14732)
		(layer "In13.Cu")
		(net "P5E_CPU0_PE2_RX_DN<10>")
	)
	(segment
		(start 388.83971 -404.705566)
		(end 388.83971 -399.754598)
		(width 0.14732)
		(layer "In13.Cu")
		(net "P5E_CPU0_PE2_RX_DN<10>")
	)
	(segment
		(start 378.557536 -219.178124)
		(end 378.56287 -219.181172)
		(width 0.0889)
		(layer "In13.Cu")
		(net "P5E_CPU0_PE2_RX_DN<10>")
	)
	(segment
		(start 390.663938 -418.93871)
		(end 390.779 -418.805614)
		(width 0.14732)
		(layer "In13.Cu")
		(net "P5E_CPU0_PE2_RX_DN<10>")
	)
	(segment
		(start 379.511306 -216.570052)
		(end 379.508258 -216.57183)
		(width 0.0889)
		(layer "In13.Cu")
		(net "P5E_CPU0_PE2_RX_DN<10>")
	)
	(segment
		(start 378.563632 -219.18168)
		(end 378.565156 -219.182442)
		(width 0.0889)
		(layer "In13.Cu")
		(net "P5E_CPU0_PE2_RX_DN<10>")
	)
	(segment
		(start 390.747758 -418.369496)
		(end 390.614662 -418.254688)
		(width 0.14732)
		(layer "In13.Cu")
		(net "P5E_CPU0_PE2_RX_DN<10>")
	)
	(segment
		(start 379.508258 -216.57183)
		(end 379.506734 -216.572846)
		(width 0.0889)
		(layer "In13.Cu")
		(net "P5E_CPU0_PE2_RX_DN<10>")
	)
	(segment
		(start 391.194544 -434.67274)
		(end 391.053574 -434.53177)
		(width 0.14732)
		(layer "In13.Cu")
		(net "P5E_CPU0_PE2_RX_DN<10>")
	)
	(segment
		(start 390.741916 -420.02075)
		(end 390.871202 -419.871398)
		(width 0.14732)
		(layer "In13.Cu")
		(net "P5E_CPU0_PE2_RX_DN<10>")
	)
	(segment
		(start 388.737094 -216.271348)
		(end 387.704838 -215.239346)
		(width 0.14732)
		(layer "In13.Cu")
		(net "P5E_CPU0_PE2_RX_DN<10>")
	)
	(arc
		(start 380.012956 -215.739726)
		(mid 379.98615 -215.753492)
		(end 379.960124 -215.768682)
		(width 0.0889)
		(layer "In13.Cu")
		(net "P5E_CPU0_PE2_RX_DN<10>")
	)
	(arc
		(start 384.310128 -215.76792)
		(mid 384.104428 -215.677555)
		(end 383.881884 -215.646762)
		(width 0.0889)
		(layer "In13.Cu")
		(net "P5E_CPU0_PE2_RX_DN<10>")
	)
	(arc
		(start 384.733038 -215.717882)
		(mid 384.703887 -215.740977)
		(end 384.672586 -215.761062)
		(width 0.0889)
		(layer "In13.Cu")
		(net "P5E_CPU0_PE2_RX_DN<10>")
	)
	(arc
		(start 379.960124 -215.768682)
		(mid 379.76638 -215.967732)
		(end 379.690884 -216.235026)
		(width 0.0889)
		(layer "In13.Cu")
		(net "P5E_CPU0_PE2_RX_DN<10>")
	)
	(arc
		(start 384.75031 -215.701626)
		(mid 384.741803 -215.709891)
		(end 384.733038 -215.717882)
		(width 0.0889)
		(layer "In13.Cu")
		(net "P5E_CPU0_PE2_RX_DN<10>")
	)
	(arc
		(start 380.399798 -215.646762)
		(mid 380.20085 -215.670243)
		(end 380.012956 -215.739726)
		(width 0.0889)
		(layer "In13.Cu")
		(net "P5E_CPU0_PE2_RX_DN<10>")
	)
	(arc
		(start 378.572522 -219.18676)
		(mid 378.751119 -219.506038)
		(end 378.572522 -219.825316)
		(width 0.0889)
		(layer "In13.Cu")
		(net "P5E_CPU0_PE2_RX_DN<10>")
	)
	(arc
		(start 379.690884 -216.25052)
		(mid 379.643205 -216.43342)
		(end 379.512322 -216.569798)
		(width 0.0889)
		(layer "In13.Cu")
		(net "P5E_CPU0_PE2_RX_DN<10>")
	)
	(arc
		(start 378.751084 -217.878406)
		(mid 378.703405 -218.061306)
		(end 378.572522 -218.197684)
		(width 0.0889)
		(layer "In13.Cu")
		(net "P5E_CPU0_PE2_RX_DN<10>")
	)
	(arc
		(start 379.033532 -217.388694)
		(mid 378.831246 -217.587675)
		(end 378.751084 -217.859864)
		(width 0.0889)
		(layer "In13.Cu")
		(net "P5E_CPU0_PE2_RX_DN<10>")
	)
	(arc
		(start 378.557536 -218.20632)
		(mid 378.280962 -218.692222)
		(end 378.557536 -219.178124)
		(width 0.0889)
		(layer "In13.Cu")
		(net "P5E_CPU0_PE2_RX_DN<10>")
	)
	(arc
		(start 378.28093 -220.319854)
		(mid 378.24407 -220.481651)
		(end 378.140976 -220.6117)
		(width 0.0889)
		(layer "In13.Cu")
		(net "P5E_CPU0_PE2_RX_DN<10>")
	)
	(arc
		(start 384.672586 -215.761062)
		(mid 384.492239 -215.811265)
		(end 384.310128 -215.76792)
		(width 0.0889)
		(layer "In13.Cu")
		(net "P5E_CPU0_PE2_RX_DN<10>")
	)
	(arc
		(start 378.55144 -219.837508)
		(mid 378.353212 -220.043356)
		(end 378.28093 -220.319854)
		(width 0.0889)
		(layer "In13.Cu")
		(net "P5E_CPU0_PE2_RX_DN<10>")
	)
	(arc
		(start 379.497336 -216.578434)
		(mid 379.294749 -216.784785)
		(end 379.22073 -217.064336)
		(width 0.0889)
		(layer "In13.Cu")
		(net "P5E_CPU0_PE2_RX_DN<10>")
	)
	(arc
		(start 379.22073 -217.072972)
		(mid 379.16846 -217.255337)
		(end 379.033532 -217.388694)
		(width 0.0889)
		(layer "In13.Cu")
		(net "P5E_CPU0_PE2_RX_DN<10>")
	)
	(segment
		(start 368.508534 -220.855794)
		(end 368.508534 -220.320108)
		(width 0.13208)
		(layer "F.Cu")
		(net "P5E_CPU0_PE2_RX_DN<0>")
	)
	(segment
		(start 368.508534 -220.320108)
		(end 368.50828 -220.319854)
		(width 0.13208)
		(layer "F.Cu")
		(net "P5E_CPU0_PE2_RX_DN<0>")
	)
	(segment
		(start 369.165632 -216.574878)
		(end 369.161822 -216.577164)
		(width 0.0889)
		(layer "In13.Cu")
		(net "P5E_CPU0_PE2_RX_DN<0>")
	)
	(segment
		(start 414.356042 -420.737538)
		(end 420.816786 -410.752544)
		(width 0.14732)
		(layer "In13.Cu")
		(net "P5E_CPU0_PE2_RX_DN<0>")
	)
	(segment
		(start 413.98317 -421.313356)
		(end 414.155128 -421.276526)
		(width 0.14732)
		(layer "In13.Cu")
		(net "P5E_CPU0_PE2_RX_DN<0>")
	)
	(segment
		(start 405.218138 -253.5047)
		(end 405.020272 -247.606566)
		(width 0.14732)
		(layer "In13.Cu")
		(net "P5E_CPU0_PE2_RX_DN<0>")
	)
	(segment
		(start 385.782058 -199.46366)
		(end 383.931668 -199.180196)
		(width 0.14732)
		(layer "In13.Cu")
		(net "P5E_CPU0_PE2_RX_DN<0>")
	)
	(segment
		(start 405.020272 -247.606566)
		(end 401.374102 -223.440752)
		(width 0.14732)
		(layer "In13.Cu")
		(net "P5E_CPU0_PE2_RX_DN<0>")
	)
	(segment
		(start 413.54502 -422.21912)
		(end 413.782764 -421.85209)
		(width 0.14732)
		(layer "In13.Cu")
		(net "P5E_CPU0_PE2_RX_DN<0>")
	)
	(segment
		(start 401.374102 -223.440752)
		(end 397.713708 -210.842606)
		(width 0.14732)
		(layer "In13.Cu")
		(net "P5E_CPU0_PE2_RX_DN<0>")
	)
	(segment
		(start 412.190946 -434.71973)
		(end 412.066232 -434.595016)
		(width 0.14732)
		(layer "In13.Cu")
		(net "P5E_CPU0_PE2_RX_DN<0>")
	)
	(segment
		(start 408.456638 -339.773514)
		(end 401.033234 -307.464206)
		(width 0.14732)
		(layer "In13.Cu")
		(net "P5E_CPU0_PE2_RX_DN<0>")
	)
	(segment
		(start 412.066232 -434.595016)
		(end 412.066232 -424.275758)
		(width 0.14732)
		(layer "In13.Cu")
		(net "P5E_CPU0_PE2_RX_DN<0>")
	)
	(segment
		(start 369.311428 -215.165432)
		(end 369.311428 -215.68283)
		(width 0.14732)
		(layer "In13.Cu")
		(net "P5E_CPU0_PE2_RX_DN<0>")
	)
	(segment
		(start 369.353338 -216.250266)
		(end 369.353084 -216.25052)
		(width 0.0889)
		(layer "In13.Cu")
		(net "P5E_CPU0_PE2_RX_DN<0>")
	)
	(segment
		(start 369.174522 -218.197684)
		(end 369.159536 -218.20632)
		(width 0.0889)
		(layer "In13.Cu")
		(net "P5E_CPU0_PE2_RX_DN<0>")
	)
	(segment
		(start 382.093724 -198.898764)
		(end 381.035814 -198.898764)
		(width 0.14732)
		(layer "In13.Cu")
		(net "P5E_CPU0_PE2_RX_DN<0>")
	)
	(segment
		(start 369.161822 -216.577164)
		(end 369.15344 -216.58199)
		(width 0.0889)
		(layer "In13.Cu")
		(net "P5E_CPU0_PE2_RX_DN<0>")
	)
	(segment
		(start 419.620954 -400.702526)
		(end 407.076402 -368.924078)
		(width 0.14732)
		(layer "In13.Cu")
		(net "P5E_CPU0_PE2_RX_DN<0>")
	)
	(segment
		(start 369.165632 -217.554048)
		(end 369.174522 -217.559128)
		(width 0.0889)
		(layer "In13.Cu")
		(net "P5E_CPU0_PE2_RX_DN<0>")
	)
	(segment
		(start 405.217122 -253.519686)
		(end 405.218138 -253.5047)
		(width 0.14732)
		(layer "In13.Cu")
		(net "P5E_CPU0_PE2_RX_DN<0>")
	)
	(segment
		(start 397.713708 -210.842606)
		(end 387.1341 -200.023984)
		(width 0.14732)
		(layer "In13.Cu")
		(net "P5E_CPU0_PE2_RX_DN<0>")
	)
	(segment
		(start 370.568982 -211.490306)
		(end 370.151152 -213.59368)
		(width 0.14732)
		(layer "In13.Cu")
		(net "P5E_CPU0_PE2_RX_DN<0>")
	)
	(segment
		(start 383.931414 -199.179942)
		(end 382.093724 -198.898764)
		(width 0.14732)
		(layer "In13.Cu")
		(net "P5E_CPU0_PE2_RX_DN<0>")
	)
	(segment
		(start 369.161822 -219.832682)
		(end 369.15344 -219.837508)
		(width 0.0889)
		(layer "In13.Cu")
		(net "P5E_CPU0_PE2_RX_DN<0>")
	)
	(segment
		(start 414.392872 -420.909496)
		(end 414.356042 -420.737538)
		(width 0.14732)
		(layer "In13.Cu")
		(net "P5E_CPU0_PE2_RX_DN<0>")
	)
	(segment
		(start 420.81831 -410.75102)
		(end 420.81831 -406.722072)
		(width 0.14732)
		(layer "In13.Cu")
		(net "P5E_CPU0_PE2_RX_DN<0>")
	)
	(segment
		(start 406.586944 -366.166146)
		(end 406.88768 -348.135702)
		(width 0.14732)
		(layer "In13.Cu")
		(net "P5E_CPU0_PE2_RX_DN<0>")
	)
	(segment
		(start 401.033234 -307.464206)
		(end 405.216868 -253.519686)
		(width 0.14732)
		(layer "In13.Cu")
		(net "P5E_CPU0_PE2_RX_DN<0>")
	)
	(segment
		(start 378.098558 -201.149204)
		(end 371.708934 -208.45526)
		(width 0.14732)
		(layer "In13.Cu")
		(net "P5E_CPU0_PE2_RX_DN<0>")
	)
	(segment
		(start 405.216868 -253.519686)
		(end 405.217122 -253.519686)
		(width 0.14732)
		(layer "In13.Cu")
		(net "P5E_CPU0_PE2_RX_DN<0>")
	)
	(segment
		(start 412.320232 -434.71973)
		(end 412.190946 -434.71973)
		(width 0.14732)
		(layer "In13.Cu")
		(net "P5E_CPU0_PE2_RX_DN<0>")
	)
	(segment
		(start 420.816786 -410.752544)
		(end 420.81831 -410.75102)
		(width 0.14732)
		(layer "In13.Cu")
		(net "P5E_CPU0_PE2_RX_DN<0>")
	)
	(segment
		(start 370.151152 -213.59368)
		(end 369.311428 -215.165432)
		(width 0.14732)
		(layer "In13.Cu")
		(net "P5E_CPU0_PE2_RX_DN<0>")
	)
	(segment
		(start 369.159536 -219.178124)
		(end 369.165632 -219.18168)
		(width 0.0889)
		(layer "In13.Cu")
		(net "P5E_CPU0_PE2_RX_DN<0>")
	)
	(segment
		(start 368.88293 -217.064336)
		(end 368.88293 -217.071956)
		(width 0.0889)
		(layer "In13.Cu")
		(net "P5E_CPU0_PE2_RX_DN<0>")
	)
	(segment
		(start 413.782764 -421.85209)
		(end 413.745934 -421.680132)
		(width 0.14732)
		(layer "In13.Cu")
		(net "P5E_CPU0_PE2_RX_DN<0>")
	)
	(segment
		(start 369.311428 -215.704928)
		(end 369.353338 -215.746838)
		(width 0.0889)
		(layer "In13.Cu")
		(net "P5E_CPU0_PE2_RX_DN<0>")
	)
	(segment
		(start 412.066232 -424.275758)
		(end 413.373062 -422.256204)
		(width 0.14732)
		(layer "In13.Cu")
		(net "P5E_CPU0_PE2_RX_DN<0>")
	)
	(segment
		(start 414.155128 -421.276526)
		(end 414.392872 -420.909496)
		(width 0.14732)
		(layer "In13.Cu")
		(net "P5E_CPU0_PE2_RX_DN<0>")
	)
	(segment
		(start 387.1341 -200.023984)
		(end 385.782058 -199.46366)
		(width 0.14732)
		(layer "In13.Cu")
		(net "P5E_CPU0_PE2_RX_DN<0>")
	)
	(segment
		(start 412.75 -434.289962)
		(end 412.320232 -434.71973)
		(width 0.14732)
		(layer "In13.Cu")
		(net "P5E_CPU0_PE2_RX_DN<0>")
	)
	(segment
		(start 371.708934 -208.45526)
		(end 370.568982 -211.490306)
		(width 0.14732)
		(layer "In13.Cu")
		(net "P5E_CPU0_PE2_RX_DN<0>")
	)
	(segment
		(start 381.035814 -198.898764)
		(end 379.863604 -199.384412)
		(width 0.14732)
		(layer "In13.Cu")
		(net "P5E_CPU0_PE2_RX_DN<0>")
	)
	(segment
		(start 369.311428 -215.68283)
		(end 369.311428 -215.704928)
		(width 0.0889)
		(layer "In13.Cu")
		(net "P5E_CPU0_PE2_RX_DN<0>")
	)
	(segment
		(start 420.81831 -406.722072)
		(end 419.620954 -400.702526)
		(width 0.14732)
		(layer "In13.Cu")
		(net "P5E_CPU0_PE2_RX_DN<0>")
	)
	(segment
		(start 369.165632 -219.830396)
		(end 369.161822 -219.832682)
		(width 0.0889)
		(layer "In13.Cu")
		(net "P5E_CPU0_PE2_RX_DN<0>")
	)
	(segment
		(start 369.165632 -219.18168)
		(end 369.174522 -219.18676)
		(width 0.0889)
		(layer "In13.Cu")
		(net "P5E_CPU0_PE2_RX_DN<0>")
	)
	(segment
		(start 383.931668 -199.180196)
		(end 383.931414 -199.179942)
		(width 0.14732)
		(layer "In13.Cu")
		(net "P5E_CPU0_PE2_RX_DN<0>")
	)
	(segment
		(start 369.353338 -215.746838)
		(end 369.353338 -216.250266)
		(width 0.0889)
		(layer "In13.Cu")
		(net "P5E_CPU0_PE2_RX_DN<0>")
	)
	(segment
		(start 369.174522 -219.825316)
		(end 369.165632 -219.830396)
		(width 0.0889)
		(layer "In13.Cu")
		(net "P5E_CPU0_PE2_RX_DN<0>")
	)
	(segment
		(start 379.863604 -199.384412)
		(end 378.098558 -201.149204)
		(width 0.14732)
		(layer "In13.Cu")
		(net "P5E_CPU0_PE2_RX_DN<0>")
	)
	(segment
		(start 413.745934 -421.680132)
		(end 413.98317 -421.313356)
		(width 0.14732)
		(layer "In13.Cu")
		(net "P5E_CPU0_PE2_RX_DN<0>")
	)
	(segment
		(start 368.664744 -220.590872)
		(end 368.50828 -220.319854)
		(width 0.0889)
		(layer "In13.Cu")
		(net "P5E_CPU0_PE2_RX_DN<0>")
	)
	(segment
		(start 407.076402 -368.924078)
		(end 406.586944 -366.166146)
		(width 0.14732)
		(layer "In13.Cu")
		(net "P5E_CPU0_PE2_RX_DN<0>")
	)
	(segment
		(start 369.174522 -216.569798)
		(end 369.165632 -216.574878)
		(width 0.0889)
		(layer "In13.Cu")
		(net "P5E_CPU0_PE2_RX_DN<0>")
	)
	(segment
		(start 368.742976 -220.6117)
		(end 368.664744 -220.590872)
		(width 0.0889)
		(layer "In13.Cu")
		(net "P5E_CPU0_PE2_RX_DN<0>")
	)
	(segment
		(start 413.373062 -422.256204)
		(end 413.54502 -422.21912)
		(width 0.14732)
		(layer "In13.Cu")
		(net "P5E_CPU0_PE2_RX_DN<0>")
	)
	(segment
		(start 406.88768 -348.135702)
		(end 408.456638 -339.773514)
		(width 0.14732)
		(layer "In13.Cu")
		(net "P5E_CPU0_PE2_RX_DN<0>")
	)
	(arc
		(start 368.88293 -217.071956)
		(mid 368.960559 -217.350369)
		(end 369.165632 -217.554048)
		(width 0.0889)
		(layer "In13.Cu")
		(net "P5E_CPU0_PE2_RX_DN<0>")
	)
	(arc
		(start 369.174522 -217.559128)
		(mid 369.352998 -217.878406)
		(end 369.174522 -218.197684)
		(width 0.0889)
		(layer "In13.Cu")
		(net "P5E_CPU0_PE2_RX_DN<0>")
	)
	(arc
		(start 369.159536 -218.20632)
		(mid 368.882962 -218.692222)
		(end 369.159536 -219.178124)
		(width 0.0889)
		(layer "In13.Cu")
		(net "P5E_CPU0_PE2_RX_DN<0>")
	)
	(arc
		(start 369.353084 -216.25052)
		(mid 369.305405 -216.43342)
		(end 369.174522 -216.569798)
		(width 0.0889)
		(layer "In13.Cu")
		(net "P5E_CPU0_PE2_RX_DN<0>")
	)
	(arc
		(start 369.15344 -219.837508)
		(mid 368.955212 -220.043356)
		(end 368.88293 -220.319854)
		(width 0.0889)
		(layer "In13.Cu")
		(net "P5E_CPU0_PE2_RX_DN<0>")
	)
	(arc
		(start 369.174522 -219.18676)
		(mid 369.353119 -219.506038)
		(end 369.174522 -219.825316)
		(width 0.0889)
		(layer "In13.Cu")
		(net "P5E_CPU0_PE2_RX_DN<0>")
	)
	(arc
		(start 368.88293 -220.319854)
		(mid 368.84607 -220.481651)
		(end 368.742976 -220.6117)
		(width 0.0889)
		(layer "In13.Cu")
		(net "P5E_CPU0_PE2_RX_DN<0>")
	)
	(arc
		(start 369.15344 -216.58199)
		(mid 368.955212 -216.787838)
		(end 368.88293 -217.064336)
		(width 0.0889)
		(layer "In13.Cu")
		(net "P5E_CPU0_PE2_RX_DN<0>")
	)
	(segment
		(start 358.640634 -224.925382)
		(end 358.640634 -224.389442)
		(width 0.13208)
		(layer "F.Cu")
		(net "P5E_CPU0_PE1_TX_DP<9>")
	)
	(segment
		(start 407.106628 -17.300194)
		(end 407.106628 -16.681958)
		(width 0.13208)
		(layer "F.Cu")
		(net "P5E_CPU0_PE1_TX_DP<9>")
	)
	(segment
		(start 406.805384 -17.601438)
		(end 407.106628 -17.300194)
		(width 0.13208)
		(layer "F.Cu")
		(net "P5E_CPU0_PE1_TX_DP<9>")
	)
	(segment
		(start 407.106628 -16.681958)
		(end 406.779984 -16.355314)
		(width 0.13208)
		(layer "F.Cu")
		(net "P5E_CPU0_PE1_TX_DP<9>")
	)
	(segment
		(start 360.808778 -158.7627)
		(end 356.274878 -184.487566)
		(width 0.14732)
		(layer "In2.Cu")
		(net "P5E_CPU0_PE1_TX_DP<9>")
	)
	(segment
		(start 358.075484 -217.859864)
		(end 358.075484 -217.888312)
		(width 0.0889)
		(layer "In2.Cu")
		(net "P5E_CPU0_PE1_TX_DP<9>")
	)
	(segment
		(start 358.03332 -214.031068)
		(end 358.07523 -214.072978)
		(width 0.0889)
		(layer "In2.Cu")
		(net "P5E_CPU0_PE1_TX_DP<9>")
	)
	(segment
		(start 358.772968 -224.02927)
		(end 358.797098 -224.118424)
		(width 0.0889)
		(layer "In2.Cu")
		(net "P5E_CPU0_PE1_TX_DP<9>")
	)
	(segment
		(start 358.545384 -221.937834)
		(end 358.545384 -221.94774)
		(width 0.0889)
		(layer "In2.Cu")
		(net "P5E_CPU0_PE1_TX_DP<9>")
	)
	(segment
		(start 358.075484 -222.75165)
		(end 358.075484 -222.780098)
		(width 0.0889)
		(layer "In2.Cu")
		(net "P5E_CPU0_PE1_TX_DP<9>")
	)
	(segment
		(start 358.075484 -216.235026)
		(end 358.075484 -216.260426)
		(width 0.0889)
		(layer "In2.Cu")
		(net "P5E_CPU0_PE1_TX_DP<9>")
	)
	(segment
		(start 406.805384 -17.601438)
		(end 407.100024 -17.896078)
		(width 0.14732)
		(layer "In2.Cu")
		(net "P5E_CPU0_PE1_TX_DP<9>")
	)
	(segment
		(start 358.361234 -218.369896)
		(end 358.366822 -218.372944)
		(width 0.0889)
		(layer "In2.Cu")
		(net "P5E_CPU0_PE1_TX_DP<9>")
	)
	(segment
		(start 408.934666 -71.625714)
		(end 407.528522 -79.925418)
		(width 0.14732)
		(layer "In2.Cu")
		(net "P5E_CPU0_PE1_TX_DP<9>")
	)
	(segment
		(start 407.100024 -21.137372)
		(end 408.934666 -71.625714)
		(width 0.14732)
		(layer "In2.Cu")
		(net "P5E_CPU0_PE1_TX_DP<9>")
	)
	(segment
		(start 358.360472 -219.015056)
		(end 358.358694 -219.016072)
		(width 0.0889)
		(layer "In2.Cu")
		(net "P5E_CPU0_PE1_TX_DP<9>")
	)
	(segment
		(start 358.54513 -223.56699)
		(end 358.54513 -223.575626)
		(width 0.0889)
		(layer "In2.Cu")
		(net "P5E_CPU0_PE1_TX_DP<9>")
	)
	(segment
		(start 356.274878 -184.487566)
		(end 358.03332 -212.756242)
		(width 0.14732)
		(layer "In2.Cu")
		(net "P5E_CPU0_PE1_TX_DP<9>")
	)
	(segment
		(start 358.03332 -212.756242)
		(end 358.03332 -214.00897)
		(width 0.14732)
		(layer "In2.Cu")
		(net "P5E_CPU0_PE1_TX_DP<9>")
	)
	(segment
		(start 358.358694 -219.016072)
		(end 358.357932 -219.01658)
		(width 0.0889)
		(layer "In2.Cu")
		(net "P5E_CPU0_PE1_TX_DP<9>")
	)
	(segment
		(start 358.03332 -214.00897)
		(end 358.03332 -214.031068)
		(width 0.0889)
		(layer "In2.Cu")
		(net "P5E_CPU0_PE1_TX_DP<9>")
	)
	(segment
		(start 358.357932 -216.739978)
		(end 358.366822 -216.745058)
		(width 0.0889)
		(layer "In2.Cu")
		(net "P5E_CPU0_PE1_TX_DP<9>")
	)
	(segment
		(start 358.358694 -215.112854)
		(end 358.366568 -215.117426)
		(width 0.0889)
		(layer "In2.Cu")
		(net "P5E_CPU0_PE1_TX_DP<9>")
	)
	(segment
		(start 358.361234 -219.014548)
		(end 358.360472 -219.015056)
		(width 0.0889)
		(layer "In2.Cu")
		(net "P5E_CPU0_PE1_TX_DP<9>")
	)
	(segment
		(start 407.100024 -17.896078)
		(end 407.100024 -21.137372)
		(width 0.14732)
		(layer "In2.Cu")
		(net "P5E_CPU0_PE1_TX_DP<9>")
	)
	(segment
		(start 358.36606 -219.012008)
		(end 358.361234 -219.014548)
		(width 0.0889)
		(layer "In2.Cu")
		(net "P5E_CPU0_PE1_TX_DP<9>")
	)
	(segment
		(start 358.357932 -218.367864)
		(end 358.358694 -218.368372)
		(width 0.0889)
		(layer "In2.Cu")
		(net "P5E_CPU0_PE1_TX_DP<9>")
	)
	(segment
		(start 358.797098 -224.118424)
		(end 358.640634 -224.389442)
		(width 0.0889)
		(layer "In2.Cu")
		(net "P5E_CPU0_PE1_TX_DP<9>")
	)
	(segment
		(start 358.54513 -220.311218)
		(end 358.54513 -220.334078)
		(width 0.0889)
		(layer "In2.Cu")
		(net "P5E_CPU0_PE1_TX_DP<9>")
	)
	(segment
		(start 358.827832 -220.809566)
		(end 358.836722 -220.814646)
		(width 0.0889)
		(layer "In2.Cu")
		(net "P5E_CPU0_PE1_TX_DP<9>")
	)
	(segment
		(start 407.528522 -79.925418)
		(end 360.808778 -158.7627)
		(width 0.14732)
		(layer "In2.Cu")
		(net "P5E_CPU0_PE1_TX_DP<9>")
	)
	(segment
		(start 358.366822 -217.383614)
		(end 358.357932 -217.388694)
		(width 0.0889)
		(layer "In2.Cu")
		(net "P5E_CPU0_PE1_TX_DP<9>")
	)
	(segment
		(start 358.366568 -215.755982)
		(end 358.357678 -215.761062)
		(width 0.0889)
		(layer "In2.Cu")
		(net "P5E_CPU0_PE1_TX_DP<9>")
	)
	(segment
		(start 358.366822 -219.0115)
		(end 358.36606 -219.012008)
		(width 0.0889)
		(layer "In2.Cu")
		(net "P5E_CPU0_PE1_TX_DP<9>")
	)
	(segment
		(start 358.358694 -218.368372)
		(end 358.361234 -218.369896)
		(width 0.0889)
		(layer "In2.Cu")
		(net "P5E_CPU0_PE1_TX_DP<9>")
	)
	(segment
		(start 358.07523 -214.072978)
		(end 358.07523 -214.636858)
		(width 0.0889)
		(layer "In2.Cu")
		(net "P5E_CPU0_PE1_TX_DP<9>")
	)
	(segment
		(start 358.836722 -221.453202)
		(end 358.827832 -221.458282)
		(width 0.0889)
		(layer "In2.Cu")
		(net "P5E_CPU0_PE1_TX_DP<9>")
	)
	(segment
		(start 358.366822 -222.267018)
		(end 358.357932 -222.272098)
		(width 0.0889)
		(layer "In2.Cu")
		(net "P5E_CPU0_PE1_TX_DP<9>")
	)
	(segment
		(start 358.075484 -219.496132)
		(end 358.075484 -219.515944)
		(width 0.0889)
		(layer "In2.Cu")
		(net "P5E_CPU0_PE1_TX_DP<9>")
	)
	(segment
		(start 358.357678 -215.112346)
		(end 358.358694 -215.112854)
		(width 0.0889)
		(layer "In2.Cu")
		(net "P5E_CPU0_PE1_TX_DP<9>")
	)
	(arc
		(start 358.545384 -217.057732)
		(mid 358.545374 -217.067132)
		(end 358.54513 -217.076528)
		(width 0.0889)
		(layer "In2.Cu")
		(net "P5E_CPU0_PE1_TX_DP<9>")
	)
	(arc
		(start 359.015284 -221.140528)
		(mid 358.966031 -221.319728)
		(end 358.836722 -221.453202)
		(width 0.0889)
		(layer "In2.Cu")
		(net "P5E_CPU0_PE1_TX_DP<9>")
	)
	(arc
		(start 358.07523 -214.636858)
		(mid 358.154371 -214.911481)
		(end 358.357678 -215.112346)
		(width 0.0889)
		(layer "In2.Cu")
		(net "P5E_CPU0_PE1_TX_DP<9>")
	)
	(arc
		(start 358.54513 -215.446864)
		(mid 358.49497 -215.624006)
		(end 358.366568 -215.755982)
		(width 0.0889)
		(layer "In2.Cu")
		(net "P5E_CPU0_PE1_TX_DP<9>")
	)
	(arc
		(start 358.54513 -223.575626)
		(mid 358.605173 -223.829513)
		(end 358.772968 -224.02927)
		(width 0.0889)
		(layer "In2.Cu")
		(net "P5E_CPU0_PE1_TX_DP<9>")
	)
	(arc
		(start 358.357932 -223.251268)
		(mid 358.492865 -223.384622)
		(end 358.54513 -223.56699)
		(width 0.0889)
		(layer "In2.Cu")
		(net "P5E_CPU0_PE1_TX_DP<9>")
	)
	(arc
		(start 358.366822 -218.372944)
		(mid 358.545419 -218.692222)
		(end 358.366822 -219.0115)
		(width 0.0889)
		(layer "In2.Cu")
		(net "P5E_CPU0_PE1_TX_DP<9>")
	)
	(arc
		(start 358.357932 -217.388694)
		(mid 358.155646 -217.587675)
		(end 358.075484 -217.859864)
		(width 0.0889)
		(layer "In2.Cu")
		(net "P5E_CPU0_PE1_TX_DP<9>")
	)
	(arc
		(start 358.545384 -221.94774)
		(mid 358.497705 -222.13064)
		(end 358.366822 -222.267018)
		(width 0.0889)
		(layer "In2.Cu")
		(net "P5E_CPU0_PE1_TX_DP<9>")
	)
	(arc
		(start 358.366568 -215.117426)
		(mid 358.493822 -215.247392)
		(end 358.544876 -215.421972)
		(width 0.0889)
		(layer "In2.Cu")
		(net "P5E_CPU0_PE1_TX_DP<9>")
	)
	(arc
		(start 358.357678 -215.761062)
		(mid 358.154855 -215.961293)
		(end 358.075484 -216.235026)
		(width 0.0889)
		(layer "In2.Cu")
		(net "P5E_CPU0_PE1_TX_DP<9>")
	)
	(arc
		(start 358.357932 -219.995496)
		(mid 358.492865 -220.12885)
		(end 358.54513 -220.311218)
		(width 0.0889)
		(layer "In2.Cu")
		(net "P5E_CPU0_PE1_TX_DP<9>")
	)
	(arc
		(start 358.54513 -217.076528)
		(mid 358.494637 -217.252506)
		(end 358.366822 -217.383614)
		(width 0.0889)
		(layer "In2.Cu")
		(net "P5E_CPU0_PE1_TX_DP<9>")
	)
	(arc
		(start 358.544876 -215.421972)
		(mid 358.545209 -215.434416)
		(end 358.54513 -215.446864)
		(width 0.0889)
		(layer "In2.Cu")
		(net "P5E_CPU0_PE1_TX_DP<9>")
	)
	(arc
		(start 358.827832 -221.458282)
		(mid 358.623497 -221.660887)
		(end 358.545384 -221.937834)
		(width 0.0889)
		(layer "In2.Cu")
		(net "P5E_CPU0_PE1_TX_DP<9>")
	)
	(arc
		(start 358.075484 -222.780098)
		(mid 358.155646 -223.052287)
		(end 358.357932 -223.251268)
		(width 0.0889)
		(layer "In2.Cu")
		(net "P5E_CPU0_PE1_TX_DP<9>")
	)
	(arc
		(start 359.015284 -221.124526)
		(mid 359.015372 -221.132527)
		(end 359.015284 -221.140528)
		(width 0.0889)
		(layer "In2.Cu")
		(net "P5E_CPU0_PE1_TX_DP<9>")
	)
	(arc
		(start 358.075484 -219.515944)
		(mid 358.153595 -219.792893)
		(end 358.357932 -219.995496)
		(width 0.0889)
		(layer "In2.Cu")
		(net "P5E_CPU0_PE1_TX_DP<9>")
	)
	(arc
		(start 358.357932 -222.272098)
		(mid 358.153597 -222.474703)
		(end 358.075484 -222.75165)
		(width 0.0889)
		(layer "In2.Cu")
		(net "P5E_CPU0_PE1_TX_DP<9>")
	)
	(arc
		(start 358.075484 -216.260426)
		(mid 358.153595 -216.537375)
		(end 358.357932 -216.739978)
		(width 0.0889)
		(layer "In2.Cu")
		(net "P5E_CPU0_PE1_TX_DP<9>")
	)
	(arc
		(start 358.366822 -216.745058)
		(mid 358.496111 -216.878544)
		(end 358.545384 -217.057732)
		(width 0.0889)
		(layer "In2.Cu")
		(net "P5E_CPU0_PE1_TX_DP<9>")
	)
	(arc
		(start 358.836722 -220.814646)
		(mid 358.965316 -220.94692)
		(end 359.015284 -221.124526)
		(width 0.0889)
		(layer "In2.Cu")
		(net "P5E_CPU0_PE1_TX_DP<9>")
	)
	(arc
		(start 358.075484 -217.888312)
		(mid 358.153595 -218.165261)
		(end 358.357932 -218.367864)
		(width 0.0889)
		(layer "In2.Cu")
		(net "P5E_CPU0_PE1_TX_DP<9>")
	)
	(arc
		(start 358.357932 -219.01658)
		(mid 358.153597 -219.219185)
		(end 358.075484 -219.496132)
		(width 0.0889)
		(layer "In2.Cu")
		(net "P5E_CPU0_PE1_TX_DP<9>")
	)
	(arc
		(start 358.54513 -220.334078)
		(mid 358.624349 -220.608763)
		(end 358.827832 -220.809566)
		(width 0.0889)
		(layer "In2.Cu")
		(net "P5E_CPU0_PE1_TX_DP<9>")
	)
	(segment
		(start 410.462984 -19.125438)
		(end 410.159708 -18.822162)
		(width 0.13208)
		(layer "F.Cu")
		(net "P5E_CPU0_PE1_TX_DP<8>")
	)
	(segment
		(start 410.159708 -18.822162)
		(end 410.159708 -18.20799)
		(width 0.13208)
		(layer "F.Cu")
		(net "P5E_CPU0_PE1_TX_DP<8>")
	)
	(segment
		(start 360.050334 -225.203512)
		(end 360.05008 -225.203258)
		(width 0.13208)
		(layer "F.Cu")
		(net "P5E_CPU0_PE1_TX_DP<8>")
	)
	(segment
		(start 410.159708 -18.20799)
		(end 410.488384 -17.879314)
		(width 0.13208)
		(layer "F.Cu")
		(net "P5E_CPU0_PE1_TX_DP<8>")
	)
	(segment
		(start 360.050334 -225.739198)
		(end 360.050334 -225.203512)
		(width 0.13208)
		(layer "F.Cu")
		(net "P5E_CPU0_PE1_TX_DP<8>")
	)
	(segment
		(start 359.67543 -215.42248)
		(end 359.67543 -215.452198)
		(width 0.0889)
		(layer "In2.Cu")
		(net "P5E_CPU0_PE1_TX_DP<8>")
	)
	(segment
		(start 357.50881 -184.424828)
		(end 359.247186 -212.814916)
		(width 0.14732)
		(layer "In2.Cu")
		(net "P5E_CPU0_PE1_TX_DP<8>")
	)
	(segment
		(start 410.169106 -20.585938)
		(end 410.181298 -20.59813)
		(width 0.14732)
		(layer "In2.Cu")
		(net "P5E_CPU0_PE1_TX_DP<8>")
	)
	(segment
		(start 359.393236 -219.18168)
		(end 359.391712 -219.182442)
		(width 0.0889)
		(layer "In2.Cu")
		(net "P5E_CPU0_PE1_TX_DP<8>")
	)
	(segment
		(start 359.205276 -214.072978)
		(end 359.205276 -214.622634)
		(width 0.0889)
		(layer "In2.Cu")
		(net "P5E_CPU0_PE1_TX_DP<8>")
	)
	(segment
		(start 359.393236 -215.926162)
		(end 359.39222 -215.92667)
		(width 0.0889)
		(layer "In2.Cu")
		(net "P5E_CPU0_PE1_TX_DP<8>")
	)
	(segment
		(start 359.675684 -217.05443)
		(end 359.675684 -217.082878)
		(width 0.0889)
		(layer "In2.Cu")
		(net "P5E_CPU0_PE1_TX_DP<8>")
	)
	(segment
		(start 410.181298 -21.889466)
		(end 410.63926 -71.644256)
		(width 0.14732)
		(layer "In2.Cu")
		(net "P5E_CPU0_PE1_TX_DP<8>")
	)
	(segment
		(start 359.917746 -224.843086)
		(end 359.893616 -224.93224)
		(width 0.0889)
		(layer "In2.Cu")
		(net "P5E_CPU0_PE1_TX_DP<8>")
	)
	(segment
		(start 359.205784 -219.506038)
		(end 359.205784 -219.542614)
		(width 0.0889)
		(layer "In2.Cu")
		(net "P5E_CPU0_PE1_TX_DP<8>")
	)
	(segment
		(start 409.27528 -79.396082)
		(end 361.942634 -159.268668)
		(width 0.14732)
		(layer "In2.Cu")
		(net "P5E_CPU0_PE1_TX_DP<8>")
	)
	(segment
		(start 361.942634 -159.268668)
		(end 357.50881 -184.424828)
		(width 0.14732)
		(layer "In2.Cu")
		(net "P5E_CPU0_PE1_TX_DP<8>")
	)
	(segment
		(start 359.247186 -214.00897)
		(end 359.247186 -214.031068)
		(width 0.0889)
		(layer "In2.Cu")
		(net "P5E_CPU0_PE1_TX_DP<8>")
	)
	(segment
		(start 359.675684 -221.939104)
		(end 359.675684 -221.957646)
		(width 0.0889)
		(layer "In2.Cu")
		(net "P5E_CPU0_PE1_TX_DP<8>")
	)
	(segment
		(start 359.854246 -223.894904)
		(end 359.855008 -223.895412)
		(width 0.0889)
		(layer "In2.Cu")
		(net "P5E_CPU0_PE1_TX_DP<8>")
	)
	(segment
		(start 359.402888 -219.836238)
		(end 359.405174 -219.837508)
		(width 0.0889)
		(layer "In2.Cu")
		(net "P5E_CPU0_PE1_TX_DP<8>")
	)
	(segment
		(start 359.393236 -222.437198)
		(end 359.384346 -222.442278)
		(width 0.0889)
		(layer "In2.Cu")
		(net "P5E_CPU0_PE1_TX_DP<8>")
	)
	(segment
		(start 359.384346 -216.569798)
		(end 359.393236 -216.574878)
		(width 0.0889)
		(layer "In2.Cu")
		(net "P5E_CPU0_PE1_TX_DP<8>")
	)
	(segment
		(start 359.391712 -219.182442)
		(end 359.384346 -219.18676)
		(width 0.0889)
		(layer "In2.Cu")
		(net "P5E_CPU0_PE1_TX_DP<8>")
	)
	(segment
		(start 359.384346 -218.197684)
		(end 359.391712 -218.202002)
		(width 0.0889)
		(layer "In2.Cu")
		(net "P5E_CPU0_PE1_TX_DP<8>")
	)
	(segment
		(start 359.391712 -218.202002)
		(end 359.393236 -218.202764)
		(width 0.0889)
		(layer "In2.Cu")
		(net "P5E_CPU0_PE1_TX_DP<8>")
	)
	(segment
		(start 359.855008 -223.895412)
		(end 359.859834 -223.897952)
		(width 0.0889)
		(layer "In2.Cu")
		(net "P5E_CPU0_PE1_TX_DP<8>")
	)
	(segment
		(start 360.145584 -224.379536)
		(end 360.145584 -224.389442)
		(width 0.0889)
		(layer "In2.Cu")
		(net "P5E_CPU0_PE1_TX_DP<8>")
	)
	(segment
		(start 359.358438 -219.810076)
		(end 359.402888 -219.836238)
		(width 0.0889)
		(layer "In2.Cu")
		(net "P5E_CPU0_PE1_TX_DP<8>")
	)
	(segment
		(start 359.868978 -221.619826)
		(end 359.863644 -221.622874)
		(width 0.0889)
		(layer "In2.Cu")
		(net "P5E_CPU0_PE1_TX_DP<8>")
	)
	(segment
		(start 359.39222 -215.92667)
		(end 359.384346 -215.931242)
		(width 0.0889)
		(layer "In2.Cu")
		(net "P5E_CPU0_PE1_TX_DP<8>")
	)
	(segment
		(start 359.854246 -220.639132)
		(end 359.863136 -220.644212)
		(width 0.0889)
		(layer "In2.Cu")
		(net "P5E_CPU0_PE1_TX_DP<8>")
	)
	(segment
		(start 359.384346 -223.080834)
		(end 359.393236 -223.085914)
		(width 0.0889)
		(layer "In2.Cu")
		(net "P5E_CPU0_PE1_TX_DP<8>")
	)
	(segment
		(start 359.861104 -223.89846)
		(end 359.863136 -223.899984)
		(width 0.0889)
		(layer "In2.Cu")
		(net "P5E_CPU0_PE1_TX_DP<8>")
	)
	(segment
		(start 359.247186 -214.031068)
		(end 359.205276 -214.072978)
		(width 0.0889)
		(layer "In2.Cu")
		(net "P5E_CPU0_PE1_TX_DP<8>")
	)
	(segment
		(start 410.181298 -20.59813)
		(end 410.181298 -21.889466)
		(width 0.14732)
		(layer "In2.Cu")
		(net "P5E_CPU0_PE1_TX_DP<8>")
	)
	(segment
		(start 359.383838 -214.941912)
		(end 359.392728 -214.946992)
		(width 0.0889)
		(layer "In2.Cu")
		(net "P5E_CPU0_PE1_TX_DP<8>")
	)
	(segment
		(start 359.675684 -218.676728)
		(end 359.675684 -218.707716)
		(width 0.0889)
		(layer "In2.Cu")
		(net "P5E_CPU0_PE1_TX_DP<8>")
	)
	(segment
		(start 359.859834 -223.897952)
		(end 359.861104 -223.89846)
		(width 0.0889)
		(layer "In2.Cu")
		(net "P5E_CPU0_PE1_TX_DP<8>")
	)
	(segment
		(start 359.675684 -223.561402)
		(end 359.675684 -223.575626)
		(width 0.0889)
		(layer "In2.Cu")
		(net "P5E_CPU0_PE1_TX_DP<8>")
	)
	(segment
		(start 410.63926 -71.644256)
		(end 409.27528 -79.396082)
		(width 0.14732)
		(layer "In2.Cu")
		(net "P5E_CPU0_PE1_TX_DP<8>")
	)
	(segment
		(start 359.893616 -224.93224)
		(end 360.05008 -225.203258)
		(width 0.0889)
		(layer "In2.Cu")
		(net "P5E_CPU0_PE1_TX_DP<8>")
	)
	(segment
		(start 359.247186 -212.814916)
		(end 359.247186 -214.00897)
		(width 0.14732)
		(layer "In2.Cu")
		(net "P5E_CPU0_PE1_TX_DP<8>")
	)
	(segment
		(start 359.393236 -217.554048)
		(end 359.392474 -217.554556)
		(width 0.0889)
		(layer "In2.Cu")
		(net "P5E_CPU0_PE1_TX_DP<8>")
	)
	(segment
		(start 410.462984 -19.125438)
		(end 410.169106 -19.419316)
		(width 0.14732)
		(layer "In2.Cu")
		(net "P5E_CPU0_PE1_TX_DP<8>")
	)
	(segment
		(start 410.169106 -19.419316)
		(end 410.169106 -20.585938)
		(width 0.14732)
		(layer "In2.Cu")
		(net "P5E_CPU0_PE1_TX_DP<8>")
	)
	(segment
		(start 359.392474 -217.554556)
		(end 359.384346 -217.559128)
		(width 0.0889)
		(layer "In2.Cu")
		(net "P5E_CPU0_PE1_TX_DP<8>")
	)
	(segment
		(start 360.145584 -221.115382)
		(end 360.145584 -221.133924)
		(width 0.0889)
		(layer "In2.Cu")
		(net "P5E_CPU0_PE1_TX_DP<8>")
	)
	(segment
		(start 359.863644 -221.622874)
		(end 359.862882 -221.623382)
		(width 0.0889)
		(layer "In2.Cu")
		(net "P5E_CPU0_PE1_TX_DP<8>")
	)
	(arc
		(start 359.384346 -219.18676)
		(mid 359.253432 -219.32312)
		(end 359.205784 -219.506038)
		(width 0.0889)
		(layer "In2.Cu")
		(net "P5E_CPU0_PE1_TX_DP<8>")
	)
	(arc
		(start 359.863136 -220.644212)
		(mid 360.065422 -220.843193)
		(end 360.145584 -221.115382)
		(width 0.0889)
		(layer "In2.Cu")
		(net "P5E_CPU0_PE1_TX_DP<8>")
	)
	(arc
		(start 359.392728 -214.946992)
		(mid 359.596209 -215.147796)
		(end 359.67543 -215.42248)
		(width 0.0889)
		(layer "In2.Cu")
		(net "P5E_CPU0_PE1_TX_DP<8>")
	)
	(arc
		(start 359.384346 -215.931242)
		(mid 359.255942 -216.063187)
		(end 359.205784 -216.24036)
		(width 0.0889)
		(layer "In2.Cu")
		(net "P5E_CPU0_PE1_TX_DP<8>")
	)
	(arc
		(start 359.384346 -222.442278)
		(mid 359.253432 -222.578638)
		(end 359.205784 -222.761556)
		(width 0.0889)
		(layer "In2.Cu")
		(net "P5E_CPU0_PE1_TX_DP<8>")
	)
	(arc
		(start 359.675684 -223.575626)
		(mid 359.723363 -223.758526)
		(end 359.854246 -223.894904)
		(width 0.0889)
		(layer "In2.Cu")
		(net "P5E_CPU0_PE1_TX_DP<8>")
	)
	(arc
		(start 359.205784 -216.24036)
		(mid 359.20569 -216.248742)
		(end 359.205784 -216.257124)
		(width 0.0889)
		(layer "In2.Cu")
		(net "P5E_CPU0_PE1_TX_DP<8>")
	)
	(arc
		(start 359.862882 -221.623382)
		(mid 359.727949 -221.756736)
		(end 359.675684 -221.939104)
		(width 0.0889)
		(layer "In2.Cu")
		(net "P5E_CPU0_PE1_TX_DP<8>")
	)
	(arc
		(start 360.145584 -221.133924)
		(mid 360.071593 -221.41349)
		(end 359.868978 -221.619826)
		(width 0.0889)
		(layer "In2.Cu")
		(net "P5E_CPU0_PE1_TX_DP<8>")
	)
	(arc
		(start 359.863136 -223.899984)
		(mid 360.067471 -224.102589)
		(end 360.145584 -224.379536)
		(width 0.0889)
		(layer "In2.Cu")
		(net "P5E_CPU0_PE1_TX_DP<8>")
	)
	(arc
		(start 359.393236 -223.085914)
		(mid 359.596541 -223.28678)
		(end 359.675684 -223.561402)
		(width 0.0889)
		(layer "In2.Cu")
		(net "P5E_CPU0_PE1_TX_DP<8>")
	)
	(arc
		(start 359.384346 -217.559128)
		(mid 359.205749 -217.878406)
		(end 359.384346 -218.197684)
		(width 0.0889)
		(layer "In2.Cu")
		(net "P5E_CPU0_PE1_TX_DP<8>")
	)
	(arc
		(start 359.67543 -215.452198)
		(mid 359.59606 -215.725932)
		(end 359.393236 -215.926162)
		(width 0.0889)
		(layer "In2.Cu")
		(net "P5E_CPU0_PE1_TX_DP<8>")
	)
	(arc
		(start 359.675684 -218.707716)
		(mid 359.596235 -218.981512)
		(end 359.393236 -219.18168)
		(width 0.0889)
		(layer "In2.Cu")
		(net "P5E_CPU0_PE1_TX_DP<8>")
	)
	(arc
		(start 359.205784 -219.542614)
		(mid 359.246559 -219.696651)
		(end 359.358438 -219.810076)
		(width 0.0889)
		(layer "In2.Cu")
		(net "P5E_CPU0_PE1_TX_DP<8>")
	)
	(arc
		(start 359.205276 -214.622634)
		(mid 359.252955 -214.805534)
		(end 359.383838 -214.941912)
		(width 0.0889)
		(layer "In2.Cu")
		(net "P5E_CPU0_PE1_TX_DP<8>")
	)
	(arc
		(start 360.145584 -224.389442)
		(mid 360.090229 -224.633629)
		(end 359.934764 -224.829878)
		(width 0.0889)
		(layer "In2.Cu")
		(net "P5E_CPU0_PE1_TX_DP<8>")
	)
	(arc
		(start 359.393236 -218.202764)
		(mid 359.596234 -218.402933)
		(end 359.675684 -218.676728)
		(width 0.0889)
		(layer "In2.Cu")
		(net "P5E_CPU0_PE1_TX_DP<8>")
	)
	(arc
		(start 359.934764 -224.829878)
		(mid 359.926318 -224.836563)
		(end 359.917746 -224.843086)
		(width 0.0889)
		(layer "In2.Cu")
		(net "P5E_CPU0_PE1_TX_DP<8>")
	)
	(arc
		(start 359.675684 -217.082878)
		(mid 359.595522 -217.355067)
		(end 359.393236 -217.554048)
		(width 0.0889)
		(layer "In2.Cu")
		(net "P5E_CPU0_PE1_TX_DP<8>")
	)
	(arc
		(start 359.205784 -222.761556)
		(mid 359.205836 -222.768923)
		(end 359.206038 -222.776288)
		(width 0.0889)
		(layer "In2.Cu")
		(net "P5E_CPU0_PE1_TX_DP<8>")
	)
	(arc
		(start 359.675684 -221.957646)
		(mid 359.597573 -222.234595)
		(end 359.393236 -222.437198)
		(width 0.0889)
		(layer "In2.Cu")
		(net "P5E_CPU0_PE1_TX_DP<8>")
	)
	(arc
		(start 359.405174 -219.837508)
		(mid 359.603402 -220.043356)
		(end 359.675684 -220.319854)
		(width 0.0889)
		(layer "In2.Cu")
		(net "P5E_CPU0_PE1_TX_DP<8>")
	)
	(arc
		(start 359.206038 -222.776288)
		(mid 359.257092 -222.950868)
		(end 359.384346 -223.080834)
		(width 0.0889)
		(layer "In2.Cu")
		(net "P5E_CPU0_PE1_TX_DP<8>")
	)
	(arc
		(start 359.393236 -216.574878)
		(mid 359.597571 -216.777483)
		(end 359.675684 -217.05443)
		(width 0.0889)
		(layer "In2.Cu")
		(net "P5E_CPU0_PE1_TX_DP<8>")
	)
	(arc
		(start 359.205784 -216.257124)
		(mid 359.255037 -216.436324)
		(end 359.384346 -216.569798)
		(width 0.0889)
		(layer "In2.Cu")
		(net "P5E_CPU0_PE1_TX_DP<8>")
	)
	(arc
		(start 359.675684 -220.319854)
		(mid 359.723363 -220.502754)
		(end 359.854246 -220.639132)
		(width 0.0889)
		(layer "In2.Cu")
		(net "P5E_CPU0_PE1_TX_DP<8>")
	)
	(segment
		(start 360.51998 -224.925382)
		(end 360.51998 -224.389696)
		(width 0.13208)
		(layer "F.Cu")
		(net "P5E_CPU0_PE1_TX_DP<7>")
	)
	(segment
		(start 412.694628 -16.681958)
		(end 412.367984 -16.355314)
		(width 0.13208)
		(layer "F.Cu")
		(net "P5E_CPU0_PE1_TX_DP<7>")
	)
	(segment
		(start 360.51998 -224.389696)
		(end 360.520234 -224.389442)
		(width 0.13208)
		(layer "F.Cu")
		(net "P5E_CPU0_PE1_TX_DP<7>")
	)
	(segment
		(start 412.694628 -17.300194)
		(end 412.694628 -16.681958)
		(width 0.13208)
		(layer "F.Cu")
		(net "P5E_CPU0_PE1_TX_DP<7>")
	)
	(segment
		(start 412.393384 -17.601438)
		(end 412.694628 -17.300194)
		(width 0.13208)
		(layer "F.Cu")
		(net "P5E_CPU0_PE1_TX_DP<7>")
	)
	(segment
		(start 360.233722 -216.737692)
		(end 360.234738 -216.7382)
		(width 0.0889)
		(layer "In2.Cu")
		(net "P5E_CPU0_PE1_TX_DP<7>")
	)
	(segment
		(start 359.955084 -219.490544)
		(end 359.955084 -219.515944)
		(width 0.0889)
		(layer "In2.Cu")
		(net "P5E_CPU0_PE1_TX_DP<7>")
	)
	(segment
		(start 412.688278 -18.435828)
		(end 413.314134 -29.873448)
		(width 0.14732)
		(layer "In2.Cu")
		(net "P5E_CPU0_PE1_TX_DP<7>")
	)
	(segment
		(start 360.42473 -220.311218)
		(end 360.42473 -220.334078)
		(width 0.0889)
		(layer "In2.Cu")
		(net "P5E_CPU0_PE1_TX_DP<7>")
	)
	(segment
		(start 360.71429 -221.454472)
		(end 360.707432 -221.458282)
		(width 0.0889)
		(layer "In2.Cu")
		(net "P5E_CPU0_PE1_TX_DP<7>")
	)
	(segment
		(start 360.246168 -215.755982)
		(end 360.237278 -215.761062)
		(width 0.0889)
		(layer "In2.Cu")
		(net "P5E_CPU0_PE1_TX_DP<7>")
	)
	(segment
		(start 360.71429 -218.198954)
		(end 360.707432 -218.202764)
		(width 0.0889)
		(layer "In2.Cu")
		(net "P5E_CPU0_PE1_TX_DP<7>")
	)
	(segment
		(start 411.44952 -71.777352)
		(end 410.125926 -79.282036)
		(width 0.14732)
		(layer "In2.Cu")
		(net "P5E_CPU0_PE1_TX_DP<7>")
	)
	(segment
		(start 362.561124 -159.539178)
		(end 358.176576 -184.411874)
		(width 0.14732)
		(layer "In2.Cu")
		(net "P5E_CPU0_PE1_TX_DP<7>")
	)
	(segment
		(start 360.231436 -216.736422)
		(end 360.233722 -216.737692)
		(width 0.0889)
		(layer "In2.Cu")
		(net "P5E_CPU0_PE1_TX_DP<7>")
	)
	(segment
		(start 360.246168 -219.0115)
		(end 360.237278 -219.01658)
		(width 0.0889)
		(layer "In2.Cu")
		(net "P5E_CPU0_PE1_TX_DP<7>")
	)
	(segment
		(start 360.707432 -220.809566)
		(end 360.716322 -220.814646)
		(width 0.0889)
		(layer "In2.Cu")
		(net "P5E_CPU0_PE1_TX_DP<7>")
	)
	(segment
		(start 359.95483 -216.240614)
		(end 359.95483 -216.25052)
		(width 0.0889)
		(layer "In2.Cu")
		(net "P5E_CPU0_PE1_TX_DP<7>")
	)
	(segment
		(start 359.955084 -222.746062)
		(end 359.955084 -222.780098)
		(width 0.0889)
		(layer "In2.Cu")
		(net "P5E_CPU0_PE1_TX_DP<7>")
	)
	(segment
		(start 358.176576 -184.411874)
		(end 359.913682 -212.808312)
		(width 0.14732)
		(layer "In2.Cu")
		(net "P5E_CPU0_PE1_TX_DP<7>")
	)
	(segment
		(start 360.716322 -221.453202)
		(end 360.71429 -221.454472)
		(width 0.0889)
		(layer "In2.Cu")
		(net "P5E_CPU0_PE1_TX_DP<7>")
	)
	(segment
		(start 360.237278 -215.112346)
		(end 360.246168 -215.117426)
		(width 0.0889)
		(layer "In2.Cu")
		(net "P5E_CPU0_PE1_TX_DP<7>")
	)
	(segment
		(start 360.234738 -216.7382)
		(end 360.237532 -216.739978)
		(width 0.0889)
		(layer "In2.Cu")
		(net "P5E_CPU0_PE1_TX_DP<7>")
	)
	(segment
		(start 360.707432 -218.202764)
		(end 360.70667 -218.203272)
		(width 0.0889)
		(layer "In2.Cu")
		(net "P5E_CPU0_PE1_TX_DP<7>")
	)
	(segment
		(start 359.955592 -214.072978)
		(end 359.955592 -214.63762)
		(width 0.0889)
		(layer "In2.Cu")
		(net "P5E_CPU0_PE1_TX_DP<7>")
	)
	(segment
		(start 413.314134 -29.873448)
		(end 411.594046 -70.467982)
		(width 0.14732)
		(layer "In2.Cu")
		(net "P5E_CPU0_PE1_TX_DP<7>")
	)
	(segment
		(start 359.955592 -214.63762)
		(end 359.955084 -214.644732)
		(width 0.0889)
		(layer "In2.Cu")
		(net "P5E_CPU0_PE1_TX_DP<7>")
	)
	(segment
		(start 412.688024 -18.415508)
		(end 412.688278 -18.435828)
		(width 0.14732)
		(layer "In2.Cu")
		(net "P5E_CPU0_PE1_TX_DP<7>")
	)
	(segment
		(start 410.125926 -79.282036)
		(end 362.561124 -159.539178)
		(width 0.14732)
		(layer "In2.Cu")
		(net "P5E_CPU0_PE1_TX_DP<7>")
	)
	(segment
		(start 360.716322 -218.197684)
		(end 360.71429 -218.198954)
		(width 0.0889)
		(layer "In2.Cu")
		(net "P5E_CPU0_PE1_TX_DP<7>")
	)
	(segment
		(start 360.70667 -218.203272)
		(end 360.705654 -218.20378)
		(width 0.0889)
		(layer "In2.Cu")
		(net "P5E_CPU0_PE1_TX_DP<7>")
	)
	(segment
		(start 360.705654 -221.459298)
		(end 360.701336 -221.461838)
		(width 0.0889)
		(layer "In2.Cu")
		(net "P5E_CPU0_PE1_TX_DP<7>")
	)
	(segment
		(start 412.393384 -17.601438)
		(end 412.688024 -17.896078)
		(width 0.14732)
		(layer "In2.Cu")
		(net "P5E_CPU0_PE1_TX_DP<7>")
	)
	(segment
		(start 360.246168 -222.267018)
		(end 360.237278 -222.272098)
		(width 0.0889)
		(layer "In2.Cu")
		(net "P5E_CPU0_PE1_TX_DP<7>")
	)
	(segment
		(start 360.707432 -221.458282)
		(end 360.70667 -221.45879)
		(width 0.0889)
		(layer "In2.Cu")
		(net "P5E_CPU0_PE1_TX_DP<7>")
	)
	(segment
		(start 360.42473 -217.0557)
		(end 360.42473 -217.07856)
		(width 0.0889)
		(layer "In2.Cu")
		(net "P5E_CPU0_PE1_TX_DP<7>")
	)
	(segment
		(start 360.70667 -221.45879)
		(end 360.705654 -221.459298)
		(width 0.0889)
		(layer "In2.Cu")
		(net "P5E_CPU0_PE1_TX_DP<7>")
	)
	(segment
		(start 412.688024 -17.896078)
		(end 412.688024 -18.415508)
		(width 0.14732)
		(layer "In2.Cu")
		(net "P5E_CPU0_PE1_TX_DP<7>")
	)
	(segment
		(start 411.594046 -70.467982)
		(end 411.44952 -71.777352)
		(width 0.14732)
		(layer "In2.Cu")
		(net "P5E_CPU0_PE1_TX_DP<7>")
	)
	(segment
		(start 360.42473 -223.56699)
		(end 360.42473 -223.575626)
		(width 0.0889)
		(layer "In2.Cu")
		(net "P5E_CPU0_PE1_TX_DP<7>")
	)
	(segment
		(start 360.652568 -224.02927)
		(end 360.676698 -224.118424)
		(width 0.0889)
		(layer "In2.Cu")
		(net "P5E_CPU0_PE1_TX_DP<7>")
	)
	(segment
		(start 359.913682 -214.031068)
		(end 359.955592 -214.072978)
		(width 0.0889)
		(layer "In2.Cu")
		(net "P5E_CPU0_PE1_TX_DP<7>")
	)
	(segment
		(start 359.913682 -212.808312)
		(end 359.913682 -214.00897)
		(width 0.14732)
		(layer "In2.Cu")
		(net "P5E_CPU0_PE1_TX_DP<7>")
	)
	(segment
		(start 359.913682 -214.00897)
		(end 359.913682 -214.031068)
		(width 0.0889)
		(layer "In2.Cu")
		(net "P5E_CPU0_PE1_TX_DP<7>")
	)
	(segment
		(start 360.676698 -224.118424)
		(end 360.520234 -224.389442)
		(width 0.0889)
		(layer "In2.Cu")
		(net "P5E_CPU0_PE1_TX_DP<7>")
	)
	(segment
		(start 360.705654 -218.20378)
		(end 360.701336 -218.20632)
		(width 0.0889)
		(layer "In2.Cu")
		(net "P5E_CPU0_PE1_TX_DP<7>")
	)
	(segment
		(start 360.707432 -217.554048)
		(end 360.716322 -217.559128)
		(width 0.0889)
		(layer "In2.Cu")
		(net "P5E_CPU0_PE1_TX_DP<7>")
	)
	(arc
		(start 360.42473 -218.692222)
		(mid 360.377051 -218.875122)
		(end 360.246168 -219.0115)
		(width 0.0889)
		(layer "In2.Cu")
		(net "P5E_CPU0_PE1_TX_DP<7>")
	)
	(arc
		(start 360.237532 -219.995496)
		(mid 360.372465 -220.12885)
		(end 360.42473 -220.311218)
		(width 0.0889)
		(layer "In2.Cu")
		(net "P5E_CPU0_PE1_TX_DP<7>")
	)
	(arc
		(start 360.701336 -221.461838)
		(mid 360.498749 -221.668189)
		(end 360.42473 -221.94774)
		(width 0.0889)
		(layer "In2.Cu")
		(net "P5E_CPU0_PE1_TX_DP<7>")
	)
	(arc
		(start 360.716322 -220.814646)
		(mid 360.894919 -221.133924)
		(end 360.716322 -221.453202)
		(width 0.0889)
		(layer "In2.Cu")
		(net "P5E_CPU0_PE1_TX_DP<7>")
	)
	(arc
		(start 360.424476 -215.421972)
		(mid 360.424758 -215.432638)
		(end 360.42473 -215.443308)
		(width 0.0889)
		(layer "In2.Cu")
		(net "P5E_CPU0_PE1_TX_DP<7>")
	)
	(arc
		(start 360.237532 -223.251268)
		(mid 360.372465 -223.384622)
		(end 360.42473 -223.56699)
		(width 0.0889)
		(layer "In2.Cu")
		(net "P5E_CPU0_PE1_TX_DP<7>")
	)
	(arc
		(start 360.237532 -216.739978)
		(mid 360.372465 -216.873332)
		(end 360.42473 -217.0557)
		(width 0.0889)
		(layer "In2.Cu")
		(net "P5E_CPU0_PE1_TX_DP<7>")
	)
	(arc
		(start 359.955084 -219.515944)
		(mid 360.033195 -219.792893)
		(end 360.237532 -219.995496)
		(width 0.0889)
		(layer "In2.Cu")
		(net "P5E_CPU0_PE1_TX_DP<7>")
	)
	(arc
		(start 360.42473 -221.94774)
		(mid 360.377051 -222.13064)
		(end 360.246168 -222.267018)
		(width 0.0889)
		(layer "In2.Cu")
		(net "P5E_CPU0_PE1_TX_DP<7>")
	)
	(arc
		(start 360.716322 -217.559128)
		(mid 360.894919 -217.878406)
		(end 360.716322 -218.197684)
		(width 0.0889)
		(layer "In2.Cu")
		(net "P5E_CPU0_PE1_TX_DP<7>")
	)
	(arc
		(start 360.237278 -215.761062)
		(mid 360.032943 -215.963667)
		(end 359.95483 -216.240614)
		(width 0.0889)
		(layer "In2.Cu")
		(net "P5E_CPU0_PE1_TX_DP<7>")
	)
	(arc
		(start 359.95483 -216.25052)
		(mid 360.028821 -216.530086)
		(end 360.231436 -216.736422)
		(width 0.0889)
		(layer "In2.Cu")
		(net "P5E_CPU0_PE1_TX_DP<7>")
	)
	(arc
		(start 360.42473 -223.575626)
		(mid 360.484773 -223.829513)
		(end 360.652568 -224.02927)
		(width 0.0889)
		(layer "In2.Cu")
		(net "P5E_CPU0_PE1_TX_DP<7>")
	)
	(arc
		(start 360.701336 -218.20632)
		(mid 360.498749 -218.412671)
		(end 360.42473 -218.692222)
		(width 0.0889)
		(layer "In2.Cu")
		(net "P5E_CPU0_PE1_TX_DP<7>")
	)
	(arc
		(start 360.42473 -215.443308)
		(mid 360.375477 -215.622508)
		(end 360.246168 -215.755982)
		(width 0.0889)
		(layer "In2.Cu")
		(net "P5E_CPU0_PE1_TX_DP<7>")
	)
	(arc
		(start 360.237278 -222.272098)
		(mid 360.034455 -222.472329)
		(end 359.955084 -222.746062)
		(width 0.0889)
		(layer "In2.Cu")
		(net "P5E_CPU0_PE1_TX_DP<7>")
	)
	(arc
		(start 360.237278 -219.01658)
		(mid 360.034455 -219.216811)
		(end 359.955084 -219.490544)
		(width 0.0889)
		(layer "In2.Cu")
		(net "P5E_CPU0_PE1_TX_DP<7>")
	)
	(arc
		(start 360.42473 -220.334078)
		(mid 360.503949 -220.608763)
		(end 360.707432 -220.809566)
		(width 0.0889)
		(layer "In2.Cu")
		(net "P5E_CPU0_PE1_TX_DP<7>")
	)
	(arc
		(start 360.246168 -215.117426)
		(mid 360.373422 -215.247392)
		(end 360.424476 -215.421972)
		(width 0.0889)
		(layer "In2.Cu")
		(net "P5E_CPU0_PE1_TX_DP<7>")
	)
	(arc
		(start 359.955084 -214.644732)
		(mid 360.035995 -214.91486)
		(end 360.237278 -215.112346)
		(width 0.0889)
		(layer "In2.Cu")
		(net "P5E_CPU0_PE1_TX_DP<7>")
	)
	(arc
		(start 359.955084 -222.780098)
		(mid 360.035246 -223.052287)
		(end 360.237532 -223.251268)
		(width 0.0889)
		(layer "In2.Cu")
		(net "P5E_CPU0_PE1_TX_DP<7>")
	)
	(arc
		(start 360.42473 -217.07856)
		(mid 360.503949 -217.353245)
		(end 360.707432 -217.554048)
		(width 0.0889)
		(layer "In2.Cu")
		(net "P5E_CPU0_PE1_TX_DP<7>")
	)
	(segment
		(start 361.92968 -225.738944)
		(end 361.92968 -225.203258)
		(width 0.13208)
		(layer "F.Cu")
		(net "P5E_CPU0_PE1_TX_DP<6>")
	)
	(segment
		(start 416.053524 -18.822162)
		(end 416.053524 -18.20799)
		(width 0.13208)
		(layer "F.Cu")
		(net "P5E_CPU0_PE1_TX_DP<6>")
	)
	(segment
		(start 361.929934 -225.739198)
		(end 361.92968 -225.738944)
		(width 0.13208)
		(layer "F.Cu")
		(net "P5E_CPU0_PE1_TX_DP<6>")
	)
	(segment
		(start 416.053524 -18.20799)
		(end 416.3822 -17.879314)
		(width 0.13208)
		(layer "F.Cu")
		(net "P5E_CPU0_PE1_TX_DP<6>")
	)
	(segment
		(start 416.3568 -19.125438)
		(end 416.053524 -18.822162)
		(width 0.13208)
		(layer "F.Cu")
		(net "P5E_CPU0_PE1_TX_DP<6>")
	)
	(segment
		(start 361.742736 -223.899984)
		(end 361.741974 -223.899476)
		(width 0.0889)
		(layer "In2.Cu")
		(net "P5E_CPU0_PE1_TX_DP<6>")
	)
	(segment
		(start 361.92968 -225.203258)
		(end 361.773216 -224.93224)
		(width 0.0889)
		(layer "In2.Cu")
		(net "P5E_CPU0_PE1_TX_DP<6>")
	)
	(segment
		(start 361.740196 -218.369388)
		(end 361.741974 -218.368372)
		(width 0.0889)
		(layer "In2.Cu")
		(net "P5E_CPU0_PE1_TX_DP<6>")
	)
	(segment
		(start 361.263946 -222.442278)
		(end 361.272836 -222.437198)
		(width 0.0889)
		(layer "In2.Cu")
		(net "P5E_CPU0_PE1_TX_DP<6>")
	)
	(segment
		(start 361.272836 -223.085914)
		(end 361.263946 -223.080834)
		(width 0.0889)
		(layer "In2.Cu")
		(net "P5E_CPU0_PE1_TX_DP<6>")
	)
	(segment
		(start 361.733846 -221.628462)
		(end 361.739434 -221.625414)
		(width 0.0889)
		(layer "In2.Cu")
		(net "P5E_CPU0_PE1_TX_DP<6>")
	)
	(segment
		(start 361.741974 -223.899476)
		(end 361.739434 -223.897952)
		(width 0.0889)
		(layer "In2.Cu")
		(net "P5E_CPU0_PE1_TX_DP<6>")
	)
	(segment
		(start 361.263946 -219.18676)
		(end 361.272836 -219.18168)
		(width 0.0889)
		(layer "In2.Cu")
		(net "P5E_CPU0_PE1_TX_DP<6>")
	)
	(segment
		(start 361.263692 -215.931242)
		(end 361.272582 -215.926162)
		(width 0.0889)
		(layer "In2.Cu")
		(net "P5E_CPU0_PE1_TX_DP<6>")
	)
	(segment
		(start 361.555284 -223.575626)
		(end 361.555284 -223.561402)
		(width 0.0889)
		(layer "In2.Cu")
		(net "P5E_CPU0_PE1_TX_DP<6>")
	)
	(segment
		(start 361.739434 -223.897952)
		(end 361.733846 -223.894904)
		(width 0.0889)
		(layer "In2.Cu")
		(net "P5E_CPU0_PE1_TX_DP<6>")
	)
	(segment
		(start 415.665158 -29.903928)
		(end 415.90976 -23.763986)
		(width 0.14732)
		(layer "In2.Cu")
		(net "P5E_CPU0_PE1_TX_DP<6>")
	)
	(segment
		(start 361.739434 -218.369896)
		(end 361.740196 -218.369388)
		(width 0.0889)
		(layer "In2.Cu")
		(net "P5E_CPU0_PE1_TX_DP<6>")
	)
	(segment
		(start 361.272582 -216.574878)
		(end 361.263692 -216.569798)
		(width 0.0889)
		(layer "In2.Cu")
		(net "P5E_CPU0_PE1_TX_DP<6>")
	)
	(segment
		(start 361.740196 -221.624906)
		(end 361.741974 -221.62389)
		(width 0.0889)
		(layer "In2.Cu")
		(net "P5E_CPU0_PE1_TX_DP<6>")
	)
	(segment
		(start 361.773216 -224.93224)
		(end 361.797346 -224.843086)
		(width 0.0889)
		(layer "In2.Cu")
		(net "P5E_CPU0_PE1_TX_DP<6>")
	)
	(segment
		(start 416.06216 -19.420078)
		(end 416.3568 -19.125438)
		(width 0.14732)
		(layer "In2.Cu")
		(net "P5E_CPU0_PE1_TX_DP<6>")
	)
	(segment
		(start 411.246828 -79.872586)
		(end 412.94177 -70.264274)
		(width 0.14732)
		(layer "In2.Cu")
		(net "P5E_CPU0_PE1_TX_DP<6>")
	)
	(segment
		(start 361.741974 -218.368372)
		(end 361.742736 -218.367864)
		(width 0.0889)
		(layer "In2.Cu")
		(net "P5E_CPU0_PE1_TX_DP<6>")
	)
	(segment
		(start 361.742736 -220.644212)
		(end 361.733846 -220.639132)
		(width 0.0889)
		(layer "In2.Cu")
		(net "P5E_CPU0_PE1_TX_DP<6>")
	)
	(segment
		(start 416.06216 -20.323302)
		(end 416.06216 -19.420078)
		(width 0.14732)
		(layer "In2.Cu")
		(net "P5E_CPU0_PE1_TX_DP<6>")
	)
	(segment
		(start 361.284774 -216.58199)
		(end 361.272582 -216.574878)
		(width 0.0889)
		(layer "In2.Cu")
		(net "P5E_CPU0_PE1_TX_DP<6>")
	)
	(segment
		(start 361.272836 -222.437198)
		(end 361.278932 -222.433642)
		(width 0.0889)
		(layer "In2.Cu")
		(net "P5E_CPU0_PE1_TX_DP<6>")
	)
	(segment
		(start 361.55503 -215.44661)
		(end 361.55503 -215.436704)
		(width 0.0889)
		(layer "In2.Cu")
		(net "P5E_CPU0_PE1_TX_DP<6>")
	)
	(segment
		(start 361.59694 -214.633048)
		(end 361.59694 -214.61095)
		(width 0.0889)
		(layer "In2.Cu")
		(net "P5E_CPU0_PE1_TX_DP<6>")
	)
	(segment
		(start 359.427272 -184.257696)
		(end 363.6772 -160.145476)
		(width 0.14732)
		(layer "In2.Cu")
		(net "P5E_CPU0_PE1_TX_DP<6>")
	)
	(segment
		(start 361.741974 -221.62389)
		(end 361.742736 -221.623382)
		(width 0.0889)
		(layer "In2.Cu")
		(net "P5E_CPU0_PE1_TX_DP<6>")
	)
	(segment
		(start 361.59694 -213.711028)
		(end 359.427272 -184.257696)
		(width 0.14732)
		(layer "In2.Cu")
		(net "P5E_CPU0_PE1_TX_DP<6>")
	)
	(segment
		(start 412.94177 -70.264274)
		(end 415.665158 -29.903928)
		(width 0.14732)
		(layer "In2.Cu")
		(net "P5E_CPU0_PE1_TX_DP<6>")
	)
	(segment
		(start 415.925254 -23.749762)
		(end 416.06216 -20.323302)
		(width 0.14732)
		(layer "In2.Cu")
		(net "P5E_CPU0_PE1_TX_DP<6>")
	)
	(segment
		(start 361.272836 -219.830396)
		(end 361.263946 -219.825316)
		(width 0.0889)
		(layer "In2.Cu")
		(net "P5E_CPU0_PE1_TX_DP<6>")
	)
	(segment
		(start 361.278932 -219.833952)
		(end 361.272836 -219.830396)
		(width 0.0889)
		(layer "In2.Cu")
		(net "P5E_CPU0_PE1_TX_DP<6>")
	)
	(segment
		(start 363.6772 -160.145476)
		(end 411.246828 -79.872586)
		(width 0.14732)
		(layer "In2.Cu")
		(net "P5E_CPU0_PE1_TX_DP<6>")
	)
	(segment
		(start 362.025184 -224.389442)
		(end 362.025184 -224.379536)
		(width 0.0889)
		(layer "In2.Cu")
		(net "P5E_CPU0_PE1_TX_DP<6>")
	)
	(segment
		(start 361.733846 -218.372944)
		(end 361.739434 -218.369896)
		(width 0.0889)
		(layer "In2.Cu")
		(net "P5E_CPU0_PE1_TX_DP<6>")
	)
	(segment
		(start 362.025184 -217.888312)
		(end 362.025184 -217.859864)
		(width 0.0889)
		(layer "In2.Cu")
		(net "P5E_CPU0_PE1_TX_DP<6>")
	)
	(segment
		(start 361.554776 -214.675212)
		(end 361.59694 -214.633048)
		(width 0.0889)
		(layer "In2.Cu")
		(net "P5E_CPU0_PE1_TX_DP<6>")
	)
	(segment
		(start 362.025184 -221.14383)
		(end 362.025184 -221.115382)
		(width 0.0889)
		(layer "In2.Cu")
		(net "P5E_CPU0_PE1_TX_DP<6>")
	)
	(segment
		(start 415.90976 -23.763986)
		(end 415.925254 -23.749762)
		(width 0.14732)
		(layer "In2.Cu")
		(net "P5E_CPU0_PE1_TX_DP<6>")
	)
	(segment
		(start 361.59694 -214.61095)
		(end 361.59694 -213.711028)
		(width 0.14732)
		(layer "In2.Cu")
		(net "P5E_CPU0_PE1_TX_DP<6>")
	)
	(segment
		(start 361.742736 -217.388694)
		(end 361.733846 -217.383614)
		(width 0.0889)
		(layer "In2.Cu")
		(net "P5E_CPU0_PE1_TX_DP<6>")
	)
	(segment
		(start 361.554776 -215.43645)
		(end 361.554776 -214.675212)
		(width 0.0889)
		(layer "In2.Cu")
		(net "P5E_CPU0_PE1_TX_DP<6>")
	)
	(segment
		(start 361.55503 -215.436704)
		(end 361.554776 -215.43645)
		(width 0.0889)
		(layer "In2.Cu")
		(net "P5E_CPU0_PE1_TX_DP<6>")
	)
	(segment
		(start 361.739434 -221.625414)
		(end 361.740196 -221.624906)
		(width 0.0889)
		(layer "In2.Cu")
		(net "P5E_CPU0_PE1_TX_DP<6>")
	)
	(segment
		(start 361.272836 -219.18168)
		(end 361.278932 -219.178124)
		(width 0.0889)
		(layer "In2.Cu")
		(net "P5E_CPU0_PE1_TX_DP<6>")
	)
	(arc
		(start 361.733846 -223.894904)
		(mid 361.602932 -223.758544)
		(end 361.555284 -223.575626)
		(width 0.0889)
		(layer "In2.Cu")
		(net "P5E_CPU0_PE1_TX_DP<6>")
	)
	(arc
		(start 361.263692 -216.569798)
		(mid 361.085095 -216.25052)
		(end 361.263692 -215.931242)
		(width 0.0889)
		(layer "In2.Cu")
		(net "P5E_CPU0_PE1_TX_DP<6>")
	)
	(arc
		(start 361.797346 -224.843086)
		(mid 361.805918 -224.836564)
		(end 361.814364 -224.829878)
		(width 0.0889)
		(layer "In2.Cu")
		(net "P5E_CPU0_PE1_TX_DP<6>")
	)
	(arc
		(start 362.025184 -221.115382)
		(mid 361.945022 -220.843193)
		(end 361.742736 -220.644212)
		(width 0.0889)
		(layer "In2.Cu")
		(net "P5E_CPU0_PE1_TX_DP<6>")
	)
	(arc
		(start 361.278932 -219.178124)
		(mid 361.481345 -218.971711)
		(end 361.555284 -218.692222)
		(width 0.0889)
		(layer "In2.Cu")
		(net "P5E_CPU0_PE1_TX_DP<6>")
	)
	(arc
		(start 361.555284 -218.692222)
		(mid 361.602963 -218.509322)
		(end 361.733846 -218.372944)
		(width 0.0889)
		(layer "In2.Cu")
		(net "P5E_CPU0_PE1_TX_DP<6>")
	)
	(arc
		(start 361.085892 -222.776288)
		(mid 361.085559 -222.763844)
		(end 361.085638 -222.751396)
		(width 0.0889)
		(layer "In2.Cu")
		(net "P5E_CPU0_PE1_TX_DP<6>")
	)
	(arc
		(start 361.278932 -222.433642)
		(mid 361.481345 -222.227229)
		(end 361.555284 -221.94774)
		(width 0.0889)
		(layer "In2.Cu")
		(net "P5E_CPU0_PE1_TX_DP<6>")
	)
	(arc
		(start 361.555284 -223.561402)
		(mid 361.476143 -223.286779)
		(end 361.272836 -223.085914)
		(width 0.0889)
		(layer "In2.Cu")
		(net "P5E_CPU0_PE1_TX_DP<6>")
	)
	(arc
		(start 361.742736 -218.367864)
		(mid 361.947071 -218.165259)
		(end 362.025184 -217.888312)
		(width 0.0889)
		(layer "In2.Cu")
		(net "P5E_CPU0_PE1_TX_DP<6>")
	)
	(arc
		(start 361.555284 -221.94774)
		(mid 361.602963 -221.76484)
		(end 361.733846 -221.628462)
		(width 0.0889)
		(layer "In2.Cu")
		(net "P5E_CPU0_PE1_TX_DP<6>")
	)
	(arc
		(start 361.555284 -217.064336)
		(mid 361.483049 -216.787812)
		(end 361.284774 -216.58199)
		(width 0.0889)
		(layer "In2.Cu")
		(net "P5E_CPU0_PE1_TX_DP<6>")
	)
	(arc
		(start 361.742736 -221.623382)
		(mid 361.947071 -221.420777)
		(end 362.025184 -221.14383)
		(width 0.0889)
		(layer "In2.Cu")
		(net "P5E_CPU0_PE1_TX_DP<6>")
	)
	(arc
		(start 361.263946 -223.080834)
		(mid 361.136866 -222.95082)
		(end 361.085892 -222.776288)
		(width 0.0889)
		(layer "In2.Cu")
		(net "P5E_CPU0_PE1_TX_DP<6>")
	)
	(arc
		(start 361.555284 -220.319854)
		(mid 361.481368 -220.040352)
		(end 361.278932 -219.833952)
		(width 0.0889)
		(layer "In2.Cu")
		(net "P5E_CPU0_PE1_TX_DP<6>")
	)
	(arc
		(start 361.272582 -215.926162)
		(mid 361.476917 -215.723557)
		(end 361.55503 -215.44661)
		(width 0.0889)
		(layer "In2.Cu")
		(net "P5E_CPU0_PE1_TX_DP<6>")
	)
	(arc
		(start 361.814364 -224.829878)
		(mid 361.969762 -224.633597)
		(end 362.025184 -224.389442)
		(width 0.0889)
		(layer "In2.Cu")
		(net "P5E_CPU0_PE1_TX_DP<6>")
	)
	(arc
		(start 362.025184 -217.859864)
		(mid 361.945022 -217.587675)
		(end 361.742736 -217.388694)
		(width 0.0889)
		(layer "In2.Cu")
		(net "P5E_CPU0_PE1_TX_DP<6>")
	)
	(arc
		(start 361.733846 -217.383614)
		(mid 361.602932 -217.247254)
		(end 361.555284 -217.064336)
		(width 0.0889)
		(layer "In2.Cu")
		(net "P5E_CPU0_PE1_TX_DP<6>")
	)
	(arc
		(start 361.263946 -219.825316)
		(mid 361.08547 -219.506038)
		(end 361.263946 -219.18676)
		(width 0.0889)
		(layer "In2.Cu")
		(net "P5E_CPU0_PE1_TX_DP<6>")
	)
	(arc
		(start 361.733846 -220.639132)
		(mid 361.602932 -220.502772)
		(end 361.555284 -220.319854)
		(width 0.0889)
		(layer "In2.Cu")
		(net "P5E_CPU0_PE1_TX_DP<6>")
	)
	(arc
		(start 361.085638 -222.751396)
		(mid 361.135653 -222.574265)
		(end 361.263946 -222.442278)
		(width 0.0889)
		(layer "In2.Cu")
		(net "P5E_CPU0_PE1_TX_DP<6>")
	)
	(arc
		(start 362.025184 -224.379536)
		(mid 361.947073 -224.102587)
		(end 361.742736 -223.899984)
		(width 0.0889)
		(layer "In2.Cu")
		(net "P5E_CPU0_PE1_TX_DP<6>")
	)
	(segment
		(start 418.2872 -17.601438)
		(end 418.588444 -17.300194)
		(width 0.13208)
		(layer "F.Cu")
		(net "P5E_CPU0_PE1_TX_DP<5>")
	)
	(segment
		(start 418.588444 -17.300194)
		(end 418.588444 -16.681958)
		(width 0.13208)
		(layer "F.Cu")
		(net "P5E_CPU0_PE1_TX_DP<5>")
	)
	(segment
		(start 418.588444 -16.681958)
		(end 418.2618 -16.355314)
		(width 0.13208)
		(layer "F.Cu")
		(net "P5E_CPU0_PE1_TX_DP<5>")
	)
	(segment
		(start 362.399834 -224.925382)
		(end 362.399834 -224.389442)
		(width 0.13208)
		(layer "F.Cu")
		(net "P5E_CPU0_PE1_TX_DP<5>")
	)
	(segment
		(start 362.26242 -213.733126)
		(end 362.26242 -214.61095)
		(width 0.14732)
		(layer "In2.Cu")
		(net "P5E_CPU0_PE1_TX_DP<5>")
	)
	(segment
		(start 362.30433 -217.0557)
		(end 362.30433 -217.07856)
		(width 0.0889)
		(layer "In2.Cu")
		(net "P5E_CPU0_PE1_TX_DP<5>")
	)
	(segment
		(start 361.834684 -219.490544)
		(end 361.834684 -219.515944)
		(width 0.0889)
		(layer "In2.Cu")
		(net "P5E_CPU0_PE1_TX_DP<5>")
	)
	(segment
		(start 362.585254 -218.20378)
		(end 362.580936 -218.20632)
		(width 0.0889)
		(layer "In2.Cu")
		(net "P5E_CPU0_PE1_TX_DP<5>")
	)
	(segment
		(start 362.532168 -224.02927)
		(end 362.556298 -224.118424)
		(width 0.0889)
		(layer "In2.Cu")
		(net "P5E_CPU0_PE1_TX_DP<5>")
	)
	(segment
		(start 362.556298 -224.118424)
		(end 362.399834 -224.389442)
		(width 0.0889)
		(layer "In2.Cu")
		(net "P5E_CPU0_PE1_TX_DP<5>")
	)
	(segment
		(start 418.58184 -17.896078)
		(end 418.58184 -21.142198)
		(width 0.14732)
		(layer "In2.Cu")
		(net "P5E_CPU0_PE1_TX_DP<5>")
	)
	(segment
		(start 362.59389 -218.198954)
		(end 362.587032 -218.202764)
		(width 0.0889)
		(layer "In2.Cu")
		(net "P5E_CPU0_PE1_TX_DP<5>")
	)
	(segment
		(start 416.362134 -54.971696)
		(end 411.941772 -80.032352)
		(width 0.14732)
		(layer "In2.Cu")
		(net "P5E_CPU0_PE1_TX_DP<5>")
	)
	(segment
		(start 362.595922 -221.453202)
		(end 362.59389 -221.454472)
		(width 0.0889)
		(layer "In2.Cu")
		(net "P5E_CPU0_PE1_TX_DP<5>")
	)
	(segment
		(start 362.262166 -213.732872)
		(end 362.26242 -213.733126)
		(width 0.14732)
		(layer "In2.Cu")
		(net "P5E_CPU0_PE1_TX_DP<5>")
	)
	(segment
		(start 362.595922 -218.197684)
		(end 362.59389 -218.198954)
		(width 0.0889)
		(layer "In2.Cu")
		(net "P5E_CPU0_PE1_TX_DP<5>")
	)
	(segment
		(start 361.834684 -222.746062)
		(end 361.834684 -222.780098)
		(width 0.0889)
		(layer "In2.Cu")
		(net "P5E_CPU0_PE1_TX_DP<5>")
	)
	(segment
		(start 362.125768 -215.755982)
		(end 362.116878 -215.761062)
		(width 0.0889)
		(layer "In2.Cu")
		(net "P5E_CPU0_PE1_TX_DP<5>")
	)
	(segment
		(start 362.58627 -221.45879)
		(end 362.585254 -221.459298)
		(width 0.0889)
		(layer "In2.Cu")
		(net "P5E_CPU0_PE1_TX_DP<5>")
	)
	(segment
		(start 362.30433 -223.56699)
		(end 362.30433 -223.575626)
		(width 0.0889)
		(layer "In2.Cu")
		(net "P5E_CPU0_PE1_TX_DP<5>")
	)
	(segment
		(start 362.587032 -220.809566)
		(end 362.595922 -220.814646)
		(width 0.0889)
		(layer "In2.Cu")
		(net "P5E_CPU0_PE1_TX_DP<5>")
	)
	(segment
		(start 362.125768 -222.267018)
		(end 362.116878 -222.272098)
		(width 0.0889)
		(layer "In2.Cu")
		(net "P5E_CPU0_PE1_TX_DP<5>")
	)
	(segment
		(start 362.59389 -221.454472)
		(end 362.587032 -221.458282)
		(width 0.0889)
		(layer "In2.Cu")
		(net "P5E_CPU0_PE1_TX_DP<5>")
	)
	(segment
		(start 418.58184 -21.142198)
		(end 416.362134 -54.971696)
		(width 0.14732)
		(layer "In2.Cu")
		(net "P5E_CPU0_PE1_TX_DP<5>")
	)
	(segment
		(start 411.941772 -80.032352)
		(end 364.291118 -160.441386)
		(width 0.14732)
		(layer "In2.Cu")
		(net "P5E_CPU0_PE1_TX_DP<5>")
	)
	(segment
		(start 364.291118 -160.441386)
		(end 360.094784 -184.246012)
		(width 0.14732)
		(layer "In2.Cu")
		(net "P5E_CPU0_PE1_TX_DP<5>")
	)
	(segment
		(start 362.30433 -220.311218)
		(end 362.30433 -220.334078)
		(width 0.0889)
		(layer "In2.Cu")
		(net "P5E_CPU0_PE1_TX_DP<5>")
	)
	(segment
		(start 362.587032 -221.458282)
		(end 362.58627 -221.45879)
		(width 0.0889)
		(layer "In2.Cu")
		(net "P5E_CPU0_PE1_TX_DP<5>")
	)
	(segment
		(start 362.116878 -215.761062)
		(end 362.110782 -215.764618)
		(width 0.0889)
		(layer "In2.Cu")
		(net "P5E_CPU0_PE1_TX_DP<5>")
	)
	(segment
		(start 362.587032 -217.554048)
		(end 362.595922 -217.559128)
		(width 0.0889)
		(layer "In2.Cu")
		(net "P5E_CPU0_PE1_TX_DP<5>")
	)
	(segment
		(start 362.125768 -219.0115)
		(end 362.116878 -219.01658)
		(width 0.0889)
		(layer "In2.Cu")
		(net "P5E_CPU0_PE1_TX_DP<5>")
	)
	(segment
		(start 362.30433 -214.674958)
		(end 362.30433 -215.436704)
		(width 0.0889)
		(layer "In2.Cu")
		(net "P5E_CPU0_PE1_TX_DP<5>")
	)
	(segment
		(start 361.83443 -216.25052)
		(end 361.834684 -216.260426)
		(width 0.0889)
		(layer "In2.Cu")
		(net "P5E_CPU0_PE1_TX_DP<5>")
	)
	(segment
		(start 362.585254 -221.459298)
		(end 362.580936 -221.461838)
		(width 0.0889)
		(layer "In2.Cu")
		(net "P5E_CPU0_PE1_TX_DP<5>")
	)
	(segment
		(start 362.26242 -214.633048)
		(end 362.30433 -214.674958)
		(width 0.0889)
		(layer "In2.Cu")
		(net "P5E_CPU0_PE1_TX_DP<5>")
	)
	(segment
		(start 362.26242 -214.61095)
		(end 362.26242 -214.633048)
		(width 0.0889)
		(layer "In2.Cu")
		(net "P5E_CPU0_PE1_TX_DP<5>")
	)
	(segment
		(start 362.587032 -218.202764)
		(end 362.58627 -218.203272)
		(width 0.0889)
		(layer "In2.Cu")
		(net "P5E_CPU0_PE1_TX_DP<5>")
	)
	(segment
		(start 360.094784 -184.246012)
		(end 362.262166 -213.732872)
		(width 0.14732)
		(layer "In2.Cu")
		(net "P5E_CPU0_PE1_TX_DP<5>")
	)
	(segment
		(start 418.2872 -17.601438)
		(end 418.58184 -17.896078)
		(width 0.14732)
		(layer "In2.Cu")
		(net "P5E_CPU0_PE1_TX_DP<5>")
	)
	(segment
		(start 362.58627 -218.203272)
		(end 362.585254 -218.20378)
		(width 0.0889)
		(layer "In2.Cu")
		(net "P5E_CPU0_PE1_TX_DP<5>")
	)
	(arc
		(start 362.595922 -220.814646)
		(mid 362.774519 -221.133924)
		(end 362.595922 -221.453202)
		(width 0.0889)
		(layer "In2.Cu")
		(net "P5E_CPU0_PE1_TX_DP<5>")
	)
	(arc
		(start 362.595922 -217.559128)
		(mid 362.774519 -217.878406)
		(end 362.595922 -218.197684)
		(width 0.0889)
		(layer "In2.Cu")
		(net "P5E_CPU0_PE1_TX_DP<5>")
	)
	(arc
		(start 361.834684 -216.260426)
		(mid 361.912795 -216.537375)
		(end 362.117132 -216.739978)
		(width 0.0889)
		(layer "In2.Cu")
		(net "P5E_CPU0_PE1_TX_DP<5>")
	)
	(arc
		(start 362.117132 -223.251268)
		(mid 362.252065 -223.384622)
		(end 362.30433 -223.56699)
		(width 0.0889)
		(layer "In2.Cu")
		(net "P5E_CPU0_PE1_TX_DP<5>")
	)
	(arc
		(start 362.580936 -218.20632)
		(mid 362.378349 -218.412671)
		(end 362.30433 -218.692222)
		(width 0.0889)
		(layer "In2.Cu")
		(net "P5E_CPU0_PE1_TX_DP<5>")
	)
	(arc
		(start 361.834684 -219.515944)
		(mid 361.912795 -219.792893)
		(end 362.117132 -219.995496)
		(width 0.0889)
		(layer "In2.Cu")
		(net "P5E_CPU0_PE1_TX_DP<5>")
	)
	(arc
		(start 362.110782 -215.764618)
		(mid 361.908369 -215.971031)
		(end 361.83443 -216.25052)
		(width 0.0889)
		(layer "In2.Cu")
		(net "P5E_CPU0_PE1_TX_DP<5>")
	)
	(arc
		(start 362.117132 -216.739978)
		(mid 362.252065 -216.873332)
		(end 362.30433 -217.0557)
		(width 0.0889)
		(layer "In2.Cu")
		(net "P5E_CPU0_PE1_TX_DP<5>")
	)
	(arc
		(start 362.30433 -215.436704)
		(mid 362.256651 -215.619604)
		(end 362.125768 -215.755982)
		(width 0.0889)
		(layer "In2.Cu")
		(net "P5E_CPU0_PE1_TX_DP<5>")
	)
	(arc
		(start 362.116878 -219.01658)
		(mid 361.914055 -219.216811)
		(end 361.834684 -219.490544)
		(width 0.0889)
		(layer "In2.Cu")
		(net "P5E_CPU0_PE1_TX_DP<5>")
	)
	(arc
		(start 361.834684 -222.780098)
		(mid 361.914846 -223.052287)
		(end 362.117132 -223.251268)
		(width 0.0889)
		(layer "In2.Cu")
		(net "P5E_CPU0_PE1_TX_DP<5>")
	)
	(arc
		(start 362.30433 -221.94774)
		(mid 362.256651 -222.13064)
		(end 362.125768 -222.267018)
		(width 0.0889)
		(layer "In2.Cu")
		(net "P5E_CPU0_PE1_TX_DP<5>")
	)
	(arc
		(start 362.117132 -219.995496)
		(mid 362.252065 -220.12885)
		(end 362.30433 -220.311218)
		(width 0.0889)
		(layer "In2.Cu")
		(net "P5E_CPU0_PE1_TX_DP<5>")
	)
	(arc
		(start 362.30433 -218.692222)
		(mid 362.256651 -218.875122)
		(end 362.125768 -219.0115)
		(width 0.0889)
		(layer "In2.Cu")
		(net "P5E_CPU0_PE1_TX_DP<5>")
	)
	(arc
		(start 362.30433 -220.334078)
		(mid 362.383549 -220.608763)
		(end 362.587032 -220.809566)
		(width 0.0889)
		(layer "In2.Cu")
		(net "P5E_CPU0_PE1_TX_DP<5>")
	)
	(arc
		(start 362.116878 -222.272098)
		(mid 361.914055 -222.472329)
		(end 361.834684 -222.746062)
		(width 0.0889)
		(layer "In2.Cu")
		(net "P5E_CPU0_PE1_TX_DP<5>")
	)
	(arc
		(start 362.580936 -221.461838)
		(mid 362.378349 -221.668189)
		(end 362.30433 -221.94774)
		(width 0.0889)
		(layer "In2.Cu")
		(net "P5E_CPU0_PE1_TX_DP<5>")
	)
	(arc
		(start 362.30433 -217.07856)
		(mid 362.383549 -217.353245)
		(end 362.587032 -217.554048)
		(width 0.0889)
		(layer "In2.Cu")
		(net "P5E_CPU0_PE1_TX_DP<5>")
	)
	(arc
		(start 362.30433 -223.575626)
		(mid 362.364373 -223.829513)
		(end 362.532168 -224.02927)
		(width 0.0889)
		(layer "In2.Cu")
		(net "P5E_CPU0_PE1_TX_DP<5>")
	)
	(segment
		(start 421.641524 -18.20799)
		(end 421.9702 -17.879314)
		(width 0.13208)
		(layer "F.Cu")
		(net "P5E_CPU0_PE1_TX_DP<4>")
	)
	(segment
		(start 363.80928 -225.738944)
		(end 363.80928 -225.203258)
		(width 0.13208)
		(layer "F.Cu")
		(net "P5E_CPU0_PE1_TX_DP<4>")
	)
	(segment
		(start 363.809534 -225.739198)
		(end 363.80928 -225.738944)
		(width 0.13208)
		(layer "F.Cu")
		(net "P5E_CPU0_PE1_TX_DP<4>")
	)
	(segment
		(start 421.641524 -18.822162)
		(end 421.641524 -18.20799)
		(width 0.13208)
		(layer "F.Cu")
		(net "P5E_CPU0_PE1_TX_DP<4>")
	)
	(segment
		(start 421.9448 -19.125438)
		(end 421.641524 -18.822162)
		(width 0.13208)
		(layer "F.Cu")
		(net "P5E_CPU0_PE1_TX_DP<4>")
	)
	(segment
		(start 421.9448 -19.125438)
		(end 421.65016 -19.420078)
		(width 0.14732)
		(layer "In2.Cu")
		(net "P5E_CPU0_PE1_TX_DP<4>")
	)
	(segment
		(start 363.43463 -218.692222)
		(end 363.43463 -218.707716)
		(width 0.0889)
		(layer "In2.Cu")
		(net "P5E_CPU0_PE1_TX_DP<4>")
	)
	(segment
		(start 363.152436 -219.18168)
		(end 363.143546 -219.18676)
		(width 0.0889)
		(layer "In2.Cu")
		(net "P5E_CPU0_PE1_TX_DP<4>")
	)
	(segment
		(start 417.487608 -55.742586)
		(end 413.132778 -80.430878)
		(width 0.14732)
		(layer "In2.Cu")
		(net "P5E_CPU0_PE1_TX_DP<4>")
	)
	(segment
		(start 363.43463 -213.327488)
		(end 363.43463 -215.436196)
		(width 0.0889)
		(layer "In2.Cu")
		(net "P5E_CPU0_PE1_TX_DP<4>")
	)
	(segment
		(start 363.43463 -215.436196)
		(end 363.434376 -215.436704)
		(width 0.0889)
		(layer "In2.Cu")
		(net "P5E_CPU0_PE1_TX_DP<4>")
	)
	(segment
		(start 363.154722 -222.435928)
		(end 363.152944 -222.436944)
		(width 0.0889)
		(layer "In2.Cu")
		(net "P5E_CPU0_PE1_TX_DP<4>")
	)
	(segment
		(start 363.152182 -216.574878)
		(end 363.158532 -216.578434)
		(width 0.0889)
		(layer "In2.Cu")
		(net "P5E_CPU0_PE1_TX_DP<4>")
	)
	(segment
		(start 363.367828 -172.618654)
		(end 361.307888 -184.305956)
		(width 0.14732)
		(layer "In2.Cu")
		(net "P5E_CPU0_PE1_TX_DP<4>")
	)
	(segment
		(start 363.143546 -219.825316)
		(end 363.152436 -219.830396)
		(width 0.0889)
		(layer "In2.Cu")
		(net "P5E_CPU0_PE1_TX_DP<4>")
	)
	(segment
		(start 365.428022 -160.931352)
		(end 363.367828 -172.618654)
		(width 0.14732)
		(layer "In2.Cu")
		(net "P5E_CPU0_PE1_TX_DP<4>")
	)
	(segment
		(start 363.621574 -223.899476)
		(end 363.622336 -223.899984)
		(width 0.0889)
		(layer "In2.Cu")
		(net "P5E_CPU0_PE1_TX_DP<4>")
	)
	(segment
		(start 363.621828 -218.368118)
		(end 363.615986 -218.37142)
		(width 0.0889)
		(layer "In2.Cu")
		(net "P5E_CPU0_PE1_TX_DP<4>")
	)
	(segment
		(start 363.613446 -220.639132)
		(end 363.622336 -220.644212)
		(width 0.0889)
		(layer "In2.Cu")
		(net "P5E_CPU0_PE1_TX_DP<4>")
	)
	(segment
		(start 363.16539 -215.918034)
		(end 363.152182 -215.926162)
		(width 0.0889)
		(layer "In2.Cu")
		(net "P5E_CPU0_PE1_TX_DP<4>")
	)
	(segment
		(start 363.628178 -218.364308)
		(end 363.621828 -218.368118)
		(width 0.0889)
		(layer "In2.Cu")
		(net "P5E_CPU0_PE1_TX_DP<4>")
	)
	(segment
		(start 363.676946 -224.843086)
		(end 363.652816 -224.93224)
		(width 0.0889)
		(layer "In2.Cu")
		(net "P5E_CPU0_PE1_TX_DP<4>")
	)
	(segment
		(start 363.615986 -218.37142)
		(end 363.613192 -218.372944)
		(width 0.0889)
		(layer "In2.Cu")
		(net "P5E_CPU0_PE1_TX_DP<4>")
	)
	(segment
		(start 363.619034 -223.897952)
		(end 363.621574 -223.899476)
		(width 0.0889)
		(layer "In2.Cu")
		(net "P5E_CPU0_PE1_TX_DP<4>")
	)
	(segment
		(start 363.652816 -224.93224)
		(end 363.80928 -225.203258)
		(width 0.0889)
		(layer "In2.Cu")
		(net "P5E_CPU0_PE1_TX_DP<4>")
	)
	(segment
		(start 363.143546 -223.080834)
		(end 363.152436 -223.085914)
		(width 0.0889)
		(layer "In2.Cu")
		(net "P5E_CPU0_PE1_TX_DP<4>")
	)
	(segment
		(start 421.65016 -20.038314)
		(end 417.487608 -55.742586)
		(width 0.14732)
		(layer "In2.Cu")
		(net "P5E_CPU0_PE1_TX_DP<4>")
	)
	(segment
		(start 363.476794 -211.611972)
		(end 363.476794 -213.263226)
		(width 0.14732)
		(layer "In2.Cu")
		(net "P5E_CPU0_PE1_TX_DP<4>")
	)
	(segment
		(start 363.613446 -217.383614)
		(end 363.622336 -217.388694)
		(width 0.0889)
		(layer "In2.Cu")
		(net "P5E_CPU0_PE1_TX_DP<4>")
	)
	(segment
		(start 363.622336 -221.623382)
		(end 363.613446 -221.628462)
		(width 0.0889)
		(layer "In2.Cu")
		(net "P5E_CPU0_PE1_TX_DP<4>")
	)
	(segment
		(start 363.152436 -219.830396)
		(end 363.158532 -219.833952)
		(width 0.0889)
		(layer "In2.Cu")
		(net "P5E_CPU0_PE1_TX_DP<4>")
	)
	(segment
		(start 362.964984 -216.241884)
		(end 362.964984 -216.259156)
		(width 0.0889)
		(layer "In2.Cu")
		(net "P5E_CPU0_PE1_TX_DP<4>")
	)
	(segment
		(start 363.434884 -223.561402)
		(end 363.434884 -223.575626)
		(width 0.0889)
		(layer "In2.Cu")
		(net "P5E_CPU0_PE1_TX_DP<4>")
	)
	(segment
		(start 363.158532 -222.433642)
		(end 363.154722 -222.435928)
		(width 0.0889)
		(layer "In2.Cu")
		(net "P5E_CPU0_PE1_TX_DP<4>")
	)
	(segment
		(start 413.132778 -80.430878)
		(end 365.428022 -160.931352)
		(width 0.14732)
		(layer "In2.Cu")
		(net "P5E_CPU0_PE1_TX_DP<4>")
	)
	(segment
		(start 363.476794 -213.263226)
		(end 363.476794 -213.285324)
		(width 0.0889)
		(layer "In2.Cu")
		(net "P5E_CPU0_PE1_TX_DP<4>")
	)
	(segment
		(start 421.65016 -19.420078)
		(end 421.65016 -20.038314)
		(width 0.14732)
		(layer "In2.Cu")
		(net "P5E_CPU0_PE1_TX_DP<4>")
	)
	(segment
		(start 363.904784 -217.859864)
		(end 363.904784 -217.878406)
		(width 0.0889)
		(layer "In2.Cu")
		(net "P5E_CPU0_PE1_TX_DP<4>")
	)
	(segment
		(start 363.613446 -223.894904)
		(end 363.619034 -223.897952)
		(width 0.0889)
		(layer "In2.Cu")
		(net "P5E_CPU0_PE1_TX_DP<4>")
	)
	(segment
		(start 363.476794 -213.285324)
		(end 363.43463 -213.327488)
		(width 0.0889)
		(layer "In2.Cu")
		(net "P5E_CPU0_PE1_TX_DP<4>")
	)
	(segment
		(start 363.152944 -222.436944)
		(end 363.143546 -222.442278)
		(width 0.0889)
		(layer "In2.Cu")
		(net "P5E_CPU0_PE1_TX_DP<4>")
	)
	(segment
		(start 361.307888 -184.305956)
		(end 363.476794 -211.611972)
		(width 0.14732)
		(layer "In2.Cu")
		(net "P5E_CPU0_PE1_TX_DP<4>")
	)
	(arc
		(start 363.622336 -220.644212)
		(mid 363.905088 -221.13386)
		(end 363.622336 -221.623382)
		(width 0.0889)
		(layer "In2.Cu")
		(net "P5E_CPU0_PE1_TX_DP<4>")
	)
	(arc
		(start 363.143546 -219.18676)
		(mid 362.96507 -219.506038)
		(end 363.143546 -219.825316)
		(width 0.0889)
		(layer "In2.Cu")
		(net "P5E_CPU0_PE1_TX_DP<4>")
	)
	(arc
		(start 363.152436 -223.085914)
		(mid 363.355741 -223.28678)
		(end 363.434884 -223.561402)
		(width 0.0889)
		(layer "In2.Cu")
		(net "P5E_CPU0_PE1_TX_DP<4>")
	)
	(arc
		(start 363.622336 -223.899984)
		(mid 363.9032 -224.346045)
		(end 363.693964 -224.829878)
		(width 0.0889)
		(layer "In2.Cu")
		(net "P5E_CPU0_PE1_TX_DP<4>")
	)
	(arc
		(start 363.434884 -223.575626)
		(mid 363.482563 -223.758526)
		(end 363.613446 -223.894904)
		(width 0.0889)
		(layer "In2.Cu")
		(net "P5E_CPU0_PE1_TX_DP<4>")
	)
	(arc
		(start 363.613192 -218.372944)
		(mid 363.482278 -218.509304)
		(end 363.43463 -218.692222)
		(width 0.0889)
		(layer "In2.Cu")
		(net "P5E_CPU0_PE1_TX_DP<4>")
	)
	(arc
		(start 363.434884 -217.064336)
		(mid 363.482563 -217.247236)
		(end 363.613446 -217.383614)
		(width 0.0889)
		(layer "In2.Cu")
		(net "P5E_CPU0_PE1_TX_DP<4>")
	)
	(arc
		(start 363.434884 -221.94774)
		(mid 363.360968 -222.227242)
		(end 363.158532 -222.433642)
		(width 0.0889)
		(layer "In2.Cu")
		(net "P5E_CPU0_PE1_TX_DP<4>")
	)
	(arc
		(start 362.964984 -216.259156)
		(mid 363.017254 -216.441521)
		(end 363.152182 -216.574878)
		(width 0.0889)
		(layer "In2.Cu")
		(net "P5E_CPU0_PE1_TX_DP<4>")
	)
	(arc
		(start 363.158532 -216.578434)
		(mid 363.360945 -216.784847)
		(end 363.434884 -217.064336)
		(width 0.0889)
		(layer "In2.Cu")
		(net "P5E_CPU0_PE1_TX_DP<4>")
	)
	(arc
		(start 362.964984 -222.751396)
		(mid 362.964904 -222.763844)
		(end 362.965238 -222.776288)
		(width 0.0889)
		(layer "In2.Cu")
		(net "P5E_CPU0_PE1_TX_DP<4>")
	)
	(arc
		(start 363.434884 -220.319854)
		(mid 363.482563 -220.502754)
		(end 363.613446 -220.639132)
		(width 0.0889)
		(layer "In2.Cu")
		(net "P5E_CPU0_PE1_TX_DP<4>")
	)
	(arc
		(start 363.622336 -217.388694)
		(mid 363.824622 -217.587675)
		(end 363.904784 -217.859864)
		(width 0.0889)
		(layer "In2.Cu")
		(net "P5E_CPU0_PE1_TX_DP<4>")
	)
	(arc
		(start 363.434376 -215.436704)
		(mid 363.362568 -215.7124)
		(end 363.16539 -215.918034)
		(width 0.0889)
		(layer "In2.Cu")
		(net "P5E_CPU0_PE1_TX_DP<4>")
	)
	(arc
		(start 363.143546 -222.442278)
		(mid 363.015142 -222.574223)
		(end 362.964984 -222.751396)
		(width 0.0889)
		(layer "In2.Cu")
		(net "P5E_CPU0_PE1_TX_DP<4>")
	)
	(arc
		(start 363.43463 -218.707716)
		(mid 363.35526 -218.98145)
		(end 363.152436 -219.18168)
		(width 0.0889)
		(layer "In2.Cu")
		(net "P5E_CPU0_PE1_TX_DP<4>")
	)
	(arc
		(start 363.904784 -217.878406)
		(mid 363.830793 -218.157972)
		(end 363.628178 -218.364308)
		(width 0.0889)
		(layer "In2.Cu")
		(net "P5E_CPU0_PE1_TX_DP<4>")
	)
	(arc
		(start 363.613446 -221.628462)
		(mid 363.482532 -221.764822)
		(end 363.434884 -221.94774)
		(width 0.0889)
		(layer "In2.Cu")
		(net "P5E_CPU0_PE1_TX_DP<4>")
	)
	(arc
		(start 363.693964 -224.829878)
		(mid 363.685518 -224.836563)
		(end 363.676946 -224.843086)
		(width 0.0889)
		(layer "In2.Cu")
		(net "P5E_CPU0_PE1_TX_DP<4>")
	)
	(arc
		(start 363.152182 -215.926162)
		(mid 363.017249 -216.059516)
		(end 362.964984 -216.241884)
		(width 0.0889)
		(layer "In2.Cu")
		(net "P5E_CPU0_PE1_TX_DP<4>")
	)
	(arc
		(start 362.965238 -222.776288)
		(mid 363.016292 -222.950868)
		(end 363.143546 -223.080834)
		(width 0.0889)
		(layer "In2.Cu")
		(net "P5E_CPU0_PE1_TX_DP<4>")
	)
	(arc
		(start 363.158532 -219.833952)
		(mid 363.360945 -220.040365)
		(end 363.434884 -220.319854)
		(width 0.0889)
		(layer "In2.Cu")
		(net "P5E_CPU0_PE1_TX_DP<4>")
	)
	(segment
		(start 364.27918 -224.925382)
		(end 364.27918 -224.389696)
		(width 0.13208)
		(layer "F.Cu")
		(net "P5E_CPU0_PE1_TX_DP<3>")
	)
	(segment
		(start 424.176444 -17.300194)
		(end 424.176444 -16.681958)
		(width 0.13208)
		(layer "F.Cu")
		(net "P5E_CPU0_PE1_TX_DP<3>")
	)
	(segment
		(start 424.176444 -16.681958)
		(end 423.8498 -16.355314)
		(width 0.13208)
		(layer "F.Cu")
		(net "P5E_CPU0_PE1_TX_DP<3>")
	)
	(segment
		(start 423.8752 -17.601438)
		(end 424.176444 -17.300194)
		(width 0.13208)
		(layer "F.Cu")
		(net "P5E_CPU0_PE1_TX_DP<3>")
	)
	(segment
		(start 364.27918 -224.389696)
		(end 364.279434 -224.389442)
		(width 0.13208)
		(layer "F.Cu")
		(net "P5E_CPU0_PE1_TX_DP<3>")
	)
	(segment
		(start 424.16984 -17.896078)
		(end 424.16984 -19.507962)
		(width 0.14732)
		(layer "In2.Cu")
		(net "P5E_CPU0_PE1_TX_DP<3>")
	)
	(segment
		(start 363.984794 -216.732612)
		(end 363.98454 -216.732866)
		(width 0.0889)
		(layer "In2.Cu")
		(net "P5E_CPU0_PE1_TX_DP<3>")
	)
	(segment
		(start 364.466632 -221.458282)
		(end 364.463838 -221.459806)
		(width 0.0889)
		(layer "In2.Cu")
		(net "P5E_CPU0_PE1_TX_DP<3>")
	)
	(segment
		(start 364.18393 -213.327234)
		(end 364.18393 -215.384634)
		(width 0.0889)
		(layer "In2.Cu")
		(net "P5E_CPU0_PE1_TX_DP<3>")
	)
	(segment
		(start 364.14202 -213.263226)
		(end 364.14202 -213.285324)
		(width 0.0889)
		(layer "In2.Cu")
		(net "P5E_CPU0_PE1_TX_DP<3>")
	)
	(segment
		(start 418.442902 -54.106318)
		(end 413.748728 -80.723232)
		(width 0.14732)
		(layer "In2.Cu")
		(net "P5E_CPU0_PE1_TX_DP<3>")
	)
	(segment
		(start 364.466632 -218.202764)
		(end 364.460536 -218.20632)
		(width 0.0889)
		(layer "In2.Cu")
		(net "P5E_CPU0_PE1_TX_DP<3>")
	)
	(segment
		(start 422.664636 -24.010874)
		(end 418.442902 -54.106318)
		(width 0.14732)
		(layer "In2.Cu")
		(net "P5E_CPU0_PE1_TX_DP<3>")
	)
	(segment
		(start 364.18393 -223.56699)
		(end 364.18393 -223.575626)
		(width 0.0889)
		(layer "In2.Cu")
		(net "P5E_CPU0_PE1_TX_DP<3>")
	)
	(segment
		(start 364.18393 -217.0557)
		(end 364.18393 -217.07856)
		(width 0.0889)
		(layer "In2.Cu")
		(net "P5E_CPU0_PE1_TX_DP<3>")
	)
	(segment
		(start 363.98454 -216.732866)
		(end 363.990128 -216.735914)
		(width 0.0889)
		(layer "In2.Cu")
		(net "P5E_CPU0_PE1_TX_DP<3>")
	)
	(segment
		(start 363.990128 -216.735914)
		(end 363.996732 -216.739978)
		(width 0.0889)
		(layer "In2.Cu")
		(net "P5E_CPU0_PE1_TX_DP<3>")
	)
	(segment
		(start 364.466632 -220.809566)
		(end 364.475522 -220.814646)
		(width 0.0889)
		(layer "In2.Cu")
		(net "P5E_CPU0_PE1_TX_DP<3>")
	)
	(segment
		(start 364.005368 -219.0115)
		(end 363.996478 -219.01658)
		(width 0.0889)
		(layer "In2.Cu")
		(net "P5E_CPU0_PE1_TX_DP<3>")
	)
	(segment
		(start 363.714284 -222.746062)
		(end 363.714284 -222.780098)
		(width 0.0889)
		(layer "In2.Cu")
		(net "P5E_CPU0_PE1_TX_DP<3>")
	)
	(segment
		(start 361.982766 -184.25287)
		(end 364.14202 -211.55279)
		(width 0.14732)
		(layer "In2.Cu")
		(net "P5E_CPU0_PE1_TX_DP<3>")
	)
	(segment
		(start 364.146846 -215.473788)
		(end 363.878368 -215.742266)
		(width 0.0889)
		(layer "In2.Cu")
		(net "P5E_CPU0_PE1_TX_DP<3>")
	)
	(segment
		(start 364.463838 -221.459806)
		(end 364.460536 -221.461838)
		(width 0.0889)
		(layer "In2.Cu")
		(net "P5E_CPU0_PE1_TX_DP<3>")
	)
	(segment
		(start 364.14202 -211.55279)
		(end 364.14202 -213.263226)
		(width 0.14732)
		(layer "In2.Cu")
		(net "P5E_CPU0_PE1_TX_DP<3>")
	)
	(segment
		(start 364.14202 -213.285324)
		(end 364.18393 -213.327234)
		(width 0.0889)
		(layer "In2.Cu")
		(net "P5E_CPU0_PE1_TX_DP<3>")
	)
	(segment
		(start 364.468156 -221.45752)
		(end 364.466632 -221.458282)
		(width 0.0889)
		(layer "In2.Cu")
		(net "P5E_CPU0_PE1_TX_DP<3>")
	)
	(segment
		(start 363.714284 -219.490544)
		(end 363.714284 -219.515944)
		(width 0.0889)
		(layer "In2.Cu")
		(net "P5E_CPU0_PE1_TX_DP<3>")
	)
	(segment
		(start 364.435898 -224.118424)
		(end 364.279434 -224.389442)
		(width 0.0889)
		(layer "In2.Cu")
		(net "P5E_CPU0_PE1_TX_DP<3>")
	)
	(segment
		(start 363.714538 -216.138252)
		(end 363.714538 -216.25052)
		(width 0.0889)
		(layer "In2.Cu")
		(net "P5E_CPU0_PE1_TX_DP<3>")
	)
	(segment
		(start 364.475522 -221.453202)
		(end 364.468156 -221.45752)
		(width 0.0889)
		(layer "In2.Cu")
		(net "P5E_CPU0_PE1_TX_DP<3>")
	)
	(segment
		(start 364.18393 -220.311218)
		(end 364.18393 -220.334078)
		(width 0.0889)
		(layer "In2.Cu")
		(net "P5E_CPU0_PE1_TX_DP<3>")
	)
	(segment
		(start 366.041686 -161.226754)
		(end 361.982766 -184.25287)
		(width 0.14732)
		(layer "In2.Cu")
		(net "P5E_CPU0_PE1_TX_DP<3>")
	)
	(segment
		(start 364.005368 -222.267018)
		(end 363.996478 -222.272098)
		(width 0.0889)
		(layer "In2.Cu")
		(net "P5E_CPU0_PE1_TX_DP<3>")
	)
	(segment
		(start 424.16984 -19.507962)
		(end 422.664636 -24.010874)
		(width 0.14732)
		(layer "In2.Cu")
		(net "P5E_CPU0_PE1_TX_DP<3>")
	)
	(segment
		(start 364.18393 -215.384634)
		(end 364.183676 -215.38438)
		(width 0.0889)
		(layer "In2.Cu")
		(net "P5E_CPU0_PE1_TX_DP<3>")
	)
	(segment
		(start 413.748728 -80.723232)
		(end 366.041686 -161.226754)
		(width 0.14732)
		(layer "In2.Cu")
		(net "P5E_CPU0_PE1_TX_DP<3>")
	)
	(segment
		(start 364.475522 -218.197684)
		(end 364.466632 -218.202764)
		(width 0.0889)
		(layer "In2.Cu")
		(net "P5E_CPU0_PE1_TX_DP<3>")
	)
	(segment
		(start 364.411768 -224.02927)
		(end 364.435898 -224.118424)
		(width 0.0889)
		(layer "In2.Cu")
		(net "P5E_CPU0_PE1_TX_DP<3>")
	)
	(segment
		(start 423.8752 -17.601438)
		(end 424.16984 -17.896078)
		(width 0.14732)
		(layer "In2.Cu")
		(net "P5E_CPU0_PE1_TX_DP<3>")
	)
	(segment
		(start 364.466632 -217.554048)
		(end 364.475522 -217.559128)
		(width 0.0889)
		(layer "In2.Cu")
		(net "P5E_CPU0_PE1_TX_DP<3>")
	)
	(arc
		(start 363.878368 -215.742266)
		(mid 363.75711 -215.923975)
		(end 363.714538 -216.138252)
		(width 0.0889)
		(layer "In2.Cu")
		(net "P5E_CPU0_PE1_TX_DP<3>")
	)
	(arc
		(start 364.18393 -218.692222)
		(mid 364.136251 -218.875122)
		(end 364.005368 -219.0115)
		(width 0.0889)
		(layer "In2.Cu")
		(net "P5E_CPU0_PE1_TX_DP<3>")
	)
	(arc
		(start 364.183676 -215.38438)
		(mid 364.17415 -215.432743)
		(end 364.146846 -215.473788)
		(width 0.0889)
		(layer "In2.Cu")
		(net "P5E_CPU0_PE1_TX_DP<3>")
	)
	(arc
		(start 364.18393 -220.334078)
		(mid 364.263149 -220.608763)
		(end 364.466632 -220.809566)
		(width 0.0889)
		(layer "In2.Cu")
		(net "P5E_CPU0_PE1_TX_DP<3>")
	)
	(arc
		(start 363.996732 -219.995496)
		(mid 364.131665 -220.12885)
		(end 364.18393 -220.311218)
		(width 0.0889)
		(layer "In2.Cu")
		(net "P5E_CPU0_PE1_TX_DP<3>")
	)
	(arc
		(start 364.475522 -220.814646)
		(mid 364.654119 -221.133924)
		(end 364.475522 -221.453202)
		(width 0.0889)
		(layer "In2.Cu")
		(net "P5E_CPU0_PE1_TX_DP<3>")
	)
	(arc
		(start 363.996732 -223.251268)
		(mid 364.131665 -223.384622)
		(end 364.18393 -223.56699)
		(width 0.0889)
		(layer "In2.Cu")
		(net "P5E_CPU0_PE1_TX_DP<3>")
	)
	(arc
		(start 363.996478 -219.01658)
		(mid 363.793655 -219.216811)
		(end 363.714284 -219.490544)
		(width 0.0889)
		(layer "In2.Cu")
		(net "P5E_CPU0_PE1_TX_DP<3>")
	)
	(arc
		(start 364.18393 -221.94774)
		(mid 364.136251 -222.13064)
		(end 364.005368 -222.267018)
		(width 0.0889)
		(layer "In2.Cu")
		(net "P5E_CPU0_PE1_TX_DP<3>")
	)
	(arc
		(start 364.18393 -223.575626)
		(mid 364.243973 -223.829513)
		(end 364.411768 -224.02927)
		(width 0.0889)
		(layer "In2.Cu")
		(net "P5E_CPU0_PE1_TX_DP<3>")
	)
	(arc
		(start 363.996478 -222.272098)
		(mid 363.793655 -222.472329)
		(end 363.714284 -222.746062)
		(width 0.0889)
		(layer "In2.Cu")
		(net "P5E_CPU0_PE1_TX_DP<3>")
	)
	(arc
		(start 363.714284 -219.515944)
		(mid 363.792395 -219.792893)
		(end 363.996732 -219.995496)
		(width 0.0889)
		(layer "In2.Cu")
		(net "P5E_CPU0_PE1_TX_DP<3>")
	)
	(arc
		(start 364.460536 -221.461838)
		(mid 364.257949 -221.668189)
		(end 364.18393 -221.94774)
		(width 0.0889)
		(layer "In2.Cu")
		(net "P5E_CPU0_PE1_TX_DP<3>")
	)
	(arc
		(start 364.460536 -218.20632)
		(mid 364.257949 -218.412671)
		(end 364.18393 -218.692222)
		(width 0.0889)
		(layer "In2.Cu")
		(net "P5E_CPU0_PE1_TX_DP<3>")
	)
	(arc
		(start 363.996732 -216.739978)
		(mid 364.131665 -216.873332)
		(end 364.18393 -217.0557)
		(width 0.0889)
		(layer "In2.Cu")
		(net "P5E_CPU0_PE1_TX_DP<3>")
	)
	(arc
		(start 363.714284 -222.780098)
		(mid 363.794446 -223.052287)
		(end 363.996732 -223.251268)
		(width 0.0889)
		(layer "In2.Cu")
		(net "P5E_CPU0_PE1_TX_DP<3>")
	)
	(arc
		(start 363.714538 -216.25052)
		(mid 363.786708 -216.526862)
		(end 363.984794 -216.732612)
		(width 0.0889)
		(layer "In2.Cu")
		(net "P5E_CPU0_PE1_TX_DP<3>")
	)
	(arc
		(start 364.475522 -217.559128)
		(mid 364.654119 -217.878406)
		(end 364.475522 -218.197684)
		(width 0.0889)
		(layer "In2.Cu")
		(net "P5E_CPU0_PE1_TX_DP<3>")
	)
	(arc
		(start 364.18393 -217.07856)
		(mid 364.263149 -217.353245)
		(end 364.466632 -217.554048)
		(width 0.0889)
		(layer "In2.Cu")
		(net "P5E_CPU0_PE1_TX_DP<3>")
	)
	(segment
		(start 427.26356 -18.20799)
		(end 427.592236 -17.879314)
		(width 0.13208)
		(layer "F.Cu")
		(net "P5E_CPU0_PE1_TX_DP<2>")
	)
	(segment
		(start 427.26356 -18.822162)
		(end 427.26356 -18.20799)
		(width 0.13208)
		(layer "F.Cu")
		(net "P5E_CPU0_PE1_TX_DP<2>")
	)
	(segment
		(start 365.689134 -225.739198)
		(end 365.68888 -225.738944)
		(width 0.13208)
		(layer "F.Cu")
		(net "P5E_CPU0_PE1_TX_DP<2>")
	)
	(segment
		(start 427.566836 -19.125438)
		(end 427.26356 -18.822162)
		(width 0.13208)
		(layer "F.Cu")
		(net "P5E_CPU0_PE1_TX_DP<2>")
	)
	(segment
		(start 365.68888 -225.738944)
		(end 365.68888 -225.203258)
		(width 0.13208)
		(layer "F.Cu")
		(net "P5E_CPU0_PE1_TX_DP<2>")
	)
	(segment
		(start 365.784384 -221.133924)
		(end 365.784384 -221.115382)
		(width 0.0889)
		(layer "In2.Cu")
		(net "P5E_CPU0_PE1_TX_DP<2>")
	)
	(segment
		(start 414.89249 -81.20253)
		(end 419.643814 -54.262528)
		(width 0.14732)
		(layer "In2.Cu")
		(net "P5E_CPU0_PE1_TX_DP<2>")
	)
	(segment
		(start 427.272196 -19.853148)
		(end 427.272196 -19.420078)
		(width 0.14732)
		(layer "In2.Cu")
		(net "P5E_CPU0_PE1_TX_DP<2>")
	)
	(segment
		(start 365.501174 -223.899476)
		(end 365.499396 -223.89846)
		(width 0.0889)
		(layer "In2.Cu")
		(net "P5E_CPU0_PE1_TX_DP<2>")
	)
	(segment
		(start 365.500158 -221.624144)
		(end 365.501682 -221.623382)
		(width 0.0889)
		(layer "In2.Cu")
		(net "P5E_CPU0_PE1_TX_DP<2>")
	)
	(segment
		(start 365.038132 -216.578434)
		(end 365.032036 -216.574878)
		(width 0.0889)
		(layer "In2.Cu")
		(net "P5E_CPU0_PE1_TX_DP<2>")
	)
	(segment
		(start 365.492792 -218.372944)
		(end 365.501682 -218.367864)
		(width 0.0889)
		(layer "In2.Cu")
		(net "P5E_CPU0_PE1_TX_DP<2>")
	)
	(segment
		(start 365.784384 -224.389442)
		(end 365.784384 -224.379536)
		(width 0.0889)
		(layer "In2.Cu")
		(net "P5E_CPU0_PE1_TX_DP<2>")
	)
	(segment
		(start 427.272196 -19.420078)
		(end 427.566836 -19.125438)
		(width 0.14732)
		(layer "In2.Cu")
		(net "P5E_CPU0_PE1_TX_DP<2>")
	)
	(segment
		(start 365.501682 -221.623382)
		(end 365.502444 -221.622874)
		(width 0.0889)
		(layer "In2.Cu")
		(net "P5E_CPU0_PE1_TX_DP<2>")
	)
	(segment
		(start 365.032036 -223.085914)
		(end 365.023146 -223.080834)
		(width 0.0889)
		(layer "In2.Cu")
		(net "P5E_CPU0_PE1_TX_DP<2>")
	)
	(segment
		(start 365.31423 -213.327488)
		(end 365.356394 -213.285324)
		(width 0.0889)
		(layer "In2.Cu")
		(net "P5E_CPU0_PE1_TX_DP<2>")
	)
	(segment
		(start 365.314484 -223.575626)
		(end 365.314484 -223.561402)
		(width 0.0889)
		(layer "In2.Cu")
		(net "P5E_CPU0_PE1_TX_DP<2>")
	)
	(segment
		(start 365.31423 -218.707716)
		(end 365.31423 -218.692222)
		(width 0.0889)
		(layer "In2.Cu")
		(net "P5E_CPU0_PE1_TX_DP<2>")
	)
	(segment
		(start 365.492792 -221.628462)
		(end 365.500158 -221.624144)
		(width 0.0889)
		(layer "In2.Cu")
		(net "P5E_CPU0_PE1_TX_DP<2>")
	)
	(segment
		(start 423.605198 -27.304746)
		(end 427.239176 -19.99361)
		(width 0.14732)
		(layer "In2.Cu")
		(net "P5E_CPU0_PE1_TX_DP<2>")
	)
	(segment
		(start 365.038132 -219.833952)
		(end 365.032036 -219.830396)
		(width 0.0889)
		(layer "In2.Cu")
		(net "P5E_CPU0_PE1_TX_DP<2>")
	)
	(segment
		(start 421.676322 -40.429688)
		(end 421.676322 -40.428926)
		(width 0.14732)
		(layer "In2.Cu")
		(net "P5E_CPU0_PE1_TX_DP<2>")
	)
	(segment
		(start 365.356394 -213.285324)
		(end 365.356394 -213.263226)
		(width 0.0889)
		(layer "In2.Cu")
		(net "P5E_CPU0_PE1_TX_DP<2>")
	)
	(segment
		(start 365.31423 -215.452198)
		(end 365.31423 -213.327488)
		(width 0.0889)
		(layer "In2.Cu")
		(net "P5E_CPU0_PE1_TX_DP<2>")
	)
	(segment
		(start 419.643814 -54.262528)
		(end 421.676322 -40.429688)
		(width 0.14732)
		(layer "In2.Cu")
		(net "P5E_CPU0_PE1_TX_DP<2>")
	)
	(segment
		(start 421.676322 -40.428926)
		(end 423.605198 -27.304746)
		(width 0.14732)
		(layer "In2.Cu")
		(net "P5E_CPU0_PE1_TX_DP<2>")
	)
	(segment
		(start 365.31423 -221.963234)
		(end 365.31423 -221.94774)
		(width 0.0889)
		(layer "In2.Cu")
		(net "P5E_CPU0_PE1_TX_DP<2>")
	)
	(segment
		(start 365.784384 -217.878406)
		(end 365.784384 -217.859864)
		(width 0.0889)
		(layer "In2.Cu")
		(net "P5E_CPU0_PE1_TX_DP<2>")
	)
	(segment
		(start 365.501936 -220.644212)
		(end 365.493046 -220.639132)
		(width 0.0889)
		(layer "In2.Cu")
		(net "P5E_CPU0_PE1_TX_DP<2>")
	)
	(segment
		(start 367.177828 -161.719514)
		(end 414.89249 -81.20253)
		(width 0.14732)
		(layer "In2.Cu")
		(net "P5E_CPU0_PE1_TX_DP<2>")
	)
	(segment
		(start 365.501936 -217.388694)
		(end 365.493046 -217.383614)
		(width 0.0889)
		(layer "In2.Cu")
		(net "P5E_CPU0_PE1_TX_DP<2>")
	)
	(segment
		(start 365.68888 -225.203258)
		(end 365.532416 -224.93224)
		(width 0.0889)
		(layer "In2.Cu")
		(net "P5E_CPU0_PE1_TX_DP<2>")
	)
	(segment
		(start 365.501682 -218.367864)
		(end 365.507778 -218.364308)
		(width 0.0889)
		(layer "In2.Cu")
		(net "P5E_CPU0_PE1_TX_DP<2>")
	)
	(segment
		(start 365.356394 -213.263226)
		(end 365.356394 -211.631784)
		(width 0.14732)
		(layer "In2.Cu")
		(net "P5E_CPU0_PE1_TX_DP<2>")
	)
	(segment
		(start 363.198156 -184.295796)
		(end 367.177828 -161.719514)
		(width 0.14732)
		(layer "In2.Cu")
		(net "P5E_CPU0_PE1_TX_DP<2>")
	)
	(segment
		(start 365.502444 -221.622874)
		(end 365.507778 -221.619826)
		(width 0.0889)
		(layer "In2.Cu")
		(net "P5E_CPU0_PE1_TX_DP<2>")
	)
	(segment
		(start 365.023146 -219.18676)
		(end 365.032036 -219.18168)
		(width 0.0889)
		(layer "In2.Cu")
		(net "P5E_CPU0_PE1_TX_DP<2>")
	)
	(segment
		(start 365.356394 -211.631784)
		(end 363.198156 -184.295796)
		(width 0.14732)
		(layer "In2.Cu")
		(net "P5E_CPU0_PE1_TX_DP<2>")
	)
	(segment
		(start 365.032036 -219.830396)
		(end 365.023146 -219.825316)
		(width 0.0889)
		(layer "In2.Cu")
		(net "P5E_CPU0_PE1_TX_DP<2>")
	)
	(segment
		(start 427.239176 -19.99361)
		(end 427.272196 -19.853148)
		(width 0.14732)
		(layer "In2.Cu")
		(net "P5E_CPU0_PE1_TX_DP<2>")
	)
	(segment
		(start 365.498634 -223.897952)
		(end 365.493046 -223.894904)
		(width 0.0889)
		(layer "In2.Cu")
		(net "P5E_CPU0_PE1_TX_DP<2>")
	)
	(segment
		(start 365.501936 -223.899984)
		(end 365.501174 -223.899476)
		(width 0.0889)
		(layer "In2.Cu")
		(net "P5E_CPU0_PE1_TX_DP<2>")
	)
	(segment
		(start 365.027718 -215.928702)
		(end 365.032036 -215.926162)
		(width 0.0889)
		(layer "In2.Cu")
		(net "P5E_CPU0_PE1_TX_DP<2>")
	)
	(segment
		(start 365.032036 -216.574878)
		(end 365.023146 -216.569798)
		(width 0.0889)
		(layer "In2.Cu")
		(net "P5E_CPU0_PE1_TX_DP<2>")
	)
	(segment
		(start 365.532416 -224.93224)
		(end 365.556546 -224.843086)
		(width 0.0889)
		(layer "In2.Cu")
		(net "P5E_CPU0_PE1_TX_DP<2>")
	)
	(segment
		(start 365.023146 -215.931242)
		(end 365.027718 -215.928702)
		(width 0.0889)
		(layer "In2.Cu")
		(net "P5E_CPU0_PE1_TX_DP<2>")
	)
	(segment
		(start 365.023146 -222.442278)
		(end 365.032036 -222.437198)
		(width 0.0889)
		(layer "In2.Cu")
		(net "P5E_CPU0_PE1_TX_DP<2>")
	)
	(segment
		(start 365.499396 -223.89846)
		(end 365.498634 -223.897952)
		(width 0.0889)
		(layer "In2.Cu")
		(net "P5E_CPU0_PE1_TX_DP<2>")
	)
	(arc
		(start 365.023146 -216.569798)
		(mid 364.84467 -216.25052)
		(end 365.023146 -215.931242)
		(width 0.0889)
		(layer "In2.Cu")
		(net "P5E_CPU0_PE1_TX_DP<2>")
	)
	(arc
		(start 365.31423 -221.94774)
		(mid 365.361909 -221.76484)
		(end 365.492792 -221.628462)
		(width 0.0889)
		(layer "In2.Cu")
		(net "P5E_CPU0_PE1_TX_DP<2>")
	)
	(arc
		(start 365.784384 -217.859864)
		(mid 365.704222 -217.587675)
		(end 365.501936 -217.388694)
		(width 0.0889)
		(layer "In2.Cu")
		(net "P5E_CPU0_PE1_TX_DP<2>")
	)
	(arc
		(start 365.507778 -221.619826)
		(mid 365.710365 -221.413475)
		(end 365.784384 -221.133924)
		(width 0.0889)
		(layer "In2.Cu")
		(net "P5E_CPU0_PE1_TX_DP<2>")
	)
	(arc
		(start 365.032036 -222.437198)
		(mid 365.234859 -222.236967)
		(end 365.31423 -221.963234)
		(width 0.0889)
		(layer "In2.Cu")
		(net "P5E_CPU0_PE1_TX_DP<2>")
	)
	(arc
		(start 365.314484 -223.561402)
		(mid 365.235343 -223.286779)
		(end 365.032036 -223.085914)
		(width 0.0889)
		(layer "In2.Cu")
		(net "P5E_CPU0_PE1_TX_DP<2>")
	)
	(arc
		(start 365.023146 -223.080834)
		(mid 364.895892 -222.950868)
		(end 364.844838 -222.776288)
		(width 0.0889)
		(layer "In2.Cu")
		(net "P5E_CPU0_PE1_TX_DP<2>")
	)
	(arc
		(start 365.023146 -219.825316)
		(mid 364.84467 -219.506038)
		(end 365.023146 -219.18676)
		(width 0.0889)
		(layer "In2.Cu")
		(net "P5E_CPU0_PE1_TX_DP<2>")
	)
	(arc
		(start 365.493046 -223.894904)
		(mid 365.362132 -223.758544)
		(end 365.314484 -223.575626)
		(width 0.0889)
		(layer "In2.Cu")
		(net "P5E_CPU0_PE1_TX_DP<2>")
	)
	(arc
		(start 365.314484 -217.064336)
		(mid 365.240568 -216.784834)
		(end 365.038132 -216.578434)
		(width 0.0889)
		(layer "In2.Cu")
		(net "P5E_CPU0_PE1_TX_DP<2>")
	)
	(arc
		(start 364.844838 -222.776288)
		(mid 364.844641 -222.768923)
		(end 364.844584 -222.761556)
		(width 0.0889)
		(layer "In2.Cu")
		(net "P5E_CPU0_PE1_TX_DP<2>")
	)
	(arc
		(start 365.032036 -219.18168)
		(mid 365.234859 -218.981449)
		(end 365.31423 -218.707716)
		(width 0.0889)
		(layer "In2.Cu")
		(net "P5E_CPU0_PE1_TX_DP<2>")
	)
	(arc
		(start 365.784384 -224.379536)
		(mid 365.706273 -224.102587)
		(end 365.501936 -223.899984)
		(width 0.0889)
		(layer "In2.Cu")
		(net "P5E_CPU0_PE1_TX_DP<2>")
	)
	(arc
		(start 365.784384 -221.115382)
		(mid 365.704222 -220.843193)
		(end 365.501936 -220.644212)
		(width 0.0889)
		(layer "In2.Cu")
		(net "P5E_CPU0_PE1_TX_DP<2>")
	)
	(arc
		(start 365.556546 -224.843086)
		(mid 365.565118 -224.836564)
		(end 365.573564 -224.829878)
		(width 0.0889)
		(layer "In2.Cu")
		(net "P5E_CPU0_PE1_TX_DP<2>")
	)
	(arc
		(start 365.573564 -224.829878)
		(mid 365.728962 -224.633597)
		(end 365.784384 -224.389442)
		(width 0.0889)
		(layer "In2.Cu")
		(net "P5E_CPU0_PE1_TX_DP<2>")
	)
	(arc
		(start 365.493046 -217.383614)
		(mid 365.362132 -217.247254)
		(end 365.314484 -217.064336)
		(width 0.0889)
		(layer "In2.Cu")
		(net "P5E_CPU0_PE1_TX_DP<2>")
	)
	(arc
		(start 365.032036 -215.926162)
		(mid 365.234859 -215.725931)
		(end 365.31423 -215.452198)
		(width 0.0889)
		(layer "In2.Cu")
		(net "P5E_CPU0_PE1_TX_DP<2>")
	)
	(arc
		(start 365.314484 -220.319854)
		(mid 365.240568 -220.040352)
		(end 365.038132 -219.833952)
		(width 0.0889)
		(layer "In2.Cu")
		(net "P5E_CPU0_PE1_TX_DP<2>")
	)
	(arc
		(start 365.507778 -218.364308)
		(mid 365.710365 -218.157957)
		(end 365.784384 -217.878406)
		(width 0.0889)
		(layer "In2.Cu")
		(net "P5E_CPU0_PE1_TX_DP<2>")
	)
	(arc
		(start 364.844584 -222.761556)
		(mid 364.892263 -222.578656)
		(end 365.023146 -222.442278)
		(width 0.0889)
		(layer "In2.Cu")
		(net "P5E_CPU0_PE1_TX_DP<2>")
	)
	(arc
		(start 365.31423 -218.692222)
		(mid 365.361909 -218.509322)
		(end 365.492792 -218.372944)
		(width 0.0889)
		(layer "In2.Cu")
		(net "P5E_CPU0_PE1_TX_DP<2>")
	)
	(arc
		(start 365.493046 -220.639132)
		(mid 365.362132 -220.502772)
		(end 365.314484 -220.319854)
		(width 0.0889)
		(layer "In2.Cu")
		(net "P5E_CPU0_PE1_TX_DP<2>")
	)
	(segment
		(start 366.15878 -224.389696)
		(end 366.159034 -224.389442)
		(width 0.13208)
		(layer "F.Cu")
		(net "P5E_CPU0_PE1_TX_DP<1>")
	)
	(segment
		(start 429.497236 -17.601438)
		(end 429.79848 -17.300194)
		(width 0.13208)
		(layer "F.Cu")
		(net "P5E_CPU0_PE1_TX_DP<1>")
	)
	(segment
		(start 429.79848 -17.300194)
		(end 429.79848 -16.681958)
		(width 0.13208)
		(layer "F.Cu")
		(net "P5E_CPU0_PE1_TX_DP<1>")
	)
	(segment
		(start 429.79848 -16.681958)
		(end 429.471836 -16.355314)
		(width 0.13208)
		(layer "F.Cu")
		(net "P5E_CPU0_PE1_TX_DP<1>")
	)
	(segment
		(start 366.15878 -224.925382)
		(end 366.15878 -224.389696)
		(width 0.13208)
		(layer "F.Cu")
		(net "P5E_CPU0_PE1_TX_DP<1>")
	)
	(segment
		(start 420.31666 -54.318662)
		(end 415.530538 -81.456784)
		(width 0.14732)
		(layer "In2.Cu")
		(net "P5E_CPU0_PE1_TX_DP<1>")
	)
	(segment
		(start 366.06353 -220.311218)
		(end 366.06353 -220.334078)
		(width 0.0889)
		(layer "In2.Cu")
		(net "P5E_CPU0_PE1_TX_DP<1>")
	)
	(segment
		(start 365.884968 -219.0115)
		(end 365.876078 -219.01658)
		(width 0.0889)
		(layer "In2.Cu")
		(net "P5E_CPU0_PE1_TX_DP<1>")
	)
	(segment
		(start 367.835942 -161.940494)
		(end 366.021874 -212.679026)
		(width 0.14732)
		(layer "In2.Cu")
		(net "P5E_CPU0_PE1_TX_DP<1>")
	)
	(segment
		(start 366.343438 -221.459806)
		(end 366.340136 -221.461838)
		(width 0.0889)
		(layer "In2.Cu")
		(net "P5E_CPU0_PE1_TX_DP<1>")
	)
	(segment
		(start 366.021874 -213.26348)
		(end 366.021874 -213.285578)
		(width 0.0889)
		(layer "In2.Cu")
		(net "P5E_CPU0_PE1_TX_DP<1>")
	)
	(segment
		(start 365.593884 -219.490544)
		(end 365.593884 -219.515944)
		(width 0.0889)
		(layer "In2.Cu")
		(net "P5E_CPU0_PE1_TX_DP<1>")
	)
	(segment
		(start 366.346232 -221.458282)
		(end 366.343438 -221.459806)
		(width 0.0889)
		(layer "In2.Cu")
		(net "P5E_CPU0_PE1_TX_DP<1>")
	)
	(segment
		(start 366.347756 -221.45752)
		(end 366.346232 -221.458282)
		(width 0.0889)
		(layer "In2.Cu")
		(net "P5E_CPU0_PE1_TX_DP<1>")
	)
	(segment
		(start 366.063784 -213.327488)
		(end 366.063784 -215.39962)
		(width 0.0889)
		(layer "In2.Cu")
		(net "P5E_CPU0_PE1_TX_DP<1>")
	)
	(segment
		(start 366.021874 -212.679026)
		(end 366.021874 -213.26348)
		(width 0.14732)
		(layer "In2.Cu")
		(net "P5E_CPU0_PE1_TX_DP<1>")
	)
	(segment
		(start 424.34129 -27.50058)
		(end 420.31666 -54.318662)
		(width 0.14732)
		(layer "In2.Cu")
		(net "P5E_CPU0_PE1_TX_DP<1>")
	)
	(segment
		(start 429.791876 -18.450052)
		(end 424.34129 -27.50058)
		(width 0.14732)
		(layer "In2.Cu")
		(net "P5E_CPU0_PE1_TX_DP<1>")
	)
	(segment
		(start 365.593884 -222.746062)
		(end 365.593884 -222.780098)
		(width 0.0889)
		(layer "In2.Cu")
		(net "P5E_CPU0_PE1_TX_DP<1>")
	)
	(segment
		(start 366.291368 -224.02927)
		(end 366.315498 -224.118424)
		(width 0.0889)
		(layer "In2.Cu")
		(net "P5E_CPU0_PE1_TX_DP<1>")
	)
	(segment
		(start 366.000284 -215.552528)
		(end 365.755682 -215.79713)
		(width 0.0889)
		(layer "In2.Cu")
		(net "P5E_CPU0_PE1_TX_DP<1>")
	)
	(segment
		(start 415.530538 -81.456784)
		(end 367.835942 -161.940494)
		(width 0.14732)
		(layer "In2.Cu")
		(net "P5E_CPU0_PE1_TX_DP<1>")
	)
	(segment
		(start 429.497236 -17.601438)
		(end 429.791876 -17.896078)
		(width 0.14732)
		(layer "In2.Cu")
		(net "P5E_CPU0_PE1_TX_DP<1>")
	)
	(segment
		(start 366.355122 -221.453202)
		(end 366.347756 -221.45752)
		(width 0.0889)
		(layer "In2.Cu")
		(net "P5E_CPU0_PE1_TX_DP<1>")
	)
	(segment
		(start 366.355122 -218.197684)
		(end 366.346232 -218.202764)
		(width 0.0889)
		(layer "In2.Cu")
		(net "P5E_CPU0_PE1_TX_DP<1>")
	)
	(segment
		(start 365.593884 -216.188036)
		(end 365.593884 -216.260426)
		(width 0.0889)
		(layer "In2.Cu")
		(net "P5E_CPU0_PE1_TX_DP<1>")
	)
	(segment
		(start 366.315498 -224.118424)
		(end 366.159034 -224.389442)
		(width 0.0889)
		(layer "In2.Cu")
		(net "P5E_CPU0_PE1_TX_DP<1>")
	)
	(segment
		(start 365.884968 -222.267018)
		(end 365.876078 -222.272098)
		(width 0.0889)
		(layer "In2.Cu")
		(net "P5E_CPU0_PE1_TX_DP<1>")
	)
	(segment
		(start 366.346232 -218.202764)
		(end 366.340136 -218.20632)
		(width 0.0889)
		(layer "In2.Cu")
		(net "P5E_CPU0_PE1_TX_DP<1>")
	)
	(segment
		(start 366.06353 -217.0557)
		(end 366.06353 -217.07856)
		(width 0.0889)
		(layer "In2.Cu")
		(net "P5E_CPU0_PE1_TX_DP<1>")
	)
	(segment
		(start 366.346232 -220.809566)
		(end 366.355122 -220.814646)
		(width 0.0889)
		(layer "In2.Cu")
		(net "P5E_CPU0_PE1_TX_DP<1>")
	)
	(segment
		(start 429.791876 -17.896078)
		(end 429.791876 -18.450052)
		(width 0.14732)
		(layer "In2.Cu")
		(net "P5E_CPU0_PE1_TX_DP<1>")
	)
	(segment
		(start 366.06353 -223.56699)
		(end 366.06353 -223.575626)
		(width 0.0889)
		(layer "In2.Cu")
		(net "P5E_CPU0_PE1_TX_DP<1>")
	)
	(segment
		(start 366.346232 -217.554048)
		(end 366.355122 -217.559128)
		(width 0.0889)
		(layer "In2.Cu")
		(net "P5E_CPU0_PE1_TX_DP<1>")
	)
	(segment
		(start 366.021874 -213.285578)
		(end 366.063784 -213.327488)
		(width 0.0889)
		(layer "In2.Cu")
		(net "P5E_CPU0_PE1_TX_DP<1>")
	)
	(arc
		(start 365.755682 -215.79713)
		(mid 365.635928 -215.976494)
		(end 365.593884 -216.188036)
		(width 0.0889)
		(layer "In2.Cu")
		(net "P5E_CPU0_PE1_TX_DP<1>")
	)
	(arc
		(start 365.876332 -219.995496)
		(mid 366.011265 -220.12885)
		(end 366.06353 -220.311218)
		(width 0.0889)
		(layer "In2.Cu")
		(net "P5E_CPU0_PE1_TX_DP<1>")
	)
	(arc
		(start 366.340136 -221.461838)
		(mid 366.137549 -221.668189)
		(end 366.06353 -221.94774)
		(width 0.0889)
		(layer "In2.Cu")
		(net "P5E_CPU0_PE1_TX_DP<1>")
	)
	(arc
		(start 366.06353 -220.334078)
		(mid 366.142749 -220.608763)
		(end 366.346232 -220.809566)
		(width 0.0889)
		(layer "In2.Cu")
		(net "P5E_CPU0_PE1_TX_DP<1>")
	)
	(arc
		(start 365.876078 -222.272098)
		(mid 365.673255 -222.472329)
		(end 365.593884 -222.746062)
		(width 0.0889)
		(layer "In2.Cu")
		(net "P5E_CPU0_PE1_TX_DP<1>")
	)
	(arc
		(start 366.340136 -218.20632)
		(mid 366.137549 -218.412671)
		(end 366.06353 -218.692222)
		(width 0.0889)
		(layer "In2.Cu")
		(net "P5E_CPU0_PE1_TX_DP<1>")
	)
	(arc
		(start 366.06353 -217.07856)
		(mid 366.142749 -217.353245)
		(end 366.346232 -217.554048)
		(width 0.0889)
		(layer "In2.Cu")
		(net "P5E_CPU0_PE1_TX_DP<1>")
	)
	(arc
		(start 366.063784 -215.39962)
		(mid 366.047213 -215.482368)
		(end 366.000284 -215.552528)
		(width 0.0889)
		(layer "In2.Cu")
		(net "P5E_CPU0_PE1_TX_DP<1>")
	)
	(arc
		(start 366.06353 -221.94774)
		(mid 366.015851 -222.13064)
		(end 365.884968 -222.267018)
		(width 0.0889)
		(layer "In2.Cu")
		(net "P5E_CPU0_PE1_TX_DP<1>")
	)
	(arc
		(start 365.863632 -216.732104)
		(mid 365.869956 -216.736083)
		(end 365.876332 -216.739978)
		(width 0.0889)
		(layer "In2.Cu")
		(net "P5E_CPU0_PE1_TX_DP<1>")
	)
	(arc
		(start 366.06353 -223.575626)
		(mid 366.123573 -223.829513)
		(end 366.291368 -224.02927)
		(width 0.0889)
		(layer "In2.Cu")
		(net "P5E_CPU0_PE1_TX_DP<1>")
	)
	(arc
		(start 365.593884 -222.780098)
		(mid 365.674046 -223.052287)
		(end 365.876332 -223.251268)
		(width 0.0889)
		(layer "In2.Cu")
		(net "P5E_CPU0_PE1_TX_DP<1>")
	)
	(arc
		(start 365.876078 -219.01658)
		(mid 365.673255 -219.216811)
		(end 365.593884 -219.490544)
		(width 0.0889)
		(layer "In2.Cu")
		(net "P5E_CPU0_PE1_TX_DP<1>")
	)
	(arc
		(start 365.593884 -219.515944)
		(mid 365.671995 -219.792893)
		(end 365.876332 -219.995496)
		(width 0.0889)
		(layer "In2.Cu")
		(net "P5E_CPU0_PE1_TX_DP<1>")
	)
	(arc
		(start 365.876332 -223.251268)
		(mid 366.011265 -223.384622)
		(end 366.06353 -223.56699)
		(width 0.0889)
		(layer "In2.Cu")
		(net "P5E_CPU0_PE1_TX_DP<1>")
	)
	(arc
		(start 366.06353 -218.692222)
		(mid 366.015851 -218.875122)
		(end 365.884968 -219.0115)
		(width 0.0889)
		(layer "In2.Cu")
		(net "P5E_CPU0_PE1_TX_DP<1>")
	)
	(arc
		(start 366.355122 -217.559128)
		(mid 366.533719 -217.878406)
		(end 366.355122 -218.197684)
		(width 0.0889)
		(layer "In2.Cu")
		(net "P5E_CPU0_PE1_TX_DP<1>")
	)
	(arc
		(start 366.355122 -220.814646)
		(mid 366.533719 -221.133924)
		(end 366.355122 -221.453202)
		(width 0.0889)
		(layer "In2.Cu")
		(net "P5E_CPU0_PE1_TX_DP<1>")
	)
	(arc
		(start 365.876332 -216.739978)
		(mid 366.011265 -216.873332)
		(end 366.06353 -217.0557)
		(width 0.0889)
		(layer "In2.Cu")
		(net "P5E_CPU0_PE1_TX_DP<1>")
	)
	(arc
		(start 365.593884 -216.260426)
		(mid 365.668338 -216.530828)
		(end 365.863632 -216.732104)
		(width 0.0889)
		(layer "In2.Cu")
		(net "P5E_CPU0_PE1_TX_DP<1>")
	)
	(segment
		(start 390.342628 -16.681958)
		(end 390.015984 -16.355314)
		(width 0.13208)
		(layer "F.Cu")
		(net "P5E_CPU0_PE1_TX_DP<15>")
	)
	(segment
		(start 390.041384 -17.601438)
		(end 390.342628 -17.300194)
		(width 0.13208)
		(layer "F.Cu")
		(net "P5E_CPU0_PE1_TX_DP<15>")
	)
	(segment
		(start 390.342628 -17.300194)
		(end 390.342628 -16.681958)
		(width 0.13208)
		(layer "F.Cu")
		(net "P5E_CPU0_PE1_TX_DP<15>")
	)
	(segment
		(start 353.00158 -224.925382)
		(end 353.00158 -224.389696)
		(width 0.13208)
		(layer "F.Cu")
		(net "P5E_CPU0_PE1_TX_DP<15>")
	)
	(segment
		(start 353.00158 -224.389696)
		(end 353.001834 -224.389442)
		(width 0.13208)
		(layer "F.Cu")
		(net "P5E_CPU0_PE1_TX_DP<15>")
	)
	(segment
		(start 351.966784 -213.288372)
		(end 351.966784 -213.938358)
		(width 0.0889)
		(layer "In2.Cu")
		(net "P5E_CPU0_PE1_TX_DP<15>")
	)
	(segment
		(start 353.18954 -221.458282)
		(end 353.178872 -221.464632)
		(width 0.0889)
		(layer "In2.Cu")
		(net "P5E_CPU0_PE1_TX_DP<15>")
	)
	(segment
		(start 353.158298 -224.118424)
		(end 353.001834 -224.389442)
		(width 0.0889)
		(layer "In2.Cu")
		(net "P5E_CPU0_PE1_TX_DP<15>")
	)
	(segment
		(start 352.72218 -219.015056)
		(end 352.721418 -219.015564)
		(width 0.0889)
		(layer "In2.Cu")
		(net "P5E_CPU0_PE1_TX_DP<15>")
	)
	(segment
		(start 352.708464 -218.36126)
		(end 352.729546 -218.373706)
		(width 0.0889)
		(layer "In2.Cu")
		(net "P5E_CPU0_PE1_TX_DP<15>")
	)
	(segment
		(start 390.336024 -21.531072)
		(end 401.548092 -76.657454)
		(width 0.14732)
		(layer "In2.Cu")
		(net "P5E_CPU0_PE1_TX_DP<15>")
	)
	(segment
		(start 352.721418 -219.015564)
		(end 352.706686 -219.0242)
		(width 0.0889)
		(layer "In2.Cu")
		(net "P5E_CPU0_PE1_TX_DP<15>")
	)
	(segment
		(start 350.97847 -207.214724)
		(end 351.925128 -212.39226)
		(width 0.14732)
		(layer "In2.Cu")
		(net "P5E_CPU0_PE1_TX_DP<15>")
	)
	(segment
		(start 390.041384 -17.601438)
		(end 390.336024 -17.896078)
		(width 0.14732)
		(layer "In2.Cu")
		(net "P5E_CPU0_PE1_TX_DP<15>")
	)
	(segment
		(start 339.42274 -176.668176)
		(end 350.977708 -207.212438)
		(width 0.14732)
		(layer "In2.Cu")
		(net "P5E_CPU0_PE1_TX_DP<15>")
	)
	(segment
		(start 352.7298 -219.010738)
		(end 352.728022 -219.011754)
		(width 0.0889)
		(layer "In2.Cu")
		(net "P5E_CPU0_PE1_TX_DP<15>")
	)
	(segment
		(start 401.548092 -76.657454)
		(end 400.938238 -79.58836)
		(width 0.14732)
		(layer "In2.Cu")
		(net "P5E_CPU0_PE1_TX_DP<15>")
	)
	(segment
		(start 352.71964 -222.272098)
		(end 352.708972 -222.278448)
		(width 0.0889)
		(layer "In2.Cu")
		(net "P5E_CPU0_PE1_TX_DP<15>")
	)
	(segment
		(start 352.708972 -223.244664)
		(end 352.71964 -223.251014)
		(width 0.0889)
		(layer "In2.Cu")
		(net "P5E_CPU0_PE1_TX_DP<15>")
	)
	(segment
		(start 338.695538 -172.539406)
		(end 339.42274 -176.668176)
		(width 0.14732)
		(layer "In2.Cu")
		(net "P5E_CPU0_PE1_TX_DP<15>")
	)
	(segment
		(start 352.248216 -215.9254)
		(end 352.249232 -215.925908)
		(width 0.0889)
		(layer "In2.Cu")
		(net "P5E_CPU0_PE1_TX_DP<15>")
	)
	(segment
		(start 390.336024 -17.896078)
		(end 390.336024 -21.531072)
		(width 0.14732)
		(layer "In2.Cu")
		(net "P5E_CPU0_PE1_TX_DP<15>")
	)
	(segment
		(start 352.43643 -214.460328)
		(end 352.43643 -214.640414)
		(width 0.0889)
		(layer "In2.Cu")
		(net "P5E_CPU0_PE1_TX_DP<15>")
	)
	(segment
		(start 352.725228 -219.013278)
		(end 352.723196 -219.014548)
		(width 0.0889)
		(layer "In2.Cu")
		(net "P5E_CPU0_PE1_TX_DP<15>")
	)
	(segment
		(start 352.906838 -221.94774)
		(end 352.906838 -221.955614)
		(width 0.0889)
		(layer "In2.Cu")
		(net "P5E_CPU0_PE1_TX_DP<15>")
	)
	(segment
		(start 352.708972 -219.989146)
		(end 352.71964 -219.995496)
		(width 0.0889)
		(layer "In2.Cu")
		(net "P5E_CPU0_PE1_TX_DP<15>")
	)
	(segment
		(start 352.708972 -216.733628)
		(end 352.71964 -216.739978)
		(width 0.0889)
		(layer "In2.Cu")
		(net "P5E_CPU0_PE1_TX_DP<15>")
	)
	(segment
		(start 352.24466 -215.923114)
		(end 352.245422 -215.923622)
		(width 0.0889)
		(layer "In2.Cu")
		(net "P5E_CPU0_PE1_TX_DP<15>")
	)
	(segment
		(start 351.966784 -213.938358)
		(end 351.984818 -213.97468)
		(width 0.0889)
		(layer "In2.Cu")
		(net "P5E_CPU0_PE1_TX_DP<15>")
	)
	(segment
		(start 340.01202 -166.602664)
		(end 338.695538 -172.539406)
		(width 0.14732)
		(layer "In2.Cu")
		(net "P5E_CPU0_PE1_TX_DP<15>")
	)
	(segment
		(start 351.925128 -213.246716)
		(end 351.966784 -213.288372)
		(width 0.0889)
		(layer "In2.Cu")
		(net "P5E_CPU0_PE1_TX_DP<15>")
	)
	(segment
		(start 352.906838 -220.31198)
		(end 352.906838 -220.330522)
		(width 0.0889)
		(layer "In2.Cu")
		(net "P5E_CPU0_PE1_TX_DP<15>")
	)
	(segment
		(start 351.925128 -213.224618)
		(end 351.925128 -213.246716)
		(width 0.0889)
		(layer "In2.Cu")
		(net "P5E_CPU0_PE1_TX_DP<15>")
	)
	(segment
		(start 351.925128 -212.39226)
		(end 351.925128 -213.224618)
		(width 0.14732)
		(layer "In2.Cu")
		(net "P5E_CPU0_PE1_TX_DP<15>")
	)
	(segment
		(start 352.728022 -219.011754)
		(end 352.725228 -219.013278)
		(width 0.0889)
		(layer "In2.Cu")
		(net "P5E_CPU0_PE1_TX_DP<15>")
	)
	(segment
		(start 352.245422 -215.923622)
		(end 352.248216 -215.9254)
		(width 0.0889)
		(layer "In2.Cu")
		(net "P5E_CPU0_PE1_TX_DP<15>")
	)
	(segment
		(start 400.938238 -79.58836)
		(end 340.01202 -166.602664)
		(width 0.14732)
		(layer "In2.Cu")
		(net "P5E_CPU0_PE1_TX_DP<15>")
	)
	(segment
		(start 352.247708 -214.948516)
		(end 352.200464 -214.976964)
		(width 0.0889)
		(layer "In2.Cu")
		(net "P5E_CPU0_PE1_TX_DP<15>")
	)
	(segment
		(start 352.436938 -216.25052)
		(end 352.436938 -216.258648)
		(width 0.0889)
		(layer "In2.Cu")
		(net "P5E_CPU0_PE1_TX_DP<15>")
	)
	(segment
		(start 352.249232 -214.9475)
		(end 352.247708 -214.948516)
		(width 0.0889)
		(layer "In2.Cu")
		(net "P5E_CPU0_PE1_TX_DP<15>")
	)
	(segment
		(start 352.71964 -217.388948)
		(end 352.708972 -217.395298)
		(width 0.0889)
		(layer "In2.Cu")
		(net "P5E_CPU0_PE1_TX_DP<15>")
	)
	(segment
		(start 352.723196 -219.014548)
		(end 352.72218 -219.015056)
		(width 0.0889)
		(layer "In2.Cu")
		(net "P5E_CPU0_PE1_TX_DP<15>")
	)
	(segment
		(start 351.968816 -215.372188)
		(end 351.967038 -215.414352)
		(width 0.0889)
		(layer "In2.Cu")
		(net "P5E_CPU0_PE1_TX_DP<15>")
	)
	(segment
		(start 353.134422 -224.029524)
		(end 353.134168 -224.02927)
		(width 0.0889)
		(layer "In2.Cu")
		(net "P5E_CPU0_PE1_TX_DP<15>")
	)
	(segment
		(start 352.23577 -215.918034)
		(end 352.24466 -215.923114)
		(width 0.0889)
		(layer "In2.Cu")
		(net "P5E_CPU0_PE1_TX_DP<15>")
	)
	(segment
		(start 352.906838 -223.56064)
		(end 352.906838 -223.586294)
		(width 0.0889)
		(layer "In2.Cu")
		(net "P5E_CPU0_PE1_TX_DP<15>")
	)
	(segment
		(start 352.706686 -219.0242)
		(end 352.706432 -219.024454)
		(width 0.0889)
		(layer "In2.Cu")
		(net "P5E_CPU0_PE1_TX_DP<15>")
	)
	(segment
		(start 352.249232 -215.925908)
		(end 352.253804 -215.928702)
		(width 0.0889)
		(layer "In2.Cu")
		(net "P5E_CPU0_PE1_TX_DP<15>")
	)
	(segment
		(start 350.977708 -207.212438)
		(end 350.97847 -207.214724)
		(width 0.14732)
		(layer "In2.Cu")
		(net "P5E_CPU0_PE1_TX_DP<15>")
	)
	(segment
		(start 353.134168 -224.02927)
		(end 353.158298 -224.118424)
		(width 0.0889)
		(layer "In2.Cu")
		(net "P5E_CPU0_PE1_TX_DP<15>")
	)
	(arc
		(start 352.437192 -217.859864)
		(mid 352.436885 -217.874086)
		(end 352.436938 -217.888312)
		(width 0.0889)
		(layer "In2.Cu")
		(net "P5E_CPU0_PE1_TX_DP<15>")
	)
	(arc
		(start 352.436938 -217.888312)
		(mid 352.511863 -218.159713)
		(end 352.708464 -218.36126)
		(width 0.0889)
		(layer "In2.Cu")
		(net "P5E_CPU0_PE1_TX_DP<15>")
	)
	(arc
		(start 353.376484 -221.140528)
		(mid 353.324795 -221.323999)
		(end 353.18954 -221.458282)
		(width 0.0889)
		(layer "In2.Cu")
		(net "P5E_CPU0_PE1_TX_DP<15>")
	)
	(arc
		(start 352.200464 -214.976964)
		(mid 352.035107 -215.14555)
		(end 351.968816 -215.372188)
		(width 0.0889)
		(layer "In2.Cu")
		(net "P5E_CPU0_PE1_TX_DP<15>")
	)
	(arc
		(start 353.11715 -224.016062)
		(mid 353.125722 -224.022875)
		(end 353.134422 -224.029524)
		(width 0.0889)
		(layer "In2.Cu")
		(net "P5E_CPU0_PE1_TX_DP<15>")
	)
	(arc
		(start 352.436938 -216.258648)
		(mid 352.511586 -216.531287)
		(end 352.708972 -216.733628)
		(width 0.0889)
		(layer "In2.Cu")
		(net "P5E_CPU0_PE1_TX_DP<15>")
	)
	(arc
		(start 353.189032 -220.809058)
		(mid 353.323994 -220.942283)
		(end 353.376484 -221.124526)
		(width 0.0889)
		(layer "In2.Cu")
		(net "P5E_CPU0_PE1_TX_DP<15>")
	)
	(arc
		(start 352.43643 -214.640414)
		(mid 352.381974 -214.817807)
		(end 352.249232 -214.9475)
		(width 0.0889)
		(layer "In2.Cu")
		(net "P5E_CPU0_PE1_TX_DP<15>")
	)
	(arc
		(start 352.906838 -217.057732)
		(mid 352.906828 -217.067132)
		(end 352.906584 -217.076528)
		(width 0.0889)
		(layer "In2.Cu")
		(net "P5E_CPU0_PE1_TX_DP<15>")
	)
	(arc
		(start 352.71964 -219.995496)
		(mid 352.854685 -220.12922)
		(end 352.906838 -220.31198)
		(width 0.0889)
		(layer "In2.Cu")
		(net "P5E_CPU0_PE1_TX_DP<15>")
	)
	(arc
		(start 352.708972 -217.395298)
		(mid 352.514204 -217.593136)
		(end 352.437192 -217.859864)
		(width 0.0889)
		(layer "In2.Cu")
		(net "P5E_CPU0_PE1_TX_DP<15>")
	)
	(arc
		(start 352.906838 -223.586294)
		(mid 352.964276 -223.824523)
		(end 353.11715 -224.016062)
		(width 0.0889)
		(layer "In2.Cu")
		(net "P5E_CPU0_PE1_TX_DP<15>")
	)
	(arc
		(start 352.906584 -217.076528)
		(mid 352.853558 -217.25694)
		(end 352.71964 -217.388948)
		(width 0.0889)
		(layer "In2.Cu")
		(net "P5E_CPU0_PE1_TX_DP<15>")
	)
	(arc
		(start 352.906838 -220.330522)
		(mid 352.984993 -220.606918)
		(end 353.189032 -220.809058)
		(width 0.0889)
		(layer "In2.Cu")
		(net "P5E_CPU0_PE1_TX_DP<15>")
	)
	(arc
		(start 351.967038 -215.414352)
		(mid 351.9668 -215.425654)
		(end 351.966784 -215.436958)
		(width 0.0889)
		(layer "In2.Cu")
		(net "P5E_CPU0_PE1_TX_DP<15>")
	)
	(arc
		(start 352.906838 -221.955614)
		(mid 352.8547 -222.138382)
		(end 352.71964 -222.272098)
		(width 0.0889)
		(layer "In2.Cu")
		(net "P5E_CPU0_PE1_TX_DP<15>")
	)
	(arc
		(start 352.436938 -222.75165)
		(mid 352.436892 -222.765749)
		(end 352.437192 -222.779844)
		(width 0.0889)
		(layer "In2.Cu")
		(net "P5E_CPU0_PE1_TX_DP<15>")
	)
	(arc
		(start 351.984818 -213.97468)
		(mid 352.094365 -214.14072)
		(end 352.25228 -214.2617)
		(width 0.0889)
		(layer "In2.Cu")
		(net "P5E_CPU0_PE1_TX_DP<15>")
	)
	(arc
		(start 351.966784 -215.436958)
		(mid 352.038675 -215.712481)
		(end 352.23577 -215.918034)
		(width 0.0889)
		(layer "In2.Cu")
		(net "P5E_CPU0_PE1_TX_DP<15>")
	)
	(arc
		(start 352.71964 -223.251014)
		(mid 352.853017 -223.381774)
		(end 352.906838 -223.56064)
		(width 0.0889)
		(layer "In2.Cu")
		(net "P5E_CPU0_PE1_TX_DP<15>")
	)
	(arc
		(start 352.25228 -214.2617)
		(mid 352.361281 -214.345316)
		(end 352.43643 -214.460328)
		(width 0.0889)
		(layer "In2.Cu")
		(net "P5E_CPU0_PE1_TX_DP<15>")
	)
	(arc
		(start 352.729546 -218.373706)
		(mid 352.906771 -218.692114)
		(end 352.7298 -219.010738)
		(width 0.0889)
		(layer "In2.Cu")
		(net "P5E_CPU0_PE1_TX_DP<15>")
	)
	(arc
		(start 352.706432 -219.024454)
		(mid 352.436871 -219.507519)
		(end 352.708972 -219.989146)
		(width 0.0889)
		(layer "In2.Cu")
		(net "P5E_CPU0_PE1_TX_DP<15>")
	)
	(arc
		(start 352.71964 -216.739978)
		(mid 352.855008 -216.874249)
		(end 352.906838 -217.057732)
		(width 0.0889)
		(layer "In2.Cu")
		(net "P5E_CPU0_PE1_TX_DP<15>")
	)
	(arc
		(start 352.708972 -222.278448)
		(mid 352.512037 -222.480023)
		(end 352.436938 -222.75165)
		(width 0.0889)
		(layer "In2.Cu")
		(net "P5E_CPU0_PE1_TX_DP<15>")
	)
	(arc
		(start 353.178872 -221.464632)
		(mid 352.979488 -221.670512)
		(end 352.906838 -221.94774)
		(width 0.0889)
		(layer "In2.Cu")
		(net "P5E_CPU0_PE1_TX_DP<15>")
	)
	(arc
		(start 352.437192 -222.779844)
		(mid 352.514145 -223.046713)
		(end 352.708972 -223.244664)
		(width 0.0889)
		(layer "In2.Cu")
		(net "P5E_CPU0_PE1_TX_DP<15>")
	)
	(arc
		(start 353.376484 -221.124526)
		(mid 353.376572 -221.132527)
		(end 353.376484 -221.140528)
		(width 0.0889)
		(layer "In2.Cu")
		(net "P5E_CPU0_PE1_TX_DP<15>")
	)
	(arc
		(start 352.253804 -215.928702)
		(mid 352.387934 -216.0654)
		(end 352.436938 -216.25052)
		(width 0.0889)
		(layer "In2.Cu")
		(net "P5E_CPU0_PE1_TX_DP<15>")
	)
	(segment
		(start 393.395708 -18.20799)
		(end 393.724384 -17.879314)
		(width 0.13208)
		(layer "F.Cu")
		(net "P5E_CPU0_PE1_TX_DP<14>")
	)
	(segment
		(start 354.41128 -225.738944)
		(end 354.41128 -225.203258)
		(width 0.13208)
		(layer "F.Cu")
		(net "P5E_CPU0_PE1_TX_DP<14>")
	)
	(segment
		(start 393.698984 -19.125438)
		(end 393.395708 -18.822162)
		(width 0.13208)
		(layer "F.Cu")
		(net "P5E_CPU0_PE1_TX_DP<14>")
	)
	(segment
		(start 354.411534 -225.739198)
		(end 354.41128 -225.738944)
		(width 0.13208)
		(layer "F.Cu")
		(net "P5E_CPU0_PE1_TX_DP<14>")
	)
	(segment
		(start 393.395708 -18.822162)
		(end 393.395708 -18.20799)
		(width 0.13208)
		(layer "F.Cu")
		(net "P5E_CPU0_PE1_TX_DP<14>")
	)
	(segment
		(start 353.745546 -223.080834)
		(end 353.754436 -223.085914)
		(width 0.0889)
		(layer "In2.Cu")
		(net "P5E_CPU0_PE1_TX_DP<14>")
	)
	(segment
		(start 353.566476 -214.579962)
		(end 353.566476 -214.644732)
		(width 0.0889)
		(layer "In2.Cu")
		(net "P5E_CPU0_PE1_TX_DP<14>")
	)
	(segment
		(start 354.221796 -223.89846)
		(end 354.223574 -223.899476)
		(width 0.0889)
		(layer "In2.Cu")
		(net "P5E_CPU0_PE1_TX_DP<14>")
	)
	(segment
		(start 402.835618 -76.550266)
		(end 402.194776 -79.91221)
		(width 0.14732)
		(layer "In2.Cu")
		(net "P5E_CPU0_PE1_TX_DP<14>")
	)
	(segment
		(start 354.224082 -221.623382)
		(end 354.222558 -221.624398)
		(width 0.0889)
		(layer "In2.Cu")
		(net "P5E_CPU0_PE1_TX_DP<14>")
	)
	(segment
		(start 393.404344 -20.019264)
		(end 393.411202 -20.083018)
		(width 0.14732)
		(layer "In2.Cu")
		(net "P5E_CPU0_PE1_TX_DP<14>")
	)
	(segment
		(start 353.745546 -219.825316)
		(end 353.754436 -219.830396)
		(width 0.0889)
		(layer "In2.Cu")
		(net "P5E_CPU0_PE1_TX_DP<14>")
	)
	(segment
		(start 353.537266 -214.396574)
		(end 353.557078 -214.489538)
		(width 0.0889)
		(layer "In2.Cu")
		(net "P5E_CPU0_PE1_TX_DP<14>")
	)
	(segment
		(start 353.275392 -215.755982)
		(end 353.284028 -215.761062)
		(width 0.0889)
		(layer "In2.Cu")
		(net "P5E_CPU0_PE1_TX_DP<14>")
	)
	(segment
		(start 353.284282 -215.112346)
		(end 353.283266 -215.112854)
		(width 0.0889)
		(layer "In2.Cu")
		(net "P5E_CPU0_PE1_TX_DP<14>")
	)
	(segment
		(start 341.149178 -167.096186)
		(end 339.934804 -172.573696)
		(width 0.14732)
		(layer "In2.Cu")
		(net "P5E_CPU0_PE1_TX_DP<14>")
	)
	(segment
		(start 353.139248 -211.98459)
		(end 353.139248 -213.220554)
		(width 0.14732)
		(layer "In2.Cu")
		(net "P5E_CPU0_PE1_TX_DP<14>")
	)
	(segment
		(start 354.506784 -224.379536)
		(end 354.506784 -224.389442)
		(width 0.0889)
		(layer "In2.Cu")
		(net "P5E_CPU0_PE1_TX_DP<14>")
	)
	(segment
		(start 354.215446 -223.894904)
		(end 354.221034 -223.897952)
		(width 0.0889)
		(layer "In2.Cu")
		(net "P5E_CPU0_PE1_TX_DP<14>")
	)
	(segment
		(start 353.139248 -213.242652)
		(end 353.097084 -213.284816)
		(width 0.0889)
		(layer "In2.Cu")
		(net "P5E_CPU0_PE1_TX_DP<14>")
	)
	(segment
		(start 353.754436 -219.830396)
		(end 353.760532 -219.833952)
		(width 0.0889)
		(layer "In2.Cu")
		(net "P5E_CPU0_PE1_TX_DP<14>")
	)
	(segment
		(start 352.25863 -207.165194)
		(end 353.139248 -211.98459)
		(width 0.14732)
		(layer "In2.Cu")
		(net "P5E_CPU0_PE1_TX_DP<14>")
	)
	(segment
		(start 354.227638 -221.62135)
		(end 354.226114 -221.622112)
		(width 0.0889)
		(layer "In2.Cu")
		(net "P5E_CPU0_PE1_TX_DP<14>")
	)
	(segment
		(start 353.284028 -215.761062)
		(end 353.288092 -215.763602)
		(width 0.0889)
		(layer "In2.Cu")
		(net "P5E_CPU0_PE1_TX_DP<14>")
	)
	(segment
		(start 354.254816 -224.93224)
		(end 354.41128 -225.203258)
		(width 0.0889)
		(layer "In2.Cu")
		(net "P5E_CPU0_PE1_TX_DP<14>")
	)
	(segment
		(start 398.972532 -45.592492)
		(end 402.835618 -76.550266)
		(width 0.14732)
		(layer "In2.Cu")
		(net "P5E_CPU0_PE1_TX_DP<14>")
	)
	(segment
		(start 354.226114 -221.622112)
		(end 354.224082 -221.623382)
		(width 0.0889)
		(layer "In2.Cu")
		(net "P5E_CPU0_PE1_TX_DP<14>")
	)
	(segment
		(start 354.222558 -221.624398)
		(end 354.221542 -221.624906)
		(width 0.0889)
		(layer "In2.Cu")
		(net "P5E_CPU0_PE1_TX_DP<14>")
	)
	(segment
		(start 353.284282 -215.761062)
		(end 353.287076 -215.762586)
		(width 0.0889)
		(layer "In2.Cu")
		(net "P5E_CPU0_PE1_TX_DP<14>")
	)
	(segment
		(start 353.287076 -215.762586)
		(end 353.290378 -215.764618)
		(width 0.0889)
		(layer "In2.Cu")
		(net "P5E_CPU0_PE1_TX_DP<14>")
	)
	(segment
		(start 353.754436 -219.18168)
		(end 353.745546 -219.18676)
		(width 0.0889)
		(layer "In2.Cu")
		(net "P5E_CPU0_PE1_TX_DP<14>")
	)
	(segment
		(start 353.745546 -216.569798)
		(end 353.754436 -216.574878)
		(width 0.0889)
		(layer "In2.Cu")
		(net "P5E_CPU0_PE1_TX_DP<14>")
	)
	(segment
		(start 354.03663 -221.94774)
		(end 354.03663 -221.963234)
		(width 0.0889)
		(layer "In2.Cu")
		(net "P5E_CPU0_PE1_TX_DP<14>")
	)
	(segment
		(start 353.754436 -217.554048)
		(end 353.745546 -217.559128)
		(width 0.0889)
		(layer "In2.Cu")
		(net "P5E_CPU0_PE1_TX_DP<14>")
	)
	(segment
		(start 402.194776 -79.91221)
		(end 341.149178 -167.096186)
		(width 0.14732)
		(layer "In2.Cu")
		(net "P5E_CPU0_PE1_TX_DP<14>")
	)
	(segment
		(start 354.036884 -217.064336)
		(end 354.036884 -217.07856)
		(width 0.0889)
		(layer "In2.Cu")
		(net "P5E_CPU0_PE1_TX_DP<14>")
	)
	(segment
		(start 353.745546 -218.197684)
		(end 353.754436 -218.202764)
		(width 0.0889)
		(layer "In2.Cu")
		(net "P5E_CPU0_PE1_TX_DP<14>")
	)
	(segment
		(start 354.221542 -221.624906)
		(end 354.215192 -221.628462)
		(width 0.0889)
		(layer "In2.Cu")
		(net "P5E_CPU0_PE1_TX_DP<14>")
	)
	(segment
		(start 354.223574 -223.899476)
		(end 354.224336 -223.899984)
		(width 0.0889)
		(layer "In2.Cu")
		(net "P5E_CPU0_PE1_TX_DP<14>")
	)
	(segment
		(start 393.404344 -19.420078)
		(end 393.404344 -20.019264)
		(width 0.14732)
		(layer "In2.Cu")
		(net "P5E_CPU0_PE1_TX_DP<14>")
	)
	(segment
		(start 353.754436 -222.437198)
		(end 353.745546 -222.442278)
		(width 0.0889)
		(layer "In2.Cu")
		(net "P5E_CPU0_PE1_TX_DP<14>")
	)
	(segment
		(start 354.230178 -221.619826)
		(end 354.227638 -221.62135)
		(width 0.0889)
		(layer "In2.Cu")
		(net "P5E_CPU0_PE1_TX_DP<14>")
	)
	(segment
		(start 353.139248 -213.220554)
		(end 353.139248 -213.242652)
		(width 0.0889)
		(layer "In2.Cu")
		(net "P5E_CPU0_PE1_TX_DP<14>")
	)
	(segment
		(start 354.036884 -223.561402)
		(end 354.036884 -223.575626)
		(width 0.0889)
		(layer "In2.Cu")
		(net "P5E_CPU0_PE1_TX_DP<14>")
	)
	(segment
		(start 339.934804 -172.573696)
		(end 340.59114 -176.298352)
		(width 0.14732)
		(layer "In2.Cu")
		(net "P5E_CPU0_PE1_TX_DP<14>")
	)
	(segment
		(start 353.754436 -216.574878)
		(end 353.760532 -216.578434)
		(width 0.0889)
		(layer "In2.Cu")
		(net "P5E_CPU0_PE1_TX_DP<14>")
	)
	(segment
		(start 393.411202 -20.083018)
		(end 398.972532 -45.592492)
		(width 0.14732)
		(layer "In2.Cu")
		(net "P5E_CPU0_PE1_TX_DP<14>")
	)
	(segment
		(start 354.03663 -218.676728)
		(end 354.03663 -218.707716)
		(width 0.0889)
		(layer "In2.Cu")
		(net "P5E_CPU0_PE1_TX_DP<14>")
	)
	(segment
		(start 393.698984 -19.125438)
		(end 393.404344 -19.420078)
		(width 0.14732)
		(layer "In2.Cu")
		(net "P5E_CPU0_PE1_TX_DP<14>")
	)
	(segment
		(start 354.278946 -224.843086)
		(end 354.254816 -224.93224)
		(width 0.0889)
		(layer "In2.Cu")
		(net "P5E_CPU0_PE1_TX_DP<14>")
	)
	(segment
		(start 353.288092 -215.763602)
		(end 353.284282 -215.761062)
		(width 0.0889)
		(layer "In2.Cu")
		(net "P5E_CPU0_PE1_TX_DP<14>")
	)
	(segment
		(start 353.097084 -213.284816)
		(end 353.097084 -213.787482)
		(width 0.0889)
		(layer "In2.Cu")
		(net "P5E_CPU0_PE1_TX_DP<14>")
	)
	(segment
		(start 353.283266 -215.112854)
		(end 353.275392 -215.117426)
		(width 0.0889)
		(layer "In2.Cu")
		(net "P5E_CPU0_PE1_TX_DP<14>")
	)
	(segment
		(start 354.215446 -220.639132)
		(end 354.224336 -220.644212)
		(width 0.0889)
		(layer "In2.Cu")
		(net "P5E_CPU0_PE1_TX_DP<14>")
	)
	(segment
		(start 354.221034 -223.897952)
		(end 354.221796 -223.89846)
		(width 0.0889)
		(layer "In2.Cu")
		(net "P5E_CPU0_PE1_TX_DP<14>")
	)
	(segment
		(start 340.59114 -176.298352)
		(end 352.25863 -207.165194)
		(width 0.14732)
		(layer "In2.Cu")
		(net "P5E_CPU0_PE1_TX_DP<14>")
	)
	(segment
		(start 354.506784 -221.115382)
		(end 354.506784 -221.133924)
		(width 0.0889)
		(layer "In2.Cu")
		(net "P5E_CPU0_PE1_TX_DP<14>")
	)
	(arc
		(start 353.557078 -214.489538)
		(mid 353.56417 -214.534502)
		(end 353.566476 -214.579962)
		(width 0.0889)
		(layer "In2.Cu")
		(net "P5E_CPU0_PE1_TX_DP<14>")
	)
	(arc
		(start 354.224336 -223.899984)
		(mid 354.260425 -223.922653)
		(end 354.294694 -223.94799)
		(width 0.0889)
		(layer "In2.Cu")
		(net "P5E_CPU0_PE1_TX_DP<14>")
	)
	(arc
		(start 354.294694 -221.575376)
		(mid 354.263207 -221.598719)
		(end 354.230178 -221.619826)
		(width 0.0889)
		(layer "In2.Cu")
		(net "P5E_CPU0_PE1_TX_DP<14>")
	)
	(arc
		(start 353.09683 -215.436704)
		(mid 353.144509 -215.619604)
		(end 353.275392 -215.755982)
		(width 0.0889)
		(layer "In2.Cu")
		(net "P5E_CPU0_PE1_TX_DP<14>")
	)
	(arc
		(start 354.036884 -223.575626)
		(mid 354.084563 -223.758526)
		(end 354.215446 -223.894904)
		(width 0.0889)
		(layer "In2.Cu")
		(net "P5E_CPU0_PE1_TX_DP<14>")
	)
	(arc
		(start 354.295964 -224.829878)
		(mid 354.287518 -224.836563)
		(end 354.278946 -224.843086)
		(width 0.0889)
		(layer "In2.Cu")
		(net "P5E_CPU0_PE1_TX_DP<14>")
	)
	(arc
		(start 353.745546 -222.442278)
		(mid 353.614632 -222.578638)
		(end 353.566984 -222.761556)
		(width 0.0889)
		(layer "In2.Cu")
		(net "P5E_CPU0_PE1_TX_DP<14>")
	)
	(arc
		(start 354.294694 -223.94799)
		(mid 354.448932 -224.140082)
		(end 354.506784 -224.379536)
		(width 0.0889)
		(layer "In2.Cu")
		(net "P5E_CPU0_PE1_TX_DP<14>")
	)
	(arc
		(start 353.745546 -219.18676)
		(mid 353.56707 -219.506038)
		(end 353.745546 -219.825316)
		(width 0.0889)
		(layer "In2.Cu")
		(net "P5E_CPU0_PE1_TX_DP<14>")
	)
	(arc
		(start 354.036884 -220.319854)
		(mid 354.084563 -220.502754)
		(end 354.215446 -220.639132)
		(width 0.0889)
		(layer "In2.Cu")
		(net "P5E_CPU0_PE1_TX_DP<14>")
	)
	(arc
		(start 353.745546 -217.559128)
		(mid 353.618466 -217.689142)
		(end 353.567492 -217.863674)
		(width 0.0889)
		(layer "In2.Cu")
		(net "P5E_CPU0_PE1_TX_DP<14>")
	)
	(arc
		(start 353.097084 -213.787482)
		(mid 353.146606 -213.966023)
		(end 353.281234 -214.093298)
		(width 0.0889)
		(layer "In2.Cu")
		(net "P5E_CPU0_PE1_TX_DP<14>")
	)
	(arc
		(start 354.03663 -218.707716)
		(mid 353.95726 -218.98145)
		(end 353.754436 -219.18168)
		(width 0.0889)
		(layer "In2.Cu")
		(net "P5E_CPU0_PE1_TX_DP<14>")
	)
	(arc
		(start 354.036884 -217.07856)
		(mid 353.957743 -217.353183)
		(end 353.754436 -217.554048)
		(width 0.0889)
		(layer "In2.Cu")
		(net "P5E_CPU0_PE1_TX_DP<14>")
	)
	(arc
		(start 354.215192 -221.628462)
		(mid 354.084278 -221.764822)
		(end 354.03663 -221.94774)
		(width 0.0889)
		(layer "In2.Cu")
		(net "P5E_CPU0_PE1_TX_DP<14>")
	)
	(arc
		(start 353.097084 -215.421972)
		(mid 353.096887 -215.429337)
		(end 353.09683 -215.436704)
		(width 0.0889)
		(layer "In2.Cu")
		(net "P5E_CPU0_PE1_TX_DP<14>")
	)
	(arc
		(start 353.760532 -219.833952)
		(mid 353.962945 -220.040365)
		(end 354.036884 -220.319854)
		(width 0.0889)
		(layer "In2.Cu")
		(net "P5E_CPU0_PE1_TX_DP<14>")
	)
	(arc
		(start 353.290378 -215.764618)
		(mid 353.492965 -215.970969)
		(end 353.566984 -216.25052)
		(width 0.0889)
		(layer "In2.Cu")
		(net "P5E_CPU0_PE1_TX_DP<14>")
	)
	(arc
		(start 354.224336 -220.644212)
		(mid 354.260416 -220.666895)
		(end 354.294694 -220.692218)
		(width 0.0889)
		(layer "In2.Cu")
		(net "P5E_CPU0_PE1_TX_DP<14>")
	)
	(arc
		(start 354.03663 -221.963234)
		(mid 353.95726 -222.236968)
		(end 353.754436 -222.437198)
		(width 0.0889)
		(layer "In2.Cu")
		(net "P5E_CPU0_PE1_TX_DP<14>")
	)
	(arc
		(start 353.275392 -215.117426)
		(mid 353.148138 -215.247392)
		(end 353.097084 -215.421972)
		(width 0.0889)
		(layer "In2.Cu")
		(net "P5E_CPU0_PE1_TX_DP<14>")
	)
	(arc
		(start 353.754436 -223.085914)
		(mid 353.957741 -223.28678)
		(end 354.036884 -223.561402)
		(width 0.0889)
		(layer "In2.Cu")
		(net "P5E_CPU0_PE1_TX_DP<14>")
	)
	(arc
		(start 354.506784 -221.133924)
		(mid 354.451078 -221.378844)
		(end 354.294694 -221.575376)
		(width 0.0889)
		(layer "In2.Cu")
		(net "P5E_CPU0_PE1_TX_DP<14>")
	)
	(arc
		(start 353.468686 -214.247984)
		(mid 353.511281 -214.318448)
		(end 353.537266 -214.396574)
		(width 0.0889)
		(layer "In2.Cu")
		(net "P5E_CPU0_PE1_TX_DP<14>")
	)
	(arc
		(start 354.294694 -220.692218)
		(mid 354.447155 -220.880538)
		(end 354.506784 -221.115382)
		(width 0.0889)
		(layer "In2.Cu")
		(net "P5E_CPU0_PE1_TX_DP<14>")
	)
	(arc
		(start 353.567492 -217.863674)
		(mid 353.567159 -217.876118)
		(end 353.567238 -217.888566)
		(width 0.0889)
		(layer "In2.Cu")
		(net "P5E_CPU0_PE1_TX_DP<14>")
	)
	(arc
		(start 353.754436 -218.202764)
		(mid 353.957259 -218.402995)
		(end 354.03663 -218.676728)
		(width 0.0889)
		(layer "In2.Cu")
		(net "P5E_CPU0_PE1_TX_DP<14>")
	)
	(arc
		(start 353.567238 -222.776288)
		(mid 353.618292 -222.950868)
		(end 353.745546 -223.080834)
		(width 0.0889)
		(layer "In2.Cu")
		(net "P5E_CPU0_PE1_TX_DP<14>")
	)
	(arc
		(start 353.566476 -214.644732)
		(mid 353.485565 -214.91486)
		(end 353.284282 -215.112346)
		(width 0.0889)
		(layer "In2.Cu")
		(net "P5E_CPU0_PE1_TX_DP<14>")
	)
	(arc
		(start 353.760532 -216.578434)
		(mid 353.962945 -216.784847)
		(end 354.036884 -217.064336)
		(width 0.0889)
		(layer "In2.Cu")
		(net "P5E_CPU0_PE1_TX_DP<14>")
	)
	(arc
		(start 354.506784 -224.389442)
		(mid 354.451429 -224.633629)
		(end 354.295964 -224.829878)
		(width 0.0889)
		(layer "In2.Cu")
		(net "P5E_CPU0_PE1_TX_DP<14>")
	)
	(arc
		(start 353.566984 -222.761556)
		(mid 353.567036 -222.768923)
		(end 353.567238 -222.776288)
		(width 0.0889)
		(layer "In2.Cu")
		(net "P5E_CPU0_PE1_TX_DP<14>")
	)
	(arc
		(start 353.567238 -217.888566)
		(mid 353.617253 -218.065697)
		(end 353.745546 -218.197684)
		(width 0.0889)
		(layer "In2.Cu")
		(net "P5E_CPU0_PE1_TX_DP<14>")
	)
	(arc
		(start 353.566984 -216.25052)
		(mid 353.614663 -216.43342)
		(end 353.745546 -216.569798)
		(width 0.0889)
		(layer "In2.Cu")
		(net "P5E_CPU0_PE1_TX_DP<14>")
	)
	(arc
		(start 353.281234 -214.093298)
		(mid 353.382899 -214.161023)
		(end 353.468686 -214.247984)
		(width 0.0889)
		(layer "In2.Cu")
		(net "P5E_CPU0_PE1_TX_DP<14>")
	)
	(segment
		(start 395.930628 -16.681958)
		(end 395.603984 -16.355314)
		(width 0.13208)
		(layer "F.Cu")
		(net "P5E_CPU0_PE1_TX_DP<13>")
	)
	(segment
		(start 354.88118 -224.925382)
		(end 354.88118 -224.389696)
		(width 0.13208)
		(layer "F.Cu")
		(net "P5E_CPU0_PE1_TX_DP<13>")
	)
	(segment
		(start 395.629384 -17.601438)
		(end 395.930628 -17.300194)
		(width 0.13208)
		(layer "F.Cu")
		(net "P5E_CPU0_PE1_TX_DP<13>")
	)
	(segment
		(start 395.930628 -17.300194)
		(end 395.930628 -16.681958)
		(width 0.13208)
		(layer "F.Cu")
		(net "P5E_CPU0_PE1_TX_DP<13>")
	)
	(segment
		(start 354.88118 -224.389696)
		(end 354.881434 -224.389442)
		(width 0.13208)
		(layer "F.Cu")
		(net "P5E_CPU0_PE1_TX_DP<13>")
	)
	(segment
		(start 402.934678 -80.015842)
		(end 341.758778 -167.385746)
		(width 0.14732)
		(layer "In2.Cu")
		(net "P5E_CPU0_PE1_TX_DP<13>")
	)
	(segment
		(start 354.128832 -215.926162)
		(end 354.130356 -215.926924)
		(width 0.0889)
		(layer "In2.Cu")
		(net "P5E_CPU0_PE1_TX_DP<13>")
	)
	(segment
		(start 354.122736 -215.922606)
		(end 354.126292 -215.924638)
		(width 0.0889)
		(layer "In2.Cu")
		(net "P5E_CPU0_PE1_TX_DP<13>")
	)
	(segment
		(start 353.804474 -213.227666)
		(end 353.804474 -213.249764)
		(width 0.0889)
		(layer "In2.Cu")
		(net "P5E_CPU0_PE1_TX_DP<13>")
	)
	(segment
		(start 354.607622 -219.0115)
		(end 354.60686 -219.012008)
		(width 0.0889)
		(layer "In2.Cu")
		(net "P5E_CPU0_PE1_TX_DP<13>")
	)
	(segment
		(start 341.758778 -167.385746)
		(end 340.609428 -172.568362)
		(width 0.14732)
		(layer "In2.Cu")
		(net "P5E_CPU0_PE1_TX_DP<13>")
	)
	(segment
		(start 354.599494 -219.016072)
		(end 354.598732 -219.01658)
		(width 0.0889)
		(layer "In2.Cu")
		(net "P5E_CPU0_PE1_TX_DP<13>")
	)
	(segment
		(start 354.602034 -219.014548)
		(end 354.601272 -219.015056)
		(width 0.0889)
		(layer "In2.Cu")
		(net "P5E_CPU0_PE1_TX_DP<13>")
	)
	(segment
		(start 354.130356 -215.926924)
		(end 354.137722 -215.931242)
		(width 0.0889)
		(layer "In2.Cu")
		(net "P5E_CPU0_PE1_TX_DP<13>")
	)
	(segment
		(start 355.077522 -221.453202)
		(end 355.068632 -221.458282)
		(width 0.0889)
		(layer "In2.Cu")
		(net "P5E_CPU0_PE1_TX_DP<13>")
	)
	(segment
		(start 354.602034 -218.369896)
		(end 354.607622 -218.372944)
		(width 0.0889)
		(layer "In2.Cu")
		(net "P5E_CPU0_PE1_TX_DP<13>")
	)
	(segment
		(start 355.013768 -224.02927)
		(end 355.037898 -224.118424)
		(width 0.0889)
		(layer "In2.Cu")
		(net "P5E_CPU0_PE1_TX_DP<13>")
	)
	(segment
		(start 354.599494 -218.368372)
		(end 354.602034 -218.369896)
		(width 0.0889)
		(layer "In2.Cu")
		(net "P5E_CPU0_PE1_TX_DP<13>")
	)
	(segment
		(start 354.316284 -216.25052)
		(end 354.316284 -216.260426)
		(width 0.0889)
		(layer "In2.Cu")
		(net "P5E_CPU0_PE1_TX_DP<13>")
	)
	(segment
		(start 354.316284 -222.75165)
		(end 354.316284 -222.780098)
		(width 0.0889)
		(layer "In2.Cu")
		(net "P5E_CPU0_PE1_TX_DP<13>")
	)
	(segment
		(start 353.84613 -215.414606)
		(end 353.84613 -215.436704)
		(width 0.0889)
		(layer "In2.Cu")
		(net "P5E_CPU0_PE1_TX_DP<13>")
	)
	(segment
		(start 354.598732 -218.367864)
		(end 354.599494 -218.368372)
		(width 0.0889)
		(layer "In2.Cu")
		(net "P5E_CPU0_PE1_TX_DP<13>")
	)
	(segment
		(start 403.7965 -75.475084)
		(end 402.934678 -80.015842)
		(width 0.14732)
		(layer "In2.Cu")
		(net "P5E_CPU0_PE1_TX_DP<13>")
	)
	(segment
		(start 340.609428 -172.568362)
		(end 341.218266 -176.024286)
		(width 0.14732)
		(layer "In2.Cu")
		(net "P5E_CPU0_PE1_TX_DP<13>")
	)
	(segment
		(start 399.689066 -40.73144)
		(end 403.7965 -75.475084)
		(width 0.14732)
		(layer "In2.Cu")
		(net "P5E_CPU0_PE1_TX_DP<13>")
	)
	(segment
		(start 353.846384 -213.291674)
		(end 353.846384 -213.930484)
		(width 0.0889)
		(layer "In2.Cu")
		(net "P5E_CPU0_PE1_TX_DP<13>")
	)
	(segment
		(start 355.068632 -220.809566)
		(end 355.077522 -220.814646)
		(width 0.0889)
		(layer "In2.Cu")
		(net "P5E_CPU0_PE1_TX_DP<13>")
	)
	(segment
		(start 353.804474 -213.249764)
		(end 353.846384 -213.291674)
		(width 0.0889)
		(layer "In2.Cu")
		(net "P5E_CPU0_PE1_TX_DP<13>")
	)
	(segment
		(start 352.88982 -206.949802)
		(end 353.804474 -211.963254)
		(width 0.14732)
		(layer "In2.Cu")
		(net "P5E_CPU0_PE1_TX_DP<13>")
	)
	(segment
		(start 354.607622 -217.383614)
		(end 354.598732 -217.388694)
		(width 0.0889)
		(layer "In2.Cu")
		(net "P5E_CPU0_PE1_TX_DP<13>")
	)
	(segment
		(start 354.60686 -219.012008)
		(end 354.602034 -219.014548)
		(width 0.0889)
		(layer "In2.Cu")
		(net "P5E_CPU0_PE1_TX_DP<13>")
	)
	(segment
		(start 354.315776 -214.461344)
		(end 354.315776 -214.622634)
		(width 0.0889)
		(layer "In2.Cu")
		(net "P5E_CPU0_PE1_TX_DP<13>")
	)
	(segment
		(start 354.598732 -216.739978)
		(end 354.607622 -216.745058)
		(width 0.0889)
		(layer "In2.Cu")
		(net "P5E_CPU0_PE1_TX_DP<13>")
	)
	(segment
		(start 395.629384 -17.601438)
		(end 395.924024 -17.896078)
		(width 0.14732)
		(layer "In2.Cu")
		(net "P5E_CPU0_PE1_TX_DP<13>")
	)
	(segment
		(start 355.037898 -224.118424)
		(end 354.881434 -224.389442)
		(width 0.0889)
		(layer "In2.Cu")
		(net "P5E_CPU0_PE1_TX_DP<13>")
	)
	(segment
		(start 354.601272 -219.015056)
		(end 354.599494 -219.016072)
		(width 0.0889)
		(layer "In2.Cu")
		(net "P5E_CPU0_PE1_TX_DP<13>")
	)
	(segment
		(start 395.924024 -17.896078)
		(end 395.924024 -20.635976)
		(width 0.14732)
		(layer "In2.Cu")
		(net "P5E_CPU0_PE1_TX_DP<13>")
	)
	(segment
		(start 341.218266 -176.024286)
		(end 352.88982 -206.949802)
		(width 0.14732)
		(layer "In2.Cu")
		(net "P5E_CPU0_PE1_TX_DP<13>")
	)
	(segment
		(start 354.316284 -217.859864)
		(end 354.316284 -217.888312)
		(width 0.0889)
		(layer "In2.Cu")
		(net "P5E_CPU0_PE1_TX_DP<13>")
	)
	(segment
		(start 354.78593 -223.56699)
		(end 354.78593 -223.575626)
		(width 0.0889)
		(layer "In2.Cu")
		(net "P5E_CPU0_PE1_TX_DP<13>")
	)
	(segment
		(start 354.786184 -221.937834)
		(end 354.786184 -221.94774)
		(width 0.0889)
		(layer "In2.Cu")
		(net "P5E_CPU0_PE1_TX_DP<13>")
	)
	(segment
		(start 354.78593 -220.311218)
		(end 354.78593 -220.334078)
		(width 0.0889)
		(layer "In2.Cu")
		(net "P5E_CPU0_PE1_TX_DP<13>")
	)
	(segment
		(start 353.804474 -211.963254)
		(end 353.804474 -213.227666)
		(width 0.14732)
		(layer "In2.Cu")
		(net "P5E_CPU0_PE1_TX_DP<13>")
	)
	(segment
		(start 395.924024 -20.635976)
		(end 399.689066 -40.73144)
		(width 0.14732)
		(layer "In2.Cu")
		(net "P5E_CPU0_PE1_TX_DP<13>")
	)
	(segment
		(start 354.29444 -216.124536)
		(end 354.29444 -216.12479)
		(width 0.0889)
		(layer "In2.Cu")
		(net "P5E_CPU0_PE1_TX_DP<13>")
	)
	(segment
		(start 354.316284 -219.496132)
		(end 354.316284 -219.515944)
		(width 0.0889)
		(layer "In2.Cu")
		(net "P5E_CPU0_PE1_TX_DP<13>")
	)
	(segment
		(start 354.126292 -215.924638)
		(end 354.128832 -215.926162)
		(width 0.0889)
		(layer "In2.Cu")
		(net "P5E_CPU0_PE1_TX_DP<13>")
	)
	(segment
		(start 354.607622 -222.267018)
		(end 354.598732 -222.272098)
		(width 0.0889)
		(layer "In2.Cu")
		(net "P5E_CPU0_PE1_TX_DP<13>")
	)
	(segment
		(start 354.137214 -214.941912)
		(end 354.128324 -214.946992)
		(width 0.0889)
		(layer "In2.Cu")
		(net "P5E_CPU0_PE1_TX_DP<13>")
	)
	(arc
		(start 354.316284 -222.780098)
		(mid 354.396446 -223.052287)
		(end 354.598732 -223.251268)
		(width 0.0889)
		(layer "In2.Cu")
		(net "P5E_CPU0_PE1_TX_DP<13>")
	)
	(arc
		(start 353.84613 -215.436704)
		(mid 353.920121 -215.71627)
		(end 354.122736 -215.922606)
		(width 0.0889)
		(layer "In2.Cu")
		(net "P5E_CPU0_PE1_TX_DP<13>")
	)
	(arc
		(start 354.137722 -215.931242)
		(mid 354.157054 -215.943996)
		(end 354.175568 -215.957912)
		(width 0.0889)
		(layer "In2.Cu")
		(net "P5E_CPU0_PE1_TX_DP<13>")
	)
	(arc
		(start 354.607622 -218.372944)
		(mid 354.786219 -218.692222)
		(end 354.607622 -219.0115)
		(width 0.0889)
		(layer "In2.Cu")
		(net "P5E_CPU0_PE1_TX_DP<13>")
	)
	(arc
		(start 354.316284 -216.260426)
		(mid 354.394395 -216.537375)
		(end 354.598732 -216.739978)
		(width 0.0889)
		(layer "In2.Cu")
		(net "P5E_CPU0_PE1_TX_DP<13>")
	)
	(arc
		(start 355.256084 -221.140528)
		(mid 355.206831 -221.319728)
		(end 355.077522 -221.453202)
		(width 0.0889)
		(layer "In2.Cu")
		(net "P5E_CPU0_PE1_TX_DP<13>")
	)
	(arc
		(start 354.78593 -220.334078)
		(mid 354.865149 -220.608763)
		(end 355.068632 -220.809566)
		(width 0.0889)
		(layer "In2.Cu")
		(net "P5E_CPU0_PE1_TX_DP<13>")
	)
	(arc
		(start 354.175568 -215.957912)
		(mid 354.246605 -216.032948)
		(end 354.29444 -216.124536)
		(width 0.0889)
		(layer "In2.Cu")
		(net "P5E_CPU0_PE1_TX_DP<13>")
	)
	(arc
		(start 354.598732 -219.01658)
		(mid 354.394397 -219.219185)
		(end 354.316284 -219.496132)
		(width 0.0889)
		(layer "In2.Cu")
		(net "P5E_CPU0_PE1_TX_DP<13>")
	)
	(arc
		(start 354.29444 -214.418926)
		(mid 354.305728 -214.439823)
		(end 354.315776 -214.461344)
		(width 0.0889)
		(layer "In2.Cu")
		(net "P5E_CPU0_PE1_TX_DP<13>")
	)
	(arc
		(start 354.78593 -217.076528)
		(mid 354.735437 -217.252506)
		(end 354.607622 -217.383614)
		(width 0.0889)
		(layer "In2.Cu")
		(net "P5E_CPU0_PE1_TX_DP<13>")
	)
	(arc
		(start 354.128324 -214.946992)
		(mid 353.927042 -215.144479)
		(end 353.84613 -215.414606)
		(width 0.0889)
		(layer "In2.Cu")
		(net "P5E_CPU0_PE1_TX_DP<13>")
	)
	(arc
		(start 354.786184 -217.057732)
		(mid 354.786174 -217.067132)
		(end 354.78593 -217.076528)
		(width 0.0889)
		(layer "In2.Cu")
		(net "P5E_CPU0_PE1_TX_DP<13>")
	)
	(arc
		(start 354.598732 -217.388694)
		(mid 354.396446 -217.587675)
		(end 354.316284 -217.859864)
		(width 0.0889)
		(layer "In2.Cu")
		(net "P5E_CPU0_PE1_TX_DP<13>")
	)
	(arc
		(start 353.861624 -213.969346)
		(mid 353.971618 -214.138715)
		(end 354.131626 -214.261954)
		(width 0.0889)
		(layer "In2.Cu")
		(net "P5E_CPU0_PE1_TX_DP<13>")
	)
	(arc
		(start 354.598732 -223.251268)
		(mid 354.733665 -223.384622)
		(end 354.78593 -223.56699)
		(width 0.0889)
		(layer "In2.Cu")
		(net "P5E_CPU0_PE1_TX_DP<13>")
	)
	(arc
		(start 354.78593 -223.575626)
		(mid 354.845973 -223.829513)
		(end 355.013768 -224.02927)
		(width 0.0889)
		(layer "In2.Cu")
		(net "P5E_CPU0_PE1_TX_DP<13>")
	)
	(arc
		(start 354.598732 -222.272098)
		(mid 354.394397 -222.474703)
		(end 354.316284 -222.75165)
		(width 0.0889)
		(layer "In2.Cu")
		(net "P5E_CPU0_PE1_TX_DP<13>")
	)
	(arc
		(start 354.316284 -219.515944)
		(mid 354.394395 -219.792893)
		(end 354.598732 -219.995496)
		(width 0.0889)
		(layer "In2.Cu")
		(net "P5E_CPU0_PE1_TX_DP<13>")
	)
	(arc
		(start 354.29444 -214.747348)
		(mid 354.232542 -214.858136)
		(end 354.137214 -214.941912)
		(width 0.0889)
		(layer "In2.Cu")
		(net "P5E_CPU0_PE1_TX_DP<13>")
	)
	(arc
		(start 354.29444 -216.12479)
		(mid 354.310742 -216.186719)
		(end 354.316284 -216.25052)
		(width 0.0889)
		(layer "In2.Cu")
		(net "P5E_CPU0_PE1_TX_DP<13>")
	)
	(arc
		(start 355.256084 -221.124526)
		(mid 355.256172 -221.132527)
		(end 355.256084 -221.140528)
		(width 0.0889)
		(layer "In2.Cu")
		(net "P5E_CPU0_PE1_TX_DP<13>")
	)
	(arc
		(start 354.315776 -214.622634)
		(mid 354.315724 -214.630001)
		(end 354.315522 -214.637366)
		(width 0.0889)
		(layer "In2.Cu")
		(net "P5E_CPU0_PE1_TX_DP<13>")
	)
	(arc
		(start 354.786184 -221.94774)
		(mid 354.738505 -222.13064)
		(end 354.607622 -222.267018)
		(width 0.0889)
		(layer "In2.Cu")
		(net "P5E_CPU0_PE1_TX_DP<13>")
	)
	(arc
		(start 354.316284 -217.888312)
		(mid 354.394395 -218.165261)
		(end 354.598732 -218.367864)
		(width 0.0889)
		(layer "In2.Cu")
		(net "P5E_CPU0_PE1_TX_DP<13>")
	)
	(arc
		(start 354.607622 -216.745058)
		(mid 354.736911 -216.878544)
		(end 354.786184 -217.057732)
		(width 0.0889)
		(layer "In2.Cu")
		(net "P5E_CPU0_PE1_TX_DP<13>")
	)
	(arc
		(start 354.598732 -219.995496)
		(mid 354.733665 -220.12885)
		(end 354.78593 -220.311218)
		(width 0.0889)
		(layer "In2.Cu")
		(net "P5E_CPU0_PE1_TX_DP<13>")
	)
	(arc
		(start 355.077522 -220.814646)
		(mid 355.206116 -220.94692)
		(end 355.256084 -221.124526)
		(width 0.0889)
		(layer "In2.Cu")
		(net "P5E_CPU0_PE1_TX_DP<13>")
	)
	(arc
		(start 354.131626 -214.261954)
		(mid 354.224156 -214.328909)
		(end 354.29444 -214.418926)
		(width 0.0889)
		(layer "In2.Cu")
		(net "P5E_CPU0_PE1_TX_DP<13>")
	)
	(arc
		(start 355.068632 -221.458282)
		(mid 354.864297 -221.660887)
		(end 354.786184 -221.937834)
		(width 0.0889)
		(layer "In2.Cu")
		(net "P5E_CPU0_PE1_TX_DP<13>")
	)
	(arc
		(start 353.846384 -213.930484)
		(mid 353.853669 -213.950046)
		(end 353.861624 -213.969346)
		(width 0.0889)
		(layer "In2.Cu")
		(net "P5E_CPU0_PE1_TX_DP<13>")
	)
	(arc
		(start 354.315522 -214.637366)
		(mid 354.309116 -214.69315)
		(end 354.29444 -214.747348)
		(width 0.0889)
		(layer "In2.Cu")
		(net "P5E_CPU0_PE1_TX_DP<13>")
	)
	(segment
		(start 356.291134 -225.739198)
		(end 356.291134 -225.203512)
		(width 0.13208)
		(layer "F.Cu")
		(net "P5E_CPU0_PE1_TX_DP<12>")
	)
	(segment
		(start 398.983708 -18.20799)
		(end 399.312384 -17.879314)
		(width 0.13208)
		(layer "F.Cu")
		(net "P5E_CPU0_PE1_TX_DP<12>")
	)
	(segment
		(start 356.291134 -225.203512)
		(end 356.29088 -225.203258)
		(width 0.13208)
		(layer "F.Cu")
		(net "P5E_CPU0_PE1_TX_DP<12>")
	)
	(segment
		(start 398.983708 -18.822162)
		(end 398.983708 -18.20799)
		(width 0.13208)
		(layer "F.Cu")
		(net "P5E_CPU0_PE1_TX_DP<12>")
	)
	(segment
		(start 399.286984 -19.125438)
		(end 398.983708 -18.822162)
		(width 0.13208)
		(layer "F.Cu")
		(net "P5E_CPU0_PE1_TX_DP<12>")
	)
	(segment
		(start 355.634036 -219.830396)
		(end 355.640132 -219.833952)
		(width 0.0889)
		(layer "In2.Cu")
		(net "P5E_CPU0_PE1_TX_DP<12>")
	)
	(segment
		(start 355.916484 -217.064336)
		(end 355.916484 -217.07856)
		(width 0.0889)
		(layer "In2.Cu")
		(net "P5E_CPU0_PE1_TX_DP<12>")
	)
	(segment
		(start 356.134416 -224.93224)
		(end 356.29088 -225.203258)
		(width 0.0889)
		(layer "In2.Cu")
		(net "P5E_CPU0_PE1_TX_DP<12>")
	)
	(segment
		(start 355.018594 -213.227666)
		(end 355.018594 -213.249764)
		(width 0.0889)
		(layer "In2.Cu")
		(net "P5E_CPU0_PE1_TX_DP<12>")
	)
	(segment
		(start 342.38057 -175.67783)
		(end 354.123244 -206.779876)
		(width 0.14732)
		(layer "In2.Cu")
		(net "P5E_CPU0_PE1_TX_DP<12>")
	)
	(segment
		(start 355.625146 -216.569798)
		(end 355.634036 -216.574878)
		(width 0.0889)
		(layer "In2.Cu")
		(net "P5E_CPU0_PE1_TX_DP<12>")
	)
	(segment
		(start 355.63302 -217.554556)
		(end 355.625146 -217.559128)
		(width 0.0889)
		(layer "In2.Cu")
		(net "P5E_CPU0_PE1_TX_DP<12>")
	)
	(segment
		(start 356.095046 -220.639132)
		(end 356.103936 -220.644212)
		(width 0.0889)
		(layer "In2.Cu")
		(net "P5E_CPU0_PE1_TX_DP<12>")
	)
	(segment
		(start 354.123244 -206.779876)
		(end 355.018594 -211.685632)
		(width 0.14732)
		(layer "In2.Cu")
		(net "P5E_CPU0_PE1_TX_DP<12>")
	)
	(segment
		(start 398.973294 -19.439128)
		(end 398.973294 -20.219162)
		(width 0.14732)
		(layer "In2.Cu")
		(net "P5E_CPU0_PE1_TX_DP<12>")
	)
	(segment
		(start 341.838534 -172.602398)
		(end 342.38057 -175.67783)
		(width 0.14732)
		(layer "In2.Cu")
		(net "P5E_CPU0_PE1_TX_DP<12>")
	)
	(segment
		(start 355.91623 -218.676728)
		(end 355.91623 -218.707716)
		(width 0.0889)
		(layer "In2.Cu")
		(net "P5E_CPU0_PE1_TX_DP<12>")
	)
	(segment
		(start 355.634036 -216.574878)
		(end 355.640132 -216.578434)
		(width 0.0889)
		(layer "In2.Cu")
		(net "P5E_CPU0_PE1_TX_DP<12>")
	)
	(segment
		(start 356.386384 -224.379536)
		(end 356.386384 -224.389442)
		(width 0.0889)
		(layer "In2.Cu")
		(net "P5E_CPU0_PE1_TX_DP<12>")
	)
	(segment
		(start 356.095808 -223.895412)
		(end 356.100634 -223.897952)
		(width 0.0889)
		(layer "In2.Cu")
		(net "P5E_CPU0_PE1_TX_DP<12>")
	)
	(segment
		(start 356.158546 -224.843086)
		(end 356.134416 -224.93224)
		(width 0.0889)
		(layer "In2.Cu")
		(net "P5E_CPU0_PE1_TX_DP<12>")
	)
	(segment
		(start 355.163882 -215.112346)
		(end 355.154992 -215.117426)
		(width 0.0889)
		(layer "In2.Cu")
		(net "P5E_CPU0_PE1_TX_DP<12>")
	)
	(segment
		(start 356.103682 -221.623382)
		(end 356.094792 -221.628462)
		(width 0.0889)
		(layer "In2.Cu")
		(net "P5E_CPU0_PE1_TX_DP<12>")
	)
	(segment
		(start 355.018594 -211.685632)
		(end 355.018594 -213.227666)
		(width 0.14732)
		(layer "In2.Cu")
		(net "P5E_CPU0_PE1_TX_DP<12>")
	)
	(segment
		(start 405.122888 -75.495658)
		(end 404.300944 -80.165448)
		(width 0.14732)
		(layer "In2.Cu")
		(net "P5E_CPU0_PE1_TX_DP<12>")
	)
	(segment
		(start 355.625146 -218.197684)
		(end 355.634036 -218.202764)
		(width 0.0889)
		(layer "In2.Cu")
		(net "P5E_CPU0_PE1_TX_DP<12>")
	)
	(segment
		(start 355.91623 -221.94774)
		(end 355.91623 -221.963234)
		(width 0.0889)
		(layer "In2.Cu")
		(net "P5E_CPU0_PE1_TX_DP<12>")
	)
	(segment
		(start 355.625146 -223.080834)
		(end 355.634036 -223.085914)
		(width 0.0889)
		(layer "In2.Cu")
		(net "P5E_CPU0_PE1_TX_DP<12>")
	)
	(segment
		(start 356.386384 -221.115382)
		(end 356.386384 -221.133924)
		(width 0.0889)
		(layer "In2.Cu")
		(net "P5E_CPU0_PE1_TX_DP<12>")
	)
	(segment
		(start 356.100634 -223.897952)
		(end 356.101396 -223.89846)
		(width 0.0889)
		(layer "In2.Cu")
		(net "P5E_CPU0_PE1_TX_DP<12>")
	)
	(segment
		(start 354.97643 -213.291928)
		(end 354.97643 -213.840314)
		(width 0.0889)
		(layer "In2.Cu")
		(net "P5E_CPU0_PE1_TX_DP<12>")
	)
	(segment
		(start 404.300944 -80.165448)
		(end 342.886792 -167.875204)
		(width 0.14732)
		(layer "In2.Cu")
		(net "P5E_CPU0_PE1_TX_DP<12>")
	)
	(segment
		(start 356.101396 -223.89846)
		(end 356.103174 -223.899476)
		(width 0.0889)
		(layer "In2.Cu")
		(net "P5E_CPU0_PE1_TX_DP<12>")
	)
	(segment
		(start 399.286984 -19.125438)
		(end 398.973294 -19.439128)
		(width 0.14732)
		(layer "In2.Cu")
		(net "P5E_CPU0_PE1_TX_DP<12>")
	)
	(segment
		(start 356.109778 -221.619826)
		(end 356.103682 -221.623382)
		(width 0.0889)
		(layer "In2.Cu")
		(net "P5E_CPU0_PE1_TX_DP<12>")
	)
	(segment
		(start 355.634036 -219.18168)
		(end 355.625146 -219.18676)
		(width 0.0889)
		(layer "In2.Cu")
		(net "P5E_CPU0_PE1_TX_DP<12>")
	)
	(segment
		(start 355.916484 -223.561402)
		(end 355.916484 -223.575626)
		(width 0.0889)
		(layer "In2.Cu")
		(net "P5E_CPU0_PE1_TX_DP<12>")
	)
	(segment
		(start 355.163882 -215.761062)
		(end 355.169978 -215.764618)
		(width 0.0889)
		(layer "In2.Cu")
		(net "P5E_CPU0_PE1_TX_DP<12>")
	)
	(segment
		(start 356.103174 -223.899476)
		(end 356.103936 -223.899984)
		(width 0.0889)
		(layer "In2.Cu")
		(net "P5E_CPU0_PE1_TX_DP<12>")
	)
	(segment
		(start 355.634036 -222.437198)
		(end 355.625146 -222.442278)
		(width 0.0889)
		(layer "In2.Cu")
		(net "P5E_CPU0_PE1_TX_DP<12>")
	)
	(segment
		(start 355.018594 -213.249764)
		(end 354.97643 -213.291928)
		(width 0.0889)
		(layer "In2.Cu")
		(net "P5E_CPU0_PE1_TX_DP<12>")
	)
	(segment
		(start 356.095046 -223.894904)
		(end 356.095808 -223.895412)
		(width 0.0889)
		(layer "In2.Cu")
		(net "P5E_CPU0_PE1_TX_DP<12>")
	)
	(segment
		(start 355.446076 -214.500206)
		(end 355.446076 -214.644732)
		(width 0.0889)
		(layer "In2.Cu")
		(net "P5E_CPU0_PE1_TX_DP<12>")
	)
	(segment
		(start 355.634036 -217.554048)
		(end 355.63302 -217.554556)
		(width 0.0889)
		(layer "In2.Cu")
		(net "P5E_CPU0_PE1_TX_DP<12>")
	)
	(segment
		(start 342.886792 -167.875204)
		(end 341.838534 -172.602398)
		(width 0.14732)
		(layer "In2.Cu")
		(net "P5E_CPU0_PE1_TX_DP<12>")
	)
	(segment
		(start 355.625146 -219.825316)
		(end 355.634036 -219.830396)
		(width 0.0889)
		(layer "In2.Cu")
		(net "P5E_CPU0_PE1_TX_DP<12>")
	)
	(segment
		(start 398.973294 -20.219162)
		(end 405.122888 -75.495658)
		(width 0.14732)
		(layer "In2.Cu")
		(net "P5E_CPU0_PE1_TX_DP<12>")
	)
	(segment
		(start 355.154992 -215.755982)
		(end 355.163882 -215.761062)
		(width 0.0889)
		(layer "In2.Cu")
		(net "P5E_CPU0_PE1_TX_DP<12>")
	)
	(arc
		(start 356.175564 -224.829878)
		(mid 356.167118 -224.836563)
		(end 356.158546 -224.843086)
		(width 0.0889)
		(layer "In2.Cu")
		(net "P5E_CPU0_PE1_TX_DP<12>")
	)
	(arc
		(start 355.640132 -219.833952)
		(mid 355.842545 -220.040365)
		(end 355.916484 -220.319854)
		(width 0.0889)
		(layer "In2.Cu")
		(net "P5E_CPU0_PE1_TX_DP<12>")
	)
	(arc
		(start 356.386384 -221.133924)
		(mid 356.312393 -221.41349)
		(end 356.109778 -221.619826)
		(width 0.0889)
		(layer "In2.Cu")
		(net "P5E_CPU0_PE1_TX_DP<12>")
	)
	(arc
		(start 355.916484 -217.07856)
		(mid 355.837343 -217.353183)
		(end 355.634036 -217.554048)
		(width 0.0889)
		(layer "In2.Cu")
		(net "P5E_CPU0_PE1_TX_DP<12>")
	)
	(arc
		(start 355.91623 -221.963234)
		(mid 355.83686 -222.236968)
		(end 355.634036 -222.437198)
		(width 0.0889)
		(layer "In2.Cu")
		(net "P5E_CPU0_PE1_TX_DP<12>")
	)
	(arc
		(start 355.13772 -214.066374)
		(mid 355.171559 -214.095237)
		(end 355.207824 -214.120984)
		(width 0.0889)
		(layer "In2.Cu")
		(net "P5E_CPU0_PE1_TX_DP<12>")
	)
	(arc
		(start 355.640132 -216.578434)
		(mid 355.842545 -216.784847)
		(end 355.916484 -217.064336)
		(width 0.0889)
		(layer "In2.Cu")
		(net "P5E_CPU0_PE1_TX_DP<12>")
	)
	(arc
		(start 354.97643 -213.840314)
		(mid 354.983921 -213.884891)
		(end 355.005894 -213.924388)
		(width 0.0889)
		(layer "In2.Cu")
		(net "P5E_CPU0_PE1_TX_DP<12>")
	)
	(arc
		(start 355.91623 -218.707716)
		(mid 355.83686 -218.98145)
		(end 355.634036 -219.18168)
		(width 0.0889)
		(layer "In2.Cu")
		(net "P5E_CPU0_PE1_TX_DP<12>")
	)
	(arc
		(start 354.976684 -215.421972)
		(mid 354.976487 -215.429337)
		(end 354.97643 -215.436704)
		(width 0.0889)
		(layer "In2.Cu")
		(net "P5E_CPU0_PE1_TX_DP<12>")
	)
	(arc
		(start 356.094792 -221.628462)
		(mid 355.963878 -221.764822)
		(end 355.91623 -221.94774)
		(width 0.0889)
		(layer "In2.Cu")
		(net "P5E_CPU0_PE1_TX_DP<12>")
	)
	(arc
		(start 355.634036 -223.085914)
		(mid 355.837341 -223.28678)
		(end 355.916484 -223.561402)
		(width 0.0889)
		(layer "In2.Cu")
		(net "P5E_CPU0_PE1_TX_DP<12>")
	)
	(arc
		(start 355.446584 -216.25052)
		(mid 355.494263 -216.43342)
		(end 355.625146 -216.569798)
		(width 0.0889)
		(layer "In2.Cu")
		(net "P5E_CPU0_PE1_TX_DP<12>")
	)
	(arc
		(start 355.446584 -222.761556)
		(mid 355.446636 -222.768923)
		(end 355.446838 -222.776288)
		(width 0.0889)
		(layer "In2.Cu")
		(net "P5E_CPU0_PE1_TX_DP<12>")
	)
	(arc
		(start 355.169978 -215.764618)
		(mid 355.372565 -215.970969)
		(end 355.446584 -216.25052)
		(width 0.0889)
		(layer "In2.Cu")
		(net "P5E_CPU0_PE1_TX_DP<12>")
	)
	(arc
		(start 355.634036 -218.202764)
		(mid 355.836859 -218.402995)
		(end 355.91623 -218.676728)
		(width 0.0889)
		(layer "In2.Cu")
		(net "P5E_CPU0_PE1_TX_DP<12>")
	)
	(arc
		(start 355.446838 -217.888566)
		(mid 355.496853 -218.065697)
		(end 355.625146 -218.197684)
		(width 0.0889)
		(layer "In2.Cu")
		(net "P5E_CPU0_PE1_TX_DP<12>")
	)
	(arc
		(start 356.386384 -224.389442)
		(mid 356.331029 -224.633629)
		(end 356.175564 -224.829878)
		(width 0.0889)
		(layer "In2.Cu")
		(net "P5E_CPU0_PE1_TX_DP<12>")
	)
	(arc
		(start 355.916484 -220.319854)
		(mid 355.964163 -220.502754)
		(end 356.095046 -220.639132)
		(width 0.0889)
		(layer "In2.Cu")
		(net "P5E_CPU0_PE1_TX_DP<12>")
	)
	(arc
		(start 354.97643 -215.436704)
		(mid 355.024109 -215.619604)
		(end 355.154992 -215.755982)
		(width 0.0889)
		(layer "In2.Cu")
		(net "P5E_CPU0_PE1_TX_DP<12>")
	)
	(arc
		(start 355.446838 -222.776288)
		(mid 355.497892 -222.950868)
		(end 355.625146 -223.080834)
		(width 0.0889)
		(layer "In2.Cu")
		(net "P5E_CPU0_PE1_TX_DP<12>")
	)
	(arc
		(start 355.446076 -214.644732)
		(mid 355.365165 -214.91486)
		(end 355.163882 -215.112346)
		(width 0.0889)
		(layer "In2.Cu")
		(net "P5E_CPU0_PE1_TX_DP<12>")
	)
	(arc
		(start 356.103936 -223.899984)
		(mid 356.308271 -224.102589)
		(end 356.386384 -224.379536)
		(width 0.0889)
		(layer "In2.Cu")
		(net "P5E_CPU0_PE1_TX_DP<12>")
	)
	(arc
		(start 355.005894 -213.924388)
		(mid 355.069432 -213.997586)
		(end 355.13772 -214.066374)
		(width 0.0889)
		(layer "In2.Cu")
		(net "P5E_CPU0_PE1_TX_DP<12>")
	)
	(arc
		(start 355.625146 -222.442278)
		(mid 355.494232 -222.578638)
		(end 355.446584 -222.761556)
		(width 0.0889)
		(layer "In2.Cu")
		(net "P5E_CPU0_PE1_TX_DP<12>")
	)
	(arc
		(start 355.154992 -215.117426)
		(mid 355.027738 -215.247392)
		(end 354.976684 -215.421972)
		(width 0.0889)
		(layer "In2.Cu")
		(net "P5E_CPU0_PE1_TX_DP<12>")
	)
	(arc
		(start 356.103936 -220.644212)
		(mid 356.306222 -220.843193)
		(end 356.386384 -221.115382)
		(width 0.0889)
		(layer "In2.Cu")
		(net "P5E_CPU0_PE1_TX_DP<12>")
	)
	(arc
		(start 355.3968 -214.31885)
		(mid 355.433505 -214.406252)
		(end 355.446076 -214.500206)
		(width 0.0889)
		(layer "In2.Cu")
		(net "P5E_CPU0_PE1_TX_DP<12>")
	)
	(arc
		(start 355.916484 -223.575626)
		(mid 355.964163 -223.758526)
		(end 356.095046 -223.894904)
		(width 0.0889)
		(layer "In2.Cu")
		(net "P5E_CPU0_PE1_TX_DP<12>")
	)
	(arc
		(start 355.447092 -217.863674)
		(mid 355.446759 -217.876118)
		(end 355.446838 -217.888566)
		(width 0.0889)
		(layer "In2.Cu")
		(net "P5E_CPU0_PE1_TX_DP<12>")
	)
	(arc
		(start 355.625146 -219.18676)
		(mid 355.44667 -219.506038)
		(end 355.625146 -219.825316)
		(width 0.0889)
		(layer "In2.Cu")
		(net "P5E_CPU0_PE1_TX_DP<12>")
	)
	(arc
		(start 355.625146 -217.559128)
		(mid 355.498066 -217.689142)
		(end 355.447092 -217.863674)
		(width 0.0889)
		(layer "In2.Cu")
		(net "P5E_CPU0_PE1_TX_DP<12>")
	)
	(arc
		(start 355.207824 -214.120984)
		(mid 355.313776 -214.208968)
		(end 355.3968 -214.31885)
		(width 0.0889)
		(layer "In2.Cu")
		(net "P5E_CPU0_PE1_TX_DP<12>")
	)
	(segment
		(start 356.76078 -224.925382)
		(end 356.761034 -224.925128)
		(width 0.13208)
		(layer "F.Cu")
		(net "P5E_CPU0_PE1_TX_DP<11>")
	)
	(segment
		(start 356.761034 -224.925128)
		(end 356.761034 -224.389442)
		(width 0.13208)
		(layer "F.Cu")
		(net "P5E_CPU0_PE1_TX_DP<11>")
	)
	(segment
		(start 401.518628 -16.681958)
		(end 401.191984 -16.355314)
		(width 0.13208)
		(layer "F.Cu")
		(net "P5E_CPU0_PE1_TX_DP<11>")
	)
	(segment
		(start 401.518628 -17.300194)
		(end 401.518628 -16.681958)
		(width 0.13208)
		(layer "F.Cu")
		(net "P5E_CPU0_PE1_TX_DP<11>")
	)
	(segment
		(start 401.217384 -17.601438)
		(end 401.518628 -17.300194)
		(width 0.13208)
		(layer "F.Cu")
		(net "P5E_CPU0_PE1_TX_DP<11>")
	)
	(segment
		(start 356.479094 -219.016072)
		(end 356.478332 -219.01658)
		(width 0.0889)
		(layer "In2.Cu")
		(net "P5E_CPU0_PE1_TX_DP<11>")
	)
	(segment
		(start 342.51265 -172.592238)
		(end 343.02192 -175.483012)
		(width 0.14732)
		(layer "In2.Cu")
		(net "P5E_CPU0_PE1_TX_DP<11>")
	)
	(segment
		(start 355.684074 -213.227666)
		(end 355.684074 -213.249764)
		(width 0.0889)
		(layer "In2.Cu")
		(net "P5E_CPU0_PE1_TX_DP<11>")
	)
	(segment
		(start 356.481634 -218.369896)
		(end 356.487222 -218.372944)
		(width 0.0889)
		(layer "In2.Cu")
		(net "P5E_CPU0_PE1_TX_DP<11>")
	)
	(segment
		(start 356.487222 -217.383614)
		(end 356.478332 -217.388694)
		(width 0.0889)
		(layer "In2.Cu")
		(net "P5E_CPU0_PE1_TX_DP<11>")
	)
	(segment
		(start 355.725984 -213.291674)
		(end 355.725984 -213.930484)
		(width 0.0889)
		(layer "In2.Cu")
		(net "P5E_CPU0_PE1_TX_DP<11>")
	)
	(segment
		(start 356.487222 -222.267018)
		(end 356.478332 -222.272098)
		(width 0.0889)
		(layer "In2.Cu")
		(net "P5E_CPU0_PE1_TX_DP<11>")
	)
	(segment
		(start 356.19563 -214.462106)
		(end 356.19563 -214.622634)
		(width 0.0889)
		(layer "In2.Cu")
		(net "P5E_CPU0_PE1_TX_DP<11>")
	)
	(segment
		(start 356.195884 -216.25052)
		(end 356.195884 -216.260426)
		(width 0.0889)
		(layer "In2.Cu")
		(net "P5E_CPU0_PE1_TX_DP<11>")
	)
	(segment
		(start 405.223726 -80.008222)
		(end 343.492836 -168.16959)
		(width 0.14732)
		(layer "In2.Cu")
		(net "P5E_CPU0_PE1_TX_DP<11>")
	)
	(segment
		(start 356.48646 -219.012008)
		(end 356.481634 -219.014548)
		(width 0.0889)
		(layer "In2.Cu")
		(net "P5E_CPU0_PE1_TX_DP<11>")
	)
	(segment
		(start 343.492836 -168.16959)
		(end 342.51265 -172.592238)
		(width 0.14732)
		(layer "In2.Cu")
		(net "P5E_CPU0_PE1_TX_DP<11>")
	)
	(segment
		(start 356.195884 -217.859864)
		(end 356.195884 -217.888312)
		(width 0.0889)
		(layer "In2.Cu")
		(net "P5E_CPU0_PE1_TX_DP<11>")
	)
	(segment
		(start 355.684074 -213.249764)
		(end 355.725984 -213.291674)
		(width 0.0889)
		(layer "In2.Cu")
		(net "P5E_CPU0_PE1_TX_DP<11>")
	)
	(segment
		(start 356.948232 -220.809566)
		(end 356.957122 -220.814646)
		(width 0.0889)
		(layer "In2.Cu")
		(net "P5E_CPU0_PE1_TX_DP<11>")
	)
	(segment
		(start 356.893368 -224.02927)
		(end 356.917498 -224.118424)
		(width 0.0889)
		(layer "In2.Cu")
		(net "P5E_CPU0_PE1_TX_DP<11>")
	)
	(segment
		(start 356.195884 -219.496132)
		(end 356.195884 -219.515944)
		(width 0.0889)
		(layer "In2.Cu")
		(net "P5E_CPU0_PE1_TX_DP<11>")
	)
	(segment
		(start 343.02192 -175.483012)
		(end 354.794566 -206.672942)
		(width 0.14732)
		(layer "In2.Cu")
		(net "P5E_CPU0_PE1_TX_DP<11>")
	)
	(segment
		(start 356.957122 -221.453202)
		(end 356.948232 -221.458282)
		(width 0.0889)
		(layer "In2.Cu")
		(net "P5E_CPU0_PE1_TX_DP<11>")
	)
	(segment
		(start 356.195884 -222.75165)
		(end 356.195884 -222.780098)
		(width 0.0889)
		(layer "In2.Cu")
		(net "P5E_CPU0_PE1_TX_DP<11>")
	)
	(segment
		(start 356.478332 -218.367864)
		(end 356.479094 -218.368372)
		(width 0.0889)
		(layer "In2.Cu")
		(net "P5E_CPU0_PE1_TX_DP<11>")
	)
	(segment
		(start 356.008432 -215.926162)
		(end 356.017322 -215.931242)
		(width 0.0889)
		(layer "In2.Cu")
		(net "P5E_CPU0_PE1_TX_DP<11>")
	)
	(segment
		(start 356.917498 -224.118424)
		(end 356.761034 -224.389442)
		(width 0.0889)
		(layer "In2.Cu")
		(net "P5E_CPU0_PE1_TX_DP<11>")
	)
	(segment
		(start 356.02291 -214.938356)
		(end 356.007924 -214.946992)
		(width 0.0889)
		(layer "In2.Cu")
		(net "P5E_CPU0_PE1_TX_DP<11>")
	)
	(segment
		(start 356.002336 -215.922606)
		(end 356.008432 -215.926162)
		(width 0.0889)
		(layer "In2.Cu")
		(net "P5E_CPU0_PE1_TX_DP<11>")
	)
	(segment
		(start 356.478332 -216.739978)
		(end 356.487222 -216.745058)
		(width 0.0889)
		(layer "In2.Cu")
		(net "P5E_CPU0_PE1_TX_DP<11>")
	)
	(segment
		(start 356.66553 -223.56699)
		(end 356.66553 -223.575626)
		(width 0.0889)
		(layer "In2.Cu")
		(net "P5E_CPU0_PE1_TX_DP<11>")
	)
	(segment
		(start 356.66553 -220.311218)
		(end 356.66553 -220.334078)
		(width 0.0889)
		(layer "In2.Cu")
		(net "P5E_CPU0_PE1_TX_DP<11>")
	)
	(segment
		(start 401.217384 -17.601438)
		(end 401.512024 -17.896078)
		(width 0.14732)
		(layer "In2.Cu")
		(net "P5E_CPU0_PE1_TX_DP<11>")
	)
	(segment
		(start 356.479094 -218.368372)
		(end 356.481634 -218.369896)
		(width 0.0889)
		(layer "In2.Cu")
		(net "P5E_CPU0_PE1_TX_DP<11>")
	)
	(segment
		(start 354.794566 -206.672942)
		(end 355.684074 -211.54771)
		(width 0.14732)
		(layer "In2.Cu")
		(net "P5E_CPU0_PE1_TX_DP<11>")
	)
	(segment
		(start 401.512024 -18.378932)
		(end 406.07996 -75.09764)
		(width 0.14732)
		(layer "In2.Cu")
		(net "P5E_CPU0_PE1_TX_DP<11>")
	)
	(segment
		(start 401.512024 -17.896078)
		(end 401.512024 -18.378932)
		(width 0.14732)
		(layer "In2.Cu")
		(net "P5E_CPU0_PE1_TX_DP<11>")
	)
	(segment
		(start 355.72573 -215.414606)
		(end 355.72573 -215.436704)
		(width 0.0889)
		(layer "In2.Cu")
		(net "P5E_CPU0_PE1_TX_DP<11>")
	)
	(segment
		(start 356.481634 -219.014548)
		(end 356.480872 -219.015056)
		(width 0.0889)
		(layer "In2.Cu")
		(net "P5E_CPU0_PE1_TX_DP<11>")
	)
	(segment
		(start 356.665784 -221.937834)
		(end 356.665784 -221.94774)
		(width 0.0889)
		(layer "In2.Cu")
		(net "P5E_CPU0_PE1_TX_DP<11>")
	)
	(segment
		(start 356.480872 -219.015056)
		(end 356.479094 -219.016072)
		(width 0.0889)
		(layer "In2.Cu")
		(net "P5E_CPU0_PE1_TX_DP<11>")
	)
	(segment
		(start 356.487222 -219.0115)
		(end 356.48646 -219.012008)
		(width 0.0889)
		(layer "In2.Cu")
		(net "P5E_CPU0_PE1_TX_DP<11>")
	)
	(segment
		(start 406.07996 -75.09764)
		(end 405.223726 -80.008222)
		(width 0.14732)
		(layer "In2.Cu")
		(net "P5E_CPU0_PE1_TX_DP<11>")
	)
	(segment
		(start 355.684074 -211.54771)
		(end 355.684074 -213.227666)
		(width 0.14732)
		(layer "In2.Cu")
		(net "P5E_CPU0_PE1_TX_DP<11>")
	)
	(arc
		(start 356.66553 -220.334078)
		(mid 356.744749 -220.608763)
		(end 356.948232 -220.809566)
		(width 0.0889)
		(layer "In2.Cu")
		(net "P5E_CPU0_PE1_TX_DP<11>")
	)
	(arc
		(start 356.66553 -223.575626)
		(mid 356.725573 -223.829513)
		(end 356.893368 -224.02927)
		(width 0.0889)
		(layer "In2.Cu")
		(net "P5E_CPU0_PE1_TX_DP<11>")
	)
	(arc
		(start 356.017322 -215.931242)
		(mid 356.148236 -216.067602)
		(end 356.195884 -216.25052)
		(width 0.0889)
		(layer "In2.Cu")
		(net "P5E_CPU0_PE1_TX_DP<11>")
	)
	(arc
		(start 356.195884 -216.260426)
		(mid 356.273995 -216.537375)
		(end 356.478332 -216.739978)
		(width 0.0889)
		(layer "In2.Cu")
		(net "P5E_CPU0_PE1_TX_DP<11>")
	)
	(arc
		(start 356.957122 -220.814646)
		(mid 357.085716 -220.94692)
		(end 357.135684 -221.124526)
		(width 0.0889)
		(layer "In2.Cu")
		(net "P5E_CPU0_PE1_TX_DP<11>")
	)
	(arc
		(start 357.135684 -221.140528)
		(mid 357.086431 -221.319728)
		(end 356.957122 -221.453202)
		(width 0.0889)
		(layer "In2.Cu")
		(net "P5E_CPU0_PE1_TX_DP<11>")
	)
	(arc
		(start 356.478332 -223.251268)
		(mid 356.613265 -223.384622)
		(end 356.66553 -223.56699)
		(width 0.0889)
		(layer "In2.Cu")
		(net "P5E_CPU0_PE1_TX_DP<11>")
	)
	(arc
		(start 356.195884 -222.780098)
		(mid 356.276046 -223.052287)
		(end 356.478332 -223.251268)
		(width 0.0889)
		(layer "In2.Cu")
		(net "P5E_CPU0_PE1_TX_DP<11>")
	)
	(arc
		(start 355.725984 -213.930484)
		(mid 355.733269 -213.950046)
		(end 355.741224 -213.969346)
		(width 0.0889)
		(layer "In2.Cu")
		(net "P5E_CPU0_PE1_TX_DP<11>")
	)
	(arc
		(start 356.665784 -221.94774)
		(mid 356.618105 -222.13064)
		(end 356.487222 -222.267018)
		(width 0.0889)
		(layer "In2.Cu")
		(net "P5E_CPU0_PE1_TX_DP<11>")
	)
	(arc
		(start 356.007924 -214.946992)
		(mid 355.806642 -215.144479)
		(end 355.72573 -215.414606)
		(width 0.0889)
		(layer "In2.Cu")
		(net "P5E_CPU0_PE1_TX_DP<11>")
	)
	(arc
		(start 357.135684 -221.124526)
		(mid 357.135772 -221.132527)
		(end 357.135684 -221.140528)
		(width 0.0889)
		(layer "In2.Cu")
		(net "P5E_CPU0_PE1_TX_DP<11>")
	)
	(arc
		(start 356.66553 -217.076528)
		(mid 356.615037 -217.252506)
		(end 356.487222 -217.383614)
		(width 0.0889)
		(layer "In2.Cu")
		(net "P5E_CPU0_PE1_TX_DP<11>")
	)
	(arc
		(start 356.011226 -214.261954)
		(mid 356.120645 -214.346176)
		(end 356.19563 -214.462106)
		(width 0.0889)
		(layer "In2.Cu")
		(net "P5E_CPU0_PE1_TX_DP<11>")
	)
	(arc
		(start 356.665784 -217.057732)
		(mid 356.665774 -217.067132)
		(end 356.66553 -217.076528)
		(width 0.0889)
		(layer "In2.Cu")
		(net "P5E_CPU0_PE1_TX_DP<11>")
	)
	(arc
		(start 355.72573 -215.436704)
		(mid 355.799721 -215.71627)
		(end 356.002336 -215.922606)
		(width 0.0889)
		(layer "In2.Cu")
		(net "P5E_CPU0_PE1_TX_DP<11>")
	)
	(arc
		(start 356.487222 -218.372944)
		(mid 356.665819 -218.692222)
		(end 356.487222 -219.0115)
		(width 0.0889)
		(layer "In2.Cu")
		(net "P5E_CPU0_PE1_TX_DP<11>")
	)
	(arc
		(start 356.195884 -219.515944)
		(mid 356.273995 -219.792893)
		(end 356.478332 -219.995496)
		(width 0.0889)
		(layer "In2.Cu")
		(net "P5E_CPU0_PE1_TX_DP<11>")
	)
	(arc
		(start 356.487222 -216.745058)
		(mid 356.616511 -216.878544)
		(end 356.665784 -217.057732)
		(width 0.0889)
		(layer "In2.Cu")
		(net "P5E_CPU0_PE1_TX_DP<11>")
	)
	(arc
		(start 356.19563 -214.622634)
		(mid 356.149626 -214.802571)
		(end 356.02291 -214.938356)
		(width 0.0889)
		(layer "In2.Cu")
		(net "P5E_CPU0_PE1_TX_DP<11>")
	)
	(arc
		(start 356.478332 -222.272098)
		(mid 356.273997 -222.474703)
		(end 356.195884 -222.75165)
		(width 0.0889)
		(layer "In2.Cu")
		(net "P5E_CPU0_PE1_TX_DP<11>")
	)
	(arc
		(start 356.948232 -221.458282)
		(mid 356.743897 -221.660887)
		(end 356.665784 -221.937834)
		(width 0.0889)
		(layer "In2.Cu")
		(net "P5E_CPU0_PE1_TX_DP<11>")
	)
	(arc
		(start 356.478332 -217.388694)
		(mid 356.276046 -217.587675)
		(end 356.195884 -217.859864)
		(width 0.0889)
		(layer "In2.Cu")
		(net "P5E_CPU0_PE1_TX_DP<11>")
	)
	(arc
		(start 356.478332 -219.01658)
		(mid 356.273997 -219.219185)
		(end 356.195884 -219.496132)
		(width 0.0889)
		(layer "In2.Cu")
		(net "P5E_CPU0_PE1_TX_DP<11>")
	)
	(arc
		(start 356.195884 -217.888312)
		(mid 356.273995 -218.165261)
		(end 356.478332 -218.367864)
		(width 0.0889)
		(layer "In2.Cu")
		(net "P5E_CPU0_PE1_TX_DP<11>")
	)
	(arc
		(start 355.741224 -213.969346)
		(mid 355.851218 -214.138715)
		(end 356.011226 -214.261954)
		(width 0.0889)
		(layer "In2.Cu")
		(net "P5E_CPU0_PE1_TX_DP<11>")
	)
	(arc
		(start 356.478332 -219.995496)
		(mid 356.613265 -220.12885)
		(end 356.66553 -220.311218)
		(width 0.0889)
		(layer "In2.Cu")
		(net "P5E_CPU0_PE1_TX_DP<11>")
	)
	(segment
		(start 358.17048 -225.738944)
		(end 358.17048 -225.203258)
		(width 0.13208)
		(layer "F.Cu")
		(net "P5E_CPU0_PE1_TX_DP<10>")
	)
	(segment
		(start 358.170734 -225.739198)
		(end 358.17048 -225.738944)
		(width 0.13208)
		(layer "F.Cu")
		(net "P5E_CPU0_PE1_TX_DP<10>")
	)
	(segment
		(start 404.874984 -19.125438)
		(end 404.571708 -18.822162)
		(width 0.13208)
		(layer "F.Cu")
		(net "P5E_CPU0_PE1_TX_DP<10>")
	)
	(segment
		(start 404.571708 -18.20799)
		(end 404.900384 -17.879314)
		(width 0.13208)
		(layer "F.Cu")
		(net "P5E_CPU0_PE1_TX_DP<10>")
	)
	(segment
		(start 404.571708 -18.822162)
		(end 404.571708 -18.20799)
		(width 0.13208)
		(layer "F.Cu")
		(net "P5E_CPU0_PE1_TX_DP<10>")
	)
	(segment
		(start 357.36784 -214.031068)
		(end 357.325676 -214.073232)
		(width 0.0889)
		(layer "In2.Cu")
		(net "P5E_CPU0_PE1_TX_DP<10>")
	)
	(segment
		(start 344.61704 -168.665398)
		(end 343.748614 -172.582078)
		(width 0.14732)
		(layer "In2.Cu")
		(net "P5E_CPU0_PE1_TX_DP<10>")
	)
	(segment
		(start 357.034592 -215.755982)
		(end 357.043482 -215.761062)
		(width 0.0889)
		(layer "In2.Cu")
		(net "P5E_CPU0_PE1_TX_DP<10>")
	)
	(segment
		(start 356.94366 -209.956908)
		(end 357.36784 -213.25332)
		(width 0.14732)
		(layer "In2.Cu")
		(net "P5E_CPU0_PE1_TX_DP<10>")
	)
	(segment
		(start 357.519732 -222.433642)
		(end 357.513636 -222.437198)
		(width 0.0889)
		(layer "In2.Cu")
		(net "P5E_CPU0_PE1_TX_DP<10>")
	)
	(segment
		(start 357.974646 -220.639132)
		(end 357.983536 -220.644212)
		(width 0.0889)
		(layer "In2.Cu")
		(net "P5E_CPU0_PE1_TX_DP<10>")
	)
	(segment
		(start 357.974646 -223.894904)
		(end 357.980234 -223.897952)
		(width 0.0889)
		(layer "In2.Cu")
		(net "P5E_CPU0_PE1_TX_DP<10>")
	)
	(segment
		(start 357.982774 -221.62389)
		(end 357.980234 -221.625414)
		(width 0.0889)
		(layer "In2.Cu")
		(net "P5E_CPU0_PE1_TX_DP<10>")
	)
	(segment
		(start 355.961696 -206.207614)
		(end 356.94366 -209.956908)
		(width 0.14732)
		(layer "In2.Cu")
		(net "P5E_CPU0_PE1_TX_DP<10>")
	)
	(segment
		(start 358.265984 -224.379536)
		(end 358.265984 -224.389442)
		(width 0.0889)
		(layer "In2.Cu")
		(net "P5E_CPU0_PE1_TX_DP<10>")
	)
	(segment
		(start 357.043482 -215.761062)
		(end 357.049578 -215.764618)
		(width 0.0889)
		(layer "In2.Cu")
		(net "P5E_CPU0_PE1_TX_DP<10>")
	)
	(segment
		(start 357.504746 -216.569798)
		(end 357.513636 -216.574878)
		(width 0.0889)
		(layer "In2.Cu")
		(net "P5E_CPU0_PE1_TX_DP<10>")
	)
	(segment
		(start 357.504746 -218.197684)
		(end 357.513636 -218.202764)
		(width 0.0889)
		(layer "In2.Cu")
		(net "P5E_CPU0_PE1_TX_DP<10>")
	)
	(segment
		(start 357.519732 -219.178124)
		(end 357.513636 -219.18168)
		(width 0.0889)
		(layer "In2.Cu")
		(net "P5E_CPU0_PE1_TX_DP<10>")
	)
	(segment
		(start 357.513636 -219.18168)
		(end 357.504746 -219.18676)
		(width 0.0889)
		(layer "In2.Cu")
		(net "P5E_CPU0_PE1_TX_DP<10>")
	)
	(segment
		(start 343.748614 -172.582078)
		(end 344.187272 -175.069754)
		(width 0.14732)
		(layer "In2.Cu")
		(net "P5E_CPU0_PE1_TX_DP<10>")
	)
	(segment
		(start 358.038146 -224.843086)
		(end 358.014016 -224.93224)
		(width 0.0889)
		(layer "In2.Cu")
		(net "P5E_CPU0_PE1_TX_DP<10>")
	)
	(segment
		(start 357.980234 -223.897952)
		(end 357.982774 -223.899476)
		(width 0.0889)
		(layer "In2.Cu")
		(net "P5E_CPU0_PE1_TX_DP<10>")
	)
	(segment
		(start 357.983536 -221.623382)
		(end 357.982774 -221.62389)
		(width 0.0889)
		(layer "In2.Cu")
		(net "P5E_CPU0_PE1_TX_DP<10>")
	)
	(segment
		(start 357.325676 -214.073232)
		(end 357.325676 -214.644732)
		(width 0.0889)
		(layer "In2.Cu")
		(net "P5E_CPU0_PE1_TX_DP<10>")
	)
	(segment
		(start 357.982774 -223.899476)
		(end 357.983536 -223.899984)
		(width 0.0889)
		(layer "In2.Cu")
		(net "P5E_CPU0_PE1_TX_DP<10>")
	)
	(segment
		(start 357.36784 -214.00897)
		(end 357.36784 -214.031068)
		(width 0.0889)
		(layer "In2.Cu")
		(net "P5E_CPU0_PE1_TX_DP<10>")
	)
	(segment
		(start 357.513636 -218.202764)
		(end 357.519732 -218.20632)
		(width 0.0889)
		(layer "In2.Cu")
		(net "P5E_CPU0_PE1_TX_DP<10>")
	)
	(segment
		(start 357.796084 -217.064336)
		(end 357.796084 -217.07856)
		(width 0.0889)
		(layer "In2.Cu")
		(net "P5E_CPU0_PE1_TX_DP<10>")
	)
	(segment
		(start 357.504746 -219.825316)
		(end 357.513636 -219.830396)
		(width 0.0889)
		(layer "In2.Cu")
		(net "P5E_CPU0_PE1_TX_DP<10>")
	)
	(segment
		(start 404.874984 -19.125438)
		(end 404.580344 -19.420078)
		(width 0.14732)
		(layer "In2.Cu")
		(net "P5E_CPU0_PE1_TX_DP<10>")
	)
	(segment
		(start 358.265984 -221.115382)
		(end 358.265984 -221.14383)
		(width 0.0889)
		(layer "In2.Cu")
		(net "P5E_CPU0_PE1_TX_DP<10>")
	)
	(segment
		(start 404.580344 -19.420078)
		(end 404.580344 -20.036028)
		(width 0.14732)
		(layer "In2.Cu")
		(net "P5E_CPU0_PE1_TX_DP<10>")
	)
	(segment
		(start 357.504746 -223.080834)
		(end 357.513636 -223.085914)
		(width 0.0889)
		(layer "In2.Cu")
		(net "P5E_CPU0_PE1_TX_DP<10>")
	)
	(segment
		(start 357.796084 -223.561402)
		(end 357.796084 -223.575626)
		(width 0.0889)
		(layer "In2.Cu")
		(net "P5E_CPU0_PE1_TX_DP<10>")
	)
	(segment
		(start 357.513636 -217.554048)
		(end 357.504746 -217.559128)
		(width 0.0889)
		(layer "In2.Cu")
		(net "P5E_CPU0_PE1_TX_DP<10>")
	)
	(segment
		(start 344.187272 -175.069754)
		(end 355.961696 -206.207614)
		(width 0.14732)
		(layer "In2.Cu")
		(net "P5E_CPU0_PE1_TX_DP<10>")
	)
	(segment
		(start 358.014016 -224.93224)
		(end 358.17048 -225.203258)
		(width 0.0889)
		(layer "In2.Cu")
		(net "P5E_CPU0_PE1_TX_DP<10>")
	)
	(segment
		(start 357.980234 -221.625414)
		(end 357.974646 -221.628462)
		(width 0.0889)
		(layer "In2.Cu")
		(net "P5E_CPU0_PE1_TX_DP<10>")
	)
	(segment
		(start 357.043482 -215.112346)
		(end 357.034592 -215.117426)
		(width 0.0889)
		(layer "In2.Cu")
		(net "P5E_CPU0_PE1_TX_DP<10>")
	)
	(segment
		(start 357.513636 -216.574878)
		(end 357.519732 -216.578434)
		(width 0.0889)
		(layer "In2.Cu")
		(net "P5E_CPU0_PE1_TX_DP<10>")
	)
	(segment
		(start 404.580344 -20.036028)
		(end 406.404826 -54.306216)
		(width 0.14732)
		(layer "In2.Cu")
		(net "P5E_CPU0_PE1_TX_DP<10>")
	)
	(segment
		(start 357.36784 -213.25332)
		(end 357.36784 -214.00897)
		(width 0.14732)
		(layer "In2.Cu")
		(net "P5E_CPU0_PE1_TX_DP<10>")
	)
	(segment
		(start 406.404826 -54.306216)
		(end 407.49474 -74.664824)
		(width 0.14732)
		(layer "In2.Cu")
		(net "P5E_CPU0_PE1_TX_DP<10>")
	)
	(segment
		(start 407.49474 -74.664824)
		(end 406.611836 -80.125824)
		(width 0.14732)
		(layer "In2.Cu")
		(net "P5E_CPU0_PE1_TX_DP<10>")
	)
	(segment
		(start 357.513636 -222.437198)
		(end 357.504746 -222.442278)
		(width 0.0889)
		(layer "In2.Cu")
		(net "P5E_CPU0_PE1_TX_DP<10>")
	)
	(segment
		(start 357.513636 -219.830396)
		(end 357.519732 -219.833952)
		(width 0.0889)
		(layer "In2.Cu")
		(net "P5E_CPU0_PE1_TX_DP<10>")
	)
	(segment
		(start 406.611836 -80.125824)
		(end 344.61704 -168.665398)
		(width 0.14732)
		(layer "In2.Cu")
		(net "P5E_CPU0_PE1_TX_DP<10>")
	)
	(arc
		(start 357.796084 -217.07856)
		(mid 357.716943 -217.353183)
		(end 357.513636 -217.554048)
		(width 0.0889)
		(layer "In2.Cu")
		(net "P5E_CPU0_PE1_TX_DP<10>")
	)
	(arc
		(start 358.265984 -224.389442)
		(mid 358.210629 -224.633629)
		(end 358.055164 -224.829878)
		(width 0.0889)
		(layer "In2.Cu")
		(net "P5E_CPU0_PE1_TX_DP<10>")
	)
	(arc
		(start 357.326184 -216.25052)
		(mid 357.373863 -216.43342)
		(end 357.504746 -216.569798)
		(width 0.0889)
		(layer "In2.Cu")
		(net "P5E_CPU0_PE1_TX_DP<10>")
	)
	(arc
		(start 357.326438 -217.888566)
		(mid 357.376453 -218.065697)
		(end 357.504746 -218.197684)
		(width 0.0889)
		(layer "In2.Cu")
		(net "P5E_CPU0_PE1_TX_DP<10>")
	)
	(arc
		(start 357.326438 -222.776288)
		(mid 357.377492 -222.950868)
		(end 357.504746 -223.080834)
		(width 0.0889)
		(layer "In2.Cu")
		(net "P5E_CPU0_PE1_TX_DP<10>")
	)
	(arc
		(start 356.856284 -215.421972)
		(mid 356.856087 -215.429337)
		(end 356.85603 -215.436704)
		(width 0.0889)
		(layer "In2.Cu")
		(net "P5E_CPU0_PE1_TX_DP<10>")
	)
	(arc
		(start 357.504746 -217.559128)
		(mid 357.377666 -217.689142)
		(end 357.326692 -217.863674)
		(width 0.0889)
		(layer "In2.Cu")
		(net "P5E_CPU0_PE1_TX_DP<10>")
	)
	(arc
		(start 358.055164 -224.829878)
		(mid 358.046718 -224.836563)
		(end 358.038146 -224.843086)
		(width 0.0889)
		(layer "In2.Cu")
		(net "P5E_CPU0_PE1_TX_DP<10>")
	)
	(arc
		(start 357.325676 -214.644732)
		(mid 357.244765 -214.91486)
		(end 357.043482 -215.112346)
		(width 0.0889)
		(layer "In2.Cu")
		(net "P5E_CPU0_PE1_TX_DP<10>")
	)
	(arc
		(start 357.034592 -215.117426)
		(mid 356.907338 -215.247392)
		(end 356.856284 -215.421972)
		(width 0.0889)
		(layer "In2.Cu")
		(net "P5E_CPU0_PE1_TX_DP<10>")
	)
	(arc
		(start 357.796084 -223.575626)
		(mid 357.843763 -223.758526)
		(end 357.974646 -223.894904)
		(width 0.0889)
		(layer "In2.Cu")
		(net "P5E_CPU0_PE1_TX_DP<10>")
	)
	(arc
		(start 357.519732 -218.20632)
		(mid 357.796058 -218.692222)
		(end 357.519732 -219.178124)
		(width 0.0889)
		(layer "In2.Cu")
		(net "P5E_CPU0_PE1_TX_DP<10>")
	)
	(arc
		(start 357.513636 -223.085914)
		(mid 357.716941 -223.28678)
		(end 357.796084 -223.561402)
		(width 0.0889)
		(layer "In2.Cu")
		(net "P5E_CPU0_PE1_TX_DP<10>")
	)
	(arc
		(start 357.983536 -220.644212)
		(mid 358.185822 -220.843193)
		(end 358.265984 -221.115382)
		(width 0.0889)
		(layer "In2.Cu")
		(net "P5E_CPU0_PE1_TX_DP<10>")
	)
	(arc
		(start 357.326184 -222.761556)
		(mid 357.326236 -222.768923)
		(end 357.326438 -222.776288)
		(width 0.0889)
		(layer "In2.Cu")
		(net "P5E_CPU0_PE1_TX_DP<10>")
	)
	(arc
		(start 357.504746 -222.442278)
		(mid 357.373832 -222.578638)
		(end 357.326184 -222.761556)
		(width 0.0889)
		(layer "In2.Cu")
		(net "P5E_CPU0_PE1_TX_DP<10>")
	)
	(arc
		(start 357.519732 -216.578434)
		(mid 357.722145 -216.784847)
		(end 357.796084 -217.064336)
		(width 0.0889)
		(layer "In2.Cu")
		(net "P5E_CPU0_PE1_TX_DP<10>")
	)
	(arc
		(start 357.519732 -219.833952)
		(mid 357.722145 -220.040365)
		(end 357.796084 -220.319854)
		(width 0.0889)
		(layer "In2.Cu")
		(net "P5E_CPU0_PE1_TX_DP<10>")
	)
	(arc
		(start 357.504746 -219.18676)
		(mid 357.32627 -219.506038)
		(end 357.504746 -219.825316)
		(width 0.0889)
		(layer "In2.Cu")
		(net "P5E_CPU0_PE1_TX_DP<10>")
	)
	(arc
		(start 358.265984 -221.14383)
		(mid 358.187873 -221.420779)
		(end 357.983536 -221.623382)
		(width 0.0889)
		(layer "In2.Cu")
		(net "P5E_CPU0_PE1_TX_DP<10>")
	)
	(arc
		(start 357.326692 -217.863674)
		(mid 357.326359 -217.876118)
		(end 357.326438 -217.888566)
		(width 0.0889)
		(layer "In2.Cu")
		(net "P5E_CPU0_PE1_TX_DP<10>")
	)
	(arc
		(start 356.85603 -215.436704)
		(mid 356.903709 -215.619604)
		(end 357.034592 -215.755982)
		(width 0.0889)
		(layer "In2.Cu")
		(net "P5E_CPU0_PE1_TX_DP<10>")
	)
	(arc
		(start 357.983536 -223.899984)
		(mid 358.187871 -224.102589)
		(end 358.265984 -224.379536)
		(width 0.0889)
		(layer "In2.Cu")
		(net "P5E_CPU0_PE1_TX_DP<10>")
	)
	(arc
		(start 357.796084 -221.94774)
		(mid 357.722168 -222.227242)
		(end 357.519732 -222.433642)
		(width 0.0889)
		(layer "In2.Cu")
		(net "P5E_CPU0_PE1_TX_DP<10>")
	)
	(arc
		(start 357.974646 -221.628462)
		(mid 357.843732 -221.764822)
		(end 357.796084 -221.94774)
		(width 0.0889)
		(layer "In2.Cu")
		(net "P5E_CPU0_PE1_TX_DP<10>")
	)
	(arc
		(start 357.796084 -220.319854)
		(mid 357.843763 -220.502754)
		(end 357.974646 -220.639132)
		(width 0.0889)
		(layer "In2.Cu")
		(net "P5E_CPU0_PE1_TX_DP<10>")
	)
	(arc
		(start 357.049578 -215.764618)
		(mid 357.252165 -215.970969)
		(end 357.326184 -216.25052)
		(width 0.0889)
		(layer "In2.Cu")
		(net "P5E_CPU0_PE1_TX_DP<10>")
	)
	(segment
		(start 367.568734 -225.203512)
		(end 367.56848 -225.203258)
		(width 0.13208)
		(layer "F.Cu")
		(net "P5E_CPU0_PE1_TX_DP<0>")
	)
	(segment
		(start 432.59248 -18.205958)
		(end 432.265836 -17.879314)
		(width 0.13208)
		(layer "F.Cu")
		(net "P5E_CPU0_PE1_TX_DP<0>")
	)
	(segment
		(start 367.568734 -225.739198)
		(end 367.568734 -225.203512)
		(width 0.13208)
		(layer "F.Cu")
		(net "P5E_CPU0_PE1_TX_DP<0>")
	)
	(segment
		(start 432.59248 -18.824194)
		(end 432.59248 -18.205958)
		(width 0.13208)
		(layer "F.Cu")
		(net "P5E_CPU0_PE1_TX_DP<0>")
	)
	(segment
		(start 432.291236 -19.125438)
		(end 432.59248 -18.824194)
		(width 0.13208)
		(layer "F.Cu")
		(net "P5E_CPU0_PE1_TX_DP<0>")
	)
	(segment
		(start 378.397516 -146.01063)
		(end 378.394976 -146.011138)
		(width 0.14732)
		(layer "In2.Cu")
		(net "P5E_CPU0_PE1_TX_DP<0>")
	)
	(segment
		(start 367.286032 -218.203018)
		(end 367.285016 -218.203526)
		(width 0.0889)
		(layer "In2.Cu")
		(net "P5E_CPU0_PE1_TX_DP<0>")
	)
	(segment
		(start 366.820196 -219.997782)
		(end 366.821212 -219.99829)
		(width 0.0889)
		(layer "In2.Cu")
		(net "P5E_CPU0_PE1_TX_DP<0>")
	)
	(segment
		(start 425.186856 -28.382722)
		(end 422.965372 -43.946064)
		(width 0.14732)
		(layer "In2.Cu")
		(net "P5E_CPU0_PE1_TX_DP<0>")
	)
	(segment
		(start 366.815878 -219.995242)
		(end 366.818418 -219.996766)
		(width 0.0889)
		(layer "In2.Cu")
		(net "P5E_CPU0_PE1_TX_DP<0>")
	)
	(segment
		(start 432.585876 -19.814286)
		(end 432.443128 -20.175982)
		(width 0.14732)
		(layer "In2.Cu")
		(net "P5E_CPU0_PE1_TX_DP<0>")
	)
	(segment
		(start 378.394976 -146.011138)
		(end 378.33046 -146.123914)
		(width 0.14732)
		(layer "In2.Cu")
		(net "P5E_CPU0_PE1_TX_DP<0>")
	)
	(segment
		(start 367.003584 -218.692222)
		(end 367.003584 -218.704668)
		(width 0.0889)
		(layer "In2.Cu")
		(net "P5E_CPU0_PE1_TX_DP<0>")
	)
	(segment
		(start 366.818418 -216.741248)
		(end 366.820196 -216.742264)
		(width 0.0889)
		(layer "In2.Cu")
		(net "P5E_CPU0_PE1_TX_DP<0>")
	)
	(segment
		(start 366.802924 -224.870772)
		(end 366.808512 -224.874074)
		(width 0.0889)
		(layer "In2.Cu")
		(net "P5E_CPU0_PE1_TX_DP<0>")
	)
	(segment
		(start 378.329698 -146.12493)
		(end 378.328936 -146.126454)
		(width 0.14732)
		(layer "In2.Cu")
		(net "P5E_CPU0_PE1_TX_DP<0>")
	)
	(segment
		(start 366.817402 -215.760808)
		(end 366.802924 -215.76919)
		(width 0.0889)
		(layer "In2.Cu")
		(net "P5E_CPU0_PE1_TX_DP<0>")
	)
	(segment
		(start 366.817402 -223.89973)
		(end 366.815624 -223.900492)
		(width 0.0889)
		(layer "In2.Cu")
		(net "P5E_CPU0_PE1_TX_DP<0>")
	)
	(segment
		(start 367.285016 -218.203526)
		(end 367.282222 -218.205304)
		(width 0.0889)
		(layer "In2.Cu")
		(net "P5E_CPU0_PE1_TX_DP<0>")
	)
	(segment
		(start 367.068354 -213.091776)
		(end 367.068354 -213.113874)
		(width 0.0889)
		(layer "In2.Cu")
		(net "P5E_CPU0_PE1_TX_DP<0>")
	)
	(segment
		(start 367.412016 -224.93224)
		(end 367.56848 -225.203258)
		(width 0.0889)
		(layer "In2.Cu")
		(net "P5E_CPU0_PE1_TX_DP<0>")
	)
	(segment
		(start 367.473738 -221.118938)
		(end 367.473738 -221.141798)
		(width 0.0889)
		(layer "In2.Cu")
		(net "P5E_CPU0_PE1_TX_DP<0>")
	)
	(segment
		(start 366.802924 -216.73185)
		(end 366.803686 -216.732358)
		(width 0.0889)
		(layer "In2.Cu")
		(net "P5E_CPU0_PE1_TX_DP<0>")
	)
	(segment
		(start 416.853624 -81.128362)
		(end 416.850322 -81.13014)
		(width 0.14732)
		(layer "In2.Cu")
		(net "P5E_CPU0_PE1_TX_DP<0>")
	)
	(segment
		(start 366.808512 -224.874074)
		(end 366.817402 -224.879154)
		(width 0.0889)
		(layer "In2.Cu")
		(net "P5E_CPU0_PE1_TX_DP<0>")
	)
	(segment
		(start 366.812576 -223.902524)
		(end 366.807496 -223.905318)
		(width 0.0889)
		(layer "In2.Cu")
		(net "P5E_CPU0_PE1_TX_DP<0>")
	)
	(segment
		(start 367.282222 -218.205304)
		(end 367.275618 -218.209114)
		(width 0.0889)
		(layer "In2.Cu")
		(net "P5E_CPU0_PE1_TX_DP<0>")
	)
	(segment
		(start 378.328936 -146.126454)
		(end 368.784378 -162.232848)
		(width 0.14732)
		(layer "In2.Cu")
		(net "P5E_CPU0_PE1_TX_DP<0>")
	)
	(segment
		(start 422.965372 -43.946064)
		(end 416.926268 -80.92948)
		(width 0.14732)
		(layer "In2.Cu")
		(net "P5E_CPU0_PE1_TX_DP<0>")
	)
	(segment
		(start 432.291236 -19.125438)
		(end 432.585876 -19.420078)
		(width 0.14732)
		(layer "In2.Cu")
		(net "P5E_CPU0_PE1_TX_DP<0>")
	)
	(segment
		(start 366.815624 -223.900492)
		(end 366.814608 -223.901254)
		(width 0.0889)
		(layer "In2.Cu")
		(net "P5E_CPU0_PE1_TX_DP<0>")
	)
	(segment
		(start 367.110264 -213.350602)
		(end 367.003584 -213.607904)
		(width 0.0889)
		(layer "In2.Cu")
		(net "P5E_CPU0_PE1_TX_DP<0>")
	)
	(segment
		(start 366.802924 -219.987368)
		(end 366.803686 -219.987876)
		(width 0.0889)
		(layer "In2.Cu")
		(net "P5E_CPU0_PE1_TX_DP<0>")
	)
	(segment
		(start 378.39904 -146.010376)
		(end 378.397516 -146.01063)
		(width 0.14732)
		(layer "In2.Cu")
		(net "P5E_CPU0_PE1_TX_DP<0>")
	)
	(segment
		(start 367.322862 -224.908872)
		(end 367.323116 -224.908618)
		(width 0.0889)
		(layer "In2.Cu")
		(net "P5E_CPU0_PE1_TX_DP<0>")
	)
	(segment
		(start 432.585876 -19.420078)
		(end 432.585876 -19.814286)
		(width 0.14732)
		(layer "In2.Cu")
		(net "P5E_CPU0_PE1_TX_DP<0>")
	)
	(segment
		(start 378.329952 -146.124676)
		(end 378.329698 -146.12493)
		(width 0.14732)
		(layer "In2.Cu")
		(net "P5E_CPU0_PE1_TX_DP<0>")
	)
	(segment
		(start 366.807496 -223.905318)
		(end 366.802924 -223.908112)
		(width 0.0889)
		(layer "In2.Cu")
		(net "P5E_CPU0_PE1_TX_DP<0>")
	)
	(segment
		(start 368.784378 -162.232848)
		(end 367.068354 -212.186012)
		(width 0.14732)
		(layer "In2.Cu")
		(net "P5E_CPU0_PE1_TX_DP<0>")
	)
	(segment
		(start 367.068354 -212.186012)
		(end 367.068354 -213.091776)
		(width 0.14732)
		(layer "In2.Cu")
		(net "P5E_CPU0_PE1_TX_DP<0>")
	)
	(segment
		(start 366.815878 -216.739724)
		(end 366.818418 -216.741248)
		(width 0.0889)
		(layer "In2.Cu")
		(net "P5E_CPU0_PE1_TX_DP<0>")
	)
	(segment
		(start 366.821212 -222.269558)
		(end 366.817402 -222.271844)
		(width 0.0889)
		(layer "In2.Cu")
		(net "P5E_CPU0_PE1_TX_DP<0>")
	)
	(segment
		(start 416.85464 -81.125822)
		(end 416.853624 -81.128362)
		(width 0.14732)
		(layer "In2.Cu")
		(net "P5E_CPU0_PE1_TX_DP<0>")
	)
	(segment
		(start 367.28654 -221.458282)
		(end 367.275872 -221.464632)
		(width 0.0889)
		(layer "In2.Cu")
		(net "P5E_CPU0_PE1_TX_DP<0>")
	)
	(segment
		(start 378.33046 -146.123914)
		(end 378.329952 -146.124676)
		(width 0.14732)
		(layer "In2.Cu")
		(net "P5E_CPU0_PE1_TX_DP<0>")
	)
	(segment
		(start 432.443128 -20.175982)
		(end 426.451014 -26.57729)
		(width 0.14732)
		(layer "In2.Cu")
		(net "P5E_CPU0_PE1_TX_DP<0>")
	)
	(segment
		(start 366.818418 -219.996766)
		(end 366.820196 -219.997782)
		(width 0.0889)
		(layer "In2.Cu")
		(net "P5E_CPU0_PE1_TX_DP<0>")
	)
	(segment
		(start 366.802924 -223.242886)
		(end 366.808512 -223.246188)
		(width 0.0889)
		(layer "In2.Cu")
		(net "P5E_CPU0_PE1_TX_DP<0>")
	)
	(segment
		(start 366.817402 -222.271844)
		(end 366.803178 -222.279972)
		(width 0.0889)
		(layer "In2.Cu")
		(net "P5E_CPU0_PE1_TX_DP<0>")
	)
	(segment
		(start 366.821212 -223.897444)
		(end 366.819688 -223.89846)
		(width 0.0889)
		(layer "In2.Cu")
		(net "P5E_CPU0_PE1_TX_DP<0>")
	)
	(segment
		(start 416.926268 -80.92948)
		(end 416.85464 -81.125822)
		(width 0.14732)
		(layer "In2.Cu")
		(net "P5E_CPU0_PE1_TX_DP<0>")
	)
	(segment
		(start 366.820196 -216.742264)
		(end 366.821212 -216.742772)
		(width 0.0889)
		(layer "In2.Cu")
		(net "P5E_CPU0_PE1_TX_DP<0>")
	)
	(segment
		(start 366.81664 -219.01658)
		(end 366.805972 -219.02293)
		(width 0.0889)
		(layer "In2.Cu")
		(net "P5E_CPU0_PE1_TX_DP<0>")
	)
	(segment
		(start 367.275872 -220.802962)
		(end 367.28654 -220.809312)
		(width 0.0889)
		(layer "In2.Cu")
		(net "P5E_CPU0_PE1_TX_DP<0>")
	)
	(segment
		(start 367.272824 -217.545666)
		(end 367.278412 -217.548968)
		(width 0.0889)
		(layer "In2.Cu")
		(net "P5E_CPU0_PE1_TX_DP<0>")
	)
	(segment
		(start 367.290604 -218.200224)
		(end 367.286032 -218.203018)
		(width 0.0889)
		(layer "In2.Cu")
		(net "P5E_CPU0_PE1_TX_DP<0>")
	)
	(segment
		(start 367.323116 -224.908618)
		(end 367.412016 -224.93224)
		(width 0.0889)
		(layer "In2.Cu")
		(net "P5E_CPU0_PE1_TX_DP<0>")
	)
	(segment
		(start 366.808512 -223.246188)
		(end 366.817402 -223.251268)
		(width 0.0889)
		(layer "In2.Cu")
		(net "P5E_CPU0_PE1_TX_DP<0>")
	)
	(segment
		(start 366.803178 -222.279972)
		(end 366.802924 -222.280226)
		(width 0.0889)
		(layer "In2.Cu")
		(net "P5E_CPU0_PE1_TX_DP<0>")
	)
	(segment
		(start 367.110264 -213.155784)
		(end 367.110264 -213.350602)
		(width 0.0889)
		(layer "In2.Cu")
		(net "P5E_CPU0_PE1_TX_DP<0>")
	)
	(segment
		(start 366.819688 -223.89846)
		(end 366.817402 -223.89973)
		(width 0.0889)
		(layer "In2.Cu")
		(net "P5E_CPU0_PE1_TX_DP<0>")
	)
	(segment
		(start 426.451014 -26.57729)
		(end 425.186856 -28.382722)
		(width 0.14732)
		(layer "In2.Cu")
		(net "P5E_CPU0_PE1_TX_DP<0>")
	)
	(segment
		(start 366.803686 -216.732358)
		(end 366.815878 -216.739724)
		(width 0.0889)
		(layer "In2.Cu")
		(net "P5E_CPU0_PE1_TX_DP<0>")
	)
	(segment
		(start 366.803686 -219.987876)
		(end 366.815878 -219.995242)
		(width 0.0889)
		(layer "In2.Cu")
		(net "P5E_CPU0_PE1_TX_DP<0>")
	)
	(segment
		(start 367.068354 -213.113874)
		(end 367.110264 -213.155784)
		(width 0.0889)
		(layer "In2.Cu")
		(net "P5E_CPU0_PE1_TX_DP<0>")
	)
	(segment
		(start 416.850322 -81.13014)
		(end 378.39904 -146.010376)
		(width 0.14732)
		(layer "In2.Cu")
		(net "P5E_CPU0_PE1_TX_DP<0>")
	)
	(segment
		(start 367.278412 -217.548968)
		(end 367.287302 -217.554048)
		(width 0.0889)
		(layer "In2.Cu")
		(net "P5E_CPU0_PE1_TX_DP<0>")
	)
	(segment
		(start 366.814608 -223.901254)
		(end 366.812576 -223.902524)
		(width 0.0889)
		(layer "In2.Cu")
		(net "P5E_CPU0_PE1_TX_DP<0>")
	)
	(segment
		(start 367.003584 -213.607904)
		(end 367.003584 -215.44915)
		(width 0.0889)
		(layer "In2.Cu")
		(net "P5E_CPU0_PE1_TX_DP<0>")
	)
	(arc
		(start 366.802924 -223.908112)
		(mid 366.533941 -224.389442)
		(end 366.802924 -224.870772)
		(width 0.0889)
		(layer "In2.Cu")
		(net "P5E_CPU0_PE1_TX_DP<0>")
	)
	(arc
		(start 367.28654 -220.809312)
		(mid 367.419917 -220.940072)
		(end 367.473738 -221.118938)
		(width 0.0889)
		(layer "In2.Cu")
		(net "P5E_CPU0_PE1_TX_DP<0>")
	)
	(arc
		(start 367.003584 -218.704668)
		(mid 366.950442 -218.884798)
		(end 366.81664 -219.01658)
		(width 0.0889)
		(layer "In2.Cu")
		(net "P5E_CPU0_PE1_TX_DP<0>")
	)
	(arc
		(start 367.003838 -217.064336)
		(mid 367.075646 -217.340032)
		(end 367.272824 -217.545666)
		(width 0.0889)
		(layer "In2.Cu")
		(net "P5E_CPU0_PE1_TX_DP<0>")
	)
	(arc
		(start 367.003838 -221.94774)
		(mid 366.955004 -222.132758)
		(end 366.821212 -222.269558)
		(width 0.0889)
		(layer "In2.Cu")
		(net "P5E_CPU0_PE1_TX_DP<0>")
	)
	(arc
		(start 366.821212 -216.742772)
		(mid 366.954923 -216.879472)
		(end 367.003838 -217.064336)
		(width 0.0889)
		(layer "In2.Cu")
		(net "P5E_CPU0_PE1_TX_DP<0>")
	)
	(arc
		(start 366.802924 -215.76919)
		(mid 366.533941 -216.25052)
		(end 366.802924 -216.73185)
		(width 0.0889)
		(layer "In2.Cu")
		(net "P5E_CPU0_PE1_TX_DP<0>")
	)
	(arc
		(start 366.802924 -222.280226)
		(mid 366.533941 -222.761556)
		(end 366.802924 -223.242886)
		(width 0.0889)
		(layer "In2.Cu")
		(net "P5E_CPU0_PE1_TX_DP<0>")
	)
	(arc
		(start 367.473738 -221.141798)
		(mid 367.4216 -221.324566)
		(end 367.28654 -221.458282)
		(width 0.0889)
		(layer "In2.Cu")
		(net "P5E_CPU0_PE1_TX_DP<0>")
	)
	(arc
		(start 367.287302 -217.554048)
		(mid 367.474 -217.876214)
		(end 367.290604 -218.200224)
		(width 0.0889)
		(layer "In2.Cu")
		(net "P5E_CPU0_PE1_TX_DP<0>")
	)
	(arc
		(start 366.817402 -223.251268)
		(mid 367.003846 -223.573215)
		(end 366.821212 -223.897444)
		(width 0.0889)
		(layer "In2.Cu")
		(net "P5E_CPU0_PE1_TX_DP<0>")
	)
	(arc
		(start 366.817402 -224.879154)
		(mid 367.066623 -224.953792)
		(end 367.322862 -224.908872)
		(width 0.0889)
		(layer "In2.Cu")
		(net "P5E_CPU0_PE1_TX_DP<0>")
	)
	(arc
		(start 367.003838 -220.319854)
		(mid 367.07653 -220.597059)
		(end 367.275872 -220.802962)
		(width 0.0889)
		(layer "In2.Cu")
		(net "P5E_CPU0_PE1_TX_DP<0>")
	)
	(arc
		(start 367.275618 -218.209114)
		(mid 367.076234 -218.414994)
		(end 367.003584 -218.692222)
		(width 0.0889)
		(layer "In2.Cu")
		(net "P5E_CPU0_PE1_TX_DP<0>")
	)
	(arc
		(start 367.275872 -221.464632)
		(mid 367.076488 -221.670512)
		(end 367.003838 -221.94774)
		(width 0.0889)
		(layer "In2.Cu")
		(net "P5E_CPU0_PE1_TX_DP<0>")
	)
	(arc
		(start 367.003584 -215.44915)
		(mid 366.950735 -215.629029)
		(end 366.817402 -215.760808)
		(width 0.0889)
		(layer "In2.Cu")
		(net "P5E_CPU0_PE1_TX_DP<0>")
	)
	(arc
		(start 366.821212 -219.99829)
		(mid 366.954923 -220.13499)
		(end 367.003838 -220.319854)
		(width 0.0889)
		(layer "In2.Cu")
		(net "P5E_CPU0_PE1_TX_DP<0>")
	)
	(arc
		(start 366.805972 -219.02293)
		(mid 366.534015 -219.504274)
		(end 366.802924 -219.987368)
		(width 0.0889)
		(layer "In2.Cu")
		(net "P5E_CPU0_PE1_TX_DP<0>")
	)
	(segment
		(start 407.365708 -16.68399)
		(end 407.694384 -16.355314)
		(width 0.13208)
		(layer "F.Cu")
		(net "P5E_CPU0_PE1_TX_DN<9>")
	)
	(segment
		(start 359.110534 -223.57588)
		(end 359.11028 -223.575626)
		(width 0.13208)
		(layer "F.Cu")
		(net "P5E_CPU0_PE1_TX_DN<9>")
	)
	(segment
		(start 407.668984 -17.601438)
		(end 407.365708 -17.298162)
		(width 0.13208)
		(layer "F.Cu")
		(net "P5E_CPU0_PE1_TX_DN<9>")
	)
	(segment
		(start 407.365708 -17.298162)
		(end 407.365708 -16.68399)
		(width 0.13208)
		(layer "F.Cu")
		(net "P5E_CPU0_PE1_TX_DN<9>")
	)
	(segment
		(start 359.110534 -224.111566)
		(end 359.110534 -223.57588)
		(width 0.13208)
		(layer "F.Cu")
		(net "P5E_CPU0_PE1_TX_DN<9>")
	)
	(segment
		(start 359.205784 -221.1197)
		(end 359.205784 -221.14383)
		(width 0.0889)
		(layer "In2.Cu")
		(net "P5E_CPU0_PE1_TX_DN<9>")
	)
	(segment
		(start 358.735884 -221.94774)
		(end 358.735884 -221.957646)
		(width 0.0889)
		(layer "In2.Cu")
		(net "P5E_CPU0_PE1_TX_DN<9>")
	)
	(segment
		(start 358.444546 -219.825316)
		(end 358.453436 -219.830396)
		(width 0.0889)
		(layer "In2.Cu")
		(net "P5E_CPU0_PE1_TX_DN<9>")
	)
	(segment
		(start 407.79065 -80.02143)
		(end 361.070398 -158.859728)
		(width 0.14732)
		(layer "In2.Cu")
		(net "P5E_CPU0_PE1_TX_DN<9>")
	)
	(segment
		(start 407.374344 -17.896078)
		(end 407.374344 -18.858738)
		(width 0.14732)
		(layer "In2.Cu")
		(net "P5E_CPU0_PE1_TX_DN<9>")
	)
	(segment
		(start 361.070398 -158.859728)
		(end 356.550722 -184.50306)
		(width 0.14732)
		(layer "In2.Cu")
		(net "P5E_CPU0_PE1_TX_DN<9>")
	)
	(segment
		(start 407.374344 -19.516598)
		(end 407.374344 -19.884898)
		(width 0.14732)
		(layer "In2.Cu")
		(net "P5E_CPU0_PE1_TX_DN<9>")
	)
	(segment
		(start 358.73563 -215.414606)
		(end 358.73563 -215.452198)
		(width 0.0889)
		(layer "In2.Cu")
		(net "P5E_CPU0_PE1_TX_DN<9>")
	)
	(segment
		(start 407.519124 -20.397978)
		(end 407.374344 -20.542758)
		(width 0.14732)
		(layer "In2.Cu")
		(net "P5E_CPU0_PE1_TX_DN<9>")
	)
	(segment
		(start 409.210002 -71.643748)
		(end 407.79065 -80.02143)
		(width 0.14732)
		(layer "In2.Cu")
		(net "P5E_CPU0_PE1_TX_DN<9>")
	)
	(segment
		(start 358.465628 -219.174568)
		(end 358.453436 -219.18168)
		(width 0.0889)
		(layer "In2.Cu")
		(net "P5E_CPU0_PE1_TX_DN<9>")
	)
	(segment
		(start 358.30764 -212.747606)
		(end 358.30764 -214.00897)
		(width 0.14732)
		(layer "In2.Cu")
		(net "P5E_CPU0_PE1_TX_DN<9>")
	)
	(segment
		(start 358.453436 -219.18168)
		(end 358.444546 -219.18676)
		(width 0.0889)
		(layer "In2.Cu")
		(net "P5E_CPU0_PE1_TX_DN<9>")
	)
	(segment
		(start 358.875838 -223.867472)
		(end 358.953816 -223.846644)
		(width 0.0889)
		(layer "In2.Cu")
		(net "P5E_CPU0_PE1_TX_DN<9>")
	)
	(segment
		(start 358.265984 -216.25052)
		(end 358.265984 -216.257124)
		(width 0.0889)
		(layer "In2.Cu")
		(net "P5E_CPU0_PE1_TX_DN<9>")
	)
	(segment
		(start 358.265476 -214.622634)
		(end 358.265984 -214.622634)
		(width 0.0889)
		(layer "In2.Cu")
		(net "P5E_CPU0_PE1_TX_DN<9>")
	)
	(segment
		(start 358.444546 -223.080834)
		(end 358.453436 -223.085914)
		(width 0.0889)
		(layer "In2.Cu")
		(net "P5E_CPU0_PE1_TX_DN<9>")
	)
	(segment
		(start 358.453436 -218.202764)
		(end 358.457246 -218.20505)
		(width 0.0889)
		(layer "In2.Cu")
		(net "P5E_CPU0_PE1_TX_DN<9>")
	)
	(segment
		(start 407.668984 -17.601438)
		(end 407.374344 -17.896078)
		(width 0.14732)
		(layer "In2.Cu")
		(net "P5E_CPU0_PE1_TX_DN<9>")
	)
	(segment
		(start 358.265476 -214.073232)
		(end 358.265476 -214.622634)
		(width 0.0889)
		(layer "In2.Cu")
		(net "P5E_CPU0_PE1_TX_DN<9>")
	)
	(segment
		(start 358.444546 -218.197684)
		(end 358.453436 -218.202764)
		(width 0.0889)
		(layer "In2.Cu")
		(net "P5E_CPU0_PE1_TX_DN<9>")
	)
	(segment
		(start 358.735884 -220.309948)
		(end 358.735884 -220.32849)
		(width 0.0889)
		(layer "In2.Cu")
		(net "P5E_CPU0_PE1_TX_DN<9>")
	)
	(segment
		(start 407.374344 -18.858738)
		(end 407.519124 -19.003518)
		(width 0.14732)
		(layer "In2.Cu")
		(net "P5E_CPU0_PE1_TX_DN<9>")
	)
	(segment
		(start 358.735884 -223.557084)
		(end 358.735884 -223.584262)
		(width 0.0889)
		(layer "In2.Cu")
		(net "P5E_CPU0_PE1_TX_DN<9>")
	)
	(segment
		(start 358.923336 -221.623382)
		(end 358.914446 -221.628462)
		(width 0.0889)
		(layer "In2.Cu")
		(net "P5E_CPU0_PE1_TX_DN<9>")
	)
	(segment
		(start 407.519124 -20.029678)
		(end 407.519124 -20.397978)
		(width 0.14732)
		(layer "In2.Cu")
		(net "P5E_CPU0_PE1_TX_DN<9>")
	)
	(segment
		(start 358.45242 -215.92667)
		(end 358.444546 -215.931242)
		(width 0.0889)
		(layer "In2.Cu")
		(net "P5E_CPU0_PE1_TX_DN<9>")
	)
	(segment
		(start 358.457246 -218.20505)
		(end 358.465628 -218.209876)
		(width 0.0889)
		(layer "In2.Cu")
		(net "P5E_CPU0_PE1_TX_DN<9>")
	)
	(segment
		(start 358.453436 -222.437198)
		(end 358.444546 -222.442278)
		(width 0.0889)
		(layer "In2.Cu")
		(net "P5E_CPU0_PE1_TX_DN<9>")
	)
	(segment
		(start 358.453436 -217.554048)
		(end 358.444546 -217.559128)
		(width 0.0889)
		(layer "In2.Cu")
		(net "P5E_CPU0_PE1_TX_DN<9>")
	)
	(segment
		(start 356.550722 -184.50306)
		(end 358.30764 -212.747606)
		(width 0.14732)
		(layer "In2.Cu")
		(net "P5E_CPU0_PE1_TX_DN<9>")
	)
	(segment
		(start 358.735884 -217.05443)
		(end 358.735884 -217.082878)
		(width 0.0889)
		(layer "In2.Cu")
		(net "P5E_CPU0_PE1_TX_DN<9>")
	)
	(segment
		(start 407.374344 -21.132292)
		(end 409.210002 -71.643748)
		(width 0.14732)
		(layer "In2.Cu")
		(net "P5E_CPU0_PE1_TX_DN<9>")
	)
	(segment
		(start 358.30764 -214.00897)
		(end 358.30764 -214.031068)
		(width 0.0889)
		(layer "In2.Cu")
		(net "P5E_CPU0_PE1_TX_DN<9>")
	)
	(segment
		(start 407.374344 -19.884898)
		(end 407.519124 -20.029678)
		(width 0.14732)
		(layer "In2.Cu")
		(net "P5E_CPU0_PE1_TX_DN<9>")
	)
	(segment
		(start 358.444546 -216.569798)
		(end 358.453436 -216.574878)
		(width 0.0889)
		(layer "In2.Cu")
		(net "P5E_CPU0_PE1_TX_DN<9>")
	)
	(segment
		(start 407.519124 -19.371818)
		(end 407.374344 -19.516598)
		(width 0.14732)
		(layer "In2.Cu")
		(net "P5E_CPU0_PE1_TX_DN<9>")
	)
	(segment
		(start 358.953816 -223.846644)
		(end 359.11028 -223.575626)
		(width 0.0889)
		(layer "In2.Cu")
		(net "P5E_CPU0_PE1_TX_DN<9>")
	)
	(segment
		(start 407.374344 -20.542758)
		(end 407.374344 -21.132292)
		(width 0.14732)
		(layer "In2.Cu")
		(net "P5E_CPU0_PE1_TX_DN<9>")
	)
	(segment
		(start 407.519124 -19.003518)
		(end 407.519124 -19.371818)
		(width 0.14732)
		(layer "In2.Cu")
		(net "P5E_CPU0_PE1_TX_DN<9>")
	)
	(segment
		(start 358.30764 -214.031068)
		(end 358.265476 -214.073232)
		(width 0.0889)
		(layer "In2.Cu")
		(net "P5E_CPU0_PE1_TX_DN<9>")
	)
	(segment
		(start 358.444546 -214.941912)
		(end 358.453436 -214.946992)
		(width 0.0889)
		(layer "In2.Cu")
		(net "P5E_CPU0_PE1_TX_DN<9>")
	)
	(segment
		(start 358.453436 -215.926162)
		(end 358.45242 -215.92667)
		(width 0.0889)
		(layer "In2.Cu")
		(net "P5E_CPU0_PE1_TX_DN<9>")
	)
	(arc
		(start 358.735884 -221.957646)
		(mid 358.657773 -222.234595)
		(end 358.453436 -222.437198)
		(width 0.0889)
		(layer "In2.Cu")
		(net "P5E_CPU0_PE1_TX_DN<9>")
	)
	(arc
		(start 358.266238 -217.866214)
		(mid 358.265993 -217.87561)
		(end 358.265984 -217.88501)
		(width 0.0889)
		(layer "In2.Cu")
		(net "P5E_CPU0_PE1_TX_DN<9>")
	)
	(arc
		(start 359.205784 -221.14383)
		(mid 359.127673 -221.420779)
		(end 358.923336 -221.623382)
		(width 0.0889)
		(layer "In2.Cu")
		(net "P5E_CPU0_PE1_TX_DN<9>")
	)
	(arc
		(start 358.444546 -219.18676)
		(mid 358.265949 -219.506038)
		(end 358.444546 -219.825316)
		(width 0.0889)
		(layer "In2.Cu")
		(net "P5E_CPU0_PE1_TX_DN<9>")
	)
	(arc
		(start 358.735884 -217.082878)
		(mid 358.655722 -217.355067)
		(end 358.453436 -217.554048)
		(width 0.0889)
		(layer "In2.Cu")
		(net "P5E_CPU0_PE1_TX_DN<9>")
	)
	(arc
		(start 358.735884 -223.584262)
		(mid 358.774558 -223.74133)
		(end 358.875838 -223.867472)
		(width 0.0889)
		(layer "In2.Cu")
		(net "P5E_CPU0_PE1_TX_DN<9>")
	)
	(arc
		(start 358.265984 -217.88501)
		(mid 358.315237 -218.06421)
		(end 358.444546 -218.197684)
		(width 0.0889)
		(layer "In2.Cu")
		(net "P5E_CPU0_PE1_TX_DN<9>")
	)
	(arc
		(start 358.453436 -219.830396)
		(mid 358.657771 -220.033001)
		(end 358.735884 -220.309948)
		(width 0.0889)
		(layer "In2.Cu")
		(net "P5E_CPU0_PE1_TX_DN<9>")
	)
	(arc
		(start 358.444546 -222.442278)
		(mid 358.315257 -222.575764)
		(end 358.265984 -222.754952)
		(width 0.0889)
		(layer "In2.Cu")
		(net "P5E_CPU0_PE1_TX_DN<9>")
	)
	(arc
		(start 358.444546 -215.931242)
		(mid 358.313632 -216.067602)
		(end 358.265984 -216.25052)
		(width 0.0889)
		(layer "In2.Cu")
		(net "P5E_CPU0_PE1_TX_DN<9>")
	)
	(arc
		(start 358.465628 -218.209876)
		(mid 358.736084 -218.692222)
		(end 358.465628 -219.174568)
		(width 0.0889)
		(layer "In2.Cu")
		(net "P5E_CPU0_PE1_TX_DN<9>")
	)
	(arc
		(start 358.265984 -216.257124)
		(mid 358.315237 -216.436324)
		(end 358.444546 -216.569798)
		(width 0.0889)
		(layer "In2.Cu")
		(net "P5E_CPU0_PE1_TX_DN<9>")
	)
	(arc
		(start 358.453436 -223.085914)
		(mid 358.655722 -223.284895)
		(end 358.735884 -223.557084)
		(width 0.0889)
		(layer "In2.Cu")
		(net "P5E_CPU0_PE1_TX_DN<9>")
	)
	(arc
		(start 358.265984 -222.754952)
		(mid 358.265994 -222.764352)
		(end 358.266238 -222.773748)
		(width 0.0889)
		(layer "In2.Cu")
		(net "P5E_CPU0_PE1_TX_DN<9>")
	)
	(arc
		(start 358.923082 -220.644212)
		(mid 359.126563 -220.845016)
		(end 359.205784 -221.1197)
		(width 0.0889)
		(layer "In2.Cu")
		(net "P5E_CPU0_PE1_TX_DN<9>")
	)
	(arc
		(start 358.73563 -215.452198)
		(mid 358.65626 -215.725932)
		(end 358.453436 -215.926162)
		(width 0.0889)
		(layer "In2.Cu")
		(net "P5E_CPU0_PE1_TX_DN<9>")
	)
	(arc
		(start 358.914446 -221.628462)
		(mid 358.783532 -221.764822)
		(end 358.735884 -221.94774)
		(width 0.0889)
		(layer "In2.Cu")
		(net "P5E_CPU0_PE1_TX_DN<9>")
	)
	(arc
		(start 358.453436 -214.946992)
		(mid 358.654718 -215.144479)
		(end 358.73563 -215.414606)
		(width 0.0889)
		(layer "In2.Cu")
		(net "P5E_CPU0_PE1_TX_DN<9>")
	)
	(arc
		(start 358.266238 -222.773748)
		(mid 358.316731 -222.949726)
		(end 358.444546 -223.080834)
		(width 0.0889)
		(layer "In2.Cu")
		(net "P5E_CPU0_PE1_TX_DN<9>")
	)
	(arc
		(start 358.265984 -214.622634)
		(mid 358.313663 -214.805534)
		(end 358.444546 -214.941912)
		(width 0.0889)
		(layer "In2.Cu")
		(net "P5E_CPU0_PE1_TX_DN<9>")
	)
	(arc
		(start 358.735884 -220.32849)
		(mid 358.788154 -220.510855)
		(end 358.923082 -220.644212)
		(width 0.0889)
		(layer "In2.Cu")
		(net "P5E_CPU0_PE1_TX_DN<9>")
	)
	(arc
		(start 358.444546 -217.559128)
		(mid 358.316653 -217.69019)
		(end 358.266238 -217.866214)
		(width 0.0889)
		(layer "In2.Cu")
		(net "P5E_CPU0_PE1_TX_DN<9>")
	)
	(arc
		(start 358.453436 -216.574878)
		(mid 358.657771 -216.777483)
		(end 358.735884 -217.05443)
		(width 0.0889)
		(layer "In2.Cu")
		(net "P5E_CPU0_PE1_TX_DN<9>")
	)
	(segment
		(start 409.900628 -18.205958)
		(end 409.573984 -17.879314)
		(width 0.13208)
		(layer "F.Cu")
		(net "P5E_CPU0_PE1_TX_DN<8>")
	)
	(segment
		(start 359.58018 -224.389696)
		(end 359.580434 -224.389442)
		(width 0.13208)
		(layer "F.Cu")
		(net "P5E_CPU0_PE1_TX_DN<8>")
	)
	(segment
		(start 359.58018 -224.925382)
		(end 359.58018 -224.389696)
		(width 0.13208)
		(layer "F.Cu")
		(net "P5E_CPU0_PE1_TX_DN<8>")
	)
	(segment
		(start 409.599384 -19.125438)
		(end 409.900628 -18.824194)
		(width 0.13208)
		(layer "F.Cu")
		(net "P5E_CPU0_PE1_TX_DN<8>")
	)
	(segment
		(start 409.900628 -18.824194)
		(end 409.900628 -18.205958)
		(width 0.13208)
		(layer "F.Cu")
		(net "P5E_CPU0_PE1_TX_DN<8>")
	)
	(segment
		(start 357.232966 -184.40908)
		(end 358.972866 -212.823552)
		(width 0.14732)
		(layer "In2.Cu")
		(net "P5E_CPU0_PE1_TX_DN<8>")
	)
	(segment
		(start 359.297478 -215.112346)
		(end 359.306368 -215.117426)
		(width 0.0889)
		(layer "In2.Cu")
		(net "P5E_CPU0_PE1_TX_DN<8>")
	)
	(segment
		(start 359.297478 -223.251268)
		(end 359.306368 -223.256348)
		(width 0.0889)
		(layer "In2.Cu")
		(net "P5E_CPU0_PE1_TX_DN<8>")
	)
	(segment
		(start 359.306622 -217.383614)
		(end 359.297732 -217.388694)
		(width 0.0889)
		(layer "In2.Cu")
		(net "P5E_CPU0_PE1_TX_DN<8>")
	)
	(segment
		(start 409.894786 -19.42084)
		(end 409.894786 -20.587208)
		(width 0.14732)
		(layer "In2.Cu")
		(net "P5E_CPU0_PE1_TX_DN<8>")
	)
	(segment
		(start 359.765092 -224.06356)
		(end 359.765854 -224.064068)
		(width 0.0889)
		(layer "In2.Cu")
		(net "P5E_CPU0_PE1_TX_DN<8>")
	)
	(segment
		(start 359.736898 -224.66046)
		(end 359.580434 -224.389442)
		(width 0.0889)
		(layer "In2.Cu")
		(net "P5E_CPU0_PE1_TX_DN<8>")
	)
	(segment
		(start 359.769156 -221.45752)
		(end 359.761536 -221.461838)
		(width 0.0889)
		(layer "In2.Cu")
		(net "P5E_CPU0_PE1_TX_DN<8>")
	)
	(segment
		(start 359.261664 -219.97416)
		(end 359.306368 -220.000576)
		(width 0.0889)
		(layer "In2.Cu")
		(net "P5E_CPU0_PE1_TX_DN<8>")
	)
	(segment
		(start 359.297732 -216.739978)
		(end 359.306622 -216.745058)
		(width 0.0889)
		(layer "In2.Cu")
		(net "P5E_CPU0_PE1_TX_DN<8>")
	)
	(segment
		(start 409.01366 -79.299308)
		(end 361.681014 -159.17164)
		(width 0.14732)
		(layer "In2.Cu")
		(net "P5E_CPU0_PE1_TX_DN<8>")
	)
	(segment
		(start 361.681014 -159.17164)
		(end 357.232966 -184.40908)
		(width 0.14732)
		(layer "In2.Cu")
		(net "P5E_CPU0_PE1_TX_DN<8>")
	)
	(segment
		(start 409.599384 -19.125438)
		(end 409.894786 -19.42084)
		(width 0.14732)
		(layer "In2.Cu")
		(net "P5E_CPU0_PE1_TX_DN<8>")
	)
	(segment
		(start 409.760674 -21.748242)
		(end 409.906978 -21.891752)
		(width 0.14732)
		(layer "In2.Cu")
		(net "P5E_CPU0_PE1_TX_DN<8>")
	)
	(segment
		(start 359.765854 -224.064068)
		(end 359.776522 -224.070164)
		(width 0.0889)
		(layer "In2.Cu")
		(net "P5E_CPU0_PE1_TX_DN<8>")
	)
	(segment
		(start 409.894786 -20.587208)
		(end 409.900628 -21.233638)
		(width 0.14732)
		(layer "In2.Cu")
		(net "P5E_CPU0_PE1_TX_DN<8>")
	)
	(segment
		(start 409.775152 -23.309834)
		(end 409.921202 -23.45309)
		(width 0.14732)
		(layer "In2.Cu")
		(net "P5E_CPU0_PE1_TX_DN<8>")
	)
	(segment
		(start 358.972866 -214.00897)
		(end 358.972866 -214.031068)
		(width 0.0889)
		(layer "In2.Cu")
		(net "P5E_CPU0_PE1_TX_DN<8>")
	)
	(segment
		(start 409.757118 -21.379688)
		(end 409.760674 -21.748242)
		(width 0.14732)
		(layer "In2.Cu")
		(net "P5E_CPU0_PE1_TX_DN<8>")
	)
	(segment
		(start 359.29189 -218.364308)
		(end 359.297224 -218.367356)
		(width 0.0889)
		(layer "In2.Cu")
		(net "P5E_CPU0_PE1_TX_DN<8>")
	)
	(segment
		(start 358.972866 -212.823552)
		(end 358.972866 -214.00897)
		(width 0.14732)
		(layer "In2.Cu")
		(net "P5E_CPU0_PE1_TX_DN<8>")
	)
	(segment
		(start 359.767632 -220.809566)
		(end 359.768394 -220.810074)
		(width 0.0889)
		(layer "In2.Cu")
		(net "P5E_CPU0_PE1_TX_DN<8>")
	)
	(segment
		(start 359.297986 -219.01658)
		(end 359.294176 -219.018866)
		(width 0.0889)
		(layer "In2.Cu")
		(net "P5E_CPU0_PE1_TX_DN<8>")
	)
	(segment
		(start 409.77185 -22.94128)
		(end 409.775152 -23.309834)
		(width 0.14732)
		(layer "In2.Cu")
		(net "P5E_CPU0_PE1_TX_DN<8>")
	)
	(segment
		(start 359.48493 -220.319854)
		(end 359.48493 -220.327474)
		(width 0.0889)
		(layer "In2.Cu")
		(net "P5E_CPU0_PE1_TX_DN<8>")
	)
	(segment
		(start 409.906978 -21.891752)
		(end 409.915106 -22.79523)
		(width 0.14732)
		(layer "In2.Cu")
		(net "P5E_CPU0_PE1_TX_DN<8>")
	)
	(segment
		(start 359.014776 -214.072978)
		(end 359.014776 -214.636858)
		(width 0.0889)
		(layer "In2.Cu")
		(net "P5E_CPU0_PE1_TX_DN<8>")
	)
	(segment
		(start 359.306368 -215.755982)
		(end 359.297478 -215.761062)
		(width 0.0889)
		(layer "In2.Cu")
		(net "P5E_CPU0_PE1_TX_DN<8>")
	)
	(segment
		(start 359.776522 -221.453202)
		(end 359.769156 -221.45752)
		(width 0.0889)
		(layer "In2.Cu")
		(net "P5E_CPU0_PE1_TX_DN<8>")
	)
	(segment
		(start 359.81513 -224.681288)
		(end 359.736898 -224.66046)
		(width 0.0889)
		(layer "In2.Cu")
		(net "P5E_CPU0_PE1_TX_DN<8>")
	)
	(segment
		(start 359.294176 -219.018866)
		(end 359.29189 -219.020136)
		(width 0.0889)
		(layer "In2.Cu")
		(net "P5E_CPU0_PE1_TX_DN<8>")
	)
	(segment
		(start 409.915106 -22.79523)
		(end 409.77185 -22.94128)
		(width 0.14732)
		(layer "In2.Cu")
		(net "P5E_CPU0_PE1_TX_DN<8>")
	)
	(segment
		(start 359.768394 -220.810074)
		(end 359.776522 -220.814646)
		(width 0.0889)
		(layer "In2.Cu")
		(net "P5E_CPU0_PE1_TX_DN<8>")
	)
	(segment
		(start 359.297224 -218.367356)
		(end 359.297986 -218.367864)
		(width 0.0889)
		(layer "In2.Cu")
		(net "P5E_CPU0_PE1_TX_DN<8>")
	)
	(segment
		(start 359.015284 -219.506038)
		(end 359.015538 -219.54236)
		(width 0.0889)
		(layer "In2.Cu")
		(net "P5E_CPU0_PE1_TX_DN<8>")
	)
	(segment
		(start 359.015284 -222.75165)
		(end 359.015284 -222.783654)
		(width 0.0889)
		(layer "In2.Cu")
		(net "P5E_CPU0_PE1_TX_DN<8>")
	)
	(segment
		(start 409.900628 -21.233638)
		(end 409.757118 -21.379688)
		(width 0.14732)
		(layer "In2.Cu")
		(net "P5E_CPU0_PE1_TX_DN<8>")
	)
	(segment
		(start 358.972866 -214.031068)
		(end 359.014776 -214.072978)
		(width 0.0889)
		(layer "In2.Cu")
		(net "P5E_CPU0_PE1_TX_DN<8>")
	)
	(segment
		(start 410.364686 -71.62165)
		(end 409.01366 -79.299308)
		(width 0.14732)
		(layer "In2.Cu")
		(net "P5E_CPU0_PE1_TX_DN<8>")
	)
	(segment
		(start 359.48493 -221.94774)
		(end 359.48493 -221.956376)
		(width 0.0889)
		(layer "In2.Cu")
		(net "P5E_CPU0_PE1_TX_DN<8>")
	)
	(segment
		(start 409.921202 -23.45309)
		(end 410.364686 -71.62165)
		(width 0.14732)
		(layer "In2.Cu")
		(net "P5E_CPU0_PE1_TX_DN<8>")
	)
	(segment
		(start 359.75544 -224.057972)
		(end 359.765092 -224.06356)
		(width 0.0889)
		(layer "In2.Cu")
		(net "P5E_CPU0_PE1_TX_DN<8>")
	)
	(arc
		(start 359.484676 -215.447118)
		(mid 359.434604 -215.624108)
		(end 359.306368 -215.755982)
		(width 0.0889)
		(layer "In2.Cu")
		(net "P5E_CPU0_PE1_TX_DN<8>")
	)
	(arc
		(start 359.485184 -217.057732)
		(mid 359.485174 -217.067132)
		(end 359.48493 -217.076528)
		(width 0.0889)
		(layer "In2.Cu")
		(net "P5E_CPU0_PE1_TX_DN<8>")
	)
	(arc
		(start 359.306368 -215.117426)
		(mid 359.434878 -215.249728)
		(end 359.484676 -215.427306)
		(width 0.0889)
		(layer "In2.Cu")
		(net "P5E_CPU0_PE1_TX_DN<8>")
	)
	(arc
		(start 359.015538 -219.54236)
		(mid 359.081203 -219.790987)
		(end 359.261664 -219.97416)
		(width 0.0889)
		(layer "In2.Cu")
		(net "P5E_CPU0_PE1_TX_DN<8>")
	)
	(arc
		(start 359.297986 -218.367864)
		(mid 359.485289 -218.692222)
		(end 359.297986 -219.01658)
		(width 0.0889)
		(layer "In2.Cu")
		(net "P5E_CPU0_PE1_TX_DN<8>")
	)
	(arc
		(start 359.015284 -216.260426)
		(mid 359.093395 -216.537375)
		(end 359.297732 -216.739978)
		(width 0.0889)
		(layer "In2.Cu")
		(net "P5E_CPU0_PE1_TX_DN<8>")
	)
	(arc
		(start 359.48493 -220.327474)
		(mid 359.562559 -220.605887)
		(end 359.767632 -220.809566)
		(width 0.0889)
		(layer "In2.Cu")
		(net "P5E_CPU0_PE1_TX_DN<8>")
	)
	(arc
		(start 359.297732 -217.388694)
		(mid 359.015083 -217.874797)
		(end 359.29189 -218.364308)
		(width 0.0889)
		(layer "In2.Cu")
		(net "P5E_CPU0_PE1_TX_DN<8>")
	)
	(arc
		(start 359.761536 -221.461838)
		(mid 359.558949 -221.668189)
		(end 359.48493 -221.94774)
		(width 0.0889)
		(layer "In2.Cu")
		(net "P5E_CPU0_PE1_TX_DN<8>")
	)
	(arc
		(start 359.48493 -223.575626)
		(mid 359.557165 -223.85215)
		(end 359.75544 -224.057972)
		(width 0.0889)
		(layer "In2.Cu")
		(net "P5E_CPU0_PE1_TX_DN<8>")
	)
	(arc
		(start 359.306368 -223.256348)
		(mid 359.437282 -223.392708)
		(end 359.48493 -223.575626)
		(width 0.0889)
		(layer "In2.Cu")
		(net "P5E_CPU0_PE1_TX_DN<8>")
	)
	(arc
		(start 359.297732 -222.272098)
		(mid 359.093397 -222.474703)
		(end 359.015284 -222.75165)
		(width 0.0889)
		(layer "In2.Cu")
		(net "P5E_CPU0_PE1_TX_DN<8>")
	)
	(arc
		(start 359.306368 -220.000576)
		(mid 359.437282 -220.136936)
		(end 359.48493 -220.319854)
		(width 0.0889)
		(layer "In2.Cu")
		(net "P5E_CPU0_PE1_TX_DN<8>")
	)
	(arc
		(start 359.306622 -216.745058)
		(mid 359.435911 -216.878544)
		(end 359.485184 -217.057732)
		(width 0.0889)
		(layer "In2.Cu")
		(net "P5E_CPU0_PE1_TX_DN<8>")
	)
	(arc
		(start 359.776522 -224.070164)
		(mid 359.954491 -224.365755)
		(end 359.81513 -224.681288)
		(width 0.0889)
		(layer "In2.Cu")
		(net "P5E_CPU0_PE1_TX_DN<8>")
	)
	(arc
		(start 359.48493 -221.956376)
		(mid 359.43266 -222.138741)
		(end 359.297732 -222.272098)
		(width 0.0889)
		(layer "In2.Cu")
		(net "P5E_CPU0_PE1_TX_DN<8>")
	)
	(arc
		(start 359.015284 -222.783654)
		(mid 359.096195 -223.053782)
		(end 359.297478 -223.251268)
		(width 0.0889)
		(layer "In2.Cu")
		(net "P5E_CPU0_PE1_TX_DN<8>")
	)
	(arc
		(start 359.29189 -219.020136)
		(mid 359.089303 -219.226487)
		(end 359.015284 -219.506038)
		(width 0.0889)
		(layer "In2.Cu")
		(net "P5E_CPU0_PE1_TX_DN<8>")
	)
	(arc
		(start 359.297478 -215.761062)
		(mid 359.09459 -215.961402)
		(end 359.015284 -216.23528)
		(width 0.0889)
		(layer "In2.Cu")
		(net "P5E_CPU0_PE1_TX_DN<8>")
	)
	(arc
		(start 359.015284 -216.23528)
		(mid 359.015141 -216.247853)
		(end 359.015284 -216.260426)
		(width 0.0889)
		(layer "In2.Cu")
		(net "P5E_CPU0_PE1_TX_DN<8>")
	)
	(arc
		(start 359.776522 -220.814646)
		(mid 359.955119 -221.133924)
		(end 359.776522 -221.453202)
		(width 0.0889)
		(layer "In2.Cu")
		(net "P5E_CPU0_PE1_TX_DN<8>")
	)
	(arc
		(start 359.014776 -214.636858)
		(mid 359.093995 -214.911543)
		(end 359.297478 -215.112346)
		(width 0.0889)
		(layer "In2.Cu")
		(net "P5E_CPU0_PE1_TX_DN<8>")
	)
	(arc
		(start 359.484676 -215.427306)
		(mid 359.484807 -215.437212)
		(end 359.484676 -215.447118)
		(width 0.0889)
		(layer "In2.Cu")
		(net "P5E_CPU0_PE1_TX_DN<8>")
	)
	(arc
		(start 359.48493 -217.076528)
		(mid 359.434437 -217.252506)
		(end 359.306622 -217.383614)
		(width 0.0889)
		(layer "In2.Cu")
		(net "P5E_CPU0_PE1_TX_DN<8>")
	)
	(segment
		(start 412.953708 -16.68399)
		(end 413.282384 -16.355314)
		(width 0.13208)
		(layer "F.Cu")
		(net "P5E_CPU0_PE1_TX_DN<7>")
	)
	(segment
		(start 413.256984 -17.601438)
		(end 412.953708 -17.298162)
		(width 0.13208)
		(layer "F.Cu")
		(net "P5E_CPU0_PE1_TX_DN<7>")
	)
	(segment
		(start 412.953708 -17.298162)
		(end 412.953708 -16.68399)
		(width 0.13208)
		(layer "F.Cu")
		(net "P5E_CPU0_PE1_TX_DN<7>")
	)
	(segment
		(start 360.990134 -223.57588)
		(end 360.98988 -223.575626)
		(width 0.13208)
		(layer "F.Cu")
		(net "P5E_CPU0_PE1_TX_DN<7>")
	)
	(segment
		(start 360.990134 -224.111566)
		(end 360.990134 -223.57588)
		(width 0.13208)
		(layer "F.Cu")
		(net "P5E_CPU0_PE1_TX_DN<7>")
	)
	(segment
		(start 411.867858 -70.48881)
		(end 411.7213 -71.816214)
		(width 0.14732)
		(layer "In2.Cu")
		(net "P5E_CPU0_PE1_TX_DN<7>")
	)
	(segment
		(start 413.09925 -20.926552)
		(end 413.251904 -21.063204)
		(width 0.14732)
		(layer "In2.Cu")
		(net "P5E_CPU0_PE1_TX_DN<7>")
	)
	(segment
		(start 361.085384 -221.1197)
		(end 361.085384 -221.133924)
		(width 0.0889)
		(layer "In2.Cu")
		(net "P5E_CPU0_PE1_TX_DN<7>")
	)
	(segment
		(start 410.387546 -79.379064)
		(end 362.822744 -159.636206)
		(width 0.14732)
		(layer "In2.Cu")
		(net "P5E_CPU0_PE1_TX_DN<7>")
	)
	(segment
		(start 360.188002 -214.031068)
		(end 360.145838 -214.073232)
		(width 0.0889)
		(layer "In2.Cu")
		(net "P5E_CPU0_PE1_TX_DN<7>")
	)
	(segment
		(start 360.802682 -218.367864)
		(end 360.801158 -218.36888)
		(width 0.0889)
		(layer "In2.Cu")
		(net "P5E_CPU0_PE1_TX_DN<7>")
	)
	(segment
		(start 360.802682 -221.623382)
		(end 360.801158 -221.624398)
		(width 0.0889)
		(layer "In2.Cu")
		(net "P5E_CPU0_PE1_TX_DN<7>")
	)
	(segment
		(start 360.615484 -217.064336)
		(end 360.615484 -217.072972)
		(width 0.0889)
		(layer "In2.Cu")
		(net "P5E_CPU0_PE1_TX_DN<7>")
	)
	(segment
		(start 362.822744 -159.636206)
		(end 358.45242 -184.427622)
		(width 0.14732)
		(layer "In2.Cu")
		(net "P5E_CPU0_PE1_TX_DN<7>")
	)
	(segment
		(start 360.324146 -223.080834)
		(end 360.333036 -223.085914)
		(width 0.0889)
		(layer "In2.Cu")
		(net "P5E_CPU0_PE1_TX_DN<7>")
	)
	(segment
		(start 360.333036 -222.437198)
		(end 360.324146 -222.442278)
		(width 0.0889)
		(layer "In2.Cu")
		(net "P5E_CPU0_PE1_TX_DN<7>")
	)
	(segment
		(start 412.962344 -18.41373)
		(end 412.962598 -18.426684)
		(width 0.14732)
		(layer "In2.Cu")
		(net "P5E_CPU0_PE1_TX_DN<7>")
	)
	(segment
		(start 360.333036 -219.18168)
		(end 360.324146 -219.18676)
		(width 0.0889)
		(layer "In2.Cu")
		(net "P5E_CPU0_PE1_TX_DN<7>")
	)
	(segment
		(start 412.962598 -18.426684)
		(end 413.031432 -19.69008)
		(width 0.14732)
		(layer "In2.Cu")
		(net "P5E_CPU0_PE1_TX_DN<7>")
	)
	(segment
		(start 360.615484 -220.309948)
		(end 360.615484 -220.32849)
		(width 0.0889)
		(layer "In2.Cu")
		(net "P5E_CPU0_PE1_TX_DN<7>")
	)
	(segment
		(start 360.801158 -218.36888)
		(end 360.800142 -218.369388)
		(width 0.0889)
		(layer "In2.Cu")
		(net "P5E_CPU0_PE1_TX_DN<7>")
	)
	(segment
		(start 360.808778 -218.364308)
		(end 360.802682 -218.367864)
		(width 0.0889)
		(layer "In2.Cu")
		(net "P5E_CPU0_PE1_TX_DN<7>")
	)
	(segment
		(start 413.272224 -21.430996)
		(end 413.135572 -21.58365)
		(width 0.14732)
		(layer "In2.Cu")
		(net "P5E_CPU0_PE1_TX_DN<7>")
	)
	(segment
		(start 413.251904 -21.063204)
		(end 413.272224 -21.430996)
		(width 0.14732)
		(layer "In2.Cu")
		(net "P5E_CPU0_PE1_TX_DN<7>")
	)
	(segment
		(start 360.61523 -221.94774)
		(end 360.61523 -221.963234)
		(width 0.0889)
		(layer "In2.Cu")
		(net "P5E_CPU0_PE1_TX_DN<7>")
	)
	(segment
		(start 412.962344 -17.896078)
		(end 412.962344 -18.41373)
		(width 0.14732)
		(layer "In2.Cu")
		(net "P5E_CPU0_PE1_TX_DN<7>")
	)
	(segment
		(start 413.18434 -19.826732)
		(end 413.204406 -20.194778)
		(width 0.14732)
		(layer "In2.Cu")
		(net "P5E_CPU0_PE1_TX_DN<7>")
	)
	(segment
		(start 413.135572 -21.58365)
		(end 413.588962 -29.87167)
		(width 0.14732)
		(layer "In2.Cu")
		(net "P5E_CPU0_PE1_TX_DN<7>")
	)
	(segment
		(start 360.800142 -221.624906)
		(end 360.793792 -221.628462)
		(width 0.0889)
		(layer "In2.Cu")
		(net "P5E_CPU0_PE1_TX_DN<7>")
	)
	(segment
		(start 360.324146 -219.825316)
		(end 360.333036 -219.830396)
		(width 0.0889)
		(layer "In2.Cu")
		(net "P5E_CPU0_PE1_TX_DN<7>")
	)
	(segment
		(start 360.808778 -221.619826)
		(end 360.802682 -221.623382)
		(width 0.0889)
		(layer "In2.Cu")
		(net "P5E_CPU0_PE1_TX_DN<7>")
	)
	(segment
		(start 360.800142 -218.369388)
		(end 360.793792 -218.372944)
		(width 0.0889)
		(layer "In2.Cu")
		(net "P5E_CPU0_PE1_TX_DN<7>")
	)
	(segment
		(start 360.332782 -216.574878)
		(end 360.338878 -216.578434)
		(width 0.0889)
		(layer "In2.Cu")
		(net "P5E_CPU0_PE1_TX_DN<7>")
	)
	(segment
		(start 361.085384 -217.864182)
		(end 361.085384 -217.878406)
		(width 0.0889)
		(layer "In2.Cu")
		(net "P5E_CPU0_PE1_TX_DN<7>")
	)
	(segment
		(start 360.324146 -214.941912)
		(end 360.333036 -214.946992)
		(width 0.0889)
		(layer "In2.Cu")
		(net "P5E_CPU0_PE1_TX_DN<7>")
	)
	(segment
		(start 360.615484 -223.557084)
		(end 360.615484 -223.584262)
		(width 0.0889)
		(layer "In2.Cu")
		(net "P5E_CPU0_PE1_TX_DN<7>")
	)
	(segment
		(start 413.256984 -17.601438)
		(end 412.962344 -17.896078)
		(width 0.14732)
		(layer "In2.Cu")
		(net "P5E_CPU0_PE1_TX_DN<7>")
	)
	(segment
		(start 360.145584 -216.241884)
		(end 360.145584 -216.259156)
		(width 0.0889)
		(layer "In2.Cu")
		(net "P5E_CPU0_PE1_TX_DN<7>")
	)
	(segment
		(start 411.7213 -71.816214)
		(end 410.387546 -79.379064)
		(width 0.14732)
		(layer "In2.Cu")
		(net "P5E_CPU0_PE1_TX_DN<7>")
	)
	(segment
		(start 413.588962 -29.87167)
		(end 411.867858 -70.48881)
		(width 0.14732)
		(layer "In2.Cu")
		(net "P5E_CPU0_PE1_TX_DN<7>")
	)
	(segment
		(start 360.188002 -212.799676)
		(end 360.188002 -214.00897)
		(width 0.14732)
		(layer "In2.Cu")
		(net "P5E_CPU0_PE1_TX_DN<7>")
	)
	(segment
		(start 413.067754 -20.347178)
		(end 413.09925 -20.926552)
		(width 0.14732)
		(layer "In2.Cu")
		(net "P5E_CPU0_PE1_TX_DN<7>")
	)
	(segment
		(start 360.61523 -218.692222)
		(end 360.61523 -218.707716)
		(width 0.0889)
		(layer "In2.Cu")
		(net "P5E_CPU0_PE1_TX_DN<7>")
	)
	(segment
		(start 413.031432 -19.69008)
		(end 413.18434 -19.826732)
		(width 0.14732)
		(layer "In2.Cu")
		(net "P5E_CPU0_PE1_TX_DN<7>")
	)
	(segment
		(start 360.188002 -214.00897)
		(end 360.188002 -214.031068)
		(width 0.0889)
		(layer "In2.Cu")
		(net "P5E_CPU0_PE1_TX_DN<7>")
	)
	(segment
		(start 360.801158 -221.624398)
		(end 360.800142 -221.624906)
		(width 0.0889)
		(layer "In2.Cu")
		(net "P5E_CPU0_PE1_TX_DN<7>")
	)
	(segment
		(start 360.145838 -214.073232)
		(end 360.145838 -214.637366)
		(width 0.0889)
		(layer "In2.Cu")
		(net "P5E_CPU0_PE1_TX_DN<7>")
	)
	(segment
		(start 360.833416 -223.846644)
		(end 360.98988 -223.575626)
		(width 0.0889)
		(layer "In2.Cu")
		(net "P5E_CPU0_PE1_TX_DN<7>")
	)
	(segment
		(start 358.45242 -184.427622)
		(end 360.188002 -212.799676)
		(width 0.14732)
		(layer "In2.Cu")
		(net "P5E_CPU0_PE1_TX_DN<7>")
	)
	(segment
		(start 360.755438 -223.867472)
		(end 360.833416 -223.846644)
		(width 0.0889)
		(layer "In2.Cu")
		(net "P5E_CPU0_PE1_TX_DN<7>")
	)
	(segment
		(start 360.61523 -215.414606)
		(end 360.61523 -215.44661)
		(width 0.0889)
		(layer "In2.Cu")
		(net "P5E_CPU0_PE1_TX_DN<7>")
	)
	(segment
		(start 413.204406 -20.194778)
		(end 413.067754 -20.347178)
		(width 0.14732)
		(layer "In2.Cu")
		(net "P5E_CPU0_PE1_TX_DN<7>")
	)
	(arc
		(start 360.338878 -216.578434)
		(mid 360.541465 -216.784785)
		(end 360.615484 -217.064336)
		(width 0.0889)
		(layer "In2.Cu")
		(net "P5E_CPU0_PE1_TX_DN<7>")
	)
	(arc
		(start 360.145838 -222.751396)
		(mid 360.145671 -222.762572)
		(end 360.145838 -222.773748)
		(width 0.0889)
		(layer "In2.Cu")
		(net "P5E_CPU0_PE1_TX_DN<7>")
	)
	(arc
		(start 360.793792 -218.372944)
		(mid 360.662878 -218.509304)
		(end 360.61523 -218.692222)
		(width 0.0889)
		(layer "In2.Cu")
		(net "P5E_CPU0_PE1_TX_DN<7>")
	)
	(arc
		(start 360.793792 -221.628462)
		(mid 360.662878 -221.764822)
		(end 360.61523 -221.94774)
		(width 0.0889)
		(layer "In2.Cu")
		(net "P5E_CPU0_PE1_TX_DN<7>")
	)
	(arc
		(start 360.145584 -219.512642)
		(mid 360.194837 -219.691842)
		(end 360.324146 -219.825316)
		(width 0.0889)
		(layer "In2.Cu")
		(net "P5E_CPU0_PE1_TX_DN<7>")
	)
	(arc
		(start 360.802682 -220.644212)
		(mid 361.006163 -220.845016)
		(end 361.085384 -221.1197)
		(width 0.0889)
		(layer "In2.Cu")
		(net "P5E_CPU0_PE1_TX_DN<7>")
	)
	(arc
		(start 360.145838 -222.773748)
		(mid 360.196331 -222.949726)
		(end 360.324146 -223.080834)
		(width 0.0889)
		(layer "In2.Cu")
		(net "P5E_CPU0_PE1_TX_DN<7>")
	)
	(arc
		(start 360.145584 -219.495878)
		(mid 360.14549 -219.50426)
		(end 360.145584 -219.512642)
		(width 0.0889)
		(layer "In2.Cu")
		(net "P5E_CPU0_PE1_TX_DN<7>")
	)
	(arc
		(start 360.324146 -219.18676)
		(mid 360.195742 -219.318705)
		(end 360.145584 -219.495878)
		(width 0.0889)
		(layer "In2.Cu")
		(net "P5E_CPU0_PE1_TX_DN<7>")
	)
	(arc
		(start 361.085384 -217.878406)
		(mid 361.011393 -218.157972)
		(end 360.808778 -218.364308)
		(width 0.0889)
		(layer "In2.Cu")
		(net "P5E_CPU0_PE1_TX_DN<7>")
	)
	(arc
		(start 360.145584 -216.259156)
		(mid 360.197854 -216.441521)
		(end 360.332782 -216.574878)
		(width 0.0889)
		(layer "In2.Cu")
		(net "P5E_CPU0_PE1_TX_DN<7>")
	)
	(arc
		(start 360.802682 -217.388694)
		(mid 361.006163 -217.589498)
		(end 361.085384 -217.864182)
		(width 0.0889)
		(layer "In2.Cu")
		(net "P5E_CPU0_PE1_TX_DN<7>")
	)
	(arc
		(start 360.615484 -223.584262)
		(mid 360.654158 -223.74133)
		(end 360.755438 -223.867472)
		(width 0.0889)
		(layer "In2.Cu")
		(net "P5E_CPU0_PE1_TX_DN<7>")
	)
	(arc
		(start 360.145838 -214.637366)
		(mid 360.196892 -214.811946)
		(end 360.324146 -214.941912)
		(width 0.0889)
		(layer "In2.Cu")
		(net "P5E_CPU0_PE1_TX_DN<7>")
	)
	(arc
		(start 360.333036 -219.830396)
		(mid 360.537371 -220.033001)
		(end 360.615484 -220.309948)
		(width 0.0889)
		(layer "In2.Cu")
		(net "P5E_CPU0_PE1_TX_DN<7>")
	)
	(arc
		(start 360.61523 -221.963234)
		(mid 360.53586 -222.236968)
		(end 360.333036 -222.437198)
		(width 0.0889)
		(layer "In2.Cu")
		(net "P5E_CPU0_PE1_TX_DN<7>")
	)
	(arc
		(start 360.615484 -220.32849)
		(mid 360.667754 -220.510855)
		(end 360.802682 -220.644212)
		(width 0.0889)
		(layer "In2.Cu")
		(net "P5E_CPU0_PE1_TX_DN<7>")
	)
	(arc
		(start 360.332782 -215.926162)
		(mid 360.197849 -216.059516)
		(end 360.145584 -216.241884)
		(width 0.0889)
		(layer "In2.Cu")
		(net "P5E_CPU0_PE1_TX_DN<7>")
	)
	(arc
		(start 360.324146 -222.442278)
		(mid 360.195827 -222.57425)
		(end 360.145838 -222.751396)
		(width 0.0889)
		(layer "In2.Cu")
		(net "P5E_CPU0_PE1_TX_DN<7>")
	)
	(arc
		(start 360.333036 -214.946992)
		(mid 360.534318 -215.144479)
		(end 360.61523 -215.414606)
		(width 0.0889)
		(layer "In2.Cu")
		(net "P5E_CPU0_PE1_TX_DN<7>")
	)
	(arc
		(start 360.333036 -223.085914)
		(mid 360.535322 -223.284895)
		(end 360.615484 -223.557084)
		(width 0.0889)
		(layer "In2.Cu")
		(net "P5E_CPU0_PE1_TX_DN<7>")
	)
	(arc
		(start 360.61523 -218.707716)
		(mid 360.53586 -218.98145)
		(end 360.333036 -219.18168)
		(width 0.0889)
		(layer "In2.Cu")
		(net "P5E_CPU0_PE1_TX_DN<7>")
	)
	(arc
		(start 360.615484 -217.072972)
		(mid 360.667754 -217.255337)
		(end 360.802682 -217.388694)
		(width 0.0889)
		(layer "In2.Cu")
		(net "P5E_CPU0_PE1_TX_DN<7>")
	)
	(arc
		(start 361.085384 -221.133924)
		(mid 361.011393 -221.41349)
		(end 360.808778 -221.619826)
		(width 0.0889)
		(layer "In2.Cu")
		(net "P5E_CPU0_PE1_TX_DN<7>")
	)
	(arc
		(start 360.61523 -215.44661)
		(mid 360.537119 -215.723559)
		(end 360.332782 -215.926162)
		(width 0.0889)
		(layer "In2.Cu")
		(net "P5E_CPU0_PE1_TX_DN<7>")
	)
	(segment
		(start 415.794444 -18.824194)
		(end 415.794444 -18.205958)
		(width 0.13208)
		(layer "F.Cu")
		(net "P5E_CPU0_PE1_TX_DN<6>")
	)
	(segment
		(start 415.4932 -19.125438)
		(end 415.794444 -18.824194)
		(width 0.13208)
		(layer "F.Cu")
		(net "P5E_CPU0_PE1_TX_DN<6>")
	)
	(segment
		(start 361.460034 -224.925128)
		(end 361.460034 -224.389442)
		(width 0.13208)
		(layer "F.Cu")
		(net "P5E_CPU0_PE1_TX_DN<6>")
	)
	(segment
		(start 415.794444 -18.205958)
		(end 415.4678 -17.879314)
		(width 0.13208)
		(layer "F.Cu")
		(net "P5E_CPU0_PE1_TX_DN<6>")
	)
	(segment
		(start 361.45978 -224.925382)
		(end 361.460034 -224.925128)
		(width 0.13208)
		(layer "F.Cu")
		(net "P5E_CPU0_PE1_TX_DN<6>")
	)
	(segment
		(start 415.52622 -23.234396)
		(end 415.676842 -23.095712)
		(width 0.14732)
		(layer "In2.Cu")
		(net "P5E_CPU0_PE1_TX_DN<6>")
	)
	(segment
		(start 415.69894 -22.541484)
		(end 415.560002 -22.390862)
		(width 0.14732)
		(layer "In2.Cu")
		(net "P5E_CPU0_PE1_TX_DN<6>")
	)
	(segment
		(start 415.57448 -22.022816)
		(end 415.725356 -21.883878)
		(width 0.14732)
		(layer "In2.Cu")
		(net "P5E_CPU0_PE1_TX_DN<6>")
	)
	(segment
		(start 361.179618 -216.741502)
		(end 361.17784 -216.740486)
		(width 0.0889)
		(layer "In2.Cu")
		(net "P5E_CPU0_PE1_TX_DN<6>")
	)
	(segment
		(start 361.185968 -216.745058)
		(end 361.185206 -216.74455)
		(width 0.0889)
		(layer "In2.Cu")
		(net "P5E_CPU0_PE1_TX_DN<6>")
	)
	(segment
		(start 415.636202 -23.737824)
		(end 415.511488 -23.602696)
		(width 0.14732)
		(layer "In2.Cu")
		(net "P5E_CPU0_PE1_TX_DN<6>")
	)
	(segment
		(start 361.36453 -215.436704)
		(end 361.36453 -214.674958)
		(width 0.0889)
		(layer "In2.Cu")
		(net "P5E_CPU0_PE1_TX_DN<6>")
	)
	(segment
		(start 360.894884 -219.521532)
		(end 360.894884 -219.490544)
		(width 0.0889)
		(layer "In2.Cu")
		(net "P5E_CPU0_PE1_TX_DN<6>")
	)
	(segment
		(start 361.616498 -224.66046)
		(end 361.69473 -224.681288)
		(width 0.0889)
		(layer "In2.Cu")
		(net "P5E_CPU0_PE1_TX_DN<6>")
	)
	(segment
		(start 361.32262 -213.721188)
		(end 359.151174 -184.243726)
		(width 0.14732)
		(layer "In2.Cu")
		(net "P5E_CPU0_PE1_TX_DN<6>")
	)
	(segment
		(start 361.656122 -217.559128)
		(end 361.647232 -217.554048)
		(width 0.0889)
		(layer "In2.Cu")
		(net "P5E_CPU0_PE1_TX_DN<6>")
	)
	(segment
		(start 361.32262 -214.61095)
		(end 361.32262 -213.721188)
		(width 0.14732)
		(layer "In2.Cu")
		(net "P5E_CPU0_PE1_TX_DN<6>")
	)
	(segment
		(start 361.177078 -222.272098)
		(end 361.178094 -222.27159)
		(width 0.0889)
		(layer "In2.Cu")
		(net "P5E_CPU0_PE1_TX_DN<6>")
	)
	(segment
		(start 415.725356 -21.883878)
		(end 415.78784 -20.312634)
		(width 0.14732)
		(layer "In2.Cu")
		(net "P5E_CPU0_PE1_TX_DN<6>")
	)
	(segment
		(start 361.177078 -215.761062)
		(end 361.185968 -215.755982)
		(width 0.0889)
		(layer "In2.Cu")
		(net "P5E_CPU0_PE1_TX_DN<6>")
	)
	(segment
		(start 361.178094 -222.27159)
		(end 361.185968 -222.267018)
		(width 0.0889)
		(layer "In2.Cu")
		(net "P5E_CPU0_PE1_TX_DN<6>")
	)
	(segment
		(start 415.560002 -22.390862)
		(end 415.57448 -22.022816)
		(width 0.14732)
		(layer "In2.Cu")
		(net "P5E_CPU0_PE1_TX_DN<6>")
	)
	(segment
		(start 415.78784 -20.312634)
		(end 415.78784 -19.420078)
		(width 0.14732)
		(layer "In2.Cu")
		(net "P5E_CPU0_PE1_TX_DN<6>")
	)
	(segment
		(start 361.63504 -218.209876)
		(end 361.647232 -218.202764)
		(width 0.0889)
		(layer "In2.Cu")
		(net "P5E_CPU0_PE1_TX_DN<6>")
	)
	(segment
		(start 361.36453 -214.674958)
		(end 361.32262 -214.633048)
		(width 0.0889)
		(layer "In2.Cu")
		(net "P5E_CPU0_PE1_TX_DN<6>")
	)
	(segment
		(start 415.391092 -29.88945)
		(end 415.636202 -23.737824)
		(width 0.14732)
		(layer "In2.Cu")
		(net "P5E_CPU0_PE1_TX_DN<6>")
	)
	(segment
		(start 361.63504 -221.465394)
		(end 361.647232 -221.458282)
		(width 0.0889)
		(layer "In2.Cu")
		(net "P5E_CPU0_PE1_TX_DN<6>")
	)
	(segment
		(start 361.36453 -220.327474)
		(end 361.36453 -220.319854)
		(width 0.0889)
		(layer "In2.Cu")
		(net "P5E_CPU0_PE1_TX_DN<6>")
	)
	(segment
		(start 360.894884 -222.783654)
		(end 360.894884 -222.746062)
		(width 0.0889)
		(layer "In2.Cu")
		(net "P5E_CPU0_PE1_TX_DN<6>")
	)
	(segment
		(start 415.676842 -23.095712)
		(end 415.69894 -22.541484)
		(width 0.14732)
		(layer "In2.Cu")
		(net "P5E_CPU0_PE1_TX_DN<6>")
	)
	(segment
		(start 361.32262 -214.633048)
		(end 361.32262 -214.61095)
		(width 0.0889)
		(layer "In2.Cu")
		(net "P5E_CPU0_PE1_TX_DN<6>")
	)
	(segment
		(start 361.185206 -216.74455)
		(end 361.18038 -216.74201)
		(width 0.0889)
		(layer "In2.Cu")
		(net "P5E_CPU0_PE1_TX_DN<6>")
	)
	(segment
		(start 361.656122 -220.814646)
		(end 361.647232 -220.809566)
		(width 0.0889)
		(layer "In2.Cu")
		(net "P5E_CPU0_PE1_TX_DN<6>")
	)
	(segment
		(start 361.177078 -219.01658)
		(end 361.178094 -219.016072)
		(width 0.0889)
		(layer "In2.Cu")
		(net "P5E_CPU0_PE1_TX_DN<6>")
	)
	(segment
		(start 361.18038 -216.74201)
		(end 361.179618 -216.741502)
		(width 0.0889)
		(layer "In2.Cu")
		(net "P5E_CPU0_PE1_TX_DN<6>")
	)
	(segment
		(start 361.647232 -218.202764)
		(end 361.656122 -218.197684)
		(width 0.0889)
		(layer "In2.Cu")
		(net "P5E_CPU0_PE1_TX_DN<6>")
	)
	(segment
		(start 361.643422 -224.062798)
		(end 361.63504 -224.057972)
		(width 0.0889)
		(layer "In2.Cu")
		(net "P5E_CPU0_PE1_TX_DN<6>")
	)
	(segment
		(start 361.17784 -216.740486)
		(end 361.177078 -216.739978)
		(width 0.0889)
		(layer "In2.Cu")
		(net "P5E_CPU0_PE1_TX_DN<6>")
	)
	(segment
		(start 412.668974 -70.231)
		(end 415.391092 -29.889196)
		(width 0.14732)
		(layer "In2.Cu")
		(net "P5E_CPU0_PE1_TX_DN<6>")
	)
	(segment
		(start 361.185968 -223.256348)
		(end 361.177078 -223.251268)
		(width 0.0889)
		(layer "In2.Cu")
		(net "P5E_CPU0_PE1_TX_DN<6>")
	)
	(segment
		(start 410.985208 -79.775558)
		(end 412.668974 -70.231)
		(width 0.14732)
		(layer "In2.Cu")
		(net "P5E_CPU0_PE1_TX_DN<6>")
	)
	(segment
		(start 415.511488 -23.602696)
		(end 415.52622 -23.234396)
		(width 0.14732)
		(layer "In2.Cu")
		(net "P5E_CPU0_PE1_TX_DN<6>")
	)
	(segment
		(start 361.185968 -220.000576)
		(end 361.178094 -219.996004)
		(width 0.0889)
		(layer "In2.Cu")
		(net "P5E_CPU0_PE1_TX_DN<6>")
	)
	(segment
		(start 361.656122 -224.070164)
		(end 361.647232 -224.065084)
		(width 0.0889)
		(layer "In2.Cu")
		(net "P5E_CPU0_PE1_TX_DN<6>")
	)
	(segment
		(start 361.178094 -219.016072)
		(end 361.185968 -219.0115)
		(width 0.0889)
		(layer "In2.Cu")
		(net "P5E_CPU0_PE1_TX_DN<6>")
	)
	(segment
		(start 359.151174 -184.243726)
		(end 363.41558 -160.048448)
		(width 0.14732)
		(layer "In2.Cu")
		(net "P5E_CPU0_PE1_TX_DN<6>")
	)
	(segment
		(start 363.41558 -160.048448)
		(end 410.985208 -79.775558)
		(width 0.14732)
		(layer "In2.Cu")
		(net "P5E_CPU0_PE1_TX_DN<6>")
	)
	(segment
		(start 361.647232 -224.065084)
		(end 361.643422 -224.062798)
		(width 0.0889)
		(layer "In2.Cu")
		(net "P5E_CPU0_PE1_TX_DN<6>")
	)
	(segment
		(start 361.178094 -219.996004)
		(end 361.177078 -219.995496)
		(width 0.0889)
		(layer "In2.Cu")
		(net "P5E_CPU0_PE1_TX_DN<6>")
	)
	(segment
		(start 361.647232 -221.458282)
		(end 361.656122 -221.453202)
		(width 0.0889)
		(layer "In2.Cu")
		(net "P5E_CPU0_PE1_TX_DN<6>")
	)
	(segment
		(start 361.460034 -224.389442)
		(end 361.616498 -224.66046)
		(width 0.0889)
		(layer "In2.Cu")
		(net "P5E_CPU0_PE1_TX_DN<6>")
	)
	(segment
		(start 415.78784 -19.420078)
		(end 415.4932 -19.125438)
		(width 0.14732)
		(layer "In2.Cu")
		(net "P5E_CPU0_PE1_TX_DN<6>")
	)
	(segment
		(start 360.89463 -216.260426)
		(end 360.89463 -216.240614)
		(width 0.0889)
		(layer "In2.Cu")
		(net "P5E_CPU0_PE1_TX_DN<6>")
	)
	(segment
		(start 361.36453 -217.071956)
		(end 361.36453 -217.064336)
		(width 0.0889)
		(layer "In2.Cu")
		(net "P5E_CPU0_PE1_TX_DN<6>")
	)
	(segment
		(start 415.391092 -29.889196)
		(end 415.391092 -29.88945)
		(width 0.14732)
		(layer "In2.Cu")
		(net "P5E_CPU0_PE1_TX_DN<6>")
	)
	(arc
		(start 361.185968 -219.0115)
		(mid 361.316882 -218.87514)
		(end 361.36453 -218.692222)
		(width 0.0889)
		(layer "In2.Cu")
		(net "P5E_CPU0_PE1_TX_DN<6>")
	)
	(arc
		(start 361.36453 -217.064336)
		(mid 361.316851 -216.881436)
		(end 361.185968 -216.745058)
		(width 0.0889)
		(layer "In2.Cu")
		(net "P5E_CPU0_PE1_TX_DN<6>")
	)
	(arc
		(start 361.834684 -217.88501)
		(mid 361.834674 -217.87561)
		(end 361.83443 -217.866214)
		(width 0.0889)
		(layer "In2.Cu")
		(net "P5E_CPU0_PE1_TX_DN<6>")
	)
	(arc
		(start 361.185968 -222.267018)
		(mid 361.316882 -222.130658)
		(end 361.36453 -221.94774)
		(width 0.0889)
		(layer "In2.Cu")
		(net "P5E_CPU0_PE1_TX_DN<6>")
	)
	(arc
		(start 361.647232 -217.554048)
		(mid 361.44216 -217.350369)
		(end 361.36453 -217.071956)
		(width 0.0889)
		(layer "In2.Cu")
		(net "P5E_CPU0_PE1_TX_DN<6>")
	)
	(arc
		(start 361.36453 -218.692222)
		(mid 361.436765 -218.415698)
		(end 361.63504 -218.209876)
		(width 0.0889)
		(layer "In2.Cu")
		(net "P5E_CPU0_PE1_TX_DN<6>")
	)
	(arc
		(start 361.177078 -216.739978)
		(mid 360.972743 -216.537373)
		(end 360.89463 -216.260426)
		(width 0.0889)
		(layer "In2.Cu")
		(net "P5E_CPU0_PE1_TX_DN<6>")
	)
	(arc
		(start 360.89463 -216.240614)
		(mid 360.972741 -215.963665)
		(end 361.177078 -215.761062)
		(width 0.0889)
		(layer "In2.Cu")
		(net "P5E_CPU0_PE1_TX_DN<6>")
	)
	(arc
		(start 360.894884 -222.746062)
		(mid 360.974254 -222.472328)
		(end 361.177078 -222.272098)
		(width 0.0889)
		(layer "In2.Cu")
		(net "P5E_CPU0_PE1_TX_DN<6>")
	)
	(arc
		(start 361.83443 -221.121732)
		(mid 361.783937 -220.945754)
		(end 361.656122 -220.814646)
		(width 0.0889)
		(layer "In2.Cu")
		(net "P5E_CPU0_PE1_TX_DN<6>")
	)
	(arc
		(start 361.36453 -223.575626)
		(mid 361.316851 -223.392726)
		(end 361.185968 -223.256348)
		(width 0.0889)
		(layer "In2.Cu")
		(net "P5E_CPU0_PE1_TX_DN<6>")
	)
	(arc
		(start 361.63504 -224.057972)
		(mid 361.436812 -223.852124)
		(end 361.36453 -223.575626)
		(width 0.0889)
		(layer "In2.Cu")
		(net "P5E_CPU0_PE1_TX_DN<6>")
	)
	(arc
		(start 360.894884 -219.490544)
		(mid 360.974254 -219.21681)
		(end 361.177078 -219.01658)
		(width 0.0889)
		(layer "In2.Cu")
		(net "P5E_CPU0_PE1_TX_DN<6>")
	)
	(arc
		(start 361.647232 -220.809566)
		(mid 361.44216 -220.605887)
		(end 361.36453 -220.327474)
		(width 0.0889)
		(layer "In2.Cu")
		(net "P5E_CPU0_PE1_TX_DN<6>")
	)
	(arc
		(start 361.656122 -218.197684)
		(mid 361.785411 -218.064198)
		(end 361.834684 -217.88501)
		(width 0.0889)
		(layer "In2.Cu")
		(net "P5E_CPU0_PE1_TX_DN<6>")
	)
	(arc
		(start 361.177078 -223.251268)
		(mid 360.975796 -223.053781)
		(end 360.894884 -222.783654)
		(width 0.0889)
		(layer "In2.Cu")
		(net "P5E_CPU0_PE1_TX_DN<6>")
	)
	(arc
		(start 361.36453 -221.94774)
		(mid 361.436765 -221.671216)
		(end 361.63504 -221.465394)
		(width 0.0889)
		(layer "In2.Cu")
		(net "P5E_CPU0_PE1_TX_DN<6>")
	)
	(arc
		(start 361.83443 -217.866214)
		(mid 361.783937 -217.690236)
		(end 361.656122 -217.559128)
		(width 0.0889)
		(layer "In2.Cu")
		(net "P5E_CPU0_PE1_TX_DN<6>")
	)
	(arc
		(start 361.834684 -224.389442)
		(mid 361.787005 -224.206542)
		(end 361.656122 -224.070164)
		(width 0.0889)
		(layer "In2.Cu")
		(net "P5E_CPU0_PE1_TX_DN<6>")
	)
	(arc
		(start 361.834684 -221.140528)
		(mid 361.834674 -221.131128)
		(end 361.83443 -221.121732)
		(width 0.0889)
		(layer "In2.Cu")
		(net "P5E_CPU0_PE1_TX_DN<6>")
	)
	(arc
		(start 361.656122 -221.453202)
		(mid 361.785411 -221.319716)
		(end 361.834684 -221.140528)
		(width 0.0889)
		(layer "In2.Cu")
		(net "P5E_CPU0_PE1_TX_DN<6>")
	)
	(arc
		(start 361.69473 -224.681288)
		(mid 361.797875 -224.551263)
		(end 361.834684 -224.389442)
		(width 0.0889)
		(layer "In2.Cu")
		(net "P5E_CPU0_PE1_TX_DN<6>")
	)
	(arc
		(start 361.185968 -215.755982)
		(mid 361.316882 -215.619622)
		(end 361.36453 -215.436704)
		(width 0.0889)
		(layer "In2.Cu")
		(net "P5E_CPU0_PE1_TX_DN<6>")
	)
	(arc
		(start 361.36453 -220.319854)
		(mid 361.316851 -220.136954)
		(end 361.185968 -220.000576)
		(width 0.0889)
		(layer "In2.Cu")
		(net "P5E_CPU0_PE1_TX_DN<6>")
	)
	(arc
		(start 361.177078 -219.995496)
		(mid 360.974255 -219.795265)
		(end 360.894884 -219.521532)
		(width 0.0889)
		(layer "In2.Cu")
		(net "P5E_CPU0_PE1_TX_DN<6>")
	)
	(segment
		(start 418.847524 -17.298162)
		(end 418.847524 -16.68399)
		(width 0.13208)
		(layer "F.Cu")
		(net "P5E_CPU0_PE1_TX_DN<5>")
	)
	(segment
		(start 419.1508 -17.601438)
		(end 418.847524 -17.298162)
		(width 0.13208)
		(layer "F.Cu")
		(net "P5E_CPU0_PE1_TX_DN<5>")
	)
	(segment
		(start 418.847524 -16.68399)
		(end 419.1762 -16.355314)
		(width 0.13208)
		(layer "F.Cu")
		(net "P5E_CPU0_PE1_TX_DN<5>")
	)
	(segment
		(start 362.869734 -224.111566)
		(end 362.869734 -223.575626)
		(width 0.13208)
		(layer "F.Cu")
		(net "P5E_CPU0_PE1_TX_DN<5>")
	)
	(segment
		(start 362.688378 -218.364308)
		(end 362.682282 -218.367864)
		(width 0.0889)
		(layer "In2.Cu")
		(net "P5E_CPU0_PE1_TX_DN<5>")
	)
	(segment
		(start 416.63493 -55.004716)
		(end 412.203392 -80.12938)
		(width 0.14732)
		(layer "In2.Cu")
		(net "P5E_CPU0_PE1_TX_DN<5>")
	)
	(segment
		(start 362.53674 -213.722712)
		(end 362.53674 -214.61095)
		(width 0.14732)
		(layer "In2.Cu")
		(net "P5E_CPU0_PE1_TX_DN<5>")
	)
	(segment
		(start 418.85616 -19.082258)
		(end 419.00094 -19.227038)
		(width 0.14732)
		(layer "In2.Cu")
		(net "P5E_CPU0_PE1_TX_DN<5>")
	)
	(segment
		(start 362.025184 -216.25052)
		(end 362.025184 -216.257124)
		(width 0.0889)
		(layer "In2.Cu")
		(net "P5E_CPU0_PE1_TX_DN<5>")
	)
	(segment
		(start 419.00094 -19.227038)
		(end 419.00094 -19.595338)
		(width 0.14732)
		(layer "In2.Cu")
		(net "P5E_CPU0_PE1_TX_DN<5>")
	)
	(segment
		(start 419.00094 -20.253198)
		(end 419.00094 -20.621498)
		(width 0.14732)
		(layer "In2.Cu")
		(net "P5E_CPU0_PE1_TX_DN<5>")
	)
	(segment
		(start 362.212636 -219.18168)
		(end 362.203746 -219.18676)
		(width 0.0889)
		(layer "In2.Cu")
		(net "P5E_CPU0_PE1_TX_DN<5>")
	)
	(segment
		(start 362.494576 -215.451944)
		(end 362.49483 -215.452198)
		(width 0.0889)
		(layer "In2.Cu")
		(net "P5E_CPU0_PE1_TX_DN<5>")
	)
	(segment
		(start 362.203746 -216.569798)
		(end 362.212636 -216.574878)
		(width 0.0889)
		(layer "In2.Cu")
		(net "P5E_CPU0_PE1_TX_DN<5>")
	)
	(segment
		(start 412.203392 -80.12938)
		(end 364.552738 -160.538414)
		(width 0.14732)
		(layer "In2.Cu")
		(net "P5E_CPU0_PE1_TX_DN<5>")
	)
	(segment
		(start 362.679742 -218.369388)
		(end 362.673392 -218.372944)
		(width 0.0889)
		(layer "In2.Cu")
		(net "P5E_CPU0_PE1_TX_DN<5>")
	)
	(segment
		(start 362.495084 -223.557084)
		(end 362.495084 -223.584262)
		(width 0.0889)
		(layer "In2.Cu")
		(net "P5E_CPU0_PE1_TX_DN<5>")
	)
	(segment
		(start 419.1508 -17.601438)
		(end 418.85616 -17.896078)
		(width 0.14732)
		(layer "In2.Cu")
		(net "P5E_CPU0_PE1_TX_DN<5>")
	)
	(segment
		(start 362.964984 -221.1197)
		(end 362.964984 -221.133924)
		(width 0.0889)
		(layer "In2.Cu")
		(net "P5E_CPU0_PE1_TX_DN<5>")
	)
	(segment
		(start 364.552738 -160.538414)
		(end 360.370882 -184.259982)
		(width 0.14732)
		(layer "In2.Cu")
		(net "P5E_CPU0_PE1_TX_DN<5>")
	)
	(segment
		(start 419.00094 -19.595338)
		(end 418.85616 -19.740118)
		(width 0.14732)
		(layer "In2.Cu")
		(net "P5E_CPU0_PE1_TX_DN<5>")
	)
	(segment
		(start 418.85616 -20.766278)
		(end 418.85616 -21.151342)
		(width 0.14732)
		(layer "In2.Cu")
		(net "P5E_CPU0_PE1_TX_DN<5>")
	)
	(segment
		(start 418.85616 -19.740118)
		(end 418.85616 -20.108418)
		(width 0.14732)
		(layer "In2.Cu")
		(net "P5E_CPU0_PE1_TX_DN<5>")
	)
	(segment
		(start 362.212636 -215.926162)
		(end 362.21162 -215.92667)
		(width 0.0889)
		(layer "In2.Cu")
		(net "P5E_CPU0_PE1_TX_DN<5>")
	)
	(segment
		(start 362.49483 -221.94774)
		(end 362.49483 -221.963234)
		(width 0.0889)
		(layer "In2.Cu")
		(net "P5E_CPU0_PE1_TX_DN<5>")
	)
	(segment
		(start 362.679742 -221.624906)
		(end 362.673392 -221.628462)
		(width 0.0889)
		(layer "In2.Cu")
		(net "P5E_CPU0_PE1_TX_DN<5>")
	)
	(segment
		(start 362.682282 -221.623382)
		(end 362.680758 -221.624398)
		(width 0.0889)
		(layer "In2.Cu")
		(net "P5E_CPU0_PE1_TX_DN<5>")
	)
	(segment
		(start 362.203746 -219.825316)
		(end 362.212636 -219.830396)
		(width 0.0889)
		(layer "In2.Cu")
		(net "P5E_CPU0_PE1_TX_DN<5>")
	)
	(segment
		(start 362.688378 -221.619826)
		(end 362.682282 -221.623382)
		(width 0.0889)
		(layer "In2.Cu")
		(net "P5E_CPU0_PE1_TX_DN<5>")
	)
	(segment
		(start 418.85616 -17.896078)
		(end 418.85616 -19.082258)
		(width 0.14732)
		(layer "In2.Cu")
		(net "P5E_CPU0_PE1_TX_DN<5>")
	)
	(segment
		(start 362.212636 -222.437198)
		(end 362.203746 -222.442278)
		(width 0.0889)
		(layer "In2.Cu")
		(net "P5E_CPU0_PE1_TX_DN<5>")
	)
	(segment
		(start 362.495084 -220.309948)
		(end 362.495084 -220.32849)
		(width 0.0889)
		(layer "In2.Cu")
		(net "P5E_CPU0_PE1_TX_DN<5>")
	)
	(segment
		(start 362.680758 -218.36888)
		(end 362.679742 -218.369388)
		(width 0.0889)
		(layer "In2.Cu")
		(net "P5E_CPU0_PE1_TX_DN<5>")
	)
	(segment
		(start 418.85616 -21.151342)
		(end 416.63493 -55.004716)
		(width 0.14732)
		(layer "In2.Cu")
		(net "P5E_CPU0_PE1_TX_DN<5>")
	)
	(segment
		(start 360.370882 -184.259982)
		(end 362.53674 -213.722712)
		(width 0.14732)
		(layer "In2.Cu")
		(net "P5E_CPU0_PE1_TX_DN<5>")
	)
	(segment
		(start 362.203746 -223.080834)
		(end 362.212636 -223.085914)
		(width 0.0889)
		(layer "In2.Cu")
		(net "P5E_CPU0_PE1_TX_DN<5>")
	)
	(segment
		(start 362.494576 -214.675212)
		(end 362.494576 -215.451944)
		(width 0.0889)
		(layer "In2.Cu")
		(net "P5E_CPU0_PE1_TX_DN<5>")
	)
	(segment
		(start 362.21162 -215.92667)
		(end 362.203746 -215.931242)
		(width 0.0889)
		(layer "In2.Cu")
		(net "P5E_CPU0_PE1_TX_DN<5>")
	)
	(segment
		(start 362.964984 -217.864182)
		(end 362.964984 -217.878406)
		(width 0.0889)
		(layer "In2.Cu")
		(net "P5E_CPU0_PE1_TX_DN<5>")
	)
	(segment
		(start 362.635038 -223.867472)
		(end 362.713016 -223.846644)
		(width 0.0889)
		(layer "In2.Cu")
		(net "P5E_CPU0_PE1_TX_DN<5>")
	)
	(segment
		(start 362.53674 -214.633048)
		(end 362.494576 -214.675212)
		(width 0.0889)
		(layer "In2.Cu")
		(net "P5E_CPU0_PE1_TX_DN<5>")
	)
	(segment
		(start 419.00094 -20.621498)
		(end 418.85616 -20.766278)
		(width 0.14732)
		(layer "In2.Cu")
		(net "P5E_CPU0_PE1_TX_DN<5>")
	)
	(segment
		(start 362.680758 -221.624398)
		(end 362.679742 -221.624906)
		(width 0.0889)
		(layer "In2.Cu")
		(net "P5E_CPU0_PE1_TX_DN<5>")
	)
	(segment
		(start 418.85616 -20.108418)
		(end 419.00094 -20.253198)
		(width 0.14732)
		(layer "In2.Cu")
		(net "P5E_CPU0_PE1_TX_DN<5>")
	)
	(segment
		(start 362.713016 -223.846644)
		(end 362.869734 -223.575626)
		(width 0.0889)
		(layer "In2.Cu")
		(net "P5E_CPU0_PE1_TX_DN<5>")
	)
	(segment
		(start 362.495084 -217.05443)
		(end 362.495084 -217.072972)
		(width 0.0889)
		(layer "In2.Cu")
		(net "P5E_CPU0_PE1_TX_DN<5>")
	)
	(segment
		(start 362.682282 -218.367864)
		(end 362.680758 -218.36888)
		(width 0.0889)
		(layer "In2.Cu")
		(net "P5E_CPU0_PE1_TX_DN<5>")
	)
	(segment
		(start 362.49483 -218.692222)
		(end 362.49483 -218.707716)
		(width 0.0889)
		(layer "In2.Cu")
		(net "P5E_CPU0_PE1_TX_DN<5>")
	)
	(segment
		(start 362.53674 -214.61095)
		(end 362.53674 -214.633048)
		(width 0.0889)
		(layer "In2.Cu")
		(net "P5E_CPU0_PE1_TX_DN<5>")
	)
	(arc
		(start 362.025438 -222.773748)
		(mid 362.075931 -222.949726)
		(end 362.203746 -223.080834)
		(width 0.0889)
		(layer "In2.Cu")
		(net "P5E_CPU0_PE1_TX_DN<5>")
	)
	(arc
		(start 362.212636 -223.085914)
		(mid 362.414922 -223.284895)
		(end 362.495084 -223.557084)
		(width 0.0889)
		(layer "In2.Cu")
		(net "P5E_CPU0_PE1_TX_DN<5>")
	)
	(arc
		(start 362.212636 -216.574878)
		(mid 362.416971 -216.777483)
		(end 362.495084 -217.05443)
		(width 0.0889)
		(layer "In2.Cu")
		(net "P5E_CPU0_PE1_TX_DN<5>")
	)
	(arc
		(start 362.673392 -218.372944)
		(mid 362.542478 -218.509304)
		(end 362.49483 -218.692222)
		(width 0.0889)
		(layer "In2.Cu")
		(net "P5E_CPU0_PE1_TX_DN<5>")
	)
	(arc
		(start 362.49483 -215.452198)
		(mid 362.41546 -215.725932)
		(end 362.212636 -215.926162)
		(width 0.0889)
		(layer "In2.Cu")
		(net "P5E_CPU0_PE1_TX_DN<5>")
	)
	(arc
		(start 362.025184 -219.495878)
		(mid 362.02509 -219.50426)
		(end 362.025184 -219.512642)
		(width 0.0889)
		(layer "In2.Cu")
		(net "P5E_CPU0_PE1_TX_DN<5>")
	)
	(arc
		(start 362.49483 -218.707716)
		(mid 362.41546 -218.98145)
		(end 362.212636 -219.18168)
		(width 0.0889)
		(layer "In2.Cu")
		(net "P5E_CPU0_PE1_TX_DN<5>")
	)
	(arc
		(start 362.212636 -219.830396)
		(mid 362.416971 -220.033001)
		(end 362.495084 -220.309948)
		(width 0.0889)
		(layer "In2.Cu")
		(net "P5E_CPU0_PE1_TX_DN<5>")
	)
	(arc
		(start 362.203746 -222.442278)
		(mid 362.075427 -222.57425)
		(end 362.025438 -222.751396)
		(width 0.0889)
		(layer "In2.Cu")
		(net "P5E_CPU0_PE1_TX_DN<5>")
	)
	(arc
		(start 362.673392 -221.628462)
		(mid 362.542478 -221.764822)
		(end 362.49483 -221.94774)
		(width 0.0889)
		(layer "In2.Cu")
		(net "P5E_CPU0_PE1_TX_DN<5>")
	)
	(arc
		(start 362.49483 -221.963234)
		(mid 362.41546 -222.236968)
		(end 362.212636 -222.437198)
		(width 0.0889)
		(layer "In2.Cu")
		(net "P5E_CPU0_PE1_TX_DN<5>")
	)
	(arc
		(start 362.964984 -217.878406)
		(mid 362.890993 -218.157972)
		(end 362.688378 -218.364308)
		(width 0.0889)
		(layer "In2.Cu")
		(net "P5E_CPU0_PE1_TX_DN<5>")
	)
	(arc
		(start 362.025438 -222.751396)
		(mid 362.025271 -222.762572)
		(end 362.025438 -222.773748)
		(width 0.0889)
		(layer "In2.Cu")
		(net "P5E_CPU0_PE1_TX_DN<5>")
	)
	(arc
		(start 362.682282 -220.644212)
		(mid 362.885763 -220.845016)
		(end 362.964984 -221.1197)
		(width 0.0889)
		(layer "In2.Cu")
		(net "P5E_CPU0_PE1_TX_DN<5>")
	)
	(arc
		(start 362.495084 -217.072972)
		(mid 362.547354 -217.255337)
		(end 362.682282 -217.388694)
		(width 0.0889)
		(layer "In2.Cu")
		(net "P5E_CPU0_PE1_TX_DN<5>")
	)
	(arc
		(start 362.203746 -215.931242)
		(mid 362.072832 -216.067602)
		(end 362.025184 -216.25052)
		(width 0.0889)
		(layer "In2.Cu")
		(net "P5E_CPU0_PE1_TX_DN<5>")
	)
	(arc
		(start 362.495084 -220.32849)
		(mid 362.547354 -220.510855)
		(end 362.682282 -220.644212)
		(width 0.0889)
		(layer "In2.Cu")
		(net "P5E_CPU0_PE1_TX_DN<5>")
	)
	(arc
		(start 362.495084 -223.584262)
		(mid 362.533758 -223.74133)
		(end 362.635038 -223.867472)
		(width 0.0889)
		(layer "In2.Cu")
		(net "P5E_CPU0_PE1_TX_DN<5>")
	)
	(arc
		(start 362.964984 -221.133924)
		(mid 362.890993 -221.41349)
		(end 362.688378 -221.619826)
		(width 0.0889)
		(layer "In2.Cu")
		(net "P5E_CPU0_PE1_TX_DN<5>")
	)
	(arc
		(start 362.682282 -217.388694)
		(mid 362.885763 -217.589498)
		(end 362.964984 -217.864182)
		(width 0.0889)
		(layer "In2.Cu")
		(net "P5E_CPU0_PE1_TX_DN<5>")
	)
	(arc
		(start 362.025184 -219.512642)
		(mid 362.074437 -219.691842)
		(end 362.203746 -219.825316)
		(width 0.0889)
		(layer "In2.Cu")
		(net "P5E_CPU0_PE1_TX_DN<5>")
	)
	(arc
		(start 362.025184 -216.257124)
		(mid 362.074437 -216.436324)
		(end 362.203746 -216.569798)
		(width 0.0889)
		(layer "In2.Cu")
		(net "P5E_CPU0_PE1_TX_DN<5>")
	)
	(arc
		(start 362.203746 -219.18676)
		(mid 362.075342 -219.318705)
		(end 362.025184 -219.495878)
		(width 0.0889)
		(layer "In2.Cu")
		(net "P5E_CPU0_PE1_TX_DN<5>")
	)
	(segment
		(start 421.382444 -18.824194)
		(end 421.382444 -18.205958)
		(width 0.13208)
		(layer "F.Cu")
		(net "P5E_CPU0_PE1_TX_DN<4>")
	)
	(segment
		(start 421.0812 -19.125438)
		(end 421.382444 -18.824194)
		(width 0.13208)
		(layer "F.Cu")
		(net "P5E_CPU0_PE1_TX_DN<4>")
	)
	(segment
		(start 363.339634 -224.925128)
		(end 363.339634 -224.389442)
		(width 0.13208)
		(layer "F.Cu")
		(net "P5E_CPU0_PE1_TX_DN<4>")
	)
	(segment
		(start 421.382444 -18.205958)
		(end 421.0558 -17.879314)
		(width 0.13208)
		(layer "F.Cu")
		(net "P5E_CPU0_PE1_TX_DN<4>")
	)
	(segment
		(start 363.33938 -224.925382)
		(end 363.339634 -224.925128)
		(width 0.13208)
		(layer "F.Cu")
		(net "P5E_CPU0_PE1_TX_DN<4>")
	)
	(segment
		(start 363.244384 -215.436196)
		(end 363.24413 -215.436704)
		(width 0.0889)
		(layer "In2.Cu")
		(net "P5E_CPU0_PE1_TX_DN<4>")
	)
	(segment
		(start 420.949628 -22.42566)
		(end 420.906956 -22.791928)
		(width 0.14732)
		(layer "In2.Cu")
		(net "P5E_CPU0_PE1_TX_DN<4>")
	)
	(segment
		(start 421.18407 -21.665946)
		(end 421.11041 -22.29866)
		(width 0.14732)
		(layer "In2.Cu")
		(net "P5E_CPU0_PE1_TX_DN<4>")
	)
	(segment
		(start 363.51464 -224.057972)
		(end 363.535722 -224.070164)
		(width 0.0889)
		(layer "In2.Cu")
		(net "P5E_CPU0_PE1_TX_DN<4>")
	)
	(segment
		(start 361.031536 -184.292748)
		(end 363.202474 -211.622894)
		(width 0.14732)
		(layer "In2.Cu")
		(net "P5E_CPU0_PE1_TX_DN<4>")
	)
	(segment
		(start 363.526832 -217.554048)
		(end 363.527594 -217.554556)
		(width 0.0889)
		(layer "In2.Cu")
		(net "P5E_CPU0_PE1_TX_DN<4>")
	)
	(segment
		(start 362.774484 -219.490544)
		(end 362.774484 -219.521532)
		(width 0.0889)
		(layer "In2.Cu")
		(net "P5E_CPU0_PE1_TX_DN<4>")
	)
	(segment
		(start 363.526832 -221.458282)
		(end 363.51464 -221.465394)
		(width 0.0889)
		(layer "In2.Cu")
		(net "P5E_CPU0_PE1_TX_DN<4>")
	)
	(segment
		(start 363.065568 -219.0115)
		(end 363.056678 -219.01658)
		(width 0.0889)
		(layer "In2.Cu")
		(net "P5E_CPU0_PE1_TX_DN<4>")
	)
	(segment
		(start 417.215828 -55.702708)
		(end 412.871158 -80.33385)
		(width 0.14732)
		(layer "In2.Cu")
		(net "P5E_CPU0_PE1_TX_DN<4>")
	)
	(segment
		(start 421.05707 -21.505164)
		(end 421.18407 -21.665946)
		(width 0.14732)
		(layer "In2.Cu")
		(net "P5E_CPU0_PE1_TX_DN<4>")
	)
	(segment
		(start 365.166402 -160.834324)
		(end 361.031536 -184.292748)
		(width 0.14732)
		(layer "In2.Cu")
		(net "P5E_CPU0_PE1_TX_DN<4>")
	)
	(segment
		(start 363.535722 -218.197684)
		(end 363.53369 -218.198954)
		(width 0.0889)
		(layer "In2.Cu")
		(net "P5E_CPU0_PE1_TX_DN<4>")
	)
	(segment
		(start 363.496098 -224.66046)
		(end 363.339634 -224.389442)
		(width 0.0889)
		(layer "In2.Cu")
		(net "P5E_CPU0_PE1_TX_DN<4>")
	)
	(segment
		(start 363.202474 -213.285324)
		(end 363.244384 -213.327234)
		(width 0.0889)
		(layer "In2.Cu")
		(net "P5E_CPU0_PE1_TX_DN<4>")
	)
	(segment
		(start 363.24413 -220.319854)
		(end 363.24413 -220.327474)
		(width 0.0889)
		(layer "In2.Cu")
		(net "P5E_CPU0_PE1_TX_DN<4>")
	)
	(segment
		(start 363.202474 -213.263226)
		(end 363.202474 -213.285324)
		(width 0.0889)
		(layer "In2.Cu")
		(net "P5E_CPU0_PE1_TX_DN<4>")
	)
	(segment
		(start 421.11041 -22.29866)
		(end 420.949628 -22.42566)
		(width 0.14732)
		(layer "In2.Cu")
		(net "P5E_CPU0_PE1_TX_DN<4>")
	)
	(segment
		(start 363.065568 -222.267018)
		(end 363.057694 -222.27159)
		(width 0.0889)
		(layer "In2.Cu")
		(net "P5E_CPU0_PE1_TX_DN<4>")
	)
	(segment
		(start 363.532166 -218.19997)
		(end 363.520736 -218.20632)
		(width 0.0889)
		(layer "In2.Cu")
		(net "P5E_CPU0_PE1_TX_DN<4>")
	)
	(segment
		(start 363.056678 -219.995496)
		(end 363.057694 -219.996004)
		(width 0.0889)
		(layer "In2.Cu")
		(net "P5E_CPU0_PE1_TX_DN<4>")
	)
	(segment
		(start 363.065568 -215.755982)
		(end 363.056678 -215.761062)
		(width 0.0889)
		(layer "In2.Cu")
		(net "P5E_CPU0_PE1_TX_DN<4>")
	)
	(segment
		(start 363.244384 -213.327234)
		(end 363.244384 -215.436196)
		(width 0.0889)
		(layer "In2.Cu")
		(net "P5E_CPU0_PE1_TX_DN<4>")
	)
	(segment
		(start 421.37584 -20.022312)
		(end 421.260524 -21.01215)
		(width 0.14732)
		(layer "In2.Cu")
		(net "P5E_CPU0_PE1_TX_DN<4>")
	)
	(segment
		(start 363.24413 -217.064336)
		(end 363.24413 -217.071956)
		(width 0.0889)
		(layer "In2.Cu")
		(net "P5E_CPU0_PE1_TX_DN<4>")
	)
	(segment
		(start 421.37584 -19.420078)
		(end 421.37584 -20.022312)
		(width 0.14732)
		(layer "In2.Cu")
		(net "P5E_CPU0_PE1_TX_DN<4>")
	)
	(segment
		(start 363.057694 -219.996004)
		(end 363.065568 -220.000576)
		(width 0.0889)
		(layer "In2.Cu")
		(net "P5E_CPU0_PE1_TX_DN<4>")
	)
	(segment
		(start 363.057694 -222.27159)
		(end 363.056678 -222.272098)
		(width 0.0889)
		(layer "In2.Cu")
		(net "P5E_CPU0_PE1_TX_DN<4>")
	)
	(segment
		(start 363.202474 -211.622894)
		(end 363.202474 -213.263226)
		(width 0.14732)
		(layer "In2.Cu")
		(net "P5E_CPU0_PE1_TX_DN<4>")
	)
	(segment
		(start 421.0812 -19.125438)
		(end 421.37584 -19.420078)
		(width 0.14732)
		(layer "In2.Cu")
		(net "P5E_CPU0_PE1_TX_DN<4>")
	)
	(segment
		(start 421.099742 -21.13915)
		(end 421.05707 -21.505164)
		(width 0.14732)
		(layer "In2.Cu")
		(net "P5E_CPU0_PE1_TX_DN<4>")
	)
	(segment
		(start 421.033956 -22.952456)
		(end 417.215828 -55.702708)
		(width 0.14732)
		(layer "In2.Cu")
		(net "P5E_CPU0_PE1_TX_DN<4>")
	)
	(segment
		(start 362.774484 -222.746062)
		(end 362.774484 -222.783654)
		(width 0.0889)
		(layer "In2.Cu")
		(net "P5E_CPU0_PE1_TX_DN<4>")
	)
	(segment
		(start 363.57433 -224.681288)
		(end 363.496098 -224.66046)
		(width 0.0889)
		(layer "In2.Cu")
		(net "P5E_CPU0_PE1_TX_DN<4>")
	)
	(segment
		(start 420.906956 -22.791928)
		(end 421.033956 -22.952456)
		(width 0.14732)
		(layer "In2.Cu")
		(net "P5E_CPU0_PE1_TX_DN<4>")
	)
	(segment
		(start 363.527594 -217.554556)
		(end 363.535722 -217.559128)
		(width 0.0889)
		(layer "In2.Cu")
		(net "P5E_CPU0_PE1_TX_DN<4>")
	)
	(segment
		(start 421.260524 -21.01215)
		(end 421.099742 -21.13915)
		(width 0.14732)
		(layer "In2.Cu")
		(net "P5E_CPU0_PE1_TX_DN<4>")
	)
	(segment
		(start 363.056678 -216.739978)
		(end 363.065568 -216.745058)
		(width 0.0889)
		(layer "In2.Cu")
		(net "P5E_CPU0_PE1_TX_DN<4>")
	)
	(segment
		(start 362.77423 -216.240614)
		(end 362.77423 -216.260426)
		(width 0.0889)
		(layer "In2.Cu")
		(net "P5E_CPU0_PE1_TX_DN<4>")
	)
	(segment
		(start 412.871158 -80.33385)
		(end 365.166402 -160.834324)
		(width 0.14732)
		(layer "In2.Cu")
		(net "P5E_CPU0_PE1_TX_DN<4>")
	)
	(segment
		(start 363.53369 -218.198954)
		(end 363.532166 -218.19997)
		(width 0.0889)
		(layer "In2.Cu")
		(net "P5E_CPU0_PE1_TX_DN<4>")
	)
	(segment
		(start 363.056678 -223.251268)
		(end 363.065568 -223.256348)
		(width 0.0889)
		(layer "In2.Cu")
		(net "P5E_CPU0_PE1_TX_DN<4>")
	)
	(arc
		(start 363.056678 -219.01658)
		(mid 362.853855 -219.216811)
		(end 362.774484 -219.490544)
		(width 0.0889)
		(layer "In2.Cu")
		(net "P5E_CPU0_PE1_TX_DN<4>")
	)
	(arc
		(start 362.774484 -219.521532)
		(mid 362.853854 -219.795266)
		(end 363.056678 -219.995496)
		(width 0.0889)
		(layer "In2.Cu")
		(net "P5E_CPU0_PE1_TX_DN<4>")
	)
	(arc
		(start 363.24413 -221.94774)
		(mid 363.196451 -222.13064)
		(end 363.065568 -222.267018)
		(width 0.0889)
		(layer "In2.Cu")
		(net "P5E_CPU0_PE1_TX_DN<4>")
	)
	(arc
		(start 363.24413 -217.071956)
		(mid 363.321759 -217.350369)
		(end 363.526832 -217.554048)
		(width 0.0889)
		(layer "In2.Cu")
		(net "P5E_CPU0_PE1_TX_DN<4>")
	)
	(arc
		(start 363.535722 -217.559128)
		(mid 363.714319 -217.878406)
		(end 363.535722 -218.197684)
		(width 0.0889)
		(layer "In2.Cu")
		(net "P5E_CPU0_PE1_TX_DN<4>")
	)
	(arc
		(start 363.535722 -224.070164)
		(mid 363.71357 -224.365756)
		(end 363.57433 -224.681288)
		(width 0.0889)
		(layer "In2.Cu")
		(net "P5E_CPU0_PE1_TX_DN<4>")
	)
	(arc
		(start 362.77423 -216.260426)
		(mid 362.852341 -216.537375)
		(end 363.056678 -216.739978)
		(width 0.0889)
		(layer "In2.Cu")
		(net "P5E_CPU0_PE1_TX_DN<4>")
	)
	(arc
		(start 363.24413 -220.327474)
		(mid 363.321759 -220.605887)
		(end 363.526832 -220.809566)
		(width 0.0889)
		(layer "In2.Cu")
		(net "P5E_CPU0_PE1_TX_DN<4>")
	)
	(arc
		(start 363.24413 -223.575626)
		(mid 363.316365 -223.85215)
		(end 363.51464 -224.057972)
		(width 0.0889)
		(layer "In2.Cu")
		(net "P5E_CPU0_PE1_TX_DN<4>")
	)
	(arc
		(start 363.056678 -222.272098)
		(mid 362.853855 -222.472329)
		(end 362.774484 -222.746062)
		(width 0.0889)
		(layer "In2.Cu")
		(net "P5E_CPU0_PE1_TX_DN<4>")
	)
	(arc
		(start 363.520736 -218.20632)
		(mid 363.318149 -218.412671)
		(end 363.24413 -218.692222)
		(width 0.0889)
		(layer "In2.Cu")
		(net "P5E_CPU0_PE1_TX_DN<4>")
	)
	(arc
		(start 363.065568 -216.745058)
		(mid 363.196482 -216.881418)
		(end 363.24413 -217.064336)
		(width 0.0889)
		(layer "In2.Cu")
		(net "P5E_CPU0_PE1_TX_DN<4>")
	)
	(arc
		(start 363.24413 -218.692222)
		(mid 363.196451 -218.875122)
		(end 363.065568 -219.0115)
		(width 0.0889)
		(layer "In2.Cu")
		(net "P5E_CPU0_PE1_TX_DN<4>")
	)
	(arc
		(start 362.774484 -222.783654)
		(mid 362.855395 -223.053782)
		(end 363.056678 -223.251268)
		(width 0.0889)
		(layer "In2.Cu")
		(net "P5E_CPU0_PE1_TX_DN<4>")
	)
	(arc
		(start 363.065568 -220.000576)
		(mid 363.196482 -220.136936)
		(end 363.24413 -220.319854)
		(width 0.0889)
		(layer "In2.Cu")
		(net "P5E_CPU0_PE1_TX_DN<4>")
	)
	(arc
		(start 363.24413 -215.436704)
		(mid 363.196451 -215.619604)
		(end 363.065568 -215.755982)
		(width 0.0889)
		(layer "In2.Cu")
		(net "P5E_CPU0_PE1_TX_DN<4>")
	)
	(arc
		(start 363.51464 -221.465394)
		(mid 363.316412 -221.671242)
		(end 363.24413 -221.94774)
		(width 0.0889)
		(layer "In2.Cu")
		(net "P5E_CPU0_PE1_TX_DN<4>")
	)
	(arc
		(start 363.526832 -220.809566)
		(mid 363.714135 -221.133924)
		(end 363.526832 -221.458282)
		(width 0.0889)
		(layer "In2.Cu")
		(net "P5E_CPU0_PE1_TX_DN<4>")
	)
	(arc
		(start 363.065568 -223.256348)
		(mid 363.196482 -223.392708)
		(end 363.24413 -223.575626)
		(width 0.0889)
		(layer "In2.Cu")
		(net "P5E_CPU0_PE1_TX_DN<4>")
	)
	(arc
		(start 363.056678 -215.761062)
		(mid 362.852343 -215.963667)
		(end 362.77423 -216.240614)
		(width 0.0889)
		(layer "In2.Cu")
		(net "P5E_CPU0_PE1_TX_DN<4>")
	)
	(segment
		(start 424.435524 -17.298162)
		(end 424.435524 -16.68399)
		(width 0.13208)
		(layer "F.Cu")
		(net "P5E_CPU0_PE1_TX_DN<3>")
	)
	(segment
		(start 424.7388 -17.601438)
		(end 424.435524 -17.298162)
		(width 0.13208)
		(layer "F.Cu")
		(net "P5E_CPU0_PE1_TX_DN<3>")
	)
	(segment
		(start 364.749334 -223.57588)
		(end 364.74908 -223.575626)
		(width 0.13208)
		(layer "F.Cu")
		(net "P5E_CPU0_PE1_TX_DN<3>")
	)
	(segment
		(start 364.749334 -224.111566)
		(end 364.749334 -223.57588)
		(width 0.13208)
		(layer "F.Cu")
		(net "P5E_CPU0_PE1_TX_DN<3>")
	)
	(segment
		(start 424.435524 -16.68399)
		(end 424.7642 -16.355314)
		(width 0.13208)
		(layer "F.Cu")
		(net "P5E_CPU0_PE1_TX_DN<3>")
	)
	(segment
		(start 362.259118 -184.266078)
		(end 364.41634 -211.541868)
		(width 0.14732)
		(layer "In2.Cu")
		(net "P5E_CPU0_PE1_TX_DN<3>")
	)
	(segment
		(start 364.092236 -219.18168)
		(end 364.083346 -219.18676)
		(width 0.0889)
		(layer "In2.Cu")
		(net "P5E_CPU0_PE1_TX_DN<3>")
	)
	(segment
		(start 364.592616 -223.846644)
		(end 364.74908 -223.575626)
		(width 0.0889)
		(layer "In2.Cu")
		(net "P5E_CPU0_PE1_TX_DN<3>")
	)
	(segment
		(start 424.44416 -19.552666)
		(end 424.327574 -19.901916)
		(width 0.14732)
		(layer "In2.Cu")
		(net "P5E_CPU0_PE1_TX_DN<3>")
	)
	(segment
		(start 364.41634 -213.285324)
		(end 364.374176 -213.327488)
		(width 0.0889)
		(layer "In2.Cu")
		(net "P5E_CPU0_PE1_TX_DN<3>")
	)
	(segment
		(start 424.58894 -19.039586)
		(end 424.44416 -19.184366)
		(width 0.14732)
		(layer "In2.Cu")
		(net "P5E_CPU0_PE1_TX_DN<3>")
	)
	(segment
		(start 364.844584 -217.864182)
		(end 364.844584 -217.878406)
		(width 0.0889)
		(layer "In2.Cu")
		(net "P5E_CPU0_PE1_TX_DN<3>")
	)
	(segment
		(start 418.71392 -54.149244)
		(end 414.010348 -80.82026)
		(width 0.14732)
		(layer "In2.Cu")
		(net "P5E_CPU0_PE1_TX_DN<3>")
	)
	(segment
		(start 364.281466 -215.608408)
		(end 364.012988 -215.876886)
		(width 0.0889)
		(layer "In2.Cu")
		(net "P5E_CPU0_PE1_TX_DN<3>")
	)
	(segment
		(start 364.374684 -223.557084)
		(end 364.374684 -223.584262)
		(width 0.0889)
		(layer "In2.Cu")
		(net "P5E_CPU0_PE1_TX_DN<3>")
	)
	(segment
		(start 364.562644 -221.622874)
		(end 364.552992 -221.628462)
		(width 0.0889)
		(layer "In2.Cu")
		(net "P5E_CPU0_PE1_TX_DN<3>")
	)
	(segment
		(start 364.083346 -219.825316)
		(end 364.092236 -219.830396)
		(width 0.0889)
		(layer "In2.Cu")
		(net "P5E_CPU0_PE1_TX_DN<3>")
	)
	(segment
		(start 424.7388 -17.601438)
		(end 424.44416 -17.896078)
		(width 0.14732)
		(layer "In2.Cu")
		(net "P5E_CPU0_PE1_TX_DN<3>")
	)
	(segment
		(start 366.303306 -161.323782)
		(end 362.259118 -184.266078)
		(width 0.14732)
		(layer "In2.Cu")
		(net "P5E_CPU0_PE1_TX_DN<3>")
	)
	(segment
		(start 364.567978 -221.619826)
		(end 364.562644 -221.622874)
		(width 0.0889)
		(layer "In2.Cu")
		(net "P5E_CPU0_PE1_TX_DN<3>")
	)
	(segment
		(start 424.302174 -20.434554)
		(end 424.118786 -20.525994)
		(width 0.14732)
		(layer "In2.Cu")
		(net "P5E_CPU0_PE1_TX_DN<3>")
	)
	(segment
		(start 364.374684 -217.05443)
		(end 364.374684 -217.072972)
		(width 0.0889)
		(layer "In2.Cu")
		(net "P5E_CPU0_PE1_TX_DN<3>")
	)
	(segment
		(start 424.327574 -19.901916)
		(end 424.419014 -20.08505)
		(width 0.14732)
		(layer "In2.Cu")
		(net "P5E_CPU0_PE1_TX_DN<3>")
	)
	(segment
		(start 364.083346 -223.080834)
		(end 364.092236 -223.085914)
		(width 0.0889)
		(layer "In2.Cu")
		(net "P5E_CPU0_PE1_TX_DN<3>")
	)
	(segment
		(start 364.514638 -223.867472)
		(end 364.592616 -223.846644)
		(width 0.0889)
		(layer "In2.Cu")
		(net "P5E_CPU0_PE1_TX_DN<3>")
	)
	(segment
		(start 424.44416 -19.184366)
		(end 424.44416 -19.552666)
		(width 0.14732)
		(layer "In2.Cu")
		(net "P5E_CPU0_PE1_TX_DN<3>")
	)
	(segment
		(start 364.092236 -222.437198)
		(end 364.083346 -222.442278)
		(width 0.0889)
		(layer "In2.Cu")
		(net "P5E_CPU0_PE1_TX_DN<3>")
	)
	(segment
		(start 422.93286 -24.073866)
		(end 418.71392 -54.149244)
		(width 0.14732)
		(layer "In2.Cu")
		(net "P5E_CPU0_PE1_TX_DN<3>")
	)
	(segment
		(start 424.44416 -18.55851)
		(end 424.58894 -18.70329)
		(width 0.14732)
		(layer "In2.Cu")
		(net "P5E_CPU0_PE1_TX_DN<3>")
	)
	(segment
		(start 424.58894 -18.70329)
		(end 424.58894 -19.039586)
		(width 0.14732)
		(layer "In2.Cu")
		(net "P5E_CPU0_PE1_TX_DN<3>")
	)
	(segment
		(start 364.844584 -221.1197)
		(end 364.844584 -221.133924)
		(width 0.0889)
		(layer "In2.Cu")
		(net "P5E_CPU0_PE1_TX_DN<3>")
	)
	(segment
		(start 424.44416 -17.896078)
		(end 424.44416 -18.55851)
		(width 0.14732)
		(layer "In2.Cu")
		(net "P5E_CPU0_PE1_TX_DN<3>")
	)
	(segment
		(start 364.083346 -216.569798)
		(end 364.092236 -216.574878)
		(width 0.0889)
		(layer "In2.Cu")
		(net "P5E_CPU0_PE1_TX_DN<3>")
	)
	(segment
		(start 364.41634 -211.541868)
		(end 364.41634 -213.263226)
		(width 0.14732)
		(layer "In2.Cu")
		(net "P5E_CPU0_PE1_TX_DN<3>")
	)
	(segment
		(start 364.37443 -218.692222)
		(end 364.37443 -218.707716)
		(width 0.0889)
		(layer "In2.Cu")
		(net "P5E_CPU0_PE1_TX_DN<3>")
	)
	(segment
		(start 364.41634 -213.263226)
		(end 364.41634 -213.285324)
		(width 0.0889)
		(layer "In2.Cu")
		(net "P5E_CPU0_PE1_TX_DN<3>")
	)
	(segment
		(start 364.567978 -218.364308)
		(end 364.552992 -218.372944)
		(width 0.0889)
		(layer "In2.Cu")
		(net "P5E_CPU0_PE1_TX_DN<3>")
	)
	(segment
		(start 424.419014 -20.08505)
		(end 424.302174 -20.434554)
		(width 0.14732)
		(layer "In2.Cu")
		(net "P5E_CPU0_PE1_TX_DN<3>")
	)
	(segment
		(start 414.010348 -80.82026)
		(end 366.303306 -161.323782)
		(width 0.14732)
		(layer "In2.Cu")
		(net "P5E_CPU0_PE1_TX_DN<3>")
	)
	(segment
		(start 424.118786 -20.525994)
		(end 422.93286 -24.073866)
		(width 0.14732)
		(layer "In2.Cu")
		(net "P5E_CPU0_PE1_TX_DN<3>")
	)
	(segment
		(start 363.904784 -216.138252)
		(end 363.904784 -216.25052)
		(width 0.0889)
		(layer "In2.Cu")
		(net "P5E_CPU0_PE1_TX_DN<3>")
	)
	(segment
		(start 364.374176 -213.327488)
		(end 364.374176 -215.38438)
		(width 0.0889)
		(layer "In2.Cu")
		(net "P5E_CPU0_PE1_TX_DN<3>")
	)
	(segment
		(start 364.374684 -220.309948)
		(end 364.374684 -220.32849)
		(width 0.0889)
		(layer "In2.Cu")
		(net "P5E_CPU0_PE1_TX_DN<3>")
	)
	(segment
		(start 364.37443 -221.94774)
		(end 364.37443 -221.963234)
		(width 0.0889)
		(layer "In2.Cu")
		(net "P5E_CPU0_PE1_TX_DN<3>")
	)
	(arc
		(start 363.904784 -216.25052)
		(mid 363.952463 -216.43342)
		(end 364.083346 -216.569798)
		(width 0.0889)
		(layer "In2.Cu")
		(net "P5E_CPU0_PE1_TX_DN<3>")
	)
	(arc
		(start 364.083346 -219.18676)
		(mid 363.954942 -219.318705)
		(end 363.904784 -219.495878)
		(width 0.0889)
		(layer "In2.Cu")
		(net "P5E_CPU0_PE1_TX_DN<3>")
	)
	(arc
		(start 363.905038 -222.773748)
		(mid 363.955509 -222.949756)
		(end 364.083346 -223.080834)
		(width 0.0889)
		(layer "In2.Cu")
		(net "P5E_CPU0_PE1_TX_DN<3>")
	)
	(arc
		(start 363.904784 -219.495878)
		(mid 363.90469 -219.50426)
		(end 363.904784 -219.512642)
		(width 0.0889)
		(layer "In2.Cu")
		(net "P5E_CPU0_PE1_TX_DN<3>")
	)
	(arc
		(start 364.092236 -219.830396)
		(mid 364.296571 -220.033001)
		(end 364.374684 -220.309948)
		(width 0.0889)
		(layer "In2.Cu")
		(net "P5E_CPU0_PE1_TX_DN<3>")
	)
	(arc
		(start 364.083346 -222.442278)
		(mid 363.955027 -222.57425)
		(end 363.905038 -222.751396)
		(width 0.0889)
		(layer "In2.Cu")
		(net "P5E_CPU0_PE1_TX_DN<3>")
	)
	(arc
		(start 364.37443 -221.963234)
		(mid 364.29506 -222.236968)
		(end 364.092236 -222.437198)
		(width 0.0889)
		(layer "In2.Cu")
		(net "P5E_CPU0_PE1_TX_DN<3>")
	)
	(arc
		(start 364.844584 -221.133924)
		(mid 364.770593 -221.41349)
		(end 364.567978 -221.619826)
		(width 0.0889)
		(layer "In2.Cu")
		(net "P5E_CPU0_PE1_TX_DN<3>")
	)
	(arc
		(start 364.561882 -217.388694)
		(mid 364.765363 -217.589498)
		(end 364.844584 -217.864182)
		(width 0.0889)
		(layer "In2.Cu")
		(net "P5E_CPU0_PE1_TX_DN<3>")
	)
	(arc
		(start 364.374684 -223.584262)
		(mid 364.413358 -223.74133)
		(end 364.514638 -223.867472)
		(width 0.0889)
		(layer "In2.Cu")
		(net "P5E_CPU0_PE1_TX_DN<3>")
	)
	(arc
		(start 364.374684 -217.072972)
		(mid 364.426954 -217.255337)
		(end 364.561882 -217.388694)
		(width 0.0889)
		(layer "In2.Cu")
		(net "P5E_CPU0_PE1_TX_DN<3>")
	)
	(arc
		(start 364.374176 -215.38438)
		(mid 364.350149 -215.505644)
		(end 364.281466 -215.608408)
		(width 0.0889)
		(layer "In2.Cu")
		(net "P5E_CPU0_PE1_TX_DN<3>")
	)
	(arc
		(start 364.374684 -220.32849)
		(mid 364.426954 -220.510855)
		(end 364.561882 -220.644212)
		(width 0.0889)
		(layer "In2.Cu")
		(net "P5E_CPU0_PE1_TX_DN<3>")
	)
	(arc
		(start 363.904784 -219.512642)
		(mid 363.954037 -219.691842)
		(end 364.083346 -219.825316)
		(width 0.0889)
		(layer "In2.Cu")
		(net "P5E_CPU0_PE1_TX_DN<3>")
	)
	(arc
		(start 364.561882 -220.644212)
		(mid 364.765363 -220.845016)
		(end 364.844584 -221.1197)
		(width 0.0889)
		(layer "In2.Cu")
		(net "P5E_CPU0_PE1_TX_DN<3>")
	)
	(arc
		(start 364.552992 -221.628462)
		(mid 364.422078 -221.764822)
		(end 364.37443 -221.94774)
		(width 0.0889)
		(layer "In2.Cu")
		(net "P5E_CPU0_PE1_TX_DN<3>")
	)
	(arc
		(start 363.905038 -222.751396)
		(mid 363.904871 -222.762572)
		(end 363.905038 -222.773748)
		(width 0.0889)
		(layer "In2.Cu")
		(net "P5E_CPU0_PE1_TX_DN<3>")
	)
	(arc
		(start 364.37443 -218.707716)
		(mid 364.29506 -218.98145)
		(end 364.092236 -219.18168)
		(width 0.0889)
		(layer "In2.Cu")
		(net "P5E_CPU0_PE1_TX_DN<3>")
	)
	(arc
		(start 364.012988 -215.876886)
		(mid 363.932917 -215.996816)
		(end 363.904784 -216.138252)
		(width 0.0889)
		(layer "In2.Cu")
		(net "P5E_CPU0_PE1_TX_DN<3>")
	)
	(arc
		(start 364.092236 -223.085914)
		(mid 364.294522 -223.284895)
		(end 364.374684 -223.557084)
		(width 0.0889)
		(layer "In2.Cu")
		(net "P5E_CPU0_PE1_TX_DN<3>")
	)
	(arc
		(start 364.092236 -216.574878)
		(mid 364.296571 -216.777483)
		(end 364.374684 -217.05443)
		(width 0.0889)
		(layer "In2.Cu")
		(net "P5E_CPU0_PE1_TX_DN<3>")
	)
	(arc
		(start 364.844584 -217.878406)
		(mid 364.770593 -218.157972)
		(end 364.567978 -218.364308)
		(width 0.0889)
		(layer "In2.Cu")
		(net "P5E_CPU0_PE1_TX_DN<3>")
	)
	(arc
		(start 364.552992 -218.372944)
		(mid 364.422078 -218.509304)
		(end 364.37443 -218.692222)
		(width 0.0889)
		(layer "In2.Cu")
		(net "P5E_CPU0_PE1_TX_DN<3>")
	)
	(segment
		(start 427.00448 -18.824194)
		(end 427.00448 -18.205958)
		(width 0.13208)
		(layer "F.Cu")
		(net "P5E_CPU0_PE1_TX_DN<2>")
	)
	(segment
		(start 426.703236 -19.125438)
		(end 427.00448 -18.824194)
		(width 0.13208)
		(layer "F.Cu")
		(net "P5E_CPU0_PE1_TX_DN<2>")
	)
	(segment
		(start 365.21898 -224.389696)
		(end 365.219234 -224.389442)
		(width 0.13208)
		(layer "F.Cu")
		(net "P5E_CPU0_PE1_TX_DN<2>")
	)
	(segment
		(start 365.21898 -224.925382)
		(end 365.21898 -224.389696)
		(width 0.13208)
		(layer "F.Cu")
		(net "P5E_CPU0_PE1_TX_DN<2>")
	)
	(segment
		(start 427.00448 -18.205958)
		(end 426.677836 -17.879314)
		(width 0.13208)
		(layer "F.Cu")
		(net "P5E_CPU0_PE1_TX_DN<2>")
	)
	(segment
		(start 364.945168 -216.745058)
		(end 364.937294 -216.740486)
		(width 0.0889)
		(layer "In2.Cu")
		(net "P5E_CPU0_PE1_TX_DN<2>")
	)
	(segment
		(start 366.916208 -161.622486)
		(end 414.63087 -81.105502)
		(width 0.14732)
		(layer "In2.Cu")
		(net "P5E_CPU0_PE1_TX_DN<2>")
	)
	(segment
		(start 365.406432 -224.065084)
		(end 365.39424 -224.057972)
		(width 0.0889)
		(layer "In2.Cu")
		(net "P5E_CPU0_PE1_TX_DN<2>")
	)
	(segment
		(start 426.141642 -21.2598)
		(end 426.305472 -20.929854)
		(width 0.14732)
		(layer "In2.Cu")
		(net "P5E_CPU0_PE1_TX_DN<2>")
	)
	(segment
		(start 364.937294 -219.996004)
		(end 364.936278 -219.995496)
		(width 0.0889)
		(layer "In2.Cu")
		(net "P5E_CPU0_PE1_TX_DN<2>")
	)
	(segment
		(start 419.391338 -54.092348)
		(end 421.404796 -40.38981)
		(width 0.14732)
		(layer "In2.Cu")
		(net "P5E_CPU0_PE1_TX_DN<2>")
	)
	(segment
		(start 426.979334 -19.899884)
		(end 426.997876 -19.821144)
		(width 0.14732)
		(layer "In2.Cu")
		(net "P5E_CPU0_PE1_TX_DN<2>")
	)
	(segment
		(start 364.936278 -215.761062)
		(end 364.94085 -215.758522)
		(width 0.0889)
		(layer "In2.Cu")
		(net "P5E_CPU0_PE1_TX_DN<2>")
	)
	(segment
		(start 364.945168 -223.256348)
		(end 364.936278 -223.251268)
		(width 0.0889)
		(layer "In2.Cu")
		(net "P5E_CPU0_PE1_TX_DN<2>")
	)
	(segment
		(start 426.500036 -20.864576)
		(end 426.979334 -19.899884)
		(width 0.14732)
		(layer "In2.Cu")
		(net "P5E_CPU0_PE1_TX_DN<2>")
	)
	(segment
		(start 365.403638 -221.459806)
		(end 365.406432 -221.458282)
		(width 0.0889)
		(layer "In2.Cu")
		(net "P5E_CPU0_PE1_TX_DN<2>")
	)
	(segment
		(start 365.082074 -211.642706)
		(end 362.921804 -184.282588)
		(width 0.14732)
		(layer "In2.Cu")
		(net "P5E_CPU0_PE1_TX_DN<2>")
	)
	(segment
		(start 365.407956 -221.45752)
		(end 365.415322 -221.453202)
		(width 0.0889)
		(layer "In2.Cu")
		(net "P5E_CPU0_PE1_TX_DN<2>")
	)
	(segment
		(start 365.219234 -224.389442)
		(end 365.375698 -224.66046)
		(width 0.0889)
		(layer "In2.Cu")
		(net "P5E_CPU0_PE1_TX_DN<2>")
	)
	(segment
		(start 365.375698 -224.66046)
		(end 365.45393 -224.681288)
		(width 0.0889)
		(layer "In2.Cu")
		(net "P5E_CPU0_PE1_TX_DN<2>")
	)
	(segment
		(start 365.407194 -217.554556)
		(end 365.406432 -217.554048)
		(width 0.0889)
		(layer "In2.Cu")
		(net "P5E_CPU0_PE1_TX_DN<2>")
	)
	(segment
		(start 421.404796 -40.38981)
		(end 421.404796 -40.389048)
		(width 0.14732)
		(layer "In2.Cu")
		(net "P5E_CPU0_PE1_TX_DN<2>")
	)
	(segment
		(start 365.415322 -217.559128)
		(end 365.407194 -217.554556)
		(width 0.0889)
		(layer "In2.Cu")
		(net "P5E_CPU0_PE1_TX_DN<2>")
	)
	(segment
		(start 425.567856 -22.739604)
		(end 425.502578 -22.545548)
		(width 0.14732)
		(layer "In2.Cu")
		(net "P5E_CPU0_PE1_TX_DN<2>")
	)
	(segment
		(start 365.406432 -218.202764)
		(end 365.415322 -218.197684)
		(width 0.0889)
		(layer "In2.Cu")
		(net "P5E_CPU0_PE1_TX_DN<2>")
	)
	(segment
		(start 365.406432 -221.458282)
		(end 365.407956 -221.45752)
		(width 0.0889)
		(layer "In2.Cu")
		(net "P5E_CPU0_PE1_TX_DN<2>")
	)
	(segment
		(start 426.997876 -19.420078)
		(end 426.703236 -19.125438)
		(width 0.14732)
		(layer "In2.Cu")
		(net "P5E_CPU0_PE1_TX_DN<2>")
	)
	(segment
		(start 423.340022 -27.221688)
		(end 425.567856 -22.739604)
		(width 0.14732)
		(layer "In2.Cu")
		(net "P5E_CPU0_PE1_TX_DN<2>")
	)
	(segment
		(start 364.654084 -216.266014)
		(end 364.654084 -216.235026)
		(width 0.0889)
		(layer "In2.Cu")
		(net "P5E_CPU0_PE1_TX_DN<2>")
	)
	(segment
		(start 365.400336 -221.461838)
		(end 365.403638 -221.459806)
		(width 0.0889)
		(layer "In2.Cu")
		(net "P5E_CPU0_PE1_TX_DN<2>")
	)
	(segment
		(start 362.921804 -184.282588)
		(end 366.916208 -161.622486)
		(width 0.14732)
		(layer "In2.Cu")
		(net "P5E_CPU0_PE1_TX_DN<2>")
	)
	(segment
		(start 426.20692 -21.453856)
		(end 426.141642 -21.2598)
		(width 0.14732)
		(layer "In2.Cu")
		(net "P5E_CPU0_PE1_TX_DN<2>")
	)
	(segment
		(start 364.936278 -222.272098)
		(end 364.945168 -222.267018)
		(width 0.0889)
		(layer "In2.Cu")
		(net "P5E_CPU0_PE1_TX_DN<2>")
	)
	(segment
		(start 364.94085 -215.758522)
		(end 364.945168 -215.755982)
		(width 0.0889)
		(layer "In2.Cu")
		(net "P5E_CPU0_PE1_TX_DN<2>")
	)
	(segment
		(start 364.937294 -216.740486)
		(end 364.936278 -216.739978)
		(width 0.0889)
		(layer "In2.Cu")
		(net "P5E_CPU0_PE1_TX_DN<2>")
	)
	(segment
		(start 419.372796 -54.21884)
		(end 419.394386 -54.096158)
		(width 0.14732)
		(layer "In2.Cu")
		(net "P5E_CPU0_PE1_TX_DN<2>")
	)
	(segment
		(start 421.404796 -40.389048)
		(end 423.340022 -27.221688)
		(width 0.14732)
		(layer "In2.Cu")
		(net "P5E_CPU0_PE1_TX_DN<2>")
	)
	(segment
		(start 365.415322 -224.070164)
		(end 365.406432 -224.065084)
		(width 0.0889)
		(layer "In2.Cu")
		(net "P5E_CPU0_PE1_TX_DN<2>")
	)
	(segment
		(start 426.997876 -19.821144)
		(end 426.997876 -19.420078)
		(width 0.14732)
		(layer "In2.Cu")
		(net "P5E_CPU0_PE1_TX_DN<2>")
	)
	(segment
		(start 419.394386 -54.096158)
		(end 419.391338 -54.092348)
		(width 0.14732)
		(layer "In2.Cu")
		(net "P5E_CPU0_PE1_TX_DN<2>")
	)
	(segment
		(start 414.63087 -81.105502)
		(end 419.372796 -54.21884)
		(width 0.14732)
		(layer "In2.Cu")
		(net "P5E_CPU0_PE1_TX_DN<2>")
	)
	(segment
		(start 425.502578 -22.545548)
		(end 425.666408 -22.215602)
		(width 0.14732)
		(layer "In2.Cu")
		(net "P5E_CPU0_PE1_TX_DN<2>")
	)
	(segment
		(start 364.936278 -219.01658)
		(end 364.945168 -219.0115)
		(width 0.0889)
		(layer "In2.Cu")
		(net "P5E_CPU0_PE1_TX_DN<2>")
	)
	(segment
		(start 425.860718 -22.150324)
		(end 426.20692 -21.453856)
		(width 0.14732)
		(layer "In2.Cu")
		(net "P5E_CPU0_PE1_TX_DN<2>")
	)
	(segment
		(start 365.407194 -220.810074)
		(end 365.406432 -220.809566)
		(width 0.0889)
		(layer "In2.Cu")
		(net "P5E_CPU0_PE1_TX_DN<2>")
	)
	(segment
		(start 425.666408 -22.215602)
		(end 425.860718 -22.150324)
		(width 0.14732)
		(layer "In2.Cu")
		(net "P5E_CPU0_PE1_TX_DN<2>")
	)
	(segment
		(start 365.082074 -213.263226)
		(end 365.082074 -211.642706)
		(width 0.14732)
		(layer "In2.Cu")
		(net "P5E_CPU0_PE1_TX_DN<2>")
	)
	(segment
		(start 364.654084 -222.783654)
		(end 364.654084 -222.746062)
		(width 0.0889)
		(layer "In2.Cu")
		(net "P5E_CPU0_PE1_TX_DN<2>")
	)
	(segment
		(start 365.12373 -217.071956)
		(end 365.12373 -217.064336)
		(width 0.0889)
		(layer "In2.Cu")
		(net "P5E_CPU0_PE1_TX_DN<2>")
	)
	(segment
		(start 365.123984 -213.327234)
		(end 365.082074 -213.285324)
		(width 0.0889)
		(layer "In2.Cu")
		(net "P5E_CPU0_PE1_TX_DN<2>")
	)
	(segment
		(start 364.654084 -219.521532)
		(end 364.654084 -219.490544)
		(width 0.0889)
		(layer "In2.Cu")
		(net "P5E_CPU0_PE1_TX_DN<2>")
	)
	(segment
		(start 365.123984 -215.43645)
		(end 365.123984 -213.327234)
		(width 0.0889)
		(layer "In2.Cu")
		(net "P5E_CPU0_PE1_TX_DN<2>")
	)
	(segment
		(start 365.400336 -218.20632)
		(end 365.406432 -218.202764)
		(width 0.0889)
		(layer "In2.Cu")
		(net "P5E_CPU0_PE1_TX_DN<2>")
	)
	(segment
		(start 365.082074 -213.285324)
		(end 365.082074 -213.263226)
		(width 0.0889)
		(layer "In2.Cu")
		(net "P5E_CPU0_PE1_TX_DN<2>")
	)
	(segment
		(start 364.945168 -220.000576)
		(end 364.937294 -219.996004)
		(width 0.0889)
		(layer "In2.Cu")
		(net "P5E_CPU0_PE1_TX_DN<2>")
	)
	(segment
		(start 365.415322 -220.814646)
		(end 365.407194 -220.810074)
		(width 0.0889)
		(layer "In2.Cu")
		(net "P5E_CPU0_PE1_TX_DN<2>")
	)
	(segment
		(start 365.12373 -215.436704)
		(end 365.123984 -215.43645)
		(width 0.0889)
		(layer "In2.Cu")
		(net "P5E_CPU0_PE1_TX_DN<2>")
	)
	(segment
		(start 426.305472 -20.929854)
		(end 426.500036 -20.864576)
		(width 0.14732)
		(layer "In2.Cu")
		(net "P5E_CPU0_PE1_TX_DN<2>")
	)
	(segment
		(start 365.12373 -220.327474)
		(end 365.12373 -220.319854)
		(width 0.0889)
		(layer "In2.Cu")
		(net "P5E_CPU0_PE1_TX_DN<2>")
	)
	(arc
		(start 364.945168 -215.755982)
		(mid 365.076082 -215.619622)
		(end 365.12373 -215.436704)
		(width 0.0889)
		(layer "In2.Cu")
		(net "P5E_CPU0_PE1_TX_DN<2>")
	)
	(arc
		(start 365.12373 -218.692222)
		(mid 365.197721 -218.412656)
		(end 365.400336 -218.20632)
		(width 0.0889)
		(layer "In2.Cu")
		(net "P5E_CPU0_PE1_TX_DN<2>")
	)
	(arc
		(start 364.936278 -223.251268)
		(mid 364.734996 -223.053781)
		(end 364.654084 -222.783654)
		(width 0.0889)
		(layer "In2.Cu")
		(net "P5E_CPU0_PE1_TX_DN<2>")
	)
	(arc
		(start 365.45393 -224.681288)
		(mid 365.557075 -224.551263)
		(end 365.593884 -224.389442)
		(width 0.0889)
		(layer "In2.Cu")
		(net "P5E_CPU0_PE1_TX_DN<2>")
	)
	(arc
		(start 364.936278 -216.739978)
		(mid 364.733455 -216.539747)
		(end 364.654084 -216.266014)
		(width 0.0889)
		(layer "In2.Cu")
		(net "P5E_CPU0_PE1_TX_DN<2>")
	)
	(arc
		(start 365.406432 -220.809566)
		(mid 365.20136 -220.605887)
		(end 365.12373 -220.327474)
		(width 0.0889)
		(layer "In2.Cu")
		(net "P5E_CPU0_PE1_TX_DN<2>")
	)
	(arc
		(start 364.654084 -219.490544)
		(mid 364.733454 -219.21681)
		(end 364.936278 -219.01658)
		(width 0.0889)
		(layer "In2.Cu")
		(net "P5E_CPU0_PE1_TX_DN<2>")
	)
	(arc
		(start 365.415322 -221.453202)
		(mid 365.593919 -221.133924)
		(end 365.415322 -220.814646)
		(width 0.0889)
		(layer "In2.Cu")
		(net "P5E_CPU0_PE1_TX_DN<2>")
	)
	(arc
		(start 364.654084 -222.746062)
		(mid 364.733454 -222.472328)
		(end 364.936278 -222.272098)
		(width 0.0889)
		(layer "In2.Cu")
		(net "P5E_CPU0_PE1_TX_DN<2>")
	)
	(arc
		(start 365.406432 -217.554048)
		(mid 365.20136 -217.350369)
		(end 365.12373 -217.071956)
		(width 0.0889)
		(layer "In2.Cu")
		(net "P5E_CPU0_PE1_TX_DN<2>")
	)
	(arc
		(start 365.12373 -217.064336)
		(mid 365.076051 -216.881436)
		(end 364.945168 -216.745058)
		(width 0.0889)
		(layer "In2.Cu")
		(net "P5E_CPU0_PE1_TX_DN<2>")
	)
	(arc
		(start 365.415322 -218.197684)
		(mid 365.593919 -217.878406)
		(end 365.415322 -217.559128)
		(width 0.0889)
		(layer "In2.Cu")
		(net "P5E_CPU0_PE1_TX_DN<2>")
	)
	(arc
		(start 365.12373 -223.575626)
		(mid 365.076051 -223.392726)
		(end 364.945168 -223.256348)
		(width 0.0889)
		(layer "In2.Cu")
		(net "P5E_CPU0_PE1_TX_DN<2>")
	)
	(arc
		(start 365.593884 -224.389442)
		(mid 365.546205 -224.206542)
		(end 365.415322 -224.070164)
		(width 0.0889)
		(layer "In2.Cu")
		(net "P5E_CPU0_PE1_TX_DN<2>")
	)
	(arc
		(start 364.945168 -222.267018)
		(mid 365.076082 -222.130658)
		(end 365.12373 -221.94774)
		(width 0.0889)
		(layer "In2.Cu")
		(net "P5E_CPU0_PE1_TX_DN<2>")
	)
	(arc
		(start 365.39424 -224.057972)
		(mid 365.196012 -223.852124)
		(end 365.12373 -223.575626)
		(width 0.0889)
		(layer "In2.Cu")
		(net "P5E_CPU0_PE1_TX_DN<2>")
	)
	(arc
		(start 365.12373 -221.94774)
		(mid 365.197721 -221.668174)
		(end 365.400336 -221.461838)
		(width 0.0889)
		(layer "In2.Cu")
		(net "P5E_CPU0_PE1_TX_DN<2>")
	)
	(arc
		(start 364.945168 -219.0115)
		(mid 365.076082 -218.87514)
		(end 365.12373 -218.692222)
		(width 0.0889)
		(layer "In2.Cu")
		(net "P5E_CPU0_PE1_TX_DN<2>")
	)
	(arc
		(start 364.936278 -219.995496)
		(mid 364.733455 -219.795265)
		(end 364.654084 -219.521532)
		(width 0.0889)
		(layer "In2.Cu")
		(net "P5E_CPU0_PE1_TX_DN<2>")
	)
	(arc
		(start 365.12373 -220.319854)
		(mid 365.076051 -220.136954)
		(end 364.945168 -220.000576)
		(width 0.0889)
		(layer "In2.Cu")
		(net "P5E_CPU0_PE1_TX_DN<2>")
	)
	(arc
		(start 364.654084 -216.235026)
		(mid 364.733454 -215.961292)
		(end 364.936278 -215.761062)
		(width 0.0889)
		(layer "In2.Cu")
		(net "P5E_CPU0_PE1_TX_DN<2>")
	)
	(segment
		(start 366.628934 -224.111566)
		(end 366.628934 -223.57588)
		(width 0.13208)
		(layer "F.Cu")
		(net "P5E_CPU0_PE1_TX_DN<1>")
	)
	(segment
		(start 430.360836 -17.601438)
		(end 430.05756 -17.298162)
		(width 0.13208)
		(layer "F.Cu")
		(net "P5E_CPU0_PE1_TX_DN<1>")
	)
	(segment
		(start 366.628934 -223.57588)
		(end 366.62868 -223.575626)
		(width 0.13208)
		(layer "F.Cu")
		(net "P5E_CPU0_PE1_TX_DN<1>")
	)
	(segment
		(start 430.05756 -17.298162)
		(end 430.05756 -16.68399)
		(width 0.13208)
		(layer "F.Cu")
		(net "P5E_CPU0_PE1_TX_DN<1>")
	)
	(segment
		(start 430.05756 -16.68399)
		(end 430.386236 -16.355314)
		(width 0.13208)
		(layer "F.Cu")
		(net "P5E_CPU0_PE1_TX_DN<1>")
	)
	(segment
		(start 365.78413 -216.188036)
		(end 365.78413 -216.258394)
		(width 0.0889)
		(layer "In2.Cu")
		(net "P5E_CPU0_PE1_TX_DN<1>")
	)
	(segment
		(start 429.363378 -19.97456)
		(end 429.173132 -20.290282)
		(width 0.14732)
		(layer "In2.Cu")
		(net "P5E_CPU0_PE1_TX_DN<1>")
	)
	(segment
		(start 365.962946 -219.825316)
		(end 365.971836 -219.830396)
		(width 0.0889)
		(layer "In2.Cu")
		(net "P5E_CPU0_PE1_TX_DN<1>")
	)
	(segment
		(start 366.439958 -221.624144)
		(end 366.432592 -221.628462)
		(width 0.0889)
		(layer "In2.Cu")
		(net "P5E_CPU0_PE1_TX_DN<1>")
	)
	(segment
		(start 424.604688 -27.595322)
		(end 420.587424 -54.362858)
		(width 0.14732)
		(layer "In2.Cu")
		(net "P5E_CPU0_PE1_TX_DN<1>")
	)
	(segment
		(start 365.962946 -223.080834)
		(end 365.971836 -223.085914)
		(width 0.0889)
		(layer "In2.Cu")
		(net "P5E_CPU0_PE1_TX_DN<1>")
	)
	(segment
		(start 366.724184 -217.864182)
		(end 366.724184 -217.878406)
		(width 0.0889)
		(layer "In2.Cu")
		(net "P5E_CPU0_PE1_TX_DN<1>")
	)
	(segment
		(start 366.254284 -223.557084)
		(end 366.254284 -223.584262)
		(width 0.0889)
		(layer "In2.Cu")
		(net "P5E_CPU0_PE1_TX_DN<1>")
	)
	(segment
		(start 366.442244 -221.622874)
		(end 366.441482 -221.623382)
		(width 0.0889)
		(layer "In2.Cu")
		(net "P5E_CPU0_PE1_TX_DN<1>")
	)
	(segment
		(start 366.447578 -221.619826)
		(end 366.442244 -221.622874)
		(width 0.0889)
		(layer "In2.Cu")
		(net "P5E_CPU0_PE1_TX_DN<1>")
	)
	(segment
		(start 366.25403 -213.327742)
		(end 366.25403 -215.399874)
		(width 0.0889)
		(layer "In2.Cu")
		(net "P5E_CPU0_PE1_TX_DN<1>")
	)
	(segment
		(start 430.066196 -17.896078)
		(end 430.066196 -18.526506)
		(width 0.14732)
		(layer "In2.Cu")
		(net "P5E_CPU0_PE1_TX_DN<1>")
	)
	(segment
		(start 368.107722 -162.02025)
		(end 366.296194 -212.684106)
		(width 0.14732)
		(layer "In2.Cu")
		(net "P5E_CPU0_PE1_TX_DN<1>")
	)
	(segment
		(start 365.971836 -222.437198)
		(end 365.962946 -222.442278)
		(width 0.0889)
		(layer "In2.Cu")
		(net "P5E_CPU0_PE1_TX_DN<1>")
	)
	(segment
		(start 430.360836 -17.601438)
		(end 430.066196 -17.896078)
		(width 0.14732)
		(layer "In2.Cu")
		(net "P5E_CPU0_PE1_TX_DN<1>")
	)
	(segment
		(start 366.441482 -221.623382)
		(end 366.439958 -221.624144)
		(width 0.0889)
		(layer "In2.Cu")
		(net "P5E_CPU0_PE1_TX_DN<1>")
	)
	(segment
		(start 365.971836 -219.18168)
		(end 365.962946 -219.18676)
		(width 0.0889)
		(layer "In2.Cu")
		(net "P5E_CPU0_PE1_TX_DN<1>")
	)
	(segment
		(start 365.962946 -216.569798)
		(end 365.971836 -216.574878)
		(width 0.0889)
		(layer "In2.Cu")
		(net "P5E_CPU0_PE1_TX_DN<1>")
	)
	(segment
		(start 366.134904 -215.687148)
		(end 365.890302 -215.93175)
		(width 0.0889)
		(layer "In2.Cu")
		(net "P5E_CPU0_PE1_TX_DN<1>")
	)
	(segment
		(start 429.313848 -19.775678)
		(end 429.363378 -19.97456)
		(width 0.14732)
		(layer "In2.Cu")
		(net "P5E_CPU0_PE1_TX_DN<1>")
	)
	(segment
		(start 428.61992 -20.928076)
		(end 428.66945 -21.126704)
		(width 0.14732)
		(layer "In2.Cu")
		(net "P5E_CPU0_PE1_TX_DN<1>")
	)
	(segment
		(start 415.792158 -81.553812)
		(end 368.107722 -162.02025)
		(width 0.14732)
		(layer "In2.Cu")
		(net "P5E_CPU0_PE1_TX_DN<1>")
	)
	(segment
		(start 366.296194 -212.684106)
		(end 366.296194 -213.26348)
		(width 0.14732)
		(layer "In2.Cu")
		(net "P5E_CPU0_PE1_TX_DN<1>")
	)
	(segment
		(start 428.97425 -20.339558)
		(end 428.61992 -20.928076)
		(width 0.14732)
		(layer "In2.Cu")
		(net "P5E_CPU0_PE1_TX_DN<1>")
	)
	(segment
		(start 366.296194 -213.26348)
		(end 366.296194 -213.285578)
		(width 0.0889)
		(layer "In2.Cu")
		(net "P5E_CPU0_PE1_TX_DN<1>")
	)
	(segment
		(start 366.254284 -217.05443)
		(end 366.254284 -217.072972)
		(width 0.0889)
		(layer "In2.Cu")
		(net "P5E_CPU0_PE1_TX_DN<1>")
	)
	(segment
		(start 430.066196 -18.526506)
		(end 429.313848 -19.775678)
		(width 0.14732)
		(layer "In2.Cu")
		(net "P5E_CPU0_PE1_TX_DN<1>")
	)
	(segment
		(start 366.254284 -220.309948)
		(end 366.254284 -220.32849)
		(width 0.0889)
		(layer "In2.Cu")
		(net "P5E_CPU0_PE1_TX_DN<1>")
	)
	(segment
		(start 429.173132 -20.290282)
		(end 428.97425 -20.339558)
		(width 0.14732)
		(layer "In2.Cu")
		(net "P5E_CPU0_PE1_TX_DN<1>")
	)
	(segment
		(start 428.280322 -21.491702)
		(end 424.604688 -27.595322)
		(width 0.14732)
		(layer "In2.Cu")
		(net "P5E_CPU0_PE1_TX_DN<1>")
	)
	(segment
		(start 366.296194 -213.285578)
		(end 366.25403 -213.327742)
		(width 0.0889)
		(layer "In2.Cu")
		(net "P5E_CPU0_PE1_TX_DN<1>")
	)
	(segment
		(start 420.587424 -54.362858)
		(end 415.792412 -81.553304)
		(width 0.14732)
		(layer "In2.Cu")
		(net "P5E_CPU0_PE1_TX_DN<1>")
	)
	(segment
		(start 415.792412 -81.553304)
		(end 415.792158 -81.553812)
		(width 0.14732)
		(layer "In2.Cu")
		(net "P5E_CPU0_PE1_TX_DN<1>")
	)
	(segment
		(start 366.472216 -223.846644)
		(end 366.62868 -223.575626)
		(width 0.0889)
		(layer "In2.Cu")
		(net "P5E_CPU0_PE1_TX_DN<1>")
	)
	(segment
		(start 366.724184 -221.1197)
		(end 366.724184 -221.133924)
		(width 0.0889)
		(layer "In2.Cu")
		(net "P5E_CPU0_PE1_TX_DN<1>")
	)
	(segment
		(start 366.441482 -218.367864)
		(end 366.432592 -218.372944)
		(width 0.0889)
		(layer "In2.Cu")
		(net "P5E_CPU0_PE1_TX_DN<1>")
	)
	(segment
		(start 366.394238 -223.867472)
		(end 366.472216 -223.846644)
		(width 0.0889)
		(layer "In2.Cu")
		(net "P5E_CPU0_PE1_TX_DN<1>")
	)
	(segment
		(start 428.479458 -21.442426)
		(end 428.280322 -21.491702)
		(width 0.14732)
		(layer "In2.Cu")
		(net "P5E_CPU0_PE1_TX_DN<1>")
	)
	(segment
		(start 366.447578 -218.364308)
		(end 366.441482 -218.367864)
		(width 0.0889)
		(layer "In2.Cu")
		(net "P5E_CPU0_PE1_TX_DN<1>")
	)
	(segment
		(start 428.66945 -21.126704)
		(end 428.479458 -21.442426)
		(width 0.14732)
		(layer "In2.Cu")
		(net "P5E_CPU0_PE1_TX_DN<1>")
	)
	(segment
		(start 366.25403 -218.692222)
		(end 366.25403 -218.707716)
		(width 0.0889)
		(layer "In2.Cu")
		(net "P5E_CPU0_PE1_TX_DN<1>")
	)
	(segment
		(start 366.25403 -221.94774)
		(end 366.25403 -221.963234)
		(width 0.0889)
		(layer "In2.Cu")
		(net "P5E_CPU0_PE1_TX_DN<1>")
	)
	(arc
		(start 365.784638 -222.773748)
		(mid 365.835131 -222.949726)
		(end 365.962946 -223.080834)
		(width 0.0889)
		(layer "In2.Cu")
		(net "P5E_CPU0_PE1_TX_DN<1>")
	)
	(arc
		(start 365.971836 -216.574878)
		(mid 366.176171 -216.777483)
		(end 366.254284 -217.05443)
		(width 0.0889)
		(layer "In2.Cu")
		(net "P5E_CPU0_PE1_TX_DN<1>")
	)
	(arc
		(start 366.25403 -221.963234)
		(mid 366.17466 -222.236968)
		(end 365.971836 -222.437198)
		(width 0.0889)
		(layer "In2.Cu")
		(net "P5E_CPU0_PE1_TX_DN<1>")
	)
	(arc
		(start 365.962946 -222.442278)
		(mid 365.834627 -222.57425)
		(end 365.784638 -222.751396)
		(width 0.0889)
		(layer "In2.Cu")
		(net "P5E_CPU0_PE1_TX_DN<1>")
	)
	(arc
		(start 365.784638 -222.751396)
		(mid 365.784471 -222.762572)
		(end 365.784638 -222.773748)
		(width 0.0889)
		(layer "In2.Cu")
		(net "P5E_CPU0_PE1_TX_DN<1>")
	)
	(arc
		(start 366.441482 -217.388694)
		(mid 366.644963 -217.589498)
		(end 366.724184 -217.864182)
		(width 0.0889)
		(layer "In2.Cu")
		(net "P5E_CPU0_PE1_TX_DN<1>")
	)
	(arc
		(start 366.724184 -221.133924)
		(mid 366.650193 -221.41349)
		(end 366.447578 -221.619826)
		(width 0.0889)
		(layer "In2.Cu")
		(net "P5E_CPU0_PE1_TX_DN<1>")
	)
	(arc
		(start 366.724184 -217.878406)
		(mid 366.650193 -218.157972)
		(end 366.447578 -218.364308)
		(width 0.0889)
		(layer "In2.Cu")
		(net "P5E_CPU0_PE1_TX_DN<1>")
	)
	(arc
		(start 366.254284 -217.072972)
		(mid 366.306554 -217.255337)
		(end 366.441482 -217.388694)
		(width 0.0889)
		(layer "In2.Cu")
		(net "P5E_CPU0_PE1_TX_DN<1>")
	)
	(arc
		(start 366.254284 -220.32849)
		(mid 366.306554 -220.510855)
		(end 366.441482 -220.644212)
		(width 0.0889)
		(layer "In2.Cu")
		(net "P5E_CPU0_PE1_TX_DN<1>")
	)
	(arc
		(start 365.962946 -219.18676)
		(mid 365.834542 -219.318705)
		(end 365.784384 -219.495878)
		(width 0.0889)
		(layer "In2.Cu")
		(net "P5E_CPU0_PE1_TX_DN<1>")
	)
	(arc
		(start 366.254284 -223.584262)
		(mid 366.292958 -223.74133)
		(end 366.394238 -223.867472)
		(width 0.0889)
		(layer "In2.Cu")
		(net "P5E_CPU0_PE1_TX_DN<1>")
	)
	(arc
		(start 366.25403 -218.707716)
		(mid 366.17466 -218.98145)
		(end 365.971836 -219.18168)
		(width 0.0889)
		(layer "In2.Cu")
		(net "P5E_CPU0_PE1_TX_DN<1>")
	)
	(arc
		(start 366.25403 -215.399874)
		(mid 366.223027 -215.555357)
		(end 366.134904 -215.687148)
		(width 0.0889)
		(layer "In2.Cu")
		(net "P5E_CPU0_PE1_TX_DN<1>")
	)
	(arc
		(start 365.890302 -215.93175)
		(mid 365.811734 -216.049335)
		(end 365.78413 -216.188036)
		(width 0.0889)
		(layer "In2.Cu")
		(net "P5E_CPU0_PE1_TX_DN<1>")
	)
	(arc
		(start 365.784384 -219.512642)
		(mid 365.833637 -219.691842)
		(end 365.962946 -219.825316)
		(width 0.0889)
		(layer "In2.Cu")
		(net "P5E_CPU0_PE1_TX_DN<1>")
	)
	(arc
		(start 365.78413 -216.258394)
		(mid 365.833801 -216.436927)
		(end 365.962946 -216.569798)
		(width 0.0889)
		(layer "In2.Cu")
		(net "P5E_CPU0_PE1_TX_DN<1>")
	)
	(arc
		(start 365.784384 -219.495878)
		(mid 365.78429 -219.50426)
		(end 365.784384 -219.512642)
		(width 0.0889)
		(layer "In2.Cu")
		(net "P5E_CPU0_PE1_TX_DN<1>")
	)
	(arc
		(start 366.432592 -221.628462)
		(mid 366.301678 -221.764822)
		(end 366.25403 -221.94774)
		(width 0.0889)
		(layer "In2.Cu")
		(net "P5E_CPU0_PE1_TX_DN<1>")
	)
	(arc
		(start 365.971836 -223.085914)
		(mid 366.174122 -223.284895)
		(end 366.254284 -223.557084)
		(width 0.0889)
		(layer "In2.Cu")
		(net "P5E_CPU0_PE1_TX_DN<1>")
	)
	(arc
		(start 366.432592 -218.372944)
		(mid 366.301678 -218.509304)
		(end 366.25403 -218.692222)
		(width 0.0889)
		(layer "In2.Cu")
		(net "P5E_CPU0_PE1_TX_DN<1>")
	)
	(arc
		(start 365.971836 -219.830396)
		(mid 366.176171 -220.033001)
		(end 366.254284 -220.309948)
		(width 0.0889)
		(layer "In2.Cu")
		(net "P5E_CPU0_PE1_TX_DN<1>")
	)
	(arc
		(start 366.441482 -220.644212)
		(mid 366.644963 -220.845016)
		(end 366.724184 -221.1197)
		(width 0.0889)
		(layer "In2.Cu")
		(net "P5E_CPU0_PE1_TX_DN<1>")
	)
	(segment
		(start 390.601708 -16.68399)
		(end 390.930384 -16.355314)
		(width 0.13208)
		(layer "F.Cu")
		(net "P5E_CPU0_PE1_TX_DN<15>")
	)
	(segment
		(start 390.601708 -17.298162)
		(end 390.601708 -16.68399)
		(width 0.13208)
		(layer "F.Cu")
		(net "P5E_CPU0_PE1_TX_DN<15>")
	)
	(segment
		(start 353.47148 -224.111312)
		(end 353.47148 -223.575626)
		(width 0.13208)
		(layer "F.Cu")
		(net "P5E_CPU0_PE1_TX_DN<15>")
	)
	(segment
		(start 390.904984 -17.601438)
		(end 390.601708 -17.298162)
		(width 0.13208)
		(layer "F.Cu")
		(net "P5E_CPU0_PE1_TX_DN<15>")
	)
	(segment
		(start 353.471734 -224.111566)
		(end 353.47148 -224.111312)
		(width 0.13208)
		(layer "F.Cu")
		(net "P5E_CPU0_PE1_TX_DN<15>")
	)
	(segment
		(start 390.755124 -20.385278)
		(end 390.755124 -20.753578)
		(width 0.14732)
		(layer "In2.Cu")
		(net "P5E_CPU0_PE1_TX_DN<15>")
	)
	(segment
		(start 338.975192 -172.545502)
		(end 339.688678 -176.595024)
		(width 0.14732)
		(layer "In2.Cu")
		(net "P5E_CPU0_PE1_TX_DN<15>")
	)
	(segment
		(start 352.627184 -216.25052)
		(end 352.627184 -216.257124)
		(width 0.0889)
		(layer "In2.Cu")
		(net "P5E_CPU0_PE1_TX_DN<15>")
	)
	(segment
		(start 351.2439 -207.140302)
		(end 352.199448 -212.367368)
		(width 0.14732)
		(layer "In2.Cu")
		(net "P5E_CPU0_PE1_TX_DN<15>")
	)
	(segment
		(start 390.755124 -19.359118)
		(end 390.755124 -19.727418)
		(width 0.14732)
		(layer "In2.Cu")
		(net "P5E_CPU0_PE1_TX_DN<15>")
	)
	(segment
		(start 352.626676 -214.424768)
		(end 352.626676 -214.644732)
		(width 0.0889)
		(layer "In2.Cu")
		(net "P5E_CPU0_PE1_TX_DN<15>")
	)
	(segment
		(start 390.755124 -19.727418)
		(end 390.610344 -19.872198)
		(width 0.14732)
		(layer "In2.Cu")
		(net "P5E_CPU0_PE1_TX_DN<15>")
	)
	(segment
		(start 401.19554 -79.699612)
		(end 340.268052 -166.71544)
		(width 0.14732)
		(layer "In2.Cu")
		(net "P5E_CPU0_PE1_TX_DN<15>")
	)
	(segment
		(start 390.610344 -20.898358)
		(end 390.610344 -21.503386)
		(width 0.14732)
		(layer "In2.Cu")
		(net "P5E_CPU0_PE1_TX_DN<15>")
	)
	(segment
		(start 353.097084 -220.309948)
		(end 353.097084 -220.32849)
		(width 0.0889)
		(layer "In2.Cu")
		(net "P5E_CPU0_PE1_TX_DN<15>")
	)
	(segment
		(start 352.805746 -218.197684)
		(end 352.826828 -218.209876)
		(width 0.0889)
		(layer "In2.Cu")
		(net "P5E_CPU0_PE1_TX_DN<15>")
	)
	(segment
		(start 390.610344 -17.896078)
		(end 390.610344 -19.214338)
		(width 0.14732)
		(layer "In2.Cu")
		(net "P5E_CPU0_PE1_TX_DN<15>")
	)
	(segment
		(start 352.344482 -215.761062)
		(end 352.350578 -215.764618)
		(width 0.0889)
		(layer "In2.Cu")
		(net "P5E_CPU0_PE1_TX_DN<15>")
	)
	(segment
		(start 353.314254 -223.846898)
		(end 353.47148 -223.575626)
		(width 0.0889)
		(layer "In2.Cu")
		(net "P5E_CPU0_PE1_TX_DN<15>")
	)
	(segment
		(start 353.097084 -221.94774)
		(end 353.097084 -221.957646)
		(width 0.0889)
		(layer "In2.Cu")
		(net "P5E_CPU0_PE1_TX_DN<15>")
	)
	(segment
		(start 390.610344 -19.872198)
		(end 390.610344 -20.240498)
		(width 0.14732)
		(layer "In2.Cu")
		(net "P5E_CPU0_PE1_TX_DN<15>")
	)
	(segment
		(start 352.817176 -219.180156)
		(end 352.816414 -219.180664)
		(width 0.0889)
		(layer "In2.Cu")
		(net "P5E_CPU0_PE1_TX_DN<15>")
	)
	(segment
		(start 353.097084 -223.557084)
		(end 353.097084 -223.584262)
		(width 0.0889)
		(layer "In2.Cu")
		(net "P5E_CPU0_PE1_TX_DN<15>")
	)
	(segment
		(start 353.284536 -221.623382)
		(end 353.275646 -221.628462)
		(width 0.0889)
		(layer "In2.Cu")
		(net "P5E_CPU0_PE1_TX_DN<15>")
	)
	(segment
		(start 352.199448 -213.224618)
		(end 352.199448 -213.246716)
		(width 0.0889)
		(layer "In2.Cu")
		(net "P5E_CPU0_PE1_TX_DN<15>")
	)
	(segment
		(start 390.610344 -20.240498)
		(end 390.755124 -20.385278)
		(width 0.14732)
		(layer "In2.Cu")
		(net "P5E_CPU0_PE1_TX_DN<15>")
	)
	(segment
		(start 390.755124 -20.753578)
		(end 390.610344 -20.898358)
		(width 0.14732)
		(layer "In2.Cu")
		(net "P5E_CPU0_PE1_TX_DN<15>")
	)
	(segment
		(start 352.814636 -222.437198)
		(end 352.805746 -222.442278)
		(width 0.0889)
		(layer "In2.Cu")
		(net "P5E_CPU0_PE1_TX_DN<15>")
	)
	(segment
		(start 351.2439 -207.14081)
		(end 351.2439 -207.140302)
		(width 0.14732)
		(layer "In2.Cu")
		(net "P5E_CPU0_PE1_TX_DN<15>")
	)
	(segment
		(start 352.15703 -213.289134)
		(end 352.15703 -213.8934)
		(width 0.0889)
		(layer "In2.Cu")
		(net "P5E_CPU0_PE1_TX_DN<15>")
	)
	(segment
		(start 340.268052 -166.71544)
		(end 338.975192 -172.545502)
		(width 0.14732)
		(layer "In2.Cu")
		(net "P5E_CPU0_PE1_TX_DN<15>")
	)
	(segment
		(start 352.805746 -216.569798)
		(end 352.814636 -216.574878)
		(width 0.0889)
		(layer "In2.Cu")
		(net "P5E_CPU0_PE1_TX_DN<15>")
	)
	(segment
		(start 352.199448 -213.246716)
		(end 352.15703 -213.289134)
		(width 0.0889)
		(layer "In2.Cu")
		(net "P5E_CPU0_PE1_TX_DN<15>")
	)
	(segment
		(start 352.33991 -215.758522)
		(end 352.344482 -215.761062)
		(width 0.0889)
		(layer "In2.Cu")
		(net "P5E_CPU0_PE1_TX_DN<15>")
	)
	(segment
		(start 352.820478 -219.178378)
		(end 352.819716 -219.178886)
		(width 0.0889)
		(layer "In2.Cu")
		(net "P5E_CPU0_PE1_TX_DN<15>")
	)
	(segment
		(start 352.816414 -219.180664)
		(end 352.805746 -219.18676)
		(width 0.0889)
		(layer "In2.Cu")
		(net "P5E_CPU0_PE1_TX_DN<15>")
	)
	(segment
		(start 352.805746 -223.080834)
		(end 352.814636 -223.085914)
		(width 0.0889)
		(layer "In2.Cu")
		(net "P5E_CPU0_PE1_TX_DN<15>")
	)
	(segment
		(start 352.335592 -215.755982)
		(end 352.33991 -215.758522)
		(width 0.0889)
		(layer "In2.Cu")
		(net "P5E_CPU0_PE1_TX_DN<15>")
	)
	(segment
		(start 352.159062 -215.379808)
		(end 352.157284 -215.421972)
		(width 0.0889)
		(layer "In2.Cu")
		(net "P5E_CPU0_PE1_TX_DN<15>")
	)
	(segment
		(start 352.344482 -215.112346)
		(end 352.299524 -215.139524)
		(width 0.0889)
		(layer "In2.Cu")
		(net "P5E_CPU0_PE1_TX_DN<15>")
	)
	(segment
		(start 390.610344 -19.214338)
		(end 390.755124 -19.359118)
		(width 0.14732)
		(layer "In2.Cu")
		(net "P5E_CPU0_PE1_TX_DN<15>")
	)
	(segment
		(start 352.814636 -217.554048)
		(end 352.805746 -217.559128)
		(width 0.0889)
		(layer "In2.Cu")
		(net "P5E_CPU0_PE1_TX_DN<15>")
	)
	(segment
		(start 401.828254 -76.657962)
		(end 401.19554 -79.699612)
		(width 0.14732)
		(layer "In2.Cu")
		(net "P5E_CPU0_PE1_TX_DN<15>")
	)
	(segment
		(start 352.15703 -213.8934)
		(end 352.157284 -213.893908)
		(width 0.0889)
		(layer "In2.Cu")
		(net "P5E_CPU0_PE1_TX_DN<15>")
	)
	(segment
		(start 352.819716 -219.178886)
		(end 352.817176 -219.180156)
		(width 0.0889)
		(layer "In2.Cu")
		(net "P5E_CPU0_PE1_TX_DN<15>")
	)
	(segment
		(start 352.805746 -219.825316)
		(end 352.814636 -219.830396)
		(width 0.0889)
		(layer "In2.Cu")
		(net "P5E_CPU0_PE1_TX_DN<15>")
	)
	(segment
		(start 352.826828 -219.174568)
		(end 352.820478 -219.178378)
		(width 0.0889)
		(layer "In2.Cu")
		(net "P5E_CPU0_PE1_TX_DN<15>")
	)
	(segment
		(start 390.904984 -17.601438)
		(end 390.610344 -17.896078)
		(width 0.14732)
		(layer "In2.Cu")
		(net "P5E_CPU0_PE1_TX_DN<15>")
	)
	(segment
		(start 390.610344 -21.503386)
		(end 401.828254 -76.657962)
		(width 0.14732)
		(layer "In2.Cu")
		(net "P5E_CPU0_PE1_TX_DN<15>")
	)
	(segment
		(start 352.199448 -212.367368)
		(end 352.199448 -213.224618)
		(width 0.14732)
		(layer "In2.Cu")
		(net "P5E_CPU0_PE1_TX_DN<15>")
	)
	(segment
		(start 339.688678 -176.595024)
		(end 351.2439 -207.14081)
		(width 0.14732)
		(layer "In2.Cu")
		(net "P5E_CPU0_PE1_TX_DN<15>")
	)
	(segment
		(start 353.237038 -223.867472)
		(end 353.314254 -223.846898)
		(width 0.0889)
		(layer "In2.Cu")
		(net "P5E_CPU0_PE1_TX_DN<15>")
	)
	(arc
		(start 353.097084 -220.32849)
		(mid 353.149354 -220.510855)
		(end 353.284282 -220.644212)
		(width 0.0889)
		(layer "In2.Cu")
		(net "P5E_CPU0_PE1_TX_DN<15>")
	)
	(arc
		(start 352.15703 -215.436704)
		(mid 352.204709 -215.619604)
		(end 352.335592 -215.755982)
		(width 0.0889)
		(layer "In2.Cu")
		(net "P5E_CPU0_PE1_TX_DN<15>")
	)
	(arc
		(start 352.626676 -214.644732)
		(mid 352.545765 -214.91486)
		(end 352.344482 -215.112346)
		(width 0.0889)
		(layer "In2.Cu")
		(net "P5E_CPU0_PE1_TX_DN<15>")
	)
	(arc
		(start 352.826828 -218.209876)
		(mid 353.097284 -218.692222)
		(end 352.826828 -219.174568)
		(width 0.0889)
		(layer "In2.Cu")
		(net "P5E_CPU0_PE1_TX_DN<15>")
	)
	(arc
		(start 352.627438 -217.866214)
		(mid 352.627193 -217.87561)
		(end 352.627184 -217.88501)
		(width 0.0889)
		(layer "In2.Cu")
		(net "P5E_CPU0_PE1_TX_DN<15>")
	)
	(arc
		(start 352.805746 -217.559128)
		(mid 352.677853 -217.69019)
		(end 352.627438 -217.866214)
		(width 0.0889)
		(layer "In2.Cu")
		(net "P5E_CPU0_PE1_TX_DN<15>")
	)
	(arc
		(start 352.814636 -216.574878)
		(mid 353.018971 -216.777483)
		(end 353.097084 -217.05443)
		(width 0.0889)
		(layer "In2.Cu")
		(net "P5E_CPU0_PE1_TX_DN<15>")
	)
	(arc
		(start 352.627184 -222.754952)
		(mid 352.627194 -222.764352)
		(end 352.627438 -222.773748)
		(width 0.0889)
		(layer "In2.Cu")
		(net "P5E_CPU0_PE1_TX_DN<15>")
	)
	(arc
		(start 352.805746 -219.18676)
		(mid 352.627149 -219.506038)
		(end 352.805746 -219.825316)
		(width 0.0889)
		(layer "In2.Cu")
		(net "P5E_CPU0_PE1_TX_DN<15>")
	)
	(arc
		(start 353.097084 -221.957646)
		(mid 353.018973 -222.234595)
		(end 352.814636 -222.437198)
		(width 0.0889)
		(layer "In2.Cu")
		(net "P5E_CPU0_PE1_TX_DN<15>")
	)
	(arc
		(start 353.275646 -221.628462)
		(mid 353.144732 -221.764822)
		(end 353.097084 -221.94774)
		(width 0.0889)
		(layer "In2.Cu")
		(net "P5E_CPU0_PE1_TX_DN<15>")
	)
	(arc
		(start 353.09683 -217.082624)
		(mid 353.016874 -217.354946)
		(end 352.814636 -217.554048)
		(width 0.0889)
		(layer "In2.Cu")
		(net "P5E_CPU0_PE1_TX_DN<15>")
	)
	(arc
		(start 353.097084 -217.05443)
		(mid 353.09713 -217.068529)
		(end 353.09683 -217.082624)
		(width 0.0889)
		(layer "In2.Cu")
		(net "P5E_CPU0_PE1_TX_DN<15>")
	)
	(arc
		(start 353.097084 -223.584262)
		(mid 353.135758 -223.74133)
		(end 353.237038 -223.867472)
		(width 0.0889)
		(layer "In2.Cu")
		(net "P5E_CPU0_PE1_TX_DN<15>")
	)
	(arc
		(start 352.814636 -223.085914)
		(mid 353.016922 -223.284895)
		(end 353.097084 -223.557084)
		(width 0.0889)
		(layer "In2.Cu")
		(net "P5E_CPU0_PE1_TX_DN<15>")
	)
	(arc
		(start 352.627438 -222.773748)
		(mid 352.677931 -222.949726)
		(end 352.805746 -223.080834)
		(width 0.0889)
		(layer "In2.Cu")
		(net "P5E_CPU0_PE1_TX_DN<15>")
	)
	(arc
		(start 352.814636 -219.830396)
		(mid 353.018971 -220.033001)
		(end 353.097084 -220.309948)
		(width 0.0889)
		(layer "In2.Cu")
		(net "P5E_CPU0_PE1_TX_DN<15>")
	)
	(arc
		(start 353.284282 -220.644212)
		(mid 353.487763 -220.845016)
		(end 353.566984 -221.1197)
		(width 0.0889)
		(layer "In2.Cu")
		(net "P5E_CPU0_PE1_TX_DN<15>")
	)
	(arc
		(start 353.566984 -221.14383)
		(mid 353.488873 -221.420779)
		(end 353.284536 -221.623382)
		(width 0.0889)
		(layer "In2.Cu")
		(net "P5E_CPU0_PE1_TX_DN<15>")
	)
	(arc
		(start 353.566984 -221.1197)
		(mid 353.567115 -221.131765)
		(end 353.566984 -221.14383)
		(width 0.0889)
		(layer "In2.Cu")
		(net "P5E_CPU0_PE1_TX_DN<15>")
	)
	(arc
		(start 352.627184 -216.257124)
		(mid 352.676437 -216.436324)
		(end 352.805746 -216.569798)
		(width 0.0889)
		(layer "In2.Cu")
		(net "P5E_CPU0_PE1_TX_DN<15>")
	)
	(arc
		(start 352.341434 -214.093298)
		(mid 352.515397 -214.232062)
		(end 352.626676 -214.424768)
		(width 0.0889)
		(layer "In2.Cu")
		(net "P5E_CPU0_PE1_TX_DN<15>")
	)
	(arc
		(start 352.299524 -215.139524)
		(mid 352.199266 -215.242107)
		(end 352.159062 -215.379808)
		(width 0.0889)
		(layer "In2.Cu")
		(net "P5E_CPU0_PE1_TX_DN<15>")
	)
	(arc
		(start 352.157284 -213.893908)
		(mid 352.232289 -214.009367)
		(end 352.341434 -214.093298)
		(width 0.0889)
		(layer "In2.Cu")
		(net "P5E_CPU0_PE1_TX_DN<15>")
	)
	(arc
		(start 352.805746 -222.442278)
		(mid 352.676457 -222.575764)
		(end 352.627184 -222.754952)
		(width 0.0889)
		(layer "In2.Cu")
		(net "P5E_CPU0_PE1_TX_DN<15>")
	)
	(arc
		(start 352.157284 -215.421972)
		(mid 352.157087 -215.429337)
		(end 352.15703 -215.436704)
		(width 0.0889)
		(layer "In2.Cu")
		(net "P5E_CPU0_PE1_TX_DN<15>")
	)
	(arc
		(start 352.627184 -217.88501)
		(mid 352.676437 -218.06421)
		(end 352.805746 -218.197684)
		(width 0.0889)
		(layer "In2.Cu")
		(net "P5E_CPU0_PE1_TX_DN<15>")
	)
	(arc
		(start 352.350578 -215.764618)
		(mid 352.553165 -215.970969)
		(end 352.627184 -216.25052)
		(width 0.0889)
		(layer "In2.Cu")
		(net "P5E_CPU0_PE1_TX_DN<15>")
	)
	(segment
		(start 393.136628 -18.824194)
		(end 393.136628 -18.205958)
		(width 0.13208)
		(layer "F.Cu")
		(net "P5E_CPU0_PE1_TX_DN<14>")
	)
	(segment
		(start 393.136628 -18.205958)
		(end 392.809984 -17.879314)
		(width 0.13208)
		(layer "F.Cu")
		(net "P5E_CPU0_PE1_TX_DN<14>")
	)
	(segment
		(start 353.94138 -224.925382)
		(end 353.941634 -224.925128)
		(width 0.13208)
		(layer "F.Cu")
		(net "P5E_CPU0_PE1_TX_DN<14>")
	)
	(segment
		(start 392.835384 -19.125438)
		(end 393.136628 -18.824194)
		(width 0.13208)
		(layer "F.Cu")
		(net "P5E_CPU0_PE1_TX_DN<14>")
	)
	(segment
		(start 353.941634 -224.925128)
		(end 353.941634 -224.389442)
		(width 0.13208)
		(layer "F.Cu")
		(net "P5E_CPU0_PE1_TX_DN<14>")
	)
	(segment
		(start 354.17633 -224.681288)
		(end 354.098098 -224.66046)
		(width 0.0889)
		(layer "In2.Cu")
		(net "P5E_CPU0_PE1_TX_DN<14>")
	)
	(segment
		(start 392.835384 -19.125438)
		(end 393.130024 -19.420078)
		(width 0.14732)
		(layer "In2.Cu")
		(net "P5E_CPU0_PE1_TX_DN<14>")
	)
	(segment
		(start 354.128832 -220.809566)
		(end 354.129594 -220.810074)
		(width 0.0889)
		(layer "In2.Cu")
		(net "P5E_CPU0_PE1_TX_DN<14>")
	)
	(segment
		(start 393.6492 -22.46376)
		(end 393.538456 -22.635972)
		(width 0.14732)
		(layer "In2.Cu")
		(net "P5E_CPU0_PE1_TX_DN<14>")
	)
	(segment
		(start 353.658678 -218.367864)
		(end 353.659694 -218.368372)
		(width 0.0889)
		(layer "In2.Cu")
		(net "P5E_CPU0_PE1_TX_DN<14>")
	)
	(segment
		(start 393.616942 -22.996144)
		(end 393.789662 -23.106888)
		(width 0.14732)
		(layer "In2.Cu")
		(net "P5E_CPU0_PE1_TX_DN<14>")
	)
	(segment
		(start 353.659694 -218.368372)
		(end 353.667568 -218.372944)
		(width 0.0889)
		(layer "In2.Cu")
		(net "P5E_CPU0_PE1_TX_DN<14>")
	)
	(segment
		(start 354.128832 -224.065084)
		(end 354.137722 -224.070164)
		(width 0.0889)
		(layer "In2.Cu")
		(net "P5E_CPU0_PE1_TX_DN<14>")
	)
	(segment
		(start 354.098098 -224.66046)
		(end 353.941634 -224.389442)
		(width 0.0889)
		(layer "In2.Cu")
		(net "P5E_CPU0_PE1_TX_DN<14>")
	)
	(segment
		(start 393.130024 -19.420078)
		(end 393.130024 -20.033488)
		(width 0.14732)
		(layer "In2.Cu")
		(net "P5E_CPU0_PE1_TX_DN<14>")
	)
	(segment
		(start 351.9932 -207.238854)
		(end 352.864928 -212.009482)
		(width 0.14732)
		(layer "In2.Cu")
		(net "P5E_CPU0_PE1_TX_DN<14>")
	)
	(segment
		(start 393.789662 -23.106888)
		(end 398.701768 -45.63872)
		(width 0.14732)
		(layer "In2.Cu")
		(net "P5E_CPU0_PE1_TX_DN<14>")
	)
	(segment
		(start 353.19081 -215.927178)
		(end 353.197922 -215.931242)
		(width 0.0889)
		(layer "In2.Cu")
		(net "P5E_CPU0_PE1_TX_DN<14>")
	)
	(segment
		(start 393.396978 -21.987002)
		(end 393.569444 -22.097746)
		(width 0.14732)
		(layer "In2.Cu")
		(net "P5E_CPU0_PE1_TX_DN<14>")
	)
	(segment
		(start 393.569444 -22.097746)
		(end 393.6492 -22.46376)
		(width 0.14732)
		(layer "In2.Cu")
		(net "P5E_CPU0_PE1_TX_DN<14>")
	)
	(segment
		(start 353.659694 -219.996004)
		(end 353.667568 -220.000576)
		(width 0.0889)
		(layer "In2.Cu")
		(net "P5E_CPU0_PE1_TX_DN<14>")
	)
	(segment
		(start 352.90633 -215.414606)
		(end 352.90633 -215.436704)
		(width 0.0889)
		(layer "In2.Cu")
		(net "P5E_CPU0_PE1_TX_DN<14>")
	)
	(segment
		(start 340.325202 -176.37125)
		(end 351.9932 -207.238854)
		(width 0.14732)
		(layer "In2.Cu")
		(net "P5E_CPU0_PE1_TX_DN<14>")
	)
	(segment
		(start 354.128832 -221.458282)
		(end 354.12807 -221.45879)
		(width 0.0889)
		(layer "In2.Cu")
		(net "P5E_CPU0_PE1_TX_DN<14>")
	)
	(segment
		(start 340.892892 -166.98341)
		(end 339.65515 -172.5676)
		(width 0.14732)
		(layer "In2.Cu")
		(net "P5E_CPU0_PE1_TX_DN<14>")
	)
	(segment
		(start 402.557996 -76.541376)
		(end 401.936204 -79.80299)
		(width 0.14732)
		(layer "In2.Cu")
		(net "P5E_CPU0_PE1_TX_DN<14>")
	)
	(segment
		(start 393.139676 -20.126452)
		(end 393.429236 -21.454618)
		(width 0.14732)
		(layer "In2.Cu")
		(net "P5E_CPU0_PE1_TX_DN<14>")
	)
	(segment
		(start 353.37623 -214.579708)
		(end 353.37623 -214.62365)
		(width 0.0889)
		(layer "In2.Cu")
		(net "P5E_CPU0_PE1_TX_DN<14>")
	)
	(segment
		(start 393.130024 -20.033488)
		(end 393.139676 -20.126452)
		(width 0.14732)
		(layer "In2.Cu")
		(net "P5E_CPU0_PE1_TX_DN<14>")
	)
	(segment
		(start 393.318492 -21.627084)
		(end 393.396978 -21.987002)
		(width 0.14732)
		(layer "In2.Cu")
		(net "P5E_CPU0_PE1_TX_DN<14>")
	)
	(segment
		(start 353.351084 -214.436452)
		(end 353.370896 -214.529162)
		(width 0.0889)
		(layer "In2.Cu")
		(net "P5E_CPU0_PE1_TX_DN<14>")
	)
	(segment
		(start 353.658678 -216.739978)
		(end 353.659694 -216.740486)
		(width 0.0889)
		(layer "In2.Cu")
		(net "P5E_CPU0_PE1_TX_DN<14>")
	)
	(segment
		(start 353.187508 -215.925146)
		(end 353.189794 -215.92667)
		(width 0.0889)
		(layer "In2.Cu")
		(net "P5E_CPU0_PE1_TX_DN<14>")
	)
	(segment
		(start 352.864928 -213.220554)
		(end 352.864928 -213.242652)
		(width 0.0889)
		(layer "In2.Cu")
		(net "P5E_CPU0_PE1_TX_DN<14>")
	)
	(segment
		(start 352.864928 -212.009482)
		(end 352.864928 -213.220554)
		(width 0.14732)
		(layer "In2.Cu")
		(net "P5E_CPU0_PE1_TX_DN<14>")
	)
	(segment
		(start 353.658678 -223.251268)
		(end 353.659694 -223.251776)
		(width 0.0889)
		(layer "In2.Cu")
		(net "P5E_CPU0_PE1_TX_DN<14>")
	)
	(segment
		(start 353.658678 -219.995496)
		(end 353.659694 -219.996004)
		(width 0.0889)
		(layer "In2.Cu")
		(net "P5E_CPU0_PE1_TX_DN<14>")
	)
	(segment
		(start 353.376484 -216.25052)
		(end 353.376484 -216.266014)
		(width 0.0889)
		(layer "In2.Cu")
		(net "P5E_CPU0_PE1_TX_DN<14>")
	)
	(segment
		(start 353.84613 -220.319854)
		(end 353.84613 -220.327474)
		(width 0.0889)
		(layer "In2.Cu")
		(net "P5E_CPU0_PE1_TX_DN<14>")
	)
	(segment
		(start 353.197414 -214.941912)
		(end 353.188524 -214.946992)
		(width 0.0889)
		(layer "In2.Cu")
		(net "P5E_CPU0_PE1_TX_DN<14>")
	)
	(segment
		(start 353.19208 -214.2617)
		(end 353.192588 -214.2617)
		(width 0.0889)
		(layer "In2.Cu")
		(net "P5E_CPU0_PE1_TX_DN<14>")
	)
	(segment
		(start 354.12807 -221.45879)
		(end 354.127054 -221.459298)
		(width 0.0889)
		(layer "In2.Cu")
		(net "P5E_CPU0_PE1_TX_DN<14>")
	)
	(segment
		(start 353.182936 -215.922606)
		(end 353.186238 -215.924384)
		(width 0.0889)
		(layer "In2.Cu")
		(net "P5E_CPU0_PE1_TX_DN<14>")
	)
	(segment
		(start 353.376484 -222.746062)
		(end 353.376484 -222.783654)
		(width 0.0889)
		(layer "In2.Cu")
		(net "P5E_CPU0_PE1_TX_DN<14>")
	)
	(segment
		(start 352.864928 -213.242652)
		(end 352.906838 -213.284562)
		(width 0.0889)
		(layer "In2.Cu")
		(net "P5E_CPU0_PE1_TX_DN<14>")
	)
	(segment
		(start 352.906838 -213.284562)
		(end 352.906838 -213.787228)
		(width 0.0889)
		(layer "In2.Cu")
		(net "P5E_CPU0_PE1_TX_DN<14>")
	)
	(segment
		(start 353.667568 -217.383614)
		(end 353.658678 -217.388694)
		(width 0.0889)
		(layer "In2.Cu")
		(net "P5E_CPU0_PE1_TX_DN<14>")
	)
	(segment
		(start 354.137722 -221.453202)
		(end 354.13569 -221.454472)
		(width 0.0889)
		(layer "In2.Cu")
		(net "P5E_CPU0_PE1_TX_DN<14>")
	)
	(segment
		(start 393.538456 -22.635972)
		(end 393.616942 -22.996144)
		(width 0.14732)
		(layer "In2.Cu")
		(net "P5E_CPU0_PE1_TX_DN<14>")
	)
	(segment
		(start 339.65515 -172.5676)
		(end 340.325202 -176.37125)
		(width 0.14732)
		(layer "In2.Cu")
		(net "P5E_CPU0_PE1_TX_DN<14>")
	)
	(segment
		(start 401.936204 -79.80299)
		(end 340.892892 -166.98341)
		(width 0.14732)
		(layer "In2.Cu")
		(net "P5E_CPU0_PE1_TX_DN<14>")
	)
	(segment
		(start 354.11664 -224.057972)
		(end 354.128832 -224.065084)
		(width 0.0889)
		(layer "In2.Cu")
		(net "P5E_CPU0_PE1_TX_DN<14>")
	)
	(segment
		(start 353.186238 -215.924384)
		(end 353.187508 -215.925146)
		(width 0.0889)
		(layer "In2.Cu")
		(net "P5E_CPU0_PE1_TX_DN<14>")
	)
	(segment
		(start 354.129594 -220.810074)
		(end 354.137722 -220.814646)
		(width 0.0889)
		(layer "In2.Cu")
		(net "P5E_CPU0_PE1_TX_DN<14>")
	)
	(segment
		(start 354.134166 -221.455234)
		(end 354.131626 -221.456758)
		(width 0.0889)
		(layer "In2.Cu")
		(net "P5E_CPU0_PE1_TX_DN<14>")
	)
	(segment
		(start 354.13569 -221.454472)
		(end 354.134166 -221.455234)
		(width 0.0889)
		(layer "In2.Cu")
		(net "P5E_CPU0_PE1_TX_DN<14>")
	)
	(segment
		(start 398.701768 -45.63872)
		(end 402.557996 -76.541376)
		(width 0.14732)
		(layer "In2.Cu")
		(net "P5E_CPU0_PE1_TX_DN<14>")
	)
	(segment
		(start 354.127054 -221.459298)
		(end 354.122736 -221.461838)
		(width 0.0889)
		(layer "In2.Cu")
		(net "P5E_CPU0_PE1_TX_DN<14>")
	)
	(segment
		(start 353.659694 -216.740486)
		(end 353.667568 -216.745058)
		(width 0.0889)
		(layer "In2.Cu")
		(net "P5E_CPU0_PE1_TX_DN<14>")
	)
	(segment
		(start 353.667568 -222.267018)
		(end 353.658678 -222.272098)
		(width 0.0889)
		(layer "In2.Cu")
		(net "P5E_CPU0_PE1_TX_DN<14>")
	)
	(segment
		(start 353.659694 -223.251776)
		(end 353.667568 -223.256348)
		(width 0.0889)
		(layer "In2.Cu")
		(net "P5E_CPU0_PE1_TX_DN<14>")
	)
	(segment
		(start 353.376484 -219.490544)
		(end 353.376484 -219.521532)
		(width 0.0889)
		(layer "In2.Cu")
		(net "P5E_CPU0_PE1_TX_DN<14>")
	)
	(segment
		(start 393.429236 -21.454618)
		(end 393.318492 -21.627084)
		(width 0.14732)
		(layer "In2.Cu")
		(net "P5E_CPU0_PE1_TX_DN<14>")
	)
	(segment
		(start 353.667568 -219.0115)
		(end 353.658678 -219.01658)
		(width 0.0889)
		(layer "In2.Cu")
		(net "P5E_CPU0_PE1_TX_DN<14>")
	)
	(segment
		(start 353.376484 -217.856308)
		(end 353.376484 -217.8939)
		(width 0.0889)
		(layer "In2.Cu")
		(net "P5E_CPU0_PE1_TX_DN<14>")
	)
	(segment
		(start 354.131626 -221.456758)
		(end 354.128832 -221.458282)
		(width 0.0889)
		(layer "In2.Cu")
		(net "P5E_CPU0_PE1_TX_DN<14>")
	)
	(segment
		(start 353.189794 -215.92667)
		(end 353.19081 -215.927178)
		(width 0.0889)
		(layer "In2.Cu")
		(net "P5E_CPU0_PE1_TX_DN<14>")
	)
	(arc
		(start 354.175568 -221.426532)
		(mid 354.15706 -221.440456)
		(end 354.137722 -221.453202)
		(width 0.0889)
		(layer "In2.Cu")
		(net "P5E_CPU0_PE1_TX_DN<14>")
	)
	(arc
		(start 353.188524 -214.946992)
		(mid 352.987242 -215.144479)
		(end 352.90633 -215.414606)
		(width 0.0889)
		(layer "In2.Cu")
		(net "P5E_CPU0_PE1_TX_DN<14>")
	)
	(arc
		(start 354.175568 -224.096834)
		(mid 354.27926 -224.227105)
		(end 354.316284 -224.389442)
		(width 0.0889)
		(layer "In2.Cu")
		(net "P5E_CPU0_PE1_TX_DN<14>")
	)
	(arc
		(start 354.137722 -220.814646)
		(mid 354.157054 -220.8274)
		(end 354.175568 -220.841316)
		(width 0.0889)
		(layer "In2.Cu")
		(net "P5E_CPU0_PE1_TX_DN<14>")
	)
	(arc
		(start 353.370896 -214.529162)
		(mid 353.374903 -214.554294)
		(end 353.37623 -214.579708)
		(width 0.0889)
		(layer "In2.Cu")
		(net "P5E_CPU0_PE1_TX_DN<14>")
	)
	(arc
		(start 353.667568 -216.745058)
		(mid 353.846165 -217.064336)
		(end 353.667568 -217.383614)
		(width 0.0889)
		(layer "In2.Cu")
		(net "P5E_CPU0_PE1_TX_DN<14>")
	)
	(arc
		(start 353.667568 -220.000576)
		(mid 353.798482 -220.136936)
		(end 353.84613 -220.319854)
		(width 0.0889)
		(layer "In2.Cu")
		(net "P5E_CPU0_PE1_TX_DN<14>")
	)
	(arc
		(start 353.84613 -220.327474)
		(mid 353.923759 -220.605887)
		(end 354.128832 -220.809566)
		(width 0.0889)
		(layer "In2.Cu")
		(net "P5E_CPU0_PE1_TX_DN<14>")
	)
	(arc
		(start 354.122736 -221.461838)
		(mid 353.920149 -221.668189)
		(end 353.84613 -221.94774)
		(width 0.0889)
		(layer "In2.Cu")
		(net "P5E_CPU0_PE1_TX_DN<14>")
	)
	(arc
		(start 353.84613 -223.575626)
		(mid 353.918365 -223.85215)
		(end 354.11664 -224.057972)
		(width 0.0889)
		(layer "In2.Cu")
		(net "P5E_CPU0_PE1_TX_DN<14>")
	)
	(arc
		(start 353.84613 -221.94774)
		(mid 353.798451 -222.13064)
		(end 353.667568 -222.267018)
		(width 0.0889)
		(layer "In2.Cu")
		(net "P5E_CPU0_PE1_TX_DN<14>")
	)
	(arc
		(start 353.197922 -215.931242)
		(mid 353.328836 -216.067602)
		(end 353.376484 -216.25052)
		(width 0.0889)
		(layer "In2.Cu")
		(net "P5E_CPU0_PE1_TX_DN<14>")
	)
	(arc
		(start 353.192588 -214.2617)
		(mid 353.256462 -214.303501)
		(end 353.31146 -214.356442)
		(width 0.0889)
		(layer "In2.Cu")
		(net "P5E_CPU0_PE1_TX_DN<14>")
	)
	(arc
		(start 353.376484 -217.8939)
		(mid 353.455854 -218.167634)
		(end 353.658678 -218.367864)
		(width 0.0889)
		(layer "In2.Cu")
		(net "P5E_CPU0_PE1_TX_DN<14>")
	)
	(arc
		(start 353.667568 -218.372944)
		(mid 353.846044 -218.692222)
		(end 353.667568 -219.0115)
		(width 0.0889)
		(layer "In2.Cu")
		(net "P5E_CPU0_PE1_TX_DN<14>")
	)
	(arc
		(start 353.667568 -223.256348)
		(mid 353.798482 -223.392708)
		(end 353.84613 -223.575626)
		(width 0.0889)
		(layer "In2.Cu")
		(net "P5E_CPU0_PE1_TX_DN<14>")
	)
	(arc
		(start 353.376484 -222.783654)
		(mid 353.457395 -223.053782)
		(end 353.658678 -223.251268)
		(width 0.0889)
		(layer "In2.Cu")
		(net "P5E_CPU0_PE1_TX_DN<14>")
	)
	(arc
		(start 353.376484 -219.521532)
		(mid 353.455854 -219.795266)
		(end 353.658678 -219.995496)
		(width 0.0889)
		(layer "In2.Cu")
		(net "P5E_CPU0_PE1_TX_DN<14>")
	)
	(arc
		(start 353.31146 -214.356442)
		(mid 353.336261 -214.393972)
		(end 353.351084 -214.436452)
		(width 0.0889)
		(layer "In2.Cu")
		(net "P5E_CPU0_PE1_TX_DN<14>")
	)
	(arc
		(start 352.906838 -213.787228)
		(mid 352.983438 -214.064174)
		(end 353.19208 -214.2617)
		(width 0.0889)
		(layer "In2.Cu")
		(net "P5E_CPU0_PE1_TX_DN<14>")
	)
	(arc
		(start 354.316284 -224.389442)
		(mid 354.279424 -224.551239)
		(end 354.17633 -224.681288)
		(width 0.0889)
		(layer "In2.Cu")
		(net "P5E_CPU0_PE1_TX_DN<14>")
	)
	(arc
		(start 352.90633 -215.436704)
		(mid 352.980321 -215.71627)
		(end 353.182936 -215.922606)
		(width 0.0889)
		(layer "In2.Cu")
		(net "P5E_CPU0_PE1_TX_DN<14>")
	)
	(arc
		(start 354.137722 -224.070164)
		(mid 354.157054 -224.082918)
		(end 354.175568 -224.096834)
		(width 0.0889)
		(layer "In2.Cu")
		(net "P5E_CPU0_PE1_TX_DN<14>")
	)
	(arc
		(start 354.175568 -220.841316)
		(mid 354.31626 -221.133924)
		(end 354.175568 -221.426532)
		(width 0.0889)
		(layer "In2.Cu")
		(net "P5E_CPU0_PE1_TX_DN<14>")
	)
	(arc
		(start 353.375722 -214.637366)
		(mid 353.324668 -214.811946)
		(end 353.197414 -214.941912)
		(width 0.0889)
		(layer "In2.Cu")
		(net "P5E_CPU0_PE1_TX_DN<14>")
	)
	(arc
		(start 353.658678 -222.272098)
		(mid 353.455855 -222.472329)
		(end 353.376484 -222.746062)
		(width 0.0889)
		(layer "In2.Cu")
		(net "P5E_CPU0_PE1_TX_DN<14>")
	)
	(arc
		(start 353.658678 -217.388694)
		(mid 353.457396 -217.586181)
		(end 353.376484 -217.856308)
		(width 0.0889)
		(layer "In2.Cu")
		(net "P5E_CPU0_PE1_TX_DN<14>")
	)
	(arc
		(start 353.376484 -216.266014)
		(mid 353.455854 -216.539748)
		(end 353.658678 -216.739978)
		(width 0.0889)
		(layer "In2.Cu")
		(net "P5E_CPU0_PE1_TX_DN<14>")
	)
	(arc
		(start 353.658678 -219.01658)
		(mid 353.455855 -219.216811)
		(end 353.376484 -219.490544)
		(width 0.0889)
		(layer "In2.Cu")
		(net "P5E_CPU0_PE1_TX_DN<14>")
	)
	(arc
		(start 353.37623 -214.62365)
		(mid 353.376037 -214.63051)
		(end 353.375722 -214.637366)
		(width 0.0889)
		(layer "In2.Cu")
		(net "P5E_CPU0_PE1_TX_DN<14>")
	)
	(segment
		(start 396.189708 -17.298162)
		(end 396.189708 -16.68399)
		(width 0.13208)
		(layer "F.Cu")
		(net "P5E_CPU0_PE1_TX_DN<13>")
	)
	(segment
		(start 355.351334 -223.57588)
		(end 355.35108 -223.575626)
		(width 0.13208)
		(layer "F.Cu")
		(net "P5E_CPU0_PE1_TX_DN<13>")
	)
	(segment
		(start 396.189708 -16.68399)
		(end 396.518384 -16.355314)
		(width 0.13208)
		(layer "F.Cu")
		(net "P5E_CPU0_PE1_TX_DN<13>")
	)
	(segment
		(start 355.351334 -224.111566)
		(end 355.351334 -223.57588)
		(width 0.13208)
		(layer "F.Cu")
		(net "P5E_CPU0_PE1_TX_DN<13>")
	)
	(segment
		(start 396.492984 -17.601438)
		(end 396.189708 -17.298162)
		(width 0.13208)
		(layer "F.Cu")
		(net "P5E_CPU0_PE1_TX_DN<13>")
	)
	(segment
		(start 396.266162 -20.972272)
		(end 396.435326 -21.087842)
		(width 0.14732)
		(layer "In2.Cu")
		(net "P5E_CPU0_PE1_TX_DN<13>")
	)
	(segment
		(start 354.976684 -220.309948)
		(end 354.976684 -220.32849)
		(width 0.0889)
		(layer "In2.Cu")
		(net "P5E_CPU0_PE1_TX_DN<13>")
	)
	(segment
		(start 354.694236 -217.554048)
		(end 354.685346 -217.559128)
		(width 0.0889)
		(layer "In2.Cu")
		(net "P5E_CPU0_PE1_TX_DN<13>")
	)
	(segment
		(start 354.694236 -222.437198)
		(end 354.685346 -222.442278)
		(width 0.0889)
		(layer "In2.Cu")
		(net "P5E_CPU0_PE1_TX_DN<13>")
	)
	(segment
		(start 396.198344 -20.242022)
		(end 396.198344 -20.610322)
		(width 0.14732)
		(layer "In2.Cu")
		(net "P5E_CPU0_PE1_TX_DN<13>")
	)
	(segment
		(start 354.078794 -211.938362)
		(end 354.078794 -213.227666)
		(width 0.14732)
		(layer "In2.Cu")
		(net "P5E_CPU0_PE1_TX_DN<13>")
	)
	(segment
		(start 403.193504 -80.125062)
		(end 342.01481 -167.498522)
		(width 0.14732)
		(layer "In2.Cu")
		(net "P5E_CPU0_PE1_TX_DN<13>")
	)
	(segment
		(start 354.706428 -219.174568)
		(end 354.694236 -219.18168)
		(width 0.0889)
		(layer "In2.Cu")
		(net "P5E_CPU0_PE1_TX_DN<13>")
	)
	(segment
		(start 399.960592 -40.690038)
		(end 404.074122 -75.484736)
		(width 0.14732)
		(layer "In2.Cu")
		(net "P5E_CPU0_PE1_TX_DN<13>")
	)
	(segment
		(start 354.078794 -213.227666)
		(end 354.078794 -213.249764)
		(width 0.0889)
		(layer "In2.Cu")
		(net "P5E_CPU0_PE1_TX_DN<13>")
	)
	(segment
		(start 342.01481 -167.498522)
		(end 340.889082 -172.574458)
		(width 0.14732)
		(layer "In2.Cu")
		(net "P5E_CPU0_PE1_TX_DN<13>")
	)
	(segment
		(start 354.976684 -217.05443)
		(end 354.976684 -217.082878)
		(width 0.0889)
		(layer "In2.Cu")
		(net "P5E_CPU0_PE1_TX_DN<13>")
	)
	(segment
		(start 340.889082 -172.574458)
		(end 341.484204 -175.951388)
		(width 0.14732)
		(layer "In2.Cu")
		(net "P5E_CPU0_PE1_TX_DN<13>")
	)
	(segment
		(start 354.078794 -213.249764)
		(end 354.03663 -213.291928)
		(width 0.0889)
		(layer "In2.Cu")
		(net "P5E_CPU0_PE1_TX_DN<13>")
	)
	(segment
		(start 396.343124 -19.728942)
		(end 396.343124 -20.097242)
		(width 0.14732)
		(layer "In2.Cu")
		(net "P5E_CPU0_PE1_TX_DN<13>")
	)
	(segment
		(start 353.15525 -206.876142)
		(end 354.078794 -211.938362)
		(width 0.14732)
		(layer "In2.Cu")
		(net "P5E_CPU0_PE1_TX_DN<13>")
	)
	(segment
		(start 354.976684 -221.94774)
		(end 354.976684 -221.957646)
		(width 0.0889)
		(layer "In2.Cu")
		(net "P5E_CPU0_PE1_TX_DN<13>")
	)
	(segment
		(start 354.03663 -213.8934)
		(end 354.036884 -213.893908)
		(width 0.0889)
		(layer "In2.Cu")
		(net "P5E_CPU0_PE1_TX_DN<13>")
	)
	(segment
		(start 354.698046 -218.20505)
		(end 354.706428 -218.209876)
		(width 0.0889)
		(layer "In2.Cu")
		(net "P5E_CPU0_PE1_TX_DN<13>")
	)
	(segment
		(start 354.685346 -218.197684)
		(end 354.694236 -218.202764)
		(width 0.0889)
		(layer "In2.Cu")
		(net "P5E_CPU0_PE1_TX_DN<13>")
	)
	(segment
		(start 396.343124 -20.097242)
		(end 396.198344 -20.242022)
		(width 0.14732)
		(layer "In2.Cu")
		(net "P5E_CPU0_PE1_TX_DN<13>")
	)
	(segment
		(start 355.116638 -223.867472)
		(end 355.194616 -223.846644)
		(width 0.0889)
		(layer "In2.Cu")
		(net "P5E_CPU0_PE1_TX_DN<13>")
	)
	(segment
		(start 354.976684 -223.557084)
		(end 354.976684 -223.584262)
		(width 0.0889)
		(layer "In2.Cu")
		(net "P5E_CPU0_PE1_TX_DN<13>")
	)
	(segment
		(start 355.164136 -221.623382)
		(end 355.155246 -221.628462)
		(width 0.0889)
		(layer "In2.Cu")
		(net "P5E_CPU0_PE1_TX_DN<13>")
	)
	(segment
		(start 404.074122 -75.484736)
		(end 403.193504 -80.125062)
		(width 0.14732)
		(layer "In2.Cu")
		(net "P5E_CPU0_PE1_TX_DN<13>")
	)
	(segment
		(start 354.22078 -215.759284)
		(end 354.22332 -215.760554)
		(width 0.0889)
		(layer "In2.Cu")
		(net "P5E_CPU0_PE1_TX_DN<13>")
	)
	(segment
		(start 396.387574 -21.618956)
		(end 399.960592 -40.690038)
		(width 0.14732)
		(layer "In2.Cu")
		(net "P5E_CPU0_PE1_TX_DN<13>")
	)
	(segment
		(start 354.685346 -223.080834)
		(end 354.694236 -223.085914)
		(width 0.0889)
		(layer "In2.Cu")
		(net "P5E_CPU0_PE1_TX_DN<13>")
	)
	(segment
		(start 354.685346 -219.825316)
		(end 354.694236 -219.830396)
		(width 0.0889)
		(layer "In2.Cu")
		(net "P5E_CPU0_PE1_TX_DN<13>")
	)
	(segment
		(start 396.503144 -21.450046)
		(end 396.387574 -21.618956)
		(width 0.14732)
		(layer "In2.Cu")
		(net "P5E_CPU0_PE1_TX_DN<13>")
	)
	(segment
		(start 354.224844 -215.76157)
		(end 354.230178 -215.764618)
		(width 0.0889)
		(layer "In2.Cu")
		(net "P5E_CPU0_PE1_TX_DN<13>")
	)
	(segment
		(start 354.03663 -213.291928)
		(end 354.03663 -213.8934)
		(width 0.0889)
		(layer "In2.Cu")
		(net "P5E_CPU0_PE1_TX_DN<13>")
	)
	(segment
		(start 354.215192 -215.755982)
		(end 354.22078 -215.759284)
		(width 0.0889)
		(layer "In2.Cu")
		(net "P5E_CPU0_PE1_TX_DN<13>")
	)
	(segment
		(start 396.198344 -19.584162)
		(end 396.343124 -19.728942)
		(width 0.14732)
		(layer "In2.Cu")
		(net "P5E_CPU0_PE1_TX_DN<13>")
	)
	(segment
		(start 354.224082 -215.112346)
		(end 354.215192 -215.117426)
		(width 0.0889)
		(layer "In2.Cu")
		(net "P5E_CPU0_PE1_TX_DN<13>")
	)
	(segment
		(start 354.685346 -216.569798)
		(end 354.694236 -216.574878)
		(width 0.0889)
		(layer "In2.Cu")
		(net "P5E_CPU0_PE1_TX_DN<13>")
	)
	(segment
		(start 354.22332 -215.760554)
		(end 354.224844 -215.76157)
		(width 0.0889)
		(layer "In2.Cu")
		(net "P5E_CPU0_PE1_TX_DN<13>")
	)
	(segment
		(start 354.694236 -219.18168)
		(end 354.685346 -219.18676)
		(width 0.0889)
		(layer "In2.Cu")
		(net "P5E_CPU0_PE1_TX_DN<13>")
	)
	(segment
		(start 396.198344 -17.896078)
		(end 396.198344 -19.584162)
		(width 0.14732)
		(layer "In2.Cu")
		(net "P5E_CPU0_PE1_TX_DN<13>")
	)
	(segment
		(start 355.446584 -221.1197)
		(end 355.446584 -221.14383)
		(width 0.0889)
		(layer "In2.Cu")
		(net "P5E_CPU0_PE1_TX_DN<13>")
	)
	(segment
		(start 341.484204 -175.951388)
		(end 353.15525 -206.876142)
		(width 0.14732)
		(layer "In2.Cu")
		(net "P5E_CPU0_PE1_TX_DN<13>")
	)
	(segment
		(start 354.506276 -214.424768)
		(end 354.506276 -214.644732)
		(width 0.0889)
		(layer "In2.Cu")
		(net "P5E_CPU0_PE1_TX_DN<13>")
	)
	(segment
		(start 354.694236 -218.202764)
		(end 354.698046 -218.20505)
		(width 0.0889)
		(layer "In2.Cu")
		(net "P5E_CPU0_PE1_TX_DN<13>")
	)
	(segment
		(start 396.492984 -17.601438)
		(end 396.198344 -17.896078)
		(width 0.14732)
		(layer "In2.Cu")
		(net "P5E_CPU0_PE1_TX_DN<13>")
	)
	(segment
		(start 354.506784 -216.25052)
		(end 354.506784 -216.257124)
		(width 0.0889)
		(layer "In2.Cu")
		(net "P5E_CPU0_PE1_TX_DN<13>")
	)
	(segment
		(start 396.435326 -21.087842)
		(end 396.503144 -21.450046)
		(width 0.14732)
		(layer "In2.Cu")
		(net "P5E_CPU0_PE1_TX_DN<13>")
	)
	(segment
		(start 355.194616 -223.846644)
		(end 355.35108 -223.575626)
		(width 0.0889)
		(layer "In2.Cu")
		(net "P5E_CPU0_PE1_TX_DN<13>")
	)
	(segment
		(start 396.198344 -20.610322)
		(end 396.266162 -20.972272)
		(width 0.14732)
		(layer "In2.Cu")
		(net "P5E_CPU0_PE1_TX_DN<13>")
	)
	(arc
		(start 354.706428 -218.209876)
		(mid 354.976884 -218.692222)
		(end 354.706428 -219.174568)
		(width 0.0889)
		(layer "In2.Cu")
		(net "P5E_CPU0_PE1_TX_DN<13>")
	)
	(arc
		(start 354.976684 -221.957646)
		(mid 354.898573 -222.234595)
		(end 354.694236 -222.437198)
		(width 0.0889)
		(layer "In2.Cu")
		(net "P5E_CPU0_PE1_TX_DN<13>")
	)
	(arc
		(start 355.155246 -221.628462)
		(mid 355.024332 -221.764822)
		(end 354.976684 -221.94774)
		(width 0.0889)
		(layer "In2.Cu")
		(net "P5E_CPU0_PE1_TX_DN<13>")
	)
	(arc
		(start 354.29444 -214.139272)
		(mid 354.422007 -214.265951)
		(end 354.506276 -214.424768)
		(width 0.0889)
		(layer "In2.Cu")
		(net "P5E_CPU0_PE1_TX_DN<13>")
	)
	(arc
		(start 354.506276 -214.644732)
		(mid 354.445993 -214.877569)
		(end 354.29444 -215.06434)
		(width 0.0889)
		(layer "In2.Cu")
		(net "P5E_CPU0_PE1_TX_DN<13>")
	)
	(arc
		(start 354.976684 -220.32849)
		(mid 355.028954 -220.510855)
		(end 355.163882 -220.644212)
		(width 0.0889)
		(layer "In2.Cu")
		(net "P5E_CPU0_PE1_TX_DN<13>")
	)
	(arc
		(start 354.506784 -222.754952)
		(mid 354.506794 -222.764352)
		(end 354.507038 -222.773748)
		(width 0.0889)
		(layer "In2.Cu")
		(net "P5E_CPU0_PE1_TX_DN<13>")
	)
	(arc
		(start 354.036884 -213.893908)
		(mid 354.111889 -214.009367)
		(end 354.221034 -214.093298)
		(width 0.0889)
		(layer "In2.Cu")
		(net "P5E_CPU0_PE1_TX_DN<13>")
	)
	(arc
		(start 354.29444 -215.06434)
		(mid 354.260164 -215.089666)
		(end 354.224082 -215.112346)
		(width 0.0889)
		(layer "In2.Cu")
		(net "P5E_CPU0_PE1_TX_DN<13>")
	)
	(arc
		(start 354.976684 -217.082878)
		(mid 354.896522 -217.355067)
		(end 354.694236 -217.554048)
		(width 0.0889)
		(layer "In2.Cu")
		(net "P5E_CPU0_PE1_TX_DN<13>")
	)
	(arc
		(start 354.036884 -215.421972)
		(mid 354.036687 -215.429337)
		(end 354.03663 -215.436704)
		(width 0.0889)
		(layer "In2.Cu")
		(net "P5E_CPU0_PE1_TX_DN<13>")
	)
	(arc
		(start 354.03663 -215.436704)
		(mid 354.084309 -215.619604)
		(end 354.215192 -215.755982)
		(width 0.0889)
		(layer "In2.Cu")
		(net "P5E_CPU0_PE1_TX_DN<13>")
	)
	(arc
		(start 354.685346 -219.18676)
		(mid 354.506749 -219.506038)
		(end 354.685346 -219.825316)
		(width 0.0889)
		(layer "In2.Cu")
		(net "P5E_CPU0_PE1_TX_DN<13>")
	)
	(arc
		(start 354.976684 -223.584262)
		(mid 355.015358 -223.74133)
		(end 355.116638 -223.867472)
		(width 0.0889)
		(layer "In2.Cu")
		(net "P5E_CPU0_PE1_TX_DN<13>")
	)
	(arc
		(start 354.694236 -219.830396)
		(mid 354.898571 -220.033001)
		(end 354.976684 -220.309948)
		(width 0.0889)
		(layer "In2.Cu")
		(net "P5E_CPU0_PE1_TX_DN<13>")
	)
	(arc
		(start 354.694236 -223.085914)
		(mid 354.896522 -223.284895)
		(end 354.976684 -223.557084)
		(width 0.0889)
		(layer "In2.Cu")
		(net "P5E_CPU0_PE1_TX_DN<13>")
	)
	(arc
		(start 354.507038 -217.866214)
		(mid 354.506793 -217.87561)
		(end 354.506784 -217.88501)
		(width 0.0889)
		(layer "In2.Cu")
		(net "P5E_CPU0_PE1_TX_DN<13>")
	)
	(arc
		(start 354.221034 -214.093298)
		(mid 354.258573 -214.114951)
		(end 354.29444 -214.139272)
		(width 0.0889)
		(layer "In2.Cu")
		(net "P5E_CPU0_PE1_TX_DN<13>")
	)
	(arc
		(start 354.215192 -215.117426)
		(mid 354.087938 -215.247392)
		(end 354.036884 -215.421972)
		(width 0.0889)
		(layer "In2.Cu")
		(net "P5E_CPU0_PE1_TX_DN<13>")
	)
	(arc
		(start 354.685346 -217.559128)
		(mid 354.557453 -217.69019)
		(end 354.507038 -217.866214)
		(width 0.0889)
		(layer "In2.Cu")
		(net "P5E_CPU0_PE1_TX_DN<13>")
	)
	(arc
		(start 354.506784 -216.257124)
		(mid 354.556037 -216.436324)
		(end 354.685346 -216.569798)
		(width 0.0889)
		(layer "In2.Cu")
		(net "P5E_CPU0_PE1_TX_DN<13>")
	)
	(arc
		(start 354.29444 -215.809068)
		(mid 354.401606 -215.922313)
		(end 354.473764 -216.060528)
		(width 0.0889)
		(layer "In2.Cu")
		(net "P5E_CPU0_PE1_TX_DN<13>")
	)
	(arc
		(start 354.507038 -222.773748)
		(mid 354.557531 -222.949726)
		(end 354.685346 -223.080834)
		(width 0.0889)
		(layer "In2.Cu")
		(net "P5E_CPU0_PE1_TX_DN<13>")
	)
	(arc
		(start 354.506784 -217.88501)
		(mid 354.556037 -218.06421)
		(end 354.685346 -218.197684)
		(width 0.0889)
		(layer "In2.Cu")
		(net "P5E_CPU0_PE1_TX_DN<13>")
	)
	(arc
		(start 355.163882 -220.644212)
		(mid 355.367363 -220.845016)
		(end 355.446584 -221.1197)
		(width 0.0889)
		(layer "In2.Cu")
		(net "P5E_CPU0_PE1_TX_DN<13>")
	)
	(arc
		(start 354.694236 -216.574878)
		(mid 354.898571 -216.777483)
		(end 354.976684 -217.05443)
		(width 0.0889)
		(layer "In2.Cu")
		(net "P5E_CPU0_PE1_TX_DN<13>")
	)
	(arc
		(start 354.230178 -215.764618)
		(mid 354.26308 -215.785729)
		(end 354.29444 -215.809068)
		(width 0.0889)
		(layer "In2.Cu")
		(net "P5E_CPU0_PE1_TX_DN<13>")
	)
	(arc
		(start 354.685346 -222.442278)
		(mid 354.556057 -222.575764)
		(end 354.506784 -222.754952)
		(width 0.0889)
		(layer "In2.Cu")
		(net "P5E_CPU0_PE1_TX_DN<13>")
	)
	(arc
		(start 354.473764 -216.060528)
		(mid 354.498432 -216.154105)
		(end 354.506784 -216.25052)
		(width 0.0889)
		(layer "In2.Cu")
		(net "P5E_CPU0_PE1_TX_DN<13>")
	)
	(arc
		(start 355.446584 -221.14383)
		(mid 355.368473 -221.420779)
		(end 355.164136 -221.623382)
		(width 0.0889)
		(layer "In2.Cu")
		(net "P5E_CPU0_PE1_TX_DN<13>")
	)
	(segment
		(start 355.82098 -224.389696)
		(end 355.821234 -224.389442)
		(width 0.13208)
		(layer "F.Cu")
		(net "P5E_CPU0_PE1_TX_DN<12>")
	)
	(segment
		(start 398.724628 -18.824194)
		(end 398.724628 -18.205958)
		(width 0.13208)
		(layer "F.Cu")
		(net "P5E_CPU0_PE1_TX_DN<12>")
	)
	(segment
		(start 398.423384 -19.125438)
		(end 398.724628 -18.824194)
		(width 0.13208)
		(layer "F.Cu")
		(net "P5E_CPU0_PE1_TX_DN<12>")
	)
	(segment
		(start 355.82098 -224.925382)
		(end 355.82098 -224.389696)
		(width 0.13208)
		(layer "F.Cu")
		(net "P5E_CPU0_PE1_TX_DN<12>")
	)
	(segment
		(start 398.724628 -18.205958)
		(end 398.397984 -17.879314)
		(width 0.13208)
		(layer "F.Cu")
		(net "P5E_CPU0_PE1_TX_DN<12>")
	)
	(segment
		(start 355.077014 -214.941912)
		(end 355.068124 -214.946992)
		(width 0.0889)
		(layer "In2.Cu")
		(net "P5E_CPU0_PE1_TX_DN<12>")
	)
	(segment
		(start 398.814544 -22.585426)
		(end 398.974564 -22.713188)
		(width 0.14732)
		(layer "In2.Cu")
		(net "P5E_CPU0_PE1_TX_DN<12>")
	)
	(segment
		(start 354.786184 -213.291674)
		(end 354.786184 -213.839806)
		(width 0.0889)
		(layer "In2.Cu")
		(net "P5E_CPU0_PE1_TX_DN<12>")
	)
	(segment
		(start 356.05593 -224.681288)
		(end 355.977698 -224.66046)
		(width 0.0889)
		(layer "In2.Cu")
		(net "P5E_CPU0_PE1_TX_DN<12>")
	)
	(segment
		(start 355.256084 -219.490544)
		(end 355.256084 -219.521532)
		(width 0.0889)
		(layer "In2.Cu")
		(net "P5E_CPU0_PE1_TX_DN<12>")
	)
	(segment
		(start 355.256084 -217.856308)
		(end 355.256084 -217.8939)
		(width 0.0889)
		(layer "In2.Cu")
		(net "P5E_CPU0_PE1_TX_DN<12>")
	)
	(segment
		(start 355.062536 -215.922606)
		(end 355.068632 -215.926162)
		(width 0.0889)
		(layer "In2.Cu")
		(net "P5E_CPU0_PE1_TX_DN<12>")
	)
	(segment
		(start 342.63076 -167.762428)
		(end 341.55888 -172.596302)
		(width 0.14732)
		(layer "In2.Cu")
		(net "P5E_CPU0_PE1_TX_DN<12>")
	)
	(segment
		(start 355.256084 -222.746062)
		(end 355.256084 -222.783654)
		(width 0.0889)
		(layer "In2.Cu")
		(net "P5E_CPU0_PE1_TX_DN<12>")
	)
	(segment
		(start 355.547168 -217.383614)
		(end 355.538278 -217.388694)
		(width 0.0889)
		(layer "In2.Cu")
		(net "P5E_CPU0_PE1_TX_DN<12>")
	)
	(segment
		(start 355.547168 -219.0115)
		(end 355.538278 -219.01658)
		(width 0.0889)
		(layer "In2.Cu")
		(net "P5E_CPU0_PE1_TX_DN<12>")
	)
	(segment
		(start 355.977698 -224.66046)
		(end 355.821234 -224.389442)
		(width 0.0889)
		(layer "In2.Cu")
		(net "P5E_CPU0_PE1_TX_DN<12>")
	)
	(segment
		(start 356.008432 -224.065084)
		(end 356.017322 -224.070164)
		(width 0.0889)
		(layer "In2.Cu")
		(net "P5E_CPU0_PE1_TX_DN<12>")
	)
	(segment
		(start 354.744274 -213.249764)
		(end 354.786184 -213.291674)
		(width 0.0889)
		(layer "In2.Cu")
		(net "P5E_CPU0_PE1_TX_DN<12>")
	)
	(segment
		(start 355.256084 -216.25052)
		(end 355.256084 -216.266014)
		(width 0.0889)
		(layer "In2.Cu")
		(net "P5E_CPU0_PE1_TX_DN<12>")
	)
	(segment
		(start 398.974564 -22.713188)
		(end 404.845774 -75.486768)
		(width 0.14732)
		(layer "In2.Cu")
		(net "P5E_CPU0_PE1_TX_DN<12>")
	)
	(segment
		(start 355.539294 -218.368372)
		(end 355.547168 -218.372944)
		(width 0.0889)
		(layer "In2.Cu")
		(net "P5E_CPU0_PE1_TX_DN<12>")
	)
	(segment
		(start 398.773904 -22.219158)
		(end 398.814544 -22.585426)
		(width 0.14732)
		(layer "In2.Cu")
		(net "P5E_CPU0_PE1_TX_DN<12>")
	)
	(segment
		(start 354.78593 -215.414606)
		(end 354.78593 -215.436704)
		(width 0.0889)
		(layer "In2.Cu")
		(net "P5E_CPU0_PE1_TX_DN<12>")
	)
	(segment
		(start 356.009194 -220.810074)
		(end 356.017322 -220.814646)
		(width 0.0889)
		(layer "In2.Cu")
		(net "P5E_CPU0_PE1_TX_DN<12>")
	)
	(segment
		(start 398.787874 -21.035518)
		(end 398.660112 -21.195538)
		(width 0.14732)
		(layer "In2.Cu")
		(net "P5E_CPU0_PE1_TX_DN<12>")
	)
	(segment
		(start 355.538278 -218.367864)
		(end 355.539294 -218.368372)
		(width 0.0889)
		(layer "In2.Cu")
		(net "P5E_CPU0_PE1_TX_DN<12>")
	)
	(segment
		(start 398.698974 -19.401028)
		(end 398.698974 -20.235164)
		(width 0.14732)
		(layer "In2.Cu")
		(net "P5E_CPU0_PE1_TX_DN<12>")
	)
	(segment
		(start 355.539294 -216.740486)
		(end 355.547168 -216.745058)
		(width 0.0889)
		(layer "In2.Cu")
		(net "P5E_CPU0_PE1_TX_DN<12>")
	)
	(segment
		(start 404.845774 -75.486768)
		(end 404.041102 -80.057752)
		(width 0.14732)
		(layer "In2.Cu")
		(net "P5E_CPU0_PE1_TX_DN<12>")
	)
	(segment
		(start 404.041102 -80.057752)
		(end 342.63076 -167.762428)
		(width 0.14732)
		(layer "In2.Cu")
		(net "P5E_CPU0_PE1_TX_DN<12>")
	)
	(segment
		(start 398.860772 -21.689314)
		(end 398.901666 -22.059138)
		(width 0.14732)
		(layer "In2.Cu")
		(net "P5E_CPU0_PE1_TX_DN<12>")
	)
	(segment
		(start 355.255576 -214.500968)
		(end 355.255576 -214.622634)
		(width 0.0889)
		(layer "In2.Cu")
		(net "P5E_CPU0_PE1_TX_DN<12>")
	)
	(segment
		(start 354.744274 -213.227666)
		(end 354.744274 -213.249764)
		(width 0.0889)
		(layer "In2.Cu")
		(net "P5E_CPU0_PE1_TX_DN<12>")
	)
	(segment
		(start 356.017322 -221.453202)
		(end 356.008432 -221.458282)
		(width 0.0889)
		(layer "In2.Cu")
		(net "P5E_CPU0_PE1_TX_DN<12>")
	)
	(segment
		(start 398.700752 -21.561806)
		(end 398.860772 -21.689314)
		(width 0.14732)
		(layer "In2.Cu")
		(net "P5E_CPU0_PE1_TX_DN<12>")
	)
	(segment
		(start 355.068632 -215.926162)
		(end 355.077522 -215.931242)
		(width 0.0889)
		(layer "In2.Cu")
		(net "P5E_CPU0_PE1_TX_DN<12>")
	)
	(segment
		(start 398.423384 -19.125438)
		(end 398.698974 -19.401028)
		(width 0.14732)
		(layer "In2.Cu")
		(net "P5E_CPU0_PE1_TX_DN<12>")
	)
	(segment
		(start 353.857814 -206.853536)
		(end 354.744274 -211.710524)
		(width 0.14732)
		(layer "In2.Cu")
		(net "P5E_CPU0_PE1_TX_DN<12>")
	)
	(segment
		(start 398.901666 -22.059138)
		(end 398.773904 -22.219158)
		(width 0.14732)
		(layer "In2.Cu")
		(net "P5E_CPU0_PE1_TX_DN<12>")
	)
	(segment
		(start 355.538278 -219.995496)
		(end 355.539294 -219.996004)
		(width 0.0889)
		(layer "In2.Cu")
		(net "P5E_CPU0_PE1_TX_DN<12>")
	)
	(segment
		(start 355.538278 -223.251268)
		(end 355.547168 -223.256348)
		(width 0.0889)
		(layer "In2.Cu")
		(net "P5E_CPU0_PE1_TX_DN<12>")
	)
	(segment
		(start 398.660112 -21.195538)
		(end 398.700752 -21.561806)
		(width 0.14732)
		(layer "In2.Cu")
		(net "P5E_CPU0_PE1_TX_DN<12>")
	)
	(segment
		(start 341.55888 -172.596302)
		(end 342.114632 -175.750728)
		(width 0.14732)
		(layer "In2.Cu")
		(net "P5E_CPU0_PE1_TX_DN<12>")
	)
	(segment
		(start 355.547168 -222.267018)
		(end 355.538278 -222.272098)
		(width 0.0889)
		(layer "In2.Cu")
		(net "P5E_CPU0_PE1_TX_DN<12>")
	)
	(segment
		(start 354.744274 -211.710524)
		(end 354.744274 -213.227666)
		(width 0.14732)
		(layer "In2.Cu")
		(net "P5E_CPU0_PE1_TX_DN<12>")
	)
	(segment
		(start 398.698974 -20.235164)
		(end 398.787874 -21.035518)
		(width 0.14732)
		(layer "In2.Cu")
		(net "P5E_CPU0_PE1_TX_DN<12>")
	)
	(segment
		(start 355.538278 -216.739978)
		(end 355.539294 -216.740486)
		(width 0.0889)
		(layer "In2.Cu")
		(net "P5E_CPU0_PE1_TX_DN<12>")
	)
	(segment
		(start 355.72573 -220.319854)
		(end 355.72573 -220.327474)
		(width 0.0889)
		(layer "In2.Cu")
		(net "P5E_CPU0_PE1_TX_DN<12>")
	)
	(segment
		(start 342.114632 -175.750728)
		(end 353.857814 -206.853536)
		(width 0.14732)
		(layer "In2.Cu")
		(net "P5E_CPU0_PE1_TX_DN<12>")
	)
	(segment
		(start 356.008432 -221.458282)
		(end 356.002336 -221.461838)
		(width 0.0889)
		(layer "In2.Cu")
		(net "P5E_CPU0_PE1_TX_DN<12>")
	)
	(segment
		(start 356.008432 -220.809566)
		(end 356.009194 -220.810074)
		(width 0.0889)
		(layer "In2.Cu")
		(net "P5E_CPU0_PE1_TX_DN<12>")
	)
	(segment
		(start 355.539294 -219.996004)
		(end 355.547168 -220.000576)
		(width 0.0889)
		(layer "In2.Cu")
		(net "P5E_CPU0_PE1_TX_DN<12>")
	)
	(segment
		(start 355.99624 -224.057972)
		(end 356.008432 -224.065084)
		(width 0.0889)
		(layer "In2.Cu")
		(net "P5E_CPU0_PE1_TX_DN<12>")
	)
	(arc
		(start 356.017322 -220.814646)
		(mid 356.195919 -221.133924)
		(end 356.017322 -221.453202)
		(width 0.0889)
		(layer "In2.Cu")
		(net "P5E_CPU0_PE1_TX_DN<12>")
	)
	(arc
		(start 355.077522 -215.931242)
		(mid 355.208436 -216.067602)
		(end 355.256084 -216.25052)
		(width 0.0889)
		(layer "In2.Cu")
		(net "P5E_CPU0_PE1_TX_DN<12>")
	)
	(arc
		(start 355.72573 -223.575626)
		(mid 355.797965 -223.85215)
		(end 355.99624 -224.057972)
		(width 0.0889)
		(layer "In2.Cu")
		(net "P5E_CPU0_PE1_TX_DN<12>")
	)
	(arc
		(start 355.256084 -217.8939)
		(mid 355.335454 -218.167634)
		(end 355.538278 -218.367864)
		(width 0.0889)
		(layer "In2.Cu")
		(net "P5E_CPU0_PE1_TX_DN<12>")
	)
	(arc
		(start 355.547168 -220.000576)
		(mid 355.678082 -220.136936)
		(end 355.72573 -220.319854)
		(width 0.0889)
		(layer "In2.Cu")
		(net "P5E_CPU0_PE1_TX_DN<12>")
	)
	(arc
		(start 356.195884 -224.389442)
		(mid 356.159024 -224.551239)
		(end 356.05593 -224.681288)
		(width 0.0889)
		(layer "In2.Cu")
		(net "P5E_CPU0_PE1_TX_DN<12>")
	)
	(arc
		(start 355.255322 -214.637366)
		(mid 355.204268 -214.811946)
		(end 355.077014 -214.941912)
		(width 0.0889)
		(layer "In2.Cu")
		(net "P5E_CPU0_PE1_TX_DN<12>")
	)
	(arc
		(start 355.256084 -222.783654)
		(mid 355.336995 -223.053782)
		(end 355.538278 -223.251268)
		(width 0.0889)
		(layer "In2.Cu")
		(net "P5E_CPU0_PE1_TX_DN<12>")
	)
	(arc
		(start 355.538278 -217.388694)
		(mid 355.336996 -217.586181)
		(end 355.256084 -217.856308)
		(width 0.0889)
		(layer "In2.Cu")
		(net "P5E_CPU0_PE1_TX_DN<12>")
	)
	(arc
		(start 354.78593 -215.436704)
		(mid 354.859921 -215.71627)
		(end 355.062536 -215.922606)
		(width 0.0889)
		(layer "In2.Cu")
		(net "P5E_CPU0_PE1_TX_DN<12>")
	)
	(arc
		(start 356.017322 -224.070164)
		(mid 356.148236 -224.206524)
		(end 356.195884 -224.389442)
		(width 0.0889)
		(layer "In2.Cu")
		(net "P5E_CPU0_PE1_TX_DN<12>")
	)
	(arc
		(start 355.256084 -216.266014)
		(mid 355.335454 -216.539748)
		(end 355.538278 -216.739978)
		(width 0.0889)
		(layer "In2.Cu")
		(net "P5E_CPU0_PE1_TX_DN<12>")
	)
	(arc
		(start 354.786184 -213.839806)
		(mid 354.804347 -213.94823)
		(end 354.857812 -214.044276)
		(width 0.0889)
		(layer "In2.Cu")
		(net "P5E_CPU0_PE1_TX_DN<12>")
	)
	(arc
		(start 355.538278 -219.01658)
		(mid 355.335455 -219.216811)
		(end 355.256084 -219.490544)
		(width 0.0889)
		(layer "In2.Cu")
		(net "P5E_CPU0_PE1_TX_DN<12>")
	)
	(arc
		(start 355.538278 -222.272098)
		(mid 355.335455 -222.472329)
		(end 355.256084 -222.746062)
		(width 0.0889)
		(layer "In2.Cu")
		(net "P5E_CPU0_PE1_TX_DN<12>")
	)
	(arc
		(start 354.857812 -214.044276)
		(mid 354.929913 -214.127304)
		(end 355.007418 -214.205312)
		(width 0.0889)
		(layer "In2.Cu")
		(net "P5E_CPU0_PE1_TX_DN<12>")
	)
	(arc
		(start 355.068124 -214.946992)
		(mid 354.866842 -215.144479)
		(end 354.78593 -215.414606)
		(width 0.0889)
		(layer "In2.Cu")
		(net "P5E_CPU0_PE1_TX_DN<12>")
	)
	(arc
		(start 355.547168 -216.745058)
		(mid 355.725765 -217.064336)
		(end 355.547168 -217.383614)
		(width 0.0889)
		(layer "In2.Cu")
		(net "P5E_CPU0_PE1_TX_DN<12>")
	)
	(arc
		(start 355.255576 -214.622634)
		(mid 355.255524 -214.630001)
		(end 355.255322 -214.637366)
		(width 0.0889)
		(layer "In2.Cu")
		(net "P5E_CPU0_PE1_TX_DN<12>")
	)
	(arc
		(start 355.104446 -214.28075)
		(mid 355.176189 -214.340426)
		(end 355.232462 -214.414862)
		(width 0.0889)
		(layer "In2.Cu")
		(net "P5E_CPU0_PE1_TX_DN<12>")
	)
	(arc
		(start 355.72573 -220.327474)
		(mid 355.803359 -220.605887)
		(end 356.008432 -220.809566)
		(width 0.0889)
		(layer "In2.Cu")
		(net "P5E_CPU0_PE1_TX_DN<12>")
	)
	(arc
		(start 355.547168 -223.256348)
		(mid 355.678082 -223.392708)
		(end 355.72573 -223.575626)
		(width 0.0889)
		(layer "In2.Cu")
		(net "P5E_CPU0_PE1_TX_DN<12>")
	)
	(arc
		(start 355.007418 -214.205312)
		(mid 355.054264 -214.245175)
		(end 355.104446 -214.28075)
		(width 0.0889)
		(layer "In2.Cu")
		(net "P5E_CPU0_PE1_TX_DN<12>")
	)
	(arc
		(start 355.232462 -214.414862)
		(mid 355.249764 -214.45637)
		(end 355.255576 -214.500968)
		(width 0.0889)
		(layer "In2.Cu")
		(net "P5E_CPU0_PE1_TX_DN<12>")
	)
	(arc
		(start 355.547168 -218.372944)
		(mid 355.725644 -218.692222)
		(end 355.547168 -219.0115)
		(width 0.0889)
		(layer "In2.Cu")
		(net "P5E_CPU0_PE1_TX_DN<12>")
	)
	(arc
		(start 356.002336 -221.461838)
		(mid 355.799749 -221.668189)
		(end 355.72573 -221.94774)
		(width 0.0889)
		(layer "In2.Cu")
		(net "P5E_CPU0_PE1_TX_DN<12>")
	)
	(arc
		(start 355.256084 -219.521532)
		(mid 355.335454 -219.795266)
		(end 355.538278 -219.995496)
		(width 0.0889)
		(layer "In2.Cu")
		(net "P5E_CPU0_PE1_TX_DN<12>")
	)
	(arc
		(start 355.72573 -221.94774)
		(mid 355.678051 -222.13064)
		(end 355.547168 -222.267018)
		(width 0.0889)
		(layer "In2.Cu")
		(net "P5E_CPU0_PE1_TX_DN<12>")
	)
	(segment
		(start 401.777708 -16.68399)
		(end 402.106384 -16.355314)
		(width 0.13208)
		(layer "F.Cu")
		(net "P5E_CPU0_PE1_TX_DN<11>")
	)
	(segment
		(start 357.230934 -224.111566)
		(end 357.230934 -223.57588)
		(width 0.13208)
		(layer "F.Cu")
		(net "P5E_CPU0_PE1_TX_DN<11>")
	)
	(segment
		(start 401.777708 -17.298162)
		(end 401.777708 -16.68399)
		(width 0.13208)
		(layer "F.Cu")
		(net "P5E_CPU0_PE1_TX_DN<11>")
	)
	(segment
		(start 357.230934 -223.57588)
		(end 357.23068 -223.575626)
		(width 0.13208)
		(layer "F.Cu")
		(net "P5E_CPU0_PE1_TX_DN<11>")
	)
	(segment
		(start 402.080984 -17.601438)
		(end 401.777708 -17.298162)
		(width 0.13208)
		(layer "F.Cu")
		(net "P5E_CPU0_PE1_TX_DN<11>")
	)
	(segment
		(start 357.074216 -223.846644)
		(end 357.23068 -223.575626)
		(width 0.0889)
		(layer "In2.Cu")
		(net "P5E_CPU0_PE1_TX_DN<11>")
	)
	(segment
		(start 356.856284 -223.557084)
		(end 356.856284 -223.584262)
		(width 0.0889)
		(layer "In2.Cu")
		(net "P5E_CPU0_PE1_TX_DN<11>")
	)
	(segment
		(start 357.326184 -221.1197)
		(end 357.326184 -221.14383)
		(width 0.0889)
		(layer "In2.Cu")
		(net "P5E_CPU0_PE1_TX_DN<11>")
	)
	(segment
		(start 355.91623 -213.291928)
		(end 355.91623 -213.8934)
		(width 0.0889)
		(layer "In2.Cu")
		(net "P5E_CPU0_PE1_TX_DN<11>")
	)
	(segment
		(start 356.573836 -218.202764)
		(end 356.577646 -218.20505)
		(width 0.0889)
		(layer "In2.Cu")
		(net "P5E_CPU0_PE1_TX_DN<11>")
	)
	(segment
		(start 356.996238 -223.867472)
		(end 357.074216 -223.846644)
		(width 0.0889)
		(layer "In2.Cu")
		(net "P5E_CPU0_PE1_TX_DN<11>")
	)
	(segment
		(start 356.573836 -219.18168)
		(end 356.564946 -219.18676)
		(width 0.0889)
		(layer "In2.Cu")
		(net "P5E_CPU0_PE1_TX_DN<11>")
	)
	(segment
		(start 355.958394 -211.522818)
		(end 355.958394 -213.227666)
		(width 0.14732)
		(layer "In2.Cu")
		(net "P5E_CPU0_PE1_TX_DN<11>")
	)
	(segment
		(start 356.573836 -222.437198)
		(end 356.564946 -222.442278)
		(width 0.0889)
		(layer "In2.Cu")
		(net "P5E_CPU0_PE1_TX_DN<11>")
	)
	(segment
		(start 401.99437 -19.144488)
		(end 402.023834 -19.511772)
		(width 0.14732)
		(layer "In2.Cu")
		(net "P5E_CPU0_PE1_TX_DN<11>")
	)
	(segment
		(start 356.577646 -218.20505)
		(end 356.586028 -218.209876)
		(width 0.0889)
		(layer "In2.Cu")
		(net "P5E_CPU0_PE1_TX_DN<11>")
	)
	(segment
		(start 401.973796 -20.690586)
		(end 406.356312 -75.11034)
		(width 0.14732)
		(layer "In2.Cu")
		(net "P5E_CPU0_PE1_TX_DN<11>")
	)
	(segment
		(start 402.106384 -20.534884)
		(end 401.973796 -20.690586)
		(width 0.14732)
		(layer "In2.Cu")
		(net "P5E_CPU0_PE1_TX_DN<11>")
	)
	(segment
		(start 402.07692 -20.167346)
		(end 402.106384 -20.534884)
		(width 0.14732)
		(layer "In2.Cu")
		(net "P5E_CPU0_PE1_TX_DN<11>")
	)
	(segment
		(start 401.92071 -20.034758)
		(end 402.07692 -20.167346)
		(width 0.14732)
		(layer "In2.Cu")
		(net "P5E_CPU0_PE1_TX_DN<11>")
	)
	(segment
		(start 355.059996 -206.599282)
		(end 355.958394 -211.522818)
		(width 0.14732)
		(layer "In2.Cu")
		(net "P5E_CPU0_PE1_TX_DN<11>")
	)
	(segment
		(start 406.356312 -75.11034)
		(end 405.483568 -80.11541)
		(width 0.14732)
		(layer "In2.Cu")
		(net "P5E_CPU0_PE1_TX_DN<11>")
	)
	(segment
		(start 355.958394 -213.227666)
		(end 355.958394 -213.249764)
		(width 0.0889)
		(layer "In2.Cu")
		(net "P5E_CPU0_PE1_TX_DN<11>")
	)
	(segment
		(start 343.749122 -168.282366)
		(end 342.792304 -172.598334)
		(width 0.14732)
		(layer "In2.Cu")
		(net "P5E_CPU0_PE1_TX_DN<11>")
	)
	(segment
		(start 355.958394 -213.249764)
		(end 355.91623 -213.291928)
		(width 0.0889)
		(layer "In2.Cu")
		(net "P5E_CPU0_PE1_TX_DN<11>")
	)
	(segment
		(start 402.080984 -17.601438)
		(end 401.786344 -17.896078)
		(width 0.14732)
		(layer "In2.Cu")
		(net "P5E_CPU0_PE1_TX_DN<11>")
	)
	(segment
		(start 356.856284 -221.94774)
		(end 356.856284 -221.957646)
		(width 0.0889)
		(layer "In2.Cu")
		(net "P5E_CPU0_PE1_TX_DN<11>")
	)
	(segment
		(start 356.564946 -219.825316)
		(end 356.573836 -219.830396)
		(width 0.0889)
		(layer "In2.Cu")
		(net "P5E_CPU0_PE1_TX_DN<11>")
	)
	(segment
		(start 342.792304 -172.598334)
		(end 343.287858 -175.410114)
		(width 0.14732)
		(layer "In2.Cu")
		(net "P5E_CPU0_PE1_TX_DN<11>")
	)
	(segment
		(start 401.83816 -19.011646)
		(end 401.99437 -19.144488)
		(width 0.14732)
		(layer "In2.Cu")
		(net "P5E_CPU0_PE1_TX_DN<11>")
	)
	(segment
		(start 402.023834 -19.511772)
		(end 401.891246 -19.667728)
		(width 0.14732)
		(layer "In2.Cu")
		(net "P5E_CPU0_PE1_TX_DN<11>")
	)
	(segment
		(start 401.786344 -17.896078)
		(end 401.786344 -18.367756)
		(width 0.14732)
		(layer "In2.Cu")
		(net "P5E_CPU0_PE1_TX_DN<11>")
	)
	(segment
		(start 401.891246 -19.667728)
		(end 401.92071 -20.034758)
		(width 0.14732)
		(layer "In2.Cu")
		(net "P5E_CPU0_PE1_TX_DN<11>")
	)
	(segment
		(start 357.043736 -221.623382)
		(end 357.034846 -221.628462)
		(width 0.0889)
		(layer "In2.Cu")
		(net "P5E_CPU0_PE1_TX_DN<11>")
	)
	(segment
		(start 356.564946 -218.197684)
		(end 356.573836 -218.202764)
		(width 0.0889)
		(layer "In2.Cu")
		(net "P5E_CPU0_PE1_TX_DN<11>")
	)
	(segment
		(start 405.483568 -80.11541)
		(end 343.749122 -168.282366)
		(width 0.14732)
		(layer "In2.Cu")
		(net "P5E_CPU0_PE1_TX_DN<11>")
	)
	(segment
		(start 356.103682 -215.112346)
		(end 356.094792 -215.117426)
		(width 0.0889)
		(layer "In2.Cu")
		(net "P5E_CPU0_PE1_TX_DN<11>")
	)
	(segment
		(start 356.856284 -220.309948)
		(end 356.856284 -220.32849)
		(width 0.0889)
		(layer "In2.Cu")
		(net "P5E_CPU0_PE1_TX_DN<11>")
	)
	(segment
		(start 401.786344 -18.367756)
		(end 401.83816 -19.011646)
		(width 0.14732)
		(layer "In2.Cu")
		(net "P5E_CPU0_PE1_TX_DN<11>")
	)
	(segment
		(start 356.586028 -219.174568)
		(end 356.573836 -219.18168)
		(width 0.0889)
		(layer "In2.Cu")
		(net "P5E_CPU0_PE1_TX_DN<11>")
	)
	(segment
		(start 356.386384 -216.25052)
		(end 356.386384 -216.257124)
		(width 0.0889)
		(layer "In2.Cu")
		(net "P5E_CPU0_PE1_TX_DN<11>")
	)
	(segment
		(start 356.094792 -215.755982)
		(end 356.103682 -215.761062)
		(width 0.0889)
		(layer "In2.Cu")
		(net "P5E_CPU0_PE1_TX_DN<11>")
	)
	(segment
		(start 355.91623 -213.8934)
		(end 355.916484 -213.893908)
		(width 0.0889)
		(layer "In2.Cu")
		(net "P5E_CPU0_PE1_TX_DN<11>")
	)
	(segment
		(start 356.564946 -216.569798)
		(end 356.573836 -216.574878)
		(width 0.0889)
		(layer "In2.Cu")
		(net "P5E_CPU0_PE1_TX_DN<11>")
	)
	(segment
		(start 343.287858 -175.410114)
		(end 355.059996 -206.599282)
		(width 0.14732)
		(layer "In2.Cu")
		(net "P5E_CPU0_PE1_TX_DN<11>")
	)
	(segment
		(start 356.573836 -217.554048)
		(end 356.564946 -217.559128)
		(width 0.0889)
		(layer "In2.Cu")
		(net "P5E_CPU0_PE1_TX_DN<11>")
	)
	(segment
		(start 356.38613 -214.425276)
		(end 356.38613 -214.636858)
		(width 0.0889)
		(layer "In2.Cu")
		(net "P5E_CPU0_PE1_TX_DN<11>")
	)
	(segment
		(start 356.103682 -215.761062)
		(end 356.109778 -215.764618)
		(width 0.0889)
		(layer "In2.Cu")
		(net "P5E_CPU0_PE1_TX_DN<11>")
	)
	(segment
		(start 356.564946 -223.080834)
		(end 356.573836 -223.085914)
		(width 0.0889)
		(layer "In2.Cu")
		(net "P5E_CPU0_PE1_TX_DN<11>")
	)
	(segment
		(start 356.856284 -217.05443)
		(end 356.856284 -217.082878)
		(width 0.0889)
		(layer "In2.Cu")
		(net "P5E_CPU0_PE1_TX_DN<11>")
	)
	(arc
		(start 356.586028 -218.209876)
		(mid 356.856484 -218.692222)
		(end 356.586028 -219.174568)
		(width 0.0889)
		(layer "In2.Cu")
		(net "P5E_CPU0_PE1_TX_DN<11>")
	)
	(arc
		(start 357.043482 -220.644212)
		(mid 357.246963 -220.845016)
		(end 357.326184 -221.1197)
		(width 0.0889)
		(layer "In2.Cu")
		(net "P5E_CPU0_PE1_TX_DN<11>")
	)
	(arc
		(start 356.564946 -217.559128)
		(mid 356.437053 -217.69019)
		(end 356.386638 -217.866214)
		(width 0.0889)
		(layer "In2.Cu")
		(net "P5E_CPU0_PE1_TX_DN<11>")
	)
	(arc
		(start 356.100634 -214.093298)
		(mid 356.274781 -214.232276)
		(end 356.38613 -214.425276)
		(width 0.0889)
		(layer "In2.Cu")
		(net "P5E_CPU0_PE1_TX_DN<11>")
	)
	(arc
		(start 356.386384 -217.88501)
		(mid 356.435637 -218.06421)
		(end 356.564946 -218.197684)
		(width 0.0889)
		(layer "In2.Cu")
		(net "P5E_CPU0_PE1_TX_DN<11>")
	)
	(arc
		(start 356.386384 -222.754952)
		(mid 356.386394 -222.764352)
		(end 356.386638 -222.773748)
		(width 0.0889)
		(layer "In2.Cu")
		(net "P5E_CPU0_PE1_TX_DN<11>")
	)
	(arc
		(start 355.916484 -215.421972)
		(mid 355.916287 -215.429337)
		(end 355.91623 -215.436704)
		(width 0.0889)
		(layer "In2.Cu")
		(net "P5E_CPU0_PE1_TX_DN<11>")
	)
	(arc
		(start 356.386384 -216.257124)
		(mid 356.435637 -216.436324)
		(end 356.564946 -216.569798)
		(width 0.0889)
		(layer "In2.Cu")
		(net "P5E_CPU0_PE1_TX_DN<11>")
	)
	(arc
		(start 356.856284 -220.32849)
		(mid 356.908554 -220.510855)
		(end 357.043482 -220.644212)
		(width 0.0889)
		(layer "In2.Cu")
		(net "P5E_CPU0_PE1_TX_DN<11>")
	)
	(arc
		(start 356.109778 -215.764618)
		(mid 356.312365 -215.970969)
		(end 356.386384 -216.25052)
		(width 0.0889)
		(layer "In2.Cu")
		(net "P5E_CPU0_PE1_TX_DN<11>")
	)
	(arc
		(start 356.094792 -215.117426)
		(mid 355.967538 -215.247392)
		(end 355.916484 -215.421972)
		(width 0.0889)
		(layer "In2.Cu")
		(net "P5E_CPU0_PE1_TX_DN<11>")
	)
	(arc
		(start 356.856284 -221.957646)
		(mid 356.778173 -222.234595)
		(end 356.573836 -222.437198)
		(width 0.0889)
		(layer "In2.Cu")
		(net "P5E_CPU0_PE1_TX_DN<11>")
	)
	(arc
		(start 356.856284 -223.584262)
		(mid 356.894958 -223.74133)
		(end 356.996238 -223.867472)
		(width 0.0889)
		(layer "In2.Cu")
		(net "P5E_CPU0_PE1_TX_DN<11>")
	)
	(arc
		(start 356.38613 -214.636858)
		(mid 356.306919 -214.911426)
		(end 356.103682 -215.112346)
		(width 0.0889)
		(layer "In2.Cu")
		(net "P5E_CPU0_PE1_TX_DN<11>")
	)
	(arc
		(start 356.573836 -216.574878)
		(mid 356.778171 -216.777483)
		(end 356.856284 -217.05443)
		(width 0.0889)
		(layer "In2.Cu")
		(net "P5E_CPU0_PE1_TX_DN<11>")
	)
	(arc
		(start 355.916484 -213.893908)
		(mid 355.991489 -214.009367)
		(end 356.100634 -214.093298)
		(width 0.0889)
		(layer "In2.Cu")
		(net "P5E_CPU0_PE1_TX_DN<11>")
	)
	(arc
		(start 356.573836 -223.085914)
		(mid 356.776122 -223.284895)
		(end 356.856284 -223.557084)
		(width 0.0889)
		(layer "In2.Cu")
		(net "P5E_CPU0_PE1_TX_DN<11>")
	)
	(arc
		(start 356.573836 -219.830396)
		(mid 356.778171 -220.033001)
		(end 356.856284 -220.309948)
		(width 0.0889)
		(layer "In2.Cu")
		(net "P5E_CPU0_PE1_TX_DN<11>")
	)
	(arc
		(start 357.326184 -221.14383)
		(mid 357.248073 -221.420779)
		(end 357.043736 -221.623382)
		(width 0.0889)
		(layer "In2.Cu")
		(net "P5E_CPU0_PE1_TX_DN<11>")
	)
	(arc
		(start 356.386638 -222.773748)
		(mid 356.437131 -222.949726)
		(end 356.564946 -223.080834)
		(width 0.0889)
		(layer "In2.Cu")
		(net "P5E_CPU0_PE1_TX_DN<11>")
	)
	(arc
		(start 356.564946 -222.442278)
		(mid 356.435657 -222.575764)
		(end 356.386384 -222.754952)
		(width 0.0889)
		(layer "In2.Cu")
		(net "P5E_CPU0_PE1_TX_DN<11>")
	)
	(arc
		(start 357.034846 -221.628462)
		(mid 356.903932 -221.764822)
		(end 356.856284 -221.94774)
		(width 0.0889)
		(layer "In2.Cu")
		(net "P5E_CPU0_PE1_TX_DN<11>")
	)
	(arc
		(start 356.386638 -217.866214)
		(mid 356.386393 -217.87561)
		(end 356.386384 -217.88501)
		(width 0.0889)
		(layer "In2.Cu")
		(net "P5E_CPU0_PE1_TX_DN<11>")
	)
	(arc
		(start 356.564946 -219.18676)
		(mid 356.386349 -219.506038)
		(end 356.564946 -219.825316)
		(width 0.0889)
		(layer "In2.Cu")
		(net "P5E_CPU0_PE1_TX_DN<11>")
	)
	(arc
		(start 355.91623 -215.436704)
		(mid 355.963909 -215.619604)
		(end 356.094792 -215.755982)
		(width 0.0889)
		(layer "In2.Cu")
		(net "P5E_CPU0_PE1_TX_DN<11>")
	)
	(arc
		(start 356.856284 -217.082878)
		(mid 356.776122 -217.355067)
		(end 356.573836 -217.554048)
		(width 0.0889)
		(layer "In2.Cu")
		(net "P5E_CPU0_PE1_TX_DN<11>")
	)
	(segment
		(start 404.312628 -18.824194)
		(end 404.312628 -18.205958)
		(width 0.13208)
		(layer "F.Cu")
		(net "P5E_CPU0_PE1_TX_DN<10>")
	)
	(segment
		(start 404.011384 -19.125438)
		(end 404.312628 -18.824194)
		(width 0.13208)
		(layer "F.Cu")
		(net "P5E_CPU0_PE1_TX_DN<10>")
	)
	(segment
		(start 404.312628 -18.205958)
		(end 403.985984 -17.879314)
		(width 0.13208)
		(layer "F.Cu")
		(net "P5E_CPU0_PE1_TX_DN<10>")
	)
	(segment
		(start 357.700834 -224.925128)
		(end 357.700834 -224.389442)
		(width 0.13208)
		(layer "F.Cu")
		(net "P5E_CPU0_PE1_TX_DN<10>")
	)
	(segment
		(start 357.70058 -224.925382)
		(end 357.700834 -224.925128)
		(width 0.13208)
		(layer "F.Cu")
		(net "P5E_CPU0_PE1_TX_DN<10>")
	)
	(segment
		(start 357.135684 -222.746062)
		(end 357.135684 -222.783654)
		(width 0.0889)
		(layer "In2.Cu")
		(net "P5E_CPU0_PE1_TX_DN<10>")
	)
	(segment
		(start 357.417878 -223.251268)
		(end 357.426768 -223.256348)
		(width 0.0889)
		(layer "In2.Cu")
		(net "P5E_CPU0_PE1_TX_DN<10>")
	)
	(segment
		(start 356.673658 -210.009486)
		(end 357.09352 -213.2711)
		(width 0.14732)
		(layer "In2.Cu")
		(net "P5E_CPU0_PE1_TX_DN<10>")
	)
	(segment
		(start 355.699822 -206.29118)
		(end 356.673658 -210.009486)
		(width 0.14732)
		(layer "In2.Cu")
		(net "P5E_CPU0_PE1_TX_DN<10>")
	)
	(segment
		(start 356.948232 -215.926162)
		(end 356.957122 -215.931242)
		(width 0.0889)
		(layer "In2.Cu")
		(net "P5E_CPU0_PE1_TX_DN<10>")
	)
	(segment
		(start 357.426768 -217.383614)
		(end 357.417878 -217.388694)
		(width 0.0889)
		(layer "In2.Cu")
		(net "P5E_CPU0_PE1_TX_DN<10>")
	)
	(segment
		(start 404.011384 -19.125438)
		(end 404.306024 -19.420078)
		(width 0.14732)
		(layer "In2.Cu")
		(net "P5E_CPU0_PE1_TX_DN<10>")
	)
	(segment
		(start 343.921334 -175.142652)
		(end 355.699822 -206.29118)
		(width 0.14732)
		(layer "In2.Cu")
		(net "P5E_CPU0_PE1_TX_DN<10>")
	)
	(segment
		(start 404.359872 -21.058378)
		(end 404.222966 -21.210524)
		(width 0.14732)
		(layer "In2.Cu")
		(net "P5E_CPU0_PE1_TX_DN<10>")
	)
	(segment
		(start 357.417878 -219.995496)
		(end 357.418894 -219.996004)
		(width 0.0889)
		(layer "In2.Cu")
		(net "P5E_CPU0_PE1_TX_DN<10>")
	)
	(segment
		(start 404.306024 -20.036028)
		(end 404.306278 -20.050506)
		(width 0.14732)
		(layer "In2.Cu")
		(net "P5E_CPU0_PE1_TX_DN<10>")
	)
	(segment
		(start 357.418894 -222.27159)
		(end 357.417878 -222.272098)
		(width 0.0889)
		(layer "In2.Cu")
		(net "P5E_CPU0_PE1_TX_DN<10>")
	)
	(segment
		(start 407.21915 -74.650092)
		(end 406.350978 -80.019906)
		(width 0.14732)
		(layer "In2.Cu")
		(net "P5E_CPU0_PE1_TX_DN<10>")
	)
	(segment
		(start 357.09352 -213.2711)
		(end 357.09352 -214.00897)
		(width 0.14732)
		(layer "In2.Cu")
		(net "P5E_CPU0_PE1_TX_DN<10>")
	)
	(segment
		(start 343.46896 -172.575982)
		(end 343.921334 -175.142652)
		(width 0.14732)
		(layer "In2.Cu")
		(net "P5E_CPU0_PE1_TX_DN<10>")
	)
	(segment
		(start 357.417878 -216.739978)
		(end 357.418894 -216.740486)
		(width 0.0889)
		(layer "In2.Cu")
		(net "P5E_CPU0_PE1_TX_DN<10>")
	)
	(segment
		(start 356.66553 -215.414606)
		(end 356.66553 -215.436704)
		(width 0.0889)
		(layer "In2.Cu")
		(net "P5E_CPU0_PE1_TX_DN<10>")
	)
	(segment
		(start 344.360754 -168.552622)
		(end 343.46896 -172.575982)
		(width 0.14732)
		(layer "In2.Cu")
		(net "P5E_CPU0_PE1_TX_DN<10>")
	)
	(segment
		(start 404.306278 -20.050506)
		(end 404.359872 -21.058378)
		(width 0.14732)
		(layer "In2.Cu")
		(net "P5E_CPU0_PE1_TX_DN<10>")
	)
	(segment
		(start 356.956614 -214.941912)
		(end 356.947724 -214.946992)
		(width 0.0889)
		(layer "In2.Cu")
		(net "P5E_CPU0_PE1_TX_DN<10>")
	)
	(segment
		(start 357.60533 -220.319854)
		(end 357.60533 -220.327474)
		(width 0.0889)
		(layer "In2.Cu")
		(net "P5E_CPU0_PE1_TX_DN<10>")
	)
	(segment
		(start 357.135684 -219.490544)
		(end 357.135684 -219.521532)
		(width 0.0889)
		(layer "In2.Cu")
		(net "P5E_CPU0_PE1_TX_DN<10>")
	)
	(segment
		(start 357.418894 -219.996004)
		(end 357.426768 -220.000576)
		(width 0.0889)
		(layer "In2.Cu")
		(net "P5E_CPU0_PE1_TX_DN<10>")
	)
	(segment
		(start 404.242524 -21.57857)
		(end 404.394924 -21.715476)
		(width 0.14732)
		(layer "In2.Cu")
		(net "P5E_CPU0_PE1_TX_DN<10>")
	)
	(segment
		(start 357.135684 -217.856308)
		(end 357.135684 -217.8939)
		(width 0.0889)
		(layer "In2.Cu")
		(net "P5E_CPU0_PE1_TX_DN<10>")
	)
	(segment
		(start 357.09352 -214.031068)
		(end 357.135176 -214.072724)
		(width 0.0889)
		(layer "In2.Cu")
		(net "P5E_CPU0_PE1_TX_DN<10>")
	)
	(segment
		(start 357.09352 -214.00897)
		(end 357.09352 -214.031068)
		(width 0.0889)
		(layer "In2.Cu")
		(net "P5E_CPU0_PE1_TX_DN<10>")
	)
	(segment
		(start 357.888032 -220.809566)
		(end 357.896922 -220.814646)
		(width 0.0889)
		(layer "In2.Cu")
		(net "P5E_CPU0_PE1_TX_DN<10>")
	)
	(segment
		(start 357.888032 -224.065084)
		(end 357.896922 -224.070164)
		(width 0.0889)
		(layer "In2.Cu")
		(net "P5E_CPU0_PE1_TX_DN<10>")
	)
	(segment
		(start 357.426768 -222.267018)
		(end 357.418894 -222.27159)
		(width 0.0889)
		(layer "In2.Cu")
		(net "P5E_CPU0_PE1_TX_DN<10>")
	)
	(segment
		(start 357.426768 -219.0115)
		(end 357.418894 -219.016072)
		(width 0.0889)
		(layer "In2.Cu")
		(net "P5E_CPU0_PE1_TX_DN<10>")
	)
	(segment
		(start 357.87584 -224.057972)
		(end 357.884222 -224.062798)
		(width 0.0889)
		(layer "In2.Cu")
		(net "P5E_CPU0_PE1_TX_DN<10>")
	)
	(segment
		(start 357.418894 -216.740486)
		(end 357.426768 -216.745058)
		(width 0.0889)
		(layer "In2.Cu")
		(net "P5E_CPU0_PE1_TX_DN<10>")
	)
	(segment
		(start 404.414482 -22.083014)
		(end 404.277576 -22.235414)
		(width 0.14732)
		(layer "In2.Cu")
		(net "P5E_CPU0_PE1_TX_DN<10>")
	)
	(segment
		(start 404.297134 -22.60346)
		(end 404.449534 -22.740366)
		(width 0.14732)
		(layer "In2.Cu")
		(net "P5E_CPU0_PE1_TX_DN<10>")
	)
	(segment
		(start 404.394924 -21.715476)
		(end 404.414482 -22.083014)
		(width 0.14732)
		(layer "In2.Cu")
		(net "P5E_CPU0_PE1_TX_DN<10>")
	)
	(segment
		(start 404.306024 -19.420078)
		(end 404.306024 -20.036028)
		(width 0.14732)
		(layer "In2.Cu")
		(net "P5E_CPU0_PE1_TX_DN<10>")
	)
	(segment
		(start 406.131014 -54.324504)
		(end 407.21915 -74.650092)
		(width 0.14732)
		(layer "In2.Cu")
		(net "P5E_CPU0_PE1_TX_DN<10>")
	)
	(segment
		(start 357.857298 -224.66046)
		(end 357.700834 -224.389442)
		(width 0.0889)
		(layer "In2.Cu")
		(net "P5E_CPU0_PE1_TX_DN<10>")
	)
	(segment
		(start 357.418894 -218.368372)
		(end 357.426768 -218.372944)
		(width 0.0889)
		(layer "In2.Cu")
		(net "P5E_CPU0_PE1_TX_DN<10>")
	)
	(segment
		(start 404.222966 -21.210524)
		(end 404.242524 -21.57857)
		(width 0.14732)
		(layer "In2.Cu")
		(net "P5E_CPU0_PE1_TX_DN<10>")
	)
	(segment
		(start 357.888032 -221.458282)
		(end 357.884222 -221.460568)
		(width 0.0889)
		(layer "In2.Cu")
		(net "P5E_CPU0_PE1_TX_DN<10>")
	)
	(segment
		(start 404.449534 -22.740366)
		(end 406.131014 -54.324504)
		(width 0.14732)
		(layer "In2.Cu")
		(net "P5E_CPU0_PE1_TX_DN<10>")
	)
	(segment
		(start 357.93553 -224.681288)
		(end 357.857298 -224.66046)
		(width 0.0889)
		(layer "In2.Cu")
		(net "P5E_CPU0_PE1_TX_DN<10>")
	)
	(segment
		(start 356.942136 -215.922606)
		(end 356.948232 -215.926162)
		(width 0.0889)
		(layer "In2.Cu")
		(net "P5E_CPU0_PE1_TX_DN<10>")
	)
	(segment
		(start 406.350978 -80.019906)
		(end 344.360754 -168.552622)
		(width 0.14732)
		(layer "In2.Cu")
		(net "P5E_CPU0_PE1_TX_DN<10>")
	)
	(segment
		(start 357.896922 -221.453202)
		(end 357.888032 -221.458282)
		(width 0.0889)
		(layer "In2.Cu")
		(net "P5E_CPU0_PE1_TX_DN<10>")
	)
	(segment
		(start 357.135176 -214.072724)
		(end 357.135176 -214.622634)
		(width 0.0889)
		(layer "In2.Cu")
		(net "P5E_CPU0_PE1_TX_DN<10>")
	)
	(segment
		(start 357.417878 -218.367864)
		(end 357.418894 -218.368372)
		(width 0.0889)
		(layer "In2.Cu")
		(net "P5E_CPU0_PE1_TX_DN<10>")
	)
	(segment
		(start 404.277576 -22.235414)
		(end 404.297134 -22.60346)
		(width 0.14732)
		(layer "In2.Cu")
		(net "P5E_CPU0_PE1_TX_DN<10>")
	)
	(segment
		(start 357.135684 -216.25052)
		(end 357.135684 -216.266014)
		(width 0.0889)
		(layer "In2.Cu")
		(net "P5E_CPU0_PE1_TX_DN<10>")
	)
	(segment
		(start 357.884222 -224.062798)
		(end 357.888032 -224.065084)
		(width 0.0889)
		(layer "In2.Cu")
		(net "P5E_CPU0_PE1_TX_DN<10>")
	)
	(segment
		(start 357.418894 -219.016072)
		(end 357.417878 -219.01658)
		(width 0.0889)
		(layer "In2.Cu")
		(net "P5E_CPU0_PE1_TX_DN<10>")
	)
	(segment
		(start 357.884222 -221.460568)
		(end 357.87584 -221.465394)
		(width 0.0889)
		(layer "In2.Cu")
		(net "P5E_CPU0_PE1_TX_DN<10>")
	)
	(arc
		(start 357.87584 -221.465394)
		(mid 357.677612 -221.671242)
		(end 357.60533 -221.94774)
		(width 0.0889)
		(layer "In2.Cu")
		(net "P5E_CPU0_PE1_TX_DN<10>")
	)
	(arc
		(start 357.135684 -217.8939)
		(mid 357.215054 -218.167634)
		(end 357.417878 -218.367864)
		(width 0.0889)
		(layer "In2.Cu")
		(net "P5E_CPU0_PE1_TX_DN<10>")
	)
	(arc
		(start 357.135684 -219.521532)
		(mid 357.215054 -219.795266)
		(end 357.417878 -219.995496)
		(width 0.0889)
		(layer "In2.Cu")
		(net "P5E_CPU0_PE1_TX_DN<10>")
	)
	(arc
		(start 357.134922 -214.637366)
		(mid 357.083868 -214.811946)
		(end 356.956614 -214.941912)
		(width 0.0889)
		(layer "In2.Cu")
		(net "P5E_CPU0_PE1_TX_DN<10>")
	)
	(arc
		(start 357.417878 -222.272098)
		(mid 357.215055 -222.472329)
		(end 357.135684 -222.746062)
		(width 0.0889)
		(layer "In2.Cu")
		(net "P5E_CPU0_PE1_TX_DN<10>")
	)
	(arc
		(start 356.66553 -215.436704)
		(mid 356.739521 -215.71627)
		(end 356.942136 -215.922606)
		(width 0.0889)
		(layer "In2.Cu")
		(net "P5E_CPU0_PE1_TX_DN<10>")
	)
	(arc
		(start 357.60533 -220.327474)
		(mid 357.682959 -220.605887)
		(end 357.888032 -220.809566)
		(width 0.0889)
		(layer "In2.Cu")
		(net "P5E_CPU0_PE1_TX_DN<10>")
	)
	(arc
		(start 357.135176 -214.622634)
		(mid 357.135124 -214.630001)
		(end 357.134922 -214.637366)
		(width 0.0889)
		(layer "In2.Cu")
		(net "P5E_CPU0_PE1_TX_DN<10>")
	)
	(arc
		(start 357.417878 -217.388694)
		(mid 357.216596 -217.586181)
		(end 357.135684 -217.856308)
		(width 0.0889)
		(layer "In2.Cu")
		(net "P5E_CPU0_PE1_TX_DN<10>")
	)
	(arc
		(start 357.896922 -220.814646)
		(mid 358.024815 -220.945708)
		(end 358.07523 -221.121732)
		(width 0.0889)
		(layer "In2.Cu")
		(net "P5E_CPU0_PE1_TX_DN<10>")
	)
	(arc
		(start 357.60533 -223.575626)
		(mid 357.677565 -223.85215)
		(end 357.87584 -224.057972)
		(width 0.0889)
		(layer "In2.Cu")
		(net "P5E_CPU0_PE1_TX_DN<10>")
	)
	(arc
		(start 356.957122 -215.931242)
		(mid 357.088036 -216.067602)
		(end 357.135684 -216.25052)
		(width 0.0889)
		(layer "In2.Cu")
		(net "P5E_CPU0_PE1_TX_DN<10>")
	)
	(arc
		(start 357.426768 -218.372944)
		(mid 357.605365 -218.692222)
		(end 357.426768 -219.0115)
		(width 0.0889)
		(layer "In2.Cu")
		(net "P5E_CPU0_PE1_TX_DN<10>")
	)
	(arc
		(start 357.60533 -221.94774)
		(mid 357.557651 -222.13064)
		(end 357.426768 -222.267018)
		(width 0.0889)
		(layer "In2.Cu")
		(net "P5E_CPU0_PE1_TX_DN<10>")
	)
	(arc
		(start 357.135684 -222.783654)
		(mid 357.216595 -223.053782)
		(end 357.417878 -223.251268)
		(width 0.0889)
		(layer "In2.Cu")
		(net "P5E_CPU0_PE1_TX_DN<10>")
	)
	(arc
		(start 357.426768 -223.256348)
		(mid 357.557682 -223.392708)
		(end 357.60533 -223.575626)
		(width 0.0889)
		(layer "In2.Cu")
		(net "P5E_CPU0_PE1_TX_DN<10>")
	)
	(arc
		(start 358.075484 -224.389442)
		(mid 358.038624 -224.551239)
		(end 357.93553 -224.681288)
		(width 0.0889)
		(layer "In2.Cu")
		(net "P5E_CPU0_PE1_TX_DN<10>")
	)
	(arc
		(start 357.135684 -216.266014)
		(mid 357.215054 -216.539748)
		(end 357.417878 -216.739978)
		(width 0.0889)
		(layer "In2.Cu")
		(net "P5E_CPU0_PE1_TX_DN<10>")
	)
	(arc
		(start 356.947724 -214.946992)
		(mid 356.746442 -215.144479)
		(end 356.66553 -215.414606)
		(width 0.0889)
		(layer "In2.Cu")
		(net "P5E_CPU0_PE1_TX_DN<10>")
	)
	(arc
		(start 357.417878 -219.01658)
		(mid 357.215055 -219.216811)
		(end 357.135684 -219.490544)
		(width 0.0889)
		(layer "In2.Cu")
		(net "P5E_CPU0_PE1_TX_DN<10>")
	)
	(arc
		(start 357.426768 -216.745058)
		(mid 357.605365 -217.064336)
		(end 357.426768 -217.383614)
		(width 0.0889)
		(layer "In2.Cu")
		(net "P5E_CPU0_PE1_TX_DN<10>")
	)
	(arc
		(start 358.075484 -221.140528)
		(mid 358.026231 -221.319728)
		(end 357.896922 -221.453202)
		(width 0.0889)
		(layer "In2.Cu")
		(net "P5E_CPU0_PE1_TX_DN<10>")
	)
	(arc
		(start 357.896922 -224.070164)
		(mid 358.027836 -224.206524)
		(end 358.075484 -224.389442)
		(width 0.0889)
		(layer "In2.Cu")
		(net "P5E_CPU0_PE1_TX_DN<10>")
	)
	(arc
		(start 358.07523 -221.121732)
		(mid 358.075475 -221.131128)
		(end 358.075484 -221.140528)
		(width 0.0889)
		(layer "In2.Cu")
		(net "P5E_CPU0_PE1_TX_DN<10>")
	)
	(arc
		(start 357.426768 -220.000576)
		(mid 357.557682 -220.136936)
		(end 357.60533 -220.319854)
		(width 0.0889)
		(layer "In2.Cu")
		(net "P5E_CPU0_PE1_TX_DN<10>")
	)
	(segment
		(start 367.09858 -224.389696)
		(end 367.098834 -224.389442)
		(width 0.13208)
		(layer "F.Cu")
		(net "P5E_CPU0_PE1_TX_DN<0>")
	)
	(segment
		(start 432.85156 -18.822162)
		(end 432.85156 -18.20799)
		(width 0.13208)
		(layer "F.Cu")
		(net "P5E_CPU0_PE1_TX_DN<0>")
	)
	(segment
		(start 432.85156 -18.20799)
		(end 433.180236 -17.879314)
		(width 0.13208)
		(layer "F.Cu")
		(net "P5E_CPU0_PE1_TX_DN<0>")
	)
	(segment
		(start 367.09858 -224.925382)
		(end 367.09858 -224.389696)
		(width 0.13208)
		(layer "F.Cu")
		(net "P5E_CPU0_PE1_TX_DN<0>")
	)
	(segment
		(start 433.154836 -19.125438)
		(end 432.85156 -18.822162)
		(width 0.13208)
		(layer "F.Cu")
		(net "P5E_CPU0_PE1_TX_DN<0>")
	)
	(segment
		(start 366.902746 -224.70872)
		(end 366.911636 -224.7138)
		(width 0.0889)
		(layer "In2.Cu")
		(net "P5E_CPU0_PE1_TX_DN<0>")
	)
	(segment
		(start 366.902746 -216.569798)
		(end 366.911636 -216.574878)
		(width 0.0889)
		(layer "In2.Cu")
		(net "P5E_CPU0_PE1_TX_DN<0>")
	)
	(segment
		(start 367.37671 -218.370404)
		(end 367.372392 -218.372944)
		(width 0.0889)
		(layer "In2.Cu")
		(net "P5E_CPU0_PE1_TX_DN<0>")
	)
	(segment
		(start 432.860196 -19.420078)
		(end 432.860196 -19.86661)
		(width 0.14732)
		(layer "In2.Cu")
		(net "P5E_CPU0_PE1_TX_DN<0>")
	)
	(segment
		(start 366.911636 -216.574878)
		(end 366.91443 -216.576402)
		(width 0.0889)
		(layer "In2.Cu")
		(net "P5E_CPU0_PE1_TX_DN<0>")
	)
	(segment
		(start 367.387378 -218.364308)
		(end 367.37671 -218.370404)
		(width 0.0889)
		(layer "In2.Cu")
		(net "P5E_CPU0_PE1_TX_DN<0>")
	)
	(segment
		(start 423.236644 -43.987466)
		(end 417.192968 -80.99933)
		(width 0.14732)
		(layer "In2.Cu")
		(net "P5E_CPU0_PE1_TX_DN<0>")
	)
	(segment
		(start 366.902746 -219.825316)
		(end 366.911636 -219.830396)
		(width 0.0889)
		(layer "In2.Cu")
		(net "P5E_CPU0_PE1_TX_DN<0>")
	)
	(segment
		(start 366.911636 -215.926162)
		(end 366.902746 -215.931242)
		(width 0.0889)
		(layer "In2.Cu")
		(net "P5E_CPU0_PE1_TX_DN<0>")
	)
	(segment
		(start 367.342674 -212.19541)
		(end 367.342674 -213.091776)
		(width 0.14732)
		(layer "In2.Cu")
		(net "P5E_CPU0_PE1_TX_DN<0>")
	)
	(segment
		(start 367.30051 -213.388702)
		(end 367.19383 -213.646004)
		(width 0.0889)
		(layer "In2.Cu")
		(net "P5E_CPU0_PE1_TX_DN<0>")
	)
	(segment
		(start 432.412394 -20.822412)
		(end 432.160426 -21.091652)
		(width 0.14732)
		(layer "In2.Cu")
		(net "P5E_CPU0_PE1_TX_DN<0>")
	)
	(segment
		(start 367.19383 -213.646004)
		(end 367.19383 -215.452198)
		(width 0.0889)
		(layer "In2.Cu")
		(net "P5E_CPU0_PE1_TX_DN<0>")
	)
	(segment
		(start 417.047426 -81.335626)
		(end 378.635006 -146.15033)
		(width 0.14732)
		(layer "In2.Cu")
		(net "P5E_CPU0_PE1_TX_DN<0>")
	)
	(segment
		(start 378.568712 -146.260566)
		(end 378.568204 -146.261074)
		(width 0.14732)
		(layer "In2.Cu")
		(net "P5E_CPU0_PE1_TX_DN<0>")
	)
	(segment
		(start 426.664628 -26.750518)
		(end 425.449238 -28.486354)
		(width 0.14732)
		(layer "In2.Cu")
		(net "P5E_CPU0_PE1_TX_DN<0>")
	)
	(segment
		(start 366.911636 -219.830396)
		(end 366.91443 -219.83192)
		(width 0.0889)
		(layer "In2.Cu")
		(net "P5E_CPU0_PE1_TX_DN<0>")
	)
	(segment
		(start 367.663984 -221.115382)
		(end 367.663984 -221.14383)
		(width 0.0889)
		(layer "In2.Cu")
		(net "P5E_CPU0_PE1_TX_DN<0>")
	)
	(segment
		(start 430.852834 -22.276562)
		(end 430.859692 -22.481032)
		(width 0.14732)
		(layer "In2.Cu")
		(net "P5E_CPU0_PE1_TX_DN<0>")
	)
	(segment
		(start 367.372646 -220.639132)
		(end 367.381536 -220.644212)
		(width 0.0889)
		(layer "In2.Cu")
		(net "P5E_CPU0_PE1_TX_DN<0>")
	)
	(segment
		(start 432.679348 -20.325334)
		(end 432.405536 -20.617688)
		(width 0.14732)
		(layer "In2.Cu")
		(net "P5E_CPU0_PE1_TX_DN<0>")
	)
	(segment
		(start 417.071556 -81.322926)
		(end 417.047426 -81.335626)
		(width 0.14732)
		(layer "In2.Cu")
		(net "P5E_CPU0_PE1_TX_DN<0>")
	)
	(segment
		(start 378.569982 -146.260058)
		(end 378.568712 -146.260566)
		(width 0.14732)
		(layer "In2.Cu")
		(net "P5E_CPU0_PE1_TX_DN<0>")
	)
	(segment
		(start 367.19383 -218.692222)
		(end 367.19383 -218.707716)
		(width 0.0889)
		(layer "In2.Cu")
		(net "P5E_CPU0_PE1_TX_DN<0>")
	)
	(segment
		(start 430.607724 -22.750272)
		(end 430.403 -22.756876)
		(width 0.14732)
		(layer "In2.Cu")
		(net "P5E_CPU0_PE1_TX_DN<0>")
	)
	(segment
		(start 378.634498 -146.151092)
		(end 378.569982 -146.260058)
		(width 0.14732)
		(layer "In2.Cu")
		(net "P5E_CPU0_PE1_TX_DN<0>")
	)
	(segment
		(start 431.401982 -21.901658)
		(end 431.197512 -21.908516)
		(width 0.14732)
		(layer "In2.Cu")
		(net "P5E_CPU0_PE1_TX_DN<0>")
	)
	(segment
		(start 367.234216 -224.738438)
		(end 367.255298 -224.66046)
		(width 0.0889)
		(layer "In2.Cu")
		(net "P5E_CPU0_PE1_TX_DN<0>")
	)
	(segment
		(start 367.342674 -213.091776)
		(end 367.342674 -213.113874)
		(width 0.0889)
		(layer "In2.Cu")
		(net "P5E_CPU0_PE1_TX_DN<0>")
	)
	(segment
		(start 367.194084 -223.561402)
		(end 367.194084 -223.575626)
		(width 0.0889)
		(layer "In2.Cu")
		(net "P5E_CPU0_PE1_TX_DN<0>")
	)
	(segment
		(start 366.90554 -224.06864)
		(end 366.903762 -224.069656)
		(width 0.0889)
		(layer "In2.Cu")
		(net "P5E_CPU0_PE1_TX_DN<0>")
	)
	(segment
		(start 378.635006 -146.15033)
		(end 378.634498 -146.151092)
		(width 0.14732)
		(layer "In2.Cu")
		(net "P5E_CPU0_PE1_TX_DN<0>")
	)
	(segment
		(start 367.381536 -221.623382)
		(end 367.372646 -221.628462)
		(width 0.0889)
		(layer "In2.Cu")
		(net "P5E_CPU0_PE1_TX_DN<0>")
	)
	(segment
		(start 366.903762 -224.069656)
		(end 366.902746 -224.070164)
		(width 0.0889)
		(layer "In2.Cu")
		(net "P5E_CPU0_PE1_TX_DN<0>")
	)
	(segment
		(start 430.403 -22.756876)
		(end 426.664628 -26.750518)
		(width 0.14732)
		(layer "In2.Cu")
		(net "P5E_CPU0_PE1_TX_DN<0>")
	)
	(segment
		(start 378.568204 -146.261074)
		(end 378.568458 -146.261074)
		(width 0.14732)
		(layer "In2.Cu")
		(net "P5E_CPU0_PE1_TX_DN<0>")
	)
	(segment
		(start 366.915954 -219.832936)
		(end 366.917732 -219.833952)
		(width 0.0889)
		(layer "In2.Cu")
		(net "P5E_CPU0_PE1_TX_DN<0>")
	)
	(segment
		(start 378.568458 -146.261074)
		(end 369.056158 -162.31235)
		(width 0.14732)
		(layer "In2.Cu")
		(net "P5E_CPU0_PE1_TX_DN<0>")
	)
	(segment
		(start 425.449238 -28.486354)
		(end 423.236644 -43.987466)
		(width 0.14732)
		(layer "In2.Cu")
		(net "P5E_CPU0_PE1_TX_DN<0>")
	)
	(segment
		(start 432.860196 -19.86661)
		(end 432.679348 -20.325334)
		(width 0.14732)
		(layer "In2.Cu")
		(net "P5E_CPU0_PE1_TX_DN<0>")
	)
	(segment
		(start 431.65395 -21.632672)
		(end 431.401982 -21.901658)
		(width 0.14732)
		(layer "In2.Cu")
		(net "P5E_CPU0_PE1_TX_DN<0>")
	)
	(segment
		(start 432.405536 -20.617688)
		(end 432.412394 -20.822412)
		(width 0.14732)
		(layer "In2.Cu")
		(net "P5E_CPU0_PE1_TX_DN<0>")
	)
	(segment
		(start 366.902746 -223.080834)
		(end 366.911636 -223.085914)
		(width 0.0889)
		(layer "In2.Cu")
		(net "P5E_CPU0_PE1_TX_DN<0>")
	)
	(segment
		(start 430.859692 -22.481032)
		(end 430.607724 -22.750272)
		(width 0.14732)
		(layer "In2.Cu")
		(net "P5E_CPU0_PE1_TX_DN<0>")
	)
	(segment
		(start 366.911636 -219.18168)
		(end 366.902746 -219.18676)
		(width 0.0889)
		(layer "In2.Cu")
		(net "P5E_CPU0_PE1_TX_DN<0>")
	)
	(segment
		(start 366.917732 -224.061528)
		(end 366.90554 -224.06864)
		(width 0.0889)
		(layer "In2.Cu")
		(net "P5E_CPU0_PE1_TX_DN<0>")
	)
	(segment
		(start 431.197512 -21.908516)
		(end 430.852834 -22.276562)
		(width 0.14732)
		(layer "In2.Cu")
		(net "P5E_CPU0_PE1_TX_DN<0>")
	)
	(segment
		(start 417.110926 -81.223866)
		(end 417.071556 -81.322926)
		(width 0.14732)
		(layer "In2.Cu")
		(net "P5E_CPU0_PE1_TX_DN<0>")
	)
	(segment
		(start 367.372646 -217.383614)
		(end 367.381536 -217.388694)
		(width 0.0889)
		(layer "In2.Cu")
		(net "P5E_CPU0_PE1_TX_DN<0>")
	)
	(segment
		(start 367.663984 -217.859864)
		(end 367.663984 -217.878406)
		(width 0.0889)
		(layer "In2.Cu")
		(net "P5E_CPU0_PE1_TX_DN<0>")
	)
	(segment
		(start 367.30051 -213.156038)
		(end 367.30051 -213.388702)
		(width 0.0889)
		(layer "In2.Cu")
		(net "P5E_CPU0_PE1_TX_DN<0>")
	)
	(segment
		(start 433.154836 -19.125438)
		(end 432.860196 -19.420078)
		(width 0.14732)
		(layer "In2.Cu")
		(net "P5E_CPU0_PE1_TX_DN<0>")
	)
	(segment
		(start 366.91443 -219.83192)
		(end 366.915954 -219.832936)
		(width 0.0889)
		(layer "In2.Cu")
		(net "P5E_CPU0_PE1_TX_DN<0>")
	)
	(segment
		(start 366.915954 -216.577418)
		(end 366.917732 -216.578434)
		(width 0.0889)
		(layer "In2.Cu")
		(net "P5E_CPU0_PE1_TX_DN<0>")
	)
	(segment
		(start 367.255298 -224.66046)
		(end 367.098834 -224.389442)
		(width 0.0889)
		(layer "In2.Cu")
		(net "P5E_CPU0_PE1_TX_DN<0>")
	)
	(segment
		(start 366.917732 -222.433642)
		(end 366.911636 -222.437198)
		(width 0.0889)
		(layer "In2.Cu")
		(net "P5E_CPU0_PE1_TX_DN<0>")
	)
	(segment
		(start 366.911636 -222.437198)
		(end 366.902746 -222.442278)
		(width 0.0889)
		(layer "In2.Cu")
		(net "P5E_CPU0_PE1_TX_DN<0>")
	)
	(segment
		(start 369.056158 -162.31235)
		(end 367.342674 -212.19541)
		(width 0.14732)
		(layer "In2.Cu")
		(net "P5E_CPU0_PE1_TX_DN<0>")
	)
	(segment
		(start 431.955956 -21.098256)
		(end 431.647346 -21.427948)
		(width 0.14732)
		(layer "In2.Cu")
		(net "P5E_CPU0_PE1_TX_DN<0>")
	)
	(segment
		(start 432.160426 -21.091652)
		(end 431.955956 -21.098256)
		(width 0.14732)
		(layer "In2.Cu")
		(net "P5E_CPU0_PE1_TX_DN<0>")
	)
	(segment
		(start 366.91443 -216.576402)
		(end 366.915954 -216.577418)
		(width 0.0889)
		(layer "In2.Cu")
		(net "P5E_CPU0_PE1_TX_DN<0>")
	)
	(segment
		(start 417.192968 -80.99933)
		(end 417.110926 -81.223866)
		(width 0.14732)
		(layer "In2.Cu")
		(net "P5E_CPU0_PE1_TX_DN<0>")
	)
	(segment
		(start 367.342674 -213.113874)
		(end 367.30051 -213.156038)
		(width 0.0889)
		(layer "In2.Cu")
		(net "P5E_CPU0_PE1_TX_DN<0>")
	)
	(segment
		(start 431.647346 -21.427948)
		(end 431.65395 -21.632672)
		(width 0.14732)
		(layer "In2.Cu")
		(net "P5E_CPU0_PE1_TX_DN<0>")
	)
	(arc
		(start 366.902746 -215.931242)
		(mid 366.72427 -216.25052)
		(end 366.902746 -216.569798)
		(width 0.0889)
		(layer "In2.Cu")
		(net "P5E_CPU0_PE1_TX_DN<0>")
	)
	(arc
		(start 367.194084 -217.064336)
		(mid 367.241763 -217.247236)
		(end 367.372646 -217.383614)
		(width 0.0889)
		(layer "In2.Cu")
		(net "P5E_CPU0_PE1_TX_DN<0>")
	)
	(arc
		(start 367.381536 -220.644212)
		(mid 367.583822 -220.843193)
		(end 367.663984 -221.115382)
		(width 0.0889)
		(layer "In2.Cu")
		(net "P5E_CPU0_PE1_TX_DN<0>")
	)
	(arc
		(start 367.372646 -221.628462)
		(mid 367.241732 -221.764822)
		(end 367.194084 -221.94774)
		(width 0.0889)
		(layer "In2.Cu")
		(net "P5E_CPU0_PE1_TX_DN<0>")
	)
	(arc
		(start 366.902746 -224.070164)
		(mid 366.72427 -224.389442)
		(end 366.902746 -224.70872)
		(width 0.0889)
		(layer "In2.Cu")
		(net "P5E_CPU0_PE1_TX_DN<0>")
	)
	(arc
		(start 366.911636 -224.7138)
		(mid 367.070124 -224.762733)
		(end 367.234216 -224.738438)
		(width 0.0889)
		(layer "In2.Cu")
		(net "P5E_CPU0_PE1_TX_DN<0>")
	)
	(arc
		(start 367.372392 -218.372944)
		(mid 367.241478 -218.509304)
		(end 367.19383 -218.692222)
		(width 0.0889)
		(layer "In2.Cu")
		(net "P5E_CPU0_PE1_TX_DN<0>")
	)
	(arc
		(start 367.19383 -218.707716)
		(mid 367.11446 -218.98145)
		(end 366.911636 -219.18168)
		(width 0.0889)
		(layer "In2.Cu")
		(net "P5E_CPU0_PE1_TX_DN<0>")
	)
	(arc
		(start 366.917732 -219.833952)
		(mid 367.120145 -220.040365)
		(end 367.194084 -220.319854)
		(width 0.0889)
		(layer "In2.Cu")
		(net "P5E_CPU0_PE1_TX_DN<0>")
	)
	(arc
		(start 367.194084 -221.94774)
		(mid 367.120168 -222.227242)
		(end 366.917732 -222.433642)
		(width 0.0889)
		(layer "In2.Cu")
		(net "P5E_CPU0_PE1_TX_DN<0>")
	)
	(arc
		(start 366.917732 -216.578434)
		(mid 367.120145 -216.784847)
		(end 367.194084 -217.064336)
		(width 0.0889)
		(layer "In2.Cu")
		(net "P5E_CPU0_PE1_TX_DN<0>")
	)
	(arc
		(start 367.194084 -220.319854)
		(mid 367.241763 -220.502754)
		(end 367.372646 -220.639132)
		(width 0.0889)
		(layer "In2.Cu")
		(net "P5E_CPU0_PE1_TX_DN<0>")
	)
	(arc
		(start 367.19383 -215.452198)
		(mid 367.11446 -215.725932)
		(end 366.911636 -215.926162)
		(width 0.0889)
		(layer "In2.Cu")
		(net "P5E_CPU0_PE1_TX_DN<0>")
	)
	(arc
		(start 367.663984 -221.14383)
		(mid 367.585873 -221.420779)
		(end 367.381536 -221.623382)
		(width 0.0889)
		(layer "In2.Cu")
		(net "P5E_CPU0_PE1_TX_DN<0>")
	)
	(arc
		(start 366.902746 -222.442278)
		(mid 366.771832 -222.578638)
		(end 366.724184 -222.761556)
		(width 0.0889)
		(layer "In2.Cu")
		(net "P5E_CPU0_PE1_TX_DN<0>")
	)
	(arc
		(start 366.902746 -219.18676)
		(mid 366.72427 -219.506038)
		(end 366.902746 -219.825316)
		(width 0.0889)
		(layer "In2.Cu")
		(net "P5E_CPU0_PE1_TX_DN<0>")
	)
	(arc
		(start 366.911636 -223.085914)
		(mid 367.114941 -223.28678)
		(end 367.194084 -223.561402)
		(width 0.0889)
		(layer "In2.Cu")
		(net "P5E_CPU0_PE1_TX_DN<0>")
	)
	(arc
		(start 367.663984 -217.878406)
		(mid 367.589993 -218.157972)
		(end 367.387378 -218.364308)
		(width 0.0889)
		(layer "In2.Cu")
		(net "P5E_CPU0_PE1_TX_DN<0>")
	)
	(arc
		(start 367.381536 -217.388694)
		(mid 367.583822 -217.587675)
		(end 367.663984 -217.859864)
		(width 0.0889)
		(layer "In2.Cu")
		(net "P5E_CPU0_PE1_TX_DN<0>")
	)
	(arc
		(start 366.724438 -222.776288)
		(mid 366.775492 -222.950868)
		(end 366.902746 -223.080834)
		(width 0.0889)
		(layer "In2.Cu")
		(net "P5E_CPU0_PE1_TX_DN<0>")
	)
	(arc
		(start 366.724184 -222.761556)
		(mid 366.724236 -222.768923)
		(end 366.724438 -222.776288)
		(width 0.0889)
		(layer "In2.Cu")
		(net "P5E_CPU0_PE1_TX_DN<0>")
	)
	(arc
		(start 367.194084 -223.575626)
		(mid 367.120168 -223.855128)
		(end 366.917732 -224.061528)
		(width 0.0889)
		(layer "In2.Cu")
		(net "P5E_CPU0_PE1_TX_DN<0>")
	)
	(segment
		(start 404.626064 -12.005564)
		(end 404.628604 -12.008104)
		(width 0.13208)
		(layer "F.Cu")
		(net "P5E_CPU0_PE1_TX_C_DP<9>")
	)
	(segment
		(start 404.446994 -11.799062)
		(end 404.626064 -11.978132)
		(width 0.13208)
		(layer "F.Cu")
		(net "P5E_CPU0_PE1_TX_C_DP<9>")
	)
	(segment
		(start 404.626064 -11.978132)
		(end 404.626064 -12.005564)
		(width 0.13208)
		(layer "F.Cu")
		(net "P5E_CPU0_PE1_TX_C_DP<9>")
	)
	(segment
		(start 407.110184 -15.491714)
		(end 406.779984 -15.821914)
		(width 0.13208)
		(layer "F.Cu")
		(net "P5E_CPU0_PE1_TX_C_DP<9>")
	)
	(segment
		(start 404.628604 -12.809474)
		(end 407.110184 -15.291054)
		(width 0.13208)
		(layer "F.Cu")
		(net "P5E_CPU0_PE1_TX_C_DP<9>")
	)
	(segment
		(start 404.446994 -11.26998)
		(end 404.446994 -11.799062)
		(width 0.13208)
		(layer "F.Cu")
		(net "P5E_CPU0_PE1_TX_C_DP<9>")
	)
	(segment
		(start 407.110184 -15.291054)
		(end 407.110184 -15.491714)
		(width 0.13208)
		(layer "F.Cu")
		(net "P5E_CPU0_PE1_TX_C_DP<9>")
	)
	(segment
		(start 404.628604 -12.008104)
		(end 404.628604 -12.809474)
		(width 0.13208)
		(layer "F.Cu")
		(net "P5E_CPU0_PE1_TX_C_DP<9>")
	)
	(segment
		(start 406.846786 -11.26998)
		(end 406.846786 -11.842242)
		(width 0.13208)
		(layer "F.Cu")
		(net "P5E_CPU0_PE1_TX_C_DP<8>")
	)
	(segment
		(start 406.687528 -12.464796)
		(end 410.163264 -15.940532)
		(width 0.13208)
		(layer "F.Cu")
		(net "P5E_CPU0_PE1_TX_C_DP<8>")
	)
	(segment
		(start 406.687528 -12.0015)
		(end 406.687528 -12.464796)
		(width 0.13208)
		(layer "F.Cu")
		(net "P5E_CPU0_PE1_TX_C_DP<8>")
	)
	(segment
		(start 406.846786 -11.842242)
		(end 406.687528 -12.0015)
		(width 0.13208)
		(layer "F.Cu")
		(net "P5E_CPU0_PE1_TX_C_DP<8>")
	)
	(segment
		(start 410.163264 -17.020794)
		(end 410.488384 -17.345914)
		(width 0.13208)
		(layer "F.Cu")
		(net "P5E_CPU0_PE1_TX_C_DP<8>")
	)
	(segment
		(start 410.163264 -15.940532)
		(end 410.163264 -17.020794)
		(width 0.13208)
		(layer "F.Cu")
		(net "P5E_CPU0_PE1_TX_C_DP<8>")
	)
	(segment
		(start 412.698184 -14.473682)
		(end 412.698184 -15.491714)
		(width 0.13208)
		(layer "F.Cu")
		(net "P5E_CPU0_PE1_TX_C_DP<7>")
	)
	(segment
		(start 413.556958 -11.26998)
		(end 413.556958 -11.799062)
		(width 0.13208)
		(layer "F.Cu")
		(net "P5E_CPU0_PE1_TX_C_DP<7>")
	)
	(segment
		(start 413.556958 -11.799062)
		(end 413.738568 -11.980672)
		(width 0.13208)
		(layer "F.Cu")
		(net "P5E_CPU0_PE1_TX_C_DP<7>")
	)
	(segment
		(start 412.698184 -15.491714)
		(end 412.367984 -15.821914)
		(width 0.13208)
		(layer "F.Cu")
		(net "P5E_CPU0_PE1_TX_C_DP<7>")
	)
	(segment
		(start 413.738568 -11.980672)
		(end 413.738568 -13.433298)
		(width 0.13208)
		(layer "F.Cu")
		(net "P5E_CPU0_PE1_TX_C_DP<7>")
	)
	(segment
		(start 413.738568 -13.433298)
		(end 412.698184 -14.473682)
		(width 0.13208)
		(layer "F.Cu")
		(net "P5E_CPU0_PE1_TX_C_DP<7>")
	)
	(segment
		(start 416.05454 -14.32306)
		(end 416.05454 -17.018254)
		(width 0.13208)
		(layer "F.Cu")
		(net "P5E_CPU0_PE1_TX_C_DP<6>")
	)
	(segment
		(start 415.794952 -11.984736)
		(end 415.794952 -14.063472)
		(width 0.13208)
		(layer "F.Cu")
		(net "P5E_CPU0_PE1_TX_C_DP<6>")
	)
	(segment
		(start 416.05454 -17.018254)
		(end 416.3822 -17.345914)
		(width 0.13208)
		(layer "F.Cu")
		(net "P5E_CPU0_PE1_TX_C_DP<6>")
	)
	(segment
		(start 415.95675 -11.822938)
		(end 415.794952 -11.984736)
		(width 0.13208)
		(layer "F.Cu")
		(net "P5E_CPU0_PE1_TX_C_DP<6>")
	)
	(segment
		(start 415.794952 -14.063472)
		(end 416.05454 -14.32306)
		(width 0.13208)
		(layer "F.Cu")
		(net "P5E_CPU0_PE1_TX_C_DP<6>")
	)
	(segment
		(start 415.95675 -11.26998)
		(end 415.95675 -11.822938)
		(width 0.13208)
		(layer "F.Cu")
		(net "P5E_CPU0_PE1_TX_C_DP<6>")
	)
	(segment
		(start 417.1569 -11.799062)
		(end 417.33851 -11.980672)
		(width 0.13208)
		(layer "F.Cu")
		(net "P5E_CPU0_PE1_TX_C_DP<5>")
	)
	(segment
		(start 417.1569 -11.26998)
		(end 417.1569 -11.799062)
		(width 0.13208)
		(layer "F.Cu")
		(net "P5E_CPU0_PE1_TX_C_DP<5>")
	)
	(segment
		(start 418.592 -15.491714)
		(end 418.2618 -15.821914)
		(width 0.13208)
		(layer "F.Cu")
		(net "P5E_CPU0_PE1_TX_C_DP<5>")
	)
	(segment
		(start 417.33851 -13.7414)
		(end 418.592 -14.99489)
		(width 0.13208)
		(layer "F.Cu")
		(net "P5E_CPU0_PE1_TX_C_DP<5>")
	)
	(segment
		(start 417.33851 -11.980672)
		(end 417.33851 -13.7414)
		(width 0.13208)
		(layer "F.Cu")
		(net "P5E_CPU0_PE1_TX_C_DP<5>")
	)
	(segment
		(start 418.592 -14.99489)
		(end 418.592 -15.491714)
		(width 0.13208)
		(layer "F.Cu")
		(net "P5E_CPU0_PE1_TX_C_DP<5>")
	)
	(segment
		(start 419.397688 -11.976354)
		(end 419.397688 -12.756896)
		(width 0.13208)
		(layer "F.Cu")
		(net "P5E_CPU0_PE1_TX_C_DP<4>")
	)
	(segment
		(start 419.397688 -12.756896)
		(end 421.64508 -15.004288)
		(width 0.13208)
		(layer "F.Cu")
		(net "P5E_CPU0_PE1_TX_C_DP<4>")
	)
	(segment
		(start 421.64508 -17.020794)
		(end 421.9702 -17.345914)
		(width 0.13208)
		(layer "F.Cu")
		(net "P5E_CPU0_PE1_TX_C_DP<4>")
	)
	(segment
		(start 421.64508 -15.004288)
		(end 421.64508 -17.020794)
		(width 0.13208)
		(layer "F.Cu")
		(net "P5E_CPU0_PE1_TX_C_DP<4>")
	)
	(segment
		(start 419.556946 -11.26998)
		(end 419.556946 -11.817096)
		(width 0.13208)
		(layer "F.Cu")
		(net "P5E_CPU0_PE1_TX_C_DP<4>")
	)
	(segment
		(start 419.556946 -11.817096)
		(end 419.397688 -11.976354)
		(width 0.13208)
		(layer "F.Cu")
		(net "P5E_CPU0_PE1_TX_C_DP<4>")
	)
	(segment
		(start 424.766994 -11.799062)
		(end 424.946064 -11.978132)
		(width 0.13208)
		(layer "F.Cu")
		(net "P5E_CPU0_PE1_TX_C_DP<3>")
	)
	(segment
		(start 424.17746 -15.494254)
		(end 423.8498 -15.821914)
		(width 0.13208)
		(layer "F.Cu")
		(net "P5E_CPU0_PE1_TX_C_DP<3>")
	)
	(segment
		(start 424.946064 -11.978132)
		(end 424.946064 -13.623798)
		(width 0.13208)
		(layer "F.Cu")
		(net "P5E_CPU0_PE1_TX_C_DP<3>")
	)
	(segment
		(start 424.17746 -14.392402)
		(end 424.17746 -15.494254)
		(width 0.13208)
		(layer "F.Cu")
		(net "P5E_CPU0_PE1_TX_C_DP<3>")
	)
	(segment
		(start 424.946064 -13.623798)
		(end 424.17746 -14.392402)
		(width 0.13208)
		(layer "F.Cu")
		(net "P5E_CPU0_PE1_TX_C_DP<3>")
	)
	(segment
		(start 424.766994 -11.26998)
		(end 424.766994 -11.799062)
		(width 0.13208)
		(layer "F.Cu")
		(net "P5E_CPU0_PE1_TX_C_DP<3>")
	)
	(segment
		(start 427.166786 -11.81862)
		(end 427.004988 -11.980418)
		(width 0.13208)
		(layer "F.Cu")
		(net "P5E_CPU0_PE1_TX_C_DP<2>")
	)
	(segment
		(start 427.004988 -11.980418)
		(end 427.004988 -14.036548)
		(width 0.13208)
		(layer "F.Cu")
		(net "P5E_CPU0_PE1_TX_C_DP<2>")
	)
	(segment
		(start 427.166786 -11.26998)
		(end 427.166786 -11.81862)
		(width 0.13208)
		(layer "F.Cu")
		(net "P5E_CPU0_PE1_TX_C_DP<2>")
	)
	(segment
		(start 427.264576 -14.296136)
		(end 427.264576 -17.018254)
		(width 0.13208)
		(layer "F.Cu")
		(net "P5E_CPU0_PE1_TX_C_DP<2>")
	)
	(segment
		(start 427.004988 -14.036548)
		(end 427.264576 -14.296136)
		(width 0.13208)
		(layer "F.Cu")
		(net "P5E_CPU0_PE1_TX_C_DP<2>")
	)
	(segment
		(start 427.264576 -17.018254)
		(end 427.592236 -17.345914)
		(width 0.13208)
		(layer "F.Cu")
		(net "P5E_CPU0_PE1_TX_C_DP<2>")
	)
	(segment
		(start 428.366936 -11.799062)
		(end 428.548546 -11.980672)
		(width 0.13208)
		(layer "F.Cu")
		(net "P5E_CPU0_PE1_TX_C_DP<1>")
	)
	(segment
		(start 428.548546 -13.775436)
		(end 429.802036 -15.028926)
		(width 0.13208)
		(layer "F.Cu")
		(net "P5E_CPU0_PE1_TX_C_DP<1>")
	)
	(segment
		(start 428.548546 -11.980672)
		(end 428.548546 -13.775436)
		(width 0.13208)
		(layer "F.Cu")
		(net "P5E_CPU0_PE1_TX_C_DP<1>")
	)
	(segment
		(start 428.366936 -11.26998)
		(end 428.366936 -11.799062)
		(width 0.13208)
		(layer "F.Cu")
		(net "P5E_CPU0_PE1_TX_C_DP<1>")
	)
	(segment
		(start 429.802036 -15.491714)
		(end 429.471836 -15.821914)
		(width 0.13208)
		(layer "F.Cu")
		(net "P5E_CPU0_PE1_TX_C_DP<1>")
	)
	(segment
		(start 429.802036 -15.028926)
		(end 429.802036 -15.491714)
		(width 0.13208)
		(layer "F.Cu")
		(net "P5E_CPU0_PE1_TX_C_DP<1>")
	)
	(segment
		(start 393.646914 -11.26998)
		(end 393.646914 -11.799062)
		(width 0.13208)
		(layer "F.Cu")
		(net "P5E_CPU0_PE1_TX_C_DP<15>")
	)
	(segment
		(start 390.474454 -15.013178)
		(end 390.343644 -15.257526)
		(width 0.13208)
		(layer "F.Cu")
		(net "P5E_CPU0_PE1_TX_C_DP<15>")
	)
	(segment
		(start 393.825984 -12.411964)
		(end 392.995912 -13.327888)
		(width 0.13208)
		(layer "F.Cu")
		(net "P5E_CPU0_PE1_TX_C_DP<15>")
	)
	(segment
		(start 392.995912 -13.327888)
		(end 390.474454 -15.013178)
		(width 0.13208)
		(layer "F.Cu")
		(net "P5E_CPU0_PE1_TX_C_DP<15>")
	)
	(segment
		(start 393.825984 -11.978132)
		(end 393.825984 -12.411964)
		(width 0.13208)
		(layer "F.Cu")
		(net "P5E_CPU0_PE1_TX_C_DP<15>")
	)
	(segment
		(start 390.343644 -15.494254)
		(end 390.015984 -15.821914)
		(width 0.13208)
		(layer "F.Cu")
		(net "P5E_CPU0_PE1_TX_C_DP<15>")
	)
	(segment
		(start 393.646914 -11.799062)
		(end 393.825984 -11.978132)
		(width 0.13208)
		(layer "F.Cu")
		(net "P5E_CPU0_PE1_TX_C_DP<15>")
	)
	(segment
		(start 390.343644 -15.257526)
		(end 390.343644 -15.494254)
		(width 0.13208)
		(layer "F.Cu")
		(net "P5E_CPU0_PE1_TX_C_DP<15>")
	)
	(segment
		(start 393.396724 -15.33398)
		(end 393.396724 -17.018254)
		(width 0.13208)
		(layer "F.Cu")
		(net "P5E_CPU0_PE1_TX_C_DP<14>")
	)
	(segment
		(start 393.396724 -17.018254)
		(end 393.724384 -17.345914)
		(width 0.13208)
		(layer "F.Cu")
		(net "P5E_CPU0_PE1_TX_C_DP<14>")
	)
	(segment
		(start 396.04696 -11.834368)
		(end 395.884908 -11.99642)
		(width 0.13208)
		(layer "F.Cu")
		(net "P5E_CPU0_PE1_TX_C_DP<14>")
	)
	(segment
		(start 396.04696 -11.26998)
		(end 396.04696 -11.834368)
		(width 0.13208)
		(layer "F.Cu")
		(net "P5E_CPU0_PE1_TX_C_DP<14>")
	)
	(segment
		(start 395.884908 -11.99642)
		(end 395.884908 -12.845796)
		(width 0.13208)
		(layer "F.Cu")
		(net "P5E_CPU0_PE1_TX_C_DP<14>")
	)
	(segment
		(start 395.884908 -12.845796)
		(end 393.396724 -15.33398)
		(width 0.13208)
		(layer "F.Cu")
		(net "P5E_CPU0_PE1_TX_C_DP<14>")
	)
	(segment
		(start 397.246856 -11.799062)
		(end 397.425926 -11.978132)
		(width 0.13208)
		(layer "F.Cu")
		(net "P5E_CPU0_PE1_TX_C_DP<13>")
	)
	(segment
		(start 397.425926 -11.978132)
		(end 397.425926 -13.112496)
		(width 0.13208)
		(layer "F.Cu")
		(net "P5E_CPU0_PE1_TX_C_DP<13>")
	)
	(segment
		(start 397.425926 -13.112496)
		(end 395.931644 -14.606778)
		(width 0.13208)
		(layer "F.Cu")
		(net "P5E_CPU0_PE1_TX_C_DP<13>")
	)
	(segment
		(start 395.931644 -15.494254)
		(end 395.603984 -15.821914)
		(width 0.13208)
		(layer "F.Cu")
		(net "P5E_CPU0_PE1_TX_C_DP<13>")
	)
	(segment
		(start 397.246856 -11.26998)
		(end 397.246856 -11.799062)
		(width 0.13208)
		(layer "F.Cu")
		(net "P5E_CPU0_PE1_TX_C_DP<13>")
	)
	(segment
		(start 395.931644 -14.606778)
		(end 395.931644 -15.494254)
		(width 0.13208)
		(layer "F.Cu")
		(net "P5E_CPU0_PE1_TX_C_DP<13>")
	)
	(segment
		(start 398.984724 -14.091412)
		(end 398.984724 -17.018254)
		(width 0.13208)
		(layer "F.Cu")
		(net "P5E_CPU0_PE1_TX_C_DP<12>")
	)
	(segment
		(start 399.485104 -11.978132)
		(end 399.485104 -13.591032)
		(width 0.13208)
		(layer "F.Cu")
		(net "P5E_CPU0_PE1_TX_C_DP<12>")
	)
	(segment
		(start 399.487644 -11.967464)
		(end 399.487644 -11.975592)
		(width 0.13208)
		(layer "F.Cu")
		(net "P5E_CPU0_PE1_TX_C_DP<12>")
	)
	(segment
		(start 399.646902 -11.26998)
		(end 399.646902 -11.808206)
		(width 0.13208)
		(layer "F.Cu")
		(net "P5E_CPU0_PE1_TX_C_DP<12>")
	)
	(segment
		(start 398.984724 -17.018254)
		(end 399.312384 -17.345914)
		(width 0.13208)
		(layer "F.Cu")
		(net "P5E_CPU0_PE1_TX_C_DP<12>")
	)
	(segment
		(start 399.485104 -13.591032)
		(end 398.984724 -14.091412)
		(width 0.13208)
		(layer "F.Cu")
		(net "P5E_CPU0_PE1_TX_C_DP<12>")
	)
	(segment
		(start 399.487644 -11.975592)
		(end 399.485104 -11.978132)
		(width 0.13208)
		(layer "F.Cu")
		(net "P5E_CPU0_PE1_TX_C_DP<12>")
	)
	(segment
		(start 399.646902 -11.808206)
		(end 399.487644 -11.967464)
		(width 0.13208)
		(layer "F.Cu")
		(net "P5E_CPU0_PE1_TX_C_DP<12>")
	)
	(segment
		(start 401.025868 -11.978132)
		(end 401.025868 -11.978386)
		(width 0.13208)
		(layer "F.Cu")
		(net "P5E_CPU0_PE1_TX_C_DP<11>")
	)
	(segment
		(start 401.028408 -11.980926)
		(end 401.028408 -13.987018)
		(width 0.13208)
		(layer "F.Cu")
		(net "P5E_CPU0_PE1_TX_C_DP<11>")
	)
	(segment
		(start 400.846798 -11.26998)
		(end 400.846798 -11.799062)
		(width 0.13208)
		(layer "F.Cu")
		(net "P5E_CPU0_PE1_TX_C_DP<11>")
	)
	(segment
		(start 401.025868 -11.978386)
		(end 401.028408 -11.980926)
		(width 0.13208)
		(layer "F.Cu")
		(net "P5E_CPU0_PE1_TX_C_DP<11>")
	)
	(segment
		(start 401.522184 -15.491714)
		(end 401.191984 -15.821914)
		(width 0.13208)
		(layer "F.Cu")
		(net "P5E_CPU0_PE1_TX_C_DP<11>")
	)
	(segment
		(start 401.028408 -13.987018)
		(end 401.522184 -14.480794)
		(width 0.13208)
		(layer "F.Cu")
		(net "P5E_CPU0_PE1_TX_C_DP<11>")
	)
	(segment
		(start 401.522184 -14.480794)
		(end 401.522184 -15.491714)
		(width 0.13208)
		(layer "F.Cu")
		(net "P5E_CPU0_PE1_TX_C_DP<11>")
	)
	(segment
		(start 400.846798 -11.799062)
		(end 401.025868 -11.978132)
		(width 0.13208)
		(layer "F.Cu")
		(net "P5E_CPU0_PE1_TX_C_DP<11>")
	)
	(segment
		(start 403.087586 -11.974068)
		(end 403.087586 -13.711174)
		(width 0.13208)
		(layer "F.Cu")
		(net "P5E_CPU0_PE1_TX_C_DP<10>")
	)
	(segment
		(start 403.246844 -11.81481)
		(end 403.087586 -11.974068)
		(width 0.13208)
		(layer "F.Cu")
		(net "P5E_CPU0_PE1_TX_C_DP<10>")
	)
	(segment
		(start 403.246844 -11.26998)
		(end 403.246844 -11.81481)
		(width 0.13208)
		(layer "F.Cu")
		(net "P5E_CPU0_PE1_TX_C_DP<10>")
	)
	(segment
		(start 404.575264 -15.198852)
		(end 404.575264 -17.020794)
		(width 0.13208)
		(layer "F.Cu")
		(net "P5E_CPU0_PE1_TX_C_DP<10>")
	)
	(segment
		(start 403.087586 -13.711174)
		(end 404.575264 -15.198852)
		(width 0.13208)
		(layer "F.Cu")
		(net "P5E_CPU0_PE1_TX_C_DP<10>")
	)
	(segment
		(start 404.575264 -17.020794)
		(end 404.900384 -17.345914)
		(width 0.13208)
		(layer "F.Cu")
		(net "P5E_CPU0_PE1_TX_C_DP<10>")
	)
	(segment
		(start 432.60264 -15.76197)
		(end 432.60264 -17.00911)
		(width 0.13208)
		(layer "F.Cu")
		(net "P5E_CPU0_PE1_TX_C_DP<0>")
	)
	(segment
		(start 430.34839 -11.980672)
		(end 430.34839 -13.50772)
		(width 0.13208)
		(layer "F.Cu")
		(net "P5E_CPU0_PE1_TX_C_DP<0>")
	)
	(segment
		(start 432.60264 -17.00911)
		(end 432.265836 -17.345914)
		(width 0.13208)
		(layer "F.Cu")
		(net "P5E_CPU0_PE1_TX_C_DP<0>")
	)
	(segment
		(start 430.16678 -11.26998)
		(end 430.16678 -11.799062)
		(width 0.13208)
		(layer "F.Cu")
		(net "P5E_CPU0_PE1_TX_C_DP<0>")
	)
	(segment
		(start 430.34839 -13.50772)
		(end 432.60264 -15.76197)
		(width 0.13208)
		(layer "F.Cu")
		(net "P5E_CPU0_PE1_TX_C_DP<0>")
	)
	(segment
		(start 430.16678 -11.799062)
		(end 430.34839 -11.980672)
		(width 0.13208)
		(layer "F.Cu")
		(net "P5E_CPU0_PE1_TX_C_DP<0>")
	)
	(segment
		(start 404.887684 -12.702032)
		(end 407.369264 -15.183612)
		(width 0.13208)
		(layer "F.Cu")
		(net "P5E_CPU0_PE1_TX_C_DN<9>")
	)
	(segment
		(start 405.046942 -11.848846)
		(end 404.887684 -12.008104)
		(width 0.13208)
		(layer "F.Cu")
		(net "P5E_CPU0_PE1_TX_C_DN<9>")
	)
	(segment
		(start 407.369264 -15.496794)
		(end 407.694384 -15.821914)
		(width 0.13208)
		(layer "F.Cu")
		(net "P5E_CPU0_PE1_TX_C_DN<9>")
	)
	(segment
		(start 407.369264 -15.183612)
		(end 407.369264 -15.496794)
		(width 0.13208)
		(layer "F.Cu")
		(net "P5E_CPU0_PE1_TX_C_DN<9>")
	)
	(segment
		(start 404.887684 -12.008104)
		(end 404.887684 -12.702032)
		(width 0.13208)
		(layer "F.Cu")
		(net "P5E_CPU0_PE1_TX_C_DN<9>")
	)
	(segment
		(start 405.046942 -11.26998)
		(end 405.046942 -11.848846)
		(width 0.13208)
		(layer "F.Cu")
		(net "P5E_CPU0_PE1_TX_C_DN<9>")
	)
	(segment
		(start 406.246838 -11.799062)
		(end 406.428448 -11.980672)
		(width 0.13208)
		(layer "F.Cu")
		(net "P5E_CPU0_PE1_TX_C_DN<8>")
	)
	(segment
		(start 406.246838 -11.26998)
		(end 406.246838 -11.799062)
		(width 0.13208)
		(layer "F.Cu")
		(net "P5E_CPU0_PE1_TX_C_DN<8>")
	)
	(segment
		(start 409.904184 -17.015714)
		(end 409.573984 -17.345914)
		(width 0.13208)
		(layer "F.Cu")
		(net "P5E_CPU0_PE1_TX_C_DN<8>")
	)
	(segment
		(start 406.428448 -11.980672)
		(end 406.428448 -12.572238)
		(width 0.13208)
		(layer "F.Cu")
		(net "P5E_CPU0_PE1_TX_C_DN<8>")
	)
	(segment
		(start 406.428448 -12.572238)
		(end 409.904184 -16.047974)
		(width 0.13208)
		(layer "F.Cu")
		(net "P5E_CPU0_PE1_TX_C_DN<8>")
	)
	(segment
		(start 409.904184 -16.047974)
		(end 409.904184 -17.015714)
		(width 0.13208)
		(layer "F.Cu")
		(net "P5E_CPU0_PE1_TX_C_DN<8>")
	)
	(segment
		(start 412.957264 -14.581124)
		(end 412.957264 -15.496794)
		(width 0.13208)
		(layer "F.Cu")
		(net "P5E_CPU0_PE1_TX_C_DN<7>")
	)
	(segment
		(start 414.156906 -11.804142)
		(end 413.997648 -11.9634)
		(width 0.13208)
		(layer "F.Cu")
		(net "P5E_CPU0_PE1_TX_C_DN<7>")
	)
	(segment
		(start 413.997648 -13.54074)
		(end 412.957264 -14.581124)
		(width 0.13208)
		(layer "F.Cu")
		(net "P5E_CPU0_PE1_TX_C_DN<7>")
	)
	(segment
		(start 413.997648 -11.9634)
		(end 413.997648 -13.54074)
		(width 0.13208)
		(layer "F.Cu")
		(net "P5E_CPU0_PE1_TX_C_DN<7>")
	)
	(segment
		(start 412.957264 -15.496794)
		(end 413.282384 -15.821914)
		(width 0.13208)
		(layer "F.Cu")
		(net "P5E_CPU0_PE1_TX_C_DN<7>")
	)
	(segment
		(start 414.156906 -11.26998)
		(end 414.156906 -11.804142)
		(width 0.13208)
		(layer "F.Cu")
		(net "P5E_CPU0_PE1_TX_C_DN<7>")
	)
	(segment
		(start 415.79546 -17.018254)
		(end 415.4678 -17.345914)
		(width 0.13208)
		(layer "F.Cu")
		(net "P5E_CPU0_PE1_TX_C_DN<6>")
	)
	(segment
		(start 415.356802 -11.799062)
		(end 415.535872 -11.978132)
		(width 0.13208)
		(layer "F.Cu")
		(net "P5E_CPU0_PE1_TX_C_DN<6>")
	)
	(segment
		(start 415.356802 -11.26998)
		(end 415.356802 -11.799062)
		(width 0.13208)
		(layer "F.Cu")
		(net "P5E_CPU0_PE1_TX_C_DN<6>")
	)
	(segment
		(start 415.535872 -11.978132)
		(end 415.535872 -14.170914)
		(width 0.13208)
		(layer "F.Cu")
		(net "P5E_CPU0_PE1_TX_C_DN<6>")
	)
	(segment
		(start 415.79546 -14.430502)
		(end 415.79546 -17.018254)
		(width 0.13208)
		(layer "F.Cu")
		(net "P5E_CPU0_PE1_TX_C_DN<6>")
	)
	(segment
		(start 415.535872 -14.170914)
		(end 415.79546 -14.430502)
		(width 0.13208)
		(layer "F.Cu")
		(net "P5E_CPU0_PE1_TX_C_DN<6>")
	)
	(segment
		(start 418.85108 -15.496794)
		(end 419.1762 -15.821914)
		(width 0.13208)
		(layer "F.Cu")
		(net "P5E_CPU0_PE1_TX_C_DN<5>")
	)
	(segment
		(start 417.756848 -11.26998)
		(end 417.756848 -11.818366)
		(width 0.13208)
		(layer "F.Cu")
		(net "P5E_CPU0_PE1_TX_C_DN<5>")
	)
	(segment
		(start 417.59759 -13.633958)
		(end 418.85108 -14.887448)
		(width 0.13208)
		(layer "F.Cu")
		(net "P5E_CPU0_PE1_TX_C_DN<5>")
	)
	(segment
		(start 417.59759 -11.977624)
		(end 417.59759 -13.633958)
		(width 0.13208)
		(layer "F.Cu")
		(net "P5E_CPU0_PE1_TX_C_DN<5>")
	)
	(segment
		(start 418.85108 -14.887448)
		(end 418.85108 -15.496794)
		(width 0.13208)
		(layer "F.Cu")
		(net "P5E_CPU0_PE1_TX_C_DN<5>")
	)
	(segment
		(start 417.756848 -11.818366)
		(end 417.59759 -11.977624)
		(width 0.13208)
		(layer "F.Cu")
		(net "P5E_CPU0_PE1_TX_C_DN<5>")
	)
	(segment
		(start 418.956998 -11.799062)
		(end 419.138608 -11.980672)
		(width 0.13208)
		(layer "F.Cu")
		(net "P5E_CPU0_PE1_TX_C_DN<4>")
	)
	(segment
		(start 418.956998 -11.26998)
		(end 418.956998 -11.799062)
		(width 0.13208)
		(layer "F.Cu")
		(net "P5E_CPU0_PE1_TX_C_DN<4>")
	)
	(segment
		(start 419.138608 -11.980672)
		(end 419.138608 -12.864338)
		(width 0.13208)
		(layer "F.Cu")
		(net "P5E_CPU0_PE1_TX_C_DN<4>")
	)
	(segment
		(start 419.138608 -12.864338)
		(end 421.386 -15.11173)
		(width 0.13208)
		(layer "F.Cu")
		(net "P5E_CPU0_PE1_TX_C_DN<4>")
	)
	(segment
		(start 421.386 -17.015714)
		(end 421.0558 -17.345914)
		(width 0.13208)
		(layer "F.Cu")
		(net "P5E_CPU0_PE1_TX_C_DN<4>")
	)
	(segment
		(start 421.386 -15.11173)
		(end 421.386 -17.015714)
		(width 0.13208)
		(layer "F.Cu")
		(net "P5E_CPU0_PE1_TX_C_DN<4>")
	)
	(segment
		(start 425.366942 -11.26998)
		(end 425.366942 -11.813286)
		(width 0.13208)
		(layer "F.Cu")
		(net "P5E_CPU0_PE1_TX_C_DN<3>")
	)
	(segment
		(start 425.205144 -11.975084)
		(end 425.205144 -13.73124)
		(width 0.13208)
		(layer "F.Cu")
		(net "P5E_CPU0_PE1_TX_C_DN<3>")
	)
	(segment
		(start 424.43654 -15.492984)
		(end 424.43908 -15.495524)
		(width 0.13208)
		(layer "F.Cu")
		(net "P5E_CPU0_PE1_TX_C_DN<3>")
	)
	(segment
		(start 424.43654 -14.499844)
		(end 424.43654 -15.492984)
		(width 0.13208)
		(layer "F.Cu")
		(net "P5E_CPU0_PE1_TX_C_DN<3>")
	)
	(segment
		(start 424.43908 -15.495524)
		(end 424.43908 -15.496794)
		(width 0.13208)
		(layer "F.Cu")
		(net "P5E_CPU0_PE1_TX_C_DN<3>")
	)
	(segment
		(start 424.43908 -15.496794)
		(end 424.7642 -15.821914)
		(width 0.13208)
		(layer "F.Cu")
		(net "P5E_CPU0_PE1_TX_C_DN<3>")
	)
	(segment
		(start 425.366942 -11.813286)
		(end 425.205144 -11.975084)
		(width 0.13208)
		(layer "F.Cu")
		(net "P5E_CPU0_PE1_TX_C_DN<3>")
	)
	(segment
		(start 425.205144 -13.73124)
		(end 424.43654 -14.499844)
		(width 0.13208)
		(layer "F.Cu")
		(net "P5E_CPU0_PE1_TX_C_DN<3>")
	)
	(segment
		(start 427.005496 -17.018254)
		(end 426.677836 -17.345914)
		(width 0.13208)
		(layer "F.Cu")
		(net "P5E_CPU0_PE1_TX_C_DN<2>")
	)
	(segment
		(start 426.745908 -14.14399)
		(end 427.005496 -14.403578)
		(width 0.13208)
		(layer "F.Cu")
		(net "P5E_CPU0_PE1_TX_C_DN<2>")
	)
	(segment
		(start 426.566838 -11.26998)
		(end 426.566838 -11.799062)
		(width 0.13208)
		(layer "F.Cu")
		(net "P5E_CPU0_PE1_TX_C_DN<2>")
	)
	(segment
		(start 426.745908 -11.978132)
		(end 426.745908 -14.14399)
		(width 0.13208)
		(layer "F.Cu")
		(net "P5E_CPU0_PE1_TX_C_DN<2>")
	)
	(segment
		(start 426.566838 -11.799062)
		(end 426.745908 -11.978132)
		(width 0.13208)
		(layer "F.Cu")
		(net "P5E_CPU0_PE1_TX_C_DN<2>")
	)
	(segment
		(start 427.005496 -14.403578)
		(end 427.005496 -17.018254)
		(width 0.13208)
		(layer "F.Cu")
		(net "P5E_CPU0_PE1_TX_C_DN<2>")
	)
	(segment
		(start 430.061116 -15.496794)
		(end 430.386236 -15.821914)
		(width 0.13208)
		(layer "F.Cu")
		(net "P5E_CPU0_PE1_TX_C_DN<1>")
	)
	(segment
		(start 428.966884 -11.26998)
		(end 428.966884 -11.80465)
		(width 0.13208)
		(layer "F.Cu")
		(net "P5E_CPU0_PE1_TX_C_DN<1>")
	)
	(segment
		(start 430.061116 -14.921484)
		(end 430.061116 -15.496794)
		(width 0.13208)
		(layer "F.Cu")
		(net "P5E_CPU0_PE1_TX_C_DN<1>")
	)
	(segment
		(start 428.807626 -13.667994)
		(end 430.061116 -14.921484)
		(width 0.13208)
		(layer "F.Cu")
		(net "P5E_CPU0_PE1_TX_C_DN<1>")
	)
	(segment
		(start 428.807626 -11.963908)
		(end 428.807626 -13.667994)
		(width 0.13208)
		(layer "F.Cu")
		(net "P5E_CPU0_PE1_TX_C_DN<1>")
	)
	(segment
		(start 428.966884 -11.80465)
		(end 428.807626 -11.963908)
		(width 0.13208)
		(layer "F.Cu")
		(net "P5E_CPU0_PE1_TX_C_DN<1>")
	)
	(segment
		(start 394.246862 -11.26998)
		(end 394.246862 -11.825732)
		(width 0.13208)
		(layer "F.Cu")
		(net "P5E_CPU0_PE1_TX_C_DN<15>")
	)
	(segment
		(start 390.605264 -15.496794)
		(end 390.930384 -15.821914)
		(width 0.13208)
		(layer "F.Cu")
		(net "P5E_CPU0_PE1_TX_C_DN<15>")
	)
	(segment
		(start 394.246862 -11.825732)
		(end 394.085064 -11.98753)
		(width 0.13208)
		(layer "F.Cu")
		(net "P5E_CPU0_PE1_TX_C_DN<15>")
	)
	(segment
		(start 394.085064 -12.51204)
		(end 393.1666 -13.525754)
		(width 0.13208)
		(layer "F.Cu")
		(net "P5E_CPU0_PE1_TX_C_DN<15>")
	)
	(segment
		(start 394.085064 -11.98753)
		(end 394.085064 -12.51204)
		(width 0.13208)
		(layer "F.Cu")
		(net "P5E_CPU0_PE1_TX_C_DN<15>")
	)
	(segment
		(start 390.672574 -15.192756)
		(end 390.605264 -15.317978)
		(width 0.13208)
		(layer "F.Cu")
		(net "P5E_CPU0_PE1_TX_C_DN<15>")
	)
	(segment
		(start 390.605264 -15.317978)
		(end 390.605264 -15.496794)
		(width 0.13208)
		(layer "F.Cu")
		(net "P5E_CPU0_PE1_TX_C_DN<15>")
	)
	(segment
		(start 393.1666 -13.525754)
		(end 390.672574 -15.192756)
		(width 0.13208)
		(layer "F.Cu")
		(net "P5E_CPU0_PE1_TX_C_DN<15>")
	)
	(segment
		(start 395.625828 -11.978132)
		(end 395.625828 -12.738354)
		(width 0.13208)
		(layer "F.Cu")
		(net "P5E_CPU0_PE1_TX_C_DN<14>")
	)
	(segment
		(start 395.625828 -12.738354)
		(end 393.137644 -15.226538)
		(width 0.13208)
		(layer "F.Cu")
		(net "P5E_CPU0_PE1_TX_C_DN<14>")
	)
	(segment
		(start 393.137644 -17.018254)
		(end 392.809984 -17.345914)
		(width 0.13208)
		(layer "F.Cu")
		(net "P5E_CPU0_PE1_TX_C_DN<14>")
	)
	(segment
		(start 395.446758 -11.799062)
		(end 395.625828 -11.978132)
		(width 0.13208)
		(layer "F.Cu")
		(net "P5E_CPU0_PE1_TX_C_DN<14>")
	)
	(segment
		(start 395.446758 -11.26998)
		(end 395.446758 -11.799062)
		(width 0.13208)
		(layer "F.Cu")
		(net "P5E_CPU0_PE1_TX_C_DN<14>")
	)
	(segment
		(start 393.137644 -15.226538)
		(end 393.137644 -17.018254)
		(width 0.13208)
		(layer "F.Cu")
		(net "P5E_CPU0_PE1_TX_C_DN<14>")
	)
	(segment
		(start 397.846804 -11.807444)
		(end 397.685006 -11.969242)
		(width 0.13208)
		(layer "F.Cu")
		(net "P5E_CPU0_PE1_TX_C_DN<13>")
	)
	(segment
		(start 397.685006 -13.219938)
		(end 396.190724 -14.71422)
		(width 0.13208)
		(layer "F.Cu")
		(net "P5E_CPU0_PE1_TX_C_DN<13>")
	)
	(segment
		(start 396.190724 -15.492984)
		(end 396.193264 -15.495524)
		(width 0.13208)
		(layer "F.Cu")
		(net "P5E_CPU0_PE1_TX_C_DN<13>")
	)
	(segment
		(start 396.190724 -14.71422)
		(end 396.190724 -15.492984)
		(width 0.13208)
		(layer "F.Cu")
		(net "P5E_CPU0_PE1_TX_C_DN<13>")
	)
	(segment
		(start 397.685006 -11.969242)
		(end 397.685006 -13.219938)
		(width 0.13208)
		(layer "F.Cu")
		(net "P5E_CPU0_PE1_TX_C_DN<13>")
	)
	(segment
		(start 397.846804 -11.26998)
		(end 397.846804 -11.807444)
		(width 0.13208)
		(layer "F.Cu")
		(net "P5E_CPU0_PE1_TX_C_DN<13>")
	)
	(segment
		(start 396.193264 -15.495524)
		(end 396.193264 -15.496794)
		(width 0.13208)
		(layer "F.Cu")
		(net "P5E_CPU0_PE1_TX_C_DN<13>")
	)
	(segment
		(start 396.193264 -15.496794)
		(end 396.518384 -15.821914)
		(width 0.13208)
		(layer "F.Cu")
		(net "P5E_CPU0_PE1_TX_C_DN<13>")
	)
	(segment
		(start 399.046954 -11.26998)
		(end 399.046954 -11.799062)
		(width 0.13208)
		(layer "F.Cu")
		(net "P5E_CPU0_PE1_TX_C_DN<12>")
	)
	(segment
		(start 399.226024 -13.48359)
		(end 398.725644 -13.98397)
		(width 0.13208)
		(layer "F.Cu")
		(net "P5E_CPU0_PE1_TX_C_DN<12>")
	)
	(segment
		(start 399.046954 -11.799062)
		(end 399.226024 -11.978132)
		(width 0.13208)
		(layer "F.Cu")
		(net "P5E_CPU0_PE1_TX_C_DN<12>")
	)
	(segment
		(start 398.725644 -13.98397)
		(end 398.725644 -17.018254)
		(width 0.13208)
		(layer "F.Cu")
		(net "P5E_CPU0_PE1_TX_C_DN<12>")
	)
	(segment
		(start 398.725644 -17.018254)
		(end 398.397984 -17.345914)
		(width 0.13208)
		(layer "F.Cu")
		(net "P5E_CPU0_PE1_TX_C_DN<12>")
	)
	(segment
		(start 399.226024 -11.978132)
		(end 399.226024 -13.48359)
		(width 0.13208)
		(layer "F.Cu")
		(net "P5E_CPU0_PE1_TX_C_DN<12>")
	)
	(segment
		(start 401.287488 -11.97864)
		(end 401.287488 -13.879576)
		(width 0.13208)
		(layer "F.Cu")
		(net "P5E_CPU0_PE1_TX_C_DN<11>")
	)
	(segment
		(start 401.781264 -14.373352)
		(end 401.781264 -15.496794)
		(width 0.13208)
		(layer "F.Cu")
		(net "P5E_CPU0_PE1_TX_C_DN<11>")
	)
	(segment
		(start 401.287488 -13.879576)
		(end 401.781264 -14.373352)
		(width 0.13208)
		(layer "F.Cu")
		(net "P5E_CPU0_PE1_TX_C_DN<11>")
	)
	(segment
		(start 401.781264 -15.496794)
		(end 402.106384 -15.821914)
		(width 0.13208)
		(layer "F.Cu")
		(net "P5E_CPU0_PE1_TX_C_DN<11>")
	)
	(segment
		(start 401.446746 -11.819382)
		(end 401.287488 -11.97864)
		(width 0.13208)
		(layer "F.Cu")
		(net "P5E_CPU0_PE1_TX_C_DN<11>")
	)
	(segment
		(start 401.446746 -11.26998)
		(end 401.446746 -11.819382)
		(width 0.13208)
		(layer "F.Cu")
		(net "P5E_CPU0_PE1_TX_C_DN<11>")
	)
	(segment
		(start 402.646896 -11.799062)
		(end 402.828506 -11.980672)
		(width 0.13208)
		(layer "F.Cu")
		(net "P5E_CPU0_PE1_TX_C_DN<10>")
	)
	(segment
		(start 402.828506 -11.980672)
		(end 402.828506 -13.818616)
		(width 0.13208)
		(layer "F.Cu")
		(net "P5E_CPU0_PE1_TX_C_DN<10>")
	)
	(segment
		(start 404.316184 -17.015714)
		(end 403.985984 -17.345914)
		(width 0.13208)
		(layer "F.Cu")
		(net "P5E_CPU0_PE1_TX_C_DN<10>")
	)
	(segment
		(start 402.828506 -13.818616)
		(end 404.316184 -15.306294)
		(width 0.13208)
		(layer "F.Cu")
		(net "P5E_CPU0_PE1_TX_C_DN<10>")
	)
	(segment
		(start 404.316184 -15.306294)
		(end 404.316184 -17.015714)
		(width 0.13208)
		(layer "F.Cu")
		(net "P5E_CPU0_PE1_TX_C_DN<10>")
	)
	(segment
		(start 402.646896 -11.26998)
		(end 402.646896 -11.799062)
		(width 0.13208)
		(layer "F.Cu")
		(net "P5E_CPU0_PE1_TX_C_DN<10>")
	)
	(segment
		(start 432.86172 -17.027398)
		(end 433.180236 -17.345914)
		(width 0.13208)
		(layer "F.Cu")
		(net "P5E_CPU0_PE1_TX_C_DN<0>")
	)
	(segment
		(start 430.766982 -11.80846)
		(end 430.60747 -11.967972)
		(width 0.13208)
		(layer "F.Cu")
		(net "P5E_CPU0_PE1_TX_C_DN<0>")
	)
	(segment
		(start 430.60747 -13.400278)
		(end 432.86172 -15.654528)
		(width 0.13208)
		(layer "F.Cu")
		(net "P5E_CPU0_PE1_TX_C_DN<0>")
	)
	(segment
		(start 430.766982 -11.26998)
		(end 430.766982 -11.80846)
		(width 0.13208)
		(layer "F.Cu")
		(net "P5E_CPU0_PE1_TX_C_DN<0>")
	)
	(segment
		(start 432.86172 -15.654528)
		(end 432.86172 -17.027398)
		(width 0.13208)
		(layer "F.Cu")
		(net "P5E_CPU0_PE1_TX_C_DN<0>")
	)
	(segment
		(start 430.60747 -11.967972)
		(end 430.60747 -13.400278)
		(width 0.13208)
		(layer "F.Cu")
		(net "P5E_CPU0_PE1_TX_C_DN<0>")
	)
	(segment
		(start 404.885652 -7.599934)
		(end 404.885652 -7.015734)
		(width 0.13208)
		(layer "F.Cu")
		(net "P5E_CPU0_PE1_RX_DP<9>")
	)
	(segment
		(start 405.046942 -7.761224)
		(end 404.885652 -7.599934)
		(width 0.13208)
		(layer "F.Cu")
		(net "P5E_CPU0_PE1_RX_DP<9>")
	)
	(segment
		(start 404.885652 -7.015734)
		(end 405.187912 -6.713474)
		(width 0.13208)
		(layer "F.Cu")
		(net "P5E_CPU0_PE1_RX_DP<9>")
	)
	(segment
		(start 405.046942 -8.320024)
		(end 405.046942 -7.761224)
		(width 0.13208)
		(layer "F.Cu")
		(net "P5E_CPU0_PE1_RX_DP<9>")
	)
	(segment
		(start 358.640634 -221.669864)
		(end 358.640634 -221.133924)
		(width 0.13208)
		(layer "F.Cu")
		(net "P5E_CPU0_PE1_RX_DP<9>")
	)
	(segment
		(start 409.12796 -17.405096)
		(end 409.12796 -17.937226)
		(width 0.14732)
		(layer "In11.Cu")
		(net "P5E_CPU0_PE1_RX_DP<9>")
	)
	(segment
		(start 405.195278 -12.619228)
		(end 405.26335 -12.728956)
		(width 0.14732)
		(layer "In11.Cu")
		(net "P5E_CPU0_PE1_RX_DP<9>")
	)
	(segment
		(start 357.03891 -215.758522)
		(end 357.049578 -215.764618)
		(width 0.0889)
		(layer "In11.Cu")
		(net "P5E_CPU0_PE1_RX_DP<9>")
	)
	(segment
		(start 357.796084 -217.064336)
		(end 357.796084 -217.07856)
		(width 0.0889)
		(layer "In11.Cu")
		(net "P5E_CPU0_PE1_RX_DP<9>")
	)
	(segment
		(start 408.929586 -16.92529)
		(end 409.12796 -17.405096)
		(width 0.14732)
		(layer "In11.Cu")
		(net "P5E_CPU0_PE1_RX_DP<9>")
	)
	(segment
		(start 404.893272 -7.008114)
		(end 404.893272 -11.890502)
		(width 0.14732)
		(layer "In11.Cu")
		(net "P5E_CPU0_PE1_RX_DP<9>")
	)
	(segment
		(start 358.265984 -221.115382)
		(end 358.265984 -221.133924)
		(width 0.0889)
		(layer "In11.Cu")
		(net "P5E_CPU0_PE1_RX_DP<9>")
	)
	(segment
		(start 357.513636 -217.554048)
		(end 357.504746 -217.559128)
		(width 0.0889)
		(layer "In11.Cu")
		(net "P5E_CPU0_PE1_RX_DP<9>")
	)
	(segment
		(start 357.505508 -216.570306)
		(end 357.513636 -216.574878)
		(width 0.0889)
		(layer "In11.Cu")
		(net "P5E_CPU0_PE1_RX_DP<9>")
	)
	(segment
		(start 408.079448 -15.731998)
		(end 408.065732 -15.936468)
		(width 0.14732)
		(layer "In11.Cu")
		(net "P5E_CPU0_PE1_RX_DP<9>")
	)
	(segment
		(start 357.83774 -212.697568)
		(end 357.79583 -212.739478)
		(width 0.0889)
		(layer "In11.Cu")
		(net "P5E_CPU0_PE1_RX_DP<9>")
	)
	(segment
		(start 357.043482 -215.112346)
		(end 357.034592 -215.117426)
		(width 0.0889)
		(layer "In11.Cu")
		(net "P5E_CPU0_PE1_RX_DP<9>")
	)
	(segment
		(start 357.79583 -213.849204)
		(end 357.325422 -214.319612)
		(width 0.0889)
		(layer "In11.Cu")
		(net "P5E_CPU0_PE1_RX_DP<9>")
	)
	(segment
		(start 356.581202 -184.329832)
		(end 357.83774 -211.951316)
		(width 0.14732)
		(layer "In11.Cu")
		(net "P5E_CPU0_PE1_RX_DP<9>")
	)
	(segment
		(start 357.504746 -219.825316)
		(end 357.511604 -219.829126)
		(width 0.0889)
		(layer "In11.Cu")
		(net "P5E_CPU0_PE1_RX_DP<9>")
	)
	(segment
		(start 408.508708 -60.627768)
		(end 408.216354 -76.425044)
		(width 0.14732)
		(layer "In11.Cu")
		(net "P5E_CPU0_PE1_RX_DP<9>")
	)
	(segment
		(start 408.417268 -19.352768)
		(end 408.508708 -60.627768)
		(width 0.14732)
		(layer "In11.Cu")
		(net "P5E_CPU0_PE1_RX_DP<9>")
	)
	(segment
		(start 405.26335 -12.728956)
		(end 406.854406 -14.549882)
		(width 0.14732)
		(layer "In11.Cu")
		(net "P5E_CPU0_PE1_RX_DP<9>")
	)
	(segment
		(start 406.879552 -79.594456)
		(end 360.647996 -161.256218)
		(width 0.14732)
		(layer "In11.Cu")
		(net "P5E_CPU0_PE1_RX_DP<9>")
	)
	(segment
		(start 407.058622 -14.563852)
		(end 407.301192 -14.841474)
		(width 0.14732)
		(layer "In11.Cu")
		(net "P5E_CPU0_PE1_RX_DP<9>")
	)
	(segment
		(start 405.187912 -6.713474)
		(end 404.893272 -7.008114)
		(width 0.14732)
		(layer "In11.Cu")
		(net "P5E_CPU0_PE1_RX_DP<9>")
	)
	(segment
		(start 360.647996 -161.256218)
		(end 356.581202 -184.329832)
		(width 0.14732)
		(layer "In11.Cu")
		(net "P5E_CPU0_PE1_RX_DP<9>")
	)
	(segment
		(start 357.511604 -219.829126)
		(end 357.513636 -219.830396)
		(width 0.0889)
		(layer "In11.Cu")
		(net "P5E_CPU0_PE1_RX_DP<9>")
	)
	(segment
		(start 357.504746 -218.197684)
		(end 357.505508 -218.198192)
		(width 0.0889)
		(layer "In11.Cu")
		(net "P5E_CPU0_PE1_RX_DP<9>")
	)
	(segment
		(start 357.83774 -211.951316)
		(end 357.83774 -212.67547)
		(width 0.14732)
		(layer "In11.Cu")
		(net "P5E_CPU0_PE1_RX_DP<9>")
	)
	(segment
		(start 408.065732 -15.936468)
		(end 408.929586 -16.92529)
		(width 0.14732)
		(layer "In11.Cu")
		(net "P5E_CPU0_PE1_RX_DP<9>")
	)
	(segment
		(start 357.505508 -218.198192)
		(end 357.513636 -218.202764)
		(width 0.0889)
		(layer "In11.Cu")
		(net "P5E_CPU0_PE1_RX_DP<9>")
	)
	(segment
		(start 407.632662 -15.44066)
		(end 407.836878 -15.454376)
		(width 0.14732)
		(layer "In11.Cu")
		(net "P5E_CPU0_PE1_RX_DP<9>")
	)
	(segment
		(start 409.12796 -17.937226)
		(end 408.417268 -19.00047)
		(width 0.14732)
		(layer "In11.Cu")
		(net "P5E_CPU0_PE1_RX_DP<9>")
	)
	(segment
		(start 357.83774 -212.67547)
		(end 357.83774 -212.697568)
		(width 0.0889)
		(layer "In11.Cu")
		(net "P5E_CPU0_PE1_RX_DP<9>")
	)
	(segment
		(start 408.417268 -19.00047)
		(end 408.417268 -19.352768)
		(width 0.14732)
		(layer "In11.Cu")
		(net "P5E_CPU0_PE1_RX_DP<9>")
	)
	(segment
		(start 357.504746 -216.569798)
		(end 357.505508 -216.570306)
		(width 0.0889)
		(layer "In11.Cu")
		(net "P5E_CPU0_PE1_RX_DP<9>")
	)
	(segment
		(start 357.034592 -215.755982)
		(end 357.03891 -215.758522)
		(width 0.0889)
		(layer "In11.Cu")
		(net "P5E_CPU0_PE1_RX_DP<9>")
	)
	(segment
		(start 404.893272 -11.890502)
		(end 405.195278 -12.619228)
		(width 0.14732)
		(layer "In11.Cu")
		(net "P5E_CPU0_PE1_RX_DP<9>")
	)
	(segment
		(start 357.519732 -219.17787)
		(end 357.504746 -219.18676)
		(width 0.0889)
		(layer "In11.Cu")
		(net "P5E_CPU0_PE1_RX_DP<9>")
	)
	(segment
		(start 407.301192 -14.841474)
		(end 407.287476 -15.04569)
		(width 0.14732)
		(layer "In11.Cu")
		(net "P5E_CPU0_PE1_RX_DP<9>")
	)
	(segment
		(start 357.974646 -220.639132)
		(end 357.983536 -220.644212)
		(width 0.0889)
		(layer "In11.Cu")
		(net "P5E_CPU0_PE1_RX_DP<9>")
	)
	(segment
		(start 407.287476 -15.04569)
		(end 407.632662 -15.44066)
		(width 0.14732)
		(layer "In11.Cu")
		(net "P5E_CPU0_PE1_RX_DP<9>")
	)
	(segment
		(start 406.854406 -14.549882)
		(end 407.058622 -14.563852)
		(width 0.14732)
		(layer "In11.Cu")
		(net "P5E_CPU0_PE1_RX_DP<9>")
	)
	(segment
		(start 358.48417 -221.404942)
		(end 358.640634 -221.133924)
		(width 0.0889)
		(layer "In11.Cu")
		(net "P5E_CPU0_PE1_RX_DP<9>")
	)
	(segment
		(start 408.216354 -76.425044)
		(end 406.879552 -79.594456)
		(width 0.14732)
		(layer "In11.Cu")
		(net "P5E_CPU0_PE1_RX_DP<9>")
	)
	(segment
		(start 357.513636 -216.574878)
		(end 357.519732 -216.578434)
		(width 0.0889)
		(layer "In11.Cu")
		(net "P5E_CPU0_PE1_RX_DP<9>")
	)
	(segment
		(start 357.513636 -219.830396)
		(end 357.519732 -219.833952)
		(width 0.0889)
		(layer "In11.Cu")
		(net "P5E_CPU0_PE1_RX_DP<9>")
	)
	(segment
		(start 357.325422 -214.319612)
		(end 357.325422 -214.62238)
		(width 0.0889)
		(layer "In11.Cu")
		(net "P5E_CPU0_PE1_RX_DP<9>")
	)
	(segment
		(start 358.405938 -221.42577)
		(end 358.48417 -221.404942)
		(width 0.0889)
		(layer "In11.Cu")
		(net "P5E_CPU0_PE1_RX_DP<9>")
	)
	(segment
		(start 357.513636 -218.202764)
		(end 357.519732 -218.20632)
		(width 0.0889)
		(layer "In11.Cu")
		(net "P5E_CPU0_PE1_RX_DP<9>")
	)
	(segment
		(start 357.519732 -219.178124)
		(end 357.519732 -219.17787)
		(width 0.0889)
		(layer "In11.Cu")
		(net "P5E_CPU0_PE1_RX_DP<9>")
	)
	(segment
		(start 357.79583 -212.739478)
		(end 357.79583 -213.849204)
		(width 0.0889)
		(layer "In11.Cu")
		(net "P5E_CPU0_PE1_RX_DP<9>")
	)
	(segment
		(start 407.836878 -15.454376)
		(end 408.079448 -15.731998)
		(width 0.14732)
		(layer "In11.Cu")
		(net "P5E_CPU0_PE1_RX_DP<9>")
	)
	(arc
		(start 357.519732 -219.833952)
		(mid 357.722145 -220.040365)
		(end 357.796084 -220.319854)
		(width 0.0889)
		(layer "In11.Cu")
		(net "P5E_CPU0_PE1_RX_DP<9>")
	)
	(arc
		(start 357.796084 -220.319854)
		(mid 357.843763 -220.502754)
		(end 357.974646 -220.639132)
		(width 0.0889)
		(layer "In11.Cu")
		(net "P5E_CPU0_PE1_RX_DP<9>")
	)
	(arc
		(start 356.856284 -215.421972)
		(mid 356.856087 -215.429337)
		(end 356.85603 -215.436704)
		(width 0.0889)
		(layer "In11.Cu")
		(net "P5E_CPU0_PE1_RX_DP<9>")
	)
	(arc
		(start 358.265984 -221.133924)
		(mid 358.302844 -221.295721)
		(end 358.405938 -221.42577)
		(width 0.0889)
		(layer "In11.Cu")
		(net "P5E_CPU0_PE1_RX_DP<9>")
	)
	(arc
		(start 357.034592 -215.117426)
		(mid 356.907338 -215.247392)
		(end 356.856284 -215.421972)
		(width 0.0889)
		(layer "In11.Cu")
		(net "P5E_CPU0_PE1_RX_DP<9>")
	)
	(arc
		(start 357.796084 -217.07856)
		(mid 357.716943 -217.353183)
		(end 357.513636 -217.554048)
		(width 0.0889)
		(layer "In11.Cu")
		(net "P5E_CPU0_PE1_RX_DP<9>")
	)
	(arc
		(start 357.519732 -216.578434)
		(mid 357.722145 -216.784847)
		(end 357.796084 -217.064336)
		(width 0.0889)
		(layer "In11.Cu")
		(net "P5E_CPU0_PE1_RX_DP<9>")
	)
	(arc
		(start 357.326184 -216.25052)
		(mid 357.373863 -216.43342)
		(end 357.504746 -216.569798)
		(width 0.0889)
		(layer "In11.Cu")
		(net "P5E_CPU0_PE1_RX_DP<9>")
	)
	(arc
		(start 357.056436 -215.103964)
		(mid 357.049988 -215.1082)
		(end 357.043482 -215.112346)
		(width 0.0889)
		(layer "In11.Cu")
		(net "P5E_CPU0_PE1_RX_DP<9>")
	)
	(arc
		(start 357.049578 -215.764618)
		(mid 357.252165 -215.970969)
		(end 357.326184 -216.25052)
		(width 0.0889)
		(layer "In11.Cu")
		(net "P5E_CPU0_PE1_RX_DP<9>")
	)
	(arc
		(start 357.519732 -218.20632)
		(mid 357.796058 -218.692222)
		(end 357.519732 -219.178124)
		(width 0.0889)
		(layer "In11.Cu")
		(net "P5E_CPU0_PE1_RX_DP<9>")
	)
	(arc
		(start 357.325422 -214.62238)
		(mid 357.253655 -214.89819)
		(end 357.056436 -215.103964)
		(width 0.0889)
		(layer "In11.Cu")
		(net "P5E_CPU0_PE1_RX_DP<9>")
	)
	(arc
		(start 357.326184 -217.878406)
		(mid 357.373863 -218.061306)
		(end 357.504746 -218.197684)
		(width 0.0889)
		(layer "In11.Cu")
		(net "P5E_CPU0_PE1_RX_DP<9>")
	)
	(arc
		(start 357.983536 -220.644212)
		(mid 358.185822 -220.843193)
		(end 358.265984 -221.115382)
		(width 0.0889)
		(layer "In11.Cu")
		(net "P5E_CPU0_PE1_RX_DP<9>")
	)
	(arc
		(start 357.504746 -219.18676)
		(mid 357.32627 -219.506038)
		(end 357.504746 -219.825316)
		(width 0.0889)
		(layer "In11.Cu")
		(net "P5E_CPU0_PE1_RX_DP<9>")
	)
	(arc
		(start 356.85603 -215.436704)
		(mid 356.903709 -215.619604)
		(end 357.034592 -215.755982)
		(width 0.0889)
		(layer "In11.Cu")
		(net "P5E_CPU0_PE1_RX_DP<9>")
	)
	(arc
		(start 357.504746 -217.559128)
		(mid 357.377492 -217.689094)
		(end 357.326438 -217.863674)
		(width 0.0889)
		(layer "In11.Cu")
		(net "P5E_CPU0_PE1_RX_DP<9>")
	)
	(arc
		(start 357.326438 -217.863674)
		(mid 357.326241 -217.871039)
		(end 357.326184 -217.878406)
		(width 0.0889)
		(layer "In11.Cu")
		(net "P5E_CPU0_PE1_RX_DP<9>")
	)
	(segment
		(start 406.846786 -7.761224)
		(end 406.689306 -7.603744)
		(width 0.13208)
		(layer "F.Cu")
		(net "P5E_CPU0_PE1_RX_DP<8>")
	)
	(segment
		(start 406.689306 -7.603744)
		(end 406.689306 -5.255006)
		(width 0.13208)
		(layer "F.Cu")
		(net "P5E_CPU0_PE1_RX_DP<8>")
	)
	(segment
		(start 359.110534 -220.855794)
		(end 359.11028 -220.319854)
		(width 0.13208)
		(layer "F.Cu")
		(net "P5E_CPU0_PE1_RX_DP<8>")
	)
	(segment
		(start 406.846786 -8.320024)
		(end 406.846786 -7.761224)
		(width 0.13208)
		(layer "F.Cu")
		(net "P5E_CPU0_PE1_RX_DP<8>")
	)
	(segment
		(start 406.689306 -5.255006)
		(end 406.992582 -4.95173)
		(width 0.13208)
		(layer "F.Cu")
		(net "P5E_CPU0_PE1_RX_DP<8>")
	)
	(segment
		(start 409.32227 -12.443714)
		(end 409.32227 -12.443968)
		(width 0.14732)
		(layer "In11.Cu")
		(net "P5E_CPU0_PE1_RX_DP<8>")
	)
	(segment
		(start 406.991566 -7.357618)
		(end 408.182064 -9.14019)
		(width 0.14732)
		(layer "In11.Cu")
		(net "P5E_CPU0_PE1_RX_DP<8>")
	)
	(segment
		(start 359.245662 -220.66885)
		(end 359.266744 -220.590872)
		(width 0.0889)
		(layer "In11.Cu")
		(net "P5E_CPU0_PE1_RX_DP<8>")
	)
	(segment
		(start 407.77287 -79.93761)
		(end 361.527598 -161.623756)
		(width 0.14732)
		(layer "In11.Cu")
		(net "P5E_CPU0_PE1_RX_DP<8>")
	)
	(segment
		(start 358.453436 -217.554048)
		(end 358.444546 -217.559128)
		(width 0.0889)
		(layer "In11.Cu")
		(net "P5E_CPU0_PE1_RX_DP<8>")
	)
	(segment
		(start 409.537154 -13.066776)
		(end 409.843224 -13.95349)
		(width 0.14732)
		(layer "In11.Cu")
		(net "P5E_CPU0_PE1_RX_DP<8>")
	)
	(segment
		(start 411.137608 -17.703546)
		(end 411.953964 -18.925032)
		(width 0.14732)
		(layer "In11.Cu")
		(net "P5E_CPU0_PE1_RX_DP<8>")
	)
	(segment
		(start 358.735884 -217.05443)
		(end 358.735884 -217.082878)
		(width 0.0889)
		(layer "In11.Cu")
		(net "P5E_CPU0_PE1_RX_DP<8>")
	)
	(segment
		(start 406.697942 -6.649212)
		(end 406.991566 -7.357618)
		(width 0.14732)
		(layer "In11.Cu")
		(net "P5E_CPU0_PE1_RX_DP<8>")
	)
	(segment
		(start 409.322524 -12.44473)
		(end 409.506674 -12.534138)
		(width 0.14732)
		(layer "In11.Cu")
		(net "P5E_CPU0_PE1_RX_DP<8>")
	)
	(segment
		(start 358.73563 -215.414606)
		(end 358.73563 -215.452198)
		(width 0.0889)
		(layer "In11.Cu")
		(net "P5E_CPU0_PE1_RX_DP<8>")
	)
	(segment
		(start 410.14777 -14.391386)
		(end 410.058108 -14.575536)
		(width 0.14732)
		(layer "In11.Cu")
		(net "P5E_CPU0_PE1_RX_DP<8>")
	)
	(segment
		(start 409.32227 -12.443968)
		(end 409.322524 -12.44473)
		(width 0.14732)
		(layer "In11.Cu")
		(net "P5E_CPU0_PE1_RX_DP<8>")
	)
	(segment
		(start 359.266744 -220.590872)
		(end 359.11028 -220.319854)
		(width 0.0889)
		(layer "In11.Cu")
		(net "P5E_CPU0_PE1_RX_DP<8>")
	)
	(segment
		(start 406.697942 -5.24637)
		(end 406.697942 -6.649212)
		(width 0.14732)
		(layer "In11.Cu")
		(net "P5E_CPU0_PE1_RX_DP<8>")
	)
	(segment
		(start 410.3624 -15.013178)
		(end 410.482542 -15.361666)
		(width 0.14732)
		(layer "In11.Cu")
		(net "P5E_CPU0_PE1_RX_DP<8>")
	)
	(segment
		(start 410.482542 -15.361666)
		(end 410.39288 -15.545562)
		(width 0.14732)
		(layer "In11.Cu")
		(net "P5E_CPU0_PE1_RX_DP<8>")
	)
	(segment
		(start 358.45242 -218.202256)
		(end 358.453436 -218.202764)
		(width 0.0889)
		(layer "In11.Cu")
		(net "P5E_CPU0_PE1_RX_DP<8>")
	)
	(segment
		(start 358.735884 -220.309948)
		(end 358.735884 -220.32849)
		(width 0.0889)
		(layer "In11.Cu")
		(net "P5E_CPU0_PE1_RX_DP<8>")
	)
	(segment
		(start 358.444546 -216.569798)
		(end 358.453436 -216.574878)
		(width 0.0889)
		(layer "In11.Cu")
		(net "P5E_CPU0_PE1_RX_DP<8>")
	)
	(segment
		(start 358.73563 -218.676728)
		(end 358.73563 -218.707716)
		(width 0.0889)
		(layer "In11.Cu")
		(net "P5E_CPU0_PE1_RX_DP<8>")
	)
	(segment
		(start 409.506674 -12.534138)
		(end 409.626816 -12.882626)
		(width 0.14732)
		(layer "In11.Cu")
		(net "P5E_CPU0_PE1_RX_DP<8>")
	)
	(segment
		(start 409.626816 -12.882626)
		(end 409.537154 -13.066776)
		(width 0.14732)
		(layer "In11.Cu")
		(net "P5E_CPU0_PE1_RX_DP<8>")
	)
	(segment
		(start 409.843224 -13.95349)
		(end 410.027628 -14.043152)
		(width 0.14732)
		(layer "In11.Cu")
		(net "P5E_CPU0_PE1_RX_DP<8>")
	)
	(segment
		(start 358.444546 -214.941912)
		(end 358.453436 -214.946992)
		(width 0.0889)
		(layer "In11.Cu")
		(net "P5E_CPU0_PE1_RX_DP<8>")
	)
	(segment
		(start 409.262326 -76.788264)
		(end 407.77287 -79.93761)
		(width 0.14732)
		(layer "In11.Cu")
		(net "P5E_CPU0_PE1_RX_DP<8>")
	)
	(segment
		(start 410.39288 -15.545562)
		(end 411.137608 -17.703546)
		(width 0.14732)
		(layer "In11.Cu")
		(net "P5E_CPU0_PE1_RX_DP<8>")
	)
	(segment
		(start 358.45242 -219.182188)
		(end 358.444546 -219.18676)
		(width 0.0889)
		(layer "In11.Cu")
		(net "P5E_CPU0_PE1_RX_DP<8>")
	)
	(segment
		(start 358.735884 -212.739478)
		(end 358.735884 -213.893908)
		(width 0.0889)
		(layer "In11.Cu")
		(net "P5E_CPU0_PE1_RX_DP<8>")
	)
	(segment
		(start 358.453436 -219.18168)
		(end 358.45242 -219.182188)
		(width 0.0889)
		(layer "In11.Cu")
		(net "P5E_CPU0_PE1_RX_DP<8>")
	)
	(segment
		(start 410.058108 -14.575536)
		(end 410.17825 -14.923516)
		(width 0.14732)
		(layer "In11.Cu")
		(net "P5E_CPU0_PE1_RX_DP<8>")
	)
	(segment
		(start 358.735884 -213.893908)
		(end 358.265984 -214.363808)
		(width 0.0889)
		(layer "In11.Cu")
		(net "P5E_CPU0_PE1_RX_DP<8>")
	)
	(segment
		(start 408.182064 -9.14019)
		(end 409.32227 -12.443714)
		(width 0.14732)
		(layer "In11.Cu")
		(net "P5E_CPU0_PE1_RX_DP<8>")
	)
	(segment
		(start 358.777794 -212.67547)
		(end 358.777794 -212.697568)
		(width 0.0889)
		(layer "In11.Cu")
		(net "P5E_CPU0_PE1_RX_DP<8>")
	)
	(segment
		(start 358.453436 -215.926162)
		(end 358.45242 -215.92667)
		(width 0.0889)
		(layer "In11.Cu")
		(net "P5E_CPU0_PE1_RX_DP<8>")
	)
	(segment
		(start 361.527598 -161.623756)
		(end 357.532686 -184.290208)
		(width 0.14732)
		(layer "In11.Cu")
		(net "P5E_CPU0_PE1_RX_DP<8>")
	)
	(segment
		(start 410.027628 -14.043152)
		(end 410.14777 -14.391386)
		(width 0.14732)
		(layer "In11.Cu")
		(net "P5E_CPU0_PE1_RX_DP<8>")
	)
	(segment
		(start 358.777794 -212.697568)
		(end 358.735884 -212.739478)
		(width 0.0889)
		(layer "In11.Cu")
		(net "P5E_CPU0_PE1_RX_DP<8>")
	)
	(segment
		(start 406.992582 -4.95173)
		(end 406.697942 -5.24637)
		(width 0.14732)
		(layer "In11.Cu")
		(net "P5E_CPU0_PE1_RX_DP<8>")
	)
	(segment
		(start 358.777794 -212.145626)
		(end 358.777794 -212.67547)
		(width 0.14732)
		(layer "In11.Cu")
		(net "P5E_CPU0_PE1_RX_DP<8>")
	)
	(segment
		(start 358.265984 -214.363808)
		(end 358.265984 -214.622634)
		(width 0.0889)
		(layer "In11.Cu")
		(net "P5E_CPU0_PE1_RX_DP<8>")
	)
	(segment
		(start 358.45242 -215.92667)
		(end 358.444546 -215.931242)
		(width 0.0889)
		(layer "In11.Cu")
		(net "P5E_CPU0_PE1_RX_DP<8>")
	)
	(segment
		(start 357.532686 -184.290208)
		(end 358.777794 -212.145626)
		(width 0.14732)
		(layer "In11.Cu")
		(net "P5E_CPU0_PE1_RX_DP<8>")
	)
	(segment
		(start 411.953964 -18.925032)
		(end 409.262326 -76.788264)
		(width 0.14732)
		(layer "In11.Cu")
		(net "P5E_CPU0_PE1_RX_DP<8>")
	)
	(segment
		(start 358.444546 -218.197684)
		(end 358.45242 -218.202256)
		(width 0.0889)
		(layer "In11.Cu")
		(net "P5E_CPU0_PE1_RX_DP<8>")
	)
	(segment
		(start 410.17825 -14.923516)
		(end 410.3624 -15.013178)
		(width 0.14732)
		(layer "In11.Cu")
		(net "P5E_CPU0_PE1_RX_DP<8>")
	)
	(segment
		(start 358.444546 -219.825316)
		(end 358.453436 -219.830396)
		(width 0.0889)
		(layer "In11.Cu")
		(net "P5E_CPU0_PE1_RX_DP<8>")
	)
	(arc
		(start 358.73563 -218.707716)
		(mid 358.65626 -218.98145)
		(end 358.453436 -219.18168)
		(width 0.0889)
		(layer "In11.Cu")
		(net "P5E_CPU0_PE1_RX_DP<8>")
	)
	(arc
		(start 358.266238 -216.257124)
		(mid 358.315437 -216.43623)
		(end 358.444546 -216.569798)
		(width 0.0889)
		(layer "In11.Cu")
		(net "P5E_CPU0_PE1_RX_DP<8>")
	)
	(arc
		(start 358.453436 -214.946992)
		(mid 358.654718 -215.144479)
		(end 358.73563 -215.414606)
		(width 0.0889)
		(layer "In11.Cu")
		(net "P5E_CPU0_PE1_RX_DP<8>")
	)
	(arc
		(start 358.266238 -219.495878)
		(mid 358.266144 -219.50426)
		(end 358.266238 -219.512642)
		(width 0.0889)
		(layer "In11.Cu")
		(net "P5E_CPU0_PE1_RX_DP<8>")
	)
	(arc
		(start 358.266238 -217.888566)
		(mid 358.316253 -218.065697)
		(end 358.444546 -218.197684)
		(width 0.0889)
		(layer "In11.Cu")
		(net "P5E_CPU0_PE1_RX_DP<8>")
	)
	(arc
		(start 358.444546 -217.559128)
		(mid 358.316735 -217.690221)
		(end 358.266238 -217.866214)
		(width 0.0889)
		(layer "In11.Cu")
		(net "P5E_CPU0_PE1_RX_DP<8>")
	)
	(arc
		(start 358.735884 -220.32849)
		(mid 358.788154 -220.510855)
		(end 358.923082 -220.644212)
		(width 0.0889)
		(layer "In11.Cu")
		(net "P5E_CPU0_PE1_RX_DP<8>")
	)
	(arc
		(start 358.923082 -220.644212)
		(mid 359.08157 -220.693145)
		(end 359.245662 -220.66885)
		(width 0.0889)
		(layer "In11.Cu")
		(net "P5E_CPU0_PE1_RX_DP<8>")
	)
	(arc
		(start 358.444546 -219.18676)
		(mid 358.316227 -219.318732)
		(end 358.266238 -219.495878)
		(width 0.0889)
		(layer "In11.Cu")
		(net "P5E_CPU0_PE1_RX_DP<8>")
	)
	(arc
		(start 358.266238 -217.866214)
		(mid 358.266071 -217.87739)
		(end 358.266238 -217.888566)
		(width 0.0889)
		(layer "In11.Cu")
		(net "P5E_CPU0_PE1_RX_DP<8>")
	)
	(arc
		(start 358.735884 -217.082878)
		(mid 358.655722 -217.355067)
		(end 358.453436 -217.554048)
		(width 0.0889)
		(layer "In11.Cu")
		(net "P5E_CPU0_PE1_RX_DP<8>")
	)
	(arc
		(start 358.453436 -216.574878)
		(mid 358.657771 -216.777483)
		(end 358.735884 -217.05443)
		(width 0.0889)
		(layer "In11.Cu")
		(net "P5E_CPU0_PE1_RX_DP<8>")
	)
	(arc
		(start 358.453436 -218.202764)
		(mid 358.656259 -218.402995)
		(end 358.73563 -218.676728)
		(width 0.0889)
		(layer "In11.Cu")
		(net "P5E_CPU0_PE1_RX_DP<8>")
	)
	(arc
		(start 358.266238 -219.512642)
		(mid 358.315437 -219.691748)
		(end 358.444546 -219.825316)
		(width 0.0889)
		(layer "In11.Cu")
		(net "P5E_CPU0_PE1_RX_DP<8>")
	)
	(arc
		(start 358.266238 -216.24036)
		(mid 358.266144 -216.248742)
		(end 358.266238 -216.257124)
		(width 0.0889)
		(layer "In11.Cu")
		(net "P5E_CPU0_PE1_RX_DP<8>")
	)
	(arc
		(start 358.265984 -214.622634)
		(mid 358.313663 -214.805534)
		(end 358.444546 -214.941912)
		(width 0.0889)
		(layer "In11.Cu")
		(net "P5E_CPU0_PE1_RX_DP<8>")
	)
	(arc
		(start 358.73563 -215.452198)
		(mid 358.65626 -215.725932)
		(end 358.453436 -215.926162)
		(width 0.0889)
		(layer "In11.Cu")
		(net "P5E_CPU0_PE1_RX_DP<8>")
	)
	(arc
		(start 358.453436 -219.830396)
		(mid 358.657771 -220.033001)
		(end 358.735884 -220.309948)
		(width 0.0889)
		(layer "In11.Cu")
		(net "P5E_CPU0_PE1_RX_DP<8>")
	)
	(arc
		(start 358.444546 -215.931242)
		(mid 358.316227 -216.063214)
		(end 358.266238 -216.24036)
		(width 0.0889)
		(layer "In11.Cu")
		(net "P5E_CPU0_PE1_RX_DP<8>")
	)
	(segment
		(start 414.156906 -8.320024)
		(end 414.156906 -7.761224)
		(width 0.13208)
		(layer "F.Cu")
		(net "P5E_CPU0_PE1_RX_DP<7>")
	)
	(segment
		(start 414.156906 -7.761224)
		(end 413.995616 -7.599934)
		(width 0.13208)
		(layer "F.Cu")
		(net "P5E_CPU0_PE1_RX_DP<7>")
	)
	(segment
		(start 360.51998 -221.669864)
		(end 360.520234 -221.133924)
		(width 0.13208)
		(layer "F.Cu")
		(net "P5E_CPU0_PE1_RX_DP<7>")
	)
	(segment
		(start 413.995616 -7.599934)
		(end 413.995616 -7.015734)
		(width 0.13208)
		(layer "F.Cu")
		(net "P5E_CPU0_PE1_RX_DP<7>")
	)
	(segment
		(start 413.995616 -7.015734)
		(end 414.297876 -6.713474)
		(width 0.13208)
		(layer "F.Cu")
		(net "P5E_CPU0_PE1_RX_DP<7>")
	)
	(segment
		(start 359.675684 -213.295992)
		(end 359.675684 -213.893908)
		(width 0.0889)
		(layer "In11.Cu")
		(net "P5E_CPU0_PE1_RX_DP<7>")
	)
	(segment
		(start 359.205022 -214.36457)
		(end 359.205022 -214.634064)
		(width 0.0889)
		(layer "In11.Cu")
		(net "P5E_CPU0_PE1_RX_DP<7>")
	)
	(segment
		(start 359.67543 -215.42248)
		(end 359.67543 -215.452198)
		(width 0.0889)
		(layer "In11.Cu")
		(net "P5E_CPU0_PE1_RX_DP<7>")
	)
	(segment
		(start 414.537398 -16.199358)
		(end 414.69564 -17.396206)
		(width 0.14732)
		(layer "In11.Cu")
		(net "P5E_CPU0_PE1_RX_DP<7>")
	)
	(segment
		(start 359.402888 -219.836238)
		(end 359.405174 -219.837508)
		(width 0.0889)
		(layer "In11.Cu")
		(net "P5E_CPU0_PE1_RX_DP<7>")
	)
	(segment
		(start 414.344104 -18.905474)
		(end 410.356812 -76.79436)
		(width 0.14732)
		(layer "In11.Cu")
		(net "P5E_CPU0_PE1_RX_DP<7>")
	)
	(segment
		(start 359.393236 -219.18168)
		(end 359.37571 -219.191078)
		(width 0.0889)
		(layer "In11.Cu")
		(net "P5E_CPU0_PE1_RX_DP<7>")
	)
	(segment
		(start 359.717848 -212.317584)
		(end 359.717848 -213.23173)
		(width 0.14732)
		(layer "In11.Cu")
		(net "P5E_CPU0_PE1_RX_DP<7>")
	)
	(segment
		(start 414.69564 -17.396206)
		(end 414.69564 -18.056606)
		(width 0.14732)
		(layer "In11.Cu")
		(net "P5E_CPU0_PE1_RX_DP<7>")
	)
	(segment
		(start 414.527492 -15.019274)
		(end 414.402778 -15.181834)
		(width 0.14732)
		(layer "In11.Cu")
		(net "P5E_CPU0_PE1_RX_DP<7>")
	)
	(segment
		(start 414.316418 -14.529308)
		(end 414.478978 -14.653768)
		(width 0.14732)
		(layer "In11.Cu")
		(net "P5E_CPU0_PE1_RX_DP<7>")
	)
	(segment
		(start 414.003236 -7.008114)
		(end 414.003236 -12.16152)
		(width 0.14732)
		(layer "In11.Cu")
		(net "P5E_CPU0_PE1_RX_DP<7>")
	)
	(segment
		(start 414.297876 -6.713474)
		(end 414.003236 -7.008114)
		(width 0.14732)
		(layer "In11.Cu")
		(net "P5E_CPU0_PE1_RX_DP<7>")
	)
	(segment
		(start 414.662112 -16.036798)
		(end 414.537398 -16.199358)
		(width 0.14732)
		(layer "In11.Cu")
		(net "P5E_CPU0_PE1_RX_DP<7>")
	)
	(segment
		(start 359.717848 -213.23173)
		(end 359.717848 -213.253828)
		(width 0.0889)
		(layer "In11.Cu")
		(net "P5E_CPU0_PE1_RX_DP<7>")
	)
	(segment
		(start 360.145584 -221.115382)
		(end 360.145584 -221.133924)
		(width 0.0889)
		(layer "In11.Cu")
		(net "P5E_CPU0_PE1_RX_DP<7>")
	)
	(segment
		(start 359.384346 -218.197684)
		(end 359.393236 -218.202764)
		(width 0.0889)
		(layer "In11.Cu")
		(net "P5E_CPU0_PE1_RX_DP<7>")
	)
	(segment
		(start 414.613598 -15.671292)
		(end 414.662112 -16.036798)
		(width 0.14732)
		(layer "In11.Cu")
		(net "P5E_CPU0_PE1_RX_DP<7>")
	)
	(segment
		(start 414.003236 -12.16152)
		(end 414.316418 -14.529308)
		(width 0.14732)
		(layer "In11.Cu")
		(net "P5E_CPU0_PE1_RX_DP<7>")
	)
	(segment
		(start 359.384346 -216.569798)
		(end 359.393236 -216.574878)
		(width 0.0889)
		(layer "In11.Cu")
		(net "P5E_CPU0_PE1_RX_DP<7>")
	)
	(segment
		(start 414.478978 -14.653768)
		(end 414.527492 -15.019274)
		(width 0.14732)
		(layer "In11.Cu")
		(net "P5E_CPU0_PE1_RX_DP<7>")
	)
	(segment
		(start 359.854246 -220.639132)
		(end 359.863136 -220.644212)
		(width 0.0889)
		(layer "In11.Cu")
		(net "P5E_CPU0_PE1_RX_DP<7>")
	)
	(segment
		(start 359.675684 -213.893908)
		(end 359.205022 -214.36457)
		(width 0.0889)
		(layer "In11.Cu")
		(net "P5E_CPU0_PE1_RX_DP<7>")
	)
	(segment
		(start 358.488234 -184.226962)
		(end 359.717848 -212.317584)
		(width 0.14732)
		(layer "In11.Cu")
		(net "P5E_CPU0_PE1_RX_DP<7>")
	)
	(segment
		(start 359.393236 -217.554048)
		(end 359.384346 -217.559128)
		(width 0.0889)
		(layer "In11.Cu")
		(net "P5E_CPU0_PE1_RX_DP<7>")
	)
	(segment
		(start 359.675684 -217.05443)
		(end 359.675684 -217.082878)
		(width 0.0889)
		(layer "In11.Cu")
		(net "P5E_CPU0_PE1_RX_DP<7>")
	)
	(segment
		(start 362.415074 -161.94913)
		(end 358.488234 -184.226962)
		(width 0.14732)
		(layer "In11.Cu")
		(net "P5E_CPU0_PE1_RX_DP<7>")
	)
	(segment
		(start 414.69564 -18.056606)
		(end 414.344104 -18.905474)
		(width 0.14732)
		(layer "In11.Cu")
		(net "P5E_CPU0_PE1_RX_DP<7>")
	)
	(segment
		(start 360.36377 -221.404942)
		(end 360.520234 -221.133924)
		(width 0.0889)
		(layer "In11.Cu")
		(net "P5E_CPU0_PE1_RX_DP<7>")
	)
	(segment
		(start 359.392982 -219.830396)
		(end 359.402888 -219.836238)
		(width 0.0889)
		(layer "In11.Cu")
		(net "P5E_CPU0_PE1_RX_DP<7>")
	)
	(segment
		(start 359.205784 -219.475812)
		(end 359.205784 -219.514674)
		(width 0.0889)
		(layer "In11.Cu")
		(net "P5E_CPU0_PE1_RX_DP<7>")
	)
	(segment
		(start 359.675684 -218.676728)
		(end 359.675684 -218.707716)
		(width 0.0889)
		(layer "In11.Cu")
		(net "P5E_CPU0_PE1_RX_DP<7>")
	)
	(segment
		(start 410.356812 -76.79436)
		(end 408.751532 -80.10144)
		(width 0.14732)
		(layer "In11.Cu")
		(net "P5E_CPU0_PE1_RX_DP<7>")
	)
	(segment
		(start 414.402778 -15.181834)
		(end 414.451038 -15.546832)
		(width 0.14732)
		(layer "In11.Cu")
		(net "P5E_CPU0_PE1_RX_DP<7>")
	)
	(segment
		(start 359.383838 -214.941912)
		(end 359.392728 -214.946992)
		(width 0.0889)
		(layer "In11.Cu")
		(net "P5E_CPU0_PE1_RX_DP<7>")
	)
	(segment
		(start 359.393236 -215.926162)
		(end 359.384346 -215.931242)
		(width 0.0889)
		(layer "In11.Cu")
		(net "P5E_CPU0_PE1_RX_DP<7>")
	)
	(segment
		(start 408.751532 -80.10144)
		(end 362.415074 -161.94913)
		(width 0.14732)
		(layer "In11.Cu")
		(net "P5E_CPU0_PE1_RX_DP<7>")
	)
	(segment
		(start 414.451038 -15.546832)
		(end 414.613598 -15.671292)
		(width 0.14732)
		(layer "In11.Cu")
		(net "P5E_CPU0_PE1_RX_DP<7>")
	)
	(segment
		(start 359.717848 -213.253828)
		(end 359.675684 -213.295992)
		(width 0.0889)
		(layer "In11.Cu")
		(net "P5E_CPU0_PE1_RX_DP<7>")
	)
	(segment
		(start 360.285538 -221.42577)
		(end 360.36377 -221.404942)
		(width 0.0889)
		(layer "In11.Cu")
		(net "P5E_CPU0_PE1_RX_DP<7>")
	)
	(arc
		(start 359.384346 -215.931242)
		(mid 359.205749 -216.25052)
		(end 359.384346 -216.569798)
		(width 0.0889)
		(layer "In11.Cu")
		(net "P5E_CPU0_PE1_RX_DP<7>")
	)
	(arc
		(start 360.145584 -221.133924)
		(mid 360.182444 -221.295721)
		(end 360.285538 -221.42577)
		(width 0.0889)
		(layer "In11.Cu")
		(net "P5E_CPU0_PE1_RX_DP<7>")
	)
	(arc
		(start 359.384346 -217.559128)
		(mid 359.205749 -217.878406)
		(end 359.384346 -218.197684)
		(width 0.0889)
		(layer "In11.Cu")
		(net "P5E_CPU0_PE1_RX_DP<7>")
	)
	(arc
		(start 359.37571 -219.191078)
		(mid 359.251523 -219.31003)
		(end 359.205784 -219.475812)
		(width 0.0889)
		(layer "In11.Cu")
		(net "P5E_CPU0_PE1_RX_DP<7>")
	)
	(arc
		(start 359.205784 -219.514674)
		(mid 359.258054 -219.697039)
		(end 359.392982 -219.830396)
		(width 0.0889)
		(layer "In11.Cu")
		(net "P5E_CPU0_PE1_RX_DP<7>")
	)
	(arc
		(start 359.675684 -218.707716)
		(mid 359.596235 -218.981512)
		(end 359.393236 -219.18168)
		(width 0.0889)
		(layer "In11.Cu")
		(net "P5E_CPU0_PE1_RX_DP<7>")
	)
	(arc
		(start 359.863136 -220.644212)
		(mid 360.065422 -220.843193)
		(end 360.145584 -221.115382)
		(width 0.0889)
		(layer "In11.Cu")
		(net "P5E_CPU0_PE1_RX_DP<7>")
	)
	(arc
		(start 359.393236 -216.574878)
		(mid 359.597571 -216.777483)
		(end 359.675684 -217.05443)
		(width 0.0889)
		(layer "In11.Cu")
		(net "P5E_CPU0_PE1_RX_DP<7>")
	)
	(arc
		(start 359.675684 -220.319854)
		(mid 359.723363 -220.502754)
		(end 359.854246 -220.639132)
		(width 0.0889)
		(layer "In11.Cu")
		(net "P5E_CPU0_PE1_RX_DP<7>")
	)
	(arc
		(start 359.67543 -215.452198)
		(mid 359.59606 -215.725932)
		(end 359.393236 -215.926162)
		(width 0.0889)
		(layer "In11.Cu")
		(net "P5E_CPU0_PE1_RX_DP<7>")
	)
	(arc
		(start 359.675684 -217.082878)
		(mid 359.595522 -217.355067)
		(end 359.393236 -217.554048)
		(width 0.0889)
		(layer "In11.Cu")
		(net "P5E_CPU0_PE1_RX_DP<7>")
	)
	(arc
		(start 359.405174 -219.837508)
		(mid 359.603402 -220.043356)
		(end 359.675684 -220.319854)
		(width 0.0889)
		(layer "In11.Cu")
		(net "P5E_CPU0_PE1_RX_DP<7>")
	)
	(arc
		(start 359.392728 -214.946992)
		(mid 359.596209 -215.147796)
		(end 359.67543 -215.42248)
		(width 0.0889)
		(layer "In11.Cu")
		(net "P5E_CPU0_PE1_RX_DP<7>")
	)
	(arc
		(start 359.205022 -214.634064)
		(mid 359.255612 -214.810515)
		(end 359.383838 -214.941912)
		(width 0.0889)
		(layer "In11.Cu")
		(net "P5E_CPU0_PE1_RX_DP<7>")
	)
	(arc
		(start 359.393236 -218.202764)
		(mid 359.596234 -218.402933)
		(end 359.675684 -218.676728)
		(width 0.0889)
		(layer "In11.Cu")
		(net "P5E_CPU0_PE1_RX_DP<7>")
	)
	(segment
		(start 415.95675 -8.320024)
		(end 415.95675 -7.761224)
		(width 0.13208)
		(layer "F.Cu")
		(net "P5E_CPU0_PE1_RX_DP<6>")
	)
	(segment
		(start 360.990134 -220.855794)
		(end 360.98988 -220.319854)
		(width 0.13208)
		(layer "F.Cu")
		(net "P5E_CPU0_PE1_RX_DP<6>")
	)
	(segment
		(start 415.95675 -7.761224)
		(end 415.79927 -7.603744)
		(width 0.13208)
		(layer "F.Cu")
		(net "P5E_CPU0_PE1_RX_DP<6>")
	)
	(segment
		(start 415.79927 -5.255006)
		(end 416.102546 -4.95173)
		(width 0.13208)
		(layer "F.Cu")
		(net "P5E_CPU0_PE1_RX_DP<6>")
	)
	(segment
		(start 415.79927 -7.603744)
		(end 415.79927 -5.255006)
		(width 0.13208)
		(layer "F.Cu")
		(net "P5E_CPU0_PE1_RX_DP<6>")
	)
	(segment
		(start 415.80816 -12.52982)
		(end 415.977832 -13.219176)
		(width 0.14732)
		(layer "In11.Cu")
		(net "P5E_CPU0_PE1_RX_DP<6>")
	)
	(segment
		(start 360.336592 -216.577164)
		(end 360.338878 -216.578434)
		(width 0.0889)
		(layer "In11.Cu")
		(net "P5E_CPU0_PE1_RX_DP<6>")
	)
	(segment
		(start 360.657394 -214.60841)
		(end 360.657394 -214.630508)
		(width 0.0889)
		(layer "In11.Cu")
		(net "P5E_CPU0_PE1_RX_DP<6>")
	)
	(segment
		(start 417.091114 -17.742154)
		(end 417.83 -18.848324)
		(width 0.14732)
		(layer "In11.Cu")
		(net "P5E_CPU0_PE1_RX_DP<6>")
	)
	(segment
		(start 416.27806 -14.43863)
		(end 416.453574 -14.544548)
		(width 0.14732)
		(layer "In11.Cu")
		(net "P5E_CPU0_PE1_RX_DP<6>")
	)
	(segment
		(start 360.615484 -220.309948)
		(end 360.615484 -220.32849)
		(width 0.0889)
		(layer "In11.Cu")
		(net "P5E_CPU0_PE1_RX_DP<6>")
	)
	(segment
		(start 416.534092 -15.479014)
		(end 416.709606 -15.584932)
		(width 0.14732)
		(layer "In11.Cu")
		(net "P5E_CPU0_PE1_RX_DP<6>")
	)
	(segment
		(start 415.807906 -5.24637)
		(end 415.807906 -12.529566)
		(width 0.14732)
		(layer "In11.Cu")
		(net "P5E_CPU0_PE1_RX_DP<6>")
	)
	(segment
		(start 409.721558 -80.481678)
		(end 363.25048 -162.566604)
		(width 0.14732)
		(layer "In11.Cu")
		(net "P5E_CPU0_PE1_RX_DP<6>")
	)
	(segment
		(start 361.146344 -220.590872)
		(end 360.98988 -220.319854)
		(width 0.0889)
		(layer "In11.Cu")
		(net "P5E_CPU0_PE1_RX_DP<6>")
	)
	(segment
		(start 363.25048 -162.566604)
		(end 359.45064 -184.126632)
		(width 0.14732)
		(layer "In11.Cu")
		(net "P5E_CPU0_PE1_RX_DP<6>")
	)
	(segment
		(start 416.135312 -13.85824)
		(end 416.27806 -14.43863)
		(width 0.14732)
		(layer "In11.Cu")
		(net "P5E_CPU0_PE1_RX_DP<6>")
	)
	(segment
		(start 416.24123 -13.68298)
		(end 416.135312 -13.85824)
		(width 0.14732)
		(layer "In11.Cu")
		(net "P5E_CPU0_PE1_RX_DP<6>")
	)
	(segment
		(start 416.691572 -16.118078)
		(end 416.691318 -16.118332)
		(width 0.14732)
		(layer "In11.Cu")
		(net "P5E_CPU0_PE1_RX_DP<6>")
	)
	(segment
		(start 416.453574 -14.544548)
		(end 416.541458 -14.902434)
		(width 0.14732)
		(layer "In11.Cu")
		(net "P5E_CPU0_PE1_RX_DP<6>")
	)
	(segment
		(start 361.125262 -220.66885)
		(end 361.146344 -220.590872)
		(width 0.0889)
		(layer "In11.Cu")
		(net "P5E_CPU0_PE1_RX_DP<6>")
	)
	(segment
		(start 416.709606 -15.584932)
		(end 416.797744 -15.942818)
		(width 0.14732)
		(layer "In11.Cu")
		(net "P5E_CPU0_PE1_RX_DP<6>")
	)
	(segment
		(start 360.657394 -211.738972)
		(end 360.657394 -214.60841)
		(width 0.14732)
		(layer "In11.Cu")
		(net "P5E_CPU0_PE1_RX_DP<6>")
	)
	(segment
		(start 360.657394 -214.630508)
		(end 360.61523 -214.672672)
		(width 0.0889)
		(layer "In11.Cu")
		(net "P5E_CPU0_PE1_RX_DP<6>")
	)
	(segment
		(start 416.797744 -15.942818)
		(end 416.691572 -16.118078)
		(width 0.14732)
		(layer "In11.Cu")
		(net "P5E_CPU0_PE1_RX_DP<6>")
	)
	(segment
		(start 360.801158 -218.368626)
		(end 360.793792 -218.372944)
		(width 0.0889)
		(layer "In11.Cu")
		(net "P5E_CPU0_PE1_RX_DP<6>")
	)
	(segment
		(start 415.807906 -12.529566)
		(end 415.80816 -12.52982)
		(width 0.14732)
		(layer "In11.Cu")
		(net "P5E_CPU0_PE1_RX_DP<6>")
	)
	(segment
		(start 360.808778 -218.364308)
		(end 360.803444 -218.367356)
		(width 0.0889)
		(layer "In11.Cu")
		(net "P5E_CPU0_PE1_RX_DP<6>")
	)
	(segment
		(start 361.085384 -217.864182)
		(end 361.085384 -217.878406)
		(width 0.0889)
		(layer "In11.Cu")
		(net "P5E_CPU0_PE1_RX_DP<6>")
	)
	(segment
		(start 360.61523 -214.672672)
		(end 360.61523 -215.44661)
		(width 0.0889)
		(layer "In11.Cu")
		(net "P5E_CPU0_PE1_RX_DP<6>")
	)
	(segment
		(start 417.83 -18.848324)
		(end 417.83 -19.395948)
		(width 0.14732)
		(layer "In11.Cu")
		(net "P5E_CPU0_PE1_RX_DP<6>")
	)
	(segment
		(start 411.27299 -77.303122)
		(end 409.721558 -80.481678)
		(width 0.14732)
		(layer "In11.Cu")
		(net "P5E_CPU0_PE1_RX_DP<6>")
	)
	(segment
		(start 360.615484 -217.064336)
		(end 360.615484 -217.072972)
		(width 0.0889)
		(layer "In11.Cu")
		(net "P5E_CPU0_PE1_RX_DP<6>")
	)
	(segment
		(start 417.83 -19.395948)
		(end 411.27299 -77.303122)
		(width 0.14732)
		(layer "In11.Cu")
		(net "P5E_CPU0_PE1_RX_DP<6>")
	)
	(segment
		(start 360.803444 -218.367356)
		(end 360.802682 -218.367864)
		(width 0.0889)
		(layer "In11.Cu")
		(net "P5E_CPU0_PE1_RX_DP<6>")
	)
	(segment
		(start 416.541458 -14.902434)
		(end 416.43554 -15.077694)
		(width 0.14732)
		(layer "In11.Cu")
		(net "P5E_CPU0_PE1_RX_DP<6>")
	)
	(segment
		(start 360.335576 -216.576656)
		(end 360.336592 -216.577164)
		(width 0.0889)
		(layer "In11.Cu")
		(net "P5E_CPU0_PE1_RX_DP<6>")
	)
	(segment
		(start 360.33202 -219.182188)
		(end 360.324146 -219.18676)
		(width 0.0889)
		(layer "In11.Cu")
		(net "P5E_CPU0_PE1_RX_DP<6>")
	)
	(segment
		(start 416.153092 -13.325094)
		(end 416.24123 -13.68298)
		(width 0.14732)
		(layer "In11.Cu")
		(net "P5E_CPU0_PE1_RX_DP<6>")
	)
	(segment
		(start 360.333036 -219.18168)
		(end 360.33202 -219.182188)
		(width 0.0889)
		(layer "In11.Cu")
		(net "P5E_CPU0_PE1_RX_DP<6>")
	)
	(segment
		(start 360.802682 -218.367864)
		(end 360.801158 -218.368626)
		(width 0.0889)
		(layer "In11.Cu")
		(net "P5E_CPU0_PE1_RX_DP<6>")
	)
	(segment
		(start 416.102546 -4.95173)
		(end 415.807906 -5.24637)
		(width 0.14732)
		(layer "In11.Cu")
		(net "P5E_CPU0_PE1_RX_DP<6>")
	)
	(segment
		(start 360.324146 -219.825316)
		(end 360.333036 -219.830396)
		(width 0.0889)
		(layer "In11.Cu")
		(net "P5E_CPU0_PE1_RX_DP<6>")
	)
	(segment
		(start 415.977832 -13.219176)
		(end 416.153092 -13.325094)
		(width 0.14732)
		(layer "In11.Cu")
		(net "P5E_CPU0_PE1_RX_DP<6>")
	)
	(segment
		(start 416.691318 -16.118332)
		(end 417.091114 -17.742154)
		(width 0.14732)
		(layer "In11.Cu")
		(net "P5E_CPU0_PE1_RX_DP<6>")
	)
	(segment
		(start 359.45064 -184.126632)
		(end 360.657394 -211.738972)
		(width 0.14732)
		(layer "In11.Cu")
		(net "P5E_CPU0_PE1_RX_DP<6>")
	)
	(segment
		(start 416.43554 -15.077694)
		(end 416.534092 -15.479014)
		(width 0.14732)
		(layer "In11.Cu")
		(net "P5E_CPU0_PE1_RX_DP<6>")
	)
	(segment
		(start 360.332782 -216.574878)
		(end 360.335576 -216.576656)
		(width 0.0889)
		(layer "In11.Cu")
		(net "P5E_CPU0_PE1_RX_DP<6>")
	)
	(segment
		(start 360.61523 -218.692222)
		(end 360.61523 -218.707716)
		(width 0.0889)
		(layer "In11.Cu")
		(net "P5E_CPU0_PE1_RX_DP<6>")
	)
	(segment
		(start 360.145584 -216.241884)
		(end 360.145584 -216.259156)
		(width 0.0889)
		(layer "In11.Cu")
		(net "P5E_CPU0_PE1_RX_DP<6>")
	)
	(arc
		(start 360.802682 -217.388694)
		(mid 361.006163 -217.589498)
		(end 361.085384 -217.864182)
		(width 0.0889)
		(layer "In11.Cu")
		(net "P5E_CPU0_PE1_RX_DP<6>")
	)
	(arc
		(start 360.61523 -215.44661)
		(mid 360.537119 -215.723559)
		(end 360.332782 -215.926162)
		(width 0.0889)
		(layer "In11.Cu")
		(net "P5E_CPU0_PE1_RX_DP<6>")
	)
	(arc
		(start 360.145584 -219.512642)
		(mid 360.194837 -219.691842)
		(end 360.324146 -219.825316)
		(width 0.0889)
		(layer "In11.Cu")
		(net "P5E_CPU0_PE1_RX_DP<6>")
	)
	(arc
		(start 360.615484 -217.072972)
		(mid 360.667754 -217.255337)
		(end 360.802682 -217.388694)
		(width 0.0889)
		(layer "In11.Cu")
		(net "P5E_CPU0_PE1_RX_DP<6>")
	)
	(arc
		(start 361.085384 -217.878406)
		(mid 361.011393 -218.157972)
		(end 360.808778 -218.364308)
		(width 0.0889)
		(layer "In11.Cu")
		(net "P5E_CPU0_PE1_RX_DP<6>")
	)
	(arc
		(start 360.145584 -216.259156)
		(mid 360.197854 -216.441521)
		(end 360.332782 -216.574878)
		(width 0.0889)
		(layer "In11.Cu")
		(net "P5E_CPU0_PE1_RX_DP<6>")
	)
	(arc
		(start 360.793792 -218.372944)
		(mid 360.662878 -218.509304)
		(end 360.61523 -218.692222)
		(width 0.0889)
		(layer "In11.Cu")
		(net "P5E_CPU0_PE1_RX_DP<6>")
	)
	(arc
		(start 360.145584 -219.495878)
		(mid 360.14549 -219.50426)
		(end 360.145584 -219.512642)
		(width 0.0889)
		(layer "In11.Cu")
		(net "P5E_CPU0_PE1_RX_DP<6>")
	)
	(arc
		(start 360.332782 -215.926162)
		(mid 360.197849 -216.059516)
		(end 360.145584 -216.241884)
		(width 0.0889)
		(layer "In11.Cu")
		(net "P5E_CPU0_PE1_RX_DP<6>")
	)
	(arc
		(start 360.61523 -218.707716)
		(mid 360.53586 -218.98145)
		(end 360.333036 -219.18168)
		(width 0.0889)
		(layer "In11.Cu")
		(net "P5E_CPU0_PE1_RX_DP<6>")
	)
	(arc
		(start 360.615484 -220.32849)
		(mid 360.667754 -220.510855)
		(end 360.802682 -220.644212)
		(width 0.0889)
		(layer "In11.Cu")
		(net "P5E_CPU0_PE1_RX_DP<6>")
	)
	(arc
		(start 360.338878 -216.578434)
		(mid 360.541465 -216.784785)
		(end 360.615484 -217.064336)
		(width 0.0889)
		(layer "In11.Cu")
		(net "P5E_CPU0_PE1_RX_DP<6>")
	)
	(arc
		(start 360.802682 -220.644212)
		(mid 360.96117 -220.693145)
		(end 361.125262 -220.66885)
		(width 0.0889)
		(layer "In11.Cu")
		(net "P5E_CPU0_PE1_RX_DP<6>")
	)
	(arc
		(start 360.324146 -219.18676)
		(mid 360.195742 -219.318705)
		(end 360.145584 -219.495878)
		(width 0.0889)
		(layer "In11.Cu")
		(net "P5E_CPU0_PE1_RX_DP<6>")
	)
	(arc
		(start 360.333036 -219.830396)
		(mid 360.537371 -220.033001)
		(end 360.615484 -220.309948)
		(width 0.0889)
		(layer "In11.Cu")
		(net "P5E_CPU0_PE1_RX_DP<6>")
	)
	(segment
		(start 417.756848 -7.761224)
		(end 417.595558 -7.599934)
		(width 0.13208)
		(layer "F.Cu")
		(net "P5E_CPU0_PE1_RX_DP<5>")
	)
	(segment
		(start 417.756848 -8.320024)
		(end 417.756848 -7.761224)
		(width 0.13208)
		(layer "F.Cu")
		(net "P5E_CPU0_PE1_RX_DP<5>")
	)
	(segment
		(start 417.595558 -7.015734)
		(end 417.897818 -6.713474)
		(width 0.13208)
		(layer "F.Cu")
		(net "P5E_CPU0_PE1_RX_DP<5>")
	)
	(segment
		(start 362.399834 -221.669864)
		(end 362.399834 -221.133924)
		(width 0.13208)
		(layer "F.Cu")
		(net "P5E_CPU0_PE1_RX_DP<5>")
	)
	(segment
		(start 417.595558 -7.599934)
		(end 417.595558 -7.015734)
		(width 0.13208)
		(layer "F.Cu")
		(net "P5E_CPU0_PE1_RX_DP<5>")
	)
	(segment
		(start 361.742736 -218.367864)
		(end 361.741974 -218.368372)
		(width 0.0889)
		(layer "In11.Cu")
		(net "P5E_CPU0_PE1_RX_DP<5>")
	)
	(segment
		(start 360.435144 -183.896762)
		(end 361.597448 -211.795106)
		(width 0.14732)
		(layer "In11.Cu")
		(net "P5E_CPU0_PE1_RX_DP<5>")
	)
	(segment
		(start 361.739434 -218.369896)
		(end 361.733846 -218.372944)
		(width 0.0889)
		(layer "In11.Cu")
		(net "P5E_CPU0_PE1_RX_DP<5>")
	)
	(segment
		(start 419.097206 -14.920214)
		(end 419.29685 -14.966188)
		(width 0.14732)
		(layer "In11.Cu")
		(net "P5E_CPU0_PE1_RX_DP<5>")
	)
	(segment
		(start 361.597702 -214.61857)
		(end 361.597702 -214.640668)
		(width 0.0889)
		(layer "In11.Cu")
		(net "P5E_CPU0_PE1_RX_DP<5>")
	)
	(segment
		(start 361.272582 -216.574878)
		(end 361.281218 -216.579704)
		(width 0.0889)
		(layer "In11.Cu")
		(net "P5E_CPU0_PE1_RX_DP<5>")
	)
	(segment
		(start 361.597448 -211.795106)
		(end 361.597702 -211.79536)
		(width 0.14732)
		(layer "In11.Cu")
		(net "P5E_CPU0_PE1_RX_DP<5>")
	)
	(segment
		(start 362.025184 -221.115382)
		(end 362.025184 -221.133924)
		(width 0.0889)
		(layer "In11.Cu")
		(net "P5E_CPU0_PE1_RX_DP<5>")
	)
	(segment
		(start 361.741974 -218.368372)
		(end 361.739434 -218.369896)
		(width 0.0889)
		(layer "In11.Cu")
		(net "P5E_CPU0_PE1_RX_DP<5>")
	)
	(segment
		(start 420.61638 -17.345914)
		(end 420.61638 -17.88541)
		(width 0.14732)
		(layer "In11.Cu")
		(net "P5E_CPU0_PE1_RX_DP<5>")
	)
	(segment
		(start 361.733846 -220.639132)
		(end 361.742736 -220.644212)
		(width 0.0889)
		(layer "In11.Cu")
		(net "P5E_CPU0_PE1_RX_DP<5>")
	)
	(segment
		(start 361.272582 -215.926162)
		(end 361.263692 -215.931242)
		(width 0.0889)
		(layer "In11.Cu")
		(net "P5E_CPU0_PE1_RX_DP<5>")
	)
	(segment
		(start 419.49243 -15.278354)
		(end 419.446456 -15.477998)
		(width 0.14732)
		(layer "In11.Cu")
		(net "P5E_CPU0_PE1_RX_DP<5>")
	)
	(segment
		(start 364.119414 -162.999166)
		(end 364.118652 -163.000436)
		(width 0.14732)
		(layer "In11.Cu")
		(net "P5E_CPU0_PE1_RX_DP<5>")
	)
	(segment
		(start 361.272836 -219.830396)
		(end 361.278932 -219.833952)
		(width 0.0889)
		(layer "In11.Cu")
		(net "P5E_CPU0_PE1_RX_DP<5>")
	)
	(segment
		(start 415.61639 -55.271162)
		(end 412.311342 -77.870558)
		(width 0.14732)
		(layer "In11.Cu")
		(net "P5E_CPU0_PE1_RX_DP<5>")
	)
	(segment
		(start 417.683188 -12.662662)
		(end 418.509958 -13.982954)
		(width 0.14732)
		(layer "In11.Cu")
		(net "P5E_CPU0_PE1_RX_DP<5>")
	)
	(segment
		(start 361.555538 -215.445594)
		(end 361.55503 -215.44661)
		(width 0.0889)
		(layer "In11.Cu")
		(net "P5E_CPU0_PE1_RX_DP<5>")
	)
	(segment
		(start 361.263946 -219.825316)
		(end 361.272836 -219.830396)
		(width 0.0889)
		(layer "In11.Cu")
		(net "P5E_CPU0_PE1_RX_DP<5>")
	)
	(segment
		(start 418.905436 -14.341094)
		(end 418.859462 -14.540738)
		(width 0.14732)
		(layer "In11.Cu")
		(net "P5E_CPU0_PE1_RX_DP<5>")
	)
	(segment
		(start 417.603178 -12.38504)
		(end 417.683188 -12.662662)
		(width 0.14732)
		(layer "In11.Cu")
		(net "P5E_CPU0_PE1_RX_DP<5>")
	)
	(segment
		(start 419.446456 -15.477998)
		(end 420.61638 -17.345914)
		(width 0.14732)
		(layer "In11.Cu")
		(net "P5E_CPU0_PE1_RX_DP<5>")
	)
	(segment
		(start 418.859462 -14.540738)
		(end 419.097206 -14.920214)
		(width 0.14732)
		(layer "In11.Cu")
		(net "P5E_CPU0_PE1_RX_DP<5>")
	)
	(segment
		(start 361.278932 -219.178124)
		(end 361.272836 -219.18168)
		(width 0.0889)
		(layer "In11.Cu")
		(net "P5E_CPU0_PE1_RX_DP<5>")
	)
	(segment
		(start 361.281218 -216.579704)
		(end 361.282488 -216.580466)
		(width 0.0889)
		(layer "In11.Cu")
		(net "P5E_CPU0_PE1_RX_DP<5>")
	)
	(segment
		(start 417.897818 -6.713474)
		(end 417.603178 -7.008114)
		(width 0.14732)
		(layer "In11.Cu")
		(net "P5E_CPU0_PE1_RX_DP<5>")
	)
	(segment
		(start 361.597702 -214.640668)
		(end 361.555538 -214.682832)
		(width 0.0889)
		(layer "In11.Cu")
		(net "P5E_CPU0_PE1_RX_DP<5>")
	)
	(segment
		(start 364.118652 -163.000436)
		(end 364.118652 -163.000944)
		(width 0.14732)
		(layer "In11.Cu")
		(net "P5E_CPU0_PE1_RX_DP<5>")
	)
	(segment
		(start 412.311342 -77.870558)
		(end 364.11916 -162.998912)
		(width 0.14732)
		(layer "In11.Cu")
		(net "P5E_CPU0_PE1_RX_DP<5>")
	)
	(segment
		(start 419.978078 -18.840704)
		(end 419.779704 -19.493738)
		(width 0.14732)
		(layer "In11.Cu")
		(net "P5E_CPU0_PE1_RX_DP<5>")
	)
	(segment
		(start 361.733846 -217.383614)
		(end 361.742736 -217.388694)
		(width 0.0889)
		(layer "In11.Cu")
		(net "P5E_CPU0_PE1_RX_DP<5>")
	)
	(segment
		(start 361.272836 -219.18168)
		(end 361.263946 -219.18676)
		(width 0.0889)
		(layer "In11.Cu")
		(net "P5E_CPU0_PE1_RX_DP<5>")
	)
	(segment
		(start 361.555538 -214.682832)
		(end 361.555538 -215.445594)
		(width 0.0889)
		(layer "In11.Cu")
		(net "P5E_CPU0_PE1_RX_DP<5>")
	)
	(segment
		(start 361.263692 -216.569798)
		(end 361.272582 -216.574878)
		(width 0.0889)
		(layer "In11.Cu")
		(net "P5E_CPU0_PE1_RX_DP<5>")
	)
	(segment
		(start 362.025184 -217.859864)
		(end 362.025184 -217.888312)
		(width 0.0889)
		(layer "In11.Cu")
		(net "P5E_CPU0_PE1_RX_DP<5>")
	)
	(segment
		(start 361.597702 -211.79536)
		(end 361.597702 -214.61857)
		(width 0.14732)
		(layer "In11.Cu")
		(net "P5E_CPU0_PE1_RX_DP<5>")
	)
	(segment
		(start 418.509958 -13.982954)
		(end 418.709856 -14.028674)
		(width 0.14732)
		(layer "In11.Cu")
		(net "P5E_CPU0_PE1_RX_DP<5>")
	)
	(segment
		(start 362.24337 -221.404942)
		(end 362.399834 -221.133924)
		(width 0.0889)
		(layer "In11.Cu")
		(net "P5E_CPU0_PE1_RX_DP<5>")
	)
	(segment
		(start 419.779704 -19.493738)
		(end 415.61639 -55.271162)
		(width 0.14732)
		(layer "In11.Cu")
		(net "P5E_CPU0_PE1_RX_DP<5>")
	)
	(segment
		(start 362.165138 -221.42577)
		(end 362.24337 -221.404942)
		(width 0.0889)
		(layer "In11.Cu")
		(net "P5E_CPU0_PE1_RX_DP<5>")
	)
	(segment
		(start 419.29685 -14.966188)
		(end 419.49243 -15.278354)
		(width 0.14732)
		(layer "In11.Cu")
		(net "P5E_CPU0_PE1_RX_DP<5>")
	)
	(segment
		(start 361.282488 -216.580466)
		(end 361.284774 -216.58199)
		(width 0.0889)
		(layer "In11.Cu")
		(net "P5E_CPU0_PE1_RX_DP<5>")
	)
	(segment
		(start 364.118652 -163.000944)
		(end 360.435144 -183.896762)
		(width 0.14732)
		(layer "In11.Cu")
		(net "P5E_CPU0_PE1_RX_DP<5>")
	)
	(segment
		(start 418.709856 -14.028674)
		(end 418.905436 -14.341094)
		(width 0.14732)
		(layer "In11.Cu")
		(net "P5E_CPU0_PE1_RX_DP<5>")
	)
	(segment
		(start 364.11916 -162.998912)
		(end 364.119414 -162.999166)
		(width 0.14732)
		(layer "In11.Cu")
		(net "P5E_CPU0_PE1_RX_DP<5>")
	)
	(segment
		(start 420.61638 -17.88541)
		(end 419.978078 -18.840704)
		(width 0.14732)
		(layer "In11.Cu")
		(net "P5E_CPU0_PE1_RX_DP<5>")
	)
	(segment
		(start 417.603178 -7.008114)
		(end 417.603178 -12.38504)
		(width 0.14732)
		(layer "In11.Cu")
		(net "P5E_CPU0_PE1_RX_DP<5>")
	)
	(arc
		(start 361.555284 -217.064336)
		(mid 361.602963 -217.247236)
		(end 361.733846 -217.383614)
		(width 0.0889)
		(layer "In11.Cu")
		(net "P5E_CPU0_PE1_RX_DP<5>")
	)
	(arc
		(start 361.733846 -218.372944)
		(mid 361.602932 -218.509304)
		(end 361.555284 -218.692222)
		(width 0.0889)
		(layer "In11.Cu")
		(net "P5E_CPU0_PE1_RX_DP<5>")
	)
	(arc
		(start 361.742736 -220.644212)
		(mid 361.945022 -220.843193)
		(end 362.025184 -221.115382)
		(width 0.0889)
		(layer "In11.Cu")
		(net "P5E_CPU0_PE1_RX_DP<5>")
	)
	(arc
		(start 361.263946 -219.18676)
		(mid 361.08547 -219.506038)
		(end 361.263946 -219.825316)
		(width 0.0889)
		(layer "In11.Cu")
		(net "P5E_CPU0_PE1_RX_DP<5>")
	)
	(arc
		(start 361.555284 -218.692222)
		(mid 361.481368 -218.971724)
		(end 361.278932 -219.178124)
		(width 0.0889)
		(layer "In11.Cu")
		(net "P5E_CPU0_PE1_RX_DP<5>")
	)
	(arc
		(start 361.742736 -217.388694)
		(mid 361.945022 -217.587675)
		(end 362.025184 -217.859864)
		(width 0.0889)
		(layer "In11.Cu")
		(net "P5E_CPU0_PE1_RX_DP<5>")
	)
	(arc
		(start 362.025184 -217.888312)
		(mid 361.947073 -218.165261)
		(end 361.742736 -218.367864)
		(width 0.0889)
		(layer "In11.Cu")
		(net "P5E_CPU0_PE1_RX_DP<5>")
	)
	(arc
		(start 362.025184 -221.133924)
		(mid 362.062044 -221.295721)
		(end 362.165138 -221.42577)
		(width 0.0889)
		(layer "In11.Cu")
		(net "P5E_CPU0_PE1_RX_DP<5>")
	)
	(arc
		(start 361.263692 -215.931242)
		(mid 361.085095 -216.25052)
		(end 361.263692 -216.569798)
		(width 0.0889)
		(layer "In11.Cu")
		(net "P5E_CPU0_PE1_RX_DP<5>")
	)
	(arc
		(start 361.55503 -215.44661)
		(mid 361.476919 -215.723559)
		(end 361.272582 -215.926162)
		(width 0.0889)
		(layer "In11.Cu")
		(net "P5E_CPU0_PE1_RX_DP<5>")
	)
	(arc
		(start 361.284774 -216.58199)
		(mid 361.483002 -216.787838)
		(end 361.555284 -217.064336)
		(width 0.0889)
		(layer "In11.Cu")
		(net "P5E_CPU0_PE1_RX_DP<5>")
	)
	(arc
		(start 361.278932 -219.833952)
		(mid 361.481345 -220.040365)
		(end 361.555284 -220.319854)
		(width 0.0889)
		(layer "In11.Cu")
		(net "P5E_CPU0_PE1_RX_DP<5>")
	)
	(arc
		(start 361.555284 -220.319854)
		(mid 361.602963 -220.502754)
		(end 361.733846 -220.639132)
		(width 0.0889)
		(layer "In11.Cu")
		(net "P5E_CPU0_PE1_RX_DP<5>")
	)
	(segment
		(start 362.869734 -220.855794)
		(end 362.86948 -220.319854)
		(width 0.13208)
		(layer "F.Cu")
		(net "P5E_CPU0_PE1_RX_DP<4>")
	)
	(segment
		(start 419.399212 -5.255006)
		(end 419.702488 -4.95173)
		(width 0.13208)
		(layer "F.Cu")
		(net "P5E_CPU0_PE1_RX_DP<4>")
	)
	(segment
		(start 419.556946 -7.761478)
		(end 419.399212 -7.603744)
		(width 0.13208)
		(layer "F.Cu")
		(net "P5E_CPU0_PE1_RX_DP<4>")
	)
	(segment
		(start 419.399212 -7.603744)
		(end 419.399212 -5.255006)
		(width 0.13208)
		(layer "F.Cu")
		(net "P5E_CPU0_PE1_RX_DP<4>")
	)
	(segment
		(start 419.556946 -8.320024)
		(end 419.556946 -7.761478)
		(width 0.13208)
		(layer "F.Cu")
		(net "P5E_CPU0_PE1_RX_DP<4>")
	)
	(segment
		(start 362.203746 -219.825316)
		(end 362.212636 -219.830396)
		(width 0.0889)
		(layer "In11.Cu")
		(net "P5E_CPU0_PE1_RX_DP<4>")
	)
	(segment
		(start 421.508428 -15.79753)
		(end 422.815258 -18.039842)
		(width 0.14732)
		(layer "In11.Cu")
		(net "P5E_CPU0_PE1_RX_DP<4>")
	)
	(segment
		(start 423.40276 -19.47926)
		(end 421.320976 -27.898344)
		(width 0.14732)
		(layer "In11.Cu")
		(net "P5E_CPU0_PE1_RX_DP<4>")
	)
	(segment
		(start 421.375078 -15.281148)
		(end 421.560498 -15.59941)
		(width 0.14732)
		(layer "In11.Cu")
		(net "P5E_CPU0_PE1_RX_DP<4>")
	)
	(segment
		(start 420.526718 -13.826236)
		(end 420.474648 -14.024102)
		(width 0.14732)
		(layer "In11.Cu")
		(net "P5E_CPU0_PE1_RX_DP<4>")
	)
	(segment
		(start 362.964984 -217.864182)
		(end 362.964984 -217.878406)
		(width 0.0889)
		(layer "In11.Cu")
		(net "P5E_CPU0_PE1_RX_DP<4>")
	)
	(segment
		(start 362.212636 -219.18168)
		(end 362.21162 -219.182188)
		(width 0.0889)
		(layer "In11.Cu")
		(net "P5E_CPU0_PE1_RX_DP<4>")
	)
	(segment
		(start 420.474648 -14.024102)
		(end 420.660068 -14.34211)
		(width 0.14732)
		(layer "In11.Cu")
		(net "P5E_CPU0_PE1_RX_DP<4>")
	)
	(segment
		(start 362.212636 -215.926162)
		(end 362.21162 -215.92667)
		(width 0.0889)
		(layer "In11.Cu")
		(net "P5E_CPU0_PE1_RX_DP<4>")
	)
	(segment
		(start 420.341298 -13.50772)
		(end 420.526718 -13.826236)
		(width 0.14732)
		(layer "In11.Cu")
		(net "P5E_CPU0_PE1_RX_DP<4>")
	)
	(segment
		(start 363.025944 -220.590872)
		(end 362.86948 -220.319854)
		(width 0.0889)
		(layer "In11.Cu")
		(net "P5E_CPU0_PE1_RX_DP<4>")
	)
	(segment
		(start 419.702488 -4.95173)
		(end 419.407848 -5.24637)
		(width 0.14732)
		(layer "In11.Cu")
		(net "P5E_CPU0_PE1_RX_DP<4>")
	)
	(segment
		(start 363.004862 -220.66885)
		(end 363.025944 -220.590872)
		(width 0.0889)
		(layer "In11.Cu")
		(net "P5E_CPU0_PE1_RX_DP<4>")
	)
	(segment
		(start 362.495084 -215.451944)
		(end 362.49483 -215.452198)
		(width 0.0889)
		(layer "In11.Cu")
		(net "P5E_CPU0_PE1_RX_DP<4>")
	)
	(segment
		(start 421.043608 -14.712696)
		(end 420.991538 -14.910816)
		(width 0.14732)
		(layer "In11.Cu")
		(net "P5E_CPU0_PE1_RX_DP<4>")
	)
	(segment
		(start 362.688378 -218.364308)
		(end 362.673392 -218.372944)
		(width 0.0889)
		(layer "In11.Cu")
		(net "P5E_CPU0_PE1_RX_DP<4>")
	)
	(segment
		(start 362.495084 -220.309948)
		(end 362.495084 -220.32849)
		(width 0.0889)
		(layer "In11.Cu")
		(net "P5E_CPU0_PE1_RX_DP<4>")
	)
	(segment
		(start 420.143178 -13.45565)
		(end 420.341298 -13.50772)
		(width 0.14732)
		(layer "In11.Cu")
		(net "P5E_CPU0_PE1_RX_DP<4>")
	)
	(segment
		(start 362.21162 -219.182188)
		(end 362.203746 -219.18676)
		(width 0.0889)
		(layer "In11.Cu")
		(net "P5E_CPU0_PE1_RX_DP<4>")
	)
	(segment
		(start 362.495084 -217.05443)
		(end 362.495084 -217.072972)
		(width 0.0889)
		(layer "In11.Cu")
		(net "P5E_CPU0_PE1_RX_DP<4>")
	)
	(segment
		(start 362.203746 -216.569798)
		(end 362.212636 -216.574878)
		(width 0.0889)
		(layer "In11.Cu")
		(net "P5E_CPU0_PE1_RX_DP<4>")
	)
	(segment
		(start 420.660068 -14.34211)
		(end 420.858188 -14.394434)
		(width 0.14732)
		(layer "In11.Cu")
		(net "P5E_CPU0_PE1_RX_DP<4>")
	)
	(segment
		(start 362.536994 -211.986114)
		(end 362.536994 -214.61857)
		(width 0.14732)
		(layer "In11.Cu")
		(net "P5E_CPU0_PE1_RX_DP<4>")
	)
	(segment
		(start 423.40276 -18.919698)
		(end 423.40276 -19.47926)
		(width 0.14732)
		(layer "In11.Cu")
		(net "P5E_CPU0_PE1_RX_DP<4>")
	)
	(segment
		(start 419.407848 -12.194286)
		(end 420.143178 -13.45565)
		(width 0.14732)
		(layer "In11.Cu")
		(net "P5E_CPU0_PE1_RX_DP<4>")
	)
	(segment
		(start 421.320976 -27.898344)
		(end 413.347662 -78.01229)
		(width 0.14732)
		(layer "In11.Cu")
		(net "P5E_CPU0_PE1_RX_DP<4>")
	)
	(segment
		(start 413.347662 -78.01229)
		(end 364.985554 -163.44138)
		(width 0.14732)
		(layer "In11.Cu")
		(net "P5E_CPU0_PE1_RX_DP<4>")
	)
	(segment
		(start 362.536994 -214.640668)
		(end 362.495084 -214.682578)
		(width 0.0889)
		(layer "In11.Cu")
		(net "P5E_CPU0_PE1_RX_DP<4>")
	)
	(segment
		(start 362.21162 -215.92667)
		(end 362.203746 -215.931242)
		(width 0.0889)
		(layer "In11.Cu")
		(net "P5E_CPU0_PE1_RX_DP<4>")
	)
	(segment
		(start 364.985554 -163.44138)
		(end 361.372912 -183.93791)
		(width 0.14732)
		(layer "In11.Cu")
		(net "P5E_CPU0_PE1_RX_DP<4>")
	)
	(segment
		(start 421.560498 -15.59941)
		(end 421.508428 -15.79753)
		(width 0.14732)
		(layer "In11.Cu")
		(net "P5E_CPU0_PE1_RX_DP<4>")
	)
	(segment
		(start 420.858188 -14.394434)
		(end 421.043608 -14.712696)
		(width 0.14732)
		(layer "In11.Cu")
		(net "P5E_CPU0_PE1_RX_DP<4>")
	)
	(segment
		(start 362.495084 -214.682578)
		(end 362.495084 -215.451944)
		(width 0.0889)
		(layer "In11.Cu")
		(net "P5E_CPU0_PE1_RX_DP<4>")
	)
	(segment
		(start 420.991538 -14.910816)
		(end 421.176958 -15.228824)
		(width 0.14732)
		(layer "In11.Cu")
		(net "P5E_CPU0_PE1_RX_DP<4>")
	)
	(segment
		(start 421.176958 -15.228824)
		(end 421.375078 -15.281148)
		(width 0.14732)
		(layer "In11.Cu")
		(net "P5E_CPU0_PE1_RX_DP<4>")
	)
	(segment
		(start 362.49483 -218.692222)
		(end 362.49483 -218.707716)
		(width 0.0889)
		(layer "In11.Cu")
		(net "P5E_CPU0_PE1_RX_DP<4>")
	)
	(segment
		(start 362.536994 -214.61857)
		(end 362.536994 -214.640668)
		(width 0.0889)
		(layer "In11.Cu")
		(net "P5E_CPU0_PE1_RX_DP<4>")
	)
	(segment
		(start 361.372912 -183.93791)
		(end 362.536994 -211.986114)
		(width 0.14732)
		(layer "In11.Cu")
		(net "P5E_CPU0_PE1_RX_DP<4>")
	)
	(segment
		(start 419.407848 -5.24637)
		(end 419.407848 -12.194286)
		(width 0.14732)
		(layer "In11.Cu")
		(net "P5E_CPU0_PE1_RX_DP<4>")
	)
	(segment
		(start 422.815258 -18.039842)
		(end 423.40276 -18.919698)
		(width 0.14732)
		(layer "In11.Cu")
		(net "P5E_CPU0_PE1_RX_DP<4>")
	)
	(arc
		(start 362.49483 -215.452198)
		(mid 362.41546 -215.725932)
		(end 362.212636 -215.926162)
		(width 0.0889)
		(layer "In11.Cu")
		(net "P5E_CPU0_PE1_RX_DP<4>")
	)
	(arc
		(start 362.495084 -220.32849)
		(mid 362.661485 -220.631278)
		(end 363.004862 -220.66885)
		(width 0.0889)
		(layer "In11.Cu")
		(net "P5E_CPU0_PE1_RX_DP<4>")
	)
	(arc
		(start 362.682282 -217.388694)
		(mid 362.885763 -217.589498)
		(end 362.964984 -217.864182)
		(width 0.0889)
		(layer "In11.Cu")
		(net "P5E_CPU0_PE1_RX_DP<4>")
	)
	(arc
		(start 362.964984 -217.878406)
		(mid 362.890993 -218.157972)
		(end 362.688378 -218.364308)
		(width 0.0889)
		(layer "In11.Cu")
		(net "P5E_CPU0_PE1_RX_DP<4>")
	)
	(arc
		(start 362.212636 -216.574878)
		(mid 362.416971 -216.777483)
		(end 362.495084 -217.05443)
		(width 0.0889)
		(layer "In11.Cu")
		(net "P5E_CPU0_PE1_RX_DP<4>")
	)
	(arc
		(start 362.203746 -215.931242)
		(mid 362.02527 -216.25052)
		(end 362.203746 -216.569798)
		(width 0.0889)
		(layer "In11.Cu")
		(net "P5E_CPU0_PE1_RX_DP<4>")
	)
	(arc
		(start 362.673392 -218.372944)
		(mid 362.542478 -218.509304)
		(end 362.49483 -218.692222)
		(width 0.0889)
		(layer "In11.Cu")
		(net "P5E_CPU0_PE1_RX_DP<4>")
	)
	(arc
		(start 362.49483 -218.707716)
		(mid 362.41546 -218.98145)
		(end 362.212636 -219.18168)
		(width 0.0889)
		(layer "In11.Cu")
		(net "P5E_CPU0_PE1_RX_DP<4>")
	)
	(arc
		(start 362.203746 -219.18676)
		(mid 362.02527 -219.506038)
		(end 362.203746 -219.825316)
		(width 0.0889)
		(layer "In11.Cu")
		(net "P5E_CPU0_PE1_RX_DP<4>")
	)
	(arc
		(start 362.212636 -219.830396)
		(mid 362.416971 -220.033001)
		(end 362.495084 -220.309948)
		(width 0.0889)
		(layer "In11.Cu")
		(net "P5E_CPU0_PE1_RX_DP<4>")
	)
	(arc
		(start 362.495084 -217.072972)
		(mid 362.547354 -217.255337)
		(end 362.682282 -217.388694)
		(width 0.0889)
		(layer "In11.Cu")
		(net "P5E_CPU0_PE1_RX_DP<4>")
	)
	(segment
		(start 425.366942 -7.761224)
		(end 425.205652 -7.599934)
		(width 0.13208)
		(layer "F.Cu")
		(net "P5E_CPU0_PE1_RX_DP<3>")
	)
	(segment
		(start 425.205652 -7.599934)
		(end 425.205652 -7.015734)
		(width 0.13208)
		(layer "F.Cu")
		(net "P5E_CPU0_PE1_RX_DP<3>")
	)
	(segment
		(start 425.366942 -8.320024)
		(end 425.366942 -7.761224)
		(width 0.13208)
		(layer "F.Cu")
		(net "P5E_CPU0_PE1_RX_DP<3>")
	)
	(segment
		(start 425.205652 -7.015734)
		(end 425.507912 -6.713474)
		(width 0.13208)
		(layer "F.Cu")
		(net "P5E_CPU0_PE1_RX_DP<3>")
	)
	(segment
		(start 364.27918 -221.669864)
		(end 364.279434 -221.133924)
		(width 0.13208)
		(layer "F.Cu")
		(net "P5E_CPU0_PE1_RX_DP<3>")
	)
	(segment
		(start 363.620558 -218.368626)
		(end 363.618526 -218.369896)
		(width 0.0889)
		(layer "In11.Cu")
		(net "P5E_CPU0_PE1_RX_DP<3>")
	)
	(segment
		(start 363.152436 -219.830396)
		(end 363.158532 -219.833952)
		(width 0.0889)
		(layer "In11.Cu")
		(net "P5E_CPU0_PE1_RX_DP<3>")
	)
	(segment
		(start 363.904784 -217.859864)
		(end 363.904784 -217.878406)
		(width 0.0889)
		(layer "In11.Cu")
		(net "P5E_CPU0_PE1_RX_DP<3>")
	)
	(segment
		(start 362.964984 -216.241884)
		(end 362.964984 -216.259156)
		(width 0.0889)
		(layer "In11.Cu")
		(net "P5E_CPU0_PE1_RX_DP<3>")
	)
	(segment
		(start 363.904784 -221.115382)
		(end 363.904784 -221.133924)
		(width 0.0889)
		(layer "In11.Cu")
		(net "P5E_CPU0_PE1_RX_DP<3>")
	)
	(segment
		(start 425.839636 -15.727934)
		(end 426.1866 -17.46631)
		(width 0.14732)
		(layer "In11.Cu")
		(net "P5E_CPU0_PE1_RX_DP<3>")
	)
	(segment
		(start 363.613446 -220.639132)
		(end 363.622336 -220.644212)
		(width 0.0889)
		(layer "In11.Cu")
		(net "P5E_CPU0_PE1_RX_DP<3>")
	)
	(segment
		(start 363.434884 -213.930484)
		(end 363.434376 -215.120982)
		(width 0.0889)
		(layer "In11.Cu")
		(net "P5E_CPU0_PE1_RX_DP<3>")
	)
	(segment
		(start 426.1866 -18.013172)
		(end 425.539662 -18.98142)
		(width 0.14732)
		(layer "In11.Cu")
		(net "P5E_CPU0_PE1_RX_DP<3>")
	)
	(segment
		(start 363.434884 -212.958172)
		(end 363.434884 -213.930484)
		(width 0.0889)
		(layer "In11.Cu")
		(net "P5E_CPU0_PE1_RX_DP<3>")
	)
	(segment
		(start 422.321736 -28.20035)
		(end 414.397698 -78.097888)
		(width 0.14732)
		(layer "In11.Cu")
		(net "P5E_CPU0_PE1_RX_DP<3>")
	)
	(segment
		(start 425.50969 -14.076172)
		(end 425.680124 -14.18971)
		(width 0.14732)
		(layer "In11.Cu")
		(net "P5E_CPU0_PE1_RX_DP<3>")
	)
	(segment
		(start 363.43463 -218.692222)
		(end 363.43463 -218.707716)
		(width 0.0889)
		(layer "In11.Cu")
		(net "P5E_CPU0_PE1_RX_DP<3>")
	)
	(segment
		(start 425.75226 -14.551152)
		(end 425.638722 -14.721586)
		(width 0.14732)
		(layer "In11.Cu")
		(net "P5E_CPU0_PE1_RX_DP<3>")
	)
	(segment
		(start 363.434376 -215.436704)
		(end 363.43463 -215.436704)
		(width 0.0889)
		(layer "In11.Cu")
		(net "P5E_CPU0_PE1_RX_DP<3>")
	)
	(segment
		(start 363.152436 -219.18168)
		(end 363.15142 -219.182188)
		(width 0.0889)
		(layer "In11.Cu")
		(net "P5E_CPU0_PE1_RX_DP<3>")
	)
	(segment
		(start 425.710604 -15.08252)
		(end 425.881292 -15.196312)
		(width 0.14732)
		(layer "In11.Cu")
		(net "P5E_CPU0_PE1_RX_DP<3>")
	)
	(segment
		(start 364.12297 -221.404942)
		(end 364.279434 -221.133924)
		(width 0.0889)
		(layer "In11.Cu")
		(net "P5E_CPU0_PE1_RX_DP<3>")
	)
	(segment
		(start 363.615224 -218.371674)
		(end 363.613192 -218.372944)
		(width 0.0889)
		(layer "In11.Cu")
		(net "P5E_CPU0_PE1_RX_DP<3>")
	)
	(segment
		(start 365.937038 -163.700968)
		(end 362.347002 -184.06618)
		(width 0.14732)
		(layer "In11.Cu")
		(net "P5E_CPU0_PE1_RX_DP<3>")
	)
	(segment
		(start 414.397698 -78.097888)
		(end 365.937038 -163.700968)
		(width 0.14732)
		(layer "In11.Cu")
		(net "P5E_CPU0_PE1_RX_DP<3>")
	)
	(segment
		(start 363.628178 -218.364308)
		(end 363.622844 -218.367356)
		(width 0.0889)
		(layer "In11.Cu")
		(net "P5E_CPU0_PE1_RX_DP<3>")
	)
	(segment
		(start 363.477048 -210.403694)
		(end 363.477048 -212.89391)
		(width 0.14732)
		(layer "In11.Cu")
		(net "P5E_CPU0_PE1_RX_DP<3>")
	)
	(segment
		(start 363.476794 -210.40344)
		(end 363.477048 -210.403694)
		(width 0.14732)
		(layer "In11.Cu")
		(net "P5E_CPU0_PE1_RX_DP<3>")
	)
	(segment
		(start 363.613446 -217.383614)
		(end 363.622336 -217.388694)
		(width 0.0889)
		(layer "In11.Cu")
		(net "P5E_CPU0_PE1_RX_DP<3>")
	)
	(segment
		(start 425.881292 -15.196312)
		(end 425.953428 -15.557754)
		(width 0.14732)
		(layer "In11.Cu")
		(net "P5E_CPU0_PE1_RX_DP<3>")
	)
	(segment
		(start 425.953428 -15.557754)
		(end 425.839636 -15.727934)
		(width 0.14732)
		(layer "In11.Cu")
		(net "P5E_CPU0_PE1_RX_DP<3>")
	)
	(segment
		(start 363.477048 -212.916008)
		(end 363.434884 -212.958172)
		(width 0.0889)
		(layer "In11.Cu")
		(net "P5E_CPU0_PE1_RX_DP<3>")
	)
	(segment
		(start 425.638722 -14.721586)
		(end 425.710604 -15.08252)
		(width 0.14732)
		(layer "In11.Cu")
		(net "P5E_CPU0_PE1_RX_DP<3>")
	)
	(segment
		(start 363.15142 -219.182188)
		(end 363.143546 -219.18676)
		(width 0.0889)
		(layer "In11.Cu")
		(net "P5E_CPU0_PE1_RX_DP<3>")
	)
	(segment
		(start 425.213272 -12.547092)
		(end 425.222162 -12.636246)
		(width 0.14732)
		(layer "In11.Cu")
		(net "P5E_CPU0_PE1_RX_DP<3>")
	)
	(segment
		(start 425.213272 -7.008114)
		(end 425.213272 -12.547092)
		(width 0.14732)
		(layer "In11.Cu")
		(net "P5E_CPU0_PE1_RX_DP<3>")
	)
	(segment
		(start 425.539662 -18.98142)
		(end 425.504102 -19.053556)
		(width 0.14732)
		(layer "In11.Cu")
		(net "P5E_CPU0_PE1_RX_DP<3>")
	)
	(segment
		(start 363.622082 -218.367864)
		(end 363.620558 -218.368626)
		(width 0.0889)
		(layer "In11.Cu")
		(net "P5E_CPU0_PE1_RX_DP<3>")
	)
	(segment
		(start 426.1866 -17.46631)
		(end 426.1866 -18.013172)
		(width 0.14732)
		(layer "In11.Cu")
		(net "P5E_CPU0_PE1_RX_DP<3>")
	)
	(segment
		(start 363.152182 -216.574878)
		(end 363.158532 -216.578434)
		(width 0.0889)
		(layer "In11.Cu")
		(net "P5E_CPU0_PE1_RX_DP<3>")
	)
	(segment
		(start 363.477048 -212.89391)
		(end 363.477048 -212.916008)
		(width 0.0889)
		(layer "In11.Cu")
		(net "P5E_CPU0_PE1_RX_DP<3>")
	)
	(segment
		(start 364.044738 -221.42577)
		(end 364.12297 -221.404942)
		(width 0.0889)
		(layer "In11.Cu")
		(net "P5E_CPU0_PE1_RX_DP<3>")
	)
	(segment
		(start 425.507912 -6.713474)
		(end 425.213272 -7.008114)
		(width 0.14732)
		(layer "In11.Cu")
		(net "P5E_CPU0_PE1_RX_DP<3>")
	)
	(segment
		(start 425.504102 -19.053556)
		(end 422.321736 -28.20035)
		(width 0.14732)
		(layer "In11.Cu")
		(net "P5E_CPU0_PE1_RX_DP<3>")
	)
	(segment
		(start 363.43463 -215.436704)
		(end 363.43463 -215.44661)
		(width 0.0889)
		(layer "In11.Cu")
		(net "P5E_CPU0_PE1_RX_DP<3>")
	)
	(segment
		(start 362.347002 -184.06618)
		(end 363.476794 -210.40344)
		(width 0.14732)
		(layer "In11.Cu")
		(net "P5E_CPU0_PE1_RX_DP<3>")
	)
	(segment
		(start 363.622844 -218.367356)
		(end 363.622082 -218.367864)
		(width 0.0889)
		(layer "In11.Cu")
		(net "P5E_CPU0_PE1_RX_DP<3>")
	)
	(segment
		(start 363.143546 -219.825316)
		(end 363.152436 -219.830396)
		(width 0.0889)
		(layer "In11.Cu")
		(net "P5E_CPU0_PE1_RX_DP<3>")
	)
	(segment
		(start 425.680124 -14.18971)
		(end 425.75226 -14.551152)
		(width 0.14732)
		(layer "In11.Cu")
		(net "P5E_CPU0_PE1_RX_DP<3>")
	)
	(segment
		(start 363.618526 -218.369896)
		(end 363.615224 -218.371674)
		(width 0.0889)
		(layer "In11.Cu")
		(net "P5E_CPU0_PE1_RX_DP<3>")
	)
	(segment
		(start 363.434376 -215.120982)
		(end 363.434376 -215.436704)
		(width 0.0889)
		(layer "In11.Cu")
		(net "P5E_CPU0_PE1_RX_DP<3>")
	)
	(segment
		(start 425.222162 -12.636246)
		(end 425.50969 -14.076172)
		(width 0.14732)
		(layer "In11.Cu")
		(net "P5E_CPU0_PE1_RX_DP<3>")
	)
	(arc
		(start 363.158532 -219.833952)
		(mid 363.360945 -220.040365)
		(end 363.434884 -220.319854)
		(width 0.0889)
		(layer "In11.Cu")
		(net "P5E_CPU0_PE1_RX_DP<3>")
	)
	(arc
		(start 363.904784 -217.878406)
		(mid 363.830793 -218.157972)
		(end 363.628178 -218.364308)
		(width 0.0889)
		(layer "In11.Cu")
		(net "P5E_CPU0_PE1_RX_DP<3>")
	)
	(arc
		(start 363.434884 -217.064336)
		(mid 363.482563 -217.247236)
		(end 363.613446 -217.383614)
		(width 0.0889)
		(layer "In11.Cu")
		(net "P5E_CPU0_PE1_RX_DP<3>")
	)
	(arc
		(start 363.43463 -218.707716)
		(mid 363.35526 -218.98145)
		(end 363.152436 -219.18168)
		(width 0.0889)
		(layer "In11.Cu")
		(net "P5E_CPU0_PE1_RX_DP<3>")
	)
	(arc
		(start 363.152182 -215.926162)
		(mid 363.017249 -216.059516)
		(end 362.964984 -216.241884)
		(width 0.0889)
		(layer "In11.Cu")
		(net "P5E_CPU0_PE1_RX_DP<3>")
	)
	(arc
		(start 363.434884 -220.319854)
		(mid 363.482563 -220.502754)
		(end 363.613446 -220.639132)
		(width 0.0889)
		(layer "In11.Cu")
		(net "P5E_CPU0_PE1_RX_DP<3>")
	)
	(arc
		(start 362.964984 -216.259156)
		(mid 363.017254 -216.441521)
		(end 363.152182 -216.574878)
		(width 0.0889)
		(layer "In11.Cu")
		(net "P5E_CPU0_PE1_RX_DP<3>")
	)
	(arc
		(start 363.622336 -217.388694)
		(mid 363.824622 -217.587675)
		(end 363.904784 -217.859864)
		(width 0.0889)
		(layer "In11.Cu")
		(net "P5E_CPU0_PE1_RX_DP<3>")
	)
	(arc
		(start 363.613192 -218.372944)
		(mid 363.482278 -218.509304)
		(end 363.43463 -218.692222)
		(width 0.0889)
		(layer "In11.Cu")
		(net "P5E_CPU0_PE1_RX_DP<3>")
	)
	(arc
		(start 363.143546 -219.18676)
		(mid 362.96507 -219.506038)
		(end 363.143546 -219.825316)
		(width 0.0889)
		(layer "In11.Cu")
		(net "P5E_CPU0_PE1_RX_DP<3>")
	)
	(arc
		(start 363.622336 -220.644212)
		(mid 363.824622 -220.843193)
		(end 363.904784 -221.115382)
		(width 0.0889)
		(layer "In11.Cu")
		(net "P5E_CPU0_PE1_RX_DP<3>")
	)
	(arc
		(start 363.904784 -221.133924)
		(mid 363.941644 -221.295721)
		(end 364.044738 -221.42577)
		(width 0.0889)
		(layer "In11.Cu")
		(net "P5E_CPU0_PE1_RX_DP<3>")
	)
	(arc
		(start 363.43463 -215.44661)
		(mid 363.356519 -215.723559)
		(end 363.152182 -215.926162)
		(width 0.0889)
		(layer "In11.Cu")
		(net "P5E_CPU0_PE1_RX_DP<3>")
	)
	(arc
		(start 363.158532 -216.578434)
		(mid 363.360945 -216.784847)
		(end 363.434884 -217.064336)
		(width 0.0889)
		(layer "In11.Cu")
		(net "P5E_CPU0_PE1_RX_DP<3>")
	)
	(segment
		(start 427.166786 -7.761224)
		(end 427.009306 -7.603744)
		(width 0.13208)
		(layer "F.Cu")
		(net "P5E_CPU0_PE1_RX_DP<2>")
	)
	(segment
		(start 427.009306 -5.255006)
		(end 427.312582 -4.95173)
		(width 0.13208)
		(layer "F.Cu")
		(net "P5E_CPU0_PE1_RX_DP<2>")
	)
	(segment
		(start 427.166786 -8.320024)
		(end 427.166786 -7.761224)
		(width 0.13208)
		(layer "F.Cu")
		(net "P5E_CPU0_PE1_RX_DP<2>")
	)
	(segment
		(start 427.009306 -7.603744)
		(end 427.009306 -5.255006)
		(width 0.13208)
		(layer "F.Cu")
		(net "P5E_CPU0_PE1_RX_DP<2>")
	)
	(segment
		(start 364.749334 -220.855794)
		(end 364.74908 -220.319854)
		(width 0.13208)
		(layer "F.Cu")
		(net "P5E_CPU0_PE1_RX_DP<2>")
	)
	(segment
		(start 364.092236 -219.830396)
		(end 364.083346 -219.825316)
		(width 0.0889)
		(layer "In11.Cu")
		(net "P5E_CPU0_PE1_RX_DP<2>")
	)
	(segment
		(start 427.582838 -14.676882)
		(end 427.480984 -14.252702)
		(width 0.14732)
		(layer "In11.Cu")
		(net "P5E_CPU0_PE1_RX_DP<2>")
	)
	(segment
		(start 364.416848 -212.916008)
		(end 364.416848 -212.89391)
		(width 0.0889)
		(layer "In11.Cu")
		(net "P5E_CPU0_PE1_RX_DP<2>")
	)
	(segment
		(start 364.562644 -218.367356)
		(end 364.567978 -218.364308)
		(width 0.0889)
		(layer "In11.Cu")
		(net "P5E_CPU0_PE1_RX_DP<2>")
	)
	(segment
		(start 429.0187 -18.768314)
		(end 428.313088 -17.712182)
		(width 0.14732)
		(layer "In11.Cu")
		(net "P5E_CPU0_PE1_RX_DP<2>")
	)
	(segment
		(start 364.374176 -215.120982)
		(end 364.374684 -213.929468)
		(width 0.0889)
		(layer "In11.Cu")
		(net "P5E_CPU0_PE1_RX_DP<2>")
	)
	(segment
		(start 364.083346 -215.931242)
		(end 364.09122 -215.92667)
		(width 0.0889)
		(layer "In11.Cu")
		(net "P5E_CPU0_PE1_RX_DP<2>")
	)
	(segment
		(start 364.416848 -212.89391)
		(end 364.416848 -210.341972)
		(width 0.14732)
		(layer "In11.Cu")
		(net "P5E_CPU0_PE1_RX_DP<2>")
	)
	(segment
		(start 427.757844 -14.783562)
		(end 427.582838 -14.676882)
		(width 0.14732)
		(layer "In11.Cu")
		(net "P5E_CPU0_PE1_RX_DP<2>")
	)
	(segment
		(start 415.282888 -78.472792)
		(end 423.418 -28.461716)
		(width 0.14732)
		(layer "In11.Cu")
		(net "P5E_CPU0_PE1_RX_DP<2>")
	)
	(segment
		(start 429.0187 -19.393916)
		(end 429.0187 -18.768314)
		(width 0.14732)
		(layer "In11.Cu")
		(net "P5E_CPU0_PE1_RX_DP<2>")
	)
	(segment
		(start 364.374684 -213.929468)
		(end 364.374684 -212.958172)
		(width 0.0889)
		(layer "In11.Cu")
		(net "P5E_CPU0_PE1_RX_DP<2>")
	)
	(segment
		(start 427.587918 -14.078204)
		(end 427.501812 -13.71981)
		(width 0.14732)
		(layer "In11.Cu")
		(net "P5E_CPU0_PE1_RX_DP<2>")
	)
	(segment
		(start 427.480984 -14.252702)
		(end 427.587918 -14.078204)
		(width 0.14732)
		(layer "In11.Cu")
		(net "P5E_CPU0_PE1_RX_DP<2>")
	)
	(segment
		(start 364.416594 -210.341718)
		(end 363.297724 -184.1373)
		(width 0.14732)
		(layer "In11.Cu")
		(net "P5E_CPU0_PE1_RX_DP<2>")
	)
	(segment
		(start 428.04461 -16.595598)
		(end 428.151544 -16.420846)
		(width 0.14732)
		(layer "In11.Cu")
		(net "P5E_CPU0_PE1_RX_DP<2>")
	)
	(segment
		(start 428.81169 -19.893026)
		(end 429.0187 -19.393916)
		(width 0.14732)
		(layer "In11.Cu")
		(net "P5E_CPU0_PE1_RX_DP<2>")
	)
	(segment
		(start 364.905544 -220.590872)
		(end 364.884462 -220.66885)
		(width 0.0889)
		(layer "In11.Cu")
		(net "P5E_CPU0_PE1_RX_DP<2>")
	)
	(segment
		(start 427.32706 -13.612876)
		(end 427.017942 -12.327636)
		(width 0.14732)
		(layer "In11.Cu")
		(net "P5E_CPU0_PE1_RX_DP<2>")
	)
	(segment
		(start 427.84395 -15.141956)
		(end 427.757844 -14.783562)
		(width 0.14732)
		(layer "In11.Cu")
		(net "P5E_CPU0_PE1_RX_DP<2>")
	)
	(segment
		(start 426.462952 -23.359364)
		(end 428.81169 -19.893026)
		(width 0.14732)
		(layer "In11.Cu")
		(net "P5E_CPU0_PE1_RX_DP<2>")
	)
	(segment
		(start 363.297724 -184.1373)
		(end 366.839246 -164.047424)
		(width 0.14732)
		(layer "In11.Cu")
		(net "P5E_CPU0_PE1_RX_DP<2>")
	)
	(segment
		(start 364.37443 -215.452198)
		(end 364.37443 -215.436704)
		(width 0.0889)
		(layer "In11.Cu")
		(net "P5E_CPU0_PE1_RX_DP<2>")
	)
	(segment
		(start 364.09122 -219.182188)
		(end 364.092236 -219.18168)
		(width 0.0889)
		(layer "In11.Cu")
		(net "P5E_CPU0_PE1_RX_DP<2>")
	)
	(segment
		(start 428.065438 -16.062706)
		(end 427.890686 -15.955772)
		(width 0.14732)
		(layer "In11.Cu")
		(net "P5E_CPU0_PE1_RX_DP<2>")
	)
	(segment
		(start 364.37443 -215.436704)
		(end 364.374176 -215.436704)
		(width 0.0889)
		(layer "In11.Cu")
		(net "P5E_CPU0_PE1_RX_DP<2>")
	)
	(segment
		(start 364.37443 -218.707716)
		(end 364.37443 -218.692222)
		(width 0.0889)
		(layer "In11.Cu")
		(net "P5E_CPU0_PE1_RX_DP<2>")
	)
	(segment
		(start 364.74908 -220.319854)
		(end 364.905544 -220.590872)
		(width 0.0889)
		(layer "In11.Cu")
		(net "P5E_CPU0_PE1_RX_DP<2>")
	)
	(segment
		(start 364.844584 -217.878406)
		(end 364.844584 -217.864182)
		(width 0.0889)
		(layer "In11.Cu")
		(net "P5E_CPU0_PE1_RX_DP<2>")
	)
	(segment
		(start 424.14444 -26.780998)
		(end 426.462952 -23.359364)
		(width 0.14732)
		(layer "In11.Cu")
		(net "P5E_CPU0_PE1_RX_DP<2>")
	)
	(segment
		(start 366.839246 -164.047424)
		(end 415.282888 -78.472792)
		(width 0.14732)
		(layer "In11.Cu")
		(net "P5E_CPU0_PE1_RX_DP<2>")
	)
	(segment
		(start 427.890686 -15.955772)
		(end 427.737016 -15.316708)
		(width 0.14732)
		(layer "In11.Cu")
		(net "P5E_CPU0_PE1_RX_DP<2>")
	)
	(segment
		(start 364.083346 -219.18676)
		(end 364.09122 -219.182188)
		(width 0.0889)
		(layer "In11.Cu")
		(net "P5E_CPU0_PE1_RX_DP<2>")
	)
	(segment
		(start 427.737016 -15.316708)
		(end 427.84395 -15.141956)
		(width 0.14732)
		(layer "In11.Cu")
		(net "P5E_CPU0_PE1_RX_DP<2>")
	)
	(segment
		(start 427.017942 -12.327636)
		(end 427.017942 -5.24637)
		(width 0.14732)
		(layer "In11.Cu")
		(net "P5E_CPU0_PE1_RX_DP<2>")
	)
	(segment
		(start 364.374176 -215.436704)
		(end 364.374176 -215.120982)
		(width 0.0889)
		(layer "In11.Cu")
		(net "P5E_CPU0_PE1_RX_DP<2>")
	)
	(segment
		(start 423.418 -28.461716)
		(end 424.14444 -26.780998)
		(width 0.14732)
		(layer "In11.Cu")
		(net "P5E_CPU0_PE1_RX_DP<2>")
	)
	(segment
		(start 364.374684 -212.958172)
		(end 364.416848 -212.916008)
		(width 0.0889)
		(layer "In11.Cu")
		(net "P5E_CPU0_PE1_RX_DP<2>")
	)
	(segment
		(start 364.561882 -218.367864)
		(end 364.562644 -218.367356)
		(width 0.0889)
		(layer "In11.Cu")
		(net "P5E_CPU0_PE1_RX_DP<2>")
	)
	(segment
		(start 428.313088 -17.712182)
		(end 428.04461 -16.595598)
		(width 0.14732)
		(layer "In11.Cu")
		(net "P5E_CPU0_PE1_RX_DP<2>")
	)
	(segment
		(start 364.374684 -220.32849)
		(end 364.374684 -220.309948)
		(width 0.0889)
		(layer "In11.Cu")
		(net "P5E_CPU0_PE1_RX_DP<2>")
	)
	(segment
		(start 427.017942 -5.24637)
		(end 427.312582 -4.95173)
		(width 0.14732)
		(layer "In11.Cu")
		(net "P5E_CPU0_PE1_RX_DP<2>")
	)
	(segment
		(start 364.092236 -216.574878)
		(end 364.083346 -216.569798)
		(width 0.0889)
		(layer "In11.Cu")
		(net "P5E_CPU0_PE1_RX_DP<2>")
	)
	(segment
		(start 364.552992 -218.372944)
		(end 364.560358 -218.368626)
		(width 0.0889)
		(layer "In11.Cu")
		(net "P5E_CPU0_PE1_RX_DP<2>")
	)
	(segment
		(start 427.501812 -13.71981)
		(end 427.32706 -13.612876)
		(width 0.14732)
		(layer "In11.Cu")
		(net "P5E_CPU0_PE1_RX_DP<2>")
	)
	(segment
		(start 364.374684 -217.072972)
		(end 364.374684 -217.05443)
		(width 0.0889)
		(layer "In11.Cu")
		(net "P5E_CPU0_PE1_RX_DP<2>")
	)
	(segment
		(start 364.560358 -218.368626)
		(end 364.561882 -218.367864)
		(width 0.0889)
		(layer "In11.Cu")
		(net "P5E_CPU0_PE1_RX_DP<2>")
	)
	(segment
		(start 364.416848 -210.341972)
		(end 364.416594 -210.341718)
		(width 0.14732)
		(layer "In11.Cu")
		(net "P5E_CPU0_PE1_RX_DP<2>")
	)
	(segment
		(start 364.09122 -215.92667)
		(end 364.092236 -215.926162)
		(width 0.0889)
		(layer "In11.Cu")
		(net "P5E_CPU0_PE1_RX_DP<2>")
	)
	(segment
		(start 428.151544 -16.420846)
		(end 428.065438 -16.062706)
		(width 0.14732)
		(layer "In11.Cu")
		(net "P5E_CPU0_PE1_RX_DP<2>")
	)
	(arc
		(start 364.561882 -217.388694)
		(mid 364.426949 -217.25534)
		(end 364.374684 -217.072972)
		(width 0.0889)
		(layer "In11.Cu")
		(net "P5E_CPU0_PE1_RX_DP<2>")
	)
	(arc
		(start 363.905038 -219.495878)
		(mid 363.955053 -219.318747)
		(end 364.083346 -219.18676)
		(width 0.0889)
		(layer "In11.Cu")
		(net "P5E_CPU0_PE1_RX_DP<2>")
	)
	(arc
		(start 364.374684 -217.05443)
		(mid 364.296573 -216.777481)
		(end 364.092236 -216.574878)
		(width 0.0889)
		(layer "In11.Cu")
		(net "P5E_CPU0_PE1_RX_DP<2>")
	)
	(arc
		(start 363.905038 -216.24036)
		(mid 363.955053 -216.063229)
		(end 364.083346 -215.931242)
		(width 0.0889)
		(layer "In11.Cu")
		(net "P5E_CPU0_PE1_RX_DP<2>")
	)
	(arc
		(start 364.561882 -220.644212)
		(mid 364.426949 -220.510858)
		(end 364.374684 -220.32849)
		(width 0.0889)
		(layer "In11.Cu")
		(net "P5E_CPU0_PE1_RX_DP<2>")
	)
	(arc
		(start 364.37443 -218.692222)
		(mid 364.422109 -218.509322)
		(end 364.552992 -218.372944)
		(width 0.0889)
		(layer "In11.Cu")
		(net "P5E_CPU0_PE1_RX_DP<2>")
	)
	(arc
		(start 364.083346 -216.569798)
		(mid 363.954142 -216.436284)
		(end 363.905038 -216.257124)
		(width 0.0889)
		(layer "In11.Cu")
		(net "P5E_CPU0_PE1_RX_DP<2>")
	)
	(arc
		(start 363.905038 -216.257124)
		(mid 363.904944 -216.248742)
		(end 363.905038 -216.24036)
		(width 0.0889)
		(layer "In11.Cu")
		(net "P5E_CPU0_PE1_RX_DP<2>")
	)
	(arc
		(start 364.374684 -220.309948)
		(mid 364.296573 -220.032999)
		(end 364.092236 -219.830396)
		(width 0.0889)
		(layer "In11.Cu")
		(net "P5E_CPU0_PE1_RX_DP<2>")
	)
	(arc
		(start 364.884462 -220.66885)
		(mid 364.720366 -220.693197)
		(end 364.561882 -220.644212)
		(width 0.0889)
		(layer "In11.Cu")
		(net "P5E_CPU0_PE1_RX_DP<2>")
	)
	(arc
		(start 364.844584 -217.864182)
		(mid 364.765365 -217.589497)
		(end 364.561882 -217.388694)
		(width 0.0889)
		(layer "In11.Cu")
		(net "P5E_CPU0_PE1_RX_DP<2>")
	)
	(arc
		(start 363.905038 -219.512642)
		(mid 363.904944 -219.50426)
		(end 363.905038 -219.495878)
		(width 0.0889)
		(layer "In11.Cu")
		(net "P5E_CPU0_PE1_RX_DP<2>")
	)
	(arc
		(start 364.567978 -218.364308)
		(mid 364.770565 -218.157957)
		(end 364.844584 -217.878406)
		(width 0.0889)
		(layer "In11.Cu")
		(net "P5E_CPU0_PE1_RX_DP<2>")
	)
	(arc
		(start 364.092236 -215.926162)
		(mid 364.295059 -215.725931)
		(end 364.37443 -215.452198)
		(width 0.0889)
		(layer "In11.Cu")
		(net "P5E_CPU0_PE1_RX_DP<2>")
	)
	(arc
		(start 364.092236 -219.18168)
		(mid 364.295059 -218.981449)
		(end 364.37443 -218.707716)
		(width 0.0889)
		(layer "In11.Cu")
		(net "P5E_CPU0_PE1_RX_DP<2>")
	)
	(arc
		(start 364.083346 -219.825316)
		(mid 363.954142 -219.691802)
		(end 363.905038 -219.512642)
		(width 0.0889)
		(layer "In11.Cu")
		(net "P5E_CPU0_PE1_RX_DP<2>")
	)
	(segment
		(start 428.805594 -7.015734)
		(end 429.107854 -6.713474)
		(width 0.13208)
		(layer "F.Cu")
		(net "P5E_CPU0_PE1_RX_DP<1>")
	)
	(segment
		(start 428.966884 -8.320024)
		(end 428.966884 -7.761224)
		(width 0.13208)
		(layer "F.Cu")
		(net "P5E_CPU0_PE1_RX_DP<1>")
	)
	(segment
		(start 366.15878 -221.669864)
		(end 366.159034 -221.133924)
		(width 0.13208)
		(layer "F.Cu")
		(net "P5E_CPU0_PE1_RX_DP<1>")
	)
	(segment
		(start 428.805594 -7.599934)
		(end 428.805594 -7.015734)
		(width 0.13208)
		(layer "F.Cu")
		(net "P5E_CPU0_PE1_RX_DP<1>")
	)
	(segment
		(start 428.966884 -7.761224)
		(end 428.805594 -7.599934)
		(width 0.13208)
		(layer "F.Cu")
		(net "P5E_CPU0_PE1_RX_DP<1>")
	)
	(segment
		(start 429.983646 -14.184376)
		(end 430.183798 -14.228572)
		(width 0.14732)
		(layer "In11.Cu")
		(net "P5E_CPU0_PE1_RX_DP<1>")
	)
	(segment
		(start 365.03102 -215.92667)
		(end 365.023146 -215.931242)
		(width 0.0889)
		(layer "In11.Cu")
		(net "P5E_CPU0_PE1_RX_DP<1>")
	)
	(segment
		(start 430.381918 -14.539214)
		(end 430.337722 -14.739112)
		(width 0.14732)
		(layer "In11.Cu")
		(net "P5E_CPU0_PE1_RX_DP<1>")
	)
	(segment
		(start 428.813214 -7.008114)
		(end 428.813214 -12.350242)
		(width 0.14732)
		(layer "In11.Cu")
		(net "P5E_CPU0_PE1_RX_DP<1>")
	)
	(segment
		(start 365.023146 -219.825316)
		(end 365.032036 -219.830396)
		(width 0.0889)
		(layer "In11.Cu")
		(net "P5E_CPU0_PE1_RX_DP<1>")
	)
	(segment
		(start 365.032036 -219.830396)
		(end 365.038132 -219.833952)
		(width 0.0889)
		(layer "In11.Cu")
		(net "P5E_CPU0_PE1_RX_DP<1>")
	)
	(segment
		(start 365.31423 -215.436704)
		(end 365.31423 -215.452198)
		(width 0.0889)
		(layer "In11.Cu")
		(net "P5E_CPU0_PE1_RX_DP<1>")
	)
	(segment
		(start 365.493046 -217.383614)
		(end 365.501936 -217.388694)
		(width 0.0889)
		(layer "In11.Cu")
		(net "P5E_CPU0_PE1_RX_DP<1>")
	)
	(segment
		(start 365.784384 -221.115382)
		(end 365.784384 -221.133924)
		(width 0.0889)
		(layer "In11.Cu")
		(net "P5E_CPU0_PE1_RX_DP<1>")
	)
	(segment
		(start 365.507778 -218.364308)
		(end 365.502444 -218.367356)
		(width 0.0889)
		(layer "In11.Cu")
		(net "P5E_CPU0_PE1_RX_DP<1>")
	)
	(segment
		(start 365.356394 -212.110574)
		(end 365.356394 -212.90407)
		(width 0.14732)
		(layer "In11.Cu")
		(net "P5E_CPU0_PE1_RX_DP<1>")
	)
	(segment
		(start 430.337722 -14.739112)
		(end 430.629568 -15.196312)
		(width 0.14732)
		(layer "In11.Cu")
		(net "P5E_CPU0_PE1_RX_DP<1>")
	)
	(segment
		(start 366.00257 -221.404942)
		(end 366.159034 -221.133924)
		(width 0.0889)
		(layer "In11.Cu")
		(net "P5E_CPU0_PE1_RX_DP<1>")
	)
	(segment
		(start 365.356394 -212.926168)
		(end 365.31423 -212.968332)
		(width 0.0889)
		(layer "In11.Cu")
		(net "P5E_CPU0_PE1_RX_DP<1>")
	)
	(segment
		(start 429.107854 -6.713474)
		(end 428.813214 -7.008114)
		(width 0.14732)
		(layer "In11.Cu")
		(net "P5E_CPU0_PE1_RX_DP<1>")
	)
	(segment
		(start 365.023146 -216.569798)
		(end 365.032036 -216.574878)
		(width 0.0889)
		(layer "In11.Cu")
		(net "P5E_CPU0_PE1_RX_DP<1>")
	)
	(segment
		(start 365.498126 -218.369896)
		(end 365.494824 -218.371674)
		(width 0.0889)
		(layer "In11.Cu")
		(net "P5E_CPU0_PE1_RX_DP<1>")
	)
	(segment
		(start 430.962562 -19.134074)
		(end 425.074334 -27.333956)
		(width 0.14732)
		(layer "In11.Cu")
		(net "P5E_CPU0_PE1_RX_DP<1>")
	)
	(segment
		(start 430.183798 -14.228572)
		(end 430.381918 -14.539214)
		(width 0.14732)
		(layer "In11.Cu")
		(net "P5E_CPU0_PE1_RX_DP<1>")
	)
	(segment
		(start 425.074334 -27.333956)
		(end 424.457368 -28.599892)
		(width 0.14732)
		(layer "In11.Cu")
		(net "P5E_CPU0_PE1_RX_DP<1>")
	)
	(segment
		(start 365.032036 -219.18168)
		(end 365.03102 -219.182188)
		(width 0.0889)
		(layer "In11.Cu")
		(net "P5E_CPU0_PE1_RX_DP<1>")
	)
	(segment
		(start 365.03102 -219.182188)
		(end 365.023146 -219.18676)
		(width 0.0889)
		(layer "In11.Cu")
		(net "P5E_CPU0_PE1_RX_DP<1>")
	)
	(segment
		(start 365.501682 -218.367864)
		(end 365.500158 -218.368626)
		(width 0.0889)
		(layer "In11.Cu")
		(net "P5E_CPU0_PE1_RX_DP<1>")
	)
	(segment
		(start 365.31423 -212.968332)
		(end 365.31423 -213.930738)
		(width 0.0889)
		(layer "In11.Cu")
		(net "P5E_CPU0_PE1_RX_DP<1>")
	)
	(segment
		(start 431.02784 -15.551404)
		(end 430.983644 -15.751302)
		(width 0.14732)
		(layer "In11.Cu")
		(net "P5E_CPU0_PE1_RX_DP<1>")
	)
	(segment
		(start 367.108994 -185.714386)
		(end 365.35614 -212.11032)
		(width 0.14732)
		(layer "In11.Cu")
		(net "P5E_CPU0_PE1_RX_DP<1>")
	)
	(segment
		(start 365.500158 -218.368626)
		(end 365.498126 -218.369896)
		(width 0.0889)
		(layer "In11.Cu")
		(net "P5E_CPU0_PE1_RX_DP<1>")
	)
	(segment
		(start 416.3187 -78.609698)
		(end 368.027966 -163.909248)
		(width 0.14732)
		(layer "In11.Cu")
		(net "P5E_CPU0_PE1_RX_DP<1>")
	)
	(segment
		(start 430.82972 -15.240508)
		(end 431.02784 -15.551404)
		(width 0.14732)
		(layer "In11.Cu")
		(net "P5E_CPU0_PE1_RX_DP<1>")
	)
	(segment
		(start 430.983644 -15.751302)
		(end 431.80762 -17.042638)
		(width 0.14732)
		(layer "In11.Cu")
		(net "P5E_CPU0_PE1_RX_DP<1>")
	)
	(segment
		(start 365.032036 -215.926162)
		(end 365.03102 -215.92667)
		(width 0.0889)
		(layer "In11.Cu")
		(net "P5E_CPU0_PE1_RX_DP<1>")
	)
	(segment
		(start 365.313976 -215.120982)
		(end 365.313976 -215.436704)
		(width 0.0889)
		(layer "In11.Cu")
		(net "P5E_CPU0_PE1_RX_DP<1>")
	)
	(segment
		(start 365.313976 -215.436704)
		(end 365.31423 -215.436704)
		(width 0.0889)
		(layer "In11.Cu")
		(net "P5E_CPU0_PE1_RX_DP<1>")
	)
	(segment
		(start 365.924338 -221.42577)
		(end 366.00257 -221.404942)
		(width 0.0889)
		(layer "In11.Cu")
		(net "P5E_CPU0_PE1_RX_DP<1>")
	)
	(segment
		(start 365.31423 -213.930738)
		(end 365.313976 -215.120982)
		(width 0.0889)
		(layer "In11.Cu")
		(net "P5E_CPU0_PE1_RX_DP<1>")
	)
	(segment
		(start 368.027966 -163.909248)
		(end 367.108994 -185.714386)
		(width 0.14732)
		(layer "In11.Cu")
		(net "P5E_CPU0_PE1_RX_DP<1>")
	)
	(segment
		(start 365.494824 -218.371674)
		(end 365.492792 -218.372944)
		(width 0.0889)
		(layer "In11.Cu")
		(net "P5E_CPU0_PE1_RX_DP<1>")
	)
	(segment
		(start 430.629568 -15.196312)
		(end 430.82972 -15.240508)
		(width 0.14732)
		(layer "In11.Cu")
		(net "P5E_CPU0_PE1_RX_DP<1>")
	)
	(segment
		(start 365.493046 -220.639132)
		(end 365.501936 -220.644212)
		(width 0.0889)
		(layer "In11.Cu")
		(net "P5E_CPU0_PE1_RX_DP<1>")
	)
	(segment
		(start 428.813214 -12.350242)
		(end 429.983646 -14.184376)
		(width 0.14732)
		(layer "In11.Cu")
		(net "P5E_CPU0_PE1_RX_DP<1>")
	)
	(segment
		(start 365.356394 -212.90407)
		(end 365.356394 -212.926168)
		(width 0.0889)
		(layer "In11.Cu")
		(net "P5E_CPU0_PE1_RX_DP<1>")
	)
	(segment
		(start 365.032036 -216.574878)
		(end 365.038132 -216.578434)
		(width 0.0889)
		(layer "In11.Cu")
		(net "P5E_CPU0_PE1_RX_DP<1>")
	)
	(segment
		(start 365.502444 -218.367356)
		(end 365.501682 -218.367864)
		(width 0.0889)
		(layer "In11.Cu")
		(net "P5E_CPU0_PE1_RX_DP<1>")
	)
	(segment
		(start 431.80762 -17.042638)
		(end 431.80762 -17.869916)
		(width 0.14732)
		(layer "In11.Cu")
		(net "P5E_CPU0_PE1_RX_DP<1>")
	)
	(segment
		(start 424.457368 -28.599892)
		(end 416.3187 -78.609698)
		(width 0.14732)
		(layer "In11.Cu")
		(net "P5E_CPU0_PE1_RX_DP<1>")
	)
	(segment
		(start 365.35614 -212.11032)
		(end 365.356394 -212.110574)
		(width 0.14732)
		(layer "In11.Cu")
		(net "P5E_CPU0_PE1_RX_DP<1>")
	)
	(segment
		(start 431.80762 -17.869916)
		(end 430.962562 -19.134074)
		(width 0.14732)
		(layer "In11.Cu")
		(net "P5E_CPU0_PE1_RX_DP<1>")
	)
	(segment
		(start 365.31423 -218.692222)
		(end 365.31423 -218.707716)
		(width 0.0889)
		(layer "In11.Cu")
		(net "P5E_CPU0_PE1_RX_DP<1>")
	)
	(segment
		(start 365.784384 -217.859864)
		(end 365.784384 -217.878406)
		(width 0.0889)
		(layer "In11.Cu")
		(net "P5E_CPU0_PE1_RX_DP<1>")
	)
	(arc
		(start 365.501936 -217.388694)
		(mid 365.704222 -217.587675)
		(end 365.784384 -217.859864)
		(width 0.0889)
		(layer "In11.Cu")
		(net "P5E_CPU0_PE1_RX_DP<1>")
	)
	(arc
		(start 365.501936 -220.644212)
		(mid 365.704222 -220.843193)
		(end 365.784384 -221.115382)
		(width 0.0889)
		(layer "In11.Cu")
		(net "P5E_CPU0_PE1_RX_DP<1>")
	)
	(arc
		(start 365.314484 -220.319854)
		(mid 365.362163 -220.502754)
		(end 365.493046 -220.639132)
		(width 0.0889)
		(layer "In11.Cu")
		(net "P5E_CPU0_PE1_RX_DP<1>")
	)
	(arc
		(start 365.784384 -217.878406)
		(mid 365.710393 -218.157972)
		(end 365.507778 -218.364308)
		(width 0.0889)
		(layer "In11.Cu")
		(net "P5E_CPU0_PE1_RX_DP<1>")
	)
	(arc
		(start 365.492792 -218.372944)
		(mid 365.361878 -218.509304)
		(end 365.31423 -218.692222)
		(width 0.0889)
		(layer "In11.Cu")
		(net "P5E_CPU0_PE1_RX_DP<1>")
	)
	(arc
		(start 365.31423 -215.452198)
		(mid 365.23486 -215.725932)
		(end 365.032036 -215.926162)
		(width 0.0889)
		(layer "In11.Cu")
		(net "P5E_CPU0_PE1_RX_DP<1>")
	)
	(arc
		(start 365.023146 -215.931242)
		(mid 364.84467 -216.25052)
		(end 365.023146 -216.569798)
		(width 0.0889)
		(layer "In11.Cu")
		(net "P5E_CPU0_PE1_RX_DP<1>")
	)
	(arc
		(start 365.038132 -216.578434)
		(mid 365.240545 -216.784847)
		(end 365.314484 -217.064336)
		(width 0.0889)
		(layer "In11.Cu")
		(net "P5E_CPU0_PE1_RX_DP<1>")
	)
	(arc
		(start 365.31423 -218.707716)
		(mid 365.23486 -218.98145)
		(end 365.032036 -219.18168)
		(width 0.0889)
		(layer "In11.Cu")
		(net "P5E_CPU0_PE1_RX_DP<1>")
	)
	(arc
		(start 365.784384 -221.133924)
		(mid 365.821244 -221.295721)
		(end 365.924338 -221.42577)
		(width 0.0889)
		(layer "In11.Cu")
		(net "P5E_CPU0_PE1_RX_DP<1>")
	)
	(arc
		(start 365.314484 -217.064336)
		(mid 365.362163 -217.247236)
		(end 365.493046 -217.383614)
		(width 0.0889)
		(layer "In11.Cu")
		(net "P5E_CPU0_PE1_RX_DP<1>")
	)
	(arc
		(start 365.023146 -219.18676)
		(mid 364.84467 -219.506038)
		(end 365.023146 -219.825316)
		(width 0.0889)
		(layer "In11.Cu")
		(net "P5E_CPU0_PE1_RX_DP<1>")
	)
	(arc
		(start 365.038132 -219.833952)
		(mid 365.240545 -220.040365)
		(end 365.314484 -220.319854)
		(width 0.0889)
		(layer "In11.Cu")
		(net "P5E_CPU0_PE1_RX_DP<1>")
	)
	(segment
		(start 394.085572 -7.599934)
		(end 394.085572 -7.015734)
		(width 0.13208)
		(layer "F.Cu")
		(net "P5E_CPU0_PE1_RX_DP<15>")
	)
	(segment
		(start 353.00158 -221.669864)
		(end 353.001834 -221.133924)
		(width 0.13208)
		(layer "F.Cu")
		(net "P5E_CPU0_PE1_RX_DP<15>")
	)
	(segment
		(start 394.246862 -8.320024)
		(end 394.246862 -7.761224)
		(width 0.13208)
		(layer "F.Cu")
		(net "P5E_CPU0_PE1_RX_DP<15>")
	)
	(segment
		(start 394.246862 -7.761224)
		(end 394.085572 -7.599934)
		(width 0.13208)
		(layer "F.Cu")
		(net "P5E_CPU0_PE1_RX_DP<15>")
	)
	(segment
		(start 394.085572 -7.015734)
		(end 394.387832 -6.713474)
		(width 0.13208)
		(layer "F.Cu")
		(net "P5E_CPU0_PE1_RX_DP<15>")
	)
	(segment
		(start 351.880932 -219.833952)
		(end 351.874836 -219.830396)
		(width 0.0889)
		(layer "In11.Cu")
		(net "P5E_CPU0_PE1_RX_DP<15>")
	)
	(segment
		(start 401.675092 -74.916792)
		(end 395.625574 -46.052994)
		(width 0.14732)
		(layer "In11.Cu")
		(net "P5E_CPU0_PE1_RX_DP<15>")
	)
	(segment
		(start 351.404682 -215.761062)
		(end 351.395792 -215.755982)
		(width 0.0889)
		(layer "In11.Cu")
		(net "P5E_CPU0_PE1_RX_DP<15>")
	)
	(segment
		(start 351.25914 -212.926168)
		(end 351.25914 -212.90407)
		(width 0.0889)
		(layer "In11.Cu")
		(net "P5E_CPU0_PE1_RX_DP<15>")
	)
	(segment
		(start 351.686876 -214.644732)
		(end 351.686876 -214.424768)
		(width 0.0889)
		(layer "In11.Cu")
		(net "P5E_CPU0_PE1_RX_DP<15>")
	)
	(segment
		(start 393.525756 -14.67993)
		(end 393.446508 -14.526768)
		(width 0.14732)
		(layer "In11.Cu")
		(net "P5E_CPU0_PE1_RX_DP<15>")
	)
	(segment
		(start 352.84537 -221.404942)
		(end 352.767138 -221.42577)
		(width 0.0889)
		(layer "In11.Cu")
		(net "P5E_CPU0_PE1_RX_DP<15>")
	)
	(segment
		(start 392.894058 -16.2687)
		(end 393.047474 -16.189452)
		(width 0.14732)
		(layer "In11.Cu")
		(net "P5E_CPU0_PE1_RX_DP<15>")
	)
	(segment
		(start 351.874836 -219.830396)
		(end 351.865946 -219.825316)
		(width 0.0889)
		(layer "In11.Cu")
		(net "P5E_CPU0_PE1_RX_DP<15>")
	)
	(segment
		(start 393.446508 -14.526768)
		(end 394.093192 -12.485878)
		(width 0.14732)
		(layer "In11.Cu")
		(net "P5E_CPU0_PE1_RX_DP<15>")
	)
	(segment
		(start 391.64514 -19.648424)
		(end 391.64514 -18.994882)
		(width 0.14732)
		(layer "In11.Cu")
		(net "P5E_CPU0_PE1_RX_DP<15>")
	)
	(segment
		(start 351.25914 -212.559138)
		(end 339.014308 -174.908972)
		(width 0.14732)
		(layer "In11.Cu")
		(net "P5E_CPU0_PE1_RX_DP<15>")
	)
	(segment
		(start 352.15703 -218.707716)
		(end 352.15703 -218.676728)
		(width 0.0889)
		(layer "In11.Cu")
		(net "P5E_CPU0_PE1_RX_DP<15>")
	)
	(segment
		(start 393.100052 -15.619476)
		(end 393.240514 -15.175992)
		(width 0.14732)
		(layer "In11.Cu")
		(net "P5E_CPU0_PE1_RX_DP<15>")
	)
	(segment
		(start 395.625574 -46.052994)
		(end 395.626082 -46.05528)
		(width 0.14732)
		(layer "In11.Cu")
		(net "P5E_CPU0_PE1_RX_DP<15>")
	)
	(segment
		(start 394.093192 -7.008114)
		(end 394.387832 -6.713474)
		(width 0.14732)
		(layer "In11.Cu")
		(net "P5E_CPU0_PE1_RX_DP<15>")
	)
	(segment
		(start 351.25914 -212.90407)
		(end 351.25914 -212.559138)
		(width 0.14732)
		(layer "In11.Cu")
		(net "P5E_CPU0_PE1_RX_DP<15>")
	)
	(segment
		(start 401.483068 -77.252322)
		(end 401.675092 -74.916792)
		(width 0.14732)
		(layer "In11.Cu")
		(net "P5E_CPU0_PE1_RX_DP<15>")
	)
	(segment
		(start 351.865946 -219.18676)
		(end 351.874836 -219.18168)
		(width 0.0889)
		(layer "In11.Cu")
		(net "P5E_CPU0_PE1_RX_DP<15>")
	)
	(segment
		(start 392.436858 -17.71142)
		(end 392.894058 -16.2687)
		(width 0.14732)
		(layer "In11.Cu")
		(net "P5E_CPU0_PE1_RX_DP<15>")
	)
	(segment
		(start 393.240514 -15.175992)
		(end 393.393676 -15.09649)
		(width 0.14732)
		(layer "In11.Cu")
		(net "P5E_CPU0_PE1_RX_DP<15>")
	)
	(segment
		(start 352.157284 -217.07856)
		(end 352.157284 -217.064336)
		(width 0.0889)
		(layer "In11.Cu")
		(net "P5E_CPU0_PE1_RX_DP<15>")
	)
	(segment
		(start 351.395792 -215.117426)
		(end 351.404682 -215.112346)
		(width 0.0889)
		(layer "In11.Cu")
		(net "P5E_CPU0_PE1_RX_DP<15>")
	)
	(segment
		(start 393.047474 -16.189452)
		(end 393.1793 -15.772638)
		(width 0.14732)
		(layer "In11.Cu")
		(net "P5E_CPU0_PE1_RX_DP<15>")
	)
	(segment
		(start 351.216976 -212.968332)
		(end 351.25914 -212.926168)
		(width 0.0889)
		(layer "In11.Cu")
		(net "P5E_CPU0_PE1_RX_DP<15>")
	)
	(segment
		(start 393.1793 -15.772638)
		(end 393.100052 -15.619476)
		(width 0.14732)
		(layer "In11.Cu")
		(net "P5E_CPU0_PE1_RX_DP<15>")
	)
	(segment
		(start 352.627184 -221.133924)
		(end 352.627184 -221.115382)
		(width 0.0889)
		(layer "In11.Cu")
		(net "P5E_CPU0_PE1_RX_DP<15>")
	)
	(segment
		(start 351.410778 -215.764618)
		(end 351.404682 -215.761062)
		(width 0.0889)
		(layer "In11.Cu")
		(net "P5E_CPU0_PE1_RX_DP<15>")
	)
	(segment
		(start 391.754106 -18.733008)
		(end 392.436858 -17.71142)
		(width 0.14732)
		(layer "In11.Cu")
		(net "P5E_CPU0_PE1_RX_DP<15>")
	)
	(segment
		(start 351.874836 -216.574878)
		(end 351.865946 -216.569798)
		(width 0.0889)
		(layer "In11.Cu")
		(net "P5E_CPU0_PE1_RX_DP<15>")
	)
	(segment
		(start 393.393676 -15.09649)
		(end 393.525756 -14.67993)
		(width 0.14732)
		(layer "In11.Cu")
		(net "P5E_CPU0_PE1_RX_DP<15>")
	)
	(segment
		(start 351.874836 -218.202764)
		(end 351.865946 -218.197684)
		(width 0.0889)
		(layer "In11.Cu")
		(net "P5E_CPU0_PE1_RX_DP<15>")
	)
	(segment
		(start 395.626082 -46.05528)
		(end 391.64514 -19.648424)
		(width 0.14732)
		(layer "In11.Cu")
		(net "P5E_CPU0_PE1_RX_DP<15>")
	)
	(segment
		(start 339.014308 -174.908972)
		(end 339.014308 -172.04944)
		(width 0.14732)
		(layer "In11.Cu")
		(net "P5E_CPU0_PE1_RX_DP<15>")
	)
	(segment
		(start 352.344736 -220.644212)
		(end 352.335846 -220.639132)
		(width 0.0889)
		(layer "In11.Cu")
		(net "P5E_CPU0_PE1_RX_DP<15>")
	)
	(segment
		(start 394.093192 -12.485878)
		(end 394.093192 -7.008114)
		(width 0.14732)
		(layer "In11.Cu")
		(net "P5E_CPU0_PE1_RX_DP<15>")
	)
	(segment
		(start 353.001834 -221.133924)
		(end 352.84537 -221.404942)
		(width 0.0889)
		(layer "In11.Cu")
		(net "P5E_CPU0_PE1_RX_DP<15>")
	)
	(segment
		(start 391.64514 -18.994882)
		(end 391.754106 -18.733008)
		(width 0.14732)
		(layer "In11.Cu")
		(net "P5E_CPU0_PE1_RX_DP<15>")
	)
	(segment
		(start 351.865946 -217.559128)
		(end 351.874836 -217.554048)
		(width 0.0889)
		(layer "In11.Cu")
		(net "P5E_CPU0_PE1_RX_DP<15>")
	)
	(segment
		(start 342.21674 -161.892742)
		(end 401.483068 -77.252322)
		(width 0.14732)
		(layer "In11.Cu")
		(net "P5E_CPU0_PE1_RX_DP<15>")
	)
	(segment
		(start 351.880932 -216.578434)
		(end 351.874836 -216.574878)
		(width 0.0889)
		(layer "In11.Cu")
		(net "P5E_CPU0_PE1_RX_DP<15>")
	)
	(segment
		(start 351.216976 -213.786974)
		(end 351.216976 -212.968332)
		(width 0.0889)
		(layer "In11.Cu")
		(net "P5E_CPU0_PE1_RX_DP<15>")
	)
	(segment
		(start 339.014308 -172.04944)
		(end 342.21674 -161.892742)
		(width 0.14732)
		(layer "In11.Cu")
		(net "P5E_CPU0_PE1_RX_DP<15>")
	)
	(arc
		(start 351.865946 -216.569798)
		(mid 351.735032 -216.433438)
		(end 351.687384 -216.25052)
		(width 0.0889)
		(layer "In11.Cu")
		(net "P5E_CPU0_PE1_RX_DP<15>")
	)
	(arc
		(start 351.874836 -219.18168)
		(mid 352.077659 -218.981449)
		(end 352.15703 -218.707716)
		(width 0.0889)
		(layer "In11.Cu")
		(net "P5E_CPU0_PE1_RX_DP<15>")
	)
	(arc
		(start 351.865946 -218.197684)
		(mid 351.735032 -218.061324)
		(end 351.687384 -217.878406)
		(width 0.0889)
		(layer "In11.Cu")
		(net "P5E_CPU0_PE1_RX_DP<15>")
	)
	(arc
		(start 352.767138 -221.42577)
		(mid 352.663993 -221.295745)
		(end 352.627184 -221.133924)
		(width 0.0889)
		(layer "In11.Cu")
		(net "P5E_CPU0_PE1_RX_DP<15>")
	)
	(arc
		(start 351.217484 -215.421972)
		(mid 351.268538 -215.247392)
		(end 351.395792 -215.117426)
		(width 0.0889)
		(layer "In11.Cu")
		(net "P5E_CPU0_PE1_RX_DP<15>")
	)
	(arc
		(start 352.157284 -220.319854)
		(mid 352.083368 -220.040352)
		(end 351.880932 -219.833952)
		(width 0.0889)
		(layer "In11.Cu")
		(net "P5E_CPU0_PE1_RX_DP<15>")
	)
	(arc
		(start 351.687384 -216.25052)
		(mid 351.613393 -215.970954)
		(end 351.410778 -215.764618)
		(width 0.0889)
		(layer "In11.Cu")
		(net "P5E_CPU0_PE1_RX_DP<15>")
	)
	(arc
		(start 352.15703 -218.676728)
		(mid 352.07766 -218.402994)
		(end 351.874836 -218.202764)
		(width 0.0889)
		(layer "In11.Cu")
		(net "P5E_CPU0_PE1_RX_DP<15>")
	)
	(arc
		(start 351.21723 -215.436704)
		(mid 351.217282 -215.429337)
		(end 351.217484 -215.421972)
		(width 0.0889)
		(layer "In11.Cu")
		(net "P5E_CPU0_PE1_RX_DP<15>")
	)
	(arc
		(start 351.395792 -215.755982)
		(mid 351.264878 -215.619622)
		(end 351.21723 -215.436704)
		(width 0.0889)
		(layer "In11.Cu")
		(net "P5E_CPU0_PE1_RX_DP<15>")
	)
	(arc
		(start 352.335846 -220.639132)
		(mid 352.204932 -220.502772)
		(end 352.157284 -220.319854)
		(width 0.0889)
		(layer "In11.Cu")
		(net "P5E_CPU0_PE1_RX_DP<15>")
	)
	(arc
		(start 351.404682 -215.112346)
		(mid 351.605964 -214.914859)
		(end 351.686876 -214.644732)
		(width 0.0889)
		(layer "In11.Cu")
		(net "P5E_CPU0_PE1_RX_DP<15>")
	)
	(arc
		(start 351.865946 -219.825316)
		(mid 351.68747 -219.506038)
		(end 351.865946 -219.18676)
		(width 0.0889)
		(layer "In11.Cu")
		(net "P5E_CPU0_PE1_RX_DP<15>")
	)
	(arc
		(start 352.157284 -217.064336)
		(mid 352.083368 -216.784834)
		(end 351.880932 -216.578434)
		(width 0.0889)
		(layer "In11.Cu")
		(net "P5E_CPU0_PE1_RX_DP<15>")
	)
	(arc
		(start 351.686876 -214.424768)
		(mid 351.575597 -214.232062)
		(end 351.401634 -214.093298)
		(width 0.0889)
		(layer "In11.Cu")
		(net "P5E_CPU0_PE1_RX_DP<15>")
	)
	(arc
		(start 352.627184 -221.115382)
		(mid 352.547022 -220.843193)
		(end 352.344736 -220.644212)
		(width 0.0889)
		(layer "In11.Cu")
		(net "P5E_CPU0_PE1_RX_DP<15>")
	)
	(arc
		(start 351.874836 -217.554048)
		(mid 352.078141 -217.353182)
		(end 352.157284 -217.07856)
		(width 0.0889)
		(layer "In11.Cu")
		(net "P5E_CPU0_PE1_RX_DP<15>")
	)
	(arc
		(start 351.687638 -217.863674)
		(mid 351.738692 -217.689094)
		(end 351.865946 -217.559128)
		(width 0.0889)
		(layer "In11.Cu")
		(net "P5E_CPU0_PE1_RX_DP<15>")
	)
	(arc
		(start 351.401634 -214.093298)
		(mid 351.26673 -213.965806)
		(end 351.216976 -213.786974)
		(width 0.0889)
		(layer "In11.Cu")
		(net "P5E_CPU0_PE1_RX_DP<15>")
	)
	(arc
		(start 351.687384 -217.878406)
		(mid 351.687436 -217.871039)
		(end 351.687638 -217.863674)
		(width 0.0889)
		(layer "In11.Cu")
		(net "P5E_CPU0_PE1_RX_DP<15>")
	)
	(segment
		(start 395.889226 -5.255006)
		(end 396.192502 -4.95173)
		(width 0.13208)
		(layer "F.Cu")
		(net "P5E_CPU0_PE1_RX_DP<14>")
	)
	(segment
		(start 396.04696 -7.761478)
		(end 395.889226 -7.603744)
		(width 0.13208)
		(layer "F.Cu")
		(net "P5E_CPU0_PE1_RX_DP<14>")
	)
	(segment
		(start 395.889226 -7.603744)
		(end 395.889226 -5.255006)
		(width 0.13208)
		(layer "F.Cu")
		(net "P5E_CPU0_PE1_RX_DP<14>")
	)
	(segment
		(start 396.04696 -8.320024)
		(end 396.04696 -7.761478)
		(width 0.13208)
		(layer "F.Cu")
		(net "P5E_CPU0_PE1_RX_DP<14>")
	)
	(segment
		(start 353.471734 -220.855794)
		(end 353.47148 -220.319854)
		(width 0.13208)
		(layer "F.Cu")
		(net "P5E_CPU0_PE1_RX_DP<14>")
	)
	(segment
		(start 402.49856 -77.43571)
		(end 343.216484 -162.098736)
		(width 0.14732)
		(layer "In11.Cu")
		(net "P5E_CPU0_PE1_RX_DP<14>")
	)
	(segment
		(start 395.217142 -14.749272)
		(end 395.313916 -14.929612)
		(width 0.14732)
		(layer "In11.Cu")
		(net "P5E_CPU0_PE1_RX_DP<14>")
	)
	(segment
		(start 395.514068 -13.7668)
		(end 395.610842 -13.947394)
		(width 0.14732)
		(layer "In11.Cu")
		(net "P5E_CPU0_PE1_RX_DP<14>")
	)
	(segment
		(start 353.606862 -220.66885)
		(end 353.627944 -220.590872)
		(width 0.0889)
		(layer "In11.Cu")
		(net "P5E_CPU0_PE1_RX_DP<14>")
	)
	(segment
		(start 339.95233 -172.450506)
		(end 339.95233 -174.734982)
		(width 0.14732)
		(layer "In11.Cu")
		(net "P5E_CPU0_PE1_RX_DP<14>")
	)
	(segment
		(start 352.814636 -219.18168)
		(end 352.81362 -219.182188)
		(width 0.0889)
		(layer "In11.Cu")
		(net "P5E_CPU0_PE1_RX_DP<14>")
	)
	(segment
		(start 395.337284 -19.84375)
		(end 402.858732 -75.125326)
		(width 0.14732)
		(layer "In11.Cu")
		(net "P5E_CPU0_PE1_RX_DP<14>")
	)
	(segment
		(start 394.4493 -17.853914)
		(end 395.120622 -18.858738)
		(width 0.14732)
		(layer "In11.Cu")
		(net "P5E_CPU0_PE1_RX_DP<14>")
	)
	(segment
		(start 395.897862 -5.24637)
		(end 395.897862 -12.390628)
		(width 0.14732)
		(layer "In11.Cu")
		(net "P5E_CPU0_PE1_RX_DP<14>")
	)
	(segment
		(start 353.097084 -217.05443)
		(end 353.097084 -217.082878)
		(width 0.0889)
		(layer "In11.Cu")
		(net "P5E_CPU0_PE1_RX_DP<14>")
	)
	(segment
		(start 352.805746 -218.197684)
		(end 352.81362 -218.202256)
		(width 0.0889)
		(layer "In11.Cu")
		(net "P5E_CPU0_PE1_RX_DP<14>")
	)
	(segment
		(start 343.216484 -162.098736)
		(end 339.95233 -172.450506)
		(width 0.14732)
		(layer "In11.Cu")
		(net "P5E_CPU0_PE1_RX_DP<14>")
	)
	(segment
		(start 395.867128 -12.598908)
		(end 395.514068 -13.7668)
		(width 0.14732)
		(layer "In11.Cu")
		(net "P5E_CPU0_PE1_RX_DP<14>")
	)
	(segment
		(start 395.897862 -12.390628)
		(end 395.867128 -12.598908)
		(width 0.14732)
		(layer "In11.Cu")
		(net "P5E_CPU0_PE1_RX_DP<14>")
	)
	(segment
		(start 394.669772 -16.559022)
		(end 394.4493 -17.287748)
		(width 0.14732)
		(layer "In11.Cu")
		(net "P5E_CPU0_PE1_RX_DP<14>")
	)
	(segment
		(start 394.956792 -16.10995)
		(end 394.850112 -16.462502)
		(width 0.14732)
		(layer "In11.Cu")
		(net "P5E_CPU0_PE1_RX_DP<14>")
	)
	(segment
		(start 352.199194 -212.372448)
		(end 352.199194 -212.90407)
		(width 0.14732)
		(layer "In11.Cu")
		(net "P5E_CPU0_PE1_RX_DP<14>")
	)
	(segment
		(start 395.207236 -15.282418)
		(end 395.026642 -15.379192)
		(width 0.14732)
		(layer "In11.Cu")
		(net "P5E_CPU0_PE1_RX_DP<14>")
	)
	(segment
		(start 395.313916 -14.929612)
		(end 395.207236 -15.282418)
		(width 0.14732)
		(layer "In11.Cu")
		(net "P5E_CPU0_PE1_RX_DP<14>")
	)
	(segment
		(start 352.81362 -219.182188)
		(end 352.805746 -219.18676)
		(width 0.0889)
		(layer "In11.Cu")
		(net "P5E_CPU0_PE1_RX_DP<14>")
	)
	(segment
		(start 352.335592 -215.755982)
		(end 352.342958 -215.7603)
		(width 0.0889)
		(layer "In11.Cu")
		(net "P5E_CPU0_PE1_RX_DP<14>")
	)
	(segment
		(start 394.850112 -16.462502)
		(end 394.669772 -16.559022)
		(width 0.14732)
		(layer "In11.Cu")
		(net "P5E_CPU0_PE1_RX_DP<14>")
	)
	(segment
		(start 395.504416 -14.3002)
		(end 395.323568 -14.396974)
		(width 0.14732)
		(layer "In11.Cu")
		(net "P5E_CPU0_PE1_RX_DP<14>")
	)
	(segment
		(start 339.95233 -174.734982)
		(end 350.708214 -206.419958)
		(width 0.14732)
		(layer "In11.Cu")
		(net "P5E_CPU0_PE1_RX_DP<14>")
	)
	(segment
		(start 352.343466 -215.112854)
		(end 352.335592 -215.117426)
		(width 0.0889)
		(layer "In11.Cu")
		(net "P5E_CPU0_PE1_RX_DP<14>")
	)
	(segment
		(start 352.34118 -214.093806)
		(end 352.34118 -214.093552)
		(width 0.0889)
		(layer "In11.Cu")
		(net "P5E_CPU0_PE1_RX_DP<14>")
	)
	(segment
		(start 395.026642 -15.379192)
		(end 394.860272 -15.929356)
		(width 0.14732)
		(layer "In11.Cu")
		(net "P5E_CPU0_PE1_RX_DP<14>")
	)
	(segment
		(start 352.199194 -212.926168)
		(end 352.15703 -212.968332)
		(width 0.0889)
		(layer "In11.Cu")
		(net "P5E_CPU0_PE1_RX_DP<14>")
	)
	(segment
		(start 395.120622 -18.858738)
		(end 395.337284 -19.84375)
		(width 0.14732)
		(layer "In11.Cu")
		(net "P5E_CPU0_PE1_RX_DP<14>")
	)
	(segment
		(start 352.344482 -215.761062)
		(end 352.347276 -215.762586)
		(width 0.0889)
		(layer "In11.Cu")
		(net "P5E_CPU0_PE1_RX_DP<14>")
	)
	(segment
		(start 352.15703 -212.968332)
		(end 352.15703 -213.894924)
		(width 0.0889)
		(layer "In11.Cu")
		(net "P5E_CPU0_PE1_RX_DP<14>")
	)
	(segment
		(start 353.097084 -220.309948)
		(end 353.097084 -220.32849)
		(width 0.0889)
		(layer "In11.Cu")
		(net "P5E_CPU0_PE1_RX_DP<14>")
	)
	(segment
		(start 402.858732 -75.125326)
		(end 402.49856 -77.43571)
		(width 0.14732)
		(layer "In11.Cu")
		(net "P5E_CPU0_PE1_RX_DP<14>")
	)
	(segment
		(start 352.34118 -214.093552)
		(end 352.341434 -214.093298)
		(width 0.0889)
		(layer "In11.Cu")
		(net "P5E_CPU0_PE1_RX_DP<14>")
	)
	(segment
		(start 353.627944 -220.590872)
		(end 353.47148 -220.319854)
		(width 0.0889)
		(layer "In11.Cu")
		(net "P5E_CPU0_PE1_RX_DP<14>")
	)
	(segment
		(start 394.860272 -15.929356)
		(end 394.956792 -16.10995)
		(width 0.14732)
		(layer "In11.Cu")
		(net "P5E_CPU0_PE1_RX_DP<14>")
	)
	(segment
		(start 352.626676 -214.424768)
		(end 352.626676 -214.644732)
		(width 0.0889)
		(layer "In11.Cu")
		(net "P5E_CPU0_PE1_RX_DP<14>")
	)
	(segment
		(start 394.4493 -17.287748)
		(end 394.4493 -17.853914)
		(width 0.14732)
		(layer "In11.Cu")
		(net "P5E_CPU0_PE1_RX_DP<14>")
	)
	(segment
		(start 352.199194 -212.90407)
		(end 352.199194 -212.926168)
		(width 0.0889)
		(layer "In11.Cu")
		(net "P5E_CPU0_PE1_RX_DP<14>")
	)
	(segment
		(start 395.610842 -13.947394)
		(end 395.504416 -14.3002)
		(width 0.14732)
		(layer "In11.Cu")
		(net "P5E_CPU0_PE1_RX_DP<14>")
	)
	(segment
		(start 352.805746 -216.569798)
		(end 352.814636 -216.574878)
		(width 0.0889)
		(layer "In11.Cu")
		(net "P5E_CPU0_PE1_RX_DP<14>")
	)
	(segment
		(start 352.347276 -215.762586)
		(end 352.350578 -215.764618)
		(width 0.0889)
		(layer "In11.Cu")
		(net "P5E_CPU0_PE1_RX_DP<14>")
	)
	(segment
		(start 352.344482 -215.112346)
		(end 352.343466 -215.112854)
		(width 0.0889)
		(layer "In11.Cu")
		(net "P5E_CPU0_PE1_RX_DP<14>")
	)
	(segment
		(start 352.805746 -219.825316)
		(end 352.814636 -219.830396)
		(width 0.0889)
		(layer "In11.Cu")
		(net "P5E_CPU0_PE1_RX_DP<14>")
	)
	(segment
		(start 353.09683 -218.676728)
		(end 353.09683 -218.707716)
		(width 0.0889)
		(layer "In11.Cu")
		(net "P5E_CPU0_PE1_RX_DP<14>")
	)
	(segment
		(start 352.814636 -217.554048)
		(end 352.805746 -217.559128)
		(width 0.0889)
		(layer "In11.Cu")
		(net "P5E_CPU0_PE1_RX_DP<14>")
	)
	(segment
		(start 352.81362 -218.202256)
		(end 352.814636 -218.202764)
		(width 0.0889)
		(layer "In11.Cu")
		(net "P5E_CPU0_PE1_RX_DP<14>")
	)
	(segment
		(start 350.708214 -206.419958)
		(end 352.199194 -212.372448)
		(width 0.14732)
		(layer "In11.Cu")
		(net "P5E_CPU0_PE1_RX_DP<14>")
	)
	(segment
		(start 395.323568 -14.396974)
		(end 395.217142 -14.749272)
		(width 0.14732)
		(layer "In11.Cu")
		(net "P5E_CPU0_PE1_RX_DP<14>")
	)
	(segment
		(start 396.192502 -4.95173)
		(end 395.897862 -5.24637)
		(width 0.14732)
		(layer "In11.Cu")
		(net "P5E_CPU0_PE1_RX_DP<14>")
	)
	(segment
		(start 352.342958 -215.7603)
		(end 352.344482 -215.761062)
		(width 0.0889)
		(layer "In11.Cu")
		(net "P5E_CPU0_PE1_RX_DP<14>")
	)
	(arc
		(start 352.814636 -216.574878)
		(mid 353.018971 -216.777483)
		(end 353.097084 -217.05443)
		(width 0.0889)
		(layer "In11.Cu")
		(net "P5E_CPU0_PE1_RX_DP<14>")
	)
	(arc
		(start 352.626676 -214.644732)
		(mid 352.545765 -214.91486)
		(end 352.344482 -215.112346)
		(width 0.0889)
		(layer "In11.Cu")
		(net "P5E_CPU0_PE1_RX_DP<14>")
	)
	(arc
		(start 352.627184 -216.25052)
		(mid 352.674863 -216.43342)
		(end 352.805746 -216.569798)
		(width 0.0889)
		(layer "In11.Cu")
		(net "P5E_CPU0_PE1_RX_DP<14>")
	)
	(arc
		(start 352.627438 -217.866214)
		(mid 352.627271 -217.87739)
		(end 352.627438 -217.888566)
		(width 0.0889)
		(layer "In11.Cu")
		(net "P5E_CPU0_PE1_RX_DP<14>")
	)
	(arc
		(start 352.15703 -215.436704)
		(mid 352.204709 -215.619604)
		(end 352.335592 -215.755982)
		(width 0.0889)
		(layer "In11.Cu")
		(net "P5E_CPU0_PE1_RX_DP<14>")
	)
	(arc
		(start 352.15703 -213.894924)
		(mid 352.232109 -214.010109)
		(end 352.34118 -214.093806)
		(width 0.0889)
		(layer "In11.Cu")
		(net "P5E_CPU0_PE1_RX_DP<14>")
	)
	(arc
		(start 352.814636 -218.202764)
		(mid 353.017459 -218.402995)
		(end 353.09683 -218.676728)
		(width 0.0889)
		(layer "In11.Cu")
		(net "P5E_CPU0_PE1_RX_DP<14>")
	)
	(arc
		(start 352.341434 -214.093298)
		(mid 352.515397 -214.232062)
		(end 352.626676 -214.424768)
		(width 0.0889)
		(layer "In11.Cu")
		(net "P5E_CPU0_PE1_RX_DP<14>")
	)
	(arc
		(start 353.097084 -220.32849)
		(mid 353.149354 -220.510855)
		(end 353.284282 -220.644212)
		(width 0.0889)
		(layer "In11.Cu")
		(net "P5E_CPU0_PE1_RX_DP<14>")
	)
	(arc
		(start 352.157284 -215.421972)
		(mid 352.157087 -215.429337)
		(end 352.15703 -215.436704)
		(width 0.0889)
		(layer "In11.Cu")
		(net "P5E_CPU0_PE1_RX_DP<14>")
	)
	(arc
		(start 353.097084 -217.082878)
		(mid 353.016922 -217.355067)
		(end 352.814636 -217.554048)
		(width 0.0889)
		(layer "In11.Cu")
		(net "P5E_CPU0_PE1_RX_DP<14>")
	)
	(arc
		(start 352.350578 -215.764618)
		(mid 352.553165 -215.970969)
		(end 352.627184 -216.25052)
		(width 0.0889)
		(layer "In11.Cu")
		(net "P5E_CPU0_PE1_RX_DP<14>")
	)
	(arc
		(start 353.284282 -220.644212)
		(mid 353.44277 -220.693145)
		(end 353.606862 -220.66885)
		(width 0.0889)
		(layer "In11.Cu")
		(net "P5E_CPU0_PE1_RX_DP<14>")
	)
	(arc
		(start 352.805746 -217.559128)
		(mid 352.677935 -217.690221)
		(end 352.627438 -217.866214)
		(width 0.0889)
		(layer "In11.Cu")
		(net "P5E_CPU0_PE1_RX_DP<14>")
	)
	(arc
		(start 352.335592 -215.117426)
		(mid 352.208338 -215.247392)
		(end 352.157284 -215.421972)
		(width 0.0889)
		(layer "In11.Cu")
		(net "P5E_CPU0_PE1_RX_DP<14>")
	)
	(arc
		(start 352.627438 -219.495878)
		(mid 352.627344 -219.50426)
		(end 352.627438 -219.512642)
		(width 0.0889)
		(layer "In11.Cu")
		(net "P5E_CPU0_PE1_RX_DP<14>")
	)
	(arc
		(start 352.627438 -219.512642)
		(mid 352.676637 -219.691748)
		(end 352.805746 -219.825316)
		(width 0.0889)
		(layer "In11.Cu")
		(net "P5E_CPU0_PE1_RX_DP<14>")
	)
	(arc
		(start 353.09683 -218.707716)
		(mid 353.01746 -218.98145)
		(end 352.814636 -219.18168)
		(width 0.0889)
		(layer "In11.Cu")
		(net "P5E_CPU0_PE1_RX_DP<14>")
	)
	(arc
		(start 352.627438 -217.888566)
		(mid 352.677453 -218.065697)
		(end 352.805746 -218.197684)
		(width 0.0889)
		(layer "In11.Cu")
		(net "P5E_CPU0_PE1_RX_DP<14>")
	)
	(arc
		(start 352.805746 -219.18676)
		(mid 352.677427 -219.318732)
		(end 352.627438 -219.495878)
		(width 0.0889)
		(layer "In11.Cu")
		(net "P5E_CPU0_PE1_RX_DP<14>")
	)
	(arc
		(start 352.814636 -219.830396)
		(mid 353.018971 -220.033001)
		(end 353.097084 -220.309948)
		(width 0.0889)
		(layer "In11.Cu")
		(net "P5E_CPU0_PE1_RX_DP<14>")
	)
	(segment
		(start 397.846804 -8.320024)
		(end 397.846804 -7.761224)
		(width 0.13208)
		(layer "F.Cu")
		(net "P5E_CPU0_PE1_RX_DP<13>")
	)
	(segment
		(start 397.685514 -7.599934)
		(end 397.685514 -7.015734)
		(width 0.13208)
		(layer "F.Cu")
		(net "P5E_CPU0_PE1_RX_DP<13>")
	)
	(segment
		(start 397.685514 -7.015734)
		(end 397.987774 -6.713474)
		(width 0.13208)
		(layer "F.Cu")
		(net "P5E_CPU0_PE1_RX_DP<13>")
	)
	(segment
		(start 397.846804 -7.761224)
		(end 397.685514 -7.599934)
		(width 0.13208)
		(layer "F.Cu")
		(net "P5E_CPU0_PE1_RX_DP<13>")
	)
	(segment
		(start 354.88118 -221.669864)
		(end 354.881434 -221.133924)
		(width 0.13208)
		(layer "F.Cu")
		(net "P5E_CPU0_PE1_RX_DP<13>")
	)
	(segment
		(start 397.23568 -18.993866)
		(end 397.23568 -19.506438)
		(width 0.14732)
		(layer "In11.Cu")
		(net "P5E_CPU0_PE1_RX_DP<13>")
	)
	(segment
		(start 353.139248 -212.90407)
		(end 353.139248 -212.926168)
		(width 0.0889)
		(layer "In11.Cu")
		(net "P5E_CPU0_PE1_RX_DP<13>")
	)
	(segment
		(start 340.890606 -172.582078)
		(end 340.890606 -174.59833)
		(width 0.14732)
		(layer "In11.Cu")
		(net "P5E_CPU0_PE1_RX_DP<13>")
	)
	(segment
		(start 353.75342 -219.182188)
		(end 353.745546 -219.18676)
		(width 0.0889)
		(layer "In11.Cu")
		(net "P5E_CPU0_PE1_RX_DP<13>")
	)
	(segment
		(start 353.284282 -215.761062)
		(end 353.290378 -215.764618)
		(width 0.0889)
		(layer "In11.Cu")
		(net "P5E_CPU0_PE1_RX_DP<13>")
	)
	(segment
		(start 353.745546 -218.197684)
		(end 353.754436 -218.202764)
		(width 0.0889)
		(layer "In11.Cu")
		(net "P5E_CPU0_PE1_RX_DP<13>")
	)
	(segment
		(start 397.23568 -19.506438)
		(end 403.91588 -75.512676)
		(width 0.14732)
		(layer "In11.Cu")
		(net "P5E_CPU0_PE1_RX_DP<13>")
	)
	(segment
		(start 397.823436 -14.178788)
		(end 397.978122 -14.313154)
		(width 0.14732)
		(layer "In11.Cu")
		(net "P5E_CPU0_PE1_RX_DP<13>")
	)
	(segment
		(start 353.139248 -212.926168)
		(end 353.097084 -212.968332)
		(width 0.0889)
		(layer "In11.Cu")
		(net "P5E_CPU0_PE1_RX_DP<13>")
	)
	(segment
		(start 398.03578 -17.661636)
		(end 397.802354 -18.225008)
		(width 0.14732)
		(layer "In11.Cu")
		(net "P5E_CPU0_PE1_RX_DP<13>")
	)
	(segment
		(start 354.036884 -217.064336)
		(end 354.036884 -217.07856)
		(width 0.0889)
		(layer "In11.Cu")
		(net "P5E_CPU0_PE1_RX_DP<13>")
	)
	(segment
		(start 353.745546 -219.825316)
		(end 353.754436 -219.830396)
		(width 0.0889)
		(layer "In11.Cu")
		(net "P5E_CPU0_PE1_RX_DP<13>")
	)
	(segment
		(start 353.745546 -216.569798)
		(end 353.754436 -216.574878)
		(width 0.0889)
		(layer "In11.Cu")
		(net "P5E_CPU0_PE1_RX_DP<13>")
	)
	(segment
		(start 353.566476 -214.424768)
		(end 353.566476 -214.644732)
		(width 0.0889)
		(layer "In11.Cu")
		(net "P5E_CPU0_PE1_RX_DP<13>")
	)
	(segment
		(start 354.646738 -221.42577)
		(end 354.72497 -221.404942)
		(width 0.0889)
		(layer "In11.Cu")
		(net "P5E_CPU0_PE1_RX_DP<13>")
	)
	(segment
		(start 353.275392 -215.755982)
		(end 353.284282 -215.761062)
		(width 0.0889)
		(layer "In11.Cu")
		(net "P5E_CPU0_PE1_RX_DP<13>")
	)
	(segment
		(start 353.097084 -212.968332)
		(end 353.097084 -213.893908)
		(width 0.0889)
		(layer "In11.Cu")
		(net "P5E_CPU0_PE1_RX_DP<13>")
	)
	(segment
		(start 397.697706 -12.379706)
		(end 397.823436 -14.178788)
		(width 0.14732)
		(layer "In11.Cu")
		(net "P5E_CPU0_PE1_RX_DP<13>")
	)
	(segment
		(start 397.802354 -18.225008)
		(end 397.378936 -18.648172)
		(width 0.14732)
		(layer "In11.Cu")
		(net "P5E_CPU0_PE1_RX_DP<13>")
	)
	(segment
		(start 403.385274 -77.796898)
		(end 344.06459 -162.51555)
		(width 0.14732)
		(layer "In11.Cu")
		(net "P5E_CPU0_PE1_RX_DP<13>")
	)
	(segment
		(start 397.693134 -7.008114)
		(end 397.693134 -12.216638)
		(width 0.14732)
		(layer "In11.Cu")
		(net "P5E_CPU0_PE1_RX_DP<13>")
	)
	(segment
		(start 397.986758 -16.51127)
		(end 398.03578 -17.214596)
		(width 0.14732)
		(layer "In11.Cu")
		(net "P5E_CPU0_PE1_RX_DP<13>")
	)
	(segment
		(start 397.94053 -15.85468)
		(end 398.09547 -15.989046)
		(width 0.14732)
		(layer "In11.Cu")
		(net "P5E_CPU0_PE1_RX_DP<13>")
	)
	(segment
		(start 353.754436 -219.830396)
		(end 353.760532 -219.833952)
		(width 0.0889)
		(layer "In11.Cu")
		(net "P5E_CPU0_PE1_RX_DP<13>")
	)
	(segment
		(start 398.09547 -15.989046)
		(end 398.121124 -16.356838)
		(width 0.14732)
		(layer "In11.Cu")
		(net "P5E_CPU0_PE1_RX_DP<13>")
	)
	(segment
		(start 344.06459 -162.51555)
		(end 340.890606 -172.582078)
		(width 0.14732)
		(layer "In11.Cu")
		(net "P5E_CPU0_PE1_RX_DP<13>")
	)
	(segment
		(start 354.506784 -221.115382)
		(end 354.506784 -221.133924)
		(width 0.0889)
		(layer "In11.Cu")
		(net "P5E_CPU0_PE1_RX_DP<13>")
	)
	(segment
		(start 398.003776 -14.680946)
		(end 397.86941 -14.835378)
		(width 0.14732)
		(layer "In11.Cu")
		(net "P5E_CPU0_PE1_RX_DP<13>")
	)
	(segment
		(start 354.215446 -220.639132)
		(end 354.224336 -220.644212)
		(width 0.0889)
		(layer "In11.Cu")
		(net "P5E_CPU0_PE1_RX_DP<13>")
	)
	(segment
		(start 353.139248 -212.089492)
		(end 353.139248 -212.90407)
		(width 0.14732)
		(layer "In11.Cu")
		(net "P5E_CPU0_PE1_RX_DP<13>")
	)
	(segment
		(start 353.754436 -216.574878)
		(end 353.760532 -216.578434)
		(width 0.0889)
		(layer "In11.Cu")
		(net "P5E_CPU0_PE1_RX_DP<13>")
	)
	(segment
		(start 351.79889 -206.737712)
		(end 353.139248 -212.089492)
		(width 0.14732)
		(layer "In11.Cu")
		(net "P5E_CPU0_PE1_RX_DP<13>")
	)
	(segment
		(start 340.890606 -174.59833)
		(end 351.79889 -206.737712)
		(width 0.14732)
		(layer "In11.Cu")
		(net "P5E_CPU0_PE1_RX_DP<13>")
	)
	(segment
		(start 354.72497 -221.404942)
		(end 354.881434 -221.133924)
		(width 0.0889)
		(layer "In11.Cu")
		(net "P5E_CPU0_PE1_RX_DP<13>")
	)
	(segment
		(start 397.693134 -12.216638)
		(end 397.697706 -12.379706)
		(width 0.14732)
		(layer "In11.Cu")
		(net "P5E_CPU0_PE1_RX_DP<13>")
	)
	(segment
		(start 353.283266 -215.112854)
		(end 353.275392 -215.117426)
		(width 0.0889)
		(layer "In11.Cu")
		(net "P5E_CPU0_PE1_RX_DP<13>")
	)
	(segment
		(start 398.03578 -17.214596)
		(end 398.03578 -17.661636)
		(width 0.14732)
		(layer "In11.Cu")
		(net "P5E_CPU0_PE1_RX_DP<13>")
	)
	(segment
		(start 397.978122 -14.313154)
		(end 398.003776 -14.680946)
		(width 0.14732)
		(layer "In11.Cu")
		(net "P5E_CPU0_PE1_RX_DP<13>")
	)
	(segment
		(start 353.284282 -215.112346)
		(end 353.283266 -215.112854)
		(width 0.0889)
		(layer "In11.Cu")
		(net "P5E_CPU0_PE1_RX_DP<13>")
	)
	(segment
		(start 353.281234 -214.093552)
		(end 353.281234 -214.093298)
		(width 0.0889)
		(layer "In11.Cu")
		(net "P5E_CPU0_PE1_RX_DP<13>")
	)
	(segment
		(start 397.378936 -18.648172)
		(end 397.23568 -18.993866)
		(width 0.14732)
		(layer "In11.Cu")
		(net "P5E_CPU0_PE1_RX_DP<13>")
	)
	(segment
		(start 403.91588 -75.512676)
		(end 403.385274 -77.796898)
		(width 0.14732)
		(layer "In11.Cu")
		(net "P5E_CPU0_PE1_RX_DP<13>")
	)
	(segment
		(start 397.86941 -14.835378)
		(end 397.94053 -15.85468)
		(width 0.14732)
		(layer "In11.Cu")
		(net "P5E_CPU0_PE1_RX_DP<13>")
	)
	(segment
		(start 353.754436 -217.554048)
		(end 353.745546 -217.559128)
		(width 0.0889)
		(layer "In11.Cu")
		(net "P5E_CPU0_PE1_RX_DP<13>")
	)
	(segment
		(start 398.121124 -16.356838)
		(end 397.986758 -16.51127)
		(width 0.14732)
		(layer "In11.Cu")
		(net "P5E_CPU0_PE1_RX_DP<13>")
	)
	(segment
		(start 353.754436 -219.18168)
		(end 353.75342 -219.182188)
		(width 0.0889)
		(layer "In11.Cu")
		(net "P5E_CPU0_PE1_RX_DP<13>")
	)
	(segment
		(start 397.987774 -6.713474)
		(end 397.693134 -7.008114)
		(width 0.14732)
		(layer "In11.Cu")
		(net "P5E_CPU0_PE1_RX_DP<13>")
	)
	(segment
		(start 354.03663 -218.676728)
		(end 354.03663 -218.707716)
		(width 0.0889)
		(layer "In11.Cu")
		(net "P5E_CPU0_PE1_RX_DP<13>")
	)
	(arc
		(start 353.566984 -217.88882)
		(mid 353.617132 -218.065874)
		(end 353.745546 -218.197684)
		(width 0.0889)
		(layer "In11.Cu")
		(net "P5E_CPU0_PE1_RX_DP<13>")
	)
	(arc
		(start 354.03663 -218.707716)
		(mid 353.95726 -218.98145)
		(end 353.754436 -219.18168)
		(width 0.0889)
		(layer "In11.Cu")
		(net "P5E_CPU0_PE1_RX_DP<13>")
	)
	(arc
		(start 354.036884 -220.319854)
		(mid 354.084563 -220.502754)
		(end 354.215446 -220.639132)
		(width 0.0889)
		(layer "In11.Cu")
		(net "P5E_CPU0_PE1_RX_DP<13>")
	)
	(arc
		(start 353.097084 -213.893908)
		(mid 353.172056 -214.009506)
		(end 353.281234 -214.093552)
		(width 0.0889)
		(layer "In11.Cu")
		(net "P5E_CPU0_PE1_RX_DP<13>")
	)
	(arc
		(start 353.760532 -216.578434)
		(mid 353.962945 -216.784847)
		(end 354.036884 -217.064336)
		(width 0.0889)
		(layer "In11.Cu")
		(net "P5E_CPU0_PE1_RX_DP<13>")
	)
	(arc
		(start 353.566476 -214.644732)
		(mid 353.485565 -214.91486)
		(end 353.284282 -215.112346)
		(width 0.0889)
		(layer "In11.Cu")
		(net "P5E_CPU0_PE1_RX_DP<13>")
	)
	(arc
		(start 354.224336 -220.644212)
		(mid 354.426622 -220.843193)
		(end 354.506784 -221.115382)
		(width 0.0889)
		(layer "In11.Cu")
		(net "P5E_CPU0_PE1_RX_DP<13>")
	)
	(arc
		(start 353.281234 -214.093298)
		(mid 353.455197 -214.232062)
		(end 353.566476 -214.424768)
		(width 0.0889)
		(layer "In11.Cu")
		(net "P5E_CPU0_PE1_RX_DP<13>")
	)
	(arc
		(start 353.745546 -219.18676)
		(mid 353.56707 -219.506038)
		(end 353.745546 -219.825316)
		(width 0.0889)
		(layer "In11.Cu")
		(net "P5E_CPU0_PE1_RX_DP<13>")
	)
	(arc
		(start 353.567238 -217.863674)
		(mid 353.566903 -217.876245)
		(end 353.566984 -217.88882)
		(width 0.0889)
		(layer "In11.Cu")
		(net "P5E_CPU0_PE1_RX_DP<13>")
	)
	(arc
		(start 353.566984 -216.25052)
		(mid 353.614663 -216.43342)
		(end 353.745546 -216.569798)
		(width 0.0889)
		(layer "In11.Cu")
		(net "P5E_CPU0_PE1_RX_DP<13>")
	)
	(arc
		(start 353.097084 -215.421972)
		(mid 353.096887 -215.429337)
		(end 353.09683 -215.436704)
		(width 0.0889)
		(layer "In11.Cu")
		(net "P5E_CPU0_PE1_RX_DP<13>")
	)
	(arc
		(start 353.754436 -218.202764)
		(mid 353.957259 -218.402995)
		(end 354.03663 -218.676728)
		(width 0.0889)
		(layer "In11.Cu")
		(net "P5E_CPU0_PE1_RX_DP<13>")
	)
	(arc
		(start 353.745546 -217.559128)
		(mid 353.61821 -217.689063)
		(end 353.567238 -217.863674)
		(width 0.0889)
		(layer "In11.Cu")
		(net "P5E_CPU0_PE1_RX_DP<13>")
	)
	(arc
		(start 354.506784 -221.133924)
		(mid 354.543644 -221.295721)
		(end 354.646738 -221.42577)
		(width 0.0889)
		(layer "In11.Cu")
		(net "P5E_CPU0_PE1_RX_DP<13>")
	)
	(arc
		(start 353.760532 -219.833952)
		(mid 353.962945 -220.040365)
		(end 354.036884 -220.319854)
		(width 0.0889)
		(layer "In11.Cu")
		(net "P5E_CPU0_PE1_RX_DP<13>")
	)
	(arc
		(start 353.290378 -215.764618)
		(mid 353.492965 -215.970969)
		(end 353.566984 -216.25052)
		(width 0.0889)
		(layer "In11.Cu")
		(net "P5E_CPU0_PE1_RX_DP<13>")
	)
	(arc
		(start 353.275392 -215.117426)
		(mid 353.148138 -215.247392)
		(end 353.097084 -215.421972)
		(width 0.0889)
		(layer "In11.Cu")
		(net "P5E_CPU0_PE1_RX_DP<13>")
	)
	(arc
		(start 353.09683 -215.436704)
		(mid 353.144509 -215.619604)
		(end 353.275392 -215.755982)
		(width 0.0889)
		(layer "In11.Cu")
		(net "P5E_CPU0_PE1_RX_DP<13>")
	)
	(arc
		(start 354.036884 -217.07856)
		(mid 353.957743 -217.353183)
		(end 353.754436 -217.554048)
		(width 0.0889)
		(layer "In11.Cu")
		(net "P5E_CPU0_PE1_RX_DP<13>")
	)
	(segment
		(start 399.646902 -7.761478)
		(end 399.489168 -7.603744)
		(width 0.13208)
		(layer "F.Cu")
		(net "P5E_CPU0_PE1_RX_DP<12>")
	)
	(segment
		(start 399.489168 -5.255006)
		(end 399.792444 -4.95173)
		(width 0.13208)
		(layer "F.Cu")
		(net "P5E_CPU0_PE1_RX_DP<12>")
	)
	(segment
		(start 399.646902 -8.320024)
		(end 399.646902 -7.761478)
		(width 0.13208)
		(layer "F.Cu")
		(net "P5E_CPU0_PE1_RX_DP<12>")
	)
	(segment
		(start 355.351334 -220.855794)
		(end 355.35108 -220.319854)
		(width 0.13208)
		(layer "F.Cu")
		(net "P5E_CPU0_PE1_RX_DP<12>")
	)
	(segment
		(start 399.489168 -7.603744)
		(end 399.489168 -5.255006)
		(width 0.13208)
		(layer "F.Cu")
		(net "P5E_CPU0_PE1_RX_DP<12>")
	)
	(segment
		(start 399.913094 -14.987778)
		(end 399.783554 -15.146274)
		(width 0.14732)
		(layer "In11.Cu")
		(net "P5E_CPU0_PE1_RX_DP<12>")
	)
	(segment
		(start 405.013414 -75.83932)
		(end 404.270464 -78.161896)
		(width 0.14732)
		(layer "In11.Cu")
		(net "P5E_CPU0_PE1_RX_DP<12>")
	)
	(segment
		(start 354.215192 -215.755982)
		(end 354.224082 -215.761062)
		(width 0.0889)
		(layer "In11.Cu")
		(net "P5E_CPU0_PE1_RX_DP<12>")
	)
	(segment
		(start 354.506276 -214.470996)
		(end 354.506276 -214.644732)
		(width 0.0889)
		(layer "In11.Cu")
		(net "P5E_CPU0_PE1_RX_DP<12>")
	)
	(segment
		(start 400.605498 -18.575274)
		(end 400.79676 -19.205448)
		(width 0.14732)
		(layer "In11.Cu")
		(net "P5E_CPU0_PE1_RX_DP<12>")
	)
	(segment
		(start 354.078794 -212.926168)
		(end 354.03663 -212.968332)
		(width 0.0889)
		(layer "In11.Cu")
		(net "P5E_CPU0_PE1_RX_DP<12>")
	)
	(segment
		(start 354.03663 -212.968332)
		(end 354.03663 -213.830662)
		(width 0.0889)
		(layer "In11.Cu")
		(net "P5E_CPU0_PE1_RX_DP<12>")
	)
	(segment
		(start 399.875756 -14.621002)
		(end 399.913094 -14.987778)
		(width 0.14732)
		(layer "In11.Cu")
		(net "P5E_CPU0_PE1_RX_DP<12>")
	)
	(segment
		(start 399.498058 -12.329922)
		(end 399.611088 -13.443458)
		(width 0.14732)
		(layer "In11.Cu")
		(net "P5E_CPU0_PE1_RX_DP<12>")
	)
	(segment
		(start 354.506022 -214.470996)
		(end 354.506276 -214.470996)
		(width 0.0889)
		(layer "In11.Cu")
		(net "P5E_CPU0_PE1_RX_DP<12>")
	)
	(segment
		(start 400.078956 -17.787112)
		(end 400.605498 -18.575274)
		(width 0.14732)
		(layer "In11.Cu")
		(net "P5E_CPU0_PE1_RX_DP<12>")
	)
	(segment
		(start 399.497804 -12.329668)
		(end 399.498058 -12.329922)
		(width 0.14732)
		(layer "In11.Cu")
		(net "P5E_CPU0_PE1_RX_DP<12>")
	)
	(segment
		(start 354.224082 -215.112346)
		(end 354.223066 -215.112854)
		(width 0.0889)
		(layer "In11.Cu")
		(net "P5E_CPU0_PE1_RX_DP<12>")
	)
	(segment
		(start 399.769584 -13.572998)
		(end 399.806668 -13.93952)
		(width 0.14732)
		(layer "In11.Cu")
		(net "P5E_CPU0_PE1_RX_DP<12>")
	)
	(segment
		(start 355.486462 -220.66885)
		(end 355.507544 -220.590872)
		(width 0.0889)
		(layer "In11.Cu")
		(net "P5E_CPU0_PE1_RX_DP<12>")
	)
	(segment
		(start 399.717006 -14.491716)
		(end 399.875756 -14.621002)
		(width 0.14732)
		(layer "In11.Cu")
		(net "P5E_CPU0_PE1_RX_DP<12>")
	)
	(segment
		(start 354.97643 -218.676728)
		(end 354.97643 -218.707716)
		(width 0.0889)
		(layer "In11.Cu")
		(net "P5E_CPU0_PE1_RX_DP<12>")
	)
	(segment
		(start 399.677128 -14.09827)
		(end 399.717006 -14.491716)
		(width 0.14732)
		(layer "In11.Cu")
		(net "P5E_CPU0_PE1_RX_DP<12>")
	)
	(segment
		(start 354.685346 -219.825316)
		(end 354.694236 -219.830396)
		(width 0.0889)
		(layer "In11.Cu")
		(net "P5E_CPU0_PE1_RX_DP<12>")
	)
	(segment
		(start 341.823548 -172.71619)
		(end 341.823548 -174.374556)
		(width 0.14732)
		(layer "In11.Cu")
		(net "P5E_CPU0_PE1_RX_DP<12>")
	)
	(segment
		(start 400.040856 -17.68094)
		(end 400.078956 -17.787112)
		(width 0.14732)
		(layer "In11.Cu")
		(net "P5E_CPU0_PE1_RX_DP<12>")
	)
	(segment
		(start 400.79676 -20.803616)
		(end 405.013414 -75.83932)
		(width 0.14732)
		(layer "In11.Cu")
		(net "P5E_CPU0_PE1_RX_DP<12>")
	)
	(segment
		(start 355.507544 -220.590872)
		(end 355.35108 -220.319854)
		(width 0.0889)
		(layer "In11.Cu")
		(net "P5E_CPU0_PE1_RX_DP<12>")
	)
	(segment
		(start 400.020536 -16.046196)
		(end 399.890996 -16.204946)
		(width 0.14732)
		(layer "In11.Cu")
		(net "P5E_CPU0_PE1_RX_DP<12>")
	)
	(segment
		(start 354.976684 -220.309948)
		(end 354.976684 -220.32849)
		(width 0.0889)
		(layer "In11.Cu")
		(net "P5E_CPU0_PE1_RX_DP<12>")
	)
	(segment
		(start 354.685346 -218.197684)
		(end 354.69322 -218.202256)
		(width 0.0889)
		(layer "In11.Cu")
		(net "P5E_CPU0_PE1_RX_DP<12>")
	)
	(segment
		(start 354.694236 -219.18168)
		(end 354.69322 -219.182188)
		(width 0.0889)
		(layer "In11.Cu")
		(net "P5E_CPU0_PE1_RX_DP<12>")
	)
	(segment
		(start 354.224082 -215.761062)
		(end 354.230178 -215.764618)
		(width 0.0889)
		(layer "In11.Cu")
		(net "P5E_CPU0_PE1_RX_DP<12>")
	)
	(segment
		(start 399.611088 -13.443458)
		(end 399.61058 -13.443458)
		(width 0.14732)
		(layer "In11.Cu")
		(net "P5E_CPU0_PE1_RX_DP<12>")
	)
	(segment
		(start 341.823548 -174.374556)
		(end 352.761042 -206.622142)
		(width 0.14732)
		(layer "In11.Cu")
		(net "P5E_CPU0_PE1_RX_DP<12>")
	)
	(segment
		(start 354.041202 -213.855046)
		(end 354.06711 -213.921086)
		(width 0.0889)
		(layer "In11.Cu")
		(net "P5E_CPU0_PE1_RX_DP<12>")
	)
	(segment
		(start 399.783554 -15.146274)
		(end 399.824448 -15.550134)
		(width 0.14732)
		(layer "In11.Cu")
		(net "P5E_CPU0_PE1_RX_DP<12>")
	)
	(segment
		(start 354.69322 -218.202256)
		(end 354.694236 -218.202764)
		(width 0.0889)
		(layer "In11.Cu")
		(net "P5E_CPU0_PE1_RX_DP<12>")
	)
	(segment
		(start 354.223066 -215.112854)
		(end 354.215192 -215.117426)
		(width 0.0889)
		(layer "In11.Cu")
		(net "P5E_CPU0_PE1_RX_DP<12>")
	)
	(segment
		(start 354.685346 -216.569798)
		(end 354.694236 -216.574878)
		(width 0.0889)
		(layer "In11.Cu")
		(net "P5E_CPU0_PE1_RX_DP<12>")
	)
	(segment
		(start 399.824448 -15.550134)
		(end 399.983452 -15.679674)
		(width 0.14732)
		(layer "In11.Cu")
		(net "P5E_CPU0_PE1_RX_DP<12>")
	)
	(segment
		(start 399.792444 -4.95173)
		(end 399.497804 -5.24637)
		(width 0.14732)
		(layer "In11.Cu")
		(net "P5E_CPU0_PE1_RX_DP<12>")
	)
	(segment
		(start 399.890996 -16.204946)
		(end 400.040856 -17.68094)
		(width 0.14732)
		(layer "In11.Cu")
		(net "P5E_CPU0_PE1_RX_DP<12>")
	)
	(segment
		(start 399.61058 -13.443458)
		(end 399.769584 -13.572998)
		(width 0.14732)
		(layer "In11.Cu")
		(net "P5E_CPU0_PE1_RX_DP<12>")
	)
	(segment
		(start 344.90406 -162.945826)
		(end 341.823548 -172.71619)
		(width 0.14732)
		(layer "In11.Cu")
		(net "P5E_CPU0_PE1_RX_DP<12>")
	)
	(segment
		(start 399.497804 -5.24637)
		(end 399.497804 -12.329668)
		(width 0.14732)
		(layer "In11.Cu")
		(net "P5E_CPU0_PE1_RX_DP<12>")
	)
	(segment
		(start 354.694236 -217.554048)
		(end 354.685346 -217.559128)
		(width 0.0889)
		(layer "In11.Cu")
		(net "P5E_CPU0_PE1_RX_DP<12>")
	)
	(segment
		(start 354.69322 -219.182188)
		(end 354.685346 -219.18676)
		(width 0.0889)
		(layer "In11.Cu")
		(net "P5E_CPU0_PE1_RX_DP<12>")
	)
	(segment
		(start 399.806668 -13.93952)
		(end 399.677128 -14.09827)
		(width 0.14732)
		(layer "In11.Cu")
		(net "P5E_CPU0_PE1_RX_DP<12>")
	)
	(segment
		(start 399.983452 -15.679674)
		(end 400.020536 -16.046196)
		(width 0.14732)
		(layer "In11.Cu")
		(net "P5E_CPU0_PE1_RX_DP<12>")
	)
	(segment
		(start 400.79676 -19.205448)
		(end 400.79676 -20.803616)
		(width 0.14732)
		(layer "In11.Cu")
		(net "P5E_CPU0_PE1_RX_DP<12>")
	)
	(segment
		(start 404.270464 -78.161896)
		(end 344.90406 -162.945826)
		(width 0.14732)
		(layer "In11.Cu")
		(net "P5E_CPU0_PE1_RX_DP<12>")
	)
	(segment
		(start 352.761042 -206.622142)
		(end 354.078794 -211.88807)
		(width 0.14732)
		(layer "In11.Cu")
		(net "P5E_CPU0_PE1_RX_DP<12>")
	)
	(segment
		(start 354.078794 -212.90407)
		(end 354.078794 -212.926168)
		(width 0.0889)
		(layer "In11.Cu")
		(net "P5E_CPU0_PE1_RX_DP<12>")
	)
	(segment
		(start 354.078794 -211.88807)
		(end 354.078794 -212.90407)
		(width 0.14732)
		(layer "In11.Cu")
		(net "P5E_CPU0_PE1_RX_DP<12>")
	)
	(arc
		(start 354.036884 -215.421972)
		(mid 354.036687 -215.429337)
		(end 354.03663 -215.436704)
		(width 0.0889)
		(layer "In11.Cu")
		(net "P5E_CPU0_PE1_RX_DP<12>")
	)
	(arc
		(start 354.03663 -213.830662)
		(mid 354.037754 -213.843073)
		(end 354.041202 -213.855046)
		(width 0.0889)
		(layer "In11.Cu")
		(net "P5E_CPU0_PE1_RX_DP<12>")
	)
	(arc
		(start 354.03663 -215.436704)
		(mid 354.084309 -215.619604)
		(end 354.215192 -215.755982)
		(width 0.0889)
		(layer "In11.Cu")
		(net "P5E_CPU0_PE1_RX_DP<12>")
	)
	(arc
		(start 354.694236 -216.574878)
		(mid 354.976988 -217.064526)
		(end 354.694236 -217.554048)
		(width 0.0889)
		(layer "In11.Cu")
		(net "P5E_CPU0_PE1_RX_DP<12>")
	)
	(arc
		(start 354.06711 -213.921086)
		(mid 354.128621 -214.021001)
		(end 354.221034 -214.093298)
		(width 0.0889)
		(layer "In11.Cu")
		(net "P5E_CPU0_PE1_RX_DP<12>")
	)
	(arc
		(start 354.506784 -216.25052)
		(mid 354.554463 -216.43342)
		(end 354.685346 -216.569798)
		(width 0.0889)
		(layer "In11.Cu")
		(net "P5E_CPU0_PE1_RX_DP<12>")
	)
	(arc
		(start 354.215192 -215.117426)
		(mid 354.087938 -215.247392)
		(end 354.036884 -215.421972)
		(width 0.0889)
		(layer "In11.Cu")
		(net "P5E_CPU0_PE1_RX_DP<12>")
	)
	(arc
		(start 354.230178 -215.764618)
		(mid 354.432765 -215.970969)
		(end 354.506784 -216.25052)
		(width 0.0889)
		(layer "In11.Cu")
		(net "P5E_CPU0_PE1_RX_DP<12>")
	)
	(arc
		(start 354.685346 -219.18676)
		(mid 354.557027 -219.318732)
		(end 354.507038 -219.495878)
		(width 0.0889)
		(layer "In11.Cu")
		(net "P5E_CPU0_PE1_RX_DP<12>")
	)
	(arc
		(start 354.481638 -214.365586)
		(mid 354.499662 -214.41694)
		(end 354.506022 -214.470996)
		(width 0.0889)
		(layer "In11.Cu")
		(net "P5E_CPU0_PE1_RX_DP<12>")
	)
	(arc
		(start 354.685346 -217.559128)
		(mid 354.557535 -217.690221)
		(end 354.507038 -217.866214)
		(width 0.0889)
		(layer "In11.Cu")
		(net "P5E_CPU0_PE1_RX_DP<12>")
	)
	(arc
		(start 354.694236 -219.830396)
		(mid 354.898571 -220.033001)
		(end 354.976684 -220.309948)
		(width 0.0889)
		(layer "In11.Cu")
		(net "P5E_CPU0_PE1_RX_DP<12>")
	)
	(arc
		(start 354.507038 -217.888566)
		(mid 354.557053 -218.065697)
		(end 354.685346 -218.197684)
		(width 0.0889)
		(layer "In11.Cu")
		(net "P5E_CPU0_PE1_RX_DP<12>")
	)
	(arc
		(start 354.976684 -220.32849)
		(mid 355.143009 -220.631339)
		(end 355.486462 -220.66885)
		(width 0.0889)
		(layer "In11.Cu")
		(net "P5E_CPU0_PE1_RX_DP<12>")
	)
	(arc
		(start 354.507038 -219.495878)
		(mid 354.506944 -219.50426)
		(end 354.507038 -219.512642)
		(width 0.0889)
		(layer "In11.Cu")
		(net "P5E_CPU0_PE1_RX_DP<12>")
	)
	(arc
		(start 354.507038 -219.512642)
		(mid 354.556237 -219.691748)
		(end 354.685346 -219.825316)
		(width 0.0889)
		(layer "In11.Cu")
		(net "P5E_CPU0_PE1_RX_DP<12>")
	)
	(arc
		(start 354.506276 -214.644732)
		(mid 354.425365 -214.91486)
		(end 354.224082 -215.112346)
		(width 0.0889)
		(layer "In11.Cu")
		(net "P5E_CPU0_PE1_RX_DP<12>")
	)
	(arc
		(start 354.97643 -218.707716)
		(mid 354.89706 -218.98145)
		(end 354.694236 -219.18168)
		(width 0.0889)
		(layer "In11.Cu")
		(net "P5E_CPU0_PE1_RX_DP<12>")
	)
	(arc
		(start 354.694236 -218.202764)
		(mid 354.897059 -218.402995)
		(end 354.97643 -218.676728)
		(width 0.0889)
		(layer "In11.Cu")
		(net "P5E_CPU0_PE1_RX_DP<12>")
	)
	(arc
		(start 354.507038 -217.866214)
		(mid 354.506871 -217.87739)
		(end 354.507038 -217.888566)
		(width 0.0889)
		(layer "In11.Cu")
		(net "P5E_CPU0_PE1_RX_DP<12>")
	)
	(arc
		(start 354.221034 -214.093298)
		(mid 354.37334 -214.208387)
		(end 354.481638 -214.365586)
		(width 0.0889)
		(layer "In11.Cu")
		(net "P5E_CPU0_PE1_RX_DP<12>")
	)
	(segment
		(start 401.285456 -7.015734)
		(end 401.587716 -6.713474)
		(width 0.13208)
		(layer "F.Cu")
		(net "P5E_CPU0_PE1_RX_DP<11>")
	)
	(segment
		(start 356.76078 -221.669864)
		(end 356.761034 -221.133924)
		(width 0.13208)
		(layer "F.Cu")
		(net "P5E_CPU0_PE1_RX_DP<11>")
	)
	(segment
		(start 401.446746 -8.320024)
		(end 401.446746 -7.761224)
		(width 0.13208)
		(layer "F.Cu")
		(net "P5E_CPU0_PE1_RX_DP<11>")
	)
	(segment
		(start 401.446746 -7.761224)
		(end 401.285456 -7.599934)
		(width 0.13208)
		(layer "F.Cu")
		(net "P5E_CPU0_PE1_RX_DP<11>")
	)
	(segment
		(start 401.285456 -7.599934)
		(end 401.285456 -7.015734)
		(width 0.13208)
		(layer "F.Cu")
		(net "P5E_CPU0_PE1_RX_DP<11>")
	)
	(segment
		(start 402.82622 -19.348196)
		(end 402.976334 -19.710654)
		(width 0.14732)
		(layer "In11.Cu")
		(net "P5E_CPU0_PE1_RX_DP<11>")
	)
	(segment
		(start 402.976334 -19.710654)
		(end 403.082252 -19.915124)
		(width 0.14732)
		(layer "In11.Cu")
		(net "P5E_CPU0_PE1_RX_DP<11>")
	)
	(segment
		(start 401.338542 -12.624308)
		(end 402.014182 -14.040866)
		(width 0.14732)
		(layer "In11.Cu")
		(net "P5E_CPU0_PE1_RX_DP<11>")
	)
	(segment
		(start 355.916484 -217.064336)
		(end 355.916484 -217.07856)
		(width 0.0889)
		(layer "In11.Cu")
		(net "P5E_CPU0_PE1_RX_DP<11>")
	)
	(segment
		(start 403.54758 -17.884648)
		(end 402.82622 -18.964148)
		(width 0.14732)
		(layer "In11.Cu")
		(net "P5E_CPU0_PE1_RX_DP<11>")
	)
	(segment
		(start 402.014182 -14.040866)
		(end 402.207476 -14.109192)
		(width 0.14732)
		(layer "In11.Cu")
		(net "P5E_CPU0_PE1_RX_DP<11>")
	)
	(segment
		(start 356.095046 -220.639132)
		(end 356.103936 -220.644212)
		(width 0.0889)
		(layer "In11.Cu")
		(net "P5E_CPU0_PE1_RX_DP<11>")
	)
	(segment
		(start 402.787612 -15.662402)
		(end 403.54758 -17.255998)
		(width 0.14732)
		(layer "In11.Cu")
		(net "P5E_CPU0_PE1_RX_DP<11>")
	)
	(segment
		(start 355.162866 -215.112854)
		(end 355.154992 -215.117426)
		(width 0.0889)
		(layer "In11.Cu")
		(net "P5E_CPU0_PE1_RX_DP<11>")
	)
	(segment
		(start 355.625146 -218.197684)
		(end 355.634036 -218.202764)
		(width 0.0889)
		(layer "In11.Cu")
		(net "P5E_CPU0_PE1_RX_DP<11>")
	)
	(segment
		(start 406.048972 -75.929998)
		(end 405.160734 -78.522068)
		(width 0.14732)
		(layer "In11.Cu")
		(net "P5E_CPU0_PE1_RX_DP<11>")
	)
	(segment
		(start 356.526338 -221.42577)
		(end 356.60457 -221.404942)
		(width 0.0889)
		(layer "In11.Cu")
		(net "P5E_CPU0_PE1_RX_DP<11>")
	)
	(segment
		(start 355.634036 -216.574878)
		(end 355.640132 -216.578434)
		(width 0.0889)
		(layer "In11.Cu")
		(net "P5E_CPU0_PE1_RX_DP<11>")
	)
	(segment
		(start 355.634036 -219.830396)
		(end 355.640132 -219.833952)
		(width 0.0889)
		(layer "In11.Cu")
		(net "P5E_CPU0_PE1_RX_DP<11>")
	)
	(segment
		(start 355.446076 -214.424768)
		(end 355.446076 -214.644732)
		(width 0.0889)
		(layer "In11.Cu")
		(net "P5E_CPU0_PE1_RX_DP<11>")
	)
	(segment
		(start 402.82622 -18.964148)
		(end 402.82622 -19.348196)
		(width 0.14732)
		(layer "In11.Cu")
		(net "P5E_CPU0_PE1_RX_DP<11>")
	)
	(segment
		(start 355.018848 -212.90407)
		(end 355.018848 -212.926168)
		(width 0.0889)
		(layer "In11.Cu")
		(net "P5E_CPU0_PE1_RX_DP<11>")
	)
	(segment
		(start 402.297646 -14.634972)
		(end 402.504148 -15.068296)
		(width 0.14732)
		(layer "In11.Cu")
		(net "P5E_CPU0_PE1_RX_DP<11>")
	)
	(segment
		(start 342.756744 -174.178214)
		(end 353.626928 -205.84922)
		(width 0.14732)
		(layer "In11.Cu")
		(net "P5E_CPU0_PE1_RX_DP<11>")
	)
	(segment
		(start 353.626928 -205.84922)
		(end 355.018848 -211.784438)
		(width 0.14732)
		(layer "In11.Cu")
		(net "P5E_CPU0_PE1_RX_DP<11>")
	)
	(segment
		(start 356.386384 -221.115382)
		(end 356.386384 -221.133924)
		(width 0.0889)
		(layer "In11.Cu")
		(net "P5E_CPU0_PE1_RX_DP<11>")
	)
	(segment
		(start 405.160734 -78.522068)
		(end 345.742768 -163.378896)
		(width 0.14732)
		(layer "In11.Cu")
		(net "P5E_CPU0_PE1_RX_DP<11>")
	)
	(segment
		(start 403.082252 -19.915124)
		(end 406.048972 -75.929998)
		(width 0.14732)
		(layer "In11.Cu")
		(net "P5E_CPU0_PE1_RX_DP<11>")
	)
	(segment
		(start 355.018848 -212.926168)
		(end 354.976684 -212.968332)
		(width 0.0889)
		(layer "In11.Cu")
		(net "P5E_CPU0_PE1_RX_DP<11>")
	)
	(segment
		(start 342.756744 -172.849032)
		(end 342.756744 -174.178214)
		(width 0.14732)
		(layer "In11.Cu")
		(net "P5E_CPU0_PE1_RX_DP<11>")
	)
	(segment
		(start 355.163882 -215.112346)
		(end 355.162866 -215.112854)
		(width 0.0889)
		(layer "In11.Cu")
		(net "P5E_CPU0_PE1_RX_DP<11>")
	)
	(segment
		(start 356.60457 -221.404942)
		(end 356.761034 -221.133924)
		(width 0.0889)
		(layer "In11.Cu")
		(net "P5E_CPU0_PE1_RX_DP<11>")
	)
	(segment
		(start 355.018848 -211.784438)
		(end 355.018848 -212.90407)
		(width 0.14732)
		(layer "In11.Cu")
		(net "P5E_CPU0_PE1_RX_DP<11>")
	)
	(segment
		(start 354.976684 -212.968332)
		(end 354.976684 -213.893908)
		(width 0.0889)
		(layer "In11.Cu")
		(net "P5E_CPU0_PE1_RX_DP<11>")
	)
	(segment
		(start 402.504148 -15.068296)
		(end 402.697442 -15.136622)
		(width 0.14732)
		(layer "In11.Cu")
		(net "P5E_CPU0_PE1_RX_DP<11>")
	)
	(segment
		(start 403.54758 -17.255998)
		(end 403.54758 -17.884648)
		(width 0.14732)
		(layer "In11.Cu")
		(net "P5E_CPU0_PE1_RX_DP<11>")
	)
	(segment
		(start 401.293076 -12.423394)
		(end 401.338542 -12.624308)
		(width 0.14732)
		(layer "In11.Cu")
		(net "P5E_CPU0_PE1_RX_DP<11>")
	)
	(segment
		(start 355.634036 -219.18168)
		(end 355.625146 -219.18676)
		(width 0.0889)
		(layer "In11.Cu")
		(net "P5E_CPU0_PE1_RX_DP<11>")
	)
	(segment
		(start 402.207476 -14.109192)
		(end 402.365972 -14.441932)
		(width 0.14732)
		(layer "In11.Cu")
		(net "P5E_CPU0_PE1_RX_DP<11>")
	)
	(segment
		(start 355.625146 -216.569798)
		(end 355.634036 -216.574878)
		(width 0.0889)
		(layer "In11.Cu")
		(net "P5E_CPU0_PE1_RX_DP<11>")
	)
	(segment
		(start 401.293076 -7.008114)
		(end 401.293076 -12.423394)
		(width 0.14732)
		(layer "In11.Cu")
		(net "P5E_CPU0_PE1_RX_DP<11>")
	)
	(segment
		(start 401.587716 -6.713474)
		(end 401.293076 -7.008114)
		(width 0.14732)
		(layer "In11.Cu")
		(net "P5E_CPU0_PE1_RX_DP<11>")
	)
	(segment
		(start 355.163882 -215.761062)
		(end 355.169978 -215.764618)
		(width 0.0889)
		(layer "In11.Cu")
		(net "P5E_CPU0_PE1_RX_DP<11>")
	)
	(segment
		(start 355.634036 -217.554048)
		(end 355.625146 -217.559128)
		(width 0.0889)
		(layer "In11.Cu")
		(net "P5E_CPU0_PE1_RX_DP<11>")
	)
	(segment
		(start 402.365972 -14.441932)
		(end 402.297646 -14.634972)
		(width 0.14732)
		(layer "In11.Cu")
		(net "P5E_CPU0_PE1_RX_DP<11>")
	)
	(segment
		(start 355.91623 -218.676728)
		(end 355.91623 -218.707716)
		(width 0.0889)
		(layer "In11.Cu")
		(net "P5E_CPU0_PE1_RX_DP<11>")
	)
	(segment
		(start 402.855938 -15.469362)
		(end 402.787612 -15.662402)
		(width 0.14732)
		(layer "In11.Cu")
		(net "P5E_CPU0_PE1_RX_DP<11>")
	)
	(segment
		(start 402.697442 -15.136622)
		(end 402.855938 -15.469362)
		(width 0.14732)
		(layer "In11.Cu")
		(net "P5E_CPU0_PE1_RX_DP<11>")
	)
	(segment
		(start 345.742768 -163.378896)
		(end 342.756744 -172.849032)
		(width 0.14732)
		(layer "In11.Cu")
		(net "P5E_CPU0_PE1_RX_DP<11>")
	)
	(segment
		(start 355.625146 -219.825316)
		(end 355.634036 -219.830396)
		(width 0.0889)
		(layer "In11.Cu")
		(net "P5E_CPU0_PE1_RX_DP<11>")
	)
	(segment
		(start 355.154992 -215.755982)
		(end 355.163882 -215.761062)
		(width 0.0889)
		(layer "In11.Cu")
		(net "P5E_CPU0_PE1_RX_DP<11>")
	)
	(arc
		(start 355.625146 -219.18676)
		(mid 355.44667 -219.506038)
		(end 355.625146 -219.825316)
		(width 0.0889)
		(layer "In11.Cu")
		(net "P5E_CPU0_PE1_RX_DP<11>")
	)
	(arc
		(start 356.386384 -221.133924)
		(mid 356.423244 -221.295721)
		(end 356.526338 -221.42577)
		(width 0.0889)
		(layer "In11.Cu")
		(net "P5E_CPU0_PE1_RX_DP<11>")
	)
	(arc
		(start 355.154992 -215.117426)
		(mid 355.027738 -215.247392)
		(end 354.976684 -215.421972)
		(width 0.0889)
		(layer "In11.Cu")
		(net "P5E_CPU0_PE1_RX_DP<11>")
	)
	(arc
		(start 355.91623 -218.707716)
		(mid 355.83686 -218.98145)
		(end 355.634036 -219.18168)
		(width 0.0889)
		(layer "In11.Cu")
		(net "P5E_CPU0_PE1_RX_DP<11>")
	)
	(arc
		(start 355.446076 -214.644732)
		(mid 355.365165 -214.91486)
		(end 355.163882 -215.112346)
		(width 0.0889)
		(layer "In11.Cu")
		(net "P5E_CPU0_PE1_RX_DP<11>")
	)
	(arc
		(start 355.640132 -219.833952)
		(mid 355.842545 -220.040365)
		(end 355.916484 -220.319854)
		(width 0.0889)
		(layer "In11.Cu")
		(net "P5E_CPU0_PE1_RX_DP<11>")
	)
	(arc
		(start 355.446584 -217.888566)
		(mid 355.496653 -218.065791)
		(end 355.625146 -218.197684)
		(width 0.0889)
		(layer "In11.Cu")
		(net "P5E_CPU0_PE1_RX_DP<11>")
	)
	(arc
		(start 356.103936 -220.644212)
		(mid 356.306222 -220.843193)
		(end 356.386384 -221.115382)
		(width 0.0889)
		(layer "In11.Cu")
		(net "P5E_CPU0_PE1_RX_DP<11>")
	)
	(arc
		(start 354.976684 -215.421972)
		(mid 354.976487 -215.429337)
		(end 354.97643 -215.436704)
		(width 0.0889)
		(layer "In11.Cu")
		(net "P5E_CPU0_PE1_RX_DP<11>")
	)
	(arc
		(start 355.625146 -217.559128)
		(mid 355.497892 -217.689094)
		(end 355.446838 -217.863674)
		(width 0.0889)
		(layer "In11.Cu")
		(net "P5E_CPU0_PE1_RX_DP<11>")
	)
	(arc
		(start 355.446838 -217.863674)
		(mid 355.446505 -217.876118)
		(end 355.446584 -217.888566)
		(width 0.0889)
		(layer "In11.Cu")
		(net "P5E_CPU0_PE1_RX_DP<11>")
	)
	(arc
		(start 355.634036 -218.202764)
		(mid 355.836859 -218.402995)
		(end 355.91623 -218.676728)
		(width 0.0889)
		(layer "In11.Cu")
		(net "P5E_CPU0_PE1_RX_DP<11>")
	)
	(arc
		(start 355.916484 -217.07856)
		(mid 355.837343 -217.353183)
		(end 355.634036 -217.554048)
		(width 0.0889)
		(layer "In11.Cu")
		(net "P5E_CPU0_PE1_RX_DP<11>")
	)
	(arc
		(start 355.446584 -216.25052)
		(mid 355.494263 -216.43342)
		(end 355.625146 -216.569798)
		(width 0.0889)
		(layer "In11.Cu")
		(net "P5E_CPU0_PE1_RX_DP<11>")
	)
	(arc
		(start 355.916484 -220.319854)
		(mid 355.964163 -220.502754)
		(end 356.095046 -220.639132)
		(width 0.0889)
		(layer "In11.Cu")
		(net "P5E_CPU0_PE1_RX_DP<11>")
	)
	(arc
		(start 355.160834 -214.093298)
		(mid 355.334797 -214.232062)
		(end 355.446076 -214.424768)
		(width 0.0889)
		(layer "In11.Cu")
		(net "P5E_CPU0_PE1_RX_DP<11>")
	)
	(arc
		(start 355.169978 -215.764618)
		(mid 355.372565 -215.970969)
		(end 355.446584 -216.25052)
		(width 0.0889)
		(layer "In11.Cu")
		(net "P5E_CPU0_PE1_RX_DP<11>")
	)
	(arc
		(start 354.976684 -213.893908)
		(mid 355.051689 -214.009367)
		(end 355.160834 -214.093298)
		(width 0.0889)
		(layer "In11.Cu")
		(net "P5E_CPU0_PE1_RX_DP<11>")
	)
	(arc
		(start 354.97643 -215.436704)
		(mid 355.024109 -215.619604)
		(end 355.154992 -215.755982)
		(width 0.0889)
		(layer "In11.Cu")
		(net "P5E_CPU0_PE1_RX_DP<11>")
	)
	(arc
		(start 355.640132 -216.578434)
		(mid 355.842545 -216.784847)
		(end 355.916484 -217.064336)
		(width 0.0889)
		(layer "In11.Cu")
		(net "P5E_CPU0_PE1_RX_DP<11>")
	)
	(segment
		(start 403.246844 -7.756398)
		(end 403.08911 -7.598664)
		(width 0.13208)
		(layer "F.Cu")
		(net "P5E_CPU0_PE1_RX_DP<10>")
	)
	(segment
		(start 403.246844 -8.320024)
		(end 403.246844 -7.756398)
		(width 0.13208)
		(layer "F.Cu")
		(net "P5E_CPU0_PE1_RX_DP<10>")
	)
	(segment
		(start 403.08911 -5.255006)
		(end 403.392386 -4.95173)
		(width 0.13208)
		(layer "F.Cu")
		(net "P5E_CPU0_PE1_RX_DP<10>")
	)
	(segment
		(start 403.08911 -7.598664)
		(end 403.08911 -5.255006)
		(width 0.13208)
		(layer "F.Cu")
		(net "P5E_CPU0_PE1_RX_DP<10>")
	)
	(segment
		(start 357.230934 -220.855794)
		(end 357.23068 -220.319854)
		(width 0.13208)
		(layer "F.Cu")
		(net "P5E_CPU0_PE1_RX_DP<10>")
	)
	(segment
		(start 406.522936 -50.536856)
		(end 406.8826 -61.707014)
		(width 0.14732)
		(layer "In11.Cu")
		(net "P5E_CPU0_PE1_RX_DP<10>")
	)
	(segment
		(start 356.564946 -216.569798)
		(end 356.573836 -216.574878)
		(width 0.0889)
		(layer "In11.Cu")
		(net "P5E_CPU0_PE1_RX_DP<10>")
	)
	(segment
		(start 404.173436 -14.410436)
		(end 404.338028 -14.473428)
		(width 0.14732)
		(layer "In11.Cu")
		(net "P5E_CPU0_PE1_RX_DP<10>")
	)
	(segment
		(start 356.38613 -214.46236)
		(end 356.38613 -214.636858)
		(width 0.0889)
		(layer "In11.Cu")
		(net "P5E_CPU0_PE1_RX_DP<10>")
	)
	(segment
		(start 356.898702 -212.340444)
		(end 356.898702 -212.93201)
		(width 0.14732)
		(layer "In11.Cu")
		(net "P5E_CPU0_PE1_RX_DP<10>")
	)
	(segment
		(start 405.365712 -17.08912)
		(end 405.809196 -18.085816)
		(width 0.14732)
		(layer "In11.Cu")
		(net "P5E_CPU0_PE1_RX_DP<10>")
	)
	(segment
		(start 343.692988 -172.972984)
		(end 343.692734 -172.973238)
		(width 0.14732)
		(layer "In11.Cu")
		(net "P5E_CPU0_PE1_RX_DP<10>")
	)
	(segment
		(start 406.8826 -61.981334)
		(end 407.089356 -76.201016)
		(width 0.14732)
		(layer "In11.Cu")
		(net "P5E_CPU0_PE1_RX_DP<10>")
	)
	(segment
		(start 406.258268 -18.757392)
		(end 406.482804 -19.93011)
		(width 0.14732)
		(layer "In11.Cu")
		(net "P5E_CPU0_PE1_RX_DP<10>")
	)
	(segment
		(start 356.856284 -220.309948)
		(end 356.856284 -220.32849)
		(width 0.0889)
		(layer "In11.Cu")
		(net "P5E_CPU0_PE1_RX_DP<10>")
	)
	(segment
		(start 404.338028 -14.473428)
		(end 404.515574 -14.87297)
		(width 0.14732)
		(layer "In11.Cu")
		(net "P5E_CPU0_PE1_RX_DP<10>")
	)
	(segment
		(start 356.85603 -218.676728)
		(end 356.85603 -218.707716)
		(width 0.0889)
		(layer "In11.Cu")
		(net "P5E_CPU0_PE1_RX_DP<10>")
	)
	(segment
		(start 403.70379 -13.048996)
		(end 403.881336 -13.448284)
		(width 0.14732)
		(layer "In11.Cu")
		(net "P5E_CPU0_PE1_RX_DP<10>")
	)
	(segment
		(start 403.818344 -13.612622)
		(end 404.173182 -14.410436)
		(width 0.14732)
		(layer "In11.Cu")
		(net "P5E_CPU0_PE1_RX_DP<10>")
	)
	(segment
		(start 403.392386 -4.95173)
		(end 403.097746 -5.24637)
		(width 0.14732)
		(layer "In11.Cu")
		(net "P5E_CPU0_PE1_RX_DP<10>")
	)
	(segment
		(start 356.856538 -214.001604)
		(end 356.62489 -214.233252)
		(width 0.0889)
		(layer "In11.Cu")
		(net "P5E_CPU0_PE1_RX_DP<10>")
	)
	(segment
		(start 403.881336 -13.448284)
		(end 403.818344 -13.612622)
		(width 0.14732)
		(layer "In11.Cu")
		(net "P5E_CPU0_PE1_RX_DP<10>")
	)
	(segment
		(start 356.62489 -214.233252)
		(end 356.570534 -214.261954)
		(width 0.0889)
		(layer "In11.Cu")
		(net "P5E_CPU0_PE1_RX_DP<10>")
	)
	(segment
		(start 356.573836 -217.554048)
		(end 356.564946 -217.559128)
		(width 0.0889)
		(layer "In11.Cu")
		(net "P5E_CPU0_PE1_RX_DP<10>")
	)
	(segment
		(start 404.630128 -15.436342)
		(end 404.79472 -15.499334)
		(width 0.14732)
		(layer "In11.Cu")
		(net "P5E_CPU0_PE1_RX_DP<10>")
	)
	(segment
		(start 343.692734 -173.982888)
		(end 356.88397 -212.325712)
		(width 0.14732)
		(layer "In11.Cu")
		(net "P5E_CPU0_PE1_RX_DP<10>")
	)
	(segment
		(start 403.539198 -12.98575)
		(end 403.70379 -13.048996)
		(width 0.14732)
		(layer "In11.Cu")
		(net "P5E_CPU0_PE1_RX_DP<10>")
	)
	(segment
		(start 356.856284 -217.05443)
		(end 356.856284 -217.082878)
		(width 0.0889)
		(layer "In11.Cu")
		(net "P5E_CPU0_PE1_RX_DP<10>")
	)
	(segment
		(start 405.251412 -16.52524)
		(end 405.428958 -16.924782)
		(width 0.14732)
		(layer "In11.Cu")
		(net "P5E_CPU0_PE1_RX_DP<10>")
	)
	(segment
		(start 405.428958 -16.924782)
		(end 405.365712 -17.08912)
		(width 0.14732)
		(layer "In11.Cu")
		(net "P5E_CPU0_PE1_RX_DP<10>")
	)
	(segment
		(start 343.692734 -172.973238)
		(end 343.692734 -173.982888)
		(width 0.14732)
		(layer "In11.Cu")
		(net "P5E_CPU0_PE1_RX_DP<10>")
	)
	(segment
		(start 404.909274 -16.063214)
		(end 405.08682 -16.462248)
		(width 0.14732)
		(layer "In11.Cu")
		(net "P5E_CPU0_PE1_RX_DP<10>")
	)
	(segment
		(start 406.8826 -61.707014)
		(end 406.8826 -61.981334)
		(width 0.14732)
		(layer "In11.Cu")
		(net "P5E_CPU0_PE1_RX_DP<10>")
	)
	(segment
		(start 406.482804 -19.93011)
		(end 406.522936 -50.536856)
		(width 0.14732)
		(layer "In11.Cu")
		(net "P5E_CPU0_PE1_RX_DP<10>")
	)
	(segment
		(start 356.573836 -219.18168)
		(end 356.564946 -219.18676)
		(width 0.0889)
		(layer "In11.Cu")
		(net "P5E_CPU0_PE1_RX_DP<10>")
	)
	(segment
		(start 356.57282 -218.202256)
		(end 356.573836 -218.202764)
		(width 0.0889)
		(layer "In11.Cu")
		(net "P5E_CPU0_PE1_RX_DP<10>")
	)
	(segment
		(start 356.898702 -212.954108)
		(end 356.856538 -212.996272)
		(width 0.0889)
		(layer "In11.Cu")
		(net "P5E_CPU0_PE1_RX_DP<10>")
	)
	(segment
		(start 346.582746 -163.807648)
		(end 343.692988 -172.972984)
		(width 0.14732)
		(layer "In11.Cu")
		(net "P5E_CPU0_PE1_RX_DP<10>")
	)
	(segment
		(start 404.173182 -14.410436)
		(end 404.173436 -14.410436)
		(width 0.14732)
		(layer "In11.Cu")
		(net "P5E_CPU0_PE1_RX_DP<10>")
	)
	(segment
		(start 403.097746 -11.99388)
		(end 403.539198 -12.98575)
		(width 0.14732)
		(layer "In11.Cu")
		(net "P5E_CPU0_PE1_RX_DP<10>")
	)
	(segment
		(start 356.564946 -218.197684)
		(end 356.57282 -218.202256)
		(width 0.0889)
		(layer "In11.Cu")
		(net "P5E_CPU0_PE1_RX_DP<10>")
	)
	(segment
		(start 404.452582 -15.037308)
		(end 404.630128 -15.436342)
		(width 0.14732)
		(layer "In11.Cu")
		(net "P5E_CPU0_PE1_RX_DP<10>")
	)
	(segment
		(start 405.08682 -16.462248)
		(end 405.251412 -16.52524)
		(width 0.14732)
		(layer "In11.Cu")
		(net "P5E_CPU0_PE1_RX_DP<10>")
	)
	(segment
		(start 356.898702 -212.93201)
		(end 356.898702 -212.954108)
		(width 0.0889)
		(layer "In11.Cu")
		(net "P5E_CPU0_PE1_RX_DP<10>")
	)
	(segment
		(start 357.387144 -220.590872)
		(end 357.23068 -220.319854)
		(width 0.0889)
		(layer "In11.Cu")
		(net "P5E_CPU0_PE1_RX_DP<10>")
	)
	(segment
		(start 356.094792 -215.755982)
		(end 356.102158 -215.7603)
		(width 0.0889)
		(layer "In11.Cu")
		(net "P5E_CPU0_PE1_RX_DP<10>")
	)
	(segment
		(start 356.102158 -215.7603)
		(end 356.103682 -215.761062)
		(width 0.0889)
		(layer "In11.Cu")
		(net "P5E_CPU0_PE1_RX_DP<10>")
	)
	(segment
		(start 356.103682 -215.112346)
		(end 356.094792 -215.117426)
		(width 0.0889)
		(layer "In11.Cu")
		(net "P5E_CPU0_PE1_RX_DP<10>")
	)
	(segment
		(start 404.515574 -14.87297)
		(end 404.452582 -15.037308)
		(width 0.14732)
		(layer "In11.Cu")
		(net "P5E_CPU0_PE1_RX_DP<10>")
	)
	(segment
		(start 406.050496 -78.879446)
		(end 346.582746 -163.807648)
		(width 0.14732)
		(layer "In11.Cu")
		(net "P5E_CPU0_PE1_RX_DP<10>")
	)
	(segment
		(start 407.089356 -76.201016)
		(end 406.050496 -78.879446)
		(width 0.14732)
		(layer "In11.Cu")
		(net "P5E_CPU0_PE1_RX_DP<10>")
	)
	(segment
		(start 403.097746 -5.24637)
		(end 403.097746 -11.99388)
		(width 0.14732)
		(layer "In11.Cu")
		(net "P5E_CPU0_PE1_RX_DP<10>")
	)
	(segment
		(start 356.106476 -215.762586)
		(end 356.109778 -215.764618)
		(width 0.0889)
		(layer "In11.Cu")
		(net "P5E_CPU0_PE1_RX_DP<10>")
	)
	(segment
		(start 405.809196 -18.085816)
		(end 406.258268 -18.757392)
		(width 0.14732)
		(layer "In11.Cu")
		(net "P5E_CPU0_PE1_RX_DP<10>")
	)
	(segment
		(start 356.564946 -219.825316)
		(end 356.573836 -219.830396)
		(width 0.0889)
		(layer "In11.Cu")
		(net "P5E_CPU0_PE1_RX_DP<10>")
	)
	(segment
		(start 404.79472 -15.499334)
		(end 404.972266 -15.898876)
		(width 0.14732)
		(layer "In11.Cu")
		(net "P5E_CPU0_PE1_RX_DP<10>")
	)
	(segment
		(start 356.103682 -215.761062)
		(end 356.106476 -215.762586)
		(width 0.0889)
		(layer "In11.Cu")
		(net "P5E_CPU0_PE1_RX_DP<10>")
	)
	(segment
		(start 357.366062 -220.66885)
		(end 357.387144 -220.590872)
		(width 0.0889)
		(layer "In11.Cu")
		(net "P5E_CPU0_PE1_RX_DP<10>")
	)
	(segment
		(start 356.88397 -212.325712)
		(end 356.898702 -212.340444)
		(width 0.14732)
		(layer "In11.Cu")
		(net "P5E_CPU0_PE1_RX_DP<10>")
	)
	(segment
		(start 356.856538 -212.996272)
		(end 356.856538 -214.001604)
		(width 0.0889)
		(layer "In11.Cu")
		(net "P5E_CPU0_PE1_RX_DP<10>")
	)
	(segment
		(start 404.972266 -15.898876)
		(end 404.909274 -16.063214)
		(width 0.14732)
		(layer "In11.Cu")
		(net "P5E_CPU0_PE1_RX_DP<10>")
	)
	(arc
		(start 356.573836 -219.830396)
		(mid 356.778171 -220.033001)
		(end 356.856284 -220.309948)
		(width 0.0889)
		(layer "In11.Cu")
		(net "P5E_CPU0_PE1_RX_DP<10>")
	)
	(arc
		(start 356.856284 -220.32849)
		(mid 356.908554 -220.510855)
		(end 357.043482 -220.644212)
		(width 0.0889)
		(layer "In11.Cu")
		(net "P5E_CPU0_PE1_RX_DP<10>")
	)
	(arc
		(start 356.38613 -214.636858)
		(mid 356.306919 -214.911426)
		(end 356.103682 -215.112346)
		(width 0.0889)
		(layer "In11.Cu")
		(net "P5E_CPU0_PE1_RX_DP<10>")
	)
	(arc
		(start 356.564946 -217.559128)
		(mid 356.437135 -217.690221)
		(end 356.386638 -217.866214)
		(width 0.0889)
		(layer "In11.Cu")
		(net "P5E_CPU0_PE1_RX_DP<10>")
	)
	(arc
		(start 356.094792 -215.117426)
		(mid 355.967538 -215.247392)
		(end 355.916484 -215.421972)
		(width 0.0889)
		(layer "In11.Cu")
		(net "P5E_CPU0_PE1_RX_DP<10>")
	)
	(arc
		(start 356.386638 -219.495878)
		(mid 356.386544 -219.50426)
		(end 356.386638 -219.512642)
		(width 0.0889)
		(layer "In11.Cu")
		(net "P5E_CPU0_PE1_RX_DP<10>")
	)
	(arc
		(start 356.386384 -216.25052)
		(mid 356.434063 -216.43342)
		(end 356.564946 -216.569798)
		(width 0.0889)
		(layer "In11.Cu")
		(net "P5E_CPU0_PE1_RX_DP<10>")
	)
	(arc
		(start 355.91623 -215.436704)
		(mid 355.963909 -215.619604)
		(end 356.094792 -215.755982)
		(width 0.0889)
		(layer "In11.Cu")
		(net "P5E_CPU0_PE1_RX_DP<10>")
	)
	(arc
		(start 356.573836 -218.202764)
		(mid 356.776659 -218.402995)
		(end 356.85603 -218.676728)
		(width 0.0889)
		(layer "In11.Cu")
		(net "P5E_CPU0_PE1_RX_DP<10>")
	)
	(arc
		(start 356.386638 -217.888566)
		(mid 356.436653 -218.065697)
		(end 356.564946 -218.197684)
		(width 0.0889)
		(layer "In11.Cu")
		(net "P5E_CPU0_PE1_RX_DP<10>")
	)
	(arc
		(start 356.573836 -216.574878)
		(mid 356.778171 -216.777483)
		(end 356.856284 -217.05443)
		(width 0.0889)
		(layer "In11.Cu")
		(net "P5E_CPU0_PE1_RX_DP<10>")
	)
	(arc
		(start 356.856284 -217.082878)
		(mid 356.776122 -217.355067)
		(end 356.573836 -217.554048)
		(width 0.0889)
		(layer "In11.Cu")
		(net "P5E_CPU0_PE1_RX_DP<10>")
	)
	(arc
		(start 356.570534 -214.261954)
		(mid 356.461139 -214.346329)
		(end 356.38613 -214.46236)
		(width 0.0889)
		(layer "In11.Cu")
		(net "P5E_CPU0_PE1_RX_DP<10>")
	)
	(arc
		(start 356.85603 -218.707716)
		(mid 356.77666 -218.98145)
		(end 356.573836 -219.18168)
		(width 0.0889)
		(layer "In11.Cu")
		(net "P5E_CPU0_PE1_RX_DP<10>")
	)
	(arc
		(start 356.386638 -219.512642)
		(mid 356.435837 -219.691748)
		(end 356.564946 -219.825316)
		(width 0.0889)
		(layer "In11.Cu")
		(net "P5E_CPU0_PE1_RX_DP<10>")
	)
	(arc
		(start 356.564946 -219.18676)
		(mid 356.436627 -219.318732)
		(end 356.386638 -219.495878)
		(width 0.0889)
		(layer "In11.Cu")
		(net "P5E_CPU0_PE1_RX_DP<10>")
	)
	(arc
		(start 356.109778 -215.764618)
		(mid 356.312365 -215.970969)
		(end 356.386384 -216.25052)
		(width 0.0889)
		(layer "In11.Cu")
		(net "P5E_CPU0_PE1_RX_DP<10>")
	)
	(arc
		(start 357.043482 -220.644212)
		(mid 357.20197 -220.693145)
		(end 357.366062 -220.66885)
		(width 0.0889)
		(layer "In11.Cu")
		(net "P5E_CPU0_PE1_RX_DP<10>")
	)
	(arc
		(start 355.916484 -215.421972)
		(mid 355.916287 -215.429337)
		(end 355.91623 -215.436704)
		(width 0.0889)
		(layer "In11.Cu")
		(net "P5E_CPU0_PE1_RX_DP<10>")
	)
	(arc
		(start 356.386638 -217.866214)
		(mid 356.386471 -217.87739)
		(end 356.386638 -217.888566)
		(width 0.0889)
		(layer "In11.Cu")
		(net "P5E_CPU0_PE1_RX_DP<10>")
	)
	(segment
		(start 430.350168 -7.601204)
		(end 430.350168 -5.252974)
		(width 0.13208)
		(layer "F.Cu")
		(net "P5E_CPU0_PE1_RX_DP<0>")
	)
	(segment
		(start 430.16678 -8.320024)
		(end 430.16678 -7.784592)
		(width 0.13208)
		(layer "F.Cu")
		(net "P5E_CPU0_PE1_RX_DP<0>")
	)
	(segment
		(start 366.628934 -220.855794)
		(end 366.62868 -220.319854)
		(width 0.13208)
		(layer "F.Cu")
		(net "P5E_CPU0_PE1_RX_DP<0>")
	)
	(segment
		(start 430.350168 -5.252974)
		(end 430.048924 -4.95173)
		(width 0.13208)
		(layer "F.Cu")
		(net "P5E_CPU0_PE1_RX_DP<0>")
	)
	(segment
		(start 430.16678 -7.784592)
		(end 430.350168 -7.601204)
		(width 0.13208)
		(layer "F.Cu")
		(net "P5E_CPU0_PE1_RX_DP<0>")
	)
	(segment
		(start 366.241584 -213.176612)
		(end 366.241584 -214.21471)
		(width 0.14732)
		(layer "In11.Cu")
		(net "P5E_CPU0_PE1_RX_DP<0>")
	)
	(segment
		(start 366.346232 -217.554048)
		(end 366.355122 -217.559128)
		(width 0.0889)
		(layer "In11.Cu")
		(net "P5E_CPU0_PE1_RX_DP<0>")
	)
	(segment
		(start 366.241584 -214.21471)
		(end 366.241584 -214.236808)
		(width 0.0889)
		(layer "In11.Cu")
		(net "P5E_CPU0_PE1_RX_DP<0>")
	)
	(segment
		(start 432.023266 -15.27048)
		(end 432.230022 -15.575026)
		(width 0.14732)
		(layer "In11.Cu")
		(net "P5E_CPU0_PE1_RX_DP<0>")
	)
	(segment
		(start 366.023652 -212.081364)
		(end 366.241584 -213.176612)
		(width 0.14732)
		(layer "In11.Cu")
		(net "P5E_CPU0_PE1_RX_DP<0>")
	)
	(segment
		(start 430.343564 -5.24637)
		(end 430.343564 -12.583668)
		(width 0.14732)
		(layer "In11.Cu")
		(net "P5E_CPU0_PE1_RX_DP<0>")
	)
	(segment
		(start 367.823496 -185.40603)
		(end 366.023652 -212.081364)
		(width 0.14732)
		(layer "In11.Cu")
		(net "P5E_CPU0_PE1_RX_DP<0>")
	)
	(segment
		(start 366.06353 -217.0557)
		(end 366.06353 -217.07856)
		(width 0.0889)
		(layer "In11.Cu")
		(net "P5E_CPU0_PE1_RX_DP<0>")
	)
	(segment
		(start 365.593884 -216.235026)
		(end 365.593884 -216.260426)
		(width 0.0889)
		(layer "In11.Cu")
		(net "P5E_CPU0_PE1_RX_DP<0>")
	)
	(segment
		(start 431.653442 -14.725904)
		(end 431.614834 -14.927072)
		(width 0.14732)
		(layer "In11.Cu")
		(net "P5E_CPU0_PE1_RX_DP<0>")
	)
	(segment
		(start 425.655232 -27.653996)
		(end 425.146724 -28.789122)
		(width 0.14732)
		(layer "In11.Cu")
		(net "P5E_CPU0_PE1_RX_DP<0>")
	)
	(segment
		(start 366.34547 -218.203272)
		(end 366.340136 -218.20632)
		(width 0.0889)
		(layer "In11.Cu")
		(net "P5E_CPU0_PE1_RX_DP<0>")
	)
	(segment
		(start 366.533684 -219.506038)
		(end 366.533684 -219.521532)
		(width 0.0889)
		(layer "In11.Cu")
		(net "P5E_CPU0_PE1_RX_DP<0>")
	)
	(segment
		(start 366.815878 -219.995496)
		(end 366.816894 -219.996004)
		(width 0.0889)
		(layer "In11.Cu")
		(net "P5E_CPU0_PE1_RX_DP<0>")
	)
	(segment
		(start 366.06353 -215.245696)
		(end 366.06353 -215.436704)
		(width 0.0889)
		(layer "In11.Cu")
		(net "P5E_CPU0_PE1_RX_DP<0>")
	)
	(segment
		(start 365.884968 -215.755982)
		(end 365.876078 -215.761062)
		(width 0.0889)
		(layer "In11.Cu")
		(net "P5E_CPU0_PE1_RX_DP<0>")
	)
	(segment
		(start 366.355122 -218.197684)
		(end 366.347756 -218.202002)
		(width 0.0889)
		(layer "In11.Cu")
		(net "P5E_CPU0_PE1_RX_DP<0>")
	)
	(segment
		(start 430.463198 -12.972796)
		(end 431.653442 -14.725904)
		(width 0.14732)
		(layer "In11.Cu")
		(net "P5E_CPU0_PE1_RX_DP<0>")
	)
	(segment
		(start 432.398424 -16.081248)
		(end 432.599846 -16.119602)
		(width 0.14732)
		(layer "In11.Cu")
		(net "P5E_CPU0_PE1_RX_DP<0>")
	)
	(segment
		(start 366.785144 -220.590872)
		(end 366.62868 -220.319854)
		(width 0.0889)
		(layer "In11.Cu")
		(net "P5E_CPU0_PE1_RX_DP<0>")
	)
	(segment
		(start 432.599846 -16.119602)
		(end 433.752244 -17.8181)
		(width 0.14732)
		(layer "In11.Cu")
		(net "P5E_CPU0_PE1_RX_DP<0>")
	)
	(segment
		(start 434.148738 -19.846036)
		(end 425.655232 -27.653996)
		(width 0.14732)
		(layer "In11.Cu")
		(net "P5E_CPU0_PE1_RX_DP<0>")
	)
	(segment
		(start 368.683032 -164.10432)
		(end 367.823496 -185.40603)
		(width 0.14732)
		(layer "In11.Cu")
		(net "P5E_CPU0_PE1_RX_DP<0>")
	)
	(segment
		(start 366.340136 -219.178124)
		(end 366.34547 -219.181172)
		(width 0.0889)
		(layer "In11.Cu")
		(net "P5E_CPU0_PE1_RX_DP<0>")
	)
	(segment
		(start 433.752244 -17.8181)
		(end 433.752752 -17.8181)
		(width 0.14732)
		(layer "In11.Cu")
		(net "P5E_CPU0_PE1_RX_DP<0>")
	)
	(segment
		(start 366.347756 -218.202002)
		(end 366.346232 -218.202764)
		(width 0.0889)
		(layer "In11.Cu")
		(net "P5E_CPU0_PE1_RX_DP<0>")
	)
	(segment
		(start 432.191668 -15.776194)
		(end 432.398424 -16.081248)
		(width 0.14732)
		(layer "In11.Cu")
		(net "P5E_CPU0_PE1_RX_DP<0>")
	)
	(segment
		(start 366.349534 -219.183458)
		(end 366.355122 -219.18676)
		(width 0.0889)
		(layer "In11.Cu")
		(net "P5E_CPU0_PE1_RX_DP<0>")
	)
	(segment
		(start 366.283494 -214.713058)
		(end 366.06353 -215.245696)
		(width 0.0889)
		(layer "In11.Cu")
		(net "P5E_CPU0_PE1_RX_DP<0>")
	)
	(segment
		(start 425.146724 -28.789122)
		(end 417.417758 -78.019656)
		(width 0.14732)
		(layer "In11.Cu")
		(net "P5E_CPU0_PE1_RX_DP<0>")
	)
	(segment
		(start 366.34547 -219.181172)
		(end 366.346994 -219.182188)
		(width 0.0889)
		(layer "In11.Cu")
		(net "P5E_CPU0_PE1_RX_DP<0>")
	)
	(segment
		(start 430.048924 -4.95173)
		(end 430.343564 -5.24637)
		(width 0.14732)
		(layer "In11.Cu")
		(net "P5E_CPU0_PE1_RX_DP<0>")
	)
	(segment
		(start 366.816894 -219.996004)
		(end 366.824768 -220.000576)
		(width 0.0889)
		(layer "In11.Cu")
		(net "P5E_CPU0_PE1_RX_DP<0>")
	)
	(segment
		(start 433.752752 -17.8181)
		(end 434.39588 -18.765266)
		(width 0.14732)
		(layer "In11.Cu")
		(net "P5E_CPU0_PE1_RX_DP<0>")
	)
	(segment
		(start 434.39588 -18.765266)
		(end 434.39588 -19.249898)
		(width 0.14732)
		(layer "In11.Cu")
		(net "P5E_CPU0_PE1_RX_DP<0>")
	)
	(segment
		(start 417.417758 -78.019656)
		(end 368.683032 -164.10432)
		(width 0.14732)
		(layer "In11.Cu")
		(net "P5E_CPU0_PE1_RX_DP<0>")
	)
	(segment
		(start 431.821844 -15.231872)
		(end 432.023266 -15.27048)
		(width 0.14732)
		(layer "In11.Cu")
		(net "P5E_CPU0_PE1_RX_DP<0>")
	)
	(segment
		(start 430.343564 -12.583668)
		(end 430.463198 -12.972796)
		(width 0.14732)
		(layer "In11.Cu")
		(net "P5E_CPU0_PE1_RX_DP<0>")
	)
	(segment
		(start 366.863376 -220.6117)
		(end 366.785144 -220.590872)
		(width 0.0889)
		(layer "In11.Cu")
		(net "P5E_CPU0_PE1_RX_DP<0>")
	)
	(segment
		(start 431.614834 -14.927072)
		(end 431.821844 -15.231872)
		(width 0.14732)
		(layer "In11.Cu")
		(net "P5E_CPU0_PE1_RX_DP<0>")
	)
	(segment
		(start 432.230022 -15.575026)
		(end 432.191668 -15.776194)
		(width 0.14732)
		(layer "In11.Cu")
		(net "P5E_CPU0_PE1_RX_DP<0>")
	)
	(segment
		(start 366.346232 -218.202764)
		(end 366.34547 -218.203272)
		(width 0.0889)
		(layer "In11.Cu")
		(net "P5E_CPU0_PE1_RX_DP<0>")
	)
	(segment
		(start 366.241584 -214.236808)
		(end 366.283494 -214.278718)
		(width 0.0889)
		(layer "In11.Cu")
		(net "P5E_CPU0_PE1_RX_DP<0>")
	)
	(segment
		(start 366.283494 -214.278718)
		(end 366.283494 -214.713058)
		(width 0.0889)
		(layer "In11.Cu")
		(net "P5E_CPU0_PE1_RX_DP<0>")
	)
	(segment
		(start 434.39588 -19.249898)
		(end 434.148738 -19.846036)
		(width 0.14732)
		(layer "In11.Cu")
		(net "P5E_CPU0_PE1_RX_DP<0>")
	)
	(segment
		(start 366.346994 -219.182188)
		(end 366.349534 -219.183458)
		(width 0.0889)
		(layer "In11.Cu")
		(net "P5E_CPU0_PE1_RX_DP<0>")
	)
	(arc
		(start 365.876078 -215.761062)
		(mid 365.673255 -215.961293)
		(end 365.593884 -216.235026)
		(width 0.0889)
		(layer "In11.Cu")
		(net "P5E_CPU0_PE1_RX_DP<0>")
	)
	(arc
		(start 366.06353 -215.436704)
		(mid 366.015851 -215.619604)
		(end 365.884968 -215.755982)
		(width 0.0889)
		(layer "In11.Cu")
		(net "P5E_CPU0_PE1_RX_DP<0>")
	)
	(arc
		(start 366.824768 -220.000576)
		(mid 366.955682 -220.136936)
		(end 367.00333 -220.319854)
		(width 0.0889)
		(layer "In11.Cu")
		(net "P5E_CPU0_PE1_RX_DP<0>")
	)
	(arc
		(start 366.355122 -217.559128)
		(mid 366.533719 -217.878406)
		(end 366.355122 -218.197684)
		(width 0.0889)
		(layer "In11.Cu")
		(net "P5E_CPU0_PE1_RX_DP<0>")
	)
	(arc
		(start 366.06353 -217.07856)
		(mid 366.142749 -217.353245)
		(end 366.346232 -217.554048)
		(width 0.0889)
		(layer "In11.Cu")
		(net "P5E_CPU0_PE1_RX_DP<0>")
	)
	(arc
		(start 366.533684 -219.521532)
		(mid 366.613054 -219.795266)
		(end 366.815878 -219.995496)
		(width 0.0889)
		(layer "In11.Cu")
		(net "P5E_CPU0_PE1_RX_DP<0>")
	)
	(arc
		(start 366.355122 -219.18676)
		(mid 366.486036 -219.32312)
		(end 366.533684 -219.506038)
		(width 0.0889)
		(layer "In11.Cu")
		(net "P5E_CPU0_PE1_RX_DP<0>")
	)
	(arc
		(start 367.00333 -220.319854)
		(mid 366.96647 -220.481651)
		(end 366.863376 -220.6117)
		(width 0.0889)
		(layer "In11.Cu")
		(net "P5E_CPU0_PE1_RX_DP<0>")
	)
	(arc
		(start 365.593884 -216.260426)
		(mid 365.671995 -216.537375)
		(end 365.876332 -216.739978)
		(width 0.0889)
		(layer "In11.Cu")
		(net "P5E_CPU0_PE1_RX_DP<0>")
	)
	(arc
		(start 366.340136 -218.20632)
		(mid 366.063562 -218.692222)
		(end 366.340136 -219.178124)
		(width 0.0889)
		(layer "In11.Cu")
		(net "P5E_CPU0_PE1_RX_DP<0>")
	)
	(arc
		(start 365.876332 -216.739978)
		(mid 366.011265 -216.873332)
		(end 366.06353 -217.0557)
		(width 0.0889)
		(layer "In11.Cu")
		(net "P5E_CPU0_PE1_RX_DP<0>")
	)
	(segment
		(start 404.626572 -7.015734)
		(end 404.324312 -6.713474)
		(width 0.13208)
		(layer "F.Cu")
		(net "P5E_CPU0_PE1_RX_DN<9>")
	)
	(segment
		(start 404.626572 -7.597394)
		(end 404.626572 -7.015734)
		(width 0.13208)
		(layer "F.Cu")
		(net "P5E_CPU0_PE1_RX_DN<9>")
	)
	(segment
		(start 404.446994 -7.776972)
		(end 404.626572 -7.597394)
		(width 0.13208)
		(layer "F.Cu")
		(net "P5E_CPU0_PE1_RX_DN<9>")
	)
	(segment
		(start 358.170734 -222.48368)
		(end 358.170734 -221.94774)
		(width 0.13208)
		(layer "F.Cu")
		(net "P5E_CPU0_PE1_RX_DN<9>")
	)
	(segment
		(start 404.446994 -8.320024)
		(end 404.446994 -7.776972)
		(width 0.13208)
		(layer "F.Cu")
		(net "P5E_CPU0_PE1_RX_DN<9>")
	)
	(segment
		(start 357.41864 -217.388948)
		(end 357.407972 -217.395298)
		(width 0.0889)
		(layer "In11.Cu")
		(net "P5E_CPU0_PE1_RX_DN<9>")
	)
	(segment
		(start 408.142948 -19.353276)
		(end 408.234134 -60.625482)
		(width 0.14732)
		(layer "In11.Cu")
		(net "P5E_CPU0_PE1_RX_DN<9>")
	)
	(segment
		(start 357.404924 -216.73185)
		(end 357.405178 -216.732104)
		(width 0.0889)
		(layer "In11.Cu")
		(net "P5E_CPU0_PE1_RX_DN<9>")
	)
	(segment
		(start 356.947216 -215.9254)
		(end 356.948232 -215.925908)
		(width 0.0889)
		(layer "In11.Cu")
		(net "P5E_CPU0_PE1_RX_DN<9>")
	)
	(segment
		(start 357.422958 -219.01404)
		(end 357.417624 -219.017342)
		(width 0.0889)
		(layer "In11.Cu")
		(net "P5E_CPU0_PE1_RX_DN<9>")
	)
	(segment
		(start 408.693112 -17.072102)
		(end 408.85364 -17.459706)
		(width 0.14732)
		(layer "In11.Cu")
		(net "P5E_CPU0_PE1_RX_DN<9>")
	)
	(segment
		(start 357.415846 -219.018358)
		(end 357.404924 -219.024708)
		(width 0.0889)
		(layer "In11.Cu")
		(net "P5E_CPU0_PE1_RX_DN<9>")
	)
	(segment
		(start 357.41864 -216.739724)
		(end 357.42372 -216.742772)
		(width 0.0889)
		(layer "In11.Cu")
		(net "P5E_CPU0_PE1_RX_DN<9>")
	)
	(segment
		(start 358.303068 -221.587568)
		(end 358.327198 -221.676722)
		(width 0.0889)
		(layer "In11.Cu")
		(net "P5E_CPU0_PE1_RX_DN<9>")
	)
	(segment
		(start 356.940358 -214.952072)
		(end 356.93477 -214.955374)
		(width 0.0889)
		(layer "In11.Cu")
		(net "P5E_CPU0_PE1_RX_DN<9>")
	)
	(segment
		(start 357.418894 -219.995496)
		(end 357.418894 -219.996004)
		(width 0.0889)
		(layer "In11.Cu")
		(net "P5E_CPU0_PE1_RX_DN<9>")
	)
	(segment
		(start 360.385868 -161.161984)
		(end 356.305612 -184.312052)
		(width 0.14732)
		(layer "In11.Cu")
		(net "P5E_CPU0_PE1_RX_DN<9>")
	)
	(segment
		(start 357.416608 -219.01785)
		(end 357.415846 -219.018358)
		(width 0.0889)
		(layer "In11.Cu")
		(net "P5E_CPU0_PE1_RX_DN<9>")
	)
	(segment
		(start 404.618952 -11.945112)
		(end 404.950168 -12.745212)
		(width 0.14732)
		(layer "In11.Cu")
		(net "P5E_CPU0_PE1_RX_DN<9>")
	)
	(segment
		(start 357.404924 -218.359736)
		(end 357.405178 -218.35999)
		(width 0.0889)
		(layer "In11.Cu")
		(net "P5E_CPU0_PE1_RX_DN<9>")
	)
	(segment
		(start 357.605584 -213.77021)
		(end 357.135176 -214.240618)
		(width 0.0889)
		(layer "In11.Cu")
		(net "P5E_CPU0_PE1_RX_DN<9>")
	)
	(segment
		(start 357.405178 -216.732104)
		(end 357.41864 -216.739724)
		(width 0.0889)
		(layer "In11.Cu")
		(net "P5E_CPU0_PE1_RX_DN<9>")
	)
	(segment
		(start 357.605584 -212.72881)
		(end 357.605584 -213.77021)
		(width 0.0889)
		(layer "In11.Cu")
		(net "P5E_CPU0_PE1_RX_DN<9>")
	)
	(segment
		(start 404.950168 -12.745212)
		(end 405.042116 -12.892786)
		(width 0.14732)
		(layer "In11.Cu")
		(net "P5E_CPU0_PE1_RX_DN<9>")
	)
	(segment
		(start 357.56342 -212.67547)
		(end 357.56342 -212.686646)
		(width 0.0889)
		(layer "In11.Cu")
		(net "P5E_CPU0_PE1_RX_DN<9>")
	)
	(segment
		(start 357.56342 -211.957666)
		(end 357.56342 -212.67547)
		(width 0.14732)
		(layer "In11.Cu")
		(net "P5E_CPU0_PE1_RX_DN<9>")
	)
	(segment
		(start 406.632918 -79.473044)
		(end 360.385868 -161.161984)
		(width 0.14732)
		(layer "In11.Cu")
		(net "P5E_CPU0_PE1_RX_DN<9>")
	)
	(segment
		(start 404.618952 -7.008114)
		(end 404.618952 -11.945112)
		(width 0.14732)
		(layer "In11.Cu")
		(net "P5E_CPU0_PE1_RX_DN<9>")
	)
	(segment
		(start 356.944422 -215.923622)
		(end 356.947216 -215.9254)
		(width 0.0889)
		(layer "In11.Cu")
		(net "P5E_CPU0_PE1_RX_DN<9>")
	)
	(segment
		(start 357.404924 -219.987368)
		(end 357.417116 -219.99448)
		(width 0.0889)
		(layer "In11.Cu")
		(net "P5E_CPU0_PE1_RX_DN<9>")
	)
	(segment
		(start 408.142948 -18.917158)
		(end 408.142948 -19.353276)
		(width 0.14732)
		(layer "In11.Cu")
		(net "P5E_CPU0_PE1_RX_DN<9>")
	)
	(segment
		(start 356.956614 -214.941658)
		(end 356.940358 -214.952072)
		(width 0.0889)
		(layer "In11.Cu")
		(net "P5E_CPU0_PE1_RX_DN<9>")
	)
	(segment
		(start 408.85364 -17.459706)
		(end 408.85364 -17.853914)
		(width 0.14732)
		(layer "In11.Cu")
		(net "P5E_CPU0_PE1_RX_DN<9>")
	)
	(segment
		(start 356.948232 -215.925908)
		(end 356.952804 -215.928702)
		(width 0.0889)
		(layer "In11.Cu")
		(net "P5E_CPU0_PE1_RX_DN<9>")
	)
	(segment
		(start 357.135176 -214.240618)
		(end 357.135176 -214.622634)
		(width 0.0889)
		(layer "In11.Cu")
		(net "P5E_CPU0_PE1_RX_DN<9>")
	)
	(segment
		(start 356.305612 -184.312052)
		(end 357.56342 -211.957666)
		(width 0.14732)
		(layer "In11.Cu")
		(net "P5E_CPU0_PE1_RX_DN<9>")
	)
	(segment
		(start 356.937818 -215.919812)
		(end 356.944422 -215.923622)
		(width 0.0889)
		(layer "In11.Cu")
		(net "P5E_CPU0_PE1_RX_DN<9>")
	)
	(segment
		(start 357.56342 -212.686646)
		(end 357.605584 -212.72881)
		(width 0.0889)
		(layer "In11.Cu")
		(net "P5E_CPU0_PE1_RX_DN<9>")
	)
	(segment
		(start 408.234134 -60.625482)
		(end 407.94305 -76.367132)
		(width 0.14732)
		(layer "In11.Cu")
		(net "P5E_CPU0_PE1_RX_DN<9>")
	)
	(segment
		(start 404.324312 -6.713474)
		(end 404.618952 -7.008114)
		(width 0.14732)
		(layer "In11.Cu")
		(net "P5E_CPU0_PE1_RX_DN<9>")
	)
	(segment
		(start 357.135176 -214.622634)
		(end 357.134922 -214.62238)
		(width 0.0889)
		(layer "In11.Cu")
		(net "P5E_CPU0_PE1_RX_DN<9>")
	)
	(segment
		(start 408.85364 -17.853914)
		(end 408.142948 -18.917158)
		(width 0.14732)
		(layer "In11.Cu")
		(net "P5E_CPU0_PE1_RX_DN<9>")
	)
	(segment
		(start 357.418894 -219.996004)
		(end 357.426768 -220.000576)
		(width 0.0889)
		(layer "In11.Cu")
		(net "P5E_CPU0_PE1_RX_DN<9>")
	)
	(segment
		(start 358.075484 -221.133924)
		(end 358.075484 -221.14383)
		(width 0.0889)
		(layer "In11.Cu")
		(net "P5E_CPU0_PE1_RX_DN<9>")
	)
	(segment
		(start 407.94305 -76.367132)
		(end 406.632918 -79.473044)
		(width 0.14732)
		(layer "In11.Cu")
		(net "P5E_CPU0_PE1_RX_DN<9>")
	)
	(segment
		(start 357.417878 -219.994988)
		(end 357.418894 -219.995496)
		(width 0.0889)
		(layer "In11.Cu")
		(net "P5E_CPU0_PE1_RX_DN<9>")
	)
	(segment
		(start 357.888032 -220.809566)
		(end 357.896922 -220.814646)
		(width 0.0889)
		(layer "In11.Cu")
		(net "P5E_CPU0_PE1_RX_DN<9>")
	)
	(segment
		(start 405.042116 -12.892786)
		(end 408.693112 -17.072102)
		(width 0.14732)
		(layer "In11.Cu")
		(net "P5E_CPU0_PE1_RX_DN<9>")
	)
	(segment
		(start 358.327198 -221.676722)
		(end 358.170734 -221.94774)
		(width 0.0889)
		(layer "In11.Cu")
		(net "P5E_CPU0_PE1_RX_DN<9>")
	)
	(segment
		(start 357.417116 -219.99448)
		(end 357.417878 -219.994988)
		(width 0.0889)
		(layer "In11.Cu")
		(net "P5E_CPU0_PE1_RX_DN<9>")
	)
	(segment
		(start 357.405178 -218.35999)
		(end 357.41864 -218.36761)
		(width 0.0889)
		(layer "In11.Cu")
		(net "P5E_CPU0_PE1_RX_DN<9>")
	)
	(segment
		(start 357.417624 -219.017342)
		(end 357.416608 -219.01785)
		(width 0.0889)
		(layer "In11.Cu")
		(net "P5E_CPU0_PE1_RX_DN<9>")
	)
	(segment
		(start 357.60533 -220.319854)
		(end 357.60533 -220.327474)
		(width 0.0889)
		(layer "In11.Cu")
		(net "P5E_CPU0_PE1_RX_DN<9>")
	)
	(segment
		(start 357.41864 -218.36761)
		(end 357.42372 -218.370658)
		(width 0.0889)
		(layer "In11.Cu")
		(net "P5E_CPU0_PE1_RX_DN<9>")
	)
	(segment
		(start 356.956614 -214.941912)
		(end 356.956614 -214.941658)
		(width 0.0889)
		(layer "In11.Cu")
		(net "P5E_CPU0_PE1_RX_DN<9>")
	)
	(arc
		(start 357.896922 -220.814646)
		(mid 358.027836 -220.951006)
		(end 358.075484 -221.133924)
		(width 0.0889)
		(layer "In11.Cu")
		(net "P5E_CPU0_PE1_RX_DN<9>")
	)
	(arc
		(start 357.135938 -217.87866)
		(mid 357.207829 -218.154183)
		(end 357.404924 -218.359736)
		(width 0.0889)
		(layer "In11.Cu")
		(net "P5E_CPU0_PE1_RX_DN<9>")
	)
	(arc
		(start 357.60533 -220.327474)
		(mid 357.682959 -220.605887)
		(end 357.888032 -220.809566)
		(width 0.0889)
		(layer "In11.Cu")
		(net "P5E_CPU0_PE1_RX_DN<9>")
	)
	(arc
		(start 356.93477 -214.955374)
		(mid 356.742996 -215.151387)
		(end 356.666038 -215.414606)
		(width 0.0889)
		(layer "In11.Cu")
		(net "P5E_CPU0_PE1_RX_DN<9>")
	)
	(arc
		(start 357.134922 -214.62238)
		(mid 357.087452 -214.805414)
		(end 356.956614 -214.941912)
		(width 0.0889)
		(layer "In11.Cu")
		(net "P5E_CPU0_PE1_RX_DN<9>")
	)
	(arc
		(start 358.075484 -221.14383)
		(mid 358.132957 -221.382677)
		(end 358.286304 -221.574614)
		(width 0.0889)
		(layer "In11.Cu")
		(net "P5E_CPU0_PE1_RX_DN<9>")
	)
	(arc
		(start 357.42372 -216.742772)
		(mid 357.605849 -217.067298)
		(end 357.41864 -217.388948)
		(width 0.0889)
		(layer "In11.Cu")
		(net "P5E_CPU0_PE1_RX_DN<9>")
	)
	(arc
		(start 358.286304 -221.574614)
		(mid 358.294626 -221.581168)
		(end 358.303068 -221.587568)
		(width 0.0889)
		(layer "In11.Cu")
		(net "P5E_CPU0_PE1_RX_DN<9>")
	)
	(arc
		(start 356.666038 -215.414606)
		(mid 356.665802 -215.425781)
		(end 356.665784 -215.436958)
		(width 0.0889)
		(layer "In11.Cu")
		(net "P5E_CPU0_PE1_RX_DN<9>")
	)
	(arc
		(start 357.136192 -217.856308)
		(mid 357.135956 -217.867483)
		(end 357.135938 -217.87866)
		(width 0.0889)
		(layer "In11.Cu")
		(net "P5E_CPU0_PE1_RX_DN<9>")
	)
	(arc
		(start 357.426768 -220.000576)
		(mid 357.557682 -220.136936)
		(end 357.60533 -220.319854)
		(width 0.0889)
		(layer "In11.Cu")
		(net "P5E_CPU0_PE1_RX_DN<9>")
	)
	(arc
		(start 356.952804 -215.928702)
		(mid 357.086934 -216.0654)
		(end 357.135938 -216.25052)
		(width 0.0889)
		(layer "In11.Cu")
		(net "P5E_CPU0_PE1_RX_DN<9>")
	)
	(arc
		(start 357.404924 -219.024708)
		(mid 357.135941 -219.506038)
		(end 357.404924 -219.987368)
		(width 0.0889)
		(layer "In11.Cu")
		(net "P5E_CPU0_PE1_RX_DN<9>")
	)
	(arc
		(start 357.135938 -216.25052)
		(mid 357.207746 -216.526216)
		(end 357.404924 -216.73185)
		(width 0.0889)
		(layer "In11.Cu")
		(net "P5E_CPU0_PE1_RX_DN<9>")
	)
	(arc
		(start 356.665784 -215.436958)
		(mid 356.738538 -215.714019)
		(end 356.937818 -215.919812)
		(width 0.0889)
		(layer "In11.Cu")
		(net "P5E_CPU0_PE1_RX_DN<9>")
	)
	(arc
		(start 357.42372 -218.370658)
		(mid 357.605737 -218.692614)
		(end 357.422958 -219.01404)
		(width 0.0889)
		(layer "In11.Cu")
		(net "P5E_CPU0_PE1_RX_DN<9>")
	)
	(arc
		(start 357.407972 -217.395298)
		(mid 357.214015 -217.591582)
		(end 357.136192 -217.856308)
		(width 0.0889)
		(layer "In11.Cu")
		(net "P5E_CPU0_PE1_RX_DN<9>")
	)
	(segment
		(start 406.430226 -5.252974)
		(end 406.128982 -4.95173)
		(width 0.13208)
		(layer "F.Cu")
		(net "P5E_CPU0_PE1_RX_DN<8>")
	)
	(segment
		(start 406.246838 -7.784592)
		(end 406.430226 -7.601204)
		(width 0.13208)
		(layer "F.Cu")
		(net "P5E_CPU0_PE1_RX_DN<8>")
	)
	(segment
		(start 359.58018 -221.669864)
		(end 359.580434 -221.133924)
		(width 0.13208)
		(layer "F.Cu")
		(net "P5E_CPU0_PE1_RX_DN<8>")
	)
	(segment
		(start 406.430226 -7.601204)
		(end 406.430226 -5.252974)
		(width 0.13208)
		(layer "F.Cu")
		(net "P5E_CPU0_PE1_RX_DN<8>")
	)
	(segment
		(start 406.246838 -8.320024)
		(end 406.246838 -7.784592)
		(width 0.13208)
		(layer "F.Cu")
		(net "P5E_CPU0_PE1_RX_DN<8>")
	)
	(segment
		(start 358.357678 -215.112346)
		(end 358.358694 -215.112854)
		(width 0.0889)
		(layer "In11.Cu")
		(net "P5E_CPU0_PE1_RX_DN<8>")
	)
	(segment
		(start 358.503474 -212.697568)
		(end 358.545384 -212.739478)
		(width 0.0889)
		(layer "In11.Cu")
		(net "P5E_CPU0_PE1_RX_DN<8>")
	)
	(segment
		(start 358.545384 -213.815168)
		(end 358.07523 -214.285322)
		(width 0.0889)
		(layer "In11.Cu")
		(net "P5E_CPU0_PE1_RX_DN<8>")
	)
	(segment
		(start 358.357678 -218.367864)
		(end 358.366568 -218.372944)
		(width 0.0889)
		(layer "In11.Cu")
		(net "P5E_CPU0_PE1_RX_DN<8>")
	)
	(segment
		(start 359.42397 -220.862906)
		(end 359.580434 -221.133924)
		(width 0.0889)
		(layer "In11.Cu")
		(net "P5E_CPU0_PE1_RX_DN<8>")
	)
	(segment
		(start 358.54513 -220.311218)
		(end 358.54513 -220.334078)
		(width 0.0889)
		(layer "In11.Cu")
		(net "P5E_CPU0_PE1_RX_DN<8>")
	)
	(segment
		(start 358.358694 -215.112854)
		(end 358.366568 -215.117426)
		(width 0.0889)
		(layer "In11.Cu")
		(net "P5E_CPU0_PE1_RX_DN<8>")
	)
	(segment
		(start 407.93416 -9.263126)
		(end 410.889704 -17.826736)
		(width 0.14732)
		(layer "In11.Cu")
		(net "P5E_CPU0_PE1_RX_DN<8>")
	)
	(segment
		(start 358.366568 -215.755982)
		(end 358.357678 -215.761062)
		(width 0.0889)
		(layer "In11.Cu")
		(net "P5E_CPU0_PE1_RX_DN<8>")
	)
	(segment
		(start 410.889704 -17.826736)
		(end 411.67558 -19.002502)
		(width 0.14732)
		(layer "In11.Cu")
		(net "P5E_CPU0_PE1_RX_DN<8>")
	)
	(segment
		(start 411.67558 -19.002502)
		(end 408.9908 -76.7207)
		(width 0.14732)
		(layer "In11.Cu")
		(net "P5E_CPU0_PE1_RX_DN<8>")
	)
	(segment
		(start 406.423622 -5.24637)
		(end 406.423622 -6.703822)
		(width 0.14732)
		(layer "In11.Cu")
		(net "P5E_CPU0_PE1_RX_DN<8>")
	)
	(segment
		(start 406.748234 -7.487666)
		(end 407.93416 -9.263126)
		(width 0.14732)
		(layer "In11.Cu")
		(net "P5E_CPU0_PE1_RX_DN<8>")
	)
	(segment
		(start 361.26547 -161.529522)
		(end 357.257096 -184.272174)
		(width 0.14732)
		(layer "In11.Cu")
		(net "P5E_CPU0_PE1_RX_DN<8>")
	)
	(segment
		(start 358.075484 -216.235026)
		(end 358.075484 -216.260426)
		(width 0.0889)
		(layer "In11.Cu")
		(net "P5E_CPU0_PE1_RX_DN<8>")
	)
	(segment
		(start 358.545384 -212.739478)
		(end 358.545384 -213.815168)
		(width 0.0889)
		(layer "In11.Cu")
		(net "P5E_CPU0_PE1_RX_DN<8>")
	)
	(segment
		(start 359.334816 -220.83903)
		(end 359.42397 -220.862906)
		(width 0.0889)
		(layer "In11.Cu")
		(net "P5E_CPU0_PE1_RX_DN<8>")
	)
	(segment
		(start 357.257096 -184.272174)
		(end 358.503474 -212.151976)
		(width 0.14732)
		(layer "In11.Cu")
		(net "P5E_CPU0_PE1_RX_DN<8>")
	)
	(segment
		(start 358.366568 -219.0115)
		(end 358.357678 -219.01658)
		(width 0.0889)
		(layer "In11.Cu")
		(net "P5E_CPU0_PE1_RX_DN<8>")
	)
	(segment
		(start 358.075484 -219.490544)
		(end 358.075484 -219.515944)
		(width 0.0889)
		(layer "In11.Cu")
		(net "P5E_CPU0_PE1_RX_DN<8>")
	)
	(segment
		(start 407.52903 -79.811118)
		(end 361.26547 -161.529522)
		(width 0.14732)
		(layer "In11.Cu")
		(net "P5E_CPU0_PE1_RX_DN<8>")
	)
	(segment
		(start 358.827832 -220.809566)
		(end 358.842564 -220.818202)
		(width 0.0889)
		(layer "In11.Cu")
		(net "P5E_CPU0_PE1_RX_DN<8>")
	)
	(segment
		(start 406.423622 -6.703822)
		(end 406.748234 -7.487666)
		(width 0.14732)
		(layer "In11.Cu")
		(net "P5E_CPU0_PE1_RX_DN<8>")
	)
	(segment
		(start 358.503474 -212.151976)
		(end 358.503474 -212.67547)
		(width 0.14732)
		(layer "In11.Cu")
		(net "P5E_CPU0_PE1_RX_DN<8>")
	)
	(segment
		(start 358.54513 -217.0557)
		(end 358.54513 -217.072972)
		(width 0.0889)
		(layer "In11.Cu")
		(net "P5E_CPU0_PE1_RX_DN<8>")
	)
	(segment
		(start 358.075484 -217.859864)
		(end 358.075484 -217.8939)
		(width 0.0889)
		(layer "In11.Cu")
		(net "P5E_CPU0_PE1_RX_DN<8>")
	)
	(segment
		(start 358.07523 -214.285322)
		(end 358.07523 -214.636858)
		(width 0.0889)
		(layer "In11.Cu")
		(net "P5E_CPU0_PE1_RX_DN<8>")
	)
	(segment
		(start 406.128982 -4.95173)
		(end 406.423622 -5.24637)
		(width 0.14732)
		(layer "In11.Cu")
		(net "P5E_CPU0_PE1_RX_DN<8>")
	)
	(segment
		(start 408.9908 -76.7207)
		(end 407.52903 -79.811118)
		(width 0.14732)
		(layer "In11.Cu")
		(net "P5E_CPU0_PE1_RX_DN<8>")
	)
	(segment
		(start 358.503474 -212.67547)
		(end 358.503474 -212.697568)
		(width 0.0889)
		(layer "In11.Cu")
		(net "P5E_CPU0_PE1_RX_DN<8>")
	)
	(arc
		(start 358.54513 -220.334078)
		(mid 358.624349 -220.608763)
		(end 358.827832 -220.809566)
		(width 0.0889)
		(layer "In11.Cu")
		(net "P5E_CPU0_PE1_RX_DN<8>")
	)
	(arc
		(start 358.07523 -214.636858)
		(mid 358.154371 -214.911481)
		(end 358.357678 -215.112346)
		(width 0.0889)
		(layer "In11.Cu")
		(net "P5E_CPU0_PE1_RX_DN<8>")
	)
	(arc
		(start 358.366568 -218.372944)
		(mid 358.545044 -218.692222)
		(end 358.366568 -219.0115)
		(width 0.0889)
		(layer "In11.Cu")
		(net "P5E_CPU0_PE1_RX_DN<8>")
	)
	(arc
		(start 358.357932 -219.995496)
		(mid 358.492865 -220.12885)
		(end 358.54513 -220.311218)
		(width 0.0889)
		(layer "In11.Cu")
		(net "P5E_CPU0_PE1_RX_DN<8>")
	)
	(arc
		(start 359.31475 -220.847158)
		(mid 359.324823 -220.843192)
		(end 359.334816 -220.83903)
		(width 0.0889)
		(layer "In11.Cu")
		(net "P5E_CPU0_PE1_RX_DN<8>")
	)
	(arc
		(start 358.357932 -216.739978)
		(mid 358.492865 -216.873332)
		(end 358.54513 -217.0557)
		(width 0.0889)
		(layer "In11.Cu")
		(net "P5E_CPU0_PE1_RX_DN<8>")
	)
	(arc
		(start 358.357678 -219.01658)
		(mid 358.154855 -219.216811)
		(end 358.075484 -219.490544)
		(width 0.0889)
		(layer "In11.Cu")
		(net "P5E_CPU0_PE1_RX_DN<8>")
	)
	(arc
		(start 358.075484 -216.260426)
		(mid 358.153595 -216.537375)
		(end 358.357932 -216.739978)
		(width 0.0889)
		(layer "In11.Cu")
		(net "P5E_CPU0_PE1_RX_DN<8>")
	)
	(arc
		(start 358.842564 -220.818202)
		(mid 359.075479 -220.884383)
		(end 359.31475 -220.847158)
		(width 0.0889)
		(layer "In11.Cu")
		(net "P5E_CPU0_PE1_RX_DN<8>")
	)
	(arc
		(start 358.357932 -217.388694)
		(mid 358.155646 -217.587675)
		(end 358.075484 -217.859864)
		(width 0.0889)
		(layer "In11.Cu")
		(net "P5E_CPU0_PE1_RX_DN<8>")
	)
	(arc
		(start 358.54513 -217.072972)
		(mid 358.49286 -217.255337)
		(end 358.357932 -217.388694)
		(width 0.0889)
		(layer "In11.Cu")
		(net "P5E_CPU0_PE1_RX_DN<8>")
	)
	(arc
		(start 358.075484 -219.515944)
		(mid 358.153595 -219.792893)
		(end 358.357932 -219.995496)
		(width 0.0889)
		(layer "In11.Cu")
		(net "P5E_CPU0_PE1_RX_DN<8>")
	)
	(arc
		(start 358.357678 -215.761062)
		(mid 358.154855 -215.961293)
		(end 358.075484 -216.235026)
		(width 0.0889)
		(layer "In11.Cu")
		(net "P5E_CPU0_PE1_RX_DN<8>")
	)
	(arc
		(start 358.075484 -217.8939)
		(mid 358.154854 -218.167634)
		(end 358.357678 -218.367864)
		(width 0.0889)
		(layer "In11.Cu")
		(net "P5E_CPU0_PE1_RX_DN<8>")
	)
	(arc
		(start 358.366568 -215.117426)
		(mid 358.493822 -215.247392)
		(end 358.544876 -215.421972)
		(width 0.0889)
		(layer "In11.Cu")
		(net "P5E_CPU0_PE1_RX_DN<8>")
	)
	(arc
		(start 358.54513 -215.436704)
		(mid 358.497451 -215.619604)
		(end 358.366568 -215.755982)
		(width 0.0889)
		(layer "In11.Cu")
		(net "P5E_CPU0_PE1_RX_DN<8>")
	)
	(arc
		(start 358.544876 -215.421972)
		(mid 358.545073 -215.429337)
		(end 358.54513 -215.436704)
		(width 0.0889)
		(layer "In11.Cu")
		(net "P5E_CPU0_PE1_RX_DN<8>")
	)
	(segment
		(start 413.736536 -7.597394)
		(end 413.736536 -7.015734)
		(width 0.13208)
		(layer "F.Cu")
		(net "P5E_CPU0_PE1_RX_DN<7>")
	)
	(segment
		(start 413.556958 -7.776972)
		(end 413.736536 -7.597394)
		(width 0.13208)
		(layer "F.Cu")
		(net "P5E_CPU0_PE1_RX_DN<7>")
	)
	(segment
		(start 413.736536 -7.015734)
		(end 413.434276 -6.713474)
		(width 0.13208)
		(layer "F.Cu")
		(net "P5E_CPU0_PE1_RX_DN<7>")
	)
	(segment
		(start 360.050334 -222.48368)
		(end 360.05008 -221.94774)
		(width 0.13208)
		(layer "F.Cu")
		(net "P5E_CPU0_PE1_RX_DN<7>")
	)
	(segment
		(start 413.556958 -8.320024)
		(end 413.556958 -7.776972)
		(width 0.13208)
		(layer "F.Cu")
		(net "P5E_CPU0_PE1_RX_DN<7>")
	)
	(segment
		(start 358.212644 -184.208928)
		(end 359.443528 -212.32368)
		(width 0.14732)
		(layer "In11.Cu")
		(net "P5E_CPU0_PE1_RX_DN<7>")
	)
	(segment
		(start 413.728916 -7.008114)
		(end 413.728916 -12.179808)
		(width 0.14732)
		(layer "In11.Cu")
		(net "P5E_CPU0_PE1_RX_DN<7>")
	)
	(segment
		(start 359.287572 -216.733628)
		(end 359.29824 -216.739978)
		(width 0.0889)
		(layer "In11.Cu")
		(net "P5E_CPU0_PE1_RX_DN<7>")
	)
	(segment
		(start 359.287572 -218.361514)
		(end 359.29824 -218.367864)
		(width 0.0889)
		(layer "In11.Cu")
		(net "P5E_CPU0_PE1_RX_DN<7>")
	)
	(segment
		(start 359.443528 -213.253828)
		(end 359.485438 -213.295738)
		(width 0.0889)
		(layer "In11.Cu")
		(net "P5E_CPU0_PE1_RX_DN<7>")
	)
	(segment
		(start 360.206544 -221.676722)
		(end 360.05008 -221.94774)
		(width 0.0889)
		(layer "In11.Cu")
		(net "P5E_CPU0_PE1_RX_DN<7>")
	)
	(segment
		(start 359.485438 -213.814914)
		(end 359.014776 -214.285576)
		(width 0.0889)
		(layer "In11.Cu")
		(net "P5E_CPU0_PE1_RX_DN<7>")
	)
	(segment
		(start 359.485438 -217.056462)
		(end 359.485438 -217.079322)
		(width 0.0889)
		(layer "In11.Cu")
		(net "P5E_CPU0_PE1_RX_DN<7>")
	)
	(segment
		(start 414.07334 -18.841974)
		(end 410.086556 -76.722478)
		(width 0.14732)
		(layer "In11.Cu")
		(net "P5E_CPU0_PE1_RX_DN<7>")
	)
	(segment
		(start 359.767632 -220.809566)
		(end 359.776522 -220.814646)
		(width 0.0889)
		(layer "In11.Cu")
		(net "P5E_CPU0_PE1_RX_DN<7>")
	)
	(segment
		(start 413.728916 -12.179808)
		(end 414.42132 -17.414494)
		(width 0.14732)
		(layer "In11.Cu")
		(net "P5E_CPU0_PE1_RX_DN<7>")
	)
	(segment
		(start 359.485438 -213.295738)
		(end 359.485438 -213.814914)
		(width 0.0889)
		(layer "In11.Cu")
		(net "P5E_CPU0_PE1_RX_DN<7>")
	)
	(segment
		(start 360.182414 -221.587568)
		(end 360.206544 -221.676722)
		(width 0.0889)
		(layer "In11.Cu")
		(net "P5E_CPU0_PE1_RX_DN<7>")
	)
	(segment
		(start 359.29697 -219.994734)
		(end 359.306368 -220.000576)
		(width 0.0889)
		(layer "In11.Cu")
		(net "P5E_CPU0_PE1_RX_DN<7>")
	)
	(segment
		(start 359.300272 -219.01531)
		(end 359.28554 -219.023438)
		(width 0.0889)
		(layer "In11.Cu")
		(net "P5E_CPU0_PE1_RX_DN<7>")
	)
	(segment
		(start 359.443528 -212.32368)
		(end 359.443528 -213.23173)
		(width 0.14732)
		(layer "In11.Cu")
		(net "P5E_CPU0_PE1_RX_DN<7>")
	)
	(segment
		(start 359.29824 -217.388948)
		(end 359.287572 -217.395298)
		(width 0.0889)
		(layer "In11.Cu")
		(net "P5E_CPU0_PE1_RX_DN<7>")
	)
	(segment
		(start 414.42132 -18.001996)
		(end 414.07334 -18.841974)
		(width 0.14732)
		(layer "In11.Cu")
		(net "P5E_CPU0_PE1_RX_DN<7>")
	)
	(segment
		(start 359.29824 -215.761062)
		(end 359.287572 -215.767158)
		(width 0.0889)
		(layer "In11.Cu")
		(net "P5E_CPU0_PE1_RX_DN<7>")
	)
	(segment
		(start 362.152946 -161.854896)
		(end 358.212644 -184.208928)
		(width 0.14732)
		(layer "In11.Cu")
		(net "P5E_CPU0_PE1_RX_DN<7>")
	)
	(segment
		(start 359.955084 -221.133924)
		(end 359.955084 -221.149418)
		(width 0.0889)
		(layer "In11.Cu")
		(net "P5E_CPU0_PE1_RX_DN<7>")
	)
	(segment
		(start 359.48493 -215.436704)
		(end 359.485184 -215.44915)
		(width 0.0889)
		(layer "In11.Cu")
		(net "P5E_CPU0_PE1_RX_DN<7>")
	)
	(segment
		(start 410.086556 -76.722478)
		(end 408.508454 -79.973932)
		(width 0.14732)
		(layer "In11.Cu")
		(net "P5E_CPU0_PE1_RX_DN<7>")
	)
	(segment
		(start 359.297478 -215.112346)
		(end 359.306368 -215.117426)
		(width 0.0889)
		(layer "In11.Cu")
		(net "P5E_CPU0_PE1_RX_DN<7>")
	)
	(segment
		(start 414.42132 -17.414494)
		(end 414.42132 -18.001996)
		(width 0.14732)
		(layer "In11.Cu")
		(net "P5E_CPU0_PE1_RX_DN<7>")
	)
	(segment
		(start 359.443528 -213.23173)
		(end 359.443528 -213.253828)
		(width 0.0889)
		(layer "In11.Cu")
		(net "P5E_CPU0_PE1_RX_DN<7>")
	)
	(segment
		(start 359.485438 -218.679776)
		(end 359.485438 -218.704668)
		(width 0.0889)
		(layer "In11.Cu")
		(net "P5E_CPU0_PE1_RX_DN<7>")
	)
	(segment
		(start 408.508454 -79.973932)
		(end 362.152946 -161.854896)
		(width 0.14732)
		(layer "In11.Cu")
		(net "P5E_CPU0_PE1_RX_DN<7>")
	)
	(segment
		(start 359.014776 -214.285576)
		(end 359.014776 -214.636858)
		(width 0.0889)
		(layer "In11.Cu")
		(net "P5E_CPU0_PE1_RX_DN<7>")
	)
	(segment
		(start 413.434276 -6.713474)
		(end 413.728916 -7.008114)
		(width 0.14732)
		(layer "In11.Cu")
		(net "P5E_CPU0_PE1_RX_DN<7>")
	)
	(segment
		(start 359.48493 -220.319854)
		(end 359.48493 -220.327474)
		(width 0.0889)
		(layer "In11.Cu")
		(net "P5E_CPU0_PE1_RX_DN<7>")
	)
	(segment
		(start 359.015538 -219.475812)
		(end 359.015538 -219.516706)
		(width 0.0889)
		(layer "In11.Cu")
		(net "P5E_CPU0_PE1_RX_DN<7>")
	)
	(arc
		(start 359.306368 -220.000576)
		(mid 359.437282 -220.136936)
		(end 359.48493 -220.319854)
		(width 0.0889)
		(layer "In11.Cu")
		(net "P5E_CPU0_PE1_RX_DN<7>")
	)
	(arc
		(start 359.015538 -219.516706)
		(mid 359.093554 -219.792621)
		(end 359.29697 -219.994734)
		(width 0.0889)
		(layer "In11.Cu")
		(net "P5E_CPU0_PE1_RX_DN<7>")
	)
	(arc
		(start 359.485438 -218.704668)
		(mid 359.432832 -218.883832)
		(end 359.300272 -219.01531)
		(width 0.0889)
		(layer "In11.Cu")
		(net "P5E_CPU0_PE1_RX_DN<7>")
	)
	(arc
		(start 360.16565 -221.574614)
		(mid 360.17397 -221.581171)
		(end 360.182414 -221.587568)
		(width 0.0889)
		(layer "In11.Cu")
		(net "P5E_CPU0_PE1_RX_DN<7>")
	)
	(arc
		(start 359.955084 -221.149418)
		(mid 360.013637 -221.385148)
		(end 360.16565 -221.574614)
		(width 0.0889)
		(layer "In11.Cu")
		(net "P5E_CPU0_PE1_RX_DN<7>")
	)
	(arc
		(start 359.29824 -216.739978)
		(mid 359.433285 -216.873702)
		(end 359.485438 -217.056462)
		(width 0.0889)
		(layer "In11.Cu")
		(net "P5E_CPU0_PE1_RX_DN<7>")
	)
	(arc
		(start 359.287572 -217.395298)
		(mid 359.01549 -217.878406)
		(end 359.287572 -218.361514)
		(width 0.0889)
		(layer "In11.Cu")
		(net "P5E_CPU0_PE1_RX_DN<7>")
	)
	(arc
		(start 359.485438 -217.079322)
		(mid 359.431633 -217.258197)
		(end 359.29824 -217.388948)
		(width 0.0889)
		(layer "In11.Cu")
		(net "P5E_CPU0_PE1_RX_DN<7>")
	)
	(arc
		(start 359.776522 -220.814646)
		(mid 359.907436 -220.951006)
		(end 359.955084 -221.133924)
		(width 0.0889)
		(layer "In11.Cu")
		(net "P5E_CPU0_PE1_RX_DN<7>")
	)
	(arc
		(start 359.014776 -214.636858)
		(mid 359.093995 -214.911543)
		(end 359.297478 -215.112346)
		(width 0.0889)
		(layer "In11.Cu")
		(net "P5E_CPU0_PE1_RX_DN<7>")
	)
	(arc
		(start 359.306368 -215.117426)
		(mid 359.437282 -215.253786)
		(end 359.48493 -215.436704)
		(width 0.0889)
		(layer "In11.Cu")
		(net "P5E_CPU0_PE1_RX_DN<7>")
	)
	(arc
		(start 359.287572 -215.767158)
		(mid 359.015273 -216.250454)
		(end 359.287572 -216.733628)
		(width 0.0889)
		(layer "In11.Cu")
		(net "P5E_CPU0_PE1_RX_DN<7>")
	)
	(arc
		(start 359.485184 -215.44915)
		(mid 359.432042 -215.62928)
		(end 359.29824 -215.761062)
		(width 0.0889)
		(layer "In11.Cu")
		(net "P5E_CPU0_PE1_RX_DN<7>")
	)
	(arc
		(start 359.28554 -219.023438)
		(mid 359.088125 -219.212383)
		(end 359.015538 -219.475812)
		(width 0.0889)
		(layer "In11.Cu")
		(net "P5E_CPU0_PE1_RX_DN<7>")
	)
	(arc
		(start 359.29824 -218.367864)
		(mid 359.432202 -218.499593)
		(end 359.485438 -218.679776)
		(width 0.0889)
		(layer "In11.Cu")
		(net "P5E_CPU0_PE1_RX_DN<7>")
	)
	(arc
		(start 359.48493 -220.327474)
		(mid 359.562559 -220.605887)
		(end 359.767632 -220.809566)
		(width 0.0889)
		(layer "In11.Cu")
		(net "P5E_CPU0_PE1_RX_DN<7>")
	)
	(segment
		(start 415.54019 -7.601204)
		(end 415.54019 -5.252974)
		(width 0.13208)
		(layer "F.Cu")
		(net "P5E_CPU0_PE1_RX_DN<6>")
	)
	(segment
		(start 361.45978 -221.669864)
		(end 361.460034 -221.133924)
		(width 0.13208)
		(layer "F.Cu")
		(net "P5E_CPU0_PE1_RX_DN<6>")
	)
	(segment
		(start 415.356802 -8.320024)
		(end 415.356802 -7.784592)
		(width 0.13208)
		(layer "F.Cu")
		(net "P5E_CPU0_PE1_RX_DN<6>")
	)
	(segment
		(start 415.54019 -5.252974)
		(end 415.238946 -4.95173)
		(width 0.13208)
		(layer "F.Cu")
		(net "P5E_CPU0_PE1_RX_DN<6>")
	)
	(segment
		(start 415.356802 -7.784592)
		(end 415.54019 -7.601204)
		(width 0.13208)
		(layer "F.Cu")
		(net "P5E_CPU0_PE1_RX_DN<6>")
	)
	(segment
		(start 360.707432 -217.554048)
		(end 360.716322 -217.559128)
		(width 0.0889)
		(layer "In11.Cu")
		(net "P5E_CPU0_PE1_RX_DN<6>")
	)
	(segment
		(start 416.836098 -17.854676)
		(end 417.55568 -18.931636)
		(width 0.14732)
		(layer "In11.Cu")
		(net "P5E_CPU0_PE1_RX_DN<6>")
	)
	(segment
		(start 360.424984 -214.672418)
		(end 360.424984 -215.444578)
		(width 0.0889)
		(layer "In11.Cu")
		(net "P5E_CPU0_PE1_RX_DN<6>")
	)
	(segment
		(start 360.383074 -211.745068)
		(end 360.383074 -214.60841)
		(width 0.14732)
		(layer "In11.Cu")
		(net "P5E_CPU0_PE1_RX_DN<6>")
	)
	(segment
		(start 360.707432 -220.809566)
		(end 360.722164 -220.818202)
		(width 0.0889)
		(layer "In11.Cu")
		(net "P5E_CPU0_PE1_RX_DN<6>")
	)
	(segment
		(start 360.716322 -218.197684)
		(end 360.708956 -218.202002)
		(width 0.0889)
		(layer "In11.Cu")
		(net "P5E_CPU0_PE1_RX_DN<6>")
	)
	(segment
		(start 415.533586 -12.563094)
		(end 416.836098 -17.854676)
		(width 0.14732)
		(layer "In11.Cu")
		(net "P5E_CPU0_PE1_RX_DN<6>")
	)
	(segment
		(start 360.708956 -218.202002)
		(end 360.707432 -218.202764)
		(width 0.0889)
		(layer "In11.Cu")
		(net "P5E_CPU0_PE1_RX_DN<6>")
	)
	(segment
		(start 360.383074 -214.60841)
		(end 360.383074 -214.630508)
		(width 0.0889)
		(layer "In11.Cu")
		(net "P5E_CPU0_PE1_RX_DN<6>")
	)
	(segment
		(start 361.214416 -220.83903)
		(end 361.30357 -220.862906)
		(width 0.0889)
		(layer "In11.Cu")
		(net "P5E_CPU0_PE1_RX_DN<6>")
	)
	(segment
		(start 360.231436 -216.736422)
		(end 360.237532 -216.739978)
		(width 0.0889)
		(layer "In11.Cu")
		(net "P5E_CPU0_PE1_RX_DN<6>")
	)
	(segment
		(start 359.955084 -219.490544)
		(end 359.955084 -219.515944)
		(width 0.0889)
		(layer "In11.Cu")
		(net "P5E_CPU0_PE1_RX_DN<6>")
	)
	(segment
		(start 361.30357 -220.862906)
		(end 361.460034 -221.133924)
		(width 0.0889)
		(layer "In11.Cu")
		(net "P5E_CPU0_PE1_RX_DN<6>")
	)
	(segment
		(start 359.95483 -216.240614)
		(end 359.95483 -216.25052)
		(width 0.0889)
		(layer "In11.Cu")
		(net "P5E_CPU0_PE1_RX_DN<6>")
	)
	(segment
		(start 362.988352 -162.47237)
		(end 359.17505 -184.108598)
		(width 0.14732)
		(layer "In11.Cu")
		(net "P5E_CPU0_PE1_RX_DN<6>")
	)
	(segment
		(start 411.005528 -77.225144)
		(end 409.47848 -80.353662)
		(width 0.14732)
		(layer "In11.Cu")
		(net "P5E_CPU0_PE1_RX_DN<6>")
	)
	(segment
		(start 359.17505 -184.108598)
		(end 360.383074 -211.745068)
		(width 0.14732)
		(layer "In11.Cu")
		(net "P5E_CPU0_PE1_RX_DN<6>")
	)
	(segment
		(start 417.55568 -18.931636)
		(end 417.55568 -19.380454)
		(width 0.14732)
		(layer "In11.Cu")
		(net "P5E_CPU0_PE1_RX_DN<6>")
	)
	(segment
		(start 360.246168 -219.0115)
		(end 360.237278 -219.01658)
		(width 0.0889)
		(layer "In11.Cu")
		(net "P5E_CPU0_PE1_RX_DN<6>")
	)
	(segment
		(start 417.55568 -19.380454)
		(end 411.005528 -77.225144)
		(width 0.14732)
		(layer "In11.Cu")
		(net "P5E_CPU0_PE1_RX_DN<6>")
	)
	(segment
		(start 360.246168 -215.755982)
		(end 360.237278 -215.761062)
		(width 0.0889)
		(layer "In11.Cu")
		(net "P5E_CPU0_PE1_RX_DN<6>")
	)
	(segment
		(start 360.707432 -218.202764)
		(end 360.704638 -218.204288)
		(width 0.0889)
		(layer "In11.Cu")
		(net "P5E_CPU0_PE1_RX_DN<6>")
	)
	(segment
		(start 409.47848 -80.353662)
		(end 362.988352 -162.47237)
		(width 0.14732)
		(layer "In11.Cu")
		(net "P5E_CPU0_PE1_RX_DN<6>")
	)
	(segment
		(start 360.704638 -218.204288)
		(end 360.701336 -218.20632)
		(width 0.0889)
		(layer "In11.Cu")
		(net "P5E_CPU0_PE1_RX_DN<6>")
	)
	(segment
		(start 415.533586 -5.24637)
		(end 415.533586 -12.563094)
		(width 0.14732)
		(layer "In11.Cu")
		(net "P5E_CPU0_PE1_RX_DN<6>")
	)
	(segment
		(start 415.238946 -4.95173)
		(end 415.533586 -5.24637)
		(width 0.14732)
		(layer "In11.Cu")
		(net "P5E_CPU0_PE1_RX_DN<6>")
	)
	(segment
		(start 360.42473 -220.311218)
		(end 360.42473 -220.334078)
		(width 0.0889)
		(layer "In11.Cu")
		(net "P5E_CPU0_PE1_RX_DN<6>")
	)
	(segment
		(start 360.383074 -214.630508)
		(end 360.424984 -214.672418)
		(width 0.0889)
		(layer "In11.Cu")
		(net "P5E_CPU0_PE1_RX_DN<6>")
	)
	(segment
		(start 360.42473 -217.0557)
		(end 360.42473 -217.07856)
		(width 0.0889)
		(layer "In11.Cu")
		(net "P5E_CPU0_PE1_RX_DN<6>")
	)
	(arc
		(start 361.19435 -220.847158)
		(mid 361.204423 -220.843192)
		(end 361.214416 -220.83903)
		(width 0.0889)
		(layer "In11.Cu")
		(net "P5E_CPU0_PE1_RX_DN<6>")
	)
	(arc
		(start 360.237532 -219.995496)
		(mid 360.372465 -220.12885)
		(end 360.42473 -220.311218)
		(width 0.0889)
		(layer "In11.Cu")
		(net "P5E_CPU0_PE1_RX_DN<6>")
	)
	(arc
		(start 360.701336 -218.20632)
		(mid 360.498749 -218.412671)
		(end 360.42473 -218.692222)
		(width 0.0889)
		(layer "In11.Cu")
		(net "P5E_CPU0_PE1_RX_DN<6>")
	)
	(arc
		(start 360.42473 -220.334078)
		(mid 360.503949 -220.608763)
		(end 360.707432 -220.809566)
		(width 0.0889)
		(layer "In11.Cu")
		(net "P5E_CPU0_PE1_RX_DN<6>")
	)
	(arc
		(start 360.42473 -217.07856)
		(mid 360.503949 -217.353245)
		(end 360.707432 -217.554048)
		(width 0.0889)
		(layer "In11.Cu")
		(net "P5E_CPU0_PE1_RX_DN<6>")
	)
	(arc
		(start 359.95483 -216.25052)
		(mid 360.028821 -216.530086)
		(end 360.231436 -216.736422)
		(width 0.0889)
		(layer "In11.Cu")
		(net "P5E_CPU0_PE1_RX_DN<6>")
	)
	(arc
		(start 360.722164 -220.818202)
		(mid 360.955079 -220.884383)
		(end 361.19435 -220.847158)
		(width 0.0889)
		(layer "In11.Cu")
		(net "P5E_CPU0_PE1_RX_DN<6>")
	)
	(arc
		(start 360.424984 -215.444578)
		(mid 360.375313 -215.623111)
		(end 360.246168 -215.755982)
		(width 0.0889)
		(layer "In11.Cu")
		(net "P5E_CPU0_PE1_RX_DN<6>")
	)
	(arc
		(start 360.237278 -219.01658)
		(mid 360.034455 -219.216811)
		(end 359.955084 -219.490544)
		(width 0.0889)
		(layer "In11.Cu")
		(net "P5E_CPU0_PE1_RX_DN<6>")
	)
	(arc
		(start 360.716322 -217.559128)
		(mid 360.89504 -217.878406)
		(end 360.716322 -218.197684)
		(width 0.0889)
		(layer "In11.Cu")
		(net "P5E_CPU0_PE1_RX_DN<6>")
	)
	(arc
		(start 360.237278 -215.761062)
		(mid 360.032943 -215.963667)
		(end 359.95483 -216.240614)
		(width 0.0889)
		(layer "In11.Cu")
		(net "P5E_CPU0_PE1_RX_DN<6>")
	)
	(arc
		(start 360.42473 -218.692222)
		(mid 360.377051 -218.875122)
		(end 360.246168 -219.0115)
		(width 0.0889)
		(layer "In11.Cu")
		(net "P5E_CPU0_PE1_RX_DN<6>")
	)
	(arc
		(start 360.237532 -216.739978)
		(mid 360.372465 -216.873332)
		(end 360.42473 -217.0557)
		(width 0.0889)
		(layer "In11.Cu")
		(net "P5E_CPU0_PE1_RX_DN<6>")
	)
	(arc
		(start 359.955084 -219.515944)
		(mid 360.033195 -219.792893)
		(end 360.237532 -219.995496)
		(width 0.0889)
		(layer "In11.Cu")
		(net "P5E_CPU0_PE1_RX_DN<6>")
	)
	(segment
		(start 417.336478 -7.597394)
		(end 417.336478 -7.015734)
		(width 0.13208)
		(layer "F.Cu")
		(net "P5E_CPU0_PE1_RX_DN<5>")
	)
	(segment
		(start 417.1569 -7.776972)
		(end 417.336478 -7.597394)
		(width 0.13208)
		(layer "F.Cu")
		(net "P5E_CPU0_PE1_RX_DN<5>")
	)
	(segment
		(start 417.1569 -8.320024)
		(end 417.1569 -7.776972)
		(width 0.13208)
		(layer "F.Cu")
		(net "P5E_CPU0_PE1_RX_DN<5>")
	)
	(segment
		(start 361.929934 -222.48368)
		(end 361.929934 -221.94774)
		(width 0.13208)
		(layer "F.Cu")
		(net "P5E_CPU0_PE1_RX_DN<5>")
	)
	(segment
		(start 417.336478 -7.015734)
		(end 417.034218 -6.713474)
		(width 0.13208)
		(layer "F.Cu")
		(net "P5E_CPU0_PE1_RX_DN<5>")
	)
	(segment
		(start 360.89463 -216.240614)
		(end 360.89463 -216.260426)
		(width 0.0889)
		(layer "In11.Cu")
		(net "P5E_CPU0_PE1_RX_DN<5>")
	)
	(segment
		(start 360.159808 -183.878474)
		(end 361.323128 -211.800948)
		(width 0.14732)
		(layer "In11.Cu")
		(net "P5E_CPU0_PE1_RX_DN<5>")
	)
	(segment
		(start 360.894884 -219.490544)
		(end 360.894884 -219.521532)
		(width 0.0889)
		(layer "In11.Cu")
		(net "P5E_CPU0_PE1_RX_DN<5>")
	)
	(segment
		(start 361.185968 -219.0115)
		(end 361.178094 -219.016072)
		(width 0.0889)
		(layer "In11.Cu")
		(net "P5E_CPU0_PE1_RX_DN<5>")
	)
	(segment
		(start 361.323382 -214.640668)
		(end 361.365292 -214.682578)
		(width 0.0889)
		(layer "In11.Cu")
		(net "P5E_CPU0_PE1_RX_DN<5>")
	)
	(segment
		(start 361.177078 -219.995496)
		(end 361.178094 -219.996004)
		(width 0.0889)
		(layer "In11.Cu")
		(net "P5E_CPU0_PE1_RX_DN<5>")
	)
	(segment
		(start 361.323382 -211.801202)
		(end 361.323382 -214.61857)
		(width 0.14732)
		(layer "In11.Cu")
		(net "P5E_CPU0_PE1_RX_DN<5>")
	)
	(segment
		(start 415.344356 -55.235348)
		(end 412.047182 -77.77988)
		(width 0.14732)
		(layer "In11.Cu")
		(net "P5E_CPU0_PE1_RX_DN<5>")
	)
	(segment
		(start 420.34206 -17.424908)
		(end 420.34206 -17.802098)
		(width 0.14732)
		(layer "In11.Cu")
		(net "P5E_CPU0_PE1_RX_DN<5>")
	)
	(segment
		(start 361.834684 -221.133924)
		(end 361.834684 -221.14383)
		(width 0.0889)
		(layer "In11.Cu")
		(net "P5E_CPU0_PE1_RX_DN<5>")
	)
	(segment
		(start 361.18165 -216.742772)
		(end 361.185968 -216.745058)
		(width 0.0889)
		(layer "In11.Cu")
		(net "P5E_CPU0_PE1_RX_DN<5>")
	)
	(segment
		(start 361.179872 -216.741756)
		(end 361.18165 -216.742772)
		(width 0.0889)
		(layer "In11.Cu")
		(net "P5E_CPU0_PE1_RX_DN<5>")
	)
	(segment
		(start 417.328858 -12.423648)
		(end 417.430204 -12.775692)
		(width 0.14732)
		(layer "In11.Cu")
		(net "P5E_CPU0_PE1_RX_DN<5>")
	)
	(segment
		(start 363.8804 -162.863784)
		(end 363.879892 -162.865308)
		(width 0.14732)
		(layer "In11.Cu")
		(net "P5E_CPU0_PE1_RX_DN<5>")
	)
	(segment
		(start 361.178094 -219.996004)
		(end 361.185968 -220.000576)
		(width 0.0889)
		(layer "In11.Cu")
		(net "P5E_CPU0_PE1_RX_DN<5>")
	)
	(segment
		(start 363.892084 -162.842702)
		(end 363.892338 -162.842702)
		(width 0.14732)
		(layer "In11.Cu")
		(net "P5E_CPU0_PE1_RX_DN<5>")
	)
	(segment
		(start 361.178856 -216.741248)
		(end 361.179872 -216.741756)
		(width 0.0889)
		(layer "In11.Cu")
		(net "P5E_CPU0_PE1_RX_DN<5>")
	)
	(segment
		(start 363.892338 -162.842702)
		(end 363.8804 -162.863784)
		(width 0.14732)
		(layer "In11.Cu")
		(net "P5E_CPU0_PE1_RX_DN<5>")
	)
	(segment
		(start 361.17784 -215.760554)
		(end 361.177078 -215.761062)
		(width 0.0889)
		(layer "In11.Cu")
		(net "P5E_CPU0_PE1_RX_DN<5>")
	)
	(segment
		(start 361.36453 -220.319854)
		(end 361.36453 -220.327474)
		(width 0.0889)
		(layer "In11.Cu")
		(net "P5E_CPU0_PE1_RX_DN<5>")
	)
	(segment
		(start 420.34206 -17.802098)
		(end 419.72738 -18.722086)
		(width 0.14732)
		(layer "In11.Cu")
		(net "P5E_CPU0_PE1_RX_DN<5>")
	)
	(segment
		(start 363.879892 -162.865308)
		(end 363.868208 -162.885882)
		(width 0.14732)
		(layer "In11.Cu")
		(net "P5E_CPU0_PE1_RX_DN<5>")
	)
	(segment
		(start 361.365292 -215.38565)
		(end 361.364276 -215.443308)
		(width 0.0889)
		(layer "In11.Cu")
		(net "P5E_CPU0_PE1_RX_DN<5>")
	)
	(segment
		(start 361.647232 -217.554048)
		(end 361.656122 -217.559128)
		(width 0.0889)
		(layer "In11.Cu")
		(net "P5E_CPU0_PE1_RX_DN<5>")
	)
	(segment
		(start 363.856524 -162.90671)
		(end 360.159808 -183.878474)
		(width 0.14732)
		(layer "In11.Cu")
		(net "P5E_CPU0_PE1_RX_DN<5>")
	)
	(segment
		(start 363.868208 -162.885882)
		(end 363.856524 -162.90671)
		(width 0.14732)
		(layer "In11.Cu")
		(net "P5E_CPU0_PE1_RX_DN<5>")
	)
	(segment
		(start 419.509956 -19.437604)
		(end 415.344356 -55.235348)
		(width 0.14732)
		(layer "In11.Cu")
		(net "P5E_CPU0_PE1_RX_DN<5>")
	)
	(segment
		(start 417.328858 -7.008114)
		(end 417.328858 -12.423648)
		(width 0.14732)
		(layer "In11.Cu")
		(net "P5E_CPU0_PE1_RX_DN<5>")
	)
	(segment
		(start 412.047182 -77.77988)
		(end 363.892592 -162.842194)
		(width 0.14732)
		(layer "In11.Cu")
		(net "P5E_CPU0_PE1_RX_DN<5>")
	)
	(segment
		(start 417.430204 -12.775692)
		(end 420.34206 -17.424908)
		(width 0.14732)
		(layer "In11.Cu")
		(net "P5E_CPU0_PE1_RX_DN<5>")
	)
	(segment
		(start 361.365292 -214.682578)
		(end 361.365292 -215.38565)
		(width 0.0889)
		(layer "In11.Cu")
		(net "P5E_CPU0_PE1_RX_DN<5>")
	)
	(segment
		(start 361.656122 -218.197684)
		(end 361.647232 -218.202764)
		(width 0.0889)
		(layer "In11.Cu")
		(net "P5E_CPU0_PE1_RX_DN<5>")
	)
	(segment
		(start 361.177078 -216.739978)
		(end 361.178856 -216.741248)
		(width 0.0889)
		(layer "In11.Cu")
		(net "P5E_CPU0_PE1_RX_DN<5>")
	)
	(segment
		(start 361.178094 -219.016072)
		(end 361.177078 -219.01658)
		(width 0.0889)
		(layer "In11.Cu")
		(net "P5E_CPU0_PE1_RX_DN<5>")
	)
	(segment
		(start 361.647232 -220.809566)
		(end 361.656122 -220.814646)
		(width 0.0889)
		(layer "In11.Cu")
		(net "P5E_CPU0_PE1_RX_DN<5>")
	)
	(segment
		(start 362.086398 -221.676722)
		(end 361.929934 -221.94774)
		(width 0.0889)
		(layer "In11.Cu")
		(net "P5E_CPU0_PE1_RX_DN<5>")
	)
	(segment
		(start 361.323128 -211.800948)
		(end 361.323382 -211.801202)
		(width 0.14732)
		(layer "In11.Cu")
		(net "P5E_CPU0_PE1_RX_DN<5>")
	)
	(segment
		(start 362.062268 -221.587568)
		(end 362.086398 -221.676722)
		(width 0.0889)
		(layer "In11.Cu")
		(net "P5E_CPU0_PE1_RX_DN<5>")
	)
	(segment
		(start 417.034218 -6.713474)
		(end 417.328858 -7.008114)
		(width 0.14732)
		(layer "In11.Cu")
		(net "P5E_CPU0_PE1_RX_DN<5>")
	)
	(segment
		(start 361.323382 -214.61857)
		(end 361.323382 -214.640668)
		(width 0.0889)
		(layer "In11.Cu")
		(net "P5E_CPU0_PE1_RX_DN<5>")
	)
	(segment
		(start 419.72738 -18.722086)
		(end 419.509956 -19.437604)
		(width 0.14732)
		(layer "In11.Cu")
		(net "P5E_CPU0_PE1_RX_DN<5>")
	)
	(segment
		(start 363.892592 -162.842194)
		(end 363.892084 -162.842702)
		(width 0.14732)
		(layer "In11.Cu")
		(net "P5E_CPU0_PE1_RX_DN<5>")
	)
	(segment
		(start 361.647232 -218.202764)
		(end 361.643422 -218.20505)
		(width 0.0889)
		(layer "In11.Cu")
		(net "P5E_CPU0_PE1_RX_DN<5>")
	)
	(segment
		(start 361.643422 -218.20505)
		(end 361.63504 -218.209876)
		(width 0.0889)
		(layer "In11.Cu")
		(net "P5E_CPU0_PE1_RX_DN<5>")
	)
	(segment
		(start 361.36453 -217.064336)
		(end 361.36453 -217.071956)
		(width 0.0889)
		(layer "In11.Cu")
		(net "P5E_CPU0_PE1_RX_DN<5>")
	)
	(arc
		(start 360.894884 -219.521532)
		(mid 360.974254 -219.795266)
		(end 361.177078 -219.995496)
		(width 0.0889)
		(layer "In11.Cu")
		(net "P5E_CPU0_PE1_RX_DN<5>")
	)
	(arc
		(start 361.185968 -216.745058)
		(mid 361.316882 -216.881418)
		(end 361.36453 -217.064336)
		(width 0.0889)
		(layer "In11.Cu")
		(net "P5E_CPU0_PE1_RX_DN<5>")
	)
	(arc
		(start 361.834684 -217.88501)
		(mid 361.785431 -218.06421)
		(end 361.656122 -218.197684)
		(width 0.0889)
		(layer "In11.Cu")
		(net "P5E_CPU0_PE1_RX_DN<5>")
	)
	(arc
		(start 361.185968 -220.000576)
		(mid 361.316882 -220.136936)
		(end 361.36453 -220.319854)
		(width 0.0889)
		(layer "In11.Cu")
		(net "P5E_CPU0_PE1_RX_DN<5>")
	)
	(arc
		(start 360.89463 -216.260426)
		(mid 360.972741 -216.537375)
		(end 361.177078 -216.739978)
		(width 0.0889)
		(layer "In11.Cu")
		(net "P5E_CPU0_PE1_RX_DN<5>")
	)
	(arc
		(start 361.177078 -219.01658)
		(mid 360.974255 -219.216811)
		(end 360.894884 -219.490544)
		(width 0.0889)
		(layer "In11.Cu")
		(net "P5E_CPU0_PE1_RX_DN<5>")
	)
	(arc
		(start 361.656122 -217.559128)
		(mid 361.784015 -217.69019)
		(end 361.83443 -217.866214)
		(width 0.0889)
		(layer "In11.Cu")
		(net "P5E_CPU0_PE1_RX_DN<5>")
	)
	(arc
		(start 361.83443 -217.866214)
		(mid 361.834675 -217.87561)
		(end 361.834684 -217.88501)
		(width 0.0889)
		(layer "In11.Cu")
		(net "P5E_CPU0_PE1_RX_DN<5>")
	)
	(arc
		(start 361.36453 -220.327474)
		(mid 361.442159 -220.605887)
		(end 361.647232 -220.809566)
		(width 0.0889)
		(layer "In11.Cu")
		(net "P5E_CPU0_PE1_RX_DN<5>")
	)
	(arc
		(start 361.63504 -218.209876)
		(mid 361.436812 -218.415724)
		(end 361.36453 -218.692222)
		(width 0.0889)
		(layer "In11.Cu")
		(net "P5E_CPU0_PE1_RX_DN<5>")
	)
	(arc
		(start 361.177078 -215.761062)
		(mid 360.972743 -215.963667)
		(end 360.89463 -216.240614)
		(width 0.0889)
		(layer "In11.Cu")
		(net "P5E_CPU0_PE1_RX_DN<5>")
	)
	(arc
		(start 361.36453 -217.071956)
		(mid 361.442159 -217.350369)
		(end 361.647232 -217.554048)
		(width 0.0889)
		(layer "In11.Cu")
		(net "P5E_CPU0_PE1_RX_DN<5>")
	)
	(arc
		(start 362.045504 -221.574614)
		(mid 362.053826 -221.581168)
		(end 362.062268 -221.587568)
		(width 0.0889)
		(layer "In11.Cu")
		(net "P5E_CPU0_PE1_RX_DN<5>")
	)
	(arc
		(start 361.834684 -221.14383)
		(mid 361.892157 -221.382677)
		(end 362.045504 -221.574614)
		(width 0.0889)
		(layer "In11.Cu")
		(net "P5E_CPU0_PE1_RX_DN<5>")
	)
	(arc
		(start 361.656122 -220.814646)
		(mid 361.787036 -220.951006)
		(end 361.834684 -221.133924)
		(width 0.0889)
		(layer "In11.Cu")
		(net "P5E_CPU0_PE1_RX_DN<5>")
	)
	(arc
		(start 361.36453 -218.692222)
		(mid 361.316851 -218.875122)
		(end 361.185968 -219.0115)
		(width 0.0889)
		(layer "In11.Cu")
		(net "P5E_CPU0_PE1_RX_DN<5>")
	)
	(arc
		(start 361.364276 -215.443308)
		(mid 361.31272 -215.626416)
		(end 361.17784 -215.760554)
		(width 0.0889)
		(layer "In11.Cu")
		(net "P5E_CPU0_PE1_RX_DN<5>")
	)
	(segment
		(start 363.33938 -221.669864)
		(end 363.339634 -221.133924)
		(width 0.13208)
		(layer "F.Cu")
		(net "P5E_CPU0_PE1_RX_DN<4>")
	)
	(segment
		(start 419.140132 -5.252974)
		(end 418.838888 -4.95173)
		(width 0.13208)
		(layer "F.Cu")
		(net "P5E_CPU0_PE1_RX_DN<4>")
	)
	(segment
		(start 418.956998 -8.320024)
		(end 418.956998 -7.784338)
		(width 0.13208)
		(layer "F.Cu")
		(net "P5E_CPU0_PE1_RX_DN<4>")
	)
	(segment
		(start 419.140132 -7.601204)
		(end 419.140132 -5.252974)
		(width 0.13208)
		(layer "F.Cu")
		(net "P5E_CPU0_PE1_RX_DN<4>")
	)
	(segment
		(start 418.956998 -7.784338)
		(end 419.140132 -7.601204)
		(width 0.13208)
		(layer "F.Cu")
		(net "P5E_CPU0_PE1_RX_DN<4>")
	)
	(segment
		(start 419.133528 -5.24637)
		(end 419.133528 -12.268454)
		(width 0.14732)
		(layer "In11.Cu")
		(net "P5E_CPU0_PE1_RX_DN<4>")
	)
	(segment
		(start 363.094016 -220.83903)
		(end 363.18317 -220.862906)
		(width 0.0889)
		(layer "In11.Cu")
		(net "P5E_CPU0_PE1_RX_DN<4>")
	)
	(segment
		(start 362.588556 -218.202002)
		(end 362.587032 -218.202764)
		(width 0.0889)
		(layer "In11.Cu")
		(net "P5E_CPU0_PE1_RX_DN<4>")
	)
	(segment
		(start 362.58627 -218.203272)
		(end 362.580936 -218.20632)
		(width 0.0889)
		(layer "In11.Cu")
		(net "P5E_CPU0_PE1_RX_DN<4>")
	)
	(segment
		(start 413.084264 -77.920088)
		(end 364.723426 -163.347146)
		(width 0.14732)
		(layer "In11.Cu")
		(net "P5E_CPU0_PE1_RX_DN<4>")
	)
	(segment
		(start 362.304584 -214.818468)
		(end 362.30433 -215.436704)
		(width 0.0889)
		(layer "In11.Cu")
		(net "P5E_CPU0_PE1_RX_DN<4>")
	)
	(segment
		(start 362.587032 -217.554048)
		(end 362.595922 -217.559128)
		(width 0.0889)
		(layer "In11.Cu")
		(net "P5E_CPU0_PE1_RX_DN<4>")
	)
	(segment
		(start 422.58234 -18.185384)
		(end 423.12844 -19.00301)
		(width 0.14732)
		(layer "In11.Cu")
		(net "P5E_CPU0_PE1_RX_DN<4>")
	)
	(segment
		(start 362.262674 -214.61857)
		(end 362.262674 -214.640668)
		(width 0.0889)
		(layer "In11.Cu")
		(net "P5E_CPU0_PE1_RX_DN<4>")
	)
	(segment
		(start 362.595922 -218.197684)
		(end 362.588556 -218.202002)
		(width 0.0889)
		(layer "In11.Cu")
		(net "P5E_CPU0_PE1_RX_DN<4>")
	)
	(segment
		(start 362.125768 -215.755982)
		(end 362.116878 -215.761062)
		(width 0.0889)
		(layer "In11.Cu")
		(net "P5E_CPU0_PE1_RX_DN<4>")
	)
	(segment
		(start 362.30433 -220.311218)
		(end 362.30433 -220.338396)
		(width 0.0889)
		(layer "In11.Cu")
		(net "P5E_CPU0_PE1_RX_DN<4>")
	)
	(segment
		(start 362.125768 -219.0115)
		(end 362.116878 -219.01658)
		(width 0.0889)
		(layer "In11.Cu")
		(net "P5E_CPU0_PE1_RX_DN<4>")
	)
	(segment
		(start 362.262674 -214.640668)
		(end 362.304584 -214.682578)
		(width 0.0889)
		(layer "In11.Cu")
		(net "P5E_CPU0_PE1_RX_DN<4>")
	)
	(segment
		(start 362.30433 -217.0557)
		(end 362.30433 -217.07856)
		(width 0.0889)
		(layer "In11.Cu")
		(net "P5E_CPU0_PE1_RX_DN<4>")
	)
	(segment
		(start 361.097576 -183.919622)
		(end 362.262674 -211.991956)
		(width 0.14732)
		(layer "In11.Cu")
		(net "P5E_CPU0_PE1_RX_DN<4>")
	)
	(segment
		(start 362.587032 -218.202764)
		(end 362.58627 -218.203272)
		(width 0.0889)
		(layer "In11.Cu")
		(net "P5E_CPU0_PE1_RX_DN<4>")
	)
	(segment
		(start 363.18317 -220.862906)
		(end 363.339634 -221.133924)
		(width 0.0889)
		(layer "In11.Cu")
		(net "P5E_CPU0_PE1_RX_DN<4>")
	)
	(segment
		(start 364.723426 -163.347146)
		(end 361.097576 -183.919622)
		(width 0.14732)
		(layer "In11.Cu")
		(net "P5E_CPU0_PE1_RX_DN<4>")
	)
	(segment
		(start 423.12844 -19.00301)
		(end 423.12844 -19.445732)
		(width 0.14732)
		(layer "In11.Cu")
		(net "P5E_CPU0_PE1_RX_DN<4>")
	)
	(segment
		(start 423.12844 -19.445732)
		(end 421.051736 -27.843734)
		(width 0.14732)
		(layer "In11.Cu")
		(net "P5E_CPU0_PE1_RX_DN<4>")
	)
	(segment
		(start 418.838888 -4.95173)
		(end 419.133528 -5.24637)
		(width 0.14732)
		(layer "In11.Cu")
		(net "P5E_CPU0_PE1_RX_DN<4>")
	)
	(segment
		(start 419.133528 -12.268454)
		(end 422.58234 -18.185384)
		(width 0.14732)
		(layer "In11.Cu")
		(net "P5E_CPU0_PE1_RX_DN<4>")
	)
	(segment
		(start 421.051736 -27.843734)
		(end 413.084264 -77.920088)
		(width 0.14732)
		(layer "In11.Cu")
		(net "P5E_CPU0_PE1_RX_DN<4>")
	)
	(segment
		(start 362.304584 -214.682578)
		(end 362.304584 -214.818468)
		(width 0.0889)
		(layer "In11.Cu")
		(net "P5E_CPU0_PE1_RX_DN<4>")
	)
	(segment
		(start 362.262674 -211.991956)
		(end 362.262674 -214.61857)
		(width 0.14732)
		(layer "In11.Cu")
		(net "P5E_CPU0_PE1_RX_DN<4>")
	)
	(arc
		(start 362.116878 -215.761062)
		(mid 361.834473 -216.25063)
		(end 362.117132 -216.739978)
		(width 0.0889)
		(layer "In11.Cu")
		(net "P5E_CPU0_PE1_RX_DN<4>")
	)
	(arc
		(start 362.595922 -217.559128)
		(mid 362.774519 -217.878406)
		(end 362.595922 -218.197684)
		(width 0.0889)
		(layer "In11.Cu")
		(net "P5E_CPU0_PE1_RX_DN<4>")
	)
	(arc
		(start 362.30433 -220.338396)
		(mid 362.557688 -220.791579)
		(end 363.07395 -220.847158)
		(width 0.0889)
		(layer "In11.Cu")
		(net "P5E_CPU0_PE1_RX_DN<4>")
	)
	(arc
		(start 362.30433 -217.07856)
		(mid 362.383549 -217.353245)
		(end 362.587032 -217.554048)
		(width 0.0889)
		(layer "In11.Cu")
		(net "P5E_CPU0_PE1_RX_DN<4>")
	)
	(arc
		(start 362.117132 -216.739978)
		(mid 362.252065 -216.873332)
		(end 362.30433 -217.0557)
		(width 0.0889)
		(layer "In11.Cu")
		(net "P5E_CPU0_PE1_RX_DN<4>")
	)
	(arc
		(start 362.30433 -215.436704)
		(mid 362.256651 -215.619604)
		(end 362.125768 -215.755982)
		(width 0.0889)
		(layer "In11.Cu")
		(net "P5E_CPU0_PE1_RX_DN<4>")
	)
	(arc
		(start 362.580936 -218.20632)
		(mid 362.378349 -218.412671)
		(end 362.30433 -218.692222)
		(width 0.0889)
		(layer "In11.Cu")
		(net "P5E_CPU0_PE1_RX_DN<4>")
	)
	(arc
		(start 362.30433 -218.692222)
		(mid 362.256651 -218.875122)
		(end 362.125768 -219.0115)
		(width 0.0889)
		(layer "In11.Cu")
		(net "P5E_CPU0_PE1_RX_DN<4>")
	)
	(arc
		(start 363.07395 -220.847158)
		(mid 363.084022 -220.843191)
		(end 363.094016 -220.83903)
		(width 0.0889)
		(layer "In11.Cu")
		(net "P5E_CPU0_PE1_RX_DN<4>")
	)
	(arc
		(start 362.117132 -219.995496)
		(mid 362.252065 -220.12885)
		(end 362.30433 -220.311218)
		(width 0.0889)
		(layer "In11.Cu")
		(net "P5E_CPU0_PE1_RX_DN<4>")
	)
	(arc
		(start 362.116878 -219.01658)
		(mid 361.834473 -219.506148)
		(end 362.117132 -219.995496)
		(width 0.0889)
		(layer "In11.Cu")
		(net "P5E_CPU0_PE1_RX_DN<4>")
	)
	(segment
		(start 363.809534 -222.48368)
		(end 363.80928 -221.94774)
		(width 0.13208)
		(layer "F.Cu")
		(net "P5E_CPU0_PE1_RX_DN<3>")
	)
	(segment
		(start 424.766994 -8.320024)
		(end 424.766994 -7.776972)
		(width 0.13208)
		(layer "F.Cu")
		(net "P5E_CPU0_PE1_RX_DN<3>")
	)
	(segment
		(start 424.946572 -7.015734)
		(end 424.644312 -6.713474)
		(width 0.13208)
		(layer "F.Cu")
		(net "P5E_CPU0_PE1_RX_DN<3>")
	)
	(segment
		(start 424.766994 -7.776972)
		(end 424.946572 -7.597394)
		(width 0.13208)
		(layer "F.Cu")
		(net "P5E_CPU0_PE1_RX_DN<3>")
	)
	(segment
		(start 424.946572 -7.597394)
		(end 424.946572 -7.015734)
		(width 0.13208)
		(layer "F.Cu")
		(net "P5E_CPU0_PE1_RX_DN<3>")
	)
	(segment
		(start 363.714284 -221.133924)
		(end 363.714284 -221.149418)
		(width 0.0889)
		(layer "In11.Cu")
		(net "P5E_CPU0_PE1_RX_DN<3>")
	)
	(segment
		(start 365.67491 -163.606734)
		(end 362.071412 -184.047892)
		(width 0.14732)
		(layer "In11.Cu")
		(net "P5E_CPU0_PE1_RX_DN<3>")
	)
	(segment
		(start 424.938952 -12.560808)
		(end 424.950382 -12.676632)
		(width 0.14732)
		(layer "In11.Cu")
		(net "P5E_CPU0_PE1_RX_DN<3>")
	)
	(segment
		(start 362.071412 -184.047892)
		(end 363.202474 -210.409536)
		(width 0.14732)
		(layer "In11.Cu")
		(net "P5E_CPU0_PE1_RX_DN<3>")
	)
	(segment
		(start 363.527594 -217.554556)
		(end 363.535722 -217.559128)
		(width 0.0889)
		(layer "In11.Cu")
		(net "P5E_CPU0_PE1_RX_DN<3>")
	)
	(segment
		(start 363.528356 -218.202002)
		(end 363.526832 -218.202764)
		(width 0.0889)
		(layer "In11.Cu")
		(net "P5E_CPU0_PE1_RX_DN<3>")
	)
	(segment
		(start 363.965744 -221.676722)
		(end 363.80928 -221.94774)
		(width 0.0889)
		(layer "In11.Cu")
		(net "P5E_CPU0_PE1_RX_DN<3>")
	)
	(segment
		(start 363.056678 -219.995496)
		(end 363.057694 -219.996004)
		(width 0.0889)
		(layer "In11.Cu")
		(net "P5E_CPU0_PE1_RX_DN<3>")
	)
	(segment
		(start 425.91228 -17.493488)
		(end 425.91228 -17.92986)
		(width 0.14732)
		(layer "In11.Cu")
		(net "P5E_CPU0_PE1_RX_DN<3>")
	)
	(segment
		(start 424.950382 -12.676632)
		(end 425.91228 -17.493488)
		(width 0.14732)
		(layer "In11.Cu")
		(net "P5E_CPU0_PE1_RX_DN<3>")
	)
	(segment
		(start 363.526832 -218.202764)
		(end 363.52607 -218.203272)
		(width 0.0889)
		(layer "In11.Cu")
		(net "P5E_CPU0_PE1_RX_DN<3>")
	)
	(segment
		(start 362.77423 -216.240614)
		(end 362.77423 -216.260426)
		(width 0.0889)
		(layer "In11.Cu")
		(net "P5E_CPU0_PE1_RX_DN<3>")
	)
	(segment
		(start 363.056678 -216.739978)
		(end 363.065568 -216.745058)
		(width 0.0889)
		(layer "In11.Cu")
		(net "P5E_CPU0_PE1_RX_DN<3>")
	)
	(segment
		(start 363.202728 -210.40979)
		(end 363.202728 -212.89391)
		(width 0.14732)
		(layer "In11.Cu")
		(net "P5E_CPU0_PE1_RX_DN<3>")
	)
	(segment
		(start 363.057694 -219.996004)
		(end 363.065568 -220.000576)
		(width 0.0889)
		(layer "In11.Cu")
		(net "P5E_CPU0_PE1_RX_DN<3>")
	)
	(segment
		(start 425.91228 -17.92986)
		(end 425.30141 -18.843752)
		(width 0.14732)
		(layer "In11.Cu")
		(net "P5E_CPU0_PE1_RX_DN<3>")
	)
	(segment
		(start 422.054528 -28.133294)
		(end 414.1343 -78.005686)
		(width 0.14732)
		(layer "In11.Cu")
		(net "P5E_CPU0_PE1_RX_DN<3>")
	)
	(segment
		(start 363.24413 -220.319854)
		(end 363.24413 -220.327474)
		(width 0.0889)
		(layer "In11.Cu")
		(net "P5E_CPU0_PE1_RX_DN<3>")
	)
	(segment
		(start 363.526832 -217.554048)
		(end 363.527594 -217.554556)
		(width 0.0889)
		(layer "In11.Cu")
		(net "P5E_CPU0_PE1_RX_DN<3>")
	)
	(segment
		(start 363.202474 -210.409536)
		(end 363.202728 -210.40979)
		(width 0.14732)
		(layer "In11.Cu")
		(net "P5E_CPU0_PE1_RX_DN<3>")
	)
	(segment
		(start 363.24413 -217.064336)
		(end 363.24413 -217.071956)
		(width 0.0889)
		(layer "In11.Cu")
		(net "P5E_CPU0_PE1_RX_DN<3>")
	)
	(segment
		(start 363.202728 -212.916008)
		(end 363.244638 -212.957918)
		(width 0.0889)
		(layer "In11.Cu")
		(net "P5E_CPU0_PE1_RX_DN<3>")
	)
	(segment
		(start 363.244638 -212.957918)
		(end 363.244638 -213.93023)
		(width 0.0889)
		(layer "In11.Cu")
		(net "P5E_CPU0_PE1_RX_DN<3>")
	)
	(segment
		(start 425.30141 -18.843752)
		(end 425.250356 -18.947384)
		(width 0.14732)
		(layer "In11.Cu")
		(net "P5E_CPU0_PE1_RX_DN<3>")
	)
	(segment
		(start 414.1343 -78.005686)
		(end 365.67491 -163.606734)
		(width 0.14732)
		(layer "In11.Cu")
		(net "P5E_CPU0_PE1_RX_DN<3>")
	)
	(segment
		(start 363.244638 -213.93023)
		(end 363.24413 -215.120728)
		(width 0.0889)
		(layer "In11.Cu")
		(net "P5E_CPU0_PE1_RX_DN<3>")
	)
	(segment
		(start 363.065568 -219.0115)
		(end 363.056678 -219.01658)
		(width 0.0889)
		(layer "In11.Cu")
		(net "P5E_CPU0_PE1_RX_DN<3>")
	)
	(segment
		(start 362.774484 -219.490544)
		(end 362.774484 -219.521532)
		(width 0.0889)
		(layer "In11.Cu")
		(net "P5E_CPU0_PE1_RX_DN<3>")
	)
	(segment
		(start 424.644312 -6.713474)
		(end 424.938952 -7.008114)
		(width 0.14732)
		(layer "In11.Cu")
		(net "P5E_CPU0_PE1_RX_DN<3>")
	)
	(segment
		(start 425.250356 -18.947384)
		(end 422.054528 -28.133294)
		(width 0.14732)
		(layer "In11.Cu")
		(net "P5E_CPU0_PE1_RX_DN<3>")
	)
	(segment
		(start 363.524038 -218.204542)
		(end 363.520736 -218.20632)
		(width 0.0889)
		(layer "In11.Cu")
		(net "P5E_CPU0_PE1_RX_DN<3>")
	)
	(segment
		(start 424.938952 -7.008114)
		(end 424.938952 -12.560808)
		(width 0.14732)
		(layer "In11.Cu")
		(net "P5E_CPU0_PE1_RX_DN<3>")
	)
	(segment
		(start 363.941614 -221.587568)
		(end 363.965744 -221.676722)
		(width 0.0889)
		(layer "In11.Cu")
		(net "P5E_CPU0_PE1_RX_DN<3>")
	)
	(segment
		(start 363.065568 -215.755982)
		(end 363.056678 -215.761062)
		(width 0.0889)
		(layer "In11.Cu")
		(net "P5E_CPU0_PE1_RX_DN<3>")
	)
	(segment
		(start 363.535722 -218.197684)
		(end 363.528356 -218.202002)
		(width 0.0889)
		(layer "In11.Cu")
		(net "P5E_CPU0_PE1_RX_DN<3>")
	)
	(segment
		(start 363.52607 -218.203272)
		(end 363.524038 -218.204542)
		(width 0.0889)
		(layer "In11.Cu")
		(net "P5E_CPU0_PE1_RX_DN<3>")
	)
	(segment
		(start 363.24413 -215.120728)
		(end 363.24413 -215.436704)
		(width 0.0889)
		(layer "In11.Cu")
		(net "P5E_CPU0_PE1_RX_DN<3>")
	)
	(segment
		(start 363.526832 -220.809566)
		(end 363.535722 -220.814646)
		(width 0.0889)
		(layer "In11.Cu")
		(net "P5E_CPU0_PE1_RX_DN<3>")
	)
	(segment
		(start 363.202728 -212.89391)
		(end 363.202728 -212.916008)
		(width 0.0889)
		(layer "In11.Cu")
		(net "P5E_CPU0_PE1_RX_DN<3>")
	)
	(arc
		(start 363.24413 -220.327474)
		(mid 363.321759 -220.605887)
		(end 363.526832 -220.809566)
		(width 0.0889)
		(layer "In11.Cu")
		(net "P5E_CPU0_PE1_RX_DN<3>")
	)
	(arc
		(start 362.77423 -216.260426)
		(mid 362.852341 -216.537375)
		(end 363.056678 -216.739978)
		(width 0.0889)
		(layer "In11.Cu")
		(net "P5E_CPU0_PE1_RX_DN<3>")
	)
	(arc
		(start 363.535722 -220.814646)
		(mid 363.666636 -220.951006)
		(end 363.714284 -221.133924)
		(width 0.0889)
		(layer "In11.Cu")
		(net "P5E_CPU0_PE1_RX_DN<3>")
	)
	(arc
		(start 363.056678 -215.761062)
		(mid 362.852343 -215.963667)
		(end 362.77423 -216.240614)
		(width 0.0889)
		(layer "In11.Cu")
		(net "P5E_CPU0_PE1_RX_DN<3>")
	)
	(arc
		(start 363.065568 -220.000576)
		(mid 363.196482 -220.136936)
		(end 363.24413 -220.319854)
		(width 0.0889)
		(layer "In11.Cu")
		(net "P5E_CPU0_PE1_RX_DN<3>")
	)
	(arc
		(start 363.24413 -215.436704)
		(mid 363.196451 -215.619604)
		(end 363.065568 -215.755982)
		(width 0.0889)
		(layer "In11.Cu")
		(net "P5E_CPU0_PE1_RX_DN<3>")
	)
	(arc
		(start 363.520736 -218.20632)
		(mid 363.318149 -218.412671)
		(end 363.24413 -218.692222)
		(width 0.0889)
		(layer "In11.Cu")
		(net "P5E_CPU0_PE1_RX_DN<3>")
	)
	(arc
		(start 363.535722 -217.559128)
		(mid 363.714198 -217.878406)
		(end 363.535722 -218.197684)
		(width 0.0889)
		(layer "In11.Cu")
		(net "P5E_CPU0_PE1_RX_DN<3>")
	)
	(arc
		(start 363.92485 -221.574614)
		(mid 363.93317 -221.581171)
		(end 363.941614 -221.587568)
		(width 0.0889)
		(layer "In11.Cu")
		(net "P5E_CPU0_PE1_RX_DN<3>")
	)
	(arc
		(start 363.24413 -217.071956)
		(mid 363.321759 -217.350369)
		(end 363.526832 -217.554048)
		(width 0.0889)
		(layer "In11.Cu")
		(net "P5E_CPU0_PE1_RX_DN<3>")
	)
	(arc
		(start 362.774484 -219.521532)
		(mid 362.853854 -219.795266)
		(end 363.056678 -219.995496)
		(width 0.0889)
		(layer "In11.Cu")
		(net "P5E_CPU0_PE1_RX_DN<3>")
	)
	(arc
		(start 363.24413 -218.692222)
		(mid 363.196451 -218.875122)
		(end 363.065568 -219.0115)
		(width 0.0889)
		(layer "In11.Cu")
		(net "P5E_CPU0_PE1_RX_DN<3>")
	)
	(arc
		(start 363.056678 -219.01658)
		(mid 362.853855 -219.216811)
		(end 362.774484 -219.490544)
		(width 0.0889)
		(layer "In11.Cu")
		(net "P5E_CPU0_PE1_RX_DN<3>")
	)
	(arc
		(start 363.065568 -216.745058)
		(mid 363.196482 -216.881418)
		(end 363.24413 -217.064336)
		(width 0.0889)
		(layer "In11.Cu")
		(net "P5E_CPU0_PE1_RX_DN<3>")
	)
	(arc
		(start 363.714284 -221.149418)
		(mid 363.772837 -221.385148)
		(end 363.92485 -221.574614)
		(width 0.0889)
		(layer "In11.Cu")
		(net "P5E_CPU0_PE1_RX_DN<3>")
	)
	(segment
		(start 365.21898 -221.669864)
		(end 365.219234 -221.133924)
		(width 0.13208)
		(layer "F.Cu")
		(net "P5E_CPU0_PE1_RX_DN<2>")
	)
	(segment
		(start 426.566838 -7.784592)
		(end 426.750226 -7.601204)
		(width 0.13208)
		(layer "F.Cu")
		(net "P5E_CPU0_PE1_RX_DN<2>")
	)
	(segment
		(start 426.566838 -8.320024)
		(end 426.566838 -7.784592)
		(width 0.13208)
		(layer "F.Cu")
		(net "P5E_CPU0_PE1_RX_DN<2>")
	)
	(segment
		(start 426.750226 -7.601204)
		(end 426.750226 -5.252974)
		(width 0.13208)
		(layer "F.Cu")
		(net "P5E_CPU0_PE1_RX_DN<2>")
	)
	(segment
		(start 426.750226 -5.252974)
		(end 426.448982 -4.95173)
		(width 0.13208)
		(layer "F.Cu")
		(net "P5E_CPU0_PE1_RX_DN<2>")
	)
	(segment
		(start 364.142274 -210.347814)
		(end 363.022134 -184.119012)
		(width 0.14732)
		(layer "In11.Cu")
		(net "P5E_CPU0_PE1_RX_DN<2>")
	)
	(segment
		(start 364.184438 -213.929214)
		(end 364.184438 -212.957918)
		(width 0.0889)
		(layer "In11.Cu")
		(net "P5E_CPU0_PE1_RX_DN<2>")
	)
	(segment
		(start 363.996478 -219.01658)
		(end 364.005368 -219.0115)
		(width 0.0889)
		(layer "In11.Cu")
		(net "P5E_CPU0_PE1_RX_DN<2>")
	)
	(segment
		(start 364.460536 -218.20632)
		(end 364.46587 -218.203272)
		(width 0.0889)
		(layer "In11.Cu")
		(net "P5E_CPU0_PE1_RX_DN<2>")
	)
	(segment
		(start 364.184438 -212.957918)
		(end 364.142528 -212.916008)
		(width 0.0889)
		(layer "In11.Cu")
		(net "P5E_CPU0_PE1_RX_DN<2>")
	)
	(segment
		(start 363.022134 -184.119012)
		(end 366.577118 -163.95319)
		(width 0.14732)
		(layer "In11.Cu")
		(net "P5E_CPU0_PE1_RX_DN<2>")
	)
	(segment
		(start 428.057818 -17.823942)
		(end 426.743622 -12.360402)
		(width 0.14732)
		(layer "In11.Cu")
		(net "P5E_CPU0_PE1_RX_DN<2>")
	)
	(segment
		(start 366.577118 -163.95319)
		(end 415.019998 -78.380336)
		(width 0.14732)
		(layer "In11.Cu")
		(net "P5E_CPU0_PE1_RX_DN<2>")
	)
	(segment
		(start 415.019998 -78.380336)
		(end 423.15257 -28.383992)
		(width 0.14732)
		(layer "In11.Cu")
		(net "P5E_CPU0_PE1_RX_DN<2>")
	)
	(segment
		(start 364.18393 -215.436704)
		(end 364.18393 -215.120728)
		(width 0.0889)
		(layer "In11.Cu")
		(net "P5E_CPU0_PE1_RX_DN<2>")
	)
	(segment
		(start 363.714284 -216.260426)
		(end 363.714284 -216.235026)
		(width 0.0889)
		(layer "In11.Cu")
		(net "P5E_CPU0_PE1_RX_DN<2>")
	)
	(segment
		(start 364.142528 -212.89391)
		(end 364.142528 -210.348068)
		(width 0.14732)
		(layer "In11.Cu")
		(net "P5E_CPU0_PE1_RX_DN<2>")
	)
	(segment
		(start 426.743622 -5.24637)
		(end 426.448982 -4.95173)
		(width 0.14732)
		(layer "In11.Cu")
		(net "P5E_CPU0_PE1_RX_DN<2>")
	)
	(segment
		(start 365.219234 -221.133924)
		(end 365.06277 -220.862906)
		(width 0.0889)
		(layer "In11.Cu")
		(net "P5E_CPU0_PE1_RX_DN<2>")
	)
	(segment
		(start 363.714284 -219.515944)
		(end 363.714284 -219.490544)
		(width 0.0889)
		(layer "In11.Cu")
		(net "P5E_CPU0_PE1_RX_DN<2>")
	)
	(segment
		(start 364.18393 -215.120728)
		(end 364.184438 -213.929214)
		(width 0.0889)
		(layer "In11.Cu")
		(net "P5E_CPU0_PE1_RX_DN<2>")
	)
	(segment
		(start 364.142528 -210.348068)
		(end 364.142274 -210.347814)
		(width 0.14732)
		(layer "In11.Cu")
		(net "P5E_CPU0_PE1_RX_DN<2>")
	)
	(segment
		(start 364.475522 -217.559128)
		(end 364.466632 -217.554048)
		(width 0.0889)
		(layer "In11.Cu")
		(net "P5E_CPU0_PE1_RX_DN<2>")
	)
	(segment
		(start 364.468156 -218.202002)
		(end 364.475522 -218.197684)
		(width 0.0889)
		(layer "In11.Cu")
		(net "P5E_CPU0_PE1_RX_DN<2>")
	)
	(segment
		(start 364.46587 -218.203272)
		(end 364.466632 -218.202764)
		(width 0.0889)
		(layer "In11.Cu")
		(net "P5E_CPU0_PE1_RX_DN<2>")
	)
	(segment
		(start 364.466632 -218.202764)
		(end 364.468156 -218.202002)
		(width 0.0889)
		(layer "In11.Cu")
		(net "P5E_CPU0_PE1_RX_DN<2>")
	)
	(segment
		(start 364.18393 -217.07856)
		(end 364.18393 -217.0557)
		(width 0.0889)
		(layer "In11.Cu")
		(net "P5E_CPU0_PE1_RX_DN<2>")
	)
	(segment
		(start 428.568866 -19.762216)
		(end 428.74438 -19.339052)
		(width 0.14732)
		(layer "In11.Cu")
		(net "P5E_CPU0_PE1_RX_DN<2>")
	)
	(segment
		(start 364.142528 -212.916008)
		(end 364.142528 -212.89391)
		(width 0.0889)
		(layer "In11.Cu")
		(net "P5E_CPU0_PE1_RX_DN<2>")
	)
	(segment
		(start 364.476792 -220.815662)
		(end 364.466378 -220.809566)
		(width 0.0889)
		(layer "In11.Cu")
		(net "P5E_CPU0_PE1_RX_DN<2>")
	)
	(segment
		(start 428.74438 -18.851626)
		(end 428.057818 -17.823942)
		(width 0.14732)
		(layer "In11.Cu")
		(net "P5E_CPU0_PE1_RX_DN<2>")
	)
	(segment
		(start 365.06277 -220.862906)
		(end 364.973616 -220.83903)
		(width 0.0889)
		(layer "In11.Cu")
		(net "P5E_CPU0_PE1_RX_DN<2>")
	)
	(segment
		(start 423.15257 -28.383992)
		(end 423.902886 -26.64841)
		(width 0.14732)
		(layer "In11.Cu")
		(net "P5E_CPU0_PE1_RX_DN<2>")
	)
	(segment
		(start 423.902886 -26.64841)
		(end 428.568866 -19.762216)
		(width 0.14732)
		(layer "In11.Cu")
		(net "P5E_CPU0_PE1_RX_DN<2>")
	)
	(segment
		(start 364.18393 -220.338396)
		(end 364.18393 -220.311218)
		(width 0.0889)
		(layer "In11.Cu")
		(net "P5E_CPU0_PE1_RX_DN<2>")
	)
	(segment
		(start 426.743622 -12.360402)
		(end 426.743622 -5.24637)
		(width 0.14732)
		(layer "In11.Cu")
		(net "P5E_CPU0_PE1_RX_DN<2>")
	)
	(segment
		(start 363.996478 -215.761062)
		(end 364.005368 -215.755982)
		(width 0.0889)
		(layer "In11.Cu")
		(net "P5E_CPU0_PE1_RX_DN<2>")
	)
	(segment
		(start 428.74438 -19.339052)
		(end 428.74438 -18.851626)
		(width 0.14732)
		(layer "In11.Cu")
		(net "P5E_CPU0_PE1_RX_DN<2>")
	)
	(arc
		(start 364.95355 -220.847158)
		(mid 364.711696 -220.884177)
		(end 364.476792 -220.815662)
		(width 0.0889)
		(layer "In11.Cu")
		(net "P5E_CPU0_PE1_RX_DN<2>")
	)
	(arc
		(start 364.18393 -217.0557)
		(mid 364.13166 -216.873335)
		(end 363.996732 -216.739978)
		(width 0.0889)
		(layer "In11.Cu")
		(net "P5E_CPU0_PE1_RX_DN<2>")
	)
	(arc
		(start 364.475522 -218.197684)
		(mid 364.654119 -217.878406)
		(end 364.475522 -217.559128)
		(width 0.0889)
		(layer "In11.Cu")
		(net "P5E_CPU0_PE1_RX_DN<2>")
	)
	(arc
		(start 364.005368 -219.0115)
		(mid 364.136282 -218.87514)
		(end 364.18393 -218.692222)
		(width 0.0889)
		(layer "In11.Cu")
		(net "P5E_CPU0_PE1_RX_DN<2>")
	)
	(arc
		(start 364.466632 -217.554048)
		(mid 364.263151 -217.353244)
		(end 364.18393 -217.07856)
		(width 0.0889)
		(layer "In11.Cu")
		(net "P5E_CPU0_PE1_RX_DN<2>")
	)
	(arc
		(start 364.466378 -220.809566)
		(mid 364.264092 -220.610585)
		(end 364.18393 -220.338396)
		(width 0.0889)
		(layer "In11.Cu")
		(net "P5E_CPU0_PE1_RX_DN<2>")
	)
	(arc
		(start 364.973616 -220.83903)
		(mid 364.963622 -220.843189)
		(end 364.95355 -220.847158)
		(width 0.0889)
		(layer "In11.Cu")
		(net "P5E_CPU0_PE1_RX_DN<2>")
	)
	(arc
		(start 363.996732 -216.739978)
		(mid 363.792397 -216.537373)
		(end 363.714284 -216.260426)
		(width 0.0889)
		(layer "In11.Cu")
		(net "P5E_CPU0_PE1_RX_DN<2>")
	)
	(arc
		(start 363.714284 -219.490544)
		(mid 363.793654 -219.21681)
		(end 363.996478 -219.01658)
		(width 0.0889)
		(layer "In11.Cu")
		(net "P5E_CPU0_PE1_RX_DN<2>")
	)
	(arc
		(start 364.18393 -218.692222)
		(mid 364.257921 -218.412656)
		(end 364.460536 -218.20632)
		(width 0.0889)
		(layer "In11.Cu")
		(net "P5E_CPU0_PE1_RX_DN<2>")
	)
	(arc
		(start 363.996732 -219.995496)
		(mid 363.792397 -219.792891)
		(end 363.714284 -219.515944)
		(width 0.0889)
		(layer "In11.Cu")
		(net "P5E_CPU0_PE1_RX_DN<2>")
	)
	(arc
		(start 364.18393 -220.311218)
		(mid 364.13166 -220.128853)
		(end 363.996732 -219.995496)
		(width 0.0889)
		(layer "In11.Cu")
		(net "P5E_CPU0_PE1_RX_DN<2>")
	)
	(arc
		(start 364.005368 -215.755982)
		(mid 364.136282 -215.619622)
		(end 364.18393 -215.436704)
		(width 0.0889)
		(layer "In11.Cu")
		(net "P5E_CPU0_PE1_RX_DN<2>")
	)
	(arc
		(start 363.714284 -216.235026)
		(mid 363.793654 -215.961292)
		(end 363.996478 -215.761062)
		(width 0.0889)
		(layer "In11.Cu")
		(net "P5E_CPU0_PE1_RX_DN<2>")
	)
	(segment
		(start 365.689134 -222.48368)
		(end 365.68888 -221.94774)
		(width 0.13208)
		(layer "F.Cu")
		(net "P5E_CPU0_PE1_RX_DN<1>")
	)
	(segment
		(start 428.366936 -8.320024)
		(end 428.366936 -7.776972)
		(width 0.13208)
		(layer "F.Cu")
		(net "P5E_CPU0_PE1_RX_DN<1>")
	)
	(segment
		(start 428.546514 -7.597394)
		(end 428.546514 -7.015734)
		(width 0.13208)
		(layer "F.Cu")
		(net "P5E_CPU0_PE1_RX_DN<1>")
	)
	(segment
		(start 428.366936 -7.776972)
		(end 428.546514 -7.597394)
		(width 0.13208)
		(layer "F.Cu")
		(net "P5E_CPU0_PE1_RX_DN<1>")
	)
	(segment
		(start 428.546514 -7.015734)
		(end 428.244254 -6.713474)
		(width 0.13208)
		(layer "F.Cu")
		(net "P5E_CPU0_PE1_RX_DN<1>")
	)
	(segment
		(start 424.192954 -28.515818)
		(end 416.05581 -78.517242)
		(width 0.14732)
		(layer "In11.Cu")
		(net "P5E_CPU0_PE1_RX_DN<1>")
	)
	(segment
		(start 365.40567 -218.203272)
		(end 365.403638 -218.204542)
		(width 0.0889)
		(layer "In11.Cu")
		(net "P5E_CPU0_PE1_RX_DN<1>")
	)
	(segment
		(start 365.406432 -218.202764)
		(end 365.40567 -218.203272)
		(width 0.0889)
		(layer "In11.Cu")
		(net "P5E_CPU0_PE1_RX_DN<1>")
	)
	(segment
		(start 431.5333 -17.786604)
		(end 430.73701 -18.977864)
		(width 0.14732)
		(layer "In11.Cu")
		(net "P5E_CPU0_PE1_RX_DN<1>")
	)
	(segment
		(start 428.244254 -6.713474)
		(end 428.538894 -7.008114)
		(width 0.14732)
		(layer "In11.Cu")
		(net "P5E_CPU0_PE1_RX_DN<1>")
	)
	(segment
		(start 364.937294 -219.996004)
		(end 364.945168 -220.000576)
		(width 0.0889)
		(layer "In11.Cu")
		(net "P5E_CPU0_PE1_RX_DN<1>")
	)
	(segment
		(start 364.654084 -216.235026)
		(end 364.654084 -216.266014)
		(width 0.0889)
		(layer "In11.Cu")
		(net "P5E_CPU0_PE1_RX_DN<1>")
	)
	(segment
		(start 365.593884 -221.133924)
		(end 365.593884 -221.149418)
		(width 0.0889)
		(layer "In11.Cu")
		(net "P5E_CPU0_PE1_RX_DN<1>")
	)
	(segment
		(start 364.936278 -219.995496)
		(end 364.937294 -219.996004)
		(width 0.0889)
		(layer "In11.Cu")
		(net "P5E_CPU0_PE1_RX_DN<1>")
	)
	(segment
		(start 365.082074 -212.926168)
		(end 365.123984 -212.968078)
		(width 0.0889)
		(layer "In11.Cu")
		(net "P5E_CPU0_PE1_RX_DN<1>")
	)
	(segment
		(start 365.12373 -217.064336)
		(end 365.12373 -217.071956)
		(width 0.0889)
		(layer "In11.Cu")
		(net "P5E_CPU0_PE1_RX_DN<1>")
	)
	(segment
		(start 365.845344 -221.676722)
		(end 365.68888 -221.94774)
		(width 0.0889)
		(layer "In11.Cu")
		(net "P5E_CPU0_PE1_RX_DN<1>")
	)
	(segment
		(start 364.936278 -216.739978)
		(end 364.937294 -216.740486)
		(width 0.0889)
		(layer "In11.Cu")
		(net "P5E_CPU0_PE1_RX_DN<1>")
	)
	(segment
		(start 365.123984 -213.930484)
		(end 365.12373 -215.120728)
		(width 0.0889)
		(layer "In11.Cu")
		(net "P5E_CPU0_PE1_RX_DN<1>")
	)
	(segment
		(start 424.837606 -27.192732)
		(end 424.192954 -28.515818)
		(width 0.14732)
		(layer "In11.Cu")
		(net "P5E_CPU0_PE1_RX_DN<1>")
	)
	(segment
		(start 428.538894 -12.430506)
		(end 431.5333 -17.122902)
		(width 0.14732)
		(layer "In11.Cu")
		(net "P5E_CPU0_PE1_RX_DN<1>")
	)
	(segment
		(start 365.821214 -221.587568)
		(end 365.845344 -221.676722)
		(width 0.0889)
		(layer "In11.Cu")
		(net "P5E_CPU0_PE1_RX_DN<1>")
	)
	(segment
		(start 365.406432 -220.809566)
		(end 365.415322 -220.814646)
		(width 0.0889)
		(layer "In11.Cu")
		(net "P5E_CPU0_PE1_RX_DN<1>")
	)
	(segment
		(start 430.73701 -18.977864)
		(end 424.837606 -27.192732)
		(width 0.14732)
		(layer "In11.Cu")
		(net "P5E_CPU0_PE1_RX_DN<1>")
	)
	(segment
		(start 365.082074 -212.10143)
		(end 365.082074 -212.90407)
		(width 0.14732)
		(layer "In11.Cu")
		(net "P5E_CPU0_PE1_RX_DN<1>")
	)
	(segment
		(start 428.538894 -7.008114)
		(end 428.538894 -12.430506)
		(width 0.14732)
		(layer "In11.Cu")
		(net "P5E_CPU0_PE1_RX_DN<1>")
	)
	(segment
		(start 367.75644 -163.831524)
		(end 366.834928 -185.6994)
		(width 0.14732)
		(layer "In11.Cu")
		(net "P5E_CPU0_PE1_RX_DN<1>")
	)
	(segment
		(start 365.403638 -218.204542)
		(end 365.400336 -218.20632)
		(width 0.0889)
		(layer "In11.Cu")
		(net "P5E_CPU0_PE1_RX_DN<1>")
	)
	(segment
		(start 365.082074 -212.90407)
		(end 365.082074 -212.926168)
		(width 0.0889)
		(layer "In11.Cu")
		(net "P5E_CPU0_PE1_RX_DN<1>")
	)
	(segment
		(start 365.407956 -218.202002)
		(end 365.406432 -218.202764)
		(width 0.0889)
		(layer "In11.Cu")
		(net "P5E_CPU0_PE1_RX_DN<1>")
	)
	(segment
		(start 365.415322 -218.197684)
		(end 365.407956 -218.202002)
		(width 0.0889)
		(layer "In11.Cu")
		(net "P5E_CPU0_PE1_RX_DN<1>")
	)
	(segment
		(start 365.407194 -217.554556)
		(end 365.415322 -217.559128)
		(width 0.0889)
		(layer "In11.Cu")
		(net "P5E_CPU0_PE1_RX_DN<1>")
	)
	(segment
		(start 365.406432 -217.554048)
		(end 365.407194 -217.554556)
		(width 0.0889)
		(layer "In11.Cu")
		(net "P5E_CPU0_PE1_RX_DN<1>")
	)
	(segment
		(start 364.945168 -219.0115)
		(end 364.936278 -219.01658)
		(width 0.0889)
		(layer "In11.Cu")
		(net "P5E_CPU0_PE1_RX_DN<1>")
	)
	(segment
		(start 365.12373 -215.120728)
		(end 365.12373 -215.436704)
		(width 0.0889)
		(layer "In11.Cu")
		(net "P5E_CPU0_PE1_RX_DN<1>")
	)
	(segment
		(start 364.945168 -215.755982)
		(end 364.936278 -215.761062)
		(width 0.0889)
		(layer "In11.Cu")
		(net "P5E_CPU0_PE1_RX_DN<1>")
	)
	(segment
		(start 366.834928 -185.6994)
		(end 365.08182 -212.101176)
		(width 0.14732)
		(layer "In11.Cu")
		(net "P5E_CPU0_PE1_RX_DN<1>")
	)
	(segment
		(start 364.937294 -216.740486)
		(end 364.945168 -216.745058)
		(width 0.0889)
		(layer "In11.Cu")
		(net "P5E_CPU0_PE1_RX_DN<1>")
	)
	(segment
		(start 365.12373 -220.319854)
		(end 365.12373 -220.327474)
		(width 0.0889)
		(layer "In11.Cu")
		(net "P5E_CPU0_PE1_RX_DN<1>")
	)
	(segment
		(start 364.654084 -219.490544)
		(end 364.654084 -219.521532)
		(width 0.0889)
		(layer "In11.Cu")
		(net "P5E_CPU0_PE1_RX_DN<1>")
	)
	(segment
		(start 431.5333 -17.122902)
		(end 431.5333 -17.786604)
		(width 0.14732)
		(layer "In11.Cu")
		(net "P5E_CPU0_PE1_RX_DN<1>")
	)
	(segment
		(start 365.08182 -212.101176)
		(end 365.082074 -212.10143)
		(width 0.14732)
		(layer "In11.Cu")
		(net "P5E_CPU0_PE1_RX_DN<1>")
	)
	(segment
		(start 365.123984 -212.968078)
		(end 365.123984 -213.930484)
		(width 0.0889)
		(layer "In11.Cu")
		(net "P5E_CPU0_PE1_RX_DN<1>")
	)
	(segment
		(start 416.05581 -78.517242)
		(end 367.75644 -163.831524)
		(width 0.14732)
		(layer "In11.Cu")
		(net "P5E_CPU0_PE1_RX_DN<1>")
	)
	(arc
		(start 365.80445 -221.574614)
		(mid 365.81277 -221.581171)
		(end 365.821214 -221.587568)
		(width 0.0889)
		(layer "In11.Cu")
		(net "P5E_CPU0_PE1_RX_DN<1>")
	)
	(arc
		(start 365.12373 -218.692222)
		(mid 365.076051 -218.875122)
		(end 364.945168 -219.0115)
		(width 0.0889)
		(layer "In11.Cu")
		(net "P5E_CPU0_PE1_RX_DN<1>")
	)
	(arc
		(start 365.415322 -217.559128)
		(mid 365.593798 -217.878406)
		(end 365.415322 -218.197684)
		(width 0.0889)
		(layer "In11.Cu")
		(net "P5E_CPU0_PE1_RX_DN<1>")
	)
	(arc
		(start 364.945168 -220.000576)
		(mid 365.076082 -220.136936)
		(end 365.12373 -220.319854)
		(width 0.0889)
		(layer "In11.Cu")
		(net "P5E_CPU0_PE1_RX_DN<1>")
	)
	(arc
		(start 365.400336 -218.20632)
		(mid 365.197749 -218.412671)
		(end 365.12373 -218.692222)
		(width 0.0889)
		(layer "In11.Cu")
		(net "P5E_CPU0_PE1_RX_DN<1>")
	)
	(arc
		(start 364.936278 -219.01658)
		(mid 364.733455 -219.216811)
		(end 364.654084 -219.490544)
		(width 0.0889)
		(layer "In11.Cu")
		(net "P5E_CPU0_PE1_RX_DN<1>")
	)
	(arc
		(start 364.654084 -216.266014)
		(mid 364.733454 -216.539748)
		(end 364.936278 -216.739978)
		(width 0.0889)
		(layer "In11.Cu")
		(net "P5E_CPU0_PE1_RX_DN<1>")
	)
	(arc
		(start 364.945168 -216.745058)
		(mid 365.076082 -216.881418)
		(end 365.12373 -217.064336)
		(width 0.0889)
		(layer "In11.Cu")
		(net "P5E_CPU0_PE1_RX_DN<1>")
	)
	(arc
		(start 365.12373 -217.071956)
		(mid 365.201359 -217.350369)
		(end 365.406432 -217.554048)
		(width 0.0889)
		(layer "In11.Cu")
		(net "P5E_CPU0_PE1_RX_DN<1>")
	)
	(arc
		(start 365.12373 -215.436704)
		(mid 365.076051 -215.619604)
		(end 364.945168 -215.755982)
		(width 0.0889)
		(layer "In11.Cu")
		(net "P5E_CPU0_PE1_RX_DN<1>")
	)
	(arc
		(start 364.654084 -219.521532)
		(mid 364.733454 -219.795266)
		(end 364.936278 -219.995496)
		(width 0.0889)
		(layer "In11.Cu")
		(net "P5E_CPU0_PE1_RX_DN<1>")
	)
	(arc
		(start 365.593884 -221.149418)
		(mid 365.652437 -221.385148)
		(end 365.80445 -221.574614)
		(width 0.0889)
		(layer "In11.Cu")
		(net "P5E_CPU0_PE1_RX_DN<1>")
	)
	(arc
		(start 365.12373 -220.327474)
		(mid 365.201359 -220.605887)
		(end 365.406432 -220.809566)
		(width 0.0889)
		(layer "In11.Cu")
		(net "P5E_CPU0_PE1_RX_DN<1>")
	)
	(arc
		(start 365.415322 -220.814646)
		(mid 365.546236 -220.951006)
		(end 365.593884 -221.133924)
		(width 0.0889)
		(layer "In11.Cu")
		(net "P5E_CPU0_PE1_RX_DN<1>")
	)
	(arc
		(start 364.936278 -215.761062)
		(mid 364.733455 -215.961293)
		(end 364.654084 -216.235026)
		(width 0.0889)
		(layer "In11.Cu")
		(net "P5E_CPU0_PE1_RX_DN<1>")
	)
	(segment
		(start 393.646914 -8.320024)
		(end 393.646914 -7.776972)
		(width 0.13208)
		(layer "F.Cu")
		(net "P5E_CPU0_PE1_RX_DN<15>")
	)
	(segment
		(start 393.826492 -7.597394)
		(end 393.826492 -7.015734)
		(width 0.13208)
		(layer "F.Cu")
		(net "P5E_CPU0_PE1_RX_DN<15>")
	)
	(segment
		(start 393.646914 -7.776972)
		(end 393.826492 -7.597394)
		(width 0.13208)
		(layer "F.Cu")
		(net "P5E_CPU0_PE1_RX_DN<15>")
	)
	(segment
		(start 352.531934 -222.48368)
		(end 352.53168 -221.94774)
		(width 0.13208)
		(layer "F.Cu")
		(net "P5E_CPU0_PE1_RX_DN<15>")
	)
	(segment
		(start 393.826492 -7.015734)
		(end 393.524232 -6.713474)
		(width 0.13208)
		(layer "F.Cu")
		(net "P5E_CPU0_PE1_RX_DN<15>")
	)
	(segment
		(start 351.787968 -220.000576)
		(end 351.780094 -219.996004)
		(width 0.0889)
		(layer "In11.Cu")
		(net "P5E_CPU0_PE1_RX_DN<15>")
	)
	(segment
		(start 350.98482 -212.926168)
		(end 350.98482 -212.90407)
		(width 0.0889)
		(layer "In11.Cu")
		(net "P5E_CPU0_PE1_RX_DN<15>")
	)
	(segment
		(start 351.779078 -217.388694)
		(end 351.787968 -217.383614)
		(width 0.0889)
		(layer "In11.Cu")
		(net "P5E_CPU0_PE1_RX_DN<15>")
	)
	(segment
		(start 351.49663 -214.62238)
		(end 351.49663 -214.460328)
		(width 0.0889)
		(layer "In11.Cu")
		(net "P5E_CPU0_PE1_RX_DN<15>")
	)
	(segment
		(start 350.98482 -212.90407)
		(end 350.98482 -212.602826)
		(width 0.14732)
		(layer "In11.Cu")
		(net "P5E_CPU0_PE1_RX_DN<15>")
	)
	(segment
		(start 393.818872 -7.008114)
		(end 393.524232 -6.713474)
		(width 0.14732)
		(layer "In11.Cu")
		(net "P5E_CPU0_PE1_RX_DN<15>")
	)
	(segment
		(start 341.967566 -161.769806)
		(end 401.215606 -77.155802)
		(width 0.14732)
		(layer "In11.Cu")
		(net "P5E_CPU0_PE1_RX_DN<15>")
	)
	(segment
		(start 393.818872 -12.443206)
		(end 393.818872 -7.008114)
		(width 0.14732)
		(layer "In11.Cu")
		(net "P5E_CPU0_PE1_RX_DN<15>")
	)
	(segment
		(start 391.37082 -18.940018)
		(end 391.511028 -18.602706)
		(width 0.14732)
		(layer "In11.Cu")
		(net "P5E_CPU0_PE1_RX_DN<15>")
	)
	(segment
		(start 351.780094 -218.368372)
		(end 351.779078 -218.367864)
		(width 0.0889)
		(layer "In11.Cu")
		(net "P5E_CPU0_PE1_RX_DN<15>")
	)
	(segment
		(start 351.02673 -215.436704)
		(end 351.02673 -215.414606)
		(width 0.0889)
		(layer "In11.Cu")
		(net "P5E_CPU0_PE1_RX_DN<15>")
	)
	(segment
		(start 351.308924 -214.946992)
		(end 351.317814 -214.941912)
		(width 0.0889)
		(layer "In11.Cu")
		(net "P5E_CPU0_PE1_RX_DN<15>")
	)
	(segment
		(start 338.739988 -174.95266)
		(end 338.739988 -172.007022)
		(width 0.14732)
		(layer "In11.Cu")
		(net "P5E_CPU0_PE1_RX_DN<15>")
	)
	(segment
		(start 395.355318 -46.101762)
		(end 391.37082 -19.668998)
		(width 0.14732)
		(layer "In11.Cu")
		(net "P5E_CPU0_PE1_RX_DN<15>")
	)
	(segment
		(start 391.37082 -19.668998)
		(end 391.37082 -18.940018)
		(width 0.14732)
		(layer "In11.Cu")
		(net "P5E_CPU0_PE1_RX_DN<15>")
	)
	(segment
		(start 401.215606 -77.155802)
		(end 401.398232 -74.93381)
		(width 0.14732)
		(layer "In11.Cu")
		(net "P5E_CPU0_PE1_RX_DN<15>")
	)
	(segment
		(start 352.53168 -221.94774)
		(end 352.688144 -221.676722)
		(width 0.0889)
		(layer "In11.Cu")
		(net "P5E_CPU0_PE1_RX_DN<15>")
	)
	(segment
		(start 351.309432 -215.926162)
		(end 351.303336 -215.922606)
		(width 0.0889)
		(layer "In11.Cu")
		(net "P5E_CPU0_PE1_RX_DN<15>")
	)
	(segment
		(start 350.98482 -212.602826)
		(end 338.739988 -174.95266)
		(width 0.14732)
		(layer "In11.Cu")
		(net "P5E_CPU0_PE1_RX_DN<15>")
	)
	(segment
		(start 352.436684 -221.149418)
		(end 352.436684 -221.133924)
		(width 0.0889)
		(layer "In11.Cu")
		(net "P5E_CPU0_PE1_RX_DN<15>")
	)
	(segment
		(start 351.779078 -219.01658)
		(end 351.787968 -219.0115)
		(width 0.0889)
		(layer "In11.Cu")
		(net "P5E_CPU0_PE1_RX_DN<15>")
	)
	(segment
		(start 351.496884 -216.266014)
		(end 351.496884 -216.25052)
		(width 0.0889)
		(layer "In11.Cu")
		(net "P5E_CPU0_PE1_RX_DN<15>")
	)
	(segment
		(start 352.688144 -221.676722)
		(end 352.664014 -221.587568)
		(width 0.0889)
		(layer "In11.Cu")
		(net "P5E_CPU0_PE1_RX_DN<15>")
	)
	(segment
		(start 351.02673 -213.787228)
		(end 351.02673 -212.968078)
		(width 0.0889)
		(layer "In11.Cu")
		(net "P5E_CPU0_PE1_RX_DN<15>")
	)
	(segment
		(start 352.258122 -220.814646)
		(end 352.249232 -220.809566)
		(width 0.0889)
		(layer "In11.Cu")
		(net "P5E_CPU0_PE1_RX_DN<15>")
	)
	(segment
		(start 351.496884 -219.521532)
		(end 351.496884 -219.490544)
		(width 0.0889)
		(layer "In11.Cu")
		(net "P5E_CPU0_PE1_RX_DN<15>")
	)
	(segment
		(start 351.318322 -215.931242)
		(end 351.309432 -215.926162)
		(width 0.0889)
		(layer "In11.Cu")
		(net "P5E_CPU0_PE1_RX_DN<15>")
	)
	(segment
		(start 338.739988 -172.007022)
		(end 341.967566 -161.769806)
		(width 0.14732)
		(layer "In11.Cu")
		(net "P5E_CPU0_PE1_RX_DN<15>")
	)
	(segment
		(start 351.496884 -217.8939)
		(end 351.496884 -217.856308)
		(width 0.0889)
		(layer "In11.Cu")
		(net "P5E_CPU0_PE1_RX_DN<15>")
	)
	(segment
		(start 351.787968 -216.745058)
		(end 351.780094 -216.740486)
		(width 0.0889)
		(layer "In11.Cu")
		(net "P5E_CPU0_PE1_RX_DN<15>")
	)
	(segment
		(start 391.511028 -18.602706)
		(end 392.186922 -17.591278)
		(width 0.14732)
		(layer "In11.Cu")
		(net "P5E_CPU0_PE1_RX_DN<15>")
	)
	(segment
		(start 351.96653 -220.327474)
		(end 351.96653 -220.319854)
		(width 0.0889)
		(layer "In11.Cu")
		(net "P5E_CPU0_PE1_RX_DN<15>")
	)
	(segment
		(start 351.787968 -218.372944)
		(end 351.780094 -218.368372)
		(width 0.0889)
		(layer "In11.Cu")
		(net "P5E_CPU0_PE1_RX_DN<15>")
	)
	(segment
		(start 351.780094 -216.740486)
		(end 351.779078 -216.739978)
		(width 0.0889)
		(layer "In11.Cu")
		(net "P5E_CPU0_PE1_RX_DN<15>")
	)
	(segment
		(start 351.02673 -212.968078)
		(end 350.98482 -212.926168)
		(width 0.0889)
		(layer "In11.Cu")
		(net "P5E_CPU0_PE1_RX_DN<15>")
	)
	(segment
		(start 392.186922 -17.591278)
		(end 393.818872 -12.443206)
		(width 0.14732)
		(layer "In11.Cu")
		(net "P5E_CPU0_PE1_RX_DN<15>")
	)
	(segment
		(start 351.780094 -219.996004)
		(end 351.779078 -219.995496)
		(width 0.0889)
		(layer "In11.Cu")
		(net "P5E_CPU0_PE1_RX_DN<15>")
	)
	(segment
		(start 351.496376 -214.622634)
		(end 351.49663 -214.62238)
		(width 0.0889)
		(layer "In11.Cu")
		(net "P5E_CPU0_PE1_RX_DN<15>")
	)
	(segment
		(start 401.398232 -74.93381)
		(end 395.355318 -46.101762)
		(width 0.14732)
		(layer "In11.Cu")
		(net "P5E_CPU0_PE1_RX_DN<15>")
	)
	(arc
		(start 351.496884 -216.25052)
		(mid 351.449205 -216.06762)
		(end 351.318322 -215.931242)
		(width 0.0889)
		(layer "In11.Cu")
		(net "P5E_CPU0_PE1_RX_DN<15>")
	)
	(arc
		(start 352.64725 -221.574614)
		(mid 352.495168 -221.385182)
		(end 352.436684 -221.149418)
		(width 0.0889)
		(layer "In11.Cu")
		(net "P5E_CPU0_PE1_RX_DN<15>")
	)
	(arc
		(start 352.249232 -220.809566)
		(mid 352.04416 -220.605887)
		(end 351.96653 -220.327474)
		(width 0.0889)
		(layer "In11.Cu")
		(net "P5E_CPU0_PE1_RX_DN<15>")
	)
	(arc
		(start 351.779078 -219.995496)
		(mid 351.576255 -219.795265)
		(end 351.496884 -219.521532)
		(width 0.0889)
		(layer "In11.Cu")
		(net "P5E_CPU0_PE1_RX_DN<15>")
	)
	(arc
		(start 352.436684 -221.133924)
		(mid 352.389005 -220.951024)
		(end 352.258122 -220.814646)
		(width 0.0889)
		(layer "In11.Cu")
		(net "P5E_CPU0_PE1_RX_DN<15>")
	)
	(arc
		(start 351.49663 -214.460328)
		(mid 351.421518 -214.345282)
		(end 351.31248 -214.2617)
		(width 0.0889)
		(layer "In11.Cu")
		(net "P5E_CPU0_PE1_RX_DN<15>")
	)
	(arc
		(start 351.787968 -217.383614)
		(mid 351.966565 -217.064336)
		(end 351.787968 -216.745058)
		(width 0.0889)
		(layer "In11.Cu")
		(net "P5E_CPU0_PE1_RX_DN<15>")
	)
	(arc
		(start 351.496122 -214.637366)
		(mid 351.496319 -214.630001)
		(end 351.496376 -214.622634)
		(width 0.0889)
		(layer "In11.Cu")
		(net "P5E_CPU0_PE1_RX_DN<15>")
	)
	(arc
		(start 351.317814 -214.941912)
		(mid 351.445068 -214.811946)
		(end 351.496122 -214.637366)
		(width 0.0889)
		(layer "In11.Cu")
		(net "P5E_CPU0_PE1_RX_DN<15>")
	)
	(arc
		(start 351.779078 -216.739978)
		(mid 351.576255 -216.539747)
		(end 351.496884 -216.266014)
		(width 0.0889)
		(layer "In11.Cu")
		(net "P5E_CPU0_PE1_RX_DN<15>")
	)
	(arc
		(start 351.31248 -214.2617)
		(mid 351.10365 -214.064178)
		(end 351.02673 -213.787228)
		(width 0.0889)
		(layer "In11.Cu")
		(net "P5E_CPU0_PE1_RX_DN<15>")
	)
	(arc
		(start 351.496884 -219.490544)
		(mid 351.576254 -219.21681)
		(end 351.779078 -219.01658)
		(width 0.0889)
		(layer "In11.Cu")
		(net "P5E_CPU0_PE1_RX_DN<15>")
	)
	(arc
		(start 351.303336 -215.922606)
		(mid 351.100749 -215.716255)
		(end 351.02673 -215.436704)
		(width 0.0889)
		(layer "In11.Cu")
		(net "P5E_CPU0_PE1_RX_DN<15>")
	)
	(arc
		(start 352.664014 -221.587568)
		(mid 352.655573 -221.581168)
		(end 352.64725 -221.574614)
		(width 0.0889)
		(layer "In11.Cu")
		(net "P5E_CPU0_PE1_RX_DN<15>")
	)
	(arc
		(start 351.787968 -219.0115)
		(mid 351.966444 -218.692222)
		(end 351.787968 -218.372944)
		(width 0.0889)
		(layer "In11.Cu")
		(net "P5E_CPU0_PE1_RX_DN<15>")
	)
	(arc
		(start 351.779078 -218.367864)
		(mid 351.576255 -218.167633)
		(end 351.496884 -217.8939)
		(width 0.0889)
		(layer "In11.Cu")
		(net "P5E_CPU0_PE1_RX_DN<15>")
	)
	(arc
		(start 351.02673 -215.414606)
		(mid 351.107641 -215.144478)
		(end 351.308924 -214.946992)
		(width 0.0889)
		(layer "In11.Cu")
		(net "P5E_CPU0_PE1_RX_DN<15>")
	)
	(arc
		(start 351.96653 -220.319854)
		(mid 351.918851 -220.136954)
		(end 351.787968 -220.000576)
		(width 0.0889)
		(layer "In11.Cu")
		(net "P5E_CPU0_PE1_RX_DN<15>")
	)
	(arc
		(start 351.496884 -217.856308)
		(mid 351.577795 -217.58618)
		(end 351.779078 -217.388694)
		(width 0.0889)
		(layer "In11.Cu")
		(net "P5E_CPU0_PE1_RX_DN<15>")
	)
	(segment
		(start 395.630146 -7.601204)
		(end 395.630146 -5.252974)
		(width 0.13208)
		(layer "F.Cu")
		(net "P5E_CPU0_PE1_RX_DN<14>")
	)
	(segment
		(start 395.630146 -5.252974)
		(end 395.328902 -4.95173)
		(width 0.13208)
		(layer "F.Cu")
		(net "P5E_CPU0_PE1_RX_DN<14>")
	)
	(segment
		(start 395.446758 -7.784592)
		(end 395.630146 -7.601204)
		(width 0.13208)
		(layer "F.Cu")
		(net "P5E_CPU0_PE1_RX_DN<14>")
	)
	(segment
		(start 395.446758 -8.320024)
		(end 395.446758 -7.784592)
		(width 0.13208)
		(layer "F.Cu")
		(net "P5E_CPU0_PE1_RX_DN<14>")
	)
	(segment
		(start 353.94138 -221.669864)
		(end 353.941634 -221.133924)
		(width 0.13208)
		(layer "F.Cu")
		(net "P5E_CPU0_PE1_RX_DN<14>")
	)
	(segment
		(start 402.581364 -75.122532)
		(end 402.237194 -77.330554)
		(width 0.14732)
		(layer "In11.Cu")
		(net "P5E_CPU0_PE1_RX_DN<14>")
	)
	(segment
		(start 395.623542 -12.370308)
		(end 395.59865 -12.538964)
		(width 0.14732)
		(layer "In11.Cu")
		(net "P5E_CPU0_PE1_RX_DN<14>")
	)
	(segment
		(start 352.436684 -216.25052)
		(end 352.436684 -216.260426)
		(width 0.0889)
		(layer "In11.Cu")
		(net "P5E_CPU0_PE1_RX_DN<14>")
	)
	(segment
		(start 352.90633 -217.0557)
		(end 352.90633 -217.072972)
		(width 0.0889)
		(layer "In11.Cu")
		(net "P5E_CPU0_PE1_RX_DN<14>")
	)
	(segment
		(start 352.250756 -215.926924)
		(end 352.258122 -215.931242)
		(width 0.0889)
		(layer "In11.Cu")
		(net "P5E_CPU0_PE1_RX_DN<14>")
	)
	(segment
		(start 352.24847 -215.925654)
		(end 352.249232 -215.926162)
		(width 0.0889)
		(layer "In11.Cu")
		(net "P5E_CPU0_PE1_RX_DN<14>")
	)
	(segment
		(start 350.444816 -206.497428)
		(end 351.924874 -212.406484)
		(width 0.14732)
		(layer "In11.Cu")
		(net "P5E_CPU0_PE1_RX_DN<14>")
	)
	(segment
		(start 351.96653 -215.414606)
		(end 351.96653 -215.436704)
		(width 0.0889)
		(layer "In11.Cu")
		(net "P5E_CPU0_PE1_RX_DN<14>")
	)
	(segment
		(start 351.924874 -212.406484)
		(end 351.924874 -212.90407)
		(width 0.14732)
		(layer "In11.Cu")
		(net "P5E_CPU0_PE1_RX_DN<14>")
	)
	(segment
		(start 351.924874 -212.90407)
		(end 351.924874 -212.926168)
		(width 0.0889)
		(layer "In11.Cu")
		(net "P5E_CPU0_PE1_RX_DN<14>")
	)
	(segment
		(start 394.954506 -14.669516)
		(end 394.954252 -14.670278)
		(width 0.14732)
		(layer "In11.Cu")
		(net "P5E_CPU0_PE1_RX_DN<14>")
	)
	(segment
		(start 394.597382 -15.850362)
		(end 394.17498 -17.247108)
		(width 0.14732)
		(layer "In11.Cu")
		(net "P5E_CPU0_PE1_RX_DN<14>")
	)
	(segment
		(start 352.436176 -214.461344)
		(end 352.436176 -214.622634)
		(width 0.0889)
		(layer "In11.Cu")
		(net "P5E_CPU0_PE1_RX_DN<14>")
	)
	(segment
		(start 394.863574 -18.968212)
		(end 395.066774 -19.891756)
		(width 0.14732)
		(layer "In11.Cu")
		(net "P5E_CPU0_PE1_RX_DN<14>")
	)
	(segment
		(start 352.90633 -220.311218)
		(end 352.90633 -220.334078)
		(width 0.0889)
		(layer "In11.Cu")
		(net "P5E_CPU0_PE1_RX_DN<14>")
	)
	(segment
		(start 339.67801 -172.408088)
		(end 339.67801 -174.780448)
		(width 0.14732)
		(layer "In11.Cu")
		(net "P5E_CPU0_PE1_RX_DN<14>")
	)
	(segment
		(start 394.17498 -17.937226)
		(end 394.863574 -18.968212)
		(width 0.14732)
		(layer "In11.Cu")
		(net "P5E_CPU0_PE1_RX_DN<14>")
	)
	(segment
		(start 352.718878 -218.367864)
		(end 352.727768 -218.372944)
		(width 0.0889)
		(layer "In11.Cu")
		(net "P5E_CPU0_PE1_RX_DN<14>")
	)
	(segment
		(start 395.066774 -19.891756)
		(end 402.581364 -75.122532)
		(width 0.14732)
		(layer "In11.Cu")
		(net "P5E_CPU0_PE1_RX_DN<14>")
	)
	(segment
		(start 353.189032 -220.809566)
		(end 353.203764 -220.818202)
		(width 0.0889)
		(layer "In11.Cu")
		(net "P5E_CPU0_PE1_RX_DN<14>")
	)
	(segment
		(start 394.17498 -17.247108)
		(end 394.17498 -17.937226)
		(width 0.14732)
		(layer "In11.Cu")
		(net "P5E_CPU0_PE1_RX_DN<14>")
	)
	(segment
		(start 352.436684 -217.859864)
		(end 352.436684 -217.8939)
		(width 0.0889)
		(layer "In11.Cu")
		(net "P5E_CPU0_PE1_RX_DN<14>")
	)
	(segment
		(start 351.924874 -212.926168)
		(end 351.966784 -212.968078)
		(width 0.0889)
		(layer "In11.Cu")
		(net "P5E_CPU0_PE1_RX_DN<14>")
	)
	(segment
		(start 342.96731 -161.9758)
		(end 339.67801 -172.408088)
		(width 0.14732)
		(layer "In11.Cu")
		(net "P5E_CPU0_PE1_RX_DN<14>")
	)
	(segment
		(start 352.257614 -214.941912)
		(end 352.248724 -214.946992)
		(width 0.0889)
		(layer "In11.Cu")
		(net "P5E_CPU0_PE1_RX_DN<14>")
	)
	(segment
		(start 394.597636 -15.8496)
		(end 394.597382 -15.850362)
		(width 0.14732)
		(layer "In11.Cu")
		(net "P5E_CPU0_PE1_RX_DN<14>")
	)
	(segment
		(start 394.954252 -14.670278)
		(end 394.597636 -15.8496)
		(width 0.14732)
		(layer "In11.Cu")
		(net "P5E_CPU0_PE1_RX_DN<14>")
	)
	(segment
		(start 339.67801 -174.780448)
		(end 350.444816 -206.497428)
		(width 0.14732)
		(layer "In11.Cu")
		(net "P5E_CPU0_PE1_RX_DN<14>")
	)
	(segment
		(start 352.243136 -215.922606)
		(end 352.24847 -215.925654)
		(width 0.0889)
		(layer "In11.Cu")
		(net "P5E_CPU0_PE1_RX_DN<14>")
	)
	(segment
		(start 395.623542 -5.24637)
		(end 395.623542 -12.370308)
		(width 0.14732)
		(layer "In11.Cu")
		(net "P5E_CPU0_PE1_RX_DN<14>")
	)
	(segment
		(start 353.696016 -220.83903)
		(end 353.78517 -220.862906)
		(width 0.0889)
		(layer "In11.Cu")
		(net "P5E_CPU0_PE1_RX_DN<14>")
	)
	(segment
		(start 352.436684 -219.490544)
		(end 352.436684 -219.515944)
		(width 0.0889)
		(layer "In11.Cu")
		(net "P5E_CPU0_PE1_RX_DN<14>")
	)
	(segment
		(start 395.59865 -12.538964)
		(end 394.954506 -14.669516)
		(width 0.14732)
		(layer "In11.Cu")
		(net "P5E_CPU0_PE1_RX_DN<14>")
	)
	(segment
		(start 402.237194 -77.330554)
		(end 342.96731 -161.9758)
		(width 0.14732)
		(layer "In11.Cu")
		(net "P5E_CPU0_PE1_RX_DN<14>")
	)
	(segment
		(start 351.966784 -212.968078)
		(end 351.966784 -213.930484)
		(width 0.0889)
		(layer "In11.Cu")
		(net "P5E_CPU0_PE1_RX_DN<14>")
	)
	(segment
		(start 353.78517 -220.862906)
		(end 353.941634 -221.133924)
		(width 0.0889)
		(layer "In11.Cu")
		(net "P5E_CPU0_PE1_RX_DN<14>")
	)
	(segment
		(start 352.727768 -219.0115)
		(end 352.718878 -219.01658)
		(width 0.0889)
		(layer "In11.Cu")
		(net "P5E_CPU0_PE1_RX_DN<14>")
	)
	(segment
		(start 395.328902 -4.95173)
		(end 395.623542 -5.24637)
		(width 0.14732)
		(layer "In11.Cu")
		(net "P5E_CPU0_PE1_RX_DN<14>")
	)
	(segment
		(start 352.249232 -215.926162)
		(end 352.250756 -215.926924)
		(width 0.0889)
		(layer "In11.Cu")
		(net "P5E_CPU0_PE1_RX_DN<14>")
	)
	(arc
		(start 352.90633 -220.334078)
		(mid 352.985549 -220.608763)
		(end 353.189032 -220.809566)
		(width 0.0889)
		(layer "In11.Cu")
		(net "P5E_CPU0_PE1_RX_DN<14>")
	)
	(arc
		(start 351.96653 -215.436704)
		(mid 352.040521 -215.71627)
		(end 352.243136 -215.922606)
		(width 0.0889)
		(layer "In11.Cu")
		(net "P5E_CPU0_PE1_RX_DN<14>")
	)
	(arc
		(start 352.436684 -217.8939)
		(mid 352.516054 -218.167634)
		(end 352.718878 -218.367864)
		(width 0.0889)
		(layer "In11.Cu")
		(net "P5E_CPU0_PE1_RX_DN<14>")
	)
	(arc
		(start 353.203764 -220.818202)
		(mid 353.436679 -220.884383)
		(end 353.67595 -220.847158)
		(width 0.0889)
		(layer "In11.Cu")
		(net "P5E_CPU0_PE1_RX_DN<14>")
	)
	(arc
		(start 352.90633 -217.072972)
		(mid 352.85406 -217.255337)
		(end 352.719132 -217.388694)
		(width 0.0889)
		(layer "In11.Cu")
		(net "P5E_CPU0_PE1_RX_DN<14>")
	)
	(arc
		(start 352.248724 -214.946992)
		(mid 352.047442 -215.144479)
		(end 351.96653 -215.414606)
		(width 0.0889)
		(layer "In11.Cu")
		(net "P5E_CPU0_PE1_RX_DN<14>")
	)
	(arc
		(start 352.719132 -216.739978)
		(mid 352.854065 -216.873332)
		(end 352.90633 -217.0557)
		(width 0.0889)
		(layer "In11.Cu")
		(net "P5E_CPU0_PE1_RX_DN<14>")
	)
	(arc
		(start 352.719132 -217.388694)
		(mid 352.516846 -217.587675)
		(end 352.436684 -217.859864)
		(width 0.0889)
		(layer "In11.Cu")
		(net "P5E_CPU0_PE1_RX_DN<14>")
	)
	(arc
		(start 352.252026 -214.261954)
		(mid 352.361173 -214.345882)
		(end 352.436176 -214.461344)
		(width 0.0889)
		(layer "In11.Cu")
		(net "P5E_CPU0_PE1_RX_DN<14>")
	)
	(arc
		(start 352.436176 -214.622634)
		(mid 352.388497 -214.805534)
		(end 352.257614 -214.941912)
		(width 0.0889)
		(layer "In11.Cu")
		(net "P5E_CPU0_PE1_RX_DN<14>")
	)
	(arc
		(start 352.436684 -216.260426)
		(mid 352.514795 -216.537375)
		(end 352.719132 -216.739978)
		(width 0.0889)
		(layer "In11.Cu")
		(net "P5E_CPU0_PE1_RX_DN<14>")
	)
	(arc
		(start 352.719132 -219.995496)
		(mid 352.854065 -220.12885)
		(end 352.90633 -220.311218)
		(width 0.0889)
		(layer "In11.Cu")
		(net "P5E_CPU0_PE1_RX_DN<14>")
	)
	(arc
		(start 353.67595 -220.847158)
		(mid 353.686023 -220.843192)
		(end 353.696016 -220.83903)
		(width 0.0889)
		(layer "In11.Cu")
		(net "P5E_CPU0_PE1_RX_DN<14>")
	)
	(arc
		(start 352.718878 -219.01658)
		(mid 352.516055 -219.216811)
		(end 352.436684 -219.490544)
		(width 0.0889)
		(layer "In11.Cu")
		(net "P5E_CPU0_PE1_RX_DN<14>")
	)
	(arc
		(start 351.966784 -213.930484)
		(mid 352.078063 -214.12319)
		(end 352.252026 -214.261954)
		(width 0.0889)
		(layer "In11.Cu")
		(net "P5E_CPU0_PE1_RX_DN<14>")
	)
	(arc
		(start 352.727768 -218.372944)
		(mid 352.906244 -218.692222)
		(end 352.727768 -219.0115)
		(width 0.0889)
		(layer "In11.Cu")
		(net "P5E_CPU0_PE1_RX_DN<14>")
	)
	(arc
		(start 352.436684 -219.515944)
		(mid 352.514795 -219.792893)
		(end 352.719132 -219.995496)
		(width 0.0889)
		(layer "In11.Cu")
		(net "P5E_CPU0_PE1_RX_DN<14>")
	)
	(arc
		(start 352.258122 -215.931242)
		(mid 352.389036 -216.067602)
		(end 352.436684 -216.25052)
		(width 0.0889)
		(layer "In11.Cu")
		(net "P5E_CPU0_PE1_RX_DN<14>")
	)
	(segment
		(start 397.426434 -7.597394)
		(end 397.426434 -7.015734)
		(width 0.13208)
		(layer "F.Cu")
		(net "P5E_CPU0_PE1_RX_DN<13>")
	)
	(segment
		(start 397.426434 -7.015734)
		(end 397.124174 -6.713474)
		(width 0.13208)
		(layer "F.Cu")
		(net "P5E_CPU0_PE1_RX_DN<13>")
	)
	(segment
		(start 397.246856 -8.320024)
		(end 397.246856 -7.776972)
		(width 0.13208)
		(layer "F.Cu")
		(net "P5E_CPU0_PE1_RX_DN<13>")
	)
	(segment
		(start 397.246856 -7.776972)
		(end 397.426434 -7.597394)
		(width 0.13208)
		(layer "F.Cu")
		(net "P5E_CPU0_PE1_RX_DN<13>")
	)
	(segment
		(start 354.411534 -222.48368)
		(end 354.41128 -221.94774)
		(width 0.13208)
		(layer "F.Cu")
		(net "P5E_CPU0_PE1_RX_DN<13>")
	)
	(segment
		(start 354.128832 -220.809566)
		(end 354.137722 -220.814646)
		(width 0.0889)
		(layer "In11.Cu")
		(net "P5E_CPU0_PE1_RX_DN<13>")
	)
	(segment
		(start 397.124174 -6.713474)
		(end 397.418814 -7.008114)
		(width 0.14732)
		(layer "In11.Cu")
		(net "P5E_CPU0_PE1_RX_DN<13>")
	)
	(segment
		(start 397.146272 -18.49247)
		(end 396.96136 -18.939256)
		(width 0.14732)
		(layer "In11.Cu")
		(net "P5E_CPU0_PE1_RX_DN<13>")
	)
	(segment
		(start 397.76146 -17.606772)
		(end 397.56969 -18.069306)
		(width 0.14732)
		(layer "In11.Cu")
		(net "P5E_CPU0_PE1_RX_DN<13>")
	)
	(segment
		(start 354.316284 -221.133924)
		(end 354.316284 -221.149418)
		(width 0.0889)
		(layer "In11.Cu")
		(net "P5E_CPU0_PE1_RX_DN<13>")
	)
	(segment
		(start 397.423386 -12.392914)
		(end 397.76146 -17.224248)
		(width 0.14732)
		(layer "In11.Cu")
		(net "P5E_CPU0_PE1_RX_DN<13>")
	)
	(segment
		(start 397.418814 -7.008114)
		(end 397.418814 -12.220448)
		(width 0.14732)
		(layer "In11.Cu")
		(net "P5E_CPU0_PE1_RX_DN<13>")
	)
	(segment
		(start 352.906838 -212.968078)
		(end 352.906838 -213.929468)
		(width 0.0889)
		(layer "In11.Cu")
		(net "P5E_CPU0_PE1_RX_DN<13>")
	)
	(segment
		(start 354.543614 -221.587568)
		(end 354.567744 -221.676722)
		(width 0.0889)
		(layer "In11.Cu")
		(net "P5E_CPU0_PE1_RX_DN<13>")
	)
	(segment
		(start 353.84613 -220.319854)
		(end 353.84613 -220.327474)
		(width 0.0889)
		(layer "In11.Cu")
		(net "P5E_CPU0_PE1_RX_DN<13>")
	)
	(segment
		(start 353.667568 -217.383614)
		(end 353.658678 -217.388694)
		(width 0.0889)
		(layer "In11.Cu")
		(net "P5E_CPU0_PE1_RX_DN<13>")
	)
	(segment
		(start 353.376484 -217.856308)
		(end 353.376484 -217.8939)
		(width 0.0889)
		(layer "In11.Cu")
		(net "P5E_CPU0_PE1_RX_DN<13>")
	)
	(segment
		(start 396.96136 -18.939256)
		(end 396.96136 -19.522948)
		(width 0.14732)
		(layer "In11.Cu")
		(net "P5E_CPU0_PE1_RX_DN<13>")
	)
	(segment
		(start 353.658678 -216.739978)
		(end 353.659694 -216.740486)
		(width 0.0889)
		(layer "In11.Cu")
		(net "P5E_CPU0_PE1_RX_DN<13>")
	)
	(segment
		(start 352.864928 -212.926168)
		(end 352.906838 -212.968078)
		(width 0.0889)
		(layer "In11.Cu")
		(net "P5E_CPU0_PE1_RX_DN<13>")
	)
	(segment
		(start 397.418814 -12.220448)
		(end 397.423386 -12.392914)
		(width 0.14732)
		(layer "In11.Cu")
		(net "P5E_CPU0_PE1_RX_DN<13>")
	)
	(segment
		(start 340.616286 -172.53966)
		(end 340.616286 -174.643796)
		(width 0.14732)
		(layer "In11.Cu")
		(net "P5E_CPU0_PE1_RX_DN<13>")
	)
	(segment
		(start 353.375976 -214.461344)
		(end 353.375976 -214.622634)
		(width 0.0889)
		(layer "In11.Cu")
		(net "P5E_CPU0_PE1_RX_DN<13>")
	)
	(segment
		(start 397.76146 -17.224248)
		(end 397.76146 -17.606772)
		(width 0.14732)
		(layer "In11.Cu")
		(net "P5E_CPU0_PE1_RX_DN<13>")
	)
	(segment
		(start 353.659694 -216.740486)
		(end 353.667568 -216.745058)
		(width 0.0889)
		(layer "In11.Cu")
		(net "P5E_CPU0_PE1_RX_DN<13>")
	)
	(segment
		(start 396.96136 -19.522948)
		(end 403.63775 -75.497436)
		(width 0.14732)
		(layer "In11.Cu")
		(net "P5E_CPU0_PE1_RX_DN<13>")
	)
	(segment
		(start 353.667568 -219.0115)
		(end 353.658678 -219.01658)
		(width 0.0889)
		(layer "In11.Cu")
		(net "P5E_CPU0_PE1_RX_DN<13>")
	)
	(segment
		(start 352.864928 -212.126068)
		(end 352.864928 -212.90407)
		(width 0.14732)
		(layer "In11.Cu")
		(net "P5E_CPU0_PE1_RX_DN<13>")
	)
	(segment
		(start 353.19208 -214.2617)
		(end 353.191826 -214.261954)
		(width 0.0889)
		(layer "In11.Cu")
		(net "P5E_CPU0_PE1_RX_DN<13>")
	)
	(segment
		(start 352.864928 -212.90407)
		(end 352.864928 -212.926168)
		(width 0.0889)
		(layer "In11.Cu")
		(net "P5E_CPU0_PE1_RX_DN<13>")
	)
	(segment
		(start 353.658678 -218.367864)
		(end 353.659694 -218.368372)
		(width 0.0889)
		(layer "In11.Cu")
		(net "P5E_CPU0_PE1_RX_DN<13>")
	)
	(segment
		(start 353.376484 -219.490544)
		(end 353.376484 -219.521532)
		(width 0.0889)
		(layer "In11.Cu")
		(net "P5E_CPU0_PE1_RX_DN<13>")
	)
	(segment
		(start 353.182936 -215.922606)
		(end 353.189032 -215.926162)
		(width 0.0889)
		(layer "In11.Cu")
		(net "P5E_CPU0_PE1_RX_DN<13>")
	)
	(segment
		(start 354.567744 -221.676722)
		(end 354.41128 -221.94774)
		(width 0.0889)
		(layer "In11.Cu")
		(net "P5E_CPU0_PE1_RX_DN<13>")
	)
	(segment
		(start 353.659694 -219.996004)
		(end 353.667568 -220.000576)
		(width 0.0889)
		(layer "In11.Cu")
		(net "P5E_CPU0_PE1_RX_DN<13>")
	)
	(segment
		(start 353.197414 -214.941912)
		(end 353.188524 -214.946992)
		(width 0.0889)
		(layer "In11.Cu")
		(net "P5E_CPU0_PE1_RX_DN<13>")
	)
	(segment
		(start 353.376484 -216.25052)
		(end 353.376484 -216.266014)
		(width 0.0889)
		(layer "In11.Cu")
		(net "P5E_CPU0_PE1_RX_DN<13>")
	)
	(segment
		(start 343.815416 -162.392614)
		(end 340.616286 -172.53966)
		(width 0.14732)
		(layer "In11.Cu")
		(net "P5E_CPU0_PE1_RX_DN<13>")
	)
	(segment
		(start 397.56969 -18.069306)
		(end 397.146272 -18.49247)
		(width 0.14732)
		(layer "In11.Cu")
		(net "P5E_CPU0_PE1_RX_DN<13>")
	)
	(segment
		(start 352.90633 -215.414606)
		(end 352.90633 -215.436704)
		(width 0.0889)
		(layer "In11.Cu")
		(net "P5E_CPU0_PE1_RX_DN<13>")
	)
	(segment
		(start 353.659694 -218.368372)
		(end 353.667568 -218.372944)
		(width 0.0889)
		(layer "In11.Cu")
		(net "P5E_CPU0_PE1_RX_DN<13>")
	)
	(segment
		(start 353.658678 -219.995496)
		(end 353.659694 -219.996004)
		(width 0.0889)
		(layer "In11.Cu")
		(net "P5E_CPU0_PE1_RX_DN<13>")
	)
	(segment
		(start 340.616286 -174.643796)
		(end 351.535492 -206.815182)
		(width 0.14732)
		(layer "In11.Cu")
		(net "P5E_CPU0_PE1_RX_DN<13>")
	)
	(segment
		(start 403.130004 -77.683106)
		(end 343.815416 -162.392614)
		(width 0.14732)
		(layer "In11.Cu")
		(net "P5E_CPU0_PE1_RX_DN<13>")
	)
	(segment
		(start 353.189032 -215.926162)
		(end 353.197922 -215.931242)
		(width 0.0889)
		(layer "In11.Cu")
		(net "P5E_CPU0_PE1_RX_DN<13>")
	)
	(segment
		(start 351.535492 -206.815182)
		(end 352.864928 -212.126068)
		(width 0.14732)
		(layer "In11.Cu")
		(net "P5E_CPU0_PE1_RX_DN<13>")
	)
	(segment
		(start 403.63775 -75.497436)
		(end 403.130004 -77.683106)
		(width 0.14732)
		(layer "In11.Cu")
		(net "P5E_CPU0_PE1_RX_DN<13>")
	)
	(arc
		(start 353.84613 -220.327474)
		(mid 353.923759 -220.605887)
		(end 354.128832 -220.809566)
		(width 0.0889)
		(layer "In11.Cu")
		(net "P5E_CPU0_PE1_RX_DN<13>")
	)
	(arc
		(start 354.316284 -221.149418)
		(mid 354.374837 -221.385148)
		(end 354.52685 -221.574614)
		(width 0.0889)
		(layer "In11.Cu")
		(net "P5E_CPU0_PE1_RX_DN<13>")
	)
	(arc
		(start 354.52685 -221.574614)
		(mid 354.53517 -221.581171)
		(end 354.543614 -221.587568)
		(width 0.0889)
		(layer "In11.Cu")
		(net "P5E_CPU0_PE1_RX_DN<13>")
	)
	(arc
		(start 353.667568 -216.745058)
		(mid 353.846165 -217.064336)
		(end 353.667568 -217.383614)
		(width 0.0889)
		(layer "In11.Cu")
		(net "P5E_CPU0_PE1_RX_DN<13>")
	)
	(arc
		(start 353.667568 -218.372944)
		(mid 353.846044 -218.692222)
		(end 353.667568 -219.0115)
		(width 0.0889)
		(layer "In11.Cu")
		(net "P5E_CPU0_PE1_RX_DN<13>")
	)
	(arc
		(start 353.376484 -219.521532)
		(mid 353.455854 -219.795266)
		(end 353.658678 -219.995496)
		(width 0.0889)
		(layer "In11.Cu")
		(net "P5E_CPU0_PE1_RX_DN<13>")
	)
	(arc
		(start 352.906838 -213.929468)
		(mid 353.017966 -214.122627)
		(end 353.19208 -214.2617)
		(width 0.0889)
		(layer "In11.Cu")
		(net "P5E_CPU0_PE1_RX_DN<13>")
	)
	(arc
		(start 353.376484 -217.8939)
		(mid 353.455854 -218.167634)
		(end 353.658678 -218.367864)
		(width 0.0889)
		(layer "In11.Cu")
		(net "P5E_CPU0_PE1_RX_DN<13>")
	)
	(arc
		(start 354.137722 -220.814646)
		(mid 354.268636 -220.951006)
		(end 354.316284 -221.133924)
		(width 0.0889)
		(layer "In11.Cu")
		(net "P5E_CPU0_PE1_RX_DN<13>")
	)
	(arc
		(start 353.376484 -216.266014)
		(mid 353.455854 -216.539748)
		(end 353.658678 -216.739978)
		(width 0.0889)
		(layer "In11.Cu")
		(net "P5E_CPU0_PE1_RX_DN<13>")
	)
	(arc
		(start 353.188524 -214.946992)
		(mid 352.987242 -215.144479)
		(end 352.90633 -215.414606)
		(width 0.0889)
		(layer "In11.Cu")
		(net "P5E_CPU0_PE1_RX_DN<13>")
	)
	(arc
		(start 353.667568 -220.000576)
		(mid 353.798482 -220.136936)
		(end 353.84613 -220.319854)
		(width 0.0889)
		(layer "In11.Cu")
		(net "P5E_CPU0_PE1_RX_DN<13>")
	)
	(arc
		(start 353.197922 -215.931242)
		(mid 353.328836 -216.067602)
		(end 353.376484 -216.25052)
		(width 0.0889)
		(layer "In11.Cu")
		(net "P5E_CPU0_PE1_RX_DN<13>")
	)
	(arc
		(start 352.90633 -215.436704)
		(mid 352.980321 -215.71627)
		(end 353.182936 -215.922606)
		(width 0.0889)
		(layer "In11.Cu")
		(net "P5E_CPU0_PE1_RX_DN<13>")
	)
	(arc
		(start 353.191826 -214.261954)
		(mid 353.300973 -214.345882)
		(end 353.375976 -214.461344)
		(width 0.0889)
		(layer "In11.Cu")
		(net "P5E_CPU0_PE1_RX_DN<13>")
	)
	(arc
		(start 353.658678 -217.388694)
		(mid 353.457396 -217.586181)
		(end 353.376484 -217.856308)
		(width 0.0889)
		(layer "In11.Cu")
		(net "P5E_CPU0_PE1_RX_DN<13>")
	)
	(arc
		(start 353.375976 -214.622634)
		(mid 353.328297 -214.805534)
		(end 353.197414 -214.941912)
		(width 0.0889)
		(layer "In11.Cu")
		(net "P5E_CPU0_PE1_RX_DN<13>")
	)
	(arc
		(start 353.658678 -219.01658)
		(mid 353.455855 -219.216811)
		(end 353.376484 -219.490544)
		(width 0.0889)
		(layer "In11.Cu")
		(net "P5E_CPU0_PE1_RX_DN<13>")
	)
	(segment
		(start 399.230088 -5.252974)
		(end 398.928844 -4.95173)
		(width 0.13208)
		(layer "F.Cu")
		(net "P5E_CPU0_PE1_RX_DN<12>")
	)
	(segment
		(start 355.82098 -221.669864)
		(end 355.821234 -221.133924)
		(width 0.13208)
		(layer "F.Cu")
		(net "P5E_CPU0_PE1_RX_DN<12>")
	)
	(segment
		(start 399.046954 -7.784338)
		(end 399.230088 -7.601204)
		(width 0.13208)
		(layer "F.Cu")
		(net "P5E_CPU0_PE1_RX_DN<12>")
	)
	(segment
		(start 399.046954 -8.320024)
		(end 399.046954 -7.784338)
		(width 0.13208)
		(layer "F.Cu")
		(net "P5E_CPU0_PE1_RX_DN<12>")
	)
	(segment
		(start 399.230088 -7.601204)
		(end 399.230088 -5.252974)
		(width 0.13208)
		(layer "F.Cu")
		(net "P5E_CPU0_PE1_RX_DN<12>")
	)
	(segment
		(start 399.223484 -5.24637)
		(end 399.223484 -12.343892)
		(width 0.14732)
		(layer "In11.Cu")
		(net "P5E_CPU0_PE1_RX_DN<12>")
	)
	(segment
		(start 352.497644 -206.699612)
		(end 353.804474 -211.922106)
		(width 0.14732)
		(layer "In11.Cu")
		(net "P5E_CPU0_PE1_RX_DN<12>")
	)
	(segment
		(start 341.549228 -174.420022)
		(end 352.497644 -206.699612)
		(width 0.14732)
		(layer "In11.Cu")
		(net "P5E_CPU0_PE1_RX_DN<12>")
	)
	(segment
		(start 400.52244 -20.814284)
		(end 404.735792 -75.806808)
		(width 0.14732)
		(layer "In11.Cu")
		(net "P5E_CPU0_PE1_RX_DN<12>")
	)
	(segment
		(start 353.804474 -212.926168)
		(end 353.846384 -212.968078)
		(width 0.0889)
		(layer "In11.Cu")
		(net "P5E_CPU0_PE1_RX_DN<12>")
	)
	(segment
		(start 399.606516 -16.119602)
		(end 399.771108 -17.742154)
		(width 0.14732)
		(layer "In11.Cu")
		(net "P5E_CPU0_PE1_RX_DN<12>")
	)
	(segment
		(start 398.928844 -4.95173)
		(end 399.223484 -5.24637)
		(width 0.14732)
		(layer "In11.Cu")
		(net "P5E_CPU0_PE1_RX_DN<12>")
	)
	(segment
		(start 355.66477 -220.862906)
		(end 355.821234 -221.133924)
		(width 0.0889)
		(layer "In11.Cu")
		(net "P5E_CPU0_PE1_RX_DN<12>")
	)
	(segment
		(start 399.832068 -17.911572)
		(end 400.3548 -18.693892)
		(width 0.14732)
		(layer "In11.Cu")
		(net "P5E_CPU0_PE1_RX_DN<12>")
	)
	(segment
		(start 400.52244 -19.246342)
		(end 400.52244 -20.814284)
		(width 0.14732)
		(layer "In11.Cu")
		(net "P5E_CPU0_PE1_RX_DN<12>")
	)
	(segment
		(start 344.654886 -162.82289)
		(end 341.549228 -172.673772)
		(width 0.14732)
		(layer "In11.Cu")
		(net "P5E_CPU0_PE1_RX_DN<12>")
	)
	(segment
		(start 354.607368 -219.0115)
		(end 354.598478 -219.01658)
		(width 0.0889)
		(layer "In11.Cu")
		(net "P5E_CPU0_PE1_RX_DN<12>")
	)
	(segment
		(start 353.86391 -213.924642)
		(end 353.889818 -213.990682)
		(width 0.0889)
		(layer "In11.Cu")
		(net "P5E_CPU0_PE1_RX_DN<12>")
	)
	(segment
		(start 404.735792 -75.806808)
		(end 404.021798 -78.038706)
		(width 0.14732)
		(layer "In11.Cu")
		(net "P5E_CPU0_PE1_RX_DN<12>")
	)
	(segment
		(start 353.84613 -215.414606)
		(end 353.84613 -215.436704)
		(width 0.0889)
		(layer "In11.Cu")
		(net "P5E_CPU0_PE1_RX_DN<12>")
	)
	(segment
		(start 353.846384 -212.968078)
		(end 353.846384 -213.830662)
		(width 0.0889)
		(layer "In11.Cu")
		(net "P5E_CPU0_PE1_RX_DN<12>")
	)
	(segment
		(start 399.606262 -16.119602)
		(end 399.606516 -16.119602)
		(width 0.14732)
		(layer "In11.Cu")
		(net "P5E_CPU0_PE1_RX_DN<12>")
	)
	(segment
		(start 354.78593 -220.311218)
		(end 354.78593 -220.334078)
		(width 0.0889)
		(layer "In11.Cu")
		(net "P5E_CPU0_PE1_RX_DN<12>")
	)
	(segment
		(start 354.78593 -217.0557)
		(end 354.78593 -217.072972)
		(width 0.0889)
		(layer "In11.Cu")
		(net "P5E_CPU0_PE1_RX_DN<12>")
	)
	(segment
		(start 354.122736 -215.922606)
		(end 354.128832 -215.926162)
		(width 0.0889)
		(layer "In11.Cu")
		(net "P5E_CPU0_PE1_RX_DN<12>")
	)
	(segment
		(start 400.3548 -18.693892)
		(end 400.52244 -19.246342)
		(width 0.14732)
		(layer "In11.Cu")
		(net "P5E_CPU0_PE1_RX_DN<12>")
	)
	(segment
		(start 354.137214 -214.941912)
		(end 354.128324 -214.946992)
		(width 0.0889)
		(layer "In11.Cu")
		(net "P5E_CPU0_PE1_RX_DN<12>")
	)
	(segment
		(start 404.021798 -78.038706)
		(end 344.654886 -162.82289)
		(width 0.14732)
		(layer "In11.Cu")
		(net "P5E_CPU0_PE1_RX_DN<12>")
	)
	(segment
		(start 353.804474 -212.90407)
		(end 353.804474 -212.926168)
		(width 0.0889)
		(layer "In11.Cu")
		(net "P5E_CPU0_PE1_RX_DN<12>")
	)
	(segment
		(start 354.316284 -216.25052)
		(end 354.316284 -216.260426)
		(width 0.0889)
		(layer "In11.Cu")
		(net "P5E_CPU0_PE1_RX_DN<12>")
	)
	(segment
		(start 354.316284 -219.490544)
		(end 354.316284 -219.515944)
		(width 0.0889)
		(layer "In11.Cu")
		(net "P5E_CPU0_PE1_RX_DN<12>")
	)
	(segment
		(start 399.223484 -12.343892)
		(end 399.606262 -16.119602)
		(width 0.14732)
		(layer "In11.Cu")
		(net "P5E_CPU0_PE1_RX_DN<12>")
	)
	(segment
		(start 341.549228 -172.673772)
		(end 341.549228 -174.420022)
		(width 0.14732)
		(layer "In11.Cu")
		(net "P5E_CPU0_PE1_RX_DN<12>")
	)
	(segment
		(start 354.316284 -217.859864)
		(end 354.316284 -217.8939)
		(width 0.0889)
		(layer "In11.Cu")
		(net "P5E_CPU0_PE1_RX_DN<12>")
	)
	(segment
		(start 354.315776 -214.472266)
		(end 354.315776 -214.622634)
		(width 0.0889)
		(layer "In11.Cu")
		(net "P5E_CPU0_PE1_RX_DN<12>")
	)
	(segment
		(start 353.804474 -211.922106)
		(end 353.804474 -212.90407)
		(width 0.14732)
		(layer "In11.Cu")
		(net "P5E_CPU0_PE1_RX_DN<12>")
	)
	(segment
		(start 354.128832 -215.926162)
		(end 354.137722 -215.931242)
		(width 0.0889)
		(layer "In11.Cu")
		(net "P5E_CPU0_PE1_RX_DN<12>")
	)
	(segment
		(start 355.575616 -220.83903)
		(end 355.66477 -220.862906)
		(width 0.0889)
		(layer "In11.Cu")
		(net "P5E_CPU0_PE1_RX_DN<12>")
	)
	(segment
		(start 354.598478 -218.367864)
		(end 354.607368 -218.372944)
		(width 0.0889)
		(layer "In11.Cu")
		(net "P5E_CPU0_PE1_RX_DN<12>")
	)
	(segment
		(start 399.771108 -17.742154)
		(end 399.832068 -17.911572)
		(width 0.14732)
		(layer "In11.Cu")
		(net "P5E_CPU0_PE1_RX_DN<12>")
	)
	(segment
		(start 355.068632 -220.809566)
		(end 355.083364 -220.818202)
		(width 0.0889)
		(layer "In11.Cu")
		(net "P5E_CPU0_PE1_RX_DN<12>")
	)
	(arc
		(start 354.598478 -219.01658)
		(mid 354.395655 -219.216811)
		(end 354.316284 -219.490544)
		(width 0.0889)
		(layer "In11.Cu")
		(net "P5E_CPU0_PE1_RX_DN<12>")
	)
	(arc
		(start 355.55555 -220.847158)
		(mid 355.565623 -220.843192)
		(end 355.575616 -220.83903)
		(width 0.0889)
		(layer "In11.Cu")
		(net "P5E_CPU0_PE1_RX_DN<12>")
	)
	(arc
		(start 354.137722 -215.931242)
		(mid 354.268636 -216.067602)
		(end 354.316284 -216.25052)
		(width 0.0889)
		(layer "In11.Cu")
		(net "P5E_CPU0_PE1_RX_DN<12>")
	)
	(arc
		(start 354.13188 -214.2617)
		(mid 354.236139 -214.340473)
		(end 354.310188 -214.448136)
		(width 0.0889)
		(layer "In11.Cu")
		(net "P5E_CPU0_PE1_RX_DN<12>")
	)
	(arc
		(start 354.78593 -220.334078)
		(mid 354.865149 -220.608763)
		(end 355.068632 -220.809566)
		(width 0.0889)
		(layer "In11.Cu")
		(net "P5E_CPU0_PE1_RX_DN<12>")
	)
	(arc
		(start 354.316284 -217.8939)
		(mid 354.395654 -218.167634)
		(end 354.598478 -218.367864)
		(width 0.0889)
		(layer "In11.Cu")
		(net "P5E_CPU0_PE1_RX_DN<12>")
	)
	(arc
		(start 353.889818 -213.990682)
		(mid 353.986515 -214.14793)
		(end 354.13188 -214.2617)
		(width 0.0889)
		(layer "In11.Cu")
		(net "P5E_CPU0_PE1_RX_DN<12>")
	)
	(arc
		(start 355.083364 -220.818202)
		(mid 355.316279 -220.884383)
		(end 355.55555 -220.847158)
		(width 0.0889)
		(layer "In11.Cu")
		(net "P5E_CPU0_PE1_RX_DN<12>")
	)
	(arc
		(start 353.846384 -213.830662)
		(mid 353.850734 -213.878475)
		(end 353.86391 -213.924642)
		(width 0.0889)
		(layer "In11.Cu")
		(net "P5E_CPU0_PE1_RX_DN<12>")
	)
	(arc
		(start 354.607368 -218.372944)
		(mid 354.785844 -218.692222)
		(end 354.607368 -219.0115)
		(width 0.0889)
		(layer "In11.Cu")
		(net "P5E_CPU0_PE1_RX_DN<12>")
	)
	(arc
		(start 354.598732 -216.739978)
		(mid 354.733665 -216.873332)
		(end 354.78593 -217.0557)
		(width 0.0889)
		(layer "In11.Cu")
		(net "P5E_CPU0_PE1_RX_DN<12>")
	)
	(arc
		(start 354.78593 -217.072972)
		(mid 354.73366 -217.255337)
		(end 354.598732 -217.388694)
		(width 0.0889)
		(layer "In11.Cu")
		(net "P5E_CPU0_PE1_RX_DN<12>")
	)
	(arc
		(start 353.84613 -215.436704)
		(mid 353.920121 -215.71627)
		(end 354.122736 -215.922606)
		(width 0.0889)
		(layer "In11.Cu")
		(net "P5E_CPU0_PE1_RX_DN<12>")
	)
	(arc
		(start 354.316284 -216.260426)
		(mid 354.394395 -216.537375)
		(end 354.598732 -216.739978)
		(width 0.0889)
		(layer "In11.Cu")
		(net "P5E_CPU0_PE1_RX_DN<12>")
	)
	(arc
		(start 354.315776 -214.622634)
		(mid 354.268097 -214.805534)
		(end 354.137214 -214.941912)
		(width 0.0889)
		(layer "In11.Cu")
		(net "P5E_CPU0_PE1_RX_DN<12>")
	)
	(arc
		(start 354.316284 -219.515944)
		(mid 354.394395 -219.792893)
		(end 354.598732 -219.995496)
		(width 0.0889)
		(layer "In11.Cu")
		(net "P5E_CPU0_PE1_RX_DN<12>")
	)
	(arc
		(start 354.310188 -214.448136)
		(mid 354.314338 -214.459889)
		(end 354.315776 -214.472266)
		(width 0.0889)
		(layer "In11.Cu")
		(net "P5E_CPU0_PE1_RX_DN<12>")
	)
	(arc
		(start 354.598732 -217.388694)
		(mid 354.396446 -217.587675)
		(end 354.316284 -217.859864)
		(width 0.0889)
		(layer "In11.Cu")
		(net "P5E_CPU0_PE1_RX_DN<12>")
	)
	(arc
		(start 354.128324 -214.946992)
		(mid 353.927042 -215.144479)
		(end 353.84613 -215.414606)
		(width 0.0889)
		(layer "In11.Cu")
		(net "P5E_CPU0_PE1_RX_DN<12>")
	)
	(arc
		(start 354.598732 -219.995496)
		(mid 354.733665 -220.12885)
		(end 354.78593 -220.311218)
		(width 0.0889)
		(layer "In11.Cu")
		(net "P5E_CPU0_PE1_RX_DN<12>")
	)
	(segment
		(start 401.026376 -7.597394)
		(end 401.026376 -7.015734)
		(width 0.13208)
		(layer "F.Cu")
		(net "P5E_CPU0_PE1_RX_DN<11>")
	)
	(segment
		(start 356.291134 -222.48368)
		(end 356.29088 -221.94774)
		(width 0.13208)
		(layer "F.Cu")
		(net "P5E_CPU0_PE1_RX_DN<11>")
	)
	(segment
		(start 400.846798 -7.776972)
		(end 401.026376 -7.597394)
		(width 0.13208)
		(layer "F.Cu")
		(net "P5E_CPU0_PE1_RX_DN<11>")
	)
	(segment
		(start 400.846798 -8.320024)
		(end 400.846798 -7.776972)
		(width 0.13208)
		(layer "F.Cu")
		(net "P5E_CPU0_PE1_RX_DN<11>")
	)
	(segment
		(start 401.026376 -7.015734)
		(end 400.724116 -6.713474)
		(width 0.13208)
		(layer "F.Cu")
		(net "P5E_CPU0_PE1_RX_DN<11>")
	)
	(segment
		(start 354.744528 -212.926168)
		(end 354.786438 -212.968078)
		(width 0.0889)
		(layer "In11.Cu")
		(net "P5E_CPU0_PE1_RX_DN<11>")
	)
	(segment
		(start 403.27326 -17.801336)
		(end 402.5519 -18.880836)
		(width 0.14732)
		(layer "In11.Cu")
		(net "P5E_CPU0_PE1_RX_DN<11>")
	)
	(segment
		(start 355.539294 -218.368372)
		(end 355.547168 -218.372944)
		(width 0.0889)
		(layer "In11.Cu")
		(net "P5E_CPU0_PE1_RX_DN<11>")
	)
	(segment
		(start 403.27326 -17.318228)
		(end 403.27326 -17.801336)
		(width 0.14732)
		(layer "In11.Cu")
		(net "P5E_CPU0_PE1_RX_DN<11>")
	)
	(segment
		(start 354.786438 -212.968078)
		(end 354.786438 -213.929468)
		(width 0.0889)
		(layer "In11.Cu")
		(net "P5E_CPU0_PE1_RX_DN<11>")
	)
	(segment
		(start 342.482424 -174.224188)
		(end 353.362768 -205.92542)
		(width 0.14732)
		(layer "In11.Cu")
		(net "P5E_CPU0_PE1_RX_DN<11>")
	)
	(segment
		(start 356.447344 -221.676722)
		(end 356.29088 -221.94774)
		(width 0.0889)
		(layer "In11.Cu")
		(net "P5E_CPU0_PE1_RX_DN<11>")
	)
	(segment
		(start 355.539294 -219.996004)
		(end 355.547168 -220.000576)
		(width 0.0889)
		(layer "In11.Cu")
		(net "P5E_CPU0_PE1_RX_DN<11>")
	)
	(segment
		(start 402.5519 -18.880836)
		(end 402.5519 -19.402806)
		(width 0.14732)
		(layer "In11.Cu")
		(net "P5E_CPU0_PE1_RX_DN<11>")
	)
	(segment
		(start 355.539294 -216.740486)
		(end 355.547168 -216.745058)
		(width 0.0889)
		(layer "In11.Cu")
		(net "P5E_CPU0_PE1_RX_DN<11>")
	)
	(segment
		(start 401.077684 -12.714732)
		(end 403.27326 -17.318228)
		(width 0.14732)
		(layer "In11.Cu")
		(net "P5E_CPU0_PE1_RX_DN<11>")
	)
	(segment
		(start 355.538278 -216.739978)
		(end 355.539294 -216.740486)
		(width 0.0889)
		(layer "In11.Cu")
		(net "P5E_CPU0_PE1_RX_DN<11>")
	)
	(segment
		(start 354.78593 -215.414606)
		(end 354.78593 -215.436704)
		(width 0.0889)
		(layer "In11.Cu")
		(net "P5E_CPU0_PE1_RX_DN<11>")
	)
	(segment
		(start 355.256084 -217.856308)
		(end 355.256084 -217.8939)
		(width 0.0889)
		(layer "In11.Cu")
		(net "P5E_CPU0_PE1_RX_DN<11>")
	)
	(segment
		(start 401.018756 -12.454128)
		(end 401.077684 -12.714732)
		(width 0.14732)
		(layer "In11.Cu")
		(net "P5E_CPU0_PE1_RX_DN<11>")
	)
	(segment
		(start 355.538278 -219.995496)
		(end 355.539294 -219.996004)
		(width 0.0889)
		(layer "In11.Cu")
		(net "P5E_CPU0_PE1_RX_DN<11>")
	)
	(segment
		(start 356.195884 -221.133924)
		(end 356.195884 -221.149418)
		(width 0.0889)
		(layer "In11.Cu")
		(net "P5E_CPU0_PE1_RX_DN<11>")
	)
	(segment
		(start 354.744528 -212.90407)
		(end 354.744528 -212.926168)
		(width 0.0889)
		(layer "In11.Cu")
		(net "P5E_CPU0_PE1_RX_DN<11>")
	)
	(segment
		(start 355.062536 -215.922606)
		(end 355.068632 -215.926162)
		(width 0.0889)
		(layer "In11.Cu")
		(net "P5E_CPU0_PE1_RX_DN<11>")
	)
	(segment
		(start 355.256084 -216.25052)
		(end 355.256084 -216.266014)
		(width 0.0889)
		(layer "In11.Cu")
		(net "P5E_CPU0_PE1_RX_DN<11>")
	)
	(segment
		(start 402.5519 -19.402806)
		(end 402.72716 -19.826478)
		(width 0.14732)
		(layer "In11.Cu")
		(net "P5E_CPU0_PE1_RX_DN<11>")
	)
	(segment
		(start 355.255576 -214.461344)
		(end 355.255576 -214.622634)
		(width 0.0889)
		(layer "In11.Cu")
		(net "P5E_CPU0_PE1_RX_DN<11>")
	)
	(segment
		(start 404.913592 -78.396338)
		(end 345.493594 -163.25596)
		(width 0.14732)
		(layer "In11.Cu")
		(net "P5E_CPU0_PE1_RX_DN<11>")
	)
	(segment
		(start 405.772112 -75.89139)
		(end 404.913592 -78.396338)
		(width 0.14732)
		(layer "In11.Cu")
		(net "P5E_CPU0_PE1_RX_DN<11>")
	)
	(segment
		(start 354.797868 -213.959694)
		(end 354.79736 -213.959948)
		(width 0.0889)
		(layer "In11.Cu")
		(net "P5E_CPU0_PE1_RX_DN<11>")
	)
	(segment
		(start 354.744528 -211.816188)
		(end 354.744528 -212.90407)
		(width 0.14732)
		(layer "In11.Cu")
		(net "P5E_CPU0_PE1_RX_DN<11>")
	)
	(segment
		(start 355.068632 -215.926162)
		(end 355.077522 -215.931242)
		(width 0.0889)
		(layer "In11.Cu")
		(net "P5E_CPU0_PE1_RX_DN<11>")
	)
	(segment
		(start 353.362768 -205.92542)
		(end 354.744528 -211.816188)
		(width 0.14732)
		(layer "In11.Cu")
		(net "P5E_CPU0_PE1_RX_DN<11>")
	)
	(segment
		(start 356.423214 -221.587568)
		(end 356.447344 -221.676722)
		(width 0.0889)
		(layer "In11.Cu")
		(net "P5E_CPU0_PE1_RX_DN<11>")
	)
	(segment
		(start 402.811234 -19.988784)
		(end 405.772112 -75.89139)
		(width 0.14732)
		(layer "In11.Cu")
		(net "P5E_CPU0_PE1_RX_DN<11>")
	)
	(segment
		(start 355.547168 -219.0115)
		(end 355.538278 -219.01658)
		(width 0.0889)
		(layer "In11.Cu")
		(net "P5E_CPU0_PE1_RX_DN<11>")
	)
	(segment
		(start 355.256084 -219.490544)
		(end 355.256084 -219.521532)
		(width 0.0889)
		(layer "In11.Cu")
		(net "P5E_CPU0_PE1_RX_DN<11>")
	)
	(segment
		(start 400.724116 -6.713474)
		(end 401.018756 -7.008114)
		(width 0.14732)
		(layer "In11.Cu")
		(net "P5E_CPU0_PE1_RX_DN<11>")
	)
	(segment
		(start 355.547168 -217.383614)
		(end 355.538278 -217.388694)
		(width 0.0889)
		(layer "In11.Cu")
		(net "P5E_CPU0_PE1_RX_DN<11>")
	)
	(segment
		(start 355.538278 -218.367864)
		(end 355.539294 -218.368372)
		(width 0.0889)
		(layer "In11.Cu")
		(net "P5E_CPU0_PE1_RX_DN<11>")
	)
	(segment
		(start 401.018756 -7.008114)
		(end 401.018756 -12.454128)
		(width 0.14732)
		(layer "In11.Cu")
		(net "P5E_CPU0_PE1_RX_DN<11>")
	)
	(segment
		(start 345.493594 -163.25596)
		(end 342.482424 -172.806614)
		(width 0.14732)
		(layer "In11.Cu")
		(net "P5E_CPU0_PE1_RX_DN<11>")
	)
	(segment
		(start 355.077014 -214.941912)
		(end 355.068124 -214.946992)
		(width 0.0889)
		(layer "In11.Cu")
		(net "P5E_CPU0_PE1_RX_DN<11>")
	)
	(segment
		(start 356.008432 -220.809566)
		(end 356.017322 -220.814646)
		(width 0.0889)
		(layer "In11.Cu")
		(net "P5E_CPU0_PE1_RX_DN<11>")
	)
	(segment
		(start 342.482424 -172.806614)
		(end 342.482424 -174.224188)
		(width 0.14732)
		(layer "In11.Cu")
		(net "P5E_CPU0_PE1_RX_DN<11>")
	)
	(segment
		(start 355.72573 -220.319854)
		(end 355.72573 -220.327474)
		(width 0.0889)
		(layer "In11.Cu")
		(net "P5E_CPU0_PE1_RX_DN<11>")
	)
	(segment
		(start 402.72716 -19.826478)
		(end 402.811234 -19.988784)
		(width 0.14732)
		(layer "In11.Cu")
		(net "P5E_CPU0_PE1_RX_DN<11>")
	)
	(arc
		(start 356.195884 -221.149418)
		(mid 356.254437 -221.385148)
		(end 356.40645 -221.574614)
		(width 0.0889)
		(layer "In11.Cu")
		(net "P5E_CPU0_PE1_RX_DN<11>")
	)
	(arc
		(start 356.40645 -221.574614)
		(mid 356.41477 -221.581171)
		(end 356.423214 -221.587568)
		(width 0.0889)
		(layer "In11.Cu")
		(net "P5E_CPU0_PE1_RX_DN<11>")
	)
	(arc
		(start 355.72573 -220.327474)
		(mid 355.803359 -220.605887)
		(end 356.008432 -220.809566)
		(width 0.0889)
		(layer "In11.Cu")
		(net "P5E_CPU0_PE1_RX_DN<11>")
	)
	(arc
		(start 355.547168 -220.000576)
		(mid 355.678082 -220.136936)
		(end 355.72573 -220.319854)
		(width 0.0889)
		(layer "In11.Cu")
		(net "P5E_CPU0_PE1_RX_DN<11>")
	)
	(arc
		(start 355.538278 -219.01658)
		(mid 355.335455 -219.216811)
		(end 355.256084 -219.490544)
		(width 0.0889)
		(layer "In11.Cu")
		(net "P5E_CPU0_PE1_RX_DN<11>")
	)
	(arc
		(start 355.256084 -217.8939)
		(mid 355.335454 -218.167634)
		(end 355.538278 -218.367864)
		(width 0.0889)
		(layer "In11.Cu")
		(net "P5E_CPU0_PE1_RX_DN<11>")
	)
	(arc
		(start 354.78593 -215.436704)
		(mid 354.859921 -215.71627)
		(end 355.062536 -215.922606)
		(width 0.0889)
		(layer "In11.Cu")
		(net "P5E_CPU0_PE1_RX_DN<11>")
	)
	(arc
		(start 354.79736 -213.959948)
		(mid 354.907884 -214.135009)
		(end 355.071426 -214.261954)
		(width 0.0889)
		(layer "In11.Cu")
		(net "P5E_CPU0_PE1_RX_DN<11>")
	)
	(arc
		(start 355.547168 -218.372944)
		(mid 355.725644 -218.692222)
		(end 355.547168 -219.0115)
		(width 0.0889)
		(layer "In11.Cu")
		(net "P5E_CPU0_PE1_RX_DN<11>")
	)
	(arc
		(start 355.071426 -214.261954)
		(mid 355.180573 -214.345882)
		(end 355.255576 -214.461344)
		(width 0.0889)
		(layer "In11.Cu")
		(net "P5E_CPU0_PE1_RX_DN<11>")
	)
	(arc
		(start 355.256084 -216.266014)
		(mid 355.335454 -216.539748)
		(end 355.538278 -216.739978)
		(width 0.0889)
		(layer "In11.Cu")
		(net "P5E_CPU0_PE1_RX_DN<11>")
	)
	(arc
		(start 355.256084 -219.521532)
		(mid 355.335454 -219.795266)
		(end 355.538278 -219.995496)
		(width 0.0889)
		(layer "In11.Cu")
		(net "P5E_CPU0_PE1_RX_DN<11>")
	)
	(arc
		(start 355.255576 -214.622634)
		(mid 355.207897 -214.805534)
		(end 355.077014 -214.941912)
		(width 0.0889)
		(layer "In11.Cu")
		(net "P5E_CPU0_PE1_RX_DN<11>")
	)
	(arc
		(start 355.547168 -216.745058)
		(mid 355.725765 -217.064336)
		(end 355.547168 -217.383614)
		(width 0.0889)
		(layer "In11.Cu")
		(net "P5E_CPU0_PE1_RX_DN<11>")
	)
	(arc
		(start 355.077522 -215.931242)
		(mid 355.208436 -216.067602)
		(end 355.256084 -216.25052)
		(width 0.0889)
		(layer "In11.Cu")
		(net "P5E_CPU0_PE1_RX_DN<11>")
	)
	(arc
		(start 356.017322 -220.814646)
		(mid 356.148236 -220.951006)
		(end 356.195884 -221.133924)
		(width 0.0889)
		(layer "In11.Cu")
		(net "P5E_CPU0_PE1_RX_DN<11>")
	)
	(arc
		(start 355.538278 -217.388694)
		(mid 355.336996 -217.586181)
		(end 355.256084 -217.856308)
		(width 0.0889)
		(layer "In11.Cu")
		(net "P5E_CPU0_PE1_RX_DN<11>")
	)
	(arc
		(start 355.068124 -214.946992)
		(mid 354.866842 -215.144479)
		(end 354.78593 -215.414606)
		(width 0.0889)
		(layer "In11.Cu")
		(net "P5E_CPU0_PE1_RX_DN<11>")
	)
	(arc
		(start 354.786438 -213.929468)
		(mid 354.791947 -213.944659)
		(end 354.797868 -213.959694)
		(width 0.0889)
		(layer "In11.Cu")
		(net "P5E_CPU0_PE1_RX_DN<11>")
	)
	(segment
		(start 402.83003 -5.252974)
		(end 402.528786 -4.95173)
		(width 0.13208)
		(layer "F.Cu")
		(net "P5E_CPU0_PE1_RX_DN<10>")
	)
	(segment
		(start 402.83003 -7.601204)
		(end 402.83003 -5.252974)
		(width 0.13208)
		(layer "F.Cu")
		(net "P5E_CPU0_PE1_RX_DN<10>")
	)
	(segment
		(start 402.646896 -7.784338)
		(end 402.83003 -7.601204)
		(width 0.13208)
		(layer "F.Cu")
		(net "P5E_CPU0_PE1_RX_DN<10>")
	)
	(segment
		(start 357.70058 -221.669864)
		(end 357.700834 -221.133924)
		(width 0.13208)
		(layer "F.Cu")
		(net "P5E_CPU0_PE1_RX_DN<10>")
	)
	(segment
		(start 402.646896 -8.320024)
		(end 402.646896 -7.784338)
		(width 0.13208)
		(layer "F.Cu")
		(net "P5E_CPU0_PE1_RX_DN<10>")
	)
	(segment
		(start 356.666292 -213.92261)
		(end 356.511098 -214.077804)
		(width 0.0889)
		(layer "In11.Cu")
		(net "P5E_CPU0_PE1_RX_DN<10>")
	)
	(segment
		(start 405.999188 -18.863564)
		(end 406.208484 -19.956272)
		(width 0.14732)
		(layer "In11.Cu")
		(net "P5E_CPU0_PE1_RX_DN<10>")
	)
	(segment
		(start 406.208484 -19.956272)
		(end 406.248616 -50.541428)
		(width 0.14732)
		(layer "In11.Cu")
		(net "P5E_CPU0_PE1_RX_DN<10>")
	)
	(segment
		(start 402.528786 -4.95173)
		(end 402.823426 -5.24637)
		(width 0.14732)
		(layer "In11.Cu")
		(net "P5E_CPU0_PE1_RX_DN<10>")
	)
	(segment
		(start 357.455216 -220.83903)
		(end 357.54437 -220.862906)
		(width 0.0889)
		(layer "In11.Cu")
		(net "P5E_CPU0_PE1_RX_DN<10>")
	)
	(segment
		(start 356.624382 -212.954108)
		(end 356.666292 -212.996018)
		(width 0.0889)
		(layer "In11.Cu")
		(net "P5E_CPU0_PE1_RX_DN<10>")
	)
	(segment
		(start 406.814274 -76.151486)
		(end 405.806656 -78.749398)
		(width 0.14732)
		(layer "In11.Cu")
		(net "P5E_CPU0_PE1_RX_DN<10>")
	)
	(segment
		(start 355.72573 -215.414606)
		(end 355.72573 -215.436704)
		(width 0.0889)
		(layer "In11.Cu")
		(net "P5E_CPU0_PE1_RX_DN<10>")
	)
	(segment
		(start 357.54437 -220.862906)
		(end 357.700834 -221.133924)
		(width 0.0889)
		(layer "In11.Cu")
		(net "P5E_CPU0_PE1_RX_DN<10>")
	)
	(segment
		(start 346.333572 -163.684712)
		(end 343.418414 -172.931328)
		(width 0.14732)
		(layer "In11.Cu")
		(net "P5E_CPU0_PE1_RX_DN<10>")
	)
	(segment
		(start 356.195884 -216.25052)
		(end 356.195884 -216.260426)
		(width 0.0889)
		(layer "In11.Cu")
		(net "P5E_CPU0_PE1_RX_DN<10>")
	)
	(segment
		(start 343.418414 -174.028862)
		(end 356.624382 -212.414866)
		(width 0.14732)
		(layer "In11.Cu")
		(net "P5E_CPU0_PE1_RX_DN<10>")
	)
	(segment
		(start 402.823426 -5.24637)
		(end 402.823426 -12.0523)
		(width 0.14732)
		(layer "In11.Cu")
		(net "P5E_CPU0_PE1_RX_DN<10>")
	)
	(segment
		(start 406.60828 -61.983366)
		(end 406.814274 -76.151486)
		(width 0.14732)
		(layer "In11.Cu")
		(net "P5E_CPU0_PE1_RX_DN<10>")
	)
	(segment
		(start 356.195884 -214.427054)
		(end 356.195884 -214.62238)
		(width 0.0889)
		(layer "In11.Cu")
		(net "P5E_CPU0_PE1_RX_DN<10>")
	)
	(segment
		(start 356.009956 -215.926924)
		(end 356.017322 -215.931242)
		(width 0.0889)
		(layer "In11.Cu")
		(net "P5E_CPU0_PE1_RX_DN<10>")
	)
	(segment
		(start 356.195884 -214.62238)
		(end 356.19563 -214.622634)
		(width 0.0889)
		(layer "In11.Cu")
		(net "P5E_CPU0_PE1_RX_DN<10>")
	)
	(segment
		(start 406.60828 -61.711586)
		(end 406.60828 -61.983366)
		(width 0.14732)
		(layer "In11.Cu")
		(net "P5E_CPU0_PE1_RX_DN<10>")
	)
	(segment
		(start 356.195884 -217.859864)
		(end 356.195884 -217.8939)
		(width 0.0889)
		(layer "In11.Cu")
		(net "P5E_CPU0_PE1_RX_DN<10>")
	)
	(segment
		(start 356.478078 -218.367864)
		(end 356.486968 -218.372944)
		(width 0.0889)
		(layer "In11.Cu")
		(net "P5E_CPU0_PE1_RX_DN<10>")
	)
	(segment
		(start 356.02291 -214.938356)
		(end 356.007924 -214.946992)
		(width 0.0889)
		(layer "In11.Cu")
		(net "P5E_CPU0_PE1_RX_DN<10>")
	)
	(segment
		(start 356.195884 -219.490544)
		(end 356.195884 -219.515944)
		(width 0.0889)
		(layer "In11.Cu")
		(net "P5E_CPU0_PE1_RX_DN<10>")
	)
	(segment
		(start 356.002336 -215.922606)
		(end 356.00767 -215.925654)
		(width 0.0889)
		(layer "In11.Cu")
		(net "P5E_CPU0_PE1_RX_DN<10>")
	)
	(segment
		(start 356.511098 -214.077804)
		(end 356.48138 -214.093552)
		(width 0.0889)
		(layer "In11.Cu")
		(net "P5E_CPU0_PE1_RX_DN<10>")
	)
	(segment
		(start 405.806656 -78.749398)
		(end 346.333572 -163.684712)
		(width 0.14732)
		(layer "In11.Cu")
		(net "P5E_CPU0_PE1_RX_DN<10>")
	)
	(segment
		(start 356.66553 -220.311218)
		(end 356.66553 -220.334078)
		(width 0.0889)
		(layer "In11.Cu")
		(net "P5E_CPU0_PE1_RX_DN<10>")
	)
	(segment
		(start 356.666292 -212.996018)
		(end 356.666292 -213.92261)
		(width 0.0889)
		(layer "In11.Cu")
		(net "P5E_CPU0_PE1_RX_DN<10>")
	)
	(segment
		(start 356.008432 -215.926162)
		(end 356.009956 -215.926924)
		(width 0.0889)
		(layer "In11.Cu")
		(net "P5E_CPU0_PE1_RX_DN<10>")
	)
	(segment
		(start 343.418414 -172.931328)
		(end 343.418414 -174.028862)
		(width 0.14732)
		(layer "In11.Cu")
		(net "P5E_CPU0_PE1_RX_DN<10>")
	)
	(segment
		(start 356.624382 -212.93201)
		(end 356.624382 -212.954108)
		(width 0.0889)
		(layer "In11.Cu")
		(net "P5E_CPU0_PE1_RX_DN<10>")
	)
	(segment
		(start 406.248616 -50.541428)
		(end 406.60828 -61.711586)
		(width 0.14732)
		(layer "In11.Cu")
		(net "P5E_CPU0_PE1_RX_DN<10>")
	)
	(segment
		(start 356.624382 -212.414866)
		(end 356.624382 -212.93201)
		(width 0.14732)
		(layer "In11.Cu")
		(net "P5E_CPU0_PE1_RX_DN<10>")
	)
	(segment
		(start 356.948232 -220.809566)
		(end 356.962964 -220.818202)
		(width 0.0889)
		(layer "In11.Cu")
		(net "P5E_CPU0_PE1_RX_DN<10>")
	)
	(segment
		(start 356.66553 -217.0557)
		(end 356.66553 -217.072972)
		(width 0.0889)
		(layer "In11.Cu")
		(net "P5E_CPU0_PE1_RX_DN<10>")
	)
	(segment
		(start 402.823426 -12.0523)
		(end 405.56815 -18.218912)
		(width 0.14732)
		(layer "In11.Cu")
		(net "P5E_CPU0_PE1_RX_DN<10>")
	)
	(segment
		(start 356.00767 -215.925654)
		(end 356.008432 -215.926162)
		(width 0.0889)
		(layer "In11.Cu")
		(net "P5E_CPU0_PE1_RX_DN<10>")
	)
	(segment
		(start 356.486968 -219.0115)
		(end 356.478078 -219.01658)
		(width 0.0889)
		(layer "In11.Cu")
		(net "P5E_CPU0_PE1_RX_DN<10>")
	)
	(segment
		(start 405.56815 -18.218912)
		(end 405.999188 -18.863564)
		(width 0.14732)
		(layer "In11.Cu")
		(net "P5E_CPU0_PE1_RX_DN<10>")
	)
	(arc
		(start 356.19563 -214.622634)
		(mid 356.149626 -214.802571)
		(end 356.02291 -214.938356)
		(width 0.0889)
		(layer "In11.Cu")
		(net "P5E_CPU0_PE1_RX_DN<10>")
	)
	(arc
		(start 356.478332 -219.995496)
		(mid 356.613265 -220.12885)
		(end 356.66553 -220.311218)
		(width 0.0889)
		(layer "In11.Cu")
		(net "P5E_CPU0_PE1_RX_DN<10>")
	)
	(arc
		(start 356.195884 -217.8939)
		(mid 356.275254 -218.167634)
		(end 356.478078 -218.367864)
		(width 0.0889)
		(layer "In11.Cu")
		(net "P5E_CPU0_PE1_RX_DN<10>")
	)
	(arc
		(start 355.72573 -215.436704)
		(mid 355.799721 -215.71627)
		(end 356.002336 -215.922606)
		(width 0.0889)
		(layer "In11.Cu")
		(net "P5E_CPU0_PE1_RX_DN<10>")
	)
	(arc
		(start 356.66553 -220.334078)
		(mid 356.744749 -220.608763)
		(end 356.948232 -220.809566)
		(width 0.0889)
		(layer "In11.Cu")
		(net "P5E_CPU0_PE1_RX_DN<10>")
	)
	(arc
		(start 356.195884 -219.515944)
		(mid 356.273995 -219.792893)
		(end 356.478332 -219.995496)
		(width 0.0889)
		(layer "In11.Cu")
		(net "P5E_CPU0_PE1_RX_DN<10>")
	)
	(arc
		(start 356.486968 -218.372944)
		(mid 356.665444 -218.692222)
		(end 356.486968 -219.0115)
		(width 0.0889)
		(layer "In11.Cu")
		(net "P5E_CPU0_PE1_RX_DN<10>")
	)
	(arc
		(start 356.007924 -214.946992)
		(mid 355.806642 -215.144479)
		(end 355.72573 -215.414606)
		(width 0.0889)
		(layer "In11.Cu")
		(net "P5E_CPU0_PE1_RX_DN<10>")
	)
	(arc
		(start 356.195884 -216.260426)
		(mid 356.273995 -216.537375)
		(end 356.478332 -216.739978)
		(width 0.0889)
		(layer "In11.Cu")
		(net "P5E_CPU0_PE1_RX_DN<10>")
	)
	(arc
		(start 356.66553 -217.072972)
		(mid 356.61326 -217.255337)
		(end 356.478332 -217.388694)
		(width 0.0889)
		(layer "In11.Cu")
		(net "P5E_CPU0_PE1_RX_DN<10>")
	)
	(arc
		(start 356.478078 -219.01658)
		(mid 356.275255 -219.216811)
		(end 356.195884 -219.490544)
		(width 0.0889)
		(layer "In11.Cu")
		(net "P5E_CPU0_PE1_RX_DN<10>")
	)
	(arc
		(start 356.48138 -214.093552)
		(mid 356.306926 -214.233161)
		(end 356.195884 -214.427054)
		(width 0.0889)
		(layer "In11.Cu")
		(net "P5E_CPU0_PE1_RX_DN<10>")
	)
	(arc
		(start 357.43515 -220.847158)
		(mid 357.445223 -220.843192)
		(end 357.455216 -220.83903)
		(width 0.0889)
		(layer "In11.Cu")
		(net "P5E_CPU0_PE1_RX_DN<10>")
	)
	(arc
		(start 356.478332 -217.388694)
		(mid 356.276046 -217.587675)
		(end 356.195884 -217.859864)
		(width 0.0889)
		(layer "In11.Cu")
		(net "P5E_CPU0_PE1_RX_DN<10>")
	)
	(arc
		(start 356.017322 -215.931242)
		(mid 356.148236 -216.067602)
		(end 356.195884 -216.25052)
		(width 0.0889)
		(layer "In11.Cu")
		(net "P5E_CPU0_PE1_RX_DN<10>")
	)
	(arc
		(start 356.478332 -216.739978)
		(mid 356.613265 -216.873332)
		(end 356.66553 -217.0557)
		(width 0.0889)
		(layer "In11.Cu")
		(net "P5E_CPU0_PE1_RX_DN<10>")
	)
	(arc
		(start 356.962964 -220.818202)
		(mid 357.195879 -220.884383)
		(end 357.43515 -220.847158)
		(width 0.0889)
		(layer "In11.Cu")
		(net "P5E_CPU0_PE1_RX_DN<10>")
	)
	(segment
		(start 430.609248 -7.603744)
		(end 430.609248 -5.255006)
		(width 0.13208)
		(layer "F.Cu")
		(net "P5E_CPU0_PE1_RX_DN<0>")
	)
	(segment
		(start 430.609248 -5.255006)
		(end 430.912524 -4.95173)
		(width 0.13208)
		(layer "F.Cu")
		(net "P5E_CPU0_PE1_RX_DN<0>")
	)
	(segment
		(start 430.766982 -8.320024)
		(end 430.766982 -7.761478)
		(width 0.13208)
		(layer "F.Cu")
		(net "P5E_CPU0_PE1_RX_DN<0>")
	)
	(segment
		(start 430.766982 -7.761478)
		(end 430.609248 -7.603744)
		(width 0.13208)
		(layer "F.Cu")
		(net "P5E_CPU0_PE1_RX_DN<0>")
	)
	(segment
		(start 367.09858 -221.669864)
		(end 367.098834 -221.133924)
		(width 0.13208)
		(layer "F.Cu")
		(net "P5E_CPU0_PE1_RX_DN<0>")
	)
	(segment
		(start 366.515904 -213.149434)
		(end 366.515904 -214.21471)
		(width 0.14732)
		(layer "In11.Cu")
		(net "P5E_CPU0_PE1_RX_DN<0>")
	)
	(segment
		(start 366.434624 -218.371674)
		(end 366.432592 -218.372944)
		(width 0.0889)
		(layer "In11.Cu")
		(net "P5E_CPU0_PE1_RX_DN<0>")
	)
	(segment
		(start 430.713388 -12.852908)
		(end 432.76266 -15.870936)
		(width 0.14732)
		(layer "In11.Cu")
		(net "P5E_CPU0_PE1_RX_DN<0>")
	)
	(segment
		(start 366.436402 -219.013786)
		(end 366.439958 -219.015818)
		(width 0.0889)
		(layer "In11.Cu")
		(net "P5E_CPU0_PE1_RX_DN<0>")
	)
	(segment
		(start 366.515904 -214.21471)
		(end 366.515904 -214.236808)
		(width 0.0889)
		(layer "In11.Cu")
		(net "P5E_CPU0_PE1_RX_DN<0>")
	)
	(segment
		(start 425.882562 -27.817826)
		(end 425.412154 -28.867862)
		(width 0.14732)
		(layer "In11.Cu")
		(net "P5E_CPU0_PE1_RX_DN<0>")
	)
	(segment
		(start 430.912524 -4.95173)
		(end 430.617884 -5.24637)
		(width 0.14732)
		(layer "In11.Cu")
		(net "P5E_CPU0_PE1_RX_DN<0>")
	)
	(segment
		(start 434.6702 -19.304508)
		(end 434.379116 -20.007072)
		(width 0.14732)
		(layer "In11.Cu")
		(net "P5E_CPU0_PE1_RX_DN<0>")
	)
	(segment
		(start 366.94237 -220.862906)
		(end 367.098834 -221.133924)
		(width 0.0889)
		(layer "In11.Cu")
		(net "P5E_CPU0_PE1_RX_DN<0>")
	)
	(segment
		(start 366.444022 -219.018104)
		(end 366.447578 -219.020136)
		(width 0.0889)
		(layer "In11.Cu")
		(net "P5E_CPU0_PE1_RX_DN<0>")
	)
	(segment
		(start 366.25403 -215.283034)
		(end 366.25403 -215.452198)
		(width 0.0889)
		(layer "In11.Cu")
		(net "P5E_CPU0_PE1_RX_DN<0>")
	)
	(segment
		(start 367.194084 -220.319854)
		(end 367.194084 -220.334078)
		(width 0.0889)
		(layer "In11.Cu")
		(net "P5E_CPU0_PE1_RX_DN<0>")
	)
	(segment
		(start 432.763168 -15.87119)
		(end 433.97932 -17.664176)
		(width 0.14732)
		(layer "In11.Cu")
		(net "P5E_CPU0_PE1_RX_DN<0>")
	)
	(segment
		(start 366.439958 -218.368626)
		(end 366.437926 -218.369896)
		(width 0.0889)
		(layer "In11.Cu")
		(net "P5E_CPU0_PE1_RX_DN<0>")
	)
	(segment
		(start 430.617884 -5.24637)
		(end 430.617884 -12.542266)
		(width 0.14732)
		(layer "In11.Cu")
		(net "P5E_CPU0_PE1_RX_DN<0>")
	)
	(segment
		(start 432.76266 -15.870936)
		(end 432.763168 -15.87119)
		(width 0.14732)
		(layer "In11.Cu")
		(net "P5E_CPU0_PE1_RX_DN<0>")
	)
	(segment
		(start 366.254284 -217.05443)
		(end 366.254284 -217.072972)
		(width 0.0889)
		(layer "In11.Cu")
		(net "P5E_CPU0_PE1_RX_DN<0>")
	)
	(segment
		(start 366.442244 -218.367356)
		(end 366.441482 -218.367864)
		(width 0.0889)
		(layer "In11.Cu")
		(net "P5E_CPU0_PE1_RX_DN<0>")
	)
	(segment
		(start 366.515904 -214.236808)
		(end 366.47374 -214.278972)
		(width 0.0889)
		(layer "In11.Cu")
		(net "P5E_CPU0_PE1_RX_DN<0>")
	)
	(segment
		(start 366.447578 -218.364308)
		(end 366.442244 -218.367356)
		(width 0.0889)
		(layer "In11.Cu")
		(net "P5E_CPU0_PE1_RX_DN<0>")
	)
	(segment
		(start 433.97932 -17.664176)
		(end 433.979828 -17.663922)
		(width 0.14732)
		(layer "In11.Cu")
		(net "P5E_CPU0_PE1_RX_DN<0>")
	)
	(segment
		(start 366.441482 -218.367864)
		(end 366.439958 -218.368626)
		(width 0.0889)
		(layer "In11.Cu")
		(net "P5E_CPU0_PE1_RX_DN<0>")
	)
	(segment
		(start 366.441482 -219.01658)
		(end 366.444022 -219.018104)
		(width 0.0889)
		(layer "In11.Cu")
		(net "P5E_CPU0_PE1_RX_DN<0>")
	)
	(segment
		(start 366.902746 -219.825316)
		(end 366.911636 -219.830396)
		(width 0.0889)
		(layer "In11.Cu")
		(net "P5E_CPU0_PE1_RX_DN<0>")
	)
	(segment
		(start 366.432592 -219.0115)
		(end 366.436402 -219.013786)
		(width 0.0889)
		(layer "In11.Cu")
		(net "P5E_CPU0_PE1_RX_DN<0>")
	)
	(segment
		(start 417.681156 -78.11135)
		(end 368.954558 -164.18179)
		(width 0.14732)
		(layer "In11.Cu")
		(net "P5E_CPU0_PE1_RX_DN<0>")
	)
	(segment
		(start 434.6702 -18.680684)
		(end 434.6702 -19.304508)
		(width 0.14732)
		(layer "In11.Cu")
		(net "P5E_CPU0_PE1_RX_DN<0>")
	)
	(segment
		(start 433.979828 -17.663922)
		(end 434.6702 -18.680684)
		(width 0.14732)
		(layer "In11.Cu")
		(net "P5E_CPU0_PE1_RX_DN<0>")
	)
	(segment
		(start 366.9665 -220.773752)
		(end 366.94237 -220.862906)
		(width 0.0889)
		(layer "In11.Cu")
		(net "P5E_CPU0_PE1_RX_DN<0>")
	)
	(segment
		(start 366.300004 -212.063584)
		(end 366.515904 -213.149434)
		(width 0.14732)
		(layer "In11.Cu")
		(net "P5E_CPU0_PE1_RX_DN<0>")
	)
	(segment
		(start 366.911636 -219.830396)
		(end 366.917732 -219.833952)
		(width 0.0889)
		(layer "In11.Cu")
		(net "P5E_CPU0_PE1_RX_DN<0>")
	)
	(segment
		(start 366.47374 -214.278972)
		(end 366.47374 -214.750904)
		(width 0.0889)
		(layer "In11.Cu")
		(net "P5E_CPU0_PE1_RX_DN<0>")
	)
	(segment
		(start 430.617884 -12.542266)
		(end 430.713388 -12.852908)
		(width 0.14732)
		(layer "In11.Cu")
		(net "P5E_CPU0_PE1_RX_DN<0>")
	)
	(segment
		(start 365.962946 -216.569798)
		(end 365.971836 -216.574878)
		(width 0.0889)
		(layer "In11.Cu")
		(net "P5E_CPU0_PE1_RX_DN<0>")
	)
	(segment
		(start 366.439958 -219.015818)
		(end 366.441482 -219.01658)
		(width 0.0889)
		(layer "In11.Cu")
		(net "P5E_CPU0_PE1_RX_DN<0>")
	)
	(segment
		(start 366.253776 -215.283542)
		(end 366.25403 -215.283034)
		(width 0.0889)
		(layer "In11.Cu")
		(net "P5E_CPU0_PE1_RX_DN<0>")
	)
	(segment
		(start 368.097562 -185.420762)
		(end 366.300004 -212.063584)
		(width 0.14732)
		(layer "In11.Cu")
		(net "P5E_CPU0_PE1_RX_DN<0>")
	)
	(segment
		(start 365.971836 -215.926162)
		(end 365.97082 -215.92667)
		(width 0.0889)
		(layer "In11.Cu")
		(net "P5E_CPU0_PE1_RX_DN<0>")
	)
	(segment
		(start 434.379116 -20.007072)
		(end 425.882562 -27.817826)
		(width 0.14732)
		(layer "In11.Cu")
		(net "P5E_CPU0_PE1_RX_DN<0>")
	)
	(segment
		(start 366.724184 -217.864182)
		(end 366.724184 -217.878406)
		(width 0.0889)
		(layer "In11.Cu")
		(net "P5E_CPU0_PE1_RX_DN<0>")
	)
	(segment
		(start 366.47374 -214.750904)
		(end 366.253776 -215.283542)
		(width 0.0889)
		(layer "In11.Cu")
		(net "P5E_CPU0_PE1_RX_DN<0>")
	)
	(segment
		(start 368.954558 -164.18179)
		(end 368.097562 -185.420762)
		(width 0.14732)
		(layer "In11.Cu")
		(net "P5E_CPU0_PE1_RX_DN<0>")
	)
	(segment
		(start 425.412154 -28.867862)
		(end 417.681156 -78.11135)
		(width 0.14732)
		(layer "In11.Cu")
		(net "P5E_CPU0_PE1_RX_DN<0>")
	)
	(segment
		(start 365.97082 -215.92667)
		(end 365.962946 -215.931242)
		(width 0.0889)
		(layer "In11.Cu")
		(net "P5E_CPU0_PE1_RX_DN<0>")
	)
	(segment
		(start 366.437926 -218.369896)
		(end 366.434624 -218.371674)
		(width 0.0889)
		(layer "In11.Cu")
		(net "P5E_CPU0_PE1_RX_DN<0>")
	)
	(arc
		(start 365.784638 -216.24036)
		(mid 365.784544 -216.248742)
		(end 365.784638 -216.257124)
		(width 0.0889)
		(layer "In11.Cu")
		(net "P5E_CPU0_PE1_RX_DN<0>")
	)
	(arc
		(start 365.962946 -215.931242)
		(mid 365.834627 -216.063214)
		(end 365.784638 -216.24036)
		(width 0.0889)
		(layer "In11.Cu")
		(net "P5E_CPU0_PE1_RX_DN<0>")
	)
	(arc
		(start 366.724184 -217.878406)
		(mid 366.650193 -218.157972)
		(end 366.447578 -218.364308)
		(width 0.0889)
		(layer "In11.Cu")
		(net "P5E_CPU0_PE1_RX_DN<0>")
	)
	(arc
		(start 365.784638 -216.257124)
		(mid 365.833837 -216.43623)
		(end 365.962946 -216.569798)
		(width 0.0889)
		(layer "In11.Cu")
		(net "P5E_CPU0_PE1_RX_DN<0>")
	)
	(arc
		(start 365.971836 -216.574878)
		(mid 366.176171 -216.777483)
		(end 366.254284 -217.05443)
		(width 0.0889)
		(layer "In11.Cu")
		(net "P5E_CPU0_PE1_RX_DN<0>")
	)
	(arc
		(start 367.194084 -220.334078)
		(mid 367.135723 -220.570676)
		(end 366.983264 -220.760798)
		(width 0.0889)
		(layer "In11.Cu")
		(net "P5E_CPU0_PE1_RX_DN<0>")
	)
	(arc
		(start 366.917732 -219.833952)
		(mid 367.120145 -220.040365)
		(end 367.194084 -220.319854)
		(width 0.0889)
		(layer "In11.Cu")
		(net "P5E_CPU0_PE1_RX_DN<0>")
	)
	(arc
		(start 366.724184 -219.506038)
		(mid 366.771863 -219.688938)
		(end 366.902746 -219.825316)
		(width 0.0889)
		(layer "In11.Cu")
		(net "P5E_CPU0_PE1_RX_DN<0>")
	)
	(arc
		(start 366.447578 -219.020136)
		(mid 366.650165 -219.226487)
		(end 366.724184 -219.506038)
		(width 0.0889)
		(layer "In11.Cu")
		(net "P5E_CPU0_PE1_RX_DN<0>")
	)
	(arc
		(start 366.25403 -215.452198)
		(mid 366.17466 -215.725932)
		(end 365.971836 -215.926162)
		(width 0.0889)
		(layer "In11.Cu")
		(net "P5E_CPU0_PE1_RX_DN<0>")
	)
	(arc
		(start 366.432592 -218.372944)
		(mid 366.253995 -218.692222)
		(end 366.432592 -219.0115)
		(width 0.0889)
		(layer "In11.Cu")
		(net "P5E_CPU0_PE1_RX_DN<0>")
	)
	(arc
		(start 366.441482 -217.388694)
		(mid 366.644963 -217.589498)
		(end 366.724184 -217.864182)
		(width 0.0889)
		(layer "In11.Cu")
		(net "P5E_CPU0_PE1_RX_DN<0>")
	)
	(arc
		(start 366.983264 -220.760798)
		(mid 366.974942 -220.767353)
		(end 366.9665 -220.773752)
		(width 0.0889)
		(layer "In11.Cu")
		(net "P5E_CPU0_PE1_RX_DN<0>")
	)
	(arc
		(start 366.254284 -217.072972)
		(mid 366.306554 -217.255337)
		(end 366.441482 -217.388694)
		(width 0.0889)
		(layer "In11.Cu")
		(net "P5E_CPU0_PE1_RX_DN<0>")
	)
	(segment
		(start 324.569328 -407.00452)
		(end 324.27037 -407.303478)
		(width 0.13208)
		(layer "F.Cu")
		(net "P5E_CPU0_PE0_TX_DP<9>")
	)
	(segment
		(start 324.27037 -407.926286)
		(end 324.594728 -408.250644)
		(width 0.13208)
		(layer "F.Cu")
		(net "P5E_CPU0_PE0_TX_DP<9>")
	)
	(segment
		(start 346.893134 -225.203512)
		(end 346.89288 -225.203258)
		(width 0.13208)
		(layer "F.Cu")
		(net "P5E_CPU0_PE0_TX_DP<9>")
	)
	(segment
		(start 346.893134 -225.739198)
		(end 346.893134 -225.203512)
		(width 0.13208)
		(layer "F.Cu")
		(net "P5E_CPU0_PE0_TX_DP<9>")
	)
	(segment
		(start 324.27037 -407.303478)
		(end 324.27037 -407.926286)
		(width 0.13208)
		(layer "F.Cu")
		(net "P5E_CPU0_PE0_TX_DP<9>")
	)
	(segment
		(start 344.730324 -214.946992)
		(end 344.739214 -214.941912)
		(width 0.0889)
		(layer "In15.Cu")
		(net "P5E_CPU0_PE0_TX_DP<9>")
	)
	(segment
		(start 319.259458 -382.269492)
		(end 319.382902 -382.688338)
		(width 0.14732)
		(layer "In15.Cu")
		(net "P5E_CPU0_PE0_TX_DP<9>")
	)
	(segment
		(start 342.046052 -210.997038)
		(end 334.940656 -210.997038)
		(width 0.14732)
		(layer "In15.Cu")
		(net "P5E_CPU0_PE0_TX_DP<9>")
	)
	(segment
		(start 344.406474 -213.12251)
		(end 344.406474 -212.75167)
		(width 0.14732)
		(layer "In15.Cu")
		(net "P5E_CPU0_PE0_TX_DP<9>")
	)
	(segment
		(start 325.784718 -218.001596)
		(end 325.784464 -218.00185)
		(width 0.14732)
		(layer "In15.Cu")
		(net "P5E_CPU0_PE0_TX_DP<9>")
	)
	(segment
		(start 346.149168 -223.256348)
		(end 346.141294 -223.251776)
		(width 0.0889)
		(layer "In15.Cu")
		(net "P5E_CPU0_PE0_TX_DP<9>")
	)
	(segment
		(start 319.95872 -384.641852)
		(end 320.081656 -385.059428)
		(width 0.14732)
		(layer "In15.Cu")
		(net "P5E_CPU0_PE0_TX_DP<9>")
	)
	(segment
		(start 345.209368 -218.372944)
		(end 345.201494 -218.368372)
		(width 0.0889)
		(layer "In15.Cu")
		(net "P5E_CPU0_PE0_TX_DP<9>")
	)
	(segment
		(start 319.21958 -381.695452)
		(end 319.343278 -382.114806)
		(width 0.14732)
		(layer "In15.Cu")
		(net "P5E_CPU0_PE0_TX_DP<9>")
	)
	(segment
		(start 320.617596 -250.190762)
		(end 320.532506 -252.720602)
		(width 0.14732)
		(layer "In15.Cu")
		(net "P5E_CPU0_PE0_TX_DP<9>")
	)
	(segment
		(start 320.532506 -252.720602)
		(end 324.150736 -309.5879)
		(width 0.14732)
		(layer "In15.Cu")
		(net "P5E_CPU0_PE0_TX_DP<9>")
	)
	(segment
		(start 344.406474 -213.144608)
		(end 344.406474 -213.12251)
		(width 0.0889)
		(layer "In15.Cu")
		(net "P5E_CPU0_PE0_TX_DP<9>")
	)
	(segment
		(start 308.836314 -331.906118)
		(end 308.836314 -341.35187)
		(width 0.14732)
		(layer "In15.Cu")
		(net "P5E_CPU0_PE0_TX_DP<9>")
	)
	(segment
		(start 323.792088 -221.868238)
		(end 322.060824 -233.019092)
		(width 0.14732)
		(layer "In15.Cu")
		(net "P5E_CPU0_PE0_TX_DP<9>")
	)
	(segment
		(start 344.918284 -216.260426)
		(end 344.918284 -216.25052)
		(width 0.0889)
		(layer "In15.Cu")
		(net "P5E_CPU0_PE0_TX_DP<9>")
	)
	(segment
		(start 344.448384 -213.930484)
		(end 344.448384 -213.929722)
		(width 0.0889)
		(layer "In15.Cu")
		(net "P5E_CPU0_PE0_TX_DP<9>")
	)
	(segment
		(start 346.736416 -224.93224)
		(end 346.647516 -224.908618)
		(width 0.0889)
		(layer "In15.Cu")
		(net "P5E_CPU0_PE0_TX_DP<9>")
	)
	(segment
		(start 344.729308 -215.925146)
		(end 344.728038 -215.924384)
		(width 0.0889)
		(layer "In15.Cu")
		(net "P5E_CPU0_PE0_TX_DP<9>")
	)
	(segment
		(start 324.274688 -405.845264)
		(end 324.274688 -406.70988)
		(width 0.14732)
		(layer "In15.Cu")
		(net "P5E_CPU0_PE0_TX_DP<9>")
	)
	(segment
		(start 324.274688 -406.70988)
		(end 324.569328 -407.00452)
		(width 0.14732)
		(layer "In15.Cu")
		(net "P5E_CPU0_PE0_TX_DP<9>")
	)
	(segment
		(start 319.382902 -382.688338)
		(end 319.382394 -382.688338)
		(width 0.14732)
		(layer "In15.Cu")
		(net "P5E_CPU0_PE0_TX_DP<9>")
	)
	(segment
		(start 344.728038 -215.924384)
		(end 344.724736 -215.922606)
		(width 0.0889)
		(layer "In15.Cu")
		(net "P5E_CPU0_PE0_TX_DP<9>")
	)
	(segment
		(start 320.27622 -385.718812)
		(end 324.460108 -399.912078)
		(width 0.14732)
		(layer "In15.Cu")
		(net "P5E_CPU0_PE0_TX_DP<9>")
	)
	(segment
		(start 320.236596 -385.14528)
		(end 320.360294 -385.56438)
		(width 0.14732)
		(layer "In15.Cu")
		(net "P5E_CPU0_PE0_TX_DP<9>")
	)
	(segment
		(start 345.200478 -219.01658)
		(end 345.209368 -219.0115)
		(width 0.0889)
		(layer "In15.Cu")
		(net "P5E_CPU0_PE0_TX_DP<9>")
	)
	(segment
		(start 319.76441 -383.983992)
		(end 319.919096 -384.068066)
		(width 0.14732)
		(layer "In15.Cu")
		(net "P5E_CPU0_PE0_TX_DP<9>")
	)
	(segment
		(start 344.918284 -217.8939)
		(end 344.918284 -217.859864)
		(width 0.0889)
		(layer "In15.Cu")
		(net "P5E_CPU0_PE0_TX_DP<9>")
	)
	(segment
		(start 346.140278 -223.899984)
		(end 346.141294 -223.899476)
		(width 0.0889)
		(layer "In15.Cu")
		(net "P5E_CPU0_PE0_TX_DP<9>")
	)
	(segment
		(start 319.919096 -384.068066)
		(end 320.042794 -384.48742)
		(width 0.14732)
		(layer "In15.Cu")
		(net "P5E_CPU0_PE0_TX_DP<9>")
	)
	(segment
		(start 345.679522 -222.442278)
		(end 345.664536 -222.433642)
		(width 0.0889)
		(layer "In15.Cu")
		(net "P5E_CPU0_PE0_TX_DP<9>")
	)
	(segment
		(start 343.53754 -211.614766)
		(end 342.046052 -210.997038)
		(width 0.14732)
		(layer "In15.Cu")
		(net "P5E_CPU0_PE0_TX_DP<9>")
	)
	(segment
		(start 319.065402 -381.611378)
		(end 319.064894 -381.611378)
		(width 0.14732)
		(layer "In15.Cu")
		(net "P5E_CPU0_PE0_TX_DP<9>")
	)
	(segment
		(start 334.940656 -210.997038)
		(end 331.113892 -213.069932)
		(width 0.14732)
		(layer "In15.Cu")
		(net "P5E_CPU0_PE0_TX_DP<9>")
	)
	(segment
		(start 346.141294 -223.251776)
		(end 346.140278 -223.251268)
		(width 0.0889)
		(layer "In15.Cu")
		(net "P5E_CPU0_PE0_TX_DP<9>")
	)
	(segment
		(start 345.858084 -222.783654)
		(end 345.858084 -222.761556)
		(width 0.0889)
		(layer "In15.Cu")
		(net "P5E_CPU0_PE0_TX_DP<9>")
	)
	(segment
		(start 319.25895 -382.269492)
		(end 319.259458 -382.269492)
		(width 0.14732)
		(layer "In15.Cu")
		(net "P5E_CPU0_PE0_TX_DP<9>")
	)
	(segment
		(start 331.113892 -213.069932)
		(end 325.784718 -218.001596)
		(width 0.14732)
		(layer "In15.Cu")
		(net "P5E_CPU0_PE0_TX_DP<9>")
	)
	(segment
		(start 315.227716 -325.514716)
		(end 308.836314 -331.906118)
		(width 0.14732)
		(layer "In15.Cu")
		(net "P5E_CPU0_PE0_TX_DP<9>")
	)
	(segment
		(start 322.060824 -233.019092)
		(end 320.617596 -250.190762)
		(width 0.14732)
		(layer "In15.Cu")
		(net "P5E_CPU0_PE0_TX_DP<9>")
	)
	(segment
		(start 320.042794 -384.48742)
		(end 319.95872 -384.641852)
		(width 0.14732)
		(layer "In15.Cu")
		(net "P5E_CPU0_PE0_TX_DP<9>")
	)
	(segment
		(start 320.360294 -385.56438)
		(end 320.27622 -385.718812)
		(width 0.14732)
		(layer "In15.Cu")
		(net "P5E_CPU0_PE0_TX_DP<9>")
	)
	(segment
		(start 319.764156 -383.982468)
		(end 319.76441 -383.983992)
		(width 0.14732)
		(layer "In15.Cu")
		(net "P5E_CPU0_PE0_TX_DP<9>")
	)
	(segment
		(start 319.382394 -382.688338)
		(end 319.53708 -382.772412)
		(width 0.14732)
		(layer "In15.Cu")
		(net "P5E_CPU0_PE0_TX_DP<9>")
	)
	(segment
		(start 344.448638 -213.929468)
		(end 344.448638 -213.186772)
		(width 0.0889)
		(layer "In15.Cu")
		(net "P5E_CPU0_PE0_TX_DP<9>")
	)
	(segment
		(start 318.90208 -380.618492)
		(end 319.025778 -381.037846)
		(width 0.14732)
		(layer "In15.Cu")
		(net "P5E_CPU0_PE0_TX_DP<9>")
	)
	(segment
		(start 344.44813 -215.436704)
		(end 344.44813 -215.414606)
		(width 0.0889)
		(layer "In15.Cu")
		(net "P5E_CPU0_PE0_TX_DP<9>")
	)
	(segment
		(start 344.21699 -212.294216)
		(end 343.53754 -211.614766)
		(width 0.14732)
		(layer "In15.Cu")
		(net "P5E_CPU0_PE0_TX_DP<9>")
	)
	(segment
		(start 344.918284 -221.149418)
		(end 344.918284 -221.115382)
		(width 0.0889)
		(layer "In15.Cu")
		(net "P5E_CPU0_PE0_TX_DP<9>")
	)
	(segment
		(start 319.660778 -383.191766)
		(end 319.576704 -383.346198)
		(width 0.14732)
		(layer "In15.Cu")
		(net "P5E_CPU0_PE0_TX_DP<9>")
	)
	(segment
		(start 345.209368 -221.628462)
		(end 345.200478 -221.623382)
		(width 0.0889)
		(layer "In15.Cu")
		(net "P5E_CPU0_PE0_TX_DP<9>")
	)
	(segment
		(start 346.89288 -225.203258)
		(end 346.736416 -224.93224)
		(width 0.0889)
		(layer "In15.Cu")
		(net "P5E_CPU0_PE0_TX_DP<9>")
	)
	(segment
		(start 324.460108 -399.912078)
		(end 324.460108 -403.961854)
		(width 0.14732)
		(layer "In15.Cu")
		(net "P5E_CPU0_PE0_TX_DP<9>")
	)
	(segment
		(start 344.731594 -215.92667)
		(end 344.729308 -215.925146)
		(width 0.0889)
		(layer "In15.Cu")
		(net "P5E_CPU0_PE0_TX_DP<9>")
	)
	(segment
		(start 318.94145 -381.192532)
		(end 318.941958 -381.192532)
		(width 0.14732)
		(layer "In15.Cu")
		(net "P5E_CPU0_PE0_TX_DP<9>")
	)
	(segment
		(start 320.081656 -385.059428)
		(end 320.08191 -385.060952)
		(width 0.14732)
		(layer "In15.Cu")
		(net "P5E_CPU0_PE0_TX_DP<9>")
	)
	(segment
		(start 319.343278 -382.114806)
		(end 319.25895 -382.269492)
		(width 0.14732)
		(layer "In15.Cu")
		(net "P5E_CPU0_PE0_TX_DP<9>")
	)
	(segment
		(start 344.448384 -213.929722)
		(end 344.448638 -213.929468)
		(width 0.0889)
		(layer "In15.Cu")
		(net "P5E_CPU0_PE0_TX_DP<9>")
	)
	(segment
		(start 308.836314 -341.35187)
		(end 313.860688 -363.957616)
		(width 0.14732)
		(layer "In15.Cu")
		(net "P5E_CPU0_PE0_TX_DP<9>")
	)
	(segment
		(start 324.150736 -309.5879)
		(end 320.811906 -317.540386)
		(width 0.14732)
		(layer "In15.Cu")
		(net "P5E_CPU0_PE0_TX_DP<9>")
	)
	(segment
		(start 344.739722 -215.931242)
		(end 344.731594 -215.92667)
		(width 0.0889)
		(layer "In15.Cu")
		(net "P5E_CPU0_PE0_TX_DP<9>")
	)
	(segment
		(start 319.064894 -381.611378)
		(end 319.21958 -381.695452)
		(width 0.14732)
		(layer "In15.Cu")
		(net "P5E_CPU0_PE0_TX_DP<9>")
	)
	(segment
		(start 346.141294 -223.899476)
		(end 346.149168 -223.894904)
		(width 0.0889)
		(layer "In15.Cu")
		(net "P5E_CPU0_PE0_TX_DP<9>")
	)
	(segment
		(start 313.860688 -363.957616)
		(end 318.747648 -380.534672)
		(width 0.14732)
		(layer "In15.Cu")
		(net "P5E_CPU0_PE0_TX_DP<9>")
	)
	(segment
		(start 318.941958 -381.192532)
		(end 319.065402 -381.611378)
		(width 0.14732)
		(layer "In15.Cu")
		(net "P5E_CPU0_PE0_TX_DP<9>")
	)
	(segment
		(start 345.858084 -224.404936)
		(end 345.858084 -224.373948)
		(width 0.0889)
		(layer "In15.Cu")
		(net "P5E_CPU0_PE0_TX_DP<9>")
	)
	(segment
		(start 344.448638 -213.186772)
		(end 344.406474 -213.144608)
		(width 0.0889)
		(layer "In15.Cu")
		(net "P5E_CPU0_PE0_TX_DP<9>")
	)
	(segment
		(start 324.460108 -403.961854)
		(end 324.274688 -405.845264)
		(width 0.14732)
		(layer "In15.Cu")
		(net "P5E_CPU0_PE0_TX_DP<9>")
	)
	(segment
		(start 318.747648 -380.534672)
		(end 318.90208 -380.618492)
		(width 0.14732)
		(layer "In15.Cu")
		(net "P5E_CPU0_PE0_TX_DP<9>")
	)
	(segment
		(start 319.53708 -382.772412)
		(end 319.660778 -383.191766)
		(width 0.14732)
		(layer "In15.Cu")
		(net "P5E_CPU0_PE0_TX_DP<9>")
	)
	(segment
		(start 325.784464 -218.00185)
		(end 323.792088 -221.868238)
		(width 0.14732)
		(layer "In15.Cu")
		(net "P5E_CPU0_PE0_TX_DP<9>")
	)
	(segment
		(start 319.025778 -381.037846)
		(end 318.94145 -381.192532)
		(width 0.14732)
		(layer "In15.Cu")
		(net "P5E_CPU0_PE0_TX_DP<9>")
	)
	(segment
		(start 320.08191 -385.060952)
		(end 320.236596 -385.14528)
		(width 0.14732)
		(layer "In15.Cu")
		(net "P5E_CPU0_PE0_TX_DP<9>")
	)
	(segment
		(start 345.201494 -218.368372)
		(end 345.200478 -218.367864)
		(width 0.0889)
		(layer "In15.Cu")
		(net "P5E_CPU0_PE0_TX_DP<9>")
	)
	(segment
		(start 344.406474 -212.75167)
		(end 344.21699 -212.294216)
		(width 0.14732)
		(layer "In15.Cu")
		(net "P5E_CPU0_PE0_TX_DP<9>")
	)
	(segment
		(start 319.576704 -383.346198)
		(end 319.764156 -383.982468)
		(width 0.14732)
		(layer "In15.Cu")
		(net "P5E_CPU0_PE0_TX_DP<9>")
	)
	(segment
		(start 320.811906 -317.540386)
		(end 315.227716 -325.514716)
		(width 0.14732)
		(layer "In15.Cu")
		(net "P5E_CPU0_PE0_TX_DP<9>")
	)
	(segment
		(start 344.917776 -214.622634)
		(end 344.917776 -214.461344)
		(width 0.0889)
		(layer "In15.Cu")
		(net "P5E_CPU0_PE0_TX_DP<9>")
	)
	(arc
		(start 345.200478 -221.623382)
		(mid 344.997655 -221.423151)
		(end 344.918284 -221.149418)
		(width 0.0889)
		(layer "In15.Cu")
		(net "P5E_CPU0_PE0_TX_DP<9>")
	)
	(arc
		(start 346.149168 -223.894904)
		(mid 346.327765 -223.575626)
		(end 346.149168 -223.256348)
		(width 0.0889)
		(layer "In15.Cu")
		(net "P5E_CPU0_PE0_TX_DP<9>")
	)
	(arc
		(start 345.38793 -221.94774)
		(mid 345.340251 -221.76484)
		(end 345.209368 -221.628462)
		(width 0.0889)
		(layer "In15.Cu")
		(net "P5E_CPU0_PE0_TX_DP<9>")
	)
	(arc
		(start 345.209368 -219.0115)
		(mid 345.387844 -218.692222)
		(end 345.209368 -218.372944)
		(width 0.0889)
		(layer "In15.Cu")
		(net "P5E_CPU0_PE0_TX_DP<9>")
	)
	(arc
		(start 344.918284 -217.859864)
		(mid 344.998446 -217.587675)
		(end 345.200732 -217.388694)
		(width 0.0889)
		(layer "In15.Cu")
		(net "P5E_CPU0_PE0_TX_DP<9>")
	)
	(arc
		(start 344.724736 -215.922606)
		(mid 344.522149 -215.716255)
		(end 344.44813 -215.436704)
		(width 0.0889)
		(layer "In15.Cu")
		(net "P5E_CPU0_PE0_TX_DP<9>")
	)
	(arc
		(start 345.858084 -222.761556)
		(mid 345.810405 -222.578656)
		(end 345.679522 -222.442278)
		(width 0.0889)
		(layer "In15.Cu")
		(net "P5E_CPU0_PE0_TX_DP<9>")
	)
	(arc
		(start 346.627958 -224.916746)
		(mid 346.379806 -224.953361)
		(end 346.140278 -224.8789)
		(width 0.0889)
		(layer "In15.Cu")
		(net "P5E_CPU0_PE0_TX_DP<9>")
	)
	(arc
		(start 344.917522 -214.637366)
		(mid 344.917719 -214.630001)
		(end 344.917776 -214.622634)
		(width 0.0889)
		(layer "In15.Cu")
		(net "P5E_CPU0_PE0_TX_DP<9>")
	)
	(arc
		(start 346.140278 -223.251268)
		(mid 345.938996 -223.053781)
		(end 345.858084 -222.783654)
		(width 0.0889)
		(layer "In15.Cu")
		(net "P5E_CPU0_PE0_TX_DP<9>")
	)
	(arc
		(start 344.739214 -214.941912)
		(mid 344.866468 -214.811946)
		(end 344.917522 -214.637366)
		(width 0.0889)
		(layer "In15.Cu")
		(net "P5E_CPU0_PE0_TX_DP<9>")
	)
	(arc
		(start 344.463624 -213.969346)
		(mid 344.455661 -213.950049)
		(end 344.448384 -213.930484)
		(width 0.0889)
		(layer "In15.Cu")
		(net "P5E_CPU0_PE0_TX_DP<9>")
	)
	(arc
		(start 345.200732 -216.739978)
		(mid 344.996397 -216.537373)
		(end 344.918284 -216.260426)
		(width 0.0889)
		(layer "In15.Cu")
		(net "P5E_CPU0_PE0_TX_DP<9>")
	)
	(arc
		(start 345.200732 -219.995496)
		(mid 344.9182 -219.506148)
		(end 345.200478 -219.01658)
		(width 0.0889)
		(layer "In15.Cu")
		(net "P5E_CPU0_PE0_TX_DP<9>")
	)
	(arc
		(start 345.200478 -218.367864)
		(mid 344.997655 -218.167633)
		(end 344.918284 -217.8939)
		(width 0.0889)
		(layer "In15.Cu")
		(net "P5E_CPU0_PE0_TX_DP<9>")
	)
	(arc
		(start 344.918284 -221.115382)
		(mid 344.998446 -220.843193)
		(end 345.200732 -220.644212)
		(width 0.0889)
		(layer "In15.Cu")
		(net "P5E_CPU0_PE0_TX_DP<9>")
	)
	(arc
		(start 345.664536 -222.433642)
		(mid 345.461949 -222.227291)
		(end 345.38793 -221.94774)
		(width 0.0889)
		(layer "In15.Cu")
		(net "P5E_CPU0_PE0_TX_DP<9>")
	)
	(arc
		(start 344.918284 -216.25052)
		(mid 344.870605 -216.06762)
		(end 344.739722 -215.931242)
		(width 0.0889)
		(layer "In15.Cu")
		(net "P5E_CPU0_PE0_TX_DP<9>")
	)
	(arc
		(start 345.200732 -217.388694)
		(mid 345.388035 -217.064336)
		(end 345.200732 -216.739978)
		(width 0.0889)
		(layer "In15.Cu")
		(net "P5E_CPU0_PE0_TX_DP<9>")
	)
	(arc
		(start 344.44813 -215.414606)
		(mid 344.529041 -215.144478)
		(end 344.730324 -214.946992)
		(width 0.0889)
		(layer "In15.Cu")
		(net "P5E_CPU0_PE0_TX_DP<9>")
	)
	(arc
		(start 344.917776 -214.461344)
		(mid 344.842771 -214.345885)
		(end 344.733626 -214.261954)
		(width 0.0889)
		(layer "In15.Cu")
		(net "P5E_CPU0_PE0_TX_DP<9>")
	)
	(arc
		(start 346.647516 -224.908618)
		(mid 346.637776 -224.912775)
		(end 346.627958 -224.916746)
		(width 0.0889)
		(layer "In15.Cu")
		(net "P5E_CPU0_PE0_TX_DP<9>")
	)
	(arc
		(start 346.140278 -224.8789)
		(mid 345.937455 -224.678669)
		(end 345.858084 -224.404936)
		(width 0.0889)
		(layer "In15.Cu")
		(net "P5E_CPU0_PE0_TX_DP<9>")
	)
	(arc
		(start 345.858084 -224.373948)
		(mid 345.937454 -224.100214)
		(end 346.140278 -223.899984)
		(width 0.0889)
		(layer "In15.Cu")
		(net "P5E_CPU0_PE0_TX_DP<9>")
	)
	(arc
		(start 345.200732 -220.644212)
		(mid 345.388035 -220.319854)
		(end 345.200732 -219.995496)
		(width 0.0889)
		(layer "In15.Cu")
		(net "P5E_CPU0_PE0_TX_DP<9>")
	)
	(arc
		(start 344.733626 -214.261954)
		(mid 344.573554 -214.138774)
		(end 344.463624 -213.969346)
		(width 0.0889)
		(layer "In15.Cu")
		(net "P5E_CPU0_PE0_TX_DP<9>")
	)
	(segment
		(start 327.632568 -407.00452)
		(end 327.33361 -407.303478)
		(width 0.13208)
		(layer "F.Cu")
		(net "P5E_CPU0_PE0_TX_DP<8>")
	)
	(segment
		(start 327.33361 -407.303478)
		(end 327.33361 -407.926286)
		(width 0.13208)
		(layer "F.Cu")
		(net "P5E_CPU0_PE0_TX_DP<8>")
	)
	(segment
		(start 327.33361 -407.926286)
		(end 327.657968 -408.250644)
		(width 0.13208)
		(layer "F.Cu")
		(net "P5E_CPU0_PE0_TX_DP<8>")
	)
	(segment
		(start 345.48318 -224.389696)
		(end 345.483434 -224.389442)
		(width 0.13208)
		(layer "F.Cu")
		(net "P5E_CPU0_PE0_TX_DP<8>")
	)
	(segment
		(start 345.48318 -224.925382)
		(end 345.48318 -224.389696)
		(width 0.13208)
		(layer "F.Cu")
		(net "P5E_CPU0_PE0_TX_DP<8>")
	)
	(segment
		(start 322.094606 -384.10007)
		(end 322.239894 -384.512312)
		(width 0.14732)
		(layer "In15.Cu")
		(net "P5E_CPU0_PE0_TX_DP<8>")
	)
	(segment
		(start 343.791794 -215.92667)
		(end 343.789508 -215.925146)
		(width 0.0889)
		(layer "In15.Cu")
		(net "P5E_CPU0_PE0_TX_DP<8>")
	)
	(segment
		(start 343.508838 -213.929468)
		(end 343.508838 -213.17585)
		(width 0.0889)
		(layer "In15.Cu")
		(net "P5E_CPU0_PE0_TX_DP<8>")
	)
	(segment
		(start 321.520312 -252.66777)
		(end 325.141082 -309.73268)
		(width 0.14732)
		(layer "In15.Cu")
		(net "P5E_CPU0_PE0_TX_DP<8>")
	)
	(segment
		(start 333.642462 -212.789262)
		(end 333.59344 -212.954616)
		(width 0.14732)
		(layer "In15.Cu")
		(net "P5E_CPU0_PE0_TX_DP<8>")
	)
	(segment
		(start 333.59344 -212.954616)
		(end 333.208884 -213.162896)
		(width 0.14732)
		(layer "In15.Cu")
		(net "P5E_CPU0_PE0_TX_DP<8>")
	)
	(segment
		(start 343.466674 -212.979)
		(end 342.84793 -212.360256)
		(width 0.14732)
		(layer "In15.Cu")
		(net "P5E_CPU0_PE0_TX_DP<8>")
	)
	(segment
		(start 334.191864 -212.630512)
		(end 334.02651 -212.581236)
		(width 0.14732)
		(layer "In15.Cu")
		(net "P5E_CPU0_PE0_TX_DP<8>")
	)
	(segment
		(start 335.235042 -211.926678)
		(end 334.625442 -212.257132)
		(width 0.14732)
		(layer "In15.Cu")
		(net "P5E_CPU0_PE0_TX_DP<8>")
	)
	(segment
		(start 321.561968 -382.965198)
		(end 321.720972 -383.041144)
		(width 0.14732)
		(layer "In15.Cu")
		(net "P5E_CPU0_PE0_TX_DP<8>")
	)
	(segment
		(start 320.815208 -380.847092)
		(end 320.8147 -380.847346)
		(width 0.14732)
		(layer "In15.Cu")
		(net "P5E_CPU0_PE0_TX_DP<8>")
	)
	(segment
		(start 322.163948 -384.671062)
		(end 322.309236 -385.08305)
		(width 0.14732)
		(layer "In15.Cu")
		(net "P5E_CPU0_PE0_TX_DP<8>")
	)
	(segment
		(start 321.188334 -381.906272)
		(end 321.347338 -381.982218)
		(width 0.14732)
		(layer "In15.Cu")
		(net "P5E_CPU0_PE0_TX_DP<8>")
	)
	(segment
		(start 320.8147 -380.847346)
		(end 320.973704 -380.923292)
		(width 0.14732)
		(layer "In15.Cu")
		(net "P5E_CPU0_PE0_TX_DP<8>")
	)
	(segment
		(start 343.978484 -219.521532)
		(end 343.978484 -219.490544)
		(width 0.0889)
		(layer "In15.Cu")
		(net "P5E_CPU0_PE0_TX_DP<8>")
	)
	(segment
		(start 321.347338 -381.982218)
		(end 321.492626 -382.39446)
		(width 0.14732)
		(layer "In15.Cu")
		(net "P5E_CPU0_PE0_TX_DP<8>")
	)
	(segment
		(start 321.416934 -382.552956)
		(end 321.562222 -382.964436)
		(width 0.14732)
		(layer "In15.Cu")
		(net "P5E_CPU0_PE0_TX_DP<8>")
	)
	(segment
		(start 344.261694 -218.368372)
		(end 344.260678 -218.367864)
		(width 0.0889)
		(layer "In15.Cu")
		(net "P5E_CPU0_PE0_TX_DP<8>")
	)
	(segment
		(start 344.260678 -217.388694)
		(end 344.269568 -217.383614)
		(width 0.0889)
		(layer "In15.Cu")
		(net "P5E_CPU0_PE0_TX_DP<8>")
	)
	(segment
		(start 344.260678 -219.01658)
		(end 344.269568 -219.0115)
		(width 0.0889)
		(layer "In15.Cu")
		(net "P5E_CPU0_PE0_TX_DP<8>")
	)
	(segment
		(start 309.766208 -341.245698)
		(end 314.739528 -363.623606)
		(width 0.14732)
		(layer "In15.Cu")
		(net "P5E_CPU0_PE0_TX_DP<8>")
	)
	(segment
		(start 333.208884 -213.162896)
		(end 333.043784 -213.11362)
		(width 0.14732)
		(layer "In15.Cu")
		(net "P5E_CPU0_PE0_TX_DP<8>")
	)
	(segment
		(start 344.261694 -219.996004)
		(end 344.260678 -219.995496)
		(width 0.0889)
		(layer "In15.Cu")
		(net "P5E_CPU0_PE0_TX_DP<8>")
	)
	(segment
		(start 333.043784 -213.113874)
		(end 331.600556 -213.895432)
		(width 0.14732)
		(layer "In15.Cu")
		(net "P5E_CPU0_PE0_TX_DP<8>")
	)
	(segment
		(start 344.739722 -222.442278)
		(end 344.724736 -222.433642)
		(width 0.0889)
		(layer "In15.Cu")
		(net "P5E_CPU0_PE0_TX_DP<8>")
	)
	(segment
		(start 334.02651 -212.581236)
		(end 333.642462 -212.789262)
		(width 0.14732)
		(layer "In15.Cu")
		(net "P5E_CPU0_PE0_TX_DP<8>")
	)
	(segment
		(start 334.625442 -212.257132)
		(end 334.625442 -212.256878)
		(width 0.14732)
		(layer "In15.Cu")
		(net "P5E_CPU0_PE0_TX_DP<8>")
	)
	(segment
		(start 315.874146 -326.240648)
		(end 309.766208 -332.348586)
		(width 0.14732)
		(layer "In15.Cu")
		(net "P5E_CPU0_PE0_TX_DP<8>")
	)
	(segment
		(start 321.596258 -250.236736)
		(end 321.520312 -252.495304)
		(width 0.14732)
		(layer "In15.Cu")
		(net "P5E_CPU0_PE0_TX_DP<8>")
	)
	(segment
		(start 327.337928 -405.845264)
		(end 327.337928 -406.70988)
		(width 0.14732)
		(layer "In15.Cu")
		(net "P5E_CPU0_PE0_TX_DP<8>")
	)
	(segment
		(start 345.483434 -224.389442)
		(end 345.639898 -224.118424)
		(width 0.0889)
		(layer "In15.Cu")
		(net "P5E_CPU0_PE0_TX_DP<8>")
	)
	(segment
		(start 321.043046 -381.494284)
		(end 321.043554 -381.49403)
		(width 0.14732)
		(layer "In15.Cu")
		(net "P5E_CPU0_PE0_TX_DP<8>")
	)
	(segment
		(start 345.639898 -224.118424)
		(end 345.615768 -224.02927)
		(width 0.0889)
		(layer "In15.Cu")
		(net "P5E_CPU0_PE0_TX_DP<8>")
	)
	(segment
		(start 322.989702 -233.16311)
		(end 321.596258 -250.236736)
		(width 0.14732)
		(layer "In15.Cu")
		(net "P5E_CPU0_PE0_TX_DP<8>")
	)
	(segment
		(start 343.466674 -213.12251)
		(end 343.466674 -212.979)
		(width 0.14732)
		(layer "In15.Cu")
		(net "P5E_CPU0_PE0_TX_DP<8>")
	)
	(segment
		(start 321.562222 -382.964436)
		(end 321.562476 -382.965198)
		(width 0.14732)
		(layer "In15.Cu")
		(net "P5E_CPU0_PE0_TX_DP<8>")
	)
	(segment
		(start 344.269568 -221.628462)
		(end 344.260678 -221.623382)
		(width 0.0889)
		(layer "In15.Cu")
		(net "P5E_CPU0_PE0_TX_DP<8>")
	)
	(segment
		(start 344.269568 -218.372944)
		(end 344.261694 -218.368372)
		(width 0.0889)
		(layer "In15.Cu")
		(net "P5E_CPU0_PE0_TX_DP<8>")
	)
	(segment
		(start 343.977976 -214.622634)
		(end 343.977976 -214.461344)
		(width 0.0889)
		(layer "In15.Cu")
		(net "P5E_CPU0_PE0_TX_DP<8>")
	)
	(segment
		(start 314.739528 -363.623606)
		(end 320.815208 -380.847092)
		(width 0.14732)
		(layer "In15.Cu")
		(net "P5E_CPU0_PE0_TX_DP<8>")
	)
	(segment
		(start 343.978484 -216.266014)
		(end 343.978484 -216.25052)
		(width 0.0889)
		(layer "In15.Cu")
		(net "P5E_CPU0_PE0_TX_DP<8>")
	)
	(segment
		(start 322.46824 -385.158996)
		(end 322.613782 -385.571238)
		(width 0.14732)
		(layer "In15.Cu")
		(net "P5E_CPU0_PE0_TX_DP<8>")
	)
	(segment
		(start 325.141082 -309.73268)
		(end 321.645026 -318.000126)
		(width 0.14732)
		(layer "In15.Cu")
		(net "P5E_CPU0_PE0_TX_DP<8>")
	)
	(segment
		(start 321.188842 -381.906018)
		(end 321.188334 -381.906272)
		(width 0.14732)
		(layer "In15.Cu")
		(net "P5E_CPU0_PE0_TX_DP<8>")
	)
	(segment
		(start 321.118992 -381.335534)
		(end 321.043046 -381.494284)
		(width 0.14732)
		(layer "In15.Cu")
		(net "P5E_CPU0_PE0_TX_DP<8>")
	)
	(segment
		(start 344.269568 -220.000576)
		(end 344.261694 -219.996004)
		(width 0.0889)
		(layer "In15.Cu")
		(net "P5E_CPU0_PE0_TX_DP<8>")
	)
	(segment
		(start 321.043554 -381.49403)
		(end 321.188842 -381.906018)
		(width 0.14732)
		(layer "In15.Cu")
		(net "P5E_CPU0_PE0_TX_DP<8>")
	)
	(segment
		(start 343.978484 -221.149418)
		(end 343.978484 -221.111826)
		(width 0.0889)
		(layer "In15.Cu")
		(net "P5E_CPU0_PE0_TX_DP<8>")
	)
	(segment
		(start 343.978484 -217.8939)
		(end 343.978484 -217.856308)
		(width 0.0889)
		(layer "In15.Cu")
		(net "P5E_CPU0_PE0_TX_DP<8>")
	)
	(segment
		(start 344.269568 -216.745058)
		(end 344.261694 -216.740486)
		(width 0.0889)
		(layer "In15.Cu")
		(net "P5E_CPU0_PE0_TX_DP<8>")
	)
	(segment
		(start 343.799922 -215.931242)
		(end 343.795604 -215.928702)
		(width 0.0889)
		(layer "In15.Cu")
		(net "P5E_CPU0_PE0_TX_DP<8>")
	)
	(segment
		(start 343.508838 -213.17585)
		(end 343.466674 -213.133686)
		(width 0.0889)
		(layer "In15.Cu")
		(net "P5E_CPU0_PE0_TX_DP<8>")
	)
	(segment
		(start 334.576166 -212.422486)
		(end 334.191864 -212.630512)
		(width 0.14732)
		(layer "In15.Cu")
		(net "P5E_CPU0_PE0_TX_DP<8>")
	)
	(segment
		(start 343.508584 -213.930484)
		(end 343.508584 -213.929722)
		(width 0.0889)
		(layer "In15.Cu")
		(net "P5E_CPU0_PE0_TX_DP<8>")
	)
	(segment
		(start 342.84793 -212.360256)
		(end 341.800942 -211.926678)
		(width 0.14732)
		(layer "In15.Cu")
		(net "P5E_CPU0_PE0_TX_DP<8>")
	)
	(segment
		(start 321.41668 -382.55321)
		(end 321.416934 -382.552956)
		(width 0.14732)
		(layer "In15.Cu")
		(net "P5E_CPU0_PE0_TX_DP<8>")
	)
	(segment
		(start 344.260678 -220.644212)
		(end 344.269568 -220.639132)
		(width 0.0889)
		(layer "In15.Cu")
		(net "P5E_CPU0_PE0_TX_DP<8>")
	)
	(segment
		(start 343.466674 -213.133686)
		(end 343.466674 -213.12251)
		(width 0.0889)
		(layer "In15.Cu")
		(net "P5E_CPU0_PE0_TX_DP<8>")
	)
	(segment
		(start 321.520312 -252.495304)
		(end 321.520312 -252.66777)
		(width 0.14732)
		(layer "In15.Cu")
		(net "P5E_CPU0_PE0_TX_DP<8>")
	)
	(segment
		(start 322.537836 -385.729988)
		(end 327.523348 -399.863818)
		(width 0.14732)
		(layer "In15.Cu")
		(net "P5E_CPU0_PE0_TX_DP<8>")
	)
	(segment
		(start 321.492626 -382.39446)
		(end 321.41668 -382.55321)
		(width 0.14732)
		(layer "In15.Cu")
		(net "P5E_CPU0_PE0_TX_DP<8>")
	)
	(segment
		(start 321.645026 -318.000126)
		(end 315.874146 -326.240648)
		(width 0.14732)
		(layer "In15.Cu")
		(net "P5E_CPU0_PE0_TX_DP<8>")
	)
	(segment
		(start 324.67042 -222.338138)
		(end 322.989702 -233.16311)
		(width 0.14732)
		(layer "In15.Cu")
		(net "P5E_CPU0_PE0_TX_DP<8>")
	)
	(segment
		(start 343.508584 -213.929722)
		(end 343.508838 -213.929468)
		(width 0.0889)
		(layer "In15.Cu")
		(net "P5E_CPU0_PE0_TX_DP<8>")
	)
	(segment
		(start 327.523348 -399.863818)
		(end 327.523348 -403.961854)
		(width 0.14732)
		(layer "In15.Cu")
		(net "P5E_CPU0_PE0_TX_DP<8>")
	)
	(segment
		(start 322.239894 -384.512312)
		(end 322.163948 -384.671062)
		(width 0.14732)
		(layer "In15.Cu")
		(net "P5E_CPU0_PE0_TX_DP<8>")
	)
	(segment
		(start 333.043784 -213.11362)
		(end 333.043784 -213.113874)
		(width 0.14732)
		(layer "In15.Cu")
		(net "P5E_CPU0_PE0_TX_DP<8>")
	)
	(segment
		(start 321.790314 -383.612136)
		(end 321.935602 -384.024124)
		(width 0.14732)
		(layer "In15.Cu")
		(net "P5E_CPU0_PE0_TX_DP<8>")
	)
	(segment
		(start 327.523348 -403.961854)
		(end 327.337928 -405.845264)
		(width 0.14732)
		(layer "In15.Cu")
		(net "P5E_CPU0_PE0_TX_DP<8>")
	)
	(segment
		(start 344.261694 -216.740486)
		(end 344.260678 -216.739978)
		(width 0.0889)
		(layer "In15.Cu")
		(net "P5E_CPU0_PE0_TX_DP<8>")
	)
	(segment
		(start 321.935602 -384.024124)
		(end 322.094606 -384.10007)
		(width 0.14732)
		(layer "In15.Cu")
		(net "P5E_CPU0_PE0_TX_DP<8>")
	)
	(segment
		(start 343.795604 -215.928702)
		(end 343.791794 -215.92667)
		(width 0.0889)
		(layer "In15.Cu")
		(net "P5E_CPU0_PE0_TX_DP<8>")
	)
	(segment
		(start 309.766208 -332.348586)
		(end 309.766208 -341.245698)
		(width 0.14732)
		(layer "In15.Cu")
		(net "P5E_CPU0_PE0_TX_DP<8>")
	)
	(segment
		(start 320.973704 -380.923292)
		(end 321.118992 -381.335534)
		(width 0.14732)
		(layer "In15.Cu")
		(net "P5E_CPU0_PE0_TX_DP<8>")
	)
	(segment
		(start 345.38793 -223.575626)
		(end 345.38793 -223.56699)
		(width 0.0889)
		(layer "In15.Cu")
		(net "P5E_CPU0_PE0_TX_DP<8>")
	)
	(segment
		(start 322.613782 -385.571238)
		(end 322.537836 -385.729988)
		(width 0.14732)
		(layer "In15.Cu")
		(net "P5E_CPU0_PE0_TX_DP<8>")
	)
	(segment
		(start 344.918284 -222.780098)
		(end 344.918284 -222.761556)
		(width 0.0889)
		(layer "In15.Cu")
		(net "P5E_CPU0_PE0_TX_DP<8>")
	)
	(segment
		(start 322.309236 -385.08305)
		(end 322.46824 -385.158996)
		(width 0.14732)
		(layer "In15.Cu")
		(net "P5E_CPU0_PE0_TX_DP<8>")
	)
	(segment
		(start 321.86626 -383.453386)
		(end 321.790314 -383.612136)
		(width 0.14732)
		(layer "In15.Cu")
		(net "P5E_CPU0_PE0_TX_DP<8>")
	)
	(segment
		(start 334.625442 -212.256878)
		(end 334.576166 -212.422486)
		(width 0.14732)
		(layer "In15.Cu")
		(net "P5E_CPU0_PE0_TX_DP<8>")
	)
	(segment
		(start 343.789508 -215.925146)
		(end 343.788238 -215.924384)
		(width 0.0889)
		(layer "In15.Cu")
		(net "P5E_CPU0_PE0_TX_DP<8>")
	)
	(segment
		(start 343.50833 -215.436704)
		(end 343.50833 -215.414606)
		(width 0.0889)
		(layer "In15.Cu")
		(net "P5E_CPU0_PE0_TX_DP<8>")
	)
	(segment
		(start 326.57923 -218.635326)
		(end 324.67042 -222.338138)
		(width 0.14732)
		(layer "In15.Cu")
		(net "P5E_CPU0_PE0_TX_DP<8>")
	)
	(segment
		(start 321.562476 -382.965198)
		(end 321.561968 -382.965198)
		(width 0.14732)
		(layer "In15.Cu")
		(net "P5E_CPU0_PE0_TX_DP<8>")
	)
	(segment
		(start 331.600556 -213.895432)
		(end 326.57923 -218.635326)
		(width 0.14732)
		(layer "In15.Cu")
		(net "P5E_CPU0_PE0_TX_DP<8>")
	)
	(segment
		(start 327.337928 -406.70988)
		(end 327.632568 -407.00452)
		(width 0.14732)
		(layer "In15.Cu")
		(net "P5E_CPU0_PE0_TX_DP<8>")
	)
	(segment
		(start 343.788238 -215.924384)
		(end 343.784936 -215.922606)
		(width 0.0889)
		(layer "In15.Cu")
		(net "P5E_CPU0_PE0_TX_DP<8>")
	)
	(segment
		(start 321.720972 -383.041144)
		(end 321.86626 -383.453386)
		(width 0.14732)
		(layer "In15.Cu")
		(net "P5E_CPU0_PE0_TX_DP<8>")
	)
	(segment
		(start 341.800942 -211.926678)
		(end 335.235042 -211.926678)
		(width 0.14732)
		(layer "In15.Cu")
		(net "P5E_CPU0_PE0_TX_DP<8>")
	)
	(segment
		(start 343.790524 -214.946992)
		(end 343.799414 -214.941912)
		(width 0.0889)
		(layer "In15.Cu")
		(net "P5E_CPU0_PE0_TX_DP<8>")
	)
	(arc
		(start 343.978484 -216.25052)
		(mid 343.930805 -216.06762)
		(end 343.799922 -215.931242)
		(width 0.0889)
		(layer "In15.Cu")
		(net "P5E_CPU0_PE0_TX_DP<8>")
	)
	(arc
		(start 343.523824 -213.969346)
		(mid 343.515861 -213.950049)
		(end 343.508584 -213.930484)
		(width 0.0889)
		(layer "In15.Cu")
		(net "P5E_CPU0_PE0_TX_DP<8>")
	)
	(arc
		(start 344.260678 -219.995496)
		(mid 344.057855 -219.795265)
		(end 343.978484 -219.521532)
		(width 0.0889)
		(layer "In15.Cu")
		(net "P5E_CPU0_PE0_TX_DP<8>")
	)
	(arc
		(start 343.978484 -217.856308)
		(mid 344.059395 -217.58618)
		(end 344.260678 -217.388694)
		(width 0.0889)
		(layer "In15.Cu")
		(net "P5E_CPU0_PE0_TX_DP<8>")
	)
	(arc
		(start 344.44813 -221.94774)
		(mid 344.400451 -221.76484)
		(end 344.269568 -221.628462)
		(width 0.0889)
		(layer "In15.Cu")
		(net "P5E_CPU0_PE0_TX_DP<8>")
	)
	(arc
		(start 343.799414 -214.941912)
		(mid 343.926668 -214.811946)
		(end 343.977722 -214.637366)
		(width 0.0889)
		(layer "In15.Cu")
		(net "P5E_CPU0_PE0_TX_DP<8>")
	)
	(arc
		(start 344.269568 -217.383614)
		(mid 344.448165 -217.064336)
		(end 344.269568 -216.745058)
		(width 0.0889)
		(layer "In15.Cu")
		(net "P5E_CPU0_PE0_TX_DP<8>")
	)
	(arc
		(start 344.269568 -219.0115)
		(mid 344.448044 -218.692222)
		(end 344.269568 -218.372944)
		(width 0.0889)
		(layer "In15.Cu")
		(net "P5E_CPU0_PE0_TX_DP<8>")
	)
	(arc
		(start 344.260678 -221.623382)
		(mid 344.057855 -221.423151)
		(end 343.978484 -221.149418)
		(width 0.0889)
		(layer "In15.Cu")
		(net "P5E_CPU0_PE0_TX_DP<8>")
	)
	(arc
		(start 345.38793 -223.56699)
		(mid 345.33566 -223.384625)
		(end 345.200732 -223.251268)
		(width 0.0889)
		(layer "In15.Cu")
		(net "P5E_CPU0_PE0_TX_DP<8>")
	)
	(arc
		(start 343.977722 -214.637366)
		(mid 343.977919 -214.630001)
		(end 343.977976 -214.622634)
		(width 0.0889)
		(layer "In15.Cu")
		(net "P5E_CPU0_PE0_TX_DP<8>")
	)
	(arc
		(start 343.793826 -214.261954)
		(mid 343.633754 -214.138774)
		(end 343.523824 -213.969346)
		(width 0.0889)
		(layer "In15.Cu")
		(net "P5E_CPU0_PE0_TX_DP<8>")
	)
	(arc
		(start 344.260678 -216.739978)
		(mid 344.057855 -216.539747)
		(end 343.978484 -216.266014)
		(width 0.0889)
		(layer "In15.Cu")
		(net "P5E_CPU0_PE0_TX_DP<8>")
	)
	(arc
		(start 343.978484 -219.490544)
		(mid 344.057854 -219.21681)
		(end 344.260678 -219.01658)
		(width 0.0889)
		(layer "In15.Cu")
		(net "P5E_CPU0_PE0_TX_DP<8>")
	)
	(arc
		(start 343.977976 -214.461344)
		(mid 343.902971 -214.345885)
		(end 343.793826 -214.261954)
		(width 0.0889)
		(layer "In15.Cu")
		(net "P5E_CPU0_PE0_TX_DP<8>")
	)
	(arc
		(start 344.918284 -222.761556)
		(mid 344.870605 -222.578656)
		(end 344.739722 -222.442278)
		(width 0.0889)
		(layer "In15.Cu")
		(net "P5E_CPU0_PE0_TX_DP<8>")
	)
	(arc
		(start 343.978484 -221.111826)
		(mid 344.059395 -220.841698)
		(end 344.260678 -220.644212)
		(width 0.0889)
		(layer "In15.Cu")
		(net "P5E_CPU0_PE0_TX_DP<8>")
	)
	(arc
		(start 343.784936 -215.922606)
		(mid 343.582349 -215.716255)
		(end 343.50833 -215.436704)
		(width 0.0889)
		(layer "In15.Cu")
		(net "P5E_CPU0_PE0_TX_DP<8>")
	)
	(arc
		(start 345.200732 -223.251268)
		(mid 344.998446 -223.052287)
		(end 344.918284 -222.780098)
		(width 0.0889)
		(layer "In15.Cu")
		(net "P5E_CPU0_PE0_TX_DP<8>")
	)
	(arc
		(start 344.269568 -220.639132)
		(mid 344.448165 -220.319854)
		(end 344.269568 -220.000576)
		(width 0.0889)
		(layer "In15.Cu")
		(net "P5E_CPU0_PE0_TX_DP<8>")
	)
	(arc
		(start 344.724736 -222.433642)
		(mid 344.522149 -222.227291)
		(end 344.44813 -221.94774)
		(width 0.0889)
		(layer "In15.Cu")
		(net "P5E_CPU0_PE0_TX_DP<8>")
	)
	(arc
		(start 345.615768 -224.02927)
		(mid 345.448014 -223.829492)
		(end 345.38793 -223.575626)
		(width 0.0889)
		(layer "In15.Cu")
		(net "P5E_CPU0_PE0_TX_DP<8>")
	)
	(arc
		(start 343.50833 -215.414606)
		(mid 343.589241 -215.144478)
		(end 343.790524 -214.946992)
		(width 0.0889)
		(layer "In15.Cu")
		(net "P5E_CPU0_PE0_TX_DP<8>")
	)
	(arc
		(start 344.260678 -218.367864)
		(mid 344.057855 -218.167633)
		(end 343.978484 -217.8939)
		(width 0.0889)
		(layer "In15.Cu")
		(net "P5E_CPU0_PE0_TX_DP<8>")
	)
	(segment
		(start 330.39685 -407.303478)
		(end 330.39685 -407.926286)
		(width 0.13208)
		(layer "F.Cu")
		(net "P5E_CPU0_PE0_TX_DP<7>")
	)
	(segment
		(start 330.39685 -407.926286)
		(end 330.721208 -408.250644)
		(width 0.13208)
		(layer "F.Cu")
		(net "P5E_CPU0_PE0_TX_DP<7>")
	)
	(segment
		(start 345.013534 -225.739198)
		(end 345.013534 -225.203512)
		(width 0.13208)
		(layer "F.Cu")
		(net "P5E_CPU0_PE0_TX_DP<7>")
	)
	(segment
		(start 345.013534 -225.203512)
		(end 345.01328 -225.203258)
		(width 0.13208)
		(layer "F.Cu")
		(net "P5E_CPU0_PE0_TX_DP<7>")
	)
	(segment
		(start 330.695808 -407.00452)
		(end 330.39685 -407.303478)
		(width 0.13208)
		(layer "F.Cu")
		(net "P5E_CPU0_PE0_TX_DP<7>")
	)
	(segment
		(start 343.978484 -222.783654)
		(end 343.978484 -222.761556)
		(width 0.0889)
		(layer "In15.Cu")
		(net "P5E_CPU0_PE0_TX_DP<7>")
	)
	(segment
		(start 344.269568 -223.256348)
		(end 344.261694 -223.251776)
		(width 0.0889)
		(layer "In15.Cu")
		(net "P5E_CPU0_PE0_TX_DP<7>")
	)
	(segment
		(start 318.98717 -371.20449)
		(end 318.919352 -371.366796)
		(width 0.14732)
		(layer "In15.Cu")
		(net "P5E_CPU0_PE0_TX_DP<7>")
	)
	(segment
		(start 320.57086 -375.076466)
		(end 320.736468 -375.480834)
		(width 0.14732)
		(layer "In15.Cu")
		(net "P5E_CPU0_PE0_TX_DP<7>")
	)
	(segment
		(start 336.786982 -212.856318)
		(end 335.19745 -213.259162)
		(width 0.14732)
		(layer "In15.Cu")
		(net "P5E_CPU0_PE0_TX_DP<7>")
	)
	(segment
		(start 330.401168 -405.845264)
		(end 330.401168 -406.70988)
		(width 0.14732)
		(layer "In15.Cu")
		(net "P5E_CPU0_PE0_TX_DP<7>")
	)
	(segment
		(start 343.978484 -224.404936)
		(end 343.978484 -224.373948)
		(width 0.0889)
		(layer "In15.Cu")
		(net "P5E_CPU0_PE0_TX_DP<7>")
	)
	(segment
		(start 320.736468 -375.480834)
		(end 320.66992 -375.639838)
		(width 0.14732)
		(layer "In15.Cu")
		(net "P5E_CPU0_PE0_TX_DP<7>")
	)
	(segment
		(start 316.389258 -327.15708)
		(end 310.695848 -332.85049)
		(width 0.14732)
		(layer "In15.Cu")
		(net "P5E_CPU0_PE0_TX_DP<7>")
	)
	(segment
		(start 343.320878 -219.01658)
		(end 343.329768 -219.0115)
		(width 0.0889)
		(layer "In15.Cu")
		(net "P5E_CPU0_PE0_TX_DP<7>")
	)
	(segment
		(start 322.455286 -252.397006)
		(end 326.205596 -309.716424)
		(width 0.14732)
		(layer "In15.Cu")
		(net "P5E_CPU0_PE0_TX_DP<7>")
	)
	(segment
		(start 319.51041 -372.810024)
		(end 319.67297 -372.878096)
		(width 0.14732)
		(layer "In15.Cu")
		(net "P5E_CPU0_PE0_TX_DP<7>")
	)
	(segment
		(start 344.856816 -224.93224)
		(end 344.767916 -224.908618)
		(width 0.0889)
		(layer "In15.Cu")
		(net "P5E_CPU0_PE0_TX_DP<7>")
	)
	(segment
		(start 318.493648 -370.327682)
		(end 318.659002 -370.731796)
		(width 0.14732)
		(layer "In15.Cu")
		(net "P5E_CPU0_PE0_TX_DP<7>")
	)
	(segment
		(start 341.46744 -212.856318)
		(end 336.786982 -212.856318)
		(width 0.14732)
		(layer "In15.Cu")
		(net "P5E_CPU0_PE0_TX_DP<7>")
	)
	(segment
		(start 344.260678 -223.899984)
		(end 344.261694 -223.899476)
		(width 0.0889)
		(layer "In15.Cu")
		(net "P5E_CPU0_PE0_TX_DP<7>")
	)
	(segment
		(start 342.855804 -215.928702)
		(end 342.851994 -215.92667)
		(width 0.0889)
		(layer "In15.Cu")
		(net "P5E_CPU0_PE0_TX_DP<7>")
	)
	(segment
		(start 342.098376 -214.636858)
		(end 342.098376 -214.461344)
		(width 0.0889)
		(layer "In15.Cu")
		(net "P5E_CPU0_PE0_TX_DP<7>")
	)
	(segment
		(start 319.936114 -373.849138)
		(end 320.098674 -373.91721)
		(width 0.14732)
		(layer "In15.Cu")
		(net "P5E_CPU0_PE0_TX_DP<7>")
	)
	(segment
		(start 343.038684 -221.149418)
		(end 343.038684 -221.115382)
		(width 0.0889)
		(layer "In15.Cu")
		(net "P5E_CPU0_PE0_TX_DP<7>")
	)
	(segment
		(start 343.321894 -221.62389)
		(end 343.320878 -221.623382)
		(width 0.0889)
		(layer "In15.Cu")
		(net "P5E_CPU0_PE0_TX_DP<7>")
	)
	(segment
		(start 341.628984 -213.930484)
		(end 341.628984 -213.929722)
		(width 0.0889)
		(layer "In15.Cu")
		(net "P5E_CPU0_PE0_TX_DP<7>")
	)
	(segment
		(start 318.659002 -370.731796)
		(end 318.821562 -370.799868)
		(width 0.14732)
		(layer "In15.Cu")
		(net "P5E_CPU0_PE0_TX_DP<7>")
	)
	(segment
		(start 344.261694 -223.251776)
		(end 344.260678 -223.251268)
		(width 0.0889)
		(layer "In15.Cu")
		(net "P5E_CPU0_PE0_TX_DP<7>")
	)
	(segment
		(start 319.084706 -371.77091)
		(end 319.247266 -371.838982)
		(width 0.14732)
		(layer "In15.Cu")
		(net "P5E_CPU0_PE0_TX_DP<7>")
	)
	(segment
		(start 322.520056 -250.474226)
		(end 322.455286 -252.397006)
		(width 0.14732)
		(layer "In15.Cu")
		(net "P5E_CPU0_PE0_TX_DP<7>")
	)
	(segment
		(start 322.556378 -318.34963)
		(end 316.389258 -327.15708)
		(width 0.14732)
		(layer "In15.Cu")
		(net "P5E_CPU0_PE0_TX_DP<7>")
	)
	(segment
		(start 320.196464 -374.484138)
		(end 320.411602 -375.009664)
		(width 0.14732)
		(layer "In15.Cu")
		(net "P5E_CPU0_PE0_TX_DP<7>")
	)
	(segment
		(start 343.321894 -218.368372)
		(end 343.320878 -218.367864)
		(width 0.0889)
		(layer "In15.Cu")
		(net "P5E_CPU0_PE0_TX_DP<7>")
	)
	(segment
		(start 343.038684 -217.8939)
		(end 343.038684 -217.859864)
		(width 0.0889)
		(layer "In15.Cu")
		(net "P5E_CPU0_PE0_TX_DP<7>")
	)
	(segment
		(start 341.629238 -213.214712)
		(end 341.587074 -213.172548)
		(width 0.0889)
		(layer "In15.Cu")
		(net "P5E_CPU0_PE0_TX_DP<7>")
	)
	(segment
		(start 330.299568 -399.155666)
		(end 330.586588 -400.614134)
		(width 0.14732)
		(layer "In15.Cu")
		(net "P5E_CPU0_PE0_TX_DP<7>")
	)
	(segment
		(start 310.695848 -341.128858)
		(end 315.628782 -363.332268)
		(width 0.14732)
		(layer "In15.Cu")
		(net "P5E_CPU0_PE0_TX_DP<7>")
	)
	(segment
		(start 342.849708 -215.925146)
		(end 342.848438 -215.924384)
		(width 0.0889)
		(layer "In15.Cu")
		(net "P5E_CPU0_PE0_TX_DP<7>")
	)
	(segment
		(start 320.098674 -373.91721)
		(end 320.264282 -374.321832)
		(width 0.14732)
		(layer "In15.Cu")
		(net "P5E_CPU0_PE0_TX_DP<7>")
	)
	(segment
		(start 318.821562 -370.799868)
		(end 318.98717 -371.20449)
		(width 0.14732)
		(layer "In15.Cu")
		(net "P5E_CPU0_PE0_TX_DP<7>")
	)
	(segment
		(start 327.268332 -219.334842)
		(end 325.688452 -222.399606)
		(width 0.14732)
		(layer "In15.Cu")
		(net "P5E_CPU0_PE0_TX_DP<7>")
	)
	(segment
		(start 341.629238 -213.929468)
		(end 341.629238 -213.214712)
		(width 0.0889)
		(layer "In15.Cu")
		(net "P5E_CPU0_PE0_TX_DP<7>")
	)
	(segment
		(start 342.851994 -215.92667)
		(end 342.849708 -215.925146)
		(width 0.0889)
		(layer "In15.Cu")
		(net "P5E_CPU0_PE0_TX_DP<7>")
	)
	(segment
		(start 342.860122 -215.931242)
		(end 342.855804 -215.928702)
		(width 0.0889)
		(layer "In15.Cu")
		(net "P5E_CPU0_PE0_TX_DP<7>")
	)
	(segment
		(start 343.329768 -218.372944)
		(end 343.321894 -218.368372)
		(width 0.0889)
		(layer "In15.Cu")
		(net "P5E_CPU0_PE0_TX_DP<7>")
	)
	(segment
		(start 341.587074 -212.975952)
		(end 341.46744 -212.856318)
		(width 0.14732)
		(layer "In15.Cu")
		(net "P5E_CPU0_PE0_TX_DP<7>")
	)
	(segment
		(start 330.586588 -400.614134)
		(end 330.586588 -403.961854)
		(width 0.14732)
		(layer "In15.Cu")
		(net "P5E_CPU0_PE0_TX_DP<7>")
	)
	(segment
		(start 315.628782 -363.332268)
		(end 318.233552 -369.692936)
		(width 0.14732)
		(layer "In15.Cu")
		(net "P5E_CPU0_PE0_TX_DP<7>")
	)
	(segment
		(start 344.261694 -223.899476)
		(end 344.269568 -223.894904)
		(width 0.0889)
		(layer "In15.Cu")
		(net "P5E_CPU0_PE0_TX_DP<7>")
	)
	(segment
		(start 343.038684 -216.260426)
		(end 343.038684 -216.25052)
		(width 0.0889)
		(layer "In15.Cu")
		(net "P5E_CPU0_PE0_TX_DP<7>")
	)
	(segment
		(start 324.019164 -233.150918)
		(end 322.520056 -250.474226)
		(width 0.14732)
		(layer "In15.Cu")
		(net "P5E_CPU0_PE0_TX_DP<7>")
	)
	(segment
		(start 335.19745 -213.259162)
		(end 331.618844 -215.19769)
		(width 0.14732)
		(layer "In15.Cu")
		(net "P5E_CPU0_PE0_TX_DP<7>")
	)
	(segment
		(start 318.233552 -369.692936)
		(end 318.396112 -369.761008)
		(width 0.14732)
		(layer "In15.Cu")
		(net "P5E_CPU0_PE0_TX_DP<7>")
	)
	(segment
		(start 342.389968 -215.117426)
		(end 342.381078 -215.112346)
		(width 0.0889)
		(layer "In15.Cu")
		(net "P5E_CPU0_PE0_TX_DP<7>")
	)
	(segment
		(start 318.396112 -369.761008)
		(end 318.56172 -370.165376)
		(width 0.14732)
		(layer "In15.Cu")
		(net "P5E_CPU0_PE0_TX_DP<7>")
	)
	(segment
		(start 319.247266 -371.838982)
		(end 319.412874 -372.243604)
		(width 0.14732)
		(layer "In15.Cu")
		(net "P5E_CPU0_PE0_TX_DP<7>")
	)
	(segment
		(start 326.205596 -309.716424)
		(end 322.556378 -318.34963)
		(width 0.14732)
		(layer "In15.Cu")
		(net "P5E_CPU0_PE0_TX_DP<7>")
	)
	(segment
		(start 341.587074 -213.15045)
		(end 341.587074 -212.975952)
		(width 0.14732)
		(layer "In15.Cu")
		(net "P5E_CPU0_PE0_TX_DP<7>")
	)
	(segment
		(start 318.919352 -371.366796)
		(end 319.084706 -371.77091)
		(width 0.14732)
		(layer "In15.Cu")
		(net "P5E_CPU0_PE0_TX_DP<7>")
	)
	(segment
		(start 345.01328 -225.203258)
		(end 344.856816 -224.93224)
		(width 0.0889)
		(layer "In15.Cu")
		(net "P5E_CPU0_PE0_TX_DP<7>")
	)
	(segment
		(start 310.695848 -332.85049)
		(end 310.695848 -341.128858)
		(width 0.14732)
		(layer "In15.Cu")
		(net "P5E_CPU0_PE0_TX_DP<7>")
	)
	(segment
		(start 320.264282 -374.321832)
		(end 320.196464 -374.484138)
		(width 0.14732)
		(layer "In15.Cu")
		(net "P5E_CPU0_PE0_TX_DP<7>")
	)
	(segment
		(start 320.66992 -375.639838)
		(end 330.299568 -399.155666)
		(width 0.14732)
		(layer "In15.Cu")
		(net "P5E_CPU0_PE0_TX_DP<7>")
	)
	(segment
		(start 342.848438 -215.924384)
		(end 342.845136 -215.922606)
		(width 0.0889)
		(layer "In15.Cu")
		(net "P5E_CPU0_PE0_TX_DP<7>")
	)
	(segment
		(start 330.586588 -403.961854)
		(end 330.401168 -405.845264)
		(width 0.14732)
		(layer "In15.Cu")
		(net "P5E_CPU0_PE0_TX_DP<7>")
	)
	(segment
		(start 319.838578 -373.282718)
		(end 319.77076 -373.445024)
		(width 0.14732)
		(layer "In15.Cu")
		(net "P5E_CPU0_PE0_TX_DP<7>")
	)
	(segment
		(start 343.799922 -222.442278)
		(end 343.79027 -222.43669)
		(width 0.0889)
		(layer "In15.Cu")
		(net "P5E_CPU0_PE0_TX_DP<7>")
	)
	(segment
		(start 320.411602 -375.009664)
		(end 320.57086 -375.076466)
		(width 0.14732)
		(layer "In15.Cu")
		(net "P5E_CPU0_PE0_TX_DP<7>")
	)
	(segment
		(start 343.79027 -222.43669)
		(end 343.784936 -222.433642)
		(width 0.0889)
		(layer "In15.Cu")
		(net "P5E_CPU0_PE0_TX_DP<7>")
	)
	(segment
		(start 341.587074 -213.172548)
		(end 341.587074 -213.15045)
		(width 0.0889)
		(layer "In15.Cu")
		(net "P5E_CPU0_PE0_TX_DP<7>")
	)
	(segment
		(start 331.618844 -215.19769)
		(end 327.268332 -219.334842)
		(width 0.14732)
		(layer "In15.Cu")
		(net "P5E_CPU0_PE0_TX_DP<7>")
	)
	(segment
		(start 319.77076 -373.445024)
		(end 319.936114 -373.849138)
		(width 0.14732)
		(layer "In15.Cu")
		(net "P5E_CPU0_PE0_TX_DP<7>")
	)
	(segment
		(start 343.329768 -221.628462)
		(end 343.321894 -221.62389)
		(width 0.0889)
		(layer "In15.Cu")
		(net "P5E_CPU0_PE0_TX_DP<7>")
	)
	(segment
		(start 341.628984 -213.929722)
		(end 341.629238 -213.929468)
		(width 0.0889)
		(layer "In15.Cu")
		(net "P5E_CPU0_PE0_TX_DP<7>")
	)
	(segment
		(start 325.688452 -222.399606)
		(end 324.019164 -233.150918)
		(width 0.14732)
		(layer "In15.Cu")
		(net "P5E_CPU0_PE0_TX_DP<7>")
	)
	(segment
		(start 318.56172 -370.165376)
		(end 318.493648 -370.327682)
		(width 0.14732)
		(layer "In15.Cu")
		(net "P5E_CPU0_PE0_TX_DP<7>")
	)
	(segment
		(start 330.401168 -406.70988)
		(end 330.695808 -407.00452)
		(width 0.14732)
		(layer "In15.Cu")
		(net "P5E_CPU0_PE0_TX_DP<7>")
	)
	(segment
		(start 319.67297 -372.878096)
		(end 319.838578 -373.282718)
		(width 0.14732)
		(layer "In15.Cu")
		(net "P5E_CPU0_PE0_TX_DP<7>")
	)
	(segment
		(start 319.412874 -372.243604)
		(end 319.345056 -372.40591)
		(width 0.14732)
		(layer "In15.Cu")
		(net "P5E_CPU0_PE0_TX_DP<7>")
	)
	(segment
		(start 319.345056 -372.40591)
		(end 319.51041 -372.810024)
		(width 0.14732)
		(layer "In15.Cu")
		(net "P5E_CPU0_PE0_TX_DP<7>")
	)
	(arc
		(start 344.767916 -224.908618)
		(mid 344.758174 -224.912771)
		(end 344.748358 -224.916746)
		(width 0.0889)
		(layer "In15.Cu")
		(net "P5E_CPU0_PE0_TX_DP<7>")
	)
	(arc
		(start 342.56853 -215.436704)
		(mid 342.520851 -215.253804)
		(end 342.389968 -215.117426)
		(width 0.0889)
		(layer "In15.Cu")
		(net "P5E_CPU0_PE0_TX_DP<7>")
	)
	(arc
		(start 343.321132 -217.388694)
		(mid 343.508435 -217.064336)
		(end 343.321132 -216.739978)
		(width 0.0889)
		(layer "In15.Cu")
		(net "P5E_CPU0_PE0_TX_DP<7>")
	)
	(arc
		(start 342.098376 -214.461344)
		(mid 342.023371 -214.345885)
		(end 341.914226 -214.261954)
		(width 0.0889)
		(layer "In15.Cu")
		(net "P5E_CPU0_PE0_TX_DP<7>")
	)
	(arc
		(start 344.269568 -223.894904)
		(mid 344.448165 -223.575626)
		(end 344.269568 -223.256348)
		(width 0.0889)
		(layer "In15.Cu")
		(net "P5E_CPU0_PE0_TX_DP<7>")
	)
	(arc
		(start 343.038684 -216.25052)
		(mid 342.991005 -216.06762)
		(end 342.860122 -215.931242)
		(width 0.0889)
		(layer "In15.Cu")
		(net "P5E_CPU0_PE0_TX_DP<7>")
	)
	(arc
		(start 344.260678 -223.251268)
		(mid 344.059396 -223.053781)
		(end 343.978484 -222.783654)
		(width 0.0889)
		(layer "In15.Cu")
		(net "P5E_CPU0_PE0_TX_DP<7>")
	)
	(arc
		(start 343.321132 -219.995496)
		(mid 343.0386 -219.506148)
		(end 343.320878 -219.01658)
		(width 0.0889)
		(layer "In15.Cu")
		(net "P5E_CPU0_PE0_TX_DP<7>")
	)
	(arc
		(start 343.320878 -221.623382)
		(mid 343.118055 -221.423151)
		(end 343.038684 -221.149418)
		(width 0.0889)
		(layer "In15.Cu")
		(net "P5E_CPU0_PE0_TX_DP<7>")
	)
	(arc
		(start 343.329768 -219.0115)
		(mid 343.508244 -218.692222)
		(end 343.329768 -218.372944)
		(width 0.0889)
		(layer "In15.Cu")
		(net "P5E_CPU0_PE0_TX_DP<7>")
	)
	(arc
		(start 343.038684 -217.859864)
		(mid 343.118846 -217.587675)
		(end 343.321132 -217.388694)
		(width 0.0889)
		(layer "In15.Cu")
		(net "P5E_CPU0_PE0_TX_DP<7>")
	)
	(arc
		(start 344.748358 -224.916746)
		(mid 344.230689 -224.860579)
		(end 343.978484 -224.404936)
		(width 0.0889)
		(layer "In15.Cu")
		(net "P5E_CPU0_PE0_TX_DP<7>")
	)
	(arc
		(start 343.978484 -224.373948)
		(mid 344.057854 -224.100214)
		(end 344.260678 -223.899984)
		(width 0.0889)
		(layer "In15.Cu")
		(net "P5E_CPU0_PE0_TX_DP<7>")
	)
	(arc
		(start 343.978484 -222.761556)
		(mid 343.930805 -222.578656)
		(end 343.799922 -222.442278)
		(width 0.0889)
		(layer "In15.Cu")
		(net "P5E_CPU0_PE0_TX_DP<7>")
	)
	(arc
		(start 343.321132 -216.739978)
		(mid 343.116797 -216.537373)
		(end 343.038684 -216.260426)
		(width 0.0889)
		(layer "In15.Cu")
		(net "P5E_CPU0_PE0_TX_DP<7>")
	)
	(arc
		(start 343.320878 -218.367864)
		(mid 343.118055 -218.167633)
		(end 343.038684 -217.8939)
		(width 0.0889)
		(layer "In15.Cu")
		(net "P5E_CPU0_PE0_TX_DP<7>")
	)
	(arc
		(start 343.50833 -221.94774)
		(mid 343.460651 -221.76484)
		(end 343.329768 -221.628462)
		(width 0.0889)
		(layer "In15.Cu")
		(net "P5E_CPU0_PE0_TX_DP<7>")
	)
	(arc
		(start 341.644224 -213.969346)
		(mid 341.636261 -213.950049)
		(end 341.628984 -213.930484)
		(width 0.0889)
		(layer "In15.Cu")
		(net "P5E_CPU0_PE0_TX_DP<7>")
	)
	(arc
		(start 341.914226 -214.261954)
		(mid 341.754154 -214.138774)
		(end 341.644224 -213.969346)
		(width 0.0889)
		(layer "In15.Cu")
		(net "P5E_CPU0_PE0_TX_DP<7>")
	)
	(arc
		(start 342.381078 -215.112346)
		(mid 342.177597 -214.911542)
		(end 342.098376 -214.636858)
		(width 0.0889)
		(layer "In15.Cu")
		(net "P5E_CPU0_PE0_TX_DP<7>")
	)
	(arc
		(start 343.321132 -220.644212)
		(mid 343.508435 -220.319854)
		(end 343.321132 -219.995496)
		(width 0.0889)
		(layer "In15.Cu")
		(net "P5E_CPU0_PE0_TX_DP<7>")
	)
	(arc
		(start 343.784936 -222.433642)
		(mid 343.582349 -222.227291)
		(end 343.50833 -221.94774)
		(width 0.0889)
		(layer "In15.Cu")
		(net "P5E_CPU0_PE0_TX_DP<7>")
	)
	(arc
		(start 342.845136 -215.922606)
		(mid 342.642549 -215.716255)
		(end 342.56853 -215.436704)
		(width 0.0889)
		(layer "In15.Cu")
		(net "P5E_CPU0_PE0_TX_DP<7>")
	)
	(arc
		(start 343.038684 -221.115382)
		(mid 343.118846 -220.843193)
		(end 343.321132 -220.644212)
		(width 0.0889)
		(layer "In15.Cu")
		(net "P5E_CPU0_PE0_TX_DP<7>")
	)
	(segment
		(start 343.60358 -224.925382)
		(end 343.60358 -224.389696)
		(width 0.13208)
		(layer "F.Cu")
		(net "P5E_CPU0_PE0_TX_DP<6>")
	)
	(segment
		(start 333.46009 -407.303478)
		(end 333.46009 -407.926286)
		(width 0.13208)
		(layer "F.Cu")
		(net "P5E_CPU0_PE0_TX_DP<6>")
	)
	(segment
		(start 333.46009 -407.926286)
		(end 333.784448 -408.250644)
		(width 0.13208)
		(layer "F.Cu")
		(net "P5E_CPU0_PE0_TX_DP<6>")
	)
	(segment
		(start 343.60358 -224.389696)
		(end 343.603834 -224.389442)
		(width 0.13208)
		(layer "F.Cu")
		(net "P5E_CPU0_PE0_TX_DP<6>")
	)
	(segment
		(start 333.759048 -407.00452)
		(end 333.46009 -407.303478)
		(width 0.13208)
		(layer "F.Cu")
		(net "P5E_CPU0_PE0_TX_DP<6>")
	)
	(segment
		(start 342.382094 -219.996004)
		(end 342.381078 -219.995496)
		(width 0.0889)
		(layer "In15.Cu")
		(net "P5E_CPU0_PE0_TX_DP<6>")
	)
	(segment
		(start 342.381078 -220.644212)
		(end 342.389968 -220.639132)
		(width 0.0889)
		(layer "In15.Cu")
		(net "P5E_CPU0_PE0_TX_DP<6>")
	)
	(segment
		(start 342.389968 -220.000576)
		(end 342.382094 -219.996004)
		(width 0.0889)
		(layer "In15.Cu")
		(net "P5E_CPU0_PE0_TX_DP<6>")
	)
	(segment
		(start 321.57289 -373.909336)
		(end 333.649828 -399.885916)
		(width 0.14732)
		(layer "In15.Cu")
		(net "P5E_CPU0_PE0_TX_DP<6>")
	)
	(segment
		(start 323.401182 -251.93625)
		(end 327.173082 -309.882794)
		(width 0.14732)
		(layer "In15.Cu")
		(net "P5E_CPU0_PE0_TX_DP<6>")
	)
	(segment
		(start 341.912956 -215.926924)
		(end 341.911432 -215.926162)
		(width 0.0889)
		(layer "In15.Cu")
		(net "P5E_CPU0_PE0_TX_DP<6>")
	)
	(segment
		(start 320.810128 -372.26875)
		(end 320.975736 -372.329202)
		(width 0.14732)
		(layer "In15.Cu")
		(net "P5E_CPU0_PE0_TX_DP<6>")
	)
	(segment
		(start 342.382094 -221.62389)
		(end 342.381078 -221.623382)
		(width 0.0889)
		(layer "In15.Cu")
		(net "P5E_CPU0_PE0_TX_DP<6>")
	)
	(segment
		(start 317.28918 -327.64603)
		(end 311.625488 -333.309722)
		(width 0.14732)
		(layer "In15.Cu")
		(net "P5E_CPU0_PE0_TX_DP<6>")
	)
	(segment
		(start 343.50833 -223.575626)
		(end 343.50833 -223.56699)
		(width 0.0889)
		(layer "In15.Cu")
		(net "P5E_CPU0_PE0_TX_DP<6>")
	)
	(segment
		(start 335.631028 -214.179912)
		(end 335.24698 -214.387938)
		(width 0.14732)
		(layer "In15.Cu")
		(net "P5E_CPU0_PE0_TX_DP<6>")
	)
	(segment
		(start 321.099434 -372.89105)
		(end 321.283584 -373.287036)
		(width 0.14732)
		(layer "In15.Cu")
		(net "P5E_CPU0_PE0_TX_DP<6>")
	)
	(segment
		(start 338.339176 -214.636858)
		(end 338.339176 -214.461344)
		(width 0.0889)
		(layer "In15.Cu")
		(net "P5E_CPU0_PE0_TX_DP<6>")
	)
	(segment
		(start 342.381078 -217.388694)
		(end 342.389968 -217.383614)
		(width 0.0889)
		(layer "In15.Cu")
		(net "P5E_CPU0_PE0_TX_DP<6>")
	)
	(segment
		(start 323.444108 -250.66117)
		(end 323.401182 -251.93625)
		(width 0.14732)
		(layer "In15.Cu")
		(net "P5E_CPU0_PE0_TX_DP<6>")
	)
	(segment
		(start 342.098884 -217.8939)
		(end 342.098884 -217.856308)
		(width 0.0889)
		(layer "In15.Cu")
		(net "P5E_CPU0_PE0_TX_DP<6>")
	)
	(segment
		(start 320.028824 -370.29263)
		(end 320.212974 -370.689124)
		(width 0.14732)
		(layer "In15.Cu")
		(net "P5E_CPU0_PE0_TX_DP<6>")
	)
	(segment
		(start 333.464408 -406.70988)
		(end 333.759048 -407.00452)
		(width 0.14732)
		(layer "In15.Cu")
		(net "P5E_CPU0_PE0_TX_DP<6>")
	)
	(segment
		(start 333.464408 -405.845264)
		(end 333.464408 -406.70988)
		(width 0.14732)
		(layer "In15.Cu")
		(net "P5E_CPU0_PE0_TX_DP<6>")
	)
	(segment
		(start 332.130908 -216.075768)
		(end 328.026268 -219.914724)
		(width 0.14732)
		(layer "In15.Cu")
		(net "P5E_CPU0_PE0_TX_DP<6>")
	)
	(segment
		(start 343.038684 -222.780098)
		(end 343.038684 -222.761556)
		(width 0.0889)
		(layer "In15.Cu")
		(net "P5E_CPU0_PE0_TX_DP<6>")
	)
	(segment
		(start 334.813402 -214.761572)
		(end 334.648302 -214.712296)
		(width 0.14732)
		(layer "In15.Cu")
		(net "P5E_CPU0_PE0_TX_DP<6>")
	)
	(segment
		(start 340.046564 -215.934798)
		(end 340.031832 -215.926162)
		(width 0.0889)
		(layer "In15.Cu")
		(net "P5E_CPU0_PE0_TX_DP<6>")
	)
	(segment
		(start 324.960488 -233.200194)
		(end 323.444108 -250.66117)
		(width 0.14732)
		(layer "In15.Cu")
		(net "P5E_CPU0_PE0_TX_DP<6>")
	)
	(segment
		(start 320.50228 -371.310916)
		(end 320.68643 -371.70741)
		(width 0.14732)
		(layer "In15.Cu")
		(net "P5E_CPU0_PE0_TX_DP<6>")
	)
	(segment
		(start 320.625978 -371.872764)
		(end 320.810128 -372.26875)
		(width 0.14732)
		(layer "In15.Cu")
		(net "P5E_CPU0_PE0_TX_DP<6>")
	)
	(segment
		(start 339.106764 -215.934798)
		(end 339.092032 -215.926162)
		(width 0.0889)
		(layer "In15.Cu")
		(net "P5E_CPU0_PE0_TX_DP<6>")
	)
	(segment
		(start 319.390014 -369.214146)
		(end 319.555368 -369.274598)
		(width 0.14732)
		(layer "In15.Cu")
		(net "P5E_CPU0_PE0_TX_DP<6>")
	)
	(segment
		(start 339.092032 -215.926162)
		(end 339.09127 -215.925654)
		(width 0.0889)
		(layer "In15.Cu")
		(net "P5E_CPU0_PE0_TX_DP<6>")
	)
	(segment
		(start 320.152522 -370.854478)
		(end 320.336672 -371.250464)
		(width 0.14732)
		(layer "In15.Cu")
		(net "P5E_CPU0_PE0_TX_DP<6>")
	)
	(segment
		(start 320.212974 -370.689124)
		(end 320.152522 -370.854478)
		(width 0.14732)
		(layer "In15.Cu")
		(net "P5E_CPU0_PE0_TX_DP<6>")
	)
	(segment
		(start 326.591168 -222.697802)
		(end 324.960488 -233.200194)
		(width 0.14732)
		(layer "In15.Cu")
		(net "P5E_CPU0_PE0_TX_DP<6>")
	)
	(segment
		(start 342.098884 -221.149418)
		(end 342.098884 -221.111826)
		(width 0.0889)
		(layer "In15.Cu")
		(net "P5E_CPU0_PE0_TX_DP<6>")
	)
	(segment
		(start 342.382094 -216.740486)
		(end 342.381078 -216.739978)
		(width 0.0889)
		(layer "In15.Cu")
		(net "P5E_CPU0_PE0_TX_DP<6>")
	)
	(segment
		(start 339.09127 -215.925654)
		(end 339.085936 -215.922606)
		(width 0.0889)
		(layer "In15.Cu")
		(net "P5E_CPU0_PE0_TX_DP<6>")
	)
	(segment
		(start 337.60537 -214.179912)
		(end 335.631028 -214.179912)
		(width 0.14732)
		(layer "In15.Cu")
		(net "P5E_CPU0_PE0_TX_DP<6>")
	)
	(segment
		(start 338.03082 -214.137748)
		(end 337.669632 -214.137748)
		(width 0.0889)
		(layer "In15.Cu")
		(net "P5E_CPU0_PE0_TX_DP<6>")
	)
	(segment
		(start 335.197958 -214.553292)
		(end 334.813402 -214.761572)
		(width 0.14732)
		(layer "In15.Cu")
		(net "P5E_CPU0_PE0_TX_DP<6>")
	)
	(segment
		(start 321.159886 -372.725696)
		(end 321.099434 -372.89105)
		(width 0.14732)
		(layer "In15.Cu")
		(net "P5E_CPU0_PE0_TX_DP<6>")
	)
	(segment
		(start 316.513464 -363.027214)
		(end 319.390014 -369.214146)
		(width 0.14732)
		(layer "In15.Cu")
		(net "P5E_CPU0_PE0_TX_DP<6>")
	)
	(segment
		(start 342.85047 -222.43669)
		(end 342.845136 -222.433642)
		(width 0.0889)
		(layer "In15.Cu")
		(net "P5E_CPU0_PE0_TX_DP<6>")
	)
	(segment
		(start 342.860122 -222.442278)
		(end 342.85047 -222.43669)
		(width 0.0889)
		(layer "In15.Cu")
		(net "P5E_CPU0_PE0_TX_DP<6>")
	)
	(segment
		(start 342.389968 -216.745058)
		(end 342.382094 -216.740486)
		(width 0.0889)
		(layer "In15.Cu")
		(net "P5E_CPU0_PE0_TX_DP<6>")
	)
	(segment
		(start 319.739518 -369.670838)
		(end 319.679066 -369.836192)
		(width 0.14732)
		(layer "In15.Cu")
		(net "P5E_CPU0_PE0_TX_DP<6>")
	)
	(segment
		(start 342.098884 -216.266014)
		(end 342.098884 -216.25052)
		(width 0.0889)
		(layer "In15.Cu")
		(net "P5E_CPU0_PE0_TX_DP<6>")
	)
	(segment
		(start 311.625488 -333.309722)
		(end 311.625488 -341.026496)
		(width 0.14732)
		(layer "In15.Cu")
		(net "P5E_CPU0_PE0_TX_DP<6>")
	)
	(segment
		(start 342.389968 -218.372944)
		(end 342.382094 -218.368372)
		(width 0.0889)
		(layer "In15.Cu")
		(net "P5E_CPU0_PE0_TX_DP<6>")
	)
	(segment
		(start 343.603834 -224.389442)
		(end 343.760298 -224.118424)
		(width 0.0889)
		(layer "In15.Cu")
		(net "P5E_CPU0_PE0_TX_DP<6>")
	)
	(segment
		(start 337.669632 -214.137748)
		(end 337.627468 -214.179912)
		(width 0.0889)
		(layer "In15.Cu")
		(net "P5E_CPU0_PE0_TX_DP<6>")
	)
	(segment
		(start 323.249798 -319.133982)
		(end 317.28918 -327.64603)
		(width 0.14732)
		(layer "In15.Cu")
		(net "P5E_CPU0_PE0_TX_DP<6>")
	)
	(segment
		(start 342.098884 -219.521532)
		(end 342.098884 -219.490544)
		(width 0.0889)
		(layer "In15.Cu")
		(net "P5E_CPU0_PE0_TX_DP<6>")
	)
	(segment
		(start 321.283584 -373.287036)
		(end 321.449192 -373.347488)
		(width 0.14732)
		(layer "In15.Cu")
		(net "P5E_CPU0_PE0_TX_DP<6>")
	)
	(segment
		(start 320.68643 -371.70741)
		(end 320.625978 -371.872764)
		(width 0.14732)
		(layer "In15.Cu")
		(net "P5E_CPU0_PE0_TX_DP<6>")
	)
	(segment
		(start 338.630768 -215.117426)
		(end 338.621878 -215.112346)
		(width 0.0889)
		(layer "In15.Cu")
		(net "P5E_CPU0_PE0_TX_DP<6>")
	)
	(segment
		(start 311.625488 -341.026496)
		(end 316.513464 -363.027214)
		(width 0.14732)
		(layer "In15.Cu")
		(net "P5E_CPU0_PE0_TX_DP<6>")
	)
	(segment
		(start 320.975736 -372.329202)
		(end 321.159886 -372.725696)
		(width 0.14732)
		(layer "In15.Cu")
		(net "P5E_CPU0_PE0_TX_DP<6>")
	)
	(segment
		(start 319.555368 -369.274598)
		(end 319.739518 -369.670838)
		(width 0.14732)
		(layer "In15.Cu")
		(net "P5E_CPU0_PE0_TX_DP<6>")
	)
	(segment
		(start 319.863216 -370.232178)
		(end 320.028824 -370.29263)
		(width 0.14732)
		(layer "In15.Cu")
		(net "P5E_CPU0_PE0_TX_DP<6>")
	)
	(segment
		(start 319.679066 -369.836192)
		(end 319.863216 -370.232178)
		(width 0.14732)
		(layer "In15.Cu")
		(net "P5E_CPU0_PE0_TX_DP<6>")
	)
	(segment
		(start 320.336672 -371.250464)
		(end 320.50228 -371.310916)
		(width 0.14732)
		(layer "In15.Cu")
		(net "P5E_CPU0_PE0_TX_DP<6>")
	)
	(segment
		(start 342.381078 -219.01658)
		(end 342.389968 -219.0115)
		(width 0.0889)
		(layer "In15.Cu")
		(net "P5E_CPU0_PE0_TX_DP<6>")
	)
	(segment
		(start 341.920322 -215.931242)
		(end 341.912956 -215.926924)
		(width 0.0889)
		(layer "In15.Cu")
		(net "P5E_CPU0_PE0_TX_DP<6>")
	)
	(segment
		(start 340.986364 -215.934798)
		(end 340.971632 -215.926162)
		(width 0.0889)
		(layer "In15.Cu")
		(net "P5E_CPU0_PE0_TX_DP<6>")
	)
	(segment
		(start 335.24698 -214.387938)
		(end 335.197958 -214.553292)
		(width 0.14732)
		(layer "In15.Cu")
		(net "P5E_CPU0_PE0_TX_DP<6>")
	)
	(segment
		(start 343.760298 -224.118424)
		(end 343.736168 -224.02927)
		(width 0.0889)
		(layer "In15.Cu")
		(net "P5E_CPU0_PE0_TX_DP<6>")
	)
	(segment
		(start 334.648302 -214.712296)
		(end 332.130908 -216.075768)
		(width 0.14732)
		(layer "In15.Cu")
		(net "P5E_CPU0_PE0_TX_DP<6>")
	)
	(segment
		(start 328.026268 -219.914724)
		(end 326.591168 -222.697802)
		(width 0.14732)
		(layer "In15.Cu")
		(net "P5E_CPU0_PE0_TX_DP<6>")
	)
	(segment
		(start 321.449192 -373.347488)
		(end 321.633342 -373.743982)
		(width 0.14732)
		(layer "In15.Cu")
		(net "P5E_CPU0_PE0_TX_DP<6>")
	)
	(segment
		(start 333.649828 -399.885916)
		(end 333.649828 -403.961854)
		(width 0.14732)
		(layer "In15.Cu")
		(net "P5E_CPU0_PE0_TX_DP<6>")
	)
	(segment
		(start 337.627468 -214.179912)
		(end 337.60537 -214.179912)
		(width 0.0889)
		(layer "In15.Cu")
		(net "P5E_CPU0_PE0_TX_DP<6>")
	)
	(segment
		(start 342.382094 -218.368372)
		(end 342.381078 -218.367864)
		(width 0.0889)
		(layer "In15.Cu")
		(net "P5E_CPU0_PE0_TX_DP<6>")
	)
	(segment
		(start 333.649828 -403.961854)
		(end 333.464408 -405.845264)
		(width 0.14732)
		(layer "In15.Cu")
		(net "P5E_CPU0_PE0_TX_DP<6>")
	)
	(segment
		(start 338.155026 -214.261954)
		(end 338.03082 -214.137748)
		(width 0.0889)
		(layer "In15.Cu")
		(net "P5E_CPU0_PE0_TX_DP<6>")
	)
	(segment
		(start 327.173082 -309.882794)
		(end 323.249798 -319.133982)
		(width 0.14732)
		(layer "In15.Cu")
		(net "P5E_CPU0_PE0_TX_DP<6>")
	)
	(segment
		(start 342.389968 -221.628462)
		(end 342.382094 -221.62389)
		(width 0.0889)
		(layer "In15.Cu")
		(net "P5E_CPU0_PE0_TX_DP<6>")
	)
	(segment
		(start 321.633342 -373.743982)
		(end 321.57289 -373.909336)
		(width 0.14732)
		(layer "In15.Cu")
		(net "P5E_CPU0_PE0_TX_DP<6>")
	)
	(arc
		(start 342.389968 -219.0115)
		(mid 342.568444 -218.692222)
		(end 342.389968 -218.372944)
		(width 0.0889)
		(layer "In15.Cu")
		(net "P5E_CPU0_PE0_TX_DP<6>")
	)
	(arc
		(start 342.098884 -221.111826)
		(mid 342.179795 -220.841698)
		(end 342.381078 -220.644212)
		(width 0.0889)
		(layer "In15.Cu")
		(net "P5E_CPU0_PE0_TX_DP<6>")
	)
	(arc
		(start 343.038684 -222.761556)
		(mid 342.991005 -222.578656)
		(end 342.860122 -222.442278)
		(width 0.0889)
		(layer "In15.Cu")
		(net "P5E_CPU0_PE0_TX_DP<6>")
	)
	(arc
		(start 342.098884 -216.25052)
		(mid 342.051205 -216.06762)
		(end 341.920322 -215.931242)
		(width 0.0889)
		(layer "In15.Cu")
		(net "P5E_CPU0_PE0_TX_DP<6>")
	)
	(arc
		(start 342.381078 -218.367864)
		(mid 342.178255 -218.167633)
		(end 342.098884 -217.8939)
		(width 0.0889)
		(layer "In15.Cu")
		(net "P5E_CPU0_PE0_TX_DP<6>")
	)
	(arc
		(start 342.381078 -219.995496)
		(mid 342.178255 -219.795265)
		(end 342.098884 -219.521532)
		(width 0.0889)
		(layer "In15.Cu")
		(net "P5E_CPU0_PE0_TX_DP<6>")
	)
	(arc
		(start 343.736168 -224.02927)
		(mid 343.568414 -223.829492)
		(end 343.50833 -223.575626)
		(width 0.0889)
		(layer "In15.Cu")
		(net "P5E_CPU0_PE0_TX_DP<6>")
	)
	(arc
		(start 342.381078 -216.739978)
		(mid 342.178255 -216.539747)
		(end 342.098884 -216.266014)
		(width 0.0889)
		(layer "In15.Cu")
		(net "P5E_CPU0_PE0_TX_DP<6>")
	)
	(arc
		(start 340.971632 -215.926162)
		(mid 340.784434 -215.876019)
		(end 340.597236 -215.926162)
		(width 0.0889)
		(layer "In15.Cu")
		(net "P5E_CPU0_PE0_TX_DP<6>")
	)
	(arc
		(start 341.537036 -215.926162)
		(mid 341.262837 -216.001997)
		(end 340.986364 -215.934798)
		(width 0.0889)
		(layer "In15.Cu")
		(net "P5E_CPU0_PE0_TX_DP<6>")
	)
	(arc
		(start 342.098884 -217.856308)
		(mid 342.179795 -217.58618)
		(end 342.381078 -217.388694)
		(width 0.0889)
		(layer "In15.Cu")
		(net "P5E_CPU0_PE0_TX_DP<6>")
	)
	(arc
		(start 342.845136 -222.433642)
		(mid 342.642549 -222.227291)
		(end 342.56853 -221.94774)
		(width 0.0889)
		(layer "In15.Cu")
		(net "P5E_CPU0_PE0_TX_DP<6>")
	)
	(arc
		(start 342.389968 -217.383614)
		(mid 342.568565 -217.064336)
		(end 342.389968 -216.745058)
		(width 0.0889)
		(layer "In15.Cu")
		(net "P5E_CPU0_PE0_TX_DP<6>")
	)
	(arc
		(start 342.381078 -221.623382)
		(mid 342.178255 -221.423151)
		(end 342.098884 -221.149418)
		(width 0.0889)
		(layer "In15.Cu")
		(net "P5E_CPU0_PE0_TX_DP<6>")
	)
	(arc
		(start 343.50833 -223.56699)
		(mid 343.45606 -223.384625)
		(end 343.321132 -223.251268)
		(width 0.0889)
		(layer "In15.Cu")
		(net "P5E_CPU0_PE0_TX_DP<6>")
	)
	(arc
		(start 340.597236 -215.926162)
		(mid 340.323037 -216.001997)
		(end 340.046564 -215.934798)
		(width 0.0889)
		(layer "In15.Cu")
		(net "P5E_CPU0_PE0_TX_DP<6>")
	)
	(arc
		(start 340.031832 -215.926162)
		(mid 339.844634 -215.876019)
		(end 339.657436 -215.926162)
		(width 0.0889)
		(layer "In15.Cu")
		(net "P5E_CPU0_PE0_TX_DP<6>")
	)
	(arc
		(start 338.621878 -215.112346)
		(mid 338.418397 -214.911542)
		(end 338.339176 -214.636858)
		(width 0.0889)
		(layer "In15.Cu")
		(net "P5E_CPU0_PE0_TX_DP<6>")
	)
	(arc
		(start 338.339176 -214.461344)
		(mid 338.264171 -214.345885)
		(end 338.155026 -214.261954)
		(width 0.0889)
		(layer "In15.Cu")
		(net "P5E_CPU0_PE0_TX_DP<6>")
	)
	(arc
		(start 342.389968 -220.639132)
		(mid 342.568565 -220.319854)
		(end 342.389968 -220.000576)
		(width 0.0889)
		(layer "In15.Cu")
		(net "P5E_CPU0_PE0_TX_DP<6>")
	)
	(arc
		(start 342.56853 -221.94774)
		(mid 342.520851 -221.76484)
		(end 342.389968 -221.628462)
		(width 0.0889)
		(layer "In15.Cu")
		(net "P5E_CPU0_PE0_TX_DP<6>")
	)
	(arc
		(start 339.657436 -215.926162)
		(mid 339.383237 -216.001997)
		(end 339.106764 -215.934798)
		(width 0.0889)
		(layer "In15.Cu")
		(net "P5E_CPU0_PE0_TX_DP<6>")
	)
	(arc
		(start 339.085936 -215.922606)
		(mid 338.883349 -215.716255)
		(end 338.80933 -215.436704)
		(width 0.0889)
		(layer "In15.Cu")
		(net "P5E_CPU0_PE0_TX_DP<6>")
	)
	(arc
		(start 341.911432 -215.926162)
		(mid 341.724234 -215.876019)
		(end 341.537036 -215.926162)
		(width 0.0889)
		(layer "In15.Cu")
		(net "P5E_CPU0_PE0_TX_DP<6>")
	)
	(arc
		(start 338.80933 -215.436704)
		(mid 338.761651 -215.253804)
		(end 338.630768 -215.117426)
		(width 0.0889)
		(layer "In15.Cu")
		(net "P5E_CPU0_PE0_TX_DP<6>")
	)
	(arc
		(start 342.098884 -219.490544)
		(mid 342.178254 -219.21681)
		(end 342.381078 -219.01658)
		(width 0.0889)
		(layer "In15.Cu")
		(net "P5E_CPU0_PE0_TX_DP<6>")
	)
	(arc
		(start 343.321132 -223.251268)
		(mid 343.118846 -223.052287)
		(end 343.038684 -222.780098)
		(width 0.0889)
		(layer "In15.Cu")
		(net "P5E_CPU0_PE0_TX_DP<6>")
	)
	(segment
		(start 336.822288 -407.00452)
		(end 336.52333 -407.303478)
		(width 0.13208)
		(layer "F.Cu")
		(net "P5E_CPU0_PE0_TX_DP<5>")
	)
	(segment
		(start 336.52333 -407.926286)
		(end 336.847688 -408.250644)
		(width 0.13208)
		(layer "F.Cu")
		(net "P5E_CPU0_PE0_TX_DP<5>")
	)
	(segment
		(start 343.133934 -225.739198)
		(end 343.133934 -225.203512)
		(width 0.13208)
		(layer "F.Cu")
		(net "P5E_CPU0_PE0_TX_DP<5>")
	)
	(segment
		(start 336.52333 -407.303478)
		(end 336.52333 -407.926286)
		(width 0.13208)
		(layer "F.Cu")
		(net "P5E_CPU0_PE0_TX_DP<5>")
	)
	(segment
		(start 343.133934 -225.203512)
		(end 343.13368 -225.203258)
		(width 0.13208)
		(layer "F.Cu")
		(net "P5E_CPU0_PE0_TX_DP<5>")
	)
	(segment
		(start 342.382094 -223.899476)
		(end 342.389968 -223.894904)
		(width 0.0889)
		(layer "In15.Cu")
		(net "P5E_CPU0_PE0_TX_DP<5>")
	)
	(segment
		(start 327.038462 -381.226822)
		(end 327.206356 -381.279908)
		(width 0.14732)
		(layer "In15.Cu")
		(net "P5E_CPU0_PE0_TX_DP<5>")
	)
	(segment
		(start 326.145906 -244.720364)
		(end 326.678036 -247.572022)
		(width 0.14732)
		(layer "In15.Cu")
		(net "P5E_CPU0_PE0_TX_DP<5>")
	)
	(segment
		(start 342.977216 -224.93224)
		(end 342.888316 -224.908618)
		(width 0.0889)
		(layer "In15.Cu")
		(net "P5E_CPU0_PE0_TX_DP<5>")
	)
	(segment
		(start 327.556114 -382.223264)
		(end 327.724262 -382.27635)
		(width 0.14732)
		(layer "In15.Cu")
		(net "P5E_CPU0_PE0_TX_DP<5>")
	)
	(segment
		(start 338.247482 -216.739978)
		(end 338.237068 -216.746074)
		(width 0.0889)
		(layer "In15.Cu")
		(net "P5E_CPU0_PE0_TX_DP<5>")
	)
	(segment
		(start 328.125328 -310.074818)
		(end 324.178676 -319.452244)
		(width 0.14732)
		(layer "In15.Cu")
		(net "P5E_CPU0_PE0_TX_DP<5>")
	)
	(segment
		(start 327.724262 -382.27635)
		(end 327.925684 -382.664462)
		(width 0.14732)
		(layer "In15.Cu")
		(net "P5E_CPU0_PE0_TX_DP<5>")
	)
	(segment
		(start 324.178676 -319.452244)
		(end 317.847472 -328.493882)
		(width 0.14732)
		(layer "In15.Cu")
		(net "P5E_CPU0_PE0_TX_DP<5>")
	)
	(segment
		(start 328.90841 -384.824986)
		(end 336.713068 -399.843752)
		(width 0.14732)
		(layer "In15.Cu")
		(net "P5E_CPU0_PE0_TX_DP<5>")
	)
	(segment
		(start 328.58583 -252.268736)
		(end 326.064372 -258.7371)
		(width 0.14732)
		(layer "In15.Cu")
		(net "P5E_CPU0_PE0_TX_DP<5>")
	)
	(segment
		(start 328.074274 -383.219706)
		(end 328.242168 -383.272792)
		(width 0.14732)
		(layer "In15.Cu")
		(net "P5E_CPU0_PE0_TX_DP<5>")
	)
	(segment
		(start 317.38951 -362.659676)
		(end 327.038462 -381.226822)
		(width 0.14732)
		(layer "In15.Cu")
		(net "P5E_CPU0_PE0_TX_DP<5>")
	)
	(segment
		(start 332.967584 -216.731596)
		(end 332.771496 -216.80932)
		(width 0.14732)
		(layer "In15.Cu")
		(net "P5E_CPU0_PE0_TX_DP<5>")
	)
	(segment
		(start 327.872598 -382.832102)
		(end 328.074274 -383.219706)
		(width 0.14732)
		(layer "In15.Cu")
		(net "P5E_CPU0_PE0_TX_DP<5>")
	)
	(segment
		(start 328.827384 -220.508322)
		(end 327.65365 -222.795084)
		(width 0.14732)
		(layer "In15.Cu")
		(net "P5E_CPU0_PE0_TX_DP<5>")
	)
	(segment
		(start 325.356982 -266.59586)
		(end 328.125328 -310.074818)
		(width 0.14732)
		(layer "In15.Cu")
		(net "P5E_CPU0_PE0_TX_DP<5>")
	)
	(segment
		(start 336.527648 -405.845264)
		(end 336.527648 -406.70988)
		(width 0.14732)
		(layer "In15.Cu")
		(net "P5E_CPU0_PE0_TX_DP<5>")
	)
	(segment
		(start 342.098884 -222.783654)
		(end 342.098884 -222.761556)
		(width 0.0889)
		(layer "In15.Cu")
		(net "P5E_CPU0_PE0_TX_DP<5>")
	)
	(segment
		(start 327.407778 -381.66802)
		(end 327.354692 -381.83566)
		(width 0.14732)
		(layer "In15.Cu")
		(net "P5E_CPU0_PE0_TX_DP<5>")
	)
	(segment
		(start 327.206356 -381.279908)
		(end 327.407778 -381.66802)
		(width 0.14732)
		(layer "In15.Cu")
		(net "P5E_CPU0_PE0_TX_DP<5>")
	)
	(segment
		(start 326.678036 -247.572022)
		(end 328.292968 -250.58878)
		(width 0.14732)
		(layer "In15.Cu")
		(net "P5E_CPU0_PE0_TX_DP<5>")
	)
	(segment
		(start 341.159084 -221.149418)
		(end 341.159084 -221.115382)
		(width 0.0889)
		(layer "In15.Cu")
		(net "P5E_CPU0_PE0_TX_DP<5>")
	)
	(segment
		(start 312.56732 -340.954106)
		(end 317.38951 -362.659676)
		(width 0.14732)
		(layer "In15.Cu")
		(net "P5E_CPU0_PE0_TX_DP<5>")
	)
	(segment
		(start 328.44359 -383.66065)
		(end 328.390504 -383.828544)
		(width 0.14732)
		(layer "In15.Cu")
		(net "P5E_CPU0_PE0_TX_DP<5>")
	)
	(segment
		(start 327.65365 -222.795084)
		(end 325.943214 -233.628692)
		(width 0.14732)
		(layer "In15.Cu")
		(net "P5E_CPU0_PE0_TX_DP<5>")
	)
	(segment
		(start 328.961242 -384.657092)
		(end 328.90841 -384.824986)
		(width 0.14732)
		(layer "In15.Cu")
		(net "P5E_CPU0_PE0_TX_DP<5>")
	)
	(segment
		(start 337.682332 -216.739978)
		(end 337.67395 -216.735152)
		(width 0.0889)
		(layer "In15.Cu")
		(net "P5E_CPU0_PE0_TX_DP<5>")
	)
	(segment
		(start 341.91067 -222.43669)
		(end 341.905336 -222.433642)
		(width 0.0889)
		(layer "In15.Cu")
		(net "P5E_CPU0_PE0_TX_DP<5>")
	)
	(segment
		(start 342.381078 -223.899984)
		(end 342.382094 -223.899476)
		(width 0.0889)
		(layer "In15.Cu")
		(net "P5E_CPU0_PE0_TX_DP<5>")
	)
	(segment
		(start 334.67548 -216.689432)
		(end 333.26959 -216.689432)
		(width 0.0889)
		(layer "In15.Cu")
		(net "P5E_CPU0_PE0_TX_DP<5>")
	)
	(segment
		(start 327.925684 -382.664462)
		(end 327.872598 -382.832102)
		(width 0.14732)
		(layer "In15.Cu")
		(net "P5E_CPU0_PE0_TX_DP<5>")
	)
	(segment
		(start 341.450168 -221.628462)
		(end 341.441278 -221.623382)
		(width 0.0889)
		(layer "In15.Cu")
		(net "P5E_CPU0_PE0_TX_DP<5>")
	)
	(segment
		(start 336.75701 -216.748614)
		(end 336.742278 -216.739978)
		(width 0.0889)
		(layer "In15.Cu")
		(net "P5E_CPU0_PE0_TX_DP<5>")
	)
	(segment
		(start 341.920322 -222.442278)
		(end 341.91067 -222.43669)
		(width 0.0889)
		(layer "In15.Cu")
		(net "P5E_CPU0_PE0_TX_DP<5>")
	)
	(segment
		(start 342.389968 -223.256348)
		(end 342.382094 -223.251776)
		(width 0.0889)
		(layer "In15.Cu")
		(net "P5E_CPU0_PE0_TX_DP<5>")
	)
	(segment
		(start 312.56732 -333.774034)
		(end 312.56732 -340.954106)
		(width 0.14732)
		(layer "In15.Cu")
		(net "P5E_CPU0_PE0_TX_DP<5>")
	)
	(segment
		(start 336.713068 -403.961854)
		(end 336.527648 -405.845264)
		(width 0.14732)
		(layer "In15.Cu")
		(net "P5E_CPU0_PE0_TX_DP<5>")
	)
	(segment
		(start 326.063864 -258.7371)
		(end 325.356982 -266.59586)
		(width 0.14732)
		(layer "In15.Cu")
		(net "P5E_CPU0_PE0_TX_DP<5>")
	)
	(segment
		(start 328.586338 -252.26899)
		(end 328.58583 -252.268736)
		(width 0.14732)
		(layer "In15.Cu")
		(net "P5E_CPU0_PE0_TX_DP<5>")
	)
	(segment
		(start 328.591926 -384.216148)
		(end 328.75982 -384.269234)
		(width 0.14732)
		(layer "In15.Cu")
		(net "P5E_CPU0_PE0_TX_DP<5>")
	)
	(segment
		(start 333.227426 -216.731596)
		(end 333.205328 -216.731596)
		(width 0.0889)
		(layer "In15.Cu")
		(net "P5E_CPU0_PE0_TX_DP<5>")
	)
	(segment
		(start 343.13368 -225.203258)
		(end 342.977216 -224.93224)
		(width 0.0889)
		(layer "In15.Cu")
		(net "P5E_CPU0_PE0_TX_DP<5>")
	)
	(segment
		(start 333.26959 -216.689432)
		(end 333.227426 -216.731596)
		(width 0.0889)
		(layer "In15.Cu")
		(net "P5E_CPU0_PE0_TX_DP<5>")
	)
	(segment
		(start 340.972394 -217.554556)
		(end 340.971632 -217.554048)
		(width 0.0889)
		(layer "In15.Cu")
		(net "P5E_CPU0_PE0_TX_DP<5>")
	)
	(segment
		(start 333.205328 -216.731596)
		(end 332.967584 -216.731596)
		(width 0.14732)
		(layer "In15.Cu")
		(net "P5E_CPU0_PE0_TX_DP<5>")
	)
	(segment
		(start 328.75982 -384.269234)
		(end 328.961242 -384.657092)
		(width 0.14732)
		(layer "In15.Cu")
		(net "P5E_CPU0_PE0_TX_DP<5>")
	)
	(segment
		(start 328.242168 -383.272792)
		(end 328.44359 -383.66065)
		(width 0.14732)
		(layer "In15.Cu")
		(net "P5E_CPU0_PE0_TX_DP<5>")
	)
	(segment
		(start 325.943214 -233.628692)
		(end 326.145906 -244.720364)
		(width 0.14732)
		(layer "In15.Cu")
		(net "P5E_CPU0_PE0_TX_DP<5>")
	)
	(segment
		(start 336.527648 -406.70988)
		(end 336.822288 -407.00452)
		(width 0.14732)
		(layer "In15.Cu")
		(net "P5E_CPU0_PE0_TX_DP<5>")
	)
	(segment
		(start 340.127082 -216.739978)
		(end 340.116668 -216.746074)
		(width 0.0889)
		(layer "In15.Cu")
		(net "P5E_CPU0_PE0_TX_DP<5>")
	)
	(segment
		(start 341.441278 -219.01658)
		(end 341.450168 -219.0115)
		(width 0.0889)
		(layer "In15.Cu")
		(net "P5E_CPU0_PE0_TX_DP<5>")
	)
	(segment
		(start 341.450168 -218.372944)
		(end 341.442294 -218.368372)
		(width 0.0889)
		(layer "In15.Cu")
		(net "P5E_CPU0_PE0_TX_DP<5>")
	)
	(segment
		(start 332.771496 -216.80932)
		(end 328.827384 -220.508322)
		(width 0.14732)
		(layer "In15.Cu")
		(net "P5E_CPU0_PE0_TX_DP<5>")
	)
	(segment
		(start 342.382094 -223.251776)
		(end 342.381078 -223.251268)
		(width 0.0889)
		(layer "In15.Cu")
		(net "P5E_CPU0_PE0_TX_DP<5>")
	)
	(segment
		(start 335.81721 -216.748614)
		(end 335.802478 -216.739978)
		(width 0.0889)
		(layer "In15.Cu")
		(net "P5E_CPU0_PE0_TX_DP<5>")
	)
	(segment
		(start 326.064372 -258.7371)
		(end 326.063864 -258.7371)
		(width 0.14732)
		(layer "In15.Cu")
		(net "P5E_CPU0_PE0_TX_DP<5>")
	)
	(segment
		(start 328.586338 -251.296932)
		(end 328.586338 -252.26899)
		(width 0.14732)
		(layer "In15.Cu")
		(net "P5E_CPU0_PE0_TX_DP<5>")
	)
	(segment
		(start 340.68893 -217.071956)
		(end 340.68893 -217.064336)
		(width 0.0889)
		(layer "In15.Cu")
		(net "P5E_CPU0_PE0_TX_DP<5>")
	)
	(segment
		(start 328.292968 -250.58878)
		(end 328.586338 -251.296932)
		(width 0.14732)
		(layer "In15.Cu")
		(net "P5E_CPU0_PE0_TX_DP<5>")
	)
	(segment
		(start 341.442294 -218.368372)
		(end 341.441278 -218.367864)
		(width 0.0889)
		(layer "In15.Cu")
		(net "P5E_CPU0_PE0_TX_DP<5>")
	)
	(segment
		(start 342.098884 -224.404936)
		(end 342.098884 -224.373948)
		(width 0.0889)
		(layer "In15.Cu")
		(net "P5E_CPU0_PE0_TX_DP<5>")
	)
	(segment
		(start 328.390504 -383.828544)
		(end 328.591926 -384.216148)
		(width 0.14732)
		(layer "In15.Cu")
		(net "P5E_CPU0_PE0_TX_DP<5>")
	)
	(segment
		(start 340.980522 -217.559128)
		(end 340.972394 -217.554556)
		(width 0.0889)
		(layer "In15.Cu")
		(net "P5E_CPU0_PE0_TX_DP<5>")
	)
	(segment
		(start 327.354692 -381.83566)
		(end 327.556114 -382.223264)
		(width 0.14732)
		(layer "In15.Cu")
		(net "P5E_CPU0_PE0_TX_DP<5>")
	)
	(segment
		(start 341.159084 -217.8939)
		(end 341.159084 -217.878406)
		(width 0.0889)
		(layer "In15.Cu")
		(net "P5E_CPU0_PE0_TX_DP<5>")
	)
	(segment
		(start 317.847472 -328.493882)
		(end 312.56732 -333.774034)
		(width 0.14732)
		(layer "In15.Cu")
		(net "P5E_CPU0_PE0_TX_DP<5>")
	)
	(segment
		(start 336.713068 -399.843752)
		(end 336.713068 -403.961854)
		(width 0.14732)
		(layer "In15.Cu")
		(net "P5E_CPU0_PE0_TX_DP<5>")
	)
	(segment
		(start 339.187536 -216.739978)
		(end 339.177122 -216.746074)
		(width 0.0889)
		(layer "In15.Cu")
		(net "P5E_CPU0_PE0_TX_DP<5>")
	)
	(segment
		(start 340.510368 -216.745058)
		(end 340.501478 -216.739978)
		(width 0.0889)
		(layer "In15.Cu")
		(net "P5E_CPU0_PE0_TX_DP<5>")
	)
	(arc
		(start 341.441532 -219.995496)
		(mid 341.159 -219.506148)
		(end 341.441278 -219.01658)
		(width 0.0889)
		(layer "In15.Cu")
		(net "P5E_CPU0_PE0_TX_DP<5>")
	)
	(arc
		(start 341.441278 -218.367864)
		(mid 341.238455 -218.167633)
		(end 341.159084 -217.8939)
		(width 0.0889)
		(layer "In15.Cu")
		(net "P5E_CPU0_PE0_TX_DP<5>")
	)
	(arc
		(start 339.561932 -216.739978)
		(mid 339.374734 -216.689835)
		(end 339.187536 -216.739978)
		(width 0.0889)
		(layer "In15.Cu")
		(net "P5E_CPU0_PE0_TX_DP<5>")
	)
	(arc
		(start 335.428082 -216.739978)
		(mid 335.153883 -216.815813)
		(end 334.87741 -216.748614)
		(width 0.0889)
		(layer "In15.Cu")
		(net "P5E_CPU0_PE0_TX_DP<5>")
	)
	(arc
		(start 341.62873 -221.94774)
		(mid 341.581051 -221.76484)
		(end 341.450168 -221.628462)
		(width 0.0889)
		(layer "In15.Cu")
		(net "P5E_CPU0_PE0_TX_DP<5>")
	)
	(arc
		(start 341.159084 -217.878406)
		(mid 341.111405 -217.695506)
		(end 340.980522 -217.559128)
		(width 0.0889)
		(layer "In15.Cu")
		(net "P5E_CPU0_PE0_TX_DP<5>")
	)
	(arc
		(start 341.159084 -221.115382)
		(mid 341.239246 -220.843193)
		(end 341.441532 -220.644212)
		(width 0.0889)
		(layer "In15.Cu")
		(net "P5E_CPU0_PE0_TX_DP<5>")
	)
	(arc
		(start 340.971632 -217.554048)
		(mid 340.76656 -217.350369)
		(end 340.68893 -217.071956)
		(width 0.0889)
		(layer "In15.Cu")
		(net "P5E_CPU0_PE0_TX_DP<5>")
	)
	(arc
		(start 342.098884 -224.373948)
		(mid 342.178254 -224.100214)
		(end 342.381078 -223.899984)
		(width 0.0889)
		(layer "In15.Cu")
		(net "P5E_CPU0_PE0_TX_DP<5>")
	)
	(arc
		(start 342.888316 -224.908618)
		(mid 342.878576 -224.912775)
		(end 342.868758 -224.916746)
		(width 0.0889)
		(layer "In15.Cu")
		(net "P5E_CPU0_PE0_TX_DP<5>")
	)
	(arc
		(start 341.905336 -222.433642)
		(mid 341.702749 -222.227291)
		(end 341.62873 -221.94774)
		(width 0.0889)
		(layer "In15.Cu")
		(net "P5E_CPU0_PE0_TX_DP<5>")
	)
	(arc
		(start 340.501478 -216.739978)
		(mid 340.31428 -216.689835)
		(end 340.127082 -216.739978)
		(width 0.0889)
		(layer "In15.Cu")
		(net "P5E_CPU0_PE0_TX_DP<5>")
	)
	(arc
		(start 335.802478 -216.739978)
		(mid 335.61528 -216.689835)
		(end 335.428082 -216.739978)
		(width 0.0889)
		(layer "In15.Cu")
		(net "P5E_CPU0_PE0_TX_DP<5>")
	)
	(arc
		(start 336.742278 -216.739978)
		(mid 336.55508 -216.689835)
		(end 336.367882 -216.739978)
		(width 0.0889)
		(layer "In15.Cu")
		(net "P5E_CPU0_PE0_TX_DP<5>")
	)
	(arc
		(start 337.307682 -216.739978)
		(mid 337.033483 -216.815813)
		(end 336.75701 -216.748614)
		(width 0.0889)
		(layer "In15.Cu")
		(net "P5E_CPU0_PE0_TX_DP<5>")
	)
	(arc
		(start 341.450168 -219.0115)
		(mid 341.628644 -218.692222)
		(end 341.450168 -218.372944)
		(width 0.0889)
		(layer "In15.Cu")
		(net "P5E_CPU0_PE0_TX_DP<5>")
	)
	(arc
		(start 339.177122 -216.746074)
		(mid 338.89869 -216.81592)
		(end 338.621878 -216.739978)
		(width 0.0889)
		(layer "In15.Cu")
		(net "P5E_CPU0_PE0_TX_DP<5>")
	)
	(arc
		(start 342.098884 -222.761556)
		(mid 342.051205 -222.578656)
		(end 341.920322 -222.442278)
		(width 0.0889)
		(layer "In15.Cu")
		(net "P5E_CPU0_PE0_TX_DP<5>")
	)
	(arc
		(start 342.389968 -223.894904)
		(mid 342.568565 -223.575626)
		(end 342.389968 -223.256348)
		(width 0.0889)
		(layer "In15.Cu")
		(net "P5E_CPU0_PE0_TX_DP<5>")
	)
	(arc
		(start 341.441532 -220.644212)
		(mid 341.628835 -220.319854)
		(end 341.441532 -219.995496)
		(width 0.0889)
		(layer "In15.Cu")
		(net "P5E_CPU0_PE0_TX_DP<5>")
	)
	(arc
		(start 342.381078 -224.8789)
		(mid 342.178255 -224.678669)
		(end 342.098884 -224.404936)
		(width 0.0889)
		(layer "In15.Cu")
		(net "P5E_CPU0_PE0_TX_DP<5>")
	)
	(arc
		(start 341.441278 -221.623382)
		(mid 341.238455 -221.423151)
		(end 341.159084 -221.149418)
		(width 0.0889)
		(layer "In15.Cu")
		(net "P5E_CPU0_PE0_TX_DP<5>")
	)
	(arc
		(start 340.116668 -216.746074)
		(mid 339.83849 -216.815797)
		(end 339.561932 -216.739978)
		(width 0.0889)
		(layer "In15.Cu")
		(net "P5E_CPU0_PE0_TX_DP<5>")
	)
	(arc
		(start 342.868758 -224.916746)
		(mid 342.620606 -224.953361)
		(end 342.381078 -224.8789)
		(width 0.0889)
		(layer "In15.Cu")
		(net "P5E_CPU0_PE0_TX_DP<5>")
	)
	(arc
		(start 337.67395 -216.735152)
		(mid 337.490188 -216.689752)
		(end 337.307682 -216.739978)
		(width 0.0889)
		(layer "In15.Cu")
		(net "P5E_CPU0_PE0_TX_DP<5>")
	)
	(arc
		(start 336.367882 -216.739978)
		(mid 336.093683 -216.815813)
		(end 335.81721 -216.748614)
		(width 0.0889)
		(layer "In15.Cu")
		(net "P5E_CPU0_PE0_TX_DP<5>")
	)
	(arc
		(start 340.68893 -217.064336)
		(mid 340.641251 -216.881436)
		(end 340.510368 -216.745058)
		(width 0.0889)
		(layer "In15.Cu")
		(net "P5E_CPU0_PE0_TX_DP<5>")
	)
	(arc
		(start 334.87741 -216.748614)
		(mid 334.780683 -216.704562)
		(end 334.67548 -216.689432)
		(width 0.0889)
		(layer "In15.Cu")
		(net "P5E_CPU0_PE0_TX_DP<5>")
	)
	(arc
		(start 338.237068 -216.746074)
		(mid 337.95889 -216.815797)
		(end 337.682332 -216.739978)
		(width 0.0889)
		(layer "In15.Cu")
		(net "P5E_CPU0_PE0_TX_DP<5>")
	)
	(arc
		(start 342.381078 -223.251268)
		(mid 342.179796 -223.053781)
		(end 342.098884 -222.783654)
		(width 0.0889)
		(layer "In15.Cu")
		(net "P5E_CPU0_PE0_TX_DP<5>")
	)
	(arc
		(start 338.621878 -216.739978)
		(mid 338.43468 -216.689835)
		(end 338.247482 -216.739978)
		(width 0.0889)
		(layer "In15.Cu")
		(net "P5E_CPU0_PE0_TX_DP<5>")
	)
	(segment
		(start 339.58657 -407.926286)
		(end 339.910928 -408.250644)
		(width 0.13208)
		(layer "F.Cu")
		(net "P5E_CPU0_PE0_TX_DP<4>")
	)
	(segment
		(start 341.72398 -224.925382)
		(end 341.72398 -224.389696)
		(width 0.13208)
		(layer "F.Cu")
		(net "P5E_CPU0_PE0_TX_DP<4>")
	)
	(segment
		(start 339.885528 -407.00452)
		(end 339.58657 -407.303478)
		(width 0.13208)
		(layer "F.Cu")
		(net "P5E_CPU0_PE0_TX_DP<4>")
	)
	(segment
		(start 339.58657 -407.303478)
		(end 339.58657 -407.926286)
		(width 0.13208)
		(layer "F.Cu")
		(net "P5E_CPU0_PE0_TX_DP<4>")
	)
	(segment
		(start 341.72398 -224.389696)
		(end 341.724234 -224.389442)
		(width 0.13208)
		(layer "F.Cu")
		(net "P5E_CPU0_PE0_TX_DP<4>")
	)
	(segment
		(start 329.893168 -382.247394)
		(end 330.110592 -382.62687)
		(width 0.14732)
		(layer "In15.Cu")
		(net "P5E_CPU0_PE0_TX_DP<4>")
	)
	(segment
		(start 332.442312 -219.356686)
		(end 332.07198 -219.588842)
		(width 0.14732)
		(layer "In15.Cu")
		(net "P5E_CPU0_PE0_TX_DP<4>")
	)
	(segment
		(start 329.50277 -252.49251)
		(end 329.502262 -252.494034)
		(width 0.14732)
		(layer "In15.Cu")
		(net "P5E_CPU0_PE0_TX_DP<4>")
	)
	(segment
		(start 330.623164 -383.770378)
		(end 330.840588 -384.149346)
		(width 0.14732)
		(layer "In15.Cu")
		(net "P5E_CPU0_PE0_TX_DP<4>")
	)
	(segment
		(start 341.724234 -224.389442)
		(end 341.880698 -224.118424)
		(width 0.0889)
		(layer "In15.Cu")
		(net "P5E_CPU0_PE0_TX_DP<4>")
	)
	(segment
		(start 340.502494 -219.996004)
		(end 340.501478 -219.995496)
		(width 0.0889)
		(layer "In15.Cu")
		(net "P5E_CPU0_PE0_TX_DP<4>")
	)
	(segment
		(start 341.159084 -222.780098)
		(end 341.159084 -222.761556)
		(width 0.0889)
		(layer "In15.Cu")
		(net "P5E_CPU0_PE0_TX_DP<4>")
	)
	(segment
		(start 333.909162 -218.832176)
		(end 333.866998 -218.87434)
		(width 0.0889)
		(layer "In15.Cu")
		(net "P5E_CPU0_PE0_TX_DP<4>")
	)
	(segment
		(start 332.48092 -219.188538)
		(end 332.442312 -219.356686)
		(width 0.14732)
		(layer "In15.Cu")
		(net "P5E_CPU0_PE0_TX_DP<4>")
	)
	(segment
		(start 340.219284 -221.149418)
		(end 340.219284 -221.111826)
		(width 0.0889)
		(layer "In15.Cu")
		(net "P5E_CPU0_PE0_TX_DP<4>")
	)
	(segment
		(start 327.129648 -244.879622)
		(end 327.565004 -247.255792)
		(width 0.14732)
		(layer "In15.Cu")
		(net "P5E_CPU0_PE0_TX_DP<4>")
	)
	(segment
		(start 328.676762 -222.981012)
		(end 326.927718 -233.827066)
		(width 0.14732)
		(layer "In15.Cu")
		(net "P5E_CPU0_PE0_TX_DP<4>")
	)
	(segment
		(start 333.8449 -218.87434)
		(end 332.982062 -218.87434)
		(width 0.14732)
		(layer "In15.Cu")
		(net "P5E_CPU0_PE0_TX_DP<4>")
	)
	(segment
		(start 340.033356 -219.182442)
		(end 340.031832 -219.18168)
		(width 0.0889)
		(layer "In15.Cu")
		(net "P5E_CPU0_PE0_TX_DP<4>")
	)
	(segment
		(start 331.227684 -384.57505)
		(end 331.18171 -384.744722)
		(width 0.14732)
		(layer "In15.Cu")
		(net "P5E_CPU0_PE0_TX_DP<4>")
	)
	(segment
		(start 327.565004 -247.255792)
		(end 329.13447 -250.19)
		(width 0.14732)
		(layer "In15.Cu")
		(net "P5E_CPU0_PE0_TX_DP<4>")
	)
	(segment
		(start 340.502494 -221.62389)
		(end 340.501478 -221.623382)
		(width 0.0889)
		(layer "In15.Cu")
		(net "P5E_CPU0_PE0_TX_DP<4>")
	)
	(segment
		(start 329.723496 -382.200912)
		(end 329.723242 -382.20142)
		(width 0.14732)
		(layer "In15.Cu")
		(net "P5E_CPU0_PE0_TX_DP<4>")
	)
	(segment
		(start 340.980522 -222.442278)
		(end 340.973156 -222.43796)
		(width 0.0889)
		(layer "In15.Cu")
		(net "P5E_CPU0_PE0_TX_DP<4>")
	)
	(segment
		(start 341.62873 -223.575626)
		(end 341.62873 -223.56699)
		(width 0.0889)
		(layer "In15.Cu")
		(net "P5E_CPU0_PE0_TX_DP<4>")
	)
	(segment
		(start 326.985376 -258.950968)
		(end 326.984614 -258.953254)
		(width 0.14732)
		(layer "In15.Cu")
		(net "P5E_CPU0_PE0_TX_DP<4>")
	)
	(segment
		(start 338.166964 -219.190316)
		(end 338.152232 -219.18168)
		(width 0.0889)
		(layer "In15.Cu")
		(net "P5E_CPU0_PE0_TX_DP<4>")
	)
	(segment
		(start 329.52182 -252.445012)
		(end 329.521312 -252.445012)
		(width 0.14732)
		(layer "In15.Cu")
		(net "P5E_CPU0_PE0_TX_DP<4>")
	)
	(segment
		(start 339.106764 -219.190316)
		(end 339.092032 -219.18168)
		(width 0.0889)
		(layer "In15.Cu")
		(net "P5E_CPU0_PE0_TX_DP<4>")
	)
	(segment
		(start 329.164696 -381.22733)
		(end 329.334622 -381.273304)
		(width 0.14732)
		(layer "In15.Cu")
		(net "P5E_CPU0_PE0_TX_DP<4>")
	)
	(segment
		(start 318.243458 -362.177076)
		(end 329.16495 -381.226822)
		(width 0.14732)
		(layer "In15.Cu")
		(net "P5E_CPU0_PE0_TX_DP<4>")
	)
	(segment
		(start 340.973156 -222.43796)
		(end 340.971632 -222.437198)
		(width 0.0889)
		(layer "In15.Cu")
		(net "P5E_CPU0_PE0_TX_DP<4>")
	)
	(segment
		(start 340.501478 -220.644212)
		(end 340.510368 -220.639132)
		(width 0.0889)
		(layer "In15.Cu")
		(net "P5E_CPU0_PE0_TX_DP<4>")
	)
	(segment
		(start 340.040722 -219.18676)
		(end 340.033356 -219.182442)
		(width 0.0889)
		(layer "In15.Cu")
		(net "P5E_CPU0_PE0_TX_DP<4>")
	)
	(segment
		(start 333.866998 -218.87434)
		(end 333.8449 -218.87434)
		(width 0.0889)
		(layer "In15.Cu")
		(net "P5E_CPU0_PE0_TX_DP<4>")
	)
	(segment
		(start 330.281788 -383.17551)
		(end 330.451714 -383.221484)
		(width 0.14732)
		(layer "In15.Cu")
		(net "P5E_CPU0_PE0_TX_DP<4>")
	)
	(segment
		(start 318.750442 -328.921364)
		(end 313.49696 -334.174846)
		(width 0.14732)
		(layer "In15.Cu")
		(net "P5E_CPU0_PE0_TX_DP<4>")
	)
	(segment
		(start 326.984614 -258.953254)
		(end 326.98436 -258.953254)
		(width 0.14732)
		(layer "In15.Cu")
		(net "P5E_CPU0_PE0_TX_DP<4>")
	)
	(segment
		(start 332.07198 -219.588842)
		(end 331.903832 -219.550234)
		(width 0.14732)
		(layer "In15.Cu")
		(net "P5E_CPU0_PE0_TX_DP<4>")
	)
	(segment
		(start 339.590888 -405.845518)
		(end 339.590888 -406.70988)
		(width 0.14732)
		(layer "In15.Cu")
		(net "P5E_CPU0_PE0_TX_DP<4>")
	)
	(segment
		(start 329.585828 -221.309692)
		(end 328.676762 -222.981012)
		(width 0.14732)
		(layer "In15.Cu")
		(net "P5E_CPU0_PE0_TX_DP<4>")
	)
	(segment
		(start 340.510368 -220.000576)
		(end 340.502494 -219.996004)
		(width 0.0889)
		(layer "In15.Cu")
		(net "P5E_CPU0_PE0_TX_DP<4>")
	)
	(segment
		(start 339.776308 -403.961854)
		(end 339.590888 -405.845518)
		(width 0.14732)
		(layer "In15.Cu")
		(net "P5E_CPU0_PE0_TX_DP<4>")
	)
	(segment
		(start 330.282042 -383.175002)
		(end 330.281788 -383.17551)
		(width 0.14732)
		(layer "In15.Cu")
		(net "P5E_CPU0_PE0_TX_DP<4>")
	)
	(segment
		(start 329.52182 -251.125482)
		(end 329.52182 -252.445012)
		(width 0.14732)
		(layer "In15.Cu")
		(net "P5E_CPU0_PE0_TX_DP<4>")
	)
	(segment
		(start 330.669138 -383.60096)
		(end 330.623164 -383.770378)
		(width 0.14732)
		(layer "In15.Cu")
		(net "P5E_CPU0_PE0_TX_DP<4>")
	)
	(segment
		(start 340.97087 -222.43669)
		(end 340.965536 -222.433642)
		(width 0.0889)
		(layer "In15.Cu")
		(net "P5E_CPU0_PE0_TX_DP<4>")
	)
	(segment
		(start 330.064872 -382.796288)
		(end 330.282042 -383.175002)
		(width 0.14732)
		(layer "In15.Cu")
		(net "P5E_CPU0_PE0_TX_DP<4>")
	)
	(segment
		(start 330.064618 -382.796542)
		(end 330.064872 -382.796288)
		(width 0.14732)
		(layer "In15.Cu")
		(net "P5E_CPU0_PE0_TX_DP<4>")
	)
	(segment
		(start 341.880698 -224.118424)
		(end 341.856568 -224.02927)
		(width 0.0889)
		(layer "In15.Cu")
		(net "P5E_CPU0_PE0_TX_DP<4>")
	)
	(segment
		(start 331.18171 -384.744722)
		(end 339.776308 -399.73631)
		(width 0.14732)
		(layer "In15.Cu")
		(net "P5E_CPU0_PE0_TX_DP<4>")
	)
	(segment
		(start 313.49696 -340.815676)
		(end 318.243458 -362.177076)
		(width 0.14732)
		(layer "In15.Cu")
		(net "P5E_CPU0_PE0_TX_DP<4>")
	)
	(segment
		(start 326.927718 -233.827066)
		(end 327.129648 -244.879622)
		(width 0.14732)
		(layer "In15.Cu")
		(net "P5E_CPU0_PE0_TX_DP<4>")
	)
	(segment
		(start 326.295512 -266.608052)
		(end 329.077574 -310.30164)
		(width 0.14732)
		(layer "In15.Cu")
		(net "P5E_CPU0_PE0_TX_DP<4>")
	)
	(segment
		(start 340.971632 -222.437198)
		(end 340.97087 -222.43669)
		(width 0.0889)
		(layer "In15.Cu")
		(net "P5E_CPU0_PE0_TX_DP<4>")
	)
	(segment
		(start 329.521312 -252.445012)
		(end 329.50277 -252.49251)
		(width 0.14732)
		(layer "In15.Cu")
		(net "P5E_CPU0_PE0_TX_DP<4>")
	)
	(segment
		(start 326.98436 -258.953254)
		(end 326.295512 -266.608052)
		(width 0.14732)
		(layer "In15.Cu")
		(net "P5E_CPU0_PE0_TX_DP<4>")
	)
	(segment
		(start 334.955896 -218.832176)
		(end 333.909162 -218.832176)
		(width 0.0889)
		(layer "In15.Cu")
		(net "P5E_CPU0_PE0_TX_DP<4>")
	)
	(segment
		(start 335.215738 -219.092018)
		(end 334.955896 -218.832176)
		(width 0.0889)
		(layer "In15.Cu")
		(net "P5E_CPU0_PE0_TX_DP<4>")
	)
	(segment
		(start 337.227164 -219.190316)
		(end 337.212432 -219.18168)
		(width 0.0889)
		(layer "In15.Cu")
		(net "P5E_CPU0_PE0_TX_DP<4>")
	)
	(segment
		(start 330.110592 -382.62687)
		(end 330.064618 -382.796542)
		(width 0.14732)
		(layer "In15.Cu")
		(net "P5E_CPU0_PE0_TX_DP<4>")
	)
	(segment
		(start 330.287122 -220.563694)
		(end 329.585828 -221.309692)
		(width 0.14732)
		(layer "In15.Cu")
		(net "P5E_CPU0_PE0_TX_DP<4>")
	)
	(segment
		(start 325.005446 -319.98793)
		(end 318.750442 -328.921364)
		(width 0.14732)
		(layer "In15.Cu")
		(net "P5E_CPU0_PE0_TX_DP<4>")
	)
	(segment
		(start 340.219284 -219.521532)
		(end 340.219284 -219.506038)
		(width 0.0889)
		(layer "In15.Cu")
		(net "P5E_CPU0_PE0_TX_DP<4>")
	)
	(segment
		(start 332.982062 -218.87434)
		(end 332.48092 -219.188538)
		(width 0.14732)
		(layer "In15.Cu")
		(net "P5E_CPU0_PE0_TX_DP<4>")
	)
	(segment
		(start 331.903832 -219.550234)
		(end 330.287122 -220.563948)
		(width 0.14732)
		(layer "In15.Cu")
		(net "P5E_CPU0_PE0_TX_DP<4>")
	)
	(segment
		(start 329.506834 -381.822452)
		(end 329.723496 -382.200912)
		(width 0.14732)
		(layer "In15.Cu")
		(net "P5E_CPU0_PE0_TX_DP<4>")
	)
	(segment
		(start 329.502262 -252.494034)
		(end 326.985376 -258.950968)
		(width 0.14732)
		(layer "In15.Cu")
		(net "P5E_CPU0_PE0_TX_DP<4>")
	)
	(segment
		(start 339.776308 -399.73631)
		(end 339.776308 -403.961854)
		(width 0.14732)
		(layer "In15.Cu")
		(net "P5E_CPU0_PE0_TX_DP<4>")
	)
	(segment
		(start 340.510368 -221.628462)
		(end 340.502494 -221.62389)
		(width 0.0889)
		(layer "In15.Cu")
		(net "P5E_CPU0_PE0_TX_DP<4>")
	)
	(segment
		(start 329.13447 -250.19)
		(end 329.52182 -251.125482)
		(width 0.14732)
		(layer "In15.Cu")
		(net "P5E_CPU0_PE0_TX_DP<4>")
	)
	(segment
		(start 329.16495 -381.226822)
		(end 329.164696 -381.22733)
		(width 0.14732)
		(layer "In15.Cu")
		(net "P5E_CPU0_PE0_TX_DP<4>")
	)
	(segment
		(start 330.840334 -384.1496)
		(end 331.01026 -384.195574)
		(width 0.14732)
		(layer "In15.Cu")
		(net "P5E_CPU0_PE0_TX_DP<4>")
	)
	(segment
		(start 329.077574 -310.30164)
		(end 325.005446 -319.98793)
		(width 0.14732)
		(layer "In15.Cu")
		(net "P5E_CPU0_PE0_TX_DP<4>")
	)
	(segment
		(start 329.552046 -381.65278)
		(end 329.506072 -381.822452)
		(width 0.14732)
		(layer "In15.Cu")
		(net "P5E_CPU0_PE0_TX_DP<4>")
	)
	(segment
		(start 339.590888 -406.70988)
		(end 339.885528 -407.00452)
		(width 0.14732)
		(layer "In15.Cu")
		(net "P5E_CPU0_PE0_TX_DP<4>")
	)
	(segment
		(start 330.840588 -384.149346)
		(end 330.840334 -384.1496)
		(width 0.14732)
		(layer "In15.Cu")
		(net "P5E_CPU0_PE0_TX_DP<4>")
	)
	(segment
		(start 329.723242 -382.20142)
		(end 329.893168 -382.247394)
		(width 0.14732)
		(layer "In15.Cu")
		(net "P5E_CPU0_PE0_TX_DP<4>")
	)
	(segment
		(start 329.506072 -381.822452)
		(end 329.506834 -381.822452)
		(width 0.14732)
		(layer "In15.Cu")
		(net "P5E_CPU0_PE0_TX_DP<4>")
	)
	(segment
		(start 329.334622 -381.273304)
		(end 329.552046 -381.65278)
		(width 0.14732)
		(layer "In15.Cu")
		(net "P5E_CPU0_PE0_TX_DP<4>")
	)
	(segment
		(start 330.287122 -220.563948)
		(end 330.287122 -220.563694)
		(width 0.14732)
		(layer "In15.Cu")
		(net "P5E_CPU0_PE0_TX_DP<4>")
	)
	(segment
		(start 313.49696 -334.174846)
		(end 313.49696 -340.815676)
		(width 0.14732)
		(layer "In15.Cu")
		(net "P5E_CPU0_PE0_TX_DP<4>")
	)
	(segment
		(start 330.451714 -383.221484)
		(end 330.669138 -383.60096)
		(width 0.14732)
		(layer "In15.Cu")
		(net "P5E_CPU0_PE0_TX_DP<4>")
	)
	(segment
		(start 331.01026 -384.195574)
		(end 331.227684 -384.57505)
		(width 0.14732)
		(layer "In15.Cu")
		(net "P5E_CPU0_PE0_TX_DP<4>")
	)
	(arc
		(start 337.777836 -219.18168)
		(mid 337.503637 -219.257515)
		(end 337.227164 -219.190316)
		(width 0.0889)
		(layer "In15.Cu")
		(net "P5E_CPU0_PE0_TX_DP<4>")
	)
	(arc
		(start 341.441532 -223.251268)
		(mid 341.239246 -223.052287)
		(end 341.159084 -222.780098)
		(width 0.0889)
		(layer "In15.Cu")
		(net "P5E_CPU0_PE0_TX_DP<4>")
	)
	(arc
		(start 338.152232 -219.18168)
		(mid 337.965034 -219.131537)
		(end 337.777836 -219.18168)
		(width 0.0889)
		(layer "In15.Cu")
		(net "P5E_CPU0_PE0_TX_DP<4>")
	)
	(arc
		(start 340.965536 -222.433642)
		(mid 340.762949 -222.227291)
		(end 340.68893 -221.94774)
		(width 0.0889)
		(layer "In15.Cu")
		(net "P5E_CPU0_PE0_TX_DP<4>")
	)
	(arc
		(start 340.501478 -219.995496)
		(mid 340.298655 -219.795265)
		(end 340.219284 -219.521532)
		(width 0.0889)
		(layer "In15.Cu")
		(net "P5E_CPU0_PE0_TX_DP<4>")
	)
	(arc
		(start 340.219284 -221.111826)
		(mid 340.300195 -220.841698)
		(end 340.501478 -220.644212)
		(width 0.0889)
		(layer "In15.Cu")
		(net "P5E_CPU0_PE0_TX_DP<4>")
	)
	(arc
		(start 340.68893 -221.94774)
		(mid 340.641251 -221.76484)
		(end 340.510368 -221.628462)
		(width 0.0889)
		(layer "In15.Cu")
		(net "P5E_CPU0_PE0_TX_DP<4>")
	)
	(arc
		(start 341.159084 -222.761556)
		(mid 341.111405 -222.578656)
		(end 340.980522 -222.442278)
		(width 0.0889)
		(layer "In15.Cu")
		(net "P5E_CPU0_PE0_TX_DP<4>")
	)
	(arc
		(start 340.501478 -221.623382)
		(mid 340.298655 -221.423151)
		(end 340.219284 -221.149418)
		(width 0.0889)
		(layer "In15.Cu")
		(net "P5E_CPU0_PE0_TX_DP<4>")
	)
	(arc
		(start 339.657436 -219.18168)
		(mid 339.383237 -219.257515)
		(end 339.106764 -219.190316)
		(width 0.0889)
		(layer "In15.Cu")
		(net "P5E_CPU0_PE0_TX_DP<4>")
	)
	(arc
		(start 337.212432 -219.18168)
		(mid 337.025234 -219.131537)
		(end 336.838036 -219.18168)
		(width 0.0889)
		(layer "In15.Cu")
		(net "P5E_CPU0_PE0_TX_DP<4>")
	)
	(arc
		(start 339.092032 -219.18168)
		(mid 338.904834 -219.131537)
		(end 338.717636 -219.18168)
		(width 0.0889)
		(layer "In15.Cu")
		(net "P5E_CPU0_PE0_TX_DP<4>")
	)
	(arc
		(start 340.219284 -219.506038)
		(mid 340.171605 -219.323138)
		(end 340.040722 -219.18676)
		(width 0.0889)
		(layer "In15.Cu")
		(net "P5E_CPU0_PE0_TX_DP<4>")
	)
	(arc
		(start 340.031832 -219.18168)
		(mid 339.844634 -219.131537)
		(end 339.657436 -219.18168)
		(width 0.0889)
		(layer "In15.Cu")
		(net "P5E_CPU0_PE0_TX_DP<4>")
	)
	(arc
		(start 341.62873 -223.56699)
		(mid 341.57646 -223.384625)
		(end 341.441532 -223.251268)
		(width 0.0889)
		(layer "In15.Cu")
		(net "P5E_CPU0_PE0_TX_DP<4>")
	)
	(arc
		(start 340.510368 -220.639132)
		(mid 340.689086 -220.319854)
		(end 340.510368 -220.000576)
		(width 0.0889)
		(layer "In15.Cu")
		(net "P5E_CPU0_PE0_TX_DP<4>")
	)
	(arc
		(start 335.898236 -219.18168)
		(mid 335.615534 -219.257456)
		(end 335.332832 -219.18168)
		(width 0.0889)
		(layer "In15.Cu")
		(net "P5E_CPU0_PE0_TX_DP<4>")
	)
	(arc
		(start 336.272632 -219.18168)
		(mid 336.085434 -219.131537)
		(end 335.898236 -219.18168)
		(width 0.0889)
		(layer "In15.Cu")
		(net "P5E_CPU0_PE0_TX_DP<4>")
	)
	(arc
		(start 341.856568 -224.02927)
		(mid 341.688814 -223.829492)
		(end 341.62873 -223.575626)
		(width 0.0889)
		(layer "In15.Cu")
		(net "P5E_CPU0_PE0_TX_DP<4>")
	)
	(arc
		(start 335.332832 -219.18168)
		(mid 335.271354 -219.140678)
		(end 335.215738 -219.092018)
		(width 0.0889)
		(layer "In15.Cu")
		(net "P5E_CPU0_PE0_TX_DP<4>")
	)
	(arc
		(start 336.838036 -219.18168)
		(mid 336.555334 -219.257456)
		(end 336.272632 -219.18168)
		(width 0.0889)
		(layer "In15.Cu")
		(net "P5E_CPU0_PE0_TX_DP<4>")
	)
	(arc
		(start 338.717636 -219.18168)
		(mid 338.443437 -219.257515)
		(end 338.166964 -219.190316)
		(width 0.0889)
		(layer "In15.Cu")
		(net "P5E_CPU0_PE0_TX_DP<4>")
	)
	(segment
		(start 341.254334 -225.739198)
		(end 341.254334 -225.203512)
		(width 0.13208)
		(layer "F.Cu")
		(net "P5E_CPU0_PE0_TX_DP<3>")
	)
	(segment
		(start 342.64981 -407.926286)
		(end 342.974168 -408.250644)
		(width 0.13208)
		(layer "F.Cu")
		(net "P5E_CPU0_PE0_TX_DP<3>")
	)
	(segment
		(start 342.64981 -407.303478)
		(end 342.64981 -407.926286)
		(width 0.13208)
		(layer "F.Cu")
		(net "P5E_CPU0_PE0_TX_DP<3>")
	)
	(segment
		(start 341.254334 -225.203512)
		(end 341.25408 -225.203258)
		(width 0.13208)
		(layer "F.Cu")
		(net "P5E_CPU0_PE0_TX_DP<3>")
	)
	(segment
		(start 342.948768 -407.00452)
		(end 342.64981 -407.303478)
		(width 0.13208)
		(layer "F.Cu")
		(net "P5E_CPU0_PE0_TX_DP<3>")
	)
	(segment
		(start 330.456286 -250.951492)
		(end 330.456286 -252.621034)
		(width 0.14732)
		(layer "In15.Cu")
		(net "P5E_CPU0_PE0_TX_DP<3>")
	)
	(segment
		(start 338.80933 -220.327474)
		(end 338.80933 -220.319854)
		(width 0.0889)
		(layer "In15.Cu")
		(net "P5E_CPU0_PE0_TX_DP<3>")
	)
	(segment
		(start 332.173834 -382.487678)
		(end 332.13421 -382.658874)
		(width 0.14732)
		(layer "In15.Cu")
		(net "P5E_CPU0_PE0_TX_DP<3>")
	)
	(segment
		(start 333.362046 -384.393186)
		(end 333.322422 -384.564636)
		(width 0.14732)
		(layer "In15.Cu")
		(net "P5E_CPU0_PE0_TX_DP<3>")
	)
	(segment
		(start 340.502494 -223.251776)
		(end 340.501478 -223.251268)
		(width 0.0889)
		(layer "In15.Cu")
		(net "P5E_CPU0_PE0_TX_DP<3>")
	)
	(segment
		(start 328.114914 -245.019576)
		(end 328.454004 -246.945404)
		(width 0.14732)
		(layer "In15.Cu")
		(net "P5E_CPU0_PE0_TX_DP<3>")
	)
	(segment
		(start 331.348334 -381.16383)
		(end 331.579728 -381.534924)
		(width 0.14732)
		(layer "In15.Cu")
		(net "P5E_CPU0_PE0_TX_DP<3>")
	)
	(segment
		(start 329.168506 -255.924558)
		(end 329.168252 -255.924812)
		(width 0.14732)
		(layer "In15.Cu")
		(net "P5E_CPU0_PE0_TX_DP<3>")
	)
	(segment
		(start 330.02601 -310.491886)
		(end 325.732902 -320.691256)
		(width 0.14732)
		(layer "In15.Cu")
		(net "P5E_CPU0_PE0_TX_DP<3>")
	)
	(segment
		(start 339.100922 -220.814646)
		(end 339.092032 -220.809566)
		(width 0.0889)
		(layer "In15.Cu")
		(net "P5E_CPU0_PE0_TX_DP<3>")
	)
	(segment
		(start 314.4266 -334.62595)
		(end 314.4266 -340.610444)
		(width 0.14732)
		(layer "In15.Cu")
		(net "P5E_CPU0_PE0_TX_DP<3>")
	)
	(segment
		(start 333.8449 -220.11386)
		(end 333.346044 -220.11386)
		(width 0.14732)
		(layer "In15.Cu")
		(net "P5E_CPU0_PE0_TX_DP<3>")
	)
	(segment
		(start 332.36535 -383.029714)
		(end 332.536546 -383.069338)
		(width 0.14732)
		(layer "In15.Cu")
		(net "P5E_CPU0_PE0_TX_DP<3>")
	)
	(segment
		(start 332.13421 -382.658874)
		(end 332.134464 -382.659382)
		(width 0.14732)
		(layer "In15.Cu")
		(net "P5E_CPU0_PE0_TX_DP<3>")
	)
	(segment
		(start 319.137284 -361.809284)
		(end 331.177392 -381.123698)
		(width 0.14732)
		(layer "In15.Cu")
		(net "P5E_CPU0_PE0_TX_DP<3>")
	)
	(segment
		(start 340.219284 -222.783654)
		(end 340.219284 -222.761556)
		(width 0.0889)
		(layer "In15.Cu")
		(net "P5E_CPU0_PE0_TX_DP<3>")
	)
	(segment
		(start 334.877156 -220.004132)
		(end 334.862424 -219.995496)
		(width 0.0889)
		(layer "In15.Cu")
		(net "P5E_CPU0_PE0_TX_DP<3>")
	)
	(segment
		(start 333.866998 -220.11386)
		(end 333.8449 -220.11386)
		(width 0.0889)
		(layer "In15.Cu")
		(net "P5E_CPU0_PE0_TX_DP<3>")
	)
	(segment
		(start 331.176884 -381.124206)
		(end 331.348334 -381.16383)
		(width 0.14732)
		(layer "In15.Cu")
		(net "P5E_CPU0_PE0_TX_DP<3>")
	)
	(segment
		(start 342.654128 -406.70988)
		(end 342.948768 -407.00452)
		(width 0.14732)
		(layer "In15.Cu")
		(net "P5E_CPU0_PE0_TX_DP<3>")
	)
	(segment
		(start 338.247482 -219.995496)
		(end 338.237068 -220.001592)
		(width 0.0889)
		(layer "In15.Cu")
		(net "P5E_CPU0_PE0_TX_DP<3>")
	)
	(segment
		(start 340.501478 -223.899984)
		(end 340.502494 -223.899476)
		(width 0.0889)
		(layer "In15.Cu")
		(net "P5E_CPU0_PE0_TX_DP<3>")
	)
	(segment
		(start 331.77099 -382.07696)
		(end 331.94244 -382.116584)
		(width 0.14732)
		(layer "In15.Cu")
		(net "P5E_CPU0_PE0_TX_DP<3>")
	)
	(segment
		(start 330.43749 -252.668532)
		(end 330.43368 -252.679962)
		(width 0.14732)
		(layer "In15.Cu")
		(net "P5E_CPU0_PE0_TX_DP<3>")
	)
	(segment
		(start 329.683364 -223.131126)
		(end 327.90257 -233.951018)
		(width 0.14732)
		(layer "In15.Cu")
		(net "P5E_CPU0_PE0_TX_DP<3>")
	)
	(segment
		(start 332.76794 -383.440432)
		(end 332.728316 -383.611628)
		(width 0.14732)
		(layer "In15.Cu")
		(net "P5E_CPU0_PE0_TX_DP<3>")
	)
	(segment
		(start 336.368136 -219.995496)
		(end 336.353404 -220.004132)
		(width 0.0889)
		(layer "In15.Cu")
		(net "P5E_CPU0_PE0_TX_DP<3>")
	)
	(segment
		(start 314.4266 -340.610444)
		(end 319.137284 -361.809284)
		(width 0.14732)
		(layer "In15.Cu")
		(net "P5E_CPU0_PE0_TX_DP<3>")
	)
	(segment
		(start 342.839548 -399.832068)
		(end 342.839548 -403.961854)
		(width 0.14732)
		(layer "In15.Cu")
		(net "P5E_CPU0_PE0_TX_DP<3>")
	)
	(segment
		(start 331.177392 -381.123698)
		(end 331.176884 -381.124206)
		(width 0.14732)
		(layer "In15.Cu")
		(net "P5E_CPU0_PE0_TX_DP<3>")
	)
	(segment
		(start 333.322422 -384.564636)
		(end 342.839548 -399.832068)
		(width 0.14732)
		(layer "In15.Cu")
		(net "P5E_CPU0_PE0_TX_DP<3>")
	)
	(segment
		(start 333.130652 -384.022092)
		(end 333.362046 -384.393186)
		(width 0.14732)
		(layer "In15.Cu")
		(net "P5E_CPU0_PE0_TX_DP<3>")
	)
	(segment
		(start 327.90257 -233.951018)
		(end 328.114914 -245.019576)
		(width 0.14732)
		(layer "In15.Cu")
		(net "P5E_CPU0_PE0_TX_DP<3>")
	)
	(segment
		(start 325.732902 -320.691256)
		(end 319.59423 -329.45832)
		(width 0.14732)
		(layer "In15.Cu")
		(net "P5E_CPU0_PE0_TX_DP<3>")
	)
	(segment
		(start 333.909162 -220.071696)
		(end 333.866998 -220.11386)
		(width 0.0889)
		(layer "In15.Cu")
		(net "P5E_CPU0_PE0_TX_DP<3>")
	)
	(segment
		(start 319.59423 -329.45832)
		(end 314.4266 -334.62595)
		(width 0.14732)
		(layer "In15.Cu")
		(net "P5E_CPU0_PE0_TX_DP<3>")
	)
	(segment
		(start 334.862424 -219.995496)
		(end 334.84566 -219.985844)
		(width 0.0889)
		(layer "In15.Cu")
		(net "P5E_CPU0_PE0_TX_DP<3>")
	)
	(segment
		(start 331.94244 -382.116584)
		(end 332.173834 -382.487678)
		(width 0.14732)
		(layer "In15.Cu")
		(net "P5E_CPU0_PE0_TX_DP<3>")
	)
	(segment
		(start 339.279484 -221.149418)
		(end 339.279484 -221.133924)
		(width 0.0889)
		(layer "In15.Cu")
		(net "P5E_CPU0_PE0_TX_DP<3>")
	)
	(segment
		(start 334.204564 -220.071696)
		(end 333.909162 -220.071696)
		(width 0.0889)
		(layer "In15.Cu")
		(net "P5E_CPU0_PE0_TX_DP<3>")
	)
	(segment
		(start 327.90384 -259.169154)
		(end 327.233026 -266.620244)
		(width 0.14732)
		(layer "In15.Cu")
		(net "P5E_CPU0_PE0_TX_DP<3>")
	)
	(segment
		(start 340.510368 -223.256348)
		(end 340.502494 -223.251776)
		(width 0.0889)
		(layer "In15.Cu")
		(net "P5E_CPU0_PE0_TX_DP<3>")
	)
	(segment
		(start 339.570568 -221.628462)
		(end 339.562694 -221.62389)
		(width 0.0889)
		(layer "In15.Cu")
		(net "P5E_CPU0_PE0_TX_DP<3>")
	)
	(segment
		(start 340.033356 -222.43796)
		(end 340.031832 -222.437198)
		(width 0.0889)
		(layer "In15.Cu")
		(net "P5E_CPU0_PE0_TX_DP<3>")
	)
	(segment
		(start 330.456286 -252.621034)
		(end 330.456032 -252.621034)
		(width 0.14732)
		(layer "In15.Cu")
		(net "P5E_CPU0_PE0_TX_DP<3>")
	)
	(segment
		(start 331.771498 -382.076452)
		(end 331.77099 -382.07696)
		(width 0.14732)
		(layer "In15.Cu")
		(net "P5E_CPU0_PE0_TX_DP<3>")
	)
	(segment
		(start 340.219284 -224.404936)
		(end 340.219284 -224.373948)
		(width 0.0889)
		(layer "In15.Cu")
		(net "P5E_CPU0_PE0_TX_DP<3>")
	)
	(segment
		(start 332.959202 -383.982468)
		(end 333.130652 -384.022092)
		(width 0.14732)
		(layer "In15.Cu")
		(net "P5E_CPU0_PE0_TX_DP<3>")
	)
	(segment
		(start 328.454004 -246.945404)
		(end 329.977496 -249.794776)
		(width 0.14732)
		(layer "In15.Cu")
		(net "P5E_CPU0_PE0_TX_DP<3>")
	)
	(segment
		(start 332.959456 -383.982214)
		(end 332.959202 -383.982468)
		(width 0.14732)
		(layer "In15.Cu")
		(net "P5E_CPU0_PE0_TX_DP<3>")
	)
	(segment
		(start 342.654128 -405.845264)
		(end 342.654128 -406.70988)
		(width 0.14732)
		(layer "In15.Cu")
		(net "P5E_CPU0_PE0_TX_DP<3>")
	)
	(segment
		(start 340.03107 -222.43669)
		(end 340.025736 -222.433642)
		(width 0.0889)
		(layer "In15.Cu")
		(net "P5E_CPU0_PE0_TX_DP<3>")
	)
	(segment
		(start 339.562694 -221.62389)
		(end 339.561678 -221.623382)
		(width 0.0889)
		(layer "In15.Cu")
		(net "P5E_CPU0_PE0_TX_DP<3>")
	)
	(segment
		(start 330.456032 -252.621034)
		(end 330.43749 -252.668532)
		(width 0.14732)
		(layer "In15.Cu")
		(net "P5E_CPU0_PE0_TX_DP<3>")
	)
	(segment
		(start 338.630768 -220.000576)
		(end 338.621878 -219.995496)
		(width 0.0889)
		(layer "In15.Cu")
		(net "P5E_CPU0_PE0_TX_DP<3>")
	)
	(segment
		(start 340.040722 -222.442278)
		(end 340.033356 -222.43796)
		(width 0.0889)
		(layer "In15.Cu")
		(net "P5E_CPU0_PE0_TX_DP<3>")
	)
	(segment
		(start 330.43368 -252.679962)
		(end 329.168506 -255.924558)
		(width 0.14732)
		(layer "In15.Cu")
		(net "P5E_CPU0_PE0_TX_DP<3>")
	)
	(segment
		(start 331.579728 -381.534924)
		(end 331.540104 -381.706374)
		(width 0.14732)
		(layer "In15.Cu")
		(net "P5E_CPU0_PE0_TX_DP<3>")
	)
	(segment
		(start 332.536546 -383.069338)
		(end 332.76794 -383.440432)
		(width 0.14732)
		(layer "In15.Cu")
		(net "P5E_CPU0_PE0_TX_DP<3>")
	)
	(segment
		(start 330.444348 -221.828614)
		(end 329.683364 -223.131126)
		(width 0.14732)
		(layer "In15.Cu")
		(net "P5E_CPU0_PE0_TX_DP<3>")
	)
	(segment
		(start 331.540104 -381.706374)
		(end 331.540612 -381.70612)
		(width 0.14732)
		(layer "In15.Cu")
		(net "P5E_CPU0_PE0_TX_DP<3>")
	)
	(segment
		(start 341.097616 -224.93224)
		(end 341.008716 -224.908618)
		(width 0.0889)
		(layer "In15.Cu")
		(net "P5E_CPU0_PE0_TX_DP<3>")
	)
	(segment
		(start 341.25408 -225.203258)
		(end 341.097616 -224.93224)
		(width 0.0889)
		(layer "In15.Cu")
		(net "P5E_CPU0_PE0_TX_DP<3>")
	)
	(segment
		(start 333.346044 -220.11386)
		(end 330.444348 -221.828614)
		(width 0.14732)
		(layer "In15.Cu")
		(net "P5E_CPU0_PE0_TX_DP<3>")
	)
	(segment
		(start 331.540612 -381.70612)
		(end 331.771498 -382.076452)
		(width 0.14732)
		(layer "In15.Cu")
		(net "P5E_CPU0_PE0_TX_DP<3>")
	)
	(segment
		(start 329.977496 -249.794776)
		(end 330.456286 -250.951492)
		(width 0.14732)
		(layer "In15.Cu")
		(net "P5E_CPU0_PE0_TX_DP<3>")
	)
	(segment
		(start 340.031832 -222.437198)
		(end 340.03107 -222.43669)
		(width 0.0889)
		(layer "In15.Cu")
		(net "P5E_CPU0_PE0_TX_DP<3>")
	)
	(segment
		(start 332.134464 -382.659382)
		(end 332.36535 -383.029714)
		(width 0.14732)
		(layer "In15.Cu")
		(net "P5E_CPU0_PE0_TX_DP<3>")
	)
	(segment
		(start 332.728316 -383.611628)
		(end 332.959456 -383.982214)
		(width 0.14732)
		(layer "In15.Cu")
		(net "P5E_CPU0_PE0_TX_DP<3>")
	)
	(segment
		(start 342.839548 -403.961854)
		(end 342.654128 -405.845264)
		(width 0.14732)
		(layer "In15.Cu")
		(net "P5E_CPU0_PE0_TX_DP<3>")
	)
	(segment
		(start 327.233026 -266.620244)
		(end 330.02601 -310.491886)
		(width 0.14732)
		(layer "In15.Cu")
		(net "P5E_CPU0_PE0_TX_DP<3>")
	)
	(segment
		(start 340.502494 -223.899476)
		(end 340.510368 -223.894904)
		(width 0.0889)
		(layer "In15.Cu")
		(net "P5E_CPU0_PE0_TX_DP<3>")
	)
	(segment
		(start 335.439258 -219.988638)
		(end 335.42732 -219.995496)
		(width 0.0889)
		(layer "In15.Cu")
		(net "P5E_CPU0_PE0_TX_DP<3>")
	)
	(segment
		(start 329.168252 -255.924812)
		(end 327.90384 -259.169154)
		(width 0.14732)
		(layer "In15.Cu")
		(net "P5E_CPU0_PE0_TX_DP<3>")
	)
	(arc
		(start 340.219284 -222.761556)
		(mid 340.171605 -222.578656)
		(end 340.040722 -222.442278)
		(width 0.0889)
		(layer "In15.Cu")
		(net "P5E_CPU0_PE0_TX_DP<3>")
	)
	(arc
		(start 339.561678 -221.623382)
		(mid 339.358855 -221.423151)
		(end 339.279484 -221.149418)
		(width 0.0889)
		(layer "In15.Cu")
		(net "P5E_CPU0_PE0_TX_DP<3>")
	)
	(arc
		(start 338.237068 -220.001592)
		(mid 337.95889 -220.071315)
		(end 337.682332 -219.995496)
		(width 0.0889)
		(layer "In15.Cu")
		(net "P5E_CPU0_PE0_TX_DP<3>")
	)
	(arc
		(start 338.80933 -220.319854)
		(mid 338.761651 -220.136954)
		(end 338.630768 -220.000576)
		(width 0.0889)
		(layer "In15.Cu")
		(net "P5E_CPU0_PE0_TX_DP<3>")
	)
	(arc
		(start 334.488028 -219.995496)
		(mid 334.351326 -220.052319)
		(end 334.204564 -220.071696)
		(width 0.0889)
		(layer "In15.Cu")
		(net "P5E_CPU0_PE0_TX_DP<3>")
	)
	(arc
		(start 340.501478 -224.8789)
		(mid 340.298655 -224.678669)
		(end 340.219284 -224.404936)
		(width 0.0889)
		(layer "In15.Cu")
		(net "P5E_CPU0_PE0_TX_DP<3>")
	)
	(arc
		(start 337.682332 -219.995496)
		(mid 337.495134 -219.945353)
		(end 337.307936 -219.995496)
		(width 0.0889)
		(layer "In15.Cu")
		(net "P5E_CPU0_PE0_TX_DP<3>")
	)
	(arc
		(start 340.025736 -222.433642)
		(mid 339.823149 -222.227291)
		(end 339.74913 -221.94774)
		(width 0.0889)
		(layer "In15.Cu")
		(net "P5E_CPU0_PE0_TX_DP<3>")
	)
	(arc
		(start 336.742532 -219.995496)
		(mid 336.555334 -219.945353)
		(end 336.368136 -219.995496)
		(width 0.0889)
		(layer "In15.Cu")
		(net "P5E_CPU0_PE0_TX_DP<3>")
	)
	(arc
		(start 337.307936 -219.995496)
		(mid 337.025234 -220.071272)
		(end 336.742532 -219.995496)
		(width 0.0889)
		(layer "In15.Cu")
		(net "P5E_CPU0_PE0_TX_DP<3>")
	)
	(arc
		(start 340.510368 -223.894904)
		(mid 340.688965 -223.575626)
		(end 340.510368 -223.256348)
		(width 0.0889)
		(layer "In15.Cu")
		(net "P5E_CPU0_PE0_TX_DP<3>")
	)
	(arc
		(start 335.42732 -219.995496)
		(mid 335.153345 -220.071328)
		(end 334.877156 -220.004132)
		(width 0.0889)
		(layer "In15.Cu")
		(net "P5E_CPU0_PE0_TX_DP<3>")
	)
	(arc
		(start 340.989158 -224.916746)
		(mid 340.741006 -224.953361)
		(end 340.501478 -224.8789)
		(width 0.0889)
		(layer "In15.Cu")
		(net "P5E_CPU0_PE0_TX_DP<3>")
	)
	(arc
		(start 340.501478 -223.251268)
		(mid 340.300196 -223.053781)
		(end 340.219284 -222.783654)
		(width 0.0889)
		(layer "In15.Cu")
		(net "P5E_CPU0_PE0_TX_DP<3>")
	)
	(arc
		(start 340.219284 -224.373948)
		(mid 340.298654 -224.100214)
		(end 340.501478 -223.899984)
		(width 0.0889)
		(layer "In15.Cu")
		(net "P5E_CPU0_PE0_TX_DP<3>")
	)
	(arc
		(start 341.008716 -224.908618)
		(mid 340.998976 -224.912775)
		(end 340.989158 -224.916746)
		(width 0.0889)
		(layer "In15.Cu")
		(net "P5E_CPU0_PE0_TX_DP<3>")
	)
	(arc
		(start 334.84566 -219.985844)
		(mid 334.665619 -219.945241)
		(end 334.488028 -219.995496)
		(width 0.0889)
		(layer "In15.Cu")
		(net "P5E_CPU0_PE0_TX_DP<3>")
	)
	(arc
		(start 339.279484 -221.133924)
		(mid 339.231805 -220.951024)
		(end 339.100922 -220.814646)
		(width 0.0889)
		(layer "In15.Cu")
		(net "P5E_CPU0_PE0_TX_DP<3>")
	)
	(arc
		(start 339.092032 -220.809566)
		(mid 338.88696 -220.605887)
		(end 338.80933 -220.327474)
		(width 0.0889)
		(layer "In15.Cu")
		(net "P5E_CPU0_PE0_TX_DP<3>")
	)
	(arc
		(start 336.353404 -220.004132)
		(mid 336.076675 -220.071572)
		(end 335.802224 -219.995496)
		(width 0.0889)
		(layer "In15.Cu")
		(net "P5E_CPU0_PE0_TX_DP<3>")
	)
	(arc
		(start 339.74913 -221.94774)
		(mid 339.701451 -221.76484)
		(end 339.570568 -221.628462)
		(width 0.0889)
		(layer "In15.Cu")
		(net "P5E_CPU0_PE0_TX_DP<3>")
	)
	(arc
		(start 335.802224 -219.995496)
		(mid 335.621623 -219.945166)
		(end 335.439258 -219.988638)
		(width 0.0889)
		(layer "In15.Cu")
		(net "P5E_CPU0_PE0_TX_DP<3>")
	)
	(arc
		(start 338.621878 -219.995496)
		(mid 338.43468 -219.945353)
		(end 338.247482 -219.995496)
		(width 0.0889)
		(layer "In15.Cu")
		(net "P5E_CPU0_PE0_TX_DP<3>")
	)
	(segment
		(start 345.71305 -407.926286)
		(end 346.037408 -408.250644)
		(width 0.13208)
		(layer "F.Cu")
		(net "P5E_CPU0_PE0_TX_DP<2>")
	)
	(segment
		(start 345.71305 -407.303478)
		(end 345.71305 -407.926286)
		(width 0.13208)
		(layer "F.Cu")
		(net "P5E_CPU0_PE0_TX_DP<2>")
	)
	(segment
		(start 346.012008 -407.00452)
		(end 345.71305 -407.303478)
		(width 0.13208)
		(layer "F.Cu")
		(net "P5E_CPU0_PE0_TX_DP<2>")
	)
	(segment
		(start 339.84438 -224.925382)
		(end 339.84438 -224.389696)
		(width 0.13208)
		(layer "F.Cu")
		(net "P5E_CPU0_PE0_TX_DP<2>")
	)
	(segment
		(start 339.84438 -224.389696)
		(end 339.844634 -224.389442)
		(width 0.13208)
		(layer "F.Cu")
		(net "P5E_CPU0_PE0_TX_DP<2>")
	)
	(segment
		(start 334.343502 -382.43764)
		(end 334.58785 -382.800352)
		(width 0.14732)
		(layer "In15.Cu")
		(net "P5E_CPU0_PE0_TX_DP<2>")
	)
	(segment
		(start 333.26578 -222.386398)
		(end 331.79639 -222.386398)
		(width 0.0889)
		(layer "In15.Cu")
		(net "P5E_CPU0_PE0_TX_DP<2>")
	)
	(segment
		(start 335.80832 -384.835908)
		(end 336.053938 -385.200652)
		(width 0.14732)
		(layer "In15.Cu")
		(net "P5E_CPU0_PE0_TX_DP<2>")
	)
	(segment
		(start 336.43443 -385.765548)
		(end 345.409266 -399.093944)
		(width 0.14732)
		(layer "In15.Cu")
		(net "P5E_CPU0_PE0_TX_DP<2>")
	)
	(segment
		(start 335.842102 -384.663188)
		(end 335.80832 -384.835908)
		(width 0.14732)
		(layer "In15.Cu")
		(net "P5E_CPU0_PE0_TX_DP<2>")
	)
	(segment
		(start 340.001098 -224.118424)
		(end 339.976968 -224.02927)
		(width 0.0889)
		(layer "In15.Cu")
		(net "P5E_CPU0_PE0_TX_DP<2>")
	)
	(segment
		(start 320.344292 -330.051156)
		(end 315.4426 -334.952848)
		(width 0.14732)
		(layer "In15.Cu")
		(net "P5E_CPU0_PE0_TX_DP<2>")
	)
	(segment
		(start 336.46745 -385.596384)
		(end 336.43443 -385.765548)
		(width 0.14732)
		(layer "In15.Cu")
		(net "P5E_CPU0_PE0_TX_DP<2>")
	)
	(segment
		(start 330.68895 -223.891094)
		(end 330.61656 -224.322132)
		(width 0.14732)
		(layer "In15.Cu")
		(net "P5E_CPU0_PE0_TX_DP<2>")
	)
	(segment
		(start 334.58785 -382.800352)
		(end 334.554068 -382.973072)
		(width 0.14732)
		(layer "In15.Cu")
		(net "P5E_CPU0_PE0_TX_DP<2>")
	)
	(segment
		(start 335.597754 -384.300476)
		(end 335.842102 -384.663188)
		(width 0.14732)
		(layer "In15.Cu")
		(net "P5E_CPU0_PE0_TX_DP<2>")
	)
	(segment
		(start 330.821284 -249.400822)
		(end 331.395832 -250.789186)
		(width 0.14732)
		(layer "In15.Cu")
		(net "P5E_CPU0_PE0_TX_DP<2>")
	)
	(segment
		(start 335.214976 -383.73177)
		(end 335.181194 -383.90449)
		(width 0.14732)
		(layer "In15.Cu")
		(net "P5E_CPU0_PE0_TX_DP<2>")
	)
	(segment
		(start 330.661518 -223.319848)
		(end 330.589128 -223.750632)
		(width 0.14732)
		(layer "In15.Cu")
		(net "P5E_CPU0_PE0_TX_DP<2>")
	)
	(segment
		(start 331.732128 -222.428562)
		(end 331.382116 -222.428562)
		(width 0.14732)
		(layer "In15.Cu")
		(net "P5E_CPU0_PE0_TX_DP<2>")
	)
	(segment
		(start 345.717368 -405.845264)
		(end 345.717368 -406.70988)
		(width 0.14732)
		(layer "In15.Cu")
		(net "P5E_CPU0_PE0_TX_DP<2>")
	)
	(segment
		(start 333.926942 -382.041654)
		(end 334.170782 -382.403858)
		(width 0.14732)
		(layer "In15.Cu")
		(net "P5E_CPU0_PE0_TX_DP<2>")
	)
	(segment
		(start 345.717368 -406.70988)
		(end 346.012008 -407.00452)
		(width 0.14732)
		(layer "In15.Cu")
		(net "P5E_CPU0_PE0_TX_DP<2>")
	)
	(segment
		(start 320.072004 -361.466384)
		(end 333.543656 -381.47244)
		(width 0.14732)
		(layer "In15.Cu")
		(net "P5E_CPU0_PE0_TX_DP<2>")
	)
	(segment
		(start 339.279484 -222.780098)
		(end 339.279484 -222.761556)
		(width 0.0889)
		(layer "In15.Cu")
		(net "P5E_CPU0_PE0_TX_DP<2>")
	)
	(segment
		(start 329.059794 -244.79123)
		(end 329.059794 -245.021354)
		(width 0.14732)
		(layer "In15.Cu")
		(net "P5E_CPU0_PE0_TX_DP<2>")
	)
	(segment
		(start 336.053938 -385.200652)
		(end 336.223102 -385.233672)
		(width 0.14732)
		(layer "In15.Cu")
		(net "P5E_CPU0_PE0_TX_DP<2>")
	)
	(segment
		(start 334.970628 -383.369058)
		(end 335.214976 -383.73177)
		(width 0.14732)
		(layer "In15.Cu")
		(net "P5E_CPU0_PE0_TX_DP<2>")
	)
	(segment
		(start 331.754226 -222.428562)
		(end 331.732128 -222.428562)
		(width 0.0889)
		(layer "In15.Cu")
		(net "P5E_CPU0_PE0_TX_DP<2>")
	)
	(segment
		(start 339.093556 -222.43796)
		(end 339.092032 -222.437198)
		(width 0.0889)
		(layer "In15.Cu")
		(net "P5E_CPU0_PE0_TX_DP<2>")
	)
	(segment
		(start 331.395832 -250.789186)
		(end 331.395832 -252.797818)
		(width 0.14732)
		(layer "In15.Cu")
		(net "P5E_CPU0_PE0_TX_DP<2>")
	)
	(segment
		(start 315.4426 -340.632796)
		(end 320.072004 -361.466384)
		(width 0.14732)
		(layer "In15.Cu")
		(net "P5E_CPU0_PE0_TX_DP<2>")
	)
	(segment
		(start 331.79639 -222.386398)
		(end 331.754226 -222.428562)
		(width 0.0889)
		(layer "In15.Cu")
		(net "P5E_CPU0_PE0_TX_DP<2>")
	)
	(segment
		(start 334.018636 -222.437198)
		(end 334.008222 -222.443294)
		(width 0.0889)
		(layer "In15.Cu")
		(net "P5E_CPU0_PE0_TX_DP<2>")
	)
	(segment
		(start 334.170782 -382.403858)
		(end 334.343502 -382.43764)
		(width 0.14732)
		(layer "In15.Cu")
		(net "P5E_CPU0_PE0_TX_DP<2>")
	)
	(segment
		(start 326.67194 -321.01409)
		(end 320.344292 -330.051156)
		(width 0.14732)
		(layer "In15.Cu")
		(net "P5E_CPU0_PE0_TX_DP<2>")
	)
	(segment
		(start 335.181194 -383.90449)
		(end 335.425034 -384.266694)
		(width 0.14732)
		(layer "In15.Cu")
		(net "P5E_CPU0_PE0_TX_DP<2>")
	)
	(segment
		(start 339.844634 -224.389442)
		(end 340.001098 -224.118424)
		(width 0.0889)
		(layer "In15.Cu")
		(net "P5E_CPU0_PE0_TX_DP<2>")
	)
	(segment
		(start 338.166964 -222.445834)
		(end 338.152232 -222.437198)
		(width 0.0889)
		(layer "In15.Cu")
		(net "P5E_CPU0_PE0_TX_DP<2>")
	)
	(segment
		(start 331.141324 -222.542608)
		(end 330.661518 -223.319848)
		(width 0.14732)
		(layer "In15.Cu")
		(net "P5E_CPU0_PE0_TX_DP<2>")
	)
	(segment
		(start 331.395832 -252.797818)
		(end 328.828146 -259.386324)
		(width 0.14732)
		(layer "In15.Cu")
		(net "P5E_CPU0_PE0_TX_DP<2>")
	)
	(segment
		(start 339.100922 -222.442278)
		(end 339.093556 -222.43796)
		(width 0.0889)
		(layer "In15.Cu")
		(net "P5E_CPU0_PE0_TX_DP<2>")
	)
	(segment
		(start 333.960724 -381.868934)
		(end 333.926942 -382.041654)
		(width 0.14732)
		(layer "In15.Cu")
		(net "P5E_CPU0_PE0_TX_DP<2>")
	)
	(segment
		(start 328.17562 -266.632436)
		(end 330.98486 -310.765444)
		(width 0.14732)
		(layer "In15.Cu")
		(net "P5E_CPU0_PE0_TX_DP<2>")
	)
	(segment
		(start 337.227164 -222.445834)
		(end 337.212432 -222.437198)
		(width 0.0889)
		(layer "In15.Cu")
		(net "P5E_CPU0_PE0_TX_DP<2>")
	)
	(segment
		(start 329.059794 -245.021354)
		(end 329.343766 -246.637048)
		(width 0.14732)
		(layer "In15.Cu")
		(net "P5E_CPU0_PE0_TX_DP<2>")
	)
	(segment
		(start 336.223102 -385.233672)
		(end 336.46745 -385.596384)
		(width 0.14732)
		(layer "In15.Cu")
		(net "P5E_CPU0_PE0_TX_DP<2>")
	)
	(segment
		(start 329.343766 -246.637048)
		(end 330.821284 -249.400822)
		(width 0.14732)
		(layer "In15.Cu")
		(net "P5E_CPU0_PE0_TX_DP<2>")
	)
	(segment
		(start 334.554068 -382.973072)
		(end 334.797908 -383.335276)
		(width 0.14732)
		(layer "In15.Cu")
		(net "P5E_CPU0_PE0_TX_DP<2>")
	)
	(segment
		(start 345.902788 -403.961854)
		(end 345.717368 -405.845264)
		(width 0.14732)
		(layer "In15.Cu")
		(net "P5E_CPU0_PE0_TX_DP<2>")
	)
	(segment
		(start 333.716376 -381.506222)
		(end 333.960724 -381.868934)
		(width 0.14732)
		(layer "In15.Cu")
		(net "P5E_CPU0_PE0_TX_DP<2>")
	)
	(segment
		(start 335.425034 -384.266694)
		(end 335.597754 -384.300476)
		(width 0.14732)
		(layer "In15.Cu")
		(net "P5E_CPU0_PE0_TX_DP<2>")
	)
	(segment
		(start 330.61656 -224.322132)
		(end 330.475844 -224.421954)
		(width 0.14732)
		(layer "In15.Cu")
		(net "P5E_CPU0_PE0_TX_DP<2>")
	)
	(segment
		(start 345.409266 -399.093944)
		(end 345.902788 -400.710654)
		(width 0.14732)
		(layer "In15.Cu")
		(net "P5E_CPU0_PE0_TX_DP<2>")
	)
	(segment
		(start 328.828146 -259.386324)
		(end 328.17562 -266.632436)
		(width 0.14732)
		(layer "In15.Cu")
		(net "P5E_CPU0_PE0_TX_DP<2>")
	)
	(segment
		(start 339.74913 -223.575626)
		(end 339.74913 -223.56699)
		(width 0.0889)
		(layer "In15.Cu")
		(net "P5E_CPU0_PE0_TX_DP<2>")
	)
	(segment
		(start 330.98486 -310.765444)
		(end 326.67194 -321.01409)
		(width 0.14732)
		(layer "In15.Cu")
		(net "P5E_CPU0_PE0_TX_DP<2>")
	)
	(segment
		(start 333.543656 -381.47244)
		(end 333.716376 -381.506222)
		(width 0.14732)
		(layer "In15.Cu")
		(net "P5E_CPU0_PE0_TX_DP<2>")
	)
	(segment
		(start 330.589128 -223.750632)
		(end 330.68895 -223.891094)
		(width 0.14732)
		(layer "In15.Cu")
		(net "P5E_CPU0_PE0_TX_DP<2>")
	)
	(segment
		(start 345.902788 -400.710654)
		(end 345.902788 -403.961854)
		(width 0.14732)
		(layer "In15.Cu")
		(net "P5E_CPU0_PE0_TX_DP<2>")
	)
	(segment
		(start 330.475844 -224.421954)
		(end 328.853546 -234.05338)
		(width 0.14732)
		(layer "In15.Cu")
		(net "P5E_CPU0_PE0_TX_DP<2>")
	)
	(segment
		(start 315.4426 -334.952848)
		(end 315.4426 -340.632796)
		(width 0.14732)
		(layer "In15.Cu")
		(net "P5E_CPU0_PE0_TX_DP<2>")
	)
	(segment
		(start 334.797908 -383.335276)
		(end 334.970628 -383.369058)
		(width 0.14732)
		(layer "In15.Cu")
		(net "P5E_CPU0_PE0_TX_DP<2>")
	)
	(segment
		(start 331.382116 -222.428562)
		(end 331.141324 -222.542608)
		(width 0.14732)
		(layer "In15.Cu")
		(net "P5E_CPU0_PE0_TX_DP<2>")
	)
	(segment
		(start 328.853546 -234.05338)
		(end 329.059794 -244.79123)
		(width 0.14732)
		(layer "In15.Cu")
		(net "P5E_CPU0_PE0_TX_DP<2>")
	)
	(arc
		(start 339.561932 -223.251268)
		(mid 339.359646 -223.052287)
		(end 339.279484 -222.780098)
		(width 0.0889)
		(layer "In15.Cu")
		(net "P5E_CPU0_PE0_TX_DP<2>")
	)
	(arc
		(start 338.152232 -222.437198)
		(mid 337.965034 -222.387055)
		(end 337.777836 -222.437198)
		(width 0.0889)
		(layer "In15.Cu")
		(net "P5E_CPU0_PE0_TX_DP<2>")
	)
	(arc
		(start 339.092032 -222.437198)
		(mid 338.904834 -222.387055)
		(end 338.717636 -222.437198)
		(width 0.0889)
		(layer "In15.Cu")
		(net "P5E_CPU0_PE0_TX_DP<2>")
	)
	(arc
		(start 334.008222 -222.443294)
		(mid 333.72979 -222.51314)
		(end 333.452978 -222.437198)
		(width 0.0889)
		(layer "In15.Cu")
		(net "P5E_CPU0_PE0_TX_DP<2>")
	)
	(arc
		(start 336.272632 -222.437198)
		(mid 336.085434 -222.387055)
		(end 335.898236 -222.437198)
		(width 0.0889)
		(layer "In15.Cu")
		(net "P5E_CPU0_PE0_TX_DP<2>")
	)
	(arc
		(start 336.838036 -222.437198)
		(mid 336.555334 -222.512974)
		(end 336.272632 -222.437198)
		(width 0.0889)
		(layer "In15.Cu")
		(net "P5E_CPU0_PE0_TX_DP<2>")
	)
	(arc
		(start 333.452978 -222.437198)
		(mid 333.362722 -222.399476)
		(end 333.26578 -222.386398)
		(width 0.0889)
		(layer "In15.Cu")
		(net "P5E_CPU0_PE0_TX_DP<2>")
	)
	(arc
		(start 335.898236 -222.437198)
		(mid 335.615534 -222.512974)
		(end 335.332832 -222.437198)
		(width 0.0889)
		(layer "In15.Cu")
		(net "P5E_CPU0_PE0_TX_DP<2>")
	)
	(arc
		(start 339.74913 -223.56699)
		(mid 339.69686 -223.384625)
		(end 339.561932 -223.251268)
		(width 0.0889)
		(layer "In15.Cu")
		(net "P5E_CPU0_PE0_TX_DP<2>")
	)
	(arc
		(start 339.976968 -224.02927)
		(mid 339.809214 -223.829492)
		(end 339.74913 -223.575626)
		(width 0.0889)
		(layer "In15.Cu")
		(net "P5E_CPU0_PE0_TX_DP<2>")
	)
	(arc
		(start 338.717636 -222.437198)
		(mid 338.443437 -222.513033)
		(end 338.166964 -222.445834)
		(width 0.0889)
		(layer "In15.Cu")
		(net "P5E_CPU0_PE0_TX_DP<2>")
	)
	(arc
		(start 335.332832 -222.437198)
		(mid 335.145634 -222.387055)
		(end 334.958436 -222.437198)
		(width 0.0889)
		(layer "In15.Cu")
		(net "P5E_CPU0_PE0_TX_DP<2>")
	)
	(arc
		(start 337.212432 -222.437198)
		(mid 337.025234 -222.387055)
		(end 336.838036 -222.437198)
		(width 0.0889)
		(layer "In15.Cu")
		(net "P5E_CPU0_PE0_TX_DP<2>")
	)
	(arc
		(start 334.958436 -222.437198)
		(mid 334.675734 -222.512974)
		(end 334.393032 -222.437198)
		(width 0.0889)
		(layer "In15.Cu")
		(net "P5E_CPU0_PE0_TX_DP<2>")
	)
	(arc
		(start 337.777836 -222.437198)
		(mid 337.503637 -222.513033)
		(end 337.227164 -222.445834)
		(width 0.0889)
		(layer "In15.Cu")
		(net "P5E_CPU0_PE0_TX_DP<2>")
	)
	(arc
		(start 334.393032 -222.437198)
		(mid 334.205834 -222.387055)
		(end 334.018636 -222.437198)
		(width 0.0889)
		(layer "In15.Cu")
		(net "P5E_CPU0_PE0_TX_DP<2>")
	)
	(arc
		(start 339.279484 -222.761556)
		(mid 339.231805 -222.578656)
		(end 339.100922 -222.442278)
		(width 0.0889)
		(layer "In15.Cu")
		(net "P5E_CPU0_PE0_TX_DP<2>")
	)
	(segment
		(start 339.374734 -225.203512)
		(end 339.37448 -225.203258)
		(width 0.13208)
		(layer "F.Cu")
		(net "P5E_CPU0_PE0_TX_DP<1>")
	)
	(segment
		(start 349.075248 -407.00452)
		(end 348.77629 -407.303478)
		(width 0.13208)
		(layer "F.Cu")
		(net "P5E_CPU0_PE0_TX_DP<1>")
	)
	(segment
		(start 348.77629 -407.303478)
		(end 348.77629 -407.926286)
		(width 0.13208)
		(layer "F.Cu")
		(net "P5E_CPU0_PE0_TX_DP<1>")
	)
	(segment
		(start 339.374734 -225.739198)
		(end 339.374734 -225.203512)
		(width 0.13208)
		(layer "F.Cu")
		(net "P5E_CPU0_PE0_TX_DP<1>")
	)
	(segment
		(start 348.77629 -407.926286)
		(end 349.100648 -408.250644)
		(width 0.13208)
		(layer "F.Cu")
		(net "P5E_CPU0_PE0_TX_DP<1>")
	)
	(segment
		(start 316.422786 -340.572852)
		(end 320.972688 -361.04703)
		(width 0.14732)
		(layer "In15.Cu")
		(net "P5E_CPU0_PE0_TX_DP<1>")
	)
	(segment
		(start 335.697576 -381.231394)
		(end 335.953608 -381.585978)
		(width 0.14732)
		(layer "In15.Cu")
		(net "P5E_CPU0_PE0_TX_DP<1>")
	)
	(segment
		(start 336.583274 -382.669796)
		(end 336.839052 -383.023872)
		(width 0.14732)
		(layer "In15.Cu")
		(net "P5E_CPU0_PE0_TX_DP<1>")
	)
	(segment
		(start 320.972688 -361.04703)
		(end 335.524348 -381.2032)
		(width 0.14732)
		(layer "In15.Cu")
		(net "P5E_CPU0_PE0_TX_DP<1>")
	)
	(segment
		(start 330.036678 -234.170982)
		(end 330.110338 -245.190518)
		(width 0.14732)
		(layer "In15.Cu")
		(net "P5E_CPU0_PE0_TX_DP<1>")
	)
	(segment
		(start 337.307936 -223.251268)
		(end 337.297522 -223.257364)
		(width 0.0889)
		(layer "In15.Cu")
		(net "P5E_CPU0_PE0_TX_DP<1>")
	)
	(segment
		(start 338.621878 -223.899984)
		(end 338.622894 -223.899476)
		(width 0.0889)
		(layer "In15.Cu")
		(net "P5E_CPU0_PE0_TX_DP<1>")
	)
	(segment
		(start 332.01356 -223.887284)
		(end 330.036678 -234.170982)
		(width 0.14732)
		(layer "In15.Cu")
		(net "P5E_CPU0_PE0_TX_DP<1>")
	)
	(segment
		(start 338.622894 -223.899476)
		(end 338.630768 -223.894904)
		(width 0.0889)
		(layer "In15.Cu")
		(net "P5E_CPU0_PE0_TX_DP<1>")
	)
	(segment
		(start 332.325472 -250.60275)
		(end 332.325472 -252.97257)
		(width 0.14732)
		(layer "In15.Cu")
		(net "P5E_CPU0_PE0_TX_DP<1>")
	)
	(segment
		(start 338.339684 -224.404936)
		(end 338.339684 -224.373948)
		(width 0.0889)
		(layer "In15.Cu")
		(net "P5E_CPU0_PE0_TX_DP<1>")
	)
	(segment
		(start 316.422786 -335.292954)
		(end 316.422786 -340.572852)
		(width 0.14732)
		(layer "In15.Cu")
		(net "P5E_CPU0_PE0_TX_DP<1>")
	)
	(segment
		(start 335.52384 -381.203454)
		(end 335.697576 -381.231394)
		(width 0.14732)
		(layer "In15.Cu")
		(net "P5E_CPU0_PE0_TX_DP<1>")
	)
	(segment
		(start 327.368662 -321.784218)
		(end 321.382136 -330.333604)
		(width 0.14732)
		(layer "In15.Cu")
		(net "P5E_CPU0_PE0_TX_DP<1>")
	)
	(segment
		(start 336.181192 -382.11379)
		(end 336.354928 -382.14173)
		(width 0.14732)
		(layer "In15.Cu")
		(net "P5E_CPU0_PE0_TX_DP<1>")
	)
	(segment
		(start 330.238608 -246.338852)
		(end 331.659738 -248.995184)
		(width 0.14732)
		(layer "In15.Cu")
		(net "P5E_CPU0_PE0_TX_DP<1>")
	)
	(segment
		(start 338.630768 -223.256348)
		(end 338.621878 -223.251268)
		(width 0.0889)
		(layer "In15.Cu")
		(net "P5E_CPU0_PE0_TX_DP<1>")
	)
	(segment
		(start 330.110338 -245.190518)
		(end 330.110338 -245.610634)
		(width 0.14732)
		(layer "In15.Cu")
		(net "P5E_CPU0_PE0_TX_DP<1>")
	)
	(segment
		(start 337.01228 -383.052066)
		(end 337.268312 -383.40665)
		(width 0.14732)
		(layer "In15.Cu")
		(net "P5E_CPU0_PE0_TX_DP<1>")
	)
	(segment
		(start 332.246732 -223.594168)
		(end 332.246732 -223.654112)
		(width 0.0889)
		(layer "In15.Cu")
		(net "P5E_CPU0_PE0_TX_DP<1>")
	)
	(segment
		(start 348.966028 -403.961854)
		(end 348.780608 -405.845264)
		(width 0.14732)
		(layer "In15.Cu")
		(net "P5E_CPU0_PE0_TX_DP<1>")
	)
	(segment
		(start 329.742546 -259.601208)
		(end 329.108308 -266.644628)
		(width 0.14732)
		(layer "In15.Cu")
		(net "P5E_CPU0_PE0_TX_DP<1>")
	)
	(segment
		(start 336.367882 -223.251268)
		(end 336.357468 -223.257364)
		(width 0.0889)
		(layer "In15.Cu")
		(net "P5E_CPU0_PE0_TX_DP<1>")
	)
	(segment
		(start 330.110338 -245.610634)
		(end 330.238608 -246.338852)
		(width 0.14732)
		(layer "In15.Cu")
		(net "P5E_CPU0_PE0_TX_DP<1>")
	)
	(segment
		(start 335.953608 -381.585978)
		(end 335.925668 -381.759714)
		(width 0.14732)
		(layer "In15.Cu")
		(net "P5E_CPU0_PE0_TX_DP<1>")
	)
	(segment
		(start 348.966028 -399.821908)
		(end 348.966028 -403.961854)
		(width 0.14732)
		(layer "In15.Cu")
		(net "P5E_CPU0_PE0_TX_DP<1>")
	)
	(segment
		(start 336.838544 -383.024126)
		(end 337.01228 -383.052066)
		(width 0.14732)
		(layer "In15.Cu")
		(net "P5E_CPU0_PE0_TX_DP<1>")
	)
	(segment
		(start 332.246732 -223.654112)
		(end 332.231238 -223.669606)
		(width 0.0889)
		(layer "In15.Cu")
		(net "P5E_CPU0_PE0_TX_DP<1>")
	)
	(segment
		(start 331.928724 -310.95061)
		(end 327.368662 -321.784218)
		(width 0.14732)
		(layer "In15.Cu")
		(net "P5E_CPU0_PE0_TX_DP<1>")
	)
	(segment
		(start 337.268312 -383.40665)
		(end 337.240372 -383.580132)
		(width 0.14732)
		(layer "In15.Cu")
		(net "P5E_CPU0_PE0_TX_DP<1>")
	)
	(segment
		(start 339.37448 -225.203258)
		(end 339.218016 -224.93224)
		(width 0.0889)
		(layer "In15.Cu")
		(net "P5E_CPU0_PE0_TX_DP<1>")
	)
	(segment
		(start 331.659738 -248.995184)
		(end 332.325472 -250.60275)
		(width 0.14732)
		(layer "In15.Cu")
		(net "P5E_CPU0_PE0_TX_DP<1>")
	)
	(segment
		(start 329.108308 -266.644628)
		(end 331.928724 -310.95061)
		(width 0.14732)
		(layer "In15.Cu")
		(net "P5E_CPU0_PE0_TX_DP<1>")
	)
	(segment
		(start 332.325472 -252.97257)
		(end 329.742546 -259.601208)
		(width 0.14732)
		(layer "In15.Cu")
		(net "P5E_CPU0_PE0_TX_DP<1>")
	)
	(segment
		(start 335.925922 -381.75946)
		(end 336.181446 -382.113282)
		(width 0.14732)
		(layer "In15.Cu")
		(net "P5E_CPU0_PE0_TX_DP<1>")
	)
	(segment
		(start 336.61096 -382.496314)
		(end 336.58302 -382.67005)
		(width 0.14732)
		(layer "In15.Cu")
		(net "P5E_CPU0_PE0_TX_DP<1>")
	)
	(segment
		(start 337.240372 -383.580132)
		(end 348.966028 -399.821908)
		(width 0.14732)
		(layer "In15.Cu")
		(net "P5E_CPU0_PE0_TX_DP<1>")
	)
	(segment
		(start 348.780608 -406.70988)
		(end 349.075248 -407.00452)
		(width 0.14732)
		(layer "In15.Cu")
		(net "P5E_CPU0_PE0_TX_DP<1>")
	)
	(segment
		(start 348.780608 -405.845264)
		(end 348.780608 -406.70988)
		(width 0.14732)
		(layer "In15.Cu")
		(net "P5E_CPU0_PE0_TX_DP<1>")
	)
	(segment
		(start 332.231238 -223.669606)
		(end 332.01356 -223.887284)
		(width 0.14732)
		(layer "In15.Cu")
		(net "P5E_CPU0_PE0_TX_DP<1>")
	)
	(segment
		(start 335.524348 -381.2032)
		(end 335.52384 -381.203454)
		(width 0.14732)
		(layer "In15.Cu")
		(net "P5E_CPU0_PE0_TX_DP<1>")
	)
	(segment
		(start 332.998064 -223.259904)
		(end 332.983332 -223.251268)
		(width 0.0889)
		(layer "In15.Cu")
		(net "P5E_CPU0_PE0_TX_DP<1>")
	)
	(segment
		(start 335.925668 -381.759714)
		(end 335.925922 -381.75946)
		(width 0.14732)
		(layer "In15.Cu")
		(net "P5E_CPU0_PE0_TX_DP<1>")
	)
	(segment
		(start 332.530704 -223.310196)
		(end 332.246732 -223.594168)
		(width 0.0889)
		(layer "In15.Cu")
		(net "P5E_CPU0_PE0_TX_DP<1>")
	)
	(segment
		(start 339.218016 -224.93224)
		(end 339.129116 -224.908618)
		(width 0.0889)
		(layer "In15.Cu")
		(net "P5E_CPU0_PE0_TX_DP<1>")
	)
	(segment
		(start 336.58302 -382.67005)
		(end 336.583274 -382.669796)
		(width 0.14732)
		(layer "In15.Cu")
		(net "P5E_CPU0_PE0_TX_DP<1>")
	)
	(segment
		(start 336.181446 -382.113282)
		(end 336.181192 -382.11379)
		(width 0.14732)
		(layer "In15.Cu")
		(net "P5E_CPU0_PE0_TX_DP<1>")
	)
	(segment
		(start 336.354928 -382.14173)
		(end 336.61096 -382.496314)
		(width 0.14732)
		(layer "In15.Cu")
		(net "P5E_CPU0_PE0_TX_DP<1>")
	)
	(segment
		(start 338.247482 -223.251268)
		(end 338.237068 -223.257364)
		(width 0.0889)
		(layer "In15.Cu")
		(net "P5E_CPU0_PE0_TX_DP<1>")
	)
	(segment
		(start 336.839052 -383.023872)
		(end 336.838544 -383.024126)
		(width 0.14732)
		(layer "In15.Cu")
		(net "P5E_CPU0_PE0_TX_DP<1>")
	)
	(segment
		(start 321.382136 -330.333604)
		(end 316.422786 -335.292954)
		(width 0.14732)
		(layer "In15.Cu")
		(net "P5E_CPU0_PE0_TX_DP<1>")
	)
	(arc
		(start 334.488536 -223.251268)
		(mid 334.205834 -223.32701)
		(end 333.923132 -223.251268)
		(width 0.0889)
		(layer "In15.Cu")
		(net "P5E_CPU0_PE0_TX_DP<1>")
	)
	(arc
		(start 333.548736 -223.251268)
		(mid 333.274507 -223.327193)
		(end 332.998064 -223.259904)
		(width 0.0889)
		(layer "In15.Cu")
		(net "P5E_CPU0_PE0_TX_DP<1>")
	)
	(arc
		(start 335.428336 -223.251268)
		(mid 335.145634 -223.32701)
		(end 334.862932 -223.251268)
		(width 0.0889)
		(layer "In15.Cu")
		(net "P5E_CPU0_PE0_TX_DP<1>")
	)
	(arc
		(start 338.621878 -223.251268)
		(mid 338.43468 -223.201125)
		(end 338.247482 -223.251268)
		(width 0.0889)
		(layer "In15.Cu")
		(net "P5E_CPU0_PE0_TX_DP<1>")
	)
	(arc
		(start 334.862932 -223.251268)
		(mid 334.675734 -223.201125)
		(end 334.488536 -223.251268)
		(width 0.0889)
		(layer "In15.Cu")
		(net "P5E_CPU0_PE0_TX_DP<1>")
	)
	(arc
		(start 332.608936 -223.251268)
		(mid 332.567878 -223.278155)
		(end 332.530704 -223.310196)
		(width 0.0889)
		(layer "In15.Cu")
		(net "P5E_CPU0_PE0_TX_DP<1>")
	)
	(arc
		(start 336.742278 -223.251268)
		(mid 336.55508 -223.201125)
		(end 336.367882 -223.251268)
		(width 0.0889)
		(layer "In15.Cu")
		(net "P5E_CPU0_PE0_TX_DP<1>")
	)
	(arc
		(start 332.983332 -223.251268)
		(mid 332.796134 -223.201125)
		(end 332.608936 -223.251268)
		(width 0.0889)
		(layer "In15.Cu")
		(net "P5E_CPU0_PE0_TX_DP<1>")
	)
	(arc
		(start 338.237068 -223.257364)
		(mid 337.95889 -223.327056)
		(end 337.682332 -223.251268)
		(width 0.0889)
		(layer "In15.Cu")
		(net "P5E_CPU0_PE0_TX_DP<1>")
	)
	(arc
		(start 336.357468 -223.257364)
		(mid 336.07929 -223.327056)
		(end 335.802732 -223.251268)
		(width 0.0889)
		(layer "In15.Cu")
		(net "P5E_CPU0_PE0_TX_DP<1>")
	)
	(arc
		(start 337.682332 -223.251268)
		(mid 337.495134 -223.201125)
		(end 337.307936 -223.251268)
		(width 0.0889)
		(layer "In15.Cu")
		(net "P5E_CPU0_PE0_TX_DP<1>")
	)
	(arc
		(start 338.630768 -223.894904)
		(mid 338.809365 -223.575626)
		(end 338.630768 -223.256348)
		(width 0.0889)
		(layer "In15.Cu")
		(net "P5E_CPU0_PE0_TX_DP<1>")
	)
	(arc
		(start 338.339684 -224.373948)
		(mid 338.419054 -224.100214)
		(end 338.621878 -223.899984)
		(width 0.0889)
		(layer "In15.Cu")
		(net "P5E_CPU0_PE0_TX_DP<1>")
	)
	(arc
		(start 339.109558 -224.916746)
		(mid 338.861406 -224.953361)
		(end 338.621878 -224.8789)
		(width 0.0889)
		(layer "In15.Cu")
		(net "P5E_CPU0_PE0_TX_DP<1>")
	)
	(arc
		(start 333.923132 -223.251268)
		(mid 333.735934 -223.201125)
		(end 333.548736 -223.251268)
		(width 0.0889)
		(layer "In15.Cu")
		(net "P5E_CPU0_PE0_TX_DP<1>")
	)
	(arc
		(start 339.129116 -224.908618)
		(mid 339.119376 -224.912775)
		(end 339.109558 -224.916746)
		(width 0.0889)
		(layer "In15.Cu")
		(net "P5E_CPU0_PE0_TX_DP<1>")
	)
	(arc
		(start 338.621878 -224.8789)
		(mid 338.419055 -224.678669)
		(end 338.339684 -224.404936)
		(width 0.0889)
		(layer "In15.Cu")
		(net "P5E_CPU0_PE0_TX_DP<1>")
	)
	(arc
		(start 335.802732 -223.251268)
		(mid 335.615534 -223.201125)
		(end 335.428336 -223.251268)
		(width 0.0889)
		(layer "In15.Cu")
		(net "P5E_CPU0_PE0_TX_DP<1>")
	)
	(arc
		(start 337.297522 -223.257364)
		(mid 337.01909 -223.327178)
		(end 336.742278 -223.251268)
		(width 0.0889)
		(layer "In15.Cu")
		(net "P5E_CPU0_PE0_TX_DP<1>")
	)
	(segment
		(start 352.531934 -225.203512)
		(end 352.53168 -225.203258)
		(width 0.13208)
		(layer "F.Cu")
		(net "P5E_CPU0_PE0_TX_DP<15>")
	)
	(segment
		(start 305.89093 -407.926286)
		(end 306.215288 -408.250644)
		(width 0.13208)
		(layer "F.Cu")
		(net "P5E_CPU0_PE0_TX_DP<15>")
	)
	(segment
		(start 306.189888 -407.00452)
		(end 305.89093 -407.303478)
		(width 0.13208)
		(layer "F.Cu")
		(net "P5E_CPU0_PE0_TX_DP<15>")
	)
	(segment
		(start 352.531934 -225.739198)
		(end 352.531934 -225.203512)
		(width 0.13208)
		(layer "F.Cu")
		(net "P5E_CPU0_PE0_TX_DP<15>")
	)
	(segment
		(start 305.89093 -407.303478)
		(end 305.89093 -407.926286)
		(width 0.13208)
		(layer "F.Cu")
		(net "P5E_CPU0_PE0_TX_DP<15>")
	)
	(segment
		(start 320.967862 -214.696548)
		(end 318.102234 -220.219524)
		(width 0.14732)
		(layer "In15.Cu")
		(net "P5E_CPU0_PE0_TX_DP<15>")
	)
	(segment
		(start 312.205624 -317.2714)
		(end 311.622694 -317.2714)
		(width 0.14732)
		(layer "In15.Cu")
		(net "P5E_CPU0_PE0_TX_DP<15>")
	)
	(segment
		(start 335.400396 -200.53427)
		(end 334.436212 -201.144886)
		(width 0.14732)
		(layer "In15.Cu")
		(net "P5E_CPU0_PE0_TX_DP<15>")
	)
	(segment
		(start 306.888896 -383.582672)
		(end 306.867306 -384.01879)
		(width 0.14732)
		(layer "In15.Cu")
		(net "P5E_CPU0_PE0_TX_DP<15>")
	)
	(segment
		(start 352.53168 -225.203258)
		(end 352.375216 -224.93224)
		(width 0.0889)
		(layer "In15.Cu")
		(net "P5E_CPU0_PE0_TX_DP<15>")
	)
	(segment
		(start 350.137222 -213.997794)
		(end 350.10471 -213.914228)
		(width 0.0889)
		(layer "In15.Cu")
		(net "P5E_CPU0_PE0_TX_DP<15>")
	)
	(segment
		(start 350.04502 -213.12251)
		(end 350.04502 -211.335366)
		(width 0.14732)
		(layer "In15.Cu")
		(net "P5E_CPU0_PE0_TX_DP<15>")
	)
	(segment
		(start 350.369124 -214.946992)
		(end 350.378014 -214.941912)
		(width 0.0889)
		(layer "In15.Cu")
		(net "P5E_CPU0_PE0_TX_DP<15>")
	)
	(segment
		(start 350.04502 -211.335366)
		(end 348.959932 -208.715864)
		(width 0.14732)
		(layer "In15.Cu")
		(net "P5E_CPU0_PE0_TX_DP<15>")
	)
	(segment
		(start 305.895248 -406.70988)
		(end 306.189888 -407.00452)
		(width 0.14732)
		(layer "In15.Cu")
		(net "P5E_CPU0_PE0_TX_DP<15>")
	)
	(segment
		(start 302.998378 -341.994998)
		(end 307.831236 -363.74832)
		(width 0.14732)
		(layer "In15.Cu")
		(net "P5E_CPU0_PE0_TX_DP<15>")
	)
	(segment
		(start 351.779078 -223.899984)
		(end 351.780094 -223.899476)
		(width 0.0889)
		(layer "In15.Cu")
		(net "P5E_CPU0_PE0_TX_DP<15>")
	)
	(segment
		(start 351.30867 -222.43669)
		(end 351.303336 -222.433642)
		(width 0.0889)
		(layer "In15.Cu")
		(net "P5E_CPU0_PE0_TX_DP<15>")
	)
	(segment
		(start 313.852814 -315.62421)
		(end 312.205624 -317.2714)
		(width 0.14732)
		(layer "In15.Cu")
		(net "P5E_CPU0_PE0_TX_DP<15>")
	)
	(segment
		(start 306.978812 -381.776224)
		(end 307.096922 -381.90678)
		(width 0.14732)
		(layer "In15.Cu")
		(net "P5E_CPU0_PE0_TX_DP<15>")
	)
	(segment
		(start 351.496884 -222.783654)
		(end 351.496884 -222.761556)
		(width 0.0889)
		(layer "In15.Cu")
		(net "P5E_CPU0_PE0_TX_DP<15>")
	)
	(segment
		(start 350.557084 -217.8939)
		(end 350.557084 -217.859864)
		(width 0.0889)
		(layer "In15.Cu")
		(net "P5E_CPU0_PE0_TX_DP<15>")
	)
	(segment
		(start 307.000402 -381.340106)
		(end 306.978812 -381.776224)
		(width 0.14732)
		(layer "In15.Cu")
		(net "P5E_CPU0_PE0_TX_DP<15>")
	)
	(segment
		(start 306.908454 -385.707382)
		(end 306.777644 -385.825492)
		(width 0.14732)
		(layer "In15.Cu")
		(net "P5E_CPU0_PE0_TX_DP<15>")
	)
	(segment
		(start 318.072262 -305.581812)
		(end 315.483494 -314.809124)
		(width 0.14732)
		(layer "In15.Cu")
		(net "P5E_CPU0_PE0_TX_DP<15>")
	)
	(segment
		(start 350.04502 -213.144608)
		(end 350.04502 -213.12251)
		(width 0.0889)
		(layer "In15.Cu")
		(net "P5E_CPU0_PE0_TX_DP<15>")
	)
	(segment
		(start 306.98567 -384.149346)
		(end 306.96408 -384.585972)
		(width 0.14732)
		(layer "In15.Cu")
		(net "P5E_CPU0_PE0_TX_DP<15>")
	)
	(segment
		(start 307.041296 -383.027936)
		(end 307.019706 -383.464562)
		(width 0.14732)
		(layer "In15.Cu")
		(net "P5E_CPU0_PE0_TX_DP<15>")
	)
	(segment
		(start 309.611014 -319.28308)
		(end 306.956206 -320.3829)
		(width 0.14732)
		(layer "In15.Cu")
		(net "P5E_CPU0_PE0_TX_DP<15>")
	)
	(segment
		(start 350.378522 -215.931242)
		(end 350.36887 -215.925654)
		(width 0.0889)
		(layer "In15.Cu")
		(net "P5E_CPU0_PE0_TX_DP<15>")
	)
	(segment
		(start 318.102234 -220.219524)
		(end 316.242446 -232.254298)
		(width 0.14732)
		(layer "In15.Cu")
		(net "P5E_CPU0_PE0_TX_DP<15>")
	)
	(segment
		(start 350.848168 -221.628462)
		(end 350.840294 -221.62389)
		(width 0.0889)
		(layer "In15.Cu")
		(net "P5E_CPU0_PE0_TX_DP<15>")
	)
	(segment
		(start 307.034438 -380.654814)
		(end 307.152548 -380.78537)
		(width 0.14732)
		(layer "In15.Cu")
		(net "P5E_CPU0_PE0_TX_DP<15>")
	)
	(segment
		(start 350.557084 -216.260426)
		(end 350.557084 -216.25052)
		(width 0.0889)
		(layer "In15.Cu")
		(net "P5E_CPU0_PE0_TX_DP<15>")
	)
	(segment
		(start 307.019706 -383.464562)
		(end 306.888896 -383.582672)
		(width 0.14732)
		(layer "In15.Cu")
		(net "P5E_CPU0_PE0_TX_DP<15>")
	)
	(segment
		(start 306.867306 -384.01879)
		(end 306.98567 -384.149346)
		(width 0.14732)
		(layer "In15.Cu")
		(net "P5E_CPU0_PE0_TX_DP<15>")
	)
	(segment
		(start 333.665068 -201.777092)
		(end 330.368148 -204.836776)
		(width 0.14732)
		(layer "In15.Cu")
		(net "P5E_CPU0_PE0_TX_DP<15>")
	)
	(segment
		(start 351.780094 -223.251776)
		(end 351.779078 -223.251268)
		(width 0.0889)
		(layer "In15.Cu")
		(net "P5E_CPU0_PE0_TX_DP<15>")
	)
	(segment
		(start 306.778152 -385.825746)
		(end 306.080668 -399.910808)
		(width 0.14732)
		(layer "In15.Cu")
		(net "P5E_CPU0_PE0_TX_DP<15>")
	)
	(segment
		(start 306.930044 -385.270756)
		(end 306.908454 -385.707382)
		(width 0.14732)
		(layer "In15.Cu")
		(net "P5E_CPU0_PE0_TX_DP<15>")
	)
	(segment
		(start 351.496884 -224.404936)
		(end 351.496884 -224.373948)
		(width 0.0889)
		(layer "In15.Cu")
		(net "P5E_CPU0_PE0_TX_DP<15>")
	)
	(segment
		(start 336.873088 -200.53427)
		(end 335.400396 -200.53427)
		(width 0.14732)
		(layer "In15.Cu")
		(net "P5E_CPU0_PE0_TX_DP<15>")
	)
	(segment
		(start 306.923186 -382.897634)
		(end 307.041296 -383.027936)
		(width 0.14732)
		(layer "In15.Cu")
		(net "P5E_CPU0_PE0_TX_DP<15>")
	)
	(segment
		(start 307.130958 -381.221742)
		(end 307.000402 -381.340106)
		(width 0.14732)
		(layer "In15.Cu")
		(net "P5E_CPU0_PE0_TX_DP<15>")
	)
	(segment
		(start 311.622694 -317.2714)
		(end 309.611014 -319.28308)
		(width 0.14732)
		(layer "In15.Cu")
		(net "P5E_CPU0_PE0_TX_DP<15>")
	)
	(segment
		(start 348.959932 -208.715864)
		(end 342.397588 -202.15352)
		(width 0.14732)
		(layer "In15.Cu")
		(net "P5E_CPU0_PE0_TX_DP<15>")
	)
	(segment
		(start 306.96408 -384.585972)
		(end 306.83327 -384.704082)
		(width 0.14732)
		(layer "In15.Cu")
		(net "P5E_CPU0_PE0_TX_DP<15>")
	)
	(segment
		(start 316.242446 -232.254298)
		(end 314.841382 -249.919744)
		(width 0.14732)
		(layer "In15.Cu")
		(net "P5E_CPU0_PE0_TX_DP<15>")
	)
	(segment
		(start 301.563532 -329.113642)
		(end 302.998378 -341.994998)
		(width 0.14732)
		(layer "In15.Cu")
		(net "P5E_CPU0_PE0_TX_DP<15>")
	)
	(segment
		(start 350.087184 -213.820502)
		(end 350.087184 -213.186772)
		(width 0.0889)
		(layer "In15.Cu")
		(net "P5E_CPU0_PE0_TX_DP<15>")
	)
	(segment
		(start 305.895248 -405.845264)
		(end 305.895248 -406.70988)
		(width 0.14732)
		(layer "In15.Cu")
		(net "P5E_CPU0_PE0_TX_DP<15>")
	)
	(segment
		(start 350.840294 -221.62389)
		(end 350.839278 -221.623382)
		(width 0.0889)
		(layer "In15.Cu")
		(net "P5E_CPU0_PE0_TX_DP<15>")
	)
	(segment
		(start 314.66917 -315.62421)
		(end 313.852814 -315.62421)
		(width 0.14732)
		(layer "In15.Cu")
		(net "P5E_CPU0_PE0_TX_DP<15>")
	)
	(segment
		(start 314.841382 -249.919744)
		(end 314.735464 -253.468886)
		(width 0.14732)
		(layer "In15.Cu")
		(net "P5E_CPU0_PE0_TX_DP<15>")
	)
	(segment
		(start 306.83327 -384.704082)
		(end 306.81168 -385.1402)
		(width 0.14732)
		(layer "In15.Cu")
		(net "P5E_CPU0_PE0_TX_DP<15>")
	)
	(segment
		(start 350.848168 -218.372944)
		(end 350.840294 -218.368372)
		(width 0.0889)
		(layer "In15.Cu")
		(net "P5E_CPU0_PE0_TX_DP<15>")
	)
	(segment
		(start 306.944776 -382.461516)
		(end 306.923186 -382.897634)
		(width 0.14732)
		(layer "In15.Cu")
		(net "P5E_CPU0_PE0_TX_DP<15>")
	)
	(segment
		(start 307.861716 -363.938312)
		(end 307.034438 -380.654814)
		(width 0.14732)
		(layer "In15.Cu")
		(net "P5E_CPU0_PE0_TX_DP<15>")
	)
	(segment
		(start 350.840294 -218.368372)
		(end 350.839278 -218.367864)
		(width 0.0889)
		(layer "In15.Cu")
		(net "P5E_CPU0_PE0_TX_DP<15>")
	)
	(segment
		(start 307.096922 -381.90678)
		(end 307.075332 -382.343152)
		(width 0.14732)
		(layer "In15.Cu")
		(net "P5E_CPU0_PE0_TX_DP<15>")
	)
	(segment
		(start 306.080668 -403.961854)
		(end 305.895248 -405.845264)
		(width 0.14732)
		(layer "In15.Cu")
		(net "P5E_CPU0_PE0_TX_DP<15>")
	)
	(segment
		(start 351.318322 -222.442278)
		(end 351.30867 -222.43669)
		(width 0.0889)
		(layer "In15.Cu")
		(net "P5E_CPU0_PE0_TX_DP<15>")
	)
	(segment
		(start 350.36887 -215.925654)
		(end 350.363536 -215.922606)
		(width 0.0889)
		(layer "In15.Cu")
		(net "P5E_CPU0_PE0_TX_DP<15>")
	)
	(segment
		(start 350.557084 -221.149418)
		(end 350.557084 -221.115382)
		(width 0.0889)
		(layer "In15.Cu")
		(net "P5E_CPU0_PE0_TX_DP<15>")
	)
	(segment
		(start 307.152548 -380.78537)
		(end 307.130958 -381.221742)
		(width 0.14732)
		(layer "In15.Cu")
		(net "P5E_CPU0_PE0_TX_DP<15>")
	)
	(segment
		(start 314.735464 -253.468886)
		(end 318.072262 -305.581812)
		(width 0.14732)
		(layer "In15.Cu")
		(net "P5E_CPU0_PE0_TX_DP<15>")
	)
	(segment
		(start 338.499196 -200.538842)
		(end 336.873088 -200.53427)
		(width 0.14732)
		(layer "In15.Cu")
		(net "P5E_CPU0_PE0_TX_DP<15>")
	)
	(segment
		(start 350.087184 -213.186772)
		(end 350.04502 -213.144608)
		(width 0.0889)
		(layer "In15.Cu")
		(net "P5E_CPU0_PE0_TX_DP<15>")
	)
	(segment
		(start 301.563532 -325.775574)
		(end 301.563532 -329.113642)
		(width 0.14732)
		(layer "In15.Cu")
		(net "P5E_CPU0_PE0_TX_DP<15>")
	)
	(segment
		(start 307.831236 -363.74832)
		(end 307.861716 -363.938312)
		(width 0.14732)
		(layer "In15.Cu")
		(net "P5E_CPU0_PE0_TX_DP<15>")
	)
	(segment
		(start 307.075332 -382.343152)
		(end 306.944776 -382.461516)
		(width 0.14732)
		(layer "In15.Cu")
		(net "P5E_CPU0_PE0_TX_DP<15>")
	)
	(segment
		(start 350.839278 -219.01658)
		(end 350.848168 -219.0115)
		(width 0.0889)
		(layer "In15.Cu")
		(net "P5E_CPU0_PE0_TX_DP<15>")
	)
	(segment
		(start 334.436212 -201.144886)
		(end 333.665068 -201.777092)
		(width 0.14732)
		(layer "In15.Cu")
		(net "P5E_CPU0_PE0_TX_DP<15>")
	)
	(segment
		(start 342.397588 -202.15352)
		(end 338.499196 -200.538842)
		(width 0.14732)
		(layer "In15.Cu")
		(net "P5E_CPU0_PE0_TX_DP<15>")
	)
	(segment
		(start 315.483494 -314.809124)
		(end 314.66917 -315.62421)
		(width 0.14732)
		(layer "In15.Cu")
		(net "P5E_CPU0_PE0_TX_DP<15>")
	)
	(segment
		(start 306.777644 -385.825492)
		(end 306.778152 -385.825746)
		(width 0.14732)
		(layer "In15.Cu")
		(net "P5E_CPU0_PE0_TX_DP<15>")
	)
	(segment
		(start 351.787968 -223.256348)
		(end 351.780094 -223.251776)
		(width 0.0889)
		(layer "In15.Cu")
		(net "P5E_CPU0_PE0_TX_DP<15>")
	)
	(segment
		(start 352.375216 -224.93224)
		(end 352.286316 -224.908618)
		(width 0.0889)
		(layer "In15.Cu")
		(net "P5E_CPU0_PE0_TX_DP<15>")
	)
	(segment
		(start 306.080668 -399.910808)
		(end 306.080668 -403.961854)
		(width 0.14732)
		(layer "In15.Cu")
		(net "P5E_CPU0_PE0_TX_DP<15>")
	)
	(segment
		(start 350.556576 -214.622634)
		(end 350.556576 -214.472266)
		(width 0.0889)
		(layer "In15.Cu")
		(net "P5E_CPU0_PE0_TX_DP<15>")
	)
	(segment
		(start 306.956206 -320.3829)
		(end 301.563532 -325.775574)
		(width 0.14732)
		(layer "In15.Cu")
		(net "P5E_CPU0_PE0_TX_DP<15>")
	)
	(segment
		(start 351.780094 -223.899476)
		(end 351.787968 -223.894904)
		(width 0.0889)
		(layer "In15.Cu")
		(net "P5E_CPU0_PE0_TX_DP<15>")
	)
	(segment
		(start 330.368148 -204.836776)
		(end 320.967862 -214.696548)
		(width 0.14732)
		(layer "In15.Cu")
		(net "P5E_CPU0_PE0_TX_DP<15>")
	)
	(segment
		(start 306.81168 -385.1402)
		(end 306.930044 -385.270756)
		(width 0.14732)
		(layer "In15.Cu")
		(net "P5E_CPU0_PE0_TX_DP<15>")
	)
	(arc
		(start 350.839532 -220.644212)
		(mid 351.026835 -220.319854)
		(end 350.839532 -219.995496)
		(width 0.0889)
		(layer "In15.Cu")
		(net "P5E_CPU0_PE0_TX_DP<15>")
	)
	(arc
		(start 350.839532 -217.388694)
		(mid 351.026835 -217.064336)
		(end 350.839532 -216.739978)
		(width 0.0889)
		(layer "In15.Cu")
		(net "P5E_CPU0_PE0_TX_DP<15>")
	)
	(arc
		(start 350.550988 -214.448136)
		(mid 350.477051 -214.340508)
		(end 350.372934 -214.2617)
		(width 0.0889)
		(layer "In15.Cu")
		(net "P5E_CPU0_PE0_TX_DP<15>")
	)
	(arc
		(start 350.10471 -213.914228)
		(mid 350.091563 -213.868185)
		(end 350.087184 -213.820502)
		(width 0.0889)
		(layer "In15.Cu")
		(net "P5E_CPU0_PE0_TX_DP<15>")
	)
	(arc
		(start 350.839278 -221.623382)
		(mid 350.636455 -221.423151)
		(end 350.557084 -221.149418)
		(width 0.0889)
		(layer "In15.Cu")
		(net "P5E_CPU0_PE0_TX_DP<15>")
	)
	(arc
		(start 351.303336 -222.433642)
		(mid 351.100749 -222.227291)
		(end 351.02673 -221.94774)
		(width 0.0889)
		(layer "In15.Cu")
		(net "P5E_CPU0_PE0_TX_DP<15>")
	)
	(arc
		(start 351.496884 -222.761556)
		(mid 351.449205 -222.578656)
		(end 351.318322 -222.442278)
		(width 0.0889)
		(layer "In15.Cu")
		(net "P5E_CPU0_PE0_TX_DP<15>")
	)
	(arc
		(start 350.839532 -219.995496)
		(mid 350.557 -219.506148)
		(end 350.839278 -219.01658)
		(width 0.0889)
		(layer "In15.Cu")
		(net "P5E_CPU0_PE0_TX_DP<15>")
	)
	(arc
		(start 350.557084 -221.115382)
		(mid 350.637246 -220.843193)
		(end 350.839532 -220.644212)
		(width 0.0889)
		(layer "In15.Cu")
		(net "P5E_CPU0_PE0_TX_DP<15>")
	)
	(arc
		(start 352.266758 -224.916746)
		(mid 352.018606 -224.953361)
		(end 351.779078 -224.8789)
		(width 0.0889)
		(layer "In15.Cu")
		(net "P5E_CPU0_PE0_TX_DP<15>")
	)
	(arc
		(start 351.779078 -223.251268)
		(mid 351.577796 -223.053781)
		(end 351.496884 -222.783654)
		(width 0.0889)
		(layer "In15.Cu")
		(net "P5E_CPU0_PE0_TX_DP<15>")
	)
	(arc
		(start 350.372934 -214.2617)
		(mid 350.231361 -214.150933)
		(end 350.137222 -213.997794)
		(width 0.0889)
		(layer "In15.Cu")
		(net "P5E_CPU0_PE0_TX_DP<15>")
	)
	(arc
		(start 351.496884 -224.373948)
		(mid 351.576254 -224.100214)
		(end 351.779078 -223.899984)
		(width 0.0889)
		(layer "In15.Cu")
		(net "P5E_CPU0_PE0_TX_DP<15>")
	)
	(arc
		(start 352.286316 -224.908618)
		(mid 352.276576 -224.912775)
		(end 352.266758 -224.916746)
		(width 0.0889)
		(layer "In15.Cu")
		(net "P5E_CPU0_PE0_TX_DP<15>")
	)
	(arc
		(start 351.787968 -223.894904)
		(mid 351.966565 -223.575626)
		(end 351.787968 -223.256348)
		(width 0.0889)
		(layer "In15.Cu")
		(net "P5E_CPU0_PE0_TX_DP<15>")
	)
	(arc
		(start 351.02673 -221.94774)
		(mid 350.979051 -221.76484)
		(end 350.848168 -221.628462)
		(width 0.0889)
		(layer "In15.Cu")
		(net "P5E_CPU0_PE0_TX_DP<15>")
	)
	(arc
		(start 350.839278 -218.367864)
		(mid 350.636455 -218.167633)
		(end 350.557084 -217.8939)
		(width 0.0889)
		(layer "In15.Cu")
		(net "P5E_CPU0_PE0_TX_DP<15>")
	)
	(arc
		(start 350.378014 -214.941912)
		(mid 350.508928 -214.805552)
		(end 350.556576 -214.622634)
		(width 0.0889)
		(layer "In15.Cu")
		(net "P5E_CPU0_PE0_TX_DP<15>")
	)
	(arc
		(start 350.556576 -214.472266)
		(mid 350.555096 -214.459899)
		(end 350.550988 -214.448136)
		(width 0.0889)
		(layer "In15.Cu")
		(net "P5E_CPU0_PE0_TX_DP<15>")
	)
	(arc
		(start 351.779078 -224.8789)
		(mid 351.576255 -224.678669)
		(end 351.496884 -224.404936)
		(width 0.0889)
		(layer "In15.Cu")
		(net "P5E_CPU0_PE0_TX_DP<15>")
	)
	(arc
		(start 350.557084 -216.25052)
		(mid 350.509405 -216.06762)
		(end 350.378522 -215.931242)
		(width 0.0889)
		(layer "In15.Cu")
		(net "P5E_CPU0_PE0_TX_DP<15>")
	)
	(arc
		(start 350.848168 -219.0115)
		(mid 351.026644 -218.692222)
		(end 350.848168 -218.372944)
		(width 0.0889)
		(layer "In15.Cu")
		(net "P5E_CPU0_PE0_TX_DP<15>")
	)
	(arc
		(start 350.363536 -215.922606)
		(mid 350.086628 -215.433205)
		(end 350.369124 -214.946992)
		(width 0.0889)
		(layer "In15.Cu")
		(net "P5E_CPU0_PE0_TX_DP<15>")
	)
	(arc
		(start 350.839532 -216.739978)
		(mid 350.635197 -216.537373)
		(end 350.557084 -216.260426)
		(width 0.0889)
		(layer "In15.Cu")
		(net "P5E_CPU0_PE0_TX_DP<15>")
	)
	(arc
		(start 350.557084 -217.859864)
		(mid 350.637246 -217.587675)
		(end 350.839532 -217.388694)
		(width 0.0889)
		(layer "In15.Cu")
		(net "P5E_CPU0_PE0_TX_DP<15>")
	)
	(segment
		(start 351.12198 -224.925382)
		(end 351.12198 -224.389696)
		(width 0.13208)
		(layer "F.Cu")
		(net "P5E_CPU0_PE0_TX_DP<14>")
	)
	(segment
		(start 309.253128 -407.00452)
		(end 308.95417 -407.303478)
		(width 0.13208)
		(layer "F.Cu")
		(net "P5E_CPU0_PE0_TX_DP<14>")
	)
	(segment
		(start 351.12198 -224.389696)
		(end 351.122234 -224.389442)
		(width 0.13208)
		(layer "F.Cu")
		(net "P5E_CPU0_PE0_TX_DP<14>")
	)
	(segment
		(start 308.95417 -407.926286)
		(end 309.278528 -408.250644)
		(width 0.13208)
		(layer "F.Cu")
		(net "P5E_CPU0_PE0_TX_DP<14>")
	)
	(segment
		(start 308.95417 -407.303478)
		(end 308.95417 -407.926286)
		(width 0.13208)
		(layer "F.Cu")
		(net "P5E_CPU0_PE0_TX_DP<14>")
	)
	(segment
		(start 349.908368 -220.000576)
		(end 349.900494 -219.996004)
		(width 0.0889)
		(layer "In15.Cu")
		(net "P5E_CPU0_PE0_TX_DP<14>")
	)
	(segment
		(start 315.89091 -249.96902)
		(end 315.752226 -254.373126)
		(width 0.14732)
		(layer "In15.Cu")
		(net "P5E_CPU0_PE0_TX_DP<14>")
	)
	(segment
		(start 349.908368 -221.628462)
		(end 349.899478 -221.623382)
		(width 0.0889)
		(layer "In15.Cu")
		(net "P5E_CPU0_PE0_TX_DP<14>")
	)
	(segment
		(start 309.143908 -403.961854)
		(end 308.958488 -405.845264)
		(width 0.14732)
		(layer "In15.Cu")
		(net "P5E_CPU0_PE0_TX_DP<14>")
	)
	(segment
		(start 309.064152 -380.626366)
		(end 309.06339 -380.626874)
		(width 0.14732)
		(layer "In15.Cu")
		(net "P5E_CPU0_PE0_TX_DP<14>")
	)
	(segment
		(start 344.173302 -205.244192)
		(end 344.000836 -205.244192)
		(width 0.14732)
		(layer "In15.Cu")
		(net "P5E_CPU0_PE0_TX_DP<14>")
	)
	(segment
		(start 344.791284 -206.03464)
		(end 344.482166 -205.725522)
		(width 0.14732)
		(layer "In15.Cu")
		(net "P5E_CPU0_PE0_TX_DP<14>")
	)
	(segment
		(start 315.752226 -254.373126)
		(end 319.20942 -308.13248)
		(width 0.14732)
		(layer "In15.Cu")
		(net "P5E_CPU0_PE0_TX_DP<14>")
	)
	(segment
		(start 338.30006 -201.49566)
		(end 336.87258 -201.492866)
		(width 0.14732)
		(layer "In15.Cu")
		(net "P5E_CPU0_PE0_TX_DP<14>")
	)
	(segment
		(start 349.10522 -213.12251)
		(end 349.10522 -211.591906)
		(width 0.14732)
		(layer "In15.Cu")
		(net "P5E_CPU0_PE0_TX_DP<14>")
	)
	(segment
		(start 321.753738 -215.313006)
		(end 319.00368 -220.613732)
		(width 0.14732)
		(layer "In15.Cu")
		(net "P5E_CPU0_PE0_TX_DP<14>")
	)
	(segment
		(start 309.200042 -383.433066)
		(end 309.07609 -383.558288)
		(width 0.14732)
		(layer "In15.Cu")
		(net "P5E_CPU0_PE0_TX_DP<14>")
	)
	(segment
		(start 309.068724 -381.7493)
		(end 309.068216 -381.749554)
		(width 0.14732)
		(layer "In15.Cu")
		(net "P5E_CPU0_PE0_TX_DP<14>")
	)
	(segment
		(start 305.414426 -327.878948)
		(end 303.957482 -329.335892)
		(width 0.14732)
		(layer "In15.Cu")
		(net "P5E_CPU0_PE0_TX_DP<14>")
	)
	(segment
		(start 309.19039 -381.18796)
		(end 309.066438 -381.312928)
		(width 0.14732)
		(layer "In15.Cu")
		(net "P5E_CPU0_PE0_TX_DP<14>")
	)
	(segment
		(start 308.997858 -364.611158)
		(end 309.064152 -380.626366)
		(width 0.14732)
		(layer "In15.Cu")
		(net "P5E_CPU0_PE0_TX_DP<14>")
	)
	(segment
		(start 348.103698 -209.174588)
		(end 344.96375 -206.03464)
		(width 0.14732)
		(layer "In15.Cu")
		(net "P5E_CPU0_PE0_TX_DP<14>")
	)
	(segment
		(start 309.066946 -381.324612)
		(end 309.068724 -381.7493)
		(width 0.14732)
		(layer "In15.Cu")
		(net "P5E_CPU0_PE0_TX_DP<14>")
	)
	(segment
		(start 309.06339 -380.626874)
		(end 309.188612 -380.750826)
		(width 0.14732)
		(layer "In15.Cu")
		(net "P5E_CPU0_PE0_TX_DP<14>")
	)
	(segment
		(start 349.10522 -211.591906)
		(end 348.103698 -209.174588)
		(width 0.14732)
		(layer "In15.Cu")
		(net "P5E_CPU0_PE0_TX_DP<14>")
	)
	(segment
		(start 319.00368 -220.613732)
		(end 317.195962 -232.309924)
		(width 0.14732)
		(layer "In15.Cu")
		(net "P5E_CPU0_PE0_TX_DP<14>")
	)
	(segment
		(start 317.565024 -312.29046)
		(end 316.187836 -315.750702)
		(width 0.14732)
		(layer "In15.Cu")
		(net "P5E_CPU0_PE0_TX_DP<14>")
	)
	(segment
		(start 349.617284 -221.149418)
		(end 349.617284 -221.111826)
		(width 0.0889)
		(layer "In15.Cu")
		(net "P5E_CPU0_PE0_TX_DP<14>")
	)
	(segment
		(start 317.195962 -232.309924)
		(end 315.89091 -249.96902)
		(width 0.14732)
		(layer "In15.Cu")
		(net "P5E_CPU0_PE0_TX_DP<14>")
	)
	(segment
		(start 317.586614 -312.236104)
		(end 317.566294 -312.287158)
		(width 0.14732)
		(layer "In15.Cu")
		(net "P5E_CPU0_PE0_TX_DP<14>")
	)
	(segment
		(start 349.617284 -217.8939)
		(end 349.617284 -217.856308)
		(width 0.0889)
		(layer "In15.Cu")
		(net "P5E_CPU0_PE0_TX_DP<14>")
	)
	(segment
		(start 334.259174 -202.49896)
		(end 331.15504 -205.392528)
		(width 0.14732)
		(layer "In15.Cu")
		(net "P5E_CPU0_PE0_TX_DP<14>")
	)
	(segment
		(start 349.147384 -213.186772)
		(end 349.10522 -213.144608)
		(width 0.0889)
		(layer "In15.Cu")
		(net "P5E_CPU0_PE0_TX_DP<14>")
	)
	(segment
		(start 351.278698 -224.118424)
		(end 351.254568 -224.02927)
		(width 0.0889)
		(layer "In15.Cu")
		(net "P5E_CPU0_PE0_TX_DP<14>")
	)
	(segment
		(start 343.691718 -204.762608)
		(end 341.92718 -202.99807)
		(width 0.14732)
		(layer "In15.Cu")
		(net "P5E_CPU0_PE0_TX_DP<14>")
	)
	(segment
		(start 351.02673 -223.575626)
		(end 351.02673 -223.56699)
		(width 0.0889)
		(layer "In15.Cu")
		(net "P5E_CPU0_PE0_TX_DP<14>")
	)
	(segment
		(start 349.900494 -218.368372)
		(end 349.899478 -218.367864)
		(width 0.0889)
		(layer "In15.Cu")
		(net "P5E_CPU0_PE0_TX_DP<14>")
	)
	(segment
		(start 309.080916 -384.680968)
		(end 309.082694 -385.117594)
		(width 0.14732)
		(layer "In15.Cu")
		(net "P5E_CPU0_PE0_TX_DP<14>")
	)
	(segment
		(start 305.414426 -325.155052)
		(end 305.414426 -327.878948)
		(width 0.14732)
		(layer "In15.Cu")
		(net "P5E_CPU0_PE0_TX_DP<14>")
	)
	(segment
		(start 309.391812 -321.177666)
		(end 305.414426 -325.155052)
		(width 0.14732)
		(layer "In15.Cu")
		(net "P5E_CPU0_PE0_TX_DP<14>")
	)
	(segment
		(start 308.958488 -406.70988)
		(end 309.253128 -407.00452)
		(width 0.14732)
		(layer "In15.Cu")
		(net "P5E_CPU0_PE0_TX_DP<14>")
	)
	(segment
		(start 317.565786 -312.288682)
		(end 317.565532 -312.288936)
		(width 0.14732)
		(layer "In15.Cu")
		(net "P5E_CPU0_PE0_TX_DP<14>")
	)
	(segment
		(start 309.082694 -385.117594)
		(end 309.207916 -385.241546)
		(width 0.14732)
		(layer "In15.Cu")
		(net "P5E_CPU0_PE0_TX_DP<14>")
	)
	(segment
		(start 349.900494 -216.740486)
		(end 349.899478 -216.739978)
		(width 0.0889)
		(layer "In15.Cu")
		(net "P5E_CPU0_PE0_TX_DP<14>")
	)
	(segment
		(start 309.085742 -385.803648)
		(end 309.143908 -399.910046)
		(width 0.14732)
		(layer "In15.Cu")
		(net "P5E_CPU0_PE0_TX_DP<14>")
	)
	(segment
		(start 309.068216 -381.749554)
		(end 309.193438 -381.873506)
		(width 0.14732)
		(layer "In15.Cu")
		(net "P5E_CPU0_PE0_TX_DP<14>")
	)
	(segment
		(start 335.67878 -201.492866)
		(end 334.823816 -202.034394)
		(width 0.14732)
		(layer "In15.Cu")
		(net "P5E_CPU0_PE0_TX_DP<14>")
	)
	(segment
		(start 344.482166 -205.553056)
		(end 344.173302 -205.244192)
		(width 0.14732)
		(layer "In15.Cu")
		(net "P5E_CPU0_PE0_TX_DP<14>")
	)
	(segment
		(start 308.958488 -405.845264)
		(end 308.958488 -406.70988)
		(width 0.14732)
		(layer "In15.Cu")
		(net "P5E_CPU0_PE0_TX_DP<14>")
	)
	(segment
		(start 344.000836 -205.244192)
		(end 343.691718 -204.935074)
		(width 0.14732)
		(layer "In15.Cu")
		(net "P5E_CPU0_PE0_TX_DP<14>")
	)
	(segment
		(start 309.195216 -382.31064)
		(end 309.071264 -382.435608)
		(width 0.14732)
		(layer "In15.Cu")
		(net "P5E_CPU0_PE0_TX_DP<14>")
	)
	(segment
		(start 349.616776 -214.622634)
		(end 349.616776 -214.504016)
		(width 0.0889)
		(layer "In15.Cu")
		(net "P5E_CPU0_PE0_TX_DP<14>")
	)
	(segment
		(start 319.20942 -308.13248)
		(end 317.5889 -312.229246)
		(width 0.14732)
		(layer "In15.Cu")
		(net "P5E_CPU0_PE0_TX_DP<14>")
	)
	(segment
		(start 309.198264 -382.996186)
		(end 309.200042 -383.433066)
		(width 0.14732)
		(layer "In15.Cu")
		(net "P5E_CPU0_PE0_TX_DP<14>")
	)
	(segment
		(start 349.438722 -215.931242)
		(end 349.423736 -215.922606)
		(width 0.0889)
		(layer "In15.Cu")
		(net "P5E_CPU0_PE0_TX_DP<14>")
	)
	(segment
		(start 336.87258 -201.492866)
		(end 335.67878 -201.492866)
		(width 0.14732)
		(layer "In15.Cu")
		(net "P5E_CPU0_PE0_TX_DP<14>")
	)
	(segment
		(start 349.899478 -219.01658)
		(end 349.908368 -219.0115)
		(width 0.0889)
		(layer "In15.Cu")
		(net "P5E_CPU0_PE0_TX_DP<14>")
	)
	(segment
		(start 312.41238 -320.72961)
		(end 310.47309 -320.72961)
		(width 0.14732)
		(layer "In15.Cu")
		(net "P5E_CPU0_PE0_TX_DP<14>")
	)
	(segment
		(start 309.204868 -384.555746)
		(end 309.080916 -384.680968)
		(width 0.14732)
		(layer "In15.Cu")
		(net "P5E_CPU0_PE0_TX_DP<14>")
	)
	(segment
		(start 351.122234 -224.389442)
		(end 351.278698 -224.118424)
		(width 0.0889)
		(layer "In15.Cu")
		(net "P5E_CPU0_PE0_TX_DP<14>")
	)
	(segment
		(start 309.188612 -380.750826)
		(end 309.19039 -381.18796)
		(width 0.14732)
		(layer "In15.Cu")
		(net "P5E_CPU0_PE0_TX_DP<14>")
	)
	(segment
		(start 350.557084 -222.780098)
		(end 350.557084 -222.761556)
		(width 0.0889)
		(layer "In15.Cu")
		(net "P5E_CPU0_PE0_TX_DP<14>")
	)
	(segment
		(start 309.07609 -383.558288)
		(end 309.077868 -383.994914)
		(width 0.14732)
		(layer "In15.Cu")
		(net "P5E_CPU0_PE0_TX_DP<14>")
	)
	(segment
		(start 303.957482 -341.933022)
		(end 308.997858 -364.611158)
		(width 0.14732)
		(layer "In15.Cu")
		(net "P5E_CPU0_PE0_TX_DP<14>")
	)
	(segment
		(start 350.378522 -222.442278)
		(end 350.36887 -222.43669)
		(width 0.0889)
		(layer "In15.Cu")
		(net "P5E_CPU0_PE0_TX_DP<14>")
	)
	(segment
		(start 309.066946 -381.313436)
		(end 309.066946 -381.324612)
		(width 0.14732)
		(layer "In15.Cu")
		(net "P5E_CPU0_PE0_TX_DP<14>")
	)
	(segment
		(start 349.900494 -219.996004)
		(end 349.899478 -219.995496)
		(width 0.0889)
		(layer "In15.Cu")
		(net "P5E_CPU0_PE0_TX_DP<14>")
	)
	(segment
		(start 309.209694 -385.67868)
		(end 309.085742 -385.803648)
		(width 0.14732)
		(layer "In15.Cu")
		(net "P5E_CPU0_PE0_TX_DP<14>")
	)
	(segment
		(start 317.5889 -312.229246)
		(end 317.586614 -312.236104)
		(width 0.14732)
		(layer "In15.Cu")
		(net "P5E_CPU0_PE0_TX_DP<14>")
	)
	(segment
		(start 349.147384 -213.788498)
		(end 349.147384 -213.186772)
		(width 0.0889)
		(layer "In15.Cu")
		(net "P5E_CPU0_PE0_TX_DP<14>")
	)
	(segment
		(start 344.482166 -205.725522)
		(end 344.482166 -205.553056)
		(width 0.14732)
		(layer "In15.Cu")
		(net "P5E_CPU0_PE0_TX_DP<14>")
	)
	(segment
		(start 349.617284 -216.266014)
		(end 349.617284 -216.25052)
		(width 0.0889)
		(layer "In15.Cu")
		(net "P5E_CPU0_PE0_TX_DP<14>")
	)
	(segment
		(start 344.96375 -206.03464)
		(end 344.791284 -206.03464)
		(width 0.14732)
		(layer "In15.Cu")
		(net "P5E_CPU0_PE0_TX_DP<14>")
	)
	(segment
		(start 309.077868 -383.994914)
		(end 309.20309 -384.118866)
		(width 0.14732)
		(layer "In15.Cu")
		(net "P5E_CPU0_PE0_TX_DP<14>")
	)
	(segment
		(start 349.429324 -214.946992)
		(end 349.438214 -214.941912)
		(width 0.0889)
		(layer "In15.Cu")
		(net "P5E_CPU0_PE0_TX_DP<14>")
	)
	(segment
		(start 349.10522 -213.144608)
		(end 349.10522 -213.12251)
		(width 0.0889)
		(layer "In15.Cu")
		(net "P5E_CPU0_PE0_TX_DP<14>")
	)
	(segment
		(start 309.071264 -382.435608)
		(end 309.073042 -382.872234)
		(width 0.14732)
		(layer "In15.Cu")
		(net "P5E_CPU0_PE0_TX_DP<14>")
	)
	(segment
		(start 349.908368 -216.745058)
		(end 349.900494 -216.740486)
		(width 0.0889)
		(layer "In15.Cu")
		(net "P5E_CPU0_PE0_TX_DP<14>")
	)
	(segment
		(start 303.957482 -329.335892)
		(end 303.957482 -341.933022)
		(width 0.14732)
		(layer "In15.Cu")
		(net "P5E_CPU0_PE0_TX_DP<14>")
	)
	(segment
		(start 313.376564 -319.765426)
		(end 312.41238 -320.72961)
		(width 0.14732)
		(layer "In15.Cu")
		(net "P5E_CPU0_PE0_TX_DP<14>")
	)
	(segment
		(start 341.92718 -202.99807)
		(end 338.30006 -201.49566)
		(width 0.14732)
		(layer "In15.Cu")
		(net "P5E_CPU0_PE0_TX_DP<14>")
	)
	(segment
		(start 350.36887 -222.43669)
		(end 350.363536 -222.433642)
		(width 0.0889)
		(layer "In15.Cu")
		(net "P5E_CPU0_PE0_TX_DP<14>")
	)
	(segment
		(start 343.691718 -204.935074)
		(end 343.691718 -204.762608)
		(width 0.14732)
		(layer "In15.Cu")
		(net "P5E_CPU0_PE0_TX_DP<14>")
	)
	(segment
		(start 331.15504 -205.392528)
		(end 321.753738 -215.313006)
		(width 0.14732)
		(layer "In15.Cu")
		(net "P5E_CPU0_PE0_TX_DP<14>")
	)
	(segment
		(start 309.143908 -399.910046)
		(end 309.143908 -403.961854)
		(width 0.14732)
		(layer "In15.Cu")
		(net "P5E_CPU0_PE0_TX_DP<14>")
	)
	(segment
		(start 309.193438 -381.873506)
		(end 309.195216 -382.31064)
		(width 0.14732)
		(layer "In15.Cu")
		(net "P5E_CPU0_PE0_TX_DP<14>")
	)
	(segment
		(start 317.566294 -312.287158)
		(end 317.565786 -312.288682)
		(width 0.14732)
		(layer "In15.Cu")
		(net "P5E_CPU0_PE0_TX_DP<14>")
	)
	(segment
		(start 316.187836 -315.750702)
		(end 313.376564 -319.765426)
		(width 0.14732)
		(layer "In15.Cu")
		(net "P5E_CPU0_PE0_TX_DP<14>")
	)
	(segment
		(start 334.823816 -202.034394)
		(end 334.259174 -202.49896)
		(width 0.14732)
		(layer "In15.Cu")
		(net "P5E_CPU0_PE0_TX_DP<14>")
	)
	(segment
		(start 309.207916 -385.241546)
		(end 309.209694 -385.67868)
		(width 0.14732)
		(layer "In15.Cu")
		(net "P5E_CPU0_PE0_TX_DP<14>")
	)
	(segment
		(start 349.899478 -220.644212)
		(end 349.908368 -220.639132)
		(width 0.0889)
		(layer "In15.Cu")
		(net "P5E_CPU0_PE0_TX_DP<14>")
	)
	(segment
		(start 309.066438 -381.312928)
		(end 309.066946 -381.313436)
		(width 0.14732)
		(layer "In15.Cu")
		(net "P5E_CPU0_PE0_TX_DP<14>")
	)
	(segment
		(start 309.20309 -384.118866)
		(end 309.204868 -384.555746)
		(width 0.14732)
		(layer "In15.Cu")
		(net "P5E_CPU0_PE0_TX_DP<14>")
	)
	(segment
		(start 349.908368 -218.372944)
		(end 349.900494 -218.368372)
		(width 0.0889)
		(layer "In15.Cu")
		(net "P5E_CPU0_PE0_TX_DP<14>")
	)
	(segment
		(start 317.565532 -312.288936)
		(end 317.565024 -312.29046)
		(width 0.14732)
		(layer "In15.Cu")
		(net "P5E_CPU0_PE0_TX_DP<14>")
	)
	(segment
		(start 310.47309 -320.72961)
		(end 309.391812 -321.177666)
		(width 0.14732)
		(layer "In15.Cu")
		(net "P5E_CPU0_PE0_TX_DP<14>")
	)
	(segment
		(start 309.073042 -382.872234)
		(end 309.198264 -382.996186)
		(width 0.14732)
		(layer "In15.Cu")
		(net "P5E_CPU0_PE0_TX_DP<14>")
	)
	(segment
		(start 349.899478 -217.388694)
		(end 349.908368 -217.383614)
		(width 0.0889)
		(layer "In15.Cu")
		(net "P5E_CPU0_PE0_TX_DP<14>")
	)
	(segment
		(start 349.617284 -219.521532)
		(end 349.617284 -219.490544)
		(width 0.0889)
		(layer "In15.Cu")
		(net "P5E_CPU0_PE0_TX_DP<14>")
	)
	(arc
		(start 349.617284 -219.490544)
		(mid 349.696654 -219.21681)
		(end 349.899478 -219.01658)
		(width 0.0889)
		(layer "In15.Cu")
		(net "P5E_CPU0_PE0_TX_DP<14>")
	)
	(arc
		(start 349.435928 -214.26932)
		(mid 349.419154 -214.256182)
		(end 349.401384 -214.244428)
		(width 0.0889)
		(layer "In15.Cu")
		(net "P5E_CPU0_PE0_TX_DP<14>")
	)
	(arc
		(start 350.839532 -223.251268)
		(mid 350.637246 -223.052287)
		(end 350.557084 -222.780098)
		(width 0.0889)
		(layer "In15.Cu")
		(net "P5E_CPU0_PE0_TX_DP<14>")
	)
	(arc
		(start 350.557084 -222.761556)
		(mid 350.509405 -222.578656)
		(end 350.378522 -222.442278)
		(width 0.0889)
		(layer "In15.Cu")
		(net "P5E_CPU0_PE0_TX_DP<14>")
	)
	(arc
		(start 349.899478 -221.623382)
		(mid 349.696655 -221.423151)
		(end 349.617284 -221.149418)
		(width 0.0889)
		(layer "In15.Cu")
		(net "P5E_CPU0_PE0_TX_DP<14>")
	)
	(arc
		(start 349.908368 -219.0115)
		(mid 350.086844 -218.692222)
		(end 349.908368 -218.372944)
		(width 0.0889)
		(layer "In15.Cu")
		(net "P5E_CPU0_PE0_TX_DP<14>")
	)
	(arc
		(start 349.438214 -214.941912)
		(mid 349.569128 -214.805552)
		(end 349.616776 -214.622634)
		(width 0.0889)
		(layer "In15.Cu")
		(net "P5E_CPU0_PE0_TX_DP<14>")
	)
	(arc
		(start 349.908368 -220.639132)
		(mid 350.087086 -220.319854)
		(end 349.908368 -220.000576)
		(width 0.0889)
		(layer "In15.Cu")
		(net "P5E_CPU0_PE0_TX_DP<14>")
	)
	(arc
		(start 350.08693 -221.94774)
		(mid 350.039251 -221.76484)
		(end 349.908368 -221.628462)
		(width 0.0889)
		(layer "In15.Cu")
		(net "P5E_CPU0_PE0_TX_DP<14>")
	)
	(arc
		(start 349.423736 -215.922606)
		(mid 349.146828 -215.433205)
		(end 349.429324 -214.946992)
		(width 0.0889)
		(layer "In15.Cu")
		(net "P5E_CPU0_PE0_TX_DP<14>")
	)
	(arc
		(start 349.617284 -217.856308)
		(mid 349.698195 -217.58618)
		(end 349.899478 -217.388694)
		(width 0.0889)
		(layer "In15.Cu")
		(net "P5E_CPU0_PE0_TX_DP<14>")
	)
	(arc
		(start 349.617284 -221.111826)
		(mid 349.698195 -220.841698)
		(end 349.899478 -220.644212)
		(width 0.0889)
		(layer "In15.Cu")
		(net "P5E_CPU0_PE0_TX_DP<14>")
	)
	(arc
		(start 349.602298 -214.45601)
		(mid 349.525268 -214.35718)
		(end 349.435928 -214.26932)
		(width 0.0889)
		(layer "In15.Cu")
		(net "P5E_CPU0_PE0_TX_DP<14>")
	)
	(arc
		(start 349.617284 -216.25052)
		(mid 349.569605 -216.06762)
		(end 349.438722 -215.931242)
		(width 0.0889)
		(layer "In15.Cu")
		(net "P5E_CPU0_PE0_TX_DP<14>")
	)
	(arc
		(start 349.908368 -217.383614)
		(mid 350.087086 -217.064336)
		(end 349.908368 -216.745058)
		(width 0.0889)
		(layer "In15.Cu")
		(net "P5E_CPU0_PE0_TX_DP<14>")
	)
	(arc
		(start 349.899478 -218.367864)
		(mid 349.696655 -218.167633)
		(end 349.617284 -217.8939)
		(width 0.0889)
		(layer "In15.Cu")
		(net "P5E_CPU0_PE0_TX_DP<14>")
	)
	(arc
		(start 351.02673 -223.56699)
		(mid 350.97446 -223.384625)
		(end 350.839532 -223.251268)
		(width 0.0889)
		(layer "In15.Cu")
		(net "P5E_CPU0_PE0_TX_DP<14>")
	)
	(arc
		(start 349.899478 -216.739978)
		(mid 349.696655 -216.539747)
		(end 349.617284 -216.266014)
		(width 0.0889)
		(layer "In15.Cu")
		(net "P5E_CPU0_PE0_TX_DP<14>")
	)
	(arc
		(start 349.616776 -214.504016)
		(mid 349.6131 -214.478944)
		(end 349.602298 -214.45601)
		(width 0.0889)
		(layer "In15.Cu")
		(net "P5E_CPU0_PE0_TX_DP<14>")
	)
	(arc
		(start 350.363536 -222.433642)
		(mid 350.160949 -222.227291)
		(end 350.08693 -221.94774)
		(width 0.0889)
		(layer "In15.Cu")
		(net "P5E_CPU0_PE0_TX_DP<14>")
	)
	(arc
		(start 351.254568 -224.02927)
		(mid 351.086814 -223.829492)
		(end 351.02673 -223.575626)
		(width 0.0889)
		(layer "In15.Cu")
		(net "P5E_CPU0_PE0_TX_DP<14>")
	)
	(arc
		(start 349.899478 -219.995496)
		(mid 349.696655 -219.795265)
		(end 349.617284 -219.521532)
		(width 0.0889)
		(layer "In15.Cu")
		(net "P5E_CPU0_PE0_TX_DP<14>")
	)
	(arc
		(start 349.401384 -214.244428)
		(mid 349.215092 -214.049491)
		(end 349.147384 -213.788498)
		(width 0.0889)
		(layer "In15.Cu")
		(net "P5E_CPU0_PE0_TX_DP<14>")
	)
	(segment
		(start 350.652334 -225.739198)
		(end 350.652334 -225.203512)
		(width 0.13208)
		(layer "F.Cu")
		(net "P5E_CPU0_PE0_TX_DP<13>")
	)
	(segment
		(start 350.652334 -225.203512)
		(end 350.65208 -225.203258)
		(width 0.13208)
		(layer "F.Cu")
		(net "P5E_CPU0_PE0_TX_DP<13>")
	)
	(segment
		(start 312.01741 -407.926286)
		(end 312.341768 -408.250644)
		(width 0.13208)
		(layer "F.Cu")
		(net "P5E_CPU0_PE0_TX_DP<13>")
	)
	(segment
		(start 312.316368 -407.00452)
		(end 312.01741 -407.303478)
		(width 0.13208)
		(layer "F.Cu")
		(net "P5E_CPU0_PE0_TX_DP<13>")
	)
	(segment
		(start 312.01741 -407.303478)
		(end 312.01741 -407.926286)
		(width 0.13208)
		(layer "F.Cu")
		(net "P5E_CPU0_PE0_TX_DP<13>")
	)
	(segment
		(start 319.581784 -223.062292)
		(end 319.581784 -223.062546)
		(width 0.14732)
		(layer "In15.Cu")
		(net "P5E_CPU0_PE0_TX_DP<13>")
	)
	(segment
		(start 319.915032 -220.90634)
		(end 319.581784 -223.062292)
		(width 0.14732)
		(layer "In15.Cu")
		(net "P5E_CPU0_PE0_TX_DP<13>")
	)
	(segment
		(start 312.002932 -322.600828)
		(end 310.967374 -322.600828)
		(width 0.14732)
		(layer "In15.Cu")
		(net "P5E_CPU0_PE0_TX_DP<13>")
	)
	(segment
		(start 334.903064 -203.185014)
		(end 332.135734 -205.753208)
		(width 0.14732)
		(layer "In15.Cu")
		(net "P5E_CPU0_PE0_TX_DP<13>")
	)
	(segment
		(start 311.055766 -380.558548)
		(end 311.187592 -380.675388)
		(width 0.14732)
		(layer "In15.Cu")
		(net "P5E_CPU0_PE0_TX_DP<13>")
	)
	(segment
		(start 311.29732 -384.606546)
		(end 311.29732 -384.60807)
		(width 0.14732)
		(layer "In15.Cu")
		(net "P5E_CPU0_PE0_TX_DP<13>")
	)
	(segment
		(start 319.581784 -223.062546)
		(end 318.120014 -232.520744)
		(width 0.14732)
		(layer "In15.Cu")
		(net "P5E_CPU0_PE0_TX_DP<13>")
	)
	(segment
		(start 348.677484 -221.149418)
		(end 348.677484 -221.115382)
		(width 0.0889)
		(layer "In15.Cu")
		(net "P5E_CPU0_PE0_TX_DP<13>")
	)
	(segment
		(start 348.16542 -213.12251)
		(end 348.16542 -211.884768)
		(width 0.14732)
		(layer "In15.Cu")
		(net "P5E_CPU0_PE0_TX_DP<13>")
	)
	(segment
		(start 311.323228 -385.04241)
		(end 311.4548 -385.158996)
		(width 0.14732)
		(layer "In15.Cu")
		(net "P5E_CPU0_PE0_TX_DP<13>")
	)
	(segment
		(start 349.899478 -223.899984)
		(end 349.900494 -223.899476)
		(width 0.0889)
		(layer "In15.Cu")
		(net "P5E_CPU0_PE0_TX_DP<13>")
	)
	(segment
		(start 311.123076 -381.679196)
		(end 311.122568 -381.67945)
		(width 0.14732)
		(layer "In15.Cu")
		(net "P5E_CPU0_PE0_TX_DP<13>")
	)
	(segment
		(start 348.968568 -221.628462)
		(end 348.959678 -221.623382)
		(width 0.0889)
		(layer "In15.Cu")
		(net "P5E_CPU0_PE0_TX_DP<13>")
	)
	(segment
		(start 348.498922 -215.931242)
		(end 348.48927 -215.925654)
		(width 0.0889)
		(layer "In15.Cu")
		(net "P5E_CPU0_PE0_TX_DP<13>")
	)
	(segment
		(start 349.900494 -223.251776)
		(end 349.899478 -223.251268)
		(width 0.0889)
		(layer "In15.Cu")
		(net "P5E_CPU0_PE0_TX_DP<13>")
	)
	(segment
		(start 311.280302 -382.232662)
		(end 311.163462 -382.364488)
		(width 0.14732)
		(layer "In15.Cu")
		(net "P5E_CPU0_PE0_TX_DP<13>")
	)
	(segment
		(start 338.173314 -202.458066)
		(end 335.93913 -202.45197)
		(width 0.14732)
		(layer "In15.Cu")
		(net "P5E_CPU0_PE0_TX_DP<13>")
	)
	(segment
		(start 335.348834 -202.820778)
		(end 334.903064 -203.185014)
		(width 0.14732)
		(layer "In15.Cu")
		(net "P5E_CPU0_PE0_TX_DP<13>")
	)
	(segment
		(start 311.2135 -381.11176)
		(end 311.09666 -381.243586)
		(width 0.14732)
		(layer "In15.Cu")
		(net "P5E_CPU0_PE0_TX_DP<13>")
	)
	(segment
		(start 348.677484 -216.260426)
		(end 348.677484 -216.25052)
		(width 0.0889)
		(layer "In15.Cu")
		(net "P5E_CPU0_PE0_TX_DP<13>")
	)
	(segment
		(start 312.207148 -403.961854)
		(end 312.021728 -405.845264)
		(width 0.14732)
		(layer "In15.Cu")
		(net "P5E_CPU0_PE0_TX_DP<13>")
	)
	(segment
		(start 311.16397 -382.364742)
		(end 311.189878 -382.800098)
		(width 0.14732)
		(layer "In15.Cu")
		(net "P5E_CPU0_PE0_TX_DP<13>")
	)
	(segment
		(start 311.29732 -384.60807)
		(end 311.323228 -385.04241)
		(width 0.14732)
		(layer "In15.Cu")
		(net "P5E_CPU0_PE0_TX_DP<13>")
	)
	(segment
		(start 341.119968 -203.67879)
		(end 338.173314 -202.458066)
		(width 0.14732)
		(layer "In15.Cu")
		(net "P5E_CPU0_PE0_TX_DP<13>")
	)
	(segment
		(start 311.413906 -384.474466)
		(end 311.297066 -384.606292)
		(width 0.14732)
		(layer "In15.Cu")
		(net "P5E_CPU0_PE0_TX_DP<13>")
	)
	(segment
		(start 309.852314 -322.034408)
		(end 306.35194 -325.534782)
		(width 0.14732)
		(layer "In15.Cu")
		(net "P5E_CPU0_PE0_TX_DP<13>")
	)
	(segment
		(start 347.344746 -209.903568)
		(end 341.119968 -203.67879)
		(width 0.14732)
		(layer "In15.Cu")
		(net "P5E_CPU0_PE0_TX_DP<13>")
	)
	(segment
		(start 320.221102 -308.663086)
		(end 317.28918 -315.810138)
		(width 0.14732)
		(layer "In15.Cu")
		(net "P5E_CPU0_PE0_TX_DP<13>")
	)
	(segment
		(start 311.254394 -381.79629)
		(end 311.280302 -382.232662)
		(width 0.14732)
		(layer "In15.Cu")
		(net "P5E_CPU0_PE0_TX_DP<13>")
	)
	(segment
		(start 348.207584 -213.819232)
		(end 348.207584 -213.186772)
		(width 0.0889)
		(layer "In15.Cu")
		(net "P5E_CPU0_PE0_TX_DP<13>")
	)
	(segment
		(start 349.908368 -223.256348)
		(end 349.900494 -223.251776)
		(width 0.0889)
		(layer "In15.Cu")
		(net "P5E_CPU0_PE0_TX_DP<13>")
	)
	(segment
		(start 348.16542 -213.144608)
		(end 348.16542 -213.12251)
		(width 0.0889)
		(layer "In15.Cu")
		(net "P5E_CPU0_PE0_TX_DP<13>")
	)
	(segment
		(start 348.16542 -211.884768)
		(end 347.344746 -209.903568)
		(width 0.14732)
		(layer "In15.Cu")
		(net "P5E_CPU0_PE0_TX_DP<13>")
	)
	(segment
		(start 348.489524 -214.946992)
		(end 348.498414 -214.941912)
		(width 0.0889)
		(layer "In15.Cu")
		(net "P5E_CPU0_PE0_TX_DP<13>")
	)
	(segment
		(start 305.056286 -329.567032)
		(end 305.056286 -341.812118)
		(width 0.14732)
		(layer "In15.Cu")
		(net "P5E_CPU0_PE0_TX_DP<13>")
	)
	(segment
		(start 316.828424 -250.012962)
		(end 316.712092 -253.471426)
		(width 0.14732)
		(layer "In15.Cu")
		(net "P5E_CPU0_PE0_TX_DP<13>")
	)
	(segment
		(start 348.676976 -214.622634)
		(end 348.676976 -214.472266)
		(width 0.0889)
		(layer "In15.Cu")
		(net "P5E_CPU0_PE0_TX_DP<13>")
	)
	(segment
		(start 311.321196 -382.917192)
		(end 311.347104 -383.353564)
		(width 0.14732)
		(layer "In15.Cu")
		(net "P5E_CPU0_PE0_TX_DP<13>")
	)
	(segment
		(start 349.900494 -223.899476)
		(end 349.908368 -223.894904)
		(width 0.0889)
		(layer "In15.Cu")
		(net "P5E_CPU0_PE0_TX_DP<13>")
	)
	(segment
		(start 311.189878 -382.800098)
		(end 311.18937 -382.800352)
		(width 0.14732)
		(layer "In15.Cu")
		(net "P5E_CPU0_PE0_TX_DP<13>")
	)
	(segment
		(start 312.207148 -399.902426)
		(end 312.207148 -403.961854)
		(width 0.14732)
		(layer "In15.Cu")
		(net "P5E_CPU0_PE0_TX_DP<13>")
	)
	(segment
		(start 311.480708 -385.595368)
		(end 311.363868 -385.727194)
		(width 0.14732)
		(layer "In15.Cu")
		(net "P5E_CPU0_PE0_TX_DP<13>")
	)
	(segment
		(start 311.387998 -384.038094)
		(end 311.413906 -384.474466)
		(width 0.14732)
		(layer "In15.Cu")
		(net "P5E_CPU0_PE0_TX_DP<13>")
	)
	(segment
		(start 348.48927 -215.925654)
		(end 348.483936 -215.922606)
		(width 0.0889)
		(layer "In15.Cu")
		(net "P5E_CPU0_PE0_TX_DP<13>")
	)
	(segment
		(start 322.530724 -215.865202)
		(end 319.915032 -220.90634)
		(width 0.14732)
		(layer "In15.Cu")
		(net "P5E_CPU0_PE0_TX_DP<13>")
	)
	(segment
		(start 311.230264 -383.48539)
		(end 311.256172 -383.921254)
		(width 0.14732)
		(layer "In15.Cu")
		(net "P5E_CPU0_PE0_TX_DP<13>")
	)
	(segment
		(start 349.42907 -222.43669)
		(end 349.423736 -222.433642)
		(width 0.0889)
		(layer "In15.Cu")
		(net "P5E_CPU0_PE0_TX_DP<13>")
	)
	(segment
		(start 348.960694 -218.368372)
		(end 348.959678 -218.367864)
		(width 0.0889)
		(layer "In15.Cu")
		(net "P5E_CPU0_PE0_TX_DP<13>")
	)
	(segment
		(start 311.363868 -385.727194)
		(end 312.207148 -399.902426)
		(width 0.14732)
		(layer "In15.Cu")
		(net "P5E_CPU0_PE0_TX_DP<13>")
	)
	(segment
		(start 311.347104 -383.353564)
		(end 311.230264 -383.48539)
		(width 0.14732)
		(layer "In15.Cu")
		(net "P5E_CPU0_PE0_TX_DP<13>")
	)
	(segment
		(start 310.101488 -364.510066)
		(end 311.056274 -380.558294)
		(width 0.14732)
		(layer "In15.Cu")
		(net "P5E_CPU0_PE0_TX_DP<13>")
	)
	(segment
		(start 348.677484 -217.8939)
		(end 348.677484 -217.859864)
		(width 0.0889)
		(layer "In15.Cu")
		(net "P5E_CPU0_PE0_TX_DP<13>")
	)
	(segment
		(start 335.93913 -202.45197)
		(end 335.348834 -202.820778)
		(width 0.14732)
		(layer "In15.Cu")
		(net "P5E_CPU0_PE0_TX_DP<13>")
	)
	(segment
		(start 332.135734 -205.753208)
		(end 322.530724 -215.865202)
		(width 0.14732)
		(layer "In15.Cu")
		(net "P5E_CPU0_PE0_TX_DP<13>")
	)
	(segment
		(start 348.257114 -213.995762)
		(end 348.224856 -213.912704)
		(width 0.0889)
		(layer "In15.Cu")
		(net "P5E_CPU0_PE0_TX_DP<13>")
	)
	(segment
		(start 311.056274 -380.558294)
		(end 311.055766 -380.558548)
		(width 0.14732)
		(layer "In15.Cu")
		(net "P5E_CPU0_PE0_TX_DP<13>")
	)
	(segment
		(start 311.187592 -380.675388)
		(end 311.2135 -381.11176)
		(width 0.14732)
		(layer "In15.Cu")
		(net "P5E_CPU0_PE0_TX_DP<13>")
	)
	(segment
		(start 310.967374 -322.600828)
		(end 310.400954 -322.034408)
		(width 0.14732)
		(layer "In15.Cu")
		(net "P5E_CPU0_PE0_TX_DP<13>")
	)
	(segment
		(start 312.021728 -405.845264)
		(end 312.021728 -406.70988)
		(width 0.14732)
		(layer "In15.Cu")
		(net "P5E_CPU0_PE0_TX_DP<13>")
	)
	(segment
		(start 316.712092 -253.471426)
		(end 316.712092 -254.30226)
		(width 0.14732)
		(layer "In15.Cu")
		(net "P5E_CPU0_PE0_TX_DP<13>")
	)
	(segment
		(start 311.18937 -382.800352)
		(end 311.321196 -382.917192)
		(width 0.14732)
		(layer "In15.Cu")
		(net "P5E_CPU0_PE0_TX_DP<13>")
	)
	(segment
		(start 348.968568 -218.372944)
		(end 348.960694 -218.368372)
		(width 0.0889)
		(layer "In15.Cu")
		(net "P5E_CPU0_PE0_TX_DP<13>")
	)
	(segment
		(start 348.959678 -219.01658)
		(end 348.968568 -219.0115)
		(width 0.0889)
		(layer "In15.Cu")
		(net "P5E_CPU0_PE0_TX_DP<13>")
	)
	(segment
		(start 317.28918 -315.810138)
		(end 313.774328 -320.829432)
		(width 0.14732)
		(layer "In15.Cu")
		(net "P5E_CPU0_PE0_TX_DP<13>")
	)
	(segment
		(start 318.120014 -232.520744)
		(end 316.828424 -250.012962)
		(width 0.14732)
		(layer "In15.Cu")
		(net "P5E_CPU0_PE0_TX_DP<13>")
	)
	(segment
		(start 313.774328 -320.829432)
		(end 312.002932 -322.600828)
		(width 0.14732)
		(layer "In15.Cu")
		(net "P5E_CPU0_PE0_TX_DP<13>")
	)
	(segment
		(start 311.4548 -385.158996)
		(end 311.480708 -385.595368)
		(width 0.14732)
		(layer "In15.Cu")
		(net "P5E_CPU0_PE0_TX_DP<13>")
	)
	(segment
		(start 311.297066 -384.606292)
		(end 311.29732 -384.606546)
		(width 0.14732)
		(layer "In15.Cu")
		(net "P5E_CPU0_PE0_TX_DP<13>")
	)
	(segment
		(start 306.35194 -328.271378)
		(end 305.056286 -329.567032)
		(width 0.14732)
		(layer "In15.Cu")
		(net "P5E_CPU0_PE0_TX_DP<13>")
	)
	(segment
		(start 306.35194 -325.534782)
		(end 306.35194 -328.271378)
		(width 0.14732)
		(layer "In15.Cu")
		(net "P5E_CPU0_PE0_TX_DP<13>")
	)
	(segment
		(start 311.256172 -383.921254)
		(end 311.387998 -384.038094)
		(width 0.14732)
		(layer "In15.Cu")
		(net "P5E_CPU0_PE0_TX_DP<13>")
	)
	(segment
		(start 305.056286 -341.812118)
		(end 310.101488 -364.510066)
		(width 0.14732)
		(layer "In15.Cu")
		(net "P5E_CPU0_PE0_TX_DP<13>")
	)
	(segment
		(start 350.65208 -225.203258)
		(end 350.495616 -224.93224)
		(width 0.0889)
		(layer "In15.Cu")
		(net "P5E_CPU0_PE0_TX_DP<13>")
	)
	(segment
		(start 311.122568 -381.67945)
		(end 311.254394 -381.79629)
		(width 0.14732)
		(layer "In15.Cu")
		(net "P5E_CPU0_PE0_TX_DP<13>")
	)
	(segment
		(start 349.617284 -222.783654)
		(end 349.617284 -222.761556)
		(width 0.0889)
		(layer "In15.Cu")
		(net "P5E_CPU0_PE0_TX_DP<13>")
	)
	(segment
		(start 349.438722 -222.442278)
		(end 349.42907 -222.43669)
		(width 0.0889)
		(layer "In15.Cu")
		(net "P5E_CPU0_PE0_TX_DP<13>")
	)
	(segment
		(start 349.617284 -224.404936)
		(end 349.617284 -224.373948)
		(width 0.0889)
		(layer "In15.Cu")
		(net "P5E_CPU0_PE0_TX_DP<13>")
	)
	(segment
		(start 316.712092 -254.30226)
		(end 320.221102 -308.663086)
		(width 0.14732)
		(layer "In15.Cu")
		(net "P5E_CPU0_PE0_TX_DP<13>")
	)
	(segment
		(start 311.09666 -381.243586)
		(end 311.097168 -381.244094)
		(width 0.14732)
		(layer "In15.Cu")
		(net "P5E_CPU0_PE0_TX_DP<13>")
	)
	(segment
		(start 348.207584 -213.186772)
		(end 348.16542 -213.144608)
		(width 0.0889)
		(layer "In15.Cu")
		(net "P5E_CPU0_PE0_TX_DP<13>")
	)
	(segment
		(start 312.021728 -406.70988)
		(end 312.316368 -407.00452)
		(width 0.14732)
		(layer "In15.Cu")
		(net "P5E_CPU0_PE0_TX_DP<13>")
	)
	(segment
		(start 310.400954 -322.034408)
		(end 309.852314 -322.034408)
		(width 0.14732)
		(layer "In15.Cu")
		(net "P5E_CPU0_PE0_TX_DP<13>")
	)
	(segment
		(start 311.163462 -382.364488)
		(end 311.16397 -382.364742)
		(width 0.14732)
		(layer "In15.Cu")
		(net "P5E_CPU0_PE0_TX_DP<13>")
	)
	(segment
		(start 311.097168 -381.244094)
		(end 311.123076 -381.679196)
		(width 0.14732)
		(layer "In15.Cu")
		(net "P5E_CPU0_PE0_TX_DP<13>")
	)
	(segment
		(start 350.495616 -224.93224)
		(end 350.406716 -224.908618)
		(width 0.0889)
		(layer "In15.Cu")
		(net "P5E_CPU0_PE0_TX_DP<13>")
	)
	(arc
		(start 349.423736 -222.433642)
		(mid 349.221149 -222.227291)
		(end 349.14713 -221.94774)
		(width 0.0889)
		(layer "In15.Cu")
		(net "P5E_CPU0_PE0_TX_DP<13>")
	)
	(arc
		(start 349.14713 -220.332046)
		(mid 349.147376 -220.32265)
		(end 349.147384 -220.31325)
		(width 0.0889)
		(layer "In15.Cu")
		(net "P5E_CPU0_PE0_TX_DP<13>")
	)
	(arc
		(start 350.387158 -224.916746)
		(mid 349.869489 -224.860579)
		(end 349.617284 -224.404936)
		(width 0.0889)
		(layer "In15.Cu")
		(net "P5E_CPU0_PE0_TX_DP<13>")
	)
	(arc
		(start 348.959932 -220.644212)
		(mid 349.093955 -220.512385)
		(end 349.14713 -220.332046)
		(width 0.0889)
		(layer "In15.Cu")
		(net "P5E_CPU0_PE0_TX_DP<13>")
	)
	(arc
		(start 348.959678 -221.623382)
		(mid 348.756855 -221.423151)
		(end 348.677484 -221.149418)
		(width 0.0889)
		(layer "In15.Cu")
		(net "P5E_CPU0_PE0_TX_DP<13>")
	)
	(arc
		(start 349.147384 -217.057732)
		(mid 349.095447 -216.874223)
		(end 348.959932 -216.739978)
		(width 0.0889)
		(layer "In15.Cu")
		(net "P5E_CPU0_PE0_TX_DP<13>")
	)
	(arc
		(start 349.14713 -221.94774)
		(mid 349.099451 -221.76484)
		(end 348.968568 -221.628462)
		(width 0.0889)
		(layer "In15.Cu")
		(net "P5E_CPU0_PE0_TX_DP<13>")
	)
	(arc
		(start 349.14713 -217.076528)
		(mid 349.147376 -217.067132)
		(end 349.147384 -217.057732)
		(width 0.0889)
		(layer "In15.Cu")
		(net "P5E_CPU0_PE0_TX_DP<13>")
	)
	(arc
		(start 348.959932 -217.388694)
		(mid 349.093955 -217.256867)
		(end 349.14713 -217.076528)
		(width 0.0889)
		(layer "In15.Cu")
		(net "P5E_CPU0_PE0_TX_DP<13>")
	)
	(arc
		(start 350.406716 -224.908618)
		(mid 350.396974 -224.912771)
		(end 350.387158 -224.916746)
		(width 0.0889)
		(layer "In15.Cu")
		(net "P5E_CPU0_PE0_TX_DP<13>")
	)
	(arc
		(start 348.498414 -214.941912)
		(mid 348.629328 -214.805552)
		(end 348.676976 -214.622634)
		(width 0.0889)
		(layer "In15.Cu")
		(net "P5E_CPU0_PE0_TX_DP<13>")
	)
	(arc
		(start 348.677484 -219.515944)
		(mid 348.677347 -219.503371)
		(end 348.677484 -219.490798)
		(width 0.0889)
		(layer "In15.Cu")
		(net "P5E_CPU0_PE0_TX_DP<13>")
	)
	(arc
		(start 348.483936 -215.922606)
		(mid 348.207153 -215.433205)
		(end 348.489524 -214.946992)
		(width 0.0889)
		(layer "In15.Cu")
		(net "P5E_CPU0_PE0_TX_DP<13>")
	)
	(arc
		(start 348.968568 -219.0115)
		(mid 349.147044 -218.692222)
		(end 348.968568 -218.372944)
		(width 0.0889)
		(layer "In15.Cu")
		(net "P5E_CPU0_PE0_TX_DP<13>")
	)
	(arc
		(start 348.676976 -214.472266)
		(mid 348.675496 -214.459899)
		(end 348.671388 -214.448136)
		(width 0.0889)
		(layer "In15.Cu")
		(net "P5E_CPU0_PE0_TX_DP<13>")
	)
	(arc
		(start 348.49308 -214.2617)
		(mid 348.351005 -214.150096)
		(end 348.257114 -213.995762)
		(width 0.0889)
		(layer "In15.Cu")
		(net "P5E_CPU0_PE0_TX_DP<13>")
	)
	(arc
		(start 348.671388 -214.448136)
		(mid 348.597332 -214.34048)
		(end 348.49308 -214.2617)
		(width 0.0889)
		(layer "In15.Cu")
		(net "P5E_CPU0_PE0_TX_DP<13>")
	)
	(arc
		(start 349.617284 -222.761556)
		(mid 349.569605 -222.578656)
		(end 349.438722 -222.442278)
		(width 0.0889)
		(layer "In15.Cu")
		(net "P5E_CPU0_PE0_TX_DP<13>")
	)
	(arc
		(start 348.959932 -219.995496)
		(mid 348.755597 -219.792891)
		(end 348.677484 -219.515944)
		(width 0.0889)
		(layer "In15.Cu")
		(net "P5E_CPU0_PE0_TX_DP<13>")
	)
	(arc
		(start 348.677484 -216.25052)
		(mid 348.629805 -216.06762)
		(end 348.498922 -215.931242)
		(width 0.0889)
		(layer "In15.Cu")
		(net "P5E_CPU0_PE0_TX_DP<13>")
	)
	(arc
		(start 348.959932 -216.739978)
		(mid 348.755597 -216.537373)
		(end 348.677484 -216.260426)
		(width 0.0889)
		(layer "In15.Cu")
		(net "P5E_CPU0_PE0_TX_DP<13>")
	)
	(arc
		(start 348.224856 -213.912704)
		(mid 348.211874 -213.866771)
		(end 348.207584 -213.819232)
		(width 0.0889)
		(layer "In15.Cu")
		(net "P5E_CPU0_PE0_TX_DP<13>")
	)
	(arc
		(start 348.677484 -221.115382)
		(mid 348.757646 -220.843193)
		(end 348.959932 -220.644212)
		(width 0.0889)
		(layer "In15.Cu")
		(net "P5E_CPU0_PE0_TX_DP<13>")
	)
	(arc
		(start 349.908368 -223.894904)
		(mid 350.086965 -223.575626)
		(end 349.908368 -223.256348)
		(width 0.0889)
		(layer "In15.Cu")
		(net "P5E_CPU0_PE0_TX_DP<13>")
	)
	(arc
		(start 349.617284 -224.373948)
		(mid 349.696654 -224.100214)
		(end 349.899478 -223.899984)
		(width 0.0889)
		(layer "In15.Cu")
		(net "P5E_CPU0_PE0_TX_DP<13>")
	)
	(arc
		(start 348.677484 -217.859864)
		(mid 348.757646 -217.587675)
		(end 348.959932 -217.388694)
		(width 0.0889)
		(layer "In15.Cu")
		(net "P5E_CPU0_PE0_TX_DP<13>")
	)
	(arc
		(start 349.147384 -220.31325)
		(mid 349.095447 -220.129741)
		(end 348.959932 -219.995496)
		(width 0.0889)
		(layer "In15.Cu")
		(net "P5E_CPU0_PE0_TX_DP<13>")
	)
	(arc
		(start 349.899478 -223.251268)
		(mid 349.698196 -223.053781)
		(end 349.617284 -222.783654)
		(width 0.0889)
		(layer "In15.Cu")
		(net "P5E_CPU0_PE0_TX_DP<13>")
	)
	(arc
		(start 348.677484 -219.490798)
		(mid 348.756795 -219.216923)
		(end 348.959678 -219.01658)
		(width 0.0889)
		(layer "In15.Cu")
		(net "P5E_CPU0_PE0_TX_DP<13>")
	)
	(arc
		(start 348.959678 -218.367864)
		(mid 348.756855 -218.167633)
		(end 348.677484 -217.8939)
		(width 0.0889)
		(layer "In15.Cu")
		(net "P5E_CPU0_PE0_TX_DP<13>")
	)
	(segment
		(start 349.24238 -224.925382)
		(end 349.24238 -224.389696)
		(width 0.13208)
		(layer "F.Cu")
		(net "P5E_CPU0_PE0_TX_DP<12>")
	)
	(segment
		(start 315.379608 -407.00452)
		(end 315.08065 -407.303478)
		(width 0.13208)
		(layer "F.Cu")
		(net "P5E_CPU0_PE0_TX_DP<12>")
	)
	(segment
		(start 315.08065 -407.926286)
		(end 315.405008 -408.250644)
		(width 0.13208)
		(layer "F.Cu")
		(net "P5E_CPU0_PE0_TX_DP<12>")
	)
	(segment
		(start 349.24238 -224.389696)
		(end 349.242634 -224.389442)
		(width 0.13208)
		(layer "F.Cu")
		(net "P5E_CPU0_PE0_TX_DP<12>")
	)
	(segment
		(start 315.08065 -407.303478)
		(end 315.08065 -407.926286)
		(width 0.13208)
		(layer "F.Cu")
		(net "P5E_CPU0_PE0_TX_DP<12>")
	)
	(segment
		(start 347.550232 -215.926162)
		(end 347.54947 -215.925654)
		(width 0.0889)
		(layer "In15.Cu")
		(net "P5E_CPU0_PE0_TX_DP<12>")
	)
	(segment
		(start 312.023252 -323.896228)
		(end 309.333392 -323.896228)
		(width 0.14732)
		(layer "In15.Cu")
		(net "P5E_CPU0_PE0_TX_DP<12>")
	)
	(segment
		(start 313.599322 -385.772152)
		(end 315.270388 -399.894552)
		(width 0.14732)
		(layer "In15.Cu")
		(net "P5E_CPU0_PE0_TX_DP<12>")
	)
	(segment
		(start 313.708288 -385.633976)
		(end 313.599322 -385.772152)
		(width 0.14732)
		(layer "In15.Cu")
		(net "P5E_CPU0_PE0_TX_DP<12>")
	)
	(segment
		(start 313.179968 -381.173736)
		(end 313.071002 -381.311912)
		(width 0.14732)
		(layer "In15.Cu")
		(net "P5E_CPU0_PE0_TX_DP<12>")
	)
	(segment
		(start 347.267784 -213.186772)
		(end 347.22562 -213.144608)
		(width 0.0889)
		(layer "In15.Cu")
		(net "P5E_CPU0_PE0_TX_DP<12>")
	)
	(segment
		(start 348.020894 -219.996004)
		(end 348.020894 -219.99575)
		(width 0.0889)
		(layer "In15.Cu")
		(net "P5E_CPU0_PE0_TX_DP<12>")
	)
	(segment
		(start 313.444128 -383.403856)
		(end 313.335162 -383.542032)
		(width 0.14732)
		(layer "In15.Cu")
		(net "P5E_CPU0_PE0_TX_DP<12>")
	)
	(segment
		(start 307.306472 -325.923148)
		(end 307.306472 -328.676508)
		(width 0.14732)
		(layer "In15.Cu")
		(net "P5E_CPU0_PE0_TX_DP<12>")
	)
	(segment
		(start 347.22562 -213.12251)
		(end 347.22562 -212.062314)
		(width 0.14732)
		(layer "In15.Cu")
		(net "P5E_CPU0_PE0_TX_DP<12>")
	)
	(segment
		(start 341.520272 -205.580996)
		(end 341.211154 -205.271878)
		(width 0.14732)
		(layer "In15.Cu")
		(net "P5E_CPU0_PE0_TX_DP<12>")
	)
	(segment
		(start 347.22562 -212.062314)
		(end 346.554806 -210.443064)
		(width 0.14732)
		(layer "In15.Cu")
		(net "P5E_CPU0_PE0_TX_DP<12>")
	)
	(segment
		(start 317.765684 -250.056904)
		(end 317.644272 -253.694692)
		(width 0.14732)
		(layer "In15.Cu")
		(net "P5E_CPU0_PE0_TX_DP<12>")
	)
	(segment
		(start 313.07151 -381.31242)
		(end 313.122818 -381.745744)
		(width 0.14732)
		(layer "In15.Cu")
		(net "P5E_CPU0_PE0_TX_DP<12>")
	)
	(segment
		(start 348.020894 -218.368118)
		(end 348.01175 -218.362784)
		(width 0.0889)
		(layer "In15.Cu")
		(net "P5E_CPU0_PE0_TX_DP<12>")
	)
	(segment
		(start 348.023942 -219.014294)
		(end 348.026482 -219.013024)
		(width 0.0889)
		(layer "In15.Cu")
		(net "P5E_CPU0_PE0_TX_DP<12>")
	)
	(segment
		(start 348.028768 -220.000576)
		(end 348.024704 -219.99829)
		(width 0.0889)
		(layer "In15.Cu")
		(net "P5E_CPU0_PE0_TX_DP<12>")
	)
	(segment
		(start 348.007178 -218.360244)
		(end 348.006924 -218.35999)
		(width 0.0889)
		(layer "In15.Cu")
		(net "P5E_CPU0_PE0_TX_DP<12>")
	)
	(segment
		(start 306.023518 -341.705692)
		(end 311.069482 -364.406942)
		(width 0.14732)
		(layer "In15.Cu")
		(net "P5E_CPU0_PE0_TX_DP<12>")
	)
	(segment
		(start 348.006924 -219.024454)
		(end 348.023942 -219.014294)
		(width 0.0889)
		(layer "In15.Cu")
		(net "P5E_CPU0_PE0_TX_DP<12>")
	)
	(segment
		(start 347.559122 -215.931242)
		(end 347.551756 -215.926924)
		(width 0.0889)
		(layer "In15.Cu")
		(net "P5E_CPU0_PE0_TX_DP<12>")
	)
	(segment
		(start 348.020894 -219.99575)
		(end 348.006924 -219.987876)
		(width 0.0889)
		(layer "In15.Cu")
		(net "P5E_CPU0_PE0_TX_DP<12>")
	)
	(segment
		(start 323.4055 -216.3191)
		(end 320.971672 -221.009718)
		(width 0.14732)
		(layer "In15.Cu")
		(net "P5E_CPU0_PE0_TX_DP<12>")
	)
	(segment
		(start 341.692738 -205.580996)
		(end 341.520272 -205.580996)
		(width 0.14732)
		(layer "In15.Cu")
		(net "P5E_CPU0_PE0_TX_DP<12>")
	)
	(segment
		(start 313.467242 -384.657092)
		(end 313.51855 -385.090924)
		(width 0.14732)
		(layer "In15.Cu")
		(net "P5E_CPU0_PE0_TX_DP<12>")
	)
	(segment
		(start 315.084968 -406.70988)
		(end 315.379608 -407.00452)
		(width 0.14732)
		(layer "In15.Cu")
		(net "P5E_CPU0_PE0_TX_DP<12>")
	)
	(segment
		(start 336.21472 -203.41717)
		(end 335.689956 -203.745338)
		(width 0.14732)
		(layer "In15.Cu")
		(net "P5E_CPU0_PE0_TX_DP<12>")
	)
	(segment
		(start 349.242634 -224.389442)
		(end 349.399098 -224.118424)
		(width 0.0889)
		(layer "In15.Cu")
		(net "P5E_CPU0_PE0_TX_DP<12>")
	)
	(segment
		(start 313.12231 -381.745744)
		(end 313.26074 -381.85471)
		(width 0.14732)
		(layer "In15.Cu")
		(net "P5E_CPU0_PE0_TX_DP<12>")
	)
	(segment
		(start 313.312048 -382.288796)
		(end 313.203082 -382.426972)
		(width 0.14732)
		(layer "In15.Cu")
		(net "P5E_CPU0_PE0_TX_DP<12>")
	)
	(segment
		(start 348.498922 -222.442278)
		(end 348.490032 -222.437198)
		(width 0.0889)
		(layer "In15.Cu")
		(net "P5E_CPU0_PE0_TX_DP<12>")
	)
	(segment
		(start 347.549724 -214.946992)
		(end 347.558614 -214.941912)
		(width 0.0889)
		(layer "In15.Cu")
		(net "P5E_CPU0_PE0_TX_DP<12>")
	)
	(segment
		(start 315.270388 -403.961854)
		(end 315.084968 -405.845264)
		(width 0.14732)
		(layer "In15.Cu")
		(net "P5E_CPU0_PE0_TX_DP<12>")
	)
	(segment
		(start 348.028768 -221.628462)
		(end 348.020894 -221.62389)
		(width 0.0889)
		(layer "In15.Cu")
		(net "P5E_CPU0_PE0_TX_DP<12>")
	)
	(segment
		(start 342.483186 -206.371444)
		(end 342.31072 -206.371444)
		(width 0.14732)
		(layer "In15.Cu")
		(net "P5E_CPU0_PE0_TX_DP<12>")
	)
	(segment
		(start 313.122818 -381.745744)
		(end 313.12231 -381.745744)
		(width 0.14732)
		(layer "In15.Cu")
		(net "P5E_CPU0_PE0_TX_DP<12>")
	)
	(segment
		(start 313.576208 -384.518916)
		(end 313.467242 -384.657092)
		(width 0.14732)
		(layer "In15.Cu")
		(net "P5E_CPU0_PE0_TX_DP<12>")
	)
	(segment
		(start 347.26753 -215.436704)
		(end 347.26753 -215.414606)
		(width 0.0889)
		(layer "In15.Cu")
		(net "P5E_CPU0_PE0_TX_DP<12>")
	)
	(segment
		(start 347.22562 -213.144608)
		(end 347.22562 -213.12251)
		(width 0.0889)
		(layer "In15.Cu")
		(net "P5E_CPU0_PE0_TX_DP<12>")
	)
	(segment
		(start 311.069482 -364.406942)
		(end 311.07253 -364.420404)
		(width 0.14732)
		(layer "In15.Cu")
		(net "P5E_CPU0_PE0_TX_DP<12>")
	)
	(segment
		(start 309.333392 -323.896228)
		(end 307.306472 -325.923148)
		(width 0.14732)
		(layer "In15.Cu")
		(net "P5E_CPU0_PE0_TX_DP<12>")
	)
	(segment
		(start 341.211154 -205.271878)
		(end 341.211154 -205.099412)
		(width 0.14732)
		(layer "In15.Cu")
		(net "P5E_CPU0_PE0_TX_DP<12>")
	)
	(segment
		(start 313.26074 -381.85471)
		(end 313.312048 -382.288796)
		(width 0.14732)
		(layer "In15.Cu")
		(net "P5E_CPU0_PE0_TX_DP<12>")
	)
	(segment
		(start 347.267784 -213.8807)
		(end 347.267784 -213.186772)
		(width 0.0889)
		(layer "In15.Cu")
		(net "P5E_CPU0_PE0_TX_DP<12>")
	)
	(segment
		(start 349.399098 -224.118424)
		(end 349.374968 -224.02927)
		(width 0.0889)
		(layer "In15.Cu")
		(net "P5E_CPU0_PE0_TX_DP<12>")
	)
	(segment
		(start 348.490032 -222.437198)
		(end 348.483936 -222.433642)
		(width 0.0889)
		(layer "In15.Cu")
		(net "P5E_CPU0_PE0_TX_DP<12>")
	)
	(segment
		(start 321.201034 -308.929024)
		(end 318.198754 -316.175898)
		(width 0.14732)
		(layer "In15.Cu")
		(net "P5E_CPU0_PE0_TX_DP<12>")
	)
	(segment
		(start 313.5249 -384.08483)
		(end 313.576208 -384.518916)
		(width 0.14732)
		(layer "In15.Cu")
		(net "P5E_CPU0_PE0_TX_DP<12>")
	)
	(segment
		(start 314.590684 -321.328796)
		(end 312.023252 -323.896228)
		(width 0.14732)
		(layer "In15.Cu")
		(net "P5E_CPU0_PE0_TX_DP<12>")
	)
	(segment
		(start 347.737176 -214.622634)
		(end 347.737176 -214.582502)
		(width 0.0889)
		(layer "In15.Cu")
		(net "P5E_CPU0_PE0_TX_DP<12>")
	)
	(segment
		(start 313.39282 -382.96977)
		(end 313.444128 -383.403856)
		(width 0.14732)
		(layer "In15.Cu")
		(net "P5E_CPU0_PE0_TX_DP<12>")
	)
	(segment
		(start 347.551756 -215.926924)
		(end 347.550232 -215.926162)
		(width 0.0889)
		(layer "In15.Cu")
		(net "P5E_CPU0_PE0_TX_DP<12>")
	)
	(segment
		(start 342.31072 -206.371444)
		(end 342.001602 -206.062326)
		(width 0.14732)
		(layer "In15.Cu")
		(net "P5E_CPU0_PE0_TX_DP<12>")
	)
	(segment
		(start 342.001602 -206.062326)
		(end 342.001602 -205.88986)
		(width 0.14732)
		(layer "In15.Cu")
		(net "P5E_CPU0_PE0_TX_DP<12>")
	)
	(segment
		(start 342.001602 -205.88986)
		(end 341.692738 -205.580996)
		(width 0.14732)
		(layer "In15.Cu")
		(net "P5E_CPU0_PE0_TX_DP<12>")
	)
	(segment
		(start 335.689956 -203.745338)
		(end 332.816454 -206.412084)
		(width 0.14732)
		(layer "In15.Cu")
		(net "P5E_CPU0_PE0_TX_DP<12>")
	)
	(segment
		(start 340.671912 -204.56017)
		(end 337.924394 -203.421996)
		(width 0.14732)
		(layer "In15.Cu")
		(net "P5E_CPU0_PE0_TX_DP<12>")
	)
	(segment
		(start 349.14713 -223.575626)
		(end 349.14713 -223.56699)
		(width 0.0889)
		(layer "In15.Cu")
		(net "P5E_CPU0_PE0_TX_DP<12>")
	)
	(segment
		(start 311.07253 -364.420404)
		(end 312.990992 -380.630684)
		(width 0.14732)
		(layer "In15.Cu")
		(net "P5E_CPU0_PE0_TX_DP<12>")
	)
	(segment
		(start 346.554806 -210.443064)
		(end 342.483186 -206.371444)
		(width 0.14732)
		(layer "In15.Cu")
		(net "P5E_CPU0_PE0_TX_DP<12>")
	)
	(segment
		(start 313.12866 -380.73965)
		(end 313.179968 -381.173736)
		(width 0.14732)
		(layer "In15.Cu")
		(net "P5E_CPU0_PE0_TX_DP<12>")
	)
	(segment
		(start 348.020894 -221.62389)
		(end 348.019878 -221.623382)
		(width 0.0889)
		(layer "In15.Cu")
		(net "P5E_CPU0_PE0_TX_DP<12>")
	)
	(segment
		(start 313.38647 -383.975864)
		(end 313.5249 -384.08483)
		(width 0.14732)
		(layer "In15.Cu")
		(net "P5E_CPU0_PE0_TX_DP<12>")
	)
	(segment
		(start 313.335162 -383.542032)
		(end 313.38647 -383.975864)
		(width 0.14732)
		(layer "In15.Cu")
		(net "P5E_CPU0_PE0_TX_DP<12>")
	)
	(segment
		(start 320.971672 -221.009718)
		(end 319.181734 -232.591356)
		(width 0.14732)
		(layer "In15.Cu")
		(net "P5E_CPU0_PE0_TX_DP<12>")
	)
	(segment
		(start 313.25439 -382.860804)
		(end 313.39282 -382.96977)
		(width 0.14732)
		(layer "In15.Cu")
		(net "P5E_CPU0_PE0_TX_DP<12>")
	)
	(segment
		(start 347.54947 -215.925654)
		(end 347.544136 -215.922606)
		(width 0.0889)
		(layer "In15.Cu")
		(net "P5E_CPU0_PE0_TX_DP<12>")
	)
	(segment
		(start 348.02572 -216.743026)
		(end 348.019878 -216.739978)
		(width 0.0889)
		(layer "In15.Cu")
		(net "P5E_CPU0_PE0_TX_DP<12>")
	)
	(segment
		(start 307.306472 -328.676508)
		(end 306.023518 -329.959462)
		(width 0.14732)
		(layer "In15.Cu")
		(net "P5E_CPU0_PE0_TX_DP<12>")
	)
	(segment
		(start 348.019878 -220.644212)
		(end 348.028768 -220.639132)
		(width 0.0889)
		(layer "In15.Cu")
		(net "P5E_CPU0_PE0_TX_DP<12>")
	)
	(segment
		(start 313.65698 -385.19989)
		(end 313.708288 -385.633976)
		(width 0.14732)
		(layer "In15.Cu")
		(net "P5E_CPU0_PE0_TX_DP<12>")
	)
	(segment
		(start 337.924394 -203.421996)
		(end 336.21472 -203.41717)
		(width 0.14732)
		(layer "In15.Cu")
		(net "P5E_CPU0_PE0_TX_DP<12>")
	)
	(segment
		(start 312.99023 -380.630684)
		(end 313.12866 -380.73965)
		(width 0.14732)
		(layer "In15.Cu")
		(net "P5E_CPU0_PE0_TX_DP<12>")
	)
	(segment
		(start 315.270388 -399.894552)
		(end 315.270388 -403.961854)
		(width 0.14732)
		(layer "In15.Cu")
		(net "P5E_CPU0_PE0_TX_DP<12>")
	)
	(segment
		(start 313.071002 -381.311912)
		(end 313.07151 -381.31242)
		(width 0.14732)
		(layer "In15.Cu")
		(net "P5E_CPU0_PE0_TX_DP<12>")
	)
	(segment
		(start 348.677484 -222.780098)
		(end 348.677484 -222.761556)
		(width 0.0889)
		(layer "In15.Cu")
		(net "P5E_CPU0_PE0_TX_DP<12>")
	)
	(segment
		(start 318.198754 -316.175898)
		(end 314.590684 -321.328796)
		(width 0.14732)
		(layer "In15.Cu")
		(net "P5E_CPU0_PE0_TX_DP<12>")
	)
	(segment
		(start 348.006924 -219.987876)
		(end 348.006924 -219.987622)
		(width 0.0889)
		(layer "In15.Cu")
		(net "P5E_CPU0_PE0_TX_DP<12>")
	)
	(segment
		(start 347.737684 -221.149418)
		(end 347.737684 -221.111826)
		(width 0.0889)
		(layer "In15.Cu")
		(net "P5E_CPU0_PE0_TX_DP<12>")
	)
	(segment
		(start 315.084968 -405.845264)
		(end 315.084968 -406.70988)
		(width 0.14732)
		(layer "In15.Cu")
		(net "P5E_CPU0_PE0_TX_DP<12>")
	)
	(segment
		(start 348.024704 -219.99829)
		(end 348.020894 -219.996004)
		(width 0.0889)
		(layer "In15.Cu")
		(net "P5E_CPU0_PE0_TX_DP<12>")
	)
	(segment
		(start 341.211154 -205.099412)
		(end 340.671912 -204.56017)
		(width 0.14732)
		(layer "In15.Cu")
		(net "P5E_CPU0_PE0_TX_DP<12>")
	)
	(segment
		(start 319.181734 -232.591356)
		(end 317.765684 -250.056904)
		(width 0.14732)
		(layer "In15.Cu")
		(net "P5E_CPU0_PE0_TX_DP<12>")
	)
	(segment
		(start 332.816454 -206.412084)
		(end 323.4055 -216.3191)
		(width 0.14732)
		(layer "In15.Cu")
		(net "P5E_CPU0_PE0_TX_DP<12>")
	)
	(segment
		(start 317.644272 -253.694692)
		(end 321.201034 -308.929024)
		(width 0.14732)
		(layer "In15.Cu")
		(net "P5E_CPU0_PE0_TX_DP<12>")
	)
	(segment
		(start 348.009718 -217.39479)
		(end 348.02064 -217.388694)
		(width 0.0889)
		(layer "In15.Cu")
		(net "P5E_CPU0_PE0_TX_DP<12>")
	)
	(segment
		(start 312.990992 -380.630684)
		(end 312.99023 -380.630684)
		(width 0.14732)
		(layer "In15.Cu")
		(net "P5E_CPU0_PE0_TX_DP<12>")
	)
	(segment
		(start 306.023518 -329.959462)
		(end 306.023518 -341.705692)
		(width 0.14732)
		(layer "In15.Cu")
		(net "P5E_CPU0_PE0_TX_DP<12>")
	)
	(segment
		(start 313.203082 -382.426972)
		(end 313.25439 -382.860804)
		(width 0.14732)
		(layer "In15.Cu")
		(net "P5E_CPU0_PE0_TX_DP<12>")
	)
	(segment
		(start 348.01175 -218.362784)
		(end 348.007178 -218.360244)
		(width 0.0889)
		(layer "In15.Cu")
		(net "P5E_CPU0_PE0_TX_DP<12>")
	)
	(segment
		(start 347.737684 -216.266014)
		(end 347.737684 -216.25052)
		(width 0.0889)
		(layer "In15.Cu")
		(net "P5E_CPU0_PE0_TX_DP<12>")
	)
	(segment
		(start 313.51855 -385.090924)
		(end 313.65698 -385.19989)
		(width 0.14732)
		(layer "In15.Cu")
		(net "P5E_CPU0_PE0_TX_DP<12>")
	)
	(segment
		(start 347.290136 -213.985602)
		(end 347.290644 -213.985348)
		(width 0.0889)
		(layer "In15.Cu")
		(net "P5E_CPU0_PE0_TX_DP<12>")
	)
	(arc
		(start 348.019878 -221.623382)
		(mid 347.817055 -221.423151)
		(end 347.737684 -221.149418)
		(width 0.0889)
		(layer "In15.Cu")
		(net "P5E_CPU0_PE0_TX_DP<12>")
	)
	(arc
		(start 347.558614 -214.941912)
		(mid 347.689528 -214.805552)
		(end 347.737176 -214.622634)
		(width 0.0889)
		(layer "In15.Cu")
		(net "P5E_CPU0_PE0_TX_DP<12>")
	)
	(arc
		(start 347.737684 -216.25052)
		(mid 347.690005 -216.06762)
		(end 347.559122 -215.931242)
		(width 0.0889)
		(layer "In15.Cu")
		(net "P5E_CPU0_PE0_TX_DP<12>")
	)
	(arc
		(start 347.545152 -214.25789)
		(mid 347.395867 -214.142132)
		(end 347.290136 -213.985602)
		(width 0.0889)
		(layer "In15.Cu")
		(net "P5E_CPU0_PE0_TX_DP<12>")
	)
	(arc
		(start 347.737176 -214.582502)
		(mid 347.685646 -214.393873)
		(end 347.545152 -214.25789)
		(width 0.0889)
		(layer "In15.Cu")
		(net "P5E_CPU0_PE0_TX_DP<12>")
	)
	(arc
		(start 348.20733 -221.94774)
		(mid 348.159651 -221.76484)
		(end 348.028768 -221.628462)
		(width 0.0889)
		(layer "In15.Cu")
		(net "P5E_CPU0_PE0_TX_DP<12>")
	)
	(arc
		(start 348.02064 -217.388694)
		(mid 348.207551 -217.067298)
		(end 348.02572 -216.743026)
		(width 0.0889)
		(layer "In15.Cu")
		(net "P5E_CPU0_PE0_TX_DP<12>")
	)
	(arc
		(start 348.677484 -222.761556)
		(mid 348.629805 -222.578656)
		(end 348.498922 -222.442278)
		(width 0.0889)
		(layer "In15.Cu")
		(net "P5E_CPU0_PE0_TX_DP<12>")
	)
	(arc
		(start 347.26753 -215.414606)
		(mid 347.348441 -215.144478)
		(end 347.549724 -214.946992)
		(width 0.0889)
		(layer "In15.Cu")
		(net "P5E_CPU0_PE0_TX_DP<12>")
	)
	(arc
		(start 348.028768 -220.639132)
		(mid 348.207365 -220.319854)
		(end 348.028768 -220.000576)
		(width 0.0889)
		(layer "In15.Cu")
		(net "P5E_CPU0_PE0_TX_DP<12>")
	)
	(arc
		(start 347.737684 -217.8939)
		(mid 347.737498 -217.875102)
		(end 347.737938 -217.856308)
		(width 0.0889)
		(layer "In15.Cu")
		(net "P5E_CPU0_PE0_TX_DP<12>")
	)
	(arc
		(start 347.737684 -221.111826)
		(mid 347.818595 -220.841698)
		(end 348.019878 -220.644212)
		(width 0.0889)
		(layer "In15.Cu")
		(net "P5E_CPU0_PE0_TX_DP<12>")
	)
	(arc
		(start 348.019878 -216.739978)
		(mid 347.817055 -216.539747)
		(end 347.737684 -216.266014)
		(width 0.0889)
		(layer "In15.Cu")
		(net "P5E_CPU0_PE0_TX_DP<12>")
	)
	(arc
		(start 348.006924 -219.987622)
		(mid 347.737724 -219.506038)
		(end 348.006924 -219.024454)
		(width 0.0889)
		(layer "In15.Cu")
		(net "P5E_CPU0_PE0_TX_DP<12>")
	)
	(arc
		(start 349.14713 -223.56699)
		(mid 349.09486 -223.384625)
		(end 348.959932 -223.251268)
		(width 0.0889)
		(layer "In15.Cu")
		(net "P5E_CPU0_PE0_TX_DP<12>")
	)
	(arc
		(start 348.959932 -223.251268)
		(mid 348.757646 -223.052287)
		(end 348.677484 -222.780098)
		(width 0.0889)
		(layer "In15.Cu")
		(net "P5E_CPU0_PE0_TX_DP<12>")
	)
	(arc
		(start 347.737938 -217.856308)
		(mid 347.815693 -217.59131)
		(end 348.009718 -217.39479)
		(width 0.0889)
		(layer "In15.Cu")
		(net "P5E_CPU0_PE0_TX_DP<12>")
	)
	(arc
		(start 347.290644 -213.985348)
		(mid 347.273514 -213.934271)
		(end 347.267784 -213.8807)
		(width 0.0889)
		(layer "In15.Cu")
		(net "P5E_CPU0_PE0_TX_DP<12>")
	)
	(arc
		(start 347.544136 -215.922606)
		(mid 347.341549 -215.716255)
		(end 347.26753 -215.436704)
		(width 0.0889)
		(layer "In15.Cu")
		(net "P5E_CPU0_PE0_TX_DP<12>")
	)
	(arc
		(start 348.483936 -222.433642)
		(mid 348.281349 -222.227291)
		(end 348.20733 -221.94774)
		(width 0.0889)
		(layer "In15.Cu")
		(net "P5E_CPU0_PE0_TX_DP<12>")
	)
	(arc
		(start 348.006924 -218.35999)
		(mid 347.813243 -218.16105)
		(end 347.737684 -217.8939)
		(width 0.0889)
		(layer "In15.Cu")
		(net "P5E_CPU0_PE0_TX_DP<12>")
	)
	(arc
		(start 349.374968 -224.02927)
		(mid 349.207214 -223.829492)
		(end 349.14713 -223.575626)
		(width 0.0889)
		(layer "In15.Cu")
		(net "P5E_CPU0_PE0_TX_DP<12>")
	)
	(arc
		(start 348.026482 -219.013024)
		(mid 348.207463 -218.688977)
		(end 348.020894 -218.368118)
		(width 0.0889)
		(layer "In15.Cu")
		(net "P5E_CPU0_PE0_TX_DP<12>")
	)
	(segment
		(start 348.772734 -225.739198)
		(end 348.772734 -225.203512)
		(width 0.13208)
		(layer "F.Cu")
		(net "P5E_CPU0_PE0_TX_DP<11>")
	)
	(segment
		(start 348.772734 -225.203512)
		(end 348.77248 -225.203258)
		(width 0.13208)
		(layer "F.Cu")
		(net "P5E_CPU0_PE0_TX_DP<11>")
	)
	(segment
		(start 318.14389 -407.926286)
		(end 318.468248 -408.250644)
		(width 0.13208)
		(layer "F.Cu")
		(net "P5E_CPU0_PE0_TX_DP<11>")
	)
	(segment
		(start 318.14389 -407.303478)
		(end 318.14389 -407.926286)
		(width 0.13208)
		(layer "F.Cu")
		(net "P5E_CPU0_PE0_TX_DP<11>")
	)
	(segment
		(start 318.442848 -407.00452)
		(end 318.14389 -407.303478)
		(width 0.13208)
		(layer "F.Cu")
		(net "P5E_CPU0_PE0_TX_DP<11>")
	)
	(segment
		(start 346.60967 -215.925654)
		(end 346.604336 -215.922606)
		(width 0.0889)
		(layer "In15.Cu")
		(net "P5E_CPU0_PE0_TX_DP<11>")
	)
	(segment
		(start 318.333628 -403.961854)
		(end 318.148208 -405.845264)
		(width 0.14732)
		(layer "In15.Cu")
		(net "P5E_CPU0_PE0_TX_DP<11>")
	)
	(segment
		(start 315.250576 -382.493012)
		(end 315.25083 -382.49352)
		(width 0.14732)
		(layer "In15.Cu")
		(net "P5E_CPU0_PE0_TX_DP<11>")
	)
	(segment
		(start 346.797884 -221.149418)
		(end 346.797884 -221.115382)
		(width 0.0889)
		(layer "In15.Cu")
		(net "P5E_CPU0_PE0_TX_DP<11>")
	)
	(segment
		(start 347.737684 -222.783654)
		(end 347.737684 -222.761556)
		(width 0.0889)
		(layer "In15.Cu")
		(net "P5E_CPU0_PE0_TX_DP<11>")
	)
	(segment
		(start 315.394848 -382.594358)
		(end 315.471048 -383.024888)
		(width 0.14732)
		(layer "In15.Cu")
		(net "P5E_CPU0_PE0_TX_DP<11>")
	)
	(segment
		(start 314.978034 -380.957836)
		(end 314.978542 -380.957836)
		(width 0.14732)
		(layer "In15.Cu")
		(net "P5E_CPU0_PE0_TX_DP<11>")
	)
	(segment
		(start 346.609924 -214.946992)
		(end 346.618814 -214.941912)
		(width 0.0889)
		(layer "In15.Cu")
		(net "P5E_CPU0_PE0_TX_DP<11>")
	)
	(segment
		(start 314.858146 -380.282196)
		(end 315.002672 -380.383034)
		(width 0.14732)
		(layer "In15.Cu")
		(net "P5E_CPU0_PE0_TX_DP<11>")
	)
	(segment
		(start 342.426036 -208.958688)
		(end 334.217518 -208.958688)
		(width 0.14732)
		(layer "In15.Cu")
		(net "P5E_CPU0_PE0_TX_DP<11>")
	)
	(segment
		(start 347.26753 -217.072972)
		(end 347.26753 -217.0557)
		(width 0.0889)
		(layer "In15.Cu")
		(net "P5E_CPU0_PE0_TX_DP<11>")
	)
	(segment
		(start 315.863224 -385.235958)
		(end 315.762386 -385.38023)
		(width 0.14732)
		(layer "In15.Cu")
		(net "P5E_CPU0_PE0_TX_DP<11>")
	)
	(segment
		(start 313.426856 -324.611238)
		(end 312.796428 -324.872096)
		(width 0.14732)
		(layer "In15.Cu")
		(net "P5E_CPU0_PE0_TX_DP<11>")
	)
	(segment
		(start 306.977034 -330.484226)
		(end 306.977034 -341.60079)
		(width 0.14732)
		(layer "In15.Cu")
		(net "P5E_CPU0_PE0_TX_DP<11>")
	)
	(segment
		(start 312.796428 -324.872096)
		(end 309.674768 -324.872096)
		(width 0.14732)
		(layer "In15.Cu")
		(net "P5E_CPU0_PE0_TX_DP<11>")
	)
	(segment
		(start 346.28582 -213.144608)
		(end 346.28582 -213.12251)
		(width 0.0889)
		(layer "In15.Cu")
		(net "P5E_CPU0_PE0_TX_DP<11>")
	)
	(segment
		(start 312.024014 -364.291118)
		(end 314.858654 -380.282196)
		(width 0.14732)
		(layer "In15.Cu")
		(net "P5E_CPU0_PE0_TX_DP<11>")
	)
	(segment
		(start 344.61958 -209.867246)
		(end 342.426036 -208.958688)
		(width 0.14732)
		(layer "In15.Cu")
		(net "P5E_CPU0_PE0_TX_DP<11>")
	)
	(segment
		(start 347.559122 -222.442278)
		(end 347.550232 -222.437198)
		(width 0.0889)
		(layer "In15.Cu")
		(net "P5E_CPU0_PE0_TX_DP<11>")
	)
	(segment
		(start 346.797376 -214.622634)
		(end 346.797376 -214.461344)
		(width 0.0889)
		(layer "In15.Cu")
		(net "P5E_CPU0_PE0_TX_DP<11>")
	)
	(segment
		(start 348.028768 -223.256348)
		(end 348.019878 -223.251268)
		(width 0.0889)
		(layer "In15.Cu")
		(net "P5E_CPU0_PE0_TX_DP<11>")
	)
	(segment
		(start 309.674768 -324.872096)
		(end 308.281832 -326.265032)
		(width 0.14732)
		(layer "In15.Cu")
		(net "P5E_CPU0_PE0_TX_DP<11>")
	)
	(segment
		(start 318.859662 -317.029338)
		(end 313.841384 -324.19671)
		(width 0.14732)
		(layer "In15.Cu")
		(net "P5E_CPU0_PE0_TX_DP<11>")
	)
	(segment
		(start 315.667136 -384.13055)
		(end 315.566298 -384.274822)
		(width 0.14732)
		(layer "In15.Cu")
		(net "P5E_CPU0_PE0_TX_DP<11>")
	)
	(segment
		(start 306.977034 -341.60079)
		(end 312.024014 -364.291118)
		(width 0.14732)
		(layer "In15.Cu")
		(net "P5E_CPU0_PE0_TX_DP<11>")
	)
	(segment
		(start 348.020894 -223.899476)
		(end 348.028768 -223.894904)
		(width 0.0889)
		(layer "In15.Cu")
		(net "P5E_CPU0_PE0_TX_DP<11>")
	)
	(segment
		(start 315.590936 -383.70002)
		(end 315.667136 -384.13055)
		(width 0.14732)
		(layer "In15.Cu")
		(net "P5E_CPU0_PE0_TX_DP<11>")
	)
	(segment
		(start 346.797884 -217.8939)
		(end 346.797884 -217.859864)
		(width 0.0889)
		(layer "In15.Cu")
		(net "P5E_CPU0_PE0_TX_DP<11>")
	)
	(segment
		(start 348.77248 -225.203258)
		(end 348.616016 -224.93224)
		(width 0.0889)
		(layer "In15.Cu")
		(net "P5E_CPU0_PE0_TX_DP<11>")
	)
	(segment
		(start 346.619322 -215.931242)
		(end 346.611956 -215.926924)
		(width 0.0889)
		(layer "In15.Cu")
		(net "P5E_CPU0_PE0_TX_DP<11>")
	)
	(segment
		(start 315.19876 -381.488696)
		(end 315.27496 -381.919226)
		(width 0.14732)
		(layer "In15.Cu")
		(net "P5E_CPU0_PE0_TX_DP<11>")
	)
	(segment
		(start 320.111628 -232.724452)
		(end 318.70523 -250.1011)
		(width 0.14732)
		(layer "In15.Cu")
		(net "P5E_CPU0_PE0_TX_DP<11>")
	)
	(segment
		(start 318.148208 -405.845264)
		(end 318.148208 -406.70988)
		(width 0.14732)
		(layer "In15.Cu")
		(net "P5E_CPU0_PE0_TX_DP<11>")
	)
	(segment
		(start 315.37021 -383.16916)
		(end 315.44641 -383.599182)
		(width 0.14732)
		(layer "In15.Cu")
		(net "P5E_CPU0_PE0_TX_DP<11>")
	)
	(segment
		(start 348.019878 -223.899984)
		(end 348.020894 -223.899476)
		(width 0.0889)
		(layer "In15.Cu")
		(net "P5E_CPU0_PE0_TX_DP<11>")
	)
	(segment
		(start 322.164964 -309.060342)
		(end 318.859662 -317.029338)
		(width 0.14732)
		(layer "In15.Cu")
		(net "P5E_CPU0_PE0_TX_DP<11>")
	)
	(segment
		(start 324.216268 -216.838784)
		(end 323.63918 -217.950796)
		(width 0.14732)
		(layer "In15.Cu")
		(net "P5E_CPU0_PE0_TX_DP<11>")
	)
	(segment
		(start 315.25083 -382.49352)
		(end 315.250322 -382.49352)
		(width 0.14732)
		(layer "In15.Cu")
		(net "P5E_CPU0_PE0_TX_DP<11>")
	)
	(segment
		(start 323.63918 -217.950796)
		(end 321.867022 -221.36735)
		(width 0.14732)
		(layer "In15.Cu")
		(net "P5E_CPU0_PE0_TX_DP<11>")
	)
	(segment
		(start 315.44641 -383.599182)
		(end 315.590936 -383.70002)
		(width 0.14732)
		(layer "In15.Cu")
		(net "P5E_CPU0_PE0_TX_DP<11>")
	)
	(segment
		(start 318.148208 -406.70988)
		(end 318.442848 -407.00452)
		(width 0.14732)
		(layer "In15.Cu")
		(net "P5E_CPU0_PE0_TX_DP<11>")
	)
	(segment
		(start 345.757246 -211.004912)
		(end 344.61958 -209.867246)
		(width 0.14732)
		(layer "In15.Cu")
		(net "P5E_CPU0_PE0_TX_DP<11>")
	)
	(segment
		(start 346.611956 -215.926924)
		(end 346.610432 -215.926162)
		(width 0.0889)
		(layer "In15.Cu")
		(net "P5E_CPU0_PE0_TX_DP<11>")
	)
	(segment
		(start 346.610432 -215.926162)
		(end 346.60967 -215.925654)
		(width 0.0889)
		(layer "In15.Cu")
		(net "P5E_CPU0_PE0_TX_DP<11>")
	)
	(segment
		(start 321.867022 -221.36735)
		(end 320.111628 -232.724452)
		(width 0.14732)
		(layer "In15.Cu")
		(net "P5E_CPU0_PE0_TX_DP<11>")
	)
	(segment
		(start 315.078872 -380.813564)
		(end 314.978034 -380.957836)
		(width 0.14732)
		(layer "In15.Cu")
		(net "P5E_CPU0_PE0_TX_DP<11>")
	)
	(segment
		(start 308.281832 -329.179428)
		(end 306.977034 -330.484226)
		(width 0.14732)
		(layer "In15.Cu")
		(net "P5E_CPU0_PE0_TX_DP<11>")
	)
	(segment
		(start 315.002672 -380.383034)
		(end 315.078872 -380.813564)
		(width 0.14732)
		(layer "In15.Cu")
		(net "P5E_CPU0_PE0_TX_DP<11>")
	)
	(segment
		(start 347.080078 -219.01658)
		(end 347.088968 -219.0115)
		(width 0.0889)
		(layer "In15.Cu")
		(net "P5E_CPU0_PE0_TX_DP<11>")
	)
	(segment
		(start 314.978542 -380.957836)
		(end 315.054742 -381.387858)
		(width 0.14732)
		(layer "In15.Cu")
		(net "P5E_CPU0_PE0_TX_DP<11>")
	)
	(segment
		(start 334.217518 -208.958688)
		(end 330.07935 -211.205572)
		(width 0.14732)
		(layer "In15.Cu")
		(net "P5E_CPU0_PE0_TX_DP<11>")
	)
	(segment
		(start 308.281832 -326.265032)
		(end 308.281832 -329.179428)
		(width 0.14732)
		(layer "In15.Cu")
		(net "P5E_CPU0_PE0_TX_DP<11>")
	)
	(segment
		(start 315.762386 -385.38023)
		(end 318.333628 -399.886678)
		(width 0.14732)
		(layer "In15.Cu")
		(net "P5E_CPU0_PE0_TX_DP<11>")
	)
	(segment
		(start 346.327984 -213.930484)
		(end 346.327984 -213.186772)
		(width 0.0889)
		(layer "In15.Cu")
		(net "P5E_CPU0_PE0_TX_DP<11>")
	)
	(segment
		(start 346.797884 -216.260426)
		(end 346.797884 -216.25052)
		(width 0.0889)
		(layer "In15.Cu")
		(net "P5E_CPU0_PE0_TX_DP<11>")
	)
	(segment
		(start 346.327984 -213.186772)
		(end 346.28582 -213.144608)
		(width 0.0889)
		(layer "In15.Cu")
		(net "P5E_CPU0_PE0_TX_DP<11>")
	)
	(segment
		(start 315.642498 -384.704844)
		(end 315.787024 -384.805682)
		(width 0.14732)
		(layer "In15.Cu")
		(net "P5E_CPU0_PE0_TX_DP<11>")
	)
	(segment
		(start 313.841384 -324.19671)
		(end 313.426856 -324.611238)
		(width 0.14732)
		(layer "In15.Cu")
		(net "P5E_CPU0_PE0_TX_DP<11>")
	)
	(segment
		(start 315.174122 -382.063498)
		(end 315.17463 -382.063498)
		(width 0.14732)
		(layer "In15.Cu")
		(net "P5E_CPU0_PE0_TX_DP<11>")
	)
	(segment
		(start 315.054742 -381.387858)
		(end 315.054234 -381.387858)
		(width 0.14732)
		(layer "In15.Cu")
		(net "P5E_CPU0_PE0_TX_DP<11>")
	)
	(segment
		(start 347.26753 -220.32849)
		(end 347.26753 -220.311218)
		(width 0.0889)
		(layer "In15.Cu")
		(net "P5E_CPU0_PE0_TX_DP<11>")
	)
	(segment
		(start 315.27496 -381.919226)
		(end 315.174122 -382.063498)
		(width 0.14732)
		(layer "In15.Cu")
		(net "P5E_CPU0_PE0_TX_DP<11>")
	)
	(segment
		(start 346.28582 -212.2805)
		(end 345.757246 -211.004912)
		(width 0.14732)
		(layer "In15.Cu")
		(net "P5E_CPU0_PE0_TX_DP<11>")
	)
	(segment
		(start 315.17463 -382.063498)
		(end 315.250576 -382.493012)
		(width 0.14732)
		(layer "In15.Cu")
		(net "P5E_CPU0_PE0_TX_DP<11>")
	)
	(segment
		(start 347.088968 -218.372944)
		(end 347.081094 -218.368372)
		(width 0.0889)
		(layer "In15.Cu")
		(net "P5E_CPU0_PE0_TX_DP<11>")
	)
	(segment
		(start 315.471048 -383.024888)
		(end 315.37021 -383.16916)
		(width 0.14732)
		(layer "In15.Cu")
		(net "P5E_CPU0_PE0_TX_DP<11>")
	)
	(segment
		(start 330.07935 -211.205572)
		(end 324.216268 -216.838784)
		(width 0.14732)
		(layer "In15.Cu")
		(net "P5E_CPU0_PE0_TX_DP<11>")
	)
	(segment
		(start 315.250322 -382.49352)
		(end 315.394848 -382.594358)
		(width 0.14732)
		(layer "In15.Cu")
		(net "P5E_CPU0_PE0_TX_DP<11>")
	)
	(segment
		(start 346.28582 -213.12251)
		(end 346.28582 -212.2805)
		(width 0.14732)
		(layer "In15.Cu")
		(net "P5E_CPU0_PE0_TX_DP<11>")
	)
	(segment
		(start 315.787024 -384.805682)
		(end 315.863224 -385.235958)
		(width 0.14732)
		(layer "In15.Cu")
		(net "P5E_CPU0_PE0_TX_DP<11>")
	)
	(segment
		(start 318.333628 -399.886678)
		(end 318.333628 -403.961854)
		(width 0.14732)
		(layer "In15.Cu")
		(net "P5E_CPU0_PE0_TX_DP<11>")
	)
	(segment
		(start 347.737684 -224.404936)
		(end 347.737684 -224.373948)
		(width 0.0889)
		(layer "In15.Cu")
		(net "P5E_CPU0_PE0_TX_DP<11>")
	)
	(segment
		(start 346.797884 -219.515944)
		(end 346.797884 -219.490544)
		(width 0.0889)
		(layer "In15.Cu")
		(net "P5E_CPU0_PE0_TX_DP<11>")
	)
	(segment
		(start 348.616016 -224.93224)
		(end 348.527116 -224.908618)
		(width 0.0889)
		(layer "In15.Cu")
		(net "P5E_CPU0_PE0_TX_DP<11>")
	)
	(segment
		(start 347.088968 -221.628462)
		(end 347.080078 -221.623382)
		(width 0.0889)
		(layer "In15.Cu")
		(net "P5E_CPU0_PE0_TX_DP<11>")
	)
	(segment
		(start 318.596518 -253.33071)
		(end 322.164964 -309.060342)
		(width 0.14732)
		(layer "In15.Cu")
		(net "P5E_CPU0_PE0_TX_DP<11>")
	)
	(segment
		(start 318.70523 -250.1011)
		(end 318.596518 -253.33071)
		(width 0.14732)
		(layer "In15.Cu")
		(net "P5E_CPU0_PE0_TX_DP<11>")
	)
	(segment
		(start 315.566298 -384.274822)
		(end 315.642498 -384.704844)
		(width 0.14732)
		(layer "In15.Cu")
		(net "P5E_CPU0_PE0_TX_DP<11>")
	)
	(segment
		(start 346.32773 -215.436704)
		(end 346.32773 -215.414606)
		(width 0.0889)
		(layer "In15.Cu")
		(net "P5E_CPU0_PE0_TX_DP<11>")
	)
	(segment
		(start 314.858654 -380.282196)
		(end 314.858146 -380.282196)
		(width 0.14732)
		(layer "In15.Cu")
		(net "P5E_CPU0_PE0_TX_DP<11>")
	)
	(segment
		(start 347.081094 -218.368372)
		(end 347.080078 -218.367864)
		(width 0.0889)
		(layer "In15.Cu")
		(net "P5E_CPU0_PE0_TX_DP<11>")
	)
	(segment
		(start 315.054234 -381.387858)
		(end 315.19876 -381.488696)
		(width 0.14732)
		(layer "In15.Cu")
		(net "P5E_CPU0_PE0_TX_DP<11>")
	)
	(segment
		(start 347.550232 -222.437198)
		(end 347.544136 -222.433642)
		(width 0.0889)
		(layer "In15.Cu")
		(net "P5E_CPU0_PE0_TX_DP<11>")
	)
	(arc
		(start 347.080332 -220.644212)
		(mid 347.215265 -220.510858)
		(end 347.26753 -220.32849)
		(width 0.0889)
		(layer "In15.Cu")
		(net "P5E_CPU0_PE0_TX_DP<11>")
	)
	(arc
		(start 347.26753 -221.94774)
		(mid 347.219851 -221.76484)
		(end 347.088968 -221.628462)
		(width 0.0889)
		(layer "In15.Cu")
		(net "P5E_CPU0_PE0_TX_DP<11>")
	)
	(arc
		(start 347.080332 -216.739978)
		(mid 346.875997 -216.537373)
		(end 346.797884 -216.260426)
		(width 0.0889)
		(layer "In15.Cu")
		(net "P5E_CPU0_PE0_TX_DP<11>")
	)
	(arc
		(start 346.618814 -214.941912)
		(mid 346.749728 -214.805552)
		(end 346.797376 -214.622634)
		(width 0.0889)
		(layer "In15.Cu")
		(net "P5E_CPU0_PE0_TX_DP<11>")
	)
	(arc
		(start 347.088968 -219.0115)
		(mid 347.267444 -218.692222)
		(end 347.088968 -218.372944)
		(width 0.0889)
		(layer "In15.Cu")
		(net "P5E_CPU0_PE0_TX_DP<11>")
	)
	(arc
		(start 346.343224 -213.969346)
		(mid 346.335261 -213.950049)
		(end 346.327984 -213.930484)
		(width 0.0889)
		(layer "In15.Cu")
		(net "P5E_CPU0_PE0_TX_DP<11>")
	)
	(arc
		(start 346.797884 -221.115382)
		(mid 346.878046 -220.843193)
		(end 347.080332 -220.644212)
		(width 0.0889)
		(layer "In15.Cu")
		(net "P5E_CPU0_PE0_TX_DP<11>")
	)
	(arc
		(start 347.080078 -218.367864)
		(mid 346.877255 -218.167633)
		(end 346.797884 -217.8939)
		(width 0.0889)
		(layer "In15.Cu")
		(net "P5E_CPU0_PE0_TX_DP<11>")
	)
	(arc
		(start 346.32773 -215.414606)
		(mid 346.408641 -215.144478)
		(end 346.609924 -214.946992)
		(width 0.0889)
		(layer "In15.Cu")
		(net "P5E_CPU0_PE0_TX_DP<11>")
	)
	(arc
		(start 348.019878 -223.251268)
		(mid 347.818596 -223.053781)
		(end 347.737684 -222.783654)
		(width 0.0889)
		(layer "In15.Cu")
		(net "P5E_CPU0_PE0_TX_DP<11>")
	)
	(arc
		(start 346.797884 -219.490544)
		(mid 346.877254 -219.21681)
		(end 347.080078 -219.01658)
		(width 0.0889)
		(layer "In15.Cu")
		(net "P5E_CPU0_PE0_TX_DP<11>")
	)
	(arc
		(start 346.797884 -216.25052)
		(mid 346.750205 -216.06762)
		(end 346.619322 -215.931242)
		(width 0.0889)
		(layer "In15.Cu")
		(net "P5E_CPU0_PE0_TX_DP<11>")
	)
	(arc
		(start 347.737684 -224.373948)
		(mid 347.817054 -224.100214)
		(end 348.019878 -223.899984)
		(width 0.0889)
		(layer "In15.Cu")
		(net "P5E_CPU0_PE0_TX_DP<11>")
	)
	(arc
		(start 346.613226 -214.261954)
		(mid 346.453154 -214.138774)
		(end 346.343224 -213.969346)
		(width 0.0889)
		(layer "In15.Cu")
		(net "P5E_CPU0_PE0_TX_DP<11>")
	)
	(arc
		(start 347.080078 -221.623382)
		(mid 346.877255 -221.423151)
		(end 346.797884 -221.149418)
		(width 0.0889)
		(layer "In15.Cu")
		(net "P5E_CPU0_PE0_TX_DP<11>")
	)
	(arc
		(start 347.544136 -222.433642)
		(mid 347.341549 -222.227291)
		(end 347.26753 -221.94774)
		(width 0.0889)
		(layer "In15.Cu")
		(net "P5E_CPU0_PE0_TX_DP<11>")
	)
	(arc
		(start 346.797884 -217.859864)
		(mid 346.878046 -217.587675)
		(end 347.080332 -217.388694)
		(width 0.0889)
		(layer "In15.Cu")
		(net "P5E_CPU0_PE0_TX_DP<11>")
	)
	(arc
		(start 347.26753 -220.311218)
		(mid 347.21526 -220.128853)
		(end 347.080332 -219.995496)
		(width 0.0889)
		(layer "In15.Cu")
		(net "P5E_CPU0_PE0_TX_DP<11>")
	)
	(arc
		(start 347.080332 -217.388694)
		(mid 347.215265 -217.25534)
		(end 347.26753 -217.072972)
		(width 0.0889)
		(layer "In15.Cu")
		(net "P5E_CPU0_PE0_TX_DP<11>")
	)
	(arc
		(start 347.080332 -219.995496)
		(mid 346.875997 -219.792891)
		(end 346.797884 -219.515944)
		(width 0.0889)
		(layer "In15.Cu")
		(net "P5E_CPU0_PE0_TX_DP<11>")
	)
	(arc
		(start 348.019878 -224.8789)
		(mid 347.817055 -224.678669)
		(end 347.737684 -224.404936)
		(width 0.0889)
		(layer "In15.Cu")
		(net "P5E_CPU0_PE0_TX_DP<11>")
	)
	(arc
		(start 348.507558 -224.916746)
		(mid 348.259406 -224.953361)
		(end 348.019878 -224.8789)
		(width 0.0889)
		(layer "In15.Cu")
		(net "P5E_CPU0_PE0_TX_DP<11>")
	)
	(arc
		(start 346.797376 -214.461344)
		(mid 346.722371 -214.345885)
		(end 346.613226 -214.261954)
		(width 0.0889)
		(layer "In15.Cu")
		(net "P5E_CPU0_PE0_TX_DP<11>")
	)
	(arc
		(start 347.737684 -222.761556)
		(mid 347.690005 -222.578656)
		(end 347.559122 -222.442278)
		(width 0.0889)
		(layer "In15.Cu")
		(net "P5E_CPU0_PE0_TX_DP<11>")
	)
	(arc
		(start 348.028768 -223.894904)
		(mid 348.207365 -223.575626)
		(end 348.028768 -223.256348)
		(width 0.0889)
		(layer "In15.Cu")
		(net "P5E_CPU0_PE0_TX_DP<11>")
	)
	(arc
		(start 346.604336 -215.922606)
		(mid 346.401749 -215.716255)
		(end 346.32773 -215.436704)
		(width 0.0889)
		(layer "In15.Cu")
		(net "P5E_CPU0_PE0_TX_DP<11>")
	)
	(arc
		(start 347.26753 -217.0557)
		(mid 347.21526 -216.873335)
		(end 347.080332 -216.739978)
		(width 0.0889)
		(layer "In15.Cu")
		(net "P5E_CPU0_PE0_TX_DP<11>")
	)
	(arc
		(start 348.527116 -224.908618)
		(mid 348.517376 -224.912775)
		(end 348.507558 -224.916746)
		(width 0.0889)
		(layer "In15.Cu")
		(net "P5E_CPU0_PE0_TX_DP<11>")
	)
	(segment
		(start 321.20713 -407.926286)
		(end 321.531488 -408.250644)
		(width 0.13208)
		(layer "F.Cu")
		(net "P5E_CPU0_PE0_TX_DP<10>")
	)
	(segment
		(start 321.20713 -407.303478)
		(end 321.20713 -407.926286)
		(width 0.13208)
		(layer "F.Cu")
		(net "P5E_CPU0_PE0_TX_DP<10>")
	)
	(segment
		(start 347.36278 -224.389696)
		(end 347.363034 -224.389442)
		(width 0.13208)
		(layer "F.Cu")
		(net "P5E_CPU0_PE0_TX_DP<10>")
	)
	(segment
		(start 321.506088 -407.00452)
		(end 321.20713 -407.303478)
		(width 0.13208)
		(layer "F.Cu")
		(net "P5E_CPU0_PE0_TX_DP<10>")
	)
	(segment
		(start 347.36278 -224.925382)
		(end 347.36278 -224.389696)
		(width 0.13208)
		(layer "F.Cu")
		(net "P5E_CPU0_PE0_TX_DP<10>")
	)
	(segment
		(start 346.611956 -222.43796)
		(end 346.610432 -222.437198)
		(width 0.0889)
		(layer "In15.Cu")
		(net "P5E_CPU0_PE0_TX_DP<10>")
	)
	(segment
		(start 323.151246 -309.414926)
		(end 319.9384 -317.128144)
		(width 0.14732)
		(layer "In15.Cu")
		(net "P5E_CPU0_PE0_TX_DP<10>")
	)
	(segment
		(start 316.934342 -380.292102)
		(end 317.035942 -380.717298)
		(width 0.14732)
		(layer "In15.Cu")
		(net "P5E_CPU0_PE0_TX_DP<10>")
	)
	(segment
		(start 333.04099 -210.86318)
		(end 332.656434 -211.07146)
		(width 0.14732)
		(layer "In15.Cu")
		(net "P5E_CPU0_PE0_TX_DP<10>")
	)
	(segment
		(start 345.679522 -215.931242)
		(end 345.671394 -215.92667)
		(width 0.0889)
		(layer "In15.Cu")
		(net "P5E_CPU0_PE0_TX_DP<10>")
	)
	(segment
		(start 345.669108 -215.925146)
		(end 345.667838 -215.924384)
		(width 0.0889)
		(layer "In15.Cu")
		(net "P5E_CPU0_PE0_TX_DP<10>")
	)
	(segment
		(start 321.396868 -403.961854)
		(end 321.211448 -405.845518)
		(width 0.14732)
		(layer "In15.Cu")
		(net "P5E_CPU0_PE0_TX_DP<10>")
	)
	(segment
		(start 346.149168 -216.745058)
		(end 346.141294 -216.740486)
		(width 0.0889)
		(layer "In15.Cu")
		(net "P5E_CPU0_PE0_TX_DP<10>")
	)
	(segment
		(start 345.858084 -216.266014)
		(end 345.858084 -216.25052)
		(width 0.0889)
		(layer "In15.Cu")
		(net "P5E_CPU0_PE0_TX_DP<10>")
	)
	(segment
		(start 317.828168 -384.568446)
		(end 317.978536 -384.660648)
		(width 0.14732)
		(layer "In15.Cu")
		(net "P5E_CPU0_PE0_TX_DP<10>")
	)
	(segment
		(start 317.195454 -381.384048)
		(end 317.2968 -381.809244)
		(width 0.14732)
		(layer "In15.Cu")
		(net "P5E_CPU0_PE0_TX_DP<10>")
	)
	(segment
		(start 346.149168 -220.000576)
		(end 346.141294 -219.996004)
		(width 0.0889)
		(layer "In15.Cu")
		(net "P5E_CPU0_PE0_TX_DP<10>")
	)
	(segment
		(start 347.26753 -223.575626)
		(end 347.26753 -223.56699)
		(width 0.0889)
		(layer "In15.Cu")
		(net "P5E_CPU0_PE0_TX_DP<10>")
	)
	(segment
		(start 344.137996 -210.80095)
		(end 342.072976 -209.945478)
		(width 0.14732)
		(layer "In15.Cu")
		(net "P5E_CPU0_PE0_TX_DP<10>")
	)
	(segment
		(start 334.023716 -210.33105)
		(end 333.639414 -210.539076)
		(width 0.14732)
		(layer "In15.Cu")
		(net "P5E_CPU0_PE0_TX_DP<10>")
	)
	(segment
		(start 333.639414 -210.539076)
		(end 333.47406 -210.4898)
		(width 0.14732)
		(layer "In15.Cu")
		(net "P5E_CPU0_PE0_TX_DP<10>")
	)
	(segment
		(start 346.140278 -219.01658)
		(end 346.149168 -219.0115)
		(width 0.0889)
		(layer "In15.Cu")
		(net "P5E_CPU0_PE0_TX_DP<10>")
	)
	(segment
		(start 330.771754 -211.953602)
		(end 324.984872 -217.441018)
		(width 0.14732)
		(layer "In15.Cu")
		(net "P5E_CPU0_PE0_TX_DP<10>")
	)
	(segment
		(start 314.50915 -324.882764)
		(end 313.922156 -325.469758)
		(width 0.14732)
		(layer "In15.Cu")
		(net "P5E_CPU0_PE0_TX_DP<10>")
	)
	(segment
		(start 317.726822 -384.143758)
		(end 317.828168 -384.568446)
		(width 0.14732)
		(layer "In15.Cu")
		(net "P5E_CPU0_PE0_TX_DP<10>")
	)
	(segment
		(start 347.363034 -224.389442)
		(end 347.519498 -224.118424)
		(width 0.0889)
		(layer "In15.Cu")
		(net "P5E_CPU0_PE0_TX_DP<10>")
	)
	(segment
		(start 317.567056 -383.476246)
		(end 317.717424 -383.568448)
		(width 0.14732)
		(layer "In15.Cu")
		(net "P5E_CPU0_PE0_TX_DP<10>")
	)
	(segment
		(start 345.858084 -217.8939)
		(end 345.858084 -217.856308)
		(width 0.0889)
		(layer "In15.Cu")
		(net "P5E_CPU0_PE0_TX_DP<10>")
	)
	(segment
		(start 345.670124 -214.946992)
		(end 345.679014 -214.941912)
		(width 0.0889)
		(layer "In15.Cu")
		(net "P5E_CPU0_PE0_TX_DP<10>")
	)
	(segment
		(start 321.211448 -405.845518)
		(end 321.211448 -406.70988)
		(width 0.14732)
		(layer "In15.Cu")
		(net "P5E_CPU0_PE0_TX_DP<10>")
	)
	(segment
		(start 333.47406 -210.4898)
		(end 333.090012 -210.697826)
		(width 0.14732)
		(layer "In15.Cu")
		(net "P5E_CPU0_PE0_TX_DP<10>")
	)
	(segment
		(start 309.227728 -329.652122)
		(end 307.906674 -330.973176)
		(width 0.14732)
		(layer "In15.Cu")
		(net "P5E_CPU0_PE0_TX_DP<10>")
	)
	(segment
		(start 345.858084 -219.521532)
		(end 345.858084 -219.490544)
		(width 0.0889)
		(layer "In15.Cu")
		(net "P5E_CPU0_PE0_TX_DP<10>")
	)
	(segment
		(start 346.140278 -220.644212)
		(end 346.149168 -220.639132)
		(width 0.0889)
		(layer "In15.Cu")
		(net "P5E_CPU0_PE0_TX_DP<10>")
	)
	(segment
		(start 317.717424 -383.568448)
		(end 317.81877 -383.993644)
		(width 0.14732)
		(layer "In15.Cu")
		(net "P5E_CPU0_PE0_TX_DP<10>")
	)
	(segment
		(start 346.610432 -222.437198)
		(end 346.60967 -222.43669)
		(width 0.0889)
		(layer "In15.Cu")
		(net "P5E_CPU0_PE0_TX_DP<10>")
	)
	(segment
		(start 317.81877 -383.993644)
		(end 317.726822 -384.143758)
		(width 0.14732)
		(layer "In15.Cu")
		(net "P5E_CPU0_PE0_TX_DP<10>")
	)
	(segment
		(start 346.60967 -222.43669)
		(end 346.604336 -222.433642)
		(width 0.0889)
		(layer "In15.Cu")
		(net "P5E_CPU0_PE0_TX_DP<10>")
	)
	(segment
		(start 346.140278 -217.388694)
		(end 346.149168 -217.383614)
		(width 0.0889)
		(layer "In15.Cu")
		(net "P5E_CPU0_PE0_TX_DP<10>")
	)
	(segment
		(start 324.984872 -217.441018)
		(end 322.78955 -221.701614)
		(width 0.14732)
		(layer "In15.Cu")
		(net "P5E_CPU0_PE0_TX_DP<10>")
	)
	(segment
		(start 321.056762 -232.863644)
		(end 319.639188 -250.144788)
		(width 0.14732)
		(layer "In15.Cu")
		(net "P5E_CPU0_PE0_TX_DP<10>")
	)
	(segment
		(start 345.388184 -213.930484)
		(end 345.388184 -213.929722)
		(width 0.0889)
		(layer "In15.Cu")
		(net "P5E_CPU0_PE0_TX_DP<10>")
	)
	(segment
		(start 317.456566 -382.476248)
		(end 317.557912 -382.901444)
		(width 0.14732)
		(layer "In15.Cu")
		(net "P5E_CPU0_PE0_TX_DP<10>")
	)
	(segment
		(start 317.306198 -382.384046)
		(end 317.456566 -382.476248)
		(width 0.14732)
		(layer "In15.Cu")
		(net "P5E_CPU0_PE0_TX_DP<10>")
	)
	(segment
		(start 345.857576 -214.622634)
		(end 345.857576 -214.461344)
		(width 0.0889)
		(layer "In15.Cu")
		(net "P5E_CPU0_PE0_TX_DP<10>")
	)
	(segment
		(start 309.227728 -326.662542)
		(end 309.227728 -329.652122)
		(width 0.14732)
		(layer "In15.Cu")
		(net "P5E_CPU0_PE0_TX_DP<10>")
	)
	(segment
		(start 317.204852 -381.959358)
		(end 317.306198 -382.384046)
		(width 0.14732)
		(layer "In15.Cu")
		(net "P5E_CPU0_PE0_TX_DP<10>")
	)
	(segment
		(start 321.211448 -406.70988)
		(end 321.506088 -407.00452)
		(width 0.14732)
		(layer "In15.Cu")
		(net "P5E_CPU0_PE0_TX_DP<10>")
	)
	(segment
		(start 334.072992 -210.165442)
		(end 334.023716 -210.33105)
		(width 0.14732)
		(layer "In15.Cu")
		(net "P5E_CPU0_PE0_TX_DP<10>")
	)
	(segment
		(start 344.952828 -211.615782)
		(end 344.137996 -210.80095)
		(width 0.14732)
		(layer "In15.Cu")
		(net "P5E_CPU0_PE0_TX_DP<10>")
	)
	(segment
		(start 345.388438 -213.929468)
		(end 345.388438 -213.186772)
		(width 0.0889)
		(layer "In15.Cu")
		(net "P5E_CPU0_PE0_TX_DP<10>")
	)
	(segment
		(start 334.479138 -209.945478)
		(end 334.072992 -210.165442)
		(width 0.14732)
		(layer "In15.Cu")
		(net "P5E_CPU0_PE0_TX_DP<10>")
	)
	(segment
		(start 332.491334 -211.022184)
		(end 330.771754 -211.953602)
		(width 0.14732)
		(layer "In15.Cu")
		(net "P5E_CPU0_PE0_TX_DP<10>")
	)
	(segment
		(start 345.671394 -215.92667)
		(end 345.669108 -215.925146)
		(width 0.0889)
		(layer "In15.Cu")
		(net "P5E_CPU0_PE0_TX_DP<10>")
	)
	(segment
		(start 317.045086 -381.291846)
		(end 317.195454 -381.384048)
		(width 0.14732)
		(layer "In15.Cu")
		(net "P5E_CPU0_PE0_TX_DP<10>")
	)
	(segment
		(start 321.396868 -399.507202)
		(end 321.396868 -403.961854)
		(width 0.14732)
		(layer "In15.Cu")
		(net "P5E_CPU0_PE0_TX_DP<10>")
	)
	(segment
		(start 345.667838 -215.924384)
		(end 345.664536 -215.922606)
		(width 0.0889)
		(layer "In15.Cu")
		(net "P5E_CPU0_PE0_TX_DP<10>")
	)
	(segment
		(start 345.346274 -213.144608)
		(end 345.346274 -213.12251)
		(width 0.0889)
		(layer "In15.Cu")
		(net "P5E_CPU0_PE0_TX_DP<10>")
	)
	(segment
		(start 342.072976 -209.945478)
		(end 334.479138 -209.945478)
		(width 0.14732)
		(layer "In15.Cu")
		(net "P5E_CPU0_PE0_TX_DP<10>")
	)
	(segment
		(start 313.922156 -325.469758)
		(end 312.795412 -325.936356)
		(width 0.14732)
		(layer "In15.Cu")
		(net "P5E_CPU0_PE0_TX_DP<10>")
	)
	(segment
		(start 317.035942 -380.717298)
		(end 316.94374 -380.867158)
		(width 0.14732)
		(layer "In15.Cu")
		(net "P5E_CPU0_PE0_TX_DP<10>")
	)
	(segment
		(start 312.961528 -364.19917)
		(end 316.784228 -380.1999)
		(width 0.14732)
		(layer "In15.Cu")
		(net "P5E_CPU0_PE0_TX_DP<10>")
	)
	(segment
		(start 318.079882 -385.085844)
		(end 317.98768 -385.235958)
		(width 0.14732)
		(layer "In15.Cu")
		(net "P5E_CPU0_PE0_TX_DP<10>")
	)
	(segment
		(start 345.388438 -213.186772)
		(end 345.346274 -213.144608)
		(width 0.0889)
		(layer "In15.Cu")
		(net "P5E_CPU0_PE0_TX_DP<10>")
	)
	(segment
		(start 346.149168 -218.372944)
		(end 346.141294 -218.368372)
		(width 0.0889)
		(layer "In15.Cu")
		(net "P5E_CPU0_PE0_TX_DP<10>")
	)
	(segment
		(start 309.953914 -325.936356)
		(end 309.227728 -326.662542)
		(width 0.14732)
		(layer "In15.Cu")
		(net "P5E_CPU0_PE0_TX_DP<10>")
	)
	(segment
		(start 322.78955 -221.701614)
		(end 321.056762 -232.863644)
		(width 0.14732)
		(layer "In15.Cu")
		(net "P5E_CPU0_PE0_TX_DP<10>")
	)
	(segment
		(start 346.141294 -219.996004)
		(end 346.140278 -219.995496)
		(width 0.0889)
		(layer "In15.Cu")
		(net "P5E_CPU0_PE0_TX_DP<10>")
	)
	(segment
		(start 319.639188 -250.144788)
		(end 319.556384 -252.603254)
		(width 0.14732)
		(layer "In15.Cu")
		(net "P5E_CPU0_PE0_TX_DP<10>")
	)
	(segment
		(start 345.346274 -213.12251)
		(end 345.346274 -212.565234)
		(width 0.14732)
		(layer "In15.Cu")
		(net "P5E_CPU0_PE0_TX_DP<10>")
	)
	(segment
		(start 345.346274 -212.565234)
		(end 344.952828 -211.615782)
		(width 0.14732)
		(layer "In15.Cu")
		(net "P5E_CPU0_PE0_TX_DP<10>")
	)
	(segment
		(start 346.149168 -221.628462)
		(end 346.140278 -221.623382)
		(width 0.0889)
		(layer "In15.Cu")
		(net "P5E_CPU0_PE0_TX_DP<10>")
	)
	(segment
		(start 317.978536 -384.660648)
		(end 318.079882 -385.085844)
		(width 0.14732)
		(layer "In15.Cu")
		(net "P5E_CPU0_PE0_TX_DP<10>")
	)
	(segment
		(start 346.141294 -218.368372)
		(end 346.140278 -218.367864)
		(width 0.0889)
		(layer "In15.Cu")
		(net "P5E_CPU0_PE0_TX_DP<10>")
	)
	(segment
		(start 319.556384 -252.603254)
		(end 323.151246 -309.414926)
		(width 0.14732)
		(layer "In15.Cu")
		(net "P5E_CPU0_PE0_TX_DP<10>")
	)
	(segment
		(start 317.46571 -383.051558)
		(end 317.567056 -383.476246)
		(width 0.14732)
		(layer "In15.Cu")
		(net "P5E_CPU0_PE0_TX_DP<10>")
	)
	(segment
		(start 319.9384 -317.128144)
		(end 314.50915 -324.882764)
		(width 0.14732)
		(layer "In15.Cu")
		(net "P5E_CPU0_PE0_TX_DP<10>")
	)
	(segment
		(start 346.619322 -222.442278)
		(end 346.611956 -222.43796)
		(width 0.0889)
		(layer "In15.Cu")
		(net "P5E_CPU0_PE0_TX_DP<10>")
	)
	(segment
		(start 333.090012 -210.697826)
		(end 333.04099 -210.86318)
		(width 0.14732)
		(layer "In15.Cu")
		(net "P5E_CPU0_PE0_TX_DP<10>")
	)
	(segment
		(start 346.797884 -222.780098)
		(end 346.797884 -222.761556)
		(width 0.0889)
		(layer "In15.Cu")
		(net "P5E_CPU0_PE0_TX_DP<10>")
	)
	(segment
		(start 346.141294 -216.740486)
		(end 346.140278 -216.739978)
		(width 0.0889)
		(layer "In15.Cu")
		(net "P5E_CPU0_PE0_TX_DP<10>")
	)
	(segment
		(start 307.906674 -341.463884)
		(end 312.961528 -364.19917)
		(width 0.14732)
		(layer "In15.Cu")
		(net "P5E_CPU0_PE0_TX_DP<10>")
	)
	(segment
		(start 317.98768 -385.235958)
		(end 321.396868 -399.507202)
		(width 0.14732)
		(layer "In15.Cu")
		(net "P5E_CPU0_PE0_TX_DP<10>")
	)
	(segment
		(start 316.94374 -380.867158)
		(end 317.045086 -381.291846)
		(width 0.14732)
		(layer "In15.Cu")
		(net "P5E_CPU0_PE0_TX_DP<10>")
	)
	(segment
		(start 347.519498 -224.118424)
		(end 347.495368 -224.02927)
		(width 0.0889)
		(layer "In15.Cu")
		(net "P5E_CPU0_PE0_TX_DP<10>")
	)
	(segment
		(start 312.795412 -325.936356)
		(end 309.953914 -325.936356)
		(width 0.14732)
		(layer "In15.Cu")
		(net "P5E_CPU0_PE0_TX_DP<10>")
	)
	(segment
		(start 317.2968 -381.809244)
		(end 317.204852 -381.959358)
		(width 0.14732)
		(layer "In15.Cu")
		(net "P5E_CPU0_PE0_TX_DP<10>")
	)
	(segment
		(start 332.656434 -211.07146)
		(end 332.491334 -211.022184)
		(width 0.14732)
		(layer "In15.Cu")
		(net "P5E_CPU0_PE0_TX_DP<10>")
	)
	(segment
		(start 345.388184 -213.929722)
		(end 345.388438 -213.929468)
		(width 0.0889)
		(layer "In15.Cu")
		(net "P5E_CPU0_PE0_TX_DP<10>")
	)
	(segment
		(start 307.906674 -330.973176)
		(end 307.906674 -341.463884)
		(width 0.14732)
		(layer "In15.Cu")
		(net "P5E_CPU0_PE0_TX_DP<10>")
	)
	(segment
		(start 317.557912 -382.901444)
		(end 317.46571 -383.051558)
		(width 0.14732)
		(layer "In15.Cu")
		(net "P5E_CPU0_PE0_TX_DP<10>")
	)
	(segment
		(start 345.38793 -215.436704)
		(end 345.38793 -215.414606)
		(width 0.0889)
		(layer "In15.Cu")
		(net "P5E_CPU0_PE0_TX_DP<10>")
	)
	(segment
		(start 316.784228 -380.1999)
		(end 316.934342 -380.292102)
		(width 0.14732)
		(layer "In15.Cu")
		(net "P5E_CPU0_PE0_TX_DP<10>")
	)
	(segment
		(start 345.858084 -221.149418)
		(end 345.858084 -221.111826)
		(width 0.0889)
		(layer "In15.Cu")
		(net "P5E_CPU0_PE0_TX_DP<10>")
	)
	(arc
		(start 347.080332 -223.251268)
		(mid 346.878046 -223.052287)
		(end 346.797884 -222.780098)
		(width 0.0889)
		(layer "In15.Cu")
		(net "P5E_CPU0_PE0_TX_DP<10>")
	)
	(arc
		(start 346.149168 -220.639132)
		(mid 346.327886 -220.319854)
		(end 346.149168 -220.000576)
		(width 0.0889)
		(layer "In15.Cu")
		(net "P5E_CPU0_PE0_TX_DP<10>")
	)
	(arc
		(start 346.140278 -221.623382)
		(mid 345.937455 -221.423151)
		(end 345.858084 -221.149418)
		(width 0.0889)
		(layer "In15.Cu")
		(net "P5E_CPU0_PE0_TX_DP<10>")
	)
	(arc
		(start 346.797884 -222.761556)
		(mid 346.750205 -222.578656)
		(end 346.619322 -222.442278)
		(width 0.0889)
		(layer "In15.Cu")
		(net "P5E_CPU0_PE0_TX_DP<10>")
	)
	(arc
		(start 347.495368 -224.02927)
		(mid 347.327614 -223.829492)
		(end 347.26753 -223.575626)
		(width 0.0889)
		(layer "In15.Cu")
		(net "P5E_CPU0_PE0_TX_DP<10>")
	)
	(arc
		(start 345.857322 -214.637366)
		(mid 345.857519 -214.630001)
		(end 345.857576 -214.622634)
		(width 0.0889)
		(layer "In15.Cu")
		(net "P5E_CPU0_PE0_TX_DP<10>")
	)
	(arc
		(start 346.149168 -217.383614)
		(mid 346.327886 -217.064336)
		(end 346.149168 -216.745058)
		(width 0.0889)
		(layer "In15.Cu")
		(net "P5E_CPU0_PE0_TX_DP<10>")
	)
	(arc
		(start 345.858084 -216.25052)
		(mid 345.810405 -216.06762)
		(end 345.679522 -215.931242)
		(width 0.0889)
		(layer "In15.Cu")
		(net "P5E_CPU0_PE0_TX_DP<10>")
	)
	(arc
		(start 345.403424 -213.969346)
		(mid 345.395461 -213.950049)
		(end 345.388184 -213.930484)
		(width 0.0889)
		(layer "In15.Cu")
		(net "P5E_CPU0_PE0_TX_DP<10>")
	)
	(arc
		(start 346.32773 -221.94774)
		(mid 346.280051 -221.76484)
		(end 346.149168 -221.628462)
		(width 0.0889)
		(layer "In15.Cu")
		(net "P5E_CPU0_PE0_TX_DP<10>")
	)
	(arc
		(start 346.140278 -218.367864)
		(mid 345.937455 -218.167633)
		(end 345.858084 -217.8939)
		(width 0.0889)
		(layer "In15.Cu")
		(net "P5E_CPU0_PE0_TX_DP<10>")
	)
	(arc
		(start 345.858084 -221.111826)
		(mid 345.938995 -220.841698)
		(end 346.140278 -220.644212)
		(width 0.0889)
		(layer "In15.Cu")
		(net "P5E_CPU0_PE0_TX_DP<10>")
	)
	(arc
		(start 345.664536 -215.922606)
		(mid 345.461949 -215.716255)
		(end 345.38793 -215.436704)
		(width 0.0889)
		(layer "In15.Cu")
		(net "P5E_CPU0_PE0_TX_DP<10>")
	)
	(arc
		(start 347.26753 -223.56699)
		(mid 347.21526 -223.384625)
		(end 347.080332 -223.251268)
		(width 0.0889)
		(layer "In15.Cu")
		(net "P5E_CPU0_PE0_TX_DP<10>")
	)
	(arc
		(start 345.857576 -214.461344)
		(mid 345.782571 -214.345885)
		(end 345.673426 -214.261954)
		(width 0.0889)
		(layer "In15.Cu")
		(net "P5E_CPU0_PE0_TX_DP<10>")
	)
	(arc
		(start 345.679014 -214.941912)
		(mid 345.806268 -214.811946)
		(end 345.857322 -214.637366)
		(width 0.0889)
		(layer "In15.Cu")
		(net "P5E_CPU0_PE0_TX_DP<10>")
	)
	(arc
		(start 346.149168 -219.0115)
		(mid 346.327644 -218.692222)
		(end 346.149168 -218.372944)
		(width 0.0889)
		(layer "In15.Cu")
		(net "P5E_CPU0_PE0_TX_DP<10>")
	)
	(arc
		(start 345.38793 -215.414606)
		(mid 345.468841 -215.144478)
		(end 345.670124 -214.946992)
		(width 0.0889)
		(layer "In15.Cu")
		(net "P5E_CPU0_PE0_TX_DP<10>")
	)
	(arc
		(start 346.604336 -222.433642)
		(mid 346.401749 -222.227291)
		(end 346.32773 -221.94774)
		(width 0.0889)
		(layer "In15.Cu")
		(net "P5E_CPU0_PE0_TX_DP<10>")
	)
	(arc
		(start 346.140278 -219.995496)
		(mid 345.937455 -219.795265)
		(end 345.858084 -219.521532)
		(width 0.0889)
		(layer "In15.Cu")
		(net "P5E_CPU0_PE0_TX_DP<10>")
	)
	(arc
		(start 345.858084 -219.490544)
		(mid 345.937454 -219.21681)
		(end 346.140278 -219.01658)
		(width 0.0889)
		(layer "In15.Cu")
		(net "P5E_CPU0_PE0_TX_DP<10>")
	)
	(arc
		(start 346.140278 -216.739978)
		(mid 345.937455 -216.539747)
		(end 345.858084 -216.266014)
		(width 0.0889)
		(layer "In15.Cu")
		(net "P5E_CPU0_PE0_TX_DP<10>")
	)
	(arc
		(start 345.673426 -214.261954)
		(mid 345.513354 -214.138774)
		(end 345.403424 -213.969346)
		(width 0.0889)
		(layer "In15.Cu")
		(net "P5E_CPU0_PE0_TX_DP<10>")
	)
	(arc
		(start 345.858084 -217.856308)
		(mid 345.938995 -217.58618)
		(end 346.140278 -217.388694)
		(width 0.0889)
		(layer "In15.Cu")
		(net "P5E_CPU0_PE0_TX_DP<10>")
	)
	(segment
		(start 351.83953 -407.303478)
		(end 351.83953 -407.926286)
		(width 0.13208)
		(layer "F.Cu")
		(net "P5E_CPU0_PE0_TX_DP<0>")
	)
	(segment
		(start 351.83953 -407.926286)
		(end 352.163888 -408.250644)
		(width 0.13208)
		(layer "F.Cu")
		(net "P5E_CPU0_PE0_TX_DP<0>")
	)
	(segment
		(start 337.96478 -224.389696)
		(end 337.965034 -224.389442)
		(width 0.13208)
		(layer "F.Cu")
		(net "P5E_CPU0_PE0_TX_DP<0>")
	)
	(segment
		(start 352.138488 -407.00452)
		(end 351.83953 -407.303478)
		(width 0.13208)
		(layer "F.Cu")
		(net "P5E_CPU0_PE0_TX_DP<0>")
	)
	(segment
		(start 337.96478 -224.925382)
		(end 337.96478 -224.389696)
		(width 0.13208)
		(layer "F.Cu")
		(net "P5E_CPU0_PE0_TX_DP<0>")
	)
	(segment
		(start 330.083414 -266.662408)
		(end 332.880716 -311.154318)
		(width 0.14732)
		(layer "In15.Cu")
		(net "P5E_CPU0_PE0_TX_DP<0>")
	)
	(segment
		(start 337.36026 -380.778512)
		(end 337.534758 -380.801118)
		(width 0.14732)
		(layer "In15.Cu")
		(net "P5E_CPU0_PE0_TX_DP<0>")
	)
	(segment
		(start 337.965034 -224.389442)
		(end 338.121498 -224.118424)
		(width 0.0889)
		(layer "In15.Cu")
		(net "P5E_CPU0_PE0_TX_DP<0>")
	)
	(segment
		(start 335.350104 -228.1936)
		(end 334.987138 -228.556566)
		(width 0.0889)
		(layer "In15.Cu")
		(net "P5E_CPU0_PE0_TX_DP<0>")
	)
	(segment
		(start 339.804248 -383.751074)
		(end 340.071202 -384.097276)
		(width 0.14732)
		(layer "In15.Cu")
		(net "P5E_CPU0_PE0_TX_DP<0>")
	)
	(segment
		(start 333.718916 -249.632724)
		(end 334.046576 -249.960384)
		(width 0.14732)
		(layer "In15.Cu")
		(net "P5E_CPU0_PE0_TX_DP<0>")
	)
	(segment
		(start 339.172296 -382.92659)
		(end 339.14969 -383.101088)
		(width 0.14732)
		(layer "In15.Cu")
		(net "P5E_CPU0_PE0_TX_DP<0>")
	)
	(segment
		(start 331.467714 -234.554522)
		(end 331.35062 -234.681268)
		(width 0.14732)
		(layer "In15.Cu")
		(net "P5E_CPU0_PE0_TX_DP<0>")
	)
	(segment
		(start 317.352426 -340.463378)
		(end 321.835018 -360.628692)
		(width 0.14732)
		(layer "In15.Cu")
		(net "P5E_CPU0_PE0_TX_DP<0>")
	)
	(segment
		(start 331.323442 -234.000802)
		(end 331.450188 -234.117896)
		(width 0.14732)
		(layer "In15.Cu")
		(net "P5E_CPU0_PE0_TX_DP<0>")
	)
	(segment
		(start 351.784666 -399.499836)
		(end 352.029268 -400.218148)
		(width 0.14732)
		(layer "In15.Cu")
		(net "P5E_CPU0_PE0_TX_DP<0>")
	)
	(segment
		(start 337.779106 -381.322072)
		(end 338.045552 -381.66802)
		(width 0.14732)
		(layer "In15.Cu")
		(net "P5E_CPU0_PE0_TX_DP<0>")
	)
	(segment
		(start 340.071202 -384.097276)
		(end 340.049104 -384.268218)
		(width 0.14732)
		(layer "In15.Cu")
		(net "P5E_CPU0_PE0_TX_DP<0>")
	)
	(segment
		(start 340.049104 -384.268218)
		(end 351.784666 -399.499836)
		(width 0.14732)
		(layer "In15.Cu")
		(net "P5E_CPU0_PE0_TX_DP<0>")
	)
	(segment
		(start 333.454756 -255.375918)
		(end 333.18323 -256.031238)
		(width 0.14732)
		(layer "In15.Cu")
		(net "P5E_CPU0_PE0_TX_DP<0>")
	)
	(segment
		(start 332.959202 -230.6447)
		(end 331.672946 -232.62717)
		(width 0.14732)
		(layer "In15.Cu")
		(net "P5E_CPU0_PE0_TX_DP<0>")
	)
	(segment
		(start 333.273908 -254.350774)
		(end 333.454756 -255.375918)
		(width 0.14732)
		(layer "In15.Cu")
		(net "P5E_CPU0_PE0_TX_DP<0>")
	)
	(segment
		(start 331.100684 -260.166104)
		(end 330.083414 -266.662408)
		(width 0.14732)
		(layer "In15.Cu")
		(net "P5E_CPU0_PE0_TX_DP<0>")
	)
	(segment
		(start 334.987138 -228.556566)
		(end 334.987138 -228.61651)
		(width 0.0889)
		(layer "In15.Cu")
		(net "P5E_CPU0_PE0_TX_DP<0>")
	)
	(segment
		(start 331.30617 -233.56443)
		(end 331.323442 -234.000802)
		(width 0.14732)
		(layer "In15.Cu")
		(net "P5E_CPU0_PE0_TX_DP<0>")
	)
	(segment
		(start 331.35062 -234.681268)
		(end 331.502004 -238.491268)
		(width 0.14732)
		(layer "In15.Cu")
		(net "P5E_CPU0_PE0_TX_DP<0>")
	)
	(segment
		(start 352.029268 -400.218148)
		(end 352.029268 -403.961854)
		(width 0.14732)
		(layer "In15.Cu")
		(net "P5E_CPU0_PE0_TX_DP<0>")
	)
	(segment
		(start 337.310476 -224.877122)
		(end 337.307682 -224.8789)
		(width 0.0889)
		(layer "In15.Cu")
		(net "P5E_CPU0_PE0_TX_DP<0>")
	)
	(segment
		(start 333.18323 -256.031238)
		(end 332.423008 -256.791714)
		(width 0.14732)
		(layer "In15.Cu")
		(net "P5E_CPU0_PE0_TX_DP<0>")
	)
	(segment
		(start 352.029268 -403.961854)
		(end 351.843848 -405.845264)
		(width 0.14732)
		(layer "In15.Cu")
		(net "P5E_CPU0_PE0_TX_DP<0>")
	)
	(segment
		(start 317.352426 -335.842864)
		(end 317.352426 -340.463378)
		(width 0.14732)
		(layer "In15.Cu")
		(net "P5E_CPU0_PE0_TX_DP<0>")
	)
	(segment
		(start 334.987138 -228.61651)
		(end 334.971644 -228.632004)
		(width 0.0889)
		(layer "In15.Cu")
		(net "P5E_CPU0_PE0_TX_DP<0>")
	)
	(segment
		(start 334.046576 -250.858782)
		(end 333.95666 -251.36983)
		(width 0.14732)
		(layer "In15.Cu")
		(net "P5E_CPU0_PE0_TX_DP<0>")
	)
	(segment
		(start 338.22005 -381.690626)
		(end 338.487004 -382.037082)
		(width 0.14732)
		(layer "In15.Cu")
		(net "P5E_CPU0_PE0_TX_DP<0>")
	)
	(segment
		(start 338.121498 -224.118424)
		(end 338.100416 -224.040446)
		(width 0.0889)
		(layer "In15.Cu")
		(net "P5E_CPU0_PE0_TX_DP<0>")
	)
	(segment
		(start 337.801712 -381.147574)
		(end 337.779106 -381.322072)
		(width 0.14732)
		(layer "In15.Cu")
		(net "P5E_CPU0_PE0_TX_DP<0>")
	)
	(segment
		(start 328.222356 -322.211192)
		(end 321.772026 -331.423264)
		(width 0.14732)
		(layer "In15.Cu")
		(net "P5E_CPU0_PE0_TX_DP<0>")
	)
	(segment
		(start 331.450188 -234.117896)
		(end 331.467714 -234.554522)
		(width 0.14732)
		(layer "In15.Cu")
		(net "P5E_CPU0_PE0_TX_DP<0>")
	)
	(segment
		(start 333.718916 -247.810782)
		(end 333.718916 -249.632724)
		(width 0.14732)
		(layer "In15.Cu")
		(net "P5E_CPU0_PE0_TX_DP<0>")
	)
	(segment
		(start 333.95666 -251.36983)
		(end 333.377286 -252.197362)
		(width 0.14732)
		(layer "In15.Cu")
		(net "P5E_CPU0_PE0_TX_DP<0>")
	)
	(segment
		(start 338.905342 -382.580134)
		(end 339.172296 -382.92659)
		(width 0.14732)
		(layer "In15.Cu")
		(net "P5E_CPU0_PE0_TX_DP<0>")
	)
	(segment
		(start 334.971644 -228.632004)
		(end 332.959202 -230.6447)
		(width 0.14732)
		(layer "In15.Cu")
		(net "P5E_CPU0_PE0_TX_DP<0>")
	)
	(segment
		(start 335.710784 -227.64496)
		(end 335.710784 -227.659184)
		(width 0.0889)
		(layer "In15.Cu")
		(net "P5E_CPU0_PE0_TX_DP<0>")
	)
	(segment
		(start 338.464398 -382.21158)
		(end 338.730844 -382.557528)
		(width 0.14732)
		(layer "In15.Cu")
		(net "P5E_CPU0_PE0_TX_DP<0>")
	)
	(segment
		(start 339.14969 -383.101088)
		(end 339.633306 -383.728722)
		(width 0.14732)
		(layer "In15.Cu")
		(net "P5E_CPU0_PE0_TX_DP<0>")
	)
	(segment
		(start 338.487004 -382.037082)
		(end 338.464398 -382.21158)
		(width 0.14732)
		(layer "In15.Cu")
		(net "P5E_CPU0_PE0_TX_DP<0>")
	)
	(segment
		(start 331.502004 -238.491268)
		(end 331.697584 -243.417852)
		(width 0.14732)
		(layer "In15.Cu")
		(net "P5E_CPU0_PE0_TX_DP<0>")
	)
	(segment
		(start 333.377286 -252.197362)
		(end 333.273908 -252.7808)
		(width 0.14732)
		(layer "In15.Cu")
		(net "P5E_CPU0_PE0_TX_DP<0>")
	)
	(segment
		(start 333.273908 -252.7808)
		(end 333.273908 -254.350774)
		(width 0.14732)
		(layer "In15.Cu")
		(net "P5E_CPU0_PE0_TX_DP<0>")
	)
	(segment
		(start 338.045552 -381.66802)
		(end 338.22005 -381.690626)
		(width 0.14732)
		(layer "In15.Cu")
		(net "P5E_CPU0_PE0_TX_DP<0>")
	)
	(segment
		(start 337.120484 -225.194622)
		(end 337.120484 -225.2218)
		(width 0.0889)
		(layer "In15.Cu")
		(net "P5E_CPU0_PE0_TX_DP<0>")
	)
	(segment
		(start 332.880716 -311.154318)
		(end 328.222356 -322.211192)
		(width 0.14732)
		(layer "In15.Cu")
		(net "P5E_CPU0_PE0_TX_DP<0>")
	)
	(segment
		(start 339.633306 -383.728722)
		(end 339.804248 -383.751074)
		(width 0.14732)
		(layer "In15.Cu")
		(net "P5E_CPU0_PE0_TX_DP<0>")
	)
	(segment
		(start 334.046576 -249.960384)
		(end 334.046576 -250.858782)
		(width 0.14732)
		(layer "In15.Cu")
		(net "P5E_CPU0_PE0_TX_DP<0>")
	)
	(segment
		(start 336.180684 -226.822508)
		(end 336.180684 -226.84105)
		(width 0.0889)
		(layer "In15.Cu")
		(net "P5E_CPU0_PE0_TX_DP<0>")
	)
	(segment
		(start 331.697584 -243.417852)
		(end 333.718916 -247.810782)
		(width 0.14732)
		(layer "In15.Cu")
		(net "P5E_CPU0_PE0_TX_DP<0>")
	)
	(segment
		(start 335.898236 -227.320602)
		(end 335.889346 -227.325682)
		(width 0.0889)
		(layer "In15.Cu")
		(net "P5E_CPU0_PE0_TX_DP<0>")
	)
	(segment
		(start 336.368644 -226.506278)
		(end 336.367882 -226.506786)
		(width 0.0889)
		(layer "In15.Cu")
		(net "P5E_CPU0_PE0_TX_DP<0>")
	)
	(segment
		(start 321.772026 -331.423264)
		(end 317.352426 -335.842864)
		(width 0.14732)
		(layer "In15.Cu")
		(net "P5E_CPU0_PE0_TX_DP<0>")
	)
	(segment
		(start 337.311492 -224.876614)
		(end 337.310476 -224.877122)
		(width 0.0889)
		(layer "In15.Cu")
		(net "P5E_CPU0_PE0_TX_DP<0>")
	)
	(segment
		(start 332.423008 -256.791714)
		(end 331.100684 -260.166104)
		(width 0.14732)
		(layer "In15.Cu")
		(net "P5E_CPU0_PE0_TX_DP<0>")
	)
	(segment
		(start 337.534758 -380.801118)
		(end 337.801712 -381.147574)
		(width 0.14732)
		(layer "In15.Cu")
		(net "P5E_CPU0_PE0_TX_DP<0>")
	)
	(segment
		(start 351.843848 -406.70988)
		(end 352.138488 -407.00452)
		(width 0.14732)
		(layer "In15.Cu")
		(net "P5E_CPU0_PE0_TX_DP<0>")
	)
	(segment
		(start 321.835018 -360.628692)
		(end 337.36026 -380.778512)
		(width 0.14732)
		(layer "In15.Cu")
		(net "P5E_CPU0_PE0_TX_DP<0>")
	)
	(segment
		(start 336.838036 -225.69297)
		(end 336.829146 -225.69805)
		(width 0.0889)
		(layer "In15.Cu")
		(net "P5E_CPU0_PE0_TX_DP<0>")
	)
	(segment
		(start 331.672946 -232.62717)
		(end 331.30617 -233.56443)
		(width 0.14732)
		(layer "In15.Cu")
		(net "P5E_CPU0_PE0_TX_DP<0>")
	)
	(segment
		(start 351.843848 -405.845264)
		(end 351.843848 -406.70988)
		(width 0.14732)
		(layer "In15.Cu")
		(net "P5E_CPU0_PE0_TX_DP<0>")
	)
	(segment
		(start 336.373978 -226.50323)
		(end 336.368644 -226.506278)
		(width 0.0889)
		(layer "In15.Cu")
		(net "P5E_CPU0_PE0_TX_DP<0>")
	)
	(segment
		(start 337.313778 -224.875344)
		(end 337.311492 -224.876614)
		(width 0.0889)
		(layer "In15.Cu")
		(net "P5E_CPU0_PE0_TX_DP<0>")
	)
	(segment
		(start 338.730844 -382.557528)
		(end 338.905342 -382.580134)
		(width 0.14732)
		(layer "In15.Cu")
		(net "P5E_CPU0_PE0_TX_DP<0>")
	)
	(segment
		(start 337.777836 -224.065084)
		(end 337.768946 -224.070164)
		(width 0.0889)
		(layer "In15.Cu")
		(net "P5E_CPU0_PE0_TX_DP<0>")
	)
	(arc
		(start 336.180684 -226.84105)
		(mid 336.102573 -227.117999)
		(end 335.898236 -227.320602)
		(width 0.0889)
		(layer "In15.Cu")
		(net "P5E_CPU0_PE0_TX_DP<0>")
	)
	(arc
		(start 337.307682 -224.8789)
		(mid 337.172749 -225.012254)
		(end 337.120484 -225.194622)
		(width 0.0889)
		(layer "In15.Cu")
		(net "P5E_CPU0_PE0_TX_DP<0>")
	)
	(arc
		(start 335.710784 -227.659184)
		(mid 335.631643 -227.933807)
		(end 335.428336 -228.134672)
		(width 0.0889)
		(layer "In15.Cu")
		(net "P5E_CPU0_PE0_TX_DP<0>")
	)
	(arc
		(start 336.650584 -226.017328)
		(mid 336.576593 -226.296894)
		(end 336.373978 -226.50323)
		(width 0.0889)
		(layer "In15.Cu")
		(net "P5E_CPU0_PE0_TX_DP<0>")
	)
	(arc
		(start 335.428336 -228.134672)
		(mid 335.387278 -228.161559)
		(end 335.350104 -228.1936)
		(width 0.0889)
		(layer "In15.Cu")
		(net "P5E_CPU0_PE0_TX_DP<0>")
	)
	(arc
		(start 335.889346 -227.325682)
		(mid 335.758432 -227.462042)
		(end 335.710784 -227.64496)
		(width 0.0889)
		(layer "In15.Cu")
		(net "P5E_CPU0_PE0_TX_DP<0>")
	)
	(arc
		(start 337.768946 -224.070164)
		(mid 337.638032 -224.206524)
		(end 337.590384 -224.389442)
		(width 0.0889)
		(layer "In15.Cu")
		(net "P5E_CPU0_PE0_TX_DP<0>")
	)
	(arc
		(start 337.590384 -224.389442)
		(mid 337.516393 -224.669008)
		(end 337.313778 -224.875344)
		(width 0.0889)
		(layer "In15.Cu")
		(net "P5E_CPU0_PE0_TX_DP<0>")
	)
	(arc
		(start 336.367882 -226.506786)
		(mid 336.232949 -226.64014)
		(end 336.180684 -226.822508)
		(width 0.0889)
		(layer "In15.Cu")
		(net "P5E_CPU0_PE0_TX_DP<0>")
	)
	(arc
		(start 337.120484 -225.2218)
		(mid 337.040322 -225.493989)
		(end 336.838036 -225.69297)
		(width 0.0889)
		(layer "In15.Cu")
		(net "P5E_CPU0_PE0_TX_DP<0>")
	)
	(arc
		(start 336.829146 -225.69805)
		(mid 336.698232 -225.83441)
		(end 336.650584 -226.017328)
		(width 0.0889)
		(layer "In15.Cu")
		(net "P5E_CPU0_PE0_TX_DP<0>")
	)
	(arc
		(start 338.100416 -224.040446)
		(mid 337.93632 -224.016099)
		(end 337.777836 -224.065084)
		(width 0.0889)
		(layer "In15.Cu")
		(net "P5E_CPU0_PE0_TX_DP<0>")
	)
	(segment
		(start 346.42298 -224.389696)
		(end 346.423234 -224.389442)
		(width 0.13208)
		(layer "F.Cu")
		(net "P5E_CPU0_PE0_TX_DN<9>")
	)
	(segment
		(start 346.42298 -224.925382)
		(end 346.42298 -224.389696)
		(width 0.13208)
		(layer "F.Cu")
		(net "P5E_CPU0_PE0_TX_DN<9>")
	)
	(segment
		(start 323.6849 -408.250644)
		(end 323.680328 -408.250644)
		(width 0.13208)
		(layer "F.Cu")
		(net "P5E_CPU0_PE0_TX_DN<9>")
	)
	(segment
		(start 323.705728 -407.00452)
		(end 324.01129 -407.310082)
		(width 0.13208)
		(layer "F.Cu")
		(net "P5E_CPU0_PE0_TX_DN<9>")
	)
	(segment
		(start 324.01129 -407.924254)
		(end 323.6849 -408.250644)
		(width 0.13208)
		(layer "F.Cu")
		(net "P5E_CPU0_PE0_TX_DN<9>")
	)
	(segment
		(start 324.01129 -407.310082)
		(end 324.01129 -407.924254)
		(width 0.13208)
		(layer "F.Cu")
		(net "P5E_CPU0_PE0_TX_DN<9>")
	)
	(segment
		(start 313.59475 -364.026196)
		(end 318.995806 -382.346708)
		(width 0.14732)
		(layer "In15.Cu")
		(net "P5E_CPU0_PE0_TX_DN<9>")
	)
	(segment
		(start 323.872606 -309.54091)
		(end 320.570352 -317.407036)
		(width 0.14732)
		(layer "In15.Cu")
		(net "P5E_CPU0_PE0_TX_DN<9>")
	)
	(segment
		(start 344.449654 -212.138768)
		(end 343.692988 -211.382102)
		(width 0.14732)
		(layer "In15.Cu")
		(net "P5E_CPU0_PE0_TX_DN<9>")
	)
	(segment
		(start 344.638884 -213.893908)
		(end 344.638884 -213.186518)
		(width 0.0889)
		(layer "In15.Cu")
		(net "P5E_CPU0_PE0_TX_DN<9>")
	)
	(segment
		(start 320.570352 -317.407036)
		(end 315.016642 -325.337424)
		(width 0.14732)
		(layer "In15.Cu")
		(net "P5E_CPU0_PE0_TX_DN<9>")
	)
	(segment
		(start 344.638884 -213.186518)
		(end 344.680794 -213.144608)
		(width 0.0889)
		(layer "In15.Cu")
		(net "P5E_CPU0_PE0_TX_DN<9>")
	)
	(segment
		(start 344.82278 -215.75903)
		(end 344.821764 -215.758522)
		(width 0.0889)
		(layer "In15.Cu")
		(net "P5E_CPU0_PE0_TX_DN<9>")
	)
	(segment
		(start 344.817192 -215.117426)
		(end 344.826082 -215.112346)
		(width 0.0889)
		(layer "In15.Cu")
		(net "P5E_CPU0_PE0_TX_DN<9>")
	)
	(segment
		(start 346.236036 -224.065084)
		(end 346.242132 -224.061528)
		(width 0.0889)
		(layer "In15.Cu")
		(net "P5E_CPU0_PE0_TX_DN<9>")
	)
	(segment
		(start 345.296236 -219.830396)
		(end 345.287346 -219.825316)
		(width 0.0889)
		(layer "In15.Cu")
		(net "P5E_CPU0_PE0_TX_DN<9>")
	)
	(segment
		(start 320.257678 -252.724666)
		(end 323.872606 -309.54091)
		(width 0.14732)
		(layer "In15.Cu")
		(net "P5E_CPU0_PE0_TX_DN<9>")
	)
	(segment
		(start 308.642258 -331.712062)
		(end 308.642004 -331.712062)
		(width 0.14732)
		(layer "In15.Cu")
		(net "P5E_CPU0_PE0_TX_DN<9>")
	)
	(segment
		(start 346.423234 -224.389442)
		(end 346.579698 -224.66046)
		(width 0.0889)
		(layer "In15.Cu")
		(net "P5E_CPU0_PE0_TX_DN<9>")
	)
	(segment
		(start 318.995806 -382.346708)
		(end 318.99606 -382.34747)
		(width 0.14732)
		(layer "In15.Cu")
		(net "P5E_CPU0_PE0_TX_DN<9>")
	)
	(segment
		(start 344.821764 -215.758522)
		(end 344.820494 -215.75776)
		(width 0.0889)
		(layer "In15.Cu")
		(net "P5E_CPU0_PE0_TX_DN<9>")
	)
	(segment
		(start 346.048838 -222.751396)
		(end 346.048584 -222.761556)
		(width 0.0889)
		(layer "In15.Cu")
		(net "P5E_CPU0_PE0_TX_DN<9>")
	)
	(segment
		(start 334.87106 -210.722718)
		(end 330.952856 -212.845142)
		(width 0.14732)
		(layer "In15.Cu")
		(net "P5E_CPU0_PE0_TX_DN<9>")
	)
	(segment
		(start 346.579698 -224.66046)
		(end 346.558616 -224.738438)
		(width 0.0889)
		(layer "In15.Cu")
		(net "P5E_CPU0_PE0_TX_DN<9>")
	)
	(segment
		(start 345.57843 -221.94774)
		(end 345.57843 -221.932246)
		(width 0.0889)
		(layer "In15.Cu")
		(net "P5E_CPU0_PE0_TX_DN<9>")
	)
	(segment
		(start 319.818766 -385.138168)
		(end 324.185788 -399.951702)
		(width 0.14732)
		(layer "In15.Cu")
		(net "P5E_CPU0_PE0_TX_DN<9>")
	)
	(segment
		(start 345.57843 -218.707716)
		(end 345.57843 -218.676728)
		(width 0.0889)
		(layer "In15.Cu")
		(net "P5E_CPU0_PE0_TX_DN<9>")
	)
	(segment
		(start 344.818462 -215.756744)
		(end 344.817192 -215.755982)
		(width 0.0889)
		(layer "In15.Cu")
		(net "P5E_CPU0_PE0_TX_DN<9>")
	)
	(segment
		(start 320.34353 -250.17476)
		(end 320.257678 -252.724666)
		(width 0.14732)
		(layer "In15.Cu")
		(net "P5E_CPU0_PE0_TX_DN<9>")
	)
	(segment
		(start 319.818512 -385.137406)
		(end 319.818766 -385.138168)
		(width 0.14732)
		(layer "In15.Cu")
		(net "P5E_CPU0_PE0_TX_DN<9>")
	)
	(segment
		(start 345.287346 -217.559128)
		(end 345.296236 -217.554048)
		(width 0.0889)
		(layer "In15.Cu")
		(net "P5E_CPU0_PE0_TX_DN<9>")
	)
	(segment
		(start 330.952856 -212.845142)
		(end 325.562722 -217.833194)
		(width 0.14732)
		(layer "In15.Cu")
		(net "P5E_CPU0_PE0_TX_DN<9>")
	)
	(segment
		(start 345.287346 -219.18676)
		(end 345.296236 -219.18168)
		(width 0.0889)
		(layer "In15.Cu")
		(net "P5E_CPU0_PE0_TX_DN<9>")
	)
	(segment
		(start 324.000368 -405.831548)
		(end 324.000368 -406.70988)
		(width 0.14732)
		(layer "In15.Cu")
		(net "P5E_CPU0_PE0_TX_DN<9>")
	)
	(segment
		(start 346.227146 -224.070164)
		(end 346.236036 -224.065084)
		(width 0.0889)
		(layer "In15.Cu")
		(net "P5E_CPU0_PE0_TX_DN<9>")
	)
	(segment
		(start 344.820494 -215.75776)
		(end 344.818462 -215.756744)
		(width 0.0889)
		(layer "In15.Cu")
		(net "P5E_CPU0_PE0_TX_DN<9>")
	)
	(segment
		(start 342.100662 -210.722718)
		(end 334.87106 -210.722718)
		(width 0.14732)
		(layer "In15.Cu")
		(net "P5E_CPU0_PE0_TX_DN<9>")
	)
	(segment
		(start 345.296236 -221.458282)
		(end 345.287346 -221.453202)
		(width 0.0889)
		(layer "In15.Cu")
		(net "P5E_CPU0_PE0_TX_DN<9>")
	)
	(segment
		(start 324.185788 -399.951702)
		(end 324.185788 -403.948138)
		(width 0.14732)
		(layer "In15.Cu")
		(net "P5E_CPU0_PE0_TX_DN<9>")
	)
	(segment
		(start 345.108276 -214.644732)
		(end 345.108276 -214.424768)
		(width 0.0889)
		(layer "In15.Cu")
		(net "P5E_CPU0_PE0_TX_DN<9>")
	)
	(segment
		(start 346.236036 -224.7138)
		(end 346.227146 -224.70872)
		(width 0.0889)
		(layer "In15.Cu")
		(net "P5E_CPU0_PE0_TX_DN<9>")
	)
	(segment
		(start 318.99606 -382.34747)
		(end 319.501012 -384.060446)
		(width 0.14732)
		(layer "In15.Cu")
		(net "P5E_CPU0_PE0_TX_DN<9>")
	)
	(segment
		(start 344.680794 -212.69706)
		(end 344.449654 -212.138768)
		(width 0.14732)
		(layer "In15.Cu")
		(net "P5E_CPU0_PE0_TX_DN<9>")
	)
	(segment
		(start 321.788028 -232.98658)
		(end 320.34353 -250.17476)
		(width 0.14732)
		(layer "In15.Cu")
		(net "P5E_CPU0_PE0_TX_DN<9>")
	)
	(segment
		(start 315.016642 -325.337424)
		(end 308.642258 -331.712062)
		(width 0.14732)
		(layer "In15.Cu")
		(net "P5E_CPU0_PE0_TX_DN<9>")
	)
	(segment
		(start 323.527674 -221.782132)
		(end 321.788028 -232.98658)
		(width 0.14732)
		(layer "In15.Cu")
		(net "P5E_CPU0_PE0_TX_DN<9>")
	)
	(segment
		(start 344.680794 -213.12251)
		(end 344.680794 -212.69706)
		(width 0.14732)
		(layer "In15.Cu")
		(net "P5E_CPU0_PE0_TX_DN<9>")
	)
	(segment
		(start 319.501266 -384.061208)
		(end 319.818512 -385.137406)
		(width 0.14732)
		(layer "In15.Cu")
		(net "P5E_CPU0_PE0_TX_DN<9>")
	)
	(segment
		(start 308.642004 -331.712062)
		(end 308.561994 -331.792326)
		(width 0.14732)
		(layer "In15.Cu")
		(net "P5E_CPU0_PE0_TX_DN<9>")
	)
	(segment
		(start 344.826082 -215.761062)
		(end 344.82532 -215.760554)
		(width 0.0889)
		(layer "In15.Cu")
		(net "P5E_CPU0_PE0_TX_DN<9>")
	)
	(segment
		(start 345.296236 -218.202764)
		(end 345.287346 -218.197684)
		(width 0.0889)
		(layer "In15.Cu")
		(net "P5E_CPU0_PE0_TX_DN<9>")
	)
	(segment
		(start 308.561994 -331.792326)
		(end 308.561994 -341.382096)
		(width 0.14732)
		(layer "In15.Cu")
		(net "P5E_CPU0_PE0_TX_DN<9>")
	)
	(segment
		(start 344.680794 -213.144608)
		(end 344.680794 -213.12251)
		(width 0.0889)
		(layer "In15.Cu")
		(net "P5E_CPU0_PE0_TX_DN<9>")
	)
	(segment
		(start 325.562722 -217.833194)
		(end 323.527674 -221.782132)
		(width 0.14732)
		(layer "In15.Cu")
		(net "P5E_CPU0_PE0_TX_DN<9>")
	)
	(segment
		(start 344.828876 -215.762586)
		(end 344.826082 -215.761062)
		(width 0.0889)
		(layer "In15.Cu")
		(net "P5E_CPU0_PE0_TX_DN<9>")
	)
	(segment
		(start 345.771978 -222.275654)
		(end 345.756992 -222.267018)
		(width 0.0889)
		(layer "In15.Cu")
		(net "P5E_CPU0_PE0_TX_DN<9>")
	)
	(segment
		(start 344.832178 -215.764618)
		(end 344.828876 -215.762586)
		(width 0.0889)
		(layer "In15.Cu")
		(net "P5E_CPU0_PE0_TX_DN<9>")
	)
	(segment
		(start 345.287346 -220.814646)
		(end 345.296236 -220.809566)
		(width 0.0889)
		(layer "In15.Cu")
		(net "P5E_CPU0_PE0_TX_DN<9>")
	)
	(segment
		(start 324.185788 -403.948138)
		(end 324.000368 -405.831548)
		(width 0.14732)
		(layer "In15.Cu")
		(net "P5E_CPU0_PE0_TX_DN<9>")
	)
	(segment
		(start 343.692988 -211.382102)
		(end 342.100662 -210.722718)
		(width 0.14732)
		(layer "In15.Cu")
		(net "P5E_CPU0_PE0_TX_DN<9>")
	)
	(segment
		(start 346.518484 -223.575626)
		(end 346.518484 -223.561402)
		(width 0.0889)
		(layer "In15.Cu")
		(net "P5E_CPU0_PE0_TX_DN<9>")
	)
	(segment
		(start 346.236036 -223.085914)
		(end 346.227146 -223.080834)
		(width 0.0889)
		(layer "In15.Cu")
		(net "P5E_CPU0_PE0_TX_DN<9>")
	)
	(segment
		(start 319.501012 -384.060446)
		(end 319.501266 -384.061208)
		(width 0.14732)
		(layer "In15.Cu")
		(net "P5E_CPU0_PE0_TX_DN<9>")
	)
	(segment
		(start 344.82532 -215.760554)
		(end 344.82278 -215.75903)
		(width 0.0889)
		(layer "In15.Cu")
		(net "P5E_CPU0_PE0_TX_DN<9>")
	)
	(segment
		(start 308.561994 -341.382096)
		(end 313.59475 -364.026196)
		(width 0.14732)
		(layer "In15.Cu")
		(net "P5E_CPU0_PE0_TX_DN<9>")
	)
	(segment
		(start 324.000368 -406.70988)
		(end 323.705728 -407.00452)
		(width 0.14732)
		(layer "In15.Cu")
		(net "P5E_CPU0_PE0_TX_DN<9>")
	)
	(segment
		(start 345.296236 -216.574878)
		(end 345.287346 -216.569798)
		(width 0.0889)
		(layer "In15.Cu")
		(net "P5E_CPU0_PE0_TX_DN<9>")
	)
	(arc
		(start 344.817192 -215.755982)
		(mid 344.686278 -215.619622)
		(end 344.63863 -215.436704)
		(width 0.0889)
		(layer "In15.Cu")
		(net "P5E_CPU0_PE0_TX_DN<9>")
	)
	(arc
		(start 344.63863 -215.436704)
		(mid 344.638682 -215.429337)
		(end 344.638884 -215.421972)
		(width 0.0889)
		(layer "In15.Cu")
		(net "P5E_CPU0_PE0_TX_DN<9>")
	)
	(arc
		(start 345.109038 -217.888566)
		(mid 345.108871 -217.87739)
		(end 345.109038 -217.866214)
		(width 0.0889)
		(layer "In15.Cu")
		(net "P5E_CPU0_PE0_TX_DN<9>")
	)
	(arc
		(start 346.227146 -224.70872)
		(mid 346.04867 -224.389442)
		(end 346.227146 -224.070164)
		(width 0.0889)
		(layer "In15.Cu")
		(net "P5E_CPU0_PE0_TX_DN<9>")
	)
	(arc
		(start 345.108784 -216.25052)
		(mid 345.034793 -215.970954)
		(end 344.832178 -215.764618)
		(width 0.0889)
		(layer "In15.Cu")
		(net "P5E_CPU0_PE0_TX_DN<9>")
	)
	(arc
		(start 346.048584 -222.761556)
		(mid 345.974593 -222.48199)
		(end 345.771978 -222.275654)
		(width 0.0889)
		(layer "In15.Cu")
		(net "P5E_CPU0_PE0_TX_DN<9>")
	)
	(arc
		(start 345.57843 -221.932246)
		(mid 345.49906 -221.658512)
		(end 345.296236 -221.458282)
		(width 0.0889)
		(layer "In15.Cu")
		(net "P5E_CPU0_PE0_TX_DN<9>")
	)
	(arc
		(start 344.638884 -215.421972)
		(mid 344.689938 -215.247392)
		(end 344.817192 -215.117426)
		(width 0.0889)
		(layer "In15.Cu")
		(net "P5E_CPU0_PE0_TX_DN<9>")
	)
	(arc
		(start 346.049092 -222.776288)
		(mid 346.048759 -222.763844)
		(end 346.048838 -222.751396)
		(width 0.0889)
		(layer "In15.Cu")
		(net "P5E_CPU0_PE0_TX_DN<9>")
	)
	(arc
		(start 346.558616 -224.738438)
		(mid 346.39452 -224.762785)
		(end 346.236036 -224.7138)
		(width 0.0889)
		(layer "In15.Cu")
		(net "P5E_CPU0_PE0_TX_DN<9>")
	)
	(arc
		(start 345.296236 -220.809566)
		(mid 345.578768 -220.320045)
		(end 345.296236 -219.830396)
		(width 0.0889)
		(layer "In15.Cu")
		(net "P5E_CPU0_PE0_TX_DN<9>")
	)
	(arc
		(start 346.227146 -223.080834)
		(mid 346.100066 -222.95082)
		(end 346.049092 -222.776288)
		(width 0.0889)
		(layer "In15.Cu")
		(net "P5E_CPU0_PE0_TX_DN<9>")
	)
	(arc
		(start 345.287346 -219.825316)
		(mid 345.108749 -219.506038)
		(end 345.287346 -219.18676)
		(width 0.0889)
		(layer "In15.Cu")
		(net "P5E_CPU0_PE0_TX_DN<9>")
	)
	(arc
		(start 345.57843 -218.676728)
		(mid 345.49906 -218.402994)
		(end 345.296236 -218.202764)
		(width 0.0889)
		(layer "In15.Cu")
		(net "P5E_CPU0_PE0_TX_DN<9>")
	)
	(arc
		(start 345.296236 -217.554048)
		(mid 345.578768 -217.064527)
		(end 345.296236 -216.574878)
		(width 0.0889)
		(layer "In15.Cu")
		(net "P5E_CPU0_PE0_TX_DN<9>")
	)
	(arc
		(start 345.756992 -222.267018)
		(mid 345.626078 -222.130658)
		(end 345.57843 -221.94774)
		(width 0.0889)
		(layer "In15.Cu")
		(net "P5E_CPU0_PE0_TX_DN<9>")
	)
	(arc
		(start 344.823034 -214.093298)
		(mid 344.713887 -214.00937)
		(end 344.638884 -213.893908)
		(width 0.0889)
		(layer "In15.Cu")
		(net "P5E_CPU0_PE0_TX_DN<9>")
	)
	(arc
		(start 346.242132 -224.061528)
		(mid 346.444545 -223.855115)
		(end 346.518484 -223.575626)
		(width 0.0889)
		(layer "In15.Cu")
		(net "P5E_CPU0_PE0_TX_DN<9>")
	)
	(arc
		(start 344.826082 -215.112346)
		(mid 345.027364 -214.914859)
		(end 345.108276 -214.644732)
		(width 0.0889)
		(layer "In15.Cu")
		(net "P5E_CPU0_PE0_TX_DN<9>")
	)
	(arc
		(start 345.109038 -221.121732)
		(mid 345.159509 -220.945724)
		(end 345.287346 -220.814646)
		(width 0.0889)
		(layer "In15.Cu")
		(net "P5E_CPU0_PE0_TX_DN<9>")
	)
	(arc
		(start 345.287346 -216.569798)
		(mid 345.156432 -216.433438)
		(end 345.108784 -216.25052)
		(width 0.0889)
		(layer "In15.Cu")
		(net "P5E_CPU0_PE0_TX_DN<9>")
	)
	(arc
		(start 346.518484 -223.561402)
		(mid 346.439343 -223.286779)
		(end 346.236036 -223.085914)
		(width 0.0889)
		(layer "In15.Cu")
		(net "P5E_CPU0_PE0_TX_DN<9>")
	)
	(arc
		(start 345.109038 -217.866214)
		(mid 345.159509 -217.690206)
		(end 345.287346 -217.559128)
		(width 0.0889)
		(layer "In15.Cu")
		(net "P5E_CPU0_PE0_TX_DN<9>")
	)
	(arc
		(start 345.296236 -219.18168)
		(mid 345.499059 -218.981449)
		(end 345.57843 -218.707716)
		(width 0.0889)
		(layer "In15.Cu")
		(net "P5E_CPU0_PE0_TX_DN<9>")
	)
	(arc
		(start 345.287346 -221.453202)
		(mid 345.159027 -221.32123)
		(end 345.109038 -221.144084)
		(width 0.0889)
		(layer "In15.Cu")
		(net "P5E_CPU0_PE0_TX_DN<9>")
	)
	(arc
		(start 345.287346 -218.197684)
		(mid 345.159027 -218.065712)
		(end 345.109038 -217.888566)
		(width 0.0889)
		(layer "In15.Cu")
		(net "P5E_CPU0_PE0_TX_DN<9>")
	)
	(arc
		(start 345.108276 -214.424768)
		(mid 344.996997 -214.232062)
		(end 344.823034 -214.093298)
		(width 0.0889)
		(layer "In15.Cu")
		(net "P5E_CPU0_PE0_TX_DN<9>")
	)
	(arc
		(start 345.109038 -221.144084)
		(mid 345.108871 -221.132908)
		(end 345.109038 -221.121732)
		(width 0.0889)
		(layer "In15.Cu")
		(net "P5E_CPU0_PE0_TX_DN<9>")
	)
	(segment
		(start 327.07453 -407.924254)
		(end 326.74814 -408.250644)
		(width 0.13208)
		(layer "F.Cu")
		(net "P5E_CPU0_PE0_TX_DN<8>")
	)
	(segment
		(start 345.953334 -224.111566)
		(end 345.953334 -223.57588)
		(width 0.13208)
		(layer "F.Cu")
		(net "P5E_CPU0_PE0_TX_DN<8>")
	)
	(segment
		(start 326.768968 -407.00452)
		(end 327.07453 -407.310082)
		(width 0.13208)
		(layer "F.Cu")
		(net "P5E_CPU0_PE0_TX_DN<8>")
	)
	(segment
		(start 327.07453 -407.310082)
		(end 327.07453 -407.924254)
		(width 0.13208)
		(layer "F.Cu")
		(net "P5E_CPU0_PE0_TX_DN<8>")
	)
	(segment
		(start 345.953334 -223.57588)
		(end 345.95308 -223.575626)
		(width 0.13208)
		(layer "F.Cu")
		(net "P5E_CPU0_PE0_TX_DN<8>")
	)
	(segment
		(start 326.74814 -408.250644)
		(end 326.743568 -408.250644)
		(width 0.13208)
		(layer "F.Cu")
		(net "P5E_CPU0_PE0_TX_DN<8>")
	)
	(segment
		(start 345.95308 -223.575626)
		(end 345.796616 -223.846644)
		(width 0.0889)
		(layer "In15.Cu")
		(net "P5E_CPU0_PE0_TX_DN<8>")
	)
	(segment
		(start 324.863206 -309.685436)
		(end 321.403472 -317.866522)
		(width 0.14732)
		(layer "In15.Cu")
		(net "P5E_CPU0_PE0_TX_DN<8>")
	)
	(segment
		(start 341.855552 -211.652358)
		(end 335.165446 -211.652358)
		(width 0.14732)
		(layer "In15.Cu")
		(net "P5E_CPU0_PE0_TX_DN<8>")
	)
	(segment
		(start 324.406006 -222.252032)
		(end 322.716906 -233.130852)
		(width 0.14732)
		(layer "In15.Cu")
		(net "P5E_CPU0_PE0_TX_DN<8>")
	)
	(segment
		(start 321.245992 -252.67666)
		(end 324.863206 -309.685436)
		(width 0.14732)
		(layer "In15.Cu")
		(net "P5E_CPU0_PE0_TX_DN<8>")
	)
	(segment
		(start 343.003378 -212.127592)
		(end 341.855552 -211.652358)
		(width 0.14732)
		(layer "In15.Cu")
		(net "P5E_CPU0_PE0_TX_DN<8>")
	)
	(segment
		(start 343.880694 -215.75776)
		(end 343.878662 -215.756744)
		(width 0.0889)
		(layer "In15.Cu")
		(net "P5E_CPU0_PE0_TX_DN<8>")
	)
	(segment
		(start 321.322192 -250.220988)
		(end 321.283838 -251.356876)
		(width 0.14732)
		(layer "In15.Cu")
		(net "P5E_CPU0_PE0_TX_DN<8>")
	)
	(segment
		(start 343.699084 -213.186518)
		(end 343.740994 -213.144608)
		(width 0.0889)
		(layer "In15.Cu")
		(net "P5E_CPU0_PE0_TX_DN<8>")
	)
	(segment
		(start 309.571898 -332.15453)
		(end 309.491888 -332.234794)
		(width 0.14732)
		(layer "In15.Cu")
		(net "P5E_CPU0_PE0_TX_DN<8>")
	)
	(segment
		(start 327.249028 -399.910808)
		(end 327.249028 -403.948138)
		(width 0.14732)
		(layer "In15.Cu")
		(net "P5E_CPU0_PE0_TX_DN<8>")
	)
	(segment
		(start 344.356436 -219.830396)
		(end 344.347546 -219.825316)
		(width 0.0889)
		(layer "In15.Cu")
		(net "P5E_CPU0_PE0_TX_DN<8>")
	)
	(segment
		(start 343.69883 -213.893654)
		(end 343.699084 -213.8934)
		(width 0.0889)
		(layer "In15.Cu")
		(net "P5E_CPU0_PE0_TX_DN<8>")
	)
	(segment
		(start 343.740994 -213.144608)
		(end 343.740994 -213.12251)
		(width 0.0889)
		(layer "In15.Cu")
		(net "P5E_CPU0_PE0_TX_DN<8>")
	)
	(segment
		(start 325.380858 -220.361002)
		(end 325.380604 -220.361256)
		(width 0.14732)
		(layer "In15.Cu")
		(net "P5E_CPU0_PE0_TX_DN<8>")
	)
	(segment
		(start 343.88552 -215.760554)
		(end 343.88298 -215.75903)
		(width 0.0889)
		(layer "In15.Cu")
		(net "P5E_CPU0_PE0_TX_DN<8>")
	)
	(segment
		(start 344.347546 -220.814646)
		(end 344.356436 -220.809566)
		(width 0.0889)
		(layer "In15.Cu")
		(net "P5E_CPU0_PE0_TX_DN<8>")
	)
	(segment
		(start 344.356436 -216.574878)
		(end 344.347546 -216.569798)
		(width 0.0889)
		(layer "In15.Cu")
		(net "P5E_CPU0_PE0_TX_DN<8>")
	)
	(segment
		(start 344.356436 -221.458282)
		(end 344.347546 -221.453202)
		(width 0.0889)
		(layer "In15.Cu")
		(net "P5E_CPU0_PE0_TX_DN<8>")
	)
	(segment
		(start 344.832178 -222.275654)
		(end 344.817192 -222.267018)
		(width 0.0889)
		(layer "In15.Cu")
		(net "P5E_CPU0_PE0_TX_DN<8>")
	)
	(segment
		(start 321.245992 -252.490478)
		(end 321.245992 -252.67666)
		(width 0.14732)
		(layer "In15.Cu")
		(net "P5E_CPU0_PE0_TX_DN<8>")
	)
	(segment
		(start 344.35542 -219.182188)
		(end 344.356436 -219.18168)
		(width 0.0889)
		(layer "In15.Cu")
		(net "P5E_CPU0_PE0_TX_DN<8>")
	)
	(segment
		(start 343.878662 -215.756744)
		(end 343.877392 -215.755982)
		(width 0.0889)
		(layer "In15.Cu")
		(net "P5E_CPU0_PE0_TX_DN<8>")
	)
	(segment
		(start 343.877392 -215.117426)
		(end 343.886282 -215.112346)
		(width 0.0889)
		(layer "In15.Cu")
		(net "P5E_CPU0_PE0_TX_DN<8>")
	)
	(segment
		(start 343.740994 -213.12251)
		(end 343.740994 -212.865208)
		(width 0.14732)
		(layer "In15.Cu")
		(net "P5E_CPU0_PE0_TX_DN<8>")
	)
	(segment
		(start 343.881964 -215.758522)
		(end 343.880694 -215.75776)
		(width 0.0889)
		(layer "In15.Cu")
		(net "P5E_CPU0_PE0_TX_DN<8>")
	)
	(segment
		(start 344.362532 -219.833952)
		(end 344.356436 -219.830396)
		(width 0.0889)
		(layer "In15.Cu")
		(net "P5E_CPU0_PE0_TX_DN<8>")
	)
	(segment
		(start 327.249028 -403.948138)
		(end 327.063608 -405.831548)
		(width 0.14732)
		(layer "In15.Cu")
		(net "P5E_CPU0_PE0_TX_DN<8>")
	)
	(segment
		(start 322.716906 -233.130852)
		(end 321.322192 -250.220988)
		(width 0.14732)
		(layer "In15.Cu")
		(net "P5E_CPU0_PE0_TX_DN<8>")
	)
	(segment
		(start 343.699084 -213.893908)
		(end 343.69883 -213.893654)
		(width 0.0889)
		(layer "In15.Cu")
		(net "P5E_CPU0_PE0_TX_DN<8>")
	)
	(segment
		(start 343.88298 -215.75903)
		(end 343.881964 -215.758522)
		(width 0.0889)
		(layer "In15.Cu")
		(net "P5E_CPU0_PE0_TX_DN<8>")
	)
	(segment
		(start 326.356726 -218.46794)
		(end 325.380858 -220.361002)
		(width 0.14732)
		(layer "In15.Cu")
		(net "P5E_CPU0_PE0_TX_DN<8>")
	)
	(segment
		(start 325.380604 -220.361256)
		(end 324.406006 -222.252032)
		(width 0.14732)
		(layer "In15.Cu")
		(net "P5E_CPU0_PE0_TX_DN<8>")
	)
	(segment
		(start 335.165446 -211.652358)
		(end 331.43825 -213.67115)
		(width 0.14732)
		(layer "In15.Cu")
		(net "P5E_CPU0_PE0_TX_DN<8>")
	)
	(segment
		(start 344.63863 -218.707716)
		(end 344.63863 -218.676728)
		(width 0.0889)
		(layer "In15.Cu")
		(net "P5E_CPU0_PE0_TX_DN<8>")
	)
	(segment
		(start 343.699084 -213.8934)
		(end 343.699084 -213.186518)
		(width 0.0889)
		(layer "In15.Cu")
		(net "P5E_CPU0_PE0_TX_DN<8>")
	)
	(segment
		(start 315.663072 -326.063356)
		(end 309.572152 -332.15453)
		(width 0.14732)
		(layer "In15.Cu")
		(net "P5E_CPU0_PE0_TX_DN<8>")
	)
	(segment
		(start 345.109038 -222.751396)
		(end 345.108784 -222.761556)
		(width 0.0889)
		(layer "In15.Cu")
		(net "P5E_CPU0_PE0_TX_DN<8>")
	)
	(segment
		(start 327.063608 -406.70988)
		(end 326.768968 -407.00452)
		(width 0.14732)
		(layer "In15.Cu")
		(net "P5E_CPU0_PE0_TX_DN<8>")
	)
	(segment
		(start 309.491888 -341.275924)
		(end 314.475114 -363.699298)
		(width 0.14732)
		(layer "In15.Cu")
		(net "P5E_CPU0_PE0_TX_DN<8>")
	)
	(segment
		(start 345.296236 -223.085914)
		(end 345.287346 -223.080834)
		(width 0.0889)
		(layer "In15.Cu")
		(net "P5E_CPU0_PE0_TX_DN<8>")
	)
	(segment
		(start 327.063608 -405.831548)
		(end 327.063608 -406.70988)
		(width 0.14732)
		(layer "In15.Cu")
		(net "P5E_CPU0_PE0_TX_DN<8>")
	)
	(segment
		(start 343.740994 -212.865208)
		(end 343.003378 -212.127592)
		(width 0.14732)
		(layer "In15.Cu")
		(net "P5E_CPU0_PE0_TX_DN<8>")
	)
	(segment
		(start 314.475114 -363.699298)
		(end 327.249028 -399.910808)
		(width 0.14732)
		(layer "In15.Cu")
		(net "P5E_CPU0_PE0_TX_DN<8>")
	)
	(segment
		(start 344.356436 -218.202764)
		(end 344.347546 -218.197684)
		(width 0.0889)
		(layer "In15.Cu")
		(net "P5E_CPU0_PE0_TX_DN<8>")
	)
	(segment
		(start 345.796616 -223.846644)
		(end 345.718638 -223.867472)
		(width 0.0889)
		(layer "In15.Cu")
		(net "P5E_CPU0_PE0_TX_DN<8>")
	)
	(segment
		(start 344.362532 -216.578434)
		(end 344.356436 -216.574878)
		(width 0.0889)
		(layer "In15.Cu")
		(net "P5E_CPU0_PE0_TX_DN<8>")
	)
	(segment
		(start 344.347546 -219.18676)
		(end 344.35542 -219.182188)
		(width 0.0889)
		(layer "In15.Cu")
		(net "P5E_CPU0_PE0_TX_DN<8>")
	)
	(segment
		(start 331.43825 -213.67115)
		(end 326.356726 -218.46794)
		(width 0.14732)
		(layer "In15.Cu")
		(net "P5E_CPU0_PE0_TX_DN<8>")
	)
	(segment
		(start 309.491888 -332.234794)
		(end 309.491888 -341.275924)
		(width 0.14732)
		(layer "In15.Cu")
		(net "P5E_CPU0_PE0_TX_DN<8>")
	)
	(segment
		(start 309.572152 -332.15453)
		(end 309.571898 -332.15453)
		(width 0.14732)
		(layer "In15.Cu")
		(net "P5E_CPU0_PE0_TX_DN<8>")
	)
	(segment
		(start 343.889076 -215.762586)
		(end 343.886282 -215.761062)
		(width 0.0889)
		(layer "In15.Cu")
		(net "P5E_CPU0_PE0_TX_DN<8>")
	)
	(segment
		(start 321.283838 -251.356876)
		(end 321.245992 -252.490478)
		(width 0.14732)
		(layer "In15.Cu")
		(net "P5E_CPU0_PE0_TX_DN<8>")
	)
	(segment
		(start 343.886282 -215.761062)
		(end 343.88552 -215.760554)
		(width 0.0889)
		(layer "In15.Cu")
		(net "P5E_CPU0_PE0_TX_DN<8>")
	)
	(segment
		(start 345.578684 -223.584262)
		(end 345.578684 -223.557084)
		(width 0.0889)
		(layer "In15.Cu")
		(net "P5E_CPU0_PE0_TX_DN<8>")
	)
	(segment
		(start 344.347546 -217.559128)
		(end 344.356436 -217.554048)
		(width 0.0889)
		(layer "In15.Cu")
		(net "P5E_CPU0_PE0_TX_DN<8>")
	)
	(segment
		(start 343.892378 -215.764618)
		(end 343.889076 -215.762586)
		(width 0.0889)
		(layer "In15.Cu")
		(net "P5E_CPU0_PE0_TX_DN<8>")
	)
	(segment
		(start 344.63863 -221.94774)
		(end 344.63863 -221.932246)
		(width 0.0889)
		(layer "In15.Cu")
		(net "P5E_CPU0_PE0_TX_DN<8>")
	)
	(segment
		(start 321.403472 -317.866522)
		(end 315.663072 -326.063356)
		(width 0.14732)
		(layer "In15.Cu")
		(net "P5E_CPU0_PE0_TX_DN<8>")
	)
	(segment
		(start 344.168476 -214.644732)
		(end 344.168476 -214.424768)
		(width 0.0889)
		(layer "In15.Cu")
		(net "P5E_CPU0_PE0_TX_DN<8>")
	)
	(arc
		(start 344.168984 -217.888566)
		(mid 344.168904 -217.876118)
		(end 344.169238 -217.863674)
		(width 0.0889)
		(layer "In15.Cu")
		(net "P5E_CPU0_PE0_TX_DN<8>")
	)
	(arc
		(start 344.63863 -218.676728)
		(mid 344.55926 -218.402994)
		(end 344.356436 -218.202764)
		(width 0.0889)
		(layer "In15.Cu")
		(net "P5E_CPU0_PE0_TX_DN<8>")
	)
	(arc
		(start 343.886282 -215.112346)
		(mid 344.087564 -214.914859)
		(end 344.168476 -214.644732)
		(width 0.0889)
		(layer "In15.Cu")
		(net "P5E_CPU0_PE0_TX_DN<8>")
	)
	(arc
		(start 343.883234 -214.093298)
		(mid 343.774087 -214.00937)
		(end 343.699084 -213.893908)
		(width 0.0889)
		(layer "In15.Cu")
		(net "P5E_CPU0_PE0_TX_DN<8>")
	)
	(arc
		(start 344.347546 -216.569798)
		(mid 344.216632 -216.433438)
		(end 344.168984 -216.25052)
		(width 0.0889)
		(layer "In15.Cu")
		(net "P5E_CPU0_PE0_TX_DN<8>")
	)
	(arc
		(start 344.347546 -218.197684)
		(mid 344.219142 -218.065739)
		(end 344.168984 -217.888566)
		(width 0.0889)
		(layer "In15.Cu")
		(net "P5E_CPU0_PE0_TX_DN<8>")
	)
	(arc
		(start 343.699084 -215.421972)
		(mid 343.750138 -215.247392)
		(end 343.877392 -215.117426)
		(width 0.0889)
		(layer "In15.Cu")
		(net "P5E_CPU0_PE0_TX_DN<8>")
	)
	(arc
		(start 344.356436 -217.554048)
		(mid 344.63905 -217.06793)
		(end 344.362532 -216.578434)
		(width 0.0889)
		(layer "In15.Cu")
		(net "P5E_CPU0_PE0_TX_DN<8>")
	)
	(arc
		(start 343.69883 -215.436704)
		(mid 343.698882 -215.429337)
		(end 343.699084 -215.421972)
		(width 0.0889)
		(layer "In15.Cu")
		(net "P5E_CPU0_PE0_TX_DN<8>")
	)
	(arc
		(start 344.817192 -222.267018)
		(mid 344.686278 -222.130658)
		(end 344.63863 -221.94774)
		(width 0.0889)
		(layer "In15.Cu")
		(net "P5E_CPU0_PE0_TX_DN<8>")
	)
	(arc
		(start 344.356436 -219.18168)
		(mid 344.559259 -218.981449)
		(end 344.63863 -218.707716)
		(width 0.0889)
		(layer "In15.Cu")
		(net "P5E_CPU0_PE0_TX_DN<8>")
	)
	(arc
		(start 345.109038 -222.773748)
		(mid 345.108871 -222.762572)
		(end 345.109038 -222.751396)
		(width 0.0889)
		(layer "In15.Cu")
		(net "P5E_CPU0_PE0_TX_DN<8>")
	)
	(arc
		(start 345.108784 -222.761556)
		(mid 345.034793 -222.48199)
		(end 344.832178 -222.275654)
		(width 0.0889)
		(layer "In15.Cu")
		(net "P5E_CPU0_PE0_TX_DN<8>")
	)
	(arc
		(start 343.877392 -215.755982)
		(mid 343.746478 -215.619622)
		(end 343.69883 -215.436704)
		(width 0.0889)
		(layer "In15.Cu")
		(net "P5E_CPU0_PE0_TX_DN<8>")
	)
	(arc
		(start 344.63863 -221.932246)
		(mid 344.55926 -221.658512)
		(end 344.356436 -221.458282)
		(width 0.0889)
		(layer "In15.Cu")
		(net "P5E_CPU0_PE0_TX_DN<8>")
	)
	(arc
		(start 344.347546 -221.453202)
		(mid 344.219142 -221.321257)
		(end 344.168984 -221.144084)
		(width 0.0889)
		(layer "In15.Cu")
		(net "P5E_CPU0_PE0_TX_DN<8>")
	)
	(arc
		(start 345.287346 -223.080834)
		(mid 345.159453 -222.949772)
		(end 345.109038 -222.773748)
		(width 0.0889)
		(layer "In15.Cu")
		(net "P5E_CPU0_PE0_TX_DN<8>")
	)
	(arc
		(start 344.168476 -214.424768)
		(mid 344.057197 -214.232062)
		(end 343.883234 -214.093298)
		(width 0.0889)
		(layer "In15.Cu")
		(net "P5E_CPU0_PE0_TX_DN<8>")
	)
	(arc
		(start 344.169238 -221.119192)
		(mid 344.220292 -220.944612)
		(end 344.347546 -220.814646)
		(width 0.0889)
		(layer "In15.Cu")
		(net "P5E_CPU0_PE0_TX_DN<8>")
	)
	(arc
		(start 344.169238 -217.863674)
		(mid 344.220292 -217.689094)
		(end 344.347546 -217.559128)
		(width 0.0889)
		(layer "In15.Cu")
		(net "P5E_CPU0_PE0_TX_DN<8>")
	)
	(arc
		(start 344.356436 -220.809566)
		(mid 344.63905 -220.323448)
		(end 344.362532 -219.833952)
		(width 0.0889)
		(layer "In15.Cu")
		(net "P5E_CPU0_PE0_TX_DN<8>")
	)
	(arc
		(start 345.578684 -223.557084)
		(mid 345.498522 -223.284895)
		(end 345.296236 -223.085914)
		(width 0.0889)
		(layer "In15.Cu")
		(net "P5E_CPU0_PE0_TX_DN<8>")
	)
	(arc
		(start 344.168984 -216.25052)
		(mid 344.094993 -215.970954)
		(end 343.892378 -215.764618)
		(width 0.0889)
		(layer "In15.Cu")
		(net "P5E_CPU0_PE0_TX_DN<8>")
	)
	(arc
		(start 344.347546 -219.825316)
		(mid 344.16907 -219.506038)
		(end 344.347546 -219.18676)
		(width 0.0889)
		(layer "In15.Cu")
		(net "P5E_CPU0_PE0_TX_DN<8>")
	)
	(arc
		(start 344.168984 -221.144084)
		(mid 344.168904 -221.131636)
		(end 344.169238 -221.119192)
		(width 0.0889)
		(layer "In15.Cu")
		(net "P5E_CPU0_PE0_TX_DN<8>")
	)
	(arc
		(start 345.718638 -223.867472)
		(mid 345.617317 -223.741351)
		(end 345.578684 -223.584262)
		(width 0.0889)
		(layer "In15.Cu")
		(net "P5E_CPU0_PE0_TX_DN<8>")
	)
	(segment
		(start 329.81138 -408.250644)
		(end 329.806808 -408.250644)
		(width 0.13208)
		(layer "F.Cu")
		(net "P5E_CPU0_PE0_TX_DN<7>")
	)
	(segment
		(start 330.13777 -407.924254)
		(end 329.81138 -408.250644)
		(width 0.13208)
		(layer "F.Cu")
		(net "P5E_CPU0_PE0_TX_DN<7>")
	)
	(segment
		(start 329.832208 -407.00452)
		(end 330.13777 -407.310082)
		(width 0.13208)
		(layer "F.Cu")
		(net "P5E_CPU0_PE0_TX_DN<7>")
	)
	(segment
		(start 344.54338 -224.389696)
		(end 344.543634 -224.389442)
		(width 0.13208)
		(layer "F.Cu")
		(net "P5E_CPU0_PE0_TX_DN<7>")
	)
	(segment
		(start 330.13777 -407.310082)
		(end 330.13777 -407.924254)
		(width 0.13208)
		(layer "F.Cu")
		(net "P5E_CPU0_PE0_TX_DN<7>")
	)
	(segment
		(start 344.54338 -224.925382)
		(end 344.54338 -224.389696)
		(width 0.13208)
		(layer "F.Cu")
		(net "P5E_CPU0_PE0_TX_DN<7>")
	)
	(segment
		(start 343.884758 -222.271336)
		(end 343.877392 -222.267018)
		(width 0.0889)
		(layer "In15.Cu")
		(net "P5E_CPU0_PE0_TX_DN<7>")
	)
	(segment
		(start 330.126848 -405.831548)
		(end 330.126848 -406.70988)
		(width 0.14732)
		(layer "In15.Cu")
		(net "P5E_CPU0_PE0_TX_DN<7>")
	)
	(segment
		(start 343.69883 -218.707716)
		(end 343.69883 -218.676728)
		(width 0.0889)
		(layer "In15.Cu")
		(net "P5E_CPU0_PE0_TX_DN<7>")
	)
	(segment
		(start 330.312268 -403.948138)
		(end 330.126848 -405.831548)
		(width 0.14732)
		(layer "In15.Cu")
		(net "P5E_CPU0_PE0_TX_DN<7>")
	)
	(segment
		(start 343.69883 -221.94774)
		(end 343.69883 -221.932246)
		(width 0.0889)
		(layer "In15.Cu")
		(net "P5E_CPU0_PE0_TX_DN<7>")
	)
	(segment
		(start 341.861394 -212.86216)
		(end 341.581232 -212.581998)
		(width 0.14732)
		(layer "In15.Cu")
		(net "P5E_CPU0_PE0_TX_DN<7>")
	)
	(segment
		(start 344.356436 -224.065084)
		(end 344.362532 -224.061528)
		(width 0.0889)
		(layer "In15.Cu")
		(net "P5E_CPU0_PE0_TX_DN<7>")
	)
	(segment
		(start 341.861394 -213.15045)
		(end 341.861394 -212.86216)
		(width 0.14732)
		(layer "In15.Cu")
		(net "P5E_CPU0_PE0_TX_DN<7>")
	)
	(segment
		(start 315.365892 -363.414564)
		(end 319.941956 -374.588024)
		(width 0.14732)
		(layer "In15.Cu")
		(net "P5E_CPU0_PE0_TX_DN<7>")
	)
	(segment
		(start 343.416636 -218.202764)
		(end 343.407746 -218.197684)
		(width 0.0889)
		(layer "In15.Cu")
		(net "P5E_CPU0_PE0_TX_DN<7>")
	)
	(segment
		(start 344.169238 -222.751396)
		(end 344.168984 -222.761556)
		(width 0.0889)
		(layer "In15.Cu")
		(net "P5E_CPU0_PE0_TX_DN<7>")
	)
	(segment
		(start 344.700098 -224.66046)
		(end 344.679016 -224.738438)
		(width 0.0889)
		(layer "In15.Cu")
		(net "P5E_CPU0_PE0_TX_DN<7>")
	)
	(segment
		(start 327.045574 -219.16771)
		(end 325.424038 -222.3135)
		(width 0.14732)
		(layer "In15.Cu")
		(net "P5E_CPU0_PE0_TX_DN<7>")
	)
	(segment
		(start 342.942164 -215.758522)
		(end 342.940894 -215.75776)
		(width 0.0889)
		(layer "In15.Cu")
		(net "P5E_CPU0_PE0_TX_DN<7>")
	)
	(segment
		(start 342.949276 -215.762586)
		(end 342.946482 -215.761062)
		(width 0.0889)
		(layer "In15.Cu")
		(net "P5E_CPU0_PE0_TX_DN<7>")
	)
	(segment
		(start 342.476328 -214.946992)
		(end 342.467438 -214.941912)
		(width 0.0889)
		(layer "In15.Cu")
		(net "P5E_CPU0_PE0_TX_DN<7>")
	)
	(segment
		(start 335.096866 -213.001606)
		(end 331.45603 -214.973662)
		(width 0.14732)
		(layer "In15.Cu")
		(net "P5E_CPU0_PE0_TX_DN<7>")
	)
	(segment
		(start 343.416636 -219.830396)
		(end 343.407746 -219.825316)
		(width 0.0889)
		(layer "In15.Cu")
		(net "P5E_CPU0_PE0_TX_DN<7>")
	)
	(segment
		(start 310.421528 -341.159084)
		(end 315.365892 -363.414564)
		(width 0.14732)
		(layer "In15.Cu")
		(net "P5E_CPU0_PE0_TX_DN<7>")
	)
	(segment
		(start 343.407746 -219.18676)
		(end 343.416636 -219.18168)
		(width 0.0889)
		(layer "In15.Cu")
		(net "P5E_CPU0_PE0_TX_DN<7>")
	)
	(segment
		(start 344.356436 -224.7138)
		(end 344.347546 -224.70872)
		(width 0.0889)
		(layer "In15.Cu")
		(net "P5E_CPU0_PE0_TX_DN<7>")
	)
	(segment
		(start 336.752692 -212.581998)
		(end 335.096866 -213.001606)
		(width 0.14732)
		(layer "In15.Cu")
		(net "P5E_CPU0_PE0_TX_DN<7>")
	)
	(segment
		(start 330.035408 -399.234914)
		(end 330.312268 -400.641058)
		(width 0.14732)
		(layer "In15.Cu")
		(net "P5E_CPU0_PE0_TX_DN<7>")
	)
	(segment
		(start 344.543634 -224.389442)
		(end 344.700098 -224.66046)
		(width 0.0889)
		(layer "In15.Cu")
		(net "P5E_CPU0_PE0_TX_DN<7>")
	)
	(segment
		(start 341.819484 -213.893908)
		(end 341.819484 -213.214458)
		(width 0.0889)
		(layer "In15.Cu")
		(net "P5E_CPU0_PE0_TX_DN<7>")
	)
	(segment
		(start 344.638884 -223.575626)
		(end 344.638884 -223.561402)
		(width 0.0889)
		(layer "In15.Cu")
		(net "P5E_CPU0_PE0_TX_DN<7>")
	)
	(segment
		(start 330.312268 -400.641058)
		(end 330.312268 -403.948138)
		(width 0.14732)
		(layer "In15.Cu")
		(net "P5E_CPU0_PE0_TX_DN<7>")
	)
	(segment
		(start 342.952578 -215.764618)
		(end 342.949276 -215.762586)
		(width 0.0889)
		(layer "In15.Cu")
		(net "P5E_CPU0_PE0_TX_DN<7>")
	)
	(segment
		(start 343.892378 -222.275654)
		(end 343.889076 -222.273622)
		(width 0.0889)
		(layer "In15.Cu")
		(net "P5E_CPU0_PE0_TX_DN<7>")
	)
	(segment
		(start 323.746622 -233.117898)
		(end 322.24599 -250.457716)
		(width 0.14732)
		(layer "In15.Cu")
		(net "P5E_CPU0_PE0_TX_DN<7>")
	)
	(segment
		(start 343.407746 -220.814646)
		(end 343.416636 -220.809566)
		(width 0.0889)
		(layer "In15.Cu")
		(net "P5E_CPU0_PE0_TX_DN<7>")
	)
	(segment
		(start 343.407746 -217.559128)
		(end 343.416636 -217.554048)
		(width 0.0889)
		(layer "In15.Cu")
		(net "P5E_CPU0_PE0_TX_DN<7>")
	)
	(segment
		(start 343.416636 -221.458282)
		(end 343.407746 -221.453202)
		(width 0.0889)
		(layer "In15.Cu")
		(net "P5E_CPU0_PE0_TX_DN<7>")
	)
	(segment
		(start 343.886282 -222.272098)
		(end 343.884758 -222.271336)
		(width 0.0889)
		(layer "In15.Cu")
		(net "P5E_CPU0_PE0_TX_DN<7>")
	)
	(segment
		(start 342.288876 -214.622634)
		(end 342.288876 -214.424768)
		(width 0.0889)
		(layer "In15.Cu")
		(net "P5E_CPU0_PE0_TX_DN<7>")
	)
	(segment
		(start 343.889076 -222.273622)
		(end 343.886282 -222.272098)
		(width 0.0889)
		(layer "In15.Cu")
		(net "P5E_CPU0_PE0_TX_DN<7>")
	)
	(segment
		(start 325.424038 -222.3135)
		(end 323.746622 -233.117898)
		(width 0.14732)
		(layer "In15.Cu")
		(net "P5E_CPU0_PE0_TX_DN<7>")
	)
	(segment
		(start 331.45603 -214.973662)
		(end 327.045574 -219.16771)
		(width 0.14732)
		(layer "In15.Cu")
		(net "P5E_CPU0_PE0_TX_DN<7>")
	)
	(segment
		(start 322.314824 -318.216026)
		(end 316.178184 -326.979788)
		(width 0.14732)
		(layer "In15.Cu")
		(net "P5E_CPU0_PE0_TX_DN<7>")
	)
	(segment
		(start 342.940894 -215.75776)
		(end 342.938862 -215.756744)
		(width 0.0889)
		(layer "In15.Cu")
		(net "P5E_CPU0_PE0_TX_DN<7>")
	)
	(segment
		(start 342.938862 -215.756744)
		(end 342.937592 -215.755982)
		(width 0.0889)
		(layer "In15.Cu")
		(net "P5E_CPU0_PE0_TX_DN<7>")
	)
	(segment
		(start 342.94572 -215.760554)
		(end 342.94318 -215.75903)
		(width 0.0889)
		(layer "In15.Cu")
		(net "P5E_CPU0_PE0_TX_DN<7>")
	)
	(segment
		(start 343.416636 -216.574878)
		(end 343.407746 -216.569798)
		(width 0.0889)
		(layer "In15.Cu")
		(net "P5E_CPU0_PE0_TX_DN<7>")
	)
	(segment
		(start 342.75903 -215.436704)
		(end 342.75903 -215.42248)
		(width 0.0889)
		(layer "In15.Cu")
		(net "P5E_CPU0_PE0_TX_DN<7>")
	)
	(segment
		(start 341.581232 -212.581998)
		(end 336.752692 -212.581998)
		(width 0.14732)
		(layer "In15.Cu")
		(net "P5E_CPU0_PE0_TX_DN<7>")
	)
	(segment
		(start 325.927466 -309.669434)
		(end 322.314824 -318.216026)
		(width 0.14732)
		(layer "In15.Cu")
		(net "P5E_CPU0_PE0_TX_DN<7>")
	)
	(segment
		(start 319.942464 -374.588024)
		(end 330.035408 -399.234914)
		(width 0.14732)
		(layer "In15.Cu")
		(net "P5E_CPU0_PE0_TX_DN<7>")
	)
	(segment
		(start 344.347546 -224.070164)
		(end 344.356436 -224.065084)
		(width 0.0889)
		(layer "In15.Cu")
		(net "P5E_CPU0_PE0_TX_DN<7>")
	)
	(segment
		(start 319.941956 -374.588024)
		(end 319.942464 -374.588024)
		(width 0.14732)
		(layer "In15.Cu")
		(net "P5E_CPU0_PE0_TX_DN<7>")
	)
	(segment
		(start 310.501792 -332.656434)
		(end 310.501538 -332.656434)
		(width 0.14732)
		(layer "In15.Cu")
		(net "P5E_CPU0_PE0_TX_DN<7>")
	)
	(segment
		(start 310.501538 -332.656434)
		(end 310.421528 -332.736698)
		(width 0.14732)
		(layer "In15.Cu")
		(net "P5E_CPU0_PE0_TX_DN<7>")
	)
	(segment
		(start 341.819484 -213.214458)
		(end 341.861394 -213.172548)
		(width 0.0889)
		(layer "In15.Cu")
		(net "P5E_CPU0_PE0_TX_DN<7>")
	)
	(segment
		(start 316.178184 -326.979788)
		(end 310.501792 -332.656434)
		(width 0.14732)
		(layer "In15.Cu")
		(net "P5E_CPU0_PE0_TX_DN<7>")
	)
	(segment
		(start 310.421528 -332.736698)
		(end 310.421528 -341.159084)
		(width 0.14732)
		(layer "In15.Cu")
		(net "P5E_CPU0_PE0_TX_DN<7>")
	)
	(segment
		(start 341.861394 -213.172548)
		(end 341.861394 -213.15045)
		(width 0.0889)
		(layer "In15.Cu")
		(net "P5E_CPU0_PE0_TX_DN<7>")
	)
	(segment
		(start 322.24599 -250.457716)
		(end 322.180458 -252.401324)
		(width 0.14732)
		(layer "In15.Cu")
		(net "P5E_CPU0_PE0_TX_DN<7>")
	)
	(segment
		(start 342.946482 -215.761062)
		(end 342.94572 -215.760554)
		(width 0.0889)
		(layer "In15.Cu")
		(net "P5E_CPU0_PE0_TX_DN<7>")
	)
	(segment
		(start 322.180458 -252.401324)
		(end 325.927466 -309.669434)
		(width 0.14732)
		(layer "In15.Cu")
		(net "P5E_CPU0_PE0_TX_DN<7>")
	)
	(segment
		(start 330.126848 -406.70988)
		(end 329.832208 -407.00452)
		(width 0.14732)
		(layer "In15.Cu")
		(net "P5E_CPU0_PE0_TX_DN<7>")
	)
	(segment
		(start 344.356436 -223.085914)
		(end 344.347546 -223.080834)
		(width 0.0889)
		(layer "In15.Cu")
		(net "P5E_CPU0_PE0_TX_DN<7>")
	)
	(segment
		(start 342.94318 -215.75903)
		(end 342.942164 -215.758522)
		(width 0.0889)
		(layer "In15.Cu")
		(net "P5E_CPU0_PE0_TX_DN<7>")
	)
	(arc
		(start 343.407746 -219.825316)
		(mid 343.229149 -219.506038)
		(end 343.407746 -219.18676)
		(width 0.0889)
		(layer "In15.Cu")
		(net "P5E_CPU0_PE0_TX_DN<7>")
	)
	(arc
		(start 342.75903 -215.42248)
		(mid 342.679811 -215.147795)
		(end 342.476328 -214.946992)
		(width 0.0889)
		(layer "In15.Cu")
		(net "P5E_CPU0_PE0_TX_DN<7>")
	)
	(arc
		(start 344.362532 -224.061528)
		(mid 344.564945 -223.855115)
		(end 344.638884 -223.575626)
		(width 0.0889)
		(layer "In15.Cu")
		(net "P5E_CPU0_PE0_TX_DN<7>")
	)
	(arc
		(start 343.229438 -221.121732)
		(mid 343.279909 -220.945724)
		(end 343.407746 -220.814646)
		(width 0.0889)
		(layer "In15.Cu")
		(net "P5E_CPU0_PE0_TX_DN<7>")
	)
	(arc
		(start 343.407746 -218.197684)
		(mid 343.279427 -218.065712)
		(end 343.229438 -217.888566)
		(width 0.0889)
		(layer "In15.Cu")
		(net "P5E_CPU0_PE0_TX_DN<7>")
	)
	(arc
		(start 342.003634 -214.093298)
		(mid 341.894487 -214.00937)
		(end 341.819484 -213.893908)
		(width 0.0889)
		(layer "In15.Cu")
		(net "P5E_CPU0_PE0_TX_DN<7>")
	)
	(arc
		(start 343.229438 -221.144084)
		(mid 343.229271 -221.132908)
		(end 343.229438 -221.121732)
		(width 0.0889)
		(layer "In15.Cu")
		(net "P5E_CPU0_PE0_TX_DN<7>")
	)
	(arc
		(start 343.69883 -221.932246)
		(mid 343.61946 -221.658512)
		(end 343.416636 -221.458282)
		(width 0.0889)
		(layer "In15.Cu")
		(net "P5E_CPU0_PE0_TX_DN<7>")
	)
	(arc
		(start 342.467438 -214.941912)
		(mid 342.336524 -214.805552)
		(end 342.288876 -214.622634)
		(width 0.0889)
		(layer "In15.Cu")
		(net "P5E_CPU0_PE0_TX_DN<7>")
	)
	(arc
		(start 344.638884 -223.561402)
		(mid 344.559743 -223.286779)
		(end 344.356436 -223.085914)
		(width 0.0889)
		(layer "In15.Cu")
		(net "P5E_CPU0_PE0_TX_DN<7>")
	)
	(arc
		(start 343.229438 -217.866214)
		(mid 343.279909 -217.690206)
		(end 343.407746 -217.559128)
		(width 0.0889)
		(layer "In15.Cu")
		(net "P5E_CPU0_PE0_TX_DN<7>")
	)
	(arc
		(start 343.229438 -217.888566)
		(mid 343.229271 -217.87739)
		(end 343.229438 -217.866214)
		(width 0.0889)
		(layer "In15.Cu")
		(net "P5E_CPU0_PE0_TX_DN<7>")
	)
	(arc
		(start 343.229184 -216.25052)
		(mid 343.155193 -215.970954)
		(end 342.952578 -215.764618)
		(width 0.0889)
		(layer "In15.Cu")
		(net "P5E_CPU0_PE0_TX_DN<7>")
	)
	(arc
		(start 343.407746 -221.453202)
		(mid 343.279427 -221.32123)
		(end 343.229438 -221.144084)
		(width 0.0889)
		(layer "In15.Cu")
		(net "P5E_CPU0_PE0_TX_DN<7>")
	)
	(arc
		(start 343.416636 -219.18168)
		(mid 343.619459 -218.981449)
		(end 343.69883 -218.707716)
		(width 0.0889)
		(layer "In15.Cu")
		(net "P5E_CPU0_PE0_TX_DN<7>")
	)
	(arc
		(start 343.407746 -216.569798)
		(mid 343.276832 -216.433438)
		(end 343.229184 -216.25052)
		(width 0.0889)
		(layer "In15.Cu")
		(net "P5E_CPU0_PE0_TX_DN<7>")
	)
	(arc
		(start 343.416636 -220.809566)
		(mid 343.699168 -220.320045)
		(end 343.416636 -219.830396)
		(width 0.0889)
		(layer "In15.Cu")
		(net "P5E_CPU0_PE0_TX_DN<7>")
	)
	(arc
		(start 344.347546 -224.70872)
		(mid 344.16907 -224.389442)
		(end 344.347546 -224.070164)
		(width 0.0889)
		(layer "In15.Cu")
		(net "P5E_CPU0_PE0_TX_DN<7>")
	)
	(arc
		(start 344.347546 -223.080834)
		(mid 344.220466 -222.95082)
		(end 344.169492 -222.776288)
		(width 0.0889)
		(layer "In15.Cu")
		(net "P5E_CPU0_PE0_TX_DN<7>")
	)
	(arc
		(start 343.69883 -218.676728)
		(mid 343.61946 -218.402994)
		(end 343.416636 -218.202764)
		(width 0.0889)
		(layer "In15.Cu")
		(net "P5E_CPU0_PE0_TX_DN<7>")
	)
	(arc
		(start 344.168984 -222.761556)
		(mid 344.094993 -222.48199)
		(end 343.892378 -222.275654)
		(width 0.0889)
		(layer "In15.Cu")
		(net "P5E_CPU0_PE0_TX_DN<7>")
	)
	(arc
		(start 344.169492 -222.776288)
		(mid 344.169159 -222.763844)
		(end 344.169238 -222.751396)
		(width 0.0889)
		(layer "In15.Cu")
		(net "P5E_CPU0_PE0_TX_DN<7>")
	)
	(arc
		(start 343.416636 -217.554048)
		(mid 343.699168 -217.064527)
		(end 343.416636 -216.574878)
		(width 0.0889)
		(layer "In15.Cu")
		(net "P5E_CPU0_PE0_TX_DN<7>")
	)
	(arc
		(start 342.288876 -214.424768)
		(mid 342.177597 -214.232062)
		(end 342.003634 -214.093298)
		(width 0.0889)
		(layer "In15.Cu")
		(net "P5E_CPU0_PE0_TX_DN<7>")
	)
	(arc
		(start 343.877392 -222.267018)
		(mid 343.746478 -222.130658)
		(end 343.69883 -221.94774)
		(width 0.0889)
		(layer "In15.Cu")
		(net "P5E_CPU0_PE0_TX_DN<7>")
	)
	(arc
		(start 344.679016 -224.738438)
		(mid 344.51492 -224.762785)
		(end 344.356436 -224.7138)
		(width 0.0889)
		(layer "In15.Cu")
		(net "P5E_CPU0_PE0_TX_DN<7>")
	)
	(arc
		(start 342.937592 -215.755982)
		(mid 342.806678 -215.619622)
		(end 342.75903 -215.436704)
		(width 0.0889)
		(layer "In15.Cu")
		(net "P5E_CPU0_PE0_TX_DN<7>")
	)
	(segment
		(start 332.895448 -407.00452)
		(end 333.20101 -407.310082)
		(width 0.13208)
		(layer "F.Cu")
		(net "P5E_CPU0_PE0_TX_DN<6>")
	)
	(segment
		(start 344.073734 -224.111566)
		(end 344.073734 -223.57588)
		(width 0.13208)
		(layer "F.Cu")
		(net "P5E_CPU0_PE0_TX_DN<6>")
	)
	(segment
		(start 333.20101 -407.924254)
		(end 332.87462 -408.250644)
		(width 0.13208)
		(layer "F.Cu")
		(net "P5E_CPU0_PE0_TX_DN<6>")
	)
	(segment
		(start 344.073734 -223.57588)
		(end 344.07348 -223.575626)
		(width 0.13208)
		(layer "F.Cu")
		(net "P5E_CPU0_PE0_TX_DN<6>")
	)
	(segment
		(start 333.20101 -407.310082)
		(end 333.20101 -407.924254)
		(width 0.13208)
		(layer "F.Cu")
		(net "P5E_CPU0_PE0_TX_DN<6>")
	)
	(segment
		(start 332.87462 -408.250644)
		(end 332.870048 -408.250644)
		(width 0.13208)
		(layer "F.Cu")
		(net "P5E_CPU0_PE0_TX_DN<6>")
	)
	(segment
		(start 342.006682 -215.761062)
		(end 341.99195 -215.752426)
		(width 0.0889)
		(layer "In15.Cu")
		(net "P5E_CPU0_PE0_TX_DN<6>")
	)
	(segment
		(start 342.467946 -220.814646)
		(end 342.476836 -220.809566)
		(width 0.0889)
		(layer "In15.Cu")
		(net "P5E_CPU0_PE0_TX_DN<6>")
	)
	(segment
		(start 337.60537 -213.905592)
		(end 335.561432 -213.905592)
		(width 0.14732)
		(layer "In15.Cu")
		(net "P5E_CPU0_PE0_TX_DN<6>")
	)
	(segment
		(start 311.431178 -333.115666)
		(end 311.351168 -333.19593)
		(width 0.14732)
		(layer "In15.Cu")
		(net "P5E_CPU0_PE0_TX_DN<6>")
	)
	(segment
		(start 311.351168 -341.056722)
		(end 316.252098 -363.11586)
		(width 0.14732)
		(layer "In15.Cu")
		(net "P5E_CPU0_PE0_TX_DN<6>")
	)
	(segment
		(start 338.99983 -215.436704)
		(end 338.99983 -215.42248)
		(width 0.0889)
		(layer "In15.Cu")
		(net "P5E_CPU0_PE0_TX_DN<6>")
	)
	(segment
		(start 333.190088 -405.831548)
		(end 333.190088 -406.70988)
		(width 0.14732)
		(layer "In15.Cu")
		(net "P5E_CPU0_PE0_TX_DN<6>")
	)
	(segment
		(start 342.012778 -215.764618)
		(end 342.007444 -215.76157)
		(width 0.0889)
		(layer "In15.Cu")
		(net "P5E_CPU0_PE0_TX_DN<6>")
	)
	(segment
		(start 326.894952 -309.83555)
		(end 323.008244 -319.000124)
		(width 0.14732)
		(layer "In15.Cu")
		(net "P5E_CPU0_PE0_TX_DN<6>")
	)
	(segment
		(start 342.482932 -216.578434)
		(end 342.476836 -216.574878)
		(width 0.0889)
		(layer "In15.Cu")
		(net "P5E_CPU0_PE0_TX_DN<6>")
	)
	(segment
		(start 333.190088 -406.70988)
		(end 332.895448 -407.00452)
		(width 0.14732)
		(layer "In15.Cu")
		(net "P5E_CPU0_PE0_TX_DN<6>")
	)
	(segment
		(start 324.687946 -233.167174)
		(end 323.170042 -250.64466)
		(width 0.14732)
		(layer "In15.Cu")
		(net "P5E_CPU0_PE0_TX_DN<6>")
	)
	(segment
		(start 342.467946 -219.18676)
		(end 342.476836 -219.18168)
		(width 0.0889)
		(layer "In15.Cu")
		(net "P5E_CPU0_PE0_TX_DN<6>")
	)
	(segment
		(start 338.109814 -213.947502)
		(end 337.669378 -213.947502)
		(width 0.0889)
		(layer "In15.Cu")
		(net "P5E_CPU0_PE0_TX_DN<6>")
	)
	(segment
		(start 342.952578 -222.275654)
		(end 342.949276 -222.273622)
		(width 0.0889)
		(layer "In15.Cu")
		(net "P5E_CPU0_PE0_TX_DN<6>")
	)
	(segment
		(start 342.949276 -222.273622)
		(end 342.946482 -222.272098)
		(width 0.0889)
		(layer "In15.Cu")
		(net "P5E_CPU0_PE0_TX_DN<6>")
	)
	(segment
		(start 343.229438 -222.751396)
		(end 343.229184 -222.761556)
		(width 0.0889)
		(layer "In15.Cu")
		(net "P5E_CPU0_PE0_TX_DN<6>")
	)
	(segment
		(start 342.75903 -218.707716)
		(end 342.75903 -218.676728)
		(width 0.0889)
		(layer "In15.Cu")
		(net "P5E_CPU0_PE0_TX_DN<6>")
	)
	(segment
		(start 326.326754 -222.611696)
		(end 324.687946 -233.167174)
		(width 0.14732)
		(layer "In15.Cu")
		(net "P5E_CPU0_PE0_TX_DN<6>")
	)
	(segment
		(start 340.127082 -215.761062)
		(end 340.11235 -215.752426)
		(width 0.0889)
		(layer "In15.Cu")
		(net "P5E_CPU0_PE0_TX_DN<6>")
	)
	(segment
		(start 323.170042 -250.64466)
		(end 323.126354 -251.940568)
		(width 0.14732)
		(layer "In15.Cu")
		(net "P5E_CPU0_PE0_TX_DN<6>")
	)
	(segment
		(start 339.185758 -215.7603)
		(end 339.178392 -215.755982)
		(width 0.0889)
		(layer "In15.Cu")
		(net "P5E_CPU0_PE0_TX_DN<6>")
	)
	(segment
		(start 343.699084 -223.584262)
		(end 343.699084 -223.557084)
		(width 0.0889)
		(layer "In15.Cu")
		(net "P5E_CPU0_PE0_TX_DN<6>")
	)
	(segment
		(start 342.476836 -219.830396)
		(end 342.467946 -219.825316)
		(width 0.0889)
		(layer "In15.Cu")
		(net "P5E_CPU0_PE0_TX_DN<6>")
	)
	(segment
		(start 342.75903 -221.94774)
		(end 342.75903 -221.932246)
		(width 0.0889)
		(layer "In15.Cu")
		(net "P5E_CPU0_PE0_TX_DN<6>")
	)
	(segment
		(start 323.008244 -319.000124)
		(end 317.078106 -327.468738)
		(width 0.14732)
		(layer "In15.Cu")
		(net "P5E_CPU0_PE0_TX_DN<6>")
	)
	(segment
		(start 343.917016 -223.846644)
		(end 343.839038 -223.867472)
		(width 0.0889)
		(layer "In15.Cu")
		(net "P5E_CPU0_PE0_TX_DN<6>")
	)
	(segment
		(start 344.07348 -223.575626)
		(end 343.917016 -223.846644)
		(width 0.0889)
		(layer "In15.Cu")
		(net "P5E_CPU0_PE0_TX_DN<6>")
	)
	(segment
		(start 323.126354 -251.940568)
		(end 326.894952 -309.83555)
		(width 0.14732)
		(layer "In15.Cu")
		(net "P5E_CPU0_PE0_TX_DN<6>")
	)
	(segment
		(start 338.717128 -214.946992)
		(end 338.708238 -214.941912)
		(width 0.0889)
		(layer "In15.Cu")
		(net "P5E_CPU0_PE0_TX_DN<6>")
	)
	(segment
		(start 338.270596 -214.10803)
		(end 338.109814 -213.947502)
		(width 0.0889)
		(layer "In15.Cu")
		(net "P5E_CPU0_PE0_TX_DN<6>")
	)
	(segment
		(start 337.669378 -213.947502)
		(end 337.627468 -213.905592)
		(width 0.0889)
		(layer "In15.Cu")
		(net "P5E_CPU0_PE0_TX_DN<6>")
	)
	(segment
		(start 342.944958 -222.271336)
		(end 342.937592 -222.267018)
		(width 0.0889)
		(layer "In15.Cu")
		(net "P5E_CPU0_PE0_TX_DN<6>")
	)
	(segment
		(start 342.007444 -215.76157)
		(end 342.006682 -215.761062)
		(width 0.0889)
		(layer "In15.Cu")
		(net "P5E_CPU0_PE0_TX_DN<6>")
	)
	(segment
		(start 337.627468 -213.905592)
		(end 337.60537 -213.905592)
		(width 0.0889)
		(layer "In15.Cu")
		(net "P5E_CPU0_PE0_TX_DN<6>")
	)
	(segment
		(start 335.561432 -213.905592)
		(end 331.969364 -215.851232)
		(width 0.14732)
		(layer "In15.Cu")
		(net "P5E_CPU0_PE0_TX_DN<6>")
	)
	(segment
		(start 342.476836 -216.574878)
		(end 342.467946 -216.569798)
		(width 0.0889)
		(layer "In15.Cu")
		(net "P5E_CPU0_PE0_TX_DN<6>")
	)
	(segment
		(start 331.969364 -215.851232)
		(end 327.804018 -219.746576)
		(width 0.14732)
		(layer "In15.Cu")
		(net "P5E_CPU0_PE0_TX_DN<6>")
	)
	(segment
		(start 311.431432 -333.115666)
		(end 311.431178 -333.115666)
		(width 0.14732)
		(layer "In15.Cu")
		(net "P5E_CPU0_PE0_TX_DN<6>")
	)
	(segment
		(start 317.078106 -327.468738)
		(end 311.431432 -333.115666)
		(width 0.14732)
		(layer "In15.Cu")
		(net "P5E_CPU0_PE0_TX_DN<6>")
	)
	(segment
		(start 311.351168 -333.19593)
		(end 311.351168 -341.056722)
		(width 0.14732)
		(layer "In15.Cu")
		(net "P5E_CPU0_PE0_TX_DN<6>")
	)
	(segment
		(start 339.187282 -215.761062)
		(end 339.185758 -215.7603)
		(width 0.0889)
		(layer "In15.Cu")
		(net "P5E_CPU0_PE0_TX_DN<6>")
	)
	(segment
		(start 341.066882 -215.761062)
		(end 341.05215 -215.752426)
		(width 0.0889)
		(layer "In15.Cu")
		(net "P5E_CPU0_PE0_TX_DN<6>")
	)
	(segment
		(start 342.476836 -218.202764)
		(end 342.467946 -218.197684)
		(width 0.0889)
		(layer "In15.Cu")
		(net "P5E_CPU0_PE0_TX_DN<6>")
	)
	(segment
		(start 342.482932 -219.833952)
		(end 342.476836 -219.830396)
		(width 0.0889)
		(layer "In15.Cu")
		(net "P5E_CPU0_PE0_TX_DN<6>")
	)
	(segment
		(start 342.476836 -221.458282)
		(end 342.467946 -221.453202)
		(width 0.0889)
		(layer "In15.Cu")
		(net "P5E_CPU0_PE0_TX_DN<6>")
	)
	(segment
		(start 316.252098 -363.11586)
		(end 321.32397 -374.024906)
		(width 0.14732)
		(layer "In15.Cu")
		(net "P5E_CPU0_PE0_TX_DN<6>")
	)
	(segment
		(start 338.529676 -214.622634)
		(end 338.529676 -214.424768)
		(width 0.0889)
		(layer "In15.Cu")
		(net "P5E_CPU0_PE0_TX_DN<6>")
	)
	(segment
		(start 327.804018 -219.746576)
		(end 326.326754 -222.611696)
		(width 0.14732)
		(layer "In15.Cu")
		(net "P5E_CPU0_PE0_TX_DN<6>")
	)
	(segment
		(start 342.946482 -222.272098)
		(end 342.944958 -222.271336)
		(width 0.0889)
		(layer "In15.Cu")
		(net "P5E_CPU0_PE0_TX_DN<6>")
	)
	(segment
		(start 343.416636 -223.085914)
		(end 343.407746 -223.080834)
		(width 0.0889)
		(layer "In15.Cu")
		(net "P5E_CPU0_PE0_TX_DN<6>")
	)
	(segment
		(start 333.375508 -403.948138)
		(end 333.190088 -405.831548)
		(width 0.14732)
		(layer "In15.Cu")
		(net "P5E_CPU0_PE0_TX_DN<6>")
	)
	(segment
		(start 342.467946 -217.559128)
		(end 342.476836 -217.554048)
		(width 0.0889)
		(layer "In15.Cu")
		(net "P5E_CPU0_PE0_TX_DN<6>")
	)
	(segment
		(start 333.375508 -399.946622)
		(end 333.375508 -403.948138)
		(width 0.14732)
		(layer "In15.Cu")
		(net "P5E_CPU0_PE0_TX_DN<6>")
	)
	(segment
		(start 321.32397 -374.024906)
		(end 333.375508 -399.946622)
		(width 0.14732)
		(layer "In15.Cu")
		(net "P5E_CPU0_PE0_TX_DN<6>")
	)
	(arc
		(start 342.289384 -217.888566)
		(mid 342.289304 -217.876118)
		(end 342.289638 -217.863674)
		(width 0.0889)
		(layer "In15.Cu")
		(net "P5E_CPU0_PE0_TX_DN<6>")
	)
	(arc
		(start 338.529676 -214.424768)
		(mid 338.428047 -214.243564)
		(end 338.270596 -214.10803)
		(width 0.0889)
		(layer "In15.Cu")
		(net "P5E_CPU0_PE0_TX_DN<6>")
	)
	(arc
		(start 339.178392 -215.755982)
		(mid 339.047478 -215.619622)
		(end 338.99983 -215.436704)
		(width 0.0889)
		(layer "In15.Cu")
		(net "P5E_CPU0_PE0_TX_DN<6>")
	)
	(arc
		(start 340.11235 -215.752426)
		(mid 339.835875 -215.685106)
		(end 339.561678 -215.761062)
		(width 0.0889)
		(layer "In15.Cu")
		(net "P5E_CPU0_PE0_TX_DN<6>")
	)
	(arc
		(start 341.441278 -215.761062)
		(mid 341.25408 -215.811205)
		(end 341.066882 -215.761062)
		(width 0.0889)
		(layer "In15.Cu")
		(net "P5E_CPU0_PE0_TX_DN<6>")
	)
	(arc
		(start 338.708238 -214.941912)
		(mid 338.577324 -214.805552)
		(end 338.529676 -214.622634)
		(width 0.0889)
		(layer "In15.Cu")
		(net "P5E_CPU0_PE0_TX_DN<6>")
	)
	(arc
		(start 342.467946 -216.569798)
		(mid 342.337032 -216.433438)
		(end 342.289384 -216.25052)
		(width 0.0889)
		(layer "In15.Cu")
		(net "P5E_CPU0_PE0_TX_DN<6>")
	)
	(arc
		(start 343.407746 -223.080834)
		(mid 343.279853 -222.949772)
		(end 343.229438 -222.773748)
		(width 0.0889)
		(layer "In15.Cu")
		(net "P5E_CPU0_PE0_TX_DN<6>")
	)
	(arc
		(start 342.289892 -221.119192)
		(mid 342.340802 -220.944623)
		(end 342.467946 -220.814646)
		(width 0.0889)
		(layer "In15.Cu")
		(net "P5E_CPU0_PE0_TX_DN<6>")
	)
	(arc
		(start 343.699084 -223.557084)
		(mid 343.618922 -223.284895)
		(end 343.416636 -223.085914)
		(width 0.0889)
		(layer "In15.Cu")
		(net "P5E_CPU0_PE0_TX_DN<6>")
	)
	(arc
		(start 342.467946 -221.453202)
		(mid 342.339627 -221.32123)
		(end 342.289638 -221.144084)
		(width 0.0889)
		(layer "In15.Cu")
		(net "P5E_CPU0_PE0_TX_DN<6>")
	)
	(arc
		(start 342.467946 -218.197684)
		(mid 342.339542 -218.065739)
		(end 342.289384 -217.888566)
		(width 0.0889)
		(layer "In15.Cu")
		(net "P5E_CPU0_PE0_TX_DN<6>")
	)
	(arc
		(start 342.289638 -221.144084)
		(mid 342.289558 -221.131636)
		(end 342.289892 -221.119192)
		(width 0.0889)
		(layer "In15.Cu")
		(net "P5E_CPU0_PE0_TX_DN<6>")
	)
	(arc
		(start 341.05215 -215.752426)
		(mid 340.775675 -215.685106)
		(end 340.501478 -215.761062)
		(width 0.0889)
		(layer "In15.Cu")
		(net "P5E_CPU0_PE0_TX_DN<6>")
	)
	(arc
		(start 340.501478 -215.761062)
		(mid 340.31428 -215.811205)
		(end 340.127082 -215.761062)
		(width 0.0889)
		(layer "In15.Cu")
		(net "P5E_CPU0_PE0_TX_DN<6>")
	)
	(arc
		(start 341.99195 -215.752426)
		(mid 341.715475 -215.685106)
		(end 341.441278 -215.761062)
		(width 0.0889)
		(layer "In15.Cu")
		(net "P5E_CPU0_PE0_TX_DN<6>")
	)
	(arc
		(start 343.229438 -222.773748)
		(mid 343.229271 -222.762572)
		(end 343.229438 -222.751396)
		(width 0.0889)
		(layer "In15.Cu")
		(net "P5E_CPU0_PE0_TX_DN<6>")
	)
	(arc
		(start 342.937592 -222.267018)
		(mid 342.806678 -222.130658)
		(end 342.75903 -221.94774)
		(width 0.0889)
		(layer "In15.Cu")
		(net "P5E_CPU0_PE0_TX_DN<6>")
	)
	(arc
		(start 342.289384 -216.25052)
		(mid 342.215393 -215.970954)
		(end 342.012778 -215.764618)
		(width 0.0889)
		(layer "In15.Cu")
		(net "P5E_CPU0_PE0_TX_DN<6>")
	)
	(arc
		(start 342.75903 -221.932246)
		(mid 342.67966 -221.658512)
		(end 342.476836 -221.458282)
		(width 0.0889)
		(layer "In15.Cu")
		(net "P5E_CPU0_PE0_TX_DN<6>")
	)
	(arc
		(start 342.289638 -217.863674)
		(mid 342.340692 -217.689094)
		(end 342.467946 -217.559128)
		(width 0.0889)
		(layer "In15.Cu")
		(net "P5E_CPU0_PE0_TX_DN<6>")
	)
	(arc
		(start 343.229184 -222.761556)
		(mid 343.155193 -222.48199)
		(end 342.952578 -222.275654)
		(width 0.0889)
		(layer "In15.Cu")
		(net "P5E_CPU0_PE0_TX_DN<6>")
	)
	(arc
		(start 338.99983 -215.42248)
		(mid 338.920611 -215.147795)
		(end 338.717128 -214.946992)
		(width 0.0889)
		(layer "In15.Cu")
		(net "P5E_CPU0_PE0_TX_DN<6>")
	)
	(arc
		(start 342.476836 -217.554048)
		(mid 342.75945 -217.06793)
		(end 342.482932 -216.578434)
		(width 0.0889)
		(layer "In15.Cu")
		(net "P5E_CPU0_PE0_TX_DN<6>")
	)
	(arc
		(start 343.839038 -223.867472)
		(mid 343.737717 -223.741351)
		(end 343.699084 -223.584262)
		(width 0.0889)
		(layer "In15.Cu")
		(net "P5E_CPU0_PE0_TX_DN<6>")
	)
	(arc
		(start 342.476836 -220.809566)
		(mid 342.75945 -220.323448)
		(end 342.482932 -219.833952)
		(width 0.0889)
		(layer "In15.Cu")
		(net "P5E_CPU0_PE0_TX_DN<6>")
	)
	(arc
		(start 342.75903 -218.676728)
		(mid 342.67966 -218.402994)
		(end 342.476836 -218.202764)
		(width 0.0889)
		(layer "In15.Cu")
		(net "P5E_CPU0_PE0_TX_DN<6>")
	)
	(arc
		(start 342.467946 -219.825316)
		(mid 342.28947 -219.506038)
		(end 342.467946 -219.18676)
		(width 0.0889)
		(layer "In15.Cu")
		(net "P5E_CPU0_PE0_TX_DN<6>")
	)
	(arc
		(start 342.476836 -219.18168)
		(mid 342.679659 -218.981449)
		(end 342.75903 -218.707716)
		(width 0.0889)
		(layer "In15.Cu")
		(net "P5E_CPU0_PE0_TX_DN<6>")
	)
	(arc
		(start 339.561678 -215.761062)
		(mid 339.37448 -215.811205)
		(end 339.187282 -215.761062)
		(width 0.0889)
		(layer "In15.Cu")
		(net "P5E_CPU0_PE0_TX_DN<6>")
	)
	(segment
		(start 335.93786 -408.250644)
		(end 335.933288 -408.250644)
		(width 0.13208)
		(layer "F.Cu")
		(net "P5E_CPU0_PE0_TX_DN<5>")
	)
	(segment
		(start 336.26425 -407.924254)
		(end 335.93786 -408.250644)
		(width 0.13208)
		(layer "F.Cu")
		(net "P5E_CPU0_PE0_TX_DN<5>")
	)
	(segment
		(start 342.66378 -224.389696)
		(end 342.664034 -224.389442)
		(width 0.13208)
		(layer "F.Cu")
		(net "P5E_CPU0_PE0_TX_DN<5>")
	)
	(segment
		(start 335.958688 -407.00452)
		(end 336.26425 -407.310082)
		(width 0.13208)
		(layer "F.Cu")
		(net "P5E_CPU0_PE0_TX_DN<5>")
	)
	(segment
		(start 336.26425 -407.310082)
		(end 336.26425 -407.924254)
		(width 0.13208)
		(layer "F.Cu")
		(net "P5E_CPU0_PE0_TX_DN<5>")
	)
	(segment
		(start 342.66378 -224.925382)
		(end 342.66378 -224.389696)
		(width 0.13208)
		(layer "F.Cu")
		(net "P5E_CPU0_PE0_TX_DN<5>")
	)
	(segment
		(start 342.476836 -224.7138)
		(end 342.467946 -224.70872)
		(width 0.0889)
		(layer "In15.Cu")
		(net "P5E_CPU0_PE0_TX_DN<5>")
	)
	(segment
		(start 317.636398 -328.31659)
		(end 312.293 -333.660242)
		(width 0.14732)
		(layer "In15.Cu")
		(net "P5E_CPU0_PE0_TX_DN<5>")
	)
	(segment
		(start 340.603332 -216.578434)
		(end 340.597236 -216.574878)
		(width 0.0889)
		(layer "In15.Cu")
		(net "P5E_CPU0_PE0_TX_DN<5>")
	)
	(segment
		(start 336.253328 -406.70988)
		(end 335.958688 -407.00452)
		(width 0.14732)
		(layer "In15.Cu")
		(net "P5E_CPU0_PE0_TX_DN<5>")
	)
	(segment
		(start 341.537036 -218.202764)
		(end 341.528146 -218.197684)
		(width 0.0889)
		(layer "In15.Cu")
		(net "P5E_CPU0_PE0_TX_DN<5>")
	)
	(segment
		(start 342.467946 -224.070164)
		(end 342.476836 -224.065084)
		(width 0.0889)
		(layer "In15.Cu")
		(net "P5E_CPU0_PE0_TX_DN<5>")
	)
	(segment
		(start 341.537036 -219.830396)
		(end 341.528146 -219.825316)
		(width 0.0889)
		(layer "In15.Cu")
		(net "P5E_CPU0_PE0_TX_DN<5>")
	)
	(segment
		(start 340.046564 -216.566242)
		(end 340.031832 -216.574878)
		(width 0.0889)
		(layer "In15.Cu")
		(net "P5E_CPU0_PE0_TX_DN<5>")
	)
	(segment
		(start 327.243694 -249.210322)
		(end 328.044556 -250.706382)
		(width 0.14732)
		(layer "In15.Cu")
		(net "P5E_CPU0_PE0_TX_DN<5>")
	)
	(segment
		(start 312.293 -333.660242)
		(end 312.293 -340.984332)
		(width 0.14732)
		(layer "In15.Cu")
		(net "P5E_CPU0_PE0_TX_DN<5>")
	)
	(segment
		(start 323.937122 -319.318894)
		(end 317.636398 -328.31659)
		(width 0.14732)
		(layer "In15.Cu")
		(net "P5E_CPU0_PE0_TX_DN<5>")
	)
	(segment
		(start 333.205328 -216.457276)
		(end 332.915006 -216.457276)
		(width 0.14732)
		(layer "In15.Cu")
		(net "P5E_CPU0_PE0_TX_DN<5>")
	)
	(segment
		(start 326.415908 -247.664224)
		(end 327.243694 -249.210068)
		(width 0.14732)
		(layer "In15.Cu")
		(net "P5E_CPU0_PE0_TX_DN<5>")
	)
	(segment
		(start 336.253328 -405.831548)
		(end 336.253328 -406.70988)
		(width 0.14732)
		(layer "In15.Cu")
		(net "P5E_CPU0_PE0_TX_DN<5>")
	)
	(segment
		(start 328.60488 -220.340682)
		(end 327.38949 -222.708978)
		(width 0.14732)
		(layer "In15.Cu")
		(net "P5E_CPU0_PE0_TX_DN<5>")
	)
	(segment
		(start 328.044556 -250.706382)
		(end 328.312018 -251.351542)
		(width 0.14732)
		(layer "In15.Cu")
		(net "P5E_CPU0_PE0_TX_DN<5>")
	)
	(segment
		(start 317.129414 -362.754164)
		(end 336.438748 -399.910808)
		(width 0.14732)
		(layer "In15.Cu")
		(net "P5E_CPU0_PE0_TX_DN<5>")
	)
	(segment
		(start 336.438748 -399.910808)
		(end 336.438748 -403.948138)
		(width 0.14732)
		(layer "In15.Cu")
		(net "P5E_CPU0_PE0_TX_DN<5>")
	)
	(segment
		(start 336.438748 -403.948138)
		(end 336.253328 -405.831548)
		(width 0.14732)
		(layer "In15.Cu")
		(net "P5E_CPU0_PE0_TX_DN<5>")
	)
	(segment
		(start 312.293 -340.984332)
		(end 317.129414 -362.754164)
		(width 0.14732)
		(layer "In15.Cu")
		(net "P5E_CPU0_PE0_TX_DN<5>")
	)
	(segment
		(start 328.311256 -252.217174)
		(end 325.79437 -258.6736)
		(width 0.14732)
		(layer "In15.Cu")
		(net "P5E_CPU0_PE0_TX_DN<5>")
	)
	(segment
		(start 342.476836 -224.065084)
		(end 342.482932 -224.061528)
		(width 0.0889)
		(layer "In15.Cu")
		(net "P5E_CPU0_PE0_TX_DN<5>")
	)
	(segment
		(start 327.847452 -310.027828)
		(end 323.937122 -319.318894)
		(width 0.14732)
		(layer "In15.Cu")
		(net "P5E_CPU0_PE0_TX_DN<5>")
	)
	(segment
		(start 328.312018 -252.217428)
		(end 328.311256 -252.217174)
		(width 0.14732)
		(layer "In15.Cu")
		(net "P5E_CPU0_PE0_TX_DN<5>")
	)
	(segment
		(start 342.006682 -222.272098)
		(end 342.005158 -222.271336)
		(width 0.0889)
		(layer "In15.Cu")
		(net "P5E_CPU0_PE0_TX_DN<5>")
	)
	(segment
		(start 341.528146 -219.18676)
		(end 341.537036 -219.18168)
		(width 0.0889)
		(layer "In15.Cu")
		(net "P5E_CPU0_PE0_TX_DN<5>")
	)
	(segment
		(start 332.62189 -216.573354)
		(end 328.60488 -220.340682)
		(width 0.14732)
		(layer "In15.Cu")
		(net "P5E_CPU0_PE0_TX_DN<5>")
	)
	(segment
		(start 333.269336 -216.499186)
		(end 333.227426 -216.457276)
		(width 0.0889)
		(layer "In15.Cu")
		(net "P5E_CPU0_PE0_TX_DN<5>")
	)
	(segment
		(start 341.349584 -217.878406)
		(end 341.349584 -217.859864)
		(width 0.0889)
		(layer "In15.Cu")
		(net "P5E_CPU0_PE0_TX_DN<5>")
	)
	(segment
		(start 341.537036 -221.458282)
		(end 341.528146 -221.453202)
		(width 0.0889)
		(layer "In15.Cu")
		(net "P5E_CPU0_PE0_TX_DN<5>")
	)
	(segment
		(start 336.837528 -216.574878)
		(end 336.822796 -216.566242)
		(width 0.0889)
		(layer "In15.Cu")
		(net "P5E_CPU0_PE0_TX_DN<5>")
	)
	(segment
		(start 342.009476 -222.273622)
		(end 342.006682 -222.272098)
		(width 0.0889)
		(layer "In15.Cu")
		(net "P5E_CPU0_PE0_TX_DN<5>")
	)
	(segment
		(start 342.012778 -222.275654)
		(end 342.009476 -222.273622)
		(width 0.0889)
		(layer "In15.Cu")
		(net "P5E_CPU0_PE0_TX_DN<5>")
	)
	(segment
		(start 332.915006 -216.457276)
		(end 332.62189 -216.573354)
		(width 0.14732)
		(layer "In15.Cu")
		(net "P5E_CPU0_PE0_TX_DN<5>")
	)
	(segment
		(start 342.820498 -224.66046)
		(end 342.799416 -224.738438)
		(width 0.0889)
		(layer "In15.Cu")
		(net "P5E_CPU0_PE0_TX_DN<5>")
	)
	(segment
		(start 334.67548 -216.499186)
		(end 333.269336 -216.499186)
		(width 0.0889)
		(layer "In15.Cu")
		(net "P5E_CPU0_PE0_TX_DN<5>")
	)
	(segment
		(start 341.528146 -220.814646)
		(end 341.537036 -220.809566)
		(width 0.0889)
		(layer "In15.Cu")
		(net "P5E_CPU0_PE0_TX_DN<5>")
	)
	(segment
		(start 325.793862 -258.6736)
		(end 325.081646 -266.592304)
		(width 0.14732)
		(layer "In15.Cu")
		(net "P5E_CPU0_PE0_TX_DN<5>")
	)
	(segment
		(start 341.067136 -217.388694)
		(end 341.058246 -217.383614)
		(width 0.0889)
		(layer "In15.Cu")
		(net "P5E_CPU0_PE0_TX_DN<5>")
	)
	(segment
		(start 335.897728 -216.574878)
		(end 335.882996 -216.566242)
		(width 0.0889)
		(layer "In15.Cu")
		(net "P5E_CPU0_PE0_TX_DN<5>")
	)
	(segment
		(start 336.84591 -216.579704)
		(end 336.837528 -216.574878)
		(width 0.0889)
		(layer "In15.Cu")
		(net "P5E_CPU0_PE0_TX_DN<5>")
	)
	(segment
		(start 341.81923 -218.707716)
		(end 341.81923 -218.676728)
		(width 0.0889)
		(layer "In15.Cu")
		(net "P5E_CPU0_PE0_TX_DN<5>")
	)
	(segment
		(start 325.081646 -266.592304)
		(end 327.847452 -310.027828)
		(width 0.14732)
		(layer "In15.Cu")
		(net "P5E_CPU0_PE0_TX_DN<5>")
	)
	(segment
		(start 342.759284 -223.575626)
		(end 342.759284 -223.561402)
		(width 0.0889)
		(layer "In15.Cu")
		(net "P5E_CPU0_PE0_TX_DN<5>")
	)
	(segment
		(start 325.87184 -244.748304)
		(end 326.415908 -247.664224)
		(width 0.14732)
		(layer "In15.Cu")
		(net "P5E_CPU0_PE0_TX_DN<5>")
	)
	(segment
		(start 341.349838 -217.866214)
		(end 341.349584 -217.878406)
		(width 0.0889)
		(layer "In15.Cu")
		(net "P5E_CPU0_PE0_TX_DN<5>")
	)
	(segment
		(start 333.227426 -216.457276)
		(end 333.205328 -216.457276)
		(width 0.0889)
		(layer "In15.Cu")
		(net "P5E_CPU0_PE0_TX_DN<5>")
	)
	(segment
		(start 342.005158 -222.271336)
		(end 341.997792 -222.267018)
		(width 0.0889)
		(layer "In15.Cu")
		(net "P5E_CPU0_PE0_TX_DN<5>")
	)
	(segment
		(start 325.668386 -233.609642)
		(end 325.87184 -244.748304)
		(width 0.14732)
		(layer "In15.Cu")
		(net "P5E_CPU0_PE0_TX_DN<5>")
	)
	(segment
		(start 338.166964 -216.566242)
		(end 338.152232 -216.574878)
		(width 0.0889)
		(layer "In15.Cu")
		(net "P5E_CPU0_PE0_TX_DN<5>")
	)
	(segment
		(start 341.81923 -221.94774)
		(end 341.81923 -221.932246)
		(width 0.0889)
		(layer "In15.Cu")
		(net "P5E_CPU0_PE0_TX_DN<5>")
	)
	(segment
		(start 325.79437 -258.6736)
		(end 325.793862 -258.6736)
		(width 0.14732)
		(layer "In15.Cu")
		(net "P5E_CPU0_PE0_TX_DN<5>")
	)
	(segment
		(start 328.312018 -251.351542)
		(end 328.312018 -252.217428)
		(width 0.14732)
		(layer "In15.Cu")
		(net "P5E_CPU0_PE0_TX_DN<5>")
	)
	(segment
		(start 327.38949 -222.708978)
		(end 325.668386 -233.609642)
		(width 0.14732)
		(layer "In15.Cu")
		(net "P5E_CPU0_PE0_TX_DN<5>")
	)
	(segment
		(start 342.664034 -224.389442)
		(end 342.820498 -224.66046)
		(width 0.0889)
		(layer "In15.Cu")
		(net "P5E_CPU0_PE0_TX_DN<5>")
	)
	(segment
		(start 342.476836 -223.085914)
		(end 342.467946 -223.080834)
		(width 0.0889)
		(layer "In15.Cu")
		(net "P5E_CPU0_PE0_TX_DN<5>")
	)
	(segment
		(start 337.777836 -216.574878)
		(end 337.767422 -216.568782)
		(width 0.0889)
		(layer "In15.Cu")
		(net "P5E_CPU0_PE0_TX_DN<5>")
	)
	(segment
		(start 327.243694 -249.210068)
		(end 327.243694 -249.210322)
		(width 0.14732)
		(layer "In15.Cu")
		(net "P5E_CPU0_PE0_TX_DN<5>")
	)
	(arc
		(start 341.349838 -221.144084)
		(mid 341.349671 -221.132908)
		(end 341.349838 -221.121732)
		(width 0.0889)
		(layer "In15.Cu")
		(net "P5E_CPU0_PE0_TX_DN<5>")
	)
	(arc
		(start 342.467946 -223.080834)
		(mid 342.340692 -222.950868)
		(end 342.289638 -222.776288)
		(width 0.0889)
		(layer "In15.Cu")
		(net "P5E_CPU0_PE0_TX_DN<5>")
	)
	(arc
		(start 341.81923 -221.932246)
		(mid 341.73986 -221.658512)
		(end 341.537036 -221.458282)
		(width 0.0889)
		(layer "In15.Cu")
		(net "P5E_CPU0_PE0_TX_DN<5>")
	)
	(arc
		(start 334.959452 -216.57564)
		(mid 334.82253 -216.518589)
		(end 334.67548 -216.499186)
		(width 0.0889)
		(layer "In15.Cu")
		(net "P5E_CPU0_PE0_TX_DN<5>")
	)
	(arc
		(start 341.528146 -219.825316)
		(mid 341.349549 -219.506038)
		(end 341.528146 -219.18676)
		(width 0.0889)
		(layer "In15.Cu")
		(net "P5E_CPU0_PE0_TX_DN<5>")
	)
	(arc
		(start 341.81923 -218.676728)
		(mid 341.73986 -218.402994)
		(end 341.537036 -218.202764)
		(width 0.0889)
		(layer "In15.Cu")
		(net "P5E_CPU0_PE0_TX_DN<5>")
	)
	(arc
		(start 342.467946 -224.70872)
		(mid 342.28947 -224.389442)
		(end 342.467946 -224.070164)
		(width 0.0889)
		(layer "In15.Cu")
		(net "P5E_CPU0_PE0_TX_DN<5>")
	)
	(arc
		(start 341.349584 -217.859864)
		(mid 341.269422 -217.587675)
		(end 341.067136 -217.388694)
		(width 0.0889)
		(layer "In15.Cu")
		(net "P5E_CPU0_PE0_TX_DN<5>")
	)
	(arc
		(start 336.822796 -216.566242)
		(mid 336.546321 -216.498922)
		(end 336.272124 -216.574878)
		(width 0.0889)
		(layer "In15.Cu")
		(net "P5E_CPU0_PE0_TX_DN<5>")
	)
	(arc
		(start 342.482932 -224.061528)
		(mid 342.685345 -223.855115)
		(end 342.759284 -223.575626)
		(width 0.0889)
		(layer "In15.Cu")
		(net "P5E_CPU0_PE0_TX_DN<5>")
	)
	(arc
		(start 340.879684 -217.064336)
		(mid 340.805768 -216.784834)
		(end 340.603332 -216.578434)
		(width 0.0889)
		(layer "In15.Cu")
		(net "P5E_CPU0_PE0_TX_DN<5>")
	)
	(arc
		(start 341.349838 -221.121732)
		(mid 341.400309 -220.945724)
		(end 341.528146 -220.814646)
		(width 0.0889)
		(layer "In15.Cu")
		(net "P5E_CPU0_PE0_TX_DN<5>")
	)
	(arc
		(start 335.332324 -216.574878)
		(mid 335.145977 -216.62502)
		(end 334.959452 -216.57564)
		(width 0.0889)
		(layer "In15.Cu")
		(net "P5E_CPU0_PE0_TX_DN<5>")
	)
	(arc
		(start 336.272124 -216.574878)
		(mid 336.084926 -216.625021)
		(end 335.897728 -216.574878)
		(width 0.0889)
		(layer "In15.Cu")
		(net "P5E_CPU0_PE0_TX_DN<5>")
	)
	(arc
		(start 341.349838 -217.888566)
		(mid 341.349671 -217.87739)
		(end 341.349838 -217.866214)
		(width 0.0889)
		(layer "In15.Cu")
		(net "P5E_CPU0_PE0_TX_DN<5>")
	)
	(arc
		(start 341.528146 -218.197684)
		(mid 341.399827 -218.065712)
		(end 341.349838 -217.888566)
		(width 0.0889)
		(layer "In15.Cu")
		(net "P5E_CPU0_PE0_TX_DN<5>")
	)
	(arc
		(start 341.528146 -221.453202)
		(mid 341.399827 -221.32123)
		(end 341.349838 -221.144084)
		(width 0.0889)
		(layer "In15.Cu")
		(net "P5E_CPU0_PE0_TX_DN<5>")
	)
	(arc
		(start 337.212178 -216.574878)
		(mid 337.029673 -216.625116)
		(end 336.84591 -216.579704)
		(width 0.0889)
		(layer "In15.Cu")
		(net "P5E_CPU0_PE0_TX_DN<5>")
	)
	(arc
		(start 341.058246 -217.383614)
		(mid 340.927332 -217.247254)
		(end 340.879684 -217.064336)
		(width 0.0889)
		(layer "In15.Cu")
		(net "P5E_CPU0_PE0_TX_DN<5>")
	)
	(arc
		(start 341.997792 -222.267018)
		(mid 341.866878 -222.130658)
		(end 341.81923 -221.94774)
		(width 0.0889)
		(layer "In15.Cu")
		(net "P5E_CPU0_PE0_TX_DN<5>")
	)
	(arc
		(start 341.537036 -220.809566)
		(mid 341.819568 -220.320045)
		(end 341.537036 -219.830396)
		(width 0.0889)
		(layer "In15.Cu")
		(net "P5E_CPU0_PE0_TX_DN<5>")
	)
	(arc
		(start 342.799416 -224.738438)
		(mid 342.63532 -224.762785)
		(end 342.476836 -224.7138)
		(width 0.0889)
		(layer "In15.Cu")
		(net "P5E_CPU0_PE0_TX_DN<5>")
	)
	(arc
		(start 340.031832 -216.574878)
		(mid 339.844634 -216.625021)
		(end 339.657436 -216.574878)
		(width 0.0889)
		(layer "In15.Cu")
		(net "P5E_CPU0_PE0_TX_DN<5>")
	)
	(arc
		(start 342.759284 -223.561402)
		(mid 342.680143 -223.286779)
		(end 342.476836 -223.085914)
		(width 0.0889)
		(layer "In15.Cu")
		(net "P5E_CPU0_PE0_TX_DN<5>")
	)
	(arc
		(start 339.657436 -216.574878)
		(mid 339.374734 -216.499102)
		(end 339.092032 -216.574878)
		(width 0.0889)
		(layer "In15.Cu")
		(net "P5E_CPU0_PE0_TX_DN<5>")
	)
	(arc
		(start 338.152232 -216.574878)
		(mid 337.965034 -216.625021)
		(end 337.777836 -216.574878)
		(width 0.0889)
		(layer "In15.Cu")
		(net "P5E_CPU0_PE0_TX_DN<5>")
	)
	(arc
		(start 339.092032 -216.574878)
		(mid 338.904834 -216.625021)
		(end 338.717636 -216.574878)
		(width 0.0889)
		(layer "In15.Cu")
		(net "P5E_CPU0_PE0_TX_DN<5>")
	)
	(arc
		(start 337.767422 -216.568782)
		(mid 337.48899 -216.498936)
		(end 337.212178 -216.574878)
		(width 0.0889)
		(layer "In15.Cu")
		(net "P5E_CPU0_PE0_TX_DN<5>")
	)
	(arc
		(start 342.289384 -222.761556)
		(mid 342.215393 -222.48199)
		(end 342.012778 -222.275654)
		(width 0.0889)
		(layer "In15.Cu")
		(net "P5E_CPU0_PE0_TX_DN<5>")
	)
	(arc
		(start 340.597236 -216.574878)
		(mid 340.323037 -216.499043)
		(end 340.046564 -216.566242)
		(width 0.0889)
		(layer "In15.Cu")
		(net "P5E_CPU0_PE0_TX_DN<5>")
	)
	(arc
		(start 335.882996 -216.566242)
		(mid 335.606521 -216.498922)
		(end 335.332324 -216.574878)
		(width 0.0889)
		(layer "In15.Cu")
		(net "P5E_CPU0_PE0_TX_DN<5>")
	)
	(arc
		(start 341.537036 -219.18168)
		(mid 341.739859 -218.981449)
		(end 341.81923 -218.707716)
		(width 0.0889)
		(layer "In15.Cu")
		(net "P5E_CPU0_PE0_TX_DN<5>")
	)
	(arc
		(start 338.717636 -216.574878)
		(mid 338.443437 -216.499043)
		(end 338.166964 -216.566242)
		(width 0.0889)
		(layer "In15.Cu")
		(net "P5E_CPU0_PE0_TX_DN<5>")
	)
	(arc
		(start 342.289638 -222.776288)
		(mid 342.289441 -222.768923)
		(end 342.289384 -222.761556)
		(width 0.0889)
		(layer "In15.Cu")
		(net "P5E_CPU0_PE0_TX_DN<5>")
	)
	(segment
		(start 339.021928 -407.00452)
		(end 339.32749 -407.310082)
		(width 0.13208)
		(layer "F.Cu")
		(net "P5E_CPU0_PE0_TX_DN<4>")
	)
	(segment
		(start 342.194134 -224.111566)
		(end 342.194134 -223.57588)
		(width 0.13208)
		(layer "F.Cu")
		(net "P5E_CPU0_PE0_TX_DN<4>")
	)
	(segment
		(start 339.32749 -407.924254)
		(end 339.0011 -408.250644)
		(width 0.13208)
		(layer "F.Cu")
		(net "P5E_CPU0_PE0_TX_DN<4>")
	)
	(segment
		(start 339.32749 -407.310082)
		(end 339.32749 -407.924254)
		(width 0.13208)
		(layer "F.Cu")
		(net "P5E_CPU0_PE0_TX_DN<4>")
	)
	(segment
		(start 342.194134 -223.57588)
		(end 342.19388 -223.575626)
		(width 0.13208)
		(layer "F.Cu")
		(net "P5E_CPU0_PE0_TX_DN<4>")
	)
	(segment
		(start 339.0011 -408.250644)
		(end 338.996528 -408.250644)
		(width 0.13208)
		(layer "F.Cu")
		(net "P5E_CPU0_PE0_TX_DN<4>")
	)
	(segment
		(start 340.588346 -220.814646)
		(end 340.597236 -220.809566)
		(width 0.0889)
		(layer "In15.Cu")
		(net "P5E_CPU0_PE0_TX_DN<4>")
	)
	(segment
		(start 340.127082 -219.01658)
		(end 340.11235 -219.007944)
		(width 0.0889)
		(layer "In15.Cu")
		(net "P5E_CPU0_PE0_TX_DN<4>")
	)
	(segment
		(start 335.350358 -218.957398)
		(end 335.350358 -218.957144)
		(width 0.0889)
		(layer "In15.Cu")
		(net "P5E_CPU0_PE0_TX_DN<4>")
	)
	(segment
		(start 340.87943 -221.94774)
		(end 340.87943 -221.932246)
		(width 0.0889)
		(layer "In15.Cu")
		(net "P5E_CPU0_PE0_TX_DN<4>")
	)
	(segment
		(start 340.879684 -220.334078)
		(end 340.879684 -220.319854)
		(width 0.0889)
		(layer "In15.Cu")
		(net "P5E_CPU0_PE0_TX_DN<4>")
	)
	(segment
		(start 329.2475 -252.39345)
		(end 329.246992 -252.393196)
		(width 0.14732)
		(layer "In15.Cu")
		(net "P5E_CPU0_PE0_TX_DN<4>")
	)
	(segment
		(start 327.302876 -247.347486)
		(end 328.107802 -248.852436)
		(width 0.14732)
		(layer "In15.Cu")
		(net "P5E_CPU0_PE0_TX_DN<4>")
	)
	(segment
		(start 329.246992 -252.393196)
		(end 326.729598 -258.850892)
		(width 0.14732)
		(layer "In15.Cu")
		(net "P5E_CPU0_PE0_TX_DN<4>")
	)
	(segment
		(start 339.316568 -406.70988)
		(end 339.021928 -407.00452)
		(width 0.14732)
		(layer "In15.Cu")
		(net "P5E_CPU0_PE0_TX_DN<4>")
	)
	(segment
		(start 318.539368 -328.744072)
		(end 313.22264 -334.061054)
		(width 0.14732)
		(layer "In15.Cu")
		(net "P5E_CPU0_PE0_TX_DN<4>")
	)
	(segment
		(start 340.129368 -219.01785)
		(end 340.127082 -219.01658)
		(width 0.0889)
		(layer "In15.Cu")
		(net "P5E_CPU0_PE0_TX_DN<4>")
	)
	(segment
		(start 329.361546 -221.147386)
		(end 328.413364 -222.891096)
		(width 0.14732)
		(layer "In15.Cu")
		(net "P5E_CPU0_PE0_TX_DN<4>")
	)
	(segment
		(start 337.307682 -219.01658)
		(end 337.297268 -219.010484)
		(width 0.0889)
		(layer "In15.Cu")
		(net "P5E_CPU0_PE0_TX_DN<4>")
	)
	(segment
		(start 326.714612 -258.889754)
		(end 326.714358 -258.889754)
		(width 0.14732)
		(layer "In15.Cu")
		(net "P5E_CPU0_PE0_TX_DN<4>")
	)
	(segment
		(start 332.903068 -218.60002)
		(end 330.111354 -220.35008)
		(width 0.14732)
		(layer "In15.Cu")
		(net "P5E_CPU0_PE0_TX_DN<4>")
	)
	(segment
		(start 326.728582 -258.85394)
		(end 326.714612 -258.889754)
		(width 0.14732)
		(layer "In15.Cu")
		(net "P5E_CPU0_PE0_TX_DN<4>")
	)
	(segment
		(start 333.866998 -218.60002)
		(end 333.8449 -218.60002)
		(width 0.0889)
		(layer "In15.Cu")
		(net "P5E_CPU0_PE0_TX_DN<4>")
	)
	(segment
		(start 342.19388 -223.575626)
		(end 342.037416 -223.846644)
		(width 0.0889)
		(layer "In15.Cu")
		(net "P5E_CPU0_PE0_TX_DN<4>")
	)
	(segment
		(start 341.537036 -223.085914)
		(end 341.528146 -223.080834)
		(width 0.0889)
		(layer "In15.Cu")
		(net "P5E_CPU0_PE0_TX_DN<4>")
	)
	(segment
		(start 339.501988 -403.948138)
		(end 339.316568 -405.831548)
		(width 0.14732)
		(layer "In15.Cu")
		(net "P5E_CPU0_PE0_TX_DN<4>")
	)
	(segment
		(start 326.020176 -266.604496)
		(end 328.799698 -310.25465)
		(width 0.14732)
		(layer "In15.Cu")
		(net "P5E_CPU0_PE0_TX_DN<4>")
	)
	(segment
		(start 340.1314 -219.01912)
		(end 340.129368 -219.01785)
		(width 0.0889)
		(layer "In15.Cu")
		(net "P5E_CPU0_PE0_TX_DN<4>")
	)
	(segment
		(start 326.729598 -258.850892)
		(end 326.728582 -258.85394)
		(width 0.14732)
		(layer "In15.Cu")
		(net "P5E_CPU0_PE0_TX_DN<4>")
	)
	(segment
		(start 313.22264 -340.845902)
		(end 317.984632 -362.277406)
		(width 0.14732)
		(layer "In15.Cu")
		(net "P5E_CPU0_PE0_TX_DN<4>")
	)
	(segment
		(start 341.349838 -222.751396)
		(end 341.349584 -222.761556)
		(width 0.0889)
		(layer "In15.Cu")
		(net "P5E_CPU0_PE0_TX_DN<4>")
	)
	(segment
		(start 341.069676 -222.273622)
		(end 341.066882 -222.272098)
		(width 0.0889)
		(layer "In15.Cu")
		(net "P5E_CPU0_PE0_TX_DN<4>")
	)
	(segment
		(start 340.597236 -221.458282)
		(end 340.588346 -221.453202)
		(width 0.0889)
		(layer "In15.Cu")
		(net "P5E_CPU0_PE0_TX_DN<4>")
	)
	(segment
		(start 341.072978 -222.275654)
		(end 341.069676 -222.273622)
		(width 0.0889)
		(layer "In15.Cu")
		(net "P5E_CPU0_PE0_TX_DN<4>")
	)
	(segment
		(start 328.886058 -250.307602)
		(end 329.2475 -251.180092)
		(width 0.14732)
		(layer "In15.Cu")
		(net "P5E_CPU0_PE0_TX_DN<4>")
	)
	(segment
		(start 339.501988 -399.809462)
		(end 339.501988 -403.948138)
		(width 0.14732)
		(layer "In15.Cu")
		(net "P5E_CPU0_PE0_TX_DN<4>")
	)
	(segment
		(start 333.8449 -218.60002)
		(end 332.903068 -218.60002)
		(width 0.14732)
		(layer "In15.Cu")
		(net "P5E_CPU0_PE0_TX_DN<4>")
	)
	(segment
		(start 326.855582 -244.907054)
		(end 327.302876 -247.347486)
		(width 0.14732)
		(layer "In15.Cu")
		(net "P5E_CPU0_PE0_TX_DN<4>")
	)
	(segment
		(start 341.819484 -223.584262)
		(end 341.819484 -223.557084)
		(width 0.0889)
		(layer "In15.Cu")
		(net "P5E_CPU0_PE0_TX_DN<4>")
	)
	(segment
		(start 328.413364 -222.891096)
		(end 326.65289 -233.807508)
		(width 0.14732)
		(layer "In15.Cu")
		(net "P5E_CPU0_PE0_TX_DN<4>")
	)
	(segment
		(start 317.984632 -362.277406)
		(end 339.501988 -399.809462)
		(width 0.14732)
		(layer "In15.Cu")
		(net "P5E_CPU0_PE0_TX_DN<4>")
	)
	(segment
		(start 326.65289 -233.807508)
		(end 326.855582 -244.907054)
		(width 0.14732)
		(layer "In15.Cu")
		(net "P5E_CPU0_PE0_TX_DN<4>")
	)
	(segment
		(start 333.908908 -218.64193)
		(end 333.866998 -218.60002)
		(width 0.0889)
		(layer "In15.Cu")
		(net "P5E_CPU0_PE0_TX_DN<4>")
	)
	(segment
		(start 342.037416 -223.846644)
		(end 341.959438 -223.867472)
		(width 0.0889)
		(layer "In15.Cu")
		(net "P5E_CPU0_PE0_TX_DN<4>")
	)
	(segment
		(start 341.066882 -222.272098)
		(end 341.065358 -222.271336)
		(width 0.0889)
		(layer "In15.Cu")
		(net "P5E_CPU0_PE0_TX_DN<4>")
	)
	(segment
		(start 335.350358 -218.957144)
		(end 335.03489 -218.64193)
		(width 0.0889)
		(layer "In15.Cu")
		(net "P5E_CPU0_PE0_TX_DN<4>")
	)
	(segment
		(start 340.133178 -219.020136)
		(end 340.1314 -219.01912)
		(width 0.0889)
		(layer "In15.Cu")
		(net "P5E_CPU0_PE0_TX_DN<4>")
	)
	(segment
		(start 339.187282 -219.01658)
		(end 339.17255 -219.007944)
		(width 0.0889)
		(layer "In15.Cu")
		(net "P5E_CPU0_PE0_TX_DN<4>")
	)
	(segment
		(start 326.714358 -258.889754)
		(end 326.020176 -266.604496)
		(width 0.14732)
		(layer "In15.Cu")
		(net "P5E_CPU0_PE0_TX_DN<4>")
	)
	(segment
		(start 338.247482 -219.01658)
		(end 338.23275 -219.007944)
		(width 0.0889)
		(layer "In15.Cu")
		(net "P5E_CPU0_PE0_TX_DN<4>")
	)
	(segment
		(start 339.316568 -405.831548)
		(end 339.316568 -406.70988)
		(width 0.14732)
		(layer "In15.Cu")
		(net "P5E_CPU0_PE0_TX_DN<4>")
	)
	(segment
		(start 328.799698 -310.25465)
		(end 324.763892 -319.85458)
		(width 0.14732)
		(layer "In15.Cu")
		(net "P5E_CPU0_PE0_TX_DN<4>")
	)
	(segment
		(start 329.2475 -251.180092)
		(end 329.2475 -252.39345)
		(width 0.14732)
		(layer "In15.Cu")
		(net "P5E_CPU0_PE0_TX_DN<4>")
	)
	(segment
		(start 328.107802 -248.852436)
		(end 328.886058 -250.307602)
		(width 0.14732)
		(layer "In15.Cu")
		(net "P5E_CPU0_PE0_TX_DN<4>")
	)
	(segment
		(start 341.065358 -222.271336)
		(end 341.057992 -222.267018)
		(width 0.0889)
		(layer "In15.Cu")
		(net "P5E_CPU0_PE0_TX_DN<4>")
	)
	(segment
		(start 340.597236 -219.830396)
		(end 340.588346 -219.825316)
		(width 0.0889)
		(layer "In15.Cu")
		(net "P5E_CPU0_PE0_TX_DN<4>")
	)
	(segment
		(start 335.03489 -218.64193)
		(end 333.908908 -218.64193)
		(width 0.0889)
		(layer "In15.Cu")
		(net "P5E_CPU0_PE0_TX_DN<4>")
	)
	(segment
		(start 340.603332 -219.833952)
		(end 340.597236 -219.830396)
		(width 0.0889)
		(layer "In15.Cu")
		(net "P5E_CPU0_PE0_TX_DN<4>")
	)
	(segment
		(start 313.22264 -334.061054)
		(end 313.22264 -340.845902)
		(width 0.14732)
		(layer "In15.Cu")
		(net "P5E_CPU0_PE0_TX_DN<4>")
	)
	(segment
		(start 324.763892 -319.85458)
		(end 318.539368 -328.744072)
		(width 0.14732)
		(layer "In15.Cu")
		(net "P5E_CPU0_PE0_TX_DN<4>")
	)
	(segment
		(start 330.111354 -220.35008)
		(end 329.361546 -221.147386)
		(width 0.14732)
		(layer "In15.Cu")
		(net "P5E_CPU0_PE0_TX_DN<4>")
	)
	(arc
		(start 335.428336 -219.01658)
		(mid 335.387406 -218.989547)
		(end 335.350358 -218.957398)
		(width 0.0889)
		(layer "In15.Cu")
		(net "P5E_CPU0_PE0_TX_DN<4>")
	)
	(arc
		(start 335.802732 -219.01658)
		(mid 335.615534 -219.066723)
		(end 335.428336 -219.01658)
		(width 0.0889)
		(layer "In15.Cu")
		(net "P5E_CPU0_PE0_TX_DN<4>")
	)
	(arc
		(start 340.11235 -219.007944)
		(mid 339.835875 -218.940624)
		(end 339.561678 -219.01658)
		(width 0.0889)
		(layer "In15.Cu")
		(net "P5E_CPU0_PE0_TX_DN<4>")
	)
	(arc
		(start 339.17255 -219.007944)
		(mid 338.896075 -218.940624)
		(end 338.621878 -219.01658)
		(width 0.0889)
		(layer "In15.Cu")
		(net "P5E_CPU0_PE0_TX_DN<4>")
	)
	(arc
		(start 339.561678 -219.01658)
		(mid 339.37448 -219.066723)
		(end 339.187282 -219.01658)
		(width 0.0889)
		(layer "In15.Cu")
		(net "P5E_CPU0_PE0_TX_DN<4>")
	)
	(arc
		(start 340.588346 -221.453202)
		(mid 340.460027 -221.32123)
		(end 340.410038 -221.144084)
		(width 0.0889)
		(layer "In15.Cu")
		(net "P5E_CPU0_PE0_TX_DN<4>")
	)
	(arc
		(start 341.959438 -223.867472)
		(mid 341.858117 -223.741351)
		(end 341.819484 -223.584262)
		(width 0.0889)
		(layer "In15.Cu")
		(net "P5E_CPU0_PE0_TX_DN<4>")
	)
	(arc
		(start 341.349838 -222.773748)
		(mid 341.349671 -222.762572)
		(end 341.349838 -222.751396)
		(width 0.0889)
		(layer "In15.Cu")
		(net "P5E_CPU0_PE0_TX_DN<4>")
	)
	(arc
		(start 341.528146 -223.080834)
		(mid 341.400253 -222.949772)
		(end 341.349838 -222.773748)
		(width 0.0889)
		(layer "In15.Cu")
		(net "P5E_CPU0_PE0_TX_DN<4>")
	)
	(arc
		(start 337.682078 -219.01658)
		(mid 337.49488 -219.066723)
		(end 337.307682 -219.01658)
		(width 0.0889)
		(layer "In15.Cu")
		(net "P5E_CPU0_PE0_TX_DN<4>")
	)
	(arc
		(start 338.621878 -219.01658)
		(mid 338.43468 -219.066723)
		(end 338.247482 -219.01658)
		(width 0.0889)
		(layer "In15.Cu")
		(net "P5E_CPU0_PE0_TX_DN<4>")
	)
	(arc
		(start 340.410292 -221.119192)
		(mid 340.461202 -220.944623)
		(end 340.588346 -220.814646)
		(width 0.0889)
		(layer "In15.Cu")
		(net "P5E_CPU0_PE0_TX_DN<4>")
	)
	(arc
		(start 341.349584 -222.761556)
		(mid 341.275593 -222.48199)
		(end 341.072978 -222.275654)
		(width 0.0889)
		(layer "In15.Cu")
		(net "P5E_CPU0_PE0_TX_DN<4>")
	)
	(arc
		(start 340.87943 -221.932246)
		(mid 340.80006 -221.658512)
		(end 340.597236 -221.458282)
		(width 0.0889)
		(layer "In15.Cu")
		(net "P5E_CPU0_PE0_TX_DN<4>")
	)
	(arc
		(start 341.819484 -223.557084)
		(mid 341.739322 -223.284895)
		(end 341.537036 -223.085914)
		(width 0.0889)
		(layer "In15.Cu")
		(net "P5E_CPU0_PE0_TX_DN<4>")
	)
	(arc
		(start 340.879684 -220.319854)
		(mid 340.805768 -220.040352)
		(end 340.603332 -219.833952)
		(width 0.0889)
		(layer "In15.Cu")
		(net "P5E_CPU0_PE0_TX_DN<4>")
	)
	(arc
		(start 340.597236 -220.809566)
		(mid 340.800541 -220.6087)
		(end 340.879684 -220.334078)
		(width 0.0889)
		(layer "In15.Cu")
		(net "P5E_CPU0_PE0_TX_DN<4>")
	)
	(arc
		(start 336.368136 -219.01658)
		(mid 336.085434 -218.940804)
		(end 335.802732 -219.01658)
		(width 0.0889)
		(layer "In15.Cu")
		(net "P5E_CPU0_PE0_TX_DN<4>")
	)
	(arc
		(start 340.410038 -221.144084)
		(mid 340.409958 -221.131636)
		(end 340.410292 -221.119192)
		(width 0.0889)
		(layer "In15.Cu")
		(net "P5E_CPU0_PE0_TX_DN<4>")
	)
	(arc
		(start 338.23275 -219.007944)
		(mid 337.956275 -218.940624)
		(end 337.682078 -219.01658)
		(width 0.0889)
		(layer "In15.Cu")
		(net "P5E_CPU0_PE0_TX_DN<4>")
	)
	(arc
		(start 341.057992 -222.267018)
		(mid 340.927078 -222.130658)
		(end 340.87943 -221.94774)
		(width 0.0889)
		(layer "In15.Cu")
		(net "P5E_CPU0_PE0_TX_DN<4>")
	)
	(arc
		(start 336.742532 -219.01658)
		(mid 336.555334 -219.066723)
		(end 336.368136 -219.01658)
		(width 0.0889)
		(layer "In15.Cu")
		(net "P5E_CPU0_PE0_TX_DN<4>")
	)
	(arc
		(start 337.297268 -219.010484)
		(mid 337.01909 -218.940761)
		(end 336.742532 -219.01658)
		(width 0.0889)
		(layer "In15.Cu")
		(net "P5E_CPU0_PE0_TX_DN<4>")
	)
	(arc
		(start 340.588346 -219.825316)
		(mid 340.457432 -219.688956)
		(end 340.409784 -219.506038)
		(width 0.0889)
		(layer "In15.Cu")
		(net "P5E_CPU0_PE0_TX_DN<4>")
	)
	(arc
		(start 340.409784 -219.506038)
		(mid 340.335793 -219.226472)
		(end 340.133178 -219.020136)
		(width 0.0889)
		(layer "In15.Cu")
		(net "P5E_CPU0_PE0_TX_DN<4>")
	)
	(segment
		(start 342.39073 -407.924254)
		(end 342.06434 -408.250644)
		(width 0.13208)
		(layer "F.Cu")
		(net "P5E_CPU0_PE0_TX_DN<3>")
	)
	(segment
		(start 340.78418 -224.925382)
		(end 340.78418 -224.389696)
		(width 0.13208)
		(layer "F.Cu")
		(net "P5E_CPU0_PE0_TX_DN<3>")
	)
	(segment
		(start 342.06434 -408.250644)
		(end 342.059768 -408.250644)
		(width 0.13208)
		(layer "F.Cu")
		(net "P5E_CPU0_PE0_TX_DN<3>")
	)
	(segment
		(start 342.085168 -407.00452)
		(end 342.39073 -407.310082)
		(width 0.13208)
		(layer "F.Cu")
		(net "P5E_CPU0_PE0_TX_DN<3>")
	)
	(segment
		(start 340.78418 -224.389696)
		(end 340.784434 -224.389442)
		(width 0.13208)
		(layer "F.Cu")
		(net "P5E_CPU0_PE0_TX_DN<3>")
	)
	(segment
		(start 342.39073 -407.310082)
		(end 342.39073 -407.924254)
		(width 0.13208)
		(layer "F.Cu")
		(net "P5E_CPU0_PE0_TX_DN<3>")
	)
	(segment
		(start 330.17841 -252.579124)
		(end 328.912982 -255.824736)
		(width 0.14732)
		(layer "In15.Cu")
		(net "P5E_CPU0_PE0_TX_DN<3>")
	)
	(segment
		(start 339.657436 -221.458282)
		(end 339.648546 -221.453202)
		(width 0.0889)
		(layer "In15.Cu")
		(net "P5E_CPU0_PE0_TX_DN<3>")
	)
	(segment
		(start 329.748134 -310.444896)
		(end 325.491348 -320.557906)
		(width 0.14732)
		(layer "In15.Cu")
		(net "P5E_CPU0_PE0_TX_DN<3>")
	)
	(segment
		(start 333.908908 -219.88145)
		(end 333.866998 -219.83954)
		(width 0.0889)
		(layer "In15.Cu")
		(net "P5E_CPU0_PE0_TX_DN<3>")
	)
	(segment
		(start 327.627742 -233.931206)
		(end 327.840848 -245.046246)
		(width 0.14732)
		(layer "In15.Cu")
		(net "P5E_CPU0_PE0_TX_DN<3>")
	)
	(segment
		(start 325.491348 -320.557906)
		(end 319.383156 -329.281028)
		(width 0.14732)
		(layer "In15.Cu")
		(net "P5E_CPU0_PE0_TX_DN<3>")
	)
	(segment
		(start 340.133178 -222.275654)
		(end 340.129876 -222.273622)
		(width 0.0889)
		(layer "In15.Cu")
		(net "P5E_CPU0_PE0_TX_DN<3>")
	)
	(segment
		(start 338.723732 -219.833952)
		(end 338.717636 -219.830396)
		(width 0.0889)
		(layer "In15.Cu")
		(net "P5E_CPU0_PE0_TX_DN<3>")
	)
	(segment
		(start 328.191368 -247.036082)
		(end 329.729084 -249.912124)
		(width 0.14732)
		(layer "In15.Cu")
		(net "P5E_CPU0_PE0_TX_DN<3>")
	)
	(segment
		(start 326.95769 -266.616688)
		(end 329.748134 -310.444896)
		(width 0.14732)
		(layer "In15.Cu")
		(net "P5E_CPU0_PE0_TX_DN<3>")
	)
	(segment
		(start 342.379808 -405.831548)
		(end 342.379808 -406.70988)
		(width 0.14732)
		(layer "In15.Cu")
		(net "P5E_CPU0_PE0_TX_DN<3>")
	)
	(segment
		(start 340.127082 -222.272098)
		(end 340.125558 -222.271336)
		(width 0.0889)
		(layer "In15.Cu")
		(net "P5E_CPU0_PE0_TX_DN<3>")
	)
	(segment
		(start 340.410038 -222.751396)
		(end 340.409784 -222.761556)
		(width 0.0889)
		(layer "In15.Cu")
		(net "P5E_CPU0_PE0_TX_DN<3>")
	)
	(segment
		(start 327.633838 -259.105654)
		(end 326.95769 -266.616688)
		(width 0.14732)
		(layer "In15.Cu")
		(net "P5E_CPU0_PE0_TX_DN<3>")
	)
	(segment
		(start 339.469984 -221.133924)
		(end 339.469984 -221.115382)
		(width 0.0889)
		(layer "In15.Cu")
		(net "P5E_CPU0_PE0_TX_DN<3>")
	)
	(segment
		(start 340.597236 -224.7138)
		(end 340.588346 -224.70872)
		(width 0.0889)
		(layer "In15.Cu")
		(net "P5E_CPU0_PE0_TX_DN<3>")
	)
	(segment
		(start 342.565228 -403.948138)
		(end 342.379808 -405.831548)
		(width 0.14732)
		(layer "In15.Cu")
		(net "P5E_CPU0_PE0_TX_DN<3>")
	)
	(segment
		(start 333.27086 -219.83954)
		(end 330.24318 -221.628462)
		(width 0.14732)
		(layer "In15.Cu")
		(net "P5E_CPU0_PE0_TX_DN<3>")
	)
	(segment
		(start 328.912728 -255.825498)
		(end 327.633838 -259.105654)
		(width 0.14732)
		(layer "In15.Cu")
		(net "P5E_CPU0_PE0_TX_DN<3>")
	)
	(segment
		(start 334.957928 -219.830396)
		(end 334.93456 -219.816934)
		(width 0.0889)
		(layer "In15.Cu")
		(net "P5E_CPU0_PE0_TX_DN<3>")
	)
	(segment
		(start 339.93963 -221.94774)
		(end 339.93963 -221.932246)
		(width 0.0889)
		(layer "In15.Cu")
		(net "P5E_CPU0_PE0_TX_DN<3>")
	)
	(segment
		(start 340.784434 -224.389442)
		(end 340.940898 -224.66046)
		(width 0.0889)
		(layer "In15.Cu")
		(net "P5E_CPU0_PE0_TX_DN<3>")
	)
	(segment
		(start 335.346548 -219.82176)
		(end 335.331816 -219.830396)
		(width 0.0889)
		(layer "In15.Cu")
		(net "P5E_CPU0_PE0_TX_DN<3>")
	)
	(segment
		(start 333.8449 -219.83954)
		(end 333.27086 -219.83954)
		(width 0.14732)
		(layer "In15.Cu")
		(net "P5E_CPU0_PE0_TX_DN<3>")
	)
	(segment
		(start 340.588346 -224.070164)
		(end 340.597236 -224.065084)
		(width 0.0889)
		(layer "In15.Cu")
		(net "P5E_CPU0_PE0_TX_DN<3>")
	)
	(segment
		(start 330.24318 -221.628462)
		(end 329.420728 -223.036384)
		(width 0.14732)
		(layer "In15.Cu")
		(net "P5E_CPU0_PE0_TX_DN<3>")
	)
	(segment
		(start 329.729084 -249.912124)
		(end 330.181966 -251.006102)
		(width 0.14732)
		(layer "In15.Cu")
		(net "P5E_CPU0_PE0_TX_DN<3>")
	)
	(segment
		(start 339.187536 -220.644212)
		(end 339.178646 -220.639132)
		(width 0.0889)
		(layer "In15.Cu")
		(net "P5E_CPU0_PE0_TX_DN<3>")
	)
	(segment
		(start 334.969866 -219.837254)
		(end 334.957928 -219.830396)
		(width 0.0889)
		(layer "In15.Cu")
		(net "P5E_CPU0_PE0_TX_DN<3>")
	)
	(segment
		(start 342.379808 -406.70988)
		(end 342.085168 -407.00452)
		(width 0.14732)
		(layer "In15.Cu")
		(net "P5E_CPU0_PE0_TX_DN<3>")
	)
	(segment
		(start 342.565228 -399.910808)
		(end 342.565228 -403.948138)
		(width 0.14732)
		(layer "In15.Cu")
		(net "P5E_CPU0_PE0_TX_DN<3>")
	)
	(segment
		(start 319.383156 -329.281028)
		(end 314.15228 -334.512158)
		(width 0.14732)
		(layer "In15.Cu")
		(net "P5E_CPU0_PE0_TX_DN<3>")
	)
	(segment
		(start 314.15228 -334.512158)
		(end 314.15228 -340.64067)
		(width 0.14732)
		(layer "In15.Cu")
		(net "P5E_CPU0_PE0_TX_DN<3>")
	)
	(segment
		(start 327.840848 -245.046246)
		(end 328.191368 -247.036082)
		(width 0.14732)
		(layer "In15.Cu")
		(net "P5E_CPU0_PE0_TX_DN<3>")
	)
	(segment
		(start 314.15228 -340.64067)
		(end 318.879474 -361.914694)
		(width 0.14732)
		(layer "In15.Cu")
		(net "P5E_CPU0_PE0_TX_DN<3>")
	)
	(segment
		(start 340.879684 -223.575626)
		(end 340.879684 -223.561402)
		(width 0.0889)
		(layer "In15.Cu")
		(net "P5E_CPU0_PE0_TX_DN<3>")
	)
	(segment
		(start 340.940898 -224.66046)
		(end 340.919816 -224.738438)
		(width 0.0889)
		(layer "In15.Cu")
		(net "P5E_CPU0_PE0_TX_DN<3>")
	)
	(segment
		(start 328.912982 -255.824736)
		(end 328.912728 -255.825498)
		(width 0.14732)
		(layer "In15.Cu")
		(net "P5E_CPU0_PE0_TX_DN<3>")
	)
	(segment
		(start 333.866998 -219.83954)
		(end 333.8449 -219.83954)
		(width 0.0889)
		(layer "In15.Cu")
		(net "P5E_CPU0_PE0_TX_DN<3>")
	)
	(segment
		(start 340.129876 -222.273622)
		(end 340.127082 -222.272098)
		(width 0.0889)
		(layer "In15.Cu")
		(net "P5E_CPU0_PE0_TX_DN<3>")
	)
	(segment
		(start 334.204564 -219.88145)
		(end 333.908908 -219.88145)
		(width 0.0889)
		(layer "In15.Cu")
		(net "P5E_CPU0_PE0_TX_DN<3>")
	)
	(segment
		(start 330.181966 -252.569218)
		(end 330.181712 -252.569218)
		(width 0.14732)
		(layer "In15.Cu")
		(net "P5E_CPU0_PE0_TX_DN<3>")
	)
	(segment
		(start 330.181712 -252.569218)
		(end 330.17841 -252.579124)
		(width 0.14732)
		(layer "In15.Cu")
		(net "P5E_CPU0_PE0_TX_DN<3>")
	)
	(segment
		(start 340.125558 -222.271336)
		(end 340.118192 -222.267018)
		(width 0.0889)
		(layer "In15.Cu")
		(net "P5E_CPU0_PE0_TX_DN<3>")
	)
	(segment
		(start 340.597236 -224.065084)
		(end 340.603332 -224.061528)
		(width 0.0889)
		(layer "In15.Cu")
		(net "P5E_CPU0_PE0_TX_DN<3>")
	)
	(segment
		(start 336.272632 -219.830396)
		(end 336.260694 -219.837254)
		(width 0.0889)
		(layer "In15.Cu")
		(net "P5E_CPU0_PE0_TX_DN<3>")
	)
	(segment
		(start 330.181966 -251.006102)
		(end 330.181966 -252.569218)
		(width 0.14732)
		(layer "In15.Cu")
		(net "P5E_CPU0_PE0_TX_DN<3>")
	)
	(segment
		(start 318.879474 -361.914694)
		(end 342.565228 -399.910808)
		(width 0.14732)
		(layer "In15.Cu")
		(net "P5E_CPU0_PE0_TX_DN<3>")
	)
	(segment
		(start 340.597236 -223.085914)
		(end 340.588346 -223.080834)
		(width 0.0889)
		(layer "In15.Cu")
		(net "P5E_CPU0_PE0_TX_DN<3>")
	)
	(segment
		(start 329.420728 -223.036384)
		(end 327.627742 -233.931206)
		(width 0.14732)
		(layer "In15.Cu")
		(net "P5E_CPU0_PE0_TX_DN<3>")
	)
	(segment
		(start 338.166964 -219.82176)
		(end 338.152232 -219.830396)
		(width 0.0889)
		(layer "In15.Cu")
		(net "P5E_CPU0_PE0_TX_DN<3>")
	)
	(arc
		(start 339.469984 -221.115382)
		(mid 339.389822 -220.843193)
		(end 339.187536 -220.644212)
		(width 0.0889)
		(layer "In15.Cu")
		(net "P5E_CPU0_PE0_TX_DN<3>")
	)
	(arc
		(start 340.588346 -224.70872)
		(mid 340.40987 -224.389442)
		(end 340.588346 -224.070164)
		(width 0.0889)
		(layer "In15.Cu")
		(net "P5E_CPU0_PE0_TX_DN<3>")
	)
	(arc
		(start 336.838036 -219.830396)
		(mid 336.555334 -219.75462)
		(end 336.272632 -219.830396)
		(width 0.0889)
		(layer "In15.Cu")
		(net "P5E_CPU0_PE0_TX_DN<3>")
	)
	(arc
		(start 340.919816 -224.738438)
		(mid 340.75572 -224.762785)
		(end 340.597236 -224.7138)
		(width 0.0889)
		(layer "In15.Cu")
		(net "P5E_CPU0_PE0_TX_DN<3>")
	)
	(arc
		(start 337.777836 -219.830396)
		(mid 337.495134 -219.75462)
		(end 337.212432 -219.830396)
		(width 0.0889)
		(layer "In15.Cu")
		(net "P5E_CPU0_PE0_TX_DN<3>")
	)
	(arc
		(start 340.879684 -223.561402)
		(mid 340.800543 -223.286779)
		(end 340.597236 -223.085914)
		(width 0.0889)
		(layer "In15.Cu")
		(net "P5E_CPU0_PE0_TX_DN<3>")
	)
	(arc
		(start 340.410292 -222.776288)
		(mid 340.409959 -222.763844)
		(end 340.410038 -222.751396)
		(width 0.0889)
		(layer "In15.Cu")
		(net "P5E_CPU0_PE0_TX_DN<3>")
	)
	(arc
		(start 339.178646 -220.639132)
		(mid 339.047732 -220.502772)
		(end 339.000084 -220.319854)
		(width 0.0889)
		(layer "In15.Cu")
		(net "P5E_CPU0_PE0_TX_DN<3>")
	)
	(arc
		(start 340.118192 -222.267018)
		(mid 339.987278 -222.130658)
		(end 339.93963 -221.94774)
		(width 0.0889)
		(layer "In15.Cu")
		(net "P5E_CPU0_PE0_TX_DN<3>")
	)
	(arc
		(start 335.331816 -219.830396)
		(mid 335.151723 -219.880472)
		(end 334.969866 -219.837254)
		(width 0.0889)
		(layer "In15.Cu")
		(net "P5E_CPU0_PE0_TX_DN<3>")
	)
	(arc
		(start 337.212432 -219.830396)
		(mid 337.025234 -219.880539)
		(end 336.838036 -219.830396)
		(width 0.0889)
		(layer "In15.Cu")
		(net "P5E_CPU0_PE0_TX_DN<3>")
	)
	(arc
		(start 335.897728 -219.830396)
		(mid 335.623275 -219.754433)
		(end 335.346548 -219.82176)
		(width 0.0889)
		(layer "In15.Cu")
		(net "P5E_CPU0_PE0_TX_DN<3>")
	)
	(arc
		(start 338.717636 -219.830396)
		(mid 338.443437 -219.754561)
		(end 338.166964 -219.82176)
		(width 0.0889)
		(layer "In15.Cu")
		(net "P5E_CPU0_PE0_TX_DN<3>")
	)
	(arc
		(start 340.588346 -223.080834)
		(mid 340.461266 -222.95082)
		(end 340.410292 -222.776288)
		(width 0.0889)
		(layer "In15.Cu")
		(net "P5E_CPU0_PE0_TX_DN<3>")
	)
	(arc
		(start 339.000084 -220.319854)
		(mid 338.926168 -220.040352)
		(end 338.723732 -219.833952)
		(width 0.0889)
		(layer "In15.Cu")
		(net "P5E_CPU0_PE0_TX_DN<3>")
	)
	(arc
		(start 339.93963 -221.932246)
		(mid 339.86026 -221.658512)
		(end 339.657436 -221.458282)
		(width 0.0889)
		(layer "In15.Cu")
		(net "P5E_CPU0_PE0_TX_DN<3>")
	)
	(arc
		(start 336.260694 -219.837254)
		(mid 336.078329 -219.880697)
		(end 335.897728 -219.830396)
		(width 0.0889)
		(layer "In15.Cu")
		(net "P5E_CPU0_PE0_TX_DN<3>")
	)
	(arc
		(start 340.603332 -224.061528)
		(mid 340.805745 -223.855115)
		(end 340.879684 -223.575626)
		(width 0.0889)
		(layer "In15.Cu")
		(net "P5E_CPU0_PE0_TX_DN<3>")
	)
	(arc
		(start 338.152232 -219.830396)
		(mid 337.965034 -219.880539)
		(end 337.777836 -219.830396)
		(width 0.0889)
		(layer "In15.Cu")
		(net "P5E_CPU0_PE0_TX_DN<3>")
	)
	(arc
		(start 334.39227 -219.830396)
		(mid 334.30178 -219.868282)
		(end 334.204564 -219.88145)
		(width 0.0889)
		(layer "In15.Cu")
		(net "P5E_CPU0_PE0_TX_DN<3>")
	)
	(arc
		(start 340.409784 -222.761556)
		(mid 340.335793 -222.48199)
		(end 340.133178 -222.275654)
		(width 0.0889)
		(layer "In15.Cu")
		(net "P5E_CPU0_PE0_TX_DN<3>")
	)
	(arc
		(start 334.93456 -219.816934)
		(mid 334.661696 -219.754414)
		(end 334.39227 -219.830396)
		(width 0.0889)
		(layer "In15.Cu")
		(net "P5E_CPU0_PE0_TX_DN<3>")
	)
	(arc
		(start 339.648546 -221.453202)
		(mid 339.517632 -221.316842)
		(end 339.469984 -221.133924)
		(width 0.0889)
		(layer "In15.Cu")
		(net "P5E_CPU0_PE0_TX_DN<3>")
	)
	(segment
		(start 345.12758 -408.250644)
		(end 345.123008 -408.250644)
		(width 0.13208)
		(layer "F.Cu")
		(net "P5E_CPU0_PE0_TX_DN<2>")
	)
	(segment
		(start 340.314534 -224.111566)
		(end 340.314534 -223.57588)
		(width 0.13208)
		(layer "F.Cu")
		(net "P5E_CPU0_PE0_TX_DN<2>")
	)
	(segment
		(start 345.148408 -407.00452)
		(end 345.45397 -407.310082)
		(width 0.13208)
		(layer "F.Cu")
		(net "P5E_CPU0_PE0_TX_DN<2>")
	)
	(segment
		(start 345.45397 -407.924254)
		(end 345.12758 -408.250644)
		(width 0.13208)
		(layer "F.Cu")
		(net "P5E_CPU0_PE0_TX_DN<2>")
	)
	(segment
		(start 345.45397 -407.310082)
		(end 345.45397 -407.924254)
		(width 0.13208)
		(layer "F.Cu")
		(net "P5E_CPU0_PE0_TX_DN<2>")
	)
	(segment
		(start 340.314534 -223.57588)
		(end 340.31428 -223.575626)
		(width 0.13208)
		(layer "F.Cu")
		(net "P5E_CPU0_PE0_TX_DN<2>")
	)
	(segment
		(start 330.950316 -222.329248)
		(end 330.399644 -223.221296)
		(width 0.14732)
		(layer "In15.Cu")
		(net "P5E_CPU0_PE0_TX_DN<2>")
	)
	(segment
		(start 340.31428 -223.575626)
		(end 340.157816 -223.846644)
		(width 0.0889)
		(layer "In15.Cu")
		(net "P5E_CPU0_PE0_TX_DN<2>")
	)
	(segment
		(start 337.307682 -222.272098)
		(end 337.297268 -222.266002)
		(width 0.0889)
		(layer "In15.Cu")
		(net "P5E_CPU0_PE0_TX_DN<2>")
	)
	(segment
		(start 331.320394 -222.154242)
		(end 330.950316 -222.329248)
		(width 0.14732)
		(layer "In15.Cu")
		(net "P5E_CPU0_PE0_TX_DN<2>")
	)
	(segment
		(start 331.121258 -252.746256)
		(end 328.558144 -259.322824)
		(width 0.14732)
		(layer "In15.Cu")
		(net "P5E_CPU0_PE0_TX_DN<2>")
	)
	(segment
		(start 328.578718 -234.03306)
		(end 328.785474 -244.794024)
		(width 0.14732)
		(layer "In15.Cu")
		(net "P5E_CPU0_PE0_TX_DN<2>")
	)
	(segment
		(start 340.157816 -223.846644)
		(end 340.079838 -223.867472)
		(width 0.0889)
		(layer "In15.Cu")
		(net "P5E_CPU0_PE0_TX_DN<2>")
	)
	(segment
		(start 330.706984 -310.718454)
		(end 326.430386 -320.88074)
		(width 0.14732)
		(layer "In15.Cu")
		(net "P5E_CPU0_PE0_TX_DN<2>")
	)
	(segment
		(start 328.558144 -259.322824)
		(end 327.900284 -266.62888)
		(width 0.14732)
		(layer "In15.Cu")
		(net "P5E_CPU0_PE0_TX_DN<2>")
	)
	(segment
		(start 326.430386 -320.88074)
		(end 320.133218 -329.873864)
		(width 0.14732)
		(layer "In15.Cu")
		(net "P5E_CPU0_PE0_TX_DN<2>")
	)
	(segment
		(start 345.443048 -406.70988)
		(end 345.148408 -407.00452)
		(width 0.14732)
		(layer "In15.Cu")
		(net "P5E_CPU0_PE0_TX_DN<2>")
	)
	(segment
		(start 338.247482 -222.272098)
		(end 338.23275 -222.263462)
		(width 0.0889)
		(layer "In15.Cu")
		(net "P5E_CPU0_PE0_TX_DN<2>")
	)
	(segment
		(start 345.443048 -405.831548)
		(end 345.443048 -406.70988)
		(width 0.14732)
		(layer "In15.Cu")
		(net "P5E_CPU0_PE0_TX_DN<2>")
	)
	(segment
		(start 339.657436 -223.085914)
		(end 339.648546 -223.080834)
		(width 0.0889)
		(layer "In15.Cu")
		(net "P5E_CPU0_PE0_TX_DN<2>")
	)
	(segment
		(start 315.16828 -340.663022)
		(end 319.815464 -361.57662)
		(width 0.14732)
		(layer "In15.Cu")
		(net "P5E_CPU0_PE0_TX_DN<2>")
	)
	(segment
		(start 333.26578 -222.196152)
		(end 331.796136 -222.196152)
		(width 0.0889)
		(layer "In15.Cu")
		(net "P5E_CPU0_PE0_TX_DN<2>")
	)
	(segment
		(start 345.158822 -399.213324)
		(end 345.628468 -400.751802)
		(width 0.14732)
		(layer "In15.Cu")
		(net "P5E_CPU0_PE0_TX_DN<2>")
	)
	(segment
		(start 345.628468 -400.751802)
		(end 345.628468 -403.948138)
		(width 0.14732)
		(layer "In15.Cu")
		(net "P5E_CPU0_PE0_TX_DN<2>")
	)
	(segment
		(start 345.628468 -403.948138)
		(end 345.443048 -405.831548)
		(width 0.14732)
		(layer "In15.Cu")
		(net "P5E_CPU0_PE0_TX_DN<2>")
	)
	(segment
		(start 330.572872 -249.51817)
		(end 331.121512 -250.843796)
		(width 0.14732)
		(layer "In15.Cu")
		(net "P5E_CPU0_PE0_TX_DN<2>")
	)
	(segment
		(start 320.133218 -329.873864)
		(end 315.16828 -334.839056)
		(width 0.14732)
		(layer "In15.Cu")
		(net "P5E_CPU0_PE0_TX_DN<2>")
	)
	(segment
		(start 329.08113 -246.727726)
		(end 330.572872 -249.51817)
		(width 0.14732)
		(layer "In15.Cu")
		(net "P5E_CPU0_PE0_TX_DN<2>")
	)
	(segment
		(start 339.939884 -223.584262)
		(end 339.939884 -223.557084)
		(width 0.0889)
		(layer "In15.Cu")
		(net "P5E_CPU0_PE0_TX_DN<2>")
	)
	(segment
		(start 339.172042 -222.263462)
		(end 339.17255 -222.263462)
		(width 0.0889)
		(layer "In15.Cu")
		(net "P5E_CPU0_PE0_TX_DN<2>")
	)
	(segment
		(start 328.785474 -244.794024)
		(end 328.785474 -245.045484)
		(width 0.14732)
		(layer "In15.Cu")
		(net "P5E_CPU0_PE0_TX_DN<2>")
	)
	(segment
		(start 331.796136 -222.196152)
		(end 331.754226 -222.154242)
		(width 0.0889)
		(layer "In15.Cu")
		(net "P5E_CPU0_PE0_TX_DN<2>")
	)
	(segment
		(start 331.121512 -252.746256)
		(end 331.121258 -252.746256)
		(width 0.14732)
		(layer "In15.Cu")
		(net "P5E_CPU0_PE0_TX_DN<2>")
	)
	(segment
		(start 335.580736 -384.98907)
		(end 345.158822 -399.213324)
		(width 0.14732)
		(layer "In15.Cu")
		(net "P5E_CPU0_PE0_TX_DN<2>")
	)
	(segment
		(start 335.580736 -384.989324)
		(end 335.580736 -384.98907)
		(width 0.14732)
		(layer "In15.Cu")
		(net "P5E_CPU0_PE0_TX_DN<2>")
	)
	(segment
		(start 331.732128 -222.154242)
		(end 331.320394 -222.154242)
		(width 0.14732)
		(layer "In15.Cu")
		(net "P5E_CPU0_PE0_TX_DN<2>")
	)
	(segment
		(start 328.785474 -245.045484)
		(end 329.08113 -246.727726)
		(width 0.14732)
		(layer "In15.Cu")
		(net "P5E_CPU0_PE0_TX_DN<2>")
	)
	(segment
		(start 319.815464 -361.57662)
		(end 335.580736 -384.989324)
		(width 0.14732)
		(layer "In15.Cu")
		(net "P5E_CPU0_PE0_TX_DN<2>")
	)
	(segment
		(start 339.470238 -222.751396)
		(end 339.469984 -222.761556)
		(width 0.0889)
		(layer "In15.Cu")
		(net "P5E_CPU0_PE0_TX_DN<2>")
	)
	(segment
		(start 315.16828 -334.839056)
		(end 315.16828 -340.663022)
		(width 0.14732)
		(layer "In15.Cu")
		(net "P5E_CPU0_PE0_TX_DN<2>")
	)
	(segment
		(start 327.900284 -266.62888)
		(end 330.706984 -310.718454)
		(width 0.14732)
		(layer "In15.Cu")
		(net "P5E_CPU0_PE0_TX_DN<2>")
	)
	(segment
		(start 331.754226 -222.154242)
		(end 331.732128 -222.154242)
		(width 0.0889)
		(layer "In15.Cu")
		(net "P5E_CPU0_PE0_TX_DN<2>")
	)
	(segment
		(start 330.399644 -223.221296)
		(end 328.578718 -234.03306)
		(width 0.14732)
		(layer "In15.Cu")
		(net "P5E_CPU0_PE0_TX_DN<2>")
	)
	(segment
		(start 339.193378 -222.275654)
		(end 339.172042 -222.263462)
		(width 0.0889)
		(layer "In15.Cu")
		(net "P5E_CPU0_PE0_TX_DN<2>")
	)
	(segment
		(start 331.121512 -250.843796)
		(end 331.121512 -252.746256)
		(width 0.14732)
		(layer "In15.Cu")
		(net "P5E_CPU0_PE0_TX_DN<2>")
	)
	(arc
		(start 336.368136 -222.272098)
		(mid 336.085434 -222.196322)
		(end 335.802732 -222.272098)
		(width 0.0889)
		(layer "In15.Cu")
		(net "P5E_CPU0_PE0_TX_DN<2>")
	)
	(arc
		(start 337.682078 -222.272098)
		(mid 337.49488 -222.322241)
		(end 337.307682 -222.272098)
		(width 0.0889)
		(layer "In15.Cu")
		(net "P5E_CPU0_PE0_TX_DN<2>")
	)
	(arc
		(start 337.297268 -222.266002)
		(mid 337.01909 -222.196279)
		(end 336.742532 -222.272098)
		(width 0.0889)
		(layer "In15.Cu")
		(net "P5E_CPU0_PE0_TX_DN<2>")
	)
	(arc
		(start 338.23275 -222.263462)
		(mid 337.956275 -222.196142)
		(end 337.682078 -222.272098)
		(width 0.0889)
		(layer "In15.Cu")
		(net "P5E_CPU0_PE0_TX_DN<2>")
	)
	(arc
		(start 333.923132 -222.272098)
		(mid 333.735934 -222.322241)
		(end 333.548736 -222.272098)
		(width 0.0889)
		(layer "In15.Cu")
		(net "P5E_CPU0_PE0_TX_DN<2>")
	)
	(arc
		(start 334.488536 -222.272098)
		(mid 334.205834 -222.196322)
		(end 333.923132 -222.272098)
		(width 0.0889)
		(layer "In15.Cu")
		(net "P5E_CPU0_PE0_TX_DN<2>")
	)
	(arc
		(start 338.621878 -222.272098)
		(mid 338.43468 -222.322241)
		(end 338.247482 -222.272098)
		(width 0.0889)
		(layer "In15.Cu")
		(net "P5E_CPU0_PE0_TX_DN<2>")
	)
	(arc
		(start 339.939884 -223.557084)
		(mid 339.859722 -223.284895)
		(end 339.657436 -223.085914)
		(width 0.0889)
		(layer "In15.Cu")
		(net "P5E_CPU0_PE0_TX_DN<2>")
	)
	(arc
		(start 339.470238 -222.773748)
		(mid 339.470071 -222.762572)
		(end 339.470238 -222.751396)
		(width 0.0889)
		(layer "In15.Cu")
		(net "P5E_CPU0_PE0_TX_DN<2>")
	)
	(arc
		(start 335.802732 -222.272098)
		(mid 335.615534 -222.322241)
		(end 335.428336 -222.272098)
		(width 0.0889)
		(layer "In15.Cu")
		(net "P5E_CPU0_PE0_TX_DN<2>")
	)
	(arc
		(start 335.428336 -222.272098)
		(mid 335.145634 -222.196322)
		(end 334.862932 -222.272098)
		(width 0.0889)
		(layer "In15.Cu")
		(net "P5E_CPU0_PE0_TX_DN<2>")
	)
	(arc
		(start 339.648546 -223.080834)
		(mid 339.520653 -222.949772)
		(end 339.470238 -222.773748)
		(width 0.0889)
		(layer "In15.Cu")
		(net "P5E_CPU0_PE0_TX_DN<2>")
	)
	(arc
		(start 339.17255 -222.263462)
		(mid 338.896075 -222.196142)
		(end 338.621878 -222.272098)
		(width 0.0889)
		(layer "In15.Cu")
		(net "P5E_CPU0_PE0_TX_DN<2>")
	)
	(arc
		(start 340.079838 -223.867472)
		(mid 339.978517 -223.741351)
		(end 339.939884 -223.584262)
		(width 0.0889)
		(layer "In15.Cu")
		(net "P5E_CPU0_PE0_TX_DN<2>")
	)
	(arc
		(start 336.742532 -222.272098)
		(mid 336.555334 -222.322241)
		(end 336.368136 -222.272098)
		(width 0.0889)
		(layer "In15.Cu")
		(net "P5E_CPU0_PE0_TX_DN<2>")
	)
	(arc
		(start 334.862932 -222.272098)
		(mid 334.675734 -222.322241)
		(end 334.488536 -222.272098)
		(width 0.0889)
		(layer "In15.Cu")
		(net "P5E_CPU0_PE0_TX_DN<2>")
	)
	(arc
		(start 333.548736 -222.272098)
		(mid 333.412264 -222.215475)
		(end 333.26578 -222.196152)
		(width 0.0889)
		(layer "In15.Cu")
		(net "P5E_CPU0_PE0_TX_DN<2>")
	)
	(arc
		(start 339.469984 -222.761556)
		(mid 339.395993 -222.48199)
		(end 339.193378 -222.275654)
		(width 0.0889)
		(layer "In15.Cu")
		(net "P5E_CPU0_PE0_TX_DN<2>")
	)
	(segment
		(start 348.51721 -407.924254)
		(end 348.19082 -408.250644)
		(width 0.13208)
		(layer "F.Cu")
		(net "P5E_CPU0_PE0_TX_DN<1>")
	)
	(segment
		(start 348.19082 -408.250644)
		(end 348.186248 -408.250644)
		(width 0.13208)
		(layer "F.Cu")
		(net "P5E_CPU0_PE0_TX_DN<1>")
	)
	(segment
		(start 338.90458 -224.925382)
		(end 338.90458 -224.389696)
		(width 0.13208)
		(layer "F.Cu")
		(net "P5E_CPU0_PE0_TX_DN<1>")
	)
	(segment
		(start 348.51721 -407.310082)
		(end 348.51721 -407.924254)
		(width 0.13208)
		(layer "F.Cu")
		(net "P5E_CPU0_PE0_TX_DN<1>")
	)
	(segment
		(start 348.211648 -407.00452)
		(end 348.51721 -407.310082)
		(width 0.13208)
		(layer "F.Cu")
		(net "P5E_CPU0_PE0_TX_DN<1>")
	)
	(segment
		(start 338.90458 -224.389696)
		(end 338.904834 -224.389442)
		(width 0.13208)
		(layer "F.Cu")
		(net "P5E_CPU0_PE0_TX_DN<1>")
	)
	(segment
		(start 332.052676 -223.460056)
		(end 332.037182 -223.47555)
		(width 0.0889)
		(layer "In15.Cu")
		(net "P5E_CPU0_PE0_TX_DN<1>")
	)
	(segment
		(start 332.396084 -223.175576)
		(end 332.111604 -223.460056)
		(width 0.0889)
		(layer "In15.Cu")
		(net "P5E_CPU0_PE0_TX_DN<1>")
	)
	(segment
		(start 329.836018 -245.634764)
		(end 329.975972 -246.42953)
		(width 0.14732)
		(layer "In15.Cu")
		(net "P5E_CPU0_PE0_TX_DN<1>")
	)
	(segment
		(start 329.762104 -234.145836)
		(end 329.836018 -245.191534)
		(width 0.14732)
		(layer "In15.Cu")
		(net "P5E_CPU0_PE0_TX_DN<1>")
	)
	(segment
		(start 348.506288 -405.831548)
		(end 348.506288 -406.70988)
		(width 0.14732)
		(layer "In15.Cu")
		(net "P5E_CPU0_PE0_TX_DN<1>")
	)
	(segment
		(start 338.166964 -223.077278)
		(end 338.152232 -223.085914)
		(width 0.0889)
		(layer "In15.Cu")
		(net "P5E_CPU0_PE0_TX_DN<1>")
	)
	(segment
		(start 328.832972 -266.641072)
		(end 331.650848 -310.90362)
		(width 0.14732)
		(layer "In15.Cu")
		(net "P5E_CPU0_PE0_TX_DN<1>")
	)
	(segment
		(start 331.650848 -310.90362)
		(end 327.127108 -321.650868)
		(width 0.14732)
		(layer "In15.Cu")
		(net "P5E_CPU0_PE0_TX_DN<1>")
	)
	(segment
		(start 316.148466 -340.603078)
		(end 320.717164 -361.161838)
		(width 0.14732)
		(layer "In15.Cu")
		(net "P5E_CPU0_PE0_TX_DN<1>")
	)
	(segment
		(start 339.061298 -224.66046)
		(end 339.040216 -224.738438)
		(width 0.0889)
		(layer "In15.Cu")
		(net "P5E_CPU0_PE0_TX_DN<1>")
	)
	(segment
		(start 331.759814 -223.752664)
		(end 329.762104 -234.145836)
		(width 0.14732)
		(layer "In15.Cu")
		(net "P5E_CPU0_PE0_TX_DN<1>")
	)
	(segment
		(start 334.018636 -223.085914)
		(end 334.008222 -223.079818)
		(width 0.0889)
		(layer "In15.Cu")
		(net "P5E_CPU0_PE0_TX_DN<1>")
	)
	(segment
		(start 348.691708 -403.948138)
		(end 348.506288 -405.831548)
		(width 0.14732)
		(layer "In15.Cu")
		(net "P5E_CPU0_PE0_TX_DN<1>")
	)
	(segment
		(start 320.717164 -361.161838)
		(end 348.691708 -399.910808)
		(width 0.14732)
		(layer "In15.Cu")
		(net "P5E_CPU0_PE0_TX_DN<1>")
	)
	(segment
		(start 329.472544 -259.537708)
		(end 328.832972 -266.641072)
		(width 0.14732)
		(layer "In15.Cu")
		(net "P5E_CPU0_PE0_TX_DN<1>")
	)
	(segment
		(start 321.171062 -330.156312)
		(end 316.148466 -335.179162)
		(width 0.14732)
		(layer "In15.Cu")
		(net "P5E_CPU0_PE0_TX_DN<1>")
	)
	(segment
		(start 327.127108 -321.650868)
		(end 321.171062 -330.156312)
		(width 0.14732)
		(layer "In15.Cu")
		(net "P5E_CPU0_PE0_TX_DN<1>")
	)
	(segment
		(start 339.000084 -223.575626)
		(end 339.000084 -223.561402)
		(width 0.0889)
		(layer "In15.Cu")
		(net "P5E_CPU0_PE0_TX_DN<1>")
	)
	(segment
		(start 332.051152 -250.65736)
		(end 332.051152 -252.921008)
		(width 0.14732)
		(layer "In15.Cu")
		(net "P5E_CPU0_PE0_TX_DN<1>")
	)
	(segment
		(start 332.037182 -223.47555)
		(end 331.759814 -223.752664)
		(width 0.14732)
		(layer "In15.Cu")
		(net "P5E_CPU0_PE0_TX_DN<1>")
	)
	(segment
		(start 338.708746 -224.070164)
		(end 338.717636 -224.065084)
		(width 0.0889)
		(layer "In15.Cu")
		(net "P5E_CPU0_PE0_TX_DN<1>")
	)
	(segment
		(start 316.148466 -335.179162)
		(end 316.148466 -340.603078)
		(width 0.14732)
		(layer "In15.Cu")
		(net "P5E_CPU0_PE0_TX_DN<1>")
	)
	(segment
		(start 331.411326 -249.112786)
		(end 332.051152 -250.65736)
		(width 0.14732)
		(layer "In15.Cu")
		(net "P5E_CPU0_PE0_TX_DN<1>")
	)
	(segment
		(start 332.051152 -252.921008)
		(end 329.472544 -259.537708)
		(width 0.14732)
		(layer "In15.Cu")
		(net "P5E_CPU0_PE0_TX_DN<1>")
	)
	(segment
		(start 329.975972 -246.42953)
		(end 331.411326 -249.112786)
		(width 0.14732)
		(layer "In15.Cu")
		(net "P5E_CPU0_PE0_TX_DN<1>")
	)
	(segment
		(start 338.717636 -224.065084)
		(end 338.723732 -224.061528)
		(width 0.0889)
		(layer "In15.Cu")
		(net "P5E_CPU0_PE0_TX_DN<1>")
	)
	(segment
		(start 338.717636 -224.7138)
		(end 338.708746 -224.70872)
		(width 0.0889)
		(layer "In15.Cu")
		(net "P5E_CPU0_PE0_TX_DN<1>")
	)
	(segment
		(start 338.904834 -224.389442)
		(end 339.061298 -224.66046)
		(width 0.0889)
		(layer "In15.Cu")
		(net "P5E_CPU0_PE0_TX_DN<1>")
	)
	(segment
		(start 329.836018 -245.191534)
		(end 329.836018 -245.634764)
		(width 0.14732)
		(layer "In15.Cu")
		(net "P5E_CPU0_PE0_TX_DN<1>")
	)
	(segment
		(start 348.691708 -399.910808)
		(end 348.691708 -403.948138)
		(width 0.14732)
		(layer "In15.Cu")
		(net "P5E_CPU0_PE0_TX_DN<1>")
	)
	(segment
		(start 336.287364 -223.077278)
		(end 336.272632 -223.085914)
		(width 0.0889)
		(layer "In15.Cu")
		(net "P5E_CPU0_PE0_TX_DN<1>")
	)
	(segment
		(start 333.078582 -223.085914)
		(end 333.06385 -223.077278)
		(width 0.0889)
		(layer "In15.Cu")
		(net "P5E_CPU0_PE0_TX_DN<1>")
	)
	(segment
		(start 348.506288 -406.70988)
		(end 348.211648 -407.00452)
		(width 0.14732)
		(layer "In15.Cu")
		(net "P5E_CPU0_PE0_TX_DN<1>")
	)
	(segment
		(start 332.111604 -223.460056)
		(end 332.052676 -223.460056)
		(width 0.0889)
		(layer "In15.Cu")
		(net "P5E_CPU0_PE0_TX_DN<1>")
	)
	(arc
		(start 338.717636 -223.085914)
		(mid 338.443407 -223.009989)
		(end 338.166964 -223.077278)
		(width 0.0889)
		(layer "In15.Cu")
		(net "P5E_CPU0_PE0_TX_DN<1>")
	)
	(arc
		(start 337.212432 -223.085914)
		(mid 337.025234 -223.136057)
		(end 336.838036 -223.085914)
		(width 0.0889)
		(layer "In15.Cu")
		(net "P5E_CPU0_PE0_TX_DN<1>")
	)
	(arc
		(start 333.452978 -223.085914)
		(mid 333.26578 -223.136057)
		(end 333.078582 -223.085914)
		(width 0.0889)
		(layer "In15.Cu")
		(net "P5E_CPU0_PE0_TX_DN<1>")
	)
	(arc
		(start 338.723732 -224.061528)
		(mid 338.926145 -223.855115)
		(end 339.000084 -223.575626)
		(width 0.0889)
		(layer "In15.Cu")
		(net "P5E_CPU0_PE0_TX_DN<1>")
	)
	(arc
		(start 332.513178 -223.085914)
		(mid 332.451693 -223.126909)
		(end 332.396084 -223.175576)
		(width 0.0889)
		(layer "In15.Cu")
		(net "P5E_CPU0_PE0_TX_DN<1>")
	)
	(arc
		(start 338.708746 -224.70872)
		(mid 338.53027 -224.389442)
		(end 338.708746 -224.070164)
		(width 0.0889)
		(layer "In15.Cu")
		(net "P5E_CPU0_PE0_TX_DN<1>")
	)
	(arc
		(start 334.958436 -223.085914)
		(mid 334.675734 -223.010172)
		(end 334.393032 -223.085914)
		(width 0.0889)
		(layer "In15.Cu")
		(net "P5E_CPU0_PE0_TX_DN<1>")
	)
	(arc
		(start 339.040216 -224.738438)
		(mid 338.87612 -224.762785)
		(end 338.717636 -224.7138)
		(width 0.0889)
		(layer "In15.Cu")
		(net "P5E_CPU0_PE0_TX_DN<1>")
	)
	(arc
		(start 333.06385 -223.077278)
		(mid 332.787409 -223.010112)
		(end 332.513178 -223.085914)
		(width 0.0889)
		(layer "In15.Cu")
		(net "P5E_CPU0_PE0_TX_DN<1>")
	)
	(arc
		(start 338.152232 -223.085914)
		(mid 337.965034 -223.136057)
		(end 337.777836 -223.085914)
		(width 0.0889)
		(layer "In15.Cu")
		(net "P5E_CPU0_PE0_TX_DN<1>")
	)
	(arc
		(start 334.393032 -223.085914)
		(mid 334.205834 -223.136057)
		(end 334.018636 -223.085914)
		(width 0.0889)
		(layer "In15.Cu")
		(net "P5E_CPU0_PE0_TX_DN<1>")
	)
	(arc
		(start 334.008222 -223.079818)
		(mid 333.72979 -223.010004)
		(end 333.452978 -223.085914)
		(width 0.0889)
		(layer "In15.Cu")
		(net "P5E_CPU0_PE0_TX_DN<1>")
	)
	(arc
		(start 336.272632 -223.085914)
		(mid 336.085434 -223.136057)
		(end 335.898236 -223.085914)
		(width 0.0889)
		(layer "In15.Cu")
		(net "P5E_CPU0_PE0_TX_DN<1>")
	)
	(arc
		(start 335.898236 -223.085914)
		(mid 335.615534 -223.010172)
		(end 335.332832 -223.085914)
		(width 0.0889)
		(layer "In15.Cu")
		(net "P5E_CPU0_PE0_TX_DN<1>")
	)
	(arc
		(start 335.332832 -223.085914)
		(mid 335.145634 -223.136057)
		(end 334.958436 -223.085914)
		(width 0.0889)
		(layer "In15.Cu")
		(net "P5E_CPU0_PE0_TX_DN<1>")
	)
	(arc
		(start 337.777836 -223.085914)
		(mid 337.495134 -223.010172)
		(end 337.212432 -223.085914)
		(width 0.0889)
		(layer "In15.Cu")
		(net "P5E_CPU0_PE0_TX_DN<1>")
	)
	(arc
		(start 336.838036 -223.085914)
		(mid 336.563807 -223.009989)
		(end 336.287364 -223.077278)
		(width 0.0889)
		(layer "In15.Cu")
		(net "P5E_CPU0_PE0_TX_DN<1>")
	)
	(arc
		(start 339.000084 -223.561402)
		(mid 338.920943 -223.286779)
		(end 338.717636 -223.085914)
		(width 0.0889)
		(layer "In15.Cu")
		(net "P5E_CPU0_PE0_TX_DN<1>")
	)
	(segment
		(start 305.326288 -407.00452)
		(end 305.63185 -407.310082)
		(width 0.13208)
		(layer "F.Cu")
		(net "P5E_CPU0_PE0_TX_DN<15>")
	)
	(segment
		(start 305.63185 -407.924254)
		(end 305.30546 -408.250644)
		(width 0.13208)
		(layer "F.Cu")
		(net "P5E_CPU0_PE0_TX_DN<15>")
	)
	(segment
		(start 352.06178 -224.925382)
		(end 352.06178 -224.389696)
		(width 0.13208)
		(layer "F.Cu")
		(net "P5E_CPU0_PE0_TX_DN<15>")
	)
	(segment
		(start 305.63185 -407.310082)
		(end 305.63185 -407.924254)
		(width 0.13208)
		(layer "F.Cu")
		(net "P5E_CPU0_PE0_TX_DN<15>")
	)
	(segment
		(start 305.30546 -408.250644)
		(end 305.300888 -408.250644)
		(width 0.13208)
		(layer "F.Cu")
		(net "P5E_CPU0_PE0_TX_DN<15>")
	)
	(segment
		(start 352.06178 -224.389696)
		(end 352.062034 -224.389442)
		(width 0.13208)
		(layer "F.Cu")
		(net "P5E_CPU0_PE0_TX_DN<15>")
	)
	(segment
		(start 350.926146 -217.559128)
		(end 350.935036 -217.554048)
		(width 0.0889)
		(layer "In15.Cu")
		(net "P5E_CPU0_PE0_TX_DN<15>")
	)
	(segment
		(start 351.875344 -224.06483)
		(end 351.877122 -224.063814)
		(width 0.0889)
		(layer "In15.Cu")
		(net "P5E_CPU0_PE0_TX_DN<15>")
	)
	(segment
		(start 351.410778 -222.275654)
		(end 351.407476 -222.273622)
		(width 0.0889)
		(layer "In15.Cu")
		(net "P5E_CPU0_PE0_TX_DN<15>")
	)
	(segment
		(start 350.31934 -213.12251)
		(end 350.31934 -211.280756)
		(width 0.14732)
		(layer "In15.Cu")
		(net "P5E_CPU0_PE0_TX_DN<15>")
	)
	(segment
		(start 311.508902 -316.99708)
		(end 309.455566 -319.050416)
		(width 0.14732)
		(layer "In15.Cu")
		(net "P5E_CPU0_PE0_TX_DN<15>")
	)
	(segment
		(start 317.795402 -305.552602)
		(end 315.238384 -314.666122)
		(width 0.14732)
		(layer "In15.Cu")
		(net "P5E_CPU0_PE0_TX_DN<15>")
	)
	(segment
		(start 314.460636 -253.473458)
		(end 317.795402 -305.552602)
		(width 0.14732)
		(layer "In15.Cu")
		(net "P5E_CPU0_PE0_TX_DN<15>")
	)
	(segment
		(start 351.874836 -224.7138)
		(end 351.865946 -224.70872)
		(width 0.0889)
		(layer "In15.Cu")
		(net "P5E_CPU0_PE0_TX_DN<15>")
	)
	(segment
		(start 301.289212 -329.128882)
		(end 302.727106 -342.04021)
		(width 0.14732)
		(layer "In15.Cu")
		(net "P5E_CPU0_PE0_TX_DN<15>")
	)
	(segment
		(start 337.686904 -200.262236)
		(end 336.873596 -200.25995)
		(width 0.14732)
		(layer "In15.Cu")
		(net "P5E_CPU0_PE0_TX_DN<15>")
	)
	(segment
		(start 351.687638 -222.751396)
		(end 351.687384 -222.761556)
		(width 0.0889)
		(layer "In15.Cu")
		(net "P5E_CPU0_PE0_TX_DN<15>")
	)
	(segment
		(start 350.935036 -218.202764)
		(end 350.926146 -218.197684)
		(width 0.0889)
		(layer "In15.Cu")
		(net "P5E_CPU0_PE0_TX_DN<15>")
	)
	(segment
		(start 336.873596 -200.25995)
		(end 335.32064 -200.25995)
		(width 0.14732)
		(layer "In15.Cu")
		(net "P5E_CPU0_PE0_TX_DN<15>")
	)
	(segment
		(start 338.55406 -200.264522)
		(end 337.686904 -200.261982)
		(width 0.14732)
		(layer "In15.Cu")
		(net "P5E_CPU0_PE0_TX_DN<15>")
	)
	(segment
		(start 315.96965 -232.222548)
		(end 314.567316 -249.904758)
		(width 0.14732)
		(layer "In15.Cu")
		(net "P5E_CPU0_PE0_TX_DN<15>")
	)
	(segment
		(start 305.806348 -403.948138)
		(end 305.620928 -405.831548)
		(width 0.14732)
		(layer "In15.Cu")
		(net "P5E_CPU0_PE0_TX_DN<15>")
	)
	(segment
		(start 350.314514 -213.928452)
		(end 350.282002 -213.84514)
		(width 0.0889)
		(layer "In15.Cu")
		(net "P5E_CPU0_PE0_TX_DN<15>")
	)
	(segment
		(start 317.83782 -220.133164)
		(end 315.96965 -232.222548)
		(width 0.14732)
		(layer "In15.Cu")
		(net "P5E_CPU0_PE0_TX_DN<15>")
	)
	(segment
		(start 305.620928 -406.70988)
		(end 305.326288 -407.00452)
		(width 0.14732)
		(layer "In15.Cu")
		(net "P5E_CPU0_PE0_TX_DN<15>")
	)
	(segment
		(start 350.464882 -215.761062)
		(end 350.463358 -215.7603)
		(width 0.0889)
		(layer "In15.Cu")
		(net "P5E_CPU0_PE0_TX_DN<15>")
	)
	(segment
		(start 350.31934 -213.144608)
		(end 350.31934 -213.12251)
		(width 0.0889)
		(layer "In15.Cu")
		(net "P5E_CPU0_PE0_TX_DN<15>")
	)
	(segment
		(start 337.686904 -200.261982)
		(end 337.686904 -200.262236)
		(width 0.14732)
		(layer "In15.Cu")
		(net "P5E_CPU0_PE0_TX_DN<15>")
	)
	(segment
		(start 351.403158 -222.271336)
		(end 351.395792 -222.267018)
		(width 0.0889)
		(layer "In15.Cu")
		(net "P5E_CPU0_PE0_TX_DN<15>")
	)
	(segment
		(start 350.935036 -216.574878)
		(end 350.926146 -216.569798)
		(width 0.0889)
		(layer "In15.Cu")
		(net "P5E_CPU0_PE0_TX_DN<15>")
	)
	(segment
		(start 351.865946 -224.070164)
		(end 351.875344 -224.06483)
		(width 0.0889)
		(layer "In15.Cu")
		(net "P5E_CPU0_PE0_TX_DN<15>")
	)
	(segment
		(start 314.555378 -315.34989)
		(end 313.739022 -315.34989)
		(width 0.14732)
		(layer "In15.Cu")
		(net "P5E_CPU0_PE0_TX_DN<15>")
	)
	(segment
		(start 306.800758 -320.150236)
		(end 301.289212 -325.661782)
		(width 0.14732)
		(layer "In15.Cu")
		(net "P5E_CPU0_PE0_TX_DN<15>")
	)
	(segment
		(start 350.926146 -219.18676)
		(end 350.935036 -219.18168)
		(width 0.0889)
		(layer "In15.Cu")
		(net "P5E_CPU0_PE0_TX_DN<15>")
	)
	(segment
		(start 350.27743 -213.820756)
		(end 350.27743 -213.186518)
		(width 0.0889)
		(layer "In15.Cu")
		(net "P5E_CPU0_PE0_TX_DN<15>")
	)
	(segment
		(start 302.727106 -342.04021)
		(end 307.561488 -363.799882)
		(width 0.14732)
		(layer "In15.Cu")
		(net "P5E_CPU0_PE0_TX_DN<15>")
	)
	(segment
		(start 350.27743 -213.186518)
		(end 350.31934 -213.144608)
		(width 0.0889)
		(layer "In15.Cu")
		(net "P5E_CPU0_PE0_TX_DN<15>")
	)
	(segment
		(start 351.404682 -222.272098)
		(end 351.403158 -222.271336)
		(width 0.0889)
		(layer "In15.Cu")
		(net "P5E_CPU0_PE0_TX_DN<15>")
	)
	(segment
		(start 307.586126 -363.953552)
		(end 305.806348 -399.90395)
		(width 0.14732)
		(layer "In15.Cu")
		(net "P5E_CPU0_PE0_TX_DN<15>")
	)
	(segment
		(start 352.157284 -223.575626)
		(end 352.157284 -223.561402)
		(width 0.0889)
		(layer "In15.Cu")
		(net "P5E_CPU0_PE0_TX_DN<15>")
	)
	(segment
		(start 305.620928 -405.831548)
		(end 305.620928 -406.70988)
		(width 0.14732)
		(layer "In15.Cu")
		(net "P5E_CPU0_PE0_TX_DN<15>")
	)
	(segment
		(start 313.739022 -315.34989)
		(end 312.091832 -316.99708)
		(width 0.14732)
		(layer "In15.Cu")
		(net "P5E_CPU0_PE0_TX_DN<15>")
	)
	(segment
		(start 307.561488 -363.799882)
		(end 307.586126 -363.953552)
		(width 0.14732)
		(layer "In15.Cu")
		(net "P5E_CPU0_PE0_TX_DN<15>")
	)
	(segment
		(start 351.21723 -221.94774)
		(end 351.21723 -221.932246)
		(width 0.0889)
		(layer "In15.Cu")
		(net "P5E_CPU0_PE0_TX_DN<15>")
	)
	(segment
		(start 350.926146 -220.814646)
		(end 350.935036 -220.809566)
		(width 0.0889)
		(layer "In15.Cu")
		(net "P5E_CPU0_PE0_TX_DN<15>")
	)
	(segment
		(start 350.935036 -221.458282)
		(end 350.926146 -221.453202)
		(width 0.0889)
		(layer "In15.Cu")
		(net "P5E_CPU0_PE0_TX_DN<15>")
	)
	(segment
		(start 309.455566 -319.050416)
		(end 306.800758 -320.150236)
		(width 0.14732)
		(layer "In15.Cu")
		(net "P5E_CPU0_PE0_TX_DN<15>")
	)
	(segment
		(start 351.407476 -222.273622)
		(end 351.404682 -222.272098)
		(width 0.0889)
		(layer "In15.Cu")
		(net "P5E_CPU0_PE0_TX_DN<15>")
	)
	(segment
		(start 350.467676 -215.762586)
		(end 350.464882 -215.761062)
		(width 0.0889)
		(layer "In15.Cu")
		(net "P5E_CPU0_PE0_TX_DN<15>")
	)
	(segment
		(start 312.091832 -316.99708)
		(end 311.508902 -316.99708)
		(width 0.14732)
		(layer "In15.Cu")
		(net "P5E_CPU0_PE0_TX_DN<15>")
	)
	(segment
		(start 320.74231 -214.535512)
		(end 317.83782 -220.133164)
		(width 0.14732)
		(layer "In15.Cu")
		(net "P5E_CPU0_PE0_TX_DN<15>")
	)
	(segment
		(start 342.553036 -201.920856)
		(end 338.55406 -200.264522)
		(width 0.14732)
		(layer "In15.Cu")
		(net "P5E_CPU0_PE0_TX_DN<15>")
	)
	(segment
		(start 305.806348 -399.90395)
		(end 305.806348 -403.948138)
		(width 0.14732)
		(layer "In15.Cu")
		(net "P5E_CPU0_PE0_TX_DN<15>")
	)
	(segment
		(start 349.192596 -208.560416)
		(end 342.553036 -201.920856)
		(width 0.14732)
		(layer "In15.Cu")
		(net "P5E_CPU0_PE0_TX_DN<15>")
	)
	(segment
		(start 350.470978 -215.764618)
		(end 350.467676 -215.762586)
		(width 0.0889)
		(layer "In15.Cu")
		(net "P5E_CPU0_PE0_TX_DN<15>")
	)
	(segment
		(start 350.747076 -214.644732)
		(end 350.747076 -214.470996)
		(width 0.0889)
		(layer "In15.Cu")
		(net "P5E_CPU0_PE0_TX_DN<15>")
	)
	(segment
		(start 350.935036 -219.830396)
		(end 350.926146 -219.825316)
		(width 0.0889)
		(layer "In15.Cu")
		(net "P5E_CPU0_PE0_TX_DN<15>")
	)
	(segment
		(start 352.062034 -224.389442)
		(end 352.218498 -224.66046)
		(width 0.0889)
		(layer "In15.Cu")
		(net "P5E_CPU0_PE0_TX_DN<15>")
	)
	(segment
		(start 350.31934 -211.280756)
		(end 349.192596 -208.560416)
		(width 0.14732)
		(layer "In15.Cu")
		(net "P5E_CPU0_PE0_TX_DN<15>")
	)
	(segment
		(start 351.877122 -224.063814)
		(end 351.880932 -224.061528)
		(width 0.0889)
		(layer "In15.Cu")
		(net "P5E_CPU0_PE0_TX_DN<15>")
	)
	(segment
		(start 351.874836 -223.085914)
		(end 351.865946 -223.080834)
		(width 0.0889)
		(layer "In15.Cu")
		(net "P5E_CPU0_PE0_TX_DN<15>")
	)
	(segment
		(start 334.275176 -200.922128)
		(end 333.484474 -201.570082)
		(width 0.14732)
		(layer "In15.Cu")
		(net "P5E_CPU0_PE0_TX_DN<15>")
	)
	(segment
		(start 315.238384 -314.666122)
		(end 314.555378 -315.34989)
		(width 0.14732)
		(layer "In15.Cu")
		(net "P5E_CPU0_PE0_TX_DN<15>")
	)
	(segment
		(start 333.484474 -201.570082)
		(end 330.175108 -204.641196)
		(width 0.14732)
		(layer "In15.Cu")
		(net "P5E_CPU0_PE0_TX_DN<15>")
	)
	(segment
		(start 335.32064 -200.25995)
		(end 334.275176 -200.922128)
		(width 0.14732)
		(layer "In15.Cu")
		(net "P5E_CPU0_PE0_TX_DN<15>")
	)
	(segment
		(start 351.21723 -218.707716)
		(end 351.21723 -218.676728)
		(width 0.0889)
		(layer "In15.Cu")
		(net "P5E_CPU0_PE0_TX_DN<15>")
	)
	(segment
		(start 350.463358 -215.7603)
		(end 350.455992 -215.755982)
		(width 0.0889)
		(layer "In15.Cu")
		(net "P5E_CPU0_PE0_TX_DN<15>")
	)
	(segment
		(start 350.747076 -214.470996)
		(end 350.746822 -214.470996)
		(width 0.0889)
		(layer "In15.Cu")
		(net "P5E_CPU0_PE0_TX_DN<15>")
	)
	(segment
		(start 301.289212 -325.661782)
		(end 301.289212 -329.128882)
		(width 0.14732)
		(layer "In15.Cu")
		(net "P5E_CPU0_PE0_TX_DN<15>")
	)
	(segment
		(start 350.455992 -215.117426)
		(end 350.464882 -215.112346)
		(width 0.0889)
		(layer "In15.Cu")
		(net "P5E_CPU0_PE0_TX_DN<15>")
	)
	(segment
		(start 330.175108 -204.641196)
		(end 320.74231 -214.535512)
		(width 0.14732)
		(layer "In15.Cu")
		(net "P5E_CPU0_PE0_TX_DN<15>")
	)
	(segment
		(start 314.567316 -249.904758)
		(end 314.460636 -253.473458)
		(width 0.14732)
		(layer "In15.Cu")
		(net "P5E_CPU0_PE0_TX_DN<15>")
	)
	(segment
		(start 352.218498 -224.66046)
		(end 352.197416 -224.738438)
		(width 0.0889)
		(layer "In15.Cu")
		(net "P5E_CPU0_PE0_TX_DN<15>")
	)
	(arc
		(start 350.747838 -221.121732)
		(mid 350.798309 -220.945724)
		(end 350.926146 -220.814646)
		(width 0.0889)
		(layer "In15.Cu")
		(net "P5E_CPU0_PE0_TX_DN<15>")
	)
	(arc
		(start 352.197416 -224.738438)
		(mid 352.03332 -224.762785)
		(end 351.874836 -224.7138)
		(width 0.0889)
		(layer "In15.Cu")
		(net "P5E_CPU0_PE0_TX_DN<15>")
	)
	(arc
		(start 350.935036 -217.554048)
		(mid 351.217568 -217.064527)
		(end 350.935036 -216.574878)
		(width 0.0889)
		(layer "In15.Cu")
		(net "P5E_CPU0_PE0_TX_DN<15>")
	)
	(arc
		(start 350.926146 -218.197684)
		(mid 350.797827 -218.065712)
		(end 350.747838 -217.888566)
		(width 0.0889)
		(layer "In15.Cu")
		(net "P5E_CPU0_PE0_TX_DN<15>")
	)
	(arc
		(start 350.926146 -219.825316)
		(mid 350.747549 -219.506038)
		(end 350.926146 -219.18676)
		(width 0.0889)
		(layer "In15.Cu")
		(net "P5E_CPU0_PE0_TX_DN<15>")
	)
	(arc
		(start 351.21723 -221.932246)
		(mid 351.13786 -221.658512)
		(end 350.935036 -221.458282)
		(width 0.0889)
		(layer "In15.Cu")
		(net "P5E_CPU0_PE0_TX_DN<15>")
	)
	(arc
		(start 351.21723 -218.676728)
		(mid 351.13786 -218.402994)
		(end 350.935036 -218.202764)
		(width 0.0889)
		(layer "In15.Cu")
		(net "P5E_CPU0_PE0_TX_DN<15>")
	)
	(arc
		(start 351.865946 -223.080834)
		(mid 351.738866 -222.95082)
		(end 351.687892 -222.776288)
		(width 0.0889)
		(layer "In15.Cu")
		(net "P5E_CPU0_PE0_TX_DN<15>")
	)
	(arc
		(start 350.461834 -214.093298)
		(mid 350.373395 -214.024092)
		(end 350.314514 -213.928452)
		(width 0.0889)
		(layer "In15.Cu")
		(net "P5E_CPU0_PE0_TX_DN<15>")
	)
	(arc
		(start 352.157284 -223.561402)
		(mid 352.078143 -223.286779)
		(end 351.874836 -223.085914)
		(width 0.0889)
		(layer "In15.Cu")
		(net "P5E_CPU0_PE0_TX_DN<15>")
	)
	(arc
		(start 350.722438 -214.365586)
		(mid 350.614111 -214.208414)
		(end 350.461834 -214.093298)
		(width 0.0889)
		(layer "In15.Cu")
		(net "P5E_CPU0_PE0_TX_DN<15>")
	)
	(arc
		(start 350.926146 -216.569798)
		(mid 350.795232 -216.433438)
		(end 350.747584 -216.25052)
		(width 0.0889)
		(layer "In15.Cu")
		(net "P5E_CPU0_PE0_TX_DN<15>")
	)
	(arc
		(start 350.926146 -221.453202)
		(mid 350.797827 -221.32123)
		(end 350.747838 -221.144084)
		(width 0.0889)
		(layer "In15.Cu")
		(net "P5E_CPU0_PE0_TX_DN<15>")
	)
	(arc
		(start 350.746822 -214.470996)
		(mid 350.740488 -214.416934)
		(end 350.722438 -214.365586)
		(width 0.0889)
		(layer "In15.Cu")
		(net "P5E_CPU0_PE0_TX_DN<15>")
	)
	(arc
		(start 351.687892 -222.776288)
		(mid 351.687559 -222.763844)
		(end 351.687638 -222.751396)
		(width 0.0889)
		(layer "In15.Cu")
		(net "P5E_CPU0_PE0_TX_DN<15>")
	)
	(arc
		(start 350.747838 -221.144084)
		(mid 350.747671 -221.132908)
		(end 350.747838 -221.121732)
		(width 0.0889)
		(layer "In15.Cu")
		(net "P5E_CPU0_PE0_TX_DN<15>")
	)
	(arc
		(start 350.282002 -213.84514)
		(mid 350.27859 -213.833161)
		(end 350.27743 -213.820756)
		(width 0.0889)
		(layer "In15.Cu")
		(net "P5E_CPU0_PE0_TX_DN<15>")
	)
	(arc
		(start 350.747838 -217.888566)
		(mid 350.747671 -217.87739)
		(end 350.747838 -217.866214)
		(width 0.0889)
		(layer "In15.Cu")
		(net "P5E_CPU0_PE0_TX_DN<15>")
	)
	(arc
		(start 350.747584 -216.25052)
		(mid 350.673593 -215.970954)
		(end 350.470978 -215.764618)
		(width 0.0889)
		(layer "In15.Cu")
		(net "P5E_CPU0_PE0_TX_DN<15>")
	)
	(arc
		(start 351.687384 -222.761556)
		(mid 351.613393 -222.48199)
		(end 351.410778 -222.275654)
		(width 0.0889)
		(layer "In15.Cu")
		(net "P5E_CPU0_PE0_TX_DN<15>")
	)
	(arc
		(start 351.880932 -224.061528)
		(mid 352.083345 -223.855115)
		(end 352.157284 -223.575626)
		(width 0.0889)
		(layer "In15.Cu")
		(net "P5E_CPU0_PE0_TX_DN<15>")
	)
	(arc
		(start 351.395792 -222.267018)
		(mid 351.264878 -222.130658)
		(end 351.21723 -221.94774)
		(width 0.0889)
		(layer "In15.Cu")
		(net "P5E_CPU0_PE0_TX_DN<15>")
	)
	(arc
		(start 350.747838 -217.866214)
		(mid 350.798309 -217.690206)
		(end 350.926146 -217.559128)
		(width 0.0889)
		(layer "In15.Cu")
		(net "P5E_CPU0_PE0_TX_DN<15>")
	)
	(arc
		(start 350.455992 -215.755982)
		(mid 350.277395 -215.436704)
		(end 350.455992 -215.117426)
		(width 0.0889)
		(layer "In15.Cu")
		(net "P5E_CPU0_PE0_TX_DN<15>")
	)
	(arc
		(start 350.935036 -219.18168)
		(mid 351.137859 -218.981449)
		(end 351.21723 -218.707716)
		(width 0.0889)
		(layer "In15.Cu")
		(net "P5E_CPU0_PE0_TX_DN<15>")
	)
	(arc
		(start 350.464882 -215.112346)
		(mid 350.666164 -214.914859)
		(end 350.747076 -214.644732)
		(width 0.0889)
		(layer "In15.Cu")
		(net "P5E_CPU0_PE0_TX_DN<15>")
	)
	(arc
		(start 350.935036 -220.809566)
		(mid 351.217568 -220.320045)
		(end 350.935036 -219.830396)
		(width 0.0889)
		(layer "In15.Cu")
		(net "P5E_CPU0_PE0_TX_DN<15>")
	)
	(arc
		(start 351.865946 -224.70872)
		(mid 351.68747 -224.389442)
		(end 351.865946 -224.070164)
		(width 0.0889)
		(layer "In15.Cu")
		(net "P5E_CPU0_PE0_TX_DN<15>")
	)
	(segment
		(start 351.592134 -224.111566)
		(end 351.592134 -223.57588)
		(width 0.13208)
		(layer "F.Cu")
		(net "P5E_CPU0_PE0_TX_DN<14>")
	)
	(segment
		(start 351.592134 -223.57588)
		(end 351.59188 -223.575626)
		(width 0.13208)
		(layer "F.Cu")
		(net "P5E_CPU0_PE0_TX_DN<14>")
	)
	(segment
		(start 308.3687 -408.250644)
		(end 308.364128 -408.250644)
		(width 0.13208)
		(layer "F.Cu")
		(net "P5E_CPU0_PE0_TX_DN<14>")
	)
	(segment
		(start 308.389528 -407.00452)
		(end 308.69509 -407.310082)
		(width 0.13208)
		(layer "F.Cu")
		(net "P5E_CPU0_PE0_TX_DN<14>")
	)
	(segment
		(start 308.69509 -407.924254)
		(end 308.3687 -408.250644)
		(width 0.13208)
		(layer "F.Cu")
		(net "P5E_CPU0_PE0_TX_DN<14>")
	)
	(segment
		(start 308.69509 -407.310082)
		(end 308.69509 -407.924254)
		(width 0.13208)
		(layer "F.Cu")
		(net "P5E_CPU0_PE0_TX_DN<14>")
	)
	(segment
		(start 351.59188 -223.575626)
		(end 351.435416 -223.846644)
		(width 0.0889)
		(layer "In15.Cu")
		(net "P5E_CPU0_PE0_TX_DN<14>")
	)
	(segment
		(start 349.995236 -221.458282)
		(end 349.986346 -221.453202)
		(width 0.0889)
		(layer "In15.Cu")
		(net "P5E_CPU0_PE0_TX_DN<14>")
	)
	(segment
		(start 308.723538 -364.641892)
		(end 308.869588 -399.910808)
		(width 0.14732)
		(layer "In15.Cu")
		(net "P5E_CPU0_PE0_TX_DN<14>")
	)
	(segment
		(start 349.37954 -213.12251)
		(end 349.37954 -211.537296)
		(width 0.14732)
		(layer "In15.Cu")
		(net "P5E_CPU0_PE0_TX_DN<14>")
	)
	(segment
		(start 315.944504 -315.619384)
		(end 313.16549 -319.588134)
		(width 0.14732)
		(layer "In15.Cu")
		(net "P5E_CPU0_PE0_TX_DN<14>")
	)
	(segment
		(start 335.532222 -201.260964)
		(end 334.66278 -201.811636)
		(width 0.14732)
		(layer "In15.Cu")
		(net "P5E_CPU0_PE0_TX_DN<14>")
	)
	(segment
		(start 317.309754 -312.188606)
		(end 317.310008 -312.189114)
		(width 0.14732)
		(layer "In15.Cu")
		(net "P5E_CPU0_PE0_TX_DN<14>")
	)
	(segment
		(start 303.683162 -341.963248)
		(end 308.723538 -364.641892)
		(width 0.14732)
		(layer "In15.Cu")
		(net "P5E_CPU0_PE0_TX_DN<14>")
	)
	(segment
		(start 303.683162 -329.2221)
		(end 303.683162 -341.963248)
		(width 0.14732)
		(layer "In15.Cu")
		(net "P5E_CPU0_PE0_TX_DN<14>")
	)
	(segment
		(start 318.931544 -308.088792)
		(end 317.33363 -312.1279)
		(width 0.14732)
		(layer "In15.Cu")
		(net "P5E_CPU0_PE0_TX_DN<14>")
	)
	(segment
		(start 349.516192 -215.117426)
		(end 349.524066 -215.112854)
		(width 0.0889)
		(layer "In15.Cu")
		(net "P5E_CPU0_PE0_TX_DN<14>")
	)
	(segment
		(start 350.001332 -219.833952)
		(end 349.995236 -219.830396)
		(width 0.0889)
		(layer "In15.Cu")
		(net "P5E_CPU0_PE0_TX_DN<14>")
	)
	(segment
		(start 349.37954 -211.537296)
		(end 348.336362 -209.01914)
		(width 0.14732)
		(layer "In15.Cu")
		(net "P5E_CPU0_PE0_TX_DN<14>")
	)
	(segment
		(start 350.467676 -222.273622)
		(end 350.464882 -222.272098)
		(width 0.0889)
		(layer "In15.Cu")
		(net "P5E_CPU0_PE0_TX_DN<14>")
	)
	(segment
		(start 349.807022 -214.622634)
		(end 349.807022 -214.504778)
		(width 0.0889)
		(layer "In15.Cu")
		(net "P5E_CPU0_PE0_TX_DN<14>")
	)
	(segment
		(start 350.001332 -216.578434)
		(end 349.995236 -216.574878)
		(width 0.0889)
		(layer "In15.Cu")
		(net "P5E_CPU0_PE0_TX_DN<14>")
	)
	(segment
		(start 349.33763 -213.788244)
		(end 349.33763 -213.186518)
		(width 0.0889)
		(layer "In15.Cu")
		(net "P5E_CPU0_PE0_TX_DN<14>")
	)
	(segment
		(start 305.140106 -327.765156)
		(end 303.683162 -329.2221)
		(width 0.14732)
		(layer "In15.Cu")
		(net "P5E_CPU0_PE0_TX_DN<14>")
	)
	(segment
		(start 310.41848 -320.45529)
		(end 309.236364 -320.945002)
		(width 0.14732)
		(layer "In15.Cu")
		(net "P5E_CPU0_PE0_TX_DN<14>")
	)
	(segment
		(start 350.935036 -223.085914)
		(end 350.926146 -223.080834)
		(width 0.0889)
		(layer "In15.Cu")
		(net "P5E_CPU0_PE0_TX_DN<14>")
	)
	(segment
		(start 315.477398 -254.377698)
		(end 318.931544 -308.088792)
		(width 0.14732)
		(layer "In15.Cu")
		(net "P5E_CPU0_PE0_TX_DN<14>")
	)
	(segment
		(start 349.33763 -213.186518)
		(end 349.37954 -213.144608)
		(width 0.0889)
		(layer "In15.Cu")
		(net "P5E_CPU0_PE0_TX_DN<14>")
	)
	(segment
		(start 349.995236 -218.202764)
		(end 349.986346 -218.197684)
		(width 0.0889)
		(layer "In15.Cu")
		(net "P5E_CPU0_PE0_TX_DN<14>")
	)
	(segment
		(start 349.986346 -220.814646)
		(end 349.995236 -220.809566)
		(width 0.0889)
		(layer "In15.Cu")
		(net "P5E_CPU0_PE0_TX_DN<14>")
	)
	(segment
		(start 336.872834 -201.218546)
		(end 335.57464 -201.218546)
		(width 0.14732)
		(layer "In15.Cu")
		(net "P5E_CPU0_PE0_TX_DN<14>")
	)
	(segment
		(start 330.961492 -205.197456)
		(end 321.527932 -215.152478)
		(width 0.14732)
		(layer "In15.Cu")
		(net "P5E_CPU0_PE0_TX_DN<14>")
	)
	(segment
		(start 349.986346 -217.559128)
		(end 349.995236 -217.554048)
		(width 0.0889)
		(layer "In15.Cu")
		(net "P5E_CPU0_PE0_TX_DN<14>")
	)
	(segment
		(start 349.99422 -219.182188)
		(end 349.995236 -219.18168)
		(width 0.0889)
		(layer "In15.Cu")
		(net "P5E_CPU0_PE0_TX_DN<14>")
	)
	(segment
		(start 318.739266 -220.527372)
		(end 316.923166 -232.278936)
		(width 0.14732)
		(layer "In15.Cu")
		(net "P5E_CPU0_PE0_TX_DN<14>")
	)
	(segment
		(start 308.869588 -403.948138)
		(end 308.684168 -405.831548)
		(width 0.14732)
		(layer "In15.Cu")
		(net "P5E_CPU0_PE0_TX_DN<14>")
	)
	(segment
		(start 349.37954 -213.144608)
		(end 349.37954 -213.12251)
		(width 0.0889)
		(layer "In15.Cu")
		(net "P5E_CPU0_PE0_TX_DN<14>")
	)
	(segment
		(start 317.332106 -312.132472)
		(end 317.31077 -312.185812)
		(width 0.14732)
		(layer "In15.Cu")
		(net "P5E_CPU0_PE0_TX_DN<14>")
	)
	(segment
		(start 348.336362 -209.01914)
		(end 342.082628 -202.765406)
		(width 0.14732)
		(layer "In15.Cu")
		(net "P5E_CPU0_PE0_TX_DN<14>")
	)
	(segment
		(start 338.354924 -201.22134)
		(end 336.872834 -201.218546)
		(width 0.14732)
		(layer "In15.Cu")
		(net "P5E_CPU0_PE0_TX_DN<14>")
	)
	(segment
		(start 349.531178 -215.764618)
		(end 349.516192 -215.755982)
		(width 0.0889)
		(layer "In15.Cu")
		(net "P5E_CPU0_PE0_TX_DN<14>")
	)
	(segment
		(start 350.27743 -221.94774)
		(end 350.27743 -221.932246)
		(width 0.0889)
		(layer "In15.Cu")
		(net "P5E_CPU0_PE0_TX_DN<14>")
	)
	(segment
		(start 342.082628 -202.765406)
		(end 338.354924 -201.22134)
		(width 0.14732)
		(layer "In15.Cu")
		(net "P5E_CPU0_PE0_TX_DN<14>")
	)
	(segment
		(start 349.986346 -219.18676)
		(end 349.99422 -219.182188)
		(width 0.0889)
		(layer "In15.Cu")
		(net "P5E_CPU0_PE0_TX_DN<14>")
	)
	(segment
		(start 350.747838 -222.751396)
		(end 350.747584 -222.761556)
		(width 0.0889)
		(layer "In15.Cu")
		(net "P5E_CPU0_PE0_TX_DN<14>")
	)
	(segment
		(start 316.923166 -232.278936)
		(end 315.616844 -249.954542)
		(width 0.14732)
		(layer "In15.Cu")
		(net "P5E_CPU0_PE0_TX_DN<14>")
	)
	(segment
		(start 350.27743 -218.707716)
		(end 350.27743 -218.676728)
		(width 0.0889)
		(layer "In15.Cu")
		(net "P5E_CPU0_PE0_TX_DN<14>")
	)
	(segment
		(start 351.217484 -223.584262)
		(end 351.217484 -223.557084)
		(width 0.0889)
		(layer "In15.Cu")
		(net "P5E_CPU0_PE0_TX_DN<14>")
	)
	(segment
		(start 349.525082 -215.112346)
		(end 349.538036 -215.103964)
		(width 0.0889)
		(layer "In15.Cu")
		(net "P5E_CPU0_PE0_TX_DN<14>")
	)
	(segment
		(start 335.57464 -201.218546)
		(end 335.532222 -201.260964)
		(width 0.14732)
		(layer "In15.Cu")
		(net "P5E_CPU0_PE0_TX_DN<14>")
	)
	(segment
		(start 308.684168 -405.831548)
		(end 308.684168 -406.70988)
		(width 0.14732)
		(layer "In15.Cu")
		(net "P5E_CPU0_PE0_TX_DN<14>")
	)
	(segment
		(start 317.31077 -312.185812)
		(end 317.310262 -312.187336)
		(width 0.14732)
		(layer "In15.Cu")
		(net "P5E_CPU0_PE0_TX_DN<14>")
	)
	(segment
		(start 351.435416 -223.846644)
		(end 351.357438 -223.867472)
		(width 0.0889)
		(layer "In15.Cu")
		(net "P5E_CPU0_PE0_TX_DN<14>")
	)
	(segment
		(start 350.470978 -222.275654)
		(end 350.467676 -222.273622)
		(width 0.0889)
		(layer "In15.Cu")
		(net "P5E_CPU0_PE0_TX_DN<14>")
	)
	(segment
		(start 309.236364 -320.945002)
		(end 305.140106 -325.04126)
		(width 0.14732)
		(layer "In15.Cu")
		(net "P5E_CPU0_PE0_TX_DN<14>")
	)
	(segment
		(start 312.298588 -320.45529)
		(end 310.41848 -320.45529)
		(width 0.14732)
		(layer "In15.Cu")
		(net "P5E_CPU0_PE0_TX_DN<14>")
	)
	(segment
		(start 350.463358 -222.271336)
		(end 350.455992 -222.267018)
		(width 0.0889)
		(layer "In15.Cu")
		(net "P5E_CPU0_PE0_TX_DN<14>")
	)
	(segment
		(start 349.995236 -216.574878)
		(end 349.986346 -216.569798)
		(width 0.0889)
		(layer "In15.Cu")
		(net "P5E_CPU0_PE0_TX_DN<14>")
	)
	(segment
		(start 315.616844 -249.954542)
		(end 315.477398 -254.377698)
		(width 0.14732)
		(layer "In15.Cu")
		(net "P5E_CPU0_PE0_TX_DN<14>")
	)
	(segment
		(start 349.524066 -215.112854)
		(end 349.525082 -215.112346)
		(width 0.0889)
		(layer "In15.Cu")
		(net "P5E_CPU0_PE0_TX_DN<14>")
	)
	(segment
		(start 308.869588 -399.910808)
		(end 308.869588 -403.948138)
		(width 0.14732)
		(layer "In15.Cu")
		(net "P5E_CPU0_PE0_TX_DN<14>")
	)
	(segment
		(start 313.16549 -319.588134)
		(end 312.298588 -320.45529)
		(width 0.14732)
		(layer "In15.Cu")
		(net "P5E_CPU0_PE0_TX_DN<14>")
	)
	(segment
		(start 334.078326 -202.292458)
		(end 330.961492 -205.197456)
		(width 0.14732)
		(layer "In15.Cu")
		(net "P5E_CPU0_PE0_TX_DN<14>")
	)
	(segment
		(start 305.140106 -325.04126)
		(end 305.140106 -327.765156)
		(width 0.14732)
		(layer "In15.Cu")
		(net "P5E_CPU0_PE0_TX_DN<14>")
	)
	(segment
		(start 334.66278 -201.811636)
		(end 334.078326 -202.292458)
		(width 0.14732)
		(layer "In15.Cu")
		(net "P5E_CPU0_PE0_TX_DN<14>")
	)
	(segment
		(start 321.527932 -215.152478)
		(end 318.739266 -220.527372)
		(width 0.14732)
		(layer "In15.Cu")
		(net "P5E_CPU0_PE0_TX_DN<14>")
	)
	(segment
		(start 317.33363 -312.1279)
		(end 317.332106 -312.132472)
		(width 0.14732)
		(layer "In15.Cu")
		(net "P5E_CPU0_PE0_TX_DN<14>")
	)
	(segment
		(start 308.684168 -406.70988)
		(end 308.389528 -407.00452)
		(width 0.14732)
		(layer "In15.Cu")
		(net "P5E_CPU0_PE0_TX_DN<14>")
	)
	(segment
		(start 317.310262 -312.187336)
		(end 317.309754 -312.188606)
		(width 0.14732)
		(layer "In15.Cu")
		(net "P5E_CPU0_PE0_TX_DN<14>")
	)
	(segment
		(start 350.464882 -222.272098)
		(end 350.463358 -222.271336)
		(width 0.0889)
		(layer "In15.Cu")
		(net "P5E_CPU0_PE0_TX_DN<14>")
	)
	(segment
		(start 317.310008 -312.189114)
		(end 315.944504 -315.619384)
		(width 0.14732)
		(layer "In15.Cu")
		(net "P5E_CPU0_PE0_TX_DN<14>")
	)
	(segment
		(start 349.995236 -219.830396)
		(end 349.986346 -219.825316)
		(width 0.0889)
		(layer "In15.Cu")
		(net "P5E_CPU0_PE0_TX_DN<14>")
	)
	(arc
		(start 349.807784 -216.25052)
		(mid 349.733793 -215.970954)
		(end 349.531178 -215.764618)
		(width 0.0889)
		(layer "In15.Cu")
		(net "P5E_CPU0_PE0_TX_DN<14>")
	)
	(arc
		(start 349.807784 -217.888566)
		(mid 349.807704 -217.876118)
		(end 349.808038 -217.863674)
		(width 0.0889)
		(layer "In15.Cu")
		(net "P5E_CPU0_PE0_TX_DN<14>")
	)
	(arc
		(start 350.747838 -222.773748)
		(mid 350.747671 -222.762572)
		(end 350.747838 -222.751396)
		(width 0.0889)
		(layer "In15.Cu")
		(net "P5E_CPU0_PE0_TX_DN<14>")
	)
	(arc
		(start 350.747584 -222.761556)
		(mid 350.673593 -222.48199)
		(end 350.470978 -222.275654)
		(width 0.0889)
		(layer "In15.Cu")
		(net "P5E_CPU0_PE0_TX_DN<14>")
	)
	(arc
		(start 349.808038 -217.863674)
		(mid 349.859092 -217.689094)
		(end 349.986346 -217.559128)
		(width 0.0889)
		(layer "In15.Cu")
		(net "P5E_CPU0_PE0_TX_DN<14>")
	)
	(arc
		(start 349.760032 -214.349584)
		(mid 349.667393 -214.230449)
		(end 349.55988 -214.12454)
		(width 0.0889)
		(layer "In15.Cu")
		(net "P5E_CPU0_PE0_TX_DN<14>")
	)
	(arc
		(start 349.995236 -220.809566)
		(mid 350.27785 -220.323448)
		(end 350.001332 -219.833952)
		(width 0.0889)
		(layer "In15.Cu")
		(net "P5E_CPU0_PE0_TX_DN<14>")
	)
	(arc
		(start 350.27743 -218.676728)
		(mid 350.19806 -218.402994)
		(end 349.995236 -218.202764)
		(width 0.0889)
		(layer "In15.Cu")
		(net "P5E_CPU0_PE0_TX_DN<14>")
	)
	(arc
		(start 349.995236 -217.554048)
		(mid 350.27785 -217.06793)
		(end 350.001332 -216.578434)
		(width 0.0889)
		(layer "In15.Cu")
		(net "P5E_CPU0_PE0_TX_DN<14>")
	)
	(arc
		(start 351.217484 -223.557084)
		(mid 351.137322 -223.284895)
		(end 350.935036 -223.085914)
		(width 0.0889)
		(layer "In15.Cu")
		(net "P5E_CPU0_PE0_TX_DN<14>")
	)
	(arc
		(start 349.986346 -216.569798)
		(mid 349.855432 -216.433438)
		(end 349.807784 -216.25052)
		(width 0.0889)
		(layer "In15.Cu")
		(net "P5E_CPU0_PE0_TX_DN<14>")
	)
	(arc
		(start 349.516192 -215.755982)
		(mid 349.337595 -215.436704)
		(end 349.516192 -215.117426)
		(width 0.0889)
		(layer "In15.Cu")
		(net "P5E_CPU0_PE0_TX_DN<14>")
	)
	(arc
		(start 350.455992 -222.267018)
		(mid 350.325078 -222.130658)
		(end 350.27743 -221.94774)
		(width 0.0889)
		(layer "In15.Cu")
		(net "P5E_CPU0_PE0_TX_DN<14>")
	)
	(arc
		(start 349.55988 -214.12454)
		(mid 349.530777 -214.101863)
		(end 349.499936 -214.081614)
		(width 0.0889)
		(layer "In15.Cu")
		(net "P5E_CPU0_PE0_TX_DN<14>")
	)
	(arc
		(start 351.357438 -223.867472)
		(mid 351.256117 -223.741351)
		(end 351.217484 -223.584262)
		(width 0.0889)
		(layer "In15.Cu")
		(net "P5E_CPU0_PE0_TX_DN<14>")
	)
	(arc
		(start 349.807784 -221.144084)
		(mid 349.807704 -221.131636)
		(end 349.808038 -221.119192)
		(width 0.0889)
		(layer "In15.Cu")
		(net "P5E_CPU0_PE0_TX_DN<14>")
	)
	(arc
		(start 350.926146 -223.080834)
		(mid 350.798253 -222.949772)
		(end 350.747838 -222.773748)
		(width 0.0889)
		(layer "In15.Cu")
		(net "P5E_CPU0_PE0_TX_DN<14>")
	)
	(arc
		(start 349.986346 -221.453202)
		(mid 349.857942 -221.321257)
		(end 349.807784 -221.144084)
		(width 0.0889)
		(layer "In15.Cu")
		(net "P5E_CPU0_PE0_TX_DN<14>")
	)
	(arc
		(start 349.499936 -214.081614)
		(mid 349.38082 -213.955937)
		(end 349.33763 -213.788244)
		(width 0.0889)
		(layer "In15.Cu")
		(net "P5E_CPU0_PE0_TX_DN<14>")
	)
	(arc
		(start 349.995236 -219.18168)
		(mid 350.198059 -218.981449)
		(end 350.27743 -218.707716)
		(width 0.0889)
		(layer "In15.Cu")
		(net "P5E_CPU0_PE0_TX_DN<14>")
	)
	(arc
		(start 349.808038 -221.119192)
		(mid 349.859092 -220.944612)
		(end 349.986346 -220.814646)
		(width 0.0889)
		(layer "In15.Cu")
		(net "P5E_CPU0_PE0_TX_DN<14>")
	)
	(arc
		(start 349.538036 -215.103964)
		(mid 349.735297 -214.898358)
		(end 349.807022 -214.622634)
		(width 0.0889)
		(layer "In15.Cu")
		(net "P5E_CPU0_PE0_TX_DN<14>")
	)
	(arc
		(start 350.27743 -221.932246)
		(mid 350.19806 -221.658512)
		(end 349.995236 -221.458282)
		(width 0.0889)
		(layer "In15.Cu")
		(net "P5E_CPU0_PE0_TX_DN<14>")
	)
	(arc
		(start 349.986346 -219.825316)
		(mid 349.80787 -219.506038)
		(end 349.986346 -219.18676)
		(width 0.0889)
		(layer "In15.Cu")
		(net "P5E_CPU0_PE0_TX_DN<14>")
	)
	(arc
		(start 349.986346 -218.197684)
		(mid 349.857942 -218.065739)
		(end 349.807784 -217.888566)
		(width 0.0889)
		(layer "In15.Cu")
		(net "P5E_CPU0_PE0_TX_DN<14>")
	)
	(arc
		(start 349.807022 -214.504778)
		(mid 349.79521 -214.42364)
		(end 349.760032 -214.349584)
		(width 0.0889)
		(layer "In15.Cu")
		(net "P5E_CPU0_PE0_TX_DN<14>")
	)
	(segment
		(start 311.75833 -407.924254)
		(end 311.43194 -408.250644)
		(width 0.13208)
		(layer "F.Cu")
		(net "P5E_CPU0_PE0_TX_DN<13>")
	)
	(segment
		(start 350.18218 -224.925382)
		(end 350.18218 -224.389696)
		(width 0.13208)
		(layer "F.Cu")
		(net "P5E_CPU0_PE0_TX_DN<13>")
	)
	(segment
		(start 311.43194 -408.250644)
		(end 311.427368 -408.250644)
		(width 0.13208)
		(layer "F.Cu")
		(net "P5E_CPU0_PE0_TX_DN<13>")
	)
	(segment
		(start 311.75833 -407.310082)
		(end 311.75833 -407.924254)
		(width 0.13208)
		(layer "F.Cu")
		(net "P5E_CPU0_PE0_TX_DN<13>")
	)
	(segment
		(start 350.18218 -224.389696)
		(end 350.182434 -224.389442)
		(width 0.13208)
		(layer "F.Cu")
		(net "P5E_CPU0_PE0_TX_DN<13>")
	)
	(segment
		(start 311.452768 -407.00452)
		(end 311.75833 -407.310082)
		(width 0.13208)
		(layer "F.Cu")
		(net "P5E_CPU0_PE0_TX_DN<13>")
	)
	(segment
		(start 309.828692 -364.548166)
		(end 311.932828 -399.910808)
		(width 0.14732)
		(layer "In15.Cu")
		(net "P5E_CPU0_PE0_TX_DN<13>")
	)
	(segment
		(start 316.437772 -253.462282)
		(end 316.437772 -254.31115)
		(width 0.14732)
		(layer "In15.Cu")
		(net "P5E_CPU0_PE0_TX_DN<13>")
	)
	(segment
		(start 322.304918 -215.704166)
		(end 319.650618 -220.81998)
		(width 0.14732)
		(layer "In15.Cu")
		(net "P5E_CPU0_PE0_TX_DN<13>")
	)
	(segment
		(start 317.847218 -232.489756)
		(end 316.554612 -249.992896)
		(width 0.14732)
		(layer "In15.Cu")
		(net "P5E_CPU0_PE0_TX_DN<13>")
	)
	(segment
		(start 311.747408 -405.831548)
		(end 311.747408 -406.70988)
		(width 0.14732)
		(layer "In15.Cu")
		(net "P5E_CPU0_PE0_TX_DN<13>")
	)
	(segment
		(start 306.07762 -325.42099)
		(end 306.07762 -328.157586)
		(width 0.14732)
		(layer "In15.Cu")
		(net "P5E_CPU0_PE0_TX_DN<13>")
	)
	(segment
		(start 348.43974 -213.144608)
		(end 348.43974 -213.12251)
		(width 0.0889)
		(layer "In15.Cu")
		(net "P5E_CPU0_PE0_TX_DN<13>")
	)
	(segment
		(start 349.525082 -222.272098)
		(end 349.523558 -222.271336)
		(width 0.0889)
		(layer "In15.Cu")
		(net "P5E_CPU0_PE0_TX_DN<13>")
	)
	(segment
		(start 317.046864 -315.677804)
		(end 313.563254 -320.65214)
		(width 0.14732)
		(layer "In15.Cu")
		(net "P5E_CPU0_PE0_TX_DN<13>")
	)
	(segment
		(start 349.046546 -220.814646)
		(end 349.055436 -220.809566)
		(width 0.0889)
		(layer "In15.Cu")
		(net "P5E_CPU0_PE0_TX_DN<13>")
	)
	(segment
		(start 316.554612 -249.992896)
		(end 316.437772 -253.462282)
		(width 0.14732)
		(layer "In15.Cu")
		(net "P5E_CPU0_PE0_TX_DN<13>")
	)
	(segment
		(start 348.39783 -213.186518)
		(end 348.43974 -213.144608)
		(width 0.0889)
		(layer "In15.Cu")
		(net "P5E_CPU0_PE0_TX_DN<13>")
	)
	(segment
		(start 349.531178 -222.275654)
		(end 349.527876 -222.273622)
		(width 0.0889)
		(layer "In15.Cu")
		(net "P5E_CPU0_PE0_TX_DN<13>")
	)
	(segment
		(start 349.995236 -223.085914)
		(end 349.986346 -223.080834)
		(width 0.0889)
		(layer "In15.Cu")
		(net "P5E_CPU0_PE0_TX_DN<13>")
	)
	(segment
		(start 348.867476 -214.470996)
		(end 348.867222 -214.470996)
		(width 0.0889)
		(layer "In15.Cu")
		(net "P5E_CPU0_PE0_TX_DN<13>")
	)
	(segment
		(start 335.860644 -202.177142)
		(end 335.188814 -202.597258)
		(width 0.14732)
		(layer "In15.Cu")
		(net "P5E_CPU0_PE0_TX_DN<13>")
	)
	(segment
		(start 331.942694 -205.557882)
		(end 322.304918 -215.704166)
		(width 0.14732)
		(layer "In15.Cu")
		(net "P5E_CPU0_PE0_TX_DN<13>")
	)
	(segment
		(start 335.188814 -202.597258)
		(end 334.722724 -202.978004)
		(width 0.14732)
		(layer "In15.Cu")
		(net "P5E_CPU0_PE0_TX_DN<13>")
	)
	(segment
		(start 348.43974 -211.830158)
		(end 347.57741 -209.74812)
		(width 0.14732)
		(layer "In15.Cu")
		(net "P5E_CPU0_PE0_TX_DN<13>")
	)
	(segment
		(start 349.046546 -217.559128)
		(end 349.055436 -217.554048)
		(width 0.0889)
		(layer "In15.Cu")
		(net "P5E_CPU0_PE0_TX_DN<13>")
	)
	(segment
		(start 338.174076 -202.183746)
		(end 335.860644 -202.177142)
		(width 0.14732)
		(layer "In15.Cu")
		(net "P5E_CPU0_PE0_TX_DN<13>")
	)
	(segment
		(start 349.046546 -219.18676)
		(end 349.055436 -219.18168)
		(width 0.0889)
		(layer "In15.Cu")
		(net "P5E_CPU0_PE0_TX_DN<13>")
	)
	(segment
		(start 349.523558 -222.271336)
		(end 349.516192 -222.267018)
		(width 0.0889)
		(layer "In15.Cu")
		(net "P5E_CPU0_PE0_TX_DN<13>")
	)
	(segment
		(start 318.297052 -229.575868)
		(end 318.297306 -229.575868)
		(width 0.14732)
		(layer "In15.Cu")
		(net "P5E_CPU0_PE0_TX_DN<13>")
	)
	(segment
		(start 348.585282 -215.761062)
		(end 348.583758 -215.7603)
		(width 0.0889)
		(layer "In15.Cu")
		(net "P5E_CPU0_PE0_TX_DN<13>")
	)
	(segment
		(start 349.995236 -224.7138)
		(end 349.986346 -224.70872)
		(width 0.0889)
		(layer "In15.Cu")
		(net "P5E_CPU0_PE0_TX_DN<13>")
	)
	(segment
		(start 350.277684 -223.575626)
		(end 350.277684 -223.561402)
		(width 0.0889)
		(layer "In15.Cu")
		(net "P5E_CPU0_PE0_TX_DN<13>")
	)
	(segment
		(start 338.228432 -202.183746)
		(end 338.174076 -202.183492)
		(width 0.14732)
		(layer "In15.Cu")
		(net "P5E_CPU0_PE0_TX_DN<13>")
	)
	(segment
		(start 334.722724 -202.978004)
		(end 331.942694 -205.557882)
		(width 0.14732)
		(layer "In15.Cu")
		(net "P5E_CPU0_PE0_TX_DN<13>")
	)
	(segment
		(start 348.43466 -213.927182)
		(end 348.402402 -213.84387)
		(width 0.0889)
		(layer "In15.Cu")
		(net "P5E_CPU0_PE0_TX_DN<13>")
	)
	(segment
		(start 306.07762 -328.157586)
		(end 304.781966 -329.45324)
		(width 0.14732)
		(layer "In15.Cu")
		(net "P5E_CPU0_PE0_TX_DN<13>")
	)
	(segment
		(start 349.986346 -224.070164)
		(end 349.995236 -224.065084)
		(width 0.0889)
		(layer "In15.Cu")
		(net "P5E_CPU0_PE0_TX_DN<13>")
	)
	(segment
		(start 348.39783 -213.819486)
		(end 348.39783 -213.186518)
		(width 0.0889)
		(layer "In15.Cu")
		(net "P5E_CPU0_PE0_TX_DN<13>")
	)
	(segment
		(start 349.055436 -218.202764)
		(end 349.046546 -218.197684)
		(width 0.0889)
		(layer "In15.Cu")
		(net "P5E_CPU0_PE0_TX_DN<13>")
	)
	(segment
		(start 348.43974 -213.12251)
		(end 348.43974 -211.830158)
		(width 0.14732)
		(layer "In15.Cu")
		(net "P5E_CPU0_PE0_TX_DN<13>")
	)
	(segment
		(start 313.563254 -320.65214)
		(end 311.88914 -322.326508)
		(width 0.14732)
		(layer "In15.Cu")
		(net "P5E_CPU0_PE0_TX_DN<13>")
	)
	(segment
		(start 311.932828 -403.948138)
		(end 311.747408 -405.831548)
		(width 0.14732)
		(layer "In15.Cu")
		(net "P5E_CPU0_PE0_TX_DN<13>")
	)
	(segment
		(start 349.527876 -222.273622)
		(end 349.525082 -222.272098)
		(width 0.0889)
		(layer "In15.Cu")
		(net "P5E_CPU0_PE0_TX_DN<13>")
	)
	(segment
		(start 349.337884 -217.082878)
		(end 349.337884 -217.05443)
		(width 0.0889)
		(layer "In15.Cu")
		(net "P5E_CPU0_PE0_TX_DN<13>")
	)
	(segment
		(start 311.88914 -322.326508)
		(end 311.081166 -322.326508)
		(width 0.14732)
		(layer "In15.Cu")
		(net "P5E_CPU0_PE0_TX_DN<13>")
	)
	(segment
		(start 304.781966 -341.842344)
		(end 309.828692 -364.548166)
		(width 0.14732)
		(layer "In15.Cu")
		(net "P5E_CPU0_PE0_TX_DN<13>")
	)
	(segment
		(start 311.081166 -322.326508)
		(end 310.514746 -321.760088)
		(width 0.14732)
		(layer "In15.Cu")
		(net "P5E_CPU0_PE0_TX_DN<13>")
	)
	(segment
		(start 348.583758 -215.7603)
		(end 348.576392 -215.755982)
		(width 0.0889)
		(layer "In15.Cu")
		(net "P5E_CPU0_PE0_TX_DN<13>")
	)
	(segment
		(start 348.576392 -215.117426)
		(end 348.584266 -215.112854)
		(width 0.0889)
		(layer "In15.Cu")
		(net "P5E_CPU0_PE0_TX_DN<13>")
	)
	(segment
		(start 348.584266 -215.112854)
		(end 348.585282 -215.112346)
		(width 0.0889)
		(layer "In15.Cu")
		(net "P5E_CPU0_PE0_TX_DN<13>")
	)
	(segment
		(start 341.275416 -203.446126)
		(end 338.228178 -202.183746)
		(width 0.14732)
		(layer "In15.Cu")
		(net "P5E_CPU0_PE0_TX_DN<13>")
	)
	(segment
		(start 319.650618 -220.81998)
		(end 318.297306 -229.575614)
		(width 0.14732)
		(layer "In15.Cu")
		(net "P5E_CPU0_PE0_TX_DN<13>")
	)
	(segment
		(start 349.055436 -219.830396)
		(end 349.046546 -219.825316)
		(width 0.0889)
		(layer "In15.Cu")
		(net "P5E_CPU0_PE0_TX_DN<13>")
	)
	(segment
		(start 349.055436 -221.458282)
		(end 349.046546 -221.453202)
		(width 0.0889)
		(layer "In15.Cu")
		(net "P5E_CPU0_PE0_TX_DN<13>")
	)
	(segment
		(start 349.33763 -221.94774)
		(end 349.33763 -221.932246)
		(width 0.0889)
		(layer "In15.Cu")
		(net "P5E_CPU0_PE0_TX_DN<13>")
	)
	(segment
		(start 309.738522 -321.760088)
		(end 306.07762 -325.42099)
		(width 0.14732)
		(layer "In15.Cu")
		(net "P5E_CPU0_PE0_TX_DN<13>")
	)
	(segment
		(start 310.514746 -321.760088)
		(end 309.738522 -321.760088)
		(width 0.14732)
		(layer "In15.Cu")
		(net "P5E_CPU0_PE0_TX_DN<13>")
	)
	(segment
		(start 350.338898 -224.66046)
		(end 350.317816 -224.738438)
		(width 0.0889)
		(layer "In15.Cu")
		(net "P5E_CPU0_PE0_TX_DN<13>")
	)
	(segment
		(start 311.747408 -406.70988)
		(end 311.452768 -407.00452)
		(width 0.14732)
		(layer "In15.Cu")
		(net "P5E_CPU0_PE0_TX_DN<13>")
	)
	(segment
		(start 316.437772 -254.31115)
		(end 319.943226 -308.61762)
		(width 0.14732)
		(layer "In15.Cu")
		(net "P5E_CPU0_PE0_TX_DN<13>")
	)
	(segment
		(start 347.57741 -209.74812)
		(end 341.275416 -203.446126)
		(width 0.14732)
		(layer "In15.Cu")
		(net "P5E_CPU0_PE0_TX_DN<13>")
	)
	(segment
		(start 349.808038 -222.751396)
		(end 349.807784 -222.761556)
		(width 0.0889)
		(layer "In15.Cu")
		(net "P5E_CPU0_PE0_TX_DN<13>")
	)
	(segment
		(start 318.297306 -229.575868)
		(end 317.847218 -232.489756)
		(width 0.14732)
		(layer "In15.Cu")
		(net "P5E_CPU0_PE0_TX_DN<13>")
	)
	(segment
		(start 350.182434 -224.389442)
		(end 350.338898 -224.66046)
		(width 0.0889)
		(layer "In15.Cu")
		(net "P5E_CPU0_PE0_TX_DN<13>")
	)
	(segment
		(start 348.867476 -214.644732)
		(end 348.867476 -214.470996)
		(width 0.0889)
		(layer "In15.Cu")
		(net "P5E_CPU0_PE0_TX_DN<13>")
	)
	(segment
		(start 311.932828 -399.910808)
		(end 311.932828 -403.948138)
		(width 0.14732)
		(layer "In15.Cu")
		(net "P5E_CPU0_PE0_TX_DN<13>")
	)
	(segment
		(start 338.174076 -202.183492)
		(end 338.174076 -202.183746)
		(width 0.14732)
		(layer "In15.Cu")
		(net "P5E_CPU0_PE0_TX_DN<13>")
	)
	(segment
		(start 349.33763 -218.707716)
		(end 349.33763 -218.676728)
		(width 0.0889)
		(layer "In15.Cu")
		(net "P5E_CPU0_PE0_TX_DN<13>")
	)
	(segment
		(start 304.781966 -329.45324)
		(end 304.781966 -341.842344)
		(width 0.14732)
		(layer "In15.Cu")
		(net "P5E_CPU0_PE0_TX_DN<13>")
	)
	(segment
		(start 349.055436 -216.574878)
		(end 349.046546 -216.569798)
		(width 0.0889)
		(layer "In15.Cu")
		(net "P5E_CPU0_PE0_TX_DN<13>")
	)
	(segment
		(start 348.588076 -215.762586)
		(end 348.585282 -215.761062)
		(width 0.0889)
		(layer "In15.Cu")
		(net "P5E_CPU0_PE0_TX_DN<13>")
	)
	(segment
		(start 319.943226 -308.61762)
		(end 317.046864 -315.677804)
		(width 0.14732)
		(layer "In15.Cu")
		(net "P5E_CPU0_PE0_TX_DN<13>")
	)
	(segment
		(start 318.297306 -229.575614)
		(end 318.297052 -229.575868)
		(width 0.14732)
		(layer "In15.Cu")
		(net "P5E_CPU0_PE0_TX_DN<13>")
	)
	(segment
		(start 349.995236 -224.065084)
		(end 350.001332 -224.061528)
		(width 0.0889)
		(layer "In15.Cu")
		(net "P5E_CPU0_PE0_TX_DN<13>")
	)
	(segment
		(start 338.228178 -202.183746)
		(end 338.228432 -202.183746)
		(width 0.14732)
		(layer "In15.Cu")
		(net "P5E_CPU0_PE0_TX_DN<13>")
	)
	(segment
		(start 348.591378 -215.764618)
		(end 348.588076 -215.762586)
		(width 0.0889)
		(layer "In15.Cu")
		(net "P5E_CPU0_PE0_TX_DN<13>")
	)
	(segment
		(start 349.337884 -220.338396)
		(end 349.337884 -220.309948)
		(width 0.0889)
		(layer "In15.Cu")
		(net "P5E_CPU0_PE0_TX_DN<13>")
	)
	(arc
		(start 349.986346 -223.080834)
		(mid 349.859266 -222.95082)
		(end 349.808292 -222.776288)
		(width 0.0889)
		(layer "In15.Cu")
		(net "P5E_CPU0_PE0_TX_DN<13>")
	)
	(arc
		(start 348.576392 -215.755982)
		(mid 348.445478 -215.619622)
		(end 348.39783 -215.436704)
		(width 0.0889)
		(layer "In15.Cu")
		(net "P5E_CPU0_PE0_TX_DN<13>")
	)
	(arc
		(start 348.868238 -221.144084)
		(mid 348.868071 -221.132908)
		(end 348.868238 -221.121732)
		(width 0.0889)
		(layer "In15.Cu")
		(net "P5E_CPU0_PE0_TX_DN<13>")
	)
	(arc
		(start 350.317816 -224.738438)
		(mid 350.15372 -224.762785)
		(end 349.995236 -224.7138)
		(width 0.0889)
		(layer "In15.Cu")
		(net "P5E_CPU0_PE0_TX_DN<13>")
	)
	(arc
		(start 349.046546 -218.197684)
		(mid 348.918227 -218.065712)
		(end 348.868238 -217.888566)
		(width 0.0889)
		(layer "In15.Cu")
		(net "P5E_CPU0_PE0_TX_DN<13>")
	)
	(arc
		(start 349.33763 -221.932246)
		(mid 349.25826 -221.658512)
		(end 349.055436 -221.458282)
		(width 0.0889)
		(layer "In15.Cu")
		(net "P5E_CPU0_PE0_TX_DN<13>")
	)
	(arc
		(start 349.046546 -221.453202)
		(mid 348.918227 -221.32123)
		(end 348.868238 -221.144084)
		(width 0.0889)
		(layer "In15.Cu")
		(net "P5E_CPU0_PE0_TX_DN<13>")
	)
	(arc
		(start 348.867222 -214.470996)
		(mid 348.860888 -214.416934)
		(end 348.842838 -214.365586)
		(width 0.0889)
		(layer "In15.Cu")
		(net "P5E_CPU0_PE0_TX_DN<13>")
	)
	(arc
		(start 348.582234 -214.093298)
		(mid 348.49342 -214.023587)
		(end 348.43466 -213.927182)
		(width 0.0889)
		(layer "In15.Cu")
		(net "P5E_CPU0_PE0_TX_DN<13>")
	)
	(arc
		(start 349.337884 -217.05443)
		(mid 349.259773 -216.777481)
		(end 349.055436 -216.574878)
		(width 0.0889)
		(layer "In15.Cu")
		(net "P5E_CPU0_PE0_TX_DN<13>")
	)
	(arc
		(start 349.046546 -216.569798)
		(mid 348.915632 -216.433438)
		(end 348.867984 -216.25052)
		(width 0.0889)
		(layer "In15.Cu")
		(net "P5E_CPU0_PE0_TX_DN<13>")
	)
	(arc
		(start 350.277684 -223.561402)
		(mid 350.198543 -223.286779)
		(end 349.995236 -223.085914)
		(width 0.0889)
		(layer "In15.Cu")
		(net "P5E_CPU0_PE0_TX_DN<13>")
	)
	(arc
		(start 350.001332 -224.061528)
		(mid 350.203745 -223.855115)
		(end 350.277684 -223.575626)
		(width 0.0889)
		(layer "In15.Cu")
		(net "P5E_CPU0_PE0_TX_DN<13>")
	)
	(arc
		(start 349.055436 -219.18168)
		(mid 349.258259 -218.981449)
		(end 349.33763 -218.707716)
		(width 0.0889)
		(layer "In15.Cu")
		(net "P5E_CPU0_PE0_TX_DN<13>")
	)
	(arc
		(start 349.33763 -218.676728)
		(mid 349.25826 -218.402994)
		(end 349.055436 -218.202764)
		(width 0.0889)
		(layer "In15.Cu")
		(net "P5E_CPU0_PE0_TX_DN<13>")
	)
	(arc
		(start 349.055436 -220.809566)
		(mid 349.257722 -220.610585)
		(end 349.337884 -220.338396)
		(width 0.0889)
		(layer "In15.Cu")
		(net "P5E_CPU0_PE0_TX_DN<13>")
	)
	(arc
		(start 348.39783 -215.436704)
		(mid 348.397882 -215.429337)
		(end 348.398084 -215.421972)
		(width 0.0889)
		(layer "In15.Cu")
		(net "P5E_CPU0_PE0_TX_DN<13>")
	)
	(arc
		(start 349.807784 -222.761556)
		(mid 349.733793 -222.48199)
		(end 349.531178 -222.275654)
		(width 0.0889)
		(layer "In15.Cu")
		(net "P5E_CPU0_PE0_TX_DN<13>")
	)
	(arc
		(start 348.585282 -215.112346)
		(mid 348.786564 -214.914859)
		(end 348.867476 -214.644732)
		(width 0.0889)
		(layer "In15.Cu")
		(net "P5E_CPU0_PE0_TX_DN<13>")
	)
	(arc
		(start 349.516192 -222.267018)
		(mid 349.385278 -222.130658)
		(end 349.33763 -221.94774)
		(width 0.0889)
		(layer "In15.Cu")
		(net "P5E_CPU0_PE0_TX_DN<13>")
	)
	(arc
		(start 348.867984 -219.512642)
		(mid 348.86789 -219.50426)
		(end 348.867984 -219.495878)
		(width 0.0889)
		(layer "In15.Cu")
		(net "P5E_CPU0_PE0_TX_DN<13>")
	)
	(arc
		(start 349.046546 -219.825316)
		(mid 348.917257 -219.69183)
		(end 348.867984 -219.512642)
		(width 0.0889)
		(layer "In15.Cu")
		(net "P5E_CPU0_PE0_TX_DN<13>")
	)
	(arc
		(start 349.808292 -222.776288)
		(mid 349.807959 -222.763844)
		(end 349.808038 -222.751396)
		(width 0.0889)
		(layer "In15.Cu")
		(net "P5E_CPU0_PE0_TX_DN<13>")
	)
	(arc
		(start 349.337884 -220.309948)
		(mid 349.259773 -220.032999)
		(end 349.055436 -219.830396)
		(width 0.0889)
		(layer "In15.Cu")
		(net "P5E_CPU0_PE0_TX_DN<13>")
	)
	(arc
		(start 348.868238 -217.866214)
		(mid 348.918731 -217.690236)
		(end 349.046546 -217.559128)
		(width 0.0889)
		(layer "In15.Cu")
		(net "P5E_CPU0_PE0_TX_DN<13>")
	)
	(arc
		(start 349.986346 -224.70872)
		(mid 349.80787 -224.389442)
		(end 349.986346 -224.070164)
		(width 0.0889)
		(layer "In15.Cu")
		(net "P5E_CPU0_PE0_TX_DN<13>")
	)
	(arc
		(start 349.055436 -217.554048)
		(mid 349.257722 -217.355067)
		(end 349.337884 -217.082878)
		(width 0.0889)
		(layer "In15.Cu")
		(net "P5E_CPU0_PE0_TX_DN<13>")
	)
	(arc
		(start 348.402402 -213.84387)
		(mid 348.398983 -213.83189)
		(end 348.39783 -213.819486)
		(width 0.0889)
		(layer "In15.Cu")
		(net "P5E_CPU0_PE0_TX_DN<13>")
	)
	(arc
		(start 348.867984 -219.495878)
		(mid 348.918053 -219.318653)
		(end 349.046546 -219.18676)
		(width 0.0889)
		(layer "In15.Cu")
		(net "P5E_CPU0_PE0_TX_DN<13>")
	)
	(arc
		(start 348.868238 -217.888566)
		(mid 348.868071 -217.87739)
		(end 348.868238 -217.866214)
		(width 0.0889)
		(layer "In15.Cu")
		(net "P5E_CPU0_PE0_TX_DN<13>")
	)
	(arc
		(start 348.868238 -221.121732)
		(mid 348.918731 -220.945754)
		(end 349.046546 -220.814646)
		(width 0.0889)
		(layer "In15.Cu")
		(net "P5E_CPU0_PE0_TX_DN<13>")
	)
	(arc
		(start 348.398084 -215.421972)
		(mid 348.449138 -215.247392)
		(end 348.576392 -215.117426)
		(width 0.0889)
		(layer "In15.Cu")
		(net "P5E_CPU0_PE0_TX_DN<13>")
	)
	(arc
		(start 348.867984 -216.25052)
		(mid 348.793993 -215.970954)
		(end 348.591378 -215.764618)
		(width 0.0889)
		(layer "In15.Cu")
		(net "P5E_CPU0_PE0_TX_DN<13>")
	)
	(arc
		(start 348.842838 -214.365586)
		(mid 348.734511 -214.208414)
		(end 348.582234 -214.093298)
		(width 0.0889)
		(layer "In15.Cu")
		(net "P5E_CPU0_PE0_TX_DN<13>")
	)
	(segment
		(start 314.516008 -407.00452)
		(end 314.82157 -407.310082)
		(width 0.13208)
		(layer "F.Cu")
		(net "P5E_CPU0_PE0_TX_DN<12>")
	)
	(segment
		(start 314.82157 -407.924254)
		(end 314.49518 -408.250644)
		(width 0.13208)
		(layer "F.Cu")
		(net "P5E_CPU0_PE0_TX_DN<12>")
	)
	(segment
		(start 349.712534 -224.111566)
		(end 349.712534 -223.57588)
		(width 0.13208)
		(layer "F.Cu")
		(net "P5E_CPU0_PE0_TX_DN<12>")
	)
	(segment
		(start 349.712534 -223.57588)
		(end 349.71228 -223.575626)
		(width 0.13208)
		(layer "F.Cu")
		(net "P5E_CPU0_PE0_TX_DN<12>")
	)
	(segment
		(start 314.49518 -408.250644)
		(end 314.490608 -408.250644)
		(width 0.13208)
		(layer "F.Cu")
		(net "P5E_CPU0_PE0_TX_DN<12>")
	)
	(segment
		(start 314.82157 -407.310082)
		(end 314.82157 -407.924254)
		(width 0.13208)
		(layer "F.Cu")
		(net "P5E_CPU0_PE0_TX_DN<12>")
	)
	(segment
		(start 349.71228 -223.575626)
		(end 349.555816 -223.846644)
		(width 0.0889)
		(layer "In15.Cu")
		(net "P5E_CPU0_PE0_TX_DN<12>")
	)
	(segment
		(start 314.810648 -405.831548)
		(end 314.810648 -406.70988)
		(width 0.14732)
		(layer "In15.Cu")
		(net "P5E_CPU0_PE0_TX_DN<12>")
	)
	(segment
		(start 307.032152 -328.562716)
		(end 305.749198 -329.84567)
		(width 0.14732)
		(layer "In15.Cu")
		(net "P5E_CPU0_PE0_TX_DN<12>")
	)
	(segment
		(start 317.491618 -250.041156)
		(end 317.369444 -253.69901)
		(width 0.14732)
		(layer "In15.Cu")
		(net "P5E_CPU0_PE0_TX_DN<12>")
	)
	(segment
		(start 348.121732 -216.578434)
		(end 348.106746 -216.569798)
		(width 0.0889)
		(layer "In15.Cu")
		(net "P5E_CPU0_PE0_TX_DN<12>")
	)
	(segment
		(start 305.749198 -329.84567)
		(end 305.749198 -341.735918)
		(width 0.14732)
		(layer "In15.Cu")
		(net "P5E_CPU0_PE0_TX_DN<12>")
	)
	(segment
		(start 317.956692 -316.043056)
		(end 314.37961 -321.151504)
		(width 0.14732)
		(layer "In15.Cu")
		(net "P5E_CPU0_PE0_TX_DN<12>")
	)
	(segment
		(start 340.82736 -204.327506)
		(end 337.979258 -203.147676)
		(width 0.14732)
		(layer "In15.Cu")
		(net "P5E_CPU0_PE0_TX_DN<12>")
	)
	(segment
		(start 323.179694 -216.158064)
		(end 320.707258 -220.923358)
		(width 0.14732)
		(layer "In15.Cu")
		(net "P5E_CPU0_PE0_TX_DN<12>")
	)
	(segment
		(start 347.636592 -215.117426)
		(end 347.644466 -215.112854)
		(width 0.0889)
		(layer "In15.Cu")
		(net "P5E_CPU0_PE0_TX_DN<12>")
	)
	(segment
		(start 347.648276 -215.762586)
		(end 347.645482 -215.761062)
		(width 0.0889)
		(layer "In15.Cu")
		(net "P5E_CPU0_PE0_TX_DN<12>")
	)
	(segment
		(start 348.591378 -222.275654)
		(end 348.576392 -222.267018)
		(width 0.0889)
		(layer "In15.Cu")
		(net "P5E_CPU0_PE0_TX_DN<12>")
	)
	(segment
		(start 314.996068 -403.948138)
		(end 314.810648 -405.831548)
		(width 0.14732)
		(layer "In15.Cu")
		(net "P5E_CPU0_PE0_TX_DN<12>")
	)
	(segment
		(start 307.032152 -325.809356)
		(end 307.032152 -328.562716)
		(width 0.14732)
		(layer "In15.Cu")
		(net "P5E_CPU0_PE0_TX_DN<12>")
	)
	(segment
		(start 310.801512 -364.466378)
		(end 314.996068 -399.910808)
		(width 0.14732)
		(layer "In15.Cu")
		(net "P5E_CPU0_PE0_TX_DN<12>")
	)
	(segment
		(start 347.49994 -213.144608)
		(end 347.49994 -213.12251)
		(width 0.0889)
		(layer "In15.Cu")
		(net "P5E_CPU0_PE0_TX_DN<12>")
	)
	(segment
		(start 346.78747 -210.287616)
		(end 340.82736 -204.327506)
		(width 0.14732)
		(layer "In15.Cu")
		(net "P5E_CPU0_PE0_TX_DN<12>")
	)
	(segment
		(start 347.643958 -215.7603)
		(end 347.636592 -215.755982)
		(width 0.0889)
		(layer "In15.Cu")
		(net "P5E_CPU0_PE0_TX_DN<12>")
	)
	(segment
		(start 347.645482 -215.761062)
		(end 347.643958 -215.7603)
		(width 0.0889)
		(layer "In15.Cu")
		(net "P5E_CPU0_PE0_TX_DN<12>")
	)
	(segment
		(start 347.45803 -213.186518)
		(end 347.49994 -213.144608)
		(width 0.0889)
		(layer "In15.Cu")
		(net "P5E_CPU0_PE0_TX_DN<12>")
	)
	(segment
		(start 348.121732 -219.833952)
		(end 348.119446 -219.832682)
		(width 0.0889)
		(layer "In15.Cu")
		(net "P5E_CPU0_PE0_TX_DN<12>")
	)
	(segment
		(start 349.337884 -223.584262)
		(end 349.337884 -223.557084)
		(width 0.0889)
		(layer "In15.Cu")
		(net "P5E_CPU0_PE0_TX_DN<12>")
	)
	(segment
		(start 337.979258 -203.147676)
		(end 336.136234 -203.142342)
		(width 0.14732)
		(layer "In15.Cu")
		(net "P5E_CPU0_PE0_TX_DN<12>")
	)
	(segment
		(start 348.119446 -219.832682)
		(end 348.107762 -219.825824)
		(width 0.0889)
		(layer "In15.Cu")
		(net "P5E_CPU0_PE0_TX_DN<12>")
	)
	(segment
		(start 348.106746 -220.814646)
		(end 348.115636 -220.809566)
		(width 0.0889)
		(layer "In15.Cu")
		(net "P5E_CPU0_PE0_TX_DN<12>")
	)
	(segment
		(start 314.810648 -406.70988)
		(end 314.516008 -407.00452)
		(width 0.14732)
		(layer "In15.Cu")
		(net "P5E_CPU0_PE0_TX_DN<12>")
	)
	(segment
		(start 347.644466 -215.112854)
		(end 347.645482 -215.112346)
		(width 0.0889)
		(layer "In15.Cu")
		(net "P5E_CPU0_PE0_TX_DN<12>")
	)
	(segment
		(start 348.115636 -221.458282)
		(end 348.106746 -221.453202)
		(width 0.0889)
		(layer "In15.Cu")
		(net "P5E_CPU0_PE0_TX_DN<12>")
	)
	(segment
		(start 348.39783 -218.707716)
		(end 348.39783 -218.676728)
		(width 0.0889)
		(layer "In15.Cu")
		(net "P5E_CPU0_PE0_TX_DN<12>")
	)
	(segment
		(start 347.45803 -213.880954)
		(end 347.45803 -213.186518)
		(width 0.0889)
		(layer "In15.Cu")
		(net "P5E_CPU0_PE0_TX_DN<12>")
	)
	(segment
		(start 318.908938 -232.559352)
		(end 317.491618 -250.041156)
		(width 0.14732)
		(layer "In15.Cu")
		(net "P5E_CPU0_PE0_TX_DN<12>")
	)
	(segment
		(start 349.555816 -223.846644)
		(end 349.477838 -223.867472)
		(width 0.0889)
		(layer "In15.Cu")
		(net "P5E_CPU0_PE0_TX_DN<12>")
	)
	(segment
		(start 348.107762 -219.825824)
		(end 348.106746 -219.825316)
		(width 0.0889)
		(layer "In15.Cu")
		(net "P5E_CPU0_PE0_TX_DN<12>")
	)
	(segment
		(start 320.922904 -308.88305)
		(end 317.956692 -316.043056)
		(width 0.14732)
		(layer "In15.Cu")
		(net "P5E_CPU0_PE0_TX_DN<12>")
	)
	(segment
		(start 311.90946 -323.621908)
		(end 309.2196 -323.621908)
		(width 0.14732)
		(layer "In15.Cu")
		(net "P5E_CPU0_PE0_TX_DN<12>")
	)
	(segment
		(start 336.136234 -203.142342)
		(end 335.522316 -203.52639)
		(width 0.14732)
		(layer "In15.Cu")
		(net "P5E_CPU0_PE0_TX_DN<12>")
	)
	(segment
		(start 309.2196 -323.621908)
		(end 307.032152 -325.809356)
		(width 0.14732)
		(layer "In15.Cu")
		(net "P5E_CPU0_PE0_TX_DN<12>")
	)
	(segment
		(start 317.369444 -253.69901)
		(end 320.922904 -308.88305)
		(width 0.14732)
		(layer "In15.Cu")
		(net "P5E_CPU0_PE0_TX_DN<12>")
	)
	(segment
		(start 348.106746 -219.18676)
		(end 348.112588 -219.183458)
		(width 0.0889)
		(layer "In15.Cu")
		(net "P5E_CPU0_PE0_TX_DN<12>")
	)
	(segment
		(start 348.115636 -218.202764)
		(end 348.106746 -218.197684)
		(width 0.0889)
		(layer "In15.Cu")
		(net "P5E_CPU0_PE0_TX_DN<12>")
	)
	(segment
		(start 348.112588 -219.183458)
		(end 348.11462 -219.182188)
		(width 0.0889)
		(layer "In15.Cu")
		(net "P5E_CPU0_PE0_TX_DN<12>")
	)
	(segment
		(start 348.106746 -217.559128)
		(end 348.115636 -217.554048)
		(width 0.0889)
		(layer "In15.Cu")
		(net "P5E_CPU0_PE0_TX_DN<12>")
	)
	(segment
		(start 348.11462 -219.182188)
		(end 348.115636 -219.18168)
		(width 0.0889)
		(layer "In15.Cu")
		(net "P5E_CPU0_PE0_TX_DN<12>")
	)
	(segment
		(start 314.996068 -399.910808)
		(end 314.996068 -403.948138)
		(width 0.14732)
		(layer "In15.Cu")
		(net "P5E_CPU0_PE0_TX_DN<12>")
	)
	(segment
		(start 348.868238 -222.751396)
		(end 348.867984 -222.761556)
		(width 0.0889)
		(layer "In15.Cu")
		(net "P5E_CPU0_PE0_TX_DN<12>")
	)
	(segment
		(start 347.49994 -213.12251)
		(end 347.49994 -212.007704)
		(width 0.14732)
		(layer "In15.Cu")
		(net "P5E_CPU0_PE0_TX_DN<12>")
	)
	(segment
		(start 332.623414 -206.216758)
		(end 323.179694 -216.158064)
		(width 0.14732)
		(layer "In15.Cu")
		(net "P5E_CPU0_PE0_TX_DN<12>")
	)
	(segment
		(start 347.49994 -212.007704)
		(end 346.78747 -210.287616)
		(width 0.14732)
		(layer "In15.Cu")
		(net "P5E_CPU0_PE0_TX_DN<12>")
	)
	(segment
		(start 347.927676 -214.644732)
		(end 347.927676 -214.582248)
		(width 0.0889)
		(layer "In15.Cu")
		(net "P5E_CPU0_PE0_TX_DN<12>")
	)
	(segment
		(start 347.651578 -215.764618)
		(end 347.648276 -215.762586)
		(width 0.0889)
		(layer "In15.Cu")
		(net "P5E_CPU0_PE0_TX_DN<12>")
	)
	(segment
		(start 348.39783 -221.94774)
		(end 348.39783 -221.932246)
		(width 0.0889)
		(layer "In15.Cu")
		(net "P5E_CPU0_PE0_TX_DN<12>")
	)
	(segment
		(start 320.707258 -220.923358)
		(end 318.908938 -232.559352)
		(width 0.14732)
		(layer "In15.Cu")
		(net "P5E_CPU0_PE0_TX_DN<12>")
	)
	(segment
		(start 305.749198 -341.735918)
		(end 310.801512 -364.466378)
		(width 0.14732)
		(layer "In15.Cu")
		(net "P5E_CPU0_PE0_TX_DN<12>")
	)
	(segment
		(start 349.055436 -223.085914)
		(end 349.046546 -223.080834)
		(width 0.0889)
		(layer "In15.Cu")
		(net "P5E_CPU0_PE0_TX_DN<12>")
	)
	(segment
		(start 314.37961 -321.151504)
		(end 311.90946 -323.621908)
		(width 0.14732)
		(layer "In15.Cu")
		(net "P5E_CPU0_PE0_TX_DN<12>")
	)
	(segment
		(start 335.522316 -203.52639)
		(end 332.623414 -206.216758)
		(width 0.14732)
		(layer "In15.Cu")
		(net "P5E_CPU0_PE0_TX_DN<12>")
	)
	(arc
		(start 348.115636 -217.554048)
		(mid 348.39825 -217.06793)
		(end 348.121732 -216.578434)
		(width 0.0889)
		(layer "In15.Cu")
		(net "P5E_CPU0_PE0_TX_DN<12>")
	)
	(arc
		(start 348.106746 -221.453202)
		(mid 347.978427 -221.32123)
		(end 347.928438 -221.144084)
		(width 0.0889)
		(layer "In15.Cu")
		(net "P5E_CPU0_PE0_TX_DN<12>")
	)
	(arc
		(start 348.106746 -219.825316)
		(mid 347.92827 -219.506038)
		(end 348.106746 -219.18676)
		(width 0.0889)
		(layer "In15.Cu")
		(net "P5E_CPU0_PE0_TX_DN<12>")
	)
	(arc
		(start 347.636592 -215.755982)
		(mid 347.505678 -215.619622)
		(end 347.45803 -215.436704)
		(width 0.0889)
		(layer "In15.Cu")
		(net "P5E_CPU0_PE0_TX_DN<12>")
	)
	(arc
		(start 349.337884 -223.557084)
		(mid 349.257722 -223.284895)
		(end 349.055436 -223.085914)
		(width 0.0889)
		(layer "In15.Cu")
		(net "P5E_CPU0_PE0_TX_DN<12>")
	)
	(arc
		(start 347.927676 -214.582248)
		(mid 347.849368 -214.296803)
		(end 347.636592 -214.091012)
		(width 0.0889)
		(layer "In15.Cu")
		(net "P5E_CPU0_PE0_TX_DN<12>")
	)
	(arc
		(start 349.046546 -223.080834)
		(mid 348.918653 -222.949772)
		(end 348.868238 -222.773748)
		(width 0.0889)
		(layer "In15.Cu")
		(net "P5E_CPU0_PE0_TX_DN<12>")
	)
	(arc
		(start 347.645482 -215.112346)
		(mid 347.846764 -214.914859)
		(end 347.927676 -214.644732)
		(width 0.0889)
		(layer "In15.Cu")
		(net "P5E_CPU0_PE0_TX_DN<12>")
	)
	(arc
		(start 347.928438 -217.863674)
		(mid 347.979492 -217.689094)
		(end 348.106746 -217.559128)
		(width 0.0889)
		(layer "In15.Cu")
		(net "P5E_CPU0_PE0_TX_DN<12>")
	)
	(arc
		(start 348.115636 -219.18168)
		(mid 348.318459 -218.981449)
		(end 348.39783 -218.707716)
		(width 0.0889)
		(layer "In15.Cu")
		(net "P5E_CPU0_PE0_TX_DN<12>")
	)
	(arc
		(start 348.39783 -221.932246)
		(mid 348.31846 -221.658512)
		(end 348.115636 -221.458282)
		(width 0.0889)
		(layer "In15.Cu")
		(net "P5E_CPU0_PE0_TX_DN<12>")
	)
	(arc
		(start 348.106746 -216.569798)
		(mid 347.975832 -216.433438)
		(end 347.928184 -216.25052)
		(width 0.0889)
		(layer "In15.Cu")
		(net "P5E_CPU0_PE0_TX_DN<12>")
	)
	(arc
		(start 348.115636 -220.809566)
		(mid 348.39825 -220.323448)
		(end 348.121732 -219.833952)
		(width 0.0889)
		(layer "In15.Cu")
		(net "P5E_CPU0_PE0_TX_DN<12>")
	)
	(arc
		(start 347.928184 -216.25052)
		(mid 347.854193 -215.970954)
		(end 347.651578 -215.764618)
		(width 0.0889)
		(layer "In15.Cu")
		(net "P5E_CPU0_PE0_TX_DN<12>")
	)
	(arc
		(start 347.463364 -213.905338)
		(mid 347.459381 -213.893436)
		(end 347.45803 -213.880954)
		(width 0.0889)
		(layer "In15.Cu")
		(net "P5E_CPU0_PE0_TX_DN<12>")
	)
	(arc
		(start 349.477838 -223.867472)
		(mid 349.376517 -223.741351)
		(end 349.337884 -223.584262)
		(width 0.0889)
		(layer "In15.Cu")
		(net "P5E_CPU0_PE0_TX_DN<12>")
	)
	(arc
		(start 347.636592 -214.091012)
		(mid 347.535159 -214.011995)
		(end 347.463364 -213.905338)
		(width 0.0889)
		(layer "In15.Cu")
		(net "P5E_CPU0_PE0_TX_DN<12>")
	)
	(arc
		(start 347.928692 -221.119192)
		(mid 347.979602 -220.944623)
		(end 348.106746 -220.814646)
		(width 0.0889)
		(layer "In15.Cu")
		(net "P5E_CPU0_PE0_TX_DN<12>")
	)
	(arc
		(start 348.576392 -222.267018)
		(mid 348.445478 -222.130658)
		(end 348.39783 -221.94774)
		(width 0.0889)
		(layer "In15.Cu")
		(net "P5E_CPU0_PE0_TX_DN<12>")
	)
	(arc
		(start 348.106746 -218.197684)
		(mid 347.978342 -218.065739)
		(end 347.928184 -217.888566)
		(width 0.0889)
		(layer "In15.Cu")
		(net "P5E_CPU0_PE0_TX_DN<12>")
	)
	(arc
		(start 348.39783 -218.676728)
		(mid 348.31846 -218.402994)
		(end 348.115636 -218.202764)
		(width 0.0889)
		(layer "In15.Cu")
		(net "P5E_CPU0_PE0_TX_DN<12>")
	)
	(arc
		(start 348.867984 -222.761556)
		(mid 348.793993 -222.48199)
		(end 348.591378 -222.275654)
		(width 0.0889)
		(layer "In15.Cu")
		(net "P5E_CPU0_PE0_TX_DN<12>")
	)
	(arc
		(start 347.458284 -215.421972)
		(mid 347.509338 -215.247392)
		(end 347.636592 -215.117426)
		(width 0.0889)
		(layer "In15.Cu")
		(net "P5E_CPU0_PE0_TX_DN<12>")
	)
	(arc
		(start 347.45803 -215.436704)
		(mid 347.458082 -215.429337)
		(end 347.458284 -215.421972)
		(width 0.0889)
		(layer "In15.Cu")
		(net "P5E_CPU0_PE0_TX_DN<12>")
	)
	(arc
		(start 347.928438 -221.144084)
		(mid 347.928358 -221.131636)
		(end 347.928692 -221.119192)
		(width 0.0889)
		(layer "In15.Cu")
		(net "P5E_CPU0_PE0_TX_DN<12>")
	)
	(arc
		(start 348.868238 -222.773748)
		(mid 348.868071 -222.762572)
		(end 348.868238 -222.751396)
		(width 0.0889)
		(layer "In15.Cu")
		(net "P5E_CPU0_PE0_TX_DN<12>")
	)
	(arc
		(start 347.928184 -217.888566)
		(mid 347.928104 -217.876118)
		(end 347.928438 -217.863674)
		(width 0.0889)
		(layer "In15.Cu")
		(net "P5E_CPU0_PE0_TX_DN<12>")
	)
	(segment
		(start 348.30258 -224.925382)
		(end 348.30258 -224.389696)
		(width 0.13208)
		(layer "F.Cu")
		(net "P5E_CPU0_PE0_TX_DN<11>")
	)
	(segment
		(start 348.30258 -224.389696)
		(end 348.302834 -224.389442)
		(width 0.13208)
		(layer "F.Cu")
		(net "P5E_CPU0_PE0_TX_DN<11>")
	)
	(segment
		(start 317.55842 -408.250644)
		(end 317.553848 -408.250644)
		(width 0.13208)
		(layer "F.Cu")
		(net "P5E_CPU0_PE0_TX_DN<11>")
	)
	(segment
		(start 317.88481 -407.310082)
		(end 317.88481 -407.924254)
		(width 0.13208)
		(layer "F.Cu")
		(net "P5E_CPU0_PE0_TX_DN<11>")
	)
	(segment
		(start 317.88481 -407.924254)
		(end 317.55842 -408.250644)
		(width 0.13208)
		(layer "F.Cu")
		(net "P5E_CPU0_PE0_TX_DN<11>")
	)
	(segment
		(start 317.579248 -407.00452)
		(end 317.88481 -407.310082)
		(width 0.13208)
		(layer "F.Cu")
		(net "P5E_CPU0_PE0_TX_DN<11>")
	)
	(segment
		(start 346.708476 -215.762586)
		(end 346.705682 -215.761062)
		(width 0.0889)
		(layer "In15.Cu")
		(net "P5E_CPU0_PE0_TX_DN<11>")
	)
	(segment
		(start 346.56014 -213.144608)
		(end 346.56014 -213.12251)
		(width 0.0889)
		(layer "In15.Cu")
		(net "P5E_CPU0_PE0_TX_DN<11>")
	)
	(segment
		(start 347.175836 -218.202764)
		(end 347.166946 -218.197684)
		(width 0.0889)
		(layer "In15.Cu")
		(net "P5E_CPU0_PE0_TX_DN<11>")
	)
	(segment
		(start 342.480646 -208.684368)
		(end 334.147668 -208.684368)
		(width 0.14732)
		(layer "In15.Cu")
		(net "P5E_CPU0_PE0_TX_DN<11>")
	)
	(segment
		(start 308.007512 -326.15124)
		(end 308.007512 -329.065636)
		(width 0.14732)
		(layer "In15.Cu")
		(net "P5E_CPU0_PE0_TX_DN<11>")
	)
	(segment
		(start 347.175836 -216.574878)
		(end 347.166946 -216.569798)
		(width 0.0889)
		(layer "In15.Cu")
		(net "P5E_CPU0_PE0_TX_DN<11>")
	)
	(segment
		(start 319.838832 -232.692448)
		(end 318.431164 -250.085352)
		(width 0.14732)
		(layer "In15.Cu")
		(net "P5E_CPU0_PE0_TX_DN<11>")
	)
	(segment
		(start 347.175836 -219.830396)
		(end 347.166946 -219.825316)
		(width 0.0889)
		(layer "In15.Cu")
		(net "P5E_CPU0_PE0_TX_DN<11>")
	)
	(segment
		(start 313.271408 -324.378574)
		(end 312.741818 -324.597776)
		(width 0.14732)
		(layer "In15.Cu")
		(net "P5E_CPU0_PE0_TX_DN<11>")
	)
	(segment
		(start 346.56014 -213.12251)
		(end 346.56014 -212.22589)
		(width 0.14732)
		(layer "In15.Cu")
		(net "P5E_CPU0_PE0_TX_DN<11>")
	)
	(segment
		(start 311.754774 -364.344966)
		(end 318.059308 -399.910808)
		(width 0.14732)
		(layer "In15.Cu")
		(net "P5E_CPU0_PE0_TX_DN<11>")
	)
	(segment
		(start 347.166946 -219.18676)
		(end 347.175836 -219.18168)
		(width 0.0889)
		(layer "In15.Cu")
		(net "P5E_CPU0_PE0_TX_DN<11>")
	)
	(segment
		(start 347.166946 -217.559128)
		(end 347.175836 -217.554048)
		(width 0.0889)
		(layer "In15.Cu")
		(net "P5E_CPU0_PE0_TX_DN<11>")
	)
	(segment
		(start 308.007512 -329.065636)
		(end 306.702714 -330.370434)
		(width 0.14732)
		(layer "In15.Cu")
		(net "P5E_CPU0_PE0_TX_DN<11>")
	)
	(segment
		(start 345.98991 -210.849464)
		(end 344.775028 -209.634582)
		(width 0.14732)
		(layer "In15.Cu")
		(net "P5E_CPU0_PE0_TX_DN<11>")
	)
	(segment
		(start 346.711778 -215.764618)
		(end 346.708476 -215.762586)
		(width 0.0889)
		(layer "In15.Cu")
		(net "P5E_CPU0_PE0_TX_DN<11>")
	)
	(segment
		(start 346.705682 -215.761062)
		(end 346.704158 -215.7603)
		(width 0.0889)
		(layer "In15.Cu")
		(net "P5E_CPU0_PE0_TX_DN<11>")
	)
	(segment
		(start 334.147668 -208.684368)
		(end 329.916028 -210.982052)
		(width 0.14732)
		(layer "In15.Cu")
		(net "P5E_CPU0_PE0_TX_DN<11>")
	)
	(segment
		(start 346.696792 -215.117426)
		(end 346.705682 -215.112346)
		(width 0.0889)
		(layer "In15.Cu")
		(net "P5E_CPU0_PE0_TX_DN<11>")
	)
	(segment
		(start 318.6176 -316.896496)
		(end 313.63031 -324.019672)
		(width 0.14732)
		(layer "In15.Cu")
		(net "P5E_CPU0_PE0_TX_DN<11>")
	)
	(segment
		(start 348.115636 -224.7138)
		(end 348.106746 -224.70872)
		(width 0.0889)
		(layer "In15.Cu")
		(net "P5E_CPU0_PE0_TX_DN<11>")
	)
	(segment
		(start 346.51823 -213.186518)
		(end 346.56014 -213.144608)
		(width 0.0889)
		(layer "In15.Cu")
		(net "P5E_CPU0_PE0_TX_DN<11>")
	)
	(segment
		(start 318.32169 -253.334774)
		(end 321.887088 -309.014114)
		(width 0.14732)
		(layer "In15.Cu")
		(net "P5E_CPU0_PE0_TX_DN<11>")
	)
	(segment
		(start 348.302834 -224.389442)
		(end 348.459298 -224.66046)
		(width 0.0889)
		(layer "In15.Cu")
		(net "P5E_CPU0_PE0_TX_DN<11>")
	)
	(segment
		(start 318.059308 -403.948138)
		(end 317.873888 -405.831548)
		(width 0.14732)
		(layer "In15.Cu")
		(net "P5E_CPU0_PE0_TX_DN<11>")
	)
	(segment
		(start 346.51823 -213.8934)
		(end 346.51823 -213.186518)
		(width 0.0889)
		(layer "In15.Cu")
		(net "P5E_CPU0_PE0_TX_DN<11>")
	)
	(segment
		(start 348.459298 -224.66046)
		(end 348.438216 -224.738438)
		(width 0.0889)
		(layer "In15.Cu")
		(net "P5E_CPU0_PE0_TX_DN<11>")
	)
	(segment
		(start 347.928438 -222.751396)
		(end 347.928184 -222.761556)
		(width 0.0889)
		(layer "In15.Cu")
		(net "P5E_CPU0_PE0_TX_DN<11>")
	)
	(segment
		(start 309.560976 -324.597776)
		(end 308.007512 -326.15124)
		(width 0.14732)
		(layer "In15.Cu")
		(net "P5E_CPU0_PE0_TX_DN<11>")
	)
	(segment
		(start 348.11462 -223.085406)
		(end 348.106746 -223.080834)
		(width 0.0889)
		(layer "In15.Cu")
		(net "P5E_CPU0_PE0_TX_DN<11>")
	)
	(segment
		(start 321.602608 -221.28099)
		(end 319.838832 -232.692448)
		(width 0.14732)
		(layer "In15.Cu")
		(net "P5E_CPU0_PE0_TX_DN<11>")
	)
	(segment
		(start 348.115636 -223.085914)
		(end 348.11462 -223.085406)
		(width 0.0889)
		(layer "In15.Cu")
		(net "P5E_CPU0_PE0_TX_DN<11>")
	)
	(segment
		(start 312.741818 -324.597776)
		(end 309.560976 -324.597776)
		(width 0.14732)
		(layer "In15.Cu")
		(net "P5E_CPU0_PE0_TX_DN<11>")
	)
	(segment
		(start 347.645482 -222.272098)
		(end 347.636592 -222.267018)
		(width 0.0889)
		(layer "In15.Cu")
		(net "P5E_CPU0_PE0_TX_DN<11>")
	)
	(segment
		(start 323.993256 -216.67216)
		(end 323.395594 -217.824558)
		(width 0.14732)
		(layer "In15.Cu")
		(net "P5E_CPU0_PE0_TX_DN<11>")
	)
	(segment
		(start 347.175836 -221.458282)
		(end 347.166946 -221.453202)
		(width 0.0889)
		(layer "In15.Cu")
		(net "P5E_CPU0_PE0_TX_DN<11>")
	)
	(segment
		(start 321.887088 -309.014114)
		(end 318.6176 -316.896496)
		(width 0.14732)
		(layer "In15.Cu")
		(net "P5E_CPU0_PE0_TX_DN<11>")
	)
	(segment
		(start 347.45803 -218.707716)
		(end 347.45803 -218.676728)
		(width 0.0889)
		(layer "In15.Cu")
		(net "P5E_CPU0_PE0_TX_DN<11>")
	)
	(segment
		(start 346.987876 -214.644732)
		(end 346.987876 -214.424768)
		(width 0.0889)
		(layer "In15.Cu")
		(net "P5E_CPU0_PE0_TX_DN<11>")
	)
	(segment
		(start 318.322198 -253.321566)
		(end 318.32169 -253.322074)
		(width 0.14732)
		(layer "In15.Cu")
		(net "P5E_CPU0_PE0_TX_DN<11>")
	)
	(segment
		(start 347.166946 -220.814646)
		(end 347.175836 -220.809566)
		(width 0.0889)
		(layer "In15.Cu")
		(net "P5E_CPU0_PE0_TX_DN<11>")
	)
	(segment
		(start 347.45803 -221.94774)
		(end 347.45803 -221.932246)
		(width 0.0889)
		(layer "In15.Cu")
		(net "P5E_CPU0_PE0_TX_DN<11>")
	)
	(segment
		(start 346.518484 -213.893908)
		(end 346.51823 -213.8934)
		(width 0.0889)
		(layer "In15.Cu")
		(net "P5E_CPU0_PE0_TX_DN<11>")
	)
	(segment
		(start 347.651578 -222.275654)
		(end 347.645482 -222.272098)
		(width 0.0889)
		(layer "In15.Cu")
		(net "P5E_CPU0_PE0_TX_DN<11>")
	)
	(segment
		(start 317.873888 -406.70988)
		(end 317.579248 -407.00452)
		(width 0.14732)
		(layer "In15.Cu")
		(net "P5E_CPU0_PE0_TX_DN<11>")
	)
	(segment
		(start 306.702714 -341.631016)
		(end 311.754774 -364.344966)
		(width 0.14732)
		(layer "In15.Cu")
		(net "P5E_CPU0_PE0_TX_DN<11>")
	)
	(segment
		(start 318.059308 -399.910808)
		(end 318.059308 -403.948138)
		(width 0.14732)
		(layer "In15.Cu")
		(net "P5E_CPU0_PE0_TX_DN<11>")
	)
	(segment
		(start 347.458284 -217.082878)
		(end 347.458284 -217.05443)
		(width 0.0889)
		(layer "In15.Cu")
		(net "P5E_CPU0_PE0_TX_DN<11>")
	)
	(segment
		(start 347.458284 -220.338396)
		(end 347.458284 -220.309948)
		(width 0.0889)
		(layer "In15.Cu")
		(net "P5E_CPU0_PE0_TX_DN<11>")
	)
	(segment
		(start 346.56014 -212.22589)
		(end 345.98991 -210.849464)
		(width 0.14732)
		(layer "In15.Cu")
		(net "P5E_CPU0_PE0_TX_DN<11>")
	)
	(segment
		(start 344.775028 -209.634582)
		(end 342.480646 -208.684368)
		(width 0.14732)
		(layer "In15.Cu")
		(net "P5E_CPU0_PE0_TX_DN<11>")
	)
	(segment
		(start 306.702714 -330.370434)
		(end 306.702714 -341.631016)
		(width 0.14732)
		(layer "In15.Cu")
		(net "P5E_CPU0_PE0_TX_DN<11>")
	)
	(segment
		(start 318.32169 -253.322074)
		(end 318.32169 -253.334774)
		(width 0.14732)
		(layer "In15.Cu")
		(net "P5E_CPU0_PE0_TX_DN<11>")
	)
	(segment
		(start 323.395594 -217.824558)
		(end 321.602608 -221.28099)
		(width 0.14732)
		(layer "In15.Cu")
		(net "P5E_CPU0_PE0_TX_DN<11>")
	)
	(segment
		(start 348.398084 -223.575626)
		(end 348.398084 -223.561402)
		(width 0.0889)
		(layer "In15.Cu")
		(net "P5E_CPU0_PE0_TX_DN<11>")
	)
	(segment
		(start 313.63031 -324.019672)
		(end 313.271408 -324.378574)
		(width 0.14732)
		(layer "In15.Cu")
		(net "P5E_CPU0_PE0_TX_DN<11>")
	)
	(segment
		(start 348.106746 -224.070164)
		(end 348.115636 -224.065084)
		(width 0.0889)
		(layer "In15.Cu")
		(net "P5E_CPU0_PE0_TX_DN<11>")
	)
	(segment
		(start 318.431164 -250.085352)
		(end 318.322198 -253.321566)
		(width 0.14732)
		(layer "In15.Cu")
		(net "P5E_CPU0_PE0_TX_DN<11>")
	)
	(segment
		(start 346.704158 -215.7603)
		(end 346.696792 -215.755982)
		(width 0.0889)
		(layer "In15.Cu")
		(net "P5E_CPU0_PE0_TX_DN<11>")
	)
	(segment
		(start 348.115636 -224.065084)
		(end 348.121732 -224.061528)
		(width 0.0889)
		(layer "In15.Cu")
		(net "P5E_CPU0_PE0_TX_DN<11>")
	)
	(segment
		(start 329.916028 -210.982052)
		(end 323.993256 -216.67216)
		(width 0.14732)
		(layer "In15.Cu")
		(net "P5E_CPU0_PE0_TX_DN<11>")
	)
	(segment
		(start 317.873888 -405.831548)
		(end 317.873888 -406.70988)
		(width 0.14732)
		(layer "In15.Cu")
		(net "P5E_CPU0_PE0_TX_DN<11>")
	)
	(arc
		(start 348.121732 -224.061528)
		(mid 348.324145 -223.855115)
		(end 348.398084 -223.575626)
		(width 0.0889)
		(layer "In15.Cu")
		(net "P5E_CPU0_PE0_TX_DN<11>")
	)
	(arc
		(start 346.988638 -217.888566)
		(mid 346.988471 -217.87739)
		(end 346.988638 -217.866214)
		(width 0.0889)
		(layer "In15.Cu")
		(net "P5E_CPU0_PE0_TX_DN<11>")
	)
	(arc
		(start 347.928692 -222.776288)
		(mid 347.928359 -222.763844)
		(end 347.928438 -222.751396)
		(width 0.0889)
		(layer "In15.Cu")
		(net "P5E_CPU0_PE0_TX_DN<11>")
	)
	(arc
		(start 347.166946 -221.453202)
		(mid 347.038627 -221.32123)
		(end 346.988638 -221.144084)
		(width 0.0889)
		(layer "In15.Cu")
		(net "P5E_CPU0_PE0_TX_DN<11>")
	)
	(arc
		(start 347.166946 -219.825316)
		(mid 347.037834 -219.691781)
		(end 346.988638 -219.512642)
		(width 0.0889)
		(layer "In15.Cu")
		(net "P5E_CPU0_PE0_TX_DN<11>")
	)
	(arc
		(start 346.988638 -221.144084)
		(mid 346.988471 -221.132908)
		(end 346.988638 -221.121732)
		(width 0.0889)
		(layer "In15.Cu")
		(net "P5E_CPU0_PE0_TX_DN<11>")
	)
	(arc
		(start 348.106746 -223.080834)
		(mid 347.979666 -222.95082)
		(end 347.928692 -222.776288)
		(width 0.0889)
		(layer "In15.Cu")
		(net "P5E_CPU0_PE0_TX_DN<11>")
	)
	(arc
		(start 348.106746 -224.70872)
		(mid 347.92827 -224.389442)
		(end 348.106746 -224.070164)
		(width 0.0889)
		(layer "In15.Cu")
		(net "P5E_CPU0_PE0_TX_DN<11>")
	)
	(arc
		(start 346.988638 -219.512642)
		(mid 346.988544 -219.50426)
		(end 346.988638 -219.495878)
		(width 0.0889)
		(layer "In15.Cu")
		(net "P5E_CPU0_PE0_TX_DN<11>")
	)
	(arc
		(start 347.45803 -218.676728)
		(mid 347.37866 -218.402994)
		(end 347.175836 -218.202764)
		(width 0.0889)
		(layer "In15.Cu")
		(net "P5E_CPU0_PE0_TX_DN<11>")
	)
	(arc
		(start 346.988384 -216.25052)
		(mid 346.914393 -215.970954)
		(end 346.711778 -215.764618)
		(width 0.0889)
		(layer "In15.Cu")
		(net "P5E_CPU0_PE0_TX_DN<11>")
	)
	(arc
		(start 346.696792 -215.755982)
		(mid 346.565878 -215.619622)
		(end 346.51823 -215.436704)
		(width 0.0889)
		(layer "In15.Cu")
		(net "P5E_CPU0_PE0_TX_DN<11>")
	)
	(arc
		(start 347.175836 -217.554048)
		(mid 347.378122 -217.355067)
		(end 347.458284 -217.082878)
		(width 0.0889)
		(layer "In15.Cu")
		(net "P5E_CPU0_PE0_TX_DN<11>")
	)
	(arc
		(start 346.518484 -215.421972)
		(mid 346.569538 -215.247392)
		(end 346.696792 -215.117426)
		(width 0.0889)
		(layer "In15.Cu")
		(net "P5E_CPU0_PE0_TX_DN<11>")
	)
	(arc
		(start 347.636592 -222.267018)
		(mid 347.505678 -222.130658)
		(end 347.45803 -221.94774)
		(width 0.0889)
		(layer "In15.Cu")
		(net "P5E_CPU0_PE0_TX_DN<11>")
	)
	(arc
		(start 347.166946 -218.197684)
		(mid 347.038627 -218.065712)
		(end 346.988638 -217.888566)
		(width 0.0889)
		(layer "In15.Cu")
		(net "P5E_CPU0_PE0_TX_DN<11>")
	)
	(arc
		(start 346.988638 -217.866214)
		(mid 347.039131 -217.690236)
		(end 347.166946 -217.559128)
		(width 0.0889)
		(layer "In15.Cu")
		(net "P5E_CPU0_PE0_TX_DN<11>")
	)
	(arc
		(start 347.458284 -217.05443)
		(mid 347.380173 -216.777481)
		(end 347.175836 -216.574878)
		(width 0.0889)
		(layer "In15.Cu")
		(net "P5E_CPU0_PE0_TX_DN<11>")
	)
	(arc
		(start 348.438216 -224.738438)
		(mid 348.27412 -224.762785)
		(end 348.115636 -224.7138)
		(width 0.0889)
		(layer "In15.Cu")
		(net "P5E_CPU0_PE0_TX_DN<11>")
	)
	(arc
		(start 346.987876 -214.424768)
		(mid 346.876597 -214.232062)
		(end 346.702634 -214.093298)
		(width 0.0889)
		(layer "In15.Cu")
		(net "P5E_CPU0_PE0_TX_DN<11>")
	)
	(arc
		(start 347.166946 -216.569798)
		(mid 347.036032 -216.433438)
		(end 346.988384 -216.25052)
		(width 0.0889)
		(layer "In15.Cu")
		(net "P5E_CPU0_PE0_TX_DN<11>")
	)
	(arc
		(start 346.51823 -215.436704)
		(mid 346.518282 -215.429337)
		(end 346.518484 -215.421972)
		(width 0.0889)
		(layer "In15.Cu")
		(net "P5E_CPU0_PE0_TX_DN<11>")
	)
	(arc
		(start 347.175836 -219.18168)
		(mid 347.378659 -218.981449)
		(end 347.45803 -218.707716)
		(width 0.0889)
		(layer "In15.Cu")
		(net "P5E_CPU0_PE0_TX_DN<11>")
	)
	(arc
		(start 346.705682 -215.112346)
		(mid 346.906964 -214.914859)
		(end 346.987876 -214.644732)
		(width 0.0889)
		(layer "In15.Cu")
		(net "P5E_CPU0_PE0_TX_DN<11>")
	)
	(arc
		(start 347.458284 -220.309948)
		(mid 347.380173 -220.032999)
		(end 347.175836 -219.830396)
		(width 0.0889)
		(layer "In15.Cu")
		(net "P5E_CPU0_PE0_TX_DN<11>")
	)
	(arc
		(start 347.45803 -221.932246)
		(mid 347.37866 -221.658512)
		(end 347.175836 -221.458282)
		(width 0.0889)
		(layer "In15.Cu")
		(net "P5E_CPU0_PE0_TX_DN<11>")
	)
	(arc
		(start 347.175836 -220.809566)
		(mid 347.378122 -220.610585)
		(end 347.458284 -220.338396)
		(width 0.0889)
		(layer "In15.Cu")
		(net "P5E_CPU0_PE0_TX_DN<11>")
	)
	(arc
		(start 348.398084 -223.561402)
		(mid 348.318943 -223.286779)
		(end 348.115636 -223.085914)
		(width 0.0889)
		(layer "In15.Cu")
		(net "P5E_CPU0_PE0_TX_DN<11>")
	)
	(arc
		(start 346.988638 -221.121732)
		(mid 347.039131 -220.945754)
		(end 347.166946 -220.814646)
		(width 0.0889)
		(layer "In15.Cu")
		(net "P5E_CPU0_PE0_TX_DN<11>")
	)
	(arc
		(start 346.988638 -219.495878)
		(mid 347.038653 -219.318747)
		(end 347.166946 -219.18676)
		(width 0.0889)
		(layer "In15.Cu")
		(net "P5E_CPU0_PE0_TX_DN<11>")
	)
	(arc
		(start 347.928184 -222.761556)
		(mid 347.854193 -222.48199)
		(end 347.651578 -222.275654)
		(width 0.0889)
		(layer "In15.Cu")
		(net "P5E_CPU0_PE0_TX_DN<11>")
	)
	(arc
		(start 346.702634 -214.093298)
		(mid 346.593487 -214.00937)
		(end 346.518484 -213.893908)
		(width 0.0889)
		(layer "In15.Cu")
		(net "P5E_CPU0_PE0_TX_DN<11>")
	)
	(segment
		(start 320.94805 -407.310082)
		(end 320.94805 -407.924254)
		(width 0.13208)
		(layer "F.Cu")
		(net "P5E_CPU0_PE0_TX_DN<10>")
	)
	(segment
		(start 347.832934 -224.111566)
		(end 347.832934 -223.57588)
		(width 0.13208)
		(layer "F.Cu")
		(net "P5E_CPU0_PE0_TX_DN<10>")
	)
	(segment
		(start 320.642488 -407.00452)
		(end 320.94805 -407.310082)
		(width 0.13208)
		(layer "F.Cu")
		(net "P5E_CPU0_PE0_TX_DN<10>")
	)
	(segment
		(start 347.832934 -223.57588)
		(end 347.83268 -223.575626)
		(width 0.13208)
		(layer "F.Cu")
		(net "P5E_CPU0_PE0_TX_DN<10>")
	)
	(segment
		(start 320.94805 -407.924254)
		(end 320.62166 -408.250644)
		(width 0.13208)
		(layer "F.Cu")
		(net "P5E_CPU0_PE0_TX_DN<10>")
	)
	(segment
		(start 320.62166 -408.250644)
		(end 320.617088 -408.250644)
		(width 0.13208)
		(layer "F.Cu")
		(net "P5E_CPU0_PE0_TX_DN<10>")
	)
	(segment
		(start 345.760294 -215.75776)
		(end 345.758262 -215.756744)
		(width 0.0889)
		(layer "In15.Cu")
		(net "P5E_CPU0_PE0_TX_DN<10>")
	)
	(segment
		(start 346.704158 -222.271336)
		(end 346.696792 -222.267018)
		(width 0.0889)
		(layer "In15.Cu")
		(net "P5E_CPU0_PE0_TX_DN<10>")
	)
	(segment
		(start 320.783966 -232.831386)
		(end 319.365122 -250.12904)
		(width 0.14732)
		(layer "In15.Cu")
		(net "P5E_CPU0_PE0_TX_DN<10>")
	)
	(segment
		(start 313.766708 -325.237094)
		(end 313.253628 -325.449692)
		(width 0.14732)
		(layer "In15.Cu")
		(net "P5E_CPU0_PE0_TX_DN<10>")
	)
	(segment
		(start 320.937128 -405.831548)
		(end 320.937128 -406.70988)
		(width 0.14732)
		(layer "In15.Cu")
		(net "P5E_CPU0_PE0_TX_DN<10>")
	)
	(segment
		(start 345.620594 -212.510624)
		(end 345.185492 -211.460334)
		(width 0.14732)
		(layer "In15.Cu")
		(net "P5E_CPU0_PE0_TX_DN<10>")
	)
	(segment
		(start 345.76258 -215.75903)
		(end 345.761564 -215.758522)
		(width 0.0889)
		(layer "In15.Cu")
		(net "P5E_CPU0_PE0_TX_DN<10>")
	)
	(segment
		(start 345.765882 -215.761062)
		(end 345.76512 -215.760554)
		(width 0.0889)
		(layer "In15.Cu")
		(net "P5E_CPU0_PE0_TX_DN<10>")
	)
	(segment
		(start 320.785236 -232.821734)
		(end 320.783966 -232.831386)
		(width 0.14732)
		(layer "In15.Cu")
		(net "P5E_CPU0_PE0_TX_DN<10>")
	)
	(segment
		(start 346.518484 -217.07856)
		(end 346.518484 -217.064336)
		(width 0.0889)
		(layer "In15.Cu")
		(net "P5E_CPU0_PE0_TX_DN<10>")
	)
	(segment
		(start 323.643244 -219.44584)
		(end 322.525136 -221.615508)
		(width 0.14732)
		(layer "In15.Cu")
		(net "P5E_CPU0_PE0_TX_DN<10>")
	)
	(segment
		(start 322.87337 -309.368444)
		(end 319.696338 -316.995048)
		(width 0.14732)
		(layer "In15.Cu")
		(net "P5E_CPU0_PE0_TX_DN<10>")
	)
	(segment
		(start 345.756992 -215.117426)
		(end 345.764866 -215.112854)
		(width 0.0889)
		(layer "In15.Cu")
		(net "P5E_CPU0_PE0_TX_DN<10>")
	)
	(segment
		(start 346.988638 -222.751396)
		(end 346.988384 -222.761556)
		(width 0.0889)
		(layer "In15.Cu")
		(net "P5E_CPU0_PE0_TX_DN<10>")
	)
	(segment
		(start 312.740802 -325.662036)
		(end 309.840122 -325.662036)
		(width 0.14732)
		(layer "In15.Cu")
		(net "P5E_CPU0_PE0_TX_DN<10>")
	)
	(segment
		(start 308.953408 -329.53833)
		(end 307.632354 -330.859384)
		(width 0.14732)
		(layer "In15.Cu")
		(net "P5E_CPU0_PE0_TX_DN<10>")
	)
	(segment
		(start 320.937128 -406.70988)
		(end 320.642488 -407.00452)
		(width 0.14732)
		(layer "In15.Cu")
		(net "P5E_CPU0_PE0_TX_DN<10>")
	)
	(segment
		(start 345.764866 -215.112854)
		(end 345.765882 -215.112346)
		(width 0.0889)
		(layer "In15.Cu")
		(net "P5E_CPU0_PE0_TX_DN<10>")
	)
	(segment
		(start 314.298076 -324.705726)
		(end 313.766708 -325.237094)
		(width 0.14732)
		(layer "In15.Cu")
		(net "P5E_CPU0_PE0_TX_DN<10>")
	)
	(segment
		(start 345.620594 -213.12251)
		(end 345.620594 -212.510624)
		(width 0.14732)
		(layer "In15.Cu")
		(net "P5E_CPU0_PE0_TX_DN<10>")
	)
	(segment
		(start 323.643244 -219.445586)
		(end 323.643244 -219.44584)
		(width 0.14732)
		(layer "In15.Cu")
		(net "P5E_CPU0_PE0_TX_DN<10>")
	)
	(segment
		(start 346.711778 -222.275654)
		(end 346.708476 -222.273622)
		(width 0.0889)
		(layer "In15.Cu")
		(net "P5E_CPU0_PE0_TX_DN<10>")
	)
	(segment
		(start 334.409542 -209.671158)
		(end 330.609194 -211.729574)
		(width 0.14732)
		(layer "In15.Cu")
		(net "P5E_CPU0_PE0_TX_DN<10>")
	)
	(segment
		(start 307.632354 -341.49411)
		(end 312.693558 -364.258606)
		(width 0.14732)
		(layer "In15.Cu")
		(net "P5E_CPU0_PE0_TX_DN<10>")
	)
	(segment
		(start 346.51823 -221.94774)
		(end 346.51823 -221.932246)
		(width 0.0889)
		(layer "In15.Cu")
		(net "P5E_CPU0_PE0_TX_DN<10>")
	)
	(segment
		(start 347.458284 -223.584262)
		(end 347.458284 -223.557084)
		(width 0.0889)
		(layer "In15.Cu")
		(net "P5E_CPU0_PE0_TX_DN<10>")
	)
	(segment
		(start 346.236036 -216.574878)
		(end 346.227146 -216.569798)
		(width 0.0889)
		(layer "In15.Cu")
		(net "P5E_CPU0_PE0_TX_DN<10>")
	)
	(segment
		(start 313.253628 -325.449692)
		(end 312.740802 -325.662036)
		(width 0.14732)
		(layer "In15.Cu")
		(net "P5E_CPU0_PE0_TX_DN<10>")
	)
	(segment
		(start 319.281556 -252.607318)
		(end 322.87337 -309.368444)
		(width 0.14732)
		(layer "In15.Cu")
		(net "P5E_CPU0_PE0_TX_DN<10>")
	)
	(segment
		(start 347.175836 -223.085914)
		(end 347.166946 -223.080834)
		(width 0.0889)
		(layer "In15.Cu")
		(net "P5E_CPU0_PE0_TX_DN<10>")
	)
	(segment
		(start 346.242132 -219.833952)
		(end 346.236036 -219.830396)
		(width 0.0889)
		(layer "In15.Cu")
		(net "P5E_CPU0_PE0_TX_DN<10>")
	)
	(segment
		(start 345.185492 -211.460334)
		(end 344.293444 -210.568286)
		(width 0.14732)
		(layer "In15.Cu")
		(net "P5E_CPU0_PE0_TX_DN<10>")
	)
	(segment
		(start 345.620594 -213.144608)
		(end 345.620594 -213.12251)
		(width 0.0889)
		(layer "In15.Cu")
		(net "P5E_CPU0_PE0_TX_DN<10>")
	)
	(segment
		(start 347.676216 -223.846644)
		(end 347.598238 -223.867472)
		(width 0.0889)
		(layer "In15.Cu")
		(net "P5E_CPU0_PE0_TX_DN<10>")
	)
	(segment
		(start 346.227146 -220.814646)
		(end 346.236036 -220.809566)
		(width 0.0889)
		(layer "In15.Cu")
		(net "P5E_CPU0_PE0_TX_DN<10>")
	)
	(segment
		(start 346.227146 -217.559128)
		(end 346.236036 -217.554048)
		(width 0.0889)
		(layer "In15.Cu")
		(net "P5E_CPU0_PE0_TX_DN<10>")
	)
	(segment
		(start 345.578684 -213.186518)
		(end 345.620594 -213.144608)
		(width 0.0889)
		(layer "In15.Cu")
		(net "P5E_CPU0_PE0_TX_DN<10>")
	)
	(segment
		(start 346.705682 -222.272098)
		(end 346.704158 -222.271336)
		(width 0.0889)
		(layer "In15.Cu")
		(net "P5E_CPU0_PE0_TX_DN<10>")
	)
	(segment
		(start 308.953408 -326.54875)
		(end 308.953408 -329.53833)
		(width 0.14732)
		(layer "In15.Cu")
		(net "P5E_CPU0_PE0_TX_DN<10>")
	)
	(segment
		(start 319.696338 -316.995048)
		(end 314.298076 -324.705726)
		(width 0.14732)
		(layer "In15.Cu")
		(net "P5E_CPU0_PE0_TX_DN<10>")
	)
	(segment
		(start 346.236036 -218.202764)
		(end 346.227146 -218.197684)
		(width 0.0889)
		(layer "In15.Cu")
		(net "P5E_CPU0_PE0_TX_DN<10>")
	)
	(segment
		(start 342.127586 -209.671158)
		(end 334.409542 -209.671158)
		(width 0.14732)
		(layer "In15.Cu")
		(net "P5E_CPU0_PE0_TX_DN<10>")
	)
	(segment
		(start 346.242132 -216.578434)
		(end 346.236036 -216.574878)
		(width 0.0889)
		(layer "In15.Cu")
		(net "P5E_CPU0_PE0_TX_DN<10>")
	)
	(segment
		(start 330.609194 -211.729574)
		(end 324.762368 -217.273886)
		(width 0.14732)
		(layer "In15.Cu")
		(net "P5E_CPU0_PE0_TX_DN<10>")
	)
	(segment
		(start 345.76512 -215.760554)
		(end 345.76258 -215.75903)
		(width 0.0889)
		(layer "In15.Cu")
		(net "P5E_CPU0_PE0_TX_DN<10>")
	)
	(segment
		(start 344.293444 -210.568286)
		(end 342.127586 -209.671158)
		(width 0.14732)
		(layer "In15.Cu")
		(net "P5E_CPU0_PE0_TX_DN<10>")
	)
	(segment
		(start 345.578684 -213.893908)
		(end 345.578684 -213.186518)
		(width 0.0889)
		(layer "In15.Cu")
		(net "P5E_CPU0_PE0_TX_DN<10>")
	)
	(segment
		(start 346.518484 -220.334078)
		(end 346.518484 -220.319854)
		(width 0.0889)
		(layer "In15.Cu")
		(net "P5E_CPU0_PE0_TX_DN<10>")
	)
	(segment
		(start 345.761564 -215.758522)
		(end 345.760294 -215.75776)
		(width 0.0889)
		(layer "In15.Cu")
		(net "P5E_CPU0_PE0_TX_DN<10>")
	)
	(segment
		(start 322.525136 -221.615508)
		(end 320.78549 -232.821734)
		(width 0.14732)
		(layer "In15.Cu")
		(net "P5E_CPU0_PE0_TX_DN<10>")
	)
	(segment
		(start 345.768676 -215.762586)
		(end 345.765882 -215.761062)
		(width 0.0889)
		(layer "In15.Cu")
		(net "P5E_CPU0_PE0_TX_DN<10>")
	)
	(segment
		(start 307.632354 -330.859384)
		(end 307.632354 -341.49411)
		(width 0.14732)
		(layer "In15.Cu")
		(net "P5E_CPU0_PE0_TX_DN<10>")
	)
	(segment
		(start 312.693558 -364.258606)
		(end 321.122548 -399.539714)
		(width 0.14732)
		(layer "In15.Cu")
		(net "P5E_CPU0_PE0_TX_DN<10>")
	)
	(segment
		(start 346.51823 -218.707716)
		(end 346.51823 -218.676728)
		(width 0.0889)
		(layer "In15.Cu")
		(net "P5E_CPU0_PE0_TX_DN<10>")
	)
	(segment
		(start 345.771978 -215.764618)
		(end 345.768676 -215.762586)
		(width 0.0889)
		(layer "In15.Cu")
		(net "P5E_CPU0_PE0_TX_DN<10>")
	)
	(segment
		(start 319.365122 -250.12904)
		(end 319.281556 -252.607318)
		(width 0.14732)
		(layer "In15.Cu")
		(net "P5E_CPU0_PE0_TX_DN<10>")
	)
	(segment
		(start 346.236036 -219.830396)
		(end 346.227146 -219.825316)
		(width 0.0889)
		(layer "In15.Cu")
		(net "P5E_CPU0_PE0_TX_DN<10>")
	)
	(segment
		(start 346.236036 -221.458282)
		(end 346.227146 -221.453202)
		(width 0.0889)
		(layer "In15.Cu")
		(net "P5E_CPU0_PE0_TX_DN<10>")
	)
	(segment
		(start 346.708476 -222.273622)
		(end 346.705682 -222.272098)
		(width 0.0889)
		(layer "In15.Cu")
		(net "P5E_CPU0_PE0_TX_DN<10>")
	)
	(segment
		(start 309.840122 -325.662036)
		(end 308.953408 -326.54875)
		(width 0.14732)
		(layer "In15.Cu")
		(net "P5E_CPU0_PE0_TX_DN<10>")
	)
	(segment
		(start 321.122548 -399.539714)
		(end 321.122548 -403.948138)
		(width 0.14732)
		(layer "In15.Cu")
		(net "P5E_CPU0_PE0_TX_DN<10>")
	)
	(segment
		(start 320.78549 -232.821734)
		(end 320.785236 -232.821734)
		(width 0.14732)
		(layer "In15.Cu")
		(net "P5E_CPU0_PE0_TX_DN<10>")
	)
	(segment
		(start 345.758262 -215.756744)
		(end 345.756992 -215.755982)
		(width 0.0889)
		(layer "In15.Cu")
		(net "P5E_CPU0_PE0_TX_DN<10>")
	)
	(segment
		(start 324.762368 -217.273886)
		(end 323.643244 -219.445586)
		(width 0.14732)
		(layer "In15.Cu")
		(net "P5E_CPU0_PE0_TX_DN<10>")
	)
	(segment
		(start 321.122548 -403.948138)
		(end 320.937128 -405.831548)
		(width 0.14732)
		(layer "In15.Cu")
		(net "P5E_CPU0_PE0_TX_DN<10>")
	)
	(segment
		(start 346.048076 -214.644732)
		(end 346.048076 -214.424768)
		(width 0.0889)
		(layer "In15.Cu")
		(net "P5E_CPU0_PE0_TX_DN<10>")
	)
	(segment
		(start 346.23502 -219.182188)
		(end 346.236036 -219.18168)
		(width 0.0889)
		(layer "In15.Cu")
		(net "P5E_CPU0_PE0_TX_DN<10>")
	)
	(segment
		(start 347.83268 -223.575626)
		(end 347.676216 -223.846644)
		(width 0.0889)
		(layer "In15.Cu")
		(net "P5E_CPU0_PE0_TX_DN<10>")
	)
	(segment
		(start 346.227146 -219.18676)
		(end 346.23502 -219.182188)
		(width 0.0889)
		(layer "In15.Cu")
		(net "P5E_CPU0_PE0_TX_DN<10>")
	)
	(arc
		(start 345.756992 -215.755982)
		(mid 345.626078 -215.619622)
		(end 345.57843 -215.436704)
		(width 0.0889)
		(layer "In15.Cu")
		(net "P5E_CPU0_PE0_TX_DN<10>")
	)
	(arc
		(start 347.458284 -223.557084)
		(mid 347.378122 -223.284895)
		(end 347.175836 -223.085914)
		(width 0.0889)
		(layer "In15.Cu")
		(net "P5E_CPU0_PE0_TX_DN<10>")
	)
	(arc
		(start 346.236036 -219.18168)
		(mid 346.438859 -218.981449)
		(end 346.51823 -218.707716)
		(width 0.0889)
		(layer "In15.Cu")
		(net "P5E_CPU0_PE0_TX_DN<10>")
	)
	(arc
		(start 346.048838 -217.863674)
		(mid 346.099892 -217.689094)
		(end 346.227146 -217.559128)
		(width 0.0889)
		(layer "In15.Cu")
		(net "P5E_CPU0_PE0_TX_DN<10>")
	)
	(arc
		(start 345.57843 -215.436704)
		(mid 345.578482 -215.429337)
		(end 345.578684 -215.421972)
		(width 0.0889)
		(layer "In15.Cu")
		(net "P5E_CPU0_PE0_TX_DN<10>")
	)
	(arc
		(start 346.518484 -220.319854)
		(mid 346.444568 -220.040352)
		(end 346.242132 -219.833952)
		(width 0.0889)
		(layer "In15.Cu")
		(net "P5E_CPU0_PE0_TX_DN<10>")
	)
	(arc
		(start 347.166946 -223.080834)
		(mid 347.039053 -222.949772)
		(end 346.988638 -222.773748)
		(width 0.0889)
		(layer "In15.Cu")
		(net "P5E_CPU0_PE0_TX_DN<10>")
	)
	(arc
		(start 346.518484 -217.064336)
		(mid 346.444568 -216.784834)
		(end 346.242132 -216.578434)
		(width 0.0889)
		(layer "In15.Cu")
		(net "P5E_CPU0_PE0_TX_DN<10>")
	)
	(arc
		(start 346.227146 -218.197684)
		(mid 346.098742 -218.065739)
		(end 346.048584 -217.888566)
		(width 0.0889)
		(layer "In15.Cu")
		(net "P5E_CPU0_PE0_TX_DN<10>")
	)
	(arc
		(start 346.51823 -218.676728)
		(mid 346.43886 -218.402994)
		(end 346.236036 -218.202764)
		(width 0.0889)
		(layer "In15.Cu")
		(net "P5E_CPU0_PE0_TX_DN<10>")
	)
	(arc
		(start 346.696792 -222.267018)
		(mid 346.565878 -222.130658)
		(end 346.51823 -221.94774)
		(width 0.0889)
		(layer "In15.Cu")
		(net "P5E_CPU0_PE0_TX_DN<10>")
	)
	(arc
		(start 346.51823 -221.932246)
		(mid 346.43886 -221.658512)
		(end 346.236036 -221.458282)
		(width 0.0889)
		(layer "In15.Cu")
		(net "P5E_CPU0_PE0_TX_DN<10>")
	)
	(arc
		(start 346.227146 -219.825316)
		(mid 346.04867 -219.506038)
		(end 346.227146 -219.18676)
		(width 0.0889)
		(layer "In15.Cu")
		(net "P5E_CPU0_PE0_TX_DN<10>")
	)
	(arc
		(start 346.988384 -222.761556)
		(mid 346.914393 -222.48199)
		(end 346.711778 -222.275654)
		(width 0.0889)
		(layer "In15.Cu")
		(net "P5E_CPU0_PE0_TX_DN<10>")
	)
	(arc
		(start 346.048584 -216.25052)
		(mid 345.974593 -215.970954)
		(end 345.771978 -215.764618)
		(width 0.0889)
		(layer "In15.Cu")
		(net "P5E_CPU0_PE0_TX_DN<10>")
	)
	(arc
		(start 345.762834 -214.093298)
		(mid 345.653687 -214.00937)
		(end 345.578684 -213.893908)
		(width 0.0889)
		(layer "In15.Cu")
		(net "P5E_CPU0_PE0_TX_DN<10>")
	)
	(arc
		(start 346.227146 -216.569798)
		(mid 346.096232 -216.433438)
		(end 346.048584 -216.25052)
		(width 0.0889)
		(layer "In15.Cu")
		(net "P5E_CPU0_PE0_TX_DN<10>")
	)
	(arc
		(start 346.048584 -217.888566)
		(mid 346.048504 -217.876118)
		(end 346.048838 -217.863674)
		(width 0.0889)
		(layer "In15.Cu")
		(net "P5E_CPU0_PE0_TX_DN<10>")
	)
	(arc
		(start 346.048838 -221.119192)
		(mid 346.099892 -220.944612)
		(end 346.227146 -220.814646)
		(width 0.0889)
		(layer "In15.Cu")
		(net "P5E_CPU0_PE0_TX_DN<10>")
	)
	(arc
		(start 346.236036 -220.809566)
		(mid 346.439341 -220.6087)
		(end 346.518484 -220.334078)
		(width 0.0889)
		(layer "In15.Cu")
		(net "P5E_CPU0_PE0_TX_DN<10>")
	)
	(arc
		(start 346.048584 -221.144084)
		(mid 346.048504 -221.131636)
		(end 346.048838 -221.119192)
		(width 0.0889)
		(layer "In15.Cu")
		(net "P5E_CPU0_PE0_TX_DN<10>")
	)
	(arc
		(start 345.765882 -215.112346)
		(mid 345.967164 -214.914859)
		(end 346.048076 -214.644732)
		(width 0.0889)
		(layer "In15.Cu")
		(net "P5E_CPU0_PE0_TX_DN<10>")
	)
	(arc
		(start 346.236036 -217.554048)
		(mid 346.439341 -217.353182)
		(end 346.518484 -217.07856)
		(width 0.0889)
		(layer "In15.Cu")
		(net "P5E_CPU0_PE0_TX_DN<10>")
	)
	(arc
		(start 345.578684 -215.421972)
		(mid 345.629738 -215.247392)
		(end 345.756992 -215.117426)
		(width 0.0889)
		(layer "In15.Cu")
		(net "P5E_CPU0_PE0_TX_DN<10>")
	)
	(arc
		(start 346.988638 -222.773748)
		(mid 346.988471 -222.762572)
		(end 346.988638 -222.751396)
		(width 0.0889)
		(layer "In15.Cu")
		(net "P5E_CPU0_PE0_TX_DN<10>")
	)
	(arc
		(start 347.598238 -223.867472)
		(mid 347.496917 -223.741351)
		(end 347.458284 -223.584262)
		(width 0.0889)
		(layer "In15.Cu")
		(net "P5E_CPU0_PE0_TX_DN<10>")
	)
	(arc
		(start 346.048076 -214.424768)
		(mid 345.936797 -214.232062)
		(end 345.762834 -214.093298)
		(width 0.0889)
		(layer "In15.Cu")
		(net "P5E_CPU0_PE0_TX_DN<10>")
	)
	(arc
		(start 346.227146 -221.453202)
		(mid 346.098742 -221.321257)
		(end 346.048584 -221.144084)
		(width 0.0889)
		(layer "In15.Cu")
		(net "P5E_CPU0_PE0_TX_DN<10>")
	)
	(segment
		(start 338.434934 -223.57588)
		(end 338.43468 -223.575626)
		(width 0.13208)
		(layer "F.Cu")
		(net "P5E_CPU0_PE0_TX_DN<0>")
	)
	(segment
		(start 351.58045 -407.924254)
		(end 351.25406 -408.250644)
		(width 0.13208)
		(layer "F.Cu")
		(net "P5E_CPU0_PE0_TX_DN<0>")
	)
	(segment
		(start 338.434934 -224.111566)
		(end 338.434934 -223.57588)
		(width 0.13208)
		(layer "F.Cu")
		(net "P5E_CPU0_PE0_TX_DN<0>")
	)
	(segment
		(start 351.274888 -407.00452)
		(end 351.58045 -407.310082)
		(width 0.13208)
		(layer "F.Cu")
		(net "P5E_CPU0_PE0_TX_DN<0>")
	)
	(segment
		(start 351.25406 -408.250644)
		(end 351.249488 -408.250644)
		(width 0.13208)
		(layer "F.Cu")
		(net "P5E_CPU0_PE0_TX_DN<0>")
	)
	(segment
		(start 351.58045 -407.310082)
		(end 351.58045 -407.924254)
		(width 0.13208)
		(layer "F.Cu")
		(net "P5E_CPU0_PE0_TX_DN<0>")
	)
	(segment
		(start 338.278216 -223.846644)
		(end 338.189316 -223.87052)
		(width 0.0889)
		(layer "In15.Cu")
		(net "P5E_CPU0_PE0_TX_DN<0>")
	)
	(segment
		(start 336.460084 -225.998786)
		(end 336.460084 -226.017328)
		(width 0.0889)
		(layer "In15.Cu")
		(net "P5E_CPU0_PE0_TX_DN<0>")
	)
	(segment
		(start 351.754948 -403.948138)
		(end 351.569528 -405.831548)
		(width 0.14732)
		(layer "In15.Cu")
		(net "P5E_CPU0_PE0_TX_DN<0>")
	)
	(segment
		(start 331.029564 -233.517948)
		(end 331.42555 -243.48313)
		(width 0.14732)
		(layer "In15.Cu")
		(net "P5E_CPU0_PE0_TX_DN<0>")
	)
	(segment
		(start 332.744572 -230.470964)
		(end 331.427582 -232.501186)
		(width 0.14732)
		(layer "In15.Cu")
		(net "P5E_CPU0_PE0_TX_DN<0>")
	)
	(segment
		(start 333.115666 -255.477264)
		(end 333.115412 -255.477518)
		(width 0.14732)
		(layer "In15.Cu")
		(net "P5E_CPU0_PE0_TX_DN<0>")
	)
	(segment
		(start 334.793082 -228.422454)
		(end 334.777588 -228.437948)
		(width 0.0889)
		(layer "In15.Cu")
		(net "P5E_CPU0_PE0_TX_DN<0>")
	)
	(segment
		(start 327.980802 -322.077842)
		(end 321.560952 -331.245972)
		(width 0.14732)
		(layer "In15.Cu")
		(net "P5E_CPU0_PE0_TX_DN<0>")
	)
	(segment
		(start 333.17053 -255.344676)
		(end 333.115666 -255.477264)
		(width 0.14732)
		(layer "In15.Cu")
		(net "P5E_CPU0_PE0_TX_DN<0>")
	)
	(segment
		(start 351.569528 -405.831548)
		(end 351.569528 -406.70988)
		(width 0.14732)
		(layer "In15.Cu")
		(net "P5E_CPU0_PE0_TX_DN<0>")
	)
	(segment
		(start 317.078106 -335.729072)
		(end 317.078106 -340.493604)
		(width 0.14732)
		(layer "In15.Cu")
		(net "P5E_CPU0_PE0_TX_DN<0>")
	)
	(segment
		(start 321.580256 -360.747818)
		(end 338.932266 -383.268728)
		(width 0.14732)
		(layer "In15.Cu")
		(net "P5E_CPU0_PE0_TX_DN<0>")
	)
	(segment
		(start 336.92973 -225.203258)
		(end 336.92973 -225.211894)
		(width 0.0889)
		(layer "In15.Cu")
		(net "P5E_CPU0_PE0_TX_DN<0>")
	)
	(segment
		(start 338.932266 -383.268728)
		(end 338.93252 -383.268728)
		(width 0.14732)
		(layer "In15.Cu")
		(net "P5E_CPU0_PE0_TX_DN<0>")
	)
	(segment
		(start 332.999588 -254.374904)
		(end 333.17053 -255.344676)
		(width 0.14732)
		(layer "In15.Cu")
		(net "P5E_CPU0_PE0_TX_DN<0>")
	)
	(segment
		(start 333.696818 -251.262134)
		(end 333.117444 -252.089666)
		(width 0.14732)
		(layer "In15.Cu")
		(net "P5E_CPU0_PE0_TX_DN<0>")
	)
	(segment
		(start 332.60284 -311.107328)
		(end 327.980802 -322.077842)
		(width 0.14732)
		(layer "In15.Cu")
		(net "P5E_CPU0_PE0_TX_DN<0>")
	)
	(segment
		(start 334.777588 -228.437948)
		(end 332.744572 -230.470964)
		(width 0.14732)
		(layer "In15.Cu")
		(net "P5E_CPU0_PE0_TX_DN<0>")
	)
	(segment
		(start 335.215484 -228.05898)
		(end 334.85201 -228.422454)
		(width 0.0889)
		(layer "In15.Cu")
		(net "P5E_CPU0_PE0_TX_DN<0>")
	)
	(segment
		(start 333.444596 -249.746516)
		(end 333.772256 -250.074176)
		(width 0.14732)
		(layer "In15.Cu")
		(net "P5E_CPU0_PE0_TX_DN<0>")
	)
	(segment
		(start 332.999588 -252.75667)
		(end 332.999588 -254.374904)
		(width 0.14732)
		(layer "In15.Cu")
		(net "P5E_CPU0_PE0_TX_DN<0>")
	)
	(segment
		(start 335.802732 -227.155502)
		(end 335.79054 -227.162614)
		(width 0.0889)
		(layer "In15.Cu")
		(net "P5E_CPU0_PE0_TX_DN<0>")
	)
	(segment
		(start 321.560952 -331.245972)
		(end 317.078106 -335.729072)
		(width 0.14732)
		(layer "In15.Cu")
		(net "P5E_CPU0_PE0_TX_DN<0>")
	)
	(segment
		(start 351.754948 -400.263614)
		(end 351.754948 -403.948138)
		(width 0.14732)
		(layer "In15.Cu")
		(net "P5E_CPU0_PE0_TX_DN<0>")
	)
	(segment
		(start 351.569528 -406.70988)
		(end 351.274888 -407.00452)
		(width 0.14732)
		(layer "In15.Cu")
		(net "P5E_CPU0_PE0_TX_DN<0>")
	)
	(segment
		(start 317.078106 -340.493604)
		(end 321.580256 -360.747818)
		(width 0.14732)
		(layer "In15.Cu")
		(net "P5E_CPU0_PE0_TX_DN<0>")
	)
	(segment
		(start 337.212432 -224.7138)
		(end 337.206336 -224.717356)
		(width 0.0889)
		(layer "In15.Cu")
		(net "P5E_CPU0_PE0_TX_DN<0>")
	)
	(segment
		(start 331.42555 -243.48313)
		(end 333.444596 -247.87098)
		(width 0.14732)
		(layer "In15.Cu")
		(net "P5E_CPU0_PE0_TX_DN<0>")
	)
	(segment
		(start 336.272632 -226.341686)
		(end 336.266536 -226.345242)
		(width 0.0889)
		(layer "In15.Cu")
		(net "P5E_CPU0_PE0_TX_DN<0>")
	)
	(segment
		(start 333.115666 -255.477518)
		(end 332.950566 -255.875536)
		(width 0.14732)
		(layer "In15.Cu")
		(net "P5E_CPU0_PE0_TX_DN<0>")
	)
	(segment
		(start 333.772256 -250.834652)
		(end 333.696818 -251.262134)
		(width 0.14732)
		(layer "In15.Cu")
		(net "P5E_CPU0_PE0_TX_DN<0>")
	)
	(segment
		(start 338.43468 -223.575626)
		(end 338.278216 -223.846644)
		(width 0.0889)
		(layer "In15.Cu")
		(net "P5E_CPU0_PE0_TX_DN<0>")
	)
	(segment
		(start 337.219036 -224.710244)
		(end 337.212432 -224.7138)
		(width 0.0889)
		(layer "In15.Cu")
		(net "P5E_CPU0_PE0_TX_DN<0>")
	)
	(segment
		(start 332.188312 -256.638044)
		(end 330.834238 -260.093968)
		(width 0.14732)
		(layer "In15.Cu")
		(net "P5E_CPU0_PE0_TX_DN<0>")
	)
	(segment
		(start 335.98993 -226.831144)
		(end 335.98993 -226.83978)
		(width 0.0889)
		(layer "In15.Cu")
		(net "P5E_CPU0_PE0_TX_DN<0>")
	)
	(segment
		(start 329.80757 -266.649708)
		(end 332.60284 -311.107328)
		(width 0.14732)
		(layer "In15.Cu")
		(net "P5E_CPU0_PE0_TX_DN<0>")
	)
	(segment
		(start 334.85201 -228.422454)
		(end 334.793082 -228.422454)
		(width 0.0889)
		(layer "In15.Cu")
		(net "P5E_CPU0_PE0_TX_DN<0>")
	)
	(segment
		(start 330.834238 -260.093968)
		(end 329.80757 -266.649708)
		(width 0.14732)
		(layer "In15.Cu")
		(net "P5E_CPU0_PE0_TX_DN<0>")
	)
	(segment
		(start 333.444596 -247.87098)
		(end 333.444596 -249.746516)
		(width 0.14732)
		(layer "In15.Cu")
		(net "P5E_CPU0_PE0_TX_DN<0>")
	)
	(segment
		(start 338.93252 -383.268728)
		(end 351.539302 -399.631408)
		(width 0.14732)
		(layer "In15.Cu")
		(net "P5E_CPU0_PE0_TX_DN<0>")
	)
	(segment
		(start 336.281522 -226.336606)
		(end 336.272632 -226.341686)
		(width 0.0889)
		(layer "In15.Cu")
		(net "P5E_CPU0_PE0_TX_DN<0>")
	)
	(segment
		(start 333.115412 -255.477518)
		(end 333.115666 -255.477518)
		(width 0.14732)
		(layer "In15.Cu")
		(net "P5E_CPU0_PE0_TX_DN<0>")
	)
	(segment
		(start 332.950566 -255.875536)
		(end 332.188312 -256.638044)
		(width 0.14732)
		(layer "In15.Cu")
		(net "P5E_CPU0_PE0_TX_DN<0>")
	)
	(segment
		(start 338.189316 -223.87052)
		(end 338.189062 -223.870774)
		(width 0.0889)
		(layer "In15.Cu")
		(net "P5E_CPU0_PE0_TX_DN<0>")
	)
	(segment
		(start 331.427582 -232.501186)
		(end 331.029564 -233.517948)
		(width 0.14732)
		(layer "In15.Cu")
		(net "P5E_CPU0_PE0_TX_DN<0>")
	)
	(segment
		(start 337.683094 -223.899984)
		(end 337.672172 -223.906334)
		(width 0.0889)
		(layer "In15.Cu")
		(net "P5E_CPU0_PE0_TX_DN<0>")
	)
	(segment
		(start 351.539302 -399.631408)
		(end 351.754948 -400.263614)
		(width 0.14732)
		(layer "In15.Cu")
		(net "P5E_CPU0_PE0_TX_DN<0>")
	)
	(segment
		(start 333.772256 -250.074176)
		(end 333.772256 -250.834652)
		(width 0.14732)
		(layer "In15.Cu")
		(net "P5E_CPU0_PE0_TX_DN<0>")
	)
	(segment
		(start 333.117444 -252.089666)
		(end 332.999588 -252.75667)
		(width 0.14732)
		(layer "In15.Cu")
		(net "P5E_CPU0_PE0_TX_DN<0>")
	)
	(arc
		(start 336.742532 -225.527616)
		(mid 336.540246 -225.726597)
		(end 336.460084 -225.998786)
		(width 0.0889)
		(layer "In15.Cu")
		(net "P5E_CPU0_PE0_TX_DN<0>")
	)
	(arc
		(start 338.189062 -223.870774)
		(mid 338.179195 -223.866616)
		(end 338.16925 -223.862646)
		(width 0.0889)
		(layer "In15.Cu")
		(net "P5E_CPU0_PE0_TX_DN<0>")
	)
	(arc
		(start 336.266536 -226.345242)
		(mid 336.063949 -226.551593)
		(end 335.98993 -226.831144)
		(width 0.0889)
		(layer "In15.Cu")
		(net "P5E_CPU0_PE0_TX_DN<0>")
	)
	(arc
		(start 335.341468 -227.964238)
		(mid 335.275171 -228.007212)
		(end 335.215484 -228.05898)
		(width 0.0889)
		(layer "In15.Cu")
		(net "P5E_CPU0_PE0_TX_DN<0>")
	)
	(arc
		(start 336.460084 -226.017328)
		(mid 336.412405 -226.200228)
		(end 336.281522 -226.336606)
		(width 0.0889)
		(layer "In15.Cu")
		(net "P5E_CPU0_PE0_TX_DN<0>")
	)
	(arc
		(start 335.79054 -227.162614)
		(mid 335.592312 -227.368462)
		(end 335.52003 -227.64496)
		(width 0.0889)
		(layer "In15.Cu")
		(net "P5E_CPU0_PE0_TX_DN<0>")
	)
	(arc
		(start 337.206336 -224.717356)
		(mid 337.003749 -224.923707)
		(end 336.92973 -225.203258)
		(width 0.0889)
		(layer "In15.Cu")
		(net "P5E_CPU0_PE0_TX_DN<0>")
	)
	(arc
		(start 337.672172 -223.906334)
		(mid 337.472788 -224.112214)
		(end 337.400138 -224.389442)
		(width 0.0889)
		(layer "In15.Cu")
		(net "P5E_CPU0_PE0_TX_DN<0>")
	)
	(arc
		(start 338.16925 -223.862646)
		(mid 337.921948 -223.826205)
		(end 337.683094 -223.899984)
		(width 0.0889)
		(layer "In15.Cu")
		(net "P5E_CPU0_PE0_TX_DN<0>")
	)
	(arc
		(start 337.400138 -224.389442)
		(mid 337.351733 -224.573633)
		(end 337.219036 -224.710244)
		(width 0.0889)
		(layer "In15.Cu")
		(net "P5E_CPU0_PE0_TX_DN<0>")
	)
	(arc
		(start 336.92973 -225.211894)
		(mid 336.87746 -225.394259)
		(end 336.742532 -225.527616)
		(width 0.0889)
		(layer "In15.Cu")
		(net "P5E_CPU0_PE0_TX_DN<0>")
	)
	(arc
		(start 335.52003 -227.64496)
		(mid 335.472351 -227.82786)
		(end 335.341468 -227.964238)
		(width 0.0889)
		(layer "In15.Cu")
		(net "P5E_CPU0_PE0_TX_DN<0>")
	)
	(arc
		(start 335.98993 -226.83978)
		(mid 335.93766 -227.022145)
		(end 335.802732 -227.155502)
		(width 0.0889)
		(layer "In15.Cu")
		(net "P5E_CPU0_PE0_TX_DN<0>")
	)
	(segment
		(start 324.26783 -409.72867)
		(end 324.26783 -409.110942)
		(width 0.13208)
		(layer "F.Cu")
		(net "P5E_CPU0_PE0_TX_C_DP<9>")
	)
	(segment
		(start 324.26783 -409.110942)
		(end 324.594728 -408.784044)
		(width 0.13208)
		(layer "F.Cu")
		(net "P5E_CPU0_PE0_TX_C_DP<9>")
	)
	(segment
		(start 324.569328 -410.030168)
		(end 324.26783 -409.72867)
		(width 0.13208)
		(layer "F.Cu")
		(net "P5E_CPU0_PE0_TX_C_DP<9>")
	)
	(segment
		(start 324.828916 -415.727388)
		(end 324.96379 -415.835084)
		(width 0.14732)
		(layer "In11.Cu")
		(net "P5E_CPU0_PE0_TX_C_DP<9>")
	)
	(segment
		(start 324.65772 -414.182306)
		(end 324.705726 -414.616392)
		(width 0.14732)
		(layer "In11.Cu")
		(net "P5E_CPU0_PE0_TX_C_DP<9>")
	)
	(segment
		(start 326.090788 -430.119536)
		(end 326.502268 -430.119536)
		(width 0.14732)
		(layer "In11.Cu")
		(net "P5E_CPU0_PE0_TX_C_DP<9>")
	)
	(segment
		(start 326.502268 -430.119536)
		(end 326.650096 -429.971708)
		(width 0.14732)
		(layer "In11.Cu")
		(net "P5E_CPU0_PE0_TX_C_DP<9>")
	)
	(segment
		(start 325.966836 -429.995584)
		(end 326.090788 -430.119536)
		(width 0.14732)
		(layer "In11.Cu")
		(net "P5E_CPU0_PE0_TX_C_DP<9>")
	)
	(segment
		(start 324.888606 -415.158682)
		(end 324.78091 -415.293302)
		(width 0.14732)
		(layer "In11.Cu")
		(net "P5E_CPU0_PE0_TX_C_DP<9>")
	)
	(segment
		(start 325.011796 -416.269678)
		(end 324.9041 -416.404298)
		(width 0.14732)
		(layer "In11.Cu")
		(net "P5E_CPU0_PE0_TX_C_DP<9>")
	)
	(segment
		(start 324.765416 -414.047686)
		(end 324.65772 -414.182306)
		(width 0.14732)
		(layer "In11.Cu")
		(net "P5E_CPU0_PE0_TX_C_DP<9>")
	)
	(segment
		(start 324.274942 -410.72562)
		(end 324.582536 -413.505396)
		(width 0.14732)
		(layer "In11.Cu")
		(net "P5E_CPU0_PE0_TX_C_DP<9>")
	)
	(segment
		(start 325.027036 -417.515294)
		(end 325.965312 -425.994322)
		(width 0.14732)
		(layer "In11.Cu")
		(net "P5E_CPU0_PE0_TX_C_DP<9>")
	)
	(segment
		(start 324.71741 -413.613092)
		(end 324.765416 -414.047686)
		(width 0.14732)
		(layer "In11.Cu")
		(net "P5E_CPU0_PE0_TX_C_DP<9>")
	)
	(segment
		(start 324.274688 -410.324808)
		(end 324.274688 -410.725366)
		(width 0.14732)
		(layer "In11.Cu")
		(net "P5E_CPU0_PE0_TX_C_DP<9>")
	)
	(segment
		(start 326.650096 -429.971708)
		(end 326.650096 -429.689768)
		(width 0.14732)
		(layer "In11.Cu")
		(net "P5E_CPU0_PE0_TX_C_DP<9>")
	)
	(segment
		(start 325.08698 -416.94608)
		(end 325.134986 -417.380674)
		(width 0.14732)
		(layer "In11.Cu")
		(net "P5E_CPU0_PE0_TX_C_DP<9>")
	)
	(segment
		(start 324.78091 -415.293302)
		(end 324.828916 -415.727388)
		(width 0.14732)
		(layer "In11.Cu")
		(net "P5E_CPU0_PE0_TX_C_DP<9>")
	)
	(segment
		(start 325.134986 -417.380674)
		(end 325.027036 -417.515294)
		(width 0.14732)
		(layer "In11.Cu")
		(net "P5E_CPU0_PE0_TX_C_DP<9>")
	)
	(segment
		(start 324.96379 -415.835084)
		(end 325.011796 -416.269678)
		(width 0.14732)
		(layer "In11.Cu")
		(net "P5E_CPU0_PE0_TX_C_DP<9>")
	)
	(segment
		(start 324.952106 -416.838384)
		(end 325.08698 -416.94608)
		(width 0.14732)
		(layer "In11.Cu")
		(net "P5E_CPU0_PE0_TX_C_DP<9>")
	)
	(segment
		(start 324.582536 -413.505396)
		(end 324.71741 -413.613092)
		(width 0.14732)
		(layer "In11.Cu")
		(net "P5E_CPU0_PE0_TX_C_DP<9>")
	)
	(segment
		(start 324.569328 -410.030168)
		(end 324.274688 -410.324808)
		(width 0.14732)
		(layer "In11.Cu")
		(net "P5E_CPU0_PE0_TX_C_DP<9>")
	)
	(segment
		(start 324.9041 -416.404298)
		(end 324.952106 -416.838384)
		(width 0.14732)
		(layer "In11.Cu")
		(net "P5E_CPU0_PE0_TX_C_DP<9>")
	)
	(segment
		(start 324.274688 -410.725366)
		(end 324.274942 -410.72562)
		(width 0.14732)
		(layer "In11.Cu")
		(net "P5E_CPU0_PE0_TX_C_DP<9>")
	)
	(segment
		(start 324.705726 -414.616392)
		(end 324.8406 -414.724088)
		(width 0.14732)
		(layer "In11.Cu")
		(net "P5E_CPU0_PE0_TX_C_DP<9>")
	)
	(segment
		(start 325.965312 -425.994322)
		(end 325.966836 -425.995846)
		(width 0.14732)
		(layer "In11.Cu")
		(net "P5E_CPU0_PE0_TX_C_DP<9>")
	)
	(segment
		(start 325.966836 -425.995846)
		(end 325.966836 -429.995584)
		(width 0.14732)
		(layer "In11.Cu")
		(net "P5E_CPU0_PE0_TX_C_DP<9>")
	)
	(segment
		(start 324.8406 -414.724088)
		(end 324.888606 -415.158682)
		(width 0.14732)
		(layer "In11.Cu")
		(net "P5E_CPU0_PE0_TX_C_DP<9>")
	)
	(segment
		(start 327.33107 -409.110942)
		(end 327.657968 -408.784044)
		(width 0.13208)
		(layer "F.Cu")
		(net "P5E_CPU0_PE0_TX_C_DP<8>")
	)
	(segment
		(start 327.33107 -409.72867)
		(end 327.33107 -409.110942)
		(width 0.13208)
		(layer "F.Cu")
		(net "P5E_CPU0_PE0_TX_C_DP<8>")
	)
	(segment
		(start 327.632568 -410.030168)
		(end 327.33107 -409.72867)
		(width 0.13208)
		(layer "F.Cu")
		(net "P5E_CPU0_PE0_TX_C_DP<8>")
	)
	(segment
		(start 327.52538 -412.326074)
		(end 327.5457 -412.7627)
		(width 0.14732)
		(layer "In11.Cu")
		(net "P5E_CPU0_PE0_TX_C_DP<8>")
	)
	(segment
		(start 327.966832 -424.486578)
		(end 327.966832 -430.992534)
		(width 0.14732)
		(layer "In11.Cu")
		(net "P5E_CPU0_PE0_TX_C_DP<8>")
	)
	(segment
		(start 328.093832 -431.119534)
		(end 328.502264 -431.119534)
		(width 0.14732)
		(layer "In11.Cu")
		(net "P5E_CPU0_PE0_TX_C_DP<8>")
	)
	(segment
		(start 328.502264 -431.119534)
		(end 328.650092 -430.971706)
		(width 0.14732)
		(layer "In11.Cu")
		(net "P5E_CPU0_PE0_TX_C_DP<8>")
	)
	(segment
		(start 327.966832 -430.992534)
		(end 328.093832 -431.119534)
		(width 0.14732)
		(layer "In11.Cu")
		(net "P5E_CPU0_PE0_TX_C_DP<8>")
	)
	(segment
		(start 327.632568 -410.030168)
		(end 327.337928 -410.324808)
		(width 0.14732)
		(layer "In11.Cu")
		(net "P5E_CPU0_PE0_TX_C_DP<8>")
	)
	(segment
		(start 327.479406 -414.014412)
		(end 327.966832 -424.486578)
		(width 0.14732)
		(layer "In11.Cu")
		(net "P5E_CPU0_PE0_TX_C_DP<8>")
	)
	(segment
		(start 327.337928 -410.978858)
		(end 327.338182 -410.979112)
		(width 0.14732)
		(layer "In11.Cu")
		(net "P5E_CPU0_PE0_TX_C_DP<8>")
	)
	(segment
		(start 327.598024 -413.88411)
		(end 327.479406 -414.014412)
		(width 0.14732)
		(layer "In11.Cu")
		(net "P5E_CPU0_PE0_TX_C_DP<8>")
	)
	(segment
		(start 327.427082 -412.892748)
		(end 327.447148 -413.32912)
		(width 0.14732)
		(layer "In11.Cu")
		(net "P5E_CPU0_PE0_TX_C_DP<8>")
	)
	(segment
		(start 327.337928 -410.324808)
		(end 327.337928 -410.978858)
		(width 0.14732)
		(layer "In11.Cu")
		(net "P5E_CPU0_PE0_TX_C_DP<8>")
	)
	(segment
		(start 327.338182 -410.979112)
		(end 327.395332 -412.20771)
		(width 0.14732)
		(layer "In11.Cu")
		(net "P5E_CPU0_PE0_TX_C_DP<8>")
	)
	(segment
		(start 327.577704 -413.447484)
		(end 327.598024 -413.88411)
		(width 0.14732)
		(layer "In11.Cu")
		(net "P5E_CPU0_PE0_TX_C_DP<8>")
	)
	(segment
		(start 328.650092 -430.971706)
		(end 328.650092 -430.689766)
		(width 0.14732)
		(layer "In11.Cu")
		(net "P5E_CPU0_PE0_TX_C_DP<8>")
	)
	(segment
		(start 327.5457 -412.7627)
		(end 327.427082 -412.892748)
		(width 0.14732)
		(layer "In11.Cu")
		(net "P5E_CPU0_PE0_TX_C_DP<8>")
	)
	(segment
		(start 327.447148 -413.32912)
		(end 327.577704 -413.447484)
		(width 0.14732)
		(layer "In11.Cu")
		(net "P5E_CPU0_PE0_TX_C_DP<8>")
	)
	(segment
		(start 327.395332 -412.20771)
		(end 327.52538 -412.326074)
		(width 0.14732)
		(layer "In11.Cu")
		(net "P5E_CPU0_PE0_TX_C_DP<8>")
	)
	(segment
		(start 330.39431 -409.110942)
		(end 330.721208 -408.784044)
		(width 0.13208)
		(layer "F.Cu")
		(net "P5E_CPU0_PE0_TX_C_DP<7>")
	)
	(segment
		(start 330.39431 -409.72867)
		(end 330.39431 -409.110942)
		(width 0.13208)
		(layer "F.Cu")
		(net "P5E_CPU0_PE0_TX_C_DP<7>")
	)
	(segment
		(start 330.695808 -410.030168)
		(end 330.39431 -409.72867)
		(width 0.13208)
		(layer "F.Cu")
		(net "P5E_CPU0_PE0_TX_C_DP<7>")
	)
	(segment
		(start 330.52893 -415.046414)
		(end 330.541884 -415.48304)
		(width 0.14732)
		(layer "In11.Cu")
		(net "P5E_CPU0_PE0_TX_C_DP<7>")
	)
	(segment
		(start 330.461874 -412.801562)
		(end 330.474828 -413.238188)
		(width 0.14732)
		(layer "In11.Cu")
		(net "P5E_CPU0_PE0_TX_C_DP<7>")
	)
	(segment
		(start 330.670154 -415.60369)
		(end 330.683108 -416.04057)
		(width 0.14732)
		(layer "In11.Cu")
		(net "P5E_CPU0_PE0_TX_C_DP<7>")
	)
	(segment
		(start 330.56957 -412.236412)
		(end 330.582524 -412.673292)
		(width 0.14732)
		(layer "In11.Cu")
		(net "P5E_CPU0_PE0_TX_C_DP<7>")
	)
	(segment
		(start 330.683108 -416.04057)
		(end 330.562458 -416.16884)
		(width 0.14732)
		(layer "In11.Cu")
		(net "P5E_CPU0_PE0_TX_C_DP<7>")
	)
	(segment
		(start 330.64958 -414.918144)
		(end 330.52893 -415.046414)
		(width 0.14732)
		(layer "In11.Cu")
		(net "P5E_CPU0_PE0_TX_C_DP<7>")
	)
	(segment
		(start 330.616052 -413.795718)
		(end 330.495402 -413.923988)
		(width 0.14732)
		(layer "In11.Cu")
		(net "P5E_CPU0_PE0_TX_C_DP<7>")
	)
	(segment
		(start 330.81468 -429.843438)
		(end 331.090778 -430.119536)
		(width 0.14732)
		(layer "In11.Cu")
		(net "P5E_CPU0_PE0_TX_C_DP<7>")
	)
	(segment
		(start 330.4413 -412.115762)
		(end 330.56957 -412.236412)
		(width 0.14732)
		(layer "In11.Cu")
		(net "P5E_CPU0_PE0_TX_C_DP<7>")
	)
	(segment
		(start 330.636626 -414.481264)
		(end 330.64958 -414.918144)
		(width 0.14732)
		(layer "In11.Cu")
		(net "P5E_CPU0_PE0_TX_C_DP<7>")
	)
	(segment
		(start 330.541884 -415.48304)
		(end 330.670154 -415.60369)
		(width 0.14732)
		(layer "In11.Cu")
		(net "P5E_CPU0_PE0_TX_C_DP<7>")
	)
	(segment
		(start 330.603098 -413.358838)
		(end 330.616052 -413.795718)
		(width 0.14732)
		(layer "In11.Cu")
		(net "P5E_CPU0_PE0_TX_C_DP<7>")
	)
	(segment
		(start 331.502258 -430.119536)
		(end 331.650086 -429.971708)
		(width 0.14732)
		(layer "In11.Cu")
		(net "P5E_CPU0_PE0_TX_C_DP<7>")
	)
	(segment
		(start 330.401168 -410.76626)
		(end 330.4413 -412.115762)
		(width 0.14732)
		(layer "In11.Cu")
		(net "P5E_CPU0_PE0_TX_C_DP<7>")
	)
	(segment
		(start 330.81468 -424.6626)
		(end 330.81468 -429.843438)
		(width 0.14732)
		(layer "In11.Cu")
		(net "P5E_CPU0_PE0_TX_C_DP<7>")
	)
	(segment
		(start 330.562458 -416.16884)
		(end 330.81468 -424.6626)
		(width 0.14732)
		(layer "In11.Cu")
		(net "P5E_CPU0_PE0_TX_C_DP<7>")
	)
	(segment
		(start 330.495402 -413.923988)
		(end 330.508356 -414.360614)
		(width 0.14732)
		(layer "In11.Cu")
		(net "P5E_CPU0_PE0_TX_C_DP<7>")
	)
	(segment
		(start 330.582524 -412.673292)
		(end 330.461874 -412.801562)
		(width 0.14732)
		(layer "In11.Cu")
		(net "P5E_CPU0_PE0_TX_C_DP<7>")
	)
	(segment
		(start 331.650086 -429.971708)
		(end 331.650086 -429.689768)
		(width 0.14732)
		(layer "In11.Cu")
		(net "P5E_CPU0_PE0_TX_C_DP<7>")
	)
	(segment
		(start 330.508356 -414.360614)
		(end 330.636626 -414.481264)
		(width 0.14732)
		(layer "In11.Cu")
		(net "P5E_CPU0_PE0_TX_C_DP<7>")
	)
	(segment
		(start 330.474828 -413.238188)
		(end 330.603098 -413.358838)
		(width 0.14732)
		(layer "In11.Cu")
		(net "P5E_CPU0_PE0_TX_C_DP<7>")
	)
	(segment
		(start 330.401168 -410.324808)
		(end 330.401168 -410.76626)
		(width 0.14732)
		(layer "In11.Cu")
		(net "P5E_CPU0_PE0_TX_C_DP<7>")
	)
	(segment
		(start 331.090778 -430.119536)
		(end 331.502258 -430.119536)
		(width 0.14732)
		(layer "In11.Cu")
		(net "P5E_CPU0_PE0_TX_C_DP<7>")
	)
	(segment
		(start 330.695808 -410.030168)
		(end 330.401168 -410.324808)
		(width 0.14732)
		(layer "In11.Cu")
		(net "P5E_CPU0_PE0_TX_C_DP<7>")
	)
	(segment
		(start 333.759048 -410.030168)
		(end 333.45755 -409.72867)
		(width 0.13208)
		(layer "F.Cu")
		(net "P5E_CPU0_PE0_TX_C_DP<6>")
	)
	(segment
		(start 333.45755 -409.110942)
		(end 333.784448 -408.784044)
		(width 0.13208)
		(layer "F.Cu")
		(net "P5E_CPU0_PE0_TX_C_DP<6>")
	)
	(segment
		(start 333.45755 -409.72867)
		(end 333.45755 -409.110942)
		(width 0.13208)
		(layer "F.Cu")
		(net "P5E_CPU0_PE0_TX_C_DP<6>")
	)
	(segment
		(start 333.097378 -431.119534)
		(end 333.502254 -431.119534)
		(width 0.14732)
		(layer "In11.Cu")
		(net "P5E_CPU0_PE0_TX_C_DP<6>")
	)
	(segment
		(start 333.588868 -412.534608)
		(end 333.464408 -412.659068)
		(width 0.14732)
		(layer "In11.Cu")
		(net "P5E_CPU0_PE0_TX_C_DP<6>")
	)
	(segment
		(start 333.443834 -414.357312)
		(end 333.562198 -414.48736)
		(width 0.14732)
		(layer "In11.Cu")
		(net "P5E_CPU0_PE0_TX_C_DP<6>")
	)
	(segment
		(start 333.464408 -411.973268)
		(end 333.588868 -412.097728)
		(width 0.14732)
		(layer "In11.Cu")
		(net "P5E_CPU0_PE0_TX_C_DP<6>")
	)
	(segment
		(start 332.966822 -424.428412)
		(end 332.966822 -430.988978)
		(width 0.14732)
		(layer "In11.Cu")
		(net "P5E_CPU0_PE0_TX_C_DP<6>")
	)
	(segment
		(start 333.502254 -431.119534)
		(end 333.650082 -430.971706)
		(width 0.14732)
		(layer "In11.Cu")
		(net "P5E_CPU0_PE0_TX_C_DP<6>")
	)
	(segment
		(start 333.650082 -430.971706)
		(end 333.650082 -430.689766)
		(width 0.14732)
		(layer "In11.Cu")
		(net "P5E_CPU0_PE0_TX_C_DP<6>")
	)
	(segment
		(start 332.966822 -430.988978)
		(end 333.097378 -431.119534)
		(width 0.14732)
		(layer "In11.Cu")
		(net "P5E_CPU0_PE0_TX_C_DP<6>")
	)
	(segment
		(start 333.464408 -412.659068)
		(end 333.464408 -413.92094)
		(width 0.14732)
		(layer "In11.Cu")
		(net "P5E_CPU0_PE0_TX_C_DP<6>")
	)
	(segment
		(start 333.411322 -415.04235)
		(end 332.966822 -424.428412)
		(width 0.14732)
		(layer "In11.Cu")
		(net "P5E_CPU0_PE0_TX_C_DP<6>")
	)
	(segment
		(start 333.541624 -414.923986)
		(end 333.411322 -415.04235)
		(width 0.14732)
		(layer "In11.Cu")
		(net "P5E_CPU0_PE0_TX_C_DP<6>")
	)
	(segment
		(start 333.562198 -414.48736)
		(end 333.541624 -414.923986)
		(width 0.14732)
		(layer "In11.Cu")
		(net "P5E_CPU0_PE0_TX_C_DP<6>")
	)
	(segment
		(start 333.759048 -410.030168)
		(end 333.464408 -410.324808)
		(width 0.14732)
		(layer "In11.Cu")
		(net "P5E_CPU0_PE0_TX_C_DP<6>")
	)
	(segment
		(start 333.464408 -410.324808)
		(end 333.464408 -411.973268)
		(width 0.14732)
		(layer "In11.Cu")
		(net "P5E_CPU0_PE0_TX_C_DP<6>")
	)
	(segment
		(start 333.588868 -412.097728)
		(end 333.588868 -412.534608)
		(width 0.14732)
		(layer "In11.Cu")
		(net "P5E_CPU0_PE0_TX_C_DP<6>")
	)
	(segment
		(start 333.464408 -413.92094)
		(end 333.443834 -414.357312)
		(width 0.14732)
		(layer "In11.Cu")
		(net "P5E_CPU0_PE0_TX_C_DP<6>")
	)
	(segment
		(start 336.822288 -410.030168)
		(end 336.52079 -409.72867)
		(width 0.13208)
		(layer "F.Cu")
		(net "P5E_CPU0_PE0_TX_C_DP<5>")
	)
	(segment
		(start 336.52079 -409.72867)
		(end 336.52079 -409.110942)
		(width 0.13208)
		(layer "F.Cu")
		(net "P5E_CPU0_PE0_TX_C_DP<5>")
	)
	(segment
		(start 336.52079 -409.110942)
		(end 336.847688 -408.784044)
		(width 0.13208)
		(layer "F.Cu")
		(net "P5E_CPU0_PE0_TX_C_DP<5>")
	)
	(segment
		(start 336.40903 -412.901892)
		(end 336.51698 -413.04083)
		(width 0.14732)
		(layer "In11.Cu")
		(net "P5E_CPU0_PE0_TX_C_DP<5>")
	)
	(segment
		(start 336.323686 -413.582612)
		(end 336.269584 -414.015936)
		(width 0.14732)
		(layer "In11.Cu")
		(net "P5E_CPU0_PE0_TX_C_DP<5>")
	)
	(segment
		(start 335.50225 -430.119536)
		(end 335.650078 -429.971708)
		(width 0.14732)
		(layer "In11.Cu")
		(net "P5E_CPU0_PE0_TX_C_DP<5>")
	)
	(segment
		(start 336.527648 -411.949646)
		(end 336.487516 -412.27248)
		(width 0.14732)
		(layer "In11.Cu")
		(net "P5E_CPU0_PE0_TX_C_DP<5>")
	)
	(segment
		(start 336.51698 -413.04083)
		(end 336.462878 -413.474408)
		(width 0.14732)
		(layer "In11.Cu")
		(net "P5E_CPU0_PE0_TX_C_DP<5>")
	)
	(segment
		(start 335.09077 -430.119536)
		(end 335.50225 -430.119536)
		(width 0.14732)
		(layer "In11.Cu")
		(net "P5E_CPU0_PE0_TX_C_DP<5>")
	)
	(segment
		(start 336.18424 -415.70275)
		(end 336.045302 -415.810446)
		(width 0.14732)
		(layer "In11.Cu")
		(net "P5E_CPU0_PE0_TX_C_DP<5>")
	)
	(segment
		(start 334.966818 -424.43908)
		(end 334.966818 -429.995584)
		(width 0.14732)
		(layer "In11.Cu")
		(net "P5E_CPU0_PE0_TX_C_DP<5>")
	)
	(segment
		(start 336.527648 -410.324808)
		(end 336.527648 -411.949646)
		(width 0.14732)
		(layer "In11.Cu")
		(net "P5E_CPU0_PE0_TX_C_DP<5>")
	)
	(segment
		(start 336.822288 -410.030168)
		(end 336.527648 -410.324808)
		(width 0.14732)
		(layer "In11.Cu")
		(net "P5E_CPU0_PE0_TX_C_DP<5>")
	)
	(segment
		(start 336.099404 -416.382962)
		(end 336.045048 -416.816794)
		(width 0.14732)
		(layer "In11.Cu")
		(net "P5E_CPU0_PE0_TX_C_DP<5>")
	)
	(segment
		(start 336.130392 -415.12998)
		(end 336.238596 -415.268918)
		(width 0.14732)
		(layer "In11.Cu")
		(net "P5E_CPU0_PE0_TX_C_DP<5>")
	)
	(segment
		(start 336.045302 -415.810446)
		(end 335.9912 -416.244024)
		(width 0.14732)
		(layer "In11.Cu")
		(net "P5E_CPU0_PE0_TX_C_DP<5>")
	)
	(segment
		(start 336.377788 -414.154874)
		(end 336.323432 -414.588706)
		(width 0.14732)
		(layer "In11.Cu")
		(net "P5E_CPU0_PE0_TX_C_DP<5>")
	)
	(segment
		(start 335.650078 -429.971708)
		(end 335.650078 -429.689768)
		(width 0.14732)
		(layer "In11.Cu")
		(net "P5E_CPU0_PE0_TX_C_DP<5>")
	)
	(segment
		(start 335.9912 -416.244024)
		(end 336.099404 -416.382962)
		(width 0.14732)
		(layer "In11.Cu")
		(net "P5E_CPU0_PE0_TX_C_DP<5>")
	)
	(segment
		(start 336.238596 -415.268918)
		(end 336.18424 -415.70275)
		(width 0.14732)
		(layer "In11.Cu")
		(net "P5E_CPU0_PE0_TX_C_DP<5>")
	)
	(segment
		(start 336.462878 -413.474408)
		(end 336.323686 -413.582612)
		(width 0.14732)
		(layer "In11.Cu")
		(net "P5E_CPU0_PE0_TX_C_DP<5>")
	)
	(segment
		(start 335.90611 -416.92449)
		(end 334.966818 -424.43908)
		(width 0.14732)
		(layer "In11.Cu")
		(net "P5E_CPU0_PE0_TX_C_DP<5>")
	)
	(segment
		(start 336.269584 -414.015936)
		(end 336.377788 -414.154874)
		(width 0.14732)
		(layer "In11.Cu")
		(net "P5E_CPU0_PE0_TX_C_DP<5>")
	)
	(segment
		(start 336.045048 -416.816794)
		(end 335.90611 -416.92449)
		(width 0.14732)
		(layer "In11.Cu")
		(net "P5E_CPU0_PE0_TX_C_DP<5>")
	)
	(segment
		(start 334.966818 -429.995584)
		(end 335.09077 -430.119536)
		(width 0.14732)
		(layer "In11.Cu")
		(net "P5E_CPU0_PE0_TX_C_DP<5>")
	)
	(segment
		(start 336.184494 -414.696402)
		(end 336.130392 -415.12998)
		(width 0.14732)
		(layer "In11.Cu")
		(net "P5E_CPU0_PE0_TX_C_DP<5>")
	)
	(segment
		(start 336.487516 -412.27248)
		(end 336.40903 -412.901892)
		(width 0.14732)
		(layer "In11.Cu")
		(net "P5E_CPU0_PE0_TX_C_DP<5>")
	)
	(segment
		(start 336.323432 -414.588706)
		(end 336.184494 -414.696402)
		(width 0.14732)
		(layer "In11.Cu")
		(net "P5E_CPU0_PE0_TX_C_DP<5>")
	)
	(segment
		(start 339.885528 -410.030168)
		(end 339.58403 -409.72867)
		(width 0.13208)
		(layer "F.Cu")
		(net "P5E_CPU0_PE0_TX_C_DP<4>")
	)
	(segment
		(start 339.58403 -409.72867)
		(end 339.58403 -409.110942)
		(width 0.13208)
		(layer "F.Cu")
		(net "P5E_CPU0_PE0_TX_C_DP<4>")
	)
	(segment
		(start 339.58403 -409.110942)
		(end 339.910928 -408.784044)
		(width 0.13208)
		(layer "F.Cu")
		(net "P5E_CPU0_PE0_TX_C_DP<4>")
	)
	(segment
		(start 339.575648 -410.340048)
		(end 339.575648 -411.585156)
		(width 0.14732)
		(layer "In11.Cu")
		(net "P5E_CPU0_PE0_TX_C_DP<4>")
	)
	(segment
		(start 339.157056 -413.588962)
		(end 339.068664 -414.016698)
		(width 0.14732)
		(layer "In11.Cu")
		(net "P5E_CPU0_PE0_TX_C_DP<4>")
	)
	(segment
		(start 338.930742 -414.683448)
		(end 338.84235 -415.111184)
		(width 0.14732)
		(layer "In11.Cu")
		(net "P5E_CPU0_PE0_TX_C_DP<4>")
	)
	(segment
		(start 338.8487 -415.683446)
		(end 338.704428 -415.777934)
		(width 0.14732)
		(layer "In11.Cu")
		(net "P5E_CPU0_PE0_TX_C_DP<4>")
	)
	(segment
		(start 339.301328 -413.49422)
		(end 339.157056 -413.588962)
		(width 0.14732)
		(layer "In11.Cu")
		(net "P5E_CPU0_PE0_TX_C_DP<4>")
	)
	(segment
		(start 336.966814 -424.18508)
		(end 336.966814 -430.97577)
		(width 0.14732)
		(layer "In11.Cu")
		(net "P5E_CPU0_PE0_TX_C_DP<4>")
	)
	(segment
		(start 339.075014 -414.58896)
		(end 338.930742 -414.683448)
		(width 0.14732)
		(layer "In11.Cu")
		(net "P5E_CPU0_PE0_TX_C_DP<4>")
	)
	(segment
		(start 337.650074 -430.971706)
		(end 337.650074 -430.689766)
		(width 0.14732)
		(layer "In11.Cu")
		(net "P5E_CPU0_PE0_TX_C_DP<4>")
	)
	(segment
		(start 339.575648 -411.585156)
		(end 339.57006 -411.590744)
		(width 0.14732)
		(layer "In11.Cu")
		(net "P5E_CPU0_PE0_TX_C_DP<4>")
	)
	(segment
		(start 337.110578 -431.119534)
		(end 337.502246 -431.119534)
		(width 0.14732)
		(layer "In11.Cu")
		(net "P5E_CPU0_PE0_TX_C_DP<4>")
	)
	(segment
		(start 339.294978 -412.921958)
		(end 339.38972 -413.065976)
		(width 0.14732)
		(layer "In11.Cu")
		(net "P5E_CPU0_PE0_TX_C_DP<4>")
	)
	(segment
		(start 336.966814 -430.97577)
		(end 337.110578 -431.119534)
		(width 0.14732)
		(layer "In11.Cu")
		(net "P5E_CPU0_PE0_TX_C_DP<4>")
	)
	(segment
		(start 338.937092 -415.255202)
		(end 338.8487 -415.683446)
		(width 0.14732)
		(layer "In11.Cu")
		(net "P5E_CPU0_PE0_TX_C_DP<4>")
	)
	(segment
		(start 339.885528 -410.030168)
		(end 339.575648 -410.340048)
		(width 0.14732)
		(layer "In11.Cu")
		(net "P5E_CPU0_PE0_TX_C_DP<4>")
	)
	(segment
		(start 339.57006 -411.590744)
		(end 339.294978 -412.921958)
		(width 0.14732)
		(layer "In11.Cu")
		(net "P5E_CPU0_PE0_TX_C_DP<4>")
	)
	(segment
		(start 338.84235 -415.111184)
		(end 338.937092 -415.255202)
		(width 0.14732)
		(layer "In11.Cu")
		(net "P5E_CPU0_PE0_TX_C_DP<4>")
	)
	(segment
		(start 338.704682 -415.777934)
		(end 336.966814 -424.18508)
		(width 0.14732)
		(layer "In11.Cu")
		(net "P5E_CPU0_PE0_TX_C_DP<4>")
	)
	(segment
		(start 339.38972 -413.065976)
		(end 339.301328 -413.49422)
		(width 0.14732)
		(layer "In11.Cu")
		(net "P5E_CPU0_PE0_TX_C_DP<4>")
	)
	(segment
		(start 339.068664 -414.016698)
		(end 339.163406 -414.160716)
		(width 0.14732)
		(layer "In11.Cu")
		(net "P5E_CPU0_PE0_TX_C_DP<4>")
	)
	(segment
		(start 337.502246 -431.119534)
		(end 337.650074 -430.971706)
		(width 0.14732)
		(layer "In11.Cu")
		(net "P5E_CPU0_PE0_TX_C_DP<4>")
	)
	(segment
		(start 339.163406 -414.160716)
		(end 339.075014 -414.58896)
		(width 0.14732)
		(layer "In11.Cu")
		(net "P5E_CPU0_PE0_TX_C_DP<4>")
	)
	(segment
		(start 338.704428 -415.777934)
		(end 338.704682 -415.777934)
		(width 0.14732)
		(layer "In11.Cu")
		(net "P5E_CPU0_PE0_TX_C_DP<4>")
	)
	(segment
		(start 342.64727 -409.110942)
		(end 342.974168 -408.784044)
		(width 0.13208)
		(layer "F.Cu")
		(net "P5E_CPU0_PE0_TX_C_DP<3>")
	)
	(segment
		(start 342.64727 -409.72867)
		(end 342.64727 -409.110942)
		(width 0.13208)
		(layer "F.Cu")
		(net "P5E_CPU0_PE0_TX_C_DP<3>")
	)
	(segment
		(start 342.948768 -410.030168)
		(end 342.64727 -409.72867)
		(width 0.13208)
		(layer "F.Cu")
		(net "P5E_CPU0_PE0_TX_C_DP<3>")
	)
	(segment
		(start 342.107012 -413.740854)
		(end 342.00592 -414.095438)
		(width 0.14732)
		(layer "In11.Cu")
		(net "P5E_CPU0_PE0_TX_C_DP<3>")
	)
	(segment
		(start 339.65007 -429.971708)
		(end 339.65007 -429.689768)
		(width 0.14732)
		(layer "In11.Cu")
		(net "P5E_CPU0_PE0_TX_C_DP<3>")
	)
	(segment
		(start 339.090762 -430.119536)
		(end 339.502242 -430.119536)
		(width 0.14732)
		(layer "In11.Cu")
		(net "P5E_CPU0_PE0_TX_C_DP<3>")
	)
	(segment
		(start 339.502242 -430.119536)
		(end 339.65007 -429.971708)
		(width 0.14732)
		(layer "In11.Cu")
		(net "P5E_CPU0_PE0_TX_C_DP<3>")
	)
	(segment
		(start 342.654128 -411.29712)
		(end 342.57107 -411.588204)
		(width 0.14732)
		(layer "In11.Cu")
		(net "P5E_CPU0_PE0_TX_C_DP<3>")
	)
	(segment
		(start 342.569546 -412.121604)
		(end 342.390222 -412.221172)
		(width 0.14732)
		(layer "In11.Cu")
		(net "P5E_CPU0_PE0_TX_C_DP<3>")
	)
	(segment
		(start 342.670638 -411.767274)
		(end 342.569546 -412.121604)
		(width 0.14732)
		(layer "In11.Cu")
		(net "P5E_CPU0_PE0_TX_C_DP<3>")
	)
	(segment
		(start 338.96681 -429.995584)
		(end 339.090762 -430.119536)
		(width 0.14732)
		(layer "In11.Cu")
		(net "P5E_CPU0_PE0_TX_C_DP<3>")
	)
	(segment
		(start 342.28913 -412.575248)
		(end 342.388698 -412.754064)
		(width 0.14732)
		(layer "In11.Cu")
		(net "P5E_CPU0_PE0_TX_C_DP<3>")
	)
	(segment
		(start 342.007444 -413.562038)
		(end 342.107012 -413.740854)
		(width 0.14732)
		(layer "In11.Cu")
		(net "P5E_CPU0_PE0_TX_C_DP<3>")
	)
	(segment
		(start 342.57107 -411.588204)
		(end 342.670638 -411.767274)
		(width 0.14732)
		(layer "In11.Cu")
		(net "P5E_CPU0_PE0_TX_C_DP<3>")
	)
	(segment
		(start 342.390222 -412.221172)
		(end 342.28913 -412.575248)
		(width 0.14732)
		(layer "In11.Cu")
		(net "P5E_CPU0_PE0_TX_C_DP<3>")
	)
	(segment
		(start 341.726012 -414.548828)
		(end 341.82558 -414.727644)
		(width 0.14732)
		(layer "In11.Cu")
		(net "P5E_CPU0_PE0_TX_C_DP<3>")
	)
	(segment
		(start 341.724488 -415.082228)
		(end 341.545418 -415.181288)
		(width 0.14732)
		(layer "In11.Cu")
		(net "P5E_CPU0_PE0_TX_C_DP<3>")
	)
	(segment
		(start 341.82558 -414.727644)
		(end 341.724488 -415.082228)
		(width 0.14732)
		(layer "In11.Cu")
		(net "P5E_CPU0_PE0_TX_C_DP<3>")
	)
	(segment
		(start 338.96681 -424.214036)
		(end 338.96681 -429.995584)
		(width 0.14732)
		(layer "In11.Cu")
		(net "P5E_CPU0_PE0_TX_C_DP<3>")
	)
	(segment
		(start 342.108536 -413.207962)
		(end 342.007444 -413.562038)
		(width 0.14732)
		(layer "In11.Cu")
		(net "P5E_CPU0_PE0_TX_C_DP<3>")
	)
	(segment
		(start 342.948768 -410.030168)
		(end 342.654128 -410.324808)
		(width 0.14732)
		(layer "In11.Cu")
		(net "P5E_CPU0_PE0_TX_C_DP<3>")
	)
	(segment
		(start 342.00592 -414.095438)
		(end 341.827104 -414.194498)
		(width 0.14732)
		(layer "In11.Cu")
		(net "P5E_CPU0_PE0_TX_C_DP<3>")
	)
	(segment
		(start 341.545418 -415.181288)
		(end 338.96681 -424.214036)
		(width 0.14732)
		(layer "In11.Cu")
		(net "P5E_CPU0_PE0_TX_C_DP<3>")
	)
	(segment
		(start 342.287606 -413.108648)
		(end 342.108536 -413.207962)
		(width 0.14732)
		(layer "In11.Cu")
		(net "P5E_CPU0_PE0_TX_C_DP<3>")
	)
	(segment
		(start 342.388698 -412.754064)
		(end 342.287606 -413.108648)
		(width 0.14732)
		(layer "In11.Cu")
		(net "P5E_CPU0_PE0_TX_C_DP<3>")
	)
	(segment
		(start 342.654128 -410.324808)
		(end 342.654128 -411.29712)
		(width 0.14732)
		(layer "In11.Cu")
		(net "P5E_CPU0_PE0_TX_C_DP<3>")
	)
	(segment
		(start 341.827104 -414.194498)
		(end 341.726012 -414.548828)
		(width 0.14732)
		(layer "In11.Cu")
		(net "P5E_CPU0_PE0_TX_C_DP<3>")
	)
	(segment
		(start 346.012008 -410.030168)
		(end 345.71051 -409.72867)
		(width 0.13208)
		(layer "F.Cu")
		(net "P5E_CPU0_PE0_TX_C_DP<2>")
	)
	(segment
		(start 345.71051 -409.110942)
		(end 346.037408 -408.784044)
		(width 0.13208)
		(layer "F.Cu")
		(net "P5E_CPU0_PE0_TX_C_DP<2>")
	)
	(segment
		(start 345.71051 -409.72867)
		(end 345.71051 -409.110942)
		(width 0.13208)
		(layer "F.Cu")
		(net "P5E_CPU0_PE0_TX_C_DP<2>")
	)
	(segment
		(start 346.012008 -410.030168)
		(end 345.717368 -410.324808)
		(width 0.14732)
		(layer "In11.Cu")
		(net "P5E_CPU0_PE0_TX_C_DP<2>")
	)
	(segment
		(start 341.502238 -431.119534)
		(end 341.650066 -430.971706)
		(width 0.14732)
		(layer "In11.Cu")
		(net "P5E_CPU0_PE0_TX_C_DP<2>")
	)
	(segment
		(start 345.717368 -410.324808)
		(end 345.717368 -411.193742)
		(width 0.14732)
		(layer "In11.Cu")
		(net "P5E_CPU0_PE0_TX_C_DP<2>")
	)
	(segment
		(start 340.966806 -430.962562)
		(end 341.123778 -431.119534)
		(width 0.14732)
		(layer "In11.Cu")
		(net "P5E_CPU0_PE0_TX_C_DP<2>")
	)
	(segment
		(start 345.102688 -413.34182)
		(end 344.917522 -413.428942)
		(width 0.14732)
		(layer "In11.Cu")
		(net "P5E_CPU0_PE0_TX_C_DP<2>")
	)
	(segment
		(start 341.123778 -431.119534)
		(end 341.502238 -431.119534)
		(width 0.14732)
		(layer "In11.Cu")
		(net "P5E_CPU0_PE0_TX_C_DP<2>")
	)
	(segment
		(start 345.263216 -412.46298)
		(end 345.139264 -412.80969)
		(width 0.14732)
		(layer "In11.Cu")
		(net "P5E_CPU0_PE0_TX_C_DP<2>")
	)
	(segment
		(start 341.650066 -430.971706)
		(end 341.650066 -430.689766)
		(width 0.14732)
		(layer "In11.Cu")
		(net "P5E_CPU0_PE0_TX_C_DP<2>")
	)
	(segment
		(start 345.226894 -412.994602)
		(end 345.102688 -413.34182)
		(width 0.14732)
		(layer "In11.Cu")
		(net "P5E_CPU0_PE0_TX_C_DP<2>")
	)
	(segment
		(start 345.448382 -412.37535)
		(end 345.263216 -412.46298)
		(width 0.14732)
		(layer "In11.Cu")
		(net "P5E_CPU0_PE0_TX_C_DP<2>")
	)
	(segment
		(start 344.917522 -413.428942)
		(end 340.966806 -424.46956)
		(width 0.14732)
		(layer "In11.Cu")
		(net "P5E_CPU0_PE0_TX_C_DP<2>")
	)
	(segment
		(start 345.572588 -412.028386)
		(end 345.448382 -412.37535)
		(width 0.14732)
		(layer "In11.Cu")
		(net "P5E_CPU0_PE0_TX_C_DP<2>")
	)
	(segment
		(start 345.484958 -411.84322)
		(end 345.572588 -412.028386)
		(width 0.14732)
		(layer "In11.Cu")
		(net "P5E_CPU0_PE0_TX_C_DP<2>")
	)
	(segment
		(start 345.717368 -411.193742)
		(end 345.484958 -411.84322)
		(width 0.14732)
		(layer "In11.Cu")
		(net "P5E_CPU0_PE0_TX_C_DP<2>")
	)
	(segment
		(start 340.966806 -424.46956)
		(end 340.966806 -430.962562)
		(width 0.14732)
		(layer "In11.Cu")
		(net "P5E_CPU0_PE0_TX_C_DP<2>")
	)
	(segment
		(start 345.139264 -412.80969)
		(end 345.226894 -412.994602)
		(width 0.14732)
		(layer "In11.Cu")
		(net "P5E_CPU0_PE0_TX_C_DP<2>")
	)
	(segment
		(start 349.075248 -410.030168)
		(end 348.77375 -409.72867)
		(width 0.13208)
		(layer "F.Cu")
		(net "P5E_CPU0_PE0_TX_C_DP<1>")
	)
	(segment
		(start 348.77375 -409.110942)
		(end 349.100648 -408.784044)
		(width 0.13208)
		(layer "F.Cu")
		(net "P5E_CPU0_PE0_TX_C_DP<1>")
	)
	(segment
		(start 348.77375 -409.72867)
		(end 348.77375 -409.110942)
		(width 0.13208)
		(layer "F.Cu")
		(net "P5E_CPU0_PE0_TX_C_DP<1>")
	)
	(segment
		(start 348.549722 -412.035244)
		(end 348.375986 -412.43631)
		(width 0.14732)
		(layer "In11.Cu")
		(net "P5E_CPU0_PE0_TX_C_DP<1>")
	)
	(segment
		(start 348.375986 -412.43631)
		(end 348.215458 -412.49981)
		(width 0.14732)
		(layer "In11.Cu")
		(net "P5E_CPU0_PE0_TX_C_DP<1>")
	)
	(segment
		(start 348.105476 -413.060896)
		(end 347.93174 -413.461962)
		(width 0.14732)
		(layer "In11.Cu")
		(net "P5E_CPU0_PE0_TX_C_DP<1>")
	)
	(segment
		(start 348.758002 -411.247336)
		(end 348.486222 -411.87497)
		(width 0.14732)
		(layer "In11.Cu")
		(net "P5E_CPU0_PE0_TX_C_DP<1>")
	)
	(segment
		(start 342.967564 -424.612562)
		(end 342.966802 -424.6118)
		(width 0.14732)
		(layer "In11.Cu")
		(net "P5E_CPU0_PE0_TX_C_DP<1>")
	)
	(segment
		(start 347.043248 -415.513266)
		(end 346.88272 -415.576766)
		(width 0.14732)
		(layer "In11.Cu")
		(net "P5E_CPU0_PE0_TX_C_DP<1>")
	)
	(segment
		(start 342.966802 -424.6118)
		(end 342.966802 -430.007776)
		(width 0.14732)
		(layer "In11.Cu")
		(net "P5E_CPU0_PE0_TX_C_DP<1>")
	)
	(segment
		(start 347.216984 -415.1122)
		(end 347.043248 -415.513266)
		(width 0.14732)
		(layer "In11.Cu")
		(net "P5E_CPU0_PE0_TX_C_DP<1>")
	)
	(segment
		(start 347.66123 -414.086548)
		(end 347.487494 -414.487614)
		(width 0.14732)
		(layer "In11.Cu")
		(net "P5E_CPU0_PE0_TX_C_DP<1>")
	)
	(segment
		(start 348.486222 -411.87497)
		(end 348.549722 -412.035244)
		(width 0.14732)
		(layer "In11.Cu")
		(net "P5E_CPU0_PE0_TX_C_DP<1>")
	)
	(segment
		(start 348.041976 -412.900622)
		(end 348.105476 -413.060896)
		(width 0.14732)
		(layer "In11.Cu")
		(net "P5E_CPU0_PE0_TX_C_DP<1>")
	)
	(segment
		(start 347.59773 -413.926274)
		(end 347.66123 -414.086548)
		(width 0.14732)
		(layer "In11.Cu")
		(net "P5E_CPU0_PE0_TX_C_DP<1>")
	)
	(segment
		(start 348.780608 -410.324808)
		(end 348.780608 -411.22473)
		(width 0.14732)
		(layer "In11.Cu")
		(net "P5E_CPU0_PE0_TX_C_DP<1>")
	)
	(segment
		(start 346.88272 -415.576766)
		(end 342.968834 -424.612562)
		(width 0.14732)
		(layer "In11.Cu")
		(net "P5E_CPU0_PE0_TX_C_DP<1>")
	)
	(segment
		(start 347.487494 -414.487614)
		(end 347.326966 -414.551114)
		(width 0.14732)
		(layer "In11.Cu")
		(net "P5E_CPU0_PE0_TX_C_DP<1>")
	)
	(segment
		(start 343.650062 -429.971708)
		(end 343.650062 -429.689768)
		(width 0.14732)
		(layer "In11.Cu")
		(net "P5E_CPU0_PE0_TX_C_DP<1>")
	)
	(segment
		(start 347.326966 -414.551114)
		(end 347.153484 -414.951926)
		(width 0.14732)
		(layer "In11.Cu")
		(net "P5E_CPU0_PE0_TX_C_DP<1>")
	)
	(segment
		(start 343.078562 -430.119536)
		(end 343.502234 -430.119536)
		(width 0.14732)
		(layer "In11.Cu")
		(net "P5E_CPU0_PE0_TX_C_DP<1>")
	)
	(segment
		(start 348.215458 -412.49981)
		(end 348.041976 -412.900622)
		(width 0.14732)
		(layer "In11.Cu")
		(net "P5E_CPU0_PE0_TX_C_DP<1>")
	)
	(segment
		(start 342.968834 -424.612562)
		(end 342.967564 -424.612562)
		(width 0.14732)
		(layer "In11.Cu")
		(net "P5E_CPU0_PE0_TX_C_DP<1>")
	)
	(segment
		(start 348.780608 -411.22473)
		(end 348.758002 -411.247336)
		(width 0.14732)
		(layer "In11.Cu")
		(net "P5E_CPU0_PE0_TX_C_DP<1>")
	)
	(segment
		(start 342.966802 -430.007776)
		(end 343.078562 -430.119536)
		(width 0.14732)
		(layer "In11.Cu")
		(net "P5E_CPU0_PE0_TX_C_DP<1>")
	)
	(segment
		(start 347.153484 -414.951926)
		(end 347.216984 -415.1122)
		(width 0.14732)
		(layer "In11.Cu")
		(net "P5E_CPU0_PE0_TX_C_DP<1>")
	)
	(segment
		(start 347.771212 -413.525462)
		(end 347.59773 -413.926274)
		(width 0.14732)
		(layer "In11.Cu")
		(net "P5E_CPU0_PE0_TX_C_DP<1>")
	)
	(segment
		(start 349.075248 -410.030168)
		(end 348.780608 -410.324808)
		(width 0.14732)
		(layer "In11.Cu")
		(net "P5E_CPU0_PE0_TX_C_DP<1>")
	)
	(segment
		(start 347.93174 -413.461962)
		(end 347.771212 -413.525462)
		(width 0.14732)
		(layer "In11.Cu")
		(net "P5E_CPU0_PE0_TX_C_DP<1>")
	)
	(segment
		(start 343.502234 -430.119536)
		(end 343.650062 -429.971708)
		(width 0.14732)
		(layer "In11.Cu")
		(net "P5E_CPU0_PE0_TX_C_DP<1>")
	)
	(segment
		(start 305.88839 -409.110942)
		(end 306.215288 -408.784044)
		(width 0.13208)
		(layer "F.Cu")
		(net "P5E_CPU0_PE0_TX_C_DP<15>")
	)
	(segment
		(start 306.189888 -410.030168)
		(end 305.88839 -409.72867)
		(width 0.13208)
		(layer "F.Cu")
		(net "P5E_CPU0_PE0_TX_C_DP<15>")
	)
	(segment
		(start 305.88839 -409.72867)
		(end 305.88839 -409.110942)
		(width 0.13208)
		(layer "F.Cu")
		(net "P5E_CPU0_PE0_TX_C_DP<15>")
	)
	(segment
		(start 307.467 -414.70453)
		(end 307.399944 -414.863534)
		(width 0.14732)
		(layer "In11.Cu")
		(net "P5E_CPU0_PE0_TX_C_DP<15>")
	)
	(segment
		(start 307.888386 -415.739834)
		(end 307.82133 -415.898838)
		(width 0.14732)
		(layer "In11.Cu")
		(net "P5E_CPU0_PE0_TX_C_DP<15>")
	)
	(segment
		(start 305.895248 -411.166564)
		(end 306.300378 -412.162244)
		(width 0.14732)
		(layer "In11.Cu")
		(net "P5E_CPU0_PE0_TX_C_DP<15>")
	)
	(segment
		(start 306.880768 -413.264604)
		(end 307.045614 -413.66948)
		(width 0.14732)
		(layer "In11.Cu")
		(net "P5E_CPU0_PE0_TX_C_DP<15>")
	)
	(segment
		(start 313.263534 -429.292258)
		(end 314.090812 -430.119536)
		(width 0.14732)
		(layer "In11.Cu")
		(net "P5E_CPU0_PE0_TX_C_DP<15>")
	)
	(segment
		(start 306.557172 -412.792926)
		(end 306.721764 -413.197548)
		(width 0.14732)
		(layer "In11.Cu")
		(net "P5E_CPU0_PE0_TX_C_DP<15>")
	)
	(segment
		(start 313.2709 -429.28921)
		(end 313.267852 -429.292258)
		(width 0.14732)
		(layer "In11.Cu")
		(net "P5E_CPU0_PE0_TX_C_DP<15>")
	)
	(segment
		(start 307.564536 -415.268156)
		(end 307.72354 -415.334958)
		(width 0.14732)
		(layer "In11.Cu")
		(net "P5E_CPU0_PE0_TX_C_DP<15>")
	)
	(segment
		(start 307.72354 -415.334958)
		(end 307.888386 -415.739834)
		(width 0.14732)
		(layer "In11.Cu")
		(net "P5E_CPU0_PE0_TX_C_DP<15>")
	)
	(segment
		(start 314.502292 -430.119536)
		(end 314.65012 -429.971708)
		(width 0.14732)
		(layer "In11.Cu")
		(net "P5E_CPU0_PE0_TX_C_DP<15>")
	)
	(segment
		(start 307.82133 -415.898838)
		(end 313.2709 -429.28921)
		(width 0.14732)
		(layer "In11.Cu")
		(net "P5E_CPU0_PE0_TX_C_DP<15>")
	)
	(segment
		(start 306.459636 -412.2293)
		(end 306.624228 -412.634176)
		(width 0.14732)
		(layer "In11.Cu")
		(net "P5E_CPU0_PE0_TX_C_DP<15>")
	)
	(segment
		(start 307.302154 -414.299654)
		(end 307.467 -414.70453)
		(width 0.14732)
		(layer "In11.Cu")
		(net "P5E_CPU0_PE0_TX_C_DP<15>")
	)
	(segment
		(start 307.14315 -414.232852)
		(end 307.302154 -414.299654)
		(width 0.14732)
		(layer "In11.Cu")
		(net "P5E_CPU0_PE0_TX_C_DP<15>")
	)
	(segment
		(start 314.65012 -429.971708)
		(end 314.65012 -429.689768)
		(width 0.14732)
		(layer "In11.Cu")
		(net "P5E_CPU0_PE0_TX_C_DP<15>")
	)
	(segment
		(start 306.978558 -413.82823)
		(end 307.14315 -414.232852)
		(width 0.14732)
		(layer "In11.Cu")
		(net "P5E_CPU0_PE0_TX_C_DP<15>")
	)
	(segment
		(start 307.399944 -414.863534)
		(end 307.564536 -415.268156)
		(width 0.14732)
		(layer "In11.Cu")
		(net "P5E_CPU0_PE0_TX_C_DP<15>")
	)
	(segment
		(start 306.624228 -412.634176)
		(end 306.557172 -412.792926)
		(width 0.14732)
		(layer "In11.Cu")
		(net "P5E_CPU0_PE0_TX_C_DP<15>")
	)
	(segment
		(start 307.045614 -413.66948)
		(end 306.978558 -413.82823)
		(width 0.14732)
		(layer "In11.Cu")
		(net "P5E_CPU0_PE0_TX_C_DP<15>")
	)
	(segment
		(start 314.090812 -430.119536)
		(end 314.502292 -430.119536)
		(width 0.14732)
		(layer "In11.Cu")
		(net "P5E_CPU0_PE0_TX_C_DP<15>")
	)
	(segment
		(start 306.300378 -412.162244)
		(end 306.459636 -412.2293)
		(width 0.14732)
		(layer "In11.Cu")
		(net "P5E_CPU0_PE0_TX_C_DP<15>")
	)
	(segment
		(start 306.721764 -413.197548)
		(end 306.880768 -413.264604)
		(width 0.14732)
		(layer "In11.Cu")
		(net "P5E_CPU0_PE0_TX_C_DP<15>")
	)
	(segment
		(start 305.895248 -410.324808)
		(end 305.895248 -411.166564)
		(width 0.14732)
		(layer "In11.Cu")
		(net "P5E_CPU0_PE0_TX_C_DP<15>")
	)
	(segment
		(start 306.189888 -410.030168)
		(end 305.895248 -410.324808)
		(width 0.14732)
		(layer "In11.Cu")
		(net "P5E_CPU0_PE0_TX_C_DP<15>")
	)
	(segment
		(start 313.267852 -429.292258)
		(end 313.263534 -429.292258)
		(width 0.14732)
		(layer "In11.Cu")
		(net "P5E_CPU0_PE0_TX_C_DP<15>")
	)
	(segment
		(start 308.95163 -409.110942)
		(end 309.278528 -408.784044)
		(width 0.13208)
		(layer "F.Cu")
		(net "P5E_CPU0_PE0_TX_C_DP<14>")
	)
	(segment
		(start 309.253128 -410.030168)
		(end 308.95163 -409.72867)
		(width 0.13208)
		(layer "F.Cu")
		(net "P5E_CPU0_PE0_TX_C_DP<14>")
	)
	(segment
		(start 308.95163 -409.72867)
		(end 308.95163 -409.110942)
		(width 0.13208)
		(layer "F.Cu")
		(net "P5E_CPU0_PE0_TX_C_DP<14>")
	)
	(segment
		(start 309.683912 -412.190184)
		(end 309.683912 -412.190438)
		(width 0.14732)
		(layer "In11.Cu")
		(net "P5E_CPU0_PE0_TX_C_DP<14>")
	)
	(segment
		(start 309.983886 -412.801816)
		(end 310.176164 -413.193992)
		(width 0.14732)
		(layer "In11.Cu")
		(net "P5E_CPU0_PE0_TX_C_DP<14>")
	)
	(segment
		(start 309.253128 -410.030168)
		(end 308.958488 -410.324808)
		(width 0.14732)
		(layer "In11.Cu")
		(net "P5E_CPU0_PE0_TX_C_DP<14>")
	)
	(segment
		(start 308.958488 -410.711396)
		(end 309.683912 -412.190184)
		(width 0.14732)
		(layer "In11.Cu")
		(net "P5E_CPU0_PE0_TX_C_DP<14>")
	)
	(segment
		(start 315.966856 -424.98645)
		(end 315.966856 -430.955958)
		(width 0.14732)
		(layer "In11.Cu")
		(net "P5E_CPU0_PE0_TX_C_DP<14>")
	)
	(segment
		(start 310.176164 -413.193992)
		(end 310.339486 -413.249618)
		(width 0.14732)
		(layer "In11.Cu")
		(net "P5E_CPU0_PE0_TX_C_DP<14>")
	)
	(segment
		(start 316.130432 -431.119534)
		(end 316.502288 -431.119534)
		(width 0.14732)
		(layer "In11.Cu")
		(net "P5E_CPU0_PE0_TX_C_DP<14>")
	)
	(segment
		(start 316.650116 -430.971706)
		(end 316.650116 -430.689766)
		(width 0.14732)
		(layer "In11.Cu")
		(net "P5E_CPU0_PE0_TX_C_DP<14>")
	)
	(segment
		(start 308.958488 -410.324808)
		(end 308.958488 -410.711396)
		(width 0.14732)
		(layer "In11.Cu")
		(net "P5E_CPU0_PE0_TX_C_DP<14>")
	)
	(segment
		(start 315.960506 -424.986196)
		(end 315.966602 -424.986196)
		(width 0.14732)
		(layer "In11.Cu")
		(net "P5E_CPU0_PE0_TX_C_DP<14>")
	)
	(segment
		(start 310.476138 -413.80537)
		(end 315.960506 -424.986196)
		(width 0.14732)
		(layer "In11.Cu")
		(net "P5E_CPU0_PE0_TX_C_DP<14>")
	)
	(segment
		(start 309.683912 -412.190438)
		(end 309.847234 -412.246064)
		(width 0.14732)
		(layer "In11.Cu")
		(net "P5E_CPU0_PE0_TX_C_DP<14>")
	)
	(segment
		(start 316.502288 -431.119534)
		(end 316.650116 -430.971706)
		(width 0.14732)
		(layer "In11.Cu")
		(net "P5E_CPU0_PE0_TX_C_DP<14>")
	)
	(segment
		(start 315.966602 -424.986196)
		(end 315.966856 -424.98645)
		(width 0.14732)
		(layer "In11.Cu")
		(net "P5E_CPU0_PE0_TX_C_DP<14>")
	)
	(segment
		(start 309.847234 -412.246064)
		(end 310.039766 -412.638494)
		(width 0.14732)
		(layer "In11.Cu")
		(net "P5E_CPU0_PE0_TX_C_DP<14>")
	)
	(segment
		(start 310.532018 -413.642302)
		(end 310.476138 -413.80537)
		(width 0.14732)
		(layer "In11.Cu")
		(net "P5E_CPU0_PE0_TX_C_DP<14>")
	)
	(segment
		(start 315.966856 -430.955958)
		(end 316.130432 -431.119534)
		(width 0.14732)
		(layer "In11.Cu")
		(net "P5E_CPU0_PE0_TX_C_DP<14>")
	)
	(segment
		(start 310.039766 -412.638494)
		(end 309.983886 -412.801816)
		(width 0.14732)
		(layer "In11.Cu")
		(net "P5E_CPU0_PE0_TX_C_DP<14>")
	)
	(segment
		(start 310.339486 -413.249618)
		(end 310.532018 -413.642302)
		(width 0.14732)
		(layer "In11.Cu")
		(net "P5E_CPU0_PE0_TX_C_DP<14>")
	)
	(segment
		(start 312.01487 -409.110942)
		(end 312.341768 -408.784044)
		(width 0.13208)
		(layer "F.Cu")
		(net "P5E_CPU0_PE0_TX_C_DP<13>")
	)
	(segment
		(start 312.01487 -409.72867)
		(end 312.01487 -409.110942)
		(width 0.13208)
		(layer "F.Cu")
		(net "P5E_CPU0_PE0_TX_C_DP<13>")
	)
	(segment
		(start 312.316368 -410.030168)
		(end 312.01487 -409.72867)
		(width 0.13208)
		(layer "F.Cu")
		(net "P5E_CPU0_PE0_TX_C_DP<13>")
	)
	(segment
		(start 313.24931 -413.754062)
		(end 313.43981 -413.830008)
		(width 0.14732)
		(layer "In11.Cu")
		(net "P5E_CPU0_PE0_TX_C_DP<13>")
	)
	(segment
		(start 317.966852 -429.995584)
		(end 318.090804 -430.119536)
		(width 0.14732)
		(layer "In11.Cu")
		(net "P5E_CPU0_PE0_TX_C_DP<13>")
	)
	(segment
		(start 318.502284 -430.119536)
		(end 318.650112 -429.971708)
		(width 0.14732)
		(layer "In11.Cu")
		(net "P5E_CPU0_PE0_TX_C_DP<13>")
	)
	(segment
		(start 313.914028 -415.301938)
		(end 317.966852 -424.74388)
		(width 0.14732)
		(layer "In11.Cu")
		(net "P5E_CPU0_PE0_TX_C_DP<13>")
	)
	(segment
		(start 312.630058 -411.943804)
		(end 312.775346 -412.282386)
		(width 0.14732)
		(layer "In11.Cu")
		(net "P5E_CPU0_PE0_TX_C_DP<13>")
	)
	(segment
		(start 313.43981 -413.830008)
		(end 313.585098 -414.16859)
		(width 0.14732)
		(layer "In11.Cu")
		(net "P5E_CPU0_PE0_TX_C_DP<13>")
	)
	(segment
		(start 317.966852 -424.74388)
		(end 317.966852 -429.995584)
		(width 0.14732)
		(layer "In11.Cu")
		(net "P5E_CPU0_PE0_TX_C_DP<13>")
	)
	(segment
		(start 312.844434 -412.81096)
		(end 313.034934 -412.886906)
		(width 0.14732)
		(layer "In11.Cu")
		(net "P5E_CPU0_PE0_TX_C_DP<13>")
	)
	(segment
		(start 313.654186 -414.697164)
		(end 313.844686 -414.77311)
		(width 0.14732)
		(layer "In11.Cu")
		(net "P5E_CPU0_PE0_TX_C_DP<13>")
	)
	(segment
		(start 312.021728 -410.324808)
		(end 312.021728 -410.832808)
		(width 0.14732)
		(layer "In11.Cu")
		(net "P5E_CPU0_PE0_TX_C_DP<13>")
	)
	(segment
		(start 313.585098 -414.16859)
		(end 313.509152 -414.358836)
		(width 0.14732)
		(layer "In11.Cu")
		(net "P5E_CPU0_PE0_TX_C_DP<13>")
	)
	(segment
		(start 313.989974 -415.111692)
		(end 313.914028 -415.301938)
		(width 0.14732)
		(layer "In11.Cu")
		(net "P5E_CPU0_PE0_TX_C_DP<13>")
	)
	(segment
		(start 313.180222 -413.225488)
		(end 313.104276 -413.415734)
		(width 0.14732)
		(layer "In11.Cu")
		(net "P5E_CPU0_PE0_TX_C_DP<13>")
	)
	(segment
		(start 312.775346 -412.282386)
		(end 312.6994 -412.472632)
		(width 0.14732)
		(layer "In11.Cu")
		(net "P5E_CPU0_PE0_TX_C_DP<13>")
	)
	(segment
		(start 312.6994 -412.472632)
		(end 312.844434 -412.81096)
		(width 0.14732)
		(layer "In11.Cu")
		(net "P5E_CPU0_PE0_TX_C_DP<13>")
	)
	(segment
		(start 313.034934 -412.886906)
		(end 313.180222 -413.225488)
		(width 0.14732)
		(layer "In11.Cu")
		(net "P5E_CPU0_PE0_TX_C_DP<13>")
	)
	(segment
		(start 318.650112 -429.971708)
		(end 318.650112 -429.689768)
		(width 0.14732)
		(layer "In11.Cu")
		(net "P5E_CPU0_PE0_TX_C_DP<13>")
	)
	(segment
		(start 312.439558 -411.867858)
		(end 312.630058 -411.943804)
		(width 0.14732)
		(layer "In11.Cu")
		(net "P5E_CPU0_PE0_TX_C_DP<13>")
	)
	(segment
		(start 313.844686 -414.77311)
		(end 313.989974 -415.111692)
		(width 0.14732)
		(layer "In11.Cu")
		(net "P5E_CPU0_PE0_TX_C_DP<13>")
	)
	(segment
		(start 313.104276 -413.415734)
		(end 313.24931 -413.754062)
		(width 0.14732)
		(layer "In11.Cu")
		(net "P5E_CPU0_PE0_TX_C_DP<13>")
	)
	(segment
		(start 318.090804 -430.119536)
		(end 318.502284 -430.119536)
		(width 0.14732)
		(layer "In11.Cu")
		(net "P5E_CPU0_PE0_TX_C_DP<13>")
	)
	(segment
		(start 312.021728 -410.832808)
		(end 312.318908 -411.58668)
		(width 0.14732)
		(layer "In11.Cu")
		(net "P5E_CPU0_PE0_TX_C_DP<13>")
	)
	(segment
		(start 312.316368 -410.030168)
		(end 312.021728 -410.324808)
		(width 0.14732)
		(layer "In11.Cu")
		(net "P5E_CPU0_PE0_TX_C_DP<13>")
	)
	(segment
		(start 313.509152 -414.358836)
		(end 313.654186 -414.697164)
		(width 0.14732)
		(layer "In11.Cu")
		(net "P5E_CPU0_PE0_TX_C_DP<13>")
	)
	(segment
		(start 312.318908 -411.58668)
		(end 312.439558 -411.867858)
		(width 0.14732)
		(layer "In11.Cu")
		(net "P5E_CPU0_PE0_TX_C_DP<13>")
	)
	(segment
		(start 315.379608 -410.030168)
		(end 315.07811 -409.72867)
		(width 0.13208)
		(layer "F.Cu")
		(net "P5E_CPU0_PE0_TX_C_DP<12>")
	)
	(segment
		(start 315.07811 -409.110942)
		(end 315.405008 -408.784044)
		(width 0.13208)
		(layer "F.Cu")
		(net "P5E_CPU0_PE0_TX_C_DP<12>")
	)
	(segment
		(start 315.07811 -409.72867)
		(end 315.07811 -409.110942)
		(width 0.13208)
		(layer "F.Cu")
		(net "P5E_CPU0_PE0_TX_C_DP<12>")
	)
	(segment
		(start 315.719968 -412.366968)
		(end 315.629036 -412.550356)
		(width 0.14732)
		(layer "In11.Cu")
		(net "P5E_CPU0_PE0_TX_C_DP<12>")
	)
	(segment
		(start 320.50228 -431.119534)
		(end 320.650108 -430.971706)
		(width 0.14732)
		(layer "In11.Cu")
		(net "P5E_CPU0_PE0_TX_C_DP<12>")
	)
	(segment
		(start 320.118232 -431.119534)
		(end 320.50228 -431.119534)
		(width 0.14732)
		(layer "In11.Cu")
		(net "P5E_CPU0_PE0_TX_C_DP<12>")
	)
	(segment
		(start 315.379608 -410.030168)
		(end 315.084968 -410.324808)
		(width 0.14732)
		(layer "In11.Cu")
		(net "P5E_CPU0_PE0_TX_C_DP<12>")
	)
	(segment
		(start 315.956696 -413.522922)
		(end 319.966848 -425.432474)
		(width 0.14732)
		(layer "In11.Cu")
		(net "P5E_CPU0_PE0_TX_C_DP<12>")
	)
	(segment
		(start 320.650108 -430.971706)
		(end 320.650108 -430.689766)
		(width 0.14732)
		(layer "In11.Cu")
		(net "P5E_CPU0_PE0_TX_C_DP<12>")
	)
	(segment
		(start 315.930026 -412.990284)
		(end 316.047628 -413.339534)
		(width 0.14732)
		(layer "In11.Cu")
		(net "P5E_CPU0_PE0_TX_C_DP<12>")
	)
	(segment
		(start 315.418724 -411.926532)
		(end 315.602366 -412.017718)
		(width 0.14732)
		(layer "In11.Cu")
		(net "P5E_CPU0_PE0_TX_C_DP<12>")
	)
	(segment
		(start 319.966848 -430.96815)
		(end 320.118232 -431.119534)
		(width 0.14732)
		(layer "In11.Cu")
		(net "P5E_CPU0_PE0_TX_C_DP<12>")
	)
	(segment
		(start 315.084968 -410.9339)
		(end 315.418724 -411.926532)
		(width 0.14732)
		(layer "In11.Cu")
		(net "P5E_CPU0_PE0_TX_C_DP<12>")
	)
	(segment
		(start 315.602366 -412.017718)
		(end 315.719968 -412.366968)
		(width 0.14732)
		(layer "In11.Cu")
		(net "P5E_CPU0_PE0_TX_C_DP<12>")
	)
	(segment
		(start 315.629036 -412.550356)
		(end 315.746384 -412.899352)
		(width 0.14732)
		(layer "In11.Cu")
		(net "P5E_CPU0_PE0_TX_C_DP<12>")
	)
	(segment
		(start 315.746384 -412.899352)
		(end 315.930026 -412.990284)
		(width 0.14732)
		(layer "In11.Cu")
		(net "P5E_CPU0_PE0_TX_C_DP<12>")
	)
	(segment
		(start 316.047628 -413.339534)
		(end 315.956696 -413.522922)
		(width 0.14732)
		(layer "In11.Cu")
		(net "P5E_CPU0_PE0_TX_C_DP<12>")
	)
	(segment
		(start 319.966848 -425.432474)
		(end 319.966848 -430.96815)
		(width 0.14732)
		(layer "In11.Cu")
		(net "P5E_CPU0_PE0_TX_C_DP<12>")
	)
	(segment
		(start 315.084968 -410.324808)
		(end 315.084968 -410.9339)
		(width 0.14732)
		(layer "In11.Cu")
		(net "P5E_CPU0_PE0_TX_C_DP<12>")
	)
	(segment
		(start 318.14135 -409.72867)
		(end 318.14135 -409.110942)
		(width 0.13208)
		(layer "F.Cu")
		(net "P5E_CPU0_PE0_TX_C_DP<11>")
	)
	(segment
		(start 318.14135 -409.110942)
		(end 318.468248 -408.784044)
		(width 0.13208)
		(layer "F.Cu")
		(net "P5E_CPU0_PE0_TX_C_DP<11>")
	)
	(segment
		(start 318.442848 -410.030168)
		(end 318.14135 -409.72867)
		(width 0.13208)
		(layer "F.Cu")
		(net "P5E_CPU0_PE0_TX_C_DP<11>")
	)
	(segment
		(start 318.875664 -413.688022)
		(end 318.969644 -414.043876)
		(width 0.14732)
		(layer "In11.Cu")
		(net "P5E_CPU0_PE0_TX_C_DP<11>")
	)
	(segment
		(start 319.400428 -415.67227)
		(end 319.400174 -415.672524)
		(width 0.14732)
		(layer "In11.Cu")
		(net "P5E_CPU0_PE0_TX_C_DP<11>")
	)
	(segment
		(start 318.44488 -412.059882)
		(end 318.621918 -412.162498)
		(width 0.14732)
		(layer "In11.Cu")
		(net "P5E_CPU0_PE0_TX_C_DP<11>")
	)
	(segment
		(start 322.650104 -429.971708)
		(end 322.650104 -429.689768)
		(width 0.14732)
		(layer "In11.Cu")
		(net "P5E_CPU0_PE0_TX_C_DP<11>")
	)
	(segment
		(start 318.969644 -414.043876)
		(end 319.146936 -414.147)
		(width 0.14732)
		(layer "In11.Cu")
		(net "P5E_CPU0_PE0_TX_C_DP<11>")
	)
	(segment
		(start 319.409318 -415.139124)
		(end 319.503552 -415.495486)
		(width 0.14732)
		(layer "In11.Cu")
		(net "P5E_CPU0_PE0_TX_C_DP<11>")
	)
	(segment
		(start 318.884554 -413.154876)
		(end 318.978788 -413.510984)
		(width 0.14732)
		(layer "In11.Cu")
		(net "P5E_CPU0_PE0_TX_C_DP<11>")
	)
	(segment
		(start 319.138046 -414.680146)
		(end 319.232026 -415.036)
		(width 0.14732)
		(layer "In11.Cu")
		(net "P5E_CPU0_PE0_TX_C_DP<11>")
	)
	(segment
		(start 318.148208 -410.324808)
		(end 318.148208 -410.938472)
		(width 0.14732)
		(layer "In11.Cu")
		(net "P5E_CPU0_PE0_TX_C_DP<11>")
	)
	(segment
		(start 321.966844 -429.995584)
		(end 322.090796 -430.119536)
		(width 0.14732)
		(layer "In11.Cu")
		(net "P5E_CPU0_PE0_TX_C_DP<11>")
	)
	(segment
		(start 318.442848 -410.030168)
		(end 318.148208 -410.324808)
		(width 0.14732)
		(layer "In11.Cu")
		(net "P5E_CPU0_PE0_TX_C_DP<11>")
	)
	(segment
		(start 322.502276 -430.119536)
		(end 322.650104 -429.971708)
		(width 0.14732)
		(layer "In11.Cu")
		(net "P5E_CPU0_PE0_TX_C_DP<11>")
	)
	(segment
		(start 318.707262 -413.051752)
		(end 318.884554 -413.154876)
		(width 0.14732)
		(layer "In11.Cu")
		(net "P5E_CPU0_PE0_TX_C_DP<11>")
	)
	(segment
		(start 319.146936 -414.147)
		(end 319.24117 -414.503362)
		(width 0.14732)
		(layer "In11.Cu")
		(net "P5E_CPU0_PE0_TX_C_DP<11>")
	)
	(segment
		(start 318.621918 -412.162498)
		(end 318.716152 -412.51886)
		(width 0.14732)
		(layer "In11.Cu")
		(net "P5E_CPU0_PE0_TX_C_DP<11>")
	)
	(segment
		(start 322.090796 -430.119536)
		(end 322.502276 -430.119536)
		(width 0.14732)
		(layer "In11.Cu")
		(net "P5E_CPU0_PE0_TX_C_DP<11>")
	)
	(segment
		(start 319.503552 -415.495486)
		(end 319.400428 -415.67227)
		(width 0.14732)
		(layer "In11.Cu")
		(net "P5E_CPU0_PE0_TX_C_DP<11>")
	)
	(segment
		(start 319.400174 -415.672524)
		(end 321.966844 -425.37888)
		(width 0.14732)
		(layer "In11.Cu")
		(net "P5E_CPU0_PE0_TX_C_DP<11>")
	)
	(segment
		(start 318.978788 -413.510984)
		(end 318.875664 -413.688022)
		(width 0.14732)
		(layer "In11.Cu")
		(net "P5E_CPU0_PE0_TX_C_DP<11>")
	)
	(segment
		(start 319.24117 -414.503362)
		(end 319.138046 -414.680146)
		(width 0.14732)
		(layer "In11.Cu")
		(net "P5E_CPU0_PE0_TX_C_DP<11>")
	)
	(segment
		(start 319.232026 -415.036)
		(end 319.409318 -415.139124)
		(width 0.14732)
		(layer "In11.Cu")
		(net "P5E_CPU0_PE0_TX_C_DP<11>")
	)
	(segment
		(start 318.716152 -412.51886)
		(end 318.613282 -412.695898)
		(width 0.14732)
		(layer "In11.Cu")
		(net "P5E_CPU0_PE0_TX_C_DP<11>")
	)
	(segment
		(start 318.613282 -412.695898)
		(end 318.707262 -413.051752)
		(width 0.14732)
		(layer "In11.Cu")
		(net "P5E_CPU0_PE0_TX_C_DP<11>")
	)
	(segment
		(start 321.966844 -425.37888)
		(end 321.966844 -429.995584)
		(width 0.14732)
		(layer "In11.Cu")
		(net "P5E_CPU0_PE0_TX_C_DP<11>")
	)
	(segment
		(start 318.148208 -410.938472)
		(end 318.44488 -412.059882)
		(width 0.14732)
		(layer "In11.Cu")
		(net "P5E_CPU0_PE0_TX_C_DP<11>")
	)
	(segment
		(start 321.506088 -410.030168)
		(end 321.20459 -409.72867)
		(width 0.13208)
		(layer "F.Cu")
		(net "P5E_CPU0_PE0_TX_C_DP<10>")
	)
	(segment
		(start 321.20459 -409.110942)
		(end 321.531488 -408.784044)
		(width 0.13208)
		(layer "F.Cu")
		(net "P5E_CPU0_PE0_TX_C_DP<10>")
	)
	(segment
		(start 321.20459 -409.72867)
		(end 321.20459 -409.110942)
		(width 0.13208)
		(layer "F.Cu")
		(net "P5E_CPU0_PE0_TX_C_DP<10>")
	)
	(segment
		(start 323.96684 -430.929542)
		(end 324.156832 -431.119534)
		(width 0.14732)
		(layer "In11.Cu")
		(net "P5E_CPU0_PE0_TX_C_DP<10>")
	)
	(segment
		(start 321.91198 -414.073848)
		(end 321.99199 -414.503108)
		(width 0.14732)
		(layer "In11.Cu")
		(net "P5E_CPU0_PE0_TX_C_DP<10>")
	)
	(segment
		(start 321.99199 -414.503108)
		(end 322.13423 -414.600644)
		(width 0.14732)
		(layer "In11.Cu")
		(net "P5E_CPU0_PE0_TX_C_DP<10>")
	)
	(segment
		(start 321.506088 -410.030168)
		(end 321.211448 -410.324808)
		(width 0.14732)
		(layer "In11.Cu")
		(net "P5E_CPU0_PE0_TX_C_DP<10>")
	)
	(segment
		(start 322.214494 -415.030412)
		(end 322.116958 -415.172652)
		(width 0.14732)
		(layer "In11.Cu")
		(net "P5E_CPU0_PE0_TX_C_DP<10>")
	)
	(segment
		(start 321.787012 -413.404558)
		(end 321.929506 -413.50184)
		(width 0.14732)
		(layer "In11.Cu")
		(net "P5E_CPU0_PE0_TX_C_DP<10>")
	)
	(segment
		(start 321.929506 -413.50184)
		(end 322.009516 -413.931608)
		(width 0.14732)
		(layer "In11.Cu")
		(net "P5E_CPU0_PE0_TX_C_DP<10>")
	)
	(segment
		(start 324.6501 -430.971706)
		(end 324.6501 -430.689766)
		(width 0.14732)
		(layer "In11.Cu")
		(net "P5E_CPU0_PE0_TX_C_DP<10>")
	)
	(segment
		(start 324.156832 -431.119534)
		(end 324.502272 -431.119534)
		(width 0.14732)
		(layer "In11.Cu")
		(net "P5E_CPU0_PE0_TX_C_DP<10>")
	)
	(segment
		(start 321.211448 -410.324808)
		(end 321.211448 -410.846778)
		(width 0.14732)
		(layer "In11.Cu")
		(net "P5E_CPU0_PE0_TX_C_DP<10>")
	)
	(segment
		(start 321.211448 -410.846778)
		(end 321.656202 -412.702502)
		(width 0.14732)
		(layer "In11.Cu")
		(net "P5E_CPU0_PE0_TX_C_DP<10>")
	)
	(segment
		(start 323.96684 -425.099226)
		(end 323.96684 -430.929542)
		(width 0.14732)
		(layer "In11.Cu")
		(net "P5E_CPU0_PE0_TX_C_DP<10>")
	)
	(segment
		(start 321.656202 -412.702502)
		(end 321.787012 -413.404558)
		(width 0.14732)
		(layer "In11.Cu")
		(net "P5E_CPU0_PE0_TX_C_DP<10>")
	)
	(segment
		(start 322.009516 -413.931608)
		(end 321.91198 -414.073848)
		(width 0.14732)
		(layer "In11.Cu")
		(net "P5E_CPU0_PE0_TX_C_DP<10>")
	)
	(segment
		(start 322.13423 -414.600644)
		(end 322.214494 -415.030412)
		(width 0.14732)
		(layer "In11.Cu")
		(net "P5E_CPU0_PE0_TX_C_DP<10>")
	)
	(segment
		(start 322.116958 -415.172652)
		(end 323.96684 -425.099226)
		(width 0.14732)
		(layer "In11.Cu")
		(net "P5E_CPU0_PE0_TX_C_DP<10>")
	)
	(segment
		(start 324.502272 -431.119534)
		(end 324.6501 -430.971706)
		(width 0.14732)
		(layer "In11.Cu")
		(net "P5E_CPU0_PE0_TX_C_DP<10>")
	)
	(segment
		(start 352.138488 -410.030168)
		(end 351.83699 -409.72867)
		(width 0.13208)
		(layer "F.Cu")
		(net "P5E_CPU0_PE0_TX_C_DP<0>")
	)
	(segment
		(start 351.83699 -409.72867)
		(end 351.83699 -409.110942)
		(width 0.13208)
		(layer "F.Cu")
		(net "P5E_CPU0_PE0_TX_C_DP<0>")
	)
	(segment
		(start 351.83699 -409.110942)
		(end 352.163888 -408.784044)
		(width 0.13208)
		(layer "F.Cu")
		(net "P5E_CPU0_PE0_TX_C_DP<0>")
	)
	(segment
		(start 351.843848 -411.08376)
		(end 351.534476 -411.694376)
		(width 0.14732)
		(layer "In11.Cu")
		(net "P5E_CPU0_PE0_TX_C_DP<0>")
	)
	(segment
		(start 351.070672 -412.610046)
		(end 351.134426 -412.80461)
		(width 0.14732)
		(layer "In11.Cu")
		(net "P5E_CPU0_PE0_TX_C_DP<0>")
	)
	(segment
		(start 344.966798 -431.000154)
		(end 345.086178 -431.119534)
		(width 0.14732)
		(layer "In11.Cu")
		(net "P5E_CPU0_PE0_TX_C_DP<0>")
	)
	(segment
		(start 351.534476 -411.694376)
		(end 351.59823 -411.88894)
		(width 0.14732)
		(layer "In11.Cu")
		(net "P5E_CPU0_PE0_TX_C_DP<0>")
	)
	(segment
		(start 352.138488 -410.030168)
		(end 351.843848 -410.324808)
		(width 0.14732)
		(layer "In11.Cu")
		(net "P5E_CPU0_PE0_TX_C_DP<0>")
	)
	(segment
		(start 345.650058 -430.971706)
		(end 345.650058 -430.689766)
		(width 0.14732)
		(layer "In11.Cu")
		(net "P5E_CPU0_PE0_TX_C_DP<0>")
	)
	(segment
		(start 345.50223 -431.119534)
		(end 345.650058 -430.971706)
		(width 0.14732)
		(layer "In11.Cu")
		(net "P5E_CPU0_PE0_TX_C_DP<0>")
	)
	(segment
		(start 344.966798 -424.66006)
		(end 344.966798 -431.000154)
		(width 0.14732)
		(layer "In11.Cu")
		(net "P5E_CPU0_PE0_TX_C_DP<0>")
	)
	(segment
		(start 351.237042 -412.281624)
		(end 351.070672 -412.610046)
		(width 0.14732)
		(layer "In11.Cu")
		(net "P5E_CPU0_PE0_TX_C_DP<0>")
	)
	(segment
		(start 351.43186 -412.21787)
		(end 351.237042 -412.281624)
		(width 0.14732)
		(layer "In11.Cu")
		(net "P5E_CPU0_PE0_TX_C_DP<0>")
	)
	(segment
		(start 350.773238 -413.197294)
		(end 344.966798 -424.66006)
		(width 0.14732)
		(layer "In11.Cu")
		(net "P5E_CPU0_PE0_TX_C_DP<0>")
	)
	(segment
		(start 345.086178 -431.119534)
		(end 345.50223 -431.119534)
		(width 0.14732)
		(layer "In11.Cu")
		(net "P5E_CPU0_PE0_TX_C_DP<0>")
	)
	(segment
		(start 351.843848 -410.324808)
		(end 351.843848 -411.08376)
		(width 0.14732)
		(layer "In11.Cu")
		(net "P5E_CPU0_PE0_TX_C_DP<0>")
	)
	(segment
		(start 350.968056 -413.13354)
		(end 350.773238 -413.197294)
		(width 0.14732)
		(layer "In11.Cu")
		(net "P5E_CPU0_PE0_TX_C_DP<0>")
	)
	(segment
		(start 351.59823 -411.88894)
		(end 351.43186 -412.21787)
		(width 0.14732)
		(layer "In11.Cu")
		(net "P5E_CPU0_PE0_TX_C_DP<0>")
	)
	(segment
		(start 351.134426 -412.80461)
		(end 350.968056 -413.13354)
		(width 0.14732)
		(layer "In11.Cu")
		(net "P5E_CPU0_PE0_TX_C_DP<0>")
	)
	(segment
		(start 323.705728 -410.030168)
		(end 324.00875 -409.727146)
		(width 0.13208)
		(layer "F.Cu")
		(net "P5E_CPU0_PE0_TX_C_DN<9>")
	)
	(segment
		(start 324.00875 -409.727146)
		(end 324.00875 -409.109164)
		(width 0.13208)
		(layer "F.Cu")
		(net "P5E_CPU0_PE0_TX_C_DN<9>")
	)
	(segment
		(start 324.00875 -409.109164)
		(end 323.68363 -408.784044)
		(width 0.13208)
		(layer "F.Cu")
		(net "P5E_CPU0_PE0_TX_C_DN<9>")
	)
	(segment
		(start 323.68363 -408.784044)
		(end 323.680328 -408.784044)
		(width 0.13208)
		(layer "F.Cu")
		(net "P5E_CPU0_PE0_TX_C_DN<9>")
	)
	(segment
		(start 324.000368 -410.324808)
		(end 323.705728 -410.030168)
		(width 0.14732)
		(layer "In11.Cu")
		(net "P5E_CPU0_PE0_TX_C_DN<9>")
	)
	(segment
		(start 324.000368 -410.74086)
		(end 324.000368 -410.324808)
		(width 0.14732)
		(layer "In11.Cu")
		(net "P5E_CPU0_PE0_TX_C_DN<9>")
	)
	(segment
		(start 325.692516 -426.023532)
		(end 324.000368 -410.74086)
		(width 0.14732)
		(layer "In11.Cu")
		(net "P5E_CPU0_PE0_TX_C_DN<9>")
	)
	(segment
		(start 326.463152 -430.393856)
		(end 325.976996 -430.393856)
		(width 0.14732)
		(layer "In11.Cu")
		(net "P5E_CPU0_PE0_TX_C_DN<9>")
	)
	(segment
		(start 326.650096 -430.889918)
		(end 326.650096 -430.5808)
		(width 0.14732)
		(layer "In11.Cu")
		(net "P5E_CPU0_PE0_TX_C_DN<9>")
	)
	(segment
		(start 325.692516 -430.109376)
		(end 325.692516 -426.023532)
		(width 0.14732)
		(layer "In11.Cu")
		(net "P5E_CPU0_PE0_TX_C_DN<9>")
	)
	(segment
		(start 326.650096 -430.5808)
		(end 326.463152 -430.393856)
		(width 0.14732)
		(layer "In11.Cu")
		(net "P5E_CPU0_PE0_TX_C_DN<9>")
	)
	(segment
		(start 325.976996 -430.393856)
		(end 325.692516 -430.109376)
		(width 0.14732)
		(layer "In11.Cu")
		(net "P5E_CPU0_PE0_TX_C_DN<9>")
	)
	(segment
		(start 327.07199 -409.109164)
		(end 326.74687 -408.784044)
		(width 0.13208)
		(layer "F.Cu")
		(net "P5E_CPU0_PE0_TX_C_DN<8>")
	)
	(segment
		(start 326.74687 -408.784044)
		(end 326.743568 -408.784044)
		(width 0.13208)
		(layer "F.Cu")
		(net "P5E_CPU0_PE0_TX_C_DN<8>")
	)
	(segment
		(start 327.07199 -409.727146)
		(end 327.07199 -409.109164)
		(width 0.13208)
		(layer "F.Cu")
		(net "P5E_CPU0_PE0_TX_C_DN<8>")
	)
	(segment
		(start 326.768968 -410.030168)
		(end 327.07199 -409.727146)
		(width 0.13208)
		(layer "F.Cu")
		(net "P5E_CPU0_PE0_TX_C_DN<8>")
	)
	(segment
		(start 327.98004 -431.393854)
		(end 327.692512 -431.106326)
		(width 0.14732)
		(layer "In11.Cu")
		(net "P5E_CPU0_PE0_TX_C_DN<8>")
	)
	(segment
		(start 327.063608 -410.324808)
		(end 326.768968 -410.030168)
		(width 0.14732)
		(layer "In11.Cu")
		(net "P5E_CPU0_PE0_TX_C_DN<8>")
	)
	(segment
		(start 328.650092 -431.580798)
		(end 328.463148 -431.393854)
		(width 0.14732)
		(layer "In11.Cu")
		(net "P5E_CPU0_PE0_TX_C_DN<8>")
	)
	(segment
		(start 328.463148 -431.393854)
		(end 327.98004 -431.393854)
		(width 0.14732)
		(layer "In11.Cu")
		(net "P5E_CPU0_PE0_TX_C_DN<8>")
	)
	(segment
		(start 328.650092 -431.889916)
		(end 328.650092 -431.580798)
		(width 0.14732)
		(layer "In11.Cu")
		(net "P5E_CPU0_PE0_TX_C_DN<8>")
	)
	(segment
		(start 327.692512 -431.106326)
		(end 327.692512 -424.493182)
		(width 0.14732)
		(layer "In11.Cu")
		(net "P5E_CPU0_PE0_TX_C_DN<8>")
	)
	(segment
		(start 327.692512 -424.493182)
		(end 327.063608 -410.985716)
		(width 0.14732)
		(layer "In11.Cu")
		(net "P5E_CPU0_PE0_TX_C_DN<8>")
	)
	(segment
		(start 327.063608 -410.985716)
		(end 327.063608 -410.324808)
		(width 0.14732)
		(layer "In11.Cu")
		(net "P5E_CPU0_PE0_TX_C_DN<8>")
	)
	(segment
		(start 330.13523 -409.109164)
		(end 329.81011 -408.784044)
		(width 0.13208)
		(layer "F.Cu")
		(net "P5E_CPU0_PE0_TX_C_DN<7>")
	)
	(segment
		(start 330.13523 -409.727146)
		(end 330.13523 -409.109164)
		(width 0.13208)
		(layer "F.Cu")
		(net "P5E_CPU0_PE0_TX_C_DN<7>")
	)
	(segment
		(start 329.81011 -408.784044)
		(end 329.806808 -408.784044)
		(width 0.13208)
		(layer "F.Cu")
		(net "P5E_CPU0_PE0_TX_C_DN<7>")
	)
	(segment
		(start 329.832208 -410.030168)
		(end 330.13523 -409.727146)
		(width 0.13208)
		(layer "F.Cu")
		(net "P5E_CPU0_PE0_TX_C_DN<7>")
	)
	(segment
		(start 330.54036 -424.666918)
		(end 330.126848 -410.770578)
		(width 0.14732)
		(layer "In11.Cu")
		(net "P5E_CPU0_PE0_TX_C_DN<7>")
	)
	(segment
		(start 330.126848 -410.770578)
		(end 330.126848 -410.324808)
		(width 0.14732)
		(layer "In11.Cu")
		(net "P5E_CPU0_PE0_TX_C_DN<7>")
	)
	(segment
		(start 330.976986 -430.393856)
		(end 330.54036 -429.95723)
		(width 0.14732)
		(layer "In11.Cu")
		(net "P5E_CPU0_PE0_TX_C_DN<7>")
	)
	(segment
		(start 331.463142 -430.393856)
		(end 330.976986 -430.393856)
		(width 0.14732)
		(layer "In11.Cu")
		(net "P5E_CPU0_PE0_TX_C_DN<7>")
	)
	(segment
		(start 330.126848 -410.324808)
		(end 329.832208 -410.030168)
		(width 0.14732)
		(layer "In11.Cu")
		(net "P5E_CPU0_PE0_TX_C_DN<7>")
	)
	(segment
		(start 330.54036 -429.95723)
		(end 330.54036 -424.666918)
		(width 0.14732)
		(layer "In11.Cu")
		(net "P5E_CPU0_PE0_TX_C_DN<7>")
	)
	(segment
		(start 331.650086 -430.889918)
		(end 331.650086 -430.5808)
		(width 0.14732)
		(layer "In11.Cu")
		(net "P5E_CPU0_PE0_TX_C_DN<7>")
	)
	(segment
		(start 331.650086 -430.5808)
		(end 331.463142 -430.393856)
		(width 0.14732)
		(layer "In11.Cu")
		(net "P5E_CPU0_PE0_TX_C_DN<7>")
	)
	(segment
		(start 332.895448 -410.030168)
		(end 333.19847 -409.727146)
		(width 0.13208)
		(layer "F.Cu")
		(net "P5E_CPU0_PE0_TX_C_DN<6>")
	)
	(segment
		(start 333.19847 -409.109164)
		(end 332.87335 -408.784044)
		(width 0.13208)
		(layer "F.Cu")
		(net "P5E_CPU0_PE0_TX_C_DN<6>")
	)
	(segment
		(start 332.87335 -408.784044)
		(end 332.870048 -408.784044)
		(width 0.13208)
		(layer "F.Cu")
		(net "P5E_CPU0_PE0_TX_C_DN<6>")
	)
	(segment
		(start 333.19847 -409.727146)
		(end 333.19847 -409.109164)
		(width 0.13208)
		(layer "F.Cu")
		(net "P5E_CPU0_PE0_TX_C_DN<6>")
	)
	(segment
		(start 333.650082 -431.889916)
		(end 333.650082 -431.580798)
		(width 0.14732)
		(layer "In11.Cu")
		(net "P5E_CPU0_PE0_TX_C_DN<6>")
	)
	(segment
		(start 333.650082 -431.580798)
		(end 333.463138 -431.393854)
		(width 0.14732)
		(layer "In11.Cu")
		(net "P5E_CPU0_PE0_TX_C_DN<6>")
	)
	(segment
		(start 333.190088 -410.324808)
		(end 332.895448 -410.030168)
		(width 0.14732)
		(layer "In11.Cu")
		(net "P5E_CPU0_PE0_TX_C_DN<6>")
	)
	(segment
		(start 333.463138 -431.393854)
		(end 332.983586 -431.393854)
		(width 0.14732)
		(layer "In11.Cu")
		(net "P5E_CPU0_PE0_TX_C_DN<6>")
	)
	(segment
		(start 332.983586 -431.393854)
		(end 332.692502 -431.10277)
		(width 0.14732)
		(layer "In11.Cu")
		(net "P5E_CPU0_PE0_TX_C_DN<6>")
	)
	(segment
		(start 333.190088 -413.914336)
		(end 333.190088 -410.324808)
		(width 0.14732)
		(layer "In11.Cu")
		(net "P5E_CPU0_PE0_TX_C_DN<6>")
	)
	(segment
		(start 332.692502 -424.421808)
		(end 333.190088 -413.914336)
		(width 0.14732)
		(layer "In11.Cu")
		(net "P5E_CPU0_PE0_TX_C_DN<6>")
	)
	(segment
		(start 332.692502 -431.10277)
		(end 332.692502 -424.421808)
		(width 0.14732)
		(layer "In11.Cu")
		(net "P5E_CPU0_PE0_TX_C_DN<6>")
	)
	(segment
		(start 336.26171 -409.727146)
		(end 336.26171 -409.109164)
		(width 0.13208)
		(layer "F.Cu")
		(net "P5E_CPU0_PE0_TX_C_DN<5>")
	)
	(segment
		(start 335.93659 -408.784044)
		(end 335.933288 -408.784044)
		(width 0.13208)
		(layer "F.Cu")
		(net "P5E_CPU0_PE0_TX_C_DN<5>")
	)
	(segment
		(start 335.958688 -410.030168)
		(end 336.26171 -409.727146)
		(width 0.13208)
		(layer "F.Cu")
		(net "P5E_CPU0_PE0_TX_C_DN<5>")
	)
	(segment
		(start 336.26171 -409.109164)
		(end 335.93659 -408.784044)
		(width 0.13208)
		(layer "F.Cu")
		(net "P5E_CPU0_PE0_TX_C_DN<5>")
	)
	(segment
		(start 335.463134 -430.393856)
		(end 334.976978 -430.393856)
		(width 0.14732)
		(layer "In11.Cu")
		(net "P5E_CPU0_PE0_TX_C_DN<5>")
	)
	(segment
		(start 335.650078 -430.5808)
		(end 335.463134 -430.393856)
		(width 0.14732)
		(layer "In11.Cu")
		(net "P5E_CPU0_PE0_TX_C_DN<5>")
	)
	(segment
		(start 336.253328 -411.932374)
		(end 336.253328 -410.324808)
		(width 0.14732)
		(layer "In11.Cu")
		(net "P5E_CPU0_PE0_TX_C_DN<5>")
	)
	(segment
		(start 334.692498 -424.421808)
		(end 336.253328 -411.932374)
		(width 0.14732)
		(layer "In11.Cu")
		(net "P5E_CPU0_PE0_TX_C_DN<5>")
	)
	(segment
		(start 336.253328 -410.324808)
		(end 335.958688 -410.030168)
		(width 0.14732)
		(layer "In11.Cu")
		(net "P5E_CPU0_PE0_TX_C_DN<5>")
	)
	(segment
		(start 334.976978 -430.393856)
		(end 334.692498 -430.109376)
		(width 0.14732)
		(layer "In11.Cu")
		(net "P5E_CPU0_PE0_TX_C_DN<5>")
	)
	(segment
		(start 334.692498 -430.109376)
		(end 334.692498 -424.421808)
		(width 0.14732)
		(layer "In11.Cu")
		(net "P5E_CPU0_PE0_TX_C_DN<5>")
	)
	(segment
		(start 335.650078 -430.889918)
		(end 335.650078 -430.5808)
		(width 0.14732)
		(layer "In11.Cu")
		(net "P5E_CPU0_PE0_TX_C_DN<5>")
	)
	(segment
		(start 339.021928 -410.030168)
		(end 339.32495 -409.727146)
		(width 0.13208)
		(layer "F.Cu")
		(net "P5E_CPU0_PE0_TX_C_DN<4>")
	)
	(segment
		(start 339.32495 -409.727146)
		(end 339.32495 -409.109164)
		(width 0.13208)
		(layer "F.Cu")
		(net "P5E_CPU0_PE0_TX_C_DN<4>")
	)
	(segment
		(start 338.99983 -408.784044)
		(end 338.996528 -408.784044)
		(width 0.13208)
		(layer "F.Cu")
		(net "P5E_CPU0_PE0_TX_C_DN<4>")
	)
	(segment
		(start 339.32495 -409.109164)
		(end 338.99983 -408.784044)
		(width 0.13208)
		(layer "F.Cu")
		(net "P5E_CPU0_PE0_TX_C_DN<4>")
	)
	(segment
		(start 339.301328 -411.535372)
		(end 339.301328 -410.309568)
		(width 0.14732)
		(layer "In11.Cu")
		(net "P5E_CPU0_PE0_TX_C_DN<4>")
	)
	(segment
		(start 339.301328 -410.309568)
		(end 339.021928 -410.030168)
		(width 0.14732)
		(layer "In11.Cu")
		(net "P5E_CPU0_PE0_TX_C_DN<4>")
	)
	(segment
		(start 337.650074 -431.580798)
		(end 337.46313 -431.393854)
		(width 0.14732)
		(layer "In11.Cu")
		(net "P5E_CPU0_PE0_TX_C_DN<4>")
	)
	(segment
		(start 336.996786 -431.393854)
		(end 336.692494 -431.089562)
		(width 0.14732)
		(layer "In11.Cu")
		(net "P5E_CPU0_PE0_TX_C_DN<4>")
	)
	(segment
		(start 337.650074 -431.889916)
		(end 337.650074 -431.580798)
		(width 0.14732)
		(layer "In11.Cu")
		(net "P5E_CPU0_PE0_TX_C_DN<4>")
	)
	(segment
		(start 336.692494 -424.156886)
		(end 339.301328 -411.535372)
		(width 0.14732)
		(layer "In11.Cu")
		(net "P5E_CPU0_PE0_TX_C_DN<4>")
	)
	(segment
		(start 336.692494 -431.089562)
		(end 336.692494 -424.156886)
		(width 0.14732)
		(layer "In11.Cu")
		(net "P5E_CPU0_PE0_TX_C_DN<4>")
	)
	(segment
		(start 337.46313 -431.393854)
		(end 336.996786 -431.393854)
		(width 0.14732)
		(layer "In11.Cu")
		(net "P5E_CPU0_PE0_TX_C_DN<4>")
	)
	(segment
		(start 342.38819 -409.109164)
		(end 342.06307 -408.784044)
		(width 0.13208)
		(layer "F.Cu")
		(net "P5E_CPU0_PE0_TX_C_DN<3>")
	)
	(segment
		(start 342.085168 -410.030168)
		(end 342.38819 -409.727146)
		(width 0.13208)
		(layer "F.Cu")
		(net "P5E_CPU0_PE0_TX_C_DN<3>")
	)
	(segment
		(start 342.38819 -409.727146)
		(end 342.38819 -409.109164)
		(width 0.13208)
		(layer "F.Cu")
		(net "P5E_CPU0_PE0_TX_C_DN<3>")
	)
	(segment
		(start 342.06307 -408.784044)
		(end 342.059768 -408.784044)
		(width 0.13208)
		(layer "F.Cu")
		(net "P5E_CPU0_PE0_TX_C_DN<3>")
	)
	(segment
		(start 339.65007 -430.5808)
		(end 339.463126 -430.393856)
		(width 0.14732)
		(layer "In11.Cu")
		(net "P5E_CPU0_PE0_TX_C_DN<3>")
	)
	(segment
		(start 338.69249 -424.175428)
		(end 342.379808 -411.258512)
		(width 0.14732)
		(layer "In11.Cu")
		(net "P5E_CPU0_PE0_TX_C_DN<3>")
	)
	(segment
		(start 339.65007 -430.889918)
		(end 339.65007 -430.5808)
		(width 0.14732)
		(layer "In11.Cu")
		(net "P5E_CPU0_PE0_TX_C_DN<3>")
	)
	(segment
		(start 342.379808 -410.324808)
		(end 342.085168 -410.030168)
		(width 0.14732)
		(layer "In11.Cu")
		(net "P5E_CPU0_PE0_TX_C_DN<3>")
	)
	(segment
		(start 338.97697 -430.393856)
		(end 338.69249 -430.109376)
		(width 0.14732)
		(layer "In11.Cu")
		(net "P5E_CPU0_PE0_TX_C_DN<3>")
	)
	(segment
		(start 342.379808 -411.258512)
		(end 342.379808 -410.324808)
		(width 0.14732)
		(layer "In11.Cu")
		(net "P5E_CPU0_PE0_TX_C_DN<3>")
	)
	(segment
		(start 338.69249 -430.109376)
		(end 338.69249 -424.175428)
		(width 0.14732)
		(layer "In11.Cu")
		(net "P5E_CPU0_PE0_TX_C_DN<3>")
	)
	(segment
		(start 339.463126 -430.393856)
		(end 338.97697 -430.393856)
		(width 0.14732)
		(layer "In11.Cu")
		(net "P5E_CPU0_PE0_TX_C_DN<3>")
	)
	(segment
		(start 345.148408 -410.030168)
		(end 345.45143 -409.727146)
		(width 0.13208)
		(layer "F.Cu")
		(net "P5E_CPU0_PE0_TX_C_DN<2>")
	)
	(segment
		(start 345.45143 -409.109164)
		(end 345.12631 -408.784044)
		(width 0.13208)
		(layer "F.Cu")
		(net "P5E_CPU0_PE0_TX_C_DN<2>")
	)
	(segment
		(start 345.12631 -408.784044)
		(end 345.123008 -408.784044)
		(width 0.13208)
		(layer "F.Cu")
		(net "P5E_CPU0_PE0_TX_C_DN<2>")
	)
	(segment
		(start 345.45143 -409.727146)
		(end 345.45143 -409.109164)
		(width 0.13208)
		(layer "F.Cu")
		(net "P5E_CPU0_PE0_TX_C_DN<2>")
	)
	(segment
		(start 341.463122 -431.393854)
		(end 341.009986 -431.393854)
		(width 0.14732)
		(layer "In11.Cu")
		(net "P5E_CPU0_PE0_TX_C_DN<2>")
	)
	(segment
		(start 340.692486 -424.421808)
		(end 345.443048 -411.14599)
		(width 0.14732)
		(layer "In11.Cu")
		(net "P5E_CPU0_PE0_TX_C_DN<2>")
	)
	(segment
		(start 340.692486 -431.076354)
		(end 340.692486 -424.421808)
		(width 0.14732)
		(layer "In11.Cu")
		(net "P5E_CPU0_PE0_TX_C_DN<2>")
	)
	(segment
		(start 341.009986 -431.393854)
		(end 340.692486 -431.076354)
		(width 0.14732)
		(layer "In11.Cu")
		(net "P5E_CPU0_PE0_TX_C_DN<2>")
	)
	(segment
		(start 345.443048 -410.324808)
		(end 345.148408 -410.030168)
		(width 0.14732)
		(layer "In11.Cu")
		(net "P5E_CPU0_PE0_TX_C_DN<2>")
	)
	(segment
		(start 341.650066 -431.580798)
		(end 341.463122 -431.393854)
		(width 0.14732)
		(layer "In11.Cu")
		(net "P5E_CPU0_PE0_TX_C_DN<2>")
	)
	(segment
		(start 341.650066 -431.889916)
		(end 341.650066 -431.580798)
		(width 0.14732)
		(layer "In11.Cu")
		(net "P5E_CPU0_PE0_TX_C_DN<2>")
	)
	(segment
		(start 345.443048 -411.14599)
		(end 345.443048 -410.324808)
		(width 0.14732)
		(layer "In11.Cu")
		(net "P5E_CPU0_PE0_TX_C_DN<2>")
	)
	(segment
		(start 348.18955 -408.784044)
		(end 348.186248 -408.784044)
		(width 0.13208)
		(layer "F.Cu")
		(net "P5E_CPU0_PE0_TX_C_DN<1>")
	)
	(segment
		(start 348.51467 -409.109164)
		(end 348.18955 -408.784044)
		(width 0.13208)
		(layer "F.Cu")
		(net "P5E_CPU0_PE0_TX_C_DN<1>")
	)
	(segment
		(start 348.51467 -409.727146)
		(end 348.51467 -409.109164)
		(width 0.13208)
		(layer "F.Cu")
		(net "P5E_CPU0_PE0_TX_C_DN<1>")
	)
	(segment
		(start 348.211648 -410.030168)
		(end 348.51467 -409.727146)
		(width 0.13208)
		(layer "F.Cu")
		(net "P5E_CPU0_PE0_TX_C_DN<1>")
	)
	(segment
		(start 343.650062 -430.889918)
		(end 343.650062 -430.5808)
		(width 0.14732)
		(layer "In11.Cu")
		(net "P5E_CPU0_PE0_TX_C_DN<1>")
	)
	(segment
		(start 342.692482 -424.560238)
		(end 348.506288 -411.138116)
		(width 0.14732)
		(layer "In11.Cu")
		(net "P5E_CPU0_PE0_TX_C_DN<1>")
	)
	(segment
		(start 343.463118 -430.393856)
		(end 342.96477 -430.393856)
		(width 0.14732)
		(layer "In11.Cu")
		(net "P5E_CPU0_PE0_TX_C_DN<1>")
	)
	(segment
		(start 348.506288 -410.324808)
		(end 348.211648 -410.030168)
		(width 0.14732)
		(layer "In11.Cu")
		(net "P5E_CPU0_PE0_TX_C_DN<1>")
	)
	(segment
		(start 342.692482 -430.121568)
		(end 342.692482 -424.560238)
		(width 0.14732)
		(layer "In11.Cu")
		(net "P5E_CPU0_PE0_TX_C_DN<1>")
	)
	(segment
		(start 342.96477 -430.393856)
		(end 342.692482 -430.121568)
		(width 0.14732)
		(layer "In11.Cu")
		(net "P5E_CPU0_PE0_TX_C_DN<1>")
	)
	(segment
		(start 348.506288 -411.138116)
		(end 348.506288 -410.324808)
		(width 0.14732)
		(layer "In11.Cu")
		(net "P5E_CPU0_PE0_TX_C_DN<1>")
	)
	(segment
		(start 343.650062 -430.5808)
		(end 343.463118 -430.393856)
		(width 0.14732)
		(layer "In11.Cu")
		(net "P5E_CPU0_PE0_TX_C_DN<1>")
	)
	(segment
		(start 305.326288 -410.030168)
		(end 305.62931 -409.727146)
		(width 0.13208)
		(layer "F.Cu")
		(net "P5E_CPU0_PE0_TX_C_DN<15>")
	)
	(segment
		(start 305.62931 -409.727146)
		(end 305.62931 -409.109164)
		(width 0.13208)
		(layer "F.Cu")
		(net "P5E_CPU0_PE0_TX_C_DN<15>")
	)
	(segment
		(start 305.30419 -408.784044)
		(end 305.300888 -408.784044)
		(width 0.13208)
		(layer "F.Cu")
		(net "P5E_CPU0_PE0_TX_C_DN<15>")
	)
	(segment
		(start 305.62931 -409.109164)
		(end 305.30419 -408.784044)
		(width 0.13208)
		(layer "F.Cu")
		(net "P5E_CPU0_PE0_TX_C_DN<15>")
	)
	(segment
		(start 313.044332 -429.461422)
		(end 305.620928 -411.220412)
		(width 0.14732)
		(layer "In11.Cu")
		(net "P5E_CPU0_PE0_TX_C_DN<15>")
	)
	(segment
		(start 305.620928 -410.324808)
		(end 305.326288 -410.030168)
		(width 0.14732)
		(layer "In11.Cu")
		(net "P5E_CPU0_PE0_TX_C_DN<15>")
	)
	(segment
		(start 314.65012 -430.889918)
		(end 314.65012 -430.5808)
		(width 0.14732)
		(layer "In11.Cu")
		(net "P5E_CPU0_PE0_TX_C_DN<15>")
	)
	(segment
		(start 313.97702 -430.393856)
		(end 313.044332 -429.461422)
		(width 0.14732)
		(layer "In11.Cu")
		(net "P5E_CPU0_PE0_TX_C_DN<15>")
	)
	(segment
		(start 305.620928 -411.220412)
		(end 305.620928 -410.324808)
		(width 0.14732)
		(layer "In11.Cu")
		(net "P5E_CPU0_PE0_TX_C_DN<15>")
	)
	(segment
		(start 314.65012 -430.5808)
		(end 314.463176 -430.393856)
		(width 0.14732)
		(layer "In11.Cu")
		(net "P5E_CPU0_PE0_TX_C_DN<15>")
	)
	(segment
		(start 314.463176 -430.393856)
		(end 313.97702 -430.393856)
		(width 0.14732)
		(layer "In11.Cu")
		(net "P5E_CPU0_PE0_TX_C_DN<15>")
	)
	(segment
		(start 308.69255 -409.109164)
		(end 308.36743 -408.784044)
		(width 0.13208)
		(layer "F.Cu")
		(net "P5E_CPU0_PE0_TX_C_DN<14>")
	)
	(segment
		(start 308.69255 -409.727146)
		(end 308.69255 -409.109164)
		(width 0.13208)
		(layer "F.Cu")
		(net "P5E_CPU0_PE0_TX_C_DN<14>")
	)
	(segment
		(start 308.36743 -408.784044)
		(end 308.364128 -408.784044)
		(width 0.13208)
		(layer "F.Cu")
		(net "P5E_CPU0_PE0_TX_C_DN<14>")
	)
	(segment
		(start 308.389528 -410.030168)
		(end 308.69255 -409.727146)
		(width 0.13208)
		(layer "F.Cu")
		(net "P5E_CPU0_PE0_TX_C_DN<14>")
	)
	(segment
		(start 308.684168 -410.77515)
		(end 308.684168 -410.324808)
		(width 0.14732)
		(layer "In11.Cu")
		(net "P5E_CPU0_PE0_TX_C_DN<14>")
	)
	(segment
		(start 308.684168 -410.324808)
		(end 308.389528 -410.030168)
		(width 0.14732)
		(layer "In11.Cu")
		(net "P5E_CPU0_PE0_TX_C_DN<14>")
	)
	(segment
		(start 316.463172 -431.393854)
		(end 316.01664 -431.393854)
		(width 0.14732)
		(layer "In11.Cu")
		(net "P5E_CPU0_PE0_TX_C_DN<14>")
	)
	(segment
		(start 315.692536 -425.062904)
		(end 308.684168 -410.77515)
		(width 0.14732)
		(layer "In11.Cu")
		(net "P5E_CPU0_PE0_TX_C_DN<14>")
	)
	(segment
		(start 316.650116 -431.580798)
		(end 316.463172 -431.393854)
		(width 0.14732)
		(layer "In11.Cu")
		(net "P5E_CPU0_PE0_TX_C_DN<14>")
	)
	(segment
		(start 315.692536 -431.06975)
		(end 315.692536 -425.062904)
		(width 0.14732)
		(layer "In11.Cu")
		(net "P5E_CPU0_PE0_TX_C_DN<14>")
	)
	(segment
		(start 316.650116 -431.889916)
		(end 316.650116 -431.580798)
		(width 0.14732)
		(layer "In11.Cu")
		(net "P5E_CPU0_PE0_TX_C_DN<14>")
	)
	(segment
		(start 316.01664 -431.393854)
		(end 315.692536 -431.06975)
		(width 0.14732)
		(layer "In11.Cu")
		(net "P5E_CPU0_PE0_TX_C_DN<14>")
	)
	(segment
		(start 311.75579 -409.727146)
		(end 311.75579 -409.109164)
		(width 0.13208)
		(layer "F.Cu")
		(net "P5E_CPU0_PE0_TX_C_DN<13>")
	)
	(segment
		(start 311.43067 -408.784044)
		(end 311.427368 -408.784044)
		(width 0.13208)
		(layer "F.Cu")
		(net "P5E_CPU0_PE0_TX_C_DN<13>")
	)
	(segment
		(start 311.75579 -409.109164)
		(end 311.43067 -408.784044)
		(width 0.13208)
		(layer "F.Cu")
		(net "P5E_CPU0_PE0_TX_C_DN<13>")
	)
	(segment
		(start 311.452768 -410.030168)
		(end 311.75579 -409.727146)
		(width 0.13208)
		(layer "F.Cu")
		(net "P5E_CPU0_PE0_TX_C_DN<13>")
	)
	(segment
		(start 312.065162 -411.691074)
		(end 311.747408 -410.885132)
		(width 0.14732)
		(layer "In11.Cu")
		(net "P5E_CPU0_PE0_TX_C_DN<13>")
	)
	(segment
		(start 317.692532 -424.800268)
		(end 312.247788 -412.116524)
		(width 0.14732)
		(layer "In11.Cu")
		(net "P5E_CPU0_PE0_TX_C_DN<13>")
	)
	(segment
		(start 312.247788 -412.116524)
		(end 312.065162 -411.691074)
		(width 0.14732)
		(layer "In11.Cu")
		(net "P5E_CPU0_PE0_TX_C_DN<13>")
	)
	(segment
		(start 317.692532 -430.109376)
		(end 317.692532 -424.800268)
		(width 0.14732)
		(layer "In11.Cu")
		(net "P5E_CPU0_PE0_TX_C_DN<13>")
	)
	(segment
		(start 318.463168 -430.393856)
		(end 317.977012 -430.393856)
		(width 0.14732)
		(layer "In11.Cu")
		(net "P5E_CPU0_PE0_TX_C_DN<13>")
	)
	(segment
		(start 311.747408 -410.885132)
		(end 311.747408 -410.324808)
		(width 0.14732)
		(layer "In11.Cu")
		(net "P5E_CPU0_PE0_TX_C_DN<13>")
	)
	(segment
		(start 317.977012 -430.393856)
		(end 317.692532 -430.109376)
		(width 0.14732)
		(layer "In11.Cu")
		(net "P5E_CPU0_PE0_TX_C_DN<13>")
	)
	(segment
		(start 318.650112 -430.889918)
		(end 318.650112 -430.5808)
		(width 0.14732)
		(layer "In11.Cu")
		(net "P5E_CPU0_PE0_TX_C_DN<13>")
	)
	(segment
		(start 318.650112 -430.5808)
		(end 318.463168 -430.393856)
		(width 0.14732)
		(layer "In11.Cu")
		(net "P5E_CPU0_PE0_TX_C_DN<13>")
	)
	(segment
		(start 311.747408 -410.324808)
		(end 311.452768 -410.030168)
		(width 0.14732)
		(layer "In11.Cu")
		(net "P5E_CPU0_PE0_TX_C_DN<13>")
	)
	(segment
		(start 314.81903 -409.109164)
		(end 314.49391 -408.784044)
		(width 0.13208)
		(layer "F.Cu")
		(net "P5E_CPU0_PE0_TX_C_DN<12>")
	)
	(segment
		(start 314.49391 -408.784044)
		(end 314.490608 -408.784044)
		(width 0.13208)
		(layer "F.Cu")
		(net "P5E_CPU0_PE0_TX_C_DN<12>")
	)
	(segment
		(start 314.516008 -410.030168)
		(end 314.81903 -409.727146)
		(width 0.13208)
		(layer "F.Cu")
		(net "P5E_CPU0_PE0_TX_C_DN<12>")
	)
	(segment
		(start 314.81903 -409.727146)
		(end 314.81903 -409.109164)
		(width 0.13208)
		(layer "F.Cu")
		(net "P5E_CPU0_PE0_TX_C_DN<12>")
	)
	(segment
		(start 319.692528 -431.081942)
		(end 319.692528 -425.477432)
		(width 0.14732)
		(layer "In11.Cu")
		(net "P5E_CPU0_PE0_TX_C_DN<12>")
	)
	(segment
		(start 315.195204 -412.122112)
		(end 315.194696 -412.121858)
		(width 0.14732)
		(layer "In11.Cu")
		(net "P5E_CPU0_PE0_TX_C_DN<12>")
	)
	(segment
		(start 314.810648 -411.007052)
		(end 314.810648 -410.324808)
		(width 0.14732)
		(layer "In11.Cu")
		(net "P5E_CPU0_PE0_TX_C_DN<12>")
	)
	(segment
		(start 320.650108 -431.580798)
		(end 320.463164 -431.393854)
		(width 0.14732)
		(layer "In11.Cu")
		(net "P5E_CPU0_PE0_TX_C_DN<12>")
	)
	(segment
		(start 314.810648 -410.324808)
		(end 314.516008 -410.030168)
		(width 0.14732)
		(layer "In11.Cu")
		(net "P5E_CPU0_PE0_TX_C_DN<12>")
	)
	(segment
		(start 315.194696 -412.121858)
		(end 314.824872 -411.021276)
		(width 0.14732)
		(layer "In11.Cu")
		(net "P5E_CPU0_PE0_TX_C_DN<12>")
	)
	(segment
		(start 314.824872 -411.021276)
		(end 314.810648 -411.007052)
		(width 0.14732)
		(layer "In11.Cu")
		(net "P5E_CPU0_PE0_TX_C_DN<12>")
	)
	(segment
		(start 320.650108 -431.889916)
		(end 320.650108 -431.580798)
		(width 0.14732)
		(layer "In11.Cu")
		(net "P5E_CPU0_PE0_TX_C_DN<12>")
	)
	(segment
		(start 315.696346 -413.610298)
		(end 315.195204 -412.122112)
		(width 0.14732)
		(layer "In11.Cu")
		(net "P5E_CPU0_PE0_TX_C_DN<12>")
	)
	(segment
		(start 320.463164 -431.393854)
		(end 320.00444 -431.393854)
		(width 0.14732)
		(layer "In11.Cu")
		(net "P5E_CPU0_PE0_TX_C_DN<12>")
	)
	(segment
		(start 320.00444 -431.393854)
		(end 319.692528 -431.081942)
		(width 0.14732)
		(layer "In11.Cu")
		(net "P5E_CPU0_PE0_TX_C_DN<12>")
	)
	(segment
		(start 319.692528 -425.477432)
		(end 315.6966 -413.610298)
		(width 0.14732)
		(layer "In11.Cu")
		(net "P5E_CPU0_PE0_TX_C_DN<12>")
	)
	(segment
		(start 315.6966 -413.610298)
		(end 315.696346 -413.610298)
		(width 0.14732)
		(layer "In11.Cu")
		(net "P5E_CPU0_PE0_TX_C_DN<12>")
	)
	(segment
		(start 317.55715 -408.784044)
		(end 317.553848 -408.784044)
		(width 0.13208)
		(layer "F.Cu")
		(net "P5E_CPU0_PE0_TX_C_DN<11>")
	)
	(segment
		(start 317.579248 -410.030168)
		(end 317.88227 -409.727146)
		(width 0.13208)
		(layer "F.Cu")
		(net "P5E_CPU0_PE0_TX_C_DN<11>")
	)
	(segment
		(start 317.88227 -409.727146)
		(end 317.88227 -409.109164)
		(width 0.13208)
		(layer "F.Cu")
		(net "P5E_CPU0_PE0_TX_C_DN<11>")
	)
	(segment
		(start 317.88227 -409.109164)
		(end 317.55715 -408.784044)
		(width 0.13208)
		(layer "F.Cu")
		(net "P5E_CPU0_PE0_TX_C_DN<11>")
	)
	(segment
		(start 321.977004 -430.393856)
		(end 321.692524 -430.109376)
		(width 0.14732)
		(layer "In11.Cu")
		(net "P5E_CPU0_PE0_TX_C_DN<11>")
	)
	(segment
		(start 322.46316 -430.393856)
		(end 321.977004 -430.393856)
		(width 0.14732)
		(layer "In11.Cu")
		(net "P5E_CPU0_PE0_TX_C_DN<11>")
	)
	(segment
		(start 321.692524 -425.414694)
		(end 317.873888 -410.974286)
		(width 0.14732)
		(layer "In11.Cu")
		(net "P5E_CPU0_PE0_TX_C_DN<11>")
	)
	(segment
		(start 322.650104 -430.5808)
		(end 322.46316 -430.393856)
		(width 0.14732)
		(layer "In11.Cu")
		(net "P5E_CPU0_PE0_TX_C_DN<11>")
	)
	(segment
		(start 321.692524 -430.109376)
		(end 321.692524 -425.414694)
		(width 0.14732)
		(layer "In11.Cu")
		(net "P5E_CPU0_PE0_TX_C_DN<11>")
	)
	(segment
		(start 322.650104 -430.889918)
		(end 322.650104 -430.5808)
		(width 0.14732)
		(layer "In11.Cu")
		(net "P5E_CPU0_PE0_TX_C_DN<11>")
	)
	(segment
		(start 317.873888 -410.974286)
		(end 317.873888 -410.324808)
		(width 0.14732)
		(layer "In11.Cu")
		(net "P5E_CPU0_PE0_TX_C_DN<11>")
	)
	(segment
		(start 317.873888 -410.324808)
		(end 317.579248 -410.030168)
		(width 0.14732)
		(layer "In11.Cu")
		(net "P5E_CPU0_PE0_TX_C_DN<11>")
	)
	(segment
		(start 320.642488 -410.030168)
		(end 320.94551 -409.727146)
		(width 0.13208)
		(layer "F.Cu")
		(net "P5E_CPU0_PE0_TX_C_DN<10>")
	)
	(segment
		(start 320.94551 -409.109164)
		(end 320.62039 -408.784044)
		(width 0.13208)
		(layer "F.Cu")
		(net "P5E_CPU0_PE0_TX_C_DN<10>")
	)
	(segment
		(start 320.94551 -409.727146)
		(end 320.94551 -409.109164)
		(width 0.13208)
		(layer "F.Cu")
		(net "P5E_CPU0_PE0_TX_C_DN<10>")
	)
	(segment
		(start 320.62039 -408.784044)
		(end 320.617088 -408.784044)
		(width 0.13208)
		(layer "F.Cu")
		(net "P5E_CPU0_PE0_TX_C_DN<10>")
	)
	(segment
		(start 324.463156 -431.393854)
		(end 324.04304 -431.393854)
		(width 0.14732)
		(layer "In11.Cu")
		(net "P5E_CPU0_PE0_TX_C_DN<10>")
	)
	(segment
		(start 324.04304 -431.393854)
		(end 323.69252 -431.043334)
		(width 0.14732)
		(layer "In11.Cu")
		(net "P5E_CPU0_PE0_TX_C_DN<10>")
	)
	(segment
		(start 323.69252 -431.043334)
		(end 323.69252 -425.124626)
		(width 0.14732)
		(layer "In11.Cu")
		(net "P5E_CPU0_PE0_TX_C_DN<10>")
	)
	(segment
		(start 321.387724 -412.759652)
		(end 320.937128 -410.87929)
		(width 0.14732)
		(layer "In11.Cu")
		(net "P5E_CPU0_PE0_TX_C_DN<10>")
	)
	(segment
		(start 324.6501 -431.889916)
		(end 324.6501 -431.580798)
		(width 0.14732)
		(layer "In11.Cu")
		(net "P5E_CPU0_PE0_TX_C_DN<10>")
	)
	(segment
		(start 323.69252 -425.124626)
		(end 321.387724 -412.759652)
		(width 0.14732)
		(layer "In11.Cu")
		(net "P5E_CPU0_PE0_TX_C_DN<10>")
	)
	(segment
		(start 320.937128 -410.324808)
		(end 320.642488 -410.030168)
		(width 0.14732)
		(layer "In11.Cu")
		(net "P5E_CPU0_PE0_TX_C_DN<10>")
	)
	(segment
		(start 320.937128 -410.87929)
		(end 320.937128 -410.324808)
		(width 0.14732)
		(layer "In11.Cu")
		(net "P5E_CPU0_PE0_TX_C_DN<10>")
	)
	(segment
		(start 324.6501 -431.580798)
		(end 324.463156 -431.393854)
		(width 0.14732)
		(layer "In11.Cu")
		(net "P5E_CPU0_PE0_TX_C_DN<10>")
	)
	(segment
		(start 351.25279 -408.784044)
		(end 351.249488 -408.784044)
		(width 0.13208)
		(layer "F.Cu")
		(net "P5E_CPU0_PE0_TX_C_DN<0>")
	)
	(segment
		(start 351.274888 -410.030168)
		(end 351.57791 -409.727146)
		(width 0.13208)
		(layer "F.Cu")
		(net "P5E_CPU0_PE0_TX_C_DN<0>")
	)
	(segment
		(start 351.57791 -409.109164)
		(end 351.25279 -408.784044)
		(width 0.13208)
		(layer "F.Cu")
		(net "P5E_CPU0_PE0_TX_C_DN<0>")
	)
	(segment
		(start 351.57791 -409.727146)
		(end 351.57791 -409.109164)
		(width 0.13208)
		(layer "F.Cu")
		(net "P5E_CPU0_PE0_TX_C_DN<0>")
	)
	(segment
		(start 344.692478 -431.113946)
		(end 344.692478 -424.594528)
		(width 0.14732)
		(layer "In11.Cu")
		(net "P5E_CPU0_PE0_TX_C_DN<0>")
	)
	(segment
		(start 345.650058 -431.580798)
		(end 345.463114 -431.393854)
		(width 0.14732)
		(layer "In11.Cu")
		(net "P5E_CPU0_PE0_TX_C_DN<0>")
	)
	(segment
		(start 351.569528 -410.324808)
		(end 351.274888 -410.030168)
		(width 0.14732)
		(layer "In11.Cu")
		(net "P5E_CPU0_PE0_TX_C_DN<0>")
	)
	(segment
		(start 345.463114 -431.393854)
		(end 344.972386 -431.393854)
		(width 0.14732)
		(layer "In11.Cu")
		(net "P5E_CPU0_PE0_TX_C_DN<0>")
	)
	(segment
		(start 344.972386 -431.393854)
		(end 344.692478 -431.113946)
		(width 0.14732)
		(layer "In11.Cu")
		(net "P5E_CPU0_PE0_TX_C_DN<0>")
	)
	(segment
		(start 345.650058 -431.889916)
		(end 345.650058 -431.580798)
		(width 0.14732)
		(layer "In11.Cu")
		(net "P5E_CPU0_PE0_TX_C_DN<0>")
	)
	(segment
		(start 344.692478 -424.594528)
		(end 351.569528 -411.018228)
		(width 0.14732)
		(layer "In11.Cu")
		(net "P5E_CPU0_PE0_TX_C_DN<0>")
	)
	(segment
		(start 351.569528 -411.018228)
		(end 351.569528 -410.324808)
		(width 0.14732)
		(layer "In11.Cu")
		(net "P5E_CPU0_PE0_TX_C_DN<0>")
	)
	(segment
		(start 345.48318 -221.134178)
		(end 345.483434 -221.133924)
		(width 0.13208)
		(layer "F.Cu")
		(net "P5E_CPU0_PE0_RX_DP<9>")
	)
	(segment
		(start 345.48318 -221.669864)
		(end 345.48318 -221.134178)
		(width 0.13208)
		(layer "F.Cu")
		(net "P5E_CPU0_PE0_RX_DP<9>")
	)
	(segment
		(start 339.10524 -210.861148)
		(end 338.461096 -210.861148)
		(width 0.14732)
		(layer "In13.Cu")
		(net "P5E_CPU0_PE0_RX_DP<9>")
	)
	(segment
		(start 322.640452 -392.421364)
		(end 322.759578 -392.84148)
		(width 0.14732)
		(layer "In13.Cu")
		(net "P5E_CPU0_PE0_RX_DP<9>")
	)
	(segment
		(start 345.209368 -218.372944)
		(end 345.201494 -218.368372)
		(width 0.0889)
		(layer "In13.Cu")
		(net "P5E_CPU0_PE0_RX_DP<9>")
	)
	(segment
		(start 326.000618 -415.548318)
		(end 326.000618 -415.995358)
		(width 0.14732)
		(layer "In13.Cu")
		(net "P5E_CPU0_PE0_RX_DP<9>")
	)
	(segment
		(start 326.140318 -413.617918)
		(end 326.140318 -413.986218)
		(width 0.14732)
		(layer "In13.Cu")
		(net "P5E_CPU0_PE0_RX_DP<9>")
	)
	(segment
		(start 345.200478 -219.01658)
		(end 345.209368 -219.0115)
		(width 0.0889)
		(layer "In13.Cu")
		(net "P5E_CPU0_PE0_RX_DP<9>")
	)
	(segment
		(start 308.836314 -342.720422)
		(end 310.777382 -350.638364)
		(width 0.14732)
		(layer "In13.Cu")
		(net "P5E_CPU0_PE0_RX_DP<9>")
	)
	(segment
		(start 344.73007 -215.925654)
		(end 344.724736 -215.922606)
		(width 0.0889)
		(layer "In13.Cu")
		(net "P5E_CPU0_PE0_RX_DP<9>")
	)
	(segment
		(start 323.032882 -393.347956)
		(end 322.94703 -393.501626)
		(width 0.14732)
		(layer "In13.Cu")
		(net "P5E_CPU0_PE0_RX_DP<9>")
	)
	(segment
		(start 322.333874 -391.341356)
		(end 322.453 -391.761726)
		(width 0.14732)
		(layer "In13.Cu")
		(net "P5E_CPU0_PE0_RX_DP<9>")
	)
	(segment
		(start 326.000618 -417.681918)
		(end 326.000618 -418.248338)
		(width 0.14732)
		(layer "In13.Cu")
		(net "P5E_CPU0_PE0_RX_DP<9>")
	)
	(segment
		(start 326.140318 -416.503358)
		(end 326.000618 -416.643058)
		(width 0.14732)
		(layer "In13.Cu")
		(net "P5E_CPU0_PE0_RX_DP<9>")
	)
	(segment
		(start 340.90356 -210.861148)
		(end 340.78164 -210.983068)
		(width 0.14732)
		(layer "In13.Cu")
		(net "P5E_CPU0_PE0_RX_DP<9>")
	)
	(segment
		(start 344.730324 -214.946992)
		(end 344.739214 -214.941912)
		(width 0.0889)
		(layer "In13.Cu")
		(net "P5E_CPU0_PE0_RX_DP<9>")
	)
	(segment
		(start 345.483434 -221.133924)
		(end 345.639898 -220.862906)
		(width 0.0889)
		(layer "In13.Cu")
		(net "P5E_CPU0_PE0_RX_DP<9>")
	)
	(segment
		(start 345.38793 -220.334078)
		(end 345.38793 -220.311218)
		(width 0.0889)
		(layer "In13.Cu")
		(net "P5E_CPU0_PE0_RX_DP<9>")
	)
	(segment
		(start 326.000618 -413.478218)
		(end 326.140318 -413.617918)
		(width 0.14732)
		(layer "In13.Cu")
		(net "P5E_CPU0_PE0_RX_DP<9>")
	)
	(segment
		(start 315.2267 -325.515986)
		(end 308.836314 -331.906118)
		(width 0.14732)
		(layer "In13.Cu")
		(net "P5E_CPU0_PE0_RX_DP<9>")
	)
	(segment
		(start 324.208902 -221.062804)
		(end 320.459608 -251.577856)
		(width 0.14732)
		(layer "In13.Cu")
		(net "P5E_CPU0_PE0_RX_DP<9>")
	)
	(segment
		(start 326.000618 -414.900618)
		(end 326.140318 -415.040318)
		(width 0.14732)
		(layer "In13.Cu")
		(net "P5E_CPU0_PE0_RX_DP<9>")
	)
	(segment
		(start 330.657962 -212.601048)
		(end 325.632064 -217.627708)
		(width 0.14732)
		(layer "In13.Cu")
		(net "P5E_CPU0_PE0_RX_DP<9>")
	)
	(segment
		(start 325.806308 -410.323284)
		(end 326.000618 -412.074868)
		(width 0.14732)
		(layer "In13.Cu")
		(net "P5E_CPU0_PE0_RX_DP<9>")
	)
	(segment
		(start 326.000618 -412.074868)
		(end 326.000618 -413.478218)
		(width 0.14732)
		(layer "In13.Cu")
		(net "P5E_CPU0_PE0_RX_DP<9>")
	)
	(segment
		(start 340.22284 -210.861148)
		(end 339.78596 -210.861148)
		(width 0.14732)
		(layer "In13.Cu")
		(net "P5E_CPU0_PE0_RX_DP<9>")
	)
	(segment
		(start 326.000618 -418.896038)
		(end 326.000618 -421.85717)
		(width 0.14732)
		(layer "In13.Cu")
		(net "P5E_CPU0_PE0_RX_DP<9>")
	)
	(segment
		(start 326.140318 -416.135058)
		(end 326.140318 -416.503358)
		(width 0.14732)
		(layer "In13.Cu")
		(net "P5E_CPU0_PE0_RX_DP<9>")
	)
	(segment
		(start 344.918284 -216.260426)
		(end 344.918284 -216.25052)
		(width 0.0889)
		(layer "In13.Cu")
		(net "P5E_CPU0_PE0_RX_DP<9>")
	)
	(segment
		(start 326.482964 -437.31942)
		(end 326.650096 -437.152288)
		(width 0.14732)
		(layer "In13.Cu")
		(net "P5E_CPU0_PE0_RX_DP<9>")
	)
	(segment
		(start 326.000618 -416.643058)
		(end 326.000618 -417.034218)
		(width 0.14732)
		(layer "In13.Cu")
		(net "P5E_CPU0_PE0_RX_DP<9>")
	)
	(segment
		(start 326.000618 -417.034218)
		(end 326.140318 -417.173918)
		(width 0.14732)
		(layer "In13.Cu")
		(net "P5E_CPU0_PE0_RX_DP<9>")
	)
	(segment
		(start 326.000618 -418.248338)
		(end 326.140318 -418.388038)
		(width 0.14732)
		(layer "In13.Cu")
		(net "P5E_CPU0_PE0_RX_DP<9>")
	)
	(segment
		(start 344.406474 -213.237064)
		(end 344.406474 -213.214966)
		(width 0.0889)
		(layer "In13.Cu")
		(net "P5E_CPU0_PE0_RX_DP<9>")
	)
	(segment
		(start 308.836314 -331.906118)
		(end 308.836314 -342.720422)
		(width 0.14732)
		(layer "In13.Cu")
		(net "P5E_CPU0_PE0_RX_DP<9>")
	)
	(segment
		(start 332.10627 -212.0011)
		(end 330.657962 -212.601048)
		(width 0.14732)
		(layer "In13.Cu")
		(net "P5E_CPU0_PE0_RX_DP<9>")
	)
	(segment
		(start 326.140318 -417.542218)
		(end 326.000618 -417.681918)
		(width 0.14732)
		(layer "In13.Cu")
		(net "P5E_CPU0_PE0_RX_DP<9>")
	)
	(segment
		(start 344.406474 -213.214966)
		(end 344.406474 -212.186012)
		(width 0.14732)
		(layer "In13.Cu")
		(net "P5E_CPU0_PE0_RX_DP<9>")
	)
	(segment
		(start 325.632064 -217.627708)
		(end 324.208902 -221.062804)
		(width 0.14732)
		(layer "In13.Cu")
		(net "P5E_CPU0_PE0_RX_DP<9>")
	)
	(segment
		(start 339.66404 -210.983068)
		(end 339.22716 -210.983068)
		(width 0.14732)
		(layer "In13.Cu")
		(net "P5E_CPU0_PE0_RX_DP<9>")
	)
	(segment
		(start 322.759578 -392.84148)
		(end 322.913502 -392.927332)
		(width 0.14732)
		(layer "In13.Cu")
		(net "P5E_CPU0_PE0_RX_DP<9>")
	)
	(segment
		(start 326.124316 -437.31942)
		(end 326.482964 -437.31942)
		(width 0.14732)
		(layer "In13.Cu")
		(net "P5E_CPU0_PE0_RX_DP<9>")
	)
	(segment
		(start 325.806308 -406.02789)
		(end 325.806308 -410.323284)
		(width 0.14732)
		(layer "In13.Cu")
		(net "P5E_CPU0_PE0_RX_DP<9>")
	)
	(segment
		(start 322.027042 -390.261348)
		(end 322.146168 -390.681464)
		(width 0.14732)
		(layer "In13.Cu")
		(net "P5E_CPU0_PE0_RX_DP<9>")
	)
	(segment
		(start 343.55151 -211.331048)
		(end 342.416892 -210.861148)
		(width 0.14732)
		(layer "In13.Cu")
		(net "P5E_CPU0_PE0_RX_DP<9>")
	)
	(segment
		(start 326.140318 -413.986218)
		(end 326.000618 -414.125918)
		(width 0.14732)
		(layer "In13.Cu")
		(net "P5E_CPU0_PE0_RX_DP<9>")
	)
	(segment
		(start 326.140318 -415.040318)
		(end 326.140318 -415.408618)
		(width 0.14732)
		(layer "In13.Cu")
		(net "P5E_CPU0_PE0_RX_DP<9>")
	)
	(segment
		(start 322.11264 -390.107678)
		(end 322.027042 -390.261348)
		(width 0.14732)
		(layer "In13.Cu")
		(net "P5E_CPU0_PE0_RX_DP<9>")
	)
	(segment
		(start 325.9582 -437.153304)
		(end 326.124316 -437.31942)
		(width 0.14732)
		(layer "In13.Cu")
		(net "P5E_CPU0_PE0_RX_DP<9>")
	)
	(segment
		(start 339.22716 -210.983068)
		(end 339.10524 -210.861148)
		(width 0.14732)
		(layer "In13.Cu")
		(net "P5E_CPU0_PE0_RX_DP<9>")
	)
	(segment
		(start 344.917776 -214.622634)
		(end 344.917776 -214.461344)
		(width 0.0889)
		(layer "In13.Cu")
		(net "P5E_CPU0_PE0_RX_DP<9>")
	)
	(segment
		(start 326.000618 -415.995358)
		(end 326.140318 -416.135058)
		(width 0.14732)
		(layer "In13.Cu")
		(net "P5E_CPU0_PE0_RX_DP<9>")
	)
	(segment
		(start 339.78596 -210.861148)
		(end 339.66404 -210.983068)
		(width 0.14732)
		(layer "In13.Cu")
		(net "P5E_CPU0_PE0_RX_DP<9>")
	)
	(segment
		(start 322.300092 -390.767062)
		(end 322.419472 -391.187686)
		(width 0.14732)
		(layer "In13.Cu")
		(net "P5E_CPU0_PE0_RX_DP<9>")
	)
	(segment
		(start 326.650096 -437.152288)
		(end 326.650096 -436.889906)
		(width 0.14732)
		(layer "In13.Cu")
		(net "P5E_CPU0_PE0_RX_DP<9>")
	)
	(segment
		(start 322.72605 -392.267694)
		(end 322.640452 -392.421364)
		(width 0.14732)
		(layer "In13.Cu")
		(net "P5E_CPU0_PE0_RX_DP<9>")
	)
	(segment
		(start 326.000618 -414.125918)
		(end 326.000618 -414.900618)
		(width 0.14732)
		(layer "In13.Cu")
		(net "P5E_CPU0_PE0_RX_DP<9>")
	)
	(segment
		(start 322.94703 -393.501626)
		(end 324.460108 -398.831054)
		(width 0.14732)
		(layer "In13.Cu")
		(net "P5E_CPU0_PE0_RX_DP<9>")
	)
	(segment
		(start 325.9582 -422.289224)
		(end 325.9582 -437.153304)
		(width 0.14732)
		(layer "In13.Cu")
		(net "P5E_CPU0_PE0_RX_DP<9>")
	)
	(segment
		(start 326.000618 -421.85717)
		(end 325.9582 -422.289224)
		(width 0.14732)
		(layer "In13.Cu")
		(net "P5E_CPU0_PE0_RX_DP<9>")
	)
	(segment
		(start 338.461096 -210.861148)
		(end 332.10627 -212.0011)
		(width 0.14732)
		(layer "In13.Cu")
		(net "P5E_CPU0_PE0_RX_DP<9>")
	)
	(segment
		(start 345.201494 -218.368372)
		(end 345.200478 -218.367864)
		(width 0.0889)
		(layer "In13.Cu")
		(net "P5E_CPU0_PE0_RX_DP<9>")
	)
	(segment
		(start 342.416892 -210.861148)
		(end 340.90356 -210.861148)
		(width 0.14732)
		(layer "In13.Cu")
		(net "P5E_CPU0_PE0_RX_DP<9>")
	)
	(segment
		(start 344.739722 -215.931242)
		(end 344.73007 -215.925654)
		(width 0.0889)
		(layer "In13.Cu")
		(net "P5E_CPU0_PE0_RX_DP<9>")
	)
	(segment
		(start 322.146168 -390.681464)
		(end 322.300092 -390.767062)
		(width 0.14732)
		(layer "In13.Cu")
		(net "P5E_CPU0_PE0_RX_DP<9>")
	)
	(segment
		(start 322.419472 -391.187686)
		(end 322.333874 -391.341356)
		(width 0.14732)
		(layer "In13.Cu")
		(net "P5E_CPU0_PE0_RX_DP<9>")
	)
	(segment
		(start 321.993514 -389.687054)
		(end 322.11264 -390.107678)
		(width 0.14732)
		(layer "In13.Cu")
		(net "P5E_CPU0_PE0_RX_DP<9>")
	)
	(segment
		(start 345.639898 -220.862906)
		(end 345.615768 -220.773752)
		(width 0.0889)
		(layer "In13.Cu")
		(net "P5E_CPU0_PE0_RX_DP<9>")
	)
	(segment
		(start 310.777382 -350.638364)
		(end 321.83959 -389.60171)
		(width 0.14732)
		(layer "In13.Cu")
		(net "P5E_CPU0_PE0_RX_DP<9>")
	)
	(segment
		(start 340.34476 -210.983068)
		(end 340.22284 -210.861148)
		(width 0.14732)
		(layer "In13.Cu")
		(net "P5E_CPU0_PE0_RX_DP<9>")
	)
	(segment
		(start 344.448384 -213.930484)
		(end 344.448384 -213.278974)
		(width 0.0889)
		(layer "In13.Cu")
		(net "P5E_CPU0_PE0_RX_DP<9>")
	)
	(segment
		(start 320.459608 -251.577856)
		(end 324.150736 -309.5879)
		(width 0.14732)
		(layer "In13.Cu")
		(net "P5E_CPU0_PE0_RX_DP<9>")
	)
	(segment
		(start 324.460108 -398.831054)
		(end 324.460108 -404.68169)
		(width 0.14732)
		(layer "In13.Cu")
		(net "P5E_CPU0_PE0_RX_DP<9>")
	)
	(segment
		(start 322.913502 -392.927332)
		(end 323.032882 -393.347956)
		(width 0.14732)
		(layer "In13.Cu")
		(net "P5E_CPU0_PE0_RX_DP<9>")
	)
	(segment
		(start 326.140318 -418.756338)
		(end 326.000618 -418.896038)
		(width 0.14732)
		(layer "In13.Cu")
		(net "P5E_CPU0_PE0_RX_DP<9>")
	)
	(segment
		(start 322.60667 -391.84707)
		(end 322.72605 -392.267694)
		(width 0.14732)
		(layer "In13.Cu")
		(net "P5E_CPU0_PE0_RX_DP<9>")
	)
	(segment
		(start 344.918284 -217.8939)
		(end 344.918284 -217.859864)
		(width 0.0889)
		(layer "In13.Cu")
		(net "P5E_CPU0_PE0_RX_DP<9>")
	)
	(segment
		(start 321.83959 -389.60171)
		(end 321.993514 -389.687054)
		(width 0.14732)
		(layer "In13.Cu")
		(net "P5E_CPU0_PE0_RX_DP<9>")
	)
	(segment
		(start 324.150736 -309.5879)
		(end 320.811906 -317.540132)
		(width 0.14732)
		(layer "In13.Cu")
		(net "P5E_CPU0_PE0_RX_DP<9>")
	)
	(segment
		(start 326.140318 -417.173918)
		(end 326.140318 -417.542218)
		(width 0.14732)
		(layer "In13.Cu")
		(net "P5E_CPU0_PE0_RX_DP<9>")
	)
	(segment
		(start 340.78164 -210.983068)
		(end 340.34476 -210.983068)
		(width 0.14732)
		(layer "In13.Cu")
		(net "P5E_CPU0_PE0_RX_DP<9>")
	)
	(segment
		(start 322.453 -391.761726)
		(end 322.60667 -391.84707)
		(width 0.14732)
		(layer "In13.Cu")
		(net "P5E_CPU0_PE0_RX_DP<9>")
	)
	(segment
		(start 326.140318 -418.388038)
		(end 326.140318 -418.756338)
		(width 0.14732)
		(layer "In13.Cu")
		(net "P5E_CPU0_PE0_RX_DP<9>")
	)
	(segment
		(start 344.448384 -213.278974)
		(end 344.406474 -213.237064)
		(width 0.0889)
		(layer "In13.Cu")
		(net "P5E_CPU0_PE0_RX_DP<9>")
	)
	(segment
		(start 324.460108 -404.68169)
		(end 325.806308 -406.02789)
		(width 0.14732)
		(layer "In13.Cu")
		(net "P5E_CPU0_PE0_RX_DP<9>")
	)
	(segment
		(start 344.406474 -212.186012)
		(end 343.55151 -211.331048)
		(width 0.14732)
		(layer "In13.Cu")
		(net "P5E_CPU0_PE0_RX_DP<9>")
	)
	(segment
		(start 320.811906 -317.540132)
		(end 315.2267 -325.515986)
		(width 0.14732)
		(layer "In13.Cu")
		(net "P5E_CPU0_PE0_RX_DP<9>")
	)
	(segment
		(start 326.140318 -415.408618)
		(end 326.000618 -415.548318)
		(width 0.14732)
		(layer "In13.Cu")
		(net "P5E_CPU0_PE0_RX_DP<9>")
	)
	(arc
		(start 344.918284 -216.25052)
		(mid 344.870605 -216.06762)
		(end 344.739722 -215.931242)
		(width 0.0889)
		(layer "In13.Cu")
		(net "P5E_CPU0_PE0_RX_DP<9>")
	)
	(arc
		(start 345.200732 -216.739978)
		(mid 344.996397 -216.537373)
		(end 344.918284 -216.260426)
		(width 0.0889)
		(layer "In13.Cu")
		(net "P5E_CPU0_PE0_RX_DP<9>")
	)
	(arc
		(start 344.733626 -214.261954)
		(mid 344.573554 -214.138774)
		(end 344.463624 -213.969346)
		(width 0.0889)
		(layer "In13.Cu")
		(net "P5E_CPU0_PE0_RX_DP<9>")
	)
	(arc
		(start 345.200478 -218.367864)
		(mid 344.997655 -218.167633)
		(end 344.918284 -217.8939)
		(width 0.0889)
		(layer "In13.Cu")
		(net "P5E_CPU0_PE0_RX_DP<9>")
	)
	(arc
		(start 345.59875 -220.760798)
		(mid 345.446263 -220.570702)
		(end 345.38793 -220.334078)
		(width 0.0889)
		(layer "In13.Cu")
		(net "P5E_CPU0_PE0_RX_DP<9>")
	)
	(arc
		(start 345.209368 -219.0115)
		(mid 345.387844 -218.692222)
		(end 345.209368 -218.372944)
		(width 0.0889)
		(layer "In13.Cu")
		(net "P5E_CPU0_PE0_RX_DP<9>")
	)
	(arc
		(start 344.917522 -214.637366)
		(mid 344.917719 -214.630001)
		(end 344.917776 -214.622634)
		(width 0.0889)
		(layer "In13.Cu")
		(net "P5E_CPU0_PE0_RX_DP<9>")
	)
	(arc
		(start 345.200732 -219.995496)
		(mid 344.9182 -219.506148)
		(end 345.200478 -219.01658)
		(width 0.0889)
		(layer "In13.Cu")
		(net "P5E_CPU0_PE0_RX_DP<9>")
	)
	(arc
		(start 344.739214 -214.941912)
		(mid 344.866468 -214.811946)
		(end 344.917522 -214.637366)
		(width 0.0889)
		(layer "In13.Cu")
		(net "P5E_CPU0_PE0_RX_DP<9>")
	)
	(arc
		(start 345.200732 -217.388694)
		(mid 345.388035 -217.064336)
		(end 345.200732 -216.739978)
		(width 0.0889)
		(layer "In13.Cu")
		(net "P5E_CPU0_PE0_RX_DP<9>")
	)
	(arc
		(start 344.463624 -213.969346)
		(mid 344.455661 -213.950049)
		(end 344.448384 -213.930484)
		(width 0.0889)
		(layer "In13.Cu")
		(net "P5E_CPU0_PE0_RX_DP<9>")
	)
	(arc
		(start 344.917776 -214.461344)
		(mid 344.842771 -214.345885)
		(end 344.733626 -214.261954)
		(width 0.0889)
		(layer "In13.Cu")
		(net "P5E_CPU0_PE0_RX_DP<9>")
	)
	(arc
		(start 344.918284 -217.859864)
		(mid 344.998446 -217.587675)
		(end 345.200732 -217.388694)
		(width 0.0889)
		(layer "In13.Cu")
		(net "P5E_CPU0_PE0_RX_DP<9>")
	)
	(arc
		(start 344.724736 -215.922606)
		(mid 344.447828 -215.433205)
		(end 344.730324 -214.946992)
		(width 0.0889)
		(layer "In13.Cu")
		(net "P5E_CPU0_PE0_RX_DP<9>")
	)
	(arc
		(start 345.615768 -220.773752)
		(mid 345.607197 -220.767356)
		(end 345.59875 -220.760798)
		(width 0.0889)
		(layer "In13.Cu")
		(net "P5E_CPU0_PE0_RX_DP<9>")
	)
	(arc
		(start 345.38793 -220.311218)
		(mid 345.33566 -220.128853)
		(end 345.200732 -219.995496)
		(width 0.0889)
		(layer "In13.Cu")
		(net "P5E_CPU0_PE0_RX_DP<9>")
	)
	(segment
		(start 345.013534 -221.947994)
		(end 345.01328 -221.94774)
		(width 0.13208)
		(layer "F.Cu")
		(net "P5E_CPU0_PE0_RX_DP<8>")
	)
	(segment
		(start 345.013534 -222.48368)
		(end 345.013534 -221.947994)
		(width 0.13208)
		(layer "F.Cu")
		(net "P5E_CPU0_PE0_RX_DP<8>")
	)
	(segment
		(start 328.900028 -414.05175)
		(end 328.765916 -414.16605)
		(width 0.14732)
		(layer "In13.Cu")
		(net "P5E_CPU0_PE0_RX_DP<8>")
	)
	(segment
		(start 311.195974 -347.956378)
		(end 322.777358 -384.332988)
		(width 0.14732)
		(layer "In13.Cu")
		(net "P5E_CPU0_PE0_RX_DP<8>")
	)
	(segment
		(start 323.407024 -385.900168)
		(end 323.326252 -386.056632)
		(width 0.14732)
		(layer "In13.Cu")
		(net "P5E_CPU0_PE0_RX_DP<8>")
	)
	(segment
		(start 344.856816 -221.676722)
		(end 344.767916 -221.6531)
		(width 0.0889)
		(layer "In13.Cu")
		(net "P5E_CPU0_PE0_RX_DP<8>")
	)
	(segment
		(start 326.393556 -218.233752)
		(end 325.11492 -221.320614)
		(width 0.14732)
		(layer "In13.Cu")
		(net "P5E_CPU0_PE0_RX_DP<8>")
	)
	(segment
		(start 324.088252 -388.039864)
		(end 324.00748 -388.196328)
		(width 0.14732)
		(layer "In13.Cu")
		(net "P5E_CPU0_PE0_RX_DP<8>")
	)
	(segment
		(start 343.791286 -215.926162)
		(end 343.79027 -215.925654)
		(width 0.0889)
		(layer "In13.Cu")
		(net "P5E_CPU0_PE0_RX_DP<8>")
	)
	(segment
		(start 343.466928 -212.779864)
		(end 343.466928 -212.618066)
		(width 0.14732)
		(layer "In13.Cu")
		(net "P5E_CPU0_PE0_RX_DP<8>")
	)
	(segment
		(start 337.923632 -211.915248)
		(end 332.417674 -212.892386)
		(width 0.14732)
		(layer "In13.Cu")
		(net "P5E_CPU0_PE0_RX_DP<8>")
	)
	(segment
		(start 323.7992 -387.542532)
		(end 323.955664 -387.623304)
		(width 0.14732)
		(layer "In13.Cu")
		(net "P5E_CPU0_PE0_RX_DP<8>")
	)
	(segment
		(start 327.966832 -438.194958)
		(end 328.091292 -438.319418)
		(width 0.14732)
		(layer "In13.Cu")
		(net "P5E_CPU0_PE0_RX_DP<8>")
	)
	(segment
		(start 324.348094 -389.266176)
		(end 324.480428 -389.682228)
		(width 0.14732)
		(layer "In13.Cu")
		(net "P5E_CPU0_PE0_RX_DP<8>")
	)
	(segment
		(start 344.260678 -220.644212)
		(end 344.269568 -220.639132)
		(width 0.0889)
		(layer "In13.Cu")
		(net "P5E_CPU0_PE0_RX_DP<8>")
	)
	(segment
		(start 343.79027 -215.925654)
		(end 343.78646 -215.923622)
		(width 0.0889)
		(layer "In13.Cu")
		(net "P5E_CPU0_PE0_RX_DP<8>")
	)
	(segment
		(start 328.091292 -438.319418)
		(end 328.48296 -438.319418)
		(width 0.14732)
		(layer "In13.Cu")
		(net "P5E_CPU0_PE0_RX_DP<8>")
	)
	(segment
		(start 325.110094 -391.249408)
		(end 325.029322 -391.405872)
		(width 0.14732)
		(layer "In13.Cu")
		(net "P5E_CPU0_PE0_RX_DP<8>")
	)
	(segment
		(start 327.523348 -404.68169)
		(end 328.869548 -406.02789)
		(width 0.14732)
		(layer "In13.Cu")
		(net "P5E_CPU0_PE0_RX_DP<8>")
	)
	(segment
		(start 324.76948 -390.17956)
		(end 324.688708 -390.336024)
		(width 0.14732)
		(layer "In13.Cu")
		(net "P5E_CPU0_PE0_RX_DP<8>")
	)
	(segment
		(start 343.508584 -213.278974)
		(end 343.466674 -213.237064)
		(width 0.0889)
		(layer "In13.Cu")
		(net "P5E_CPU0_PE0_RX_DP<8>")
	)
	(segment
		(start 323.666866 -387.12648)
		(end 323.7992 -387.542532)
		(width 0.14732)
		(layer "In13.Cu")
		(net "P5E_CPU0_PE0_RX_DP<8>")
	)
	(segment
		(start 324.296278 -388.693152)
		(end 324.428866 -389.109712)
		(width 0.14732)
		(layer "In13.Cu")
		(net "P5E_CPU0_PE0_RX_DP<8>")
	)
	(segment
		(start 343.978484 -221.149418)
		(end 343.978484 -221.111826)
		(width 0.0889)
		(layer "In13.Cu")
		(net "P5E_CPU0_PE0_RX_DP<8>")
	)
	(segment
		(start 324.688708 -390.336024)
		(end 324.821042 -390.752076)
		(width 0.14732)
		(layer "In13.Cu")
		(net "P5E_CPU0_PE0_RX_DP<8>")
	)
	(segment
		(start 325.450708 -392.319256)
		(end 325.369936 -392.47572)
		(width 0.14732)
		(layer "In13.Cu")
		(net "P5E_CPU0_PE0_RX_DP<8>")
	)
	(segment
		(start 343.466928 -212.618066)
		(end 342.949022 -212.10016)
		(width 0.14732)
		(layer "In13.Cu")
		(net "P5E_CPU0_PE0_RX_DP<8>")
	)
	(segment
		(start 342.949022 -212.10016)
		(end 342.50249 -211.915248)
		(width 0.14732)
		(layer "In13.Cu")
		(net "P5E_CPU0_PE0_RX_DP<8>")
	)
	(segment
		(start 328.869548 -412.836614)
		(end 328.81951 -413.482282)
		(width 0.14732)
		(layer "In13.Cu")
		(net "P5E_CPU0_PE0_RX_DP<8>")
	)
	(segment
		(start 323.955664 -387.623304)
		(end 324.088252 -388.039864)
		(width 0.14732)
		(layer "In13.Cu")
		(net "P5E_CPU0_PE0_RX_DP<8>")
	)
	(segment
		(start 344.269568 -220.000576)
		(end 344.261694 -219.996004)
		(width 0.0889)
		(layer "In13.Cu")
		(net "P5E_CPU0_PE0_RX_DP<8>")
	)
	(segment
		(start 342.50249 -211.915248)
		(end 337.923632 -211.915248)
		(width 0.14732)
		(layer "In13.Cu")
		(net "P5E_CPU0_PE0_RX_DP<8>")
	)
	(segment
		(start 321.646296 -317.997332)
		(end 316.00775 -326.050148)
		(width 0.14732)
		(layer "In13.Cu")
		(net "P5E_CPU0_PE0_RX_DP<8>")
	)
	(segment
		(start 344.261694 -216.740486)
		(end 344.260678 -216.739978)
		(width 0.0889)
		(layer "In13.Cu")
		(net "P5E_CPU0_PE0_RX_DP<8>")
	)
	(segment
		(start 332.417674 -212.892386)
		(end 331.252068 -213.37524)
		(width 0.14732)
		(layer "In13.Cu")
		(net "P5E_CPU0_PE0_RX_DP<8>")
	)
	(segment
		(start 325.161656 -391.821924)
		(end 325.31812 -391.902696)
		(width 0.14732)
		(layer "In13.Cu")
		(net "P5E_CPU0_PE0_RX_DP<8>")
	)
	(segment
		(start 328.81951 -413.482282)
		(end 328.93381 -413.615886)
		(width 0.14732)
		(layer "In13.Cu")
		(net "P5E_CPU0_PE0_RX_DP<8>")
	)
	(segment
		(start 325.369936 -392.47572)
		(end 327.523348 -399.239994)
		(width 0.14732)
		(layer "In13.Cu")
		(net "P5E_CPU0_PE0_RX_DP<8>")
	)
	(segment
		(start 343.790524 -214.946992)
		(end 343.799414 -214.941912)
		(width 0.0889)
		(layer "In13.Cu")
		(net "P5E_CPU0_PE0_RX_DP<8>")
	)
	(segment
		(start 316.00775 -326.050148)
		(end 309.766208 -332.291436)
		(width 0.14732)
		(layer "In13.Cu")
		(net "P5E_CPU0_PE0_RX_DP<8>")
	)
	(segment
		(start 343.466674 -213.214966)
		(end 343.466674 -212.780118)
		(width 0.14732)
		(layer "In13.Cu")
		(net "P5E_CPU0_PE0_RX_DP<8>")
	)
	(segment
		(start 328.869548 -406.02789)
		(end 328.869548 -412.836614)
		(width 0.14732)
		(layer "In13.Cu")
		(net "P5E_CPU0_PE0_RX_DP<8>")
	)
	(segment
		(start 323.458586 -386.472684)
		(end 323.61505 -386.553456)
		(width 0.14732)
		(layer "In13.Cu")
		(net "P5E_CPU0_PE0_RX_DP<8>")
	)
	(segment
		(start 323.61505 -386.553456)
		(end 323.747638 -386.970016)
		(width 0.14732)
		(layer "In13.Cu")
		(net "P5E_CPU0_PE0_RX_DP<8>")
	)
	(segment
		(start 325.141082 -309.73268)
		(end 321.646296 -317.997332)
		(width 0.14732)
		(layer "In13.Cu")
		(net "P5E_CPU0_PE0_RX_DP<8>")
	)
	(segment
		(start 324.428866 -389.109712)
		(end 324.348094 -389.266176)
		(width 0.14732)
		(layer "In13.Cu")
		(net "P5E_CPU0_PE0_RX_DP<8>")
	)
	(segment
		(start 324.977506 -390.832848)
		(end 325.110094 -391.249408)
		(width 0.14732)
		(layer "In13.Cu")
		(net "P5E_CPU0_PE0_RX_DP<8>")
	)
	(segment
		(start 325.029322 -391.405872)
		(end 325.161656 -391.821924)
		(width 0.14732)
		(layer "In13.Cu")
		(net "P5E_CPU0_PE0_RX_DP<8>")
	)
	(segment
		(start 343.508584 -213.930484)
		(end 343.508584 -213.278974)
		(width 0.0889)
		(layer "In13.Cu")
		(net "P5E_CPU0_PE0_RX_DP<8>")
	)
	(segment
		(start 343.978484 -219.521532)
		(end 343.978484 -219.490544)
		(width 0.0889)
		(layer "In13.Cu")
		(net "P5E_CPU0_PE0_RX_DP<8>")
	)
	(segment
		(start 343.978484 -217.8939)
		(end 343.978484 -217.856308)
		(width 0.0889)
		(layer "In13.Cu")
		(net "P5E_CPU0_PE0_RX_DP<8>")
	)
	(segment
		(start 328.765916 -414.16605)
		(end 327.967086 -424.43654)
		(width 0.14732)
		(layer "In13.Cu")
		(net "P5E_CPU0_PE0_RX_DP<8>")
	)
	(segment
		(start 344.269568 -218.372944)
		(end 344.263726 -218.369388)
		(width 0.0889)
		(layer "In13.Cu")
		(net "P5E_CPU0_PE0_RX_DP<8>")
	)
	(segment
		(start 328.650092 -438.152286)
		(end 328.650092 -437.889904)
		(width 0.14732)
		(layer "In13.Cu")
		(net "P5E_CPU0_PE0_RX_DP<8>")
	)
	(segment
		(start 309.766208 -342.49868)
		(end 311.195974 -347.956378)
		(width 0.14732)
		(layer "In13.Cu")
		(net "P5E_CPU0_PE0_RX_DP<8>")
	)
	(segment
		(start 331.252068 -213.37524)
		(end 326.393556 -218.233752)
		(width 0.14732)
		(layer "In13.Cu")
		(net "P5E_CPU0_PE0_RX_DP<8>")
	)
	(segment
		(start 327.523348 -399.239994)
		(end 327.523348 -404.68169)
		(width 0.14732)
		(layer "In13.Cu")
		(net "P5E_CPU0_PE0_RX_DP<8>")
	)
	(segment
		(start 344.263726 -218.369388)
		(end 344.260678 -218.367864)
		(width 0.0889)
		(layer "In13.Cu")
		(net "P5E_CPU0_PE0_RX_DP<8>")
	)
	(segment
		(start 343.799922 -215.931242)
		(end 343.791286 -215.926162)
		(width 0.0889)
		(layer "In13.Cu")
		(net "P5E_CPU0_PE0_RX_DP<8>")
	)
	(segment
		(start 343.977976 -214.622634)
		(end 343.977976 -214.461344)
		(width 0.0889)
		(layer "In13.Cu")
		(net "P5E_CPU0_PE0_RX_DP<8>")
	)
	(segment
		(start 344.260678 -217.388694)
		(end 344.269568 -217.383614)
		(width 0.0889)
		(layer "In13.Cu")
		(net "P5E_CPU0_PE0_RX_DP<8>")
	)
	(segment
		(start 324.480428 -389.682228)
		(end 324.636892 -389.763)
		(width 0.14732)
		(layer "In13.Cu")
		(net "P5E_CPU0_PE0_RX_DP<8>")
	)
	(segment
		(start 325.31812 -391.902696)
		(end 325.450708 -392.319256)
		(width 0.14732)
		(layer "In13.Cu")
		(net "P5E_CPU0_PE0_RX_DP<8>")
	)
	(segment
		(start 323.747638 -386.970016)
		(end 323.666866 -387.12648)
		(width 0.14732)
		(layer "In13.Cu")
		(net "P5E_CPU0_PE0_RX_DP<8>")
	)
	(segment
		(start 328.93381 -413.615886)
		(end 328.900028 -414.05175)
		(width 0.14732)
		(layer "In13.Cu")
		(net "P5E_CPU0_PE0_RX_DP<8>")
	)
	(segment
		(start 345.01328 -221.94774)
		(end 344.856816 -221.676722)
		(width 0.0889)
		(layer "In13.Cu")
		(net "P5E_CPU0_PE0_RX_DP<8>")
	)
	(segment
		(start 344.269568 -216.745058)
		(end 344.261694 -216.740486)
		(width 0.0889)
		(layer "In13.Cu")
		(net "P5E_CPU0_PE0_RX_DP<8>")
	)
	(segment
		(start 322.985638 -384.986784)
		(end 323.117972 -385.402836)
		(width 0.14732)
		(layer "In13.Cu")
		(net "P5E_CPU0_PE0_RX_DP<8>")
	)
	(segment
		(start 343.466674 -213.237064)
		(end 343.466674 -213.214966)
		(width 0.0889)
		(layer "In13.Cu")
		(net "P5E_CPU0_PE0_RX_DP<8>")
	)
	(segment
		(start 324.00748 -388.196328)
		(end 324.139814 -388.61238)
		(width 0.14732)
		(layer "In13.Cu")
		(net "P5E_CPU0_PE0_RX_DP<8>")
	)
	(segment
		(start 324.821042 -390.752076)
		(end 324.977506 -390.832848)
		(width 0.14732)
		(layer "In13.Cu")
		(net "P5E_CPU0_PE0_RX_DP<8>")
	)
	(segment
		(start 322.933822 -384.41376)
		(end 323.06641 -384.83032)
		(width 0.14732)
		(layer "In13.Cu")
		(net "P5E_CPU0_PE0_RX_DP<8>")
	)
	(segment
		(start 323.274436 -385.483608)
		(end 323.407024 -385.900168)
		(width 0.14732)
		(layer "In13.Cu")
		(net "P5E_CPU0_PE0_RX_DP<8>")
	)
	(segment
		(start 324.139814 -388.61238)
		(end 324.296278 -388.693152)
		(width 0.14732)
		(layer "In13.Cu")
		(net "P5E_CPU0_PE0_RX_DP<8>")
	)
	(segment
		(start 323.117972 -385.402836)
		(end 323.274436 -385.483608)
		(width 0.14732)
		(layer "In13.Cu")
		(net "P5E_CPU0_PE0_RX_DP<8>")
	)
	(segment
		(start 324.636892 -389.763)
		(end 324.76948 -390.17956)
		(width 0.14732)
		(layer "In13.Cu")
		(net "P5E_CPU0_PE0_RX_DP<8>")
	)
	(segment
		(start 323.326252 -386.056632)
		(end 323.458586 -386.472684)
		(width 0.14732)
		(layer "In13.Cu")
		(net "P5E_CPU0_PE0_RX_DP<8>")
	)
	(segment
		(start 321.446652 -251.503688)
		(end 325.141082 -309.73268)
		(width 0.14732)
		(layer "In13.Cu")
		(net "P5E_CPU0_PE0_RX_DP<8>")
	)
	(segment
		(start 327.966832 -424.43654)
		(end 327.966832 -438.194958)
		(width 0.14732)
		(layer "In13.Cu")
		(net "P5E_CPU0_PE0_RX_DP<8>")
	)
	(segment
		(start 325.11492 -221.320614)
		(end 321.446652 -251.503688)
		(width 0.14732)
		(layer "In13.Cu")
		(net "P5E_CPU0_PE0_RX_DP<8>")
	)
	(segment
		(start 344.261694 -219.996004)
		(end 344.260678 -219.995496)
		(width 0.0889)
		(layer "In13.Cu")
		(net "P5E_CPU0_PE0_RX_DP<8>")
	)
	(segment
		(start 343.466674 -212.780118)
		(end 343.466928 -212.779864)
		(width 0.14732)
		(layer "In13.Cu")
		(net "P5E_CPU0_PE0_RX_DP<8>")
	)
	(segment
		(start 323.06641 -384.83032)
		(end 322.985638 -384.986784)
		(width 0.14732)
		(layer "In13.Cu")
		(net "P5E_CPU0_PE0_RX_DP<8>")
	)
	(segment
		(start 343.978484 -216.266014)
		(end 343.978484 -216.25052)
		(width 0.0889)
		(layer "In13.Cu")
		(net "P5E_CPU0_PE0_RX_DP<8>")
	)
	(segment
		(start 343.78646 -215.923622)
		(end 343.784936 -215.922606)
		(width 0.0889)
		(layer "In13.Cu")
		(net "P5E_CPU0_PE0_RX_DP<8>")
	)
	(segment
		(start 309.766208 -332.291436)
		(end 309.766208 -342.49868)
		(width 0.14732)
		(layer "In13.Cu")
		(net "P5E_CPU0_PE0_RX_DP<8>")
	)
	(segment
		(start 327.967086 -424.43654)
		(end 327.966832 -424.43654)
		(width 0.14732)
		(layer "In13.Cu")
		(net "P5E_CPU0_PE0_RX_DP<8>")
	)
	(segment
		(start 322.777358 -384.332988)
		(end 322.933822 -384.41376)
		(width 0.14732)
		(layer "In13.Cu")
		(net "P5E_CPU0_PE0_RX_DP<8>")
	)
	(segment
		(start 328.48296 -438.319418)
		(end 328.650092 -438.152286)
		(width 0.14732)
		(layer "In13.Cu")
		(net "P5E_CPU0_PE0_RX_DP<8>")
	)
	(segment
		(start 344.260678 -219.01658)
		(end 344.269568 -219.0115)
		(width 0.0889)
		(layer "In13.Cu")
		(net "P5E_CPU0_PE0_RX_DP<8>")
	)
	(arc
		(start 344.269568 -219.0115)
		(mid 344.448044 -218.692222)
		(end 344.269568 -218.372944)
		(width 0.0889)
		(layer "In13.Cu")
		(net "P5E_CPU0_PE0_RX_DP<8>")
	)
	(arc
		(start 343.799414 -214.941912)
		(mid 343.926668 -214.811946)
		(end 343.977722 -214.637366)
		(width 0.0889)
		(layer "In13.Cu")
		(net "P5E_CPU0_PE0_RX_DP<8>")
	)
	(arc
		(start 344.260678 -216.739978)
		(mid 344.057855 -216.539747)
		(end 343.978484 -216.266014)
		(width 0.0889)
		(layer "In13.Cu")
		(net "P5E_CPU0_PE0_RX_DP<8>")
	)
	(arc
		(start 343.978484 -221.111826)
		(mid 344.059395 -220.841698)
		(end 344.260678 -220.644212)
		(width 0.0889)
		(layer "In13.Cu")
		(net "P5E_CPU0_PE0_RX_DP<8>")
	)
	(arc
		(start 344.269568 -217.383614)
		(mid 344.448165 -217.064336)
		(end 344.269568 -216.745058)
		(width 0.0889)
		(layer "In13.Cu")
		(net "P5E_CPU0_PE0_RX_DP<8>")
	)
	(arc
		(start 343.523824 -213.969346)
		(mid 343.515861 -213.950049)
		(end 343.508584 -213.930484)
		(width 0.0889)
		(layer "In13.Cu")
		(net "P5E_CPU0_PE0_RX_DP<8>")
	)
	(arc
		(start 343.784936 -215.922606)
		(mid 343.508028 -215.433205)
		(end 343.790524 -214.946992)
		(width 0.0889)
		(layer "In13.Cu")
		(net "P5E_CPU0_PE0_RX_DP<8>")
	)
	(arc
		(start 343.977722 -214.637366)
		(mid 343.977919 -214.630001)
		(end 343.977976 -214.622634)
		(width 0.0889)
		(layer "In13.Cu")
		(net "P5E_CPU0_PE0_RX_DP<8>")
	)
	(arc
		(start 343.978484 -217.856308)
		(mid 344.059395 -217.58618)
		(end 344.260678 -217.388694)
		(width 0.0889)
		(layer "In13.Cu")
		(net "P5E_CPU0_PE0_RX_DP<8>")
	)
	(arc
		(start 344.748104 -221.661228)
		(mid 344.230514 -221.604895)
		(end 343.978484 -221.149418)
		(width 0.0889)
		(layer "In13.Cu")
		(net "P5E_CPU0_PE0_RX_DP<8>")
	)
	(arc
		(start 344.260678 -219.995496)
		(mid 344.057855 -219.795265)
		(end 343.978484 -219.521532)
		(width 0.0889)
		(layer "In13.Cu")
		(net "P5E_CPU0_PE0_RX_DP<8>")
	)
	(arc
		(start 343.977976 -214.461344)
		(mid 343.902971 -214.345885)
		(end 343.793826 -214.261954)
		(width 0.0889)
		(layer "In13.Cu")
		(net "P5E_CPU0_PE0_RX_DP<8>")
	)
	(arc
		(start 344.767916 -221.6531)
		(mid 344.758049 -221.657259)
		(end 344.748104 -221.661228)
		(width 0.0889)
		(layer "In13.Cu")
		(net "P5E_CPU0_PE0_RX_DP<8>")
	)
	(arc
		(start 344.269568 -220.639132)
		(mid 344.448165 -220.319854)
		(end 344.269568 -220.000576)
		(width 0.0889)
		(layer "In13.Cu")
		(net "P5E_CPU0_PE0_RX_DP<8>")
	)
	(arc
		(start 344.260678 -218.367864)
		(mid 344.057855 -218.167633)
		(end 343.978484 -217.8939)
		(width 0.0889)
		(layer "In13.Cu")
		(net "P5E_CPU0_PE0_RX_DP<8>")
	)
	(arc
		(start 343.978484 -219.490544)
		(mid 344.057854 -219.21681)
		(end 344.260678 -219.01658)
		(width 0.0889)
		(layer "In13.Cu")
		(net "P5E_CPU0_PE0_RX_DP<8>")
	)
	(arc
		(start 343.793826 -214.261954)
		(mid 343.633754 -214.138774)
		(end 343.523824 -213.969346)
		(width 0.0889)
		(layer "In13.Cu")
		(net "P5E_CPU0_PE0_RX_DP<8>")
	)
	(arc
		(start 343.978484 -216.25052)
		(mid 343.930805 -216.06762)
		(end 343.799922 -215.931242)
		(width 0.0889)
		(layer "In13.Cu")
		(net "P5E_CPU0_PE0_RX_DP<8>")
	)
	(segment
		(start 343.60358 -221.134178)
		(end 343.603834 -221.133924)
		(width 0.13208)
		(layer "F.Cu")
		(net "P5E_CPU0_PE0_RX_DP<7>")
	)
	(segment
		(start 343.60358 -221.669864)
		(end 343.60358 -221.134178)
		(width 0.13208)
		(layer "F.Cu")
		(net "P5E_CPU0_PE0_RX_DP<7>")
	)
	(segment
		(start 326.060308 -386.77977)
		(end 326.205088 -387.192266)
		(width 0.14732)
		(layer "In13.Cu")
		(net "P5E_CPU0_PE0_RX_DP<7>")
	)
	(segment
		(start 342.85047 -215.925654)
		(end 342.845136 -215.922606)
		(width 0.0889)
		(layer "In13.Cu")
		(net "P5E_CPU0_PE0_RX_DP<7>")
	)
	(segment
		(start 336.939128 -213.263988)
		(end 336.796888 -213.166452)
		(width 0.14732)
		(layer "In13.Cu")
		(net "P5E_CPU0_PE0_RX_DP<7>")
	)
	(segment
		(start 326.948546 -389.311134)
		(end 326.872346 -389.469884)
		(width 0.14732)
		(layer "In13.Cu")
		(net "P5E_CPU0_PE0_RX_DP<7>")
	)
	(segment
		(start 342.568784 -213.335616)
		(end 342.527128 -213.29396)
		(width 0.0889)
		(layer "In13.Cu")
		(net "P5E_CPU0_PE0_RX_DP<7>")
	)
	(segment
		(start 327.180702 -218.774772)
		(end 326.025256 -221.5642)
		(width 0.14732)
		(layer "In13.Cu")
		(net "P5E_CPU0_PE0_RX_DP<7>")
	)
	(segment
		(start 325.833232 -386.132832)
		(end 325.757032 -386.291582)
		(width 0.14732)
		(layer "In13.Cu")
		(net "P5E_CPU0_PE0_RX_DP<7>")
	)
	(segment
		(start 338.225384 -212.899244)
		(end 337.466432 -213.04123)
		(width 0.14732)
		(layer "In13.Cu")
		(net "P5E_CPU0_PE0_RX_DP<7>")
	)
	(segment
		(start 327.388728 -390.941306)
		(end 327.547478 -391.017506)
		(width 0.14732)
		(layer "In13.Cu")
		(net "P5E_CPU0_PE0_RX_DP<7>")
	)
	(segment
		(start 342.527128 -213.29396)
		(end 342.527128 -213.271862)
		(width 0.0889)
		(layer "In13.Cu")
		(net "P5E_CPU0_PE0_RX_DP<7>")
	)
	(segment
		(start 342.527128 -213.047072)
		(end 342.3793 -212.899244)
		(width 0.14732)
		(layer "In13.Cu")
		(net "P5E_CPU0_PE0_RX_DP<7>")
	)
	(segment
		(start 327.244202 -390.529318)
		(end 327.388728 -390.941306)
		(width 0.14732)
		(layer "In13.Cu")
		(net "P5E_CPU0_PE0_RX_DP<7>")
	)
	(segment
		(start 342.3793 -212.899244)
		(end 338.225384 -212.899244)
		(width 0.14732)
		(layer "In13.Cu")
		(net "P5E_CPU0_PE0_RX_DP<7>")
	)
	(segment
		(start 342.850724 -214.946992)
		(end 342.859614 -214.941912)
		(width 0.0889)
		(layer "In13.Cu")
		(net "P5E_CPU0_PE0_RX_DP<7>")
	)
	(segment
		(start 327.016872 -389.881872)
		(end 327.175622 -389.958072)
		(width 0.14732)
		(layer "In13.Cu")
		(net "P5E_CPU0_PE0_RX_DP<7>")
	)
	(segment
		(start 336.367628 -213.246716)
		(end 336.270092 -213.38921)
		(width 0.14732)
		(layer "In13.Cu")
		(net "P5E_CPU0_PE0_RX_DP<7>")
	)
	(segment
		(start 343.329768 -218.372944)
		(end 343.321894 -218.368372)
		(width 0.0889)
		(layer "In13.Cu")
		(net "P5E_CPU0_PE0_RX_DP<7>")
	)
	(segment
		(start 326.128888 -387.351016)
		(end 326.273414 -387.763258)
		(width 0.14732)
		(layer "In13.Cu")
		(net "P5E_CPU0_PE0_RX_DP<7>")
	)
	(segment
		(start 327.320402 -390.370568)
		(end 327.244202 -390.529318)
		(width 0.14732)
		(layer "In13.Cu")
		(net "P5E_CPU0_PE0_RX_DP<7>")
	)
	(segment
		(start 330.586588 -404.68169)
		(end 331.932788 -406.02789)
		(width 0.14732)
		(layer "In13.Cu")
		(net "P5E_CPU0_PE0_RX_DP<7>")
	)
	(segment
		(start 326.025256 -221.5642)
		(end 322.396866 -251.500386)
		(width 0.14732)
		(layer "In13.Cu")
		(net "P5E_CPU0_PE0_RX_DP<7>")
	)
	(segment
		(start 325.01332 -384.172714)
		(end 325.157846 -384.584702)
		(width 0.14732)
		(layer "In13.Cu")
		(net "P5E_CPU0_PE0_RX_DP<7>")
	)
	(segment
		(start 343.038684 -217.8939)
		(end 343.038684 -217.859864)
		(width 0.0889)
		(layer "In13.Cu")
		(net "P5E_CPU0_PE0_RX_DP<7>")
	)
	(segment
		(start 331.932788 -406.02789)
		(end 331.932788 -412.162244)
		(width 0.14732)
		(layer "In13.Cu")
		(net "P5E_CPU0_PE0_RX_DP<7>")
	)
	(segment
		(start 310.695848 -342.33358)
		(end 312.337196 -348.052898)
		(width 0.14732)
		(layer "In13.Cu")
		(net "P5E_CPU0_PE0_RX_DP<7>")
	)
	(segment
		(start 327.175622 -389.958072)
		(end 327.320402 -390.370568)
		(width 0.14732)
		(layer "In13.Cu")
		(net "P5E_CPU0_PE0_RX_DP<7>")
	)
	(segment
		(start 337.466432 -213.04123)
		(end 337.368896 -213.183724)
		(width 0.14732)
		(layer "In13.Cu")
		(net "P5E_CPU0_PE0_RX_DP<7>")
	)
	(segment
		(start 343.320878 -219.01658)
		(end 343.329768 -219.0115)
		(width 0.0889)
		(layer "In13.Cu")
		(net "P5E_CPU0_PE0_RX_DP<7>")
	)
	(segment
		(start 331.091286 -437.31942)
		(end 331.482954 -437.31942)
		(width 0.14732)
		(layer "In13.Cu")
		(net "P5E_CPU0_PE0_RX_DP<7>")
	)
	(segment
		(start 342.527128 -213.271862)
		(end 342.527128 -213.047072)
		(width 0.14732)
		(layer "In13.Cu")
		(net "P5E_CPU0_PE0_RX_DP<7>")
	)
	(segment
		(start 324.786244 -383.525522)
		(end 324.94474 -383.601468)
		(width 0.14732)
		(layer "In13.Cu")
		(net "P5E_CPU0_PE0_RX_DP<7>")
	)
	(segment
		(start 322.396866 -251.500386)
		(end 326.205596 -309.716424)
		(width 0.14732)
		(layer "In13.Cu")
		(net "P5E_CPU0_PE0_RX_DP<7>")
	)
	(segment
		(start 328.064114 -392.489436)
		(end 327.987914 -392.648186)
		(width 0.14732)
		(layer "In13.Cu")
		(net "P5E_CPU0_PE0_RX_DP<7>")
	)
	(segment
		(start 327.692258 -391.430002)
		(end 327.616058 -391.588752)
		(width 0.14732)
		(layer "In13.Cu")
		(net "P5E_CPU0_PE0_RX_DP<7>")
	)
	(segment
		(start 342.860122 -215.931242)
		(end 342.85047 -215.925654)
		(width 0.0889)
		(layer "In13.Cu")
		(net "P5E_CPU0_PE0_RX_DP<7>")
	)
	(segment
		(start 326.50049 -388.41045)
		(end 326.645016 -388.822438)
		(width 0.14732)
		(layer "In13.Cu")
		(net "P5E_CPU0_PE0_RX_DP<7>")
	)
	(segment
		(start 312.337196 -348.052898)
		(end 324.786244 -383.525522)
		(width 0.14732)
		(layer "In13.Cu")
		(net "P5E_CPU0_PE0_RX_DP<7>")
	)
	(segment
		(start 331.650086 -437.152288)
		(end 331.650086 -436.889906)
		(width 0.14732)
		(layer "In13.Cu")
		(net "P5E_CPU0_PE0_RX_DP<7>")
	)
	(segment
		(start 326.645016 -388.822438)
		(end 326.803766 -388.898638)
		(width 0.14732)
		(layer "In13.Cu")
		(net "P5E_CPU0_PE0_RX_DP<7>")
	)
	(segment
		(start 332.791054 -213.915752)
		(end 331.509624 -214.446358)
		(width 0.14732)
		(layer "In13.Cu")
		(net "P5E_CPU0_PE0_RX_DP<7>")
	)
	(segment
		(start 331.932788 -412.162244)
		(end 330.966826 -424.323764)
		(width 0.14732)
		(layer "In13.Cu")
		(net "P5E_CPU0_PE0_RX_DP<7>")
	)
	(segment
		(start 326.43191 -387.839204)
		(end 326.57669 -388.2517)
		(width 0.14732)
		(layer "In13.Cu")
		(net "P5E_CPU0_PE0_RX_DP<7>")
	)
	(segment
		(start 327.547478 -391.017506)
		(end 327.692258 -391.430002)
		(width 0.14732)
		(layer "In13.Cu")
		(net "P5E_CPU0_PE0_RX_DP<7>")
	)
	(segment
		(start 325.461376 -385.073398)
		(end 325.385176 -385.232148)
		(width 0.14732)
		(layer "In13.Cu")
		(net "P5E_CPU0_PE0_RX_DP<7>")
	)
	(segment
		(start 331.509624 -214.446358)
		(end 327.180702 -218.774772)
		(width 0.14732)
		(layer "In13.Cu")
		(net "P5E_CPU0_PE0_RX_DP<7>")
	)
	(segment
		(start 326.273414 -387.763258)
		(end 326.43191 -387.839204)
		(width 0.14732)
		(layer "In13.Cu")
		(net "P5E_CPU0_PE0_RX_DP<7>")
	)
	(segment
		(start 316.820296 -326.553068)
		(end 310.695848 -332.677262)
		(width 0.14732)
		(layer "In13.Cu")
		(net "P5E_CPU0_PE0_RX_DP<7>")
	)
	(segment
		(start 343.603834 -221.133924)
		(end 343.760298 -220.862906)
		(width 0.0889)
		(layer "In13.Cu")
		(net "P5E_CPU0_PE0_RX_DP<7>")
	)
	(segment
		(start 343.321894 -218.368372)
		(end 343.320878 -218.367864)
		(width 0.0889)
		(layer "In13.Cu")
		(net "P5E_CPU0_PE0_RX_DP<7>")
	)
	(segment
		(start 343.038176 -214.622634)
		(end 343.038176 -214.461344)
		(width 0.0889)
		(layer "In13.Cu")
		(net "P5E_CPU0_PE0_RX_DP<7>")
	)
	(segment
		(start 336.796888 -213.166452)
		(end 336.367628 -213.246716)
		(width 0.14732)
		(layer "In13.Cu")
		(net "P5E_CPU0_PE0_RX_DP<7>")
	)
	(segment
		(start 326.872346 -389.469884)
		(end 327.016872 -389.881872)
		(width 0.14732)
		(layer "In13.Cu")
		(net "P5E_CPU0_PE0_RX_DP<7>")
	)
	(segment
		(start 325.08952 -384.013964)
		(end 325.01332 -384.172714)
		(width 0.14732)
		(layer "In13.Cu")
		(net "P5E_CPU0_PE0_RX_DP<7>")
	)
	(segment
		(start 326.57669 -388.2517)
		(end 326.50049 -388.41045)
		(width 0.14732)
		(layer "In13.Cu")
		(net "P5E_CPU0_PE0_RX_DP<7>")
	)
	(segment
		(start 326.205596 -309.716424)
		(end 322.544186 -318.37884)
		(width 0.14732)
		(layer "In13.Cu")
		(net "P5E_CPU0_PE0_RX_DP<7>")
	)
	(segment
		(start 327.987914 -392.648186)
		(end 330.586588 -400.053048)
		(width 0.14732)
		(layer "In13.Cu")
		(net "P5E_CPU0_PE0_RX_DP<7>")
	)
	(segment
		(start 310.695848 -332.677262)
		(end 310.695848 -342.33358)
		(width 0.14732)
		(layer "In13.Cu")
		(net "P5E_CPU0_PE0_RX_DP<7>")
	)
	(segment
		(start 335.840578 -213.469474)
		(end 335.698338 -213.371938)
		(width 0.14732)
		(layer "In13.Cu")
		(net "P5E_CPU0_PE0_RX_DP<7>")
	)
	(segment
		(start 343.038684 -216.260426)
		(end 343.038684 -216.25052)
		(width 0.0889)
		(layer "In13.Cu")
		(net "P5E_CPU0_PE0_RX_DP<7>")
	)
	(segment
		(start 336.270092 -213.38921)
		(end 335.840578 -213.469474)
		(width 0.14732)
		(layer "In13.Cu")
		(net "P5E_CPU0_PE0_RX_DP<7>")
	)
	(segment
		(start 325.757032 -386.291582)
		(end 325.901558 -386.70357)
		(width 0.14732)
		(layer "In13.Cu")
		(net "P5E_CPU0_PE0_RX_DP<7>")
	)
	(segment
		(start 330.966826 -424.323764)
		(end 330.966826 -437.19496)
		(width 0.14732)
		(layer "In13.Cu")
		(net "P5E_CPU0_PE0_RX_DP<7>")
	)
	(segment
		(start 326.205088 -387.192266)
		(end 326.128888 -387.351016)
		(width 0.14732)
		(layer "In13.Cu")
		(net "P5E_CPU0_PE0_RX_DP<7>")
	)
	(segment
		(start 325.901558 -386.70357)
		(end 326.060308 -386.77977)
		(width 0.14732)
		(layer "In13.Cu")
		(net "P5E_CPU0_PE0_RX_DP<7>")
	)
	(segment
		(start 325.385176 -385.232148)
		(end 325.529702 -385.644136)
		(width 0.14732)
		(layer "In13.Cu")
		(net "P5E_CPU0_PE0_RX_DP<7>")
	)
	(segment
		(start 325.316596 -384.660902)
		(end 325.461376 -385.073398)
		(width 0.14732)
		(layer "In13.Cu")
		(net "P5E_CPU0_PE0_RX_DP<7>")
	)
	(segment
		(start 330.966826 -437.19496)
		(end 331.091286 -437.31942)
		(width 0.14732)
		(layer "In13.Cu")
		(net "P5E_CPU0_PE0_RX_DP<7>")
	)
	(segment
		(start 342.568784 -213.930484)
		(end 342.568784 -213.335616)
		(width 0.0889)
		(layer "In13.Cu")
		(net "P5E_CPU0_PE0_RX_DP<7>")
	)
	(segment
		(start 343.50833 -220.334078)
		(end 343.50833 -220.311218)
		(width 0.0889)
		(layer "In13.Cu")
		(net "P5E_CPU0_PE0_RX_DP<7>")
	)
	(segment
		(start 327.919588 -392.07694)
		(end 328.064114 -392.489436)
		(width 0.14732)
		(layer "In13.Cu")
		(net "P5E_CPU0_PE0_RX_DP<7>")
	)
	(segment
		(start 330.586588 -400.053048)
		(end 330.586588 -404.68169)
		(width 0.14732)
		(layer "In13.Cu")
		(net "P5E_CPU0_PE0_RX_DP<7>")
	)
	(segment
		(start 343.760298 -220.862906)
		(end 343.736168 -220.773752)
		(width 0.0889)
		(layer "In13.Cu")
		(net "P5E_CPU0_PE0_RX_DP<7>")
	)
	(segment
		(start 324.94474 -383.601468)
		(end 325.08952 -384.013964)
		(width 0.14732)
		(layer "In13.Cu")
		(net "P5E_CPU0_PE0_RX_DP<7>")
	)
	(segment
		(start 327.760584 -392.00074)
		(end 327.919588 -392.07694)
		(width 0.14732)
		(layer "In13.Cu")
		(net "P5E_CPU0_PE0_RX_DP<7>")
	)
	(segment
		(start 337.368896 -213.183724)
		(end 336.939128 -213.263988)
		(width 0.14732)
		(layer "In13.Cu")
		(net "P5E_CPU0_PE0_RX_DP<7>")
	)
	(segment
		(start 326.803766 -388.898638)
		(end 326.948546 -389.311134)
		(width 0.14732)
		(layer "In13.Cu")
		(net "P5E_CPU0_PE0_RX_DP<7>")
	)
	(segment
		(start 327.616058 -391.588752)
		(end 327.760584 -392.00074)
		(width 0.14732)
		(layer "In13.Cu")
		(net "P5E_CPU0_PE0_RX_DP<7>")
	)
	(segment
		(start 322.544186 -318.37884)
		(end 316.820296 -326.553068)
		(width 0.14732)
		(layer "In13.Cu")
		(net "P5E_CPU0_PE0_RX_DP<7>")
	)
	(segment
		(start 325.529702 -385.644136)
		(end 325.688452 -385.720336)
		(width 0.14732)
		(layer "In13.Cu")
		(net "P5E_CPU0_PE0_RX_DP<7>")
	)
	(segment
		(start 335.698338 -213.371938)
		(end 332.791054 -213.915752)
		(width 0.14732)
		(layer "In13.Cu")
		(net "P5E_CPU0_PE0_RX_DP<7>")
	)
	(segment
		(start 325.688452 -385.720336)
		(end 325.833232 -386.132832)
		(width 0.14732)
		(layer "In13.Cu")
		(net "P5E_CPU0_PE0_RX_DP<7>")
	)
	(segment
		(start 331.482954 -437.31942)
		(end 331.650086 -437.152288)
		(width 0.14732)
		(layer "In13.Cu")
		(net "P5E_CPU0_PE0_RX_DP<7>")
	)
	(segment
		(start 325.157846 -384.584702)
		(end 325.316596 -384.660902)
		(width 0.14732)
		(layer "In13.Cu")
		(net "P5E_CPU0_PE0_RX_DP<7>")
	)
	(arc
		(start 343.50833 -220.311218)
		(mid 343.45606 -220.128853)
		(end 343.321132 -219.995496)
		(width 0.0889)
		(layer "In13.Cu")
		(net "P5E_CPU0_PE0_RX_DP<7>")
	)
	(arc
		(start 343.037922 -214.637366)
		(mid 343.038119 -214.630001)
		(end 343.038176 -214.622634)
		(width 0.0889)
		(layer "In13.Cu")
		(net "P5E_CPU0_PE0_RX_DP<7>")
	)
	(arc
		(start 342.859614 -214.941912)
		(mid 342.986868 -214.811946)
		(end 343.037922 -214.637366)
		(width 0.0889)
		(layer "In13.Cu")
		(net "P5E_CPU0_PE0_RX_DP<7>")
	)
	(arc
		(start 343.320878 -218.367864)
		(mid 343.118055 -218.167633)
		(end 343.038684 -217.8939)
		(width 0.0889)
		(layer "In13.Cu")
		(net "P5E_CPU0_PE0_RX_DP<7>")
	)
	(arc
		(start 343.321132 -216.739978)
		(mid 343.116797 -216.537373)
		(end 343.038684 -216.260426)
		(width 0.0889)
		(layer "In13.Cu")
		(net "P5E_CPU0_PE0_RX_DP<7>")
	)
	(arc
		(start 343.038176 -214.461344)
		(mid 342.963171 -214.345885)
		(end 342.854026 -214.261954)
		(width 0.0889)
		(layer "In13.Cu")
		(net "P5E_CPU0_PE0_RX_DP<7>")
	)
	(arc
		(start 343.321132 -219.995496)
		(mid 343.0386 -219.506148)
		(end 343.320878 -219.01658)
		(width 0.0889)
		(layer "In13.Cu")
		(net "P5E_CPU0_PE0_RX_DP<7>")
	)
	(arc
		(start 342.584024 -213.969346)
		(mid 342.576061 -213.950049)
		(end 342.568784 -213.930484)
		(width 0.0889)
		(layer "In13.Cu")
		(net "P5E_CPU0_PE0_RX_DP<7>")
	)
	(arc
		(start 343.71915 -220.760798)
		(mid 343.566663 -220.570702)
		(end 343.50833 -220.334078)
		(width 0.0889)
		(layer "In13.Cu")
		(net "P5E_CPU0_PE0_RX_DP<7>")
	)
	(arc
		(start 342.854026 -214.261954)
		(mid 342.693954 -214.138774)
		(end 342.584024 -213.969346)
		(width 0.0889)
		(layer "In13.Cu")
		(net "P5E_CPU0_PE0_RX_DP<7>")
	)
	(arc
		(start 343.038684 -217.859864)
		(mid 343.118846 -217.587675)
		(end 343.321132 -217.388694)
		(width 0.0889)
		(layer "In13.Cu")
		(net "P5E_CPU0_PE0_RX_DP<7>")
	)
	(arc
		(start 342.845136 -215.922606)
		(mid 342.568228 -215.433205)
		(end 342.850724 -214.946992)
		(width 0.0889)
		(layer "In13.Cu")
		(net "P5E_CPU0_PE0_RX_DP<7>")
	)
	(arc
		(start 343.321132 -217.388694)
		(mid 343.508435 -217.064336)
		(end 343.321132 -216.739978)
		(width 0.0889)
		(layer "In13.Cu")
		(net "P5E_CPU0_PE0_RX_DP<7>")
	)
	(arc
		(start 343.329768 -219.0115)
		(mid 343.508244 -218.692222)
		(end 343.329768 -218.372944)
		(width 0.0889)
		(layer "In13.Cu")
		(net "P5E_CPU0_PE0_RX_DP<7>")
	)
	(arc
		(start 343.736168 -220.773752)
		(mid 343.727597 -220.767356)
		(end 343.71915 -220.760798)
		(width 0.0889)
		(layer "In13.Cu")
		(net "P5E_CPU0_PE0_RX_DP<7>")
	)
	(arc
		(start 343.038684 -216.25052)
		(mid 342.991005 -216.06762)
		(end 342.860122 -215.931242)
		(width 0.0889)
		(layer "In13.Cu")
		(net "P5E_CPU0_PE0_RX_DP<7>")
	)
	(segment
		(start 343.133934 -221.947994)
		(end 343.13368 -221.94774)
		(width 0.13208)
		(layer "F.Cu")
		(net "P5E_CPU0_PE0_RX_DP<6>")
	)
	(segment
		(start 343.133934 -222.48368)
		(end 343.133934 -221.947994)
		(width 0.13208)
		(layer "F.Cu")
		(net "P5E_CPU0_PE0_RX_DP<6>")
	)
	(segment
		(start 333.649828 -399.759678)
		(end 333.649828 -404.68169)
		(width 0.14732)
		(layer "In13.Cu")
		(net "P5E_CPU0_PE0_RX_DP<6>")
	)
	(segment
		(start 333.912464 -215.103456)
		(end 333.066136 -215.103456)
		(width 0.14732)
		(layer "In13.Cu")
		(net "P5E_CPU0_PE0_RX_DP<6>")
	)
	(segment
		(start 334.3402 -416.690556)
		(end 334.180688 -416.807142)
		(width 0.14732)
		(layer "In13.Cu")
		(net "P5E_CPU0_PE0_RX_DP<6>")
	)
	(segment
		(start 333.861664 -419.791388)
		(end 333.702152 -419.907974)
		(width 0.14732)
		(layer "In13.Cu")
		(net "P5E_CPU0_PE0_RX_DP<6>")
	)
	(segment
		(start 330.055474 -390.190482)
		(end 329.984608 -390.351772)
		(width 0.14732)
		(layer "In13.Cu")
		(net "P5E_CPU0_PE0_RX_DP<6>")
	)
	(segment
		(start 333.9465 -418.323522)
		(end 333.800958 -419.26764)
		(width 0.14732)
		(layer "In13.Cu")
		(net "P5E_CPU0_PE0_RX_DP<6>")
	)
	(segment
		(start 333.917798 -419.427152)
		(end 333.861664 -419.791388)
		(width 0.14732)
		(layer "In13.Cu")
		(net "P5E_CPU0_PE0_RX_DP<6>")
	)
	(segment
		(start 331.353922 -215.991186)
		(end 331.353922 -216.163652)
		(width 0.14732)
		(layer "In13.Cu")
		(net "P5E_CPU0_PE0_RX_DP<6>")
	)
	(segment
		(start 343.13368 -221.94774)
		(end 342.977216 -221.676722)
		(width 0.0889)
		(layer "In13.Cu")
		(net "P5E_CPU0_PE0_RX_DP<6>")
	)
	(segment
		(start 330.870814 -392.282934)
		(end 330.799948 -392.444224)
		(width 0.14732)
		(layer "In13.Cu")
		(net "P5E_CPU0_PE0_RX_DP<6>")
	)
	(segment
		(start 335.428082 -215.112346)
		(end 335.417668 -215.118442)
		(width 0.0889)
		(layer "In13.Cu")
		(net "P5E_CPU0_PE0_RX_DP<6>")
	)
	(segment
		(start 330.392278 -391.397998)
		(end 330.550774 -391.804906)
		(width 0.14732)
		(layer "In13.Cu")
		(net "P5E_CPU0_PE0_RX_DP<6>")
	)
	(segment
		(start 311.625488 -342.160098)
		(end 313.08294 -346.967556)
		(width 0.14732)
		(layer "In13.Cu")
		(net "P5E_CPU0_PE0_RX_DP<6>")
	)
	(segment
		(start 334.67548 -215.061292)
		(end 333.976726 -215.061292)
		(width 0.0889)
		(layer "In13.Cu")
		(net "P5E_CPU0_PE0_RX_DP<6>")
	)
	(segment
		(start 340.046564 -215.934798)
		(end 340.031832 -215.926162)
		(width 0.0889)
		(layer "In13.Cu")
		(net "P5E_CPU0_PE0_RX_DP<6>")
	)
	(segment
		(start 330.463144 -391.236708)
		(end 330.392278 -391.397998)
		(width 0.14732)
		(layer "In13.Cu")
		(net "P5E_CPU0_PE0_RX_DP<6>")
	)
	(segment
		(start 329.735688 -389.712708)
		(end 329.896724 -389.78332)
		(width 0.14732)
		(layer "In13.Cu")
		(net "P5E_CPU0_PE0_RX_DP<6>")
	)
	(segment
		(start 331.044804 -216.47277)
		(end 330.872338 -216.47277)
		(width 0.14732)
		(layer "In13.Cu")
		(net "P5E_CPU0_PE0_RX_DP<6>")
	)
	(segment
		(start 333.649828 -404.68169)
		(end 334.996028 -406.02789)
		(width 0.14732)
		(layer "In13.Cu")
		(net "P5E_CPU0_PE0_RX_DP<6>")
	)
	(segment
		(start 333.976726 -215.061292)
		(end 333.934562 -215.103456)
		(width 0.0889)
		(layer "In13.Cu")
		(net "P5E_CPU0_PE0_RX_DP<6>")
	)
	(segment
		(start 341.159084 -217.8939)
		(end 341.159084 -217.859864)
		(width 0.0889)
		(layer "In13.Cu")
		(net "P5E_CPU0_PE0_RX_DP<6>")
	)
	(segment
		(start 340.973156 -215.926924)
		(end 340.971632 -215.926162)
		(width 0.0889)
		(layer "In13.Cu")
		(net "P5E_CPU0_PE0_RX_DP<6>")
	)
	(segment
		(start 342.389968 -220.000576)
		(end 342.382094 -219.996004)
		(width 0.0889)
		(layer "In13.Cu")
		(net "P5E_CPU0_PE0_RX_DP<6>")
	)
	(segment
		(start 327.173082 -309.882794)
		(end 323.250306 -319.13322)
		(width 0.14732)
		(layer "In13.Cu")
		(net "P5E_CPU0_PE0_RX_DP<6>")
	)
	(segment
		(start 323.250306 -319.13322)
		(end 317.791846 -326.92848)
		(width 0.14732)
		(layer "In13.Cu")
		(net "P5E_CPU0_PE0_RX_DP<6>")
	)
	(segment
		(start 340.980522 -215.931242)
		(end 340.973156 -215.926924)
		(width 0.0889)
		(layer "In13.Cu")
		(net "P5E_CPU0_PE0_RX_DP<6>")
	)
	(segment
		(start 330.872338 -216.47277)
		(end 327.948036 -219.397326)
		(width 0.14732)
		(layer "In13.Cu")
		(net "P5E_CPU0_PE0_RX_DP<6>")
	)
	(segment
		(start 330.712064 -391.875772)
		(end 330.870814 -392.282934)
		(width 0.14732)
		(layer "In13.Cu")
		(net "P5E_CPU0_PE0_RX_DP<6>")
	)
	(segment
		(start 333.934562 -215.103456)
		(end 333.912464 -215.103456)
		(width 0.0889)
		(layer "In13.Cu")
		(net "P5E_CPU0_PE0_RX_DP<6>")
	)
	(segment
		(start 334.180688 -416.807142)
		(end 334.04556 -417.683188)
		(width 0.14732)
		(layer "In13.Cu")
		(net "P5E_CPU0_PE0_RX_DP<6>")
	)
	(segment
		(start 342.977216 -221.676722)
		(end 342.888316 -221.6531)
		(width 0.0889)
		(layer "In13.Cu")
		(net "P5E_CPU0_PE0_RX_DP<6>")
	)
	(segment
		(start 341.911432 -219.18168)
		(end 341.91067 -219.181172)
		(width 0.0889)
		(layer "In13.Cu")
		(net "P5E_CPU0_PE0_RX_DP<6>")
	)
	(segment
		(start 311.625488 -333.094584)
		(end 311.625488 -342.160098)
		(width 0.14732)
		(layer "In13.Cu")
		(net "P5E_CPU0_PE0_RX_DP<6>")
	)
	(segment
		(start 323.3801 -251.615956)
		(end 327.173082 -309.882794)
		(width 0.14732)
		(layer "In13.Cu")
		(net "P5E_CPU0_PE0_RX_DP<6>")
	)
	(segment
		(start 336.751168 -215.117426)
		(end 336.742278 -215.112346)
		(width 0.0889)
		(layer "In13.Cu")
		(net "P5E_CPU0_PE0_RX_DP<6>")
	)
	(segment
		(start 332.966822 -424.673268)
		(end 332.966822 -438.194958)
		(width 0.14732)
		(layer "In13.Cu")
		(net "P5E_CPU0_PE0_RX_DP<6>")
	)
	(segment
		(start 333.800958 -419.26764)
		(end 333.917798 -419.427152)
		(width 0.14732)
		(layer "In13.Cu")
		(net "P5E_CPU0_PE0_RX_DP<6>")
	)
	(segment
		(start 334.396334 -416.32632)
		(end 334.3402 -416.690556)
		(width 0.14732)
		(layer "In13.Cu")
		(net "P5E_CPU0_PE0_RX_DP<6>")
	)
	(segment
		(start 331.353922 -216.163652)
		(end 331.044804 -216.47277)
		(width 0.14732)
		(layer "In13.Cu")
		(net "P5E_CPU0_PE0_RX_DP<6>")
	)
	(segment
		(start 329.984608 -390.351772)
		(end 330.143104 -390.75868)
		(width 0.14732)
		(layer "In13.Cu")
		(net "P5E_CPU0_PE0_RX_DP<6>")
	)
	(segment
		(start 331.829664 -215.515444)
		(end 331.353922 -215.991186)
		(width 0.14732)
		(layer "In13.Cu")
		(net "P5E_CPU0_PE0_RX_DP<6>")
	)
	(segment
		(start 341.442294 -218.368372)
		(end 341.441278 -218.367864)
		(width 0.0889)
		(layer "In13.Cu")
		(net "P5E_CPU0_PE0_RX_DP<6>")
	)
	(segment
		(start 341.912956 -219.182442)
		(end 341.911432 -219.18168)
		(width 0.0889)
		(layer "In13.Cu")
		(net "P5E_CPU0_PE0_RX_DP<6>")
	)
	(segment
		(start 333.650082 -438.152286)
		(end 333.650082 -437.889904)
		(width 0.14732)
		(layer "In13.Cu")
		(net "P5E_CPU0_PE0_RX_DP<6>")
	)
	(segment
		(start 326.944482 -221.81947)
		(end 323.3801 -251.615956)
		(width 0.14732)
		(layer "In13.Cu")
		(net "P5E_CPU0_PE0_RX_DP<6>")
	)
	(segment
		(start 333.702152 -419.907974)
		(end 332.966822 -424.673268)
		(width 0.14732)
		(layer "In13.Cu")
		(net "P5E_CPU0_PE0_RX_DP<6>")
	)
	(segment
		(start 333.48295 -438.319418)
		(end 333.650082 -438.152286)
		(width 0.14732)
		(layer "In13.Cu")
		(net "P5E_CPU0_PE0_RX_DP<6>")
	)
	(segment
		(start 342.381078 -220.644212)
		(end 342.389968 -220.639132)
		(width 0.0889)
		(layer "In13.Cu")
		(net "P5E_CPU0_PE0_RX_DP<6>")
	)
	(segment
		(start 313.08294 -346.967556)
		(end 329.735688 -389.712708)
		(width 0.14732)
		(layer "In13.Cu")
		(net "P5E_CPU0_PE0_RX_DP<6>")
	)
	(segment
		(start 342.382094 -219.996004)
		(end 342.381078 -219.995496)
		(width 0.0889)
		(layer "In13.Cu")
		(net "P5E_CPU0_PE0_RX_DP<6>")
	)
	(segment
		(start 342.098884 -221.149418)
		(end 342.098884 -221.111826)
		(width 0.0889)
		(layer "In13.Cu")
		(net "P5E_CPU0_PE0_RX_DP<6>")
	)
	(segment
		(start 334.04556 -417.683188)
		(end 334.1624 -417.8427)
		(width 0.14732)
		(layer "In13.Cu")
		(net "P5E_CPU0_PE0_RX_DP<6>")
	)
	(segment
		(start 330.304394 -390.829546)
		(end 330.463144 -391.236708)
		(width 0.14732)
		(layer "In13.Cu")
		(net "P5E_CPU0_PE0_RX_DP<6>")
	)
	(segment
		(start 332.966822 -438.194958)
		(end 333.091282 -438.319418)
		(width 0.14732)
		(layer "In13.Cu")
		(net "P5E_CPU0_PE0_RX_DP<6>")
	)
	(segment
		(start 334.106266 -418.206936)
		(end 333.9465 -418.323522)
		(width 0.14732)
		(layer "In13.Cu")
		(net "P5E_CPU0_PE0_RX_DP<6>")
	)
	(segment
		(start 330.799948 -392.444224)
		(end 333.649828 -399.759678)
		(width 0.14732)
		(layer "In13.Cu")
		(net "P5E_CPU0_PE0_RX_DP<6>")
	)
	(segment
		(start 336.92973 -215.452198)
		(end 336.92973 -215.436704)
		(width 0.0889)
		(layer "In13.Cu")
		(net "P5E_CPU0_PE0_RX_DP<6>")
	)
	(segment
		(start 327.948036 -219.397326)
		(end 326.944482 -221.81947)
		(width 0.14732)
		(layer "In13.Cu")
		(net "P5E_CPU0_PE0_RX_DP<6>")
	)
	(segment
		(start 330.550774 -391.804906)
		(end 330.712064 -391.875772)
		(width 0.14732)
		(layer "In13.Cu")
		(net "P5E_CPU0_PE0_RX_DP<6>")
	)
	(segment
		(start 334.996028 -411.52318)
		(end 334.279748 -416.166808)
		(width 0.14732)
		(layer "In13.Cu")
		(net "P5E_CPU0_PE0_RX_DP<6>")
	)
	(segment
		(start 339.106764 -215.934798)
		(end 339.092032 -215.926162)
		(width 0.0889)
		(layer "In13.Cu")
		(net "P5E_CPU0_PE0_RX_DP<6>")
	)
	(segment
		(start 334.996028 -406.02789)
		(end 334.996028 -411.52318)
		(width 0.14732)
		(layer "In13.Cu")
		(net "P5E_CPU0_PE0_RX_DP<6>")
	)
	(segment
		(start 317.791846 -326.92848)
		(end 311.625488 -333.094584)
		(width 0.14732)
		(layer "In13.Cu")
		(net "P5E_CPU0_PE0_RX_DP<6>")
	)
	(segment
		(start 333.066136 -215.103456)
		(end 331.829664 -215.515444)
		(width 0.14732)
		(layer "In13.Cu")
		(net "P5E_CPU0_PE0_RX_DP<6>")
	)
	(segment
		(start 333.091282 -438.319418)
		(end 333.48295 -438.319418)
		(width 0.14732)
		(layer "In13.Cu")
		(net "P5E_CPU0_PE0_RX_DP<6>")
	)
	(segment
		(start 341.920322 -219.18676)
		(end 341.912956 -219.182442)
		(width 0.0889)
		(layer "In13.Cu")
		(net "P5E_CPU0_PE0_RX_DP<6>")
	)
	(segment
		(start 342.098884 -219.521532)
		(end 342.098884 -219.506038)
		(width 0.0889)
		(layer "In13.Cu")
		(net "P5E_CPU0_PE0_RX_DP<6>")
	)
	(segment
		(start 334.1624 -417.8427)
		(end 334.106266 -418.206936)
		(width 0.14732)
		(layer "In13.Cu")
		(net "P5E_CPU0_PE0_RX_DP<6>")
	)
	(segment
		(start 341.91067 -219.181172)
		(end 341.905336 -219.178124)
		(width 0.0889)
		(layer "In13.Cu")
		(net "P5E_CPU0_PE0_RX_DP<6>")
	)
	(segment
		(start 330.143104 -390.75868)
		(end 330.304394 -390.829546)
		(width 0.14732)
		(layer "In13.Cu")
		(net "P5E_CPU0_PE0_RX_DP<6>")
	)
	(segment
		(start 341.450168 -218.372944)
		(end 341.442294 -218.368372)
		(width 0.0889)
		(layer "In13.Cu")
		(net "P5E_CPU0_PE0_RX_DP<6>")
	)
	(segment
		(start 341.159084 -216.260426)
		(end 341.159084 -216.25052)
		(width 0.0889)
		(layer "In13.Cu")
		(net "P5E_CPU0_PE0_RX_DP<6>")
	)
	(segment
		(start 329.896724 -389.78332)
		(end 330.055474 -390.190482)
		(width 0.14732)
		(layer "In13.Cu")
		(net "P5E_CPU0_PE0_RX_DP<6>")
	)
	(segment
		(start 338.166964 -215.934798)
		(end 338.152232 -215.926162)
		(width 0.0889)
		(layer "In13.Cu")
		(net "P5E_CPU0_PE0_RX_DP<6>")
	)
	(segment
		(start 334.279748 -416.166808)
		(end 334.396334 -416.32632)
		(width 0.14732)
		(layer "In13.Cu")
		(net "P5E_CPU0_PE0_RX_DP<6>")
	)
	(segment
		(start 341.62873 -217.072972)
		(end 341.62873 -217.0557)
		(width 0.0889)
		(layer "In13.Cu")
		(net "P5E_CPU0_PE0_RX_DP<6>")
	)
	(arc
		(start 339.092032 -215.926162)
		(mid 338.904834 -215.876019)
		(end 338.717636 -215.926162)
		(width 0.0889)
		(layer "In13.Cu")
		(net "P5E_CPU0_PE0_RX_DP<6>")
	)
	(arc
		(start 341.441278 -218.367864)
		(mid 341.238455 -218.167633)
		(end 341.159084 -217.8939)
		(width 0.0889)
		(layer "In13.Cu")
		(net "P5E_CPU0_PE0_RX_DP<6>")
	)
	(arc
		(start 342.098884 -219.506038)
		(mid 342.051205 -219.323138)
		(end 341.920322 -219.18676)
		(width 0.0889)
		(layer "In13.Cu")
		(net "P5E_CPU0_PE0_RX_DP<6>")
	)
	(arc
		(start 341.905336 -219.178124)
		(mid 341.702749 -218.971773)
		(end 341.62873 -218.692222)
		(width 0.0889)
		(layer "In13.Cu")
		(net "P5E_CPU0_PE0_RX_DP<6>")
	)
	(arc
		(start 342.098884 -221.111826)
		(mid 342.179795 -220.841698)
		(end 342.381078 -220.644212)
		(width 0.0889)
		(layer "In13.Cu")
		(net "P5E_CPU0_PE0_RX_DP<6>")
	)
	(arc
		(start 340.031832 -215.926162)
		(mid 339.844634 -215.876019)
		(end 339.657436 -215.926162)
		(width 0.0889)
		(layer "In13.Cu")
		(net "P5E_CPU0_PE0_RX_DP<6>")
	)
	(arc
		(start 341.441532 -217.388694)
		(mid 341.576465 -217.25534)
		(end 341.62873 -217.072972)
		(width 0.0889)
		(layer "In13.Cu")
		(net "P5E_CPU0_PE0_RX_DP<6>")
	)
	(arc
		(start 341.441532 -216.739978)
		(mid 341.237197 -216.537373)
		(end 341.159084 -216.260426)
		(width 0.0889)
		(layer "In13.Cu")
		(net "P5E_CPU0_PE0_RX_DP<6>")
	)
	(arc
		(start 342.381078 -219.995496)
		(mid 342.178255 -219.795265)
		(end 342.098884 -219.521532)
		(width 0.0889)
		(layer "In13.Cu")
		(net "P5E_CPU0_PE0_RX_DP<6>")
	)
	(arc
		(start 340.597236 -215.926162)
		(mid 340.323037 -216.001997)
		(end 340.046564 -215.934798)
		(width 0.0889)
		(layer "In13.Cu")
		(net "P5E_CPU0_PE0_RX_DP<6>")
	)
	(arc
		(start 342.389968 -220.639132)
		(mid 342.568565 -220.319854)
		(end 342.389968 -220.000576)
		(width 0.0889)
		(layer "In13.Cu")
		(net "P5E_CPU0_PE0_RX_DP<6>")
	)
	(arc
		(start 335.417668 -215.118442)
		(mid 335.13949 -215.188134)
		(end 334.862932 -215.112346)
		(width 0.0889)
		(layer "In13.Cu")
		(net "P5E_CPU0_PE0_RX_DP<6>")
	)
	(arc
		(start 341.62873 -217.0557)
		(mid 341.57646 -216.873335)
		(end 341.441532 -216.739978)
		(width 0.0889)
		(layer "In13.Cu")
		(net "P5E_CPU0_PE0_RX_DP<6>")
	)
	(arc
		(start 336.367882 -215.112346)
		(mid 336.08518 -215.188088)
		(end 335.802478 -215.112346)
		(width 0.0889)
		(layer "In13.Cu")
		(net "P5E_CPU0_PE0_RX_DP<6>")
	)
	(arc
		(start 339.657436 -215.926162)
		(mid 339.383237 -216.001997)
		(end 339.106764 -215.934798)
		(width 0.0889)
		(layer "In13.Cu")
		(net "P5E_CPU0_PE0_RX_DP<6>")
	)
	(arc
		(start 337.777836 -215.926162)
		(mid 337.49488 -216.002065)
		(end 337.211924 -215.926162)
		(width 0.0889)
		(layer "In13.Cu")
		(net "P5E_CPU0_PE0_RX_DP<6>")
	)
	(arc
		(start 341.159084 -216.25052)
		(mid 341.111405 -216.06762)
		(end 340.980522 -215.931242)
		(width 0.0889)
		(layer "In13.Cu")
		(net "P5E_CPU0_PE0_RX_DP<6>")
	)
	(arc
		(start 342.868504 -221.661228)
		(mid 342.350914 -221.604895)
		(end 342.098884 -221.149418)
		(width 0.0889)
		(layer "In13.Cu")
		(net "P5E_CPU0_PE0_RX_DP<6>")
	)
	(arc
		(start 338.717636 -215.926162)
		(mid 338.443437 -216.001997)
		(end 338.166964 -215.934798)
		(width 0.0889)
		(layer "In13.Cu")
		(net "P5E_CPU0_PE0_RX_DP<6>")
	)
	(arc
		(start 341.62873 -218.692222)
		(mid 341.581051 -218.509322)
		(end 341.450168 -218.372944)
		(width 0.0889)
		(layer "In13.Cu")
		(net "P5E_CPU0_PE0_RX_DP<6>")
	)
	(arc
		(start 341.159084 -217.859864)
		(mid 341.239246 -217.587675)
		(end 341.441532 -217.388694)
		(width 0.0889)
		(layer "In13.Cu")
		(net "P5E_CPU0_PE0_RX_DP<6>")
	)
	(arc
		(start 336.742278 -215.112346)
		(mid 336.55508 -215.062203)
		(end 336.367882 -215.112346)
		(width 0.0889)
		(layer "In13.Cu")
		(net "P5E_CPU0_PE0_RX_DP<6>")
	)
	(arc
		(start 335.802478 -215.112346)
		(mid 335.61528 -215.062203)
		(end 335.428082 -215.112346)
		(width 0.0889)
		(layer "In13.Cu")
		(net "P5E_CPU0_PE0_RX_DP<6>")
	)
	(arc
		(start 338.152232 -215.926162)
		(mid 337.965034 -215.876019)
		(end 337.777836 -215.926162)
		(width 0.0889)
		(layer "In13.Cu")
		(net "P5E_CPU0_PE0_RX_DP<6>")
	)
	(arc
		(start 337.211924 -215.926162)
		(mid 337.009101 -215.725931)
		(end 336.92973 -215.452198)
		(width 0.0889)
		(layer "In13.Cu")
		(net "P5E_CPU0_PE0_RX_DP<6>")
	)
	(arc
		(start 342.888316 -221.6531)
		(mid 342.878449 -221.657259)
		(end 342.868504 -221.661228)
		(width 0.0889)
		(layer "In13.Cu")
		(net "P5E_CPU0_PE0_RX_DP<6>")
	)
	(arc
		(start 340.971632 -215.926162)
		(mid 340.784434 -215.876019)
		(end 340.597236 -215.926162)
		(width 0.0889)
		(layer "In13.Cu")
		(net "P5E_CPU0_PE0_RX_DP<6>")
	)
	(arc
		(start 336.92973 -215.436704)
		(mid 336.882051 -215.253804)
		(end 336.751168 -215.117426)
		(width 0.0889)
		(layer "In13.Cu")
		(net "P5E_CPU0_PE0_RX_DP<6>")
	)
	(arc
		(start 334.862932 -215.112346)
		(mid 334.772574 -215.074443)
		(end 334.67548 -215.061292)
		(width 0.0889)
		(layer "In13.Cu")
		(net "P5E_CPU0_PE0_RX_DP<6>")
	)
	(segment
		(start 341.72398 -221.669864)
		(end 341.72398 -221.134178)
		(width 0.13208)
		(layer "F.Cu")
		(net "P5E_CPU0_PE0_RX_DP<5>")
	)
	(segment
		(start 341.72398 -221.134178)
		(end 341.724234 -221.133924)
		(width 0.13208)
		(layer "F.Cu")
		(net "P5E_CPU0_PE0_RX_DP<5>")
	)
	(segment
		(start 334.966818 -437.17972)
		(end 335.106518 -437.31942)
		(width 0.14732)
		(layer "In13.Cu")
		(net "P5E_CPU0_PE0_RX_DP<5>")
	)
	(segment
		(start 336.35569 -419.213284)
		(end 336.188304 -419.318186)
		(width 0.14732)
		(layer "In13.Cu")
		(net "P5E_CPU0_PE0_RX_DP<5>")
	)
	(segment
		(start 331.915262 -388.522972)
		(end 332.085442 -388.925562)
		(width 0.14732)
		(layer "In13.Cu")
		(net "P5E_CPU0_PE0_RX_DP<5>")
	)
	(segment
		(start 328.586338 -252.324616)
		(end 326.074278 -258.767326)
		(width 0.14732)
		(layer "In13.Cu")
		(net "P5E_CPU0_PE0_RX_DP<5>")
	)
	(segment
		(start 328.669396 -220.187266)
		(end 327.87082 -222.115634)
		(width 0.14732)
		(layer "In13.Cu")
		(net "P5E_CPU0_PE0_RX_DP<5>")
	)
	(segment
		(start 340.502494 -218.368372)
		(end 340.501478 -218.367864)
		(width 0.0889)
		(layer "In13.Cu")
		(net "P5E_CPU0_PE0_RX_DP<5>")
	)
	(segment
		(start 336.540856 -417.77539)
		(end 336.33283 -418.686488)
		(width 0.14732)
		(layer "In13.Cu")
		(net "P5E_CPU0_PE0_RX_DP<5>")
	)
	(segment
		(start 333.064612 -391.559034)
		(end 333.227934 -391.625074)
		(width 0.14732)
		(layer "In13.Cu")
		(net "P5E_CPU0_PE0_RX_DP<5>")
	)
	(segment
		(start 312.56732 -342.004396)
		(end 313.768486 -345.964256)
		(width 0.14732)
		(layer "In13.Cu")
		(net "P5E_CPU0_PE0_RX_DP<5>")
	)
	(segment
		(start 340.127082 -216.739978)
		(end 340.116668 -216.746074)
		(width 0.0889)
		(layer "In13.Cu")
		(net "P5E_CPU0_PE0_RX_DP<5>")
	)
	(segment
		(start 332.790292 -390.59104)
		(end 332.960472 -390.99363)
		(width 0.14732)
		(layer "In13.Cu")
		(net "P5E_CPU0_PE0_RX_DP<5>")
	)
	(segment
		(start 340.980522 -219.18676)
		(end 340.971632 -219.18168)
		(width 0.0889)
		(layer "In13.Cu")
		(net "P5E_CPU0_PE0_RX_DP<5>")
	)
	(segment
		(start 335.959704 -420.318184)
		(end 334.966818 -424.66387)
		(width 0.14732)
		(layer "In13.Cu")
		(net "P5E_CPU0_PE0_RX_DP<5>")
	)
	(segment
		(start 335.650078 -437.152288)
		(end 335.650078 -436.889906)
		(width 0.14732)
		(layer "In13.Cu")
		(net "P5E_CPU0_PE0_RX_DP<5>")
	)
	(segment
		(start 332.131416 -216.927938)
		(end 331.79766 -217.209624)
		(width 0.14732)
		(layer "In13.Cu")
		(net "P5E_CPU0_PE0_RX_DP<5>")
	)
	(segment
		(start 332.189582 -389.490966)
		(end 332.35265 -389.557006)
		(width 0.14732)
		(layer "In13.Cu")
		(net "P5E_CPU0_PE0_RX_DP<5>")
	)
	(segment
		(start 335.81721 -216.748614)
		(end 335.802478 -216.739978)
		(width 0.0889)
		(layer "In13.Cu")
		(net "P5E_CPU0_PE0_RX_DP<5>")
	)
	(segment
		(start 341.724234 -221.133924)
		(end 341.880698 -220.862906)
		(width 0.0889)
		(layer "In13.Cu")
		(net "P5E_CPU0_PE0_RX_DP<5>")
	)
	(segment
		(start 338.247482 -216.739978)
		(end 338.237068 -216.746074)
		(width 0.0889)
		(layer "In13.Cu")
		(net "P5E_CPU0_PE0_RX_DP<5>")
	)
	(segment
		(start 328.278744 -250.555506)
		(end 328.586338 -251.298456)
		(width 0.14732)
		(layer "In13.Cu")
		(net "P5E_CPU0_PE0_RX_DP<5>")
	)
	(segment
		(start 339.187536 -216.739978)
		(end 339.177122 -216.746074)
		(width 0.0889)
		(layer "In13.Cu")
		(net "P5E_CPU0_PE0_RX_DP<5>")
	)
	(segment
		(start 341.880698 -220.862906)
		(end 341.856568 -220.773752)
		(width 0.0889)
		(layer "In13.Cu")
		(net "P5E_CPU0_PE0_RX_DP<5>")
	)
	(segment
		(start 332.793594 -216.689178)
		(end 332.563216 -216.756996)
		(width 0.0889)
		(layer "In13.Cu")
		(net "P5E_CPU0_PE0_RX_DP<5>")
	)
	(segment
		(start 313.768486 -345.964256)
		(end 331.75194 -388.456932)
		(width 0.14732)
		(layer "In13.Cu")
		(net "P5E_CPU0_PE0_RX_DP<5>")
	)
	(segment
		(start 340.219284 -217.8939)
		(end 340.219284 -217.856308)
		(width 0.0889)
		(layer "In13.Cu")
		(net "P5E_CPU0_PE0_RX_DP<5>")
	)
	(segment
		(start 326.05726 -258.811522)
		(end 325.356982 -266.59586)
		(width 0.14732)
		(layer "In13.Cu")
		(net "P5E_CPU0_PE0_RX_DP<5>")
	)
	(segment
		(start 326.73163 -233.138218)
		(end 326.975724 -246.511318)
		(width 0.14732)
		(layer "In13.Cu")
		(net "P5E_CPU0_PE0_RX_DP<5>")
	)
	(segment
		(start 337.090766 -415.997136)
		(end 337.008724 -416.356546)
		(width 0.14732)
		(layer "In13.Cu")
		(net "P5E_CPU0_PE0_RX_DP<5>")
	)
	(segment
		(start 341.62873 -220.334078)
		(end 341.62873 -220.311218)
		(width 0.0889)
		(layer "In13.Cu")
		(net "P5E_CPU0_PE0_RX_DP<5>")
	)
	(segment
		(start 332.960472 -390.99363)
		(end 332.894432 -391.156952)
		(width 0.14732)
		(layer "In13.Cu")
		(net "P5E_CPU0_PE0_RX_DP<5>")
	)
	(segment
		(start 332.404466 -216.847674)
		(end 332.383384 -216.85377)
		(width 0.0889)
		(layer "In13.Cu")
		(net "P5E_CPU0_PE0_RX_DP<5>")
	)
	(segment
		(start 336.75701 -216.748614)
		(end 336.742278 -216.739978)
		(width 0.0889)
		(layer "In13.Cu")
		(net "P5E_CPU0_PE0_RX_DP<5>")
	)
	(segment
		(start 336.12709 -420.213282)
		(end 335.959704 -420.318184)
		(width 0.14732)
		(layer "In13.Cu")
		(net "P5E_CPU0_PE0_RX_DP<5>")
	)
	(segment
		(start 326.071738 -258.774438)
		(end 326.05726 -258.811522)
		(width 0.14732)
		(layer "In13.Cu")
		(net "P5E_CPU0_PE0_RX_DP<5>")
	)
	(segment
		(start 334.862678 -216.739978)
		(end 334.8482 -216.731596)
		(width 0.0889)
		(layer "In13.Cu")
		(net "P5E_CPU0_PE0_RX_DP<5>")
	)
	(segment
		(start 332.45679 -390.122918)
		(end 332.62697 -390.525)
		(width 0.14732)
		(layer "In13.Cu")
		(net "P5E_CPU0_PE0_RX_DP<5>")
	)
	(segment
		(start 336.985356 -415.82975)
		(end 336.98561 -415.830004)
		(width 0.14732)
		(layer "In13.Cu")
		(net "P5E_CPU0_PE0_RX_DP<5>")
	)
	(segment
		(start 332.62697 -390.525)
		(end 332.790292 -390.59104)
		(width 0.14732)
		(layer "In13.Cu")
		(net "P5E_CPU0_PE0_RX_DP<5>")
	)
	(segment
		(start 329.889104 -218.819476)
		(end 328.669396 -220.187266)
		(width 0.14732)
		(layer "In13.Cu")
		(net "P5E_CPU0_PE0_RX_DP<5>")
	)
	(segment
		(start 336.713068 -400.179794)
		(end 336.713068 -404.68169)
		(width 0.14732)
		(layer "In13.Cu")
		(net "P5E_CPU0_PE0_RX_DP<5>")
	)
	(segment
		(start 341.159084 -219.515944)
		(end 341.159084 -219.506038)
		(width 0.0889)
		(layer "In13.Cu")
		(net "P5E_CPU0_PE0_RX_DP<5>")
	)
	(segment
		(start 337.008724 -416.356546)
		(end 336.841084 -416.461702)
		(width 0.14732)
		(layer "In13.Cu")
		(net "P5E_CPU0_PE0_RX_DP<5>")
	)
	(segment
		(start 326.074278 -258.767326)
		(end 326.071738 -258.774438)
		(width 0.14732)
		(layer "In13.Cu")
		(net "P5E_CPU0_PE0_RX_DP<5>")
	)
	(segment
		(start 334.87741 -216.748614)
		(end 334.862678 -216.739978)
		(width 0.0889)
		(layer "In13.Cu")
		(net "P5E_CPU0_PE0_RX_DP<5>")
	)
	(segment
		(start 332.019402 -389.088884)
		(end 332.189582 -389.490966)
		(width 0.14732)
		(layer "In13.Cu")
		(net "P5E_CPU0_PE0_RX_DP<5>")
	)
	(segment
		(start 338.059268 -406.02789)
		(end 338.059268 -411.128718)
		(width 0.14732)
		(layer "In13.Cu")
		(net "P5E_CPU0_PE0_RX_DP<5>")
	)
	(segment
		(start 336.841084 -416.461702)
		(end 336.685382 -417.143692)
		(width 0.14732)
		(layer "In13.Cu")
		(net "P5E_CPU0_PE0_RX_DP<5>")
	)
	(segment
		(start 332.563216 -216.756996)
		(end 332.43266 -216.795604)
		(width 0.0889)
		(layer "In13.Cu")
		(net "P5E_CPU0_PE0_RX_DP<5>")
	)
	(segment
		(start 328.586338 -251.298456)
		(end 328.586338 -252.324616)
		(width 0.14732)
		(layer "In13.Cu")
		(net "P5E_CPU0_PE0_RX_DP<5>")
	)
	(segment
		(start 336.437732 -418.853874)
		(end 336.35569 -419.213284)
		(width 0.14732)
		(layer "In13.Cu")
		(net "P5E_CPU0_PE0_RX_DP<5>")
	)
	(segment
		(start 332.35265 -389.557006)
		(end 332.52283 -389.959596)
		(width 0.14732)
		(layer "In13.Cu")
		(net "P5E_CPU0_PE0_RX_DP<5>")
	)
	(segment
		(start 331.782928 -217.381328)
		(end 331.448918 -217.663268)
		(width 0.14732)
		(layer "In13.Cu")
		(net "P5E_CPU0_PE0_RX_DP<5>")
	)
	(segment
		(start 335.482946 -437.31942)
		(end 335.650078 -437.152288)
		(width 0.14732)
		(layer "In13.Cu")
		(net "P5E_CPU0_PE0_RX_DP<5>")
	)
	(segment
		(start 336.188304 -419.318186)
		(end 336.10423 -419.686486)
		(width 0.14732)
		(layer "In13.Cu")
		(net "P5E_CPU0_PE0_RX_DP<5>")
	)
	(segment
		(start 337.682332 -216.739978)
		(end 337.67395 -216.735152)
		(width 0.0889)
		(layer "In13.Cu")
		(net "P5E_CPU0_PE0_RX_DP<5>")
	)
	(segment
		(start 318.54521 -327.496932)
		(end 312.56732 -333.474822)
		(width 0.14732)
		(layer "In13.Cu")
		(net "P5E_CPU0_PE0_RX_DP<5>")
	)
	(segment
		(start 325.356982 -266.59586)
		(end 328.125328 -310.074818)
		(width 0.14732)
		(layer "In13.Cu")
		(net "P5E_CPU0_PE0_RX_DP<5>")
	)
	(segment
		(start 340.501478 -217.388694)
		(end 340.510368 -217.383614)
		(width 0.0889)
		(layer "In13.Cu")
		(net "P5E_CPU0_PE0_RX_DP<5>")
	)
	(segment
		(start 340.510368 -218.372944)
		(end 340.502494 -218.368372)
		(width 0.0889)
		(layer "In13.Cu")
		(net "P5E_CPU0_PE0_RX_DP<5>")
	)
	(segment
		(start 331.79766 -217.209624)
		(end 331.782928 -217.381328)
		(width 0.14732)
		(layer "In13.Cu")
		(net "P5E_CPU0_PE0_RX_DP<5>")
	)
	(segment
		(start 336.790538 -417.311078)
		(end 336.708496 -417.670488)
		(width 0.14732)
		(layer "In13.Cu")
		(net "P5E_CPU0_PE0_RX_DP<5>")
	)
	(segment
		(start 328.125328 -310.074818)
		(end 324.17893 -319.451482)
		(width 0.14732)
		(layer "In13.Cu")
		(net "P5E_CPU0_PE0_RX_DP<5>")
	)
	(segment
		(start 333.227934 -391.625074)
		(end 333.398368 -392.027664)
		(width 0.14732)
		(layer "In13.Cu")
		(net "P5E_CPU0_PE0_RX_DP<5>")
	)
	(segment
		(start 326.975724 -246.511318)
		(end 327.789032 -249.639328)
		(width 0.14732)
		(layer "In13.Cu")
		(net "P5E_CPU0_PE0_RX_DP<5>")
	)
	(segment
		(start 327.87082 -222.115634)
		(end 326.73163 -233.138218)
		(width 0.14732)
		(layer "In13.Cu")
		(net "P5E_CPU0_PE0_RX_DP<5>")
	)
	(segment
		(start 338.059268 -411.128718)
		(end 336.985356 -415.82975)
		(width 0.14732)
		(layer "In13.Cu")
		(net "P5E_CPU0_PE0_RX_DP<5>")
	)
	(segment
		(start 327.789032 -249.639328)
		(end 328.278744 -250.555506)
		(width 0.14732)
		(layer "In13.Cu")
		(net "P5E_CPU0_PE0_RX_DP<5>")
	)
	(segment
		(start 333.332074 -392.190732)
		(end 336.713068 -400.179794)
		(width 0.14732)
		(layer "In13.Cu")
		(net "P5E_CPU0_PE0_RX_DP<5>")
	)
	(segment
		(start 336.685382 -417.143692)
		(end 336.790538 -417.311078)
		(width 0.14732)
		(layer "In13.Cu")
		(net "P5E_CPU0_PE0_RX_DP<5>")
	)
	(segment
		(start 324.17893 -319.451482)
		(end 318.54521 -327.496932)
		(width 0.14732)
		(layer "In13.Cu")
		(net "P5E_CPU0_PE0_RX_DP<5>")
	)
	(segment
		(start 336.10423 -419.686486)
		(end 336.209132 -419.853872)
		(width 0.14732)
		(layer "In13.Cu")
		(net "P5E_CPU0_PE0_RX_DP<5>")
	)
	(segment
		(start 336.33283 -418.686488)
		(end 336.437732 -418.853874)
		(width 0.14732)
		(layer "In13.Cu")
		(net "P5E_CPU0_PE0_RX_DP<5>")
	)
	(segment
		(start 332.52283 -389.959596)
		(end 332.45679 -390.122918)
		(width 0.14732)
		(layer "In13.Cu")
		(net "P5E_CPU0_PE0_RX_DP<5>")
	)
	(segment
		(start 334.966818 -424.66387)
		(end 334.966818 -437.17972)
		(width 0.14732)
		(layer "In13.Cu")
		(net "P5E_CPU0_PE0_RX_DP<5>")
	)
	(segment
		(start 336.98561 -415.830004)
		(end 337.090766 -415.997136)
		(width 0.14732)
		(layer "In13.Cu")
		(net "P5E_CPU0_PE0_RX_DP<5>")
	)
	(segment
		(start 332.383384 -216.85377)
		(end 332.131416 -216.927938)
		(width 0.14732)
		(layer "In13.Cu")
		(net "P5E_CPU0_PE0_RX_DP<5>")
	)
	(segment
		(start 332.894432 -391.156952)
		(end 333.064612 -391.559034)
		(width 0.14732)
		(layer "In13.Cu")
		(net "P5E_CPU0_PE0_RX_DP<5>")
	)
	(segment
		(start 332.99908 -216.750392)
		(end 332.981046 -216.739978)
		(width 0.0889)
		(layer "In13.Cu")
		(net "P5E_CPU0_PE0_RX_DP<5>")
	)
	(segment
		(start 340.971632 -219.18168)
		(end 340.965536 -219.178124)
		(width 0.0889)
		(layer "In13.Cu")
		(net "P5E_CPU0_PE0_RX_DP<5>")
	)
	(segment
		(start 331.27696 -217.64879)
		(end 329.889104 -218.819476)
		(width 0.14732)
		(layer "In13.Cu")
		(net "P5E_CPU0_PE0_RX_DP<5>")
	)
	(segment
		(start 336.209132 -419.853872)
		(end 336.12709 -420.213282)
		(width 0.14732)
		(layer "In13.Cu")
		(net "P5E_CPU0_PE0_RX_DP<5>")
	)
	(segment
		(start 331.75194 -388.456932)
		(end 331.915262 -388.522972)
		(width 0.14732)
		(layer "In13.Cu")
		(net "P5E_CPU0_PE0_RX_DP<5>")
	)
	(segment
		(start 312.56732 -333.474822)
		(end 312.56732 -342.004396)
		(width 0.14732)
		(layer "In13.Cu")
		(net "P5E_CPU0_PE0_RX_DP<5>")
	)
	(segment
		(start 340.510368 -216.745058)
		(end 340.501478 -216.739978)
		(width 0.0889)
		(layer "In13.Cu")
		(net "P5E_CPU0_PE0_RX_DP<5>")
	)
	(segment
		(start 333.943706 -216.752678)
		(end 333.898748 -216.72677)
		(width 0.0889)
		(layer "In13.Cu")
		(net "P5E_CPU0_PE0_RX_DP<5>")
	)
	(segment
		(start 333.398368 -392.027664)
		(end 333.332074 -392.190732)
		(width 0.14732)
		(layer "In13.Cu")
		(net "P5E_CPU0_PE0_RX_DP<5>")
	)
	(segment
		(start 336.708496 -417.670488)
		(end 336.540856 -417.77539)
		(width 0.14732)
		(layer "In13.Cu")
		(net "P5E_CPU0_PE0_RX_DP<5>")
	)
	(segment
		(start 336.713068 -404.68169)
		(end 338.059268 -406.02789)
		(width 0.14732)
		(layer "In13.Cu")
		(net "P5E_CPU0_PE0_RX_DP<5>")
	)
	(segment
		(start 332.43266 -216.795604)
		(end 332.404466 -216.847674)
		(width 0.0889)
		(layer "In13.Cu")
		(net "P5E_CPU0_PE0_RX_DP<5>")
	)
	(segment
		(start 331.448918 -217.663268)
		(end 331.27696 -217.64879)
		(width 0.14732)
		(layer "In13.Cu")
		(net "P5E_CPU0_PE0_RX_DP<5>")
	)
	(segment
		(start 332.085442 -388.925562)
		(end 332.019402 -389.088884)
		(width 0.14732)
		(layer "In13.Cu")
		(net "P5E_CPU0_PE0_RX_DP<5>")
	)
	(segment
		(start 335.106518 -437.31942)
		(end 335.482946 -437.31942)
		(width 0.14732)
		(layer "In13.Cu")
		(net "P5E_CPU0_PE0_RX_DP<5>")
	)
	(arc
		(start 337.67395 -216.735152)
		(mid 337.490188 -216.689752)
		(end 337.307682 -216.739978)
		(width 0.0889)
		(layer "In13.Cu")
		(net "P5E_CPU0_PE0_RX_DP<5>")
	)
	(arc
		(start 340.501478 -218.367864)
		(mid 340.298655 -218.167633)
		(end 340.219284 -217.8939)
		(width 0.0889)
		(layer "In13.Cu")
		(net "P5E_CPU0_PE0_RX_DP<5>")
	)
	(arc
		(start 335.802478 -216.739978)
		(mid 335.61528 -216.689835)
		(end 335.428082 -216.739978)
		(width 0.0889)
		(layer "In13.Cu")
		(net "P5E_CPU0_PE0_RX_DP<5>")
	)
	(arc
		(start 341.83955 -220.760798)
		(mid 341.687063 -220.570702)
		(end 341.62873 -220.334078)
		(width 0.0889)
		(layer "In13.Cu")
		(net "P5E_CPU0_PE0_RX_DP<5>")
	)
	(arc
		(start 337.307682 -216.739978)
		(mid 337.033483 -216.815813)
		(end 336.75701 -216.748614)
		(width 0.0889)
		(layer "In13.Cu")
		(net "P5E_CPU0_PE0_RX_DP<5>")
	)
	(arc
		(start 341.441532 -219.995496)
		(mid 341.237197 -219.792891)
		(end 341.159084 -219.515944)
		(width 0.0889)
		(layer "In13.Cu")
		(net "P5E_CPU0_PE0_RX_DP<5>")
	)
	(arc
		(start 341.159084 -219.506038)
		(mid 341.111405 -219.323138)
		(end 340.980522 -219.18676)
		(width 0.0889)
		(layer "In13.Cu")
		(net "P5E_CPU0_PE0_RX_DP<5>")
	)
	(arc
		(start 340.965536 -219.178124)
		(mid 340.762949 -218.971773)
		(end 340.68893 -218.692222)
		(width 0.0889)
		(layer "In13.Cu")
		(net "P5E_CPU0_PE0_RX_DP<5>")
	)
	(arc
		(start 339.177122 -216.746074)
		(mid 338.89869 -216.81592)
		(end 338.621878 -216.739978)
		(width 0.0889)
		(layer "In13.Cu")
		(net "P5E_CPU0_PE0_RX_DP<5>")
	)
	(arc
		(start 336.742278 -216.739978)
		(mid 336.55508 -216.689835)
		(end 336.367882 -216.739978)
		(width 0.0889)
		(layer "In13.Cu")
		(net "P5E_CPU0_PE0_RX_DP<5>")
	)
	(arc
		(start 332.981046 -216.739978)
		(mid 332.890667 -216.702223)
		(end 332.793594 -216.689178)
		(width 0.0889)
		(layer "In13.Cu")
		(net "P5E_CPU0_PE0_RX_DP<5>")
	)
	(arc
		(start 336.367882 -216.739978)
		(mid 336.093683 -216.815813)
		(end 335.81721 -216.748614)
		(width 0.0889)
		(layer "In13.Cu")
		(net "P5E_CPU0_PE0_RX_DP<5>")
	)
	(arc
		(start 334.8482 -216.731596)
		(mid 334.666783 -216.689539)
		(end 334.48752 -216.739978)
		(width 0.0889)
		(layer "In13.Cu")
		(net "P5E_CPU0_PE0_RX_DP<5>")
	)
	(arc
		(start 339.561932 -216.739978)
		(mid 339.374734 -216.689835)
		(end 339.187536 -216.739978)
		(width 0.0889)
		(layer "In13.Cu")
		(net "P5E_CPU0_PE0_RX_DP<5>")
	)
	(arc
		(start 335.428082 -216.739978)
		(mid 335.153883 -216.815813)
		(end 334.87741 -216.748614)
		(width 0.0889)
		(layer "In13.Cu")
		(net "P5E_CPU0_PE0_RX_DP<5>")
	)
	(arc
		(start 334.48752 -216.739978)
		(mid 334.217242 -216.815982)
		(end 333.943706 -216.752678)
		(width 0.0889)
		(layer "In13.Cu")
		(net "P5E_CPU0_PE0_RX_DP<5>")
	)
	(arc
		(start 340.116668 -216.746074)
		(mid 339.83849 -216.815797)
		(end 339.561932 -216.739978)
		(width 0.0889)
		(layer "In13.Cu")
		(net "P5E_CPU0_PE0_RX_DP<5>")
	)
	(arc
		(start 338.621878 -216.739978)
		(mid 338.43468 -216.689835)
		(end 338.247482 -216.739978)
		(width 0.0889)
		(layer "In13.Cu")
		(net "P5E_CPU0_PE0_RX_DP<5>")
	)
	(arc
		(start 340.510368 -217.383614)
		(mid 340.688965 -217.064336)
		(end 340.510368 -216.745058)
		(width 0.0889)
		(layer "In13.Cu")
		(net "P5E_CPU0_PE0_RX_DP<5>")
	)
	(arc
		(start 333.898748 -216.72677)
		(mid 333.72159 -216.689712)
		(end 333.54772 -216.739978)
		(width 0.0889)
		(layer "In13.Cu")
		(net "P5E_CPU0_PE0_RX_DP<5>")
	)
	(arc
		(start 333.54772 -216.739978)
		(mid 333.274746 -216.816161)
		(end 332.99908 -216.750392)
		(width 0.0889)
		(layer "In13.Cu")
		(net "P5E_CPU0_PE0_RX_DP<5>")
	)
	(arc
		(start 341.856568 -220.773752)
		(mid 341.847997 -220.767356)
		(end 341.83955 -220.760798)
		(width 0.0889)
		(layer "In13.Cu")
		(net "P5E_CPU0_PE0_RX_DP<5>")
	)
	(arc
		(start 341.62873 -220.311218)
		(mid 341.57646 -220.128853)
		(end 341.441532 -219.995496)
		(width 0.0889)
		(layer "In13.Cu")
		(net "P5E_CPU0_PE0_RX_DP<5>")
	)
	(arc
		(start 340.219284 -217.856308)
		(mid 340.300195 -217.58618)
		(end 340.501478 -217.388694)
		(width 0.0889)
		(layer "In13.Cu")
		(net "P5E_CPU0_PE0_RX_DP<5>")
	)
	(arc
		(start 340.68893 -218.692222)
		(mid 340.641251 -218.509322)
		(end 340.510368 -218.372944)
		(width 0.0889)
		(layer "In13.Cu")
		(net "P5E_CPU0_PE0_RX_DP<5>")
	)
	(arc
		(start 338.237068 -216.746074)
		(mid 337.95889 -216.815797)
		(end 337.682332 -216.739978)
		(width 0.0889)
		(layer "In13.Cu")
		(net "P5E_CPU0_PE0_RX_DP<5>")
	)
	(arc
		(start 340.501478 -216.739978)
		(mid 340.31428 -216.689835)
		(end 340.127082 -216.739978)
		(width 0.0889)
		(layer "In13.Cu")
		(net "P5E_CPU0_PE0_RX_DP<5>")
	)
	(segment
		(start 341.254334 -221.947994)
		(end 341.25408 -221.94774)
		(width 0.13208)
		(layer "F.Cu")
		(net "P5E_CPU0_PE0_RX_DP<4>")
	)
	(segment
		(start 341.254334 -222.48368)
		(end 341.254334 -221.947994)
		(width 0.13208)
		(layer "F.Cu")
		(net "P5E_CPU0_PE0_RX_DP<4>")
	)
	(segment
		(start 327.710038 -233.450384)
		(end 327.94956 -246.54637)
		(width 0.14732)
		(layer "In13.Cu")
		(net "P5E_CPU0_PE0_RX_DP<4>")
	)
	(segment
		(start 340.219284 -219.521532)
		(end 340.219284 -219.506038)
		(width 0.0889)
		(layer "In13.Cu")
		(net "P5E_CPU0_PE0_RX_DP<4>")
	)
	(segment
		(start 336.966814 -424.542458)
		(end 336.966814 -438.194958)
		(width 0.14732)
		(layer "In13.Cu")
		(net "P5E_CPU0_PE0_RX_DP<4>")
	)
	(segment
		(start 340.031832 -219.18168)
		(end 340.025736 -219.178124)
		(width 0.0889)
		(layer "In13.Cu")
		(net "P5E_CPU0_PE0_RX_DP<4>")
	)
	(segment
		(start 337.986878 -421.192452)
		(end 336.966814 -424.542458)
		(width 0.14732)
		(layer "In13.Cu")
		(net "P5E_CPU0_PE0_RX_DP<4>")
	)
	(segment
		(start 332.908402 -217.709242)
		(end 332.908402 -217.769186)
		(width 0.0889)
		(layer "In13.Cu")
		(net "P5E_CPU0_PE0_RX_DP<4>")
	)
	(segment
		(start 338.61502 -419.61054)
		(end 338.507578 -419.963092)
		(width 0.14732)
		(layer "In13.Cu")
		(net "P5E_CPU0_PE0_RX_DP<4>")
	)
	(segment
		(start 341.122508 -410.896054)
		(end 339.261958 -417.006278)
		(width 0.14732)
		(layer "In13.Cu")
		(net "P5E_CPU0_PE0_RX_DP<4>")
	)
	(segment
		(start 335.767172 -391.344404)
		(end 335.949544 -391.741152)
		(width 0.14732)
		(layer "In13.Cu")
		(net "P5E_CPU0_PE0_RX_DP<4>")
	)
	(segment
		(start 338.161376 -421.099488)
		(end 337.986878 -421.192452)
		(width 0.14732)
		(layer "In13.Cu")
		(net "P5E_CPU0_PE0_RX_DP<4>")
	)
	(segment
		(start 325.007478 -319.985898)
		(end 319.340738 -328.078084)
		(width 0.14732)
		(layer "In13.Cu")
		(net "P5E_CPU0_PE0_RX_DP<4>")
	)
	(segment
		(start 335.48066 -390.720834)
		(end 335.646014 -390.782048)
		(width 0.14732)
		(layer "In13.Cu")
		(net "P5E_CPU0_PE0_RX_DP<4>")
	)
	(segment
		(start 338.903056 -418.185854)
		(end 338.995766 -418.360098)
		(width 0.14732)
		(layer "In13.Cu")
		(net "P5E_CPU0_PE0_RX_DP<4>")
	)
	(segment
		(start 332.908402 -217.769186)
		(end 332.892908 -217.78468)
		(width 0.0889)
		(layer "In13.Cu")
		(net "P5E_CPU0_PE0_RX_DP<4>")
	)
	(segment
		(start 336.287364 -217.562684)
		(end 336.272632 -217.554048)
		(width 0.0889)
		(layer "In13.Cu")
		(net "P5E_CPU0_PE0_RX_DP<4>")
	)
	(segment
		(start 341.25408 -221.94774)
		(end 341.097616 -221.676722)
		(width 0.0889)
		(layer "In13.Cu")
		(net "P5E_CPU0_PE0_RX_DP<4>")
	)
	(segment
		(start 330.6318 -219.52585)
		(end 329.456288 -220.774768)
		(width 0.14732)
		(layer "In13.Cu")
		(net "P5E_CPU0_PE0_RX_DP<4>")
	)
	(segment
		(start 313.49696 -341.215472)
		(end 314.535312 -345.146122)
		(width 0.14732)
		(layer "In13.Cu")
		(net "P5E_CPU0_PE0_RX_DP<4>")
	)
	(segment
		(start 332.388972 -218.283028)
		(end 330.6318 -219.52585)
		(width 0.14732)
		(layer "In13.Cu")
		(net "P5E_CPU0_PE0_RX_DP<4>")
	)
	(segment
		(start 338.175854 -420.572692)
		(end 338.268818 -420.746936)
		(width 0.14732)
		(layer "In13.Cu")
		(net "P5E_CPU0_PE0_RX_DP<4>")
	)
	(segment
		(start 329.52182 -251.126752)
		(end 329.52182 -252.500384)
		(width 0.14732)
		(layer "In13.Cu")
		(net "P5E_CPU0_PE0_RX_DP<4>")
	)
	(segment
		(start 336.236056 -392.364468)
		(end 339.776308 -400.06778)
		(width 0.14732)
		(layer "In13.Cu")
		(net "P5E_CPU0_PE0_RX_DP<4>")
	)
	(segment
		(start 338.71408 -418.805614)
		(end 338.522056 -419.436296)
		(width 0.14732)
		(layer "In13.Cu")
		(net "P5E_CPU0_PE0_RX_DP<4>")
	)
	(segment
		(start 338.507578 -419.963092)
		(end 338.33308 -420.056056)
		(width 0.14732)
		(layer "In13.Cu")
		(net "P5E_CPU0_PE0_RX_DP<4>")
	)
	(segment
		(start 314.535312 -345.146122)
		(end 335.011522 -389.700262)
		(width 0.14732)
		(layer "In13.Cu")
		(net "P5E_CPU0_PE0_RX_DP<4>")
	)
	(segment
		(start 338.717636 -217.554048)
		(end 338.708746 -217.559128)
		(width 0.0889)
		(layer "In13.Cu")
		(net "P5E_CPU0_PE0_RX_DP<4>")
	)
	(segment
		(start 338.2518 -218.365324)
		(end 338.249768 -218.366594)
		(width 0.0889)
		(layer "In13.Cu")
		(net "P5E_CPU0_PE0_RX_DP<4>")
	)
	(segment
		(start 333.00416 -217.613484)
		(end 332.908402 -217.709242)
		(width 0.0889)
		(layer "In13.Cu")
		(net "P5E_CPU0_PE0_RX_DP<4>")
	)
	(segment
		(start 326.977756 -259.027422)
		(end 326.295512 -266.608052)
		(width 0.14732)
		(layer "In13.Cu")
		(net "P5E_CPU0_PE0_RX_DP<4>")
	)
	(segment
		(start 339.279484 -217.8939)
		(end 339.279484 -217.878406)
		(width 0.0889)
		(layer "In13.Cu")
		(net "P5E_CPU0_PE0_RX_DP<4>")
	)
	(segment
		(start 337.482942 -438.319418)
		(end 337.650074 -438.152286)
		(width 0.14732)
		(layer "In13.Cu")
		(net "P5E_CPU0_PE0_RX_DP<4>")
	)
	(segment
		(start 340.502494 -219.996004)
		(end 340.501478 -219.995496)
		(width 0.0889)
		(layer "In13.Cu")
		(net "P5E_CPU0_PE0_RX_DP<4>")
	)
	(segment
		(start 337.221322 -217.559128)
		(end 337.212432 -217.554048)
		(width 0.0889)
		(layer "In13.Cu")
		(net "P5E_CPU0_PE0_RX_DP<4>")
	)
	(segment
		(start 334.957928 -217.554048)
		(end 334.947514 -217.560144)
		(width 0.0889)
		(layer "In13.Cu")
		(net "P5E_CPU0_PE0_RX_DP<4>")
	)
	(segment
		(start 338.253578 -218.364308)
		(end 338.2518 -218.365324)
		(width 0.0889)
		(layer "In13.Cu")
		(net "P5E_CPU0_PE0_RX_DP<4>")
	)
	(segment
		(start 338.268818 -420.746936)
		(end 338.161376 -421.099488)
		(width 0.14732)
		(layer "In13.Cu")
		(net "P5E_CPU0_PE0_RX_DP<4>")
	)
	(segment
		(start 339.247734 -417.533836)
		(end 339.073236 -417.6268)
		(width 0.14732)
		(layer "In13.Cu")
		(net "P5E_CPU0_PE0_RX_DP<4>")
	)
	(segment
		(start 336.966814 -438.194958)
		(end 337.091274 -438.319418)
		(width 0.14732)
		(layer "In13.Cu")
		(net "P5E_CPU0_PE0_RX_DP<4>")
	)
	(segment
		(start 339.776308 -404.68169)
		(end 341.122508 -406.02789)
		(width 0.14732)
		(layer "In13.Cu")
		(net "P5E_CPU0_PE0_RX_DP<4>")
	)
	(segment
		(start 335.949544 -391.741152)
		(end 336.114898 -391.802366)
		(width 0.14732)
		(layer "In13.Cu")
		(net "P5E_CPU0_PE0_RX_DP<4>")
	)
	(segment
		(start 335.298288 -390.323578)
		(end 335.48066 -390.720834)
		(width 0.14732)
		(layer "In13.Cu")
		(net "P5E_CPU0_PE0_RX_DP<4>")
	)
	(segment
		(start 328.669904 -249.313954)
		(end 329.118214 -250.152408)
		(width 0.14732)
		(layer "In13.Cu")
		(net "P5E_CPU0_PE0_RX_DP<4>")
	)
	(segment
		(start 339.073236 -417.6268)
		(end 338.903056 -418.185854)
		(width 0.14732)
		(layer "In13.Cu")
		(net "P5E_CPU0_PE0_RX_DP<4>")
	)
	(segment
		(start 328.820526 -222.30842)
		(end 327.710038 -233.450384)
		(width 0.14732)
		(layer "In13.Cu")
		(net "P5E_CPU0_PE0_RX_DP<4>")
	)
	(segment
		(start 336.29727 -392.199622)
		(end 336.236056 -392.364468)
		(width 0.14732)
		(layer "In13.Cu")
		(net "P5E_CPU0_PE0_RX_DP<4>")
	)
	(segment
		(start 339.776308 -400.06778)
		(end 339.776308 -404.68169)
		(width 0.14732)
		(layer "In13.Cu")
		(net "P5E_CPU0_PE0_RX_DP<4>")
	)
	(segment
		(start 319.340738 -328.078084)
		(end 313.49696 -333.921862)
		(width 0.14732)
		(layer "In13.Cu")
		(net "P5E_CPU0_PE0_RX_DP<4>")
	)
	(segment
		(start 338.995766 -418.360098)
		(end 338.888578 -418.71265)
		(width 0.14732)
		(layer "In13.Cu")
		(net "P5E_CPU0_PE0_RX_DP<4>")
	)
	(segment
		(start 338.249768 -218.366594)
		(end 338.247482 -218.367864)
		(width 0.0889)
		(layer "In13.Cu")
		(net "P5E_CPU0_PE0_RX_DP<4>")
	)
	(segment
		(start 337.399884 -217.8939)
		(end 337.399884 -217.878406)
		(width 0.0889)
		(layer "In13.Cu")
		(net "P5E_CPU0_PE0_RX_DP<4>")
	)
	(segment
		(start 335.359248 -390.158732)
		(end 335.298288 -390.323578)
		(width 0.14732)
		(layer "In13.Cu")
		(net "P5E_CPU0_PE0_RX_DP<4>")
	)
	(segment
		(start 329.456288 -220.774768)
		(end 328.820526 -222.30842)
		(width 0.14732)
		(layer "In13.Cu")
		(net "P5E_CPU0_PE0_RX_DP<4>")
	)
	(segment
		(start 337.091274 -438.319418)
		(end 337.482942 -438.319418)
		(width 0.14732)
		(layer "In13.Cu")
		(net "P5E_CPU0_PE0_RX_DP<4>")
	)
	(segment
		(start 339.570568 -218.372944)
		(end 339.562694 -218.368372)
		(width 0.0889)
		(layer "In13.Cu")
		(net "P5E_CPU0_PE0_RX_DP<4>")
	)
	(segment
		(start 332.892908 -217.78468)
		(end 332.39456 -218.283028)
		(width 0.14732)
		(layer "In13.Cu")
		(net "P5E_CPU0_PE0_RX_DP<4>")
	)
	(segment
		(start 338.888578 -418.71265)
		(end 338.71408 -418.805614)
		(width 0.14732)
		(layer "In13.Cu")
		(net "P5E_CPU0_PE0_RX_DP<4>")
	)
	(segment
		(start 337.650074 -438.152286)
		(end 337.650074 -437.889904)
		(width 0.14732)
		(layer "In13.Cu")
		(net "P5E_CPU0_PE0_RX_DP<4>")
	)
	(segment
		(start 340.219284 -221.149418)
		(end 340.219284 -221.111826)
		(width 0.0889)
		(layer "In13.Cu")
		(net "P5E_CPU0_PE0_RX_DP<4>")
	)
	(segment
		(start 332.39456 -218.283028)
		(end 332.388972 -218.283028)
		(width 0.14732)
		(layer "In13.Cu")
		(net "P5E_CPU0_PE0_RX_DP<4>")
	)
	(segment
		(start 339.562694 -218.368372)
		(end 339.561678 -218.367864)
		(width 0.0889)
		(layer "In13.Cu")
		(net "P5E_CPU0_PE0_RX_DP<4>")
	)
	(segment
		(start 340.510368 -220.000576)
		(end 340.502494 -219.996004)
		(width 0.0889)
		(layer "In13.Cu")
		(net "P5E_CPU0_PE0_RX_DP<4>")
	)
	(segment
		(start 339.262212 -417.006786)
		(end 339.355176 -417.18103)
		(width 0.14732)
		(layer "In13.Cu")
		(net "P5E_CPU0_PE0_RX_DP<4>")
	)
	(segment
		(start 329.078082 -310.314086)
		(end 325.007478 -319.985898)
		(width 0.14732)
		(layer "In13.Cu")
		(net "P5E_CPU0_PE0_RX_DP<4>")
	)
	(segment
		(start 336.114898 -391.802366)
		(end 336.29727 -392.199622)
		(width 0.14732)
		(layer "In13.Cu")
		(net "P5E_CPU0_PE0_RX_DP<4>")
	)
	(segment
		(start 326.295512 -266.608052)
		(end 329.078082 -310.314086)
		(width 0.14732)
		(layer "In13.Cu")
		(net "P5E_CPU0_PE0_RX_DP<4>")
	)
	(segment
		(start 329.52182 -252.500384)
		(end 326.977756 -259.027422)
		(width 0.14732)
		(layer "In13.Cu")
		(net "P5E_CPU0_PE0_RX_DP<4>")
	)
	(segment
		(start 335.646014 -390.782048)
		(end 335.828386 -391.179304)
		(width 0.14732)
		(layer "In13.Cu")
		(net "P5E_CPU0_PE0_RX_DP<4>")
	)
	(segment
		(start 335.828386 -391.179304)
		(end 335.767172 -391.344404)
		(width 0.14732)
		(layer "In13.Cu")
		(net "P5E_CPU0_PE0_RX_DP<4>")
	)
	(segment
		(start 335.176876 -389.761476)
		(end 335.359248 -390.158732)
		(width 0.14732)
		(layer "In13.Cu")
		(net "P5E_CPU0_PE0_RX_DP<4>")
	)
	(segment
		(start 339.355176 -417.18103)
		(end 339.247734 -417.533836)
		(width 0.14732)
		(layer "In13.Cu")
		(net "P5E_CPU0_PE0_RX_DP<4>")
	)
	(segment
		(start 313.49696 -333.921862)
		(end 313.49696 -341.215472)
		(width 0.14732)
		(layer "In13.Cu")
		(net "P5E_CPU0_PE0_RX_DP<4>")
	)
	(segment
		(start 338.522056 -419.436296)
		(end 338.61502 -419.61054)
		(width 0.14732)
		(layer "In13.Cu")
		(net "P5E_CPU0_PE0_RX_DP<4>")
	)
	(segment
		(start 340.040722 -219.18676)
		(end 340.031832 -219.18168)
		(width 0.0889)
		(layer "In13.Cu")
		(net "P5E_CPU0_PE0_RX_DP<4>")
	)
	(segment
		(start 339.100922 -217.559128)
		(end 339.092032 -217.554048)
		(width 0.0889)
		(layer "In13.Cu")
		(net "P5E_CPU0_PE0_RX_DP<4>")
	)
	(segment
		(start 338.33308 -420.056056)
		(end 338.175854 -420.572692)
		(width 0.14732)
		(layer "In13.Cu")
		(net "P5E_CPU0_PE0_RX_DP<4>")
	)
	(segment
		(start 327.94956 -246.54637)
		(end 328.669904 -249.313954)
		(width 0.14732)
		(layer "In13.Cu")
		(net "P5E_CPU0_PE0_RX_DP<4>")
	)
	(segment
		(start 341.122508 -406.02789)
		(end 341.122508 -410.896054)
		(width 0.14732)
		(layer "In13.Cu")
		(net "P5E_CPU0_PE0_RX_DP<4>")
	)
	(segment
		(start 335.011522 -389.700262)
		(end 335.176876 -389.761476)
		(width 0.14732)
		(layer "In13.Cu")
		(net "P5E_CPU0_PE0_RX_DP<4>")
	)
	(segment
		(start 341.097616 -221.676722)
		(end 341.008716 -221.6531)
		(width 0.0889)
		(layer "In13.Cu")
		(net "P5E_CPU0_PE0_RX_DP<4>")
	)
	(segment
		(start 329.118214 -250.152408)
		(end 329.52182 -251.126752)
		(width 0.14732)
		(layer "In13.Cu")
		(net "P5E_CPU0_PE0_RX_DP<4>")
	)
	(segment
		(start 340.501478 -220.644212)
		(end 340.510368 -220.639132)
		(width 0.0889)
		(layer "In13.Cu")
		(net "P5E_CPU0_PE0_RX_DP<4>")
	)
	(segment
		(start 338.247482 -218.367864)
		(end 338.23275 -218.3765)
		(width 0.0889)
		(layer "In13.Cu")
		(net "P5E_CPU0_PE0_RX_DP<4>")
	)
	(segment
		(start 339.261958 -417.006278)
		(end 339.262212 -417.006786)
		(width 0.14732)
		(layer "In13.Cu")
		(net "P5E_CPU0_PE0_RX_DP<4>")
	)
	(arc
		(start 337.212432 -217.554048)
		(mid 337.025234 -217.503905)
		(end 336.838036 -217.554048)
		(width 0.0889)
		(layer "In13.Cu")
		(net "P5E_CPU0_PE0_RX_DP<4>")
	)
	(arc
		(start 339.092032 -217.554048)
		(mid 338.904834 -217.503905)
		(end 338.717636 -217.554048)
		(width 0.0889)
		(layer "In13.Cu")
		(net "P5E_CPU0_PE0_RX_DP<4>")
	)
	(arc
		(start 340.219284 -219.506038)
		(mid 340.171605 -219.323138)
		(end 340.040722 -219.18676)
		(width 0.0889)
		(layer "In13.Cu")
		(net "P5E_CPU0_PE0_RX_DP<4>")
	)
	(arc
		(start 335.898236 -217.554048)
		(mid 335.61528 -217.629917)
		(end 335.332324 -217.554048)
		(width 0.0889)
		(layer "In13.Cu")
		(net "P5E_CPU0_PE0_RX_DP<4>")
	)
	(arc
		(start 340.510368 -220.639132)
		(mid 340.688965 -220.319854)
		(end 340.510368 -220.000576)
		(width 0.0889)
		(layer "In13.Cu")
		(net "P5E_CPU0_PE0_RX_DP<4>")
	)
	(arc
		(start 338.23275 -218.3765)
		(mid 337.956275 -218.44382)
		(end 337.682078 -218.367864)
		(width 0.0889)
		(layer "In13.Cu")
		(net "P5E_CPU0_PE0_RX_DP<4>")
	)
	(arc
		(start 334.947514 -217.560144)
		(mid 334.669336 -217.629836)
		(end 334.392778 -217.554048)
		(width 0.0889)
		(layer "In13.Cu")
		(net "P5E_CPU0_PE0_RX_DP<4>")
	)
	(arc
		(start 334.018382 -217.554048)
		(mid 333.73568 -217.62979)
		(end 333.452978 -217.554048)
		(width 0.0889)
		(layer "In13.Cu")
		(net "P5E_CPU0_PE0_RX_DP<4>")
	)
	(arc
		(start 333.452978 -217.554048)
		(mid 333.26578 -217.503905)
		(end 333.078582 -217.554048)
		(width 0.0889)
		(layer "In13.Cu")
		(net "P5E_CPU0_PE0_RX_DP<4>")
	)
	(arc
		(start 340.988904 -221.661228)
		(mid 340.740893 -221.697693)
		(end 340.501478 -221.623382)
		(width 0.0889)
		(layer "In13.Cu")
		(net "P5E_CPU0_PE0_RX_DP<4>")
	)
	(arc
		(start 341.008716 -221.6531)
		(mid 340.998849 -221.657259)
		(end 340.988904 -221.661228)
		(width 0.0889)
		(layer "In13.Cu")
		(net "P5E_CPU0_PE0_RX_DP<4>")
	)
	(arc
		(start 336.272632 -217.554048)
		(mid 336.085434 -217.503905)
		(end 335.898236 -217.554048)
		(width 0.0889)
		(layer "In13.Cu")
		(net "P5E_CPU0_PE0_RX_DP<4>")
	)
	(arc
		(start 338.530438 -217.863674)
		(mid 338.530241 -217.871039)
		(end 338.530184 -217.878406)
		(width 0.0889)
		(layer "In13.Cu")
		(net "P5E_CPU0_PE0_RX_DP<4>")
	)
	(arc
		(start 339.279484 -217.878406)
		(mid 339.231805 -217.695506)
		(end 339.100922 -217.559128)
		(width 0.0889)
		(layer "In13.Cu")
		(net "P5E_CPU0_PE0_RX_DP<4>")
	)
	(arc
		(start 340.025736 -219.178124)
		(mid 339.823149 -218.971773)
		(end 339.74913 -218.692222)
		(width 0.0889)
		(layer "In13.Cu")
		(net "P5E_CPU0_PE0_RX_DP<4>")
	)
	(arc
		(start 340.501478 -221.623382)
		(mid 340.298655 -221.423151)
		(end 340.219284 -221.149418)
		(width 0.0889)
		(layer "In13.Cu")
		(net "P5E_CPU0_PE0_RX_DP<4>")
	)
	(arc
		(start 339.561678 -218.367864)
		(mid 339.358855 -218.167633)
		(end 339.279484 -217.8939)
		(width 0.0889)
		(layer "In13.Cu")
		(net "P5E_CPU0_PE0_RX_DP<4>")
	)
	(arc
		(start 337.682078 -218.367864)
		(mid 337.479255 -218.167633)
		(end 337.399884 -217.8939)
		(width 0.0889)
		(layer "In13.Cu")
		(net "P5E_CPU0_PE0_RX_DP<4>")
	)
	(arc
		(start 333.078582 -217.554048)
		(mid 333.039766 -217.581756)
		(end 333.00416 -217.613484)
		(width 0.0889)
		(layer "In13.Cu")
		(net "P5E_CPU0_PE0_RX_DP<4>")
	)
	(arc
		(start 337.399884 -217.878406)
		(mid 337.352205 -217.695506)
		(end 337.221322 -217.559128)
		(width 0.0889)
		(layer "In13.Cu")
		(net "P5E_CPU0_PE0_RX_DP<4>")
	)
	(arc
		(start 338.530184 -217.878406)
		(mid 338.456193 -218.157972)
		(end 338.253578 -218.364308)
		(width 0.0889)
		(layer "In13.Cu")
		(net "P5E_CPU0_PE0_RX_DP<4>")
	)
	(arc
		(start 340.501478 -219.995496)
		(mid 340.298655 -219.795265)
		(end 340.219284 -219.521532)
		(width 0.0889)
		(layer "In13.Cu")
		(net "P5E_CPU0_PE0_RX_DP<4>")
	)
	(arc
		(start 335.332324 -217.554048)
		(mid 335.145126 -217.503905)
		(end 334.957928 -217.554048)
		(width 0.0889)
		(layer "In13.Cu")
		(net "P5E_CPU0_PE0_RX_DP<4>")
	)
	(arc
		(start 334.392778 -217.554048)
		(mid 334.20558 -217.503905)
		(end 334.018382 -217.554048)
		(width 0.0889)
		(layer "In13.Cu")
		(net "P5E_CPU0_PE0_RX_DP<4>")
	)
	(arc
		(start 340.219284 -221.111826)
		(mid 340.300195 -220.841698)
		(end 340.501478 -220.644212)
		(width 0.0889)
		(layer "In13.Cu")
		(net "P5E_CPU0_PE0_RX_DP<4>")
	)
	(arc
		(start 339.74913 -218.692222)
		(mid 339.701451 -218.509322)
		(end 339.570568 -218.372944)
		(width 0.0889)
		(layer "In13.Cu")
		(net "P5E_CPU0_PE0_RX_DP<4>")
	)
	(arc
		(start 338.708746 -217.559128)
		(mid 338.581492 -217.689094)
		(end 338.530438 -217.863674)
		(width 0.0889)
		(layer "In13.Cu")
		(net "P5E_CPU0_PE0_RX_DP<4>")
	)
	(arc
		(start 336.838036 -217.554048)
		(mid 336.563807 -217.629973)
		(end 336.287364 -217.562684)
		(width 0.0889)
		(layer "In13.Cu")
		(net "P5E_CPU0_PE0_RX_DP<4>")
	)
	(segment
		(start 340.314534 -220.320108)
		(end 340.31428 -220.319854)
		(width 0.13208)
		(layer "F.Cu")
		(net "P5E_CPU0_PE0_RX_DP<3>")
	)
	(segment
		(start 340.314534 -220.855794)
		(end 340.314534 -220.320108)
		(width 0.13208)
		(layer "F.Cu")
		(net "P5E_CPU0_PE0_RX_DP<3>")
	)
	(segment
		(start 333.204566 -219.269564)
		(end 333.224632 -219.260674)
		(width 0.0889)
		(layer "In13.Cu")
		(net "P5E_CPU0_PE0_RX_DP<3>")
	)
	(segment
		(start 339.17255 -219.007944)
		(end 339.172042 -219.007944)
		(width 0.0889)
		(layer "In13.Cu")
		(net "P5E_CPU0_PE0_RX_DP<3>")
	)
	(segment
		(start 337.297268 -219.010484)
		(end 337.307682 -219.01658)
		(width 0.0889)
		(layer "In13.Cu")
		(net "P5E_CPU0_PE0_RX_DP<3>")
	)
	(segment
		(start 343.911428 -406.141682)
		(end 342.565228 -404.795482)
		(width 0.14732)
		(layer "In13.Cu")
		(net "P5E_CPU0_PE0_RX_DP<3>")
	)
	(segment
		(start 330.181966 -252.617732)
		(end 330.181966 -251.007372)
		(width 0.14732)
		(layer "In13.Cu")
		(net "P5E_CPU0_PE0_RX_DP<3>")
	)
	(segment
		(start 339.502496 -437.59374)
		(end 338.980526 -437.59374)
		(width 0.14732)
		(layer "In13.Cu")
		(net "P5E_CPU0_PE0_RX_DP<3>")
	)
	(segment
		(start 342.565228 -400.014948)
		(end 315.07049 -344.586306)
		(width 0.14732)
		(layer "In13.Cu")
		(net "P5E_CPU0_PE0_RX_DP<3>")
	)
	(segment
		(start 339.65007 -437.741314)
		(end 339.502496 -437.59374)
		(width 0.14732)
		(layer "In13.Cu")
		(net "P5E_CPU0_PE0_RX_DP<3>")
	)
	(segment
		(start 328.614278 -245.050818)
		(end 328.395076 -233.601768)
		(width 0.14732)
		(layer "In13.Cu")
		(net "P5E_CPU0_PE0_RX_DP<3>")
	)
	(segment
		(start 328.395076 -233.601768)
		(end 329.476862 -222.455486)
		(width 0.14732)
		(layer "In13.Cu")
		(net "P5E_CPU0_PE0_RX_DP<3>")
	)
	(segment
		(start 330.181966 -251.007372)
		(end 329.709018 -249.865896)
		(width 0.14732)
		(layer "In13.Cu")
		(net "P5E_CPU0_PE0_RX_DP<3>")
	)
	(segment
		(start 342.565228 -404.795482)
		(end 342.565228 -400.014948)
		(width 0.14732)
		(layer "In13.Cu")
		(net "P5E_CPU0_PE0_RX_DP<3>")
	)
	(segment
		(start 326.95769 -266.616688)
		(end 327.628504 -259.167884)
		(width 0.14732)
		(layer "In13.Cu")
		(net "P5E_CPU0_PE0_RX_DP<3>")
	)
	(segment
		(start 314.15228 -334.220566)
		(end 320.063114 -328.309732)
		(width 0.14732)
		(layer "In13.Cu")
		(net "P5E_CPU0_PE0_RX_DP<3>")
	)
	(segment
		(start 329.709018 -249.865896)
		(end 329.34275 -249.180604)
		(width 0.14732)
		(layer "In13.Cu")
		(net "P5E_CPU0_PE0_RX_DP<3>")
	)
	(segment
		(start 333.513684 -219.177108)
		(end 334.657954 -219.067888)
		(width 0.0889)
		(layer "In13.Cu")
		(net "P5E_CPU0_PE0_RX_DP<3>")
	)
	(segment
		(start 329.34275 -249.180604)
		(end 328.614278 -245.050818)
		(width 0.14732)
		(layer "In13.Cu")
		(net "P5E_CPU0_PE0_RX_DP<3>")
	)
	(segment
		(start 339.65007 -438.089802)
		(end 339.65007 -437.741314)
		(width 0.14732)
		(layer "In13.Cu")
		(net "P5E_CPU0_PE0_RX_DP<3>")
	)
	(segment
		(start 338.69249 -437.305704)
		(end 338.69249 -424.502834)
		(width 0.14732)
		(layer "In13.Cu")
		(net "P5E_CPU0_PE0_RX_DP<3>")
	)
	(segment
		(start 334.657954 -219.067888)
		(end 334.669892 -219.067126)
		(width 0.0889)
		(layer "In13.Cu")
		(net "P5E_CPU0_PE0_RX_DP<3>")
	)
	(segment
		(start 327.628504 -259.167884)
		(end 330.181966 -252.617732)
		(width 0.14732)
		(layer "In13.Cu")
		(net "P5E_CPU0_PE0_RX_DP<3>")
	)
	(segment
		(start 340.079838 -220.6117)
		(end 340.157816 -220.590872)
		(width 0.0889)
		(layer "In13.Cu")
		(net "P5E_CPU0_PE0_RX_DP<3>")
	)
	(segment
		(start 320.063114 -328.309732)
		(end 325.560436 -320.459354)
		(width 0.14732)
		(layer "In13.Cu")
		(net "P5E_CPU0_PE0_RX_DP<3>")
	)
	(segment
		(start 329.75169 -310.501538)
		(end 326.95769 -266.616688)
		(width 0.14732)
		(layer "In13.Cu")
		(net "P5E_CPU0_PE0_RX_DP<3>")
	)
	(segment
		(start 339.648546 -219.825316)
		(end 339.657436 -219.830396)
		(width 0.0889)
		(layer "In13.Cu")
		(net "P5E_CPU0_PE0_RX_DP<3>")
	)
	(segment
		(start 329.986132 -221.226634)
		(end 330.98105 -220.264482)
		(width 0.14732)
		(layer "In13.Cu")
		(net "P5E_CPU0_PE0_RX_DP<3>")
	)
	(segment
		(start 338.69249 -424.502834)
		(end 343.911428 -410.64688)
		(width 0.14732)
		(layer "In13.Cu")
		(net "P5E_CPU0_PE0_RX_DP<3>")
	)
	(segment
		(start 339.172042 -219.007944)
		(end 339.193378 -219.020136)
		(width 0.0889)
		(layer "In13.Cu")
		(net "P5E_CPU0_PE0_RX_DP<3>")
	)
	(segment
		(start 325.560436 -320.459354)
		(end 329.75169 -310.501538)
		(width 0.14732)
		(layer "In13.Cu")
		(net "P5E_CPU0_PE0_RX_DP<3>")
	)
	(segment
		(start 314.15228 -341.08263)
		(end 314.15228 -334.220566)
		(width 0.14732)
		(layer "In13.Cu")
		(net "P5E_CPU0_PE0_RX_DP<3>")
	)
	(segment
		(start 333.224632 -219.260674)
		(end 333.279496 -219.28201)
		(width 0.0889)
		(layer "In13.Cu")
		(net "P5E_CPU0_PE0_RX_DP<3>")
	)
	(segment
		(start 333.279496 -219.28201)
		(end 333.513684 -219.177108)
		(width 0.0889)
		(layer "In13.Cu")
		(net "P5E_CPU0_PE0_RX_DP<3>")
	)
	(segment
		(start 329.476862 -222.455486)
		(end 329.986132 -221.226634)
		(width 0.14732)
		(layer "In13.Cu")
		(net "P5E_CPU0_PE0_RX_DP<3>")
	)
	(segment
		(start 343.911428 -410.64688)
		(end 343.911428 -406.141682)
		(width 0.14732)
		(layer "In13.Cu")
		(net "P5E_CPU0_PE0_RX_DP<3>")
	)
	(segment
		(start 334.669892 -219.067126)
		(end 334.675988 -219.067126)
		(width 0.0889)
		(layer "In13.Cu")
		(net "P5E_CPU0_PE0_RX_DP<3>")
	)
	(segment
		(start 338.980526 -437.59374)
		(end 338.69249 -437.305704)
		(width 0.14732)
		(layer "In13.Cu")
		(net "P5E_CPU0_PE0_RX_DP<3>")
	)
	(segment
		(start 340.157816 -220.590872)
		(end 340.31428 -220.319854)
		(width 0.0889)
		(layer "In13.Cu")
		(net "P5E_CPU0_PE0_RX_DP<3>")
	)
	(segment
		(start 315.07049 -344.586306)
		(end 314.15228 -341.08263)
		(width 0.14732)
		(layer "In13.Cu")
		(net "P5E_CPU0_PE0_RX_DP<3>")
	)
	(segment
		(start 339.939884 -220.309948)
		(end 339.939884 -220.32849)
		(width 0.0889)
		(layer "In13.Cu")
		(net "P5E_CPU0_PE0_RX_DP<3>")
	)
	(segment
		(start 330.98105 -220.264482)
		(end 333.204566 -219.269564)
		(width 0.14732)
		(layer "In13.Cu")
		(net "P5E_CPU0_PE0_RX_DP<3>")
	)
	(segment
		(start 338.23275 -219.007944)
		(end 338.247482 -219.01658)
		(width 0.0889)
		(layer "In13.Cu")
		(net "P5E_CPU0_PE0_RX_DP<3>")
	)
	(arc
		(start 335.428336 -219.01658)
		(mid 335.615534 -219.066723)
		(end 335.802732 -219.01658)
		(width 0.0889)
		(layer "In13.Cu")
		(net "P5E_CPU0_PE0_RX_DP<3>")
	)
	(arc
		(start 337.307682 -219.01658)
		(mid 337.49488 -219.066723)
		(end 337.682078 -219.01658)
		(width 0.0889)
		(layer "In13.Cu")
		(net "P5E_CPU0_PE0_RX_DP<3>")
	)
	(arc
		(start 334.86344 -219.01658)
		(mid 335.145888 -218.940931)
		(end 335.428336 -219.01658)
		(width 0.0889)
		(layer "In13.Cu")
		(net "P5E_CPU0_PE0_RX_DP<3>")
	)
	(arc
		(start 339.469984 -219.506038)
		(mid 339.517663 -219.688938)
		(end 339.648546 -219.825316)
		(width 0.0889)
		(layer "In13.Cu")
		(net "P5E_CPU0_PE0_RX_DP<3>")
	)
	(arc
		(start 334.675988 -219.067126)
		(mid 334.773043 -219.0542)
		(end 334.86344 -219.01658)
		(width 0.0889)
		(layer "In13.Cu")
		(net "P5E_CPU0_PE0_RX_DP<3>")
	)
	(arc
		(start 335.802732 -219.01658)
		(mid 336.085434 -218.940804)
		(end 336.368136 -219.01658)
		(width 0.0889)
		(layer "In13.Cu")
		(net "P5E_CPU0_PE0_RX_DP<3>")
	)
	(arc
		(start 338.621878 -219.01658)
		(mid 338.896077 -218.940745)
		(end 339.17255 -219.007944)
		(width 0.0889)
		(layer "In13.Cu")
		(net "P5E_CPU0_PE0_RX_DP<3>")
	)
	(arc
		(start 338.247482 -219.01658)
		(mid 338.43468 -219.066723)
		(end 338.621878 -219.01658)
		(width 0.0889)
		(layer "In13.Cu")
		(net "P5E_CPU0_PE0_RX_DP<3>")
	)
	(arc
		(start 339.657436 -219.830396)
		(mid 339.861771 -220.033001)
		(end 339.939884 -220.309948)
		(width 0.0889)
		(layer "In13.Cu")
		(net "P5E_CPU0_PE0_RX_DP<3>")
	)
	(arc
		(start 336.368136 -219.01658)
		(mid 336.555334 -219.066723)
		(end 336.742532 -219.01658)
		(width 0.0889)
		(layer "In13.Cu")
		(net "P5E_CPU0_PE0_RX_DP<3>")
	)
	(arc
		(start 337.682078 -219.01658)
		(mid 337.956277 -218.940745)
		(end 338.23275 -219.007944)
		(width 0.0889)
		(layer "In13.Cu")
		(net "P5E_CPU0_PE0_RX_DP<3>")
	)
	(arc
		(start 339.939884 -220.32849)
		(mid 339.978558 -220.485558)
		(end 340.079838 -220.6117)
		(width 0.0889)
		(layer "In13.Cu")
		(net "P5E_CPU0_PE0_RX_DP<3>")
	)
	(arc
		(start 339.193378 -219.020136)
		(mid 339.395965 -219.226487)
		(end 339.469984 -219.506038)
		(width 0.0889)
		(layer "In13.Cu")
		(net "P5E_CPU0_PE0_RX_DP<3>")
	)
	(arc
		(start 336.742532 -219.01658)
		(mid 337.019091 -218.940837)
		(end 337.297268 -219.010484)
		(width 0.0889)
		(layer "In13.Cu")
		(net "P5E_CPU0_PE0_RX_DP<3>")
	)
	(segment
		(start 339.374734 -221.947994)
		(end 339.37448 -221.94774)
		(width 0.13208)
		(layer "F.Cu")
		(net "P5E_CPU0_PE0_RX_DP<2>")
	)
	(segment
		(start 339.374734 -222.48368)
		(end 339.374734 -221.947994)
		(width 0.13208)
		(layer "F.Cu")
		(net "P5E_CPU0_PE0_RX_DP<2>")
	)
	(segment
		(start 333.814674 -220.309694)
		(end 333.606648 -220.402912)
		(width 0.0889)
		(layer "In13.Cu")
		(net "P5E_CPU0_PE0_RX_DP<2>")
	)
	(segment
		(start 343.47531 -419.325552)
		(end 343.289636 -419.393878)
		(width 0.14732)
		(layer "In13.Cu")
		(net "P5E_CPU0_PE0_RX_DP<2>")
	)
	(segment
		(start 343.560908 -418.80536)
		(end 343.629234 -418.99078)
		(width 0.14732)
		(layer "In13.Cu")
		(net "P5E_CPU0_PE0_RX_DP<2>")
	)
	(segment
		(start 345.902788 -404.68169)
		(end 347.248988 -406.02789)
		(width 0.14732)
		(layer "In13.Cu")
		(net "P5E_CPU0_PE0_RX_DP<2>")
	)
	(segment
		(start 334.503522 -219.987114)
		(end 334.489044 -219.995496)
		(width 0.0889)
		(layer "In13.Cu")
		(net "P5E_CPU0_PE0_RX_DP<2>")
	)
	(segment
		(start 342.345772 -421.777922)
		(end 342.160098 -421.846502)
		(width 0.14732)
		(layer "In13.Cu")
		(net "P5E_CPU0_PE0_RX_DP<2>")
	)
	(segment
		(start 342.84539 -420.693088)
		(end 342.65997 -420.761414)
		(width 0.14732)
		(layer "In13.Cu")
		(net "P5E_CPU0_PE0_RX_DP<2>")
	)
	(segment
		(start 345.902788 -400.455638)
		(end 345.902788 -404.68169)
		(width 0.14732)
		(layer "In13.Cu")
		(net "P5E_CPU0_PE0_RX_DP<2>")
	)
	(segment
		(start 338.339684 -221.149418)
		(end 338.339684 -221.111826)
		(width 0.0889)
		(layer "In13.Cu")
		(net "P5E_CPU0_PE0_RX_DP<2>")
	)
	(segment
		(start 344.277188 -417.24961)
		(end 344.010488 -417.828984)
		(width 0.14732)
		(layer "In13.Cu")
		(net "P5E_CPU0_PE0_RX_DP<2>")
	)
	(segment
		(start 335.428844 -219.995496)
		(end 335.41081 -220.00591)
		(width 0.0889)
		(layer "In13.Cu")
		(net "P5E_CPU0_PE0_RX_DP<2>")
	)
	(segment
		(start 342.068404 -422.379394)
		(end 341.91448 -422.714166)
		(width 0.14732)
		(layer "In13.Cu")
		(net "P5E_CPU0_PE0_RX_DP<2>")
	)
	(segment
		(start 331.395832 -252.824234)
		(end 328.825098 -259.421122)
		(width 0.14732)
		(layer "In13.Cu")
		(net "P5E_CPU0_PE0_RX_DP<2>")
	)
	(segment
		(start 329.83551 -244.836696)
		(end 330.5429 -248.870724)
		(width 0.14732)
		(layer "In13.Cu")
		(net "P5E_CPU0_PE0_RX_DP<2>")
	)
	(segment
		(start 343.629234 -418.99078)
		(end 343.47531 -419.325552)
		(width 0.14732)
		(layer "In13.Cu")
		(net "P5E_CPU0_PE0_RX_DP<2>")
	)
	(segment
		(start 347.248988 -406.02789)
		(end 347.248988 -410.796232)
		(width 0.14732)
		(layer "In13.Cu")
		(net "P5E_CPU0_PE0_RX_DP<2>")
	)
	(segment
		(start 335.8134 -220.001592)
		(end 335.802986 -219.995496)
		(width 0.0889)
		(layer "In13.Cu")
		(net "P5E_CPU0_PE0_RX_DP<2>")
	)
	(segment
		(start 342.65997 -420.761414)
		(end 342.43137 -421.25773)
		(width 0.14732)
		(layer "In13.Cu")
		(net "P5E_CPU0_PE0_RX_DP<2>")
	)
	(segment
		(start 341.193882 -438.319418)
		(end 341.482934 -438.319418)
		(width 0.14732)
		(layer "In13.Cu")
		(net "P5E_CPU0_PE0_RX_DP<2>")
	)
	(segment
		(start 338.630768 -220.000576)
		(end 338.621878 -219.995496)
		(width 0.0889)
		(layer "In13.Cu")
		(net "P5E_CPU0_PE0_RX_DP<2>")
	)
	(segment
		(start 331.63637 -221.329758)
		(end 331.00391 -221.962218)
		(width 0.14732)
		(layer "In13.Cu")
		(net "P5E_CPU0_PE0_RX_DP<2>")
	)
	(segment
		(start 344.462862 -417.18103)
		(end 344.277188 -417.24961)
		(width 0.14732)
		(layer "In13.Cu")
		(net "P5E_CPU0_PE0_RX_DP<2>")
	)
	(segment
		(start 342.160098 -421.846502)
		(end 342.000078 -422.193974)
		(width 0.14732)
		(layer "In13.Cu")
		(net "P5E_CPU0_PE0_RX_DP<2>")
	)
	(segment
		(start 316.183264 -344.037666)
		(end 345.902788 -400.455638)
		(width 0.14732)
		(layer "In13.Cu")
		(net "P5E_CPU0_PE0_RX_DP<2>")
	)
	(segment
		(start 341.728806 -422.782492)
		(end 340.966806 -424.437556)
		(width 0.14732)
		(layer "In13.Cu")
		(net "P5E_CPU0_PE0_RX_DP<2>")
	)
	(segment
		(start 334.40624 -220.059504)
		(end 333.814674 -220.309694)
		(width 0.0889)
		(layer "In13.Cu")
		(net "P5E_CPU0_PE0_RX_DP<2>")
	)
	(segment
		(start 328.17562 -266.632436)
		(end 330.98486 -310.765444)
		(width 0.14732)
		(layer "In13.Cu")
		(net "P5E_CPU0_PE0_RX_DP<2>")
	)
	(segment
		(start 331.395832 -250.791218)
		(end 331.395832 -252.824234)
		(width 0.14732)
		(layer "In13.Cu")
		(net "P5E_CPU0_PE0_RX_DP<2>")
	)
	(segment
		(start 344.616786 -416.846258)
		(end 344.462862 -417.18103)
		(width 0.14732)
		(layer "In13.Cu")
		(net "P5E_CPU0_PE0_RX_DP<2>")
	)
	(segment
		(start 328.825098 -259.421122)
		(end 328.17562 -266.632436)
		(width 0.14732)
		(layer "In13.Cu")
		(net "P5E_CPU0_PE0_RX_DP<2>")
	)
	(segment
		(start 341.650066 -438.152286)
		(end 341.650066 -437.889904)
		(width 0.14732)
		(layer "In13.Cu")
		(net "P5E_CPU0_PE0_RX_DP<2>")
	)
	(segment
		(start 342.930988 -420.172896)
		(end 342.999568 -420.358062)
		(width 0.14732)
		(layer "In13.Cu")
		(net "P5E_CPU0_PE0_RX_DP<2>")
	)
	(segment
		(start 330.5429 -248.870724)
		(end 330.797662 -249.347228)
		(width 0.14732)
		(layer "In13.Cu")
		(net "P5E_CPU0_PE0_RX_DP<2>")
	)
	(segment
		(start 338.621878 -220.644212)
		(end 338.630768 -220.639132)
		(width 0.0889)
		(layer "In13.Cu")
		(net "P5E_CPU0_PE0_RX_DP<2>")
	)
	(segment
		(start 344.010488 -417.828984)
		(end 344.079068 -418.014404)
		(width 0.14732)
		(layer "In13.Cu")
		(net "P5E_CPU0_PE0_RX_DP<2>")
	)
	(segment
		(start 342.499696 -421.44315)
		(end 342.345772 -421.777922)
		(width 0.14732)
		(layer "In13.Cu")
		(net "P5E_CPU0_PE0_RX_DP<2>")
	)
	(segment
		(start 315.4426 -340.952328)
		(end 316.183264 -344.037666)
		(width 0.14732)
		(layer "In13.Cu")
		(net "P5E_CPU0_PE0_RX_DP<2>")
	)
	(segment
		(start 339.37448 -221.94774)
		(end 339.218016 -221.676722)
		(width 0.0889)
		(layer "In13.Cu")
		(net "P5E_CPU0_PE0_RX_DP<2>")
	)
	(segment
		(start 347.248988 -410.796232)
		(end 344.54846 -416.661092)
		(width 0.14732)
		(layer "In13.Cu")
		(net "P5E_CPU0_PE0_RX_DP<2>")
	)
	(segment
		(start 342.43137 -421.25773)
		(end 342.499696 -421.44315)
		(width 0.14732)
		(layer "In13.Cu")
		(net "P5E_CPU0_PE0_RX_DP<2>")
	)
	(segment
		(start 329.619864 -233.596434)
		(end 329.83551 -244.836696)
		(width 0.14732)
		(layer "In13.Cu")
		(net "P5E_CPU0_PE0_RX_DP<2>")
	)
	(segment
		(start 331.00391 -221.962218)
		(end 330.66228 -222.786956)
		(width 0.14732)
		(layer "In13.Cu")
		(net "P5E_CPU0_PE0_RX_DP<2>")
	)
	(segment
		(start 344.079068 -418.014404)
		(end 343.92489 -418.349176)
		(width 0.14732)
		(layer "In13.Cu")
		(net "P5E_CPU0_PE0_RX_DP<2>")
	)
	(segment
		(start 340.966806 -424.437556)
		(end 340.966806 -438.092342)
		(width 0.14732)
		(layer "In13.Cu")
		(net "P5E_CPU0_PE0_RX_DP<2>")
	)
	(segment
		(start 330.98486 -310.765444)
		(end 326.67194 -321.013836)
		(width 0.14732)
		(layer "In13.Cu")
		(net "P5E_CPU0_PE0_RX_DP<2>")
	)
	(segment
		(start 341.482934 -438.319418)
		(end 341.650066 -438.152286)
		(width 0.14732)
		(layer "In13.Cu")
		(net "P5E_CPU0_PE0_RX_DP<2>")
	)
	(segment
		(start 330.797662 -249.347228)
		(end 331.395832 -250.791218)
		(width 0.14732)
		(layer "In13.Cu")
		(net "P5E_CPU0_PE0_RX_DP<2>")
	)
	(segment
		(start 333.585566 -220.458538)
		(end 333.5655 -220.467428)
		(width 0.0889)
		(layer "In13.Cu")
		(net "P5E_CPU0_PE0_RX_DP<2>")
	)
	(segment
		(start 343.92489 -418.349176)
		(end 343.73947 -418.417502)
		(width 0.14732)
		(layer "In13.Cu")
		(net "P5E_CPU0_PE0_RX_DP<2>")
	)
	(segment
		(start 343.289636 -419.393878)
		(end 342.930988 -420.172896)
		(width 0.14732)
		(layer "In13.Cu")
		(net "P5E_CPU0_PE0_RX_DP<2>")
	)
	(segment
		(start 320.904616 -329.250294)
		(end 315.4426 -334.712056)
		(width 0.14732)
		(layer "In13.Cu")
		(net "P5E_CPU0_PE0_RX_DP<2>")
	)
	(segment
		(start 341.91448 -422.714166)
		(end 341.728806 -422.782492)
		(width 0.14732)
		(layer "In13.Cu")
		(net "P5E_CPU0_PE0_RX_DP<2>")
	)
	(segment
		(start 330.66228 -222.786956)
		(end 329.619864 -233.596434)
		(width 0.14732)
		(layer "In13.Cu")
		(net "P5E_CPU0_PE0_RX_DP<2>")
	)
	(segment
		(start 342.000078 -422.193974)
		(end 342.068404 -422.379394)
		(width 0.14732)
		(layer "In13.Cu")
		(net "P5E_CPU0_PE0_RX_DP<2>")
	)
	(segment
		(start 339.218016 -221.676722)
		(end 339.129116 -221.6531)
		(width 0.0889)
		(layer "In13.Cu")
		(net "P5E_CPU0_PE0_RX_DP<2>")
	)
	(segment
		(start 333.606648 -220.402912)
		(end 333.585566 -220.458538)
		(width 0.0889)
		(layer "In13.Cu")
		(net "P5E_CPU0_PE0_RX_DP<2>")
	)
	(segment
		(start 326.67194 -321.013836)
		(end 320.904616 -329.250294)
		(width 0.14732)
		(layer "In13.Cu")
		(net "P5E_CPU0_PE0_RX_DP<2>")
	)
	(segment
		(start 343.73947 -418.417502)
		(end 343.560908 -418.80536)
		(width 0.14732)
		(layer "In13.Cu")
		(net "P5E_CPU0_PE0_RX_DP<2>")
	)
	(segment
		(start 344.54846 -416.661092)
		(end 344.616786 -416.846258)
		(width 0.14732)
		(layer "In13.Cu")
		(net "P5E_CPU0_PE0_RX_DP<2>")
	)
	(segment
		(start 342.999568 -420.358062)
		(end 342.84539 -420.693088)
		(width 0.14732)
		(layer "In13.Cu")
		(net "P5E_CPU0_PE0_RX_DP<2>")
	)
	(segment
		(start 340.966806 -438.092342)
		(end 341.193882 -438.319418)
		(width 0.14732)
		(layer "In13.Cu")
		(net "P5E_CPU0_PE0_RX_DP<2>")
	)
	(segment
		(start 333.5655 -220.467428)
		(end 331.63637 -221.329758)
		(width 0.14732)
		(layer "In13.Cu")
		(net "P5E_CPU0_PE0_RX_DP<2>")
	)
	(segment
		(start 315.4426 -334.712056)
		(end 315.4426 -340.952328)
		(width 0.14732)
		(layer "In13.Cu")
		(net "P5E_CPU0_PE0_RX_DP<2>")
	)
	(segment
		(start 338.247482 -219.995496)
		(end 338.237068 -220.001592)
		(width 0.0889)
		(layer "In13.Cu")
		(net "P5E_CPU0_PE0_RX_DP<2>")
	)
	(segment
		(start 335.802986 -219.995496)
		(end 335.794604 -219.99067)
		(width 0.0889)
		(layer "In13.Cu")
		(net "P5E_CPU0_PE0_RX_DP<2>")
	)
	(segment
		(start 334.410812 -220.054932)
		(end 334.40624 -220.059504)
		(width 0.0889)
		(layer "In13.Cu")
		(net "P5E_CPU0_PE0_RX_DP<2>")
	)
	(arc
		(start 335.794604 -219.99067)
		(mid 335.611096 -219.945392)
		(end 335.428844 -219.995496)
		(width 0.0889)
		(layer "In13.Cu")
		(net "P5E_CPU0_PE0_RX_DP<2>")
	)
	(arc
		(start 336.368136 -219.995496)
		(mid 336.091577 -220.071239)
		(end 335.8134 -220.001592)
		(width 0.0889)
		(layer "In13.Cu")
		(net "P5E_CPU0_PE0_RX_DP<2>")
	)
	(arc
		(start 339.129116 -221.6531)
		(mid 339.119249 -221.657259)
		(end 339.109304 -221.661228)
		(width 0.0889)
		(layer "In13.Cu")
		(net "P5E_CPU0_PE0_RX_DP<2>")
	)
	(arc
		(start 335.41081 -220.00591)
		(mid 335.135652 -220.071433)
		(end 334.863186 -219.995496)
		(width 0.0889)
		(layer "In13.Cu")
		(net "P5E_CPU0_PE0_RX_DP<2>")
	)
	(arc
		(start 339.109304 -221.661228)
		(mid 338.861293 -221.697693)
		(end 338.621878 -221.623382)
		(width 0.0889)
		(layer "In13.Cu")
		(net "P5E_CPU0_PE0_RX_DP<2>")
	)
	(arc
		(start 338.621878 -221.623382)
		(mid 338.419055 -221.423151)
		(end 338.339684 -221.149418)
		(width 0.0889)
		(layer "In13.Cu")
		(net "P5E_CPU0_PE0_RX_DP<2>")
	)
	(arc
		(start 336.742532 -219.995496)
		(mid 336.555334 -219.945353)
		(end 336.368136 -219.995496)
		(width 0.0889)
		(layer "In13.Cu")
		(net "P5E_CPU0_PE0_RX_DP<2>")
	)
	(arc
		(start 337.307936 -219.995496)
		(mid 337.025234 -220.071272)
		(end 336.742532 -219.995496)
		(width 0.0889)
		(layer "In13.Cu")
		(net "P5E_CPU0_PE0_RX_DP<2>")
	)
	(arc
		(start 334.863186 -219.995496)
		(mid 334.68443 -219.945327)
		(end 334.503522 -219.987114)
		(width 0.0889)
		(layer "In13.Cu")
		(net "P5E_CPU0_PE0_RX_DP<2>")
	)
	(arc
		(start 334.42402 -220.042486)
		(mid 334.417342 -220.04863)
		(end 334.410812 -220.054932)
		(width 0.0889)
		(layer "In13.Cu")
		(net "P5E_CPU0_PE0_RX_DP<2>")
	)
	(arc
		(start 338.339684 -221.111826)
		(mid 338.420595 -220.841698)
		(end 338.621878 -220.644212)
		(width 0.0889)
		(layer "In13.Cu")
		(net "P5E_CPU0_PE0_RX_DP<2>")
	)
	(arc
		(start 338.630768 -220.639132)
		(mid 338.809365 -220.319854)
		(end 338.630768 -220.000576)
		(width 0.0889)
		(layer "In13.Cu")
		(net "P5E_CPU0_PE0_RX_DP<2>")
	)
	(arc
		(start 338.621878 -219.995496)
		(mid 338.43468 -219.945353)
		(end 338.247482 -219.995496)
		(width 0.0889)
		(layer "In13.Cu")
		(net "P5E_CPU0_PE0_RX_DP<2>")
	)
	(arc
		(start 334.489044 -219.995496)
		(mid 334.455267 -220.017241)
		(end 334.42402 -220.042486)
		(width 0.0889)
		(layer "In13.Cu")
		(net "P5E_CPU0_PE0_RX_DP<2>")
	)
	(arc
		(start 337.682332 -219.995496)
		(mid 337.495134 -219.945353)
		(end 337.307936 -219.995496)
		(width 0.0889)
		(layer "In13.Cu")
		(net "P5E_CPU0_PE0_RX_DP<2>")
	)
	(arc
		(start 338.237068 -220.001592)
		(mid 337.95889 -220.071315)
		(end 337.682332 -219.995496)
		(width 0.0889)
		(layer "In13.Cu")
		(net "P5E_CPU0_PE0_RX_DP<2>")
	)
	(segment
		(start 338.434934 -220.855794)
		(end 338.434934 -220.320108)
		(width 0.13208)
		(layer "F.Cu")
		(net "P5E_CPU0_PE0_RX_DP<1>")
	)
	(segment
		(start 338.434934 -220.320108)
		(end 338.43468 -220.319854)
		(width 0.13208)
		(layer "F.Cu")
		(net "P5E_CPU0_PE0_RX_DP<1>")
	)
	(segment
		(start 330.403962 -233.353356)
		(end 331.371702 -222.925386)
		(width 0.14732)
		(layer "In13.Cu")
		(net "P5E_CPU0_PE0_RX_DP<1>")
	)
	(segment
		(start 335.703926 -220.716348)
		(end 335.70418 -220.716094)
		(width 0.0889)
		(layer "In13.Cu")
		(net "P5E_CPU0_PE0_RX_DP<1>")
	)
	(segment
		(start 332.051152 -250.660408)
		(end 331.391006 -249.066558)
		(width 0.14732)
		(layer "In13.Cu")
		(net "P5E_CPU0_PE0_RX_DP<1>")
	)
	(segment
		(start 331.650848 -310.90362)
		(end 328.832972 -266.641072)
		(width 0.14732)
		(layer "In13.Cu")
		(net "P5E_CPU0_PE0_RX_DP<1>")
	)
	(segment
		(start 342.692736 -424.49496)
		(end 350.037908 -410.565092)
		(width 0.14732)
		(layer "In13.Cu")
		(net "P5E_CPU0_PE0_RX_DP<1>")
	)
	(segment
		(start 316.148466 -334.93583)
		(end 321.739006 -329.34529)
		(width 0.14732)
		(layer "In13.Cu")
		(net "P5E_CPU0_PE0_RX_DP<1>")
	)
	(segment
		(start 332.051152 -253.06909)
		(end 332.051152 -250.660408)
		(width 0.14732)
		(layer "In13.Cu")
		(net "P5E_CPU0_PE0_RX_DP<1>")
	)
	(segment
		(start 333.821024 -221.12986)
		(end 334.862932 -221.12986)
		(width 0.14732)
		(layer "In13.Cu")
		(net "P5E_CPU0_PE0_RX_DP<1>")
	)
	(segment
		(start 334.92694 -221.17177)
		(end 335.247996 -221.17177)
		(width 0.0889)
		(layer "In13.Cu")
		(net "P5E_CPU0_PE0_RX_DP<1>")
	)
	(segment
		(start 328.832972 -266.641072)
		(end 329.455272 -259.73024)
		(width 0.14732)
		(layer "In13.Cu")
		(net "P5E_CPU0_PE0_RX_DP<1>")
	)
	(segment
		(start 329.455272 -259.73024)
		(end 332.051152 -253.06909)
		(width 0.14732)
		(layer "In13.Cu")
		(net "P5E_CPU0_PE0_RX_DP<1>")
	)
	(segment
		(start 330.488798 -244.651022)
		(end 330.403962 -233.353356)
		(width 0.14732)
		(layer "In13.Cu")
		(net "P5E_CPU0_PE0_RX_DP<1>")
	)
	(segment
		(start 338.189316 -220.614748)
		(end 338.278216 -220.590872)
		(width 0.0889)
		(layer "In13.Cu")
		(net "P5E_CPU0_PE0_RX_DP<1>")
	)
	(segment
		(start 316.767464 -343.514934)
		(end 316.148466 -340.896956)
		(width 0.14732)
		(layer "In13.Cu")
		(net "P5E_CPU0_PE0_RX_DP<1>")
	)
	(segment
		(start 338.189062 -220.615256)
		(end 338.189316 -220.614748)
		(width 0.0889)
		(layer "In13.Cu")
		(net "P5E_CPU0_PE0_RX_DP<1>")
	)
	(segment
		(start 338.278216 -220.590872)
		(end 338.43468 -220.319854)
		(width 0.0889)
		(layer "In13.Cu")
		(net "P5E_CPU0_PE0_RX_DP<1>")
	)
	(segment
		(start 350.037908 -406.141682)
		(end 348.691708 -404.795482)
		(width 0.14732)
		(layer "In13.Cu")
		(net "P5E_CPU0_PE0_RX_DP<1>")
	)
	(segment
		(start 343.650062 -438.089802)
		(end 343.650062 -437.741314)
		(width 0.14732)
		(layer "In13.Cu")
		(net "P5E_CPU0_PE0_RX_DP<1>")
	)
	(segment
		(start 316.148466 -340.896956)
		(end 316.148466 -334.93583)
		(width 0.14732)
		(layer "In13.Cu")
		(net "P5E_CPU0_PE0_RX_DP<1>")
	)
	(segment
		(start 331.371702 -222.925386)
		(end 331.631798 -222.297752)
		(width 0.14732)
		(layer "In13.Cu")
		(net "P5E_CPU0_PE0_RX_DP<1>")
	)
	(segment
		(start 342.692736 -437.26735)
		(end 342.692736 -424.49496)
		(width 0.14732)
		(layer "In13.Cu")
		(net "P5E_CPU0_PE0_RX_DP<1>")
	)
	(segment
		(start 343.650062 -437.741314)
		(end 343.502488 -437.59374)
		(width 0.14732)
		(layer "In13.Cu")
		(net "P5E_CPU0_PE0_RX_DP<1>")
	)
	(segment
		(start 348.691708 -400.31924)
		(end 316.767464 -343.514934)
		(width 0.14732)
		(layer "In13.Cu")
		(net "P5E_CPU0_PE0_RX_DP<1>")
	)
	(segment
		(start 334.88503 -221.12986)
		(end 334.92694 -221.17177)
		(width 0.0889)
		(layer "In13.Cu")
		(net "P5E_CPU0_PE0_RX_DP<1>")
	)
	(segment
		(start 335.247996 -221.17177)
		(end 335.685638 -220.734128)
		(width 0.0889)
		(layer "In13.Cu")
		(net "P5E_CPU0_PE0_RX_DP<1>")
	)
	(segment
		(start 321.739006 -329.34529)
		(end 327.127108 -321.651122)
		(width 0.14732)
		(layer "In13.Cu")
		(net "P5E_CPU0_PE0_RX_DP<1>")
	)
	(segment
		(start 331.20584 -248.719848)
		(end 330.488798 -244.651022)
		(width 0.14732)
		(layer "In13.Cu")
		(net "P5E_CPU0_PE0_RX_DP<1>")
	)
	(segment
		(start 350.037908 -410.565092)
		(end 350.037908 -406.141682)
		(width 0.14732)
		(layer "In13.Cu")
		(net "P5E_CPU0_PE0_RX_DP<1>")
	)
	(segment
		(start 348.691708 -404.795482)
		(end 348.691708 -400.31924)
		(width 0.14732)
		(layer "In13.Cu")
		(net "P5E_CPU0_PE0_RX_DP<1>")
	)
	(segment
		(start 331.631798 -222.297752)
		(end 332.077822 -221.851728)
		(width 0.14732)
		(layer "In13.Cu")
		(net "P5E_CPU0_PE0_RX_DP<1>")
	)
	(segment
		(start 334.862932 -221.12986)
		(end 334.88503 -221.12986)
		(width 0.0889)
		(layer "In13.Cu")
		(net "P5E_CPU0_PE0_RX_DP<1>")
	)
	(segment
		(start 331.391006 -249.066558)
		(end 331.20584 -248.719848)
		(width 0.14732)
		(layer "In13.Cu")
		(net "P5E_CPU0_PE0_RX_DP<1>")
	)
	(segment
		(start 343.502488 -437.59374)
		(end 343.019126 -437.59374)
		(width 0.14732)
		(layer "In13.Cu")
		(net "P5E_CPU0_PE0_RX_DP<1>")
	)
	(segment
		(start 336.742532 -220.644212)
		(end 336.74304 -220.64472)
		(width 0.0889)
		(layer "In13.Cu")
		(net "P5E_CPU0_PE0_RX_DP<1>")
	)
	(segment
		(start 327.127108 -321.651122)
		(end 331.650848 -310.90362)
		(width 0.14732)
		(layer "In13.Cu")
		(net "P5E_CPU0_PE0_RX_DP<1>")
	)
	(segment
		(start 332.077822 -221.851728)
		(end 333.821024 -221.12986)
		(width 0.14732)
		(layer "In13.Cu")
		(net "P5E_CPU0_PE0_RX_DP<1>")
	)
	(segment
		(start 343.019126 -437.59374)
		(end 342.692736 -437.26735)
		(width 0.14732)
		(layer "In13.Cu")
		(net "P5E_CPU0_PE0_RX_DP<1>")
	)
	(arc
		(start 338.16925 -220.607128)
		(mid 338.179194 -220.611099)
		(end 338.189062 -220.615256)
		(width 0.0889)
		(layer "In13.Cu")
		(net "P5E_CPU0_PE0_RX_DP<1>")
	)
	(arc
		(start 335.70418 -220.716094)
		(mid 335.751518 -220.677497)
		(end 335.802732 -220.644212)
		(width 0.0889)
		(layer "In13.Cu")
		(net "P5E_CPU0_PE0_RX_DP<1>")
	)
	(arc
		(start 336.74304 -220.64472)
		(mid 337.025234 -220.569164)
		(end 337.307428 -220.64472)
		(width 0.0889)
		(layer "In13.Cu")
		(net "P5E_CPU0_PE0_RX_DP<1>")
	)
	(arc
		(start 335.685638 -220.734128)
		(mid 335.694681 -220.725134)
		(end 335.703926 -220.716348)
		(width 0.0889)
		(layer "In13.Cu")
		(net "P5E_CPU0_PE0_RX_DP<1>")
	)
	(arc
		(start 337.68284 -220.64472)
		(mid 337.921776 -220.570715)
		(end 338.16925 -220.607128)
		(width 0.0889)
		(layer "In13.Cu")
		(net "P5E_CPU0_PE0_RX_DP<1>")
	)
	(arc
		(start 335.802732 -220.644212)
		(mid 336.085434 -220.56847)
		(end 336.368136 -220.644212)
		(width 0.0889)
		(layer "In13.Cu")
		(net "P5E_CPU0_PE0_RX_DP<1>")
	)
	(arc
		(start 336.368136 -220.644212)
		(mid 336.555334 -220.694355)
		(end 336.742532 -220.644212)
		(width 0.0889)
		(layer "In13.Cu")
		(net "P5E_CPU0_PE0_RX_DP<1>")
	)
	(arc
		(start 337.307428 -220.64472)
		(mid 337.495134 -220.695049)
		(end 337.68284 -220.64472)
		(width 0.0889)
		(layer "In13.Cu")
		(net "P5E_CPU0_PE0_RX_DP<1>")
	)
	(segment
		(start 351.12198 -221.669864)
		(end 351.12198 -221.134178)
		(width 0.13208)
		(layer "F.Cu")
		(net "P5E_CPU0_PE0_RX_DP<15>")
	)
	(segment
		(start 351.12198 -221.134178)
		(end 351.122234 -221.133924)
		(width 0.13208)
		(layer "F.Cu")
		(net "P5E_CPU0_PE0_RX_DP<15>")
	)
	(segment
		(start 312.205624 -317.2714)
		(end 311.622694 -317.2714)
		(width 0.14732)
		(layer "In13.Cu")
		(net "P5E_CPU0_PE0_RX_DP<15>")
	)
	(segment
		(start 330.416662 -204.573378)
		(end 321.023996 -213.966298)
		(width 0.14732)
		(layer "In13.Cu")
		(net "P5E_CPU0_PE0_RX_DP<15>")
	)
	(segment
		(start 306.213002 -387.29412)
		(end 306.223924 -387.731254)
		(width 0.14732)
		(layer "In13.Cu")
		(net "P5E_CPU0_PE0_RX_DP<15>")
	)
	(segment
		(start 350.557084 -216.260426)
		(end 350.557084 -216.25052)
		(width 0.0889)
		(layer "In13.Cu")
		(net "P5E_CPU0_PE0_RX_DP<15>")
	)
	(segment
		(start 306.336954 -392.220958)
		(end 306.215542 -392.348466)
		(width 0.14732)
		(layer "In13.Cu")
		(net "P5E_CPU0_PE0_RX_DP<15>")
	)
	(segment
		(start 350.087184 -213.248748)
		(end 350.045274 -213.206838)
		(width 0.0889)
		(layer "In13.Cu")
		(net "P5E_CPU0_PE0_RX_DP<15>")
	)
	(segment
		(start 306.098194 -382.732026)
		(end 306.109116 -383.16916)
		(width 0.14732)
		(layer "In13.Cu")
		(net "P5E_CPU0_PE0_RX_DP<15>")
	)
	(segment
		(start 314.482988 -437.31942)
		(end 314.65012 -437.152288)
		(width 0.14732)
		(layer "In13.Cu")
		(net "P5E_CPU0_PE0_RX_DP<15>")
	)
	(segment
		(start 306.015898 -384.419094)
		(end 306.02682 -384.85572)
		(width 0.14732)
		(layer "In13.Cu")
		(net "P5E_CPU0_PE0_RX_DP<15>")
	)
	(segment
		(start 350.045274 -213.206838)
		(end 350.045274 -213.18474)
		(width 0.0889)
		(layer "In13.Cu")
		(net "P5E_CPU0_PE0_RX_DP<15>")
	)
	(segment
		(start 314.802012 -250.759468)
		(end 314.697364 -252.874018)
		(width 0.14732)
		(layer "In13.Cu")
		(net "P5E_CPU0_PE0_RX_DP<15>")
	)
	(segment
		(start 332.24089 -203.076302)
		(end 330.416662 -204.573378)
		(width 0.14732)
		(layer "In13.Cu")
		(net "P5E_CPU0_PE0_RX_DP<15>")
	)
	(segment
		(start 306.984654 -320.354452)
		(end 301.563532 -325.775574)
		(width 0.14732)
		(layer "In13.Cu")
		(net "P5E_CPU0_PE0_RX_DP<15>")
	)
	(segment
		(start 350.848168 -218.372944)
		(end 350.840294 -218.368372)
		(width 0.0889)
		(layer "In13.Cu")
		(net "P5E_CPU0_PE0_RX_DP<15>")
	)
	(segment
		(start 349.563944 -208.868518)
		(end 349.254826 -208.5594)
		(width 0.14732)
		(layer "In13.Cu")
		(net "P5E_CPU0_PE0_RX_DP<15>")
	)
	(segment
		(start 306.241196 -388.416546)
		(end 306.252118 -388.85368)
		(width 0.14732)
		(layer "In13.Cu")
		(net "P5E_CPU0_PE0_RX_DP<15>")
	)
	(segment
		(start 349.254826 -208.5594)
		(end 349.254826 -208.386934)
		(width 0.14732)
		(layer "In13.Cu")
		(net "P5E_CPU0_PE0_RX_DP<15>")
	)
	(segment
		(start 350.839278 -219.01658)
		(end 350.848168 -219.0115)
		(width 0.0889)
		(layer "In13.Cu")
		(net "P5E_CPU0_PE0_RX_DP<15>")
	)
	(segment
		(start 350.840294 -218.368372)
		(end 350.839278 -218.367864)
		(width 0.0889)
		(layer "In13.Cu")
		(net "P5E_CPU0_PE0_RX_DP<15>")
	)
	(segment
		(start 306.044092 -385.54152)
		(end 306.055014 -385.978146)
		(width 0.14732)
		(layer "In13.Cu")
		(net "P5E_CPU0_PE0_RX_DP<15>")
	)
	(segment
		(start 306.08524 -387.172962)
		(end 306.213002 -387.29412)
		(width 0.14732)
		(layer "In13.Cu")
		(net "P5E_CPU0_PE0_RX_DP<15>")
	)
	(segment
		(start 318.074802 -305.622198)
		(end 316.874144 -309.901082)
		(width 0.14732)
		(layer "In13.Cu")
		(net "P5E_CPU0_PE0_RX_DP<15>")
	)
	(segment
		(start 306.308506 -391.098532)
		(end 306.187094 -391.22604)
		(width 0.14732)
		(layer "In13.Cu")
		(net "P5E_CPU0_PE0_RX_DP<15>")
	)
	(segment
		(start 306.187094 -391.22604)
		(end 306.198016 -391.662666)
		(width 0.14732)
		(layer "In13.Cu")
		(net "P5E_CPU0_PE0_RX_DP<15>")
	)
	(segment
		(start 306.130706 -388.981188)
		(end 306.141628 -389.417814)
		(width 0.14732)
		(layer "In13.Cu")
		(net "P5E_CPU0_PE0_RX_DP<15>")
	)
	(segment
		(start 303.30902 -345.145868)
		(end 305.670204 -370.647976)
		(width 0.14732)
		(layer "In13.Cu")
		(net "P5E_CPU0_PE0_RX_DP<15>")
	)
	(segment
		(start 306.126388 -383.854452)
		(end 306.13731 -384.291586)
		(width 0.14732)
		(layer "In13.Cu")
		(net "P5E_CPU0_PE0_RX_DP<15>")
	)
	(segment
		(start 318.630046 -219.745814)
		(end 314.802012 -250.759468)
		(width 0.14732)
		(layer "In13.Cu")
		(net "P5E_CPU0_PE0_RX_DP<15>")
	)
	(segment
		(start 306.169822 -390.54024)
		(end 306.297584 -390.661398)
		(width 0.14732)
		(layer "In13.Cu")
		(net "P5E_CPU0_PE0_RX_DP<15>")
	)
	(segment
		(start 313.852814 -315.62421)
		(end 312.205624 -317.2714)
		(width 0.14732)
		(layer "In13.Cu")
		(net "P5E_CPU0_PE0_RX_DP<15>")
	)
	(segment
		(start 306.223924 -387.731254)
		(end 306.102512 -387.858762)
		(width 0.14732)
		(layer "In13.Cu")
		(net "P5E_CPU0_PE0_RX_DP<15>")
	)
	(segment
		(start 349.73641 -208.868518)
		(end 349.563944 -208.868518)
		(width 0.14732)
		(layer "In13.Cu")
		(net "P5E_CPU0_PE0_RX_DP<15>")
	)
	(segment
		(start 306.365148 -393.343384)
		(end 306.243736 -393.470892)
		(width 0.14732)
		(layer "In13.Cu")
		(net "P5E_CPU0_PE0_RX_DP<15>")
	)
	(segment
		(start 351.278698 -220.862906)
		(end 351.254568 -220.773752)
		(width 0.0889)
		(layer "In13.Cu")
		(net "P5E_CPU0_PE0_RX_DP<15>")
	)
	(segment
		(start 306.07254 -386.663946)
		(end 306.08524 -387.172962)
		(width 0.14732)
		(layer "In13.Cu")
		(net "P5E_CPU0_PE0_RX_DP<15>")
	)
	(segment
		(start 302.560482 -340.886288)
		(end 303.30902 -345.145868)
		(width 0.14732)
		(layer "In13.Cu")
		(net "P5E_CPU0_PE0_RX_DP<15>")
	)
	(segment
		(start 306.080668 -404.68169)
		(end 307.426868 -406.02789)
		(width 0.14732)
		(layer "In13.Cu")
		(net "P5E_CPU0_PE0_RX_DP<15>")
	)
	(segment
		(start 307.426868 -406.02789)
		(end 307.426868 -411.247336)
		(width 0.14732)
		(layer "In13.Cu")
		(net "P5E_CPU0_PE0_RX_DP<15>")
	)
	(segment
		(start 336.028538 -200.648316)
		(end 333.707232 -201.60996)
		(width 0.14732)
		(layer "In13.Cu")
		(net "P5E_CPU0_PE0_RX_DP<15>")
	)
	(segment
		(start 333.707232 -201.60996)
		(end 332.24089 -203.076302)
		(width 0.14732)
		(layer "In13.Cu")
		(net "P5E_CPU0_PE0_RX_DP<15>")
	)
	(segment
		(start 351.02673 -220.334078)
		(end 351.02673 -220.311218)
		(width 0.0889)
		(layer "In13.Cu")
		(net "P5E_CPU0_PE0_RX_DP<15>")
	)
	(segment
		(start 316.87389 -309.901082)
		(end 315.45784 -314.948824)
		(width 0.14732)
		(layer "In13.Cu")
		(net "P5E_CPU0_PE0_RX_DP<15>")
	)
	(segment
		(start 301.563532 -329.11542)
		(end 302.560482 -340.886288)
		(width 0.14732)
		(layer "In13.Cu")
		(net "P5E_CPU0_PE0_RX_DP<15>")
	)
	(segment
		(start 306.226464 -392.785092)
		(end 306.354226 -392.90625)
		(width 0.14732)
		(layer "In13.Cu")
		(net "P5E_CPU0_PE0_RX_DP<15>")
	)
	(segment
		(start 305.670204 -370.647976)
		(end 305.970432 -382.610868)
		(width 0.14732)
		(layer "In13.Cu")
		(net "P5E_CPU0_PE0_RX_DP<15>")
	)
	(segment
		(start 350.556576 -214.622634)
		(end 350.556576 -214.461344)
		(width 0.0889)
		(layer "In13.Cu")
		(net "P5E_CPU0_PE0_RX_DP<15>")
	)
	(segment
		(start 306.258468 -394.058394)
		(end 306.080668 -399.632678)
		(width 0.14732)
		(layer "In13.Cu")
		(net "P5E_CPU0_PE0_RX_DP<15>")
	)
	(segment
		(start 308.835806 -320.058288)
		(end 307.699156 -320.058288)
		(width 0.14732)
		(layer "In13.Cu")
		(net "P5E_CPU0_PE0_RX_DP<15>")
	)
	(segment
		(start 311.622694 -317.2714)
		(end 308.835806 -320.058288)
		(width 0.14732)
		(layer "In13.Cu")
		(net "P5E_CPU0_PE0_RX_DP<15>")
	)
	(segment
		(start 305.970432 -382.610868)
		(end 306.098194 -382.732026)
		(width 0.14732)
		(layer "In13.Cu")
		(net "P5E_CPU0_PE0_RX_DP<15>")
	)
	(segment
		(start 306.280312 -389.976106)
		(end 306.1589 -390.103614)
		(width 0.14732)
		(layer "In13.Cu")
		(net "P5E_CPU0_PE0_RX_DP<15>")
	)
	(segment
		(start 306.02682 -384.85572)
		(end 306.154582 -384.976878)
		(width 0.14732)
		(layer "In13.Cu")
		(net "P5E_CPU0_PE0_RX_DP<15>")
	)
	(segment
		(start 307.699156 -320.058288)
		(end 306.984654 -320.354452)
		(width 0.14732)
		(layer "In13.Cu")
		(net "P5E_CPU0_PE0_RX_DP<15>")
	)
	(segment
		(start 349.254826 -208.386934)
		(end 347.96857 -207.100678)
		(width 0.14732)
		(layer "In13.Cu")
		(net "P5E_CPU0_PE0_RX_DP<15>")
	)
	(segment
		(start 314.697364 -252.874018)
		(end 318.074802 -305.622198)
		(width 0.14732)
		(layer "In13.Cu")
		(net "P5E_CPU0_PE0_RX_DP<15>")
	)
	(segment
		(start 306.165504 -385.414012)
		(end 306.044092 -385.54152)
		(width 0.14732)
		(layer "In13.Cu")
		(net "P5E_CPU0_PE0_RX_DP<15>")
	)
	(segment
		(start 350.557084 -217.8939)
		(end 350.557084 -217.859864)
		(width 0.0889)
		(layer "In13.Cu")
		(net "P5E_CPU0_PE0_RX_DP<15>")
	)
	(segment
		(start 306.297584 -390.661398)
		(end 306.308506 -391.098532)
		(width 0.14732)
		(layer "In13.Cu")
		(net "P5E_CPU0_PE0_RX_DP<15>")
	)
	(segment
		(start 306.154582 -384.976878)
		(end 306.165504 -385.414012)
		(width 0.14732)
		(layer "In13.Cu")
		(net "P5E_CPU0_PE0_RX_DP<15>")
	)
	(segment
		(start 350.369124 -214.946992)
		(end 350.378014 -214.941912)
		(width 0.0889)
		(layer "In13.Cu")
		(net "P5E_CPU0_PE0_RX_DP<15>")
	)
	(segment
		(start 307.426868 -411.247336)
		(end 313.254898 -436.436262)
		(width 0.14732)
		(layer "In13.Cu")
		(net "P5E_CPU0_PE0_RX_DP<15>")
	)
	(segment
		(start 347.96857 -207.100678)
		(end 338.875116 -200.648316)
		(width 0.14732)
		(layer "In13.Cu")
		(net "P5E_CPU0_PE0_RX_DP<15>")
	)
	(segment
		(start 306.1589 -390.103614)
		(end 306.169822 -390.54024)
		(width 0.14732)
		(layer "In13.Cu")
		(net "P5E_CPU0_PE0_RX_DP<15>")
	)
	(segment
		(start 314.782454 -315.62421)
		(end 313.852814 -315.62421)
		(width 0.14732)
		(layer "In13.Cu")
		(net "P5E_CPU0_PE0_RX_DP<15>")
	)
	(segment
		(start 306.326032 -391.783824)
		(end 306.336954 -392.220958)
		(width 0.14732)
		(layer "In13.Cu")
		(net "P5E_CPU0_PE0_RX_DP<15>")
	)
	(segment
		(start 306.198016 -391.662666)
		(end 306.326032 -391.783824)
		(width 0.14732)
		(layer "In13.Cu")
		(net "P5E_CPU0_PE0_RX_DP<15>")
	)
	(segment
		(start 306.080668 -399.632678)
		(end 306.080668 -404.68169)
		(width 0.14732)
		(layer "In13.Cu")
		(net "P5E_CPU0_PE0_RX_DP<15>")
	)
	(segment
		(start 306.18303 -386.099304)
		(end 306.193952 -386.536438)
		(width 0.14732)
		(layer "In13.Cu")
		(net "P5E_CPU0_PE0_RX_DP<15>")
	)
	(segment
		(start 306.252118 -388.85368)
		(end 306.130706 -388.981188)
		(width 0.14732)
		(layer "In13.Cu")
		(net "P5E_CPU0_PE0_RX_DP<15>")
	)
	(segment
		(start 315.45784 -314.948824)
		(end 314.782454 -315.62421)
		(width 0.14732)
		(layer "In13.Cu")
		(net "P5E_CPU0_PE0_RX_DP<15>")
	)
	(segment
		(start 350.045274 -209.177382)
		(end 349.73641 -208.868518)
		(width 0.14732)
		(layer "In13.Cu")
		(net "P5E_CPU0_PE0_RX_DP<15>")
	)
	(segment
		(start 306.193952 -386.536438)
		(end 306.07254 -386.663946)
		(width 0.14732)
		(layer "In13.Cu")
		(net "P5E_CPU0_PE0_RX_DP<15>")
	)
	(segment
		(start 350.378522 -215.931242)
		(end 350.363536 -215.922606)
		(width 0.0889)
		(layer "In13.Cu")
		(net "P5E_CPU0_PE0_RX_DP<15>")
	)
	(segment
		(start 306.243736 -393.470892)
		(end 306.258468 -394.058394)
		(width 0.14732)
		(layer "In13.Cu")
		(net "P5E_CPU0_PE0_RX_DP<15>")
	)
	(segment
		(start 305.998626 -383.733294)
		(end 306.126388 -383.854452)
		(width 0.14732)
		(layer "In13.Cu")
		(net "P5E_CPU0_PE0_RX_DP<15>")
	)
	(segment
		(start 351.122234 -221.133924)
		(end 351.278698 -220.862906)
		(width 0.0889)
		(layer "In13.Cu")
		(net "P5E_CPU0_PE0_RX_DP<15>")
	)
	(segment
		(start 316.874144 -309.901082)
		(end 316.87389 -309.901082)
		(width 0.14732)
		(layer "In13.Cu")
		(net "P5E_CPU0_PE0_RX_DP<15>")
	)
	(segment
		(start 306.113434 -388.295388)
		(end 306.241196 -388.416546)
		(width 0.14732)
		(layer "In13.Cu")
		(net "P5E_CPU0_PE0_RX_DP<15>")
	)
	(segment
		(start 306.13731 -384.291586)
		(end 306.015898 -384.419094)
		(width 0.14732)
		(layer "In13.Cu")
		(net "P5E_CPU0_PE0_RX_DP<15>")
	)
	(segment
		(start 305.987704 -383.296668)
		(end 305.998626 -383.733294)
		(width 0.14732)
		(layer "In13.Cu")
		(net "P5E_CPU0_PE0_RX_DP<15>")
	)
	(segment
		(start 350.087184 -213.930484)
		(end 350.087184 -213.248748)
		(width 0.0889)
		(layer "In13.Cu")
		(net "P5E_CPU0_PE0_RX_DP<15>")
	)
	(segment
		(start 338.875116 -200.648316)
		(end 336.028538 -200.648316)
		(width 0.14732)
		(layer "In13.Cu")
		(net "P5E_CPU0_PE0_RX_DP<15>")
	)
	(segment
		(start 314.65012 -437.152288)
		(end 314.65012 -436.889906)
		(width 0.14732)
		(layer "In13.Cu")
		(net "P5E_CPU0_PE0_RX_DP<15>")
	)
	(segment
		(start 314.138056 -437.31942)
		(end 314.482988 -437.31942)
		(width 0.14732)
		(layer "In13.Cu")
		(net "P5E_CPU0_PE0_RX_DP<15>")
	)
	(segment
		(start 306.26939 -389.538972)
		(end 306.280312 -389.976106)
		(width 0.14732)
		(layer "In13.Cu")
		(net "P5E_CPU0_PE0_RX_DP<15>")
	)
	(segment
		(start 306.109116 -383.16916)
		(end 305.987704 -383.296668)
		(width 0.14732)
		(layer "In13.Cu")
		(net "P5E_CPU0_PE0_RX_DP<15>")
	)
	(segment
		(start 306.215542 -392.348466)
		(end 306.226464 -392.785092)
		(width 0.14732)
		(layer "In13.Cu")
		(net "P5E_CPU0_PE0_RX_DP<15>")
	)
	(segment
		(start 306.354226 -392.90625)
		(end 306.365148 -393.343384)
		(width 0.14732)
		(layer "In13.Cu")
		(net "P5E_CPU0_PE0_RX_DP<15>")
	)
	(segment
		(start 306.055014 -385.978146)
		(end 306.18303 -386.099304)
		(width 0.14732)
		(layer "In13.Cu")
		(net "P5E_CPU0_PE0_RX_DP<15>")
	)
	(segment
		(start 306.141628 -389.417814)
		(end 306.26939 -389.538972)
		(width 0.14732)
		(layer "In13.Cu")
		(net "P5E_CPU0_PE0_RX_DP<15>")
	)
	(segment
		(start 301.563532 -325.775574)
		(end 301.563532 -329.11542)
		(width 0.14732)
		(layer "In13.Cu")
		(net "P5E_CPU0_PE0_RX_DP<15>")
	)
	(segment
		(start 321.023996 -213.966298)
		(end 318.630046 -219.745814)
		(width 0.14732)
		(layer "In13.Cu")
		(net "P5E_CPU0_PE0_RX_DP<15>")
	)
	(segment
		(start 306.102512 -387.858762)
		(end 306.113434 -388.295388)
		(width 0.14732)
		(layer "In13.Cu")
		(net "P5E_CPU0_PE0_RX_DP<15>")
	)
	(segment
		(start 313.254898 -436.436262)
		(end 314.138056 -437.31942)
		(width 0.14732)
		(layer "In13.Cu")
		(net "P5E_CPU0_PE0_RX_DP<15>")
	)
	(segment
		(start 350.045274 -213.18474)
		(end 350.045274 -209.177382)
		(width 0.14732)
		(layer "In13.Cu")
		(net "P5E_CPU0_PE0_RX_DP<15>")
	)
	(arc
		(start 350.839532 -216.739978)
		(mid 350.635197 -216.537373)
		(end 350.557084 -216.260426)
		(width 0.0889)
		(layer "In13.Cu")
		(net "P5E_CPU0_PE0_RX_DP<15>")
	)
	(arc
		(start 351.23755 -220.760798)
		(mid 351.085063 -220.570702)
		(end 351.02673 -220.334078)
		(width 0.0889)
		(layer "In13.Cu")
		(net "P5E_CPU0_PE0_RX_DP<15>")
	)
	(arc
		(start 351.02673 -220.311218)
		(mid 350.97446 -220.128853)
		(end 350.839532 -219.995496)
		(width 0.0889)
		(layer "In13.Cu")
		(net "P5E_CPU0_PE0_RX_DP<15>")
	)
	(arc
		(start 350.848168 -219.0115)
		(mid 351.026644 -218.692222)
		(end 350.848168 -218.372944)
		(width 0.0889)
		(layer "In13.Cu")
		(net "P5E_CPU0_PE0_RX_DP<15>")
	)
	(arc
		(start 350.839532 -219.995496)
		(mid 350.557 -219.506148)
		(end 350.839278 -219.01658)
		(width 0.0889)
		(layer "In13.Cu")
		(net "P5E_CPU0_PE0_RX_DP<15>")
	)
	(arc
		(start 351.254568 -220.773752)
		(mid 351.245997 -220.767356)
		(end 351.23755 -220.760798)
		(width 0.0889)
		(layer "In13.Cu")
		(net "P5E_CPU0_PE0_RX_DP<15>")
	)
	(arc
		(start 350.363536 -215.922606)
		(mid 350.086628 -215.433205)
		(end 350.369124 -214.946992)
		(width 0.0889)
		(layer "In13.Cu")
		(net "P5E_CPU0_PE0_RX_DP<15>")
	)
	(arc
		(start 350.102424 -213.969346)
		(mid 350.094461 -213.950049)
		(end 350.087184 -213.930484)
		(width 0.0889)
		(layer "In13.Cu")
		(net "P5E_CPU0_PE0_RX_DP<15>")
	)
	(arc
		(start 350.372426 -214.261954)
		(mid 350.212354 -214.138774)
		(end 350.102424 -213.969346)
		(width 0.0889)
		(layer "In13.Cu")
		(net "P5E_CPU0_PE0_RX_DP<15>")
	)
	(arc
		(start 350.556576 -214.461344)
		(mid 350.481571 -214.345885)
		(end 350.372426 -214.261954)
		(width 0.0889)
		(layer "In13.Cu")
		(net "P5E_CPU0_PE0_RX_DP<15>")
	)
	(arc
		(start 350.556322 -214.637366)
		(mid 350.556519 -214.630001)
		(end 350.556576 -214.622634)
		(width 0.0889)
		(layer "In13.Cu")
		(net "P5E_CPU0_PE0_RX_DP<15>")
	)
	(arc
		(start 350.378014 -214.941912)
		(mid 350.505268 -214.811946)
		(end 350.556322 -214.637366)
		(width 0.0889)
		(layer "In13.Cu")
		(net "P5E_CPU0_PE0_RX_DP<15>")
	)
	(arc
		(start 350.839532 -217.388694)
		(mid 351.026835 -217.064336)
		(end 350.839532 -216.739978)
		(width 0.0889)
		(layer "In13.Cu")
		(net "P5E_CPU0_PE0_RX_DP<15>")
	)
	(arc
		(start 350.557084 -217.859864)
		(mid 350.637246 -217.587675)
		(end 350.839532 -217.388694)
		(width 0.0889)
		(layer "In13.Cu")
		(net "P5E_CPU0_PE0_RX_DP<15>")
	)
	(arc
		(start 350.839278 -218.367864)
		(mid 350.636455 -218.167633)
		(end 350.557084 -217.8939)
		(width 0.0889)
		(layer "In13.Cu")
		(net "P5E_CPU0_PE0_RX_DP<15>")
	)
	(arc
		(start 350.557084 -216.25052)
		(mid 350.509405 -216.06762)
		(end 350.378522 -215.931242)
		(width 0.0889)
		(layer "In13.Cu")
		(net "P5E_CPU0_PE0_RX_DP<15>")
	)
	(segment
		(start 350.652334 -222.48368)
		(end 350.652334 -221.947994)
		(width 0.13208)
		(layer "F.Cu")
		(net "P5E_CPU0_PE0_RX_DP<14>")
	)
	(segment
		(start 350.652334 -221.947994)
		(end 350.65208 -221.94774)
		(width 0.13208)
		(layer "F.Cu")
		(net "P5E_CPU0_PE0_RX_DP<14>")
	)
	(segment
		(start 308.894226 -391.62355)
		(end 309.027068 -391.739374)
		(width 0.14732)
		(layer "In13.Cu")
		(net "P5E_CPU0_PE0_RX_DP<14>")
	)
	(segment
		(start 305.414426 -327.878948)
		(end 304.005996 -329.287632)
		(width 0.14732)
		(layer "In13.Cu")
		(net "P5E_CPU0_PE0_RX_DP<14>")
	)
	(segment
		(start 308.66715 -388.262368)
		(end 308.799992 -388.378192)
		(width 0.14732)
		(layer "In13.Cu")
		(net "P5E_CPU0_PE0_RX_DP<14>")
	)
	(segment
		(start 316.482984 -438.319418)
		(end 316.650116 -438.152286)
		(width 0.14732)
		(layer "In13.Cu")
		(net "P5E_CPU0_PE0_RX_DP<14>")
	)
	(segment
		(start 349.617284 -217.8939)
		(end 349.617284 -217.856308)
		(width 0.0889)
		(layer "In13.Cu")
		(net "P5E_CPU0_PE0_RX_DP<14>")
	)
	(segment
		(start 313.642756 -319.385188)
		(end 313.459876 -319.513712)
		(width 0.14732)
		(layer "In13.Cu")
		(net "P5E_CPU0_PE0_RX_DP<14>")
	)
	(segment
		(start 305.414426 -325.155052)
		(end 305.414426 -327.878948)
		(width 0.14732)
		(layer "In13.Cu")
		(net "P5E_CPU0_PE0_RX_DP<14>")
	)
	(segment
		(start 313.459876 -319.513712)
		(end 312.243724 -320.72961)
		(width 0.14732)
		(layer "In13.Cu")
		(net "P5E_CPU0_PE0_RX_DP<14>")
	)
	(segment
		(start 349.899478 -217.388694)
		(end 349.908368 -217.383614)
		(width 0.0889)
		(layer "In13.Cu")
		(net "P5E_CPU0_PE0_RX_DP<14>")
	)
	(segment
		(start 309.027068 -391.739374)
		(end 309.056532 -392.175746)
		(width 0.14732)
		(layer "In13.Cu")
		(net "P5E_CPU0_PE0_RX_DP<14>")
	)
	(segment
		(start 349.902526 -218.369388)
		(end 349.899478 -218.367864)
		(width 0.0889)
		(layer "In13.Cu")
		(net "P5E_CPU0_PE0_RX_DP<14>")
	)
	(segment
		(start 317.58636 -312.23585)
		(end 317.586614 -312.23585)
		(width 0.14732)
		(layer "In13.Cu")
		(net "P5E_CPU0_PE0_RX_DP<14>")
	)
	(segment
		(start 317.586614 -312.23585)
		(end 317.586614 -312.236104)
		(width 0.14732)
		(layer "In13.Cu")
		(net "P5E_CPU0_PE0_RX_DP<14>")
	)
	(segment
		(start 308.440836 -384.901186)
		(end 308.573424 -385.01701)
		(width 0.14732)
		(layer "In13.Cu")
		(net "P5E_CPU0_PE0_RX_DP<14>")
	)
	(segment
		(start 334.297782 -202.398376)
		(end 332.944978 -203.75118)
		(width 0.14732)
		(layer "In13.Cu")
		(net "P5E_CPU0_PE0_RX_DP<14>")
	)
	(segment
		(start 309.143908 -404.68169)
		(end 310.490108 -406.02789)
		(width 0.14732)
		(layer "In13.Cu")
		(net "P5E_CPU0_PE0_RX_DP<14>")
	)
	(segment
		(start 315.699394 -253.263146)
		(end 319.225676 -308.091332)
		(width 0.14732)
		(layer "In13.Cu")
		(net "P5E_CPU0_PE0_RX_DP<14>")
	)
	(segment
		(start 349.900494 -216.740486)
		(end 349.899478 -216.739978)
		(width 0.0889)
		(layer "In13.Cu")
		(net "P5E_CPU0_PE0_RX_DP<14>")
	)
	(segment
		(start 309.056532 -392.175746)
		(end 308.940708 -392.30808)
		(width 0.14732)
		(layer "In13.Cu")
		(net "P5E_CPU0_PE0_RX_DP<14>")
	)
	(segment
		(start 349.429832 -215.926162)
		(end 349.42907 -215.925654)
		(width 0.0889)
		(layer "In13.Cu")
		(net "P5E_CPU0_PE0_RX_DP<14>")
	)
	(segment
		(start 303.542192 -340.571836)
		(end 304.018188 -343.285826)
		(width 0.14732)
		(layer "In13.Cu")
		(net "P5E_CPU0_PE0_RX_DP<14>")
	)
	(segment
		(start 308.441598 -384.900678)
		(end 308.440836 -384.901186)
		(width 0.14732)
		(layer "In13.Cu")
		(net "P5E_CPU0_PE0_RX_DP<14>")
	)
	(segment
		(start 310.490108 -406.02789)
		(end 310.490108 -410.524198)
		(width 0.14732)
		(layer "In13.Cu")
		(net "P5E_CPU0_PE0_RX_DP<14>")
	)
	(segment
		(start 317.565024 -312.29046)
		(end 316.187582 -315.75121)
		(width 0.14732)
		(layer "In13.Cu")
		(net "P5E_CPU0_PE0_RX_DP<14>")
	)
	(segment
		(start 349.616776 -214.622634)
		(end 349.616776 -214.461344)
		(width 0.0889)
		(layer "In13.Cu")
		(net "P5E_CPU0_PE0_RX_DP<14>")
	)
	(segment
		(start 349.617284 -219.521532)
		(end 349.617284 -219.490544)
		(width 0.0889)
		(layer "In13.Cu")
		(net "P5E_CPU0_PE0_RX_DP<14>")
	)
	(segment
		(start 308.969918 -392.743944)
		(end 309.10276 -392.859768)
		(width 0.14732)
		(layer "In13.Cu")
		(net "P5E_CPU0_PE0_RX_DP<14>")
	)
	(segment
		(start 304.018188 -343.285826)
		(end 307.48986 -370.778024)
		(width 0.14732)
		(layer "In13.Cu")
		(net "P5E_CPU0_PE0_RX_DP<14>")
	)
	(segment
		(start 349.908368 -220.000576)
		(end 349.900494 -219.996004)
		(width 0.0889)
		(layer "In13.Cu")
		(net "P5E_CPU0_PE0_RX_DP<14>")
	)
	(segment
		(start 319.225676 -308.091332)
		(end 317.58636 -312.23585)
		(width 0.14732)
		(layer "In13.Cu")
		(net "P5E_CPU0_PE0_RX_DP<14>")
	)
	(segment
		(start 308.63794 -387.826504)
		(end 308.66715 -388.262368)
		(width 0.14732)
		(layer "In13.Cu")
		(net "P5E_CPU0_PE0_RX_DP<14>")
	)
	(segment
		(start 349.617284 -216.266014)
		(end 349.617284 -216.25052)
		(width 0.0889)
		(layer "In13.Cu")
		(net "P5E_CPU0_PE0_RX_DP<14>")
	)
	(segment
		(start 321.765676 -214.611712)
		(end 319.53708 -219.991178)
		(width 0.14732)
		(layer "In13.Cu")
		(net "P5E_CPU0_PE0_RX_DP<14>")
	)
	(segment
		(start 317.565532 -312.288936)
		(end 317.565024 -312.29046)
		(width 0.14732)
		(layer "In13.Cu")
		(net "P5E_CPU0_PE0_RX_DP<14>")
	)
	(segment
		(start 336.132424 -201.638408)
		(end 334.297782 -202.398376)
		(width 0.14732)
		(layer "In13.Cu")
		(net "P5E_CPU0_PE0_RX_DP<14>")
	)
	(segment
		(start 349.900494 -219.996004)
		(end 349.899478 -219.995496)
		(width 0.0889)
		(layer "In13.Cu")
		(net "P5E_CPU0_PE0_RX_DP<14>")
	)
	(segment
		(start 308.648862 -386.137404)
		(end 308.678326 -386.573776)
		(width 0.14732)
		(layer "In13.Cu")
		(net "P5E_CPU0_PE0_RX_DP<14>")
	)
	(segment
		(start 312.243724 -320.72961)
		(end 310.47309 -320.72961)
		(width 0.14732)
		(layer "In13.Cu")
		(net "P5E_CPU0_PE0_RX_DP<14>")
	)
	(segment
		(start 307.48986 -370.778024)
		(end 308.441598 -384.900678)
		(width 0.14732)
		(layer "In13.Cu")
		(net "P5E_CPU0_PE0_RX_DP<14>")
	)
	(segment
		(start 309.13197 -393.295886)
		(end 309.016146 -393.428474)
		(width 0.14732)
		(layer "In13.Cu")
		(net "P5E_CPU0_PE0_RX_DP<14>")
	)
	(segment
		(start 310.490108 -410.524198)
		(end 311.537858 -412.679896)
		(width 0.14732)
		(layer "In13.Cu")
		(net "P5E_CPU0_PE0_RX_DP<14>")
	)
	(segment
		(start 308.865016 -391.187686)
		(end 308.894226 -391.62355)
		(width 0.14732)
		(layer "In13.Cu")
		(net "P5E_CPU0_PE0_RX_DP<14>")
	)
	(segment
		(start 349.617284 -221.149418)
		(end 349.617284 -221.111826)
		(width 0.0889)
		(layer "In13.Cu")
		(net "P5E_CPU0_PE0_RX_DP<14>")
	)
	(segment
		(start 349.908368 -216.745058)
		(end 349.900494 -216.740486)
		(width 0.0889)
		(layer "In13.Cu")
		(net "P5E_CPU0_PE0_RX_DP<14>")
	)
	(segment
		(start 350.495616 -221.676722)
		(end 350.406716 -221.6531)
		(width 0.0889)
		(layer "In13.Cu")
		(net "P5E_CPU0_PE0_RX_DP<14>")
	)
	(segment
		(start 317.565786 -312.288682)
		(end 317.565532 -312.288936)
		(width 0.14732)
		(layer "In13.Cu")
		(net "P5E_CPU0_PE0_RX_DP<14>")
	)
	(segment
		(start 308.905148 -389.934958)
		(end 308.789324 -390.067292)
		(width 0.14732)
		(layer "In13.Cu")
		(net "P5E_CPU0_PE0_RX_DP<14>")
	)
	(segment
		(start 308.940708 -392.30808)
		(end 308.969918 -392.743944)
		(width 0.14732)
		(layer "In13.Cu")
		(net "P5E_CPU0_PE0_RX_DP<14>")
	)
	(segment
		(start 308.7243 -387.257798)
		(end 308.753764 -387.69417)
		(width 0.14732)
		(layer "In13.Cu")
		(net "P5E_CPU0_PE0_RX_DP<14>")
	)
	(segment
		(start 349.908368 -218.372944)
		(end 349.902526 -218.369388)
		(width 0.0889)
		(layer "In13.Cu")
		(net "P5E_CPU0_PE0_RX_DP<14>")
	)
	(segment
		(start 315.966856 -438.194958)
		(end 316.091316 -438.319418)
		(width 0.14732)
		(layer "In13.Cu")
		(net "P5E_CPU0_PE0_RX_DP<14>")
	)
	(segment
		(start 349.429324 -214.946992)
		(end 349.438214 -214.941912)
		(width 0.0889)
		(layer "In13.Cu")
		(net "P5E_CPU0_PE0_RX_DP<14>")
	)
	(segment
		(start 311.537858 -412.679896)
		(end 315.966856 -424.904408)
		(width 0.14732)
		(layer "In13.Cu")
		(net "P5E_CPU0_PE0_RX_DP<14>")
	)
	(segment
		(start 308.753764 -387.69417)
		(end 308.63794 -387.826504)
		(width 0.14732)
		(layer "In13.Cu")
		(net "P5E_CPU0_PE0_RX_DP<14>")
	)
	(segment
		(start 308.602888 -385.453382)
		(end 308.487064 -385.585716)
		(width 0.14732)
		(layer "In13.Cu")
		(net "P5E_CPU0_PE0_RX_DP<14>")
	)
	(segment
		(start 315.966856 -424.904408)
		(end 315.966856 -438.194958)
		(width 0.14732)
		(layer "In13.Cu")
		(net "P5E_CPU0_PE0_RX_DP<14>")
	)
	(segment
		(start 349.899478 -220.644212)
		(end 349.908368 -220.639132)
		(width 0.0889)
		(layer "In13.Cu")
		(net "P5E_CPU0_PE0_RX_DP<14>")
	)
	(segment
		(start 349.899478 -219.01658)
		(end 349.908368 -219.0115)
		(width 0.0889)
		(layer "In13.Cu")
		(net "P5E_CPU0_PE0_RX_DP<14>")
	)
	(segment
		(start 308.875684 -389.498586)
		(end 308.905148 -389.934958)
		(width 0.14732)
		(layer "In13.Cu")
		(net "P5E_CPU0_PE0_RX_DP<14>")
	)
	(segment
		(start 349.147384 -213.930484)
		(end 349.147384 -213.248748)
		(width 0.0889)
		(layer "In13.Cu")
		(net "P5E_CPU0_PE0_RX_DP<14>")
	)
	(segment
		(start 310.47309 -320.72961)
		(end 309.391812 -321.177666)
		(width 0.14732)
		(layer "In13.Cu")
		(net "P5E_CPU0_PE0_RX_DP<14>")
	)
	(segment
		(start 308.818534 -390.503156)
		(end 308.951376 -390.61898)
		(width 0.14732)
		(layer "In13.Cu")
		(net "P5E_CPU0_PE0_RX_DP<14>")
	)
	(segment
		(start 349.42907 -215.925654)
		(end 349.423736 -215.922606)
		(width 0.0889)
		(layer "In13.Cu")
		(net "P5E_CPU0_PE0_RX_DP<14>")
	)
	(segment
		(start 308.573424 -385.01701)
		(end 308.602888 -385.453382)
		(width 0.14732)
		(layer "In13.Cu")
		(net "P5E_CPU0_PE0_RX_DP<14>")
	)
	(segment
		(start 309.143908 -395.324584)
		(end 309.143908 -404.68169)
		(width 0.14732)
		(layer "In13.Cu")
		(net "P5E_CPU0_PE0_RX_DP<14>")
	)
	(segment
		(start 308.591712 -387.141974)
		(end 308.7243 -387.257798)
		(width 0.14732)
		(layer "In13.Cu")
		(net "P5E_CPU0_PE0_RX_DP<14>")
	)
	(segment
		(start 349.105474 -213.206838)
		(end 349.105474 -213.18474)
		(width 0.0889)
		(layer "In13.Cu")
		(net "P5E_CPU0_PE0_RX_DP<14>")
	)
	(segment
		(start 349.105474 -209.820256)
		(end 346.579952 -207.294734)
		(width 0.14732)
		(layer "In13.Cu")
		(net "P5E_CPU0_PE0_RX_DP<14>")
	)
	(segment
		(start 308.799992 -388.378192)
		(end 308.829456 -388.814564)
		(width 0.14732)
		(layer "In13.Cu")
		(net "P5E_CPU0_PE0_RX_DP<14>")
	)
	(segment
		(start 349.147384 -213.248748)
		(end 349.105474 -213.206838)
		(width 0.0889)
		(layer "In13.Cu")
		(net "P5E_CPU0_PE0_RX_DP<14>")
	)
	(segment
		(start 350.65208 -221.94774)
		(end 350.495616 -221.676722)
		(width 0.0889)
		(layer "In13.Cu")
		(net "P5E_CPU0_PE0_RX_DP<14>")
	)
	(segment
		(start 338.547964 -201.638408)
		(end 336.132424 -201.638408)
		(width 0.14732)
		(layer "In13.Cu")
		(net "P5E_CPU0_PE0_RX_DP<14>")
	)
	(segment
		(start 331.167232 -205.210156)
		(end 321.765676 -214.611712)
		(width 0.14732)
		(layer "In13.Cu")
		(net "P5E_CPU0_PE0_RX_DP<14>")
	)
	(segment
		(start 308.678326 -386.573776)
		(end 308.562502 -386.70611)
		(width 0.14732)
		(layer "In13.Cu")
		(net "P5E_CPU0_PE0_RX_DP<14>")
	)
	(segment
		(start 315.778642 -250.876562)
		(end 315.699394 -253.263146)
		(width 0.14732)
		(layer "In13.Cu")
		(net "P5E_CPU0_PE0_RX_DP<14>")
	)
	(segment
		(start 317.586614 -312.236104)
		(end 317.565786 -312.288682)
		(width 0.14732)
		(layer "In13.Cu")
		(net "P5E_CPU0_PE0_RX_DP<14>")
	)
	(segment
		(start 316.091316 -438.319418)
		(end 316.482984 -438.319418)
		(width 0.14732)
		(layer "In13.Cu")
		(net "P5E_CPU0_PE0_RX_DP<14>")
	)
	(segment
		(start 304.005996 -329.287632)
		(end 303.528984 -330.458826)
		(width 0.14732)
		(layer "In13.Cu")
		(net "P5E_CPU0_PE0_RX_DP<14>")
	)
	(segment
		(start 308.713632 -388.946898)
		(end 308.742842 -389.382762)
		(width 0.14732)
		(layer "In13.Cu")
		(net "P5E_CPU0_PE0_RX_DP<14>")
	)
	(segment
		(start 308.829456 -388.814564)
		(end 308.713632 -388.946898)
		(width 0.14732)
		(layer "In13.Cu")
		(net "P5E_CPU0_PE0_RX_DP<14>")
	)
	(segment
		(start 303.528984 -330.458826)
		(end 303.542192 -340.571836)
		(width 0.14732)
		(layer "In13.Cu")
		(net "P5E_CPU0_PE0_RX_DP<14>")
	)
	(segment
		(start 308.516274 -386.02158)
		(end 308.648862 -386.137404)
		(width 0.14732)
		(layer "In13.Cu")
		(net "P5E_CPU0_PE0_RX_DP<14>")
	)
	(segment
		(start 309.391812 -321.177666)
		(end 305.414426 -325.155052)
		(width 0.14732)
		(layer "In13.Cu")
		(net "P5E_CPU0_PE0_RX_DP<14>")
	)
	(segment
		(start 308.951376 -390.61898)
		(end 308.98084 -391.055352)
		(width 0.14732)
		(layer "In13.Cu")
		(net "P5E_CPU0_PE0_RX_DP<14>")
	)
	(segment
		(start 309.016146 -393.428474)
		(end 309.143908 -395.324584)
		(width 0.14732)
		(layer "In13.Cu")
		(net "P5E_CPU0_PE0_RX_DP<14>")
	)
	(segment
		(start 349.434404 -215.928702)
		(end 349.429832 -215.926162)
		(width 0.0889)
		(layer "In13.Cu")
		(net "P5E_CPU0_PE0_RX_DP<14>")
	)
	(segment
		(start 316.650116 -438.152286)
		(end 316.650116 -437.889904)
		(width 0.14732)
		(layer "In13.Cu")
		(net "P5E_CPU0_PE0_RX_DP<14>")
	)
	(segment
		(start 308.789324 -390.067292)
		(end 308.818534 -390.503156)
		(width 0.14732)
		(layer "In13.Cu")
		(net "P5E_CPU0_PE0_RX_DP<14>")
	)
	(segment
		(start 316.187582 -315.75121)
		(end 313.642756 -319.385188)
		(width 0.14732)
		(layer "In13.Cu")
		(net "P5E_CPU0_PE0_RX_DP<14>")
	)
	(segment
		(start 349.105474 -213.18474)
		(end 349.105474 -209.820256)
		(width 0.14732)
		(layer "In13.Cu")
		(net "P5E_CPU0_PE0_RX_DP<14>")
	)
	(segment
		(start 308.562502 -386.70611)
		(end 308.591712 -387.141974)
		(width 0.14732)
		(layer "In13.Cu")
		(net "P5E_CPU0_PE0_RX_DP<14>")
	)
	(segment
		(start 308.98084 -391.055352)
		(end 308.865016 -391.187686)
		(width 0.14732)
		(layer "In13.Cu")
		(net "P5E_CPU0_PE0_RX_DP<14>")
	)
	(segment
		(start 309.10276 -392.859768)
		(end 309.13197 -393.295886)
		(width 0.14732)
		(layer "In13.Cu")
		(net "P5E_CPU0_PE0_RX_DP<14>")
	)
	(segment
		(start 319.53708 -219.991178)
		(end 315.778642 -250.876562)
		(width 0.14732)
		(layer "In13.Cu")
		(net "P5E_CPU0_PE0_RX_DP<14>")
	)
	(segment
		(start 308.487064 -385.585716)
		(end 308.516274 -386.02158)
		(width 0.14732)
		(layer "In13.Cu")
		(net "P5E_CPU0_PE0_RX_DP<14>")
	)
	(segment
		(start 349.438722 -215.931242)
		(end 349.434404 -215.928702)
		(width 0.0889)
		(layer "In13.Cu")
		(net "P5E_CPU0_PE0_RX_DP<14>")
	)
	(segment
		(start 346.579952 -207.294734)
		(end 338.547964 -201.638408)
		(width 0.14732)
		(layer "In13.Cu")
		(net "P5E_CPU0_PE0_RX_DP<14>")
	)
	(segment
		(start 332.944978 -203.75118)
		(end 331.167232 -205.210156)
		(width 0.14732)
		(layer "In13.Cu")
		(net "P5E_CPU0_PE0_RX_DP<14>")
	)
	(segment
		(start 349.14713 -215.436704)
		(end 349.14713 -215.414606)
		(width 0.0889)
		(layer "In13.Cu")
		(net "P5E_CPU0_PE0_RX_DP<14>")
	)
	(segment
		(start 308.742842 -389.382762)
		(end 308.875684 -389.498586)
		(width 0.14732)
		(layer "In13.Cu")
		(net "P5E_CPU0_PE0_RX_DP<14>")
	)
	(arc
		(start 349.162624 -213.969346)
		(mid 349.154661 -213.950049)
		(end 349.147384 -213.930484)
		(width 0.0889)
		(layer "In13.Cu")
		(net "P5E_CPU0_PE0_RX_DP<14>")
	)
	(arc
		(start 349.908368 -219.0115)
		(mid 350.086844 -218.692222)
		(end 349.908368 -218.372944)
		(width 0.0889)
		(layer "In13.Cu")
		(net "P5E_CPU0_PE0_RX_DP<14>")
	)
	(arc
		(start 350.386904 -221.661228)
		(mid 350.138893 -221.697693)
		(end 349.899478 -221.623382)
		(width 0.0889)
		(layer "In13.Cu")
		(net "P5E_CPU0_PE0_RX_DP<14>")
	)
	(arc
		(start 349.432626 -214.261954)
		(mid 349.272554 -214.138774)
		(end 349.162624 -213.969346)
		(width 0.0889)
		(layer "In13.Cu")
		(net "P5E_CPU0_PE0_RX_DP<14>")
	)
	(arc
		(start 349.899478 -218.367864)
		(mid 349.696655 -218.167633)
		(end 349.617284 -217.8939)
		(width 0.0889)
		(layer "In13.Cu")
		(net "P5E_CPU0_PE0_RX_DP<14>")
	)
	(arc
		(start 349.617284 -221.111826)
		(mid 349.698195 -220.841698)
		(end 349.899478 -220.644212)
		(width 0.0889)
		(layer "In13.Cu")
		(net "P5E_CPU0_PE0_RX_DP<14>")
	)
	(arc
		(start 349.616776 -214.461344)
		(mid 349.541771 -214.345885)
		(end 349.432626 -214.261954)
		(width 0.0889)
		(layer "In13.Cu")
		(net "P5E_CPU0_PE0_RX_DP<14>")
	)
	(arc
		(start 349.899478 -221.623382)
		(mid 349.696655 -221.423151)
		(end 349.617284 -221.149418)
		(width 0.0889)
		(layer "In13.Cu")
		(net "P5E_CPU0_PE0_RX_DP<14>")
	)
	(arc
		(start 349.438214 -214.941912)
		(mid 349.565468 -214.811946)
		(end 349.616522 -214.637366)
		(width 0.0889)
		(layer "In13.Cu")
		(net "P5E_CPU0_PE0_RX_DP<14>")
	)
	(arc
		(start 350.406716 -221.6531)
		(mid 350.396849 -221.657259)
		(end 350.386904 -221.661228)
		(width 0.0889)
		(layer "In13.Cu")
		(net "P5E_CPU0_PE0_RX_DP<14>")
	)
	(arc
		(start 349.899478 -216.739978)
		(mid 349.696655 -216.539747)
		(end 349.617284 -216.266014)
		(width 0.0889)
		(layer "In13.Cu")
		(net "P5E_CPU0_PE0_RX_DP<14>")
	)
	(arc
		(start 349.616522 -214.637366)
		(mid 349.616719 -214.630001)
		(end 349.616776 -214.622634)
		(width 0.0889)
		(layer "In13.Cu")
		(net "P5E_CPU0_PE0_RX_DP<14>")
	)
	(arc
		(start 349.908368 -220.639132)
		(mid 350.086965 -220.319854)
		(end 349.908368 -220.000576)
		(width 0.0889)
		(layer "In13.Cu")
		(net "P5E_CPU0_PE0_RX_DP<14>")
	)
	(arc
		(start 349.617284 -217.856308)
		(mid 349.698195 -217.58618)
		(end 349.899478 -217.388694)
		(width 0.0889)
		(layer "In13.Cu")
		(net "P5E_CPU0_PE0_RX_DP<14>")
	)
	(arc
		(start 349.908368 -217.383614)
		(mid 350.086965 -217.064336)
		(end 349.908368 -216.745058)
		(width 0.0889)
		(layer "In13.Cu")
		(net "P5E_CPU0_PE0_RX_DP<14>")
	)
	(arc
		(start 349.617284 -216.25052)
		(mid 349.569605 -216.06762)
		(end 349.438722 -215.931242)
		(width 0.0889)
		(layer "In13.Cu")
		(net "P5E_CPU0_PE0_RX_DP<14>")
	)
	(arc
		(start 349.617284 -219.490544)
		(mid 349.696654 -219.21681)
		(end 349.899478 -219.01658)
		(width 0.0889)
		(layer "In13.Cu")
		(net "P5E_CPU0_PE0_RX_DP<14>")
	)
	(arc
		(start 349.423736 -215.922606)
		(mid 349.221149 -215.716255)
		(end 349.14713 -215.436704)
		(width 0.0889)
		(layer "In13.Cu")
		(net "P5E_CPU0_PE0_RX_DP<14>")
	)
	(arc
		(start 349.899478 -219.995496)
		(mid 349.696655 -219.795265)
		(end 349.617284 -219.521532)
		(width 0.0889)
		(layer "In13.Cu")
		(net "P5E_CPU0_PE0_RX_DP<14>")
	)
	(arc
		(start 349.14713 -215.414606)
		(mid 349.228041 -215.144478)
		(end 349.429324 -214.946992)
		(width 0.0889)
		(layer "In13.Cu")
		(net "P5E_CPU0_PE0_RX_DP<14>")
	)
	(segment
		(start 349.24238 -221.134178)
		(end 349.242634 -221.133924)
		(width 0.13208)
		(layer "F.Cu")
		(net "P5E_CPU0_PE0_RX_DP<13>")
	)
	(segment
		(start 349.24238 -221.669864)
		(end 349.24238 -221.134178)
		(width 0.13208)
		(layer "F.Cu")
		(net "P5E_CPU0_PE0_RX_DP<13>")
	)
	(segment
		(start 310.368442 -322.034408)
		(end 309.852314 -322.034408)
		(width 0.14732)
		(layer "In13.Cu")
		(net "P5E_CPU0_PE0_RX_DP<13>")
	)
	(segment
		(start 318.650112 -437.152288)
		(end 318.650112 -436.889906)
		(width 0.14732)
		(layer "In13.Cu")
		(net "P5E_CPU0_PE0_RX_DP<13>")
	)
	(segment
		(start 310.914288 -387.13664)
		(end 310.971946 -387.569964)
		(width 0.14732)
		(layer "In13.Cu")
		(net "P5E_CPU0_PE0_RX_DP<13>")
	)
	(segment
		(start 304.724816 -341.466678)
		(end 310.630062 -385.924044)
		(width 0.14732)
		(layer "In13.Cu")
		(net "P5E_CPU0_PE0_RX_DP<13>")
	)
	(segment
		(start 310.629808 -385.924044)
		(end 310.766968 -386.028692)
		(width 0.14732)
		(layer "In13.Cu")
		(net "P5E_CPU0_PE0_RX_DP<13>")
	)
	(segment
		(start 348.959678 -219.01658)
		(end 348.968568 -219.0115)
		(width 0.0889)
		(layer "In13.Cu")
		(net "P5E_CPU0_PE0_RX_DP<13>")
	)
	(segment
		(start 310.901842 -322.567808)
		(end 310.368442 -322.034408)
		(width 0.14732)
		(layer "In13.Cu")
		(net "P5E_CPU0_PE0_RX_DP<13>")
	)
	(segment
		(start 315.436758 -416.056572)
		(end 317.966852 -424.59021)
		(width 0.14732)
		(layer "In13.Cu")
		(net "P5E_CPU0_PE0_RX_DP<13>")
	)
	(segment
		(start 315.2521 -415.434526)
		(end 315.42609 -415.52876)
		(width 0.14732)
		(layer "In13.Cu")
		(net "P5E_CPU0_PE0_RX_DP<13>")
	)
	(segment
		(start 314.193428 -411.86354)
		(end 314.533026 -413.009588)
		(width 0.14732)
		(layer "In13.Cu")
		(net "P5E_CPU0_PE0_RX_DP<13>")
	)
	(segment
		(start 348.165674 -213.275672)
		(end 348.165674 -210.37042)
		(width 0.14732)
		(layer "In13.Cu")
		(net "P5E_CPU0_PE0_RX_DP<13>")
	)
	(segment
		(start 318.091312 -437.31942)
		(end 318.48298 -437.31942)
		(width 0.14732)
		(layer "In13.Cu")
		(net "P5E_CPU0_PE0_RX_DP<13>")
	)
	(segment
		(start 311.061354 -388.244588)
		(end 311.119012 -388.677912)
		(width 0.14732)
		(layer "In13.Cu")
		(net "P5E_CPU0_PE0_RX_DP<13>")
	)
	(segment
		(start 311.266078 -389.78586)
		(end 311.161176 -389.922766)
		(width 0.14732)
		(layer "In13.Cu")
		(net "P5E_CPU0_PE0_RX_DP<13>")
	)
	(segment
		(start 317.966852 -437.19496)
		(end 318.091312 -437.31942)
		(width 0.14732)
		(layer "In13.Cu")
		(net "P5E_CPU0_PE0_RX_DP<13>")
	)
	(segment
		(start 311.071514 -389.247888)
		(end 311.07126 -389.247888)
		(width 0.14732)
		(layer "In13.Cu")
		(net "P5E_CPU0_PE0_RX_DP<13>")
	)
	(segment
		(start 315.436504 -416.05581)
		(end 315.436758 -416.056572)
		(width 0.14732)
		(layer "In13.Cu")
		(net "P5E_CPU0_PE0_RX_DP<13>")
	)
	(segment
		(start 320.485262 -220.225112)
		(end 316.709552 -251.091954)
		(width 0.14732)
		(layer "In13.Cu")
		(net "P5E_CPU0_PE0_RX_DP<13>")
	)
	(segment
		(start 311.119012 -388.677912)
		(end 311.01411 -388.814818)
		(width 0.14732)
		(layer "In13.Cu")
		(net "P5E_CPU0_PE0_RX_DP<13>")
	)
	(segment
		(start 315.02604 -414.180274)
		(end 315.130942 -414.533588)
		(width 0.14732)
		(layer "In13.Cu")
		(net "P5E_CPU0_PE0_RX_DP<13>")
	)
	(segment
		(start 349.242634 -221.133924)
		(end 349.399098 -220.862906)
		(width 0.0889)
		(layer "In13.Cu")
		(net "P5E_CPU0_PE0_RX_DP<13>")
	)
	(segment
		(start 314.852304 -414.08604)
		(end 315.02604 -414.180274)
		(width 0.14732)
		(layer "In13.Cu")
		(net "P5E_CPU0_PE0_RX_DP<13>")
	)
	(segment
		(start 313.553348 -410.442156)
		(end 314.193428 -411.86354)
		(width 0.14732)
		(layer "In13.Cu")
		(net "P5E_CPU0_PE0_RX_DP<13>")
	)
	(segment
		(start 348.968568 -218.372944)
		(end 348.960694 -218.368372)
		(width 0.0889)
		(layer "In13.Cu")
		(net "P5E_CPU0_PE0_RX_DP<13>")
	)
	(segment
		(start 318.48298 -437.31942)
		(end 318.650112 -437.152288)
		(width 0.14732)
		(layer "In13.Cu")
		(net "P5E_CPU0_PE0_RX_DP<13>")
	)
	(segment
		(start 310.867044 -387.70687)
		(end 310.924448 -388.13994)
		(width 0.14732)
		(layer "In13.Cu")
		(net "P5E_CPU0_PE0_RX_DP<13>")
	)
	(segment
		(start 311.560464 -392.001756)
		(end 311.455562 -392.138662)
		(width 0.14732)
		(layer "In13.Cu")
		(net "P5E_CPU0_PE0_RX_DP<13>")
	)
	(segment
		(start 314.728352 -413.667194)
		(end 314.728606 -413.667956)
		(width 0.14732)
		(layer "In13.Cu")
		(net "P5E_CPU0_PE0_RX_DP<13>")
	)
	(segment
		(start 322.61175 -215.09101)
		(end 320.485262 -220.225112)
		(width 0.14732)
		(layer "In13.Cu")
		(net "P5E_CPU0_PE0_RX_DP<13>")
	)
	(segment
		(start 311.161176 -389.922766)
		(end 311.21858 -390.355836)
		(width 0.14732)
		(layer "In13.Cu")
		(net "P5E_CPU0_PE0_RX_DP<13>")
	)
	(segment
		(start 318.427608 -280.88209)
		(end 318.427862 -280.88336)
		(width 0.14732)
		(layer "In13.Cu")
		(net "P5E_CPU0_PE0_RX_DP<13>")
	)
	(segment
		(start 315.130942 -414.533588)
		(end 315.036708 -414.707324)
		(width 0.14732)
		(layer "In13.Cu")
		(net "P5E_CPU0_PE0_RX_DP<13>")
	)
	(segment
		(start 348.960694 -218.368372)
		(end 348.959678 -218.367864)
		(width 0.0889)
		(layer "In13.Cu")
		(net "P5E_CPU0_PE0_RX_DP<13>")
	)
	(segment
		(start 306.35194 -328.271378)
		(end 304.933096 -329.690222)
		(width 0.14732)
		(layer "In13.Cu")
		(net "P5E_CPU0_PE0_RX_DP<13>")
	)
	(segment
		(start 304.933096 -329.690222)
		(end 304.546508 -330.897484)
		(width 0.14732)
		(layer "In13.Cu")
		(net "P5E_CPU0_PE0_RX_DP<13>")
	)
	(segment
		(start 315.036708 -414.707324)
		(end 315.2521 -415.434526)
		(width 0.14732)
		(layer "In13.Cu")
		(net "P5E_CPU0_PE0_RX_DP<13>")
	)
	(segment
		(start 331.603096 -206.099156)
		(end 322.61175 -215.09101)
		(width 0.14732)
		(layer "In13.Cu")
		(net "P5E_CPU0_PE0_RX_DP<13>")
	)
	(segment
		(start 304.546508 -330.897484)
		(end 304.725832 -341.41156)
		(width 0.14732)
		(layer "In13.Cu")
		(net "P5E_CPU0_PE0_RX_DP<13>")
	)
	(segment
		(start 314.728606 -413.667956)
		(end 314.852304 -414.08604)
		(width 0.14732)
		(layer "In13.Cu")
		(net "P5E_CPU0_PE0_RX_DP<13>")
	)
	(segment
		(start 310.971946 -387.569964)
		(end 310.867044 -387.70687)
		(width 0.14732)
		(layer "In13.Cu")
		(net "P5E_CPU0_PE0_RX_DP<13>")
	)
	(segment
		(start 317.286386 -315.816742)
		(end 313.8678 -320.693288)
		(width 0.14732)
		(layer "In13.Cu")
		(net "P5E_CPU0_PE0_RX_DP<13>")
	)
	(segment
		(start 310.924448 -388.13994)
		(end 310.924194 -388.13994)
		(width 0.14732)
		(layer "In13.Cu")
		(net "P5E_CPU0_PE0_RX_DP<13>")
	)
	(segment
		(start 314.812172 -413.512508)
		(end 314.728352 -413.667194)
		(width 0.14732)
		(layer "In13.Cu")
		(net "P5E_CPU0_PE0_RX_DP<13>")
	)
	(segment
		(start 310.766968 -386.028692)
		(end 310.824626 -386.462016)
		(width 0.14732)
		(layer "In13.Cu")
		(net "P5E_CPU0_PE0_RX_DP<13>")
	)
	(segment
		(start 311.308496 -391.030714)
		(end 311.3659 -391.463784)
		(width 0.14732)
		(layer "In13.Cu")
		(net "P5E_CPU0_PE0_RX_DP<13>")
	)
	(segment
		(start 311.413398 -390.893808)
		(end 311.308496 -391.030714)
		(width 0.14732)
		(layer "In13.Cu")
		(net "P5E_CPU0_PE0_RX_DP<13>")
	)
	(segment
		(start 313.8678 -320.693288)
		(end 311.993026 -322.567808)
		(width 0.14732)
		(layer "In13.Cu")
		(net "P5E_CPU0_PE0_RX_DP<13>")
	)
	(segment
		(start 311.602882 -393.246864)
		(end 312.207148 -397.797528)
		(width 0.14732)
		(layer "In13.Cu")
		(net "P5E_CPU0_PE0_RX_DP<13>")
	)
	(segment
		(start 318.427862 -280.88336)
		(end 320.221102 -308.663086)
		(width 0.14732)
		(layer "In13.Cu")
		(net "P5E_CPU0_PE0_RX_DP<13>")
	)
	(segment
		(start 310.719724 -386.598922)
		(end 310.777128 -387.031992)
		(width 0.14732)
		(layer "In13.Cu")
		(net "P5E_CPU0_PE0_RX_DP<13>")
	)
	(segment
		(start 313.553348 -406.02789)
		(end 313.553348 -410.442156)
		(width 0.14732)
		(layer "In13.Cu")
		(net "P5E_CPU0_PE0_RX_DP<13>")
	)
	(segment
		(start 310.777128 -387.031992)
		(end 310.914288 -387.13664)
		(width 0.14732)
		(layer "In13.Cu")
		(net "P5E_CPU0_PE0_RX_DP<13>")
	)
	(segment
		(start 310.924194 -388.13994)
		(end 311.061354 -388.244588)
		(width 0.14732)
		(layer "In13.Cu")
		(net "P5E_CPU0_PE0_RX_DP<13>")
	)
	(segment
		(start 348.207584 -213.33968)
		(end 348.165674 -213.29777)
		(width 0.0889)
		(layer "In13.Cu")
		(net "P5E_CPU0_PE0_RX_DP<13>")
	)
	(segment
		(start 311.650126 -392.676634)
		(end 311.70753 -393.109958)
		(width 0.14732)
		(layer "In13.Cu")
		(net "P5E_CPU0_PE0_RX_DP<13>")
	)
	(segment
		(start 349.399098 -220.862906)
		(end 349.374968 -220.773752)
		(width 0.0889)
		(layer "In13.Cu")
		(net "P5E_CPU0_PE0_RX_DP<13>")
	)
	(segment
		(start 348.207584 -213.930484)
		(end 348.207584 -213.33968)
		(width 0.0889)
		(layer "In13.Cu")
		(net "P5E_CPU0_PE0_RX_DP<13>")
	)
	(segment
		(start 311.20842 -389.352536)
		(end 311.266078 -389.78586)
		(width 0.14732)
		(layer "In13.Cu")
		(net "P5E_CPU0_PE0_RX_DP<13>")
	)
	(segment
		(start 311.21858 -390.355836)
		(end 311.35574 -390.460484)
		(width 0.14732)
		(layer "In13.Cu")
		(net "P5E_CPU0_PE0_RX_DP<13>")
	)
	(segment
		(start 338.203032 -202.573128)
		(end 336.363056 -202.573128)
		(width 0.14732)
		(layer "In13.Cu")
		(net "P5E_CPU0_PE0_RX_DP<13>")
	)
	(segment
		(start 304.725832 -341.41156)
		(end 304.724816 -341.466678)
		(width 0.14732)
		(layer "In13.Cu")
		(net "P5E_CPU0_PE0_RX_DP<13>")
	)
	(segment
		(start 348.677484 -216.260426)
		(end 348.677484 -216.25052)
		(width 0.0889)
		(layer "In13.Cu")
		(net "P5E_CPU0_PE0_RX_DP<13>")
	)
	(segment
		(start 310.630062 -385.924044)
		(end 310.629808 -385.924044)
		(width 0.14732)
		(layer "In13.Cu")
		(net "P5E_CPU0_PE0_RX_DP<13>")
	)
	(segment
		(start 309.852314 -322.034408)
		(end 306.35194 -325.534782)
		(width 0.14732)
		(layer "In13.Cu")
		(net "P5E_CPU0_PE0_RX_DP<13>")
	)
	(segment
		(start 336.363056 -202.573128)
		(end 334.98663 -203.14285)
		(width 0.14732)
		(layer "In13.Cu")
		(net "P5E_CPU0_PE0_RX_DP<13>")
	)
	(segment
		(start 311.35574 -390.460484)
		(end 311.413398 -390.893808)
		(width 0.14732)
		(layer "In13.Cu")
		(net "P5E_CPU0_PE0_RX_DP<13>")
	)
	(segment
		(start 314.687966 -413.093408)
		(end 314.812172 -413.512508)
		(width 0.14732)
		(layer "In13.Cu")
		(net "P5E_CPU0_PE0_RX_DP<13>")
	)
	(segment
		(start 344.443304 -206.954374)
		(end 338.203032 -202.573128)
		(width 0.14732)
		(layer "In13.Cu")
		(net "P5E_CPU0_PE0_RX_DP<13>")
	)
	(segment
		(start 311.01411 -388.814818)
		(end 311.071514 -389.247888)
		(width 0.14732)
		(layer "In13.Cu")
		(net "P5E_CPU0_PE0_RX_DP<13>")
	)
	(segment
		(start 311.3659 -391.463784)
		(end 311.365646 -391.463784)
		(width 0.14732)
		(layer "In13.Cu")
		(net "P5E_CPU0_PE0_RX_DP<13>")
	)
	(segment
		(start 316.709552 -251.091954)
		(end 316.639448 -253.178564)
		(width 0.14732)
		(layer "In13.Cu")
		(net "P5E_CPU0_PE0_RX_DP<13>")
	)
	(segment
		(start 345.472258 -207.677004)
		(end 345.00058 -207.345788)
		(width 0.14732)
		(layer "In13.Cu")
		(net "P5E_CPU0_PE0_RX_DP<13>")
	)
	(segment
		(start 349.14713 -220.334078)
		(end 349.14713 -220.311218)
		(width 0.0889)
		(layer "In13.Cu")
		(net "P5E_CPU0_PE0_RX_DP<13>")
	)
	(segment
		(start 311.455562 -392.138662)
		(end 311.512966 -392.571732)
		(width 0.14732)
		(layer "In13.Cu")
		(net "P5E_CPU0_PE0_RX_DP<13>")
	)
	(segment
		(start 312.207148 -397.797528)
		(end 312.207148 -404.68169)
		(width 0.14732)
		(layer "In13.Cu")
		(net "P5E_CPU0_PE0_RX_DP<13>")
	)
	(segment
		(start 311.365646 -391.463784)
		(end 311.502806 -391.568432)
		(width 0.14732)
		(layer "In13.Cu")
		(net "P5E_CPU0_PE0_RX_DP<13>")
	)
	(segment
		(start 348.489524 -214.946992)
		(end 348.498414 -214.941912)
		(width 0.0889)
		(layer "In13.Cu")
		(net "P5E_CPU0_PE0_RX_DP<13>")
	)
	(segment
		(start 311.512966 -392.571732)
		(end 311.650126 -392.676634)
		(width 0.14732)
		(layer "In13.Cu")
		(net "P5E_CPU0_PE0_RX_DP<13>")
	)
	(segment
		(start 317.966852 -424.59021)
		(end 317.966852 -437.19496)
		(width 0.14732)
		(layer "In13.Cu")
		(net "P5E_CPU0_PE0_RX_DP<13>")
	)
	(segment
		(start 311.70753 -393.109958)
		(end 311.602882 -393.246864)
		(width 0.14732)
		(layer "In13.Cu")
		(net "P5E_CPU0_PE0_RX_DP<13>")
	)
	(segment
		(start 348.165674 -213.29777)
		(end 348.165674 -213.275672)
		(width 0.0889)
		(layer "In13.Cu")
		(net "P5E_CPU0_PE0_RX_DP<13>")
	)
	(segment
		(start 311.502806 -391.568432)
		(end 311.560464 -392.001756)
		(width 0.14732)
		(layer "In13.Cu")
		(net "P5E_CPU0_PE0_RX_DP<13>")
	)
	(segment
		(start 316.639448 -253.178564)
		(end 318.427608 -280.88209)
		(width 0.14732)
		(layer "In13.Cu")
		(net "P5E_CPU0_PE0_RX_DP<13>")
	)
	(segment
		(start 312.207148 -404.68169)
		(end 313.553348 -406.02789)
		(width 0.14732)
		(layer "In13.Cu")
		(net "P5E_CPU0_PE0_RX_DP<13>")
	)
	(segment
		(start 334.98663 -203.14285)
		(end 333.984346 -204.14488)
		(width 0.14732)
		(layer "In13.Cu")
		(net "P5E_CPU0_PE0_RX_DP<13>")
	)
	(segment
		(start 314.533026 -413.009588)
		(end 314.687966 -413.093408)
		(width 0.14732)
		(layer "In13.Cu")
		(net "P5E_CPU0_PE0_RX_DP<13>")
	)
	(segment
		(start 345.00058 -207.345788)
		(end 344.830654 -207.375506)
		(width 0.14732)
		(layer "In13.Cu")
		(net "P5E_CPU0_PE0_RX_DP<13>")
	)
	(segment
		(start 344.830654 -207.375506)
		(end 344.473022 -207.1243)
		(width 0.14732)
		(layer "In13.Cu")
		(net "P5E_CPU0_PE0_RX_DP<13>")
	)
	(segment
		(start 348.676976 -214.622634)
		(end 348.676976 -214.461344)
		(width 0.0889)
		(layer "In13.Cu")
		(net "P5E_CPU0_PE0_RX_DP<13>")
	)
	(segment
		(start 315.42609 -415.52876)
		(end 315.530738 -415.882074)
		(width 0.14732)
		(layer "In13.Cu")
		(net "P5E_CPU0_PE0_RX_DP<13>")
	)
	(segment
		(start 306.35194 -325.534782)
		(end 306.35194 -328.271378)
		(width 0.14732)
		(layer "In13.Cu")
		(net "P5E_CPU0_PE0_RX_DP<13>")
	)
	(segment
		(start 348.165674 -210.37042)
		(end 345.472258 -207.677004)
		(width 0.14732)
		(layer "In13.Cu")
		(net "P5E_CPU0_PE0_RX_DP<13>")
	)
	(segment
		(start 348.677484 -217.8939)
		(end 348.677484 -217.859864)
		(width 0.0889)
		(layer "In13.Cu")
		(net "P5E_CPU0_PE0_RX_DP<13>")
	)
	(segment
		(start 348.498922 -215.931242)
		(end 348.483936 -215.922606)
		(width 0.0889)
		(layer "In13.Cu")
		(net "P5E_CPU0_PE0_RX_DP<13>")
	)
	(segment
		(start 333.984346 -204.14488)
		(end 331.603096 -206.099156)
		(width 0.14732)
		(layer "In13.Cu")
		(net "P5E_CPU0_PE0_RX_DP<13>")
	)
	(segment
		(start 311.07126 -389.247888)
		(end 311.20842 -389.352536)
		(width 0.14732)
		(layer "In13.Cu")
		(net "P5E_CPU0_PE0_RX_DP<13>")
	)
	(segment
		(start 320.221102 -308.663086)
		(end 317.286386 -315.816742)
		(width 0.14732)
		(layer "In13.Cu")
		(net "P5E_CPU0_PE0_RX_DP<13>")
	)
	(segment
		(start 311.993026 -322.567808)
		(end 310.901842 -322.567808)
		(width 0.14732)
		(layer "In13.Cu")
		(net "P5E_CPU0_PE0_RX_DP<13>")
	)
	(segment
		(start 344.473022 -207.1243)
		(end 344.443304 -206.954374)
		(width 0.14732)
		(layer "In13.Cu")
		(net "P5E_CPU0_PE0_RX_DP<13>")
	)
	(segment
		(start 310.824626 -386.462016)
		(end 310.719724 -386.598922)
		(width 0.14732)
		(layer "In13.Cu")
		(net "P5E_CPU0_PE0_RX_DP<13>")
	)
	(segment
		(start 315.530738 -415.882074)
		(end 315.436504 -416.05581)
		(width 0.14732)
		(layer "In13.Cu")
		(net "P5E_CPU0_PE0_RX_DP<13>")
	)
	(arc
		(start 348.959678 -218.367864)
		(mid 348.756855 -218.167633)
		(end 348.677484 -217.8939)
		(width 0.0889)
		(layer "In13.Cu")
		(net "P5E_CPU0_PE0_RX_DP<13>")
	)
	(arc
		(start 348.676976 -214.461344)
		(mid 348.601971 -214.345885)
		(end 348.492826 -214.261954)
		(width 0.0889)
		(layer "In13.Cu")
		(net "P5E_CPU0_PE0_RX_DP<13>")
	)
	(arc
		(start 348.492826 -214.261954)
		(mid 348.332754 -214.138774)
		(end 348.222824 -213.969346)
		(width 0.0889)
		(layer "In13.Cu")
		(net "P5E_CPU0_PE0_RX_DP<13>")
	)
	(arc
		(start 348.676722 -214.637366)
		(mid 348.676919 -214.630001)
		(end 348.676976 -214.622634)
		(width 0.0889)
		(layer "In13.Cu")
		(net "P5E_CPU0_PE0_RX_DP<13>")
	)
	(arc
		(start 348.483936 -215.922606)
		(mid 348.207028 -215.433205)
		(end 348.489524 -214.946992)
		(width 0.0889)
		(layer "In13.Cu")
		(net "P5E_CPU0_PE0_RX_DP<13>")
	)
	(arc
		(start 348.222824 -213.969346)
		(mid 348.214861 -213.950049)
		(end 348.207584 -213.930484)
		(width 0.0889)
		(layer "In13.Cu")
		(net "P5E_CPU0_PE0_RX_DP<13>")
	)
	(arc
		(start 349.374968 -220.773752)
		(mid 349.366397 -220.767356)
		(end 349.35795 -220.760798)
		(width 0.0889)
		(layer "In13.Cu")
		(net "P5E_CPU0_PE0_RX_DP<13>")
	)
	(arc
		(start 348.498414 -214.941912)
		(mid 348.625668 -214.811946)
		(end 348.676722 -214.637366)
		(width 0.0889)
		(layer "In13.Cu")
		(net "P5E_CPU0_PE0_RX_DP<13>")
	)
	(arc
		(start 349.14713 -220.311218)
		(mid 349.09486 -220.128853)
		(end 348.959932 -219.995496)
		(width 0.0889)
		(layer "In13.Cu")
		(net "P5E_CPU0_PE0_RX_DP<13>")
	)
	(arc
		(start 348.968568 -219.0115)
		(mid 349.147044 -218.692222)
		(end 348.968568 -218.372944)
		(width 0.0889)
		(layer "In13.Cu")
		(net "P5E_CPU0_PE0_RX_DP<13>")
	)
	(arc
		(start 348.677484 -217.859864)
		(mid 348.757646 -217.587675)
		(end 348.959932 -217.388694)
		(width 0.0889)
		(layer "In13.Cu")
		(net "P5E_CPU0_PE0_RX_DP<13>")
	)
	(arc
		(start 348.677484 -216.25052)
		(mid 348.629805 -216.06762)
		(end 348.498922 -215.931242)
		(width 0.0889)
		(layer "In13.Cu")
		(net "P5E_CPU0_PE0_RX_DP<13>")
	)
	(arc
		(start 348.959932 -219.995496)
		(mid 348.6774 -219.506148)
		(end 348.959678 -219.01658)
		(width 0.0889)
		(layer "In13.Cu")
		(net "P5E_CPU0_PE0_RX_DP<13>")
	)
	(arc
		(start 348.959932 -217.388694)
		(mid 349.147235 -217.064336)
		(end 348.959932 -216.739978)
		(width 0.0889)
		(layer "In13.Cu")
		(net "P5E_CPU0_PE0_RX_DP<13>")
	)
	(arc
		(start 348.959932 -216.739978)
		(mid 348.755597 -216.537373)
		(end 348.677484 -216.260426)
		(width 0.0889)
		(layer "In13.Cu")
		(net "P5E_CPU0_PE0_RX_DP<13>")
	)
	(arc
		(start 349.35795 -220.760798)
		(mid 349.205463 -220.570702)
		(end 349.14713 -220.334078)
		(width 0.0889)
		(layer "In13.Cu")
		(net "P5E_CPU0_PE0_RX_DP<13>")
	)
	(segment
		(start 348.772734 -222.48368)
		(end 348.772734 -221.947994)
		(width 0.13208)
		(layer "F.Cu")
		(net "P5E_CPU0_PE0_RX_DP<12>")
	)
	(segment
		(start 348.772734 -221.947994)
		(end 348.77248 -221.94774)
		(width 0.13208)
		(layer "F.Cu")
		(net "P5E_CPU0_PE0_RX_DP<12>")
	)
	(segment
		(start 347.737684 -216.266014)
		(end 347.737684 -216.25052)
		(width 0.0889)
		(layer "In13.Cu")
		(net "P5E_CPU0_PE0_RX_DP<12>")
	)
	(segment
		(start 321.422014 -220.442028)
		(end 317.66002 -251.248164)
		(width 0.14732)
		(layer "In13.Cu")
		(net "P5E_CPU0_PE0_RX_DP<12>")
	)
	(segment
		(start 347.550232 -215.926162)
		(end 347.54947 -215.925654)
		(width 0.0889)
		(layer "In13.Cu")
		(net "P5E_CPU0_PE0_RX_DP<12>")
	)
	(segment
		(start 317.859664 -415.315908)
		(end 318.026034 -415.423096)
		(width 0.14732)
		(layer "In13.Cu")
		(net "P5E_CPU0_PE0_RX_DP<12>")
	)
	(segment
		(start 320.650108 -438.152286)
		(end 320.650108 -437.889904)
		(width 0.14732)
		(layer "In13.Cu")
		(net "P5E_CPU0_PE0_RX_DP<12>")
	)
	(segment
		(start 314.45835 -391.909046)
		(end 314.358782 -392.050016)
		(width 0.14732)
		(layer "In13.Cu")
		(net "P5E_CPU0_PE0_RX_DP<12>")
	)
	(segment
		(start 317.606934 -252.828298)
		(end 321.217036 -308.89067)
		(width 0.14732)
		(layer "In13.Cu")
		(net "P5E_CPU0_PE0_RX_DP<12>")
	)
	(segment
		(start 348.028768 -218.372944)
		(end 348.022926 -218.369388)
		(width 0.0889)
		(layer "In13.Cu")
		(net "P5E_CPU0_PE0_RX_DP<12>")
	)
	(segment
		(start 313.864752 -389.175752)
		(end 314.005722 -389.27532)
		(width 0.14732)
		(layer "In13.Cu")
		(net "P5E_CPU0_PE0_RX_DP<12>")
	)
	(segment
		(start 313.626754 -387.072124)
		(end 313.700922 -387.502908)
		(width 0.14732)
		(layer "In13.Cu")
		(net "P5E_CPU0_PE0_RX_DP<12>")
	)
	(segment
		(start 309.725568 -323.504052)
		(end 307.306472 -325.923148)
		(width 0.14732)
		(layer "In13.Cu")
		(net "P5E_CPU0_PE0_RX_DP<12>")
	)
	(segment
		(start 313.890406 -388.604506)
		(end 313.790838 -388.745222)
		(width 0.14732)
		(layer "In13.Cu")
		(net "P5E_CPU0_PE0_RX_DP<12>")
	)
	(segment
		(start 348.020894 -219.996004)
		(end 348.019878 -219.995496)
		(width 0.0889)
		(layer "In13.Cu")
		(net "P5E_CPU0_PE0_RX_DP<12>")
	)
	(segment
		(start 347.268038 -213.339934)
		(end 347.225874 -213.29777)
		(width 0.0889)
		(layer "In13.Cu")
		(net "P5E_CPU0_PE0_RX_DP<12>")
	)
	(segment
		(start 348.019878 -219.01658)
		(end 348.028768 -219.0115)
		(width 0.0889)
		(layer "In13.Cu")
		(net "P5E_CPU0_PE0_RX_DP<12>")
	)
	(segment
		(start 347.553026 -214.261954)
		(end 347.527626 -214.248492)
		(width 0.0889)
		(layer "In13.Cu")
		(net "P5E_CPU0_PE0_RX_DP<12>")
	)
	(segment
		(start 314.468256 -392.68654)
		(end 314.609226 -392.786108)
		(width 0.14732)
		(layer "In13.Cu")
		(net "P5E_CPU0_PE0_RX_DP<12>")
	)
	(segment
		(start 306.023518 -329.959462)
		(end 305.51374 -331.1525)
		(width 0.14732)
		(layer "In13.Cu")
		(net "P5E_CPU0_PE0_RX_DP<12>")
	)
	(segment
		(start 313.675268 -388.074154)
		(end 313.816238 -388.173722)
		(width 0.14732)
		(layer "In13.Cu")
		(net "P5E_CPU0_PE0_RX_DP<12>")
	)
	(segment
		(start 348.019878 -220.644212)
		(end 348.028768 -220.639132)
		(width 0.0889)
		(layer "In13.Cu")
		(net "P5E_CPU0_PE0_RX_DP<12>")
	)
	(segment
		(start 348.020894 -216.740486)
		(end 348.019878 -216.739978)
		(width 0.0889)
		(layer "In13.Cu")
		(net "P5E_CPU0_PE0_RX_DP<12>")
	)
	(segment
		(start 319.966848 -425.095924)
		(end 319.966848 -438.194958)
		(width 0.14732)
		(layer "In13.Cu")
		(net "P5E_CPU0_PE0_RX_DP<12>")
	)
	(segment
		(start 314.384436 -391.478262)
		(end 314.45835 -391.909046)
		(width 0.14732)
		(layer "In13.Cu")
		(net "P5E_CPU0_PE0_RX_DP<12>")
	)
	(segment
		(start 305.927506 -343.016332)
		(end 313.485784 -386.972556)
		(width 0.14732)
		(layer "In13.Cu")
		(net "P5E_CPU0_PE0_RX_DP<12>")
	)
	(segment
		(start 315.270388 -404.68169)
		(end 316.616588 -406.02789)
		(width 0.14732)
		(layer "In13.Cu")
		(net "P5E_CPU0_PE0_RX_DP<12>")
	)
	(segment
		(start 317.66002 -251.248164)
		(end 317.606934 -252.828298)
		(width 0.14732)
		(layer "In13.Cu")
		(net "P5E_CPU0_PE0_RX_DP<12>")
	)
	(segment
		(start 313.816238 -388.173722)
		(end 313.890406 -388.604506)
		(width 0.14732)
		(layer "In13.Cu")
		(net "P5E_CPU0_PE0_RX_DP<12>")
	)
	(segment
		(start 320.482976 -438.319418)
		(end 320.650108 -438.152286)
		(width 0.14732)
		(layer "In13.Cu")
		(net "P5E_CPU0_PE0_RX_DP<12>")
	)
	(segment
		(start 314.07989 -389.706104)
		(end 313.980322 -389.84682)
		(width 0.14732)
		(layer "In13.Cu")
		(net "P5E_CPU0_PE0_RX_DP<12>")
	)
	(segment
		(start 323.415914 -215.62822)
		(end 321.422014 -220.442028)
		(width 0.14732)
		(layer "In13.Cu")
		(net "P5E_CPU0_PE0_RX_DP<12>")
	)
	(segment
		(start 348.019878 -217.388694)
		(end 348.028768 -217.383614)
		(width 0.0889)
		(layer "In13.Cu")
		(net "P5E_CPU0_PE0_RX_DP<12>")
	)
	(segment
		(start 347.737684 -219.521532)
		(end 347.737684 -219.490544)
		(width 0.0889)
		(layer "In13.Cu")
		(net "P5E_CPU0_PE0_RX_DP<12>")
	)
	(segment
		(start 317.610236 -414.15843)
		(end 317.776606 -414.265618)
		(width 0.14732)
		(layer "In13.Cu")
		(net "P5E_CPU0_PE0_RX_DP<12>")
	)
	(segment
		(start 317.996316 -415.949384)
		(end 319.966848 -425.095924)
		(width 0.14732)
		(layer "In13.Cu")
		(net "P5E_CPU0_PE0_RX_DP<12>")
	)
	(segment
		(start 314.194698 -390.376918)
		(end 314.268866 -390.807702)
		(width 0.14732)
		(layer "In13.Cu")
		(net "P5E_CPU0_PE0_RX_DP<12>")
	)
	(segment
		(start 348.616016 -221.676722)
		(end 348.527116 -221.6531)
		(width 0.0889)
		(layer "In13.Cu")
		(net "P5E_CPU0_PE0_RX_DP<12>")
	)
	(segment
		(start 314.054236 -390.27735)
		(end 314.053728 -390.27735)
		(width 0.14732)
		(layer "In13.Cu")
		(net "P5E_CPU0_PE0_RX_DP<12>")
	)
	(segment
		(start 317.316612 -412.79572)
		(end 317.610236 -414.15843)
		(width 0.14732)
		(layer "In13.Cu")
		(net "P5E_CPU0_PE0_RX_DP<12>")
	)
	(segment
		(start 337.626706 -203.548488)
		(end 336.485992 -203.548488)
		(width 0.14732)
		(layer "In13.Cu")
		(net "P5E_CPU0_PE0_RX_DP<12>")
	)
	(segment
		(start 313.980322 -389.84682)
		(end 314.054236 -390.27735)
		(width 0.14732)
		(layer "In13.Cu")
		(net "P5E_CPU0_PE0_RX_DP<12>")
	)
	(segment
		(start 314.243212 -391.378948)
		(end 314.384436 -391.478262)
		(width 0.14732)
		(layer "In13.Cu")
		(net "P5E_CPU0_PE0_RX_DP<12>")
	)
	(segment
		(start 347.225874 -213.275672)
		(end 347.225874 -210.792568)
		(width 0.14732)
		(layer "In13.Cu")
		(net "P5E_CPU0_PE0_RX_DP<12>")
	)
	(segment
		(start 348.028768 -220.000576)
		(end 348.020894 -219.996004)
		(width 0.0889)
		(layer "In13.Cu")
		(net "P5E_CPU0_PE0_RX_DP<12>")
	)
	(segment
		(start 305.927252 -343.016332)
		(end 305.927506 -343.016332)
		(width 0.14732)
		(layer "In13.Cu")
		(net "P5E_CPU0_PE0_RX_DP<12>")
	)
	(segment
		(start 314.053728 -390.27735)
		(end 314.194698 -390.376918)
		(width 0.14732)
		(layer "In13.Cu")
		(net "P5E_CPU0_PE0_RX_DP<12>")
	)
	(segment
		(start 307.306472 -325.923148)
		(end 307.306472 -328.676508)
		(width 0.14732)
		(layer "In13.Cu")
		(net "P5E_CPU0_PE0_RX_DP<12>")
	)
	(segment
		(start 347.225874 -213.29777)
		(end 347.225874 -213.275672)
		(width 0.0889)
		(layer "In13.Cu")
		(net "P5E_CPU0_PE0_RX_DP<12>")
	)
	(segment
		(start 305.90998 -342.849708)
		(end 305.927252 -343.016332)
		(width 0.14732)
		(layer "In13.Cu")
		(net "P5E_CPU0_PE0_RX_DP<12>")
	)
	(segment
		(start 317.776606 -414.265618)
		(end 317.854076 -414.626044)
		(width 0.14732)
		(layer "In13.Cu")
		(net "P5E_CPU0_PE0_RX_DP<12>")
	)
	(segment
		(start 347.225874 -210.792568)
		(end 345.345512 -208.912206)
		(width 0.14732)
		(layer "In13.Cu")
		(net "P5E_CPU0_PE0_RX_DP<12>")
	)
	(segment
		(start 314.268866 -390.807702)
		(end 314.169298 -390.948418)
		(width 0.14732)
		(layer "In13.Cu")
		(net "P5E_CPU0_PE0_RX_DP<12>")
	)
	(segment
		(start 316.616588 -406.02789)
		(end 316.616588 -410.386022)
		(width 0.14732)
		(layer "In13.Cu")
		(net "P5E_CPU0_PE0_RX_DP<12>")
	)
	(segment
		(start 331.711046 -207.332834)
		(end 323.415914 -215.62822)
		(width 0.14732)
		(layer "In13.Cu")
		(net "P5E_CPU0_PE0_RX_DP<12>")
	)
	(segment
		(start 314.005722 -389.27532)
		(end 314.07989 -389.706104)
		(width 0.14732)
		(layer "In13.Cu")
		(net "P5E_CPU0_PE0_RX_DP<12>")
	)
	(segment
		(start 312.415174 -323.504052)
		(end 309.725568 -323.504052)
		(width 0.14732)
		(layer "In13.Cu")
		(net "P5E_CPU0_PE0_RX_DP<12>")
	)
	(segment
		(start 318.103504 -415.783268)
		(end 317.996316 -415.949384)
		(width 0.14732)
		(layer "In13.Cu")
		(net "P5E_CPU0_PE0_RX_DP<12>")
	)
	(segment
		(start 316.616588 -410.386022)
		(end 317.316612 -412.79572)
		(width 0.14732)
		(layer "In13.Cu")
		(net "P5E_CPU0_PE0_RX_DP<12>")
	)
	(segment
		(start 321.217036 -308.89067)
		(end 318.199008 -316.175136)
		(width 0.14732)
		(layer "In13.Cu")
		(net "P5E_CPU0_PE0_RX_DP<12>")
	)
	(segment
		(start 314.609226 -392.786108)
		(end 314.683394 -393.216892)
		(width 0.14732)
		(layer "In13.Cu")
		(net "P5E_CPU0_PE0_RX_DP<12>")
	)
	(segment
		(start 347.737684 -217.8939)
		(end 347.737684 -217.856308)
		(width 0.0889)
		(layer "In13.Cu")
		(net "P5E_CPU0_PE0_RX_DP<12>")
	)
	(segment
		(start 313.485784 -386.972556)
		(end 313.626754 -387.072124)
		(width 0.14732)
		(layer "In13.Cu")
		(net "P5E_CPU0_PE0_RX_DP<12>")
	)
	(segment
		(start 347.559122 -215.931242)
		(end 347.554804 -215.928702)
		(width 0.0889)
		(layer "In13.Cu")
		(net "P5E_CPU0_PE0_RX_DP<12>")
	)
	(segment
		(start 347.527626 -214.248492)
		(end 347.524832 -214.245444)
		(width 0.0889)
		(layer "In13.Cu")
		(net "P5E_CPU0_PE0_RX_DP<12>")
	)
	(segment
		(start 313.601354 -387.643624)
		(end 313.675268 -388.074154)
		(width 0.14732)
		(layer "In13.Cu")
		(net "P5E_CPU0_PE0_RX_DP<12>")
	)
	(segment
		(start 314.683394 -393.216892)
		(end 314.583826 -393.357608)
		(width 0.14732)
		(layer "In13.Cu")
		(net "P5E_CPU0_PE0_RX_DP<12>")
	)
	(segment
		(start 347.737176 -214.622634)
		(end 347.737176 -214.461344)
		(width 0.0889)
		(layer "In13.Cu")
		(net "P5E_CPU0_PE0_RX_DP<12>")
	)
	(segment
		(start 320.091308 -438.319418)
		(end 320.482976 -438.319418)
		(width 0.14732)
		(layer "In13.Cu")
		(net "P5E_CPU0_PE0_RX_DP<12>")
	)
	(segment
		(start 319.966848 -438.194958)
		(end 320.091308 -438.319418)
		(width 0.14732)
		(layer "In13.Cu")
		(net "P5E_CPU0_PE0_RX_DP<12>")
	)
	(segment
		(start 347.26753 -215.436704)
		(end 347.26753 -215.414606)
		(width 0.0889)
		(layer "In13.Cu")
		(net "P5E_CPU0_PE0_RX_DP<12>")
	)
	(segment
		(start 317.854076 -414.626044)
		(end 317.746888 -414.791906)
		(width 0.14732)
		(layer "In13.Cu")
		(net "P5E_CPU0_PE0_RX_DP<12>")
	)
	(segment
		(start 348.028768 -216.745058)
		(end 348.020894 -216.740486)
		(width 0.0889)
		(layer "In13.Cu")
		(net "P5E_CPU0_PE0_RX_DP<12>")
	)
	(segment
		(start 313.700922 -387.502908)
		(end 313.601354 -387.643624)
		(width 0.14732)
		(layer "In13.Cu")
		(net "P5E_CPU0_PE0_RX_DP<12>")
	)
	(segment
		(start 305.51374 -331.1525)
		(end 305.90998 -342.849708)
		(width 0.14732)
		(layer "In13.Cu")
		(net "P5E_CPU0_PE0_RX_DP<12>")
	)
	(segment
		(start 314.590684 -321.328796)
		(end 312.415174 -323.504052)
		(width 0.14732)
		(layer "In13.Cu")
		(net "P5E_CPU0_PE0_RX_DP<12>")
	)
	(segment
		(start 347.268038 -213.929468)
		(end 347.268038 -213.339934)
		(width 0.0889)
		(layer "In13.Cu")
		(net "P5E_CPU0_PE0_RX_DP<12>")
	)
	(segment
		(start 348.022926 -218.369388)
		(end 348.019878 -218.367864)
		(width 0.0889)
		(layer "In13.Cu")
		(net "P5E_CPU0_PE0_RX_DP<12>")
	)
	(segment
		(start 315.270388 -397.350742)
		(end 315.270388 -404.68169)
		(width 0.14732)
		(layer "In13.Cu")
		(net "P5E_CPU0_PE0_RX_DP<12>")
	)
	(segment
		(start 313.790838 -388.745222)
		(end 313.864752 -389.175752)
		(width 0.14732)
		(layer "In13.Cu")
		(net "P5E_CPU0_PE0_RX_DP<12>")
	)
	(segment
		(start 318.199008 -316.175136)
		(end 314.590684 -321.328796)
		(width 0.14732)
		(layer "In13.Cu")
		(net "P5E_CPU0_PE0_RX_DP<12>")
	)
	(segment
		(start 347.54947 -215.925654)
		(end 347.544136 -215.922606)
		(width 0.0889)
		(layer "In13.Cu")
		(net "P5E_CPU0_PE0_RX_DP<12>")
	)
	(segment
		(start 347.549724 -214.946992)
		(end 347.558614 -214.941912)
		(width 0.0889)
		(layer "In13.Cu")
		(net "P5E_CPU0_PE0_RX_DP<12>")
	)
	(segment
		(start 318.026034 -415.423096)
		(end 318.103504 -415.783268)
		(width 0.14732)
		(layer "In13.Cu")
		(net "P5E_CPU0_PE0_RX_DP<12>")
	)
	(segment
		(start 347.737684 -221.149418)
		(end 347.737684 -221.111826)
		(width 0.0889)
		(layer "In13.Cu")
		(net "P5E_CPU0_PE0_RX_DP<12>")
	)
	(segment
		(start 348.77248 -221.94774)
		(end 348.616016 -221.676722)
		(width 0.0889)
		(layer "In13.Cu")
		(net "P5E_CPU0_PE0_RX_DP<12>")
	)
	(segment
		(start 334.021176 -205.436978)
		(end 331.711046 -207.332834)
		(width 0.14732)
		(layer "In13.Cu")
		(net "P5E_CPU0_PE0_RX_DP<12>")
	)
	(segment
		(start 347.554804 -215.928702)
		(end 347.550232 -215.926162)
		(width 0.0889)
		(layer "In13.Cu")
		(net "P5E_CPU0_PE0_RX_DP<12>")
	)
	(segment
		(start 307.306472 -328.676508)
		(end 306.023518 -329.959462)
		(width 0.14732)
		(layer "In13.Cu")
		(net "P5E_CPU0_PE0_RX_DP<12>")
	)
	(segment
		(start 317.746888 -414.791906)
		(end 317.859664 -415.315908)
		(width 0.14732)
		(layer "In13.Cu")
		(net "P5E_CPU0_PE0_RX_DP<12>")
	)
	(segment
		(start 314.169298 -390.948418)
		(end 314.243212 -391.378948)
		(width 0.14732)
		(layer "In13.Cu")
		(net "P5E_CPU0_PE0_RX_DP<12>")
	)
	(segment
		(start 336.485992 -203.548488)
		(end 335.50225 -203.955904)
		(width 0.14732)
		(layer "In13.Cu")
		(net "P5E_CPU0_PE0_RX_DP<12>")
	)
	(segment
		(start 335.50225 -203.955904)
		(end 334.021176 -205.436978)
		(width 0.14732)
		(layer "In13.Cu")
		(net "P5E_CPU0_PE0_RX_DP<12>")
	)
	(segment
		(start 314.583826 -393.357608)
		(end 315.270388 -397.350742)
		(width 0.14732)
		(layer "In13.Cu")
		(net "P5E_CPU0_PE0_RX_DP<12>")
	)
	(segment
		(start 345.345512 -208.912206)
		(end 337.626706 -203.548488)
		(width 0.14732)
		(layer "In13.Cu")
		(net "P5E_CPU0_PE0_RX_DP<12>")
	)
	(segment
		(start 314.358782 -392.050016)
		(end 314.468256 -392.68654)
		(width 0.14732)
		(layer "In13.Cu")
		(net "P5E_CPU0_PE0_RX_DP<12>")
	)
	(arc
		(start 347.736922 -214.637366)
		(mid 347.737119 -214.630001)
		(end 347.737176 -214.622634)
		(width 0.0889)
		(layer "In13.Cu")
		(net "P5E_CPU0_PE0_RX_DP<12>")
	)
	(arc
		(start 347.737684 -216.25052)
		(mid 347.690005 -216.06762)
		(end 347.559122 -215.931242)
		(width 0.0889)
		(layer "In13.Cu")
		(net "P5E_CPU0_PE0_RX_DP<12>")
	)
	(arc
		(start 348.019878 -218.367864)
		(mid 347.817055 -218.167633)
		(end 347.737684 -217.8939)
		(width 0.0889)
		(layer "In13.Cu")
		(net "P5E_CPU0_PE0_RX_DP<12>")
	)
	(arc
		(start 348.507304 -221.661228)
		(mid 348.259293 -221.697693)
		(end 348.019878 -221.623382)
		(width 0.0889)
		(layer "In13.Cu")
		(net "P5E_CPU0_PE0_RX_DP<12>")
	)
	(arc
		(start 348.527116 -221.6531)
		(mid 348.517249 -221.657259)
		(end 348.507304 -221.661228)
		(width 0.0889)
		(layer "In13.Cu")
		(net "P5E_CPU0_PE0_RX_DP<12>")
	)
	(arc
		(start 348.028768 -217.383614)
		(mid 348.207365 -217.064336)
		(end 348.028768 -216.745058)
		(width 0.0889)
		(layer "In13.Cu")
		(net "P5E_CPU0_PE0_RX_DP<12>")
	)
	(arc
		(start 348.019878 -219.995496)
		(mid 347.817055 -219.795265)
		(end 347.737684 -219.521532)
		(width 0.0889)
		(layer "In13.Cu")
		(net "P5E_CPU0_PE0_RX_DP<12>")
	)
	(arc
		(start 348.019878 -221.623382)
		(mid 347.817055 -221.423151)
		(end 347.737684 -221.149418)
		(width 0.0889)
		(layer "In13.Cu")
		(net "P5E_CPU0_PE0_RX_DP<12>")
	)
	(arc
		(start 347.558614 -214.941912)
		(mid 347.685868 -214.811946)
		(end 347.736922 -214.637366)
		(width 0.0889)
		(layer "In13.Cu")
		(net "P5E_CPU0_PE0_RX_DP<12>")
	)
	(arc
		(start 347.524832 -214.245444)
		(mid 347.368704 -214.109987)
		(end 347.268038 -213.929468)
		(width 0.0889)
		(layer "In13.Cu")
		(net "P5E_CPU0_PE0_RX_DP<12>")
	)
	(arc
		(start 348.028768 -219.0115)
		(mid 348.207244 -218.692222)
		(end 348.028768 -218.372944)
		(width 0.0889)
		(layer "In13.Cu")
		(net "P5E_CPU0_PE0_RX_DP<12>")
	)
	(arc
		(start 347.544136 -215.922606)
		(mid 347.341549 -215.716255)
		(end 347.26753 -215.436704)
		(width 0.0889)
		(layer "In13.Cu")
		(net "P5E_CPU0_PE0_RX_DP<12>")
	)
	(arc
		(start 347.737684 -221.111826)
		(mid 347.818595 -220.841698)
		(end 348.019878 -220.644212)
		(width 0.0889)
		(layer "In13.Cu")
		(net "P5E_CPU0_PE0_RX_DP<12>")
	)
	(arc
		(start 347.737684 -217.856308)
		(mid 347.818595 -217.58618)
		(end 348.019878 -217.388694)
		(width 0.0889)
		(layer "In13.Cu")
		(net "P5E_CPU0_PE0_RX_DP<12>")
	)
	(arc
		(start 348.028768 -220.639132)
		(mid 348.207365 -220.319854)
		(end 348.028768 -220.000576)
		(width 0.0889)
		(layer "In13.Cu")
		(net "P5E_CPU0_PE0_RX_DP<12>")
	)
	(arc
		(start 347.737684 -219.490544)
		(mid 347.817054 -219.21681)
		(end 348.019878 -219.01658)
		(width 0.0889)
		(layer "In13.Cu")
		(net "P5E_CPU0_PE0_RX_DP<12>")
	)
	(arc
		(start 347.26753 -215.414606)
		(mid 347.348441 -215.144478)
		(end 347.549724 -214.946992)
		(width 0.0889)
		(layer "In13.Cu")
		(net "P5E_CPU0_PE0_RX_DP<12>")
	)
	(arc
		(start 348.019878 -216.739978)
		(mid 347.817055 -216.539747)
		(end 347.737684 -216.266014)
		(width 0.0889)
		(layer "In13.Cu")
		(net "P5E_CPU0_PE0_RX_DP<12>")
	)
	(arc
		(start 347.737176 -214.461344)
		(mid 347.662171 -214.345885)
		(end 347.553026 -214.261954)
		(width 0.0889)
		(layer "In13.Cu")
		(net "P5E_CPU0_PE0_RX_DP<12>")
	)
	(segment
		(start 347.832934 -220.855794)
		(end 347.832934 -220.320108)
		(width 0.13208)
		(layer "F.Cu")
		(net "P5E_CPU0_PE0_RX_DP<11>")
	)
	(segment
		(start 347.832934 -220.320108)
		(end 347.83268 -220.319854)
		(width 0.13208)
		(layer "F.Cu")
		(net "P5E_CPU0_PE0_RX_DP<11>")
	)
	(segment
		(start 321.977512 -437.59374)
		(end 321.692524 -437.308752)
		(width 0.14732)
		(layer "In13.Cu")
		(net "P5E_CPU0_PE0_RX_DP<11>")
	)
	(segment
		(start 313.47029 -324.24878)
		(end 318.616838 -316.89802)
		(width 0.14732)
		(layer "In13.Cu")
		(net "P5E_CPU0_PE0_RX_DP<11>")
	)
	(segment
		(start 329.419712 -210.676236)
		(end 331.72908 -209.719672)
		(width 0.14732)
		(layer "In13.Cu")
		(net "P5E_CPU0_PE0_RX_DP<11>")
	)
	(segment
		(start 318.059308 -404.795482)
		(end 318.059308 -398.556734)
		(width 0.14732)
		(layer "In13.Cu")
		(net "P5E_CPU0_PE0_RX_DP<11>")
	)
	(segment
		(start 346.704158 -215.7603)
		(end 346.705682 -215.761062)
		(width 0.0889)
		(layer "In13.Cu")
		(net "P5E_CPU0_PE0_RX_DP<11>")
	)
	(segment
		(start 346.696792 -215.755982)
		(end 346.704158 -215.7603)
		(width 0.0889)
		(layer "In13.Cu")
		(net "P5E_CPU0_PE0_RX_DP<11>")
	)
	(segment
		(start 321.692524 -425.872148)
		(end 319.67551 -411.430724)
		(width 0.14732)
		(layer "In13.Cu")
		(net "P5E_CPU0_PE0_RX_DP<11>")
	)
	(segment
		(start 342.68537 -208.592928)
		(end 345.035124 -209.566002)
		(width 0.14732)
		(layer "In13.Cu")
		(net "P5E_CPU0_PE0_RX_DP<11>")
	)
	(segment
		(start 306.243228 -331.6986)
		(end 306.614068 -330.45908)
		(width 0.14732)
		(layer "In13.Cu")
		(net "P5E_CPU0_PE0_RX_DP<11>")
	)
	(segment
		(start 331.72908 -209.719672)
		(end 338.026756 -208.592928)
		(width 0.14732)
		(layer "In13.Cu")
		(net "P5E_CPU0_PE0_RX_DP<11>")
	)
	(segment
		(start 319.405508 -406.141682)
		(end 318.059308 -404.795482)
		(width 0.14732)
		(layer "In13.Cu")
		(net "P5E_CPU0_PE0_RX_DP<11>")
	)
	(segment
		(start 309.560976 -324.597776)
		(end 312.741818 -324.597776)
		(width 0.14732)
		(layer "In13.Cu")
		(net "P5E_CPU0_PE0_RX_DP<11>")
	)
	(segment
		(start 347.17482 -219.182188)
		(end 347.166946 -219.18676)
		(width 0.0889)
		(layer "In13.Cu")
		(net "P5E_CPU0_PE0_RX_DP<11>")
	)
	(segment
		(start 306.614068 -330.45908)
		(end 308.007512 -329.065636)
		(width 0.14732)
		(layer "In13.Cu")
		(net "P5E_CPU0_PE0_RX_DP<11>")
	)
	(segment
		(start 307.545994 -348.171516)
		(end 306.623212 -342.891364)
		(width 0.14732)
		(layer "In13.Cu")
		(net "P5E_CPU0_PE0_RX_DP<11>")
	)
	(segment
		(start 318.059308 -398.556734)
		(end 307.545994 -348.171516)
		(width 0.14732)
		(layer "In13.Cu")
		(net "P5E_CPU0_PE0_RX_DP<11>")
	)
	(segment
		(start 322.650104 -438.089802)
		(end 322.650104 -437.741314)
		(width 0.14732)
		(layer "In13.Cu")
		(net "P5E_CPU0_PE0_RX_DP<11>")
	)
	(segment
		(start 347.676216 -220.590872)
		(end 347.83268 -220.319854)
		(width 0.0889)
		(layer "In13.Cu")
		(net "P5E_CPU0_PE0_RX_DP<11>")
	)
	(segment
		(start 346.705682 -215.112346)
		(end 346.704666 -215.112854)
		(width 0.0889)
		(layer "In13.Cu")
		(net "P5E_CPU0_PE0_RX_DP<11>")
	)
	(segment
		(start 319.405508 -410.534358)
		(end 319.405508 -406.141682)
		(width 0.14732)
		(layer "In13.Cu")
		(net "P5E_CPU0_PE0_RX_DP<11>")
	)
	(segment
		(start 321.887088 -309.014114)
		(end 318.276478 -252.607064)
		(width 0.14732)
		(layer "In13.Cu")
		(net "P5E_CPU0_PE0_RX_DP<11>")
	)
	(segment
		(start 319.67551 -411.430724)
		(end 319.405508 -410.534358)
		(width 0.14732)
		(layer "In13.Cu")
		(net "P5E_CPU0_PE0_RX_DP<11>")
	)
	(segment
		(start 322.50253 -437.59374)
		(end 321.977512 -437.59374)
		(width 0.14732)
		(layer "In13.Cu")
		(net "P5E_CPU0_PE0_RX_DP<11>")
	)
	(segment
		(start 318.276478 -252.607064)
		(end 318.319912 -251.318776)
		(width 0.14732)
		(layer "In13.Cu")
		(net "P5E_CPU0_PE0_RX_DP<11>")
	)
	(segment
		(start 312.741818 -324.597776)
		(end 313.390026 -324.329552)
		(width 0.14732)
		(layer "In13.Cu")
		(net "P5E_CPU0_PE0_RX_DP<11>")
	)
	(segment
		(start 347.166946 -219.825316)
		(end 347.175836 -219.830396)
		(width 0.0889)
		(layer "In13.Cu")
		(net "P5E_CPU0_PE0_RX_DP<11>")
	)
	(segment
		(start 345.035124 -209.566002)
		(end 346.560394 -211.091272)
		(width 0.14732)
		(layer "In13.Cu")
		(net "P5E_CPU0_PE0_RX_DP<11>")
	)
	(segment
		(start 346.987876 -214.424768)
		(end 346.987876 -214.644732)
		(width 0.0889)
		(layer "In13.Cu")
		(net "P5E_CPU0_PE0_RX_DP<11>")
	)
	(segment
		(start 346.560394 -213.248494)
		(end 346.560394 -213.270592)
		(width 0.0889)
		(layer "In13.Cu")
		(net "P5E_CPU0_PE0_RX_DP<11>")
	)
	(segment
		(start 346.560394 -211.091272)
		(end 346.560394 -213.248494)
		(width 0.14732)
		(layer "In13.Cu")
		(net "P5E_CPU0_PE0_RX_DP<11>")
	)
	(segment
		(start 306.623212 -342.891364)
		(end 306.243228 -331.6986)
		(width 0.14732)
		(layer "In13.Cu")
		(net "P5E_CPU0_PE0_RX_DP<11>")
	)
	(segment
		(start 322.08216 -220.5863)
		(end 323.901308 -216.19464)
		(width 0.14732)
		(layer "In13.Cu")
		(net "P5E_CPU0_PE0_RX_DP<11>")
	)
	(segment
		(start 347.45803 -218.676728)
		(end 347.45803 -218.707716)
		(width 0.0889)
		(layer "In13.Cu")
		(net "P5E_CPU0_PE0_RX_DP<11>")
	)
	(segment
		(start 318.319912 -251.318776)
		(end 322.08216 -220.5863)
		(width 0.14732)
		(layer "In13.Cu")
		(net "P5E_CPU0_PE0_RX_DP<11>")
	)
	(segment
		(start 321.692524 -437.308752)
		(end 321.692524 -425.872148)
		(width 0.14732)
		(layer "In13.Cu")
		(net "P5E_CPU0_PE0_RX_DP<11>")
	)
	(segment
		(start 347.166946 -216.569798)
		(end 347.175836 -216.574878)
		(width 0.0889)
		(layer "In13.Cu")
		(net "P5E_CPU0_PE0_RX_DP<11>")
	)
	(segment
		(start 346.705682 -215.761062)
		(end 346.708476 -215.762586)
		(width 0.0889)
		(layer "In13.Cu")
		(net "P5E_CPU0_PE0_RX_DP<11>")
	)
	(segment
		(start 322.650104 -437.741314)
		(end 322.50253 -437.59374)
		(width 0.14732)
		(layer "In13.Cu")
		(net "P5E_CPU0_PE0_RX_DP<11>")
	)
	(segment
		(start 347.166946 -218.197684)
		(end 347.175836 -218.202764)
		(width 0.0889)
		(layer "In13.Cu")
		(net "P5E_CPU0_PE0_RX_DP<11>")
	)
	(segment
		(start 323.901308 -216.19464)
		(end 329.419712 -210.676236)
		(width 0.14732)
		(layer "In13.Cu")
		(net "P5E_CPU0_PE0_RX_DP<11>")
	)
	(segment
		(start 347.458284 -217.05443)
		(end 347.458284 -217.082878)
		(width 0.0889)
		(layer "In13.Cu")
		(net "P5E_CPU0_PE0_RX_DP<11>")
	)
	(segment
		(start 347.598238 -220.6117)
		(end 347.676216 -220.590872)
		(width 0.0889)
		(layer "In13.Cu")
		(net "P5E_CPU0_PE0_RX_DP<11>")
	)
	(segment
		(start 347.175836 -217.554048)
		(end 347.166946 -217.559128)
		(width 0.0889)
		(layer "In13.Cu")
		(net "P5E_CPU0_PE0_RX_DP<11>")
	)
	(segment
		(start 318.616838 -316.89802)
		(end 321.887088 -309.014114)
		(width 0.14732)
		(layer "In13.Cu")
		(net "P5E_CPU0_PE0_RX_DP<11>")
	)
	(segment
		(start 338.026756 -208.592928)
		(end 342.68537 -208.592928)
		(width 0.14732)
		(layer "In13.Cu")
		(net "P5E_CPU0_PE0_RX_DP<11>")
	)
	(segment
		(start 346.704666 -215.112854)
		(end 346.696792 -215.117426)
		(width 0.0889)
		(layer "In13.Cu")
		(net "P5E_CPU0_PE0_RX_DP<11>")
	)
	(segment
		(start 313.390026 -324.329552)
		(end 313.47029 -324.24878)
		(width 0.14732)
		(layer "In13.Cu")
		(net "P5E_CPU0_PE0_RX_DP<11>")
	)
	(segment
		(start 346.518484 -213.312502)
		(end 346.518484 -213.893908)
		(width 0.0889)
		(layer "In13.Cu")
		(net "P5E_CPU0_PE0_RX_DP<11>")
	)
	(segment
		(start 308.007512 -326.15124)
		(end 309.560976 -324.597776)
		(width 0.14732)
		(layer "In13.Cu")
		(net "P5E_CPU0_PE0_RX_DP<11>")
	)
	(segment
		(start 347.458284 -220.309948)
		(end 347.458284 -220.32849)
		(width 0.0889)
		(layer "In13.Cu")
		(net "P5E_CPU0_PE0_RX_DP<11>")
	)
	(segment
		(start 308.007512 -329.065636)
		(end 308.007512 -326.15124)
		(width 0.14732)
		(layer "In13.Cu")
		(net "P5E_CPU0_PE0_RX_DP<11>")
	)
	(segment
		(start 347.175836 -219.18168)
		(end 347.17482 -219.182188)
		(width 0.0889)
		(layer "In13.Cu")
		(net "P5E_CPU0_PE0_RX_DP<11>")
	)
	(segment
		(start 346.560394 -213.270592)
		(end 346.518484 -213.312502)
		(width 0.0889)
		(layer "In13.Cu")
		(net "P5E_CPU0_PE0_RX_DP<11>")
	)
	(segment
		(start 346.708476 -215.762586)
		(end 346.711778 -215.764618)
		(width 0.0889)
		(layer "In13.Cu")
		(net "P5E_CPU0_PE0_RX_DP<11>")
	)
	(arc
		(start 347.175836 -216.574878)
		(mid 347.380171 -216.777483)
		(end 347.458284 -217.05443)
		(width 0.0889)
		(layer "In13.Cu")
		(net "P5E_CPU0_PE0_RX_DP<11>")
	)
	(arc
		(start 347.166946 -217.559128)
		(mid 347.039053 -217.69019)
		(end 346.988638 -217.866214)
		(width 0.0889)
		(layer "In13.Cu")
		(net "P5E_CPU0_PE0_RX_DP<11>")
	)
	(arc
		(start 346.518484 -213.893908)
		(mid 346.593489 -214.009367)
		(end 346.702634 -214.093298)
		(width 0.0889)
		(layer "In13.Cu")
		(net "P5E_CPU0_PE0_RX_DP<11>")
	)
	(arc
		(start 346.702634 -214.093298)
		(mid 346.876597 -214.232062)
		(end 346.987876 -214.424768)
		(width 0.0889)
		(layer "In13.Cu")
		(net "P5E_CPU0_PE0_RX_DP<11>")
	)
	(arc
		(start 346.711778 -215.764618)
		(mid 346.914365 -215.970969)
		(end 346.988384 -216.25052)
		(width 0.0889)
		(layer "In13.Cu")
		(net "P5E_CPU0_PE0_RX_DP<11>")
	)
	(arc
		(start 347.166946 -219.18676)
		(mid 347.038542 -219.318705)
		(end 346.988384 -219.495878)
		(width 0.0889)
		(layer "In13.Cu")
		(net "P5E_CPU0_PE0_RX_DP<11>")
	)
	(arc
		(start 346.988384 -219.512642)
		(mid 347.037637 -219.691842)
		(end 347.166946 -219.825316)
		(width 0.0889)
		(layer "In13.Cu")
		(net "P5E_CPU0_PE0_RX_DP<11>")
	)
	(arc
		(start 347.458284 -220.32849)
		(mid 347.496958 -220.485558)
		(end 347.598238 -220.6117)
		(width 0.0889)
		(layer "In13.Cu")
		(net "P5E_CPU0_PE0_RX_DP<11>")
	)
	(arc
		(start 346.988638 -217.866214)
		(mid 346.988471 -217.87739)
		(end 346.988638 -217.888566)
		(width 0.0889)
		(layer "In13.Cu")
		(net "P5E_CPU0_PE0_RX_DP<11>")
	)
	(arc
		(start 346.987876 -214.644732)
		(mid 346.906965 -214.91486)
		(end 346.705682 -215.112346)
		(width 0.0889)
		(layer "In13.Cu")
		(net "P5E_CPU0_PE0_RX_DP<11>")
	)
	(arc
		(start 346.988384 -216.25052)
		(mid 347.036063 -216.43342)
		(end 347.166946 -216.569798)
		(width 0.0889)
		(layer "In13.Cu")
		(net "P5E_CPU0_PE0_RX_DP<11>")
	)
	(arc
		(start 346.988638 -217.888566)
		(mid 347.038653 -218.065697)
		(end 347.166946 -218.197684)
		(width 0.0889)
		(layer "In13.Cu")
		(net "P5E_CPU0_PE0_RX_DP<11>")
	)
	(arc
		(start 347.45803 -218.707716)
		(mid 347.37866 -218.98145)
		(end 347.175836 -219.18168)
		(width 0.0889)
		(layer "In13.Cu")
		(net "P5E_CPU0_PE0_RX_DP<11>")
	)
	(arc
		(start 346.518484 -215.421972)
		(mid 346.518287 -215.429337)
		(end 346.51823 -215.436704)
		(width 0.0889)
		(layer "In13.Cu")
		(net "P5E_CPU0_PE0_RX_DP<11>")
	)
	(arc
		(start 346.988384 -219.495878)
		(mid 346.98829 -219.50426)
		(end 346.988384 -219.512642)
		(width 0.0889)
		(layer "In13.Cu")
		(net "P5E_CPU0_PE0_RX_DP<11>")
	)
	(arc
		(start 347.175836 -219.830396)
		(mid 347.380171 -220.033001)
		(end 347.458284 -220.309948)
		(width 0.0889)
		(layer "In13.Cu")
		(net "P5E_CPU0_PE0_RX_DP<11>")
	)
	(arc
		(start 346.696792 -215.117426)
		(mid 346.569538 -215.247392)
		(end 346.518484 -215.421972)
		(width 0.0889)
		(layer "In13.Cu")
		(net "P5E_CPU0_PE0_RX_DP<11>")
	)
	(arc
		(start 346.51823 -215.436704)
		(mid 346.565909 -215.619604)
		(end 346.696792 -215.755982)
		(width 0.0889)
		(layer "In13.Cu")
		(net "P5E_CPU0_PE0_RX_DP<11>")
	)
	(arc
		(start 347.175836 -218.202764)
		(mid 347.378659 -218.402995)
		(end 347.45803 -218.676728)
		(width 0.0889)
		(layer "In13.Cu")
		(net "P5E_CPU0_PE0_RX_DP<11>")
	)
	(arc
		(start 347.458284 -217.082878)
		(mid 347.378122 -217.355067)
		(end 347.175836 -217.554048)
		(width 0.0889)
		(layer "In13.Cu")
		(net "P5E_CPU0_PE0_RX_DP<11>")
	)
	(segment
		(start 346.893134 -222.48368)
		(end 346.893134 -221.947994)
		(width 0.13208)
		(layer "F.Cu")
		(net "P5E_CPU0_PE0_RX_DP<10>")
	)
	(segment
		(start 346.893134 -221.947994)
		(end 346.89288 -221.94774)
		(width 0.13208)
		(layer "F.Cu")
		(net "P5E_CPU0_PE0_RX_DP<10>")
	)
	(segment
		(start 324.482968 -438.319418)
		(end 324.6501 -438.152286)
		(width 0.14732)
		(layer "In13.Cu")
		(net "P5E_CPU0_PE0_RX_DP<10>")
	)
	(segment
		(start 321.538854 -313.28614)
		(end 321.539108 -313.28614)
		(width 0.14732)
		(layer "In13.Cu")
		(net "P5E_CPU0_PE0_RX_DP<10>")
	)
	(segment
		(start 319.96507 -392.829542)
		(end 320.069718 -393.253468)
		(width 0.14732)
		(layer "In13.Cu")
		(net "P5E_CPU0_PE0_RX_DP<10>")
	)
	(segment
		(start 324.875652 -216.995248)
		(end 323.28358 -220.839284)
		(width 0.14732)
		(layer "In13.Cu")
		(net "P5E_CPU0_PE0_RX_DP<10>")
	)
	(segment
		(start 346.141294 -216.740486)
		(end 346.140278 -216.739978)
		(width 0.0889)
		(layer "In13.Cu")
		(net "P5E_CPU0_PE0_RX_DP<10>")
	)
	(segment
		(start 345.858084 -221.149418)
		(end 345.858084 -221.111826)
		(width 0.0889)
		(layer "In13.Cu")
		(net "P5E_CPU0_PE0_RX_DP<10>")
	)
	(segment
		(start 346.149168 -216.745058)
		(end 346.141294 -216.740486)
		(width 0.0889)
		(layer "In13.Cu")
		(net "P5E_CPU0_PE0_RX_DP<10>")
	)
	(segment
		(start 345.670124 -214.946992)
		(end 345.672156 -214.945722)
		(width 0.0889)
		(layer "In13.Cu")
		(net "P5E_CPU0_PE0_RX_DP<10>")
	)
	(segment
		(start 346.149168 -220.000576)
		(end 346.141294 -219.996004)
		(width 0.0889)
		(layer "In13.Cu")
		(net "P5E_CPU0_PE0_RX_DP<10>")
	)
	(segment
		(start 330.117196 -211.753704)
		(end 324.875652 -216.995248)
		(width 0.14732)
		(layer "In13.Cu")
		(net "P5E_CPU0_PE0_RX_DP<10>")
	)
	(segment
		(start 320.056002 -392.678666)
		(end 319.96507 -392.829542)
		(width 0.14732)
		(layer "In13.Cu")
		(net "P5E_CPU0_PE0_RX_DP<10>")
	)
	(segment
		(start 345.674442 -214.944452)
		(end 345.679014 -214.941912)
		(width 0.0889)
		(layer "In13.Cu")
		(net "P5E_CPU0_PE0_RX_DP<10>")
	)
	(segment
		(start 346.736416 -221.676722)
		(end 346.647516 -221.6531)
		(width 0.0889)
		(layer "In13.Cu")
		(net "P5E_CPU0_PE0_RX_DP<10>")
	)
	(segment
		(start 345.857576 -214.622634)
		(end 345.857576 -214.461344)
		(width 0.0889)
		(layer "In13.Cu")
		(net "P5E_CPU0_PE0_RX_DP<10>")
	)
	(segment
		(start 318.440816 -386.137658)
		(end 318.349884 -386.288534)
		(width 0.14732)
		(layer "In13.Cu")
		(net "P5E_CPU0_PE0_RX_DP<10>")
	)
	(segment
		(start 346.140278 -217.388694)
		(end 346.149168 -217.383614)
		(width 0.0889)
		(layer "In13.Cu")
		(net "P5E_CPU0_PE0_RX_DP<10>")
	)
	(segment
		(start 323.28358 -220.839284)
		(end 319.526412 -251.530358)
		(width 0.14732)
		(layer "In13.Cu")
		(net "P5E_CPU0_PE0_RX_DP<10>")
	)
	(segment
		(start 321.396868 -404.68169)
		(end 322.743068 -406.02789)
		(width 0.14732)
		(layer "In13.Cu")
		(net "P5E_CPU0_PE0_RX_DP<10>")
	)
	(segment
		(start 309.953914 -325.936356)
		(end 309.227728 -326.662542)
		(width 0.14732)
		(layer "In13.Cu")
		(net "P5E_CPU0_PE0_RX_DP<10>")
	)
	(segment
		(start 318.723772 -387.802628)
		(end 318.874648 -387.893814)
		(width 0.14732)
		(layer "In13.Cu")
		(net "P5E_CPU0_PE0_RX_DP<10>")
	)
	(segment
		(start 323.966332 -424.628818)
		(end 323.966332 -438.19445)
		(width 0.14732)
		(layer "In13.Cu")
		(net "P5E_CPU0_PE0_RX_DP<10>")
	)
	(segment
		(start 320.325242 -393.769088)
		(end 320.23431 -393.91971)
		(width 0.14732)
		(layer "In13.Cu")
		(net "P5E_CPU0_PE0_RX_DP<10>")
	)
	(segment
		(start 318.993012 -388.89305)
		(end 319.143634 -388.983982)
		(width 0.14732)
		(layer "In13.Cu")
		(net "P5E_CPU0_PE0_RX_DP<10>")
	)
	(segment
		(start 319.682114 -391.164318)
		(end 319.786762 -391.588498)
		(width 0.14732)
		(layer "In13.Cu")
		(net "P5E_CPU0_PE0_RX_DP<10>")
	)
	(segment
		(start 318.080898 -385.19862)
		(end 318.185546 -385.622546)
		(width 0.14732)
		(layer "In13.Cu")
		(net "P5E_CPU0_PE0_RX_DP<10>")
	)
	(segment
		(start 345.388184 -213.312756)
		(end 345.34602 -213.270592)
		(width 0.0889)
		(layer "In13.Cu")
		(net "P5E_CPU0_PE0_RX_DP<10>")
	)
	(segment
		(start 346.140278 -220.644212)
		(end 346.149168 -220.639132)
		(width 0.0889)
		(layer "In13.Cu")
		(net "P5E_CPU0_PE0_RX_DP<10>")
	)
	(segment
		(start 318.979296 -388.317994)
		(end 318.888364 -388.46887)
		(width 0.14732)
		(layer "In13.Cu")
		(net "P5E_CPU0_PE0_RX_DP<10>")
	)
	(segment
		(start 319.93967 -317.125858)
		(end 314.428124 -324.99935)
		(width 0.14732)
		(layer "In13.Cu")
		(net "P5E_CPU0_PE0_RX_DP<10>")
	)
	(segment
		(start 345.858084 -219.521532)
		(end 345.858084 -219.490544)
		(width 0.0889)
		(layer "In13.Cu")
		(net "P5E_CPU0_PE0_RX_DP<10>")
	)
	(segment
		(start 345.672918 -214.945214)
		(end 345.674442 -214.944452)
		(width 0.0889)
		(layer "In13.Cu")
		(net "P5E_CPU0_PE0_RX_DP<10>")
	)
	(segment
		(start 318.454532 -386.71246)
		(end 318.605408 -386.803646)
		(width 0.14732)
		(layer "In13.Cu")
		(net "P5E_CPU0_PE0_RX_DP<10>")
	)
	(segment
		(start 318.336168 -385.713478)
		(end 318.440816 -386.137658)
		(width 0.14732)
		(layer "In13.Cu")
		(net "P5E_CPU0_PE0_RX_DP<10>")
	)
	(segment
		(start 319.143634 -388.983982)
		(end 319.248282 -389.408162)
		(width 0.14732)
		(layer "In13.Cu")
		(net "P5E_CPU0_PE0_RX_DP<10>")
	)
	(segment
		(start 313.983116 -325.444358)
		(end 312.795412 -325.936356)
		(width 0.14732)
		(layer "In13.Cu")
		(net "P5E_CPU0_PE0_RX_DP<10>")
	)
	(segment
		(start 346.141294 -219.996004)
		(end 346.140278 -219.995496)
		(width 0.0889)
		(layer "In13.Cu")
		(net "P5E_CPU0_PE0_RX_DP<10>")
	)
	(segment
		(start 318.170052 -385.051046)
		(end 318.080898 -385.19862)
		(width 0.14732)
		(layer "In13.Cu")
		(net "P5E_CPU0_PE0_RX_DP<10>")
	)
	(segment
		(start 323.151246 -309.414926)
		(end 321.538854 -313.28614)
		(width 0.14732)
		(layer "In13.Cu")
		(net "P5E_CPU0_PE0_RX_DP<10>")
	)
	(segment
		(start 338.190078 -209.921348)
		(end 331.951838 -210.993736)
		(width 0.14732)
		(layer "In13.Cu")
		(net "P5E_CPU0_PE0_RX_DP<10>")
	)
	(segment
		(start 314.428124 -324.99935)
		(end 313.983116 -325.444358)
		(width 0.14732)
		(layer "In13.Cu")
		(net "P5E_CPU0_PE0_RX_DP<10>")
	)
	(segment
		(start 319.531238 -391.073132)
		(end 319.682114 -391.164318)
		(width 0.14732)
		(layer "In13.Cu")
		(net "P5E_CPU0_PE0_RX_DP<10>")
	)
	(segment
		(start 319.786762 -391.588498)
		(end 319.69583 -391.739374)
		(width 0.14732)
		(layer "In13.Cu")
		(net "P5E_CPU0_PE0_RX_DP<10>")
	)
	(segment
		(start 323.648578 -423.36339)
		(end 323.966332 -424.628818)
		(width 0.14732)
		(layer "In13.Cu")
		(net "P5E_CPU0_PE0_RX_DP<10>")
	)
	(segment
		(start 319.42659 -390.649206)
		(end 319.531238 -391.073132)
		(width 0.14732)
		(layer "In13.Cu")
		(net "P5E_CPU0_PE0_RX_DP<10>")
	)
	(segment
		(start 322.743068 -410.399484)
		(end 323.648578 -423.36339)
		(width 0.14732)
		(layer "In13.Cu")
		(net "P5E_CPU0_PE0_RX_DP<10>")
	)
	(segment
		(start 323.966332 -438.19445)
		(end 324.0913 -438.319418)
		(width 0.14732)
		(layer "In13.Cu")
		(net "P5E_CPU0_PE0_RX_DP<10>")
	)
	(segment
		(start 319.526412 -251.530358)
		(end 319.513204 -251.925074)
		(width 0.14732)
		(layer "In13.Cu")
		(net "P5E_CPU0_PE0_RX_DP<10>")
	)
	(segment
		(start 318.605408 -386.803646)
		(end 318.710056 -387.227826)
		(width 0.14732)
		(layer "In13.Cu")
		(net "P5E_CPU0_PE0_RX_DP<10>")
	)
	(segment
		(start 345.34602 -213.270592)
		(end 345.34602 -213.248494)
		(width 0.0889)
		(layer "In13.Cu")
		(net "P5E_CPU0_PE0_RX_DP<10>")
	)
	(segment
		(start 312.795412 -325.936356)
		(end 309.953914 -325.936356)
		(width 0.14732)
		(layer "In13.Cu")
		(net "P5E_CPU0_PE0_RX_DP<10>")
	)
	(segment
		(start 309.227728 -326.662542)
		(end 309.227728 -329.652122)
		(width 0.14732)
		(layer "In13.Cu")
		(net "P5E_CPU0_PE0_RX_DP<10>")
	)
	(segment
		(start 319.412874 -390.07415)
		(end 319.517522 -390.49833)
		(width 0.14732)
		(layer "In13.Cu")
		(net "P5E_CPU0_PE0_RX_DP<10>")
	)
	(segment
		(start 318.888364 -388.46887)
		(end 318.993012 -388.89305)
		(width 0.14732)
		(layer "In13.Cu")
		(net "P5E_CPU0_PE0_RX_DP<10>")
	)
	(segment
		(start 345.34602 -213.248494)
		(end 345.34602 -211.785454)
		(width 0.14732)
		(layer "In13.Cu")
		(net "P5E_CPU0_PE0_RX_DP<10>")
	)
	(segment
		(start 320.23431 -393.91971)
		(end 321.396868 -398.629124)
		(width 0.14732)
		(layer "In13.Cu")
		(net "P5E_CPU0_PE0_RX_DP<10>")
	)
	(segment
		(start 319.513204 -251.925074)
		(end 323.151246 -309.414926)
		(width 0.14732)
		(layer "In13.Cu")
		(net "P5E_CPU0_PE0_RX_DP<10>")
	)
	(segment
		(start 318.874648 -387.893814)
		(end 318.979296 -388.317994)
		(width 0.14732)
		(layer "In13.Cu")
		(net "P5E_CPU0_PE0_RX_DP<10>")
	)
	(segment
		(start 319.261998 -389.982964)
		(end 319.412874 -390.07415)
		(width 0.14732)
		(layer "In13.Cu")
		(net "P5E_CPU0_PE0_RX_DP<10>")
	)
	(segment
		(start 309.227728 -329.652122)
		(end 307.80609 -331.07376)
		(width 0.14732)
		(layer "In13.Cu")
		(net "P5E_CPU0_PE0_RX_DP<10>")
	)
	(segment
		(start 345.34602 -211.785454)
		(end 344.091768 -210.531202)
		(width 0.14732)
		(layer "In13.Cu")
		(net "P5E_CPU0_PE0_RX_DP<10>")
	)
	(segment
		(start 319.15735 -389.559038)
		(end 319.261998 -389.982964)
		(width 0.14732)
		(layer "In13.Cu")
		(net "P5E_CPU0_PE0_RX_DP<10>")
	)
	(segment
		(start 345.858084 -216.266014)
		(end 345.858084 -216.25052)
		(width 0.0889)
		(layer "In13.Cu")
		(net "P5E_CPU0_PE0_RX_DP<10>")
	)
	(segment
		(start 308.451758 -346.198698)
		(end 317.917576 -384.537458)
		(width 0.14732)
		(layer "In13.Cu")
		(net "P5E_CPU0_PE0_RX_DP<10>")
	)
	(segment
		(start 324.6501 -438.152286)
		(end 324.6501 -437.889904)
		(width 0.14732)
		(layer "In13.Cu")
		(net "P5E_CPU0_PE0_RX_DP<10>")
	)
	(segment
		(start 318.619124 -387.378702)
		(end 318.723772 -387.802628)
		(width 0.14732)
		(layer "In13.Cu")
		(net "P5E_CPU0_PE0_RX_DP<10>")
	)
	(segment
		(start 345.388184 -213.930484)
		(end 345.388184 -213.312756)
		(width 0.0889)
		(layer "In13.Cu")
		(net "P5E_CPU0_PE0_RX_DP<10>")
	)
	(segment
		(start 346.89288 -221.94774)
		(end 346.736416 -221.676722)
		(width 0.0889)
		(layer "In13.Cu")
		(net "P5E_CPU0_PE0_RX_DP<10>")
	)
	(segment
		(start 318.065404 -384.626612)
		(end 318.170052 -385.051046)
		(width 0.14732)
		(layer "In13.Cu")
		(net "P5E_CPU0_PE0_RX_DP<10>")
	)
	(segment
		(start 318.349884 -386.288534)
		(end 318.454532 -386.71246)
		(width 0.14732)
		(layer "In13.Cu")
		(net "P5E_CPU0_PE0_RX_DP<10>")
	)
	(segment
		(start 319.248282 -389.408162)
		(end 319.15735 -389.559038)
		(width 0.14732)
		(layer "In13.Cu")
		(net "P5E_CPU0_PE0_RX_DP<10>")
	)
	(segment
		(start 307.826664 -342.612218)
		(end 308.451758 -346.198698)
		(width 0.14732)
		(layer "In13.Cu")
		(net "P5E_CPU0_PE0_RX_DP<10>")
	)
	(segment
		(start 317.917576 -384.537458)
		(end 318.065404 -384.626612)
		(width 0.14732)
		(layer "In13.Cu")
		(net "P5E_CPU0_PE0_RX_DP<10>")
	)
	(segment
		(start 321.539108 -313.28614)
		(end 319.93967 -317.125858)
		(width 0.14732)
		(layer "In13.Cu")
		(net "P5E_CPU0_PE0_RX_DP<10>")
	)
	(segment
		(start 346.141294 -218.368372)
		(end 346.140278 -218.367864)
		(width 0.0889)
		(layer "In13.Cu")
		(net "P5E_CPU0_PE0_RX_DP<10>")
	)
	(segment
		(start 319.517522 -390.49833)
		(end 319.42659 -390.649206)
		(width 0.14732)
		(layer "In13.Cu")
		(net "P5E_CPU0_PE0_RX_DP<10>")
	)
	(segment
		(start 322.743068 -406.02789)
		(end 322.743068 -410.399484)
		(width 0.14732)
		(layer "In13.Cu")
		(net "P5E_CPU0_PE0_RX_DP<10>")
	)
	(segment
		(start 345.679522 -215.931242)
		(end 345.664536 -215.922606)
		(width 0.0889)
		(layer "In13.Cu")
		(net "P5E_CPU0_PE0_RX_DP<10>")
	)
	(segment
		(start 318.710056 -387.227826)
		(end 318.619124 -387.378702)
		(width 0.14732)
		(layer "In13.Cu")
		(net "P5E_CPU0_PE0_RX_DP<10>")
	)
	(segment
		(start 320.220594 -393.344654)
		(end 320.325242 -393.769088)
		(width 0.14732)
		(layer "In13.Cu")
		(net "P5E_CPU0_PE0_RX_DP<10>")
	)
	(segment
		(start 346.149168 -218.372944)
		(end 346.141294 -218.368372)
		(width 0.0889)
		(layer "In13.Cu")
		(net "P5E_CPU0_PE0_RX_DP<10>")
	)
	(segment
		(start 320.069718 -393.253468)
		(end 320.220594 -393.344654)
		(width 0.14732)
		(layer "In13.Cu")
		(net "P5E_CPU0_PE0_RX_DP<10>")
	)
	(segment
		(start 331.951838 -210.993736)
		(end 330.117196 -211.753704)
		(width 0.14732)
		(layer "In13.Cu")
		(net "P5E_CPU0_PE0_RX_DP<10>")
	)
	(segment
		(start 318.185546 -385.622546)
		(end 318.336168 -385.713478)
		(width 0.14732)
		(layer "In13.Cu")
		(net "P5E_CPU0_PE0_RX_DP<10>")
	)
	(segment
		(start 319.951354 -392.254486)
		(end 320.056002 -392.678666)
		(width 0.14732)
		(layer "In13.Cu")
		(net "P5E_CPU0_PE0_RX_DP<10>")
	)
	(segment
		(start 307.80609 -331.07376)
		(end 307.578252 -331.783182)
		(width 0.14732)
		(layer "In13.Cu")
		(net "P5E_CPU0_PE0_RX_DP<10>")
	)
	(segment
		(start 319.69583 -391.739374)
		(end 319.800478 -392.1633)
		(width 0.14732)
		(layer "In13.Cu")
		(net "P5E_CPU0_PE0_RX_DP<10>")
	)
	(segment
		(start 321.396868 -398.629124)
		(end 321.396868 -404.68169)
		(width 0.14732)
		(layer "In13.Cu")
		(net "P5E_CPU0_PE0_RX_DP<10>")
	)
	(segment
		(start 324.0913 -438.319418)
		(end 324.482968 -438.319418)
		(width 0.14732)
		(layer "In13.Cu")
		(net "P5E_CPU0_PE0_RX_DP<10>")
	)
	(segment
		(start 342.61933 -209.921348)
		(end 338.190078 -209.921348)
		(width 0.14732)
		(layer "In13.Cu")
		(net "P5E_CPU0_PE0_RX_DP<10>")
	)
	(segment
		(start 345.858084 -217.8939)
		(end 345.858084 -217.856308)
		(width 0.0889)
		(layer "In13.Cu")
		(net "P5E_CPU0_PE0_RX_DP<10>")
	)
	(segment
		(start 307.578252 -331.783182)
		(end 307.826664 -342.612218)
		(width 0.14732)
		(layer "In13.Cu")
		(net "P5E_CPU0_PE0_RX_DP<10>")
	)
	(segment
		(start 319.800478 -392.1633)
		(end 319.951354 -392.254486)
		(width 0.14732)
		(layer "In13.Cu")
		(net "P5E_CPU0_PE0_RX_DP<10>")
	)
	(segment
		(start 345.672156 -214.945722)
		(end 345.672918 -214.945214)
		(width 0.0889)
		(layer "In13.Cu")
		(net "P5E_CPU0_PE0_RX_DP<10>")
	)
	(segment
		(start 346.140278 -219.01658)
		(end 346.149168 -219.0115)
		(width 0.0889)
		(layer "In13.Cu")
		(net "P5E_CPU0_PE0_RX_DP<10>")
	)
	(segment
		(start 344.091768 -210.531202)
		(end 342.61933 -209.921348)
		(width 0.14732)
		(layer "In13.Cu")
		(net "P5E_CPU0_PE0_RX_DP<10>")
	)
	(arc
		(start 346.149168 -219.0115)
		(mid 346.327644 -218.692222)
		(end 346.149168 -218.372944)
		(width 0.0889)
		(layer "In13.Cu")
		(net "P5E_CPU0_PE0_RX_DP<10>")
	)
	(arc
		(start 345.679014 -214.941912)
		(mid 345.809928 -214.805552)
		(end 345.857576 -214.622634)
		(width 0.0889)
		(layer "In13.Cu")
		(net "P5E_CPU0_PE0_RX_DP<10>")
	)
	(arc
		(start 346.627704 -221.661228)
		(mid 346.379693 -221.697693)
		(end 346.140278 -221.623382)
		(width 0.0889)
		(layer "In13.Cu")
		(net "P5E_CPU0_PE0_RX_DP<10>")
	)
	(arc
		(start 345.673426 -214.261954)
		(mid 345.513354 -214.138774)
		(end 345.403424 -213.969346)
		(width 0.0889)
		(layer "In13.Cu")
		(net "P5E_CPU0_PE0_RX_DP<10>")
	)
	(arc
		(start 345.858084 -216.25052)
		(mid 345.810405 -216.06762)
		(end 345.679522 -215.931242)
		(width 0.0889)
		(layer "In13.Cu")
		(net "P5E_CPU0_PE0_RX_DP<10>")
	)
	(arc
		(start 345.664536 -215.922606)
		(mid 345.387628 -215.433205)
		(end 345.670124 -214.946992)
		(width 0.0889)
		(layer "In13.Cu")
		(net "P5E_CPU0_PE0_RX_DP<10>")
	)
	(arc
		(start 346.647516 -221.6531)
		(mid 346.637649 -221.657259)
		(end 346.627704 -221.661228)
		(width 0.0889)
		(layer "In13.Cu")
		(net "P5E_CPU0_PE0_RX_DP<10>")
	)
	(arc
		(start 345.858084 -217.856308)
		(mid 345.938995 -217.58618)
		(end 346.140278 -217.388694)
		(width 0.0889)
		(layer "In13.Cu")
		(net "P5E_CPU0_PE0_RX_DP<10>")
	)
	(arc
		(start 346.149168 -220.639132)
		(mid 346.327765 -220.319854)
		(end 346.149168 -220.000576)
		(width 0.0889)
		(layer "In13.Cu")
		(net "P5E_CPU0_PE0_RX_DP<10>")
	)
	(arc
		(start 345.403424 -213.969346)
		(mid 345.395461 -213.950049)
		(end 345.388184 -213.930484)
		(width 0.0889)
		(layer "In13.Cu")
		(net "P5E_CPU0_PE0_RX_DP<10>")
	)
	(arc
		(start 345.858084 -221.111826)
		(mid 345.938995 -220.841698)
		(end 346.140278 -220.644212)
		(width 0.0889)
		(layer "In13.Cu")
		(net "P5E_CPU0_PE0_RX_DP<10>")
	)
	(arc
		(start 346.140278 -219.995496)
		(mid 345.937455 -219.795265)
		(end 345.858084 -219.521532)
		(width 0.0889)
		(layer "In13.Cu")
		(net "P5E_CPU0_PE0_RX_DP<10>")
	)
	(arc
		(start 345.858084 -219.490544)
		(mid 345.937454 -219.21681)
		(end 346.140278 -219.01658)
		(width 0.0889)
		(layer "In13.Cu")
		(net "P5E_CPU0_PE0_RX_DP<10>")
	)
	(arc
		(start 346.140278 -216.739978)
		(mid 345.937455 -216.539747)
		(end 345.858084 -216.266014)
		(width 0.0889)
		(layer "In13.Cu")
		(net "P5E_CPU0_PE0_RX_DP<10>")
	)
	(arc
		(start 346.149168 -217.383614)
		(mid 346.327765 -217.064336)
		(end 346.149168 -216.745058)
		(width 0.0889)
		(layer "In13.Cu")
		(net "P5E_CPU0_PE0_RX_DP<10>")
	)
	(arc
		(start 346.140278 -218.367864)
		(mid 345.937455 -218.167633)
		(end 345.858084 -217.8939)
		(width 0.0889)
		(layer "In13.Cu")
		(net "P5E_CPU0_PE0_RX_DP<10>")
	)
	(arc
		(start 346.140278 -221.623382)
		(mid 345.937455 -221.423151)
		(end 345.858084 -221.149418)
		(width 0.0889)
		(layer "In13.Cu")
		(net "P5E_CPU0_PE0_RX_DP<10>")
	)
	(arc
		(start 345.857576 -214.461344)
		(mid 345.782571 -214.345885)
		(end 345.673426 -214.261954)
		(width 0.0889)
		(layer "In13.Cu")
		(net "P5E_CPU0_PE0_RX_DP<10>")
	)
	(segment
		(start 337.495134 -222.48368)
		(end 337.495134 -221.947994)
		(width 0.13208)
		(layer "F.Cu")
		(net "P5E_CPU0_PE0_RX_DP<0>")
	)
	(segment
		(start 337.495134 -221.947994)
		(end 337.49488 -221.94774)
		(width 0.13208)
		(layer "F.Cu")
		(net "P5E_CPU0_PE0_RX_DP<0>")
	)
	(segment
		(start 333.273908 -254.350774)
		(end 333.454756 -255.375918)
		(width 0.14732)
		(layer "In13.Cu")
		(net "P5E_CPU0_PE0_RX_DP<0>")
	)
	(segment
		(start 332.356968 -256.96037)
		(end 331.100684 -260.166104)
		(width 0.14732)
		(layer "In13.Cu")
		(net "P5E_CPU0_PE0_RX_DP<0>")
	)
	(segment
		(start 332.880716 -311.154318)
		(end 328.222356 -322.211192)
		(width 0.14732)
		(layer "In13.Cu")
		(net "P5E_CPU0_PE0_RX_DP<0>")
	)
	(segment
		(start 333.540608 -228.426772)
		(end 333.436722 -228.607874)
		(width 0.14732)
		(layer "In13.Cu")
		(net "P5E_CPU0_PE0_RX_DP<0>")
	)
	(segment
		(start 348.079822 -419.479222)
		(end 347.887544 -419.793674)
		(width 0.14732)
		(layer "In13.Cu")
		(net "P5E_CPU0_PE0_RX_DP<0>")
	)
	(segment
		(start 336.180684 -223.56699)
		(end 336.180684 -223.585532)
		(width 0.0889)
		(layer "In13.Cu")
		(net "P5E_CPU0_PE0_RX_DP<0>")
	)
	(segment
		(start 317.352426 -335.449672)
		(end 317.352426 -340.736682)
		(width 0.14732)
		(layer "In13.Cu")
		(net "P5E_CPU0_PE0_RX_DP<0>")
	)
	(segment
		(start 346.52077 -422.026588)
		(end 346.328238 -422.072816)
		(width 0.14732)
		(layer "In13.Cu")
		(net "P5E_CPU0_PE0_RX_DP<0>")
	)
	(segment
		(start 331.63256 -233.234992)
		(end 331.74305 -242.283996)
		(width 0.14732)
		(layer "In13.Cu")
		(net "P5E_CPU0_PE0_RX_DP<0>")
	)
	(segment
		(start 335.710784 -224.389442)
		(end 335.710784 -224.399348)
		(width 0.0889)
		(layer "In13.Cu")
		(net "P5E_CPU0_PE0_RX_DP<0>")
	)
	(segment
		(start 336.838036 -222.437198)
		(end 336.829146 -222.442278)
		(width 0.0889)
		(layer "In13.Cu")
		(net "P5E_CPU0_PE0_RX_DP<0>")
	)
	(segment
		(start 345.091258 -438.319418)
		(end 345.482926 -438.319418)
		(width 0.14732)
		(layer "In13.Cu")
		(net "P5E_CPU0_PE0_RX_DP<0>")
	)
	(segment
		(start 328.222356 -322.211192)
		(end 322.690744 -330.111608)
		(width 0.14732)
		(layer "In13.Cu")
		(net "P5E_CPU0_PE0_RX_DP<0>")
	)
	(segment
		(start 347.266006 -420.808912)
		(end 347.073728 -421.12311)
		(width 0.14732)
		(layer "In13.Cu")
		(net "P5E_CPU0_PE0_RX_DP<0>")
	)
	(segment
		(start 346.507308 -391.05967)
		(end 346.46362 -391.230358)
		(width 0.14732)
		(layer "In13.Cu")
		(net "P5E_CPU0_PE0_RX_DP<0>")
	)
	(segment
		(start 333.436722 -228.607874)
		(end 333.02956 -229.616508)
		(width 0.14732)
		(layer "In13.Cu")
		(net "P5E_CPU0_PE0_RX_DP<0>")
	)
	(segment
		(start 353.375468 -406.605486)
		(end 353.375468 -410.561536)
		(width 0.14732)
		(layer "In13.Cu")
		(net "P5E_CPU0_PE0_RX_DP<0>")
	)
	(segment
		(start 333.6036 -228.232208)
		(end 333.535782 -228.350318)
		(width 0.0889)
		(layer "In13.Cu")
		(net "P5E_CPU0_PE0_RX_DP<0>")
	)
	(segment
		(start 334.494378 -226.50323)
		(end 334.488282 -226.506786)
		(width 0.0889)
		(layer "In13.Cu")
		(net "P5E_CPU0_PE0_RX_DP<0>")
	)
	(segment
		(start 322.690744 -330.111608)
		(end 317.352426 -335.449672)
		(width 0.14732)
		(layer "In13.Cu")
		(net "P5E_CPU0_PE0_RX_DP<0>")
	)
	(segment
		(start 346.284804 -390.683496)
		(end 346.507308 -391.05967)
		(width 0.14732)
		(layer "In13.Cu")
		(net "P5E_CPU0_PE0_RX_DP<0>")
	)
	(segment
		(start 333.273908 -252.7808)
		(end 333.273908 -254.350774)
		(width 0.14732)
		(layer "In13.Cu")
		(net "P5E_CPU0_PE0_RX_DP<0>")
	)
	(segment
		(start 333.718916 -248.911872)
		(end 334.046576 -249.703082)
		(width 0.14732)
		(layer "In13.Cu")
		(net "P5E_CPU0_PE0_RX_DP<0>")
	)
	(segment
		(start 331.74305 -242.283996)
		(end 333.718916 -248.47804)
		(width 0.14732)
		(layer "In13.Cu")
		(net "P5E_CPU0_PE0_RX_DP<0>")
	)
	(segment
		(start 347.219778 -420.616634)
		(end 347.266006 -420.808912)
		(width 0.14732)
		(layer "In13.Cu")
		(net "P5E_CPU0_PE0_RX_DP<0>")
	)
	(segment
		(start 346.328238 -422.072816)
		(end 344.966798 -424.29684)
		(width 0.14732)
		(layer "In13.Cu")
		(net "P5E_CPU0_PE0_RX_DP<0>")
	)
	(segment
		(start 346.713048 -421.712136)
		(end 346.52077 -422.026588)
		(width 0.14732)
		(layer "In13.Cu")
		(net "P5E_CPU0_PE0_RX_DP<0>")
	)
	(segment
		(start 348.49181 -418.539168)
		(end 348.033848 -419.287198)
		(width 0.14732)
		(layer "In13.Cu")
		(net "P5E_CPU0_PE0_RX_DP<0>")
	)
	(segment
		(start 334.770984 -226.008692)
		(end 334.770984 -226.017328)
		(width 0.0889)
		(layer "In13.Cu")
		(net "P5E_CPU0_PE0_RX_DP<0>")
	)
	(segment
		(start 347.887544 -419.793674)
		(end 347.695266 -419.839648)
		(width 0.14732)
		(layer "In13.Cu")
		(net "P5E_CPU0_PE0_RX_DP<0>")
	)
	(segment
		(start 317.352426 -340.736682)
		(end 317.922656 -342.965024)
		(width 0.14732)
		(layer "In13.Cu")
		(net "P5E_CPU0_PE0_RX_DP<0>")
	)
	(segment
		(start 349.229172 -417.572444)
		(end 349.05823 -417.613846)
		(width 0.14732)
		(layer "In13.Cu")
		(net "P5E_CPU0_PE0_RX_DP<0>")
	)
	(segment
		(start 333.377286 -252.197362)
		(end 333.273908 -252.7808)
		(width 0.14732)
		(layer "In13.Cu")
		(net "P5E_CPU0_PE0_RX_DP<0>")
	)
	(segment
		(start 334.046576 -249.703082)
		(end 334.046576 -250.839478)
		(width 0.14732)
		(layer "In13.Cu")
		(net "P5E_CPU0_PE0_RX_DP<0>")
	)
	(segment
		(start 352.090736 -400.145504)
		(end 353.375468 -406.605486)
		(width 0.14732)
		(layer "In13.Cu")
		(net "P5E_CPU0_PE0_RX_DP<0>")
	)
	(segment
		(start 333.55153 -228.407722)
		(end 333.540608 -228.426772)
		(width 0.0889)
		(layer "In13.Cu")
		(net "P5E_CPU0_PE0_RX_DP<0>")
	)
	(segment
		(start 345.650058 -438.152286)
		(end 345.650058 -437.889904)
		(width 0.14732)
		(layer "In13.Cu")
		(net "P5E_CPU0_PE0_RX_DP<0>")
	)
	(segment
		(start 346.11437 -390.639554)
		(end 346.284804 -390.683496)
		(width 0.14732)
		(layer "In13.Cu")
		(net "P5E_CPU0_PE0_RX_DP<0>")
	)
	(segment
		(start 317.922656 -342.965024)
		(end 346.11437 -390.639554)
		(width 0.14732)
		(layer "In13.Cu")
		(net "P5E_CPU0_PE0_RX_DP<0>")
	)
	(segment
		(start 333.535782 -228.350318)
		(end 333.55153 -228.407722)
		(width 0.0889)
		(layer "In13.Cu")
		(net "P5E_CPU0_PE0_RX_DP<0>")
	)
	(segment
		(start 337.338416 -221.676722)
		(end 337.260438 -221.655894)
		(width 0.0889)
		(layer "In13.Cu")
		(net "P5E_CPU0_PE0_RX_DP<0>")
	)
	(segment
		(start 347.695266 -419.839648)
		(end 347.219778 -420.616634)
		(width 0.14732)
		(layer "In13.Cu")
		(net "P5E_CPU0_PE0_RX_DP<0>")
	)
	(segment
		(start 344.966798 -424.29684)
		(end 344.966798 -438.194958)
		(width 0.14732)
		(layer "In13.Cu")
		(net "P5E_CPU0_PE0_RX_DP<0>")
	)
	(segment
		(start 348.876366 -418.178488)
		(end 348.684088 -418.49294)
		(width 0.14732)
		(layer "In13.Cu")
		(net "P5E_CPU0_PE0_RX_DP<0>")
	)
	(segment
		(start 346.46362 -391.230358)
		(end 350.75876 -398.493742)
		(width 0.14732)
		(layer "In13.Cu")
		(net "P5E_CPU0_PE0_RX_DP<0>")
	)
	(segment
		(start 333.02956 -229.616508)
		(end 331.81544 -232.209848)
		(width 0.14732)
		(layer "In13.Cu")
		(net "P5E_CPU0_PE0_RX_DP<0>")
	)
	(segment
		(start 336.650584 -222.761556)
		(end 336.650584 -222.77578)
		(width 0.0889)
		(layer "In13.Cu")
		(net "P5E_CPU0_PE0_RX_DP<0>")
	)
	(segment
		(start 335.898236 -224.065084)
		(end 335.889346 -224.070164)
		(width 0.0889)
		(layer "In13.Cu")
		(net "P5E_CPU0_PE0_RX_DP<0>")
	)
	(segment
		(start 348.033848 -419.287198)
		(end 348.079822 -419.479222)
		(width 0.14732)
		(layer "In13.Cu")
		(net "P5E_CPU0_PE0_RX_DP<0>")
	)
	(segment
		(start 333.952088 -251.37618)
		(end 333.377286 -252.197362)
		(width 0.14732)
		(layer "In13.Cu")
		(net "P5E_CPU0_PE0_RX_DP<0>")
	)
	(segment
		(start 348.684088 -418.49294)
		(end 348.49181 -418.539168)
		(width 0.14732)
		(layer "In13.Cu")
		(net "P5E_CPU0_PE0_RX_DP<0>")
	)
	(segment
		(start 337.120484 -221.939104)
		(end 337.120484 -221.957646)
		(width 0.0889)
		(layer "In13.Cu")
		(net "P5E_CPU0_PE0_RX_DP<0>")
	)
	(segment
		(start 334.018636 -227.320602)
		(end 334.009746 -227.325682)
		(width 0.0889)
		(layer "In13.Cu")
		(net "P5E_CPU0_PE0_RX_DP<0>")
	)
	(segment
		(start 333.718916 -248.47804)
		(end 333.718916 -248.911872)
		(width 0.14732)
		(layer "In13.Cu")
		(net "P5E_CPU0_PE0_RX_DP<0>")
	)
	(segment
		(start 345.482926 -438.319418)
		(end 345.650058 -438.152286)
		(width 0.14732)
		(layer "In13.Cu")
		(net "P5E_CPU0_PE0_RX_DP<0>")
	)
	(segment
		(start 349.457518 -417.199826)
		(end 349.229172 -417.572444)
		(width 0.14732)
		(layer "In13.Cu")
		(net "P5E_CPU0_PE0_RX_DP<0>")
	)
	(segment
		(start 346.88145 -421.169338)
		(end 346.66682 -421.520112)
		(width 0.14732)
		(layer "In13.Cu")
		(net "P5E_CPU0_PE0_RX_DP<0>")
	)
	(segment
		(start 333.454756 -255.375918)
		(end 333.110332 -256.207006)
		(width 0.14732)
		(layer "In13.Cu")
		(net "P5E_CPU0_PE0_RX_DP<0>")
	)
	(segment
		(start 344.966798 -438.194958)
		(end 345.091258 -438.319418)
		(width 0.14732)
		(layer "In13.Cu")
		(net "P5E_CPU0_PE0_RX_DP<0>")
	)
	(segment
		(start 349.41637 -417.02863)
		(end 349.457518 -417.199826)
		(width 0.14732)
		(layer "In13.Cu")
		(net "P5E_CPU0_PE0_RX_DP<0>")
	)
	(segment
		(start 335.240884 -225.203258)
		(end 335.240884 -225.217482)
		(width 0.0889)
		(layer "In13.Cu")
		(net "P5E_CPU0_PE0_RX_DP<0>")
	)
	(segment
		(start 331.81544 -232.209848)
		(end 331.63256 -233.234992)
		(width 0.14732)
		(layer "In13.Cu")
		(net "P5E_CPU0_PE0_RX_DP<0>")
	)
	(segment
		(start 350.75876 -398.493742)
		(end 352.090736 -400.145504)
		(width 0.14732)
		(layer "In13.Cu")
		(net "P5E_CPU0_PE0_RX_DP<0>")
	)
	(segment
		(start 334.046576 -250.839478)
		(end 333.952088 -251.37618)
		(width 0.14732)
		(layer "In13.Cu")
		(net "P5E_CPU0_PE0_RX_DP<0>")
	)
	(segment
		(start 333.110332 -256.207006)
		(end 332.356968 -256.96037)
		(width 0.14732)
		(layer "In13.Cu")
		(net "P5E_CPU0_PE0_RX_DP<0>")
	)
	(segment
		(start 331.100684 -260.166104)
		(end 330.083414 -266.662408)
		(width 0.14732)
		(layer "In13.Cu")
		(net "P5E_CPU0_PE0_RX_DP<0>")
	)
	(segment
		(start 347.073728 -421.12311)
		(end 346.88145 -421.169338)
		(width 0.14732)
		(layer "In13.Cu")
		(net "P5E_CPU0_PE0_RX_DP<0>")
	)
	(segment
		(start 353.375468 -410.561536)
		(end 349.41637 -417.02863)
		(width 0.14732)
		(layer "In13.Cu")
		(net "P5E_CPU0_PE0_RX_DP<0>")
	)
	(segment
		(start 330.083414 -266.662408)
		(end 332.880716 -311.154318)
		(width 0.14732)
		(layer "In13.Cu")
		(net "P5E_CPU0_PE0_RX_DP<0>")
	)
	(segment
		(start 346.66682 -421.520112)
		(end 346.713048 -421.712136)
		(width 0.14732)
		(layer "In13.Cu")
		(net "P5E_CPU0_PE0_RX_DP<0>")
	)
	(segment
		(start 333.831184 -227.835206)
		(end 333.6036 -228.232208)
		(width 0.0889)
		(layer "In13.Cu")
		(net "P5E_CPU0_PE0_RX_DP<0>")
	)
	(segment
		(start 333.831184 -227.64496)
		(end 333.831184 -227.835206)
		(width 0.0889)
		(layer "In13.Cu")
		(net "P5E_CPU0_PE0_RX_DP<0>")
	)
	(segment
		(start 348.830138 -417.98621)
		(end 348.876366 -418.178488)
		(width 0.14732)
		(layer "In13.Cu")
		(net "P5E_CPU0_PE0_RX_DP<0>")
	)
	(segment
		(start 334.301084 -226.822508)
		(end 334.301084 -226.84105)
		(width 0.0889)
		(layer "In13.Cu")
		(net "P5E_CPU0_PE0_RX_DP<0>")
	)
	(segment
		(start 335.428336 -224.8789)
		(end 335.419446 -224.88398)
		(width 0.0889)
		(layer "In13.Cu")
		(net "P5E_CPU0_PE0_RX_DP<0>")
	)
	(segment
		(start 349.05823 -417.613846)
		(end 348.830138 -417.98621)
		(width 0.14732)
		(layer "In13.Cu")
		(net "P5E_CPU0_PE0_RX_DP<0>")
	)
	(segment
		(start 337.49488 -221.94774)
		(end 337.338416 -221.676722)
		(width 0.0889)
		(layer "In13.Cu")
		(net "P5E_CPU0_PE0_RX_DP<0>")
	)
	(arc
		(start 336.180684 -223.585532)
		(mid 336.102573 -223.862481)
		(end 335.898236 -224.065084)
		(width 0.0889)
		(layer "In13.Cu")
		(net "P5E_CPU0_PE0_RX_DP<0>")
	)
	(arc
		(start 337.120484 -221.957646)
		(mid 337.042373 -222.234595)
		(end 336.838036 -222.437198)
		(width 0.0889)
		(layer "In13.Cu")
		(net "P5E_CPU0_PE0_RX_DP<0>")
	)
	(arc
		(start 334.488282 -226.506786)
		(mid 334.353349 -226.64014)
		(end 334.301084 -226.822508)
		(width 0.0889)
		(layer "In13.Cu")
		(net "P5E_CPU0_PE0_RX_DP<0>")
	)
	(arc
		(start 334.009746 -227.325682)
		(mid 333.878832 -227.462042)
		(end 333.831184 -227.64496)
		(width 0.0889)
		(layer "In13.Cu")
		(net "P5E_CPU0_PE0_RX_DP<0>")
	)
	(arc
		(start 336.367882 -223.251268)
		(mid 336.232949 -223.384622)
		(end 336.180684 -223.56699)
		(width 0.0889)
		(layer "In13.Cu")
		(net "P5E_CPU0_PE0_RX_DP<0>")
	)
	(arc
		(start 335.889346 -224.070164)
		(mid 335.758432 -224.206524)
		(end 335.710784 -224.389442)
		(width 0.0889)
		(layer "In13.Cu")
		(net "P5E_CPU0_PE0_RX_DP<0>")
	)
	(arc
		(start 335.419446 -224.88398)
		(mid 335.288532 -225.02034)
		(end 335.240884 -225.203258)
		(width 0.0889)
		(layer "In13.Cu")
		(net "P5E_CPU0_PE0_RX_DP<0>")
	)
	(arc
		(start 334.301084 -226.84105)
		(mid 334.222973 -227.117999)
		(end 334.018636 -227.320602)
		(width 0.0889)
		(layer "In13.Cu")
		(net "P5E_CPU0_PE0_RX_DP<0>")
	)
	(arc
		(start 336.650584 -222.77578)
		(mid 336.571365 -223.050465)
		(end 336.367882 -223.251268)
		(width 0.0889)
		(layer "In13.Cu")
		(net "P5E_CPU0_PE0_RX_DP<0>")
	)
	(arc
		(start 334.770984 -226.017328)
		(mid 334.696993 -226.296894)
		(end 334.494378 -226.50323)
		(width 0.0889)
		(layer "In13.Cu")
		(net "P5E_CPU0_PE0_RX_DP<0>")
	)
	(arc
		(start 336.829146 -222.442278)
		(mid 336.698232 -222.578638)
		(end 336.650584 -222.761556)
		(width 0.0889)
		(layer "In13.Cu")
		(net "P5E_CPU0_PE0_RX_DP<0>")
	)
	(arc
		(start 337.260438 -221.655894)
		(mid 337.159117 -221.782015)
		(end 337.120484 -221.939104)
		(width 0.0889)
		(layer "In13.Cu")
		(net "P5E_CPU0_PE0_RX_DP<0>")
	)
	(arc
		(start 334.958182 -225.69297)
		(mid 334.823249 -225.826324)
		(end 334.770984 -226.008692)
		(width 0.0889)
		(layer "In13.Cu")
		(net "P5E_CPU0_PE0_RX_DP<0>")
	)
	(arc
		(start 335.710784 -224.399348)
		(mid 335.632673 -224.676297)
		(end 335.428336 -224.8789)
		(width 0.0889)
		(layer "In13.Cu")
		(net "P5E_CPU0_PE0_RX_DP<0>")
	)
	(arc
		(start 335.240884 -225.217482)
		(mid 335.161665 -225.492167)
		(end 334.958182 -225.69297)
		(width 0.0889)
		(layer "In13.Cu")
		(net "P5E_CPU0_PE0_RX_DP<0>")
	)
	(segment
		(start 345.953334 -220.320108)
		(end 345.95308 -220.319854)
		(width 0.13208)
		(layer "F.Cu")
		(net "P5E_CPU0_PE0_RX_DN<9>")
	)
	(segment
		(start 345.953334 -220.855794)
		(end 345.953334 -220.320108)
		(width 0.13208)
		(layer "F.Cu")
		(net "P5E_CPU0_PE0_RX_DN<9>")
	)
	(segment
		(start 330.502514 -212.368384)
		(end 332.028546 -211.736178)
		(width 0.14732)
		(layer "In13.Cu")
		(net "P5E_CPU0_PE0_RX_DN<9>")
	)
	(segment
		(start 320.570352 -317.406782)
		(end 323.872606 -309.54091)
		(width 0.14732)
		(layer "In13.Cu")
		(net "P5E_CPU0_PE0_RX_DN<9>")
	)
	(segment
		(start 308.561994 -331.792326)
		(end 315.015626 -325.338694)
		(width 0.14732)
		(layer "In13.Cu")
		(net "P5E_CPU0_PE0_RX_DN<9>")
	)
	(segment
		(start 323.872606 -309.54091)
		(end 320.184018 -251.569728)
		(width 0.14732)
		(layer "In13.Cu")
		(net "P5E_CPU0_PE0_RX_DN<9>")
	)
	(segment
		(start 332.028546 -211.736178)
		(end 338.436458 -210.586828)
		(width 0.14732)
		(layer "In13.Cu")
		(net "P5E_CPU0_PE0_RX_DN<9>")
	)
	(segment
		(start 344.824558 -215.7603)
		(end 344.826082 -215.761062)
		(width 0.0889)
		(layer "In13.Cu")
		(net "P5E_CPU0_PE0_RX_DN<9>")
	)
	(segment
		(start 344.680794 -213.214966)
		(end 344.680794 -213.237064)
		(width 0.0889)
		(layer "In13.Cu")
		(net "P5E_CPU0_PE0_RX_DN<9>")
	)
	(segment
		(start 326.650096 -437.741314)
		(end 326.502522 -437.59374)
		(width 0.14732)
		(layer "In13.Cu")
		(net "P5E_CPU0_PE0_RX_DN<9>")
	)
	(segment
		(start 345.578684 -220.309948)
		(end 345.578684 -220.32849)
		(width 0.0889)
		(layer "In13.Cu")
		(net "P5E_CPU0_PE0_RX_DN<9>")
	)
	(segment
		(start 315.015626 -325.338694)
		(end 320.570352 -317.406782)
		(width 0.14732)
		(layer "In13.Cu")
		(net "P5E_CPU0_PE0_RX_DN<9>")
	)
	(segment
		(start 345.57843 -218.676728)
		(end 345.57843 -218.707716)
		(width 0.0889)
		(layer "In13.Cu")
		(net "P5E_CPU0_PE0_RX_DN<9>")
	)
	(segment
		(start 325.531988 -410.338524)
		(end 325.531988 -406.141682)
		(width 0.14732)
		(layer "In13.Cu")
		(net "P5E_CPU0_PE0_RX_DN<9>")
	)
	(segment
		(start 345.296236 -217.554048)
		(end 345.287346 -217.559128)
		(width 0.0889)
		(layer "In13.Cu")
		(net "P5E_CPU0_PE0_RX_DN<9>")
	)
	(segment
		(start 344.826082 -215.112346)
		(end 344.825066 -215.112854)
		(width 0.0889)
		(layer "In13.Cu")
		(net "P5E_CPU0_PE0_RX_DN<9>")
	)
	(segment
		(start 344.680794 -212.07222)
		(end 344.680794 -213.214966)
		(width 0.14732)
		(layer "In13.Cu")
		(net "P5E_CPU0_PE0_RX_DN<9>")
	)
	(segment
		(start 326.650096 -438.089802)
		(end 326.650096 -437.741314)
		(width 0.14732)
		(layer "In13.Cu")
		(net "P5E_CPU0_PE0_RX_DN<9>")
	)
	(segment
		(start 345.718638 -220.6117)
		(end 345.796616 -220.590872)
		(width 0.0889)
		(layer "In13.Cu")
		(net "P5E_CPU0_PE0_RX_DN<9>")
	)
	(segment
		(start 345.796616 -220.590872)
		(end 345.95308 -220.319854)
		(width 0.0889)
		(layer "In13.Cu")
		(net "P5E_CPU0_PE0_RX_DN<9>")
	)
	(segment
		(start 325.68388 -437.267096)
		(end 325.68388 -422.275762)
		(width 0.14732)
		(layer "In13.Cu")
		(net "P5E_CPU0_PE0_RX_DN<9>")
	)
	(segment
		(start 324.185788 -398.869408)
		(end 310.511952 -350.708468)
		(width 0.14732)
		(layer "In13.Cu")
		(net "P5E_CPU0_PE0_RX_DN<9>")
	)
	(segment
		(start 338.436458 -210.586828)
		(end 342.471502 -210.586828)
		(width 0.14732)
		(layer "In13.Cu")
		(net "P5E_CPU0_PE0_RX_DN<9>")
	)
	(segment
		(start 308.561994 -342.753696)
		(end 308.561994 -331.792326)
		(width 0.14732)
		(layer "In13.Cu")
		(net "P5E_CPU0_PE0_RX_DN<9>")
	)
	(segment
		(start 344.828876 -215.762586)
		(end 344.832178 -215.764618)
		(width 0.0889)
		(layer "In13.Cu")
		(net "P5E_CPU0_PE0_RX_DN<9>")
	)
	(segment
		(start 344.638884 -213.278974)
		(end 344.638884 -213.893908)
		(width 0.0889)
		(layer "In13.Cu")
		(net "P5E_CPU0_PE0_RX_DN<9>")
	)
	(segment
		(start 345.29522 -219.182188)
		(end 345.287346 -219.18676)
		(width 0.0889)
		(layer "In13.Cu")
		(net "P5E_CPU0_PE0_RX_DN<9>")
	)
	(segment
		(start 345.287346 -218.197684)
		(end 345.296236 -218.202764)
		(width 0.0889)
		(layer "In13.Cu")
		(net "P5E_CPU0_PE0_RX_DN<9>")
	)
	(segment
		(start 345.108276 -214.424768)
		(end 345.108276 -214.644732)
		(width 0.0889)
		(layer "In13.Cu")
		(net "P5E_CPU0_PE0_RX_DN<9>")
	)
	(segment
		(start 325.3994 -217.47226)
		(end 330.502514 -212.368384)
		(width 0.14732)
		(layer "In13.Cu")
		(net "P5E_CPU0_PE0_RX_DN<9>")
	)
	(segment
		(start 325.726298 -412.090108)
		(end 325.531988 -410.338524)
		(width 0.14732)
		(layer "In13.Cu")
		(net "P5E_CPU0_PE0_RX_DN<9>")
	)
	(segment
		(start 345.287346 -219.825316)
		(end 345.296236 -219.830396)
		(width 0.0889)
		(layer "In13.Cu")
		(net "P5E_CPU0_PE0_RX_DN<9>")
	)
	(segment
		(start 345.287346 -216.569798)
		(end 345.296236 -216.574878)
		(width 0.0889)
		(layer "In13.Cu")
		(net "P5E_CPU0_PE0_RX_DN<9>")
	)
	(segment
		(start 326.502522 -437.59374)
		(end 326.010524 -437.59374)
		(width 0.14732)
		(layer "In13.Cu")
		(net "P5E_CPU0_PE0_RX_DN<9>")
	)
	(segment
		(start 326.010524 -437.59374)
		(end 325.68388 -437.267096)
		(width 0.14732)
		(layer "In13.Cu")
		(net "P5E_CPU0_PE0_RX_DN<9>")
	)
	(segment
		(start 344.817192 -215.755982)
		(end 344.824558 -215.7603)
		(width 0.0889)
		(layer "In13.Cu")
		(net "P5E_CPU0_PE0_RX_DN<9>")
	)
	(segment
		(start 325.531988 -406.141682)
		(end 324.185788 -404.795482)
		(width 0.14732)
		(layer "In13.Cu")
		(net "P5E_CPU0_PE0_RX_DN<9>")
	)
	(segment
		(start 310.511952 -350.708468)
		(end 308.561994 -342.753696)
		(width 0.14732)
		(layer "In13.Cu")
		(net "P5E_CPU0_PE0_RX_DN<9>")
	)
	(segment
		(start 324.185788 -404.795482)
		(end 324.185788 -398.869408)
		(width 0.14732)
		(layer "In13.Cu")
		(net "P5E_CPU0_PE0_RX_DN<9>")
	)
	(segment
		(start 344.826082 -215.761062)
		(end 344.828876 -215.762586)
		(width 0.0889)
		(layer "In13.Cu")
		(net "P5E_CPU0_PE0_RX_DN<9>")
	)
	(segment
		(start 344.680794 -213.237064)
		(end 344.638884 -213.278974)
		(width 0.0889)
		(layer "In13.Cu")
		(net "P5E_CPU0_PE0_RX_DN<9>")
	)
	(segment
		(start 343.706958 -211.098384)
		(end 344.680794 -212.07222)
		(width 0.14732)
		(layer "In13.Cu")
		(net "P5E_CPU0_PE0_RX_DN<9>")
	)
	(segment
		(start 345.296236 -219.18168)
		(end 345.29522 -219.182188)
		(width 0.0889)
		(layer "In13.Cu")
		(net "P5E_CPU0_PE0_RX_DN<9>")
	)
	(segment
		(start 325.726298 -421.843708)
		(end 325.726298 -412.090108)
		(width 0.14732)
		(layer "In13.Cu")
		(net "P5E_CPU0_PE0_RX_DN<9>")
	)
	(segment
		(start 342.471502 -210.586828)
		(end 343.706958 -211.098384)
		(width 0.14732)
		(layer "In13.Cu")
		(net "P5E_CPU0_PE0_RX_DN<9>")
	)
	(segment
		(start 344.825066 -215.112854)
		(end 344.817192 -215.117426)
		(width 0.0889)
		(layer "In13.Cu")
		(net "P5E_CPU0_PE0_RX_DN<9>")
	)
	(segment
		(start 323.941186 -220.992192)
		(end 325.3994 -217.47226)
		(width 0.14732)
		(layer "In13.Cu")
		(net "P5E_CPU0_PE0_RX_DN<9>")
	)
	(segment
		(start 325.68388 -422.275762)
		(end 325.726298 -421.843708)
		(width 0.14732)
		(layer "In13.Cu")
		(net "P5E_CPU0_PE0_RX_DN<9>")
	)
	(segment
		(start 320.184018 -251.569728)
		(end 323.941186 -220.992192)
		(width 0.14732)
		(layer "In13.Cu")
		(net "P5E_CPU0_PE0_RX_DN<9>")
	)
	(arc
		(start 345.57843 -218.707716)
		(mid 345.49906 -218.98145)
		(end 345.296236 -219.18168)
		(width 0.0889)
		(layer "In13.Cu")
		(net "P5E_CPU0_PE0_RX_DN<9>")
	)
	(arc
		(start 344.832178 -215.764618)
		(mid 345.034765 -215.970969)
		(end 345.108784 -216.25052)
		(width 0.0889)
		(layer "In13.Cu")
		(net "P5E_CPU0_PE0_RX_DN<9>")
	)
	(arc
		(start 344.817192 -215.117426)
		(mid 344.638595 -215.436704)
		(end 344.817192 -215.755982)
		(width 0.0889)
		(layer "In13.Cu")
		(net "P5E_CPU0_PE0_RX_DN<9>")
	)
	(arc
		(start 345.578684 -220.32849)
		(mid 345.617358 -220.485558)
		(end 345.718638 -220.6117)
		(width 0.0889)
		(layer "In13.Cu")
		(net "P5E_CPU0_PE0_RX_DN<9>")
	)
	(arc
		(start 345.109038 -217.866214)
		(mid 345.108871 -217.87739)
		(end 345.109038 -217.888566)
		(width 0.0889)
		(layer "In13.Cu")
		(net "P5E_CPU0_PE0_RX_DN<9>")
	)
	(arc
		(start 345.287346 -217.559128)
		(mid 345.159535 -217.690221)
		(end 345.109038 -217.866214)
		(width 0.0889)
		(layer "In13.Cu")
		(net "P5E_CPU0_PE0_RX_DN<9>")
	)
	(arc
		(start 345.296236 -219.830396)
		(mid 345.500571 -220.033001)
		(end 345.578684 -220.309948)
		(width 0.0889)
		(layer "In13.Cu")
		(net "P5E_CPU0_PE0_RX_DN<9>")
	)
	(arc
		(start 345.287346 -219.18676)
		(mid 345.108749 -219.506038)
		(end 345.287346 -219.825316)
		(width 0.0889)
		(layer "In13.Cu")
		(net "P5E_CPU0_PE0_RX_DN<9>")
	)
	(arc
		(start 345.108784 -216.25052)
		(mid 345.156463 -216.43342)
		(end 345.287346 -216.569798)
		(width 0.0889)
		(layer "In13.Cu")
		(net "P5E_CPU0_PE0_RX_DN<9>")
	)
	(arc
		(start 345.108276 -214.644732)
		(mid 345.027365 -214.91486)
		(end 344.826082 -215.112346)
		(width 0.0889)
		(layer "In13.Cu")
		(net "P5E_CPU0_PE0_RX_DN<9>")
	)
	(arc
		(start 344.638884 -213.893908)
		(mid 344.713889 -214.009367)
		(end 344.823034 -214.093298)
		(width 0.0889)
		(layer "In13.Cu")
		(net "P5E_CPU0_PE0_RX_DN<9>")
	)
	(arc
		(start 344.823034 -214.093298)
		(mid 344.996997 -214.232062)
		(end 345.108276 -214.424768)
		(width 0.0889)
		(layer "In13.Cu")
		(net "P5E_CPU0_PE0_RX_DN<9>")
	)
	(arc
		(start 345.109038 -217.888566)
		(mid 345.159053 -218.065697)
		(end 345.287346 -218.197684)
		(width 0.0889)
		(layer "In13.Cu")
		(net "P5E_CPU0_PE0_RX_DN<9>")
	)
	(arc
		(start 345.296236 -216.574878)
		(mid 345.578988 -217.064526)
		(end 345.296236 -217.554048)
		(width 0.0889)
		(layer "In13.Cu")
		(net "P5E_CPU0_PE0_RX_DN<9>")
	)
	(arc
		(start 345.296236 -218.202764)
		(mid 345.499059 -218.402995)
		(end 345.57843 -218.676728)
		(width 0.0889)
		(layer "In13.Cu")
		(net "P5E_CPU0_PE0_RX_DN<9>")
	)
	(segment
		(start 344.54338 -221.669864)
		(end 344.54338 -221.134178)
		(width 0.13208)
		(layer "F.Cu")
		(net "P5E_CPU0_PE0_RX_DN<8>")
	)
	(segment
		(start 344.54338 -221.134178)
		(end 344.543634 -221.133924)
		(width 0.13208)
		(layer "F.Cu")
		(net "P5E_CPU0_PE0_RX_DN<8>")
	)
	(segment
		(start 344.16873 -216.25052)
		(end 344.16873 -216.262966)
		(width 0.0889)
		(layer "In13.Cu")
		(net "P5E_CPU0_PE0_RX_DN<8>")
	)
	(segment
		(start 344.36939 -220.801184)
		(end 344.363802 -220.804486)
		(width 0.0889)
		(layer "In13.Cu")
		(net "P5E_CPU0_PE0_RX_DN<8>")
	)
	(segment
		(start 343.741248 -212.889084)
		(end 343.740994 -212.889338)
		(width 0.14732)
		(layer "In13.Cu")
		(net "P5E_CPU0_PE0_RX_DN<8>")
	)
	(segment
		(start 344.16873 -221.116144)
		(end 344.16873 -221.14637)
		(width 0.0889)
		(layer "In13.Cu")
		(net "P5E_CPU0_PE0_RX_DN<8>")
	)
	(segment
		(start 344.168222 -214.425784)
		(end 344.168222 -214.62238)
		(width 0.0889)
		(layer "In13.Cu")
		(net "P5E_CPU0_PE0_RX_DN<8>")
	)
	(segment
		(start 343.883234 -214.093298)
		(end 343.88298 -214.093552)
		(width 0.0889)
		(layer "In13.Cu")
		(net "P5E_CPU0_PE0_RX_DN<8>")
	)
	(segment
		(start 344.358468 -219.832174)
		(end 344.36685 -219.837)
		(width 0.0889)
		(layer "In13.Cu")
		(net "P5E_CPU0_PE0_RX_DN<8>")
	)
	(segment
		(start 344.356944 -219.831158)
		(end 344.358468 -219.832174)
		(width 0.0889)
		(layer "In13.Cu")
		(net "P5E_CPU0_PE0_RX_DN<8>")
	)
	(segment
		(start 344.36939 -217.545666)
		(end 344.363802 -217.548968)
		(width 0.0889)
		(layer "In13.Cu")
		(net "P5E_CPU0_PE0_RX_DN<8>")
	)
	(segment
		(start 309.491888 -332.177644)
		(end 315.796676 -325.872856)
		(width 0.14732)
		(layer "In13.Cu")
		(net "P5E_CPU0_PE0_RX_DN<8>")
	)
	(segment
		(start 344.35034 -218.199716)
		(end 344.352118 -218.200732)
		(width 0.0889)
		(layer "In13.Cu")
		(net "P5E_CPU0_PE0_RX_DN<8>")
	)
	(segment
		(start 344.679016 -221.48292)
		(end 344.700098 -221.404942)
		(width 0.0889)
		(layer "In13.Cu")
		(net "P5E_CPU0_PE0_RX_DN<8>")
	)
	(segment
		(start 343.899236 -215.103964)
		(end 343.893648 -215.107266)
		(width 0.0889)
		(layer "In13.Cu")
		(net "P5E_CPU0_PE0_RX_DN<8>")
	)
	(segment
		(start 328.650092 -438.741312)
		(end 328.502518 -438.593738)
		(width 0.14732)
		(layer "In13.Cu")
		(net "P5E_CPU0_PE0_RX_DN<8>")
	)
	(segment
		(start 344.351356 -216.572592)
		(end 344.352372 -216.5731)
		(width 0.0889)
		(layer "In13.Cu")
		(net "P5E_CPU0_PE0_RX_DN<8>")
	)
	(segment
		(start 328.595228 -406.141682)
		(end 327.249028 -404.795482)
		(width 0.14732)
		(layer "In13.Cu")
		(net "P5E_CPU0_PE0_RX_DN<8>")
	)
	(segment
		(start 324.863206 -309.685436)
		(end 321.171062 -251.495814)
		(width 0.14732)
		(layer "In13.Cu")
		(net "P5E_CPU0_PE0_RX_DN<8>")
	)
	(segment
		(start 343.740994 -213.214966)
		(end 343.740994 -213.237064)
		(width 0.0889)
		(layer "In13.Cu")
		(net "P5E_CPU0_PE0_RX_DN<8>")
	)
	(segment
		(start 343.893648 -215.107266)
		(end 343.884758 -215.112346)
		(width 0.0889)
		(layer "In13.Cu")
		(net "P5E_CPU0_PE0_RX_DN<8>")
	)
	(segment
		(start 309.491888 -342.53424)
		(end 309.491888 -332.177644)
		(width 0.14732)
		(layer "In13.Cu")
		(net "P5E_CPU0_PE0_RX_DN<8>")
	)
	(segment
		(start 328.502518 -438.593738)
		(end 327.9775 -438.593738)
		(width 0.14732)
		(layer "In13.Cu")
		(net "P5E_CPU0_PE0_RX_DN<8>")
	)
	(segment
		(start 327.692512 -438.30875)
		(end 327.692512 -424.16222)
		(width 0.14732)
		(layer "In13.Cu")
		(net "P5E_CPU0_PE0_RX_DN<8>")
	)
	(segment
		(start 344.358468 -216.576656)
		(end 344.36685 -216.581482)
		(width 0.0889)
		(layer "In13.Cu")
		(net "P5E_CPU0_PE0_RX_DN<8>")
	)
	(segment
		(start 328.650092 -439.0898)
		(end 328.650092 -438.741312)
		(width 0.14732)
		(layer "In13.Cu")
		(net "P5E_CPU0_PE0_RX_DN<8>")
	)
	(segment
		(start 327.249028 -404.795482)
		(end 327.249028 -399.282666)
		(width 0.14732)
		(layer "In13.Cu")
		(net "P5E_CPU0_PE0_RX_DN<8>")
	)
	(segment
		(start 343.10447 -211.867496)
		(end 343.741248 -212.504274)
		(width 0.14732)
		(layer "In13.Cu")
		(net "P5E_CPU0_PE0_RX_DN<8>")
	)
	(segment
		(start 344.36939 -219.173552)
		(end 344.363802 -219.176854)
		(width 0.0889)
		(layer "In13.Cu")
		(net "P5E_CPU0_PE0_RX_DN<8>")
	)
	(segment
		(start 326.160892 -218.078304)
		(end 331.09662 -213.142576)
		(width 0.14732)
		(layer "In13.Cu")
		(net "P5E_CPU0_PE0_RX_DN<8>")
	)
	(segment
		(start 344.700098 -221.404942)
		(end 344.543634 -221.133924)
		(width 0.0889)
		(layer "In13.Cu")
		(net "P5E_CPU0_PE0_RX_DN<8>")
	)
	(segment
		(start 315.796676 -325.872856)
		(end 321.404742 -317.863728)
		(width 0.14732)
		(layer "In13.Cu")
		(net "P5E_CPU0_PE0_RX_DN<8>")
	)
	(segment
		(start 328.595228 -412.825946)
		(end 328.595228 -406.141682)
		(width 0.14732)
		(layer "In13.Cu")
		(net "P5E_CPU0_PE0_RX_DN<8>")
	)
	(segment
		(start 343.741248 -212.504274)
		(end 343.741248 -212.889084)
		(width 0.14732)
		(layer "In13.Cu")
		(net "P5E_CPU0_PE0_RX_DN<8>")
	)
	(segment
		(start 342.5571 -211.640928)
		(end 343.10447 -211.867496)
		(width 0.14732)
		(layer "In13.Cu")
		(net "P5E_CPU0_PE0_RX_DN<8>")
	)
	(segment
		(start 344.352372 -219.828618)
		(end 344.356944 -219.831158)
		(width 0.0889)
		(layer "In13.Cu")
		(net "P5E_CPU0_PE0_RX_DN<8>")
	)
	(segment
		(start 344.16873 -219.493592)
		(end 344.16873 -219.518484)
		(width 0.0889)
		(layer "In13.Cu")
		(net "P5E_CPU0_PE0_RX_DN<8>")
	)
	(segment
		(start 343.889838 -215.763094)
		(end 343.899744 -215.76919)
		(width 0.0889)
		(layer "In13.Cu")
		(net "P5E_CPU0_PE0_RX_DN<8>")
	)
	(segment
		(start 344.352372 -216.5731)
		(end 344.356944 -216.57564)
		(width 0.0889)
		(layer "In13.Cu")
		(net "P5E_CPU0_PE0_RX_DN<8>")
	)
	(segment
		(start 327.692512 -424.16222)
		(end 327.713086 -424.16222)
		(width 0.14732)
		(layer "In13.Cu")
		(net "P5E_CPU0_PE0_RX_DN<8>")
	)
	(segment
		(start 327.9775 -438.593738)
		(end 327.692512 -438.30875)
		(width 0.14732)
		(layer "In13.Cu")
		(net "P5E_CPU0_PE0_RX_DN<8>")
	)
	(segment
		(start 344.352118 -218.200732)
		(end 344.36939 -218.210892)
		(width 0.0889)
		(layer "In13.Cu")
		(net "P5E_CPU0_PE0_RX_DN<8>")
	)
	(segment
		(start 343.740994 -212.889338)
		(end 343.740994 -213.214966)
		(width 0.14732)
		(layer "In13.Cu")
		(net "P5E_CPU0_PE0_RX_DN<8>")
	)
	(segment
		(start 343.740994 -213.237064)
		(end 343.699084 -213.278974)
		(width 0.0889)
		(layer "In13.Cu")
		(net "P5E_CPU0_PE0_RX_DN<8>")
	)
	(segment
		(start 344.67927 -221.483682)
		(end 344.679016 -221.48292)
		(width 0.0889)
		(layer "In13.Cu")
		(net "P5E_CPU0_PE0_RX_DN<8>")
	)
	(segment
		(start 344.356944 -216.57564)
		(end 344.358468 -216.576656)
		(width 0.0889)
		(layer "In13.Cu")
		(net "P5E_CPU0_PE0_RX_DN<8>")
	)
	(segment
		(start 344.363802 -220.804486)
		(end 344.354912 -220.809566)
		(width 0.0889)
		(layer "In13.Cu")
		(net "P5E_CPU0_PE0_RX_DN<8>")
	)
	(segment
		(start 343.882472 -215.75903)
		(end 343.887806 -215.762078)
		(width 0.0889)
		(layer "In13.Cu")
		(net "P5E_CPU0_PE0_RX_DN<8>")
	)
	(segment
		(start 344.363802 -217.548968)
		(end 344.354912 -217.554048)
		(width 0.0889)
		(layer "In13.Cu")
		(net "P5E_CPU0_PE0_RX_DN<8>")
	)
	(segment
		(start 321.171062 -251.495814)
		(end 324.84695 -221.250256)
		(width 0.14732)
		(layer "In13.Cu")
		(net "P5E_CPU0_PE0_RX_DN<8>")
	)
	(segment
		(start 321.404742 -317.863728)
		(end 324.863206 -309.685436)
		(width 0.14732)
		(layer "In13.Cu")
		(net "P5E_CPU0_PE0_RX_DN<8>")
	)
	(segment
		(start 343.887806 -215.762078)
		(end 343.889838 -215.763094)
		(width 0.0889)
		(layer "In13.Cu")
		(net "P5E_CPU0_PE0_RX_DN<8>")
	)
	(segment
		(start 343.699084 -213.278974)
		(end 343.699084 -213.893908)
		(width 0.0889)
		(layer "In13.Cu")
		(net "P5E_CPU0_PE0_RX_DN<8>")
	)
	(segment
		(start 344.16873 -217.860626)
		(end 344.16873 -217.890852)
		(width 0.0889)
		(layer "In13.Cu")
		(net "P5E_CPU0_PE0_RX_DN<8>")
	)
	(segment
		(start 327.713086 -424.16222)
		(end 328.595228 -412.825946)
		(width 0.14732)
		(layer "In13.Cu")
		(net "P5E_CPU0_PE0_RX_DN<8>")
	)
	(segment
		(start 310.932322 -348.032832)
		(end 309.491888 -342.53424)
		(width 0.14732)
		(layer "In13.Cu")
		(net "P5E_CPU0_PE0_RX_DN<8>")
	)
	(segment
		(start 324.84695 -221.250256)
		(end 326.160892 -218.078304)
		(width 0.14732)
		(layer "In13.Cu")
		(net "P5E_CPU0_PE0_RX_DN<8>")
	)
	(segment
		(start 327.249028 -399.282666)
		(end 310.932322 -348.032832)
		(width 0.14732)
		(layer "In13.Cu")
		(net "P5E_CPU0_PE0_RX_DN<8>")
	)
	(segment
		(start 343.880948 -215.758014)
		(end 343.882472 -215.75903)
		(width 0.0889)
		(layer "In13.Cu")
		(net "P5E_CPU0_PE0_RX_DN<8>")
	)
	(segment
		(start 332.340204 -212.627464)
		(end 337.899248 -211.640928)
		(width 0.14732)
		(layer "In13.Cu")
		(net "P5E_CPU0_PE0_RX_DN<8>")
	)
	(segment
		(start 344.351356 -219.82811)
		(end 344.352372 -219.828618)
		(width 0.0889)
		(layer "In13.Cu")
		(net "P5E_CPU0_PE0_RX_DN<8>")
	)
	(segment
		(start 337.899248 -211.640928)
		(end 342.5571 -211.640928)
		(width 0.14732)
		(layer "In13.Cu")
		(net "P5E_CPU0_PE0_RX_DN<8>")
	)
	(segment
		(start 331.09662 -213.142576)
		(end 332.340204 -212.627464)
		(width 0.14732)
		(layer "In13.Cu")
		(net "P5E_CPU0_PE0_RX_DN<8>")
	)
	(segment
		(start 344.363802 -219.176854)
		(end 344.354912 -219.181934)
		(width 0.0889)
		(layer "In13.Cu")
		(net "P5E_CPU0_PE0_RX_DN<8>")
	)
	(arc
		(start 344.168222 -214.62238)
		(mid 344.168207 -214.633557)
		(end 344.167968 -214.644732)
		(width 0.0889)
		(layer "In13.Cu")
		(net "P5E_CPU0_PE0_RX_DN<8>")
	)
	(arc
		(start 344.36939 -218.210892)
		(mid 344.562803 -218.409899)
		(end 344.638122 -218.676982)
		(width 0.0889)
		(layer "In13.Cu")
		(net "P5E_CPU0_PE0_RX_DN<8>")
	)
	(arc
		(start 344.354912 -219.181934)
		(mid 344.221635 -219.313746)
		(end 344.16873 -219.493592)
		(width 0.0889)
		(layer "In13.Cu")
		(net "P5E_CPU0_PE0_RX_DN<8>")
	)
	(arc
		(start 344.16873 -217.890852)
		(mid 344.220304 -218.068341)
		(end 344.35034 -218.199716)
		(width 0.0889)
		(layer "In13.Cu")
		(net "P5E_CPU0_PE0_RX_DN<8>")
	)
	(arc
		(start 344.16873 -216.262966)
		(mid 344.220534 -216.441084)
		(end 344.351356 -216.572592)
		(width 0.0889)
		(layer "In13.Cu")
		(net "P5E_CPU0_PE0_RX_DN<8>")
	)
	(arc
		(start 344.354912 -217.554048)
		(mid 344.222854 -217.683664)
		(end 344.16873 -217.860626)
		(width 0.0889)
		(layer "In13.Cu")
		(net "P5E_CPU0_PE0_RX_DN<8>")
	)
	(arc
		(start 343.884758 -215.112346)
		(mid 343.69866 -215.43404)
		(end 343.880948 -215.758014)
		(width 0.0889)
		(layer "In13.Cu")
		(net "P5E_CPU0_PE0_RX_DN<8>")
	)
	(arc
		(start 344.167968 -214.644732)
		(mid 344.091062 -214.907981)
		(end 343.899236 -215.103964)
		(width 0.0889)
		(layer "In13.Cu")
		(net "P5E_CPU0_PE0_RX_DN<8>")
	)
	(arc
		(start 343.88298 -214.093552)
		(mid 344.057071 -214.232646)
		(end 344.168222 -214.425784)
		(width 0.0889)
		(layer "In13.Cu")
		(net "P5E_CPU0_PE0_RX_DN<8>")
	)
	(arc
		(start 344.354912 -220.809566)
		(mid 344.222854 -220.939182)
		(end 344.16873 -221.116144)
		(width 0.0889)
		(layer "In13.Cu")
		(net "P5E_CPU0_PE0_RX_DN<8>")
	)
	(arc
		(start 344.638122 -218.707462)
		(mid 344.562763 -218.974522)
		(end 344.36939 -219.173552)
		(width 0.0889)
		(layer "In13.Cu")
		(net "P5E_CPU0_PE0_RX_DN<8>")
	)
	(arc
		(start 343.899744 -215.76919)
		(mid 344.09692 -215.974825)
		(end 344.16873 -216.25052)
		(width 0.0889)
		(layer "In13.Cu")
		(net "P5E_CPU0_PE0_RX_DN<8>")
	)
	(arc
		(start 344.16873 -221.14637)
		(mid 344.336863 -221.4469)
		(end 344.67927 -221.483682)
		(width 0.0889)
		(layer "In13.Cu")
		(net "P5E_CPU0_PE0_RX_DN<8>")
	)
	(arc
		(start 344.638122 -218.676982)
		(mid 344.638328 -218.692222)
		(end 344.638122 -218.707462)
		(width 0.0889)
		(layer "In13.Cu")
		(net "P5E_CPU0_PE0_RX_DN<8>")
	)
	(arc
		(start 344.16873 -219.518484)
		(mid 344.220534 -219.696602)
		(end 344.351356 -219.82811)
		(width 0.0889)
		(layer "In13.Cu")
		(net "P5E_CPU0_PE0_RX_DN<8>")
	)
	(arc
		(start 343.699084 -213.893908)
		(mid 343.774089 -214.009367)
		(end 343.883234 -214.093298)
		(width 0.0889)
		(layer "In13.Cu")
		(net "P5E_CPU0_PE0_RX_DN<8>")
	)
	(arc
		(start 344.36685 -216.581482)
		(mid 344.638468 -217.062855)
		(end 344.36939 -217.545666)
		(width 0.0889)
		(layer "In13.Cu")
		(net "P5E_CPU0_PE0_RX_DN<8>")
	)
	(arc
		(start 344.36685 -219.837)
		(mid 344.638468 -220.318373)
		(end 344.36939 -220.801184)
		(width 0.0889)
		(layer "In13.Cu")
		(net "P5E_CPU0_PE0_RX_DN<8>")
	)
	(segment
		(start 344.073734 -220.855794)
		(end 344.073734 -220.320108)
		(width 0.13208)
		(layer "F.Cu")
		(net "P5E_CPU0_PE0_RX_DN<7>")
	)
	(segment
		(start 344.073734 -220.320108)
		(end 344.07348 -220.319854)
		(width 0.13208)
		(layer "F.Cu")
		(net "P5E_CPU0_PE0_RX_DN<7>")
	)
	(segment
		(start 343.839038 -220.6117)
		(end 343.917016 -220.590872)
		(width 0.0889)
		(layer "In13.Cu")
		(net "P5E_CPU0_PE0_RX_DN<7>")
	)
	(segment
		(start 343.41562 -219.182188)
		(end 343.407746 -219.18676)
		(width 0.0889)
		(layer "In13.Cu")
		(net "P5E_CPU0_PE0_RX_DN<7>")
	)
	(segment
		(start 342.946482 -215.112346)
		(end 342.945466 -215.112854)
		(width 0.0889)
		(layer "In13.Cu")
		(net "P5E_CPU0_PE0_RX_DN<7>")
	)
	(segment
		(start 316.609222 -326.375776)
		(end 322.302632 -318.245236)
		(width 0.14732)
		(layer "In13.Cu")
		(net "P5E_CPU0_PE0_RX_DN<7>")
	)
	(segment
		(start 343.416636 -219.18168)
		(end 343.41562 -219.182188)
		(width 0.0889)
		(layer "In13.Cu")
		(net "P5E_CPU0_PE0_RX_DN<7>")
	)
	(segment
		(start 325.757286 -221.493842)
		(end 326.948038 -218.619324)
		(width 0.14732)
		(layer "In13.Cu")
		(net "P5E_CPU0_PE0_RX_DN<7>")
	)
	(segment
		(start 312.075576 -348.13621)
		(end 310.421528 -342.372188)
		(width 0.14732)
		(layer "In13.Cu")
		(net "P5E_CPU0_PE0_RX_DN<7>")
	)
	(segment
		(start 343.407746 -218.197684)
		(end 343.416636 -218.202764)
		(width 0.0889)
		(layer "In13.Cu")
		(net "P5E_CPU0_PE0_RX_DN<7>")
	)
	(segment
		(start 324.024244 -280.580846)
		(end 322.121276 -251.492766)
		(width 0.14732)
		(layer "In13.Cu")
		(net "P5E_CPU0_PE0_RX_DN<7>")
	)
	(segment
		(start 325.927466 -309.669434)
		(end 324.024244 -280.5811)
		(width 0.14732)
		(layer "In13.Cu")
		(net "P5E_CPU0_PE0_RX_DN<7>")
	)
	(segment
		(start 310.421528 -342.372188)
		(end 310.421528 -332.56347)
		(width 0.14732)
		(layer "In13.Cu")
		(net "P5E_CPU0_PE0_RX_DN<7>")
	)
	(segment
		(start 331.502512 -437.59374)
		(end 330.977494 -437.59374)
		(width 0.14732)
		(layer "In13.Cu")
		(net "P5E_CPU0_PE0_RX_DN<7>")
	)
	(segment
		(start 324.024244 -280.5811)
		(end 324.024244 -280.580846)
		(width 0.14732)
		(layer "In13.Cu")
		(net "P5E_CPU0_PE0_RX_DN<7>")
	)
	(segment
		(start 343.69883 -218.676728)
		(end 343.69883 -218.707716)
		(width 0.0889)
		(layer "In13.Cu")
		(net "P5E_CPU0_PE0_RX_DN<7>")
	)
	(segment
		(start 310.421528 -332.56347)
		(end 316.609222 -326.375776)
		(width 0.14732)
		(layer "In13.Cu")
		(net "P5E_CPU0_PE0_RX_DN<7>")
	)
	(segment
		(start 330.692506 -437.308752)
		(end 330.692506 -424.312842)
		(width 0.14732)
		(layer "In13.Cu")
		(net "P5E_CPU0_PE0_RX_DN<7>")
	)
	(segment
		(start 343.407746 -219.825316)
		(end 343.416636 -219.830396)
		(width 0.0889)
		(layer "In13.Cu")
		(net "P5E_CPU0_PE0_RX_DN<7>")
	)
	(segment
		(start 342.801448 -212.93328)
		(end 342.801448 -213.062312)
		(width 0.14732)
		(layer "In13.Cu")
		(net "P5E_CPU0_PE0_RX_DN<7>")
	)
	(segment
		(start 322.302632 -318.245236)
		(end 325.927466 -309.669434)
		(width 0.14732)
		(layer "In13.Cu")
		(net "P5E_CPU0_PE0_RX_DN<7>")
	)
	(segment
		(start 342.945466 -215.112854)
		(end 342.937592 -215.117426)
		(width 0.0889)
		(layer "In13.Cu")
		(net "P5E_CPU0_PE0_RX_DN<7>")
	)
	(segment
		(start 342.801448 -213.29396)
		(end 342.759284 -213.336124)
		(width 0.0889)
		(layer "In13.Cu")
		(net "P5E_CPU0_PE0_RX_DN<7>")
	)
	(segment
		(start 342.80094 -213.06282)
		(end 342.80094 -213.077298)
		(width 0.14732)
		(layer "In13.Cu")
		(net "P5E_CPU0_PE0_RX_DN<7>")
	)
	(segment
		(start 342.801448 -213.062312)
		(end 342.80094 -213.06282)
		(width 0.14732)
		(layer "In13.Cu")
		(net "P5E_CPU0_PE0_RX_DN<7>")
	)
	(segment
		(start 331.650086 -438.089802)
		(end 331.650086 -437.741314)
		(width 0.14732)
		(layer "In13.Cu")
		(net "P5E_CPU0_PE0_RX_DN<7>")
	)
	(segment
		(start 343.407746 -216.569798)
		(end 343.416636 -216.574878)
		(width 0.0889)
		(layer "In13.Cu")
		(net "P5E_CPU0_PE0_RX_DN<7>")
	)
	(segment
		(start 343.416636 -217.554048)
		(end 343.407746 -217.559128)
		(width 0.0889)
		(layer "In13.Cu")
		(net "P5E_CPU0_PE0_RX_DN<7>")
	)
	(segment
		(start 326.948038 -218.619324)
		(end 331.354176 -214.213694)
		(width 0.14732)
		(layer "In13.Cu")
		(net "P5E_CPU0_PE0_RX_DN<7>")
	)
	(segment
		(start 338.19973 -212.624924)
		(end 342.493092 -212.624924)
		(width 0.14732)
		(layer "In13.Cu")
		(net "P5E_CPU0_PE0_RX_DN<7>")
	)
	(segment
		(start 331.650086 -437.741314)
		(end 331.502512 -437.59374)
		(width 0.14732)
		(layer "In13.Cu")
		(net "P5E_CPU0_PE0_RX_DN<7>")
	)
	(segment
		(start 343.917016 -220.590872)
		(end 344.07348 -220.319854)
		(width 0.0889)
		(layer "In13.Cu")
		(net "P5E_CPU0_PE0_RX_DN<7>")
	)
	(segment
		(start 342.801448 -213.271862)
		(end 342.801448 -213.29396)
		(width 0.0889)
		(layer "In13.Cu")
		(net "P5E_CPU0_PE0_RX_DN<7>")
	)
	(segment
		(start 330.977494 -437.59374)
		(end 330.692506 -437.308752)
		(width 0.14732)
		(layer "In13.Cu")
		(net "P5E_CPU0_PE0_RX_DN<7>")
	)
	(segment
		(start 331.354176 -214.213694)
		(end 332.712568 -213.651338)
		(width 0.14732)
		(layer "In13.Cu")
		(net "P5E_CPU0_PE0_RX_DN<7>")
	)
	(segment
		(start 342.759284 -213.336124)
		(end 342.759284 -213.893908)
		(width 0.0889)
		(layer "In13.Cu")
		(net "P5E_CPU0_PE0_RX_DN<7>")
	)
	(segment
		(start 331.658468 -412.151322)
		(end 331.658468 -406.141682)
		(width 0.14732)
		(layer "In13.Cu")
		(net "P5E_CPU0_PE0_RX_DN<7>")
	)
	(segment
		(start 342.801448 -213.077806)
		(end 342.801448 -213.271862)
		(width 0.14732)
		(layer "In13.Cu")
		(net "P5E_CPU0_PE0_RX_DN<7>")
	)
	(segment
		(start 342.493092 -212.624924)
		(end 342.801448 -212.93328)
		(width 0.14732)
		(layer "In13.Cu")
		(net "P5E_CPU0_PE0_RX_DN<7>")
	)
	(segment
		(start 332.712568 -213.651338)
		(end 338.19973 -212.624924)
		(width 0.14732)
		(layer "In13.Cu")
		(net "P5E_CPU0_PE0_RX_DN<7>")
	)
	(segment
		(start 330.312268 -404.795482)
		(end 330.312268 -400.100038)
		(width 0.14732)
		(layer "In13.Cu")
		(net "P5E_CPU0_PE0_RX_DN<7>")
	)
	(segment
		(start 343.228676 -214.424768)
		(end 343.228676 -214.644732)
		(width 0.0889)
		(layer "In13.Cu")
		(net "P5E_CPU0_PE0_RX_DN<7>")
	)
	(segment
		(start 343.699084 -220.309948)
		(end 343.699084 -220.32849)
		(width 0.0889)
		(layer "In13.Cu")
		(net "P5E_CPU0_PE0_RX_DN<7>")
	)
	(segment
		(start 331.658468 -406.141682)
		(end 330.312268 -404.795482)
		(width 0.14732)
		(layer "In13.Cu")
		(net "P5E_CPU0_PE0_RX_DN<7>")
	)
	(segment
		(start 322.121276 -251.492766)
		(end 325.757286 -221.493842)
		(width 0.14732)
		(layer "In13.Cu")
		(net "P5E_CPU0_PE0_RX_DN<7>")
	)
	(segment
		(start 330.312268 -400.100038)
		(end 312.075576 -348.13621)
		(width 0.14732)
		(layer "In13.Cu")
		(net "P5E_CPU0_PE0_RX_DN<7>")
	)
	(segment
		(start 342.944958 -215.7603)
		(end 342.946482 -215.761062)
		(width 0.0889)
		(layer "In13.Cu")
		(net "P5E_CPU0_PE0_RX_DN<7>")
	)
	(segment
		(start 342.80094 -213.077298)
		(end 342.801448 -213.077806)
		(width 0.14732)
		(layer "In13.Cu")
		(net "P5E_CPU0_PE0_RX_DN<7>")
	)
	(segment
		(start 342.949276 -215.762586)
		(end 342.952578 -215.764618)
		(width 0.0889)
		(layer "In13.Cu")
		(net "P5E_CPU0_PE0_RX_DN<7>")
	)
	(segment
		(start 342.937592 -215.755982)
		(end 342.944958 -215.7603)
		(width 0.0889)
		(layer "In13.Cu")
		(net "P5E_CPU0_PE0_RX_DN<7>")
	)
	(segment
		(start 342.946482 -215.761062)
		(end 342.949276 -215.762586)
		(width 0.0889)
		(layer "In13.Cu")
		(net "P5E_CPU0_PE0_RX_DN<7>")
	)
	(segment
		(start 330.692506 -424.312842)
		(end 331.658468 -412.151322)
		(width 0.14732)
		(layer "In13.Cu")
		(net "P5E_CPU0_PE0_RX_DN<7>")
	)
	(arc
		(start 343.407746 -219.18676)
		(mid 343.229149 -219.506038)
		(end 343.407746 -219.825316)
		(width 0.0889)
		(layer "In13.Cu")
		(net "P5E_CPU0_PE0_RX_DN<7>")
	)
	(arc
		(start 343.416636 -216.574878)
		(mid 343.699388 -217.064526)
		(end 343.416636 -217.554048)
		(width 0.0889)
		(layer "In13.Cu")
		(net "P5E_CPU0_PE0_RX_DN<7>")
	)
	(arc
		(start 342.759284 -213.893908)
		(mid 342.834289 -214.009367)
		(end 342.943434 -214.093298)
		(width 0.0889)
		(layer "In13.Cu")
		(net "P5E_CPU0_PE0_RX_DN<7>")
	)
	(arc
		(start 342.943434 -214.093298)
		(mid 343.117397 -214.232062)
		(end 343.228676 -214.424768)
		(width 0.0889)
		(layer "In13.Cu")
		(net "P5E_CPU0_PE0_RX_DN<7>")
	)
	(arc
		(start 343.229438 -217.888566)
		(mid 343.279453 -218.065697)
		(end 343.407746 -218.197684)
		(width 0.0889)
		(layer "In13.Cu")
		(net "P5E_CPU0_PE0_RX_DN<7>")
	)
	(arc
		(start 343.228676 -214.644732)
		(mid 343.147765 -214.91486)
		(end 342.946482 -215.112346)
		(width 0.0889)
		(layer "In13.Cu")
		(net "P5E_CPU0_PE0_RX_DN<7>")
	)
	(arc
		(start 342.937592 -215.117426)
		(mid 342.758995 -215.436704)
		(end 342.937592 -215.755982)
		(width 0.0889)
		(layer "In13.Cu")
		(net "P5E_CPU0_PE0_RX_DN<7>")
	)
	(arc
		(start 343.416636 -218.202764)
		(mid 343.619459 -218.402995)
		(end 343.69883 -218.676728)
		(width 0.0889)
		(layer "In13.Cu")
		(net "P5E_CPU0_PE0_RX_DN<7>")
	)
	(arc
		(start 343.416636 -219.830396)
		(mid 343.620971 -220.033001)
		(end 343.699084 -220.309948)
		(width 0.0889)
		(layer "In13.Cu")
		(net "P5E_CPU0_PE0_RX_DN<7>")
	)
	(arc
		(start 343.229184 -216.25052)
		(mid 343.276863 -216.43342)
		(end 343.407746 -216.569798)
		(width 0.0889)
		(layer "In13.Cu")
		(net "P5E_CPU0_PE0_RX_DN<7>")
	)
	(arc
		(start 343.229438 -217.866214)
		(mid 343.229271 -217.87739)
		(end 343.229438 -217.888566)
		(width 0.0889)
		(layer "In13.Cu")
		(net "P5E_CPU0_PE0_RX_DN<7>")
	)
	(arc
		(start 343.699084 -220.32849)
		(mid 343.737758 -220.485558)
		(end 343.839038 -220.6117)
		(width 0.0889)
		(layer "In13.Cu")
		(net "P5E_CPU0_PE0_RX_DN<7>")
	)
	(arc
		(start 343.69883 -218.707716)
		(mid 343.61946 -218.98145)
		(end 343.416636 -219.18168)
		(width 0.0889)
		(layer "In13.Cu")
		(net "P5E_CPU0_PE0_RX_DN<7>")
	)
	(arc
		(start 343.407746 -217.559128)
		(mid 343.279935 -217.690221)
		(end 343.229438 -217.866214)
		(width 0.0889)
		(layer "In13.Cu")
		(net "P5E_CPU0_PE0_RX_DN<7>")
	)
	(arc
		(start 342.952578 -215.764618)
		(mid 343.155165 -215.970969)
		(end 343.229184 -216.25052)
		(width 0.0889)
		(layer "In13.Cu")
		(net "P5E_CPU0_PE0_RX_DN<7>")
	)
	(segment
		(start 342.66378 -221.669864)
		(end 342.66378 -221.134178)
		(width 0.13208)
		(layer "F.Cu")
		(net "P5E_CPU0_PE0_RX_DN<6>")
	)
	(segment
		(start 342.66378 -221.134178)
		(end 342.664034 -221.133924)
		(width 0.13208)
		(layer "F.Cu")
		(net "P5E_CPU0_PE0_RX_DN<6>")
	)
	(segment
		(start 342.009476 -219.018104)
		(end 342.012778 -219.020136)
		(width 0.0889)
		(layer "In13.Cu")
		(net "P5E_CPU0_PE0_RX_DN<6>")
	)
	(segment
		(start 326.676512 -221.749366)
		(end 327.715372 -219.241878)
		(width 0.14732)
		(layer "In13.Cu")
		(net "P5E_CPU0_PE0_RX_DN<6>")
	)
	(segment
		(start 312.823352 -347.057472)
		(end 311.351168 -342.200992)
		(width 0.14732)
		(layer "In13.Cu")
		(net "P5E_CPU0_PE0_RX_DN<6>")
	)
	(segment
		(start 334.721708 -411.502098)
		(end 334.721708 -406.141682)
		(width 0.14732)
		(layer "In13.Cu")
		(net "P5E_CPU0_PE0_RX_DN<6>")
	)
	(segment
		(start 342.006682 -219.01658)
		(end 342.009476 -219.018104)
		(width 0.0889)
		(layer "In13.Cu")
		(net "P5E_CPU0_PE0_RX_DN<6>")
	)
	(segment
		(start 333.650082 -438.741312)
		(end 333.502508 -438.593738)
		(width 0.14732)
		(layer "In13.Cu")
		(net "P5E_CPU0_PE0_RX_DN<6>")
	)
	(segment
		(start 332.97749 -438.593738)
		(end 332.692502 -438.30875)
		(width 0.14732)
		(layer "In13.Cu")
		(net "P5E_CPU0_PE0_RX_DN<6>")
	)
	(segment
		(start 332.692502 -424.652186)
		(end 334.721708 -411.502098)
		(width 0.14732)
		(layer "In13.Cu")
		(net "P5E_CPU0_PE0_RX_DN<6>")
	)
	(segment
		(start 342.47582 -220.810074)
		(end 342.467946 -220.814646)
		(width 0.0889)
		(layer "In13.Cu")
		(net "P5E_CPU0_PE0_RX_DN<6>")
	)
	(segment
		(start 331.681328 -215.275414)
		(end 333.021432 -214.829136)
		(width 0.14732)
		(layer "In13.Cu")
		(net "P5E_CPU0_PE0_RX_DN<6>")
	)
	(segment
		(start 323.10451 -251.60859)
		(end 326.676512 -221.749366)
		(width 0.14732)
		(layer "In13.Cu")
		(net "P5E_CPU0_PE0_RX_DN<6>")
	)
	(segment
		(start 341.528146 -216.569798)
		(end 341.537036 -216.574878)
		(width 0.0889)
		(layer "In13.Cu")
		(net "P5E_CPU0_PE0_RX_DN<6>")
	)
	(segment
		(start 333.021432 -214.829136)
		(end 333.912464 -214.829136)
		(width 0.14732)
		(layer "In13.Cu")
		(net "P5E_CPU0_PE0_RX_DN<6>")
	)
	(segment
		(start 334.721708 -406.141682)
		(end 333.375508 -404.795482)
		(width 0.14732)
		(layer "In13.Cu")
		(net "P5E_CPU0_PE0_RX_DN<6>")
	)
	(segment
		(start 341.528146 -218.197684)
		(end 341.537036 -218.202764)
		(width 0.0889)
		(layer "In13.Cu")
		(net "P5E_CPU0_PE0_RX_DN<6>")
	)
	(segment
		(start 342.005158 -219.015818)
		(end 342.006682 -219.01658)
		(width 0.0889)
		(layer "In13.Cu")
		(net "P5E_CPU0_PE0_RX_DN<6>")
	)
	(segment
		(start 327.715372 -219.241878)
		(end 331.681328 -215.275414)
		(width 0.14732)
		(layer "In13.Cu")
		(net "P5E_CPU0_PE0_RX_DN<6>")
	)
	(segment
		(start 332.692502 -438.30875)
		(end 332.692502 -424.652186)
		(width 0.14732)
		(layer "In13.Cu")
		(net "P5E_CPU0_PE0_RX_DN<6>")
	)
	(segment
		(start 342.799416 -221.48292)
		(end 342.820498 -221.404942)
		(width 0.0889)
		(layer "In13.Cu")
		(net "P5E_CPU0_PE0_RX_DN<6>")
	)
	(segment
		(start 311.351168 -332.980792)
		(end 317.580772 -326.751188)
		(width 0.14732)
		(layer "In13.Cu")
		(net "P5E_CPU0_PE0_RX_DN<6>")
	)
	(segment
		(start 337.12023 -215.42248)
		(end 337.12023 -215.436704)
		(width 0.0889)
		(layer "In13.Cu")
		(net "P5E_CPU0_PE0_RX_DN<6>")
	)
	(segment
		(start 341.537036 -217.554048)
		(end 341.528146 -217.559128)
		(width 0.0889)
		(layer "In13.Cu")
		(net "P5E_CPU0_PE0_RX_DN<6>")
	)
	(segment
		(start 333.934562 -214.829136)
		(end 333.976472 -214.871046)
		(width 0.0889)
		(layer "In13.Cu")
		(net "P5E_CPU0_PE0_RX_DN<6>")
	)
	(segment
		(start 333.502508 -438.593738)
		(end 332.97749 -438.593738)
		(width 0.14732)
		(layer "In13.Cu")
		(net "P5E_CPU0_PE0_RX_DN<6>")
	)
	(segment
		(start 333.976472 -214.871046)
		(end 334.67548 -214.871046)
		(width 0.0889)
		(layer "In13.Cu")
		(net "P5E_CPU0_PE0_RX_DN<6>")
	)
	(segment
		(start 317.580772 -326.751188)
		(end 323.008752 -318.999362)
		(width 0.14732)
		(layer "In13.Cu")
		(net "P5E_CPU0_PE0_RX_DN<6>")
	)
	(segment
		(start 336.827114 -214.940896)
		(end 336.837528 -214.946992)
		(width 0.0889)
		(layer "In13.Cu")
		(net "P5E_CPU0_PE0_RX_DN<6>")
	)
	(segment
		(start 333.375508 -404.795482)
		(end 333.375508 -399.81124)
		(width 0.14732)
		(layer "In13.Cu")
		(net "P5E_CPU0_PE0_RX_DN<6>")
	)
	(segment
		(start 341.81923 -218.676728)
		(end 341.81923 -218.692222)
		(width 0.0889)
		(layer "In13.Cu")
		(net "P5E_CPU0_PE0_RX_DN<6>")
	)
	(segment
		(start 342.467946 -219.825316)
		(end 342.476836 -219.830396)
		(width 0.0889)
		(layer "In13.Cu")
		(net "P5E_CPU0_PE0_RX_DN<6>")
	)
	(segment
		(start 333.375508 -399.81124)
		(end 312.823352 -347.057472)
		(width 0.14732)
		(layer "In13.Cu")
		(net "P5E_CPU0_PE0_RX_DN<6>")
	)
	(segment
		(start 333.912464 -214.829136)
		(end 333.934562 -214.829136)
		(width 0.0889)
		(layer "In13.Cu")
		(net "P5E_CPU0_PE0_RX_DN<6>")
	)
	(segment
		(start 341.051642 -215.752426)
		(end 341.072978 -215.764618)
		(width 0.0889)
		(layer "In13.Cu")
		(net "P5E_CPU0_PE0_RX_DN<6>")
	)
	(segment
		(start 341.997792 -219.0115)
		(end 342.005158 -219.015818)
		(width 0.0889)
		(layer "In13.Cu")
		(net "P5E_CPU0_PE0_RX_DN<6>")
	)
	(segment
		(start 341.05215 -215.752426)
		(end 341.051642 -215.752426)
		(width 0.0889)
		(layer "In13.Cu")
		(net "P5E_CPU0_PE0_RX_DN<6>")
	)
	(segment
		(start 342.476836 -220.809566)
		(end 342.47582 -220.810074)
		(width 0.0889)
		(layer "In13.Cu")
		(net "P5E_CPU0_PE0_RX_DN<6>")
	)
	(segment
		(start 342.476836 -219.830396)
		(end 342.482932 -219.833952)
		(width 0.0889)
		(layer "In13.Cu")
		(net "P5E_CPU0_PE0_RX_DN<6>")
	)
	(segment
		(start 338.23275 -215.752426)
		(end 338.247482 -215.761062)
		(width 0.0889)
		(layer "In13.Cu")
		(net "P5E_CPU0_PE0_RX_DN<6>")
	)
	(segment
		(start 333.650082 -439.0898)
		(end 333.650082 -438.741312)
		(width 0.14732)
		(layer "In13.Cu")
		(net "P5E_CPU0_PE0_RX_DN<6>")
	)
	(segment
		(start 323.008752 -318.999362)
		(end 326.894952 -309.83555)
		(width 0.14732)
		(layer "In13.Cu")
		(net "P5E_CPU0_PE0_RX_DN<6>")
	)
	(segment
		(start 326.894952 -309.83555)
		(end 323.10451 -251.60859)
		(width 0.14732)
		(layer "In13.Cu")
		(net "P5E_CPU0_PE0_RX_DN<6>")
	)
	(segment
		(start 337.298792 -215.755982)
		(end 337.307682 -215.761062)
		(width 0.0889)
		(layer "In13.Cu")
		(net "P5E_CPU0_PE0_RX_DN<6>")
	)
	(segment
		(start 335.332832 -214.946992)
		(end 335.343246 -214.940896)
		(width 0.0889)
		(layer "In13.Cu")
		(net "P5E_CPU0_PE0_RX_DN<6>")
	)
	(segment
		(start 340.11235 -215.752426)
		(end 340.127082 -215.761062)
		(width 0.0889)
		(layer "In13.Cu")
		(net "P5E_CPU0_PE0_RX_DN<6>")
	)
	(segment
		(start 311.351168 -342.200992)
		(end 311.351168 -332.980792)
		(width 0.14732)
		(layer "In13.Cu")
		(net "P5E_CPU0_PE0_RX_DN<6>")
	)
	(segment
		(start 341.819484 -217.05443)
		(end 341.819484 -217.082878)
		(width 0.0889)
		(layer "In13.Cu")
		(net "P5E_CPU0_PE0_RX_DN<6>")
	)
	(segment
		(start 342.820498 -221.404942)
		(end 342.664034 -221.133924)
		(width 0.0889)
		(layer "In13.Cu")
		(net "P5E_CPU0_PE0_RX_DN<6>")
	)
	(segment
		(start 339.17255 -215.752426)
		(end 339.187282 -215.761062)
		(width 0.0889)
		(layer "In13.Cu")
		(net "P5E_CPU0_PE0_RX_DN<6>")
	)
	(arc
		(start 336.837528 -214.946992)
		(mid 337.041009 -215.147796)
		(end 337.12023 -215.42248)
		(width 0.0889)
		(layer "In13.Cu")
		(net "P5E_CPU0_PE0_RX_DN<6>")
	)
	(arc
		(start 337.12023 -215.436704)
		(mid 337.167909 -215.619604)
		(end 337.298792 -215.755982)
		(width 0.0889)
		(layer "In13.Cu")
		(net "P5E_CPU0_PE0_RX_DN<6>")
	)
	(arc
		(start 342.289384 -221.144084)
		(mid 342.45656 -221.445665)
		(end 342.799416 -221.48292)
		(width 0.0889)
		(layer "In13.Cu")
		(net "P5E_CPU0_PE0_RX_DN<6>")
	)
	(arc
		(start 341.349838 -217.888566)
		(mid 341.399853 -218.065697)
		(end 341.528146 -218.197684)
		(width 0.0889)
		(layer "In13.Cu")
		(net "P5E_CPU0_PE0_RX_DN<6>")
	)
	(arc
		(start 338.247482 -215.761062)
		(mid 338.43468 -215.811205)
		(end 338.621878 -215.761062)
		(width 0.0889)
		(layer "In13.Cu")
		(net "P5E_CPU0_PE0_RX_DN<6>")
	)
	(arc
		(start 335.897982 -214.946992)
		(mid 336.08518 -214.997135)
		(end 336.272378 -214.946992)
		(width 0.0889)
		(layer "In13.Cu")
		(net "P5E_CPU0_PE0_RX_DN<6>")
	)
	(arc
		(start 341.537036 -218.202764)
		(mid 341.739859 -218.402995)
		(end 341.81923 -218.676728)
		(width 0.0889)
		(layer "In13.Cu")
		(net "P5E_CPU0_PE0_RX_DN<6>")
	)
	(arc
		(start 341.349584 -216.25052)
		(mid 341.397263 -216.43342)
		(end 341.528146 -216.569798)
		(width 0.0889)
		(layer "In13.Cu")
		(net "P5E_CPU0_PE0_RX_DN<6>")
	)
	(arc
		(start 340.501478 -215.761062)
		(mid 340.775677 -215.685227)
		(end 341.05215 -215.752426)
		(width 0.0889)
		(layer "In13.Cu")
		(net "P5E_CPU0_PE0_RX_DN<6>")
	)
	(arc
		(start 341.072978 -215.764618)
		(mid 341.275565 -215.970969)
		(end 341.349584 -216.25052)
		(width 0.0889)
		(layer "In13.Cu")
		(net "P5E_CPU0_PE0_RX_DN<6>")
	)
	(arc
		(start 341.537036 -216.574878)
		(mid 341.741371 -216.777483)
		(end 341.819484 -217.05443)
		(width 0.0889)
		(layer "In13.Cu")
		(net "P5E_CPU0_PE0_RX_DN<6>")
	)
	(arc
		(start 342.012778 -219.020136)
		(mid 342.215365 -219.226487)
		(end 342.289384 -219.506038)
		(width 0.0889)
		(layer "In13.Cu")
		(net "P5E_CPU0_PE0_RX_DN<6>")
	)
	(arc
		(start 336.272378 -214.946992)
		(mid 336.548937 -214.871283)
		(end 336.827114 -214.940896)
		(width 0.0889)
		(layer "In13.Cu")
		(net "P5E_CPU0_PE0_RX_DN<6>")
	)
	(arc
		(start 341.528146 -217.559128)
		(mid 341.400335 -217.690221)
		(end 341.349838 -217.866214)
		(width 0.0889)
		(layer "In13.Cu")
		(net "P5E_CPU0_PE0_RX_DN<6>")
	)
	(arc
		(start 335.343246 -214.940896)
		(mid 335.621424 -214.871204)
		(end 335.897982 -214.946992)
		(width 0.0889)
		(layer "In13.Cu")
		(net "P5E_CPU0_PE0_RX_DN<6>")
	)
	(arc
		(start 341.819484 -217.082878)
		(mid 341.739322 -217.355067)
		(end 341.537036 -217.554048)
		(width 0.0889)
		(layer "In13.Cu")
		(net "P5E_CPU0_PE0_RX_DN<6>")
	)
	(arc
		(start 334.67548 -214.871046)
		(mid 334.82195 -214.890406)
		(end 334.958436 -214.946992)
		(width 0.0889)
		(layer "In13.Cu")
		(net "P5E_CPU0_PE0_RX_DN<6>")
	)
	(arc
		(start 337.307682 -215.761062)
		(mid 337.49488 -215.811205)
		(end 337.682078 -215.761062)
		(width 0.0889)
		(layer "In13.Cu")
		(net "P5E_CPU0_PE0_RX_DN<6>")
	)
	(arc
		(start 342.289384 -219.506038)
		(mid 342.337063 -219.688938)
		(end 342.467946 -219.825316)
		(width 0.0889)
		(layer "In13.Cu")
		(net "P5E_CPU0_PE0_RX_DN<6>")
	)
	(arc
		(start 339.187282 -215.761062)
		(mid 339.37448 -215.811205)
		(end 339.561678 -215.761062)
		(width 0.0889)
		(layer "In13.Cu")
		(net "P5E_CPU0_PE0_RX_DN<6>")
	)
	(arc
		(start 340.127082 -215.761062)
		(mid 340.31428 -215.811205)
		(end 340.501478 -215.761062)
		(width 0.0889)
		(layer "In13.Cu")
		(net "P5E_CPU0_PE0_RX_DN<6>")
	)
	(arc
		(start 338.621878 -215.761062)
		(mid 338.896077 -215.685227)
		(end 339.17255 -215.752426)
		(width 0.0889)
		(layer "In13.Cu")
		(net "P5E_CPU0_PE0_RX_DN<6>")
	)
	(arc
		(start 342.482932 -219.833952)
		(mid 342.759246 -220.323446)
		(end 342.476836 -220.809566)
		(width 0.0889)
		(layer "In13.Cu")
		(net "P5E_CPU0_PE0_RX_DN<6>")
	)
	(arc
		(start 342.289638 -221.119192)
		(mid 342.289304 -221.131636)
		(end 342.289384 -221.144084)
		(width 0.0889)
		(layer "In13.Cu")
		(net "P5E_CPU0_PE0_RX_DN<6>")
	)
	(arc
		(start 342.467946 -220.814646)
		(mid 342.34061 -220.944581)
		(end 342.289638 -221.119192)
		(width 0.0889)
		(layer "In13.Cu")
		(net "P5E_CPU0_PE0_RX_DN<6>")
	)
	(arc
		(start 337.682078 -215.761062)
		(mid 337.956277 -215.685227)
		(end 338.23275 -215.752426)
		(width 0.0889)
		(layer "In13.Cu")
		(net "P5E_CPU0_PE0_RX_DN<6>")
	)
	(arc
		(start 339.561678 -215.761062)
		(mid 339.835877 -215.685227)
		(end 340.11235 -215.752426)
		(width 0.0889)
		(layer "In13.Cu")
		(net "P5E_CPU0_PE0_RX_DN<6>")
	)
	(arc
		(start 341.81923 -218.692222)
		(mid 341.866909 -218.875122)
		(end 341.997792 -219.0115)
		(width 0.0889)
		(layer "In13.Cu")
		(net "P5E_CPU0_PE0_RX_DN<6>")
	)
	(arc
		(start 334.958436 -214.946992)
		(mid 335.145634 -214.997135)
		(end 335.332832 -214.946992)
		(width 0.0889)
		(layer "In13.Cu")
		(net "P5E_CPU0_PE0_RX_DN<6>")
	)
	(arc
		(start 341.349838 -217.866214)
		(mid 341.349671 -217.87739)
		(end 341.349838 -217.888566)
		(width 0.0889)
		(layer "In13.Cu")
		(net "P5E_CPU0_PE0_RX_DN<6>")
	)
	(segment
		(start 342.194134 -220.855794)
		(end 342.194134 -220.320108)
		(width 0.13208)
		(layer "F.Cu")
		(net "P5E_CPU0_PE0_RX_DN<5>")
	)
	(segment
		(start 342.194134 -220.320108)
		(end 342.19388 -220.319854)
		(width 0.13208)
		(layer "F.Cu")
		(net "P5E_CPU0_PE0_RX_DN<5>")
	)
	(segment
		(start 341.057992 -219.0115)
		(end 341.066882 -219.01658)
		(width 0.0889)
		(layer "In13.Cu")
		(net "P5E_CPU0_PE0_RX_DN<5>")
	)
	(segment
		(start 340.597236 -216.574878)
		(end 340.603332 -216.578434)
		(width 0.0889)
		(layer "In13.Cu")
		(net "P5E_CPU0_PE0_RX_DN<5>")
	)
	(segment
		(start 326.464422 -288.310066)
		(end 325.081646 -266.592304)
		(width 0.14732)
		(layer "In13.Cu")
		(net "P5E_CPU0_PE0_RX_DN<5>")
	)
	(segment
		(start 325.787512 -258.748022)
		(end 325.81469 -258.678426)
		(width 0.14732)
		(layer "In13.Cu")
		(net "P5E_CPU0_PE0_RX_DN<5>")
	)
	(segment
		(start 332.509622 -216.57437)
		(end 332.763622 -216.49944)
		(width 0.0889)
		(layer "In13.Cu")
		(net "P5E_CPU0_PE0_RX_DN<5>")
	)
	(segment
		(start 334.01762 -216.574624)
		(end 334.040988 -216.588086)
		(width 0.0889)
		(layer "In13.Cu")
		(net "P5E_CPU0_PE0_RX_DN<5>")
	)
	(segment
		(start 334.692498 -424.632882)
		(end 337.784948 -411.09773)
		(width 0.14732)
		(layer "In13.Cu")
		(net "P5E_CPU0_PE0_RX_DN<5>")
	)
	(segment
		(start 337.784948 -406.141682)
		(end 336.438748 -404.795482)
		(width 0.14732)
		(layer "In13.Cu")
		(net "P5E_CPU0_PE0_RX_DN<5>")
	)
	(segment
		(start 326.456802 -233.126534)
		(end 327.601834 -222.047562)
		(width 0.14732)
		(layer "In13.Cu")
		(net "P5E_CPU0_PE0_RX_DN<5>")
	)
	(segment
		(start 341.959438 -220.6117)
		(end 342.037416 -220.590872)
		(width 0.0889)
		(layer "In13.Cu")
		(net "P5E_CPU0_PE0_RX_DN<5>")
	)
	(segment
		(start 335.650078 -437.741314)
		(end 335.502504 -437.59374)
		(width 0.14732)
		(layer "In13.Cu")
		(net "P5E_CPU0_PE0_RX_DN<5>")
	)
	(segment
		(start 336.438748 -404.795482)
		(end 336.438748 -400.235674)
		(width 0.14732)
		(layer "In13.Cu")
		(net "P5E_CPU0_PE0_RX_DN<5>")
	)
	(segment
		(start 337.784948 -411.09773)
		(end 337.784948 -406.141682)
		(width 0.14732)
		(layer "In13.Cu")
		(net "P5E_CPU0_PE0_RX_DN<5>")
	)
	(segment
		(start 327.847452 -310.027828)
		(end 326.464422 -288.310066)
		(width 0.14732)
		(layer "In13.Cu")
		(net "P5E_CPU0_PE0_RX_DN<5>")
	)
	(segment
		(start 340.031832 -216.574878)
		(end 340.046564 -216.566242)
		(width 0.0889)
		(layer "In13.Cu")
		(net "P5E_CPU0_PE0_RX_DN<5>")
	)
	(segment
		(start 312.293 -342.04529)
		(end 312.293 -333.36103)
		(width 0.14732)
		(layer "In13.Cu")
		(net "P5E_CPU0_PE0_RX_DN<5>")
	)
	(segment
		(start 326.701912 -246.54891)
		(end 326.456802 -233.126534)
		(width 0.14732)
		(layer "In13.Cu")
		(net "P5E_CPU0_PE0_RX_DN<5>")
	)
	(segment
		(start 312.293 -333.36103)
		(end 318.333628 -327.320402)
		(width 0.14732)
		(layer "In13.Cu")
		(net "P5E_CPU0_PE0_RX_DN<5>")
	)
	(segment
		(start 328.030332 -250.672854)
		(end 327.53173 -249.739912)
		(width 0.14732)
		(layer "In13.Cu")
		(net "P5E_CPU0_PE0_RX_DN<5>")
	)
	(segment
		(start 342.037416 -220.590872)
		(end 342.19388 -220.319854)
		(width 0.0889)
		(layer "In13.Cu")
		(net "P5E_CPU0_PE0_RX_DN<5>")
	)
	(segment
		(start 340.87943 -218.676728)
		(end 340.87943 -218.692222)
		(width 0.0889)
		(layer "In13.Cu")
		(net "P5E_CPU0_PE0_RX_DN<5>")
	)
	(segment
		(start 323.937376 -319.318132)
		(end 327.847452 -310.027828)
		(width 0.14732)
		(layer "In13.Cu")
		(net "P5E_CPU0_PE0_RX_DN<5>")
	)
	(segment
		(start 332.379066 -216.612978)
		(end 332.509622 -216.57437)
		(width 0.0889)
		(layer "In13.Cu")
		(net "P5E_CPU0_PE0_RX_DN<5>")
	)
	(segment
		(start 336.438748 -400.235674)
		(end 313.510168 -346.057728)
		(width 0.14732)
		(layer "In13.Cu")
		(net "P5E_CPU0_PE0_RX_DN<5>")
	)
	(segment
		(start 325.81723 -258.671314)
		(end 328.312018 -252.2728)
		(width 0.14732)
		(layer "In13.Cu")
		(net "P5E_CPU0_PE0_RX_DN<5>")
	)
	(segment
		(start 327.53173 -249.739912)
		(end 326.701912 -246.54891)
		(width 0.14732)
		(layer "In13.Cu")
		(net "P5E_CPU0_PE0_RX_DN<5>")
	)
	(segment
		(start 327.601834 -222.047562)
		(end 328.43343 -220.039184)
		(width 0.14732)
		(layer "In13.Cu")
		(net "P5E_CPU0_PE0_RX_DN<5>")
	)
	(segment
		(start 332.326996 -216.584276)
		(end 332.379066 -216.612978)
		(width 0.0889)
		(layer "In13.Cu")
		(net "P5E_CPU0_PE0_RX_DN<5>")
	)
	(segment
		(start 341.066882 -219.01658)
		(end 341.072978 -219.020136)
		(width 0.0889)
		(layer "In13.Cu")
		(net "P5E_CPU0_PE0_RX_DN<5>")
	)
	(segment
		(start 332.306168 -216.590118)
		(end 332.326996 -216.584276)
		(width 0.0889)
		(layer "In13.Cu")
		(net "P5E_CPU0_PE0_RX_DN<5>")
	)
	(segment
		(start 331.998574 -216.68105)
		(end 332.306168 -216.590372)
		(width 0.14732)
		(layer "In13.Cu")
		(net "P5E_CPU0_PE0_RX_DN<5>")
	)
	(segment
		(start 340.588346 -218.197684)
		(end 340.597236 -218.202764)
		(width 0.0889)
		(layer "In13.Cu")
		(net "P5E_CPU0_PE0_RX_DN<5>")
	)
	(segment
		(start 340.879684 -217.064336)
		(end 340.879684 -217.07856)
		(width 0.0889)
		(layer "In13.Cu")
		(net "P5E_CPU0_PE0_RX_DN<5>")
	)
	(segment
		(start 336.837528 -216.574878)
		(end 336.84591 -216.579704)
		(width 0.0889)
		(layer "In13.Cu")
		(net "P5E_CPU0_PE0_RX_DN<5>")
	)
	(segment
		(start 338.152232 -216.574878)
		(end 338.166964 -216.566242)
		(width 0.0889)
		(layer "In13.Cu")
		(net "P5E_CPU0_PE0_RX_DN<5>")
	)
	(segment
		(start 328.312018 -251.353066)
		(end 328.030332 -250.672854)
		(width 0.14732)
		(layer "In13.Cu")
		(net "P5E_CPU0_PE0_RX_DN<5>")
	)
	(segment
		(start 313.510168 -346.057728)
		(end 312.293 -342.04529)
		(width 0.14732)
		(layer "In13.Cu")
		(net "P5E_CPU0_PE0_RX_DN<5>")
	)
	(segment
		(start 341.819484 -220.309948)
		(end 341.819484 -220.32849)
		(width 0.0889)
		(layer "In13.Cu")
		(net "P5E_CPU0_PE0_RX_DN<5>")
	)
	(segment
		(start 325.081646 -266.592304)
		(end 325.787512 -258.748022)
		(width 0.14732)
		(layer "In13.Cu")
		(net "P5E_CPU0_PE0_RX_DN<5>")
	)
	(segment
		(start 333.993744 -216.560654)
		(end 334.01762 -216.574624)
		(width 0.0889)
		(layer "In13.Cu")
		(net "P5E_CPU0_PE0_RX_DN<5>")
	)
	(segment
		(start 334.9371 -216.562686)
		(end 334.957928 -216.574878)
		(width 0.0889)
		(layer "In13.Cu")
		(net "P5E_CPU0_PE0_RX_DN<5>")
	)
	(segment
		(start 335.882996 -216.566242)
		(end 335.897728 -216.574878)
		(width 0.0889)
		(layer "In13.Cu")
		(net "P5E_CPU0_PE0_RX_DN<5>")
	)
	(segment
		(start 328.43343 -220.039184)
		(end 329.69708 -218.622118)
		(width 0.14732)
		(layer "In13.Cu")
		(net "P5E_CPU0_PE0_RX_DN<5>")
	)
	(segment
		(start 337.767422 -216.568782)
		(end 337.777836 -216.574878)
		(width 0.0889)
		(layer "In13.Cu")
		(net "P5E_CPU0_PE0_RX_DN<5>")
	)
	(segment
		(start 336.822796 -216.566242)
		(end 336.837528 -216.574878)
		(width 0.0889)
		(layer "In13.Cu")
		(net "P5E_CPU0_PE0_RX_DN<5>")
	)
	(segment
		(start 318.333628 -327.320402)
		(end 323.937376 -319.318132)
		(width 0.14732)
		(layer "In13.Cu")
		(net "P5E_CPU0_PE0_RX_DN<5>")
	)
	(segment
		(start 334.992726 -437.59374)
		(end 334.692498 -437.293512)
		(width 0.14732)
		(layer "In13.Cu")
		(net "P5E_CPU0_PE0_RX_DN<5>")
	)
	(segment
		(start 325.81469 -258.678426)
		(end 325.81723 -258.671314)
		(width 0.14732)
		(layer "In13.Cu")
		(net "P5E_CPU0_PE0_RX_DN<5>")
	)
	(segment
		(start 332.306168 -216.590372)
		(end 332.306168 -216.590118)
		(width 0.0889)
		(layer "In13.Cu")
		(net "P5E_CPU0_PE0_RX_DN<5>")
	)
	(segment
		(start 328.312018 -252.2728)
		(end 328.312018 -251.353066)
		(width 0.14732)
		(layer "In13.Cu")
		(net "P5E_CPU0_PE0_RX_DN<5>")
	)
	(segment
		(start 329.69708 -218.622118)
		(end 331.998574 -216.68105)
		(width 0.14732)
		(layer "In13.Cu")
		(net "P5E_CPU0_PE0_RX_DN<5>")
	)
	(segment
		(start 335.650078 -438.089802)
		(end 335.650078 -437.741314)
		(width 0.14732)
		(layer "In13.Cu")
		(net "P5E_CPU0_PE0_RX_DN<5>")
	)
	(segment
		(start 341.528146 -219.825316)
		(end 341.537036 -219.830396)
		(width 0.0889)
		(layer "In13.Cu")
		(net "P5E_CPU0_PE0_RX_DN<5>")
	)
	(segment
		(start 335.502504 -437.59374)
		(end 334.992726 -437.59374)
		(width 0.14732)
		(layer "In13.Cu")
		(net "P5E_CPU0_PE0_RX_DN<5>")
	)
	(segment
		(start 333.076804 -216.574878)
		(end 333.091282 -216.58326)
		(width 0.0889)
		(layer "In13.Cu")
		(net "P5E_CPU0_PE0_RX_DN<5>")
	)
	(segment
		(start 334.692498 -437.293512)
		(end 334.692498 -424.632882)
		(width 0.14732)
		(layer "In13.Cu")
		(net "P5E_CPU0_PE0_RX_DN<5>")
	)
	(segment
		(start 340.597236 -217.554048)
		(end 340.588346 -217.559128)
		(width 0.0889)
		(layer "In13.Cu")
		(net "P5E_CPU0_PE0_RX_DN<5>")
	)
	(arc
		(start 334.957928 -216.574878)
		(mid 335.145126 -216.625021)
		(end 335.332324 -216.574878)
		(width 0.0889)
		(layer "In13.Cu")
		(net "P5E_CPU0_PE0_RX_DN<5>")
	)
	(arc
		(start 340.879684 -217.07856)
		(mid 340.800543 -217.353183)
		(end 340.597236 -217.554048)
		(width 0.0889)
		(layer "In13.Cu")
		(net "P5E_CPU0_PE0_RX_DN<5>")
	)
	(arc
		(start 332.851252 -216.501726)
		(mid 332.967898 -216.526364)
		(end 333.076804 -216.574878)
		(width 0.0889)
		(layer "In13.Cu")
		(net "P5E_CPU0_PE0_RX_DN<5>")
	)
	(arc
		(start 340.87943 -218.692222)
		(mid 340.927109 -218.875122)
		(end 341.057992 -219.0115)
		(width 0.0889)
		(layer "In13.Cu")
		(net "P5E_CPU0_PE0_RX_DN<5>")
	)
	(arc
		(start 334.392016 -216.574878)
		(mid 334.663003 -216.498736)
		(end 334.9371 -216.562686)
		(width 0.0889)
		(layer "In13.Cu")
		(net "P5E_CPU0_PE0_RX_DN<5>")
	)
	(arc
		(start 340.409784 -217.878406)
		(mid 340.457463 -218.061306)
		(end 340.588346 -218.197684)
		(width 0.0889)
		(layer "In13.Cu")
		(net "P5E_CPU0_PE0_RX_DN<5>")
	)
	(arc
		(start 338.717636 -216.574878)
		(mid 338.904834 -216.625021)
		(end 339.092032 -216.574878)
		(width 0.0889)
		(layer "In13.Cu")
		(net "P5E_CPU0_PE0_RX_DN<5>")
	)
	(arc
		(start 336.272124 -216.574878)
		(mid 336.546323 -216.499043)
		(end 336.822796 -216.566242)
		(width 0.0889)
		(layer "In13.Cu")
		(net "P5E_CPU0_PE0_RX_DN<5>")
	)
	(arc
		(start 338.166964 -216.566242)
		(mid 338.443439 -216.498922)
		(end 338.717636 -216.574878)
		(width 0.0889)
		(layer "In13.Cu")
		(net "P5E_CPU0_PE0_RX_DN<5>")
	)
	(arc
		(start 337.212178 -216.574878)
		(mid 337.488991 -216.499008)
		(end 337.767422 -216.568782)
		(width 0.0889)
		(layer "In13.Cu")
		(net "P5E_CPU0_PE0_RX_DN<5>")
	)
	(arc
		(start 340.588346 -217.559128)
		(mid 340.461092 -217.689094)
		(end 340.410038 -217.863674)
		(width 0.0889)
		(layer "In13.Cu")
		(net "P5E_CPU0_PE0_RX_DN<5>")
	)
	(arc
		(start 340.410038 -217.863674)
		(mid 340.409841 -217.871039)
		(end 340.409784 -217.878406)
		(width 0.0889)
		(layer "In13.Cu")
		(net "P5E_CPU0_PE0_RX_DN<5>")
	)
	(arc
		(start 332.763622 -216.49944)
		(mid 332.807482 -216.498875)
		(end 332.851252 -216.501726)
		(width 0.0889)
		(layer "In13.Cu")
		(net "P5E_CPU0_PE0_RX_DN<5>")
	)
	(arc
		(start 333.091282 -216.58326)
		(mid 333.272699 -216.625317)
		(end 333.451962 -216.574878)
		(width 0.0889)
		(layer "In13.Cu")
		(net "P5E_CPU0_PE0_RX_DN<5>")
	)
	(arc
		(start 337.777836 -216.574878)
		(mid 337.965034 -216.625021)
		(end 338.152232 -216.574878)
		(width 0.0889)
		(layer "In13.Cu")
		(net "P5E_CPU0_PE0_RX_DN<5>")
	)
	(arc
		(start 336.84591 -216.579704)
		(mid 337.029672 -216.625104)
		(end 337.212178 -216.574878)
		(width 0.0889)
		(layer "In13.Cu")
		(net "P5E_CPU0_PE0_RX_DN<5>")
	)
	(arc
		(start 339.092032 -216.574878)
		(mid 339.374734 -216.499102)
		(end 339.657436 -216.574878)
		(width 0.0889)
		(layer "In13.Cu")
		(net "P5E_CPU0_PE0_RX_DN<5>")
	)
	(arc
		(start 335.332324 -216.574878)
		(mid 335.606523 -216.499043)
		(end 335.882996 -216.566242)
		(width 0.0889)
		(layer "In13.Cu")
		(net "P5E_CPU0_PE0_RX_DN<5>")
	)
	(arc
		(start 341.072978 -219.020136)
		(mid 341.275565 -219.226487)
		(end 341.349584 -219.506038)
		(width 0.0889)
		(layer "In13.Cu")
		(net "P5E_CPU0_PE0_RX_DN<5>")
	)
	(arc
		(start 334.040988 -216.588086)
		(mid 334.218146 -216.625144)
		(end 334.392016 -216.574878)
		(width 0.0889)
		(layer "In13.Cu")
		(net "P5E_CPU0_PE0_RX_DN<5>")
	)
	(arc
		(start 339.657436 -216.574878)
		(mid 339.844634 -216.625021)
		(end 340.031832 -216.574878)
		(width 0.0889)
		(layer "In13.Cu")
		(net "P5E_CPU0_PE0_RX_DN<5>")
	)
	(arc
		(start 340.046564 -216.566242)
		(mid 340.323039 -216.498922)
		(end 340.597236 -216.574878)
		(width 0.0889)
		(layer "In13.Cu")
		(net "P5E_CPU0_PE0_RX_DN<5>")
	)
	(arc
		(start 340.597236 -218.202764)
		(mid 340.800059 -218.402995)
		(end 340.87943 -218.676728)
		(width 0.0889)
		(layer "In13.Cu")
		(net "P5E_CPU0_PE0_RX_DN<5>")
	)
	(arc
		(start 341.819484 -220.32849)
		(mid 341.858158 -220.485558)
		(end 341.959438 -220.6117)
		(width 0.0889)
		(layer "In13.Cu")
		(net "P5E_CPU0_PE0_RX_DN<5>")
	)
	(arc
		(start 335.897728 -216.574878)
		(mid 336.084926 -216.625021)
		(end 336.272124 -216.574878)
		(width 0.0889)
		(layer "In13.Cu")
		(net "P5E_CPU0_PE0_RX_DN<5>")
	)
	(arc
		(start 340.603332 -216.578434)
		(mid 340.805745 -216.784847)
		(end 340.879684 -217.064336)
		(width 0.0889)
		(layer "In13.Cu")
		(net "P5E_CPU0_PE0_RX_DN<5>")
	)
	(arc
		(start 333.451962 -216.574878)
		(mid 333.721044 -216.498662)
		(end 333.993744 -216.560654)
		(width 0.0889)
		(layer "In13.Cu")
		(net "P5E_CPU0_PE0_RX_DN<5>")
	)
	(arc
		(start 341.537036 -219.830396)
		(mid 341.741371 -220.033001)
		(end 341.819484 -220.309948)
		(width 0.0889)
		(layer "In13.Cu")
		(net "P5E_CPU0_PE0_RX_DN<5>")
	)
	(arc
		(start 341.349584 -219.506038)
		(mid 341.397263 -219.688938)
		(end 341.528146 -219.825316)
		(width 0.0889)
		(layer "In13.Cu")
		(net "P5E_CPU0_PE0_RX_DN<5>")
	)
	(segment
		(start 340.78418 -221.669864)
		(end 340.78418 -221.134178)
		(width 0.13208)
		(layer "F.Cu")
		(net "P5E_CPU0_PE0_RX_DN<4>")
	)
	(segment
		(start 340.78418 -221.134178)
		(end 340.784434 -221.133924)
		(width 0.13208)
		(layer "F.Cu")
		(net "P5E_CPU0_PE0_RX_DN<4>")
	)
	(segment
		(start 330.858114 -219.029534)
		(end 330.88707 -218.859608)
		(width 0.14732)
		(layer "In13.Cu")
		(net "P5E_CPU0_PE0_RX_DN<4>")
	)
	(segment
		(start 336.977482 -438.593738)
		(end 336.692494 -438.30875)
		(width 0.14732)
		(layer "In13.Cu")
		(net "P5E_CPU0_PE0_RX_DN<4>")
	)
	(segment
		(start 337.590384 -217.859864)
		(end 337.590384 -217.878406)
		(width 0.0889)
		(layer "In13.Cu")
		(net "P5E_CPU0_PE0_RX_DN<4>")
	)
	(segment
		(start 332.698852 -217.590624)
		(end 332.714346 -217.57513)
		(width 0.0889)
		(layer "In13.Cu")
		(net "P5E_CPU0_PE0_RX_DN<4>")
	)
	(segment
		(start 327.675748 -246.583962)
		(end 327.435464 -233.439208)
		(width 0.14732)
		(layer "In13.Cu")
		(net "P5E_CPU0_PE0_RX_DN<4>")
	)
	(segment
		(start 337.650074 -438.741312)
		(end 337.5025 -438.593738)
		(width 0.14732)
		(layer "In13.Cu")
		(net "P5E_CPU0_PE0_RX_DN<4>")
	)
	(segment
		(start 336.35315 -217.380058)
		(end 336.367882 -217.388694)
		(width 0.0889)
		(layer "In13.Cu")
		(net "P5E_CPU0_PE0_RX_DN<4>")
	)
	(segment
		(start 326.707754 -258.963922)
		(end 329.2475 -252.448568)
		(width 0.14732)
		(layer "In13.Cu")
		(net "P5E_CPU0_PE0_RX_DN<4>")
	)
	(segment
		(start 339.501988 -404.795482)
		(end 339.501988 -400.127978)
		(width 0.14732)
		(layer "In13.Cu")
		(net "P5E_CPU0_PE0_RX_DN<4>")
	)
	(segment
		(start 334.862678 -217.388694)
		(end 334.87741 -217.380058)
		(width 0.0889)
		(layer "In13.Cu")
		(net "P5E_CPU0_PE0_RX_DN<4>")
	)
	(segment
		(start 338.153756 -218.202002)
		(end 338.161122 -218.197684)
		(width 0.0889)
		(layer "In13.Cu")
		(net "P5E_CPU0_PE0_RX_DN<4>")
	)
	(segment
		(start 313.22264 -333.80807)
		(end 319.129664 -327.900792)
		(width 0.14732)
		(layer "In13.Cu")
		(net "P5E_CPU0_PE0_RX_DN<4>")
	)
	(segment
		(start 329.2475 -251.181362)
		(end 328.869802 -250.27001)
		(width 0.14732)
		(layer "In13.Cu")
		(net "P5E_CPU0_PE0_RX_DN<4>")
	)
	(segment
		(start 340.597236 -220.809566)
		(end 340.59622 -220.810074)
		(width 0.0889)
		(layer "In13.Cu")
		(net "P5E_CPU0_PE0_RX_DN<4>")
	)
	(segment
		(start 340.919816 -221.48292)
		(end 340.940898 -221.404942)
		(width 0.0889)
		(layer "In13.Cu")
		(net "P5E_CPU0_PE0_RX_DN<4>")
	)
	(segment
		(start 340.940898 -221.404942)
		(end 340.784434 -221.133924)
		(width 0.0889)
		(layer "In13.Cu")
		(net "P5E_CPU0_PE0_RX_DN<4>")
	)
	(segment
		(start 339.648546 -218.197684)
		(end 339.657436 -218.202764)
		(width 0.0889)
		(layer "In13.Cu")
		(net "P5E_CPU0_PE0_RX_DN<4>")
	)
	(segment
		(start 327.435464 -233.439208)
		(end 328.55154 -222.240856)
		(width 0.14732)
		(layer "In13.Cu")
		(net "P5E_CPU0_PE0_RX_DN<4>")
	)
	(segment
		(start 340.588346 -219.825316)
		(end 340.597236 -219.830396)
		(width 0.0889)
		(layer "In13.Cu")
		(net "P5E_CPU0_PE0_RX_DN<4>")
	)
	(segment
		(start 340.59622 -220.810074)
		(end 340.588346 -220.814646)
		(width 0.0889)
		(layer "In13.Cu")
		(net "P5E_CPU0_PE0_RX_DN<4>")
	)
	(segment
		(start 338.339684 -217.878406)
		(end 338.339684 -217.856308)
		(width 0.0889)
		(layer "In13.Cu")
		(net "P5E_CPU0_PE0_RX_DN<4>")
	)
	(segment
		(start 332.714346 -217.57513)
		(end 332.773274 -217.57513)
		(width 0.0889)
		(layer "In13.Cu")
		(net "P5E_CPU0_PE0_RX_DN<4>")
	)
	(segment
		(start 328.412602 -249.414538)
		(end 327.675748 -246.583962)
		(width 0.14732)
		(layer "In13.Cu")
		(net "P5E_CPU0_PE0_RX_DN<4>")
	)
	(segment
		(start 340.118192 -219.0115)
		(end 340.133178 -219.020136)
		(width 0.0889)
		(layer "In13.Cu")
		(net "P5E_CPU0_PE0_RX_DN<4>")
	)
	(segment
		(start 329.2475 -252.448568)
		(end 329.2475 -251.181362)
		(width 0.14732)
		(layer "In13.Cu")
		(net "P5E_CPU0_PE0_RX_DN<4>")
	)
	(segment
		(start 326.020176 -266.604496)
		(end 326.707754 -258.963922)
		(width 0.14732)
		(layer "In13.Cu")
		(net "P5E_CPU0_PE0_RX_DN<4>")
	)
	(segment
		(start 340.848188 -406.141682)
		(end 339.501988 -404.795482)
		(width 0.14732)
		(layer "In13.Cu")
		(net "P5E_CPU0_PE0_RX_DN<4>")
	)
	(segment
		(start 330.450698 -219.31757)
		(end 330.858114 -219.029534)
		(width 0.14732)
		(layer "In13.Cu")
		(net "P5E_CPU0_PE0_RX_DN<4>")
	)
	(segment
		(start 340.597236 -219.830396)
		(end 340.603332 -219.833952)
		(width 0.0889)
		(layer "In13.Cu")
		(net "P5E_CPU0_PE0_RX_DN<4>")
	)
	(segment
		(start 332.773274 -217.57513)
		(end 332.86954 -217.478864)
		(width 0.0889)
		(layer "In13.Cu")
		(net "P5E_CPU0_PE0_RX_DN<4>")
	)
	(segment
		(start 324.765924 -319.852548)
		(end 328.800206 -310.267096)
		(width 0.14732)
		(layer "In13.Cu")
		(net "P5E_CPU0_PE0_RX_DN<4>")
	)
	(segment
		(start 332.230476 -218.059)
		(end 332.698852 -217.590624)
		(width 0.14732)
		(layer "In13.Cu")
		(net "P5E_CPU0_PE0_RX_DN<4>")
	)
	(segment
		(start 319.129664 -327.900792)
		(end 324.765924 -319.852548)
		(width 0.14732)
		(layer "In13.Cu")
		(net "P5E_CPU0_PE0_RX_DN<4>")
	)
	(segment
		(start 328.55154 -222.240856)
		(end 329.221846 -220.62313)
		(width 0.14732)
		(layer "In13.Cu")
		(net "P5E_CPU0_PE0_RX_DN<4>")
	)
	(segment
		(start 336.692494 -424.501564)
		(end 340.848188 -410.85516)
		(width 0.14732)
		(layer "In13.Cu")
		(net "P5E_CPU0_PE0_RX_DN<4>")
	)
	(segment
		(start 330.88707 -218.859608)
		(end 331.244194 -218.607132)
		(width 0.14732)
		(layer "In13.Cu")
		(net "P5E_CPU0_PE0_RX_DN<4>")
	)
	(segment
		(start 314.275978 -345.239086)
		(end 313.22264 -341.251286)
		(width 0.14732)
		(layer "In13.Cu")
		(net "P5E_CPU0_PE0_RX_DN<4>")
	)
	(segment
		(start 331.244194 -218.607132)
		(end 331.41412 -218.636342)
		(width 0.14732)
		(layer "In13.Cu")
		(net "P5E_CPU0_PE0_RX_DN<4>")
	)
	(segment
		(start 313.22264 -341.251286)
		(end 313.22264 -333.80807)
		(width 0.14732)
		(layer "In13.Cu")
		(net "P5E_CPU0_PE0_RX_DN<4>")
	)
	(segment
		(start 339.469984 -217.859864)
		(end 339.469984 -217.878406)
		(width 0.0889)
		(layer "In13.Cu")
		(net "P5E_CPU0_PE0_RX_DN<4>")
	)
	(segment
		(start 339.93963 -218.676728)
		(end 339.93963 -218.692222)
		(width 0.0889)
		(layer "In13.Cu")
		(net "P5E_CPU0_PE0_RX_DN<4>")
	)
	(segment
		(start 331.41412 -218.636342)
		(end 332.230476 -218.059)
		(width 0.14732)
		(layer "In13.Cu")
		(net "P5E_CPU0_PE0_RX_DN<4>")
	)
	(segment
		(start 337.5025 -438.593738)
		(end 336.977482 -438.593738)
		(width 0.14732)
		(layer "In13.Cu")
		(net "P5E_CPU0_PE0_RX_DN<4>")
	)
	(segment
		(start 328.869802 -250.27001)
		(end 328.412602 -249.414538)
		(width 0.14732)
		(layer "In13.Cu")
		(net "P5E_CPU0_PE0_RX_DN<4>")
	)
	(segment
		(start 339.501988 -400.127978)
		(end 314.275978 -345.239086)
		(width 0.14732)
		(layer "In13.Cu")
		(net "P5E_CPU0_PE0_RX_DN<4>")
	)
	(segment
		(start 329.221846 -220.62313)
		(end 330.450698 -219.31757)
		(width 0.14732)
		(layer "In13.Cu")
		(net "P5E_CPU0_PE0_RX_DN<4>")
	)
	(segment
		(start 340.848188 -410.85516)
		(end 340.848188 -406.141682)
		(width 0.14732)
		(layer "In13.Cu")
		(net "P5E_CPU0_PE0_RX_DN<4>")
	)
	(segment
		(start 336.692494 -438.30875)
		(end 336.692494 -424.501564)
		(width 0.14732)
		(layer "In13.Cu")
		(net "P5E_CPU0_PE0_RX_DN<4>")
	)
	(segment
		(start 338.152232 -218.202764)
		(end 338.153756 -218.202002)
		(width 0.0889)
		(layer "In13.Cu")
		(net "P5E_CPU0_PE0_RX_DN<4>")
	)
	(segment
		(start 337.650074 -439.0898)
		(end 337.650074 -438.741312)
		(width 0.14732)
		(layer "In13.Cu")
		(net "P5E_CPU0_PE0_RX_DN<4>")
	)
	(segment
		(start 328.800206 -310.267096)
		(end 326.020176 -266.604496)
		(width 0.14732)
		(layer "In13.Cu")
		(net "P5E_CPU0_PE0_RX_DN<4>")
	)
	(arc
		(start 338.161122 -218.197684)
		(mid 338.292036 -218.061324)
		(end 338.339684 -217.878406)
		(width 0.0889)
		(layer "In13.Cu")
		(net "P5E_CPU0_PE0_RX_DN<4>")
	)
	(arc
		(start 340.409784 -219.506038)
		(mid 340.457463 -219.688938)
		(end 340.588346 -219.825316)
		(width 0.0889)
		(layer "In13.Cu")
		(net "P5E_CPU0_PE0_RX_DN<4>")
	)
	(arc
		(start 333.548482 -217.388694)
		(mid 333.73568 -217.438837)
		(end 333.922878 -217.388694)
		(width 0.0889)
		(layer "In13.Cu")
		(net "P5E_CPU0_PE0_RX_DN<4>")
	)
	(arc
		(start 335.428082 -217.388694)
		(mid 335.61528 -217.438837)
		(end 335.802478 -217.388694)
		(width 0.0889)
		(layer "In13.Cu")
		(net "P5E_CPU0_PE0_RX_DN<4>")
	)
	(arc
		(start 340.133178 -219.020136)
		(mid 340.335765 -219.226487)
		(end 340.409784 -219.506038)
		(width 0.0889)
		(layer "In13.Cu")
		(net "P5E_CPU0_PE0_RX_DN<4>")
	)
	(arc
		(start 340.603332 -219.833952)
		(mid 340.879646 -220.323446)
		(end 340.597236 -220.809566)
		(width 0.0889)
		(layer "In13.Cu")
		(net "P5E_CPU0_PE0_RX_DN<4>")
	)
	(arc
		(start 339.657436 -218.202764)
		(mid 339.860259 -218.402995)
		(end 339.93963 -218.676728)
		(width 0.0889)
		(layer "In13.Cu")
		(net "P5E_CPU0_PE0_RX_DN<4>")
	)
	(arc
		(start 338.339684 -217.856308)
		(mid 338.906611 -217.312339)
		(end 339.469984 -217.859864)
		(width 0.0889)
		(layer "In13.Cu")
		(net "P5E_CPU0_PE0_RX_DN<4>")
	)
	(arc
		(start 332.983078 -217.388694)
		(mid 333.26578 -217.312952)
		(end 333.548482 -217.388694)
		(width 0.0889)
		(layer "In13.Cu")
		(net "P5E_CPU0_PE0_RX_DN<4>")
	)
	(arc
		(start 335.802478 -217.388694)
		(mid 336.076707 -217.312769)
		(end 336.35315 -217.380058)
		(width 0.0889)
		(layer "In13.Cu")
		(net "P5E_CPU0_PE0_RX_DN<4>")
	)
	(arc
		(start 339.469984 -217.878406)
		(mid 339.517663 -218.061306)
		(end 339.648546 -218.197684)
		(width 0.0889)
		(layer "In13.Cu")
		(net "P5E_CPU0_PE0_RX_DN<4>")
	)
	(arc
		(start 336.367882 -217.388694)
		(mid 336.55508 -217.438837)
		(end 336.742278 -217.388694)
		(width 0.0889)
		(layer "In13.Cu")
		(net "P5E_CPU0_PE0_RX_DN<4>")
	)
	(arc
		(start 340.410038 -221.119192)
		(mid 340.409704 -221.131636)
		(end 340.409784 -221.144084)
		(width 0.0889)
		(layer "In13.Cu")
		(net "P5E_CPU0_PE0_RX_DN<4>")
	)
	(arc
		(start 339.93963 -218.692222)
		(mid 339.987309 -218.875122)
		(end 340.118192 -219.0115)
		(width 0.0889)
		(layer "In13.Cu")
		(net "P5E_CPU0_PE0_RX_DN<4>")
	)
	(arc
		(start 340.409784 -221.144084)
		(mid 340.576972 -221.445809)
		(end 340.919816 -221.48292)
		(width 0.0889)
		(layer "In13.Cu")
		(net "P5E_CPU0_PE0_RX_DN<4>")
	)
	(arc
		(start 334.488282 -217.388694)
		(mid 334.67548 -217.438837)
		(end 334.862678 -217.388694)
		(width 0.0889)
		(layer "In13.Cu")
		(net "P5E_CPU0_PE0_RX_DN<4>")
	)
	(arc
		(start 334.87741 -217.380058)
		(mid 335.153851 -217.312892)
		(end 335.428082 -217.388694)
		(width 0.0889)
		(layer "In13.Cu")
		(net "P5E_CPU0_PE0_RX_DN<4>")
	)
	(arc
		(start 333.922878 -217.388694)
		(mid 334.20558 -217.312952)
		(end 334.488282 -217.388694)
		(width 0.0889)
		(layer "In13.Cu")
		(net "P5E_CPU0_PE0_RX_DN<4>")
	)
	(arc
		(start 332.86954 -217.478864)
		(mid 332.923714 -217.430512)
		(end 332.983078 -217.388694)
		(width 0.0889)
		(layer "In13.Cu")
		(net "P5E_CPU0_PE0_RX_DN<4>")
	)
	(arc
		(start 337.590384 -217.878406)
		(mid 337.777683 -218.202847)
		(end 338.152232 -218.202764)
		(width 0.0889)
		(layer "In13.Cu")
		(net "P5E_CPU0_PE0_RX_DN<4>")
	)
	(arc
		(start 336.742278 -217.388694)
		(mid 337.299871 -217.383981)
		(end 337.590384 -217.859864)
		(width 0.0889)
		(layer "In13.Cu")
		(net "P5E_CPU0_PE0_RX_DN<4>")
	)
	(arc
		(start 340.588346 -220.814646)
		(mid 340.46101 -220.944581)
		(end 340.410038 -221.119192)
		(width 0.0889)
		(layer "In13.Cu")
		(net "P5E_CPU0_PE0_RX_DN<4>")
	)
	(segment
		(start 339.84438 -221.669864)
		(end 339.84438 -221.134178)
		(width 0.13208)
		(layer "F.Cu")
		(net "P5E_CPU0_PE0_RX_DN<3>")
	)
	(segment
		(start 339.84438 -221.134178)
		(end 339.844634 -221.133924)
		(width 0.13208)
		(layer "F.Cu")
		(net "P5E_CPU0_PE0_RX_DN<3>")
	)
	(segment
		(start 314.4266 -334.334358)
		(end 314.4266 -341.04707)
		(width 0.14732)
		(layer "In13.Cu")
		(net "P5E_CPU0_PE0_RX_DN<3>")
	)
	(segment
		(start 329.746102 -222.522796)
		(end 328.669904 -233.612436)
		(width 0.14732)
		(layer "In13.Cu")
		(net "P5E_CPU0_PE0_RX_DN<3>")
	)
	(segment
		(start 334.675988 -219.257372)
		(end 333.56296 -219.363544)
		(width 0.0889)
		(layer "In13.Cu")
		(net "P5E_CPU0_PE0_RX_DN<3>")
	)
	(segment
		(start 333.336646 -219.511118)
		(end 333.31658 -219.520008)
		(width 0.0889)
		(layer "In13.Cu")
		(net "P5E_CPU0_PE0_RX_DN<3>")
	)
	(segment
		(start 343.435686 -413.084772)
		(end 343.305892 -413.429704)
		(width 0.14732)
		(layer "In13.Cu")
		(net "P5E_CPU0_PE0_RX_DN<3>")
	)
	(segment
		(start 330.029566 -310.548528)
		(end 325.80199 -320.592704)
		(width 0.14732)
		(layer "In13.Cu")
		(net "P5E_CPU0_PE0_RX_DN<3>")
	)
	(segment
		(start 341.092282 -418.909246)
		(end 341.091012 -418.913056)
		(width 0.14732)
		(layer "In13.Cu")
		(net "P5E_CPU0_PE0_RX_DN<3>")
	)
	(segment
		(start 343.305892 -413.429704)
		(end 343.125552 -413.511238)
		(width 0.14732)
		(layer "In13.Cu")
		(net "P5E_CPU0_PE0_RX_DN<3>")
	)
	(segment
		(start 340.509098 -420.457884)
		(end 340.508844 -420.458646)
		(width 0.14732)
		(layer "In13.Cu")
		(net "P5E_CPU0_PE0_RX_DN<3>")
	)
	(segment
		(start 342.563196 -415.005012)
		(end 342.433402 -415.349436)
		(width 0.14732)
		(layer "In13.Cu")
		(net "P5E_CPU0_PE0_RX_DN<3>")
	)
	(segment
		(start 328.669904 -233.612436)
		(end 328.888344 -245.024148)
		(width 0.14732)
		(layer "In13.Cu")
		(net "P5E_CPU0_PE0_RX_DN<3>")
	)
	(segment
		(start 329.95743 -249.748548)
		(end 330.456286 -250.952762)
		(width 0.14732)
		(layer "In13.Cu")
		(net "P5E_CPU0_PE0_RX_DN<3>")
	)
	(segment
		(start 327.233026 -266.620244)
		(end 330.029566 -310.548528)
		(width 0.14732)
		(layer "In13.Cu")
		(net "P5E_CPU0_PE0_RX_DN<3>")
	)
	(segment
		(start 339.094318 -437.31942)
		(end 339.482938 -437.31942)
		(width 0.14732)
		(layer "In13.Cu")
		(net "P5E_CPU0_PE0_RX_DN<3>")
	)
	(segment
		(start 340.22919 -421.201088)
		(end 340.310724 -421.381174)
		(width 0.14732)
		(layer "In13.Cu")
		(net "P5E_CPU0_PE0_RX_DN<3>")
	)
	(segment
		(start 340.310724 -421.381174)
		(end 340.18093 -421.726106)
		(width 0.14732)
		(layer "In13.Cu")
		(net "P5E_CPU0_PE0_RX_DN<3>")
	)
	(segment
		(start 342.385142 -415.874454)
		(end 342.204802 -415.955734)
		(width 0.14732)
		(layer "In13.Cu")
		(net "P5E_CPU0_PE0_RX_DN<3>")
	)
	(segment
		(start 340.737444 -419.851586)
		(end 340.818978 -420.031672)
		(width 0.14732)
		(layer "In13.Cu")
		(net "P5E_CPU0_PE0_RX_DN<3>")
	)
	(segment
		(start 335.3435 -219.187776)
		(end 335.333086 -219.18168)
		(width 0.0889)
		(layer "In13.Cu")
		(net "P5E_CPU0_PE0_RX_DN<3>")
	)
	(segment
		(start 342.028526 -416.42411)
		(end 342.028272 -416.424872)
		(width 0.14732)
		(layer "In13.Cu")
		(net "P5E_CPU0_PE0_RX_DN<3>")
	)
	(segment
		(start 341.799672 -417.031424)
		(end 341.320882 -418.302694)
		(width 0.14732)
		(layer "In13.Cu")
		(net "P5E_CPU0_PE0_RX_DN<3>")
	)
	(segment
		(start 339.82787 -422.66362)
		(end 339.698076 -423.008552)
		(width 0.14732)
		(layer "In13.Cu")
		(net "P5E_CPU0_PE0_RX_DN<3>")
	)
	(segment
		(start 342.028272 -416.424872)
		(end 342.109806 -416.604958)
		(width 0.14732)
		(layer "In13.Cu")
		(net "P5E_CPU0_PE0_RX_DN<3>")
	)
	(segment
		(start 338.166964 -219.190316)
		(end 338.152232 -219.18168)
		(width 0.0889)
		(layer "In13.Cu")
		(net "P5E_CPU0_PE0_RX_DN<3>")
	)
	(segment
		(start 315.328808 -344.489532)
		(end 342.839548 -399.950432)
		(width 0.14732)
		(layer "In13.Cu")
		(net "P5E_CPU0_PE0_RX_DN<3>")
	)
	(segment
		(start 340.508844 -420.458646)
		(end 340.22919 -421.201088)
		(width 0.14732)
		(layer "In13.Cu")
		(net "P5E_CPU0_PE0_RX_DN<3>")
	)
	(segment
		(start 341.320882 -418.302694)
		(end 341.402416 -418.48278)
		(width 0.14732)
		(layer "In13.Cu")
		(net "P5E_CPU0_PE0_RX_DN<3>")
	)
	(segment
		(start 340.18093 -421.726106)
		(end 340.000844 -421.80764)
		(width 0.14732)
		(layer "In13.Cu")
		(net "P5E_CPU0_PE0_RX_DN<3>")
	)
	(segment
		(start 339.746336 -422.483534)
		(end 339.82787 -422.66362)
		(width 0.14732)
		(layer "In13.Cu")
		(net "P5E_CPU0_PE0_RX_DN<3>")
	)
	(segment
		(start 344.185748 -406.02789)
		(end 344.185748 -410.696918)
		(width 0.14732)
		(layer "In13.Cu")
		(net "P5E_CPU0_PE0_RX_DN<3>")
	)
	(segment
		(start 340.689184 -420.37635)
		(end 340.509098 -420.457884)
		(width 0.14732)
		(layer "In13.Cu")
		(net "P5E_CPU0_PE0_RX_DN<3>")
	)
	(segment
		(start 342.433402 -415.349436)
		(end 342.514936 -415.529522)
		(width 0.14732)
		(layer "In13.Cu")
		(net "P5E_CPU0_PE0_RX_DN<3>")
	)
	(segment
		(start 342.109806 -416.604958)
		(end 341.980012 -416.94989)
		(width 0.14732)
		(layer "In13.Cu")
		(net "P5E_CPU0_PE0_RX_DN<3>")
	)
	(segment
		(start 327.898506 -259.231384)
		(end 327.233026 -266.620244)
		(width 0.14732)
		(layer "In13.Cu")
		(net "P5E_CPU0_PE0_RX_DN<3>")
	)
	(segment
		(start 337.227164 -219.190316)
		(end 337.212432 -219.18168)
		(width 0.0889)
		(layer "In13.Cu")
		(net "P5E_CPU0_PE0_RX_DN<3>")
	)
	(segment
		(start 331.13726 -220.495368)
		(end 330.21778 -221.384368)
		(width 0.14732)
		(layer "In13.Cu")
		(net "P5E_CPU0_PE0_RX_DN<3>")
	)
	(segment
		(start 339.844634 -221.133924)
		(end 340.001098 -220.862906)
		(width 0.0889)
		(layer "In13.Cu")
		(net "P5E_CPU0_PE0_RX_DN<3>")
	)
	(segment
		(start 342.743282 -414.923478)
		(end 342.563196 -415.005012)
		(width 0.14732)
		(layer "In13.Cu")
		(net "P5E_CPU0_PE0_RX_DN<3>")
	)
	(segment
		(start 333.56296 -219.363544)
		(end 333.357728 -219.455492)
		(width 0.0889)
		(layer "In13.Cu")
		(net "P5E_CPU0_PE0_RX_DN<3>")
	)
	(segment
		(start 339.74913 -220.334078)
		(end 339.74913 -220.311218)
		(width 0.0889)
		(layer "In13.Cu")
		(net "P5E_CPU0_PE0_RX_DN<3>")
	)
	(segment
		(start 342.791542 -414.39846)
		(end 342.873076 -414.578546)
		(width 0.14732)
		(layer "In13.Cu")
		(net "P5E_CPU0_PE0_RX_DN<3>")
	)
	(segment
		(start 339.279484 -219.515944)
		(end 339.279484 -219.506038)
		(width 0.0889)
		(layer "In13.Cu")
		(net "P5E_CPU0_PE0_RX_DN<3>")
	)
	(segment
		(start 329.605386 -249.089926)
		(end 329.95743 -249.748548)
		(width 0.14732)
		(layer "In13.Cu")
		(net "P5E_CPU0_PE0_RX_DN<3>")
	)
	(segment
		(start 339.482938 -437.31942)
		(end 339.65007 -437.152288)
		(width 0.14732)
		(layer "In13.Cu")
		(net "P5E_CPU0_PE0_RX_DN<3>")
	)
	(segment
		(start 338.96681 -424.552872)
		(end 338.96681 -437.191912)
		(width 0.14732)
		(layer "In13.Cu")
		(net "P5E_CPU0_PE0_RX_DN<3>")
	)
	(segment
		(start 314.4266 -341.04707)
		(end 315.328808 -344.489532)
		(width 0.14732)
		(layer "In13.Cu")
		(net "P5E_CPU0_PE0_RX_DN<3>")
	)
	(segment
		(start 341.980012 -416.94989)
		(end 341.799672 -417.031424)
		(width 0.14732)
		(layer "In13.Cu")
		(net "P5E_CPU0_PE0_RX_DN<3>")
	)
	(segment
		(start 333.31658 -219.520008)
		(end 331.13726 -220.495368)
		(width 0.14732)
		(layer "In13.Cu")
		(net "P5E_CPU0_PE0_RX_DN<3>")
	)
	(segment
		(start 341.091012 -418.913056)
		(end 340.737698 -419.850824)
		(width 0.14732)
		(layer "In13.Cu")
		(net "P5E_CPU0_PE0_RX_DN<3>")
	)
	(segment
		(start 339.65007 -437.152288)
		(end 339.65007 -436.889906)
		(width 0.14732)
		(layer "In13.Cu")
		(net "P5E_CPU0_PE0_RX_DN<3>")
	)
	(segment
		(start 320.274188 -328.487024)
		(end 314.4266 -334.334358)
		(width 0.14732)
		(layer "In13.Cu")
		(net "P5E_CPU0_PE0_RX_DN<3>")
	)
	(segment
		(start 328.888344 -245.024148)
		(end 329.605386 -249.089926)
		(width 0.14732)
		(layer "In13.Cu")
		(net "P5E_CPU0_PE0_RX_DN<3>")
	)
	(segment
		(start 325.80199 -320.592704)
		(end 320.274188 -328.487024)
		(width 0.14732)
		(layer "In13.Cu")
		(net "P5E_CPU0_PE0_RX_DN<3>")
	)
	(segment
		(start 343.125552 -413.511238)
		(end 342.791542 -414.39846)
		(width 0.14732)
		(layer "In13.Cu")
		(net "P5E_CPU0_PE0_RX_DN<3>")
	)
	(segment
		(start 339.100922 -219.18676)
		(end 339.093556 -219.182442)
		(width 0.0889)
		(layer "In13.Cu")
		(net "P5E_CPU0_PE0_RX_DN<3>")
	)
	(segment
		(start 340.737698 -419.850824)
		(end 340.737444 -419.851586)
		(width 0.14732)
		(layer "In13.Cu")
		(net "P5E_CPU0_PE0_RX_DN<3>")
	)
	(segment
		(start 340.001098 -220.862906)
		(end 339.976968 -220.773752)
		(width 0.0889)
		(layer "In13.Cu")
		(net "P5E_CPU0_PE0_RX_DN<3>")
	)
	(segment
		(start 339.093556 -219.182442)
		(end 339.092032 -219.18168)
		(width 0.0889)
		(layer "In13.Cu")
		(net "P5E_CPU0_PE0_RX_DN<3>")
	)
	(segment
		(start 344.185748 -410.696918)
		(end 343.354152 -412.90494)
		(width 0.14732)
		(layer "In13.Cu")
		(net "P5E_CPU0_PE0_RX_DN<3>")
	)
	(segment
		(start 339.517736 -423.090086)
		(end 338.96681 -424.552872)
		(width 0.14732)
		(layer "In13.Cu")
		(net "P5E_CPU0_PE0_RX_DN<3>")
	)
	(segment
		(start 341.402416 -418.48278)
		(end 341.272622 -418.827712)
		(width 0.14732)
		(layer "In13.Cu")
		(net "P5E_CPU0_PE0_RX_DN<3>")
	)
	(segment
		(start 342.204802 -415.955734)
		(end 342.028526 -416.42411)
		(width 0.14732)
		(layer "In13.Cu")
		(net "P5E_CPU0_PE0_RX_DN<3>")
	)
	(segment
		(start 342.514936 -415.529522)
		(end 342.385142 -415.874454)
		(width 0.14732)
		(layer "In13.Cu")
		(net "P5E_CPU0_PE0_RX_DN<3>")
	)
	(segment
		(start 342.839548 -399.950432)
		(end 342.839548 -404.68169)
		(width 0.14732)
		(layer "In13.Cu")
		(net "P5E_CPU0_PE0_RX_DN<3>")
	)
	(segment
		(start 340.818978 -420.031672)
		(end 340.689184 -420.37635)
		(width 0.14732)
		(layer "In13.Cu")
		(net "P5E_CPU0_PE0_RX_DN<3>")
	)
	(segment
		(start 338.96681 -437.191912)
		(end 339.094318 -437.31942)
		(width 0.14732)
		(layer "In13.Cu")
		(net "P5E_CPU0_PE0_RX_DN<3>")
	)
	(segment
		(start 342.839548 -404.68169)
		(end 344.185748 -406.02789)
		(width 0.14732)
		(layer "In13.Cu")
		(net "P5E_CPU0_PE0_RX_DN<3>")
	)
	(segment
		(start 343.354152 -412.90494)
		(end 343.435686 -413.084772)
		(width 0.14732)
		(layer "In13.Cu")
		(net "P5E_CPU0_PE0_RX_DN<3>")
	)
	(segment
		(start 340.000844 -421.80764)
		(end 339.746336 -422.483534)
		(width 0.14732)
		(layer "In13.Cu")
		(net "P5E_CPU0_PE0_RX_DN<3>")
	)
	(segment
		(start 342.873076 -414.578546)
		(end 342.743282 -414.923478)
		(width 0.14732)
		(layer "In13.Cu")
		(net "P5E_CPU0_PE0_RX_DN<3>")
	)
	(segment
		(start 341.272622 -418.827712)
		(end 341.092282 -418.909246)
		(width 0.14732)
		(layer "In13.Cu")
		(net "P5E_CPU0_PE0_RX_DN<3>")
	)
	(segment
		(start 333.357728 -219.455492)
		(end 333.336646 -219.511118)
		(width 0.0889)
		(layer "In13.Cu")
		(net "P5E_CPU0_PE0_RX_DN<3>")
	)
	(segment
		(start 330.456286 -252.669548)
		(end 327.898506 -259.231384)
		(width 0.14732)
		(layer "In13.Cu")
		(net "P5E_CPU0_PE0_RX_DN<3>")
	)
	(segment
		(start 330.456286 -250.952762)
		(end 330.456286 -252.669548)
		(width 0.14732)
		(layer "In13.Cu")
		(net "P5E_CPU0_PE0_RX_DN<3>")
	)
	(segment
		(start 330.21778 -221.384368)
		(end 329.746102 -222.522796)
		(width 0.14732)
		(layer "In13.Cu")
		(net "P5E_CPU0_PE0_RX_DN<3>")
	)
	(segment
		(start 339.698076 -423.008552)
		(end 339.517736 -423.090086)
		(width 0.14732)
		(layer "In13.Cu")
		(net "P5E_CPU0_PE0_RX_DN<3>")
	)
	(arc
		(start 337.777836 -219.18168)
		(mid 337.503637 -219.257515)
		(end 337.227164 -219.190316)
		(width 0.0889)
		(layer "In13.Cu")
		(net "P5E_CPU0_PE0_RX_DN<3>")
	)
	(arc
		(start 335.333086 -219.18168)
		(mid 335.145888 -219.131537)
		(end 334.95869 -219.18168)
		(width 0.0889)
		(layer "In13.Cu")
		(net "P5E_CPU0_PE0_RX_DN<3>")
	)
	(arc
		(start 336.838036 -219.18168)
		(mid 336.555334 -219.257456)
		(end 336.272632 -219.18168)
		(width 0.0889)
		(layer "In13.Cu")
		(net "P5E_CPU0_PE0_RX_DN<3>")
	)
	(arc
		(start 335.898236 -219.18168)
		(mid 335.621677 -219.257423)
		(end 335.3435 -219.187776)
		(width 0.0889)
		(layer "In13.Cu")
		(net "P5E_CPU0_PE0_RX_DN<3>")
	)
	(arc
		(start 336.272632 -219.18168)
		(mid 336.085434 -219.131537)
		(end 335.898236 -219.18168)
		(width 0.0889)
		(layer "In13.Cu")
		(net "P5E_CPU0_PE0_RX_DN<3>")
	)
	(arc
		(start 339.74913 -220.311218)
		(mid 339.69686 -220.128853)
		(end 339.561932 -219.995496)
		(width 0.0889)
		(layer "In13.Cu")
		(net "P5E_CPU0_PE0_RX_DN<3>")
	)
	(arc
		(start 339.279484 -219.506038)
		(mid 339.231805 -219.323138)
		(end 339.100922 -219.18676)
		(width 0.0889)
		(layer "In13.Cu")
		(net "P5E_CPU0_PE0_RX_DN<3>")
	)
	(arc
		(start 339.95995 -220.760798)
		(mid 339.807463 -220.570702)
		(end 339.74913 -220.334078)
		(width 0.0889)
		(layer "In13.Cu")
		(net "P5E_CPU0_PE0_RX_DN<3>")
	)
	(arc
		(start 339.976968 -220.773752)
		(mid 339.968397 -220.767356)
		(end 339.95995 -220.760798)
		(width 0.0889)
		(layer "In13.Cu")
		(net "P5E_CPU0_PE0_RX_DN<3>")
	)
	(arc
		(start 337.212432 -219.18168)
		(mid 337.025234 -219.131537)
		(end 336.838036 -219.18168)
		(width 0.0889)
		(layer "In13.Cu")
		(net "P5E_CPU0_PE0_RX_DN<3>")
	)
	(arc
		(start 338.717636 -219.18168)
		(mid 338.443437 -219.257515)
		(end 338.166964 -219.190316)
		(width 0.0889)
		(layer "In13.Cu")
		(net "P5E_CPU0_PE0_RX_DN<3>")
	)
	(arc
		(start 338.152232 -219.18168)
		(mid 337.965034 -219.131537)
		(end 337.777836 -219.18168)
		(width 0.0889)
		(layer "In13.Cu")
		(net "P5E_CPU0_PE0_RX_DN<3>")
	)
	(arc
		(start 334.95869 -219.18168)
		(mid 334.822321 -219.238122)
		(end 334.675988 -219.257372)
		(width 0.0889)
		(layer "In13.Cu")
		(net "P5E_CPU0_PE0_RX_DN<3>")
	)
	(arc
		(start 339.561932 -219.995496)
		(mid 339.357597 -219.792891)
		(end 339.279484 -219.515944)
		(width 0.0889)
		(layer "In13.Cu")
		(net "P5E_CPU0_PE0_RX_DN<3>")
	)
	(arc
		(start 339.092032 -219.18168)
		(mid 338.904834 -219.131537)
		(end 338.717636 -219.18168)
		(width 0.0889)
		(layer "In13.Cu")
		(net "P5E_CPU0_PE0_RX_DN<3>")
	)
	(segment
		(start 338.90458 -221.669864)
		(end 338.90458 -221.134178)
		(width 0.13208)
		(layer "F.Cu")
		(net "P5E_CPU0_PE0_RX_DN<2>")
	)
	(segment
		(start 338.90458 -221.134178)
		(end 338.904834 -221.133924)
		(width 0.13208)
		(layer "F.Cu")
		(net "P5E_CPU0_PE0_RX_DN<2>")
	)
	(segment
		(start 327.900284 -266.62888)
		(end 328.555096 -259.357622)
		(width 0.14732)
		(layer "In13.Cu")
		(net "P5E_CPU0_PE0_RX_DN<2>")
	)
	(segment
		(start 331.121512 -250.845828)
		(end 330.54925 -249.46483)
		(width 0.14732)
		(layer "In13.Cu")
		(net "P5E_CPU0_PE0_RX_DN<2>")
	)
	(segment
		(start 333.528416 -220.22943)
		(end 333.528924 -220.229176)
		(width 0.0889)
		(layer "In13.Cu")
		(net "P5E_CPU0_PE0_RX_DN<2>")
	)
	(segment
		(start 333.738728 -220.135196)
		(end 334.299814 -219.897706)
		(width 0.0889)
		(layer "In13.Cu")
		(net "P5E_CPU0_PE0_RX_DN<2>")
	)
	(segment
		(start 331.121512 -252.772418)
		(end 331.121512 -250.845828)
		(width 0.14732)
		(layer "In13.Cu")
		(net "P5E_CPU0_PE0_RX_DN<2>")
	)
	(segment
		(start 335.325212 -219.835222)
		(end 335.333594 -219.830396)
		(width 0.0889)
		(layer "In13.Cu")
		(net "P5E_CPU0_PE0_RX_DN<2>")
	)
	(segment
		(start 315.16828 -340.98484)
		(end 315.16828 -334.598264)
		(width 0.14732)
		(layer "In13.Cu")
		(net "P5E_CPU0_PE0_RX_DN<2>")
	)
	(segment
		(start 331.478128 -221.099888)
		(end 333.453486 -220.216984)
		(width 0.14732)
		(layer "In13.Cu")
		(net "P5E_CPU0_PE0_RX_DN<2>")
	)
	(segment
		(start 339.040216 -221.48292)
		(end 339.061298 -221.404942)
		(width 0.0889)
		(layer "In13.Cu")
		(net "P5E_CPU0_PE0_RX_DN<2>")
	)
	(segment
		(start 339.061298 -221.404942)
		(end 338.904834 -221.133924)
		(width 0.0889)
		(layer "In13.Cu")
		(net "P5E_CPU0_PE0_RX_DN<2>")
	)
	(segment
		(start 338.721954 -219.832936)
		(end 338.723732 -219.833952)
		(width 0.0889)
		(layer "In13.Cu")
		(net "P5E_CPU0_PE0_RX_DN<2>")
	)
	(segment
		(start 330.54925 -249.46483)
		(end 330.280264 -248.961402)
		(width 0.14732)
		(layer "In13.Cu")
		(net "P5E_CPU0_PE0_RX_DN<2>")
	)
	(segment
		(start 338.717636 -219.830396)
		(end 338.721954 -219.832936)
		(width 0.0889)
		(layer "In13.Cu")
		(net "P5E_CPU0_PE0_RX_DN<2>")
	)
	(segment
		(start 329.345036 -233.585766)
		(end 330.39304 -222.7199)
		(width 0.14732)
		(layer "In13.Cu")
		(net "P5E_CPU0_PE0_RX_DN<2>")
	)
	(segment
		(start 346.974668 -406.141682)
		(end 345.628468 -404.795482)
		(width 0.14732)
		(layer "In13.Cu")
		(net "P5E_CPU0_PE0_RX_DN<2>")
	)
	(segment
		(start 346.974668 -410.736034)
		(end 346.974668 -406.141682)
		(width 0.14732)
		(layer "In13.Cu")
		(net "P5E_CPU0_PE0_RX_DN<2>")
	)
	(segment
		(start 339.000084 -220.319854)
		(end 339.000084 -220.334078)
		(width 0.0889)
		(layer "In13.Cu")
		(net "P5E_CPU0_PE0_RX_DN<2>")
	)
	(segment
		(start 329.561444 -244.863112)
		(end 329.345036 -233.585766)
		(width 0.14732)
		(layer "In13.Cu")
		(net "P5E_CPU0_PE0_RX_DN<2>")
	)
	(segment
		(start 334.39354 -219.830396)
		(end 334.414368 -219.818204)
		(width 0.0889)
		(layer "In13.Cu")
		(net "P5E_CPU0_PE0_RX_DN<2>")
	)
	(segment
		(start 335.89849 -219.830396)
		(end 335.906872 -219.835222)
		(width 0.0889)
		(layer "In13.Cu")
		(net "P5E_CPU0_PE0_RX_DN<2>")
	)
	(segment
		(start 320.693542 -329.073002)
		(end 326.430386 -320.880486)
		(width 0.14732)
		(layer "In13.Cu")
		(net "P5E_CPU0_PE0_RX_DN<2>")
	)
	(segment
		(start 340.692486 -424.377358)
		(end 346.974668 -410.736034)
		(width 0.14732)
		(layer "In13.Cu")
		(net "P5E_CPU0_PE0_RX_DN<2>")
	)
	(segment
		(start 330.39304 -222.7199)
		(end 330.771246 -221.80677)
		(width 0.14732)
		(layer "In13.Cu")
		(net "P5E_CPU0_PE0_RX_DN<2>")
	)
	(segment
		(start 345.628468 -404.795482)
		(end 345.628468 -400.52371)
		(width 0.14732)
		(layer "In13.Cu")
		(net "P5E_CPU0_PE0_RX_DN<2>")
	)
	(segment
		(start 341.08009 -438.593738)
		(end 340.692486 -438.206134)
		(width 0.14732)
		(layer "In13.Cu")
		(net "P5E_CPU0_PE0_RX_DN<2>")
	)
	(segment
		(start 315.16828 -334.598264)
		(end 320.693542 -329.073002)
		(width 0.14732)
		(layer "In13.Cu")
		(net "P5E_CPU0_PE0_RX_DN<2>")
	)
	(segment
		(start 341.650066 -439.0898)
		(end 341.650066 -438.741312)
		(width 0.14732)
		(layer "In13.Cu")
		(net "P5E_CPU0_PE0_RX_DN<2>")
	)
	(segment
		(start 338.708746 -221.453202)
		(end 338.717636 -221.458282)
		(width 0.0889)
		(layer "In13.Cu")
		(net "P5E_CPU0_PE0_RX_DN<2>")
	)
	(segment
		(start 328.555096 -259.357622)
		(end 331.121512 -252.772418)
		(width 0.14732)
		(layer "In13.Cu")
		(net "P5E_CPU0_PE0_RX_DN<2>")
	)
	(segment
		(start 326.430386 -320.880486)
		(end 330.706984 -310.718454)
		(width 0.14732)
		(layer "In13.Cu")
		(net "P5E_CPU0_PE0_RX_DN<2>")
	)
	(segment
		(start 340.692486 -438.206134)
		(end 340.692486 -424.377358)
		(width 0.14732)
		(layer "In13.Cu")
		(net "P5E_CPU0_PE0_RX_DN<2>")
	)
	(segment
		(start 345.628468 -400.52371)
		(end 315.924438 -344.135202)
		(width 0.14732)
		(layer "In13.Cu")
		(net "P5E_CPU0_PE0_RX_DN<2>")
	)
	(segment
		(start 341.502492 -438.593738)
		(end 341.08009 -438.593738)
		(width 0.14732)
		(layer "In13.Cu")
		(net "P5E_CPU0_PE0_RX_DN<2>")
	)
	(segment
		(start 341.650066 -438.741312)
		(end 341.502492 -438.593738)
		(width 0.14732)
		(layer "In13.Cu")
		(net "P5E_CPU0_PE0_RX_DN<2>")
	)
	(segment
		(start 338.152232 -219.830396)
		(end 338.166964 -219.82176)
		(width 0.0889)
		(layer "In13.Cu")
		(net "P5E_CPU0_PE0_RX_DN<2>")
	)
	(segment
		(start 330.706984 -310.718454)
		(end 327.900284 -266.62888)
		(width 0.14732)
		(layer "In13.Cu")
		(net "P5E_CPU0_PE0_RX_DN<2>")
	)
	(segment
		(start 333.528924 -220.229176)
		(end 333.738728 -220.135196)
		(width 0.0889)
		(layer "In13.Cu")
		(net "P5E_CPU0_PE0_RX_DN<2>")
	)
	(segment
		(start 338.71662 -220.810074)
		(end 338.708746 -220.814646)
		(width 0.0889)
		(layer "In13.Cu")
		(net "P5E_CPU0_PE0_RX_DN<2>")
	)
	(segment
		(start 330.280264 -248.961402)
		(end 329.561444 -244.863112)
		(width 0.14732)
		(layer "In13.Cu")
		(net "P5E_CPU0_PE0_RX_DN<2>")
	)
	(segment
		(start 333.473552 -220.208094)
		(end 333.528416 -220.22943)
		(width 0.0889)
		(layer "In13.Cu")
		(net "P5E_CPU0_PE0_RX_DN<2>")
	)
	(segment
		(start 333.453486 -220.216984)
		(end 333.473552 -220.208094)
		(width 0.0889)
		(layer "In13.Cu")
		(net "P5E_CPU0_PE0_RX_DN<2>")
	)
	(segment
		(start 330.771246 -221.80677)
		(end 331.478128 -221.099888)
		(width 0.14732)
		(layer "In13.Cu")
		(net "P5E_CPU0_PE0_RX_DN<2>")
	)
	(segment
		(start 315.924438 -344.135202)
		(end 315.16828 -340.98484)
		(width 0.14732)
		(layer "In13.Cu")
		(net "P5E_CPU0_PE0_RX_DN<2>")
	)
	(segment
		(start 338.717636 -220.809566)
		(end 338.71662 -220.810074)
		(width 0.0889)
		(layer "In13.Cu")
		(net "P5E_CPU0_PE0_RX_DN<2>")
	)
	(arc
		(start 334.299814 -219.897706)
		(mid 334.344959 -219.861659)
		(end 334.39354 -219.830396)
		(width 0.0889)
		(layer "In13.Cu")
		(net "P5E_CPU0_PE0_RX_DN<2>")
	)
	(arc
		(start 337.777836 -219.830396)
		(mid 337.965034 -219.880539)
		(end 338.152232 -219.830396)
		(width 0.0889)
		(layer "In13.Cu")
		(net "P5E_CPU0_PE0_RX_DN<2>")
	)
	(arc
		(start 336.838036 -219.830396)
		(mid 337.025234 -219.880539)
		(end 337.212432 -219.830396)
		(width 0.0889)
		(layer "In13.Cu")
		(net "P5E_CPU0_PE0_RX_DN<2>")
	)
	(arc
		(start 334.414368 -219.818204)
		(mid 334.688209 -219.75446)
		(end 334.958944 -219.830396)
		(width 0.0889)
		(layer "In13.Cu")
		(net "P5E_CPU0_PE0_RX_DN<2>")
	)
	(arc
		(start 338.717636 -221.458282)
		(mid 338.876124 -221.507215)
		(end 339.040216 -221.48292)
		(width 0.0889)
		(layer "In13.Cu")
		(net "P5E_CPU0_PE0_RX_DN<2>")
	)
	(arc
		(start 337.212432 -219.830396)
		(mid 337.495134 -219.75462)
		(end 337.777836 -219.830396)
		(width 0.0889)
		(layer "In13.Cu")
		(net "P5E_CPU0_PE0_RX_DN<2>")
	)
	(arc
		(start 338.166964 -219.82176)
		(mid 338.443439 -219.75444)
		(end 338.717636 -219.830396)
		(width 0.0889)
		(layer "In13.Cu")
		(net "P5E_CPU0_PE0_RX_DN<2>")
	)
	(arc
		(start 338.723732 -219.833952)
		(mid 338.926145 -220.040365)
		(end 339.000084 -220.319854)
		(width 0.0889)
		(layer "In13.Cu")
		(net "P5E_CPU0_PE0_RX_DN<2>")
	)
	(arc
		(start 336.272632 -219.830396)
		(mid 336.555334 -219.75462)
		(end 336.838036 -219.830396)
		(width 0.0889)
		(layer "In13.Cu")
		(net "P5E_CPU0_PE0_RX_DN<2>")
	)
	(arc
		(start 338.530438 -221.119192)
		(mid 338.530241 -221.126557)
		(end 338.530184 -221.133924)
		(width 0.0889)
		(layer "In13.Cu")
		(net "P5E_CPU0_PE0_RX_DN<2>")
	)
	(arc
		(start 335.333594 -219.830396)
		(mid 335.616042 -219.754747)
		(end 335.89849 -219.830396)
		(width 0.0889)
		(layer "In13.Cu")
		(net "P5E_CPU0_PE0_RX_DN<2>")
	)
	(arc
		(start 338.708746 -220.814646)
		(mid 338.581492 -220.944612)
		(end 338.530438 -221.119192)
		(width 0.0889)
		(layer "In13.Cu")
		(net "P5E_CPU0_PE0_RX_DN<2>")
	)
	(arc
		(start 338.530184 -221.133924)
		(mid 338.577863 -221.316824)
		(end 338.708746 -221.453202)
		(width 0.0889)
		(layer "In13.Cu")
		(net "P5E_CPU0_PE0_RX_DN<2>")
	)
	(arc
		(start 334.958944 -219.830396)
		(mid 335.141449 -219.880634)
		(end 335.325212 -219.835222)
		(width 0.0889)
		(layer "In13.Cu")
		(net "P5E_CPU0_PE0_RX_DN<2>")
	)
	(arc
		(start 339.000084 -220.334078)
		(mid 338.920943 -220.608701)
		(end 338.717636 -220.809566)
		(width 0.0889)
		(layer "In13.Cu")
		(net "P5E_CPU0_PE0_RX_DN<2>")
	)
	(arc
		(start 335.906872 -219.835222)
		(mid 336.09038 -219.8805)
		(end 336.272632 -219.830396)
		(width 0.0889)
		(layer "In13.Cu")
		(net "P5E_CPU0_PE0_RX_DN<2>")
	)
	(segment
		(start 337.96478 -221.669864)
		(end 337.96478 -221.134178)
		(width 0.13208)
		(layer "F.Cu")
		(net "P5E_CPU0_PE0_RX_DN<1>")
	)
	(segment
		(start 337.96478 -221.134178)
		(end 337.965034 -221.133924)
		(width 0.13208)
		(layer "F.Cu")
		(net "P5E_CPU0_PE0_RX_DN<1>")
	)
	(segment
		(start 342.388698 -388.289546)
		(end 342.60282 -388.6708)
		(width 0.14732)
		(layer "In13.Cu")
		(net "P5E_CPU0_PE0_RX_DN<1>")
	)
	(segment
		(start 348.966028 -400.247358)
		(end 348.966028 -404.68169)
		(width 0.14732)
		(layer "In13.Cu")
		(net "P5E_CPU0_PE0_RX_DN<1>")
	)
	(segment
		(start 343.48293 -437.31942)
		(end 343.650062 -437.152288)
		(width 0.14732)
		(layer "In13.Cu")
		(net "P5E_CPU0_PE0_RX_DN<1>")
	)
	(segment
		(start 335.820258 -220.868748)
		(end 335.32699 -221.362016)
		(width 0.0889)
		(layer "In13.Cu")
		(net "P5E_CPU0_PE0_RX_DN<1>")
	)
	(segment
		(start 342.555322 -388.840218)
		(end 342.76919 -389.220964)
		(width 0.14732)
		(layer "In13.Cu")
		(net "P5E_CPU0_PE0_RX_DN<1>")
	)
	(segment
		(start 316.422786 -335.049622)
		(end 316.422786 -340.864952)
		(width 0.14732)
		(layer "In13.Cu")
		(net "P5E_CPU0_PE0_RX_DN<1>")
	)
	(segment
		(start 331.580744 -223.645222)
		(end 331.690726 -223.77781)
		(width 0.14732)
		(layer "In13.Cu")
		(net "P5E_CPU0_PE0_RX_DN<1>")
	)
	(segment
		(start 345.992704 -418.825426)
		(end 346.051124 -419.014148)
		(width 0.14732)
		(layer "In13.Cu")
		(net "P5E_CPU0_PE0_RX_DN<1>")
	)
	(segment
		(start 338.121498 -220.862906)
		(end 338.100416 -220.784928)
		(width 0.0889)
		(layer "In13.Cu")
		(net "P5E_CPU0_PE0_RX_DN<1>")
	)
	(segment
		(start 345.51874 -419.724332)
		(end 345.57716 -419.913054)
		(width 0.14732)
		(layer "In13.Cu")
		(net "P5E_CPU0_PE0_RX_DN<1>")
	)
	(segment
		(start 345.405456 -420.23919)
		(end 345.21648 -420.29761)
		(width 0.14732)
		(layer "In13.Cu")
		(net "P5E_CPU0_PE0_RX_DN<1>")
	)
	(segment
		(start 334.88503 -221.40418)
		(end 334.862932 -221.40418)
		(width 0.0889)
		(layer "In13.Cu")
		(net "P5E_CPU0_PE0_RX_DN<1>")
	)
	(segment
		(start 337.965034 -221.133924)
		(end 338.121498 -220.862906)
		(width 0.0889)
		(layer "In13.Cu")
		(net "P5E_CPU0_PE0_RX_DN<1>")
	)
	(segment
		(start 317.025528 -343.414096)
		(end 342.219026 -388.242048)
		(width 0.14732)
		(layer "In13.Cu")
		(net "P5E_CPU0_PE0_RX_DN<1>")
	)
	(segment
		(start 344.080338 -422.45153)
		(end 342.967056 -424.563032)
		(width 0.14732)
		(layer "In13.Cu")
		(net "P5E_CPU0_PE0_RX_DN<1>")
	)
	(segment
		(start 342.60282 -388.6708)
		(end 342.555322 -388.840218)
		(width 0.14732)
		(layer "In13.Cu")
		(net "P5E_CPU0_PE0_RX_DN<1>")
	)
	(segment
		(start 331.641196 -222.992188)
		(end 331.580744 -223.645222)
		(width 0.14732)
		(layer "In13.Cu")
		(net "P5E_CPU0_PE0_RX_DN<1>")
	)
	(segment
		(start 321.95008 -329.522582)
		(end 316.422786 -335.049622)
		(width 0.14732)
		(layer "In13.Cu")
		(net "P5E_CPU0_PE0_RX_DN<1>")
	)
	(segment
		(start 332.325472 -253.120906)
		(end 329.725274 -259.79374)
		(width 0.14732)
		(layer "In13.Cu")
		(net "P5E_CPU0_PE0_RX_DN<1>")
	)
	(segment
		(start 343.105486 -389.819134)
		(end 343.319354 -390.19988)
		(width 0.14732)
		(layer "In13.Cu")
		(net "P5E_CPU0_PE0_RX_DN<1>")
	)
	(segment
		(start 331.690726 -223.77781)
		(end 331.650594 -224.213166)
		(width 0.14732)
		(layer "In13.Cu")
		(net "P5E_CPU0_PE0_RX_DN<1>")
	)
	(segment
		(start 344.441018 -422.067228)
		(end 344.269314 -422.393364)
		(width 0.14732)
		(layer "In13.Cu")
		(net "P5E_CPU0_PE0_RX_DN<1>")
	)
	(segment
		(start 342.967056 -437.153558)
		(end 343.132918 -437.31942)
		(width 0.14732)
		(layer "In13.Cu")
		(net "P5E_CPU0_PE0_RX_DN<1>")
	)
	(segment
		(start 342.219026 -388.242048)
		(end 342.388698 -388.289546)
		(width 0.14732)
		(layer "In13.Cu")
		(net "P5E_CPU0_PE0_RX_DN<1>")
	)
	(segment
		(start 331.650594 -224.213166)
		(end 331.517498 -224.323148)
		(width 0.14732)
		(layer "In13.Cu")
		(net "P5E_CPU0_PE0_RX_DN<1>")
	)
	(segment
		(start 330.763118 -244.625876)
		(end 331.468476 -248.62917)
		(width 0.14732)
		(layer "In13.Cu")
		(net "P5E_CPU0_PE0_RX_DN<1>")
	)
	(segment
		(start 346.051124 -419.014148)
		(end 345.87942 -419.340284)
		(width 0.14732)
		(layer "In13.Cu")
		(net "P5E_CPU0_PE0_RX_DN<1>")
	)
	(segment
		(start 334.862932 -221.40418)
		(end 333.875634 -221.40418)
		(width 0.14732)
		(layer "In13.Cu")
		(net "P5E_CPU0_PE0_RX_DN<1>")
	)
	(segment
		(start 345.023694 -420.663116)
		(end 345.082114 -420.851838)
		(width 0.14732)
		(layer "In13.Cu")
		(net "P5E_CPU0_PE0_RX_DN<1>")
	)
	(segment
		(start 350.312228 -406.02789)
		(end 350.312228 -410.633164)
		(width 0.14732)
		(layer "In13.Cu")
		(net "P5E_CPU0_PE0_RX_DN<1>")
	)
	(segment
		(start 343.319354 -390.19988)
		(end 343.488772 -390.247378)
		(width 0.14732)
		(layer "In13.Cu")
		(net "P5E_CPU0_PE0_RX_DN<1>")
	)
	(segment
		(start 342.967056 -424.563032)
		(end 342.967056 -437.153558)
		(width 0.14732)
		(layer "In13.Cu")
		(net "P5E_CPU0_PE0_RX_DN<1>")
	)
	(segment
		(start 329.725274 -259.79374)
		(end 329.108308 -266.644628)
		(width 0.14732)
		(layer "In13.Cu")
		(net "P5E_CPU0_PE0_RX_DN<1>")
	)
	(segment
		(start 331.928724 -310.95061)
		(end 327.368662 -321.784472)
		(width 0.14732)
		(layer "In13.Cu")
		(net "P5E_CPU0_PE0_RX_DN<1>")
	)
	(segment
		(start 342.938862 -389.268462)
		(end 343.152984 -389.649716)
		(width 0.14732)
		(layer "In13.Cu")
		(net "P5E_CPU0_PE0_RX_DN<1>")
	)
	(segment
		(start 343.650062 -437.152288)
		(end 343.650062 -436.889906)
		(width 0.14732)
		(layer "In13.Cu")
		(net "P5E_CPU0_PE0_RX_DN<1>")
	)
	(segment
		(start 344.03919 -391.226294)
		(end 344.253058 -391.607294)
		(width 0.14732)
		(layer "In13.Cu")
		(net "P5E_CPU0_PE0_RX_DN<1>")
	)
	(segment
		(start 331.864462 -222.4532)
		(end 331.641196 -222.992188)
		(width 0.14732)
		(layer "In13.Cu")
		(net "P5E_CPU0_PE0_RX_DN<1>")
	)
	(segment
		(start 344.269314 -422.393364)
		(end 344.080338 -422.45153)
		(width 0.14732)
		(layer "In13.Cu")
		(net "P5E_CPU0_PE0_RX_DN<1>")
	)
	(segment
		(start 331.517498 -224.323148)
		(end 330.678536 -233.36504)
		(width 0.14732)
		(layer "In13.Cu")
		(net "P5E_CPU0_PE0_RX_DN<1>")
	)
	(segment
		(start 333.875634 -221.40418)
		(end 332.23327 -222.084392)
		(width 0.14732)
		(layer "In13.Cu")
		(net "P5E_CPU0_PE0_RX_DN<1>")
	)
	(segment
		(start 345.082114 -420.851838)
		(end 344.910156 -421.17772)
		(width 0.14732)
		(layer "In13.Cu")
		(net "P5E_CPU0_PE0_RX_DN<1>")
	)
	(segment
		(start 343.869264 -391.178796)
		(end 344.03919 -391.226294)
		(width 0.14732)
		(layer "In13.Cu")
		(net "P5E_CPU0_PE0_RX_DN<1>")
	)
	(segment
		(start 343.702894 -390.628632)
		(end 343.655396 -390.79805)
		(width 0.14732)
		(layer "In13.Cu")
		(net "P5E_CPU0_PE0_RX_DN<1>")
	)
	(segment
		(start 345.87942 -419.340284)
		(end 345.690444 -419.398704)
		(width 0.14732)
		(layer "In13.Cu")
		(net "P5E_CPU0_PE0_RX_DN<1>")
	)
	(segment
		(start 327.368662 -321.784472)
		(end 321.95008 -329.522582)
		(width 0.14732)
		(layer "In13.Cu")
		(net "P5E_CPU0_PE0_RX_DN<1>")
	)
	(segment
		(start 345.57716 -419.913054)
		(end 345.405456 -420.23919)
		(width 0.14732)
		(layer "In13.Cu")
		(net "P5E_CPU0_PE0_RX_DN<1>")
	)
	(segment
		(start 331.639418 -248.94921)
		(end 332.325472 -250.605798)
		(width 0.14732)
		(layer "In13.Cu")
		(net "P5E_CPU0_PE0_RX_DN<1>")
	)
	(segment
		(start 342.76919 -389.220964)
		(end 342.938862 -389.268462)
		(width 0.14732)
		(layer "In13.Cu")
		(net "P5E_CPU0_PE0_RX_DN<1>")
	)
	(segment
		(start 344.910156 -421.17772)
		(end 344.72118 -421.23614)
		(width 0.14732)
		(layer "In13.Cu")
		(net "P5E_CPU0_PE0_RX_DN<1>")
	)
	(segment
		(start 316.422786 -340.864952)
		(end 317.025528 -343.414096)
		(width 0.14732)
		(layer "In13.Cu")
		(net "P5E_CPU0_PE0_RX_DN<1>")
	)
	(segment
		(start 343.655396 -390.79805)
		(end 343.869264 -391.178796)
		(width 0.14732)
		(layer "In13.Cu")
		(net "P5E_CPU0_PE0_RX_DN<1>")
	)
	(segment
		(start 335.32699 -221.362016)
		(end 334.927194 -221.362016)
		(width 0.0889)
		(layer "In13.Cu")
		(net "P5E_CPU0_PE0_RX_DN<1>")
	)
	(segment
		(start 344.72118 -421.23614)
		(end 344.382598 -421.878506)
		(width 0.14732)
		(layer "In13.Cu")
		(net "P5E_CPU0_PE0_RX_DN<1>")
	)
	(segment
		(start 343.152984 -389.649716)
		(end 343.105486 -389.819134)
		(width 0.14732)
		(layer "In13.Cu")
		(net "P5E_CPU0_PE0_RX_DN<1>")
	)
	(segment
		(start 332.23327 -222.084392)
		(end 331.864462 -222.4532)
		(width 0.14732)
		(layer "In13.Cu")
		(net "P5E_CPU0_PE0_RX_DN<1>")
	)
	(segment
		(start 330.678536 -233.36504)
		(end 330.763118 -244.625876)
		(width 0.14732)
		(layer "In13.Cu")
		(net "P5E_CPU0_PE0_RX_DN<1>")
	)
	(segment
		(start 331.468476 -248.62917)
		(end 331.639418 -248.94921)
		(width 0.14732)
		(layer "In13.Cu")
		(net "P5E_CPU0_PE0_RX_DN<1>")
	)
	(segment
		(start 334.927194 -221.362016)
		(end 334.88503 -221.40418)
		(width 0.0889)
		(layer "In13.Cu")
		(net "P5E_CPU0_PE0_RX_DN<1>")
	)
	(segment
		(start 348.966028 -404.68169)
		(end 350.312228 -406.02789)
		(width 0.14732)
		(layer "In13.Cu")
		(net "P5E_CPU0_PE0_RX_DN<1>")
	)
	(segment
		(start 344.382598 -421.878506)
		(end 344.441018 -422.067228)
		(width 0.14732)
		(layer "In13.Cu")
		(net "P5E_CPU0_PE0_RX_DN<1>")
	)
	(segment
		(start 345.21648 -420.29761)
		(end 345.023694 -420.663116)
		(width 0.14732)
		(layer "In13.Cu")
		(net "P5E_CPU0_PE0_RX_DN<1>")
	)
	(segment
		(start 343.132918 -437.31942)
		(end 343.48293 -437.31942)
		(width 0.14732)
		(layer "In13.Cu")
		(net "P5E_CPU0_PE0_RX_DN<1>")
	)
	(segment
		(start 345.690444 -419.398704)
		(end 345.51874 -419.724332)
		(width 0.14732)
		(layer "In13.Cu")
		(net "P5E_CPU0_PE0_RX_DN<1>")
	)
	(segment
		(start 329.108308 -266.644628)
		(end 331.928724 -310.95061)
		(width 0.14732)
		(layer "In13.Cu")
		(net "P5E_CPU0_PE0_RX_DN<1>")
	)
	(segment
		(start 344.20556 -391.776712)
		(end 348.966028 -400.247358)
		(width 0.14732)
		(layer "In13.Cu")
		(net "P5E_CPU0_PE0_RX_DN<1>")
	)
	(segment
		(start 343.488772 -390.247378)
		(end 343.702894 -390.628632)
		(width 0.14732)
		(layer "In13.Cu")
		(net "P5E_CPU0_PE0_RX_DN<1>")
	)
	(segment
		(start 332.325472 -250.605798)
		(end 332.325472 -253.120906)
		(width 0.14732)
		(layer "In13.Cu")
		(net "P5E_CPU0_PE0_RX_DN<1>")
	)
	(segment
		(start 344.253058 -391.607294)
		(end 344.20556 -391.776712)
		(width 0.14732)
		(layer "In13.Cu")
		(net "P5E_CPU0_PE0_RX_DN<1>")
	)
	(segment
		(start 350.312228 -410.633164)
		(end 345.992704 -418.825426)
		(width 0.14732)
		(layer "In13.Cu")
		(net "P5E_CPU0_PE0_RX_DN<1>")
	)
	(arc
		(start 337.212432 -220.809566)
		(mid 337.025234 -220.759423)
		(end 336.838036 -220.809566)
		(width 0.0889)
		(layer "In13.Cu")
		(net "P5E_CPU0_PE0_RX_DN<1>")
	)
	(arc
		(start 335.832196 -220.857318)
		(mid 335.826165 -220.862968)
		(end 335.820258 -220.868748)
		(width 0.0889)
		(layer "In13.Cu")
		(net "P5E_CPU0_PE0_RX_DN<1>")
	)
	(arc
		(start 338.100416 -220.784928)
		(mid 337.93632 -220.760581)
		(end 337.777836 -220.809566)
		(width 0.0889)
		(layer "In13.Cu")
		(net "P5E_CPU0_PE0_RX_DN<1>")
	)
	(arc
		(start 336.838036 -220.809566)
		(mid 336.555334 -220.885308)
		(end 336.272632 -220.809566)
		(width 0.0889)
		(layer "In13.Cu")
		(net "P5E_CPU0_PE0_RX_DN<1>")
	)
	(arc
		(start 337.777836 -220.809566)
		(mid 337.495134 -220.885308)
		(end 337.212432 -220.809566)
		(width 0.0889)
		(layer "In13.Cu")
		(net "P5E_CPU0_PE0_RX_DN<1>")
	)
	(arc
		(start 335.898236 -220.809566)
		(mid 335.863904 -220.831629)
		(end 335.832196 -220.857318)
		(width 0.0889)
		(layer "In13.Cu")
		(net "P5E_CPU0_PE0_RX_DN<1>")
	)
	(arc
		(start 336.272632 -220.809566)
		(mid 336.085434 -220.759423)
		(end 335.898236 -220.809566)
		(width 0.0889)
		(layer "In13.Cu")
		(net "P5E_CPU0_PE0_RX_DN<1>")
	)
	(segment
		(start 351.592134 -220.320108)
		(end 351.59188 -220.319854)
		(width 0.13208)
		(layer "F.Cu")
		(net "P5E_CPU0_PE0_RX_DN<15>")
	)
	(segment
		(start 351.592134 -220.855794)
		(end 351.592134 -220.320108)
		(width 0.13208)
		(layer "F.Cu")
		(net "P5E_CPU0_PE0_RX_DN<15>")
	)
	(segment
		(start 351.217484 -220.309948)
		(end 351.217484 -220.32849)
		(width 0.0889)
		(layer "In13.Cu")
		(net "P5E_CPU0_PE0_RX_DN<15>")
	)
	(segment
		(start 303.036732 -345.182444)
		(end 302.28794 -340.921594)
		(width 0.14732)
		(layer "In13.Cu")
		(net "P5E_CPU0_PE0_RX_DN<15>")
	)
	(segment
		(start 305.396138 -370.663978)
		(end 303.036732 -345.182444)
		(width 0.14732)
		(layer "In13.Cu")
		(net "P5E_CPU0_PE0_RX_DN<15>")
	)
	(segment
		(start 332.056232 -202.872594)
		(end 333.551784 -201.377296)
		(width 0.14732)
		(layer "In13.Cu")
		(net "P5E_CPU0_PE0_RX_DN<15>")
	)
	(segment
		(start 302.28794 -340.921594)
		(end 301.289212 -329.127104)
		(width 0.14732)
		(layer "In13.Cu")
		(net "P5E_CPU0_PE0_RX_DN<15>")
	)
	(segment
		(start 351.357438 -220.6117)
		(end 351.435416 -220.590872)
		(width 0.0889)
		(layer "In13.Cu")
		(net "P5E_CPU0_PE0_RX_DN<15>")
	)
	(segment
		(start 301.289212 -329.127104)
		(end 301.289212 -325.661782)
		(width 0.14732)
		(layer "In13.Cu")
		(net "P5E_CPU0_PE0_RX_DN<15>")
	)
	(segment
		(start 306.829206 -320.121788)
		(end 307.644546 -319.783968)
		(width 0.14732)
		(layer "In13.Cu")
		(net "P5E_CPU0_PE0_RX_DN<15>")
	)
	(segment
		(start 316.60973 -309.827422)
		(end 316.60973 -309.827168)
		(width 0.14732)
		(layer "In13.Cu")
		(net "P5E_CPU0_PE0_RX_DN<15>")
	)
	(segment
		(start 335.973928 -200.373996)
		(end 338.962746 -200.373996)
		(width 0.14732)
		(layer "In13.Cu")
		(net "P5E_CPU0_PE0_RX_DN<15>")
	)
	(segment
		(start 307.152548 -406.141682)
		(end 305.806348 -404.795482)
		(width 0.14732)
		(layer "In13.Cu")
		(net "P5E_CPU0_PE0_RX_DN<15>")
	)
	(segment
		(start 350.935036 -217.554048)
		(end 350.926146 -217.559128)
		(width 0.0889)
		(layer "In13.Cu")
		(net "P5E_CPU0_PE0_RX_DN<15>")
	)
	(segment
		(start 320.791332 -213.81085)
		(end 330.232004 -204.36967)
		(width 0.14732)
		(layer "In13.Cu")
		(net "P5E_CPU0_PE0_RX_DN<15>")
	)
	(segment
		(start 350.464882 -215.112346)
		(end 350.463866 -215.112854)
		(width 0.0889)
		(layer "In13.Cu")
		(net "P5E_CPU0_PE0_RX_DN<15>")
	)
	(segment
		(start 314.502546 -437.59374)
		(end 314.024264 -437.59374)
		(width 0.14732)
		(layer "In13.Cu")
		(net "P5E_CPU0_PE0_RX_DN<15>")
	)
	(segment
		(start 316.609222 -309.828438)
		(end 316.609476 -309.827422)
		(width 0.14732)
		(layer "In13.Cu")
		(net "P5E_CPU0_PE0_RX_DN<15>")
	)
	(segment
		(start 313.739022 -315.34989)
		(end 314.668662 -315.34989)
		(width 0.14732)
		(layer "In13.Cu")
		(net "P5E_CPU0_PE0_RX_DN<15>")
	)
	(segment
		(start 311.508902 -316.99708)
		(end 312.091832 -316.99708)
		(width 0.14732)
		(layer "In13.Cu")
		(net "P5E_CPU0_PE0_RX_DN<15>")
	)
	(segment
		(start 316.609984 -309.826914)
		(end 317.797942 -305.592988)
		(width 0.14732)
		(layer "In13.Cu")
		(net "P5E_CPU0_PE0_RX_DN<15>")
	)
	(segment
		(start 308.722014 -319.783968)
		(end 311.508902 -316.99708)
		(width 0.14732)
		(layer "In13.Cu")
		(net "P5E_CPU0_PE0_RX_DN<15>")
	)
	(segment
		(start 350.926146 -219.825316)
		(end 350.935036 -219.830396)
		(width 0.0889)
		(layer "In13.Cu")
		(net "P5E_CPU0_PE0_RX_DN<15>")
	)
	(segment
		(start 338.962746 -200.373996)
		(end 348.14637 -206.890112)
		(width 0.14732)
		(layer "In13.Cu")
		(net "P5E_CPU0_PE0_RX_DN<15>")
	)
	(segment
		(start 350.463866 -215.112854)
		(end 350.455992 -215.117426)
		(width 0.0889)
		(layer "In13.Cu")
		(net "P5E_CPU0_PE0_RX_DN<15>")
	)
	(segment
		(start 314.668662 -315.34989)
		(end 315.212984 -314.805568)
		(width 0.14732)
		(layer "In13.Cu")
		(net "P5E_CPU0_PE0_RX_DN<15>")
	)
	(segment
		(start 314.65012 -437.741314)
		(end 314.502546 -437.59374)
		(width 0.14732)
		(layer "In13.Cu")
		(net "P5E_CPU0_PE0_RX_DN<15>")
	)
	(segment
		(start 350.93402 -219.182188)
		(end 350.926146 -219.18676)
		(width 0.0889)
		(layer "In13.Cu")
		(net "P5E_CPU0_PE0_RX_DN<15>")
	)
	(segment
		(start 350.319594 -213.206838)
		(end 350.277684 -213.248748)
		(width 0.0889)
		(layer "In13.Cu")
		(net "P5E_CPU0_PE0_RX_DN<15>")
	)
	(segment
		(start 312.091832 -316.99708)
		(end 313.739022 -315.34989)
		(width 0.14732)
		(layer "In13.Cu")
		(net "P5E_CPU0_PE0_RX_DN<15>")
	)
	(segment
		(start 305.983894 -394.057378)
		(end 305.396138 -370.663978)
		(width 0.14732)
		(layer "In13.Cu")
		(net "P5E_CPU0_PE0_RX_DN<15>")
	)
	(segment
		(start 350.926146 -218.197684)
		(end 350.935036 -218.202764)
		(width 0.0889)
		(layer "In13.Cu")
		(net "P5E_CPU0_PE0_RX_DN<15>")
	)
	(segment
		(start 317.797942 -305.592988)
		(end 314.422536 -252.87605)
		(width 0.14732)
		(layer "In13.Cu")
		(net "P5E_CPU0_PE0_RX_DN<15>")
	)
	(segment
		(start 350.277684 -213.248748)
		(end 350.277684 -213.893908)
		(width 0.0889)
		(layer "In13.Cu")
		(net "P5E_CPU0_PE0_RX_DN<15>")
	)
	(segment
		(start 314.528454 -250.735846)
		(end 318.36233 -219.675202)
		(width 0.14732)
		(layer "In13.Cu")
		(net "P5E_CPU0_PE0_RX_DN<15>")
	)
	(segment
		(start 307.152548 -411.278832)
		(end 307.152548 -406.141682)
		(width 0.14732)
		(layer "In13.Cu")
		(net "P5E_CPU0_PE0_RX_DN<15>")
	)
	(segment
		(start 350.319594 -213.18474)
		(end 350.319594 -213.206838)
		(width 0.0889)
		(layer "In13.Cu")
		(net "P5E_CPU0_PE0_RX_DN<15>")
	)
	(segment
		(start 350.455992 -215.755982)
		(end 350.470978 -215.764618)
		(width 0.0889)
		(layer "In13.Cu")
		(net "P5E_CPU0_PE0_RX_DN<15>")
	)
	(segment
		(start 307.644546 -319.783968)
		(end 308.722014 -319.783968)
		(width 0.14732)
		(layer "In13.Cu")
		(net "P5E_CPU0_PE0_RX_DN<15>")
	)
	(segment
		(start 313.005216 -436.574692)
		(end 307.152548 -411.278832)
		(width 0.14732)
		(layer "In13.Cu")
		(net "P5E_CPU0_PE0_RX_DN<15>")
	)
	(segment
		(start 330.232004 -204.36967)
		(end 332.056232 -202.872594)
		(width 0.14732)
		(layer "In13.Cu")
		(net "P5E_CPU0_PE0_RX_DN<15>")
	)
	(segment
		(start 315.212984 -314.805568)
		(end 316.609222 -309.828438)
		(width 0.14732)
		(layer "In13.Cu")
		(net "P5E_CPU0_PE0_RX_DN<15>")
	)
	(segment
		(start 350.935036 -219.18168)
		(end 350.93402 -219.182188)
		(width 0.0889)
		(layer "In13.Cu")
		(net "P5E_CPU0_PE0_RX_DN<15>")
	)
	(segment
		(start 305.806348 -399.628106)
		(end 305.983894 -394.057378)
		(width 0.14732)
		(layer "In13.Cu")
		(net "P5E_CPU0_PE0_RX_DN<15>")
	)
	(segment
		(start 318.36233 -219.675202)
		(end 320.791332 -213.81085)
		(width 0.14732)
		(layer "In13.Cu")
		(net "P5E_CPU0_PE0_RX_DN<15>")
	)
	(segment
		(start 301.289212 -325.661782)
		(end 306.829206 -320.121788)
		(width 0.14732)
		(layer "In13.Cu")
		(net "P5E_CPU0_PE0_RX_DN<15>")
	)
	(segment
		(start 350.926146 -216.569798)
		(end 350.935036 -216.574878)
		(width 0.0889)
		(layer "In13.Cu")
		(net "P5E_CPU0_PE0_RX_DN<15>")
	)
	(segment
		(start 350.747076 -214.424768)
		(end 350.747076 -214.644732)
		(width 0.0889)
		(layer "In13.Cu")
		(net "P5E_CPU0_PE0_RX_DN<15>")
	)
	(segment
		(start 316.60973 -309.827168)
		(end 316.609984 -309.826914)
		(width 0.14732)
		(layer "In13.Cu")
		(net "P5E_CPU0_PE0_RX_DN<15>")
	)
	(segment
		(start 351.435416 -220.590872)
		(end 351.59188 -220.319854)
		(width 0.0889)
		(layer "In13.Cu")
		(net "P5E_CPU0_PE0_RX_DN<15>")
	)
	(segment
		(start 348.14637 -206.890112)
		(end 350.319594 -209.06359)
		(width 0.14732)
		(layer "In13.Cu")
		(net "P5E_CPU0_PE0_RX_DN<15>")
	)
	(segment
		(start 314.422536 -252.87605)
		(end 314.528454 -250.735846)
		(width 0.14732)
		(layer "In13.Cu")
		(net "P5E_CPU0_PE0_RX_DN<15>")
	)
	(segment
		(start 314.65012 -438.089802)
		(end 314.65012 -437.741314)
		(width 0.14732)
		(layer "In13.Cu")
		(net "P5E_CPU0_PE0_RX_DN<15>")
	)
	(segment
		(start 333.551784 -201.377296)
		(end 335.973928 -200.373996)
		(width 0.14732)
		(layer "In13.Cu")
		(net "P5E_CPU0_PE0_RX_DN<15>")
	)
	(segment
		(start 350.319594 -209.06359)
		(end 350.319594 -213.18474)
		(width 0.14732)
		(layer "In13.Cu")
		(net "P5E_CPU0_PE0_RX_DN<15>")
	)
	(segment
		(start 351.21723 -218.676728)
		(end 351.21723 -218.707716)
		(width 0.0889)
		(layer "In13.Cu")
		(net "P5E_CPU0_PE0_RX_DN<15>")
	)
	(segment
		(start 314.024264 -437.59374)
		(end 313.005216 -436.574692)
		(width 0.14732)
		(layer "In13.Cu")
		(net "P5E_CPU0_PE0_RX_DN<15>")
	)
	(segment
		(start 305.806348 -404.795482)
		(end 305.806348 -399.628106)
		(width 0.14732)
		(layer "In13.Cu")
		(net "P5E_CPU0_PE0_RX_DN<15>")
	)
	(segment
		(start 316.609476 -309.827422)
		(end 316.60973 -309.827422)
		(width 0.14732)
		(layer "In13.Cu")
		(net "P5E_CPU0_PE0_RX_DN<15>")
	)
	(arc
		(start 350.461834 -214.093298)
		(mid 350.635797 -214.232062)
		(end 350.747076 -214.424768)
		(width 0.0889)
		(layer "In13.Cu")
		(net "P5E_CPU0_PE0_RX_DN<15>")
	)
	(arc
		(start 351.217484 -220.32849)
		(mid 351.256158 -220.485558)
		(end 351.357438 -220.6117)
		(width 0.0889)
		(layer "In13.Cu")
		(net "P5E_CPU0_PE0_RX_DN<15>")
	)
	(arc
		(start 350.935036 -218.202764)
		(mid 351.137859 -218.402995)
		(end 351.21723 -218.676728)
		(width 0.0889)
		(layer "In13.Cu")
		(net "P5E_CPU0_PE0_RX_DN<15>")
	)
	(arc
		(start 350.747838 -217.888566)
		(mid 350.797853 -218.065697)
		(end 350.926146 -218.197684)
		(width 0.0889)
		(layer "In13.Cu")
		(net "P5E_CPU0_PE0_RX_DN<15>")
	)
	(arc
		(start 350.935036 -216.574878)
		(mid 351.217788 -217.064526)
		(end 350.935036 -217.554048)
		(width 0.0889)
		(layer "In13.Cu")
		(net "P5E_CPU0_PE0_RX_DN<15>")
	)
	(arc
		(start 350.470978 -215.764618)
		(mid 350.673565 -215.970969)
		(end 350.747584 -216.25052)
		(width 0.0889)
		(layer "In13.Cu")
		(net "P5E_CPU0_PE0_RX_DN<15>")
	)
	(arc
		(start 350.935036 -219.830396)
		(mid 351.139371 -220.033001)
		(end 351.217484 -220.309948)
		(width 0.0889)
		(layer "In13.Cu")
		(net "P5E_CPU0_PE0_RX_DN<15>")
	)
	(arc
		(start 350.455992 -215.117426)
		(mid 350.277395 -215.436704)
		(end 350.455992 -215.755982)
		(width 0.0889)
		(layer "In13.Cu")
		(net "P5E_CPU0_PE0_RX_DN<15>")
	)
	(arc
		(start 350.926146 -219.18676)
		(mid 350.747549 -219.506038)
		(end 350.926146 -219.825316)
		(width 0.0889)
		(layer "In13.Cu")
		(net "P5E_CPU0_PE0_RX_DN<15>")
	)
	(arc
		(start 350.747584 -216.25052)
		(mid 350.795263 -216.43342)
		(end 350.926146 -216.569798)
		(width 0.0889)
		(layer "In13.Cu")
		(net "P5E_CPU0_PE0_RX_DN<15>")
	)
	(arc
		(start 350.277684 -213.893908)
		(mid 350.352689 -214.009367)
		(end 350.461834 -214.093298)
		(width 0.0889)
		(layer "In13.Cu")
		(net "P5E_CPU0_PE0_RX_DN<15>")
	)
	(arc
		(start 350.747076 -214.644732)
		(mid 350.666165 -214.91486)
		(end 350.464882 -215.112346)
		(width 0.0889)
		(layer "In13.Cu")
		(net "P5E_CPU0_PE0_RX_DN<15>")
	)
	(arc
		(start 351.21723 -218.707716)
		(mid 351.13786 -218.98145)
		(end 350.935036 -219.18168)
		(width 0.0889)
		(layer "In13.Cu")
		(net "P5E_CPU0_PE0_RX_DN<15>")
	)
	(arc
		(start 350.747838 -217.866214)
		(mid 350.747671 -217.87739)
		(end 350.747838 -217.888566)
		(width 0.0889)
		(layer "In13.Cu")
		(net "P5E_CPU0_PE0_RX_DN<15>")
	)
	(arc
		(start 350.926146 -217.559128)
		(mid 350.798335 -217.690221)
		(end 350.747838 -217.866214)
		(width 0.0889)
		(layer "In13.Cu")
		(net "P5E_CPU0_PE0_RX_DN<15>")
	)
	(segment
		(start 350.18218 -221.669864)
		(end 350.18218 -221.134178)
		(width 0.13208)
		(layer "F.Cu")
		(net "P5E_CPU0_PE0_RX_DN<14>")
	)
	(segment
		(start 350.18218 -221.134178)
		(end 350.182434 -221.133924)
		(width 0.13208)
		(layer "F.Cu")
		(net "P5E_CPU0_PE0_RX_DN<14>")
	)
	(segment
		(start 350.00819 -217.545666)
		(end 350.002602 -217.548968)
		(width 0.0889)
		(layer "In13.Cu")
		(net "P5E_CPU0_PE0_RX_DN<14>")
	)
	(segment
		(start 350.277176 -220.319854)
		(end 350.277684 -220.319854)
		(width 0.0889)
		(layer "In13.Cu")
		(net "P5E_CPU0_PE0_RX_DN<14>")
	)
	(segment
		(start 349.995744 -219.831158)
		(end 349.997268 -219.832174)
		(width 0.0889)
		(layer "In13.Cu")
		(net "P5E_CPU0_PE0_RX_DN<14>")
	)
	(segment
		(start 309.236364 -320.945002)
		(end 310.41848 -320.45529)
		(width 0.14732)
		(layer "In13.Cu")
		(net "P5E_CPU0_PE0_RX_DN<14>")
	)
	(segment
		(start 349.991172 -219.828618)
		(end 349.995744 -219.831158)
		(width 0.0889)
		(layer "In13.Cu")
		(net "P5E_CPU0_PE0_RX_DN<14>")
	)
	(segment
		(start 349.807022 -214.425784)
		(end 349.807022 -214.62238)
		(width 0.0889)
		(layer "In13.Cu")
		(net "P5E_CPU0_PE0_RX_DN<14>")
	)
	(segment
		(start 350.002602 -217.548968)
		(end 349.993712 -217.554048)
		(width 0.0889)
		(layer "In13.Cu")
		(net "P5E_CPU0_PE0_RX_DN<14>")
	)
	(segment
		(start 318.9478 -308.047644)
		(end 315.424566 -253.267464)
		(width 0.14732)
		(layer "In13.Cu")
		(net "P5E_CPU0_PE0_RX_DN<14>")
	)
	(segment
		(start 349.986346 -221.453202)
		(end 349.995236 -221.458282)
		(width 0.0889)
		(layer "In13.Cu")
		(net "P5E_CPU0_PE0_RX_DN<14>")
	)
	(segment
		(start 349.538036 -215.103964)
		(end 349.532448 -215.107266)
		(width 0.0889)
		(layer "In13.Cu")
		(net "P5E_CPU0_PE0_RX_DN<14>")
	)
	(segment
		(start 305.140106 -325.04126)
		(end 309.236364 -320.945002)
		(width 0.14732)
		(layer "In13.Cu")
		(net "P5E_CPU0_PE0_RX_DN<14>")
	)
	(segment
		(start 313.281822 -319.3034)
		(end 313.445652 -319.188338)
		(width 0.14732)
		(layer "In13.Cu")
		(net "P5E_CPU0_PE0_RX_DN<14>")
	)
	(segment
		(start 349.379794 -209.706464)
		(end 349.379794 -213.18474)
		(width 0.14732)
		(layer "In13.Cu")
		(net "P5E_CPU0_PE0_RX_DN<14>")
	)
	(segment
		(start 349.528892 -215.763602)
		(end 349.535496 -215.767412)
		(width 0.0889)
		(layer "In13.Cu")
		(net "P5E_CPU0_PE0_RX_DN<14>")
	)
	(segment
		(start 350.002602 -219.176854)
		(end 349.993712 -219.181934)
		(width 0.0889)
		(layer "In13.Cu")
		(net "P5E_CPU0_PE0_RX_DN<14>")
	)
	(segment
		(start 303.267872 -340.595966)
		(end 303.25441 -330.405232)
		(width 0.14732)
		(layer "In13.Cu")
		(net "P5E_CPU0_PE0_RX_DN<14>")
	)
	(segment
		(start 349.997268 -219.832174)
		(end 350.00565 -219.837)
		(width 0.0889)
		(layer "In13.Cu")
		(net "P5E_CPU0_PE0_RX_DN<14>")
	)
	(segment
		(start 308.869588 -404.795482)
		(end 308.869588 -395.333982)
		(width 0.14732)
		(layer "In13.Cu")
		(net "P5E_CPU0_PE0_RX_DN<14>")
	)
	(segment
		(start 321.533012 -214.456264)
		(end 330.982574 -205.006448)
		(width 0.14732)
		(layer "In13.Cu")
		(net "P5E_CPU0_PE0_RX_DN<14>")
	)
	(segment
		(start 315.50483 -250.85548)
		(end 319.26911 -219.92082)
		(width 0.14732)
		(layer "In13.Cu")
		(net "P5E_CPU0_PE0_RX_DN<14>")
	)
	(segment
		(start 310.215788 -410.587444)
		(end 310.215788 -406.141682)
		(width 0.14732)
		(layer "In13.Cu")
		(net "P5E_CPU0_PE0_RX_DN<14>")
	)
	(segment
		(start 349.995744 -216.57564)
		(end 349.997268 -216.576656)
		(width 0.0889)
		(layer "In13.Cu")
		(net "P5E_CPU0_PE0_RX_DN<14>")
	)
	(segment
		(start 349.991172 -216.5731)
		(end 349.995744 -216.57564)
		(width 0.0889)
		(layer "In13.Cu")
		(net "P5E_CPU0_PE0_RX_DN<14>")
	)
	(segment
		(start 346.757498 -207.083914)
		(end 349.379794 -209.706464)
		(width 0.14732)
		(layer "In13.Cu")
		(net "P5E_CPU0_PE0_RX_DN<14>")
	)
	(segment
		(start 349.80753 -217.860626)
		(end 349.80753 -217.890852)
		(width 0.0889)
		(layer "In13.Cu")
		(net "P5E_CPU0_PE0_RX_DN<14>")
	)
	(segment
		(start 330.982574 -205.006448)
		(end 332.76032 -203.547472)
		(width 0.14732)
		(layer "In13.Cu")
		(net "P5E_CPU0_PE0_RX_DN<14>")
	)
	(segment
		(start 332.76032 -203.547472)
		(end 334.142334 -202.165712)
		(width 0.14732)
		(layer "In13.Cu")
		(net "P5E_CPU0_PE0_RX_DN<14>")
	)
	(segment
		(start 349.99422 -220.810074)
		(end 349.986346 -220.814646)
		(width 0.0889)
		(layer "In13.Cu")
		(net "P5E_CPU0_PE0_RX_DN<14>")
	)
	(segment
		(start 310.41848 -320.45529)
		(end 312.129932 -320.45529)
		(width 0.14732)
		(layer "In13.Cu")
		(net "P5E_CPU0_PE0_RX_DN<14>")
	)
	(segment
		(start 349.532448 -215.107266)
		(end 349.523558 -215.112346)
		(width 0.0889)
		(layer "In13.Cu")
		(net "P5E_CPU0_PE0_RX_DN<14>")
	)
	(segment
		(start 349.80753 -216.25052)
		(end 349.80753 -216.262966)
		(width 0.0889)
		(layer "In13.Cu")
		(net "P5E_CPU0_PE0_RX_DN<14>")
	)
	(segment
		(start 349.99803 -218.204796)
		(end 349.999554 -218.205812)
		(width 0.0889)
		(layer "In13.Cu")
		(net "P5E_CPU0_PE0_RX_DN<14>")
	)
	(segment
		(start 350.317816 -221.48292)
		(end 350.338898 -221.404942)
		(width 0.0889)
		(layer "In13.Cu")
		(net "P5E_CPU0_PE0_RX_DN<14>")
	)
	(segment
		(start 336.077814 -201.364088)
		(end 338.635086 -201.364088)
		(width 0.14732)
		(layer "In13.Cu")
		(net "P5E_CPU0_PE0_RX_DN<14>")
	)
	(segment
		(start 305.140106 -327.765156)
		(end 305.140106 -325.04126)
		(width 0.14732)
		(layer "In13.Cu")
		(net "P5E_CPU0_PE0_RX_DN<14>")
	)
	(segment
		(start 349.999554 -218.205812)
		(end 350.00819 -218.210892)
		(width 0.0889)
		(layer "In13.Cu")
		(net "P5E_CPU0_PE0_RX_DN<14>")
	)
	(segment
		(start 346.73794 -207.070452)
		(end 346.738194 -207.070198)
		(width 0.14732)
		(layer "In13.Cu")
		(net "P5E_CPU0_PE0_RX_DN<14>")
	)
	(segment
		(start 349.997268 -216.576656)
		(end 350.00565 -216.581482)
		(width 0.0889)
		(layer "In13.Cu")
		(net "P5E_CPU0_PE0_RX_DN<14>")
	)
	(segment
		(start 311.28462 -412.787084)
		(end 310.215788 -410.587444)
		(width 0.14732)
		(layer "In13.Cu")
		(net "P5E_CPU0_PE0_RX_DN<14>")
	)
	(segment
		(start 312.129932 -320.45529)
		(end 313.281822 -319.3034)
		(width 0.14732)
		(layer "In13.Cu")
		(net "P5E_CPU0_PE0_RX_DN<14>")
	)
	(segment
		(start 315.977524 -438.593738)
		(end 315.692536 -438.30875)
		(width 0.14732)
		(layer "In13.Cu")
		(net "P5E_CPU0_PE0_RX_DN<14>")
	)
	(segment
		(start 316.650116 -438.741312)
		(end 316.502542 -438.593738)
		(width 0.14732)
		(layer "In13.Cu")
		(net "P5E_CPU0_PE0_RX_DN<14>")
	)
	(segment
		(start 317.33109 -312.135012)
		(end 317.331344 -312.134758)
		(width 0.14732)
		(layer "In13.Cu")
		(net "P5E_CPU0_PE0_RX_DN<14>")
	)
	(segment
		(start 338.635086 -201.364088)
		(end 346.73794 -207.070452)
		(width 0.14732)
		(layer "In13.Cu")
		(net "P5E_CPU0_PE0_RX_DN<14>")
	)
	(segment
		(start 349.525082 -215.761316)
		(end 349.526098 -215.761824)
		(width 0.0889)
		(layer "In13.Cu")
		(net "P5E_CPU0_PE0_RX_DN<14>")
	)
	(segment
		(start 349.379794 -213.18474)
		(end 349.379794 -213.206838)
		(width 0.0889)
		(layer "In13.Cu")
		(net "P5E_CPU0_PE0_RX_DN<14>")
	)
	(segment
		(start 349.526098 -215.761824)
		(end 349.528892 -215.763602)
		(width 0.0889)
		(layer "In13.Cu")
		(net "P5E_CPU0_PE0_RX_DN<14>")
	)
	(segment
		(start 350.277684 -220.319854)
		(end 350.277684 -220.334078)
		(width 0.0889)
		(layer "In13.Cu")
		(net "P5E_CPU0_PE0_RX_DN<14>")
	)
	(segment
		(start 303.77257 -329.132692)
		(end 305.140106 -327.765156)
		(width 0.14732)
		(layer "In13.Cu")
		(net "P5E_CPU0_PE0_RX_DN<14>")
	)
	(segment
		(start 349.522034 -214.093298)
		(end 349.52178 -214.093552)
		(width 0.0889)
		(layer "In13.Cu")
		(net "P5E_CPU0_PE0_RX_DN<14>")
	)
	(segment
		(start 349.995236 -220.809566)
		(end 349.99422 -220.810074)
		(width 0.0889)
		(layer "In13.Cu")
		(net "P5E_CPU0_PE0_RX_DN<14>")
	)
	(segment
		(start 349.52051 -215.758522)
		(end 349.525082 -215.761316)
		(width 0.0889)
		(layer "In13.Cu")
		(net "P5E_CPU0_PE0_RX_DN<14>")
	)
	(segment
		(start 349.337884 -213.248748)
		(end 349.337884 -213.893908)
		(width 0.0889)
		(layer "In13.Cu")
		(net "P5E_CPU0_PE0_RX_DN<14>")
	)
	(segment
		(start 303.25441 -330.405232)
		(end 303.77257 -329.132692)
		(width 0.14732)
		(layer "In13.Cu")
		(net "P5E_CPU0_PE0_RX_DN<14>")
	)
	(segment
		(start 315.692536 -424.952668)
		(end 311.28462 -412.787084)
		(width 0.14732)
		(layer "In13.Cu")
		(net "P5E_CPU0_PE0_RX_DN<14>")
	)
	(segment
		(start 350.338898 -221.404942)
		(end 350.182434 -221.133924)
		(width 0.0889)
		(layer "In13.Cu")
		(net "P5E_CPU0_PE0_RX_DN<14>")
	)
	(segment
		(start 346.738194 -207.070198)
		(end 346.757498 -207.083914)
		(width 0.14732)
		(layer "In13.Cu")
		(net "P5E_CPU0_PE0_RX_DN<14>")
	)
	(segment
		(start 334.142334 -202.165712)
		(end 336.077814 -201.364088)
		(width 0.14732)
		(layer "In13.Cu")
		(net "P5E_CPU0_PE0_RX_DN<14>")
	)
	(segment
		(start 310.215788 -406.141682)
		(end 308.869588 -404.795482)
		(width 0.14732)
		(layer "In13.Cu")
		(net "P5E_CPU0_PE0_RX_DN<14>")
	)
	(segment
		(start 349.990156 -219.82811)
		(end 349.991172 -219.828618)
		(width 0.0889)
		(layer "In13.Cu")
		(net "P5E_CPU0_PE0_RX_DN<14>")
	)
	(segment
		(start 307.216556 -370.80444)
		(end 303.746662 -343.32672)
		(width 0.14732)
		(layer "In13.Cu")
		(net "P5E_CPU0_PE0_RX_DN<14>")
	)
	(segment
		(start 349.379794 -213.206838)
		(end 349.337884 -213.248748)
		(width 0.0889)
		(layer "In13.Cu")
		(net "P5E_CPU0_PE0_RX_DN<14>")
	)
	(segment
		(start 349.337376 -215.418924)
		(end 349.337376 -215.436704)
		(width 0.0889)
		(layer "In13.Cu")
		(net "P5E_CPU0_PE0_RX_DN<14>")
	)
	(segment
		(start 349.990156 -216.572592)
		(end 349.991172 -216.5731)
		(width 0.0889)
		(layer "In13.Cu")
		(net "P5E_CPU0_PE0_RX_DN<14>")
	)
	(segment
		(start 315.424566 -253.267464)
		(end 315.50483 -250.85548)
		(width 0.14732)
		(layer "In13.Cu")
		(net "P5E_CPU0_PE0_RX_DN<14>")
	)
	(segment
		(start 349.98914 -218.199716)
		(end 349.99803 -218.204796)
		(width 0.0889)
		(layer "In13.Cu")
		(net "P5E_CPU0_PE0_RX_DN<14>")
	)
	(segment
		(start 308.869588 -395.333982)
		(end 307.216556 -370.80444)
		(width 0.14732)
		(layer "In13.Cu")
		(net "P5E_CPU0_PE0_RX_DN<14>")
	)
	(segment
		(start 349.80753 -219.493592)
		(end 349.80753 -219.518484)
		(width 0.0889)
		(layer "In13.Cu")
		(net "P5E_CPU0_PE0_RX_DN<14>")
	)
	(segment
		(start 315.692536 -438.30875)
		(end 315.692536 -424.952668)
		(width 0.14732)
		(layer "In13.Cu")
		(net "P5E_CPU0_PE0_RX_DN<14>")
	)
	(segment
		(start 303.746662 -343.32672)
		(end 303.267872 -340.595966)
		(width 0.14732)
		(layer "In13.Cu")
		(net "P5E_CPU0_PE0_RX_DN<14>")
	)
	(segment
		(start 317.309246 -312.190638)
		(end 317.310262 -312.18759)
		(width 0.14732)
		(layer "In13.Cu")
		(net "P5E_CPU0_PE0_RX_DN<14>")
	)
	(segment
		(start 350.00819 -219.173552)
		(end 350.002602 -219.176854)
		(width 0.0889)
		(layer "In13.Cu")
		(net "P5E_CPU0_PE0_RX_DN<14>")
	)
	(segment
		(start 313.445652 -319.188338)
		(end 315.94425 -315.619892)
		(width 0.14732)
		(layer "In13.Cu")
		(net "P5E_CPU0_PE0_RX_DN<14>")
	)
	(segment
		(start 316.650116 -439.0898)
		(end 316.650116 -438.741312)
		(width 0.14732)
		(layer "In13.Cu")
		(net "P5E_CPU0_PE0_RX_DN<14>")
	)
	(segment
		(start 315.94425 -315.619892)
		(end 317.309246 -312.190638)
		(width 0.14732)
		(layer "In13.Cu")
		(net "P5E_CPU0_PE0_RX_DN<14>")
	)
	(segment
		(start 317.331344 -312.134758)
		(end 318.9478 -308.047644)
		(width 0.14732)
		(layer "In13.Cu")
		(net "P5E_CPU0_PE0_RX_DN<14>")
	)
	(segment
		(start 319.26911 -219.92082)
		(end 321.533012 -214.456264)
		(width 0.14732)
		(layer "In13.Cu")
		(net "P5E_CPU0_PE0_RX_DN<14>")
	)
	(segment
		(start 317.310262 -312.18759)
		(end 317.33109 -312.135012)
		(width 0.14732)
		(layer "In13.Cu")
		(net "P5E_CPU0_PE0_RX_DN<14>")
	)
	(segment
		(start 316.502542 -438.593738)
		(end 315.977524 -438.593738)
		(width 0.14732)
		(layer "In13.Cu")
		(net "P5E_CPU0_PE0_RX_DN<14>")
	)
	(arc
		(start 349.807784 -221.133924)
		(mid 349.855463 -221.316824)
		(end 349.986346 -221.453202)
		(width 0.0889)
		(layer "In13.Cu")
		(net "P5E_CPU0_PE0_RX_DN<14>")
	)
	(arc
		(start 350.276922 -218.707462)
		(mid 350.201563 -218.974522)
		(end 350.00819 -219.173552)
		(width 0.0889)
		(layer "In13.Cu")
		(net "P5E_CPU0_PE0_RX_DN<14>")
	)
	(arc
		(start 350.277684 -220.334078)
		(mid 350.198543 -220.608701)
		(end 349.995236 -220.809566)
		(width 0.0889)
		(layer "In13.Cu")
		(net "P5E_CPU0_PE0_RX_DN<14>")
	)
	(arc
		(start 349.80753 -216.262966)
		(mid 349.859334 -216.441084)
		(end 349.990156 -216.572592)
		(width 0.0889)
		(layer "In13.Cu")
		(net "P5E_CPU0_PE0_RX_DN<14>")
	)
	(arc
		(start 349.80753 -219.518484)
		(mid 349.859334 -219.696602)
		(end 349.990156 -219.82811)
		(width 0.0889)
		(layer "In13.Cu")
		(net "P5E_CPU0_PE0_RX_DN<14>")
	)
	(arc
		(start 349.808038 -221.119192)
		(mid 349.807841 -221.126557)
		(end 349.807784 -221.133924)
		(width 0.0889)
		(layer "In13.Cu")
		(net "P5E_CPU0_PE0_RX_DN<14>")
	)
	(arc
		(start 349.986346 -220.814646)
		(mid 349.859092 -220.944612)
		(end 349.808038 -221.119192)
		(width 0.0889)
		(layer "In13.Cu")
		(net "P5E_CPU0_PE0_RX_DN<14>")
	)
	(arc
		(start 349.993712 -219.181934)
		(mid 349.860435 -219.313746)
		(end 349.80753 -219.493592)
		(width 0.0889)
		(layer "In13.Cu")
		(net "P5E_CPU0_PE0_RX_DN<14>")
	)
	(arc
		(start 349.995236 -221.458282)
		(mid 350.153724 -221.507215)
		(end 350.317816 -221.48292)
		(width 0.0889)
		(layer "In13.Cu")
		(net "P5E_CPU0_PE0_RX_DN<14>")
	)
	(arc
		(start 350.276922 -218.676982)
		(mid 350.277128 -218.692222)
		(end 350.276922 -218.707462)
		(width 0.0889)
		(layer "In13.Cu")
		(net "P5E_CPU0_PE0_RX_DN<14>")
	)
	(arc
		(start 349.535496 -215.767412)
		(mid 349.73488 -215.973292)
		(end 349.80753 -216.25052)
		(width 0.0889)
		(layer "In13.Cu")
		(net "P5E_CPU0_PE0_RX_DN<14>")
	)
	(arc
		(start 349.337376 -215.436704)
		(mid 349.386434 -215.621794)
		(end 349.52051 -215.758522)
		(width 0.0889)
		(layer "In13.Cu")
		(net "P5E_CPU0_PE0_RX_DN<14>")
	)
	(arc
		(start 349.993712 -217.554048)
		(mid 349.861654 -217.683664)
		(end 349.80753 -217.860626)
		(width 0.0889)
		(layer "In13.Cu")
		(net "P5E_CPU0_PE0_RX_DN<14>")
	)
	(arc
		(start 349.807022 -214.62238)
		(mid 349.807007 -214.633557)
		(end 349.806768 -214.644732)
		(width 0.0889)
		(layer "In13.Cu")
		(net "P5E_CPU0_PE0_RX_DN<14>")
	)
	(arc
		(start 349.52178 -214.093552)
		(mid 349.695871 -214.232646)
		(end 349.807022 -214.425784)
		(width 0.0889)
		(layer "In13.Cu")
		(net "P5E_CPU0_PE0_RX_DN<14>")
	)
	(arc
		(start 350.00819 -218.210892)
		(mid 350.201603 -218.409899)
		(end 350.276922 -218.676982)
		(width 0.0889)
		(layer "In13.Cu")
		(net "P5E_CPU0_PE0_RX_DN<14>")
	)
	(arc
		(start 350.00565 -219.837)
		(mid 350.204619 -220.04288)
		(end 350.277176 -220.319854)
		(width 0.0889)
		(layer "In13.Cu")
		(net "P5E_CPU0_PE0_RX_DN<14>")
	)
	(arc
		(start 349.80753 -217.890852)
		(mid 349.859104 -218.068341)
		(end 349.98914 -218.199716)
		(width 0.0889)
		(layer "In13.Cu")
		(net "P5E_CPU0_PE0_RX_DN<14>")
	)
	(arc
		(start 350.277176 -217.064336)
		(mid 350.205368 -217.340032)
		(end 350.00819 -217.545666)
		(width 0.0889)
		(layer "In13.Cu")
		(net "P5E_CPU0_PE0_RX_DN<14>")
	)
	(arc
		(start 350.00565 -216.581482)
		(mid 350.204619 -216.787362)
		(end 350.277176 -217.064336)
		(width 0.0889)
		(layer "In13.Cu")
		(net "P5E_CPU0_PE0_RX_DN<14>")
	)
	(arc
		(start 349.523558 -215.112346)
		(mid 349.3915 -215.241962)
		(end 349.337376 -215.418924)
		(width 0.0889)
		(layer "In13.Cu")
		(net "P5E_CPU0_PE0_RX_DN<14>")
	)
	(arc
		(start 349.806768 -214.644732)
		(mid 349.729862 -214.907981)
		(end 349.538036 -215.103964)
		(width 0.0889)
		(layer "In13.Cu")
		(net "P5E_CPU0_PE0_RX_DN<14>")
	)
	(arc
		(start 349.337884 -213.893908)
		(mid 349.412889 -214.009367)
		(end 349.522034 -214.093298)
		(width 0.0889)
		(layer "In13.Cu")
		(net "P5E_CPU0_PE0_RX_DN<14>")
	)
	(segment
		(start 349.712534 -220.855794)
		(end 349.712534 -220.320108)
		(width 0.13208)
		(layer "F.Cu")
		(net "P5E_CPU0_PE0_RX_DN<13>")
	)
	(segment
		(start 349.712534 -220.320108)
		(end 349.71228 -220.319854)
		(width 0.13208)
		(layer "F.Cu")
		(net "P5E_CPU0_PE0_RX_DN<13>")
	)
	(segment
		(start 348.576392 -215.755982)
		(end 348.591378 -215.764618)
		(width 0.0889)
		(layer "In13.Cu")
		(net "P5E_CPU0_PE0_RX_DN<13>")
	)
	(segment
		(start 318.502538 -437.59374)
		(end 317.97752 -437.59374)
		(width 0.14732)
		(layer "In13.Cu")
		(net "P5E_CPU0_PE0_RX_DN<13>")
	)
	(segment
		(start 304.451258 -341.411306)
		(end 304.271426 -330.856844)
		(width 0.14732)
		(layer "In13.Cu")
		(net "P5E_CPU0_PE0_RX_DN<13>")
	)
	(segment
		(start 320.217292 -220.1545)
		(end 322.379086 -214.935562)
		(width 0.14732)
		(layer "In13.Cu")
		(net "P5E_CPU0_PE0_RX_DN<13>")
	)
	(segment
		(start 310.482234 -321.760088)
		(end 311.015634 -322.293488)
		(width 0.14732)
		(layer "In13.Cu")
		(net "P5E_CPU0_PE0_RX_DN<13>")
	)
	(segment
		(start 309.738522 -321.760088)
		(end 310.482234 -321.760088)
		(width 0.14732)
		(layer "In13.Cu")
		(net "P5E_CPU0_PE0_RX_DN<13>")
	)
	(segment
		(start 349.046546 -219.825316)
		(end 349.055436 -219.830396)
		(width 0.0889)
		(layer "In13.Cu")
		(net "P5E_CPU0_PE0_RX_DN<13>")
	)
	(segment
		(start 348.439994 -210.256628)
		(end 348.439994 -213.275672)
		(width 0.14732)
		(layer "In13.Cu")
		(net "P5E_CPU0_PE0_RX_DN<13>")
	)
	(segment
		(start 349.477838 -220.6117)
		(end 349.555816 -220.590872)
		(width 0.0889)
		(layer "In13.Cu")
		(net "P5E_CPU0_PE0_RX_DN<13>")
	)
	(segment
		(start 348.585282 -215.112346)
		(end 348.584266 -215.112854)
		(width 0.0889)
		(layer "In13.Cu")
		(net "P5E_CPU0_PE0_RX_DN<13>")
	)
	(segment
		(start 318.153796 -280.899616)
		(end 316.36462 -253.182882)
		(width 0.14732)
		(layer "In13.Cu")
		(net "P5E_CPU0_PE0_RX_DN<13>")
	)
	(segment
		(start 313.279028 -410.501084)
		(end 313.279028 -406.141682)
		(width 0.14732)
		(layer "In13.Cu")
		(net "P5E_CPU0_PE0_RX_DN<13>")
	)
	(segment
		(start 304.271426 -330.856844)
		(end 304.271172 -330.842112)
		(width 0.14732)
		(layer "In13.Cu")
		(net "P5E_CPU0_PE0_RX_DN<13>")
	)
	(segment
		(start 348.439994 -213.29777)
		(end 348.398084 -213.33968)
		(width 0.0889)
		(layer "In13.Cu")
		(net "P5E_CPU0_PE0_RX_DN<13>")
	)
	(segment
		(start 322.379086 -214.935562)
		(end 331.418438 -205.895448)
		(width 0.14732)
		(layer "In13.Cu")
		(net "P5E_CPU0_PE0_RX_DN<13>")
	)
	(segment
		(start 311.932828 -404.795482)
		(end 311.932828 -397.815816)
		(width 0.14732)
		(layer "In13.Cu")
		(net "P5E_CPU0_PE0_RX_DN<13>")
	)
	(segment
		(start 336.308446 -202.298808)
		(end 338.2899 -202.298808)
		(width 0.14732)
		(layer "In13.Cu")
		(net "P5E_CPU0_PE0_RX_DN<13>")
	)
	(segment
		(start 338.2899 -202.298808)
		(end 345.64955 -207.46593)
		(width 0.14732)
		(layer "In13.Cu")
		(net "P5E_CPU0_PE0_RX_DN<13>")
	)
	(segment
		(start 304.449988 -341.482426)
		(end 304.451258 -341.411306)
		(width 0.14732)
		(layer "In13.Cu")
		(net "P5E_CPU0_PE0_RX_DN<13>")
	)
	(segment
		(start 317.043816 -315.6839)
		(end 319.942972 -308.616858)
		(width 0.14732)
		(layer "In13.Cu")
		(net "P5E_CPU0_PE0_RX_DN<13>")
	)
	(segment
		(start 318.153796 -280.89987)
		(end 318.153796 -280.899616)
		(width 0.14732)
		(layer "In13.Cu")
		(net "P5E_CPU0_PE0_RX_DN<13>")
	)
	(segment
		(start 349.05442 -219.182188)
		(end 349.046546 -219.18676)
		(width 0.0889)
		(layer "In13.Cu")
		(net "P5E_CPU0_PE0_RX_DN<13>")
	)
	(segment
		(start 349.055436 -217.554048)
		(end 349.046546 -217.559128)
		(width 0.0889)
		(layer "In13.Cu")
		(net "P5E_CPU0_PE0_RX_DN<13>")
	)
	(segment
		(start 304.271172 -330.842112)
		(end 304.69205 -329.543156)
		(width 0.14732)
		(layer "In13.Cu")
		(net "P5E_CPU0_PE0_RX_DN<13>")
	)
	(segment
		(start 318.650112 -438.089802)
		(end 318.650112 -437.741314)
		(width 0.14732)
		(layer "In13.Cu")
		(net "P5E_CPU0_PE0_RX_DN<13>")
	)
	(segment
		(start 317.692532 -424.630088)
		(end 314.589414 -414.164272)
		(width 0.14732)
		(layer "In13.Cu")
		(net "P5E_CPU0_PE0_RX_DN<13>")
	)
	(segment
		(start 319.942972 -308.616858)
		(end 318.153796 -280.89987)
		(width 0.14732)
		(layer "In13.Cu")
		(net "P5E_CPU0_PE0_RX_DN<13>")
	)
	(segment
		(start 348.584266 -215.112854)
		(end 348.576392 -215.117426)
		(width 0.0889)
		(layer "In13.Cu")
		(net "P5E_CPU0_PE0_RX_DN<13>")
	)
	(segment
		(start 349.046546 -218.197684)
		(end 349.055436 -218.202764)
		(width 0.0889)
		(layer "In13.Cu")
		(net "P5E_CPU0_PE0_RX_DN<13>")
	)
	(segment
		(start 349.055436 -219.18168)
		(end 349.05442 -219.182188)
		(width 0.0889)
		(layer "In13.Cu")
		(net "P5E_CPU0_PE0_RX_DN<13>")
	)
	(segment
		(start 349.337884 -220.309948)
		(end 349.337884 -220.32849)
		(width 0.0889)
		(layer "In13.Cu")
		(net "P5E_CPU0_PE0_RX_DN<13>")
	)
	(segment
		(start 348.867476 -214.424768)
		(end 348.867476 -214.644732)
		(width 0.0889)
		(layer "In13.Cu")
		(net "P5E_CPU0_PE0_RX_DN<13>")
	)
	(segment
		(start 314.589414 -414.164272)
		(end 314.58916 -414.163764)
		(width 0.14732)
		(layer "In13.Cu")
		(net "P5E_CPU0_PE0_RX_DN<13>")
	)
	(segment
		(start 348.398084 -213.33968)
		(end 348.398084 -213.893908)
		(width 0.0889)
		(layer "In13.Cu")
		(net "P5E_CPU0_PE0_RX_DN<13>")
	)
	(segment
		(start 306.07762 -325.42099)
		(end 309.738522 -321.760088)
		(width 0.14732)
		(layer "In13.Cu")
		(net "P5E_CPU0_PE0_RX_DN<13>")
	)
	(segment
		(start 314.58916 -414.163764)
		(end 313.935618 -411.959298)
		(width 0.14732)
		(layer "In13.Cu")
		(net "P5E_CPU0_PE0_RX_DN<13>")
	)
	(segment
		(start 306.07762 -328.157586)
		(end 306.07762 -325.42099)
		(width 0.14732)
		(layer "In13.Cu")
		(net "P5E_CPU0_PE0_RX_DN<13>")
	)
	(segment
		(start 349.33763 -218.676728)
		(end 349.33763 -218.707716)
		(width 0.0889)
		(layer "In13.Cu")
		(net "P5E_CPU0_PE0_RX_DN<13>")
	)
	(segment
		(start 331.418438 -205.895448)
		(end 333.799688 -203.941172)
		(width 0.14732)
		(layer "In13.Cu")
		(net "P5E_CPU0_PE0_RX_DN<13>")
	)
	(segment
		(start 316.36462 -253.182882)
		(end 316.43574 -251.070618)
		(width 0.14732)
		(layer "In13.Cu")
		(net "P5E_CPU0_PE0_RX_DN<13>")
	)
	(segment
		(start 317.97752 -437.59374)
		(end 317.692532 -437.308752)
		(width 0.14732)
		(layer "In13.Cu")
		(net "P5E_CPU0_PE0_RX_DN<13>")
	)
	(segment
		(start 349.046546 -216.569798)
		(end 349.055436 -216.574878)
		(width 0.0889)
		(layer "In13.Cu")
		(net "P5E_CPU0_PE0_RX_DN<13>")
	)
	(segment
		(start 311.932828 -397.815816)
		(end 304.449988 -341.482426)
		(width 0.14732)
		(layer "In13.Cu")
		(net "P5E_CPU0_PE0_RX_DN<13>")
	)
	(segment
		(start 334.831182 -202.910186)
		(end 336.308446 -202.298808)
		(width 0.14732)
		(layer "In13.Cu")
		(net "P5E_CPU0_PE0_RX_DN<13>")
	)
	(segment
		(start 317.692532 -437.308752)
		(end 317.692532 -424.630088)
		(width 0.14732)
		(layer "In13.Cu")
		(net "P5E_CPU0_PE0_RX_DN<13>")
	)
	(segment
		(start 313.935618 -411.959298)
		(end 313.279028 -410.501084)
		(width 0.14732)
		(layer "In13.Cu")
		(net "P5E_CPU0_PE0_RX_DN<13>")
	)
	(segment
		(start 349.555816 -220.590872)
		(end 349.71228 -220.319854)
		(width 0.0889)
		(layer "In13.Cu")
		(net "P5E_CPU0_PE0_RX_DN<13>")
	)
	(segment
		(start 313.279028 -406.141682)
		(end 311.932828 -404.795482)
		(width 0.14732)
		(layer "In13.Cu")
		(net "P5E_CPU0_PE0_RX_DN<13>")
	)
	(segment
		(start 318.650112 -437.741314)
		(end 318.502538 -437.59374)
		(width 0.14732)
		(layer "In13.Cu")
		(net "P5E_CPU0_PE0_RX_DN<13>")
	)
	(segment
		(start 311.879234 -322.293488)
		(end 313.656726 -320.515996)
		(width 0.14732)
		(layer "In13.Cu")
		(net "P5E_CPU0_PE0_RX_DN<13>")
	)
	(segment
		(start 311.015634 -322.293488)
		(end 311.879234 -322.293488)
		(width 0.14732)
		(layer "In13.Cu")
		(net "P5E_CPU0_PE0_RX_DN<13>")
	)
	(segment
		(start 333.799688 -203.941172)
		(end 334.831182 -202.910186)
		(width 0.14732)
		(layer "In13.Cu")
		(net "P5E_CPU0_PE0_RX_DN<13>")
	)
	(segment
		(start 313.656726 -320.515996)
		(end 317.043816 -315.6839)
		(width 0.14732)
		(layer "In13.Cu")
		(net "P5E_CPU0_PE0_RX_DN<13>")
	)
	(segment
		(start 316.43574 -251.070618)
		(end 320.217292 -220.1545)
		(width 0.14732)
		(layer "In13.Cu")
		(net "P5E_CPU0_PE0_RX_DN<13>")
	)
	(segment
		(start 348.439994 -213.275672)
		(end 348.439994 -213.29777)
		(width 0.0889)
		(layer "In13.Cu")
		(net "P5E_CPU0_PE0_RX_DN<13>")
	)
	(segment
		(start 345.64955 -207.46593)
		(end 348.439994 -210.256628)
		(width 0.14732)
		(layer "In13.Cu")
		(net "P5E_CPU0_PE0_RX_DN<13>")
	)
	(segment
		(start 304.69205 -329.543156)
		(end 306.07762 -328.157586)
		(width 0.14732)
		(layer "In13.Cu")
		(net "P5E_CPU0_PE0_RX_DN<13>")
	)
	(arc
		(start 349.055436 -216.574878)
		(mid 349.338188 -217.064526)
		(end 349.055436 -217.554048)
		(width 0.0889)
		(layer "In13.Cu")
		(net "P5E_CPU0_PE0_RX_DN<13>")
	)
	(arc
		(start 349.055436 -218.202764)
		(mid 349.258259 -218.402995)
		(end 349.33763 -218.676728)
		(width 0.0889)
		(layer "In13.Cu")
		(net "P5E_CPU0_PE0_RX_DN<13>")
	)
	(arc
		(start 349.046546 -219.18676)
		(mid 348.867949 -219.506038)
		(end 349.046546 -219.825316)
		(width 0.0889)
		(layer "In13.Cu")
		(net "P5E_CPU0_PE0_RX_DN<13>")
	)
	(arc
		(start 349.33763 -218.707716)
		(mid 349.25826 -218.98145)
		(end 349.055436 -219.18168)
		(width 0.0889)
		(layer "In13.Cu")
		(net "P5E_CPU0_PE0_RX_DN<13>")
	)
	(arc
		(start 348.868238 -217.888566)
		(mid 348.918253 -218.065697)
		(end 349.046546 -218.197684)
		(width 0.0889)
		(layer "In13.Cu")
		(net "P5E_CPU0_PE0_RX_DN<13>")
	)
	(arc
		(start 348.398084 -213.893908)
		(mid 348.473089 -214.009367)
		(end 348.582234 -214.093298)
		(width 0.0889)
		(layer "In13.Cu")
		(net "P5E_CPU0_PE0_RX_DN<13>")
	)
	(arc
		(start 348.582234 -214.093298)
		(mid 348.756197 -214.232062)
		(end 348.867476 -214.424768)
		(width 0.0889)
		(layer "In13.Cu")
		(net "P5E_CPU0_PE0_RX_DN<13>")
	)
	(arc
		(start 349.055436 -219.830396)
		(mid 349.259771 -220.033001)
		(end 349.337884 -220.309948)
		(width 0.0889)
		(layer "In13.Cu")
		(net "P5E_CPU0_PE0_RX_DN<13>")
	)
	(arc
		(start 348.867984 -216.25052)
		(mid 348.915663 -216.43342)
		(end 349.046546 -216.569798)
		(width 0.0889)
		(layer "In13.Cu")
		(net "P5E_CPU0_PE0_RX_DN<13>")
	)
	(arc
		(start 349.046546 -217.559128)
		(mid 348.918735 -217.690221)
		(end 348.868238 -217.866214)
		(width 0.0889)
		(layer "In13.Cu")
		(net "P5E_CPU0_PE0_RX_DN<13>")
	)
	(arc
		(start 348.868238 -217.866214)
		(mid 348.868071 -217.87739)
		(end 348.868238 -217.888566)
		(width 0.0889)
		(layer "In13.Cu")
		(net "P5E_CPU0_PE0_RX_DN<13>")
	)
	(arc
		(start 348.576392 -215.117426)
		(mid 348.397795 -215.436704)
		(end 348.576392 -215.755982)
		(width 0.0889)
		(layer "In13.Cu")
		(net "P5E_CPU0_PE0_RX_DN<13>")
	)
	(arc
		(start 348.591378 -215.764618)
		(mid 348.793965 -215.970969)
		(end 348.867984 -216.25052)
		(width 0.0889)
		(layer "In13.Cu")
		(net "P5E_CPU0_PE0_RX_DN<13>")
	)
	(arc
		(start 348.867476 -214.644732)
		(mid 348.786565 -214.91486)
		(end 348.585282 -215.112346)
		(width 0.0889)
		(layer "In13.Cu")
		(net "P5E_CPU0_PE0_RX_DN<13>")
	)
	(arc
		(start 349.337884 -220.32849)
		(mid 349.376558 -220.485558)
		(end 349.477838 -220.6117)
		(width 0.0889)
		(layer "In13.Cu")
		(net "P5E_CPU0_PE0_RX_DN<13>")
	)
	(segment
		(start 348.30258 -221.669864)
		(end 348.30258 -221.134178)
		(width 0.13208)
		(layer "F.Cu")
		(net "P5E_CPU0_PE0_RX_DN<12>")
	)
	(segment
		(start 348.30258 -221.134178)
		(end 348.302834 -221.133924)
		(width 0.13208)
		(layer "F.Cu")
		(net "P5E_CPU0_PE0_RX_DN<12>")
	)
	(segment
		(start 323.18325 -215.472772)
		(end 331.526388 -207.129126)
		(width 0.14732)
		(layer "In13.Cu")
		(net "P5E_CPU0_PE0_RX_DN<12>")
	)
	(segment
		(start 309.611776 -323.229732)
		(end 312.301382 -323.229732)
		(width 0.14732)
		(layer "In13.Cu")
		(net "P5E_CPU0_PE0_RX_DN<12>")
	)
	(segment
		(start 337.712812 -203.274168)
		(end 345.522296 -208.700624)
		(width 0.14732)
		(layer "In13.Cu")
		(net "P5E_CPU0_PE0_RX_DN<12>")
	)
	(segment
		(start 348.12859 -217.545666)
		(end 348.123002 -217.548968)
		(width 0.0889)
		(layer "In13.Cu")
		(net "P5E_CPU0_PE0_RX_DN<12>")
	)
	(segment
		(start 314.996068 -404.795482)
		(end 314.996068 -397.374364)
		(width 0.14732)
		(layer "In13.Cu")
		(net "P5E_CPU0_PE0_RX_DN<12>")
	)
	(segment
		(start 317.956946 -316.042294)
		(end 320.938906 -308.844696)
		(width 0.14732)
		(layer "In13.Cu")
		(net "P5E_CPU0_PE0_RX_DN<12>")
	)
	(segment
		(start 317.332106 -252.832616)
		(end 317.386208 -251.226828)
		(width 0.14732)
		(layer "In13.Cu")
		(net "P5E_CPU0_PE0_RX_DN<12>")
	)
	(segment
		(start 321.154044 -220.37167)
		(end 323.18325 -215.472772)
		(width 0.14732)
		(layer "In13.Cu")
		(net "P5E_CPU0_PE0_RX_DN<12>")
	)
	(segment
		(start 348.116144 -219.831158)
		(end 348.117668 -219.832174)
		(width 0.0889)
		(layer "In13.Cu")
		(net "P5E_CPU0_PE0_RX_DN<12>")
	)
	(segment
		(start 347.645482 -215.761316)
		(end 347.646498 -215.761824)
		(width 0.0889)
		(layer "In13.Cu")
		(net "P5E_CPU0_PE0_RX_DN<12>")
	)
	(segment
		(start 348.111572 -219.828618)
		(end 348.116144 -219.831158)
		(width 0.0889)
		(layer "In13.Cu")
		(net "P5E_CPU0_PE0_RX_DN<12>")
	)
	(segment
		(start 307.032152 -328.562716)
		(end 307.032152 -325.809356)
		(width 0.14732)
		(layer "In13.Cu")
		(net "P5E_CPU0_PE0_RX_DN<12>")
	)
	(segment
		(start 331.526388 -207.129126)
		(end 333.836518 -205.23327)
		(width 0.14732)
		(layer "In13.Cu")
		(net "P5E_CPU0_PE0_RX_DN<12>")
	)
	(segment
		(start 348.106746 -221.453202)
		(end 348.115636 -221.458282)
		(width 0.0889)
		(layer "In13.Cu")
		(net "P5E_CPU0_PE0_RX_DN<12>")
	)
	(segment
		(start 348.115636 -220.809566)
		(end 348.11462 -220.810074)
		(width 0.0889)
		(layer "In13.Cu")
		(net "P5E_CPU0_PE0_RX_DN<12>")
	)
	(segment
		(start 333.836518 -205.23327)
		(end 335.346802 -203.72324)
		(width 0.14732)
		(layer "In13.Cu")
		(net "P5E_CPU0_PE0_RX_DN<12>")
	)
	(segment
		(start 347.92793 -219.493592)
		(end 347.92793 -219.518484)
		(width 0.0889)
		(layer "In13.Cu")
		(net "P5E_CPU0_PE0_RX_DN<12>")
	)
	(segment
		(start 348.397576 -220.319854)
		(end 348.398084 -220.319854)
		(width 0.0889)
		(layer "In13.Cu")
		(net "P5E_CPU0_PE0_RX_DN<12>")
	)
	(segment
		(start 347.92793 -216.25052)
		(end 347.92793 -216.262966)
		(width 0.0889)
		(layer "In13.Cu")
		(net "P5E_CPU0_PE0_RX_DN<12>")
	)
	(segment
		(start 319.692528 -438.30875)
		(end 319.692528 -425.125388)
		(width 0.14732)
		(layer "In13.Cu")
		(net "P5E_CPU0_PE0_RX_DN<12>")
	)
	(segment
		(start 348.123002 -219.176854)
		(end 348.114112 -219.181934)
		(width 0.0889)
		(layer "In13.Cu")
		(net "P5E_CPU0_PE0_RX_DN<12>")
	)
	(segment
		(start 317.386208 -251.226828)
		(end 321.154044 -220.37167)
		(width 0.14732)
		(layer "In13.Cu")
		(net "P5E_CPU0_PE0_RX_DN<12>")
	)
	(segment
		(start 347.655388 -215.105742)
		(end 347.64472 -215.112092)
		(width 0.0889)
		(layer "In13.Cu")
		(net "P5E_CPU0_PE0_RX_DN<12>")
	)
	(segment
		(start 336.431382 -203.274168)
		(end 337.712812 -203.274168)
		(width 0.14732)
		(layer "In13.Cu")
		(net "P5E_CPU0_PE0_RX_DN<12>")
	)
	(segment
		(start 314.996068 -397.374364)
		(end 305.655218 -343.05367)
		(width 0.14732)
		(layer "In13.Cu")
		(net "P5E_CPU0_PE0_RX_DN<12>")
	)
	(segment
		(start 348.111318 -218.200732)
		(end 348.12859 -218.210892)
		(width 0.0889)
		(layer "In13.Cu")
		(net "P5E_CPU0_PE0_RX_DN<12>")
	)
	(segment
		(start 348.110556 -216.572592)
		(end 348.111572 -216.5731)
		(width 0.0889)
		(layer "In13.Cu")
		(net "P5E_CPU0_PE0_RX_DN<12>")
	)
	(segment
		(start 348.111572 -216.5731)
		(end 348.116144 -216.57564)
		(width 0.0889)
		(layer "In13.Cu")
		(net "P5E_CPU0_PE0_RX_DN<12>")
	)
	(segment
		(start 348.110556 -219.82811)
		(end 348.111572 -219.828618)
		(width 0.0889)
		(layer "In13.Cu")
		(net "P5E_CPU0_PE0_RX_DN<12>")
	)
	(segment
		(start 305.237388 -331.100938)
		(end 305.79187 -329.802744)
		(width 0.14732)
		(layer "In13.Cu")
		(net "P5E_CPU0_PE0_RX_DN<12>")
	)
	(segment
		(start 305.655218 -343.05367)
		(end 305.635914 -342.868504)
		(width 0.14732)
		(layer "In13.Cu")
		(net "P5E_CPU0_PE0_RX_DN<12>")
	)
	(segment
		(start 347.646498 -215.761824)
		(end 347.649292 -215.763602)
		(width 0.0889)
		(layer "In13.Cu")
		(net "P5E_CPU0_PE0_RX_DN<12>")
	)
	(segment
		(start 317.05042 -412.86303)
		(end 316.342268 -410.425138)
		(width 0.14732)
		(layer "In13.Cu")
		(net "P5E_CPU0_PE0_RX_DN<12>")
	)
	(segment
		(start 320.650108 -439.0898)
		(end 320.650108 -438.741312)
		(width 0.14732)
		(layer "In13.Cu")
		(net "P5E_CPU0_PE0_RX_DN<12>")
	)
	(segment
		(start 348.11462 -220.810074)
		(end 348.106746 -220.814646)
		(width 0.0889)
		(layer "In13.Cu")
		(net "P5E_CPU0_PE0_RX_DN<12>")
	)
	(segment
		(start 348.123002 -217.548968)
		(end 348.114112 -217.554048)
		(width 0.0889)
		(layer "In13.Cu")
		(net "P5E_CPU0_PE0_RX_DN<12>")
	)
	(segment
		(start 347.642434 -214.093298)
		(end 347.64218 -214.093552)
		(width 0.0889)
		(layer "In13.Cu")
		(net "P5E_CPU0_PE0_RX_DN<12>")
	)
	(segment
		(start 345.522296 -208.700624)
		(end 347.500194 -210.678776)
		(width 0.14732)
		(layer "In13.Cu")
		(net "P5E_CPU0_PE0_RX_DN<12>")
	)
	(segment
		(start 348.398084 -220.319854)
		(end 348.398084 -220.334078)
		(width 0.0889)
		(layer "In13.Cu")
		(net "P5E_CPU0_PE0_RX_DN<12>")
	)
	(segment
		(start 320.502534 -438.593738)
		(end 319.977516 -438.593738)
		(width 0.14732)
		(layer "In13.Cu")
		(net "P5E_CPU0_PE0_RX_DN<12>")
	)
	(segment
		(start 335.346802 -203.72324)
		(end 336.431382 -203.274168)
		(width 0.14732)
		(layer "In13.Cu")
		(net "P5E_CPU0_PE0_RX_DN<12>")
	)
	(segment
		(start 320.650108 -438.741312)
		(end 320.502534 -438.593738)
		(width 0.14732)
		(layer "In13.Cu")
		(net "P5E_CPU0_PE0_RX_DN<12>")
	)
	(segment
		(start 348.117668 -216.576656)
		(end 348.12605 -216.581482)
		(width 0.0889)
		(layer "In13.Cu")
		(net "P5E_CPU0_PE0_RX_DN<12>")
	)
	(segment
		(start 347.500194 -210.678776)
		(end 347.500194 -213.275672)
		(width 0.14732)
		(layer "In13.Cu")
		(net "P5E_CPU0_PE0_RX_DN<12>")
	)
	(segment
		(start 348.438216 -221.48292)
		(end 348.459298 -221.404942)
		(width 0.0889)
		(layer "In13.Cu")
		(net "P5E_CPU0_PE0_RX_DN<12>")
	)
	(segment
		(start 305.79187 -329.802744)
		(end 307.032152 -328.562716)
		(width 0.14732)
		(layer "In13.Cu")
		(net "P5E_CPU0_PE0_RX_DN<12>")
	)
	(segment
		(start 348.117668 -219.832174)
		(end 348.12605 -219.837)
		(width 0.0889)
		(layer "In13.Cu")
		(net "P5E_CPU0_PE0_RX_DN<12>")
	)
	(segment
		(start 347.649292 -215.763602)
		(end 347.655896 -215.767412)
		(width 0.0889)
		(layer "In13.Cu")
		(net "P5E_CPU0_PE0_RX_DN<12>")
	)
	(segment
		(start 316.342268 -406.141682)
		(end 314.996068 -404.795482)
		(width 0.14732)
		(layer "In13.Cu")
		(net "P5E_CPU0_PE0_RX_DN<12>")
	)
	(segment
		(start 312.301382 -323.229732)
		(end 314.37961 -321.151504)
		(width 0.14732)
		(layer "In13.Cu")
		(net "P5E_CPU0_PE0_RX_DN<12>")
	)
	(segment
		(start 348.459298 -221.404942)
		(end 348.302834 -221.133924)
		(width 0.0889)
		(layer "In13.Cu")
		(net "P5E_CPU0_PE0_RX_DN<12>")
	)
	(segment
		(start 347.64091 -215.758522)
		(end 347.645482 -215.761316)
		(width 0.0889)
		(layer "In13.Cu")
		(net "P5E_CPU0_PE0_RX_DN<12>")
	)
	(segment
		(start 319.977516 -438.593738)
		(end 319.692528 -438.30875)
		(width 0.14732)
		(layer "In13.Cu")
		(net "P5E_CPU0_PE0_RX_DN<12>")
	)
	(segment
		(start 347.927422 -214.425784)
		(end 347.927422 -214.62238)
		(width 0.0889)
		(layer "In13.Cu")
		(net "P5E_CPU0_PE0_RX_DN<12>")
	)
	(segment
		(start 348.116144 -216.57564)
		(end 348.117668 -216.576656)
		(width 0.0889)
		(layer "In13.Cu")
		(net "P5E_CPU0_PE0_RX_DN<12>")
	)
	(segment
		(start 348.10954 -218.199716)
		(end 348.111318 -218.200732)
		(width 0.0889)
		(layer "In13.Cu")
		(net "P5E_CPU0_PE0_RX_DN<12>")
	)
	(segment
		(start 316.342268 -410.425138)
		(end 316.342268 -406.141682)
		(width 0.14732)
		(layer "In13.Cu")
		(net "P5E_CPU0_PE0_RX_DN<12>")
	)
	(segment
		(start 347.92793 -217.860626)
		(end 347.92793 -217.890852)
		(width 0.0889)
		(layer "In13.Cu")
		(net "P5E_CPU0_PE0_RX_DN<12>")
	)
	(segment
		(start 347.458284 -213.33968)
		(end 347.458284 -213.893908)
		(width 0.0889)
		(layer "In13.Cu")
		(net "P5E_CPU0_PE0_RX_DN<12>")
	)
	(segment
		(start 348.12859 -219.173552)
		(end 348.123002 -219.176854)
		(width 0.0889)
		(layer "In13.Cu")
		(net "P5E_CPU0_PE0_RX_DN<12>")
	)
	(segment
		(start 347.500194 -213.275672)
		(end 347.500194 -213.29777)
		(width 0.0889)
		(layer "In13.Cu")
		(net "P5E_CPU0_PE0_RX_DN<12>")
	)
	(segment
		(start 314.37961 -321.151504)
		(end 317.956946 -316.042294)
		(width 0.14732)
		(layer "In13.Cu")
		(net "P5E_CPU0_PE0_RX_DN<12>")
	)
	(segment
		(start 307.032152 -325.809356)
		(end 309.611776 -323.229732)
		(width 0.14732)
		(layer "In13.Cu")
		(net "P5E_CPU0_PE0_RX_DN<12>")
	)
	(segment
		(start 305.635914 -342.868504)
		(end 305.237388 -331.100938)
		(width 0.14732)
		(layer "In13.Cu")
		(net "P5E_CPU0_PE0_RX_DN<12>")
	)
	(segment
		(start 319.692528 -425.125388)
		(end 317.05042 -412.86303)
		(width 0.14732)
		(layer "In13.Cu")
		(net "P5E_CPU0_PE0_RX_DN<12>")
	)
	(segment
		(start 347.500194 -213.29777)
		(end 347.458284 -213.33968)
		(width 0.0889)
		(layer "In13.Cu")
		(net "P5E_CPU0_PE0_RX_DN<12>")
	)
	(segment
		(start 320.938906 -308.844696)
		(end 317.332106 -252.832616)
		(width 0.14732)
		(layer "In13.Cu")
		(net "P5E_CPU0_PE0_RX_DN<12>")
	)
	(segment
		(start 347.457776 -215.418924)
		(end 347.457776 -215.436704)
		(width 0.0889)
		(layer "In13.Cu")
		(net "P5E_CPU0_PE0_RX_DN<12>")
	)
	(arc
		(start 348.397576 -217.064336)
		(mid 348.325768 -217.340032)
		(end 348.12859 -217.545666)
		(width 0.0889)
		(layer "In13.Cu")
		(net "P5E_CPU0_PE0_RX_DN<12>")
	)
	(arc
		(start 347.92793 -219.518484)
		(mid 347.979734 -219.696602)
		(end 348.110556 -219.82811)
		(width 0.0889)
		(layer "In13.Cu")
		(net "P5E_CPU0_PE0_RX_DN<12>")
	)
	(arc
		(start 348.12605 -216.581482)
		(mid 348.325019 -216.787362)
		(end 348.397576 -217.064336)
		(width 0.0889)
		(layer "In13.Cu")
		(net "P5E_CPU0_PE0_RX_DN<12>")
	)
	(arc
		(start 347.458284 -213.893908)
		(mid 347.52576 -214.001087)
		(end 347.622876 -214.082376)
		(width 0.0889)
		(layer "In13.Cu")
		(net "P5E_CPU0_PE0_RX_DN<12>")
	)
	(arc
		(start 348.398084 -220.334078)
		(mid 348.318943 -220.608701)
		(end 348.115636 -220.809566)
		(width 0.0889)
		(layer "In13.Cu")
		(net "P5E_CPU0_PE0_RX_DN<12>")
	)
	(arc
		(start 347.92793 -216.262966)
		(mid 347.979734 -216.441084)
		(end 348.110556 -216.572592)
		(width 0.0889)
		(layer "In13.Cu")
		(net "P5E_CPU0_PE0_RX_DN<12>")
	)
	(arc
		(start 348.397322 -218.676982)
		(mid 348.397528 -218.692222)
		(end 348.397322 -218.707462)
		(width 0.0889)
		(layer "In13.Cu")
		(net "P5E_CPU0_PE0_RX_DN<12>")
	)
	(arc
		(start 347.928184 -221.133924)
		(mid 347.975863 -221.316824)
		(end 348.106746 -221.453202)
		(width 0.0889)
		(layer "In13.Cu")
		(net "P5E_CPU0_PE0_RX_DN<12>")
	)
	(arc
		(start 348.114112 -217.554048)
		(mid 347.982054 -217.683664)
		(end 347.92793 -217.860626)
		(width 0.0889)
		(layer "In13.Cu")
		(net "P5E_CPU0_PE0_RX_DN<12>")
	)
	(arc
		(start 347.64218 -214.093552)
		(mid 347.816271 -214.232646)
		(end 347.927422 -214.425784)
		(width 0.0889)
		(layer "In13.Cu")
		(net "P5E_CPU0_PE0_RX_DN<12>")
	)
	(arc
		(start 347.928438 -221.119192)
		(mid 347.928241 -221.126557)
		(end 347.928184 -221.133924)
		(width 0.0889)
		(layer "In13.Cu")
		(net "P5E_CPU0_PE0_RX_DN<12>")
	)
	(arc
		(start 348.12605 -219.837)
		(mid 348.325019 -220.04288)
		(end 348.397576 -220.319854)
		(width 0.0889)
		(layer "In13.Cu")
		(net "P5E_CPU0_PE0_RX_DN<12>")
	)
	(arc
		(start 347.92793 -217.890852)
		(mid 347.979504 -218.068341)
		(end 348.10954 -218.199716)
		(width 0.0889)
		(layer "In13.Cu")
		(net "P5E_CPU0_PE0_RX_DN<12>")
	)
	(arc
		(start 347.927168 -214.644732)
		(mid 347.849279 -214.909419)
		(end 347.655388 -215.105742)
		(width 0.0889)
		(layer "In13.Cu")
		(net "P5E_CPU0_PE0_RX_DN<12>")
	)
	(arc
		(start 348.397322 -218.707462)
		(mid 348.321963 -218.974522)
		(end 348.12859 -219.173552)
		(width 0.0889)
		(layer "In13.Cu")
		(net "P5E_CPU0_PE0_RX_DN<12>")
	)
	(arc
		(start 347.457776 -215.436704)
		(mid 347.506834 -215.621794)
		(end 347.64091 -215.758522)
		(width 0.0889)
		(layer "In13.Cu")
		(net "P5E_CPU0_PE0_RX_DN<12>")
	)
	(arc
		(start 347.64472 -215.112092)
		(mid 347.512155 -215.241687)
		(end 347.457776 -215.418924)
		(width 0.0889)
		(layer "In13.Cu")
		(net "P5E_CPU0_PE0_RX_DN<12>")
	)
	(arc
		(start 347.655896 -215.767412)
		(mid 347.85528 -215.973292)
		(end 347.92793 -216.25052)
		(width 0.0889)
		(layer "In13.Cu")
		(net "P5E_CPU0_PE0_RX_DN<12>")
	)
	(arc
		(start 348.12859 -218.210892)
		(mid 348.322003 -218.409899)
		(end 348.397322 -218.676982)
		(width 0.0889)
		(layer "In13.Cu")
		(net "P5E_CPU0_PE0_RX_DN<12>")
	)
	(arc
		(start 348.114112 -219.181934)
		(mid 347.980835 -219.313746)
		(end 347.92793 -219.493592)
		(width 0.0889)
		(layer "In13.Cu")
		(net "P5E_CPU0_PE0_RX_DN<12>")
	)
	(arc
		(start 348.115636 -221.458282)
		(mid 348.274124 -221.507215)
		(end 348.438216 -221.48292)
		(width 0.0889)
		(layer "In13.Cu")
		(net "P5E_CPU0_PE0_RX_DN<12>")
	)
	(arc
		(start 347.622876 -214.082376)
		(mid 347.63258 -214.08797)
		(end 347.642434 -214.093298)
		(width 0.0889)
		(layer "In13.Cu")
		(net "P5E_CPU0_PE0_RX_DN<12>")
	)
	(arc
		(start 348.106746 -220.814646)
		(mid 347.979492 -220.944612)
		(end 347.928438 -221.119192)
		(width 0.0889)
		(layer "In13.Cu")
		(net "P5E_CPU0_PE0_RX_DN<12>")
	)
	(arc
		(start 347.927422 -214.62238)
		(mid 347.927407 -214.633557)
		(end 347.927168 -214.644732)
		(width 0.0889)
		(layer "In13.Cu")
		(net "P5E_CPU0_PE0_RX_DN<12>")
	)
	(segment
		(start 347.36278 -221.134178)
		(end 347.363034 -221.133924)
		(width 0.13208)
		(layer "F.Cu")
		(net "P5E_CPU0_PE0_RX_DN<11>")
	)
	(segment
		(start 347.36278 -221.669864)
		(end 347.36278 -221.134178)
		(width 0.13208)
		(layer "F.Cu")
		(net "P5E_CPU0_PE0_RX_DN<11>")
	)
	(segment
		(start 316.282832 -388.089648)
		(end 316.186312 -388.236968)
		(width 0.14732)
		(layer "In13.Cu")
		(net "P5E_CPU0_PE0_RX_DN<11>")
	)
	(segment
		(start 316.186312 -388.236968)
		(end 316.275466 -388.66445)
		(width 0.14732)
		(layer "In13.Cu")
		(net "P5E_CPU0_PE0_RX_DN<11>")
	)
	(segment
		(start 322.164964 -309.060342)
		(end 318.8589 -317.030862)
		(width 0.14732)
		(layer "In13.Cu")
		(net "P5E_CPU0_PE0_RX_DN<11>")
	)
	(segment
		(start 316.741556 -390.287764)
		(end 316.645036 -390.435084)
		(width 0.14732)
		(layer "In13.Cu")
		(net "P5E_CPU0_PE0_RX_DN<11>")
	)
	(segment
		(start 338.05114 -208.867248)
		(end 331.80655 -209.984594)
		(width 0.14732)
		(layer "In13.Cu")
		(net "P5E_CPU0_PE0_RX_DN<11>")
	)
	(segment
		(start 308.281832 -329.179428)
		(end 306.857146 -330.604114)
		(width 0.14732)
		(layer "In13.Cu")
		(net "P5E_CPU0_PE0_RX_DN<11>")
	)
	(segment
		(start 312.796428 -324.872096)
		(end 309.674768 -324.872096)
		(width 0.14732)
		(layer "In13.Cu")
		(net "P5E_CPU0_PE0_RX_DN<11>")
	)
	(segment
		(start 329.57516 -210.9089)
		(end 324.133972 -216.350088)
		(width 0.14732)
		(layer "In13.Cu")
		(net "P5E_CPU0_PE0_RX_DN<11>")
	)
	(segment
		(start 316.881256 -390.958832)
		(end 316.970664 -391.386822)
		(width 0.14732)
		(layer "In13.Cu")
		(net "P5E_CPU0_PE0_RX_DN<11>")
	)
	(segment
		(start 315.95695 -387.13791)
		(end 316.046104 -387.565392)
		(width 0.14732)
		(layer "In13.Cu")
		(net "P5E_CPU0_PE0_RX_DN<11>")
	)
	(segment
		(start 315.964062 -386.5626)
		(end 316.05347 -386.99059)
		(width 0.14732)
		(layer "In13.Cu")
		(net "P5E_CPU0_PE0_RX_DN<11>")
	)
	(segment
		(start 340.61908 -208.867248)
		(end 340.49716 -208.989168)
		(width 0.14732)
		(layer "In13.Cu")
		(net "P5E_CPU0_PE0_RX_DN<11>")
	)
	(segment
		(start 316.193424 -387.661658)
		(end 316.282832 -388.089648)
		(width 0.14732)
		(layer "In13.Cu")
		(net "P5E_CPU0_PE0_RX_DN<11>")
	)
	(segment
		(start 320.968624 -417.694872)
		(end 320.849498 -417.852606)
		(width 0.14732)
		(layer "In13.Cu")
		(net "P5E_CPU0_PE0_RX_DN<11>")
	)
	(segment
		(start 313.681618 -324.425818)
		(end 313.545474 -324.562216)
		(width 0.14732)
		(layer "In13.Cu")
		(net "P5E_CPU0_PE0_RX_DN<11>")
	)
	(segment
		(start 316.652148 -389.859774)
		(end 316.741556 -390.287764)
		(width 0.14732)
		(layer "In13.Cu")
		(net "P5E_CPU0_PE0_RX_DN<11>")
	)
	(segment
		(start 319.944496 -411.371796)
		(end 320.461132 -415.070798)
		(width 0.14732)
		(layer "In13.Cu")
		(net "P5E_CPU0_PE0_RX_DN<11>")
	)
	(segment
		(start 324.133972 -216.350088)
		(end 322.35013 -220.656912)
		(width 0.14732)
		(layer "In13.Cu")
		(net "P5E_CPU0_PE0_RX_DN<11>")
	)
	(segment
		(start 321.966844 -425.852844)
		(end 321.966844 -437.19496)
		(width 0.14732)
		(layer "In13.Cu")
		(net "P5E_CPU0_PE0_RX_DN<11>")
	)
	(segment
		(start 339.93836 -208.867248)
		(end 339.50148 -208.867248)
		(width 0.14732)
		(layer "In13.Cu")
		(net "P5E_CPU0_PE0_RX_DN<11>")
	)
	(segment
		(start 318.333628 -404.68169)
		(end 319.679828 -406.02789)
		(width 0.14732)
		(layer "In13.Cu")
		(net "P5E_CPU0_PE0_RX_DN<11>")
	)
	(segment
		(start 346.797884 -217.8939)
		(end 346.797884 -217.859864)
		(width 0.0889)
		(layer "In13.Cu")
		(net "P5E_CPU0_PE0_RX_DN<11>")
	)
	(segment
		(start 346.797884 -216.260426)
		(end 346.797884 -216.25052)
		(width 0.0889)
		(layer "In13.Cu")
		(net "P5E_CPU0_PE0_RX_DN<11>")
	)
	(segment
		(start 320.91757 -417.329874)
		(end 320.968624 -417.694872)
		(width 0.14732)
		(layer "In13.Cu")
		(net "P5E_CPU0_PE0_RX_DN<11>")
	)
	(segment
		(start 346.797884 -219.515944)
		(end 346.797884 -219.490544)
		(width 0.0889)
		(layer "In13.Cu")
		(net "P5E_CPU0_PE0_RX_DN<11>")
	)
	(segment
		(start 339.50148 -208.867248)
		(end 339.37956 -208.989168)
		(width 0.14732)
		(layer "In13.Cu")
		(net "P5E_CPU0_PE0_RX_DN<11>")
	)
	(segment
		(start 316.874144 -391.534142)
		(end 316.963298 -391.961624)
		(width 0.14732)
		(layer "In13.Cu")
		(net "P5E_CPU0_PE0_RX_DN<11>")
	)
	(segment
		(start 346.328238 -213.312756)
		(end 346.286074 -213.270592)
		(width 0.0889)
		(layer "In13.Cu")
		(net "P5E_CPU0_PE0_RX_DN<11>")
	)
	(segment
		(start 316.415674 -389.336026)
		(end 316.504828 -389.763508)
		(width 0.14732)
		(layer "In13.Cu")
		(net "P5E_CPU0_PE0_RX_DN<11>")
	)
	(segment
		(start 320.550286 -415.712148)
		(end 320.616072 -416.184334)
		(width 0.14732)
		(layer "In13.Cu")
		(net "P5E_CPU0_PE0_RX_DN<11>")
	)
	(segment
		(start 320.618358 -415.189416)
		(end 320.669412 -415.554414)
		(width 0.14732)
		(layer "In13.Cu")
		(net "P5E_CPU0_PE0_RX_DN<11>")
	)
	(segment
		(start 316.275466 -388.66445)
		(end 316.422786 -388.760716)
		(width 0.14732)
		(layer "In13.Cu")
		(net "P5E_CPU0_PE0_RX_DN<11>")
	)
	(segment
		(start 346.32773 -215.436704)
		(end 346.32773 -215.414606)
		(width 0.0889)
		(layer "In13.Cu")
		(net "P5E_CPU0_PE0_RX_DN<11>")
	)
	(segment
		(start 306.857146 -330.604114)
		(end 306.519072 -331.73416)
		(width 0.14732)
		(layer "In13.Cu")
		(net "P5E_CPU0_PE0_RX_DN<11>")
	)
	(segment
		(start 320.759582 -417.211002)
		(end 320.91757 -417.329874)
		(width 0.14732)
		(layer "In13.Cu")
		(net "P5E_CPU0_PE0_RX_DN<11>")
	)
	(segment
		(start 347.081094 -218.368372)
		(end 347.080078 -218.367864)
		(width 0.0889)
		(layer "In13.Cu")
		(net "P5E_CPU0_PE0_RX_DN<11>")
	)
	(segment
		(start 346.610432 -215.926162)
		(end 346.60967 -215.925654)
		(width 0.0889)
		(layer "In13.Cu")
		(net "P5E_CPU0_PE0_RX_DN<11>")
	)
	(segment
		(start 347.26753 -217.072972)
		(end 347.26753 -217.0557)
		(width 0.0889)
		(layer "In13.Cu")
		(net "P5E_CPU0_PE0_RX_DN<11>")
	)
	(segment
		(start 344.879676 -209.798666)
		(end 342.63076 -208.867248)
		(width 0.14732)
		(layer "In13.Cu")
		(net "P5E_CPU0_PE0_RX_DN<11>")
	)
	(segment
		(start 317.110872 -392.05789)
		(end 317.200026 -392.48588)
		(width 0.14732)
		(layer "In13.Cu")
		(net "P5E_CPU0_PE0_RX_DN<11>")
	)
	(segment
		(start 347.26753 -220.334078)
		(end 347.26753 -220.311218)
		(width 0.0889)
		(layer "In13.Cu")
		(net "P5E_CPU0_PE0_RX_DN<11>")
	)
	(segment
		(start 346.286074 -213.270592)
		(end 346.286074 -213.248494)
		(width 0.0889)
		(layer "In13.Cu")
		(net "P5E_CPU0_PE0_RX_DN<11>")
	)
	(segment
		(start 320.825114 -416.668458)
		(end 320.705988 -416.825938)
		(width 0.14732)
		(layer "In13.Cu")
		(net "P5E_CPU0_PE0_RX_DN<11>")
	)
	(segment
		(start 346.286074 -213.248494)
		(end 346.286074 -211.205064)
		(width 0.14732)
		(layer "In13.Cu")
		(net "P5E_CPU0_PE0_RX_DN<11>")
	)
	(segment
		(start 346.60967 -215.925654)
		(end 346.604336 -215.922606)
		(width 0.0889)
		(layer "In13.Cu")
		(net "P5E_CPU0_PE0_RX_DN<11>")
	)
	(segment
		(start 346.328238 -213.929468)
		(end 346.328238 -213.312756)
		(width 0.0889)
		(layer "In13.Cu")
		(net "P5E_CPU0_PE0_RX_DN<11>")
	)
	(segment
		(start 316.963298 -391.961624)
		(end 317.110872 -392.05789)
		(width 0.14732)
		(layer "In13.Cu")
		(net "P5E_CPU0_PE0_RX_DN<11>")
	)
	(segment
		(start 318.333628 -398.528286)
		(end 318.333628 -404.68169)
		(width 0.14732)
		(layer "In13.Cu")
		(net "P5E_CPU0_PE0_RX_DN<11>")
	)
	(segment
		(start 346.619322 -215.931242)
		(end 346.611956 -215.926924)
		(width 0.0889)
		(layer "In13.Cu")
		(net "P5E_CPU0_PE0_RX_DN<11>")
	)
	(segment
		(start 316.73419 -390.86282)
		(end 316.881256 -390.958832)
		(width 0.14732)
		(layer "In13.Cu")
		(net "P5E_CPU0_PE0_RX_DN<11>")
	)
	(segment
		(start 340.06028 -208.989168)
		(end 339.93836 -208.867248)
		(width 0.14732)
		(layer "In13.Cu")
		(net "P5E_CPU0_PE0_RX_DN<11>")
	)
	(segment
		(start 346.609924 -214.946992)
		(end 346.618814 -214.941912)
		(width 0.0889)
		(layer "In13.Cu")
		(net "P5E_CPU0_PE0_RX_DN<11>")
	)
	(segment
		(start 316.970664 -391.386822)
		(end 316.874144 -391.534142)
		(width 0.14732)
		(layer "In13.Cu")
		(net "P5E_CPU0_PE0_RX_DN<11>")
	)
	(segment
		(start 309.674768 -324.872096)
		(end 308.281832 -326.265032)
		(width 0.14732)
		(layer "In13.Cu")
		(net "P5E_CPU0_PE0_RX_DN<11>")
	)
	(segment
		(start 346.327984 -213.930484)
		(end 346.327984 -213.929722)
		(width 0.0889)
		(layer "In13.Cu")
		(net "P5E_CPU0_PE0_RX_DN<11>")
	)
	(segment
		(start 321.966844 -437.19496)
		(end 322.091304 -437.31942)
		(width 0.14732)
		(layer "In13.Cu")
		(net "P5E_CPU0_PE0_RX_DN<11>")
	)
	(segment
		(start 347.519498 -220.862906)
		(end 347.495368 -220.773752)
		(width 0.0889)
		(layer "In13.Cu")
		(net "P5E_CPU0_PE0_RX_DN<11>")
	)
	(segment
		(start 320.705988 -416.825938)
		(end 320.759582 -417.211002)
		(width 0.14732)
		(layer "In13.Cu")
		(net "P5E_CPU0_PE0_RX_DN<11>")
	)
	(segment
		(start 320.461132 -415.070798)
		(end 320.618358 -415.189416)
		(width 0.14732)
		(layer "In13.Cu")
		(net "P5E_CPU0_PE0_RX_DN<11>")
	)
	(segment
		(start 308.281832 -326.265032)
		(end 308.281832 -329.179428)
		(width 0.14732)
		(layer "In13.Cu")
		(net "P5E_CPU0_PE0_RX_DN<11>")
	)
	(segment
		(start 322.35013 -220.656912)
		(end 318.593724 -251.340112)
		(width 0.14732)
		(layer "In13.Cu")
		(net "P5E_CPU0_PE0_RX_DN<11>")
	)
	(segment
		(start 347.088968 -218.372944)
		(end 347.081094 -218.368372)
		(width 0.0889)
		(layer "In13.Cu")
		(net "P5E_CPU0_PE0_RX_DN<11>")
	)
	(segment
		(start 318.8589 -317.030862)
		(end 313.681618 -324.425564)
		(width 0.14732)
		(layer "In13.Cu")
		(net "P5E_CPU0_PE0_RX_DN<11>")
	)
	(segment
		(start 331.80655 -209.984594)
		(end 329.57516 -210.9089)
		(width 0.14732)
		(layer "In13.Cu")
		(net "P5E_CPU0_PE0_RX_DN<11>")
	)
	(segment
		(start 306.519072 -331.73416)
		(end 306.89677 -342.862916)
		(width 0.14732)
		(layer "In13.Cu")
		(net "P5E_CPU0_PE0_RX_DN<11>")
	)
	(segment
		(start 322.091304 -437.31942)
		(end 322.482972 -437.31942)
		(width 0.14732)
		(layer "In13.Cu")
		(net "P5E_CPU0_PE0_RX_DN<11>")
	)
	(segment
		(start 346.797376 -214.622634)
		(end 346.797376 -214.461344)
		(width 0.0889)
		(layer "In13.Cu")
		(net "P5E_CPU0_PE0_RX_DN<11>")
	)
	(segment
		(start 322.482972 -437.31942)
		(end 322.650104 -437.152288)
		(width 0.14732)
		(layer "In13.Cu")
		(net "P5E_CPU0_PE0_RX_DN<11>")
	)
	(segment
		(start 320.77406 -416.303206)
		(end 320.825114 -416.668458)
		(width 0.14732)
		(layer "In13.Cu")
		(net "P5E_CPU0_PE0_RX_DN<11>")
	)
	(segment
		(start 320.669412 -415.554414)
		(end 320.550286 -415.712148)
		(width 0.14732)
		(layer "In13.Cu")
		(net "P5E_CPU0_PE0_RX_DN<11>")
	)
	(segment
		(start 316.512194 -389.188706)
		(end 316.415674 -389.336026)
		(width 0.14732)
		(layer "In13.Cu")
		(net "P5E_CPU0_PE0_RX_DN<11>")
	)
	(segment
		(start 320.849498 -417.852606)
		(end 321.966844 -425.852844)
		(width 0.14732)
		(layer "In13.Cu")
		(net "P5E_CPU0_PE0_RX_DN<11>")
	)
	(segment
		(start 319.679828 -410.493718)
		(end 319.944496 -411.371796)
		(width 0.14732)
		(layer "In13.Cu")
		(net "P5E_CPU0_PE0_RX_DN<11>")
	)
	(segment
		(start 316.645036 -390.435084)
		(end 316.73419 -390.86282)
		(width 0.14732)
		(layer "In13.Cu")
		(net "P5E_CPU0_PE0_RX_DN<11>")
	)
	(segment
		(start 316.504828 -389.763508)
		(end 316.652148 -389.859774)
		(width 0.14732)
		(layer "In13.Cu")
		(net "P5E_CPU0_PE0_RX_DN<11>")
	)
	(segment
		(start 342.63076 -208.867248)
		(end 340.61908 -208.867248)
		(width 0.14732)
		(layer "In13.Cu")
		(net "P5E_CPU0_PE0_RX_DN<11>")
	)
	(segment
		(start 320.616072 -416.184334)
		(end 320.77406 -416.303206)
		(width 0.14732)
		(layer "In13.Cu")
		(net "P5E_CPU0_PE0_RX_DN<11>")
	)
	(segment
		(start 338.82076 -208.867248)
		(end 338.05114 -208.867248)
		(width 0.14732)
		(layer "In13.Cu")
		(net "P5E_CPU0_PE0_RX_DN<11>")
	)
	(segment
		(start 338.94268 -208.989168)
		(end 338.82076 -208.867248)
		(width 0.14732)
		(layer "In13.Cu")
		(net "P5E_CPU0_PE0_RX_DN<11>")
	)
	(segment
		(start 346.286074 -211.205064)
		(end 344.879676 -209.798666)
		(width 0.14732)
		(layer "In13.Cu")
		(net "P5E_CPU0_PE0_RX_DN<11>")
	)
	(segment
		(start 315.816996 -386.466588)
		(end 315.964062 -386.5626)
		(width 0.14732)
		(layer "In13.Cu")
		(net "P5E_CPU0_PE0_RX_DN<11>")
	)
	(segment
		(start 340.49716 -208.989168)
		(end 340.06028 -208.989168)
		(width 0.14732)
		(layer "In13.Cu")
		(net "P5E_CPU0_PE0_RX_DN<11>")
	)
	(segment
		(start 316.05347 -386.99059)
		(end 315.95695 -387.13791)
		(width 0.14732)
		(layer "In13.Cu")
		(net "P5E_CPU0_PE0_RX_DN<11>")
	)
	(segment
		(start 346.611956 -215.926924)
		(end 346.610432 -215.926162)
		(width 0.0889)
		(layer "In13.Cu")
		(net "P5E_CPU0_PE0_RX_DN<11>")
	)
	(segment
		(start 316.046104 -387.565392)
		(end 316.193424 -387.661658)
		(width 0.14732)
		(layer "In13.Cu")
		(net "P5E_CPU0_PE0_RX_DN<11>")
	)
	(segment
		(start 347.080078 -219.01658)
		(end 347.088968 -219.0115)
		(width 0.0889)
		(layer "In13.Cu")
		(net "P5E_CPU0_PE0_RX_DN<11>")
	)
	(segment
		(start 317.200026 -392.48588)
		(end 317.10376 -392.6332)
		(width 0.14732)
		(layer "In13.Cu")
		(net "P5E_CPU0_PE0_RX_DN<11>")
	)
	(segment
		(start 307.815488 -348.119954)
		(end 315.816996 -386.466588)
		(width 0.14732)
		(layer "In13.Cu")
		(net "P5E_CPU0_PE0_RX_DN<11>")
	)
	(segment
		(start 322.650104 -437.152288)
		(end 322.650104 -436.889906)
		(width 0.14732)
		(layer "In13.Cu")
		(net "P5E_CPU0_PE0_RX_DN<11>")
	)
	(segment
		(start 313.681618 -324.425564)
		(end 313.681618 -324.425818)
		(width 0.14732)
		(layer "In13.Cu")
		(net "P5E_CPU0_PE0_RX_DN<11>")
	)
	(segment
		(start 318.593724 -251.340112)
		(end 318.551306 -252.603)
		(width 0.14732)
		(layer "In13.Cu")
		(net "P5E_CPU0_PE0_RX_DN<11>")
	)
	(segment
		(start 316.422786 -388.760716)
		(end 316.512194 -389.188706)
		(width 0.14732)
		(layer "In13.Cu")
		(net "P5E_CPU0_PE0_RX_DN<11>")
	)
	(segment
		(start 313.545474 -324.562216)
		(end 312.796428 -324.872096)
		(width 0.14732)
		(layer "In13.Cu")
		(net "P5E_CPU0_PE0_RX_DN<11>")
	)
	(segment
		(start 347.363034 -221.133924)
		(end 347.519498 -220.862906)
		(width 0.0889)
		(layer "In13.Cu")
		(net "P5E_CPU0_PE0_RX_DN<11>")
	)
	(segment
		(start 339.37956 -208.989168)
		(end 338.94268 -208.989168)
		(width 0.14732)
		(layer "In13.Cu")
		(net "P5E_CPU0_PE0_RX_DN<11>")
	)
	(segment
		(start 318.551306 -252.603)
		(end 322.164964 -309.060342)
		(width 0.14732)
		(layer "In13.Cu")
		(net "P5E_CPU0_PE0_RX_DN<11>")
	)
	(segment
		(start 306.89677 -342.862916)
		(end 307.815488 -348.119954)
		(width 0.14732)
		(layer "In13.Cu")
		(net "P5E_CPU0_PE0_RX_DN<11>")
	)
	(segment
		(start 319.679828 -406.02789)
		(end 319.679828 -410.493718)
		(width 0.14732)
		(layer "In13.Cu")
		(net "P5E_CPU0_PE0_RX_DN<11>")
	)
	(segment
		(start 346.327984 -213.929722)
		(end 346.328238 -213.929468)
		(width 0.0889)
		(layer "In13.Cu")
		(net "P5E_CPU0_PE0_RX_DN<11>")
	)
	(segment
		(start 317.10376 -392.6332)
		(end 318.333628 -398.528286)
		(width 0.14732)
		(layer "In13.Cu")
		(net "P5E_CPU0_PE0_RX_DN<11>")
	)
	(arc
		(start 346.618814 -214.941912)
		(mid 346.746068 -214.811946)
		(end 346.797122 -214.637366)
		(width 0.0889)
		(layer "In13.Cu")
		(net "P5E_CPU0_PE0_RX_DN<11>")
	)
	(arc
		(start 346.604336 -215.922606)
		(mid 346.401749 -215.716255)
		(end 346.32773 -215.436704)
		(width 0.0889)
		(layer "In13.Cu")
		(net "P5E_CPU0_PE0_RX_DN<11>")
	)
	(arc
		(start 346.797884 -216.25052)
		(mid 346.750205 -216.06762)
		(end 346.619322 -215.931242)
		(width 0.0889)
		(layer "In13.Cu")
		(net "P5E_CPU0_PE0_RX_DN<11>")
	)
	(arc
		(start 346.613226 -214.261954)
		(mid 346.453154 -214.138774)
		(end 346.343224 -213.969346)
		(width 0.0889)
		(layer "In13.Cu")
		(net "P5E_CPU0_PE0_RX_DN<11>")
	)
	(arc
		(start 347.080332 -216.739978)
		(mid 346.875997 -216.537373)
		(end 346.797884 -216.260426)
		(width 0.0889)
		(layer "In13.Cu")
		(net "P5E_CPU0_PE0_RX_DN<11>")
	)
	(arc
		(start 347.26753 -220.311218)
		(mid 347.21526 -220.128853)
		(end 347.080332 -219.995496)
		(width 0.0889)
		(layer "In13.Cu")
		(net "P5E_CPU0_PE0_RX_DN<11>")
	)
	(arc
		(start 347.26753 -217.0557)
		(mid 347.21526 -216.873335)
		(end 347.080332 -216.739978)
		(width 0.0889)
		(layer "In13.Cu")
		(net "P5E_CPU0_PE0_RX_DN<11>")
	)
	(arc
		(start 346.797122 -214.637366)
		(mid 346.797319 -214.630001)
		(end 346.797376 -214.622634)
		(width 0.0889)
		(layer "In13.Cu")
		(net "P5E_CPU0_PE0_RX_DN<11>")
	)
	(arc
		(start 346.32773 -215.414606)
		(mid 346.408641 -215.144478)
		(end 346.609924 -214.946992)
		(width 0.0889)
		(layer "In13.Cu")
		(net "P5E_CPU0_PE0_RX_DN<11>")
	)
	(arc
		(start 347.47835 -220.760798)
		(mid 347.325863 -220.570702)
		(end 347.26753 -220.334078)
		(width 0.0889)
		(layer "In13.Cu")
		(net "P5E_CPU0_PE0_RX_DN<11>")
	)
	(arc
		(start 347.080332 -219.995496)
		(mid 346.875997 -219.792891)
		(end 346.797884 -219.515944)
		(width 0.0889)
		(layer "In13.Cu")
		(net "P5E_CPU0_PE0_RX_DN<11>")
	)
	(arc
		(start 347.088968 -219.0115)
		(mid 347.267444 -218.692222)
		(end 347.088968 -218.372944)
		(width 0.0889)
		(layer "In13.Cu")
		(net "P5E_CPU0_PE0_RX_DN<11>")
	)
	(arc
		(start 347.495368 -220.773752)
		(mid 347.486797 -220.767356)
		(end 347.47835 -220.760798)
		(width 0.0889)
		(layer "In13.Cu")
		(net "P5E_CPU0_PE0_RX_DN<11>")
	)
	(arc
		(start 346.797884 -219.490544)
		(mid 346.877254 -219.21681)
		(end 347.080078 -219.01658)
		(width 0.0889)
		(layer "In13.Cu")
		(net "P5E_CPU0_PE0_RX_DN<11>")
	)
	(arc
		(start 347.080332 -217.388694)
		(mid 347.215265 -217.25534)
		(end 347.26753 -217.072972)
		(width 0.0889)
		(layer "In13.Cu")
		(net "P5E_CPU0_PE0_RX_DN<11>")
	)
	(arc
		(start 346.343224 -213.969346)
		(mid 346.335261 -213.950049)
		(end 346.327984 -213.930484)
		(width 0.0889)
		(layer "In13.Cu")
		(net "P5E_CPU0_PE0_RX_DN<11>")
	)
	(arc
		(start 346.797376 -214.461344)
		(mid 346.722371 -214.345885)
		(end 346.613226 -214.261954)
		(width 0.0889)
		(layer "In13.Cu")
		(net "P5E_CPU0_PE0_RX_DN<11>")
	)
	(arc
		(start 347.080078 -218.367864)
		(mid 346.877255 -218.167633)
		(end 346.797884 -217.8939)
		(width 0.0889)
		(layer "In13.Cu")
		(net "P5E_CPU0_PE0_RX_DN<11>")
	)
	(arc
		(start 346.797884 -217.859864)
		(mid 346.878046 -217.587675)
		(end 347.080332 -217.388694)
		(width 0.0889)
		(layer "In13.Cu")
		(net "P5E_CPU0_PE0_RX_DN<11>")
	)
	(segment
		(start 346.42298 -221.669864)
		(end 346.42298 -221.134178)
		(width 0.13208)
		(layer "F.Cu")
		(net "P5E_CPU0_PE0_RX_DN<10>")
	)
	(segment
		(start 346.42298 -221.134178)
		(end 346.423234 -221.133924)
		(width 0.13208)
		(layer "F.Cu")
		(net "P5E_CPU0_PE0_RX_DN<10>")
	)
	(segment
		(start 322.87337 -309.368444)
		(end 319.238376 -251.929138)
		(width 0.14732)
		(layer "In13.Cu")
		(net "P5E_CPU0_PE0_RX_DN<10>")
	)
	(segment
		(start 346.236036 -220.809566)
		(end 346.23502 -220.810074)
		(width 0.0889)
		(layer "In13.Cu")
		(net "P5E_CPU0_PE0_RX_DN<10>")
	)
	(segment
		(start 346.227146 -219.825316)
		(end 346.236036 -219.830396)
		(width 0.0889)
		(layer "In13.Cu")
		(net "P5E_CPU0_PE0_RX_DN<10>")
	)
	(segment
		(start 329.961748 -211.52104)
		(end 331.87513 -210.72856)
		(width 0.14732)
		(layer "In13.Cu")
		(net "P5E_CPU0_PE0_RX_DN<10>")
	)
	(segment
		(start 346.236036 -219.830396)
		(end 346.242132 -219.833952)
		(width 0.0889)
		(layer "In13.Cu")
		(net "P5E_CPU0_PE0_RX_DN<10>")
	)
	(segment
		(start 345.773248 -215.10752)
		(end 345.771216 -215.10879)
		(width 0.0889)
		(layer "In13.Cu")
		(net "P5E_CPU0_PE0_RX_DN<10>")
	)
	(segment
		(start 307.552852 -342.639142)
		(end 307.302916 -331.743304)
		(width 0.14732)
		(layer "In13.Cu")
		(net "P5E_CPU0_PE0_RX_DN<10>")
	)
	(segment
		(start 307.302916 -331.743304)
		(end 307.565044 -330.926694)
		(width 0.14732)
		(layer "In13.Cu")
		(net "P5E_CPU0_PE0_RX_DN<10>")
	)
	(segment
		(start 323.977508 -438.593738)
		(end 323.692012 -438.308242)
		(width 0.14732)
		(layer "In13.Cu")
		(net "P5E_CPU0_PE0_RX_DN<10>")
	)
	(segment
		(start 308.183026 -346.255086)
		(end 307.552852 -342.639142)
		(width 0.14732)
		(layer "In13.Cu")
		(net "P5E_CPU0_PE0_RX_DN<10>")
	)
	(segment
		(start 346.579698 -221.404942)
		(end 346.423234 -221.133924)
		(width 0.0889)
		(layer "In13.Cu")
		(net "P5E_CPU0_PE0_RX_DN<10>")
	)
	(segment
		(start 319.697608 -316.992762)
		(end 322.87337 -309.368444)
		(width 0.14732)
		(layer "In13.Cu")
		(net "P5E_CPU0_PE0_RX_DN<10>")
	)
	(segment
		(start 321.122548 -404.795482)
		(end 321.122548 -398.662652)
		(width 0.14732)
		(layer "In13.Cu")
		(net "P5E_CPU0_PE0_RX_DN<10>")
	)
	(segment
		(start 308.953408 -326.54875)
		(end 309.840122 -325.662036)
		(width 0.14732)
		(layer "In13.Cu")
		(net "P5E_CPU0_PE0_RX_DN<10>")
	)
	(segment
		(start 322.468748 -410.409136)
		(end 322.468748 -406.141682)
		(width 0.14732)
		(layer "In13.Cu")
		(net "P5E_CPU0_PE0_RX_DN<10>")
	)
	(segment
		(start 344.247216 -210.298538)
		(end 345.62034 -211.671662)
		(width 0.14732)
		(layer "In13.Cu")
		(net "P5E_CPU0_PE0_RX_DN<10>")
	)
	(segment
		(start 346.227146 -221.453202)
		(end 346.236036 -221.458282)
		(width 0.0889)
		(layer "In13.Cu")
		(net "P5E_CPU0_PE0_RX_DN<10>")
	)
	(segment
		(start 345.62034 -213.270592)
		(end 345.57843 -213.312502)
		(width 0.0889)
		(layer "In13.Cu")
		(net "P5E_CPU0_PE0_RX_DN<10>")
	)
	(segment
		(start 345.76512 -215.112854)
		(end 345.76131 -215.114886)
		(width 0.0889)
		(layer "In13.Cu")
		(net "P5E_CPU0_PE0_RX_DN<10>")
	)
	(segment
		(start 345.57843 -213.312502)
		(end 345.57843 -213.894416)
		(width 0.0889)
		(layer "In13.Cu")
		(net "P5E_CPU0_PE0_RX_DN<10>")
	)
	(segment
		(start 323.692012 -438.308242)
		(end 323.692012 -424.662854)
		(width 0.14732)
		(layer "In13.Cu")
		(net "P5E_CPU0_PE0_RX_DN<10>")
	)
	(segment
		(start 346.236036 -216.574878)
		(end 346.242132 -216.578434)
		(width 0.0889)
		(layer "In13.Cu")
		(net "P5E_CPU0_PE0_RX_DN<10>")
	)
	(segment
		(start 346.227146 -218.197684)
		(end 346.236036 -218.202764)
		(width 0.0889)
		(layer "In13.Cu")
		(net "P5E_CPU0_PE0_RX_DN<10>")
	)
	(segment
		(start 345.756992 -215.755982)
		(end 345.771978 -215.764618)
		(width 0.0889)
		(layer "In13.Cu")
		(net "P5E_CPU0_PE0_RX_DN<10>")
	)
	(segment
		(start 322.468748 -406.141682)
		(end 321.122548 -404.795482)
		(width 0.14732)
		(layer "In13.Cu")
		(net "P5E_CPU0_PE0_RX_DN<10>")
	)
	(segment
		(start 346.227146 -216.569798)
		(end 346.236036 -216.574878)
		(width 0.0889)
		(layer "In13.Cu")
		(net "P5E_CPU0_PE0_RX_DN<10>")
	)
	(segment
		(start 321.122548 -398.662652)
		(end 308.183026 -346.255086)
		(width 0.14732)
		(layer "In13.Cu")
		(net "P5E_CPU0_PE0_RX_DN<10>")
	)
	(segment
		(start 312.740802 -325.662036)
		(end 313.827668 -325.211694)
		(width 0.14732)
		(layer "In13.Cu")
		(net "P5E_CPU0_PE0_RX_DN<10>")
	)
	(segment
		(start 324.6501 -438.741312)
		(end 324.502526 -438.593738)
		(width 0.14732)
		(layer "In13.Cu")
		(net "P5E_CPU0_PE0_RX_DN<10>")
	)
	(segment
		(start 309.840122 -325.662036)
		(end 312.740802 -325.662036)
		(width 0.14732)
		(layer "In13.Cu")
		(net "P5E_CPU0_PE0_RX_DN<10>")
	)
	(segment
		(start 308.953408 -329.53833)
		(end 308.953408 -326.54875)
		(width 0.14732)
		(layer "In13.Cu")
		(net "P5E_CPU0_PE0_RX_DN<10>")
	)
	(segment
		(start 346.047822 -214.425784)
		(end 346.047822 -214.622634)
		(width 0.0889)
		(layer "In13.Cu")
		(net "P5E_CPU0_PE0_RX_DN<10>")
	)
	(segment
		(start 323.01561 -220.768672)
		(end 324.642988 -216.8398)
		(width 0.14732)
		(layer "In13.Cu")
		(net "P5E_CPU0_PE0_RX_DN<10>")
	)
	(segment
		(start 346.51823 -218.676728)
		(end 346.51823 -218.707716)
		(width 0.0889)
		(layer "In13.Cu")
		(net "P5E_CPU0_PE0_RX_DN<10>")
	)
	(segment
		(start 324.642988 -216.8398)
		(end 329.961748 -211.52104)
		(width 0.14732)
		(layer "In13.Cu")
		(net "P5E_CPU0_PE0_RX_DN<10>")
	)
	(segment
		(start 342.67394 -209.647028)
		(end 344.247216 -210.298538)
		(width 0.14732)
		(layer "In13.Cu")
		(net "P5E_CPU0_PE0_RX_DN<10>")
	)
	(segment
		(start 324.502526 -438.593738)
		(end 323.977508 -438.593738)
		(width 0.14732)
		(layer "In13.Cu")
		(net "P5E_CPU0_PE0_RX_DN<10>")
	)
	(segment
		(start 345.765882 -215.112346)
		(end 345.76512 -215.112854)
		(width 0.0889)
		(layer "In13.Cu")
		(net "P5E_CPU0_PE0_RX_DN<10>")
	)
	(segment
		(start 345.76639 -215.111584)
		(end 345.765882 -215.112346)
		(width 0.0889)
		(layer "In13.Cu")
		(net "P5E_CPU0_PE0_RX_DN<10>")
	)
	(segment
		(start 314.21705 -324.822312)
		(end 319.697608 -316.992762)
		(width 0.14732)
		(layer "In13.Cu")
		(net "P5E_CPU0_PE0_RX_DN<10>")
	)
	(segment
		(start 319.252346 -251.511816)
		(end 323.01561 -220.768672)
		(width 0.14732)
		(layer "In13.Cu")
		(net "P5E_CPU0_PE0_RX_DN<10>")
	)
	(segment
		(start 345.774772 -215.106504)
		(end 345.773248 -215.10752)
		(width 0.0889)
		(layer "In13.Cu")
		(net "P5E_CPU0_PE0_RX_DN<10>")
	)
	(segment
		(start 346.236036 -219.18168)
		(end 346.227146 -219.18676)
		(width 0.0889)
		(layer "In13.Cu")
		(net "P5E_CPU0_PE0_RX_DN<10>")
	)
	(segment
		(start 338.166456 -209.647028)
		(end 342.67394 -209.647028)
		(width 0.14732)
		(layer "In13.Cu")
		(net "P5E_CPU0_PE0_RX_DN<10>")
	)
	(segment
		(start 345.62034 -213.248494)
		(end 345.62034 -213.270592)
		(width 0.0889)
		(layer "In13.Cu")
		(net "P5E_CPU0_PE0_RX_DN<10>")
	)
	(segment
		(start 345.771216 -215.10879)
		(end 345.76639 -215.111584)
		(width 0.0889)
		(layer "In13.Cu")
		(net "P5E_CPU0_PE0_RX_DN<10>")
	)
	(segment
		(start 346.558616 -221.48292)
		(end 346.579698 -221.404942)
		(width 0.0889)
		(layer "In13.Cu")
		(net "P5E_CPU0_PE0_RX_DN<10>")
	)
	(segment
		(start 323.692012 -424.662854)
		(end 323.376544 -423.40657)
		(width 0.14732)
		(layer "In13.Cu")
		(net "P5E_CPU0_PE0_RX_DN<10>")
	)
	(segment
		(start 345.76131 -215.114886)
		(end 345.756992 -215.117426)
		(width 0.0889)
		(layer "In13.Cu")
		(net "P5E_CPU0_PE0_RX_DN<10>")
	)
	(segment
		(start 324.6501 -439.0898)
		(end 324.6501 -438.741312)
		(width 0.14732)
		(layer "In13.Cu")
		(net "P5E_CPU0_PE0_RX_DN<10>")
	)
	(segment
		(start 346.518484 -220.319854)
		(end 346.518484 -220.334078)
		(width 0.0889)
		(layer "In13.Cu")
		(net "P5E_CPU0_PE0_RX_DN<10>")
	)
	(segment
		(start 319.238376 -251.929138)
		(end 319.252346 -251.511816)
		(width 0.14732)
		(layer "In13.Cu")
		(net "P5E_CPU0_PE0_RX_DN<10>")
	)
	(segment
		(start 346.236036 -217.554048)
		(end 346.227146 -217.559128)
		(width 0.0889)
		(layer "In13.Cu")
		(net "P5E_CPU0_PE0_RX_DN<10>")
	)
	(segment
		(start 313.827668 -325.211694)
		(end 314.21705 -324.822312)
		(width 0.14732)
		(layer "In13.Cu")
		(net "P5E_CPU0_PE0_RX_DN<10>")
	)
	(segment
		(start 346.23502 -220.810074)
		(end 346.227146 -220.814646)
		(width 0.0889)
		(layer "In13.Cu")
		(net "P5E_CPU0_PE0_RX_DN<10>")
	)
	(segment
		(start 323.376544 -423.40657)
		(end 322.468748 -410.409136)
		(width 0.14732)
		(layer "In13.Cu")
		(net "P5E_CPU0_PE0_RX_DN<10>")
	)
	(segment
		(start 331.87513 -210.72856)
		(end 338.166456 -209.647028)
		(width 0.14732)
		(layer "In13.Cu")
		(net "P5E_CPU0_PE0_RX_DN<10>")
	)
	(segment
		(start 345.62034 -211.671662)
		(end 345.62034 -213.248494)
		(width 0.14732)
		(layer "In13.Cu")
		(net "P5E_CPU0_PE0_RX_DN<10>")
	)
	(segment
		(start 307.565044 -330.926694)
		(end 308.953408 -329.53833)
		(width 0.14732)
		(layer "In13.Cu")
		(net "P5E_CPU0_PE0_RX_DN<10>")
	)
	(arc
		(start 346.048584 -221.133924)
		(mid 346.096263 -221.316824)
		(end 346.227146 -221.453202)
		(width 0.0889)
		(layer "In13.Cu")
		(net "P5E_CPU0_PE0_RX_DN<10>")
	)
	(arc
		(start 345.771978 -215.764618)
		(mid 345.974565 -215.970969)
		(end 346.048584 -216.25052)
		(width 0.0889)
		(layer "In13.Cu")
		(net "P5E_CPU0_PE0_RX_DN<10>")
	)
	(arc
		(start 345.756992 -215.117426)
		(mid 345.578395 -215.436704)
		(end 345.756992 -215.755982)
		(width 0.0889)
		(layer "In13.Cu")
		(net "P5E_CPU0_PE0_RX_DN<10>")
	)
	(arc
		(start 346.227146 -219.18676)
		(mid 346.04867 -219.506038)
		(end 346.227146 -219.825316)
		(width 0.0889)
		(layer "In13.Cu")
		(net "P5E_CPU0_PE0_RX_DN<10>")
	)
	(arc
		(start 345.57843 -213.894416)
		(mid 345.653504 -214.009701)
		(end 345.76258 -214.093552)
		(width 0.0889)
		(layer "In13.Cu")
		(net "P5E_CPU0_PE0_RX_DN<10>")
	)
	(arc
		(start 346.048838 -217.863674)
		(mid 346.048505 -217.876118)
		(end 346.048584 -217.888566)
		(width 0.0889)
		(layer "In13.Cu")
		(net "P5E_CPU0_PE0_RX_DN<10>")
	)
	(arc
		(start 346.227146 -217.559128)
		(mid 346.099892 -217.689094)
		(end 346.048838 -217.863674)
		(width 0.0889)
		(layer "In13.Cu")
		(net "P5E_CPU0_PE0_RX_DN<10>")
	)
	(arc
		(start 346.242132 -219.833952)
		(mid 346.444545 -220.040365)
		(end 346.518484 -220.319854)
		(width 0.0889)
		(layer "In13.Cu")
		(net "P5E_CPU0_PE0_RX_DN<10>")
	)
	(arc
		(start 346.518484 -220.334078)
		(mid 346.439343 -220.608701)
		(end 346.236036 -220.809566)
		(width 0.0889)
		(layer "In13.Cu")
		(net "P5E_CPU0_PE0_RX_DN<10>")
	)
	(arc
		(start 345.76258 -214.093552)
		(mid 345.936671 -214.232646)
		(end 346.047822 -214.425784)
		(width 0.0889)
		(layer "In13.Cu")
		(net "P5E_CPU0_PE0_RX_DN<10>")
	)
	(arc
		(start 346.227146 -220.814646)
		(mid 346.099892 -220.944612)
		(end 346.048838 -221.119192)
		(width 0.0889)
		(layer "In13.Cu")
		(net "P5E_CPU0_PE0_RX_DN<10>")
	)
	(arc
		(start 346.236036 -218.202764)
		(mid 346.438859 -218.402995)
		(end 346.51823 -218.676728)
		(width 0.0889)
		(layer "In13.Cu")
		(net "P5E_CPU0_PE0_RX_DN<10>")
	)
	(arc
		(start 346.048584 -216.25052)
		(mid 346.096263 -216.43342)
		(end 346.227146 -216.569798)
		(width 0.0889)
		(layer "In13.Cu")
		(net "P5E_CPU0_PE0_RX_DN<10>")
	)
	(arc
		(start 346.242132 -216.578434)
		(mid 346.518446 -217.067928)
		(end 346.236036 -217.554048)
		(width 0.0889)
		(layer "In13.Cu")
		(net "P5E_CPU0_PE0_RX_DN<10>")
	)
	(arc
		(start 346.047822 -214.622634)
		(mid 345.974841 -214.900419)
		(end 345.774772 -215.106504)
		(width 0.0889)
		(layer "In13.Cu")
		(net "P5E_CPU0_PE0_RX_DN<10>")
	)
	(arc
		(start 346.236036 -221.458282)
		(mid 346.394524 -221.507215)
		(end 346.558616 -221.48292)
		(width 0.0889)
		(layer "In13.Cu")
		(net "P5E_CPU0_PE0_RX_DN<10>")
	)
	(arc
		(start 346.51823 -218.707716)
		(mid 346.43886 -218.98145)
		(end 346.236036 -219.18168)
		(width 0.0889)
		(layer "In13.Cu")
		(net "P5E_CPU0_PE0_RX_DN<10>")
	)
	(arc
		(start 346.048584 -217.888566)
		(mid 346.098653 -218.065791)
		(end 346.227146 -218.197684)
		(width 0.0889)
		(layer "In13.Cu")
		(net "P5E_CPU0_PE0_RX_DN<10>")
	)
	(arc
		(start 346.048838 -221.119192)
		(mid 346.048641 -221.126557)
		(end 346.048584 -221.133924)
		(width 0.0889)
		(layer "In13.Cu")
		(net "P5E_CPU0_PE0_RX_DN<10>")
	)
	(segment
		(start 337.02498 -221.669864)
		(end 337.02498 -221.134178)
		(width 0.13208)
		(layer "F.Cu")
		(net "P5E_CPU0_PE0_RX_DN<0>")
	)
	(segment
		(start 337.02498 -221.134178)
		(end 337.025234 -221.133924)
		(width 0.13208)
		(layer "F.Cu")
		(net "P5E_CPU0_PE0_RX_DN<0>")
	)
	(segment
		(start 332.60284 -311.107328)
		(end 329.80757 -266.649708)
		(width 0.14732)
		(layer "In13.Cu")
		(net "P5E_CPU0_PE0_RX_DN<0>")
	)
	(segment
		(start 333.772256 -250.815348)
		(end 333.772256 -249.757692)
		(width 0.14732)
		(layer "In13.Cu")
		(net "P5E_CPU0_PE0_RX_DN<0>")
	)
	(segment
		(start 329.80757 -266.649708)
		(end 330.834238 -260.093968)
		(width 0.14732)
		(layer "In13.Cu")
		(net "P5E_CPU0_PE0_RX_DN<0>")
	)
	(segment
		(start 317.66637 -343.070942)
		(end 317.078106 -340.771226)
		(width 0.14732)
		(layer "In13.Cu")
		(net "P5E_CPU0_PE0_RX_DN<0>")
	)
	(segment
		(start 345.650058 -438.741312)
		(end 345.502484 -438.593738)
		(width 0.14732)
		(layer "In13.Cu")
		(net "P5E_CPU0_PE0_RX_DN<0>")
	)
	(segment
		(start 344.692478 -438.30875)
		(end 344.692478 -424.21937)
		(width 0.14732)
		(layer "In13.Cu")
		(net "P5E_CPU0_PE0_RX_DN<0>")
	)
	(segment
		(start 334.58023 -226.025964)
		(end 334.58023 -226.003104)
		(width 0.0889)
		(layer "In13.Cu")
		(net "P5E_CPU0_PE0_RX_DN<0>")
	)
	(segment
		(start 333.444596 -248.520966)
		(end 331.469238 -242.328446)
		(width 0.14732)
		(layer "In13.Cu")
		(net "P5E_CPU0_PE0_RX_DN<0>")
	)
	(segment
		(start 345.650058 -439.0898)
		(end 345.650058 -438.741312)
		(width 0.14732)
		(layer "In13.Cu")
		(net "P5E_CPU0_PE0_RX_DN<0>")
	)
	(segment
		(start 344.692478 -424.21937)
		(end 348.595696 -417.843208)
		(width 0.14732)
		(layer "In13.Cu")
		(net "P5E_CPU0_PE0_RX_DN<0>")
	)
	(segment
		(start 333.4385 -228.137466)
		(end 333.640938 -227.784406)
		(width 0.0889)
		(layer "In13.Cu")
		(net "P5E_CPU0_PE0_RX_DN<0>")
	)
	(segment
		(start 331.469238 -242.328446)
		(end 331.357732 -233.212386)
		(width 0.14732)
		(layer "In13.Cu")
		(net "P5E_CPU0_PE0_RX_DN<0>")
	)
	(segment
		(start 333.117444 -252.089666)
		(end 333.692246 -251.268484)
		(width 0.14732)
		(layer "In13.Cu")
		(net "P5E_CPU0_PE0_RX_DN<0>")
	)
	(segment
		(start 333.913734 -227.16109)
		(end 333.923132 -227.155502)
		(width 0.0889)
		(layer "In13.Cu")
		(net "P5E_CPU0_PE0_RX_DN<0>")
	)
	(segment
		(start 334.11033 -226.83978)
		(end 334.11033 -226.831144)
		(width 0.0889)
		(layer "In13.Cu")
		(net "P5E_CPU0_PE0_RX_DN<0>")
	)
	(segment
		(start 322.47967 -329.934316)
		(end 327.980802 -322.077842)
		(width 0.14732)
		(layer "In13.Cu")
		(net "P5E_CPU0_PE0_RX_DN<0>")
	)
	(segment
		(start 336.742278 -222.272098)
		(end 336.742532 -222.272098)
		(width 0.0889)
		(layer "In13.Cu")
		(net "P5E_CPU0_PE0_RX_DN<0>")
	)
	(segment
		(start 336.92973 -221.956376)
		(end 336.92973 -221.94774)
		(width 0.0889)
		(layer "In13.Cu")
		(net "P5E_CPU0_PE0_RX_DN<0>")
	)
	(segment
		(start 336.272632 -223.085914)
		(end 336.281522 -223.080834)
		(width 0.0889)
		(layer "In13.Cu")
		(net "P5E_CPU0_PE0_RX_DN<0>")
	)
	(segment
		(start 350.5327 -398.65046)
		(end 317.66637 -343.070942)
		(width 0.14732)
		(layer "In13.Cu")
		(net "P5E_CPU0_PE0_RX_DN<0>")
	)
	(segment
		(start 333.772256 -249.757692)
		(end 333.444596 -248.966482)
		(width 0.14732)
		(layer "In13.Cu")
		(net "P5E_CPU0_PE0_RX_DN<0>")
	)
	(segment
		(start 336.460084 -222.761556)
		(end 336.460084 -222.746062)
		(width 0.0889)
		(layer "In13.Cu")
		(net "P5E_CPU0_PE0_RX_DN<0>")
	)
	(segment
		(start 327.980802 -322.077842)
		(end 332.60284 -311.107328)
		(width 0.14732)
		(layer "In13.Cu")
		(net "P5E_CPU0_PE0_RX_DN<0>")
	)
	(segment
		(start 333.370682 -228.25583)
		(end 333.4385 -228.137466)
		(width 0.0889)
		(layer "In13.Cu")
		(net "P5E_CPU0_PE0_RX_DN<0>")
	)
	(segment
		(start 331.551534 -232.126028)
		(end 332.777846 -229.507034)
		(width 0.14732)
		(layer "In13.Cu")
		(net "P5E_CPU0_PE0_RX_DN<0>")
	)
	(segment
		(start 335.520284 -224.389442)
		(end 335.520284 -224.379536)
		(width 0.0889)
		(layer "In13.Cu")
		(net "P5E_CPU0_PE0_RX_DN<0>")
	)
	(segment
		(start 317.078106 -335.33588)
		(end 322.47967 -329.934316)
		(width 0.14732)
		(layer "In13.Cu")
		(net "P5E_CPU0_PE0_RX_DN<0>")
	)
	(segment
		(start 348.595696 -417.843208)
		(end 348.59595 -417.843208)
		(width 0.14732)
		(layer "In13.Cu")
		(net "P5E_CPU0_PE0_RX_DN<0>")
	)
	(segment
		(start 351.834704 -400.265392)
		(end 350.5327 -398.65046)
		(width 0.14732)
		(layer "In13.Cu")
		(net "P5E_CPU0_PE0_RX_DN<0>")
	)
	(segment
		(start 348.59595 -417.843208)
		(end 353.101148 -410.484066)
		(width 0.14732)
		(layer "In13.Cu")
		(net "P5E_CPU0_PE0_RX_DN<0>")
	)
	(segment
		(start 332.999588 -254.374904)
		(end 332.999588 -252.75667)
		(width 0.14732)
		(layer "In13.Cu")
		(net "P5E_CPU0_PE0_RX_DN<0>")
	)
	(segment
		(start 333.444596 -248.966482)
		(end 333.444596 -248.520966)
		(width 0.14732)
		(layer "In13.Cu")
		(net "P5E_CPU0_PE0_RX_DN<0>")
	)
	(segment
		(start 345.502484 -438.593738)
		(end 344.977466 -438.593738)
		(width 0.14732)
		(layer "In13.Cu")
		(net "P5E_CPU0_PE0_RX_DN<0>")
	)
	(segment
		(start 353.101148 -406.632664)
		(end 351.834704 -400.265392)
		(width 0.14732)
		(layer "In13.Cu")
		(net "P5E_CPU0_PE0_RX_DN<0>")
	)
	(segment
		(start 337.181698 -221.404942)
		(end 337.025234 -221.133924)
		(width 0.0889)
		(layer "In13.Cu")
		(net "P5E_CPU0_PE0_RX_DN<0>")
	)
	(segment
		(start 332.777846 -229.507034)
		(end 333.189326 -228.487732)
		(width 0.14732)
		(layer "In13.Cu")
		(net "P5E_CPU0_PE0_RX_DN<0>")
	)
	(segment
		(start 333.911194 -227.162868)
		(end 333.91094 -227.162614)
		(width 0.0889)
		(layer "In13.Cu")
		(net "P5E_CPU0_PE0_RX_DN<0>")
	)
	(segment
		(start 333.313532 -228.27107)
		(end 333.370682 -228.25583)
		(width 0.0889)
		(layer "In13.Cu")
		(net "P5E_CPU0_PE0_RX_DN<0>")
	)
	(segment
		(start 335.050384 -225.203258)
		(end 335.050384 -225.193352)
		(width 0.0889)
		(layer "In13.Cu")
		(net "P5E_CPU0_PE0_RX_DN<0>")
	)
	(segment
		(start 332.122272 -256.8067)
		(end 332.877668 -256.051558)
		(width 0.14732)
		(layer "In13.Cu")
		(net "P5E_CPU0_PE0_RX_DN<0>")
	)
	(segment
		(start 333.692246 -251.268484)
		(end 333.772256 -250.815348)
		(width 0.14732)
		(layer "In13.Cu")
		(net "P5E_CPU0_PE0_RX_DN<0>")
	)
	(segment
		(start 333.91094 -227.162614)
		(end 333.913734 -227.16109)
		(width 0.0889)
		(layer "In13.Cu")
		(net "P5E_CPU0_PE0_RX_DN<0>")
	)
	(segment
		(start 333.30261 -228.29012)
		(end 333.313532 -228.27107)
		(width 0.0889)
		(layer "In13.Cu")
		(net "P5E_CPU0_PE0_RX_DN<0>")
	)
	(segment
		(start 344.977466 -438.593738)
		(end 344.692478 -438.30875)
		(width 0.14732)
		(layer "In13.Cu")
		(net "P5E_CPU0_PE0_RX_DN<0>")
	)
	(segment
		(start 335.332832 -224.7138)
		(end 335.341722 -224.70872)
		(width 0.0889)
		(layer "In13.Cu")
		(net "P5E_CPU0_PE0_RX_DN<0>")
	)
	(segment
		(start 333.189326 -228.487732)
		(end 333.30261 -228.29012)
		(width 0.14732)
		(layer "In13.Cu")
		(net "P5E_CPU0_PE0_RX_DN<0>")
	)
	(segment
		(start 331.357732 -233.212386)
		(end 331.551534 -232.126028)
		(width 0.14732)
		(layer "In13.Cu")
		(net "P5E_CPU0_PE0_RX_DN<0>")
	)
	(segment
		(start 335.98993 -223.584262)
		(end 335.98993 -223.561402)
		(width 0.0889)
		(layer "In13.Cu")
		(net "P5E_CPU0_PE0_RX_DN<0>")
	)
	(segment
		(start 317.078106 -340.771226)
		(end 317.078106 -335.33588)
		(width 0.14732)
		(layer "In13.Cu")
		(net "P5E_CPU0_PE0_RX_DN<0>")
	)
	(segment
		(start 330.834238 -260.093968)
		(end 332.122272 -256.8067)
		(width 0.14732)
		(layer "In13.Cu")
		(net "P5E_CPU0_PE0_RX_DN<0>")
	)
	(segment
		(start 333.640938 -227.784406)
		(end 333.640938 -227.64496)
		(width 0.0889)
		(layer "In13.Cu")
		(net "P5E_CPU0_PE0_RX_DN<0>")
	)
	(segment
		(start 337.157568 -221.494096)
		(end 337.181698 -221.404942)
		(width 0.0889)
		(layer "In13.Cu")
		(net "P5E_CPU0_PE0_RX_DN<0>")
	)
	(segment
		(start 333.17053 -255.344676)
		(end 332.999588 -254.374904)
		(width 0.14732)
		(layer "In13.Cu")
		(net "P5E_CPU0_PE0_RX_DN<0>")
	)
	(segment
		(start 334.386936 -226.345242)
		(end 334.393032 -226.341686)
		(width 0.0889)
		(layer "In13.Cu")
		(net "P5E_CPU0_PE0_RX_DN<0>")
	)
	(segment
		(start 332.999588 -252.75667)
		(end 333.117444 -252.089666)
		(width 0.14732)
		(layer "In13.Cu")
		(net "P5E_CPU0_PE0_RX_DN<0>")
	)
	(segment
		(start 334.862932 -225.527616)
		(end 334.871822 -225.522536)
		(width 0.0889)
		(layer "In13.Cu")
		(net "P5E_CPU0_PE0_RX_DN<0>")
	)
	(segment
		(start 332.877668 -256.051558)
		(end 333.17053 -255.344676)
		(width 0.14732)
		(layer "In13.Cu")
		(net "P5E_CPU0_PE0_RX_DN<0>")
	)
	(segment
		(start 353.101148 -410.484066)
		(end 353.101148 -406.632664)
		(width 0.14732)
		(layer "In13.Cu")
		(net "P5E_CPU0_PE0_RX_DN<0>")
	)
	(arc
		(start 335.050384 -225.193352)
		(mid 335.128495 -224.916403)
		(end 335.332832 -224.7138)
		(width 0.0889)
		(layer "In13.Cu")
		(net "P5E_CPU0_PE0_RX_DN<0>")
	)
	(arc
		(start 335.98993 -223.561402)
		(mid 336.069149 -223.286717)
		(end 336.272632 -223.085914)
		(width 0.0889)
		(layer "In13.Cu")
		(net "P5E_CPU0_PE0_RX_DN<0>")
	)
	(arc
		(start 336.742532 -222.272098)
		(mid 336.877465 -222.138744)
		(end 336.92973 -221.956376)
		(width 0.0889)
		(layer "In13.Cu")
		(net "P5E_CPU0_PE0_RX_DN<0>")
	)
	(arc
		(start 335.802732 -223.899984)
		(mid 335.937665 -223.76663)
		(end 335.98993 -223.584262)
		(width 0.0889)
		(layer "In13.Cu")
		(net "P5E_CPU0_PE0_RX_DN<0>")
	)
	(arc
		(start 333.923132 -227.155502)
		(mid 334.058065 -227.022148)
		(end 334.11033 -226.83978)
		(width 0.0889)
		(layer "In13.Cu")
		(net "P5E_CPU0_PE0_RX_DN<0>")
	)
	(arc
		(start 336.460084 -222.746062)
		(mid 336.539454 -222.472328)
		(end 336.742278 -222.272098)
		(width 0.0889)
		(layer "In13.Cu")
		(net "P5E_CPU0_PE0_RX_DN<0>")
	)
	(arc
		(start 333.640938 -227.64496)
		(mid 333.713108 -227.368618)
		(end 333.911194 -227.162868)
		(width 0.0889)
		(layer "In13.Cu")
		(net "P5E_CPU0_PE0_RX_DN<0>")
	)
	(arc
		(start 335.341722 -224.70872)
		(mid 335.472636 -224.57236)
		(end 335.520284 -224.389442)
		(width 0.0889)
		(layer "In13.Cu")
		(net "P5E_CPU0_PE0_RX_DN<0>")
	)
	(arc
		(start 334.11033 -226.831144)
		(mid 334.184321 -226.551578)
		(end 334.386936 -226.345242)
		(width 0.0889)
		(layer "In13.Cu")
		(net "P5E_CPU0_PE0_RX_DN<0>")
	)
	(arc
		(start 335.520284 -224.379536)
		(mid 335.598395 -224.102587)
		(end 335.802732 -223.899984)
		(width 0.0889)
		(layer "In13.Cu")
		(net "P5E_CPU0_PE0_RX_DN<0>")
	)
	(arc
		(start 334.871822 -225.522536)
		(mid 335.002736 -225.386176)
		(end 335.050384 -225.203258)
		(width 0.0889)
		(layer "In13.Cu")
		(net "P5E_CPU0_PE0_RX_DN<0>")
	)
	(arc
		(start 336.281522 -223.080834)
		(mid 336.412436 -222.944474)
		(end 336.460084 -222.761556)
		(width 0.0889)
		(layer "In13.Cu")
		(net "P5E_CPU0_PE0_RX_DN<0>")
	)
	(arc
		(start 336.92973 -221.94774)
		(mid 336.989773 -221.693853)
		(end 337.157568 -221.494096)
		(width 0.0889)
		(layer "In13.Cu")
		(net "P5E_CPU0_PE0_RX_DN<0>")
	)
	(arc
		(start 334.393032 -226.341686)
		(mid 334.527965 -226.208332)
		(end 334.58023 -226.025964)
		(width 0.0889)
		(layer "In13.Cu")
		(net "P5E_CPU0_PE0_RX_DN<0>")
	)
	(arc
		(start 334.58023 -226.003104)
		(mid 334.659449 -225.728419)
		(end 334.862932 -225.527616)
		(width 0.0889)
		(layer "In13.Cu")
		(net "P5E_CPU0_PE0_RX_DN<0>")
	)
	(segment
		(start 151.94026 -20.165822)
		(end 151.94026 -21.199348)
		(width 0.254)
		(layer "F.Cu")
		(net "P3V_BAT_R1")
	)
	(segment
		(start 151.456898 -16.550132)
		(end 151.456898 -19.68246)
		(width 0.254)
		(layer "F.Cu")
		(net "P3V_BAT_R1")
	)
	(segment
		(start 151.94026 -21.199348)
		(end 151.69388 -21.445728)
		(width 0.254)
		(layer "F.Cu")
		(net "P3V_BAT_R1")
	)
	(segment
		(start 151.69388 -21.445728)
		(end 151.69388 -22.424898)
		(width 0.254)
		(layer "F.Cu")
		(net "P3V_BAT_R1")
	)
	(segment
		(start 151.456898 -19.68246)
		(end 151.94026 -20.165822)
		(width 0.254)
		(layer "F.Cu")
		(net "P3V_BAT_R1")
	)
	(via
		(at 151.94026 -21.199348)
		(size 0.762)
		(drill 0.381)
		(layers "F.Cu" "B.Cu")
		(net "P3V_BAT_R1")
	)
	(segment
		(start 299.891704 -27.141932)
		(end 299.891704 -27.952954)
		(width 0.254)
		(layer "F.Cu")
		(net "P3V_BAT_R")
	)
	(segment
		(start 301.650654 -27.7114)
		(end 300.4566 -27.7114)
		(width 0.254)
		(layer "F.Cu")
		(net "P3V_BAT_R")
	)
	(segment
		(start 300.28515 -27.88285)
		(end 300.28515 -28.3464)
		(width 0.254)
		(layer "F.Cu")
		(net "P3V_BAT_R")
	)
	(segment
		(start 301.936912 -27.997658)
		(end 301.650654 -27.7114)
		(width 0.254)
		(layer "F.Cu")
		(net "P3V_BAT_R")
	)
	(segment
		(start 153.34488 -24.983948)
		(end 153.34488 -24.729948)
		(width 0.254)
		(layer "F.Cu")
		(net "P3V_BAT_R")
	)
	(segment
		(start 302.507142 -27.997658)
		(end 301.936912 -27.997658)
		(width 0.254)
		(layer "F.Cu")
		(net "P3V_BAT_R")
	)
	(segment
		(start 299.891704 -27.952954)
		(end 300.28515 -28.3464)
		(width 0.254)
		(layer "F.Cu")
		(net "P3V_BAT_R")
	)
	(segment
		(start 153.34488 -24.729948)
		(end 151.83993 -23.224998)
		(width 0.254)
		(layer "F.Cu")
		(net "P3V_BAT_R")
	)
	(segment
		(start 300.4566 -27.7114)
		(end 300.28515 -27.88285)
		(width 0.254)
		(layer "F.Cu")
		(net "P3V_BAT_R")
	)
	(segment
		(start 151.83993 -23.224998)
		(end 151.69388 -23.224998)
		(width 0.254)
		(layer "F.Cu")
		(net "P3V_BAT_R")
	)
	(via
		(at 299.891704 -27.141932)
		(size 0.508)
		(drill 0.254)
		(layers "F.Cu" "B.Cu")
		(net "P3V_BAT_R")
	)
	(via
		(at 153.34488 -24.983948)
		(size 0.508)
		(drill 0.254)
		(layers "F.Cu" "B.Cu")
		(net "P3V_BAT_R")
	)
	(segment
		(start 297.265344 -29.768292)
		(end 299.891704 -27.141932)
		(width 0.254)
		(layer "In11.Cu")
		(net "P3V_BAT_R")
	)
	(segment
		(start 195.432426 -25.512522)
		(end 199.097392 -29.177488)
		(width 0.254)
		(layer "In11.Cu")
		(net "P3V_BAT_R")
	)
	(segment
		(start 240.606072 -50.502312)
		(end 240.606072 -48.0441)
		(width 0.254)
		(layer "In11.Cu")
		(net "P3V_BAT_R")
	)
	(segment
		(start 229.698042 -41.900348)
		(end 231.06888 -43.271186)
		(width 0.254)
		(layer "In11.Cu")
		(net "P3V_BAT_R")
	)
	(segment
		(start 248.44121 -42.281856)
		(end 252.713744 -42.281856)
		(width 0.254)
		(layer "In11.Cu")
		(net "P3V_BAT_R")
	)
	(segment
		(start 238.14151 -50.510948)
		(end 238.873792 -51.24323)
		(width 0.254)
		(layer "In11.Cu")
		(net "P3V_BAT_R")
	)
	(segment
		(start 170.13047 -20.961858)
		(end 170.71213 -20.961858)
		(width 0.254)
		(layer "In11.Cu")
		(net "P3V_BAT_R")
	)
	(segment
		(start 267.621512 -35.349688)
		(end 273.202908 -29.768292)
		(width 0.254)
		(layer "In11.Cu")
		(net "P3V_BAT_R")
	)
	(segment
		(start 153.34488 -24.983948)
		(end 154.33802 -25.977088)
		(width 0.254)
		(layer "In11.Cu")
		(net "P3V_BAT_R")
	)
	(segment
		(start 239.865154 -51.24323)
		(end 240.606072 -50.502312)
		(width 0.254)
		(layer "In11.Cu")
		(net "P3V_BAT_R")
	)
	(segment
		(start 243.133118 -47.589948)
		(end 248.44121 -42.281856)
		(width 0.254)
		(layer "In11.Cu")
		(net "P3V_BAT_R")
	)
	(segment
		(start 231.06888 -47.462948)
		(end 234.11688 -50.510948)
		(width 0.254)
		(layer "In11.Cu")
		(net "P3V_BAT_R")
	)
	(segment
		(start 154.33802 -25.977088)
		(end 161.18586 -25.977088)
		(width 0.254)
		(layer "In11.Cu")
		(net "P3V_BAT_R")
	)
	(segment
		(start 200.97242 -29.177488)
		(end 204.39888 -32.603948)
		(width 0.254)
		(layer "In11.Cu")
		(net "P3V_BAT_R")
	)
	(segment
		(start 238.873792 -51.24323)
		(end 239.865154 -51.24323)
		(width 0.254)
		(layer "In11.Cu")
		(net "P3V_BAT_R")
	)
	(segment
		(start 231.06888 -43.271186)
		(end 231.06888 -47.462948)
		(width 0.254)
		(layer "In11.Cu")
		(net "P3V_BAT_R")
	)
	(segment
		(start 179.705 -19.014948)
		(end 183.74106 -19.014948)
		(width 0.254)
		(layer "In11.Cu")
		(net "P3V_BAT_R")
	)
	(segment
		(start 195.432426 -22.291294)
		(end 195.432426 -25.512522)
		(width 0.254)
		(layer "In11.Cu")
		(net "P3V_BAT_R")
	)
	(segment
		(start 199.097392 -29.177488)
		(end 200.97242 -29.177488)
		(width 0.254)
		(layer "In11.Cu")
		(net "P3V_BAT_R")
	)
	(segment
		(start 223.76638 -41.900348)
		(end 229.698042 -41.900348)
		(width 0.254)
		(layer "In11.Cu")
		(net "P3V_BAT_R")
	)
	(segment
		(start 209.75828 -32.603948)
		(end 218.03868 -40.884348)
		(width 0.254)
		(layer "In11.Cu")
		(net "P3V_BAT_R")
	)
	(segment
		(start 176.49952 -19.014948)
		(end 177.165 -19.014948)
		(width 0.254)
		(layer "In11.Cu")
		(net "P3V_BAT_R")
	)
	(segment
		(start 185.4073 -19.688048)
		(end 185.60542 -19.489928)
		(width 0.254)
		(layer "In11.Cu")
		(net "P3V_BAT_R")
	)
	(segment
		(start 252.713744 -42.281856)
		(end 253.487174 -43.055286)
		(width 0.254)
		(layer "In11.Cu")
		(net "P3V_BAT_R")
	)
	(segment
		(start 259.043932 -41.331134)
		(end 259.043932 -40.315134)
		(width 0.254)
		(layer "In11.Cu")
		(net "P3V_BAT_R")
	)
	(segment
		(start 204.39888 -32.603948)
		(end 209.75828 -32.603948)
		(width 0.254)
		(layer "In11.Cu")
		(net "P3V_BAT_R")
	)
	(segment
		(start 185.60542 -19.489928)
		(end 190.356744 -19.489928)
		(width 0.254)
		(layer "In11.Cu")
		(net "P3V_BAT_R")
	)
	(segment
		(start 241.060224 -47.589948)
		(end 243.133118 -47.589948)
		(width 0.254)
		(layer "In11.Cu")
		(net "P3V_BAT_R")
	)
	(segment
		(start 183.74106 -19.014948)
		(end 184.41416 -19.688048)
		(width 0.254)
		(layer "In11.Cu")
		(net "P3V_BAT_R")
	)
	(segment
		(start 169.51198 -21.580348)
		(end 170.13047 -20.961858)
		(width 0.254)
		(layer "In11.Cu")
		(net "P3V_BAT_R")
	)
	(segment
		(start 177.165 -19.014948)
		(end 177.8 -19.649948)
		(width 0.254)
		(layer "In11.Cu")
		(net "P3V_BAT_R")
	)
	(segment
		(start 218.03868 -40.884348)
		(end 222.75038 -40.884348)
		(width 0.254)
		(layer "In11.Cu")
		(net "P3V_BAT_R")
	)
	(segment
		(start 264.009378 -35.349688)
		(end 267.621512 -35.349688)
		(width 0.254)
		(layer "In11.Cu")
		(net "P3V_BAT_R")
	)
	(segment
		(start 253.487174 -43.055286)
		(end 257.31978 -43.055286)
		(width 0.254)
		(layer "In11.Cu")
		(net "P3V_BAT_R")
	)
	(segment
		(start 234.11688 -50.510948)
		(end 238.14151 -50.510948)
		(width 0.254)
		(layer "In11.Cu")
		(net "P3V_BAT_R")
	)
	(segment
		(start 184.41416 -19.688048)
		(end 185.4073 -19.688048)
		(width 0.254)
		(layer "In11.Cu")
		(net "P3V_BAT_R")
	)
	(segment
		(start 190.356744 -19.489928)
		(end 191.613028 -20.746212)
		(width 0.254)
		(layer "In11.Cu")
		(net "P3V_BAT_R")
	)
	(segment
		(start 161.18586 -25.977088)
		(end 165.5826 -21.580348)
		(width 0.254)
		(layer "In11.Cu")
		(net "P3V_BAT_R")
	)
	(segment
		(start 222.75038 -40.884348)
		(end 223.76638 -41.900348)
		(width 0.254)
		(layer "In11.Cu")
		(net "P3V_BAT_R")
	)
	(segment
		(start 273.202908 -29.768292)
		(end 297.265344 -29.768292)
		(width 0.254)
		(layer "In11.Cu")
		(net "P3V_BAT_R")
	)
	(segment
		(start 257.31978 -43.055286)
		(end 259.043932 -41.331134)
		(width 0.254)
		(layer "In11.Cu")
		(net "P3V_BAT_R")
	)
	(segment
		(start 191.613028 -20.746212)
		(end 193.887344 -20.746212)
		(width 0.254)
		(layer "In11.Cu")
		(net "P3V_BAT_R")
	)
	(segment
		(start 177.8 -19.649948)
		(end 179.07 -19.649948)
		(width 0.254)
		(layer "In11.Cu")
		(net "P3V_BAT_R")
	)
	(segment
		(start 170.71213 -20.961858)
		(end 171.02328 -21.273008)
		(width 0.254)
		(layer "In11.Cu")
		(net "P3V_BAT_R")
	)
	(segment
		(start 179.07 -19.649948)
		(end 179.705 -19.014948)
		(width 0.254)
		(layer "In11.Cu")
		(net "P3V_BAT_R")
	)
	(segment
		(start 174.24146 -21.273008)
		(end 176.49952 -19.014948)
		(width 0.254)
		(layer "In11.Cu")
		(net "P3V_BAT_R")
	)
	(segment
		(start 193.887344 -20.746212)
		(end 195.432426 -22.291294)
		(width 0.254)
		(layer "In11.Cu")
		(net "P3V_BAT_R")
	)
	(segment
		(start 240.606072 -48.0441)
		(end 241.060224 -47.589948)
		(width 0.254)
		(layer "In11.Cu")
		(net "P3V_BAT_R")
	)
	(segment
		(start 259.043932 -40.315134)
		(end 264.009378 -35.349688)
		(width 0.254)
		(layer "In11.Cu")
		(net "P3V_BAT_R")
	)
	(segment
		(start 165.5826 -21.580348)
		(end 169.51198 -21.580348)
		(width 0.254)
		(layer "In11.Cu")
		(net "P3V_BAT_R")
	)
	(segment
		(start 171.02328 -21.273008)
		(end 174.24146 -21.273008)
		(width 0.254)
		(layer "In11.Cu")
		(net "P3V_BAT_R")
	)
	(segment
		(start 293.720012 -34.001964)
		(end 293.78148 -33.940496)
		(width 0.254)
		(layer "F.Cu")
		(net "P3V_BAT")
	)
	(segment
		(start 300.6598 -29.337)
		(end 298.9072 -29.337)
		(width 0.254)
		(layer "F.Cu")
		(net "P3V_BAT")
	)
	(segment
		(start 301.08525 -28.3464)
		(end 301.08525 -28.91155)
		(width 0.254)
		(layer "F.Cu")
		(net "P3V_BAT")
	)
	(segment
		(start 293.78148 -31.671768)
		(end 298.33443 -27.118818)
		(width 0.254)
		(layer "F.Cu")
		(net "P3V_BAT")
	)
	(segment
		(start 298.9072 -29.337)
		(end 298.33443 -28.76423)
		(width 0.254)
		(layer "F.Cu")
		(net "P3V_BAT")
	)
	(segment
		(start 293.78148 -33.940496)
		(end 293.78148 -31.671768)
		(width 0.254)
		(layer "F.Cu")
		(net "P3V_BAT")
	)
	(segment
		(start 301.08525 -28.91155)
		(end 300.6598 -29.337)
		(width 0.254)
		(layer "F.Cu")
		(net "P3V_BAT")
	)
	(segment
		(start 298.33443 -28.76423)
		(end 298.33443 -27.118818)
		(width 0.254)
		(layer "F.Cu")
		(net "P3V_BAT")
	)
	(via
		(at 298.33443 -27.118818)
		(size 0.762)
		(drill 0.381)
		(layers "F.Cu" "B.Cu")
		(net "P3V_BAT")
	)
	(segment
		(start 303.123854 -33.658302)
		(end 303.123854 -32.462216)
		(width 0.381)
		(layer "F.Cu")
		(net "P3V3_RTC_AUX")
	)
	(segment
		(start 324.727824 -25.036272)
		(end 324.793864 -25.102312)
		(width 0.508)
		(layer "F.Cu")
		(net "P3V3_RTC_AUX")
	)
	(segment
		(start 302.566324 -34.537396)
		(end 302.566324 -34.28238)
		(width 0.381)
		(layer "F.Cu")
		(net "P3V3_RTC_AUX")
	)
	(segment
		(start 323.371972 -27.212798)
		(end 323.815456 -27.212798)
		(width 0.508)
		(layer "F.Cu")
		(net "P3V3_RTC_AUX")
	)
	(segment
		(start 322.906136 -27.678634)
		(end 323.371972 -27.212798)
		(width 0.508)
		(layer "F.Cu")
		(net "P3V3_RTC_AUX")
	)
	(segment
		(start 303.123854 -32.462216)
		(end 303.123854 -31.808928)
		(width 0.381)
		(layer "F.Cu")
		(net "P3V3_RTC_AUX")
	)
	(segment
		(start 303.457102 -31.47568)
		(end 303.457102 -29.997654)
		(width 0.635)
		(layer "F.Cu")
		(net "P3V3_RTC_AUX")
	)
	(segment
		(start 303.123854 -31.808928)
		(end 303.457102 -31.47568)
		(width 0.381)
		(layer "F.Cu")
		(net "P3V3_RTC_AUX")
	)
	(segment
		(start 324.727824 -24.431498)
		(end 324.727824 -25.036272)
		(width 0.508)
		(layer "F.Cu")
		(net "P3V3_RTC_AUX")
	)
	(segment
		(start 303.157128 -33.691576)
		(end 303.123854 -33.658302)
		(width 0.381)
		(layer "F.Cu")
		(net "P3V3_RTC_AUX")
	)
	(segment
		(start 333.481426 -46.993048)
		(end 333.23657 -46.570646)
		(width 0.2032)
		(layer "F.Cu")
		(net "P3V3_RTC_AUX")
	)
	(segment
		(start 333.508858 -47.040546)
		(end 333.481426 -46.993048)
		(width 0.2032)
		(layer "F.Cu")
		(net "P3V3_RTC_AUX")
	)
	(segment
		(start 302.566324 -34.28238)
		(end 303.157128 -33.691576)
		(width 0.381)
		(layer "F.Cu")
		(net "P3V3_RTC_AUX")
	)
	(via
		(at 322.906136 -27.678634)
		(size 0.508)
		(drill 0.254)
		(layers "F.Cu" "B.Cu")
		(net "P3V3_RTC_AUX")
	)
	(via
		(at 324.727824 -24.431498)
		(size 0.508)
		(drill 0.254)
		(layers "F.Cu" "B.Cu")
		(net "P3V3_RTC_AUX")
	)
	(via
		(at 303.157128 -33.691576)
		(size 0.508)
		(drill 0.254)
		(layers "F.Cu" "B.Cu")
		(net "P3V3_RTC_AUX")
	)
	(via
		(at 333.508858 -47.040546)
		(size 0.4572)
		(drill 0.2032)
		(layers "F.Cu" "B.Cu")
		(net "P3V3_RTC_AUX")
	)
	(segment
		(start 333.10449 -39.757096)
		(end 333.10449 -39.256208)
		(width 0.254)
		(layer "In13.Cu")
		(net "P3V3_RTC_AUX")
	)
	(segment
		(start 333.10449 -39.256208)
		(end 333.10449 -36.349178)
		(width 0.635)
		(layer "In13.Cu")
		(net "P3V3_RTC_AUX")
	)
	(segment
		(start 325.618856 -26.270712)
		(end 325.419974 -25.790652)
		(width 0.635)
		(layer "In13.Cu")
		(net "P3V3_RTC_AUX")
	)
	(segment
		(start 325.25335 -25.790652)
		(end 324.747636 -25.284938)
		(width 0.635)
		(layer "In13.Cu")
		(net "P3V3_RTC_AUX")
	)
	(segment
		(start 333.083408 -44.021502)
		(end 333.103982 -43.986196)
		(width 0.254)
		(layer "In13.Cu")
		(net "P3V3_RTC_AUX")
	)
	(segment
		(start 333.114396 -42.594276)
		(end 333.103982 -42.576496)
		(width 0.254)
		(layer "In13.Cu")
		(net "P3V3_RTC_AUX")
	)
	(segment
		(start 326.185276 -26.505408)
		(end 325.618856 -26.270712)
		(width 0.635)
		(layer "In13.Cu")
		(net "P3V3_RTC_AUX")
	)
	(segment
		(start 325.419974 -25.790652)
		(end 325.25335 -25.790652)
		(width 0.635)
		(layer "In13.Cu")
		(net "P3V3_RTC_AUX")
	)
	(segment
		(start 333.103982 -42.106596)
		(end 333.114396 -42.088816)
		(width 0.254)
		(layer "In13.Cu")
		(net "P3V3_RTC_AUX")
	)
	(segment
		(start 333.101188 -45.865796)
		(end 333.113888 -45.843952)
		(width 0.254)
		(layer "In13.Cu")
		(net "P3V3_RTC_AUX")
	)
	(segment
		(start 324.747636 -25.284938)
		(end 324.747636 -24.45131)
		(width 0.635)
		(layer "In13.Cu")
		(net "P3V3_RTC_AUX")
	)
	(segment
		(start 326.620378 -26.94051)
		(end 326.185276 -26.505408)
		(width 0.635)
		(layer "In13.Cu")
		(net "P3V3_RTC_AUX")
	)
	(segment
		(start 333.10449 -36.349178)
		(end 328.96048 -32.205168)
		(width 0.635)
		(layer "In13.Cu")
		(net "P3V3_RTC_AUX")
	)
	(segment
		(start 324.747636 -24.45131)
		(end 324.727824 -24.431498)
		(width 0.635)
		(layer "In13.Cu")
		(net "P3V3_RTC_AUX")
	)
	(segment
		(start 327.03897 -27.950922)
		(end 326.620378 -26.94051)
		(width 0.635)
		(layer "In13.Cu")
		(net "P3V3_RTC_AUX")
	)
	(segment
		(start 328.96048 -32.205168)
		(end 328.96048 -29.872432)
		(width 0.635)
		(layer "In13.Cu")
		(net "P3V3_RTC_AUX")
	)
	(segment
		(start 333.508858 -47.040546)
		(end 333.101188 -46.335696)
		(width 0.254)
		(layer "In13.Cu")
		(net "P3V3_RTC_AUX")
	)
	(segment
		(start 333.103982 -43.986196)
		(end 333.114396 -43.968416)
		(width 0.254)
		(layer "In13.Cu")
		(net "P3V3_RTC_AUX")
	)
	(segment
		(start 328.96048 -29.872432)
		(end 327.03897 -27.950922)
		(width 0.635)
		(layer "In13.Cu")
		(net "P3V3_RTC_AUX")
	)
	(arc
		(start 333.10449 -41.636696)
		(mid 333.04153 -41.401746)
		(end 333.10449 -41.166796)
		(width 0.254)
		(layer "In13.Cu")
		(net "P3V3_RTC_AUX")
	)
	(arc
		(start 333.10449 -43.046396)
		(mid 333.167428 -42.821592)
		(end 333.114396 -42.594276)
		(width 0.254)
		(layer "In13.Cu")
		(net "P3V3_RTC_AUX")
	)
	(arc
		(start 333.10195 -45.395896)
		(mid 333.039194 -45.160946)
		(end 333.10195 -44.925996)
		(width 0.254)
		(layer "In13.Cu")
		(net "P3V3_RTC_AUX")
	)
	(arc
		(start 333.10449 -40.226996)
		(mid 333.167416 -39.992046)
		(end 333.10449 -39.757096)
		(width 0.254)
		(layer "In13.Cu")
		(net "P3V3_RTC_AUX")
	)
	(arc
		(start 333.114396 -42.088816)
		(mid 333.167318 -41.861502)
		(end 333.10449 -41.636696)
		(width 0.254)
		(layer "In13.Cu")
		(net "P3V3_RTC_AUX")
	)
	(arc
		(start 333.10449 -41.166796)
		(mid 333.167416 -40.931846)
		(end 333.10449 -40.696896)
		(width 0.254)
		(layer "In13.Cu")
		(net "P3V3_RTC_AUX")
	)
	(arc
		(start 333.10195 -44.456096)
		(mid 333.039499 -44.241058)
		(end 333.083408 -44.021502)
		(width 0.254)
		(layer "In13.Cu")
		(net "P3V3_RTC_AUX")
	)
	(arc
		(start 333.113888 -45.843952)
		(mid 333.164655 -45.618398)
		(end 333.10195 -45.395896)
		(width 0.254)
		(layer "In13.Cu")
		(net "P3V3_RTC_AUX")
	)
	(arc
		(start 333.10449 -43.516296)
		(mid 333.04153 -43.281346)
		(end 333.10449 -43.046396)
		(width 0.254)
		(layer "In13.Cu")
		(net "P3V3_RTC_AUX")
	)
	(arc
		(start 333.10449 -40.696896)
		(mid 333.04153 -40.461946)
		(end 333.10449 -40.226996)
		(width 0.254)
		(layer "In13.Cu")
		(net "P3V3_RTC_AUX")
	)
	(arc
		(start 333.10195 -44.925996)
		(mid 333.164706 -44.691046)
		(end 333.10195 -44.456096)
		(width 0.254)
		(layer "In13.Cu")
		(net "P3V3_RTC_AUX")
	)
	(arc
		(start 333.114396 -43.968416)
		(mid 333.167318 -43.741102)
		(end 333.10449 -43.516296)
		(width 0.254)
		(layer "In13.Cu")
		(net "P3V3_RTC_AUX")
	)
	(arc
		(start 333.103982 -42.576496)
		(mid 333.040954 -42.341546)
		(end 333.103982 -42.106596)
		(width 0.254)
		(layer "In13.Cu")
		(net "P3V3_RTC_AUX")
	)
	(arc
		(start 333.101188 -46.335696)
		(mid 333.03833 -46.100746)
		(end 333.101188 -45.865796)
		(width 0.254)
		(layer "In13.Cu")
		(net "P3V3_RTC_AUX")
	)
	(segment
		(start 308.762146 -33.01238)
		(end 307.180742 -34.593784)
		(width 0.635)
		(layer "In15.Cu")
		(net "P3V3_RTC_AUX")
	)
	(segment
		(start 315.886846 -31.737808)
		(end 315.07303 -30.923992)
		(width 0.635)
		(layer "In15.Cu")
		(net "P3V3_RTC_AUX")
	)
	(segment
		(start 324.727824 -24.431498)
		(end 324.727824 -25.856946)
		(width 0.635)
		(layer "In15.Cu")
		(net "P3V3_RTC_AUX")
	)
	(segment
		(start 322.906136 -27.678634)
		(end 318.846962 -31.737808)
		(width 0.635)
		(layer "In15.Cu")
		(net "P3V3_RTC_AUX")
	)
	(segment
		(start 308.762146 -31.84525)
		(end 308.762146 -33.01238)
		(width 0.635)
		(layer "In15.Cu")
		(net "P3V3_RTC_AUX")
	)
	(segment
		(start 315.07303 -30.923992)
		(end 309.683404 -30.923992)
		(width 0.635)
		(layer "In15.Cu")
		(net "P3V3_RTC_AUX")
	)
	(segment
		(start 307.180742 -34.593784)
		(end 303.725834 -34.593784)
		(width 0.635)
		(layer "In15.Cu")
		(net "P3V3_RTC_AUX")
	)
	(segment
		(start 303.157128 -34.025078)
		(end 303.157128 -33.691576)
		(width 0.635)
		(layer "In15.Cu")
		(net "P3V3_RTC_AUX")
	)
	(segment
		(start 309.683404 -30.923992)
		(end 308.762146 -31.84525)
		(width 0.635)
		(layer "In15.Cu")
		(net "P3V3_RTC_AUX")
	)
	(segment
		(start 324.727824 -25.856946)
		(end 322.906136 -27.678634)
		(width 0.635)
		(layer "In15.Cu")
		(net "P3V3_RTC_AUX")
	)
	(segment
		(start 318.846962 -31.737808)
		(end 315.886846 -31.737808)
		(width 0.635)
		(layer "In15.Cu")
		(net "P3V3_RTC_AUX")
	)
	(segment
		(start 303.725834 -34.593784)
		(end 303.157128 -34.025078)
		(width 0.635)
		(layer "In15.Cu")
		(net "P3V3_RTC_AUX")
	)
	(segment
		(start 467.07552 -48.940212)
		(end 467.07552 -49.571148)
		(width 0.381)
		(layer "F.Cu")
		(net "P3V3_OCP_SFF")
	)
	(segment
		(start 445.677798 -47.524924)
		(end 445.677798 -46.152054)
		(width 0.381)
		(layer "F.Cu")
		(net "P3V3_OCP_SFF")
	)
	(segment
		(start 434.366924 -11.26998)
		(end 434.366924 -12.37488)
		(width 0.3556)
		(layer "F.Cu")
		(net "P3V3_OCP_SFF")
	)
	(segment
		(start 450.8373 -44.171362)
		(end 451.49008 -44.171362)
		(width 0.381)
		(layer "F.Cu")
		(net "P3V3_OCP_SFF")
	)
	(segment
		(start 388.72541 -37.965126)
		(end 388.72541 -36.881308)
		(width 0.381)
		(layer "F.Cu")
		(net "P3V3_OCP_SFF")
	)
	(segment
		(start 450.8373 -45.314362)
		(end 451.49008 -45.314362)
		(width 0.381)
		(layer "F.Cu")
		(net "P3V3_OCP_SFF")
	)
	(segment
		(start 445.575436 -47.627286)
		(end 445.677798 -47.524924)
		(width 0.381)
		(layer "F.Cu")
		(net "P3V3_OCP_SFF")
	)
	(segment
		(start 445.677798 -46.152054)
		(end 446.109598 -45.720254)
		(width 0.381)
		(layer "F.Cu")
		(net "P3V3_OCP_SFF")
	)
	(segment
		(start 388.425182 -38.265354)
		(end 388.425182 -38.903148)
		(width 0.381)
		(layer "F.Cu")
		(net "P3V3_OCP_SFF")
	)
	(segment
		(start 446.109598 -45.720254)
		(end 447.048382 -45.720254)
		(width 0.381)
		(layer "F.Cu")
		(net "P3V3_OCP_SFF")
	)
	(segment
		(start 434.366924 -11.26998)
		(end 434.366924 -10.16508)
		(width 0.3556)
		(layer "F.Cu")
		(net "P3V3_OCP_SFF")
	)
	(segment
		(start 388.425182 -38.265354)
		(end 388.72541 -37.965126)
		(width 0.381)
		(layer "F.Cu")
		(net "P3V3_OCP_SFF")
	)
	(segment
		(start 459.78445 -45.693838)
		(end 459.03388 -45.693838)
		(width 0.381)
		(layer "F.Cu")
		(net "P3V3_OCP_SFF")
	)
	(segment
		(start 445.575436 -48.472344)
		(end 445.575436 -47.627286)
		(width 0.381)
		(layer "F.Cu")
		(net "P3V3_OCP_SFF")
	)
	(via
		(at 388.425182 -38.903148)
		(size 0.508)
		(drill 0.254)
		(layers "F.Cu" "B.Cu")
		(net "P3V3_OCP_SFF")
	)
	(via
		(at 459.03388 -45.693838)
		(size 0.508)
		(drill 0.254)
		(layers "F.Cu" "B.Cu")
		(net "P3V3_OCP_SFF")
	)
	(via
		(at 451.49008 -44.171362)
		(size 0.508)
		(drill 0.254)
		(layers "F.Cu" "B.Cu")
		(net "P3V3_OCP_SFF")
	)
	(via
		(at 448.9196 -10.13841)
		(size 0.508)
		(drill 0.254)
		(layers "F.Cu" "B.Cu")
		(net "P3V3_OCP_SFF")
	)
	(via
		(at 436.17388 -99.479608)
		(size 0.508)
		(drill 0.254)
		(layers "F.Cu" "B.Cu")
		(net "P3V3_OCP_SFF")
	)
	(via
		(at 434.366924 -10.16508)
		(size 0.508)
		(drill 0.254)
		(layers "F.Cu" "B.Cu")
		(net "P3V3_OCP_SFF")
	)
	(via
		(at 445.575436 -48.472344)
		(size 0.508)
		(drill 0.254)
		(layers "F.Cu" "B.Cu")
		(net "P3V3_OCP_SFF")
	)
	(via
		(at 435.28488 -98.590608)
		(size 0.508)
		(drill 0.254)
		(layers "F.Cu" "B.Cu")
		(net "P3V3_OCP_SFF")
	)
	(via
		(at 436.17388 -98.590608)
		(size 0.508)
		(drill 0.254)
		(layers "F.Cu" "B.Cu")
		(net "P3V3_OCP_SFF")
	)
	(via
		(at 436.1434 -96.002348)
		(size 0.762)
		(drill 0.381)
		(layers "F.Cu" "B.Cu")
		(net "P3V3_OCP_SFF")
	)
	(via
		(at 467.07552 -49.571148)
		(size 0.508)
		(drill 0.254)
		(layers "F.Cu" "B.Cu")
		(net "P3V3_OCP_SFF")
	)
	(via
		(at 436.17388 -96.812608)
		(size 0.508)
		(drill 0.254)
		(layers "F.Cu" "B.Cu")
		(net "P3V3_OCP_SFF")
	)
	(via
		(at 435.28488 -99.479608)
		(size 0.508)
		(drill 0.254)
		(layers "F.Cu" "B.Cu")
		(net "P3V3_OCP_SFF")
	)
	(via
		(at 436.17388 -97.701608)
		(size 0.508)
		(drill 0.254)
		(layers "F.Cu" "B.Cu")
		(net "P3V3_OCP_SFF")
	)
	(via
		(at 434.366924 -12.37488)
		(size 0.508)
		(drill 0.254)
		(layers "F.Cu" "B.Cu")
		(net "P3V3_OCP_SFF")
	)
	(via
		(at 451.49008 -45.314362)
		(size 0.508)
		(drill 0.254)
		(layers "F.Cu" "B.Cu")
		(net "P3V3_OCP_SFF")
	)
	(via
		(at 435.28488 -97.701608)
		(size 0.508)
		(drill 0.254)
		(layers "F.Cu" "B.Cu")
		(net "P3V3_OCP_SFF")
	)
	(via
		(at 435.28488 -96.812608)
		(size 0.508)
		(drill 0.254)
		(layers "F.Cu" "B.Cu")
		(net "P3V3_OCP_SFF")
	)
	(via
		(at 445.67348 -9.921748)
		(size 0.508)
		(drill 0.254)
		(layers "F.Cu" "B.Cu")
		(net "P3V3_OCP_SFF")
	)
	(via
		(at 451.549516 -9.587484)
		(size 0.508)
		(drill 0.254)
		(layers "F.Cu" "B.Cu")
		(net "P3V3_OCP_SFF")
	)
	(segment
		(start 451.549516 -10.234676)
		(end 451.549516 -9.587484)
		(width 0.381)
		(layer "B.Cu")
		(net "P3V3_OCP_SFF")
	)
	(segment
		(start 452.62546 -10.20572)
		(end 452.596504 -10.234676)
		(width 0.381)
		(layer "B.Cu")
		(net "P3V3_OCP_SFF")
	)
	(segment
		(start 450.745098 -8.744966)
		(end 450.542914 -8.744966)
		(width 0.381)
		(layer "B.Cu")
		(net "P3V3_OCP_SFF")
	)
	(segment
		(start 448.9196 -10.13841)
		(end 448.975226 -10.194036)
		(width 0.381)
		(layer "B.Cu")
		(net "P3V3_OCP_SFF")
	)
	(segment
		(start 451.549516 -9.587484)
		(end 451.549516 -9.549384)
		(width 0.381)
		(layer "B.Cu")
		(net "P3V3_OCP_SFF")
	)
	(segment
		(start 448.975226 -10.194036)
		(end 449.5546 -10.194036)
		(width 0.381)
		(layer "B.Cu")
		(net "P3V3_OCP_SFF")
	)
	(segment
		(start 451.549516 -9.549384)
		(end 450.745098 -8.744966)
		(width 0.381)
		(layer "B.Cu")
		(net "P3V3_OCP_SFF")
	)
	(segment
		(start 452.596504 -10.234676)
		(end 451.549516 -10.234676)
		(width 0.381)
		(layer "B.Cu")
		(net "P3V3_OCP_SFF")
	)
	(segment
		(start 445.67348 -9.921748)
		(end 445.945768 -10.194036)
		(width 0.381)
		(layer "B.Cu")
		(net "P3V3_OCP_SFF")
	)
	(segment
		(start 445.945768 -10.194036)
		(end 446.55105 -10.194036)
		(width 0.381)
		(layer "B.Cu")
		(net "P3V3_OCP_SFF")
	)
	(segment
		(start 419.63594 -106.858308)
		(end 418.84854 -106.858308)
		(width 0.12954)
		(layer "F.Cu")
		(net "P3V3_OCP_DVDT_1")
	)
	(segment
		(start 420.025068 -106.46918)
		(end 419.63594 -106.858308)
		(width 0.12954)
		(layer "F.Cu")
		(net "P3V3_OCP_DVDT_1")
	)
	(segment
		(start 418.08654 -108.591858)
		(end 418.36594 -108.871258)
		(width 0.12954)
		(layer "F.Cu")
		(net "P3V3_OCP_DVDT_1")
	)
	(segment
		(start 418.84854 -106.858308)
		(end 418.08654 -107.620308)
		(width 0.12954)
		(layer "F.Cu")
		(net "P3V3_OCP_DVDT_1")
	)
	(segment
		(start 420.025068 -106.207306)
		(end 420.025068 -106.46918)
		(width 0.12954)
		(layer "F.Cu")
		(net "P3V3_OCP_DVDT_1")
	)
	(segment
		(start 418.08654 -107.620308)
		(end 418.08654 -108.591858)
		(width 0.12954)
		(layer "F.Cu")
		(net "P3V3_OCP_DVDT_1")
	)
	(via
		(at 418.08654 -107.620308)
		(size 0.762)
		(drill 0.381)
		(layers "F.Cu" "B.Cu")
		(net "P3V3_OCP_DVDT_1")
	)
	(segment
		(start 236.801406 -127.758444)
		(end 237.041944 -127.517906)
		(width 0.2032)
		(layer "F.Cu")
		(net "P3V3_DB2000_VDDR")
	)
	(segment
		(start 237.041944 -127.517906)
		(end 237.247938 -127.517906)
		(width 0.2032)
		(layer "F.Cu")
		(net "P3V3_DB2000_VDDR")
	)
	(via
		(at 235.812076 -120.574054)
		(size 0.508)
		(drill 0.254)
		(layers "F.Cu" "B.Cu")
		(net "P3V3_DB2000_VDDR")
	)
	(via
		(at 236.62132 -119.911368)
		(size 0.6604)
		(drill 0.3302)
		(layers "F.Cu" "B.Cu")
		(net "P3V3_DB2000_VDDR")
	)
	(via
		(at 235.812076 -119.939054)
		(size 0.508)
		(drill 0.254)
		(layers "F.Cu" "B.Cu")
		(net "P3V3_DB2000_VDDR")
	)
	(via
		(at 236.801406 -127.758444)
		(size 0.49022)
		(drill 0.254)
		(layers "F.Cu" "B.Cu")
		(net "P3V3_DB2000_VDDR")
	)
	(segment
		(start 236.801406 -127.758444)
		(end 237.0709 -127.48895)
		(width 0.381)
		(layer "B.Cu")
		(net "P3V3_DB2000_VDDR")
	)
	(segment
		(start 237.0709 -127.48895)
		(end 237.436152 -127.48895)
		(width 0.381)
		(layer "B.Cu")
		(net "P3V3_DB2000_VDDR")
	)
	(segment
		(start 235.497116 -124.994162)
		(end 235.497116 -124.767086)
		(width 0.2032)
		(layer "F.Cu")
		(net "P3V3_DB2000_VDDA")
	)
	(segment
		(start 235.497116 -124.767086)
		(end 235.247942 -124.517912)
		(width 0.2032)
		(layer "F.Cu")
		(net "P3V3_DB2000_VDDA")
	)
	(via
		(at 235.497116 -124.994162)
		(size 0.49022)
		(drill 0.254)
		(layers "F.Cu" "B.Cu")
		(net "P3V3_DB2000_VDDA")
	)
	(segment
		(start 232.748074 -129.017776)
		(end 233.239056 -128.526794)
		(width 0.2032)
		(layer "F.Cu")
		(net "P3V3_DB2000_VDD")
	)
	(segment
		(start 237.247938 -129.017776)
		(end 236.750606 -128.520444)
		(width 0.2032)
		(layer "F.Cu")
		(net "P3V3_DB2000_VDD")
	)
	(segment
		(start 236.750606 -125.143514)
		(end 236.750606 -125.015244)
		(width 0.2032)
		(layer "F.Cu")
		(net "P3V3_DB2000_VDD")
	)
	(segment
		(start 233.307128 -125.08103)
		(end 233.307128 -125.062234)
		(width 0.2032)
		(layer "F.Cu")
		(net "P3V3_DB2000_VDD")
	)
	(segment
		(start 236.750606 -125.015244)
		(end 237.247938 -124.517912)
		(width 0.2032)
		(layer "F.Cu")
		(net "P3V3_DB2000_VDD")
	)
	(segment
		(start 232.762806 -124.517912)
		(end 232.748074 -124.517912)
		(width 0.2032)
		(layer "F.Cu")
		(net "P3V3_DB2000_VDD")
	)
	(segment
		(start 233.307128 -125.062234)
		(end 232.762806 -124.517912)
		(width 0.2032)
		(layer "F.Cu")
		(net "P3V3_DB2000_VDD")
	)
	(via
		(at 228.72446 -122.619008)
		(size 0.6604)
		(drill 0.3302)
		(layers "F.Cu" "B.Cu")
		(net "P3V3_DB2000_VDD")
	)
	(via
		(at 233.307128 -125.08103)
		(size 0.49022)
		(drill 0.254)
		(layers "F.Cu" "B.Cu")
		(net "P3V3_DB2000_VDD")
	)
	(via
		(at 230.550212 -123.996958)
		(size 0.508)
		(drill 0.254)
		(layers "F.Cu" "B.Cu")
		(net "P3V3_DB2000_VDD")
	)
	(via
		(at 236.750606 -125.143514)
		(size 0.49022)
		(drill 0.254)
		(layers "F.Cu" "B.Cu")
		(net "P3V3_DB2000_VDD")
	)
	(via
		(at 236.750606 -128.520444)
		(size 0.49022)
		(drill 0.254)
		(layers "F.Cu" "B.Cu")
		(net "P3V3_DB2000_VDD")
	)
	(via
		(at 233.239056 -128.526794)
		(size 0.4572)
		(drill 0.2032)
		(layers "F.Cu" "B.Cu")
		(net "P3V3_DB2000_VDD")
	)
	(segment
		(start 233.239056 -128.526794)
		(end 232.692194 -129.073656)
		(width 0.381)
		(layer "B.Cu")
		(net "P3V3_DB2000_VDD")
	)
	(segment
		(start 232.692194 -129.073656)
		(end 232.692194 -129.273808)
		(width 0.381)
		(layer "B.Cu")
		(net "P3V3_DB2000_VDD")
	)
	(segment
		(start 236.752892 -128.518158)
		(end 237.437422 -128.518158)
		(width 0.381)
		(layer "B.Cu")
		(net "P3V3_DB2000_VDD")
	)
	(segment
		(start 236.750606 -128.520444)
		(end 236.752892 -128.518158)
		(width 0.381)
		(layer "B.Cu")
		(net "P3V3_DB2000_VDD")
	)
	(segment
		(start 236.750606 -124.372624)
		(end 236.851698 -124.271532)
		(width 0.381)
		(layer "B.Cu")
		(net "P3V3_DB2000_VDD")
	)
	(segment
		(start 236.750606 -125.143514)
		(end 236.750606 -124.372624)
		(width 0.381)
		(layer "B.Cu")
		(net "P3V3_DB2000_VDD")
	)
	(via
		(at 232.2322 -123.662948)
		(size 0.6604)
		(drill 0.3302)
		(layers "F.Cu" "B.Cu")
		(net "P3V3_DB2000_FB_VDD")
	)
	(segment
		(start 452.289418 -77.126592)
		(end 452.086472 -76.923646)
		(width 0.254)
		(layer "F.Cu")
		(net "P3V3_AUX_VOS")
	)
	(segment
		(start 450.781674 -75.675744)
		(end 450.781674 -75.277472)
		(width 0.254)
		(layer "F.Cu")
		(net "P3V3_AUX_VOS")
	)
	(segment
		(start 452.289418 -77.214476)
		(end 452.289418 -77.126592)
		(width 0.254)
		(layer "F.Cu")
		(net "P3V3_AUX_VOS")
	)
	(segment
		(start 452.086472 -76.007722)
		(end 451.113652 -76.007722)
		(width 0.254)
		(layer "F.Cu")
		(net "P3V3_AUX_VOS")
	)
	(segment
		(start 451.113652 -76.007722)
		(end 450.781674 -75.675744)
		(width 0.254)
		(layer "F.Cu")
		(net "P3V3_AUX_VOS")
	)
	(segment
		(start 452.086472 -76.923646)
		(end 452.086472 -76.007722)
		(width 0.254)
		(layer "F.Cu")
		(net "P3V3_AUX_VOS")
	)
	(via
		(at 452.289418 -77.214476)
		(size 0.762)
		(drill 0.381)
		(layers "F.Cu" "B.Cu")
		(net "P3V3_AUX_VOS")
	)
	(segment
		(start 443.23 -73.904348)
		(end 443.23 -73.145142)
		(width 0.254)
		(layer "F.Cu")
		(net "P3V3_AUX_VCC")
	)
	(segment
		(start 443.6364 -73.497948)
		(end 444.324232 -73.497948)
		(width 0.254)
		(layer "F.Cu")
		(net "P3V3_AUX_VCC")
	)
	(segment
		(start 443.23 -73.145142)
		(end 443.576964 -72.798178)
		(width 0.254)
		(layer "F.Cu")
		(net "P3V3_AUX_VCC")
	)
	(segment
		(start 444.810388 -73.984104)
		(end 445.01689 -73.777602)
		(width 0.254)
		(layer "F.Cu")
		(net "P3V3_AUX_VCC")
	)
	(segment
		(start 445.01689 -73.777602)
		(end 446.068958 -73.777602)
		(width 0.254)
		(layer "F.Cu")
		(net "P3V3_AUX_VCC")
	)
	(segment
		(start 444.324232 -73.497948)
		(end 444.810388 -73.984104)
		(width 0.254)
		(layer "F.Cu")
		(net "P3V3_AUX_VCC")
	)
	(segment
		(start 443.23 -73.904348)
		(end 443.6364 -73.497948)
		(width 0.254)
		(layer "F.Cu")
		(net "P3V3_AUX_VCC")
	)
	(via
		(at 444.810388 -73.984104)
		(size 0.762)
		(drill 0.381)
		(layers "F.Cu" "B.Cu")
		(net "P3V3_AUX_VCC")
	)
	(segment
		(start 450.169026 -76.19238)
		(end 451.509892 -77.533246)
		(width 0.254)
		(layer "F.Cu")
		(net "P3V3_AUX_SS")
	)
	(segment
		(start 450.169026 -75.915266)
		(end 450.169026 -76.19238)
		(width 0.254)
		(layer "F.Cu")
		(net "P3V3_AUX_SS")
	)
	(segment
		(start 450.459094 -77.429868)
		(end 450.307202 -77.429868)
		(width 0.254)
		(layer "F.Cu")
		(net "P3V3_AUX_SS")
	)
	(segment
		(start 451.509892 -77.533246)
		(end 451.509892 -78.304644)
		(width 0.254)
		(layer "F.Cu")
		(net "P3V3_AUX_SS")
	)
	(segment
		(start 451.509892 -78.304644)
		(end 451.33387 -78.304644)
		(width 0.254)
		(layer "F.Cu")
		(net "P3V3_AUX_SS")
	)
	(segment
		(start 451.33387 -78.304644)
		(end 450.459094 -77.429868)
		(width 0.254)
		(layer "F.Cu")
		(net "P3V3_AUX_SS")
	)
	(via
		(at 451.509892 -78.304644)
		(size 0.762)
		(drill 0.381)
		(layers "F.Cu" "B.Cu")
		(net "P3V3_AUX_SS")
	)
	(segment
		(start 446.971928 -77.132942)
		(end 446.675002 -77.429868)
		(width 0.254)
		(layer "F.Cu")
		(net "P3V3_AUX_MODE")
	)
	(segment
		(start 446.971928 -76.71308)
		(end 446.971928 -77.132942)
		(width 0.254)
		(layer "F.Cu")
		(net "P3V3_AUX_MODE")
	)
	(segment
		(start 447.066416 -76.618592)
		(end 446.971928 -76.71308)
		(width 0.254)
		(layer "F.Cu")
		(net "P3V3_AUX_MODE")
	)
	(segment
		(start 446.668906 -75.915266)
		(end 446.668906 -76.221082)
		(width 0.254)
		(layer "F.Cu")
		(net "P3V3_AUX_MODE")
	)
	(segment
		(start 446.668906 -76.221082)
		(end 447.066416 -76.618592)
		(width 0.254)
		(layer "F.Cu")
		(net "P3V3_AUX_MODE")
	)
	(via
		(at 447.066416 -76.618592)
		(size 0.508)
		(drill 0.254)
		(layers "F.Cu" "B.Cu")
		(net "P3V3_AUX_MODE")
	)
	(segment
		(start 445.93383 -75.614784)
		(end 445.93383 -76.488544)
		(width 0.1524)
		(layer "F.Cu")
		(net "P3V3_AUX_ILIM")
	)
	(segment
		(start 446.056258 -75.277472)
		(end 446.056258 -75.492356)
		(width 0.1524)
		(layer "F.Cu")
		(net "P3V3_AUX_ILIM")
	)
	(segment
		(start 445.93383 -76.488544)
		(end 446.075816 -76.63053)
		(width 0.1524)
		(layer "F.Cu")
		(net "P3V3_AUX_ILIM")
	)
	(segment
		(start 445.760602 -76.945744)
		(end 445.760602 -77.429868)
		(width 0.1524)
		(layer "F.Cu")
		(net "P3V3_AUX_ILIM")
	)
	(segment
		(start 446.056258 -75.492356)
		(end 445.93383 -75.614784)
		(width 0.1524)
		(layer "F.Cu")
		(net "P3V3_AUX_ILIM")
	)
	(segment
		(start 446.075816 -76.63053)
		(end 445.760602 -76.945744)
		(width 0.1524)
		(layer "F.Cu")
		(net "P3V3_AUX_ILIM")
	)
	(via
		(at 446.075816 -76.63053)
		(size 0.508)
		(drill 0.254)
		(layers "F.Cu" "B.Cu")
		(net "P3V3_AUX_ILIM")
	)
	(segment
		(start 449.6689 -75.902566)
		(end 449.6689 -77.145388)
		(width 0.254)
		(layer "F.Cu")
		(net "P3V3_AUX_FB")
	)
	(segment
		(start 449.38442 -77.429868)
		(end 449.303902 -77.510386)
		(width 0.254)
		(layer "F.Cu")
		(net "P3V3_AUX_FB")
	)
	(segment
		(start 449.303902 -77.510386)
		(end 448.55892 -77.510386)
		(width 0.254)
		(layer "F.Cu")
		(net "P3V3_AUX_FB")
	)
	(segment
		(start 448.478402 -77.429868)
		(end 447.589402 -77.429868)
		(width 0.254)
		(layer "F.Cu")
		(net "P3V3_AUX_FB")
	)
	(segment
		(start 449.6689 -77.145388)
		(end 449.38442 -77.429868)
		(width 0.254)
		(layer "F.Cu")
		(net "P3V3_AUX_FB")
	)
	(segment
		(start 448.55892 -77.510386)
		(end 448.478402 -77.429868)
		(width 0.254)
		(layer "F.Cu")
		(net "P3V3_AUX_FB")
	)
	(segment
		(start 261.46633 -95.641668)
		(end 260.526022 -96.581976)
		(width 0.2032)
		(layer "F.Cu")
		(net "P3V3_AUX_CLK_GEN_VDD_CK440")
	)
	(segment
		(start 260.526022 -96.581976)
		(end 260.055868 -97.05213)
		(width 0.0889)
		(layer "F.Cu")
		(net "P3V3_AUX_CLK_GEN_VDD_CK440")
	)
	(segment
		(start 257.688588 -95.080328)
		(end 257.834384 -94.934532)
		(width 0.0889)
		(layer "F.Cu")
		(net "P3V3_AUX_CLK_GEN_VDD_CK440")
	)
	(segment
		(start 260.055868 -97.05213)
		(end 259.820918 -97.05213)
		(width 0.0889)
		(layer "F.Cu")
		(net "P3V3_AUX_CLK_GEN_VDD_CK440")
	)
	(segment
		(start 257.688588 -95.523812)
		(end 257.688588 -95.080328)
		(width 0.0889)
		(layer "F.Cu")
		(net "P3V3_AUX_CLK_GEN_VDD_CK440")
	)
	(segment
		(start 261.46633 -95.464376)
		(end 261.46633 -95.641668)
		(width 0.2032)
		(layer "F.Cu")
		(net "P3V3_AUX_CLK_GEN_VDD_CK440")
	)
	(via
		(at 263.99236 -94.651068)
		(size 0.6604)
		(drill 0.3302)
		(layers "F.Cu" "B.Cu")
		(net "P3V3_AUX_CLK_GEN_VDD_CK440")
	)
	(via
		(at 260.6675 -96.921828)
		(size 0.6604)
		(drill 0.3302)
		(layers "F.Cu" "B.Cu")
		(net "P3V3_AUX_CLK_GEN_VDD_CK440")
	)
	(via
		(at 257.834384 -94.934532)
		(size 0.508)
		(drill 0.254)
		(layers "F.Cu" "B.Cu")
		(net "P3V3_AUX_CLK_GEN_VDD_CK440")
	)
	(via
		(at 261.46633 -95.464376)
		(size 0.508)
		(drill 0.254)
		(layers "F.Cu" "B.Cu")
		(net "P3V3_AUX_CLK_GEN_VDD_CK440")
	)
	(segment
		(start 250.5456 -97.313242)
		(end 251.807726 -97.313242)
		(width 0.1778)
		(layer "F.Cu")
		(net "P3V3_AUX_CLK_GEN_VDDXTAL_CK440")
	)
	(via
		(at 250.5456 -97.313242)
		(size 0.508)
		(drill 0.254)
		(layers "F.Cu" "B.Cu")
		(net "P3V3_AUX_CLK_GEN_VDDXTAL_CK440")
	)
	(via
		(at 240.5634 -95.113348)
		(size 0.6604)
		(drill 0.3302)
		(layers "F.Cu" "B.Cu")
		(net "P3V3_AUX_CLK_GEN_VDDXTAL_CK440")
	)
	(via
		(at 263.99998 -105.115868)
		(size 0.6604)
		(drill 0.3302)
		(layers "F.Cu" "B.Cu")
		(net "P3V3_AUX_CLK_GEN_VDDPT_CK440")
	)
	(via
		(at 263.12368 -106.695748)
		(size 0.508)
		(drill 0.254)
		(layers "F.Cu" "B.Cu")
		(net "P3V3_AUX_CLK_GEN_VDDPT_CK440")
	)
	(via
		(at 250.68657 -99.552506)
		(size 0.508)
		(drill 0.254)
		(layers "F.Cu" "B.Cu")
		(net "P3V3_AUX_CLK_GEN_VDDPT_CK440")
	)
	(via
		(at 263.12368 -106.035348)
		(size 0.508)
		(drill 0.254)
		(layers "F.Cu" "B.Cu")
		(net "P3V3_AUX_CLK_GEN_VDDPT_CK440")
	)
	(via
		(at 263.99998 -106.385868)
		(size 0.6604)
		(drill 0.3302)
		(layers "F.Cu" "B.Cu")
		(net "P3V3_AUX_CLK_GEN_VDDPT_CK440")
	)
	(segment
		(start 259.773928 -101.56444)
		(end 260.562598 -101.56444)
		(width 0.0889)
		(layer "F.Cu")
		(net "P3V3_AUX_CLK_GEN_VDDMXCK_CK440")
	)
	(segment
		(start 260.562598 -101.56444)
		(end 260.743192 -101.745034)
		(width 0.0889)
		(layer "F.Cu")
		(net "P3V3_AUX_CLK_GEN_VDDMXCK_CK440")
	)
	(via
		(at 260.743192 -101.745034)
		(size 0.508)
		(drill 0.254)
		(layers "F.Cu" "B.Cu")
		(net "P3V3_AUX_CLK_GEN_VDDMXCK_CK440")
	)
	(via
		(at 260.81228 -100.167948)
		(size 0.508)
		(drill 0.254)
		(layers "F.Cu" "B.Cu")
		(net "P3V3_AUX_CLK_GEN_VDDMXCK_CK440")
	)
	(via
		(at 255.301242 -105.324148)
		(size 0.508)
		(drill 0.254)
		(layers "F.Cu" "B.Cu")
		(net "P3V3_AUX_CLK_GEN_VDDMXCK_CK440")
	)
	(via
		(at 258.9022 -103.038148)
		(size 0.6604)
		(drill 0.3302)
		(layers "F.Cu" "B.Cu")
		(net "P3V3_AUX_CLK_GEN_VDDMXCK_CK440")
	)
	(via
		(at 257.91668 -104.358948)
		(size 0.508)
		(drill 0.254)
		(layers "F.Cu" "B.Cu")
		(net "P3V3_AUX_CLK_GEN_VDDMXCK_CK440")
	)
	(segment
		(start 252.557788 -102.063296)
		(end 252.557788 -102.63886)
		(width 0.254)
		(layer "F.Cu")
		(net "P3V3_AUX_CLK_GEN_VDDA25M_CK440")
	)
	(via
		(at 252.557788 -102.63886)
		(size 0.508)
		(drill 0.254)
		(layers "F.Cu" "B.Cu")
		(net "P3V3_AUX_CLK_GEN_VDDA25M_CK440")
	)
	(via
		(at 240.3602 -99.710748)
		(size 0.6604)
		(drill 0.3302)
		(layers "F.Cu" "B.Cu")
		(net "P3V3_AUX_CLK_GEN_VDDA25M_CK440")
	)
	(via
		(at 241.599974 -99.546664)
		(size 0.508)
		(drill 0.254)
		(layers "F.Cu" "B.Cu")
		(net "P3V3_AUX_CLK_GEN_VDDA25M_CK440")
	)
	(via
		(at 246.7864 -103.784908)
		(size 0.6604)
		(drill 0.3302)
		(layers "F.Cu" "B.Cu")
		(net "P3V3_AUX_CLK_GEN_VDDA25M_CK440")
	)
	(via
		(at 242.073684 -99.086162)
		(size 0.508)
		(drill 0.254)
		(layers "F.Cu" "B.Cu")
		(net "P3V3_AUX_CLK_GEN_VDDA25M_CK440")
	)
	(segment
		(start 251.6124 -101.524054)
		(end 251.6124 -100.613718)
		(width 0.381)
		(layer "B.Cu")
		(net "P3V3_AUX_CLK_GEN_VDDA25M_CK440")
	)
	(segment
		(start 252.557788 -102.63886)
		(end 252.24994 -102.63886)
		(width 0.381)
		(layer "B.Cu")
		(net "P3V3_AUX_CLK_GEN_VDDA25M_CK440")
	)
	(segment
		(start 251.842524 -101.754178)
		(end 251.6124 -101.524054)
		(width 0.381)
		(layer "B.Cu")
		(net "P3V3_AUX_CLK_GEN_VDDA25M_CK440")
	)
	(segment
		(start 251.842524 -102.231444)
		(end 251.842524 -101.754178)
		(width 0.381)
		(layer "B.Cu")
		(net "P3V3_AUX_CLK_GEN_VDDA25M_CK440")
	)
	(segment
		(start 252.24994 -102.63886)
		(end 251.842524 -102.231444)
		(width 0.381)
		(layer "B.Cu")
		(net "P3V3_AUX_CLK_GEN_VDDA25M_CK440")
	)
	(via
		(at 265.10488 -92.319348)
		(size 0.508)
		(drill 0.254)
		(layers "F.Cu" "B.Cu")
		(net "P3V3_AUX_CLK_GEN_VDDA100M_CK440")
	)
	(via
		(at 255.70434 -94.724474)
		(size 0.508)
		(drill 0.254)
		(layers "F.Cu" "B.Cu")
		(net "P3V3_AUX_CLK_GEN_VDDA100M_CK440")
	)
	(via
		(at 265.20648 -93.055948)
		(size 0.508)
		(drill 0.254)
		(layers "F.Cu" "B.Cu")
		(net "P3V3_AUX_CLK_GEN_VDDA100M_CK440")
	)
	(via
		(at 255.575054 -93.981016)
		(size 0.508)
		(drill 0.254)
		(layers "F.Cu" "B.Cu")
		(net "P3V3_AUX_CLK_GEN_VDDA100M_CK440")
	)
	(segment
		(start 147.04695 -130.647948)
		(end 147.04695 -131.278884)
		(width 0.381)
		(layer "F.Cu")
		(net "P3V3_AUX")
	)
	(segment
		(start 103.158036 -40.935148)
		(end 103.104442 -40.881554)
		(width 0.381)
		(layer "F.Cu")
		(net "P3V3_AUX")
	)
	(segment
		(start 211.653882 -13.605256)
		(end 213.72068 -13.605256)
		(width 0.381)
		(layer "F.Cu")
		(net "P3V3_AUX")
	)
	(segment
		(start 370.683282 -60.48375)
		(end 371.36324 -60.48375)
		(width 0.381)
		(layer "F.Cu")
		(net "P3V3_AUX")
	)
	(segment
		(start 131.866894 -137.114026)
		(end 132.476494 -137.114026)
		(width 0.381)
		(layer "F.Cu")
		(net "P3V3_AUX")
	)
	(segment
		(start 293.548562 -18.714466)
		(end 292.636448 -18.714466)
		(width 0.381)
		(layer "F.Cu")
		(net "P3V3_AUX")
	)
	(segment
		(start 333.23657 -48.450246)
		(end 333.508858 -48.920146)
		(width 0.2032)
		(layer "F.Cu")
		(net "P3V3_AUX")
	)
	(segment
		(start 307.04282 -319.199768)
		(end 307.04282 -319.545462)
		(width 0.381)
		(layer "F.Cu")
		(net "P3V3_AUX")
	)
	(segment
		(start 137.006838 -33.477708)
		(end 140.296646 -33.477708)
		(width 0.381)
		(layer "F.Cu")
		(net "P3V3_AUX")
	)
	(segment
		(start 23.669752 -406.874218)
		(end 23.060152 -406.874218)
		(width 0.381)
		(layer "F.Cu")
		(net "P3V3_AUX")
	)
	(segment
		(start 147.773644 -78.955138)
		(end 144.694656 -78.955138)
		(width 0.381)
		(layer "F.Cu")
		(net "P3V3_AUX")
	)
	(segment
		(start 406.524714 -363.008926)
		(end 406.524714 -361.865926)
		(width 0.381)
		(layer "F.Cu")
		(net "P3V3_AUX")
	)
	(segment
		(start 129.411984 -66.538856)
		(end 126.852934 -66.538856)
		(width 0.381)
		(layer "F.Cu")
		(net "P3V3_AUX")
	)
	(segment
		(start 110.932722 -140.403326)
		(end 110.323122 -140.403326)
		(width 0.381)
		(layer "F.Cu")
		(net "P3V3_AUX")
	)
	(segment
		(start 309.259224 -438.587896)
		(end 308.567836 -438.587896)
		(width 0.381)
		(layer "F.Cu")
		(net "P3V3_AUX")
	)
	(segment
		(start 116.71808 -393.537948)
		(end 116.71808 -392.928348)
		(width 0.381)
		(layer "F.Cu")
		(net "P3V3_AUX")
	)
	(segment
		(start 8.140446 -319.716658)
		(end 7.035546 -319.716658)
		(width 0.381)
		(layer "F.Cu")
		(net "P3V3_AUX")
	)
	(segment
		(start 31.770828 -438.681368)
		(end 32.357568 -438.681368)
		(width 0.381)
		(layer "F.Cu")
		(net "P3V3_AUX")
	)
	(segment
		(start 116.84508 -400.815048)
		(end 116.84508 -401.424648)
		(width 0.3556)
		(layer "F.Cu")
		(net "P3V3_AUX")
	)
	(segment
		(start 104.42575 -409.2702)
		(end 104.42575 -408.2796)
		(width 0.381)
		(layer "F.Cu")
		(net "P3V3_AUX")
	)
	(segment
		(start 120.269 -59.635898)
		(end 119.6086 -59.635898)
		(width 0.381)
		(layer "F.Cu")
		(net "P3V3_AUX")
	)
	(segment
		(start 180.784246 -417.310824)
		(end 180.784246 -418.800534)
		(width 0.381)
		(layer "F.Cu")
		(net "P3V3_AUX")
	)
	(segment
		(start 115.332764 -17.784064)
		(end 115.856512 -17.784064)
		(width 0.381)
		(layer "F.Cu")
		(net "P3V3_AUX")
	)
	(segment
		(start 107.47883 -57.876948)
		(end 107.47883 -57.241948)
		(width 0.381)
		(layer "F.Cu")
		(net "P3V3_AUX")
	)
	(segment
		(start 144.204182 -124.88672)
		(end 144.48536 -125.167898)
		(width 0.381)
		(layer "F.Cu")
		(net "P3V3_AUX")
	)
	(segment
		(start 308.491636 -39.995348)
		(end 308.995826 -39.995348)
		(width 0.381)
		(layer "F.Cu")
		(net "P3V3_AUX")
	)
	(segment
		(start 187.883546 -319.716658)
		(end 188.988446 -319.716658)
		(width 0.381)
		(layer "F.Cu")
		(net "P3V3_AUX")
	)
	(segment
		(start 423.804842 -389.600948)
		(end 423.195242 -389.600948)
		(width 0.381)
		(layer "F.Cu")
		(net "P3V3_AUX")
	)
	(segment
		(start 308.969664 -13.7414)
		(end 310.770778 -13.7414)
		(width 0.381)
		(layer "F.Cu")
		(net "P3V3_AUX")
	)
	(segment
		(start 163.248086 -66.091308)
		(end 163.857686 -66.091308)
		(width 0.381)
		(layer "F.Cu")
		(net "P3V3_AUX")
	)
	(segment
		(start 137.02665 -28.578048)
		(end 137.02665 -30.168088)
		(width 0.381)
		(layer "F.Cu")
		(net "P3V3_AUX")
	)
	(segment
		(start 436.967376 -43.262804)
		(end 435.57317 -43.262804)
		(width 0.381)
		(layer "F.Cu")
		(net "P3V3_AUX")
	)
	(segment
		(start 152.30983 -122.519948)
		(end 152.30983 -121.884948)
		(width 0.381)
		(layer "F.Cu")
		(net "P3V3_AUX")
	)
	(segment
		(start 107.569 -29.842714)
		(end 106.730292 -30.681422)
		(width 0.381)
		(layer "F.Cu")
		(net "P3V3_AUX")
	)
	(segment
		(start 209.922618 -36.17214)
		(end 209.922618 -37.331904)
		(width 0.2286)
		(layer "F.Cu")
		(net "P3V3_AUX")
	)
	(segment
		(start 302.85436 -432.64582)
		(end 302.85436 -431.907188)
		(width 0.381)
		(layer "F.Cu")
		(net "P3V3_AUX")
	)
	(segment
		(start 181.7624 -93.138498)
		(end 180.4924 -93.138498)
		(width 0.381)
		(layer "F.Cu")
		(net "P3V3_AUX")
	)
	(segment
		(start 355.42855 -403.9108)
		(end 354.7364 -403.9108)
		(width 0.381)
		(layer "F.Cu")
		(net "P3V3_AUX")
	)
	(segment
		(start 51.193446 -109.53877)
		(end 50.583846 -109.53877)
		(width 0.381)
		(layer "F.Cu")
		(net "P3V3_AUX")
	)
	(segment
		(start 179.12588 -127.364998)
		(end 179.12588 -127.975868)
		(width 0.381)
		(layer "F.Cu")
		(net "P3V3_AUX")
	)
	(segment
		(start 342.79078 -26.453338)
		(end 342.803734 -26.466292)
		(width 0.381)
		(layer "F.Cu")
		(net "P3V3_AUX")
	)
	(segment
		(start 277.20671 -424.424602)
		(end 277.743412 -424.424602)
		(width 0.381)
		(layer "F.Cu")
		(net "P3V3_AUX")
	)
	(segment
		(start 369.7224 -102.982268)
		(end 369.23853 -103.466138)
		(width 0.381)
		(layer "F.Cu")
		(net "P3V3_AUX")
	)
	(segment
		(start 150.29688 -110.219998)
		(end 150.93188 -110.219998)
		(width 0.381)
		(layer "F.Cu")
		(net "P3V3_AUX")
	)
	(segment
		(start 150.22195 -133.314948)
		(end 150.22195 -132.673598)
		(width 0.381)
		(layer "F.Cu")
		(net "P3V3_AUX")
	)
	(segment
		(start 440.38012 -99.87153)
		(end 440.38012 -99.21748)
		(width 0.381)
		(layer "F.Cu")
		(net "P3V3_AUX")
	)
	(segment
		(start 215.58123 -41.341548)
		(end 215.60028 -41.360598)
		(width 0.381)
		(layer "F.Cu")
		(net "P3V3_AUX")
	)
	(segment
		(start 208.89341 -121.1072)
		(end 209.321146 -121.1072)
		(width 0.381)
		(layer "F.Cu")
		(net "P3V3_AUX")
	)
	(segment
		(start 304.09896 -432.64582)
		(end 304.09896 -431.907188)
		(width 0.381)
		(layer "F.Cu")
		(net "P3V3_AUX")
	)
	(segment
		(start 276.173184 -17.678908)
		(end 276.178264 -17.683988)
		(width 0.381)
		(layer "F.Cu")
		(net "P3V3_AUX")
	)
	(segment
		(start 439.408316 -104.540812)
		(end 439.408316 -105.268776)
		(width 0.381)
		(layer "F.Cu")
		(net "P3V3_AUX")
	)
	(segment
		(start 19.790664 -106.761026)
		(end 19.181064 -106.761026)
		(width 0.3556)
		(layer "F.Cu")
		(net "P3V3_AUX")
	)
	(segment
		(start 131.866894 -131.310126)
		(end 132.476494 -131.310126)
		(width 0.381)
		(layer "F.Cu")
		(net "P3V3_AUX")
	)
	(segment
		(start 112.892332 -406.439116)
		(end 112.892332 -405.18842)
		(width 0.381)
		(layer "F.Cu")
		(net "P3V3_AUX")
	)
	(segment
		(start 127.23495 -58.003948)
		(end 127.152908 -57.921906)
		(width 0.381)
		(layer "F.Cu")
		(net "P3V3_AUX")
	)
	(segment
		(start 121.503186 -38.655498)
		(end 121.492264 -38.655498)
		(width 0.381)
		(layer "F.Cu")
		(net "P3V3_AUX")
	)
	(segment
		(start 368.395758 -15.321788)
		(end 366.91189 -15.321788)
		(width 0.381)
		(layer "F.Cu")
		(net "P3V3_AUX")
	)
	(segment
		(start 147.797774 -50.388012)
		(end 147.188174 -50.388012)
		(width 0.381)
		(layer "F.Cu")
		(net "P3V3_AUX")
	)
	(segment
		(start 169.022522 -419.495478)
		(end 168.412922 -419.495478)
		(width 0.381)
		(layer "F.Cu")
		(net "P3V3_AUX")
	)
	(segment
		(start 132.55879 -114.920268)
		(end 132.55879 -115.585748)
		(width 0.381)
		(layer "F.Cu")
		(net "P3V3_AUX")
	)
	(segment
		(start 140.40993 -46.954948)
		(end 141.01953 -46.954948)
		(width 0.381)
		(layer "F.Cu")
		(net "P3V3_AUX")
	)
	(segment
		(start 24.12365 -392.731498)
		(end 24.52878 -392.731498)
		(width 0.4572)
		(layer "F.Cu")
		(net "P3V3_AUX")
	)
	(segment
		(start 194.00393 -104.955848)
		(end 194.61353 -104.955848)
		(width 0.381)
		(layer "F.Cu")
		(net "P3V3_AUX")
	)
	(segment
		(start 278.039576 -16.576548)
		(end 278.039576 -16.373348)
		(width 0.381)
		(layer "F.Cu")
		(net "P3V3_AUX")
	)
	(segment
		(start 51.193446 -117.53977)
		(end 51.193446 -116.52377)
		(width 0.381)
		(layer "F.Cu")
		(net "P3V3_AUX")
	)
	(segment
		(start 23.646892 -414.111948)
		(end 23.037292 -414.111948)
		(width 0.381)
		(layer "F.Cu")
		(net "P3V3_AUX")
	)
	(segment
		(start 291.94633 -411.21584)
		(end 291.32784 -411.21584)
		(width 0.381)
		(layer "F.Cu")
		(net "P3V3_AUX")
	)
	(segment
		(start 196.738748 -111.963962)
		(end 195.850764 -111.963962)
		(width 0.381)
		(layer "F.Cu")
		(net "P3V3_AUX")
	)
	(segment
		(start 391.18286 -31.186628)
		(end 391.5664 -31.186628)
		(width 0.381)
		(layer "F.Cu")
		(net "P3V3_AUX")
	)
	(segment
		(start 180.776626 -417.303204)
		(end 180.784246 -417.310824)
		(width 0.381)
		(layer "F.Cu")
		(net "P3V3_AUX")
	)
	(segment
		(start 96.294448 -74.367644)
		(end 96.294448 -73.758044)
		(width 0.381)
		(layer "F.Cu")
		(net "P3V3_AUX")
	)
	(segment
		(start 234.126278 -245.011448)
		(end 234.126278 -244.368828)
		(width 0.381)
		(layer "F.Cu")
		(net "P3V3_AUX")
	)
	(segment
		(start 182.17388 -127.364998)
		(end 182.17388 -127.975868)
		(width 0.381)
		(layer "F.Cu")
		(net "P3V3_AUX")
	)
	(segment
		(start 446.4431 -117.193822)
		(end 447.082164 -117.193822)
		(width 0.381)
		(layer "F.Cu")
		(net "P3V3_AUX")
	)
	(segment
		(start 208.89341 -119.1006)
		(end 209.5754 -119.1006)
		(width 0.381)
		(layer "F.Cu")
		(net "P3V3_AUX")
	)
	(segment
		(start 15.933674 -77.578204)
		(end 15.933674 -76.943204)
		(width 0.381)
		(layer "F.Cu")
		(net "P3V3_AUX")
	)
	(segment
		(start 447.91249 -41.025572)
		(end 447.91249 -41.747948)
		(width 0.381)
		(layer "F.Cu")
		(net "P3V3_AUX")
	)
	(segment
		(start 143.368268 -115.437666)
		(end 143.495268 -115.310666)
		(width 0.381)
		(layer "F.Cu")
		(net "P3V3_AUX")
	)
	(segment
		(start 365.788448 -398.93494)
		(end 366.894872 -398.93494)
		(width 0.381)
		(layer "F.Cu")
		(net "P3V3_AUX")
	)
	(segment
		(start 359.983532 -385.17449)
		(end 359.2449 -385.17449)
		(width 0.381)
		(layer "F.Cu")
		(net "P3V3_AUX")
	)
	(segment
		(start 46.98365 -107.032298)
		(end 46.982634 -107.031282)
		(width 0.3556)
		(layer "F.Cu")
		(net "P3V3_AUX")
	)
	(segment
		(start 359.59542 -407.233628)
		(end 360.85145 -407.233628)
		(width 0.381)
		(layer "F.Cu")
		(net "P3V3_AUX")
	)
	(segment
		(start 375.04878 -421.925496)
		(end 374.275858 -421.925496)
		(width 0.381)
		(layer "F.Cu")
		(net "P3V3_AUX")
	)
	(segment
		(start 333.23784 -14.770608)
		(end 333.23784 -14.118082)
		(width 0.381)
		(layer "F.Cu")
		(net "P3V3_AUX")
	)
	(segment
		(start 144.48536 -125.167898)
		(end 144.48536 -126.630684)
		(width 0.381)
		(layer "F.Cu")
		(net "P3V3_AUX")
	)
	(segment
		(start 127.152908 -57.921906)
		(end 125.476 -57.921906)
		(width 0.381)
		(layer "F.Cu")
		(net "P3V3_AUX")
	)
	(segment
		(start 291.94633 -411.21584)
		(end 291.94633 -410.19349)
		(width 0.381)
		(layer "F.Cu")
		(net "P3V3_AUX")
	)
	(segment
		(start 304.407062 -27.997658)
		(end 305.174142 -27.997658)
		(width 0.381)
		(layer "F.Cu")
		(net "P3V3_AUX")
	)
	(segment
		(start 177.22342 -426.07484)
		(end 177.18532 -426.07484)
		(width 0.381)
		(layer "F.Cu")
		(net "P3V3_AUX")
	)
	(segment
		(start 303.821084 -426.957236)
		(end 303.186084 -426.957236)
		(width 0.381)
		(layer "F.Cu")
		(net "P3V3_AUX")
	)
	(segment
		(start 83.730592 -64.668908)
		(end 83.730592 -64.059308)
		(width 0.381)
		(layer "F.Cu")
		(net "P3V3_AUX")
	)
	(segment
		(start 278.039576 -17.269968)
		(end 278.039576 -16.576548)
		(width 0.381)
		(layer "F.Cu")
		(net "P3V3_AUX")
	)
	(segment
		(start 365.78667 -403.957028)
		(end 365.771684 -403.972014)
		(width 0.381)
		(layer "F.Cu")
		(net "P3V3_AUX")
	)
	(segment
		(start 225.171762 -70.792848)
		(end 224.536762 -70.792848)
		(width 0.4572)
		(layer "F.Cu")
		(net "P3V3_AUX")
	)
	(segment
		(start 371.176804 -67.721226)
		(end 370.55552 -67.721226)
		(width 0.381)
		(layer "F.Cu")
		(net "P3V3_AUX")
	)
	(segment
		(start 435.585616 -41.1226)
		(end 435.6735 -41.1226)
		(width 0.381)
		(layer "F.Cu")
		(net "P3V3_AUX")
	)
	(segment
		(start 209.922618 -37.331904)
		(end 209.959956 -37.369242)
		(width 0.2286)
		(layer "F.Cu")
		(net "P3V3_AUX")
	)
	(segment
		(start 423.823892 -396.635478)
		(end 423.214292 -396.635478)
		(width 0.381)
		(layer "F.Cu")
		(net "P3V3_AUX")
	)
	(segment
		(start 193.004186 -429.01108)
		(end 193.004186 -428.26686)
		(width 0.381)
		(layer "F.Cu")
		(net "P3V3_AUX")
	)
	(segment
		(start 77.910944 -74.501502)
		(end 77.910944 -73.828148)
		(width 0.381)
		(layer "F.Cu")
		(net "P3V3_AUX")
	)
	(segment
		(start 21.577046 -99.413314)
		(end 22.23008 -99.413314)
		(width 0.381)
		(layer "F.Cu")
		(net "P3V3_AUX")
	)
	(segment
		(start 327.45934 -20.632928)
		(end 327.45934 -20.363688)
		(width 0.381)
		(layer "F.Cu")
		(net "P3V3_AUX")
	)
	(segment
		(start 26.6446 -408.3812)
		(end 26.6446 -408.64155)
		(width 0.381)
		(layer "F.Cu")
		(net "P3V3_AUX")
	)
	(segment
		(start 137.01141 -25.189688)
		(end 137.78484 -25.189688)
		(width 0.381)
		(layer "F.Cu")
		(net "P3V3_AUX")
	)
	(segment
		(start 382.405382 -71.134224)
		(end 383.044446 -71.134224)
		(width 0.381)
		(layer "F.Cu")
		(net "P3V3_AUX")
	)
	(segment
		(start 202.26401 -119.19966)
		(end 201.545698 -119.19966)
		(width 0.381)
		(layer "F.Cu")
		(net "P3V3_AUX")
	)
	(segment
		(start 150.332694 -73.319894)
		(end 152.286208 -73.319894)
		(width 0.381)
		(layer "F.Cu")
		(net "P3V3_AUX")
	)
	(segment
		(start 319.247266 -61.864748)
		(end 319.790572 -61.864748)
		(width 0.381)
		(layer "F.Cu")
		(net "P3V3_AUX")
	)
	(segment
		(start 224.390458 -234.50169)
		(end 224.870518 -234.02163)
		(width 0.381)
		(layer "F.Cu")
		(net "P3V3_AUX")
	)
	(segment
		(start 208.89341 -121.1072)
		(end 208.89341 -121.8184)
		(width 0.381)
		(layer "F.Cu")
		(net "P3V3_AUX")
	)
	(segment
		(start 118.169944 -75.431142)
		(end 118.804944 -75.431142)
		(width 0.381)
		(layer "F.Cu")
		(net "P3V3_AUX")
	)
	(segment
		(start 49.096422 -436.803038)
		(end 49.096422 -436.405528)
		(width 0.381)
		(layer "F.Cu")
		(net "P3V3_AUX")
	)
	(segment
		(start 348.206314 -358.906826)
		(end 348.206314 -358.217724)
		(width 0.381)
		(layer "F.Cu")
		(net "P3V3_AUX")
	)
	(segment
		(start 35.977068 -436.268368)
		(end 35.977068 -436.903368)
		(width 0.381)
		(layer "F.Cu")
		(net "P3V3_AUX")
	)
	(segment
		(start 453.319896 -104.249728)
		(end 452.710296 -104.249728)
		(width 0.381)
		(layer "F.Cu")
		(net "P3V3_AUX")
	)
	(segment
		(start 293.130478 -17.253204)
		(end 294.482012 -17.253204)
		(width 0.381)
		(layer "F.Cu")
		(net "P3V3_AUX")
	)
	(segment
		(start 218.48953 -128.819148)
		(end 219.10548 -128.819148)
		(width 0.381)
		(layer "F.Cu")
		(net "P3V3_AUX")
	)
	(segment
		(start 464.036156 -110.287308)
		(end 464.036156 -109.656372)
		(width 0.381)
		(layer "F.Cu")
		(net "P3V3_AUX")
	)
	(segment
		(start 164.14115 -433.265326)
		(end 164.14115 -433.874926)
		(width 0.381)
		(layer "F.Cu")
		(net "P3V3_AUX")
	)
	(segment
		(start 312.043572 -39.868348)
		(end 311.427622 -39.868348)
		(width 0.3302)
		(layer "F.Cu")
		(net "P3V3_AUX")
	)
	(segment
		(start 211.4296 -107.81665)
		(end 211.4296 -108.4834)
		(width 0.381)
		(layer "F.Cu")
		(net "P3V3_AUX")
	)
	(segment
		(start 309.761636 -29.588968)
		(end 309.761636 -30.182312)
		(width 0.381)
		(layer "F.Cu")
		(net "P3V3_AUX")
	)
	(segment
		(start 360.16565 -405.04745)
		(end 360.16565 -404.7998)
		(width 0.381)
		(layer "F.Cu")
		(net "P3V3_AUX")
	)
	(segment
		(start 127.80518 -21.772118)
		(end 126.91872 -21.772118)
		(width 0.381)
		(layer "F.Cu")
		(net "P3V3_AUX")
	)
	(segment
		(start 181.86908 -56.352948)
		(end 181.17693 -56.352948)
		(width 0.381)
		(layer "F.Cu")
		(net "P3V3_AUX")
	)
	(segment
		(start 210.34883 -42.382948)
		(end 210.34883 -40.731948)
		(width 0.381)
		(layer "F.Cu")
		(net "P3V3_AUX")
	)
	(segment
		(start 67.81165 -36.294568)
		(end 67.81165 -35.587178)
		(width 0.381)
		(layer "F.Cu")
		(net "P3V3_AUX")
	)
	(segment
		(start 197.41388 -113.102898)
		(end 198.12508 -113.102898)
		(width 0.381)
		(layer "F.Cu")
		(net "P3V3_AUX")
	)
	(segment
		(start 461.179164 -118.919498)
		(end 461.179164 -120.020334)
		(width 0.381)
		(layer "F.Cu")
		(net "P3V3_AUX")
	)
	(segment
		(start 305.863244 -14.51102)
		(end 305.094132 -14.51102)
		(width 0.381)
		(layer "F.Cu")
		(net "P3V3_AUX")
	)
	(segment
		(start 160.002474 -319.716658)
		(end 158.813246 -319.716658)
		(width 0.381)
		(layer "F.Cu")
		(net "P3V3_AUX")
	)
	(segment
		(start 20.20951 -70.814692)
		(end 19.59991 -70.814692)
		(width 0.381)
		(layer "F.Cu")
		(net "P3V3_AUX")
	)
	(segment
		(start 143.495268 -114.73434)
		(end 143.013176 -114.73434)
		(width 0.381)
		(layer "F.Cu")
		(net "P3V3_AUX")
	)
	(segment
		(start 106.730292 -30.681422)
		(end 106.030522 -30.681422)
		(width 0.381)
		(layer "F.Cu")
		(net "P3V3_AUX")
	)
	(segment
		(start 165.495224 -421.835326)
		(end 164.862256 -422.468294)
		(width 0.381)
		(layer "F.Cu")
		(net "P3V3_AUX")
	)
	(segment
		(start 101.433884 -391.61974)
		(end 100.779072 -391.61974)
		(width 0.381)
		(layer "F.Cu")
		(net "P3V3_AUX")
	)
	(segment
		(start 95.123 -418.685218)
		(end 95.123 -418.083238)
		(width 0.381)
		(layer "F.Cu")
		(net "P3V3_AUX")
	)
	(segment
		(start 51.193446 -112.33277)
		(end 50.583846 -112.33277)
		(width 0.381)
		(layer "F.Cu")
		(net "P3V3_AUX")
	)
	(segment
		(start 76.90231 -74.501502)
		(end 76.90231 -73.828148)
		(width 0.381)
		(layer "F.Cu")
		(net "P3V3_AUX")
	)
	(segment
		(start 29.504132 -391.625582)
		(end 29.53004 -391.65149)
		(width 0.4572)
		(layer "F.Cu")
		(net "P3V3_AUX")
	)
	(segment
		(start 102.411276 -420.215568)
		(end 102.063296 -420.563548)
		(width 0.381)
		(layer "F.Cu")
		(net "P3V3_AUX")
	)
	(segment
		(start 90.760042 -33.020508)
		(end 92.32011 -33.020508)
		(width 0.381)
		(layer "F.Cu")
		(net "P3V3_AUX")
	)
	(segment
		(start 36.358068 -438.223406)
		(end 36.800282 -438.223406)
		(width 0.381)
		(layer "F.Cu")
		(net "P3V3_AUX")
	)
	(segment
		(start 362.54055 -409.654248)
		(end 363.2835 -409.654248)
		(width 0.381)
		(layer "F.Cu")
		(net "P3V3_AUX")
	)
	(segment
		(start 80.77073 -60.37834)
		(end 80.77073 -59.772296)
		(width 0.4572)
		(layer "F.Cu")
		(net "P3V3_AUX")
	)
	(segment
		(start 297.552364 -14.506194)
		(end 298.22648 -14.506194)
		(width 0.381)
		(layer "F.Cu")
		(net "P3V3_AUX")
	)
	(segment
		(start 333.23657 -52.209446)
		(end 333.508858 -51.739546)
		(width 0.2032)
		(layer "F.Cu")
		(net "P3V3_AUX")
	)
	(segment
		(start 316.353444 -51.450748)
		(end 316.607444 -51.196748)
		(width 0.3048)
		(layer "F.Cu")
		(net "P3V3_AUX")
	)
	(segment
		(start 276.178264 -17.683988)
		(end 276.178264 -18.228564)
		(width 0.381)
		(layer "F.Cu")
		(net "P3V3_AUX")
	)
	(segment
		(start 116.75618 -418.554662)
		(end 117.722396 -419.520878)
		(width 0.381)
		(layer "F.Cu")
		(net "P3V3_AUX")
	)
	(segment
		(start 301.01032 -412.004256)
		(end 301.6504 -412.004256)
		(width 0.381)
		(layer "F.Cu")
		(net "P3V3_AUX")
	)
	(segment
		(start 176.478438 -416.729418)
		(end 177.088038 -416.729418)
		(width 0.381)
		(layer "F.Cu")
		(net "P3V3_AUX")
	)
	(segment
		(start 183.257952 -409.18003)
		(end 182.781448 -408.703526)
		(width 0.381)
		(layer "F.Cu")
		(net "P3V3_AUX")
	)
	(segment
		(start 116.75618 -417.713668)
		(end 116.75618 -418.554662)
		(width 0.381)
		(layer "F.Cu")
		(net "P3V3_AUX")
	)
	(segment
		(start 385.316222 -59.719464)
		(end 384.706622 -59.719464)
		(width 0.381)
		(layer "F.Cu")
		(net "P3V3_AUX")
	)
	(segment
		(start 128.009396 -73.370948)
		(end 128.37795 -73.370948)
		(width 0.381)
		(layer "F.Cu")
		(net "P3V3_AUX")
	)
	(segment
		(start 311.5056 -31.8008)
		(end 312.048144 -32.343344)
		(width 0.3302)
		(layer "F.Cu")
		(net "P3V3_AUX")
	)
	(segment
		(start 278.039576 -16.373348)
		(end 277.709376 -16.043148)
		(width 0.381)
		(layer "F.Cu")
		(net "P3V3_AUX")
	)
	(segment
		(start 458.01661 -39.765478)
		(end 457.43495 -39.765478)
		(width 0.381)
		(layer "F.Cu")
		(net "P3V3_AUX")
	)
	(segment
		(start 312.00598 -35.804348)
		(end 312.043572 -35.84194)
		(width 0.381)
		(layer "F.Cu")
		(net "P3V3_AUX")
	)
	(segment
		(start 150.42388 -44.160948)
		(end 150.61438 -44.351448)
		(width 0.381)
		(layer "F.Cu")
		(net "P3V3_AUX")
	)
	(segment
		(start 150.89886 -127.497078)
		(end 151.5872 -127.497078)
		(width 0.381)
		(layer "F.Cu")
		(net "P3V3_AUX")
	)
	(segment
		(start 319.174622 -59.428888)
		(end 319.661032 -59.428888)
		(width 0.381)
		(layer "F.Cu")
		(net "P3V3_AUX")
	)
	(segment
		(start 303.780444 -438.509156)
		(end 303.066196 -438.509156)
		(width 0.381)
		(layer "F.Cu")
		(net "P3V3_AUX")
	)
	(segment
		(start 147.797774 -52.420012)
		(end 147.188174 -52.420012)
		(width 0.381)
		(layer "F.Cu")
		(net "P3V3_AUX")
	)
	(segment
		(start 198.30923 -115.534948)
		(end 197.59041 -115.534948)
		(width 0.381)
		(layer "F.Cu")
		(net "P3V3_AUX")
	)
	(segment
		(start 352.53168 -230.622348)
		(end 352.53168 -230.086662)
		(width 0.2032)
		(layer "F.Cu")
		(net "P3V3_AUX")
	)
	(segment
		(start 183.364632 -426.8216)
		(end 184.023 -426.8216)
		(width 0.381)
		(layer "F.Cu")
		(net "P3V3_AUX")
	)
	(segment
		(start 461.169004 -107.018836)
		(end 458.634592 -107.018836)
		(width 0.381)
		(layer "F.Cu")
		(net "P3V3_AUX")
	)
	(segment
		(start 209.34553 -132.862828)
		(end 208.71688 -132.862828)
		(width 0.381)
		(layer "F.Cu")
		(net "P3V3_AUX")
	)
	(segment
		(start 281.16022 -17.613122)
		(end 279.727914 -17.613122)
		(width 0.381)
		(layer "F.Cu")
		(net "P3V3_AUX")
	)
	(segment
		(start 158.33471 -81.5086)
		(end 158.33471 -80.452468)
		(width 0.381)
		(layer "F.Cu")
		(net "P3V3_AUX")
	)
	(segment
		(start 145.57121 -36.956238)
		(end 145.76552 -36.761928)
		(width 0.381)
		(layer "F.Cu")
		(net "P3V3_AUX")
	)
	(segment
		(start 72.26681 -74.501502)
		(end 72.26681 -73.828148)
		(width 0.381)
		(layer "F.Cu")
		(net "P3V3_AUX")
	)
	(segment
		(start 211.172044 -14.892528)
		(end 211.172044 -14.087094)
		(width 0.381)
		(layer "F.Cu")
		(net "P3V3_AUX")
	)
	(segment
		(start 124.141992 -18.355056)
		(end 124.141992 -16.90751)
		(width 0.381)
		(layer "F.Cu")
		(net "P3V3_AUX")
	)
	(segment
		(start 127.288544 -76.621132)
		(end 127.288544 -75.253342)
		(width 0.254)
		(layer "F.Cu")
		(net "P3V3_AUX")
	)
	(segment
		(start 407.942542 -319.716658)
		(end 406.753314 -319.716658)
		(width 0.381)
		(layer "F.Cu")
		(net "P3V3_AUX")
	)
	(segment
		(start 49.747932 -393.30122)
		(end 49.724564 -393.324588)
		(width 0.4572)
		(layer "F.Cu")
		(net "P3V3_AUX")
	)
	(segment
		(start 29.11983 -430.875948)
		(end 27.92984 -430.875948)
		(width 0.381)
		(layer "F.Cu")
		(net "P3V3_AUX")
	)
	(segment
		(start 180.975 -20.284948)
		(end 180.848 -20.411948)
		(width 0.381)
		(layer "F.Cu")
		(net "P3V3_AUX")
	)
	(segment
		(start 451.81774 -114.82451)
		(end 452.49338 -114.82451)
		(width 0.381)
		(layer "F.Cu")
		(net "P3V3_AUX")
	)
	(segment
		(start 210.514946 -319.716658)
		(end 211.619846 -319.716658)
		(width 0.381)
		(layer "F.Cu")
		(net "P3V3_AUX")
	)
	(segment
		(start 21.352002 -403.827488)
		(end 20.576032 -403.827488)
		(width 0.381)
		(layer "F.Cu")
		(net "P3V3_AUX")
	)
	(segment
		(start 127.288544 -75.253342)
		(end 126.653544 -75.253342)
		(width 0.381)
		(layer "F.Cu")
		(net "P3V3_AUX")
	)
	(segment
		(start 69.8119 -112.410748)
		(end 69.060822 -111.65967)
		(width 0.381)
		(layer "F.Cu")
		(net "P3V3_AUX")
	)
	(segment
		(start 465.83727 -101.960934)
		(end 465.443316 -101.56698)
		(width 0.381)
		(layer "F.Cu")
		(net "P3V3_AUX")
	)
	(segment
		(start 316.996572 -53.787548)
		(end 316.380622 -53.787548)
		(width 0.381)
		(layer "F.Cu")
		(net "P3V3_AUX")
	)
	(segment
		(start 288.87801 -96.416368)
		(end 288.87801 -95.760794)
		(width 0.381)
		(layer "F.Cu")
		(net "P3V3_AUX")
	)
	(segment
		(start 23.669752 -411.434534)
		(end 23.060152 -411.434534)
		(width 0.381)
		(layer "F.Cu")
		(net "P3V3_AUX")
	)
	(segment
		(start 95.7072 -428.816008)
		(end 96.141286 -428.381922)
		(width 0.381)
		(layer "F.Cu")
		(net "P3V3_AUX")
	)
	(segment
		(start 404.045928 -66.641472)
		(end 404.346156 -66.341244)
		(width 0.508)
		(layer "F.Cu")
		(net "P3V3_AUX")
	)
	(segment
		(start 86.868 -64.773048)
		(end 86.868 -64.163448)
		(width 0.381)
		(layer "F.Cu")
		(net "P3V3_AUX")
	)
	(segment
		(start 137.006838 -38.049708)
		(end 139.03833 -38.049708)
		(width 0.381)
		(layer "F.Cu")
		(net "P3V3_AUX")
	)
	(segment
		(start 185.22188 -127.364998)
		(end 185.22188 -127.975868)
		(width 0.381)
		(layer "F.Cu")
		(net "P3V3_AUX")
	)
	(segment
		(start 356.21595 -415.127948)
		(end 355.6 -415.127948)
		(width 0.381)
		(layer "F.Cu")
		(net "P3V3_AUX")
	)
	(segment
		(start 146.081496 -66.648838)
		(end 146.141186 -66.708528)
		(width 0.381)
		(layer "F.Cu")
		(net "P3V3_AUX")
	)
	(segment
		(start 438.74055 -94.827598)
		(end 438.277 -95.291148)
		(width 0.381)
		(layer "F.Cu")
		(net "P3V3_AUX")
	)
	(segment
		(start 438.47766 -43.960288)
		(end 437.66486 -43.960288)
		(width 0.381)
		(layer "F.Cu")
		(net "P3V3_AUX")
	)
	(segment
		(start 278.654764 -17.885156)
		(end 278.039576 -17.269968)
		(width 0.381)
		(layer "F.Cu")
		(net "P3V3_AUX")
	)
	(segment
		(start 365.78667 -404.711408)
		(end 365.78667 -403.957028)
		(width 0.381)
		(layer "F.Cu")
		(net "P3V3_AUX")
	)
	(segment
		(start 113.28908 -398.275048)
		(end 113.28908 -398.884648)
		(width 0.3556)
		(layer "F.Cu")
		(net "P3V3_AUX")
	)
	(segment
		(start 81.604104 -152.221692)
		(end 82.322924 -152.221692)
		(width 0.381)
		(layer "F.Cu")
		(net "P3V3_AUX")
	)
	(segment
		(start 220.487494 -102.255574)
		(end 221.1578 -102.255574)
		(width 0.381)
		(layer "F.Cu")
		(net "P3V3_AUX")
	)
	(segment
		(start 139.03833 -38.049708)
		(end 139.03833 -37.414708)
		(width 0.381)
		(layer "F.Cu")
		(net "P3V3_AUX")
	)
	(segment
		(start 398.95145 -68.035678)
		(end 400.345656 -66.641472)
		(width 0.508)
		(layer "F.Cu")
		(net "P3V3_AUX")
	)
	(segment
		(start 282.131516 -16.641826)
		(end 281.16022 -17.613122)
		(width 0.381)
		(layer "F.Cu")
		(net "P3V3_AUX")
	)
	(segment
		(start 254.98679 -91.985338)
		(end 254.98679 -92.291408)
		(width 0.381)
		(layer "F.Cu")
		(net "P3V3_AUX")
	)
	(segment
		(start 385.17195 -29.581348)
		(end 385.261104 -29.670502)
		(width 0.381)
		(layer "F.Cu")
		(net "P3V3_AUX")
	)
	(segment
		(start 306.63388 -61.975492)
		(end 307.3146 -61.975492)
		(width 0.381)
		(layer "F.Cu")
		(net "P3V3_AUX")
	)
	(segment
		(start 124.26442 -417.472368)
		(end 123.33732 -418.399468)
		(width 0.381)
		(layer "F.Cu")
		(net "P3V3_AUX")
	)
	(segment
		(start 293.01059 -92.278454)
		(end 293.01059 -93.482414)
		(width 0.381)
		(layer "F.Cu")
		(net "P3V3_AUX")
	)
	(segment
		(start 420.040816 -138.575288)
		(end 420.282116 -138.333988)
		(width 0.381)
		(layer "F.Cu")
		(net "P3V3_AUX")
	)
	(segment
		(start 150.298658 -73.285858)
		(end 150.332694 -73.319894)
		(width 0.381)
		(layer "F.Cu")
		(net "P3V3_AUX")
	)
	(segment
		(start 386.037582 -73.394824)
		(end 386.653532 -73.394824)
		(width 0.381)
		(layer "F.Cu")
		(net "P3V3_AUX")
	)
	(segment
		(start 115.21313 -393.048998)
		(end 115.21313 -394.07338)
		(width 0.381)
		(layer "F.Cu")
		(net "P3V3_AUX")
	)
	(segment
		(start 26.24582 -71.821548)
		(end 25.62352 -71.821548)
		(width 0.381)
		(layer "F.Cu")
		(net "P3V3_AUX")
	)
	(segment
		(start 449.38442 -78.861412)
		(end 449.38442 -78.229968)
		(width 0.381)
		(layer "F.Cu")
		(net "P3V3_AUX")
	)
	(segment
		(start 450.72808 -113.655348)
		(end 451.73519 -113.655348)
		(width 0.381)
		(layer "F.Cu")
		(net "P3V3_AUX")
	)
	(segment
		(start 164.24783 -121.376948)
		(end 163.63188 -121.376948)
		(width 0.381)
		(layer "F.Cu")
		(net "P3V3_AUX")
	)
	(segment
		(start 140.39088 -41.855898)
		(end 140.40993 -41.836848)
		(width 0.381)
		(layer "F.Cu")
		(net "P3V3_AUX")
	)
	(segment
		(start 368.75212 -103.466138)
		(end 368.121184 -103.466138)
		(width 0.381)
		(layer "F.Cu")
		(net "P3V3_AUX")
	)
	(segment
		(start 216.872312 -68.336922)
		(end 216.875868 -68.340478)
		(width 0.4572)
		(layer "F.Cu")
		(net "P3V3_AUX")
	)
	(segment
		(start 103.652066 -230.622602)
		(end 103.651812 -230.622348)
		(width 0.2032)
		(layer "F.Cu")
		(net "P3V3_AUX")
	)
	(segment
		(start 124.141992 -16.90751)
		(end 124.169932 -16.87957)
		(width 0.381)
		(layer "F.Cu")
		(net "P3V3_AUX")
	)
	(segment
		(start 145.57121 -40.952928)
		(end 145.57121 -40.114728)
		(width 0.381)
		(layer "F.Cu")
		(net "P3V3_AUX")
	)
	(segment
		(start 393.37488 -148.408898)
		(end 393.37488 -147.792948)
		(width 0.381)
		(layer "F.Cu")
		(net "P3V3_AUX")
	)
	(segment
		(start 408.046174 -319.696846)
		(end 407.962354 -319.696846)
		(width 0.381)
		(layer "F.Cu")
		(net "P3V3_AUX")
	)
	(segment
		(start 390.355074 -38.829742)
		(end 391.763758 -38.829742)
		(width 0.381)
		(layer "F.Cu")
		(net "P3V3_AUX")
	)
	(segment
		(start 25.62352 -76.266548)
		(end 28.15463 -76.266548)
		(width 0.381)
		(layer "F.Cu")
		(net "P3V3_AUX")
	)
	(segment
		(start 22.51583 -430.367948)
		(end 21.90623 -430.367948)
		(width 0.381)
		(layer "F.Cu")
		(net "P3V3_AUX")
	)
	(segment
		(start 8.40867 -76.827888)
		(end 8.40867 -76.232512)
		(width 0.381)
		(layer "F.Cu")
		(net "P3V3_AUX")
	)
	(segment
		(start 374.26011 -421.909748)
		(end 373.30888 -421.909748)
		(width 0.381)
		(layer "F.Cu")
		(net "P3V3_AUX")
	)
	(segment
		(start 164.24783 -116.296948)
		(end 164.24783 -115.026948)
		(width 0.381)
		(layer "F.Cu")
		(net "P3V3_AUX")
	)
	(segment
		(start 217.387932 -53.95595)
		(end 217.137234 -53.705252)
		(width 0.254)
		(layer "F.Cu")
		(net "P3V3_AUX")
	)
	(segment
		(start 360.5403 -405.4221)
		(end 360.16565 -405.04745)
		(width 0.381)
		(layer "F.Cu")
		(net "P3V3_AUX")
	)
	(segment
		(start 99.589082 -74.511916)
		(end 99.589082 -73.902316)
		(width 0.381)
		(layer "F.Cu")
		(net "P3V3_AUX")
	)
	(segment
		(start 140.363448 -368.14633)
		(end 140.984478 -368.14633)
		(width 0.381)
		(layer "F.Cu")
		(net "P3V3_AUX")
	)
	(segment
		(start 369.7224 -102.106984)
		(end 369.7224 -102.982268)
		(width 0.381)
		(layer "F.Cu")
		(net "P3V3_AUX")
	)
	(segment
		(start 23.713694 -389.275828)
		(end 23.894796 -389.094726)
		(width 0.1778)
		(layer "F.Cu")
		(net "P3V3_AUX")
	)
	(segment
		(start 29.13888 -427.592998)
		(end 29.11348 -427.592998)
		(width 0.381)
		(layer "F.Cu")
		(net "P3V3_AUX")
	)
	(segment
		(start 147.48383 -124.005848)
		(end 148.09343 -124.005848)
		(width 0.381)
		(layer "F.Cu")
		(net "P3V3_AUX")
	)
	(segment
		(start 20.20951 -77.028548)
		(end 19.59991 -77.028548)
		(width 0.381)
		(layer "F.Cu")
		(net "P3V3_AUX")
	)
	(segment
		(start 103.286306 -420.215568)
		(end 102.411276 -420.215568)
		(width 0.381)
		(layer "F.Cu")
		(net "P3V3_AUX")
	)
	(segment
		(start 93.090492 -74.336656)
		(end 93.090492 -73.727056)
		(width 0.381)
		(layer "F.Cu")
		(net "P3V3_AUX")
	)
	(segment
		(start 99.457002 -417.231576)
		(end 99.457002 -416.621976)
		(width 0.381)
		(layer "F.Cu")
		(net "P3V3_AUX")
	)
	(segment
		(start 66.084958 -106.319066)
		(end 67.681094 -106.319066)
		(width 0.381)
		(layer "F.Cu")
		(net "P3V3_AUX")
	)
	(segment
		(start 14.426946 -386.103876)
		(end 15.036546 -386.103876)
		(width 0.381)
		(layer "F.Cu")
		(net "P3V3_AUX")
	)
	(segment
		(start 360.85145 -407.233628)
		(end 360.85653 -407.228548)
		(width 0.381)
		(layer "F.Cu")
		(net "P3V3_AUX")
	)
	(segment
		(start 444.472314 -319.716658)
		(end 443.367414 -319.716658)
		(width 0.381)
		(layer "F.Cu")
		(net "P3V3_AUX")
	)
	(segment
		(start 453.319896 -106.408728)
		(end 452.710296 -106.408728)
		(width 0.381)
		(layer "F.Cu")
		(net "P3V3_AUX")
	)
	(segment
		(start 319.172336 -62.992508)
		(end 319.678812 -62.992508)
		(width 0.381)
		(layer "F.Cu")
		(net "P3V3_AUX")
	)
	(segment
		(start 92.33535 -39.675308)
		(end 92.26931 -39.609268)
		(width 0.381)
		(layer "F.Cu")
		(net "P3V3_AUX")
	)
	(segment
		(start 25.948132 -131.55295)
		(end 26.63825 -131.55295)
		(width 0.381)
		(layer "F.Cu")
		(net "P3V3_AUX")
	)
	(segment
		(start 279.45588 -17.885156)
		(end 278.654764 -17.885156)
		(width 0.381)
		(layer "F.Cu")
		(net "P3V3_AUX")
	)
	(segment
		(start 387.633972 -29.50972)
		(end 386.82168 -29.50972)
		(width 0.381)
		(layer "F.Cu")
		(net "P3V3_AUX")
	)
	(segment
		(start 23.646892 -417.159948)
		(end 23.037292 -417.159948)
		(width 0.381)
		(layer "F.Cu")
		(net "P3V3_AUX")
	)
	(segment
		(start 347.057726 -22.76983)
		(end 347.057726 -23.4823)
		(width 0.381)
		(layer "F.Cu")
		(net "P3V3_AUX")
	)
	(segment
		(start 297.836844 -16.715994)
		(end 298.685204 -17.564354)
		(width 0.381)
		(layer "F.Cu")
		(net "P3V3_AUX")
	)
	(segment
		(start 124.724922 -139.813538)
		(end 124.724922 -139.178538)
		(width 0.381)
		(layer "F.Cu")
		(net "P3V3_AUX")
	)
	(segment
		(start 435.31409 -319.716658)
		(end 436.928514 -319.716658)
		(width 0.381)
		(layer "F.Cu")
		(net "P3V3_AUX")
	)
	(segment
		(start 126.852934 -66.538856)
		(end 126.770384 -66.456306)
		(width 0.381)
		(layer "F.Cu")
		(net "P3V3_AUX")
	)
	(segment
		(start 332.701392 -14.118082)
		(end 332.18374 -14.635734)
		(width 0.381)
		(layer "F.Cu")
		(net "P3V3_AUX")
	)
	(segment
		(start 298.66082 -421.01516)
		(end 298.66082 -420.276528)
		(width 0.381)
		(layer "F.Cu")
		(net "P3V3_AUX")
	)
	(segment
		(start 423.804842 -386.298948)
		(end 423.195242 -386.298948)
		(width 0.3556)
		(layer "F.Cu")
		(net "P3V3_AUX")
	)
	(segment
		(start 297.41622 -421.01516)
		(end 297.41622 -420.276528)
		(width 0.381)
		(layer "F.Cu")
		(net "P3V3_AUX")
	)
	(segment
		(start 103.651812 -230.622348)
		(end 103.651812 -230.086662)
		(width 0.2032)
		(layer "F.Cu")
		(net "P3V3_AUX")
	)
	(segment
		(start 7.920736 -75.744578)
		(end 7.129272 -75.744578)
		(width 0.381)
		(layer "F.Cu")
		(net "P3V3_AUX")
	)
	(segment
		(start 125.919738 -110.200948)
		(end 125.919738 -109.451902)
		(width 0.381)
		(layer "F.Cu")
		(net "P3V3_AUX")
	)
	(segment
		(start 148.58238 -75.350878)
		(end 147.95754 -75.350878)
		(width 0.381)
		(layer "F.Cu")
		(net "P3V3_AUX")
	)
	(segment
		(start 180.848 -20.411948)
		(end 179.05095 -20.411948)
		(width 0.381)
		(layer "F.Cu")
		(net "P3V3_AUX")
	)
	(segment
		(start 110.57636 -31.037784)
		(end 111.21136 -31.037784)
		(width 0.381)
		(layer "F.Cu")
		(net "P3V3_AUX")
	)
	(segment
		(start 23.713694 -389.425942)
		(end 23.713694 -389.275828)
		(width 0.1778)
		(layer "F.Cu")
		(net "P3V3_AUX")
	)
	(segment
		(start 95.095314 -418.712904)
		(end 95.123 -418.685218)
		(width 0.381)
		(layer "F.Cu")
		(net "P3V3_AUX")
	)
	(segment
		(start 307.55082 -425.831)
		(end 307.55082 -425.186602)
		(width 0.381)
		(layer "F.Cu")
		(net "P3V3_AUX")
	)
	(segment
		(start 334.099408 -47.250096)
		(end 334.499458 -46.850046)
		(width 0.2032)
		(layer "F.Cu")
		(net "P3V3_AUX")
	)
	(segment
		(start 111.095282 -406.458166)
		(end 111.095282 -407.067766)
		(width 0.3556)
		(layer "F.Cu")
		(net "P3V3_AUX")
	)
	(segment
		(start 272.691606 -128.641094)
		(end 272.691606 -129.44983)
		(width 0.381)
		(layer "F.Cu")
		(net "P3V3_AUX")
	)
	(segment
		(start 86.30285 -36.032948)
		(end 86.741 -36.032948)
		(width 0.381)
		(layer "F.Cu")
		(net "P3V3_AUX")
	)
	(segment
		(start 140.39088 -41.855898)
		(end 141.02588 -41.855898)
		(width 0.381)
		(layer "F.Cu")
		(net "P3V3_AUX")
	)
	(segment
		(start 334.499458 -47.650146)
		(end 334.099408 -47.250096)
		(width 0.2032)
		(layer "F.Cu")
		(net "P3V3_AUX")
	)
	(segment
		(start 124.210572 -14.19733)
		(end 124.210572 -15.50543)
		(width 0.381)
		(layer "F.Cu")
		(net "P3V3_AUX")
	)
	(segment
		(start 457.43495 -39.765478)
		(end 457.25842 -39.588948)
		(width 0.381)
		(layer "F.Cu")
		(net "P3V3_AUX")
	)
	(segment
		(start 216.06256 -131.973828)
		(end 217.72753 -131.973828)
		(width 0.381)
		(layer "F.Cu")
		(net "P3V3_AUX")
	)
	(segment
		(start 92.32011 -33.020508)
		(end 92.36075 -33.061148)
		(width 0.381)
		(layer "F.Cu")
		(net "P3V3_AUX")
	)
	(segment
		(start 439.28792 -94.827598)
		(end 438.74055 -94.827598)
		(width 0.254)
		(layer "F.Cu")
		(net "P3V3_AUX")
	)
	(segment
		(start 259.51053 -92.587572)
		(end 259.181346 -92.258388)
		(width 0.381)
		(layer "F.Cu")
		(net "P3V3_AUX")
	)
	(segment
		(start 117.722396 -419.520878)
		(end 118.09222 -419.520878)
		(width 0.381)
		(layer "F.Cu")
		(net "P3V3_AUX")
	)
	(segment
		(start 419.382448 -138.575288)
		(end 420.040816 -138.575288)
		(width 0.381)
		(layer "F.Cu")
		(net "P3V3_AUX")
	)
	(segment
		(start 49.724564 -393.324588)
		(end 49.724564 -394.44676)
		(width 0.4572)
		(layer "F.Cu")
		(net "P3V3_AUX")
	)
	(segment
		(start 183.69788 -127.364998)
		(end 183.69788 -127.975868)
		(width 0.381)
		(layer "F.Cu")
		(net "P3V3_AUX")
	)
	(segment
		(start 312.043572 -43.932348)
		(end 311.427622 -43.932348)
		(width 0.3302)
		(layer "F.Cu")
		(net "P3V3_AUX")
	)
	(segment
		(start 155.290774 -51.531012)
		(end 155.290774 -50.896012)
		(width 0.381)
		(layer "F.Cu")
		(net "P3V3_AUX")
	)
	(segment
		(start 215.662256 -131.573524)
		(end 216.06256 -131.973828)
		(width 0.381)
		(layer "F.Cu")
		(net "P3V3_AUX")
	)
	(segment
		(start 96.48444 -64.743584)
		(end 96.48444 -64.049148)
		(width 0.381)
		(layer "F.Cu")
		(net "P3V3_AUX")
	)
	(segment
		(start 154.34945 -80.936338)
		(end 154.34945 -81.489296)
		(width 0.381)
		(layer "F.Cu")
		(net "P3V3_AUX")
	)
	(segment
		(start 117.36324 -417.393628)
		(end 117.07622 -417.393628)
		(width 0.381)
		(layer "F.Cu")
		(net "P3V3_AUX")
	)
	(segment
		(start 99.7077 -411.1371)
		(end 99.52482 -411.31998)
		(width 0.381)
		(layer "F.Cu")
		(net "P3V3_AUX")
	)
	(segment
		(start 143.495268 -115.310666)
		(end 143.495268 -114.73434)
		(width 0.381)
		(layer "F.Cu")
		(net "P3V3_AUX")
	)
	(segment
		(start 298.342304 -426.878496)
		(end 297.707304 -426.878496)
		(width 0.381)
		(layer "F.Cu")
		(net "P3V3_AUX")
	)
	(segment
		(start 15.933674 -76.137516)
		(end 15.667736 -75.871578)
		(width 0.381)
		(layer "F.Cu")
		(net "P3V3_AUX")
	)
	(segment
		(start 254.36576 -91.364308)
		(end 254.98679 -91.985338)
		(width 0.381)
		(layer "F.Cu")
		(net "P3V3_AUX")
	)
	(segment
		(start 31.69793 -430.875948)
		(end 32.30753 -430.875948)
		(width 0.381)
		(layer "F.Cu")
		(net "P3V3_AUX")
	)
	(segment
		(start 379.618494 -97.620582)
		(end 379.618494 -96.212152)
		(width 0.381)
		(layer "F.Cu")
		(net "P3V3_AUX")
	)
	(segment
		(start 132.55879 -116.255292)
		(end 132.314696 -116.499386)
		(width 0.381)
		(layer "F.Cu")
		(net "P3V3_AUX")
	)
	(segment
		(start 140.26388 -368.245898)
		(end 140.363448 -368.14633)
		(width 0.381)
		(layer "F.Cu")
		(net "P3V3_AUX")
	)
	(segment
		(start 461.193896 -107.043728)
		(end 461.169004 -107.018836)
		(width 0.381)
		(layer "F.Cu")
		(net "P3V3_AUX")
	)
	(segment
		(start 384.8608 -29.581348)
		(end 385.17195 -29.581348)
		(width 0.381)
		(layer "F.Cu")
		(net "P3V3_AUX")
	)
	(segment
		(start 49.775364 -390.000744)
		(end 49.79035 -389.985758)
		(width 0.4572)
		(layer "F.Cu")
		(net "P3V3_AUX")
	)
	(segment
		(start 92.26931 -39.609268)
		(end 90.760296 -39.609268)
		(width 0.381)
		(layer "F.Cu")
		(net "P3V3_AUX")
	)
	(segment
		(start 307.04282 -319.545462)
		(end 307.214016 -319.716658)
		(width 0.381)
		(layer "F.Cu")
		(net "P3V3_AUX")
	)
	(segment
		(start 194.28968 -431.137314)
		(end 194.00266 -431.424334)
		(width 0.381)
		(layer "F.Cu")
		(net "P3V3_AUX")
	)
	(segment
		(start 70.75805 -115.426998)
		(end 70.75805 -114.772948)
		(width 0.381)
		(layer "F.Cu")
		(net "P3V3_AUX")
	)
	(segment
		(start 341.778082 -23.191978)
		(end 341.651082 -23.318978)
		(width 0.381)
		(layer "F.Cu")
		(net "P3V3_AUX")
	)
	(segment
		(start 439.320686 -46.033436)
		(end 439.633868 -45.720254)
		(width 0.381)
		(layer "F.Cu")
		(net "P3V3_AUX")
	)
	(segment
		(start 334.099408 -45.649896)
		(end 334.499458 -45.249846)
		(width 0.2032)
		(layer "F.Cu")
		(net "P3V3_AUX")
	)
	(segment
		(start 213.01583 -125.821948)
		(end 213.01583 -125.186948)
		(width 0.381)
		(layer "F.Cu")
		(net "P3V3_AUX")
	)
	(segment
		(start 163.248086 -63.297308)
		(end 163.857686 -63.297308)
		(width 0.381)
		(layer "F.Cu")
		(net "P3V3_AUX")
	)
	(segment
		(start 313.135264 -26.062686)
		(end 313.135264 -27.078686)
		(width 0.381)
		(layer "F.Cu")
		(net "P3V3_AUX")
	)
	(segment
		(start 164.52215 -418.114226)
		(end 164.52215 -417.504626)
		(width 0.381)
		(layer "F.Cu")
		(net "P3V3_AUX")
	)
	(segment
		(start 319.790572 -55.235348)
		(end 319.152016 -55.235348)
		(width 0.381)
		(layer "F.Cu")
		(net "P3V3_AUX")
	)
	(segment
		(start 20.20951 -75.132692)
		(end 19.59991 -75.132692)
		(width 0.381)
		(layer "F.Cu")
		(net "P3V3_AUX")
	)
	(segment
		(start 26.2509 -71.816468)
		(end 26.24582 -71.821548)
		(width 0.381)
		(layer "F.Cu")
		(net "P3V3_AUX")
	)
	(segment
		(start 311.364122 -49.202848)
		(end 310.79313 -49.202848)
		(width 0.381)
		(layer "F.Cu")
		(net "P3V3_AUX")
	)
	(segment
		(start 151.16683 -43.570398)
		(end 150.734522 -43.13809)
		(width 0.381)
		(layer "F.Cu")
		(net "P3V3_AUX")
	)
	(segment
		(start 110.932722 -126.678182)
		(end 110.323122 -126.678182)
		(width 0.381)
		(layer "F.Cu")
		(net "P3V3_AUX")
	)
	(segment
		(start 8.40867 -77.462888)
		(end 8.40867 -76.827888)
		(width 0.381)
		(layer "F.Cu")
		(net "P3V3_AUX")
	)
	(segment
		(start 194.28968 -430.618138)
		(end 194.28968 -431.137314)
		(width 0.381)
		(layer "F.Cu")
		(net "P3V3_AUX")
	)
	(segment
		(start 196.780912 -39.046912)
		(end 196.171312 -39.046912)
		(width 0.381)
		(layer "F.Cu")
		(net "P3V3_AUX")
	)
	(segment
		(start 15.933674 -76.943204)
		(end 15.933674 -76.137516)
		(width 0.381)
		(layer "F.Cu")
		(net "P3V3_AUX")
	)
	(segment
		(start 177.9524 -93.138498)
		(end 177.9524 -92.527628)
		(width 0.381)
		(layer "F.Cu")
		(net "P3V3_AUX")
	)
	(segment
		(start 180.4924 -93.138498)
		(end 180.4924 -92.527628)
		(width 0.381)
		(layer "F.Cu")
		(net "P3V3_AUX")
	)
	(segment
		(start 433.73294 -135.029702)
		(end 433.73294 -135.664702)
		(width 0.381)
		(layer "F.Cu")
		(net "P3V3_AUX")
	)
	(segment
		(start 145.57121 -40.114728)
		(end 145.57121 -36.956238)
		(width 0.381)
		(layer "F.Cu")
		(net "P3V3_AUX")
	)
	(segment
		(start 304.1396 -60.094368)
		(end 303.48936 -60.094368)
		(width 0.381)
		(layer "F.Cu")
		(net "P3V3_AUX")
	)
	(segment
		(start 224.870518 -234.02163)
		(end 224.870518 -233.76255)
		(width 0.381)
		(layer "F.Cu")
		(net "P3V3_AUX")
	)
	(segment
		(start 109.980984 -393.14374)
		(end 109.980984 -394.15974)
		(width 0.381)
		(layer "F.Cu")
		(net "P3V3_AUX")
	)
	(segment
		(start 301.136304 -426.878496)
		(end 300.501304 -426.878496)
		(width 0.381)
		(layer "F.Cu")
		(net "P3V3_AUX")
	)
	(segment
		(start 19.119596 -392.815826)
		(end 18.484596 -392.815826)
		(width 0.381)
		(layer "F.Cu")
		(net "P3V3_AUX")
	)
	(segment
		(start 215.58123 -40.687498)
		(end 215.58123 -41.341548)
		(width 0.381)
		(layer "F.Cu")
		(net "P3V3_AUX")
	)
	(segment
		(start 410.225748 -360.995214)
		(end 409.355036 -361.865926)
		(width 0.381)
		(layer "F.Cu")
		(net "P3V3_AUX")
	)
	(segment
		(start 111.764826 -404.060914)
		(end 111.764826 -403.095206)
		(width 0.381)
		(layer "F.Cu")
		(net "P3V3_AUX")
	)
	(segment
		(start 309.976012 -44.895008)
		(end 309.922672 -44.948348)
		(width 0.3302)
		(layer "F.Cu")
		(net "P3V3_AUX")
	)
	(segment
		(start 391.763758 -38.829742)
		(end 391.763758 -38.667182)
		(width 0.381)
		(layer "F.Cu")
		(net "P3V3_AUX")
	)
	(segment
		(start 164.647626 -39.20363)
		(end 164.647626 -38.067234)
		(width 0.381)
		(layer "F.Cu")
		(net "P3V3_AUX")
	)
	(segment
		(start 15.197582 -408.116786)
		(end 15.197582 -407.507186)
		(width 0.381)
		(layer "F.Cu")
		(net "P3V3_AUX")
	)
	(segment
		(start 32.362902 -407.509218)
		(end 32.972502 -407.509218)
		(width 0.381)
		(layer "F.Cu")
		(net "P3V3_AUX")
	)
	(segment
		(start 451.73519 -113.655348)
		(end 451.81774 -113.572798)
		(width 0.381)
		(layer "F.Cu")
		(net "P3V3_AUX")
	)
	(segment
		(start 453.319896 -108.059728)
		(end 452.710296 -108.059728)
		(width 0.381)
		(layer "F.Cu")
		(net "P3V3_AUX")
	)
	(segment
		(start 164.24783 -115.026948)
		(end 163.63188 -115.026948)
		(width 0.381)
		(layer "F.Cu")
		(net "P3V3_AUX")
	)
	(segment
		(start 47.633128 -107.032298)
		(end 46.98365 -107.032298)
		(width 0.3556)
		(layer "F.Cu")
		(net "P3V3_AUX")
	)
	(segment
		(start 107.65663 -59.070748)
		(end 107.65663 -60.086748)
		(width 0.381)
		(layer "F.Cu")
		(net "P3V3_AUX")
	)
	(segment
		(start 75.268074 -38.5699)
		(end 74.10831 -38.5699)
		(width 0.2286)
		(layer "F.Cu")
		(net "P3V3_AUX")
	)
	(segment
		(start 404.346156 -66.341244)
		(end 404.346156 -65.085976)
		(width 0.508)
		(layer "F.Cu")
		(net "P3V3_AUX")
	)
	(segment
		(start 180.79212 -410.80817)
		(end 180.79212 -410.10586)
		(width 0.381)
		(layer "F.Cu")
		(net "P3V3_AUX")
	)
	(segment
		(start 360.85653 -406.780238)
		(end 360.85653 -407.228548)
		(width 0.381)
		(layer "F.Cu")
		(net "P3V3_AUX")
	)
	(segment
		(start 203.99502 -112.02924)
		(end 203.71054 -111.74476)
		(width 0.381)
		(layer "F.Cu")
		(net "P3V3_AUX")
	)
	(segment
		(start 13.800582 -410.402786)
		(end 13.800582 -409.793186)
		(width 0.381)
		(layer "F.Cu")
		(net "P3V3_AUX")
	)
	(segment
		(start 159.181546 -30.941518)
		(end 159.181546 -30.272228)
		(width 0.381)
		(layer "F.Cu")
		(net "P3V3_AUX")
	)
	(segment
		(start 194.33413 -355.996748)
		(end 194.33413 -354.904548)
		(width 0.381)
		(layer "F.Cu")
		(net "P3V3_AUX")
	)
	(segment
		(start 278.01443 -424.69562)
		(end 277.93315 -424.61434)
		(width 0.381)
		(layer "F.Cu")
		(net "P3V3_AUX")
	)
	(segment
		(start 310.538876 -39.177468)
		(end 309.993792 -39.177468)
		(width 0.381)
		(layer "F.Cu")
		(net "P3V3_AUX")
	)
	(segment
		(start 213.445598 -27.268424)
		(end 213.802468 -26.911554)
		(width 0.381)
		(layer "F.Cu")
		(net "P3V3_AUX")
	)
	(segment
		(start 181.407562 -417.303204)
		(end 180.776626 -417.303204)
		(width 0.381)
		(layer "F.Cu")
		(net "P3V3_AUX")
	)
	(segment
		(start 461.557878 -94.317566)
		(end 461.517746 -94.277434)
		(width 0.381)
		(layer "F.Cu")
		(net "P3V3_AUX")
	)
	(segment
		(start 449.52666 -51.976528)
		(end 449.52666 -52.891436)
		(width 0.508)
		(layer "F.Cu")
		(net "P3V3_AUX")
	)
	(segment
		(start 28.028646 -389.304276)
		(end 28.054046 -389.278876)
		(width 0.381)
		(layer "F.Cu")
		(net "P3V3_AUX")
	)
	(segment
		(start 147.79625 -48.283368)
		(end 147.10918 -48.283368)
		(width 0.381)
		(layer "F.Cu")
		(net "P3V3_AUX")
	)
	(segment
		(start 120.77827 -422.463468)
		(end 121.38787 -422.463468)
		(width 0.381)
		(layer "F.Cu")
		(net "P3V3_AUX")
	)
	(segment
		(start 193.089022 -25.565862)
		(end 192.454022 -25.565862)
		(width 0.4572)
		(layer "F.Cu")
		(net "P3V3_AUX")
	)
	(segment
		(start 29.897578 -394.654786)
		(end 29.548074 -394.305282)
		(width 0.4572)
		(layer "F.Cu")
		(net "P3V3_AUX")
	)
	(segment
		(start 369.12169 -403.936708)
		(end 369.83162 -403.936708)
		(width 0.381)
		(layer "F.Cu")
		(net "P3V3_AUX")
	)
	(segment
		(start 29.11348 -427.592998)
		(end 28.62453 -428.081948)
		(width 0.381)
		(layer "F.Cu")
		(net "P3V3_AUX")
	)
	(segment
		(start 112.111536 -31.037784)
		(end 112.4966 -30.65272)
		(width 0.381)
		(layer "F.Cu")
		(net "P3V3_AUX")
	)
	(segment
		(start 97.821242 -417.366196)
		(end 97.821242 -416.491928)
		(width 0.381)
		(layer "F.Cu")
		(net "P3V3_AUX")
	)
	(segment
		(start 131.866894 -128.516126)
		(end 132.476494 -128.516126)
		(width 0.381)
		(layer "F.Cu")
		(net "P3V3_AUX")
	)
	(segment
		(start 214.752682 -131.573524)
		(end 215.662256 -131.573524)
		(width 0.381)
		(layer "F.Cu")
		(net "P3V3_AUX")
	)
	(segment
		(start 141.561312 -368.14633)
		(end 141.66088 -368.245898)
		(width 0.381)
		(layer "F.Cu")
		(net "P3V3_AUX")
	)
	(segment
		(start 360.044492 -390.43737)
		(end 359.30586 -390.43737)
		(width 0.381)
		(layer "F.Cu")
		(net "P3V3_AUX")
	)
	(segment
		(start 431.751486 -101.97719)
		(end 431.751486 -102.61219)
		(width 0.4572)
		(layer "F.Cu")
		(net "P3V3_AUX")
	)
	(segment
		(start 103.563166 -393.711684)
		(end 103.53675 -393.685268)
		(width 0.381)
		(layer "F.Cu")
		(net "P3V3_AUX")
	)
	(segment
		(start 164.647626 -35.737546)
		(end 165.30066 -35.737546)
		(width 0.381)
		(layer "F.Cu")
		(net "P3V3_AUX")
	)
	(segment
		(start 116.610892 -110.236762)
		(end 116.610892 -109.487716)
		(width 0.381)
		(layer "F.Cu")
		(net "P3V3_AUX")
	)
	(segment
		(start 29.504132 -390.084818)
		(end 29.504132 -391.625582)
		(width 0.4572)
		(layer "F.Cu")
		(net "P3V3_AUX")
	)
	(segment
		(start 193.82613 -80.627728)
		(end 193.21018 -80.627728)
		(width 0.381)
		(layer "F.Cu")
		(net "P3V3_AUX")
	)
	(segment
		(start 132.55879 -115.585748)
		(end 132.55879 -116.255292)
		(width 0.381)
		(layer "F.Cu")
		(net "P3V3_AUX")
	)
	(segment
		(start 319.174622 -57.396888)
		(end 319.661032 -57.396888)
		(width 0.381)
		(layer "F.Cu")
		(net "P3V3_AUX")
	)
	(segment
		(start 300.56201 -319.716658)
		(end 301.343314 -319.716658)
		(width 0.381)
		(layer "F.Cu")
		(net "P3V3_AUX")
	)
	(segment
		(start 142.952216 -78.500478)
		(end 141.79296 -78.500478)
		(width 0.381)
		(layer "F.Cu")
		(net "P3V3_AUX")
	)
	(segment
		(start 109.737906 -31.445962)
		(end 109.737906 -31.49981)
		(width 0.381)
		(layer "F.Cu")
		(net "P3V3_AUX")
	)
	(segment
		(start 395.924278 -150.49246)
		(end 395.413738 -150.49246)
		(width 0.381)
		(layer "F.Cu")
		(net "P3V3_AUX")
	)
	(segment
		(start 20.113498 -389.234426)
		(end 19.945096 -389.066024)
		(width 0.1778)
		(layer "F.Cu")
		(net "P3V3_AUX")
	)
	(segment
		(start 461.993996 -105.011728)
		(end 462.60512 -105.011728)
		(width 0.381)
		(layer "F.Cu")
		(net "P3V3_AUX")
	)
	(segment
		(start 430.677066 -101.97719)
		(end 430.677066 -102.61219)
		(width 0.4572)
		(layer "F.Cu")
		(net "P3V3_AUX")
	)
	(segment
		(start 102.86619 -64.72301)
		(end 102.86619 -64.049148)
		(width 0.381)
		(layer "F.Cu")
		(net "P3V3_AUX")
	)
	(segment
		(start 310.50103 -49.494948)
		(end 309.95493 -49.494948)
		(width 0.381)
		(layer "F.Cu")
		(net "P3V3_AUX")
	)
	(segment
		(start 164.647626 -38.067234)
		(end 165.30066 -38.067234)
		(width 0.381)
		(layer "F.Cu")
		(net "P3V3_AUX")
	)
	(segment
		(start 115.759484 -38.065456)
		(end 115.149884 -38.065456)
		(width 0.3556)
		(layer "F.Cu")
		(net "P3V3_AUX")
	)
	(segment
		(start 432.390042 -391.505948)
		(end 432.999642 -391.505948)
		(width 0.381)
		(layer "F.Cu")
		(net "P3V3_AUX")
	)
	(segment
		(start 319.790572 -60.620148)
		(end 319.169796 -60.620148)
		(width 0.381)
		(layer "F.Cu")
		(net "P3V3_AUX")
	)
	(segment
		(start 104.746044 -393.711684)
		(end 103.563166 -393.711684)
		(width 0.381)
		(layer "F.Cu")
		(net "P3V3_AUX")
	)
	(segment
		(start 156.37129 -81.50352)
		(end 156.37129 -80.679798)
		(width 0.381)
		(layer "F.Cu")
		(net "P3V3_AUX")
	)
	(segment
		(start 213.19744 -29.174948)
		(end 211.99221 -27.969718)
		(width 0.381)
		(layer "F.Cu")
		(net "P3V3_AUX")
	)
	(segment
		(start 391.763758 -38.667182)
		(end 391.769854 -38.661086)
		(width 0.381)
		(layer "F.Cu")
		(net "P3V3_AUX")
	)
	(segment
		(start 438.282588 -122.648726)
		(end 437.643016 -122.648726)
		(width 0.381)
		(layer "F.Cu")
		(net "P3V3_AUX")
	)
	(segment
		(start 297.552364 -14.506194)
		(end 297.552364 -15.567914)
		(width 0.381)
		(layer "F.Cu")
		(net "P3V3_AUX")
	)
	(segment
		(start 209.070956 -29.876242)
		(end 209.070956 -29.266642)
		(width 0.381)
		(layer "F.Cu")
		(net "P3V3_AUX")
	)
	(segment
		(start 82.322924 -152.221692)
		(end 82.384138 -152.160478)
		(width 0.381)
		(layer "F.Cu")
		(net "P3V3_AUX")
	)
	(segment
		(start 277.21941 -93.741494)
		(end 276.18182 -93.741494)
		(width 0.381)
		(layer "F.Cu")
		(net "P3V3_AUX")
	)
	(segment
		(start 211.172044 -14.087094)
		(end 211.653882 -13.605256)
		(width 0.381)
		(layer "F.Cu")
		(net "P3V3_AUX")
	)
	(segment
		(start 288.34334 -95.748348)
		(end 287.765998 -96.32569)
		(width 0.381)
		(layer "F.Cu")
		(net "P3V3_AUX")
	)
	(segment
		(start 384.5306 -29.911548)
		(end 384.8608 -29.581348)
		(width 0.381)
		(layer "F.Cu")
		(net "P3V3_AUX")
	)
	(segment
		(start 204.59573 -112.02924)
		(end 203.99502 -112.02924)
		(width 0.381)
		(layer "F.Cu")
		(net "P3V3_AUX")
	)
	(segment
		(start 437.66486 -43.960288)
		(end 436.967376 -43.262804)
		(width 0.381)
		(layer "F.Cu")
		(net "P3V3_AUX")
	)
	(segment
		(start 8.40867 -76.232512)
		(end 7.920736 -75.744578)
		(width 0.381)
		(layer "F.Cu")
		(net "P3V3_AUX")
	)
	(segment
		(start 466.28304 -47.186088)
		(end 466.28304 -46.408848)
		(width 0.381)
		(layer "F.Cu")
		(net "P3V3_AUX")
	)
	(segment
		(start 429.384714 -319.716658)
		(end 428.279814 -319.716658)
		(width 0.381)
		(layer "F.Cu")
		(net "P3V3_AUX")
	)
	(segment
		(start 204.9526 -68.5292)
		(end 205.4352 -68.0466)
		(width 0.381)
		(layer "F.Cu")
		(net "P3V3_AUX")
	)
	(segment
		(start 400.345656 -66.641472)
		(end 404.045928 -66.641472)
		(width 0.508)
		(layer "F.Cu")
		(net "P3V3_AUX")
	)
	(segment
		(start 95.65894 -428.816008)
		(end 95.7072 -428.816008)
		(width 0.381)
		(layer "F.Cu")
		(net "P3V3_AUX")
	)
	(segment
		(start 166.80815 -421.835326)
		(end 166.17315 -421.835326)
		(width 0.381)
		(layer "F.Cu")
		(net "P3V3_AUX")
	)
	(segment
		(start 201.545698 -119.19966)
		(end 201.40041 -119.344948)
		(width 0.381)
		(layer "F.Cu")
		(net "P3V3_AUX")
	)
	(segment
		(start 99.724464 -64.741044)
		(end 99.724464 -64.049148)
		(width 0.381)
		(layer "F.Cu")
		(net "P3V3_AUX")
	)
	(segment
		(start 53.87848 -433.498498)
		(end 53.87848 -432.577748)
		(width 0.381)
		(layer "F.Cu")
		(net "P3V3_AUX")
	)
	(segment
		(start 452.886572 -76.007722)
		(end 452.886572 -76.639166)
		(width 0.381)
		(layer "F.Cu")
		(net "P3V3_AUX")
	)
	(segment
		(start 35.74923 -433.923948)
		(end 34.90468 -433.923948)
		(width 0.381)
		(layer "F.Cu")
		(net "P3V3_AUX")
	)
	(segment
		(start 107.65663 -60.086748)
		(end 107.614974 -60.128404)
		(width 0.381)
		(layer "F.Cu")
		(net "P3V3_AUX")
	)
	(segment
		(start 29.77388 -427.592998)
		(end 29.13888 -427.592998)
		(width 0.381)
		(layer "F.Cu")
		(net "P3V3_AUX")
	)
	(segment
		(start 369.529868 -387.779006)
		(end 370.224558 -387.779006)
		(width 0.381)
		(layer "F.Cu")
		(net "P3V3_AUX")
	)
	(segment
		(start 80.550766 -64.682624)
		(end 80.550766 -63.998348)
		(width 0.381)
		(layer "F.Cu")
		(net "P3V3_AUX")
	)
	(segment
		(start 105.973372 -74.593196)
		(end 105.973372 -73.983596)
		(width 0.381)
		(layer "F.Cu")
		(net "P3V3_AUX")
	)
	(segment
		(start 111.21136 -31.037784)
		(end 112.111536 -31.037784)
		(width 0.381)
		(layer "F.Cu")
		(net "P3V3_AUX")
	)
	(segment
		(start 112.892332 -405.18842)
		(end 111.764826 -404.060914)
		(width 0.381)
		(layer "F.Cu")
		(net "P3V3_AUX")
	)
	(segment
		(start 118.216934 -108.731812)
		(end 117.581934 -108.731812)
		(width 0.381)
		(layer "F.Cu")
		(net "P3V3_AUX")
	)
	(segment
		(start 305.690524 -426.179742)
		(end 305.080924 -426.179742)
		(width 0.381)
		(layer "F.Cu")
		(net "P3V3_AUX")
	)
	(segment
		(start 312.048144 -32.343344)
		(end 312.048144 -32.869886)
		(width 0.3302)
		(layer "F.Cu")
		(net "P3V3_AUX")
	)
	(segment
		(start 453.319896 -102.598728)
		(end 452.710296 -102.598728)
		(width 0.381)
		(layer "F.Cu")
		(net "P3V3_AUX")
	)
	(segment
		(start 160.311084 -81.51241)
		(end 160.311084 -80.713072)
		(width 0.381)
		(layer "F.Cu")
		(net "P3V3_AUX")
	)
	(segment
		(start 310.79313 -49.202848)
		(end 310.50103 -49.494948)
		(width 0.381)
		(layer "F.Cu")
		(net "P3V3_AUX")
	)
	(segment
		(start 127.44069 -156.365448)
		(end 128.05029 -156.365448)
		(width 0.381)
		(layer "F.Cu")
		(net "P3V3_AUX")
	)
	(segment
		(start 447.424556 -40.537638)
		(end 447.91249 -41.025572)
		(width 0.381)
		(layer "F.Cu")
		(net "P3V3_AUX")
	)
	(segment
		(start 117.366796 -108.731812)
		(end 117.581934 -108.731812)
		(width 0.381)
		(layer "F.Cu")
		(net "P3V3_AUX")
	)
	(segment
		(start 211.99221 -27.969718)
		(end 211.99221 -27.268424)
		(width 0.381)
		(layer "F.Cu")
		(net "P3V3_AUX")
	)
	(segment
		(start 51.193446 -106.74477)
		(end 50.583846 -106.74477)
		(width 0.381)
		(layer "F.Cu")
		(net "P3V3_AUX")
	)
	(segment
		(start 116.767356 -30.720792)
		(end 117.50548 -30.720792)
		(width 0.381)
		(layer "F.Cu")
		(net "P3V3_AUX")
	)
	(segment
		(start 131.32308 -122.942858)
		(end 131.95808 -122.942858)
		(width 0.381)
		(layer "F.Cu")
		(net "P3V3_AUX")
	)
	(segment
		(start 289.33775 -405.79802)
		(end 289.94735 -405.79802)
		(width 0.381)
		(layer "F.Cu")
		(net "P3V3_AUX")
	)
	(segment
		(start 110.932722 -139.133326)
		(end 110.323122 -139.133326)
		(width 0.381)
		(layer "F.Cu")
		(net "P3V3_AUX")
	)
	(segment
		(start 288.87801 -95.760794)
		(end 288.865564 -95.748348)
		(width 0.381)
		(layer "F.Cu")
		(net "P3V3_AUX")
	)
	(segment
		(start 371.36324 -60.48375)
		(end 371.807232 -60.927742)
		(width 0.381)
		(layer "F.Cu")
		(net "P3V3_AUX")
	)
	(segment
		(start 124.210572 -15.50543)
		(end 124.169932 -15.54607)
		(width 0.381)
		(layer "F.Cu")
		(net "P3V3_AUX")
	)
	(segment
		(start 110.932722 -137.854182)
		(end 110.323122 -137.854182)
		(width 0.381)
		(layer "F.Cu")
		(net "P3V3_AUX")
	)
	(segment
		(start 365.390938 -416.75304)
		(end 365.390938 -416.105848)
		(width 0.381)
		(layer "F.Cu")
		(net "P3V3_AUX")
	)
	(segment
		(start 277.24989 -96.329754)
		(end 276.18182 -96.329754)
		(width 0.381)
		(layer "F.Cu")
		(net "P3V3_AUX")
	)
	(segment
		(start 319.790572 -57.267348)
		(end 319.790572 -58.283348)
		(width 0.381)
		(layer "F.Cu")
		(net "P3V3_AUX")
	)
	(segment
		(start 391.5664 -31.186628)
		(end 391.965434 -31.585662)
		(width 0.381)
		(layer "F.Cu")
		(net "P3V3_AUX")
	)
	(segment
		(start 25.781 -407.5176)
		(end 26.6446 -408.3812)
		(width 0.381)
		(layer "F.Cu")
		(net "P3V3_AUX")
	)
	(segment
		(start 460.6798 -380.291848)
		(end 460.6798 -379.669548)
		(width 0.381)
		(layer "F.Cu")
		(net "P3V3_AUX")
	)
	(segment
		(start 175.4124 -93.138498)
		(end 175.4124 -92.527628)
		(width 0.381)
		(layer "F.Cu")
		(net "P3V3_AUX")
	)
	(segment
		(start 461.516476 -100.470208)
		(end 461.516476 -99.493832)
		(width 0.381)
		(layer "F.Cu")
		(net "P3V3_AUX")
	)
	(segment
		(start 356.28072 -406.450038)
		(end 356.28072 -405.8158)
		(width 0.381)
		(layer "F.Cu")
		(net "P3V3_AUX")
	)
	(segment
		(start 451.81774 -113.572798)
		(end 452.73468 -113.572798)
		(width 0.381)
		(layer "F.Cu")
		(net "P3V3_AUX")
	)
	(segment
		(start 194.31635 -119.344948)
		(end 193.78041 -119.344948)
		(width 0.381)
		(layer "F.Cu")
		(net "P3V3_AUX")
	)
	(segment
		(start 49.096422 -437.438038)
		(end 49.096422 -436.803038)
		(width 0.381)
		(layer "F.Cu")
		(net "P3V3_AUX")
	)
	(segment
		(start 112.892332 -407.074116)
		(end 112.892332 -406.439116)
		(width 0.381)
		(layer "F.Cu")
		(net "P3V3_AUX")
	)
	(segment
		(start 182.17388 -130.666998)
		(end 182.17388 -131.280408)
		(width 0.381)
		(layer "F.Cu")
		(net "P3V3_AUX")
	)
	(segment
		(start 180.735732 -418.849048)
		(end 180.735732 -419.496748)
		(width 0.381)
		(layer "F.Cu")
		(net "P3V3_AUX")
	)
	(segment
		(start 75.305412 -38.532562)
		(end 75.268074 -38.5699)
		(width 0.2286)
		(layer "F.Cu")
		(net "P3V3_AUX")
	)
	(segment
		(start 438.277 -95.957898)
		(end 438.9882 -95.957898)
		(width 0.381)
		(layer "F.Cu")
		(net "P3V3_AUX")
	)
	(segment
		(start 122.301 -74.621898)
		(end 121.66473 -74.621898)
		(width 0.381)
		(layer "F.Cu")
		(net "P3V3_AUX")
	)
	(segment
		(start 126.91872 -19.949668)
		(end 126.91872 -21.772118)
		(width 0.381)
		(layer "F.Cu")
		(net "P3V3_AUX")
	)
	(segment
		(start 368.598704 -355.352604)
		(end 368.978942 -355.352604)
		(width 0.381)
		(layer "F.Cu")
		(net "P3V3_AUX")
	)
	(segment
		(start 277.23465 -95.029274)
		(end 276.18182 -95.029274)
		(width 0.381)
		(layer "F.Cu")
		(net "P3V3_AUX")
	)
	(segment
		(start 168.56583 -437.606948)
		(end 168.56583 -436.971948)
		(width 0.381)
		(layer "F.Cu")
		(net "P3V3_AUX")
	)
	(segment
		(start 110.932722 -129.472182)
		(end 110.323122 -129.472182)
		(width 0.381)
		(layer "F.Cu")
		(net "P3V3_AUX")
	)
	(segment
		(start 213.19744 -29.846778)
		(end 213.19744 -29.174948)
		(width 0.381)
		(layer "F.Cu")
		(net "P3V3_AUX")
	)
	(segment
		(start 310.57088 -41.493948)
		(end 310.329072 -41.493948)
		(width 0.381)
		(layer "F.Cu")
		(net "P3V3_AUX")
	)
	(segment
		(start 119.249952 -409.113228)
		(end 119.249952 -408.269948)
		(width 0.381)
		(layer "F.Cu")
		(net "P3V3_AUX")
	)
	(segment
		(start 297.552364 -15.567914)
		(end 297.547284 -15.572994)
		(width 0.381)
		(layer "F.Cu")
		(net "P3V3_AUX")
	)
	(segment
		(start 194.00266 -431.424334)
		(end 194.00266 -432.317906)
		(width 0.381)
		(layer "F.Cu")
		(net "P3V3_AUX")
	)
	(segment
		(start 334.499458 -48.450246)
		(end 334.11287 -48.063658)
		(width 0.2032)
		(layer "F.Cu")
		(net "P3V3_AUX")
	)
	(segment
		(start 307.214016 -319.716658)
		(end 308.887114 -319.716658)
		(width 0.381)
		(layer "F.Cu")
		(net "P3V3_AUX")
	)
	(segment
		(start 51.193446 -118.93677)
		(end 50.583846 -118.93677)
		(width 0.381)
		(layer "F.Cu")
		(net "P3V3_AUX")
	)
	(segment
		(start 174.1424 -93.138498)
		(end 174.1424 -92.527628)
		(width 0.381)
		(layer "F.Cu")
		(net "P3V3_AUX")
	)
	(segment
		(start 51.193446 -108.14177)
		(end 50.583846 -108.14177)
		(width 0.381)
		(layer "F.Cu")
		(net "P3V3_AUX")
	)
	(segment
		(start 466.193886 -46.319694)
		(end 464.96351 -46.319694)
		(width 0.381)
		(layer "F.Cu")
		(net "P3V3_AUX")
	)
	(segment
		(start 103.704136 -41.570148)
		(end 103.704136 -40.935148)
		(width 0.381)
		(layer "F.Cu")
		(net "P3V3_AUX")
	)
	(segment
		(start 306.516024 -438.520586)
		(end 305.800506 -438.520586)
		(width 0.381)
		(layer "F.Cu")
		(net "P3V3_AUX")
	)
	(segment
		(start 148.696934 -32.929068)
		(end 149.41423 -32.929068)
		(width 0.381)
		(layer "F.Cu")
		(net "P3V3_AUX")
	)
	(segment
		(start 327.243948 -20.148296)
		(end 326.647302 -20.148296)
		(width 0.381)
		(layer "F.Cu")
		(net "P3V3_AUX")
	)
	(segment
		(start 438.277 -95.291148)
		(end 438.277 -95.957898)
		(width 0.381)
		(layer "F.Cu")
		(net "P3V3_AUX")
	)
	(segment
		(start 278.63165 -424.69562)
		(end 278.01443 -424.69562)
		(width 0.381)
		(layer "F.Cu")
		(net "P3V3_AUX")
	)
	(segment
		(start 461.193896 -107.678728)
		(end 461.193896 -107.043728)
		(width 0.381)
		(layer "F.Cu")
		(net "P3V3_AUX")
	)
	(segment
		(start 14.426946 -391.183876)
		(end 15.036546 -391.183876)
		(width 0.381)
		(layer "F.Cu")
		(net "P3V3_AUX")
	)
	(segment
		(start 179.05095 -20.411948)
		(end 178.816 -20.176998)
		(width 0.381)
		(layer "F.Cu")
		(net "P3V3_AUX")
	)
	(segment
		(start 156.249624 -68.850764)
		(end 155.98013 -69.120258)
		(width 0.381)
		(layer "F.Cu")
		(net "P3V3_AUX")
	)
	(segment
		(start 28.177998 -76.289916)
		(end 28.177998 -76.924916)
		(width 0.381)
		(layer "F.Cu")
		(net "P3V3_AUX")
	)
	(segment
		(start 63.975742 -114.801396)
		(end 64.615822 -114.801396)
		(width 0.381)
		(layer "F.Cu")
		(net "P3V3_AUX")
	)
	(segment
		(start 131.866894 -134.104126)
		(end 132.476494 -134.104126)
		(width 0.381)
		(layer "F.Cu")
		(net "P3V3_AUX")
	)
	(segment
		(start 300.1899 -320.088768)
		(end 300.56201 -319.716658)
		(width 0.381)
		(layer "F.Cu")
		(net "P3V3_AUX")
	)
	(segment
		(start 99.699318 -360.42981)
		(end 99.699318 -359.996232)
		(width 0.381)
		(layer "F.Cu")
		(net "P3V3_AUX")
	)
	(segment
		(start 363.62005 -415.889948)
		(end 363.62005 -415.249868)
		(width 0.381)
		(layer "F.Cu")
		(net "P3V3_AUX")
	)
	(segment
		(start 150.734522 -43.13809)
		(end 150.20417 -43.13809)
		(width 0.381)
		(layer "F.Cu")
		(net "P3V3_AUX")
	)
	(segment
		(start 198.12508 -112.124998)
		(end 197.41388 -112.124998)
		(width 0.381)
		(layer "F.Cu")
		(net "P3V3_AUX")
	)
	(segment
		(start 11.387582 -420.816786)
		(end 12.022582 -420.816786)
		(width 0.381)
		(layer "F.Cu")
		(net "P3V3_AUX")
	)
	(segment
		(start 74.615802 -74.501502)
		(end 74.615802 -73.828148)
		(width 0.381)
		(layer "F.Cu")
		(net "P3V3_AUX")
	)
	(segment
		(start 373.30888 -421.909748)
		(end 372.810278 -421.411146)
		(width 0.381)
		(layer "F.Cu")
		(net "P3V3_AUX")
	)
	(segment
		(start 449.38442 -78.229968)
		(end 448.478402 -78.229968)
		(width 0.381)
		(layer "F.Cu")
		(net "P3V3_AUX")
	)
	(segment
		(start 104.591866 -230.622602)
		(end 104.591612 -230.622348)
		(width 0.2032)
		(layer "F.Cu")
		(net "P3V3_AUX")
	)
	(segment
		(start 458.668882 -103.614728)
		(end 458.637386 -103.646224)
		(width 0.381)
		(layer "F.Cu")
		(net "P3V3_AUX")
	)
	(segment
		(start 332.253336 -17.414748)
		(end 331.624686 -17.414748)
		(width 0.381)
		(layer "F.Cu")
		(net "P3V3_AUX")
	)
	(segment
		(start 127.23495 -58.003948)
		(end 127.23495 -58.740548)
		(width 0.381)
		(layer "F.Cu")
		(net "P3V3_AUX")
	)
	(segment
		(start 263.624314 -319.716658)
		(end 262.519414 -319.716658)
		(width 0.381)
		(layer "F.Cu")
		(net "P3V3_AUX")
	)
	(segment
		(start 216.875868 -68.340478)
		(end 217.481912 -68.340478)
		(width 0.4572)
		(layer "F.Cu")
		(net "P3V3_AUX")
	)
	(segment
		(start 371.807232 -60.927742)
		(end 371.807232 -61.581792)
		(width 0.381)
		(layer "F.Cu")
		(net "P3V3_AUX")
	)
	(segment
		(start 210.4644 -15.425674)
		(end 210.997546 -14.892528)
		(width 0.381)
		(layer "F.Cu")
		(net "P3V3_AUX")
	)
	(segment
		(start 108.45038 -401.184364)
		(end 107.84078 -401.184364)
		(width 0.381)
		(layer "F.Cu")
		(net "P3V3_AUX")
	)
	(segment
		(start 293.548562 -19.787362)
		(end 293.548562 -18.714466)
		(width 0.381)
		(layer "F.Cu")
		(net "P3V3_AUX")
	)
	(segment
		(start 351.592134 -230.622602)
		(end 351.59188 -230.622348)
		(width 0.2032)
		(layer "F.Cu")
		(net "P3V3_AUX")
	)
	(segment
		(start 194.39509 -119.266208)
		(end 194.31635 -119.344948)
		(width 0.381)
		(layer "F.Cu")
		(net "P3V3_AUX")
	)
	(segment
		(start 447.110104 -117.221762)
		(end 447.082164 -117.193822)
		(width 0.381)
		(layer "F.Cu")
		(net "P3V3_AUX")
	)
	(segment
		(start 82.702654 -40.623744)
		(end 83.50504 -40.623744)
		(width 0.381)
		(layer "F.Cu")
		(net "P3V3_AUX")
	)
	(segment
		(start 374.275858 -421.925496)
		(end 374.26011 -421.909748)
		(width 0.381)
		(layer "F.Cu")
		(net "P3V3_AUX")
	)
	(segment
		(start 28.028646 -388.262876)
		(end 28.638246 -388.262876)
		(width 0.381)
		(layer "F.Cu")
		(net "P3V3_AUX")
	)
	(segment
		(start 122.236484 -39.388796)
		(end 121.503186 -38.655498)
		(width 0.381)
		(layer "F.Cu")
		(net "P3V3_AUX")
	)
	(segment
		(start 445.557148 -92.468192)
		(end 446.2272 -92.468192)
		(width 0.381)
		(layer "F.Cu")
		(net "P3V3_AUX")
	)
	(segment
		(start 432.390042 -386.171948)
		(end 432.999642 -386.171948)
		(width 0.381)
		(layer "F.Cu")
		(net "P3V3_AUX")
	)
	(segment
		(start 214.019384 -13.90396)
		(end 214.019384 -14.845792)
		(width 0.381)
		(layer "F.Cu")
		(net "P3V3_AUX")
	)
	(segment
		(start 65.20053 -115.386104)
		(end 65.20053 -116.488718)
		(width 0.381)
		(layer "F.Cu")
		(net "P3V3_AUX")
	)
	(segment
		(start 116.610892 -109.487716)
		(end 117.366796 -108.731812)
		(width 0.381)
		(layer "F.Cu")
		(net "P3V3_AUX")
	)
	(segment
		(start 20.113498 -389.425942)
		(end 20.113498 -389.234426)
		(width 0.1778)
		(layer "F.Cu")
		(net "P3V3_AUX")
	)
	(segment
		(start 381.8763 -98.004122)
		(end 381.229616 -98.004122)
		(width 0.381)
		(layer "F.Cu")
		(net "P3V3_AUX")
	)
	(segment
		(start 194.00393 -108.765848)
		(end 194.61353 -108.765848)
		(width 0.381)
		(layer "F.Cu")
		(net "P3V3_AUX")
	)
	(segment
		(start 189.28588 -131.280408)
		(end 189.28588 -130.666998)
		(width 0.381)
		(layer "F.Cu")
		(net "P3V3_AUX")
	)
	(segment
		(start 179.2224 -93.138498)
		(end 179.2224 -92.527628)
		(width 0.381)
		(layer "F.Cu")
		(net "P3V3_AUX")
	)
	(segment
		(start 38.315646 -319.716658)
		(end 37.210746 -319.716658)
		(width 0.381)
		(layer "F.Cu")
		(net "P3V3_AUX")
	)
	(segment
		(start 162.74288 -77.862938)
		(end 163.5252 -77.862938)
		(width 0.381)
		(layer "F.Cu")
		(net "P3V3_AUX")
	)
	(segment
		(start 103.519478 -420.44874)
		(end 103.286306 -420.215568)
		(width 0.381)
		(layer "F.Cu")
		(net "P3V3_AUX")
	)
	(segment
		(start 38.505892 -128.72974)
		(end 38.72738 -128.508252)
		(width 0.381)
		(layer "F.Cu")
		(net "P3V3_AUX")
	)
	(segment
		(start 165.252146 -319.716658)
		(end 166.357046 -319.716658)
		(width 0.381)
		(layer "F.Cu")
		(net "P3V3_AUX")
	)
	(segment
		(start 371.73154 -68.275962)
		(end 371.176804 -67.721226)
		(width 0.381)
		(layer "F.Cu")
		(net "P3V3_AUX")
	)
	(segment
		(start 96.150938 -417.36772)
		(end 96.150938 -416.491928)
		(width 0.381)
		(layer "F.Cu")
		(net "P3V3_AUX")
	)
	(segment
		(start 154.69616 -80.589628)
		(end 154.34945 -80.936338)
		(width 0.381)
		(layer "F.Cu")
		(net "P3V3_AUX")
	)
	(segment
		(start 158.0642 -64.761364)
		(end 156.692346 -64.761364)
		(width 0.381)
		(layer "F.Cu")
		(net "P3V3_AUX")
	)
	(segment
		(start 450.3801 -113.307368)
		(end 450.72808 -113.655348)
		(width 0.381)
		(layer "F.Cu")
		(net "P3V3_AUX")
	)
	(segment
		(start 93.295724 -64.823594)
		(end 93.295724 -64.213994)
		(width 0.381)
		(layer "F.Cu")
		(net "P3V3_AUX")
	)
	(segment
		(start 435.25948 -319.662048)
		(end 435.31409 -319.716658)
		(width 0.381)
		(layer "F.Cu")
		(net "P3V3_AUX")
	)
	(segment
		(start 80.381602 -74.501502)
		(end 80.381602 -73.828148)
		(width 0.381)
		(layer "F.Cu")
		(net "P3V3_AUX")
	)
	(segment
		(start 319.149476 -61.766958)
		(end 319.247266 -61.864748)
		(width 0.381)
		(layer "F.Cu")
		(net "P3V3_AUX")
	)
	(segment
		(start 413.120332 -32.925258)
		(end 412.465774 -32.925258)
		(width 0.3556)
		(layer "F.Cu")
		(net "P3V3_AUX")
	)
	(segment
		(start 25.903682 -131.5974)
		(end 25.948132 -131.55295)
		(width 0.381)
		(layer "F.Cu")
		(net "P3V3_AUX")
	)
	(segment
		(start 13.259054 -420.816786)
		(end 13.640054 -420.435786)
		(width 0.381)
		(layer "F.Cu")
		(net "P3V3_AUX")
	)
	(segment
		(start 272.691606 -129.44983)
		(end 272.654776 -129.48666)
		(width 0.381)
		(layer "F.Cu")
		(net "P3V3_AUX")
	)
	(segment
		(start 82.706718 -19.542252)
		(end 82.071718 -19.542252)
		(width 0.4572)
		(layer "F.Cu")
		(net "P3V3_AUX")
	)
	(segment
		(start 77.381354 -64.682624)
		(end 77.381354 -63.998348)
		(width 0.381)
		(layer "F.Cu")
		(net "P3V3_AUX")
	)
	(segment
		(start 209.959956 -37.369242)
		(end 210.594956 -37.369242)
		(width 0.381)
		(layer "F.Cu")
		(net "P3V3_AUX")
	)
	(segment
		(start 391.965434 -31.585662)
		(end 392.119866 -31.585662)
		(width 0.381)
		(layer "F.Cu")
		(net "P3V3_AUX")
	)
	(segment
		(start 261.598918 -92.097606)
		(end 260.593332 -92.097606)
		(width 0.381)
		(layer "F.Cu")
		(net "P3V3_AUX")
	)
	(segment
		(start 321.695572 -59.299348)
		(end 321.695572 -60.208668)
		(width 0.381)
		(layer "F.Cu")
		(net "P3V3_AUX")
	)
	(segment
		(start 190.20028 -35.017456)
		(end 190.80988 -35.017456)
		(width 0.381)
		(layer "F.Cu")
		(net "P3V3_AUX")
	)
	(segment
		(start 301.45482 -421.01516)
		(end 301.45482 -420.276528)
		(width 0.381)
		(layer "F.Cu")
		(net "P3V3_AUX")
	)
	(segment
		(start 148.468334 -33.157668)
		(end 148.696934 -32.929068)
		(width 0.381)
		(layer "F.Cu")
		(net "P3V3_AUX")
	)
	(segment
		(start 457.25842 -39.588948)
		(end 456.379072 -39.588948)
		(width 0.381)
		(layer "F.Cu")
		(net "P3V3_AUX")
	)
	(segment
		(start 156.053536 -30.941518)
		(end 156.053536 -30.312868)
		(width 0.381)
		(layer "F.Cu")
		(net "P3V3_AUX")
	)
	(segment
		(start 319.790572 -56.251348)
		(end 319.790572 -55.235348)
		(width 0.381)
		(layer "F.Cu")
		(net "P3V3_AUX")
	)
	(segment
		(start 466.223604 -115.295934)
		(end 466.948266 -115.295934)
		(width 0.381)
		(layer "F.Cu")
		(net "P3V3_AUX")
	)
	(segment
		(start 449.01993 -94.602808)
		(end 449.65112 -94.602808)
		(width 0.381)
		(layer "F.Cu")
		(net "P3V3_AUX")
	)
	(segment
		(start 277.743412 -424.424602)
		(end 277.93315 -424.61434)
		(width 0.381)
		(layer "F.Cu")
		(net "P3V3_AUX")
	)
	(segment
		(start 439.320686 -46.590458)
		(end 439.320686 -46.033436)
		(width 0.381)
		(layer "F.Cu")
		(net "P3V3_AUX")
	)
	(segment
		(start 306.83454 -432.65725)
		(end 306.83454 -431.918618)
		(width 0.381)
		(layer "F.Cu")
		(net "P3V3_AUX")
	)
	(segment
		(start 449.52666 -51.976528)
		(end 450.441568 -51.976528)
		(width 0.508)
		(layer "F.Cu")
		(net "P3V3_AUX")
	)
	(segment
		(start 309.9054 -23.7744)
		(end 310.4134 -23.2664)
		(width 0.381)
		(layer "F.Cu")
		(net "P3V3_AUX")
	)
	(segment
		(start 23.241 -398.035526)
		(end 23.241 -397.425926)
		(width 0.381)
		(layer "F.Cu")
		(net "P3V3_AUX")
	)
	(segment
		(start 277.630636 -17.678908)
		(end 276.173184 -17.678908)
		(width 0.381)
		(layer "F.Cu")
		(net "P3V3_AUX")
	)
	(segment
		(start 140.296646 -33.477708)
		(end 140.30833 -33.466024)
		(width 0.381)
		(layer "F.Cu")
		(net "P3V3_AUX")
	)
	(segment
		(start 140.39088 -41.855898)
		(end 140.375386 -41.840404)
		(width 0.381)
		(layer "F.Cu")
		(net "P3V3_AUX")
	)
	(segment
		(start 131.866894 -129.913126)
		(end 132.476494 -129.913126)
		(width 0.381)
		(layer "F.Cu")
		(net "P3V3_AUX")
	)
	(segment
		(start 175.0568 -418.806122)
		(end 175.680878 -418.806122)
		(width 0.381)
		(layer "F.Cu")
		(net "P3V3_AUX")
	)
	(segment
		(start 429.299116 -110.273084)
		(end 429.299116 -109.66704)
		(width 0.4572)
		(layer "F.Cu")
		(net "P3V3_AUX")
	)
	(segment
		(start 308.908704 -14.412468)
		(end 308.908704 -13.68044)
		(width 0.381)
		(layer "F.Cu")
		(net "P3V3_AUX")
	)
	(segment
		(start 292.688518 -413.05988)
		(end 292.673278 -413.07512)
		(width 0.381)
		(layer "F.Cu")
		(net "P3V3_AUX")
	)
	(segment
		(start 110.932722 -133.663182)
		(end 110.323122 -133.663182)
		(width 0.381)
		(layer "F.Cu")
		(net "P3V3_AUX")
	)
	(segment
		(start 19.790664 -107.777026)
		(end 19.181064 -107.777026)
		(width 0.3556)
		(layer "F.Cu")
		(net "P3V3_AUX")
	)
	(segment
		(start 304.901346 -27.1018)
		(end 300.863 -27.1018)
		(width 0.381)
		(layer "F.Cu")
		(net "P3V3_AUX")
	)
	(segment
		(start 15.067788 -92.287598)
		(end 15.067788 -91.618308)
		(width 0.381)
		(layer "F.Cu")
		(net "P3V3_AUX")
	)
	(segment
		(start 292.636448 -17.747234)
		(end 293.130478 -17.253204)
		(width 0.381)
		(layer "F.Cu")
		(net "P3V3_AUX")
	)
	(segment
		(start 215.60028 -41.360598)
		(end 215.60028 -42.078148)
		(width 0.381)
		(layer "F.Cu")
		(net "P3V3_AUX")
	)
	(segment
		(start 309.57774 -432.72456)
		(end 309.57774 -431.985928)
		(width 0.381)
		(layer "F.Cu")
		(net "P3V3_AUX")
	)
	(segment
		(start 21.072094 -166.906194)
		(end 21.211032 -166.767256)
		(width 0.381)
		(layer "F.Cu")
		(net "P3V3_AUX")
	)
	(segment
		(start 302.895 -421.0939)
		(end 302.895 -420.355268)
		(width 0.381)
		(layer "F.Cu")
		(net "P3V3_AUX")
	)
	(segment
		(start 210.185 -120.8278)
		(end 210.555586 -120.457214)
		(width 0.381)
		(layer "F.Cu")
		(net "P3V3_AUX")
	)
	(segment
		(start 100.2665 -359.42905)
		(end 100.2665 -359.059226)
		(width 0.381)
		(layer "F.Cu")
		(net "P3V3_AUX")
	)
	(segment
		(start 219.09405 -95.97898)
		(end 218.574874 -95.459804)
		(width 0.381)
		(layer "F.Cu")
		(net "P3V3_AUX")
	)
	(segment
		(start 204.733398 -68.5292)
		(end 204.9526 -68.5292)
		(width 0.381)
		(layer "F.Cu")
		(net "P3V3_AUX")
	)
	(segment
		(start 20.20951 -72.710548)
		(end 19.59991 -72.710548)
		(width 0.381)
		(layer "F.Cu")
		(net "P3V3_AUX")
	)
	(segment
		(start 35.977068 -437.842406)
		(end 36.358068 -438.223406)
		(width 0.381)
		(layer "F.Cu")
		(net "P3V3_AUX")
	)
	(segment
		(start 193.033142 -79.057246)
		(end 193.946272 -79.057246)
		(width 0.381)
		(layer "F.Cu")
		(net "P3V3_AUX")
	)
	(segment
		(start 219.09405 -96.103948)
		(end 219.09405 -95.97898)
		(width 0.381)
		(layer "F.Cu")
		(net "P3V3_AUX")
	)
	(segment
		(start 468.89289 -43.735498)
		(end 469.50249 -43.735498)
		(width 0.381)
		(layer "F.Cu")
		(net "P3V3_AUX")
	)
	(segment
		(start 392.10488 -148.408898)
		(end 392.10488 -147.792948)
		(width 0.381)
		(layer "F.Cu")
		(net "P3V3_AUX")
	)
	(segment
		(start 459.559914 -319.716658)
		(end 458.455014 -319.716658)
		(width 0.381)
		(layer "F.Cu")
		(net "P3V3_AUX")
	)
	(segment
		(start 32.291782 -416.016948)
		(end 32.901382 -416.016948)
		(width 0.381)
		(layer "F.Cu")
		(net "P3V3_AUX")
	)
	(segment
		(start 358.3686 -412.0388)
		(end 358.3686 -412.6992)
		(width 0.381)
		(layer "F.Cu")
		(net "P3V3_AUX")
	)
	(segment
		(start 319.668906 -26.251408)
		(end 319.668906 -25.6286)
		(width 0.381)
		(layer "F.Cu")
		(net "P3V3_AUX")
	)
	(segment
		(start 123.708668 -137.546588)
		(end 124.450348 -137.546588)
		(width 0.381)
		(layer "F.Cu")
		(net "P3V3_AUX")
	)
	(segment
		(start 103.704136 -40.935148)
		(end 103.158036 -40.935148)
		(width 0.381)
		(layer "F.Cu")
		(net "P3V3_AUX")
	)
	(segment
		(start 380.002034 -98.004122)
		(end 379.618494 -97.620582)
		(width 0.381)
		(layer "F.Cu")
		(net "P3V3_AUX")
	)
	(segment
		(start 327.45934 -20.363688)
		(end 327.243948 -20.148296)
		(width 0.381)
		(layer "F.Cu")
		(net "P3V3_AUX")
	)
	(segment
		(start 360.082592 -392.04265)
		(end 359.34396 -392.04265)
		(width 0.381)
		(layer "F.Cu")
		(net "P3V3_AUX")
	)
	(segment
		(start 272.654776 -129.48666)
		(end 270.843248 -129.48666)
		(width 0.381)
		(layer "F.Cu")
		(net "P3V3_AUX")
	)
	(segment
		(start 23.713694 -391.92581)
		(end 23.993602 -392.60145)
		(width 0.1778)
		(layer "F.Cu")
		(net "P3V3_AUX")
	)
	(segment
		(start 82.4738 -41.220898)
		(end 82.28965 -41.036748)
		(width 0.381)
		(layer "F.Cu")
		(net "P3V3_AUX")
	)
	(segment
		(start 261.600188 -90.67546)
		(end 261.600188 -92.098876)
		(width 0.381)
		(layer "F.Cu")
		(net "P3V3_AUX")
	)
	(segment
		(start 305.174142 -27.997658)
		(end 305.2318 -27.94)
		(width 0.381)
		(layer "F.Cu")
		(net "P3V3_AUX")
	)
	(segment
		(start 53.403246 -319.716658)
		(end 52.298346 -319.716658)
		(width 0.381)
		(layer "F.Cu")
		(net "P3V3_AUX")
	)
	(segment
		(start 406.524714 -367.576862)
		(end 406.524714 -366.437926)
		(width 0.381)
		(layer "F.Cu")
		(net "P3V3_AUX")
	)
	(segment
		(start 40.389556 -400.776694)
		(end 39.990014 -401.176236)
		(width 0.4572)
		(layer "F.Cu")
		(net "P3V3_AUX")
	)
	(segment
		(start 143.94942 -76.451968)
		(end 143.919956 -76.481432)
		(width 0.381)
		(layer "F.Cu")
		(net "P3V3_AUX")
	)
	(segment
		(start 133.81355 -124.234448)
		(end 133.20395 -124.234448)
		(width 0.381)
		(layer "F.Cu")
		(net "P3V3_AUX")
	)
	(segment
		(start 140.840206 -64.313308)
		(end 140.230606 -64.313308)
		(width 0.381)
		(layer "F.Cu")
		(net "P3V3_AUX")
	)
	(segment
		(start 197.41388 -112.124998)
		(end 196.899784 -112.124998)
		(width 0.381)
		(layer "F.Cu")
		(net "P3V3_AUX")
	)
	(segment
		(start 332.18374 -14.635734)
		(end 331.798676 -14.635734)
		(width 0.381)
		(layer "F.Cu")
		(net "P3V3_AUX")
	)
	(segment
		(start 177.18532 -426.07484)
		(end 176.829212 -426.430948)
		(width 0.381)
		(layer "F.Cu")
		(net "P3V3_AUX")
	)
	(segment
		(start 423.804842 -379.313948)
		(end 423.195242 -379.313948)
		(width 0.381)
		(layer "F.Cu")
		(net "P3V3_AUX")
	)
	(segment
		(start 176.459388 -415.713418)
		(end 177.068988 -415.713418)
		(width 0.381)
		(layer "F.Cu")
		(net "P3V3_AUX")
	)
	(segment
		(start 127.77216 -73.133712)
		(end 128.009396 -73.370948)
		(width 0.381)
		(layer "F.Cu")
		(net "P3V3_AUX")
	)
	(segment
		(start 202.971146 -319.716658)
		(end 204.076046 -319.716658)
		(width 0.381)
		(layer "F.Cu")
		(net "P3V3_AUX")
	)
	(segment
		(start 297.480228 -388.349998)
		(end 297.480228 -387.143498)
		(width 0.4572)
		(layer "F.Cu")
		(net "P3V3_AUX")
	)
	(segment
		(start 278.039576 -17.269968)
		(end 277.630636 -17.678908)
		(width 0.381)
		(layer "F.Cu")
		(net "P3V3_AUX")
	)
	(segment
		(start 445.557148 -93.484192)
		(end 446.2272 -93.484192)
		(width 0.381)
		(layer "F.Cu")
		(net "P3V3_AUX")
	)
	(segment
		(start 121.384314 -355.69779)
		(end 120.645682 -355.69779)
		(width 0.381)
		(layer "F.Cu")
		(net "P3V3_AUX")
	)
	(segment
		(start 369.23853 -103.466138)
		(end 368.75212 -103.466138)
		(width 0.381)
		(layer "F.Cu")
		(net "P3V3_AUX")
	)
	(segment
		(start 440.653678 -46.95571)
		(end 439.685938 -46.95571)
		(width 0.381)
		(layer "F.Cu")
		(net "P3V3_AUX")
	)
	(segment
		(start 254.381 -37.686996)
		(end 254.40005 -37.667946)
		(width 0.381)
		(layer "F.Cu")
		(net "P3V3_AUX")
	)
	(segment
		(start 291.502846 -409.750006)
		(end 290.91509 -409.750006)
		(width 0.381)
		(layer "F.Cu")
		(net "P3V3_AUX")
	)
	(segment
		(start 114.660172 -19.30019)
		(end 114.660172 -18.456656)
		(width 0.381)
		(layer "F.Cu")
		(net "P3V3_AUX")
	)
	(segment
		(start 447.110104 -118.336822)
		(end 447.110104 -117.221762)
		(width 0.381)
		(layer "F.Cu")
		(net "P3V3_AUX")
	)
	(segment
		(start 70.75805 -113.521998)
		(end 70.75805 -113.756948)
		(width 0.381)
		(layer "F.Cu")
		(net "P3V3_AUX")
	)
	(segment
		(start 210.160108 -104.96804)
		(end 209.54492 -104.96804)
		(width 0.381)
		(layer "F.Cu")
		(net "P3V3_AUX")
	)
	(segment
		(start 146.081496 -65.351914)
		(end 146.081496 -66.648838)
		(width 0.381)
		(layer "F.Cu")
		(net "P3V3_AUX")
	)
	(segment
		(start 369.41506 -409.6512)
		(end 368.681 -409.6512)
		(width 0.381)
		(layer "F.Cu")
		(net "P3V3_AUX")
	)
	(segment
		(start 163.10483 -436.463948)
		(end 162.49523 -436.463948)
		(width 0.381)
		(layer "F.Cu")
		(net "P3V3_AUX")
	)
	(segment
		(start 465.443316 -101.56698)
		(end 465.443316 -101.39299)
		(width 0.381)
		(layer "F.Cu")
		(net "P3V3_AUX")
	)
	(segment
		(start 160.43783 -117.566948)
		(end 159.82188 -117.566948)
		(width 0.381)
		(layer "F.Cu")
		(net "P3V3_AUX")
	)
	(segment
		(start 149.41423 -32.929068)
		(end 149.41423 -33.564068)
		(width 0.381)
		(layer "F.Cu")
		(net "P3V3_AUX")
	)
	(segment
		(start 267.38707 -93.483938)
		(end 267.38707 -93.03258)
		(width 0.381)
		(layer "F.Cu")
		(net "P3V3_AUX")
	)
	(segment
		(start 342.803734 -26.466292)
		(end 342.803734 -27.088338)
		(width 0.381)
		(layer "F.Cu")
		(net "P3V3_AUX")
	)
	(segment
		(start 341.651082 -23.318978)
		(end 341.651082 -23.817072)
		(width 0.381)
		(layer "F.Cu")
		(net "P3V3_AUX")
	)
	(segment
		(start 295.86682 -421.01516)
		(end 295.86682 -420.276528)
		(width 0.381)
		(layer "F.Cu")
		(net "P3V3_AUX")
	)
	(segment
		(start 300.863 -27.1018)
		(end 293.548562 -19.787362)
		(width 0.381)
		(layer "F.Cu")
		(net "P3V3_AUX")
	)
	(segment
		(start 195.427346 -319.716658)
		(end 196.532246 -319.716658)
		(width 0.381)
		(layer "F.Cu")
		(net "P3V3_AUX")
	)
	(segment
		(start 155.253436 -51.56835)
		(end 155.290774 -51.531012)
		(width 0.2286)
		(layer "F.Cu")
		(net "P3V3_AUX")
	)
	(segment
		(start 224.220532 -232.027476)
		(end 224.220532 -231.488488)
		(width 0.381)
		(layer "F.Cu")
		(net "P3V3_AUX")
	)
	(segment
		(start 277.230078 -416.88385)
		(end 276.69363 -416.88385)
		(width 0.381)
		(layer "F.Cu")
		(net "P3V3_AUX")
	)
	(segment
		(start 154.65933 -69.86397)
		(end 155.98013 -69.86397)
		(width 0.381)
		(layer "F.Cu")
		(net "P3V3_AUX")
	)
	(segment
		(start 371.73154 -68.930012)
		(end 371.73154 -68.275962)
		(width 0.381)
		(layer "F.Cu")
		(net "P3V3_AUX")
	)
	(segment
		(start 365.96955 -408.1272)
		(end 365.3282 -408.1272)
		(width 0.381)
		(layer "F.Cu")
		(net "P3V3_AUX")
	)
	(segment
		(start 49.096422 -436.405528)
		(end 48.391318 -435.700424)
		(width 0.381)
		(layer "F.Cu")
		(net "P3V3_AUX")
	)
	(segment
		(start 14.689582 -424.029886)
		(end 14.689582 -424.639486)
		(width 0.381)
		(layer "F.Cu")
		(net "P3V3_AUX")
	)
	(segment
		(start 118.09222 -419.520878)
		(end 118.88216 -419.520878)
		(width 0.381)
		(layer "F.Cu")
		(net "P3V3_AUX")
	)
	(segment
		(start 185.59272 -417.66871)
		(end 185.59272 -417.37788)
		(width 0.381)
		(layer "F.Cu")
		(net "P3V3_AUX")
	)
	(segment
		(start 369.358418 -416.77336)
		(end 369.358418 -416.128708)
		(width 0.381)
		(layer "F.Cu")
		(net "P3V3_AUX")
	)
	(segment
		(start 107.13085 -410.6164)
		(end 107.8992 -410.6164)
		(width 0.381)
		(layer "F.Cu")
		(net "P3V3_AUX")
	)
	(segment
		(start 110.57636 -31.037784)
		(end 110.146084 -31.037784)
		(width 0.381)
		(layer "F.Cu")
		(net "P3V3_AUX")
	)
	(segment
		(start 70.228714 -64.682624)
		(end 70.228714 -63.998348)
		(width 0.381)
		(layer "F.Cu")
		(net "P3V3_AUX")
	)
	(segment
		(start 267.92428 -94.021148)
		(end 267.38707 -93.483938)
		(width 0.381)
		(layer "F.Cu")
		(net "P3V3_AUX")
	)
	(segment
		(start 16.110966 -92.287598)
		(end 16.110966 -91.618308)
		(width 0.381)
		(layer "F.Cu")
		(net "P3V3_AUX")
	)
	(segment
		(start 118.804944 -75.431142)
		(end 118.804944 -76.798932)
		(width 0.254)
		(layer "F.Cu")
		(net "P3V3_AUX")
	)
	(segment
		(start 288.865564 -95.748348)
		(end 288.34334 -95.748348)
		(width 0.381)
		(layer "F.Cu")
		(net "P3V3_AUX")
	)
	(segment
		(start 189.28588 -130.666998)
		(end 186.74588 -130.666998)
		(width 0.381)
		(layer "F.Cu")
		(net "P3V3_AUX")
	)
	(segment
		(start 158.138368 -30.941518)
		(end 159.181546 -30.941518)
		(width 0.381)
		(layer "F.Cu")
		(net "P3V3_AUX")
	)
	(segment
		(start 39.26332 -400.553936)
		(end 40.389556 -400.553936)
		(width 0.4572)
		(layer "F.Cu")
		(net "P3V3_AUX")
	)
	(segment
		(start 262.45439 -89.821258)
		(end 261.600188 -90.67546)
		(width 0.381)
		(layer "F.Cu")
		(net "P3V3_AUX")
	)
	(segment
		(start 307.55082 -425.186602)
		(end 307.574188 -425.163234)
		(width 0.381)
		(layer "F.Cu")
		(net "P3V3_AUX")
	)
	(segment
		(start 12.982956 -92.287598)
		(end 12.982956 -91.658948)
		(width 0.381)
		(layer "F.Cu")
		(net "P3V3_AUX")
	)
	(segment
		(start 319.678812 -62.992508)
		(end 319.790572 -62.880748)
		(width 0.381)
		(layer "F.Cu")
		(net "P3V3_AUX")
	)
	(segment
		(start 217.72753 -131.973828)
		(end 217.72753 -132.629148)
		(width 0.381)
		(layer "F.Cu")
		(net "P3V3_AUX")
	)
	(segment
		(start 374.03151 -413.518858)
		(end 374.03151 -412.40329)
		(width 0.381)
		(layer "F.Cu")
		(net "P3V3_AUX")
	)
	(segment
		(start 235.413042 -245.002558)
		(end 235.413042 -244.368828)
		(width 0.381)
		(layer "F.Cu")
		(net "P3V3_AUX")
	)
	(segment
		(start 293.82466 -92.260674)
		(end 293.02837 -92.260674)
		(width 0.381)
		(layer "F.Cu")
		(net "P3V3_AUX")
	)
	(segment
		(start 255.991614 -319.805558)
		(end 256.080514 -319.716658)
		(width 0.381)
		(layer "F.Cu")
		(net "P3V3_AUX")
	)
	(segment
		(start 333.508858 -51.739546)
		(end 333.23657 -51.269646)
		(width 0.2032)
		(layer "F.Cu")
		(net "P3V3_AUX")
	)
	(segment
		(start 124.724922 -137.821162)
		(end 124.724922 -139.178538)
		(width 0.381)
		(layer "F.Cu")
		(net "P3V3_AUX")
	)
	(segment
		(start 60.947046 -319.716658)
		(end 59.842146 -319.716658)
		(width 0.381)
		(layer "F.Cu")
		(net "P3V3_AUX")
	)
	(segment
		(start 369.628928 -394.647166)
		(end 370.323618 -394.647166)
		(width 0.381)
		(layer "F.Cu")
		(net "P3V3_AUX")
	)
	(segment
		(start 308.33314 -432.72456)
		(end 308.33314 -431.985928)
		(width 0.381)
		(layer "F.Cu")
		(net "P3V3_AUX")
	)
	(segment
		(start 49.724564 -394.44676)
		(end 49.724564 -394.765276)
		(width 0.4572)
		(layer "F.Cu")
		(net "P3V3_AUX")
	)
	(segment
		(start 37.965888 -128.72974)
		(end 38.505892 -128.72974)
		(width 0.381)
		(layer "F.Cu")
		(net "P3V3_AUX")
	)
	(segment
		(start 316.353444 -51.562)
		(end 316.353444 -51.450748)
		(width 0.3048)
		(layer "F.Cu")
		(net "P3V3_AUX")
	)
	(segment
		(start 107.614974 -60.128404)
		(end 105.931208 -60.128404)
		(width 0.381)
		(layer "F.Cu")
		(net "P3V3_AUX")
	)
	(segment
		(start 23.228046 -319.716658)
		(end 22.123146 -319.716658)
		(width 0.381)
		(layer "F.Cu")
		(net "P3V3_AUX")
	)
	(segment
		(start 423.804842 -381.345948)
		(end 423.195242 -381.345948)
		(width 0.3556)
		(layer "F.Cu")
		(net "P3V3_AUX")
	)
	(segment
		(start 21.73351 -167.783256)
		(end 21.73351 -166.767256)
		(width 0.381)
		(layer "F.Cu")
		(net "P3V3_AUX")
	)
	(segment
		(start 180.784246 -418.800534)
		(end 180.735732 -418.849048)
		(width 0.381)
		(layer "F.Cu")
		(net "P3V3_AUX")
	)
	(segment
		(start 74.106786 -64.682624)
		(end 74.106786 -63.998348)
		(width 0.381)
		(layer "F.Cu")
		(net "P3V3_AUX")
	)
	(segment
		(start 51.193446 -115.12677)
		(end 50.583846 -115.12677)
		(width 0.381)
		(layer "F.Cu")
		(net "P3V3_AUX")
	)
	(segment
		(start 316.996572 -55.794148)
		(end 316.996572 -54.803548)
		(width 0.381)
		(layer "F.Cu")
		(net "P3V3_AUX")
	)
	(segment
		(start 299.769022 -412.055818)
		(end 300.959266 -412.055818)
		(width 0.381)
		(layer "F.Cu")
		(net "P3V3_AUX")
	)
	(segment
		(start 310.329072 -41.493948)
		(end 309.922672 -41.900348)
		(width 0.381)
		(layer "F.Cu")
		(net "P3V3_AUX")
	)
	(segment
		(start 29.11983 -431.510948)
		(end 29.11983 -430.875948)
		(width 0.381)
		(layer "F.Cu")
		(net "P3V3_AUX")
	)
	(segment
		(start 389.106918 -29.50972)
		(end 387.633972 -29.50972)
		(width 0.381)
		(layer "F.Cu")
		(net "P3V3_AUX")
	)
	(segment
		(start 454.847452 -19.827748)
		(end 454.212452 -19.827748)
		(width 0.4572)
		(layer "F.Cu")
		(net "P3V3_AUX")
	)
	(segment
		(start 109.695742 -64.82207)
		(end 106.11231 -64.82207)
		(width 0.381)
		(layer "F.Cu")
		(net "P3V3_AUX")
	)
	(segment
		(start 83.50504 -40.623744)
		(end 83.50504 -39.899844)
		(width 0.381)
		(layer "F.Cu")
		(net "P3V3_AUX")
	)
	(segment
		(start 356.21595 -416.143948)
		(end 355.6 -416.143948)
		(width 0.381)
		(layer "F.Cu")
		(net "P3V3_AUX")
	)
	(segment
		(start 49.775364 -391.887202)
		(end 49.775364 -391.078212)
		(width 0.4572)
		(layer "F.Cu")
		(net "P3V3_AUX")
	)
	(segment
		(start 438.47766 -44.976288)
		(end 437.66486 -44.976288)
		(width 0.381)
		(layer "F.Cu")
		(net "P3V3_AUX")
	)
	(segment
		(start 461.187038 -99.164394)
		(end 460.529686 -99.164394)
		(width 0.381)
		(layer "F.Cu")
		(net "P3V3_AUX")
	)
	(segment
		(start 102.39375 -361.334812)
		(end 102.39375 -361.952032)
		(width 0.381)
		(layer "F.Cu")
		(net "P3V3_AUX")
	)
	(segment
		(start 321.863466 -25.539192)
		(end 321.747388 -25.65527)
		(width 0.381)
		(layer "F.Cu")
		(net "P3V3_AUX")
	)
	(segment
		(start 192.877186 -438.57418)
		(end 192.877186 -439.29808)
		(width 0.381)
		(layer "F.Cu")
		(net "P3V3_AUX")
	)
	(segment
		(start 31.148782 -403.695408)
		(end 31.758382 -403.695408)
		(width 0.381)
		(layer "F.Cu")
		(net "P3V3_AUX")
	)
	(segment
		(start 309.919116 -44.944792)
		(end 309.922672 -44.948348)
		(width 0.3302)
		(layer "F.Cu")
		(net "P3V3_AUX")
	)
	(segment
		(start 120.76049 -427.091348)
		(end 120.76049 -426.075348)
		(width 0.381)
		(layer "F.Cu")
		(net "P3V3_AUX")
	)
	(segment
		(start 28.638246 -394.358876)
		(end 28.028646 -394.358876)
		(width 0.381)
		(layer "F.Cu")
		(net "P3V3_AUX")
	)
	(segment
		(start 215.72855 -121.1326)
		(end 215.0618 -121.1326)
		(width 0.381)
		(layer "F.Cu")
		(net "P3V3_AUX")
	)
	(segment
		(start 99.108768 -411.31998)
		(end 98.53041 -411.898338)
		(width 0.381)
		(layer "F.Cu")
		(net "P3V3_AUX")
	)
	(segment
		(start 32.256476 -77.783944)
		(end 32.866076 -77.783944)
		(width 0.381)
		(layer "F.Cu")
		(net "P3V3_AUX")
	)
	(segment
		(start 126.675642 -108.695998)
		(end 126.89078 -108.695998)
		(width 0.381)
		(layer "F.Cu")
		(net "P3V3_AUX")
	)
	(segment
		(start 147.128738 -33.157668)
		(end 148.468334 -33.157668)
		(width 0.381)
		(layer "F.Cu")
		(net "P3V3_AUX")
	)
	(segment
		(start 129.348484 -361.313476)
		(end 129.348484 -360.680508)
		(width 0.381)
		(layer "F.Cu")
		(net "P3V3_AUX")
	)
	(segment
		(start 15.684246 -319.716658)
		(end 14.579346 -319.716658)
		(width 0.381)
		(layer "F.Cu")
		(net "P3V3_AUX")
	)
	(segment
		(start 120.76049 -426.075348)
		(end 121.37009 -426.075348)
		(width 0.381)
		(layer "F.Cu")
		(net "P3V3_AUX")
	)
	(segment
		(start 321.747388 -25.65527)
		(end 321.899788 -25.80767)
		(width 0.381)
		(layer "F.Cu")
		(net "P3V3_AUX")
	)
	(segment
		(start 460.288894 -120.020334)
		(end 461.179164 -120.020334)
		(width 0.381)
		(layer "F.Cu")
		(net "P3V3_AUX")
	)
	(segment
		(start 316.380622 -55.794148)
		(end 316.996572 -55.794148)
		(width 0.381)
		(layer "F.Cu")
		(net "P3V3_AUX")
	)
	(segment
		(start 28.054046 -389.278876)
		(end 28.638246 -389.278876)
		(width 0.381)
		(layer "F.Cu")
		(net "P3V3_AUX")
	)
	(segment
		(start 367.920778 -416.7505)
		(end 367.920778 -416.105848)
		(width 0.381)
		(layer "F.Cu")
		(net "P3V3_AUX")
	)
	(segment
		(start 309.993792 -39.177468)
		(end 309.922672 -39.106348)
		(width 0.381)
		(layer "F.Cu")
		(net "P3V3_AUX")
	)
	(segment
		(start 337.730084 -27.278076)
		(end 337.730084 -26.658316)
		(width 0.381)
		(layer "F.Cu")
		(net "P3V3_AUX")
	)
	(segment
		(start 162.74288 -74.759058)
		(end 163.5252 -74.759058)
		(width 0.381)
		(layer "F.Cu")
		(net "P3V3_AUX")
	)
	(segment
		(start 124.272294 -77.571092)
		(end 123.662694 -77.571092)
		(width 0.381)
		(layer "F.Cu")
		(net "P3V3_AUX")
	)
	(segment
		(start 305.2318 -27.94)
		(end 305.2318 -27.432254)
		(width 0.381)
		(layer "F.Cu")
		(net "P3V3_AUX")
	)
	(segment
		(start 439.408316 -105.268776)
		(end 439.49366 -105.35412)
		(width 0.381)
		(layer "F.Cu")
		(net "P3V3_AUX")
	)
	(segment
		(start 215.60028 -42.078148)
		(end 214.990172 -42.688256)
		(width 0.381)
		(layer "F.Cu")
		(net "P3V3_AUX")
	)
	(segment
		(start 140.208 -368.245898)
		(end 140.26388 -368.245898)
		(width 0.381)
		(layer "F.Cu")
		(net "P3V3_AUX")
	)
	(segment
		(start 439.685938 -46.95571)
		(end 439.320686 -46.590458)
		(width 0.381)
		(layer "F.Cu")
		(net "P3V3_AUX")
	)
	(segment
		(start 166.17315 -421.835326)
		(end 165.495224 -421.835326)
		(width 0.381)
		(layer "F.Cu")
		(net "P3V3_AUX")
	)
	(segment
		(start 439.633868 -45.720254)
		(end 442.698378 -45.720254)
		(width 0.381)
		(layer "F.Cu")
		(net "P3V3_AUX")
	)
	(segment
		(start 214.990172 -42.688256)
		(end 214.010748 -42.688256)
		(width 0.381)
		(layer "F.Cu")
		(net "P3V3_AUX")
	)
	(segment
		(start 14.426946 -396.263876)
		(end 15.036546 -396.263876)
		(width 0.381)
		(layer "F.Cu")
		(net "P3V3_AUX")
	)
	(segment
		(start 209.321146 -121.1072)
		(end 209.600546 -120.8278)
		(width 0.381)
		(layer "F.Cu")
		(net "P3V3_AUX")
	)
	(segment
		(start 371.807232 -61.581792)
		(end 371.807232 -62.216792)
		(width 0.381)
		(layer "F.Cu")
		(net "P3V3_AUX")
	)
	(segment
		(start 224.836482 -70.053708)
		(end 224.50298 -70.053708)
		(width 0.4572)
		(layer "F.Cu")
		(net "P3V3_AUX")
	)
	(segment
		(start 20.113498 -391.92581)
		(end 19.223482 -392.815826)
		(width 0.1778)
		(layer "F.Cu")
		(net "P3V3_AUX")
	)
	(segment
		(start 395.221206 -150.684992)
		(end 395.221206 -152.714452)
		(width 0.381)
		(layer "F.Cu")
		(net "P3V3_AUX")
	)
	(segment
		(start 13.640054 -420.435786)
		(end 13.640054 -420.12743)
		(width 0.381)
		(layer "F.Cu")
		(net "P3V3_AUX")
	)
	(segment
		(start 45.859446 -319.716658)
		(end 44.754546 -319.716658)
		(width 0.381)
		(layer "F.Cu")
		(net "P3V3_AUX")
	)
	(segment
		(start 104.591612 -230.622348)
		(end 104.591612 -230.086662)
		(width 0.2032)
		(layer "F.Cu")
		(net "P3V3_AUX")
	)
	(segment
		(start 143.919956 -77.532738)
		(end 142.952216 -78.500478)
		(width 0.381)
		(layer "F.Cu")
		(net "P3V3_AUX")
	)
	(segment
		(start 287.765998 -96.32569)
		(end 286.994854 -96.32569)
		(width 0.381)
		(layer "F.Cu")
		(net "P3V3_AUX")
	)
	(segment
		(start 193.089022 -24.491442)
		(end 192.454022 -24.491442)
		(width 0.4572)
		(layer "F.Cu")
		(net "P3V3_AUX")
	)
	(segment
		(start 90.086688 -64.793622)
		(end 90.086688 -64.184022)
		(width 0.381)
		(layer "F.Cu")
		(net "P3V3_AUX")
	)
	(segment
		(start 103.104442 -40.881554)
		(end 102.16388 -40.881554)
		(width 0.381)
		(layer "F.Cu")
		(net "P3V3_AUX")
	)
	(segment
		(start 300.959266 -412.055818)
		(end 301.01032 -412.004764)
		(width 0.381)
		(layer "F.Cu")
		(net "P3V3_AUX")
	)
	(segment
		(start 99.52482 -411.31998)
		(end 99.108768 -411.31998)
		(width 0.381)
		(layer "F.Cu")
		(net "P3V3_AUX")
	)
	(segment
		(start 309.761636 -30.182312)
		(end 309.922672 -30.343348)
		(width 0.381)
		(layer "F.Cu")
		(net "P3V3_AUX")
	)
	(segment
		(start 202.7936 -92.23375)
		(end 202.7936 -91.5924)
		(width 0.381)
		(layer "F.Cu")
		(net "P3V3_AUX")
	)
	(segment
		(start 164.12083 -43.525948)
		(end 163.36518 -43.525948)
		(width 0.381)
		(layer "F.Cu")
		(net "P3V3_AUX")
	)
	(segment
		(start 292.673278 -413.07512)
		(end 292.673278 -413.74314)
		(width 0.381)
		(layer "F.Cu")
		(net "P3V3_AUX")
	)
	(segment
		(start 196.899784 -112.124998)
		(end 196.738748 -111.963962)
		(width 0.381)
		(layer "F.Cu")
		(net "P3V3_AUX")
	)
	(segment
		(start 135.98525 -113.384584)
		(end 135.2931 -113.384584)
		(width 0.381)
		(layer "F.Cu")
		(net "P3V3_AUX")
	)
	(segment
		(start 439.49366 -105.98531)
		(end 438.8358 -105.98531)
		(width 0.381)
		(layer "F.Cu")
		(net "P3V3_AUX")
	)
	(segment
		(start 297.76547 -406.6794)
		(end 297.494452 -406.6794)
		(width 0.381)
		(layer "F.Cu")
		(net "P3V3_AUX")
	)
	(segment
		(start 168.56583 -436.971948)
		(end 167.37584 -436.971948)
		(width 0.381)
		(layer "F.Cu")
		(net "P3V3_AUX")
	)
	(segment
		(start 461.516476 -99.493832)
		(end 461.187038 -99.164394)
		(width 0.381)
		(layer "F.Cu")
		(net "P3V3_AUX")
	)
	(segment
		(start 439.49366 -105.35412)
		(end 439.49366 -105.98531)
		(width 0.381)
		(layer "F.Cu")
		(net "P3V3_AUX")
	)
	(segment
		(start 32.256476 -70.83425)
		(end 32.866076 -70.83425)
		(width 0.381)
		(layer "F.Cu")
		(net "P3V3_AUX")
	)
	(segment
		(start 212.1916 -68.2752)
		(end 211.813394 -68.653406)
		(width 0.381)
		(layer "F.Cu")
		(net "P3V3_AUX")
	)
	(segment
		(start 185.22188 -130.666998)
		(end 185.22188 -131.280408)
		(width 0.381)
		(layer "F.Cu")
		(net "P3V3_AUX")
	)
	(segment
		(start 225.171762 -69.718428)
		(end 224.836482 -70.053708)
		(width 0.4572)
		(layer "F.Cu")
		(net "P3V3_AUX")
	)
	(segment
		(start 150.93188 -110.219998)
		(end 150.97379 -110.261908)
		(width 0.381)
		(layer "F.Cu")
		(net "P3V3_AUX")
	)
	(segment
		(start 312.974228 -28.107386)
		(end 313.135264 -27.94635)
		(width 0.381)
		(layer "F.Cu")
		(net "P3V3_AUX")
	)
	(segment
		(start 282.131516 -15.247112)
		(end 282.131516 -16.641826)
		(width 0.381)
		(layer "F.Cu")
		(net "P3V3_AUX")
	)
	(segment
		(start 336.49285 -53.149246)
		(end 335.953608 -53.149246)
		(width 0.2032)
		(layer "F.Cu")
		(net "P3V3_AUX")
	)
	(segment
		(start 154.093672 -51.56835)
		(end 155.253436 -51.56835)
		(width 0.2286)
		(layer "F.Cu")
		(net "P3V3_AUX")
	)
	(segment
		(start 28.177998 -72.51573)
		(end 28.177998 -71.88073)
		(width 0.381)
		(layer "F.Cu")
		(net "P3V3_AUX")
	)
	(segment
		(start 12.784582 -410.402786)
		(end 12.784582 -409.793186)
		(width 0.381)
		(layer "F.Cu")
		(net "P3V3_AUX")
	)
	(segment
		(start 335.138268 -44.221146)
		(end 335.67878 -44.221146)
		(width 0.2032)
		(layer "F.Cu")
		(net "P3V3_AUX")
	)
	(segment
		(start 313.13501 -26.062432)
		(end 313.135264 -26.062686)
		(width 0.381)
		(layer "F.Cu")
		(net "P3V3_AUX")
	)
	(segment
		(start 161.80308 -132.679948)
		(end 161.61893 -132.864098)
		(width 0.381)
		(layer "F.Cu")
		(net "P3V3_AUX")
	)
	(segment
		(start 133.81355 -125.758448)
		(end 133.20395 -125.758448)
		(width 0.381)
		(layer "F.Cu")
		(net "P3V3_AUX")
	)
	(segment
		(start 67.693794 -109.483906)
		(end 66.006726 -109.483906)
		(width 0.381)
		(layer "F.Cu")
		(net "P3V3_AUX")
	)
	(segment
		(start 123.33732 -418.399468)
		(end 120.77827 -418.399468)
		(width 0.381)
		(layer "F.Cu")
		(net "P3V3_AUX")
	)
	(segment
		(start 350.790764 -361.334812)
		(end 350.790764 -361.952032)
		(width 0.381)
		(layer "F.Cu")
		(net "P3V3_AUX")
	)
	(segment
		(start 146.141186 -66.708528)
		(end 146.141186 -67.343528)
		(width 0.381)
		(layer "F.Cu")
		(net "P3V3_AUX")
	)
	(segment
		(start 126.89332 -19.924268)
		(end 126.91872 -19.949668)
		(width 0.381)
		(layer "F.Cu")
		(net "P3V3_AUX")
	)
	(segment
		(start 163.10483 -437.479948)
		(end 162.49523 -437.479948)
		(width 0.381)
		(layer "F.Cu")
		(net "P3V3_AUX")
	)
	(segment
		(start 210.086956 -29.876242)
		(end 210.086956 -29.266642)
		(width 0.3556)
		(layer "F.Cu")
		(net "P3V3_AUX")
	)
	(segment
		(start 276.578822 -18.629122)
		(end 277.464774 -18.629122)
		(width 0.381)
		(layer "F.Cu")
		(net "P3V3_AUX")
	)
	(segment
		(start 357.335582 -397.519398)
		(end 356.725982 -397.519398)
		(width 0.381)
		(layer "F.Cu")
		(net "P3V3_AUX")
	)
	(segment
		(start 461.516476 -101.105208)
		(end 461.516476 -100.470208)
		(width 0.381)
		(layer "F.Cu")
		(net "P3V3_AUX")
	)
	(segment
		(start 21.577046 -97.083626)
		(end 22.23008 -97.083626)
		(width 0.381)
		(layer "F.Cu")
		(net "P3V3_AUX")
	)
	(segment
		(start 125.919738 -109.451902)
		(end 126.675642 -108.695998)
		(width 0.381)
		(layer "F.Cu")
		(net "P3V3_AUX")
	)
	(segment
		(start 446.633092 -40.537638)
		(end 447.424556 -40.537638)
		(width 0.381)
		(layer "F.Cu")
		(net "P3V3_AUX")
	)
	(segment
		(start 311.427622 -49.139348)
		(end 311.364122 -49.202848)
		(width 0.381)
		(layer "F.Cu")
		(net "P3V3_AUX")
	)
	(segment
		(start 321.899788 -25.80767)
		(end 321.899788 -26.311606)
		(width 0.381)
		(layer "F.Cu")
		(net "P3V3_AUX")
	)
	(segment
		(start 180.339746 -319.716658)
		(end 181.444646 -319.716658)
		(width 0.381)
		(layer "F.Cu")
		(net "P3V3_AUX")
	)
	(segment
		(start 227.448618 -233.152696)
		(end 227.448618 -233.76255)
		(width 0.381)
		(layer "F.Cu")
		(net "P3V3_AUX")
	)
	(segment
		(start 241.01679 -253.345188)
		(end 241.69624 -253.345188)
		(width 0.381)
		(layer "F.Cu")
		(net "P3V3_AUX")
	)
	(segment
		(start 104.103678 -426.787818)
		(end 104.103678 -427.422818)
		(width 0.381)
		(layer "F.Cu")
		(net "P3V3_AUX")
	)
	(segment
		(start 164.862256 -422.468294)
		(end 164.862256 -423.01287)
		(width 0.381)
		(layer "F.Cu")
		(net "P3V3_AUX")
	)
	(segment
		(start 28.638246 -395.374876)
		(end 28.028646 -395.374876)
		(width 0.381)
		(layer "F.Cu")
		(net "P3V3_AUX")
	)
	(segment
		(start 98.53041 -411.898338)
		(end 98.53041 -412.171388)
		(width 0.381)
		(layer "F.Cu")
		(net "P3V3_AUX")
	)
	(segment
		(start 64.615822 -114.801396)
		(end 65.20053 -115.386104)
		(width 0.381)
		(layer "F.Cu")
		(net "P3V3_AUX")
	)
	(segment
		(start 118.954042 -66.292984)
		(end 118.954042 -64.658748)
		(width 0.381)
		(layer "F.Cu")
		(net "P3V3_AUX")
	)
	(segment
		(start 215.092788 -68.846446)
		(end 215.933782 -68.846446)
		(width 0.381)
		(layer "F.Cu")
		(net "P3V3_AUX")
	)
	(segment
		(start 432.390042 -381.218948)
		(end 432.999642 -381.218948)
		(width 0.381)
		(layer "F.Cu")
		(net "P3V3_AUX")
	)
	(segment
		(start 56.618378 -81.745074)
		(end 57.253378 -81.745074)
		(width 0.381)
		(layer "F.Cu")
		(net "P3V3_AUX")
	)
	(segment
		(start 307.456078 -424.501056)
		(end 307.456078 -423.82313)
		(width 0.381)
		(layer "F.Cu")
		(net "P3V3_AUX")
	)
	(segment
		(start 32.357568 -438.681368)
		(end 32.380428 -438.704228)
		(width 0.381)
		(layer "F.Cu")
		(net "P3V3_AUX")
	)
	(segment
		(start 116.13388 -402.95068)
		(end 116.13388 -402.34108)
		(width 0.381)
		(layer "F.Cu")
		(net "P3V3_AUX")
	)
	(segment
		(start 182.781448 -408.703526)
		(end 182.781448 -407.862532)
		(width 0.381)
		(layer "F.Cu")
		(net "P3V3_AUX")
	)
	(segment
		(start 180.64988 -127.364998)
		(end 180.64988 -127.975868)
		(width 0.381)
		(layer "F.Cu")
		(net "P3V3_AUX")
	)
	(segment
		(start 69.042534 -64.682624)
		(end 69.042534 -63.998348)
		(width 0.381)
		(layer "F.Cu")
		(net "P3V3_AUX")
	)
	(segment
		(start 310.406796 -44.895008)
		(end 309.976012 -44.895008)
		(width 0.3302)
		(layer "F.Cu")
		(net "P3V3_AUX")
	)
	(segment
		(start 312.01995 -23.9268)
		(end 312.01995 -23.241)
		(width 0.381)
		(layer "F.Cu")
		(net "P3V3_AUX")
	)
	(segment
		(start 312.043572 -41.519348)
		(end 311.371996 -41.519348)
		(width 0.381)
		(layer "F.Cu")
		(net "P3V3_AUX")
	)
	(segment
		(start 103.53675 -393.685268)
		(end 103.53675 -394.353288)
		(width 0.381)
		(layer "F.Cu")
		(net "P3V3_AUX")
	)
	(segment
		(start 75.738736 -74.501502)
		(end 75.738736 -73.828148)
		(width 0.381)
		(layer "F.Cu")
		(net "P3V3_AUX")
	)
	(segment
		(start 107.65663 -59.070748)
		(end 106.9848 -59.070748)
		(width 0.381)
		(layer "F.Cu")
		(net "P3V3_AUX")
	)
	(segment
		(start 293.799514 -319.716658)
		(end 292.694614 -319.716658)
		(width 0.381)
		(layer "F.Cu")
		(net "P3V3_AUX")
	)
	(segment
		(start 310.571896 -44.729908)
		(end 310.406796 -44.895008)
		(width 0.3302)
		(layer "F.Cu")
		(net "P3V3_AUX")
	)
	(segment
		(start 361.135168 -406.5016)
		(end 360.85653 -406.780238)
		(width 0.381)
		(layer "F.Cu")
		(net "P3V3_AUX")
	)
	(segment
		(start 137.068306 -68.445888)
		(end 137.068306 -69.080888)
		(width 0.381)
		(layer "F.Cu")
		(net "P3V3_AUX")
	)
	(segment
		(start 194.33413 -351.551748)
		(end 195.20408 -351.551748)
		(width 0.381)
		(layer "F.Cu")
		(net "P3V3_AUX")
	)
	(segment
		(start 150.61438 -44.351448)
		(end 151.16683 -44.351448)
		(width 0.381)
		(layer "F.Cu")
		(net "P3V3_AUX")
	)
	(segment
		(start 291.94633 -410.19349)
		(end 291.502846 -409.750006)
		(width 0.381)
		(layer "F.Cu")
		(net "P3V3_AUX")
	)
	(segment
		(start 112.27308 -398.275048)
		(end 113.28908 -398.275048)
		(width 0.381)
		(layer "F.Cu")
		(net "P3V3_AUX")
	)
	(segment
		(start 319.661032 -59.428888)
		(end 319.790572 -59.299348)
		(width 0.381)
		(layer "F.Cu")
		(net "P3V3_AUX")
	)
	(segment
		(start 51.3588 -440.187588)
		(end 51.9684 -440.187588)
		(width 0.381)
		(layer "F.Cu")
		(net "P3V3_AUX")
	)
	(segment
		(start 128.316228 -80.112616)
		(end 127.568706 -80.112616)
		(width 0.381)
		(layer "F.Cu")
		(net "P3V3_AUX")
	)
	(segment
		(start 300.21022 -421.01516)
		(end 300.21022 -420.276528)
		(width 0.381)
		(layer "F.Cu")
		(net "P3V3_AUX")
	)
	(segment
		(start 461.517746 -94.277434)
		(end 460.387446 -94.277434)
		(width 0.381)
		(layer "F.Cu")
		(net "P3V3_AUX")
	)
	(segment
		(start 22.225 -398.035526)
		(end 22.225 -397.425926)
		(width 0.381)
		(layer "F.Cu")
		(net "P3V3_AUX")
	)
	(segment
		(start 51.193446 -105.34777)
		(end 50.583846 -105.34777)
		(width 0.381)
		(layer "F.Cu")
		(net "P3V3_AUX")
	)
	(segment
		(start 217.137234 -53.705252)
		(end 216.659714 -53.705252)
		(width 0.254)
		(layer "F.Cu")
		(net "P3V3_AUX")
	)
	(segment
		(start 122.236484 -40.351456)
		(end 122.236484 -39.388796)
		(width 0.381)
		(layer "F.Cu")
		(net "P3V3_AUX")
	)
	(segment
		(start 414.297114 -319.716658)
		(end 413.192214 -319.716658)
		(width 0.381)
		(layer "F.Cu")
		(net "P3V3_AUX")
	)
	(segment
		(start 148.58238 -77.229208)
		(end 147.95754 -77.229208)
		(width 0.381)
		(layer "F.Cu")
		(net "P3V3_AUX")
	)
	(segment
		(start 432.461162 -397.270478)
		(end 433.070762 -397.270478)
		(width 0.381)
		(layer "F.Cu")
		(net "P3V3_AUX")
	)
	(segment
		(start 439.662316 -121.427748)
		(end 439.662316 -122.089926)
		(width 0.381)
		(layer "F.Cu")
		(net "P3V3_AUX")
	)
	(segment
		(start 30.771846 -319.716658)
		(end 29.666946 -319.716658)
		(width 0.381)
		(layer "F.Cu")
		(net "P3V3_AUX")
	)
	(segment
		(start 461.320896 -103.614728)
		(end 458.668882 -103.614728)
		(width 0.381)
		(layer "F.Cu")
		(net "P3V3_AUX")
	)
	(segment
		(start 371.73154 -69.565012)
		(end 371.73154 -68.930012)
		(width 0.381)
		(layer "F.Cu")
		(net "P3V3_AUX")
	)
	(segment
		(start 70.993 -115.661948)
		(end 70.75805 -115.426998)
		(width 0.381)
		(layer "F.Cu")
		(net "P3V3_AUX")
	)
	(segment
		(start 65.20053 -117.123718)
		(end 65.20053 -116.488718)
		(width 0.381)
		(layer "F.Cu")
		(net "P3V3_AUX")
	)
	(segment
		(start 219.64523 -109.591348)
		(end 219.02928 -109.591348)
		(width 0.381)
		(layer "F.Cu")
		(net "P3V3_AUX")
	)
	(segment
		(start 359.983532 -386.41909)
		(end 359.2449 -386.41909)
		(width 0.381)
		(layer "F.Cu")
		(net "P3V3_AUX")
	)
	(segment
		(start 29.548074 -394.305282)
		(end 29.548074 -393.198858)
		(width 0.4572)
		(layer "F.Cu")
		(net "P3V3_AUX")
	)
	(segment
		(start 312.043572 -42.713148)
		(end 311.427622 -42.713148)
		(width 0.3302)
		(layer "F.Cu")
		(net "P3V3_AUX")
	)
	(segment
		(start 396.127478 -150.69566)
		(end 395.924278 -150.49246)
		(width 0.381)
		(layer "F.Cu")
		(net "P3V3_AUX")
	)
	(segment
		(start 370.618258 -416.77336)
		(end 370.618258 -416.128708)
		(width 0.381)
		(layer "F.Cu")
		(net "P3V3_AUX")
	)
	(segment
		(start 284.589728 -413.63773)
		(end 283.821378 -413.63773)
		(width 0.381)
		(layer "F.Cu")
		(net "P3V3_AUX")
	)
	(segment
		(start 37.62883 -434.939948)
		(end 37.01923 -434.939948)
		(width 0.381)
		(layer "F.Cu")
		(net "P3V3_AUX")
	)
	(segment
		(start 12.022582 -420.816786)
		(end 13.259054 -420.816786)
		(width 0.381)
		(layer "F.Cu")
		(net "P3V3_AUX")
	)
	(segment
		(start 278.711914 -319.716658)
		(end 277.607014 -319.716658)
		(width 0.381)
		(layer "F.Cu")
		(net "P3V3_AUX")
	)
	(segment
		(start 38.060122 -392.68019)
		(end 37.355018 -392.68019)
		(width 0.254)
		(layer "F.Cu")
		(net "P3V3_AUX")
	)
	(segment
		(start 86.741 -36.032948)
		(end 87.0458 -35.728148)
		(width 0.381)
		(layer "F.Cu")
		(net "P3V3_AUX")
	)
	(segment
		(start 19.6215 -388.742428)
		(end 19.47672 -388.742428)
		(width 0.254)
		(layer "F.Cu")
		(net "P3V3_AUX")
	)
	(segment
		(start 446.294764 -110.038134)
		(end 446.294764 -110.673134)
		(width 0.381)
		(layer "F.Cu")
		(net "P3V3_AUX")
	)
	(segment
		(start 311.051956 -29.708348)
		(end 310.621426 -29.277818)
		(width 0.381)
		(layer "F.Cu")
		(net "P3V3_AUX")
	)
	(segment
		(start 307.574188 -424.619166)
		(end 307.456078 -424.501056)
		(width 0.381)
		(layer "F.Cu")
		(net "P3V3_AUX")
	)
	(segment
		(start 366.91189 -15.321788)
		(end 366.84585 -15.255748)
		(width 0.381)
		(layer "F.Cu")
		(net "P3V3_AUX")
	)
	(segment
		(start 281.240738 -15.247112)
		(end 282.131516 -15.247112)
		(width 0.381)
		(layer "F.Cu")
		(net "P3V3_AUX")
	)
	(segment
		(start 157.74924 -68.850764)
		(end 156.249624 -68.850764)
		(width 0.381)
		(layer "F.Cu")
		(net "P3V3_AUX")
	)
	(segment
		(start 143.013176 -114.73434)
		(end 142.61338 -114.334544)
		(width 0.381)
		(layer "F.Cu")
		(net "P3V3_AUX")
	)
	(segment
		(start 381.229616 -98.004122)
		(end 380.002034 -98.004122)
		(width 0.381)
		(layer "F.Cu")
		(net "P3V3_AUX")
	)
	(segment
		(start 295.548304 -426.878496)
		(end 294.913304 -426.878496)
		(width 0.381)
		(layer "F.Cu")
		(net "P3V3_AUX")
	)
	(segment
		(start 49.775364 -391.078212)
		(end 49.775364 -390.000744)
		(width 0.4572)
		(layer "F.Cu")
		(net "P3V3_AUX")
	)
	(segment
		(start 140.375386 -41.840404)
		(end 136.868408 -41.840404)
		(width 0.381)
		(layer "F.Cu")
		(net "P3V3_AUX")
	)
	(segment
		(start 200.407016 -108.022898)
		(end 200.58888 -108.022898)
		(width 0.381)
		(layer "F.Cu")
		(net "P3V3_AUX")
	)
	(segment
		(start 170.63593 -439.003948)
		(end 171.24553 -439.003948)
		(width 0.381)
		(layer "F.Cu")
		(net "P3V3_AUX")
	)
	(segment
		(start 431.57394 -184.772808)
		(end 431.80254 -184.544208)
		(width 0.3048)
		(layer "F.Cu")
		(net "P3V3_AUX")
	)
	(segment
		(start 395.413738 -150.49246)
		(end 395.221206 -150.684992)
		(width 0.381)
		(layer "F.Cu")
		(net "P3V3_AUX")
	)
	(segment
		(start 155.98013 -69.120258)
		(end 155.98013 -69.86397)
		(width 0.381)
		(layer "F.Cu")
		(net "P3V3_AUX")
	)
	(segment
		(start 214.33917 -22.278594)
		(end 214.33917 -22.630384)
		(width 0.381)
		(layer "F.Cu")
		(net "P3V3_AUX")
	)
	(segment
		(start 51.193446 -117.53977)
		(end 51.193446 -118.93677)
		(width 0.381)
		(layer "F.Cu")
		(net "P3V3_AUX")
	)
	(segment
		(start 95.095314 -419.322504)
		(end 95.095314 -418.712904)
		(width 0.381)
		(layer "F.Cu")
		(net "P3V3_AUX")
	)
	(segment
		(start 333.23657 -45.630846)
		(end 333.508858 -46.100746)
		(width 0.2032)
		(layer "F.Cu")
		(net "P3V3_AUX")
	)
	(segment
		(start 194.00266 -432.317906)
		(end 193.551302 -432.769264)
		(width 0.381)
		(layer "F.Cu")
		(net "P3V3_AUX")
	)
	(segment
		(start 147.95754 -79.139034)
		(end 147.773644 -78.955138)
		(width 0.381)
		(layer "F.Cu")
		(net "P3V3_AUX")
	)
	(segment
		(start 371.796818 -416.77336)
		(end 371.796818 -416.128708)
		(width 0.381)
		(layer "F.Cu")
		(net "P3V3_AUX")
	)
	(segment
		(start 332.276196 -17.437608)
		(end 332.253336 -17.414748)
		(width 0.381)
		(layer "F.Cu")
		(net "P3V3_AUX")
	)
	(segment
		(start 124.169932 -16.87957)
		(end 124.169932 -15.54607)
		(width 0.381)
		(layer "F.Cu")
		(net "P3V3_AUX")
	)
	(segment
		(start 308.995826 -39.995348)
		(end 309.122572 -40.122348)
		(width 0.381)
		(layer "F.Cu")
		(net "P3V3_AUX")
	)
	(segment
		(start 452.016114 -319.716658)
		(end 450.911214 -319.716658)
		(width 0.381)
		(layer "F.Cu")
		(net "P3V3_AUX")
	)
	(segment
		(start 122.236484 -40.986456)
		(end 122.236484 -40.351456)
		(width 0.381)
		(layer "F.Cu")
		(net "P3V3_AUX")
	)
	(segment
		(start 104.3178 -420.44874)
		(end 103.519478 -420.44874)
		(width 0.381)
		(layer "F.Cu")
		(net "P3V3_AUX")
	)
	(segment
		(start 197.81393 -99.875848)
		(end 198.42353 -99.875848)
		(width 0.381)
		(layer "F.Cu")
		(net "P3V3_AUX")
	)
	(segment
		(start 372.810278 -421.411146)
		(end 372.810278 -420.582344)
		(width 0.381)
		(layer "F.Cu")
		(net "P3V3_AUX")
	)
	(segment
		(start 83.0326 -41.220898)
		(end 82.4738 -41.220898)
		(width 0.381)
		(layer "F.Cu")
		(net "P3V3_AUX")
	)
	(segment
		(start 48.391318 -435.700424)
		(end 47.855378 -435.700424)
		(width 0.381)
		(layer "F.Cu")
		(net "P3V3_AUX")
	)
	(segment
		(start 148.58238 -79.139034)
		(end 147.95754 -79.139034)
		(width 0.381)
		(layer "F.Cu")
		(net "P3V3_AUX")
	)
	(segment
		(start 107.47883 -57.241948)
		(end 107.463844 -57.226962)
		(width 0.381)
		(layer "F.Cu")
		(net "P3V3_AUX")
	)
	(segment
		(start 151.16683 -44.351448)
		(end 151.16683 -43.570398)
		(width 0.381)
		(layer "F.Cu")
		(net "P3V3_AUX")
	)
	(segment
		(start 181.17693 -39.969948)
		(end 181.84876 -39.969948)
		(width 0.381)
		(layer "F.Cu")
		(net "P3V3_AUX")
	)
	(segment
		(start 23.650702 -405.858218)
		(end 23.041102 -405.858218)
		(width 0.381)
		(layer "F.Cu")
		(net "P3V3_AUX")
	)
	(segment
		(start 150.298658 -72.608948)
		(end 150.298658 -73.285858)
		(width 0.381)
		(layer "F.Cu")
		(net "P3V3_AUX")
	)
	(segment
		(start 25.215596 -388.408926)
		(end 24.580596 -388.408926)
		(width 0.381)
		(layer "F.Cu")
		(net "P3V3_AUX")
	)
	(segment
		(start 51.193446 -113.72977)
		(end 50.583846 -113.72977)
		(width 0.381)
		(layer "F.Cu")
		(net "P3V3_AUX")
	)
	(segment
		(start 311.427622 -35.804348)
		(end 312.00598 -35.804348)
		(width 0.381)
		(layer "F.Cu")
		(net "P3V3_AUX")
	)
	(segment
		(start 407.962354 -319.696846)
		(end 407.942542 -319.716658)
		(width 0.381)
		(layer "F.Cu")
		(net "P3V3_AUX")
	)
	(segment
		(start 294.62222 -421.01516)
		(end 294.62222 -420.276528)
		(width 0.381)
		(layer "F.Cu")
		(net "P3V3_AUX")
	)
	(segment
		(start 223.868488 -232.37952)
		(end 224.220532 -232.027476)
		(width 0.381)
		(layer "F.Cu")
		(net "P3V3_AUX")
	)
	(segment
		(start 198.42607 -115.418108)
		(end 198.30923 -115.534948)
		(width 0.381)
		(layer "F.Cu")
		(net "P3V3_AUX")
	)
	(segment
		(start 23.669752 -410.418534)
		(end 23.060152 -410.418534)
		(width 0.381)
		(layer "F.Cu")
		(net "P3V3_AUX")
	)
	(segment
		(start 301.01032 -412.004764)
		(end 301.01032 -412.004256)
		(width 0.381)
		(layer "F.Cu")
		(net "P3V3_AUX")
	)
	(segment
		(start 261.600188 -92.098876)
		(end 261.598918 -92.097606)
		(width 0.381)
		(layer "F.Cu")
		(net "P3V3_AUX")
	)
	(segment
		(start 454.847452 -20.902168)
		(end 454.212452 -20.902168)
		(width 0.4572)
		(layer "F.Cu")
		(net "P3V3_AUX")
	)
	(segment
		(start 23.650702 -401.790408)
		(end 23.041102 -401.790408)
		(width 0.381)
		(layer "F.Cu")
		(net "P3V3_AUX")
	)
	(segment
		(start 276.178264 -18.228564)
		(end 276.578822 -18.629122)
		(width 0.381)
		(layer "F.Cu")
		(net "P3V3_AUX")
	)
	(segment
		(start 390.02208 -38.496748)
		(end 390.355074 -38.829742)
		(width 0.381)
		(layer "F.Cu")
		(net "P3V3_AUX")
	)
	(segment
		(start 316.996572 -51.196748)
		(end 316.996572 -52.161948)
		(width 0.3048)
		(layer "F.Cu")
		(net "P3V3_AUX")
	)
	(segment
		(start 423.804842 -395.619478)
		(end 423.195242 -395.619478)
		(width 0.381)
		(layer "F.Cu")
		(net "P3V3_AUX")
	)
	(segment
		(start 21.577046 -100.54971)
		(end 22.23008 -100.54971)
		(width 0.381)
		(layer "F.Cu")
		(net "P3V3_AUX")
	)
	(segment
		(start 107.463844 -57.226962)
		(end 105.76941 -57.226962)
		(width 0.381)
		(layer "F.Cu")
		(net "P3V3_AUX")
	)
	(segment
		(start 211.813394 -68.653406)
		(end 211.455 -68.653406)
		(width 0.381)
		(layer "F.Cu")
		(net "P3V3_AUX")
	)
	(segment
		(start 377.288298 -361.313476)
		(end 377.288298 -360.680508)
		(width 0.381)
		(layer "F.Cu")
		(net "P3V3_AUX")
	)
	(segment
		(start 252.73 -37.775896)
		(end 252.62205 -37.667946)
		(width 0.4572)
		(layer "F.Cu")
		(net "P3V3_AUX")
	)
	(segment
		(start 161.61893 -132.864098)
		(end 161.61893 -133.695948)
		(width 0.381)
		(layer "F.Cu")
		(net "P3V3_AUX")
	)
	(segment
		(start 172.8724 -93.138498)
		(end 172.8724 -92.527628)
		(width 0.381)
		(layer "F.Cu")
		(net "P3V3_AUX")
	)
	(segment
		(start 194.30873 -359.349548)
		(end 195.02628 -359.349548)
		(width 0.381)
		(layer "F.Cu")
		(net "P3V3_AUX")
	)
	(segment
		(start 19.945096 -389.066024)
		(end 19.6215 -388.742428)
		(width 0.254)
		(layer "F.Cu")
		(net "P3V3_AUX")
	)
	(segment
		(start 276.69363 -416.88385)
		(end 276.55266 -417.02482)
		(width 0.381)
		(layer "F.Cu")
		(net "P3V3_AUX")
	)
	(segment
		(start 131.866894 -127.119126)
		(end 132.476494 -127.119126)
		(width 0.381)
		(layer "F.Cu")
		(net "P3V3_AUX")
	)
	(segment
		(start 274.094956 -19.952462)
		(end 274.094956 -19.24685)
		(width 0.381)
		(layer "F.Cu")
		(net "P3V3_AUX")
	)
	(segment
		(start 68.010786 -64.682624)
		(end 68.010786 -63.998348)
		(width 0.381)
		(layer "F.Cu")
		(net "P3V3_AUX")
	)
	(segment
		(start 75.305412 -37.897562)
		(end 75.305412 -38.532562)
		(width 0.381)
		(layer "F.Cu")
		(net "P3V3_AUX")
	)
	(segment
		(start 142.61338 -114.334544)
		(end 141.761972 -114.334544)
		(width 0.381)
		(layer "F.Cu")
		(net "P3V3_AUX")
	)
	(segment
		(start 47.026068 -439.189368)
		(end 47.635668 -439.189368)
		(width 0.381)
		(layer "F.Cu")
		(net "P3V3_AUX")
	)
	(segment
		(start 309.922672 -35.804348)
		(end 310.538622 -35.804348)
		(width 0.381)
		(layer "F.Cu")
		(net "P3V3_AUX")
	)
	(segment
		(start 82.706718 -20.616672)
		(end 82.071718 -20.616672)
		(width 0.4572)
		(layer "F.Cu")
		(net "P3V3_AUX")
	)
	(segment
		(start 212.98662 -127.132842)
		(end 212.98662 -125.851158)
		(width 0.381)
		(layer "F.Cu")
		(net "P3V3_AUX")
	)
	(segment
		(start 307.361336 -60.037726)
		(end 307.361336 -61.928756)
		(width 0.381)
		(layer "F.Cu")
		(net "P3V3_AUX")
	)
	(segment
		(start 305.58994 -432.65725)
		(end 305.58994 -431.918618)
		(width 0.381)
		(layer "F.Cu")
		(net "P3V3_AUX")
	)
	(segment
		(start 307.574188 -425.163234)
		(end 307.574188 -424.619166)
		(width 0.381)
		(layer "F.Cu")
		(net "P3V3_AUX")
	)
	(segment
		(start 160.22193 -58.511948)
		(end 160.22193 -59.527948)
		(width 0.381)
		(layer "F.Cu")
		(net "P3V3_AUX")
	)
	(segment
		(start 65.842896 -106.561128)
		(end 66.084958 -106.319066)
		(width 0.381)
		(layer "F.Cu")
		(net "P3V3_AUX")
	)
	(segment
		(start 339.483446 -27.52598)
		(end 339.483446 -26.91638)
		(width 0.381)
		(layer "F.Cu")
		(net "P3V3_AUX")
	)
	(segment
		(start 211.99221 -27.268424)
		(end 213.445598 -27.268424)
		(width 0.381)
		(layer "F.Cu")
		(net "P3V3_AUX")
	)
	(segment
		(start 209.600546 -120.8278)
		(end 210.185 -120.8278)
		(width 0.381)
		(layer "F.Cu")
		(net "P3V3_AUX")
	)
	(segment
		(start 80.767174 -60.381896)
		(end 80.77073 -60.37834)
		(width 0.4572)
		(layer "F.Cu")
		(net "P3V3_AUX")
	)
	(segment
		(start 254.381 -38.324282)
		(end 254.381 -37.686996)
		(width 0.381)
		(layer "F.Cu")
		(net "P3V3_AUX")
	)
	(segment
		(start 304.1396 -421.0939)
		(end 304.1396 -420.355268)
		(width 0.381)
		(layer "F.Cu")
		(net "P3V3_AUX")
	)
	(segment
		(start 254.973074 -319.805558)
		(end 255.991614 -319.805558)
		(width 0.381)
		(layer "F.Cu")
		(net "P3V3_AUX")
	)
	(segment
		(start 461.557878 -94.317566)
		(end 461.557878 -94.952566)
		(width 0.381)
		(layer "F.Cu")
		(net "P3V3_AUX")
	)
	(segment
		(start 52.881022 -435.360318)
		(end 53.490622 -435.360318)
		(width 0.381)
		(layer "F.Cu")
		(net "P3V3_AUX")
	)
	(segment
		(start 141.688566 -115.437666)
		(end 143.368268 -115.437666)
		(width 0.381)
		(layer "F.Cu")
		(net "P3V3_AUX")
	)
	(segment
		(start 114.660172 -18.456656)
		(end 115.332764 -17.784064)
		(width 0.381)
		(layer "F.Cu")
		(net "P3V3_AUX")
	)
	(segment
		(start 279.727914 -17.613122)
		(end 279.45588 -17.885156)
		(width 0.381)
		(layer "F.Cu")
		(net "P3V3_AUX")
	)
	(segment
		(start 140.40993 -41.836848)
		(end 140.40993 -40.985948)
		(width 0.381)
		(layer "F.Cu")
		(net "P3V3_AUX")
	)
	(segment
		(start 14.426946 -390.167876)
		(end 15.036546 -390.167876)
		(width 0.381)
		(layer "F.Cu")
		(net "P3V3_AUX")
	)
	(segment
		(start 70.231 -112.994948)
		(end 70.75805 -113.521998)
		(width 0.381)
		(layer "F.Cu")
		(net "P3V3_AUX")
	)
	(segment
		(start 293.02837 -92.260674)
		(end 293.01059 -92.278454)
		(width 0.381)
		(layer "F.Cu")
		(net "P3V3_AUX")
	)
	(segment
		(start 212.82025 -134.565644)
		(end 213.61146 -134.565644)
		(width 0.254)
		(layer "F.Cu")
		(net "P3V3_AUX")
	)
	(segment
		(start 194.00393 -107.495848)
		(end 194.61353 -107.495848)
		(width 0.381)
		(layer "F.Cu")
		(net "P3V3_AUX")
	)
	(segment
		(start 420.66718 -320.129408)
		(end 421.07993 -319.716658)
		(width 0.381)
		(layer "F.Cu")
		(net "P3V3_AUX")
	)
	(segment
		(start 365.96955 -407.0604)
		(end 365.3282 -407.0604)
		(width 0.381)
		(layer "F.Cu")
		(net "P3V3_AUX")
	)
	(segment
		(start 152.059894 -127.024384)
		(end 152.059894 -126.263908)
		(width 0.381)
		(layer "F.Cu")
		(net "P3V3_AUX")
	)
	(segment
		(start 96.141286 -428.381922)
		(end 96.141286 -428.176436)
		(width 0.381)
		(layer "F.Cu")
		(net "P3V3_AUX")
	)
	(segment
		(start 174.50943 -424.398948)
		(end 173.31944 -424.398948)
		(width 0.381)
		(layer "F.Cu")
		(net "P3V3_AUX")
	)
	(segment
		(start 132.79247 -121.536968)
		(end 132.79247 -122.46737)
		(width 0.381)
		(layer "F.Cu")
		(net "P3V3_AUX")
	)
	(segment
		(start 259.181346 -92.258388)
		(end 258.58343 -92.258388)
		(width 0.381)
		(layer "F.Cu")
		(net "P3V3_AUX")
	)
	(segment
		(start 431.80254 -184.544208)
		(end 432.27879 -184.544208)
		(width 0.3048)
		(layer "F.Cu")
		(net "P3V3_AUX")
	)
	(segment
		(start 277.709376 -16.043148)
		(end 276.522942 -16.043148)
		(width 0.381)
		(layer "F.Cu")
		(net "P3V3_AUX")
	)
	(segment
		(start 368.1984 -101.571298)
		(end 368.1984 -102.189788)
		(width 0.381)
		(layer "F.Cu")
		(net "P3V3_AUX")
	)
	(segment
		(start 466.28304 -46.408848)
		(end 466.193886 -46.319694)
		(width 0.381)
		(layer "F.Cu")
		(net "P3V3_AUX")
	)
	(segment
		(start 119.249952 -408.269948)
		(end 119.249952 -407.335228)
		(width 0.381)
		(layer "F.Cu")
		(net "P3V3_AUX")
	)
	(segment
		(start 15.667736 -75.871578)
		(end 14.901672 -75.871578)
		(width 0.381)
		(layer "F.Cu")
		(net "P3V3_AUX")
	)
	(segment
		(start 106.654854 -29.842714)
		(end 107.569 -29.842714)
		(width 0.381)
		(layer "F.Cu")
		(net "P3V3_AUX")
	)
	(segment
		(start 223.2914 -231.802432)
		(end 223.868488 -232.37952)
		(width 0.381)
		(layer "F.Cu")
		(net "P3V3_AUX")
	)
	(segment
		(start 305.2318 -27.432254)
		(end 304.901346 -27.1018)
		(width 0.381)
		(layer "F.Cu")
		(net "P3V3_AUX")
	)
	(segment
		(start 145.76552 -36.761928)
		(end 146.595338 -36.761928)
		(width 0.381)
		(layer "F.Cu")
		(net "P3V3_AUX")
	)
	(segment
		(start 210.33105 -114.0968)
		(end 210.9724 -114.0968)
		(width 0.381)
		(layer "F.Cu")
		(net "P3V3_AUX")
	)
	(segment
		(start 29.53004 -393.180824)
		(end 29.53004 -391.65149)
		(width 0.4572)
		(layer "F.Cu")
		(net "P3V3_AUX")
	)
	(segment
		(start 423.804842 -385.282948)
		(end 423.804842 -386.298948)
		(width 0.381)
		(layer "F.Cu")
		(net "P3V3_AUX")
	)
	(segment
		(start 409.355036 -361.865926)
		(end 406.524714 -361.865926)
		(width 0.381)
		(layer "F.Cu")
		(net "P3V3_AUX")
	)
	(segment
		(start 214.33917 -22.630384)
		(end 214.61349 -22.904704)
		(width 0.381)
		(layer "F.Cu")
		(net "P3V3_AUX")
	)
	(segment
		(start 360.082592 -393.28725)
		(end 359.34396 -393.28725)
		(width 0.381)
		(layer "F.Cu")
		(net "P3V3_AUX")
	)
	(segment
		(start 458.01661 -39.124128)
		(end 458.01661 -39.765478)
		(width 0.381)
		(layer "F.Cu")
		(net "P3V3_AUX")
	)
	(segment
		(start 435.6735 -41.1226)
		(end 436.39994 -40.39616)
		(width 0.381)
		(layer "F.Cu")
		(net "P3V3_AUX")
	)
	(segment
		(start 128.41605 -61.432948)
		(end 129.032 -61.432948)
		(width 0.381)
		(layer "F.Cu")
		(net "P3V3_AUX")
	)
	(segment
		(start 83.566508 -74.501502)
		(end 83.566508 -73.828148)
		(width 0.381)
		(layer "F.Cu")
		(net "P3V3_AUX")
	)
	(segment
		(start 185.59272 -417.37788)
		(end 185.2041 -416.98926)
		(width 0.381)
		(layer "F.Cu")
		(net "P3V3_AUX")
	)
	(segment
		(start 365.60125 -413.6898)
		(end 366.2172 -413.6898)
		(width 0.381)
		(layer "F.Cu")
		(net "P3V3_AUX")
	)
	(segment
		(start 360.044492 -389.19277)
		(end 359.30586 -389.19277)
		(width 0.381)
		(layer "F.Cu")
		(net "P3V3_AUX")
	)
	(segment
		(start 423.823892 -401.655534)
		(end 423.214292 -401.655534)
		(width 0.381)
		(layer "F.Cu")
		(net "P3V3_AUX")
	)
	(segment
		(start 30.71114 -437.761888)
		(end 31.342076 -437.761888)
		(width 0.381)
		(layer "F.Cu")
		(net "P3V3_AUX")
	)
	(segment
		(start 309.919116 -43.92803)
		(end 309.919116 -44.944792)
		(width 0.3302)
		(layer "F.Cu")
		(net "P3V3_AUX")
	)
	(segment
		(start 143.658844 -124.88672)
		(end 144.204182 -124.88672)
		(width 0.381)
		(layer "F.Cu")
		(net "P3V3_AUX")
	)
	(segment
		(start 365.60125 -412.623)
		(end 366.2172 -412.623)
		(width 0.381)
		(layer "F.Cu")
		(net "P3V3_AUX")
	)
	(segment
		(start 29.548074 -393.198858)
		(end 29.53004 -393.180824)
		(width 0.4572)
		(layer "F.Cu")
		(net "P3V3_AUX")
	)
	(segment
		(start 297.547284 -16.715994)
		(end 297.836844 -16.715994)
		(width 0.381)
		(layer "F.Cu")
		(net "P3V3_AUX")
	)
	(segment
		(start 114.68608 -120.246648)
		(end 114.68608 -120.862598)
		(width 0.381)
		(layer "F.Cu")
		(net "P3V3_AUX")
	)
	(segment
		(start 262.701532 -67.08902)
		(end 262.052308 -67.08902)
		(width 0.381)
		(layer "F.Cu")
		(net "P3V3_AUX")
	)
	(segment
		(start 210.997546 -14.892528)
		(end 211.172044 -14.892528)
		(width 0.381)
		(layer "F.Cu")
		(net "P3V3_AUX")
	)
	(segment
		(start 449.52666 -51.06162)
		(end 449.52666 -51.976528)
		(width 0.508)
		(layer "F.Cu")
		(net "P3V3_AUX")
	)
	(segment
		(start 28.15463 -76.266548)
		(end 28.177998 -76.289916)
		(width 0.381)
		(layer "F.Cu")
		(net "P3V3_AUX")
	)
	(segment
		(start 176.57953 -422.366948)
		(end 177.18913 -422.366948)
		(width 0.381)
		(layer "F.Cu")
		(net "P3V3_AUX")
	)
	(segment
		(start 351.59188 -230.622348)
		(end 351.59188 -230.086662)
		(width 0.2032)
		(layer "F.Cu")
		(net "P3V3_AUX")
	)
	(segment
		(start 313.135264 -27.94635)
		(end 313.135264 -27.078686)
		(width 0.381)
		(layer "F.Cu")
		(net "P3V3_AUX")
	)
	(segment
		(start 112.4966 -30.65272)
		(end 112.4966 -29.76753)
		(width 0.381)
		(layer "F.Cu")
		(net "P3V3_AUX")
	)
	(segment
		(start 28.62453 -428.081948)
		(end 27.92984 -428.081948)
		(width 0.381)
		(layer "F.Cu")
		(net "P3V3_AUX")
	)
	(segment
		(start 460.901034 -118.641368)
		(end 461.179164 -118.919498)
		(width 0.381)
		(layer "F.Cu")
		(net "P3V3_AUX")
	)
	(segment
		(start 132.314696 -116.499386)
		(end 132.314696 -117.026182)
		(width 0.381)
		(layer "F.Cu")
		(net "P3V3_AUX")
	)
	(segment
		(start 285.714948 -410.88945)
		(end 285.714948 -410.21254)
		(width 0.381)
		(layer "F.Cu")
		(net "P3V3_AUX")
	)
	(segment
		(start 421.07993 -319.716658)
		(end 421.840914 -319.716658)
		(width 0.381)
		(layer "F.Cu")
		(net "P3V3_AUX")
	)
	(segment
		(start 210.4644 -15.685008)
		(end 210.4644 -15.425674)
		(width 0.381)
		(layer "F.Cu")
		(net "P3V3_AUX")
	)
	(segment
		(start 19.223482 -392.815826)
		(end 19.119596 -392.815826)
		(width 0.1778)
		(layer "F.Cu")
		(net "P3V3_AUX")
	)
	(segment
		(start 126.770384 -64.125348)
		(end 126.770384 -66.456306)
		(width 0.381)
		(layer "F.Cu")
		(net "P3V3_AUX")
	)
	(segment
		(start 143.919956 -76.481432)
		(end 143.919956 -77.532738)
		(width 0.381)
		(layer "F.Cu")
		(net "P3V3_AUX")
	)
	(segment
		(start 101.433884 -395.42974)
		(end 100.824284 -395.42974)
		(width 0.381)
		(layer "F.Cu")
		(net "P3V3_AUX")
	)
	(segment
		(start 183.69788 -130.666998)
		(end 183.69788 -131.280408)
		(width 0.381)
		(layer "F.Cu")
		(net "P3V3_AUX")
	)
	(segment
		(start 40.389556 -400.553936)
		(end 40.389556 -400.776694)
		(width 0.4572)
		(layer "F.Cu")
		(net "P3V3_AUX")
	)
	(segment
		(start 169.041572 -420.511478)
		(end 168.431972 -420.511478)
		(width 0.381)
		(layer "F.Cu")
		(net "P3V3_AUX")
	)
	(segment
		(start 379.443996 -93.615764)
		(end 379.443996 -93.287342)
		(width 0.381)
		(layer "F.Cu")
		(net "P3V3_AUX")
	)
	(segment
		(start 174.50943 -425.033948)
		(end 174.50943 -424.398948)
		(width 0.381)
		(layer "F.Cu")
		(net "P3V3_AUX")
	)
	(segment
		(start 423.804842 -392.648948)
		(end 423.195242 -392.648948)
		(width 0.381)
		(layer "F.Cu")
		(net "P3V3_AUX")
	)
	(segment
		(start 312.043572 -34.102548)
		(end 311.427622 -34.102548)
		(width 0.3048)
		(layer "F.Cu")
		(net "P3V3_AUX")
	)
	(segment
		(start 352.531934 -230.622602)
		(end 352.53168 -230.622348)
		(width 0.2032)
		(layer "F.Cu")
		(net "P3V3_AUX")
	)
	(segment
		(start 297.494452 -406.6794)
		(end 297.171872 -407.00198)
		(width 0.381)
		(layer "F.Cu")
		(net "P3V3_AUX")
	)
	(segment
		(start 51.193446 -110.93577)
		(end 50.583846 -110.93577)
		(width 0.381)
		(layer "F.Cu")
		(net "P3V3_AUX")
	)
	(segment
		(start 224.220532 -231.488488)
		(end 224.028 -231.295956)
		(width 0.381)
		(layer "F.Cu")
		(net "P3V3_AUX")
	)
	(segment
		(start 32.25165 -69.7992)
		(end 32.86125 -69.7992)
		(width 0.381)
		(layer "F.Cu")
		(net "P3V3_AUX")
	)
	(segment
		(start 448.611752 -51.976528)
		(end 449.52666 -51.976528)
		(width 0.508)
		(layer "F.Cu")
		(net "P3V3_AUX")
	)
	(segment
		(start 174.04588 -130.666998)
		(end 174.04588 -131.280408)
		(width 0.381)
		(layer "F.Cu")
		(net "P3V3_AUX")
	)
	(segment
		(start 72.766174 -64.682624)
		(end 72.766174 -63.998348)
		(width 0.381)
		(layer "F.Cu")
		(net "P3V3_AUX")
	)
	(segment
		(start 170.63593 -434.939948)
		(end 171.24553 -434.939948)
		(width 0.381)
		(layer "F.Cu")
		(net "P3V3_AUX")
	)
	(segment
		(start 140.30833 -33.466024)
		(end 140.30833 -34.12236)
		(width 0.381)
		(layer "F.Cu")
		(net "P3V3_AUX")
	)
	(segment
		(start 368.243358 -92.562934)
		(end 368.243358 -91.953334)
		(width 0.3556)
		(layer "F.Cu")
		(net "P3V3_AUX")
	)
	(segment
		(start 32.545782 -412.069534)
		(end 33.155382 -412.069534)
		(width 0.381)
		(layer "F.Cu")
		(net "P3V3_AUX")
	)
	(segment
		(start 308.908704 -13.68044)
		(end 308.969664 -13.7414)
		(width 0.381)
		(layer "F.Cu")
		(net "P3V3_AUX")
	)
	(segment
		(start 123.994926 -120.210834)
		(end 123.994926 -120.826784)
		(width 0.381)
		(layer "F.Cu")
		(net "P3V3_AUX")
	)
	(segment
		(start 254.987806 -92.292424)
		(end 254.98679 -92.291408)
		(width 0.381)
		(layer "F.Cu")
		(net "P3V3_AUX")
	)
	(segment
		(start 460.648812 -118.641368)
		(end 460.901034 -118.641368)
		(width 0.381)
		(layer "F.Cu")
		(net "P3V3_AUX")
	)
	(segment
		(start 160.22193 -59.527948)
		(end 160.22193 -60.162948)
		(width 0.381)
		(layer "F.Cu")
		(net "P3V3_AUX")
	)
	(segment
		(start 110.932722 -132.266182)
		(end 110.323122 -132.266182)
		(width 0.381)
		(layer "F.Cu")
		(net "P3V3_AUX")
	)
	(segment
		(start 126.89078 -108.695998)
		(end 127.52578 -108.695998)
		(width 0.381)
		(layer "F.Cu")
		(net "P3V3_AUX")
	)
	(segment
		(start 224.028 -231.295956)
		(end 224.028 -230.571548)
		(width 0.381)
		(layer "F.Cu")
		(net "P3V3_AUX")
	)
	(segment
		(start 110.932722 -128.075182)
		(end 110.323122 -128.075182)
		(width 0.381)
		(layer "F.Cu")
		(net "P3V3_AUX")
	)
	(segment
		(start 210.160362 -100.908104)
		(end 209.550762 -100.908104)
		(width 0.381)
		(layer "F.Cu")
		(net "P3V3_AUX")
	)
	(segment
		(start 256.073402 -92.292424)
		(end 254.987806 -92.292424)
		(width 0.381)
		(layer "F.Cu")
		(net "P3V3_AUX")
	)
	(segment
		(start 355.42855 -402.9456)
		(end 354.7364 -402.9456)
		(width 0.381)
		(layer "F.Cu")
		(net "P3V3_AUX")
	)
	(segment
		(start 35.977068 -436.903368)
		(end 35.977068 -437.842406)
		(width 0.381)
		(layer "F.Cu")
		(net "P3V3_AUX")
	)
	(segment
		(start 158.531306 -64.294258)
		(end 158.0642 -64.761364)
		(width 0.381)
		(layer "F.Cu")
		(net "P3V3_AUX")
	)
	(segment
		(start 69.060822 -111.65967)
		(end 68.493386 -111.65967)
		(width 0.381)
		(layer "F.Cu")
		(net "P3V3_AUX")
	)
	(segment
		(start 361.6198 -406.5016)
		(end 361.135168 -406.5016)
		(width 0.381)
		(layer "F.Cu")
		(net "P3V3_AUX")
	)
	(segment
		(start 292.636448 -18.714466)
		(end 292.636448 -17.747234)
		(width 0.381)
		(layer "F.Cu")
		(net "P3V3_AUX")
	)
	(segment
		(start 314.710572 -50.155348)
		(end 314.094622 -50.155348)
		(width 0.254)
		(layer "F.Cu")
		(net "P3V3_AUX")
	)
	(segment
		(start 23.993602 -392.60145)
		(end 24.12365 -392.731498)
		(width 0.4572)
		(layer "F.Cu")
		(net "P3V3_AUX")
	)
	(segment
		(start 110.932722 -130.869182)
		(end 110.323122 -130.869182)
		(width 0.381)
		(layer "F.Cu")
		(net "P3V3_AUX")
	)
	(segment
		(start 89.69883 -56.352948)
		(end 89.69883 -55.717948)
		(width 0.381)
		(layer "F.Cu")
		(net "P3V3_AUX")
	)
	(segment
		(start 366.678718 -416.74796)
		(end 366.678718 -416.105848)
		(width 0.381)
		(layer "F.Cu")
		(net "P3V3_AUX")
	)
	(segment
		(start 114.81308 -400.815048)
		(end 114.81308 -401.424648)
		(width 0.381)
		(layer "F.Cu")
		(net "P3V3_AUX")
	)
	(segment
		(start 92.33535 -40.310308)
		(end 92.33535 -39.675308)
		(width 0.381)
		(layer "F.Cu")
		(net "P3V3_AUX")
	)
	(segment
		(start 307.361336 -61.928756)
		(end 307.3146 -61.975492)
		(width 0.381)
		(layer "F.Cu")
		(net "P3V3_AUX")
	)
	(segment
		(start 207.772 -97.28835)
		(end 207.772 -96.2152)
		(width 0.381)
		(layer "F.Cu")
		(net "P3V3_AUX")
	)
	(segment
		(start 366.84585 -15.255748)
		(end 366.84585 -14.544548)
		(width 0.381)
		(layer "F.Cu")
		(net "P3V3_AUX")
	)
	(segment
		(start 159.274256 -64.294258)
		(end 158.531306 -64.294258)
		(width 0.381)
		(layer "F.Cu")
		(net "P3V3_AUX")
	)
	(segment
		(start 140.984478 -368.14633)
		(end 141.561312 -368.14633)
		(width 0.381)
		(layer "F.Cu")
		(net "P3V3_AUX")
	)
	(segment
		(start 379.7681 -93.939868)
		(end 379.443996 -93.615764)
		(width 0.381)
		(layer "F.Cu")
		(net "P3V3_AUX")
	)
	(segment
		(start 87.0458 -35.728148)
		(end 87.0458 -35.474148)
		(width 0.381)
		(layer "F.Cu")
		(net "P3V3_AUX")
	)
	(segment
		(start 144.48536 -127.265684)
		(end 144.48536 -126.630684)
		(width 0.381)
		(layer "F.Cu")
		(net "P3V3_AUX")
	)
	(segment
		(start 169.04843 -423.890948)
		(end 168.43883 -423.890948)
		(width 0.381)
		(layer "F.Cu")
		(net "P3V3_AUX")
	)
	(segment
		(start 150.97379 -110.261908)
		(end 152.313894 -110.261908)
		(width 0.381)
		(layer "F.Cu")
		(net "P3V3_AUX")
	)
	(segment
		(start 316.607444 -51.196748)
		(end 316.996572 -51.196748)
		(width 0.3048)
		(layer "F.Cu")
		(net "P3V3_AUX")
	)
	(segment
		(start 410.77261 -365.968788)
		(end 410.303472 -366.437926)
		(width 0.381)
		(layer "F.Cu")
		(net "P3V3_AUX")
	)
	(segment
		(start 461.320896 -104.249728)
		(end 461.320896 -103.614728)
		(width 0.381)
		(layer "F.Cu")
		(net "P3V3_AUX")
	)
	(segment
		(start 319.661032 -57.396888)
		(end 319.790572 -57.267348)
		(width 0.381)
		(layer "F.Cu")
		(net "P3V3_AUX")
	)
	(segment
		(start 223.545908 -234.50169)
		(end 224.390458 -234.50169)
		(width 0.381)
		(layer "F.Cu")
		(net "P3V3_AUX")
	)
	(segment
		(start 410.303472 -366.437926)
		(end 406.524714 -366.437926)
		(width 0.381)
		(layer "F.Cu")
		(net "P3V3_AUX")
	)
	(segment
		(start 172.795946 -319.716658)
		(end 173.900846 -319.716658)
		(width 0.381)
		(layer "F.Cu")
		(net "P3V3_AUX")
	)
	(segment
		(start 210.555586 -120.457214)
		(end 211.349336 -120.457214)
		(width 0.381)
		(layer "F.Cu")
		(net "P3V3_AUX")
	)
	(segment
		(start 99.699318 -359.996232)
		(end 100.2665 -359.42905)
		(width 0.381)
		(layer "F.Cu")
		(net "P3V3_AUX")
	)
	(segment
		(start 212.98662 -125.851158)
		(end 213.01583 -125.821948)
		(width 0.381)
		(layer "F.Cu")
		(net "P3V3_AUX")
	)
	(segment
		(start 182.12308 -56.098948)
		(end 181.86908 -56.352948)
		(width 0.381)
		(layer "F.Cu")
		(net "P3V3_AUX")
	)
	(segment
		(start 151.5872 -127.497078)
		(end 152.059894 -127.024384)
		(width 0.381)
		(layer "F.Cu")
		(net "P3V3_AUX")
	)
	(segment
		(start 28.177998 -71.88073)
		(end 28.113736 -71.816468)
		(width 0.381)
		(layer "F.Cu")
		(net "P3V3_AUX")
	)
	(segment
		(start 49.724564 -394.765276)
		(end 48.9204 -395.56944)
		(width 0.4572)
		(layer "F.Cu")
		(net "P3V3_AUX")
	)
	(segment
		(start 106.11231 -64.82207)
		(end 106.11231 -64.049148)
		(width 0.381)
		(layer "F.Cu")
		(net "P3V3_AUX")
	)
	(segment
		(start 73.475596 -74.501502)
		(end 73.475596 -73.828148)
		(width 0.381)
		(layer "F.Cu")
		(net "P3V3_AUX")
	)
	(segment
		(start 176.6824 -93.138498)
		(end 176.6824 -92.527628)
		(width 0.381)
		(layer "F.Cu")
		(net "P3V3_AUX")
	)
	(segment
		(start 447.91249 -41.747948)
		(end 447.91249 -42.382948)
		(width 0.381)
		(layer "F.Cu")
		(net "P3V3_AUX")
	)
	(segment
		(start 310.621426 -29.277818)
		(end 310.621426 -28.951428)
		(width 0.381)
		(layer "F.Cu")
		(net "P3V3_AUX")
	)
	(segment
		(start 159.909256 -64.294258)
		(end 159.274256 -64.294258)
		(width 0.381)
		(layer "F.Cu")
		(net "P3V3_AUX")
	)
	(segment
		(start 213.72068 -13.605256)
		(end 214.019384 -13.90396)
		(width 0.381)
		(layer "F.Cu")
		(net "P3V3_AUX")
	)
	(segment
		(start 39.990014 -401.176236)
		(end 39.990014 -401.810728)
		(width 0.4572)
		(layer "F.Cu")
		(net "P3V3_AUX")
	)
	(segment
		(start 124.450348 -137.546588)
		(end 124.724922 -137.821162)
		(width 0.381)
		(layer "F.Cu")
		(net "P3V3_AUX")
	)
	(segment
		(start 333.23784 -14.118082)
		(end 332.701392 -14.118082)
		(width 0.381)
		(layer "F.Cu")
		(net "P3V3_AUX")
	)
	(segment
		(start 102.063296 -420.563548)
		(end 102.063296 -420.929816)
		(width 0.381)
		(layer "F.Cu")
		(net "P3V3_AUX")
	)
	(segment
		(start 28.113736 -71.816468)
		(end 26.2509 -71.816468)
		(width 0.381)
		(layer "F.Cu")
		(net "P3V3_AUX")
	)
	(segment
		(start 176.829212 -426.430948)
		(end 176.57953 -426.430948)
		(width 0.381)
		(layer "F.Cu")
		(net "P3V3_AUX")
	)
	(segment
		(start 23.894796 -389.094726)
		(end 24.580596 -388.408926)
		(width 0.254)
		(layer "F.Cu")
		(net "P3V3_AUX")
	)
	(segment
		(start 127.98425 -21.951188)
		(end 127.80518 -21.772118)
		(width 0.381)
		(layer "F.Cu")
		(net "P3V3_AUX")
	)
	(segment
		(start 109.980984 -394.15974)
		(end 110.590584 -394.15974)
		(width 0.381)
		(layer "F.Cu")
		(net "P3V3_AUX")
	)
	(segment
		(start 109.737906 -32.64281)
		(end 109.737906 -31.49981)
		(width 0.381)
		(layer "F.Cu")
		(net "P3V3_AUX")
	)
	(segment
		(start 227.32111 -233.025188)
		(end 227.448618 -233.152696)
		(width 0.381)
		(layer "F.Cu")
		(net "P3V3_AUX")
	)
	(segment
		(start 169.04843 -424.906948)
		(end 168.43883 -424.906948)
		(width 0.381)
		(layer "F.Cu")
		(net "P3V3_AUX")
	)
	(segment
		(start 117.07622 -417.393628)
		(end 116.75618 -417.713668)
		(width 0.381)
		(layer "F.Cu")
		(net "P3V3_AUX")
	)
	(segment
		(start 114.660172 -20.010628)
		(end 114.660172 -19.30019)
		(width 0.381)
		(layer "F.Cu")
		(net "P3V3_AUX")
	)
	(segment
		(start 92.36075 -33.061148)
		(end 92.36075 -32.426148)
		(width 0.381)
		(layer "F.Cu")
		(net "P3V3_AUX")
	)
	(segment
		(start 200.18248 -107.798362)
		(end 200.407016 -108.022898)
		(width 0.381)
		(layer "F.Cu")
		(net "P3V3_AUX")
	)
	(segment
		(start 21.211032 -166.767256)
		(end 21.73351 -166.767256)
		(width 0.381)
		(layer "F.Cu")
		(net "P3V3_AUX")
	)
	(segment
		(start 109.144308 -74.463402)
		(end 109.144308 -73.853802)
		(width 0.381)
		(layer "F.Cu")
		(net "P3V3_AUX")
	)
	(segment
		(start 321.863466 -24.579072)
		(end 321.863466 -25.539192)
		(width 0.381)
		(layer "F.Cu")
		(net "P3V3_AUX")
	)
	(segment
		(start 192.947798 -79.14259)
		(end 193.033142 -79.057246)
		(width 0.381)
		(layer "F.Cu")
		(net "P3V3_AUX")
	)
	(segment
		(start 140.40993 -43.652948)
		(end 141.01953 -43.652948)
		(width 0.381)
		(layer "F.Cu")
		(net "P3V3_AUX")
	)
	(segment
		(start 169.57294 -28.825698)
		(end 171.23283 -28.825698)
		(width 0.381)
		(layer "F.Cu")
		(net "P3V3_AUX")
	)
	(segment
		(start 110.146084 -31.037784)
		(end 109.737906 -31.445962)
		(width 0.381)
		(layer "F.Cu")
		(net "P3V3_AUX")
	)
	(segment
		(start 252.73 -38.324282)
		(end 252.73 -37.775896)
		(width 0.4572)
		(layer "F.Cu")
		(net "P3V3_AUX")
	)
	(segment
		(start 286.255714 -319.716658)
		(end 285.150814 -319.716658)
		(width 0.381)
		(layer "F.Cu")
		(net "P3V3_AUX")
	)
	(segment
		(start 391.769854 -38.661086)
		(end 391.769854 -37.518594)
		(width 0.381)
		(layer "F.Cu")
		(net "P3V3_AUX")
	)
	(segment
		(start 368.978942 -355.352604)
		(end 369.324128 -355.69779)
		(width 0.381)
		(layer "F.Cu")
		(net "P3V3_AUX")
	)
	(segment
		(start 160.43783 -116.296948)
		(end 159.82188 -116.296948)
		(width 0.381)
		(layer "F.Cu")
		(net "P3V3_AUX")
	)
	(segment
		(start 194.33413 -354.904548)
		(end 195.22948 -354.904548)
		(width 0.381)
		(layer "F.Cu")
		(net "P3V3_AUX")
	)
	(segment
		(start 169.036238 -417.237418)
		(end 168.426638 -417.237418)
		(width 0.381)
		(layer "F.Cu")
		(net "P3V3_AUX")
	)
	(segment
		(start 271.168114 -319.716658)
		(end 270.063214 -319.716658)
		(width 0.381)
		(layer "F.Cu")
		(net "P3V3_AUX")
	)
	(segment
		(start 71.393558 -64.682624)
		(end 71.393558 -63.998348)
		(width 0.381)
		(layer "F.Cu")
		(net "P3V3_AUX")
	)
	(segment
		(start 369.590828 -391.797286)
		(end 370.285518 -391.797286)
		(width 0.381)
		(layer "F.Cu")
		(net "P3V3_AUX")
	)
	(segment
		(start 334.499458 -46.049946)
		(end 334.099408 -45.649896)
		(width 0.2032)
		(layer "F.Cu")
		(net "P3V3_AUX")
	)
	(segment
		(start 357.335582 -398.789398)
		(end 356.725982 -398.789398)
		(width 0.381)
		(layer "F.Cu")
		(net "P3V3_AUX")
	)
	(segment
		(start 102.67061 -74.55916)
		(end 102.67061 -73.94956)
		(width 0.381)
		(layer "F.Cu")
		(net "P3V3_AUX")
	)
	(segment
		(start 309.77205 -23.7744)
		(end 309.9054 -23.7744)
		(width 0.381)
		(layer "F.Cu")
		(net "P3V3_AUX")
	)
	(segment
		(start 293.645844 -413.05988)
		(end 292.688518 -413.05988)
		(width 0.381)
		(layer "F.Cu")
		(net "P3V3_AUX")
	)
	(segment
		(start 82.28965 -41.036748)
		(end 82.702654 -40.623744)
		(width 0.381)
		(layer "F.Cu")
		(net "P3V3_AUX")
	)
	(segment
		(start 385.261104 -29.670502)
		(end 385.261104 -31.018988)
		(width 0.381)
		(layer "F.Cu")
		(net "P3V3_AUX")
	)
	(segment
		(start 365.771684 -403.972014)
		(end 364.59668 -403.972014)
		(width 0.381)
		(layer "F.Cu")
		(net "P3V3_AUX")
	)
	(segment
		(start 450.3801 -112.912652)
		(end 450.3801 -113.307368)
		(width 0.381)
		(layer "F.Cu")
		(net "P3V3_AUX")
	)
	(segment
		(start 131.866894 -132.707126)
		(end 132.476494 -132.707126)
		(width 0.381)
		(layer "F.Cu")
		(net "P3V3_AUX")
	)
	(segment
		(start 104.42575 -408.2796)
		(end 103.7844 -408.2796)
		(width 0.381)
		(layer "F.Cu")
		(net "P3V3_AUX")
	)
	(segment
		(start 200.18248 -107.427268)
		(end 200.18248 -107.798362)
		(width 0.381)
		(layer "F.Cu")
		(net "P3V3_AUX")
	)
	(segment
		(start 429.29556 -110.27664)
		(end 429.299116 -110.273084)
		(width 0.4572)
		(layer "F.Cu")
		(net "P3V3_AUX")
	)
	(segment
		(start 82.384138 -152.160478)
		(end 82.384138 -149.900132)
		(width 0.381)
		(layer "F.Cu")
		(net "P3V3_AUX")
	)
	(via
		(at 466.28304 -47.186088)
		(size 0.508)
		(drill 0.254)
		(layers "F.Cu" "B.Cu")
		(net "P3V3_AUX")
	)
	(via
		(at 297.171872 -407.00198)
		(size 0.508)
		(drill 0.254)
		(layers "F.Cu" "B.Cu")
		(net "P3V3_AUX")
	)
	(via
		(at 11.6078 -183.9214)
		(size 0.508)
		(drill 0.254)
		(layers "F.Cu" "B.Cu")
		(net "P3V3_AUX")
	)
	(via
		(at 318.8081 -132.250688)
		(size 0.508)
		(drill 0.254)
		(layers "F.Cu" "B.Cu")
		(net "P3V3_AUX")
	)
	(via
		(at 18.44294 -112.969548)
		(size 0.508)
		(drill 0.254)
		(layers "F.Cu" "B.Cu")
		(net "P3V3_AUX")
	)
	(via
		(at 319.716658 -13.223494)
		(size 0.508)
		(drill 0.254)
		(layers "F.Cu" "B.Cu")
		(net "P3V3_AUX")
	)
	(via
		(at 114.81308 -401.424648)
		(size 0.508)
		(drill 0.254)
		(layers "F.Cu" "B.Cu")
		(net "P3V3_AUX")
	)
	(via
		(at 276.18182 -96.329754)
		(size 0.508)
		(drill 0.254)
		(layers "F.Cu" "B.Cu")
		(net "P3V3_AUX")
	)
	(via
		(at 224.50298 -70.053708)
		(size 0.508)
		(drill 0.254)
		(layers "F.Cu" "B.Cu")
		(net "P3V3_AUX")
	)
	(via
		(at 370.618258 -416.128708)
		(size 0.508)
		(drill 0.254)
		(layers "F.Cu" "B.Cu")
		(net "P3V3_AUX")
	)
	(via
		(at 441.325 -56.124348)
		(size 0.508)
		(drill 0.254)
		(layers "F.Cu" "B.Cu")
		(net "P3V3_AUX")
	)
	(via
		(at 70.504812 -129.295906)
		(size 0.508)
		(drill 0.254)
		(layers "F.Cu" "B.Cu")
		(net "P3V3_AUX")
	)
	(via
		(at 198.12508 -113.102898)
		(size 0.508)
		(drill 0.254)
		(layers "F.Cu" "B.Cu")
		(net "P3V3_AUX")
	)
	(via
		(at 209.5754 -119.1006)
		(size 0.508)
		(drill 0.254)
		(layers "F.Cu" "B.Cu")
		(net "P3V3_AUX")
	)
	(via
		(at 310.4134 -23.2664)
		(size 0.508)
		(drill 0.254)
		(layers "F.Cu" "B.Cu")
		(net "P3V3_AUX")
	)
	(via
		(at 172.62856 -409.956)
		(size 0.508)
		(drill 0.254)
		(layers "F.Cu" "B.Cu")
		(net "P3V3_AUX")
	)
	(via
		(at 24.543004 -186.991498)
		(size 0.508)
		(drill 0.254)
		(layers "F.Cu" "B.Cu")
		(net "P3V3_AUX")
	)
	(via
		(at 106.654854 -29.842714)
		(size 0.508)
		(drill 0.254)
		(layers "F.Cu" "B.Cu")
		(net "P3V3_AUX")
	)
	(via
		(at 452.710296 -108.059728)
		(size 0.508)
		(drill 0.254)
		(layers "F.Cu" "B.Cu")
		(net "P3V3_AUX")
	)
	(via
		(at 164.52215 -417.504626)
		(size 0.508)
		(drill 0.254)
		(layers "F.Cu" "B.Cu")
		(net "P3V3_AUX")
	)
	(via
		(at 14.426946 -391.183876)
		(size 0.508)
		(drill 0.254)
		(layers "F.Cu" "B.Cu")
		(net "P3V3_AUX")
	)
	(via
		(at 202.971146 -319.716658)
		(size 0.4572)
		(drill 0.2032)
		(layers "F.Cu" "B.Cu")
		(net "P3V3_AUX")
	)
	(via
		(at 165.30066 -35.737546)
		(size 0.508)
		(drill 0.254)
		(layers "F.Cu" "B.Cu")
		(net "P3V3_AUX")
	)
	(via
		(at 156.37129 -80.679798)
		(size 0.508)
		(drill 0.254)
		(layers "F.Cu" "B.Cu")
		(net "P3V3_AUX")
	)
	(via
		(at 370.51488 -36.921948)
		(size 0.508)
		(drill 0.254)
		(layers "F.Cu" "B.Cu")
		(net "P3V3_AUX")
	)
	(via
		(at 293.82466 -92.260674)
		(size 0.508)
		(drill 0.254)
		(layers "F.Cu" "B.Cu")
		(net "P3V3_AUX")
	)
	(via
		(at 209.54492 -104.96804)
		(size 0.508)
		(drill 0.254)
		(layers "F.Cu" "B.Cu")
		(net "P3V3_AUX")
	)
	(via
		(at 434.086 -105.628948)
		(size 0.508)
		(drill 0.254)
		(layers "F.Cu" "B.Cu")
		(net "P3V3_AUX")
	)
	(via
		(at 159.766 -17.109948)
		(size 0.508)
		(drill 0.254)
		(layers "F.Cu" "B.Cu")
		(net "P3V3_AUX")
	)
	(via
		(at 305.094132 -14.51102)
		(size 0.508)
		(drill 0.254)
		(layers "F.Cu" "B.Cu")
		(net "P3V3_AUX")
	)
	(via
		(at 96.294448 -73.758044)
		(size 0.508)
		(drill 0.254)
		(layers "F.Cu" "B.Cu")
		(net "P3V3_AUX")
	)
	(via
		(at 115.21313 -394.07338)
		(size 0.508)
		(drill 0.254)
		(layers "F.Cu" "B.Cu")
		(net "P3V3_AUX")
	)
	(via
		(at 37.976048 -130.76174)
		(size 0.508)
		(drill 0.254)
		(layers "F.Cu" "B.Cu")
		(net "P3V3_AUX")
	)
	(via
		(at 254.381 -38.324282)
		(size 0.508)
		(drill 0.254)
		(layers "F.Cu" "B.Cu")
		(net "P3V3_AUX")
	)
	(via
		(at 70.231 -112.994948)
		(size 0.508)
		(drill 0.254)
		(layers "F.Cu" "B.Cu")
		(net "P3V3_AUX")
	)
	(via
		(at 21.90623 -430.367948)
		(size 0.508)
		(drill 0.254)
		(layers "F.Cu" "B.Cu")
		(net "P3V3_AUX")
	)
	(via
		(at 140.30833 -34.12236)
		(size 0.508)
		(drill 0.254)
		(layers "F.Cu" "B.Cu")
		(net "P3V3_AUX")
	)
	(via
		(at 118.954042 -64.658748)
		(size 0.508)
		(drill 0.254)
		(layers "F.Cu" "B.Cu")
		(net "P3V3_AUX")
	)
	(via
		(at 147.95754 -75.350878)
		(size 0.508)
		(drill 0.254)
		(layers "F.Cu" "B.Cu")
		(net "P3V3_AUX")
	)
	(via
		(at 325.837296 -27.653488)
		(size 0.508)
		(drill 0.254)
		(layers "F.Cu" "B.Cu")
		(net "P3V3_AUX")
	)
	(via
		(at 366.84585 -14.544548)
		(size 0.508)
		(drill 0.254)
		(layers "F.Cu" "B.Cu")
		(net "P3V3_AUX")
	)
	(via
		(at 15.933674 -77.578204)
		(size 0.508)
		(drill 0.254)
		(layers "F.Cu" "B.Cu")
		(net "P3V3_AUX")
	)
	(via
		(at 192.454022 -24.491442)
		(size 0.508)
		(drill 0.254)
		(layers "F.Cu" "B.Cu")
		(net "P3V3_AUX")
	)
	(via
		(at 117.50548 -30.720792)
		(size 0.508)
		(drill 0.254)
		(layers "F.Cu" "B.Cu")
		(net "P3V3_AUX")
	)
	(via
		(at 151.710898 -23.942548)
		(size 0.508)
		(drill 0.254)
		(layers "F.Cu" "B.Cu")
		(net "P3V3_AUX")
	)
	(via
		(at 306.83454 -431.918618)
		(size 0.508)
		(drill 0.254)
		(layers "F.Cu" "B.Cu")
		(net "P3V3_AUX")
	)
	(via
		(at 390.02208 -38.496748)
		(size 0.508)
		(drill 0.254)
		(layers "F.Cu" "B.Cu")
		(net "P3V3_AUX")
	)
	(via
		(at 45.90288 -187.416948)
		(size 0.508)
		(drill 0.254)
		(layers "F.Cu" "B.Cu")
		(net "P3V3_AUX")
	)
	(via
		(at 132.55879 -114.920268)
		(size 0.508)
		(drill 0.254)
		(layers "F.Cu" "B.Cu")
		(net "P3V3_AUX")
	)
	(via
		(at 83.566508 -73.828148)
		(size 0.508)
		(drill 0.254)
		(layers "F.Cu" "B.Cu")
		(net "P3V3_AUX")
	)
	(via
		(at 102.39375 -361.952032)
		(size 0.508)
		(drill 0.254)
		(layers "F.Cu" "B.Cu")
		(net "P3V3_AUX")
	)
	(via
		(at 18.44294 -112.080548)
		(size 0.508)
		(drill 0.254)
		(layers "F.Cu" "B.Cu")
		(net "P3V3_AUX")
	)
	(via
		(at 418.41674 -104.501188)
		(size 0.508)
		(drill 0.254)
		(layers "F.Cu" "B.Cu")
		(net "P3V3_AUX")
	)
	(via
		(at 127.23495 -58.740548)
		(size 0.508)
		(drill 0.254)
		(layers "F.Cu" "B.Cu")
		(net "P3V3_AUX")
	)
	(via
		(at 140.984478 -368.14633)
		(size 0.508)
		(drill 0.254)
		(layers "F.Cu" "B.Cu")
		(net "P3V3_AUX")
	)
	(via
		(at 110.323122 -140.403326)
		(size 0.508)
		(drill 0.254)
		(layers "F.Cu" "B.Cu")
		(net "P3V3_AUX")
	)
	(via
		(at 8.40867 -77.462888)
		(size 0.508)
		(drill 0.254)
		(layers "F.Cu" "B.Cu")
		(net "P3V3_AUX")
	)
	(via
		(at 317.50254 -29.748734)
		(size 0.508)
		(drill 0.254)
		(layers "F.Cu" "B.Cu")
		(net "P3V3_AUX")
	)
	(via
		(at 23.241 -398.035526)
		(size 0.508)
		(drill 0.254)
		(layers "F.Cu" "B.Cu")
		(net "P3V3_AUX")
	)
	(via
		(at 137.78484 -25.189688)
		(size 0.508)
		(drill 0.254)
		(layers "F.Cu" "B.Cu")
		(net "P3V3_AUX")
	)
	(via
		(at 208.89341 -121.8184)
		(size 0.508)
		(drill 0.254)
		(layers "F.Cu" "B.Cu")
		(net "P3V3_AUX")
	)
	(via
		(at 50.583846 -108.14177)
		(size 0.508)
		(drill 0.254)
		(layers "F.Cu" "B.Cu")
		(net "P3V3_AUX")
	)
	(via
		(at 177.22342 -426.07484)
		(size 0.508)
		(drill 0.254)
		(layers "F.Cu" "B.Cu")
		(net "P3V3_AUX")
	)
	(via
		(at 416.5092 -108.453428)
		(size 0.508)
		(drill 0.254)
		(layers "F.Cu" "B.Cu")
		(net "P3V3_AUX")
	)
	(via
		(at 65.20053 -117.123718)
		(size 0.508)
		(drill 0.254)
		(layers "F.Cu" "B.Cu")
		(net "P3V3_AUX")
	)
	(via
		(at 171.52493 -101.564948)
		(size 0.508)
		(drill 0.254)
		(layers "F.Cu" "B.Cu")
		(net "P3V3_AUX")
	)
	(via
		(at 110.323122 -126.678182)
		(size 0.508)
		(drill 0.254)
		(layers "F.Cu" "B.Cu")
		(net "P3V3_AUX")
	)
	(via
		(at 441.325 -55.362348)
		(size 0.508)
		(drill 0.254)
		(layers "F.Cu" "B.Cu")
		(net "P3V3_AUX")
	)
	(via
		(at 419.382448 -138.575288)
		(size 0.508)
		(drill 0.254)
		(layers "F.Cu" "B.Cu")
		(net "P3V3_AUX")
	)
	(via
		(at 369.884198 -184.64403)
		(size 0.508)
		(drill 0.254)
		(layers "F.Cu" "B.Cu")
		(net "P3V3_AUX")
	)
	(via
		(at 311.371996 -41.519348)
		(size 0.508)
		(drill 0.254)
		(layers "F.Cu" "B.Cu")
		(net "P3V3_AUX")
	)
	(via
		(at 466.948266 -115.295934)
		(size 0.508)
		(drill 0.254)
		(layers "F.Cu" "B.Cu")
		(net "P3V3_AUX")
	)
	(via
		(at 148.09343 -124.005848)
		(size 0.508)
		(drill 0.254)
		(layers "F.Cu" "B.Cu")
		(net "P3V3_AUX")
	)
	(via
		(at 176.58588 -101.564948)
		(size 0.508)
		(drill 0.254)
		(layers "F.Cu" "B.Cu")
		(net "P3V3_AUX")
	)
	(via
		(at 63.801498 -318.77635)
		(size 0.508)
		(drill 0.254)
		(layers "F.Cu" "B.Cu")
		(net "P3V3_AUX")
	)
	(via
		(at 93.090492 -73.727056)
		(size 0.508)
		(drill 0.254)
		(layers "F.Cu" "B.Cu")
		(net "P3V3_AUX")
	)
	(via
		(at 319.174622 -57.396888)
		(size 0.508)
		(drill 0.254)
		(layers "F.Cu" "B.Cu")
		(net "P3V3_AUX")
	)
	(via
		(at 21.45538 -169.850308)
		(size 0.508)
		(drill 0.254)
		(layers "F.Cu" "B.Cu")
		(net "P3V3_AUX")
	)
	(via
		(at 150.89886 -127.497078)
		(size 0.508)
		(drill 0.254)
		(layers "F.Cu" "B.Cu")
		(net "P3V3_AUX")
	)
	(via
		(at 101.851714 -359.985056)
		(size 0.508)
		(drill 0.254)
		(layers "F.Cu" "B.Cu")
		(net "P3V3_AUX")
	)
	(via
		(at 50.583846 -105.34777)
		(size 0.508)
		(drill 0.254)
		(layers "F.Cu" "B.Cu")
		(net "P3V3_AUX")
	)
	(via
		(at 22.23008 -99.413314)
		(size 0.508)
		(drill 0.254)
		(layers "F.Cu" "B.Cu")
		(net "P3V3_AUX")
	)
	(via
		(at 274.094956 -19.24685)
		(size 0.508)
		(drill 0.254)
		(layers "F.Cu" "B.Cu")
		(net "P3V3_AUX")
	)
	(via
		(at 37.01923 -434.939948)
		(size 0.508)
		(drill 0.254)
		(layers "F.Cu" "B.Cu")
		(net "P3V3_AUX")
	)
	(via
		(at 441.325 -53.838348)
		(size 0.508)
		(drill 0.254)
		(layers "F.Cu" "B.Cu")
		(net "P3V3_AUX")
	)
	(via
		(at 122.236484 -40.986456)
		(size 0.508)
		(drill 0.254)
		(layers "F.Cu" "B.Cu")
		(net "P3V3_AUX")
	)
	(via
		(at 23.037292 -417.159948)
		(size 0.508)
		(drill 0.254)
		(layers "F.Cu" "B.Cu")
		(net "P3V3_AUX")
	)
	(via
		(at 213.19744 -29.174948)
		(size 0.508)
		(drill 0.254)
		(layers "F.Cu" "B.Cu")
		(net "P3V3_AUX")
	)
	(via
		(at 25.903682 -131.5974)
		(size 0.508)
		(drill 0.254)
		(layers "F.Cu" "B.Cu")
		(net "P3V3_AUX")
	)
	(via
		(at 350.790764 -361.952032)
		(size 0.508)
		(drill 0.254)
		(layers "F.Cu" "B.Cu")
		(net "P3V3_AUX")
	)
	(via
		(at 179.2224 -92.527628)
		(size 0.508)
		(drill 0.254)
		(layers "F.Cu" "B.Cu")
		(net "P3V3_AUX")
	)
	(via
		(at 302.85436 -431.907188)
		(size 0.508)
		(drill 0.254)
		(layers "F.Cu" "B.Cu")
		(net "P3V3_AUX")
	)
	(via
		(at 291.32784 -411.21584)
		(size 0.508)
		(drill 0.254)
		(layers "F.Cu" "B.Cu")
		(net "P3V3_AUX")
	)
	(via
		(at 173.56328 -124.628148)
		(size 0.508)
		(drill 0.254)
		(layers "F.Cu" "B.Cu")
		(net "P3V3_AUX")
	)
	(via
		(at 441.325 -54.600348)
		(size 0.508)
		(drill 0.254)
		(layers "F.Cu" "B.Cu")
		(net "P3V3_AUX")
	)
	(via
		(at 49.775364 -391.887202)
		(size 0.508)
		(drill 0.254)
		(layers "F.Cu" "B.Cu")
		(net "P3V3_AUX")
	)
	(via
		(at 156.01188 -113.756948)
		(size 0.508)
		(drill 0.254)
		(layers "F.Cu" "B.Cu")
		(net "P3V3_AUX")
	)
	(via
		(at 451.809612 -55.734712)
		(size 0.508)
		(drill 0.254)
		(layers "F.Cu" "B.Cu")
		(net "P3V3_AUX")
	)
	(via
		(at 106.9848 -59.070748)
		(size 0.508)
		(drill 0.254)
		(layers "F.Cu" "B.Cu")
		(net "P3V3_AUX")
	)
	(via
		(at 149.41423 -33.564068)
		(size 0.508)
		(drill 0.254)
		(layers "F.Cu" "B.Cu")
		(net "P3V3_AUX")
	)
	(via
		(at 309.64124 -192.347088)
		(size 0.508)
		(drill 0.254)
		(layers "F.Cu" "B.Cu")
		(net "P3V3_AUX")
	)
	(via
		(at 160.22193 -60.162948)
		(size 0.508)
		(drill 0.254)
		(layers "F.Cu" "B.Cu")
		(net "P3V3_AUX")
	)
	(via
		(at 159.82188 -117.566948)
		(size 0.508)
		(drill 0.254)
		(layers "F.Cu" "B.Cu")
		(net "P3V3_AUX")
	)
	(via
		(at 116.71808 -392.928348)
		(size 0.508)
		(drill 0.254)
		(layers "F.Cu" "B.Cu")
		(net "P3V3_AUX")
	)
	(via
		(at 32.86125 -69.7992)
		(size 0.508)
		(drill 0.254)
		(layers "F.Cu" "B.Cu")
		(net "P3V3_AUX")
	)
	(via
		(at 69.042534 -63.998348)
		(size 0.508)
		(drill 0.254)
		(layers "F.Cu" "B.Cu")
		(net "P3V3_AUX")
	)
	(via
		(at 181.378098 -189.44971)
		(size 0.508)
		(drill 0.254)
		(layers "F.Cu" "B.Cu")
		(net "P3V3_AUX")
	)
	(via
		(at 461.557878 -94.952566)
		(size 0.508)
		(drill 0.254)
		(layers "F.Cu" "B.Cu")
		(net "P3V3_AUX")
	)
	(via
		(at 328.092816 -27.794458)
		(size 0.508)
		(drill 0.254)
		(layers "F.Cu" "B.Cu")
		(net "P3V3_AUX")
	)
	(via
		(at 37.987478 -125.565662)
		(size 0.508)
		(drill 0.254)
		(layers "F.Cu" "B.Cu")
		(net "P3V3_AUX")
	)
	(via
		(at 320.351658 -13.223494)
		(size 0.508)
		(drill 0.254)
		(layers "F.Cu" "B.Cu")
		(net "P3V3_AUX")
	)
	(via
		(at 20.576032 -403.827488)
		(size 0.508)
		(drill 0.254)
		(layers "F.Cu" "B.Cu")
		(net "P3V3_AUX")
	)
	(via
		(at 181.374034 -422.615868)
		(size 0.508)
		(drill 0.254)
		(layers "F.Cu" "B.Cu")
		(net "P3V3_AUX")
	)
	(via
		(at 21.072094 -166.906194)
		(size 0.508)
		(drill 0.254)
		(layers "F.Cu" "B.Cu")
		(net "P3V3_AUX")
	)
	(via
		(at 314.3631 -132.250688)
		(size 0.508)
		(drill 0.254)
		(layers "F.Cu" "B.Cu")
		(net "P3V3_AUX")
	)
	(via
		(at 183.257952 -409.18003)
		(size 0.508)
		(drill 0.254)
		(layers "F.Cu" "B.Cu")
		(net "P3V3_AUX")
	)
	(via
		(at 431.61331 -132.462778)
		(size 0.508)
		(drill 0.254)
		(layers "F.Cu" "B.Cu")
		(net "P3V3_AUX")
	)
	(via
		(at 75.738736 -73.828148)
		(size 0.508)
		(drill 0.254)
		(layers "F.Cu" "B.Cu")
		(net "P3V3_AUX")
	)
	(via
		(at 446.4431 -117.193822)
		(size 0.508)
		(drill 0.254)
		(layers "F.Cu" "B.Cu")
		(net "P3V3_AUX")
	)
	(via
		(at 163.5252 -77.862938)
		(size 0.508)
		(drill 0.254)
		(layers "F.Cu" "B.Cu")
		(net "P3V3_AUX")
	)
	(via
		(at 105.71988 -92.471748)
		(size 0.508)
		(drill 0.254)
		(layers "F.Cu" "B.Cu")
		(net "P3V3_AUX")
	)
	(via
		(at 416.5092 -111.501428)
		(size 0.508)
		(drill 0.254)
		(layers "F.Cu" "B.Cu")
		(net "P3V3_AUX")
	)
	(via
		(at 383.3749 -188.29401)
		(size 0.508)
		(drill 0.254)
		(layers "F.Cu" "B.Cu")
		(net "P3V3_AUX")
	)
	(via
		(at 298.66082 -420.276528)
		(size 0.508)
		(drill 0.254)
		(layers "F.Cu" "B.Cu")
		(net "P3V3_AUX")
	)
	(via
		(at 157.70098 -193.566288)
		(size 0.508)
		(drill 0.254)
		(layers "F.Cu" "B.Cu")
		(net "P3V3_AUX")
	)
	(via
		(at 254.36576 -91.364308)
		(size 0.508)
		(drill 0.254)
		(layers "F.Cu" "B.Cu")
		(net "P3V3_AUX")
	)
	(via
		(at 30.159198 -186.874404)
		(size 0.508)
		(drill 0.254)
		(layers "F.Cu" "B.Cu")
		(net "P3V3_AUX")
	)
	(via
		(at 28.638246 -388.262876)
		(size 0.508)
		(drill 0.254)
		(layers "F.Cu" "B.Cu")
		(net "P3V3_AUX")
	)
	(via
		(at 415.7472 -110.739428)
		(size 0.508)
		(drill 0.254)
		(layers "F.Cu" "B.Cu")
		(net "P3V3_AUX")
	)
	(via
		(at 342.70188 -35.651948)
		(size 0.508)
		(drill 0.254)
		(layers "F.Cu" "B.Cu")
		(net "P3V3_AUX")
	)
	(via
		(at 16.110966 -91.618308)
		(size 0.508)
		(drill 0.254)
		(layers "F.Cu" "B.Cu")
		(net "P3V3_AUX")
	)
	(via
		(at 259.26288 -78.977998)
		(size 0.508)
		(drill 0.254)
		(layers "F.Cu" "B.Cu")
		(net "P3V3_AUX")
	)
	(via
		(at 313.4741 -132.250688)
		(size 0.508)
		(drill 0.254)
		(layers "F.Cu" "B.Cu")
		(net "P3V3_AUX")
	)
	(via
		(at 159.181546 -30.272228)
		(size 0.508)
		(drill 0.254)
		(layers "F.Cu" "B.Cu")
		(net "P3V3_AUX")
	)
	(via
		(at 77.381354 -63.998348)
		(size 0.508)
		(drill 0.254)
		(layers "F.Cu" "B.Cu")
		(net "P3V3_AUX")
	)
	(via
		(at 303.707292 -148.887688)
		(size 0.508)
		(drill 0.254)
		(layers "F.Cu" "B.Cu")
		(net "P3V3_AUX")
	)
	(via
		(at 163.5252 -74.759058)
		(size 0.508)
		(drill 0.254)
		(layers "F.Cu" "B.Cu")
		(net "P3V3_AUX")
	)
	(via
		(at 452.710296 -102.598728)
		(size 0.508)
		(drill 0.254)
		(layers "F.Cu" "B.Cu")
		(net "P3V3_AUX")
	)
	(via
		(at 298.685204 -17.564354)
		(size 0.508)
		(drill 0.254)
		(layers "F.Cu" "B.Cu")
		(net "P3V3_AUX")
	)
	(via
		(at 160.002474 -319.716658)
		(size 0.4572)
		(drill 0.2032)
		(layers "F.Cu" "B.Cu")
		(net "P3V3_AUX")
	)
	(via
		(at 254.973074 -319.805558)
		(size 0.4572)
		(drill 0.2032)
		(layers "F.Cu" "B.Cu")
		(net "P3V3_AUX")
	)
	(via
		(at 333.508858 -46.100746)
		(size 0.4572)
		(drill 0.2032)
		(layers "F.Cu" "B.Cu")
		(net "P3V3_AUX")
	)
	(via
		(at 433.73294 -135.664702)
		(size 0.508)
		(drill 0.254)
		(layers "F.Cu" "B.Cu")
		(net "P3V3_AUX")
	)
	(via
		(at 214.33917 -22.278594)
		(size 0.508)
		(drill 0.254)
		(layers "F.Cu" "B.Cu")
		(net "P3V3_AUX")
	)
	(via
		(at 50.583846 -109.53877)
		(size 0.508)
		(drill 0.254)
		(layers "F.Cu" "B.Cu")
		(net "P3V3_AUX")
	)
	(via
		(at 308.908704 -14.412468)
		(size 0.508)
		(drill 0.254)
		(layers "F.Cu" "B.Cu")
		(net "P3V3_AUX")
	)
	(via
		(at 181.356 -126.017528)
		(size 0.508)
		(drill 0.254)
		(layers "F.Cu" "B.Cu")
		(net "P3V3_AUX")
	)
	(via
		(at 168.431972 -420.511478)
		(size 0.508)
		(drill 0.254)
		(layers "F.Cu" "B.Cu")
		(net "P3V3_AUX")
	)
	(via
		(at 133.015228 -78.115414)
		(size 0.508)
		(drill 0.254)
		(layers "F.Cu" "B.Cu")
		(net "P3V3_AUX")
	)
	(via
		(at 168.56583 -437.606948)
		(size 0.508)
		(drill 0.254)
		(layers "F.Cu" "B.Cu")
		(net "P3V3_AUX")
	)
	(via
		(at 312.01995 -23.241)
		(size 0.508)
		(drill 0.254)
		(layers "F.Cu" "B.Cu")
		(net "P3V3_AUX")
	)
	(via
		(at 445.027812 -57.588912)
		(size 0.508)
		(drill 0.254)
		(layers "F.Cu" "B.Cu")
		(net "P3V3_AUX")
	)
	(via
		(at 23.060152 -410.418534)
		(size 0.508)
		(drill 0.254)
		(layers "F.Cu" "B.Cu")
		(net "P3V3_AUX")
	)
	(via
		(at 66.167 -57.114948)
		(size 0.508)
		(drill 0.254)
		(layers "F.Cu" "B.Cu")
		(net "P3V3_AUX")
	)
	(via
		(at 162.49523 -437.479948)
		(size 0.508)
		(drill 0.254)
		(layers "F.Cu" "B.Cu")
		(net "P3V3_AUX")
	)
	(via
		(at 212.1916 -68.2752)
		(size 0.508)
		(drill 0.254)
		(layers "F.Cu" "B.Cu")
		(net "P3V3_AUX")
	)
	(via
		(at 419.10508 -104.508808)
		(size 0.508)
		(drill 0.254)
		(layers "F.Cu" "B.Cu")
		(net "P3V3_AUX")
	)
	(via
		(at 312.974228 -28.107386)
		(size 0.508)
		(drill 0.254)
		(layers "F.Cu" "B.Cu")
		(net "P3V3_AUX")
	)
	(via
		(at 105.973372 -73.983596)
		(size 0.508)
		(drill 0.254)
		(layers "F.Cu" "B.Cu")
		(net "P3V3_AUX")
	)
	(via
		(at 453.105012 -57.639712)
		(size 0.508)
		(drill 0.254)
		(layers "F.Cu" "B.Cu")
		(net "P3V3_AUX")
	)
	(via
		(at 379.7681 -93.939868)
		(size 0.508)
		(drill 0.254)
		(layers "F.Cu" "B.Cu")
		(net "P3V3_AUX")
	)
	(via
		(at 359.2449 -386.41909)
		(size 0.508)
		(drill 0.254)
		(layers "F.Cu" "B.Cu")
		(net "P3V3_AUX")
	)
	(via
		(at 121.37009 -426.075348)
		(size 0.508)
		(drill 0.254)
		(layers "F.Cu" "B.Cu")
		(net "P3V3_AUX")
	)
	(via
		(at 373.43588 -43.144948)
		(size 0.508)
		(drill 0.254)
		(layers "F.Cu" "B.Cu")
		(net "P3V3_AUX")
	)
	(via
		(at 311.6961 -132.250688)
		(size 0.508)
		(drill 0.254)
		(layers "F.Cu" "B.Cu")
		(net "P3V3_AUX")
	)
	(via
		(at 34.90468 -433.923948)
		(size 0.508)
		(drill 0.254)
		(layers "F.Cu" "B.Cu")
		(net "P3V3_AUX")
	)
	(via
		(at 213.61146 -134.565644)
		(size 0.508)
		(drill 0.254)
		(layers "F.Cu" "B.Cu")
		(net "P3V3_AUX")
	)
	(via
		(at 8.864346 -180.6956)
		(size 0.508)
		(drill 0.254)
		(layers "F.Cu" "B.Cu")
		(net "P3V3_AUX")
	)
	(via
		(at 442.087 -55.362348)
		(size 0.508)
		(drill 0.254)
		(layers "F.Cu" "B.Cu")
		(net "P3V3_AUX")
	)
	(via
		(at 351.233486 -235.708444)
		(size 0.4572)
		(drill 0.2032)
		(layers "F.Cu" "B.Cu")
		(net "P3V3_AUX")
	)
	(via
		(at 224.536762 -70.792848)
		(size 0.508)
		(drill 0.254)
		(layers "F.Cu" "B.Cu")
		(net "P3V3_AUX")
	)
	(via
		(at 159.7406 -109.4867)
		(size 0.508)
		(drill 0.254)
		(layers "F.Cu" "B.Cu")
		(net "P3V3_AUX")
	)
	(via
		(at 198.42353 -99.875848)
		(size 0.508)
		(drill 0.254)
		(layers "F.Cu" "B.Cu")
		(net "P3V3_AUX")
	)
	(via
		(at 185.47588 -132.933948)
		(size 0.508)
		(drill 0.254)
		(layers "F.Cu" "B.Cu")
		(net "P3V3_AUX")
	)
	(via
		(at 32.925258 -395.31544)
		(size 0.508)
		(drill 0.254)
		(layers "F.Cu" "B.Cu")
		(net "P3V3_AUX")
	)
	(via
		(at 6.9342 -194.1068)
		(size 0.508)
		(drill 0.254)
		(layers "F.Cu" "B.Cu")
		(net "P3V3_AUX")
	)
	(via
		(at 25.93848 -174.9171)
		(size 0.508)
		(drill 0.254)
		(layers "F.Cu" "B.Cu")
		(net "P3V3_AUX")
	)
	(via
		(at 132.476494 -134.104126)
		(size 0.508)
		(drill 0.254)
		(layers "F.Cu" "B.Cu")
		(net "P3V3_AUX")
	)
	(via
		(at 452.710296 -106.408728)
		(size 0.508)
		(drill 0.254)
		(layers "F.Cu" "B.Cu")
		(net "P3V3_AUX")
	)
	(via
		(at 315.189616 -38.504368)
		(size 0.508)
		(drill 0.254)
		(layers "F.Cu" "B.Cu")
		(net "P3V3_AUX")
	)
	(via
		(at 293.548562 -18.714466)
		(size 0.508)
		(drill 0.254)
		(layers "F.Cu" "B.Cu")
		(net "P3V3_AUX")
	)
	(via
		(at 110.590584 -394.15974)
		(size 0.508)
		(drill 0.254)
		(layers "F.Cu" "B.Cu")
		(net "P3V3_AUX")
	)
	(via
		(at 174.50943 -425.033948)
		(size 0.508)
		(drill 0.254)
		(layers "F.Cu" "B.Cu")
		(net "P3V3_AUX")
	)
	(via
		(at 133.20395 -125.758448)
		(size 0.508)
		(drill 0.254)
		(layers "F.Cu" "B.Cu")
		(net "P3V3_AUX")
	)
	(via
		(at 182.17388 -127.975868)
		(size 0.508)
		(drill 0.254)
		(layers "F.Cu" "B.Cu")
		(net "P3V3_AUX")
	)
	(via
		(at 305.080924 -426.179742)
		(size 0.508)
		(drill 0.254)
		(layers "F.Cu" "B.Cu")
		(net "P3V3_AUX")
	)
	(via
		(at 294.913304 -426.878496)
		(size 0.508)
		(drill 0.254)
		(layers "F.Cu" "B.Cu")
		(net "P3V3_AUX")
	)
	(via
		(at 469.50249 -43.735498)
		(size 0.508)
		(drill 0.254)
		(layers "F.Cu" "B.Cu")
		(net "P3V3_AUX")
	)
	(via
		(at 256.288286 -106.666792)
		(size 0.508)
		(drill 0.254)
		(layers "F.Cu" "B.Cu")
		(net "P3V3_AUX")
	)
	(via
		(at 317.0301 -132.250688)
		(size 0.508)
		(drill 0.254)
		(layers "F.Cu" "B.Cu")
		(net "P3V3_AUX")
	)
	(via
		(at 413.192214 -319.716658)
		(size 0.4572)
		(drill 0.2032)
		(layers "F.Cu" "B.Cu")
		(net "P3V3_AUX")
	)
	(via
		(at 103.776526 -235.993432)
		(size 0.4572)
		(drill 0.2032)
		(layers "F.Cu" "B.Cu")
		(net "P3V3_AUX")
	)
	(via
		(at 223.2914 -231.802432)
		(size 0.508)
		(drill 0.254)
		(layers "F.Cu" "B.Cu")
		(net "P3V3_AUX")
	)
	(via
		(at 45.90288 -186.654948)
		(size 0.508)
		(drill 0.254)
		(layers "F.Cu" "B.Cu")
		(net "P3V3_AUX")
	)
	(via
		(at 453.105012 -55.734712)
		(size 0.508)
		(drill 0.254)
		(layers "F.Cu" "B.Cu")
		(net "P3V3_AUX")
	)
	(via
		(at 32.30753 -430.875948)
		(size 0.508)
		(drill 0.254)
		(layers "F.Cu" "B.Cu")
		(net "P3V3_AUX")
	)
	(via
		(at 272.691606 -128.641094)
		(size 0.508)
		(drill 0.254)
		(layers "F.Cu" "B.Cu")
		(net "P3V3_AUX")
	)
	(via
		(at 217.72753 -132.629148)
		(size 0.508)
		(drill 0.254)
		(layers "F.Cu" "B.Cu")
		(net "P3V3_AUX")
	)
	(via
		(at 168.43883 -424.906948)
		(size 0.508)
		(drill 0.254)
		(layers "F.Cu" "B.Cu")
		(net "P3V3_AUX")
	)
	(via
		(at 423.195242 -389.600948)
		(size 0.508)
		(drill 0.254)
		(layers "F.Cu" "B.Cu")
		(net "P3V3_AUX")
	)
	(via
		(at 132.79247 -122.46737)
		(size 0.508)
		(drill 0.254)
		(layers "F.Cu" "B.Cu")
		(net "P3V3_AUX")
	)
	(via
		(at 107.8992 -410.6164)
		(size 0.508)
		(drill 0.254)
		(layers "F.Cu" "B.Cu")
		(net "P3V3_AUX")
	)
	(via
		(at 123.994926 -120.826784)
		(size 0.508)
		(drill 0.254)
		(layers "F.Cu" "B.Cu")
		(net "P3V3_AUX")
	)
	(via
		(at 443.1284 -53.101748)
		(size 0.508)
		(drill 0.254)
		(layers "F.Cu" "B.Cu")
		(net "P3V3_AUX")
	)
	(via
		(at 210.67268 -192.639188)
		(size 0.508)
		(drill 0.254)
		(layers "F.Cu" "B.Cu")
		(net "P3V3_AUX")
	)
	(via
		(at 307.04282 -319.199768)
		(size 0.4572)
		(drill 0.2032)
		(layers "F.Cu" "B.Cu")
		(net "P3V3_AUX")
	)
	(via
		(at 23.041102 -405.858218)
		(size 0.508)
		(drill 0.254)
		(layers "F.Cu" "B.Cu")
		(net "P3V3_AUX")
	)
	(via
		(at 210.4644 -15.685008)
		(size 0.508)
		(drill 0.254)
		(layers "F.Cu" "B.Cu")
		(net "P3V3_AUX")
	)
	(via
		(at 83.730592 -64.059308)
		(size 0.508)
		(drill 0.254)
		(layers "F.Cu" "B.Cu")
		(net "P3V3_AUX")
	)
	(via
		(at 290.100258 -148.958808)
		(size 0.508)
		(drill 0.254)
		(layers "F.Cu" "B.Cu")
		(net "P3V3_AUX")
	)
	(via
		(at 351.59188 -230.086662)
		(size 0.4572)
		(drill 0.2032)
		(layers "F.Cu" "B.Cu")
		(net "P3V3_AUX")
	)
	(via
		(at 368.243358 -91.953334)
		(size 0.508)
		(drill 0.254)
		(layers "F.Cu" "B.Cu")
		(net "P3V3_AUX")
	)
	(via
		(at 97.821242 -416.491928)
		(size 0.508)
		(drill 0.254)
		(layers "F.Cu" "B.Cu")
		(net "P3V3_AUX")
	)
	(via
		(at 87.0458 -35.474148)
		(size 0.508)
		(drill 0.254)
		(layers "F.Cu" "B.Cu")
		(net "P3V3_AUX")
	)
	(via
		(at 192.3161 -71.270368)
		(size 0.508)
		(drill 0.254)
		(layers "F.Cu" "B.Cu")
		(net "P3V3_AUX")
	)
	(via
		(at 29.897578 -394.654786)
		(size 0.508)
		(drill 0.254)
		(layers "F.Cu" "B.Cu")
		(net "P3V3_AUX")
	)
	(via
		(at 445.789812 -56.369712)
		(size 0.508)
		(drill 0.254)
		(layers "F.Cu" "B.Cu")
		(net "P3V3_AUX")
	)
	(via
		(at 283.42844 -28.926282)
		(size 0.508)
		(drill 0.254)
		(layers "F.Cu" "B.Cu")
		(net "P3V3_AUX")
	)
	(via
		(at 66.802 -57.876948)
		(size 0.508)
		(drill 0.254)
		(layers "F.Cu" "B.Cu")
		(net "P3V3_AUX")
	)
	(via
		(at 193.004186 -428.26686)
		(size 0.508)
		(drill 0.254)
		(layers "F.Cu" "B.Cu")
		(net "P3V3_AUX")
	)
	(via
		(at 366.2172 -413.6898)
		(size 0.508)
		(drill 0.254)
		(layers "F.Cu" "B.Cu")
		(net "P3V3_AUX")
	)
	(via
		(at 384.5306 -29.911548)
		(size 0.508)
		(drill 0.254)
		(layers "F.Cu" "B.Cu")
		(net "P3V3_AUX")
	)
	(via
		(at 22.23008 -97.083626)
		(size 0.508)
		(drill 0.254)
		(layers "F.Cu" "B.Cu")
		(net "P3V3_AUX")
	)
	(via
		(at 250.000516 -106.268266)
		(size 0.508)
		(drill 0.254)
		(layers "F.Cu" "B.Cu")
		(net "P3V3_AUX")
	)
	(via
		(at 31.770828 -438.681368)
		(size 0.508)
		(drill 0.254)
		(layers "F.Cu" "B.Cu")
		(net "P3V3_AUX")
	)
	(via
		(at 44.754546 -319.716658)
		(size 0.4572)
		(drill 0.2032)
		(layers "F.Cu" "B.Cu")
		(net "P3V3_AUX")
	)
	(via
		(at 319.152016 -55.235348)
		(size 0.508)
		(drill 0.254)
		(layers "F.Cu" "B.Cu")
		(net "P3V3_AUX")
	)
	(via
		(at 31.758382 -403.695408)
		(size 0.508)
		(drill 0.254)
		(layers "F.Cu" "B.Cu")
		(net "P3V3_AUX")
	)
	(via
		(at 447.91249 -42.382948)
		(size 0.508)
		(drill 0.254)
		(layers "F.Cu" "B.Cu")
		(net "P3V3_AUX")
	)
	(via
		(at 180.79212 -410.10586)
		(size 0.508)
		(drill 0.254)
		(layers "F.Cu" "B.Cu")
		(net "P3V3_AUX")
	)
	(via
		(at 25.781 -407.5176)
		(size 0.508)
		(drill 0.254)
		(layers "F.Cu" "B.Cu")
		(net "P3V3_AUX")
	)
	(via
		(at 297.480228 -387.143498)
		(size 0.508)
		(drill 0.254)
		(layers "F.Cu" "B.Cu")
		(net "P3V3_AUX")
	)
	(via
		(at 85.598 -55.717948)
		(size 0.508)
		(drill 0.254)
		(layers "F.Cu" "B.Cu")
		(net "P3V3_AUX")
	)
	(via
		(at 176.6824 -92.527628)
		(size 0.508)
		(drill 0.254)
		(layers "F.Cu" "B.Cu")
		(net "P3V3_AUX")
	)
	(via
		(at 429.546766 -127.431038)
		(size 0.508)
		(drill 0.254)
		(layers "F.Cu" "B.Cu")
		(net "P3V3_AUX")
	)
	(via
		(at 443.8904 -53.101748)
		(size 0.508)
		(drill 0.254)
		(layers "F.Cu" "B.Cu")
		(net "P3V3_AUX")
	)
	(via
		(at 219.02928 -109.591348)
		(size 0.508)
		(drill 0.254)
		(layers "F.Cu" "B.Cu")
		(net "P3V3_AUX")
	)
	(via
		(at 442.087 -56.124348)
		(size 0.508)
		(drill 0.254)
		(layers "F.Cu" "B.Cu")
		(net "P3V3_AUX")
	)
	(via
		(at 457.308458 -317.02375)
		(size 0.4572)
		(drill 0.2032)
		(layers "F.Cu" "B.Cu")
		(net "P3V3_AUX")
	)
	(via
		(at 465.83727 -101.960934)
		(size 0.508)
		(drill 0.254)
		(layers "F.Cu" "B.Cu")
		(net "P3V3_AUX")
	)
	(via
		(at 99.7077 -411.1371)
		(size 0.508)
		(drill 0.254)
		(layers "F.Cu" "B.Cu")
		(net "P3V3_AUX")
	)
	(via
		(at 264.19048 -100.066348)
		(size 0.508)
		(drill 0.254)
		(layers "F.Cu" "B.Cu")
		(net "P3V3_AUX")
	)
	(via
		(at 116.84508 -401.424648)
		(size 0.508)
		(drill 0.254)
		(layers "F.Cu" "B.Cu")
		(net "P3V3_AUX")
	)
	(via
		(at 118.88216 -419.520878)
		(size 0.508)
		(drill 0.254)
		(layers "F.Cu" "B.Cu")
		(net "P3V3_AUX")
	)
	(via
		(at 278.039576 -17.269968)
		(size 0.508)
		(drill 0.254)
		(layers "F.Cu" "B.Cu")
		(net "P3V3_AUX")
	)
	(via
		(at 140.230606 -64.313308)
		(size 0.508)
		(drill 0.254)
		(layers "F.Cu" "B.Cu")
		(net "P3V3_AUX")
	)
	(via
		(at 310.57088 -41.493948)
		(size 0.508)
		(drill 0.254)
		(layers "F.Cu" "B.Cu")
		(net "P3V3_AUX")
	)
	(via
		(at 213.01583 -125.186948)
		(size 0.508)
		(drill 0.254)
		(layers "F.Cu" "B.Cu")
		(net "P3V3_AUX")
	)
	(via
		(at 100.824284 -395.42974)
		(size 0.508)
		(drill 0.254)
		(layers "F.Cu" "B.Cu")
		(net "P3V3_AUX")
	)
	(via
		(at 95.65894 -428.816008)
		(size 0.508)
		(drill 0.254)
		(layers "F.Cu" "B.Cu")
		(net "P3V3_AUX")
	)
	(via
		(at 423.195242 -379.313948)
		(size 0.508)
		(drill 0.254)
		(layers "F.Cu" "B.Cu")
		(net "P3V3_AUX")
	)
	(via
		(at 82.846672 -52.72532)
		(size 0.508)
		(drill 0.254)
		(layers "F.Cu" "B.Cu")
		(net "P3V3_AUX")
	)
	(via
		(at 110.323122 -133.663182)
		(size 0.508)
		(drill 0.254)
		(layers "F.Cu" "B.Cu")
		(net "P3V3_AUX")
	)
	(via
		(at 171.23283 -28.825698)
		(size 0.508)
		(drill 0.254)
		(layers "F.Cu" "B.Cu")
		(net "P3V3_AUX")
	)
	(via
		(at 165.593522 -8.51789)
		(size 0.508)
		(drill 0.254)
		(layers "F.Cu" "B.Cu")
		(net "P3V3_AUX")
	)
	(via
		(at 160.311084 -80.713072)
		(size 0.508)
		(drill 0.254)
		(layers "F.Cu" "B.Cu")
		(net "P3V3_AUX")
	)
	(via
		(at 28.177998 -72.51573)
		(size 0.508)
		(drill 0.254)
		(layers "F.Cu" "B.Cu")
		(net "P3V3_AUX")
	)
	(via
		(at 458.01661 -39.124128)
		(size 0.508)
		(drill 0.254)
		(layers "F.Cu" "B.Cu")
		(net "P3V3_AUX")
	)
	(via
		(at 333.23784 -14.770608)
		(size 0.508)
		(drill 0.254)
		(layers "F.Cu" "B.Cu")
		(net "P3V3_AUX")
	)
	(via
		(at 259.51053 -92.587572)
		(size 0.508)
		(drill 0.254)
		(layers "F.Cu" "B.Cu")
		(net "P3V3_AUX")
	)
	(via
		(at 306.63388 -61.975492)
		(size 0.508)
		(drill 0.254)
		(layers "F.Cu" "B.Cu")
		(net "P3V3_AUX")
	)
	(via
		(at 235.413042 -244.368828)
		(size 0.508)
		(drill 0.254)
		(layers "F.Cu" "B.Cu")
		(net "P3V3_AUX")
	)
	(via
		(at 33.155382 -412.069534)
		(size 0.508)
		(drill 0.254)
		(layers "F.Cu" "B.Cu")
		(net "P3V3_AUX")
	)
	(via
		(at 366.2172 -412.623)
		(size 0.508)
		(drill 0.254)
		(layers "F.Cu" "B.Cu")
		(net "P3V3_AUX")
	)
	(via
		(at 292.673278 -413.74314)
		(size 0.508)
		(drill 0.254)
		(layers "F.Cu" "B.Cu")
		(net "P3V3_AUX")
	)
	(via
		(at 202.26401 -119.19966)
		(size 0.508)
		(drill 0.254)
		(layers "F.Cu" "B.Cu")
		(net "P3V3_AUX")
	)
	(via
		(at 177.088038 -416.729418)
		(size 0.508)
		(drill 0.254)
		(layers "F.Cu" "B.Cu")
		(net "P3V3_AUX")
	)
	(via
		(at 129.348484 -360.680508)
		(size 0.508)
		(drill 0.254)
		(layers "F.Cu" "B.Cu")
		(net "P3V3_AUX")
	)
	(via
		(at 221.38132 -46.57598)
		(size 0.508)
		(drill 0.254)
		(layers "F.Cu" "B.Cu")
		(net "P3V3_AUX")
	)
	(via
		(at 370.224558 -387.779006)
		(size 0.508)
		(drill 0.254)
		(layers "F.Cu" "B.Cu")
		(net "P3V3_AUX")
	)
	(via
		(at 119.249952 -408.269948)
		(size 0.508)
		(drill 0.254)
		(layers "F.Cu" "B.Cu")
		(net "P3V3_AUX")
	)
	(via
		(at 129.032 -61.432948)
		(size 0.508)
		(drill 0.254)
		(layers "F.Cu" "B.Cu")
		(net "P3V3_AUX")
	)
	(via
		(at 196.171312 -39.046912)
		(size 0.508)
		(drill 0.254)
		(layers "F.Cu" "B.Cu")
		(net "P3V3_AUX")
	)
	(via
		(at 363.2835 -409.654248)
		(size 0.508)
		(drill 0.254)
		(layers "F.Cu" "B.Cu")
		(net "P3V3_AUX")
	)
	(via
		(at 23.060152 -411.434534)
		(size 0.508)
		(drill 0.254)
		(layers "F.Cu" "B.Cu")
		(net "P3V3_AUX")
	)
	(via
		(at 81.604104 -152.221692)
		(size 0.508)
		(drill 0.254)
		(layers "F.Cu" "B.Cu")
		(net "P3V3_AUX")
	)
	(via
		(at 423.214292 -396.635478)
		(size 0.508)
		(drill 0.254)
		(layers "F.Cu" "B.Cu")
		(net "P3V3_AUX")
	)
	(via
		(at 180.92166 -27.107388)
		(size 0.508)
		(drill 0.254)
		(layers "F.Cu" "B.Cu")
		(net "P3V3_AUX")
	)
	(via
		(at 156.053536 -30.312868)
		(size 0.508)
		(drill 0.254)
		(layers "F.Cu" "B.Cu")
		(net "P3V3_AUX")
	)
	(via
		(at 334.099408 -45.649896)
		(size 0.4572)
		(drill 0.2032)
		(layers "F.Cu" "B.Cu")
		(net "P3V3_AUX")
	)
	(via
		(at 84.963 -55.717948)
		(size 0.508)
		(drill 0.254)
		(layers "F.Cu" "B.Cu")
		(net "P3V3_AUX")
	)
	(via
		(at 124.26442 -417.472368)
		(size 0.508)
		(drill 0.254)
		(layers "F.Cu" "B.Cu")
		(net "P3V3_AUX")
	)
	(via
		(at 359.2449 -385.17449)
		(size 0.508)
		(drill 0.254)
		(layers "F.Cu" "B.Cu")
		(net "P3V3_AUX")
	)
	(via
		(at 194.39509 -119.266208)
		(size 0.508)
		(drill 0.254)
		(layers "F.Cu" "B.Cu")
		(net "P3V3_AUX")
	)
	(via
		(at 381.8763 -98.004122)
		(size 0.508)
		(drill 0.254)
		(layers "F.Cu" "B.Cu")
		(net "P3V3_AUX")
	)
	(via
		(at 391.18286 -31.186628)
		(size 0.508)
		(drill 0.254)
		(layers "F.Cu" "B.Cu")
		(net "P3V3_AUX")
	)
	(via
		(at 18.484596 -392.815826)
		(size 0.508)
		(drill 0.254)
		(layers "F.Cu" "B.Cu")
		(net "P3V3_AUX")
	)
	(via
		(at 392.10488 -147.792948)
		(size 0.508)
		(drill 0.254)
		(layers "F.Cu" "B.Cu")
		(net "P3V3_AUX")
	)
	(via
		(at 305.2318 -27.94)
		(size 0.508)
		(drill 0.254)
		(layers "F.Cu" "B.Cu")
		(net "P3V3_AUX")
	)
	(via
		(at 53.87848 -432.577748)
		(size 0.508)
		(drill 0.254)
		(layers "F.Cu" "B.Cu")
		(net "P3V3_AUX")
	)
	(via
		(at 262.519414 -319.716658)
		(size 0.4572)
		(drill 0.2032)
		(layers "F.Cu" "B.Cu")
		(net "P3V3_AUX")
	)
	(via
		(at 354.7364 -403.9108)
		(size 0.508)
		(drill 0.254)
		(layers "F.Cu" "B.Cu")
		(net "P3V3_AUX")
	)
	(via
		(at 316.380622 -53.787548)
		(size 0.508)
		(drill 0.254)
		(layers "F.Cu" "B.Cu")
		(net "P3V3_AUX")
	)
	(via
		(at 412.465774 -32.925258)
		(size 0.508)
		(drill 0.254)
		(layers "F.Cu" "B.Cu")
		(net "P3V3_AUX")
	)
	(via
		(at 453.105012 -55.099712)
		(size 0.508)
		(drill 0.254)
		(layers "F.Cu" "B.Cu")
		(net "P3V3_AUX")
	)
	(via
		(at 445.027812 -56.953912)
		(size 0.508)
		(drill 0.254)
		(layers "F.Cu" "B.Cu")
		(net "P3V3_AUX")
	)
	(via
		(at 195.427346 -319.716658)
		(size 0.4572)
		(drill 0.2032)
		(layers "F.Cu" "B.Cu")
		(net "P3V3_AUX")
	)
	(via
		(at 50.583846 -118.93677)
		(size 0.508)
		(drill 0.254)
		(layers "F.Cu" "B.Cu")
		(net "P3V3_AUX")
	)
	(via
		(at 124.141992 -18.355056)
		(size 0.508)
		(drill 0.254)
		(layers "F.Cu" "B.Cu")
		(net "P3V3_AUX")
	)
	(via
		(at 365.110522 -357.197406)
		(size 0.508)
		(drill 0.254)
		(layers "F.Cu" "B.Cu")
		(net "P3V3_AUX")
	)
	(via
		(at 324.553834 -64.813942)
		(size 0.508)
		(drill 0.254)
		(layers "F.Cu" "B.Cu")
		(net "P3V3_AUX")
	)
	(via
		(at 116.13388 -402.34108)
		(size 0.508)
		(drill 0.254)
		(layers "F.Cu" "B.Cu")
		(net "P3V3_AUX")
	)
	(via
		(at 96.150938 -416.491928)
		(size 0.508)
		(drill 0.254)
		(layers "F.Cu" "B.Cu")
		(net "P3V3_AUX")
	)
	(via
		(at 164.14115 -433.874926)
		(size 0.508)
		(drill 0.254)
		(layers "F.Cu" "B.Cu")
		(net "P3V3_AUX")
	)
	(via
		(at 126.653544 -75.253342)
		(size 0.508)
		(drill 0.254)
		(layers "F.Cu" "B.Cu")
		(net "P3V3_AUX")
	)
	(via
		(at 319.668906 -25.6286)
		(size 0.508)
		(drill 0.254)
		(layers "F.Cu" "B.Cu")
		(net "P3V3_AUX")
	)
	(via
		(at 297.707304 -426.878496)
		(size 0.508)
		(drill 0.254)
		(layers "F.Cu" "B.Cu")
		(net "P3V3_AUX")
	)
	(via
		(at 292.694614 -319.716658)
		(size 0.4572)
		(drill 0.2032)
		(layers "F.Cu" "B.Cu")
		(net "P3V3_AUX")
	)
	(via
		(at 14.579346 -319.716658)
		(size 0.4572)
		(drill 0.2032)
		(layers "F.Cu" "B.Cu")
		(net "P3V3_AUX")
	)
	(via
		(at 194.61353 -104.955848)
		(size 0.508)
		(drill 0.254)
		(layers "F.Cu" "B.Cu")
		(net "P3V3_AUX")
	)
	(via
		(at 262.45439 -89.821258)
		(size 0.508)
		(drill 0.254)
		(layers "F.Cu" "B.Cu")
		(net "P3V3_AUX")
	)
	(via
		(at 86.868 -64.163448)
		(size 0.508)
		(drill 0.254)
		(layers "F.Cu" "B.Cu")
		(net "P3V3_AUX")
	)
	(via
		(at 19.59991 -75.132692)
		(size 0.508)
		(drill 0.254)
		(layers "F.Cu" "B.Cu")
		(net "P3V3_AUX")
	)
	(via
		(at 103.704136 -41.570148)
		(size 0.508)
		(drill 0.254)
		(layers "F.Cu" "B.Cu")
		(net "P3V3_AUX")
	)
	(via
		(at 221.56928 -77.453744)
		(size 0.508)
		(drill 0.254)
		(layers "F.Cu" "B.Cu")
		(net "P3V3_AUX")
	)
	(via
		(at 66.006726 -109.483906)
		(size 0.508)
		(drill 0.254)
		(layers "F.Cu" "B.Cu")
		(net "P3V3_AUX")
	)
	(via
		(at 237.037118 -97.712022)
		(size 0.508)
		(drill 0.254)
		(layers "F.Cu" "B.Cu")
		(net "P3V3_AUX")
	)
	(via
		(at 150.445978 -23.942548)
		(size 0.508)
		(drill 0.254)
		(layers "F.Cu" "B.Cu")
		(net "P3V3_AUX")
	)
	(via
		(at 298.22648 -14.506194)
		(size 0.508)
		(drill 0.254)
		(layers "F.Cu" "B.Cu")
		(net "P3V3_AUX")
	)
	(via
		(at 319.169796 -60.620148)
		(size 0.508)
		(drill 0.254)
		(layers "F.Cu" "B.Cu")
		(net "P3V3_AUX")
	)
	(via
		(at 26.63825 -124.70892)
		(size 0.508)
		(drill 0.254)
		(layers "F.Cu" "B.Cu")
		(net "P3V3_AUX")
	)
	(via
		(at 110.323122 -129.472182)
		(size 0.508)
		(drill 0.254)
		(layers "F.Cu" "B.Cu")
		(net "P3V3_AUX")
	)
	(via
		(at 432.999642 -381.218948)
		(size 0.508)
		(drill 0.254)
		(layers "F.Cu" "B.Cu")
		(net "P3V3_AUX")
	)
	(via
		(at 181.15788 -101.564948)
		(size 0.508)
		(drill 0.254)
		(layers "F.Cu" "B.Cu")
		(net "P3V3_AUX")
	)
	(via
		(at 446.2272 -92.468192)
		(size 0.508)
		(drill 0.254)
		(layers "F.Cu" "B.Cu")
		(net "P3V3_AUX")
	)
	(via
		(at 435.057296 -176.904904)
		(size 0.508)
		(drill 0.254)
		(layers "F.Cu" "B.Cu")
		(net "P3V3_AUX")
	)
	(via
		(at 163.857686 -66.091308)
		(size 0.508)
		(drill 0.254)
		(layers "F.Cu" "B.Cu")
		(net "P3V3_AUX")
	)
	(via
		(at 251.182632 -94.841568)
		(size 0.508)
		(drill 0.254)
		(layers "F.Cu" "B.Cu")
		(net "P3V3_AUX")
	)
	(via
		(at 19.181064 -107.777026)
		(size 0.508)
		(drill 0.254)
		(layers "F.Cu" "B.Cu")
		(net "P3V3_AUX")
	)
	(via
		(at 37.965888 -128.72974)
		(size 0.508)
		(drill 0.254)
		(layers "F.Cu" "B.Cu")
		(net "P3V3_AUX")
	)
	(via
		(at 353.2124 -63.058548)
		(size 0.508)
		(drill 0.254)
		(layers "F.Cu" "B.Cu")
		(net "P3V3_AUX")
	)
	(via
		(at 311.427622 -34.102548)
		(size 0.508)
		(drill 0.254)
		(layers "F.Cu" "B.Cu")
		(net "P3V3_AUX")
	)
	(via
		(at 19.59991 -70.814692)
		(size 0.508)
		(drill 0.254)
		(layers "F.Cu" "B.Cu")
		(net "P3V3_AUX")
	)
	(via
		(at 303.48936 -60.094368)
		(size 0.508)
		(drill 0.254)
		(layers "F.Cu" "B.Cu")
		(net "P3V3_AUX")
	)
	(via
		(at 383.667 -32.001968)
		(size 0.508)
		(drill 0.254)
		(layers "F.Cu" "B.Cu")
		(net "P3V3_AUX")
	)
	(via
		(at 167.31488 -101.564948)
		(size 0.508)
		(drill 0.254)
		(layers "F.Cu" "B.Cu")
		(net "P3V3_AUX")
	)
	(via
		(at 300.21022 -420.276528)
		(size 0.508)
		(drill 0.254)
		(layers "F.Cu" "B.Cu")
		(net "P3V3_AUX")
	)
	(via
		(at 321.747388 -25.65527)
		(size 0.508)
		(drill 0.254)
		(layers "F.Cu" "B.Cu")
		(net "P3V3_AUX")
	)
	(via
		(at 415.271712 -192.074546)
		(size 0.508)
		(drill 0.254)
		(layers "F.Cu" "B.Cu")
		(net "P3V3_AUX")
	)
	(via
		(at 360.5403 -405.4221)
		(size 0.508)
		(drill 0.254)
		(layers "F.Cu" "B.Cu")
		(net "P3V3_AUX")
	)
	(via
		(at 198.42607 -115.418108)
		(size 0.508)
		(drill 0.254)
		(layers "F.Cu" "B.Cu")
		(net "P3V3_AUX")
	)
	(via
		(at 22.225 -398.035526)
		(size 0.508)
		(drill 0.254)
		(layers "F.Cu" "B.Cu")
		(net "P3V3_AUX")
	)
	(via
		(at 323.533516 -65.152016)
		(size 0.508)
		(drill 0.254)
		(layers "F.Cu" "B.Cu")
		(net "P3V3_AUX")
	)
	(via
		(at 213.867238 -196.36359)
		(size 0.508)
		(drill 0.254)
		(layers "F.Cu" "B.Cu")
		(net "P3V3_AUX")
	)
	(via
		(at 415.7472 -108.453428)
		(size 0.508)
		(drill 0.254)
		(layers "F.Cu" "B.Cu")
		(net "P3V3_AUX")
	)
	(via
		(at 311.051956 -29.708348)
		(size 0.508)
		(drill 0.254)
		(layers "F.Cu" "B.Cu")
		(net "P3V3_AUX")
	)
	(via
		(at 193.01968 -71.262748)
		(size 0.508)
		(drill 0.254)
		(layers "F.Cu" "B.Cu")
		(net "P3V3_AUX")
	)
	(via
		(at 419.10508 -103.873808)
		(size 0.508)
		(drill 0.254)
		(layers "F.Cu" "B.Cu")
		(net "P3V3_AUX")
	)
	(via
		(at 132.476494 -129.913126)
		(size 0.508)
		(drill 0.254)
		(layers "F.Cu" "B.Cu")
		(net "P3V3_AUX")
	)
	(via
		(at 29.666946 -319.716658)
		(size 0.4572)
		(drill 0.2032)
		(layers "F.Cu" "B.Cu")
		(net "P3V3_AUX")
	)
	(via
		(at 321.695572 -60.208668)
		(size 0.508)
		(drill 0.254)
		(layers "F.Cu" "B.Cu")
		(net "P3V3_AUX")
	)
	(via
		(at 110.323122 -130.869182)
		(size 0.508)
		(drill 0.254)
		(layers "F.Cu" "B.Cu")
		(net "P3V3_AUX")
	)
	(via
		(at 445.027812 -56.318912)
		(size 0.508)
		(drill 0.254)
		(layers "F.Cu" "B.Cu")
		(net "P3V3_AUX")
	)
	(via
		(at 163.857686 -63.297308)
		(size 0.508)
		(drill 0.254)
		(layers "F.Cu" "B.Cu")
		(net "P3V3_AUX")
	)
	(via
		(at 177.9524 -92.527628)
		(size 0.508)
		(drill 0.254)
		(layers "F.Cu" "B.Cu")
		(net "P3V3_AUX")
	)
	(via
		(at 126.67742 -32.662368)
		(size 0.508)
		(drill 0.254)
		(layers "F.Cu" "B.Cu")
		(net "P3V3_AUX")
	)
	(via
		(at 355.6 -415.127948)
		(size 0.508)
		(drill 0.254)
		(layers "F.Cu" "B.Cu")
		(net "P3V3_AUX")
	)
	(via
		(at 314.094622 -50.155348)
		(size 0.508)
		(drill 0.254)
		(layers "F.Cu" "B.Cu")
		(net "P3V3_AUX")
	)
	(via
		(at 28.177998 -76.924916)
		(size 0.508)
		(drill 0.254)
		(layers "F.Cu" "B.Cu")
		(net "P3V3_AUX")
	)
	(via
		(at 172.206412 -30.395672)
		(size 0.508)
		(drill 0.254)
		(layers "F.Cu" "B.Cu")
		(net "P3V3_AUX")
	)
	(via
		(at 308.837584 -192.263268)
		(size 0.508)
		(drill 0.254)
		(layers "F.Cu" "B.Cu")
		(net "P3V3_AUX")
	)
	(via
		(at 66.167 -57.749948)
		(size 0.508)
		(drill 0.254)
		(layers "F.Cu" "B.Cu")
		(net "P3V3_AUX")
	)
	(via
		(at 92.36075 -32.426148)
		(size 0.508)
		(drill 0.254)
		(layers "F.Cu" "B.Cu")
		(net "P3V3_AUX")
	)
	(via
		(at 319.149476 -61.766958)
		(size 0.508)
		(drill 0.254)
		(layers "F.Cu" "B.Cu")
		(net "P3V3_AUX")
	)
	(via
		(at 317.9191 -132.250688)
		(size 0.508)
		(drill 0.254)
		(layers "F.Cu" "B.Cu")
		(net "P3V3_AUX")
	)
	(via
		(at 174.04588 -131.280408)
		(size 0.508)
		(drill 0.254)
		(layers "F.Cu" "B.Cu")
		(net "P3V3_AUX")
	)
	(via
		(at 183.69788 -131.280408)
		(size 0.508)
		(drill 0.254)
		(layers "F.Cu" "B.Cu")
		(net "P3V3_AUX")
	)
	(via
		(at 187.883546 -319.716658)
		(size 0.4572)
		(drill 0.2032)
		(layers "F.Cu" "B.Cu")
		(net "P3V3_AUX")
	)
	(via
		(at 311.427622 -49.139348)
		(size 0.508)
		(drill 0.254)
		(layers "F.Cu" "B.Cu")
		(net "P3V3_AUX")
	)
	(via
		(at 147.95754 -77.229208)
		(size 0.508)
		(drill 0.254)
		(layers "F.Cu" "B.Cu")
		(net "P3V3_AUX")
	)
	(via
		(at 339.483446 -26.91638)
		(size 0.508)
		(drill 0.254)
		(layers "F.Cu" "B.Cu")
		(net "P3V3_AUX")
	)
	(via
		(at 23.060152 -406.874218)
		(size 0.508)
		(drill 0.254)
		(layers "F.Cu" "B.Cu")
		(net "P3V3_AUX")
	)
	(via
		(at 279.15362 -62.26556)
		(size 0.508)
		(drill 0.254)
		(layers "F.Cu" "B.Cu")
		(net "P3V3_AUX")
	)
	(via
		(at 14.426946 -396.263876)
		(size 0.508)
		(drill 0.254)
		(layers "F.Cu" "B.Cu")
		(net "P3V3_AUX")
	)
	(via
		(at 423.195242 -381.345948)
		(size 0.508)
		(drill 0.254)
		(layers "F.Cu" "B.Cu")
		(net "P3V3_AUX")
	)
	(via
		(at 423.195242 -395.619478)
		(size 0.508)
		(drill 0.254)
		(layers "F.Cu" "B.Cu")
		(net "P3V3_AUX")
	)
	(via
		(at 429.29556 -110.27664)
		(size 0.508)
		(drill 0.254)
		(layers "F.Cu" "B.Cu")
		(net "P3V3_AUX")
	)
	(via
		(at 267.92428 -94.021148)
		(size 0.508)
		(drill 0.254)
		(layers "F.Cu" "B.Cu")
		(net "P3V3_AUX")
	)
	(via
		(at 93.295724 -64.213994)
		(size 0.508)
		(drill 0.254)
		(layers "F.Cu" "B.Cu")
		(net "P3V3_AUX")
	)
	(via
		(at 163.63188 -121.376948)
		(size 0.508)
		(drill 0.254)
		(layers "F.Cu" "B.Cu")
		(net "P3V3_AUX")
	)
	(via
		(at 314.605416 -38.115748)
		(size 0.508)
		(drill 0.254)
		(layers "F.Cu" "B.Cu")
		(net "P3V3_AUX")
	)
	(via
		(at 202.7936 -91.5924)
		(size 0.508)
		(drill 0.254)
		(layers "F.Cu" "B.Cu")
		(net "P3V3_AUX")
	)
	(via
		(at 65.842896 -106.561128)
		(size 0.508)
		(drill 0.254)
		(layers "F.Cu" "B.Cu")
		(net "P3V3_AUX")
	)
	(via
		(at 453.105012 -56.369712)
		(size 0.508)
		(drill 0.254)
		(layers "F.Cu" "B.Cu")
		(net "P3V3_AUX")
	)
	(via
		(at 431.715164 -137.542778)
		(size 0.508)
		(drill 0.254)
		(layers "F.Cu" "B.Cu")
		(net "P3V3_AUX")
	)
	(via
		(at 155.290774 -50.896012)
		(size 0.508)
		(drill 0.254)
		(layers "F.Cu" "B.Cu")
		(net "P3V3_AUX")
	)
	(via
		(at 28.638246 -394.358876)
		(size 0.508)
		(drill 0.254)
		(layers "F.Cu" "B.Cu")
		(net "P3V3_AUX")
	)
	(via
		(at 259.394706 -105.911396)
		(size 0.508)
		(drill 0.254)
		(layers "F.Cu" "B.Cu")
		(net "P3V3_AUX")
	)
	(via
		(at 319.174622 -59.428888)
		(size 0.508)
		(drill 0.254)
		(layers "F.Cu" "B.Cu")
		(net "P3V3_AUX")
	)
	(via
		(at 285.058612 -27.317446)
		(size 0.508)
		(drill 0.254)
		(layers "F.Cu" "B.Cu")
		(net "P3V3_AUX")
	)
	(via
		(at 120.645682 -355.69779)
		(size 0.508)
		(drill 0.254)
		(layers "F.Cu" "B.Cu")
		(net "P3V3_AUX")
	)
	(via
		(at 182.17388 -131.280408)
		(size 0.508)
		(drill 0.254)
		(layers "F.Cu" "B.Cu")
		(net "P3V3_AUX")
	)
	(via
		(at 127.83058 -32.662368)
		(size 0.508)
		(drill 0.254)
		(layers "F.Cu" "B.Cu")
		(net "P3V3_AUX")
	)
	(via
		(at 341.536274 -32.319976)
		(size 0.508)
		(drill 0.254)
		(layers "F.Cu" "B.Cu")
		(net "P3V3_AUX")
	)
	(via
		(at 449.38442 -78.861412)
		(size 0.508)
		(drill 0.254)
		(layers "F.Cu" "B.Cu")
		(net "P3V3_AUX")
	)
	(via
		(at 175.4124 -92.527628)
		(size 0.508)
		(drill 0.254)
		(layers "F.Cu" "B.Cu")
		(net "P3V3_AUX")
	)
	(via
		(at 215.933782 -68.846446)
		(size 0.508)
		(drill 0.254)
		(layers "F.Cu" "B.Cu")
		(net "P3V3_AUX")
	)
	(via
		(at 205.4352 -68.0466)
		(size 0.508)
		(drill 0.254)
		(layers "F.Cu" "B.Cu")
		(net "P3V3_AUX")
	)
	(via
		(at 171.24553 -434.939948)
		(size 0.508)
		(drill 0.254)
		(layers "F.Cu" "B.Cu")
		(net "P3V3_AUX")
	)
	(via
		(at 110.57636 -31.037784)
		(size 0.508)
		(drill 0.254)
		(layers "F.Cu" "B.Cu")
		(net "P3V3_AUX")
	)
	(via
		(at 31.683198 -187.636404)
		(size 0.508)
		(drill 0.254)
		(layers "F.Cu" "B.Cu")
		(net "P3V3_AUX")
	)
	(via
		(at 446.294764 -110.673134)
		(size 0.508)
		(drill 0.254)
		(layers "F.Cu" "B.Cu")
		(net "P3V3_AUX")
	)
	(via
		(at 444.9572 -52.517548)
		(size 0.508)
		(drill 0.254)
		(layers "F.Cu" "B.Cu")
		(net "P3V3_AUX")
	)
	(via
		(at 67.81165 -35.587178)
		(size 0.508)
		(drill 0.254)
		(layers "F.Cu" "B.Cu")
		(net "P3V3_AUX")
	)
	(via
		(at 82.071718 -19.542252)
		(size 0.508)
		(drill 0.254)
		(layers "F.Cu" "B.Cu")
		(net "P3V3_AUX")
	)
	(via
		(at 460.6798 -379.669548)
		(size 0.508)
		(drill 0.254)
		(layers "F.Cu" "B.Cu")
		(net "P3V3_AUX")
	)
	(via
		(at 12.784582 -409.793186)
		(size 0.508)
		(drill 0.254)
		(layers "F.Cu" "B.Cu")
		(net "P3V3_AUX")
	)
	(via
		(at 112.892332 -407.074116)
		(size 0.508)
		(drill 0.254)
		(layers "F.Cu" "B.Cu")
		(net "P3V3_AUX")
	)
	(via
		(at 410.225748 -360.995214)
		(size 0.508)
		(drill 0.254)
		(layers "F.Cu" "B.Cu")
		(net "P3V3_AUX")
	)
	(via
		(at 365.390938 -416.105848)
		(size 0.508)
		(drill 0.254)
		(layers "F.Cu" "B.Cu")
		(net "P3V3_AUX")
	)
	(via
		(at 276.55266 -417.02482)
		(size 0.508)
		(drill 0.254)
		(layers "F.Cu" "B.Cu")
		(net "P3V3_AUX")
	)
	(via
		(at 307.55082 -425.831)
		(size 0.508)
		(drill 0.254)
		(layers "F.Cu" "B.Cu")
		(net "P3V3_AUX")
	)
	(via
		(at 106.11231 -64.049148)
		(size 0.508)
		(drill 0.254)
		(layers "F.Cu" "B.Cu")
		(net "P3V3_AUX")
	)
	(via
		(at 217.07348 -315.49975)
		(size 0.508)
		(drill 0.254)
		(layers "F.Cu" "B.Cu")
		(net "P3V3_AUX")
	)
	(via
		(at 47.42688 -187.416948)
		(size 0.508)
		(drill 0.254)
		(layers "F.Cu" "B.Cu")
		(net "P3V3_AUX")
	)
	(via
		(at 416.287712 -192.074546)
		(size 0.508)
		(drill 0.254)
		(layers "F.Cu" "B.Cu")
		(net "P3V3_AUX")
	)
	(via
		(at 116.7257 -355.942392)
		(size 0.508)
		(drill 0.254)
		(layers "F.Cu" "B.Cu")
		(net "P3V3_AUX")
	)
	(via
		(at 347.057726 -23.4823)
		(size 0.508)
		(drill 0.254)
		(layers "F.Cu" "B.Cu")
		(net "P3V3_AUX")
	)
	(via
		(at 172.206412 -29.379672)
		(size 0.508)
		(drill 0.254)
		(layers "F.Cu" "B.Cu")
		(net "P3V3_AUX")
	)
	(via
		(at 234.92968 -49.834546)
		(size 0.508)
		(drill 0.254)
		(layers "F.Cu" "B.Cu")
		(net "P3V3_AUX")
	)
	(via
		(at 371.796818 -416.128708)
		(size 0.508)
		(drill 0.254)
		(layers "F.Cu" "B.Cu")
		(net "P3V3_AUX")
	)
	(via
		(at 192.71488 -71.948548)
		(size 0.508)
		(drill 0.254)
		(layers "F.Cu" "B.Cu")
		(net "P3V3_AUX")
	)
	(via
		(at 132.476494 -127.119126)
		(size 0.508)
		(drill 0.254)
		(layers "F.Cu" "B.Cu")
		(net "P3V3_AUX")
	)
	(via
		(at 192.877186 -439.29808)
		(size 0.508)
		(drill 0.254)
		(layers "F.Cu" "B.Cu")
		(net "P3V3_AUX")
	)
	(via
		(at 99.457002 -416.621976)
		(size 0.508)
		(drill 0.254)
		(layers "F.Cu" "B.Cu")
		(net "P3V3_AUX")
	)
	(via
		(at 433.451 -104.993948)
		(size 0.508)
		(drill 0.254)
		(layers "F.Cu" "B.Cu")
		(net "P3V3_AUX")
	)
	(via
		(at 218.574874 -95.459804)
		(size 0.508)
		(drill 0.254)
		(layers "F.Cu" "B.Cu")
		(net "P3V3_AUX")
	)
	(via
		(at 308.33314 -431.985928)
		(size 0.508)
		(drill 0.254)
		(layers "F.Cu" "B.Cu")
		(net "P3V3_AUX")
	)
	(via
		(at 13.800582 -409.793186)
		(size 0.508)
		(drill 0.254)
		(layers "F.Cu" "B.Cu")
		(net "P3V3_AUX")
	)
	(via
		(at 461.516476 -101.105208)
		(size 0.508)
		(drill 0.254)
		(layers "F.Cu" "B.Cu")
		(net "P3V3_AUX")
	)
	(via
		(at 359.34396 -392.04265)
		(size 0.508)
		(drill 0.254)
		(layers "F.Cu" "B.Cu")
		(net "P3V3_AUX")
	)
	(via
		(at 321.272916 -65.149984)
		(size 0.508)
		(drill 0.254)
		(layers "F.Cu" "B.Cu")
		(net "P3V3_AUX")
	)
	(via
		(at 453.105012 -57.004712)
		(size 0.508)
		(drill 0.254)
		(layers "F.Cu" "B.Cu")
		(net "P3V3_AUX")
	)
	(via
		(at 359.34396 -393.28725)
		(size 0.508)
		(drill 0.254)
		(layers "F.Cu" "B.Cu")
		(net "P3V3_AUX")
	)
	(via
		(at 217.387932 -53.95595)
		(size 0.508)
		(drill 0.254)
		(layers "F.Cu" "B.Cu")
		(net "P3V3_AUX")
	)
	(via
		(at 304.1396 -420.355268)
		(size 0.508)
		(drill 0.254)
		(layers "F.Cu" "B.Cu")
		(net "P3V3_AUX")
	)
	(via
		(at 293.778686 -326.81799)
		(size 0.508)
		(drill 0.254)
		(layers "F.Cu" "B.Cu")
		(net "P3V3_AUX")
	)
	(via
		(at 35.977068 -436.268368)
		(size 0.508)
		(drill 0.254)
		(layers "F.Cu" "B.Cu")
		(net "P3V3_AUX")
	)
	(via
		(at 337.730084 -26.658316)
		(size 0.508)
		(drill 0.254)
		(layers "F.Cu" "B.Cu")
		(net "P3V3_AUX")
	)
	(via
		(at 75.305412 -37.897562)
		(size 0.508)
		(drill 0.254)
		(layers "F.Cu" "B.Cu")
		(net "P3V3_AUX")
	)
	(via
		(at 46.66488 -187.416948)
		(size 0.508)
		(drill 0.254)
		(layers "F.Cu" "B.Cu")
		(net "P3V3_AUX")
	)
	(via
		(at 28.638246 -389.278876)
		(size 0.508)
		(drill 0.254)
		(layers "F.Cu" "B.Cu")
		(net "P3V3_AUX")
	)
	(via
		(at 103.202232 -235.871004)
		(size 0.4572)
		(drill 0.2032)
		(layers "F.Cu" "B.Cu")
		(net "P3V3_AUX")
	)
	(via
		(at 365.3282 -408.1272)
		(size 0.508)
		(drill 0.254)
		(layers "F.Cu" "B.Cu")
		(net "P3V3_AUX")
	)
	(via
		(at 185.22188 -131.280408)
		(size 0.508)
		(drill 0.254)
		(layers "F.Cu" "B.Cu")
		(net "P3V3_AUX")
	)
	(via
		(at 416.5092 -110.739428)
		(size 0.508)
		(drill 0.254)
		(layers "F.Cu" "B.Cu")
		(net "P3V3_AUX")
	)
	(via
		(at 460.288894 -120.020334)
		(size 0.508)
		(drill 0.254)
		(layers "F.Cu" "B.Cu")
		(net "P3V3_AUX")
	)
	(via
		(at 370.23548 -186.99353)
		(size 0.508)
		(drill 0.254)
		(layers "F.Cu" "B.Cu")
		(net "P3V3_AUX")
	)
	(via
		(at 442.087 -53.076348)
		(size 0.508)
		(drill 0.254)
		(layers "F.Cu" "B.Cu")
		(net "P3V3_AUX")
	)
	(via
		(at 321.224402 -40.372284)
		(size 0.508)
		(drill 0.254)
		(layers "F.Cu" "B.Cu")
		(net "P3V3_AUX")
	)
	(via
		(at 438.282588 -122.648726)
		(size 0.508)
		(drill 0.254)
		(layers "F.Cu" "B.Cu")
		(net "P3V3_AUX")
	)
	(via
		(at 304.342292 -148.887688)
		(size 0.508)
		(drill 0.254)
		(layers "F.Cu" "B.Cu")
		(net "P3V3_AUX")
	)
	(via
		(at 32.901382 -416.016948)
		(size 0.508)
		(drill 0.254)
		(layers "F.Cu" "B.Cu")
		(net "P3V3_AUX")
	)
	(via
		(at 363.62005 -415.249868)
		(size 0.508)
		(drill 0.254)
		(layers "F.Cu" "B.Cu")
		(net "P3V3_AUX")
	)
	(via
		(at 141.01953 -46.954948)
		(size 0.508)
		(drill 0.254)
		(layers "F.Cu" "B.Cu")
		(net "P3V3_AUX")
	)
	(via
		(at 415.7472 -109.215428)
		(size 0.508)
		(drill 0.254)
		(layers "F.Cu" "B.Cu")
		(net "P3V3_AUX")
	)
	(via
		(at 70.993 -115.661948)
		(size 0.508)
		(drill 0.254)
		(layers "F.Cu" "B.Cu")
		(net "P3V3_AUX")
	)
	(via
		(at 127.52578 -108.695998)
		(size 0.508)
		(drill 0.254)
		(layers "F.Cu" "B.Cu")
		(net "P3V3_AUX")
	)
	(via
		(at 14.426946 -386.103876)
		(size 0.508)
		(drill 0.254)
		(layers "F.Cu" "B.Cu")
		(net "P3V3_AUX")
	)
	(via
		(at 165.30066 -38.067234)
		(size 0.508)
		(drill 0.254)
		(layers "F.Cu" "B.Cu")
		(net "P3V3_AUX")
	)
	(via
		(at 48.9204 -395.56944)
		(size 0.508)
		(drill 0.254)
		(layers "F.Cu" "B.Cu")
		(net "P3V3_AUX")
	)
	(via
		(at 234.126278 -244.368828)
		(size 0.508)
		(drill 0.254)
		(layers "F.Cu" "B.Cu")
		(net "P3V3_AUX")
	)
	(via
		(at 124.724922 -139.813538)
		(size 0.508)
		(drill 0.254)
		(layers "F.Cu" "B.Cu")
		(net "P3V3_AUX")
	)
	(via
		(at 19.47672 -388.742428)
		(size 0.508)
		(drill 0.254)
		(layers "F.Cu" "B.Cu")
		(net "P3V3_AUX")
	)
	(via
		(at 19.59991 -72.710548)
		(size 0.508)
		(drill 0.254)
		(layers "F.Cu" "B.Cu")
		(net "P3V3_AUX")
	)
	(via
		(at 177.068988 -415.713418)
		(size 0.508)
		(drill 0.254)
		(layers "F.Cu" "B.Cu")
		(net "P3V3_AUX")
	)
	(via
		(at 301.45482 -420.276528)
		(size 0.508)
		(drill 0.254)
		(layers "F.Cu" "B.Cu")
		(net "P3V3_AUX")
	)
	(via
		(at 156.63545 -8.071358)
		(size 0.508)
		(drill 0.254)
		(layers "F.Cu" "B.Cu")
		(net "P3V3_AUX")
	)
	(via
		(at 99.589082 -73.902316)
		(size 0.508)
		(drill 0.254)
		(layers "F.Cu" "B.Cu")
		(net "P3V3_AUX")
	)
	(via
		(at 209.550762 -100.908104)
		(size 0.508)
		(drill 0.254)
		(layers "F.Cu" "B.Cu")
		(net "P3V3_AUX")
	)
	(via
		(at 435.25948 -319.662048)
		(size 0.4572)
		(drill 0.2032)
		(layers "F.Cu" "B.Cu")
		(net "P3V3_AUX")
	)
	(via
		(at 295.86682 -420.276528)
		(size 0.508)
		(drill 0.254)
		(layers "F.Cu" "B.Cu")
		(net "P3V3_AUX")
	)
	(via
		(at 366.678718 -416.105848)
		(size 0.508)
		(drill 0.254)
		(layers "F.Cu" "B.Cu")
		(net "P3V3_AUX")
	)
	(via
		(at 324.991222 -63.160148)
		(size 0.508)
		(drill 0.254)
		(layers "F.Cu" "B.Cu")
		(net "P3V3_AUX")
	)
	(via
		(at 452.886572 -76.639166)
		(size 0.508)
		(drill 0.254)
		(layers "F.Cu" "B.Cu")
		(net "P3V3_AUX")
	)
	(via
		(at 445.789812 -55.734712)
		(size 0.508)
		(drill 0.254)
		(layers "F.Cu" "B.Cu")
		(net "P3V3_AUX")
	)
	(via
		(at 440.38012 -99.21748)
		(size 0.508)
		(drill 0.254)
		(layers "F.Cu" "B.Cu")
		(net "P3V3_AUX")
	)
	(via
		(at 368.598704 -355.352604)
		(size 0.508)
		(drill 0.254)
		(layers "F.Cu" "B.Cu")
		(net "P3V3_AUX")
	)
	(via
		(at 163.36518 -43.525948)
		(size 0.508)
		(drill 0.254)
		(layers "F.Cu" "B.Cu")
		(net "P3V3_AUX")
	)
	(via
		(at 318.768476 -39.975028)
		(size 0.508)
		(drill 0.254)
		(layers "F.Cu" "B.Cu")
		(net "P3V3_AUX")
	)
	(via
		(at 445.027812 -55.683912)
		(size 0.508)
		(drill 0.254)
		(layers "F.Cu" "B.Cu")
		(net "P3V3_AUX")
	)
	(via
		(at 242.9764 -423.38625)
		(size 0.508)
		(drill 0.254)
		(layers "F.Cu" "B.Cu")
		(net "P3V3_AUX")
	)
	(via
		(at 174.235872 -14.771878)
		(size 0.508)
		(drill 0.254)
		(layers "F.Cu" "B.Cu")
		(net "P3V3_AUX")
	)
	(via
		(at 305.800506 -438.520586)
		(size 0.508)
		(drill 0.254)
		(layers "F.Cu" "B.Cu")
		(net "P3V3_AUX")
	)
	(via
		(at 239.81918 -244.561868)
		(size 0.508)
		(drill 0.254)
		(layers "F.Cu" "B.Cu")
		(net "P3V3_AUX")
	)
	(via
		(at 452.73468 -113.572798)
		(size 0.508)
		(drill 0.254)
		(layers "F.Cu" "B.Cu")
		(net "P3V3_AUX")
	)
	(via
		(at 95.94088 -391.124948)
		(size 0.508)
		(drill 0.254)
		(layers "F.Cu" "B.Cu")
		(net "P3V3_AUX")
	)
	(via
		(at 212.725 -58.329068)
		(size 0.508)
		(drill 0.254)
		(layers "F.Cu" "B.Cu")
		(net "P3V3_AUX")
	)
	(via
		(at 77.910944 -73.828148)
		(size 0.508)
		(drill 0.254)
		(layers "F.Cu" "B.Cu")
		(net "P3V3_AUX")
	)
	(via
		(at 277.93315 -424.61434)
		(size 0.508)
		(drill 0.254)
		(layers "F.Cu" "B.Cu")
		(net "P3V3_AUX")
	)
	(via
		(at 432.999642 -386.171948)
		(size 0.508)
		(drill 0.254)
		(layers "F.Cu" "B.Cu")
		(net "P3V3_AUX")
	)
	(via
		(at 423.214292 -401.655534)
		(size 0.508)
		(drill 0.254)
		(layers "F.Cu" "B.Cu")
		(net "P3V3_AUX")
	)
	(via
		(at 121.66473 -74.621898)
		(size 0.508)
		(drill 0.254)
		(layers "F.Cu" "B.Cu")
		(net "P3V3_AUX")
	)
	(via
		(at 111.095282 -407.067766)
		(size 0.508)
		(drill 0.254)
		(layers "F.Cu" "B.Cu")
		(net "P3V3_AUX")
	)
	(via
		(at 114.660172 -20.010628)
		(size 0.508)
		(drill 0.254)
		(layers "F.Cu" "B.Cu")
		(net "P3V3_AUX")
	)
	(via
		(at 439.662316 -121.427748)
		(size 0.508)
		(drill 0.254)
		(layers "F.Cu" "B.Cu")
		(net "P3V3_AUX")
	)
	(via
		(at 168.412922 -419.495478)
		(size 0.508)
		(drill 0.254)
		(layers "F.Cu" "B.Cu")
		(net "P3V3_AUX")
	)
	(via
		(at 416.5092 -109.977428)
		(size 0.508)
		(drill 0.254)
		(layers "F.Cu" "B.Cu")
		(net "P3V3_AUX")
	)
	(via
		(at 285.714948 -410.21254)
		(size 0.508)
		(drill 0.254)
		(layers "F.Cu" "B.Cu")
		(net "P3V3_AUX")
	)
	(via
		(at 150.22195 -132.673598)
		(size 0.508)
		(drill 0.254)
		(layers "F.Cu" "B.Cu")
		(net "P3V3_AUX")
	)
	(via
		(at 196.18071 -124.170948)
		(size 0.508)
		(drill 0.254)
		(layers "F.Cu" "B.Cu")
		(net "P3V3_AUX")
	)
	(via
		(at 11.387582 -420.816786)
		(size 0.508)
		(drill 0.254)
		(layers "F.Cu" "B.Cu")
		(net "P3V3_AUX")
	)
	(via
		(at 82.071718 -20.616672)
		(size 0.508)
		(drill 0.254)
		(layers "F.Cu" "B.Cu")
		(net "P3V3_AUX")
	)
	(via
		(at 181.84876 -39.969948)
		(size 0.508)
		(drill 0.254)
		(layers "F.Cu" "B.Cu")
		(net "P3V3_AUX")
	)
	(via
		(at 333.508858 -48.920146)
		(size 0.4572)
		(drill 0.2032)
		(layers "F.Cu" "B.Cu")
		(net "P3V3_AUX")
	)
	(via
		(at 161.80308 -132.679948)
		(size 0.508)
		(drill 0.254)
		(layers "F.Cu" "B.Cu")
		(net "P3V3_AUX")
	)
	(via
		(at 180.47716 -415.56178)
		(size 0.508)
		(drill 0.254)
		(layers "F.Cu" "B.Cu")
		(net "P3V3_AUX")
	)
	(via
		(at 159.82188 -116.296948)
		(size 0.508)
		(drill 0.254)
		(layers "F.Cu" "B.Cu")
		(net "P3V3_AUX")
	)
	(via
		(at 374.03151 -412.40329)
		(size 0.508)
		(drill 0.254)
		(layers "F.Cu" "B.Cu")
		(net "P3V3_AUX")
	)
	(via
		(at 461.320896 -104.249728)
		(size 0.508)
		(drill 0.254)
		(layers "F.Cu" "B.Cu")
		(net "P3V3_AUX")
	)
	(via
		(at 437.371744 -119.192802)
		(size 0.508)
		(drill 0.254)
		(layers "F.Cu" "B.Cu")
		(net "P3V3_AUX")
	)
	(via
		(at 407.341324 -53.727604)
		(size 0.508)
		(drill 0.254)
		(layers "F.Cu" "B.Cu")
		(net "P3V3_AUX")
	)
	(via
		(at 194.61353 -107.495848)
		(size 0.508)
		(drill 0.254)
		(layers "F.Cu" "B.Cu")
		(net "P3V3_AUX")
	)
	(via
		(at 312.5851 -132.250688)
		(size 0.508)
		(drill 0.254)
		(layers "F.Cu" "B.Cu")
		(net "P3V3_AUX")
	)
	(via
		(at 68.010786 -63.998348)
		(size 0.508)
		(drill 0.254)
		(layers "F.Cu" "B.Cu")
		(net "P3V3_AUX")
	)
	(via
		(at 377.288298 -360.680508)
		(size 0.508)
		(drill 0.254)
		(layers "F.Cu" "B.Cu")
		(net "P3V3_AUX")
	)
	(via
		(at 204.978 -192.420748)
		(size 0.508)
		(drill 0.254)
		(layers "F.Cu" "B.Cu")
		(net "P3V3_AUX")
	)
	(via
		(at 146.141186 -67.343528)
		(size 0.508)
		(drill 0.254)
		(layers "F.Cu" "B.Cu")
		(net "P3V3_AUX")
	)
	(via
		(at 437.66486 -44.976288)
		(size 0.508)
		(drill 0.254)
		(layers "F.Cu" "B.Cu")
		(net "P3V3_AUX")
	)
	(via
		(at 300.501304 -426.878496)
		(size 0.508)
		(drill 0.254)
		(layers "F.Cu" "B.Cu")
		(net "P3V3_AUX")
	)
	(via
		(at 300.1899 -320.088768)
		(size 0.4572)
		(drill 0.2032)
		(layers "F.Cu" "B.Cu")
		(net "P3V3_AUX")
	)
	(via
		(at 163.63188 -117.566948)
		(size 0.508)
		(drill 0.254)
		(layers "F.Cu" "B.Cu")
		(net "P3V3_AUX")
	)
	(via
		(at 359.30586 -390.43737)
		(size 0.508)
		(drill 0.254)
		(layers "F.Cu" "B.Cu")
		(net "P3V3_AUX")
	)
	(via
		(at 383.044446 -71.134224)
		(size 0.508)
		(drill 0.254)
		(layers "F.Cu" "B.Cu")
		(net "P3V3_AUX")
	)
	(via
		(at 219.66428 -77.453744)
		(size 0.508)
		(drill 0.254)
		(layers "F.Cu" "B.Cu")
		(net "P3V3_AUX")
	)
	(via
		(at 84.95919 -55.069486)
		(size 0.508)
		(drill 0.254)
		(layers "F.Cu" "B.Cu")
		(net "P3V3_AUX")
	)
	(via
		(at 19.61388 -96.271588)
		(size 0.508)
		(drill 0.254)
		(layers "F.Cu" "B.Cu")
		(net "P3V3_AUX")
	)
	(via
		(at 441.325 -53.076348)
		(size 0.508)
		(drill 0.254)
		(layers "F.Cu" "B.Cu")
		(net "P3V3_AUX")
	)
	(via
		(at 241.69624 -253.345188)
		(size 0.508)
		(drill 0.254)
		(layers "F.Cu" "B.Cu")
		(net "P3V3_AUX")
	)
	(via
		(at 210.594956 -37.369242)
		(size 0.508)
		(drill 0.254)
		(layers "F.Cu" "B.Cu")
		(net "P3V3_AUX")
	)
	(via
		(at 431.751486 -102.61219)
		(size 0.508)
		(drill 0.254)
		(layers "F.Cu" "B.Cu")
		(net "P3V3_AUX")
	)
	(via
		(at 414.255712 -192.074546)
		(size 0.508)
		(drill 0.254)
		(layers "F.Cu" "B.Cu")
		(net "P3V3_AUX")
	)
	(via
		(at 316.353444 -51.562)
		(size 0.508)
		(drill 0.254)
		(layers "F.Cu" "B.Cu")
		(net "P3V3_AUX")
	)
	(via
		(at 386.653532 -73.394824)
		(size 0.508)
		(drill 0.254)
		(layers "F.Cu" "B.Cu")
		(net "P3V3_AUX")
	)
	(via
		(at 304.977292 -148.887688)
		(size 0.508)
		(drill 0.254)
		(layers "F.Cu" "B.Cu")
		(net "P3V3_AUX")
	)
	(via
		(at 356.28072 -405.8158)
		(size 0.508)
		(drill 0.254)
		(layers "F.Cu" "B.Cu")
		(net "P3V3_AUX")
	)
	(via
		(at 450.911214 -319.716658)
		(size 0.4572)
		(drill 0.2032)
		(layers "F.Cu" "B.Cu")
		(net "P3V3_AUX")
	)
	(via
		(at 46.66488 -186.654948)
		(size 0.508)
		(drill 0.254)
		(layers "F.Cu" "B.Cu")
		(net "P3V3_AUX")
	)
	(via
		(at 47.635668 -439.189368)
		(size 0.508)
		(drill 0.254)
		(layers "F.Cu" "B.Cu")
		(net "P3V3_AUX")
	)
	(via
		(at 32.866076 -77.783944)
		(size 0.508)
		(drill 0.254)
		(layers "F.Cu" "B.Cu")
		(net "P3V3_AUX")
	)
	(via
		(at 332.3844 -165.989)
		(size 0.508)
		(drill 0.254)
		(layers "F.Cu" "B.Cu")
		(net "P3V3_AUX")
	)
	(via
		(at 386.82168 -29.50972)
		(size 0.508)
		(drill 0.254)
		(layers "F.Cu" "B.Cu")
		(net "P3V3_AUX")
	)
	(via
		(at 53.490622 -435.360318)
		(size 0.508)
		(drill 0.254)
		(layers "F.Cu" "B.Cu")
		(net "P3V3_AUX")
	)
	(via
		(at 370.285518 -391.797286)
		(size 0.508)
		(drill 0.254)
		(layers "F.Cu" "B.Cu")
		(net "P3V3_AUX")
	)
	(via
		(at 32.866076 -70.83425)
		(size 0.508)
		(drill 0.254)
		(layers "F.Cu" "B.Cu")
		(net "P3V3_AUX")
	)
	(via
		(at 446.2272 -93.484192)
		(size 0.508)
		(drill 0.254)
		(layers "F.Cu" "B.Cu")
		(net "P3V3_AUX")
	)
	(via
		(at 24.52878 -392.731498)
		(size 0.508)
		(drill 0.254)
		(layers "F.Cu" "B.Cu")
		(net "P3V3_AUX")
	)
	(via
		(at 39.990014 -401.810728)
		(size 0.508)
		(drill 0.254)
		(layers "F.Cu" "B.Cu")
		(net "P3V3_AUX")
	)
	(via
		(at 137.02665 -30.168088)
		(size 0.508)
		(drill 0.254)
		(layers "F.Cu" "B.Cu")
		(net "P3V3_AUX")
	)
	(via
		(at 369.83162 -403.936708)
		(size 0.508)
		(drill 0.254)
		(layers "F.Cu" "B.Cu")
		(net "P3V3_AUX")
	)
	(via
		(at 144.399 -8.346948)
		(size 0.508)
		(drill 0.254)
		(layers "F.Cu" "B.Cu")
		(net "P3V3_AUX")
	)
	(via
		(at 435.2163 -184.968388)
		(size 0.508)
		(drill 0.254)
		(layers "F.Cu" "B.Cu")
		(net "P3V3_AUX")
	)
	(via
		(at 147.188174 -50.388012)
		(size 0.508)
		(drill 0.254)
		(layers "F.Cu" "B.Cu")
		(net "P3V3_AUX")
	)
	(via
		(at 114.57432 -364.16996)
		(size 0.508)
		(drill 0.254)
		(layers "F.Cu" "B.Cu")
		(net "P3V3_AUX")
	)
	(via
		(at 306.6034 -152.624028)
		(size 0.508)
		(drill 0.254)
		(layers "F.Cu" "B.Cu")
		(net "P3V3_AUX")
	)
	(via
		(at 210.34883 -40.731948)
		(size 0.508)
		(drill 0.254)
		(layers "F.Cu" "B.Cu")
		(net "P3V3_AUX")
	)
	(via
		(at 311.427622 -39.868348)
		(size 0.508)
		(drill 0.254)
		(layers "F.Cu" "B.Cu")
		(net "P3V3_AUX")
	)
	(via
		(at 190.80988 -35.017456)
		(size 0.508)
		(drill 0.254)
		(layers "F.Cu" "B.Cu")
		(net "P3V3_AUX")
	)
	(via
		(at 11.6332 -184.625996)
		(size 0.508)
		(drill 0.254)
		(layers "F.Cu" "B.Cu")
		(net "P3V3_AUX")
	)
	(via
		(at 59.842146 -319.716658)
		(size 0.4572)
		(drill 0.2032)
		(layers "F.Cu" "B.Cu")
		(net "P3V3_AUX")
	)
	(via
		(at 447.421 -54.371748)
		(size 0.508)
		(drill 0.254)
		(layers "F.Cu" "B.Cu")
		(net "P3V3_AUX")
	)
	(via
		(at 33.900618 -161.170874)
		(size 0.508)
		(drill 0.254)
		(layers "F.Cu" "B.Cu")
		(net "P3V3_AUX")
	)
	(via
		(at 333.508858 -51.739546)
		(size 0.4572)
		(drill 0.2032)
		(layers "F.Cu" "B.Cu")
		(net "P3V3_AUX")
	)
	(via
		(at 204.8383 -78.831948)
		(size 0.508)
		(drill 0.254)
		(layers "F.Cu" "B.Cu")
		(net "P3V3_AUX")
	)
	(via
		(at 190.80988 -131.280408)
		(size 0.508)
		(drill 0.254)
		(layers "F.Cu" "B.Cu")
		(net "P3V3_AUX")
	)
	(via
		(at 193.21018 -80.627728)
		(size 0.508)
		(drill 0.254)
		(layers "F.Cu" "B.Cu")
		(net "P3V3_AUX")
	)
	(via
		(at 371.73154 -69.565012)
		(size 0.508)
		(drill 0.254)
		(layers "F.Cu" "B.Cu")
		(net "P3V3_AUX")
	)
	(via
		(at 195.02628 -359.349548)
		(size 0.508)
		(drill 0.254)
		(layers "F.Cu" "B.Cu")
		(net "P3V3_AUX")
	)
	(via
		(at 220.29928 -77.453744)
		(size 0.508)
		(drill 0.254)
		(layers "F.Cu" "B.Cu")
		(net "P3V3_AUX")
	)
	(via
		(at 100.779072 -391.61974)
		(size 0.508)
		(drill 0.254)
		(layers "F.Cu" "B.Cu")
		(net "P3V3_AUX")
	)
	(via
		(at 71.393558 -63.998348)
		(size 0.508)
		(drill 0.254)
		(layers "F.Cu" "B.Cu")
		(net "P3V3_AUX")
	)
	(via
		(at 28.638246 -395.374876)
		(size 0.508)
		(drill 0.254)
		(layers "F.Cu" "B.Cu")
		(net "P3V3_AUX")
	)
	(via
		(at 301.6504 -412.004256)
		(size 0.508)
		(drill 0.254)
		(layers "F.Cu" "B.Cu")
		(net "P3V3_AUX")
	)
	(via
		(at 207.772 -96.2152)
		(size 0.508)
		(drill 0.254)
		(layers "F.Cu" "B.Cu")
		(net "P3V3_AUX")
	)
	(via
		(at 410.77261 -365.968788)
		(size 0.508)
		(drill 0.254)
		(layers "F.Cu" "B.Cu")
		(net "P3V3_AUX")
	)
	(via
		(at 103.651812 -230.086662)
		(size 0.4572)
		(drill 0.2032)
		(layers "F.Cu" "B.Cu")
		(net "P3V3_AUX")
	)
	(via
		(at 327.45934 -20.632928)
		(size 0.508)
		(drill 0.254)
		(layers "F.Cu" "B.Cu")
		(net "P3V3_AUX")
	)
	(via
		(at 102.86619 -64.049148)
		(size 0.508)
		(drill 0.254)
		(layers "F.Cu" "B.Cu")
		(net "P3V3_AUX")
	)
	(via
		(at 319.172336 -62.992508)
		(size 0.508)
		(drill 0.254)
		(layers "F.Cu" "B.Cu")
		(net "P3V3_AUX")
	)
	(via
		(at 139.03833 -37.414708)
		(size 0.508)
		(drill 0.254)
		(layers "F.Cu" "B.Cu")
		(net "P3V3_AUX")
	)
	(via
		(at 30.159198 -187.636404)
		(size 0.508)
		(drill 0.254)
		(layers "F.Cu" "B.Cu")
		(net "P3V3_AUX")
	)
	(via
		(at 171.24553 -439.003948)
		(size 0.508)
		(drill 0.254)
		(layers "F.Cu" "B.Cu")
		(net "P3V3_AUX")
	)
	(via
		(at 310.8071 -132.250688)
		(size 0.508)
		(drill 0.254)
		(layers "F.Cu" "B.Cu")
		(net "P3V3_AUX")
	)
	(via
		(at 408.046174 -319.696846)
		(size 0.4572)
		(drill 0.2032)
		(layers "F.Cu" "B.Cu")
		(net "P3V3_AUX")
	)
	(via
		(at 195.22948 -354.904548)
		(size 0.508)
		(drill 0.254)
		(layers "F.Cu" "B.Cu")
		(net "P3V3_AUX")
	)
	(via
		(at 395.55928 -51.637438)
		(size 0.508)
		(drill 0.254)
		(layers "F.Cu" "B.Cu")
		(net "P3V3_AUX")
	)
	(via
		(at 95.095314 -418.712904)
		(size 0.508)
		(drill 0.254)
		(layers "F.Cu" "B.Cu")
		(net "P3V3_AUX")
	)
	(via
		(at 107.47883 -57.876948)
		(size 0.508)
		(drill 0.254)
		(layers "F.Cu" "B.Cu")
		(net "P3V3_AUX")
	)
	(via
		(at 284.58668 -27.896566)
		(size 0.508)
		(drill 0.254)
		(layers "F.Cu" "B.Cu")
		(net "P3V3_AUX")
	)
	(via
		(at 210.9724 -114.0968)
		(size 0.508)
		(drill 0.254)
		(layers "F.Cu" "B.Cu")
		(net "P3V3_AUX")
	)
	(via
		(at 436.865522 -29.633418)
		(size 0.508)
		(drill 0.254)
		(layers "F.Cu" "B.Cu")
		(net "P3V3_AUX")
	)
	(via
		(at 141.02588 -41.855898)
		(size 0.508)
		(drill 0.254)
		(layers "F.Cu" "B.Cu")
		(net "P3V3_AUX")
	)
	(via
		(at 162.49523 -436.463948)
		(size 0.508)
		(drill 0.254)
		(layers "F.Cu" "B.Cu")
		(net "P3V3_AUX")
	)
	(via
		(at 101.915976 -365.956342)
		(size 0.508)
		(drill 0.254)
		(layers "F.Cu" "B.Cu")
		(net "P3V3_AUX")
	)
	(via
		(at 103.7844 -408.2796)
		(size 0.508)
		(drill 0.254)
		(layers "F.Cu" "B.Cu")
		(net "P3V3_AUX")
	)
	(via
		(at 220.93428 -77.453744)
		(size 0.508)
		(drill 0.254)
		(layers "F.Cu" "B.Cu")
		(net "P3V3_AUX")
	)
	(via
		(at 52.298346 -319.716658)
		(size 0.4572)
		(drill 0.2032)
		(layers "F.Cu" "B.Cu")
		(net "P3V3_AUX")
	)
	(via
		(at 356.725982 -397.519398)
		(size 0.508)
		(drill 0.254)
		(layers "F.Cu" "B.Cu")
		(net "P3V3_AUX")
	)
	(via
		(at 32.972502 -407.509218)
		(size 0.508)
		(drill 0.254)
		(layers "F.Cu" "B.Cu")
		(net "P3V3_AUX")
	)
	(via
		(at 143.94942 -76.451968)
		(size 0.508)
		(drill 0.254)
		(layers "F.Cu" "B.Cu")
		(net "P3V3_AUX")
	)
	(via
		(at 62.184788 -29.347922)
		(size 0.508)
		(drill 0.254)
		(layers "F.Cu" "B.Cu")
		(net "P3V3_AUX")
	)
	(via
		(at 168.43883 -423.890948)
		(size 0.508)
		(drill 0.254)
		(layers "F.Cu" "B.Cu")
		(net "P3V3_AUX")
	)
	(via
		(at 454.212452 -19.827748)
		(size 0.508)
		(drill 0.254)
		(layers "F.Cu" "B.Cu")
		(net "P3V3_AUX")
	)
	(via
		(at 131.95808 -122.942858)
		(size 0.508)
		(drill 0.254)
		(layers "F.Cu" "B.Cu")
		(net "P3V3_AUX")
	)
	(via
		(at 211.4296 -108.4834)
		(size 0.508)
		(drill 0.254)
		(layers "F.Cu" "B.Cu")
		(net "P3V3_AUX")
	)
	(via
		(at 436.865522 -28.617418)
		(size 0.508)
		(drill 0.254)
		(layers "F.Cu" "B.Cu")
		(net "P3V3_AUX")
	)
	(via
		(at 359.30586 -389.19277)
		(size 0.508)
		(drill 0.254)
		(layers "F.Cu" "B.Cu")
		(net "P3V3_AUX")
	)
	(via
		(at 51.9684 -440.187588)
		(size 0.508)
		(drill 0.254)
		(layers "F.Cu" "B.Cu")
		(net "P3V3_AUX")
	)
	(via
		(at 95.17888 -391.124948)
		(size 0.508)
		(drill 0.254)
		(layers "F.Cu" "B.Cu")
		(net "P3V3_AUX")
	)
	(via
		(at 12.982956 -91.658948)
		(size 0.508)
		(drill 0.254)
		(layers "F.Cu" "B.Cu")
		(net "P3V3_AUX")
	)
	(via
		(at 445.789812 -57.004712)
		(size 0.508)
		(drill 0.254)
		(layers "F.Cu" "B.Cu")
		(net "P3V3_AUX")
	)
	(via
		(at 179.12588 -127.975868)
		(size 0.508)
		(drill 0.254)
		(layers "F.Cu" "B.Cu")
		(net "P3V3_AUX")
	)
	(via
		(at 118.169944 -75.431142)
		(size 0.508)
		(drill 0.254)
		(layers "F.Cu" "B.Cu")
		(net "P3V3_AUX")
	)
	(via
		(at 25.215596 -388.408926)
		(size 0.508)
		(drill 0.254)
		(layers "F.Cu" "B.Cu")
		(net "P3V3_AUX")
	)
	(via
		(at 454.212452 -20.902168)
		(size 0.508)
		(drill 0.254)
		(layers "F.Cu" "B.Cu")
		(net "P3V3_AUX")
	)
	(via
		(at 182.12308 -56.098948)
		(size 0.508)
		(drill 0.254)
		(layers "F.Cu" "B.Cu")
		(net "P3V3_AUX")
	)
	(via
		(at 366.894872 -398.93494)
		(size 0.508)
		(drill 0.254)
		(layers "F.Cu" "B.Cu")
		(net "P3V3_AUX")
	)
	(via
		(at 69.8119 -112.410748)
		(size 0.508)
		(drill 0.254)
		(layers "F.Cu" "B.Cu")
		(net "P3V3_AUX")
	)
	(via
		(at 222.057722 -72.909938)
		(size 0.508)
		(drill 0.254)
		(layers "F.Cu" "B.Cu")
		(net "P3V3_AUX")
	)
	(via
		(at 432.999642 -391.505948)
		(size 0.508)
		(drill 0.254)
		(layers "F.Cu" "B.Cu")
		(net "P3V3_AUX")
	)
	(via
		(at 15.197582 -407.507186)
		(size 0.508)
		(drill 0.254)
		(layers "F.Cu" "B.Cu")
		(net "P3V3_AUX")
	)
	(via
		(at 184.023 -426.8216)
		(size 0.508)
		(drill 0.254)
		(layers "F.Cu" "B.Cu")
		(net "P3V3_AUX")
	)
	(via
		(at 297.41622 -420.276528)
		(size 0.508)
		(drill 0.254)
		(layers "F.Cu" "B.Cu")
		(net "P3V3_AUX")
	)
	(via
		(at 180.64988 -127.975868)
		(size 0.508)
		(drill 0.254)
		(layers "F.Cu" "B.Cu")
		(net "P3V3_AUX")
	)
	(via
		(at 102.67061 -73.94956)
		(size 0.508)
		(drill 0.254)
		(layers "F.Cu" "B.Cu")
		(net "P3V3_AUX")
	)
	(via
		(at 104.591612 -230.086662)
		(size 0.4572)
		(drill 0.2032)
		(layers "F.Cu" "B.Cu")
		(net "P3V3_AUX")
	)
	(via
		(at 72.26681 -73.828148)
		(size 0.508)
		(drill 0.254)
		(layers "F.Cu" "B.Cu")
		(net "P3V3_AUX")
	)
	(via
		(at 449.65112 -94.602808)
		(size 0.508)
		(drill 0.254)
		(layers "F.Cu" "B.Cu")
		(net "P3V3_AUX")
	)
	(via
		(at 195.20408 -351.551748)
		(size 0.508)
		(drill 0.254)
		(layers "F.Cu" "B.Cu")
		(net "P3V3_AUX")
	)
	(via
		(at 96.48444 -64.049148)
		(size 0.508)
		(drill 0.254)
		(layers "F.Cu" "B.Cu")
		(net "P3V3_AUX")
	)
	(via
		(at 448.31 -54.371748)
		(size 0.508)
		(drill 0.254)
		(layers "F.Cu" "B.Cu")
		(net "P3V3_AUX")
	)
	(via
		(at 305.58994 -431.918618)
		(size 0.508)
		(drill 0.254)
		(layers "F.Cu" "B.Cu")
		(net "P3V3_AUX")
	)
	(via
		(at 154.69616 -80.589628)
		(size 0.508)
		(drill 0.254)
		(layers "F.Cu" "B.Cu")
		(net "P3V3_AUX")
	)
	(via
		(at 62.184788 -28.331922)
		(size 0.508)
		(drill 0.254)
		(layers "F.Cu" "B.Cu")
		(net "P3V3_AUX")
	)
	(via
		(at 461.193896 -107.678728)
		(size 0.508)
		(drill 0.254)
		(layers "F.Cu" "B.Cu")
		(net "P3V3_AUX")
	)
	(via
		(at 74.615802 -73.828148)
		(size 0.508)
		(drill 0.254)
		(layers "F.Cu" "B.Cu")
		(net "P3V3_AUX")
	)
	(via
		(at 238.80318 -244.561868)
		(size 0.508)
		(drill 0.254)
		(layers "F.Cu" "B.Cu")
		(net "P3V3_AUX")
	)
	(via
		(at 418.41674 -103.866188)
		(size 0.508)
		(drill 0.254)
		(layers "F.Cu" "B.Cu")
		(net "P3V3_AUX")
	)
	(via
		(at 316.380622 -55.794148)
		(size 0.508)
		(drill 0.254)
		(layers "F.Cu" "B.Cu")
		(net "P3V3_AUX")
	)
	(via
		(at 180.4924 -92.527628)
		(size 0.508)
		(drill 0.254)
		(layers "F.Cu" "B.Cu")
		(net "P3V3_AUX")
	)
	(via
		(at 23.037292 -414.111948)
		(size 0.508)
		(drill 0.254)
		(layers "F.Cu" "B.Cu")
		(net "P3V3_AUX")
	)
	(via
		(at 334.11287 -48.063658)
		(size 0.4572)
		(drill 0.2032)
		(layers "F.Cu" "B.Cu")
		(net "P3V3_AUX")
	)
	(via
		(at 50.583846 -110.93577)
		(size 0.508)
		(drill 0.254)
		(layers "F.Cu" "B.Cu")
		(net "P3V3_AUX")
	)
	(via
		(at 192.454022 -25.565862)
		(size 0.508)
		(drill 0.254)
		(layers "F.Cu" "B.Cu")
		(net "P3V3_AUX")
	)
	(via
		(at 443.367414 -319.716658)
		(size 0.4572)
		(drill 0.2032)
		(layers "F.Cu" "B.Cu")
		(net "P3V3_AUX")
	)
	(via
		(at 47.42688 -186.654948)
		(size 0.508)
		(drill 0.254)
		(layers "F.Cu" "B.Cu")
		(net "P3V3_AUX")
	)
	(via
		(at 452.49338 -114.82451)
		(size 0.508)
		(drill 0.254)
		(layers "F.Cu" "B.Cu")
		(net "P3V3_AUX")
	)
	(via
		(at 370.323618 -394.647166)
		(size 0.508)
		(drill 0.254)
		(layers "F.Cu" "B.Cu")
		(net "P3V3_AUX")
	)
	(via
		(at 194.28968 -430.618138)
		(size 0.508)
		(drill 0.254)
		(layers "F.Cu" "B.Cu")
		(net "P3V3_AUX")
	)
	(via
		(at 30.921198 -186.874404)
		(size 0.508)
		(drill 0.254)
		(layers "F.Cu" "B.Cu")
		(net "P3V3_AUX")
	)
	(via
		(at 433.451 -105.628948)
		(size 0.508)
		(drill 0.254)
		(layers "F.Cu" "B.Cu")
		(net "P3V3_AUX")
	)
	(via
		(at 423.195242 -392.648948)
		(size 0.508)
		(drill 0.254)
		(layers "F.Cu" "B.Cu")
		(net "P3V3_AUX")
	)
	(via
		(at 361.6198 -406.5016)
		(size 0.508)
		(drill 0.254)
		(layers "F.Cu" "B.Cu")
		(net "P3V3_AUX")
	)
	(via
		(at 193.65468 -71.262748)
		(size 0.508)
		(drill 0.254)
		(layers "F.Cu" "B.Cu")
		(net "P3V3_AUX")
	)
	(via
		(at 152.30983 -121.884948)
		(size 0.508)
		(drill 0.254)
		(layers "F.Cu" "B.Cu")
		(net "P3V3_AUX")
	)
	(via
		(at 200.18248 -107.427268)
		(size 0.508)
		(drill 0.254)
		(layers "F.Cu" "B.Cu")
		(net "P3V3_AUX")
	)
	(via
		(at 368.681 -409.6512)
		(size 0.508)
		(drill 0.254)
		(layers "F.Cu" "B.Cu")
		(net "P3V3_AUX")
	)
	(via
		(at 308.567836 -438.587896)
		(size 0.508)
		(drill 0.254)
		(layers "F.Cu" "B.Cu")
		(net "P3V3_AUX")
	)
	(via
		(at 288.87801 -96.416368)
		(size 0.508)
		(drill 0.254)
		(layers "F.Cu" "B.Cu")
		(net "P3V3_AUX")
	)
	(via
		(at 132.476494 -132.707126)
		(size 0.508)
		(drill 0.254)
		(layers "F.Cu" "B.Cu")
		(net "P3V3_AUX")
	)
	(via
		(at 264.85088 -100.066348)
		(size 0.508)
		(drill 0.254)
		(layers "F.Cu" "B.Cu")
		(net "P3V3_AUX")
	)
	(via
		(at 347.145356 -27.814524)
		(size 0.508)
		(drill 0.254)
		(layers "F.Cu" "B.Cu")
		(net "P3V3_AUX")
	)
	(via
		(at 445.027812 -55.048912)
		(size 0.508)
		(drill 0.254)
		(layers "F.Cu" "B.Cu")
		(net "P3V3_AUX")
	)
	(via
		(at 262.052308 -67.08902)
		(size 0.508)
		(drill 0.254)
		(layers "F.Cu" "B.Cu")
		(net "P3V3_AUX")
	)
	(via
		(at 252.73 -38.324282)
		(size 0.508)
		(drill 0.254)
		(layers "F.Cu" "B.Cu")
		(net "P3V3_AUX")
	)
	(via
		(at 309.761636 -29.588968)
		(size 0.508)
		(drill 0.254)
		(layers "F.Cu" "B.Cu")
		(net "P3V3_AUX")
	)
	(via
		(at 181.407562 -417.303204)
		(size 0.508)
		(drill 0.254)
		(layers "F.Cu" "B.Cu")
		(net "P3V3_AUX")
	)
	(via
		(at 31.342076 -437.761888)
		(size 0.508)
		(drill 0.254)
		(layers "F.Cu" "B.Cu")
		(net "P3V3_AUX")
	)
	(via
		(at 80.767174 -60.381896)
		(size 0.508)
		(drill 0.254)
		(layers "F.Cu" "B.Cu")
		(net "P3V3_AUX")
	)
	(via
		(at 185.2041 -416.98926)
		(size 0.508)
		(drill 0.254)
		(layers "F.Cu" "B.Cu")
		(net "P3V3_AUX")
	)
	(via
		(at 416.5092 -109.215428)
		(size 0.508)
		(drill 0.254)
		(layers "F.Cu" "B.Cu")
		(net "P3V3_AUX")
	)
	(via
		(at 423.195242 -386.298948)
		(size 0.508)
		(drill 0.254)
		(layers "F.Cu" "B.Cu")
		(net "P3V3_AUX")
	)
	(via
		(at 179.41798 -11.882628)
		(size 0.508)
		(drill 0.254)
		(layers "F.Cu" "B.Cu")
		(net "P3V3_AUX")
	)
	(via
		(at 14.426946 -390.167876)
		(size 0.508)
		(drill 0.254)
		(layers "F.Cu" "B.Cu")
		(net "P3V3_AUX")
	)
	(via
		(at 276.18182 -93.741494)
		(size 0.508)
		(drill 0.254)
		(layers "F.Cu" "B.Cu")
		(net "P3V3_AUX")
	)
	(via
		(at 434.086 -104.993948)
		(size 0.508)
		(drill 0.254)
		(layers "F.Cu" "B.Cu")
		(net "P3V3_AUX")
	)
	(via
		(at 442.087 -54.600348)
		(size 0.508)
		(drill 0.254)
		(layers "F.Cu" "B.Cu")
		(net "P3V3_AUX")
	)
	(via
		(at 431.57394 -184.772808)
		(size 0.508)
		(drill 0.254)
		(layers "F.Cu" "B.Cu")
		(net "P3V3_AUX")
	)
	(via
		(at 458.455014 -319.716658)
		(size 0.4572)
		(drill 0.2032)
		(layers "F.Cu" "B.Cu")
		(net "P3V3_AUX")
	)
	(via
		(at 311.427622 -42.713148)
		(size 0.508)
		(drill 0.254)
		(layers "F.Cu" "B.Cu")
		(net "P3V3_AUX")
	)
	(via
		(at 308.491636 -39.995348)
		(size 0.508)
		(drill 0.254)
		(layers "F.Cu" "B.Cu")
		(net "P3V3_AUX")
	)
	(via
		(at 208.71688 -132.862828)
		(size 0.508)
		(drill 0.254)
		(layers "F.Cu" "B.Cu")
		(net "P3V3_AUX")
	)
	(via
		(at 343.762076 -33.480248)
		(size 0.508)
		(drill 0.254)
		(layers "F.Cu" "B.Cu")
		(net "P3V3_AUX")
	)
	(via
		(at 158.33471 -80.452468)
		(size 0.508)
		(drill 0.254)
		(layers "F.Cu" "B.Cu")
		(net "P3V3_AUX")
	)
	(via
		(at 19.181064 -106.761026)
		(size 0.508)
		(drill 0.254)
		(layers "F.Cu" "B.Cu")
		(net "P3V3_AUX")
	)
	(via
		(at 99.724464 -64.049148)
		(size 0.508)
		(drill 0.254)
		(layers "F.Cu" "B.Cu")
		(net "P3V3_AUX")
	)
	(via
		(at 254.30353 -55.854092)
		(size 0.508)
		(drill 0.254)
		(layers "F.Cu" "B.Cu")
		(net "P3V3_AUX")
	)
	(via
		(at 21.61413 -183.429656)
		(size 0.508)
		(drill 0.254)
		(layers "F.Cu" "B.Cu")
		(net "P3V3_AUX")
	)
	(via
		(at 115.149884 -38.065456)
		(size 0.508)
		(drill 0.254)
		(layers "F.Cu" "B.Cu")
		(net "P3V3_AUX")
	)
	(via
		(at 110.323122 -128.075182)
		(size 0.508)
		(drill 0.254)
		(layers "F.Cu" "B.Cu")
		(net "P3V3_AUX")
	)
	(via
		(at 114.68608 -120.862598)
		(size 0.508)
		(drill 0.254)
		(layers "F.Cu" "B.Cu")
		(net "P3V3_AUX")
	)
	(via
		(at 99.699318 -360.42981)
		(size 0.508)
		(drill 0.254)
		(layers "F.Cu" "B.Cu")
		(net "P3V3_AUX")
	)
	(via
		(at 118.216934 -108.731812)
		(size 0.508)
		(drill 0.254)
		(layers "F.Cu" "B.Cu")
		(net "P3V3_AUX")
	)
	(via
		(at 80.381602 -73.828148)
		(size 0.508)
		(drill 0.254)
		(layers "F.Cu" "B.Cu")
		(net "P3V3_AUX")
	)
	(via
		(at 341.778082 -23.191978)
		(size 0.508)
		(drill 0.254)
		(layers "F.Cu" "B.Cu")
		(net "P3V3_AUX")
	)
	(via
		(at 180.975 -20.284948)
		(size 0.508)
		(drill 0.254)
		(layers "F.Cu" "B.Cu")
		(net "P3V3_AUX")
	)
	(via
		(at 390.37895 -33.003998)
		(size 0.508)
		(drill 0.254)
		(layers "F.Cu" "B.Cu")
		(net "P3V3_AUX")
	)
	(via
		(at 398.95145 -68.035678)
		(size 0.508)
		(drill 0.254)
		(layers "F.Cu" "B.Cu")
		(net "P3V3_AUX")
	)
	(via
		(at 163.63188 -115.026948)
		(size 0.508)
		(drill 0.254)
		(layers "F.Cu" "B.Cu")
		(net "P3V3_AUX")
	)
	(via
		(at 174.1424 -92.527628)
		(size 0.508)
		(drill 0.254)
		(layers "F.Cu" "B.Cu")
		(net "P3V3_AUX")
	)
	(via
		(at 315.2521 -132.250688)
		(size 0.508)
		(drill 0.254)
		(layers "F.Cu" "B.Cu")
		(net "P3V3_AUX")
	)
	(via
		(at 311.5056 -31.8008)
		(size 0.508)
		(drill 0.254)
		(layers "F.Cu" "B.Cu")
		(net "P3V3_AUX")
	)
	(via
		(at 189.41288 -101.564948)
		(size 0.508)
		(drill 0.254)
		(layers "F.Cu" "B.Cu")
		(net "P3V3_AUX")
	)
	(via
		(at 150.42388 -44.160948)
		(size 0.508)
		(drill 0.254)
		(layers "F.Cu" "B.Cu")
		(net "P3V3_AUX")
	)
	(via
		(at 50.583846 -112.33277)
		(size 0.508)
		(drill 0.254)
		(layers "F.Cu" "B.Cu")
		(net "P3V3_AUX")
	)
	(via
		(at 147.04695 -131.278884)
		(size 0.508)
		(drill 0.254)
		(layers "F.Cu" "B.Cu")
		(net "P3V3_AUX")
	)
	(via
		(at 367.920778 -416.105848)
		(size 0.508)
		(drill 0.254)
		(layers "F.Cu" "B.Cu")
		(net "P3V3_AUX")
	)
	(via
		(at 310.571896 -44.729908)
		(size 0.508)
		(drill 0.254)
		(layers "F.Cu" "B.Cu")
		(net "P3V3_AUX")
	)
	(via
		(at 30.921198 -187.636404)
		(size 0.508)
		(drill 0.254)
		(layers "F.Cu" "B.Cu")
		(net "P3V3_AUX")
	)
	(via
		(at 310.538876 -39.177468)
		(size 0.508)
		(drill 0.254)
		(layers "F.Cu" "B.Cu")
		(net "P3V3_AUX")
	)
	(via
		(at 221.1578 -102.255574)
		(size 0.508)
		(drill 0.254)
		(layers "F.Cu" "B.Cu")
		(net "P3V3_AUX")
	)
	(via
		(at 334.099408 -47.250096)
		(size 0.4572)
		(drill 0.2032)
		(layers "F.Cu" "B.Cu")
		(net "P3V3_AUX")
	)
	(via
		(at 147.10918 -48.283368)
		(size 0.508)
		(drill 0.254)
		(layers "F.Cu" "B.Cu")
		(net "P3V3_AUX")
	)
	(via
		(at 311.427622 -35.804348)
		(size 0.508)
		(drill 0.254)
		(layers "F.Cu" "B.Cu")
		(net "P3V3_AUX")
	)
	(via
		(at 369.358418 -416.128708)
		(size 0.508)
		(drill 0.254)
		(layers "F.Cu" "B.Cu")
		(net "P3V3_AUX")
	)
	(via
		(at 420.66718 -320.129408)
		(size 0.4572)
		(drill 0.2032)
		(layers "F.Cu" "B.Cu")
		(net "P3V3_AUX")
	)
	(via
		(at 47.633128 -107.032298)
		(size 0.508)
		(drill 0.254)
		(layers "F.Cu" "B.Cu")
		(net "P3V3_AUX")
	)
	(via
		(at 37.355018 -392.68019)
		(size 0.508)
		(drill 0.254)
		(layers "F.Cu" "B.Cu")
		(net "P3V3_AUX")
	)
	(via
		(at 355.6 -416.143948)
		(size 0.508)
		(drill 0.254)
		(layers "F.Cu" "B.Cu")
		(net "P3V3_AUX")
	)
	(via
		(at 180.339746 -319.716658)
		(size 0.4572)
		(drill 0.2032)
		(layers "F.Cu" "B.Cu")
		(net "P3V3_AUX")
	)
	(via
		(at 185.22188 -127.975868)
		(size 0.508)
		(drill 0.254)
		(layers "F.Cu" "B.Cu")
		(net "P3V3_AUX")
	)
	(via
		(at 50.583846 -106.74477)
		(size 0.508)
		(drill 0.254)
		(layers "F.Cu" "B.Cu")
		(net "P3V3_AUX")
	)
	(via
		(at 181.811168 -398.135094)
		(size 0.508)
		(drill 0.254)
		(layers "F.Cu" "B.Cu")
		(net "P3V3_AUX")
	)
	(via
		(at 110.323122 -132.266182)
		(size 0.508)
		(drill 0.254)
		(layers "F.Cu" "B.Cu")
		(net "P3V3_AUX")
	)
	(via
		(at 126.89332 -19.924268)
		(size 0.508)
		(drill 0.254)
		(layers "F.Cu" "B.Cu")
		(net "P3V3_AUX")
	)
	(via
		(at 29.77388 -427.592998)
		(size 0.508)
		(drill 0.254)
		(layers "F.Cu" "B.Cu")
		(net "P3V3_AUX")
	)
	(via
		(at 427.97476 -117.60962)
		(size 0.508)
		(drill 0.254)
		(layers "F.Cu" "B.Cu")
		(net "P3V3_AUX")
	)
	(via
		(at 216.872312 -68.336922)
		(size 0.508)
		(drill 0.254)
		(layers "F.Cu" "B.Cu")
		(net "P3V3_AUX")
	)
	(via
		(at 127.77216 -73.133712)
		(size 0.508)
		(drill 0.254)
		(layers "F.Cu" "B.Cu")
		(net "P3V3_AUX")
	)
	(via
		(at 150.298658 -72.608948)
		(size 0.508)
		(drill 0.254)
		(layers "F.Cu" "B.Cu")
		(net "P3V3_AUX")
	)
	(via
		(at 67.437 -57.876948)
		(size 0.508)
		(drill 0.254)
		(layers "F.Cu" "B.Cu")
		(net "P3V3_AUX")
	)
	(via
		(at 168.426638 -417.237418)
		(size 0.508)
		(drill 0.254)
		(layers "F.Cu" "B.Cu")
		(net "P3V3_AUX")
	)
	(via
		(at 282.131516 -15.247112)
		(size 0.508)
		(drill 0.254)
		(layers "F.Cu" "B.Cu")
		(net "P3V3_AUX")
	)
	(via
		(at 57.253378 -81.745074)
		(size 0.508)
		(drill 0.254)
		(layers "F.Cu" "B.Cu")
		(net "P3V3_AUX")
	)
	(via
		(at 109.144308 -73.853802)
		(size 0.508)
		(drill 0.254)
		(layers "F.Cu" "B.Cu")
		(net "P3V3_AUX")
	)
	(via
		(at 192.947798 -79.14259)
		(size 0.508)
		(drill 0.254)
		(layers "F.Cu" "B.Cu")
		(net "P3V3_AUX")
	)
	(via
		(at 132.476494 -131.310126)
		(size 0.508)
		(drill 0.254)
		(layers "F.Cu" "B.Cu")
		(net "P3V3_AUX")
	)
	(via
		(at 128.05029 -156.365448)
		(size 0.508)
		(drill 0.254)
		(layers "F.Cu" "B.Cu")
		(net "P3V3_AUX")
	)
	(via
		(at 172.8724 -92.527628)
		(size 0.508)
		(drill 0.254)
		(layers "F.Cu" "B.Cu")
		(net "P3V3_AUX")
	)
	(via
		(at 183.69788 -127.975868)
		(size 0.508)
		(drill 0.254)
		(layers "F.Cu" "B.Cu")
		(net "P3V3_AUX")
	)
	(via
		(at 321.272916 -64.514984)
		(size 0.508)
		(drill 0.254)
		(layers "F.Cu" "B.Cu")
		(net "P3V3_AUX")
	)
	(via
		(at 70.228714 -63.998348)
		(size 0.508)
		(drill 0.254)
		(layers "F.Cu" "B.Cu")
		(net "P3V3_AUX")
	)
	(via
		(at 310.538622 -35.804348)
		(size 0.508)
		(drill 0.254)
		(layers "F.Cu" "B.Cu")
		(net "P3V3_AUX")
	)
	(via
		(at 198.12508 -112.124998)
		(size 0.508)
		(drill 0.254)
		(layers "F.Cu" "B.Cu")
		(net "P3V3_AUX")
	)
	(via
		(at 32.914844 -394.654786)
		(size 0.508)
		(drill 0.254)
		(layers "F.Cu" "B.Cu")
		(net "P3V3_AUX")
	)
	(via
		(at 371.807232 -62.216792)
		(size 0.508)
		(drill 0.254)
		(layers "F.Cu" "B.Cu")
		(net "P3V3_AUX")
	)
	(via
		(at 203.71054 -111.74476)
		(size 0.508)
		(drill 0.254)
		(layers "F.Cu" "B.Cu")
		(net "P3V3_AUX")
	)
	(via
		(at 23.041102 -401.790408)
		(size 0.508)
		(drill 0.254)
		(layers "F.Cu" "B.Cu")
		(net "P3V3_AUX")
	)
	(via
		(at 19.61388 -96.906588)
		(size 0.508)
		(drill 0.254)
		(layers "F.Cu" "B.Cu")
		(net "P3V3_AUX")
	)
	(via
		(at 255.582928 -87.371682)
		(size 0.508)
		(drill 0.254)
		(layers "F.Cu" "B.Cu")
		(net "P3V3_AUX")
	)
	(via
		(at 121.38787 -422.463468)
		(size 0.508)
		(drill 0.254)
		(layers "F.Cu" "B.Cu")
		(net "P3V3_AUX")
	)
	(via
		(at 219.10548 -128.819148)
		(size 0.508)
		(drill 0.254)
		(layers "F.Cu" "B.Cu")
		(net "P3V3_AUX")
	)
	(via
		(at 159.66186 -14.889988)
		(size 0.508)
		(drill 0.254)
		(layers "F.Cu" "B.Cu")
		(net "P3V3_AUX")
	)
	(via
		(at 33.35782 -169.09796)
		(size 0.508)
		(drill 0.254)
		(layers "F.Cu" "B.Cu")
		(net "P3V3_AUX")
	)
	(via
		(at 311.427622 -43.932348)
		(size 0.508)
		(drill 0.254)
		(layers "F.Cu" "B.Cu")
		(net "P3V3_AUX")
	)
	(via
		(at 348.206314 -358.217724)
		(size 0.508)
		(drill 0.254)
		(layers "F.Cu" "B.Cu")
		(net "P3V3_AUX")
	)
	(via
		(at 145.57121 -40.952928)
		(size 0.508)
		(drill 0.254)
		(layers "F.Cu" "B.Cu")
		(net "P3V3_AUX")
	)
	(via
		(at 7.035546 -319.716658)
		(size 0.4572)
		(drill 0.2032)
		(layers "F.Cu" "B.Cu")
		(net "P3V3_AUX")
	)
	(via
		(at 451.809612 -56.369712)
		(size 0.508)
		(drill 0.254)
		(layers "F.Cu" "B.Cu")
		(net "P3V3_AUX")
	)
	(via
		(at 76.90231 -73.828148)
		(size 0.508)
		(drill 0.254)
		(layers "F.Cu" "B.Cu")
		(net "P3V3_AUX")
	)
	(via
		(at 428.279814 -319.716658)
		(size 0.4572)
		(drill 0.2032)
		(layers "F.Cu" "B.Cu")
		(net "P3V3_AUX")
	)
	(via
		(at 31.683198 -186.874404)
		(size 0.508)
		(drill 0.254)
		(layers "F.Cu" "B.Cu")
		(net "P3V3_AUX")
	)
	(via
		(at 150.29688 -110.219998)
		(size 0.508)
		(drill 0.254)
		(layers "F.Cu" "B.Cu")
		(net "P3V3_AUX")
	)
	(via
		(at 368.121184 -103.466138)
		(size 0.508)
		(drill 0.254)
		(layers "F.Cu" "B.Cu")
		(net "P3V3_AUX")
	)
	(via
		(at 147.95754 -79.139034)
		(size 0.508)
		(drill 0.254)
		(layers "F.Cu" "B.Cu")
		(net "P3V3_AUX")
	)
	(via
		(at 263.73328 -103.393748)
		(size 0.508)
		(drill 0.254)
		(layers "F.Cu" "B.Cu")
		(net "P3V3_AUX")
	)
	(via
		(at 449.199 -54.371748)
		(size 0.508)
		(drill 0.254)
		(layers "F.Cu" "B.Cu")
		(net "P3V3_AUX")
	)
	(via
		(at 119.6086 -59.635898)
		(size 0.508)
		(drill 0.254)
		(layers "F.Cu" "B.Cu")
		(net "P3V3_AUX")
	)
	(via
		(at 22.123146 -319.716658)
		(size 0.4572)
		(drill 0.2032)
		(layers "F.Cu" "B.Cu")
		(net "P3V3_AUX")
	)
	(via
		(at 16.13916 -111.455708)
		(size 0.508)
		(drill 0.254)
		(layers "F.Cu" "B.Cu")
		(net "P3V3_AUX")
	)
	(via
		(at 14.689582 -424.639486)
		(size 0.508)
		(drill 0.254)
		(layers "F.Cu" "B.Cu")
		(net "P3V3_AUX")
	)
	(via
		(at 284.050486 -28.368498)
		(size 0.508)
		(drill 0.254)
		(layers "F.Cu" "B.Cu")
		(net "P3V3_AUX")
	)
	(via
		(at 123.662694 -77.571092)
		(size 0.508)
		(drill 0.254)
		(layers "F.Cu" "B.Cu")
		(net "P3V3_AUX")
	)
	(via
		(at 270.063214 -319.716658)
		(size 0.4572)
		(drill 0.2032)
		(layers "F.Cu" "B.Cu")
		(net "P3V3_AUX")
	)
	(via
		(at 330.45146 -30.940248)
		(size 0.508)
		(drill 0.254)
		(layers "F.Cu" "B.Cu")
		(net "P3V3_AUX")
	)
	(via
		(at 442.087 -53.838348)
		(size 0.508)
		(drill 0.254)
		(layers "F.Cu" "B.Cu")
		(net "P3V3_AUX")
	)
	(via
		(at 215.0618 -121.1326)
		(size 0.508)
		(drill 0.254)
		(layers "F.Cu" "B.Cu")
		(net "P3V3_AUX")
	)
	(via
		(at 99.10572 -423.725848)
		(size 0.508)
		(drill 0.254)
		(layers "F.Cu" "B.Cu")
		(net "P3V3_AUX")
	)
	(via
		(at 137.068306 -69.080888)
		(size 0.508)
		(drill 0.254)
		(layers "F.Cu" "B.Cu")
		(net "P3V3_AUX")
	)
	(via
		(at 437.66486 -43.960288)
		(size 0.508)
		(drill 0.254)
		(layers "F.Cu" "B.Cu")
		(net "P3V3_AUX")
	)
	(via
		(at 285.150814 -319.716658)
		(size 0.4572)
		(drill 0.2032)
		(layers "F.Cu" "B.Cu")
		(net "P3V3_AUX")
	)
	(via
		(at 354.7364 -402.9456)
		(size 0.508)
		(drill 0.254)
		(layers "F.Cu" "B.Cu")
		(net "P3V3_AUX")
	)
	(via
		(at 127.568706 -80.112616)
		(size 0.508)
		(drill 0.254)
		(layers "F.Cu" "B.Cu")
		(net "P3V3_AUX")
	)
	(via
		(at 335.953608 -53.149246)
		(size 0.4572)
		(drill 0.2032)
		(layers "F.Cu" "B.Cu")
		(net "P3V3_AUX")
	)
	(via
		(at 451.809612 -55.099712)
		(size 0.508)
		(drill 0.254)
		(layers "F.Cu" "B.Cu")
		(net "P3V3_AUX")
	)
	(via
		(at 433.070762 -397.270478)
		(size 0.508)
		(drill 0.254)
		(layers "F.Cu" "B.Cu")
		(net "P3V3_AUX")
	)
	(via
		(at 438.9882 -95.957898)
		(size 0.508)
		(drill 0.254)
		(layers "F.Cu" "B.Cu")
		(net "P3V3_AUX")
	)
	(via
		(at 80.550766 -63.998348)
		(size 0.508)
		(drill 0.254)
		(layers "F.Cu" "B.Cu")
		(net "P3V3_AUX")
	)
	(via
		(at 450.088 -54.371748)
		(size 0.508)
		(drill 0.254)
		(layers "F.Cu" "B.Cu")
		(net "P3V3_AUX")
	)
	(via
		(at 352.53168 -230.086662)
		(size 0.4572)
		(drill 0.2032)
		(layers "F.Cu" "B.Cu")
		(net "P3V3_AUX")
	)
	(via
		(at 309.57774 -431.985928)
		(size 0.508)
		(drill 0.254)
		(layers "F.Cu" "B.Cu")
		(net "P3V3_AUX")
	)
	(via
		(at 358.3686 -412.6992)
		(size 0.508)
		(drill 0.254)
		(layers "F.Cu" "B.Cu")
		(net "P3V3_AUX")
	)
	(via
		(at 430.677066 -102.61219)
		(size 0.508)
		(drill 0.254)
		(layers "F.Cu" "B.Cu")
		(net "P3V3_AUX")
	)
	(via
		(at 335.138268 -44.221146)
		(size 0.4572)
		(drill 0.2032)
		(layers "F.Cu" "B.Cu")
		(net "P3V3_AUX")
	)
	(via
		(at 294.62222 -420.276528)
		(size 0.508)
		(drill 0.254)
		(layers "F.Cu" "B.Cu")
		(net "P3V3_AUX")
	)
	(via
		(at 92.33535 -40.310308)
		(size 0.508)
		(drill 0.254)
		(layers "F.Cu" "B.Cu")
		(net "P3V3_AUX")
	)
	(via
		(at 200.94956 -193.470022)
		(size 0.508)
		(drill 0.254)
		(layers "F.Cu" "B.Cu")
		(net "P3V3_AUX")
	)
	(via
		(at 73.475596 -73.828148)
		(size 0.508)
		(drill 0.254)
		(layers "F.Cu" "B.Cu")
		(net "P3V3_AUX")
	)
	(via
		(at 375.04878 -421.925496)
		(size 0.508)
		(drill 0.254)
		(layers "F.Cu" "B.Cu")
		(net "P3V3_AUX")
	)
	(via
		(at 172.795946 -319.716658)
		(size 0.4572)
		(drill 0.2032)
		(layers "F.Cu" "B.Cu")
		(net "P3V3_AUX")
	)
	(via
		(at 415.7472 -109.977428)
		(size 0.508)
		(drill 0.254)
		(layers "F.Cu" "B.Cu")
		(net "P3V3_AUX")
	)
	(via
		(at 438.8358 -105.98531)
		(size 0.508)
		(drill 0.254)
		(layers "F.Cu" "B.Cu")
		(net "P3V3_AUX")
	)
	(via
		(at 415.7472 -111.501428)
		(size 0.508)
		(drill 0.254)
		(layers "F.Cu" "B.Cu")
		(net "P3V3_AUX")
	)
	(via
		(at 50.583846 -113.72977)
		(size 0.508)
		(drill 0.254)
		(layers "F.Cu" "B.Cu")
		(net "P3V3_AUX")
	)
	(via
		(at 303.186084 -426.957236)
		(size 0.508)
		(drill 0.254)
		(layers "F.Cu" "B.Cu")
		(net "P3V3_AUX")
	)
	(via
		(at 209.070956 -29.266642)
		(size 0.508)
		(drill 0.254)
		(layers "F.Cu" "B.Cu")
		(net "P3V3_AUX")
	)
	(via
		(at 431.609754 -135.545068)
		(size 0.508)
		(drill 0.254)
		(layers "F.Cu" "B.Cu")
		(net "P3V3_AUX")
	)
	(via
		(at 441.325 -57.648348)
		(size 0.508)
		(drill 0.254)
		(layers "F.Cu" "B.Cu")
		(net "P3V3_AUX")
	)
	(via
		(at 177.18913 -422.366948)
		(size 0.508)
		(drill 0.254)
		(layers "F.Cu" "B.Cu")
		(net "P3V3_AUX")
	)
	(via
		(at 107.84078 -401.184364)
		(size 0.508)
		(drill 0.254)
		(layers "F.Cu" "B.Cu")
		(net "P3V3_AUX")
	)
	(via
		(at 159.909256 -64.294258)
		(size 0.508)
		(drill 0.254)
		(layers "F.Cu" "B.Cu")
		(net "P3V3_AUX")
	)
	(via
		(at 22.23008 -100.54971)
		(size 0.508)
		(drill 0.254)
		(layers "F.Cu" "B.Cu")
		(net "P3V3_AUX")
	)
	(via
		(at 189.28588 -131.280408)
		(size 0.508)
		(drill 0.254)
		(layers "F.Cu" "B.Cu")
		(net "P3V3_AUX")
	)
	(via
		(at 283.821378 -413.63773)
		(size 0.508)
		(drill 0.254)
		(layers "F.Cu" "B.Cu")
		(net "P3V3_AUX")
	)
	(via
		(at 175.0568 -418.806122)
		(size 0.508)
		(drill 0.254)
		(layers "F.Cu" "B.Cu")
		(net "P3V3_AUX")
	)
	(via
		(at 219.674186 -47.52594)
		(size 0.508)
		(drill 0.254)
		(layers "F.Cu" "B.Cu")
		(net "P3V3_AUX")
	)
	(via
		(at 85.598 -55.082948)
		(size 0.508)
		(drill 0.254)
		(layers "F.Cu" "B.Cu")
		(net "P3V3_AUX")
	)
	(via
		(at 276.18182 -95.029274)
		(size 0.508)
		(drill 0.254)
		(layers "F.Cu" "B.Cu")
		(net "P3V3_AUX")
	)
	(via
		(at 244.819424 -101.168708)
		(size 0.508)
		(drill 0.254)
		(layers "F.Cu" "B.Cu")
		(net "P3V3_AUX")
	)
	(via
		(at 195.411598 -193.23685)
		(size 0.508)
		(drill 0.254)
		(layers "F.Cu" "B.Cu")
		(net "P3V3_AUX")
	)
	(via
		(at 72.766174 -63.998348)
		(size 0.508)
		(drill 0.254)
		(layers "F.Cu" "B.Cu")
		(net "P3V3_AUX")
	)
	(via
		(at 440.653678 -46.95571)
		(size 0.508)
		(drill 0.254)
		(layers "F.Cu" "B.Cu")
		(net "P3V3_AUX")
	)
	(via
		(at 133.20395 -124.234448)
		(size 0.508)
		(drill 0.254)
		(layers "F.Cu" "B.Cu")
		(net "P3V3_AUX")
	)
	(via
		(at 74.106786 -63.998348)
		(size 0.508)
		(drill 0.254)
		(layers "F.Cu" "B.Cu")
		(net "P3V3_AUX")
	)
	(via
		(at 303.072292 -148.887688)
		(size 0.508)
		(drill 0.254)
		(layers "F.Cu" "B.Cu")
		(net "P3V3_AUX")
	)
	(via
		(at 332.276196 -17.437608)
		(size 0.508)
		(drill 0.254)
		(layers "F.Cu" "B.Cu")
		(net "P3V3_AUX")
	)
	(via
		(at 316.1411 -132.250688)
		(size 0.508)
		(drill 0.254)
		(layers "F.Cu" "B.Cu")
		(net "P3V3_AUX")
	)
	(via
		(at 289.94735 -405.79802)
		(size 0.508)
		(drill 0.254)
		(layers "F.Cu" "B.Cu")
		(net "P3V3_AUX")
	)
	(via
		(at 210.514946 -319.716658)
		(size 0.4572)
		(drill 0.2032)
		(layers "F.Cu" "B.Cu")
		(net "P3V3_AUX")
	)
	(via
		(at 15.067788 -91.618308)
		(size 0.508)
		(drill 0.254)
		(layers "F.Cu" "B.Cu")
		(net "P3V3_AUX")
	)
	(via
		(at 215.58123 -40.687498)
		(size 0.508)
		(drill 0.254)
		(layers "F.Cu" "B.Cu")
		(net "P3V3_AUX")
	)
	(via
		(at 37.210746 -319.716658)
		(size 0.4572)
		(drill 0.2032)
		(layers "F.Cu" "B.Cu")
		(net "P3V3_AUX")
	)
	(via
		(at 365.78667 -404.711408)
		(size 0.508)
		(drill 0.254)
		(layers "F.Cu" "B.Cu")
		(net "P3V3_AUX")
	)
	(via
		(at 442.087 -57.648348)
		(size 0.508)
		(drill 0.254)
		(layers "F.Cu" "B.Cu")
		(net "P3V3_AUX")
	)
	(via
		(at 157.74924 -68.850764)
		(size 0.508)
		(drill 0.254)
		(layers "F.Cu" "B.Cu")
		(net "P3V3_AUX")
	)
	(via
		(at 384.706622 -59.719464)
		(size 0.508)
		(drill 0.254)
		(layers "F.Cu" "B.Cu")
		(net "P3V3_AUX")
	)
	(via
		(at 141.01953 -43.652948)
		(size 0.508)
		(drill 0.254)
		(layers "F.Cu" "B.Cu")
		(net "P3V3_AUX")
	)
	(via
		(at 90.086688 -64.184022)
		(size 0.508)
		(drill 0.254)
		(layers "F.Cu" "B.Cu")
		(net "P3V3_AUX")
	)
	(via
		(at 396.127478 -150.69566)
		(size 0.508)
		(drill 0.254)
		(layers "F.Cu" "B.Cu")
		(net "P3V3_AUX")
	)
	(via
		(at 365.3282 -407.0604)
		(size 0.508)
		(drill 0.254)
		(layers "F.Cu" "B.Cu")
		(net "P3V3_AUX")
	)
	(via
		(at 144.48536 -127.265684)
		(size 0.508)
		(drill 0.254)
		(layers "F.Cu" "B.Cu")
		(net "P3V3_AUX")
	)
	(via
		(at 462.60512 -105.011728)
		(size 0.508)
		(drill 0.254)
		(layers "F.Cu" "B.Cu")
		(net "P3V3_AUX")
	)
	(via
		(at 110.323122 -137.854182)
		(size 0.508)
		(drill 0.254)
		(layers "F.Cu" "B.Cu")
		(net "P3V3_AUX")
	)
	(via
		(at 19.83232 -178.265328)
		(size 0.508)
		(drill 0.254)
		(layers "F.Cu" "B.Cu")
		(net "P3V3_AUX")
	)
	(via
		(at 113.28908 -398.884648)
		(size 0.508)
		(drill 0.254)
		(layers "F.Cu" "B.Cu")
		(net "P3V3_AUX")
	)
	(via
		(at 464.036156 -109.656372)
		(size 0.508)
		(drill 0.254)
		(layers "F.Cu" "B.Cu")
		(net "P3V3_AUX")
	)
	(via
		(at 436.39994 -40.39616)
		(size 0.508)
		(drill 0.254)
		(layers "F.Cu" "B.Cu")
		(net "P3V3_AUX")
	)
	(via
		(at 361.93222 -364.1979)
		(size 0.508)
		(drill 0.254)
		(layers "F.Cu" "B.Cu")
		(net "P3V3_AUX")
	)
	(via
		(at 166.80815 -421.835326)
		(size 0.508)
		(drill 0.254)
		(layers "F.Cu" "B.Cu")
		(net "P3V3_AUX")
	)
	(via
		(at 104.103678 -427.422818)
		(size 0.508)
		(drill 0.254)
		(layers "F.Cu" "B.Cu")
		(net "P3V3_AUX")
	)
	(via
		(at 445.789812 -55.099712)
		(size 0.508)
		(drill 0.254)
		(layers "F.Cu" "B.Cu")
		(net "P3V3_AUX")
	)
	(via
		(at 147.188174 -52.420012)
		(size 0.508)
		(drill 0.254)
		(layers "F.Cu" "B.Cu")
		(net "P3V3_AUX")
	)
	(via
		(at 89.69883 -55.717948)
		(size 0.508)
		(drill 0.254)
		(layers "F.Cu" "B.Cu")
		(net "P3V3_AUX")
	)
	(via
		(at 165.252146 -319.716658)
		(size 0.4572)
		(drill 0.2032)
		(layers "F.Cu" "B.Cu")
		(net "P3V3_AUX")
	)
	(via
		(at 452.710296 -104.249728)
		(size 0.508)
		(drill 0.254)
		(layers "F.Cu" "B.Cu")
		(net "P3V3_AUX")
	)
	(via
		(at 263.73328 -102.733348)
		(size 0.508)
		(drill 0.254)
		(layers "F.Cu" "B.Cu")
		(net "P3V3_AUX")
	)
	(via
		(at 393.37488 -147.792948)
		(size 0.508)
		(drill 0.254)
		(layers "F.Cu" "B.Cu")
		(net "P3V3_AUX")
	)
	(via
		(at 237.037118 -96.696022)
		(size 0.508)
		(drill 0.254)
		(layers "F.Cu" "B.Cu")
		(net "P3V3_AUX")
	)
	(via
		(at 104.3178 -420.44874)
		(size 0.508)
		(drill 0.254)
		(layers "F.Cu" "B.Cu")
		(net "P3V3_AUX")
	)
	(via
		(at 303.066196 -438.509156)
		(size 0.508)
		(drill 0.254)
		(layers "F.Cu" "B.Cu")
		(net "P3V3_AUX")
	)
	(via
		(at 128.85928 -32.662368)
		(size 0.508)
		(drill 0.254)
		(layers "F.Cu" "B.Cu")
		(net "P3V3_AUX")
	)
	(via
		(at 210.086956 -29.266642)
		(size 0.508)
		(drill 0.254)
		(layers "F.Cu" "B.Cu")
		(net "P3V3_AUX")
	)
	(via
		(at 132.476494 -128.516126)
		(size 0.508)
		(drill 0.254)
		(layers "F.Cu" "B.Cu")
		(net "P3V3_AUX")
	)
	(via
		(at 126.770384 -64.125348)
		(size 0.508)
		(drill 0.254)
		(layers "F.Cu" "B.Cu")
		(net "P3V3_AUX")
	)
	(via
		(at 103.53675 -394.353288)
		(size 0.508)
		(drill 0.254)
		(layers "F.Cu" "B.Cu")
		(net "P3V3_AUX")
	)
	(via
		(at 227.32111 -233.025188)
		(size 0.508)
		(drill 0.254)
		(layers "F.Cu" "B.Cu")
		(net "P3V3_AUX")
	)
	(via
		(at 223.545908 -234.50169)
		(size 0.508)
		(drill 0.254)
		(layers "F.Cu" "B.Cu")
		(net "P3V3_AUX")
	)
	(via
		(at 29.11983 -431.510948)
		(size 0.508)
		(drill 0.254)
		(layers "F.Cu" "B.Cu")
		(net "P3V3_AUX")
	)
	(via
		(at 172.62856 -410.85008)
		(size 0.508)
		(drill 0.254)
		(layers "F.Cu" "B.Cu")
		(net "P3V3_AUX")
	)
	(via
		(at 82.14868 -52.717446)
		(size 0.508)
		(drill 0.254)
		(layers "F.Cu" "B.Cu")
		(net "P3V3_AUX")
	)
	(via
		(at 350.117918 -359.484168)
		(size 0.508)
		(drill 0.254)
		(layers "F.Cu" "B.Cu")
		(net "P3V3_AUX")
	)
	(via
		(at 304.09896 -431.907188)
		(size 0.508)
		(drill 0.254)
		(layers "F.Cu" "B.Cu")
		(net "P3V3_AUX")
	)
	(via
		(at 194.61353 -108.765848)
		(size 0.508)
		(drill 0.254)
		(layers "F.Cu" "B.Cu")
		(net "P3V3_AUX")
	)
	(via
		(at 356.725982 -398.789398)
		(size 0.508)
		(drill 0.254)
		(layers "F.Cu" "B.Cu")
		(net "P3V3_AUX")
	)
	(via
		(at 83.0326 -41.220898)
		(size 0.508)
		(drill 0.254)
		(layers "F.Cu" "B.Cu")
		(net "P3V3_AUX")
	)
	(via
		(at 342.79078 -26.453338)
		(size 0.508)
		(drill 0.254)
		(layers "F.Cu" "B.Cu")
		(net "P3V3_AUX")
	)
	(via
		(at 368.1984 -102.189788)
		(size 0.508)
		(drill 0.254)
		(layers "F.Cu" "B.Cu")
		(net "P3V3_AUX")
	)
	(via
		(at 110.323122 -139.133326)
		(size 0.508)
		(drill 0.254)
		(layers "F.Cu" "B.Cu")
		(net "P3V3_AUX")
	)
	(via
		(at 163.576 -111.470948)
		(size 0.508)
		(drill 0.254)
		(layers "F.Cu" "B.Cu")
		(net "P3V3_AUX")
	)
	(via
		(at 407.48458 -58.79846)
		(size 0.508)
		(drill 0.254)
		(layers "F.Cu" "B.Cu")
		(net "P3V3_AUX")
	)
	(via
		(at 441.325 -56.886348)
		(size 0.508)
		(drill 0.254)
		(layers "F.Cu" "B.Cu")
		(net "P3V3_AUX")
	)
	(via
		(at 302.895 -420.355268)
		(size 0.508)
		(drill 0.254)
		(layers "F.Cu" "B.Cu")
		(net "P3V3_AUX")
	)
	(via
		(at 19.59991 -77.028548)
		(size 0.508)
		(drill 0.254)
		(layers "F.Cu" "B.Cu")
		(net "P3V3_AUX")
	)
	(via
		(at 442.087 -56.886348)
		(size 0.508)
		(drill 0.254)
		(layers "F.Cu" "B.Cu")
		(net "P3V3_AUX")
	)
	(via
		(at 351.80778 -235.830872)
		(size 0.4572)
		(drill 0.2032)
		(layers "F.Cu" "B.Cu")
		(net "P3V3_AUX")
	)
	(via
		(at 50.583846 -115.12677)
		(size 0.508)
		(drill 0.254)
		(layers "F.Cu" "B.Cu")
		(net "P3V3_AUX")
	)
	(via
		(at 277.607014 -319.716658)
		(size 0.4572)
		(drill 0.2032)
		(layers "F.Cu" "B.Cu")
		(net "P3V3_AUX")
	)
	(via
		(at 132.476494 -137.114026)
		(size 0.508)
		(drill 0.254)
		(layers "F.Cu" "B.Cu")
		(net "P3V3_AUX")
	)
	(via
		(at 141.688566 -115.437666)
		(size 0.508)
		(drill 0.254)
		(layers "F.Cu" "B.Cu")
		(net "P3V3_AUX")
	)
	(via
		(at 133.015228 -77.353414)
		(size 0.508)
		(drill 0.254)
		(layers "F.Cu" "B.Cu")
		(net "P3V3_AUX")
	)
	(via
		(at 49.096422 -437.438038)
		(size 0.508)
		(drill 0.254)
		(layers "F.Cu" "B.Cu")
		(net "P3V3_AUX")
	)
	(via
		(at 135.2931 -113.384584)
		(size 0.508)
		(drill 0.254)
		(layers "F.Cu" "B.Cu")
		(net "P3V3_AUX")
	)
	(segment
		(start 63.801498 -318.77635)
		(end 64.404494 -318.77635)
		(width 0.381)
		(layer "B.Cu")
		(net "P3V3_AUX")
	)
	(segment
		(start 186.572398 -317.066422)
		(end 186.01944 -316.513464)
		(width 0.381)
		(layer "B.Cu")
		(net "P3V3_AUX")
	)
	(segment
		(start 207.6069 -134.48538)
		(end 208.0387 -134.91718)
		(width 0.508)
		(layer "B.Cu")
		(net "P3V3_AUX")
	)
	(segment
		(start 186.597036 -319.716658)
		(end 186.519312 -319.638934)
		(width 0.381)
		(layer "B.Cu")
		(net "P3V3_AUX")
	)
	(segment
		(start 435.327552 -317.790576)
		(end 434.941218 -318.72301)
		(width 0.3048)
		(layer "B.Cu")
		(net "P3V3_AUX")
	)
	(segment
		(start 127.83058 -31.929578)
		(end 127.83058 -32.662368)
		(width 0.381)
		(layer "B.Cu")
		(net "P3V3_AUX")
	)
	(segment
		(start 205.9559 -193.37401)
		(end 205.194408 -193.37401)
		(width 0.381)
		(layer "B.Cu")
		(net "P3V3_AUX")
	)
	(segment
		(start 291.964618 -149.253448)
		(end 291.964618 -149.592538)
		(width 0.381)
		(layer "B.Cu")
		(net "P3V3_AUX")
	)
	(segment
		(start 307.04282 -319.199768)
		(end 307.221128 -319.02146)
		(width 0.381)
		(layer "B.Cu")
		(net "P3V3_AUX")
	)
	(segment
		(start 37.399468 -130.76174)
		(end 37.976048 -130.76174)
		(width 0.381)
		(layer "B.Cu")
		(net "P3V3_AUX")
	)
	(segment
		(start 156.63545 -8.801608)
		(end 156.63545 -8.071358)
		(width 0.381)
		(layer "B.Cu")
		(net "P3V3_AUX")
	)
	(segment
		(start 292.959282 -319.716658)
		(end 293.412164 -319.263776)
		(width 0.381)
		(layer "B.Cu")
		(net "P3V3_AUX")
	)
	(segment
		(start 216.762838 -315.49975)
		(end 216.197942 -314.934854)
		(width 0.381)
		(layer "B.Cu")
		(net "P3V3_AUX")
	)
	(segment
		(start 255.582928 -87.371682)
		(end 255.035812 -86.824566)
		(width 0.381)
		(layer "B.Cu")
		(net "P3V3_AUX")
	)
	(segment
		(start 210.086956 -29.266642)
		(end 208.290668 -31.06293)
		(width 0.508)
		(layer "B.Cu")
		(net "P3V3_AUX")
	)
	(segment
		(start 466.386164 -44.400724)
		(end 466.386164 -47.082964)
		(width 0.381)
		(layer "B.Cu")
		(net "P3V3_AUX")
	)
	(segment
		(start 210.514946 -319.716658)
		(end 210.784694 -319.716658)
		(width 0.381)
		(layer "B.Cu")
		(net "P3V3_AUX")
	)
	(segment
		(start 181.530752 -192.299844)
		(end 180.514752 -192.299844)
		(width 0.381)
		(layer "B.Cu")
		(net "P3V3_AUX")
	)
	(segment
		(start 434.482494 -319.662048)
		(end 434.089302 -319.268856)
		(width 0.381)
		(layer "B.Cu")
		(net "P3V3_AUX")
	)
	(segment
		(start 15.13205 -319.716658)
		(end 15.296896 -319.551812)
		(width 0.381)
		(layer "B.Cu")
		(net "P3V3_AUX")
	)
	(segment
		(start 429.114966 -128.641348)
		(end 429.546766 -128.209548)
		(width 0.508)
		(layer "B.Cu")
		(net "P3V3_AUX")
	)
	(segment
		(start 188.663072 -318.148462)
		(end 188.245496 -317.730886)
		(width 0.381)
		(layer "B.Cu")
		(net "P3V3_AUX")
	)
	(segment
		(start 10.958322 -183.482996)
		(end 11.169396 -183.482996)
		(width 0.381)
		(layer "B.Cu")
		(net "P3V3_AUX")
	)
	(segment
		(start 207.786732 -132.862828)
		(end 207.6069 -133.04266)
		(width 0.508)
		(layer "B.Cu")
		(net "P3V3_AUX")
	)
	(segment
		(start 428.79391 -319.46723)
		(end 428.997364 -319.263776)
		(width 0.381)
		(layer "B.Cu")
		(net "P3V3_AUX")
	)
	(segment
		(start 435.183788 -316.032896)
		(end 435.183788 -317.386208)
		(width 0.3048)
		(layer "B.Cu")
		(net "P3V3_AUX")
	)
	(segment
		(start 421.545766 -128.641348)
		(end 429.114966 -128.641348)
		(width 0.508)
		(layer "B.Cu")
		(net "P3V3_AUX")
	)
	(segment
		(start 368.075972 -184.801002)
		(end 369.117372 -184.801002)
		(width 0.381)
		(layer "B.Cu")
		(net "P3V3_AUX")
	)
	(segment
		(start 431.034444 -135.545068)
		(end 431.000154 -135.510778)
		(width 0.381)
		(layer "B.Cu")
		(net "P3V3_AUX")
	)
	(segment
		(start 318.768476 -40.313864)
		(end 319.14211 -40.687498)
		(width 0.381)
		(layer "B.Cu")
		(net "P3V3_AUX")
	)
	(segment
		(start 163.36518 -43.525948)
		(end 163.24834 -43.409108)
		(width 0.381)
		(layer "B.Cu")
		(net "P3V3_AUX")
	)
	(segment
		(start 181.53126 -26.693368)
		(end 181.53126 -25.578308)
		(width 0.381)
		(layer "B.Cu")
		(net "P3V3_AUX")
	)
	(segment
		(start 210.6676 -192.634108)
		(end 210.63077 -192.634108)
		(width 0.381)
		(layer "B.Cu")
		(net "P3V3_AUX")
	)
	(segment
		(start 187.632848 -317.730886)
		(end 186.968384 -317.066422)
		(width 0.381)
		(layer "B.Cu")
		(net "P3V3_AUX")
	)
	(segment
		(start 64.404494 -318.77635)
		(end 64.590168 -318.962024)
		(width 0.381)
		(layer "B.Cu")
		(net "P3V3_AUX")
	)
	(segment
		(start 181.374034 -422.615868)
		(end 180.764434 -422.615868)
		(width 0.381)
		(layer "B.Cu")
		(net "P3V3_AUX")
	)
	(segment
		(start 250.000516 -105.656634)
		(end 250.000516 -106.268266)
		(width 0.381)
		(layer "B.Cu")
		(net "P3V3_AUX")
	)
	(segment
		(start 208.290668 -31.06293)
		(end 205.348586 -31.06293)
		(width 0.508)
		(layer "B.Cu")
		(net "P3V3_AUX")
	)
	(segment
		(start 196.017896 -193.91757)
		(end 195.042028 -193.91757)
		(width 0.381)
		(layer "B.Cu")
		(net "P3V3_AUX")
	)
	(segment
		(start 159.47009 -319.656714)
		(end 159.17672 -319.363344)
		(width 0.381)
		(layer "B.Cu")
		(net "P3V3_AUX")
	)
	(segment
		(start 325.837296 -27.653488)
		(end 325.837296 -28.275026)
		(width 0.381)
		(layer "B.Cu")
		(net "P3V3_AUX")
	)
	(segment
		(start 195.427346 -319.716658)
		(end 195.697094 -319.716658)
		(width 0.381)
		(layer "B.Cu")
		(net "P3V3_AUX")
	)
	(segment
		(start 182.0926 -22.266148)
		(end 181.59095 -21.764498)
		(width 0.381)
		(layer "B.Cu")
		(net "P3V3_AUX")
	)
	(segment
		(start 211.634578 -318.44361)
		(end 211.634578 -317.349886)
		(width 0.381)
		(layer "B.Cu")
		(net "P3V3_AUX")
	)
	(segment
		(start 163.24834 -43.409108)
		(end 161.83356 -43.409108)
		(width 0.381)
		(layer "B.Cu")
		(net "P3V3_AUX")
	)
	(segment
		(start 200.610978 -193.8401)
		(end 200.431908 -194.01917)
		(width 0.381)
		(layer "B.Cu")
		(net "P3V3_AUX")
	)
	(segment
		(start 137.02665 -30.168088)
		(end 137.43686 -29.757878)
		(width 0.381)
		(layer "B.Cu")
		(net "P3V3_AUX")
	)
	(segment
		(start 68.223638 -321.185286)
		(end 68.223638 -320.30543)
		(width 0.381)
		(layer "B.Cu")
		(net "P3V3_AUX")
	)
	(segment
		(start 194.39509 -119.266208)
		(end 194.31635 -119.344948)
		(width 0.381)
		(layer "B.Cu")
		(net "P3V3_AUX")
	)
	(segment
		(start 162.306 -16.112998)
		(end 161.29 -16.112998)
		(width 0.381)
		(layer "B.Cu")
		(net "P3V3_AUX")
	)
	(segment
		(start 60.16498 -319.393824)
		(end 60.526168 -319.393824)
		(width 0.381)
		(layer "B.Cu")
		(net "P3V3_AUX")
	)
	(segment
		(start 59.842146 -319.716658)
		(end 60.16498 -319.393824)
		(width 0.381)
		(layer "B.Cu")
		(net "P3V3_AUX")
	)
	(segment
		(start 195.697094 -319.716658)
		(end 196.144896 -319.268856)
		(width 0.381)
		(layer "B.Cu")
		(net "P3V3_AUX")
	)
	(segment
		(start 186.43219 -315.458602)
		(end 186.568334 -315.458602)
		(width 0.381)
		(layer "B.Cu")
		(net "P3V3_AUX")
	)
	(segment
		(start 204.569822 -79.736188)
		(end 205.373986 -79.736188)
		(width 0.381)
		(layer "B.Cu")
		(net "P3V3_AUX")
	)
	(segment
		(start 32.027368 -161.57702)
		(end 32.876998 -160.72739)
		(width 0.381)
		(layer "B.Cu")
		(net "P3V3_AUX")
	)
	(segment
		(start 32.254952 -170.05427)
		(end 32.254952 -170.381676)
		(width 0.381)
		(layer "B.Cu")
		(net "P3V3_AUX")
	)
	(segment
		(start 374.900444 -360.680508)
		(end 373.772938 -359.553002)
		(width 0.381)
		(layer "B.Cu")
		(net "P3V3_AUX")
	)
	(segment
		(start 150.445978 -23.942548)
		(end 150.445978 -23.247096)
		(width 0.381)
		(layer "B.Cu")
		(net "P3V3_AUX")
	)
	(segment
		(start 101.851714 -359.985056)
		(end 102.163626 -360.296968)
		(width 0.381)
		(layer "B.Cu")
		(net "P3V3_AUX")
	)
	(segment
		(start 325.837296 -28.275026)
		(end 326.00519 -28.44292)
		(width 0.381)
		(layer "B.Cu")
		(net "P3V3_AUX")
	)
	(segment
		(start 217.387932 -53.95595)
		(end 216.60993 -53.177948)
		(width 0.254)
		(layer "B.Cu")
		(net "P3V3_AUX")
	)
	(segment
		(start 367.302034 -188.23178)
		(end 367.493042 -188.23178)
		(width 0.381)
		(layer "B.Cu")
		(net "P3V3_AUX")
	)
	(segment
		(start 173.065694 -319.716658)
		(end 173.513496 -319.268856)
		(width 0.381)
		(layer "B.Cu")
		(net "P3V3_AUX")
	)
	(segment
		(start 33.457134 -160.72739)
		(end 33.900618 -161.170874)
		(width 0.381)
		(layer "B.Cu")
		(net "P3V3_AUX")
	)
	(segment
		(start 183.7436 -21.751798)
		(end 183.22925 -22.266148)
		(width 0.381)
		(layer "B.Cu")
		(net "P3V3_AUX")
	)
	(segment
		(start 172.795946 -319.716658)
		(end 173.065694 -319.716658)
		(width 0.381)
		(layer "B.Cu")
		(net "P3V3_AUX")
	)
	(segment
		(start 458.82433 -319.347342)
		(end 458.82433 -319.132204)
		(width 0.381)
		(layer "B.Cu")
		(net "P3V3_AUX")
	)
	(segment
		(start 309.702962 -316.54877)
		(end 308.901846 -317.349886)
		(width 0.381)
		(layer "B.Cu")
		(net "P3V3_AUX")
	)
	(segment
		(start 9.581134 -194.213734)
		(end 9.581134 -193.82486)
		(width 0.381)
		(layer "B.Cu")
		(net "P3V3_AUX")
	)
	(segment
		(start 210.23961 -194.136264)
		(end 210.194906 -194.136264)
		(width 0.381)
		(layer "B.Cu")
		(net "P3V3_AUX")
	)
	(segment
		(start 180.148484 -415.233104)
		(end 180.47716 -415.56178)
		(width 0.381)
		(layer "B.Cu")
		(net "P3V3_AUX")
	)
	(segment
		(start 200.610978 -193.808604)
		(end 200.610978 -193.8401)
		(width 0.381)
		(layer "B.Cu")
		(net "P3V3_AUX")
	)
	(segment
		(start 342.70188 -35.651948)
		(end 342.037416 -36.316412)
		(width 0.381)
		(layer "B.Cu")
		(net "P3V3_AUX")
	)
	(segment
		(start 428.961804 -127.431038)
		(end 429.546766 -127.431038)
		(width 0.381)
		(layer "B.Cu")
		(net "P3V3_AUX")
	)
	(segment
		(start 175.31588 -14.162278)
		(end 174.235872 -14.162278)
		(width 0.381)
		(layer "B.Cu")
		(net "P3V3_AUX")
	)
	(segment
		(start 21.48332 -169.850308)
		(end 21.5011 -169.868088)
		(width 0.381)
		(layer "B.Cu")
		(net "P3V3_AUX")
	)
	(segment
		(start 262.784082 -319.716658)
		(end 263.236964 -319.263776)
		(width 0.381)
		(layer "B.Cu")
		(net "P3V3_AUX")
	)
	(segment
		(start 312.043572 -34.102548)
		(end 311.427622 -34.102548)
		(width 0.3048)
		(layer "B.Cu")
		(net "P3V3_AUX")
	)
	(segment
		(start 151.710898 -23.242016)
		(end 151.69388 -23.224998)
		(width 0.381)
		(layer "B.Cu")
		(net "P3V3_AUX")
	)
	(segment
		(start 434.348636 -313.913266)
		(end 434.083968 -313.913266)
		(width 0.3048)
		(layer "B.Cu")
		(net "P3V3_AUX")
	)
	(segment
		(start 128.85674 -18.139918)
		(end 127.80518 -18.139918)
		(width 0.381)
		(layer "B.Cu")
		(net "P3V3_AUX")
	)
	(segment
		(start 64.590168 -319.17767)
		(end 64.590168 -318.962024)
		(width 0.381)
		(layer "B.Cu")
		(net "P3V3_AUX")
	)
	(segment
		(start 120.645682 -355.69779)
		(end 120.645682 -355.89083)
		(width 0.381)
		(layer "B.Cu")
		(net "P3V3_AUX")
	)
	(segment
		(start 258.784852 -105.911396)
		(end 259.394706 -105.911396)
		(width 0.381)
		(layer "B.Cu")
		(net "P3V3_AUX")
	)
	(segment
		(start 413.192214 -319.716658)
		(end 413.550862 -319.35801)
		(width 0.381)
		(layer "B.Cu")
		(net "P3V3_AUX")
	)
	(segment
		(start 404.402798 -58.79846)
		(end 407.48458 -58.79846)
		(width 0.381)
		(layer "B.Cu")
		(net "P3V3_AUX")
	)
	(segment
		(start 165.252146 -319.716658)
		(end 165.521894 -319.716658)
		(width 0.381)
		(layer "B.Cu")
		(net "P3V3_AUX")
	)
	(segment
		(start 467.05139 -43.735498)
		(end 466.386164 -44.400724)
		(width 0.381)
		(layer "B.Cu")
		(net "P3V3_AUX")
	)
	(segment
		(start 309.65394 -29.696664)
		(end 309.65394 -30.734508)
		(width 0.381)
		(layer "B.Cu")
		(net "P3V3_AUX")
	)
	(segment
		(start 37.928296 -318.932306)
		(end 37.928296 -319.268856)
		(width 0.381)
		(layer "B.Cu")
		(net "P3V3_AUX")
	)
	(segment
		(start 204.83957 -192.420748)
		(end 204.534008 -192.72631)
		(width 0.381)
		(layer "B.Cu")
		(net "P3V3_AUX")
	)
	(segment
		(start 9.869678 -195.416678)
		(end 10.373106 -195.416678)
		(width 0.381)
		(layer "B.Cu")
		(net "P3V3_AUX")
	)
	(segment
		(start 25.784556 -174.9171)
		(end 25.277064 -175.424592)
		(width 0.381)
		(layer "B.Cu")
		(net "P3V3_AUX")
	)
	(segment
		(start 188.639704 -319.450974)
		(end 188.663072 -319.427606)
		(width 0.381)
		(layer "B.Cu")
		(net "P3V3_AUX")
	)
	(segment
		(start 126.89332 -18.415508)
		(end 126.89332 -19.924268)
		(width 0.381)
		(layer "B.Cu")
		(net "P3V3_AUX")
	)
	(segment
		(start 234.92968 -49.834546)
		(end 235.10748 -49.834546)
		(width 0.381)
		(layer "B.Cu")
		(net "P3V3_AUX")
	)
	(segment
		(start 159.94253 -319.656714)
		(end 159.47009 -319.656714)
		(width 0.381)
		(layer "B.Cu")
		(net "P3V3_AUX")
	)
	(segment
		(start 195.763388 -24.659336)
		(end 195.763388 -21.347176)
		(width 0.508)
		(layer "B.Cu")
		(net "P3V3_AUX")
	)
	(segment
		(start 188.4299 -319.440052)
		(end 188.153294 -319.716658)
		(width 0.381)
		(layer "B.Cu")
		(net "P3V3_AUX")
	)
	(segment
		(start 366.853724 -398.976088)
		(end 366.22609 -398.976088)
		(width 0.381)
		(layer "B.Cu")
		(net "P3V3_AUX")
	)
	(segment
		(start 24.18842 -392.017758)
		(end 24.18842 -392.391138)
		(width 0.381)
		(layer "B.Cu")
		(net "P3V3_AUX")
	)
	(segment
		(start 161.83356 -43.409108)
		(end 160.935162 -42.51071)
		(width 0.381)
		(layer "B.Cu")
		(net "P3V3_AUX")
	)
	(segment
		(start 456.119992 -51.976528)
		(end 457.0349 -51.976528)
		(width 0.508)
		(layer "B.Cu")
		(net "P3V3_AUX")
	)
	(segment
		(start 188.628782 -319.440052)
		(end 188.4299 -319.440052)
		(width 0.381)
		(layer "B.Cu")
		(net "P3V3_AUX")
	)
	(segment
		(start 420.193724 -132.528056)
		(end 420.193724 -131.992878)
		(width 0.381)
		(layer "B.Cu")
		(net "P3V3_AUX")
	)
	(segment
		(start 204.978 -192.420748)
		(end 204.83957 -192.420748)
		(width 0.381)
		(layer "B.Cu")
		(net "P3V3_AUX")
	)
	(segment
		(start 181.341268 -128.80848)
		(end 182.17388 -127.975868)
		(width 0.381)
		(layer "B.Cu")
		(net "P3V3_AUX")
	)
	(segment
		(start 330.17206 -31.473648)
		(end 330.17206 -32.300418)
		(width 0.381)
		(layer "B.Cu")
		(net "P3V3_AUX")
	)
	(segment
		(start 22.123146 -319.716658)
		(end 22.392894 -319.716658)
		(width 0.381)
		(layer "B.Cu")
		(net "P3V3_AUX")
	)
	(segment
		(start 127.8001 -18.134838)
		(end 127.17399 -18.134838)
		(width 0.381)
		(layer "B.Cu")
		(net "P3V3_AUX")
	)
	(segment
		(start 253.294134 -94.841568)
		(end 254.10795 -95.655384)
		(width 0.381)
		(layer "B.Cu")
		(net "P3V3_AUX")
	)
	(segment
		(start 436.142892 -319.662048)
		(end 435.25948 -319.662048)
		(width 0.381)
		(layer "B.Cu")
		(net "P3V3_AUX")
	)
	(segment
		(start 290.186618 -148.872448)
		(end 291.583618 -148.872448)
		(width 0.381)
		(layer "B.Cu")
		(net "P3V3_AUX")
	)
	(segment
		(start 181.378098 -190.95085)
		(end 180.514752 -191.814196)
		(width 0.381)
		(layer "B.Cu")
		(net "P3V3_AUX")
	)
	(segment
		(start 186.01944 -315.871352)
		(end 186.43219 -315.458602)
		(width 0.381)
		(layer "B.Cu")
		(net "P3V3_AUX")
	)
	(segment
		(start 163.576 -111.470948)
		(end 164.24783 -111.470948)
		(width 0.381)
		(layer "B.Cu")
		(net "P3V3_AUX")
	)
	(segment
		(start 367.986818 -189.3697)
		(end 368.178588 -189.56147)
		(width 0.381)
		(layer "B.Cu")
		(net "P3V3_AUX")
	)
	(segment
		(start 428.529242 -319.46723)
		(end 428.79391 -319.46723)
		(width 0.381)
		(layer "B.Cu")
		(net "P3V3_AUX")
	)
	(segment
		(start 203.126848 -28.841192)
		(end 199.945244 -28.841192)
		(width 0.508)
		(layer "B.Cu")
		(net "P3V3_AUX")
	)
	(segment
		(start 457.0349 -51.976528)
		(end 457.949808 -51.976528)
		(width 0.508)
		(layer "B.Cu")
		(net "P3V3_AUX")
	)
	(segment
		(start 285.415482 -319.716658)
		(end 285.150814 -319.716658)
		(width 0.381)
		(layer "B.Cu")
		(net "P3V3_AUX")
	)
	(segment
		(start 369.756436 -354.13569)
		(end 369.756436 -354.53828)
		(width 0.381)
		(layer "B.Cu")
		(net "P3V3_AUX")
	)
	(segment
		(start 33.69056 -169.4307)
		(end 33.35782 -169.09796)
		(width 0.381)
		(layer "B.Cu")
		(net "P3V3_AUX")
	)
	(segment
		(start 368.317018 -354.734114)
		(end 368.512852 -354.53828)
		(width 0.381)
		(layer "B.Cu")
		(net "P3V3_AUX")
	)
	(segment
		(start 194.61353 -104.955848)
		(end 194.00393 -104.955848)
		(width 0.381)
		(layer "B.Cu")
		(net "P3V3_AUX")
	)
	(segment
		(start 434.083968 -313.913266)
		(end 433.803298 -314.193936)
		(width 0.3048)
		(layer "B.Cu")
		(net "P3V3_AUX")
	)
	(segment
		(start 255.035812 -86.824566)
		(end 254.669036 -86.824566)
		(width 0.381)
		(layer "B.Cu")
		(net "P3V3_AUX")
	)
	(segment
		(start 189.28588 -130.666998)
		(end 189.28588 -131.280408)
		(width 0.381)
		(layer "B.Cu")
		(net "P3V3_AUX")
	)
	(segment
		(start 202.971146 -319.716658)
		(end 203.240894 -319.716658)
		(width 0.381)
		(layer "B.Cu")
		(net "P3V3_AUX")
	)
	(segment
		(start 215.761316 -195.36791)
		(end 214.460328 -195.36791)
		(width 0.381)
		(layer "B.Cu")
		(net "P3V3_AUX")
	)
	(segment
		(start 435.25948 -319.662048)
		(end 434.482494 -319.662048)
		(width 0.381)
		(layer "B.Cu")
		(net "P3V3_AUX")
	)
	(segment
		(start 420.298372 -132.632704)
		(end 420.193724 -132.528056)
		(width 0.381)
		(layer "B.Cu")
		(net "P3V3_AUX")
	)
	(segment
		(start 127.17399 -18.134838)
		(end 126.89332 -18.415508)
		(width 0.381)
		(layer "B.Cu")
		(net "P3V3_AUX")
	)
	(segment
		(start 150.445978 -23.247096)
		(end 150.42388 -23.224998)
		(width 0.381)
		(layer "B.Cu")
		(net "P3V3_AUX")
	)
	(segment
		(start 457.308458 -317.02375)
		(end 457.730098 -317.02375)
		(width 0.381)
		(layer "B.Cu")
		(net "P3V3_AUX")
	)
	(segment
		(start 321.747388 -25.65527)
		(end 321.747642 -25.655524)
		(width 0.381)
		(layer "B.Cu")
		(net "P3V3_AUX")
	)
	(segment
		(start 204.277976 -79.392272)
		(end 204.277976 -79.444342)
		(width 0.381)
		(layer "B.Cu")
		(net "P3V3_AUX")
	)
	(segment
		(start 194.00393 -107.495848)
		(end 194.61353 -107.495848)
		(width 0.381)
		(layer "B.Cu")
		(net "P3V3_AUX")
	)
	(segment
		(start 307.16601 -318.252602)
		(end 307.16601 -317.706502)
		(width 0.381)
		(layer "B.Cu")
		(net "P3V3_AUX")
	)
	(segment
		(start 45.26915 -319.716658)
		(end 45.472096 -319.513712)
		(width 0.381)
		(layer "B.Cu")
		(net "P3V3_AUX")
	)
	(segment
		(start 194.304158 -79.14259)
		(end 192.947798 -79.14259)
		(width 0.381)
		(layer "B.Cu")
		(net "P3V3_AUX")
	)
	(segment
		(start 37.689028 -128.72974)
		(end 37.965888 -128.72974)
		(width 0.381)
		(layer "B.Cu")
		(net "P3V3_AUX")
	)
	(segment
		(start 30.384496 -319.526412)
		(end 30.384496 -319.268856)
		(width 0.381)
		(layer "B.Cu")
		(net "P3V3_AUX")
	)
	(segment
		(start 137.43686 -29.757878)
		(end 137.80262 -29.757878)
		(width 0.381)
		(layer "B.Cu")
		(net "P3V3_AUX")
	)
	(segment
		(start 256.088642 -106.467148)
		(end 255.224534 -106.467148)
		(width 0.381)
		(layer "B.Cu")
		(net "P3V3_AUX")
	)
	(segment
		(start 291.583618 -148.872448)
		(end 291.964618 -149.253448)
		(width 0.381)
		(layer "B.Cu")
		(net "P3V3_AUX")
	)
	(segment
		(start 38.347396 -318.513206)
		(end 37.928296 -318.932306)
		(width 0.381)
		(layer "B.Cu")
		(net "P3V3_AUX")
	)
	(segment
		(start 138.77798 -29.757878)
		(end 138.77798 -29.275278)
		(width 0.254)
		(layer "B.Cu")
		(net "P3V3_AUX")
	)
	(segment
		(start 157.70098 -192.95364)
		(end 156.1465 -191.39916)
		(width 0.381)
		(layer "B.Cu")
		(net "P3V3_AUX")
	)
	(segment
		(start 437.371744 -119.952008)
		(end 437.371744 -119.192802)
		(width 0.381)
		(layer "B.Cu")
		(net "P3V3_AUX")
	)
	(segment
		(start 456.543918 -316.98311)
		(end 457.267818 -316.98311)
		(width 0.381)
		(layer "B.Cu")
		(net "P3V3_AUX")
	)
	(segment
		(start 182.546752 -192.299844)
		(end 181.530752 -192.299844)
		(width 0.381)
		(layer "B.Cu")
		(net "P3V3_AUX")
	)
	(segment
		(start 368.512852 -354.53828)
		(end 369.756436 -354.53828)
		(width 0.381)
		(layer "B.Cu")
		(net "P3V3_AUX")
	)
	(segment
		(start 10.373106 -195.416678)
		(end 10.373106 -195.005706)
		(width 0.381)
		(layer "B.Cu")
		(net "P3V3_AUX")
	)
	(segment
		(start 181.11724 -27.107388)
		(end 181.53126 -26.693368)
		(width 0.381)
		(layer "B.Cu")
		(net "P3V3_AUX")
	)
	(segment
		(start 195.042028 -193.91757)
		(end 194.559428 -193.43497)
		(width 0.381)
		(layer "B.Cu")
		(net "P3V3_AUX")
	)
	(segment
		(start 434.941218 -318.72301)
		(end 434.395372 -319.268856)
		(width 0.3048)
		(layer "B.Cu")
		(net "P3V3_AUX")
	)
	(segment
		(start 373.772938 -354.14331)
		(end 373.384318 -353.75469)
		(width 0.381)
		(layer "B.Cu")
		(net "P3V3_AUX")
	)
	(segment
		(start 37.210746 -319.716658)
		(end 37.480494 -319.716658)
		(width 0.381)
		(layer "B.Cu")
		(net "P3V3_AUX")
	)
	(segment
		(start 208.71688 -132.862828)
		(end 217.49385 -132.862828)
		(width 0.508)
		(layer "B.Cu")
		(net "P3V3_AUX")
	)
	(segment
		(start 196.79031 -124.170948)
		(end 196.782182 -124.16282)
		(width 0.381)
		(layer "B.Cu")
		(net "P3V3_AUX")
	)
	(segment
		(start 210.67268 -192.639188)
		(end 210.6676 -192.634108)
		(width 0.381)
		(layer "B.Cu")
		(net "P3V3_AUX")
	)
	(segment
		(start 126.67742 -31.927038)
		(end 126.67742 -32.662368)
		(width 0.381)
		(layer "B.Cu")
		(net "P3V3_AUX")
	)
	(segment
		(start 208.71688 -132.862828)
		(end 207.786732 -132.862828)
		(width 0.508)
		(layer "B.Cu")
		(net "P3V3_AUX")
	)
	(segment
		(start 32.876998 -160.72739)
		(end 33.457134 -160.72739)
		(width 0.381)
		(layer "B.Cu")
		(net "P3V3_AUX")
	)
	(segment
		(start 165.521894 -319.716658)
		(end 165.969696 -319.268856)
		(width 0.381)
		(layer "B.Cu")
		(net "P3V3_AUX")
	)
	(segment
		(start 255.369822 -319.805558)
		(end 255.69164 -319.48374)
		(width 0.381)
		(layer "B.Cu")
		(net "P3V3_AUX")
	)
	(segment
		(start 341.536274 -32.319976)
		(end 341.672164 -32.184086)
		(width 0.381)
		(layer "B.Cu")
		(net "P3V3_AUX")
	)
	(segment
		(start 160.43783 -109.489748)
		(end 159.743648 -109.489748)
		(width 0.381)
		(layer "B.Cu")
		(net "P3V3_AUX")
	)
	(segment
		(start 21.45538 -169.850308)
		(end 21.48332 -169.850308)
		(width 0.381)
		(layer "B.Cu")
		(net "P3V3_AUX")
	)
	(segment
		(start 419.95852 -130.228594)
		(end 421.545766 -128.641348)
		(width 0.508)
		(layer "B.Cu")
		(net "P3V3_AUX")
	)
	(segment
		(start 188.245496 -317.730886)
		(end 187.632848 -317.730886)
		(width 0.381)
		(layer "B.Cu")
		(net "P3V3_AUX")
	)
	(segment
		(start 7.753096 -319.544192)
		(end 7.753096 -319.268856)
		(width 0.381)
		(layer "B.Cu")
		(net "P3V3_AUX")
	)
	(segment
		(start 180.339746 -319.716658)
		(end 180.609494 -319.716658)
		(width 0.381)
		(layer "B.Cu")
		(net "P3V3_AUX")
	)
	(segment
		(start 192.71488 -72.100948)
		(end 193.195956 -72.582024)
		(width 0.381)
		(layer "B.Cu")
		(net "P3V3_AUX")
	)
	(segment
		(start 346.097098 -32.58439)
		(end 346.097098 -32.529018)
		(width 0.381)
		(layer "B.Cu")
		(net "P3V3_AUX")
	)
	(segment
		(start 160.002474 -319.716658)
		(end 159.94253 -319.656714)
		(width 0.381)
		(layer "B.Cu")
		(net "P3V3_AUX")
	)
	(segment
		(start 311.427622 -43.932348)
		(end 311.369456 -43.932348)
		(width 0.381)
		(layer "B.Cu")
		(net "P3V3_AUX")
	)
	(segment
		(start 192.71488 -71.948548)
		(end 192.71488 -72.100948)
		(width 0.381)
		(layer "B.Cu")
		(net "P3V3_AUX")
	)
	(segment
		(start 199.945244 -28.841192)
		(end 195.763388 -24.659336)
		(width 0.508)
		(layer "B.Cu")
		(net "P3V3_AUX")
	)
	(segment
		(start 427.97476 -117.60962)
		(end 427.97476 -117.793008)
		(width 0.381)
		(layer "B.Cu")
		(net "P3V3_AUX")
	)
	(segment
		(start 270.327882 -319.716658)
		(end 270.780764 -319.263776)
		(width 0.381)
		(layer "B.Cu")
		(net "P3V3_AUX")
	)
	(segment
		(start 164.24783 -117.566948)
		(end 163.63188 -117.566948)
		(width 0.381)
		(layer "B.Cu")
		(net "P3V3_AUX")
	)
	(segment
		(start 443.367414 -319.716658)
		(end 443.609222 -319.47485)
		(width 0.381)
		(layer "B.Cu")
		(net "P3V3_AUX")
	)
	(segment
		(start 138.77798 -29.275278)
		(end 139.023852 -29.029406)
		(width 0.254)
		(layer "B.Cu")
		(net "P3V3_AUX")
	)
	(segment
		(start 466.386164 -47.082964)
		(end 466.28304 -47.186088)
		(width 0.381)
		(layer "B.Cu")
		(net "P3V3_AUX")
	)
	(segment
		(start 192.454022 -24.491442)
		(end 192.454022 -25.565862)
		(width 0.508)
		(layer "B.Cu")
		(net "P3V3_AUX")
	)
	(segment
		(start 449.52666 -51.976528)
		(end 449.52666 -52.891436)
		(width 0.508)
		(layer "B.Cu")
		(net "P3V3_AUX")
	)
	(segment
		(start 160.24733 -14.889988)
		(end 159.66186 -14.889988)
		(width 0.381)
		(layer "B.Cu")
		(net "P3V3_AUX")
	)
	(segment
		(start 346.9132 -27.814524)
		(end 345.220798 -29.506926)
		(width 0.381)
		(layer "B.Cu")
		(net "P3V3_AUX")
	)
	(segment
		(start 389.636 -33.003998)
		(end 390.37895 -33.003998)
		(width 0.381)
		(layer "B.Cu")
		(net "P3V3_AUX")
	)
	(segment
		(start 413.81553 -319.35801)
		(end 413.909764 -319.263776)
		(width 0.381)
		(layer "B.Cu")
		(net "P3V3_AUX")
	)
	(segment
		(start 9.4234 -194.9704)
		(end 9.869678 -195.416678)
		(width 0.381)
		(layer "B.Cu")
		(net "P3V3_AUX")
	)
	(segment
		(start 364.277148 -356.67569)
		(end 363.69625 -356.094792)
		(width 0.381)
		(layer "B.Cu")
		(net "P3V3_AUX")
	)
	(segment
		(start 180.609494 -319.716658)
		(end 181.057296 -319.268856)
		(width 0.381)
		(layer "B.Cu")
		(net "P3V3_AUX")
	)
	(segment
		(start 160.935162 -42.51071)
		(end 160.935162 -42.232834)
		(width 0.381)
		(layer "B.Cu")
		(net "P3V3_AUX")
	)
	(segment
		(start 367.986818 -188.725556)
		(end 367.986818 -189.3697)
		(width 0.381)
		(layer "B.Cu")
		(net "P3V3_AUX")
	)
	(segment
		(start 419.95852 -131.424934)
		(end 419.95852 -130.228594)
		(width 0.508)
		(layer "B.Cu")
		(net "P3V3_AUX")
	)
	(segment
		(start 254.973074 -319.805558)
		(end 255.369822 -319.805558)
		(width 0.381)
		(layer "B.Cu")
		(net "P3V3_AUX")
	)
	(segment
		(start 311.427622 -42.713148)
		(end 311.427622 -43.932348)
		(width 0.381)
		(layer "B.Cu")
		(net "P3V3_AUX")
	)
	(segment
		(start 204.277976 -79.444342)
		(end 204.569822 -79.736188)
		(width 0.381)
		(layer "B.Cu")
		(net "P3V3_AUX")
	)
	(segment
		(start 217.49385 -132.862828)
		(end 217.72753 -132.629148)
		(width 0.508)
		(layer "B.Cu")
		(net "P3V3_AUX")
	)
	(segment
		(start 302.383444 -149.533356)
		(end 303.072292 -149.533356)
		(width 0.381)
		(layer "B.Cu")
		(net "P3V3_AUX")
	)
	(segment
		(start 341.672164 -32.184086)
		(end 341.672164 -31.678372)
		(width 0.381)
		(layer "B.Cu")
		(net "P3V3_AUX")
	)
	(segment
		(start 310.843422 -316.728094)
		(end 310.664098 -316.54877)
		(width 0.381)
		(layer "B.Cu")
		(net "P3V3_AUX")
	)
	(segment
		(start 120.645682 -355.89083)
		(end 120.955308 -356.200456)
		(width 0.381)
		(layer "B.Cu")
		(net "P3V3_AUX")
	)
	(segment
		(start 11.169396 -183.482996)
		(end 11.6078 -183.9214)
		(width 0.381)
		(layer "B.Cu")
		(net "P3V3_AUX")
	)
	(segment
		(start 186.519312 -319.638934)
		(end 186.519312 -319.483994)
		(width 0.381)
		(layer "B.Cu")
		(net "P3V3_AUX")
	)
	(segment
		(start 6.9342 -194.7164)
		(end 7.1882 -194.9704)
		(width 0.381)
		(layer "B.Cu")
		(net "P3V3_AUX")
	)
	(segment
		(start 194.31635 -119.344948)
		(end 193.78041 -119.344948)
		(width 0.381)
		(layer "B.Cu")
		(net "P3V3_AUX")
	)
	(segment
		(start 14.579346 -319.716658)
		(end 15.13205 -319.716658)
		(width 0.381)
		(layer "B.Cu")
		(net "P3V3_AUX")
	)
	(segment
		(start 160.76295 -16.112998)
		(end 161.29 -16.112998)
		(width 0.381)
		(layer "B.Cu")
		(net "P3V3_AUX")
	)
	(segment
		(start 10.958322 -184.625996)
		(end 11.6332 -184.625996)
		(width 0.381)
		(layer "B.Cu")
		(net "P3V3_AUX")
	)
	(segment
		(start 194.00393 -104.955848)
		(end 194.00393 -103.685848)
		(width 0.381)
		(layer "B.Cu")
		(net "P3V3_AUX")
	)
	(segment
		(start 32.254952 -170.381676)
		(end 32.713676 -170.8404)
		(width 0.381)
		(layer "B.Cu")
		(net "P3V3_AUX")
	)
	(segment
		(start 114.18443 -363.78007)
		(end 114.18443 -362.703872)
		(width 0.381)
		(layer "B.Cu")
		(net "P3V3_AUX")
	)
	(segment
		(start 382.409954 -188.29401)
		(end 383.3749 -188.29401)
		(width 0.381)
		(layer "B.Cu")
		(net "P3V3_AUX")
	)
	(segment
		(start 310.664098 -316.54877)
		(end 309.702962 -316.54877)
		(width 0.381)
		(layer "B.Cu")
		(net "P3V3_AUX")
	)
	(segment
		(start 435.54523 -184.639458)
		(end 435.2163 -184.968388)
		(width 0.381)
		(layer "B.Cu")
		(net "P3V3_AUX")
	)
	(segment
		(start 362.091224 -363.330998)
		(end 362.091224 -362.698792)
		(width 0.381)
		(layer "B.Cu")
		(net "P3V3_AUX")
	)
	(segment
		(start 300.1899 -320.088768)
		(end 300.1899 -319.992248)
		(width 0.381)
		(layer "B.Cu")
		(net "P3V3_AUX")
	)
	(segment
		(start 21.61413 -184.107328)
		(end 21.819362 -184.31256)
		(width 0.381)
		(layer "B.Cu")
		(net "P3V3_AUX")
	)
	(segment
		(start 37.480494 -319.716658)
		(end 37.928296 -319.268856)
		(width 0.381)
		(layer "B.Cu")
		(net "P3V3_AUX")
	)
	(segment
		(start 262.519414 -319.716658)
		(end 262.784082 -319.716658)
		(width 0.381)
		(layer "B.Cu")
		(net "P3V3_AUX")
	)
	(segment
		(start 203.240894 -319.716658)
		(end 203.688696 -319.268856)
		(width 0.381)
		(layer "B.Cu")
		(net "P3V3_AUX")
	)
	(segment
		(start 195.213478 -193.43497)
		(end 194.559428 -193.43497)
		(width 0.381)
		(layer "B.Cu")
		(net "P3V3_AUX")
	)
	(segment
		(start 242.2906 -423.38625)
		(end 242.9764 -423.38625)
		(width 0.381)
		(layer "B.Cu")
		(net "P3V3_AUX")
	)
	(segment
		(start 15.296896 -319.551812)
		(end 15.296896 -319.268856)
		(width 0.381)
		(layer "B.Cu")
		(net "P3V3_AUX")
	)
	(segment
		(start 245.435374 -101.127052)
		(end 245.42115 -101.141276)
		(width 0.381)
		(layer "B.Cu")
		(net "P3V3_AUX")
	)
	(segment
		(start 32.713676 -170.8404)
		(end 33.32226 -170.8404)
		(width 0.381)
		(layer "B.Cu")
		(net "P3V3_AUX")
	)
	(segment
		(start 285.150814 -319.716658)
		(end 284.826202 -319.392046)
		(width 0.381)
		(layer "B.Cu")
		(net "P3V3_AUX")
	)
	(segment
		(start 211.65566 -134.91718)
		(end 212.007196 -134.565644)
		(width 0.508)
		(layer "B.Cu")
		(net "P3V3_AUX")
	)
	(segment
		(start 205.194408 -193.37401)
		(end 204.534008 -194.03441)
		(width 0.381)
		(layer "B.Cu")
		(net "P3V3_AUX")
	)
	(segment
		(start 369.274344 -184.64403)
		(end 369.117372 -184.801002)
		(width 0.381)
		(layer "B.Cu")
		(net "P3V3_AUX")
	)
	(segment
		(start 45.472096 -319.513712)
		(end 45.472096 -319.268856)
		(width 0.381)
		(layer "B.Cu")
		(net "P3V3_AUX")
	)
	(segment
		(start 436.541164 -319.263776)
		(end 436.142892 -319.662048)
		(width 0.381)
		(layer "B.Cu")
		(net "P3V3_AUX")
	)
	(segment
		(start 31.796482 -169.5958)
		(end 32.254952 -170.05427)
		(width 0.381)
		(layer "B.Cu")
		(net "P3V3_AUX")
	)
	(segment
		(start 257.48488 -78.977998)
		(end 258.50088 -78.977998)
		(width 0.381)
		(layer "B.Cu")
		(net "P3V3_AUX")
	)
	(segment
		(start 320.985896 -40.133778)
		(end 320.985896 -39.392098)
		(width 0.381)
		(layer "B.Cu")
		(net "P3V3_AUX")
	)
	(segment
		(start 205.896464 -79.21371)
		(end 206.374746 -79.21371)
		(width 0.381)
		(layer "B.Cu")
		(net "P3V3_AUX")
	)
	(segment
		(start 180.8734 -24.920448)
		(end 180.8734 -21.764498)
		(width 0.381)
		(layer "B.Cu")
		(net "P3V3_AUX")
	)
	(segment
		(start 286.275526 -316.666626)
		(end 286.275526 -318.331342)
		(width 0.381)
		(layer "B.Cu")
		(net "P3V3_AUX")
	)
	(segment
		(start 32.027368 -162.196272)
		(end 32.027368 -161.57702)
		(width 0.381)
		(layer "B.Cu")
		(net "P3V3_AUX")
	)
	(segment
		(start 277.871682 -319.716658)
		(end 278.324564 -319.263776)
		(width 0.381)
		(layer "B.Cu")
		(net "P3V3_AUX")
	)
	(segment
		(start 395.55928 -51.637438)
		(end 395.93266 -51.264058)
		(width 0.381)
		(layer "B.Cu")
		(net "P3V3_AUX")
	)
	(segment
		(start 53.015896 -319.450212)
		(end 53.015896 -319.268856)
		(width 0.381)
		(layer "B.Cu")
		(net "P3V3_AUX")
	)
	(segment
		(start 256.288286 -106.666792)
		(end 256.088642 -106.467148)
		(width 0.381)
		(layer "B.Cu")
		(net "P3V3_AUX")
	)
	(segment
		(start 316.353444 -51.562)
		(end 315.962792 -51.171348)
		(width 0.381)
		(layer "B.Cu")
		(net "P3V3_AUX")
	)
	(segment
		(start 321.747642 -25.655524)
		(end 321.747642 -26.31059)
		(width 0.381)
		(layer "B.Cu")
		(net "P3V3_AUX")
	)
	(segment
		(start 300.918372 -319.263776)
		(end 300.955964 -319.263776)
		(width 0.381)
		(layer "B.Cu")
		(net "P3V3_AUX")
	)
	(segment
		(start 342.037416 -36.316412)
		(end 342.037416 -37.174678)
		(width 0.381)
		(layer "B.Cu")
		(net "P3V3_AUX")
	)
	(segment
		(start 174.235872 -14.162278)
		(end 174.235872 -14.771878)
		(width 0.381)
		(layer "B.Cu")
		(net "P3V3_AUX")
	)
	(segment
		(start 193.199258 -24.364442)
		(end 193.072258 -24.491442)
		(width 0.508)
		(layer "B.Cu")
		(net "P3V3_AUX")
	)
	(segment
		(start 99.699318 -360.42981)
		(end 99.699318 -359.996232)
		(width 0.381)
		(layer "B.Cu")
		(net "P3V3_AUX")
	)
	(segment
		(start 364.705392 -356.67569)
		(end 364.277148 -356.67569)
		(width 0.381)
		(layer "B.Cu")
		(net "P3V3_AUX")
	)
	(segment
		(start 434.165756 -315.430408)
		(end 434.5813 -315.430408)
		(width 0.3048)
		(layer "B.Cu")
		(net "P3V3_AUX")
	)
	(segment
		(start 180.92166 -27.107388)
		(end 181.11724 -27.107388)
		(width 0.381)
		(layer "B.Cu")
		(net "P3V3_AUX")
	)
	(segment
		(start 33.32226 -170.8404)
		(end 33.69056 -170.4721)
		(width 0.381)
		(layer "B.Cu")
		(net "P3V3_AUX")
	)
	(segment
		(start 350.48698 -359.484168)
		(end 350.86798 -359.103168)
		(width 0.381)
		(layer "B.Cu")
		(net "P3V3_AUX")
	)
	(segment
		(start 404.406862 -53.727604)
		(end 407.341324 -53.727604)
		(width 0.381)
		(layer "B.Cu")
		(net "P3V3_AUX")
	)
	(segment
		(start 361.93222 -363.490002)
		(end 362.091224 -363.330998)
		(width 0.381)
		(layer "B.Cu")
		(net "P3V3_AUX")
	)
	(segment
		(start 44.754546 -319.716658)
		(end 45.26915 -319.716658)
		(width 0.381)
		(layer "B.Cu")
		(net "P3V3_AUX")
	)
	(segment
		(start 99.699318 -359.996232)
		(end 99.906836 -359.788714)
		(width 0.381)
		(layer "B.Cu")
		(net "P3V3_AUX")
	)
	(segment
		(start 421.453564 -319.505584)
		(end 421.453564 -319.263776)
		(width 0.3048)
		(layer "B.Cu")
		(net "P3V3_AUX")
	)
	(segment
		(start 431.000154 -132.462778)
		(end 431.61331 -132.462778)
		(width 0.381)
		(layer "B.Cu")
		(net "P3V3_AUX")
	)
	(segment
		(start 195.411598 -193.23685)
		(end 195.213478 -193.43497)
		(width 0.381)
		(layer "B.Cu")
		(net "P3V3_AUX")
	)
	(segment
		(start 245.435374 -101.127052)
		(end 244.86108 -101.127052)
		(width 0.381)
		(layer "B.Cu")
		(net "P3V3_AUX")
	)
	(segment
		(start 210.194906 -193.119248)
		(end 210.170268 -193.09461)
		(width 0.381)
		(layer "B.Cu")
		(net "P3V3_AUX")
	)
	(segment
		(start 343.8779 -35.622738)
		(end 342.73109 -35.622738)
		(width 0.381)
		(layer "B.Cu")
		(net "P3V3_AUX")
	)
	(segment
		(start 431.000154 -137.542778)
		(end 431.715164 -137.542778)
		(width 0.381)
		(layer "B.Cu")
		(net "P3V3_AUX")
	)
	(segment
		(start 315.962792 -51.171348)
		(end 315.510672 -51.171348)
		(width 0.381)
		(layer "B.Cu")
		(net "P3V3_AUX")
	)
	(segment
		(start 244.819424 -101.168708)
		(end 244.12194 -100.471224)
		(width 0.381)
		(layer "B.Cu")
		(net "P3V3_AUX")
	)
	(segment
		(start 245.302786 -98.092006)
		(end 245.418356 -98.092006)
		(width 0.381)
		(layer "B.Cu")
		(net "P3V3_AUX")
	)
	(segment
		(start 435.327552 -317.529972)
		(end 435.327552 -317.790576)
		(width 0.3048)
		(layer "B.Cu")
		(net "P3V3_AUX")
	)
	(segment
		(start 193.62039 -20.402804)
		(end 192.94094 -21.082254)
		(width 0.508)
		(layer "B.Cu")
		(net "P3V3_AUX")
	)
	(segment
		(start 217.07348 -315.49975)
		(end 216.762838 -315.49975)
		(width 0.381)
		(layer "B.Cu")
		(net "P3V3_AUX")
	)
	(segment
		(start 302.100742 -149.816058)
		(end 302.383444 -149.533356)
		(width 0.381)
		(layer "B.Cu")
		(net "P3V3_AUX")
	)
	(segment
		(start 37.55009 -125.565662)
		(end 37.368988 -125.38456)
		(width 0.381)
		(layer "B.Cu")
		(net "P3V3_AUX")
	)
	(segment
		(start 244.12194 -100.471224)
		(end 244.12194 -99.272852)
		(width 0.381)
		(layer "B.Cu")
		(net "P3V3_AUX")
	)
	(segment
		(start 330.45146 -30.940248)
		(end 330.45146 -31.194248)
		(width 0.381)
		(layer "B.Cu")
		(net "P3V3_AUX")
	)
	(segment
		(start 25.82672 -388.742428)
		(end 25.94102 -388.856728)
		(width 0.381)
		(layer "B.Cu")
		(net "P3V3_AUX")
	)
	(segment
		(start 216.197942 -314.934854)
		(end 215.840818 -314.934854)
		(width 0.381)
		(layer "B.Cu")
		(net "P3V3_AUX")
	)
	(segment
		(start 368.598704 -355.352604)
		(end 368.317018 -355.070918)
		(width 0.381)
		(layer "B.Cu")
		(net "P3V3_AUX")
	)
	(segment
		(start 434.908452 -176.75606)
		(end 434.354478 -176.75606)
		(width 0.381)
		(layer "B.Cu")
		(net "P3V3_AUX")
	)
	(segment
		(start 435.183788 -317.386208)
		(end 435.327552 -317.529972)
		(width 0.3048)
		(layer "B.Cu")
		(net "P3V3_AUX")
	)
	(segment
		(start 159.743648 -109.489748)
		(end 159.7406 -109.4867)
		(width 0.381)
		(layer "B.Cu")
		(net "P3V3_AUX")
	)
	(segment
		(start 435.255924 -182.035704)
		(end 435.54523 -182.32501)
		(width 0.381)
		(layer "B.Cu")
		(net "P3V3_AUX")
	)
	(segment
		(start 448.611752 -51.976528)
		(end 449.52666 -51.976528)
		(width 0.508)
		(layer "B.Cu")
		(net "P3V3_AUX")
	)
	(segment
		(start 37.987478 -125.565662)
		(end 37.55009 -125.565662)
		(width 0.381)
		(layer "B.Cu")
		(net "P3V3_AUX")
	)
	(segment
		(start 193.199258 -22.939502)
		(end 193.199258 -24.364442)
		(width 0.508)
		(layer "B.Cu")
		(net "P3V3_AUX")
	)
	(segment
		(start 21.775166 -169.868088)
		(end 21.983446 -169.659808)
		(width 0.381)
		(layer "B.Cu")
		(net "P3V3_AUX")
	)
	(segment
		(start 83.2231 -52.348892)
		(end 82.846672 -52.72532)
		(width 0.4572)
		(layer "B.Cu")
		(net "P3V3_AUX")
	)
	(segment
		(start 317.50254 -30.507178)
		(end 317.50254 -29.748734)
		(width 0.381)
		(layer "B.Cu")
		(net "P3V3_AUX")
	)
	(segment
		(start 413.550862 -319.35801)
		(end 413.81553 -319.35801)
		(width 0.381)
		(layer "B.Cu")
		(net "P3V3_AUX")
	)
	(segment
		(start 367.493042 -188.23178)
		(end 367.986818 -188.725556)
		(width 0.381)
		(layer "B.Cu")
		(net "P3V3_AUX")
	)
	(segment
		(start 307.221128 -318.30772)
		(end 307.16601 -318.252602)
		(width 0.381)
		(layer "B.Cu")
		(net "P3V3_AUX")
	)
	(segment
		(start 212.007196 -134.565644)
		(end 213.61146 -134.565644)
		(width 0.508)
		(layer "B.Cu")
		(net "P3V3_AUX")
	)
	(segment
		(start 461.583278 -51.920902)
		(end 465.32673 -51.920902)
		(width 0.381)
		(layer "B.Cu")
		(net "P3V3_AUX")
	)
	(segment
		(start 428.813976 -127.578866)
		(end 428.961804 -127.431038)
		(width 0.381)
		(layer "B.Cu")
		(net "P3V3_AUX")
	)
	(segment
		(start 186.519312 -319.483994)
		(end 186.464194 -319.428876)
		(width 0.381)
		(layer "B.Cu")
		(net "P3V3_AUX")
	)
	(segment
		(start 114.57432 -364.16996)
		(end 114.18443 -363.78007)
		(width 0.381)
		(layer "B.Cu")
		(net "P3V3_AUX")
	)
	(segment
		(start 159.66186 -14.889988)
		(end 159.66186 -15.124938)
		(width 0.381)
		(layer "B.Cu")
		(net "P3V3_AUX")
	)
	(segment
		(start 395.93266 -51.264058)
		(end 396.72006 -51.264058)
		(width 0.381)
		(layer "B.Cu")
		(net "P3V3_AUX")
	)
	(segment
		(start 214.460328 -195.36791)
		(end 214.241888 -195.58635)
		(width 0.381)
		(layer "B.Cu")
		(net "P3V3_AUX")
	)
	(segment
		(start 210.784694 -319.716658)
		(end 211.232496 -319.268856)
		(width 0.381)
		(layer "B.Cu")
		(net "P3V3_AUX")
	)
	(segment
		(start 307.573426 -317.706502)
		(end 307.729382 -317.862458)
		(width 0.381)
		(layer "B.Cu")
		(net "P3V3_AUX")
	)
	(segment
		(start 144.399 -8.962898)
		(end 144.399 -8.346948)
		(width 0.381)
		(layer "B.Cu")
		(net "P3V3_AUX")
	)
	(segment
		(start 370.137436 -353.75469)
		(end 369.756436 -354.13569)
		(width 0.381)
		(layer "B.Cu")
		(net "P3V3_AUX")
	)
	(segment
		(start 188.663072 -319.427606)
		(end 188.663072 -318.148462)
		(width 0.381)
		(layer "B.Cu")
		(net "P3V3_AUX")
	)
	(segment
		(start 21.61413 -183.429656)
		(end 21.61413 -184.107328)
		(width 0.381)
		(layer "B.Cu")
		(net "P3V3_AUX")
	)
	(segment
		(start 192.454022 -25.565862)
		(end 192.454022 -33.373314)
		(width 0.508)
		(layer "B.Cu")
		(net "P3V3_AUX")
	)
	(segment
		(start 415.271712 -192.68948)
		(end 415.271712 -192.074546)
		(width 0.381)
		(layer "B.Cu")
		(net "P3V3_AUX")
	)
	(segment
		(start 179.887626 -415.233104)
		(end 180.148484 -415.233104)
		(width 0.381)
		(layer "B.Cu")
		(net "P3V3_AUX")
	)
	(segment
		(start 443.609222 -319.47485)
		(end 443.87389 -319.47485)
		(width 0.381)
		(layer "B.Cu")
		(net "P3V3_AUX")
	)
	(segment
		(start 431.609754 -135.545068)
		(end 431.034444 -135.545068)
		(width 0.381)
		(layer "B.Cu")
		(net "P3V3_AUX")
	)
	(segment
		(start 116.083334 -355.942392)
		(end 116.06657 -355.925628)
		(width 0.381)
		(layer "B.Cu")
		(net "P3V3_AUX")
	)
	(segment
		(start 307.16601 -317.706502)
		(end 307.573426 -317.706502)
		(width 0.381)
		(layer "B.Cu")
		(net "P3V3_AUX")
	)
	(segment
		(start 254.10795 -95.655384)
		(end 254.10795 -96.738948)
		(width 0.381)
		(layer "B.Cu")
		(net "P3V3_AUX")
	)
	(segment
		(start 342.650318 -31.678372)
		(end 341.672164 -31.678372)
		(width 0.381)
		(layer "B.Cu")
		(net "P3V3_AUX")
	)
	(segment
		(start 214.241888 -195.98894)
		(end 214.241888 -195.58635)
		(width 0.381)
		(layer "B.Cu")
		(net "P3V3_AUX")
	)
	(segment
		(start 193.195956 -72.582024)
		(end 193.195956 -72.804528)
		(width 0.381)
		(layer "B.Cu")
		(net "P3V3_AUX")
	)
	(segment
		(start 353.08032 -62.926468)
		(end 353.08032 -59.737752)
		(width 0.381)
		(layer "B.Cu")
		(net "P3V3_AUX")
	)
	(segment
		(start 211.232496 -319.268856)
		(end 211.232496 -318.845692)
		(width 0.381)
		(layer "B.Cu")
		(net "P3V3_AUX")
	)
	(segment
		(start 157.70098 -193.566288)
		(end 157.70098 -192.95364)
		(width 0.381)
		(layer "B.Cu")
		(net "P3V3_AUX")
	)
	(segment
		(start 139.023852 -29.029406)
		(end 139.8778 -29.029406)
		(width 0.254)
		(layer "B.Cu")
		(net "P3V3_AUX")
	)
	(segment
		(start 309.94985 -34.1884)
		(end 311.34177 -34.1884)
		(width 0.3048)
		(layer "B.Cu")
		(net "P3V3_AUX")
	)
	(segment
		(start 183.22925 -22.266148)
		(end 182.0926 -22.266148)
		(width 0.381)
		(layer "B.Cu")
		(net "P3V3_AUX")
	)
	(segment
		(start 420.66718 -320.129408)
		(end 420.82974 -320.129408)
		(width 0.3048)
		(layer "B.Cu")
		(net "P3V3_AUX")
	)
	(segment
		(start 270.063214 -319.716658)
		(end 270.327882 -319.716658)
		(width 0.381)
		(layer "B.Cu")
		(net "P3V3_AUX")
	)
	(segment
		(start 21.983446 -169.659808)
		(end 22.08911 -169.659808)
		(width 0.381)
		(layer "B.Cu")
		(net "P3V3_AUX")
	)
	(segment
		(start 180.514752 -191.814196)
		(end 180.514752 -192.299844)
		(width 0.381)
		(layer "B.Cu")
		(net "P3V3_AUX")
	)
	(segment
		(start 208.0387 -134.91718)
		(end 211.65566 -134.91718)
		(width 0.508)
		(layer "B.Cu")
		(net "P3V3_AUX")
	)
	(segment
		(start 164.857938 -8.51789)
		(end 165.593522 -8.51789)
		(width 0.381)
		(layer "B.Cu")
		(net "P3V3_AUX")
	)
	(segment
		(start 186.968384 -317.066422)
		(end 186.572398 -317.066422)
		(width 0.381)
		(layer "B.Cu")
		(net "P3V3_AUX")
	)
	(segment
		(start 18.613374 -177.876962)
		(end 18.613374 -176.831244)
		(width 0.381)
		(layer "B.Cu")
		(net "P3V3_AUX")
	)
	(segment
		(start 321.224402 -40.372284)
		(end 320.985896 -40.133778)
		(width 0.381)
		(layer "B.Cu")
		(net "P3V3_AUX")
	)
	(segment
		(start 37.356288 -130.80492)
		(end 37.399468 -130.76174)
		(width 0.381)
		(layer "B.Cu")
		(net "P3V3_AUX")
	)
	(segment
		(start 6.9342 -194.1068)
		(end 6.9342 -194.7164)
		(width 0.381)
		(layer "B.Cu")
		(net "P3V3_AUX")
	)
	(segment
		(start 204.534008 -192.72631)
		(end 204.534008 -192.95491)
		(width 0.381)
		(layer "B.Cu")
		(net "P3V3_AUX")
	)
	(segment
		(start 22.392894 -319.716658)
		(end 22.840696 -319.268856)
		(width 0.381)
		(layer "B.Cu")
		(net "P3V3_AUX")
	)
	(segment
		(start 345.220798 -31.652718)
		(end 345.220798 -31.527242)
		(width 0.381)
		(layer "B.Cu")
		(net "P3V3_AUX")
	)
	(segment
		(start 251.182632 -94.841568)
		(end 253.294134 -94.841568)
		(width 0.381)
		(layer "B.Cu")
		(net "P3V3_AUX")
	)
	(segment
		(start 25.93848 -174.9171)
		(end 25.784556 -174.9171)
		(width 0.381)
		(layer "B.Cu")
		(net "P3V3_AUX")
	)
	(segment
		(start 318.768476 -39.975028)
		(end 318.768476 -40.313864)
		(width 0.381)
		(layer "B.Cu")
		(net "P3V3_AUX")
	)
	(segment
		(start 38.347396 -318.252856)
		(end 38.347396 -318.513206)
		(width 0.381)
		(layer "B.Cu")
		(net "P3V3_AUX")
	)
	(segment
		(start 120.955308 -356.200456)
		(end 121.373392 -356.200456)
		(width 0.381)
		(layer "B.Cu")
		(net "P3V3_AUX")
	)
	(segment
		(start 433.803298 -314.193936)
		(end 433.803298 -315.06795)
		(width 0.3048)
		(layer "B.Cu")
		(net "P3V3_AUX")
	)
	(segment
		(start 102.163626 -360.296968)
		(end 102.445566 -360.296968)
		(width 0.381)
		(layer "B.Cu")
		(net "P3V3_AUX")
	)
	(segment
		(start 353.2124 -63.058548)
		(end 353.08032 -62.926468)
		(width 0.381)
		(layer "B.Cu")
		(net "P3V3_AUX")
	)
	(segment
		(start 328.092816 -27.794458)
		(end 328.092816 -27.001724)
		(width 0.381)
		(layer "B.Cu")
		(net "P3V3_AUX")
	)
	(segment
		(start 137.80262 -29.757878)
		(end 138.77798 -29.757878)
		(width 0.381)
		(layer "B.Cu")
		(net "P3V3_AUX")
	)
	(segment
		(start 284.826202 -319.392046)
		(end 284.475428 -319.392046)
		(width 0.381)
		(layer "B.Cu")
		(net "P3V3_AUX")
	)
	(segment
		(start 457.730098 -317.02375)
		(end 458.292962 -316.460886)
		(width 0.381)
		(layer "B.Cu")
		(net "P3V3_AUX")
	)
	(segment
		(start 369.505738 -186.99353)
		(end 368.677698 -187.82157)
		(width 0.381)
		(layer "B.Cu")
		(net "P3V3_AUX")
	)
	(segment
		(start 214.813388 -68.846446)
		(end 214.757 -68.902834)
		(width 0.381)
		(layer "B.Cu")
		(net "P3V3_AUX")
	)
	(segment
		(start 210.63077 -192.634108)
		(end 210.170268 -193.09461)
		(width 0.381)
		(layer "B.Cu")
		(net "P3V3_AUX")
	)
	(segment
		(start 290.100258 -148.958808)
		(end 290.186618 -148.872448)
		(width 0.381)
		(layer "B.Cu")
		(net "P3V3_AUX")
	)
	(segment
		(start 435.057296 -176.904904)
		(end 434.908452 -176.75606)
		(width 0.381)
		(layer "B.Cu")
		(net "P3V3_AUX")
	)
	(segment
		(start 188.639704 -319.450974)
		(end 188.628782 -319.440052)
		(width 0.381)
		(layer "B.Cu")
		(net "P3V3_AUX")
	)
	(segment
		(start 373.772938 -359.553002)
		(end 373.772938 -354.14331)
		(width 0.381)
		(layer "B.Cu")
		(net "P3V3_AUX")
	)
	(segment
		(start 245.42115 -101.141276)
		(end 245.42115 -102.112318)
		(width 0.381)
		(layer "B.Cu")
		(net "P3V3_AUX")
	)
	(segment
		(start 193.24447 -72.853042)
		(end 195.55333 -72.853042)
		(width 0.381)
		(layer "B.Cu")
		(net "P3V3_AUX")
	)
	(segment
		(start 151.710898 -23.942548)
		(end 151.710898 -23.242016)
		(width 0.381)
		(layer "B.Cu")
		(net "P3V3_AUX")
	)
	(segment
		(start 369.89893 -36.921948)
		(end 370.51488 -36.921948)
		(width 0.3556)
		(layer "B.Cu")
		(net "P3V3_AUX")
	)
	(segment
		(start 192.94094 -21.082254)
		(end 192.94094 -22.681184)
		(width 0.508)
		(layer "B.Cu")
		(net "P3V3_AUX")
	)
	(segment
		(start 204.534008 -192.95491)
		(end 204.534008 -194.03441)
		(width 0.381)
		(layer "B.Cu")
		(net "P3V3_AUX")
	)
	(segment
		(start 285.868364 -319.263776)
		(end 285.415482 -319.716658)
		(width 0.381)
		(layer "B.Cu")
		(net "P3V3_AUX")
	)
	(segment
		(start 195.763388 -21.347176)
		(end 194.819016 -20.402804)
		(width 0.508)
		(layer "B.Cu")
		(net "P3V3_AUX")
	)
	(segment
		(start 311.369456 -43.932348)
		(end 310.571896 -44.729908)
		(width 0.381)
		(layer "B.Cu")
		(net "P3V3_AUX")
	)
	(segment
		(start 469.50249 -43.735498)
		(end 467.05139 -43.735498)
		(width 0.381)
		(layer "B.Cu")
		(net "P3V3_AUX")
	)
	(segment
		(start 465.32673 -51.920902)
		(end 466.28304 -50.964592)
		(width 0.381)
		(layer "B.Cu")
		(net "P3V3_AUX")
	)
	(segment
		(start 324.991222 -63.160148)
		(end 324.991222 -62.607698)
		(width 0.381)
		(layer "B.Cu")
		(net "P3V3_AUX")
	)
	(segment
		(start 156.62783 -113.756948)
		(end 156.01188 -113.756948)
		(width 0.381)
		(layer "B.Cu")
		(net "P3V3_AUX")
	)
	(segment
		(start 286.275526 -318.331342)
		(end 285.868364 -318.738504)
		(width 0.381)
		(layer "B.Cu")
		(net "P3V3_AUX")
	)
	(segment
		(start 24.18842 -392.391138)
		(end 24.52878 -392.731498)
		(width 0.381)
		(layer "B.Cu")
		(net "P3V3_AUX")
	)
	(segment
		(start 361.93222 -364.1979)
		(end 361.93222 -363.490002)
		(width 0.381)
		(layer "B.Cu")
		(net "P3V3_AUX")
	)
	(segment
		(start 160.30702 -14.949678)
		(end 160.24733 -14.889988)
		(width 0.381)
		(layer "B.Cu")
		(net "P3V3_AUX")
	)
	(segment
		(start 211.232496 -318.845692)
		(end 211.634578 -318.44361)
		(width 0.381)
		(layer "B.Cu")
		(net "P3V3_AUX")
	)
	(segment
		(start 407.83002 -319.480692)
		(end 407.0731 -319.480692)
		(width 0.381)
		(layer "B.Cu")
		(net "P3V3_AUX")
	)
	(segment
		(start 205.373986 -79.736188)
		(end 205.896464 -79.21371)
		(width 0.381)
		(layer "B.Cu")
		(net "P3V3_AUX")
	)
	(segment
		(start 64.971168 -319.55867)
		(end 64.590168 -319.17767)
		(width 0.381)
		(layer "B.Cu")
		(net "P3V3_AUX")
	)
	(segment
		(start 435.255924 -181.359048)
		(end 435.255924 -182.035704)
		(width 0.381)
		(layer "B.Cu")
		(net "P3V3_AUX")
	)
	(segment
		(start 466.28304 -50.964592)
		(end 466.28304 -47.186088)
		(width 0.381)
		(layer "B.Cu")
		(net "P3V3_AUX")
	)
	(segment
		(start 21.5011 -169.868088)
		(end 21.775166 -169.868088)
		(width 0.381)
		(layer "B.Cu")
		(net "P3V3_AUX")
	)
	(segment
		(start 443.87389 -319.47485)
		(end 444.084964 -319.263776)
		(width 0.381)
		(layer "B.Cu")
		(net "P3V3_AUX")
	)
	(segment
		(start 212.725 -57.461658)
		(end 212.725 -58.329068)
		(width 0.381)
		(layer "B.Cu")
		(net "P3V3_AUX")
	)
	(segment
		(start 210.945984 -193.42989)
		(end 210.23961 -194.136264)
		(width 0.381)
		(layer "B.Cu")
		(net "P3V3_AUX")
	)
	(segment
		(start 38.335458 -318.240918)
		(end 38.335458 -316.666626)
		(width 0.381)
		(layer "B.Cu")
		(net "P3V3_AUX")
	)
	(segment
		(start 244.12194 -99.272852)
		(end 245.302786 -98.092006)
		(width 0.381)
		(layer "B.Cu")
		(net "P3V3_AUX")
	)
	(segment
		(start 365.110522 -357.08082)
		(end 364.705392 -356.67569)
		(width 0.381)
		(layer "B.Cu")
		(net "P3V3_AUX")
	)
	(segment
		(start 187.883546 -319.716658)
		(end 186.597036 -319.716658)
		(width 0.381)
		(layer "B.Cu")
		(net "P3V3_AUX")
	)
	(segment
		(start 428.135542 -117.95379)
		(end 428.135542 -118.470934)
		(width 0.381)
		(layer "B.Cu")
		(net "P3V3_AUX")
	)
	(segment
		(start 434.5813 -315.430408)
		(end 435.183788 -316.032896)
		(width 0.3048)
		(layer "B.Cu")
		(net "P3V3_AUX")
	)
	(segment
		(start 429.546766 -128.209548)
		(end 429.546766 -127.431038)
		(width 0.508)
		(layer "B.Cu")
		(net "P3V3_AUX")
	)
	(segment
		(start 126.87554 -19.942048)
		(end 126.87554 -20.585938)
		(width 0.381)
		(layer "B.Cu")
		(net "P3V3_AUX")
	)
	(segment
		(start 370.23548 -186.99353)
		(end 369.505738 -186.99353)
		(width 0.381)
		(layer "B.Cu")
		(net "P3V3_AUX")
	)
	(segment
		(start 67.476878 -319.55867)
		(end 64.971168 -319.55867)
		(width 0.381)
		(layer "B.Cu")
		(net "P3V3_AUX")
	)
	(segment
		(start 277.607014 -319.716658)
		(end 277.871682 -319.716658)
		(width 0.381)
		(layer "B.Cu")
		(net "P3V3_AUX")
	)
	(segment
		(start 159.17672 -319.363344)
		(end 159.097218 -319.363344)
		(width 0.381)
		(layer "B.Cu")
		(net "P3V3_AUX")
	)
	(segment
		(start 38.347396 -318.252856)
		(end 38.335458 -318.240918)
		(width 0.381)
		(layer "B.Cu")
		(net "P3V3_AUX")
	)
	(segment
		(start 68.223638 -320.30543)
		(end 67.476878 -319.55867)
		(width 0.381)
		(layer "B.Cu")
		(net "P3V3_AUX")
	)
	(segment
		(start 368.489738 -189.56147)
		(end 368.178588 -189.56147)
		(width 0.381)
		(layer "B.Cu")
		(net "P3V3_AUX")
	)
	(segment
		(start 116.7257 -355.942392)
		(end 116.083334 -355.942392)
		(width 0.381)
		(layer "B.Cu")
		(net "P3V3_AUX")
	)
	(segment
		(start 433.803298 -315.06795)
		(end 434.165756 -315.430408)
		(width 0.3048)
		(layer "B.Cu")
		(net "P3V3_AUX")
	)
	(segment
		(start 311.051956 -29.708348)
		(end 311.789572 -29.708348)
		(width 0.381)
		(layer "B.Cu")
		(net "P3V3_AUX")
	)
	(segment
		(start 457.0349 -51.976528)
		(end 457.0349 -52.891436)
		(width 0.508)
		(layer "B.Cu")
		(net "P3V3_AUX")
	)
	(segment
		(start 159.766 -17.109948)
		(end 160.76295 -16.112998)
		(width 0.381)
		(layer "B.Cu")
		(net "P3V3_AUX")
	)
	(segment
		(start 235.466382 -50.193448)
		(end 235.8009 -50.193448)
		(width 0.381)
		(layer "B.Cu")
		(net "P3V3_AUX")
	)
	(segment
		(start 7.58063 -319.716658)
		(end 7.753096 -319.544192)
		(width 0.381)
		(layer "B.Cu")
		(net "P3V3_AUX")
	)
	(segment
		(start 7.035546 -319.716658)
		(end 7.58063 -319.716658)
		(width 0.381)
		(layer "B.Cu")
		(net "P3V3_AUX")
	)
	(segment
		(start 186.01944 -316.513464)
		(end 186.01944 -315.871352)
		(width 0.381)
		(layer "B.Cu")
		(net "P3V3_AUX")
	)
	(segment
		(start 181.863238 -131.280408)
		(end 181.341268 -130.758438)
		(width 0.381)
		(layer "B.Cu")
		(net "P3V3_AUX")
	)
	(segment
		(start 347.84665 -358.577388)
		(end 347.84665 -358.848914)
		(width 0.381)
		(layer "B.Cu")
		(net "P3V3_AUX")
	)
	(segment
		(start 427.97476 -117.793008)
		(end 428.135542 -117.95379)
		(width 0.381)
		(layer "B.Cu")
		(net "P3V3_AUX")
	)
	(segment
		(start 205.348586 -31.06293)
		(end 203.126848 -28.841192)
		(width 0.508)
		(layer "B.Cu")
		(net "P3V3_AUX")
	)
	(segment
		(start 52.298346 -319.716658)
		(end 52.74945 -319.716658)
		(width 0.381)
		(layer "B.Cu")
		(net "P3V3_AUX")
	)
	(segment
		(start 377.288298 -360.680508)
		(end 374.900444 -360.680508)
		(width 0.381)
		(layer "B.Cu")
		(net "P3V3_AUX")
	)
	(segment
		(start 52.74945 -319.716658)
		(end 53.015896 -319.450212)
		(width 0.381)
		(layer "B.Cu")
		(net "P3V3_AUX")
	)
	(segment
		(start 200.431908 -192.95237)
		(end 200.94956 -193.470022)
		(width 0.381)
		(layer "B.Cu")
		(net "P3V3_AUX")
	)
	(segment
		(start 365.110522 -357.197406)
		(end 365.110522 -357.08082)
		(width 0.381)
		(layer "B.Cu")
		(net "P3V3_AUX")
	)
	(segment
		(start 200.94956 -193.470022)
		(end 200.610978 -193.808604)
		(width 0.381)
		(layer "B.Cu")
		(net "P3V3_AUX")
	)
	(segment
		(start 300.1899 -319.992248)
		(end 300.918372 -319.263776)
		(width 0.381)
		(layer "B.Cu")
		(net "P3V3_AUX")
	)
	(segment
		(start 428.279814 -319.716658)
		(end 428.529242 -319.46723)
		(width 0.381)
		(layer "B.Cu")
		(net "P3V3_AUX")
	)
	(segment
		(start 320.985896 -39.392098)
		(end 321.086226 -39.291768)
		(width 0.381)
		(layer "B.Cu")
		(net "P3V3_AUX")
	)
	(segment
		(start 368.677698 -189.37351)
		(end 368.489738 -189.56147)
		(width 0.381)
		(layer "B.Cu")
		(net "P3V3_AUX")
	)
	(segment
		(start 307.729382 -317.862458)
		(end 308.389274 -317.862458)
		(width 0.381)
		(layer "B.Cu")
		(net "P3V3_AUX")
	)
	(segment
		(start 309.761636 -29.588968)
		(end 309.65394 -29.696664)
		(width 0.381)
		(layer "B.Cu")
		(net "P3V3_AUX")
	)
	(segment
		(start 193.195956 -72.804528)
		(end 193.24447 -72.853042)
		(width 0.381)
		(layer "B.Cu")
		(net "P3V3_AUX")
	)
	(segment
		(start 213.867238 -196.36359)
		(end 214.241888 -195.98894)
		(width 0.381)
		(layer "B.Cu")
		(net "P3V3_AUX")
	)
	(segment
		(start 420.82974 -320.129408)
		(end 421.453564 -319.505584)
		(width 0.3048)
		(layer "B.Cu")
		(net "P3V3_AUX")
	)
	(segment
		(start 192.454022 -33.373314)
		(end 190.80988 -35.017456)
		(width 0.508)
		(layer "B.Cu")
		(net "P3V3_AUX")
	)
	(segment
		(start 457.267818 -316.98311)
		(end 457.308458 -317.02375)
		(width 0.381)
		(layer "B.Cu")
		(net "P3V3_AUX")
	)
	(segment
		(start 324.991222 -62.607698)
		(end 325.193914 -62.405006)
		(width 0.381)
		(layer "B.Cu")
		(net "P3V3_AUX")
	)
	(segment
		(start 345.220798 -29.506926)
		(end 345.220798 -31.527242)
		(width 0.381)
		(layer "B.Cu")
		(net "P3V3_AUX")
	)
	(segment
		(start 451.175882 -319.45199)
		(end 451.44055 -319.45199)
		(width 0.381)
		(layer "B.Cu")
		(net "P3V3_AUX")
	)
	(segment
		(start 258.50088 -78.977998)
		(end 259.26288 -78.977998)
		(width 0.381)
		(layer "B.Cu")
		(net "P3V3_AUX")
	)
	(segment
		(start 26.63825 -124.70892)
		(end 26.63825 -125.342396)
		(width 0.381)
		(layer "B.Cu")
		(net "P3V3_AUX")
	)
	(segment
		(start 7.1882 -194.9704)
		(end 9.4234 -194.9704)
		(width 0.381)
		(layer "B.Cu")
		(net "P3V3_AUX")
	)
	(segment
		(start 458.292962 -316.460886)
		(end 459.574646 -316.460886)
		(width 0.381)
		(layer "B.Cu")
		(net "P3V3_AUX")
	)
	(segment
		(start 193.072258 -24.491442)
		(end 192.454022 -24.491442)
		(width 0.508)
		(layer "B.Cu")
		(net "P3V3_AUX")
	)
	(segment
		(start 244.86108 -101.127052)
		(end 244.819424 -101.168708)
		(width 0.381)
		(layer "B.Cu")
		(net "P3V3_AUX")
	)
	(segment
		(start 190.80988 -130.666998)
		(end 190.80988 -131.280408)
		(width 0.381)
		(layer "B.Cu")
		(net "P3V3_AUX")
	)
	(segment
		(start 342.73109 -35.622738)
		(end 342.70188 -35.651948)
		(width 0.381)
		(layer "B.Cu")
		(net "P3V3_AUX")
	)
	(segment
		(start 420.193724 -131.992878)
		(end 419.95852 -131.424934)
		(width 0.381)
		(layer "B.Cu")
		(net "P3V3_AUX")
	)
	(segment
		(start 98.50374 -423.123868)
		(end 98.50374 -422.556178)
		(width 0.381)
		(layer "B.Cu")
		(net "P3V3_AUX")
	)
	(segment
		(start 29.666946 -319.716658)
		(end 30.19425 -319.716658)
		(width 0.381)
		(layer "B.Cu")
		(net "P3V3_AUX")
	)
	(segment
		(start 416.287712 -192.68948)
		(end 416.287712 -192.074546)
		(width 0.381)
		(layer "B.Cu")
		(net "P3V3_AUX")
	)
	(segment
		(start 307.221128 -319.02146)
		(end 307.221128 -318.30772)
		(width 0.381)
		(layer "B.Cu")
		(net "P3V3_AUX")
	)
	(segment
		(start 99.10572 -423.725848)
		(end 98.50374 -423.123868)
		(width 0.381)
		(layer "B.Cu")
		(net "P3V3_AUX")
	)
	(segment
		(start 204.8383 -78.831948)
		(end 204.277976 -79.392272)
		(width 0.381)
		(layer "B.Cu")
		(net "P3V3_AUX")
	)
	(segment
		(start 210.194906 -194.136264)
		(end 210.194906 -193.119248)
		(width 0.381)
		(layer "B.Cu")
		(net "P3V3_AUX")
	)
	(segment
		(start 451.44055 -319.45199)
		(end 451.628764 -319.263776)
		(width 0.381)
		(layer "B.Cu")
		(net "P3V3_AUX")
	)
	(segment
		(start 207.6069 -133.04266)
		(end 207.6069 -134.48538)
		(width 0.508)
		(layer "B.Cu")
		(net "P3V3_AUX")
	)
	(segment
		(start 458.455014 -319.716658)
		(end 458.82433 -319.347342)
		(width 0.381)
		(layer "B.Cu")
		(net "P3V3_AUX")
	)
	(segment
		(start 408.046174 -319.696846)
		(end 407.83002 -319.480692)
		(width 0.381)
		(layer "B.Cu")
		(net "P3V3_AUX")
	)
	(segment
		(start 159.66186 -15.124938)
		(end 159.22371 -15.563088)
		(width 0.381)
		(layer "B.Cu")
		(net "P3V3_AUX")
	)
	(segment
		(start 196.782182 -124.16282)
		(end 196.782182 -123.139708)
		(width 0.381)
		(layer "B.Cu")
		(net "P3V3_AUX")
	)
	(segment
		(start 373.384318 -353.75469)
		(end 370.137436 -353.75469)
		(width 0.381)
		(layer "B.Cu")
		(net "P3V3_AUX")
	)
	(segment
		(start 188.153294 -319.716658)
		(end 187.883546 -319.716658)
		(width 0.381)
		(layer "B.Cu")
		(net "P3V3_AUX")
	)
	(segment
		(start 179.41798 -11.882628)
		(end 179.41798 -12.195048)
		(width 0.381)
		(layer "B.Cu")
		(net "P3V3_AUX")
	)
	(segment
		(start 341.00135 -37.174678)
		(end 342.037416 -37.174678)
		(width 0.381)
		(layer "B.Cu")
		(net "P3V3_AUX")
	)
	(segment
		(start 37.368988 -128.4097)
		(end 37.689028 -128.72974)
		(width 0.381)
		(layer "B.Cu")
		(net "P3V3_AUX")
	)
	(segment
		(start 414.255712 -192.68948)
		(end 414.255712 -192.074546)
		(width 0.381)
		(layer "B.Cu")
		(net "P3V3_AUX")
	)
	(segment
		(start 301.258732 -149.816058)
		(end 302.100742 -149.816058)
		(width 0.381)
		(layer "B.Cu")
		(net "P3V3_AUX")
	)
	(segment
		(start 328.092816 -28.452826)
		(end 328.092816 -27.794458)
		(width 0.381)
		(layer "B.Cu")
		(net "P3V3_AUX")
	)
	(segment
		(start 30.19425 -319.716658)
		(end 30.384496 -319.526412)
		(width 0.381)
		(layer "B.Cu")
		(net "P3V3_AUX")
	)
	(segment
		(start 82.14868 -52.082446)
		(end 82.14868 -52.717446)
		(width 0.4572)
		(layer "B.Cu")
		(net "P3V3_AUX")
	)
	(segment
		(start 292.694614 -319.716658)
		(end 292.959282 -319.716658)
		(width 0.381)
		(layer "B.Cu")
		(net "P3V3_AUX")
	)
	(segment
		(start 83.2231 -52.082446)
		(end 83.2231 -52.348892)
		(width 0.4572)
		(layer "B.Cu")
		(net "P3V3_AUX")
	)
	(segment
		(start 435.54523 -182.32501)
		(end 435.54523 -184.639458)
		(width 0.381)
		(layer "B.Cu")
		(net "P3V3_AUX")
	)
	(segment
		(start 350.117918 -359.484168)
		(end 350.48698 -359.484168)
		(width 0.381)
		(layer "B.Cu")
		(net "P3V3_AUX")
	)
	(segment
		(start 196.18071 -124.170948)
		(end 196.79031 -124.170948)
		(width 0.381)
		(layer "B.Cu")
		(net "P3V3_AUX")
	)
	(segment
		(start 235.10748 -49.834546)
		(end 235.466382 -50.193448)
		(width 0.381)
		(layer "B.Cu")
		(net "P3V3_AUX")
	)
	(segment
		(start 330.45146 -31.194248)
		(end 330.17206 -31.473648)
		(width 0.381)
		(layer "B.Cu")
		(net "P3V3_AUX")
	)
	(segment
		(start 303.072292 -148.887688)
		(end 303.072292 -149.533356)
		(width 0.381)
		(layer "B.Cu")
		(net "P3V3_AUX")
	)
	(segment
		(start 308.389274 -317.862458)
		(end 308.901846 -317.349886)
		(width 0.381)
		(layer "B.Cu")
		(net "P3V3_AUX")
	)
	(segment
		(start 182.17388 -131.280408)
		(end 181.863238 -131.280408)
		(width 0.381)
		(layer "B.Cu")
		(net "P3V3_AUX")
	)
	(segment
		(start 285.868364 -318.738504)
		(end 285.868364 -319.263776)
		(width 0.381)
		(layer "B.Cu")
		(net "P3V3_AUX")
	)
	(segment
		(start 126.89332 -19.924268)
		(end 126.87554 -19.942048)
		(width 0.381)
		(layer "B.Cu")
		(net "P3V3_AUX")
	)
	(segment
		(start 181.378098 -189.44971)
		(end 181.378098 -190.95085)
		(width 0.381)
		(layer "B.Cu")
		(net "P3V3_AUX")
	)
	(segment
		(start 215.933782 -68.846446)
		(end 214.813388 -68.846446)
		(width 0.381)
		(layer "B.Cu")
		(net "P3V3_AUX")
	)
	(segment
		(start 368.317018 -355.070918)
		(end 368.317018 -354.734114)
		(width 0.381)
		(layer "B.Cu")
		(net "P3V3_AUX")
	)
	(segment
		(start 194.819016 -20.402804)
		(end 193.62039 -20.402804)
		(width 0.508)
		(layer "B.Cu")
		(net "P3V3_AUX")
	)
	(segment
		(start 347.145356 -27.814524)
		(end 346.9132 -27.814524)
		(width 0.381)
		(layer "B.Cu")
		(net "P3V3_AUX")
	)
	(segment
		(start 178.50866 -13.104368)
		(end 178.50866 -13.359638)
		(width 0.381)
		(layer "B.Cu")
		(net "P3V3_AUX")
	)
	(segment
		(start 181.341268 -130.758438)
		(end 181.341268 -128.80848)
		(width 0.381)
		(layer "B.Cu")
		(net "P3V3_AUX")
	)
	(segment
		(start 33.69056 -170.4721)
		(end 33.69056 -169.4307)
		(width 0.381)
		(layer "B.Cu")
		(net "P3V3_AUX")
	)
	(segment
		(start 348.206314 -358.217724)
		(end 347.84665 -358.577388)
		(width 0.381)
		(layer "B.Cu")
		(net "P3V3_AUX")
	)
	(segment
		(start 434.395372 -319.268856)
		(end 434.089302 -319.268856)
		(width 0.3048)
		(layer "B.Cu")
		(net "P3V3_AUX")
	)
	(segment
		(start 10.373106 -195.005706)
		(end 9.581134 -194.213734)
		(width 0.381)
		(layer "B.Cu")
		(net "P3V3_AUX")
	)
	(segment
		(start 127.80518 -18.139918)
		(end 127.8001 -18.134838)
		(width 0.381)
		(layer "B.Cu")
		(net "P3V3_AUX")
	)
	(segment
		(start 211.61248 -193.42989)
		(end 210.945984 -193.42989)
		(width 0.381)
		(layer "B.Cu")
		(net "P3V3_AUX")
	)
	(segment
		(start 369.884198 -184.64403)
		(end 369.274344 -184.64403)
		(width 0.381)
		(layer "B.Cu")
		(net "P3V3_AUX")
	)
	(segment
		(start 19.83232 -178.265328)
		(end 19.00174 -178.265328)
		(width 0.381)
		(layer "B.Cu")
		(net "P3V3_AUX")
	)
	(segment
		(start 24.0538 -391.883138)
		(end 24.18842 -392.017758)
		(width 0.381)
		(layer "B.Cu")
		(net "P3V3_AUX")
	)
	(segment
		(start 19.00174 -178.265328)
		(end 18.613374 -177.876962)
		(width 0.381)
		(layer "B.Cu")
		(net "P3V3_AUX")
	)
	(segment
		(start 372.81993 -43.144948)
		(end 373.43588 -43.144948)
		(width 0.381)
		(layer "B.Cu")
		(net "P3V3_AUX")
	)
	(segment
		(start 346.097098 -32.529018)
		(end 345.220798 -31.652718)
		(width 0.381)
		(layer "B.Cu")
		(net "P3V3_AUX")
	)
	(segment
		(start 311.34177 -34.1884)
		(end 311.427622 -34.102548)
		(width 0.3048)
		(layer "B.Cu")
		(net "P3V3_AUX")
	)
	(segment
		(start 368.677698 -187.82157)
		(end 368.677698 -189.37351)
		(width 0.381)
		(layer "B.Cu")
		(net "P3V3_AUX")
	)
	(segment
		(start 192.94094 -22.681184)
		(end 193.199258 -22.939502)
		(width 0.508)
		(layer "B.Cu")
		(net "P3V3_AUX")
	)
	(segment
		(start 366.894872 -398.93494)
		(end 366.853724 -398.976088)
		(width 0.381)
		(layer "B.Cu")
		(net "P3V3_AUX")
	)
	(segment
		(start 450.911214 -319.716658)
		(end 451.175882 -319.45199)
		(width 0.381)
		(layer "B.Cu")
		(net "P3V3_AUX")
	)
	(segment
		(start 128.85928 -31.942278)
		(end 128.85928 -32.662368)
		(width 0.381)
		(layer "B.Cu")
		(net "P3V3_AUX")
	)
	(segment
		(start 179.41798 -12.195048)
		(end 178.50866 -13.104368)
		(width 0.381)
		(layer "B.Cu")
		(net "P3V3_AUX")
	)
	(segment
		(start 181.53126 -25.578308)
		(end 180.8734 -24.920448)
		(width 0.381)
		(layer "B.Cu")
		(net "P3V3_AUX")
	)
	(segment
		(start 449.52666 -51.976528)
		(end 450.441568 -51.976528)
		(width 0.508)
		(layer "B.Cu")
		(net "P3V3_AUX")
	)
	(segment
		(start 428.135542 -118.470934)
		(end 428.269908 -118.6053)
		(width 0.381)
		(layer "B.Cu")
		(net "P3V3_AUX")
	)
	(segment
		(start 181.59095 -21.764498)
		(end 180.8734 -21.764498)
		(width 0.381)
		(layer "B.Cu")
		(net "P3V3_AUX")
	)
	(segment
		(start 118.052596 -362.754672)
		(end 115.617498 -365.18977)
		(width 0.508)
		(layer "In2.Cu")
		(net "P3V3_AUX")
	)
	(segment
		(start 138.015218 -371.11559)
		(end 117.485922 -371.11559)
		(width 0.508)
		(layer "In2.Cu")
		(net "P3V3_AUX")
	)
	(segment
		(start 247.027192 -58.794904)
		(end 252.84049 -58.794904)
		(width 0.508)
		(layer "In2.Cu")
		(net "P3V3_AUX")
	)
	(segment
		(start 115.617498 -365.18977)
		(end 115.617498 -368.52987)
		(width 0.508)
		(layer "In2.Cu")
		(net "P3V3_AUX")
	)
	(segment
		(start 164.1983 -8.656828)
		(end 163.2077 -9.647428)
		(width 0.381)
		(layer "In2.Cu")
		(net "P3V3_AUX")
	)
	(segment
		(start 26.63825 -124.70892)
		(end 25.63368 -124.70892)
		(width 0.381)
		(layer "In2.Cu")
		(net "P3V3_AUX")
	)
	(segment
		(start 240.14684 -436.41264)
		(end 237.8329 -438.72658)
		(width 0.381)
		(layer "In2.Cu")
		(net "P3V3_AUX")
	)
	(segment
		(start 262.052308 -64.26708)
		(end 262.052308 -67.08902)
		(width 0.508)
		(layer "In2.Cu")
		(net "P3V3_AUX")
	)
	(segment
		(start 242.9764 -423.38625)
		(end 242.83797 -423.24782)
		(width 0.381)
		(layer "In2.Cu")
		(net "P3V3_AUX")
	)
	(segment
		(start 333.23784 -15.139416)
		(end 332.276196 -16.10106)
		(width 0.381)
		(layer "In2.Cu")
		(net "P3V3_AUX")
	)
	(segment
		(start 365.110522 -358.26446)
		(end 365.110522 -357.197406)
		(width 0.381)
		(layer "In2.Cu")
		(net "P3V3_AUX")
	)
	(segment
		(start 114.680238 -369.46713)
		(end 115.617498 -368.52987)
		(width 0.508)
		(layer "In2.Cu")
		(net "P3V3_AUX")
	)
	(segment
		(start 115.617498 -369.247166)
		(end 115.617498 -368.52987)
		(width 0.508)
		(layer "In2.Cu")
		(net "P3V3_AUX")
	)
	(segment
		(start 252.84049 -58.794904)
		(end 254.30353 -57.331864)
		(width 0.508)
		(layer "In2.Cu")
		(net "P3V3_AUX")
	)
	(segment
		(start 243.187474 -51.17973)
		(end 243.187474 -54.955186)
		(width 0.508)
		(layer "In2.Cu")
		(net "P3V3_AUX")
	)
	(segment
		(start 365.523272 -363.622082)
		(end 365.523272 -358.67721)
		(width 0.381)
		(layer "In2.Cu")
		(net "P3V3_AUX")
	)
	(segment
		(start 235.295694 -421.28948)
		(end 234.877102 -421.708072)
		(width 0.381)
		(layer "In2.Cu")
		(net "P3V3_AUX")
	)
	(segment
		(start 82.071718 -20.616672)
		(end 82.071718 -19.542252)
		(width 0.508)
		(layer "In2.Cu")
		(net "P3V3_AUX")
	)
	(segment
		(start 366.418622 -357.197406)
		(end 365.110522 -357.197406)
		(width 0.381)
		(layer "In2.Cu")
		(net "P3V3_AUX")
	)
	(segment
		(start 278.66086 -61.7728)
		(end 264.546588 -61.7728)
		(width 0.508)
		(layer "In2.Cu")
		(net "P3V3_AUX")
	)
	(segment
		(start 237.78972 -426.30344)
		(end 239.76584 -426.30344)
		(width 0.381)
		(layer "In2.Cu")
		(net "P3V3_AUX")
	)
	(segment
		(start 116.7257 -355.942392)
		(end 116.7257 -356.364794)
		(width 0.508)
		(layer "In2.Cu")
		(net "P3V3_AUX")
	)
	(segment
		(start 24.235156 -130.542538)
		(end 24.235156 -131.616704)
		(width 0.381)
		(layer "In2.Cu")
		(net "P3V3_AUX")
	)
	(segment
		(start 368.598704 -355.352604)
		(end 368.263424 -355.352604)
		(width 0.381)
		(layer "In2.Cu")
		(net "P3V3_AUX")
	)
	(segment
		(start 157.07995 -8.071358)
		(end 156.63545 -8.071358)
		(width 0.381)
		(layer "In2.Cu")
		(net "P3V3_AUX")
	)
	(segment
		(start 374.01754 -32.001968)
		(end 368.24158 -26.226008)
		(width 0.381)
		(layer "In2.Cu")
		(net "P3V3_AUX")
	)
	(segment
		(start 234.877102 -423.390822)
		(end 237.78972 -426.30344)
		(width 0.381)
		(layer "In2.Cu")
		(net "P3V3_AUX")
	)
	(segment
		(start 120.046496 -355.69779)
		(end 118.052596 -357.69169)
		(width 0.508)
		(layer "In2.Cu")
		(net "P3V3_AUX")
	)
	(segment
		(start 87.0458 -35.474148)
		(end 87.0458 -35.020758)
		(width 0.508)
		(layer "In2.Cu")
		(net "P3V3_AUX")
	)
	(segment
		(start 115.37569 -365.18977)
		(end 115.617498 -365.18977)
		(width 0.508)
		(layer "In2.Cu")
		(net "P3V3_AUX")
	)
	(segment
		(start 25.903682 -131.94792)
		(end 25.903682 -131.5974)
		(width 0.381)
		(layer "In2.Cu")
		(net "P3V3_AUX")
	)
	(segment
		(start 120.645682 -355.69779)
		(end 120.046496 -355.69779)
		(width 0.508)
		(layer "In2.Cu")
		(net "P3V3_AUX")
	)
	(segment
		(start 254.30353 -57.331864)
		(end 254.30353 -55.854092)
		(width 0.508)
		(layer "In2.Cu")
		(net "P3V3_AUX")
	)
	(segment
		(start 179.41798 -13.332968)
		(end 179.06492 -13.686028)
		(width 0.381)
		(layer "In2.Cu")
		(net "P3V3_AUX")
	)
	(segment
		(start 242.83797 -423.24782)
		(end 239.75314 -423.24782)
		(width 0.381)
		(layer "In2.Cu")
		(net "P3V3_AUX")
	)
	(segment
		(start 156.23921 -7.675118)
		(end 150.61819 -7.675118)
		(width 0.381)
		(layer "In2.Cu")
		(net "P3V3_AUX")
	)
	(segment
		(start 368.263424 -355.352604)
		(end 366.418622 -357.197406)
		(width 0.381)
		(layer "In2.Cu")
		(net "P3V3_AUX")
	)
	(segment
		(start 175.321722 -13.686028)
		(end 174.235872 -14.771878)
		(width 0.381)
		(layer "In2.Cu")
		(net "P3V3_AUX")
	)
	(segment
		(start 365.523272 -358.67721)
		(end 365.110522 -358.26446)
		(width 0.381)
		(layer "In2.Cu")
		(net "P3V3_AUX")
	)
	(segment
		(start 239.24006 -421.70604)
		(end 238.8235 -421.28948)
		(width 0.381)
		(layer "In2.Cu")
		(net "P3V3_AUX")
	)
	(segment
		(start 24.86787 -129.909824)
		(end 24.235156 -130.542538)
		(width 0.381)
		(layer "In2.Cu")
		(net "P3V3_AUX")
	)
	(segment
		(start 243.187474 -54.955186)
		(end 247.027192 -58.794904)
		(width 0.508)
		(layer "In2.Cu")
		(net "P3V3_AUX")
	)
	(segment
		(start 84.019136 -31.994094)
		(end 84.019136 -21.075396)
		(width 0.508)
		(layer "In2.Cu")
		(net "P3V3_AUX")
	)
	(segment
		(start 333.23784 -14.770608)
		(end 333.23784 -15.139416)
		(width 0.381)
		(layer "In2.Cu")
		(net "P3V3_AUX")
	)
	(segment
		(start 241.887756 -49.880012)
		(end 243.187474 -51.17973)
		(width 0.508)
		(layer "In2.Cu")
		(net "P3V3_AUX")
	)
	(segment
		(start 362.4961 -364.76178)
		(end 364.383574 -364.76178)
		(width 0.381)
		(layer "In2.Cu")
		(net "P3V3_AUX")
	)
	(segment
		(start 165.454584 -8.656828)
		(end 164.1983 -8.656828)
		(width 0.381)
		(layer "In2.Cu")
		(net "P3V3_AUX")
	)
	(segment
		(start 264.546588 -61.7728)
		(end 262.052308 -64.26708)
		(width 0.508)
		(layer "In2.Cu")
		(net "P3V3_AUX")
	)
	(segment
		(start 361.93222 -364.1979)
		(end 362.4961 -364.76178)
		(width 0.381)
		(layer "In2.Cu")
		(net "P3V3_AUX")
	)
	(segment
		(start 87.49919 -35.474148)
		(end 92.33535 -40.310308)
		(width 0.508)
		(layer "In2.Cu")
		(net "P3V3_AUX")
	)
	(segment
		(start 25.63368 -124.70892)
		(end 24.86787 -125.47473)
		(width 0.381)
		(layer "In2.Cu")
		(net "P3V3_AUX")
	)
	(segment
		(start 116.7257 -356.364794)
		(end 118.052596 -357.69169)
		(width 0.508)
		(layer "In2.Cu")
		(net "P3V3_AUX")
	)
	(segment
		(start 239.75314 -423.24782)
		(end 239.24006 -422.73474)
		(width 0.381)
		(layer "In2.Cu")
		(net "P3V3_AUX")
	)
	(segment
		(start 150.61819 -7.675118)
		(end 148.30806 -9.985248)
		(width 0.381)
		(layer "In2.Cu")
		(net "P3V3_AUX")
	)
	(segment
		(start 144.399 -8.918448)
		(end 144.399 -8.346948)
		(width 0.381)
		(layer "In2.Cu")
		(net "P3V3_AUX")
	)
	(segment
		(start 105.426764 -369.46713)
		(end 114.680238 -369.46713)
		(width 0.508)
		(layer "In2.Cu")
		(net "P3V3_AUX")
	)
	(segment
		(start 240.14684 -426.68444)
		(end 240.14684 -436.41264)
		(width 0.381)
		(layer "In2.Cu")
		(net "P3V3_AUX")
	)
	(segment
		(start 332.276196 -16.10106)
		(end 332.276196 -17.437608)
		(width 0.381)
		(layer "In2.Cu")
		(net "P3V3_AUX")
	)
	(segment
		(start 87.0458 -35.474148)
		(end 87.49919 -35.474148)
		(width 0.508)
		(layer "In2.Cu")
		(net "P3V3_AUX")
	)
	(segment
		(start 156.63545 -8.071358)
		(end 156.23921 -7.675118)
		(width 0.381)
		(layer "In2.Cu")
		(net "P3V3_AUX")
	)
	(segment
		(start 148.30806 -9.985248)
		(end 145.4658 -9.985248)
		(width 0.381)
		(layer "In2.Cu")
		(net "P3V3_AUX")
	)
	(segment
		(start 234.877102 -421.708072)
		(end 234.877102 -423.390822)
		(width 0.381)
		(layer "In2.Cu")
		(net "P3V3_AUX")
	)
	(segment
		(start 24.235156 -131.616704)
		(end 24.7904 -132.171948)
		(width 0.381)
		(layer "In2.Cu")
		(net "P3V3_AUX")
	)
	(segment
		(start 145.4658 -9.985248)
		(end 144.399 -8.918448)
		(width 0.381)
		(layer "In2.Cu")
		(net "P3V3_AUX")
	)
	(segment
		(start 114.57432 -364.16996)
		(end 114.57432 -364.3884)
		(width 0.508)
		(layer "In2.Cu")
		(net "P3V3_AUX")
	)
	(segment
		(start 24.7904 -132.171948)
		(end 25.679654 -132.171948)
		(width 0.381)
		(layer "In2.Cu")
		(net "P3V3_AUX")
	)
	(segment
		(start 239.76584 -426.30344)
		(end 240.14684 -426.68444)
		(width 0.381)
		(layer "In2.Cu")
		(net "P3V3_AUX")
	)
	(segment
		(start 165.593522 -8.51789)
		(end 165.454584 -8.656828)
		(width 0.381)
		(layer "In2.Cu")
		(net "P3V3_AUX")
	)
	(segment
		(start 237.8329 -438.72658)
		(end 193.448686 -438.72658)
		(width 0.381)
		(layer "In2.Cu")
		(net "P3V3_AUX")
	)
	(segment
		(start 24.86787 -125.47473)
		(end 24.86787 -129.909824)
		(width 0.381)
		(layer "In2.Cu")
		(net "P3V3_AUX")
	)
	(segment
		(start 368.24158 -15.940278)
		(end 366.84585 -14.544548)
		(width 0.381)
		(layer "In2.Cu")
		(net "P3V3_AUX")
	)
	(segment
		(start 279.15362 -62.26556)
		(end 278.66086 -61.7728)
		(width 0.508)
		(layer "In2.Cu")
		(net "P3V3_AUX")
	)
	(segment
		(start 193.448686 -438.72658)
		(end 192.877186 -439.29808)
		(width 0.381)
		(layer "In2.Cu")
		(net "P3V3_AUX")
	)
	(segment
		(start 101.915976 -365.956342)
		(end 105.426764 -369.46713)
		(width 0.508)
		(layer "In2.Cu")
		(net "P3V3_AUX")
	)
	(segment
		(start 114.57432 -364.3884)
		(end 115.37569 -365.18977)
		(width 0.508)
		(layer "In2.Cu")
		(net "P3V3_AUX")
	)
	(segment
		(start 140.984478 -368.14633)
		(end 138.015218 -371.11559)
		(width 0.508)
		(layer "In2.Cu")
		(net "P3V3_AUX")
	)
	(segment
		(start 118.052596 -357.69169)
		(end 118.052596 -362.754672)
		(width 0.508)
		(layer "In2.Cu")
		(net "P3V3_AUX")
	)
	(segment
		(start 163.2077 -9.647428)
		(end 158.65602 -9.647428)
		(width 0.381)
		(layer "In2.Cu")
		(net "P3V3_AUX")
	)
	(segment
		(start 238.8235 -421.28948)
		(end 235.295694 -421.28948)
		(width 0.381)
		(layer "In2.Cu")
		(net "P3V3_AUX")
	)
	(segment
		(start 364.383574 -364.76178)
		(end 365.523272 -363.622082)
		(width 0.381)
		(layer "In2.Cu")
		(net "P3V3_AUX")
	)
	(segment
		(start 25.679654 -132.171948)
		(end 25.903682 -131.94792)
		(width 0.381)
		(layer "In2.Cu")
		(net "P3V3_AUX")
	)
	(segment
		(start 117.485922 -371.11559)
		(end 115.617498 -369.247166)
		(width 0.508)
		(layer "In2.Cu")
		(net "P3V3_AUX")
	)
	(segment
		(start 83.560412 -20.616672)
		(end 82.071718 -20.616672)
		(width 0.508)
		(layer "In2.Cu")
		(net "P3V3_AUX")
	)
	(segment
		(start 239.24006 -422.73474)
		(end 239.24006 -421.70604)
		(width 0.381)
		(layer "In2.Cu")
		(net "P3V3_AUX")
	)
	(segment
		(start 87.0458 -35.020758)
		(end 84.019136 -31.994094)
		(width 0.508)
		(layer "In2.Cu")
		(net "P3V3_AUX")
	)
	(segment
		(start 158.65602 -9.647428)
		(end 157.07995 -8.071358)
		(width 0.381)
		(layer "In2.Cu")
		(net "P3V3_AUX")
	)
	(segment
		(start 179.41798 -11.882628)
		(end 179.41798 -13.332968)
		(width 0.381)
		(layer "In2.Cu")
		(net "P3V3_AUX")
	)
	(segment
		(start 84.019136 -21.075396)
		(end 83.560412 -20.616672)
		(width 0.508)
		(layer "In2.Cu")
		(net "P3V3_AUX")
	)
	(segment
		(start 179.06492 -13.686028)
		(end 175.321722 -13.686028)
		(width 0.381)
		(layer "In2.Cu")
		(net "P3V3_AUX")
	)
	(segment
		(start 383.667 -32.001968)
		(end 374.01754 -32.001968)
		(width 0.381)
		(layer "In2.Cu")
		(net "P3V3_AUX")
	)
	(segment
		(start 368.24158 -26.226008)
		(end 368.24158 -15.940278)
		(width 0.381)
		(layer "In2.Cu")
		(net "P3V3_AUX")
	)
	(segment
		(start 217.55735 -315.49975)
		(end 217.07348 -315.49975)
		(width 0.381)
		(layer "In4.Cu")
		(net "P3V3_AUX")
	)
	(segment
		(start 173.625002 -15.382748)
		(end 174.235872 -14.771878)
		(width 0.381)
		(layer "In4.Cu")
		(net "P3V3_AUX")
	)
	(segment
		(start 21.9202 -167.7543)
		(end 21.072094 -166.906194)
		(width 0.381)
		(layer "In4.Cu")
		(net "P3V3_AUX")
	)
	(segment
		(start 31.292292 -117.025928)
		(end 47.251874 -117.025928)
		(width 0.508)
		(layer "In4.Cu")
		(net "P3V3_AUX")
	)
	(segment
		(start 196.019166 -355.694234)
		(end 195.22948 -354.904548)
		(width 0.508)
		(layer "In4.Cu")
		(net "P3V3_AUX")
	)
	(segment
		(start 293.778686 -325.927212)
		(end 293.778686 -326.81799)
		(width 0.381)
		(layer "In4.Cu")
		(net "P3V3_AUX")
	)
	(segment
		(start 217.72753 -132.629148)
		(end 217.72753 -132.469636)
		(width 0.508)
		(layer "In4.Cu")
		(net "P3V3_AUX")
	)
	(segment
		(start 24.543004 -186.991498)
		(end 21.61413 -184.062624)
		(width 0.381)
		(layer "In4.Cu")
		(net "P3V3_AUX")
	)
	(segment
		(start 148.9964 -129.329434)
		(end 147.04695 -131.278884)
		(width 0.381)
		(layer "In4.Cu")
		(net "P3V3_AUX")
	)
	(segment
		(start 34.842196 -168.148508)
		(end 34.842196 -161.540952)
		(width 0.381)
		(layer "In4.Cu")
		(net "P3V3_AUX")
	)
	(segment
		(start 37.10559 -122.560334)
		(end 37.10559 -124.898658)
		(width 0.508)
		(layer "In4.Cu")
		(net "P3V3_AUX")
	)
	(segment
		(start 150.22195 -132.673598)
		(end 148.441664 -132.673598)
		(width 0.381)
		(layer "In4.Cu")
		(net "P3V3_AUX")
	)
	(segment
		(start 22.047962 -179.023772)
		(end 24.552148 -179.023772)
		(width 0.381)
		(layer "In4.Cu")
		(net "P3V3_AUX")
	)
	(segment
		(start 21.45538 -170.946064)
		(end 21.45538 -169.850308)
		(width 0.381)
		(layer "In4.Cu")
		(net "P3V3_AUX")
	)
	(segment
		(start 217.9574 -315.8998)
		(end 217.55735 -315.49975)
		(width 0.381)
		(layer "In4.Cu")
		(net "P3V3_AUX")
	)
	(segment
		(start 21.289518 -178.265328)
		(end 22.047962 -179.023772)
		(width 0.381)
		(layer "In4.Cu")
		(net "P3V3_AUX")
	)
	(segment
		(start 74.04989 -36.64204)
		(end 68.615814 -36.64204)
		(width 0.508)
		(layer "In4.Cu")
		(net "P3V3_AUX")
	)
	(segment
		(start 217.9574 -318.262)
		(end 217.9574 -315.8998)
		(width 0.381)
		(layer "In4.Cu")
		(net "P3V3_AUX")
	)
	(segment
		(start 217.245438 -126.959106)
		(end 219.10548 -128.819148)
		(width 0.508)
		(layer "In4.Cu")
		(net "P3V3_AUX")
	)
	(segment
		(start 152.57399 -132.679948)
		(end 151.71801 -131.823968)
		(width 0.381)
		(layer "In4.Cu")
		(net "P3V3_AUX")
	)
	(segment
		(start 438.10301 -34.85896)
		(end 438.10301 -33.188656)
		(width 0.508)
		(layer "In4.Cu")
		(net "P3V3_AUX")
	)
	(segment
		(start 18.165826 -183.631586)
		(end 17.521174 -182.986934)
		(width 0.381)
		(layer "In4.Cu")
		(net "P3V3_AUX")
	)
	(segment
		(start 219.398342 -129.11201)
		(end 219.10548 -128.819148)
		(width 0.508)
		(layer "In4.Cu")
		(net "P3V3_AUX")
	)
	(segment
		(start 148.9964 -128.057148)
		(end 148.9964 -129.329434)
		(width 0.381)
		(layer "In4.Cu")
		(net "P3V3_AUX")
	)
	(segment
		(start 140.909802 -368.071654)
		(end 140.984478 -368.14633)
		(width 0.508)
		(layer "In4.Cu")
		(net "P3V3_AUX")
	)
	(segment
		(start 25.426416 -174.9171)
		(end 21.45538 -170.946064)
		(width 0.381)
		(layer "In4.Cu")
		(net "P3V3_AUX")
	)
	(segment
		(start 26.63825 -124.70892)
		(end 27.424634 -124.70892)
		(width 0.508)
		(layer "In4.Cu")
		(net "P3V3_AUX")
	)
	(segment
		(start 33.55594 -170.74388)
		(end 33.55594 -169.29608)
		(width 0.381)
		(layer "In4.Cu")
		(net "P3V3_AUX")
	)
	(segment
		(start 25.313894 -178.262026)
		(end 25.313894 -177.341276)
		(width 0.381)
		(layer "In4.Cu")
		(net "P3V3_AUX")
	)
	(segment
		(start 304.686208 -321.55638)
		(end 304.686208 -321.84086)
		(width 0.381)
		(layer "In4.Cu")
		(net "P3V3_AUX")
	)
	(segment
		(start 40.687752 -118.978172)
		(end 37.10559 -122.560334)
		(width 0.508)
		(layer "In4.Cu")
		(net "P3V3_AUX")
	)
	(segment
		(start 196.293994 -352.641662)
		(end 195.20408 -351.551748)
		(width 0.508)
		(layer "In4.Cu")
		(net "P3V3_AUX")
	)
	(segment
		(start 50.252122 -114.795046)
		(end 50.583846 -115.12677)
		(width 0.508)
		(layer "In4.Cu")
		(net "P3V3_AUX")
	)
	(segment
		(start 67.81165 -35.587178)
		(end 67.20078 -34.976308)
		(width 0.508)
		(layer "In4.Cu")
		(net "P3V3_AUX")
	)
	(segment
		(start 136.559036 -367.029238)
		(end 137.601452 -368.071654)
		(width 0.508)
		(layer "In4.Cu")
		(net "P3V3_AUX")
	)
	(segment
		(start 25.313894 -177.341276)
		(end 24.937466 -176.964848)
		(width 0.381)
		(layer "In4.Cu")
		(net "P3V3_AUX")
	)
	(segment
		(start 195.556886 -354.904548)
		(end 196.293994 -354.16744)
		(width 0.508)
		(layer "In4.Cu")
		(net "P3V3_AUX")
	)
	(segment
		(start 197.79996 -324.13194)
		(end 197.79996 -321.102228)
		(width 0.508)
		(layer "In4.Cu")
		(net "P3V3_AUX")
	)
	(segment
		(start 195.22948 -354.904548)
		(end 195.556886 -354.904548)
		(width 0.508)
		(layer "In4.Cu")
		(net "P3V3_AUX")
	)
	(segment
		(start 213.01583 -126.089664)
		(end 213.885272 -126.959106)
		(width 0.508)
		(layer "In4.Cu")
		(net "P3V3_AUX")
	)
	(segment
		(start 17.521174 -180.532278)
		(end 19.788124 -178.265328)
		(width 0.381)
		(layer "In4.Cu")
		(net "P3V3_AUX")
	)
	(segment
		(start 193.934334 -331.729842)
		(end 196.272658 -329.391518)
		(width 0.508)
		(layer "In4.Cu")
		(net "P3V3_AUX")
	)
	(segment
		(start 151.71801 -128.15316)
		(end 151.061928 -127.497078)
		(width 0.381)
		(layer "In4.Cu")
		(net "P3V3_AUX")
	)
	(segment
		(start 151.71801 -131.823968)
		(end 151.71801 -128.15316)
		(width 0.381)
		(layer "In4.Cu")
		(net "P3V3_AUX")
	)
	(segment
		(start 129.348484 -360.680508)
		(end 133.501638 -360.680508)
		(width 0.508)
		(layer "In4.Cu")
		(net "P3V3_AUX")
	)
	(segment
		(start 438.10301 -33.188656)
		(end 436.865522 -31.951168)
		(width 0.508)
		(layer "In4.Cu")
		(net "P3V3_AUX")
	)
	(segment
		(start 436.865522 -31.951168)
		(end 436.865522 -29.633418)
		(width 0.508)
		(layer "In4.Cu")
		(net "P3V3_AUX")
	)
	(segment
		(start 195.659756 -359.349548)
		(end 196.019166 -358.990138)
		(width 0.508)
		(layer "In4.Cu")
		(net "P3V3_AUX")
	)
	(segment
		(start 196.019166 -358.990138)
		(end 196.019166 -355.694234)
		(width 0.508)
		(layer "In4.Cu")
		(net "P3V3_AUX")
	)
	(segment
		(start 21.61413 -183.429656)
		(end 21.4122 -183.631586)
		(width 0.381)
		(layer "In4.Cu")
		(net "P3V3_AUX")
	)
	(segment
		(start 213.885272 -126.959106)
		(end 217.245438 -126.959106)
		(width 0.508)
		(layer "In4.Cu")
		(net "P3V3_AUX")
	)
	(segment
		(start 34.842196 -161.540952)
		(end 34.472118 -161.170874)
		(width 0.381)
		(layer "In4.Cu")
		(net "P3V3_AUX")
	)
	(segment
		(start 68.615814 -36.64204)
		(end 67.81165 -35.837876)
		(width 0.508)
		(layer "In4.Cu")
		(net "P3V3_AUX")
	)
	(segment
		(start 67.20078 -34.976308)
		(end 64.455548 -34.976308)
		(width 0.508)
		(layer "In4.Cu")
		(net "P3V3_AUX")
	)
	(segment
		(start 64.455548 -34.976308)
		(end 62.184788 -32.705548)
		(width 0.508)
		(layer "In4.Cu")
		(net "P3V3_AUX")
	)
	(segment
		(start 217.5764 -318.643)
		(end 217.9574 -318.262)
		(width 0.381)
		(layer "In4.Cu")
		(net "P3V3_AUX")
	)
	(segment
		(start 33.55594 -169.29608)
		(end 33.35782 -169.09796)
		(width 0.381)
		(layer "In4.Cu")
		(net "P3V3_AUX")
	)
	(segment
		(start 50.542444 -118.978172)
		(end 40.687752 -118.978172)
		(width 0.508)
		(layer "In4.Cu")
		(net "P3V3_AUX")
	)
	(segment
		(start 194.442334 -351.551748)
		(end 193.934334 -351.043748)
		(width 0.508)
		(layer "In4.Cu")
		(net "P3V3_AUX")
	)
	(segment
		(start 196.272658 -325.659242)
		(end 197.79996 -324.13194)
		(width 0.508)
		(layer "In4.Cu")
		(net "P3V3_AUX")
	)
	(segment
		(start 37.148516 -126.404624)
		(end 37.148516 -128.213104)
		(width 0.381)
		(layer "In4.Cu")
		(net "P3V3_AUX")
	)
	(segment
		(start 33.892744 -169.09796)
		(end 34.842196 -168.148508)
		(width 0.381)
		(layer "In4.Cu")
		(net "P3V3_AUX")
	)
	(segment
		(start 21.9202 -169.385488)
		(end 21.9202 -167.7543)
		(width 0.381)
		(layer "In4.Cu")
		(net "P3V3_AUX")
	)
	(segment
		(start 34.472118 -161.170874)
		(end 33.900618 -161.170874)
		(width 0.381)
		(layer "In4.Cu")
		(net "P3V3_AUX")
	)
	(segment
		(start 26.087832 -174.767748)
		(end 27.290268 -174.767748)
		(width 0.381)
		(layer "In4.Cu")
		(net "P3V3_AUX")
	)
	(segment
		(start 21.4122 -183.631586)
		(end 18.165826 -183.631586)
		(width 0.381)
		(layer "In4.Cu")
		(net "P3V3_AUX")
	)
	(segment
		(start 437.66486 -43.960288)
		(end 438.10301 -43.522138)
		(width 0.508)
		(layer "In4.Cu")
		(net "P3V3_AUX")
	)
	(segment
		(start 219.398342 -130.798824)
		(end 219.398342 -129.11201)
		(width 0.508)
		(layer "In4.Cu")
		(net "P3V3_AUX")
	)
	(segment
		(start 197.79996 -321.102228)
		(end 196.41439 -319.716658)
		(width 0.508)
		(layer "In4.Cu")
		(net "P3V3_AUX")
	)
	(segment
		(start 30.354016 -171.704)
		(end 32.59582 -171.704)
		(width 0.381)
		(layer "In4.Cu")
		(net "P3V3_AUX")
	)
	(segment
		(start 210.514946 -319.716658)
		(end 211.588604 -318.643)
		(width 0.381)
		(layer "In4.Cu")
		(net "P3V3_AUX")
	)
	(segment
		(start 8.864346 -182.9689)
		(end 6.9342 -184.899046)
		(width 0.381)
		(layer "In4.Cu")
		(net "P3V3_AUX")
	)
	(segment
		(start 168.607994 -15.382748)
		(end 173.625002 -15.382748)
		(width 0.381)
		(layer "In4.Cu")
		(net "P3V3_AUX")
	)
	(segment
		(start 17.521174 -182.986934)
		(end 17.521174 -180.532278)
		(width 0.381)
		(layer "In4.Cu")
		(net "P3V3_AUX")
	)
	(segment
		(start 37.432742 -129.262886)
		(end 37.432742 -130.491992)
		(width 0.381)
		(layer "In4.Cu")
		(net "P3V3_AUX")
	)
	(segment
		(start 438.75198 -40.096186)
		(end 438.75198 -35.50793)
		(width 0.508)
		(layer "In4.Cu")
		(net "P3V3_AUX")
	)
	(segment
		(start 302.433736 -324.093332)
		(end 295.612566 -324.093332)
		(width 0.381)
		(layer "In4.Cu")
		(net "P3V3_AUX")
	)
	(segment
		(start 211.588604 -318.643)
		(end 217.5764 -318.643)
		(width 0.381)
		(layer "In4.Cu")
		(net "P3V3_AUX")
	)
	(segment
		(start 50.583846 -118.93677)
		(end 50.542444 -118.978172)
		(width 0.508)
		(layer "In4.Cu")
		(net "P3V3_AUX")
	)
	(segment
		(start 307.04282 -319.199768)
		(end 304.686208 -321.55638)
		(width 0.381)
		(layer "In4.Cu")
		(net "P3V3_AUX")
	)
	(segment
		(start 37.965888 -128.72974)
		(end 37.432742 -129.262886)
		(width 0.381)
		(layer "In4.Cu")
		(net "P3V3_AUX")
	)
	(segment
		(start 8.864346 -180.6956)
		(end 8.864346 -182.9689)
		(width 0.381)
		(layer "In4.Cu")
		(net "P3V3_AUX")
	)
	(segment
		(start 28.053538 -120.264682)
		(end 31.292292 -117.025928)
		(width 0.508)
		(layer "In4.Cu")
		(net "P3V3_AUX")
	)
	(segment
		(start 21.61413 -184.062624)
		(end 21.61413 -183.429656)
		(width 0.381)
		(layer "In4.Cu")
		(net "P3V3_AUX")
	)
	(segment
		(start 32.59582 -171.704)
		(end 33.55594 -170.74388)
		(width 0.381)
		(layer "In4.Cu")
		(net "P3V3_AUX")
	)
	(segment
		(start 196.293994 -354.16744)
		(end 196.293994 -352.641662)
		(width 0.508)
		(layer "In4.Cu")
		(net "P3V3_AUX")
	)
	(segment
		(start 27.290268 -174.767748)
		(end 30.354016 -171.704)
		(width 0.381)
		(layer "In4.Cu")
		(net "P3V3_AUX")
	)
	(segment
		(start 19.788124 -178.265328)
		(end 19.83232 -178.265328)
		(width 0.381)
		(layer "In4.Cu")
		(net "P3V3_AUX")
	)
	(segment
		(start 193.934334 -351.043748)
		(end 193.934334 -331.729842)
		(width 0.508)
		(layer "In4.Cu")
		(net "P3V3_AUX")
	)
	(segment
		(start 6.9342 -184.899046)
		(end 6.9342 -194.1068)
		(width 0.381)
		(layer "In4.Cu")
		(net "P3V3_AUX")
	)
	(segment
		(start 195.20408 -351.551748)
		(end 194.442334 -351.551748)
		(width 0.508)
		(layer "In4.Cu")
		(net "P3V3_AUX")
	)
	(segment
		(start 25.93848 -174.9171)
		(end 26.087832 -174.767748)
		(width 0.381)
		(layer "In4.Cu")
		(net "P3V3_AUX")
	)
	(segment
		(start 33.35782 -169.09796)
		(end 33.892744 -169.09796)
		(width 0.381)
		(layer "In4.Cu")
		(net "P3V3_AUX")
	)
	(segment
		(start 21.45538 -169.850308)
		(end 21.9202 -169.385488)
		(width 0.381)
		(layer "In4.Cu")
		(net "P3V3_AUX")
	)
	(segment
		(start 438.10301 -40.745156)
		(end 438.75198 -40.096186)
		(width 0.508)
		(layer "In4.Cu")
		(net "P3V3_AUX")
	)
	(segment
		(start 159.766 -17.109948)
		(end 160.8328 -16.043148)
		(width 0.508)
		(layer "In4.Cu")
		(net "P3V3_AUX")
	)
	(segment
		(start 295.612566 -324.093332)
		(end 293.778686 -325.927212)
		(width 0.381)
		(layer "In4.Cu")
		(net "P3V3_AUX")
	)
	(segment
		(start 62.184788 -29.347922)
		(end 62.184788 -28.331922)
		(width 0.508)
		(layer "In4.Cu")
		(net "P3V3_AUX")
	)
	(segment
		(start 167.947594 -16.043148)
		(end 168.607994 -15.382748)
		(width 0.508)
		(layer "In4.Cu")
		(net "P3V3_AUX")
	)
	(segment
		(start 37.665152 -128.72974)
		(end 37.965888 -128.72974)
		(width 0.381)
		(layer "In4.Cu")
		(net "P3V3_AUX")
	)
	(segment
		(start 37.10559 -124.898658)
		(end 37.772594 -125.565662)
		(width 0.508)
		(layer "In4.Cu")
		(net "P3V3_AUX")
	)
	(segment
		(start 25.93848 -174.9171)
		(end 25.426416 -174.9171)
		(width 0.381)
		(layer "In4.Cu")
		(net "P3V3_AUX")
	)
	(segment
		(start 160.8328 -16.043148)
		(end 167.947594 -16.043148)
		(width 0.508)
		(layer "In4.Cu")
		(net "P3V3_AUX")
	)
	(segment
		(start 37.432742 -130.491992)
		(end 37.70249 -130.76174)
		(width 0.381)
		(layer "In4.Cu")
		(net "P3V3_AUX")
	)
	(segment
		(start 304.686208 -321.84086)
		(end 302.433736 -324.093332)
		(width 0.381)
		(layer "In4.Cu")
		(net "P3V3_AUX")
	)
	(segment
		(start 136.559036 -363.737906)
		(end 136.559036 -367.029238)
		(width 0.508)
		(layer "In4.Cu")
		(net "P3V3_AUX")
	)
	(segment
		(start 67.81165 -35.837876)
		(end 67.81165 -35.587178)
		(width 0.508)
		(layer "In4.Cu")
		(net "P3V3_AUX")
	)
	(segment
		(start 150.89886 -127.497078)
		(end 149.55647 -127.497078)
		(width 0.381)
		(layer "In4.Cu")
		(net "P3V3_AUX")
	)
	(segment
		(start 151.061928 -127.497078)
		(end 150.89886 -127.497078)
		(width 0.381)
		(layer "In4.Cu")
		(net "P3V3_AUX")
	)
	(segment
		(start 62.184788 -32.705548)
		(end 62.184788 -29.347922)
		(width 0.508)
		(layer "In4.Cu")
		(net "P3V3_AUX")
	)
	(segment
		(start 28.053538 -124.080016)
		(end 28.053538 -120.264682)
		(width 0.508)
		(layer "In4.Cu")
		(net "P3V3_AUX")
	)
	(segment
		(start 148.441664 -132.673598)
		(end 147.04695 -131.278884)
		(width 0.381)
		(layer "In4.Cu")
		(net "P3V3_AUX")
	)
	(segment
		(start 47.251874 -117.025928)
		(end 49.482756 -114.795046)
		(width 0.508)
		(layer "In4.Cu")
		(net "P3V3_AUX")
	)
	(segment
		(start 149.55647 -127.497078)
		(end 148.9964 -128.057148)
		(width 0.381)
		(layer "In4.Cu")
		(net "P3V3_AUX")
	)
	(segment
		(start 438.75198 -35.50793)
		(end 438.10301 -34.85896)
		(width 0.508)
		(layer "In4.Cu")
		(net "P3V3_AUX")
	)
	(segment
		(start 19.83232 -178.265328)
		(end 21.289518 -178.265328)
		(width 0.381)
		(layer "In4.Cu")
		(net "P3V3_AUX")
	)
	(segment
		(start 196.272658 -329.391518)
		(end 196.272658 -325.659242)
		(width 0.508)
		(layer "In4.Cu")
		(net "P3V3_AUX")
	)
	(segment
		(start 133.501638 -360.680508)
		(end 136.559036 -363.737906)
		(width 0.508)
		(layer "In4.Cu")
		(net "P3V3_AUX")
	)
	(segment
		(start 137.601452 -368.071654)
		(end 140.909802 -368.071654)
		(width 0.508)
		(layer "In4.Cu")
		(net "P3V3_AUX")
	)
	(segment
		(start 37.70249 -130.76174)
		(end 37.976048 -130.76174)
		(width 0.381)
		(layer "In4.Cu")
		(net "P3V3_AUX")
	)
	(segment
		(start 49.482756 -114.795046)
		(end 50.252122 -114.795046)
		(width 0.508)
		(layer "In4.Cu")
		(net "P3V3_AUX")
	)
	(segment
		(start 436.865522 -29.633418)
		(end 436.865522 -28.617418)
		(width 0.508)
		(layer "In4.Cu")
		(net "P3V3_AUX")
	)
	(segment
		(start 24.937466 -176.964848)
		(end 24.937466 -175.40605)
		(width 0.381)
		(layer "In4.Cu")
		(net "P3V3_AUX")
	)
	(segment
		(start 438.10301 -43.522138)
		(end 438.10301 -40.745156)
		(width 0.508)
		(layer "In4.Cu")
		(net "P3V3_AUX")
	)
	(segment
		(start 75.305412 -37.897562)
		(end 74.04989 -36.64204)
		(width 0.508)
		(layer "In4.Cu")
		(net "P3V3_AUX")
	)
	(segment
		(start 37.148516 -128.213104)
		(end 37.665152 -128.72974)
		(width 0.381)
		(layer "In4.Cu")
		(net "P3V3_AUX")
	)
	(segment
		(start 24.937466 -175.40605)
		(end 25.426416 -174.9171)
		(width 0.381)
		(layer "In4.Cu")
		(net "P3V3_AUX")
	)
	(segment
		(start 37.772594 -125.565662)
		(end 37.987478 -125.565662)
		(width 0.508)
		(layer "In4.Cu")
		(net "P3V3_AUX")
	)
	(segment
		(start 24.552148 -179.023772)
		(end 25.313894 -178.262026)
		(width 0.381)
		(layer "In4.Cu")
		(net "P3V3_AUX")
	)
	(segment
		(start 195.02628 -359.349548)
		(end 195.659756 -359.349548)
		(width 0.508)
		(layer "In4.Cu")
		(net "P3V3_AUX")
	)
	(segment
		(start 217.72753 -132.469636)
		(end 219.398342 -130.798824)
		(width 0.508)
		(layer "In4.Cu")
		(net "P3V3_AUX")
	)
	(segment
		(start 213.01583 -125.186948)
		(end 213.01583 -126.089664)
		(width 0.508)
		(layer "In4.Cu")
		(net "P3V3_AUX")
	)
	(segment
		(start 196.41439 -319.716658)
		(end 195.427346 -319.716658)
		(width 0.508)
		(layer "In4.Cu")
		(net "P3V3_AUX")
	)
	(segment
		(start 161.80308 -132.679948)
		(end 152.57399 -132.679948)
		(width 0.381)
		(layer "In4.Cu")
		(net "P3V3_AUX")
	)
	(segment
		(start 27.424634 -124.70892)
		(end 28.053538 -124.080016)
		(width 0.508)
		(layer "In4.Cu")
		(net "P3V3_AUX")
	)
	(segment
		(start 37.987478 -125.565662)
		(end 37.148516 -126.404624)
		(width 0.381)
		(layer "In4.Cu")
		(net "P3V3_AUX")
	)
	(segment
		(start 175.811942 -16.347948)
		(end 178.054 -16.347948)
		(width 0.381)
		(layer "In6.Cu")
		(net "P3V3_AUX")
	)
	(segment
		(start 81.604104 -151.834596)
		(end 83.591146 -149.847554)
		(width 0.508)
		(layer "In6.Cu")
		(net "P3V3_AUX")
	)
	(segment
		(start 288.8234 -56.200548)
		(end 282.440634 -62.583314)
		(width 0.381)
		(layer "In6.Cu")
		(net "P3V3_AUX")
	)
	(segment
		(start 301.85614 -58.461148)
		(end 295.4782 -58.461148)
		(width 0.381)
		(layer "In6.Cu")
		(net "P3V3_AUX")
	)
	(segment
		(start 160.290764 -12.436348)
		(end 163.453064 -9.274048)
		(width 0.381)
		(layer "In6.Cu")
		(net "P3V3_AUX")
	)
	(segment
		(start 158.38932 -13.637768)
		(end 159.59074 -12.436348)
		(width 0.381)
		(layer "In6.Cu")
		(net "P3V3_AUX")
	)
	(segment
		(start 81.604104 -152.221692)
		(end 81.604104 -151.834596)
		(width 0.508)
		(layer "In6.Cu")
		(net "P3V3_AUX")
	)
	(segment
		(start 283.821378 -413.63773)
		(end 283.821378 -414.861502)
		(width 0.508)
		(layer "In6.Cu")
		(net "P3V3_AUX")
	)
	(segment
		(start 174.235872 -14.771878)
		(end 175.811942 -16.347948)
		(width 0.381)
		(layer "In6.Cu")
		(net "P3V3_AUX")
	)
	(segment
		(start 368.912648 -185.413142)
		(end 368.912648 -186.614562)
		(width 0.508)
		(layer "In6.Cu")
		(net "P3V3_AUX")
	)
	(segment
		(start 163.453064 -9.274048)
		(end 165.1508 -9.274048)
		(width 0.381)
		(layer "In6.Cu")
		(net "P3V3_AUX")
	)
	(segment
		(start 276.55266 -417.02482)
		(end 276.55266 -418.76091)
		(width 0.508)
		(layer "In6.Cu")
		(net "P3V3_AUX")
	)
	(segment
		(start 83.591146 -142.38224)
		(end 70.504812 -129.295906)
		(width 0.508)
		(layer "In6.Cu")
		(net "P3V3_AUX")
	)
	(segment
		(start 178.054 -16.347948)
		(end 181.102 -19.395948)
		(width 0.381)
		(layer "In6.Cu")
		(net "P3V3_AUX")
	)
	(segment
		(start 295.4782 -58.461148)
		(end 294.513 -57.495948)
		(width 0.381)
		(layer "In6.Cu")
		(net "P3V3_AUX")
	)
	(segment
		(start 158.74238 -14.542008)
		(end 158.38932 -14.188948)
		(width 0.381)
		(layer "In6.Cu")
		(net "P3V3_AUX")
	)
	(segment
		(start 181.102 -19.395948)
		(end 181.102 -20.157948)
		(width 0.381)
		(layer "In6.Cu")
		(net "P3V3_AUX")
	)
	(segment
		(start 181.102 -20.157948)
		(end 180.975 -20.284948)
		(width 0.381)
		(layer "In6.Cu")
		(net "P3V3_AUX")
	)
	(segment
		(start 279.471374 -62.583314)
		(end 279.15362 -62.26556)
		(width 0.381)
		(layer "In6.Cu")
		(net "P3V3_AUX")
	)
	(segment
		(start 411.196282 -365.545116)
		(end 411.196282 -361.62615)
		(width 0.508)
		(layer "In6.Cu")
		(net "P3V3_AUX")
	)
	(segment
		(start 294.513 -57.495948)
		(end 291.4904 -57.495948)
		(width 0.381)
		(layer "In6.Cu")
		(net "P3V3_AUX")
	)
	(segment
		(start 282.649676 -416.033204)
		(end 280.795476 -416.033204)
		(width 0.508)
		(layer "In6.Cu")
		(net "P3V3_AUX")
	)
	(segment
		(start 303.48936 -60.094368)
		(end 301.85614 -58.461148)
		(width 0.381)
		(layer "In6.Cu")
		(net "P3V3_AUX")
	)
	(segment
		(start 159.59074 -12.436348)
		(end 160.290764 -12.436348)
		(width 0.381)
		(layer "In6.Cu")
		(net "P3V3_AUX")
	)
	(segment
		(start 369.212876 -186.91479)
		(end 370.15674 -186.91479)
		(width 0.508)
		(layer "In6.Cu")
		(net "P3V3_AUX")
	)
	(segment
		(start 159.766 -17.109948)
		(end 158.74238 -16.086328)
		(width 0.381)
		(layer "In6.Cu")
		(net "P3V3_AUX")
	)
	(segment
		(start 158.74238 -16.086328)
		(end 158.74238 -14.542008)
		(width 0.381)
		(layer "In6.Cu")
		(net "P3V3_AUX")
	)
	(segment
		(start 369.884198 -184.64403)
		(end 369.68176 -184.64403)
		(width 0.508)
		(layer "In6.Cu")
		(net "P3V3_AUX")
	)
	(segment
		(start 282.440634 -62.583314)
		(end 279.471374 -62.583314)
		(width 0.381)
		(layer "In6.Cu")
		(net "P3V3_AUX")
	)
	(segment
		(start 158.38932 -14.188948)
		(end 158.38932 -13.637768)
		(width 0.381)
		(layer "In6.Cu")
		(net "P3V3_AUX")
	)
	(segment
		(start 290.195 -56.200548)
		(end 288.8234 -56.200548)
		(width 0.381)
		(layer "In6.Cu")
		(net "P3V3_AUX")
	)
	(segment
		(start 165.1508 -9.274048)
		(end 165.593522 -8.831326)
		(width 0.381)
		(layer "In6.Cu")
		(net "P3V3_AUX")
	)
	(segment
		(start 410.565346 -360.995214)
		(end 410.225748 -360.995214)
		(width 0.508)
		(layer "In6.Cu")
		(net "P3V3_AUX")
	)
	(segment
		(start 411.196282 -361.62615)
		(end 410.565346 -360.995214)
		(width 0.508)
		(layer "In6.Cu")
		(net "P3V3_AUX")
	)
	(segment
		(start 83.591146 -149.847554)
		(end 83.591146 -142.38224)
		(width 0.508)
		(layer "In6.Cu")
		(net "P3V3_AUX")
	)
	(segment
		(start 410.77261 -365.968788)
		(end 411.196282 -365.545116)
		(width 0.508)
		(layer "In6.Cu")
		(net "P3V3_AUX")
	)
	(segment
		(start 280.795476 -416.033204)
		(end 279.80386 -417.02482)
		(width 0.508)
		(layer "In6.Cu")
		(net "P3V3_AUX")
	)
	(segment
		(start 276.55266 -418.76091)
		(end 277.93315 -420.1414)
		(width 0.508)
		(layer "In6.Cu")
		(net "P3V3_AUX")
	)
	(segment
		(start 369.68176 -184.64403)
		(end 368.912648 -185.413142)
		(width 0.508)
		(layer "In6.Cu")
		(net "P3V3_AUX")
	)
	(segment
		(start 165.593522 -8.831326)
		(end 165.593522 -8.51789)
		(width 0.381)
		(layer "In6.Cu")
		(net "P3V3_AUX")
	)
	(segment
		(start 368.912648 -186.614562)
		(end 369.212876 -186.91479)
		(width 0.508)
		(layer "In6.Cu")
		(net "P3V3_AUX")
	)
	(segment
		(start 370.15674 -186.91479)
		(end 370.23548 -186.99353)
		(width 0.508)
		(layer "In6.Cu")
		(net "P3V3_AUX")
	)
	(segment
		(start 277.93315 -420.1414)
		(end 277.93315 -424.61434)
		(width 0.508)
		(layer "In6.Cu")
		(net "P3V3_AUX")
	)
	(segment
		(start 279.80386 -417.02482)
		(end 276.55266 -417.02482)
		(width 0.508)
		(layer "In6.Cu")
		(net "P3V3_AUX")
	)
	(segment
		(start 283.821378 -414.861502)
		(end 282.649676 -416.033204)
		(width 0.508)
		(layer "In6.Cu")
		(net "P3V3_AUX")
	)
	(segment
		(start 291.4904 -57.495948)
		(end 290.195 -56.200548)
		(width 0.381)
		(layer "In6.Cu")
		(net "P3V3_AUX")
	)
	(segment
		(start 408.88666 -357.71201)
		(end 407.256234 -359.342436)
		(width 0.4572)
		(layer "In11.Cu")
		(net "P3V3_AUX")
	)
	(segment
		(start 396.127478 -150.69566)
		(end 395.658848 -151.16429)
		(width 0.508)
		(layer "In11.Cu")
		(net "P3V3_AUX")
	)
	(segment
		(start 408.2288 -144.4498)
		(end 408.9654 -143.7132)
		(width 0.508)
		(layer "In11.Cu")
		(net "P3V3_AUX")
	)
	(segment
		(start 398.213072 -359.342436)
		(end 392.411458 -365.14405)
		(width 0.4572)
		(layer "In11.Cu")
		(net "P3V3_AUX")
	)
	(segment
		(start 382.338326 -362.482638)
		(end 379.090428 -362.482638)
		(width 0.4572)
		(layer "In11.Cu")
		(net "P3V3_AUX")
	)
	(segment
		(start 410.737558 -358.265984)
		(end 410.183584 -357.71201)
		(width 0.4572)
		(layer "In11.Cu")
		(net "P3V3_AUX")
	)
	(segment
		(start 395.658848 -151.16429)
		(end 393.73429 -151.16429)
		(width 0.508)
		(layer "In11.Cu")
		(net "P3V3_AUX")
	)
	(segment
		(start 393.73429 -151.16429)
		(end 393.37488 -150.80488)
		(width 0.508)
		(layer "In11.Cu")
		(net "P3V3_AUX")
	)
	(segment
		(start 410.0068 -122.0724)
		(end 418.4396 -122.0724)
		(width 0.508)
		(layer "In11.Cu")
		(net "P3V3_AUX")
	)
	(segment
		(start 395.2748 -145.2372)
		(end 396.0622 -144.4498)
		(width 0.508)
		(layer "In11.Cu")
		(net "P3V3_AUX")
	)
	(segment
		(start 408.9654 -143.7132)
		(end 408.9654 -123.1138)
		(width 0.508)
		(layer "In11.Cu")
		(net "P3V3_AUX")
	)
	(segment
		(start 396.127478 -150.687278)
		(end 395.2748 -149.8346)
		(width 0.508)
		(layer "In11.Cu")
		(net "P3V3_AUX")
	)
	(segment
		(start 407.256234 -359.342436)
		(end 398.213072 -359.342436)
		(width 0.4572)
		(layer "In11.Cu")
		(net "P3V3_AUX")
	)
	(segment
		(start 179.197 -27.107388)
		(end 180.92166 -27.107388)
		(width 0.381)
		(layer "In11.Cu")
		(net "P3V3_AUX")
	)
	(segment
		(start 350.117918 -359.484168)
		(end 349.472758 -359.484168)
		(width 0.381)
		(layer "In11.Cu")
		(net "P3V3_AUX")
	)
	(segment
		(start 408.9654 -123.1138)
		(end 410.0068 -122.0724)
		(width 0.508)
		(layer "In11.Cu")
		(net "P3V3_AUX")
	)
	(segment
		(start 350.58858 -359.764584)
		(end 350.308164 -359.484168)
		(width 0.381)
		(layer "In11.Cu")
		(net "P3V3_AUX")
	)
	(segment
		(start 396.0622 -144.4498)
		(end 408.2288 -144.4498)
		(width 0.508)
		(layer "In11.Cu")
		(net "P3V3_AUX")
	)
	(segment
		(start 410.183584 -357.71201)
		(end 408.88666 -357.71201)
		(width 0.4572)
		(layer "In11.Cu")
		(net "P3V3_AUX")
	)
	(segment
		(start 410.737558 -360.315256)
		(end 410.737558 -358.265984)
		(width 0.4572)
		(layer "In11.Cu")
		(net "P3V3_AUX")
	)
	(segment
		(start 410.225748 -360.827066)
		(end 410.737558 -360.315256)
		(width 0.4572)
		(layer "In11.Cu")
		(net "P3V3_AUX")
	)
	(segment
		(start 382.715516 -188.29401)
		(end 383.3749 -188.29401)
		(width 0.508)
		(layer "In11.Cu")
		(net "P3V3_AUX")
	)
	(segment
		(start 418.4396 -122.0724)
		(end 419.3286 -122.9614)
		(width 0.508)
		(layer "In11.Cu")
		(net "P3V3_AUX")
	)
	(segment
		(start 350.58858 -361.749848)
		(end 350.58858 -359.764584)
		(width 0.381)
		(layer "In11.Cu")
		(net "P3V3_AUX")
	)
	(segment
		(start 392.10488 -147.792948)
		(end 392.399774 -148.087842)
		(width 0.508)
		(layer "In11.Cu")
		(net "P3V3_AUX")
	)
	(segment
		(start 179.048156 -27.256232)
		(end 179.197 -27.107388)
		(width 0.381)
		(layer "In11.Cu")
		(net "P3V3_AUX")
	)
	(segment
		(start 174.329852 -27.256232)
		(end 179.048156 -27.256232)
		(width 0.381)
		(layer "In11.Cu")
		(net "P3V3_AUX")
	)
	(segment
		(start 410.225748 -360.995214)
		(end 410.225748 -360.827066)
		(width 0.4572)
		(layer "In11.Cu")
		(net "P3V3_AUX")
	)
	(segment
		(start 383.3749 -188.29401)
		(end 382.753362 -188.915548)
		(width 0.508)
		(layer "In11.Cu")
		(net "P3V3_AUX")
	)
	(segment
		(start 350.308164 -359.484168)
		(end 350.117918 -359.484168)
		(width 0.381)
		(layer "In11.Cu")
		(net "P3V3_AUX")
	)
	(segment
		(start 384.999738 -365.14405)
		(end 382.338326 -362.482638)
		(width 0.4572)
		(layer "In11.Cu")
		(net "P3V3_AUX")
	)
	(segment
		(start 381.889 -187.467494)
		(end 382.715516 -188.29401)
		(width 0.508)
		(layer "In11.Cu")
		(net "P3V3_AUX")
	)
	(segment
		(start 381.889 -161.450782)
		(end 381.889 -187.467494)
		(width 0.508)
		(layer "In11.Cu")
		(net "P3V3_AUX")
	)
	(segment
		(start 379.090428 -362.482638)
		(end 377.288298 -360.680508)
		(width 0.4572)
		(layer "In11.Cu")
		(net "P3V3_AUX")
	)
	(segment
		(start 392.399774 -150.940008)
		(end 381.889 -161.450782)
		(width 0.508)
		(layer "In11.Cu")
		(net "P3V3_AUX")
	)
	(segment
		(start 382.753362 -188.915548)
		(end 374.109234 -188.915548)
		(width 0.508)
		(layer "In11.Cu")
		(net "P3V3_AUX")
	)
	(segment
		(start 372.187216 -186.99353)
		(end 370.23548 -186.99353)
		(width 0.508)
		(layer "In11.Cu")
		(net "P3V3_AUX")
	)
	(segment
		(start 392.399774 -148.087842)
		(end 392.399774 -150.940008)
		(width 0.508)
		(layer "In11.Cu")
		(net "P3V3_AUX")
	)
	(segment
		(start 374.109234 -188.915548)
		(end 372.187216 -186.99353)
		(width 0.508)
		(layer "In11.Cu")
		(net "P3V3_AUX")
	)
	(segment
		(start 349.472758 -359.484168)
		(end 348.206314 -358.217724)
		(width 0.381)
		(layer "In11.Cu")
		(net "P3V3_AUX")
	)
	(segment
		(start 395.2748 -149.8346)
		(end 395.2748 -145.2372)
		(width 0.508)
		(layer "In11.Cu")
		(net "P3V3_AUX")
	)
	(segment
		(start 396.127478 -150.69566)
		(end 396.127478 -150.687278)
		(width 0.508)
		(layer "In11.Cu")
		(net "P3V3_AUX")
	)
	(segment
		(start 350.790764 -361.952032)
		(end 350.58858 -361.749848)
		(width 0.381)
		(layer "In11.Cu")
		(net "P3V3_AUX")
	)
	(segment
		(start 392.10488 -147.792948)
		(end 393.37488 -147.792948)
		(width 0.508)
		(layer "In11.Cu")
		(net "P3V3_AUX")
	)
	(segment
		(start 393.37488 -150.80488)
		(end 393.37488 -147.792948)
		(width 0.508)
		(layer "In11.Cu")
		(net "P3V3_AUX")
	)
	(segment
		(start 172.206412 -29.379672)
		(end 174.329852 -27.256232)
		(width 0.381)
		(layer "In11.Cu")
		(net "P3V3_AUX")
	)
	(segment
		(start 392.411458 -365.14405)
		(end 384.999738 -365.14405)
		(width 0.4572)
		(layer "In11.Cu")
		(net "P3V3_AUX")
	)
	(segment
		(start 452.886572 -78.801976)
		(end 451.8914 -79.797148)
		(width 0.381)
		(layer "In13.Cu")
		(net "P3V3_AUX")
	)
	(segment
		(start 452.886572 -76.639166)
		(end 452.886572 -77.210666)
		(width 0.381)
		(layer "In13.Cu")
		(net "P3V3_AUX")
	)
	(segment
		(start 443.41542 -57.894728)
		(end 439.928 -61.382148)
		(width 0.381)
		(layer "In13.Cu")
		(net "P3V3_AUX")
	)
	(segment
		(start 446.78092 -51.976528)
		(end 443.41542 -55.342028)
		(width 0.381)
		(layer "In13.Cu")
		(net "P3V3_AUX")
	)
	(segment
		(start 439.928 -61.382148)
		(end 439.928 -78.044548)
		(width 0.381)
		(layer "In13.Cu")
		(net "P3V3_AUX")
	)
	(segment
		(start 452.9328 -78.231492)
		(end 452.886572 -78.27772)
		(width 0.381)
		(layer "In13.Cu")
		(net "P3V3_AUX")
	)
	(segment
		(start 441.8584 -79.974948)
		(end 448.270884 -79.974948)
		(width 0.381)
		(layer "In13.Cu")
		(net "P3V3_AUX")
	)
	(segment
		(start 451.8914 -79.797148)
		(end 450.320156 -79.797148)
		(width 0.381)
		(layer "In13.Cu")
		(net "P3V3_AUX")
	)
	(segment
		(start 252.73 -38.324282)
		(end 253.3015 -38.324282)
		(width 0.381)
		(layer "In13.Cu")
		(net "P3V3_AUX")
	)
	(segment
		(start 449.52666 -51.976528)
		(end 446.78092 -51.976528)
		(width 0.381)
		(layer "In13.Cu")
		(net "P3V3_AUX")
	)
	(segment
		(start 448.270884 -79.974948)
		(end 449.38442 -78.861412)
		(width 0.381)
		(layer "In13.Cu")
		(net "P3V3_AUX")
	)
	(segment
		(start 253.317502 -38.340284)
		(end 253.793498 -38.340284)
		(width 0.381)
		(layer "In13.Cu")
		(net "P3V3_AUX")
	)
	(segment
		(start 452.886572 -77.210666)
		(end 452.9328 -77.256894)
		(width 0.381)
		(layer "In13.Cu")
		(net "P3V3_AUX")
	)
	(segment
		(start 439.928 -78.044548)
		(end 441.8584 -79.974948)
		(width 0.381)
		(layer "In13.Cu")
		(net "P3V3_AUX")
	)
	(segment
		(start 452.886572 -78.27772)
		(end 452.886572 -78.801976)
		(width 0.381)
		(layer "In13.Cu")
		(net "P3V3_AUX")
	)
	(segment
		(start 253.8095 -38.324282)
		(end 254.381 -38.324282)
		(width 0.381)
		(layer "In13.Cu")
		(net "P3V3_AUX")
	)
	(segment
		(start 253.3015 -38.324282)
		(end 253.317502 -38.340284)
		(width 0.381)
		(layer "In13.Cu")
		(net "P3V3_AUX")
	)
	(segment
		(start 443.41542 -55.342028)
		(end 443.41542 -57.894728)
		(width 0.381)
		(layer "In13.Cu")
		(net "P3V3_AUX")
	)
	(segment
		(start 452.9328 -77.256894)
		(end 452.9328 -78.231492)
		(width 0.381)
		(layer "In13.Cu")
		(net "P3V3_AUX")
	)
	(segment
		(start 450.320156 -79.797148)
		(end 449.38442 -78.861412)
		(width 0.381)
		(layer "In13.Cu")
		(net "P3V3_AUX")
	)
	(segment
		(start 253.793498 -38.340284)
		(end 253.8095 -38.324282)
		(width 0.381)
		(layer "In13.Cu")
		(net "P3V3_AUX")
	)
	(segment
		(start 361.642914 -364.487206)
		(end 361.642914 -365.625888)
		(width 0.381)
		(layer "In15.Cu")
		(net "P3V3_AUX")
	)
	(segment
		(start 278.559006 -22.61997)
		(end 266.80414 -34.374836)
		(width 0.508)
		(layer "In15.Cu")
		(net "P3V3_AUX")
	)
	(segment
		(start 266.80414 -34.374836)
		(end 264.122408 -34.374836)
		(width 0.508)
		(layer "In15.Cu")
		(net "P3V3_AUX")
	)
	(segment
		(start 350.790764 -363.485938)
		(end 350.790764 -361.952032)
		(width 0.381)
		(layer "In15.Cu")
		(net "P3V3_AUX")
	)
	(segment
		(start 289.643058 -22.61997)
		(end 278.559006 -22.61997)
		(width 0.508)
		(layer "In15.Cu")
		(net "P3V3_AUX")
	)
	(segment
		(start 456.337162 -51.27879)
		(end 457.0349 -51.976528)
		(width 0.508)
		(layer "In15.Cu")
		(net "P3V3_AUX")
	)
	(segment
		(start 259.952744 -39.166546)
		(end 255.858264 -39.166546)
		(width 0.508)
		(layer "In15.Cu")
		(net "P3V3_AUX")
	)
	(segment
		(start 447.66484 -375.417588)
		(end 456.42784 -375.417588)
		(width 0.381)
		(layer "In15.Cu")
		(net "P3V3_AUX")
	)
	(segment
		(start 446.88252 -376.199908)
		(end 447.66484 -375.417588)
		(width 0.381)
		(layer "In15.Cu")
		(net "P3V3_AUX")
	)
	(segment
		(start 410.77261 -374.313196)
		(end 410.77261 -365.968788)
		(width 0.508)
		(layer "In15.Cu")
		(net "P3V3_AUX")
	)
	(segment
		(start 456.337162 -52.674266)
		(end 457.0349 -51.976528)
		(width 0.508)
		(layer "In15.Cu")
		(net "P3V3_AUX")
	)
	(segment
		(start 361.642914 -365.625888)
		(end 359.560622 -367.70818)
		(width 0.381)
		(layer "In15.Cu")
		(net "P3V3_AUX")
	)
	(segment
		(start 414.29559 -377.836176)
		(end 410.77261 -374.313196)
		(width 0.508)
		(layer "In15.Cu")
		(net "P3V3_AUX")
	)
	(segment
		(start 255.858264 -39.166546)
		(end 255.016 -38.324282)
		(width 0.508)
		(layer "In15.Cu")
		(net "P3V3_AUX")
	)
	(segment
		(start 302.006 -411.648656)
		(end 301.6504 -412.004256)
		(width 0.381)
		(layer "In15.Cu")
		(net "P3V3_AUX")
	)
	(segment
		(start 355.013006 -367.70818)
		(end 350.790764 -363.485938)
		(width 0.381)
		(layer "In15.Cu")
		(net "P3V3_AUX")
	)
	(segment
		(start 435.79542 -376.199908)
		(end 446.88252 -376.199908)
		(width 0.381)
		(layer "In15.Cu")
		(net "P3V3_AUX")
	)
	(segment
		(start 457.0349 -51.976528)
		(end 457.732638 -51.27879)
		(width 0.508)
		(layer "In15.Cu")
		(net "P3V3_AUX")
	)
	(segment
		(start 262.706358 -36.412932)
		(end 259.952744 -39.166546)
		(width 0.508)
		(layer "In15.Cu")
		(net "P3V3_AUX")
	)
	(segment
		(start 264.122408 -34.374836)
		(end 262.706358 -35.790886)
		(width 0.508)
		(layer "In15.Cu")
		(net "P3V3_AUX")
	)
	(segment
		(start 421.71747 -377.836176)
		(end 414.29559 -377.836176)
		(width 0.508)
		(layer "In15.Cu")
		(net "P3V3_AUX")
	)
	(segment
		(start 262.706358 -35.790886)
		(end 262.706358 -36.412932)
		(width 0.508)
		(layer "In15.Cu")
		(net "P3V3_AUX")
	)
	(segment
		(start 448.828922 -51.27879)
		(end 449.52666 -51.976528)
		(width 0.508)
		(layer "In15.Cu")
		(net "P3V3_AUX")
	)
	(segment
		(start 456.42784 -375.417588)
		(end 460.6798 -379.669548)
		(width 0.381)
		(layer "In15.Cu")
		(net "P3V3_AUX")
	)
	(segment
		(start 449.52666 -51.976528)
		(end 450.224398 -52.674266)
		(width 0.508)
		(layer "In15.Cu")
		(net "P3V3_AUX")
	)
	(segment
		(start 255.016 -38.324282)
		(end 254.381 -38.324282)
		(width 0.508)
		(layer "In15.Cu")
		(net "P3V3_AUX")
	)
	(segment
		(start 457.0349 -51.976528)
		(end 457.732638 -52.674266)
		(width 0.508)
		(layer "In15.Cu")
		(net "P3V3_AUX")
	)
	(segment
		(start 448.828922 -52.674266)
		(end 449.52666 -51.976528)
		(width 0.508)
		(layer "In15.Cu")
		(net "P3V3_AUX")
	)
	(segment
		(start 361.93222 -364.1979)
		(end 361.642914 -364.487206)
		(width 0.381)
		(layer "In15.Cu")
		(net "P3V3_AUX")
	)
	(segment
		(start 359.560622 -367.70818)
		(end 355.013006 -367.70818)
		(width 0.381)
		(layer "In15.Cu")
		(net "P3V3_AUX")
	)
	(segment
		(start 449.52666 -51.976528)
		(end 450.224398 -51.27879)
		(width 0.508)
		(layer "In15.Cu")
		(net "P3V3_AUX")
	)
	(segment
		(start 423.195242 -379.313948)
		(end 421.71747 -377.836176)
		(width 0.508)
		(layer "In15.Cu")
		(net "P3V3_AUX")
	)
	(segment
		(start 293.548562 -18.714466)
		(end 289.643058 -22.61997)
		(width 0.508)
		(layer "In15.Cu")
		(net "P3V3_AUX")
	)
	(segment
		(start 134.54888 -99.767898)
		(end 134.54888 -99.151948)
		(width 0.381)
		(layer "F.Cu")
		(net "P3V3")
	)
	(segment
		(start 258.621276 -132.10794)
		(end 258.621276 -131.502912)
		(width 0.381)
		(layer "F.Cu")
		(net "P3V3")
	)
	(segment
		(start 422.751504 -47.545498)
		(end 423.605706 -47.545498)
		(width 0.381)
		(layer "F.Cu")
		(net "P3V3")
	)
	(segment
		(start 407.15692 -142.240508)
		(end 393.17422 -142.240508)
		(width 0.508)
		(layer "F.Cu")
		(net "P3V3")
	)
	(segment
		(start 410.191458 -362.223304)
		(end 410.727398 -362.223304)
		(width 0.381)
		(layer "F.Cu")
		(net "P3V3")
	)
	(segment
		(start 145.520664 -96.043496)
		(end 145.175224 -96.043496)
		(width 0.381)
		(layer "F.Cu")
		(net "P3V3")
	)
	(segment
		(start 380.064518 -155.35021)
		(end 380.064518 -157.875986)
		(width 0.508)
		(layer "F.Cu")
		(net "P3V3")
	)
	(segment
		(start 380.064518 -157.875986)
		(end 375.328434 -162.61207)
		(width 0.508)
		(layer "F.Cu")
		(net "P3V3")
	)
	(segment
		(start 425.38777 -51.512724)
		(end 424.733974 -52.16652)
		(width 0.381)
		(layer "F.Cu")
		(net "P3V3")
	)
	(segment
		(start 345.526868 -174.39132)
		(end 345.162378 -174.02683)
		(width 0.508)
		(layer "F.Cu")
		(net "P3V3")
	)
	(segment
		(start 119.23903 -412.17469)
		(end 119.94134 -412.17469)
		(width 0.381)
		(layer "F.Cu")
		(net "P3V3")
	)
	(segment
		(start 118.671594 -93.804232)
		(end 118.671594 -94.463108)
		(width 0.381)
		(layer "F.Cu")
		(net "P3V3")
	)
	(segment
		(start 272.47342 -98.227642)
		(end 273.167348 -98.227642)
		(width 0.381)
		(layer "F.Cu")
		(net "P3V3")
	)
	(segment
		(start 264.526776 -129.439924)
		(end 264.526776 -128.652016)
		(width 0.381)
		(layer "F.Cu")
		(net "P3V3")
	)
	(segment
		(start 46.982634 -108.047282)
		(end 47.592234 -108.047282)
		(width 0.3556)
		(layer "F.Cu")
		(net "P3V3")
	)
	(segment
		(start 130.48488 -99.767898)
		(end 130.48488 -99.151948)
		(width 0.381)
		(layer "F.Cu")
		(net "P3V3")
	)
	(segment
		(start 120.5865 -412.81985)
		(end 120.5865 -414.194752)
		(width 0.381)
		(layer "F.Cu")
		(net "P3V3")
	)
	(segment
		(start 346.683838 -174.03191)
		(end 346.324428 -174.39132)
		(width 0.508)
		(layer "F.Cu")
		(net "P3V3")
	)
	(segment
		(start 145.920714 -95.643446)
		(end 145.520664 -96.043496)
		(width 0.381)
		(layer "F.Cu")
		(net "P3V3")
	)
	(segment
		(start 393.17422 -142.240508)
		(end 380.064518 -155.35021)
		(width 0.508)
		(layer "F.Cu")
		(net "P3V3")
	)
	(segment
		(start 345.162378 -174.02683)
		(end 345.162378 -173.040548)
		(width 0.508)
		(layer "F.Cu")
		(net "P3V3")
	)
	(segment
		(start 258.621276 -130.193796)
		(end 258.621276 -131.502912)
		(width 0.381)
		(layer "F.Cu")
		(net "P3V3")
	)
	(segment
		(start 117.169692 -93.271086)
		(end 117.169692 -92.583762)
		(width 0.381)
		(layer "F.Cu")
		(net "P3V3")
	)
	(segment
		(start 346.683838 -166.967662)
		(end 346.683838 -174.03191)
		(width 0.508)
		(layer "F.Cu")
		(net "P3V3")
	)
	(segment
		(start 351.03943 -162.61207)
		(end 346.683838 -166.967662)
		(width 0.508)
		(layer "F.Cu")
		(net "P3V3")
	)
	(segment
		(start 118.671594 -93.804232)
		(end 118.671594 -93.778832)
		(width 0.381)
		(layer "F.Cu")
		(net "P3V3")
	)
	(segment
		(start 258.595368 -132.133848)
		(end 258.621276 -132.10794)
		(width 0.381)
		(layer "F.Cu")
		(net "P3V3")
	)
	(segment
		(start 145.175224 -96.043496)
		(end 145.156174 -96.062546)
		(width 0.381)
		(layer "F.Cu")
		(net "P3V3")
	)
	(segment
		(start 115.75288 -102.193598)
		(end 115.75288 -102.809548)
		(width 0.381)
		(layer "F.Cu")
		(net "P3V3")
	)
	(segment
		(start 119.94134 -412.17469)
		(end 120.5865 -412.81985)
		(width 0.381)
		(layer "F.Cu")
		(net "P3V3")
	)
	(segment
		(start 142.0622 -104.516428)
		(end 142.0622 -105.184448)
		(width 0.381)
		(layer "F.Cu")
		(net "P3V3")
	)
	(segment
		(start 122.61088 -92.274898)
		(end 122.61088 -91.658948)
		(width 0.381)
		(layer "F.Cu")
		(net "P3V3")
	)
	(segment
		(start 264.526776 -129.439924)
		(end 264.573512 -129.48666)
		(width 0.381)
		(layer "F.Cu")
		(net "P3V3")
	)
	(segment
		(start 143.606012 -95.551498)
		(end 143.606012 -94.887542)
		(width 0.381)
		(layer "F.Cu")
		(net "P3V3")
	)
	(segment
		(start 410.727398 -362.223304)
		(end 410.801058 -362.296964)
		(width 0.381)
		(layer "F.Cu")
		(net "P3V3")
	)
	(segment
		(start 136.07288 -92.274898)
		(end 136.07288 -91.658948)
		(width 0.381)
		(layer "F.Cu")
		(net "P3V3")
	)
	(segment
		(start 375.328434 -162.61207)
		(end 351.03943 -162.61207)
		(width 0.508)
		(layer "F.Cu")
		(net "P3V3")
	)
	(segment
		(start 145.156174 -96.062546)
		(end 144.11706 -96.062546)
		(width 0.381)
		(layer "F.Cu")
		(net "P3V3")
	)
	(segment
		(start 283.426662 -362.984796)
		(end 283.426662 -362.290868)
		(width 0.381)
		(layer "F.Cu")
		(net "P3V3")
	)
	(segment
		(start 144.11706 -96.062546)
		(end 143.606012 -95.551498)
		(width 0.381)
		(layer "F.Cu")
		(net "P3V3")
	)
	(segment
		(start 35.596068 -353.70643)
		(end 36.154868 -353.70643)
		(width 0.381)
		(layer "F.Cu")
		(net "P3V3")
	)
	(segment
		(start 192.475866 -126.405386)
		(end 192.98285 -126.405386)
		(width 0.381)
		(layer "F.Cu")
		(net "P3V3")
	)
	(segment
		(start 166.03726 -353.659948)
		(end 166.140892 -353.76358)
		(width 0.381)
		(layer "F.Cu")
		(net "P3V3")
	)
	(segment
		(start 120.5865 -414.194752)
		(end 120.50649 -414.274762)
		(width 0.381)
		(layer "F.Cu")
		(net "P3V3")
	)
	(segment
		(start 166.140892 -353.76358)
		(end 166.664894 -353.76358)
		(width 0.381)
		(layer "F.Cu")
		(net "P3V3")
	)
	(segment
		(start 154.093672 -52.568348)
		(end 155.18511 -52.568348)
		(width 0.2286)
		(layer "F.Cu")
		(net "P3V3")
	)
	(segment
		(start 264.526776 -128.652016)
		(end 264.772902 -128.40589)
		(width 0.381)
		(layer "F.Cu")
		(net "P3V3")
	)
	(segment
		(start 155.18511 -52.568348)
		(end 155.290774 -52.674012)
		(width 0.2286)
		(layer "F.Cu")
		(net "P3V3")
	)
	(segment
		(start 36.154868 -353.70643)
		(end 36.205668 -353.75723)
		(width 0.381)
		(layer "F.Cu")
		(net "P3V3")
	)
	(segment
		(start 118.671594 -93.778832)
		(end 117.677438 -93.778832)
		(width 0.381)
		(layer "F.Cu")
		(net "P3V3")
	)
	(segment
		(start 117.677438 -93.778832)
		(end 117.169692 -93.271086)
		(width 0.381)
		(layer "F.Cu")
		(net "P3V3")
	)
	(segment
		(start 155.290774 -52.674012)
		(end 155.290774 -53.309012)
		(width 0.381)
		(layer "F.Cu")
		(net "P3V3")
	)
	(segment
		(start 144.94383 -345.129358)
		(end 144.94383 -345.784932)
		(width 0.381)
		(layer "F.Cu")
		(net "P3V3")
	)
	(segment
		(start 425.38777 -51.22418)
		(end 425.38777 -51.512724)
		(width 0.381)
		(layer "F.Cu")
		(net "P3V3")
	)
	(segment
		(start 130.73888 -92.274898)
		(end 130.73888 -91.658948)
		(width 0.381)
		(layer "F.Cu")
		(net "P3V3")
	)
	(segment
		(start 115.95354 -410.075888)
		(end 115.306094 -409.428442)
		(width 0.381)
		(layer "F.Cu")
		(net "P3V3")
	)
	(segment
		(start 264.772902 -128.40589)
		(end 264.772902 -127.548894)
		(width 0.381)
		(layer "F.Cu")
		(net "P3V3")
	)
	(segment
		(start 424.733974 -52.16652)
		(end 423.173652 -52.16652)
		(width 0.381)
		(layer "F.Cu")
		(net "P3V3")
	)
	(segment
		(start 127.69088 -92.274898)
		(end 127.69088 -91.658948)
		(width 0.381)
		(layer "F.Cu")
		(net "P3V3")
	)
	(segment
		(start 192.187068 -126.116588)
		(end 192.475866 -126.405386)
		(width 0.381)
		(layer "F.Cu")
		(net "P3V3")
	)
	(segment
		(start 346.324428 -174.39132)
		(end 345.526868 -174.39132)
		(width 0.508)
		(layer "F.Cu")
		(net "P3V3")
	)
	(segment
		(start 86.68893 -74.330306)
		(end 86.68893 -73.720706)
		(width 0.381)
		(layer "F.Cu")
		(net "P3V3")
	)
	(segment
		(start 264.573512 -129.48666)
		(end 266.493244 -129.48666)
		(width 0.381)
		(layer "F.Cu")
		(net "P3V3")
	)
	(segment
		(start 115.306094 -409.428442)
		(end 115.10137 -409.428442)
		(width 0.381)
		(layer "F.Cu")
		(net "P3V3")
	)
	(via
		(at 432.121056 -55.234332)
		(size 0.508)
		(drill 0.254)
		(layers "F.Cu" "B.Cu")
		(net "P3V3")
	)
	(via
		(at 258.595368 -132.133848)
		(size 0.508)
		(drill 0.254)
		(layers "F.Cu" "B.Cu")
		(net "P3V3")
	)
	(via
		(at 102.69728 -417.944808)
		(size 0.508)
		(drill 0.254)
		(layers "F.Cu" "B.Cu")
		(net "P3V3")
	)
	(via
		(at 225.921062 -116.567204)
		(size 0.508)
		(drill 0.254)
		(layers "F.Cu" "B.Cu")
		(net "P3V3")
	)
	(via
		(at 324.067424 -344.956892)
		(size 0.508)
		(drill 0.254)
		(layers "F.Cu" "B.Cu")
		(net "P3V3")
	)
	(via
		(at 432.883056 -54.599332)
		(size 0.508)
		(drill 0.254)
		(layers "F.Cu" "B.Cu")
		(net "P3V3")
	)
	(via
		(at 130.73888 -91.658948)
		(size 0.508)
		(drill 0.254)
		(layers "F.Cu" "B.Cu")
		(net "P3V3")
	)
	(via
		(at 102.04196 -418.612828)
		(size 0.508)
		(drill 0.254)
		(layers "F.Cu" "B.Cu")
		(net "P3V3")
	)
	(via
		(at 146.35988 -361.660948)
		(size 0.508)
		(drill 0.254)
		(layers "F.Cu" "B.Cu")
		(net "P3V3")
	)
	(via
		(at 431.435764 -54.585616)
		(size 0.508)
		(drill 0.254)
		(layers "F.Cu" "B.Cu")
		(net "P3V3")
	)
	(via
		(at 238.727488 -125.936502)
		(size 0.508)
		(drill 0.254)
		(layers "F.Cu" "B.Cu")
		(net "P3V3")
	)
	(via
		(at 113.875312 -401.948904)
		(size 0.508)
		(drill 0.254)
		(layers "F.Cu" "B.Cu")
		(net "P3V3")
	)
	(via
		(at 102.06228 -417.944808)
		(size 0.508)
		(drill 0.254)
		(layers "F.Cu" "B.Cu")
		(net "P3V3")
	)
	(via
		(at 432.883056 -55.869332)
		(size 0.508)
		(drill 0.254)
		(layers "F.Cu" "B.Cu")
		(net "P3V3")
	)
	(via
		(at 432.883056 -55.234332)
		(size 0.508)
		(drill 0.254)
		(layers "F.Cu" "B.Cu")
		(net "P3V3")
	)
	(via
		(at 430.140364 -54.534816)
		(size 0.508)
		(drill 0.254)
		(layers "F.Cu" "B.Cu")
		(net "P3V3")
	)
	(via
		(at 433.618386 -57.17032)
		(size 0.508)
		(drill 0.254)
		(layers "F.Cu" "B.Cu")
		(net "P3V3")
	)
	(via
		(at 155.290774 -53.309012)
		(size 0.508)
		(drill 0.254)
		(layers "F.Cu" "B.Cu")
		(net "P3V3")
	)
	(via
		(at 119.94134 -412.17469)
		(size 0.508)
		(drill 0.254)
		(layers "F.Cu" "B.Cu")
		(net "P3V3")
	)
	(via
		(at 270.881348 -386.102352)
		(size 0.508)
		(drill 0.254)
		(layers "F.Cu" "B.Cu")
		(net "P3V3")
	)
	(via
		(at 283.426662 -362.290868)
		(size 0.508)
		(drill 0.254)
		(layers "F.Cu" "B.Cu")
		(net "P3V3")
	)
	(via
		(at 410.191458 -362.223304)
		(size 0.508)
		(drill 0.254)
		(layers "F.Cu" "B.Cu")
		(net "P3V3")
	)
	(via
		(at 229.393496 -119.582438)
		(size 0.508)
		(drill 0.254)
		(layers "F.Cu" "B.Cu")
		(net "P3V3")
	)
	(via
		(at 430.20615 -55.221886)
		(size 0.508)
		(drill 0.254)
		(layers "F.Cu" "B.Cu")
		(net "P3V3")
	)
	(via
		(at 430.84115 -55.856886)
		(size 0.508)
		(drill 0.254)
		(layers "F.Cu" "B.Cu")
		(net "P3V3")
	)
	(via
		(at 27.284426 -123.902978)
		(size 0.508)
		(drill 0.254)
		(layers "F.Cu" "B.Cu")
		(net "P3V3")
	)
	(via
		(at 436.368698 -144.70507)
		(size 0.508)
		(drill 0.254)
		(layers "F.Cu" "B.Cu")
		(net "P3V3")
	)
	(via
		(at 436.810658 -373.910352)
		(size 0.508)
		(drill 0.254)
		(layers "F.Cu" "B.Cu")
		(net "P3V3")
	)
	(via
		(at 159.69742 -55.999888)
		(size 0.508)
		(drill 0.254)
		(layers "F.Cu" "B.Cu")
		(net "P3V3")
	)
	(via
		(at 422.76014 -156.960062)
		(size 0.508)
		(drill 0.254)
		(layers "F.Cu" "B.Cu")
		(net "P3V3")
	)
	(via
		(at 430.84115 -55.221886)
		(size 0.508)
		(drill 0.254)
		(layers "F.Cu" "B.Cu")
		(net "P3V3")
	)
	(via
		(at 432.121056 -55.869332)
		(size 0.508)
		(drill 0.254)
		(layers "F.Cu" "B.Cu")
		(net "P3V3")
	)
	(via
		(at 160.45942 -57.015888)
		(size 0.508)
		(drill 0.254)
		(layers "F.Cu" "B.Cu")
		(net "P3V3")
	)
	(via
		(at 130.48488 -99.151948)
		(size 0.508)
		(drill 0.254)
		(layers "F.Cu" "B.Cu")
		(net "P3V3")
	)
	(via
		(at 91.55938 -179.31511)
		(size 0.508)
		(drill 0.254)
		(layers "F.Cu" "B.Cu")
		(net "P3V3")
	)
	(via
		(at 432.86299 -56.56834)
		(size 0.508)
		(drill 0.254)
		(layers "F.Cu" "B.Cu")
		(net "P3V3")
	)
	(via
		(at 430.20615 -55.856886)
		(size 0.508)
		(drill 0.254)
		(layers "F.Cu" "B.Cu")
		(net "P3V3")
	)
	(via
		(at 407.15692 -142.240508)
		(size 0.508)
		(drill 0.254)
		(layers "F.Cu" "B.Cu")
		(net "P3V3")
	)
	(via
		(at 430.800764 -54.585616)
		(size 0.508)
		(drill 0.254)
		(layers "F.Cu" "B.Cu")
		(net "P3V3")
	)
	(via
		(at 430.140364 -53.214016)
		(size 0.508)
		(drill 0.254)
		(layers "F.Cu" "B.Cu")
		(net "P3V3")
	)
	(via
		(at 47.592234 -108.047282)
		(size 0.508)
		(drill 0.254)
		(layers "F.Cu" "B.Cu")
		(net "P3V3")
	)
	(via
		(at 37.18306 -382.07696)
		(size 0.508)
		(drill 0.254)
		(layers "F.Cu" "B.Cu")
		(net "P3V3")
	)
	(via
		(at 433.618386 -54.63032)
		(size 0.508)
		(drill 0.254)
		(layers "F.Cu" "B.Cu")
		(net "P3V3")
	)
	(via
		(at 432.095656 -53.913532)
		(size 0.508)
		(drill 0.254)
		(layers "F.Cu" "B.Cu")
		(net "P3V3")
	)
	(via
		(at 159.69742 -54.983888)
		(size 0.508)
		(drill 0.254)
		(layers "F.Cu" "B.Cu")
		(net "P3V3")
	)
	(via
		(at 438.005474 -339.422994)
		(size 0.508)
		(drill 0.254)
		(layers "F.Cu" "B.Cu")
		(net "P3V3")
	)
	(via
		(at 118.671594 -94.463108)
		(size 0.508)
		(drill 0.254)
		(layers "F.Cu" "B.Cu")
		(net "P3V3")
	)
	(via
		(at 88.401398 -185.09869)
		(size 0.508)
		(drill 0.254)
		(layers "F.Cu" "B.Cu")
		(net "P3V3")
	)
	(via
		(at 345.162378 -173.040548)
		(size 0.508)
		(drill 0.254)
		(layers "F.Cu" "B.Cu")
		(net "P3V3")
	)
	(via
		(at 432.095656 -53.278532)
		(size 0.508)
		(drill 0.254)
		(layers "F.Cu" "B.Cu")
		(net "P3V3")
	)
	(via
		(at 86.68893 -73.720706)
		(size 0.508)
		(drill 0.254)
		(layers "F.Cu" "B.Cu")
		(net "P3V3")
	)
	(via
		(at 431.435764 -53.264816)
		(size 0.508)
		(drill 0.254)
		(layers "F.Cu" "B.Cu")
		(net "P3V3")
	)
	(via
		(at 273.167348 -98.227642)
		(size 0.508)
		(drill 0.254)
		(layers "F.Cu" "B.Cu")
		(net "P3V3")
	)
	(via
		(at 115.75288 -102.809548)
		(size 0.508)
		(drill 0.254)
		(layers "F.Cu" "B.Cu")
		(net "P3V3")
	)
	(via
		(at 430.800764 -53.264816)
		(size 0.508)
		(drill 0.254)
		(layers "F.Cu" "B.Cu")
		(net "P3V3")
	)
	(via
		(at 431.47615 -55.856886)
		(size 0.508)
		(drill 0.254)
		(layers "F.Cu" "B.Cu")
		(net "P3V3")
	)
	(via
		(at 431.435764 -53.950616)
		(size 0.508)
		(drill 0.254)
		(layers "F.Cu" "B.Cu")
		(net "P3V3")
	)
	(via
		(at 432.121056 -54.599332)
		(size 0.508)
		(drill 0.254)
		(layers "F.Cu" "B.Cu")
		(net "P3V3")
	)
	(via
		(at 53.42128 -170.500548)
		(size 0.508)
		(drill 0.254)
		(layers "F.Cu" "B.Cu")
		(net "P3V3")
	)
	(via
		(at 166.03726 -353.659948)
		(size 0.508)
		(drill 0.254)
		(layers "F.Cu" "B.Cu")
		(net "P3V3")
	)
	(via
		(at 122.61088 -91.658948)
		(size 0.508)
		(drill 0.254)
		(layers "F.Cu" "B.Cu")
		(net "P3V3")
	)
	(via
		(at 144.94383 -345.784932)
		(size 0.508)
		(drill 0.254)
		(layers "F.Cu" "B.Cu")
		(net "P3V3")
	)
	(via
		(at 423.605706 -47.545498)
		(size 0.508)
		(drill 0.254)
		(layers "F.Cu" "B.Cu")
		(net "P3V3")
	)
	(via
		(at 145.920714 -95.643446)
		(size 0.508)
		(drill 0.254)
		(layers "F.Cu" "B.Cu")
		(net "P3V3")
	)
	(via
		(at 160.45942 -55.999888)
		(size 0.508)
		(drill 0.254)
		(layers "F.Cu" "B.Cu")
		(net "P3V3")
	)
	(via
		(at 433.618386 -55.90032)
		(size 0.508)
		(drill 0.254)
		(layers "F.Cu" "B.Cu")
		(net "P3V3")
	)
	(via
		(at 75.841098 -129.050796)
		(size 0.508)
		(drill 0.254)
		(layers "F.Cu" "B.Cu")
		(net "P3V3")
	)
	(via
		(at 244.944138 -129.403348)
		(size 0.508)
		(drill 0.254)
		(layers "F.Cu" "B.Cu")
		(net "P3V3")
	)
	(via
		(at 127.69088 -91.658948)
		(size 0.508)
		(drill 0.254)
		(layers "F.Cu" "B.Cu")
		(net "P3V3")
	)
	(via
		(at 433.618386 -56.53532)
		(size 0.508)
		(drill 0.254)
		(layers "F.Cu" "B.Cu")
		(net "P3V3")
	)
	(via
		(at 229.17404 -120.180862)
		(size 0.508)
		(drill 0.254)
		(layers "F.Cu" "B.Cu")
		(net "P3V3")
	)
	(via
		(at 117.654578 -393.075922)
		(size 0.508)
		(drill 0.254)
		(layers "F.Cu" "B.Cu")
		(net "P3V3")
	)
	(via
		(at 115.95354 -410.075888)
		(size 0.508)
		(drill 0.254)
		(layers "F.Cu" "B.Cu")
		(net "P3V3")
	)
	(via
		(at 142.0622 -105.184448)
		(size 0.508)
		(drill 0.254)
		(layers "F.Cu" "B.Cu")
		(net "P3V3")
	)
	(via
		(at 432.872642 -53.265578)
		(size 0.508)
		(drill 0.254)
		(layers "F.Cu" "B.Cu")
		(net "P3V3")
	)
	(via
		(at 102.67696 -418.612828)
		(size 0.508)
		(drill 0.254)
		(layers "F.Cu" "B.Cu")
		(net "P3V3")
	)
	(via
		(at 264.526776 -128.652016)
		(size 0.508)
		(drill 0.254)
		(layers "F.Cu" "B.Cu")
		(net "P3V3")
	)
	(via
		(at 430.800764 -53.950616)
		(size 0.508)
		(drill 0.254)
		(layers "F.Cu" "B.Cu")
		(net "P3V3")
	)
	(via
		(at 192.187068 -126.116588)
		(size 0.508)
		(drill 0.254)
		(layers "F.Cu" "B.Cu")
		(net "P3V3")
	)
	(via
		(at 431.47615 -55.221886)
		(size 0.508)
		(drill 0.254)
		(layers "F.Cu" "B.Cu")
		(net "P3V3")
	)
	(via
		(at 229.17404 -120.815862)
		(size 0.508)
		(drill 0.254)
		(layers "F.Cu" "B.Cu")
		(net "P3V3")
	)
	(via
		(at 134.54888 -99.151948)
		(size 0.508)
		(drill 0.254)
		(layers "F.Cu" "B.Cu")
		(net "P3V3")
	)
	(via
		(at 433.618386 -55.26532)
		(size 0.508)
		(drill 0.254)
		(layers "F.Cu" "B.Cu")
		(net "P3V3")
	)
	(via
		(at 430.140364 -53.899816)
		(size 0.508)
		(drill 0.254)
		(layers "F.Cu" "B.Cu")
		(net "P3V3")
	)
	(via
		(at 136.07288 -91.658948)
		(size 0.508)
		(drill 0.254)
		(layers "F.Cu" "B.Cu")
		(net "P3V3")
	)
	(via
		(at 160.45942 -54.983888)
		(size 0.508)
		(drill 0.254)
		(layers "F.Cu" "B.Cu")
		(net "P3V3")
	)
	(via
		(at 159.69742 -57.015888)
		(size 0.508)
		(drill 0.254)
		(layers "F.Cu" "B.Cu")
		(net "P3V3")
	)
	(via
		(at 173.26864 -393.20216)
		(size 0.508)
		(drill 0.254)
		(layers "F.Cu" "B.Cu")
		(net "P3V3")
	)
	(via
		(at 432.872642 -53.900578)
		(size 0.508)
		(drill 0.254)
		(layers "F.Cu" "B.Cu")
		(net "P3V3")
	)
	(via
		(at 35.596068 -353.70643)
		(size 0.508)
		(drill 0.254)
		(layers "F.Cu" "B.Cu")
		(net "P3V3")
	)
	(segment
		(start 263.901428 -376.615452)
		(end 270.881348 -383.595372)
		(width 0.508)
		(layer "B.Cu")
		(net "P3V3")
	)
	(segment
		(start 226.914456 -117.560598)
		(end 228.114098 -117.560598)
		(width 0.381)
		(layer "B.Cu")
		(net "P3V3")
	)
	(segment
		(start 88.401398 -184.4167)
		(end 88.401398 -185.09869)
		(width 0.381)
		(layer "B.Cu")
		(net "P3V3")
	)
	(segment
		(start 408.906218 -362.223304)
		(end 410.191458 -362.223304)
		(width 0.508)
		(layer "B.Cu")
		(net "P3V3")
	)
	(segment
		(start 226.671124 -128.74625)
		(end 226.108768 -128.74625)
		(width 0.381)
		(layer "B.Cu")
		(net "P3V3")
	)
	(segment
		(start 192.475612 -126.405132)
		(end 192.984628 -126.405132)
		(width 0.381)
		(layer "B.Cu")
		(net "P3V3")
	)
	(segment
		(start 245.948708 -128.743964)
		(end 244.944138 -128.743964)
		(width 0.381)
		(layer "B.Cu")
		(net "P3V3")
	)
	(segment
		(start 365.197898 -180.08727)
		(end 363.257338 -180.08727)
		(width 0.508)
		(layer "B.Cu")
		(net "P3V3")
	)
	(segment
		(start 192.187068 -126.116588)
		(end 192.475612 -126.405132)
		(width 0.381)
		(layer "B.Cu")
		(net "P3V3")
	)
	(segment
		(start 427.289976 -144.70507)
		(end 426.585634 -144.000728)
		(width 0.508)
		(layer "B.Cu")
		(net "P3V3")
	)
	(segment
		(start 363.257338 -180.08727)
		(end 362.457238 -180.88737)
		(width 0.508)
		(layer "B.Cu")
		(net "P3V3")
	)
	(segment
		(start 226.59467 -119.258334)
		(end 225.818954 -118.482618)
		(width 0.381)
		(layer "B.Cu")
		(net "P3V3")
	)
	(segment
		(start 53.42128 -170.811698)
		(end 53.14188 -171.091098)
		(width 0.381)
		(layer "B.Cu")
		(net "P3V3")
	)
	(segment
		(start 426.585634 -144.000728)
		(end 416.204654 -144.000728)
		(width 0.508)
		(layer "B.Cu")
		(net "P3V3")
	)
	(segment
		(start 414.444434 -142.240508)
		(end 407.15692 -142.240508)
		(width 0.508)
		(layer "B.Cu")
		(net "P3V3")
	)
	(segment
		(start 226.59467 -119.797322)
		(end 226.59467 -119.258334)
		(width 0.381)
		(layer "B.Cu")
		(net "P3V3")
	)
	(segment
		(start 365.829088 -180.71846)
		(end 365.197898 -180.08727)
		(width 0.508)
		(layer "B.Cu")
		(net "P3V3")
	)
	(segment
		(start 408.43454 -342.064086)
		(end 408.43454 -361.751626)
		(width 0.508)
		(layer "B.Cu")
		(net "P3V3")
	)
	(segment
		(start 238.242856 -125.45187)
		(end 238.242856 -125.400054)
		(width 0.381)
		(layer "B.Cu")
		(net "P3V3")
	)
	(segment
		(start 90.061288 -179.31511)
		(end 91.55938 -179.31511)
		(width 0.381)
		(layer "B.Cu")
		(net "P3V3")
	)
	(segment
		(start 365.829088 -180.99405)
		(end 365.829088 -180.71846)
		(width 0.508)
		(layer "B.Cu")
		(net "P3V3")
	)
	(segment
		(start 362.457238 -182.21706)
		(end 362.336588 -182.33771)
		(width 0.508)
		(layer "B.Cu")
		(net "P3V3")
	)
	(segment
		(start 238.727488 -125.936502)
		(end 238.242856 -125.45187)
		(width 0.381)
		(layer "B.Cu")
		(net "P3V3")
	)
	(segment
		(start 226.108768 -128.74625)
		(end 223.92513 -126.562612)
		(width 0.381)
		(layer "B.Cu")
		(net "P3V3")
	)
	(segment
		(start 324.067424 -344.327988)
		(end 324.067424 -344.956892)
		(width 0.381)
		(layer "B.Cu")
		(net "P3V3")
	)
	(segment
		(start 353.356418 -177.95621)
		(end 357.737918 -182.33771)
		(width 0.508)
		(layer "B.Cu")
		(net "P3V3")
	)
	(segment
		(start 192.98158 -126.40818)
		(end 192.98158 -127.422148)
		(width 0.381)
		(layer "B.Cu")
		(net "P3V3")
	)
	(segment
		(start 436.368698 -144.70507)
		(end 427.289976 -144.70507)
		(width 0.508)
		(layer "B.Cu")
		(net "P3V3")
	)
	(segment
		(start 116.978938 -391.785856)
		(end 117.654578 -392.461496)
		(width 0.508)
		(layer "B.Cu")
		(net "P3V3")
	)
	(segment
		(start 362.457238 -180.88737)
		(end 362.457238 -182.21706)
		(width 0.508)
		(layer "B.Cu")
		(net "P3V3")
	)
	(segment
		(start 348.367858 -177.95621)
		(end 353.356418 -177.95621)
		(width 0.508)
		(layer "B.Cu")
		(net "P3V3")
	)
	(segment
		(start 37.6555 -381.68326)
		(end 104.158288 -381.68326)
		(width 0.508)
		(layer "B.Cu")
		(net "P3V3")
	)
	(segment
		(start 173.26864 -393.20216)
		(end 173.26864 -392.73226)
		(width 0.508)
		(layer "B.Cu")
		(net "P3V3")
	)
	(segment
		(start 114.260884 -391.785856)
		(end 116.978938 -391.785856)
		(width 0.508)
		(layer "B.Cu")
		(net "P3V3")
	)
	(segment
		(start 225.818954 -118.482618)
		(end 225.818954 -116.669312)
		(width 0.381)
		(layer "B.Cu")
		(net "P3V3")
	)
	(segment
		(start 223.92513 -122.466862)
		(end 226.59467 -119.797322)
		(width 0.381)
		(layer "B.Cu")
		(net "P3V3")
	)
	(segment
		(start 225.921062 -116.567204)
		(end 226.914456 -117.560598)
		(width 0.381)
		(layer "B.Cu")
		(net "P3V3")
	)
	(segment
		(start 422.578276 -156.778198)
		(end 421.92448 -156.778198)
		(width 0.381)
		(layer "B.Cu")
		(net "P3V3")
	)
	(segment
		(start 411.075632 -339.422994)
		(end 408.43454 -342.064086)
		(width 0.508)
		(layer "B.Cu")
		(net "P3V3")
	)
	(segment
		(start 53.14188 -171.091098)
		(end 53.14188 -171.141898)
		(width 0.381)
		(layer "B.Cu")
		(net "P3V3")
	)
	(segment
		(start 53.42128 -170.500548)
		(end 53.42128 -170.811698)
		(width 0.381)
		(layer "B.Cu")
		(net "P3V3")
	)
	(segment
		(start 192.984628 -126.405132)
		(end 192.98158 -126.40818)
		(width 0.381)
		(layer "B.Cu")
		(net "P3V3")
	)
	(segment
		(start 223.92513 -126.562612)
		(end 223.92513 -122.466862)
		(width 0.381)
		(layer "B.Cu")
		(net "P3V3")
	)
	(segment
		(start 225.818954 -116.669312)
		(end 225.921062 -116.567204)
		(width 0.381)
		(layer "B.Cu")
		(net "P3V3")
	)
	(segment
		(start 408.43454 -361.751626)
		(end 408.906218 -362.223304)
		(width 0.508)
		(layer "B.Cu")
		(net "P3V3")
	)
	(segment
		(start 37.18306 -382.07696)
		(end 37.2618 -382.07696)
		(width 0.508)
		(layer "B.Cu")
		(net "P3V3")
	)
	(segment
		(start 117.654578 -392.461496)
		(end 117.654578 -393.075922)
		(width 0.508)
		(layer "B.Cu")
		(net "P3V3")
	)
	(segment
		(start 345.162378 -173.040548)
		(end 345.162378 -174.75073)
		(width 0.508)
		(layer "B.Cu")
		(net "P3V3")
	)
	(segment
		(start 189.385448 -376.615452)
		(end 263.901428 -376.615452)
		(width 0.508)
		(layer "B.Cu")
		(net "P3V3")
	)
	(segment
		(start 244.944138 -128.743964)
		(end 244.944138 -129.403348)
		(width 0.381)
		(layer "B.Cu")
		(net "P3V3")
	)
	(segment
		(start 357.737918 -182.33771)
		(end 362.336588 -182.33771)
		(width 0.508)
		(layer "B.Cu")
		(net "P3V3")
	)
	(segment
		(start 245.96217 -128.730502)
		(end 245.948708 -128.743964)
		(width 0.381)
		(layer "B.Cu")
		(net "P3V3")
	)
	(segment
		(start 37.2618 -382.07696)
		(end 37.6555 -381.68326)
		(width 0.508)
		(layer "B.Cu")
		(net "P3V3")
	)
	(segment
		(start 173.26864 -392.73226)
		(end 189.385448 -376.615452)
		(width 0.508)
		(layer "B.Cu")
		(net "P3V3")
	)
	(segment
		(start 345.162378 -174.75073)
		(end 348.367858 -177.95621)
		(width 0.508)
		(layer "B.Cu")
		(net "P3V3")
	)
	(segment
		(start 438.005474 -339.422994)
		(end 411.075632 -339.422994)
		(width 0.508)
		(layer "B.Cu")
		(net "P3V3")
	)
	(segment
		(start 270.881348 -383.595372)
		(end 270.881348 -386.102352)
		(width 0.508)
		(layer "B.Cu")
		(net "P3V3")
	)
	(segment
		(start 104.158288 -381.68326)
		(end 114.260884 -391.785856)
		(width 0.508)
		(layer "B.Cu")
		(net "P3V3")
	)
	(segment
		(start 422.76014 -156.960062)
		(end 422.578276 -156.778198)
		(width 0.381)
		(layer "B.Cu")
		(net "P3V3")
	)
	(segment
		(start 416.204654 -144.000728)
		(end 414.444434 -142.240508)
		(width 0.508)
		(layer "B.Cu")
		(net "P3V3")
	)
	(segment
		(start 117.654578 -394.401802)
		(end 116.931186 -395.125194)
		(width 0.508)
		(layer "In2.Cu")
		(net "P3V3")
	)
	(segment
		(start 117.654578 -393.075922)
		(end 117.654578 -394.401802)
		(width 0.508)
		(layer "In2.Cu")
		(net "P3V3")
	)
	(segment
		(start 116.931186 -396.912592)
		(end 115.24234 -398.601438)
		(width 0.508)
		(layer "In2.Cu")
		(net "P3V3")
	)
	(segment
		(start 84.931504 -151.539956)
		(end 83.54949 -150.157942)
		(width 0.508)
		(layer "In2.Cu")
		(net "P3V3")
	)
	(segment
		(start 91.55938 -179.31511)
		(end 90.91168 -178.66741)
		(width 0.508)
		(layer "In2.Cu")
		(net "P3V3")
	)
	(segment
		(start 88.80094 -176.167796)
		(end 88.80094 -161.121344)
		(width 0.508)
		(layer "In2.Cu")
		(net "P3V3")
	)
	(segment
		(start 83.54949 -147.2692)
		(end 82.552032 -144.861026)
		(width 0.508)
		(layer "In2.Cu")
		(net "P3V3")
	)
	(segment
		(start 91.110308 -180.571394)
		(end 91.110308 -179.764182)
		(width 0.508)
		(layer "In2.Cu")
		(net "P3V3")
	)
	(segment
		(start 88.401398 -183.280304)
		(end 91.110308 -180.571394)
		(width 0.508)
		(layer "In2.Cu")
		(net "P3V3")
	)
	(segment
		(start 146.35988 -361.660948)
		(end 144.94383 -360.244898)
		(width 0.381)
		(layer "In2.Cu")
		(net "P3V3")
	)
	(segment
		(start 116.931186 -395.125194)
		(end 116.931186 -396.912592)
		(width 0.508)
		(layer "In2.Cu")
		(net "P3V3")
	)
	(segment
		(start 83.54949 -150.157942)
		(end 83.54949 -147.2692)
		(width 0.508)
		(layer "In2.Cu")
		(net "P3V3")
	)
	(segment
		(start 88.401398 -185.09869)
		(end 88.401398 -183.280304)
		(width 0.508)
		(layer "In2.Cu")
		(net "P3V3")
	)
	(segment
		(start 115.24234 -398.601438)
		(end 115.24234 -399.722594)
		(width 0.508)
		(layer "In2.Cu")
		(net "P3V3")
	)
	(segment
		(start 144.94383 -360.244898)
		(end 144.94383 -345.784932)
		(width 0.381)
		(layer "In2.Cu")
		(net "P3V3")
	)
	(segment
		(start 90.91168 -178.66741)
		(end 90.91168 -178.278536)
		(width 0.508)
		(layer "In2.Cu")
		(net "P3V3")
	)
	(segment
		(start 76.547218 -136.490202)
		(end 76.547218 -129.756916)
		(width 0.508)
		(layer "In2.Cu")
		(net "P3V3")
	)
	(segment
		(start 81.553304 -143.862298)
		(end 81.553304 -141.496288)
		(width 0.508)
		(layer "In2.Cu")
		(net "P3V3")
	)
	(segment
		(start 81.553304 -141.496288)
		(end 76.547218 -136.490202)
		(width 0.508)
		(layer "In2.Cu")
		(net "P3V3")
	)
	(segment
		(start 90.91168 -178.278536)
		(end 88.80094 -176.167796)
		(width 0.508)
		(layer "In2.Cu")
		(net "P3V3")
	)
	(segment
		(start 84.931504 -157.251908)
		(end 84.931504 -151.539956)
		(width 0.508)
		(layer "In2.Cu")
		(net "P3V3")
	)
	(segment
		(start 115.24234 -399.722594)
		(end 113.875312 -401.089622)
		(width 0.508)
		(layer "In2.Cu")
		(net "P3V3")
	)
	(segment
		(start 91.110308 -179.764182)
		(end 91.55938 -179.31511)
		(width 0.508)
		(layer "In2.Cu")
		(net "P3V3")
	)
	(segment
		(start 113.875312 -401.089622)
		(end 113.875312 -401.948904)
		(width 0.508)
		(layer "In2.Cu")
		(net "P3V3")
	)
	(segment
		(start 82.552032 -144.861026)
		(end 81.553304 -143.862298)
		(width 0.508)
		(layer "In2.Cu")
		(net "P3V3")
	)
	(segment
		(start 76.547218 -129.756916)
		(end 75.841098 -129.050796)
		(width 0.508)
		(layer "In2.Cu")
		(net "P3V3")
	)
	(segment
		(start 88.80094 -161.121344)
		(end 84.931504 -157.251908)
		(width 0.508)
		(layer "In2.Cu")
		(net "P3V3")
	)
	(segment
		(start 53.42128 -171.079668)
		(end 53.42128 -170.500548)
		(width 0.381)
		(layer "In4.Cu")
		(net "P3V3")
	)
	(segment
		(start 114.547142 -408.889454)
		(end 114.547142 -402.620734)
		(width 0.508)
		(layer "In4.Cu")
		(net "P3V3")
	)
	(segment
		(start 53.086 -171.414948)
		(end 53.42128 -171.079668)
		(width 0.381)
		(layer "In4.Cu")
		(net "P3V3")
	)
	(segment
		(start 23.24354 -137.034778)
		(end 36.65474 -150.445978)
		(width 0.381)
		(layer "In4.Cu")
		(net "P3V3")
	)
	(segment
		(start 36.65474 -150.445978)
		(end 36.65474 -157.281118)
		(width 0.381)
		(layer "In4.Cu")
		(net "P3V3")
	)
	(segment
		(start 118.052342 -412.17469)
		(end 115.95354 -410.075888)
		(width 0.508)
		(layer "In4.Cu")
		(net "P3V3")
	)
	(segment
		(start 170.84802 -391.0584)
		(end 170.84802 -369.811046)
		(width 0.508)
		(layer "In4.Cu")
		(net "P3V3")
	)
	(segment
		(start 35.765486 -158.170372)
		(end 35.765486 -170.802046)
		(width 0.381)
		(layer "In4.Cu")
		(net "P3V3")
	)
	(segment
		(start 115.733576 -410.075888)
		(end 114.547142 -408.889454)
		(width 0.508)
		(layer "In4.Cu")
		(net "P3V3")
	)
	(segment
		(start 36.65474 -157.281118)
		(end 35.765486 -158.170372)
		(width 0.381)
		(layer "In4.Cu")
		(net "P3V3")
	)
	(segment
		(start 170.84802 -369.811046)
		(end 168.08196 -367.044986)
		(width 0.508)
		(layer "In4.Cu")
		(net "P3V3")
	)
	(segment
		(start 166.790878 -358.942386)
		(end 166.790878 -354.103686)
		(width 0.508)
		(layer "In4.Cu")
		(net "P3V3")
	)
	(segment
		(start 50.603404 -173.237144)
		(end 52.4256 -171.414948)
		(width 0.381)
		(layer "In4.Cu")
		(net "P3V3")
	)
	(segment
		(start 39.855648 -174.892208)
		(end 45.569886 -174.892208)
		(width 0.381)
		(layer "In4.Cu")
		(net "P3V3")
	)
	(segment
		(start 114.547142 -402.620734)
		(end 113.875312 -401.948904)
		(width 0.508)
		(layer "In4.Cu")
		(net "P3V3")
	)
	(segment
		(start 146.35988 -366.691418)
		(end 145.528284 -368.699034)
		(width 0.508)
		(layer "In4.Cu")
		(net "P3V3")
	)
	(segment
		(start 45.569886 -174.892208)
		(end 47.22495 -173.237144)
		(width 0.381)
		(layer "In4.Cu")
		(net "P3V3")
	)
	(segment
		(start 119.130826 -391.599674)
		(end 117.654578 -393.075922)
		(width 0.508)
		(layer "In4.Cu")
		(net "P3V3")
	)
	(segment
		(start 145.528284 -368.699034)
		(end 122.627644 -391.599674)
		(width 0.508)
		(layer "In4.Cu")
		(net "P3V3")
	)
	(segment
		(start 115.95354 -410.075888)
		(end 115.733576 -410.075888)
		(width 0.508)
		(layer "In4.Cu")
		(net "P3V3")
	)
	(segment
		(start 173.26864 -393.20216)
		(end 172.99178 -393.20216)
		(width 0.508)
		(layer "In4.Cu")
		(net "P3V3")
	)
	(segment
		(start 172.99178 -393.20216)
		(end 170.84802 -391.0584)
		(width 0.508)
		(layer "In4.Cu")
		(net "P3V3")
	)
	(segment
		(start 26.142442 -123.902978)
		(end 23.24354 -126.80188)
		(width 0.381)
		(layer "In4.Cu")
		(net "P3V3")
	)
	(segment
		(start 166.34714 -353.659948)
		(end 166.03726 -353.659948)
		(width 0.508)
		(layer "In4.Cu")
		(net "P3V3")
	)
	(segment
		(start 146.35988 -361.660948)
		(end 146.35988 -366.691418)
		(width 0.508)
		(layer "In4.Cu")
		(net "P3V3")
	)
	(segment
		(start 47.22495 -173.237144)
		(end 50.603404 -173.237144)
		(width 0.381)
		(layer "In4.Cu")
		(net "P3V3")
	)
	(segment
		(start 166.790878 -354.103686)
		(end 166.34714 -353.659948)
		(width 0.508)
		(layer "In4.Cu")
		(net "P3V3")
	)
	(segment
		(start 122.627644 -391.599674)
		(end 119.130826 -391.599674)
		(width 0.508)
		(layer "In4.Cu")
		(net "P3V3")
	)
	(segment
		(start 168.08196 -367.044986)
		(end 168.08196 -360.233468)
		(width 0.508)
		(layer "In4.Cu")
		(net "P3V3")
	)
	(segment
		(start 168.08196 -360.233468)
		(end 166.790878 -358.942386)
		(width 0.508)
		(layer "In4.Cu")
		(net "P3V3")
	)
	(segment
		(start 27.284426 -123.902978)
		(end 26.142442 -123.902978)
		(width 0.381)
		(layer "In4.Cu")
		(net "P3V3")
	)
	(segment
		(start 23.24354 -126.80188)
		(end 23.24354 -137.034778)
		(width 0.381)
		(layer "In4.Cu")
		(net "P3V3")
	)
	(segment
		(start 119.94134 -412.17469)
		(end 118.052342 -412.17469)
		(width 0.508)
		(layer "In4.Cu")
		(net "P3V3")
	)
	(segment
		(start 35.765486 -170.802046)
		(end 39.855648 -174.892208)
		(width 0.381)
		(layer "In4.Cu")
		(net "P3V3")
	)
	(segment
		(start 52.4256 -171.414948)
		(end 53.086 -171.414948)
		(width 0.381)
		(layer "In4.Cu")
		(net "P3V3")
	)
	(segment
		(start 283.426662 -358.825546)
		(end 283.426662 -362.290868)
		(width 0.381)
		(layer "In6.Cu")
		(net "P3V3")
	)
	(segment
		(start 415.58972 -146.624548)
		(end 411.20568 -142.240508)
		(width 0.381)
		(layer "In6.Cu")
		(net "P3V3")
	)
	(segment
		(start 424.18762 -154.991308)
		(end 426.8978 -152.281128)
		(width 0.381)
		(layer "In6.Cu")
		(net "P3V3")
	)
	(segment
		(start 119.271034 -394.549884)
		(end 121.558558 -396.837408)
		(width 0.508)
		(layer "In6.Cu")
		(net "P3V3")
	)
	(segment
		(start 117.654578 -393.075922)
		(end 117.654578 -393.275566)
		(width 0.508)
		(layer "In6.Cu")
		(net "P3V3")
	)
	(segment
		(start 422.76014 -156.960062)
		(end 422.76014 -156.014928)
		(width 0.381)
		(layer "In6.Cu")
		(net "P3V3")
	)
	(segment
		(start 411.20568 -142.240508)
		(end 407.15692 -142.240508)
		(width 0.381)
		(layer "In6.Cu")
		(net "P3V3")
	)
	(segment
		(start 424.587924 -392.737848)
		(end 423.88155 -393.444222)
		(width 0.508)
		(layer "In6.Cu")
		(net "P3V3")
	)
	(segment
		(start 423.88155 -393.444222)
		(end 423.236898 -393.444222)
		(width 0.508)
		(layer "In6.Cu")
		(net "P3V3")
	)
	(segment
		(start 425.4754 -146.624548)
		(end 415.58972 -146.624548)
		(width 0.381)
		(layer "In6.Cu")
		(net "P3V3")
	)
	(segment
		(start 426.39996 -393.16787)
		(end 425.969938 -392.737848)
		(width 0.508)
		(layer "In6.Cu")
		(net "P3V3")
	)
	(segment
		(start 368.879882 -396.20825)
		(end 366.453674 -396.20825)
		(width 0.508)
		(layer "In6.Cu")
		(net "P3V3")
	)
	(segment
		(start 426.8978 -152.281128)
		(end 426.8978 -148.046948)
		(width 0.381)
		(layer "In6.Cu")
		(net "P3V3")
	)
	(segment
		(start 421.117776 -395.563344)
		(end 369.524788 -395.563344)
		(width 0.508)
		(layer "In6.Cu")
		(net "P3V3")
	)
	(segment
		(start 300.63948 -390.432798)
		(end 300.63948 -386.93852)
		(width 0.508)
		(layer "In6.Cu")
		(net "P3V3")
	)
	(segment
		(start 121.558558 -396.837408)
		(end 168.5163 -396.837408)
		(width 0.508)
		(layer "In6.Cu")
		(net "P3V3")
	)
	(segment
		(start 436.810658 -373.910352)
		(end 431.528474 -379.192536)
		(width 0.508)
		(layer "In6.Cu")
		(net "P3V3")
	)
	(segment
		(start 171.35856 -393.29614)
		(end 173.17466 -393.29614)
		(width 0.508)
		(layer "In6.Cu")
		(net "P3V3")
	)
	(segment
		(start 431.528474 -379.192536)
		(end 431.528474 -391.755122)
		(width 0.508)
		(layer "In6.Cu")
		(net "P3V3")
	)
	(segment
		(start 423.236898 -393.444222)
		(end 421.117776 -395.563344)
		(width 0.508)
		(layer "In6.Cu")
		(net "P3V3")
	)
	(segment
		(start 431.528474 -391.755122)
		(end 430.115726 -393.16787)
		(width 0.508)
		(layer "In6.Cu")
		(net "P3V3")
	)
	(segment
		(start 422.76014 -156.014928)
		(end 423.78376 -154.991308)
		(width 0.381)
		(layer "In6.Cu")
		(net "P3V3")
	)
	(segment
		(start 304.305208 -357.538528)
		(end 284.71368 -357.538528)
		(width 0.381)
		(layer "In6.Cu")
		(net "P3V3")
	)
	(segment
		(start 301.455328 -391.248646)
		(end 300.63948 -390.432798)
		(width 0.508)
		(layer "In6.Cu")
		(net "P3V3")
	)
	(segment
		(start 169.13352 -396.220188)
		(end 169.13352 -395.892528)
		(width 0.508)
		(layer "In6.Cu")
		(net "P3V3")
	)
	(segment
		(start 169.6466 -395.379448)
		(end 169.6466 -395.0081)
		(width 0.508)
		(layer "In6.Cu")
		(net "P3V3")
	)
	(segment
		(start 423.78376 -154.991308)
		(end 424.18762 -154.991308)
		(width 0.381)
		(layer "In6.Cu")
		(net "P3V3")
	)
	(segment
		(start 169.6466 -395.0081)
		(end 171.35856 -393.29614)
		(width 0.508)
		(layer "In6.Cu")
		(net "P3V3")
	)
	(segment
		(start 118.928896 -394.549884)
		(end 119.271034 -394.549884)
		(width 0.508)
		(layer "In6.Cu")
		(net "P3V3")
	)
	(segment
		(start 366.453674 -396.20825)
		(end 364.301786 -394.056362)
		(width 0.508)
		(layer "In6.Cu")
		(net "P3V3")
	)
	(segment
		(start 173.17466 -393.29614)
		(end 173.26864 -393.20216)
		(width 0.508)
		(layer "In6.Cu")
		(net "P3V3")
	)
	(segment
		(start 297.715432 -384.014472)
		(end 279.339294 -384.014472)
		(width 0.508)
		(layer "In6.Cu")
		(net "P3V3")
	)
	(segment
		(start 425.969938 -392.737848)
		(end 424.587924 -392.737848)
		(width 0.508)
		(layer "In6.Cu")
		(net "P3V3")
	)
	(segment
		(start 279.339294 -384.014472)
		(end 277.251414 -386.102352)
		(width 0.508)
		(layer "In6.Cu")
		(net "P3V3")
	)
	(segment
		(start 352.40341 -392.108436)
		(end 303.820068 -392.108436)
		(width 0.508)
		(layer "In6.Cu")
		(net "P3V3")
	)
	(segment
		(start 284.71368 -357.538528)
		(end 283.426662 -358.825546)
		(width 0.381)
		(layer "In6.Cu")
		(net "P3V3")
	)
	(segment
		(start 302.960278 -391.248646)
		(end 301.455328 -391.248646)
		(width 0.508)
		(layer "In6.Cu")
		(net "P3V3")
	)
	(segment
		(start 303.820068 -392.108436)
		(end 302.960278 -391.248646)
		(width 0.508)
		(layer "In6.Cu")
		(net "P3V3")
	)
	(segment
		(start 354.351336 -394.056362)
		(end 352.40341 -392.108436)
		(width 0.508)
		(layer "In6.Cu")
		(net "P3V3")
	)
	(segment
		(start 168.5163 -396.837408)
		(end 169.13352 -396.220188)
		(width 0.508)
		(layer "In6.Cu")
		(net "P3V3")
	)
	(segment
		(start 426.8978 -148.046948)
		(end 425.4754 -146.624548)
		(width 0.381)
		(layer "In6.Cu")
		(net "P3V3")
	)
	(segment
		(start 315.44387 -346.399866)
		(end 304.305208 -357.538528)
		(width 0.381)
		(layer "In6.Cu")
		(net "P3V3")
	)
	(segment
		(start 323.004942 -346.399866)
		(end 315.44387 -346.399866)
		(width 0.381)
		(layer "In6.Cu")
		(net "P3V3")
	)
	(segment
		(start 369.524788 -395.563344)
		(end 368.879882 -396.20825)
		(width 0.508)
		(layer "In6.Cu")
		(net "P3V3")
	)
	(segment
		(start 277.251414 -386.102352)
		(end 270.881348 -386.102352)
		(width 0.508)
		(layer "In6.Cu")
		(net "P3V3")
	)
	(segment
		(start 324.067424 -345.337384)
		(end 323.004942 -346.399866)
		(width 0.381)
		(layer "In6.Cu")
		(net "P3V3")
	)
	(segment
		(start 117.654578 -393.275566)
		(end 118.928896 -394.549884)
		(width 0.508)
		(layer "In6.Cu")
		(net "P3V3")
	)
	(segment
		(start 300.63948 -386.93852)
		(end 297.715432 -384.014472)
		(width 0.508)
		(layer "In6.Cu")
		(net "P3V3")
	)
	(segment
		(start 169.13352 -395.892528)
		(end 169.6466 -395.379448)
		(width 0.508)
		(layer "In6.Cu")
		(net "P3V3")
	)
	(segment
		(start 324.067424 -344.956892)
		(end 324.067424 -345.337384)
		(width 0.381)
		(layer "In6.Cu")
		(net "P3V3")
	)
	(segment
		(start 430.115726 -393.16787)
		(end 426.39996 -393.16787)
		(width 0.508)
		(layer "In6.Cu")
		(net "P3V3")
	)
	(segment
		(start 364.301786 -394.056362)
		(end 354.351336 -394.056362)
		(width 0.508)
		(layer "In6.Cu")
		(net "P3V3")
	)
	(segment
		(start 281.038808 -364.678722)
		(end 283.426662 -362.290868)
		(width 0.381)
		(layer "In11.Cu")
		(net "P3V3")
	)
	(segment
		(start 228.469444 -116.567204)
		(end 225.921062 -116.567204)
		(width 0.381)
		(layer "In11.Cu")
		(net "P3V3")
	)
	(segment
		(start 281.038808 -373.707406)
		(end 281.038808 -364.678722)
		(width 0.381)
		(layer "In11.Cu")
		(net "P3V3")
	)
	(segment
		(start 270.850614 -386.071618)
		(end 270.850614 -383.8956)
		(width 0.508)
		(layer "In11.Cu")
		(net "P3V3")
	)
	(segment
		(start 270.881348 -386.102352)
		(end 270.850614 -386.071618)
		(width 0.508)
		(layer "In11.Cu")
		(net "P3V3")
	)
	(segment
		(start 229.393496 -117.491256)
		(end 228.469444 -116.567204)
		(width 0.381)
		(layer "In11.Cu")
		(net "P3V3")
	)
	(segment
		(start 229.393496 -119.582438)
		(end 229.393496 -117.491256)
		(width 0.381)
		(layer "In11.Cu")
		(net "P3V3")
	)
	(segment
		(start 270.850614 -383.8956)
		(end 281.038808 -373.707406)
		(width 0.508)
		(layer "In11.Cu")
		(net "P3V3")
	)
	(segment
		(start 34.90976 -382.07696)
		(end 34.107374 -381.274574)
		(width 0.508)
		(layer "In13.Cu")
		(net "P3V3")
	)
	(segment
		(start 37.18306 -382.07696)
		(end 34.90976 -382.07696)
		(width 0.508)
		(layer "In13.Cu")
		(net "P3V3")
	)
	(segment
		(start 34.628328 -353.70643)
		(end 35.596068 -353.70643)
		(width 0.508)
		(layer "In13.Cu")
		(net "P3V3")
	)
	(segment
		(start 34.107374 -354.227384)
		(end 34.628328 -353.70643)
		(width 0.508)
		(layer "In13.Cu")
		(net "P3V3")
	)
	(segment
		(start 34.107374 -381.274574)
		(end 34.107374 -354.227384)
		(width 0.508)
		(layer "In13.Cu")
		(net "P3V3")
	)
	(segment
		(start 181.122828 -44.677838)
		(end 180.795168 -45.005498)
		(width 0.13208)
		(layer "F.Cu")
		(net "P3E_PCH_M2_TX_DP<3>")
	)
	(segment
		(start 181.739032 -44.677838)
		(end 181.122828 -44.677838)
		(width 0.13208)
		(layer "F.Cu")
		(net "P3E_PCH_M2_TX_DP<3>")
	)
	(segment
		(start 182.041292 -44.980098)
		(end 181.739032 -44.677838)
		(width 0.13208)
		(layer "F.Cu")
		(net "P3E_PCH_M2_TX_DP<3>")
	)
	(segment
		(start 343.006172 -44.689268)
		(end 343.005156 -44.691046)
		(width 0.13208)
		(layer "F.Cu")
		(net "P3E_PCH_M2_TX_DP<3>")
	)
	(segment
		(start 342.735154 -44.220892)
		(end 343.006172 -44.689268)
		(width 0.13208)
		(layer "F.Cu")
		(net "P3E_PCH_M2_TX_DP<3>")
	)
	(segment
		(start 343.868756 -43.94708)
		(end 343.873836 -43.93819)
		(width 0.0889)
		(layer "In13.Cu")
		(net "P3E_PCH_M2_TX_DP<3>")
	)
	(segment
		(start 184.049416 -44.815252)
		(end 183.31307 -44.685458)
		(width 0.14732)
		(layer "In13.Cu")
		(net "P3E_PCH_M2_TX_DP<3>")
	)
	(segment
		(start 202.300078 -57.845452)
		(end 184.049416 -44.815252)
		(width 0.14732)
		(layer "In13.Cu")
		(net "P3E_PCH_M2_TX_DP<3>")
	)
	(segment
		(start 347.62948 -26.711148)
		(end 346.33408 -26.711148)
		(width 0.14732)
		(layer "In13.Cu")
		(net "P3E_PCH_M2_TX_DP<3>")
	)
	(segment
		(start 183.31307 -44.685458)
		(end 182.335932 -44.685458)
		(width 0.14732)
		(layer "In13.Cu")
		(net "P3E_PCH_M2_TX_DP<3>")
	)
	(segment
		(start 338.388198 -18.765266)
		(end 337.93176 -18.308828)
		(width 0.14732)
		(layer "In13.Cu")
		(net "P3E_PCH_M2_TX_DP<3>")
	)
	(segment
		(start 343.67597 -24.18969)
		(end 343.496138 -24.009858)
		(width 0.14732)
		(layer "In13.Cu")
		(net "P3E_PCH_M2_TX_DP<3>")
	)
	(segment
		(start 341.40521 -21.91893)
		(end 341.225378 -21.739098)
		(width 0.14732)
		(layer "In13.Cu")
		(net "P3E_PCH_M2_TX_DP<3>")
	)
	(segment
		(start 343.496138 -23.873206)
		(end 342.471502 -22.84857)
		(width 0.14732)
		(layer "In13.Cu")
		(net "P3E_PCH_M2_TX_DP<3>")
	)
	(segment
		(start 348.908878 -28.127198)
		(end 348.908878 -27.990546)
		(width 0.14732)
		(layer "In13.Cu")
		(net "P3E_PCH_M2_TX_DP<3>")
	)
	(segment
		(start 338.704682 -19.08175)
		(end 338.56803 -19.08175)
		(width 0.14732)
		(layer "In13.Cu")
		(net "P3E_PCH_M2_TX_DP<3>")
	)
	(segment
		(start 343.812622 -24.18969)
		(end 343.67597 -24.18969)
		(width 0.14732)
		(layer "In13.Cu")
		(net "P3E_PCH_M2_TX_DP<3>")
	)
	(segment
		(start 349.76308 -30.452568)
		(end 349.66656 -30.356048)
		(width 0.14732)
		(layer "In13.Cu")
		(net "P3E_PCH_M2_TX_DP<3>")
	)
	(segment
		(start 346.432378 -43.698668)
		(end 347.507306 -43.698668)
		(width 0.14732)
		(layer "In13.Cu")
		(net "P3E_PCH_M2_TX_DP<3>")
	)
	(segment
		(start 349.66656 -30.102048)
		(end 349.76308 -30.005528)
		(width 0.14732)
		(layer "In13.Cu")
		(net "P3E_PCH_M2_TX_DP<3>")
	)
	(segment
		(start 297.058842 -22.77618)
		(end 274.215352 -55.400448)
		(width 0.14732)
		(layer "In13.Cu")
		(net "P3E_PCH_M2_TX_DP<3>")
	)
	(segment
		(start 349.76308 -41.442894)
		(end 349.76308 -31.786068)
		(width 0.14732)
		(layer "In13.Cu")
		(net "P3E_PCH_M2_TX_DP<3>")
	)
	(segment
		(start 341.225378 -21.602446)
		(end 340.674452 -21.05152)
		(width 0.14732)
		(layer "In13.Cu")
		(net "P3E_PCH_M2_TX_DP<3>")
	)
	(segment
		(start 327.114154 -17.067022)
		(end 318.136524 -17.067022)
		(width 0.14732)
		(layer "In13.Cu")
		(net "P3E_PCH_M2_TX_DP<3>")
	)
	(segment
		(start 349.225362 -28.30703)
		(end 349.08871 -28.30703)
		(width 0.14732)
		(layer "In13.Cu")
		(net "P3E_PCH_M2_TX_DP<3>")
	)
	(segment
		(start 339.435948 -19.949668)
		(end 339.435948 -19.813016)
		(width 0.14732)
		(layer "In13.Cu")
		(net "P3E_PCH_M2_TX_DP<3>")
	)
	(segment
		(start 342.471502 -22.84857)
		(end 342.33485 -22.84857)
		(width 0.14732)
		(layer "In13.Cu")
		(net "P3E_PCH_M2_TX_DP<3>")
	)
	(segment
		(start 339.435948 -19.813016)
		(end 338.704682 -19.08175)
		(width 0.14732)
		(layer "In13.Cu")
		(net "P3E_PCH_M2_TX_DP<3>")
	)
	(segment
		(start 243.912898 -63.147956)
		(end 235.137452 -63.63589)
		(width 0.14732)
		(layer "In13.Cu")
		(net "P3E_PCH_M2_TX_DP<3>")
	)
	(segment
		(start 348.387162 -27.46883)
		(end 348.25051 -27.46883)
		(width 0.14732)
		(layer "In13.Cu")
		(net "P3E_PCH_M2_TX_DP<3>")
	)
	(segment
		(start 182.335932 -44.685458)
		(end 182.041292 -44.980098)
		(width 0.14732)
		(layer "In13.Cu")
		(net "P3E_PCH_M2_TX_DP<3>")
	)
	(segment
		(start 336.50301 -18.453608)
		(end 336.35823 -18.308828)
		(width 0.14732)
		(layer "In13.Cu")
		(net "P3E_PCH_M2_TX_DP<3>")
	)
	(segment
		(start 340.5378 -21.05152)
		(end 340.357968 -20.871688)
		(width 0.14732)
		(layer "In13.Cu")
		(net "P3E_PCH_M2_TX_DP<3>")
	)
	(segment
		(start 343.530936 -44.125642)
		(end 343.549478 -44.125642)
		(width 0.0889)
		(layer "In13.Cu")
		(net "P3E_PCH_M2_TX_DP<3>")
	)
	(segment
		(start 349.76308 -31.786068)
		(end 349.66656 -31.689548)
		(width 0.14732)
		(layer "In13.Cu")
		(net "P3E_PCH_M2_TX_DP<3>")
	)
	(segment
		(start 337.01609 -18.308828)
		(end 336.87131 -18.453608)
		(width 0.14732)
		(layer "In13.Cu")
		(net "P3E_PCH_M2_TX_DP<3>")
	)
	(segment
		(start 336.87131 -18.453608)
		(end 336.50301 -18.453608)
		(width 0.14732)
		(layer "In13.Cu")
		(net "P3E_PCH_M2_TX_DP<3>")
	)
	(segment
		(start 348.070678 -27.288998)
		(end 348.070678 -27.152346)
		(width 0.14732)
		(layer "In13.Cu")
		(net "P3E_PCH_M2_TX_DP<3>")
	)
	(segment
		(start 341.541862 -21.91893)
		(end 341.40521 -21.91893)
		(width 0.14732)
		(layer "In13.Cu")
		(net "P3E_PCH_M2_TX_DP<3>")
	)
	(segment
		(start 342.735154 -44.220892)
		(end 342.735154 -44.536614)
		(width 0.0889)
		(layer "In13.Cu")
		(net "P3E_PCH_M2_TX_DP<3>")
	)
	(segment
		(start 343.496138 -24.009858)
		(end 343.496138 -23.873206)
		(width 0.14732)
		(layer "In13.Cu")
		(net "P3E_PCH_M2_TX_DP<3>")
	)
	(segment
		(start 336.35823 -18.308828)
		(end 335.38922 -18.308828)
		(width 0.14732)
		(layer "In13.Cu")
		(net "P3E_PCH_M2_TX_DP<3>")
	)
	(segment
		(start 327.70826 -17.661128)
		(end 327.114154 -17.067022)
		(width 0.14732)
		(layer "In13.Cu")
		(net "P3E_PCH_M2_TX_DP<3>")
	)
	(segment
		(start 349.66656 -31.689548)
		(end 349.66656 -31.435548)
		(width 0.14732)
		(layer "In13.Cu")
		(net "P3E_PCH_M2_TX_DP<3>")
	)
	(segment
		(start 349.08871 -28.30703)
		(end 348.908878 -28.127198)
		(width 0.14732)
		(layer "In13.Cu")
		(net "P3E_PCH_M2_TX_DP<3>")
	)
	(segment
		(start 330.82484 -18.997168)
		(end 329.4888 -17.661128)
		(width 0.14732)
		(layer "In13.Cu")
		(net "P3E_PCH_M2_TX_DP<3>")
	)
	(segment
		(start 342.155018 -22.532086)
		(end 341.541862 -21.91893)
		(width 0.14732)
		(layer "In13.Cu")
		(net "P3E_PCH_M2_TX_DP<3>")
	)
	(segment
		(start 349.66656 -31.435548)
		(end 349.76308 -31.339028)
		(width 0.14732)
		(layer "In13.Cu")
		(net "P3E_PCH_M2_TX_DP<3>")
	)
	(segment
		(start 339.61578 -20.1295)
		(end 339.435948 -19.949668)
		(width 0.14732)
		(layer "In13.Cu")
		(net "P3E_PCH_M2_TX_DP<3>")
	)
	(segment
		(start 344.363294 -43.655996)
		(end 344.87358 -43.655996)
		(width 0.0889)
		(layer "In13.Cu")
		(net "P3E_PCH_M2_TX_DP<3>")
	)
	(segment
		(start 349.76308 -31.339028)
		(end 349.76308 -30.452568)
		(width 0.14732)
		(layer "In13.Cu")
		(net "P3E_PCH_M2_TX_DP<3>")
	)
	(segment
		(start 346.41028 -43.698668)
		(end 346.432378 -43.698668)
		(width 0.0889)
		(layer "In13.Cu")
		(net "P3E_PCH_M2_TX_DP<3>")
	)
	(segment
		(start 348.070678 -27.152346)
		(end 347.62948 -26.711148)
		(width 0.14732)
		(layer "In13.Cu")
		(net "P3E_PCH_M2_TX_DP<3>")
	)
	(segment
		(start 346.33408 -26.711148)
		(end 343.812622 -24.18969)
		(width 0.14732)
		(layer "In13.Cu")
		(net "P3E_PCH_M2_TX_DP<3>")
	)
	(segment
		(start 334.70088 -18.997168)
		(end 330.82484 -18.997168)
		(width 0.14732)
		(layer "In13.Cu")
		(net "P3E_PCH_M2_TX_DP<3>")
	)
	(segment
		(start 338.388198 -18.901918)
		(end 338.388198 -18.765266)
		(width 0.14732)
		(layer "In13.Cu")
		(net "P3E_PCH_M2_TX_DP<3>")
	)
	(segment
		(start 340.357968 -20.735036)
		(end 339.752432 -20.1295)
		(width 0.14732)
		(layer "In13.Cu")
		(net "P3E_PCH_M2_TX_DP<3>")
	)
	(segment
		(start 349.76308 -28.844748)
		(end 349.225362 -28.30703)
		(width 0.14732)
		(layer "In13.Cu")
		(net "P3E_PCH_M2_TX_DP<3>")
	)
	(segment
		(start 349.76308 -30.005528)
		(end 349.76308 -28.844748)
		(width 0.14732)
		(layer "In13.Cu")
		(net "P3E_PCH_M2_TX_DP<3>")
	)
	(segment
		(start 340.357968 -20.871688)
		(end 340.357968 -20.735036)
		(width 0.14732)
		(layer "In13.Cu")
		(net "P3E_PCH_M2_TX_DP<3>")
	)
	(segment
		(start 337.93176 -18.308828)
		(end 337.01609 -18.308828)
		(width 0.14732)
		(layer "In13.Cu")
		(net "P3E_PCH_M2_TX_DP<3>")
	)
	(segment
		(start 344.958416 -43.740832)
		(end 346.368116 -43.740832)
		(width 0.0889)
		(layer "In13.Cu")
		(net "P3E_PCH_M2_TX_DP<3>")
	)
	(segment
		(start 339.752432 -20.1295)
		(end 339.61578 -20.1295)
		(width 0.14732)
		(layer "In13.Cu")
		(net "P3E_PCH_M2_TX_DP<3>")
	)
	(segment
		(start 348.908878 -27.990546)
		(end 348.387162 -27.46883)
		(width 0.14732)
		(layer "In13.Cu")
		(net "P3E_PCH_M2_TX_DP<3>")
	)
	(segment
		(start 298.115228 -22.036278)
		(end 297.058842 -22.77618)
		(width 0.14732)
		(layer "In13.Cu")
		(net "P3E_PCH_M2_TX_DP<3>")
	)
	(segment
		(start 235.137452 -63.63589)
		(end 202.300078 -57.845452)
		(width 0.14732)
		(layer "In13.Cu")
		(net "P3E_PCH_M2_TX_DP<3>")
	)
	(segment
		(start 346.368116 -43.740832)
		(end 346.41028 -43.698668)
		(width 0.0889)
		(layer "In13.Cu")
		(net "P3E_PCH_M2_TX_DP<3>")
	)
	(segment
		(start 344.87358 -43.655996)
		(end 344.958416 -43.740832)
		(width 0.0889)
		(layer "In13.Cu")
		(net "P3E_PCH_M2_TX_DP<3>")
	)
	(segment
		(start 342.735154 -44.536614)
		(end 342.790018 -44.591478)
		(width 0.0889)
		(layer "In13.Cu")
		(net "P3E_PCH_M2_TX_DP<3>")
	)
	(segment
		(start 349.66656 -30.356048)
		(end 349.66656 -30.102048)
		(width 0.14732)
		(layer "In13.Cu")
		(net "P3E_PCH_M2_TX_DP<3>")
	)
	(segment
		(start 318.136524 -17.067022)
		(end 298.115228 -22.036278)
		(width 0.14732)
		(layer "In13.Cu")
		(net "P3E_PCH_M2_TX_DP<3>")
	)
	(segment
		(start 274.215352 -55.400448)
		(end 269.62735 -58.61304)
		(width 0.14732)
		(layer "In13.Cu")
		(net "P3E_PCH_M2_TX_DP<3>")
	)
	(segment
		(start 338.56803 -19.08175)
		(end 338.388198 -18.901918)
		(width 0.14732)
		(layer "In13.Cu")
		(net "P3E_PCH_M2_TX_DP<3>")
	)
	(segment
		(start 340.674452 -21.05152)
		(end 340.5378 -21.05152)
		(width 0.14732)
		(layer "In13.Cu")
		(net "P3E_PCH_M2_TX_DP<3>")
	)
	(segment
		(start 341.225378 -21.739098)
		(end 341.225378 -21.602446)
		(width 0.14732)
		(layer "In13.Cu")
		(net "P3E_PCH_M2_TX_DP<3>")
	)
	(segment
		(start 335.38922 -18.308828)
		(end 334.70088 -18.997168)
		(width 0.14732)
		(layer "In13.Cu")
		(net "P3E_PCH_M2_TX_DP<3>")
	)
	(segment
		(start 347.507306 -43.698668)
		(end 349.76308 -41.442894)
		(width 0.14732)
		(layer "In13.Cu")
		(net "P3E_PCH_M2_TX_DP<3>")
	)
	(segment
		(start 329.4888 -17.661128)
		(end 327.70826 -17.661128)
		(width 0.14732)
		(layer "In13.Cu")
		(net "P3E_PCH_M2_TX_DP<3>")
	)
	(segment
		(start 348.25051 -27.46883)
		(end 348.070678 -27.288998)
		(width 0.14732)
		(layer "In13.Cu")
		(net "P3E_PCH_M2_TX_DP<3>")
	)
	(segment
		(start 269.62735 -58.61304)
		(end 243.912898 -63.147956)
		(width 0.14732)
		(layer "In13.Cu")
		(net "P3E_PCH_M2_TX_DP<3>")
	)
	(segment
		(start 342.33485 -22.84857)
		(end 342.155018 -22.668738)
		(width 0.14732)
		(layer "In13.Cu")
		(net "P3E_PCH_M2_TX_DP<3>")
	)
	(segment
		(start 342.155018 -22.668738)
		(end 342.155018 -22.532086)
		(width 0.14732)
		(layer "In13.Cu")
		(net "P3E_PCH_M2_TX_DP<3>")
	)
	(arc
		(start 342.790018 -44.591478)
		(mid 342.94586 -44.530645)
		(end 343.059766 -44.40809)
		(width 0.0889)
		(layer "In13.Cu")
		(net "P3E_PCH_M2_TX_DP<3>")
	)
	(arc
		(start 343.059766 -44.40809)
		(mid 343.258747 -44.205804)
		(end 343.530936 -44.125642)
		(width 0.0889)
		(layer "In13.Cu")
		(net "P3E_PCH_M2_TX_DP<3>")
	)
	(arc
		(start 343.881964 -43.924982)
		(mid 344.087599 -43.727806)
		(end 344.363294 -43.655996)
		(width 0.0889)
		(layer "In13.Cu")
		(net "P3E_PCH_M2_TX_DP<3>")
	)
	(arc
		(start 343.873836 -43.93819)
		(mid 343.877856 -43.931559)
		(end 343.881964 -43.924982)
		(width 0.0889)
		(layer "In13.Cu")
		(net "P3E_PCH_M2_TX_DP<3>")
	)
	(arc
		(start 343.549478 -44.125642)
		(mid 343.732378 -44.077963)
		(end 343.868756 -43.94708)
		(width 0.0889)
		(layer "In13.Cu")
		(net "P3E_PCH_M2_TX_DP<3>")
	)
	(segment
		(start 181.124098 -47.724568)
		(end 180.795168 -48.053498)
		(width 0.13208)
		(layer "F.Cu")
		(net "P3E_PCH_M2_TX_DP<2>")
	)
	(segment
		(start 182.041292 -48.028098)
		(end 181.737762 -47.724568)
		(width 0.13208)
		(layer "F.Cu")
		(net "P3E_PCH_M2_TX_DP<2>")
	)
	(segment
		(start 344.363548 -42.341292)
		(end 344.540586 -42.649648)
		(width 0.13208)
		(layer "F.Cu")
		(net "P3E_PCH_M2_TX_DP<2>")
	)
	(segment
		(start 344.540586 -42.649648)
		(end 344.63355 -42.811446)
		(width 0.13208)
		(layer "F.Cu")
		(net "P3E_PCH_M2_TX_DP<2>")
	)
	(segment
		(start 181.737762 -47.724568)
		(end 181.124098 -47.724568)
		(width 0.13208)
		(layer "F.Cu")
		(net "P3E_PCH_M2_TX_DP<2>")
	)
	(segment
		(start 298.575476 -23.047452)
		(end 297.564302 -23.755858)
		(width 0.14732)
		(layer "In13.Cu")
		(net "P3E_PCH_M2_TX_DP<2>")
	)
	(segment
		(start 348.57436 -38.384988)
		(end 348.67088 -38.288468)
		(width 0.14732)
		(layer "In13.Cu")
		(net "P3E_PCH_M2_TX_DP<2>")
	)
	(segment
		(start 345.302332 -27.178)
		(end 345.16568 -27.178)
		(width 0.14732)
		(layer "In13.Cu")
		(net "P3E_PCH_M2_TX_DP<2>")
	)
	(segment
		(start 342.47328 -24.348948)
		(end 341.10168 -24.348948)
		(width 0.14732)
		(layer "In13.Cu")
		(net "P3E_PCH_M2_TX_DP<2>")
	)
	(segment
		(start 348.67088 -38.288468)
		(end 348.67088 -37.513768)
		(width 0.14732)
		(layer "In13.Cu")
		(net "P3E_PCH_M2_TX_DP<2>")
	)
	(segment
		(start 318.924178 -17.996662)
		(end 298.575476 -23.047452)
		(width 0.14732)
		(layer "In13.Cu")
		(net "P3E_PCH_M2_TX_DP<2>")
	)
	(segment
		(start 274.720304 -56.380634)
		(end 270.055594 -59.647074)
		(width 0.14732)
		(layer "In13.Cu")
		(net "P3E_PCH_M2_TX_DP<2>")
	)
	(segment
		(start 345.90736 -29.665168)
		(end 346.00388 -29.568648)
		(width 0.14732)
		(layer "In13.Cu")
		(net "P3E_PCH_M2_TX_DP<2>")
	)
	(segment
		(start 337.64728 -20.894548)
		(end 336.405982 -20.894548)
		(width 0.14732)
		(layer "In13.Cu")
		(net "P3E_PCH_M2_TX_DP<2>")
	)
	(segment
		(start 347.763338 -35.303206)
		(end 347.148912 -34.68878)
		(width 0.14732)
		(layer "In13.Cu")
		(net "P3E_PCH_M2_TX_DP<2>")
	)
	(segment
		(start 347.96349 -41.333166)
		(end 348.099888 -41.333166)
		(width 0.14732)
		(layer "In13.Cu")
		(net "P3E_PCH_M2_TX_DP<2>")
	)
	(segment
		(start 183.490362 -47.795434)
		(end 183.13908 -47.733458)
		(width 0.14732)
		(layer "In13.Cu")
		(net "P3E_PCH_M2_TX_DP<2>")
	)
	(segment
		(start 346.432378 -42.717974)
		(end 346.71508 -42.717974)
		(width 0.14732)
		(layer "In13.Cu")
		(net "P3E_PCH_M2_TX_DP<2>")
	)
	(segment
		(start 183.841898 -47.85741)
		(end 183.490362 -47.79518)
		(width 0.14732)
		(layer "In13.Cu")
		(net "P3E_PCH_M2_TX_DP<2>")
	)
	(segment
		(start 348.57436 -37.163248)
		(end 348.67088 -37.066728)
		(width 0.14732)
		(layer "In13.Cu")
		(net "P3E_PCH_M2_TX_DP<2>")
	)
	(segment
		(start 348.67088 -40.762174)
		(end 348.67088 -38.735508)
		(width 0.14732)
		(layer "In13.Cu")
		(net "P3E_PCH_M2_TX_DP<2>")
	)
	(segment
		(start 346.00388 -31.036768)
		(end 345.90736 -30.940248)
		(width 0.14732)
		(layer "In13.Cu")
		(net "P3E_PCH_M2_TX_DP<2>")
	)
	(segment
		(start 347.01226 -34.68878)
		(end 346.832428 -34.508948)
		(width 0.14732)
		(layer "In13.Cu")
		(net "P3E_PCH_M2_TX_DP<2>")
	)
	(segment
		(start 344.357706 -42.715688)
		(end 344.390218 -42.716196)
		(width 0.0889)
		(layer "In13.Cu")
		(net "P3E_PCH_M2_TX_DP<2>")
	)
	(segment
		(start 348.67088 -37.513768)
		(end 348.57436 -37.417248)
		(width 0.14732)
		(layer "In13.Cu")
		(net "P3E_PCH_M2_TX_DP<2>")
	)
	(segment
		(start 327.32218 -18.893028)
		(end 326.425814 -17.996662)
		(width 0.14732)
		(layer "In13.Cu")
		(net "P3E_PCH_M2_TX_DP<2>")
	)
	(segment
		(start 344.390218 -42.716196)
		(end 344.706702 -42.716196)
		(width 0.0889)
		(layer "In13.Cu")
		(net "P3E_PCH_M2_TX_DP<2>")
	)
	(segment
		(start 333.720186 -22.007068)
		(end 332.20406 -22.007068)
		(width 0.14732)
		(layer "In13.Cu")
		(net "P3E_PCH_M2_TX_DP<2>")
	)
	(segment
		(start 341.10168 -24.348948)
		(end 338.897722 -22.14499)
		(width 0.14732)
		(layer "In13.Cu")
		(net "P3E_PCH_M2_TX_DP<2>")
	)
	(segment
		(start 344.60053 -26.61285)
		(end 344.420698 -26.433018)
		(width 0.14732)
		(layer "In13.Cu")
		(net "P3E_PCH_M2_TX_DP<2>")
	)
	(segment
		(start 344.737182 -26.61285)
		(end 344.60053 -26.61285)
		(width 0.14732)
		(layer "In13.Cu")
		(net "P3E_PCH_M2_TX_DP<2>")
	)
	(segment
		(start 183.490362 -47.79518)
		(end 183.490362 -47.795434)
		(width 0.14732)
		(layer "In13.Cu")
		(net "P3E_PCH_M2_TX_DP<2>")
	)
	(segment
		(start 345.90736 -28.679648)
		(end 346.00388 -28.583128)
		(width 0.14732)
		(layer "In13.Cu")
		(net "P3E_PCH_M2_TX_DP<2>")
	)
	(segment
		(start 344.188542 -26.06421)
		(end 344.05189 -26.06421)
		(width 0.14732)
		(layer "In13.Cu")
		(net "P3E_PCH_M2_TX_DP<2>")
	)
	(segment
		(start 346.71508 -42.717974)
		(end 347.783658 -41.649396)
		(width 0.14732)
		(layer "In13.Cu")
		(net "P3E_PCH_M2_TX_DP<2>")
	)
	(segment
		(start 344.05189 -26.06421)
		(end 343.872058 -25.884378)
		(width 0.14732)
		(layer "In13.Cu")
		(net "P3E_PCH_M2_TX_DP<2>")
	)
	(segment
		(start 345.16568 -27.178)
		(end 344.985848 -26.998168)
		(width 0.14732)
		(layer "In13.Cu")
		(net "P3E_PCH_M2_TX_DP<2>")
	)
	(segment
		(start 342.83269 -24.844756)
		(end 342.652858 -24.664924)
		(width 0.14732)
		(layer "In13.Cu")
		(net "P3E_PCH_M2_TX_DP<2>")
	)
	(segment
		(start 346.00388 -27.879548)
		(end 345.302332 -27.178)
		(width 0.14732)
		(layer "In13.Cu")
		(net "P3E_PCH_M2_TX_DP<2>")
	)
	(segment
		(start 342.969088 -24.844756)
		(end 342.83269 -24.844756)
		(width 0.14732)
		(layer "In13.Cu")
		(net "P3E_PCH_M2_TX_DP<2>")
	)
	(segment
		(start 342.652858 -24.528526)
		(end 342.47328 -24.348948)
		(width 0.14732)
		(layer "In13.Cu")
		(net "P3E_PCH_M2_TX_DP<2>")
	)
	(segment
		(start 348.67088 -37.066728)
		(end 348.67088 -36.210748)
		(width 0.14732)
		(layer "In13.Cu")
		(net "P3E_PCH_M2_TX_DP<2>")
	)
	(segment
		(start 345.90736 -30.940248)
		(end 345.90736 -30.686248)
		(width 0.14732)
		(layer "In13.Cu")
		(net "P3E_PCH_M2_TX_DP<2>")
	)
	(segment
		(start 346.832428 -34.508948)
		(end 346.832428 -34.372296)
		(width 0.14732)
		(layer "In13.Cu")
		(net "P3E_PCH_M2_TX_DP<2>")
	)
	(segment
		(start 348.099888 -41.333166)
		(end 348.67088 -40.762174)
		(width 0.14732)
		(layer "In13.Cu")
		(net "P3E_PCH_M2_TX_DP<2>")
	)
	(segment
		(start 345.90736 -30.686248)
		(end 346.00388 -30.589728)
		(width 0.14732)
		(layer "In13.Cu")
		(net "P3E_PCH_M2_TX_DP<2>")
	)
	(segment
		(start 244.401848 -64.170814)
		(end 235.20146 -64.626998)
		(width 0.14732)
		(layer "In13.Cu")
		(net "P3E_PCH_M2_TX_DP<2>")
	)
	(segment
		(start 270.055594 -59.647074)
		(end 244.401848 -64.170814)
		(width 0.14732)
		(layer "In13.Cu")
		(net "P3E_PCH_M2_TX_DP<2>")
	)
	(segment
		(start 346.00388 -29.030168)
		(end 345.90736 -28.933648)
		(width 0.14732)
		(layer "In13.Cu")
		(net "P3E_PCH_M2_TX_DP<2>")
	)
	(segment
		(start 344.363548 -42.341292)
		(end 344.09253 -42.497756)
		(width 0.0889)
		(layer "In13.Cu")
		(net "P3E_PCH_M2_TX_DP<2>")
	)
	(segment
		(start 192.340484 -53.192426)
		(end 192.34023 -53.192426)
		(width 0.14732)
		(layer "In13.Cu")
		(net "P3E_PCH_M2_TX_DP<2>")
	)
	(segment
		(start 346.00388 -30.589728)
		(end 346.00388 -30.015688)
		(width 0.14732)
		(layer "In13.Cu")
		(net "P3E_PCH_M2_TX_DP<2>")
	)
	(segment
		(start 346.00388 -29.568648)
		(end 346.00388 -29.030168)
		(width 0.14732)
		(layer "In13.Cu")
		(net "P3E_PCH_M2_TX_DP<2>")
	)
	(segment
		(start 344.750644 -42.760138)
		(end 346.368116 -42.760138)
		(width 0.0889)
		(layer "In13.Cu")
		(net "P3E_PCH_M2_TX_DP<2>")
	)
	(segment
		(start 348.67088 -38.735508)
		(end 348.57436 -38.638988)
		(width 0.14732)
		(layer "In13.Cu")
		(net "P3E_PCH_M2_TX_DP<2>")
	)
	(segment
		(start 346.00388 -33.543748)
		(end 346.00388 -31.036768)
		(width 0.14732)
		(layer "In13.Cu")
		(net "P3E_PCH_M2_TX_DP<2>")
	)
	(segment
		(start 326.425814 -17.996662)
		(end 318.924178 -17.996662)
		(width 0.14732)
		(layer "In13.Cu")
		(net "P3E_PCH_M2_TX_DP<2>")
	)
	(segment
		(start 344.985848 -26.861516)
		(end 344.737182 -26.61285)
		(width 0.14732)
		(layer "In13.Cu")
		(net "P3E_PCH_M2_TX_DP<2>")
	)
	(segment
		(start 332.20406 -22.007068)
		(end 329.09002 -18.893028)
		(width 0.14732)
		(layer "In13.Cu")
		(net "P3E_PCH_M2_TX_DP<2>")
	)
	(segment
		(start 348.67088 -36.210748)
		(end 348.079822 -35.61969)
		(width 0.14732)
		(layer "In13.Cu")
		(net "P3E_PCH_M2_TX_DP<2>")
	)
	(segment
		(start 342.652858 -24.664924)
		(end 342.652858 -24.528526)
		(width 0.14732)
		(layer "In13.Cu")
		(net "P3E_PCH_M2_TX_DP<2>")
	)
	(segment
		(start 347.783658 -41.649396)
		(end 347.783658 -41.512998)
		(width 0.14732)
		(layer "In13.Cu")
		(net "P3E_PCH_M2_TX_DP<2>")
	)
	(segment
		(start 329.09002 -18.893028)
		(end 327.32218 -18.893028)
		(width 0.14732)
		(layer "In13.Cu")
		(net "P3E_PCH_M2_TX_DP<2>")
	)
	(segment
		(start 344.706702 -42.716196)
		(end 344.750644 -42.760138)
		(width 0.0889)
		(layer "In13.Cu")
		(net "P3E_PCH_M2_TX_DP<2>")
	)
	(segment
		(start 338.76107 -22.14499)
		(end 338.581238 -21.965158)
		(width 0.14732)
		(layer "In13.Cu")
		(net "P3E_PCH_M2_TX_DP<2>")
	)
	(segment
		(start 297.564302 -23.755858)
		(end 274.720304 -56.380634)
		(width 0.14732)
		(layer "In13.Cu")
		(net "P3E_PCH_M2_TX_DP<2>")
	)
	(segment
		(start 348.57436 -37.417248)
		(end 348.57436 -37.163248)
		(width 0.14732)
		(layer "In13.Cu")
		(net "P3E_PCH_M2_TX_DP<2>")
	)
	(segment
		(start 344.420698 -26.296366)
		(end 344.188542 -26.06421)
		(width 0.14732)
		(layer "In13.Cu")
		(net "P3E_PCH_M2_TX_DP<2>")
	)
	(segment
		(start 346.00388 -30.015688)
		(end 345.90736 -29.919168)
		(width 0.14732)
		(layer "In13.Cu")
		(net "P3E_PCH_M2_TX_DP<2>")
	)
	(segment
		(start 348.079822 -35.61969)
		(end 347.94317 -35.61969)
		(width 0.14732)
		(layer "In13.Cu")
		(net "P3E_PCH_M2_TX_DP<2>")
	)
	(segment
		(start 347.783658 -41.512998)
		(end 347.96349 -41.333166)
		(width 0.14732)
		(layer "In13.Cu")
		(net "P3E_PCH_M2_TX_DP<2>")
	)
	(segment
		(start 344.420698 -26.433018)
		(end 344.420698 -26.296366)
		(width 0.14732)
		(layer "In13.Cu")
		(net "P3E_PCH_M2_TX_DP<2>")
	)
	(segment
		(start 346.832428 -34.372296)
		(end 346.00388 -33.543748)
		(width 0.14732)
		(layer "In13.Cu")
		(net "P3E_PCH_M2_TX_DP<2>")
	)
	(segment
		(start 345.90736 -28.933648)
		(end 345.90736 -28.679648)
		(width 0.14732)
		(layer "In13.Cu")
		(net "P3E_PCH_M2_TX_DP<2>")
	)
	(segment
		(start 182.335932 -47.733458)
		(end 182.041292 -48.028098)
		(width 0.14732)
		(layer "In13.Cu")
		(net "P3E_PCH_M2_TX_DP<2>")
	)
	(segment
		(start 338.581238 -21.828506)
		(end 337.64728 -20.894548)
		(width 0.14732)
		(layer "In13.Cu")
		(net "P3E_PCH_M2_TX_DP<2>")
	)
	(segment
		(start 347.94317 -35.61969)
		(end 347.763338 -35.439858)
		(width 0.14732)
		(layer "In13.Cu")
		(net "P3E_PCH_M2_TX_DP<2>")
	)
	(segment
		(start 235.20146 -64.626998)
		(end 200.929494 -58.584592)
		(width 0.14732)
		(layer "In13.Cu")
		(net "P3E_PCH_M2_TX_DP<2>")
	)
	(segment
		(start 200.929494 -58.584592)
		(end 192.340484 -53.192426)
		(width 0.14732)
		(layer "In13.Cu")
		(net "P3E_PCH_M2_TX_DP<2>")
	)
	(segment
		(start 346.368116 -42.760138)
		(end 346.41028 -42.717974)
		(width 0.0889)
		(layer "In13.Cu")
		(net "P3E_PCH_M2_TX_DP<2>")
	)
	(segment
		(start 343.872058 -25.747726)
		(end 342.969088 -24.844756)
		(width 0.14732)
		(layer "In13.Cu")
		(net "P3E_PCH_M2_TX_DP<2>")
	)
	(segment
		(start 348.57436 -38.638988)
		(end 348.57436 -38.384988)
		(width 0.14732)
		(layer "In13.Cu")
		(net "P3E_PCH_M2_TX_DP<2>")
	)
	(segment
		(start 347.148912 -34.68878)
		(end 347.01226 -34.68878)
		(width 0.14732)
		(layer "In13.Cu")
		(net "P3E_PCH_M2_TX_DP<2>")
	)
	(segment
		(start 344.09253 -42.497756)
		(end 344.071702 -42.575988)
		(width 0.0889)
		(layer "In13.Cu")
		(net "P3E_PCH_M2_TX_DP<2>")
	)
	(segment
		(start 336.405982 -20.894548)
		(end 333.720186 -22.007068)
		(width 0.14732)
		(layer "In13.Cu")
		(net "P3E_PCH_M2_TX_DP<2>")
	)
	(segment
		(start 192.34023 -53.192426)
		(end 183.841898 -47.85741)
		(width 0.14732)
		(layer "In13.Cu")
		(net "P3E_PCH_M2_TX_DP<2>")
	)
	(segment
		(start 338.581238 -21.965158)
		(end 338.581238 -21.828506)
		(width 0.14732)
		(layer "In13.Cu")
		(net "P3E_PCH_M2_TX_DP<2>")
	)
	(segment
		(start 346.41028 -42.717974)
		(end 346.432378 -42.717974)
		(width 0.0889)
		(layer "In13.Cu")
		(net "P3E_PCH_M2_TX_DP<2>")
	)
	(segment
		(start 345.90736 -29.919168)
		(end 345.90736 -29.665168)
		(width 0.14732)
		(layer "In13.Cu")
		(net "P3E_PCH_M2_TX_DP<2>")
	)
	(segment
		(start 183.13908 -47.733458)
		(end 182.335932 -47.733458)
		(width 0.14732)
		(layer "In13.Cu")
		(net "P3E_PCH_M2_TX_DP<2>")
	)
	(segment
		(start 338.897722 -22.14499)
		(end 338.76107 -22.14499)
		(width 0.14732)
		(layer "In13.Cu")
		(net "P3E_PCH_M2_TX_DP<2>")
	)
	(segment
		(start 343.872058 -25.884378)
		(end 343.872058 -25.747726)
		(width 0.14732)
		(layer "In13.Cu")
		(net "P3E_PCH_M2_TX_DP<2>")
	)
	(segment
		(start 344.985848 -26.998168)
		(end 344.985848 -26.861516)
		(width 0.14732)
		(layer "In13.Cu")
		(net "P3E_PCH_M2_TX_DP<2>")
	)
	(segment
		(start 346.00388 -28.583128)
		(end 346.00388 -27.879548)
		(width 0.14732)
		(layer "In13.Cu")
		(net "P3E_PCH_M2_TX_DP<2>")
	)
	(segment
		(start 347.763338 -35.439858)
		(end 347.763338 -35.303206)
		(width 0.14732)
		(layer "In13.Cu")
		(net "P3E_PCH_M2_TX_DP<2>")
	)
	(arc
		(start 344.071702 -42.575988)
		(mid 344.199135 -42.677704)
		(end 344.357706 -42.715688)
		(width 0.0889)
		(layer "In13.Cu")
		(net "P3E_PCH_M2_TX_DP<2>")
	)
	(segment
		(start 182.041292 -50.949098)
		(end 181.755542 -50.663348)
		(width 0.13208)
		(layer "F.Cu")
		(net "P3E_PCH_M2_TX_DP<1>")
	)
	(segment
		(start 181.755542 -50.663348)
		(end 181.106318 -50.663348)
		(width 0.13208)
		(layer "F.Cu")
		(net "P3E_PCH_M2_TX_DP<1>")
	)
	(segment
		(start 181.106318 -50.663348)
		(end 180.795168 -50.974498)
		(width 0.13208)
		(layer "F.Cu")
		(net "P3E_PCH_M2_TX_DP<1>")
	)
	(segment
		(start 343.006934 -43.750992)
		(end 343.005156 -43.751246)
		(width 0.13208)
		(layer "F.Cu")
		(net "P3E_PCH_M2_TX_DP<1>")
	)
	(segment
		(start 342.735154 -43.281092)
		(end 343.006934 -43.750992)
		(width 0.13208)
		(layer "F.Cu")
		(net "P3E_PCH_M2_TX_DP<1>")
	)
	(segment
		(start 299.014388 -24.01189)
		(end 298.209716 -24.575516)
		(width 0.14732)
		(layer "In13.Cu")
		(net "P3E_PCH_M2_TX_DP<1>")
	)
	(segment
		(start 343.85758 -31.5849)
		(end 343.677748 -31.405068)
		(width 0.14732)
		(layer "In13.Cu")
		(net "P3E_PCH_M2_TX_DP<1>")
	)
	(segment
		(start 341.635588 -29.226256)
		(end 341.258652 -28.84932)
		(width 0.14732)
		(layer "In13.Cu")
		(net "P3E_PCH_M2_TX_DP<1>")
	)
	(segment
		(start 340.31428 -27.904948)
		(end 340.31428 -26.300938)
		(width 0.14732)
		(layer "In13.Cu")
		(net "P3E_PCH_M2_TX_DP<1>")
	)
	(segment
		(start 342.47201 -30.19933)
		(end 342.292178 -30.019498)
		(width 0.14732)
		(layer "In13.Cu")
		(net "P3E_PCH_M2_TX_DP<1>")
	)
	(segment
		(start 346.364306 -41.225978)
		(end 346.364306 -39.669974)
		(width 0.14732)
		(layer "In13.Cu")
		(net "P3E_PCH_M2_TX_DP<1>")
	)
	(segment
		(start 346.201238 -41.44899)
		(end 346.201238 -41.389046)
		(width 0.0889)
		(layer "In13.Cu")
		(net "P3E_PCH_M2_TX_DP<1>")
	)
	(segment
		(start 345.01328 -32.603948)
		(end 343.994232 -31.5849)
		(width 0.14732)
		(layer "In13.Cu")
		(net "P3E_PCH_M2_TX_DP<1>")
	)
	(segment
		(start 340.31428 -25.136348)
		(end 339.631782 -24.45385)
		(width 0.14732)
		(layer "In13.Cu")
		(net "P3E_PCH_M2_TX_DP<1>")
	)
	(segment
		(start 328.7268 -19.886168)
		(end 326.72782 -19.886168)
		(width 0.14732)
		(layer "In13.Cu")
		(net "P3E_PCH_M2_TX_DP<1>")
	)
	(segment
		(start 341.122 -28.84932)
		(end 340.942168 -28.669488)
		(width 0.14732)
		(layer "In13.Cu")
		(net "P3E_PCH_M2_TX_DP<1>")
	)
	(segment
		(start 182.89397 -50.654458)
		(end 182.335932 -50.654458)
		(width 0.14732)
		(layer "In13.Cu")
		(net "P3E_PCH_M2_TX_DP<1>")
	)
	(segment
		(start 298.209716 -24.575516)
		(end 275.361654 -57.206642)
		(width 0.14732)
		(layer "In13.Cu")
		(net "P3E_PCH_M2_TX_DP<1>")
	)
	(segment
		(start 199.268588 -59.246262)
		(end 185.93308 -51.91379)
		(width 0.14732)
		(layer "In13.Cu")
		(net "P3E_PCH_M2_TX_DP<1>")
	)
	(segment
		(start 326.72782 -19.886168)
		(end 325.767954 -18.926302)
		(width 0.14732)
		(layer "In13.Cu")
		(net "P3E_PCH_M2_TX_DP<1>")
	)
	(segment
		(start 339.315298 -24.137366)
		(end 338.11972 -22.941788)
		(width 0.14732)
		(layer "In13.Cu")
		(net "P3E_PCH_M2_TX_DP<1>")
	)
	(segment
		(start 338.11972 -22.941788)
		(end 331.78242 -22.941788)
		(width 0.14732)
		(layer "In13.Cu")
		(net "P3E_PCH_M2_TX_DP<1>")
	)
	(segment
		(start 182.335932 -50.654458)
		(end 182.041292 -50.949098)
		(width 0.14732)
		(layer "In13.Cu")
		(net "P3E_PCH_M2_TX_DP<1>")
	)
	(segment
		(start 345.874086 -41.776142)
		(end 346.201238 -41.44899)
		(width 0.0889)
		(layer "In13.Cu")
		(net "P3E_PCH_M2_TX_DP<1>")
	)
	(segment
		(start 339.315298 -24.274018)
		(end 339.315298 -24.137366)
		(width 0.14732)
		(layer "In13.Cu")
		(net "P3E_PCH_M2_TX_DP<1>")
	)
	(segment
		(start 343.530936 -42.246042)
		(end 343.549478 -42.246042)
		(width 0.0889)
		(layer "In13.Cu")
		(net "P3E_PCH_M2_TX_DP<1>")
	)
	(segment
		(start 344.363548 -41.776142)
		(end 345.874086 -41.776142)
		(width 0.0889)
		(layer "In13.Cu")
		(net "P3E_PCH_M2_TX_DP<1>")
	)
	(segment
		(start 343.677748 -31.268416)
		(end 343.229692 -30.82036)
		(width 0.14732)
		(layer "In13.Cu")
		(net "P3E_PCH_M2_TX_DP<1>")
	)
	(segment
		(start 339.631782 -24.45385)
		(end 339.49513 -24.45385)
		(width 0.14732)
		(layer "In13.Cu")
		(net "P3E_PCH_M2_TX_DP<1>")
	)
	(segment
		(start 343.677748 -31.405068)
		(end 343.677748 -31.268416)
		(width 0.14732)
		(layer "In13.Cu")
		(net "P3E_PCH_M2_TX_DP<1>")
	)
	(segment
		(start 343.994232 -31.5849)
		(end 343.85758 -31.5849)
		(width 0.14732)
		(layer "In13.Cu")
		(net "P3E_PCH_M2_TX_DP<1>")
	)
	(segment
		(start 342.735154 -43.281092)
		(end 343.008712 -43.438826)
		(width 0.0889)
		(layer "In13.Cu")
		(net "P3E_PCH_M2_TX_DP<1>")
	)
	(segment
		(start 342.913208 -30.503876)
		(end 342.608662 -30.19933)
		(width 0.14732)
		(layer "In13.Cu")
		(net "P3E_PCH_M2_TX_DP<1>")
	)
	(segment
		(start 343.09304 -30.82036)
		(end 342.913208 -30.640528)
		(width 0.14732)
		(layer "In13.Cu")
		(net "P3E_PCH_M2_TX_DP<1>")
	)
	(segment
		(start 185.93308 -51.91379)
		(end 182.89397 -50.654458)
		(width 0.14732)
		(layer "In13.Cu")
		(net "P3E_PCH_M2_TX_DP<1>")
	)
	(segment
		(start 341.258652 -28.84932)
		(end 341.122 -28.84932)
		(width 0.14732)
		(layer "In13.Cu")
		(net "P3E_PCH_M2_TX_DP<1>")
	)
	(segment
		(start 341.635588 -29.362908)
		(end 341.635588 -29.226256)
		(width 0.14732)
		(layer "In13.Cu")
		(net "P3E_PCH_M2_TX_DP<1>")
	)
	(segment
		(start 340.31428 -26.300938)
		(end 340.1695 -26.156158)
		(width 0.14732)
		(layer "In13.Cu")
		(net "P3E_PCH_M2_TX_DP<1>")
	)
	(segment
		(start 340.942168 -28.669488)
		(end 340.942168 -28.532836)
		(width 0.14732)
		(layer "In13.Cu")
		(net "P3E_PCH_M2_TX_DP<1>")
	)
	(segment
		(start 344.344752 -41.776396)
		(end 344.3478 -41.776142)
		(width 0.0889)
		(layer "In13.Cu")
		(net "P3E_PCH_M2_TX_DP<1>")
	)
	(segment
		(start 339.49513 -24.45385)
		(end 339.315298 -24.274018)
		(width 0.14732)
		(layer "In13.Cu")
		(net "P3E_PCH_M2_TX_DP<1>")
	)
	(segment
		(start 343.229692 -30.82036)
		(end 343.09304 -30.82036)
		(width 0.14732)
		(layer "In13.Cu")
		(net "P3E_PCH_M2_TX_DP<1>")
	)
	(segment
		(start 345.01328 -33.797748)
		(end 345.01328 -32.603948)
		(width 0.14732)
		(layer "In13.Cu")
		(net "P3E_PCH_M2_TX_DP<1>")
	)
	(segment
		(start 340.1695 -25.787858)
		(end 340.31428 -25.643078)
		(width 0.14732)
		(layer "In13.Cu")
		(net "P3E_PCH_M2_TX_DP<1>")
	)
	(segment
		(start 342.292178 -30.019498)
		(end 342.292178 -29.882846)
		(width 0.14732)
		(layer "In13.Cu")
		(net "P3E_PCH_M2_TX_DP<1>")
	)
	(segment
		(start 343.84996 -35.977068)
		(end 343.94648 -35.880548)
		(width 0.14732)
		(layer "In13.Cu")
		(net "P3E_PCH_M2_TX_DP<1>")
	)
	(segment
		(start 346.364306 -39.669974)
		(end 343.94648 -37.252148)
		(width 0.14732)
		(layer "In13.Cu")
		(net "P3E_PCH_M2_TX_DP<1>")
	)
	(segment
		(start 342.292178 -29.882846)
		(end 341.952072 -29.54274)
		(width 0.14732)
		(layer "In13.Cu")
		(net "P3E_PCH_M2_TX_DP<1>")
	)
	(segment
		(start 343.871296 -42.062908)
		(end 343.873836 -42.05859)
		(width 0.0889)
		(layer "In13.Cu")
		(net "P3E_PCH_M2_TX_DP<1>")
	)
	(segment
		(start 325.767954 -18.926302)
		(end 319.502028 -18.926302)
		(width 0.14732)
		(layer "In13.Cu")
		(net "P3E_PCH_M2_TX_DP<1>")
	)
	(segment
		(start 331.78242 -22.941788)
		(end 328.7268 -19.886168)
		(width 0.14732)
		(layer "In13.Cu")
		(net "P3E_PCH_M2_TX_DP<1>")
	)
	(segment
		(start 346.201238 -41.389046)
		(end 346.216732 -41.373552)
		(width 0.0889)
		(layer "In13.Cu")
		(net "P3E_PCH_M2_TX_DP<1>")
	)
	(segment
		(start 341.952072 -29.54274)
		(end 341.81542 -29.54274)
		(width 0.14732)
		(layer "In13.Cu")
		(net "P3E_PCH_M2_TX_DP<1>")
	)
	(segment
		(start 319.502028 -18.926302)
		(end 299.014388 -24.01189)
		(width 0.14732)
		(layer "In13.Cu")
		(net "P3E_PCH_M2_TX_DP<1>")
	)
	(segment
		(start 270.465296 -60.632848)
		(end 244.787166 -65.160398)
		(width 0.14732)
		(layer "In13.Cu")
		(net "P3E_PCH_M2_TX_DP<1>")
	)
	(segment
		(start 343.94648 -34.864548)
		(end 345.01328 -33.797748)
		(width 0.14732)
		(layer "In13.Cu")
		(net "P3E_PCH_M2_TX_DP<1>")
	)
	(segment
		(start 343.868756 -42.06748)
		(end 343.871296 -42.062908)
		(width 0.0889)
		(layer "In13.Cu")
		(net "P3E_PCH_M2_TX_DP<1>")
	)
	(segment
		(start 340.1695 -26.156158)
		(end 340.1695 -25.787858)
		(width 0.14732)
		(layer "In13.Cu")
		(net "P3E_PCH_M2_TX_DP<1>")
	)
	(segment
		(start 275.361654 -57.206642)
		(end 270.465296 -60.632848)
		(width 0.14732)
		(layer "In13.Cu")
		(net "P3E_PCH_M2_TX_DP<1>")
	)
	(segment
		(start 343.008712 -43.438826)
		(end 343.083642 -43.418506)
		(width 0.0889)
		(layer "In13.Cu")
		(net "P3E_PCH_M2_TX_DP<1>")
	)
	(segment
		(start 341.81542 -29.54274)
		(end 341.635588 -29.362908)
		(width 0.14732)
		(layer "In13.Cu")
		(net "P3E_PCH_M2_TX_DP<1>")
	)
	(segment
		(start 340.942168 -28.532836)
		(end 340.31428 -27.904948)
		(width 0.14732)
		(layer "In13.Cu")
		(net "P3E_PCH_M2_TX_DP<1>")
	)
	(segment
		(start 244.787166 -65.160398)
		(end 235.253022 -65.590928)
		(width 0.14732)
		(layer "In13.Cu")
		(net "P3E_PCH_M2_TX_DP<1>")
	)
	(segment
		(start 235.253022 -65.590928)
		(end 199.268588 -59.246262)
		(width 0.14732)
		(layer "In13.Cu")
		(net "P3E_PCH_M2_TX_DP<1>")
	)
	(segment
		(start 343.84996 -36.231068)
		(end 343.84996 -35.977068)
		(width 0.14732)
		(layer "In13.Cu")
		(net "P3E_PCH_M2_TX_DP<1>")
	)
	(segment
		(start 342.913208 -30.640528)
		(end 342.913208 -30.503876)
		(width 0.14732)
		(layer "In13.Cu")
		(net "P3E_PCH_M2_TX_DP<1>")
	)
	(segment
		(start 343.94648 -35.880548)
		(end 343.94648 -34.864548)
		(width 0.14732)
		(layer "In13.Cu")
		(net "P3E_PCH_M2_TX_DP<1>")
	)
	(segment
		(start 340.31428 -25.643078)
		(end 340.31428 -25.136348)
		(width 0.14732)
		(layer "In13.Cu")
		(net "P3E_PCH_M2_TX_DP<1>")
	)
	(segment
		(start 343.94648 -36.327588)
		(end 343.84996 -36.231068)
		(width 0.14732)
		(layer "In13.Cu")
		(net "P3E_PCH_M2_TX_DP<1>")
	)
	(segment
		(start 343.94648 -37.252148)
		(end 343.94648 -36.327588)
		(width 0.14732)
		(layer "In13.Cu")
		(net "P3E_PCH_M2_TX_DP<1>")
	)
	(segment
		(start 346.216732 -41.373552)
		(end 346.364306 -41.225978)
		(width 0.14732)
		(layer "In13.Cu")
		(net "P3E_PCH_M2_TX_DP<1>")
	)
	(segment
		(start 342.608662 -30.19933)
		(end 342.47201 -30.19933)
		(width 0.14732)
		(layer "In13.Cu")
		(net "P3E_PCH_M2_TX_DP<1>")
	)
	(arc
		(start 343.549478 -42.246042)
		(mid 343.732378 -42.198363)
		(end 343.868756 -42.06748)
		(width 0.0889)
		(layer "In13.Cu")
		(net "P3E_PCH_M2_TX_DP<1>")
	)
	(arc
		(start 343.059766 -43.093894)
		(mid 343.055217 -42.53652)
		(end 343.530936 -42.246042)
		(width 0.0889)
		(layer "In13.Cu")
		(net "P3E_PCH_M2_TX_DP<1>")
	)
	(arc
		(start 343.873836 -42.05859)
		(mid 344.072759 -41.856548)
		(end 344.344752 -41.776396)
		(width 0.0889)
		(layer "In13.Cu")
		(net "P3E_PCH_M2_TX_DP<1>")
	)
	(arc
		(start 343.083642 -43.418506)
		(mid 343.108847 -43.253457)
		(end 343.059766 -43.093894)
		(width 0.0889)
		(layer "In13.Cu")
		(net "P3E_PCH_M2_TX_DP<1>")
	)
	(arc
		(start 344.3478 -41.776142)
		(mid 344.355674 -41.776087)
		(end 344.363548 -41.776142)
		(width 0.0889)
		(layer "In13.Cu")
		(net "P3E_PCH_M2_TX_DP<1>")
	)
	(segment
		(start 181.75732 -53.660548)
		(end 181.114954 -53.660548)
		(width 0.13208)
		(layer "F.Cu")
		(net "P3E_PCH_M2_TX_DP<0>")
	)
	(segment
		(start 182.041292 -53.94452)
		(end 181.75732 -53.660548)
		(width 0.13208)
		(layer "F.Cu")
		(net "P3E_PCH_M2_TX_DP<0>")
	)
	(segment
		(start 182.041292 -53.954934)
		(end 182.041292 -53.94452)
		(width 0.13208)
		(layer "F.Cu")
		(net "P3E_PCH_M2_TX_DP<0>")
	)
	(segment
		(start 341.37727 -45.630846)
		(end 341.105998 -45.160946)
		(width 0.13208)
		(layer "F.Cu")
		(net "P3E_PCH_M2_TX_DP<0>")
	)
	(segment
		(start 181.114954 -53.660548)
		(end 180.795168 -53.980334)
		(width 0.13208)
		(layer "F.Cu")
		(net "P3E_PCH_M2_TX_DP<0>")
	)
	(segment
		(start 184.732422 -53.888894)
		(end 183.437022 -53.660294)
		(width 0.14732)
		(layer "In13.Cu")
		(net "P3E_PCH_M2_TX_DP<0>")
	)
	(segment
		(start 336.78368 -33.660588)
		(end 336.78368 -33.068768)
		(width 0.14732)
		(layer "In13.Cu")
		(net "P3E_PCH_M2_TX_DP<0>")
	)
	(segment
		(start 319.763648 -19.855942)
		(end 310.858408 -22.066504)
		(width 0.14732)
		(layer "In13.Cu")
		(net "P3E_PCH_M2_TX_DP<0>")
	)
	(segment
		(start 276.0853 -57.876186)
		(end 270.84274 -61.54674)
		(width 0.14732)
		(layer "In13.Cu")
		(net "P3E_PCH_M2_TX_DP<0>")
	)
	(segment
		(start 338.135214 -35.184588)
		(end 337.826096 -34.87547)
		(width 0.14732)
		(layer "In13.Cu")
		(net "P3E_PCH_M2_TX_DP<0>")
	)
	(segment
		(start 338.616544 -35.665918)
		(end 338.616544 -35.493452)
		(width 0.14732)
		(layer "In13.Cu")
		(net "P3E_PCH_M2_TX_DP<0>")
	)
	(segment
		(start 325.201534 -19.855942)
		(end 319.763648 -19.855942)
		(width 0.14732)
		(layer "In13.Cu")
		(net "P3E_PCH_M2_TX_DP<0>")
	)
	(segment
		(start 182.335932 -53.660294)
		(end 182.041292 -53.954934)
		(width 0.14732)
		(layer "In13.Cu")
		(net "P3E_PCH_M2_TX_DP<0>")
	)
	(segment
		(start 329.908408 -22.705568)
		(end 328.05116 -22.705568)
		(width 0.14732)
		(layer "In13.Cu")
		(net "P3E_PCH_M2_TX_DP<0>")
	)
	(segment
		(start 342.733884 -41.776142)
		(end 342.761062 -41.776142)
		(width 0.0889)
		(layer "In13.Cu")
		(net "P3E_PCH_M2_TX_DP<0>")
	)
	(segment
		(start 244.977158 -66.107056)
		(end 235.25607 -66.540888)
		(width 0.14732)
		(layer "In13.Cu")
		(net "P3E_PCH_M2_TX_DP<0>")
	)
	(segment
		(start 341.414862 -42.548048)
		(end 341.41664 -42.544746)
		(width 0.0889)
		(layer "In13.Cu")
		(net "P3E_PCH_M2_TX_DP<0>")
	)
	(segment
		(start 341.414608 -42.548556)
		(end 341.414862 -42.548048)
		(width 0.0889)
		(layer "In13.Cu")
		(net "P3E_PCH_M2_TX_DP<0>")
	)
	(segment
		(start 343.774776 -39.28618)
		(end 343.774776 -39.077646)
		(width 0.14732)
		(layer "In13.Cu")
		(net "P3E_PCH_M2_TX_DP<0>")
	)
	(segment
		(start 328.05116 -22.705568)
		(end 325.201534 -19.855942)
		(width 0.14732)
		(layer "In13.Cu")
		(net "P3E_PCH_M2_TX_DP<0>")
	)
	(segment
		(start 339.406992 -36.456366)
		(end 339.406992 -36.2839)
		(width 0.14732)
		(layer "In13.Cu")
		(net "P3E_PCH_M2_TX_DP<0>")
	)
	(segment
		(start 343.513664 -41.306496)
		(end 343.548462 -41.306242)
		(width 0.0889)
		(layer "In13.Cu")
		(net "P3E_PCH_M2_TX_DP<0>")
	)
	(segment
		(start 339.098128 -35.975036)
		(end 338.925662 -35.975036)
		(width 0.14732)
		(layer "In13.Cu")
		(net "P3E_PCH_M2_TX_DP<0>")
	)
	(segment
		(start 235.25607 -66.540888)
		(end 197.239636 -59.838336)
		(width 0.14732)
		(layer "In13.Cu")
		(net "P3E_PCH_M2_TX_DP<0>")
	)
	(segment
		(start 339.406992 -36.2839)
		(end 339.098128 -35.975036)
		(width 0.14732)
		(layer "In13.Cu")
		(net "P3E_PCH_M2_TX_DP<0>")
	)
	(segment
		(start 341.105998 -45.160946)
		(end 341.353394 -45.017944)
		(width 0.0889)
		(layer "In13.Cu")
		(net "P3E_PCH_M2_TX_DP<0>")
	)
	(segment
		(start 299.779436 -29.826712)
		(end 297.328336 -33.327086)
		(width 0.14732)
		(layer "In13.Cu")
		(net "P3E_PCH_M2_TX_DP<0>")
	)
	(segment
		(start 343.548462 -41.306242)
		(end 343.56802 -41.306242)
		(width 0.0889)
		(layer "In13.Cu")
		(net "P3E_PCH_M2_TX_DP<0>")
	)
	(segment
		(start 339.888576 -36.765484)
		(end 339.71611 -36.765484)
		(width 0.14732)
		(layer "In13.Cu")
		(net "P3E_PCH_M2_TX_DP<0>")
	)
	(segment
		(start 197.239636 -59.838336)
		(end 184.732422 -53.888894)
		(width 0.14732)
		(layer "In13.Cu")
		(net "P3E_PCH_M2_TX_DP<0>")
	)
	(segment
		(start 336.78368 -32.388048)
		(end 336.78368 -30.013148)
		(width 0.14732)
		(layer "In13.Cu")
		(net "P3E_PCH_M2_TX_DP<0>")
	)
	(segment
		(start 336.78368 -33.068768)
		(end 336.66176 -32.946848)
		(width 0.14732)
		(layer "In13.Cu")
		(net "P3E_PCH_M2_TX_DP<0>")
	)
	(segment
		(start 343.81694 -39.350442)
		(end 343.774776 -39.308278)
		(width 0.0889)
		(layer "In13.Cu")
		(net "P3E_PCH_M2_TX_DP<0>")
	)
	(segment
		(start 343.872566 -40.179244)
		(end 343.95029 -40.044116)
		(width 0.0889)
		(layer "In13.Cu")
		(net "P3E_PCH_M2_TX_DP<0>")
	)
	(segment
		(start 341.353394 -45.017944)
		(end 341.385398 -44.896278)
		(width 0.0889)
		(layer "In13.Cu")
		(net "P3E_PCH_M2_TX_DP<0>")
	)
	(segment
		(start 336.66176 -32.946848)
		(end 336.66176 -32.509968)
		(width 0.14732)
		(layer "In13.Cu")
		(net "P3E_PCH_M2_TX_DP<0>")
	)
	(segment
		(start 343.774776 -39.308278)
		(end 343.774776 -39.28618)
		(width 0.0889)
		(layer "In13.Cu")
		(net "P3E_PCH_M2_TX_DP<0>")
	)
	(segment
		(start 341.272114 -43.802808)
		(end 341.371174 -43.564048)
		(width 0.0889)
		(layer "In13.Cu")
		(net "P3E_PCH_M2_TX_DP<0>")
	)
	(segment
		(start 341.771478 -37.074348)
		(end 340.19744 -37.074348)
		(width 0.14732)
		(layer "In13.Cu")
		(net "P3E_PCH_M2_TX_DP<0>")
	)
	(segment
		(start 330.73848 -23.53564)
		(end 329.908408 -22.705568)
		(width 0.14732)
		(layer "In13.Cu")
		(net "P3E_PCH_M2_TX_DP<0>")
	)
	(segment
		(start 270.84274 -61.54674)
		(end 244.977158 -66.107056)
		(width 0.14732)
		(layer "In13.Cu")
		(net "P3E_PCH_M2_TX_DP<0>")
	)
	(segment
		(start 339.71611 -36.765484)
		(end 339.406992 -36.456366)
		(width 0.14732)
		(layer "In13.Cu")
		(net "P3E_PCH_M2_TX_DP<0>")
	)
	(segment
		(start 337.826096 -34.703004)
		(end 336.78368 -33.660588)
		(width 0.14732)
		(layer "In13.Cu")
		(net "P3E_PCH_M2_TX_DP<0>")
	)
	(segment
		(start 342.695784 -41.776396)
		(end 342.733884 -41.776142)
		(width 0.0889)
		(layer "In13.Cu")
		(net "P3E_PCH_M2_TX_DP<0>")
	)
	(segment
		(start 338.30768 -35.184588)
		(end 338.135214 -35.184588)
		(width 0.14732)
		(layer "In13.Cu")
		(net "P3E_PCH_M2_TX_DP<0>")
	)
	(segment
		(start 338.925662 -35.975036)
		(end 338.616544 -35.665918)
		(width 0.14732)
		(layer "In13.Cu")
		(net "P3E_PCH_M2_TX_DP<0>")
	)
	(segment
		(start 336.66176 -32.509968)
		(end 336.78368 -32.388048)
		(width 0.14732)
		(layer "In13.Cu")
		(net "P3E_PCH_M2_TX_DP<0>")
	)
	(segment
		(start 338.616544 -35.493452)
		(end 338.30768 -35.184588)
		(width 0.14732)
		(layer "In13.Cu")
		(net "P3E_PCH_M2_TX_DP<0>")
	)
	(segment
		(start 330.73848 -23.967948)
		(end 330.73848 -23.53564)
		(width 0.14732)
		(layer "In13.Cu")
		(net "P3E_PCH_M2_TX_DP<0>")
	)
	(segment
		(start 343.81694 -39.486332)
		(end 343.81694 -39.350442)
		(width 0.0889)
		(layer "In13.Cu")
		(net "P3E_PCH_M2_TX_DP<0>")
	)
	(segment
		(start 343.86647 -40.189658)
		(end 343.872566 -40.179244)
		(width 0.0889)
		(layer "In13.Cu")
		(net "P3E_PCH_M2_TX_DP<0>")
	)
	(segment
		(start 341.41664 -42.544746)
		(end 341.425784 -42.528998)
		(width 0.0889)
		(layer "In13.Cu")
		(net "P3E_PCH_M2_TX_DP<0>")
	)
	(segment
		(start 280.081228 -53.880766)
		(end 276.0853 -57.876186)
		(width 0.14732)
		(layer "In13.Cu")
		(net "P3E_PCH_M2_TX_DP<0>")
	)
	(segment
		(start 337.826096 -34.87547)
		(end 337.826096 -34.703004)
		(width 0.14732)
		(layer "In13.Cu")
		(net "P3E_PCH_M2_TX_DP<0>")
	)
	(segment
		(start 336.78368 -30.013148)
		(end 330.73848 -23.967948)
		(width 0.14732)
		(layer "In13.Cu")
		(net "P3E_PCH_M2_TX_DP<0>")
	)
	(segment
		(start 341.272114 -44.700444)
		(end 341.272114 -43.802808)
		(width 0.0889)
		(layer "In13.Cu")
		(net "P3E_PCH_M2_TX_DP<0>")
	)
	(segment
		(start 340.19744 -37.074348)
		(end 339.888576 -36.765484)
		(width 0.14732)
		(layer "In13.Cu")
		(net "P3E_PCH_M2_TX_DP<0>")
	)
	(segment
		(start 343.881456 -40.759888)
		(end 343.872566 -40.744394)
		(width 0.0889)
		(layer "In13.Cu")
		(net "P3E_PCH_M2_TX_DP<0>")
	)
	(segment
		(start 297.328336 -33.327086)
		(end 280.081228 -53.880766)
		(width 0.14732)
		(layer "In13.Cu")
		(net "P3E_PCH_M2_TX_DP<0>")
	)
	(segment
		(start 341.385398 -44.896278)
		(end 341.272114 -44.700444)
		(width 0.0889)
		(layer "In13.Cu")
		(net "P3E_PCH_M2_TX_DP<0>")
	)
	(segment
		(start 310.858408 -22.066504)
		(end 299.779436 -29.826712)
		(width 0.14732)
		(layer "In13.Cu")
		(net "P3E_PCH_M2_TX_DP<0>")
	)
	(segment
		(start 341.85987 -42.246296)
		(end 341.942166 -42.246296)
		(width 0.0889)
		(layer "In13.Cu")
		(net "P3E_PCH_M2_TX_DP<0>")
	)
	(segment
		(start 343.774776 -39.077646)
		(end 341.771478 -37.074348)
		(width 0.14732)
		(layer "In13.Cu")
		(net "P3E_PCH_M2_TX_DP<0>")
	)
	(segment
		(start 183.437022 -53.660294)
		(end 182.335932 -53.660294)
		(width 0.14732)
		(layer "In13.Cu")
		(net "P3E_PCH_M2_TX_DP<0>")
	)
	(arc
		(start 341.371174 -43.564048)
		(mid 341.37667 -43.551754)
		(end 341.382604 -43.539664)
		(width 0.0889)
		(layer "In13.Cu")
		(net "P3E_PCH_M2_TX_DP<0>")
	)
	(arc
		(start 341.942166 -42.246296)
		(mid 342.116761 -42.190581)
		(end 342.244172 -42.058844)
		(width 0.0889)
		(layer "In13.Cu")
		(net "P3E_PCH_M2_TX_DP<0>")
	)
	(arc
		(start 343.05875 -41.588944)
		(mid 343.250731 -41.390619)
		(end 343.513664 -41.306496)
		(width 0.0889)
		(layer "In13.Cu")
		(net "P3E_PCH_M2_TX_DP<0>")
	)
	(arc
		(start 341.425784 -42.528998)
		(mid 341.60874 -42.335312)
		(end 341.85987 -42.246296)
		(width 0.0889)
		(layer "In13.Cu")
		(net "P3E_PCH_M2_TX_DP<0>")
	)
	(arc
		(start 342.244172 -42.058844)
		(mid 342.434698 -41.86122)
		(end 342.695784 -41.776396)
		(width 0.0889)
		(layer "In13.Cu")
		(net "P3E_PCH_M2_TX_DP<0>")
	)
	(arc
		(start 341.425276 -43.093894)
		(mid 341.350276 -42.822585)
		(end 341.414608 -42.548556)
		(width 0.0889)
		(layer "In13.Cu")
		(net "P3E_PCH_M2_TX_DP<0>")
	)
	(arc
		(start 343.95029 -40.044116)
		(mid 343.945643 -39.911432)
		(end 343.898474 -39.787322)
		(width 0.0889)
		(layer "In13.Cu")
		(net "P3E_PCH_M2_TX_DP<0>")
	)
	(arc
		(start 343.872566 -40.744394)
		(mid 343.796891 -40.467835)
		(end 343.86647 -40.189658)
		(width 0.0889)
		(layer "In13.Cu")
		(net "P3E_PCH_M2_TX_DP<0>")
	)
	(arc
		(start 341.382604 -43.539664)
		(mid 341.39471 -43.517521)
		(end 341.408258 -43.49623)
		(width 0.0889)
		(layer "In13.Cu")
		(net "P3E_PCH_M2_TX_DP<0>")
	)
	(arc
		(start 343.873074 -41.11879)
		(mid 343.923012 -40.940401)
		(end 343.881456 -40.759888)
		(width 0.0889)
		(layer "In13.Cu")
		(net "P3E_PCH_M2_TX_DP<0>")
	)
	(arc
		(start 343.898474 -39.787322)
		(mid 343.837705 -39.642244)
		(end 343.81694 -39.486332)
		(width 0.0889)
		(layer "In13.Cu")
		(net "P3E_PCH_M2_TX_DP<0>")
	)
	(arc
		(start 341.425276 -43.468798)
		(mid 341.475073 -43.281346)
		(end 341.425276 -43.093894)
		(width 0.0889)
		(layer "In13.Cu")
		(net "P3E_PCH_M2_TX_DP<0>")
	)
	(arc
		(start 342.761062 -41.776142)
		(mid 342.933195 -41.719569)
		(end 343.05875 -41.588944)
		(width 0.0889)
		(layer "In13.Cu")
		(net "P3E_PCH_M2_TX_DP<0>")
	)
	(arc
		(start 341.408258 -43.49623)
		(mid 341.417061 -43.482696)
		(end 341.425276 -43.468798)
		(width 0.0889)
		(layer "In13.Cu")
		(net "P3E_PCH_M2_TX_DP<0>")
	)
	(arc
		(start 343.56802 -41.306242)
		(mid 343.744361 -41.251263)
		(end 343.873074 -41.11879)
		(width 0.0889)
		(layer "In13.Cu")
		(net "P3E_PCH_M2_TX_DP<0>")
	)
	(segment
		(start 181.122828 -44.418758)
		(end 180.795168 -44.091098)
		(width 0.13208)
		(layer "F.Cu")
		(net "P3E_PCH_M2_TX_DN<3>")
	)
	(segment
		(start 182.041292 -44.116498)
		(end 181.739032 -44.418758)
		(width 0.13208)
		(layer "F.Cu")
		(net "P3E_PCH_M2_TX_DN<3>")
	)
	(segment
		(start 181.739032 -44.418758)
		(end 181.122828 -44.418758)
		(width 0.13208)
		(layer "F.Cu")
		(net "P3E_PCH_M2_TX_DN<3>")
	)
	(segment
		(start 342.735154 -45.160692)
		(end 343.006934 -45.630592)
		(width 0.13208)
		(layer "F.Cu")
		(net "P3E_PCH_M2_TX_DN<3>")
	)
	(segment
		(start 343.006934 -45.630592)
		(end 343.005156 -45.630846)
		(width 0.13208)
		(layer "F.Cu")
		(net "P3E_PCH_M2_TX_DN<3>")
	)
	(segment
		(start 329.602592 -17.386808)
		(end 327.822052 -17.386808)
		(width 0.14732)
		(layer "In13.Cu")
		(net "P3E_PCH_M2_TX_DN<3>")
	)
	(segment
		(start 343.542366 -44.316142)
		(end 343.559384 -44.316142)
		(width 0.0889)
		(layer "In13.Cu")
		(net "P3E_PCH_M2_TX_DN<3>")
	)
	(segment
		(start 346.447872 -26.436828)
		(end 338.045552 -18.034508)
		(width 0.14732)
		(layer "In13.Cu")
		(net "P3E_PCH_M2_TX_DN<3>")
	)
	(segment
		(start 346.36837 -43.931078)
		(end 346.41028 -43.972988)
		(width 0.0889)
		(layer "In13.Cu")
		(net "P3E_PCH_M2_TX_DN<3>")
	)
	(segment
		(start 347.621098 -43.972988)
		(end 350.0374 -41.556686)
		(width 0.14732)
		(layer "In13.Cu")
		(net "P3E_PCH_M2_TX_DN<3>")
	)
	(segment
		(start 202.409044 -57.585864)
		(end 184.158382 -44.555664)
		(width 0.14732)
		(layer "In13.Cu")
		(net "P3E_PCH_M2_TX_DN<3>")
	)
	(segment
		(start 342.735154 -45.160692)
		(end 342.735154 -44.84497)
		(width 0.0889)
		(layer "In13.Cu")
		(net "P3E_PCH_M2_TX_DN<3>")
	)
	(segment
		(start 338.045552 -18.034508)
		(end 335.275428 -18.034508)
		(width 0.14732)
		(layer "In13.Cu")
		(net "P3E_PCH_M2_TX_DN<3>")
	)
	(segment
		(start 183.3372 -44.411138)
		(end 182.335932 -44.411138)
		(width 0.14732)
		(layer "In13.Cu")
		(net "P3E_PCH_M2_TX_DN<3>")
	)
	(segment
		(start 347.743272 -26.436828)
		(end 346.447872 -26.436828)
		(width 0.14732)
		(layer "In13.Cu")
		(net "P3E_PCH_M2_TX_DN<3>")
	)
	(segment
		(start 344.039444 -44.032932)
		(end 344.044016 -44.024804)
		(width 0.0889)
		(layer "In13.Cu")
		(net "P3E_PCH_M2_TX_DN<3>")
	)
	(segment
		(start 344.038936 -44.033694)
		(end 344.039444 -44.032932)
		(width 0.0889)
		(layer "In13.Cu")
		(net "P3E_PCH_M2_TX_DN<3>")
	)
	(segment
		(start 327.227946 -16.792702)
		(end 318.102742 -16.792702)
		(width 0.14732)
		(layer "In13.Cu")
		(net "P3E_PCH_M2_TX_DN<3>")
	)
	(segment
		(start 235.153962 -63.360046)
		(end 202.409044 -57.585864)
		(width 0.14732)
		(layer "In13.Cu")
		(net "P3E_PCH_M2_TX_DN<3>")
	)
	(segment
		(start 350.0374 -28.730956)
		(end 347.743272 -26.436828)
		(width 0.14732)
		(layer "In13.Cu")
		(net "P3E_PCH_M2_TX_DN<3>")
	)
	(segment
		(start 296.861738 -22.579076)
		(end 274.018248 -55.203344)
		(width 0.14732)
		(layer "In13.Cu")
		(net "P3E_PCH_M2_TX_DN<3>")
	)
	(segment
		(start 327.822052 -17.386808)
		(end 327.227946 -16.792702)
		(width 0.14732)
		(layer "In13.Cu")
		(net "P3E_PCH_M2_TX_DN<3>")
	)
	(segment
		(start 243.881402 -62.874906)
		(end 235.153962 -63.360046)
		(width 0.14732)
		(layer "In13.Cu")
		(net "P3E_PCH_M2_TX_DN<3>")
	)
	(segment
		(start 182.335932 -44.411138)
		(end 182.041292 -44.116498)
		(width 0.14732)
		(layer "In13.Cu")
		(net "P3E_PCH_M2_TX_DN<3>")
	)
	(segment
		(start 346.41028 -43.972988)
		(end 346.432378 -43.972988)
		(width 0.0889)
		(layer "In13.Cu")
		(net "P3E_PCH_M2_TX_DN<3>")
	)
	(segment
		(start 335.275428 -18.034508)
		(end 334.587088 -18.722848)
		(width 0.14732)
		(layer "In13.Cu")
		(net "P3E_PCH_M2_TX_DN<3>")
	)
	(segment
		(start 350.0374 -41.556686)
		(end 350.0374 -28.730956)
		(width 0.14732)
		(layer "In13.Cu")
		(net "P3E_PCH_M2_TX_DN<3>")
	)
	(segment
		(start 344.363294 -43.846242)
		(end 344.794586 -43.846242)
		(width 0.0889)
		(layer "In13.Cu")
		(net "P3E_PCH_M2_TX_DN<3>")
	)
	(segment
		(start 274.018248 -55.203344)
		(end 269.519654 -58.353198)
		(width 0.14732)
		(layer "In13.Cu")
		(net "P3E_PCH_M2_TX_DN<3>")
	)
	(segment
		(start 184.158382 -44.555664)
		(end 183.3372 -44.411138)
		(width 0.14732)
		(layer "In13.Cu")
		(net "P3E_PCH_M2_TX_DN<3>")
	)
	(segment
		(start 342.735154 -44.84497)
		(end 342.79713 -44.782994)
		(width 0.0889)
		(layer "In13.Cu")
		(net "P3E_PCH_M2_TX_DN<3>")
	)
	(segment
		(start 344.879422 -43.931078)
		(end 346.36837 -43.931078)
		(width 0.0889)
		(layer "In13.Cu")
		(net "P3E_PCH_M2_TX_DN<3>")
	)
	(segment
		(start 346.432378 -43.972988)
		(end 347.621098 -43.972988)
		(width 0.14732)
		(layer "In13.Cu")
		(net "P3E_PCH_M2_TX_DN<3>")
	)
	(segment
		(start 297.999658 -21.782278)
		(end 296.861738 -22.579076)
		(width 0.14732)
		(layer "In13.Cu")
		(net "P3E_PCH_M2_TX_DN<3>")
	)
	(segment
		(start 318.102742 -16.792702)
		(end 297.999658 -21.782278)
		(width 0.14732)
		(layer "In13.Cu")
		(net "P3E_PCH_M2_TX_DN<3>")
	)
	(segment
		(start 344.794586 -43.846242)
		(end 344.879422 -43.931078)
		(width 0.0889)
		(layer "In13.Cu")
		(net "P3E_PCH_M2_TX_DN<3>")
	)
	(segment
		(start 269.519654 -58.353198)
		(end 243.881402 -62.874906)
		(width 0.14732)
		(layer "In13.Cu")
		(net "P3E_PCH_M2_TX_DN<3>")
	)
	(segment
		(start 330.938632 -18.722848)
		(end 329.602592 -17.386808)
		(width 0.14732)
		(layer "In13.Cu")
		(net "P3E_PCH_M2_TX_DN<3>")
	)
	(segment
		(start 334.587088 -18.722848)
		(end 330.938632 -18.722848)
		(width 0.14732)
		(layer "In13.Cu")
		(net "P3E_PCH_M2_TX_DN<3>")
	)
	(arc
		(start 343.559384 -44.316142)
		(mid 343.836333 -44.238031)
		(end 344.038936 -44.033694)
		(width 0.0889)
		(layer "In13.Cu")
		(net "P3E_PCH_M2_TX_DN<3>")
	)
	(arc
		(start 344.044016 -44.024804)
		(mid 344.180376 -43.89389)
		(end 344.363294 -43.846242)
		(width 0.0889)
		(layer "In13.Cu")
		(net "P3E_PCH_M2_TX_DN<3>")
	)
	(arc
		(start 342.817958 -44.7802)
		(mid 343.053057 -44.68846)
		(end 343.224866 -44.503594)
		(width 0.0889)
		(layer "In13.Cu")
		(net "P3E_PCH_M2_TX_DN<3>")
	)
	(arc
		(start 342.79713 -44.782994)
		(mid 342.807557 -44.781693)
		(end 342.817958 -44.7802)
		(width 0.0889)
		(layer "In13.Cu")
		(net "P3E_PCH_M2_TX_DN<3>")
	)
	(arc
		(start 343.224866 -44.503594)
		(mid 343.358965 -44.368114)
		(end 343.542366 -44.316142)
		(width 0.0889)
		(layer "In13.Cu")
		(net "P3E_PCH_M2_TX_DN<3>")
	)
	(segment
		(start 181.740302 -47.465488)
		(end 181.121558 -47.465488)
		(width 0.13208)
		(layer "F.Cu")
		(net "P3E_PCH_M2_TX_DN<2>")
	)
	(segment
		(start 343.81948 -43.281346)
		(end 343.549478 -42.811192)
		(width 0.13208)
		(layer "F.Cu")
		(net "P3E_PCH_M2_TX_DN<2>")
	)
	(segment
		(start 182.041292 -47.164498)
		(end 181.740302 -47.465488)
		(width 0.13208)
		(layer "F.Cu")
		(net "P3E_PCH_M2_TX_DN<2>")
	)
	(segment
		(start 181.121558 -47.465488)
		(end 180.795168 -47.139098)
		(width 0.13208)
		(layer "F.Cu")
		(net "P3E_PCH_M2_TX_DN<2>")
	)
	(segment
		(start 344.344752 -42.906188)
		(end 344.363294 -42.906442)
		(width 0.0889)
		(layer "In13.Cu")
		(net "P3E_PCH_M2_TX_DN<2>")
	)
	(segment
		(start 333.665576 -21.732748)
		(end 332.317852 -21.732748)
		(width 0.14732)
		(layer "In13.Cu")
		(net "P3E_PCH_M2_TX_DN<2>")
	)
	(segment
		(start 201.030078 -58.32348)
		(end 183.942482 -47.596552)
		(width 0.14732)
		(layer "In13.Cu")
		(net "P3E_PCH_M2_TX_DN<2>")
	)
	(segment
		(start 244.371114 -63.89751)
		(end 235.218732 -64.351408)
		(width 0.14732)
		(layer "In13.Cu")
		(net "P3E_PCH_M2_TX_DN<2>")
	)
	(segment
		(start 343.778586 -42.678858)
		(end 343.90965 -42.678858)
		(width 0.0889)
		(layer "In13.Cu")
		(net "P3E_PCH_M2_TX_DN<2>")
	)
	(segment
		(start 183.16321 -47.459138)
		(end 182.335932 -47.459138)
		(width 0.14732)
		(layer "In13.Cu")
		(net "P3E_PCH_M2_TX_DN<2>")
	)
	(segment
		(start 342.587072 -24.074628)
		(end 341.215472 -24.074628)
		(width 0.14732)
		(layer "In13.Cu")
		(net "P3E_PCH_M2_TX_DN<2>")
	)
	(segment
		(start 326.539606 -17.722342)
		(end 318.890396 -17.722342)
		(width 0.14732)
		(layer "In13.Cu")
		(net "P3E_PCH_M2_TX_DN<2>")
	)
	(segment
		(start 348.9452 -40.875966)
		(end 348.9452 -36.096956)
		(width 0.14732)
		(layer "In13.Cu")
		(net "P3E_PCH_M2_TX_DN<2>")
	)
	(segment
		(start 346.36837 -42.950384)
		(end 346.41028 -42.992294)
		(width 0.0889)
		(layer "In13.Cu")
		(net "P3E_PCH_M2_TX_DN<2>")
	)
	(segment
		(start 183.41213 -47.502572)
		(end 183.40959 -47.502572)
		(width 0.14732)
		(layer "In13.Cu")
		(net "P3E_PCH_M2_TX_DN<2>")
	)
	(segment
		(start 274.5232 -56.18353)
		(end 269.947898 -59.387232)
		(width 0.14732)
		(layer "In13.Cu")
		(net "P3E_PCH_M2_TX_DN<2>")
	)
	(segment
		(start 298.459906 -22.793452)
		(end 297.367198 -23.558754)
		(width 0.14732)
		(layer "In13.Cu")
		(net "P3E_PCH_M2_TX_DN<2>")
	)
	(segment
		(start 336.351372 -20.620228)
		(end 333.665576 -21.732748)
		(width 0.14732)
		(layer "In13.Cu")
		(net "P3E_PCH_M2_TX_DN<2>")
	)
	(segment
		(start 346.2782 -27.765756)
		(end 342.587072 -24.074628)
		(width 0.14732)
		(layer "In13.Cu")
		(net "P3E_PCH_M2_TX_DN<2>")
	)
	(segment
		(start 346.41028 -42.992294)
		(end 346.432378 -42.992294)
		(width 0.0889)
		(layer "In13.Cu")
		(net "P3E_PCH_M2_TX_DN<2>")
	)
	(segment
		(start 235.218732 -64.351408)
		(end 201.030078 -58.32348)
		(width 0.14732)
		(layer "In13.Cu")
		(net "P3E_PCH_M2_TX_DN<2>")
	)
	(segment
		(start 341.215472 -24.074628)
		(end 337.761072 -20.620228)
		(width 0.14732)
		(layer "In13.Cu")
		(net "P3E_PCH_M2_TX_DN<2>")
	)
	(segment
		(start 346.2782 -33.429956)
		(end 346.2782 -27.765756)
		(width 0.14732)
		(layer "In13.Cu")
		(net "P3E_PCH_M2_TX_DN<2>")
	)
	(segment
		(start 183.40959 -47.502572)
		(end 183.16321 -47.459138)
		(width 0.14732)
		(layer "In13.Cu")
		(net "P3E_PCH_M2_TX_DN<2>")
	)
	(segment
		(start 348.9452 -36.096956)
		(end 346.2782 -33.429956)
		(width 0.14732)
		(layer "In13.Cu")
		(net "P3E_PCH_M2_TX_DN<2>")
	)
	(segment
		(start 344.67165 -42.950384)
		(end 346.36837 -42.950384)
		(width 0.0889)
		(layer "In13.Cu")
		(net "P3E_PCH_M2_TX_DN<2>")
	)
	(segment
		(start 269.947898 -59.387232)
		(end 244.371114 -63.89751)
		(width 0.14732)
		(layer "In13.Cu")
		(net "P3E_PCH_M2_TX_DN<2>")
	)
	(segment
		(start 346.432378 -42.992294)
		(end 346.828872 -42.992294)
		(width 0.14732)
		(layer "In13.Cu")
		(net "P3E_PCH_M2_TX_DN<2>")
	)
	(segment
		(start 344.363294 -42.906442)
		(end 344.627708 -42.906442)
		(width 0.0889)
		(layer "In13.Cu")
		(net "P3E_PCH_M2_TX_DN<2>")
	)
	(segment
		(start 329.203812 -18.618708)
		(end 327.435972 -18.618708)
		(width 0.14732)
		(layer "In13.Cu")
		(net "P3E_PCH_M2_TX_DN<2>")
	)
	(segment
		(start 183.942482 -47.596552)
		(end 183.41213 -47.502572)
		(width 0.14732)
		(layer "In13.Cu")
		(net "P3E_PCH_M2_TX_DN<2>")
	)
	(segment
		(start 318.890396 -17.722342)
		(end 298.459906 -22.793452)
		(width 0.14732)
		(layer "In13.Cu")
		(net "P3E_PCH_M2_TX_DN<2>")
	)
	(segment
		(start 327.435972 -18.618708)
		(end 326.539606 -17.722342)
		(width 0.14732)
		(layer "In13.Cu")
		(net "P3E_PCH_M2_TX_DN<2>")
	)
	(segment
		(start 337.761072 -20.620228)
		(end 336.351372 -20.620228)
		(width 0.14732)
		(layer "In13.Cu")
		(net "P3E_PCH_M2_TX_DN<2>")
	)
	(segment
		(start 344.627708 -42.906442)
		(end 344.67165 -42.950384)
		(width 0.0889)
		(layer "In13.Cu")
		(net "P3E_PCH_M2_TX_DN<2>")
	)
	(segment
		(start 297.367198 -23.558754)
		(end 274.5232 -56.18353)
		(width 0.14732)
		(layer "In13.Cu")
		(net "P3E_PCH_M2_TX_DN<2>")
	)
	(segment
		(start 343.549478 -42.811192)
		(end 343.778586 -42.678858)
		(width 0.0889)
		(layer "In13.Cu")
		(net "P3E_PCH_M2_TX_DN<2>")
	)
	(segment
		(start 182.335932 -47.459138)
		(end 182.041292 -47.164498)
		(width 0.14732)
		(layer "In13.Cu")
		(net "P3E_PCH_M2_TX_DN<2>")
	)
	(segment
		(start 346.828872 -42.992294)
		(end 348.9452 -40.875966)
		(width 0.14732)
		(layer "In13.Cu")
		(net "P3E_PCH_M2_TX_DN<2>")
	)
	(segment
		(start 332.317852 -21.732748)
		(end 329.203812 -18.618708)
		(width 0.14732)
		(layer "In13.Cu")
		(net "P3E_PCH_M2_TX_DN<2>")
	)
	(arc
		(start 343.90965 -42.678858)
		(mid 343.916173 -42.68743)
		(end 343.922858 -42.695876)
		(width 0.0889)
		(layer "In13.Cu")
		(net "P3E_PCH_M2_TX_DN<2>")
	)
	(arc
		(start 343.922858 -42.695876)
		(mid 344.110848 -42.847071)
		(end 344.344752 -42.906188)
		(width 0.0889)
		(layer "In13.Cu")
		(net "P3E_PCH_M2_TX_DN<2>")
	)
	(segment
		(start 181.139338 -50.404268)
		(end 180.795168 -50.060098)
		(width 0.13208)
		(layer "F.Cu")
		(net "P3E_PCH_M2_TX_DN<1>")
	)
	(segment
		(start 182.041292 -50.085498)
		(end 181.722522 -50.404268)
		(width 0.13208)
		(layer "F.Cu")
		(net "P3E_PCH_M2_TX_DN<1>")
	)
	(segment
		(start 181.722522 -50.404268)
		(end 181.139338 -50.404268)
		(width 0.13208)
		(layer "F.Cu")
		(net "P3E_PCH_M2_TX_DN<1>")
	)
	(segment
		(start 343.548716 -43.753532)
		(end 343.81948 -44.221146)
		(width 0.13208)
		(layer "F.Cu")
		(net "P3E_PCH_M2_TX_DN<1>")
	)
	(segment
		(start 343.549478 -43.750992)
		(end 343.548716 -43.753532)
		(width 0.13208)
		(layer "F.Cu")
		(net "P3E_PCH_M2_TX_DN<1>")
	)
	(segment
		(start 345.2876 -32.490156)
		(end 340.5886 -27.791156)
		(width 0.14732)
		(layer "In13.Cu")
		(net "P3E_PCH_M2_TX_DN<1>")
	)
	(segment
		(start 346.638626 -39.556182)
		(end 344.2208 -37.138356)
		(width 0.14732)
		(layer "In13.Cu")
		(net "P3E_PCH_M2_TX_DN<1>")
	)
	(segment
		(start 346.395294 -41.583102)
		(end 346.410788 -41.567608)
		(width 0.0889)
		(layer "In13.Cu")
		(net "P3E_PCH_M2_TX_DN<1>")
	)
	(segment
		(start 346.336366 -41.583102)
		(end 346.395294 -41.583102)
		(width 0.0889)
		(layer "In13.Cu")
		(net "P3E_PCH_M2_TX_DN<1>")
	)
	(segment
		(start 344.2208 -37.138356)
		(end 344.2208 -34.97834)
		(width 0.14732)
		(layer "In13.Cu")
		(net "P3E_PCH_M2_TX_DN<1>")
	)
	(segment
		(start 343.549478 -43.750992)
		(end 343.27592 -43.593258)
		(width 0.0889)
		(layer "In13.Cu")
		(net "P3E_PCH_M2_TX_DN<1>")
	)
	(segment
		(start 346.410788 -41.567608)
		(end 346.638626 -41.33977)
		(width 0.14732)
		(layer "In13.Cu")
		(net "P3E_PCH_M2_TX_DN<1>")
	)
	(segment
		(start 344.04173 -42.149522)
		(end 344.04427 -42.145204)
		(width 0.0889)
		(layer "In13.Cu")
		(net "P3E_PCH_M2_TX_DN<1>")
	)
	(segment
		(start 331.896212 -22.667468)
		(end 328.840592 -19.611848)
		(width 0.14732)
		(layer "In13.Cu")
		(net "P3E_PCH_M2_TX_DN<1>")
	)
	(segment
		(start 338.233512 -22.667468)
		(end 331.896212 -22.667468)
		(width 0.14732)
		(layer "In13.Cu")
		(net "P3E_PCH_M2_TX_DN<1>")
	)
	(segment
		(start 344.2208 -34.97834)
		(end 345.2876 -33.91154)
		(width 0.14732)
		(layer "In13.Cu")
		(net "P3E_PCH_M2_TX_DN<1>")
	)
	(segment
		(start 270.3576 -60.373006)
		(end 244.75694 -64.887094)
		(width 0.14732)
		(layer "In13.Cu")
		(net "P3E_PCH_M2_TX_DN<1>")
	)
	(segment
		(start 343.27592 -43.593258)
		(end 343.25306 -43.508168)
		(width 0.0889)
		(layer "In13.Cu")
		(net "P3E_PCH_M2_TX_DN<1>")
	)
	(segment
		(start 326.841612 -19.611848)
		(end 325.881746 -18.651982)
		(width 0.14732)
		(layer "In13.Cu")
		(net "P3E_PCH_M2_TX_DN<1>")
	)
	(segment
		(start 345.95308 -41.966388)
		(end 346.336366 -41.583102)
		(width 0.0889)
		(layer "In13.Cu")
		(net "P3E_PCH_M2_TX_DN<1>")
	)
	(segment
		(start 325.881746 -18.651982)
		(end 319.468246 -18.651982)
		(width 0.14732)
		(layer "In13.Cu")
		(net "P3E_PCH_M2_TX_DN<1>")
	)
	(segment
		(start 343.542366 -42.436542)
		(end 343.56802 -42.436542)
		(width 0.0889)
		(layer "In13.Cu")
		(net "P3E_PCH_M2_TX_DN<1>")
	)
	(segment
		(start 344.363548 -41.966642)
		(end 344.363802 -41.966388)
		(width 0.0889)
		(layer "In13.Cu")
		(net "P3E_PCH_M2_TX_DN<1>")
	)
	(segment
		(start 344.363802 -41.966388)
		(end 345.95308 -41.966388)
		(width 0.0889)
		(layer "In13.Cu")
		(net "P3E_PCH_M2_TX_DN<1>")
	)
	(segment
		(start 182.94858 -50.380138)
		(end 182.335932 -50.380138)
		(width 0.14732)
		(layer "In13.Cu")
		(net "P3E_PCH_M2_TX_DN<1>")
	)
	(segment
		(start 275.16455 -57.009538)
		(end 270.3576 -60.373006)
		(width 0.14732)
		(layer "In13.Cu")
		(net "P3E_PCH_M2_TX_DN<1>")
	)
	(segment
		(start 346.638626 -41.33977)
		(end 346.638626 -39.556182)
		(width 0.14732)
		(layer "In13.Cu")
		(net "P3E_PCH_M2_TX_DN<1>")
	)
	(segment
		(start 340.5886 -25.022556)
		(end 338.233512 -22.667468)
		(width 0.14732)
		(layer "In13.Cu")
		(net "P3E_PCH_M2_TX_DN<1>")
	)
	(segment
		(start 182.335932 -50.380138)
		(end 182.041292 -50.085498)
		(width 0.14732)
		(layer "In13.Cu")
		(net "P3E_PCH_M2_TX_DN<1>")
	)
	(segment
		(start 199.361044 -58.98388)
		(end 186.052206 -51.665886)
		(width 0.14732)
		(layer "In13.Cu")
		(net "P3E_PCH_M2_TX_DN<1>")
	)
	(segment
		(start 345.2876 -33.91154)
		(end 345.2876 -32.490156)
		(width 0.14732)
		(layer "In13.Cu")
		(net "P3E_PCH_M2_TX_DN<1>")
	)
	(segment
		(start 235.270802 -65.315338)
		(end 199.361044 -58.98388)
		(width 0.14732)
		(layer "In13.Cu")
		(net "P3E_PCH_M2_TX_DN<1>")
	)
	(segment
		(start 244.75694 -64.887094)
		(end 235.270802 -65.315338)
		(width 0.14732)
		(layer "In13.Cu")
		(net "P3E_PCH_M2_TX_DN<1>")
	)
	(segment
		(start 328.840592 -19.611848)
		(end 326.841612 -19.611848)
		(width 0.14732)
		(layer "In13.Cu")
		(net "P3E_PCH_M2_TX_DN<1>")
	)
	(segment
		(start 319.468246 -18.651982)
		(end 298.898818 -23.75789)
		(width 0.14732)
		(layer "In13.Cu")
		(net "P3E_PCH_M2_TX_DN<1>")
	)
	(segment
		(start 344.03919 -42.154094)
		(end 344.04173 -42.149522)
		(width 0.0889)
		(layer "In13.Cu")
		(net "P3E_PCH_M2_TX_DN<1>")
	)
	(segment
		(start 298.898818 -23.75789)
		(end 298.012612 -24.378412)
		(width 0.14732)
		(layer "In13.Cu")
		(net "P3E_PCH_M2_TX_DN<1>")
	)
	(segment
		(start 186.052206 -51.665886)
		(end 182.94858 -50.380138)
		(width 0.14732)
		(layer "In13.Cu")
		(net "P3E_PCH_M2_TX_DN<1>")
	)
	(segment
		(start 340.5886 -27.791156)
		(end 340.5886 -25.022556)
		(width 0.14732)
		(layer "In13.Cu")
		(net "P3E_PCH_M2_TX_DN<1>")
	)
	(segment
		(start 298.012612 -24.378412)
		(end 275.16455 -57.009538)
		(width 0.14732)
		(layer "In13.Cu")
		(net "P3E_PCH_M2_TX_DN<1>")
	)
	(arc
		(start 343.224866 -42.99839)
		(mid 343.223243 -42.626838)
		(end 343.542366 -42.436542)
		(width 0.0889)
		(layer "In13.Cu")
		(net "P3E_PCH_M2_TX_DN<1>")
	)
	(arc
		(start 344.04427 -42.145204)
		(mid 344.18063 -42.01429)
		(end 344.363548 -41.966642)
		(width 0.0889)
		(layer "In13.Cu")
		(net "P3E_PCH_M2_TX_DN<1>")
	)
	(arc
		(start 343.56802 -42.436542)
		(mid 343.840209 -42.35638)
		(end 344.03919 -42.154094)
		(width 0.0889)
		(layer "In13.Cu")
		(net "P3E_PCH_M2_TX_DN<1>")
	)
	(arc
		(start 343.25306 -43.508168)
		(mid 343.257219 -43.498301)
		(end 343.261188 -43.488356)
		(width 0.0889)
		(layer "In13.Cu")
		(net "P3E_PCH_M2_TX_DN<1>")
	)
	(arc
		(start 343.261188 -43.488356)
		(mid 343.298979 -43.23923)
		(end 343.224866 -42.99839)
		(width 0.0889)
		(layer "In13.Cu")
		(net "P3E_PCH_M2_TX_DN<1>")
	)
	(segment
		(start 341.918798 -44.691046)
		(end 342.190578 -45.160946)
		(width 0.13208)
		(layer "F.Cu")
		(net "P3E_PCH_M2_TX_DN<0>")
	)
	(segment
		(start 342.190578 -45.160946)
		(end 342.19134 -45.160946)
		(width 0.13208)
		(layer "F.Cu")
		(net "P3E_PCH_M2_TX_DN<0>")
	)
	(segment
		(start 181.130702 -53.401468)
		(end 180.795168 -53.065934)
		(width 0.13208)
		(layer "F.Cu")
		(net "P3E_PCH_M2_TX_DN<0>")
	)
	(segment
		(start 182.041292 -53.117496)
		(end 181.75732 -53.401468)
		(width 0.13208)
		(layer "F.Cu")
		(net "P3E_PCH_M2_TX_DN<0>")
	)
	(segment
		(start 182.041292 -53.091334)
		(end 182.041292 -53.117496)
		(width 0.13208)
		(layer "F.Cu")
		(net "P3E_PCH_M2_TX_DN<0>")
	)
	(segment
		(start 181.75732 -53.401468)
		(end 181.130702 -53.401468)
		(width 0.13208)
		(layer "F.Cu")
		(net "P3E_PCH_M2_TX_DN<0>")
	)
	(segment
		(start 341.583772 -42.637202)
		(end 341.591392 -42.623994)
		(width 0.0889)
		(layer "In13.Cu")
		(net "P3E_PCH_M2_TX_DN<0>")
	)
	(segment
		(start 343.54897 -41.496742)
		(end 343.57818 -41.496488)
		(width 0.0889)
		(layer "In13.Cu")
		(net "P3E_PCH_M2_TX_DN<0>")
	)
	(segment
		(start 344.049096 -39.308278)
		(end 344.049096 -39.28618)
		(width 0.0889)
		(layer "In13.Cu")
		(net "P3E_PCH_M2_TX_DN<0>")
	)
	(segment
		(start 341.67191 -44.833794)
		(end 341.550244 -44.801028)
		(width 0.0889)
		(layer "In13.Cu")
		(net "P3E_PCH_M2_TX_DN<0>")
	)
	(segment
		(start 330.0222 -22.431248)
		(end 328.164952 -22.431248)
		(width 0.14732)
		(layer "In13.Cu")
		(net "P3E_PCH_M2_TX_DN<0>")
	)
	(segment
		(start 344.049096 -38.963854)
		(end 341.88527 -36.800028)
		(width 0.14732)
		(layer "In13.Cu")
		(net "P3E_PCH_M2_TX_DN<0>")
	)
	(segment
		(start 342.734646 -41.966896)
		(end 342.769444 -41.966642)
		(width 0.0889)
		(layer "In13.Cu")
		(net "P3E_PCH_M2_TX_DN<0>")
	)
	(segment
		(start 319.729866 -19.581622)
		(end 310.742838 -21.812504)
		(width 0.14732)
		(layer "In13.Cu")
		(net "P3E_PCH_M2_TX_DN<0>")
	)
	(segment
		(start 344.046048 -40.662606)
		(end 344.03792 -40.64889)
		(width 0.0889)
		(layer "In13.Cu")
		(net "P3E_PCH_M2_TX_DN<0>")
	)
	(segment
		(start 275.908262 -57.665112)
		(end 270.735044 -61.286898)
		(width 0.14732)
		(layer "In13.Cu")
		(net "P3E_PCH_M2_TX_DN<0>")
	)
	(segment
		(start 279.878536 -53.695092)
		(end 277.893526 -55.680102)
		(width 0.14732)
		(layer "In13.Cu")
		(net "P3E_PCH_M2_TX_DN<0>")
	)
	(segment
		(start 341.46236 -44.649136)
		(end 341.46236 -43.840908)
		(width 0.0889)
		(layer "In13.Cu")
		(net "P3E_PCH_M2_TX_DN<0>")
	)
	(segment
		(start 341.918798 -44.691046)
		(end 341.67191 -44.833794)
		(width 0.0889)
		(layer "In13.Cu")
		(net "P3E_PCH_M2_TX_DN<0>")
	)
	(segment
		(start 341.582502 -42.639742)
		(end 341.583772 -42.637202)
		(width 0.0889)
		(layer "In13.Cu")
		(net "P3E_PCH_M2_TX_DN<0>")
	)
	(segment
		(start 197.323964 -59.57443)
		(end 184.81675 -53.624988)
		(width 0.14732)
		(layer "In13.Cu")
		(net "P3E_PCH_M2_TX_DN<0>")
	)
	(segment
		(start 299.582586 -29.629354)
		(end 299.582332 -29.629608)
		(width 0.14732)
		(layer "In13.Cu")
		(net "P3E_PCH_M2_TX_DN<0>")
	)
	(segment
		(start 337.058 -29.899356)
		(end 331.0128 -23.854156)
		(width 0.14732)
		(layer "In13.Cu")
		(net "P3E_PCH_M2_TX_DN<0>")
	)
	(segment
		(start 328.164952 -22.431248)
		(end 325.315326 -19.581622)
		(width 0.14732)
		(layer "In13.Cu")
		(net "P3E_PCH_M2_TX_DN<0>")
	)
	(segment
		(start 183.461152 -53.385974)
		(end 182.335932 -53.385974)
		(width 0.14732)
		(layer "In13.Cu")
		(net "P3E_PCH_M2_TX_DN<0>")
	)
	(segment
		(start 310.742838 -21.812504)
		(end 299.582586 -29.629354)
		(width 0.14732)
		(layer "In13.Cu")
		(net "P3E_PCH_M2_TX_DN<0>")
	)
	(segment
		(start 344.007186 -39.350188)
		(end 344.049096 -39.308278)
		(width 0.0889)
		(layer "In13.Cu")
		(net "P3E_PCH_M2_TX_DN<0>")
	)
	(segment
		(start 337.058 -33.546796)
		(end 337.058 -29.899356)
		(width 0.14732)
		(layer "In13.Cu")
		(net "P3E_PCH_M2_TX_DN<0>")
	)
	(segment
		(start 331.0128 -23.854156)
		(end 331.0128 -23.421848)
		(width 0.14732)
		(layer "In13.Cu")
		(net "P3E_PCH_M2_TX_DN<0>")
	)
	(segment
		(start 297.110404 -33.159954)
		(end 279.878536 -53.695092)
		(width 0.14732)
		(layer "In13.Cu")
		(net "P3E_PCH_M2_TX_DN<0>")
	)
	(segment
		(start 341.874602 -42.436796)
		(end 341.956898 -42.436796)
		(width 0.0889)
		(layer "In13.Cu")
		(net "P3E_PCH_M2_TX_DN<0>")
	)
	(segment
		(start 344.049096 -39.28618)
		(end 344.049096 -38.963854)
		(width 0.14732)
		(layer "In13.Cu")
		(net "P3E_PCH_M2_TX_DN<0>")
	)
	(segment
		(start 341.46236 -43.840908)
		(end 341.546942 -43.637708)
		(width 0.0889)
		(layer "In13.Cu")
		(net "P3E_PCH_M2_TX_DN<0>")
	)
	(segment
		(start 184.81675 -53.624988)
		(end 183.461152 -53.385974)
		(width 0.14732)
		(layer "In13.Cu")
		(net "P3E_PCH_M2_TX_DN<0>")
	)
	(segment
		(start 343.525602 -41.496742)
		(end 343.54897 -41.496742)
		(width 0.0889)
		(layer "In13.Cu")
		(net "P3E_PCH_M2_TX_DN<0>")
	)
	(segment
		(start 244.947186 -65.833752)
		(end 235.274104 -66.265298)
		(width 0.14732)
		(layer "In13.Cu")
		(net "P3E_PCH_M2_TX_DN<0>")
	)
	(segment
		(start 277.893526 -55.680356)
		(end 275.908262 -57.665112)
		(width 0.14732)
		(layer "In13.Cu")
		(net "P3E_PCH_M2_TX_DN<0>")
	)
	(segment
		(start 344.007186 -39.486078)
		(end 344.007186 -39.350188)
		(width 0.0889)
		(layer "In13.Cu")
		(net "P3E_PCH_M2_TX_DN<0>")
	)
	(segment
		(start 331.0128 -23.421848)
		(end 330.0222 -22.431248)
		(width 0.14732)
		(layer "In13.Cu")
		(net "P3E_PCH_M2_TX_DN<0>")
	)
	(segment
		(start 299.582332 -29.629608)
		(end 297.110404 -33.159954)
		(width 0.14732)
		(layer "In13.Cu")
		(net "P3E_PCH_M2_TX_DN<0>")
	)
	(segment
		(start 325.315326 -19.581622)
		(end 319.729866 -19.581622)
		(width 0.14732)
		(layer "In13.Cu")
		(net "P3E_PCH_M2_TX_DN<0>")
	)
	(segment
		(start 342.707468 -41.966896)
		(end 342.734646 -41.966896)
		(width 0.0889)
		(layer "In13.Cu")
		(net "P3E_PCH_M2_TX_DN<0>")
	)
	(segment
		(start 344.03792 -40.64889)
		(end 344.03157 -40.637968)
		(width 0.0889)
		(layer "In13.Cu")
		(net "P3E_PCH_M2_TX_DN<0>")
	)
	(segment
		(start 235.274104 -66.265298)
		(end 197.323964 -59.57443)
		(width 0.14732)
		(layer "In13.Cu")
		(net "P3E_PCH_M2_TX_DN<0>")
	)
	(segment
		(start 182.335932 -53.385974)
		(end 182.041292 -53.091334)
		(width 0.14732)
		(layer "In13.Cu")
		(net "P3E_PCH_M2_TX_DN<0>")
	)
	(segment
		(start 344.037666 -40.274494)
		(end 344.133424 -40.108632)
		(width 0.0889)
		(layer "In13.Cu")
		(net "P3E_PCH_M2_TX_DN<0>")
	)
	(segment
		(start 277.893526 -55.680102)
		(end 277.893526 -55.680356)
		(width 0.14732)
		(layer "In13.Cu")
		(net "P3E_PCH_M2_TX_DN<0>")
	)
	(segment
		(start 341.550244 -44.801028)
		(end 341.46236 -44.649136)
		(width 0.0889)
		(layer "In13.Cu")
		(net "P3E_PCH_M2_TX_DN<0>")
	)
	(segment
		(start 341.88527 -36.800028)
		(end 340.311232 -36.800028)
		(width 0.14732)
		(layer "In13.Cu")
		(net "P3E_PCH_M2_TX_DN<0>")
	)
	(segment
		(start 270.735044 -61.286898)
		(end 244.947186 -65.833752)
		(width 0.14732)
		(layer "In13.Cu")
		(net "P3E_PCH_M2_TX_DN<0>")
	)
	(segment
		(start 340.311232 -36.800028)
		(end 337.058 -33.546796)
		(width 0.14732)
		(layer "In13.Cu")
		(net "P3E_PCH_M2_TX_DN<0>")
	)
	(arc
		(start 341.590884 -42.998898)
		(mid 341.541192 -42.820367)
		(end 341.582502 -42.639742)
		(width 0.0889)
		(layer "In13.Cu")
		(net "P3E_PCH_M2_TX_DN<0>")
	)
	(arc
		(start 343.57818 -41.496488)
		(mid 343.844036 -41.413809)
		(end 344.038174 -41.214294)
		(width 0.0889)
		(layer "In13.Cu")
		(net "P3E_PCH_M2_TX_DN<0>")
	)
	(arc
		(start 344.038174 -41.214294)
		(mid 344.113917 -40.939467)
		(end 344.046048 -40.662606)
		(width 0.0889)
		(layer "In13.Cu")
		(net "P3E_PCH_M2_TX_DN<0>")
	)
	(arc
		(start 342.40978 -42.154094)
		(mid 342.535355 -42.0235)
		(end 342.707468 -41.966896)
		(width 0.0889)
		(layer "In13.Cu")
		(net "P3E_PCH_M2_TX_DN<0>")
	)
	(arc
		(start 341.546942 -43.637708)
		(mid 341.552949 -43.624893)
		(end 341.559896 -43.612562)
		(width 0.0889)
		(layer "In13.Cu")
		(net "P3E_PCH_M2_TX_DN<0>")
	)
	(arc
		(start 344.06332 -39.691056)
		(mid 344.02158 -39.592306)
		(end 344.007186 -39.486078)
		(width 0.0889)
		(layer "In13.Cu")
		(net "P3E_PCH_M2_TX_DN<0>")
	)
	(arc
		(start 341.591138 -43.56354)
		(mid 341.666087 -43.281173)
		(end 341.590884 -42.998898)
		(width 0.0889)
		(layer "In13.Cu")
		(net "P3E_PCH_M2_TX_DN<0>")
	)
	(arc
		(start 344.03157 -40.637968)
		(mid 343.987605 -40.455438)
		(end 344.037666 -40.274494)
		(width 0.0889)
		(layer "In13.Cu")
		(net "P3E_PCH_M2_TX_DN<0>")
	)
	(arc
		(start 343.224104 -41.684194)
		(mid 343.351298 -41.552588)
		(end 343.525602 -41.496742)
		(width 0.0889)
		(layer "In13.Cu")
		(net "P3E_PCH_M2_TX_DN<0>")
	)
	(arc
		(start 341.591392 -42.623994)
		(mid 341.710747 -42.496728)
		(end 341.874602 -42.436796)
		(width 0.0889)
		(layer "In13.Cu")
		(net "P3E_PCH_M2_TX_DN<0>")
	)
	(arc
		(start 344.133424 -40.108632)
		(mid 344.136622 -39.893423)
		(end 344.06332 -39.691056)
		(width 0.0889)
		(layer "In13.Cu")
		(net "P3E_PCH_M2_TX_DN<0>")
	)
	(arc
		(start 342.769444 -41.966642)
		(mid 343.032287 -41.882573)
		(end 343.224104 -41.684194)
		(width 0.0889)
		(layer "In13.Cu")
		(net "P3E_PCH_M2_TX_DN<0>")
	)
	(arc
		(start 341.956898 -42.436796)
		(mid 342.218736 -42.352149)
		(end 342.40978 -42.154094)
		(width 0.0889)
		(layer "In13.Cu")
		(net "P3E_PCH_M2_TX_DN<0>")
	)
	(arc
		(start 341.559896 -43.612562)
		(mid 341.576143 -43.58845)
		(end 341.591138 -43.56354)
		(width 0.0889)
		(layer "In13.Cu")
		(net "P3E_PCH_M2_TX_DN<0>")
	)
	(segment
		(start 177.108104 -44.800012)
		(end 177.749962 -44.800012)
		(width 0.13208)
		(layer "F.Cu")
		(net "P3E_PCH_M2_TX_C_DP<3>")
	)
	(segment
		(start 177.749962 -44.800012)
		(end 177.870612 -44.679362)
		(width 0.13208)
		(layer "F.Cu")
		(net "P3E_PCH_M2_TX_C_DP<3>")
	)
	(segment
		(start 177.870612 -44.679362)
		(end 179.935632 -44.679362)
		(width 0.13208)
		(layer "F.Cu")
		(net "P3E_PCH_M2_TX_C_DP<3>")
	)
	(segment
		(start 179.935632 -44.679362)
		(end 180.261768 -45.005498)
		(width 0.13208)
		(layer "F.Cu")
		(net "P3E_PCH_M2_TX_C_DP<3>")
	)
	(segment
		(start 177.868072 -47.679356)
		(end 177.747422 -47.800006)
		(width 0.13208)
		(layer "F.Cu")
		(net "P3E_PCH_M2_TX_C_DP<2>")
	)
	(segment
		(start 179.887626 -47.679356)
		(end 177.868072 -47.679356)
		(width 0.13208)
		(layer "F.Cu")
		(net "P3E_PCH_M2_TX_C_DP<2>")
	)
	(segment
		(start 180.261768 -48.053498)
		(end 179.887626 -47.679356)
		(width 0.13208)
		(layer "F.Cu")
		(net "P3E_PCH_M2_TX_C_DP<2>")
	)
	(segment
		(start 177.747422 -47.800006)
		(end 177.108104 -47.800006)
		(width 0.13208)
		(layer "F.Cu")
		(net "P3E_PCH_M2_TX_C_DP<2>")
	)
	(segment
		(start 177.865532 -50.67935)
		(end 179.96662 -50.67935)
		(width 0.13208)
		(layer "F.Cu")
		(net "P3E_PCH_M2_TX_C_DP<1>")
	)
	(segment
		(start 177.744882 -50.8)
		(end 177.865532 -50.67935)
		(width 0.13208)
		(layer "F.Cu")
		(net "P3E_PCH_M2_TX_C_DP<1>")
	)
	(segment
		(start 177.108104 -50.8)
		(end 177.744882 -50.8)
		(width 0.13208)
		(layer "F.Cu")
		(net "P3E_PCH_M2_TX_C_DP<1>")
	)
	(segment
		(start 179.96662 -50.67935)
		(end 180.261768 -50.974498)
		(width 0.13208)
		(layer "F.Cu")
		(net "P3E_PCH_M2_TX_C_DP<1>")
	)
	(segment
		(start 179.960778 -53.679344)
		(end 180.261768 -53.980334)
		(width 0.13208)
		(layer "F.Cu")
		(net "P3E_PCH_M2_TX_C_DP<0>")
	)
	(segment
		(start 177.862484 -53.679344)
		(end 179.960778 -53.679344)
		(width 0.13208)
		(layer "F.Cu")
		(net "P3E_PCH_M2_TX_C_DP<0>")
	)
	(segment
		(start 177.741834 -53.799994)
		(end 177.862484 -53.679344)
		(width 0.13208)
		(layer "F.Cu")
		(net "P3E_PCH_M2_TX_C_DP<0>")
	)
	(segment
		(start 177.108104 -53.799994)
		(end 177.741834 -53.799994)
		(width 0.13208)
		(layer "F.Cu")
		(net "P3E_PCH_M2_TX_C_DP<0>")
	)
	(segment
		(start 177.108104 -44.299886)
		(end 177.766472 -44.299886)
		(width 0.13208)
		(layer "F.Cu")
		(net "P3E_PCH_M2_TX_C_DN<3>")
	)
	(segment
		(start 177.766472 -44.299886)
		(end 177.886868 -44.420282)
		(width 0.13208)
		(layer "F.Cu")
		(net "P3E_PCH_M2_TX_C_DN<3>")
	)
	(segment
		(start 177.886868 -44.420282)
		(end 179.932584 -44.420282)
		(width 0.13208)
		(layer "F.Cu")
		(net "P3E_PCH_M2_TX_C_DN<3>")
	)
	(segment
		(start 179.932584 -44.420282)
		(end 180.261768 -44.091098)
		(width 0.13208)
		(layer "F.Cu")
		(net "P3E_PCH_M2_TX_C_DN<3>")
	)
	(segment
		(start 177.889408 -47.420276)
		(end 179.98948 -47.420276)
		(width 0.13208)
		(layer "F.Cu")
		(net "P3E_PCH_M2_TX_C_DN<2>")
	)
	(segment
		(start 177.769012 -47.29988)
		(end 177.889408 -47.420276)
		(width 0.13208)
		(layer "F.Cu")
		(net "P3E_PCH_M2_TX_C_DN<2>")
	)
	(segment
		(start 177.108104 -47.29988)
		(end 177.769012 -47.29988)
		(width 0.13208)
		(layer "F.Cu")
		(net "P3E_PCH_M2_TX_C_DN<2>")
	)
	(segment
		(start 180.261768 -47.147988)
		(end 180.261768 -47.139098)
		(width 0.13208)
		(layer "F.Cu")
		(net "P3E_PCH_M2_TX_C_DN<2>")
	)
	(segment
		(start 179.98948 -47.420276)
		(end 180.261768 -47.147988)
		(width 0.13208)
		(layer "F.Cu")
		(net "P3E_PCH_M2_TX_C_DN<2>")
	)
	(segment
		(start 177.891948 -50.42027)
		(end 179.901596 -50.42027)
		(width 0.13208)
		(layer "F.Cu")
		(net "P3E_PCH_M2_TX_C_DN<1>")
	)
	(segment
		(start 179.901596 -50.42027)
		(end 180.261768 -50.060098)
		(width 0.13208)
		(layer "F.Cu")
		(net "P3E_PCH_M2_TX_C_DN<1>")
	)
	(segment
		(start 177.108104 -50.299874)
		(end 177.771552 -50.299874)
		(width 0.13208)
		(layer "F.Cu")
		(net "P3E_PCH_M2_TX_C_DN<1>")
	)
	(segment
		(start 177.771552 -50.299874)
		(end 177.891948 -50.42027)
		(width 0.13208)
		(layer "F.Cu")
		(net "P3E_PCH_M2_TX_C_DN<1>")
	)
	(segment
		(start 179.907438 -53.420264)
		(end 180.261768 -53.065934)
		(width 0.13208)
		(layer "F.Cu")
		(net "P3E_PCH_M2_TX_C_DN<0>")
	)
	(segment
		(start 177.844196 -53.420264)
		(end 179.907438 -53.420264)
		(width 0.13208)
		(layer "F.Cu")
		(net "P3E_PCH_M2_TX_C_DN<0>")
	)
	(segment
		(start 177.108104 -53.299868)
		(end 177.7238 -53.299868)
		(width 0.13208)
		(layer "F.Cu")
		(net "P3E_PCH_M2_TX_C_DN<0>")
	)
	(segment
		(start 177.7238 -53.299868)
		(end 177.844196 -53.420264)
		(width 0.13208)
		(layer "F.Cu")
		(net "P3E_PCH_M2_TX_C_DN<0>")
	)
	(segment
		(start 351.51187 -49.177956)
		(end 351.66427 -49.177956)
		(width 0.0889)
		(layer "F.Cu")
		(net "P3E_PCH_M2_RX_DP<3>")
	)
	(segment
		(start 358.196642 -49.474628)
		(end 358.56037 -49.1109)
		(width 0.13208)
		(layer "F.Cu")
		(net "P3E_PCH_M2_RX_DP<3>")
	)
	(segment
		(start 352.27387 -49.076356)
		(end 352.42627 -49.076356)
		(width 0.0889)
		(layer "F.Cu")
		(net "P3E_PCH_M2_RX_DP<3>")
	)
	(segment
		(start 350.64827 -49.177956)
		(end 350.74987 -49.076356)
		(width 0.0889)
		(layer "F.Cu")
		(net "P3E_PCH_M2_RX_DP<3>")
	)
	(segment
		(start 349.63227 -49.177956)
		(end 349.73387 -49.076356)
		(width 0.0889)
		(layer "F.Cu")
		(net "P3E_PCH_M2_RX_DP<3>")
	)
	(segment
		(start 178.70932 -45.920406)
		(end 179.01158 -45.618146)
		(width 0.13208)
		(layer "F.Cu")
		(net "P3E_PCH_M2_RX_DP<3>")
	)
	(segment
		(start 351.66427 -49.177956)
		(end 351.76587 -49.076356)
		(width 0.0889)
		(layer "F.Cu")
		(net "P3E_PCH_M2_RX_DP<3>")
	)
	(segment
		(start 349.98787 -49.177956)
		(end 350.14027 -49.177956)
		(width 0.0889)
		(layer "F.Cu")
		(net "P3E_PCH_M2_RX_DP<3>")
	)
	(segment
		(start 356.385368 -49.076356)
		(end 356.749096 -49.440084)
		(width 0.0889)
		(layer "F.Cu")
		(net "P3E_PCH_M2_RX_DP<3>")
	)
	(segment
		(start 351.00387 -49.177956)
		(end 351.15627 -49.177956)
		(width 0.0889)
		(layer "F.Cu")
		(net "P3E_PCH_M2_RX_DP<3>")
	)
	(segment
		(start 350.39427 -49.076356)
		(end 350.49587 -49.177956)
		(width 0.0889)
		(layer "F.Cu")
		(net "P3E_PCH_M2_RX_DP<3>")
	)
	(segment
		(start 350.90227 -49.076356)
		(end 351.00387 -49.177956)
		(width 0.0889)
		(layer "F.Cu")
		(net "P3E_PCH_M2_RX_DP<3>")
	)
	(segment
		(start 356.749096 -49.440084)
		(end 357.194358 -49.440084)
		(width 0.0889)
		(layer "F.Cu")
		(net "P3E_PCH_M2_RX_DP<3>")
	)
	(segment
		(start 362.02366 -47.112682)
		(end 362.33354 -46.802802)
		(width 0.13208)
		(layer "F.Cu")
		(net "P3E_PCH_M2_RX_DP<3>")
	)
	(segment
		(start 350.49587 -49.177956)
		(end 350.64827 -49.177956)
		(width 0.0889)
		(layer "F.Cu")
		(net "P3E_PCH_M2_RX_DP<3>")
	)
	(segment
		(start 352.52787 -49.177956)
		(end 352.68027 -49.177956)
		(width 0.0889)
		(layer "F.Cu")
		(net "P3E_PCH_M2_RX_DP<3>")
	)
	(segment
		(start 351.41027 -49.076356)
		(end 351.51187 -49.177956)
		(width 0.0889)
		(layer "F.Cu")
		(net "P3E_PCH_M2_RX_DP<3>")
	)
	(segment
		(start 352.68027 -49.177956)
		(end 352.78187 -49.076356)
		(width 0.0889)
		(layer "F.Cu")
		(net "P3E_PCH_M2_RX_DP<3>")
	)
	(segment
		(start 357.194358 -49.440084)
		(end 357.228902 -49.474628)
		(width 0.0889)
		(layer "F.Cu")
		(net "P3E_PCH_M2_RX_DP<3>")
	)
	(segment
		(start 357.228902 -49.474628)
		(end 357.251 -49.474628)
		(width 0.0889)
		(layer "F.Cu")
		(net "P3E_PCH_M2_RX_DP<3>")
	)
	(segment
		(start 358.56037 -49.1109)
		(end 360.45013 -49.1109)
		(width 0.13208)
		(layer "F.Cu")
		(net "P3E_PCH_M2_RX_DP<3>")
	)
	(segment
		(start 351.76587 -49.076356)
		(end 351.91827 -49.076356)
		(width 0.0889)
		(layer "F.Cu")
		(net "P3E_PCH_M2_RX_DP<3>")
	)
	(segment
		(start 349.73387 -49.076356)
		(end 349.88627 -49.076356)
		(width 0.0889)
		(layer "F.Cu")
		(net "P3E_PCH_M2_RX_DP<3>")
	)
	(segment
		(start 351.25787 -49.076356)
		(end 351.41027 -49.076356)
		(width 0.0889)
		(layer "F.Cu")
		(net "P3E_PCH_M2_RX_DP<3>")
	)
	(segment
		(start 352.42627 -49.076356)
		(end 352.52787 -49.177956)
		(width 0.0889)
		(layer "F.Cu")
		(net "P3E_PCH_M2_RX_DP<3>")
	)
	(segment
		(start 349.47987 -49.177956)
		(end 349.63227 -49.177956)
		(width 0.0889)
		(layer "F.Cu")
		(net "P3E_PCH_M2_RX_DP<3>")
	)
	(segment
		(start 357.251 -49.474628)
		(end 358.196642 -49.474628)
		(width 0.13208)
		(layer "F.Cu")
		(net "P3E_PCH_M2_RX_DP<3>")
	)
	(segment
		(start 347.007688 -49.450498)
		(end 347.011752 -49.446434)
		(width 0.0889)
		(layer "F.Cu")
		(net "P3E_PCH_M2_RX_DP<3>")
	)
	(segment
		(start 346.799662 -49.450498)
		(end 347.007688 -49.450498)
		(width 0.0889)
		(layer "F.Cu")
		(net "P3E_PCH_M2_RX_DP<3>")
	)
	(segment
		(start 350.74987 -49.076356)
		(end 350.90227 -49.076356)
		(width 0.0889)
		(layer "F.Cu")
		(net "P3E_PCH_M2_RX_DP<3>")
	)
	(segment
		(start 350.24187 -49.076356)
		(end 350.39427 -49.076356)
		(width 0.0889)
		(layer "F.Cu")
		(net "P3E_PCH_M2_RX_DP<3>")
	)
	(segment
		(start 349.22587 -49.076356)
		(end 349.37827 -49.076356)
		(width 0.0889)
		(layer "F.Cu")
		(net "P3E_PCH_M2_RX_DP<3>")
	)
	(segment
		(start 352.17227 -49.177956)
		(end 352.27387 -49.076356)
		(width 0.0889)
		(layer "F.Cu")
		(net "P3E_PCH_M2_RX_DP<3>")
	)
	(segment
		(start 349.37827 -49.076356)
		(end 349.47987 -49.177956)
		(width 0.0889)
		(layer "F.Cu")
		(net "P3E_PCH_M2_RX_DP<3>")
	)
	(segment
		(start 346.799662 -49.450752)
		(end 346.799662 -49.450498)
		(width 0.0889)
		(layer "F.Cu")
		(net "P3E_PCH_M2_RX_DP<3>")
	)
	(segment
		(start 347.011752 -49.446434)
		(end 348.855792 -49.446434)
		(width 0.0889)
		(layer "F.Cu")
		(net "P3E_PCH_M2_RX_DP<3>")
	)
	(segment
		(start 360.45013 -49.1109)
		(end 362.02366 -47.53737)
		(width 0.13208)
		(layer "F.Cu")
		(net "P3E_PCH_M2_RX_DP<3>")
	)
	(segment
		(start 352.01987 -49.177956)
		(end 352.17227 -49.177956)
		(width 0.0889)
		(layer "F.Cu")
		(net "P3E_PCH_M2_RX_DP<3>")
	)
	(segment
		(start 352.78187 -49.076356)
		(end 356.385368 -49.076356)
		(width 0.0889)
		(layer "F.Cu")
		(net "P3E_PCH_M2_RX_DP<3>")
	)
	(segment
		(start 349.88627 -49.076356)
		(end 349.98787 -49.177956)
		(width 0.0889)
		(layer "F.Cu")
		(net "P3E_PCH_M2_RX_DP<3>")
	)
	(segment
		(start 362.02366 -47.53737)
		(end 362.02366 -47.112682)
		(width 0.13208)
		(layer "F.Cu")
		(net "P3E_PCH_M2_RX_DP<3>")
	)
	(segment
		(start 350.14027 -49.177956)
		(end 350.24187 -49.076356)
		(width 0.0889)
		(layer "F.Cu")
		(net "P3E_PCH_M2_RX_DP<3>")
	)
	(segment
		(start 177.82032 -45.920406)
		(end 178.70932 -45.920406)
		(width 0.13208)
		(layer "F.Cu")
		(net "P3E_PCH_M2_RX_DP<3>")
	)
	(segment
		(start 177.108104 -45.80001)
		(end 177.699924 -45.80001)
		(width 0.13208)
		(layer "F.Cu")
		(net "P3E_PCH_M2_RX_DP<3>")
	)
	(segment
		(start 348.855792 -49.446434)
		(end 349.22587 -49.076356)
		(width 0.0889)
		(layer "F.Cu")
		(net "P3E_PCH_M2_RX_DP<3>")
	)
	(segment
		(start 351.15627 -49.177956)
		(end 351.25787 -49.076356)
		(width 0.0889)
		(layer "F.Cu")
		(net "P3E_PCH_M2_RX_DP<3>")
	)
	(segment
		(start 351.91827 -49.076356)
		(end 352.01987 -49.177956)
		(width 0.0889)
		(layer "F.Cu")
		(net "P3E_PCH_M2_RX_DP<3>")
	)
	(segment
		(start 177.699924 -45.80001)
		(end 177.82032 -45.920406)
		(width 0.13208)
		(layer "F.Cu")
		(net "P3E_PCH_M2_RX_DP<3>")
	)
	(segment
		(start 235.106718 -63.377318)
		(end 203.402946 -57.787286)
		(width 0.14732)
		(layer "In15.Cu")
		(net "P3E_PCH_M2_RX_DP<3>")
	)
	(segment
		(start 363.765846 -29.385514)
		(end 352.6028 -18.222468)
		(width 0.14732)
		(layer "In15.Cu")
		(net "P3E_PCH_M2_RX_DP<3>")
	)
	(segment
		(start 352.6028 -18.222468)
		(end 331.520292 -18.222468)
		(width 0.14732)
		(layer "In15.Cu")
		(net "P3E_PCH_M2_RX_DP<3>")
	)
	(segment
		(start 362.33354 -46.802802)
		(end 362.0389 -46.508162)
		(width 0.14732)
		(layer "In15.Cu")
		(net "P3E_PCH_M2_RX_DP<3>")
	)
	(segment
		(start 330.235052 -16.937228)
		(end 318.017906 -16.937228)
		(width 0.14732)
		(layer "In15.Cu")
		(net "P3E_PCH_M2_RX_DP<3>")
	)
	(segment
		(start 203.402946 -57.787286)
		(end 185.019188 -47.48149)
		(width 0.14732)
		(layer "In15.Cu")
		(net "P3E_PCH_M2_RX_DP<3>")
	)
	(segment
		(start 270.022574 -58.038238)
		(end 241.787426 -63.016638)
		(width 0.14732)
		(layer "In15.Cu")
		(net "P3E_PCH_M2_RX_DP<3>")
	)
	(segment
		(start 274.05838 -55.21198)
		(end 273.049492 -55.918608)
		(width 0.14732)
		(layer "In15.Cu")
		(net "P3E_PCH_M2_RX_DP<3>")
	)
	(segment
		(start 294.802306 -24.638508)
		(end 274.05838 -55.21198)
		(width 0.14732)
		(layer "In15.Cu")
		(net "P3E_PCH_M2_RX_DP<3>")
	)
	(segment
		(start 183.21528 -46.218348)
		(end 181.482492 -45.912786)
		(width 0.14732)
		(layer "In15.Cu")
		(net "P3E_PCH_M2_RX_DP<3>")
	)
	(segment
		(start 363.765846 -44.364402)
		(end 363.765846 -29.385514)
		(width 0.14732)
		(layer "In15.Cu")
		(net "P3E_PCH_M2_RX_DP<3>")
	)
	(segment
		(start 181.482492 -45.912786)
		(end 179.30622 -45.912786)
		(width 0.14732)
		(layer "In15.Cu")
		(net "P3E_PCH_M2_RX_DP<3>")
	)
	(segment
		(start 185.019188 -47.48149)
		(end 183.21528 -46.218348)
		(width 0.14732)
		(layer "In15.Cu")
		(net "P3E_PCH_M2_RX_DP<3>")
	)
	(segment
		(start 179.30622 -45.912786)
		(end 179.01158 -45.618146)
		(width 0.14732)
		(layer "In15.Cu")
		(net "P3E_PCH_M2_RX_DP<3>")
	)
	(segment
		(start 241.787426 -63.016638)
		(end 235.106718 -63.377318)
		(width 0.14732)
		(layer "In15.Cu")
		(net "P3E_PCH_M2_RX_DP<3>")
	)
	(segment
		(start 362.0389 -46.091348)
		(end 363.765846 -44.364402)
		(width 0.14732)
		(layer "In15.Cu")
		(net "P3E_PCH_M2_RX_DP<3>")
	)
	(segment
		(start 273.049492 -55.918608)
		(end 270.022574 -58.038238)
		(width 0.14732)
		(layer "In15.Cu")
		(net "P3E_PCH_M2_RX_DP<3>")
	)
	(segment
		(start 318.017906 -16.937228)
		(end 299.02277 -21.569172)
		(width 0.14732)
		(layer "In15.Cu")
		(net "P3E_PCH_M2_RX_DP<3>")
	)
	(segment
		(start 362.0389 -46.508162)
		(end 362.0389 -46.091348)
		(width 0.14732)
		(layer "In15.Cu")
		(net "P3E_PCH_M2_RX_DP<3>")
	)
	(segment
		(start 331.520292 -18.222468)
		(end 330.235052 -16.937228)
		(width 0.14732)
		(layer "In15.Cu")
		(net "P3E_PCH_M2_RX_DP<3>")
	)
	(segment
		(start 299.02277 -21.569172)
		(end 294.802306 -24.638508)
		(width 0.14732)
		(layer "In15.Cu")
		(net "P3E_PCH_M2_RX_DP<3>")
	)
	(segment
		(start 359.70464 -47.105062)
		(end 360.0069 -46.802802)
		(width 0.13208)
		(layer "F.Cu")
		(net "P3E_PCH_M2_RX_DP<2>")
	)
	(segment
		(start 359.37698 -47.921926)
		(end 359.70464 -47.594266)
		(width 0.13208)
		(layer "F.Cu")
		(net "P3E_PCH_M2_RX_DP<2>")
	)
	(segment
		(start 177.82032 -48.9204)
		(end 178.70932 -48.9204)
		(width 0.13208)
		(layer "F.Cu")
		(net "P3E_PCH_M2_RX_DP<2>")
	)
	(segment
		(start 349.377508 -48.635158)
		(end 349.529908 -48.635158)
		(width 0.0889)
		(layer "F.Cu")
		(net "P3E_PCH_M2_RX_DP<2>")
	)
	(segment
		(start 351.368868 -48.635158)
		(end 351.521268 -48.635158)
		(width 0.0889)
		(layer "F.Cu")
		(net "P3E_PCH_M2_RX_DP<2>")
	)
	(segment
		(start 350.276668 -48.538638)
		(end 350.373188 -48.635158)
		(width 0.0889)
		(layer "F.Cu")
		(net "P3E_PCH_M2_RX_DP<2>")
	)
	(segment
		(start 350.774508 -48.538638)
		(end 350.871028 -48.635158)
		(width 0.0889)
		(layer "F.Cu")
		(net "P3E_PCH_M2_RX_DP<2>")
	)
	(segment
		(start 351.770188 -48.538638)
		(end 351.866708 -48.635158)
		(width 0.0889)
		(layer "F.Cu")
		(net "P3E_PCH_M2_RX_DP<2>")
	)
	(segment
		(start 350.124268 -48.538638)
		(end 350.276668 -48.538638)
		(width 0.0889)
		(layer "F.Cu")
		(net "P3E_PCH_M2_RX_DP<2>")
	)
	(segment
		(start 357.75265 -48.538638)
		(end 358.221026 -48.070262)
		(width 0.0889)
		(layer "F.Cu")
		(net "P3E_PCH_M2_RX_DP<2>")
	)
	(segment
		(start 351.119948 -48.538638)
		(end 351.272348 -48.538638)
		(width 0.0889)
		(layer "F.Cu")
		(net "P3E_PCH_M2_RX_DP<2>")
	)
	(segment
		(start 347.30055 -48.86452)
		(end 347.41104 -48.86452)
		(width 0.0889)
		(layer "F.Cu")
		(net "P3E_PCH_M2_RX_DP<2>")
	)
	(segment
		(start 347.41104 -48.86452)
		(end 347.490542 -48.944022)
		(width 0.0889)
		(layer "F.Cu")
		(net "P3E_PCH_M2_RX_DP<2>")
	)
	(segment
		(start 349.626428 -48.538638)
		(end 349.778828 -48.538638)
		(width 0.0889)
		(layer "F.Cu")
		(net "P3E_PCH_M2_RX_DP<2>")
	)
	(segment
		(start 351.617788 -48.538638)
		(end 351.770188 -48.538638)
		(width 0.0889)
		(layer "F.Cu")
		(net "P3E_PCH_M2_RX_DP<2>")
	)
	(segment
		(start 347.490542 -48.944022)
		(end 348.723204 -48.944022)
		(width 0.0889)
		(layer "F.Cu")
		(net "P3E_PCH_M2_RX_DP<2>")
	)
	(segment
		(start 358.41813 -47.921926)
		(end 359.37698 -47.921926)
		(width 0.13208)
		(layer "F.Cu")
		(net "P3E_PCH_M2_RX_DP<2>")
	)
	(segment
		(start 352.516948 -48.635158)
		(end 352.613468 -48.538638)
		(width 0.0889)
		(layer "F.Cu")
		(net "P3E_PCH_M2_RX_DP<2>")
	)
	(segment
		(start 350.373188 -48.635158)
		(end 350.525588 -48.635158)
		(width 0.0889)
		(layer "F.Cu")
		(net "P3E_PCH_M2_RX_DP<2>")
	)
	(segment
		(start 352.019108 -48.635158)
		(end 352.115628 -48.538638)
		(width 0.0889)
		(layer "F.Cu")
		(net "P3E_PCH_M2_RX_DP<2>")
	)
	(segment
		(start 349.778828 -48.538638)
		(end 349.875348 -48.635158)
		(width 0.0889)
		(layer "F.Cu")
		(net "P3E_PCH_M2_RX_DP<2>")
	)
	(segment
		(start 349.875348 -48.635158)
		(end 350.027748 -48.635158)
		(width 0.0889)
		(layer "F.Cu")
		(net "P3E_PCH_M2_RX_DP<2>")
	)
	(segment
		(start 349.529908 -48.635158)
		(end 349.626428 -48.538638)
		(width 0.0889)
		(layer "F.Cu")
		(net "P3E_PCH_M2_RX_DP<2>")
	)
	(segment
		(start 350.027748 -48.635158)
		(end 350.124268 -48.538638)
		(width 0.0889)
		(layer "F.Cu")
		(net "P3E_PCH_M2_RX_DP<2>")
	)
	(segment
		(start 352.613468 -48.538638)
		(end 357.75265 -48.538638)
		(width 0.0889)
		(layer "F.Cu")
		(net "P3E_PCH_M2_RX_DP<2>")
	)
	(segment
		(start 351.272348 -48.538638)
		(end 351.368868 -48.635158)
		(width 0.0889)
		(layer "F.Cu")
		(net "P3E_PCH_M2_RX_DP<2>")
	)
	(segment
		(start 350.622108 -48.538638)
		(end 350.774508 -48.538638)
		(width 0.0889)
		(layer "F.Cu")
		(net "P3E_PCH_M2_RX_DP<2>")
	)
	(segment
		(start 348.723204 -48.944022)
		(end 349.128588 -48.538638)
		(width 0.0889)
		(layer "F.Cu")
		(net "P3E_PCH_M2_RX_DP<2>")
	)
	(segment
		(start 177.108104 -48.800004)
		(end 177.699924 -48.800004)
		(width 0.13208)
		(layer "F.Cu")
		(net "P3E_PCH_M2_RX_DP<2>")
	)
	(segment
		(start 349.280988 -48.538638)
		(end 349.377508 -48.635158)
		(width 0.0889)
		(layer "F.Cu")
		(net "P3E_PCH_M2_RX_DP<2>")
	)
	(segment
		(start 351.866708 -48.635158)
		(end 352.019108 -48.635158)
		(width 0.0889)
		(layer "F.Cu")
		(net "P3E_PCH_M2_RX_DP<2>")
	)
	(segment
		(start 358.285288 -48.054768)
		(end 358.41813 -47.921926)
		(width 0.13208)
		(layer "F.Cu")
		(net "P3E_PCH_M2_RX_DP<2>")
	)
	(segment
		(start 352.115628 -48.538638)
		(end 352.268028 -48.538638)
		(width 0.0889)
		(layer "F.Cu")
		(net "P3E_PCH_M2_RX_DP<2>")
	)
	(segment
		(start 351.023428 -48.635158)
		(end 351.119948 -48.538638)
		(width 0.0889)
		(layer "F.Cu")
		(net "P3E_PCH_M2_RX_DP<2>")
	)
	(segment
		(start 177.699924 -48.800004)
		(end 177.82032 -48.9204)
		(width 0.13208)
		(layer "F.Cu")
		(net "P3E_PCH_M2_RX_DP<2>")
	)
	(segment
		(start 351.521268 -48.635158)
		(end 351.617788 -48.538638)
		(width 0.0889)
		(layer "F.Cu")
		(net "P3E_PCH_M2_RX_DP<2>")
	)
	(segment
		(start 178.70932 -48.9204)
		(end 179.01158 -48.61814)
		(width 0.13208)
		(layer "F.Cu")
		(net "P3E_PCH_M2_RX_DP<2>")
	)
	(segment
		(start 352.268028 -48.538638)
		(end 352.364548 -48.635158)
		(width 0.0889)
		(layer "F.Cu")
		(net "P3E_PCH_M2_RX_DP<2>")
	)
	(segment
		(start 358.269794 -48.070262)
		(end 358.285288 -48.054768)
		(width 0.0889)
		(layer "F.Cu")
		(net "P3E_PCH_M2_RX_DP<2>")
	)
	(segment
		(start 349.128588 -48.538638)
		(end 349.280988 -48.538638)
		(width 0.0889)
		(layer "F.Cu")
		(net "P3E_PCH_M2_RX_DP<2>")
	)
	(segment
		(start 352.364548 -48.635158)
		(end 352.516948 -48.635158)
		(width 0.0889)
		(layer "F.Cu")
		(net "P3E_PCH_M2_RX_DP<2>")
	)
	(segment
		(start 358.221026 -48.070262)
		(end 358.269794 -48.070262)
		(width 0.0889)
		(layer "F.Cu")
		(net "P3E_PCH_M2_RX_DP<2>")
	)
	(segment
		(start 359.70464 -47.594266)
		(end 359.70464 -47.105062)
		(width 0.13208)
		(layer "F.Cu")
		(net "P3E_PCH_M2_RX_DP<2>")
	)
	(segment
		(start 350.871028 -48.635158)
		(end 351.023428 -48.635158)
		(width 0.0889)
		(layer "F.Cu")
		(net "P3E_PCH_M2_RX_DP<2>")
	)
	(segment
		(start 350.525588 -48.635158)
		(end 350.622108 -48.538638)
		(width 0.0889)
		(layer "F.Cu")
		(net "P3E_PCH_M2_RX_DP<2>")
	)
	(segment
		(start 347.214698 -48.950372)
		(end 347.30055 -48.86452)
		(width 0.0889)
		(layer "F.Cu")
		(net "P3E_PCH_M2_RX_DP<2>")
	)
	(segment
		(start 360.10088 -45.911008)
		(end 360.646472 -45.911008)
		(width 0.14732)
		(layer "In15.Cu")
		(net "P3E_PCH_M2_RX_DP<2>")
	)
	(segment
		(start 359.71226 -46.299628)
		(end 360.10088 -45.911008)
		(width 0.14732)
		(layer "In15.Cu")
		(net "P3E_PCH_M2_RX_DP<2>")
	)
	(segment
		(start 182.277766 -48.91278)
		(end 179.30622 -48.91278)
		(width 0.14732)
		(layer "In15.Cu")
		(net "P3E_PCH_M2_RX_DP<2>")
	)
	(segment
		(start 274.8534 -55.995062)
		(end 270.45285 -59.077098)
		(width 0.14732)
		(layer "In15.Cu")
		(net "P3E_PCH_M2_RX_DP<2>")
	)
	(segment
		(start 235.773214 -64.453008)
		(end 202.867768 -58.650886)
		(width 0.14732)
		(layer "In15.Cu")
		(net "P3E_PCH_M2_RX_DP<2>")
	)
	(segment
		(start 360.0069 -46.802802)
		(end 359.71226 -46.508162)
		(width 0.14732)
		(layer "In15.Cu")
		(net "P3E_PCH_M2_RX_DP<2>")
	)
	(segment
		(start 360.646472 -45.911008)
		(end 362.7374 -43.82008)
		(width 0.14732)
		(layer "In15.Cu")
		(net "P3E_PCH_M2_RX_DP<2>")
	)
	(segment
		(start 352.856292 -20.297648)
		(end 336.926428 -20.297648)
		(width 0.14732)
		(layer "In15.Cu")
		(net "P3E_PCH_M2_RX_DP<2>")
	)
	(segment
		(start 335.501488 -21.722588)
		(end 332.472792 -21.722588)
		(width 0.14732)
		(layer "In15.Cu")
		(net "P3E_PCH_M2_RX_DP<2>")
	)
	(segment
		(start 270.45285 -59.077098)
		(end 241.833654 -64.118998)
		(width 0.14732)
		(layer "In15.Cu")
		(net "P3E_PCH_M2_RX_DP<2>")
	)
	(segment
		(start 362.7374 -43.82008)
		(end 362.7374 -30.178756)
		(width 0.14732)
		(layer "In15.Cu")
		(net "P3E_PCH_M2_RX_DP<2>")
	)
	(segment
		(start 331.31506 -19.439636)
		(end 329.742292 -17.866868)
		(width 0.14732)
		(layer "In15.Cu")
		(net "P3E_PCH_M2_RX_DP<2>")
	)
	(segment
		(start 295.603168 -25.413716)
		(end 274.8534 -55.995062)
		(width 0.14732)
		(layer "In15.Cu")
		(net "P3E_PCH_M2_RX_DP<2>")
	)
	(segment
		(start 336.926428 -20.297648)
		(end 335.501488 -21.722588)
		(width 0.14732)
		(layer "In15.Cu")
		(net "P3E_PCH_M2_RX_DP<2>")
	)
	(segment
		(start 183.418226 -49.113948)
		(end 182.277766 -48.91278)
		(width 0.14732)
		(layer "In15.Cu")
		(net "P3E_PCH_M2_RX_DP<2>")
	)
	(segment
		(start 331.31506 -20.564856)
		(end 331.31506 -19.439636)
		(width 0.14732)
		(layer "In15.Cu")
		(net "P3E_PCH_M2_RX_DP<2>")
	)
	(segment
		(start 183.96458 -49.496218)
		(end 183.418226 -49.113948)
		(width 0.14732)
		(layer "In15.Cu")
		(net "P3E_PCH_M2_RX_DP<2>")
	)
	(segment
		(start 359.71226 -46.508162)
		(end 359.71226 -46.299628)
		(width 0.14732)
		(layer "In15.Cu")
		(net "P3E_PCH_M2_RX_DP<2>")
	)
	(segment
		(start 241.833654 -64.118998)
		(end 235.773214 -64.453008)
		(width 0.14732)
		(layer "In15.Cu")
		(net "P3E_PCH_M2_RX_DP<2>")
	)
	(segment
		(start 329.742292 -17.866868)
		(end 318.837564 -17.866868)
		(width 0.14732)
		(layer "In15.Cu")
		(net "P3E_PCH_M2_RX_DP<2>")
	)
	(segment
		(start 299.493178 -22.584156)
		(end 295.603168 -25.413716)
		(width 0.14732)
		(layer "In15.Cu")
		(net "P3E_PCH_M2_RX_DP<2>")
	)
	(segment
		(start 202.867768 -58.650886)
		(end 183.96458 -49.496218)
		(width 0.14732)
		(layer "In15.Cu")
		(net "P3E_PCH_M2_RX_DP<2>")
	)
	(segment
		(start 362.7374 -30.178756)
		(end 352.856292 -20.297648)
		(width 0.14732)
		(layer "In15.Cu")
		(net "P3E_PCH_M2_RX_DP<2>")
	)
	(segment
		(start 332.472792 -21.722588)
		(end 331.31506 -20.564856)
		(width 0.14732)
		(layer "In15.Cu")
		(net "P3E_PCH_M2_RX_DP<2>")
	)
	(segment
		(start 318.837564 -17.866868)
		(end 299.493178 -22.584156)
		(width 0.14732)
		(layer "In15.Cu")
		(net "P3E_PCH_M2_RX_DP<2>")
	)
	(segment
		(start 179.30622 -48.91278)
		(end 179.01158 -48.61814)
		(width 0.14732)
		(layer "In15.Cu")
		(net "P3E_PCH_M2_RX_DP<2>")
	)
	(segment
		(start 357.349552 -47.473616)
		(end 357.349552 -47.143416)
		(width 0.0889)
		(layer "F.Cu")
		(net "P3E_PCH_M2_RX_DP<1>")
	)
	(segment
		(start 349.481648 -48.104552)
		(end 349.580708 -48.005492)
		(width 0.0889)
		(layer "F.Cu")
		(net "P3E_PCH_M2_RX_DP<1>")
	)
	(segment
		(start 353.101148 -48.005492)
		(end 353.253548 -48.005492)
		(width 0.0889)
		(layer "F.Cu")
		(net "P3E_PCH_M2_RX_DP<1>")
	)
	(segment
		(start 353.352608 -48.104552)
		(end 353.505008 -48.104552)
		(width 0.0889)
		(layer "F.Cu")
		(net "P3E_PCH_M2_RX_DP<1>")
	)
	(segment
		(start 352.849688 -48.104552)
		(end 353.002088 -48.104552)
		(width 0.0889)
		(layer "F.Cu")
		(net "P3E_PCH_M2_RX_DP<1>")
	)
	(segment
		(start 349.077788 -48.005492)
		(end 349.230188 -48.005492)
		(width 0.0889)
		(layer "F.Cu")
		(net "P3E_PCH_M2_RX_DP<1>")
	)
	(segment
		(start 357.349552 -47.143416)
		(end 357.690166 -46.802802)
		(width 0.0889)
		(layer "F.Cu")
		(net "P3E_PCH_M2_RX_DP<1>")
	)
	(segment
		(start 350.335088 -48.104552)
		(end 350.487488 -48.104552)
		(width 0.0889)
		(layer "F.Cu")
		(net "P3E_PCH_M2_RX_DP<1>")
	)
	(segment
		(start 177.108104 -51.799998)
		(end 177.699924 -51.799998)
		(width 0.13208)
		(layer "F.Cu")
		(net "P3E_PCH_M2_RX_DP<1>")
	)
	(segment
		(start 353.002088 -48.104552)
		(end 353.101148 -48.005492)
		(width 0.0889)
		(layer "F.Cu")
		(net "P3E_PCH_M2_RX_DP<1>")
	)
	(segment
		(start 349.733108 -48.005492)
		(end 349.832168 -48.104552)
		(width 0.0889)
		(layer "F.Cu")
		(net "P3E_PCH_M2_RX_DP<1>")
	)
	(segment
		(start 356.817676 -48.005492)
		(end 357.349552 -47.473616)
		(width 0.0889)
		(layer "F.Cu")
		(net "P3E_PCH_M2_RX_DP<1>")
	)
	(segment
		(start 351.241868 -48.005492)
		(end 351.340928 -48.104552)
		(width 0.0889)
		(layer "F.Cu")
		(net "P3E_PCH_M2_RX_DP<1>")
	)
	(segment
		(start 350.990408 -48.104552)
		(end 351.089468 -48.005492)
		(width 0.0889)
		(layer "F.Cu")
		(net "P3E_PCH_M2_RX_DP<1>")
	)
	(segment
		(start 350.083628 -48.005492)
		(end 350.236028 -48.005492)
		(width 0.0889)
		(layer "F.Cu")
		(net "P3E_PCH_M2_RX_DP<1>")
	)
	(segment
		(start 352.346768 -48.104552)
		(end 352.499168 -48.104552)
		(width 0.0889)
		(layer "F.Cu")
		(net "P3E_PCH_M2_RX_DP<1>")
	)
	(segment
		(start 351.744788 -48.005492)
		(end 351.843848 -48.104552)
		(width 0.0889)
		(layer "F.Cu")
		(net "P3E_PCH_M2_RX_DP<1>")
	)
	(segment
		(start 351.089468 -48.005492)
		(end 351.241868 -48.005492)
		(width 0.0889)
		(layer "F.Cu")
		(net "P3E_PCH_M2_RX_DP<1>")
	)
	(segment
		(start 352.499168 -48.104552)
		(end 352.598228 -48.005492)
		(width 0.0889)
		(layer "F.Cu")
		(net "P3E_PCH_M2_RX_DP<1>")
	)
	(segment
		(start 352.750628 -48.005492)
		(end 352.849688 -48.104552)
		(width 0.0889)
		(layer "F.Cu")
		(net "P3E_PCH_M2_RX_DP<1>")
	)
	(segment
		(start 346.799662 -48.450246)
		(end 346.806012 -48.456596)
		(width 0.0889)
		(layer "F.Cu")
		(net "P3E_PCH_M2_RX_DP<1>")
	)
	(segment
		(start 350.738948 -48.005492)
		(end 350.838008 -48.104552)
		(width 0.0889)
		(layer "F.Cu")
		(net "P3E_PCH_M2_RX_DP<1>")
	)
	(segment
		(start 351.340928 -48.104552)
		(end 351.493328 -48.104552)
		(width 0.0889)
		(layer "F.Cu")
		(net "P3E_PCH_M2_RX_DP<1>")
	)
	(segment
		(start 352.247708 -48.005492)
		(end 352.346768 -48.104552)
		(width 0.0889)
		(layer "F.Cu")
		(net "P3E_PCH_M2_RX_DP<1>")
	)
	(segment
		(start 349.230188 -48.005492)
		(end 349.329248 -48.104552)
		(width 0.0889)
		(layer "F.Cu")
		(net "P3E_PCH_M2_RX_DP<1>")
	)
	(segment
		(start 349.984568 -48.104552)
		(end 350.083628 -48.005492)
		(width 0.0889)
		(layer "F.Cu")
		(net "P3E_PCH_M2_RX_DP<1>")
	)
	(segment
		(start 352.095308 -48.005492)
		(end 352.247708 -48.005492)
		(width 0.0889)
		(layer "F.Cu")
		(net "P3E_PCH_M2_RX_DP<1>")
	)
	(segment
		(start 350.586548 -48.005492)
		(end 350.738948 -48.005492)
		(width 0.0889)
		(layer "F.Cu")
		(net "P3E_PCH_M2_RX_DP<1>")
	)
	(segment
		(start 177.82032 -51.920394)
		(end 178.70932 -51.920394)
		(width 0.13208)
		(layer "F.Cu")
		(net "P3E_PCH_M2_RX_DP<1>")
	)
	(segment
		(start 177.699924 -51.799998)
		(end 177.82032 -51.920394)
		(width 0.13208)
		(layer "F.Cu")
		(net "P3E_PCH_M2_RX_DP<1>")
	)
	(segment
		(start 349.580708 -48.005492)
		(end 349.733108 -48.005492)
		(width 0.0889)
		(layer "F.Cu")
		(net "P3E_PCH_M2_RX_DP<1>")
	)
	(segment
		(start 350.838008 -48.104552)
		(end 350.990408 -48.104552)
		(width 0.0889)
		(layer "F.Cu")
		(net "P3E_PCH_M2_RX_DP<1>")
	)
	(segment
		(start 353.505008 -48.104552)
		(end 353.604068 -48.005492)
		(width 0.0889)
		(layer "F.Cu")
		(net "P3E_PCH_M2_RX_DP<1>")
	)
	(segment
		(start 353.253548 -48.005492)
		(end 353.352608 -48.104552)
		(width 0.0889)
		(layer "F.Cu")
		(net "P3E_PCH_M2_RX_DP<1>")
	)
	(segment
		(start 349.329248 -48.104552)
		(end 349.481648 -48.104552)
		(width 0.0889)
		(layer "F.Cu")
		(net "P3E_PCH_M2_RX_DP<1>")
	)
	(segment
		(start 352.598228 -48.005492)
		(end 352.750628 -48.005492)
		(width 0.0889)
		(layer "F.Cu")
		(net "P3E_PCH_M2_RX_DP<1>")
	)
	(segment
		(start 351.996248 -48.104552)
		(end 352.095308 -48.005492)
		(width 0.0889)
		(layer "F.Cu")
		(net "P3E_PCH_M2_RX_DP<1>")
	)
	(segment
		(start 350.236028 -48.005492)
		(end 350.335088 -48.104552)
		(width 0.0889)
		(layer "F.Cu")
		(net "P3E_PCH_M2_RX_DP<1>")
	)
	(segment
		(start 348.626684 -48.456596)
		(end 349.077788 -48.005492)
		(width 0.0889)
		(layer "F.Cu")
		(net "P3E_PCH_M2_RX_DP<1>")
	)
	(segment
		(start 353.604068 -48.005492)
		(end 356.817676 -48.005492)
		(width 0.0889)
		(layer "F.Cu")
		(net "P3E_PCH_M2_RX_DP<1>")
	)
	(segment
		(start 350.487488 -48.104552)
		(end 350.586548 -48.005492)
		(width 0.0889)
		(layer "F.Cu")
		(net "P3E_PCH_M2_RX_DP<1>")
	)
	(segment
		(start 351.493328 -48.104552)
		(end 351.592388 -48.005492)
		(width 0.0889)
		(layer "F.Cu")
		(net "P3E_PCH_M2_RX_DP<1>")
	)
	(segment
		(start 346.806012 -48.456596)
		(end 348.626684 -48.456596)
		(width 0.0889)
		(layer "F.Cu")
		(net "P3E_PCH_M2_RX_DP<1>")
	)
	(segment
		(start 178.70932 -51.920394)
		(end 179.01158 -51.618134)
		(width 0.13208)
		(layer "F.Cu")
		(net "P3E_PCH_M2_RX_DP<1>")
	)
	(segment
		(start 349.832168 -48.104552)
		(end 349.984568 -48.104552)
		(width 0.0889)
		(layer "F.Cu")
		(net "P3E_PCH_M2_RX_DP<1>")
	)
	(segment
		(start 351.592388 -48.005492)
		(end 351.744788 -48.005492)
		(width 0.0889)
		(layer "F.Cu")
		(net "P3E_PCH_M2_RX_DP<1>")
	)
	(segment
		(start 351.843848 -48.104552)
		(end 351.996248 -48.104552)
		(width 0.0889)
		(layer "F.Cu")
		(net "P3E_PCH_M2_RX_DP<1>")
	)
	(segment
		(start 353.7712 -30.102556)
		(end 353.7712 -28.324556)
		(width 0.14732)
		(layer "In15.Cu")
		(net "P3E_PCH_M2_RX_DP<1>")
	)
	(segment
		(start 331.771498 -22.652228)
		(end 330.37526 -21.25599)
		(width 0.14732)
		(layer "In15.Cu")
		(net "P3E_PCH_M2_RX_DP<1>")
	)
	(segment
		(start 357.39832 -46.510956)
		(end 357.39832 -46.23308)
		(width 0.14732)
		(layer "In15.Cu")
		(net "P3E_PCH_M2_RX_DP<1>")
	)
	(segment
		(start 357.690166 -46.802802)
		(end 357.39832 -46.510956)
		(width 0.14732)
		(layer "In15.Cu")
		(net "P3E_PCH_M2_RX_DP<1>")
	)
	(segment
		(start 361.5182 -34.750756)
		(end 358.639872 -31.872428)
		(width 0.14732)
		(layer "In15.Cu")
		(net "P3E_PCH_M2_RX_DP<1>")
	)
	(segment
		(start 202.55357 -59.54141)
		(end 183.67248 -52.212748)
		(width 0.14732)
		(layer "In15.Cu")
		(net "P3E_PCH_M2_RX_DP<1>")
	)
	(segment
		(start 330.37526 -21.25599)
		(end 330.37526 -19.830796)
		(width 0.14732)
		(layer "In15.Cu")
		(net "P3E_PCH_M2_RX_DP<1>")
	)
	(segment
		(start 241.95532 -65.107058)
		(end 236.017308 -65.442084)
		(width 0.14732)
		(layer "In15.Cu")
		(net "P3E_PCH_M2_RX_DP<1>")
	)
	(segment
		(start 353.7712 -28.324556)
		(end 351.883472 -26.436828)
		(width 0.14732)
		(layer "In15.Cu")
		(net "P3E_PCH_M2_RX_DP<1>")
	)
	(segment
		(start 183.67248 -52.212748)
		(end 182.819548 -52.062634)
		(width 0.14732)
		(layer "In15.Cu")
		(net "P3E_PCH_M2_RX_DP<1>")
	)
	(segment
		(start 351.883472 -26.436828)
		(end 345.000072 -26.436828)
		(width 0.14732)
		(layer "In15.Cu")
		(net "P3E_PCH_M2_RX_DP<1>")
	)
	(segment
		(start 296.343832 -26.086816)
		(end 275.571204 -56.702198)
		(width 0.14732)
		(layer "In15.Cu")
		(net "P3E_PCH_M2_RX_DP<1>")
	)
	(segment
		(start 342.739472 -24.176228)
		(end 339.666072 -24.176228)
		(width 0.14732)
		(layer "In15.Cu")
		(net "P3E_PCH_M2_RX_DP<1>")
	)
	(segment
		(start 357.39832 -46.23308)
		(end 358.703372 -44.928028)
		(width 0.14732)
		(layer "In15.Cu")
		(net "P3E_PCH_M2_RX_DP<1>")
	)
	(segment
		(start 330.37526 -19.830796)
		(end 329.340972 -18.796508)
		(width 0.14732)
		(layer "In15.Cu")
		(net "P3E_PCH_M2_RX_DP<1>")
	)
	(segment
		(start 358.703372 -44.928028)
		(end 360.176572 -44.928028)
		(width 0.14732)
		(layer "In15.Cu")
		(net "P3E_PCH_M2_RX_DP<1>")
	)
	(segment
		(start 274.38858 -57.530492)
		(end 270.841216 -60.014866)
		(width 0.14732)
		(layer "In15.Cu")
		(net "P3E_PCH_M2_RX_DP<1>")
	)
	(segment
		(start 339.666072 -24.176228)
		(end 338.142072 -22.652228)
		(width 0.14732)
		(layer "In15.Cu")
		(net "P3E_PCH_M2_RX_DP<1>")
	)
	(segment
		(start 345.000072 -26.436828)
		(end 342.739472 -24.176228)
		(width 0.14732)
		(layer "In15.Cu")
		(net "P3E_PCH_M2_RX_DP<1>")
	)
	(segment
		(start 329.340972 -18.796508)
		(end 319.206626 -18.796508)
		(width 0.14732)
		(layer "In15.Cu")
		(net "P3E_PCH_M2_RX_DP<1>")
	)
	(segment
		(start 236.017308 -65.442084)
		(end 202.55357 -59.54141)
		(width 0.14732)
		(layer "In15.Cu")
		(net "P3E_PCH_M2_RX_DP<1>")
	)
	(segment
		(start 299.890434 -23.506938)
		(end 296.343832 -26.086816)
		(width 0.14732)
		(layer "In15.Cu")
		(net "P3E_PCH_M2_RX_DP<1>")
	)
	(segment
		(start 270.841216 -60.014866)
		(end 241.95532 -65.107058)
		(width 0.14732)
		(layer "In15.Cu")
		(net "P3E_PCH_M2_RX_DP<1>")
	)
	(segment
		(start 182.819294 -52.06238)
		(end 181.969156 -51.912774)
		(width 0.14732)
		(layer "In15.Cu")
		(net "P3E_PCH_M2_RX_DP<1>")
	)
	(segment
		(start 360.176572 -44.928028)
		(end 361.5182 -43.5864)
		(width 0.14732)
		(layer "In15.Cu")
		(net "P3E_PCH_M2_RX_DP<1>")
	)
	(segment
		(start 358.639872 -31.872428)
		(end 355.541072 -31.872428)
		(width 0.14732)
		(layer "In15.Cu")
		(net "P3E_PCH_M2_RX_DP<1>")
	)
	(segment
		(start 338.142072 -22.652228)
		(end 331.771498 -22.652228)
		(width 0.14732)
		(layer "In15.Cu")
		(net "P3E_PCH_M2_RX_DP<1>")
	)
	(segment
		(start 355.541072 -31.872428)
		(end 353.7712 -30.102556)
		(width 0.14732)
		(layer "In15.Cu")
		(net "P3E_PCH_M2_RX_DP<1>")
	)
	(segment
		(start 361.5182 -43.5864)
		(end 361.5182 -34.750756)
		(width 0.14732)
		(layer "In15.Cu")
		(net "P3E_PCH_M2_RX_DP<1>")
	)
	(segment
		(start 275.571204 -56.702198)
		(end 274.38858 -57.530492)
		(width 0.14732)
		(layer "In15.Cu")
		(net "P3E_PCH_M2_RX_DP<1>")
	)
	(segment
		(start 179.30622 -51.912774)
		(end 179.01158 -51.618134)
		(width 0.14732)
		(layer "In15.Cu")
		(net "P3E_PCH_M2_RX_DP<1>")
	)
	(segment
		(start 319.206626 -18.796508)
		(end 299.890434 -23.506938)
		(width 0.14732)
		(layer "In15.Cu")
		(net "P3E_PCH_M2_RX_DP<1>")
	)
	(segment
		(start 181.969156 -51.912774)
		(end 179.30622 -51.912774)
		(width 0.14732)
		(layer "In15.Cu")
		(net "P3E_PCH_M2_RX_DP<1>")
	)
	(segment
		(start 182.819548 -52.062634)
		(end 182.819294 -52.06238)
		(width 0.14732)
		(layer "In15.Cu")
		(net "P3E_PCH_M2_RX_DP<1>")
	)
	(segment
		(start 348.967298 -47.506128)
		(end 349.119698 -47.506128)
		(width 0.0889)
		(layer "F.Cu")
		(net "P3E_PCH_M2_RX_DP<0>")
	)
	(segment
		(start 352.701098 -47.602648)
		(end 352.853498 -47.602648)
		(width 0.0889)
		(layer "F.Cu")
		(net "P3E_PCH_M2_RX_DP<0>")
	)
	(segment
		(start 353.198938 -47.602648)
		(end 353.351338 -47.602648)
		(width 0.0889)
		(layer "F.Cu")
		(net "P3E_PCH_M2_RX_DP<0>")
	)
	(segment
		(start 355.634036 -46.425358)
		(end 356.47884 -45.580554)
		(width 0.0889)
		(layer "F.Cu")
		(net "P3E_PCH_M2_RX_DP<0>")
	)
	(segment
		(start 356.47884 -45.32376)
		(end 356.804214 -44.998386)
		(width 0.0889)
		(layer "F.Cu")
		(net "P3E_PCH_M2_RX_DP<0>")
	)
	(segment
		(start 351.705418 -47.602648)
		(end 351.857818 -47.602648)
		(width 0.0889)
		(layer "F.Cu")
		(net "P3E_PCH_M2_RX_DP<0>")
	)
	(segment
		(start 177.108104 -54.799992)
		(end 177.699924 -54.799992)
		(width 0.13208)
		(layer "F.Cu")
		(net "P3E_PCH_M2_RX_DP<0>")
	)
	(segment
		(start 353.447858 -47.506128)
		(end 354.867718 -47.506128)
		(width 0.0889)
		(layer "F.Cu")
		(net "P3E_PCH_M2_RX_DP<0>")
	)
	(segment
		(start 353.102418 -47.506128)
		(end 353.198938 -47.602648)
		(width 0.0889)
		(layer "F.Cu")
		(net "P3E_PCH_M2_RX_DP<0>")
	)
	(segment
		(start 349.714058 -47.602648)
		(end 349.866458 -47.602648)
		(width 0.0889)
		(layer "F.Cu")
		(net "P3E_PCH_M2_RX_DP<0>")
	)
	(segment
		(start 353.351338 -47.602648)
		(end 353.447858 -47.506128)
		(width 0.0889)
		(layer "F.Cu")
		(net "P3E_PCH_M2_RX_DP<0>")
	)
	(segment
		(start 352.106738 -47.506128)
		(end 352.203258 -47.602648)
		(width 0.0889)
		(layer "F.Cu")
		(net "P3E_PCH_M2_RX_DP<0>")
	)
	(segment
		(start 177.699924 -54.799992)
		(end 177.82032 -54.920388)
		(width 0.13208)
		(layer "F.Cu")
		(net "P3E_PCH_M2_RX_DP<0>")
	)
	(segment
		(start 351.608898 -47.506128)
		(end 351.705418 -47.602648)
		(width 0.0889)
		(layer "F.Cu")
		(net "P3E_PCH_M2_RX_DP<0>")
	)
	(segment
		(start 347.377512 -47.95012)
		(end 347.496892 -48.0695)
		(width 0.0889)
		(layer "F.Cu")
		(net "P3E_PCH_M2_RX_DP<0>")
	)
	(segment
		(start 350.862138 -47.602648)
		(end 350.958658 -47.506128)
		(width 0.0889)
		(layer "F.Cu")
		(net "P3E_PCH_M2_RX_DP<0>")
	)
	(segment
		(start 350.460818 -47.506128)
		(end 350.613218 -47.506128)
		(width 0.0889)
		(layer "F.Cu")
		(net "P3E_PCH_M2_RX_DP<0>")
	)
	(segment
		(start 350.115378 -47.506128)
		(end 350.211898 -47.602648)
		(width 0.0889)
		(layer "F.Cu")
		(net "P3E_PCH_M2_RX_DP<0>")
	)
	(segment
		(start 351.207578 -47.602648)
		(end 351.359978 -47.602648)
		(width 0.0889)
		(layer "F.Cu")
		(net "P3E_PCH_M2_RX_DP<0>")
	)
	(segment
		(start 177.82032 -54.920388)
		(end 178.70932 -54.920388)
		(width 0.13208)
		(layer "F.Cu")
		(net "P3E_PCH_M2_RX_DP<0>")
	)
	(segment
		(start 354.867718 -47.506128)
		(end 355.634036 -46.73981)
		(width 0.0889)
		(layer "F.Cu")
		(net "P3E_PCH_M2_RX_DP<0>")
	)
	(segment
		(start 350.958658 -47.506128)
		(end 351.111058 -47.506128)
		(width 0.0889)
		(layer "F.Cu")
		(net "P3E_PCH_M2_RX_DP<0>")
	)
	(segment
		(start 350.709738 -47.602648)
		(end 350.862138 -47.602648)
		(width 0.0889)
		(layer "F.Cu")
		(net "P3E_PCH_M2_RX_DP<0>")
	)
	(segment
		(start 352.203258 -47.602648)
		(end 352.355658 -47.602648)
		(width 0.0889)
		(layer "F.Cu")
		(net "P3E_PCH_M2_RX_DP<0>")
	)
	(segment
		(start 349.368618 -47.602648)
		(end 349.465138 -47.506128)
		(width 0.0889)
		(layer "F.Cu")
		(net "P3E_PCH_M2_RX_DP<0>")
	)
	(segment
		(start 349.216218 -47.602648)
		(end 349.368618 -47.602648)
		(width 0.0889)
		(layer "F.Cu")
		(net "P3E_PCH_M2_RX_DP<0>")
	)
	(segment
		(start 350.364298 -47.602648)
		(end 350.460818 -47.506128)
		(width 0.0889)
		(layer "F.Cu")
		(net "P3E_PCH_M2_RX_DP<0>")
	)
	(segment
		(start 348.403926 -48.0695)
		(end 348.967298 -47.506128)
		(width 0.0889)
		(layer "F.Cu")
		(net "P3E_PCH_M2_RX_DP<0>")
	)
	(segment
		(start 351.456498 -47.506128)
		(end 351.608898 -47.506128)
		(width 0.0889)
		(layer "F.Cu")
		(net "P3E_PCH_M2_RX_DP<0>")
	)
	(segment
		(start 349.962978 -47.506128)
		(end 350.115378 -47.506128)
		(width 0.0889)
		(layer "F.Cu")
		(net "P3E_PCH_M2_RX_DP<0>")
	)
	(segment
		(start 349.465138 -47.506128)
		(end 349.617538 -47.506128)
		(width 0.0889)
		(layer "F.Cu")
		(net "P3E_PCH_M2_RX_DP<0>")
	)
	(segment
		(start 352.355658 -47.602648)
		(end 352.452178 -47.506128)
		(width 0.0889)
		(layer "F.Cu")
		(net "P3E_PCH_M2_RX_DP<0>")
	)
	(segment
		(start 347.214698 -47.95012)
		(end 347.377512 -47.95012)
		(width 0.0889)
		(layer "F.Cu")
		(net "P3E_PCH_M2_RX_DP<0>")
	)
	(segment
		(start 351.857818 -47.602648)
		(end 351.954338 -47.506128)
		(width 0.0889)
		(layer "F.Cu")
		(net "P3E_PCH_M2_RX_DP<0>")
	)
	(segment
		(start 351.954338 -47.506128)
		(end 352.106738 -47.506128)
		(width 0.0889)
		(layer "F.Cu")
		(net "P3E_PCH_M2_RX_DP<0>")
	)
	(segment
		(start 349.119698 -47.506128)
		(end 349.216218 -47.602648)
		(width 0.0889)
		(layer "F.Cu")
		(net "P3E_PCH_M2_RX_DP<0>")
	)
	(segment
		(start 347.496892 -48.0695)
		(end 348.403926 -48.0695)
		(width 0.0889)
		(layer "F.Cu")
		(net "P3E_PCH_M2_RX_DP<0>")
	)
	(segment
		(start 351.359978 -47.602648)
		(end 351.456498 -47.506128)
		(width 0.0889)
		(layer "F.Cu")
		(net "P3E_PCH_M2_RX_DP<0>")
	)
	(segment
		(start 356.47884 -45.580554)
		(end 356.47884 -45.32376)
		(width 0.0889)
		(layer "F.Cu")
		(net "P3E_PCH_M2_RX_DP<0>")
	)
	(segment
		(start 178.70932 -54.920388)
		(end 179.01158 -54.618128)
		(width 0.13208)
		(layer "F.Cu")
		(net "P3E_PCH_M2_RX_DP<0>")
	)
	(segment
		(start 355.634036 -46.73981)
		(end 355.634036 -46.425358)
		(width 0.0889)
		(layer "F.Cu")
		(net "P3E_PCH_M2_RX_DP<0>")
	)
	(segment
		(start 350.613218 -47.506128)
		(end 350.709738 -47.602648)
		(width 0.0889)
		(layer "F.Cu")
		(net "P3E_PCH_M2_RX_DP<0>")
	)
	(segment
		(start 352.950018 -47.506128)
		(end 353.102418 -47.506128)
		(width 0.0889)
		(layer "F.Cu")
		(net "P3E_PCH_M2_RX_DP<0>")
	)
	(segment
		(start 349.866458 -47.602648)
		(end 349.962978 -47.506128)
		(width 0.0889)
		(layer "F.Cu")
		(net "P3E_PCH_M2_RX_DP<0>")
	)
	(segment
		(start 352.604578 -47.506128)
		(end 352.701098 -47.602648)
		(width 0.0889)
		(layer "F.Cu")
		(net "P3E_PCH_M2_RX_DP<0>")
	)
	(segment
		(start 352.853498 -47.602648)
		(end 352.950018 -47.506128)
		(width 0.0889)
		(layer "F.Cu")
		(net "P3E_PCH_M2_RX_DP<0>")
	)
	(segment
		(start 352.452178 -47.506128)
		(end 352.604578 -47.506128)
		(width 0.0889)
		(layer "F.Cu")
		(net "P3E_PCH_M2_RX_DP<0>")
	)
	(segment
		(start 350.211898 -47.602648)
		(end 350.364298 -47.602648)
		(width 0.0889)
		(layer "F.Cu")
		(net "P3E_PCH_M2_RX_DP<0>")
	)
	(segment
		(start 349.617538 -47.506128)
		(end 349.714058 -47.602648)
		(width 0.0889)
		(layer "F.Cu")
		(net "P3E_PCH_M2_RX_DP<0>")
	)
	(segment
		(start 351.111058 -47.506128)
		(end 351.207578 -47.602648)
		(width 0.0889)
		(layer "F.Cu")
		(net "P3E_PCH_M2_RX_DP<0>")
	)
	(segment
		(start 348.56166 -35.072828)
		(end 347.336872 -35.072828)
		(width 0.14732)
		(layer "In15.Cu")
		(net "P3E_PCH_M2_RX_DP<0>")
	)
	(segment
		(start 202.410314 -60.478924)
		(end 184.94756 -55.131462)
		(width 0.14732)
		(layer "In15.Cu")
		(net "P3E_PCH_M2_RX_DP<0>")
	)
	(segment
		(start 184.94756 -55.131462)
		(end 184.404508 -55.035958)
		(width 0.14732)
		(layer "In15.Cu")
		(net "P3E_PCH_M2_RX_DP<0>")
	)
	(segment
		(start 331.0636 -23.259288)
		(end 329.44562 -21.641308)
		(width 0.14732)
		(layer "In15.Cu")
		(net "P3E_PCH_M2_RX_DP<0>")
	)
	(segment
		(start 236.340904 -66.460878)
		(end 202.410314 -60.478924)
		(width 0.14732)
		(layer "In15.Cu")
		(net "P3E_PCH_M2_RX_DP<0>")
	)
	(segment
		(start 184.38241 -55.032148)
		(end 184.381394 -55.031894)
		(width 0.14732)
		(layer "In15.Cu")
		(net "P3E_PCH_M2_RX_DP<0>")
	)
	(segment
		(start 183.706008 -54.912768)
		(end 179.30622 -54.912768)
		(width 0.14732)
		(layer "In15.Cu")
		(net "P3E_PCH_M2_RX_DP<0>")
	)
	(segment
		(start 184.404508 -55.035958)
		(end 184.403746 -55.035704)
		(width 0.14732)
		(layer "In15.Cu")
		(net "P3E_PCH_M2_RX_DP<0>")
	)
	(segment
		(start 282.78709 -52.79644)
		(end 271.20977 -60.904628)
		(width 0.14732)
		(layer "In15.Cu")
		(net "P3E_PCH_M2_RX_DP<0>")
	)
	(segment
		(start 356.24008 -44.262548)
		(end 353.605592 -44.262548)
		(width 0.14732)
		(layer "In15.Cu")
		(net "P3E_PCH_M2_RX_DP<0>")
	)
	(segment
		(start 335.729072 -28.595828)
		(end 331.0636 -23.930356)
		(width 0.14732)
		(layer "In15.Cu")
		(net "P3E_PCH_M2_RX_DP<0>")
	)
	(segment
		(start 340.859872 -28.595828)
		(end 335.729072 -28.595828)
		(width 0.14732)
		(layer "In15.Cu")
		(net "P3E_PCH_M2_RX_DP<0>")
	)
	(segment
		(start 353.605592 -44.262548)
		(end 350.6851 -41.342056)
		(width 0.14732)
		(layer "In15.Cu")
		(net "P3E_PCH_M2_RX_DP<0>")
	)
	(segment
		(start 347.336872 -35.072828)
		(end 340.859872 -28.595828)
		(width 0.14732)
		(layer "In15.Cu")
		(net "P3E_PCH_M2_RX_DP<0>")
	)
	(segment
		(start 298.550584 -29.563314)
		(end 282.78709 -52.79644)
		(width 0.14732)
		(layer "In15.Cu")
		(net "P3E_PCH_M2_RX_DP<0>")
	)
	(segment
		(start 319.361312 -19.726148)
		(end 308.39791 -22.399752)
		(width 0.14732)
		(layer "In15.Cu")
		(net "P3E_PCH_M2_RX_DP<0>")
	)
	(segment
		(start 356.509574 -44.887642)
		(end 356.509574 -44.532042)
		(width 0.14732)
		(layer "In15.Cu")
		(net "P3E_PCH_M2_RX_DP<0>")
	)
	(segment
		(start 241.616484 -66.12128)
		(end 236.340904 -66.460878)
		(width 0.14732)
		(layer "In15.Cu")
		(net "P3E_PCH_M2_RX_DP<0>")
	)
	(segment
		(start 331.0636 -23.930356)
		(end 331.0636 -23.259288)
		(width 0.14732)
		(layer "In15.Cu")
		(net "P3E_PCH_M2_RX_DP<0>")
	)
	(segment
		(start 184.403746 -55.035704)
		(end 184.40146 -55.035196)
		(width 0.14732)
		(layer "In15.Cu")
		(net "P3E_PCH_M2_RX_DP<0>")
	)
	(segment
		(start 184.381394 -55.031894)
		(end 184.38114 -55.031894)
		(width 0.14732)
		(layer "In15.Cu")
		(net "P3E_PCH_M2_RX_DP<0>")
	)
	(segment
		(start 350.6851 -41.342056)
		(end 350.6851 -37.196268)
		(width 0.14732)
		(layer "In15.Cu")
		(net "P3E_PCH_M2_RX_DP<0>")
	)
	(segment
		(start 308.39791 -22.399752)
		(end 298.550584 -29.563314)
		(width 0.14732)
		(layer "In15.Cu")
		(net "P3E_PCH_M2_RX_DP<0>")
	)
	(segment
		(start 356.509574 -44.532042)
		(end 356.24008 -44.262548)
		(width 0.14732)
		(layer "In15.Cu")
		(net "P3E_PCH_M2_RX_DP<0>")
	)
	(segment
		(start 356.804214 -44.998386)
		(end 356.620318 -44.998386)
		(width 0.14732)
		(layer "In15.Cu")
		(net "P3E_PCH_M2_RX_DP<0>")
	)
	(segment
		(start 328.929492 -19.726148)
		(end 319.361312 -19.726148)
		(width 0.14732)
		(layer "In15.Cu")
		(net "P3E_PCH_M2_RX_DP<0>")
	)
	(segment
		(start 184.399682 -55.034942)
		(end 184.38241 -55.032148)
		(width 0.14732)
		(layer "In15.Cu")
		(net "P3E_PCH_M2_RX_DP<0>")
	)
	(segment
		(start 179.30622 -54.912768)
		(end 179.01158 -54.618128)
		(width 0.14732)
		(layer "In15.Cu")
		(net "P3E_PCH_M2_RX_DP<0>")
	)
	(segment
		(start 356.620318 -44.998386)
		(end 356.509574 -44.887642)
		(width 0.14732)
		(layer "In15.Cu")
		(net "P3E_PCH_M2_RX_DP<0>")
	)
	(segment
		(start 184.40146 -55.035196)
		(end 184.399682 -55.034942)
		(width 0.14732)
		(layer "In15.Cu")
		(net "P3E_PCH_M2_RX_DP<0>")
	)
	(segment
		(start 271.20977 -60.904628)
		(end 241.616484 -66.12128)
		(width 0.14732)
		(layer "In15.Cu")
		(net "P3E_PCH_M2_RX_DP<0>")
	)
	(segment
		(start 329.44562 -21.641308)
		(end 329.44562 -20.242276)
		(width 0.14732)
		(layer "In15.Cu")
		(net "P3E_PCH_M2_RX_DP<0>")
	)
	(segment
		(start 350.6851 -37.196268)
		(end 348.56166 -35.072828)
		(width 0.14732)
		(layer "In15.Cu")
		(net "P3E_PCH_M2_RX_DP<0>")
	)
	(segment
		(start 329.44562 -20.242276)
		(end 328.929492 -19.726148)
		(width 0.14732)
		(layer "In15.Cu")
		(net "P3E_PCH_M2_RX_DP<0>")
	)
	(segment
		(start 184.38114 -55.031894)
		(end 183.706008 -54.912768)
		(width 0.14732)
		(layer "In15.Cu")
		(net "P3E_PCH_M2_RX_DP<0>")
	)
	(segment
		(start 177.88636 -46.179486)
		(end 178.70932 -46.179486)
		(width 0.13208)
		(layer "F.Cu")
		(net "P3E_PCH_M2_RX_DN<3>")
	)
	(segment
		(start 361.46994 -46.802802)
		(end 361.76458 -47.097442)
		(width 0.13208)
		(layer "F.Cu")
		(net "P3E_PCH_M2_RX_DN<3>")
	)
	(segment
		(start 349.146876 -48.88611)
		(end 348.776798 -49.256188)
		(width 0.0889)
		(layer "F.Cu")
		(net "P3E_PCH_M2_RX_DN<3>")
	)
	(segment
		(start 357.194612 -49.249838)
		(end 356.82809 -49.249838)
		(width 0.0889)
		(layer "F.Cu")
		(net "P3E_PCH_M2_RX_DN<3>")
	)
	(segment
		(start 178.70932 -46.179486)
		(end 179.01158 -46.481746)
		(width 0.13208)
		(layer "F.Cu")
		(net "P3E_PCH_M2_RX_DN<3>")
	)
	(segment
		(start 346.659962 -49.14392)
		(end 346.50426 -49.278286)
		(width 0.0889)
		(layer "F.Cu")
		(net "P3E_PCH_M2_RX_DN<3>")
	)
	(segment
		(start 357.228902 -49.215548)
		(end 357.194612 -49.249838)
		(width 0.0889)
		(layer "F.Cu")
		(net "P3E_PCH_M2_RX_DN<3>")
	)
	(segment
		(start 346.331794 -49.450752)
		(end 345.96959 -49.450752)
		(width 0.0889)
		(layer "F.Cu")
		(net "P3E_PCH_M2_RX_DN<3>")
	)
	(segment
		(start 177.108104 -46.299882)
		(end 177.765964 -46.299882)
		(width 0.13208)
		(layer "F.Cu")
		(net "P3E_PCH_M2_RX_DN<3>")
	)
	(segment
		(start 360.342688 -48.85182)
		(end 358.452928 -48.85182)
		(width 0.13208)
		(layer "F.Cu")
		(net "P3E_PCH_M2_RX_DN<3>")
	)
	(segment
		(start 358.0892 -49.215548)
		(end 357.251 -49.215548)
		(width 0.13208)
		(layer "F.Cu")
		(net "P3E_PCH_M2_RX_DN<3>")
	)
	(segment
		(start 356.464362 -48.88611)
		(end 349.146876 -48.88611)
		(width 0.0889)
		(layer "F.Cu")
		(net "P3E_PCH_M2_RX_DN<3>")
	)
	(segment
		(start 358.452928 -48.85182)
		(end 358.0892 -49.215548)
		(width 0.13208)
		(layer "F.Cu")
		(net "P3E_PCH_M2_RX_DN<3>")
	)
	(segment
		(start 177.765964 -46.299882)
		(end 177.88636 -46.179486)
		(width 0.13208)
		(layer "F.Cu")
		(net "P3E_PCH_M2_RX_DN<3>")
	)
	(segment
		(start 346.978478 -49.14392)
		(end 346.659962 -49.14392)
		(width 0.0889)
		(layer "F.Cu")
		(net "P3E_PCH_M2_RX_DN<3>")
	)
	(segment
		(start 347.090746 -49.256188)
		(end 346.978478 -49.14392)
		(width 0.0889)
		(layer "F.Cu")
		(net "P3E_PCH_M2_RX_DN<3>")
	)
	(segment
		(start 356.82809 -49.249838)
		(end 356.464362 -48.88611)
		(width 0.0889)
		(layer "F.Cu")
		(net "P3E_PCH_M2_RX_DN<3>")
	)
	(segment
		(start 357.251 -49.215548)
		(end 357.228902 -49.215548)
		(width 0.0889)
		(layer "F.Cu")
		(net "P3E_PCH_M2_RX_DN<3>")
	)
	(segment
		(start 346.50426 -49.278286)
		(end 346.331794 -49.450752)
		(width 0.0889)
		(layer "F.Cu")
		(net "P3E_PCH_M2_RX_DN<3>")
	)
	(segment
		(start 361.76458 -47.097442)
		(end 361.76458 -47.429928)
		(width 0.13208)
		(layer "F.Cu")
		(net "P3E_PCH_M2_RX_DN<3>")
	)
	(segment
		(start 361.76458 -47.429928)
		(end 360.342688 -48.85182)
		(width 0.13208)
		(layer "F.Cu")
		(net "P3E_PCH_M2_RX_DN<3>")
	)
	(segment
		(start 348.776798 -49.256188)
		(end 347.090746 -49.256188)
		(width 0.0889)
		(layer "F.Cu")
		(net "P3E_PCH_M2_RX_DN<3>")
	)
	(segment
		(start 359.51287 -25.52065)
		(end 352.489008 -18.496788)
		(width 0.14732)
		(layer "In15.Cu")
		(net "P3E_PCH_M2_RX_DN<3>")
	)
	(segment
		(start 360.499152 -26.711656)
		(end 360.238548 -26.451052)
		(width 0.14732)
		(layer "In15.Cu")
		(net "P3E_PCH_M2_RX_DN<3>")
	)
	(segment
		(start 361.982004 -28.194508)
		(end 361.7214 -27.933904)
		(width 0.14732)
		(layer "In15.Cu")
		(net "P3E_PCH_M2_RX_DN<3>")
	)
	(segment
		(start 359.978198 -25.985978)
		(end 359.773474 -25.985978)
		(width 0.14732)
		(layer "In15.Cu")
		(net "P3E_PCH_M2_RX_DN<3>")
	)
	(segment
		(start 241.818668 -63.289688)
		(end 235.089954 -63.653162)
		(width 0.14732)
		(layer "In15.Cu")
		(net "P3E_PCH_M2_RX_DN<3>")
	)
	(segment
		(start 361.76458 -46.508162)
		(end 361.76458 -45.977556)
		(width 0.14732)
		(layer "In15.Cu")
		(net "P3E_PCH_M2_RX_DN<3>")
	)
	(segment
		(start 274.257262 -55.407814)
		(end 272.198338 -56.849772)
		(width 0.14732)
		(layer "In15.Cu")
		(net "P3E_PCH_M2_RX_DN<3>")
	)
	(segment
		(start 181.458362 -46.187106)
		(end 179.30622 -46.187106)
		(width 0.14732)
		(layer "In15.Cu")
		(net "P3E_PCH_M2_RX_DN<3>")
	)
	(segment
		(start 331.4065 -18.496788)
		(end 330.12126 -17.211548)
		(width 0.14732)
		(layer "In15.Cu")
		(net "P3E_PCH_M2_RX_DN<3>")
	)
	(segment
		(start 363.491526 -44.25061)
		(end 363.491526 -29.499306)
		(width 0.14732)
		(layer "In15.Cu")
		(net "P3E_PCH_M2_RX_DN<3>")
	)
	(segment
		(start 363.491526 -29.499306)
		(end 362.186728 -28.194508)
		(width 0.14732)
		(layer "In15.Cu")
		(net "P3E_PCH_M2_RX_DN<3>")
	)
	(segment
		(start 361.429554 -27.437334)
		(end 361.22483 -27.437334)
		(width 0.14732)
		(layer "In15.Cu")
		(net "P3E_PCH_M2_RX_DN<3>")
	)
	(segment
		(start 360.703876 -26.711656)
		(end 360.499152 -26.711656)
		(width 0.14732)
		(layer "In15.Cu")
		(net "P3E_PCH_M2_RX_DN<3>")
	)
	(segment
		(start 361.76458 -45.977556)
		(end 363.491526 -44.25061)
		(width 0.14732)
		(layer "In15.Cu")
		(net "P3E_PCH_M2_RX_DN<3>")
	)
	(segment
		(start 361.7214 -27.933904)
		(end 361.7214 -27.72918)
		(width 0.14732)
		(layer "In15.Cu")
		(net "P3E_PCH_M2_RX_DN<3>")
	)
	(segment
		(start 272.198338 -56.849772)
		(end 272.198084 -56.849772)
		(width 0.14732)
		(layer "In15.Cu")
		(net "P3E_PCH_M2_RX_DN<3>")
	)
	(segment
		(start 272.198084 -56.849772)
		(end 270.13027 -58.29808)
		(width 0.14732)
		(layer "In15.Cu")
		(net "P3E_PCH_M2_RX_DN<3>")
	)
	(segment
		(start 179.30622 -46.187106)
		(end 179.01158 -46.481746)
		(width 0.14732)
		(layer "In15.Cu")
		(net "P3E_PCH_M2_RX_DN<3>")
	)
	(segment
		(start 203.309474 -58.049414)
		(end 184.873138 -47.714154)
		(width 0.14732)
		(layer "In15.Cu")
		(net "P3E_PCH_M2_RX_DN<3>")
	)
	(segment
		(start 184.873138 -47.714154)
		(end 183.107584 -46.47819)
		(width 0.14732)
		(layer "In15.Cu")
		(net "P3E_PCH_M2_RX_DN<3>")
	)
	(segment
		(start 295.002712 -24.83231)
		(end 274.257262 -55.407814)
		(width 0.14732)
		(layer "In15.Cu")
		(net "P3E_PCH_M2_RX_DN<3>")
	)
	(segment
		(start 255.952752 -60.797694)
		(end 255.952498 -60.797694)
		(width 0.14732)
		(layer "In15.Cu")
		(net "P3E_PCH_M2_RX_DN<3>")
	)
	(segment
		(start 359.773474 -25.985978)
		(end 359.51287 -25.725374)
		(width 0.14732)
		(layer "In15.Cu")
		(net "P3E_PCH_M2_RX_DN<3>")
	)
	(segment
		(start 235.089954 -63.653162)
		(end 203.309474 -58.049414)
		(width 0.14732)
		(layer "In15.Cu")
		(net "P3E_PCH_M2_RX_DN<3>")
	)
	(segment
		(start 183.107584 -46.47819)
		(end 182.283354 -46.332648)
		(width 0.14732)
		(layer "In15.Cu")
		(net "P3E_PCH_M2_RX_DN<3>")
	)
	(segment
		(start 182.2831 -46.332648)
		(end 181.458362 -46.187106)
		(width 0.14732)
		(layer "In15.Cu")
		(net "P3E_PCH_M2_RX_DN<3>")
	)
	(segment
		(start 270.13027 -58.29808)
		(end 255.952752 -60.797694)
		(width 0.14732)
		(layer "In15.Cu")
		(net "P3E_PCH_M2_RX_DN<3>")
	)
	(segment
		(start 360.964226 -26.972006)
		(end 360.703876 -26.711656)
		(width 0.14732)
		(layer "In15.Cu")
		(net "P3E_PCH_M2_RX_DN<3>")
	)
	(segment
		(start 255.952498 -60.797694)
		(end 241.818668 -63.289688)
		(width 0.14732)
		(layer "In15.Cu")
		(net "P3E_PCH_M2_RX_DN<3>")
	)
	(segment
		(start 318.050926 -17.211548)
		(end 299.140372 -21.822918)
		(width 0.14732)
		(layer "In15.Cu")
		(net "P3E_PCH_M2_RX_DN<3>")
	)
	(segment
		(start 360.238548 -26.451052)
		(end 360.238548 -26.246328)
		(width 0.14732)
		(layer "In15.Cu")
		(net "P3E_PCH_M2_RX_DN<3>")
	)
	(segment
		(start 361.7214 -27.72918)
		(end 361.429554 -27.437334)
		(width 0.14732)
		(layer "In15.Cu")
		(net "P3E_PCH_M2_RX_DN<3>")
	)
	(segment
		(start 361.46994 -46.802802)
		(end 361.76458 -46.508162)
		(width 0.14732)
		(layer "In15.Cu")
		(net "P3E_PCH_M2_RX_DN<3>")
	)
	(segment
		(start 359.51287 -25.725374)
		(end 359.51287 -25.52065)
		(width 0.14732)
		(layer "In15.Cu")
		(net "P3E_PCH_M2_RX_DN<3>")
	)
	(segment
		(start 360.238548 -26.246328)
		(end 359.978198 -25.985978)
		(width 0.14732)
		(layer "In15.Cu")
		(net "P3E_PCH_M2_RX_DN<3>")
	)
	(segment
		(start 352.489008 -18.496788)
		(end 331.4065 -18.496788)
		(width 0.14732)
		(layer "In15.Cu")
		(net "P3E_PCH_M2_RX_DN<3>")
	)
	(segment
		(start 330.12126 -17.211548)
		(end 318.050926 -17.211548)
		(width 0.14732)
		(layer "In15.Cu")
		(net "P3E_PCH_M2_RX_DN<3>")
	)
	(segment
		(start 360.964226 -27.17673)
		(end 360.964226 -26.972006)
		(width 0.14732)
		(layer "In15.Cu")
		(net "P3E_PCH_M2_RX_DN<3>")
	)
	(segment
		(start 182.283354 -46.332648)
		(end 182.2831 -46.332648)
		(width 0.14732)
		(layer "In15.Cu")
		(net "P3E_PCH_M2_RX_DN<3>")
	)
	(segment
		(start 361.22483 -27.437334)
		(end 360.964226 -27.17673)
		(width 0.14732)
		(layer "In15.Cu")
		(net "P3E_PCH_M2_RX_DN<3>")
	)
	(segment
		(start 299.140372 -21.822918)
		(end 295.002712 -24.83231)
		(width 0.14732)
		(layer "In15.Cu")
		(net "P3E_PCH_M2_RX_DN<3>")
	)
	(segment
		(start 362.186728 -28.194508)
		(end 361.982004 -28.194508)
		(width 0.14732)
		(layer "In15.Cu")
		(net "P3E_PCH_M2_RX_DN<3>")
	)
	(segment
		(start 177.108104 -49.299876)
		(end 177.765964 -49.299876)
		(width 0.13208)
		(layer "F.Cu")
		(net "P3E_PCH_M2_RX_DN<2>")
	)
	(segment
		(start 359.1433 -46.802802)
		(end 359.44556 -47.105062)
		(width 0.13208)
		(layer "F.Cu")
		(net "P3E_PCH_M2_RX_DN<2>")
	)
	(segment
		(start 346.74683 -48.950372)
		(end 346.384626 -48.950372)
		(width 0.0889)
		(layer "F.Cu")
		(net "P3E_PCH_M2_RX_DN<2>")
	)
	(segment
		(start 358.1019 -47.87138)
		(end 358.086406 -47.886874)
		(width 0.0889)
		(layer "F.Cu")
		(net "P3E_PCH_M2_RX_DN<2>")
	)
	(segment
		(start 346.919296 -48.777906)
		(end 346.74683 -48.950372)
		(width 0.0889)
		(layer "F.Cu")
		(net "P3E_PCH_M2_RX_DN<2>")
	)
	(segment
		(start 359.44556 -47.486824)
		(end 359.269538 -47.662846)
		(width 0.13208)
		(layer "F.Cu")
		(net "P3E_PCH_M2_RX_DN<2>")
	)
	(segment
		(start 347.569536 -48.753776)
		(end 347.490034 -48.674274)
		(width 0.0889)
		(layer "F.Cu")
		(net "P3E_PCH_M2_RX_DN<2>")
	)
	(segment
		(start 358.086406 -47.935642)
		(end 357.673656 -48.348392)
		(width 0.0889)
		(layer "F.Cu")
		(net "P3E_PCH_M2_RX_DN<2>")
	)
	(segment
		(start 347.039184 -48.674274)
		(end 346.919296 -48.777906)
		(width 0.0889)
		(layer "F.Cu")
		(net "P3E_PCH_M2_RX_DN<2>")
	)
	(segment
		(start 358.086406 -47.886874)
		(end 358.086406 -47.935642)
		(width 0.0889)
		(layer "F.Cu")
		(net "P3E_PCH_M2_RX_DN<2>")
	)
	(segment
		(start 359.269538 -47.662846)
		(end 358.310434 -47.662846)
		(width 0.13208)
		(layer "F.Cu")
		(net "P3E_PCH_M2_RX_DN<2>")
	)
	(segment
		(start 348.64421 -48.753776)
		(end 347.569536 -48.753776)
		(width 0.0889)
		(layer "F.Cu")
		(net "P3E_PCH_M2_RX_DN<2>")
	)
	(segment
		(start 177.765964 -49.299876)
		(end 177.88636 -49.17948)
		(width 0.13208)
		(layer "F.Cu")
		(net "P3E_PCH_M2_RX_DN<2>")
	)
	(segment
		(start 357.673656 -48.348392)
		(end 349.049594 -48.348392)
		(width 0.0889)
		(layer "F.Cu")
		(net "P3E_PCH_M2_RX_DN<2>")
	)
	(segment
		(start 177.88636 -49.17948)
		(end 178.70932 -49.17948)
		(width 0.13208)
		(layer "F.Cu")
		(net "P3E_PCH_M2_RX_DN<2>")
	)
	(segment
		(start 349.049594 -48.348392)
		(end 348.64421 -48.753776)
		(width 0.0889)
		(layer "F.Cu")
		(net "P3E_PCH_M2_RX_DN<2>")
	)
	(segment
		(start 347.490034 -48.674274)
		(end 347.039184 -48.674274)
		(width 0.0889)
		(layer "F.Cu")
		(net "P3E_PCH_M2_RX_DN<2>")
	)
	(segment
		(start 359.44556 -47.105062)
		(end 359.44556 -47.486824)
		(width 0.13208)
		(layer "F.Cu")
		(net "P3E_PCH_M2_RX_DN<2>")
	)
	(segment
		(start 358.310434 -47.662846)
		(end 358.1019 -47.87138)
		(width 0.13208)
		(layer "F.Cu")
		(net "P3E_PCH_M2_RX_DN<2>")
	)
	(segment
		(start 178.70932 -49.17948)
		(end 179.01158 -49.48174)
		(width 0.13208)
		(layer "F.Cu")
		(net "P3E_PCH_M2_RX_DN<2>")
	)
	(segment
		(start 361.072176 -29.106368)
		(end 361.072176 -28.901644)
		(width 0.14732)
		(layer "In15.Cu")
		(net "P3E_PCH_M2_RX_DN<2>")
	)
	(segment
		(start 360.086148 -27.915616)
		(end 359.881424 -27.915616)
		(width 0.14732)
		(layer "In15.Cu")
		(net "P3E_PCH_M2_RX_DN<2>")
	)
	(segment
		(start 318.870584 -18.141188)
		(end 299.61078 -22.837902)
		(width 0.14732)
		(layer "In15.Cu")
		(net "P3E_PCH_M2_RX_DN<2>")
	)
	(segment
		(start 183.825134 -49.733708)
		(end 183.310784 -49.37379)
		(width 0.14732)
		(layer "In15.Cu")
		(net "P3E_PCH_M2_RX_DN<2>")
	)
	(segment
		(start 362.46308 -30.292548)
		(end 361.537504 -29.366972)
		(width 0.14732)
		(layer "In15.Cu")
		(net "P3E_PCH_M2_RX_DN<2>")
	)
	(segment
		(start 358.895142 -26.929334)
		(end 358.895142 -26.72461)
		(width 0.14732)
		(layer "In15.Cu")
		(net "P3E_PCH_M2_RX_DN<2>")
	)
	(segment
		(start 359.36047 -27.189938)
		(end 359.155746 -27.189938)
		(width 0.14732)
		(layer "In15.Cu")
		(net "P3E_PCH_M2_RX_DN<2>")
	)
	(segment
		(start 182.78221 -49.280572)
		(end 182.253636 -49.1871)
		(width 0.14732)
		(layer "In15.Cu")
		(net "P3E_PCH_M2_RX_DN<2>")
	)
	(segment
		(start 329.6285 -18.141188)
		(end 318.870584 -18.141188)
		(width 0.14732)
		(layer "In15.Cu")
		(net "P3E_PCH_M2_RX_DN<2>")
	)
	(segment
		(start 202.782424 -58.914538)
		(end 183.825134 -49.733708)
		(width 0.14732)
		(layer "In15.Cu")
		(net "P3E_PCH_M2_RX_DN<2>")
	)
	(segment
		(start 352.7425 -20.571968)
		(end 337.04022 -20.571968)
		(width 0.14732)
		(layer "In15.Cu")
		(net "P3E_PCH_M2_RX_DN<2>")
	)
	(segment
		(start 359.987088 -45.636688)
		(end 360.53268 -45.636688)
		(width 0.14732)
		(layer "In15.Cu")
		(net "P3E_PCH_M2_RX_DN<2>")
	)
	(segment
		(start 179.30622 -49.1871)
		(end 179.01158 -49.48174)
		(width 0.14732)
		(layer "In15.Cu")
		(net "P3E_PCH_M2_RX_DN<2>")
	)
	(segment
		(start 362.46308 -43.706288)
		(end 362.46308 -30.292548)
		(width 0.14732)
		(layer "In15.Cu")
		(net "P3E_PCH_M2_RX_DN<2>")
	)
	(segment
		(start 337.04022 -20.571968)
		(end 335.61528 -21.996908)
		(width 0.14732)
		(layer "In15.Cu")
		(net "P3E_PCH_M2_RX_DN<2>")
	)
	(segment
		(start 182.253636 -49.1871)
		(end 179.30622 -49.1871)
		(width 0.14732)
		(layer "In15.Cu")
		(net "P3E_PCH_M2_RX_DN<2>")
	)
	(segment
		(start 275.052282 -56.190896)
		(end 270.560546 -59.33694)
		(width 0.14732)
		(layer "In15.Cu")
		(net "P3E_PCH_M2_RX_DN<2>")
	)
	(segment
		(start 361.072176 -28.901644)
		(end 360.811826 -28.641294)
		(width 0.14732)
		(layer "In15.Cu")
		(net "P3E_PCH_M2_RX_DN<2>")
	)
	(segment
		(start 360.346498 -28.38069)
		(end 360.346498 -28.175966)
		(width 0.14732)
		(layer "In15.Cu")
		(net "P3E_PCH_M2_RX_DN<2>")
	)
	(segment
		(start 331.04074 -19.553428)
		(end 329.6285 -18.141188)
		(width 0.14732)
		(layer "In15.Cu")
		(net "P3E_PCH_M2_RX_DN<2>")
	)
	(segment
		(start 270.560546 -59.33694)
		(end 256.191004 -61.868304)
		(width 0.14732)
		(layer "In15.Cu")
		(net "P3E_PCH_M2_RX_DN<2>")
	)
	(segment
		(start 183.310784 -49.37379)
		(end 182.782464 -49.280572)
		(width 0.14732)
		(layer "In15.Cu")
		(net "P3E_PCH_M2_RX_DN<2>")
	)
	(segment
		(start 359.62082 -27.655012)
		(end 359.62082 -27.450288)
		(width 0.14732)
		(layer "In15.Cu")
		(net "P3E_PCH_M2_RX_DN<2>")
	)
	(segment
		(start 360.346498 -28.175966)
		(end 360.086148 -27.915616)
		(width 0.14732)
		(layer "In15.Cu")
		(net "P3E_PCH_M2_RX_DN<2>")
	)
	(segment
		(start 256.19075 -61.868304)
		(end 241.86515 -64.392048)
		(width 0.14732)
		(layer "In15.Cu")
		(net "P3E_PCH_M2_RX_DN<2>")
	)
	(segment
		(start 295.803574 -25.607518)
		(end 275.052282 -56.190896)
		(width 0.14732)
		(layer "In15.Cu")
		(net "P3E_PCH_M2_RX_DN<2>")
	)
	(segment
		(start 359.62082 -27.450288)
		(end 359.36047 -27.189938)
		(width 0.14732)
		(layer "In15.Cu")
		(net "P3E_PCH_M2_RX_DN<2>")
	)
	(segment
		(start 359.881424 -27.915616)
		(end 359.62082 -27.655012)
		(width 0.14732)
		(layer "In15.Cu")
		(net "P3E_PCH_M2_RX_DN<2>")
	)
	(segment
		(start 182.782464 -49.280572)
		(end 182.78221 -49.280572)
		(width 0.14732)
		(layer "In15.Cu")
		(net "P3E_PCH_M2_RX_DN<2>")
	)
	(segment
		(start 360.811826 -28.641294)
		(end 360.607102 -28.641294)
		(width 0.14732)
		(layer "In15.Cu")
		(net "P3E_PCH_M2_RX_DN<2>")
	)
	(segment
		(start 331.04074 -20.678648)
		(end 331.04074 -19.553428)
		(width 0.14732)
		(layer "In15.Cu")
		(net "P3E_PCH_M2_RX_DN<2>")
	)
	(segment
		(start 359.43794 -46.508162)
		(end 359.43794 -46.185836)
		(width 0.14732)
		(layer "In15.Cu")
		(net "P3E_PCH_M2_RX_DN<2>")
	)
	(segment
		(start 299.61078 -22.837902)
		(end 295.803574 -25.607518)
		(width 0.14732)
		(layer "In15.Cu")
		(net "P3E_PCH_M2_RX_DN<2>")
	)
	(segment
		(start 361.33278 -29.366972)
		(end 361.072176 -29.106368)
		(width 0.14732)
		(layer "In15.Cu")
		(net "P3E_PCH_M2_RX_DN<2>")
	)
	(segment
		(start 360.607102 -28.641294)
		(end 360.346498 -28.38069)
		(width 0.14732)
		(layer "In15.Cu")
		(net "P3E_PCH_M2_RX_DN<2>")
	)
	(segment
		(start 361.537504 -29.366972)
		(end 361.33278 -29.366972)
		(width 0.14732)
		(layer "In15.Cu")
		(net "P3E_PCH_M2_RX_DN<2>")
	)
	(segment
		(start 358.895142 -26.72461)
		(end 352.7425 -20.571968)
		(width 0.14732)
		(layer "In15.Cu")
		(net "P3E_PCH_M2_RX_DN<2>")
	)
	(segment
		(start 335.61528 -21.996908)
		(end 332.359 -21.996908)
		(width 0.14732)
		(layer "In15.Cu")
		(net "P3E_PCH_M2_RX_DN<2>")
	)
	(segment
		(start 241.86515 -64.392048)
		(end 235.756704 -64.728852)
		(width 0.14732)
		(layer "In15.Cu")
		(net "P3E_PCH_M2_RX_DN<2>")
	)
	(segment
		(start 359.155746 -27.189938)
		(end 358.895142 -26.929334)
		(width 0.14732)
		(layer "In15.Cu")
		(net "P3E_PCH_M2_RX_DN<2>")
	)
	(segment
		(start 256.191004 -61.868304)
		(end 256.19075 -61.868304)
		(width 0.14732)
		(layer "In15.Cu")
		(net "P3E_PCH_M2_RX_DN<2>")
	)
	(segment
		(start 332.359 -21.996908)
		(end 331.04074 -20.678648)
		(width 0.14732)
		(layer "In15.Cu")
		(net "P3E_PCH_M2_RX_DN<2>")
	)
	(segment
		(start 360.53268 -45.636688)
		(end 362.46308 -43.706288)
		(width 0.14732)
		(layer "In15.Cu")
		(net "P3E_PCH_M2_RX_DN<2>")
	)
	(segment
		(start 235.756704 -64.728852)
		(end 202.782424 -58.914538)
		(width 0.14732)
		(layer "In15.Cu")
		(net "P3E_PCH_M2_RX_DN<2>")
	)
	(segment
		(start 359.43794 -46.185836)
		(end 359.987088 -45.636688)
		(width 0.14732)
		(layer "In15.Cu")
		(net "P3E_PCH_M2_RX_DN<2>")
	)
	(segment
		(start 359.1433 -46.802802)
		(end 359.43794 -46.508162)
		(width 0.14732)
		(layer "In15.Cu")
		(net "P3E_PCH_M2_RX_DN<2>")
	)
	(segment
		(start 348.54769 -48.26635)
		(end 348.998794 -47.815246)
		(width 0.0889)
		(layer "F.Cu")
		(net "P3E_PCH_M2_RX_DN<1>")
	)
	(segment
		(start 356.738682 -47.815246)
		(end 357.159306 -47.394622)
		(width 0.0889)
		(layer "F.Cu")
		(net "P3E_PCH_M2_RX_DN<1>")
	)
	(segment
		(start 346.331794 -48.450246)
		(end 346.50426 -48.27778)
		(width 0.0889)
		(layer "F.Cu")
		(net "P3E_PCH_M2_RX_DN<1>")
	)
	(segment
		(start 346.987114 -48.151542)
		(end 347.101922 -48.26635)
		(width 0.0889)
		(layer "F.Cu")
		(net "P3E_PCH_M2_RX_DN<1>")
	)
	(segment
		(start 346.650564 -48.151542)
		(end 346.987114 -48.151542)
		(width 0.0889)
		(layer "F.Cu")
		(net "P3E_PCH_M2_RX_DN<1>")
	)
	(segment
		(start 177.765964 -52.29987)
		(end 177.88636 -52.179474)
		(width 0.13208)
		(layer "F.Cu")
		(net "P3E_PCH_M2_RX_DN<1>")
	)
	(segment
		(start 346.50426 -48.27778)
		(end 346.650564 -48.151542)
		(width 0.0889)
		(layer "F.Cu")
		(net "P3E_PCH_M2_RX_DN<1>")
	)
	(segment
		(start 348.998794 -47.815246)
		(end 356.738682 -47.815246)
		(width 0.0889)
		(layer "F.Cu")
		(net "P3E_PCH_M2_RX_DN<1>")
	)
	(segment
		(start 357.159306 -47.135542)
		(end 356.826566 -46.802802)
		(width 0.0889)
		(layer "F.Cu")
		(net "P3E_PCH_M2_RX_DN<1>")
	)
	(segment
		(start 357.159306 -47.394622)
		(end 357.159306 -47.135542)
		(width 0.0889)
		(layer "F.Cu")
		(net "P3E_PCH_M2_RX_DN<1>")
	)
	(segment
		(start 347.101922 -48.26635)
		(end 348.54769 -48.26635)
		(width 0.0889)
		(layer "F.Cu")
		(net "P3E_PCH_M2_RX_DN<1>")
	)
	(segment
		(start 177.88636 -52.179474)
		(end 178.70932 -52.179474)
		(width 0.13208)
		(layer "F.Cu")
		(net "P3E_PCH_M2_RX_DN<1>")
	)
	(segment
		(start 345.96959 -48.450246)
		(end 346.331794 -48.450246)
		(width 0.0889)
		(layer "F.Cu")
		(net "P3E_PCH_M2_RX_DN<1>")
	)
	(segment
		(start 178.70932 -52.179474)
		(end 179.01158 -52.481734)
		(width 0.13208)
		(layer "F.Cu")
		(net "P3E_PCH_M2_RX_DN<1>")
	)
	(segment
		(start 177.108104 -52.29987)
		(end 177.765964 -52.29987)
		(width 0.13208)
		(layer "F.Cu")
		(net "P3E_PCH_M2_RX_DN<1>")
	)
	(segment
		(start 361.12196 -39.488618)
		(end 361.24388 -39.610538)
		(width 0.14732)
		(layer "In15.Cu")
		(net "P3E_PCH_M2_RX_DN<1>")
	)
	(segment
		(start 358.58958 -44.653708)
		(end 357.124 -46.119288)
		(width 0.14732)
		(layer "In15.Cu")
		(net "P3E_PCH_M2_RX_DN<1>")
	)
	(segment
		(start 330.10094 -21.369782)
		(end 331.657706 -22.926548)
		(width 0.14732)
		(layer "In15.Cu")
		(net "P3E_PCH_M2_RX_DN<1>")
	)
	(segment
		(start 361.12196 -41.264078)
		(end 361.12196 -41.700958)
		(width 0.14732)
		(layer "In15.Cu")
		(net "P3E_PCH_M2_RX_DN<1>")
	)
	(segment
		(start 339.55228 -24.450548)
		(end 342.62568 -24.450548)
		(width 0.14732)
		(layer "In15.Cu")
		(net "P3E_PCH_M2_RX_DN<1>")
	)
	(segment
		(start 179.01158 -52.481734)
		(end 179.30622 -52.187094)
		(width 0.14732)
		(layer "In15.Cu")
		(net "P3E_PCH_M2_RX_DN<1>")
	)
	(segment
		(start 361.24388 -40.047418)
		(end 361.0991 -40.192198)
		(width 0.14732)
		(layer "In15.Cu")
		(net "P3E_PCH_M2_RX_DN<1>")
	)
	(segment
		(start 338.02828 -22.926548)
		(end 339.55228 -24.450548)
		(width 0.14732)
		(layer "In15.Cu")
		(net "P3E_PCH_M2_RX_DN<1>")
	)
	(segment
		(start 236.001052 -65.717928)
		(end 241.98707 -65.380108)
		(width 0.14732)
		(layer "In15.Cu")
		(net "P3E_PCH_M2_RX_DN<1>")
	)
	(segment
		(start 270.948912 -60.274708)
		(end 273.36369 -58.583322)
		(width 0.14732)
		(layer "In15.Cu")
		(net "P3E_PCH_M2_RX_DN<1>")
	)
	(segment
		(start 357.124 -46.119288)
		(end 357.124 -46.505368)
		(width 0.14732)
		(layer "In15.Cu")
		(net "P3E_PCH_M2_RX_DN<1>")
	)
	(segment
		(start 179.30622 -52.187094)
		(end 181.945026 -52.187094)
		(width 0.14732)
		(layer "In15.Cu")
		(net "P3E_PCH_M2_RX_DN<1>")
	)
	(segment
		(start 361.12196 -42.818558)
		(end 361.24388 -42.940478)
		(width 0.14732)
		(layer "In15.Cu")
		(net "P3E_PCH_M2_RX_DN<1>")
	)
	(segment
		(start 342.62568 -24.450548)
		(end 344.88628 -26.711148)
		(width 0.14732)
		(layer "In15.Cu")
		(net "P3E_PCH_M2_RX_DN<1>")
	)
	(segment
		(start 344.88628 -26.711148)
		(end 351.76968 -26.711148)
		(width 0.14732)
		(layer "In15.Cu")
		(net "P3E_PCH_M2_RX_DN<1>")
	)
	(segment
		(start 361.24388 -34.864548)
		(end 361.24388 -38.929818)
		(width 0.14732)
		(layer "In15.Cu")
		(net "P3E_PCH_M2_RX_DN<1>")
	)
	(segment
		(start 182.771796 -52.33289)
		(end 182.77205 -52.33289)
		(width 0.14732)
		(layer "In15.Cu")
		(net "P3E_PCH_M2_RX_DN<1>")
	)
	(segment
		(start 361.12196 -42.381678)
		(end 361.12196 -42.818558)
		(width 0.14732)
		(layer "In15.Cu")
		(net "P3E_PCH_M2_RX_DN<1>")
	)
	(segment
		(start 360.06278 -44.653708)
		(end 358.58958 -44.653708)
		(width 0.14732)
		(layer "In15.Cu")
		(net "P3E_PCH_M2_RX_DN<1>")
	)
	(segment
		(start 361.24388 -41.822878)
		(end 361.24388 -42.259758)
		(width 0.14732)
		(layer "In15.Cu")
		(net "P3E_PCH_M2_RX_DN<1>")
	)
	(segment
		(start 256.445766 -62.831218)
		(end 256.44602 -62.831218)
		(width 0.14732)
		(layer "In15.Cu")
		(net "P3E_PCH_M2_RX_DN<1>")
	)
	(segment
		(start 329.22718 -19.070828)
		(end 330.10094 -19.944588)
		(width 0.14732)
		(layer "In15.Cu")
		(net "P3E_PCH_M2_RX_DN<1>")
	)
	(segment
		(start 273.36369 -58.583322)
		(end 273.363944 -58.583322)
		(width 0.14732)
		(layer "In15.Cu")
		(net "P3E_PCH_M2_RX_DN<1>")
	)
	(segment
		(start 296.544238 -26.280618)
		(end 300.008036 -23.760684)
		(width 0.14732)
		(layer "In15.Cu")
		(net "P3E_PCH_M2_RX_DN<1>")
	)
	(segment
		(start 361.24388 -43.472608)
		(end 360.06278 -44.653708)
		(width 0.14732)
		(layer "In15.Cu")
		(net "P3E_PCH_M2_RX_DN<1>")
	)
	(segment
		(start 357.124 -46.505368)
		(end 356.826566 -46.802802)
		(width 0.14732)
		(layer "In15.Cu")
		(net "P3E_PCH_M2_RX_DN<1>")
	)
	(segment
		(start 330.10094 -19.944588)
		(end 330.10094 -21.369782)
		(width 0.14732)
		(layer "In15.Cu")
		(net "P3E_PCH_M2_RX_DN<1>")
	)
	(segment
		(start 361.24388 -41.142158)
		(end 361.12196 -41.264078)
		(width 0.14732)
		(layer "In15.Cu")
		(net "P3E_PCH_M2_RX_DN<1>")
	)
	(segment
		(start 300.008036 -23.760684)
		(end 319.239646 -19.070828)
		(width 0.14732)
		(layer "In15.Cu")
		(net "P3E_PCH_M2_RX_DN<1>")
	)
	(segment
		(start 360.712512 -34.33318)
		(end 361.24388 -34.864548)
		(width 0.14732)
		(layer "In15.Cu")
		(net "P3E_PCH_M2_RX_DN<1>")
	)
	(segment
		(start 355.42728 -32.146748)
		(end 358.52608 -32.146748)
		(width 0.14732)
		(layer "In15.Cu")
		(net "P3E_PCH_M2_RX_DN<1>")
	)
	(segment
		(start 361.24388 -42.940478)
		(end 361.24388 -43.472608)
		(width 0.14732)
		(layer "In15.Cu")
		(net "P3E_PCH_M2_RX_DN<1>")
	)
	(segment
		(start 361.24388 -40.705278)
		(end 361.24388 -41.142158)
		(width 0.14732)
		(layer "In15.Cu")
		(net "P3E_PCH_M2_RX_DN<1>")
	)
	(segment
		(start 183.598312 -52.478432)
		(end 202.479402 -59.807094)
		(width 0.14732)
		(layer "In15.Cu")
		(net "P3E_PCH_M2_RX_DN<1>")
	)
	(segment
		(start 319.239646 -19.070828)
		(end 329.22718 -19.070828)
		(width 0.14732)
		(layer "In15.Cu")
		(net "P3E_PCH_M2_RX_DN<1>")
	)
	(segment
		(start 360.230928 -33.851596)
		(end 360.230928 -34.024062)
		(width 0.14732)
		(layer "In15.Cu")
		(net "P3E_PCH_M2_RX_DN<1>")
	)
	(segment
		(start 331.657706 -22.926548)
		(end 338.02828 -22.926548)
		(width 0.14732)
		(layer "In15.Cu")
		(net "P3E_PCH_M2_RX_DN<1>")
	)
	(segment
		(start 181.945026 -52.187094)
		(end 182.771796 -52.33289)
		(width 0.14732)
		(layer "In15.Cu")
		(net "P3E_PCH_M2_RX_DN<1>")
	)
	(segment
		(start 241.98707 -65.380108)
		(end 256.445766 -62.831218)
		(width 0.14732)
		(layer "In15.Cu")
		(net "P3E_PCH_M2_RX_DN<1>")
	)
	(segment
		(start 275.770086 -56.898032)
		(end 296.544238 -26.280618)
		(width 0.14732)
		(layer "In15.Cu")
		(net "P3E_PCH_M2_RX_DN<1>")
	)
	(segment
		(start 353.49688 -30.216348)
		(end 355.42728 -32.146748)
		(width 0.14732)
		(layer "In15.Cu")
		(net "P3E_PCH_M2_RX_DN<1>")
	)
	(segment
		(start 361.24388 -39.610538)
		(end 361.24388 -40.047418)
		(width 0.14732)
		(layer "In15.Cu")
		(net "P3E_PCH_M2_RX_DN<1>")
	)
	(segment
		(start 361.24388 -38.929818)
		(end 361.12196 -39.051738)
		(width 0.14732)
		(layer "In15.Cu")
		(net "P3E_PCH_M2_RX_DN<1>")
	)
	(segment
		(start 361.12196 -39.051738)
		(end 361.12196 -39.488618)
		(width 0.14732)
		(layer "In15.Cu")
		(net "P3E_PCH_M2_RX_DN<1>")
	)
	(segment
		(start 353.49688 -28.438348)
		(end 353.49688 -30.216348)
		(width 0.14732)
		(layer "In15.Cu")
		(net "P3E_PCH_M2_RX_DN<1>")
	)
	(segment
		(start 361.0991 -40.560498)
		(end 361.24388 -40.705278)
		(width 0.14732)
		(layer "In15.Cu")
		(net "P3E_PCH_M2_RX_DN<1>")
	)
	(segment
		(start 351.76968 -26.711148)
		(end 353.49688 -28.438348)
		(width 0.14732)
		(layer "In15.Cu")
		(net "P3E_PCH_M2_RX_DN<1>")
	)
	(segment
		(start 360.540046 -34.33318)
		(end 360.712512 -34.33318)
		(width 0.14732)
		(layer "In15.Cu")
		(net "P3E_PCH_M2_RX_DN<1>")
	)
	(segment
		(start 361.24388 -42.259758)
		(end 361.12196 -42.381678)
		(width 0.14732)
		(layer "In15.Cu")
		(net "P3E_PCH_M2_RX_DN<1>")
	)
	(segment
		(start 361.0991 -40.192198)
		(end 361.0991 -40.560498)
		(width 0.14732)
		(layer "In15.Cu")
		(net "P3E_PCH_M2_RX_DN<1>")
	)
	(segment
		(start 360.230928 -34.024062)
		(end 360.540046 -34.33318)
		(width 0.14732)
		(layer "In15.Cu")
		(net "P3E_PCH_M2_RX_DN<1>")
	)
	(segment
		(start 202.479402 -59.807094)
		(end 236.001052 -65.717928)
		(width 0.14732)
		(layer "In15.Cu")
		(net "P3E_PCH_M2_RX_DN<1>")
	)
	(segment
		(start 256.44602 -62.831218)
		(end 270.948912 -60.274708)
		(width 0.14732)
		(layer "In15.Cu")
		(net "P3E_PCH_M2_RX_DN<1>")
	)
	(segment
		(start 182.77205 -52.33289)
		(end 183.598312 -52.478432)
		(width 0.14732)
		(layer "In15.Cu")
		(net "P3E_PCH_M2_RX_DN<1>")
	)
	(segment
		(start 361.12196 -41.700958)
		(end 361.24388 -41.822878)
		(width 0.14732)
		(layer "In15.Cu")
		(net "P3E_PCH_M2_RX_DN<1>")
	)
	(segment
		(start 358.52608 -32.146748)
		(end 360.230928 -33.851596)
		(width 0.14732)
		(layer "In15.Cu")
		(net "P3E_PCH_M2_RX_DN<1>")
	)
	(segment
		(start 273.363944 -58.583322)
		(end 275.770086 -56.898032)
		(width 0.14732)
		(layer "In15.Cu")
		(net "P3E_PCH_M2_RX_DN<1>")
	)
	(segment
		(start 346.74683 -47.95012)
		(end 346.384626 -47.95012)
		(width 0.0889)
		(layer "F.Cu")
		(net "P3E_PCH_M2_RX_DN<0>")
	)
	(segment
		(start 177.765964 -55.299864)
		(end 177.88636 -55.179468)
		(width 0.13208)
		(layer "F.Cu")
		(net "P3E_PCH_M2_RX_DN<0>")
	)
	(segment
		(start 348.324932 -47.879254)
		(end 347.575886 -47.879254)
		(width 0.0889)
		(layer "F.Cu")
		(net "P3E_PCH_M2_RX_DN<0>")
	)
	(segment
		(start 347.039184 -47.674022)
		(end 346.919296 -47.777654)
		(width 0.0889)
		(layer "F.Cu")
		(net "P3E_PCH_M2_RX_DN<0>")
	)
	(segment
		(start 356.288594 -45.346366)
		(end 356.288594 -45.50156)
		(width 0.0889)
		(layer "F.Cu")
		(net "P3E_PCH_M2_RX_DN<0>")
	)
	(segment
		(start 177.108104 -55.299864)
		(end 177.765964 -55.299864)
		(width 0.13208)
		(layer "F.Cu")
		(net "P3E_PCH_M2_RX_DN<0>")
	)
	(segment
		(start 178.70932 -55.179468)
		(end 179.01158 -55.481728)
		(width 0.13208)
		(layer "F.Cu")
		(net "P3E_PCH_M2_RX_DN<0>")
	)
	(segment
		(start 355.44379 -46.346364)
		(end 355.44379 -46.660816)
		(width 0.0889)
		(layer "F.Cu")
		(net "P3E_PCH_M2_RX_DN<0>")
	)
	(segment
		(start 346.919296 -47.777654)
		(end 346.74683 -47.95012)
		(width 0.0889)
		(layer "F.Cu")
		(net "P3E_PCH_M2_RX_DN<0>")
	)
	(segment
		(start 347.575886 -47.879254)
		(end 347.370654 -47.674022)
		(width 0.0889)
		(layer "F.Cu")
		(net "P3E_PCH_M2_RX_DN<0>")
	)
	(segment
		(start 355.940614 -44.998386)
		(end 356.288594 -45.346366)
		(width 0.0889)
		(layer "F.Cu")
		(net "P3E_PCH_M2_RX_DN<0>")
	)
	(segment
		(start 177.88636 -55.179468)
		(end 178.70932 -55.179468)
		(width 0.13208)
		(layer "F.Cu")
		(net "P3E_PCH_M2_RX_DN<0>")
	)
	(segment
		(start 356.288594 -45.50156)
		(end 355.44379 -46.346364)
		(width 0.0889)
		(layer "F.Cu")
		(net "P3E_PCH_M2_RX_DN<0>")
	)
	(segment
		(start 354.788724 -47.315882)
		(end 348.888304 -47.315882)
		(width 0.0889)
		(layer "F.Cu")
		(net "P3E_PCH_M2_RX_DN<0>")
	)
	(segment
		(start 355.44379 -46.660816)
		(end 354.788724 -47.315882)
		(width 0.0889)
		(layer "F.Cu")
		(net "P3E_PCH_M2_RX_DN<0>")
	)
	(segment
		(start 347.370654 -47.674022)
		(end 347.039184 -47.674022)
		(width 0.0889)
		(layer "F.Cu")
		(net "P3E_PCH_M2_RX_DN<0>")
	)
	(segment
		(start 348.888304 -47.315882)
		(end 348.324932 -47.879254)
		(width 0.0889)
		(layer "F.Cu")
		(net "P3E_PCH_M2_RX_DN<0>")
	)
	(segment
		(start 350.41078 -40.202358)
		(end 350.266 -40.057578)
		(width 0.14732)
		(layer "In15.Cu")
		(net "P3E_PCH_M2_RX_DN<0>")
	)
	(segment
		(start 184.352946 -55.305706)
		(end 184.35193 -55.305452)
		(width 0.14732)
		(layer "In15.Cu")
		(net "P3E_PCH_M2_RX_DN<0>")
	)
	(segment
		(start 330.78928 -23.37308)
		(end 329.1713 -21.7551)
		(width 0.14732)
		(layer "In15.Cu")
		(net "P3E_PCH_M2_RX_DN<0>")
	)
	(segment
		(start 236.325664 -66.736976)
		(end 202.346052 -60.746386)
		(width 0.14732)
		(layer "In15.Cu")
		(net "P3E_PCH_M2_RX_DN<0>")
	)
	(segment
		(start 184.336436 -55.302912)
		(end 184.334912 -55.302404)
		(width 0.14732)
		(layer "In15.Cu")
		(net "P3E_PCH_M2_RX_DN<0>")
	)
	(segment
		(start 350.41078 -39.544498)
		(end 350.41078 -38.906958)
		(width 0.14732)
		(layer "In15.Cu")
		(net "P3E_PCH_M2_RX_DN<0>")
	)
	(segment
		(start 184.356248 -55.306214)
		(end 184.352946 -55.305706)
		(width 0.14732)
		(layer "In15.Cu")
		(net "P3E_PCH_M2_RX_DN<0>")
	)
	(segment
		(start 350.266 -38.762178)
		(end 350.266 -38.393878)
		(width 0.14732)
		(layer "In15.Cu")
		(net "P3E_PCH_M2_RX_DN<0>")
	)
	(segment
		(start 355.940614 -44.998386)
		(end 356.126542 -44.998386)
		(width 0.14732)
		(layer "In15.Cu")
		(net "P3E_PCH_M2_RX_DN<0>")
	)
	(segment
		(start 329.1713 -20.356068)
		(end 328.8157 -20.000468)
		(width 0.14732)
		(layer "In15.Cu")
		(net "P3E_PCH_M2_RX_DN<0>")
	)
	(segment
		(start 353.4918 -44.536868)
		(end 350.41078 -41.455848)
		(width 0.14732)
		(layer "In15.Cu")
		(net "P3E_PCH_M2_RX_DN<0>")
	)
	(segment
		(start 350.41078 -38.249098)
		(end 350.41078 -37.31006)
		(width 0.14732)
		(layer "In15.Cu")
		(net "P3E_PCH_M2_RX_DN<0>")
	)
	(segment
		(start 356.126288 -44.536868)
		(end 354.62464 -44.536868)
		(width 0.14732)
		(layer "In15.Cu")
		(net "P3E_PCH_M2_RX_DN<0>")
	)
	(segment
		(start 349.19539 -36.299394)
		(end 349.19539 -36.09467)
		(width 0.14732)
		(layer "In15.Cu")
		(net "P3E_PCH_M2_RX_DN<0>")
	)
	(segment
		(start 329.1713 -21.7551)
		(end 329.1713 -20.356068)
		(width 0.14732)
		(layer "In15.Cu")
		(net "P3E_PCH_M2_RX_DN<0>")
	)
	(segment
		(start 350.41078 -37.31006)
		(end 349.660718 -36.559998)
		(width 0.14732)
		(layer "In15.Cu")
		(net "P3E_PCH_M2_RX_DN<0>")
	)
	(segment
		(start 350.266 -38.393878)
		(end 350.41078 -38.249098)
		(width 0.14732)
		(layer "In15.Cu")
		(net "P3E_PCH_M2_RX_DN<0>")
	)
	(segment
		(start 348.447868 -35.347148)
		(end 347.22308 -35.347148)
		(width 0.14732)
		(layer "In15.Cu")
		(net "P3E_PCH_M2_RX_DN<0>")
	)
	(segment
		(start 356.126542 -44.998386)
		(end 356.235254 -44.889674)
		(width 0.14732)
		(layer "In15.Cu")
		(net "P3E_PCH_M2_RX_DN<0>")
	)
	(segment
		(start 335.61528 -28.870148)
		(end 330.78928 -24.044148)
		(width 0.14732)
		(layer "In15.Cu")
		(net "P3E_PCH_M2_RX_DN<0>")
	)
	(segment
		(start 350.266 -39.689278)
		(end 350.41078 -39.544498)
		(width 0.14732)
		(layer "In15.Cu")
		(net "P3E_PCH_M2_RX_DN<0>")
	)
	(segment
		(start 330.78928 -24.044148)
		(end 330.78928 -23.37308)
		(width 0.14732)
		(layer "In15.Cu")
		(net "P3E_PCH_M2_RX_DN<0>")
	)
	(segment
		(start 184.35193 -55.305452)
		(end 184.35066 -55.305198)
		(width 0.14732)
		(layer "In15.Cu")
		(net "P3E_PCH_M2_RX_DN<0>")
	)
	(segment
		(start 256.460498 -63.78321)
		(end 241.64925 -66.394076)
		(width 0.14732)
		(layer "In15.Cu")
		(net "P3E_PCH_M2_RX_DN<0>")
	)
	(segment
		(start 319.394332 -20.000468)
		(end 308.515512 -22.653498)
		(width 0.14732)
		(layer "In15.Cu")
		(net "P3E_PCH_M2_RX_DN<0>")
	)
	(segment
		(start 354.50272 -44.658788)
		(end 354.06584 -44.658788)
		(width 0.14732)
		(layer "In15.Cu")
		(net "P3E_PCH_M2_RX_DN<0>")
	)
	(segment
		(start 179.30622 -55.187088)
		(end 179.01158 -55.481728)
		(width 0.14732)
		(layer "In15.Cu")
		(net "P3E_PCH_M2_RX_DN<0>")
	)
	(segment
		(start 347.22308 -35.347148)
		(end 340.74608 -28.870148)
		(width 0.14732)
		(layer "In15.Cu")
		(net "P3E_PCH_M2_RX_DN<0>")
	)
	(segment
		(start 277.156164 -57.075324)
		(end 277.15591 -57.075324)
		(width 0.14732)
		(layer "In15.Cu")
		(net "P3E_PCH_M2_RX_DN<0>")
	)
	(segment
		(start 340.74608 -28.870148)
		(end 335.61528 -28.870148)
		(width 0.14732)
		(layer "In15.Cu")
		(net "P3E_PCH_M2_RX_DN<0>")
	)
	(segment
		(start 350.266 -40.057578)
		(end 350.266 -39.689278)
		(width 0.14732)
		(layer "In15.Cu")
		(net "P3E_PCH_M2_RX_DN<0>")
	)
	(segment
		(start 256.460498 -63.783464)
		(end 256.460498 -63.78321)
		(width 0.14732)
		(layer "In15.Cu")
		(net "P3E_PCH_M2_RX_DN<0>")
	)
	(segment
		(start 356.235254 -44.645834)
		(end 356.126288 -44.536868)
		(width 0.14732)
		(layer "In15.Cu")
		(net "P3E_PCH_M2_RX_DN<0>")
	)
	(segment
		(start 350.41078 -38.906958)
		(end 350.266 -38.762178)
		(width 0.14732)
		(layer "In15.Cu")
		(net "P3E_PCH_M2_RX_DN<0>")
	)
	(segment
		(start 183.681878 -55.187088)
		(end 179.30622 -55.187088)
		(width 0.14732)
		(layer "In15.Cu")
		(net "P3E_PCH_M2_RX_DN<0>")
	)
	(segment
		(start 328.8157 -20.000468)
		(end 319.394332 -20.000468)
		(width 0.14732)
		(layer "In15.Cu")
		(net "P3E_PCH_M2_RX_DN<0>")
	)
	(segment
		(start 350.41078 -41.455848)
		(end 350.41078 -40.202358)
		(width 0.14732)
		(layer "In15.Cu")
		(net "P3E_PCH_M2_RX_DN<0>")
	)
	(segment
		(start 184.35066 -55.305198)
		(end 184.336436 -55.302912)
		(width 0.14732)
		(layer "In15.Cu")
		(net "P3E_PCH_M2_RX_DN<0>")
	)
	(segment
		(start 271.317466 -61.16447)
		(end 256.460498 -63.783464)
		(width 0.14732)
		(layer "In15.Cu")
		(net "P3E_PCH_M2_RX_DN<0>")
	)
	(segment
		(start 308.515512 -22.653498)
		(end 298.75099 -29.757116)
		(width 0.14732)
		(layer "In15.Cu")
		(net "P3E_PCH_M2_RX_DN<0>")
	)
	(segment
		(start 202.346052 -60.746386)
		(end 184.883298 -55.398924)
		(width 0.14732)
		(layer "In15.Cu")
		(net "P3E_PCH_M2_RX_DN<0>")
	)
	(segment
		(start 356.235254 -44.889674)
		(end 356.235254 -44.645834)
		(width 0.14732)
		(layer "In15.Cu")
		(net "P3E_PCH_M2_RX_DN<0>")
	)
	(segment
		(start 184.35701 -55.306468)
		(end 184.356248 -55.306214)
		(width 0.14732)
		(layer "In15.Cu")
		(net "P3E_PCH_M2_RX_DN<0>")
	)
	(segment
		(start 349.660718 -36.559998)
		(end 349.455994 -36.559998)
		(width 0.14732)
		(layer "In15.Cu")
		(net "P3E_PCH_M2_RX_DN<0>")
	)
	(segment
		(start 277.15591 -57.075324)
		(end 271.317466 -61.16447)
		(width 0.14732)
		(layer "In15.Cu")
		(net "P3E_PCH_M2_RX_DN<0>")
	)
	(segment
		(start 282.985972 -52.992274)
		(end 277.156164 -57.075324)
		(width 0.14732)
		(layer "In15.Cu")
		(net "P3E_PCH_M2_RX_DN<0>")
	)
	(segment
		(start 184.334912 -55.302404)
		(end 183.681878 -55.187088)
		(width 0.14732)
		(layer "In15.Cu")
		(net "P3E_PCH_M2_RX_DN<0>")
	)
	(segment
		(start 241.64925 -66.394076)
		(end 236.325664 -66.736976)
		(width 0.14732)
		(layer "In15.Cu")
		(net "P3E_PCH_M2_RX_DN<0>")
	)
	(segment
		(start 349.455994 -36.559998)
		(end 349.19539 -36.299394)
		(width 0.14732)
		(layer "In15.Cu")
		(net "P3E_PCH_M2_RX_DN<0>")
	)
	(segment
		(start 298.75099 -29.757116)
		(end 282.985972 -52.992274)
		(width 0.14732)
		(layer "In15.Cu")
		(net "P3E_PCH_M2_RX_DN<0>")
	)
	(segment
		(start 349.19539 -36.09467)
		(end 348.447868 -35.347148)
		(width 0.14732)
		(layer "In15.Cu")
		(net "P3E_PCH_M2_RX_DN<0>")
	)
	(segment
		(start 353.94392 -44.536868)
		(end 353.4918 -44.536868)
		(width 0.14732)
		(layer "In15.Cu")
		(net "P3E_PCH_M2_RX_DN<0>")
	)
	(segment
		(start 354.62464 -44.536868)
		(end 354.50272 -44.658788)
		(width 0.14732)
		(layer "In15.Cu")
		(net "P3E_PCH_M2_RX_DN<0>")
	)
	(segment
		(start 184.883298 -55.398924)
		(end 184.35701 -55.306468)
		(width 0.14732)
		(layer "In15.Cu")
		(net "P3E_PCH_M2_RX_DN<0>")
	)
	(segment
		(start 354.06584 -44.658788)
		(end 353.94392 -44.536868)
		(width 0.14732)
		(layer "In15.Cu")
		(net "P3E_PCH_M2_RX_DN<0>")
	)
	(segment
		(start 344.63355 -48.450246)
		(end 344.363294 -47.980092)
		(width 0.13208)
		(layer "F.Cu")
		(net "P3E_PCH_BMC_TX_DP")
	)
	(via
		(at 344.363294 -47.980092)
		(size 0.4572)
		(drill 0.2032)
		(layers "F.Cu" "B.Cu")
		(net "P3E_PCH_BMC_TX_DP")
	)
	(segment
		(start 169.09669 -8.898382)
		(end 169.389806 -9.191498)
		(width 0.13208)
		(layer "B.Cu")
		(net "P3E_PCH_BMC_TX_DP")
	)
	(segment
		(start 344.939874 -48.354742)
		(end 345.656916 -49.071784)
		(width 0.0889)
		(layer "B.Cu")
		(net "P3E_PCH_BMC_TX_DP")
	)
	(segment
		(start 165.40226 -14.716506)
		(end 165.40226 -10.491978)
		(width 0.13208)
		(layer "B.Cu")
		(net "P3E_PCH_BMC_TX_DP")
	)
	(segment
		(start 181.047898 -46.258988)
		(end 179.493418 -44.704508)
		(width 0.13208)
		(layer "B.Cu")
		(net "P3E_PCH_BMC_TX_DP")
	)
	(segment
		(start 356.15626 -58.735468)
		(end 354.79228 -60.099448)
		(width 0.13208)
		(layer "B.Cu")
		(net "P3E_PCH_BMC_TX_DP")
	)
	(segment
		(start 166.233856 -9.02589)
		(end 167.387778 -7.871968)
		(width 0.13208)
		(layer "B.Cu")
		(net "P3E_PCH_BMC_TX_DP")
	)
	(segment
		(start 163.17214 -27.617674)
		(end 163.17214 -21.29663)
		(width 0.13208)
		(layer "B.Cu")
		(net "P3E_PCH_BMC_TX_DP")
	)
	(segment
		(start 353.187 -79.54899)
		(end 344.958162 -87.777828)
		(width 0.13208)
		(layer "B.Cu")
		(net "P3E_PCH_BMC_TX_DP")
	)
	(segment
		(start 165.561518 -33.137348)
		(end 165.290246 -32.731456)
		(width 0.13208)
		(layer "B.Cu")
		(net "P3E_PCH_BMC_TX_DP")
	)
	(segment
		(start 230.19639 -68.099178)
		(end 227.731066 -65.633854)
		(width 0.13208)
		(layer "B.Cu")
		(net "P3E_PCH_BMC_TX_DP")
	)
	(segment
		(start 162.60064 -17.518126)
		(end 165.40226 -14.716506)
		(width 0.13208)
		(layer "B.Cu")
		(net "P3E_PCH_BMC_TX_DP")
	)
	(segment
		(start 344.343736 -48.354742)
		(end 344.939874 -48.354742)
		(width 0.0889)
		(layer "B.Cu")
		(net "P3E_PCH_BMC_TX_DP")
	)
	(segment
		(start 354.79228 -60.099448)
		(end 354.79228 -71.893176)
		(width 0.13208)
		(layer "B.Cu")
		(net "P3E_PCH_BMC_TX_DP")
	)
	(segment
		(start 166.84117 -34.417)
		(end 165.561518 -33.137348)
		(width 0.13208)
		(layer "B.Cu")
		(net "P3E_PCH_BMC_TX_DP")
	)
	(segment
		(start 163.17214 -21.29663)
		(end 162.60064 -20.72513)
		(width 0.13208)
		(layer "B.Cu")
		(net "P3E_PCH_BMC_TX_DP")
	)
	(segment
		(start 167.51808 -36.051236)
		(end 166.84117 -34.417)
		(width 0.13208)
		(layer "B.Cu")
		(net "P3E_PCH_BMC_TX_DP")
	)
	(segment
		(start 353.187 -76.779374)
		(end 353.187 -79.54899)
		(width 0.13208)
		(layer "B.Cu")
		(net "P3E_PCH_BMC_TX_DP")
	)
	(segment
		(start 183.608218 -46.258988)
		(end 181.047898 -46.258988)
		(width 0.13208)
		(layer "B.Cu")
		(net "P3E_PCH_BMC_TX_DP")
	)
	(segment
		(start 162.60064 -20.72513)
		(end 162.60064 -17.518126)
		(width 0.13208)
		(layer "B.Cu")
		(net "P3E_PCH_BMC_TX_DP")
	)
	(segment
		(start 355.11486 -54.087268)
		(end 355.11486 -56.618632)
		(width 0.13208)
		(layer "B.Cu")
		(net "P3E_PCH_BMC_TX_DP")
	)
	(segment
		(start 353.06508 -52.037488)
		(end 355.11486 -54.087268)
		(width 0.13208)
		(layer "B.Cu")
		(net "P3E_PCH_BMC_TX_DP")
	)
	(segment
		(start 345.721178 -49.087278)
		(end 348.671388 -52.037488)
		(width 0.13208)
		(layer "B.Cu")
		(net "P3E_PCH_BMC_TX_DP")
	)
	(segment
		(start 165.290246 -32.731456)
		(end 163.17214 -27.617674)
		(width 0.13208)
		(layer "B.Cu")
		(net "P3E_PCH_BMC_TX_DP")
	)
	(segment
		(start 167.387778 -7.871968)
		(end 168.71061 -7.871968)
		(width 0.13208)
		(layer "B.Cu")
		(net "P3E_PCH_BMC_TX_DP")
	)
	(segment
		(start 344.363294 -47.980092)
		(end 344.091768 -47.823882)
		(width 0.0889)
		(layer "B.Cu")
		(net "P3E_PCH_BMC_TX_DP")
	)
	(segment
		(start 191.03848 -49.959768)
		(end 187.308998 -49.959768)
		(width 0.13208)
		(layer "B.Cu")
		(net "P3E_PCH_BMC_TX_DP")
	)
	(segment
		(start 345.656916 -49.071784)
		(end 345.705684 -49.071784)
		(width 0.0889)
		(layer "B.Cu")
		(net "P3E_PCH_BMC_TX_DP")
	)
	(segment
		(start 227.731066 -65.633854)
		(end 216.30767 -60.902088)
		(width 0.13208)
		(layer "B.Cu")
		(net "P3E_PCH_BMC_TX_DP")
	)
	(segment
		(start 356.15626 -57.660032)
		(end 356.15626 -58.735468)
		(width 0.13208)
		(layer "B.Cu")
		(net "P3E_PCH_BMC_TX_DP")
	)
	(segment
		(start 173.746414 -44.704508)
		(end 167.51808 -38.476174)
		(width 0.13208)
		(layer "B.Cu")
		(net "P3E_PCH_BMC_TX_DP")
	)
	(segment
		(start 287.078928 -82.850228)
		(end 281.621484 -80.589628)
		(width 0.13208)
		(layer "B.Cu")
		(net "P3E_PCH_BMC_TX_DP")
	)
	(segment
		(start 169.09669 -8.258048)
		(end 169.09669 -8.898382)
		(width 0.13208)
		(layer "B.Cu")
		(net "P3E_PCH_BMC_TX_DP")
	)
	(segment
		(start 329.815698 -82.850228)
		(end 287.078928 -82.850228)
		(width 0.13208)
		(layer "B.Cu")
		(net "P3E_PCH_BMC_TX_DP")
	)
	(segment
		(start 168.71061 -7.871968)
		(end 169.09669 -8.258048)
		(width 0.13208)
		(layer "B.Cu")
		(net "P3E_PCH_BMC_TX_DP")
	)
	(segment
		(start 354.405438 -73.8378)
		(end 353.187 -76.779374)
		(width 0.13208)
		(layer "B.Cu")
		(net "P3E_PCH_BMC_TX_DP")
	)
	(segment
		(start 344.958162 -87.777828)
		(end 341.712042 -87.777828)
		(width 0.13208)
		(layer "B.Cu")
		(net "P3E_PCH_BMC_TX_DP")
	)
	(segment
		(start 355.11486 -56.618632)
		(end 356.15626 -57.660032)
		(width 0.13208)
		(layer "B.Cu")
		(net "P3E_PCH_BMC_TX_DP")
	)
	(segment
		(start 354.79228 -71.893176)
		(end 354.405438 -73.8378)
		(width 0.13208)
		(layer "B.Cu")
		(net "P3E_PCH_BMC_TX_DP")
	)
	(segment
		(start 167.51808 -38.476174)
		(end 167.51808 -36.051236)
		(width 0.13208)
		(layer "B.Cu")
		(net "P3E_PCH_BMC_TX_DP")
	)
	(segment
		(start 238.695484 -70.298818)
		(end 232.561892 -69.078856)
		(width 0.13208)
		(layer "B.Cu")
		(net "P3E_PCH_BMC_TX_DP")
	)
	(segment
		(start 281.621484 -80.589628)
		(end 251.334778 -80.589628)
		(width 0.13208)
		(layer "B.Cu")
		(net "P3E_PCH_BMC_TX_DP")
	)
	(segment
		(start 251.334778 -80.589628)
		(end 242.70462 -71.95947)
		(width 0.13208)
		(layer "B.Cu")
		(net "P3E_PCH_BMC_TX_DP")
	)
	(segment
		(start 216.30767 -60.902088)
		(end 201.9808 -60.902088)
		(width 0.13208)
		(layer "B.Cu")
		(net "P3E_PCH_BMC_TX_DP")
	)
	(segment
		(start 201.9808 -60.902088)
		(end 191.03848 -49.959768)
		(width 0.13208)
		(layer "B.Cu")
		(net "P3E_PCH_BMC_TX_DP")
	)
	(segment
		(start 341.712042 -87.777828)
		(end 329.815698 -82.850228)
		(width 0.13208)
		(layer "B.Cu")
		(net "P3E_PCH_BMC_TX_DP")
	)
	(segment
		(start 165.40226 -10.491978)
		(end 165.64356 -9.909556)
		(width 0.13208)
		(layer "B.Cu")
		(net "P3E_PCH_BMC_TX_DP")
	)
	(segment
		(start 348.671388 -52.037488)
		(end 353.06508 -52.037488)
		(width 0.13208)
		(layer "B.Cu")
		(net "P3E_PCH_BMC_TX_DP")
	)
	(segment
		(start 344.091768 -47.823882)
		(end 344.013536 -47.845218)
		(width 0.0889)
		(layer "B.Cu")
		(net "P3E_PCH_BMC_TX_DP")
	)
	(segment
		(start 242.70462 -71.95947)
		(end 238.695484 -70.298818)
		(width 0.13208)
		(layer "B.Cu")
		(net "P3E_PCH_BMC_TX_DP")
	)
	(segment
		(start 187.308998 -49.959768)
		(end 183.608218 -46.258988)
		(width 0.13208)
		(layer "B.Cu")
		(net "P3E_PCH_BMC_TX_DP")
	)
	(segment
		(start 165.64356 -9.909556)
		(end 166.233856 -9.02589)
		(width 0.13208)
		(layer "B.Cu")
		(net "P3E_PCH_BMC_TX_DP")
	)
	(segment
		(start 179.493418 -44.704508)
		(end 173.746414 -44.704508)
		(width 0.13208)
		(layer "B.Cu")
		(net "P3E_PCH_BMC_TX_DP")
	)
	(segment
		(start 345.705684 -49.071784)
		(end 345.721178 -49.087278)
		(width 0.0889)
		(layer "B.Cu")
		(net "P3E_PCH_BMC_TX_DP")
	)
	(segment
		(start 232.561892 -69.078856)
		(end 230.19639 -68.099178)
		(width 0.13208)
		(layer "B.Cu")
		(net "P3E_PCH_BMC_TX_DP")
	)
	(arc
		(start 344.013536 -47.845218)
		(mid 343.989456 -48.009031)
		(end 344.038174 -48.16729)
		(width 0.0889)
		(layer "B.Cu")
		(net "P3E_PCH_BMC_TX_DP")
	)
	(arc
		(start 344.038174 -48.16729)
		(mid 344.167117 -48.299874)
		(end 344.343736 -48.354742)
		(width 0.0889)
		(layer "B.Cu")
		(net "P3E_PCH_BMC_TX_DP")
	)
	(segment
		(start 343.547954 -47.5107)
		(end 343.81948 -47.980346)
		(width 0.13208)
		(layer "F.Cu")
		(net "P3E_PCH_BMC_TX_DN")
	)
	(segment
		(start 343.547954 -47.510192)
		(end 343.547954 -47.5107)
		(width 0.13208)
		(layer "F.Cu")
		(net "P3E_PCH_BMC_TX_DN")
	)
	(via
		(at 343.547954 -47.510192)
		(size 0.4572)
		(drill 0.2032)
		(layers "F.Cu" "B.Cu")
		(net "P3E_PCH_BMC_TX_DN")
	)
	(segment
		(start 165.66134 -14.823948)
		(end 165.66134 -13.862558)
		(width 0.13208)
		(layer "B.Cu")
		(net "P3E_PCH_BMC_TX_DN")
	)
	(segment
		(start 163.43122 -21.944838)
		(end 163.43122 -21.189188)
		(width 0.13208)
		(layer "B.Cu")
		(net "P3E_PCH_BMC_TX_DN")
	)
	(segment
		(start 227.877878 -65.414144)
		(end 222.118682 -63.028322)
		(width 0.13208)
		(layer "B.Cu")
		(net "P3E_PCH_BMC_TX_DN")
	)
	(segment
		(start 162.85972 -19.290538)
		(end 162.85972 -18.896838)
		(width 0.13208)
		(layer "B.Cu")
		(net "P3E_PCH_BMC_TX_DN")
	)
	(segment
		(start 162.85972 -18.896838)
		(end 162.98418 -18.772378)
		(width 0.13208)
		(layer "B.Cu")
		(net "P3E_PCH_BMC_TX_DN")
	)
	(segment
		(start 162.98418 -19.808698)
		(end 162.98418 -19.414998)
		(width 0.13208)
		(layer "B.Cu")
		(net "P3E_PCH_BMC_TX_DN")
	)
	(segment
		(start 163.55568 -22.462998)
		(end 163.55568 -22.069298)
		(width 0.13208)
		(layer "B.Cu")
		(net "P3E_PCH_BMC_TX_DN")
	)
	(segment
		(start 167.216836 -8.5852)
		(end 167.216836 -8.409432)
		(width 0.13208)
		(layer "B.Cu")
		(net "P3E_PCH_BMC_TX_DN")
	)
	(segment
		(start 163.43122 -27.566112)
		(end 163.43122 -24.660098)
		(width 0.13208)
		(layer "B.Cu")
		(net "P3E_PCH_BMC_TX_DN")
	)
	(segment
		(start 242.851432 -71.73976)
		(end 238.771176 -70.049644)
		(width 0.13208)
		(layer "B.Cu")
		(net "P3E_PCH_BMC_TX_DN")
	)
	(segment
		(start 222.118428 -63.028068)
		(end 216.359232 -60.643008)
		(width 0.13208)
		(layer "B.Cu")
		(net "P3E_PCH_BMC_TX_DN")
	)
	(segment
		(start 166.435278 -9.191244)
		(end 166.76243 -8.863838)
		(width 0.13208)
		(layer "B.Cu")
		(net "P3E_PCH_BMC_TX_DN")
	)
	(segment
		(start 162.85972 -17.625568)
		(end 164.19576 -16.289528)
		(width 0.13208)
		(layer "B.Cu")
		(net "P3E_PCH_BMC_TX_DN")
	)
	(segment
		(start 163.55568 -24.141938)
		(end 163.43122 -24.017478)
		(width 0.13208)
		(layer "B.Cu")
		(net "P3E_PCH_BMC_TX_DN")
	)
	(segment
		(start 191.145922 -49.700688)
		(end 187.41644 -49.700688)
		(width 0.13208)
		(layer "B.Cu")
		(net "P3E_PCH_BMC_TX_DN")
	)
	(segment
		(start 167.77716 -38.368732)
		(end 167.77716 -35.999674)
		(width 0.13208)
		(layer "B.Cu")
		(net "P3E_PCH_BMC_TX_DN")
	)
	(segment
		(start 165.7858 -13.738098)
		(end 165.7858 -13.344398)
		(width 0.13208)
		(layer "B.Cu")
		(net "P3E_PCH_BMC_TX_DN")
	)
	(segment
		(start 165.382956 -15.2781)
		(end 165.382956 -15.102332)
		(width 0.13208)
		(layer "B.Cu")
		(net "P3E_PCH_BMC_TX_DN")
	)
	(segment
		(start 163.43122 -24.660098)
		(end 163.55568 -24.535638)
		(width 0.13208)
		(layer "B.Cu")
		(net "P3E_PCH_BMC_TX_DN")
	)
	(segment
		(start 181.15534 -45.999908)
		(end 179.60086 -44.445428)
		(width 0.13208)
		(layer "B.Cu")
		(net "P3E_PCH_BMC_TX_DN")
	)
	(segment
		(start 183.71566 -45.999908)
		(end 181.15534 -45.999908)
		(width 0.13208)
		(layer "B.Cu")
		(net "P3E_PCH_BMC_TX_DN")
	)
	(segment
		(start 355.89718 -58.628026)
		(end 354.5332 -59.992006)
		(width 0.13208)
		(layer "B.Cu")
		(net "P3E_PCH_BMC_TX_DN")
	)
	(segment
		(start 166.938198 -8.863838)
		(end 167.216836 -8.5852)
		(width 0.13208)
		(layer "B.Cu")
		(net "P3E_PCH_BMC_TX_DN")
	)
	(segment
		(start 251.44222 -80.330548)
		(end 242.851432 -71.73976)
		(width 0.13208)
		(layer "B.Cu")
		(net "P3E_PCH_BMC_TX_DN")
	)
	(segment
		(start 202.088242 -60.643008)
		(end 191.145922 -49.700688)
		(width 0.13208)
		(layer "B.Cu")
		(net "P3E_PCH_BMC_TX_DN")
	)
	(segment
		(start 165.66134 -11.875008)
		(end 165.66134 -11.383518)
		(width 0.13208)
		(layer "B.Cu")
		(net "P3E_PCH_BMC_TX_DN")
	)
	(segment
		(start 355.89718 -57.767474)
		(end 355.89718 -58.628026)
		(width 0.13208)
		(layer "B.Cu")
		(net "P3E_PCH_BMC_TX_DN")
	)
	(segment
		(start 165.520116 -32.60852)
		(end 163.43122 -27.566112)
		(width 0.13208)
		(layer "B.Cu")
		(net "P3E_PCH_BMC_TX_DN")
	)
	(segment
		(start 187.41644 -49.700688)
		(end 183.71566 -45.999908)
		(width 0.13208)
		(layer "B.Cu")
		(net "P3E_PCH_BMC_TX_DN")
	)
	(segment
		(start 165.7858 -13.344398)
		(end 165.66134 -13.219938)
		(width 0.13208)
		(layer "B.Cu")
		(net "P3E_PCH_BMC_TX_DN")
	)
	(segment
		(start 165.382956 -15.102332)
		(end 165.66134 -14.823948)
		(width 0.13208)
		(layer "B.Cu")
		(net "P3E_PCH_BMC_TX_DN")
	)
	(segment
		(start 162.85972 -20.617688)
		(end 162.85972 -19.933158)
		(width 0.13208)
		(layer "B.Cu")
		(net "P3E_PCH_BMC_TX_DN")
	)
	(segment
		(start 351.00133 -81.368138)
		(end 350.722946 -81.646522)
		(width 0.13208)
		(layer "B.Cu")
		(net "P3E_PCH_BMC_TX_DN")
	)
	(segment
		(start 164.92855 -15.556738)
		(end 165.104318 -15.556738)
		(width 0.13208)
		(layer "B.Cu")
		(net "P3E_PCH_BMC_TX_DN")
	)
	(segment
		(start 167.216836 -8.409432)
		(end 167.49522 -8.131048)
		(width 0.13208)
		(layer "B.Cu")
		(net "P3E_PCH_BMC_TX_DN")
	)
	(segment
		(start 162.85972 -19.933158)
		(end 162.98418 -19.808698)
		(width 0.13208)
		(layer "B.Cu")
		(net "P3E_PCH_BMC_TX_DN")
	)
	(segment
		(start 162.98418 -18.378678)
		(end 162.85972 -18.254218)
		(width 0.13208)
		(layer "B.Cu")
		(net "P3E_PCH_BMC_TX_DN")
	)
	(segment
		(start 230.343202 -67.879468)
		(end 227.877878 -65.414144)
		(width 0.13208)
		(layer "B.Cu")
		(net "P3E_PCH_BMC_TX_DN")
	)
	(segment
		(start 168.83761 -8.898128)
		(end 168.544494 -9.191244)
		(width 0.13208)
		(layer "B.Cu")
		(net "P3E_PCH_BMC_TX_DN")
	)
	(segment
		(start 343.81948 -47.666402)
		(end 343.84361 -47.75581)
		(width 0.0889)
		(layer "B.Cu")
		(net "P3E_PCH_BMC_TX_DN")
	)
	(segment
		(start 350.26854 -82.100928)
		(end 349.990156 -82.379312)
		(width 0.13208)
		(layer "B.Cu")
		(net "P3E_PCH_BMC_TX_DN")
	)
	(segment
		(start 352.92792 -79.441548)
		(end 351.455736 -80.913732)
		(width 0.13208)
		(layer "B.Cu")
		(net "P3E_PCH_BMC_TX_DN")
	)
	(segment
		(start 281.673046 -80.330548)
		(end 251.44222 -80.330548)
		(width 0.13208)
		(layer "B.Cu")
		(net "P3E_PCH_BMC_TX_DN")
	)
	(segment
		(start 164.371528 -16.289528)
		(end 164.650166 -16.01089)
		(width 0.13208)
		(layer "B.Cu")
		(net "P3E_PCH_BMC_TX_DN")
	)
	(segment
		(start 163.55568 -23.499318)
		(end 163.55568 -23.105618)
		(width 0.13208)
		(layer "B.Cu")
		(net "P3E_PCH_BMC_TX_DN")
	)
	(segment
		(start 164.19576 -16.289528)
		(end 164.371528 -16.289528)
		(width 0.13208)
		(layer "B.Cu")
		(net "P3E_PCH_BMC_TX_DN")
	)
	(segment
		(start 167.49522 -8.131048)
		(end 168.603168 -8.131048)
		(width 0.13208)
		(layer "B.Cu")
		(net "P3E_PCH_BMC_TX_DN")
	)
	(segment
		(start 348.80296 -83.39074)
		(end 348.80296 -83.566508)
		(width 0.13208)
		(layer "B.Cu")
		(net "P3E_PCH_BMC_TX_DN")
	)
	(segment
		(start 222.118682 -63.028322)
		(end 222.118428 -63.028068)
		(width 0.13208)
		(layer "B.Cu")
		(net "P3E_PCH_BMC_TX_DN")
	)
	(segment
		(start 165.7858 -12.380468)
		(end 165.7858 -11.999468)
		(width 0.13208)
		(layer "B.Cu")
		(net "P3E_PCH_BMC_TX_DN")
	)
	(segment
		(start 344.334084 -48.545242)
		(end 344.861134 -48.545242)
		(width 0.0889)
		(layer "B.Cu")
		(net "P3E_PCH_BMC_TX_DN")
	)
	(segment
		(start 354.85578 -54.19471)
		(end 354.85578 -56.726074)
		(width 0.13208)
		(layer "B.Cu")
		(net "P3E_PCH_BMC_TX_DN")
	)
	(segment
		(start 163.55568 -22.069298)
		(end 163.43122 -21.944838)
		(width 0.13208)
		(layer "B.Cu")
		(net "P3E_PCH_BMC_TX_DN")
	)
	(segment
		(start 165.7858 -11.259058)
		(end 165.7858 -10.865358)
		(width 0.13208)
		(layer "B.Cu")
		(net "P3E_PCH_BMC_TX_DN")
	)
	(segment
		(start 166.76243 -8.863838)
		(end 166.938198 -8.863838)
		(width 0.13208)
		(layer "B.Cu")
		(net "P3E_PCH_BMC_TX_DN")
	)
	(segment
		(start 238.771176 -70.049644)
		(end 232.637584 -68.829428)
		(width 0.13208)
		(layer "B.Cu")
		(net "P3E_PCH_BMC_TX_DN")
	)
	(segment
		(start 165.7858 -11.999468)
		(end 165.66134 -11.875008)
		(width 0.13208)
		(layer "B.Cu")
		(net "P3E_PCH_BMC_TX_DN")
	)
	(segment
		(start 164.650166 -15.835122)
		(end 164.92855 -15.556738)
		(width 0.13208)
		(layer "B.Cu")
		(net "P3E_PCH_BMC_TX_DN")
	)
	(segment
		(start 162.98418 -19.414998)
		(end 162.85972 -19.290538)
		(width 0.13208)
		(layer "B.Cu")
		(net "P3E_PCH_BMC_TX_DN")
	)
	(segment
		(start 164.650166 -16.01089)
		(end 164.650166 -15.835122)
		(width 0.13208)
		(layer "B.Cu")
		(net "P3E_PCH_BMC_TX_DN")
	)
	(segment
		(start 351.00133 -81.19237)
		(end 351.00133 -81.368138)
		(width 0.13208)
		(layer "B.Cu")
		(net "P3E_PCH_BMC_TX_DN")
	)
	(segment
		(start 352.80346 -78.031848)
		(end 352.92792 -78.156308)
		(width 0.13208)
		(layer "B.Cu")
		(net "P3E_PCH_BMC_TX_DN")
	)
	(segment
		(start 352.80346 -77.650848)
		(end 352.80346 -78.031848)
		(width 0.13208)
		(layer "B.Cu")
		(net "P3E_PCH_BMC_TX_DN")
	)
	(segment
		(start 345.522296 -49.255172)
		(end 345.53779 -49.270666)
		(width 0.0889)
		(layer "B.Cu")
		(net "P3E_PCH_BMC_TX_DN")
	)
	(segment
		(start 168.83761 -8.36549)
		(end 168.83761 -8.898128)
		(width 0.13208)
		(layer "B.Cu")
		(net "P3E_PCH_BMC_TX_DN")
	)
	(segment
		(start 349.814388 -82.379312)
		(end 349.53575 -82.65795)
		(width 0.13208)
		(layer "B.Cu")
		(net "P3E_PCH_BMC_TX_DN")
	)
	(segment
		(start 352.957638 -52.296568)
		(end 354.85578 -54.19471)
		(width 0.13208)
		(layer "B.Cu")
		(net "P3E_PCH_BMC_TX_DN")
	)
	(segment
		(start 163.43122 -21.189188)
		(end 162.85972 -20.617688)
		(width 0.13208)
		(layer "B.Cu")
		(net "P3E_PCH_BMC_TX_DN")
	)
	(segment
		(start 351.279968 -80.913732)
		(end 351.00133 -81.19237)
		(width 0.13208)
		(layer "B.Cu")
		(net "P3E_PCH_BMC_TX_DN")
	)
	(segment
		(start 165.7858 -10.865358)
		(end 165.66134 -10.740898)
		(width 0.13208)
		(layer "B.Cu")
		(net "P3E_PCH_BMC_TX_DN")
	)
	(segment
		(start 232.637584 -68.829428)
		(end 230.343202 -67.879468)
		(width 0.13208)
		(layer "B.Cu")
		(net "P3E_PCH_BMC_TX_DN")
	)
	(segment
		(start 165.104318 -15.556738)
		(end 165.382956 -15.2781)
		(width 0.13208)
		(layer "B.Cu")
		(net "P3E_PCH_BMC_TX_DN")
	)
	(segment
		(start 352.92792 -77.526388)
		(end 352.80346 -77.650848)
		(width 0.13208)
		(layer "B.Cu")
		(net "P3E_PCH_BMC_TX_DN")
	)
	(segment
		(start 163.43122 -24.017478)
		(end 163.43122 -23.623778)
		(width 0.13208)
		(layer "B.Cu")
		(net "P3E_PCH_BMC_TX_DN")
	)
	(segment
		(start 349.53575 -82.65795)
		(end 349.53575 -82.833718)
		(width 0.13208)
		(layer "B.Cu")
		(net "P3E_PCH_BMC_TX_DN")
	)
	(segment
		(start 354.85578 -56.726074)
		(end 355.89718 -57.767474)
		(width 0.13208)
		(layer "B.Cu")
		(net "P3E_PCH_BMC_TX_DN")
	)
	(segment
		(start 165.66134 -13.219938)
		(end 165.66134 -12.504928)
		(width 0.13208)
		(layer "B.Cu")
		(net "P3E_PCH_BMC_TX_DN")
	)
	(segment
		(start 354.5332 -59.992006)
		(end 354.5332 -71.867522)
		(width 0.13208)
		(layer "B.Cu")
		(net "P3E_PCH_BMC_TX_DN")
	)
	(segment
		(start 350.722946 -81.646522)
		(end 350.547178 -81.646522)
		(width 0.13208)
		(layer "B.Cu")
		(net "P3E_PCH_BMC_TX_DN")
	)
	(segment
		(start 165.66134 -12.504928)
		(end 165.7858 -12.380468)
		(width 0.13208)
		(layer "B.Cu")
		(net "P3E_PCH_BMC_TX_DN")
	)
	(segment
		(start 165.66134 -11.383518)
		(end 165.7858 -11.259058)
		(width 0.13208)
		(layer "B.Cu")
		(net "P3E_PCH_BMC_TX_DN")
	)
	(segment
		(start 163.43122 -22.587458)
		(end 163.55568 -22.462998)
		(width 0.13208)
		(layer "B.Cu")
		(net "P3E_PCH_BMC_TX_DN")
	)
	(segment
		(start 349.257366 -83.112102)
		(end 349.081598 -83.112102)
		(width 0.13208)
		(layer "B.Cu")
		(net "P3E_PCH_BMC_TX_DN")
	)
	(segment
		(start 165.66134 -10.740898)
		(end 165.66134 -10.54354)
		(width 0.13208)
		(layer "B.Cu")
		(net "P3E_PCH_BMC_TX_DN")
	)
	(segment
		(start 287.13049 -82.591148)
		(end 281.673046 -80.330548)
		(width 0.13208)
		(layer "B.Cu")
		(net "P3E_PCH_BMC_TX_DN")
	)
	(segment
		(start 345.522296 -49.206404)
		(end 345.522296 -49.255172)
		(width 0.0889)
		(layer "B.Cu")
		(net "P3E_PCH_BMC_TX_DN")
	)
	(segment
		(start 162.85972 -18.254218)
		(end 162.85972 -17.625568)
		(width 0.13208)
		(layer "B.Cu")
		(net "P3E_PCH_BMC_TX_DN")
	)
	(segment
		(start 344.85072 -87.518748)
		(end 341.763604 -87.518748)
		(width 0.13208)
		(layer "B.Cu")
		(net "P3E_PCH_BMC_TX_DN")
	)
	(segment
		(start 163.43122 -23.623778)
		(end 163.55568 -23.499318)
		(width 0.13208)
		(layer "B.Cu")
		(net "P3E_PCH_BMC_TX_DN")
	)
	(segment
		(start 348.563692 -52.296568)
		(end 352.957638 -52.296568)
		(width 0.13208)
		(layer "B.Cu")
		(net "P3E_PCH_BMC_TX_DN")
	)
	(segment
		(start 349.990156 -82.379312)
		(end 349.814388 -82.379312)
		(width 0.13208)
		(layer "B.Cu")
		(net "P3E_PCH_BMC_TX_DN")
	)
	(segment
		(start 345.53779 -49.270666)
		(end 348.563692 -52.296568)
		(width 0.13208)
		(layer "B.Cu")
		(net "P3E_PCH_BMC_TX_DN")
	)
	(segment
		(start 350.26854 -81.92516)
		(end 350.26854 -82.100928)
		(width 0.13208)
		(layer "B.Cu")
		(net "P3E_PCH_BMC_TX_DN")
	)
	(segment
		(start 341.763604 -87.518748)
		(end 329.86726 -82.591148)
		(width 0.13208)
		(layer "B.Cu")
		(net "P3E_PCH_BMC_TX_DN")
	)
	(segment
		(start 352.92792 -76.727812)
		(end 352.92792 -77.526388)
		(width 0.13208)
		(layer "B.Cu")
		(net "P3E_PCH_BMC_TX_DN")
	)
	(segment
		(start 165.66134 -10.54354)
		(end 165.873176 -10.032238)
		(width 0.13208)
		(layer "B.Cu")
		(net "P3E_PCH_BMC_TX_DN")
	)
	(segment
		(start 343.547954 -47.510192)
		(end 343.81948 -47.666402)
		(width 0.0889)
		(layer "B.Cu")
		(net "P3E_PCH_BMC_TX_DN")
	)
	(segment
		(start 216.359232 -60.643008)
		(end 202.088242 -60.643008)
		(width 0.13208)
		(layer "B.Cu")
		(net "P3E_PCH_BMC_TX_DN")
	)
	(segment
		(start 344.861134 -48.545242)
		(end 345.522296 -49.206404)
		(width 0.0889)
		(layer "B.Cu")
		(net "P3E_PCH_BMC_TX_DN")
	)
	(segment
		(start 163.43122 -22.981158)
		(end 163.43122 -22.587458)
		(width 0.13208)
		(layer "B.Cu")
		(net "P3E_PCH_BMC_TX_DN")
	)
	(segment
		(start 167.06088 -34.270188)
		(end 165.76294 -32.971994)
		(width 0.13208)
		(layer "B.Cu")
		(net "P3E_PCH_BMC_TX_DN")
	)
	(segment
		(start 165.76294 -32.971994)
		(end 165.520116 -32.60852)
		(width 0.13208)
		(layer "B.Cu")
		(net "P3E_PCH_BMC_TX_DN")
	)
	(segment
		(start 352.92792 -78.156308)
		(end 352.92792 -79.441548)
		(width 0.13208)
		(layer "B.Cu")
		(net "P3E_PCH_BMC_TX_DN")
	)
	(segment
		(start 173.853856 -44.445428)
		(end 167.77716 -38.368732)
		(width 0.13208)
		(layer "B.Cu")
		(net "P3E_PCH_BMC_TX_DN")
	)
	(segment
		(start 348.80296 -83.566508)
		(end 344.85072 -87.518748)
		(width 0.13208)
		(layer "B.Cu")
		(net "P3E_PCH_BMC_TX_DN")
	)
	(segment
		(start 349.53575 -82.833718)
		(end 349.257366 -83.112102)
		(width 0.13208)
		(layer "B.Cu")
		(net "P3E_PCH_BMC_TX_DN")
	)
	(segment
		(start 349.081598 -83.112102)
		(end 348.80296 -83.39074)
		(width 0.13208)
		(layer "B.Cu")
		(net "P3E_PCH_BMC_TX_DN")
	)
	(segment
		(start 351.455736 -80.913732)
		(end 351.279968 -80.913732)
		(width 0.13208)
		(layer "B.Cu")
		(net "P3E_PCH_BMC_TX_DN")
	)
	(segment
		(start 329.86726 -82.591148)
		(end 287.13049 -82.591148)
		(width 0.13208)
		(layer "B.Cu")
		(net "P3E_PCH_BMC_TX_DN")
	)
	(segment
		(start 179.60086 -44.445428)
		(end 173.853856 -44.445428)
		(width 0.13208)
		(layer "B.Cu")
		(net "P3E_PCH_BMC_TX_DN")
	)
	(segment
		(start 354.5332 -71.867522)
		(end 354.156264 -73.762108)
		(width 0.13208)
		(layer "B.Cu")
		(net "P3E_PCH_BMC_TX_DN")
	)
	(segment
		(start 165.66134 -13.862558)
		(end 165.7858 -13.738098)
		(width 0.13208)
		(layer "B.Cu")
		(net "P3E_PCH_BMC_TX_DN")
	)
	(segment
		(start 350.547178 -81.646522)
		(end 350.26854 -81.92516)
		(width 0.13208)
		(layer "B.Cu")
		(net "P3E_PCH_BMC_TX_DN")
	)
	(segment
		(start 168.603168 -8.131048)
		(end 168.83761 -8.36549)
		(width 0.13208)
		(layer "B.Cu")
		(net "P3E_PCH_BMC_TX_DN")
	)
	(segment
		(start 163.55568 -24.535638)
		(end 163.55568 -24.141938)
		(width 0.13208)
		(layer "B.Cu")
		(net "P3E_PCH_BMC_TX_DN")
	)
	(segment
		(start 167.77716 -35.999674)
		(end 167.06088 -34.270188)
		(width 0.13208)
		(layer "B.Cu")
		(net "P3E_PCH_BMC_TX_DN")
	)
	(segment
		(start 354.156264 -73.762108)
		(end 352.92792 -76.727812)
		(width 0.13208)
		(layer "B.Cu")
		(net "P3E_PCH_BMC_TX_DN")
	)
	(segment
		(start 165.873176 -10.032238)
		(end 166.435278 -9.191244)
		(width 0.13208)
		(layer "B.Cu")
		(net "P3E_PCH_BMC_TX_DN")
	)
	(segment
		(start 163.55568 -23.105618)
		(end 163.43122 -22.981158)
		(width 0.13208)
		(layer "B.Cu")
		(net "P3E_PCH_BMC_TX_DN")
	)
	(segment
		(start 162.98418 -18.772378)
		(end 162.98418 -18.378678)
		(width 0.13208)
		(layer "B.Cu")
		(net "P3E_PCH_BMC_TX_DN")
	)
	(arc
		(start 343.84361 -47.75581)
		(mid 343.839317 -47.766055)
		(end 343.835228 -47.776384)
		(width 0.0889)
		(layer "B.Cu")
		(net "P3E_PCH_BMC_TX_DN")
	)
	(arc
		(start 343.835228 -47.776384)
		(mid 343.888467 -48.288134)
		(end 344.334084 -48.545242)
		(width 0.0889)
		(layer "B.Cu")
		(net "P3E_PCH_BMC_TX_DN")
	)
	(segment
		(start 169.267124 -13.600176)
		(end 169.267124 -13.073126)
		(width 0.13208)
		(layer "F.Cu")
		(net "P3E_PCH_BMC_TX_C_DP")
	)
	(segment
		(start 169.096436 -11.312398)
		(end 169.403522 -11.005312)
		(width 0.13208)
		(layer "F.Cu")
		(net "P3E_PCH_BMC_TX_C_DP")
	)
	(segment
		(start 169.096436 -12.902438)
		(end 169.096436 -11.312398)
		(width 0.13208)
		(layer "F.Cu")
		(net "P3E_PCH_BMC_TX_C_DP")
	)
	(segment
		(start 169.267124 -13.073126)
		(end 169.096436 -12.902438)
		(width 0.13208)
		(layer "F.Cu")
		(net "P3E_PCH_BMC_TX_C_DP")
	)
	(via
		(at 169.403522 -11.005312)
		(size 0.508)
		(drill 0.254)
		(layers "F.Cu" "B.Cu")
		(net "P3E_PCH_BMC_TX_C_DP")
	)
	(segment
		(start 169.09669 -10.69848)
		(end 169.403522 -11.005312)
		(width 0.13208)
		(layer "B.Cu")
		(net "P3E_PCH_BMC_TX_C_DP")
	)
	(segment
		(start 169.389806 -9.724898)
		(end 169.09669 -10.018014)
		(width 0.13208)
		(layer "B.Cu")
		(net "P3E_PCH_BMC_TX_C_DP")
	)
	(segment
		(start 169.09669 -10.018014)
		(end 169.09669 -10.69848)
		(width 0.13208)
		(layer "B.Cu")
		(net "P3E_PCH_BMC_TX_C_DP")
	)
	(segment
		(start 168.666922 -13.077952)
		(end 168.837356 -12.907518)
		(width 0.13208)
		(layer "F.Cu")
		(net "P3E_PCH_BMC_TX_C_DN")
	)
	(segment
		(start 168.666922 -13.600176)
		(end 168.666922 -13.077952)
		(width 0.13208)
		(layer "F.Cu")
		(net "P3E_PCH_BMC_TX_C_DN")
	)
	(segment
		(start 168.837356 -12.907518)
		(end 168.837356 -11.302746)
		(width 0.13208)
		(layer "F.Cu")
		(net "P3E_PCH_BMC_TX_C_DN")
	)
	(segment
		(start 168.837356 -11.302746)
		(end 168.539922 -11.005312)
		(width 0.13208)
		(layer "F.Cu")
		(net "P3E_PCH_BMC_TX_C_DN")
	)
	(via
		(at 168.539922 -11.005312)
		(size 0.508)
		(drill 0.254)
		(layers "F.Cu" "B.Cu")
		(net "P3E_PCH_BMC_TX_C_DN")
	)
	(segment
		(start 168.83761 -10.01776)
		(end 168.83761 -10.707624)
		(width 0.13208)
		(layer "B.Cu")
		(net "P3E_PCH_BMC_TX_C_DN")
	)
	(segment
		(start 168.83761 -10.707624)
		(end 168.539922 -11.005312)
		(width 0.13208)
		(layer "B.Cu")
		(net "P3E_PCH_BMC_TX_C_DN")
	)
	(segment
		(start 168.544494 -9.724644)
		(end 168.83761 -10.01776)
		(width 0.13208)
		(layer "B.Cu")
		(net "P3E_PCH_BMC_TX_C_DN")
	)
	(segment
		(start 361.607862 -53.044852)
		(end 361.732322 -52.920392)
		(width 0.13208)
		(layer "F.Cu")
		(net "P3E_PCH_BMC_RX_DP")
	)
	(segment
		(start 364.1979 -55.049928)
		(end 364.1979 -55.582312)
		(width 0.13208)
		(layer "F.Cu")
		(net "P3E_PCH_BMC_RX_DP")
	)
	(segment
		(start 359.617518 -53.044852)
		(end 359.741978 -52.920392)
		(width 0.13208)
		(layer "F.Cu")
		(net "P3E_PCH_BMC_RX_DP")
	)
	(segment
		(start 353.948492 -52.984654)
		(end 354.212652 -52.984654)
		(width 0.0889)
		(layer "F.Cu")
		(net "P3E_PCH_BMC_RX_DP")
	)
	(segment
		(start 355.39807 -52.984908)
		(end 355.65969 -52.984908)
		(width 0.0889)
		(layer "F.Cu")
		(net "P3E_PCH_BMC_RX_DP")
	)
	(segment
		(start 350.418908 -52.32654)
		(end 350.683068 -52.32654)
		(width 0.0889)
		(layer "F.Cu")
		(net "P3E_PCH_BMC_RX_DP")
	)
	(segment
		(start 363.470444 -54.322472)
		(end 364.1979 -55.049928)
		(width 0.13208)
		(layer "F.Cu")
		(net "P3E_PCH_BMC_RX_DP")
	)
	(segment
		(start 354.311458 -52.885848)
		(end 354.575618 -52.885848)
		(width 0.0889)
		(layer "F.Cu")
		(net "P3E_PCH_BMC_RX_DP")
	)
	(segment
		(start 347.436694 -51.864514)
		(end 347.639386 -51.864514)
		(width 0.0889)
		(layer "F.Cu")
		(net "P3E_PCH_BMC_RX_DP")
	)
	(segment
		(start 347.639386 -51.864514)
		(end 348.516448 -52.227734)
		(width 0.0889)
		(layer "F.Cu")
		(net "P3E_PCH_BMC_RX_DP")
	)
	(segment
		(start 358.225598 -53.044852)
		(end 358.606598 -53.044852)
		(width 0.13208)
		(layer "F.Cu")
		(net "P3E_PCH_BMC_RX_DP")
	)
	(segment
		(start 351.046034 -52.227734)
		(end 351.14484 -52.32654)
		(width 0.0889)
		(layer "F.Cu")
		(net "P3E_PCH_BMC_RX_DP")
	)
	(segment
		(start 356.484682 -52.885848)
		(end 357.663496 -52.885848)
		(width 0.0889)
		(layer "F.Cu")
		(net "P3E_PCH_BMC_RX_DP")
	)
	(segment
		(start 354.674424 -52.984654)
		(end 354.938584 -52.984654)
		(width 0.0889)
		(layer "F.Cu")
		(net "P3E_PCH_BMC_RX_DP")
	)
	(segment
		(start 360.122978 -52.920392)
		(end 360.247438 -53.044852)
		(width 0.13208)
		(layer "F.Cu")
		(net "P3E_PCH_BMC_RX_DP")
	)
	(segment
		(start 350.320102 -52.227734)
		(end 350.418908 -52.32654)
		(width 0.0889)
		(layer "F.Cu")
		(net "P3E_PCH_BMC_RX_DP")
	)
	(segment
		(start 362.283248 -53.135276)
		(end 362.283248 -53.311044)
		(width 0.13208)
		(layer "F.Cu")
		(net "P3E_PCH_BMC_RX_DP")
	)
	(segment
		(start 363.016038 -53.868066)
		(end 363.016038 -54.043834)
		(width 0.13208)
		(layer "F.Cu")
		(net "P3E_PCH_BMC_RX_DP")
	)
	(segment
		(start 353.123754 -52.885848)
		(end 353.22256 -52.984654)
		(width 0.0889)
		(layer "F.Cu")
		(net "P3E_PCH_BMC_RX_DP")
	)
	(segment
		(start 167.467026 -13.061696)
		(end 167.296846 -12.891516)
		(width 0.13208)
		(layer "F.Cu")
		(net "P3E_PCH_BMC_RX_DP")
	)
	(segment
		(start 167.296846 -12.891516)
		(end 167.296846 -12.307316)
		(width 0.13208)
		(layer "F.Cu")
		(net "P3E_PCH_BMC_RX_DP")
	)
	(segment
		(start 359.236518 -53.044852)
		(end 359.617518 -53.044852)
		(width 0.13208)
		(layer "F.Cu")
		(net "P3E_PCH_BMC_RX_DP")
	)
	(segment
		(start 355.75875 -52.885848)
		(end 356.024942 -52.885848)
		(width 0.0889)
		(layer "F.Cu")
		(net "P3E_PCH_BMC_RX_DP")
	)
	(segment
		(start 347.349318 -51.95189)
		(end 347.436694 -51.864514)
		(width 0.0889)
		(layer "F.Cu")
		(net "P3E_PCH_BMC_RX_DP")
	)
	(segment
		(start 362.283248 -53.311044)
		(end 362.561886 -53.589682)
		(width 0.13208)
		(layer "F.Cu")
		(net "P3E_PCH_BMC_RX_DP")
	)
	(segment
		(start 361.226862 -53.044852)
		(end 361.607862 -53.044852)
		(width 0.13208)
		(layer "F.Cu")
		(net "P3E_PCH_BMC_RX_DP")
	)
	(segment
		(start 351.409 -52.32654)
		(end 351.507806 -52.227734)
		(width 0.0889)
		(layer "F.Cu")
		(net "P3E_PCH_BMC_RX_DP")
	)
	(segment
		(start 349.957136 -52.32654)
		(end 350.055942 -52.227734)
		(width 0.0889)
		(layer "F.Cu")
		(net "P3E_PCH_BMC_RX_DP")
	)
	(segment
		(start 359.112058 -52.920392)
		(end 359.236518 -53.044852)
		(width 0.13208)
		(layer "F.Cu")
		(net "P3E_PCH_BMC_RX_DP")
	)
	(segment
		(start 351.507806 -52.227734)
		(end 351.771966 -52.227734)
		(width 0.0889)
		(layer "F.Cu")
		(net "P3E_PCH_BMC_RX_DP")
	)
	(segment
		(start 362.068364 -52.920392)
		(end 362.283248 -53.135276)
		(width 0.13208)
		(layer "F.Cu")
		(net "P3E_PCH_BMC_RX_DP")
	)
	(segment
		(start 350.055942 -52.227734)
		(end 350.320102 -52.227734)
		(width 0.0889)
		(layer "F.Cu")
		(net "P3E_PCH_BMC_RX_DP")
	)
	(segment
		(start 362.561886 -53.589682)
		(end 362.737654 -53.589682)
		(width 0.13208)
		(layer "F.Cu")
		(net "P3E_PCH_BMC_RX_DP")
	)
	(segment
		(start 348.516448 -52.227734)
		(end 349.59417 -52.227734)
		(width 0.0889)
		(layer "F.Cu")
		(net "P3E_PCH_BMC_RX_DP")
	)
	(segment
		(start 359.741978 -52.920392)
		(end 360.122978 -52.920392)
		(width 0.13208)
		(layer "F.Cu")
		(net "P3E_PCH_BMC_RX_DP")
	)
	(segment
		(start 351.771966 -52.227734)
		(end 352.43008 -52.885848)
		(width 0.0889)
		(layer "F.Cu")
		(net "P3E_PCH_BMC_RX_DP")
	)
	(segment
		(start 353.22256 -52.984654)
		(end 353.48672 -52.984654)
		(width 0.0889)
		(layer "F.Cu")
		(net "P3E_PCH_BMC_RX_DP")
	)
	(segment
		(start 167.467026 -13.600176)
		(end 167.467026 -13.061696)
		(width 0.13208)
		(layer "F.Cu")
		(net "P3E_PCH_BMC_RX_DP")
	)
	(segment
		(start 357.663496 -52.885848)
		(end 357.69804 -52.920392)
		(width 0.0889)
		(layer "F.Cu")
		(net "P3E_PCH_BMC_RX_DP")
	)
	(segment
		(start 167.296846 -12.307316)
		(end 167.599106 -12.005056)
		(width 0.13208)
		(layer "F.Cu")
		(net "P3E_PCH_BMC_RX_DP")
	)
	(segment
		(start 357.69804 -52.920392)
		(end 357.720138 -52.920392)
		(width 0.0889)
		(layer "F.Cu")
		(net "P3E_PCH_BMC_RX_DP")
	)
	(segment
		(start 350.683068 -52.32654)
		(end 350.781874 -52.227734)
		(width 0.0889)
		(layer "F.Cu")
		(net "P3E_PCH_BMC_RX_DP")
	)
	(segment
		(start 361.102402 -52.920392)
		(end 361.226862 -53.044852)
		(width 0.13208)
		(layer "F.Cu")
		(net "P3E_PCH_BMC_RX_DP")
	)
	(segment
		(start 351.14484 -52.32654)
		(end 351.409 -52.32654)
		(width 0.0889)
		(layer "F.Cu")
		(net "P3E_PCH_BMC_RX_DP")
	)
	(segment
		(start 358.606598 -53.044852)
		(end 358.731058 -52.920392)
		(width 0.13208)
		(layer "F.Cu")
		(net "P3E_PCH_BMC_RX_DP")
	)
	(segment
		(start 363.016038 -54.043834)
		(end 363.294676 -54.322472)
		(width 0.13208)
		(layer "F.Cu")
		(net "P3E_PCH_BMC_RX_DP")
	)
	(segment
		(start 355.29901 -52.885848)
		(end 355.39807 -52.984908)
		(width 0.0889)
		(layer "F.Cu")
		(net "P3E_PCH_BMC_RX_DP")
	)
	(segment
		(start 347.214698 -51.95189)
		(end 347.349318 -51.95189)
		(width 0.0889)
		(layer "F.Cu")
		(net "P3E_PCH_BMC_RX_DP")
	)
	(segment
		(start 349.59417 -52.227734)
		(end 349.692976 -52.32654)
		(width 0.0889)
		(layer "F.Cu")
		(net "P3E_PCH_BMC_RX_DP")
	)
	(segment
		(start 357.720138 -52.920392)
		(end 358.101138 -52.920392)
		(width 0.13208)
		(layer "F.Cu")
		(net "P3E_PCH_BMC_RX_DP")
	)
	(segment
		(start 356.385622 -52.984908)
		(end 356.484682 -52.885848)
		(width 0.0889)
		(layer "F.Cu")
		(net "P3E_PCH_BMC_RX_DP")
	)
	(segment
		(start 353.48672 -52.984654)
		(end 353.585526 -52.885848)
		(width 0.0889)
		(layer "F.Cu")
		(net "P3E_PCH_BMC_RX_DP")
	)
	(segment
		(start 355.65969 -52.984908)
		(end 355.75875 -52.885848)
		(width 0.0889)
		(layer "F.Cu")
		(net "P3E_PCH_BMC_RX_DP")
	)
	(segment
		(start 354.575618 -52.885848)
		(end 354.674424 -52.984654)
		(width 0.0889)
		(layer "F.Cu")
		(net "P3E_PCH_BMC_RX_DP")
	)
	(segment
		(start 349.692976 -52.32654)
		(end 349.957136 -52.32654)
		(width 0.0889)
		(layer "F.Cu")
		(net "P3E_PCH_BMC_RX_DP")
	)
	(segment
		(start 356.024942 -52.885848)
		(end 356.124002 -52.984908)
		(width 0.0889)
		(layer "F.Cu")
		(net "P3E_PCH_BMC_RX_DP")
	)
	(segment
		(start 350.781874 -52.227734)
		(end 351.046034 -52.227734)
		(width 0.0889)
		(layer "F.Cu")
		(net "P3E_PCH_BMC_RX_DP")
	)
	(segment
		(start 360.628438 -53.044852)
		(end 360.752898 -52.920392)
		(width 0.13208)
		(layer "F.Cu")
		(net "P3E_PCH_BMC_RX_DP")
	)
	(segment
		(start 364.1979 -55.582312)
		(end 363.89564 -55.884572)
		(width 0.13208)
		(layer "F.Cu")
		(net "P3E_PCH_BMC_RX_DP")
	)
	(segment
		(start 355.03739 -52.885848)
		(end 355.29901 -52.885848)
		(width 0.0889)
		(layer "F.Cu")
		(net "P3E_PCH_BMC_RX_DP")
	)
	(segment
		(start 356.124002 -52.984908)
		(end 356.385622 -52.984908)
		(width 0.0889)
		(layer "F.Cu")
		(net "P3E_PCH_BMC_RX_DP")
	)
	(segment
		(start 363.294676 -54.322472)
		(end 363.470444 -54.322472)
		(width 0.13208)
		(layer "F.Cu")
		(net "P3E_PCH_BMC_RX_DP")
	)
	(segment
		(start 354.938584 -52.984654)
		(end 355.03739 -52.885848)
		(width 0.0889)
		(layer "F.Cu")
		(net "P3E_PCH_BMC_RX_DP")
	)
	(segment
		(start 362.737654 -53.589682)
		(end 363.016038 -53.868066)
		(width 0.13208)
		(layer "F.Cu")
		(net "P3E_PCH_BMC_RX_DP")
	)
	(segment
		(start 360.247438 -53.044852)
		(end 360.628438 -53.044852)
		(width 0.13208)
		(layer "F.Cu")
		(net "P3E_PCH_BMC_RX_DP")
	)
	(segment
		(start 358.731058 -52.920392)
		(end 359.112058 -52.920392)
		(width 0.13208)
		(layer "F.Cu")
		(net "P3E_PCH_BMC_RX_DP")
	)
	(segment
		(start 361.732322 -52.920392)
		(end 362.068364 -52.920392)
		(width 0.13208)
		(layer "F.Cu")
		(net "P3E_PCH_BMC_RX_DP")
	)
	(segment
		(start 354.212652 -52.984654)
		(end 354.311458 -52.885848)
		(width 0.0889)
		(layer "F.Cu")
		(net "P3E_PCH_BMC_RX_DP")
	)
	(segment
		(start 353.585526 -52.885848)
		(end 353.849686 -52.885848)
		(width 0.0889)
		(layer "F.Cu")
		(net "P3E_PCH_BMC_RX_DP")
	)
	(segment
		(start 353.849686 -52.885848)
		(end 353.948492 -52.984654)
		(width 0.0889)
		(layer "F.Cu")
		(net "P3E_PCH_BMC_RX_DP")
	)
	(segment
		(start 360.752898 -52.920392)
		(end 361.102402 -52.920392)
		(width 0.13208)
		(layer "F.Cu")
		(net "P3E_PCH_BMC_RX_DP")
	)
	(segment
		(start 352.43008 -52.885848)
		(end 353.123754 -52.885848)
		(width 0.0889)
		(layer "F.Cu")
		(net "P3E_PCH_BMC_RX_DP")
	)
	(segment
		(start 358.101138 -52.920392)
		(end 358.225598 -53.044852)
		(width 0.13208)
		(layer "F.Cu")
		(net "P3E_PCH_BMC_RX_DP")
	)
	(segment
		(start 367.812574 -30.894782)
		(end 367.812574 -31.099506)
		(width 0.14732)
		(layer "In6.Cu")
		(net "P3E_PCH_BMC_RX_DP")
	)
	(segment
		(start 369.42014 -36.118038)
		(end 369.27536 -36.262818)
		(width 0.14732)
		(layer "In6.Cu")
		(net "P3E_PCH_BMC_RX_DP")
	)
	(segment
		(start 369.42014 -36.775898)
		(end 369.42014 -47.406052)
		(width 0.14732)
		(layer "In6.Cu")
		(net "P3E_PCH_BMC_RX_DP")
	)
	(segment
		(start 330.344526 -13.276834)
		(end 332.25232 -14.067028)
		(width 0.14732)
		(layer "In6.Cu")
		(net "P3E_PCH_BMC_RX_DP")
	)
	(segment
		(start 211.397342 -23.767796)
		(end 211.56422 -24.171656)
		(width 0.14732)
		(layer "In6.Cu")
		(net "P3E_PCH_BMC_RX_DP")
	)
	(segment
		(start 211.296504 -23.204932)
		(end 211.463382 -23.608538)
		(width 0.14732)
		(layer "In6.Cu")
		(net "P3E_PCH_BMC_RX_DP")
	)
	(segment
		(start 369.42014 -34.065718)
		(end 369.27536 -34.210498)
		(width 0.14732)
		(layer "In6.Cu")
		(net "P3E_PCH_BMC_RX_DP")
	)
	(segment
		(start 369.42014 -34.723578)
		(end 369.42014 -35.091878)
		(width 0.14732)
		(layer "In6.Cu")
		(net "P3E_PCH_BMC_RX_DP")
	)
	(segment
		(start 211.723732 -24.237696)
		(end 212.035898 -24.992076)
		(width 0.14732)
		(layer "In6.Cu")
		(net "P3E_PCH_BMC_RX_DP")
	)
	(segment
		(start 259.738876 -37.038788)
		(end 300.283372 -20.244562)
		(width 0.14732)
		(layer "In6.Cu")
		(net "P3E_PCH_BMC_RX_DP")
	)
	(segment
		(start 193.05143 -14.018768)
		(end 206.387446 -16.67129)
		(width 0.14732)
		(layer "In6.Cu")
		(net "P3E_PCH_BMC_RX_DP")
	)
	(segment
		(start 191.05372 -14.018768)
		(end 193.05143 -14.018768)
		(width 0.14732)
		(layer "In6.Cu")
		(net "P3E_PCH_BMC_RX_DP")
	)
	(segment
		(start 369.42014 -35.749738)
		(end 369.42014 -36.118038)
		(width 0.14732)
		(layer "In6.Cu")
		(net "P3E_PCH_BMC_RX_DP")
	)
	(segment
		(start 211.136992 -23.138892)
		(end 211.296504 -23.204932)
		(width 0.14732)
		(layer "In6.Cu")
		(net "P3E_PCH_BMC_RX_DP")
	)
	(segment
		(start 211.56422 -24.171656)
		(end 211.723732 -24.237696)
		(width 0.14732)
		(layer "In6.Cu")
		(net "P3E_PCH_BMC_RX_DP")
	)
	(segment
		(start 369.42014 -32.502348)
		(end 369.42014 -33.039558)
		(width 0.14732)
		(layer "In6.Cu")
		(net "P3E_PCH_BMC_RX_DP")
	)
	(segment
		(start 339.870796 -14.067028)
		(end 352.314764 -19.22145)
		(width 0.14732)
		(layer "In6.Cu")
		(net "P3E_PCH_BMC_RX_DP")
	)
	(segment
		(start 167.599106 -12.005056)
		(end 167.304466 -11.710416)
		(width 0.14732)
		(layer "In6.Cu")
		(net "P3E_PCH_BMC_RX_DP")
	)
	(segment
		(start 223.482408 -37.038788)
		(end 259.738876 -37.038788)
		(width 0.14732)
		(layer "In6.Cu")
		(net "P3E_PCH_BMC_RX_DP")
	)
	(segment
		(start 182.7657 -13.513308)
		(end 190.54826 -13.513308)
		(width 0.14732)
		(layer "In6.Cu")
		(net "P3E_PCH_BMC_RX_DP")
	)
	(segment
		(start 352.314764 -19.22145)
		(end 363.840776 -26.922984)
		(width 0.14732)
		(layer "In6.Cu")
		(net "P3E_PCH_BMC_RX_DP")
	)
	(segment
		(start 369.27536 -33.184338)
		(end 369.27536 -33.552638)
		(width 0.14732)
		(layer "In6.Cu")
		(net "P3E_PCH_BMC_RX_DP")
	)
	(segment
		(start 300.283372 -20.244562)
		(end 303.365662 -19.309588)
		(width 0.14732)
		(layer "In6.Cu")
		(net "P3E_PCH_BMC_RX_DP")
	)
	(segment
		(start 369.27536 -36.262818)
		(end 369.27536 -36.631118)
		(width 0.14732)
		(layer "In6.Cu")
		(net "P3E_PCH_BMC_RX_DP")
	)
	(segment
		(start 303.365662 -19.309588)
		(end 303.365916 -19.309588)
		(width 0.14732)
		(layer "In6.Cu")
		(net "P3E_PCH_BMC_RX_DP")
	)
	(segment
		(start 367.3475 -30.634432)
		(end 367.552224 -30.634432)
		(width 0.14732)
		(layer "In6.Cu")
		(net "P3E_PCH_BMC_RX_DP")
	)
	(segment
		(start 326.147938 -13.276834)
		(end 330.344526 -13.276834)
		(width 0.14732)
		(layer "In6.Cu")
		(net "P3E_PCH_BMC_RX_DP")
	)
	(segment
		(start 211.463382 -23.608538)
		(end 211.397342 -23.767796)
		(width 0.14732)
		(layer "In6.Cu")
		(net "P3E_PCH_BMC_RX_DP")
	)
	(segment
		(start 320.66992 -15.545816)
		(end 326.147938 -13.276834)
		(width 0.14732)
		(layer "In6.Cu")
		(net "P3E_PCH_BMC_RX_DP")
	)
	(segment
		(start 367.812574 -31.099506)
		(end 368.073178 -31.36011)
		(width 0.14732)
		(layer "In6.Cu")
		(net "P3E_PCH_BMC_RX_DP")
	)
	(segment
		(start 210.96986 -22.735032)
		(end 211.136992 -23.138892)
		(width 0.14732)
		(layer "In6.Cu")
		(net "P3E_PCH_BMC_RX_DP")
	)
	(segment
		(start 363.840776 -26.922984)
		(end 367.086896 -30.169104)
		(width 0.14732)
		(layer "In6.Cu")
		(net "P3E_PCH_BMC_RX_DP")
	)
	(segment
		(start 190.54826 -13.513308)
		(end 191.05372 -14.018768)
		(width 0.14732)
		(layer "In6.Cu")
		(net "P3E_PCH_BMC_RX_DP")
	)
	(segment
		(start 369.27536 -34.578798)
		(end 369.42014 -34.723578)
		(width 0.14732)
		(layer "In6.Cu")
		(net "P3E_PCH_BMC_RX_DP")
	)
	(segment
		(start 216.086182 -31.059882)
		(end 217.503502 -31.059882)
		(width 0.14732)
		(layer "In6.Cu")
		(net "P3E_PCH_BMC_RX_DP")
	)
	(segment
		(start 364.19028 -54.026308)
		(end 364.19028 -55.589932)
		(width 0.14732)
		(layer "In6.Cu")
		(net "P3E_PCH_BMC_RX_DP")
	)
	(segment
		(start 368.436906 -49.779682)
		(end 364.19028 -54.026308)
		(width 0.14732)
		(layer "In6.Cu")
		(net "P3E_PCH_BMC_RX_DP")
	)
	(segment
		(start 303.365916 -19.309588)
		(end 306.44846 -18.37436)
		(width 0.14732)
		(layer "In6.Cu")
		(net "P3E_PCH_BMC_RX_DP")
	)
	(segment
		(start 212.035898 -27.87269)
		(end 212.367876 -28.204668)
		(width 0.14732)
		(layer "In6.Cu")
		(net "P3E_PCH_BMC_RX_DP")
	)
	(segment
		(start 168.050972 -9.256268)
		(end 178.50866 -9.256268)
		(width 0.14732)
		(layer "In6.Cu")
		(net "P3E_PCH_BMC_RX_DP")
	)
	(segment
		(start 178.50866 -9.256268)
		(end 182.7657 -13.513308)
		(width 0.14732)
		(layer "In6.Cu")
		(net "P3E_PCH_BMC_RX_DP")
	)
	(segment
		(start 369.27536 -34.210498)
		(end 369.27536 -34.578798)
		(width 0.14732)
		(layer "In6.Cu")
		(net "P3E_PCH_BMC_RX_DP")
	)
	(segment
		(start 212.035898 -24.992076)
		(end 212.035898 -27.87269)
		(width 0.14732)
		(layer "In6.Cu")
		(net "P3E_PCH_BMC_RX_DP")
	)
	(segment
		(start 217.503502 -31.059882)
		(end 223.482408 -37.038788)
		(width 0.14732)
		(layer "In6.Cu")
		(net "P3E_PCH_BMC_RX_DP")
	)
	(segment
		(start 369.27536 -33.552638)
		(end 369.42014 -33.697418)
		(width 0.14732)
		(layer "In6.Cu")
		(net "P3E_PCH_BMC_RX_DP")
	)
	(segment
		(start 212.367876 -28.204668)
		(end 213.230968 -28.204668)
		(width 0.14732)
		(layer "In6.Cu")
		(net "P3E_PCH_BMC_RX_DP")
	)
	(segment
		(start 367.552224 -30.634432)
		(end 367.812574 -30.894782)
		(width 0.14732)
		(layer "In6.Cu")
		(net "P3E_PCH_BMC_RX_DP")
	)
	(segment
		(start 306.44846 -18.37436)
		(end 320.66992 -15.545816)
		(width 0.14732)
		(layer "In6.Cu")
		(net "P3E_PCH_BMC_RX_DP")
	)
	(segment
		(start 369.27536 -36.631118)
		(end 369.42014 -36.775898)
		(width 0.14732)
		(layer "In6.Cu")
		(net "P3E_PCH_BMC_RX_DP")
	)
	(segment
		(start 167.304466 -11.710416)
		(end 167.304466 -10.002774)
		(width 0.14732)
		(layer "In6.Cu")
		(net "P3E_PCH_BMC_RX_DP")
	)
	(segment
		(start 368.277902 -31.36011)
		(end 369.42014 -32.502348)
		(width 0.14732)
		(layer "In6.Cu")
		(net "P3E_PCH_BMC_RX_DP")
	)
	(segment
		(start 206.387446 -16.67129)
		(end 210.14944 -20.433284)
		(width 0.14732)
		(layer "In6.Cu")
		(net "P3E_PCH_BMC_RX_DP")
	)
	(segment
		(start 369.27536 -35.236658)
		(end 369.27536 -35.604958)
		(width 0.14732)
		(layer "In6.Cu")
		(net "P3E_PCH_BMC_RX_DP")
	)
	(segment
		(start 332.25232 -14.067028)
		(end 339.870796 -14.067028)
		(width 0.14732)
		(layer "In6.Cu")
		(net "P3E_PCH_BMC_RX_DP")
	)
	(segment
		(start 369.42014 -35.091878)
		(end 369.27536 -35.236658)
		(width 0.14732)
		(layer "In6.Cu")
		(net "P3E_PCH_BMC_RX_DP")
	)
	(segment
		(start 369.42014 -33.039558)
		(end 369.27536 -33.184338)
		(width 0.14732)
		(layer "In6.Cu")
		(net "P3E_PCH_BMC_RX_DP")
	)
	(segment
		(start 211.0359 -22.575774)
		(end 210.96986 -22.735032)
		(width 0.14732)
		(layer "In6.Cu")
		(net "P3E_PCH_BMC_RX_DP")
	)
	(segment
		(start 167.304466 -10.002774)
		(end 168.050972 -9.256268)
		(width 0.14732)
		(layer "In6.Cu")
		(net "P3E_PCH_BMC_RX_DP")
	)
	(segment
		(start 369.42014 -47.406052)
		(end 368.436906 -49.779682)
		(width 0.14732)
		(layer "In6.Cu")
		(net "P3E_PCH_BMC_RX_DP")
	)
	(segment
		(start 369.42014 -33.697418)
		(end 369.42014 -34.065718)
		(width 0.14732)
		(layer "In6.Cu")
		(net "P3E_PCH_BMC_RX_DP")
	)
	(segment
		(start 369.27536 -35.604958)
		(end 369.42014 -35.749738)
		(width 0.14732)
		(layer "In6.Cu")
		(net "P3E_PCH_BMC_RX_DP")
	)
	(segment
		(start 367.086896 -30.169104)
		(end 367.086896 -30.373828)
		(width 0.14732)
		(layer "In6.Cu")
		(net "P3E_PCH_BMC_RX_DP")
	)
	(segment
		(start 210.14944 -20.433284)
		(end 211.0359 -22.575774)
		(width 0.14732)
		(layer "In6.Cu")
		(net "P3E_PCH_BMC_RX_DP")
	)
	(segment
		(start 364.19028 -55.589932)
		(end 363.89564 -55.884572)
		(width 0.14732)
		(layer "In6.Cu")
		(net "P3E_PCH_BMC_RX_DP")
	)
	(segment
		(start 367.086896 -30.373828)
		(end 367.3475 -30.634432)
		(width 0.14732)
		(layer "In6.Cu")
		(net "P3E_PCH_BMC_RX_DP")
	)
	(segment
		(start 368.073178 -31.36011)
		(end 368.277902 -31.36011)
		(width 0.14732)
		(layer "In6.Cu")
		(net "P3E_PCH_BMC_RX_DP")
	)
	(segment
		(start 213.230968 -28.204668)
		(end 216.086182 -31.059882)
		(width 0.14732)
		(layer "In6.Cu")
		(net "P3E_PCH_BMC_RX_DP")
	)
	(segment
		(start 347.041216 -51.674268)
		(end 346.919296 -51.779424)
		(width 0.0889)
		(layer "F.Cu")
		(net "P3E_PCH_BMC_RX_DN")
	)
	(segment
		(start 351.85096 -52.037488)
		(end 348.554294 -52.037488)
		(width 0.0889)
		(layer "F.Cu")
		(net "P3E_PCH_BMC_RX_DN")
	)
	(segment
		(start 166.867078 -13.600176)
		(end 166.867078 -13.074904)
		(width 0.13208)
		(layer "F.Cu")
		(net "P3E_PCH_BMC_RX_DN")
	)
	(segment
		(start 346.919296 -51.779424)
		(end 346.74683 -51.95189)
		(width 0.0889)
		(layer "F.Cu")
		(net "P3E_PCH_BMC_RX_DN")
	)
	(segment
		(start 357.69804 -52.661312)
		(end 357.66375 -52.695602)
		(width 0.0889)
		(layer "F.Cu")
		(net "P3E_PCH_BMC_RX_DN")
	)
	(segment
		(start 348.554294 -52.037488)
		(end 347.677232 -51.674268)
		(width 0.0889)
		(layer "F.Cu")
		(net "P3E_PCH_BMC_RX_DN")
	)
	(segment
		(start 167.037766 -12.904216)
		(end 167.037766 -12.307316)
		(width 0.13208)
		(layer "F.Cu")
		(net "P3E_PCH_BMC_RX_DN")
	)
	(segment
		(start 362.175806 -52.661312)
		(end 357.720138 -52.661312)
		(width 0.13208)
		(layer "F.Cu")
		(net "P3E_PCH_BMC_RX_DN")
	)
	(segment
		(start 364.45698 -54.942486)
		(end 362.175806 -52.661312)
		(width 0.13208)
		(layer "F.Cu")
		(net "P3E_PCH_BMC_RX_DN")
	)
	(segment
		(start 347.677232 -51.674268)
		(end 347.041216 -51.674268)
		(width 0.0889)
		(layer "F.Cu")
		(net "P3E_PCH_BMC_RX_DN")
	)
	(segment
		(start 364.75924 -55.884572)
		(end 364.45698 -55.582312)
		(width 0.13208)
		(layer "F.Cu")
		(net "P3E_PCH_BMC_RX_DN")
	)
	(segment
		(start 357.720138 -52.661312)
		(end 357.69804 -52.661312)
		(width 0.0889)
		(layer "F.Cu")
		(net "P3E_PCH_BMC_RX_DN")
	)
	(segment
		(start 357.66375 -52.695602)
		(end 352.509074 -52.695602)
		(width 0.0889)
		(layer "F.Cu")
		(net "P3E_PCH_BMC_RX_DN")
	)
	(segment
		(start 364.45698 -55.582312)
		(end 364.45698 -54.942486)
		(width 0.13208)
		(layer "F.Cu")
		(net "P3E_PCH_BMC_RX_DN")
	)
	(segment
		(start 346.74683 -51.95189)
		(end 346.384626 -51.95189)
		(width 0.0889)
		(layer "F.Cu")
		(net "P3E_PCH_BMC_RX_DN")
	)
	(segment
		(start 167.037766 -12.307316)
		(end 166.735506 -12.005056)
		(width 0.13208)
		(layer "F.Cu")
		(net "P3E_PCH_BMC_RX_DN")
	)
	(segment
		(start 166.867078 -13.074904)
		(end 167.037766 -12.904216)
		(width 0.13208)
		(layer "F.Cu")
		(net "P3E_PCH_BMC_RX_DN")
	)
	(segment
		(start 352.509074 -52.695602)
		(end 351.85096 -52.037488)
		(width 0.0889)
		(layer "F.Cu")
		(net "P3E_PCH_BMC_RX_DN")
	)
	(segment
		(start 259.684266 -36.764468)
		(end 300.190662 -19.985736)
		(width 0.14732)
		(layer "In6.Cu")
		(net "P3E_PCH_BMC_RX_DN")
	)
	(segment
		(start 167.030146 -11.710416)
		(end 167.030146 -9.888982)
		(width 0.14732)
		(layer "In6.Cu")
		(net "P3E_PCH_BMC_RX_DN")
	)
	(segment
		(start 339.925406 -13.792708)
		(end 352.444812 -18.978372)
		(width 0.14732)
		(layer "In6.Cu")
		(net "P3E_PCH_BMC_RX_DN")
	)
	(segment
		(start 216.199974 -30.785562)
		(end 217.617294 -30.785562)
		(width 0.14732)
		(layer "In6.Cu")
		(net "P3E_PCH_BMC_RX_DN")
	)
	(segment
		(start 217.617294 -30.785562)
		(end 223.5962 -36.764468)
		(width 0.14732)
		(layer "In6.Cu")
		(net "P3E_PCH_BMC_RX_DN")
	)
	(segment
		(start 166.735506 -12.005056)
		(end 167.030146 -11.710416)
		(width 0.14732)
		(layer "In6.Cu")
		(net "P3E_PCH_BMC_RX_DN")
	)
	(segment
		(start 369.69446 -47.460662)
		(end 368.66957 -49.93513)
		(width 0.14732)
		(layer "In6.Cu")
		(net "P3E_PCH_BMC_RX_DN")
	)
	(segment
		(start 190.662052 -13.238988)
		(end 191.167512 -13.744448)
		(width 0.14732)
		(layer "In6.Cu")
		(net "P3E_PCH_BMC_RX_DN")
	)
	(segment
		(start 178.622452 -8.981948)
		(end 182.879492 -13.238988)
		(width 0.14732)
		(layer "In6.Cu")
		(net "P3E_PCH_BMC_RX_DN")
	)
	(segment
		(start 193.078608 -13.744448)
		(end 206.522574 -16.418306)
		(width 0.14732)
		(layer "In6.Cu")
		(net "P3E_PCH_BMC_RX_DN")
	)
	(segment
		(start 320.58991 -15.28191)
		(end 326.093328 -13.002514)
		(width 0.14732)
		(layer "In6.Cu")
		(net "P3E_PCH_BMC_RX_DN")
	)
	(segment
		(start 167.93718 -8.981948)
		(end 178.622452 -8.981948)
		(width 0.14732)
		(layer "In6.Cu")
		(net "P3E_PCH_BMC_RX_DN")
	)
	(segment
		(start 300.190662 -19.985736)
		(end 306.381658 -18.107914)
		(width 0.14732)
		(layer "In6.Cu")
		(net "P3E_PCH_BMC_RX_DN")
	)
	(segment
		(start 364.015782 -26.709624)
		(end 369.69446 -32.388556)
		(width 0.14732)
		(layer "In6.Cu")
		(net "P3E_PCH_BMC_RX_DN")
	)
	(segment
		(start 167.030146 -9.888982)
		(end 167.93718 -8.981948)
		(width 0.14732)
		(layer "In6.Cu")
		(net "P3E_PCH_BMC_RX_DN")
	)
	(segment
		(start 364.4646 -55.589932)
		(end 364.75924 -55.884572)
		(width 0.14732)
		(layer "In6.Cu")
		(net "P3E_PCH_BMC_RX_DN")
	)
	(segment
		(start 352.444812 -18.978372)
		(end 364.015782 -26.709624)
		(width 0.14732)
		(layer "In6.Cu")
		(net "P3E_PCH_BMC_RX_DN")
	)
	(segment
		(start 210.382104 -20.277836)
		(end 212.310218 -24.937466)
		(width 0.14732)
		(layer "In6.Cu")
		(net "P3E_PCH_BMC_RX_DN")
	)
	(segment
		(start 364.4646 -54.1401)
		(end 364.4646 -55.589932)
		(width 0.14732)
		(layer "In6.Cu")
		(net "P3E_PCH_BMC_RX_DN")
	)
	(segment
		(start 191.167512 -13.744448)
		(end 193.078608 -13.744448)
		(width 0.14732)
		(layer "In6.Cu")
		(net "P3E_PCH_BMC_RX_DN")
	)
	(segment
		(start 206.522574 -16.418306)
		(end 210.382104 -20.277836)
		(width 0.14732)
		(layer "In6.Cu")
		(net "P3E_PCH_BMC_RX_DN")
	)
	(segment
		(start 223.5962 -36.764468)
		(end 259.684266 -36.764468)
		(width 0.14732)
		(layer "In6.Cu")
		(net "P3E_PCH_BMC_RX_DN")
	)
	(segment
		(start 330.399136 -13.002514)
		(end 332.30693 -13.792708)
		(width 0.14732)
		(layer "In6.Cu")
		(net "P3E_PCH_BMC_RX_DN")
	)
	(segment
		(start 368.66957 -49.93513)
		(end 364.4646 -54.1401)
		(width 0.14732)
		(layer "In6.Cu")
		(net "P3E_PCH_BMC_RX_DN")
	)
	(segment
		(start 182.879492 -13.238988)
		(end 190.662052 -13.238988)
		(width 0.14732)
		(layer "In6.Cu")
		(net "P3E_PCH_BMC_RX_DN")
	)
	(segment
		(start 213.34476 -27.930348)
		(end 216.199974 -30.785562)
		(width 0.14732)
		(layer "In6.Cu")
		(net "P3E_PCH_BMC_RX_DN")
	)
	(segment
		(start 212.310218 -27.758898)
		(end 212.481668 -27.930348)
		(width 0.14732)
		(layer "In6.Cu")
		(net "P3E_PCH_BMC_RX_DN")
	)
	(segment
		(start 212.481668 -27.930348)
		(end 213.34476 -27.930348)
		(width 0.14732)
		(layer "In6.Cu")
		(net "P3E_PCH_BMC_RX_DN")
	)
	(segment
		(start 306.381658 -18.107914)
		(end 320.58991 -15.28191)
		(width 0.14732)
		(layer "In6.Cu")
		(net "P3E_PCH_BMC_RX_DN")
	)
	(segment
		(start 332.30693 -13.792708)
		(end 339.925406 -13.792708)
		(width 0.14732)
		(layer "In6.Cu")
		(net "P3E_PCH_BMC_RX_DN")
	)
	(segment
		(start 369.69446 -32.388556)
		(end 369.69446 -47.460662)
		(width 0.14732)
		(layer "In6.Cu")
		(net "P3E_PCH_BMC_RX_DN")
	)
	(segment
		(start 326.093328 -13.002514)
		(end 330.399136 -13.002514)
		(width 0.14732)
		(layer "In6.Cu")
		(net "P3E_PCH_BMC_RX_DN")
	)
	(segment
		(start 212.310218 -24.937466)
		(end 212.310218 -27.758898)
		(width 0.14732)
		(layer "In6.Cu")
		(net "P3E_PCH_BMC_RX_DN")
	)
	(segment
		(start 343.005156 -49.390046)
		(end 342.735154 -48.919892)
		(width 0.2032)
		(layer "F.Cu")
		(net "P1V8_PCH_PLL_AUX")
	)
	(segment
		(start 341.37727 -49.390046)
		(end 341.105998 -48.920146)
		(width 0.2032)
		(layer "F.Cu")
		(net "P1V8_PCH_PLL_AUX")
	)
	(segment
		(start 339.700108 -50.450496)
		(end 340.562946 -50.799746)
		(width 0.2032)
		(layer "F.Cu")
		(net "P1V8_PCH_PLL_AUX")
	)
	(segment
		(start 340.562946 -51.739546)
		(end 340.290658 -51.269646)
		(width 0.2032)
		(layer "F.Cu")
		(net "P1V8_PCH_PLL_AUX")
	)
	(segment
		(start 339.300058 -50.850546)
		(end 339.700108 -50.450496)
		(width 0.2032)
		(layer "F.Cu")
		(net "P1V8_PCH_PLL_AUX")
	)
	(via
		(at 351.76333 -56.221884)
		(size 0.508)
		(drill 0.254)
		(layers "F.Cu" "B.Cu")
		(net "P1V8_PCH_PLL_AUX")
	)
	(via
		(at 351.540318 -56.819038)
		(size 0.508)
		(drill 0.254)
		(layers "F.Cu" "B.Cu")
		(net "P1V8_PCH_PLL_AUX")
	)
	(via
		(at 349.009716 -56.833008)
		(size 0.6604)
		(drill 0.3302)
		(layers "F.Cu" "B.Cu")
		(net "P1V8_PCH_PLL_AUX")
	)
	(via
		(at 342.735154 -48.919892)
		(size 0.4572)
		(drill 0.2032)
		(layers "F.Cu" "B.Cu")
		(net "P1V8_PCH_PLL_AUX")
	)
	(via
		(at 349.315278 -58.358024)
		(size 0.508)
		(drill 0.254)
		(layers "F.Cu" "B.Cu")
		(net "P1V8_PCH_PLL_AUX")
	)
	(via
		(at 341.105998 -48.920146)
		(size 0.4572)
		(drill 0.2032)
		(layers "F.Cu" "B.Cu")
		(net "P1V8_PCH_PLL_AUX")
	)
	(via
		(at 350.797876 -57.000648)
		(size 0.6604)
		(drill 0.3302)
		(layers "F.Cu" "B.Cu")
		(net "P1V8_PCH_PLL_AUX")
	)
	(via
		(at 351.015554 -56.24068)
		(size 0.508)
		(drill 0.254)
		(layers "F.Cu" "B.Cu")
		(net "P1V8_PCH_PLL_AUX")
	)
	(via
		(at 340.290658 -51.269646)
		(size 0.4572)
		(drill 0.2032)
		(layers "F.Cu" "B.Cu")
		(net "P1V8_PCH_PLL_AUX")
	)
	(via
		(at 348.867222 -57.851548)
		(size 0.508)
		(drill 0.254)
		(layers "F.Cu" "B.Cu")
		(net "P1V8_PCH_PLL_AUX")
	)
	(via
		(at 352.264472 -56.625998)
		(size 0.508)
		(drill 0.254)
		(layers "F.Cu" "B.Cu")
		(net "P1V8_PCH_PLL_AUX")
	)
	(via
		(at 352.079052 -57.254394)
		(size 0.508)
		(drill 0.254)
		(layers "F.Cu" "B.Cu")
		(net "P1V8_PCH_PLL_AUX")
	)
	(via
		(at 350.185736 -58.196988)
		(size 0.6604)
		(drill 0.3302)
		(layers "F.Cu" "B.Cu")
		(net "P1V8_PCH_PLL_AUX")
	)
	(via
		(at 339.700108 -50.450496)
		(size 0.4572)
		(drill 0.2032)
		(layers "F.Cu" "B.Cu")
		(net "P1V8_PCH_PLL_AUX")
	)
	(via
		(at 383.173732 -73.95845)
		(size 0.508)
		(drill 0.254)
		(layers "F.Cu" "B.Cu")
		(net "P1V8_PCH_AUX_VCC")
	)
	(via
		(at 383.39268 -80.312768)
		(size 0.762)
		(drill 0.381)
		(layers "F.Cu" "B.Cu")
		(net "P1V8_PCH_AUX_VCC")
	)
	(via
		(at 383.422906 -78.350618)
		(size 0.508)
		(drill 0.254)
		(layers "F.Cu" "B.Cu")
		(net "P1V8_PCH_AUX_VCC")
	)
	(segment
		(start 383.422906 -78.350618)
		(end 383.422906 -77.99451)
		(width 0.508)
		(layer "B.Cu")
		(net "P1V8_PCH_AUX_VCC")
	)
	(segment
		(start 383.173732 -75.757278)
		(end 383.173732 -73.95845)
		(width 0.508)
		(layer "B.Cu")
		(net "P1V8_PCH_AUX_VCC")
	)
	(segment
		(start 383.422906 -77.99451)
		(end 383.64795 -77.769466)
		(width 0.508)
		(layer "B.Cu")
		(net "P1V8_PCH_AUX_VCC")
	)
	(segment
		(start 383.64795 -77.769466)
		(end 383.64795 -76.231496)
		(width 0.508)
		(layer "B.Cu")
		(net "P1V8_PCH_AUX_VCC")
	)
	(segment
		(start 383.64795 -76.231496)
		(end 383.173732 -75.757278)
		(width 0.508)
		(layer "B.Cu")
		(net "P1V8_PCH_AUX_VCC")
	)
	(segment
		(start 383.080006 -76.643992)
		(end 382.504188 -77.21981)
		(width 0.254)
		(layer "F.Cu")
		(net "P1V8_PCH_AUX_MODE")
	)
	(segment
		(start 382.504188 -77.688694)
		(end 382.168908 -78.023974)
		(width 0.254)
		(layer "F.Cu")
		(net "P1V8_PCH_AUX_MODE")
	)
	(segment
		(start 382.504188 -77.364082)
		(end 382.504188 -77.688694)
		(width 0.254)
		(layer "F.Cu")
		(net "P1V8_PCH_AUX_MODE")
	)
	(segment
		(start 382.504188 -77.21981)
		(end 382.504188 -77.364082)
		(width 0.254)
		(layer "F.Cu")
		(net "P1V8_PCH_AUX_MODE")
	)
	(segment
		(start 383.409952 -76.643992)
		(end 383.080006 -76.643992)
		(width 0.254)
		(layer "F.Cu")
		(net "P1V8_PCH_AUX_MODE")
	)
	(via
		(at 382.504188 -77.364082)
		(size 0.508)
		(drill 0.254)
		(layers "F.Cu" "B.Cu")
		(net "P1V8_PCH_AUX_MODE")
	)
	(segment
		(start 148.53793 -59.273948)
		(end 148.53793 -58.638948)
		(width 0.381)
		(layer "F.Cu")
		(net "P1V8_PCH_AUX")
	)
	(segment
		(start 334.899508 -52.050696)
		(end 335.299558 -51.650646)
		(width 0.2032)
		(layer "F.Cu")
		(net "P1V8_PCH_AUX")
	)
	(segment
		(start 148.53793 -58.613548)
		(end 149.390354 -57.761124)
		(width 0.381)
		(layer "F.Cu")
		(net "P1V8_PCH_AUX")
	)
	(segment
		(start 290.72205 -44.176696)
		(end 294.224202 -44.176696)
		(width 0.508)
		(layer "F.Cu")
		(net "P1V8_PCH_AUX")
	)
	(segment
		(start 336.499708 -52.050696)
		(end 336.899758 -51.650646)
		(width 0.2032)
		(layer "F.Cu")
		(net "P1V8_PCH_AUX")
	)
	(segment
		(start 384.247136 -72.147938)
		(end 384.609848 -72.51065)
		(width 0.254)
		(layer "F.Cu")
		(net "P1V8_PCH_AUX")
	)
	(segment
		(start 334.499458 -51.650646)
		(end 334.099408 -52.050696)
		(width 0.2032)
		(layer "F.Cu")
		(net "P1V8_PCH_AUX")
	)
	(segment
		(start 299.935138 -60.698888)
		(end 301.501302 -60.698888)
		(width 0.508)
		(layer "F.Cu")
		(net "P1V8_PCH_AUX")
	)
	(segment
		(start 377.020074 -70.209918)
		(end 383.367026 -70.209918)
		(width 0.254)
		(layer "F.Cu")
		(net "P1V8_PCH_AUX")
	)
	(segment
		(start 147.73783 -56.225948)
		(end 147.12823 -56.225948)
		(width 0.381)
		(layer "F.Cu")
		(net "P1V8_PCH_AUX")
	)
	(segment
		(start 335.138268 -53.619146)
		(end 335.67878 -53.619146)
		(width 0.2032)
		(layer "F.Cu")
		(net "P1V8_PCH_AUX")
	)
	(segment
		(start 294.224202 -44.176696)
		(end 296.80281 -46.755304)
		(width 0.508)
		(layer "F.Cu")
		(net "P1V8_PCH_AUX")
	)
	(segment
		(start 147.73783 -57.241948)
		(end 147.73783 -56.225948)
		(width 0.381)
		(layer "F.Cu")
		(net "P1V8_PCH_AUX")
	)
	(segment
		(start 288.940748 -45.957998)
		(end 290.72205 -44.176696)
		(width 0.508)
		(layer "F.Cu")
		(net "P1V8_PCH_AUX")
	)
	(segment
		(start 336.099658 -51.650646)
		(end 336.499708 -52.050696)
		(width 0.2032)
		(layer "F.Cu")
		(net "P1V8_PCH_AUX")
	)
	(segment
		(start 376.347482 -71.489824)
		(end 376.347482 -70.88251)
		(width 0.254)
		(layer "F.Cu")
		(net "P1V8_PCH_AUX")
	)
	(segment
		(start 384.609848 -72.51065)
		(end 384.609848 -74.694034)
		(width 0.254)
		(layer "F.Cu")
		(net "P1V8_PCH_AUX")
	)
	(segment
		(start 148.53793 -58.638948)
		(end 148.53793 -58.613548)
		(width 0.381)
		(layer "F.Cu")
		(net "P1V8_PCH_AUX")
	)
	(segment
		(start 296.80281 -57.56656)
		(end 299.935138 -60.698888)
		(width 0.508)
		(layer "F.Cu")
		(net "P1V8_PCH_AUX")
	)
	(segment
		(start 384.247136 -71.090028)
		(end 384.247136 -72.147938)
		(width 0.254)
		(layer "F.Cu")
		(net "P1V8_PCH_AUX")
	)
	(segment
		(start 296.80281 -46.755304)
		(end 296.80281 -57.56656)
		(width 0.508)
		(layer "F.Cu")
		(net "P1V8_PCH_AUX")
	)
	(segment
		(start 149.390354 -57.761124)
		(end 151.997664 -57.761124)
		(width 0.381)
		(layer "F.Cu")
		(net "P1V8_PCH_AUX")
	)
	(segment
		(start 383.367026 -70.209918)
		(end 384.247136 -71.090028)
		(width 0.254)
		(layer "F.Cu")
		(net "P1V8_PCH_AUX")
	)
	(segment
		(start 376.347482 -70.88251)
		(end 377.020074 -70.209918)
		(width 0.254)
		(layer "F.Cu")
		(net "P1V8_PCH_AUX")
	)
	(segment
		(start 397.765016 -61.74994)
		(end 396.169388 -61.74994)
		(width 0.254)
		(layer "F.Cu")
		(net "P1V8_PCH_AUX")
	)
	(segment
		(start 274.645628 -45.957998)
		(end 288.940748 -45.957998)
		(width 0.508)
		(layer "F.Cu")
		(net "P1V8_PCH_AUX")
	)
	(segment
		(start 337.699858 -51.650646)
		(end 337.299808 -52.050696)
		(width 0.2032)
		(layer "F.Cu")
		(net "P1V8_PCH_AUX")
	)
	(via
		(at 238.405162 -60.976002)
		(size 0.508)
		(drill 0.254)
		(layers "F.Cu" "B.Cu")
		(net "P1V8_PCH_AUX")
	)
	(via
		(at 374.764808 -73.585832)
		(size 0.508)
		(drill 0.254)
		(layers "F.Cu" "B.Cu")
		(net "P1V8_PCH_AUX")
	)
	(via
		(at 396.169388 -61.74994)
		(size 0.508)
		(drill 0.254)
		(layers "F.Cu" "B.Cu")
		(net "P1V8_PCH_AUX")
	)
	(via
		(at 376.26163 -77.802232)
		(size 0.508)
		(drill 0.254)
		(layers "F.Cu" "B.Cu")
		(net "P1V8_PCH_AUX")
	)
	(via
		(at 374.739408 -77.802232)
		(size 0.508)
		(drill 0.254)
		(layers "F.Cu" "B.Cu")
		(net "P1V8_PCH_AUX")
	)
	(via
		(at 337.299808 -52.050696)
		(size 0.4572)
		(drill 0.2032)
		(layers "F.Cu" "B.Cu")
		(net "P1V8_PCH_AUX")
	)
	(via
		(at 354.8126 -58.148728)
		(size 0.508)
		(drill 0.254)
		(layers "F.Cu" "B.Cu")
		(net "P1V8_PCH_AUX")
	)
	(via
		(at 353.93884 -57.511188)
		(size 0.508)
		(drill 0.254)
		(layers "F.Cu" "B.Cu")
		(net "P1V8_PCH_AUX")
	)
	(via
		(at 147.12823 -56.225948)
		(size 0.508)
		(drill 0.254)
		(layers "F.Cu" "B.Cu")
		(net "P1V8_PCH_AUX")
	)
	(via
		(at 336.499708 -52.050696)
		(size 0.4572)
		(drill 0.2032)
		(layers "F.Cu" "B.Cu")
		(net "P1V8_PCH_AUX")
	)
	(via
		(at 375.113804 -79.292958)
		(size 0.508)
		(drill 0.254)
		(layers "F.Cu" "B.Cu")
		(net "P1V8_PCH_AUX")
	)
	(via
		(at 321.681856 -21.10486)
		(size 0.508)
		(drill 0.254)
		(layers "F.Cu" "B.Cu")
		(net "P1V8_PCH_AUX")
	)
	(via
		(at 319.756282 -71.261732)
		(size 0.762)
		(drill 0.254)
		(layers "F.Cu" "B.Cu")
		(net "P1V8_PCH_AUX")
	)
	(via
		(at 375.85523 -79.300832)
		(size 0.508)
		(drill 0.254)
		(layers "F.Cu" "B.Cu")
		(net "P1V8_PCH_AUX")
	)
	(via
		(at 373.954294 -76.246228)
		(size 0.6604)
		(drill 0.3302)
		(layers "F.Cu" "B.Cu")
		(net "P1V8_PCH_AUX")
	)
	(via
		(at 375.520204 -77.794358)
		(size 0.508)
		(drill 0.254)
		(layers "F.Cu" "B.Cu")
		(net "P1V8_PCH_AUX")
	)
	(via
		(at 375.545604 -73.577958)
		(size 0.508)
		(drill 0.254)
		(layers "F.Cu" "B.Cu")
		(net "P1V8_PCH_AUX")
	)
	(via
		(at 320.917316 -21.09724)
		(size 0.508)
		(drill 0.254)
		(layers "F.Cu" "B.Cu")
		(net "P1V8_PCH_AUX")
	)
	(via
		(at 372.9736 -72.062086)
		(size 0.6604)
		(drill 0.3302)
		(layers "F.Cu" "B.Cu")
		(net "P1V8_PCH_AUX")
	)
	(via
		(at 334.899508 -52.050696)
		(size 0.4572)
		(drill 0.2032)
		(layers "F.Cu" "B.Cu")
		(net "P1V8_PCH_AUX")
	)
	(via
		(at 148.53793 -59.273948)
		(size 0.508)
		(drill 0.254)
		(layers "F.Cu" "B.Cu")
		(net "P1V8_PCH_AUX")
	)
	(via
		(at 335.138268 -53.619146)
		(size 0.4572)
		(drill 0.2032)
		(layers "F.Cu" "B.Cu")
		(net "P1V8_PCH_AUX")
	)
	(via
		(at 274.645628 -45.957998)
		(size 0.508)
		(drill 0.254)
		(layers "F.Cu" "B.Cu")
		(net "P1V8_PCH_AUX")
	)
	(via
		(at 373.398542 -80.315308)
		(size 0.6604)
		(drill 0.3302)
		(layers "F.Cu" "B.Cu")
		(net "P1V8_PCH_AUX")
	)
	(via
		(at 301.501302 -60.698888)
		(size 0.508)
		(drill 0.254)
		(layers "F.Cu" "B.Cu")
		(net "P1V8_PCH_AUX")
	)
	(via
		(at 375.60123 -71.503032)
		(size 0.508)
		(drill 0.254)
		(layers "F.Cu" "B.Cu")
		(net "P1V8_PCH_AUX")
	)
	(via
		(at 324.3072 -70.246748)
		(size 0.508)
		(drill 0.254)
		(layers "F.Cu" "B.Cu")
		(net "P1V8_PCH_AUX")
	)
	(via
		(at 354.57384 -57.511188)
		(size 0.508)
		(drill 0.254)
		(layers "F.Cu" "B.Cu")
		(net "P1V8_PCH_AUX")
	)
	(via
		(at 376.28703 -73.585832)
		(size 0.508)
		(drill 0.254)
		(layers "F.Cu" "B.Cu")
		(net "P1V8_PCH_AUX")
	)
	(via
		(at 334.099408 -52.050696)
		(size 0.4572)
		(drill 0.2032)
		(layers "F.Cu" "B.Cu")
		(net "P1V8_PCH_AUX")
	)
	(segment
		(start 319.203578 -71.814436)
		(end 319.202308 -71.81469)
		(width 0.508)
		(layer "B.Cu")
		(net "P1V8_PCH_AUX")
	)
	(segment
		(start 396.267686 -61.848238)
		(end 396.97406 -61.848238)
		(width 0.381)
		(layer "B.Cu")
		(net "P1V8_PCH_AUX")
	)
	(segment
		(start 147.50034 -56.225948)
		(end 147.12823 -56.225948)
		(width 0.508)
		(layer "B.Cu")
		(net "P1V8_PCH_AUX")
	)
	(segment
		(start 148.53793 -59.273948)
		(end 148.610574 -59.201304)
		(width 0.508)
		(layer "B.Cu")
		(net "P1V8_PCH_AUX")
	)
	(segment
		(start 396.169388 -61.74994)
		(end 396.267686 -61.848238)
		(width 0.381)
		(layer "B.Cu")
		(net "P1V8_PCH_AUX")
	)
	(segment
		(start 148.610574 -57.336182)
		(end 147.50034 -56.225948)
		(width 0.508)
		(layer "B.Cu")
		(net "P1V8_PCH_AUX")
	)
	(segment
		(start 319.202308 -71.81469)
		(end 305.521868 -71.81469)
		(width 0.508)
		(layer "B.Cu")
		(net "P1V8_PCH_AUX")
	)
	(segment
		(start 319.756282 -71.261732)
		(end 319.203578 -71.814436)
		(width 0.508)
		(layer "B.Cu")
		(net "P1V8_PCH_AUX")
	)
	(segment
		(start 305.521868 -71.81469)
		(end 301.501302 -67.794124)
		(width 0.508)
		(layer "B.Cu")
		(net "P1V8_PCH_AUX")
	)
	(segment
		(start 301.501302 -67.794124)
		(end 301.501302 -60.698888)
		(width 0.508)
		(layer "B.Cu")
		(net "P1V8_PCH_AUX")
	)
	(segment
		(start 148.610574 -59.201304)
		(end 148.610574 -57.336182)
		(width 0.508)
		(layer "B.Cu")
		(net "P1V8_PCH_AUX")
	)
	(segment
		(start 322.34759 -69.57187)
		(end 323.022468 -70.246748)
		(width 0.508)
		(layer "In4.Cu")
		(net "P1V8_PCH_AUX")
	)
	(segment
		(start 331.1906 -60.670948)
		(end 330.1238 -61.737748)
		(width 0.508)
		(layer "In4.Cu")
		(net "P1V8_PCH_AUX")
	)
	(segment
		(start 322.707 -63.388748)
		(end 322.707 -68.494148)
		(width 0.508)
		(layer "In4.Cu")
		(net "P1V8_PCH_AUX")
	)
	(segment
		(start 330.1238 -61.737748)
		(end 324.358 -61.737748)
		(width 0.508)
		(layer "In4.Cu")
		(net "P1V8_PCH_AUX")
	)
	(segment
		(start 323.022468 -70.246748)
		(end 324.3072 -70.246748)
		(width 0.508)
		(layer "In4.Cu")
		(net "P1V8_PCH_AUX")
	)
	(segment
		(start 335.138268 -53.619146)
		(end 335.118202 -53.619146)
		(width 0.508)
		(layer "In4.Cu")
		(net "P1V8_PCH_AUX")
	)
	(segment
		(start 334.137 -57.318148)
		(end 333.7814 -57.673748)
		(width 0.508)
		(layer "In4.Cu")
		(net "P1V8_PCH_AUX")
	)
	(segment
		(start 335.118202 -53.619146)
		(end 334.4164 -54.320948)
		(width 0.508)
		(layer "In4.Cu")
		(net "P1V8_PCH_AUX")
	)
	(segment
		(start 331.1906 -59.832748)
		(end 331.1906 -60.670948)
		(width 0.508)
		(layer "In4.Cu")
		(net "P1V8_PCH_AUX")
	)
	(segment
		(start 322.707 -68.494148)
		(end 322.34759 -68.853558)
		(width 0.508)
		(layer "In4.Cu")
		(net "P1V8_PCH_AUX")
	)
	(segment
		(start 334.4164 -55.286148)
		(end 334.137 -55.565548)
		(width 0.508)
		(layer "In4.Cu")
		(net "P1V8_PCH_AUX")
	)
	(segment
		(start 333.7814 -57.673748)
		(end 333.3496 -57.673748)
		(width 0.508)
		(layer "In4.Cu")
		(net "P1V8_PCH_AUX")
	)
	(segment
		(start 334.4164 -54.320948)
		(end 334.4164 -55.286148)
		(width 0.508)
		(layer "In4.Cu")
		(net "P1V8_PCH_AUX")
	)
	(segment
		(start 333.3496 -57.673748)
		(end 331.1906 -59.832748)
		(width 0.508)
		(layer "In4.Cu")
		(net "P1V8_PCH_AUX")
	)
	(segment
		(start 334.137 -55.565548)
		(end 334.137 -57.318148)
		(width 0.508)
		(layer "In4.Cu")
		(net "P1V8_PCH_AUX")
	)
	(segment
		(start 324.358 -61.737748)
		(end 322.707 -63.388748)
		(width 0.508)
		(layer "In4.Cu")
		(net "P1V8_PCH_AUX")
	)
	(segment
		(start 322.34759 -68.853558)
		(end 322.34759 -69.57187)
		(width 0.508)
		(layer "In4.Cu")
		(net "P1V8_PCH_AUX")
	)
	(segment
		(start 323.292216 -71.261732)
		(end 319.756282 -71.261732)
		(width 0.508)
		(layer "In6.Cu")
		(net "P1V8_PCH_AUX")
	)
	(segment
		(start 324.3072 -70.246748)
		(end 323.292216 -71.261732)
		(width 0.508)
		(layer "In6.Cu")
		(net "P1V8_PCH_AUX")
	)
	(segment
		(start 176.232312 -56.76646)
		(end 175.126904 -55.661052)
		(width 0.508)
		(layer "In11.Cu")
		(net "P1V8_PCH_AUX")
	)
	(segment
		(start 232.55478 -58.703972)
		(end 228.042978 -63.215774)
		(width 0.508)
		(layer "In11.Cu")
		(net "P1V8_PCH_AUX")
	)
	(segment
		(start 175.126904 -55.661052)
		(end 169.322496 -55.661052)
		(width 0.508)
		(layer "In11.Cu")
		(net "P1V8_PCH_AUX")
	)
	(segment
		(start 238.405162 -60.976002)
		(end 237.95609 -60.52693)
		(width 0.508)
		(layer "In11.Cu")
		(net "P1V8_PCH_AUX")
	)
	(segment
		(start 192.354962 -56.76646)
		(end 176.232312 -56.76646)
		(width 0.508)
		(layer "In11.Cu")
		(net "P1V8_PCH_AUX")
	)
	(segment
		(start 163.180522 -56.92013)
		(end 160.826704 -59.273948)
		(width 0.508)
		(layer "In11.Cu")
		(net "P1V8_PCH_AUX")
	)
	(segment
		(start 237.940088 -60.52693)
		(end 236.11713 -58.703972)
		(width 0.508)
		(layer "In11.Cu")
		(net "P1V8_PCH_AUX")
	)
	(segment
		(start 228.042978 -63.215774)
		(end 198.804276 -63.215774)
		(width 0.508)
		(layer "In11.Cu")
		(net "P1V8_PCH_AUX")
	)
	(segment
		(start 198.804276 -63.215774)
		(end 192.354962 -56.76646)
		(width 0.508)
		(layer "In11.Cu")
		(net "P1V8_PCH_AUX")
	)
	(segment
		(start 160.826704 -59.273948)
		(end 148.53793 -59.273948)
		(width 0.508)
		(layer "In11.Cu")
		(net "P1V8_PCH_AUX")
	)
	(segment
		(start 169.322496 -55.661052)
		(end 168.063418 -56.92013)
		(width 0.508)
		(layer "In11.Cu")
		(net "P1V8_PCH_AUX")
	)
	(segment
		(start 168.063418 -56.92013)
		(end 163.180522 -56.92013)
		(width 0.508)
		(layer "In11.Cu")
		(net "P1V8_PCH_AUX")
	)
	(segment
		(start 236.11713 -58.703972)
		(end 232.55478 -58.703972)
		(width 0.508)
		(layer "In11.Cu")
		(net "P1V8_PCH_AUX")
	)
	(segment
		(start 237.95609 -60.52693)
		(end 237.940088 -60.52693)
		(width 0.508)
		(layer "In11.Cu")
		(net "P1V8_PCH_AUX")
	)
	(segment
		(start 262.005826 -57.506616)
		(end 262.005826 -49.990502)
		(width 0.508)
		(layer "In13.Cu")
		(net "P1V8_PCH_AUX")
	)
	(segment
		(start 266.03833 -45.957998)
		(end 274.645628 -45.957998)
		(width 0.508)
		(layer "In13.Cu")
		(net "P1V8_PCH_AUX")
	)
	(segment
		(start 239.040162 -60.976002)
		(end 239.056164 -60.992004)
		(width 0.508)
		(layer "In13.Cu")
		(net "P1V8_PCH_AUX")
	)
	(segment
		(start 260.733286 -58.779156)
		(end 262.005826 -57.506616)
		(width 0.508)
		(layer "In13.Cu")
		(net "P1V8_PCH_AUX")
	)
	(segment
		(start 238.405162 -60.976002)
		(end 239.040162 -60.976002)
		(width 0.508)
		(layer "In13.Cu")
		(net "P1V8_PCH_AUX")
	)
	(segment
		(start 262.005826 -49.990502)
		(end 266.03833 -45.957998)
		(width 0.508)
		(layer "In13.Cu")
		(net "P1V8_PCH_AUX")
	)
	(segment
		(start 254.470916 -60.024772)
		(end 260.733286 -58.779156)
		(width 0.508)
		(layer "In13.Cu")
		(net "P1V8_PCH_AUX")
	)
	(segment
		(start 243.103654 -60.992004)
		(end 244.070886 -60.024772)
		(width 0.508)
		(layer "In13.Cu")
		(net "P1V8_PCH_AUX")
	)
	(segment
		(start 239.056164 -60.992004)
		(end 243.103654 -60.992004)
		(width 0.508)
		(layer "In13.Cu")
		(net "P1V8_PCH_AUX")
	)
	(segment
		(start 244.070886 -60.024772)
		(end 254.470916 -60.024772)
		(width 0.508)
		(layer "In13.Cu")
		(net "P1V8_PCH_AUX")
	)
	(segment
		(start 339.300058 -51.650646)
		(end 339.68563 -51.265074)
		(width 0.2032)
		(layer "F.Cu")
		(net "P1V05_PCH_PLL_AUX")
	)
	(segment
		(start 338.394548 -52.679346)
		(end 337.306666 -52.679346)
		(width 0.254)
		(layer "F.Cu")
		(net "P1V05_PCH_PLL_AUX")
	)
	(segment
		(start 339.826854 -49.79289)
		(end 339.300058 -49.266094)
		(width 0.254)
		(layer "F.Cu")
		(net "P1V05_PCH_PLL_AUX")
	)
	(segment
		(start 339.300058 -49.266094)
		(end 339.300058 -49.250346)
		(width 0.254)
		(layer "F.Cu")
		(net "P1V05_PCH_PLL_AUX")
	)
	(segment
		(start 338.93506 -52.679346)
		(end 338.394548 -52.679346)
		(width 0.2032)
		(layer "F.Cu")
		(net "P1V05_PCH_PLL_AUX")
	)
	(segment
		(start 340.562946 -47.980346)
		(end 340.290658 -47.510446)
		(width 0.2032)
		(layer "F.Cu")
		(net "P1V05_PCH_PLL_AUX")
	)
	(segment
		(start 340.290658 -46.570646)
		(end 340.535514 -46.993048)
		(width 0.2032)
		(layer "F.Cu")
		(net "P1V05_PCH_PLL_AUX")
	)
	(segment
		(start 340.562946 -52.679346)
		(end 340.280244 -52.191412)
		(width 0.2032)
		(layer "F.Cu")
		(net "P1V05_PCH_PLL_AUX")
	)
	(segment
		(start 340.562946 -49.859946)
		(end 339.826854 -49.79289)
		(width 0.2032)
		(layer "F.Cu")
		(net "P1V05_PCH_PLL_AUX")
	)
	(segment
		(start 338.499958 -45.249846)
		(end 338.900008 -44.849796)
		(width 0.2032)
		(layer "F.Cu")
		(net "P1V05_PCH_PLL_AUX")
	)
	(segment
		(start 340.535514 -46.993048)
		(end 340.562946 -47.040546)
		(width 0.2032)
		(layer "F.Cu")
		(net "P1V05_PCH_PLL_AUX")
	)
	(via
		(at 333.531718 -63.65367)
		(size 0.508)
		(drill 0.254)
		(layers "F.Cu" "B.Cu")
		(net "P1V05_PCH_PLL_AUX")
	)
	(via
		(at 332.087474 -65.049146)
		(size 0.508)
		(drill 0.254)
		(layers "F.Cu" "B.Cu")
		(net "P1V05_PCH_PLL_AUX")
	)
	(via
		(at 333.06385 -64.083438)
		(size 0.508)
		(drill 0.254)
		(layers "F.Cu" "B.Cu")
		(net "P1V05_PCH_PLL_AUX")
	)
	(via
		(at 340.290658 -46.570646)
		(size 0.4572)
		(drill 0.2032)
		(layers "F.Cu" "B.Cu")
		(net "P1V05_PCH_PLL_AUX")
	)
	(via
		(at 331.610208 -65.525396)
		(size 0.508)
		(drill 0.254)
		(layers "F.Cu" "B.Cu")
		(net "P1V05_PCH_PLL_AUX")
	)
	(via
		(at 332.557882 -64.557148)
		(size 0.508)
		(drill 0.254)
		(layers "F.Cu" "B.Cu")
		(net "P1V05_PCH_PLL_AUX")
	)
	(via
		(at 338.394548 -52.679346)
		(size 0.4572)
		(drill 0.2032)
		(layers "F.Cu" "B.Cu")
		(net "P1V05_PCH_PLL_AUX")
	)
	(via
		(at 338.900008 -44.849796)
		(size 0.4572)
		(drill 0.2032)
		(layers "F.Cu" "B.Cu")
		(net "P1V05_PCH_PLL_AUX")
	)
	(via
		(at 339.826854 -49.79289)
		(size 0.4572)
		(drill 0.2032)
		(layers "F.Cu" "B.Cu")
		(net "P1V05_PCH_PLL_AUX")
	)
	(via
		(at 340.290658 -47.510446)
		(size 0.4572)
		(drill 0.2032)
		(layers "F.Cu" "B.Cu")
		(net "P1V05_PCH_PLL_AUX")
	)
	(via
		(at 333.92999 -63.157354)
		(size 0.508)
		(drill 0.254)
		(layers "F.Cu" "B.Cu")
		(net "P1V05_PCH_PLL_AUX")
	)
	(via
		(at 334.5942 -63.541148)
		(size 0.6604)
		(drill 0.3302)
		(layers "F.Cu" "B.Cu")
		(net "P1V05_PCH_PLL_AUX")
	)
	(via
		(at 339.68563 -51.265074)
		(size 0.4572)
		(drill 0.2032)
		(layers "F.Cu" "B.Cu")
		(net "P1V05_PCH_PLL_AUX")
	)
	(via
		(at 340.280244 -52.191412)
		(size 0.4572)
		(drill 0.2032)
		(layers "F.Cu" "B.Cu")
		(net "P1V05_PCH_PLL_AUX")
	)
	(via
		(at 329.700128 -67.873626)
		(size 0.6604)
		(drill 0.3302)
		(layers "F.Cu" "B.Cu")
		(net "P1V05_PCH_PLL_AUX")
	)
	(segment
		(start 338.900008 -44.849796)
		(end 338.844636 -44.905168)
		(width 0.381)
		(layer "B.Cu")
		(net "P1V05_PCH_PLL_AUX")
	)
	(segment
		(start 338.394548 -52.679346)
		(end 338.786978 -53.071776)
		(width 0.4572)
		(layer "B.Cu")
		(net "P1V05_PCH_PLL_AUX")
	)
	(segment
		(start 338.844636 -44.905168)
		(end 338.844636 -45.481748)
		(width 0.381)
		(layer "B.Cu")
		(net "P1V05_PCH_PLL_AUX")
	)
	(segment
		(start 338.786978 -53.071776)
		(end 339.12048 -53.071776)
		(width 0.4572)
		(layer "B.Cu")
		(net "P1V05_PCH_PLL_AUX")
	)
	(via
		(at 263.554972 -66.3448)
		(size 0.508)
		(drill 0.254)
		(layers "F.Cu" "B.Cu")
		(net "P1V05_PCH_AUX_VCC")
	)
	(segment
		(start 261.704582 -74.21372)
		(end 261.704582 -75.042522)
		(width 0.254)
		(layer "F.Cu")
		(net "P1V05_PCH_AUX_REF")
	)
	(segment
		(start 261.704582 -74.058018)
		(end 261.704582 -74.21372)
		(width 0.1778)
		(layer "F.Cu")
		(net "P1V05_PCH_AUX_REF")
	)
	(segment
		(start 261.704582 -75.042522)
		(end 261.88035 -75.21829)
		(width 0.254)
		(layer "F.Cu")
		(net "P1V05_PCH_AUX_REF")
	)
	(segment
		(start 261.704582 -72.841104)
		(end 261.704582 -74.058018)
		(width 0.1778)
		(layer "F.Cu")
		(net "P1V05_PCH_AUX_REF")
	)
	(segment
		(start 261.88035 -75.21829)
		(end 262.84809 -75.21829)
		(width 0.254)
		(layer "F.Cu")
		(net "P1V05_PCH_AUX_REF")
	)
	(via
		(at 261.704582 -74.058018)
		(size 0.4064)
		(drill 0.2032)
		(layers "F.Cu" "B.Cu")
		(net "P1V05_PCH_AUX_REF")
	)
	(segment
		(start 260.904482 -72.841104)
		(end 260.904482 -73.179432)
		(width 0.1778)
		(layer "F.Cu")
		(net "P1V05_PCH_AUX_FB")
	)
	(segment
		(start 260.161532 -74.506074)
		(end 260.161532 -75.505056)
		(width 0.254)
		(layer "F.Cu")
		(net "P1V05_PCH_AUX_FB")
	)
	(segment
		(start 260.568948 -74.098658)
		(end 260.161532 -74.506074)
		(width 0.1778)
		(layer "F.Cu")
		(net "P1V05_PCH_AUX_FB")
	)
	(segment
		(start 260.90372 -73.180194)
		(end 260.90372 -73.447402)
		(width 0.1778)
		(layer "F.Cu")
		(net "P1V05_PCH_AUX_FB")
	)
	(segment
		(start 260.568948 -73.782174)
		(end 260.568948 -74.098658)
		(width 0.1778)
		(layer "F.Cu")
		(net "P1V05_PCH_AUX_FB")
	)
	(segment
		(start 260.90372 -73.447402)
		(end 260.568948 -73.782174)
		(width 0.1778)
		(layer "F.Cu")
		(net "P1V05_PCH_AUX_FB")
	)
	(segment
		(start 260.161532 -76.533502)
		(end 260.161532 -75.505056)
		(width 0.254)
		(layer "F.Cu")
		(net "P1V05_PCH_AUX_FB")
	)
	(segment
		(start 260.904482 -73.179432)
		(end 260.90372 -73.180194)
		(width 0.1778)
		(layer "F.Cu")
		(net "P1V05_PCH_AUX_FB")
	)
	(segment
		(start 260.161532 -77.549502)
		(end 260.161532 -76.533502)
		(width 0.254)
		(layer "F.Cu")
		(net "P1V05_PCH_AUX_FB")
	)
	(via
		(at 260.568948 -74.098658)
		(size 0.508)
		(drill 0.254)
		(layers "F.Cu" "B.Cu")
		(net "P1V05_PCH_AUX_FB")
	)
	(segment
		(start 262.73252 -74.027792)
		(end 262.73252 -74.326496)
		(width 0.254)
		(layer "F.Cu")
		(net "P1V05_PCH_AUX_CS")
	)
	(segment
		(start 262.504682 -73.596754)
		(end 262.73252 -73.824592)
		(width 0.1778)
		(layer "F.Cu")
		(net "P1V05_PCH_AUX_CS")
	)
	(segment
		(start 262.94842 -74.542396)
		(end 263.07796 -74.59599)
		(width 0.254)
		(layer "F.Cu")
		(net "P1V05_PCH_AUX_CS")
	)
	(segment
		(start 262.73252 -74.326496)
		(end 262.94842 -74.542396)
		(width 0.254)
		(layer "F.Cu")
		(net "P1V05_PCH_AUX_CS")
	)
	(segment
		(start 263.07796 -74.59599)
		(end 263.70026 -75.21829)
		(width 0.254)
		(layer "F.Cu")
		(net "P1V05_PCH_AUX_CS")
	)
	(segment
		(start 262.504682 -72.841104)
		(end 262.504682 -73.596754)
		(width 0.1778)
		(layer "F.Cu")
		(net "P1V05_PCH_AUX_CS")
	)
	(segment
		(start 263.70026 -75.21829)
		(end 263.805924 -75.21829)
		(width 0.254)
		(layer "F.Cu")
		(net "P1V05_PCH_AUX_CS")
	)
	(segment
		(start 262.73252 -73.824592)
		(end 262.73252 -74.027792)
		(width 0.1778)
		(layer "F.Cu")
		(net "P1V05_PCH_AUX_CS")
	)
	(segment
		(start 339.300058 -48.450246)
		(end 338.499958 -48.450246)
		(width 0.2032)
		(layer "F.Cu")
		(net "P1V05_PCH_AUX")
	)
	(segment
		(start 232.778046 -73.073768)
		(end 227.180648 -78.671166)
		(width 0.508)
		(layer "F.Cu")
		(net "P1V05_PCH_AUX")
	)
	(segment
		(start 245.5545 -80.180688)
		(end 245.15318 -80.582008)
		(width 0.508)
		(layer "F.Cu")
		(net "P1V05_PCH_AUX")
	)
	(segment
		(start 339.300058 -47.650146)
		(end 338.499958 -47.650146)
		(width 0.2032)
		(layer "F.Cu")
		(net "P1V05_PCH_AUX")
	)
	(segment
		(start 338.499958 -47.650146)
		(end 338.099908 -47.250096)
		(width 0.2032)
		(layer "F.Cu")
		(net "P1V05_PCH_AUX")
	)
	(segment
		(start 338.499958 -46.049946)
		(end 338.099908 -45.649896)
		(width 0.2032)
		(layer "F.Cu")
		(net "P1V05_PCH_AUX")
	)
	(segment
		(start 227.180648 -83.791806)
		(end 226.167188 -84.805266)
		(width 0.508)
		(layer "F.Cu")
		(net "P1V05_PCH_AUX")
	)
	(segment
		(start 271.097502 -81.519014)
		(end 253.69647 -81.519014)
		(width 0.508)
		(layer "F.Cu")
		(net "P1V05_PCH_AUX")
	)
	(segment
		(start 244.313456 -80.582008)
		(end 244.02161 -80.290162)
		(width 0.508)
		(layer "F.Cu")
		(net "P1V05_PCH_AUX")
	)
	(segment
		(start 336.099658 -45.249846)
		(end 336.127852 -45.249846)
		(width 0.2032)
		(layer "F.Cu")
		(net "P1V05_PCH_AUX")
	)
	(segment
		(start 371.348 -38.953948)
		(end 371.348 -39.315898)
		(width 0.254)
		(layer "F.Cu")
		(net "P1V05_PCH_AUX")
	)
	(segment
		(start 279.5778 -72.050148)
		(end 280.518108 -71.10984)
		(width 0.508)
		(layer "F.Cu")
		(net "P1V05_PCH_AUX")
	)
	(segment
		(start 338.499958 -48.450246)
		(end 338.099908 -48.050196)
		(width 0.2032)
		(layer "F.Cu")
		(net "P1V05_PCH_AUX")
	)
	(segment
		(start 336.499708 -45.649896)
		(end 336.899758 -46.049946)
		(width 0.2032)
		(layer "F.Cu")
		(net "P1V05_PCH_AUX")
	)
	(segment
		(start 243.89588 -76.706476)
		(end 240.263172 -73.073768)
		(width 0.508)
		(layer "F.Cu")
		(net "P1V05_PCH_AUX")
	)
	(segment
		(start 336.127852 -45.249846)
		(end 336.57159 -44.806108)
		(width 0.2032)
		(layer "F.Cu")
		(net "P1V05_PCH_AUX")
	)
	(segment
		(start 298.036996 -43.194224)
		(end 297.33113 -43.194224)
		(width 0.381)
		(layer "F.Cu")
		(net "P1V05_PCH_AUX")
	)
	(segment
		(start 334.499458 -50.850546)
		(end 335.299558 -50.850546)
		(width 0.2032)
		(layer "F.Cu")
		(net "P1V05_PCH_AUX")
	)
	(segment
		(start 278.637492 -71.10984)
		(end 279.5778 -72.050148)
		(width 0.508)
		(layer "F.Cu")
		(net "P1V05_PCH_AUX")
	)
	(segment
		(start 298.62018 -55.416196)
		(end 297.90009 -55.416196)
		(width 0.381)
		(layer "F.Cu")
		(net "P1V05_PCH_AUX")
	)
	(segment
		(start 297.9674 -47.488348)
		(end 297.9674 -47.363126)
		(width 0.381)
		(layer "F.Cu")
		(net "P1V05_PCH_AUX")
	)
	(segment
		(start 336.899758 -46.850046)
		(end 336.499708 -46.449996)
		(width 0.2032)
		(layer "F.Cu")
		(net "P1V05_PCH_AUX")
	)
	(segment
		(start 318.8081 -76.985114)
		(end 318.8081 -77.777594)
		(width 0.381)
		(layer "F.Cu")
		(net "P1V05_PCH_AUX")
	)
	(segment
		(start 366.378236 -53.532278)
		(end 366.73028 -53.532278)
		(width 0.254)
		(layer "F.Cu")
		(net "P1V05_PCH_AUX")
	)
	(segment
		(start 333.23657 -53.149246)
		(end 332.697328 -53.149246)
		(width 0.2032)
		(layer "F.Cu")
		(net "P1V05_PCH_AUX")
	)
	(segment
		(start 253.69647 -81.519014)
		(end 252.358144 -80.180688)
		(width 0.508)
		(layer "F.Cu")
		(net "P1V05_PCH_AUX")
	)
	(segment
		(start 336.899758 -49.250346)
		(end 336.499708 -49.650396)
		(width 0.2032)
		(layer "F.Cu")
		(net "P1V05_PCH_AUX")
	)
	(segment
		(start 298.62018 -54.400196)
		(end 298.62018 -55.416196)
		(width 0.381)
		(layer "F.Cu")
		(net "P1V05_PCH_AUX")
	)
	(segment
		(start 336.899758 -47.650146)
		(end 336.499708 -47.250096)
		(width 0.2032)
		(layer "F.Cu")
		(net "P1V05_PCH_AUX")
	)
	(segment
		(start 336.499708 -46.449996)
		(end 336.099658 -46.850046)
		(width 0.2032)
		(layer "F.Cu")
		(net "P1V05_PCH_AUX")
	)
	(segment
		(start 252.358144 -80.180688)
		(end 245.5545 -80.180688)
		(width 0.508)
		(layer "F.Cu")
		(net "P1V05_PCH_AUX")
	)
	(segment
		(start 338.099908 -46.449996)
		(end 338.499958 -46.850046)
		(width 0.2032)
		(layer "F.Cu")
		(net "P1V05_PCH_AUX")
	)
	(segment
		(start 337.306666 -53.619146)
		(end 336.766408 -53.619146)
		(width 0.2032)
		(layer "F.Cu")
		(net "P1V05_PCH_AUX")
	)
	(segment
		(start 337.306666 -44.221146)
		(end 336.766662 -44.221146)
		(width 0.2032)
		(layer "F.Cu")
		(net "P1V05_PCH_AUX")
	)
	(segment
		(start 338.499958 -46.850046)
		(end 339.300058 -46.850046)
		(width 0.2032)
		(layer "F.Cu")
		(net "P1V05_PCH_AUX")
	)
	(segment
		(start 337.299808 -51.250596)
		(end 337.699858 -50.850546)
		(width 0.2032)
		(layer "F.Cu")
		(net "P1V05_PCH_AUX")
	)
	(segment
		(start 377.941332 -59.295792)
		(end 377.941332 -59.959748)
		(width 0.381)
		(layer "F.Cu")
		(net "P1V05_PCH_AUX")
	)
	(segment
		(start 278.662892 -66.818256)
		(end 279.6032 -65.877948)
		(width 0.508)
		(layer "F.Cu")
		(net "P1V05_PCH_AUX")
	)
	(segment
		(start 377.14047 -109.720888)
		(end 377.14047 -108.604558)
		(width 0.508)
		(layer "F.Cu")
		(net "P1V05_PCH_AUX")
	)
	(segment
		(start 298.62018 -51.352196)
		(end 297.92295 -51.352196)
		(width 0.381)
		(layer "F.Cu")
		(net "P1V05_PCH_AUX")
	)
	(segment
		(start 336.099658 -46.049946)
		(end 336.499708 -45.649896)
		(width 0.2032)
		(layer "F.Cu")
		(net "P1V05_PCH_AUX")
	)
	(segment
		(start 336.899758 -45.134276)
		(end 336.899758 -45.249846)
		(width 0.2032)
		(layer "F.Cu")
		(net "P1V05_PCH_AUX")
	)
	(segment
		(start 335.699608 -51.250596)
		(end 336.099658 -50.850546)
		(width 0.2032)
		(layer "F.Cu")
		(net "P1V05_PCH_AUX")
	)
	(segment
		(start 273.308572 -79.307944)
		(end 271.097502 -81.519014)
		(width 0.508)
		(layer "F.Cu")
		(net "P1V05_PCH_AUX")
	)
	(segment
		(start 334.899508 -49.650396)
		(end 335.299558 -49.250346)
		(width 0.2032)
		(layer "F.Cu")
		(net "P1V05_PCH_AUX")
	)
	(segment
		(start 338.396072 -43.281346)
		(end 338.93506 -43.281346)
		(width 0.2032)
		(layer "F.Cu")
		(net "P1V05_PCH_AUX")
	)
	(segment
		(start 435.57317 -42.140886)
		(end 436.275226 -42.140886)
		(width 0.381)
		(layer "F.Cu")
		(net "P1V05_PCH_AUX")
	)
	(segment
		(start 359.117138 -60.840112)
		(end 357.837232 -59.560206)
		(width 0.4572)
		(layer "F.Cu")
		(net "P1V05_PCH_AUX")
	)
	(segment
		(start 317.018162 -62.83706)
		(end 317.018162 -62.342268)
		(width 0.381)
		(layer "F.Cu")
		(net "P1V05_PCH_AUX")
	)
	(segment
		(start 336.099658 -49.250346)
		(end 335.699608 -49.650396)
		(width 0.2032)
		(layer "F.Cu")
		(net "P1V05_PCH_AUX")
	)
	(segment
		(start 298.04233 -47.288196)
		(end 298.62018 -47.288196)
		(width 0.381)
		(layer "F.Cu")
		(net "P1V05_PCH_AUX")
	)
	(segment
		(start 278.662892 -64.93764)
		(end 279.6032 -65.877948)
		(width 0.508)
		(layer "F.Cu")
		(net "P1V05_PCH_AUX")
	)
	(segment
		(start 244.02161 -80.290162)
		(end 243.89588 -79.986378)
		(width 0.508)
		(layer "F.Cu")
		(net "P1V05_PCH_AUX")
	)
	(segment
		(start 336.499708 -47.250096)
		(end 336.099658 -47.650146)
		(width 0.2032)
		(layer "F.Cu")
		(net "P1V05_PCH_AUX")
	)
	(segment
		(start 336.57159 -44.806108)
		(end 336.899758 -45.134276)
		(width 0.2032)
		(layer "F.Cu")
		(net "P1V05_PCH_AUX")
	)
	(segment
		(start 337.699858 -49.250346)
		(end 337.299808 -49.650396)
		(width 0.2032)
		(layer "F.Cu")
		(net "P1V05_PCH_AUX")
	)
	(segment
		(start 322.8721 -76.985114)
		(end 322.8721 -77.671168)
		(width 0.381)
		(layer "F.Cu")
		(net "P1V05_PCH_AUX")
	)
	(segment
		(start 298.62018 -50.336196)
		(end 298.62018 -51.352196)
		(width 0.381)
		(layer "F.Cu")
		(net "P1V05_PCH_AUX")
	)
	(segment
		(start 240.263172 -73.073768)
		(end 232.778046 -73.073768)
		(width 0.508)
		(layer "F.Cu")
		(net "P1V05_PCH_AUX")
	)
	(segment
		(start 335.299558 -50.850546)
		(end 335.699608 -51.250596)
		(width 0.2032)
		(layer "F.Cu")
		(net "P1V05_PCH_AUX")
	)
	(segment
		(start 316.707012 -63.14821)
		(end 317.018162 -62.83706)
		(width 0.381)
		(layer "F.Cu")
		(net "P1V05_PCH_AUX")
	)
	(segment
		(start 338.93506 -53.619146)
		(end 338.394548 -53.619146)
		(width 0.2032)
		(layer "F.Cu")
		(net "P1V05_PCH_AUX")
	)
	(segment
		(start 279.6032 -65.877948)
		(end 280.543508 -64.93764)
		(width 0.508)
		(layer "F.Cu")
		(net "P1V05_PCH_AUX")
	)
	(segment
		(start 245.15318 -80.582008)
		(end 244.313456 -80.582008)
		(width 0.508)
		(layer "F.Cu")
		(net "P1V05_PCH_AUX")
	)
	(segment
		(start 337.306666 -43.281346)
		(end 336.49285 -43.751246)
		(width 0.2032)
		(layer "F.Cu")
		(net "P1V05_PCH_AUX")
	)
	(segment
		(start 297.9674 -47.363126)
		(end 298.04233 -47.288196)
		(width 0.381)
		(layer "F.Cu")
		(net "P1V05_PCH_AUX")
	)
	(segment
		(start 279.6032 -65.877948)
		(end 280.543508 -66.818256)
		(width 0.508)
		(layer "F.Cu")
		(net "P1V05_PCH_AUX")
	)
	(segment
		(start 278.637492 -72.990456)
		(end 279.5778 -72.050148)
		(width 0.508)
		(layer "F.Cu")
		(net "P1V05_PCH_AUX")
	)
	(segment
		(start 371.348 -39.315898)
		(end 371.602 -39.569898)
		(width 0.254)
		(layer "F.Cu")
		(net "P1V05_PCH_AUX")
	)
	(segment
		(start 94.373954 -56.225948)
		(end 94.373954 -57.114948)
		(width 0.381)
		(layer "F.Cu")
		(net "P1V05_PCH_AUX")
	)
	(segment
		(start 273.308572 -73.5076)
		(end 273.308572 -79.307944)
		(width 0.508)
		(layer "F.Cu")
		(net "P1V05_PCH_AUX")
	)
	(segment
		(start 319.8241 -76.985114)
		(end 318.8081 -76.985114)
		(width 0.381)
		(layer "F.Cu")
		(net "P1V05_PCH_AUX")
	)
	(segment
		(start 279.5778 -72.050148)
		(end 280.518108 -72.990456)
		(width 0.508)
		(layer "F.Cu")
		(net "P1V05_PCH_AUX")
	)
	(segment
		(start 385.316222 -63.423292)
		(end 384.706622 -63.423292)
		(width 0.381)
		(layer "F.Cu")
		(net "P1V05_PCH_AUX")
	)
	(segment
		(start 366.73028 -53.532278)
		(end 367.01095 -53.812948)
		(width 0.254)
		(layer "F.Cu")
		(net "P1V05_PCH_AUX")
	)
	(segment
		(start 336.766662 -44.221146)
		(end 336.49285 -43.751246)
		(width 0.2032)
		(layer "F.Cu")
		(net "P1V05_PCH_AUX")
	)
	(segment
		(start 338.120736 -54.089046)
		(end 337.581748 -54.089046)
		(width 0.2032)
		(layer "F.Cu")
		(net "P1V05_PCH_AUX")
	)
	(segment
		(start 336.899758 -50.850546)
		(end 337.299808 -51.250596)
		(width 0.254)
		(layer "F.Cu")
		(net "P1V05_PCH_AUX")
	)
	(segment
		(start 377.86564 -64.866012)
		(end 378.47524 -64.866012)
		(width 0.381)
		(layer "F.Cu")
		(net "P1V05_PCH_AUX")
	)
	(segment
		(start 357.837232 -59.560206)
		(end 357.837232 -57.898792)
		(width 0.4572)
		(layer "F.Cu")
		(net "P1V05_PCH_AUX")
	)
	(segment
		(start 300.094904 -42.387774)
		(end 300.094904 -43.750738)
		(width 0.381)
		(layer "F.Cu")
		(net "P1V05_PCH_AUX")
	)
	(segment
		(start 339.300058 -46.049946)
		(end 338.499958 -46.049946)
		(width 0.2032)
		(layer "F.Cu")
		(net "P1V05_PCH_AUX")
	)
	(segment
		(start 243.89588 -79.986378)
		(end 243.89588 -76.706476)
		(width 0.508)
		(layer "F.Cu")
		(net "P1V05_PCH_AUX")
	)
	(segment
		(start 227.180648 -78.671166)
		(end 227.180648 -83.791806)
		(width 0.508)
		(layer "F.Cu")
		(net "P1V05_PCH_AUX")
	)
	(via
		(at 334.899508 -49.650396)
		(size 0.4572)
		(drill 0.2032)
		(layers "F.Cu" "B.Cu")
		(net "P1V05_PCH_AUX")
	)
	(via
		(at 315.768736 -46.335188)
		(size 0.508)
		(drill 0.254)
		(layers "F.Cu" "B.Cu")
		(net "P1V05_PCH_AUX")
	)
	(via
		(at 338.099908 -48.050196)
		(size 0.4572)
		(drill 0.2032)
		(layers "F.Cu" "B.Cu")
		(net "P1V05_PCH_AUX")
	)
	(via
		(at 147.76577 -60.192412)
		(size 0.508)
		(drill 0.254)
		(layers "F.Cu" "B.Cu")
		(net "P1V05_PCH_AUX")
	)
	(via
		(at 275.594572 -73.5076)
		(size 0.508)
		(drill 0.254)
		(layers "F.Cu" "B.Cu")
		(net "P1V05_PCH_AUX")
	)
	(via
		(at 300.101 -53.838348)
		(size 0.508)
		(drill 0.254)
		(layers "F.Cu" "B.Cu")
		(net "P1V05_PCH_AUX")
	)
	(via
		(at 377.941332 -59.959748)
		(size 0.508)
		(drill 0.254)
		(layers "F.Cu" "B.Cu")
		(net "P1V05_PCH_AUX")
	)
	(via
		(at 337.299808 -51.250596)
		(size 0.4572)
		(drill 0.2032)
		(layers "F.Cu" "B.Cu")
		(net "P1V05_PCH_AUX")
	)
	(via
		(at 301.8282 -48.021748)
		(size 0.508)
		(drill 0.254)
		(layers "F.Cu" "B.Cu")
		(net "P1V05_PCH_AUX")
	)
	(via
		(at 274.402042 -67.421252)
		(size 0.508)
		(drill 0.254)
		(layers "F.Cu" "B.Cu")
		(net "P1V05_PCH_AUX")
	)
	(via
		(at 273.308572 -73.5076)
		(size 0.508)
		(drill 0.254)
		(layers "F.Cu" "B.Cu")
		(net "P1V05_PCH_AUX")
	)
	(via
		(at 275.291042 -67.421252)
		(size 0.508)
		(drill 0.254)
		(layers "F.Cu" "B.Cu")
		(net "P1V05_PCH_AUX")
	)
	(via
		(at 386.018532 -67.350894)
		(size 0.508)
		(drill 0.254)
		(layers "F.Cu" "B.Cu")
		(net "P1V05_PCH_AUX")
	)
	(via
		(at 301.879 -52.266088)
		(size 0.508)
		(drill 0.254)
		(layers "F.Cu" "B.Cu")
		(net "P1V05_PCH_AUX")
	)
	(via
		(at 316.360556 -56.972708)
		(size 0.508)
		(drill 0.254)
		(layers "F.Cu" "B.Cu")
		(net "P1V05_PCH_AUX")
	)
	(via
		(at 281.708352 -61.129672)
		(size 0.508)
		(drill 0.254)
		(layers "F.Cu" "B.Cu")
		(net "P1V05_PCH_AUX")
	)
	(via
		(at 282.427172 -60.380372)
		(size 0.508)
		(drill 0.254)
		(layers "F.Cu" "B.Cu")
		(net "P1V05_PCH_AUX")
	)
	(via
		(at 336.766408 -53.619146)
		(size 0.4572)
		(drill 0.2032)
		(layers "F.Cu" "B.Cu")
		(net "P1V05_PCH_AUX")
	)
	(via
		(at 308.390036 -45.966888)
		(size 0.508)
		(drill 0.254)
		(layers "F.Cu" "B.Cu")
		(net "P1V05_PCH_AUX")
	)
	(via
		(at 275.306282 -66.253868)
		(size 0.508)
		(drill 0.254)
		(layers "F.Cu" "B.Cu")
		(net "P1V05_PCH_AUX")
	)
	(via
		(at 386.653532 -67.350894)
		(size 0.508)
		(drill 0.254)
		(layers "F.Cu" "B.Cu")
		(net "P1V05_PCH_AUX")
	)
	(via
		(at 314.927996 -46.309788)
		(size 0.508)
		(drill 0.254)
		(layers "F.Cu" "B.Cu")
		(net "P1V05_PCH_AUX")
	)
	(via
		(at 436.275226 -42.140886)
		(size 0.508)
		(drill 0.254)
		(layers "F.Cu" "B.Cu")
		(net "P1V05_PCH_AUX")
	)
	(via
		(at 282.427172 -59.618372)
		(size 0.508)
		(drill 0.254)
		(layers "F.Cu" "B.Cu")
		(net "P1V05_PCH_AUX")
	)
	(via
		(at 300.101 -54.854348)
		(size 0.508)
		(drill 0.254)
		(layers "F.Cu" "B.Cu")
		(net "P1V05_PCH_AUX")
	)
	(via
		(at 300.094904 -43.750738)
		(size 0.508)
		(drill 0.254)
		(layers "F.Cu" "B.Cu")
		(net "P1V05_PCH_AUX")
	)
	(via
		(at 273.513042 -67.421252)
		(size 0.508)
		(drill 0.254)
		(layers "F.Cu" "B.Cu")
		(net "P1V05_PCH_AUX")
	)
	(via
		(at 378.47524 -64.866012)
		(size 0.508)
		(drill 0.254)
		(layers "F.Cu" "B.Cu")
		(net "P1V05_PCH_AUX")
	)
	(via
		(at 310.61406 -39.878508)
		(size 0.508)
		(drill 0.254)
		(layers "F.Cu" "B.Cu")
		(net "P1V05_PCH_AUX")
	)
	(via
		(at 322.8721 -77.671168)
		(size 0.508)
		(drill 0.254)
		(layers "F.Cu" "B.Cu")
		(net "P1V05_PCH_AUX")
	)
	(via
		(at 94.373954 -57.114948)
		(size 0.508)
		(drill 0.254)
		(layers "F.Cu" "B.Cu")
		(net "P1V05_PCH_AUX")
	)
	(via
		(at 335.699608 -49.650396)
		(size 0.4572)
		(drill 0.2032)
		(layers "F.Cu" "B.Cu")
		(net "P1V05_PCH_AUX")
	)
	(via
		(at 274.567142 -62.575948)
		(size 0.508)
		(drill 0.254)
		(layers "F.Cu" "B.Cu")
		(net "P1V05_PCH_AUX")
	)
	(via
		(at 321.204336 -57.554368)
		(size 0.508)
		(drill 0.254)
		(layers "F.Cu" "B.Cu")
		(net "P1V05_PCH_AUX")
	)
	(via
		(at 377.14047 -108.604558)
		(size 0.508)
		(drill 0.254)
		(layers "F.Cu" "B.Cu")
		(net "P1V05_PCH_AUX")
	)
	(via
		(at 273.1516 -69.535548)
		(size 0.508)
		(drill 0.254)
		(layers "F.Cu" "B.Cu")
		(net "P1V05_PCH_AUX")
	)
	(via
		(at 384.706622 -63.423292)
		(size 0.508)
		(drill 0.254)
		(layers "F.Cu" "B.Cu")
		(net "P1V05_PCH_AUX")
	)
	(via
		(at 332.697328 -53.149246)
		(size 0.4572)
		(drill 0.2032)
		(layers "F.Cu" "B.Cu")
		(net "P1V05_PCH_AUX")
	)
	(via
		(at 336.499708 -45.649896)
		(size 0.4572)
		(drill 0.2032)
		(layers "F.Cu" "B.Cu")
		(net "P1V05_PCH_AUX")
	)
	(via
		(at 336.499708 -47.250096)
		(size 0.4572)
		(drill 0.2032)
		(layers "F.Cu" "B.Cu")
		(net "P1V05_PCH_AUX")
	)
	(via
		(at 281.708352 -59.605672)
		(size 0.508)
		(drill 0.254)
		(layers "F.Cu" "B.Cu")
		(net "P1V05_PCH_AUX")
	)
	(via
		(at 336.57159 -44.806108)
		(size 0.4572)
		(drill 0.2032)
		(layers "F.Cu" "B.Cu")
		(net "P1V05_PCH_AUX")
	)
	(via
		(at 273.9136 -69.535548)
		(size 0.508)
		(drill 0.254)
		(layers "F.Cu" "B.Cu")
		(net "P1V05_PCH_AUX")
	)
	(via
		(at 336.499708 -46.449996)
		(size 0.4572)
		(drill 0.2032)
		(layers "F.Cu" "B.Cu")
		(net "P1V05_PCH_AUX")
	)
	(via
		(at 301.5742 -55.336948)
		(size 0.508)
		(drill 0.254)
		(layers "F.Cu" "B.Cu")
		(net "P1V05_PCH_AUX")
	)
	(via
		(at 371.348 -38.953948)
		(size 0.508)
		(drill 0.254)
		(layers "F.Cu" "B.Cu")
		(net "P1V05_PCH_AUX")
	)
	(via
		(at 281.708352 -60.367672)
		(size 0.508)
		(drill 0.254)
		(layers "F.Cu" "B.Cu")
		(net "P1V05_PCH_AUX")
	)
	(via
		(at 322.555616 -48.943768)
		(size 0.508)
		(drill 0.254)
		(layers "F.Cu" "B.Cu")
		(net "P1V05_PCH_AUX")
	)
	(via
		(at 338.099908 -47.250096)
		(size 0.4572)
		(drill 0.2032)
		(layers "F.Cu" "B.Cu")
		(net "P1V05_PCH_AUX")
	)
	(via
		(at 276.1996 -69.535548)
		(size 0.508)
		(drill 0.254)
		(layers "F.Cu" "B.Cu")
		(net "P1V05_PCH_AUX")
	)
	(via
		(at 275.044662 -68.450968)
		(size 0.508)
		(drill 0.254)
		(layers "F.Cu" "B.Cu")
		(net "P1V05_PCH_AUX")
	)
	(via
		(at 327.66127 -73.728072)
		(size 0.508)
		(drill 0.254)
		(layers "F.Cu" "B.Cu")
		(net "P1V05_PCH_AUX")
	)
	(via
		(at 319.174622 -56.251348)
		(size 0.508)
		(drill 0.254)
		(layers "F.Cu" "B.Cu")
		(net "P1V05_PCH_AUX")
	)
	(via
		(at 301.33036 -51.940968)
		(size 0.508)
		(drill 0.254)
		(layers "F.Cu" "B.Cu")
		(net "P1V05_PCH_AUX")
	)
	(via
		(at 366.378236 -53.532278)
		(size 0.508)
		(drill 0.254)
		(layers "F.Cu" "B.Cu")
		(net "P1V05_PCH_AUX")
	)
	(via
		(at 336.499708 -49.650396)
		(size 0.4572)
		(drill 0.2032)
		(layers "F.Cu" "B.Cu")
		(net "P1V05_PCH_AUX")
	)
	(via
		(at 300.101 -55.489348)
		(size 0.508)
		(drill 0.254)
		(layers "F.Cu" "B.Cu")
		(net "P1V05_PCH_AUX")
	)
	(via
		(at 274.070572 -73.5076)
		(size 0.508)
		(drill 0.254)
		(layers "F.Cu" "B.Cu")
		(net "P1V05_PCH_AUX")
	)
	(via
		(at 316.707012 -63.14821)
		(size 0.508)
		(drill 0.254)
		(layers "F.Cu" "B.Cu")
		(net "P1V05_PCH_AUX")
	)
	(via
		(at 308.532022 -44.440348)
		(size 0.508)
		(drill 0.254)
		(layers "F.Cu" "B.Cu")
		(net "P1V05_PCH_AUX")
	)
	(via
		(at 274.544282 -66.253868)
		(size 0.508)
		(drill 0.254)
		(layers "F.Cu" "B.Cu")
		(net "P1V05_PCH_AUX")
	)
	(via
		(at 274.6756 -69.535548)
		(size 0.508)
		(drill 0.254)
		(layers "F.Cu" "B.Cu")
		(net "P1V05_PCH_AUX")
	)
	(via
		(at 327.932034 -69.987922)
		(size 0.508)
		(drill 0.254)
		(layers "F.Cu" "B.Cu")
		(net "P1V05_PCH_AUX")
	)
	(via
		(at 273.805142 -62.575948)
		(size 0.508)
		(drill 0.254)
		(layers "F.Cu" "B.Cu")
		(net "P1V05_PCH_AUX")
	)
	(via
		(at 189.038738 -79.399892)
		(size 0.508)
		(drill 0.254)
		(layers "F.Cu" "B.Cu")
		(net "P1V05_PCH_AUX")
	)
	(via
		(at 274.282662 -68.450968)
		(size 0.508)
		(drill 0.254)
		(layers "F.Cu" "B.Cu")
		(net "P1V05_PCH_AUX")
	)
	(via
		(at 297.33113 -43.194224)
		(size 0.508)
		(drill 0.254)
		(layers "F.Cu" "B.Cu")
		(net "P1V05_PCH_AUX")
	)
	(via
		(at 318.8081 -77.777594)
		(size 0.508)
		(drill 0.254)
		(layers "F.Cu" "B.Cu")
		(net "P1V05_PCH_AUX")
	)
	(via
		(at 282.427172 -61.142372)
		(size 0.508)
		(drill 0.254)
		(layers "F.Cu" "B.Cu")
		(net "P1V05_PCH_AUX")
	)
	(via
		(at 337.299808 -49.650396)
		(size 0.4572)
		(drill 0.2032)
		(layers "F.Cu" "B.Cu")
		(net "P1V05_PCH_AUX")
	)
	(via
		(at 276.356572 -73.5076)
		(size 0.508)
		(drill 0.254)
		(layers "F.Cu" "B.Cu")
		(net "P1V05_PCH_AUX")
	)
	(via
		(at 313.99988 -48.097948)
		(size 0.508)
		(drill 0.254)
		(layers "F.Cu" "B.Cu")
		(net "P1V05_PCH_AUX")
	)
	(via
		(at 338.099908 -45.649896)
		(size 0.4572)
		(drill 0.2032)
		(layers "F.Cu" "B.Cu")
		(net "P1V05_PCH_AUX")
	)
	(via
		(at 300.067726 -50.605436)
		(size 0.508)
		(drill 0.254)
		(layers "F.Cu" "B.Cu")
		(net "P1V05_PCH_AUX")
	)
	(via
		(at 359.117138 -60.840112)
		(size 0.508)
		(drill 0.254)
		(layers "F.Cu" "B.Cu")
		(net "P1V05_PCH_AUX")
	)
	(via
		(at 297.90009 -55.416196)
		(size 0.508)
		(drill 0.254)
		(layers "F.Cu" "B.Cu")
		(net "P1V05_PCH_AUX")
	)
	(via
		(at 327.932034 -70.749922)
		(size 0.508)
		(drill 0.254)
		(layers "F.Cu" "B.Cu")
		(net "P1V05_PCH_AUX")
	)
	(via
		(at 315.144912 -34.594292)
		(size 0.508)
		(drill 0.254)
		(layers "F.Cu" "B.Cu")
		(net "P1V05_PCH_AUX")
	)
	(via
		(at 338.396072 -43.281346)
		(size 0.4572)
		(drill 0.2032)
		(layers "F.Cu" "B.Cu")
		(net "P1V05_PCH_AUX")
	)
	(via
		(at 275.4376 -69.535548)
		(size 0.508)
		(drill 0.254)
		(layers "F.Cu" "B.Cu")
		(net "P1V05_PCH_AUX")
	)
	(via
		(at 338.394548 -53.619146)
		(size 0.4572)
		(drill 0.2032)
		(layers "F.Cu" "B.Cu")
		(net "P1V05_PCH_AUX")
	)
	(via
		(at 321.891406 -48.810418)
		(size 0.508)
		(drill 0.254)
		(layers "F.Cu" "B.Cu")
		(net "P1V05_PCH_AUX")
	)
	(via
		(at 273.782282 -66.253868)
		(size 0.508)
		(drill 0.254)
		(layers "F.Cu" "B.Cu")
		(net "P1V05_PCH_AUX")
	)
	(via
		(at 336.766662 -44.221146)
		(size 0.4572)
		(drill 0.2032)
		(layers "F.Cu" "B.Cu")
		(net "P1V05_PCH_AUX")
	)
	(via
		(at 337.581748 -54.089046)
		(size 0.4572)
		(drill 0.2032)
		(layers "F.Cu" "B.Cu")
		(net "P1V05_PCH_AUX")
	)
	(via
		(at 275.329142 -62.575948)
		(size 0.508)
		(drill 0.254)
		(layers "F.Cu" "B.Cu")
		(net "P1V05_PCH_AUX")
	)
	(via
		(at 297.92295 -51.352196)
		(size 0.508)
		(drill 0.254)
		(layers "F.Cu" "B.Cu")
		(net "P1V05_PCH_AUX")
	)
	(via
		(at 275.6662 -71.669148)
		(size 0.6604)
		(drill 0.3302)
		(layers "F.Cu" "B.Cu")
		(net "P1V05_PCH_AUX")
	)
	(via
		(at 274.832572 -73.5076)
		(size 0.508)
		(drill 0.254)
		(layers "F.Cu" "B.Cu")
		(net "P1V05_PCH_AUX")
	)
	(via
		(at 386.787644 -66.689732)
		(size 0.508)
		(drill 0.254)
		(layers "F.Cu" "B.Cu")
		(net "P1V05_PCH_AUX")
	)
	(via
		(at 335.699608 -51.250596)
		(size 0.4572)
		(drill 0.2032)
		(layers "F.Cu" "B.Cu")
		(net "P1V05_PCH_AUX")
	)
	(via
		(at 226.167188 -84.805266)
		(size 0.508)
		(drill 0.254)
		(layers "F.Cu" "B.Cu")
		(net "P1V05_PCH_AUX")
	)
	(via
		(at 297.9674 -47.488348)
		(size 0.508)
		(drill 0.254)
		(layers "F.Cu" "B.Cu")
		(net "P1V05_PCH_AUX")
	)
	(via
		(at 338.099908 -46.449996)
		(size 0.4572)
		(drill 0.2032)
		(layers "F.Cu" "B.Cu")
		(net "P1V05_PCH_AUX")
	)
	(segment
		(start 421.632888 -46.778672)
		(end 416.693604 -51.717956)
		(width 0.508)
		(layer "B.Cu")
		(net "P1V05_PCH_AUX")
	)
	(segment
		(start 313.99988 -48.097948)
		(end 314.74283 -48.840898)
		(width 0.381)
		(layer "B.Cu")
		(net "P1V05_PCH_AUX")
	)
	(segment
		(start 375.0564 -96.787208)
		(end 377.3424 -99.073208)
		(width 0.508)
		(layer "B.Cu")
		(net "P1V05_PCH_AUX")
	)
	(segment
		(start 408.290522 -49.669954)
		(end 407.077926 -49.669954)
		(width 0.508)
		(layer "B.Cu")
		(net "P1V05_PCH_AUX")
	)
	(segment
		(start 376.17781 -90.19159)
		(end 375.0564 -91.313)
		(width 0.508)
		(layer "B.Cu")
		(net "P1V05_PCH_AUX")
	)
	(segment
		(start 410.338524 -51.717956)
		(end 408.290522 -49.669954)
		(width 0.508)
		(layer "B.Cu")
		(net "P1V05_PCH_AUX")
	)
	(segment
		(start 377.1646 -108.580428)
		(end 377.14047 -108.604558)
		(width 0.508)
		(layer "B.Cu")
		(net "P1V05_PCH_AUX")
	)
	(segment
		(start 278.637492 -71.10984)
		(end 279.5778 -72.050148)
		(width 0.508)
		(layer "B.Cu")
		(net "P1V05_PCH_AUX")
	)
	(segment
		(start 226.167188 -84.805266)
		(end 223.771968 -84.805266)
		(width 0.508)
		(layer "B.Cu")
		(net "P1V05_PCH_AUX")
	)
	(segment
		(start 375.0564 -91.313)
		(end 375.0564 -96.787208)
		(width 0.508)
		(layer "B.Cu")
		(net "P1V05_PCH_AUX")
	)
	(segment
		(start 436.275226 -42.140886)
		(end 433.842414 -42.140886)
		(width 0.508)
		(layer "B.Cu")
		(net "P1V05_PCH_AUX")
	)
	(segment
		(start 195.072 -81.918048)
		(end 191.556894 -81.918048)
		(width 0.508)
		(layer "B.Cu")
		(net "P1V05_PCH_AUX")
	)
	(segment
		(start 337.299808 -51.295808)
		(end 338.00415 -52.00015)
		(width 0.3048)
		(layer "B.Cu")
		(net "P1V05_PCH_AUX")
	)
	(segment
		(start 430.024032 -46.778672)
		(end 421.632888 -46.778672)
		(width 0.508)
		(layer "B.Cu")
		(net "P1V05_PCH_AUX")
	)
	(segment
		(start 417.34232 -61.276484)
		(end 413.161226 -65.457578)
		(width 0.508)
		(layer "B.Cu")
		(net "P1V05_PCH_AUX")
	)
	(segment
		(start 407.077926 -49.669954)
		(end 406.30856 -48.900588)
		(width 0.508)
		(layer "B.Cu")
		(net "P1V05_PCH_AUX")
	)
	(segment
		(start 326.666606 -73.728072)
		(end 326.438006 -73.499472)
		(width 0.381)
		(layer "B.Cu")
		(net "P1V05_PCH_AUX")
	)
	(segment
		(start 394.01242 -50.338228)
		(end 394.01242 -54.153308)
		(width 0.508)
		(layer "B.Cu")
		(net "P1V05_PCH_AUX")
	)
	(segment
		(start 320.178176 -57.898538)
		(end 320.860166 -57.898538)
		(width 0.381)
		(layer "B.Cu")
		(net "P1V05_PCH_AUX")
	)
	(segment
		(start 337.299808 -51.250596)
		(end 337.299808 -51.295808)
		(width 0.3048)
		(layer "B.Cu")
		(net "P1V05_PCH_AUX")
	)
	(segment
		(start 312.178192 -40.208708)
		(end 312.178192 -39.794688)
		(width 0.381)
		(layer "B.Cu")
		(net "P1V05_PCH_AUX")
	)
	(segment
		(start 313.560968 -33.010348)
		(end 312.843672 -33.010348)
		(width 0.381)
		(layer "B.Cu")
		(net "P1V05_PCH_AUX")
	)
	(segment
		(start 196.2023 -80.787748)
		(end 195.072 -81.918048)
		(width 0.508)
		(layer "B.Cu")
		(net "P1V05_PCH_AUX")
	)
	(segment
		(start 395.45006 -48.900588)
		(end 394.01242 -50.338228)
		(width 0.508)
		(layer "B.Cu")
		(net "P1V05_PCH_AUX")
	)
	(segment
		(start 432.538124 -44.26458)
		(end 430.024032 -46.778672)
		(width 0.508)
		(layer "B.Cu")
		(net "P1V05_PCH_AUX")
	)
	(segment
		(start 220.88475 -81.918048)
		(end 199.8472 -81.918048)
		(width 0.508)
		(layer "B.Cu")
		(net "P1V05_PCH_AUX")
	)
	(segment
		(start 409.598876 -65.457578)
		(end 389.854694 -85.20176)
		(width 0.508)
		(layer "B.Cu")
		(net "P1V05_PCH_AUX")
	)
	(segment
		(start 377.3424 -104.943148)
		(end 376.9106 -105.374948)
		(width 0.508)
		(layer "B.Cu")
		(net "P1V05_PCH_AUX")
	)
	(segment
		(start 314.74283 -48.840898)
		(end 314.74283 -49.113948)
		(width 0.381)
		(layer "B.Cu")
		(net "P1V05_PCH_AUX")
	)
	(segment
		(start 278.662892 -66.818256)
		(end 279.6032 -65.877948)
		(width 0.508)
		(layer "B.Cu")
		(net "P1V05_PCH_AUX")
	)
	(segment
		(start 406.30856 -48.900588)
		(end 395.45006 -48.900588)
		(width 0.508)
		(layer "B.Cu")
		(net "P1V05_PCH_AUX")
	)
	(segment
		(start 389.854694 -88.184482)
		(end 387.847586 -90.19159)
		(width 0.508)
		(layer "B.Cu")
		(net "P1V05_PCH_AUX")
	)
	(segment
		(start 310.61406 -39.878508)
		(end 310.61406 -40.104568)
		(width 0.381)
		(layer "B.Cu")
		(net "P1V05_PCH_AUX")
	)
	(segment
		(start 389.854694 -85.20176)
		(end 389.854694 -88.184482)
		(width 0.508)
		(layer "B.Cu")
		(net "P1V05_PCH_AUX")
	)
	(segment
		(start 387.847586 -90.19159)
		(end 376.17781 -90.19159)
		(width 0.508)
		(layer "B.Cu")
		(net "P1V05_PCH_AUX")
	)
	(segment
		(start 377.3424 -99.073208)
		(end 377.3424 -104.943148)
		(width 0.508)
		(layer "B.Cu")
		(net "P1V05_PCH_AUX")
	)
	(segment
		(start 278.662892 -64.93764)
		(end 279.6032 -65.877948)
		(width 0.508)
		(layer "B.Cu")
		(net "P1V05_PCH_AUX")
	)
	(segment
		(start 377.1646 -106.517948)
		(end 377.1646 -108.580428)
		(width 0.508)
		(layer "B.Cu")
		(net "P1V05_PCH_AUX")
	)
	(segment
		(start 321.204336 -57.554368)
		(end 320.662046 -57.012078)
		(width 0.381)
		(layer "B.Cu")
		(net "P1V05_PCH_AUX")
	)
	(segment
		(start 338.00415 -52.00015)
		(end 338.00415 -52.0446)
		(width 0.3048)
		(layer "B.Cu")
		(net "P1V05_PCH_AUX")
	)
	(segment
		(start 417.34232 -52.366672)
		(end 417.34232 -61.276484)
		(width 0.508)
		(layer "B.Cu")
		(net "P1V05_PCH_AUX")
	)
	(segment
		(start 433.842414 -42.140886)
		(end 432.538124 -43.445176)
		(width 0.508)
		(layer "B.Cu")
		(net "P1V05_PCH_AUX")
	)
	(segment
		(start 376.9106 -106.263948)
		(end 377.1646 -106.517948)
		(width 0.508)
		(layer "B.Cu")
		(net "P1V05_PCH_AUX")
	)
	(segment
		(start 320.662046 -57.012078)
		(end 320.170556 -57.012078)
		(width 0.381)
		(layer "B.Cu")
		(net "P1V05_PCH_AUX")
	)
	(segment
		(start 394.01242 -54.153308)
		(end 394.586714 -54.727602)
		(width 0.508)
		(layer "B.Cu")
		(net "P1V05_PCH_AUX")
	)
	(segment
		(start 394.586714 -56.047894)
		(end 393.827 -56.807608)
		(width 0.508)
		(layer "B.Cu")
		(net "P1V05_PCH_AUX")
	)
	(segment
		(start 310.97474 -40.465248)
		(end 311.921652 -40.465248)
		(width 0.381)
		(layer "B.Cu")
		(net "P1V05_PCH_AUX")
	)
	(segment
		(start 416.693604 -51.717956)
		(end 410.338524 -51.717956)
		(width 0.508)
		(layer "B.Cu")
		(net "P1V05_PCH_AUX")
	)
	(segment
		(start 320.860166 -57.898538)
		(end 321.204336 -57.554368)
		(width 0.381)
		(layer "B.Cu")
		(net "P1V05_PCH_AUX")
	)
	(segment
		(start 386.787644 -66.47053)
		(end 386.787644 -66.689732)
		(width 0.508)
		(layer "B.Cu")
		(net "P1V05_PCH_AUX")
	)
	(segment
		(start 198.7169 -80.787748)
		(end 196.2023 -80.787748)
		(width 0.508)
		(layer "B.Cu")
		(net "P1V05_PCH_AUX")
	)
	(segment
		(start 199.8472 -81.918048)
		(end 198.7169 -80.787748)
		(width 0.508)
		(layer "B.Cu")
		(net "P1V05_PCH_AUX")
	)
	(segment
		(start 279.5778 -72.050148)
		(end 280.518108 -72.990456)
		(width 0.508)
		(layer "B.Cu")
		(net "P1V05_PCH_AUX")
	)
	(segment
		(start 413.161226 -65.457578)
		(end 409.598876 -65.457578)
		(width 0.508)
		(layer "B.Cu")
		(net "P1V05_PCH_AUX")
	)
	(segment
		(start 279.5778 -72.050148)
		(end 280.518108 -71.10984)
		(width 0.508)
		(layer "B.Cu")
		(net "P1V05_PCH_AUX")
	)
	(segment
		(start 311.921652 -40.465248)
		(end 312.178192 -40.208708)
		(width 0.381)
		(layer "B.Cu")
		(net "P1V05_PCH_AUX")
	)
	(segment
		(start 394.586714 -54.727602)
		(end 394.586714 -56.047894)
		(width 0.508)
		(layer "B.Cu")
		(net "P1V05_PCH_AUX")
	)
	(segment
		(start 338.394548 -53.619146)
		(end 338.647278 -53.871876)
		(width 0.4572)
		(layer "B.Cu")
		(net "P1V05_PCH_AUX")
	)
	(segment
		(start 191.556894 -81.918048)
		(end 189.038738 -79.399892)
		(width 0.508)
		(layer "B.Cu")
		(net "P1V05_PCH_AUX")
	)
	(segment
		(start 393.827 -59.431174)
		(end 386.787644 -66.47053)
		(width 0.508)
		(layer "B.Cu")
		(net "P1V05_PCH_AUX")
	)
	(segment
		(start 338.647278 -53.871876)
		(end 339.12048 -53.871876)
		(width 0.4572)
		(layer "B.Cu")
		(net "P1V05_PCH_AUX")
	)
	(segment
		(start 416.693604 -51.717956)
		(end 417.34232 -52.366672)
		(width 0.508)
		(layer "B.Cu")
		(net "P1V05_PCH_AUX")
	)
	(segment
		(start 315.144912 -34.594292)
		(end 313.560968 -33.010348)
		(width 0.381)
		(layer "B.Cu")
		(net "P1V05_PCH_AUX")
	)
	(segment
		(start 279.6032 -65.877948)
		(end 280.543508 -66.818256)
		(width 0.508)
		(layer "B.Cu")
		(net "P1V05_PCH_AUX")
	)
	(segment
		(start 278.637492 -72.990456)
		(end 279.5778 -72.050148)
		(width 0.508)
		(layer "B.Cu")
		(net "P1V05_PCH_AUX")
	)
	(segment
		(start 223.771968 -84.805266)
		(end 220.88475 -81.918048)
		(width 0.508)
		(layer "B.Cu")
		(net "P1V05_PCH_AUX")
	)
	(segment
		(start 432.538124 -43.445176)
		(end 432.538124 -44.26458)
		(width 0.508)
		(layer "B.Cu")
		(net "P1V05_PCH_AUX")
	)
	(segment
		(start 279.6032 -65.877948)
		(end 280.543508 -64.93764)
		(width 0.508)
		(layer "B.Cu")
		(net "P1V05_PCH_AUX")
	)
	(segment
		(start 327.66127 -73.728072)
		(end 326.666606 -73.728072)
		(width 0.381)
		(layer "B.Cu")
		(net "P1V05_PCH_AUX")
	)
	(segment
		(start 310.61406 -40.104568)
		(end 310.97474 -40.465248)
		(width 0.381)
		(layer "B.Cu")
		(net "P1V05_PCH_AUX")
	)
	(segment
		(start 376.9106 -105.374948)
		(end 376.9106 -106.263948)
		(width 0.508)
		(layer "B.Cu")
		(net "P1V05_PCH_AUX")
	)
	(segment
		(start 393.827 -56.807608)
		(end 393.827 -59.431174)
		(width 0.508)
		(layer "B.Cu")
		(net "P1V05_PCH_AUX")
	)
	(segment
		(start 386.018532 -67.350894)
		(end 384.706622 -66.038984)
		(width 0.381)
		(layer "In2.Cu")
		(net "P1V05_PCH_AUX")
	)
	(segment
		(start 384.706622 -66.038984)
		(end 384.706622 -63.423292)
		(width 0.381)
		(layer "In2.Cu")
		(net "P1V05_PCH_AUX")
	)
	(segment
		(start 187.719716 -65.635124)
		(end 187.719716 -75.68565)
		(width 0.508)
		(layer "In4.Cu")
		(net "P1V05_PCH_AUX")
	)
	(segment
		(start 279.6032 -65.877948)
		(end 280.318972 -66.59372)
		(width 0.508)
		(layer "In4.Cu")
		(net "P1V05_PCH_AUX")
	)
	(segment
		(start 278.862028 -72.76592)
		(end 279.5778 -72.050148)
		(width 0.508)
		(layer "In4.Cu")
		(net "P1V05_PCH_AUX")
	)
	(segment
		(start 278.862028 -71.334376)
		(end 279.5778 -72.050148)
		(width 0.508)
		(layer "In4.Cu")
		(net "P1V05_PCH_AUX")
	)
	(segment
		(start 148.886672 -61.313314)
		(end 172.119036 -61.313314)
		(width 0.508)
		(layer "In4.Cu")
		(net "P1V05_PCH_AUX")
	)
	(segment
		(start 173.900338 -59.532012)
		(end 181.616604 -59.532012)
		(width 0.508)
		(layer "In4.Cu")
		(net "P1V05_PCH_AUX")
	)
	(segment
		(start 279.6032 -65.877948)
		(end 280.318972 -65.162176)
		(width 0.508)
		(layer "In4.Cu")
		(net "P1V05_PCH_AUX")
	)
	(segment
		(start 172.119036 -61.313314)
		(end 173.900338 -59.532012)
		(width 0.508)
		(layer "In4.Cu")
		(net "P1V05_PCH_AUX")
	)
	(segment
		(start 278.887428 -66.59372)
		(end 279.6032 -65.877948)
		(width 0.508)
		(layer "In4.Cu")
		(net "P1V05_PCH_AUX")
	)
	(segment
		(start 279.5778 -72.050148)
		(end 280.293572 -72.76592)
		(width 0.508)
		(layer "In4.Cu")
		(net "P1V05_PCH_AUX")
	)
	(segment
		(start 189.038738 -77.004672)
		(end 189.038738 -79.399892)
		(width 0.508)
		(layer "In4.Cu")
		(net "P1V05_PCH_AUX")
	)
	(segment
		(start 147.76577 -60.192412)
		(end 148.886672 -61.313314)
		(width 0.508)
		(layer "In4.Cu")
		(net "P1V05_PCH_AUX")
	)
	(segment
		(start 279.5778 -72.050148)
		(end 280.293572 -71.334376)
		(width 0.508)
		(layer "In4.Cu")
		(net "P1V05_PCH_AUX")
	)
	(segment
		(start 187.719716 -75.68565)
		(end 189.038738 -77.004672)
		(width 0.508)
		(layer "In4.Cu")
		(net "P1V05_PCH_AUX")
	)
	(segment
		(start 181.616604 -59.532012)
		(end 187.719716 -65.635124)
		(width 0.508)
		(layer "In4.Cu")
		(net "P1V05_PCH_AUX")
	)
	(segment
		(start 278.887428 -65.162176)
		(end 279.6032 -65.877948)
		(width 0.508)
		(layer "In4.Cu")
		(net "P1V05_PCH_AUX")
	)
	(segment
		(start 314.320174 -40.508174)
		(end 310.911494 -40.508174)
		(width 0.381)
		(layer "In6.Cu")
		(net "P1V05_PCH_AUX")
	)
	(segment
		(start 124.841 -57.597548)
		(end 124.1044 -58.334148)
		(width 0.508)
		(layer "In6.Cu")
		(net "P1V05_PCH_AUX")
	)
	(segment
		(start 143.358362 -60.192412)
		(end 140.763498 -57.597548)
		(width 0.508)
		(layer "In6.Cu")
		(net "P1V05_PCH_AUX")
	)
	(segment
		(start 315.144912 -34.594292)
		(end 315.9887 -35.43808)
		(width 0.381)
		(layer "In6.Cu")
		(net "P1V05_PCH_AUX")
	)
	(segment
		(start 315.9887 -35.43808)
		(end 315.9887 -38.839648)
		(width 0.381)
		(layer "In6.Cu")
		(net "P1V05_PCH_AUX")
	)
	(segment
		(start 315.9887 -38.839648)
		(end 314.320174 -40.508174)
		(width 0.381)
		(layer "In6.Cu")
		(net "P1V05_PCH_AUX")
	)
	(segment
		(start 310.911494 -40.508174)
		(end 310.61406 -40.21074)
		(width 0.381)
		(layer "In6.Cu")
		(net "P1V05_PCH_AUX")
	)
	(segment
		(start 109.301788 -57.196736)
		(end 97.36836 -57.196736)
		(width 0.508)
		(layer "In6.Cu")
		(net "P1V05_PCH_AUX")
	)
	(segment
		(start 95.254064 -57.995058)
		(end 94.373954 -57.114948)
		(width 0.508)
		(layer "In6.Cu")
		(net "P1V05_PCH_AUX")
	)
	(segment
		(start 97.36836 -57.196736)
		(end 96.570038 -57.995058)
		(width 0.508)
		(layer "In6.Cu")
		(net "P1V05_PCH_AUX")
	)
	(segment
		(start 140.763498 -57.597548)
		(end 124.841 -57.597548)
		(width 0.508)
		(layer "In6.Cu")
		(net "P1V05_PCH_AUX")
	)
	(segment
		(start 377.941332 -45.54728)
		(end 371.348 -38.953948)
		(width 0.254)
		(layer "In6.Cu")
		(net "P1V05_PCH_AUX")
	)
	(segment
		(start 96.570038 -57.995058)
		(end 95.254064 -57.995058)
		(width 0.508)
		(layer "In6.Cu")
		(net "P1V05_PCH_AUX")
	)
	(segment
		(start 110.4392 -58.334148)
		(end 109.301788 -57.196736)
		(width 0.508)
		(layer "In6.Cu")
		(net "P1V05_PCH_AUX")
	)
	(segment
		(start 310.61406 -40.21074)
		(end 310.61406 -39.878508)
		(width 0.381)
		(layer "In6.Cu")
		(net "P1V05_PCH_AUX")
	)
	(segment
		(start 377.941332 -59.959748)
		(end 377.941332 -45.54728)
		(width 0.254)
		(layer "In6.Cu")
		(net "P1V05_PCH_AUX")
	)
	(segment
		(start 147.76577 -60.192412)
		(end 143.358362 -60.192412)
		(width 0.508)
		(layer "In6.Cu")
		(net "P1V05_PCH_AUX")
	)
	(segment
		(start 124.1044 -58.334148)
		(end 110.4392 -58.334148)
		(width 0.508)
		(layer "In6.Cu")
		(net "P1V05_PCH_AUX")
	)
	(segment
		(start 333.975964 -57.218834)
		(end 331.00899 -60.185808)
		(width 0.254)
		(layer "In13.Cu")
		(net "P1V05_PCH_AUX")
	)
	(segment
		(start 328.259948 -73.977754)
		(end 327.910952 -73.977754)
		(width 0.254)
		(layer "In13.Cu")
		(net "P1V05_PCH_AUX")
	)
	(segment
		(start 333.975964 -55.205884)
		(end 333.975964 -57.218834)
		(width 0.254)
		(layer "In13.Cu")
		(net "P1V05_PCH_AUX")
	)
	(segment
		(start 329.708764 -62.396878)
		(end 329.708764 -65.732406)
		(width 0.254)
		(layer "In13.Cu")
		(net "P1V05_PCH_AUX")
	)
	(segment
		(start 331.00899 -60.185808)
		(end 331.00899 -61.096652)
		(width 0.254)
		(layer "In13.Cu")
		(net "P1V05_PCH_AUX")
	)
	(segment
		(start 335.092802 -54.089046)
		(end 333.975964 -55.205884)
		(width 0.254)
		(layer "In13.Cu")
		(net "P1V05_PCH_AUX")
	)
	(segment
		(start 329.274678 -66.166492)
		(end 329.274678 -72.963024)
		(width 0.254)
		(layer "In13.Cu")
		(net "P1V05_PCH_AUX")
	)
	(segment
		(start 336.22996 -54.089046)
		(end 335.092802 -54.089046)
		(width 0.254)
		(layer "In13.Cu")
		(net "P1V05_PCH_AUX")
	)
	(segment
		(start 331.00899 -61.096652)
		(end 329.708764 -62.396878)
		(width 0.254)
		(layer "In13.Cu")
		(net "P1V05_PCH_AUX")
	)
	(segment
		(start 329.274678 -72.963024)
		(end 328.259948 -73.977754)
		(width 0.254)
		(layer "In13.Cu")
		(net "P1V05_PCH_AUX")
	)
	(segment
		(start 329.708764 -65.732406)
		(end 329.274678 -66.166492)
		(width 0.254)
		(layer "In13.Cu")
		(net "P1V05_PCH_AUX")
	)
	(segment
		(start 327.910952 -73.977754)
		(end 327.66127 -73.728072)
		(width 0.254)
		(layer "In13.Cu")
		(net "P1V05_PCH_AUX")
	)
	(segment
		(start 337.581748 -54.089046)
		(end 336.22996 -54.089046)
		(width 0.2032)
		(layer "In13.Cu")
		(net "P1V05_PCH_AUX")
	)
	(segment
		(start 377.941332 -59.959748)
		(end 377.268994 -59.28741)
		(width 0.4572)
		(layer "In15.Cu")
		(net "P1V05_PCH_AUX")
	)
	(segment
		(start 377.268994 -59.28741)
		(end 377.268994 -57.42305)
		(width 0.4572)
		(layer "In15.Cu")
		(net "P1V05_PCH_AUX")
	)
	(segment
		(start 367.01476 -53.532278)
		(end 366.378236 -53.532278)
		(width 0.4572)
		(layer "In15.Cu")
		(net "P1V05_PCH_AUX")
	)
	(segment
		(start 369.152932 -55.67045)
		(end 367.01476 -53.532278)
		(width 0.4572)
		(layer "In15.Cu")
		(net "P1V05_PCH_AUX")
	)
	(segment
		(start 377.268994 -57.42305)
		(end 375.516394 -55.67045)
		(width 0.4572)
		(layer "In15.Cu")
		(net "P1V05_PCH_AUX")
	)
	(segment
		(start 375.516394 -55.67045)
		(end 369.152932 -55.67045)
		(width 0.4572)
		(layer "In15.Cu")
		(net "P1V05_PCH_AUX")
	)
	(via
		(at 191.67348 -13.106908)
		(size 0.508)
		(drill 0.254)
		(layers "F.Cu" "B.Cu")
		(net "P12V_SCM")
	)
	(via
		(at 200.69048 -34.394648)
		(size 0.6604)
		(drill 0.3302)
		(layers "F.Cu" "B.Cu")
		(net "P12V_SCM")
	)
	(via
		(at 192.68948 -13.106908)
		(size 0.508)
		(drill 0.254)
		(layers "F.Cu" "B.Cu")
		(net "P12V_SCM")
	)
	(via
		(at 191.9478 -15.225268)
		(size 0.508)
		(drill 0.254)
		(layers "F.Cu" "B.Cu")
		(net "P12V_SCM")
	)
	(via
		(at 192.5828 -15.225268)
		(size 0.508)
		(drill 0.254)
		(layers "F.Cu" "B.Cu")
		(net "P12V_SCM")
	)
	(via
		(at 198.18604 -31.6484)
		(size 0.762)
		(drill 0.381)
		(layers "F.Cu" "B.Cu")
		(net "P12V_SCM")
	)
	(via
		(at 192.5828 -15.860268)
		(size 0.508)
		(drill 0.254)
		(layers "F.Cu" "B.Cu")
		(net "P12V_SCM")
	)
	(via
		(at 198.48576 -30.133798)
		(size 0.508)
		(drill 0.254)
		(layers "F.Cu" "B.Cu")
		(net "P12V_SCM")
	)
	(via
		(at 199.43572 -30.720538)
		(size 0.508)
		(drill 0.254)
		(layers "F.Cu" "B.Cu")
		(net "P12V_SCM")
	)
	(via
		(at 200.39076 -30.133798)
		(size 0.508)
		(drill 0.254)
		(layers "F.Cu" "B.Cu")
		(net "P12V_SCM")
	)
	(via
		(at 199.12076 -30.133798)
		(size 0.508)
		(drill 0.254)
		(layers "F.Cu" "B.Cu")
		(net "P12V_SCM")
	)
	(via
		(at 200.70572 -30.720538)
		(size 0.508)
		(drill 0.254)
		(layers "F.Cu" "B.Cu")
		(net "P12V_SCM")
	)
	(via
		(at 200.07072 -30.720538)
		(size 0.508)
		(drill 0.254)
		(layers "F.Cu" "B.Cu")
		(net "P12V_SCM")
	)
	(via
		(at 193.2178 -15.225268)
		(size 0.508)
		(drill 0.254)
		(layers "F.Cu" "B.Cu")
		(net "P12V_SCM")
	)
	(via
		(at 198.16572 -33.89884)
		(size 0.762)
		(drill 0.381)
		(layers "F.Cu" "B.Cu")
		(net "P12V_SCM")
	)
	(via
		(at 199.75576 -30.133798)
		(size 0.508)
		(drill 0.254)
		(layers "F.Cu" "B.Cu")
		(net "P12V_SCM")
	)
	(via
		(at 201.34072 -30.720538)
		(size 0.508)
		(drill 0.254)
		(layers "F.Cu" "B.Cu")
		(net "P12V_SCM")
	)
	(via
		(at 191.9478 -15.860268)
		(size 0.508)
		(drill 0.254)
		(layers "F.Cu" "B.Cu")
		(net "P12V_SCM")
	)
	(via
		(at 193.2178 -15.860268)
		(size 0.508)
		(drill 0.254)
		(layers "F.Cu" "B.Cu")
		(net "P12V_SCM")
	)
	(segment
		(start 201.56678 -30.946598)
		(end 201.56678 -33.518348)
		(width 0.381)
		(layer "B.Cu")
		(net "P12V_SCM")
	)
	(segment
		(start 200.69048 -35.067748)
		(end 200.99528 -35.372548)
		(width 0.381)
		(layer "B.Cu")
		(net "P12V_SCM")
	)
	(segment
		(start 200.99528 -35.372548)
		(end 202.93203 -35.372548)
		(width 0.381)
		(layer "B.Cu")
		(net "P12V_SCM")
	)
	(segment
		(start 200.69048 -34.394648)
		(end 200.69048 -35.067748)
		(width 0.381)
		(layer "B.Cu")
		(net "P12V_SCM")
	)
	(segment
		(start 201.34072 -30.720538)
		(end 201.56678 -30.946598)
		(width 0.381)
		(layer "B.Cu")
		(net "P12V_SCM")
	)
	(segment
		(start 201.56678 -33.518348)
		(end 200.69048 -34.394648)
		(width 0.381)
		(layer "B.Cu")
		(net "P12V_SCM")
	)
	(via
		(at 201.94143 -327.797668)
		(size 0.508)
		(drill 0.254)
		(layers "F.Cu" "B.Cu")
		(net "P12V_S3_AUX_CPU1_NVDIMM")
	)
	(via
		(at 18.41119 -331.254608)
		(size 0.508)
		(drill 0.254)
		(layers "F.Cu" "B.Cu")
		(net "P12V_S3_AUX_CPU1_NVDIMM")
	)
	(via
		(at 25.26919 -331.254608)
		(size 0.508)
		(drill 0.254)
		(layers "F.Cu" "B.Cu")
		(net "P12V_S3_AUX_CPU1_NVDIMM")
	)
	(via
		(at 193.63563 -326.273668)
		(size 0.508)
		(drill 0.254)
		(layers "F.Cu" "B.Cu")
		(net "P12V_S3_AUX_CPU1_NVDIMM")
	)
	(via
		(at 18.41119 -332.016608)
		(size 0.508)
		(drill 0.254)
		(layers "F.Cu" "B.Cu")
		(net "P12V_S3_AUX_CPU1_NVDIMM")
	)
	(via
		(at 26.79065 -331.272388)
		(size 0.508)
		(drill 0.254)
		(layers "F.Cu" "B.Cu")
		(net "P12V_S3_AUX_CPU1_NVDIMM")
	)
	(via
		(at 195.427346 -321.41668)
		(size 0.4572)
		(drill 0.2032)
		(layers "F.Cu" "B.Cu")
		(net "P12V_S3_AUX_CPU1_NVDIMM")
	)
	(via
		(at 194.36207 -328.491088)
		(size 0.508)
		(drill 0.254)
		(layers "F.Cu" "B.Cu")
		(net "P12V_S3_AUX_CPU1_NVDIMM")
	)
	(via
		(at 169.328084 -321.173856)
		(size 0.4572)
		(drill 0.2032)
		(layers "F.Cu" "B.Cu")
		(net "P12V_S3_AUX_CPU1_NVDIMM")
	)
	(via
		(at 19.93519 -331.254608)
		(size 0.508)
		(drill 0.254)
		(layers "F.Cu" "B.Cu")
		(net "P12V_S3_AUX_CPU1_NVDIMM")
	)
	(via
		(at 19.17319 -332.778608)
		(size 0.508)
		(drill 0.254)
		(layers "F.Cu" "B.Cu")
		(net "P12V_S3_AUX_CPU1_NVDIMM")
	)
	(via
		(at 197.61327 -328.699368)
		(size 0.508)
		(drill 0.254)
		(layers "F.Cu" "B.Cu")
		(net "P12V_S3_AUX_CPU1_NVDIMM")
	)
	(via
		(at 33.767014 -321.41668)
		(size 0.4572)
		(drill 0.2032)
		(layers "F.Cu" "B.Cu")
		(net "P12V_S3_AUX_CPU1_NVDIMM")
	)
	(via
		(at 17.64919 -332.778608)
		(size 0.508)
		(drill 0.254)
		(layers "F.Cu" "B.Cu")
		(net "P12V_S3_AUX_CPU1_NVDIMM")
	)
	(via
		(at 164.995098 -321.758564)
		(size 0.4572)
		(drill 0.2032)
		(layers "F.Cu" "B.Cu")
		(net "P12V_S3_AUX_CPU1_NVDIMM")
	)
	(via
		(at 202.70089 -326.291448)
		(size 0.508)
		(drill 0.254)
		(layers "F.Cu" "B.Cu")
		(net "P12V_S3_AUX_CPU1_NVDIMM")
	)
	(via
		(at 184.439814 -320.566796)
		(size 0.4572)
		(drill 0.2032)
		(layers "F.Cu" "B.Cu")
		(net "P12V_S3_AUX_CPU1_NVDIMM")
	)
	(via
		(at 25.26919 -332.778608)
		(size 0.508)
		(drill 0.254)
		(layers "F.Cu" "B.Cu")
		(net "P12V_S3_AUX_CPU1_NVDIMM")
	)
	(via
		(at 17.64919 -332.016608)
		(size 0.508)
		(drill 0.254)
		(layers "F.Cu" "B.Cu")
		(net "P12V_S3_AUX_CPU1_NVDIMM")
	)
	(via
		(at 17.64919 -331.254608)
		(size 0.508)
		(drill 0.254)
		(layers "F.Cu" "B.Cu")
		(net "P12V_S3_AUX_CPU1_NVDIMM")
	)
	(via
		(at 23.74519 -332.016608)
		(size 0.508)
		(drill 0.254)
		(layers "F.Cu" "B.Cu")
		(net "P12V_S3_AUX_CPU1_NVDIMM")
	)
	(via
		(at 193.63563 -327.035668)
		(size 0.508)
		(drill 0.254)
		(layers "F.Cu" "B.Cu")
		(net "P12V_S3_AUX_CPU1_NVDIMM")
	)
	(via
		(at 33.767014 -320.566796)
		(size 0.4572)
		(drill 0.2032)
		(layers "F.Cu" "B.Cu")
		(net "P12V_S3_AUX_CPU1_NVDIMM")
	)
	(via
		(at 20.69719 -331.254608)
		(size 0.508)
		(drill 0.254)
		(layers "F.Cu" "B.Cu")
		(net "P12V_S3_AUX_CPU1_NVDIMM")
	)
	(via
		(at 207.071214 -321.41668)
		(size 0.4572)
		(drill 0.2032)
		(layers "F.Cu" "B.Cu")
		(net "P12V_S3_AUX_CPU1_NVDIMM")
	)
	(via
		(at 26.79065 -332.796388)
		(size 0.508)
		(drill 0.254)
		(layers "F.Cu" "B.Cu")
		(net "P12V_S3_AUX_CPU1_NVDIMM")
	)
	(via
		(at 161.766758 -320.35369)
		(size 0.4572)
		(drill 0.2032)
		(layers "F.Cu" "B.Cu")
		(net "P12V_S3_AUX_CPU1_NVDIMM")
	)
	(via
		(at 26.79065 -334.193388)
		(size 0.508)
		(drill 0.254)
		(layers "F.Cu" "B.Cu")
		(net "P12V_S3_AUX_CPU1_NVDIMM")
	)
	(via
		(at 19.17319 -334.302608)
		(size 0.508)
		(drill 0.254)
		(layers "F.Cu" "B.Cu")
		(net "P12V_S3_AUX_CPU1_NVDIMM")
	)
	(via
		(at 194.39763 -326.273668)
		(size 0.508)
		(drill 0.254)
		(layers "F.Cu" "B.Cu")
		(net "P12V_S3_AUX_CPU1_NVDIMM")
	)
	(via
		(at 59.81192 -321.413124)
		(size 0.4572)
		(drill 0.2032)
		(layers "F.Cu" "B.Cu")
		(net "P12V_S3_AUX_CPU1_NVDIMM")
	)
	(via
		(at 172.731684 -321.300856)
		(size 0.4572)
		(drill 0.2032)
		(layers "F.Cu" "B.Cu")
		(net "P12V_S3_AUX_CPU1_NVDIMM")
	)
	(via
		(at 27.55011 -332.052168)
		(size 0.508)
		(drill 0.254)
		(layers "F.Cu" "B.Cu")
		(net "P12V_S3_AUX_CPU1_NVDIMM")
	)
	(via
		(at 63.399162 -321.615816)
		(size 0.4572)
		(drill 0.2032)
		(layers "F.Cu" "B.Cu")
		(net "P12V_S3_AUX_CPU1_NVDIMM")
	)
	(via
		(at 22.98319 -331.254608)
		(size 0.508)
		(drill 0.254)
		(layers "F.Cu" "B.Cu")
		(net "P12V_S3_AUX_CPU1_NVDIMM")
	)
	(via
		(at 19.17319 -333.540608)
		(size 0.508)
		(drill 0.254)
		(layers "F.Cu" "B.Cu")
		(net "P12V_S3_AUX_CPU1_NVDIMM")
	)
	(via
		(at 56.398414 -320.566796)
		(size 0.4572)
		(drill 0.2032)
		(layers "F.Cu" "B.Cu")
		(net "P12V_S3_AUX_CPU1_NVDIMM")
	)
	(via
		(at 48.854614 -321.41668)
		(size 0.4572)
		(drill 0.2032)
		(layers "F.Cu" "B.Cu")
		(net "P12V_S3_AUX_CPU1_NVDIMM")
	)
	(via
		(at 18.679414 -320.566796)
		(size 0.4572)
		(drill 0.2032)
		(layers "F.Cu" "B.Cu")
		(net "P12V_S3_AUX_CPU1_NVDIMM")
	)
	(via
		(at 195.15709 -326.291448)
		(size 0.508)
		(drill 0.254)
		(layers "F.Cu" "B.Cu")
		(net "P12V_S3_AUX_CPU1_NVDIMM")
	)
	(via
		(at 191.983614 -320.566796)
		(size 0.4572)
		(drill 0.2032)
		(layers "F.Cu" "B.Cu")
		(net "P12V_S3_AUX_CPU1_NVDIMM")
	)
	(via
		(at 194.39763 -327.035668)
		(size 0.508)
		(drill 0.254)
		(layers "F.Cu" "B.Cu")
		(net "P12V_S3_AUX_CPU1_NVDIMM")
	)
	(via
		(at 26.03119 -332.778608)
		(size 0.508)
		(drill 0.254)
		(layers "F.Cu" "B.Cu")
		(net "P12V_S3_AUX_CPU1_NVDIMM")
	)
	(via
		(at 27.55011 -334.211168)
		(size 0.508)
		(drill 0.254)
		(layers "F.Cu" "B.Cu")
		(net "P12V_S3_AUX_CPU1_NVDIMM")
	)
	(via
		(at 202.971146 -321.41668)
		(size 0.4572)
		(drill 0.2032)
		(layers "F.Cu" "B.Cu")
		(net "P12V_S3_AUX_CPU1_NVDIMM")
	)
	(via
		(at 23.74519 -331.254608)
		(size 0.508)
		(drill 0.254)
		(layers "F.Cu" "B.Cu")
		(net "P12V_S3_AUX_CPU1_NVDIMM")
	)
	(via
		(at 201.14387 -328.491088)
		(size 0.508)
		(drill 0.254)
		(layers "F.Cu" "B.Cu")
		(net "P12V_S3_AUX_CPU1_NVDIMM")
	)
	(via
		(at 195.15709 -327.815448)
		(size 0.508)
		(drill 0.254)
		(layers "F.Cu" "B.Cu")
		(net "P12V_S3_AUX_CPU1_NVDIMM")
	)
	(via
		(at 11.135614 -321.41668)
		(size 0.4572)
		(drill 0.2032)
		(layers "F.Cu" "B.Cu")
		(net "P12V_S3_AUX_CPU1_NVDIMM")
	)
	(via
		(at 160.34258 -321.295268)
		(size 0.4572)
		(drill 0.2032)
		(layers "F.Cu" "B.Cu")
		(net "P12V_S3_AUX_CPU1_NVDIMM")
	)
	(via
		(at 27.55011 -332.814168)
		(size 0.508)
		(drill 0.254)
		(layers "F.Cu" "B.Cu")
		(net "P12V_S3_AUX_CPU1_NVDIMM")
	)
	(via
		(at 195.15709 -327.053448)
		(size 0.508)
		(drill 0.254)
		(layers "F.Cu" "B.Cu")
		(net "P12V_S3_AUX_CPU1_NVDIMM")
	)
	(via
		(at 24.50719 -334.810608)
		(size 0.508)
		(drill 0.254)
		(layers "F.Cu" "B.Cu")
		(net "P12V_S3_AUX_CPU1_NVDIMM")
	)
	(via
		(at 202.70089 -327.815448)
		(size 0.508)
		(drill 0.254)
		(layers "F.Cu" "B.Cu")
		(net "P12V_S3_AUX_CPU1_NVDIMM")
	)
	(via
		(at 26.79065 -334.828388)
		(size 0.508)
		(drill 0.254)
		(layers "F.Cu" "B.Cu")
		(net "P12V_S3_AUX_CPU1_NVDIMM")
	)
	(via
		(at 30.207458 -332.40599)
		(size 0.6604)
		(drill 0.3302)
		(layers "F.Cu" "B.Cu")
		(net "P12V_S3_AUX_CPU1_NVDIMM")
	)
	(via
		(at 21.45919 -331.254608)
		(size 0.508)
		(drill 0.254)
		(layers "F.Cu" "B.Cu")
		(net "P12V_S3_AUX_CPU1_NVDIMM")
	)
	(via
		(at 27.55011 -333.576168)
		(size 0.508)
		(drill 0.254)
		(layers "F.Cu" "B.Cu")
		(net "P12V_S3_AUX_CPU1_NVDIMM")
	)
	(via
		(at 25.26919 -332.016608)
		(size 0.508)
		(drill 0.254)
		(layers "F.Cu" "B.Cu")
		(net "P12V_S3_AUX_CPU1_NVDIMM")
	)
	(via
		(at 7.035546 -321.41668)
		(size 0.4572)
		(drill 0.2032)
		(layers "F.Cu" "B.Cu")
		(net "P12V_S3_AUX_CPU1_NVDIMM")
	)
	(via
		(at 24.50719 -331.254608)
		(size 0.508)
		(drill 0.254)
		(layers "F.Cu" "B.Cu")
		(net "P12V_S3_AUX_CPU1_NVDIMM")
	)
	(via
		(at 56.398414 -321.41668)
		(size 0.4572)
		(drill 0.2032)
		(layers "F.Cu" "B.Cu")
		(net "P12V_S3_AUX_CPU1_NVDIMM")
	)
	(via
		(at 25.26919 -334.175608)
		(size 0.508)
		(drill 0.254)
		(layers "F.Cu" "B.Cu")
		(net "P12V_S3_AUX_CPU1_NVDIMM")
	)
	(via
		(at 195.12153 -328.508868)
		(size 0.508)
		(drill 0.254)
		(layers "F.Cu" "B.Cu")
		(net "P12V_S3_AUX_CPU1_NVDIMM")
	)
	(via
		(at 26.223214 -321.41668)
		(size 0.4572)
		(drill 0.2032)
		(layers "F.Cu" "B.Cu")
		(net "P12V_S3_AUX_CPU1_NVDIMM")
	)
	(via
		(at 63.931546 -321.374516)
		(size 0.4572)
		(drill 0.2032)
		(layers "F.Cu" "B.Cu")
		(net "P12V_S3_AUX_CPU1_NVDIMM")
	)
	(via
		(at 26.03119 -334.810608)
		(size 0.508)
		(drill 0.254)
		(layers "F.Cu" "B.Cu")
		(net "P12V_S3_AUX_CPU1_NVDIMM")
	)
	(via
		(at 25.26919 -333.540608)
		(size 0.508)
		(drill 0.254)
		(layers "F.Cu" "B.Cu")
		(net "P12V_S3_AUX_CPU1_NVDIMM")
	)
	(via
		(at 201.17943 -327.797668)
		(size 0.508)
		(drill 0.254)
		(layers "F.Cu" "B.Cu")
		(net "P12V_S3_AUX_CPU1_NVDIMM")
	)
	(via
		(at 23.74519 -334.810608)
		(size 0.508)
		(drill 0.254)
		(layers "F.Cu" "B.Cu")
		(net "P12V_S3_AUX_CPU1_NVDIMM")
	)
	(via
		(at 193.60007 -328.491088)
		(size 0.508)
		(drill 0.254)
		(layers "F.Cu" "B.Cu")
		(net "P12V_S3_AUX_CPU1_NVDIMM")
	)
	(via
		(at 19.17319 -331.254608)
		(size 0.508)
		(drill 0.254)
		(layers "F.Cu" "B.Cu")
		(net "P12V_S3_AUX_CPU1_NVDIMM")
	)
	(via
		(at 18.41119 -333.540608)
		(size 0.508)
		(drill 0.254)
		(layers "F.Cu" "B.Cu")
		(net "P12V_S3_AUX_CPU1_NVDIMM")
	)
	(via
		(at 41.310814 -320.566796)
		(size 0.4572)
		(drill 0.2032)
		(layers "F.Cu" "B.Cu")
		(net "P12V_S3_AUX_CPU1_NVDIMM")
	)
	(via
		(at 201.17943 -327.035668)
		(size 0.508)
		(drill 0.254)
		(layers "F.Cu" "B.Cu")
		(net "P12V_S3_AUX_CPU1_NVDIMM")
	)
	(via
		(at 25.26919 -334.810608)
		(size 0.508)
		(drill 0.254)
		(layers "F.Cu" "B.Cu")
		(net "P12V_S3_AUX_CPU1_NVDIMM")
	)
	(via
		(at 23.74519 -333.540608)
		(size 0.508)
		(drill 0.254)
		(layers "F.Cu" "B.Cu")
		(net "P12V_S3_AUX_CPU1_NVDIMM")
	)
	(via
		(at 169.352214 -320.566796)
		(size 0.4572)
		(drill 0.2032)
		(layers "F.Cu" "B.Cu")
		(net "P12V_S3_AUX_CPU1_NVDIMM")
	)
	(via
		(at 48.854614 -320.566796)
		(size 0.4572)
		(drill 0.2032)
		(layers "F.Cu" "B.Cu")
		(net "P12V_S3_AUX_CPU1_NVDIMM")
	)
	(via
		(at 18.41119 -332.778608)
		(size 0.508)
		(drill 0.254)
		(layers "F.Cu" "B.Cu")
		(net "P12V_S3_AUX_CPU1_NVDIMM")
	)
	(via
		(at 201.94143 -327.035668)
		(size 0.508)
		(drill 0.254)
		(layers "F.Cu" "B.Cu")
		(net "P12V_S3_AUX_CPU1_NVDIMM")
	)
	(via
		(at 26.03119 -333.540608)
		(size 0.508)
		(drill 0.254)
		(layers "F.Cu" "B.Cu")
		(net "P12V_S3_AUX_CPU1_NVDIMM")
	)
	(via
		(at 30.156658 -334.44053)
		(size 0.6604)
		(drill 0.3302)
		(layers "F.Cu" "B.Cu")
		(net "P12V_S3_AUX_CPU1_NVDIMM")
	)
	(via
		(at 210.514946 -321.41668)
		(size 0.4572)
		(drill 0.2032)
		(layers "F.Cu" "B.Cu")
		(net "P12V_S3_AUX_CPU1_NVDIMM")
	)
	(via
		(at 27.55011 -334.846168)
		(size 0.508)
		(drill 0.254)
		(layers "F.Cu" "B.Cu")
		(net "P12V_S3_AUX_CPU1_NVDIMM")
	)
	(via
		(at 19.17319 -332.016608)
		(size 0.508)
		(drill 0.254)
		(layers "F.Cu" "B.Cu")
		(net "P12V_S3_AUX_CPU1_NVDIMM")
	)
	(via
		(at 176.795684 -320.996056)
		(size 0.4572)
		(drill 0.2032)
		(layers "F.Cu" "B.Cu")
		(net "P12V_S3_AUX_CPU1_NVDIMM")
	)
	(via
		(at 190.989458 -330.52639)
		(size 0.6604)
		(drill 0.3302)
		(layers "F.Cu" "B.Cu")
		(net "P12V_S3_AUX_CPU1_NVDIMM")
	)
	(via
		(at 26.03119 -331.254608)
		(size 0.508)
		(drill 0.254)
		(layers "F.Cu" "B.Cu")
		(net "P12V_S3_AUX_CPU1_NVDIMM")
	)
	(via
		(at 202.66533 -328.508868)
		(size 0.508)
		(drill 0.254)
		(layers "F.Cu" "B.Cu")
		(net "P12V_S3_AUX_CPU1_NVDIMM")
	)
	(via
		(at 187.883038 -321.41668)
		(size 0.4572)
		(drill 0.2032)
		(layers "F.Cu" "B.Cu")
		(net "P12V_S3_AUX_CPU1_NVDIMM")
	)
	(via
		(at 199.527414 -320.566796)
		(size 0.4572)
		(drill 0.2032)
		(layers "F.Cu" "B.Cu")
		(net "P12V_S3_AUX_CPU1_NVDIMM")
	)
	(via
		(at 27.55011 -331.290168)
		(size 0.508)
		(drill 0.254)
		(layers "F.Cu" "B.Cu")
		(net "P12V_S3_AUX_CPU1_NVDIMM")
	)
	(via
		(at 37.210746 -321.41668)
		(size 0.4572)
		(drill 0.2032)
		(layers "F.Cu" "B.Cu")
		(net "P12V_S3_AUX_CPU1_NVDIMM")
	)
	(via
		(at 18.679414 -321.41668)
		(size 0.4572)
		(drill 0.2032)
		(layers "F.Cu" "B.Cu")
		(net "P12V_S3_AUX_CPU1_NVDIMM")
	)
	(via
		(at 180.334158 -321.30619)
		(size 0.4572)
		(drill 0.2032)
		(layers "F.Cu" "B.Cu")
		(net "P12V_S3_AUX_CPU1_NVDIMM")
	)
	(via
		(at 11.135614 -320.566796)
		(size 0.4572)
		(drill 0.2032)
		(layers "F.Cu" "B.Cu")
		(net "P12V_S3_AUX_CPU1_NVDIMM")
	)
	(via
		(at 201.94143 -326.273668)
		(size 0.508)
		(drill 0.254)
		(layers "F.Cu" "B.Cu")
		(net "P12V_S3_AUX_CPU1_NVDIMM")
	)
	(via
		(at 26.03119 -334.175608)
		(size 0.508)
		(drill 0.254)
		(layers "F.Cu" "B.Cu")
		(net "P12V_S3_AUX_CPU1_NVDIMM")
	)
	(via
		(at 22.123146 -321.41668)
		(size 0.4572)
		(drill 0.2032)
		(layers "F.Cu" "B.Cu")
		(net "P12V_S3_AUX_CPU1_NVDIMM")
	)
	(via
		(at 214.615014 -321.41668)
		(size 0.4572)
		(drill 0.2032)
		(layers "F.Cu" "B.Cu")
		(net "P12V_S3_AUX_CPU1_NVDIMM")
	)
	(via
		(at 201.90587 -328.491088)
		(size 0.508)
		(drill 0.254)
		(layers "F.Cu" "B.Cu")
		(net "P12V_S3_AUX_CPU1_NVDIMM")
	)
	(via
		(at 202.70089 -327.053448)
		(size 0.508)
		(drill 0.254)
		(layers "F.Cu" "B.Cu")
		(net "P12V_S3_AUX_CPU1_NVDIMM")
	)
	(via
		(at 22.22119 -331.254608)
		(size 0.508)
		(drill 0.254)
		(layers "F.Cu" "B.Cu")
		(net "P12V_S3_AUX_CPU1_NVDIMM")
	)
	(via
		(at 179.112418 -320.566796)
		(size 0.4572)
		(drill 0.2032)
		(layers "F.Cu" "B.Cu")
		(net "P12V_S3_AUX_CPU1_NVDIMM")
	)
	(via
		(at 26.79065 -333.558388)
		(size 0.508)
		(drill 0.254)
		(layers "F.Cu" "B.Cu")
		(net "P12V_S3_AUX_CPU1_NVDIMM")
	)
	(via
		(at 23.74519 -334.175608)
		(size 0.508)
		(drill 0.254)
		(layers "F.Cu" "B.Cu")
		(net "P12V_S3_AUX_CPU1_NVDIMM")
	)
	(via
		(at 44.754546 -321.41668)
		(size 0.4572)
		(drill 0.2032)
		(layers "F.Cu" "B.Cu")
		(net "P12V_S3_AUX_CPU1_NVDIMM")
	)
	(via
		(at 201.17943 -326.273668)
		(size 0.508)
		(drill 0.254)
		(layers "F.Cu" "B.Cu")
		(net "P12V_S3_AUX_CPU1_NVDIMM")
	)
	(via
		(at 26.79065 -332.034388)
		(size 0.508)
		(drill 0.254)
		(layers "F.Cu" "B.Cu")
		(net "P12V_S3_AUX_CPU1_NVDIMM")
	)
	(via
		(at 194.39763 -327.797668)
		(size 0.508)
		(drill 0.254)
		(layers "F.Cu" "B.Cu")
		(net "P12V_S3_AUX_CPU1_NVDIMM")
	)
	(via
		(at 207.071214 -320.566796)
		(size 0.4572)
		(drill 0.2032)
		(layers "F.Cu" "B.Cu")
		(net "P12V_S3_AUX_CPU1_NVDIMM")
	)
	(via
		(at 24.50719 -334.175608)
		(size 0.508)
		(drill 0.254)
		(layers "F.Cu" "B.Cu")
		(net "P12V_S3_AUX_CPU1_NVDIMM")
	)
	(via
		(at 14.579346 -321.41668)
		(size 0.4572)
		(drill 0.2032)
		(layers "F.Cu" "B.Cu")
		(net "P12V_S3_AUX_CPU1_NVDIMM")
	)
	(via
		(at 23.74519 -332.778608)
		(size 0.508)
		(drill 0.254)
		(layers "F.Cu" "B.Cu")
		(net "P12V_S3_AUX_CPU1_NVDIMM")
	)
	(via
		(at 41.310814 -321.41668)
		(size 0.4572)
		(drill 0.2032)
		(layers "F.Cu" "B.Cu")
		(net "P12V_S3_AUX_CPU1_NVDIMM")
	)
	(via
		(at 26.223214 -320.566796)
		(size 0.4572)
		(drill 0.2032)
		(layers "F.Cu" "B.Cu")
		(net "P12V_S3_AUX_CPU1_NVDIMM")
	)
	(via
		(at 193.63563 -327.797668)
		(size 0.508)
		(drill 0.254)
		(layers "F.Cu" "B.Cu")
		(net "P12V_S3_AUX_CPU1_NVDIMM")
	)
	(via
		(at 26.03119 -332.016608)
		(size 0.508)
		(drill 0.254)
		(layers "F.Cu" "B.Cu")
		(net "P12V_S3_AUX_CPU1_NVDIMM")
	)
	(via
		(at 214.615014 -320.566796)
		(size 0.4572)
		(drill 0.2032)
		(layers "F.Cu" "B.Cu")
		(net "P12V_S3_AUX_CPU1_NVDIMM")
	)
	(via
		(at 24.50719 -332.016608)
		(size 0.508)
		(drill 0.254)
		(layers "F.Cu" "B.Cu")
		(net "P12V_S3_AUX_CPU1_NVDIMM")
	)
	(via
		(at 191.972438 -321.41668)
		(size 0.4572)
		(drill 0.2032)
		(layers "F.Cu" "B.Cu")
		(net "P12V_S3_AUX_CPU1_NVDIMM")
	)
	(via
		(at 24.50719 -333.540608)
		(size 0.508)
		(drill 0.254)
		(layers "F.Cu" "B.Cu")
		(net "P12V_S3_AUX_CPU1_NVDIMM")
	)
	(via
		(at 199.527414 -321.41668)
		(size 0.4572)
		(drill 0.2032)
		(layers "F.Cu" "B.Cu")
		(net "P12V_S3_AUX_CPU1_NVDIMM")
	)
	(via
		(at 184.431178 -321.41668)
		(size 0.4572)
		(drill 0.2032)
		(layers "F.Cu" "B.Cu")
		(net "P12V_S3_AUX_CPU1_NVDIMM")
	)
	(via
		(at 29.666946 -321.41668)
		(size 0.4572)
		(drill 0.2032)
		(layers "F.Cu" "B.Cu")
		(net "P12V_S3_AUX_CPU1_NVDIMM")
	)
	(via
		(at 24.50719 -332.778608)
		(size 0.508)
		(drill 0.254)
		(layers "F.Cu" "B.Cu")
		(net "P12V_S3_AUX_CPU1_NVDIMM")
	)
	(via
		(at 52.298346 -321.41668)
		(size 0.4572)
		(drill 0.2032)
		(layers "F.Cu" "B.Cu")
		(net "P12V_S3_AUX_CPU1_NVDIMM")
	)
	(via
		(at 281.707082 -321.41668)
		(size 0.4572)
		(drill 0.2032)
		(layers "F.Cu" "B.Cu")
		(net "P12V_S3_AUX_CPU0_NVDIMM")
	)
	(via
		(at 450.89191 -329.799188)
		(size 0.508)
		(drill 0.254)
		(layers "F.Cu" "B.Cu")
		(net "P12V_S3_AUX_CPU0_NVDIMM")
	)
	(via
		(at 447.08191 -332.847188)
		(size 0.508)
		(drill 0.254)
		(layers "F.Cu" "B.Cu")
		(net "P12V_S3_AUX_CPU0_NVDIMM")
	)
	(via
		(at 451.65391 -331.323188)
		(size 0.508)
		(drill 0.254)
		(layers "F.Cu" "B.Cu")
		(net "P12V_S3_AUX_CPU0_NVDIMM")
	)
	(via
		(at 453.17791 -329.799188)
		(size 0.508)
		(drill 0.254)
		(layers "F.Cu" "B.Cu")
		(net "P12V_S3_AUX_CPU0_NVDIMM")
	)
	(via
		(at 270.091916 -326.825356)
		(size 0.508)
		(drill 0.254)
		(layers "F.Cu" "B.Cu")
		(net "P12V_S3_AUX_CPU0_NVDIMM")
	)
	(via
		(at 289.04692 -321.109848)
		(size 0.4572)
		(drill 0.2032)
		(layers "F.Cu" "B.Cu")
		(net "P12V_S3_AUX_CPU0_NVDIMM")
	)
	(via
		(at 452.41591 -330.561188)
		(size 0.508)
		(drill 0.254)
		(layers "F.Cu" "B.Cu")
		(net "P12V_S3_AUX_CPU0_NVDIMM")
	)
	(via
		(at 462.555082 -320.566796)
		(size 0.4572)
		(drill 0.2032)
		(layers "F.Cu" "B.Cu")
		(net "P12V_S3_AUX_CPU0_NVDIMM")
	)
	(via
		(at 450.12991 -329.037188)
		(size 0.508)
		(drill 0.254)
		(layers "F.Cu" "B.Cu")
		(net "P12V_S3_AUX_CPU0_NVDIMM")
	)
	(via
		(at 281.6987 -320.794888)
		(size 0.4572)
		(drill 0.2032)
		(layers "F.Cu" "B.Cu")
		(net "P12V_S3_AUX_CPU0_NVDIMM")
	)
	(via
		(at 453.17791 -332.847188)
		(size 0.508)
		(drill 0.254)
		(layers "F.Cu" "B.Cu")
		(net "P12V_S3_AUX_CPU0_NVDIMM")
	)
	(via
		(at 266.57554 -329.35037)
		(size 0.508)
		(drill 0.254)
		(layers "F.Cu" "B.Cu")
		(net "P12V_S3_AUX_CPU0_NVDIMM")
	)
	(via
		(at 259.075682 -321.41668)
		(size 0.4572)
		(drill 0.2032)
		(layers "F.Cu" "B.Cu")
		(net "P12V_S3_AUX_CPU0_NVDIMM")
	)
	(via
		(at 275.263356 -326.426576)
		(size 0.508)
		(drill 0.254)
		(layers "F.Cu" "B.Cu")
		(net "P12V_S3_AUX_CPU0_NVDIMM")
	)
	(via
		(at 274.163282 -320.566796)
		(size 0.4572)
		(drill 0.2032)
		(layers "F.Cu" "B.Cu")
		(net "P12V_S3_AUX_CPU0_NVDIMM")
	)
	(via
		(at 446.31991 -332.847188)
		(size 0.508)
		(drill 0.254)
		(layers "F.Cu" "B.Cu")
		(net "P12V_S3_AUX_CPU0_NVDIMM")
	)
	(via
		(at 268.821916 -326.825356)
		(size 0.508)
		(drill 0.254)
		(layers "F.Cu" "B.Cu")
		(net "P12V_S3_AUX_CPU0_NVDIMM")
	)
	(via
		(at 445.55791 -329.799188)
		(size 0.508)
		(drill 0.254)
		(layers "F.Cu" "B.Cu")
		(net "P12V_S3_AUX_CPU0_NVDIMM")
	)
	(via
		(at 443.367414 -321.41668)
		(size 0.4572)
		(drill 0.2032)
		(layers "F.Cu" "B.Cu")
		(net "P12V_S3_AUX_CPU0_NVDIMM")
	)
	(via
		(at 447.08191 -329.037188)
		(size 0.508)
		(drill 0.254)
		(layers "F.Cu" "B.Cu")
		(net "P12V_S3_AUX_CPU0_NVDIMM")
	)
	(via
		(at 408.405838 -321.16903)
		(size 0.4572)
		(drill 0.2032)
		(layers "F.Cu" "B.Cu")
		(net "P12V_S3_AUX_CPU0_NVDIMM")
	)
	(via
		(at 452.41591 -332.085188)
		(size 0.508)
		(drill 0.254)
		(layers "F.Cu" "B.Cu")
		(net "P12V_S3_AUX_CPU0_NVDIMM")
	)
	(via
		(at 453.17791 -331.323188)
		(size 0.508)
		(drill 0.254)
		(layers "F.Cu" "B.Cu")
		(net "P12V_S3_AUX_CPU0_NVDIMM")
	)
	(via
		(at 446.31991 -330.561188)
		(size 0.508)
		(drill 0.254)
		(layers "F.Cu" "B.Cu")
		(net "P12V_S3_AUX_CPU0_NVDIMM")
	)
	(via
		(at 455.011282 -321.41668)
		(size 0.4572)
		(drill 0.2032)
		(layers "F.Cu" "B.Cu")
		(net "P12V_S3_AUX_CPU0_NVDIMM")
	)
	(via
		(at 420.671752 -321.300856)
		(size 0.4572)
		(drill 0.2032)
		(layers "F.Cu" "B.Cu")
		(net "P12V_S3_AUX_CPU0_NVDIMM")
	)
	(via
		(at 428.274226 -321.30619)
		(size 0.4572)
		(drill 0.2032)
		(layers "F.Cu" "B.Cu")
		(net "P12V_S3_AUX_CPU0_NVDIMM")
	)
	(via
		(at 296.061638 -330.47813)
		(size 0.6604)
		(drill 0.3302)
		(layers "F.Cu" "B.Cu")
		(net "P12V_S3_AUX_CPU0_NVDIMM")
	)
	(via
		(at 304.33772 -320.576448)
		(size 0.4572)
		(drill 0.2032)
		(layers "F.Cu" "B.Cu")
		(net "P12V_S3_AUX_CPU0_NVDIMM")
	)
	(via
		(at 439.912506 -321.41668)
		(size 0.4572)
		(drill 0.2032)
		(layers "F.Cu" "B.Cu")
		(net "P12V_S3_AUX_CPU0_NVDIMM")
	)
	(via
		(at 259.075682 -320.566796)
		(size 0.4572)
		(drill 0.2032)
		(layers "F.Cu" "B.Cu")
		(net "P12V_S3_AUX_CPU0_NVDIMM")
	)
	(via
		(at 297.833542 -326.83831)
		(size 0.508)
		(drill 0.254)
		(layers "F.Cu" "B.Cu")
		(net "P12V_S3_AUX_CPU0_NVDIMM")
	)
	(via
		(at 445.55791 -331.323188)
		(size 0.508)
		(drill 0.254)
		(layers "F.Cu" "B.Cu")
		(net "P12V_S3_AUX_CPU0_NVDIMM")
	)
	(via
		(at 462.555082 -321.41668)
		(size 0.4572)
		(drill 0.2032)
		(layers "F.Cu" "B.Cu")
		(net "P12V_S3_AUX_CPU0_NVDIMM")
	)
	(via
		(at 289.250882 -320.554858)
		(size 0.4572)
		(drill 0.2032)
		(layers "F.Cu" "B.Cu")
		(net "P12V_S3_AUX_CPU0_NVDIMM")
	)
	(via
		(at 268.821916 -328.095356)
		(size 0.508)
		(drill 0.254)
		(layers "F.Cu" "B.Cu")
		(net "P12V_S3_AUX_CPU0_NVDIMM")
	)
	(via
		(at 446.31991 -329.037188)
		(size 0.508)
		(drill 0.254)
		(layers "F.Cu" "B.Cu")
		(net "P12V_S3_AUX_CPU0_NVDIMM")
	)
	(via
		(at 270.091916 -328.095356)
		(size 0.508)
		(drill 0.254)
		(layers "F.Cu" "B.Cu")
		(net "P12V_S3_AUX_CPU0_NVDIMM")
	)
	(via
		(at 439.923682 -320.566796)
		(size 0.4572)
		(drill 0.2032)
		(layers "F.Cu" "B.Cu")
		(net "P12V_S3_AUX_CPU0_NVDIMM")
	)
	(via
		(at 274.163282 -321.41668)
		(size 0.4572)
		(drill 0.2032)
		(layers "F.Cu" "B.Cu")
		(net "P12V_S3_AUX_CPU0_NVDIMM")
	)
	(via
		(at 268.80566 -329.260708)
		(size 0.508)
		(drill 0.254)
		(layers "F.Cu" "B.Cu")
		(net "P12V_S3_AUX_CPU0_NVDIMM")
	)
	(via
		(at 292.694614 -321.41668)
		(size 0.4572)
		(drill 0.2032)
		(layers "F.Cu" "B.Cu")
		(net "P12V_S3_AUX_CPU0_NVDIMM")
	)
	(via
		(at 432.379882 -320.566796)
		(size 0.4572)
		(drill 0.2032)
		(layers "F.Cu" "B.Cu")
		(net "P12V_S3_AUX_CPU0_NVDIMM")
	)
	(via
		(at 273.719036 -328.896726)
		(size 0.508)
		(drill 0.254)
		(layers "F.Cu" "B.Cu")
		(net "P12V_S3_AUX_CPU0_NVDIMM")
	)
	(via
		(at 452.41591 -329.799188)
		(size 0.508)
		(drill 0.254)
		(layers "F.Cu" "B.Cu")
		(net "P12V_S3_AUX_CPU0_NVDIMM")
	)
	(via
		(at 272.079466 -328.845926)
		(size 0.508)
		(drill 0.254)
		(layers "F.Cu" "B.Cu")
		(net "P12V_S3_AUX_CPU0_NVDIMM")
	)
	(via
		(at 264.03554 -329.35037)
		(size 0.508)
		(drill 0.254)
		(layers "F.Cu" "B.Cu")
		(net "P12V_S3_AUX_CPU0_NVDIMM")
	)
	(via
		(at 265.30554 -329.35037)
		(size 0.508)
		(drill 0.254)
		(layers "F.Cu" "B.Cu")
		(net "P12V_S3_AUX_CPU0_NVDIMM")
	)
	(via
		(at 427.052486 -320.566796)
		(size 0.4572)
		(drill 0.2032)
		(layers "F.Cu" "B.Cu")
		(net "P12V_S3_AUX_CPU0_NVDIMM")
	)
	(via
		(at 417.268152 -321.173856)
		(size 0.4572)
		(drill 0.2032)
		(layers "F.Cu" "B.Cu")
		(net "P12V_S3_AUX_CPU0_NVDIMM")
	)
	(via
		(at 445.55791 -332.085188)
		(size 0.508)
		(drill 0.254)
		(layers "F.Cu" "B.Cu")
		(net "P12V_S3_AUX_CPU0_NVDIMM")
	)
	(via
		(at 445.55791 -332.847188)
		(size 0.508)
		(drill 0.254)
		(layers "F.Cu" "B.Cu")
		(net "P12V_S3_AUX_CPU0_NVDIMM")
	)
	(via
		(at 448.60591 -329.799188)
		(size 0.508)
		(drill 0.254)
		(layers "F.Cu" "B.Cu")
		(net "P12V_S3_AUX_CPU0_NVDIMM")
	)
	(via
		(at 307.65496 -321.437508)
		(size 0.4572)
		(drill 0.2032)
		(layers "F.Cu" "B.Cu")
		(net "P12V_S3_AUX_CPU0_NVDIMM")
	)
	(via
		(at 267.551916 -329.365356)
		(size 0.508)
		(drill 0.254)
		(layers "F.Cu" "B.Cu")
		(net "P12V_S3_AUX_CPU0_NVDIMM")
	)
	(via
		(at 452.41591 -331.323188)
		(size 0.508)
		(drill 0.254)
		(layers "F.Cu" "B.Cu")
		(net "P12V_S3_AUX_CPU0_NVDIMM")
	)
	(via
		(at 451.65391 -330.561188)
		(size 0.508)
		(drill 0.254)
		(layers "F.Cu" "B.Cu")
		(net "P12V_S3_AUX_CPU0_NVDIMM")
	)
	(via
		(at 294.385238 -330.47813)
		(size 0.6604)
		(drill 0.3302)
		(layers "F.Cu" "B.Cu")
		(net "P12V_S3_AUX_CPU0_NVDIMM")
	)
	(via
		(at 452.41591 -333.482188)
		(size 0.508)
		(drill 0.254)
		(layers "F.Cu" "B.Cu")
		(net "P12V_S3_AUX_CPU0_NVDIMM")
	)
	(via
		(at 447.84391 -329.037188)
		(size 0.508)
		(drill 0.254)
		(layers "F.Cu" "B.Cu")
		(net "P12V_S3_AUX_CPU0_NVDIMM")
	)
	(via
		(at 453.17791 -333.482188)
		(size 0.508)
		(drill 0.254)
		(layers "F.Cu" "B.Cu")
		(net "P12V_S3_AUX_CPU0_NVDIMM")
	)
	(via
		(at 453.17791 -329.037188)
		(size 0.508)
		(drill 0.254)
		(layers "F.Cu" "B.Cu")
		(net "P12V_S3_AUX_CPU0_NVDIMM")
	)
	(via
		(at 447.84391 -330.561188)
		(size 0.508)
		(drill 0.254)
		(layers "F.Cu" "B.Cu")
		(net "P12V_S3_AUX_CPU0_NVDIMM")
	)
	(via
		(at 292.708838 -330.47813)
		(size 0.6604)
		(drill 0.3302)
		(layers "F.Cu" "B.Cu")
		(net "P12V_S3_AUX_CPU0_NVDIMM")
	)
	(via
		(at 272.894298 -328.841608)
		(size 0.508)
		(drill 0.254)
		(layers "F.Cu" "B.Cu")
		(net "P12V_S3_AUX_CPU0_NVDIMM")
	)
	(via
		(at 448.60591 -329.037188)
		(size 0.508)
		(drill 0.254)
		(layers "F.Cu" "B.Cu")
		(net "P12V_S3_AUX_CPU0_NVDIMM")
	)
	(via
		(at 267.551916 -326.825356)
		(size 0.508)
		(drill 0.254)
		(layers "F.Cu" "B.Cu")
		(net "P12V_S3_AUX_CPU0_NVDIMM")
	)
	(via
		(at 300.238414 -321.41668)
		(size 0.4572)
		(drill 0.2032)
		(layers "F.Cu" "B.Cu")
		(net "P12V_S3_AUX_CPU0_NVDIMM")
	)
	(via
		(at 453.17791 -332.085188)
		(size 0.508)
		(drill 0.254)
		(layers "F.Cu" "B.Cu")
		(net "P12V_S3_AUX_CPU0_NVDIMM")
	)
	(via
		(at 447.84391 -329.799188)
		(size 0.508)
		(drill 0.254)
		(layers "F.Cu" "B.Cu")
		(net "P12V_S3_AUX_CPU0_NVDIMM")
	)
	(via
		(at 455.011282 -320.566796)
		(size 0.4572)
		(drill 0.2032)
		(layers "F.Cu" "B.Cu")
		(net "P12V_S3_AUX_CPU0_NVDIMM")
	)
	(via
		(at 422.876218 -331.09027)
		(size 0.6604)
		(drill 0.3302)
		(layers "F.Cu" "B.Cu")
		(net "P12V_S3_AUX_CPU0_NVDIMM")
	)
	(via
		(at 445.55791 -330.561188)
		(size 0.508)
		(drill 0.254)
		(layers "F.Cu" "B.Cu")
		(net "P12V_S3_AUX_CPU0_NVDIMM")
	)
	(via
		(at 442.649356 -326.959976)
		(size 0.508)
		(drill 0.254)
		(layers "F.Cu" "B.Cu")
		(net "P12V_S3_AUX_CPU0_NVDIMM")
	)
	(via
		(at 276.787356 -326.426576)
		(size 0.508)
		(drill 0.254)
		(layers "F.Cu" "B.Cu")
		(net "P12V_S3_AUX_CPU0_NVDIMM")
	)
	(via
		(at 458.455014 -321.41668)
		(size 0.4572)
		(drill 0.2032)
		(layers "F.Cu" "B.Cu")
		(net "P12V_S3_AUX_CPU0_NVDIMM")
	)
	(via
		(at 270.091916 -329.365356)
		(size 0.508)
		(drill 0.254)
		(layers "F.Cu" "B.Cu")
		(net "P12V_S3_AUX_CPU0_NVDIMM")
	)
	(via
		(at 275.263356 -327.188576)
		(size 0.508)
		(drill 0.254)
		(layers "F.Cu" "B.Cu")
		(net "P12V_S3_AUX_CPU0_NVDIMM")
	)
	(via
		(at 409.706826 -320.35369)
		(size 0.4572)
		(drill 0.2032)
		(layers "F.Cu" "B.Cu")
		(net "P12V_S3_AUX_CPU0_NVDIMM")
	)
	(via
		(at 426.229018 -331.09027)
		(size 0.6604)
		(drill 0.3302)
		(layers "F.Cu" "B.Cu")
		(net "P12V_S3_AUX_CPU0_NVDIMM")
	)
	(via
		(at 266.619482 -320.566796)
		(size 0.4572)
		(drill 0.2032)
		(layers "F.Cu" "B.Cu")
		(net "P12V_S3_AUX_CPU0_NVDIMM")
	)
	(via
		(at 449.36791 -329.037188)
		(size 0.508)
		(drill 0.254)
		(layers "F.Cu" "B.Cu")
		(net "P12V_S3_AUX_CPU0_NVDIMM")
	)
	(via
		(at 417.292282 -320.566796)
		(size 0.4572)
		(drill 0.2032)
		(layers "F.Cu" "B.Cu")
		(net "P12V_S3_AUX_CPU0_NVDIMM")
	)
	(via
		(at 303.90338 -321.407028)
		(size 0.4572)
		(drill 0.2032)
		(layers "F.Cu" "B.Cu")
		(net "P12V_S3_AUX_CPU0_NVDIMM")
	)
	(via
		(at 441.455556 -326.985376)
		(size 0.508)
		(drill 0.254)
		(layers "F.Cu" "B.Cu")
		(net "P12V_S3_AUX_CPU0_NVDIMM")
	)
	(via
		(at 254.975614 -321.41668)
		(size 0.4572)
		(drill 0.2032)
		(layers "F.Cu" "B.Cu")
		(net "P12V_S3_AUX_CPU0_NVDIMM")
	)
	(via
		(at 432.371246 -321.41668)
		(size 0.4572)
		(drill 0.2032)
		(layers "F.Cu" "B.Cu")
		(net "P12V_S3_AUX_CPU0_NVDIMM")
	)
	(via
		(at 452.41591 -332.847188)
		(size 0.508)
		(drill 0.254)
		(layers "F.Cu" "B.Cu")
		(net "P12V_S3_AUX_CPU0_NVDIMM")
	)
	(via
		(at 447.08191 -330.561188)
		(size 0.508)
		(drill 0.254)
		(layers "F.Cu" "B.Cu")
		(net "P12V_S3_AUX_CPU0_NVDIMM")
	)
	(via
		(at 451.65391 -332.847188)
		(size 0.508)
		(drill 0.254)
		(layers "F.Cu" "B.Cu")
		(net "P12V_S3_AUX_CPU0_NVDIMM")
	)
	(via
		(at 452.41591 -329.037188)
		(size 0.508)
		(drill 0.254)
		(layers "F.Cu" "B.Cu")
		(net "P12V_S3_AUX_CPU0_NVDIMM")
	)
	(via
		(at 296.794682 -321.41668)
		(size 0.4572)
		(drill 0.2032)
		(layers "F.Cu" "B.Cu")
		(net "P12V_S3_AUX_CPU0_NVDIMM")
	)
	(via
		(at 451.65391 -332.085188)
		(size 0.508)
		(drill 0.254)
		(layers "F.Cu" "B.Cu")
		(net "P12V_S3_AUX_CPU0_NVDIMM")
	)
	(via
		(at 448.60591 -330.561188)
		(size 0.508)
		(drill 0.254)
		(layers "F.Cu" "B.Cu")
		(net "P12V_S3_AUX_CPU0_NVDIMM")
	)
	(via
		(at 296.794682 -320.566796)
		(size 0.4572)
		(drill 0.2032)
		(layers "F.Cu" "B.Cu")
		(net "P12V_S3_AUX_CPU0_NVDIMM")
	)
	(via
		(at 447.467482 -321.41668)
		(size 0.4572)
		(drill 0.2032)
		(layers "F.Cu" "B.Cu")
		(net "P12V_S3_AUX_CPU0_NVDIMM")
	)
	(via
		(at 424.735752 -320.996056)
		(size 0.4572)
		(drill 0.2032)
		(layers "F.Cu" "B.Cu")
		(net "P12V_S3_AUX_CPU0_NVDIMM")
	)
	(via
		(at 450.911214 -321.41668)
		(size 0.4572)
		(drill 0.2032)
		(layers "F.Cu" "B.Cu")
		(net "P12V_S3_AUX_CPU0_NVDIMM")
	)
	(via
		(at 450.89191 -330.561188)
		(size 0.508)
		(drill 0.254)
		(layers "F.Cu" "B.Cu")
		(net "P12V_S3_AUX_CPU0_NVDIMM")
	)
	(via
		(at 449.36791 -329.799188)
		(size 0.508)
		(drill 0.254)
		(layers "F.Cu" "B.Cu")
		(net "P12V_S3_AUX_CPU0_NVDIMM")
	)
	(via
		(at 450.12991 -329.799188)
		(size 0.508)
		(drill 0.254)
		(layers "F.Cu" "B.Cu")
		(net "P12V_S3_AUX_CPU0_NVDIMM")
	)
	(via
		(at 262.519414 -321.41668)
		(size 0.4572)
		(drill 0.2032)
		(layers "F.Cu" "B.Cu")
		(net "P12V_S3_AUX_CPU0_NVDIMM")
	)
	(via
		(at 451.65391 -333.482188)
		(size 0.508)
		(drill 0.254)
		(layers "F.Cu" "B.Cu")
		(net "P12V_S3_AUX_CPU0_NVDIMM")
	)
	(via
		(at 266.57554 -328.46137)
		(size 0.508)
		(drill 0.254)
		(layers "F.Cu" "B.Cu")
		(net "P12V_S3_AUX_CPU0_NVDIMM")
	)
	(via
		(at 264.03554 -328.46137)
		(size 0.508)
		(drill 0.254)
		(layers "F.Cu" "B.Cu")
		(net "P12V_S3_AUX_CPU0_NVDIMM")
	)
	(via
		(at 446.31991 -332.085188)
		(size 0.508)
		(drill 0.254)
		(layers "F.Cu" "B.Cu")
		(net "P12V_S3_AUX_CPU0_NVDIMM")
	)
	(via
		(at 443.944756 -326.985376)
		(size 0.508)
		(drill 0.254)
		(layers "F.Cu" "B.Cu")
		(net "P12V_S3_AUX_CPU0_NVDIMM")
	)
	(via
		(at 275.263356 -327.950576)
		(size 0.508)
		(drill 0.254)
		(layers "F.Cu" "B.Cu")
		(net "P12V_S3_AUX_CPU0_NVDIMM")
	)
	(via
		(at 447.08191 -329.799188)
		(size 0.508)
		(drill 0.254)
		(layers "F.Cu" "B.Cu")
		(net "P12V_S3_AUX_CPU0_NVDIMM")
	)
	(via
		(at 445.55791 -329.037188)
		(size 0.508)
		(drill 0.254)
		(layers "F.Cu" "B.Cu")
		(net "P12V_S3_AUX_CPU0_NVDIMM")
	)
	(via
		(at 311.28716 -321.666108)
		(size 0.4572)
		(drill 0.2032)
		(layers "F.Cu" "B.Cu")
		(net "P12V_S3_AUX_CPU0_NVDIMM")
	)
	(via
		(at 297.738038 -330.47813)
		(size 0.6604)
		(drill 0.3302)
		(layers "F.Cu" "B.Cu")
		(net "P12V_S3_AUX_CPU0_NVDIMM")
	)
	(via
		(at 285.14548 -321.213988)
		(size 0.4572)
		(drill 0.2032)
		(layers "F.Cu" "B.Cu")
		(net "P12V_S3_AUX_CPU0_NVDIMM")
	)
	(via
		(at 451.65391 -329.799188)
		(size 0.508)
		(drill 0.254)
		(layers "F.Cu" "B.Cu")
		(net "P12V_S3_AUX_CPU0_NVDIMM")
	)
	(via
		(at 449.36791 -330.561188)
		(size 0.508)
		(drill 0.254)
		(layers "F.Cu" "B.Cu")
		(net "P12V_S3_AUX_CPU0_NVDIMM")
	)
	(via
		(at 446.31991 -329.799188)
		(size 0.508)
		(drill 0.254)
		(layers "F.Cu" "B.Cu")
		(net "P12V_S3_AUX_CPU0_NVDIMM")
	)
	(via
		(at 267.551916 -328.095356)
		(size 0.508)
		(drill 0.254)
		(layers "F.Cu" "B.Cu")
		(net "P12V_S3_AUX_CPU0_NVDIMM")
	)
	(via
		(at 311.82818 -321.351148)
		(size 0.4572)
		(drill 0.2032)
		(layers "F.Cu" "B.Cu")
		(net "P12V_S3_AUX_CPU0_NVDIMM")
	)
	(via
		(at 435.823106 -321.41668)
		(size 0.4572)
		(drill 0.2032)
		(layers "F.Cu" "B.Cu")
		(net "P12V_S3_AUX_CPU0_NVDIMM")
	)
	(via
		(at 298.595542 -326.83831)
		(size 0.508)
		(drill 0.254)
		(layers "F.Cu" "B.Cu")
		(net "P12V_S3_AUX_CPU0_NVDIMM")
	)
	(via
		(at 451.65391 -329.037188)
		(size 0.508)
		(drill 0.254)
		(layers "F.Cu" "B.Cu")
		(net "P12V_S3_AUX_CPU0_NVDIMM")
	)
	(via
		(at 265.30554 -328.46137)
		(size 0.508)
		(drill 0.254)
		(layers "F.Cu" "B.Cu")
		(net "P12V_S3_AUX_CPU0_NVDIMM")
	)
	(via
		(at 266.619482 -321.41668)
		(size 0.4572)
		(drill 0.2032)
		(layers "F.Cu" "B.Cu")
		(net "P12V_S3_AUX_CPU0_NVDIMM")
	)
	(via
		(at 290.239196 -327.052432)
		(size 0.508)
		(drill 0.254)
		(layers "F.Cu" "B.Cu")
		(net "P12V_S3_AUX_CPU0_NVDIMM")
	)
	(via
		(at 277.607014 -321.41668)
		(size 0.4572)
		(drill 0.2032)
		(layers "F.Cu" "B.Cu")
		(net "P12V_S3_AUX_CPU0_NVDIMM")
	)
	(via
		(at 447.08191 -331.323188)
		(size 0.508)
		(drill 0.254)
		(layers "F.Cu" "B.Cu")
		(net "P12V_S3_AUX_CPU0_NVDIMM")
	)
	(via
		(at 270.063214 -321.41668)
		(size 0.4572)
		(drill 0.2032)
		(layers "F.Cu" "B.Cu")
		(net "P12V_S3_AUX_CPU0_NVDIMM")
	)
	(via
		(at 447.467482 -320.566796)
		(size 0.4572)
		(drill 0.2032)
		(layers "F.Cu" "B.Cu")
		(net "P12V_S3_AUX_CPU0_NVDIMM")
	)
	(via
		(at 446.31991 -331.323188)
		(size 0.508)
		(drill 0.254)
		(layers "F.Cu" "B.Cu")
		(net "P12V_S3_AUX_CPU0_NVDIMM")
	)
	(via
		(at 450.89191 -329.037188)
		(size 0.508)
		(drill 0.254)
		(layers "F.Cu" "B.Cu")
		(net "P12V_S3_AUX_CPU0_NVDIMM")
	)
	(via
		(at 450.12991 -330.561188)
		(size 0.508)
		(drill 0.254)
		(layers "F.Cu" "B.Cu")
		(net "P12V_S3_AUX_CPU0_NVDIMM")
	)
	(via
		(at 453.17791 -330.561188)
		(size 0.508)
		(drill 0.254)
		(layers "F.Cu" "B.Cu")
		(net "P12V_S3_AUX_CPU0_NVDIMM")
	)
	(via
		(at 447.08191 -332.085188)
		(size 0.508)
		(drill 0.254)
		(layers "F.Cu" "B.Cu")
		(net "P12V_S3_AUX_CPU0_NVDIMM")
	)
	(segment
		(start 453.454262 -24.619458)
		(end 453.454262 -25.627838)
		(width 0.508)
		(layer "F.Cu")
		(net "P12V_OCP_SFF")
	)
	(segment
		(start 455.70648 -23.945342)
		(end 455.70648 -17.855438)
		(width 0.508)
		(layer "F.Cu")
		(net "P12V_OCP_SFF")
	)
	(segment
		(start 455.200766 -17.349724)
		(end 455.298556 -17.447514)
		(width 0.508)
		(layer "F.Cu")
		(net "P12V_OCP_SFF")
	)
	(segment
		(start 440.735212 -21.698458)
		(end 436.673752 -21.698458)
		(width 0.254)
		(layer "F.Cu")
		(net "P12V_OCP_SFF")
	)
	(segment
		(start 455.70648 -17.855438)
		(end 455.298556 -17.447514)
		(width 0.508)
		(layer "F.Cu")
		(net "P12V_OCP_SFF")
	)
	(segment
		(start 453.454262 -25.627838)
		(end 453.443594 -25.638506)
		(width 0.508)
		(layer "F.Cu")
		(net "P12V_OCP_SFF")
	)
	(segment
		(start 435.657752 -26.006806)
		(end 436.526432 -26.875486)
		(width 0.254)
		(layer "F.Cu")
		(net "P12V_OCP_SFF")
	)
	(segment
		(start 435.657752 -22.714458)
		(end 435.657752 -26.006806)
		(width 0.254)
		(layer "F.Cu")
		(net "P12V_OCP_SFF")
	)
	(segment
		(start 436.673752 -21.698458)
		(end 435.657752 -22.714458)
		(width 0.254)
		(layer "F.Cu")
		(net "P12V_OCP_SFF")
	)
	(segment
		(start 452.61403 -17.349724)
		(end 455.200766 -17.349724)
		(width 0.508)
		(layer "F.Cu")
		(net "P12V_OCP_SFF")
	)
	(segment
		(start 455.032364 -24.619458)
		(end 455.70648 -23.945342)
		(width 0.508)
		(layer "F.Cu")
		(net "P12V_OCP_SFF")
	)
	(segment
		(start 453.454262 -24.619458)
		(end 455.032364 -24.619458)
		(width 0.508)
		(layer "F.Cu")
		(net "P12V_OCP_SFF")
	)
	(via
		(at 442.90488 -25.872948)
		(size 0.508)
		(drill 0.254)
		(layers "F.Cu" "B.Cu")
		(net "P12V_OCP_SFF")
	)
	(via
		(at 438.8104 -13.355828)
		(size 0.508)
		(drill 0.254)
		(layers "F.Cu" "B.Cu")
		(net "P12V_OCP_SFF")
	)
	(via
		(at 438.58688 -12.664948)
		(size 0.508)
		(drill 0.254)
		(layers "F.Cu" "B.Cu")
		(net "P12V_OCP_SFF")
	)
	(via
		(at 442.39688 -25.110948)
		(size 0.508)
		(drill 0.254)
		(layers "F.Cu" "B.Cu")
		(net "P12V_OCP_SFF")
	)
	(via
		(at 442.177932 -19.00682)
		(size 0.508)
		(drill 0.254)
		(layers "F.Cu" "B.Cu")
		(net "P12V_OCP_SFF")
	)
	(via
		(at 440.95416 -11.250168)
		(size 0.508)
		(drill 0.254)
		(layers "F.Cu" "B.Cu")
		(net "P12V_OCP_SFF")
	)
	(via
		(at 452.063612 -17.786858)
		(size 0.508)
		(drill 0.254)
		(layers "F.Cu" "B.Cu")
		(net "P12V_OCP_SFF")
	)
	(via
		(at 439.45556 -13.348208)
		(size 0.508)
		(drill 0.254)
		(layers "F.Cu" "B.Cu")
		(net "P12V_OCP_SFF")
	)
	(via
		(at 444.17488 -24.729948)
		(size 0.508)
		(drill 0.254)
		(layers "F.Cu" "B.Cu")
		(net "P12V_OCP_SFF")
	)
	(via
		(at 442.177932 -20.91182)
		(size 0.508)
		(drill 0.254)
		(layers "F.Cu" "B.Cu")
		(net "P12V_OCP_SFF")
	)
	(via
		(at 450.679312 -15.998698)
		(size 0.508)
		(drill 0.254)
		(layers "F.Cu" "B.Cu")
		(net "P12V_OCP_SFF")
	)
	(via
		(at 440.13374 -13.330428)
		(size 0.508)
		(drill 0.254)
		(layers "F.Cu" "B.Cu")
		(net "P12V_OCP_SFF")
	)
	(via
		(at 450.679312 -15.262098)
		(size 0.508)
		(drill 0.254)
		(layers "F.Cu" "B.Cu")
		(net "P12V_OCP_SFF")
	)
	(via
		(at 440.36488 -12.664948)
		(size 0.508)
		(drill 0.254)
		(layers "F.Cu" "B.Cu")
		(net "P12V_OCP_SFF")
	)
	(via
		(at 439.47588 -12.664948)
		(size 0.508)
		(drill 0.254)
		(layers "F.Cu" "B.Cu")
		(net "P12V_OCP_SFF")
	)
	(via
		(at 440.95416 -10.615168)
		(size 0.508)
		(drill 0.254)
		(layers "F.Cu" "B.Cu")
		(net "P12V_OCP_SFF")
	)
	(via
		(at 452.063612 -18.523458)
		(size 0.508)
		(drill 0.254)
		(layers "F.Cu" "B.Cu")
		(net "P12V_OCP_SFF")
	)
	(via
		(at 442.01588 -25.872948)
		(size 0.508)
		(drill 0.254)
		(layers "F.Cu" "B.Cu")
		(net "P12V_OCP_SFF")
	)
	(via
		(at 441.12688 -25.872948)
		(size 0.508)
		(drill 0.254)
		(layers "F.Cu" "B.Cu")
		(net "P12V_OCP_SFF")
	)
	(via
		(at 442.177932 -18.37182)
		(size 0.508)
		(drill 0.254)
		(layers "F.Cu" "B.Cu")
		(net "P12V_OCP_SFF")
	)
	(via
		(at 442.177932 -20.27682)
		(size 0.508)
		(drill 0.254)
		(layers "F.Cu" "B.Cu")
		(net "P12V_OCP_SFF")
	)
	(via
		(at 443.28588 -25.110948)
		(size 0.508)
		(drill 0.254)
		(layers "F.Cu" "B.Cu")
		(net "P12V_OCP_SFF")
	)
	(via
		(at 441.50788 -25.110948)
		(size 0.508)
		(drill 0.254)
		(layers "F.Cu" "B.Cu")
		(net "P12V_OCP_SFF")
	)
	(segment
		(start 437.05018 -31.773368)
		(end 437.240172 -31.773368)
		(width 0.254)
		(layer "F.Cu")
		(net "P12V_OCP_IMON_1")
	)
	(segment
		(start 439.272172 -31.773368)
		(end 438.256172 -31.773368)
		(width 0.254)
		(layer "F.Cu")
		(net "P12V_OCP_IMON_1")
	)
	(segment
		(start 438.256172 -31.773368)
		(end 437.240172 -31.773368)
		(width 0.254)
		(layer "F.Cu")
		(net "P12V_OCP_IMON_1")
	)
	(segment
		(start 440.853068 -30.192472)
		(end 439.272172 -31.773368)
		(width 0.254)
		(layer "F.Cu")
		(net "P12V_OCP_IMON_1")
	)
	(segment
		(start 436.224172 -31.773368)
		(end 436.09514 -31.644336)
		(width 0.254)
		(layer "F.Cu")
		(net "P12V_OCP_IMON_1")
	)
	(segment
		(start 436.46344 -30.589728)
		(end 437.05018 -31.176468)
		(width 0.254)
		(layer "F.Cu")
		(net "P12V_OCP_IMON_1")
	)
	(segment
		(start 436.09514 -31.644336)
		(end 436.09514 -30.589728)
		(width 0.254)
		(layer "F.Cu")
		(net "P12V_OCP_IMON_1")
	)
	(segment
		(start 437.05018 -31.176468)
		(end 437.05018 -31.773368)
		(width 0.254)
		(layer "F.Cu")
		(net "P12V_OCP_IMON_1")
	)
	(segment
		(start 440.853068 -29.575506)
		(end 440.853068 -30.192472)
		(width 0.254)
		(layer "F.Cu")
		(net "P12V_OCP_IMON_1")
	)
	(segment
		(start 436.09514 -30.589728)
		(end 436.46344 -30.589728)
		(width 0.254)
		(layer "F.Cu")
		(net "P12V_OCP_IMON_1")
	)
	(via
		(at 436.09514 -30.589728)
		(size 0.762)
		(drill 0.381)
		(layers "F.Cu" "B.Cu")
		(net "P12V_OCP_IMON_1")
	)
	(segment
		(start 21.44522 -338.605114)
		(end 21.44522 -336.252566)
		(width 0.254)
		(layer "F.Cu")
		(net "P12V_AUX_CPU1_DIMM_ISEN_P")
	)
	(segment
		(start 21.271484 -336.07883)
		(end 18.581878 -336.07883)
		(width 0.254)
		(layer "F.Cu")
		(net "P12V_AUX_CPU1_DIMM_ISEN_P")
	)
	(segment
		(start 17.655032 -336.821272)
		(end 16.57096 -336.821272)
		(width 0.254)
		(layer "F.Cu")
		(net "P12V_AUX_CPU1_DIMM_ISEN_P")
	)
	(segment
		(start 21.44522 -336.252566)
		(end 21.271484 -336.07883)
		(width 0.254)
		(layer "F.Cu")
		(net "P12V_AUX_CPU1_DIMM_ISEN_P")
	)
	(segment
		(start 17.839436 -336.821272)
		(end 17.655032 -336.821272)
		(width 0.254)
		(layer "F.Cu")
		(net "P12V_AUX_CPU1_DIMM_ISEN_P")
	)
	(segment
		(start 18.581878 -336.07883)
		(end 17.839436 -336.821272)
		(width 0.254)
		(layer "F.Cu")
		(net "P12V_AUX_CPU1_DIMM_ISEN_P")
	)
	(via
		(at 16.57096 -336.821272)
		(size 0.508)
		(drill 0.254)
		(layers "F.Cu" "B.Cu")
		(net "P12V_AUX_CPU1_DIMM_ISEN_P")
	)
	(via
		(at 7.97306 -169.31513)
		(size 0.508)
		(drill 0.254)
		(layers "F.Cu" "B.Cu")
		(net "P12V_AUX_CPU1_DIMM_ISEN_P")
	)
	(segment
		(start 36.78174 -169.451528)
		(end 36.78174 -166.70528)
		(width 0.254)
		(layer "B.Cu")
		(net "P12V_AUX_CPU1_DIMM_ISEN_P")
	)
	(segment
		(start 8.21436 -169.55643)
		(end 8.21436 -170.120056)
		(width 0.254)
		(layer "B.Cu")
		(net "P12V_AUX_CPU1_DIMM_ISEN_P")
	)
	(segment
		(start 35.502088 -166.09695)
		(end 35.246564 -165.841426)
		(width 0.254)
		(layer "B.Cu")
		(net "P12V_AUX_CPU1_DIMM_ISEN_P")
	)
	(segment
		(start 7.97306 -169.31513)
		(end 8.21436 -169.55643)
		(width 0.254)
		(layer "B.Cu")
		(net "P12V_AUX_CPU1_DIMM_ISEN_P")
	)
	(segment
		(start 36.78174 -166.70528)
		(end 36.17341 -166.09695)
		(width 0.254)
		(layer "B.Cu")
		(net "P12V_AUX_CPU1_DIMM_ISEN_P")
	)
	(segment
		(start 11.513312 -173.419008)
		(end 32.81426 -173.419008)
		(width 0.254)
		(layer "B.Cu")
		(net "P12V_AUX_CPU1_DIMM_ISEN_P")
	)
	(segment
		(start 32.81426 -173.419008)
		(end 36.78174 -169.451528)
		(width 0.254)
		(layer "B.Cu")
		(net "P12V_AUX_CPU1_DIMM_ISEN_P")
	)
	(segment
		(start 8.21436 -170.120056)
		(end 11.513312 -173.419008)
		(width 0.254)
		(layer "B.Cu")
		(net "P12V_AUX_CPU1_DIMM_ISEN_P")
	)
	(segment
		(start 36.17341 -166.09695)
		(end 35.502088 -166.09695)
		(width 0.254)
		(layer "B.Cu")
		(net "P12V_AUX_CPU1_DIMM_ISEN_P")
	)
	(segment
		(start 4.86664 -334.371188)
		(end 4.86664 -194.351656)
		(width 0.254)
		(layer "In11.Cu")
		(net "P12V_AUX_CPU1_DIMM_ISEN_P")
	)
	(segment
		(start 8.21436 -169.55643)
		(end 7.97306 -169.31513)
		(width 0.254)
		(layer "In11.Cu")
		(net "P12V_AUX_CPU1_DIMM_ISEN_P")
	)
	(segment
		(start 14.056868 -338.216748)
		(end 13.131292 -338.216748)
		(width 0.254)
		(layer "In11.Cu")
		(net "P12V_AUX_CPU1_DIMM_ISEN_P")
	)
	(segment
		(start 7.00532 -192.212976)
		(end 7.00532 -173.185328)
		(width 0.254)
		(layer "In11.Cu")
		(net "P12V_AUX_CPU1_DIMM_ISEN_P")
	)
	(segment
		(start 16.59128 -336.311748)
		(end 16.41348 -336.133948)
		(width 0.254)
		(layer "In11.Cu")
		(net "P12V_AUX_CPU1_DIMM_ISEN_P")
	)
	(segment
		(start 16.59128 -336.800952)
		(end 16.59128 -336.311748)
		(width 0.254)
		(layer "In11.Cu")
		(net "P12V_AUX_CPU1_DIMM_ISEN_P")
	)
	(segment
		(start 7.00532 -173.185328)
		(end 8.21436 -171.976288)
		(width 0.254)
		(layer "In11.Cu")
		(net "P12V_AUX_CPU1_DIMM_ISEN_P")
	)
	(segment
		(start 16.57096 -336.821272)
		(end 16.59128 -336.800952)
		(width 0.254)
		(layer "In11.Cu")
		(net "P12V_AUX_CPU1_DIMM_ISEN_P")
	)
	(segment
		(start 16.41348 -336.133948)
		(end 16.139668 -336.133948)
		(width 0.254)
		(layer "In11.Cu")
		(net "P12V_AUX_CPU1_DIMM_ISEN_P")
	)
	(segment
		(start 12.567412 -337.652868)
		(end 8.14832 -337.652868)
		(width 0.254)
		(layer "In11.Cu")
		(net "P12V_AUX_CPU1_DIMM_ISEN_P")
	)
	(segment
		(start 13.131292 -338.216748)
		(end 12.567412 -337.652868)
		(width 0.254)
		(layer "In11.Cu")
		(net "P12V_AUX_CPU1_DIMM_ISEN_P")
	)
	(segment
		(start 16.139668 -336.133948)
		(end 14.056868 -338.216748)
		(width 0.254)
		(layer "In11.Cu")
		(net "P12V_AUX_CPU1_DIMM_ISEN_P")
	)
	(segment
		(start 8.21436 -171.976288)
		(end 8.21436 -169.55643)
		(width 0.254)
		(layer "In11.Cu")
		(net "P12V_AUX_CPU1_DIMM_ISEN_P")
	)
	(segment
		(start 8.14832 -337.652868)
		(end 4.86664 -334.371188)
		(width 0.254)
		(layer "In11.Cu")
		(net "P12V_AUX_CPU1_DIMM_ISEN_P")
	)
	(segment
		(start 4.86664 -194.351656)
		(end 7.00532 -192.212976)
		(width 0.254)
		(layer "In11.Cu")
		(net "P12V_AUX_CPU1_DIMM_ISEN_P")
	)
	(segment
		(start 21.44522 -333.205074)
		(end 21.44522 -335.557622)
		(width 0.254)
		(layer "F.Cu")
		(net "P12V_AUX_CPU1_DIMM_ISEN_N")
	)
	(segment
		(start 18.43151 -335.69783)
		(end 17.655032 -334.921352)
		(width 0.254)
		(layer "F.Cu")
		(net "P12V_AUX_CPU1_DIMM_ISEN_N")
	)
	(segment
		(start 21.305012 -335.69783)
		(end 18.43151 -335.69783)
		(width 0.254)
		(layer "F.Cu")
		(net "P12V_AUX_CPU1_DIMM_ISEN_N")
	)
	(segment
		(start 21.44522 -335.557622)
		(end 21.305012 -335.69783)
		(width 0.254)
		(layer "F.Cu")
		(net "P12V_AUX_CPU1_DIMM_ISEN_N")
	)
	(segment
		(start 17.655032 -334.921352)
		(end 16.6624 -334.921352)
		(width 0.254)
		(layer "F.Cu")
		(net "P12V_AUX_CPU1_DIMM_ISEN_N")
	)
	(via
		(at 16.6624 -334.921352)
		(size 0.508)
		(drill 0.254)
		(layers "F.Cu" "B.Cu")
		(net "P12V_AUX_CPU1_DIMM_ISEN_N")
	)
	(via
		(at 8.83666 -169.31513)
		(size 0.508)
		(drill 0.254)
		(layers "F.Cu" "B.Cu")
		(net "P12V_AUX_CPU1_DIMM_ISEN_N")
	)
	(segment
		(start 36.40074 -166.863268)
		(end 36.015422 -166.47795)
		(width 0.254)
		(layer "B.Cu")
		(net "P12V_AUX_CPU1_DIMM_ISEN_N")
	)
	(segment
		(start 32.656272 -173.038008)
		(end 36.40074 -169.29354)
		(width 0.254)
		(layer "B.Cu")
		(net "P12V_AUX_CPU1_DIMM_ISEN_N")
	)
	(segment
		(start 36.015422 -166.47795)
		(end 35.502088 -166.47795)
		(width 0.254)
		(layer "B.Cu")
		(net "P12V_AUX_CPU1_DIMM_ISEN_N")
	)
	(segment
		(start 35.502088 -166.47795)
		(end 35.246564 -166.733474)
		(width 0.254)
		(layer "B.Cu")
		(net "P12V_AUX_CPU1_DIMM_ISEN_N")
	)
	(segment
		(start 8.59536 -169.55643)
		(end 8.59536 -169.962068)
		(width 0.254)
		(layer "B.Cu")
		(net "P12V_AUX_CPU1_DIMM_ISEN_N")
	)
	(segment
		(start 8.83666 -169.31513)
		(end 8.59536 -169.55643)
		(width 0.254)
		(layer "B.Cu")
		(net "P12V_AUX_CPU1_DIMM_ISEN_N")
	)
	(segment
		(start 8.59536 -169.962068)
		(end 11.6713 -173.038008)
		(width 0.254)
		(layer "B.Cu")
		(net "P12V_AUX_CPU1_DIMM_ISEN_N")
	)
	(segment
		(start 36.40074 -169.29354)
		(end 36.40074 -166.863268)
		(width 0.254)
		(layer "B.Cu")
		(net "P12V_AUX_CPU1_DIMM_ISEN_N")
	)
	(segment
		(start 11.6713 -173.038008)
		(end 32.656272 -173.038008)
		(width 0.254)
		(layer "B.Cu")
		(net "P12V_AUX_CPU1_DIMM_ISEN_N")
	)
	(segment
		(start 8.306308 -337.271868)
		(end 5.24764 -334.2132)
		(width 0.254)
		(layer "In11.Cu")
		(net "P12V_AUX_CPU1_DIMM_ISEN_N")
	)
	(segment
		(start 8.59536 -169.55643)
		(end 8.83666 -169.31513)
		(width 0.254)
		(layer "In11.Cu")
		(net "P12V_AUX_CPU1_DIMM_ISEN_N")
	)
	(segment
		(start 5.24764 -194.509644)
		(end 7.38632 -192.370964)
		(width 0.254)
		(layer "In11.Cu")
		(net "P12V_AUX_CPU1_DIMM_ISEN_N")
	)
	(segment
		(start 13.89888 -337.835748)
		(end 13.28928 -337.835748)
		(width 0.254)
		(layer "In11.Cu")
		(net "P12V_AUX_CPU1_DIMM_ISEN_N")
	)
	(segment
		(start 16.38808 -335.752948)
		(end 15.98168 -335.752948)
		(width 0.254)
		(layer "In11.Cu")
		(net "P12V_AUX_CPU1_DIMM_ISEN_N")
	)
	(segment
		(start 7.38632 -192.370964)
		(end 7.38632 -173.343316)
		(width 0.254)
		(layer "In11.Cu")
		(net "P12V_AUX_CPU1_DIMM_ISEN_N")
	)
	(segment
		(start 7.38632 -173.343316)
		(end 8.59536 -172.134276)
		(width 0.254)
		(layer "In11.Cu")
		(net "P12V_AUX_CPU1_DIMM_ISEN_N")
	)
	(segment
		(start 8.59536 -172.134276)
		(end 8.59536 -169.55643)
		(width 0.254)
		(layer "In11.Cu")
		(net "P12V_AUX_CPU1_DIMM_ISEN_N")
	)
	(segment
		(start 12.7254 -337.271868)
		(end 8.306308 -337.271868)
		(width 0.254)
		(layer "In11.Cu")
		(net "P12V_AUX_CPU1_DIMM_ISEN_N")
	)
	(segment
		(start 13.28928 -337.835748)
		(end 12.7254 -337.271868)
		(width 0.254)
		(layer "In11.Cu")
		(net "P12V_AUX_CPU1_DIMM_ISEN_N")
	)
	(segment
		(start 16.6624 -335.478628)
		(end 16.38808 -335.752948)
		(width 0.254)
		(layer "In11.Cu")
		(net "P12V_AUX_CPU1_DIMM_ISEN_N")
	)
	(segment
		(start 16.6624 -334.921352)
		(end 16.6624 -335.478628)
		(width 0.254)
		(layer "In11.Cu")
		(net "P12V_AUX_CPU1_DIMM_ISEN_N")
	)
	(segment
		(start 5.24764 -334.2132)
		(end 5.24764 -194.509644)
		(width 0.254)
		(layer "In11.Cu")
		(net "P12V_AUX_CPU1_DIMM_ISEN_N")
	)
	(segment
		(start 15.98168 -335.752948)
		(end 13.89888 -337.835748)
		(width 0.254)
		(layer "In11.Cu")
		(net "P12V_AUX_CPU1_DIMM_ISEN_N")
	)
	(segment
		(start 449.350638 -335.583276)
		(end 449.178934 -335.411572)
		(width 0.254)
		(layer "F.Cu")
		(net "P12V_AUX_CPU0_DIMM_ISEN_P")
	)
	(segment
		(start 447.040508 -335.411572)
		(end 446.621408 -335.830672)
		(width 0.254)
		(layer "F.Cu")
		(net "P12V_AUX_CPU0_DIMM_ISEN_P")
	)
	(segment
		(start 449.178934 -335.411572)
		(end 447.040508 -335.411572)
		(width 0.254)
		(layer "F.Cu")
		(net "P12V_AUX_CPU0_DIMM_ISEN_P")
	)
	(segment
		(start 446.621408 -335.830672)
		(end 446.035176 -335.830672)
		(width 0.254)
		(layer "F.Cu")
		(net "P12V_AUX_CPU0_DIMM_ISEN_P")
	)
	(segment
		(start 445.694816 -336.171032)
		(end 445.33947 -336.171032)
		(width 0.254)
		(layer "F.Cu")
		(net "P12V_AUX_CPU0_DIMM_ISEN_P")
	)
	(segment
		(start 446.035176 -335.830672)
		(end 445.694816 -336.171032)
		(width 0.254)
		(layer "F.Cu")
		(net "P12V_AUX_CPU0_DIMM_ISEN_P")
	)
	(segment
		(start 449.350638 -338.160614)
		(end 449.350638 -335.583276)
		(width 0.254)
		(layer "F.Cu")
		(net "P12V_AUX_CPU0_DIMM_ISEN_P")
	)
	(via
		(at 446.621408 -335.830672)
		(size 0.508)
		(drill 0.254)
		(layers "F.Cu" "B.Cu")
		(net "P12V_AUX_CPU0_DIMM_ISEN_P")
	)
	(segment
		(start 465.76996 -323.867526)
		(end 464.151218 -325.486268)
		(width 0.254)
		(layer "B.Cu")
		(net "P12V_AUX_CPU0_DIMM_ISEN_P")
	)
	(segment
		(start 461.885538 -311.540906)
		(end 463.211926 -311.540906)
		(width 0.254)
		(layer "B.Cu")
		(net "P12V_AUX_CPU0_DIMM_ISEN_P")
	)
	(segment
		(start 456.561698 -187.492386)
		(end 459.861158 -190.791846)
		(width 0.254)
		(layer "B.Cu")
		(net "P12V_AUX_CPU0_DIMM_ISEN_P")
	)
	(segment
		(start 459.861158 -190.791846)
		(end 459.861158 -252.383798)
		(width 0.254)
		(layer "B.Cu")
		(net "P12V_AUX_CPU0_DIMM_ISEN_P")
	)
	(segment
		(start 447.480944 -123.035568)
		(end 447.480944 -137.30097)
		(width 0.254)
		(layer "B.Cu")
		(net "P12V_AUX_CPU0_DIMM_ISEN_P")
	)
	(segment
		(start 464.151218 -325.486268)
		(end 464.151218 -328.479912)
		(width 0.254)
		(layer "B.Cu")
		(net "P12V_AUX_CPU0_DIMM_ISEN_P")
	)
	(segment
		(start 459.861158 -252.383798)
		(end 459.49108 -252.753876)
		(width 0.254)
		(layer "B.Cu")
		(net "P12V_AUX_CPU0_DIMM_ISEN_P")
	)
	(segment
		(start 465.76996 -319.179448)
		(end 465.76996 -323.867526)
		(width 0.254)
		(layer "B.Cu")
		(net "P12V_AUX_CPU0_DIMM_ISEN_P")
	)
	(segment
		(start 456.561698 -171.537122)
		(end 456.561698 -187.492386)
		(width 0.254)
		(layer "B.Cu")
		(net "P12V_AUX_CPU0_DIMM_ISEN_P")
	)
	(segment
		(start 425.704 -118.23192)
		(end 429.357282 -114.578638)
		(width 0.254)
		(layer "B.Cu")
		(net "P12V_AUX_CPU0_DIMM_ISEN_P")
	)
	(segment
		(start 460.302102 -312.069988)
		(end 461.356456 -312.069988)
		(width 0.254)
		(layer "B.Cu")
		(net "P12V_AUX_CPU0_DIMM_ISEN_P")
	)
	(segment
		(start 459.49108 -255.626616)
		(end 459.8289 -255.964436)
		(width 0.254)
		(layer "B.Cu")
		(net "P12V_AUX_CPU0_DIMM_ISEN_P")
	)
	(segment
		(start 461.356456 -312.069988)
		(end 461.885538 -311.540906)
		(width 0.254)
		(layer "B.Cu")
		(net "P12V_AUX_CPU0_DIMM_ISEN_P")
	)
	(segment
		(start 429.357282 -114.578638)
		(end 439.024014 -114.578638)
		(width 0.254)
		(layer "B.Cu")
		(net "P12V_AUX_CPU0_DIMM_ISEN_P")
	)
	(segment
		(start 426.329602 -122.57786)
		(end 425.704 -121.952258)
		(width 0.254)
		(layer "B.Cu")
		(net "P12V_AUX_CPU0_DIMM_ISEN_P")
	)
	(segment
		(start 425.704 -121.952258)
		(end 425.704 -118.23192)
		(width 0.254)
		(layer "B.Cu")
		(net "P12V_AUX_CPU0_DIMM_ISEN_P")
	)
	(segment
		(start 463.211926 -311.540906)
		(end 463.818478 -312.147458)
		(width 0.254)
		(layer "B.Cu")
		(net "P12V_AUX_CPU0_DIMM_ISEN_P")
	)
	(segment
		(start 464.151218 -328.479912)
		(end 457.239878 -335.391252)
		(width 0.254)
		(layer "B.Cu")
		(net "P12V_AUX_CPU0_DIMM_ISEN_P")
	)
	(segment
		(start 453.60082 -168.576244)
		(end 456.561698 -171.537122)
		(width 0.254)
		(layer "B.Cu")
		(net "P12V_AUX_CPU0_DIMM_ISEN_P")
	)
	(segment
		(start 463.818478 -312.147458)
		(end 463.818478 -317.227966)
		(width 0.254)
		(layer "B.Cu")
		(net "P12V_AUX_CPU0_DIMM_ISEN_P")
	)
	(segment
		(start 439.024014 -114.578638)
		(end 447.480944 -123.035568)
		(width 0.254)
		(layer "B.Cu")
		(net "P12V_AUX_CPU0_DIMM_ISEN_P")
	)
	(segment
		(start 457.239878 -335.391252)
		(end 447.060828 -335.391252)
		(width 0.254)
		(layer "B.Cu")
		(net "P12V_AUX_CPU0_DIMM_ISEN_P")
	)
	(segment
		(start 459.8289 -311.596786)
		(end 460.302102 -312.069988)
		(width 0.254)
		(layer "B.Cu")
		(net "P12V_AUX_CPU0_DIMM_ISEN_P")
	)
	(segment
		(start 459.8289 -255.964436)
		(end 459.8289 -311.596786)
		(width 0.254)
		(layer "B.Cu")
		(net "P12V_AUX_CPU0_DIMM_ISEN_P")
	)
	(segment
		(start 463.818478 -317.227966)
		(end 465.76996 -319.179448)
		(width 0.254)
		(layer "B.Cu")
		(net "P12V_AUX_CPU0_DIMM_ISEN_P")
	)
	(segment
		(start 447.480944 -137.30097)
		(end 453.60082 -143.420846)
		(width 0.254)
		(layer "B.Cu")
		(net "P12V_AUX_CPU0_DIMM_ISEN_P")
	)
	(segment
		(start 453.60082 -143.420846)
		(end 453.60082 -168.576244)
		(width 0.254)
		(layer "B.Cu")
		(net "P12V_AUX_CPU0_DIMM_ISEN_P")
	)
	(segment
		(start 459.49108 -252.753876)
		(end 459.49108 -255.626616)
		(width 0.254)
		(layer "B.Cu")
		(net "P12V_AUX_CPU0_DIMM_ISEN_P")
	)
	(segment
		(start 447.060828 -335.391252)
		(end 446.621408 -335.830672)
		(width 0.254)
		(layer "B.Cu")
		(net "P12V_AUX_CPU0_DIMM_ISEN_P")
	)
	(segment
		(start 426.492162 -122.57786)
		(end 426.329602 -122.57786)
		(width 0.254)
		(layer "B.Cu")
		(net "P12V_AUX_CPU0_DIMM_ISEN_P")
	)
	(segment
		(start 449.20535 -335.030572)
		(end 447.040508 -335.030572)
		(width 0.254)
		(layer "F.Cu")
		(net "P12V_AUX_CPU0_DIMM_ISEN_N")
	)
	(segment
		(start 447.040508 -335.030572)
		(end 446.621408 -334.611472)
		(width 0.254)
		(layer "F.Cu")
		(net "P12V_AUX_CPU0_DIMM_ISEN_N")
	)
	(segment
		(start 449.350638 -332.760574)
		(end 449.350638 -334.885284)
		(width 0.254)
		(layer "F.Cu")
		(net "P12V_AUX_CPU0_DIMM_ISEN_N")
	)
	(segment
		(start 445.673734 -334.271112)
		(end 445.33947 -334.271112)
		(width 0.254)
		(layer "F.Cu")
		(net "P12V_AUX_CPU0_DIMM_ISEN_N")
	)
	(segment
		(start 446.621408 -334.611472)
		(end 446.014094 -334.611472)
		(width 0.254)
		(layer "F.Cu")
		(net "P12V_AUX_CPU0_DIMM_ISEN_N")
	)
	(segment
		(start 446.014094 -334.611472)
		(end 445.673734 -334.271112)
		(width 0.254)
		(layer "F.Cu")
		(net "P12V_AUX_CPU0_DIMM_ISEN_N")
	)
	(segment
		(start 449.350638 -334.885284)
		(end 449.20535 -335.030572)
		(width 0.254)
		(layer "F.Cu")
		(net "P12V_AUX_CPU0_DIMM_ISEN_N")
	)
	(via
		(at 446.621408 -334.611472)
		(size 0.508)
		(drill 0.254)
		(layers "F.Cu" "B.Cu")
		(net "P12V_AUX_CPU0_DIMM_ISEN_N")
	)
	(segment
		(start 429.51527 -114.959638)
		(end 438.866026 -114.959638)
		(width 0.254)
		(layer "B.Cu")
		(net "P12V_AUX_CPU0_DIMM_ISEN_N")
	)
	(segment
		(start 447.099944 -123.193556)
		(end 447.099944 -137.458958)
		(width 0.254)
		(layer "B.Cu")
		(net "P12V_AUX_CPU0_DIMM_ISEN_N")
	)
	(segment
		(start 459.11008 -255.784604)
		(end 459.4479 -256.122424)
		(width 0.254)
		(layer "B.Cu")
		(net "P12V_AUX_CPU0_DIMM_ISEN_N")
	)
	(segment
		(start 459.11008 -252.595888)
		(end 459.11008 -255.784604)
		(width 0.254)
		(layer "B.Cu")
		(net "P12V_AUX_CPU0_DIMM_ISEN_N")
	)
	(segment
		(start 447.099944 -137.458958)
		(end 453.21982 -143.578834)
		(width 0.254)
		(layer "B.Cu")
		(net "P12V_AUX_CPU0_DIMM_ISEN_N")
	)
	(segment
		(start 463.437478 -317.385954)
		(end 465.38896 -319.337436)
		(width 0.254)
		(layer "B.Cu")
		(net "P12V_AUX_CPU0_DIMM_ISEN_N")
	)
	(segment
		(start 453.21982 -168.734232)
		(end 456.180698 -171.69511)
		(width 0.254)
		(layer "B.Cu")
		(net "P12V_AUX_CPU0_DIMM_ISEN_N")
	)
	(segment
		(start 459.480158 -190.949834)
		(end 459.480158 -252.22581)
		(width 0.254)
		(layer "B.Cu")
		(net "P12V_AUX_CPU0_DIMM_ISEN_N")
	)
	(segment
		(start 426.08373 -118.391178)
		(end 429.51527 -114.959638)
		(width 0.254)
		(layer "B.Cu")
		(net "P12V_AUX_CPU0_DIMM_ISEN_N")
	)
	(segment
		(start 463.770218 -325.32828)
		(end 463.770218 -328.321924)
		(width 0.254)
		(layer "B.Cu")
		(net "P12V_AUX_CPU0_DIMM_ISEN_N")
	)
	(segment
		(start 463.770218 -328.321924)
		(end 457.08189 -335.010252)
		(width 0.254)
		(layer "B.Cu")
		(net "P12V_AUX_CPU0_DIMM_ISEN_N")
	)
	(segment
		(start 463.437478 -312.305446)
		(end 463.437478 -317.385954)
		(width 0.254)
		(layer "B.Cu")
		(net "P12V_AUX_CPU0_DIMM_ISEN_N")
	)
	(segment
		(start 426.08373 -121.446036)
		(end 426.08373 -118.391178)
		(width 0.254)
		(layer "B.Cu")
		(net "P12V_AUX_CPU0_DIMM_ISEN_N")
	)
	(segment
		(start 456.180698 -187.650374)
		(end 459.480158 -190.949834)
		(width 0.254)
		(layer "B.Cu")
		(net "P12V_AUX_CPU0_DIMM_ISEN_N")
	)
	(segment
		(start 426.323506 -121.685812)
		(end 426.08373 -121.446036)
		(width 0.254)
		(layer "B.Cu")
		(net "P12V_AUX_CPU0_DIMM_ISEN_N")
	)
	(segment
		(start 465.38896 -319.337436)
		(end 465.38896 -323.709538)
		(width 0.254)
		(layer "B.Cu")
		(net "P12V_AUX_CPU0_DIMM_ISEN_N")
	)
	(segment
		(start 453.21982 -143.578834)
		(end 453.21982 -168.734232)
		(width 0.254)
		(layer "B.Cu")
		(net "P12V_AUX_CPU0_DIMM_ISEN_N")
	)
	(segment
		(start 447.020188 -335.010252)
		(end 446.621408 -334.611472)
		(width 0.254)
		(layer "B.Cu")
		(net "P12V_AUX_CPU0_DIMM_ISEN_N")
	)
	(segment
		(start 438.866026 -114.959638)
		(end 447.099944 -123.193556)
		(width 0.254)
		(layer "B.Cu")
		(net "P12V_AUX_CPU0_DIMM_ISEN_N")
	)
	(segment
		(start 426.492162 -121.685812)
		(end 426.323506 -121.685812)
		(width 0.254)
		(layer "B.Cu")
		(net "P12V_AUX_CPU0_DIMM_ISEN_N")
	)
	(segment
		(start 461.514444 -312.450988)
		(end 462.043526 -311.921906)
		(width 0.254)
		(layer "B.Cu")
		(net "P12V_AUX_CPU0_DIMM_ISEN_N")
	)
	(segment
		(start 465.38896 -323.709538)
		(end 463.770218 -325.32828)
		(width 0.254)
		(layer "B.Cu")
		(net "P12V_AUX_CPU0_DIMM_ISEN_N")
	)
	(segment
		(start 456.180698 -171.69511)
		(end 456.180698 -187.650374)
		(width 0.254)
		(layer "B.Cu")
		(net "P12V_AUX_CPU0_DIMM_ISEN_N")
	)
	(segment
		(start 462.043526 -311.921906)
		(end 463.053938 -311.921906)
		(width 0.254)
		(layer "B.Cu")
		(net "P12V_AUX_CPU0_DIMM_ISEN_N")
	)
	(segment
		(start 459.4479 -256.122424)
		(end 459.4479 -311.754774)
		(width 0.254)
		(layer "B.Cu")
		(net "P12V_AUX_CPU0_DIMM_ISEN_N")
	)
	(segment
		(start 460.144114 -312.450988)
		(end 461.514444 -312.450988)
		(width 0.254)
		(layer "B.Cu")
		(net "P12V_AUX_CPU0_DIMM_ISEN_N")
	)
	(segment
		(start 457.08189 -335.010252)
		(end 447.020188 -335.010252)
		(width 0.254)
		(layer "B.Cu")
		(net "P12V_AUX_CPU0_DIMM_ISEN_N")
	)
	(segment
		(start 463.053938 -311.921906)
		(end 463.437478 -312.305446)
		(width 0.254)
		(layer "B.Cu")
		(net "P12V_AUX_CPU0_DIMM_ISEN_N")
	)
	(segment
		(start 459.4479 -311.754774)
		(end 460.144114 -312.450988)
		(width 0.254)
		(layer "B.Cu")
		(net "P12V_AUX_CPU0_DIMM_ISEN_N")
	)
	(segment
		(start 459.480158 -252.22581)
		(end 459.11008 -252.595888)
		(width 0.254)
		(layer "B.Cu")
		(net "P12V_AUX_CPU0_DIMM_ISEN_N")
	)
	(segment
		(start 182.50662 -416.11423)
		(end 182.50662 -417.63061)
		(width 0.381)
		(layer "F.Cu")
		(net "P12V_AUX")
	)
	(segment
		(start 204.724 -92.23375)
		(end 204.724 -91.5924)
		(width 0.381)
		(layer "F.Cu")
		(net "P12V_AUX")
	)
	(segment
		(start 212.20684 -113.47831)
		(end 212.19795 -113.4872)
		(width 0.381)
		(layer "F.Cu")
		(net "P12V_AUX")
	)
	(segment
		(start 212.19795 -113.4872)
		(end 211.5058 -113.4872)
		(width 0.381)
		(layer "F.Cu")
		(net "P12V_AUX")
	)
	(segment
		(start 220.487494 -101.24948)
		(end 221.1578 -101.24948)
		(width 0.381)
		(layer "F.Cu")
		(net "P12V_AUX")
	)
	(segment
		(start 444.3603 -74.640948)
		(end 444.627 -74.907648)
		(width 0.254)
		(layer "F.Cu")
		(net "P12V_AUX")
	)
	(segment
		(start 446.551558 -18.449798)
		(end 447.157602 -18.449798)
		(width 0.4572)
		(layer "F.Cu")
		(net "P12V_AUX")
	)
	(segment
		(start 288.980118 -395.046454)
		(end 288.980118 -392.569954)
		(width 0.4572)
		(layer "F.Cu")
		(net "P12V_AUX")
	)
	(segment
		(start 220.500702 -105.226104)
		(end 221.110302 -105.226104)
		(width 0.381)
		(layer "F.Cu")
		(net "P12V_AUX")
	)
	(segment
		(start 294.79113 -54.31409)
		(end 294.79113 -53.68798)
		(width 0.381)
		(layer "F.Cu")
		(net "P12V_AUX")
	)
	(segment
		(start 200.93305 -97.8662)
		(end 200.93305 -98.552)
		(width 0.381)
		(layer "F.Cu")
		(net "P12V_AUX")
	)
	(segment
		(start 184.793128 -23.113492)
		(end 185.399172 -23.113492)
		(width 0.4572)
		(layer "F.Cu")
		(net "P12V_AUX")
	)
	(segment
		(start 469.694514 -42.2783)
		(end 469.059514 -42.2783)
		(width 0.381)
		(layer "F.Cu")
		(net "P12V_AUX")
	)
	(segment
		(start 60.55995 -35.791648)
		(end 60.26785 -36.083748)
		(width 0.4572)
		(layer "F.Cu")
		(net "P12V_AUX")
	)
	(segment
		(start 308.8132 -28.2702)
		(end 308.57825 -28.2702)
		(width 0.381)
		(layer "F.Cu")
		(net "P12V_AUX")
	)
	(segment
		(start 288.980118 -395.046454)
		(end 288.980118 -395.73708)
		(width 0.381)
		(layer "F.Cu")
		(net "P12V_AUX")
	)
	(segment
		(start 190.02375 -42.554398)
		(end 189.41415 -42.554398)
		(width 0.381)
		(layer "F.Cu")
		(net "P12V_AUX")
	)
	(segment
		(start 201.53122 -97.26803)
		(end 202.19924 -97.26803)
		(width 0.381)
		(layer "F.Cu")
		(net "P12V_AUX")
	)
	(segment
		(start 446.548002 -18.446242)
		(end 446.551558 -18.449798)
		(width 0.4572)
		(layer "F.Cu")
		(net "P12V_AUX")
	)
	(segment
		(start 220.487494 -98.164904)
		(end 221.1578 -98.164904)
		(width 0.381)
		(layer "F.Cu")
		(net "P12V_AUX")
	)
	(segment
		(start 308.09565 -28.12542)
		(end 308.90591 -27.31516)
		(width 0.381)
		(layer "F.Cu")
		(net "P12V_AUX")
	)
	(segment
		(start 308.09565 -28.7528)
		(end 308.09565 -28.12542)
		(width 0.381)
		(layer "F.Cu")
		(net "P12V_AUX")
	)
	(segment
		(start 198.9963 -132.094478)
		(end 198.9963 -132.705348)
		(width 0.381)
		(layer "F.Cu")
		(net "P12V_AUX")
	)
	(segment
		(start 302.9458 -23.6728)
		(end 301.8028 -24.8158)
		(width 0.381)
		(layer "F.Cu")
		(net "P12V_AUX")
	)
	(segment
		(start 301.8028 -25.4508)
		(end 301.9298 -25.5778)
		(width 0.381)
		(layer "F.Cu")
		(net "P12V_AUX")
	)
	(segment
		(start 250.30303 -45.985176)
		(end 250.30303 -45.379132)
		(width 0.4572)
		(layer "F.Cu")
		(net "P12V_AUX")
	)
	(segment
		(start 212.20684 -111.96701)
		(end 212.20684 -113.47831)
		(width 0.381)
		(layer "F.Cu")
		(net "P12V_AUX")
	)
	(segment
		(start 74.407268 -18.160746)
		(end 74.410824 -18.164302)
		(width 0.4572)
		(layer "F.Cu")
		(net "P12V_AUX")
	)
	(segment
		(start 178.942238 -406.898602)
		(end 178.942238 -406.127458)
		(width 0.381)
		(layer "F.Cu")
		(net "P12V_AUX")
	)
	(segment
		(start 209.34553 -130.830828)
		(end 208.71688 -130.830828)
		(width 0.381)
		(layer "F.Cu")
		(net "P12V_AUX")
	)
	(segment
		(start 210.160362 -98.809048)
		(end 209.550762 -98.809048)
		(width 0.381)
		(layer "F.Cu")
		(net "P12V_AUX")
	)
	(segment
		(start 369.7224 -74.74585)
		(end 369.7224 -75.4888)
		(width 0.381)
		(layer "F.Cu")
		(net "P12V_AUX")
	)
	(segment
		(start 294.80002 -54.32298)
		(end 294.79113 -54.31409)
		(width 0.381)
		(layer "F.Cu")
		(net "P12V_AUX")
	)
	(segment
		(start 206.45374 -131.268978)
		(end 207.1751 -131.268978)
		(width 0.381)
		(layer "F.Cu")
		(net "P12V_AUX")
	)
	(segment
		(start 301.8028 -24.8158)
		(end 301.8028 -25.4508)
		(width 0.381)
		(layer "F.Cu")
		(net "P12V_AUX")
	)
	(segment
		(start 291.79393 -53.652674)
		(end 291.79393 -54.287674)
		(width 0.381)
		(layer "F.Cu")
		(net "P12V_AUX")
	)
	(segment
		(start 444.627 -75.428348)
		(end 445.135 -74.920348)
		(width 0.254)
		(layer "F.Cu")
		(net "P12V_AUX")
	)
	(segment
		(start 250.299474 -45.988732)
		(end 250.30303 -45.985176)
		(width 0.4572)
		(layer "F.Cu")
		(net "P12V_AUX")
	)
	(segment
		(start 74.410824 -18.164302)
		(end 75.016868 -18.164302)
		(width 0.4572)
		(layer "F.Cu")
		(net "P12V_AUX")
	)
	(segment
		(start 164.29101 -130.926586)
		(end 164.29101 -131.565396)
		(width 0.381)
		(layer "F.Cu")
		(net "P12V_AUX")
	)
	(segment
		(start 64.708024 -39.808658)
		(end 65.343024 -39.808658)
		(width 0.381)
		(layer "F.Cu")
		(net "P12V_AUX")
	)
	(segment
		(start 303.58715 -23.6728)
		(end 302.9458 -23.6728)
		(width 0.381)
		(layer "F.Cu")
		(net "P12V_AUX")
	)
	(segment
		(start 445.625728 -74.277474)
		(end 446.068958 -74.277474)
		(width 0.254)
		(layer "F.Cu")
		(net "P12V_AUX")
	)
	(segment
		(start 46.982634 -112.619282)
		(end 47.592234 -112.619282)
		(width 0.3556)
		(layer "F.Cu")
		(net "P12V_AUX")
	)
	(segment
		(start 445.135 -74.920348)
		(end 445.135 -74.768202)
		(width 0.254)
		(layer "F.Cu")
		(net "P12V_AUX")
	)
	(segment
		(start 463.743548 -43.221148)
		(end 463.743548 -42.586148)
		(width 0.381)
		(layer "F.Cu")
		(net "P12V_AUX")
	)
	(segment
		(start 165.31463 -134.17677)
		(end 164.667184 -134.17677)
		(width 0.381)
		(layer "F.Cu")
		(net "P12V_AUX")
	)
	(segment
		(start 182.50662 -417.63061)
		(end 182.42153 -417.7157)
		(width 0.381)
		(layer "F.Cu")
		(net "P12V_AUX")
	)
	(segment
		(start 182.42153 -417.7157)
		(end 182.42153 -418.4142)
		(width 0.381)
		(layer "F.Cu")
		(net "P12V_AUX")
	)
	(segment
		(start 445.135 -74.768202)
		(end 445.625728 -74.277474)
		(width 0.254)
		(layer "F.Cu")
		(net "P12V_AUX")
	)
	(segment
		(start 308.90591 -27.31516)
		(end 309.75681 -27.31516)
		(width 0.381)
		(layer "F.Cu")
		(net "P12V_AUX")
	)
	(segment
		(start 200.93305 -97.8662)
		(end 201.53122 -97.26803)
		(width 0.381)
		(layer "F.Cu")
		(net "P12V_AUX")
	)
	(segment
		(start 444.627 -74.907648)
		(end 444.627 -75.428348)
		(width 0.254)
		(layer "F.Cu")
		(net "P12V_AUX")
	)
	(segment
		(start 308.57825 -28.2702)
		(end 308.09565 -28.7528)
		(width 0.381)
		(layer "F.Cu")
		(net "P12V_AUX")
	)
	(segment
		(start 184.789572 -23.109936)
		(end 184.793128 -23.113492)
		(width 0.4572)
		(layer "F.Cu")
		(net "P12V_AUX")
	)
	(segment
		(start 61.948568 -35.791648)
		(end 60.55995 -35.791648)
		(width 0.4572)
		(layer "F.Cu")
		(net "P12V_AUX")
	)
	(segment
		(start 212.4202 -107.01655)
		(end 212.4202 -106.3752)
		(width 0.381)
		(layer "F.Cu")
		(net "P12V_AUX")
	)
	(via
		(at 287.995614 -370.955062)
		(size 0.508)
		(drill 0.254)
		(layers "F.Cu" "B.Cu")
		(net "P12V_AUX")
	)
	(via
		(at 286.598614 -373.749062)
		(size 0.508)
		(drill 0.254)
		(layers "F.Cu" "B.Cu")
		(net "P12V_AUX")
	)
	(via
		(at 177.443892 -29.255212)
		(size 0.4572)
		(drill 0.254)
		(layers "F.Cu" "B.Cu")
		(net "P12V_AUX")
	)
	(via
		(at 199.225408 -396.822422)
		(size 0.508)
		(drill 0.254)
		(layers "F.Cu" "B.Cu")
		(net "P12V_AUX")
	)
	(via
		(at 263.981692 -394.020548)
		(size 0.508)
		(drill 0.254)
		(layers "F.Cu" "B.Cu")
		(net "P12V_AUX")
	)
	(via
		(at 463.32013 -58.783982)
		(size 0.508)
		(drill 0.254)
		(layers "F.Cu" "B.Cu")
		(net "P12V_AUX")
	)
	(via
		(at 190.077344 -398.358614)
		(size 0.508)
		(drill 0.254)
		(layers "F.Cu" "B.Cu")
		(net "P12V_AUX")
	)
	(via
		(at 203.035408 -396.060422)
		(size 0.508)
		(drill 0.254)
		(layers "F.Cu" "B.Cu")
		(net "P12V_AUX")
	)
	(via
		(at 253.508764 -390.972548)
		(size 0.508)
		(drill 0.254)
		(layers "F.Cu" "B.Cu")
		(net "P12V_AUX")
	)
	(via
		(at 263.981692 -392.496548)
		(size 0.508)
		(drill 0.254)
		(layers "F.Cu" "B.Cu")
		(net "P12V_AUX")
	)
	(via
		(at 26.005536 -128.364996)
		(size 0.508)
		(drill 0.254)
		(layers "F.Cu" "B.Cu")
		(net "P12V_AUX")
	)
	(via
		(at 61.948568 -35.791648)
		(size 0.508)
		(drill 0.254)
		(layers "F.Cu" "B.Cu")
		(net "P12V_AUX")
	)
	(via
		(at 275.80082 -391.734548)
		(size 0.508)
		(drill 0.254)
		(layers "F.Cu" "B.Cu")
		(net "P12V_AUX")
	)
	(via
		(at 199.987408 -396.822422)
		(size 0.508)
		(drill 0.254)
		(layers "F.Cu" "B.Cu")
		(net "P12V_AUX")
	)
	(via
		(at 45.464222 -146.75866)
		(size 0.508)
		(drill 0.254)
		(layers "F.Cu" "B.Cu")
		(net "P12V_AUX")
	)
	(via
		(at 392.599672 -77.537564)
		(size 0.508)
		(drill 0.254)
		(layers "F.Cu" "B.Cu")
		(net "P12V_AUX")
	)
	(via
		(at 90.25255 -360.016044)
		(size 0.508)
		(drill 0.254)
		(layers "F.Cu" "B.Cu")
		(net "P12V_AUX")
	)
	(via
		(at 335.867248 -361.954572)
		(size 0.508)
		(drill 0.254)
		(layers "F.Cu" "B.Cu")
		(net "P12V_AUX")
	)
	(via
		(at 207.1751 -131.268978)
		(size 0.508)
		(drill 0.254)
		(layers "F.Cu" "B.Cu")
		(net "P12V_AUX")
	)
	(via
		(at 213.703408 -399.108422)
		(size 0.508)
		(drill 0.254)
		(layers "F.Cu" "B.Cu")
		(net "P12V_AUX")
	)
	(via
		(at 466.06333 -57.488582)
		(size 0.508)
		(drill 0.254)
		(layers "F.Cu" "B.Cu")
		(net "P12V_AUX")
	)
	(via
		(at 210.655408 -398.346422)
		(size 0.508)
		(drill 0.254)
		(layers "F.Cu" "B.Cu")
		(net "P12V_AUX")
	)
	(via
		(at 188.553344 -397.596614)
		(size 0.508)
		(drill 0.254)
		(layers "F.Cu" "B.Cu")
		(net "P12V_AUX")
	)
	(via
		(at 464.74253 -59.418982)
		(size 0.508)
		(drill 0.254)
		(layers "F.Cu" "B.Cu")
		(net "P12V_AUX")
	)
	(via
		(at 234.277408 -396.822422)
		(size 0.508)
		(drill 0.254)
		(layers "F.Cu" "B.Cu")
		(net "P12V_AUX")
	)
	(via
		(at 240.78692 -391.73404)
		(size 0.508)
		(drill 0.254)
		(layers "F.Cu" "B.Cu")
		(net "P12V_AUX")
	)
	(via
		(at 201.511408 -396.822422)
		(size 0.508)
		(drill 0.254)
		(layers "F.Cu" "B.Cu")
		(net "P12V_AUX")
	)
	(via
		(at 278.01062 -391.734548)
		(size 0.508)
		(drill 0.254)
		(layers "F.Cu" "B.Cu")
		(net "P12V_AUX")
	)
	(via
		(at 301.9298 -25.5778)
		(size 0.508)
		(drill 0.254)
		(layers "F.Cu" "B.Cu")
		(net "P12V_AUX")
	)
	(via
		(at 252.746764 -391.734548)
		(size 0.508)
		(drill 0.254)
		(layers "F.Cu" "B.Cu")
		(net "P12V_AUX")
	)
	(via
		(at 272.075656 -393.258548)
		(size 0.508)
		(drill 0.254)
		(layers "F.Cu" "B.Cu")
		(net "P12V_AUX")
	)
	(via
		(at 231.991408 -398.346422)
		(size 0.508)
		(drill 0.254)
		(layers "F.Cu" "B.Cu")
		(net "P12V_AUX")
	)
	(via
		(at 465.40293 -58.148982)
		(size 0.508)
		(drill 0.254)
		(layers "F.Cu" "B.Cu")
		(net "P12V_AUX")
	)
	(via
		(at 190.000382 -29.537152)
		(size 0.508)
		(drill 0.254)
		(layers "F.Cu" "B.Cu")
		(net "P12V_AUX")
	)
	(via
		(at 92.634562 -359.309924)
		(size 0.508)
		(drill 0.254)
		(layers "F.Cu" "B.Cu")
		(net "P12V_AUX")
	)
	(via
		(at 199.987408 -399.870422)
		(size 0.508)
		(drill 0.254)
		(layers "F.Cu" "B.Cu")
		(net "P12V_AUX")
	)
	(via
		(at 213.703408 -399.870422)
		(size 0.508)
		(drill 0.254)
		(layers "F.Cu" "B.Cu")
		(net "P12V_AUX")
	)
	(via
		(at 22.303486 -341.690452)
		(size 0.508)
		(drill 0.254)
		(layers "F.Cu" "B.Cu")
		(net "P12V_AUX")
	)
	(via
		(at 453.346566 -340.473792)
		(size 0.508)
		(drill 0.254)
		(layers "F.Cu" "B.Cu")
		(net "P12V_AUX")
	)
	(via
		(at 254.956564 -390.972548)
		(size 0.508)
		(drill 0.254)
		(layers "F.Cu" "B.Cu")
		(net "P12V_AUX")
	)
	(via
		(at 96.47555 -356.206044)
		(size 0.508)
		(drill 0.254)
		(layers "F.Cu" "B.Cu")
		(net "P12V_AUX")
	)
	(via
		(at 248.90476 -73.599548)
		(size 0.508)
		(drill 0.254)
		(layers "F.Cu" "B.Cu")
		(net "P12V_AUX")
	)
	(via
		(at 450.298566 -341.210392)
		(size 0.508)
		(drill 0.254)
		(layers "F.Cu" "B.Cu")
		(net "P12V_AUX")
	)
	(via
		(at 242.31092 -392.49604)
		(size 0.508)
		(drill 0.254)
		(layers "F.Cu" "B.Cu")
		(net "P12V_AUX")
	)
	(via
		(at 182.862982 -31.619952)
		(size 0.508)
		(drill 0.254)
		(layers "F.Cu" "B.Cu")
		(net "P12V_AUX")
	)
	(via
		(at 339.685376 -359.271824)
		(size 0.508)
		(drill 0.254)
		(layers "F.Cu" "B.Cu")
		(net "P12V_AUX")
	)
	(via
		(at 277.24862 -390.972548)
		(size 0.508)
		(drill 0.254)
		(layers "F.Cu" "B.Cu")
		(net "P12V_AUX")
	)
	(via
		(at 272.075656 -391.734548)
		(size 0.508)
		(drill 0.254)
		(layers "F.Cu" "B.Cu")
		(net "P12V_AUX")
	)
	(via
		(at 453.346566 -338.619592)
		(size 0.508)
		(drill 0.254)
		(layers "F.Cu" "B.Cu")
		(net "P12V_AUX")
	)
	(via
		(at 39.37762 -362.997496)
		(size 0.508)
		(drill 0.254)
		(layers "F.Cu" "B.Cu")
		(net "P12V_AUX")
	)
	(via
		(at 451.822566 -338.619592)
		(size 0.508)
		(drill 0.254)
		(layers "F.Cu" "B.Cu")
		(net "P12V_AUX")
	)
	(via
		(at 172.987462 -26.585672)
		(size 0.508)
		(drill 0.254)
		(layers "F.Cu" "B.Cu")
		(net "P12V_AUX")
	)
	(via
		(at 452.584566 -336.409792)
		(size 0.508)
		(drill 0.254)
		(layers "F.Cu" "B.Cu")
		(net "P12V_AUX")
	)
	(via
		(at 337.314032 -360.68508)
		(size 0.508)
		(drill 0.254)
		(layers "F.Cu" "B.Cu")
		(net "P12V_AUX")
	)
	(via
		(at 48.080422 -146.098006)
		(size 0.508)
		(drill 0.254)
		(layers "F.Cu" "B.Cu")
		(net "P12V_AUX")
	)
	(via
		(at 234.277408 -398.346422)
		(size 0.508)
		(drill 0.254)
		(layers "F.Cu" "B.Cu")
		(net "P12V_AUX")
	)
	(via
		(at 221.110302 -105.226104)
		(size 0.508)
		(drill 0.254)
		(layers "F.Cu" "B.Cu")
		(net "P12V_AUX")
	)
	(via
		(at 170.471846 -364.273846)
		(size 0.508)
		(drill 0.254)
		(layers "F.Cu" "B.Cu")
		(net "P12V_AUX")
	)
	(via
		(at 431.368708 -167.09136)
		(size 0.508)
		(drill 0.254)
		(layers "F.Cu" "B.Cu")
		(net "P12V_AUX")
	)
	(via
		(at 252.086364 -393.258548)
		(size 0.508)
		(drill 0.254)
		(layers "F.Cu" "B.Cu")
		(net "P12V_AUX")
	)
	(via
		(at 233.515408 -396.060422)
		(size 0.508)
		(drill 0.254)
		(layers "F.Cu" "B.Cu")
		(net "P12V_AUX")
	)
	(via
		(at 392.625072 -76.902564)
		(size 0.508)
		(drill 0.254)
		(layers "F.Cu" "B.Cu")
		(net "P12V_AUX")
	)
	(via
		(at 252.746764 -394.782548)
		(size 0.508)
		(drill 0.254)
		(layers "F.Cu" "B.Cu")
		(net "P12V_AUX")
	)
	(via
		(at 270.551656 -390.210548)
		(size 0.508)
		(drill 0.254)
		(layers "F.Cu" "B.Cu")
		(net "P12V_AUX")
	)
	(via
		(at 287.233614 -370.955062)
		(size 0.508)
		(drill 0.254)
		(layers "F.Cu" "B.Cu")
		(net "P12V_AUX")
	)
	(via
		(at 249.0216 -392.496548)
		(size 0.508)
		(drill 0.254)
		(layers "F.Cu" "B.Cu")
		(net "P12V_AUX")
	)
	(via
		(at 266.826492 -390.210548)
		(size 0.508)
		(drill 0.254)
		(layers "F.Cu" "B.Cu")
		(net "P12V_AUX")
	)
	(via
		(at 287.995614 -371.590062)
		(size 0.508)
		(drill 0.254)
		(layers "F.Cu" "B.Cu")
		(net "P12V_AUX")
	)
	(via
		(at 48.080422 -146.75866)
		(size 0.508)
		(drill 0.254)
		(layers "F.Cu" "B.Cu")
		(net "P12V_AUX")
	)
	(via
		(at 186.267344 -396.834614)
		(size 0.508)
		(drill 0.254)
		(layers "F.Cu" "B.Cu")
		(net "P12V_AUX")
	)
	(via
		(at 338.024216 -357.768144)
		(size 0.508)
		(drill 0.254)
		(layers "F.Cu" "B.Cu")
		(net "P12V_AUX")
	)
	(via
		(at 338.934044 -360.68508)
		(size 0.508)
		(drill 0.254)
		(layers "F.Cu" "B.Cu")
		(net "P12V_AUX")
	)
	(via
		(at 253.508764 -391.734548)
		(size 0.508)
		(drill 0.254)
		(layers "F.Cu" "B.Cu")
		(net "P12V_AUX")
	)
	(via
		(at 90.25255 -358.492044)
		(size 0.508)
		(drill 0.254)
		(layers "F.Cu" "B.Cu")
		(net "P12V_AUX")
	)
	(via
		(at 20.779486 -340.420452)
		(size 0.508)
		(drill 0.254)
		(layers "F.Cu" "B.Cu")
		(net "P12V_AUX")
	)
	(via
		(at 451.822566 -344.108532)
		(size 0.508)
		(drill 0.254)
		(layers "F.Cu" "B.Cu")
		(net "P12V_AUX")
	)
	(via
		(at 183.675782 -31.619952)
		(size 0.508)
		(drill 0.254)
		(layers "F.Cu" "B.Cu")
		(net "P12V_AUX")
	)
	(via
		(at 40.01262 -363.759496)
		(size 0.508)
		(drill 0.254)
		(layers "F.Cu" "B.Cu")
		(net "P12V_AUX")
	)
	(via
		(at 263.981692 -393.258548)
		(size 0.508)
		(drill 0.254)
		(layers "F.Cu" "B.Cu")
		(net "P12V_AUX")
	)
	(via
		(at 464.696556 -381.204978)
		(size 0.508)
		(drill 0.254)
		(layers "F.Cu" "B.Cu")
		(net "P12V_AUX")
	)
	(via
		(at 437.646572 -25.823418)
		(size 0.508)
		(drill 0.254)
		(layers "F.Cu" "B.Cu")
		(net "P12V_AUX")
	)
	(via
		(at 235.039408 -398.346422)
		(size 0.508)
		(drill 0.254)
		(layers "F.Cu" "B.Cu")
		(net "P12V_AUX")
	)
	(via
		(at 88.807544 -355.498654)
		(size 0.508)
		(drill 0.254)
		(layers "F.Cu" "B.Cu")
		(net "P12V_AUX")
	)
	(via
		(at 259.489448 -390.210548)
		(size 0.508)
		(drill 0.254)
		(layers "F.Cu" "B.Cu")
		(net "P12V_AUX")
	)
	(via
		(at 89.589102 -355.431344)
		(size 0.508)
		(drill 0.254)
		(layers "F.Cu" "B.Cu")
		(net "P12V_AUX")
	)
	(via
		(at 46.785022 -145.463006)
		(size 0.508)
		(drill 0.254)
		(layers "F.Cu" "B.Cu")
		(net "P12V_AUX")
	)
	(via
		(at 89.509854 -359.265728)
		(size 0.508)
		(drill 0.254)
		(layers "F.Cu" "B.Cu")
		(net "P12V_AUX")
	)
	(via
		(at 198.463408 -399.870422)
		(size 0.508)
		(drill 0.254)
		(layers "F.Cu" "B.Cu")
		(net "P12V_AUX")
	)
	(via
		(at 276.48662 -390.210548)
		(size 0.508)
		(drill 0.254)
		(layers "F.Cu" "B.Cu")
		(net "P12V_AUX")
	)
	(via
		(at 246.126 -394.020548)
		(size 0.508)
		(drill 0.254)
		(layers "F.Cu" "B.Cu")
		(net "P12V_AUX")
	)
	(via
		(at 451.060566 -341.946992)
		(size 0.508)
		(drill 0.254)
		(layers "F.Cu" "B.Cu")
		(net "P12V_AUX")
	)
	(via
		(at 18.548858 -342.37295)
		(size 0.508)
		(drill 0.254)
		(layers "F.Cu" "B.Cu")
		(net "P12V_AUX")
	)
	(via
		(at 289.964114 -370.929662)
		(size 0.508)
		(drill 0.254)
		(layers "F.Cu" "B.Cu")
		(net "P12V_AUX")
	)
	(via
		(at 272.075656 -394.782548)
		(size 0.508)
		(drill 0.254)
		(layers "F.Cu" "B.Cu")
		(net "P12V_AUX")
	)
	(via
		(at 271.313656 -391.734548)
		(size 0.508)
		(drill 0.254)
		(layers "F.Cu" "B.Cu")
		(net "P12V_AUX")
	)
	(via
		(at 231.991408 -396.822422)
		(size 0.508)
		(drill 0.254)
		(layers "F.Cu" "B.Cu")
		(net "P12V_AUX")
	)
	(via
		(at 19.280886 -340.979252)
		(size 0.508)
		(drill 0.254)
		(layers "F.Cu" "B.Cu")
		(net "P12V_AUX")
	)
	(via
		(at 253.508764 -394.020548)
		(size 0.508)
		(drill 0.254)
		(layers "F.Cu" "B.Cu")
		(net "P12V_AUX")
	)
	(via
		(at 94.920562 -356.206044)
		(size 0.508)
		(drill 0.254)
		(layers "F.Cu" "B.Cu")
		(net "P12V_AUX")
	)
	(via
		(at 176.54397 -28.620212)
		(size 0.4572)
		(drill 0.254)
		(layers "F.Cu" "B.Cu")
		(net "P12V_AUX")
	)
	(via
		(at 272.761456 -392.496548)
		(size 0.508)
		(drill 0.254)
		(layers "F.Cu" "B.Cu")
		(net "P12V_AUX")
	)
	(via
		(at 202.273408 -399.870422)
		(size 0.508)
		(drill 0.254)
		(layers "F.Cu" "B.Cu")
		(net "P12V_AUX")
	)
	(via
		(at 93.396562 -360.016044)
		(size 0.508)
		(drill 0.254)
		(layers "F.Cu" "B.Cu")
		(net "P12V_AUX")
	)
	(via
		(at 338.024216 -358.530144)
		(size 0.508)
		(drill 0.254)
		(layers "F.Cu" "B.Cu")
		(net "P12V_AUX")
	)
	(via
		(at 254.270764 -394.782548)
		(size 0.508)
		(drill 0.254)
		(layers "F.Cu" "B.Cu")
		(net "P12V_AUX")
	)
	(via
		(at 451.822566 -339.737192)
		(size 0.508)
		(drill 0.254)
		(layers "F.Cu" "B.Cu")
		(net "P12V_AUX")
	)
	(via
		(at 260.911848 -390.972548)
		(size 0.508)
		(drill 0.254)
		(layers "F.Cu" "B.Cu")
		(net "P12V_AUX")
	)
	(via
		(at 258.5212 -47.065946)
		(size 0.508)
		(drill 0.254)
		(layers "F.Cu" "B.Cu")
		(net "P12V_AUX")
	)
	(via
		(at 451.822566 -341.210392)
		(size 0.508)
		(drill 0.254)
		(layers "F.Cu" "B.Cu")
		(net "P12V_AUX")
	)
	(via
		(at 241.54892 -392.49604)
		(size 0.508)
		(drill 0.254)
		(layers "F.Cu" "B.Cu")
		(net "P12V_AUX")
	)
	(via
		(at 340.437216 -356.866444)
		(size 0.508)
		(drill 0.254)
		(layers "F.Cu" "B.Cu")
		(net "P12V_AUX")
	)
	(via
		(at 466.82533 -58.783982)
		(size 0.508)
		(drill 0.254)
		(layers "F.Cu" "B.Cu")
		(net "P12V_AUX")
	)
	(via
		(at 335.85658 -361.303316)
		(size 0.508)
		(drill 0.254)
		(layers "F.Cu" "B.Cu")
		(net "P12V_AUX")
	)
	(via
		(at 453.181212 -28.937458)
		(size 0.508)
		(drill 0.254)
		(layers "F.Cu" "B.Cu")
		(net "P12V_AUX")
	)
	(via
		(at 342.764364 -358.509824)
		(size 0.508)
		(drill 0.254)
		(layers "F.Cu" "B.Cu")
		(net "P12V_AUX")
	)
	(via
		(at 40.77462 -362.997496)
		(size 0.508)
		(drill 0.254)
		(layers "F.Cu" "B.Cu")
		(net "P12V_AUX")
	)
	(via
		(at 339.706712 -361.336336)
		(size 0.508)
		(drill 0.254)
		(layers "F.Cu" "B.Cu")
		(net "P12V_AUX")
	)
	(via
		(at 265.378692 -392.496548)
		(size 0.508)
		(drill 0.254)
		(layers "F.Cu" "B.Cu")
		(net "P12V_AUX")
	)
	(via
		(at 224.371408 -399.108422)
		(size 0.508)
		(drill 0.254)
		(layers "F.Cu" "B.Cu")
		(net "P12V_AUX")
	)
	(via
		(at 265.378692 -390.210548)
		(size 0.508)
		(drill 0.254)
		(layers "F.Cu" "B.Cu")
		(net "P12V_AUX")
	)
	(via
		(at 241.54892 -394.78204)
		(size 0.508)
		(drill 0.254)
		(layers "F.Cu" "B.Cu")
		(net "P12V_AUX")
	)
	(via
		(at 431.350928 -165.1)
		(size 0.508)
		(drill 0.254)
		(layers "F.Cu" "B.Cu")
		(net "P12V_AUX")
	)
	(via
		(at 246.8118 -390.210548)
		(size 0.508)
		(drill 0.254)
		(layers "F.Cu" "B.Cu")
		(net "P12V_AUX")
	)
	(via
		(at 219.799408 -399.108422)
		(size 0.508)
		(drill 0.254)
		(layers "F.Cu" "B.Cu")
		(net "P12V_AUX")
	)
	(via
		(at 203.035408 -399.108422)
		(size 0.508)
		(drill 0.254)
		(layers "F.Cu" "B.Cu")
		(net "P12V_AUX")
	)
	(via
		(at 79.592678 -22.733762)
		(size 0.508)
		(drill 0.254)
		(layers "F.Cu" "B.Cu")
		(net "P12V_AUX")
	)
	(via
		(at 212.941408 -399.108422)
		(size 0.508)
		(drill 0.254)
		(layers "F.Cu" "B.Cu")
		(net "P12V_AUX")
	)
	(via
		(at 277.24862 -394.782548)
		(size 0.508)
		(drill 0.254)
		(layers "F.Cu" "B.Cu")
		(net "P12V_AUX")
	)
	(via
		(at 270.551656 -392.496548)
		(size 0.508)
		(drill 0.254)
		(layers "F.Cu" "B.Cu")
		(net "P12V_AUX")
	)
	(via
		(at 190.077344 -397.596614)
		(size 0.508)
		(drill 0.254)
		(layers "F.Cu" "B.Cu")
		(net "P12V_AUX")
	)
	(via
		(at 342.775032 -360.68508)
		(size 0.508)
		(drill 0.254)
		(layers "F.Cu" "B.Cu")
		(net "P12V_AUX")
	)
	(via
		(at 340.437216 -356.104444)
		(size 0.508)
		(drill 0.254)
		(layers "F.Cu" "B.Cu")
		(net "P12V_AUX")
	)
	(via
		(at 249.0216 -390.972548)
		(size 0.508)
		(drill 0.254)
		(layers "F.Cu" "B.Cu")
		(net "P12V_AUX")
	)
	(via
		(at 342.716612 -361.359196)
		(size 0.508)
		(drill 0.254)
		(layers "F.Cu" "B.Cu")
		(net "P12V_AUX")
	)
	(via
		(at 96.47555 -356.968044)
		(size 0.508)
		(drill 0.254)
		(layers "F.Cu" "B.Cu")
		(net "P12V_AUX")
	)
	(via
		(at 442.103002 -28.492958)
		(size 0.4572)
		(drill 0.254)
		(layers "F.Cu" "B.Cu")
		(net "P12V_AUX")
	)
	(via
		(at 43.508422 -146.098006)
		(size 0.508)
		(drill 0.254)
		(layers "F.Cu" "B.Cu")
		(net "P12V_AUX")
	)
	(via
		(at 241.54892 -394.02004)
		(size 0.508)
		(drill 0.254)
		(layers "F.Cu" "B.Cu")
		(net "P12V_AUX")
	)
	(via
		(at 190.839344 -396.072614)
		(size 0.508)
		(drill 0.254)
		(layers "F.Cu" "B.Cu")
		(net "P12V_AUX")
	)
	(via
		(at 188.553344 -396.072614)
		(size 0.508)
		(drill 0.254)
		(layers "F.Cu" "B.Cu")
		(net "P12V_AUX")
	)
	(via
		(at 221.1578 -101.24948)
		(size 0.508)
		(drill 0.254)
		(layers "F.Cu" "B.Cu")
		(net "P12V_AUX")
	)
	(via
		(at 40.01262 -361.727496)
		(size 0.508)
		(drill 0.254)
		(layers "F.Cu" "B.Cu")
		(net "P12V_AUX")
	)
	(via
		(at 266.140692 -394.782548)
		(size 0.508)
		(drill 0.254)
		(layers "F.Cu" "B.Cu")
		(net "P12V_AUX")
	)
	(via
		(at 416.46983 -374.30583)
		(size 0.508)
		(drill 0.254)
		(layers "F.Cu" "B.Cu")
		(net "P12V_AUX")
	)
	(via
		(at 222.847408 -396.822422)
		(size 0.508)
		(drill 0.254)
		(layers "F.Cu" "B.Cu")
		(net "P12V_AUX")
	)
	(via
		(at 19.255486 -339.450172)
		(size 0.508)
		(drill 0.254)
		(layers "F.Cu" "B.Cu")
		(net "P12V_AUX")
	)
	(via
		(at 264.616692 -394.020548)
		(size 0.508)
		(drill 0.254)
		(layers "F.Cu" "B.Cu")
		(net "P12V_AUX")
	)
	(via
		(at 182.989982 -34.312352)
		(size 0.508)
		(drill 0.254)
		(layers "F.Cu" "B.Cu")
		(net "P12V_AUX")
	)
	(via
		(at 232.753408 -396.822422)
		(size 0.508)
		(drill 0.254)
		(layers "F.Cu" "B.Cu")
		(net "P12V_AUX")
	)
	(via
		(at 266.140692 -391.734548)
		(size 0.508)
		(drill 0.254)
		(layers "F.Cu" "B.Cu")
		(net "P12V_AUX")
	)
	(via
		(at 40.76446 -361.049316)
		(size 0.508)
		(drill 0.254)
		(layers "F.Cu" "B.Cu")
		(net "P12V_AUX")
	)
	(via
		(at 448.774566 -340.473792)
		(size 0.508)
		(drill 0.254)
		(layers "F.Cu" "B.Cu")
		(net "P12V_AUX")
	)
	(via
		(at 68.32219 -27.572462)
		(size 0.4572)
		(drill 0.254)
		(layers "F.Cu" "B.Cu")
		(net "P12V_AUX")
	)
	(via
		(at 287.995614 -372.987062)
		(size 0.508)
		(drill 0.254)
		(layers "F.Cu" "B.Cu")
		(net "P12V_AUX")
	)
	(via
		(at 248.90476 -74.234548)
		(size 0.508)
		(drill 0.254)
		(layers "F.Cu" "B.Cu")
		(net "P12V_AUX")
	)
	(via
		(at 258.067048 -393.258548)
		(size 0.508)
		(drill 0.254)
		(layers "F.Cu" "B.Cu")
		(net "P12V_AUX")
	)
	(via
		(at 212.941408 -396.060422)
		(size 0.508)
		(drill 0.254)
		(layers "F.Cu" "B.Cu")
		(net "P12V_AUX")
	)
	(via
		(at 211.417408 -397.584422)
		(size 0.508)
		(drill 0.254)
		(layers "F.Cu" "B.Cu")
		(net "P12V_AUX")
	)
	(via
		(at 271.313656 -393.258548)
		(size 0.508)
		(drill 0.254)
		(layers "F.Cu" "B.Cu")
		(net "P12V_AUX")
	)
	(via
		(at 241.54892 -390.97204)
		(size 0.508)
		(drill 0.254)
		(layers "F.Cu" "B.Cu")
		(net "P12V_AUX")
	)
	(via
		(at 63.016638 -23.404322)
		(size 0.508)
		(drill 0.254)
		(layers "F.Cu" "B.Cu")
		(net "P12V_AUX")
	)
	(via
		(at 179.24399 -29.255212)
		(size 0.4572)
		(drill 0.254)
		(layers "F.Cu" "B.Cu")
		(net "P12V_AUX")
	)
	(via
		(at 65.343024 -39.808658)
		(size 0.508)
		(drill 0.254)
		(layers "F.Cu" "B.Cu")
		(net "P12V_AUX")
	)
	(via
		(at 287.233614 -372.225062)
		(size 0.508)
		(drill 0.254)
		(layers "F.Cu" "B.Cu")
		(net "P12V_AUX")
	)
	(via
		(at 212.179408 -396.060422)
		(size 0.508)
		(drill 0.254)
		(layers "F.Cu" "B.Cu")
		(net "P12V_AUX")
	)
	(via
		(at 343.450164 -358.509824)
		(size 0.508)
		(drill 0.254)
		(layers "F.Cu" "B.Cu")
		(net "P12V_AUX")
	)
	(via
		(at 451.822566 -341.946992)
		(size 0.508)
		(drill 0.254)
		(layers "F.Cu" "B.Cu")
		(net "P12V_AUX")
	)
	(via
		(at 286.598614 -370.955062)
		(size 0.508)
		(drill 0.254)
		(layers "F.Cu" "B.Cu")
		(net "P12V_AUX")
	)
	(via
		(at 23.065486 -341.055452)
		(size 0.508)
		(drill 0.254)
		(layers "F.Cu" "B.Cu")
		(net "P12V_AUX")
	)
	(via
		(at 177.443892 -28.620212)
		(size 0.4572)
		(drill 0.254)
		(layers "F.Cu" "B.Cu")
		(net "P12V_AUX")
	)
	(via
		(at 186.267344 -397.596614)
		(size 0.508)
		(drill 0.254)
		(layers "F.Cu" "B.Cu")
		(net "P12V_AUX")
	)
	(via
		(at 342.764364 -359.271824)
		(size 0.508)
		(drill 0.254)
		(layers "F.Cu" "B.Cu")
		(net "P12V_AUX")
	)
	(via
		(at 451.758812 -24.873458)
		(size 0.508)
		(drill 0.254)
		(layers "F.Cu" "B.Cu")
		(net "P12V_AUX")
	)
	(via
		(at 219.799408 -398.346422)
		(size 0.508)
		(drill 0.254)
		(layers "F.Cu" "B.Cu")
		(net "P12V_AUX")
	)
	(via
		(at 255.57988 -40.842946)
		(size 0.508)
		(drill 0.254)
		(layers "F.Cu" "B.Cu")
		(net "P12V_AUX")
	)
	(via
		(at 253.508764 -392.496548)
		(size 0.508)
		(drill 0.254)
		(layers "F.Cu" "B.Cu")
		(net "P12V_AUX")
	)
	(via
		(at 453.181212 -28.226258)
		(size 0.508)
		(drill 0.254)
		(layers "F.Cu" "B.Cu")
		(net "P12V_AUX")
	)
	(via
		(at 89.509854 -358.503728)
		(size 0.508)
		(drill 0.254)
		(layers "F.Cu" "B.Cu")
		(net "P12V_AUX")
	)
	(via
		(at 369.7224 -75.4888)
		(size 0.508)
		(drill 0.254)
		(layers "F.Cu" "B.Cu")
		(net "P12V_AUX")
	)
	(via
		(at 209.131408 -396.060422)
		(size 0.508)
		(drill 0.254)
		(layers "F.Cu" "B.Cu")
		(net "P12V_AUX")
	)
	(via
		(at 240.78692 -394.78204)
		(size 0.508)
		(drill 0.254)
		(layers "F.Cu" "B.Cu")
		(net "P12V_AUX")
	)
	(via
		(at 23.929086 -342.452452)
		(size 0.508)
		(drill 0.254)
		(layers "F.Cu" "B.Cu")
		(net "P12V_AUX")
	)
	(via
		(at 24.589486 -340.420452)
		(size 0.508)
		(drill 0.254)
		(layers "F.Cu" "B.Cu")
		(net "P12V_AUX")
	)
	(via
		(at 222.085408 -396.822422)
		(size 0.508)
		(drill 0.254)
		(layers "F.Cu" "B.Cu")
		(net "P12V_AUX")
	)
	(via
		(at 246.126 -392.496548)
		(size 0.508)
		(drill 0.254)
		(layers "F.Cu" "B.Cu")
		(net "P12V_AUX")
	)
	(via
		(at 73.293478 -26.670762)
		(size 0.508)
		(drill 0.254)
		(layers "F.Cu" "B.Cu")
		(net "P12V_AUX")
	)
	(via
		(at 222.847408 -399.108422)
		(size 0.508)
		(drill 0.254)
		(layers "F.Cu" "B.Cu")
		(net "P12V_AUX")
	)
	(via
		(at 336.560668 -358.521508)
		(size 0.508)
		(drill 0.254)
		(layers "F.Cu" "B.Cu")
		(net "P12V_AUX")
	)
	(via
		(at 248.415048 -74.928984)
		(size 0.508)
		(drill 0.254)
		(layers "F.Cu" "B.Cu")
		(net "P12V_AUX")
	)
	(via
		(at 240.02492 -394.02004)
		(size 0.508)
		(drill 0.254)
		(layers "F.Cu" "B.Cu")
		(net "P12V_AUX")
	)
	(via
		(at 441.20308 -28.492958)
		(size 0.4572)
		(drill 0.254)
		(layers "F.Cu" "B.Cu")
		(net "P12V_AUX")
	)
	(via
		(at 277.24862 -390.210548)
		(size 0.508)
		(drill 0.254)
		(layers "F.Cu" "B.Cu")
		(net "P12V_AUX")
	)
	(via
		(at 452.584566 -338.619592)
		(size 0.508)
		(drill 0.254)
		(layers "F.Cu" "B.Cu")
		(net "P12V_AUX")
	)
	(via
		(at 275.80082 -394.782548)
		(size 0.508)
		(drill 0.254)
		(layers "F.Cu" "B.Cu")
		(net "P12V_AUX")
	)
	(via
		(at 187.791344 -396.072614)
		(size 0.508)
		(drill 0.254)
		(layers "F.Cu" "B.Cu")
		(net "P12V_AUX")
	)
	(via
		(at 211.417408 -396.822422)
		(size 0.508)
		(drill 0.254)
		(layers "F.Cu" "B.Cu")
		(net "P12V_AUX")
	)
	(via
		(at 231.991408 -397.584422)
		(size 0.508)
		(drill 0.254)
		(layers "F.Cu" "B.Cu")
		(net "P12V_AUX")
	)
	(via
		(at 449.536566 -342.683592)
		(size 0.508)
		(drill 0.254)
		(layers "F.Cu" "B.Cu")
		(net "P12V_AUX")
	)
	(via
		(at 257.7846 -47.065946)
		(size 0.508)
		(drill 0.254)
		(layers "F.Cu" "B.Cu")
		(net "P12V_AUX")
	)
	(via
		(at 23.929086 -341.690452)
		(size 0.508)
		(drill 0.254)
		(layers "F.Cu" "B.Cu")
		(net "P12V_AUX")
	)
	(via
		(at 42.037 -365.851948)
		(size 0.508)
		(drill 0.254)
		(layers "F.Cu" "B.Cu")
		(net "P12V_AUX")
	)
	(via
		(at 451.822566 -340.473792)
		(size 0.508)
		(drill 0.254)
		(layers "F.Cu" "B.Cu")
		(net "P12V_AUX")
	)
	(via
		(at 392.800332 -78.195424)
		(size 0.508)
		(drill 0.254)
		(layers "F.Cu" "B.Cu")
		(net "P12V_AUX")
	)
	(via
		(at 199.987408 -399.108422)
		(size 0.508)
		(drill 0.254)
		(layers "F.Cu" "B.Cu")
		(net "P12V_AUX")
	)
	(via
		(at 230.467408 -398.346422)
		(size 0.508)
		(drill 0.254)
		(layers "F.Cu" "B.Cu")
		(net "P12V_AUX")
	)
	(via
		(at 339.696044 -360.68508)
		(size 0.508)
		(drill 0.254)
		(layers "F.Cu" "B.Cu")
		(net "P12V_AUX")
	)
	(via
		(at 448.012566 -339.737192)
		(size 0.508)
		(drill 0.254)
		(layers "F.Cu" "B.Cu")
		(net "P12V_AUX")
	)
	(via
		(at 447.531744 -78.920086)
		(size 0.508)
		(drill 0.254)
		(layers "F.Cu" "B.Cu")
		(net "P12V_AUX")
	)
	(via
		(at 223.609408 -396.822422)
		(size 0.508)
		(drill 0.254)
		(layers "F.Cu" "B.Cu")
		(net "P12V_AUX")
	)
	(via
		(at 189.315344 -399.120614)
		(size 0.508)
		(drill 0.254)
		(layers "F.Cu" "B.Cu")
		(net "P12V_AUX")
	)
	(via
		(at 212.179408 -397.584422)
		(size 0.508)
		(drill 0.254)
		(layers "F.Cu" "B.Cu")
		(net "P12V_AUX")
	)
	(via
		(at 188.553344 -396.834614)
		(size 0.508)
		(drill 0.254)
		(layers "F.Cu" "B.Cu")
		(net "P12V_AUX")
	)
	(via
		(at 222.085408 -397.584422)
		(size 0.508)
		(drill 0.254)
		(layers "F.Cu" "B.Cu")
		(net "P12V_AUX")
	)
	(via
		(at 200.749408 -399.108422)
		(size 0.508)
		(drill 0.254)
		(layers "F.Cu" "B.Cu")
		(net "P12V_AUX")
	)
	(via
		(at 23.929086 -340.420452)
		(size 0.508)
		(drill 0.254)
		(layers "F.Cu" "B.Cu")
		(net "P12V_AUX")
	)
	(via
		(at 269.865856 -392.496548)
		(size 0.508)
		(drill 0.254)
		(layers "F.Cu" "B.Cu")
		(net "P12V_AUX")
	)
	(via
		(at 230.467408 -397.584422)
		(size 0.508)
		(drill 0.254)
		(layers "F.Cu" "B.Cu")
		(net "P12V_AUX")
	)
	(via
		(at 258.067048 -390.210548)
		(size 0.508)
		(drill 0.254)
		(layers "F.Cu" "B.Cu")
		(net "P12V_AUX")
	)
	(via
		(at 336.560668 -360.045508)
		(size 0.508)
		(drill 0.254)
		(layers "F.Cu" "B.Cu")
		(net "P12V_AUX")
	)
	(via
		(at 47.592234 -112.619282)
		(size 0.508)
		(drill 0.254)
		(layers "F.Cu" "B.Cu")
		(net "P12V_AUX")
	)
	(via
		(at 71.337678 -27.254962)
		(size 0.508)
		(drill 0.254)
		(layers "F.Cu" "B.Cu")
		(net "P12V_AUX")
	)
	(via
		(at 338.944712 -361.336336)
		(size 0.508)
		(drill 0.254)
		(layers "F.Cu" "B.Cu")
		(net "P12V_AUX")
	)
	(via
		(at 252.086364 -390.972548)
		(size 0.508)
		(drill 0.254)
		(layers "F.Cu" "B.Cu")
		(net "P12V_AUX")
	)
	(via
		(at 248.415048 -70.933564)
		(size 0.508)
		(drill 0.254)
		(layers "F.Cu" "B.Cu")
		(net "P12V_AUX")
	)
	(via
		(at 247.5738 -390.972548)
		(size 0.508)
		(drill 0.254)
		(layers "F.Cu" "B.Cu")
		(net "P12V_AUX")
	)
	(via
		(at 466.06333 -56.828182)
		(size 0.508)
		(drill 0.254)
		(layers "F.Cu" "B.Cu")
		(net "P12V_AUX")
	)
	(via
		(at 189.41415 -42.554398)
		(size 0.508)
		(drill 0.254)
		(layers "F.Cu" "B.Cu")
		(net "P12V_AUX")
	)
	(via
		(at 91.872562 -360.016044)
		(size 0.508)
		(drill 0.254)
		(layers "F.Cu" "B.Cu")
		(net "P12V_AUX")
	)
	(via
		(at 266.826492 -392.496548)
		(size 0.508)
		(drill 0.254)
		(layers "F.Cu" "B.Cu")
		(net "P12V_AUX")
	)
	(via
		(at 341.220044 -360.68508)
		(size 0.508)
		(drill 0.254)
		(layers "F.Cu" "B.Cu")
		(net "P12V_AUX")
	)
	(via
		(at 184.789572 -23.109936)
		(size 0.508)
		(drill 0.254)
		(layers "F.Cu" "B.Cu")
		(net "P12V_AUX")
	)
	(via
		(at 252.086364 -392.496548)
		(size 0.508)
		(drill 0.254)
		(layers "F.Cu" "B.Cu")
		(net "P12V_AUX")
	)
	(via
		(at 210.655408 -396.822422)
		(size 0.508)
		(drill 0.254)
		(layers "F.Cu" "B.Cu")
		(net "P12V_AUX")
	)
	(via
		(at 79.008478 -27.204162)
		(size 0.508)
		(drill 0.254)
		(layers "F.Cu" "B.Cu")
		(net "P12V_AUX")
	)
	(via
		(at 254.270764 -394.020548)
		(size 0.508)
		(drill 0.254)
		(layers "F.Cu" "B.Cu")
		(net "P12V_AUX")
	)
	(via
		(at 260.911848 -393.258548)
		(size 0.508)
		(drill 0.254)
		(layers "F.Cu" "B.Cu")
		(net "P12V_AUX")
	)
	(via
		(at 45.464222 -145.463006)
		(size 0.508)
		(drill 0.254)
		(layers "F.Cu" "B.Cu")
		(net "P12V_AUX")
	)
	(via
		(at 266.140692 -393.258548)
		(size 0.508)
		(drill 0.254)
		(layers "F.Cu" "B.Cu")
		(net "P12V_AUX")
	)
	(via
		(at 44.143422 -146.75866)
		(size 0.508)
		(drill 0.254)
		(layers "F.Cu" "B.Cu")
		(net "P12V_AUX")
	)
	(via
		(at 44.143422 -145.463006)
		(size 0.508)
		(drill 0.254)
		(layers "F.Cu" "B.Cu")
		(net "P12V_AUX")
	)
	(via
		(at 20.060158 -342.39835)
		(size 0.508)
		(drill 0.254)
		(layers "F.Cu" "B.Cu")
		(net "P12V_AUX")
	)
	(via
		(at 210.655408 -399.108422)
		(size 0.508)
		(drill 0.254)
		(layers "F.Cu" "B.Cu")
		(net "P12V_AUX")
	)
	(via
		(at 231.229408 -399.108422)
		(size 0.508)
		(drill 0.254)
		(layers "F.Cu" "B.Cu")
		(net "P12V_AUX")
	)
	(via
		(at 24.589486 -341.055452)
		(size 0.508)
		(drill 0.254)
		(layers "F.Cu" "B.Cu")
		(net "P12V_AUX")
	)
	(via
		(at 67.422268 -27.572462)
		(size 0.4572)
		(drill 0.254)
		(layers "F.Cu" "B.Cu")
		(net "P12V_AUX")
	)
	(via
		(at 275.80082 -393.258548)
		(size 0.508)
		(drill 0.254)
		(layers "F.Cu" "B.Cu")
		(net "P12V_AUX")
	)
	(via
		(at 247.5738 -393.258548)
		(size 0.508)
		(drill 0.254)
		(layers "F.Cu" "B.Cu")
		(net "P12V_AUX")
	)
	(via
		(at 271.313656 -394.020548)
		(size 0.508)
		(drill 0.254)
		(layers "F.Cu" "B.Cu")
		(net "P12V_AUX")
	)
	(via
		(at 87.992204 -359.257854)
		(size 0.508)
		(drill 0.254)
		(layers "F.Cu" "B.Cu")
		(net "P12V_AUX")
	)
	(via
		(at 21.541486 -341.055452)
		(size 0.508)
		(drill 0.254)
		(layers "F.Cu" "B.Cu")
		(net "P12V_AUX")
	)
	(via
		(at 392.165332 -78.119224)
		(size 0.508)
		(drill 0.254)
		(layers "F.Cu" "B.Cu")
		(net "P12V_AUX")
	)
	(via
		(at 338.19338 -361.987592)
		(size 0.508)
		(drill 0.254)
		(layers "F.Cu" "B.Cu")
		(net "P12V_AUX")
	)
	(via
		(at 252.086364 -394.020548)
		(size 0.508)
		(drill 0.254)
		(layers "F.Cu" "B.Cu")
		(net "P12V_AUX")
	)
	(via
		(at 463.54873 -381.559054)
		(size 0.508)
		(drill 0.254)
		(layers "F.Cu" "B.Cu")
		(net "P12V_AUX")
	)
	(via
		(at 40.77462 -363.759496)
		(size 0.508)
		(drill 0.254)
		(layers "F.Cu" "B.Cu")
		(net "P12V_AUX")
	)
	(via
		(at 187.791344 -397.596614)
		(size 0.508)
		(drill 0.254)
		(layers "F.Cu" "B.Cu")
		(net "P12V_AUX")
	)
	(via
		(at 254.956564 -394.020548)
		(size 0.508)
		(drill 0.254)
		(layers "F.Cu" "B.Cu")
		(net "P12V_AUX")
	)
	(via
		(at 447.161412 -26.956258)
		(size 0.508)
		(drill 0.254)
		(layers "F.Cu" "B.Cu")
		(net "P12V_AUX")
	)
	(via
		(at 243.07292 -390.21004)
		(size 0.508)
		(drill 0.254)
		(layers "F.Cu" "B.Cu")
		(net "P12V_AUX")
	)
	(via
		(at 243.07292 -390.97204)
		(size 0.508)
		(drill 0.254)
		(layers "F.Cu" "B.Cu")
		(net "P12V_AUX")
	)
	(via
		(at 88.664542 -359.246424)
		(size 0.508)
		(drill 0.254)
		(layers "F.Cu" "B.Cu")
		(net "P12V_AUX")
	)
	(via
		(at 19.268186 -341.665052)
		(size 0.508)
		(drill 0.254)
		(layers "F.Cu" "B.Cu")
		(net "P12V_AUX")
	)
	(via
		(at 259.489448 -393.258548)
		(size 0.508)
		(drill 0.254)
		(layers "F.Cu" "B.Cu")
		(net "P12V_AUX")
	)
	(via
		(at 230.467408 -396.060422)
		(size 0.508)
		(drill 0.254)
		(layers "F.Cu" "B.Cu")
		(net "P12V_AUX")
	)
	(via
		(at 170.471846 -362.876846)
		(size 0.508)
		(drill 0.254)
		(layers "F.Cu" "B.Cu")
		(net "P12V_AUX")
	)
	(via
		(at 342.019636 -358.519984)
		(size 0.508)
		(drill 0.254)
		(layers "F.Cu" "B.Cu")
		(net "P12V_AUX")
	)
	(via
		(at 198.9963 -132.705348)
		(size 0.508)
		(drill 0.254)
		(layers "F.Cu" "B.Cu")
		(net "P12V_AUX")
	)
	(via
		(at 442.103002 -27.857958)
		(size 0.4572)
		(drill 0.254)
		(layers "F.Cu" "B.Cu")
		(net "P12V_AUX")
	)
	(via
		(at 95.71355 -359.254044)
		(size 0.508)
		(drill 0.254)
		(layers "F.Cu" "B.Cu")
		(net "P12V_AUX")
	)
	(via
		(at 270.551656 -390.972548)
		(size 0.508)
		(drill 0.254)
		(layers "F.Cu" "B.Cu")
		(net "P12V_AUX")
	)
	(via
		(at 247.5738 -394.020548)
		(size 0.508)
		(drill 0.254)
		(layers "F.Cu" "B.Cu")
		(net "P12V_AUX")
	)
	(via
		(at 449.536566 -340.473792)
		(size 0.508)
		(drill 0.254)
		(layers "F.Cu" "B.Cu")
		(net "P12V_AUX")
	)
	(via
		(at 258.067048 -394.782548)
		(size 0.508)
		(drill 0.254)
		(layers "F.Cu" "B.Cu")
		(net "P12V_AUX")
	)
	(via
		(at 248.3358 -394.782548)
		(size 0.508)
		(drill 0.254)
		(layers "F.Cu" "B.Cu")
		(net "P12V_AUX")
	)
	(via
		(at 252.746764 -390.210548)
		(size 0.508)
		(drill 0.254)
		(layers "F.Cu" "B.Cu")
		(net "P12V_AUX")
	)
	(via
		(at 337.303364 -359.271824)
		(size 0.508)
		(drill 0.254)
		(layers "F.Cu" "B.Cu")
		(net "P12V_AUX")
	)
	(via
		(at 71.337678 -27.915362)
		(size 0.508)
		(drill 0.254)
		(layers "F.Cu" "B.Cu")
		(net "P12V_AUX")
	)
	(via
		(at 341.199216 -356.866444)
		(size 0.508)
		(drill 0.254)
		(layers "F.Cu" "B.Cu")
		(net "P12V_AUX")
	)
	(via
		(at 254.270764 -392.496548)
		(size 0.508)
		(drill 0.254)
		(layers "F.Cu" "B.Cu")
		(net "P12V_AUX")
	)
	(via
		(at 444.3603 -74.640948)
		(size 0.508)
		(drill 0.254)
		(layers "F.Cu" "B.Cu")
		(net "P12V_AUX")
	)
	(via
		(at 258.727448 -394.782548)
		(size 0.508)
		(drill 0.254)
		(layers "F.Cu" "B.Cu")
		(net "P12V_AUX")
	)
	(via
		(at 452.584566 -341.946992)
		(size 0.508)
		(drill 0.254)
		(layers "F.Cu" "B.Cu")
		(net "P12V_AUX")
	)
	(via
		(at 447.036698 -336.64525)
		(size 0.508)
		(drill 0.254)
		(layers "F.Cu" "B.Cu")
		(net "P12V_AUX")
	)
	(via
		(at 179.24399 -28.620212)
		(size 0.4572)
		(drill 0.254)
		(layers "F.Cu" "B.Cu")
		(net "P12V_AUX")
	)
	(via
		(at 415.37001 -372.29923)
		(size 0.508)
		(drill 0.254)
		(layers "F.Cu" "B.Cu")
		(net "P12V_AUX")
	)
	(via
		(at 202.273408 -397.584422)
		(size 0.508)
		(drill 0.254)
		(layers "F.Cu" "B.Cu")
		(net "P12V_AUX")
	)
	(via
		(at 446.018412 -28.200858)
		(size 0.508)
		(drill 0.254)
		(layers "F.Cu" "B.Cu")
		(net "P12V_AUX")
	)
	(via
		(at 88.763602 -356.942644)
		(size 0.508)
		(drill 0.254)
		(layers "F.Cu" "B.Cu")
		(net "P12V_AUX")
	)
	(via
		(at 240.78692 -393.25804)
		(size 0.508)
		(drill 0.254)
		(layers "F.Cu" "B.Cu")
		(net "P12V_AUX")
	)
	(via
		(at 464.08213 -58.148982)
		(size 0.508)
		(drill 0.254)
		(layers "F.Cu" "B.Cu")
		(net "P12V_AUX")
	)
	(via
		(at 181.034182 -29.105352)
		(size 0.508)
		(drill 0.254)
		(layers "F.Cu" "B.Cu")
		(net "P12V_AUX")
	)
	(via
		(at 40.01262 -362.362496)
		(size 0.508)
		(drill 0.254)
		(layers "F.Cu" "B.Cu")
		(net "P12V_AUX")
	)
	(via
		(at 258.067048 -392.496548)
		(size 0.508)
		(drill 0.254)
		(layers "F.Cu" "B.Cu")
		(net "P12V_AUX")
	)
	(via
		(at 463.743548 -42.586148)
		(size 0.508)
		(drill 0.254)
		(layers "F.Cu" "B.Cu")
		(net "P12V_AUX")
	)
	(via
		(at 187.029344 -396.072614)
		(size 0.508)
		(drill 0.254)
		(layers "F.Cu" "B.Cu")
		(net "P12V_AUX")
	)
	(via
		(at 190.077344 -399.120614)
		(size 0.508)
		(drill 0.254)
		(layers "F.Cu" "B.Cu")
		(net "P12V_AUX")
	)
	(via
		(at 221.323408 -398.346422)
		(size 0.508)
		(drill 0.254)
		(layers "F.Cu" "B.Cu")
		(net "P12V_AUX")
	)
	(via
		(at 20.779486 -341.690452)
		(size 0.508)
		(drill 0.254)
		(layers "F.Cu" "B.Cu")
		(net "P12V_AUX")
	)
	(via
		(at 46.785022 -146.098006)
		(size 0.508)
		(drill 0.254)
		(layers "F.Cu" "B.Cu")
		(net "P12V_AUX")
	)
	(via
		(at 340.443312 -361.991656)
		(size 0.508)
		(drill 0.254)
		(layers "F.Cu" "B.Cu")
		(net "P12V_AUX")
	)
	(via
		(at 20.779486 -341.055452)
		(size 0.508)
		(drill 0.254)
		(layers "F.Cu" "B.Cu")
		(net "P12V_AUX")
	)
	(via
		(at 258.727448 -393.258548)
		(size 0.508)
		(drill 0.254)
		(layers "F.Cu" "B.Cu")
		(net "P12V_AUX")
	)
	(via
		(at 235.039408 -399.108422)
		(size 0.508)
		(drill 0.254)
		(layers "F.Cu" "B.Cu")
		(net "P12V_AUX")
	)
	(via
		(at 447.974212 -26.956258)
		(size 0.508)
		(drill 0.254)
		(layers "F.Cu" "B.Cu")
		(net "P12V_AUX")
	)
	(via
		(at 200.749408 -396.822422)
		(size 0.508)
		(drill 0.254)
		(layers "F.Cu" "B.Cu")
		(net "P12V_AUX")
	)
	(via
		(at 342.019636 -357.757984)
		(size 0.508)
		(drill 0.254)
		(layers "F.Cu" "B.Cu")
		(net "P12V_AUX")
	)
	(via
		(at 222.847408 -398.346422)
		(size 0.508)
		(drill 0.254)
		(layers "F.Cu" "B.Cu")
		(net "P12V_AUX")
	)
	(via
		(at 252.746764 -393.258548)
		(size 0.508)
		(drill 0.254)
		(layers "F.Cu" "B.Cu")
		(net "P12V_AUX")
	)
	(via
		(at 18.538698 -341.00389)
		(size 0.508)
		(drill 0.254)
		(layers "F.Cu" "B.Cu")
		(net "P12V_AUX")
	)
	(via
		(at 248.3358 -391.734548)
		(size 0.508)
		(drill 0.254)
		(layers "F.Cu" "B.Cu")
		(net "P12V_AUX")
	)
	(via
		(at 246.126 -390.972548)
		(size 0.508)
		(drill 0.254)
		(layers "F.Cu" "B.Cu")
		(net "P12V_AUX")
	)
	(via
		(at 89.509854 -357.741728)
		(size 0.508)
		(drill 0.254)
		(layers "F.Cu" "B.Cu")
		(net "P12V_AUX")
	)
	(via
		(at 276.48662 -394.782548)
		(size 0.508)
		(drill 0.254)
		(layers "F.Cu" "B.Cu")
		(net "P12V_AUX")
	)
	(via
		(at 23.065486 -340.420452)
		(size 0.508)
		(drill 0.254)
		(layers "F.Cu" "B.Cu")
		(net "P12V_AUX")
	)
	(via
		(at 253.54407 -49.71669)
		(size 0.4572)
		(drill 0.254)
		(layers "F.Cu" "B.Cu")
		(net "P12V_AUX")
	)
	(via
		(at 266.826492 -391.734548)
		(size 0.508)
		(drill 0.254)
		(layers "F.Cu" "B.Cu")
		(net "P12V_AUX")
	)
	(via
		(at 21.541486 -341.690452)
		(size 0.508)
		(drill 0.254)
		(layers "F.Cu" "B.Cu")
		(net "P12V_AUX")
	)
	(via
		(at 209.131408 -396.822422)
		(size 0.508)
		(drill 0.254)
		(layers "F.Cu" "B.Cu")
		(net "P12V_AUX")
	)
	(via
		(at 272.761456 -393.258548)
		(size 0.508)
		(drill 0.254)
		(layers "F.Cu" "B.Cu")
		(net "P12V_AUX")
	)
	(via
		(at 40.01262 -365.189516)
		(size 0.508)
		(drill 0.254)
		(layers "F.Cu" "B.Cu")
		(net "P12V_AUX")
	)
	(via
		(at 88.728042 -357.735124)
		(size 0.508)
		(drill 0.254)
		(layers "F.Cu" "B.Cu")
		(net "P12V_AUX")
	)
	(via
		(at 246.126 -393.258548)
		(size 0.508)
		(drill 0.254)
		(layers "F.Cu" "B.Cu")
		(net "P12V_AUX")
	)
	(via
		(at 415.37001 -373.06123)
		(size 0.508)
		(drill 0.254)
		(layers "F.Cu" "B.Cu")
		(net "P12V_AUX")
	)
	(via
		(at 79.008478 -27.940762)
		(size 0.508)
		(drill 0.254)
		(layers "F.Cu" "B.Cu")
		(net "P12V_AUX")
	)
	(via
		(at 212.941408 -396.822422)
		(size 0.508)
		(drill 0.254)
		(layers "F.Cu" "B.Cu")
		(net "P12V_AUX")
	)
	(via
		(at 69.222366 -27.572462)
		(size 0.4572)
		(drill 0.254)
		(layers "F.Cu" "B.Cu")
		(net "P12V_AUX")
	)
	(via
		(at 417.33851 -372.27383)
		(size 0.508)
		(drill 0.254)
		(layers "F.Cu" "B.Cu")
		(net "P12V_AUX")
	)
	(via
		(at 44.803822 -145.463006)
		(size 0.508)
		(drill 0.254)
		(layers "F.Cu" "B.Cu")
		(net "P12V_AUX")
	)
	(via
		(at 178.343814 -28.620212)
		(size 0.4572)
		(drill 0.254)
		(layers "F.Cu" "B.Cu")
		(net "P12V_AUX")
	)
	(via
		(at 463.32013 -56.828182)
		(size 0.508)
		(drill 0.254)
		(layers "F.Cu" "B.Cu")
		(net "P12V_AUX")
	)
	(via
		(at 269.865856 -390.972548)
		(size 0.508)
		(drill 0.254)
		(layers "F.Cu" "B.Cu")
		(net "P12V_AUX")
	)
	(via
		(at 453.346566 -336.409792)
		(size 0.508)
		(drill 0.254)
		(layers "F.Cu" "B.Cu")
		(net "P12V_AUX")
	)
	(via
		(at 187.791344 -396.834614)
		(size 0.508)
		(drill 0.254)
		(layers "F.Cu" "B.Cu")
		(net "P12V_AUX")
	)
	(via
		(at 17.731486 -338.180172)
		(size 0.508)
		(drill 0.254)
		(layers "F.Cu" "B.Cu")
		(net "P12V_AUX")
	)
	(via
		(at 231.991408 -399.108422)
		(size 0.508)
		(drill 0.254)
		(layers "F.Cu" "B.Cu")
		(net "P12V_AUX")
	)
	(via
		(at 335.835244 -360.000804)
		(size 0.508)
		(drill 0.254)
		(layers "F.Cu" "B.Cu")
		(net "P12V_AUX")
	)
	(via
		(at 91.113102 -355.431344)
		(size 0.508)
		(drill 0.254)
		(layers "F.Cu" "B.Cu")
		(net "P12V_AUX")
	)
	(via
		(at 66.522346 -27.572462)
		(size 0.4572)
		(drill 0.254)
		(layers "F.Cu" "B.Cu")
		(net "P12V_AUX")
	)
	(via
		(at 464.08213 -58.783982)
		(size 0.508)
		(drill 0.254)
		(layers "F.Cu" "B.Cu")
		(net "P12V_AUX")
	)
	(via
		(at 252.086364 -391.734548)
		(size 0.508)
		(drill 0.254)
		(layers "F.Cu" "B.Cu")
		(net "P12V_AUX")
	)
	(via
		(at 88.776302 -356.185724)
		(size 0.508)
		(drill 0.254)
		(layers "F.Cu" "B.Cu")
		(net "P12V_AUX")
	)
	(via
		(at 338.95538 -361.987592)
		(size 0.508)
		(drill 0.254)
		(layers "F.Cu" "B.Cu")
		(net "P12V_AUX")
	)
	(via
		(at 294.80002 -54.32298)
		(size 0.508)
		(drill 0.254)
		(layers "F.Cu" "B.Cu")
		(net "P12V_AUX")
	)
	(via
		(at 338.161376 -360.033824)
		(size 0.508)
		(drill 0.254)
		(layers "F.Cu" "B.Cu")
		(net "P12V_AUX")
	)
	(via
		(at 173.202346 -362.851446)
		(size 0.508)
		(drill 0.254)
		(layers "F.Cu" "B.Cu")
		(net "P12V_AUX")
	)
	(via
		(at 278.01062 -394.782548)
		(size 0.508)
		(drill 0.254)
		(layers "F.Cu" "B.Cu")
		(net "P12V_AUX")
	)
	(via
		(at 464.74253 -56.828182)
		(size 0.508)
		(drill 0.254)
		(layers "F.Cu" "B.Cu")
		(net "P12V_AUX")
	)
	(via
		(at 18.556986 -341.665052)
		(size 0.508)
		(drill 0.254)
		(layers "F.Cu" "B.Cu")
		(net "P12V_AUX")
	)
	(via
		(at 171.233846 -363.511846)
		(size 0.508)
		(drill 0.254)
		(layers "F.Cu" "B.Cu")
		(net "P12V_AUX")
	)
	(via
		(at 265.378692 -391.734548)
		(size 0.508)
		(drill 0.254)
		(layers "F.Cu" "B.Cu")
		(net "P12V_AUX")
	)
	(via
		(at 272.761456 -394.782548)
		(size 0.508)
		(drill 0.254)
		(layers "F.Cu" "B.Cu")
		(net "P12V_AUX")
	)
	(via
		(at 169.836846 -362.241846)
		(size 0.508)
		(drill 0.254)
		(layers "F.Cu" "B.Cu")
		(net "P12V_AUX")
	)
	(via
		(at 432.016408 -162.402774)
		(size 0.508)
		(drill 0.254)
		(layers "F.Cu" "B.Cu")
		(net "P12V_AUX")
	)
	(via
		(at 452.584566 -343.371932)
		(size 0.508)
		(drill 0.254)
		(layers "F.Cu" "B.Cu")
		(net "P12V_AUX")
	)
	(via
		(at 264.616692 -390.972548)
		(size 0.508)
		(drill 0.254)
		(layers "F.Cu" "B.Cu")
		(net "P12V_AUX")
	)
	(via
		(at 199.987408 -396.060422)
		(size 0.508)
		(drill 0.254)
		(layers "F.Cu" "B.Cu")
		(net "P12V_AUX")
	)
	(via
		(at 263.981692 -390.210548)
		(size 0.508)
		(drill 0.254)
		(layers "F.Cu" "B.Cu")
		(net "P12V_AUX")
	)
	(via
		(at 202.273408 -399.108422)
		(size 0.508)
		(drill 0.254)
		(layers "F.Cu" "B.Cu")
		(net "P12V_AUX")
	)
	(via
		(at 260.251448 -393.258548)
		(size 0.508)
		(drill 0.254)
		(layers "F.Cu" "B.Cu")
		(net "P12V_AUX")
	)
	(via
		(at 247.5738 -392.496548)
		(size 0.508)
		(drill 0.254)
		(layers "F.Cu" "B.Cu")
		(net "P12V_AUX")
	)
	(via
		(at 209.131408 -398.346422)
		(size 0.508)
		(drill 0.254)
		(layers "F.Cu" "B.Cu")
		(net "P12V_AUX")
	)
	(via
		(at 432.676808 -165.745414)
		(size 0.508)
		(drill 0.254)
		(layers "F.Cu" "B.Cu")
		(net "P12V_AUX")
	)
	(via
		(at 188.553344 -399.882614)
		(size 0.508)
		(drill 0.254)
		(layers "F.Cu" "B.Cu")
		(net "P12V_AUX")
	)
	(via
		(at 240.78692 -392.49604)
		(size 0.508)
		(drill 0.254)
		(layers "F.Cu" "B.Cu")
		(net "P12V_AUX")
	)
	(via
		(at 198.463408 -397.584422)
		(size 0.508)
		(drill 0.254)
		(layers "F.Cu" "B.Cu")
		(net "P12V_AUX")
	)
	(via
		(at 220.561408 -396.822422)
		(size 0.508)
		(drill 0.254)
		(layers "F.Cu" "B.Cu")
		(net "P12V_AUX")
	)
	(via
		(at 91.839542 -356.955344)
		(size 0.508)
		(drill 0.254)
		(layers "F.Cu" "B.Cu")
		(net "P12V_AUX")
	)
	(via
		(at 341.954612 -361.359196)
		(size 0.508)
		(drill 0.254)
		(layers "F.Cu" "B.Cu")
		(net "P12V_AUX")
	)
	(via
		(at 212.941408 -398.346422)
		(size 0.508)
		(drill 0.254)
		(layers "F.Cu" "B.Cu")
		(net "P12V_AUX")
	)
	(via
		(at 277.24862 -391.734548)
		(size 0.508)
		(drill 0.254)
		(layers "F.Cu" "B.Cu")
		(net "P12V_AUX")
	)
	(via
		(at 213.703408 -397.584422)
		(size 0.508)
		(drill 0.254)
		(layers "F.Cu" "B.Cu")
		(net "P12V_AUX")
	)
	(via
		(at 419.570154 -135.142478)
		(size 0.508)
		(drill 0.254)
		(layers "F.Cu" "B.Cu")
		(net "P12V_AUX")
	)
	(via
		(at 39.37762 -365.189516)
		(size 0.508)
		(drill 0.254)
		(layers "F.Cu" "B.Cu")
		(net "P12V_AUX")
	)
	(via
		(at 199.987408 -398.346422)
		(size 0.508)
		(drill 0.254)
		(layers "F.Cu" "B.Cu")
		(net "P12V_AUX")
	)
	(via
		(at 248.415048 -71.652384)
		(size 0.508)
		(drill 0.254)
		(layers "F.Cu" "B.Cu")
		(net "P12V_AUX")
	)
	(via
		(at 260.911848 -390.210548)
		(size 0.508)
		(drill 0.254)
		(layers "F.Cu" "B.Cu")
		(net "P12V_AUX")
	)
	(via
		(at 339.681312 -361.991656)
		(size 0.508)
		(drill 0.254)
		(layers "F.Cu" "B.Cu")
		(net "P12V_AUX")
	)
	(via
		(at 202.273408 -396.822422)
		(size 0.508)
		(drill 0.254)
		(layers "F.Cu" "B.Cu")
		(net "P12V_AUX")
	)
	(via
		(at 71.845678 -29.363162)
		(size 0.508)
		(drill 0.254)
		(layers "F.Cu" "B.Cu")
		(net "P12V_AUX")
	)
	(via
		(at 231.991408 -396.060422)
		(size 0.508)
		(drill 0.254)
		(layers "F.Cu" "B.Cu")
		(net "P12V_AUX")
	)
	(via
		(at 187.029344 -398.358614)
		(size 0.508)
		(drill 0.254)
		(layers "F.Cu" "B.Cu")
		(net "P12V_AUX")
	)
	(via
		(at 222.085408 -396.060422)
		(size 0.508)
		(drill 0.254)
		(layers "F.Cu" "B.Cu")
		(net "P12V_AUX")
	)
	(via
		(at 264.616692 -391.734548)
		(size 0.508)
		(drill 0.254)
		(layers "F.Cu" "B.Cu")
		(net "P12V_AUX")
	)
	(via
		(at 451.822566 -336.409792)
		(size 0.508)
		(drill 0.254)
		(layers "F.Cu" "B.Cu")
		(net "P12V_AUX")
	)
	(via
		(at 211.417408 -396.060422)
		(size 0.508)
		(drill 0.254)
		(layers "F.Cu" "B.Cu")
		(net "P12V_AUX")
	)
	(via
		(at 253.508764 -393.258548)
		(size 0.508)
		(drill 0.254)
		(layers "F.Cu" "B.Cu")
		(net "P12V_AUX")
	)
	(via
		(at 39.37762 -363.759496)
		(size 0.508)
		(drill 0.254)
		(layers "F.Cu" "B.Cu")
		(net "P12V_AUX")
	)
	(via
		(at 233.515408 -399.870422)
		(size 0.508)
		(drill 0.254)
		(layers "F.Cu" "B.Cu")
		(net "P12V_AUX")
	)
	(via
		(at 451.060566 -340.473792)
		(size 0.508)
		(drill 0.254)
		(layers "F.Cu" "B.Cu")
		(net "P12V_AUX")
	)
	(via
		(at 72.607678 -29.363162)
		(size 0.508)
		(drill 0.254)
		(layers "F.Cu" "B.Cu")
		(net "P12V_AUX")
	)
	(via
		(at 260.251448 -391.734548)
		(size 0.508)
		(drill 0.254)
		(layers "F.Cu" "B.Cu")
		(net "P12V_AUX")
	)
	(via
		(at 465.356956 -380.542292)
		(size 0.508)
		(drill 0.254)
		(layers "F.Cu" "B.Cu")
		(net "P12V_AUX")
	)
	(via
		(at 186.267344 -399.882614)
		(size 0.508)
		(drill 0.254)
		(layers "F.Cu" "B.Cu")
		(net "P12V_AUX")
	)
	(via
		(at 173.202346 -364.248446)
		(size 0.508)
		(drill 0.254)
		(layers "F.Cu" "B.Cu")
		(net "P12V_AUX")
	)
	(via
		(at 343.440004 -356.866444)
		(size 0.508)
		(drill 0.254)
		(layers "F.Cu" "B.Cu")
		(net "P12V_AUX")
	)
	(via
		(at 253.508764 -390.210548)
		(size 0.508)
		(drill 0.254)
		(layers "F.Cu" "B.Cu")
		(net "P12V_AUX")
	)
	(via
		(at 240.02492 -392.49604)
		(size 0.508)
		(drill 0.254)
		(layers "F.Cu" "B.Cu")
		(net "P12V_AUX")
	)
	(via
		(at 340.458044 -360.68508)
		(size 0.508)
		(drill 0.254)
		(layers "F.Cu" "B.Cu")
		(net "P12V_AUX")
	)
	(via
		(at 246.126 -390.210548)
		(size 0.508)
		(drill 0.254)
		(layers "F.Cu" "B.Cu")
		(net "P12V_AUX")
	)
	(via
		(at 198.463408 -398.346422)
		(size 0.508)
		(drill 0.254)
		(layers "F.Cu" "B.Cu")
		(net "P12V_AUX")
	)
	(via
		(at 276.48662 -392.496548)
		(size 0.508)
		(drill 0.254)
		(layers "F.Cu" "B.Cu")
		(net "P12V_AUX")
	)
	(via
		(at 265.378692 -394.020548)
		(size 0.508)
		(drill 0.254)
		(layers "F.Cu" "B.Cu")
		(net "P12V_AUX")
	)
	(via
		(at 341.209376 -360.033824)
		(size 0.508)
		(drill 0.254)
		(layers "F.Cu" "B.Cu")
		(net "P12V_AUX")
	)
	(via
		(at 465.40293 -58.783982)
		(size 0.508)
		(drill 0.254)
		(layers "F.Cu" "B.Cu")
		(net "P12V_AUX")
	)
	(via
		(at 95.71355 -358.492044)
		(size 0.508)
		(drill 0.254)
		(layers "F.Cu" "B.Cu")
		(net "P12V_AUX")
	)
	(via
		(at 257.35788 -40.842946)
		(size 0.508)
		(drill 0.254)
		(layers "F.Cu" "B.Cu")
		(net "P12V_AUX")
	)
	(via
		(at 90.351102 -355.431344)
		(size 0.508)
		(drill 0.254)
		(layers "F.Cu" "B.Cu")
		(net "P12V_AUX")
	)
	(via
		(at 178.942238 -406.127458)
		(size 0.508)
		(drill 0.254)
		(layers "F.Cu" "B.Cu")
		(net "P12V_AUX")
	)
	(via
		(at 199.225408 -396.060422)
		(size 0.508)
		(drill 0.254)
		(layers "F.Cu" "B.Cu")
		(net "P12V_AUX")
	)
	(via
		(at 413.97301 -371.53723)
		(size 0.508)
		(drill 0.254)
		(layers "F.Cu" "B.Cu")
		(net "P12V_AUX")
	)
	(via
		(at 258.3688 -44.627546)
		(size 0.508)
		(drill 0.254)
		(layers "F.Cu" "B.Cu")
		(net "P12V_AUX")
	)
	(via
		(at 40.77462 -362.362496)
		(size 0.508)
		(drill 0.254)
		(layers "F.Cu" "B.Cu")
		(net "P12V_AUX")
	)
	(via
		(at 466.82533 -58.148982)
		(size 0.508)
		(drill 0.254)
		(layers "F.Cu" "B.Cu")
		(net "P12V_AUX")
	)
	(via
		(at 431.350928 -165.7604)
		(size 0.508)
		(drill 0.254)
		(layers "F.Cu" "B.Cu")
		(net "P12V_AUX")
	)
	(via
		(at 249.0216 -390.210548)
		(size 0.508)
		(drill 0.254)
		(layers "F.Cu" "B.Cu")
		(net "P12V_AUX")
	)
	(via
		(at 259.0546 -44.652946)
		(size 0.508)
		(drill 0.254)
		(layers "F.Cu" "B.Cu")
		(net "P12V_AUX")
	)
	(via
		(at 221.323408 -399.108422)
		(size 0.508)
		(drill 0.254)
		(layers "F.Cu" "B.Cu")
		(net "P12V_AUX")
	)
	(via
		(at 466.06333 -58.783982)
		(size 0.508)
		(drill 0.254)
		(layers "F.Cu" "B.Cu")
		(net "P12V_AUX")
	)
	(via
		(at 252.086364 -390.210548)
		(size 0.508)
		(drill 0.254)
		(layers "F.Cu" "B.Cu")
		(net "P12V_AUX")
	)
	(via
		(at 240.02492 -391.73404)
		(size 0.508)
		(drill 0.254)
		(layers "F.Cu" "B.Cu")
		(net "P12V_AUX")
	)
	(via
		(at 233.515408 -396.822422)
		(size 0.508)
		(drill 0.254)
		(layers "F.Cu" "B.Cu")
		(net "P12V_AUX")
	)
	(via
		(at 413.97301 -370.90223)
		(size 0.508)
		(drill 0.254)
		(layers "F.Cu" "B.Cu")
		(net "P12V_AUX")
	)
	(via
		(at 271.313656 -392.496548)
		(size 0.508)
		(drill 0.254)
		(layers "F.Cu" "B.Cu")
		(net "P12V_AUX")
	)
	(via
		(at 202.273408 -396.060422)
		(size 0.508)
		(drill 0.254)
		(layers "F.Cu" "B.Cu")
		(net "P12V_AUX")
	)
	(via
		(at 246.8118 -394.782548)
		(size 0.508)
		(drill 0.254)
		(layers "F.Cu" "B.Cu")
		(net "P12V_AUX")
	)
	(via
		(at 289.964114 -372.961662)
		(size 0.508)
		(drill 0.254)
		(layers "F.Cu" "B.Cu")
		(net "P12V_AUX")
	)
	(via
		(at 242.31092 -393.25804)
		(size 0.508)
		(drill 0.254)
		(layers "F.Cu" "B.Cu")
		(net "P12V_AUX")
	)
	(via
		(at 453.181212 -27.489658)
		(size 0.508)
		(drill 0.254)
		(layers "F.Cu" "B.Cu")
		(net "P12V_AUX")
	)
	(via
		(at 338.923376 -359.271824)
		(size 0.508)
		(drill 0.254)
		(layers "F.Cu" "B.Cu")
		(net "P12V_AUX")
	)
	(via
		(at 92.634562 -360.016044)
		(size 0.508)
		(drill 0.254)
		(layers "F.Cu" "B.Cu")
		(net "P12V_AUX")
	)
	(via
		(at 91.872562 -355.444044)
		(size 0.508)
		(drill 0.254)
		(layers "F.Cu" "B.Cu")
		(net "P12V_AUX")
	)
	(via
		(at 266.140692 -390.972548)
		(size 0.508)
		(drill 0.254)
		(layers "F.Cu" "B.Cu")
		(net "P12V_AUX")
	)
	(via
		(at 233.515408 -397.584422)
		(size 0.508)
		(drill 0.254)
		(layers "F.Cu" "B.Cu")
		(net "P12V_AUX")
	)
	(via
		(at 278.69642 -391.734548)
		(size 0.508)
		(drill 0.254)
		(layers "F.Cu" "B.Cu")
		(net "P12V_AUX")
	)
	(via
		(at 211.417408 -399.108422)
		(size 0.508)
		(drill 0.254)
		(layers "F.Cu" "B.Cu")
		(net "P12V_AUX")
	)
	(via
		(at 417.33851 -370.24183)
		(size 0.508)
		(drill 0.254)
		(layers "F.Cu" "B.Cu")
		(net "P12V_AUX")
	)
	(via
		(at 201.511408 -399.108422)
		(size 0.508)
		(drill 0.254)
		(layers "F.Cu" "B.Cu")
		(net "P12V_AUX")
	)
	(via
		(at 19.268186 -342.427052)
		(size 0.508)
		(drill 0.254)
		(layers "F.Cu" "B.Cu")
		(net "P12V_AUX")
	)
	(via
		(at 248.3358 -390.972548)
		(size 0.508)
		(drill 0.254)
		(layers "F.Cu" "B.Cu")
		(net "P12V_AUX")
	)
	(via
		(at 189.79642 -27.577288)
		(size 0.508)
		(drill 0.254)
		(layers "F.Cu" "B.Cu")
		(net "P12V_AUX")
	)
	(via
		(at 47.445422 -146.098006)
		(size 0.508)
		(drill 0.254)
		(layers "F.Cu" "B.Cu")
		(net "P12V_AUX")
	)
	(via
		(at 259.7912 -44.652946)
		(size 0.508)
		(drill 0.254)
		(layers "F.Cu" "B.Cu")
		(net "P12V_AUX")
	)
	(via
		(at 87.949024 -359.994454)
		(size 0.508)
		(drill 0.254)
		(layers "F.Cu" "B.Cu")
		(net "P12V_AUX")
	)
	(via
		(at 181.846982 -29.105352)
		(size 0.508)
		(drill 0.254)
		(layers "F.Cu" "B.Cu")
		(net "P12V_AUX")
	)
	(via
		(at 254.69088 -47.065946)
		(size 0.508)
		(drill 0.254)
		(layers "F.Cu" "B.Cu")
		(net "P12V_AUX")
	)
	(via
		(at 93.396562 -359.309924)
		(size 0.508)
		(drill 0.254)
		(layers "F.Cu" "B.Cu")
		(net "P12V_AUX")
	)
	(via
		(at 466.82533 -59.418982)
		(size 0.508)
		(drill 0.254)
		(layers "F.Cu" "B.Cu")
		(net "P12V_AUX")
	)
	(via
		(at 413.97301 -370.26723)
		(size 0.508)
		(drill 0.254)
		(layers "F.Cu" "B.Cu")
		(net "P12V_AUX")
	)
	(via
		(at 246.8118 -392.496548)
		(size 0.508)
		(drill 0.254)
		(layers "F.Cu" "B.Cu")
		(net "P12V_AUX")
	)
	(via
		(at 18.493486 -338.815172)
		(size 0.508)
		(drill 0.254)
		(layers "F.Cu" "B.Cu")
		(net "P12V_AUX")
	)
	(via
		(at 19.255486 -338.180172)
		(size 0.508)
		(drill 0.254)
		(layers "F.Cu" "B.Cu")
		(net "P12V_AUX")
	)
	(via
		(at 341.209376 -359.271824)
		(size 0.508)
		(drill 0.254)
		(layers "F.Cu" "B.Cu")
		(net "P12V_AUX")
	)
	(via
		(at 338.923376 -360.033824)
		(size 0.508)
		(drill 0.254)
		(layers "F.Cu" "B.Cu")
		(net "P12V_AUX")
	)
	(via
		(at 414.60801 -370.26723)
		(size 0.508)
		(drill 0.254)
		(layers "F.Cu" "B.Cu")
		(net "P12V_AUX")
	)
	(via
		(at 341.199216 -356.104444)
		(size 0.508)
		(drill 0.254)
		(layers "F.Cu" "B.Cu")
		(net "P12V_AUX")
	)
	(via
		(at 338.172044 -360.68508)
		(size 0.508)
		(drill 0.254)
		(layers "F.Cu" "B.Cu")
		(net "P12V_AUX")
	)
	(via
		(at 252.746764 -394.020548)
		(size 0.508)
		(drill 0.254)
		(layers "F.Cu" "B.Cu")
		(net "P12V_AUX")
	)
	(via
		(at 232.753408 -396.060422)
		(size 0.508)
		(drill 0.254)
		(layers "F.Cu" "B.Cu")
		(net "P12V_AUX")
	)
	(via
		(at 176.54397 -29.255212)
		(size 0.4572)
		(drill 0.254)
		(layers "F.Cu" "B.Cu")
		(net "P12V_AUX")
	)
	(via
		(at 451.060566 -341.210392)
		(size 0.508)
		(drill 0.254)
		(layers "F.Cu" "B.Cu")
		(net "P12V_AUX")
	)
	(via
		(at 270.551656 -393.258548)
		(size 0.508)
		(drill 0.254)
		(layers "F.Cu" "B.Cu")
		(net "P12V_AUX")
	)
	(via
		(at 287.233614 -371.590062)
		(size 0.508)
		(drill 0.254)
		(layers "F.Cu" "B.Cu")
		(net "P12V_AUX")
	)
	(via
		(at 289.964114 -372.199662)
		(size 0.508)
		(drill 0.254)
		(layers "F.Cu" "B.Cu")
		(net "P12V_AUX")
	)
	(via
		(at 342.754204 -356.866444)
		(size 0.508)
		(drill 0.254)
		(layers "F.Cu" "B.Cu")
		(net "P12V_AUX")
	)
	(via
		(at 449.536566 -343.371932)
		(size 0.508)
		(drill 0.254)
		(layers "F.Cu" "B.Cu")
		(net "P12V_AUX")
	)
	(via
		(at 391.403332 -78.170024)
		(size 0.508)
		(drill 0.254)
		(layers "F.Cu" "B.Cu")
		(net "P12V_AUX")
	)
	(via
		(at 72.480678 -26.670762)
		(size 0.508)
		(drill 0.254)
		(layers "F.Cu" "B.Cu")
		(net "P12V_AUX")
	)
	(via
		(at 223.609408 -399.870422)
		(size 0.508)
		(drill 0.254)
		(layers "F.Cu" "B.Cu")
		(net "P12V_AUX")
	)
	(via
		(at 201.511408 -399.870422)
		(size 0.508)
		(drill 0.254)
		(layers "F.Cu" "B.Cu")
		(net "P12V_AUX")
	)
	(via
		(at 275.80082 -390.210548)
		(size 0.508)
		(drill 0.254)
		(layers "F.Cu" "B.Cu")
		(net "P12V_AUX")
	)
	(via
		(at 342.764364 -357.747824)
		(size 0.508)
		(drill 0.254)
		(layers "F.Cu" "B.Cu")
		(net "P12V_AUX")
	)
	(via
		(at 18.537174 -118.46179)
		(size 0.508)
		(drill 0.254)
		(layers "F.Cu" "B.Cu")
		(net "P12V_AUX")
	)
	(via
		(at 417.33851 -370.87683)
		(size 0.508)
		(drill 0.254)
		(layers "F.Cu" "B.Cu")
		(net "P12V_AUX")
	)
	(via
		(at 189.315344 -398.358614)
		(size 0.508)
		(drill 0.254)
		(layers "F.Cu" "B.Cu")
		(net "P12V_AUX")
	)
	(via
		(at 243.07292 -392.49604)
		(size 0.508)
		(drill 0.254)
		(layers "F.Cu" "B.Cu")
		(net "P12V_AUX")
	)
	(via
		(at 343.450164 -360.795824)
		(size 0.508)
		(drill 0.254)
		(layers "F.Cu" "B.Cu")
		(net "P12V_AUX")
	)
	(via
		(at 186.267344 -398.358614)
		(size 0.508)
		(drill 0.254)
		(layers "F.Cu" "B.Cu")
		(net "P12V_AUX")
	)
	(via
		(at 260.251448 -394.782548)
		(size 0.508)
		(drill 0.254)
		(layers "F.Cu" "B.Cu")
		(net "P12V_AUX")
	)
	(via
		(at 189.315344 -397.596614)
		(size 0.508)
		(drill 0.254)
		(layers "F.Cu" "B.Cu")
		(net "P12V_AUX")
	)
	(via
		(at 200.93305 -98.552)
		(size 0.508)
		(drill 0.254)
		(layers "F.Cu" "B.Cu")
		(net "P12V_AUX")
	)
	(via
		(at 443.002924 -28.492958)
		(size 0.4572)
		(drill 0.254)
		(layers "F.Cu" "B.Cu")
		(net "P12V_AUX")
	)
	(via
		(at 335.845912 -360.65206)
		(size 0.508)
		(drill 0.254)
		(layers "F.Cu" "B.Cu")
		(net "P12V_AUX")
	)
	(via
		(at 190.839344 -398.358614)
		(size 0.508)
		(drill 0.254)
		(layers "F.Cu" "B.Cu")
		(net "P12V_AUX")
	)
	(via
		(at 251.50953 -55.073042)
		(size 0.508)
		(drill 0.254)
		(layers "F.Cu" "B.Cu")
		(net "P12V_AUX")
	)
	(via
		(at 93.396562 -355.444044)
		(size 0.508)
		(drill 0.254)
		(layers "F.Cu" "B.Cu")
		(net "P12V_AUX")
	)
	(via
		(at 259.489448 -392.496548)
		(size 0.508)
		(drill 0.254)
		(layers "F.Cu" "B.Cu")
		(net "P12V_AUX")
	)
	(via
		(at 222.847408 -399.870422)
		(size 0.508)
		(drill 0.254)
		(layers "F.Cu" "B.Cu")
		(net "P12V_AUX")
	)
	(via
		(at 185.098182 -32.102552)
		(size 0.508)
		(drill 0.254)
		(layers "F.Cu" "B.Cu")
		(net "P12V_AUX")
	)
	(via
		(at 232.753408 -399.108422)
		(size 0.508)
		(drill 0.254)
		(layers "F.Cu" "B.Cu")
		(net "P12V_AUX")
	)
	(via
		(at 272.761456 -391.734548)
		(size 0.508)
		(drill 0.254)
		(layers "F.Cu" "B.Cu")
		(net "P12V_AUX")
	)
	(via
		(at 276.48662 -393.258548)
		(size 0.508)
		(drill 0.254)
		(layers "F.Cu" "B.Cu")
		(net "P12V_AUX")
	)
	(via
		(at 338.913216 -356.866444)
		(size 0.508)
		(drill 0.254)
		(layers "F.Cu" "B.Cu")
		(net "P12V_AUX")
	)
	(via
		(at 271.313656 -394.782548)
		(size 0.508)
		(drill 0.254)
		(layers "F.Cu" "B.Cu")
		(net "P12V_AUX")
	)
	(via
		(at 22.303486 -342.452452)
		(size 0.508)
		(drill 0.254)
		(layers "F.Cu" "B.Cu")
		(net "P12V_AUX")
	)
	(via
		(at 243.07292 -393.25804)
		(size 0.508)
		(drill 0.254)
		(layers "F.Cu" "B.Cu")
		(net "P12V_AUX")
	)
	(via
		(at 266.826492 -394.782548)
		(size 0.508)
		(drill 0.254)
		(layers "F.Cu" "B.Cu")
		(net "P12V_AUX")
	)
	(via
		(at 212.4202 -106.3752)
		(size 0.508)
		(drill 0.254)
		(layers "F.Cu" "B.Cu")
		(net "P12V_AUX")
	)
	(via
		(at 464.08213 -56.828182)
		(size 0.508)
		(drill 0.254)
		(layers "F.Cu" "B.Cu")
		(net "P12V_AUX")
	)
	(via
		(at 431.350928 -163.07816)
		(size 0.508)
		(drill 0.254)
		(layers "F.Cu" "B.Cu")
		(net "P12V_AUX")
	)
	(via
		(at 221.323408 -399.870422)
		(size 0.508)
		(drill 0.254)
		(layers "F.Cu" "B.Cu")
		(net "P12V_AUX")
	)
	(via
		(at 341.961216 -356.104444)
		(size 0.508)
		(drill 0.254)
		(layers "F.Cu" "B.Cu")
		(net "P12V_AUX")
	)
	(via
		(at 340.468712 -361.336336)
		(size 0.508)
		(drill 0.254)
		(layers "F.Cu" "B.Cu")
		(net "P12V_AUX")
	)
	(via
		(at 94.158562 -355.444044)
		(size 0.508)
		(drill 0.254)
		(layers "F.Cu" "B.Cu")
		(net "P12V_AUX")
	)
	(via
		(at 90.25255 -356.968044)
		(size 0.508)
		(drill 0.254)
		(layers "F.Cu" "B.Cu")
		(net "P12V_AUX")
	)
	(via
		(at 278.69642 -393.258548)
		(size 0.508)
		(drill 0.254)
		(layers "F.Cu" "B.Cu")
		(net "P12V_AUX")
	)
	(via
		(at 266.140692 -390.210548)
		(size 0.508)
		(drill 0.254)
		(layers "F.Cu" "B.Cu")
		(net "P12V_AUX")
	)
	(via
		(at 115.981226 -363.522006)
		(size 0.508)
		(drill 0.254)
		(layers "F.Cu" "B.Cu")
		(net "P12V_AUX")
	)
	(via
		(at 199.225408 -398.346422)
		(size 0.508)
		(drill 0.254)
		(layers "F.Cu" "B.Cu")
		(net "P12V_AUX")
	)
	(via
		(at 182.227982 -34.312352)
		(size 0.508)
		(drill 0.254)
		(layers "F.Cu" "B.Cu")
		(net "P12V_AUX")
	)
	(via
		(at 338.161376 -359.271824)
		(size 0.508)
		(drill 0.254)
		(layers "F.Cu" "B.Cu")
		(net "P12V_AUX")
	)
	(via
		(at 247.5738 -391.734548)
		(size 0.508)
		(drill 0.254)
		(layers "F.Cu" "B.Cu")
		(net "P12V_AUX")
	)
	(via
		(at 201.511408 -397.584422)
		(size 0.508)
		(drill 0.254)
		(layers "F.Cu" "B.Cu")
		(net "P12V_AUX")
	)
	(via
		(at 209.893408 -399.108422)
		(size 0.508)
		(drill 0.254)
		(layers "F.Cu" "B.Cu")
		(net "P12V_AUX")
	)
	(via
		(at 46.124622 -146.75866)
		(size 0.508)
		(drill 0.254)
		(layers "F.Cu" "B.Cu")
		(net "P12V_AUX")
	)
	(via
		(at 209.893408 -398.346422)
		(size 0.508)
		(drill 0.254)
		(layers "F.Cu" "B.Cu")
		(net "P12V_AUX")
	)
	(via
		(at 91.872562 -359.309924)
		(size 0.508)
		(drill 0.254)
		(layers "F.Cu" "B.Cu")
		(net "P12V_AUX")
	)
	(via
		(at 40.77462 -361.727496)
		(size 0.508)
		(drill 0.254)
		(layers "F.Cu" "B.Cu")
		(net "P12V_AUX")
	)
	(via
		(at 431.350928 -166.4208)
		(size 0.508)
		(drill 0.254)
		(layers "F.Cu" "B.Cu")
		(net "P12V_AUX")
	)
	(via
		(at 74.407268 -18.160746)
		(size 0.508)
		(drill 0.254)
		(layers "F.Cu" "B.Cu")
		(net "P12V_AUX")
	)
	(via
		(at 449.536566 -339.737192)
		(size 0.508)
		(drill 0.254)
		(layers "F.Cu" "B.Cu")
		(net "P12V_AUX")
	)
	(via
		(at 451.060566 -342.683592)
		(size 0.508)
		(drill 0.254)
		(layers "F.Cu" "B.Cu")
		(net "P12V_AUX")
	)
	(via
		(at 22.303486 -341.055452)
		(size 0.508)
		(drill 0.254)
		(layers "F.Cu" "B.Cu")
		(net "P12V_AUX")
	)
	(via
		(at 272.761456 -390.210548)
		(size 0.508)
		(drill 0.254)
		(layers "F.Cu" "B.Cu")
		(net "P12V_AUX")
	)
	(via
		(at 463.32013 -57.488582)
		(size 0.508)
		(drill 0.254)
		(layers "F.Cu" "B.Cu")
		(net "P12V_AUX")
	)
	(via
		(at 432.676808 -165.085014)
		(size 0.508)
		(drill 0.254)
		(layers "F.Cu" "B.Cu")
		(net "P12V_AUX")
	)
	(via
		(at 221.323408 -396.822422)
		(size 0.508)
		(drill 0.254)
		(layers "F.Cu" "B.Cu")
		(net "P12V_AUX")
	)
	(via
		(at 254.17907 -48.816514)
		(size 0.4572)
		(drill 0.254)
		(layers "F.Cu" "B.Cu")
		(net "P12V_AUX")
	)
	(via
		(at 276.48662 -394.020548)
		(size 0.508)
		(drill 0.254)
		(layers "F.Cu" "B.Cu")
		(net "P12V_AUX")
	)
	(via
		(at 94.125542 -356.955344)
		(size 0.508)
		(drill 0.254)
		(layers "F.Cu" "B.Cu")
		(net "P12V_AUX")
	)
	(via
		(at 212.179408 -398.346422)
		(size 0.508)
		(drill 0.254)
		(layers "F.Cu" "B.Cu")
		(net "P12V_AUX")
	)
	(via
		(at 287.995614 -373.749062)
		(size 0.508)
		(drill 0.254)
		(layers "F.Cu" "B.Cu")
		(net "P12V_AUX")
	)
	(via
		(at 278.69642 -394.782548)
		(size 0.508)
		(drill 0.254)
		(layers "F.Cu" "B.Cu")
		(net "P12V_AUX")
	)
	(via
		(at 90.25255 -359.254044)
		(size 0.508)
		(drill 0.254)
		(layers "F.Cu" "B.Cu")
		(net "P12V_AUX")
	)
	(via
		(at 23.929086 -341.055452)
		(size 0.508)
		(drill 0.254)
		(layers "F.Cu" "B.Cu")
		(net "P12V_AUX")
	)
	(via
		(at 253.54407 -50.616612)
		(size 0.4572)
		(drill 0.254)
		(layers "F.Cu" "B.Cu")
		(net "P12V_AUX")
	)
	(via
		(at 275.80082 -390.972548)
		(size 0.508)
		(drill 0.254)
		(layers "F.Cu" "B.Cu")
		(net "P12V_AUX")
	)
	(via
		(at 335.835244 -358.476804)
		(size 0.508)
		(drill 0.254)
		(layers "F.Cu" "B.Cu")
		(net "P12V_AUX")
	)
	(via
		(at 435.48046 -36.30168)
		(size 0.508)
		(drill 0.254)
		(layers "F.Cu" "B.Cu")
		(net "P12V_AUX")
	)
	(via
		(at 79.008478 -28.651962)
		(size 0.508)
		(drill 0.254)
		(layers "F.Cu" "B.Cu")
		(net "P12V_AUX")
	)
	(via
		(at 199.225408 -399.870422)
		(size 0.508)
		(drill 0.254)
		(layers "F.Cu" "B.Cu")
		(net "P12V_AUX")
	)
	(via
		(at 187.791344 -399.882614)
		(size 0.508)
		(drill 0.254)
		(layers "F.Cu" "B.Cu")
		(net "P12V_AUX")
	)
	(via
		(at 263.981692 -390.972548)
		(size 0.508)
		(drill 0.254)
		(layers "F.Cu" "B.Cu")
		(net "P12V_AUX")
	)
	(via
		(at 450.298566 -343.371932)
		(size 0.508)
		(drill 0.254)
		(layers "F.Cu" "B.Cu")
		(net "P12V_AUX")
	)
	(via
		(at 265.378692 -390.972548)
		(size 0.508)
		(drill 0.254)
		(layers "F.Cu" "B.Cu")
		(net "P12V_AUX")
	)
	(via
		(at 452.584566 -341.210392)
		(size 0.508)
		(drill 0.254)
		(layers "F.Cu" "B.Cu")
		(net "P12V_AUX")
	)
	(via
		(at 266.140692 -392.496548)
		(size 0.508)
		(drill 0.254)
		(layers "F.Cu" "B.Cu")
		(net "P12V_AUX")
	)
	(via
		(at 213.703408 -396.060422)
		(size 0.508)
		(drill 0.254)
		(layers "F.Cu" "B.Cu")
		(net "P12V_AUX")
	)
	(via
		(at 452.584566 -337.146392)
		(size 0.508)
		(drill 0.254)
		(layers "F.Cu" "B.Cu")
		(net "P12V_AUX")
	)
	(via
		(at 223.609408 -397.584422)
		(size 0.508)
		(drill 0.254)
		(layers "F.Cu" "B.Cu")
		(net "P12V_AUX")
	)
	(via
		(at 340.447376 -359.271824)
		(size 0.508)
		(drill 0.254)
		(layers "F.Cu" "B.Cu")
		(net "P12V_AUX")
	)
	(via
		(at 234.277408 -399.870422)
		(size 0.508)
		(drill 0.254)
		(layers "F.Cu" "B.Cu")
		(net "P12V_AUX")
	)
	(via
		(at 246.126 -391.734548)
		(size 0.508)
		(drill 0.254)
		(layers "F.Cu" "B.Cu")
		(net "P12V_AUX")
	)
	(via
		(at 336.571336 -360.696764)
		(size 0.508)
		(drill 0.254)
		(layers "F.Cu" "B.Cu")
		(net "P12V_AUX")
	)
	(via
		(at 209.893408 -397.584422)
		(size 0.508)
		(drill 0.254)
		(layers "F.Cu" "B.Cu")
		(net "P12V_AUX")
	)
	(via
		(at 259.489448 -391.734548)
		(size 0.508)
		(drill 0.254)
		(layers "F.Cu" "B.Cu")
		(net "P12V_AUX")
	)
	(via
		(at 453.346566 -339.737192)
		(size 0.508)
		(drill 0.254)
		(layers "F.Cu" "B.Cu")
		(net "P12V_AUX")
	)
	(via
		(at 91.872562 -356.206044)
		(size 0.508)
		(drill 0.254)
		(layers "F.Cu" "B.Cu")
		(net "P12V_AUX")
	)
	(via
		(at 230.467408 -399.108422)
		(size 0.508)
		(drill 0.254)
		(layers "F.Cu" "B.Cu")
		(net "P12V_AUX")
	)
	(via
		(at 223.609408 -398.346422)
		(size 0.508)
		(drill 0.254)
		(layers "F.Cu" "B.Cu")
		(net "P12V_AUX")
	)
	(via
		(at 233.515408 -399.108422)
		(size 0.508)
		(drill 0.254)
		(layers "F.Cu" "B.Cu")
		(net "P12V_AUX")
	)
	(via
		(at 260.251448 -394.020548)
		(size 0.508)
		(drill 0.254)
		(layers "F.Cu" "B.Cu")
		(net "P12V_AUX")
	)
	(via
		(at 291.79393 -54.287674)
		(size 0.508)
		(drill 0.254)
		(layers "F.Cu" "B.Cu")
		(net "P12V_AUX")
	)
	(via
		(at 209.131408 -399.870422)
		(size 0.508)
		(drill 0.254)
		(layers "F.Cu" "B.Cu")
		(net "P12V_AUX")
	)
	(via
		(at 188.553344 -399.120614)
		(size 0.508)
		(drill 0.254)
		(layers "F.Cu" "B.Cu")
		(net "P12V_AUX")
	)
	(via
		(at 343.450164 -359.271824)
		(size 0.508)
		(drill 0.254)
		(layers "F.Cu" "B.Cu")
		(net "P12V_AUX")
	)
	(via
		(at 90.987118 -358.49687)
		(size 0.508)
		(drill 0.254)
		(layers "F.Cu" "B.Cu")
		(net "P12V_AUX")
	)
	(via
		(at 336.560668 -359.283508)
		(size 0.508)
		(drill 0.254)
		(layers "F.Cu" "B.Cu")
		(net "P12V_AUX")
	)
	(via
		(at 91.110562 -356.206044)
		(size 0.508)
		(drill 0.254)
		(layers "F.Cu" "B.Cu")
		(net "P12V_AUX")
	)
	(via
		(at 269.865856 -394.782548)
		(size 0.508)
		(drill 0.254)
		(layers "F.Cu" "B.Cu")
		(net "P12V_AUX")
	)
	(via
		(at 233.515408 -398.346422)
		(size 0.508)
		(drill 0.254)
		(layers "F.Cu" "B.Cu")
		(net "P12V_AUX")
	)
	(via
		(at 432.016408 -166.405814)
		(size 0.508)
		(drill 0.254)
		(layers "F.Cu" "B.Cu")
		(net "P12V_AUX")
	)
	(via
		(at 260.911848 -394.782548)
		(size 0.508)
		(drill 0.254)
		(layers "F.Cu" "B.Cu")
		(net "P12V_AUX")
	)
	(via
		(at 254.956564 -393.258548)
		(size 0.508)
		(drill 0.254)
		(layers "F.Cu" "B.Cu")
		(net "P12V_AUX")
	)
	(via
		(at 464.696556 -380.542292)
		(size 0.508)
		(drill 0.254)
		(layers "F.Cu" "B.Cu")
		(net "P12V_AUX")
	)
	(via
		(at 464.74253 -58.148982)
		(size 0.508)
		(drill 0.254)
		(layers "F.Cu" "B.Cu")
		(net "P12V_AUX")
	)
	(via
		(at 247.780048 -71.652384)
		(size 0.508)
		(drill 0.254)
		(layers "F.Cu" "B.Cu")
		(net "P12V_AUX")
	)
	(via
		(at 185.505344 -396.834614)
		(size 0.508)
		(drill 0.254)
		(layers "F.Cu" "B.Cu")
		(net "P12V_AUX")
	)
	(via
		(at 337.335368 -361.987592)
		(size 0.508)
		(drill 0.254)
		(layers "F.Cu" "B.Cu")
		(net "P12V_AUX")
	)
	(via
		(at 263.981692 -394.782548)
		(size 0.508)
		(drill 0.254)
		(layers "F.Cu" "B.Cu")
		(net "P12V_AUX")
	)
	(via
		(at 18.493486 -338.180172)
		(size 0.508)
		(drill 0.254)
		(layers "F.Cu" "B.Cu")
		(net "P12V_AUX")
	)
	(via
		(at 341.230712 -361.336336)
		(size 0.508)
		(drill 0.254)
		(layers "F.Cu" "B.Cu")
		(net "P12V_AUX")
	)
	(via
		(at 338.151216 -356.866444)
		(size 0.508)
		(drill 0.254)
		(layers "F.Cu" "B.Cu")
		(net "P12V_AUX")
	)
	(via
		(at 47.445422 -146.75866)
		(size 0.508)
		(drill 0.254)
		(layers "F.Cu" "B.Cu")
		(net "P12V_AUX")
	)
	(via
		(at 253.54407 -51.516534)
		(size 0.4572)
		(drill 0.254)
		(layers "F.Cu" "B.Cu")
		(net "P12V_AUX")
	)
	(via
		(at 464.08213 -59.418982)
		(size 0.508)
		(drill 0.254)
		(layers "F.Cu" "B.Cu")
		(net "P12V_AUX")
	)
	(via
		(at 235.039408 -396.822422)
		(size 0.508)
		(drill 0.254)
		(layers "F.Cu" "B.Cu")
		(net "P12V_AUX")
	)
	(via
		(at 269.865856 -391.734548)
		(size 0.508)
		(drill 0.254)
		(layers "F.Cu" "B.Cu")
		(net "P12V_AUX")
	)
	(via
		(at 258.067048 -391.734548)
		(size 0.508)
		(drill 0.254)
		(layers "F.Cu" "B.Cu")
		(net "P12V_AUX")
	)
	(via
		(at 94.887542 -356.955344)
		(size 0.508)
		(drill 0.254)
		(layers "F.Cu" "B.Cu")
		(net "P12V_AUX")
	)
	(via
		(at 189.315344 -399.882614)
		(size 0.508)
		(drill 0.254)
		(layers "F.Cu" "B.Cu")
		(net "P12V_AUX")
	)
	(via
		(at 289.964114 -371.564662)
		(size 0.508)
		(drill 0.254)
		(layers "F.Cu" "B.Cu")
		(net "P12V_AUX")
	)
	(via
		(at 414.60801 -373.06123)
		(size 0.508)
		(drill 0.254)
		(layers "F.Cu" "B.Cu")
		(net "P12V_AUX")
	)
	(via
		(at 341.961216 -356.866444)
		(size 0.508)
		(drill 0.254)
		(layers "F.Cu" "B.Cu")
		(net "P12V_AUX")
	)
	(via
		(at 69.222366 -28.207462)
		(size 0.4572)
		(drill 0.254)
		(layers "F.Cu" "B.Cu")
		(net "P12V_AUX")
	)
	(via
		(at 248.90476 -72.964548)
		(size 0.508)
		(drill 0.254)
		(layers "F.Cu" "B.Cu")
		(net "P12V_AUX")
	)
	(via
		(at 242.31092 -391.73404)
		(size 0.508)
		(drill 0.254)
		(layers "F.Cu" "B.Cu")
		(net "P12V_AUX")
	)
	(via
		(at 219.799408 -396.822422)
		(size 0.508)
		(drill 0.254)
		(layers "F.Cu" "B.Cu")
		(net "P12V_AUX")
	)
	(via
		(at 209.550762 -98.809048)
		(size 0.508)
		(drill 0.254)
		(layers "F.Cu" "B.Cu")
		(net "P12V_AUX")
	)
	(via
		(at 432.676808 -163.063174)
		(size 0.508)
		(drill 0.254)
		(layers "F.Cu" "B.Cu")
		(net "P12V_AUX")
	)
	(via
		(at 269.865856 -394.020548)
		(size 0.508)
		(drill 0.254)
		(layers "F.Cu" "B.Cu")
		(net "P12V_AUX")
	)
	(via
		(at 272.075656 -390.972548)
		(size 0.508)
		(drill 0.254)
		(layers "F.Cu" "B.Cu")
		(net "P12V_AUX")
	)
	(via
		(at 242.31092 -394.78204)
		(size 0.508)
		(drill 0.254)
		(layers "F.Cu" "B.Cu")
		(net "P12V_AUX")
	)
	(via
		(at 452.584566 -342.683592)
		(size 0.508)
		(drill 0.254)
		(layers "F.Cu" "B.Cu")
		(net "P12V_AUX")
	)
	(via
		(at 93.396562 -356.206044)
		(size 0.508)
		(drill 0.254)
		(layers "F.Cu" "B.Cu")
		(net "P12V_AUX")
	)
	(via
		(at 199.225408 -399.108422)
		(size 0.508)
		(drill 0.254)
		(layers "F.Cu" "B.Cu")
		(net "P12V_AUX")
	)
	(via
		(at 278.01062 -394.020548)
		(size 0.508)
		(drill 0.254)
		(layers "F.Cu" "B.Cu")
		(net "P12V_AUX")
	)
	(via
		(at 431.350928 -163.7792)
		(size 0.508)
		(drill 0.254)
		(layers "F.Cu" "B.Cu")
		(net "P12V_AUX")
	)
	(via
		(at 264.616692 -393.258548)
		(size 0.508)
		(drill 0.254)
		(layers "F.Cu" "B.Cu")
		(net "P12V_AUX")
	)
	(via
		(at 240.02492 -393.25804)
		(size 0.508)
		(drill 0.254)
		(layers "F.Cu" "B.Cu")
		(net "P12V_AUX")
	)
	(via
		(at 249.0216 -394.020548)
		(size 0.508)
		(drill 0.254)
		(layers "F.Cu" "B.Cu")
		(net "P12V_AUX")
	)
	(via
		(at 189.315344 -396.072614)
		(size 0.508)
		(drill 0.254)
		(layers "F.Cu" "B.Cu")
		(net "P12V_AUX")
	)
	(via
		(at 364.315248 -359.460038)
		(size 0.508)
		(drill 0.254)
		(layers "F.Cu" "B.Cu")
		(net "P12V_AUX")
	)
	(via
		(at 450.298566 -341.946992)
		(size 0.508)
		(drill 0.254)
		(layers "F.Cu" "B.Cu")
		(net "P12V_AUX")
	)
	(via
		(at 335.835244 -359.238804)
		(size 0.508)
		(drill 0.254)
		(layers "F.Cu" "B.Cu")
		(net "P12V_AUX")
	)
	(via
		(at 210.655408 -399.870422)
		(size 0.508)
		(drill 0.254)
		(layers "F.Cu" "B.Cu")
		(net "P12V_AUX")
	)
	(via
		(at 260.911848 -392.496548)
		(size 0.508)
		(drill 0.254)
		(layers "F.Cu" "B.Cu")
		(net "P12V_AUX")
	)
	(via
		(at 223.609408 -399.108422)
		(size 0.508)
		(drill 0.254)
		(layers "F.Cu" "B.Cu")
		(net "P12V_AUX")
	)
	(via
		(at 449.536566 -341.946992)
		(size 0.508)
		(drill 0.254)
		(layers "F.Cu" "B.Cu")
		(net "P12V_AUX")
	)
	(via
		(at 277.24862 -394.020548)
		(size 0.508)
		(drill 0.254)
		(layers "F.Cu" "B.Cu")
		(net "P12V_AUX")
	)
	(via
		(at 222.085408 -399.108422)
		(size 0.508)
		(drill 0.254)
		(layers "F.Cu" "B.Cu")
		(net "P12V_AUX")
	)
	(via
		(at 278.69642 -392.496548)
		(size 0.508)
		(drill 0.254)
		(layers "F.Cu" "B.Cu")
		(net "P12V_AUX")
	)
	(via
		(at 258.727448 -390.972548)
		(size 0.508)
		(drill 0.254)
		(layers "F.Cu" "B.Cu")
		(net "P12V_AUX")
	)
	(via
		(at 43.508422 -145.463006)
		(size 0.508)
		(drill 0.254)
		(layers "F.Cu" "B.Cu")
		(net "P12V_AUX")
	)
	(via
		(at 253.508764 -394.782548)
		(size 0.508)
		(drill 0.254)
		(layers "F.Cu" "B.Cu")
		(net "P12V_AUX")
	)
	(via
		(at 241.54892 -390.21004)
		(size 0.508)
		(drill 0.254)
		(layers "F.Cu" "B.Cu")
		(net "P12V_AUX")
	)
	(via
		(at 264.616692 -390.210548)
		(size 0.508)
		(drill 0.254)
		(layers "F.Cu" "B.Cu")
		(net "P12V_AUX")
	)
	(via
		(at 203.035408 -396.822422)
		(size 0.508)
		(drill 0.254)
		(layers "F.Cu" "B.Cu")
		(net "P12V_AUX")
	)
	(via
		(at 19.280886 -340.344252)
		(size 0.508)
		(drill 0.254)
		(layers "F.Cu" "B.Cu")
		(net "P12V_AUX")
	)
	(via
		(at 79.618078 -24.587962)
		(size 0.508)
		(drill 0.254)
		(layers "F.Cu" "B.Cu")
		(net "P12V_AUX")
	)
	(via
		(at 39.37762 -361.727496)
		(size 0.508)
		(drill 0.254)
		(layers "F.Cu" "B.Cu")
		(net "P12V_AUX")
	)
	(via
		(at 44.803822 -146.098006)
		(size 0.508)
		(drill 0.254)
		(layers "F.Cu" "B.Cu")
		(net "P12V_AUX")
	)
	(via
		(at 339.675216 -356.866444)
		(size 0.508)
		(drill 0.254)
		(layers "F.Cu" "B.Cu")
		(net "P12V_AUX")
	)
	(via
		(at 452.584566 -337.882992)
		(size 0.508)
		(drill 0.254)
		(layers "F.Cu" "B.Cu")
		(net "P12V_AUX")
	)
	(via
		(at 447.036698 -337.38185)
		(size 0.508)
		(drill 0.254)
		(layers "F.Cu" "B.Cu")
		(net "P12V_AUX")
	)
	(via
		(at 277.24862 -393.258548)
		(size 0.508)
		(drill 0.254)
		(layers "F.Cu" "B.Cu")
		(net "P12V_AUX")
	)
	(via
		(at 278.01062 -390.972548)
		(size 0.508)
		(drill 0.254)
		(layers "F.Cu" "B.Cu")
		(net "P12V_AUX")
	)
	(via
		(at 164.29101 -131.565396)
		(size 0.508)
		(drill 0.254)
		(layers "F.Cu" "B.Cu")
		(net "P12V_AUX")
	)
	(via
		(at 95.71355 -355.444044)
		(size 0.508)
		(drill 0.254)
		(layers "F.Cu" "B.Cu")
		(net "P12V_AUX")
	)
	(via
		(at 247.5738 -390.210548)
		(size 0.508)
		(drill 0.254)
		(layers "F.Cu" "B.Cu")
		(net "P12V_AUX")
	)
	(via
		(at 466.82533 -56.828182)
		(size 0.508)
		(drill 0.254)
		(layers "F.Cu" "B.Cu")
		(net "P12V_AUX")
	)
	(via
		(at 252.746764 -392.496548)
		(size 0.508)
		(drill 0.254)
		(layers "F.Cu" "B.Cu")
		(net "P12V_AUX")
	)
	(via
		(at 40.01262 -362.997496)
		(size 0.508)
		(drill 0.254)
		(layers "F.Cu" "B.Cu")
		(net "P12V_AUX")
	)
	(via
		(at 39.37762 -364.521496)
		(size 0.508)
		(drill 0.254)
		(layers "F.Cu" "B.Cu")
		(net "P12V_AUX")
	)
	(via
		(at 222.847408 -397.584422)
		(size 0.508)
		(drill 0.254)
		(layers "F.Cu" "B.Cu")
		(net "P12V_AUX")
	)
	(via
		(at 211.417408 -398.346422)
		(size 0.508)
		(drill 0.254)
		(layers "F.Cu" "B.Cu")
		(net "P12V_AUX")
	)
	(via
		(at 95.71355 -360.016044)
		(size 0.508)
		(drill 0.254)
		(layers "F.Cu" "B.Cu")
		(net "P12V_AUX")
	)
	(via
		(at 242.31092 -390.21004)
		(size 0.508)
		(drill 0.254)
		(layers "F.Cu" "B.Cu")
		(net "P12V_AUX")
	)
	(via
		(at 276.48662 -391.734548)
		(size 0.508)
		(drill 0.254)
		(layers "F.Cu" "B.Cu")
		(net "P12V_AUX")
	)
	(via
		(at 260.911848 -391.734548)
		(size 0.508)
		(drill 0.254)
		(layers "F.Cu" "B.Cu")
		(net "P12V_AUX")
	)
	(via
		(at 95.71355 -356.968044)
		(size 0.508)
		(drill 0.254)
		(layers "F.Cu" "B.Cu")
		(net "P12V_AUX")
	)
	(via
		(at 271.313656 -390.210548)
		(size 0.508)
		(drill 0.254)
		(layers "F.Cu" "B.Cu")
		(net "P12V_AUX")
	)
	(via
		(at 448.774566 -339.737192)
		(size 0.508)
		(drill 0.254)
		(layers "F.Cu" "B.Cu")
		(net "P12V_AUX")
	)
	(via
		(at 220.561408 -399.108422)
		(size 0.508)
		(drill 0.254)
		(layers "F.Cu" "B.Cu")
		(net "P12V_AUX")
	)
	(via
		(at 225.383852 -75.37704)
		(size 0.508)
		(drill 0.254)
		(layers "F.Cu" "B.Cu")
		(net "P12V_AUX")
	)
	(via
		(at 44.143422 -146.098006)
		(size 0.508)
		(drill 0.254)
		(layers "F.Cu" "B.Cu")
		(net "P12V_AUX")
	)
	(via
		(at 22.303486 -340.420452)
		(size 0.508)
		(drill 0.254)
		(layers "F.Cu" "B.Cu")
		(net "P12V_AUX")
	)
	(via
		(at 276.930866 -32.137096)
		(size 0.508)
		(drill 0.254)
		(layers "F.Cu" "B.Cu")
		(net "P12V_AUX")
	)
	(via
		(at 18.518886 -340.344252)
		(size 0.508)
		(drill 0.254)
		(layers "F.Cu" "B.Cu")
		(net "P12V_AUX")
	)
	(via
		(at 213.703408 -398.346422)
		(size 0.508)
		(drill 0.254)
		(layers "F.Cu" "B.Cu")
		(net "P12V_AUX")
	)
	(via
		(at 88.621362 -359.983024)
		(size 0.508)
		(drill 0.254)
		(layers "F.Cu" "B.Cu")
		(net "P12V_AUX")
	)
	(via
		(at 337.293204 -356.866444)
		(size 0.508)
		(drill 0.254)
		(layers "F.Cu" "B.Cu")
		(net "P12V_AUX")
	)
	(via
		(at 96.47555 -357.730044)
		(size 0.508)
		(drill 0.254)
		(layers "F.Cu" "B.Cu")
		(net "P12V_AUX")
	)
	(via
		(at 275.80082 -392.496548)
		(size 0.508)
		(drill 0.254)
		(layers "F.Cu" "B.Cu")
		(net "P12V_AUX")
	)
	(via
		(at 270.551656 -394.020548)
		(size 0.508)
		(drill 0.254)
		(layers "F.Cu" "B.Cu")
		(net "P12V_AUX")
	)
	(via
		(at 339.685376 -360.033824)
		(size 0.508)
		(drill 0.254)
		(layers "F.Cu" "B.Cu")
		(net "P12V_AUX")
	)
	(via
		(at 278.69642 -394.020548)
		(size 0.508)
		(drill 0.254)
		(layers "F.Cu" "B.Cu")
		(net "P12V_AUX")
	)
	(via
		(at 466.82533 -57.488582)
		(size 0.508)
		(drill 0.254)
		(layers "F.Cu" "B.Cu")
		(net "P12V_AUX")
	)
	(via
		(at 209.893408 -396.060422)
		(size 0.508)
		(drill 0.254)
		(layers "F.Cu" "B.Cu")
		(net "P12V_AUX")
	)
	(via
		(at 203.035408 -397.584422)
		(size 0.508)
		(drill 0.254)
		(layers "F.Cu" "B.Cu")
		(net "P12V_AUX")
	)
	(via
		(at 448.774566 -341.210392)
		(size 0.508)
		(drill 0.254)
		(layers "F.Cu" "B.Cu")
		(net "P12V_AUX")
	)
	(via
		(at 463.32013 -59.418982)
		(size 0.508)
		(drill 0.254)
		(layers "F.Cu" "B.Cu")
		(net "P12V_AUX")
	)
	(via
		(at 172.039026 -363.438186)
		(size 0.508)
		(drill 0.254)
		(layers "F.Cu" "B.Cu")
		(net "P12V_AUX")
	)
	(via
		(at 414.60801 -371.53723)
		(size 0.508)
		(drill 0.254)
		(layers "F.Cu" "B.Cu")
		(net "P12V_AUX")
	)
	(via
		(at 46.785022 -146.75866)
		(size 0.508)
		(drill 0.254)
		(layers "F.Cu" "B.Cu")
		(net "P12V_AUX")
	)
	(via
		(at 414.60801 -372.29923)
		(size 0.508)
		(drill 0.254)
		(layers "F.Cu" "B.Cu")
		(net "P12V_AUX")
	)
	(via
		(at 212.179408 -399.870422)
		(size 0.508)
		(drill 0.254)
		(layers "F.Cu" "B.Cu")
		(net "P12V_AUX")
	)
	(via
		(at 211.417408 -399.870422)
		(size 0.508)
		(drill 0.254)
		(layers "F.Cu" "B.Cu")
		(net "P12V_AUX")
	)
	(via
		(at 278.01062 -392.496548)
		(size 0.508)
		(drill 0.254)
		(layers "F.Cu" "B.Cu")
		(net "P12V_AUX")
	)
	(via
		(at 235.039408 -399.870422)
		(size 0.508)
		(drill 0.254)
		(layers "F.Cu" "B.Cu")
		(net "P12V_AUX")
	)
	(via
		(at 185.505344 -396.072614)
		(size 0.508)
		(drill 0.254)
		(layers "F.Cu" "B.Cu")
		(net "P12V_AUX")
	)
	(via
		(at 441.20308 -27.857958)
		(size 0.4572)
		(drill 0.254)
		(layers "F.Cu" "B.Cu")
		(net "P12V_AUX")
	)
	(via
		(at 186.267344 -399.120614)
		(size 0.508)
		(drill 0.254)
		(layers "F.Cu" "B.Cu")
		(net "P12V_AUX")
	)
	(via
		(at 249.0216 -393.258548)
		(size 0.508)
		(drill 0.254)
		(layers "F.Cu" "B.Cu")
		(net "P12V_AUX")
	)
	(via
		(at 242.31092 -390.97204)
		(size 0.508)
		(drill 0.254)
		(layers "F.Cu" "B.Cu")
		(net "P12V_AUX")
	)
	(via
		(at 187.029344 -397.596614)
		(size 0.508)
		(drill 0.254)
		(layers "F.Cu" "B.Cu")
		(net "P12V_AUX")
	)
	(via
		(at 21.541486 -340.420452)
		(size 0.508)
		(drill 0.254)
		(layers "F.Cu" "B.Cu")
		(net "P12V_AUX")
	)
	(via
		(at 200.749408 -397.584422)
		(size 0.508)
		(drill 0.254)
		(layers "F.Cu" "B.Cu")
		(net "P12V_AUX")
	)
	(via
		(at 432.676808 -164.424614)
		(size 0.508)
		(drill 0.254)
		(layers "F.Cu" "B.Cu")
		(net "P12V_AUX")
	)
	(via
		(at 96.47555 -358.492044)
		(size 0.508)
		(drill 0.254)
		(layers "F.Cu" "B.Cu")
		(net "P12V_AUX")
	)
	(via
		(at 252.746764 -390.972548)
		(size 0.508)
		(drill 0.254)
		(layers "F.Cu" "B.Cu")
		(net "P12V_AUX")
	)
	(via
		(at 89.525602 -356.942644)
		(size 0.508)
		(drill 0.254)
		(layers "F.Cu" "B.Cu")
		(net "P12V_AUX")
	)
	(via
		(at 447.288412 -29.648658)
		(size 0.508)
		(drill 0.254)
		(layers "F.Cu" "B.Cu")
		(net "P12V_AUX")
	)
	(via
		(at 269.865856 -390.210548)
		(size 0.508)
		(drill 0.254)
		(layers "F.Cu" "B.Cu")
		(net "P12V_AUX")
	)
	(via
		(at 270.551656 -394.782548)
		(size 0.508)
		(drill 0.254)
		(layers "F.Cu" "B.Cu")
		(net "P12V_AUX")
	)
	(via
		(at 451.822566 -337.882992)
		(size 0.508)
		(drill 0.254)
		(layers "F.Cu" "B.Cu")
		(net "P12V_AUX")
	)
	(via
		(at 256.46888 -40.842946)
		(size 0.508)
		(drill 0.254)
		(layers "F.Cu" "B.Cu")
		(net "P12V_AUX")
	)
	(via
		(at 169.836846 -364.273846)
		(size 0.508)
		(drill 0.254)
		(layers "F.Cu" "B.Cu")
		(net "P12V_AUX")
	)
	(via
		(at 94.111318 -359.31221)
		(size 0.508)
		(drill 0.254)
		(layers "F.Cu" "B.Cu")
		(net "P12V_AUX")
	)
	(via
		(at 222.085408 -399.870422)
		(size 0.508)
		(drill 0.254)
		(layers "F.Cu" "B.Cu")
		(net "P12V_AUX")
	)
	(via
		(at 258.727448 -391.734548)
		(size 0.508)
		(drill 0.254)
		(layers "F.Cu" "B.Cu")
		(net "P12V_AUX")
	)
	(via
		(at 464.74253 -57.488582)
		(size 0.508)
		(drill 0.254)
		(layers "F.Cu" "B.Cu")
		(net "P12V_AUX")
	)
	(via
		(at 308.8132 -28.2702)
		(size 0.508)
		(drill 0.254)
		(layers "F.Cu" "B.Cu")
		(net "P12V_AUX")
	)
	(via
		(at 252.086364 -394.782548)
		(size 0.508)
		(drill 0.254)
		(layers "F.Cu" "B.Cu")
		(net "P12V_AUX")
	)
	(via
		(at 260.251448 -392.496548)
		(size 0.508)
		(drill 0.254)
		(layers "F.Cu" "B.Cu")
		(net "P12V_AUX")
	)
	(via
		(at 209.131408 -399.108422)
		(size 0.508)
		(drill 0.254)
		(layers "F.Cu" "B.Cu")
		(net "P12V_AUX")
	)
	(via
		(at 259.489448 -394.782548)
		(size 0.508)
		(drill 0.254)
		(layers "F.Cu" "B.Cu")
		(net "P12V_AUX")
	)
	(via
		(at 231.229408 -397.584422)
		(size 0.508)
		(drill 0.254)
		(layers "F.Cu" "B.Cu")
		(net "P12V_AUX")
	)
	(via
		(at 40.01262 -364.521496)
		(size 0.508)
		(drill 0.254)
		(layers "F.Cu" "B.Cu")
		(net "P12V_AUX")
	)
	(via
		(at 264.616692 -394.782548)
		(size 0.508)
		(drill 0.254)
		(layers "F.Cu" "B.Cu")
		(net "P12V_AUX")
	)
	(via
		(at 337.303364 -360.033824)
		(size 0.508)
		(drill 0.254)
		(layers "F.Cu" "B.Cu")
		(net "P12V_AUX")
	)
	(via
		(at 259.489448 -394.020548)
		(size 0.508)
		(drill 0.254)
		(layers "F.Cu" "B.Cu")
		(net "P12V_AUX")
	)
	(via
		(at 221.323408 -397.584422)
		(size 0.508)
		(drill 0.254)
		(layers "F.Cu" "B.Cu")
		(net "P12V_AUX")
	)
	(via
		(at 91.110562 -360.016044)
		(size 0.508)
		(drill 0.254)
		(layers "F.Cu" "B.Cu")
		(net "P12V_AUX")
	)
	(via
		(at 248.3358 -392.496548)
		(size 0.508)
		(drill 0.254)
		(layers "F.Cu" "B.Cu")
		(net "P12V_AUX")
	)
	(via
		(at 254.270764 -390.210548)
		(size 0.508)
		(drill 0.254)
		(layers "F.Cu" "B.Cu")
		(net "P12V_AUX")
	)
	(via
		(at 260.251448 -390.972548)
		(size 0.508)
		(drill 0.254)
		(layers "F.Cu" "B.Cu")
		(net "P12V_AUX")
	)
	(via
		(at 258.067048 -390.972548)
		(size 0.508)
		(drill 0.254)
		(layers "F.Cu" "B.Cu")
		(net "P12V_AUX")
	)
	(via
		(at 213.703408 -396.822422)
		(size 0.508)
		(drill 0.254)
		(layers "F.Cu" "B.Cu")
		(net "P12V_AUX")
	)
	(via
		(at 432.016408 -165.085014)
		(size 0.508)
		(drill 0.254)
		(layers "F.Cu" "B.Cu")
		(net "P12V_AUX")
	)
	(via
		(at 260.911848 -394.020548)
		(size 0.508)
		(drill 0.254)
		(layers "F.Cu" "B.Cu")
		(net "P12V_AUX")
	)
	(via
		(at 212.179408 -396.822422)
		(size 0.508)
		(drill 0.254)
		(layers "F.Cu" "B.Cu")
		(net "P12V_AUX")
	)
	(via
		(at 258.067048 -394.020548)
		(size 0.508)
		(drill 0.254)
		(layers "F.Cu" "B.Cu")
		(net "P12V_AUX")
	)
	(via
		(at 204.724 -91.5924)
		(size 0.508)
		(drill 0.254)
		(layers "F.Cu" "B.Cu")
		(net "P12V_AUX")
	)
	(via
		(at 259.489448 -390.972548)
		(size 0.508)
		(drill 0.254)
		(layers "F.Cu" "B.Cu")
		(net "P12V_AUX")
	)
	(via
		(at 246.126 -394.782548)
		(size 0.508)
		(drill 0.254)
		(layers "F.Cu" "B.Cu")
		(net "P12V_AUX")
	)
	(via
		(at 336.582004 -361.34802)
		(size 0.508)
		(drill 0.254)
		(layers "F.Cu" "B.Cu")
		(net "P12V_AUX")
	)
	(via
		(at 266.826492 -393.258548)
		(size 0.508)
		(drill 0.254)
		(layers "F.Cu" "B.Cu")
		(net "P12V_AUX")
	)
	(via
		(at 240.78692 -390.97204)
		(size 0.508)
		(drill 0.254)
		(layers "F.Cu" "B.Cu")
		(net "P12V_AUX")
	)
	(via
		(at 466.06333 -59.418982)
		(size 0.508)
		(drill 0.254)
		(layers "F.Cu" "B.Cu")
		(net "P12V_AUX")
	)
	(via
		(at 222.847408 -396.060422)
		(size 0.508)
		(drill 0.254)
		(layers "F.Cu" "B.Cu")
		(net "P12V_AUX")
	)
	(via
		(at 211.5058 -113.4872)
		(size 0.508)
		(drill 0.254)
		(layers "F.Cu" "B.Cu")
		(net "P12V_AUX")
	)
	(via
		(at 190.077344 -399.882614)
		(size 0.508)
		(drill 0.254)
		(layers "F.Cu" "B.Cu")
		(net "P12V_AUX")
	)
	(via
		(at 417.23183 -374.30583)
		(size 0.508)
		(drill 0.254)
		(layers "F.Cu" "B.Cu")
		(net "P12V_AUX")
	)
	(via
		(at 450.298566 -340.473792)
		(size 0.508)
		(drill 0.254)
		(layers "F.Cu" "B.Cu")
		(net "P12V_AUX")
	)
	(via
		(at 39.36746 -361.049316)
		(size 0.508)
		(drill 0.254)
		(layers "F.Cu" "B.Cu")
		(net "P12V_AUX")
	)
	(via
		(at 446.018412 -27.540458)
		(size 0.508)
		(drill 0.254)
		(layers "F.Cu" "B.Cu")
		(net "P12V_AUX")
	)
	(via
		(at 223.609408 -396.060422)
		(size 0.508)
		(drill 0.254)
		(layers "F.Cu" "B.Cu")
		(net "P12V_AUX")
	)
	(via
		(at 181.034182 -29.841952)
		(size 0.508)
		(drill 0.254)
		(layers "F.Cu" "B.Cu")
		(net "P12V_AUX")
	)
	(via
		(at 364.1725 -363.018832)
		(size 0.508)
		(drill 0.254)
		(layers "F.Cu" "B.Cu")
		(net "P12V_AUX")
	)
	(via
		(at 278.01062 -393.258548)
		(size 0.508)
		(drill 0.254)
		(layers "F.Cu" "B.Cu")
		(net "P12V_AUX")
	)
	(via
		(at 90.25255 -357.730044)
		(size 0.508)
		(drill 0.254)
		(layers "F.Cu" "B.Cu")
		(net "P12V_AUX")
	)
	(via
		(at 46.124622 -145.463006)
		(size 0.508)
		(drill 0.254)
		(layers "F.Cu" "B.Cu")
		(net "P12V_AUX")
	)
	(via
		(at 277.24862 -392.496548)
		(size 0.508)
		(drill 0.254)
		(layers "F.Cu" "B.Cu")
		(net "P12V_AUX")
	)
	(via
		(at 263.981692 -391.734548)
		(size 0.508)
		(drill 0.254)
		(layers "F.Cu" "B.Cu")
		(net "P12V_AUX")
	)
	(via
		(at 266.140692 -394.020548)
		(size 0.508)
		(drill 0.254)
		(layers "F.Cu" "B.Cu")
		(net "P12V_AUX")
	)
	(via
		(at 93.363542 -356.955344)
		(size 0.508)
		(drill 0.254)
		(layers "F.Cu" "B.Cu")
		(net "P12V_AUX")
	)
	(via
		(at 415.37001 -370.26723)
		(size 0.508)
		(drill 0.254)
		(layers "F.Cu" "B.Cu")
		(net "P12V_AUX")
	)
	(via
		(at 254.270764 -391.734548)
		(size 0.508)
		(drill 0.254)
		(layers "F.Cu" "B.Cu")
		(net "P12V_AUX")
	)
	(via
		(at 76.500482 -28.651962)
		(size 0.508)
		(drill 0.254)
		(layers "F.Cu" "B.Cu")
		(net "P12V_AUX")
	)
	(via
		(at 265.378692 -393.258548)
		(size 0.508)
		(drill 0.254)
		(layers "F.Cu" "B.Cu")
		(net "P12V_AUX")
	)
	(via
		(at 432.676808 -162.402774)
		(size 0.508)
		(drill 0.254)
		(layers "F.Cu" "B.Cu")
		(net "P12V_AUX")
	)
	(via
		(at 272.075656 -394.020548)
		(size 0.508)
		(drill 0.254)
		(layers "F.Cu" "B.Cu")
		(net "P12V_AUX")
	)
	(via
		(at 219.799408 -399.870422)
		(size 0.508)
		(drill 0.254)
		(layers "F.Cu" "B.Cu")
		(net "P12V_AUX")
	)
	(via
		(at 44.803822 -146.75866)
		(size 0.508)
		(drill 0.254)
		(layers "F.Cu" "B.Cu")
		(net "P12V_AUX")
	)
	(via
		(at 254.17907 -50.616612)
		(size 0.4572)
		(drill 0.254)
		(layers "F.Cu" "B.Cu")
		(net "P12V_AUX")
	)
	(via
		(at 450.298566 -344.108532)
		(size 0.508)
		(drill 0.254)
		(layers "F.Cu" "B.Cu")
		(net "P12V_AUX")
	)
	(via
		(at 224.371408 -397.584422)
		(size 0.508)
		(drill 0.254)
		(layers "F.Cu" "B.Cu")
		(net "P12V_AUX")
	)
	(via
		(at 337.303364 -358.509824)
		(size 0.508)
		(drill 0.254)
		(layers "F.Cu" "B.Cu")
		(net "P12V_AUX")
	)
	(via
		(at 200.749408 -398.346422)
		(size 0.508)
		(drill 0.254)
		(layers "F.Cu" "B.Cu")
		(net "P12V_AUX")
	)
	(via
		(at 248.3358 -390.210548)
		(size 0.508)
		(drill 0.254)
		(layers "F.Cu" "B.Cu")
		(net "P12V_AUX")
	)
	(via
		(at 95.002858 -358.48671)
		(size 0.508)
		(drill 0.254)
		(layers "F.Cu" "B.Cu")
		(net "P12V_AUX")
	)
	(via
		(at 62.965838 -25.537922)
		(size 0.508)
		(drill 0.254)
		(layers "F.Cu" "B.Cu")
		(net "P12V_AUX")
	)
	(via
		(at 17.731486 -339.450172)
		(size 0.508)
		(drill 0.254)
		(layers "F.Cu" "B.Cu")
		(net "P12V_AUX")
	)
	(via
		(at 94.158562 -356.206044)
		(size 0.508)
		(drill 0.254)
		(layers "F.Cu" "B.Cu")
		(net "P12V_AUX")
	)
	(via
		(at 254.270764 -390.972548)
		(size 0.508)
		(drill 0.254)
		(layers "F.Cu" "B.Cu")
		(net "P12V_AUX")
	)
	(via
		(at 209.893408 -396.822422)
		(size 0.508)
		(drill 0.254)
		(layers "F.Cu" "B.Cu")
		(net "P12V_AUX")
	)
	(via
		(at 234.277408 -396.060422)
		(size 0.508)
		(drill 0.254)
		(layers "F.Cu" "B.Cu")
		(net "P12V_AUX")
	)
	(via
		(at 253.54407 -48.816514)
		(size 0.4572)
		(drill 0.254)
		(layers "F.Cu" "B.Cu")
		(net "P12V_AUX")
	)
	(via
		(at 172.039026 -364.073186)
		(size 0.508)
		(drill 0.254)
		(layers "F.Cu" "B.Cu")
		(net "P12V_AUX")
	)
	(via
		(at 201.511408 -398.346422)
		(size 0.508)
		(drill 0.254)
		(layers "F.Cu" "B.Cu")
		(net "P12V_AUX")
	)
	(via
		(at 220.561408 -398.346422)
		(size 0.508)
		(drill 0.254)
		(layers "F.Cu" "B.Cu")
		(net "P12V_AUX")
	)
	(via
		(at 443.002924 -27.857958)
		(size 0.4572)
		(drill 0.254)
		(layers "F.Cu" "B.Cu")
		(net "P12V_AUX")
	)
	(via
		(at 76.500482 -27.940762)
		(size 0.508)
		(drill 0.254)
		(layers "F.Cu" "B.Cu")
		(net "P12V_AUX")
	)
	(via
		(at 47.445422 -145.463006)
		(size 0.508)
		(drill 0.254)
		(layers "F.Cu" "B.Cu")
		(net "P12V_AUX")
	)
	(via
		(at 234.277408 -397.584422)
		(size 0.508)
		(drill 0.254)
		(layers "F.Cu" "B.Cu")
		(net "P12V_AUX")
	)
	(via
		(at 200.749408 -396.060422)
		(size 0.508)
		(drill 0.254)
		(layers "F.Cu" "B.Cu")
		(net "P12V_AUX")
	)
	(via
		(at 341.929212 -362.014516)
		(size 0.508)
		(drill 0.254)
		(layers "F.Cu" "B.Cu")
		(net "P12V_AUX")
	)
	(via
		(at 253.80188 -47.065946)
		(size 0.508)
		(drill 0.254)
		(layers "F.Cu" "B.Cu")
		(net "P12V_AUX")
	)
	(via
		(at 453.346566 -337.146392)
		(size 0.508)
		(drill 0.254)
		(layers "F.Cu" "B.Cu")
		(net "P12V_AUX")
	)
	(via
		(at 231.229408 -398.346422)
		(size 0.508)
		(drill 0.254)
		(layers "F.Cu" "B.Cu")
		(net "P12V_AUX")
	)
	(via
		(at 40.77462 -365.189516)
		(size 0.508)
		(drill 0.254)
		(layers "F.Cu" "B.Cu")
		(net "P12V_AUX")
	)
	(via
		(at 220.561408 -399.870422)
		(size 0.508)
		(drill 0.254)
		(layers "F.Cu" "B.Cu")
		(net "P12V_AUX")
	)
	(via
		(at 265.378692 -394.782548)
		(size 0.508)
		(drill 0.254)
		(layers "F.Cu" "B.Cu")
		(net "P12V_AUX")
	)
	(via
		(at 242.31092 -394.02004)
		(size 0.508)
		(drill 0.254)
		(layers "F.Cu" "B.Cu")
		(net "P12V_AUX")
	)
	(via
		(at 254.956564 -392.496548)
		(size 0.508)
		(drill 0.254)
		(layers "F.Cu" "B.Cu")
		(net "P12V_AUX")
	)
	(via
		(at 417.33851 -371.51183)
		(size 0.508)
		(drill 0.254)
		(layers "F.Cu" "B.Cu")
		(net "P12V_AUX")
	)
	(via
		(at 46.124622 -146.098006)
		(size 0.508)
		(drill 0.254)
		(layers "F.Cu" "B.Cu")
		(net "P12V_AUX")
	)
	(via
		(at 257.048 -47.065946)
		(size 0.508)
		(drill 0.254)
		(layers "F.Cu" "B.Cu")
		(net "P12V_AUX")
	)
	(via
		(at 23.929086 -339.785452)
		(size 0.508)
		(drill 0.254)
		(layers "F.Cu" "B.Cu")
		(net "P12V_AUX")
	)
	(via
		(at 210.655408 -397.584422)
		(size 0.508)
		(drill 0.254)
		(layers "F.Cu" "B.Cu")
		(net "P12V_AUX")
	)
	(via
		(at 187.791344 -399.120614)
		(size 0.508)
		(drill 0.254)
		(layers "F.Cu" "B.Cu")
		(net "P12V_AUX")
	)
	(via
		(at 89.538302 -356.185724)
		(size 0.508)
		(drill 0.254)
		(layers "F.Cu" "B.Cu")
		(net "P12V_AUX")
	)
	(via
		(at 258.727448 -392.496548)
		(size 0.508)
		(drill 0.254)
		(layers "F.Cu" "B.Cu")
		(net "P12V_AUX")
	)
	(via
		(at 264.616692 -392.496548)
		(size 0.508)
		(drill 0.254)
		(layers "F.Cu" "B.Cu")
		(net "P12V_AUX")
	)
	(via
		(at 186.267344 -396.072614)
		(size 0.508)
		(drill 0.254)
		(layers "F.Cu" "B.Cu")
		(net "P12V_AUX")
	)
	(via
		(at 221.1578 -98.164904)
		(size 0.508)
		(drill 0.254)
		(layers "F.Cu" "B.Cu")
		(net "P12V_AUX")
	)
	(via
		(at 203.035408 -398.346422)
		(size 0.508)
		(drill 0.254)
		(layers "F.Cu" "B.Cu")
		(net "P12V_AUX")
	)
	(via
		(at 222.085408 -398.346422)
		(size 0.508)
		(drill 0.254)
		(layers "F.Cu" "B.Cu")
		(net "P12V_AUX")
	)
	(via
		(at 187.029344 -399.882614)
		(size 0.508)
		(drill 0.254)
		(layers "F.Cu" "B.Cu")
		(net "P12V_AUX")
	)
	(via
		(at 449.396612 -28.886658)
		(size 0.508)
		(drill 0.254)
		(layers "F.Cu" "B.Cu")
		(net "P12V_AUX")
	)
	(via
		(at 95.073978 -357.66629)
		(size 0.508)
		(drill 0.254)
		(layers "F.Cu" "B.Cu")
		(net "P12V_AUX")
	)
	(via
		(at 413.97301 -372.29923)
		(size 0.508)
		(drill 0.254)
		(layers "F.Cu" "B.Cu")
		(net "P12V_AUX")
	)
	(via
		(at 66.522346 -28.207462)
		(size 0.4572)
		(drill 0.254)
		(layers "F.Cu" "B.Cu")
		(net "P12V_AUX")
	)
	(via
		(at 451.060566 -339.737192)
		(size 0.508)
		(drill 0.254)
		(layers "F.Cu" "B.Cu")
		(net "P12V_AUX")
	)
	(via
		(at 24.589486 -341.690452)
		(size 0.508)
		(drill 0.254)
		(layers "F.Cu" "B.Cu")
		(net "P12V_AUX")
	)
	(via
		(at 432.034188 -167.076374)
		(size 0.508)
		(drill 0.254)
		(layers "F.Cu" "B.Cu")
		(net "P12V_AUX")
	)
	(via
		(at 255.57988 -47.065946)
		(size 0.508)
		(drill 0.254)
		(layers "F.Cu" "B.Cu")
		(net "P12V_AUX")
	)
	(via
		(at 469.059514 -42.2783)
		(size 0.508)
		(drill 0.254)
		(layers "F.Cu" "B.Cu")
		(net "P12V_AUX")
	)
	(via
		(at 203.035408 -399.870422)
		(size 0.508)
		(drill 0.254)
		(layers "F.Cu" "B.Cu")
		(net "P12V_AUX")
	)
	(via
		(at 208.71688 -130.830828)
		(size 0.508)
		(drill 0.254)
		(layers "F.Cu" "B.Cu")
		(net "P12V_AUX")
	)
	(via
		(at 446.526412 -29.648658)
		(size 0.508)
		(drill 0.254)
		(layers "F.Cu" "B.Cu")
		(net "P12V_AUX")
	)
	(via
		(at 189.315344 -396.834614)
		(size 0.508)
		(drill 0.254)
		(layers "F.Cu" "B.Cu")
		(net "P12V_AUX")
	)
	(via
		(at 232.753408 -398.346422)
		(size 0.508)
		(drill 0.254)
		(layers "F.Cu" "B.Cu")
		(net "P12V_AUX")
	)
	(via
		(at 190.077344 -396.834614)
		(size 0.508)
		(drill 0.254)
		(layers "F.Cu" "B.Cu")
		(net "P12V_AUX")
	)
	(via
		(at 198.463408 -399.108422)
		(size 0.508)
		(drill 0.254)
		(layers "F.Cu" "B.Cu")
		(net "P12V_AUX")
	)
	(via
		(at 437.697372 -23.689818)
		(size 0.508)
		(drill 0.254)
		(layers "F.Cu" "B.Cu")
		(net "P12V_AUX")
	)
	(via
		(at 247.5738 -394.782548)
		(size 0.508)
		(drill 0.254)
		(layers "F.Cu" "B.Cu")
		(net "P12V_AUX")
	)
	(via
		(at 43.508422 -146.75866)
		(size 0.508)
		(drill 0.254)
		(layers "F.Cu" "B.Cu")
		(net "P12V_AUX")
	)
	(via
		(at 246.8118 -390.972548)
		(size 0.508)
		(drill 0.254)
		(layers "F.Cu" "B.Cu")
		(net "P12V_AUX")
	)
	(via
		(at 240.78692 -394.02004)
		(size 0.508)
		(drill 0.254)
		(layers "F.Cu" "B.Cu")
		(net "P12V_AUX")
	)
	(via
		(at 212.941408 -399.870422)
		(size 0.508)
		(drill 0.254)
		(layers "F.Cu" "B.Cu")
		(net "P12V_AUX")
	)
	(via
		(at 231.229408 -396.060422)
		(size 0.508)
		(drill 0.254)
		(layers "F.Cu" "B.Cu")
		(net "P12V_AUX")
	)
	(via
		(at 258.727448 -390.210548)
		(size 0.508)
		(drill 0.254)
		(layers "F.Cu" "B.Cu")
		(net "P12V_AUX")
	)
	(via
		(at 269.865856 -393.258548)
		(size 0.508)
		(drill 0.254)
		(layers "F.Cu" "B.Cu")
		(net "P12V_AUX")
	)
	(via
		(at 450.298566 -342.683592)
		(size 0.508)
		(drill 0.254)
		(layers "F.Cu" "B.Cu")
		(net "P12V_AUX")
	)
	(via
		(at 453.346566 -337.882992)
		(size 0.508)
		(drill 0.254)
		(layers "F.Cu" "B.Cu")
		(net "P12V_AUX")
	)
	(via
		(at 224.371408 -399.870422)
		(size 0.508)
		(drill 0.254)
		(layers "F.Cu" "B.Cu")
		(net "P12V_AUX")
	)
	(via
		(at 451.822566 -342.683592)
		(size 0.508)
		(drill 0.254)
		(layers "F.Cu" "B.Cu")
		(net "P12V_AUX")
	)
	(via
		(at 95.71355 -356.206044)
		(size 0.508)
		(drill 0.254)
		(layers "F.Cu" "B.Cu")
		(net "P12V_AUX")
	)
	(via
		(at 173.202346 -363.486446)
		(size 0.508)
		(drill 0.254)
		(layers "F.Cu" "B.Cu")
		(net "P12V_AUX")
	)
	(via
		(at 68.32219 -28.207462)
		(size 0.4572)
		(drill 0.254)
		(layers "F.Cu" "B.Cu")
		(net "P12V_AUX")
	)
	(via
		(at 220.561408 -396.060422)
		(size 0.508)
		(drill 0.254)
		(layers "F.Cu" "B.Cu")
		(net "P12V_AUX")
	)
	(via
		(at 224.371408 -396.822422)
		(size 0.508)
		(drill 0.254)
		(layers "F.Cu" "B.Cu")
		(net "P12V_AUX")
	)
	(via
		(at 45.464222 -146.098006)
		(size 0.508)
		(drill 0.254)
		(layers "F.Cu" "B.Cu")
		(net "P12V_AUX")
	)
	(via
		(at 241.54892 -391.73404)
		(size 0.508)
		(drill 0.254)
		(layers "F.Cu" "B.Cu")
		(net "P12V_AUX")
	)
	(via
		(at 336.592672 -361.999276)
		(size 0.508)
		(drill 0.254)
		(layers "F.Cu" "B.Cu")
		(net "P12V_AUX")
	)
	(via
		(at 219.799408 -397.584422)
		(size 0.508)
		(drill 0.254)
		(layers "F.Cu" "B.Cu")
		(net "P12V_AUX")
	)
	(via
		(at 338.151216 -356.104444)
		(size 0.508)
		(drill 0.254)
		(layers "F.Cu" "B.Cu")
		(net "P12V_AUX")
	)
	(via
		(at 415.37001 -371.53723)
		(size 0.508)
		(drill 0.254)
		(layers "F.Cu" "B.Cu")
		(net "P12V_AUX")
	)
	(via
		(at 248.3358 -393.258548)
		(size 0.508)
		(drill 0.254)
		(layers "F.Cu" "B.Cu")
		(net "P12V_AUX")
	)
	(via
		(at 451.733412 -23.019258)
		(size 0.508)
		(drill 0.254)
		(layers "F.Cu" "B.Cu")
		(net "P12V_AUX")
	)
	(via
		(at 465.40293 -56.828182)
		(size 0.508)
		(drill 0.254)
		(layers "F.Cu" "B.Cu")
		(net "P12V_AUX")
	)
	(via
		(at 210.655408 -396.060422)
		(size 0.508)
		(drill 0.254)
		(layers "F.Cu" "B.Cu")
		(net "P12V_AUX")
	)
	(via
		(at 272.075656 -390.210548)
		(size 0.508)
		(drill 0.254)
		(layers "F.Cu" "B.Cu")
		(net "P12V_AUX")
	)
	(via
		(at 20.068286 -340.420452)
		(size 0.508)
		(drill 0.254)
		(layers "F.Cu" "B.Cu")
		(net "P12V_AUX")
	)
	(via
		(at 220.561408 -397.584422)
		(size 0.508)
		(drill 0.254)
		(layers "F.Cu" "B.Cu")
		(net "P12V_AUX")
	)
	(via
		(at 23.065486 -341.690452)
		(size 0.508)
		(drill 0.254)
		(layers "F.Cu" "B.Cu")
		(net "P12V_AUX")
	)
	(via
		(at 248.415048 -70.214744)
		(size 0.508)
		(drill 0.254)
		(layers "F.Cu" "B.Cu")
		(net "P12V_AUX")
	)
	(via
		(at 452.584566 -339.737192)
		(size 0.508)
		(drill 0.254)
		(layers "F.Cu" "B.Cu")
		(net "P12V_AUX")
	)
	(via
		(at 451.822566 -343.371932)
		(size 0.508)
		(drill 0.254)
		(layers "F.Cu" "B.Cu")
		(net "P12V_AUX")
	)
	(via
		(at 449.396612 -27.438858)
		(size 0.508)
		(drill 0.254)
		(layers "F.Cu" "B.Cu")
		(net "P12V_AUX")
	)
	(via
		(at 209.131408 -397.584422)
		(size 0.508)
		(drill 0.254)
		(layers "F.Cu" "B.Cu")
		(net "P12V_AUX")
	)
	(via
		(at 231.229408 -399.870422)
		(size 0.508)
		(drill 0.254)
		(layers "F.Cu" "B.Cu")
		(net "P12V_AUX")
	)
	(via
		(at 254.17907 -51.516534)
		(size 0.4572)
		(drill 0.254)
		(layers "F.Cu" "B.Cu")
		(net "P12V_AUX")
	)
	(via
		(at 286.598614 -372.987062)
		(size 0.508)
		(drill 0.254)
		(layers "F.Cu" "B.Cu")
		(net "P12V_AUX")
	)
	(via
		(at 234.277408 -399.108422)
		(size 0.508)
		(drill 0.254)
		(layers "F.Cu" "B.Cu")
		(net "P12V_AUX")
	)
	(via
		(at 243.07292 -391.73404)
		(size 0.508)
		(drill 0.254)
		(layers "F.Cu" "B.Cu")
		(net "P12V_AUX")
	)
	(via
		(at 446.548002 -18.446242)
		(size 0.508)
		(drill 0.254)
		(layers "F.Cu" "B.Cu")
		(net "P12V_AUX")
	)
	(via
		(at 450.298566 -339.737192)
		(size 0.508)
		(drill 0.254)
		(layers "F.Cu" "B.Cu")
		(net "P12V_AUX")
	)
	(via
		(at 449.396612 -28.175458)
		(size 0.508)
		(drill 0.254)
		(layers "F.Cu" "B.Cu")
		(net "P12V_AUX")
	)
	(via
		(at 443.9031 -28.492958)
		(size 0.4572)
		(drill 0.254)
		(layers "F.Cu" "B.Cu")
		(net "P12V_AUX")
	)
	(via
		(at 432.016408 -163.764214)
		(size 0.508)
		(drill 0.254)
		(layers "F.Cu" "B.Cu")
		(net "P12V_AUX")
	)
	(via
		(at 199.987408 -397.584422)
		(size 0.508)
		(drill 0.254)
		(layers "F.Cu" "B.Cu")
		(net "P12V_AUX")
	)
	(via
		(at 91.110562 -359.309924)
		(size 0.508)
		(drill 0.254)
		(layers "F.Cu" "B.Cu")
		(net "P12V_AUX")
	)
	(via
		(at 463.32013 -58.148982)
		(size 0.508)
		(drill 0.254)
		(layers "F.Cu" "B.Cu")
		(net "P12V_AUX")
	)
	(via
		(at 286.598614 -372.225062)
		(size 0.508)
		(drill 0.254)
		(layers "F.Cu" "B.Cu")
		(net "P12V_AUX")
	)
	(via
		(at 287.233614 -373.749062)
		(size 0.508)
		(drill 0.254)
		(layers "F.Cu" "B.Cu")
		(net "P12V_AUX")
	)
	(via
		(at 235.039408 -396.060422)
		(size 0.508)
		(drill 0.254)
		(layers "F.Cu" "B.Cu")
		(net "P12V_AUX")
	)
	(via
		(at 95.71355 -357.730044)
		(size 0.508)
		(drill 0.254)
		(layers "F.Cu" "B.Cu")
		(net "P12V_AUX")
	)
	(via
		(at 221.323408 -396.060422)
		(size 0.508)
		(drill 0.254)
		(layers "F.Cu" "B.Cu")
		(net "P12V_AUX")
	)
	(via
		(at 343.450164 -360.033824)
		(size 0.508)
		(drill 0.254)
		(layers "F.Cu" "B.Cu")
		(net "P12V_AUX")
	)
	(via
		(at 240.78692 -390.21004)
		(size 0.508)
		(drill 0.254)
		(layers "F.Cu" "B.Cu")
		(net "P12V_AUX")
	)
	(via
		(at 212.941408 -397.584422)
		(size 0.508)
		(drill 0.254)
		(layers "F.Cu" "B.Cu")
		(net "P12V_AUX")
	)
	(via
		(at 341.982044 -360.68508)
		(size 0.508)
		(drill 0.254)
		(layers "F.Cu" "B.Cu")
		(net "P12V_AUX")
	)
	(via
		(at 247.780048 -74.928984)
		(size 0.508)
		(drill 0.254)
		(layers "F.Cu" "B.Cu")
		(net "P12V_AUX")
	)
	(via
		(at 200.749408 -399.870422)
		(size 0.508)
		(drill 0.254)
		(layers "F.Cu" "B.Cu")
		(net "P12V_AUX")
	)
	(via
		(at 40.00246 -361.049316)
		(size 0.508)
		(drill 0.254)
		(layers "F.Cu" "B.Cu")
		(net "P12V_AUX")
	)
	(via
		(at 287.233614 -372.987062)
		(size 0.508)
		(drill 0.254)
		(layers "F.Cu" "B.Cu")
		(net "P12V_AUX")
	)
	(via
		(at 336.560668 -357.759508)
		(size 0.508)
		(drill 0.254)
		(layers "F.Cu" "B.Cu")
		(net "P12V_AUX")
	)
	(via
		(at 417.33851 -373.03583)
		(size 0.508)
		(drill 0.254)
		(layers "F.Cu" "B.Cu")
		(net "P12V_AUX")
	)
	(via
		(at 170.471846 -363.511846)
		(size 0.508)
		(drill 0.254)
		(layers "F.Cu" "B.Cu")
		(net "P12V_AUX")
	)
	(via
		(at 96.47555 -359.254044)
		(size 0.508)
		(drill 0.254)
		(layers "F.Cu" "B.Cu")
		(net "P12V_AUX")
	)
	(via
		(at 415.37001 -370.90223)
		(size 0.508)
		(drill 0.254)
		(layers "F.Cu" "B.Cu")
		(net "P12V_AUX")
	)
	(via
		(at 199.225408 -397.584422)
		(size 0.508)
		(drill 0.254)
		(layers "F.Cu" "B.Cu")
		(net "P12V_AUX")
	)
	(via
		(at 88.677242 -358.489504)
		(size 0.508)
		(drill 0.254)
		(layers "F.Cu" "B.Cu")
		(net "P12V_AUX")
	)
	(via
		(at 92.634562 -355.444044)
		(size 0.508)
		(drill 0.254)
		(layers "F.Cu" "B.Cu")
		(net "P12V_AUX")
	)
	(via
		(at 18.493486 -339.450172)
		(size 0.508)
		(drill 0.254)
		(layers "F.Cu" "B.Cu")
		(net "P12V_AUX")
	)
	(via
		(at 254.956564 -390.210548)
		(size 0.508)
		(drill 0.254)
		(layers "F.Cu" "B.Cu")
		(net "P12V_AUX")
	)
	(via
		(at 171.233846 -364.273846)
		(size 0.508)
		(drill 0.254)
		(layers "F.Cu" "B.Cu")
		(net "P12V_AUX")
	)
	(via
		(at 254.17907 -49.71669)
		(size 0.4572)
		(drill 0.254)
		(layers "F.Cu" "B.Cu")
		(net "P12V_AUX")
	)
	(via
		(at 23.065486 -342.452452)
		(size 0.508)
		(drill 0.254)
		(layers "F.Cu" "B.Cu")
		(net "P12V_AUX")
	)
	(via
		(at 339.675216 -356.104444)
		(size 0.508)
		(drill 0.254)
		(layers "F.Cu" "B.Cu")
		(net "P12V_AUX")
	)
	(via
		(at 219.799408 -396.060422)
		(size 0.508)
		(drill 0.254)
		(layers "F.Cu" "B.Cu")
		(net "P12V_AUX")
	)
	(via
		(at 465.40293 -57.488582)
		(size 0.508)
		(drill 0.254)
		(layers "F.Cu" "B.Cu")
		(net "P12V_AUX")
	)
	(via
		(at 187.029344 -396.834614)
		(size 0.508)
		(drill 0.254)
		(layers "F.Cu" "B.Cu")
		(net "P12V_AUX")
	)
	(via
		(at 338.182712 -361.336336)
		(size 0.508)
		(drill 0.254)
		(layers "F.Cu" "B.Cu")
		(net "P12V_AUX")
	)
	(via
		(at 230.467408 -399.870422)
		(size 0.508)
		(drill 0.254)
		(layers "F.Cu" "B.Cu")
		(net "P12V_AUX")
	)
	(via
		(at 94.920562 -359.309924)
		(size 0.508)
		(drill 0.254)
		(layers "F.Cu" "B.Cu")
		(net "P12V_AUX")
	)
	(via
		(at 249.0216 -391.734548)
		(size 0.508)
		(drill 0.254)
		(layers "F.Cu" "B.Cu")
		(net "P12V_AUX")
	)
	(via
		(at 254.956564 -391.734548)
		(size 0.508)
		(drill 0.254)
		(layers "F.Cu" "B.Cu")
		(net "P12V_AUX")
	)
	(via
		(at 20.068286 -341.055452)
		(size 0.508)
		(drill 0.254)
		(layers "F.Cu" "B.Cu")
		(net "P12V_AUX")
	)
	(via
		(at 240.02492 -390.21004)
		(size 0.508)
		(drill 0.254)
		(layers "F.Cu" "B.Cu")
		(net "P12V_AUX")
	)
	(via
		(at 249.0216 -394.782548)
		(size 0.508)
		(drill 0.254)
		(layers "F.Cu" "B.Cu")
		(net "P12V_AUX")
	)
	(via
		(at 466.06333 -58.148982)
		(size 0.508)
		(drill 0.254)
		(layers "F.Cu" "B.Cu")
		(net "P12V_AUX")
	)
	(via
		(at 170.471846 -362.241846)
		(size 0.508)
		(drill 0.254)
		(layers "F.Cu" "B.Cu")
		(net "P12V_AUX")
	)
	(via
		(at 190.839344 -396.834614)
		(size 0.508)
		(drill 0.254)
		(layers "F.Cu" "B.Cu")
		(net "P12V_AUX")
	)
	(via
		(at 19.255486 -338.815172)
		(size 0.508)
		(drill 0.254)
		(layers "F.Cu" "B.Cu")
		(net "P12V_AUX")
	)
	(via
		(at 20.779486 -342.452452)
		(size 0.508)
		(drill 0.254)
		(layers "F.Cu" "B.Cu")
		(net "P12V_AUX")
	)
	(via
		(at 240.02492 -394.78204)
		(size 0.508)
		(drill 0.254)
		(layers "F.Cu" "B.Cu")
		(net "P12V_AUX")
	)
	(via
		(at 96.47555 -355.444044)
		(size 0.508)
		(drill 0.254)
		(layers "F.Cu" "B.Cu")
		(net "P12V_AUX")
	)
	(via
		(at 94.920562 -360.016044)
		(size 0.508)
		(drill 0.254)
		(layers "F.Cu" "B.Cu")
		(net "P12V_AUX")
	)
	(via
		(at 451.822566 -337.146392)
		(size 0.508)
		(drill 0.254)
		(layers "F.Cu" "B.Cu")
		(net "P12V_AUX")
	)
	(via
		(at 465.356956 -381.204978)
		(size 0.508)
		(drill 0.254)
		(layers "F.Cu" "B.Cu")
		(net "P12V_AUX")
	)
	(via
		(at 116.444014 -359.382822)
		(size 0.508)
		(drill 0.254)
		(layers "F.Cu" "B.Cu")
		(net "P12V_AUX")
	)
	(via
		(at 449.536566 -341.210392)
		(size 0.508)
		(drill 0.254)
		(layers "F.Cu" "B.Cu")
		(net "P12V_AUX")
	)
	(via
		(at 254.956564 -394.782548)
		(size 0.508)
		(drill 0.254)
		(layers "F.Cu" "B.Cu")
		(net "P12V_AUX")
	)
	(via
		(at 248.3358 -394.020548)
		(size 0.508)
		(drill 0.254)
		(layers "F.Cu" "B.Cu")
		(net "P12V_AUX")
	)
	(via
		(at 94.162118 -360.02087)
		(size 0.508)
		(drill 0.254)
		(layers "F.Cu" "B.Cu")
		(net "P12V_AUX")
	)
	(via
		(at 20.068286 -341.690452)
		(size 0.508)
		(drill 0.254)
		(layers "F.Cu" "B.Cu")
		(net "P12V_AUX")
	)
	(via
		(at 254.270764 -393.258548)
		(size 0.508)
		(drill 0.254)
		(layers "F.Cu" "B.Cu")
		(net "P12V_AUX")
	)
	(via
		(at 231.229408 -396.822422)
		(size 0.508)
		(drill 0.254)
		(layers "F.Cu" "B.Cu")
		(net "P12V_AUX")
	)
	(via
		(at 432.43246 -52.01412)
		(size 0.508)
		(drill 0.254)
		(layers "F.Cu" "B.Cu")
		(net "P12V_AUX")
	)
	(via
		(at 342.754204 -356.104444)
		(size 0.508)
		(drill 0.254)
		(layers "F.Cu" "B.Cu")
		(net "P12V_AUX")
	)
	(via
		(at 288.980118 -395.73708)
		(size 0.508)
		(drill 0.254)
		(layers "F.Cu" "B.Cu")
		(net "P12V_AUX")
	)
	(via
		(at 432.016408 -163.063174)
		(size 0.508)
		(drill 0.254)
		(layers "F.Cu" "B.Cu")
		(net "P12V_AUX")
	)
	(via
		(at 392.139932 -78.754224)
		(size 0.508)
		(drill 0.254)
		(layers "F.Cu" "B.Cu")
		(net "P12V_AUX")
	)
	(via
		(at 343.450164 -357.747824)
		(size 0.508)
		(drill 0.254)
		(layers "F.Cu" "B.Cu")
		(net "P12V_AUX")
	)
	(via
		(at 275.80082 -394.020548)
		(size 0.508)
		(drill 0.254)
		(layers "F.Cu" "B.Cu")
		(net "P12V_AUX")
	)
	(via
		(at 67.422268 -28.207462)
		(size 0.4572)
		(drill 0.254)
		(layers "F.Cu" "B.Cu")
		(net "P12V_AUX")
	)
	(via
		(at 224.371408 -396.060422)
		(size 0.508)
		(drill 0.254)
		(layers "F.Cu" "B.Cu")
		(net "P12V_AUX")
	)
	(via
		(at 21.541486 -342.452452)
		(size 0.508)
		(drill 0.254)
		(layers "F.Cu" "B.Cu")
		(net "P12V_AUX")
	)
	(via
		(at 94.920562 -355.444044)
		(size 0.508)
		(drill 0.254)
		(layers "F.Cu" "B.Cu")
		(net "P12V_AUX")
	)
	(via
		(at 451.060566 -344.108532)
		(size 0.508)
		(drill 0.254)
		(layers "F.Cu" "B.Cu")
		(net "P12V_AUX")
	)
	(via
		(at 241.54892 -393.25804)
		(size 0.508)
		(drill 0.254)
		(layers "F.Cu" "B.Cu")
		(net "P12V_AUX")
	)
	(via
		(at 231.991408 -399.870422)
		(size 0.508)
		(drill 0.254)
		(layers "F.Cu" "B.Cu")
		(net "P12V_AUX")
	)
	(via
		(at 212.179408 -399.108422)
		(size 0.508)
		(drill 0.254)
		(layers "F.Cu" "B.Cu")
		(net "P12V_AUX")
	)
	(via
		(at 431.350928 -164.4396)
		(size 0.508)
		(drill 0.254)
		(layers "F.Cu" "B.Cu")
		(net "P12V_AUX")
	)
	(via
		(at 464.74253 -58.783982)
		(size 0.508)
		(drill 0.254)
		(layers "F.Cu" "B.Cu")
		(net "P12V_AUX")
	)
	(via
		(at 92.601542 -356.955344)
		(size 0.508)
		(drill 0.254)
		(layers "F.Cu" "B.Cu")
		(net "P12V_AUX")
	)
	(via
		(at 341.971376 -359.271824)
		(size 0.508)
		(drill 0.254)
		(layers "F.Cu" "B.Cu")
		(net "P12V_AUX")
	)
	(via
		(at 431.350928 -162.41776)
		(size 0.508)
		(drill 0.254)
		(layers "F.Cu" "B.Cu")
		(net "P12V_AUX")
	)
	(via
		(at 173.202346 -362.216446)
		(size 0.508)
		(drill 0.254)
		(layers "F.Cu" "B.Cu")
		(net "P12V_AUX")
	)
	(via
		(at 266.826492 -390.972548)
		(size 0.508)
		(drill 0.254)
		(layers "F.Cu" "B.Cu")
		(net "P12V_AUX")
	)
	(via
		(at 198.463408 -396.060422)
		(size 0.508)
		(drill 0.254)
		(layers "F.Cu" "B.Cu")
		(net "P12V_AUX")
	)
	(via
		(at 343.440004 -356.104444)
		(size 0.508)
		(drill 0.254)
		(layers "F.Cu" "B.Cu")
		(net "P12V_AUX")
	)
	(via
		(at 187.029344 -399.120614)
		(size 0.508)
		(drill 0.254)
		(layers "F.Cu" "B.Cu")
		(net "P12V_AUX")
	)
	(via
		(at 76.500482 -27.204162)
		(size 0.508)
		(drill 0.254)
		(layers "F.Cu" "B.Cu")
		(net "P12V_AUX")
	)
	(via
		(at 182.42153 -418.4142)
		(size 0.508)
		(drill 0.254)
		(layers "F.Cu" "B.Cu")
		(net "P12V_AUX")
	)
	(via
		(at 342.764364 -360.033824)
		(size 0.508)
		(drill 0.254)
		(layers "F.Cu" "B.Cu")
		(net "P12V_AUX")
	)
	(via
		(at 187.791344 -398.358614)
		(size 0.508)
		(drill 0.254)
		(layers "F.Cu" "B.Cu")
		(net "P12V_AUX")
	)
	(via
		(at 247.780048 -70.933564)
		(size 0.508)
		(drill 0.254)
		(layers "F.Cu" "B.Cu")
		(net "P12V_AUX")
	)
	(via
		(at 452.584566 -340.473792)
		(size 0.508)
		(drill 0.254)
		(layers "F.Cu" "B.Cu")
		(net "P12V_AUX")
	)
	(via
		(at 172.039026 -362.803186)
		(size 0.508)
		(drill 0.254)
		(layers "F.Cu" "B.Cu")
		(net "P12V_AUX")
	)
	(via
		(at 272.761456 -390.972548)
		(size 0.508)
		(drill 0.254)
		(layers "F.Cu" "B.Cu")
		(net "P12V_AUX")
	)
	(via
		(at 248.90476 -72.329548)
		(size 0.508)
		(drill 0.254)
		(layers "F.Cu" "B.Cu")
		(net "P12V_AUX")
	)
	(via
		(at 90.910918 -357.68407)
		(size 0.508)
		(drill 0.254)
		(layers "F.Cu" "B.Cu")
		(net "P12V_AUX")
	)
	(via
		(at 341.971376 -360.033824)
		(size 0.508)
		(drill 0.254)
		(layers "F.Cu" "B.Cu")
		(net "P12V_AUX")
	)
	(via
		(at 17.731486 -338.815172)
		(size 0.508)
		(drill 0.254)
		(layers "F.Cu" "B.Cu")
		(net "P12V_AUX")
	)
	(via
		(at 266.826492 -394.020548)
		(size 0.508)
		(drill 0.254)
		(layers "F.Cu" "B.Cu")
		(net "P12V_AUX")
	)
	(via
		(at 89.466674 -360.002328)
		(size 0.508)
		(drill 0.254)
		(layers "F.Cu" "B.Cu")
		(net "P12V_AUX")
	)
	(via
		(at 276.48662 -390.972548)
		(size 0.508)
		(drill 0.254)
		(layers "F.Cu" "B.Cu")
		(net "P12V_AUX")
	)
	(via
		(at 90.300302 -356.185724)
		(size 0.508)
		(drill 0.254)
		(layers "F.Cu" "B.Cu")
		(net "P12V_AUX")
	)
	(via
		(at 451.060566 -343.371932)
		(size 0.508)
		(drill 0.254)
		(layers "F.Cu" "B.Cu")
		(net "P12V_AUX")
	)
	(via
		(at 190.077344 -396.072614)
		(size 0.508)
		(drill 0.254)
		(layers "F.Cu" "B.Cu")
		(net "P12V_AUX")
	)
	(via
		(at 337.303364 -357.747824)
		(size 0.508)
		(drill 0.254)
		(layers "F.Cu" "B.Cu")
		(net "P12V_AUX")
	)
	(via
		(at 181.846982 -29.841952)
		(size 0.508)
		(drill 0.254)
		(layers "F.Cu" "B.Cu")
		(net "P12V_AUX")
	)
	(via
		(at 232.753408 -397.584422)
		(size 0.508)
		(drill 0.254)
		(layers "F.Cu" "B.Cu")
		(net "P12V_AUX")
	)
	(via
		(at 202.273408 -398.346422)
		(size 0.508)
		(drill 0.254)
		(layers "F.Cu" "B.Cu")
		(net "P12V_AUX")
	)
	(via
		(at 190.839344 -397.596614)
		(size 0.508)
		(drill 0.254)
		(layers "F.Cu" "B.Cu")
		(net "P12V_AUX")
	)
	(via
		(at 235.039408 -397.584422)
		(size 0.508)
		(drill 0.254)
		(layers "F.Cu" "B.Cu")
		(net "P12V_AUX")
	)
	(via
		(at 337.3247 -361.336336)
		(size 0.508)
		(drill 0.254)
		(layers "F.Cu" "B.Cu")
		(net "P12V_AUX")
	)
	(via
		(at 341.205312 -361.991656)
		(size 0.508)
		(drill 0.254)
		(layers "F.Cu" "B.Cu")
		(net "P12V_AUX")
	)
	(via
		(at 169.836846 -363.511846)
		(size 0.508)
		(drill 0.254)
		(layers "F.Cu" "B.Cu")
		(net "P12V_AUX")
	)
	(via
		(at 413.97301 -373.06123)
		(size 0.508)
		(drill 0.254)
		(layers "F.Cu" "B.Cu")
		(net "P12V_AUX")
	)
	(via
		(at 171.233846 -362.241846)
		(size 0.508)
		(drill 0.254)
		(layers "F.Cu" "B.Cu")
		(net "P12V_AUX")
	)
	(via
		(at 40.77462 -364.521496)
		(size 0.508)
		(drill 0.254)
		(layers "F.Cu" "B.Cu")
		(net "P12V_AUX")
	)
	(via
		(at 443.9031 -27.857958)
		(size 0.4572)
		(drill 0.254)
		(layers "F.Cu" "B.Cu")
		(net "P12V_AUX")
	)
	(via
		(at 198.463408 -396.822422)
		(size 0.508)
		(drill 0.254)
		(layers "F.Cu" "B.Cu")
		(net "P12V_AUX")
	)
	(via
		(at 169.836846 -362.876846)
		(size 0.508)
		(drill 0.254)
		(layers "F.Cu" "B.Cu")
		(net "P12V_AUX")
	)
	(via
		(at 257.6322 -44.627546)
		(size 0.508)
		(drill 0.254)
		(layers "F.Cu" "B.Cu")
		(net "P12V_AUX")
	)
	(via
		(at 92.634562 -356.206044)
		(size 0.508)
		(drill 0.254)
		(layers "F.Cu" "B.Cu")
		(net "P12V_AUX")
	)
	(via
		(at 201.511408 -396.060422)
		(size 0.508)
		(drill 0.254)
		(layers "F.Cu" "B.Cu")
		(net "P12V_AUX")
	)
	(via
		(at 258.727448 -394.020548)
		(size 0.508)
		(drill 0.254)
		(layers "F.Cu" "B.Cu")
		(net "P12V_AUX")
	)
	(via
		(at 240.02492 -390.97204)
		(size 0.508)
		(drill 0.254)
		(layers "F.Cu" "B.Cu")
		(net "P12V_AUX")
	)
	(via
		(at 254.69088 -40.842946)
		(size 0.508)
		(drill 0.254)
		(layers "F.Cu" "B.Cu")
		(net "P12V_AUX")
	)
	(via
		(at 246.8118 -393.258548)
		(size 0.508)
		(drill 0.254)
		(layers "F.Cu" "B.Cu")
		(net "P12V_AUX")
	)
	(via
		(at 338.913216 -356.104444)
		(size 0.508)
		(drill 0.254)
		(layers "F.Cu" "B.Cu")
		(net "P12V_AUX")
	)
	(via
		(at 39.37762 -362.362496)
		(size 0.508)
		(drill 0.254)
		(layers "F.Cu" "B.Cu")
		(net "P12V_AUX")
	)
	(via
		(at 340.447376 -360.033824)
		(size 0.508)
		(drill 0.254)
		(layers "F.Cu" "B.Cu")
		(net "P12V_AUX")
	)
	(via
		(at 232.753408 -399.870422)
		(size 0.508)
		(drill 0.254)
		(layers "F.Cu" "B.Cu")
		(net "P12V_AUX")
	)
	(via
		(at 224.371408 -398.346422)
		(size 0.508)
		(drill 0.254)
		(layers "F.Cu" "B.Cu")
		(net "P12V_AUX")
	)
	(via
		(at 185.098182 -32.839152)
		(size 0.508)
		(drill 0.254)
		(layers "F.Cu" "B.Cu")
		(net "P12V_AUX")
	)
	(via
		(at 246.8118 -391.734548)
		(size 0.508)
		(drill 0.254)
		(layers "F.Cu" "B.Cu")
		(net "P12V_AUX")
	)
	(via
		(at 272.761456 -394.020548)
		(size 0.508)
		(drill 0.254)
		(layers "F.Cu" "B.Cu")
		(net "P12V_AUX")
	)
	(via
		(at 249.37593 -55.022242)
		(size 0.508)
		(drill 0.254)
		(layers "F.Cu" "B.Cu")
		(net "P12V_AUX")
	)
	(via
		(at 246.8118 -394.020548)
		(size 0.508)
		(drill 0.254)
		(layers "F.Cu" "B.Cu")
		(net "P12V_AUX")
	)
	(via
		(at 209.893408 -399.870422)
		(size 0.508)
		(drill 0.254)
		(layers "F.Cu" "B.Cu")
		(net "P12V_AUX")
	)
	(via
		(at 432.016408 -165.745414)
		(size 0.508)
		(drill 0.254)
		(layers "F.Cu" "B.Cu")
		(net "P12V_AUX")
	)
	(via
		(at 243.07292 -394.02004)
		(size 0.508)
		(drill 0.254)
		(layers "F.Cu" "B.Cu")
		(net "P12V_AUX")
	)
	(via
		(at 178.343814 -29.255212)
		(size 0.4572)
		(drill 0.254)
		(layers "F.Cu" "B.Cu")
		(net "P12V_AUX")
	)
	(via
		(at 432.016408 -164.424614)
		(size 0.508)
		(drill 0.254)
		(layers "F.Cu" "B.Cu")
		(net "P12V_AUX")
	)
	(via
		(at 171.233846 -362.876846)
		(size 0.508)
		(drill 0.254)
		(layers "F.Cu" "B.Cu")
		(net "P12V_AUX")
	)
	(via
		(at 271.313656 -390.972548)
		(size 0.508)
		(drill 0.254)
		(layers "F.Cu" "B.Cu")
		(net "P12V_AUX")
	)
	(via
		(at 24.589486 -342.452452)
		(size 0.508)
		(drill 0.254)
		(layers "F.Cu" "B.Cu")
		(net "P12V_AUX")
	)
	(via
		(at 243.07292 -394.78204)
		(size 0.508)
		(drill 0.254)
		(layers "F.Cu" "B.Cu")
		(net "P12V_AUX")
	)
	(via
		(at 91.077542 -356.955344)
		(size 0.508)
		(drill 0.254)
		(layers "F.Cu" "B.Cu")
		(net "P12V_AUX")
	)
	(via
		(at 230.467408 -396.822422)
		(size 0.508)
		(drill 0.254)
		(layers "F.Cu" "B.Cu")
		(net "P12V_AUX")
	)
	(via
		(at 260.251448 -390.210548)
		(size 0.508)
		(drill 0.254)
		(layers "F.Cu" "B.Cu")
		(net "P12V_AUX")
	)
	(via
		(at 185.098182 -33.550352)
		(size 0.508)
		(drill 0.254)
		(layers "F.Cu" "B.Cu")
		(net "P12V_AUX")
	)
	(via
		(at 270.551656 -391.734548)
		(size 0.508)
		(drill 0.254)
		(layers "F.Cu" "B.Cu")
		(net "P12V_AUX")
	)
	(via
		(at 164.667184 -134.17677)
		(size 0.508)
		(drill 0.254)
		(layers "F.Cu" "B.Cu")
		(net "P12V_AUX")
	)
	(via
		(at 272.075656 -392.496548)
		(size 0.508)
		(drill 0.254)
		(layers "F.Cu" "B.Cu")
		(net "P12V_AUX")
	)
	(via
		(at 188.553344 -398.358614)
		(size 0.508)
		(drill 0.254)
		(layers "F.Cu" "B.Cu")
		(net "P12V_AUX")
	)
	(via
		(at 414.60801 -370.90223)
		(size 0.508)
		(drill 0.254)
		(layers "F.Cu" "B.Cu")
		(net "P12V_AUX")
	)
	(via
		(at 432.676808 -163.764214)
		(size 0.508)
		(drill 0.254)
		(layers "F.Cu" "B.Cu")
		(net "P12V_AUX")
	)
	(via
		(at 464.08213 -57.488582)
		(size 0.508)
		(drill 0.254)
		(layers "F.Cu" "B.Cu")
		(net "P12V_AUX")
	)
	(via
		(at 289.964114 -373.723662)
		(size 0.508)
		(drill 0.254)
		(layers "F.Cu" "B.Cu")
		(net "P12V_AUX")
	)
	(via
		(at 465.40293 -59.418982)
		(size 0.508)
		(drill 0.254)
		(layers "F.Cu" "B.Cu")
		(net "P12V_AUX")
	)
	(via
		(at 452.584566 -344.108532)
		(size 0.508)
		(drill 0.254)
		(layers "F.Cu" "B.Cu")
		(net "P12V_AUX")
	)
	(via
		(at 286.598614 -371.590062)
		(size 0.508)
		(drill 0.254)
		(layers "F.Cu" "B.Cu")
		(net "P12V_AUX")
	)
	(via
		(at 287.995614 -372.225062)
		(size 0.508)
		(drill 0.254)
		(layers "F.Cu" "B.Cu")
		(net "P12V_AUX")
	)
	(via
		(at 250.299474 -45.988732)
		(size 0.508)
		(drill 0.254)
		(layers "F.Cu" "B.Cu")
		(net "P12V_AUX")
	)
	(segment
		(start 432.59883 -51.84775)
		(end 432.43246 -52.01412)
		(width 0.381)
		(layer "B.Cu")
		(net "P12V_AUX")
	)
	(segment
		(start 364.213902 -359.358692)
		(end 362.973874 -359.358692)
		(width 0.381)
		(layer "B.Cu")
		(net "P12V_AUX")
	)
	(segment
		(start 185.376058 -397.942562)
		(end 185.376058 -398.651222)
		(width 0.381)
		(layer "B.Cu")
		(net "P12V_AUX")
	)
	(segment
		(start 432.81473 -50.72888)
		(end 432.81473 -51.63185)
		(width 0.381)
		(layer "B.Cu")
		(net "P12V_AUX")
	)
	(segment
		(start 26.005536 -128.364996)
		(end 26.63825 -128.364996)
		(width 0.381)
		(layer "B.Cu")
		(net "P12V_AUX")
	)
	(segment
		(start 115.434872 -363.522006)
		(end 114.99088 -363.078014)
		(width 0.381)
		(layer "B.Cu")
		(net "P12V_AUX")
	)
	(segment
		(start 362.973874 -359.358692)
		(end 362.31449 -360.018076)
		(width 0.381)
		(layer "B.Cu")
		(net "P12V_AUX")
	)
	(segment
		(start 447.936112 -78.515718)
		(end 448.22872 -78.515718)
		(width 0.381)
		(layer "B.Cu")
		(net "P12V_AUX")
	)
	(segment
		(start 362.907326 -362.90123)
		(end 362.907326 -362.029248)
		(width 0.381)
		(layer "B.Cu")
		(net "P12V_AUX")
	)
	(segment
		(start 115.981226 -363.522006)
		(end 115.434872 -363.522006)
		(width 0.381)
		(layer "B.Cu")
		(net "P12V_AUX")
	)
	(segment
		(start 364.1725 -363.018832)
		(end 363.859064 -363.332268)
		(width 0.381)
		(layer "B.Cu")
		(net "P12V_AUX")
	)
	(segment
		(start 364.315248 -359.460038)
		(end 364.213902 -359.358692)
		(width 0.381)
		(layer "B.Cu")
		(net "P12V_AUX")
	)
	(segment
		(start 432.81473 -51.63185)
		(end 432.59883 -51.84775)
		(width 0.381)
		(layer "B.Cu")
		(net "P12V_AUX")
	)
	(segment
		(start 362.637324 -361.759246)
		(end 362.091224 -361.759246)
		(width 0.381)
		(layer "B.Cu")
		(net "P12V_AUX")
	)
	(segment
		(start 420.282116 -135.146034)
		(end 420.282116 -136.162034)
		(width 0.381)
		(layer "B.Cu")
		(net "P12V_AUX")
	)
	(segment
		(start 114.18443 -361.785662)
		(end 114.18443 -361.764326)
		(width 0.381)
		(layer "B.Cu")
		(net "P12V_AUX")
	)
	(segment
		(start 114.99088 -363.078014)
		(end 114.99088 -362.592112)
		(width 0.381)
		(layer "B.Cu")
		(net "P12V_AUX")
	)
	(segment
		(start 363.859064 -363.332268)
		(end 363.338364 -363.332268)
		(width 0.381)
		(layer "B.Cu")
		(net "P12V_AUX")
	)
	(segment
		(start 116.392198 -359.331006)
		(end 114.95405 -359.331006)
		(width 0.381)
		(layer "B.Cu")
		(net "P12V_AUX")
	)
	(segment
		(start 419.570154 -135.142478)
		(end 419.57371 -135.146034)
		(width 0.381)
		(layer "B.Cu")
		(net "P12V_AUX")
	)
	(segment
		(start 26.63825 -128.364996)
		(end 26.63825 -129.380996)
		(width 0.381)
		(layer "B.Cu")
		(net "P12V_AUX")
	)
	(segment
		(start 433.61864 -51.84775)
		(end 432.59883 -51.84775)
		(width 0.381)
		(layer "B.Cu")
		(net "P12V_AUX")
	)
	(segment
		(start 116.444014 -359.382822)
		(end 116.392198 -359.331006)
		(width 0.381)
		(layer "B.Cu")
		(net "P12V_AUX")
	)
	(segment
		(start 114.374676 -359.91038)
		(end 114.374676 -360.018076)
		(width 0.381)
		(layer "B.Cu")
		(net "P12V_AUX")
	)
	(segment
		(start 114.99088 -362.592112)
		(end 114.18443 -361.785662)
		(width 0.381)
		(layer "B.Cu")
		(net "P12V_AUX")
	)
	(segment
		(start 447.531744 -78.920086)
		(end 447.936112 -78.515718)
		(width 0.381)
		(layer "B.Cu")
		(net "P12V_AUX")
	)
	(segment
		(start 362.907326 -362.029248)
		(end 362.637324 -361.759246)
		(width 0.381)
		(layer "B.Cu")
		(net "P12V_AUX")
	)
	(segment
		(start 419.57371 -135.146034)
		(end 420.282116 -135.146034)
		(width 0.381)
		(layer "B.Cu")
		(net "P12V_AUX")
	)
	(segment
		(start 185.46826 -397.85036)
		(end 185.376058 -397.942562)
		(width 0.381)
		(layer "B.Cu")
		(net "P12V_AUX")
	)
	(segment
		(start 114.95405 -359.331006)
		(end 114.374676 -359.91038)
		(width 0.381)
		(layer "B.Cu")
		(net "P12V_AUX")
	)
	(segment
		(start 363.338364 -363.332268)
		(end 362.907326 -362.90123)
		(width 0.381)
		(layer "B.Cu")
		(net "P12V_AUX")
	)
	(segment
		(start 364.44428 -362.747052)
		(end 364.44428 -359.58907)
		(width 0.381)
		(layer "In2.Cu")
		(net "P12V_AUX")
	)
	(segment
		(start 364.44428 -359.58907)
		(end 364.315248 -359.460038)
		(width 0.381)
		(layer "In2.Cu")
		(net "P12V_AUX")
	)
	(segment
		(start 279.01138 -390.85774)
		(end 282.58516 -390.85774)
		(width 0.381)
		(layer "In2.Cu")
		(net "P12V_AUX")
	)
	(segment
		(start 434.71592 -37.06622)
		(end 434.71592 -50.43932)
		(width 0.381)
		(layer "In2.Cu")
		(net "P12V_AUX")
	)
	(segment
		(start 46.348142 -112.619282)
		(end 47.592234 -112.619282)
		(width 0.508)
		(layer "In2.Cu")
		(net "P12V_AUX")
	)
	(segment
		(start 291.61232 -50.70602)
		(end 285.970472 -45.064172)
		(width 0.508)
		(layer "In2.Cu")
		(net "P12V_AUX")
	)
	(segment
		(start 364.1725 -363.018832)
		(end 364.44428 -362.747052)
		(width 0.381)
		(layer "In2.Cu")
		(net "P12V_AUX")
	)
	(segment
		(start 294.80002 -54.32298)
		(end 294.764714 -54.287674)
		(width 0.508)
		(layer "In2.Cu")
		(net "P12V_AUX")
	)
	(segment
		(start 283.34208 -391.61466)
		(end 283.34208 -394.58138)
		(width 0.381)
		(layer "In2.Cu")
		(net "P12V_AUX")
	)
	(segment
		(start 116.444014 -363.059218)
		(end 116.444014 -359.382822)
		(width 0.381)
		(layer "In2.Cu")
		(net "P12V_AUX")
	)
	(segment
		(start 65.343024 -39.186104)
		(end 65.343024 -39.808658)
		(width 0.4572)
		(layer "In2.Cu")
		(net "P12V_AUX")
	)
	(segment
		(start 435.48046 -36.30168)
		(end 434.71592 -37.06622)
		(width 0.381)
		(layer "In2.Cu")
		(net "P12V_AUX")
	)
	(segment
		(start 115.981226 -363.522006)
		(end 116.444014 -363.059218)
		(width 0.381)
		(layer "In2.Cu")
		(net "P12V_AUX")
	)
	(segment
		(start 285.970472 -41.176702)
		(end 276.930866 -32.137096)
		(width 0.508)
		(layer "In2.Cu")
		(net "P12V_AUX")
	)
	(segment
		(start 291.79393 -54.287674)
		(end 291.61232 -54.106064)
		(width 0.508)
		(layer "In2.Cu")
		(net "P12V_AUX")
	)
	(segment
		(start 283.34208 -394.58138)
		(end 284.49778 -395.73708)
		(width 0.381)
		(layer "In2.Cu")
		(net "P12V_AUX")
	)
	(segment
		(start 44.867068 -111.875316)
		(end 45.604176 -111.875316)
		(width 0.508)
		(layer "In2.Cu")
		(net "P12V_AUX")
	)
	(segment
		(start 284.49778 -395.73708)
		(end 288.980118 -395.73708)
		(width 0.381)
		(layer "In2.Cu")
		(net "P12V_AUX")
	)
	(segment
		(start 61.948568 -35.791648)
		(end 65.343024 -39.186104)
		(width 0.4572)
		(layer "In2.Cu")
		(net "P12V_AUX")
	)
	(segment
		(start 291.61232 -54.106064)
		(end 291.61232 -50.70602)
		(width 0.508)
		(layer "In2.Cu")
		(net "P12V_AUX")
	)
	(segment
		(start 45.604176 -111.875316)
		(end 46.348142 -112.619282)
		(width 0.508)
		(layer "In2.Cu")
		(net "P12V_AUX")
	)
	(segment
		(start 38.280594 -118.46179)
		(end 44.867068 -111.875316)
		(width 0.508)
		(layer "In2.Cu")
		(net "P12V_AUX")
	)
	(segment
		(start 294.764714 -54.287674)
		(end 291.79393 -54.287674)
		(width 0.508)
		(layer "In2.Cu")
		(net "P12V_AUX")
	)
	(segment
		(start 433.14112 -52.01412)
		(end 432.43246 -52.01412)
		(width 0.381)
		(layer "In2.Cu")
		(net "P12V_AUX")
	)
	(segment
		(start 434.71592 -50.43932)
		(end 433.14112 -52.01412)
		(width 0.381)
		(layer "In2.Cu")
		(net "P12V_AUX")
	)
	(segment
		(start 18.537174 -118.46179)
		(end 38.280594 -118.46179)
		(width 0.508)
		(layer "In2.Cu")
		(net "P12V_AUX")
	)
	(segment
		(start 285.970472 -45.064172)
		(end 285.970472 -41.176702)
		(width 0.508)
		(layer "In2.Cu")
		(net "P12V_AUX")
	)
	(segment
		(start 282.58516 -390.85774)
		(end 283.34208 -391.61466)
		(width 0.381)
		(layer "In2.Cu")
		(net "P12V_AUX")
	)
	(segment
		(start 217.827606 -98.809048)
		(end 219.379546 -97.257108)
		(width 0.508)
		(layer "In4.Cu")
		(net "P12V_AUX")
	)
	(segment
		(start 372.53164 -82.11566)
		(end 369.7224 -79.30642)
		(width 0.381)
		(layer "In4.Cu")
		(net "P12V_AUX")
	)
	(segment
		(start 219.379546 -104.6734)
		(end 219.93225 -105.226104)
		(width 0.508)
		(layer "In4.Cu")
		(net "P12V_AUX")
	)
	(segment
		(start 369.7224 -79.30642)
		(end 369.7224 -75.4888)
		(width 0.381)
		(layer "In4.Cu")
		(net "P12V_AUX")
	)
	(segment
		(start 221.097094 -81.56067)
		(end 225.383852 -77.273912)
		(width 0.508)
		(layer "In4.Cu")
		(net "P12V_AUX")
	)
	(segment
		(start 209.550762 -98.809048)
		(end 217.827606 -98.809048)
		(width 0.508)
		(layer "In4.Cu")
		(net "P12V_AUX")
	)
	(segment
		(start 219.750386 -97.257108)
		(end 221.097094 -95.9104)
		(width 0.508)
		(layer "In4.Cu")
		(net "P12V_AUX")
	)
	(segment
		(start 388.778496 -82.11566)
		(end 372.53164 -82.11566)
		(width 0.381)
		(layer "In4.Cu")
		(net "P12V_AUX")
	)
	(segment
		(start 219.379546 -97.257108)
		(end 219.379546 -104.6734)
		(width 0.508)
		(layer "In4.Cu")
		(net "P12V_AUX")
	)
	(segment
		(start 221.097094 -95.9104)
		(end 221.097094 -81.56067)
		(width 0.508)
		(layer "In4.Cu")
		(net "P12V_AUX")
	)
	(segment
		(start 219.379546 -97.257108)
		(end 219.750386 -97.257108)
		(width 0.508)
		(layer "In4.Cu")
		(net "P12V_AUX")
	)
	(segment
		(start 219.93225 -105.226104)
		(end 221.110302 -105.226104)
		(width 0.508)
		(layer "In4.Cu")
		(net "P12V_AUX")
	)
	(segment
		(start 225.383852 -77.273912)
		(end 225.383852 -75.37704)
		(width 0.508)
		(layer "In4.Cu")
		(net "P12V_AUX")
	)
	(segment
		(start 392.139932 -78.754224)
		(end 388.778496 -82.11566)
		(width 0.381)
		(layer "In4.Cu")
		(net "P12V_AUX")
	)
	(segment
		(start 307.848 -28.74518)
		(end 308.32298 -28.2702)
		(width 0.381)
		(layer "In11.Cu")
		(net "P12V_AUX")
	)
	(segment
		(start 301.9298 -27.38882)
		(end 298.81068 -30.50794)
		(width 0.381)
		(layer "In11.Cu")
		(net "P12V_AUX")
	)
	(segment
		(start 181.22646 -418.4142)
		(end 182.42153 -418.4142)
		(width 0.381)
		(layer "In11.Cu")
		(net "P12V_AUX")
	)
	(segment
		(start 303.97196 -28.03652)
		(end 304.68062 -28.74518)
		(width 0.381)
		(layer "In11.Cu")
		(net "P12V_AUX")
	)
	(segment
		(start 298.81068 -30.50794)
		(end 277.54326 -30.50794)
		(width 0.381)
		(layer "In11.Cu")
		(net "P12V_AUX")
	)
	(segment
		(start 302.16856 -25.81656)
		(end 303.25314 -25.81656)
		(width 0.381)
		(layer "In11.Cu")
		(net "P12V_AUX")
	)
	(segment
		(start 178.95316 -416.1409)
		(end 181.22646 -418.4142)
		(width 0.381)
		(layer "In11.Cu")
		(net "P12V_AUX")
	)
	(segment
		(start 304.68062 -28.74518)
		(end 307.848 -28.74518)
		(width 0.381)
		(layer "In11.Cu")
		(net "P12V_AUX")
	)
	(segment
		(start 301.9298 -25.5778)
		(end 301.9298 -27.38882)
		(width 0.381)
		(layer "In11.Cu")
		(net "P12V_AUX")
	)
	(segment
		(start 178.05654 -413.27578)
		(end 178.95316 -414.1724)
		(width 0.381)
		(layer "In11.Cu")
		(net "P12V_AUX")
	)
	(segment
		(start 178.942238 -406.127458)
		(end 178.05654 -407.013156)
		(width 0.381)
		(layer "In11.Cu")
		(net "P12V_AUX")
	)
	(segment
		(start 301.9298 -25.5778)
		(end 302.16856 -25.81656)
		(width 0.381)
		(layer "In11.Cu")
		(net "P12V_AUX")
	)
	(segment
		(start 178.05654 -407.013156)
		(end 178.05654 -413.27578)
		(width 0.381)
		(layer "In11.Cu")
		(net "P12V_AUX")
	)
	(segment
		(start 277.54326 -30.50794)
		(end 276.930866 -31.120334)
		(width 0.381)
		(layer "In11.Cu")
		(net "P12V_AUX")
	)
	(segment
		(start 303.25314 -25.81656)
		(end 303.97196 -26.53538)
		(width 0.381)
		(layer "In11.Cu")
		(net "P12V_AUX")
	)
	(segment
		(start 276.930866 -31.120334)
		(end 276.930866 -32.137096)
		(width 0.381)
		(layer "In11.Cu")
		(net "P12V_AUX")
	)
	(segment
		(start 178.95316 -414.1724)
		(end 178.95316 -416.1409)
		(width 0.381)
		(layer "In11.Cu")
		(net "P12V_AUX")
	)
	(segment
		(start 303.97196 -26.53538)
		(end 303.97196 -28.03652)
		(width 0.381)
		(layer "In11.Cu")
		(net "P12V_AUX")
	)
	(segment
		(start 308.32298 -28.2702)
		(end 308.8132 -28.2702)
		(width 0.381)
		(layer "In11.Cu")
		(net "P12V_AUX")
	)
	(segment
		(start 200.93305 -93.62059)
		(end 200.93305 -98.552)
		(width 0.381)
		(layer "In13.Cu")
		(net "P12V_AUX")
	)
	(segment
		(start 201.80554 -92.7481)
		(end 200.93305 -93.62059)
		(width 0.381)
		(layer "In13.Cu")
		(net "P12V_AUX")
	)
	(segment
		(start 204.724 -91.5924)
		(end 204.724 -92.20454)
		(width 0.381)
		(layer "In13.Cu")
		(net "P12V_AUX")
	)
	(segment
		(start 204.724 -92.20454)
		(end 204.18044 -92.7481)
		(width 0.381)
		(layer "In13.Cu")
		(net "P12V_AUX")
	)
	(segment
		(start 204.18044 -92.7481)
		(end 201.80554 -92.7481)
		(width 0.381)
		(layer "In13.Cu")
		(net "P12V_AUX")
	)
	(segment
		(start 468.89162 -45.805598)
		(end 468.415878 -46.28134)
		(width 0.12954)
		(layer "F.Cu")
		(net "OCP_SFF_WAKE_BUFF_R_N")
	)
	(segment
		(start 314.10148 -14.950948)
		(end 313.841892 -14.69136)
		(width 0.12954)
		(layer "F.Cu")
		(net "OCP_SFF_WAKE_BUFF_R_N")
	)
	(segment
		(start 313.841892 -14.69136)
		(end 313.17057 -14.69136)
		(width 0.12954)
		(layer "F.Cu")
		(net "OCP_SFF_WAKE_BUFF_R_N")
	)
	(segment
		(start 468.89162 -44.887388)
		(end 468.89162 -45.805598)
		(width 0.12954)
		(layer "F.Cu")
		(net "OCP_SFF_WAKE_BUFF_R_N")
	)
	(via
		(at 314.10148 -14.950948)
		(size 0.508)
		(drill 0.254)
		(layers "F.Cu" "B.Cu")
		(net "OCP_SFF_WAKE_BUFF_R_N")
	)
	(via
		(at 468.415878 -46.28134)
		(size 0.508)
		(drill 0.254)
		(layers "F.Cu" "B.Cu")
		(net "OCP_SFF_WAKE_BUFF_R_N")
	)
	(segment
		(start 468.415878 -46.28134)
		(end 468.415878 -43.802046)
		(width 0.127)
		(layer "In2.Cu")
		(net "OCP_SFF_WAKE_BUFF_R_N")
	)
	(segment
		(start 458.016356 -13.450824)
		(end 457.454508 -12.888976)
		(width 0.127)
		(layer "In2.Cu")
		(net "OCP_SFF_WAKE_BUFF_R_N")
	)
	(segment
		(start 335.064862 -15.123668)
		(end 335.064862 -14.961362)
		(width 0.127)
		(layer "In2.Cu")
		(net "OCP_SFF_WAKE_BUFF_R_N")
	)
	(segment
		(start 336.75447 -14.801088)
		(end 336.048096 -15.507462)
		(width 0.127)
		(layer "In2.Cu")
		(net "OCP_SFF_WAKE_BUFF_R_N")
	)
	(segment
		(start 455.325988 -12.888976)
		(end 453.59574 -11.158728)
		(width 0.127)
		(layer "In2.Cu")
		(net "OCP_SFF_WAKE_BUFF_R_N")
	)
	(segment
		(start 336.75447 -14.570964)
		(end 336.75447 -14.801088)
		(width 0.127)
		(layer "In2.Cu")
		(net "OCP_SFF_WAKE_BUFF_R_N")
	)
	(segment
		(start 453.20204 -4.044188)
		(end 453.20204 -2.997708)
		(width 0.127)
		(layer "In2.Cu")
		(net "OCP_SFF_WAKE_BUFF_R_N")
	)
	(segment
		(start 452.93534 -2.731008)
		(end 445.096392 -2.731008)
		(width 0.127)
		(layer "In2.Cu")
		(net "OCP_SFF_WAKE_BUFF_R_N")
	)
	(segment
		(start 334.627728 -13.757656)
		(end 322.236338 -13.757656)
		(width 0.127)
		(layer "In2.Cu")
		(net "OCP_SFF_WAKE_BUFF_R_N")
	)
	(segment
		(start 433.818792 -14.008608)
		(end 337.316826 -14.008608)
		(width 0.127)
		(layer "In2.Cu")
		(net "OCP_SFF_WAKE_BUFF_R_N")
	)
	(segment
		(start 463.67446 -37.838888)
		(end 459.3717 -33.536128)
		(width 0.127)
		(layer "In2.Cu")
		(net "OCP_SFF_WAKE_BUFF_R_N")
	)
	(segment
		(start 445.096392 -2.731008)
		(end 433.818792 -14.008608)
		(width 0.127)
		(layer "In2.Cu")
		(net "OCP_SFF_WAKE_BUFF_R_N")
	)
	(segment
		(start 464.4898 -37.838888)
		(end 463.67446 -37.838888)
		(width 0.127)
		(layer "In2.Cu")
		(net "OCP_SFF_WAKE_BUFF_R_N")
	)
	(segment
		(start 459.3717 -33.536128)
		(end 459.3717 -16.115792)
		(width 0.127)
		(layer "In2.Cu")
		(net "OCP_SFF_WAKE_BUFF_R_N")
	)
	(segment
		(start 458.016356 -14.760448)
		(end 458.016356 -13.450824)
		(width 0.127)
		(layer "In2.Cu")
		(net "OCP_SFF_WAKE_BUFF_R_N")
	)
	(segment
		(start 452.102474 -5.143754)
		(end 453.20204 -4.044188)
		(width 0.127)
		(layer "In2.Cu")
		(net "OCP_SFF_WAKE_BUFF_R_N")
	)
	(segment
		(start 459.3717 -16.115792)
		(end 458.016356 -14.760448)
		(width 0.127)
		(layer "In2.Cu")
		(net "OCP_SFF_WAKE_BUFF_R_N")
	)
	(segment
		(start 322.236338 -13.757656)
		(end 321.703446 -14.290548)
		(width 0.127)
		(layer "In2.Cu")
		(net "OCP_SFF_WAKE_BUFF_R_N")
	)
	(segment
		(start 334.873346 -14.769846)
		(end 334.873346 -14.003274)
		(width 0.127)
		(layer "In2.Cu")
		(net "OCP_SFF_WAKE_BUFF_R_N")
	)
	(segment
		(start 457.454508 -12.888976)
		(end 455.325988 -12.888976)
		(width 0.127)
		(layer "In2.Cu")
		(net "OCP_SFF_WAKE_BUFF_R_N")
	)
	(segment
		(start 452.102474 -7.102602)
		(end 452.102474 -5.143754)
		(width 0.127)
		(layer "In2.Cu")
		(net "OCP_SFF_WAKE_BUFF_R_N")
	)
	(segment
		(start 321.703446 -14.290548)
		(end 314.76188 -14.290548)
		(width 0.127)
		(layer "In2.Cu")
		(net "OCP_SFF_WAKE_BUFF_R_N")
	)
	(segment
		(start 337.316826 -14.008608)
		(end 336.75447 -14.570964)
		(width 0.127)
		(layer "In2.Cu")
		(net "OCP_SFF_WAKE_BUFF_R_N")
	)
	(segment
		(start 453.59574 -11.158728)
		(end 453.59574 -8.595868)
		(width 0.127)
		(layer "In2.Cu")
		(net "OCP_SFF_WAKE_BUFF_R_N")
	)
	(segment
		(start 314.76188 -14.290548)
		(end 314.10148 -14.950948)
		(width 0.127)
		(layer "In2.Cu")
		(net "OCP_SFF_WAKE_BUFF_R_N")
	)
	(segment
		(start 465.62772 -41.013888)
		(end 465.62772 -38.976808)
		(width 0.127)
		(layer "In2.Cu")
		(net "OCP_SFF_WAKE_BUFF_R_N")
	)
	(segment
		(start 453.20204 -2.997708)
		(end 452.93534 -2.731008)
		(width 0.127)
		(layer "In2.Cu")
		(net "OCP_SFF_WAKE_BUFF_R_N")
	)
	(segment
		(start 335.064862 -14.961362)
		(end 334.873346 -14.769846)
		(width 0.127)
		(layer "In2.Cu")
		(net "OCP_SFF_WAKE_BUFF_R_N")
	)
	(segment
		(start 336.048096 -15.507462)
		(end 335.448656 -15.507462)
		(width 0.127)
		(layer "In2.Cu")
		(net "OCP_SFF_WAKE_BUFF_R_N")
	)
	(segment
		(start 334.873346 -14.003274)
		(end 334.627728 -13.757656)
		(width 0.127)
		(layer "In2.Cu")
		(net "OCP_SFF_WAKE_BUFF_R_N")
	)
	(segment
		(start 468.415878 -43.802046)
		(end 465.62772 -41.013888)
		(width 0.127)
		(layer "In2.Cu")
		(net "OCP_SFF_WAKE_BUFF_R_N")
	)
	(segment
		(start 453.59574 -8.595868)
		(end 452.102474 -7.102602)
		(width 0.127)
		(layer "In2.Cu")
		(net "OCP_SFF_WAKE_BUFF_R_N")
	)
	(segment
		(start 335.448656 -15.507462)
		(end 335.064862 -15.123668)
		(width 0.127)
		(layer "In2.Cu")
		(net "OCP_SFF_WAKE_BUFF_R_N")
	)
	(segment
		(start 465.62772 -38.976808)
		(end 464.4898 -37.838888)
		(width 0.127)
		(layer "In2.Cu")
		(net "OCP_SFF_WAKE_BUFF_R_N")
	)
	(segment
		(start 467.959186 -45.019722)
		(end 468.09152 -44.887388)
		(width 0.12954)
		(layer "F.Cu")
		(net "OCP_SFF_WAKE_BUFF_N")
	)
	(segment
		(start 468.09279 -43.735498)
		(end 468.09152 -43.736768)
		(width 0.12954)
		(layer "F.Cu")
		(net "OCP_SFF_WAKE_BUFF_N")
	)
	(segment
		(start 468.09152 -43.736768)
		(end 468.09152 -44.887388)
		(width 0.12954)
		(layer "F.Cu")
		(net "OCP_SFF_WAKE_BUFF_N")
	)
	(segment
		(start 466.510878 -45.019722)
		(end 467.959186 -45.019722)
		(width 0.12954)
		(layer "F.Cu")
		(net "OCP_SFF_WAKE_BUFF_N")
	)
	(segment
		(start 464.96351 -45.019722)
		(end 466.510878 -45.019722)
		(width 0.12954)
		(layer "F.Cu")
		(net "OCP_SFF_WAKE_BUFF_N")
	)
	(via
		(at 466.510878 -45.019722)
		(size 0.762)
		(drill 0.381)
		(layers "F.Cu" "B.Cu")
		(net "OCP_SFF_WAKE_BUFF_N")
	)
	(segment
		(start 392.025886 -9.066784)
		(end 392.025886 -9.582912)
		(width 0.13208)
		(layer "F.Cu")
		(net "OCP_SFF_USB2_3_DP")
	)
	(segment
		(start 390.426702 -9.749028)
		(end 387.65988 -12.51585)
		(width 0.13208)
		(layer "F.Cu")
		(net "OCP_SFF_USB2_3_DP")
	)
	(segment
		(start 392.025886 -9.582912)
		(end 391.85977 -9.749028)
		(width 0.13208)
		(layer "F.Cu")
		(net "OCP_SFF_USB2_3_DP")
	)
	(segment
		(start 391.846816 -8.887714)
		(end 392.025886 -9.066784)
		(width 0.13208)
		(layer "F.Cu")
		(net "OCP_SFF_USB2_3_DP")
	)
	(segment
		(start 391.85977 -9.749028)
		(end 390.426702 -9.749028)
		(width 0.13208)
		(layer "F.Cu")
		(net "OCP_SFF_USB2_3_DP")
	)
	(segment
		(start 387.65988 -12.51585)
		(end 387.65988 -13.455396)
		(width 0.13208)
		(layer "F.Cu")
		(net "OCP_SFF_USB2_3_DP")
	)
	(segment
		(start 391.846816 -8.320024)
		(end 391.846816 -8.887714)
		(width 0.13208)
		(layer "F.Cu")
		(net "OCP_SFF_USB2_3_DP")
	)
	(segment
		(start 387.65988 -13.455396)
		(end 387.262116 -13.85316)
		(width 0.13208)
		(layer "F.Cu")
		(net "OCP_SFF_USB2_3_DP")
	)
	(segment
		(start 387.91896 -12.623292)
		(end 387.91896 -13.494004)
		(width 0.13208)
		(layer "F.Cu")
		(net "OCP_SFF_USB2_3_DN")
	)
	(segment
		(start 390.534144 -10.008108)
		(end 387.91896 -12.623292)
		(width 0.13208)
		(layer "F.Cu")
		(net "OCP_SFF_USB2_3_DN")
	)
	(segment
		(start 392.284966 -9.08558)
		(end 392.284966 -9.690354)
		(width 0.13208)
		(layer "F.Cu")
		(net "OCP_SFF_USB2_3_DN")
	)
	(segment
		(start 392.284966 -9.690354)
		(end 391.967212 -10.008108)
		(width 0.13208)
		(layer "F.Cu")
		(net "OCP_SFF_USB2_3_DN")
	)
	(segment
		(start 391.967212 -10.008108)
		(end 390.534144 -10.008108)
		(width 0.13208)
		(layer "F.Cu")
		(net "OCP_SFF_USB2_3_DN")
	)
	(segment
		(start 387.91896 -13.494004)
		(end 388.278116 -13.85316)
		(width 0.13208)
		(layer "F.Cu")
		(net "OCP_SFF_USB2_3_DN")
	)
	(segment
		(start 392.446764 -8.923782)
		(end 392.284966 -9.08558)
		(width 0.13208)
		(layer "F.Cu")
		(net "OCP_SFF_USB2_3_DN")
	)
	(segment
		(start 392.446764 -8.320024)
		(end 392.446764 -8.923782)
		(width 0.13208)
		(layer "F.Cu")
		(net "OCP_SFF_USB2_3_DN")
	)
	(segment
		(start 144.595342 -36.111942)
		(end 143.48206 -36.111942)
		(width 0.12954)
		(layer "F.Cu")
		(net "OCP_SFF_RBT_ARB_OUT")
	)
	(via
		(at 191.84747 -75.907138)
		(size 0.508)
		(drill 0.254)
		(layers "F.Cu" "B.Cu")
		(net "OCP_SFF_RBT_ARB_OUT")
	)
	(via
		(at 143.48206 -36.111942)
		(size 0.508)
		(drill 0.254)
		(layers "F.Cu" "B.Cu")
		(net "OCP_SFF_RBT_ARB_OUT")
	)
	(via
		(at 213.2203 -69.256148)
		(size 0.508)
		(drill 0.254)
		(layers "F.Cu" "B.Cu")
		(net "OCP_SFF_RBT_ARB_OUT")
	)
	(segment
		(start 214.166958 -70.202806)
		(end 214.757 -70.202806)
		(width 0.12954)
		(layer "B.Cu")
		(net "OCP_SFF_RBT_ARB_OUT")
	)
	(segment
		(start 213.2203 -69.256148)
		(end 214.166958 -70.202806)
		(width 0.12954)
		(layer "B.Cu")
		(net "OCP_SFF_RBT_ARB_OUT")
	)
	(segment
		(start 191.84747 -77.4827)
		(end 191.47409 -77.85608)
		(width 0.12954)
		(layer "B.Cu")
		(net "OCP_SFF_RBT_ARB_OUT")
	)
	(segment
		(start 191.84747 -75.907138)
		(end 191.84747 -77.4827)
		(width 0.12954)
		(layer "B.Cu")
		(net "OCP_SFF_RBT_ARB_OUT")
	)
	(segment
		(start 149.36724 -39.995348)
		(end 148.90242 -39.995348)
		(width 0.127)
		(layer "In6.Cu")
		(net "OCP_SFF_RBT_ARB_OUT")
	)
	(segment
		(start 191.84747 -75.907138)
		(end 189.43955 -75.907138)
		(width 0.127)
		(layer "In6.Cu")
		(net "OCP_SFF_RBT_ARB_OUT")
	)
	(segment
		(start 186.56554 -73.033128)
		(end 186.56554 -63.086488)
		(width 0.127)
		(layer "In6.Cu")
		(net "OCP_SFF_RBT_ARB_OUT")
	)
	(segment
		(start 181.69382 -58.214768)
		(end 179.62372 -58.214768)
		(width 0.127)
		(layer "In6.Cu")
		(net "OCP_SFF_RBT_ARB_OUT")
	)
	(segment
		(start 152.87498 -40.028368)
		(end 151.88946 -41.013888)
		(width 0.127)
		(layer "In6.Cu")
		(net "OCP_SFF_RBT_ARB_OUT")
	)
	(segment
		(start 186.56554 -63.086488)
		(end 181.69382 -58.214768)
		(width 0.127)
		(layer "In6.Cu")
		(net "OCP_SFF_RBT_ARB_OUT")
	)
	(segment
		(start 151.88946 -41.013888)
		(end 150.38578 -41.013888)
		(width 0.127)
		(layer "In6.Cu")
		(net "OCP_SFF_RBT_ARB_OUT")
	)
	(segment
		(start 200.7616 -70.754748)
		(end 201.92492 -71.918068)
		(width 0.127)
		(layer "In6.Cu")
		(net "OCP_SFF_RBT_ARB_OUT")
	)
	(segment
		(start 213.2203 -69.797168)
		(end 213.2203 -69.256148)
		(width 0.127)
		(layer "In6.Cu")
		(net "OCP_SFF_RBT_ARB_OUT")
	)
	(segment
		(start 191.2493 -74.31024)
		(end 191.88049 -73.67905)
		(width 0.127)
		(layer "In6.Cu")
		(net "OCP_SFF_RBT_ARB_OUT")
	)
	(segment
		(start 191.88049 -73.67905)
		(end 196.516498 -73.67905)
		(width 0.127)
		(layer "In6.Cu")
		(net "OCP_SFF_RBT_ARB_OUT")
	)
	(segment
		(start 143.92656 -36.111942)
		(end 143.48206 -36.111942)
		(width 0.127)
		(layer "In6.Cu")
		(net "OCP_SFF_RBT_ARB_OUT")
	)
	(segment
		(start 145.077434 -36.170362)
		(end 143.98498 -36.170362)
		(width 0.127)
		(layer "In6.Cu")
		(net "OCP_SFF_RBT_ARB_OUT")
	)
	(segment
		(start 201.92492 -71.918068)
		(end 211.0994 -71.918068)
		(width 0.127)
		(layer "In6.Cu")
		(net "OCP_SFF_RBT_ARB_OUT")
	)
	(segment
		(start 199.4408 -70.754748)
		(end 200.7616 -70.754748)
		(width 0.127)
		(layer "In6.Cu")
		(net "OCP_SFF_RBT_ARB_OUT")
	)
	(segment
		(start 211.0994 -71.918068)
		(end 213.2203 -69.797168)
		(width 0.127)
		(layer "In6.Cu")
		(net "OCP_SFF_RBT_ARB_OUT")
	)
	(segment
		(start 189.43955 -75.907138)
		(end 186.56554 -73.033128)
		(width 0.127)
		(layer "In6.Cu")
		(net "OCP_SFF_RBT_ARB_OUT")
	)
	(segment
		(start 196.516498 -73.67905)
		(end 199.4408 -70.754748)
		(width 0.127)
		(layer "In6.Cu")
		(net "OCP_SFF_RBT_ARB_OUT")
	)
	(segment
		(start 191.2493 -75.308968)
		(end 191.2493 -74.31024)
		(width 0.127)
		(layer "In6.Cu")
		(net "OCP_SFF_RBT_ARB_OUT")
	)
	(segment
		(start 179.62372 -58.214768)
		(end 161.43732 -40.028368)
		(width 0.127)
		(layer "In6.Cu")
		(net "OCP_SFF_RBT_ARB_OUT")
	)
	(segment
		(start 191.84747 -75.907138)
		(end 191.2493 -75.308968)
		(width 0.127)
		(layer "In6.Cu")
		(net "OCP_SFF_RBT_ARB_OUT")
	)
	(segment
		(start 143.98498 -36.170362)
		(end 143.92656 -36.111942)
		(width 0.127)
		(layer "In6.Cu")
		(net "OCP_SFF_RBT_ARB_OUT")
	)
	(segment
		(start 150.38578 -41.013888)
		(end 149.36724 -39.995348)
		(width 0.127)
		(layer "In6.Cu")
		(net "OCP_SFF_RBT_ARB_OUT")
	)
	(segment
		(start 161.43732 -40.028368)
		(end 152.87498 -40.028368)
		(width 0.127)
		(layer "In6.Cu")
		(net "OCP_SFF_RBT_ARB_OUT")
	)
	(segment
		(start 148.90242 -39.995348)
		(end 145.077434 -36.170362)
		(width 0.127)
		(layer "In6.Cu")
		(net "OCP_SFF_RBT_ARB_OUT")
	)
	(segment
		(start 140.79728 -40.099488)
		(end 136.44626 -40.099488)
		(width 0.12954)
		(layer "F.Cu")
		(net "OCP_SFF_RBT_ARB_IN")
	)
	(segment
		(start 142.42288 -39.357808)
		(end 141.4018 -40.378888)
		(width 0.12954)
		(layer "F.Cu")
		(net "OCP_SFF_RBT_ARB_IN")
	)
	(segment
		(start 141.4018 -40.378888)
		(end 141.07668 -40.378888)
		(width 0.12954)
		(layer "F.Cu")
		(net "OCP_SFF_RBT_ARB_IN")
	)
	(segment
		(start 141.07668 -40.378888)
		(end 140.79728 -40.099488)
		(width 0.12954)
		(layer "F.Cu")
		(net "OCP_SFF_RBT_ARB_IN")
	)
	(segment
		(start 135.83031 -40.715438)
		(end 135.83031 -40.911018)
		(width 0.12954)
		(layer "F.Cu")
		(net "OCP_SFF_RBT_ARB_IN")
	)
	(segment
		(start 145.128742 -32.507682)
		(end 144.188942 -32.507682)
		(width 0.12954)
		(layer "F.Cu")
		(net "OCP_SFF_RBT_ARB_IN")
	)
	(segment
		(start 143.84782 -32.504888)
		(end 142.42288 -33.929828)
		(width 0.12954)
		(layer "F.Cu")
		(net "OCP_SFF_RBT_ARB_IN")
	)
	(segment
		(start 142.42288 -33.929828)
		(end 142.42288 -39.357808)
		(width 0.12954)
		(layer "F.Cu")
		(net "OCP_SFF_RBT_ARB_IN")
	)
	(segment
		(start 144.186148 -32.504888)
		(end 143.84782 -32.504888)
		(width 0.12954)
		(layer "F.Cu")
		(net "OCP_SFF_RBT_ARB_IN")
	)
	(segment
		(start 144.188942 -32.507682)
		(end 144.186148 -32.504888)
		(width 0.12954)
		(layer "F.Cu")
		(net "OCP_SFF_RBT_ARB_IN")
	)
	(segment
		(start 136.44626 -40.099488)
		(end 135.83031 -40.715438)
		(width 0.12954)
		(layer "F.Cu")
		(net "OCP_SFF_RBT_ARB_IN")
	)
	(via
		(at 190.118492 -78.64856)
		(size 0.508)
		(drill 0.254)
		(layers "F.Cu" "B.Cu")
		(net "OCP_SFF_RBT_ARB_IN")
	)
	(via
		(at 135.83031 -40.911018)
		(size 0.508)
		(drill 0.254)
		(layers "F.Cu" "B.Cu")
		(net "OCP_SFF_RBT_ARB_IN")
	)
	(segment
		(start 190.118492 -78.64856)
		(end 190.66637 -78.64856)
		(width 0.12954)
		(layer "B.Cu")
		(net "OCP_SFF_RBT_ARB_IN")
	)
	(segment
		(start 190.66637 -78.64856)
		(end 191.47409 -79.45628)
		(width 0.12954)
		(layer "B.Cu")
		(net "OCP_SFF_RBT_ARB_IN")
	)
	(segment
		(start 159.7279 -65.987168)
		(end 160.846008 -65.987168)
		(width 0.127)
		(layer "In4.Cu")
		(net "OCP_SFF_RBT_ARB_IN")
	)
	(segment
		(start 135.83031 -40.911018)
		(end 135.83031 -42.257218)
		(width 0.127)
		(layer "In4.Cu")
		(net "OCP_SFF_RBT_ARB_IN")
	)
	(segment
		(start 146.88058 -64.900048)
		(end 151.8539 -64.900048)
		(width 0.127)
		(layer "In4.Cu")
		(net "OCP_SFF_RBT_ARB_IN")
	)
	(segment
		(start 190.118492 -79.886048)
		(end 190.118492 -78.64856)
		(width 0.127)
		(layer "In4.Cu")
		(net "OCP_SFF_RBT_ARB_IN")
	)
	(segment
		(start 154.90952 -64.122808)
		(end 155.8417 -65.054988)
		(width 0.127)
		(layer "In4.Cu")
		(net "OCP_SFF_RBT_ARB_IN")
	)
	(segment
		(start 137.08634 -43.513248)
		(end 137.08634 -46.893988)
		(width 0.127)
		(layer "In4.Cu")
		(net "OCP_SFF_RBT_ARB_IN")
	)
	(segment
		(start 155.8417 -65.054988)
		(end 158.79572 -65.054988)
		(width 0.127)
		(layer "In4.Cu")
		(net "OCP_SFF_RBT_ARB_IN")
	)
	(segment
		(start 137.08634 -46.893988)
		(end 142.52702 -52.334668)
		(width 0.127)
		(layer "In4.Cu")
		(net "OCP_SFF_RBT_ARB_IN")
	)
	(segment
		(start 188.490606 -81.513934)
		(end 190.118492 -79.886048)
		(width 0.127)
		(layer "In4.Cu")
		(net "OCP_SFF_RBT_ARB_IN")
	)
	(segment
		(start 176.372774 -81.513934)
		(end 188.490606 -81.513934)
		(width 0.127)
		(layer "In4.Cu")
		(net "OCP_SFF_RBT_ARB_IN")
	)
	(segment
		(start 151.8539 -64.900048)
		(end 152.63114 -64.122808)
		(width 0.127)
		(layer "In4.Cu")
		(net "OCP_SFF_RBT_ARB_IN")
	)
	(segment
		(start 142.52702 -52.334668)
		(end 142.52702 -60.546488)
		(width 0.127)
		(layer "In4.Cu")
		(net "OCP_SFF_RBT_ARB_IN")
	)
	(segment
		(start 142.52702 -60.546488)
		(end 146.88058 -64.900048)
		(width 0.127)
		(layer "In4.Cu")
		(net "OCP_SFF_RBT_ARB_IN")
	)
	(segment
		(start 135.83031 -42.257218)
		(end 137.08634 -43.513248)
		(width 0.127)
		(layer "In4.Cu")
		(net "OCP_SFF_RBT_ARB_IN")
	)
	(segment
		(start 160.846008 -65.987168)
		(end 176.372774 -81.513934)
		(width 0.127)
		(layer "In4.Cu")
		(net "OCP_SFF_RBT_ARB_IN")
	)
	(segment
		(start 158.79572 -65.054988)
		(end 159.7279 -65.987168)
		(width 0.127)
		(layer "In4.Cu")
		(net "OCP_SFF_RBT_ARB_IN")
	)
	(segment
		(start 152.63114 -64.122808)
		(end 154.90952 -64.122808)
		(width 0.127)
		(layer "In4.Cu")
		(net "OCP_SFF_RBT_ARB_IN")
	)
	(segment
		(start 394.45184 -31.587186)
		(end 394.450316 -31.585662)
		(width 0.12954)
		(layer "F.Cu")
		(net "OCP_SFF_PWRBRK_N")
	)
	(segment
		(start 391.50036 -6.998208)
		(end 392.17854 -6.998208)
		(width 0.12954)
		(layer "F.Cu")
		(net "OCP_SFF_PWRBRK_N")
	)
	(segment
		(start 391.246868 -7.2517)
		(end 391.50036 -6.998208)
		(width 0.12954)
		(layer "F.Cu")
		(net "OCP_SFF_PWRBRK_N")
	)
	(segment
		(start 391.246868 -8.320024)
		(end 391.246868 -7.2517)
		(width 0.12954)
		(layer "F.Cu")
		(net "OCP_SFF_PWRBRK_N")
	)
	(segment
		(start 394.450316 -31.585662)
		(end 393.115038 -31.585662)
		(width 0.12954)
		(layer "F.Cu")
		(net "OCP_SFF_PWRBRK_N")
	)
	(via
		(at 392.17854 -6.998208)
		(size 0.508)
		(drill 0.254)
		(layers "F.Cu" "B.Cu")
		(net "OCP_SFF_PWRBRK_N")
	)
	(via
		(at 394.45184 -31.587186)
		(size 0.508)
		(drill 0.254)
		(layers "F.Cu" "B.Cu")
		(net "OCP_SFF_PWRBRK_N")
	)
	(segment
		(start 394.45184 -31.587186)
		(end 391.572496 -28.707842)
		(width 0.127)
		(layer "In6.Cu")
		(net "OCP_SFF_PWRBRK_N")
	)
	(segment
		(start 391.572496 -18.428208)
		(end 392.17854 -17.822164)
		(width 0.127)
		(layer "In6.Cu")
		(net "OCP_SFF_PWRBRK_N")
	)
	(segment
		(start 392.17854 -17.822164)
		(end 392.17854 -6.998208)
		(width 0.127)
		(layer "In6.Cu")
		(net "OCP_SFF_PWRBRK_N")
	)
	(segment
		(start 391.572496 -28.707842)
		(end 391.572496 -18.428208)
		(width 0.127)
		(layer "In6.Cu")
		(net "OCP_SFF_PWRBRK_N")
	)
	(segment
		(start 392.13028 -30.775148)
		(end 392.119866 -30.785562)
		(width 0.12954)
		(layer "F.Cu")
		(net "OCP_SFF_PWRBRK_BUFF_N")
	)
	(segment
		(start 392.13028 -29.96438)
		(end 392.13028 -30.775148)
		(width 0.12954)
		(layer "F.Cu")
		(net "OCP_SFF_PWRBRK_BUFF_N")
	)
	(segment
		(start 391.006838 -29.50972)
		(end 392.58494 -29.50972)
		(width 0.12954)
		(layer "F.Cu")
		(net "OCP_SFF_PWRBRK_BUFF_N")
	)
	(segment
		(start 393.115038 -30.785562)
		(end 392.119866 -30.785562)
		(width 0.12954)
		(layer "F.Cu")
		(net "OCP_SFF_PWRBRK_BUFF_N")
	)
	(segment
		(start 392.58494 -29.50972)
		(end 392.13028 -29.96438)
		(width 0.12954)
		(layer "F.Cu")
		(net "OCP_SFF_PWRBRK_BUFF_N")
	)
	(via
		(at 392.58494 -29.50972)
		(size 0.762)
		(drill 0.381)
		(layers "F.Cu" "B.Cu")
		(net "OCP_SFF_PWRBRK_BUFF_N")
	)
	(segment
		(start 434.966872 -7.136638)
		(end 434.870606 -7.040372)
		(width 0.12954)
		(layer "F.Cu")
		(net "OCP_SFF_PRSNTA_R_N")
	)
	(segment
		(start 434.966872 -8.320024)
		(end 434.966872 -7.136638)
		(width 0.12954)
		(layer "F.Cu")
		(net "OCP_SFF_PRSNTA_R_N")
	)
	(segment
		(start 435.483 -4.643628)
		(end 435.66334 -4.643628)
		(width 0.12954)
		(layer "F.Cu")
		(net "OCP_SFF_PRSNTA_R_N")
	)
	(segment
		(start 434.870606 -5.256022)
		(end 435.483 -4.643628)
		(width 0.12954)
		(layer "F.Cu")
		(net "OCP_SFF_PRSNTA_R_N")
	)
	(segment
		(start 434.870606 -7.040372)
		(end 434.870606 -5.256022)
		(width 0.12954)
		(layer "F.Cu")
		(net "OCP_SFF_PRSNTA_R_N")
	)
	(via
		(at 435.66334 -4.643628)
		(size 0.508)
		(drill 0.254)
		(layers "F.Cu" "B.Cu")
		(net "OCP_SFF_PRSNTA_R_N")
	)
	(segment
		(start 436.12308 -5.103368)
		(end 436.12308 -5.756148)
		(width 0.12954)
		(layer "B.Cu")
		(net "OCP_SFF_PRSNTA_R_N")
	)
	(segment
		(start 436.12308 -5.756148)
		(end 435.145942 -6.733286)
		(width 0.12954)
		(layer "B.Cu")
		(net "OCP_SFF_PRSNTA_R_N")
	)
	(segment
		(start 435.145942 -6.733286)
		(end 435.145942 -7.916926)
		(width 0.12954)
		(layer "B.Cu")
		(net "OCP_SFF_PRSNTA_R_N")
	)
	(segment
		(start 435.66334 -4.643628)
		(end 436.12308 -5.103368)
		(width 0.12954)
		(layer "B.Cu")
		(net "OCP_SFF_PRSNTA_R_N")
	)
	(segment
		(start 390.92886 -12.062968)
		(end 390.22274 -12.062968)
		(width 0.12954)
		(layer "F.Cu")
		(net "OCP_SFF_PRSNT3_R_N")
	)
	(segment
		(start 391.246868 -11.26998)
		(end 391.246868 -11.74496)
		(width 0.12954)
		(layer "F.Cu")
		(net "OCP_SFF_PRSNT3_R_N")
	)
	(segment
		(start 454.119996 -102.598728)
		(end 455.296778 -102.598728)
		(width 0.12954)
		(layer "F.Cu")
		(net "OCP_SFF_PRSNT3_R_N")
	)
	(segment
		(start 444.909702 -39.187628)
		(end 446.633092 -39.187628)
		(width 0.12954)
		(layer "F.Cu")
		(net "OCP_SFF_PRSNT3_R_N")
	)
	(segment
		(start 456.339956 -102.598728)
		(end 456.737466 -102.996238)
		(width 0.12954)
		(layer "F.Cu")
		(net "OCP_SFF_PRSNT3_R_N")
	)
	(segment
		(start 444.11011 -38.388036)
		(end 444.909702 -39.187628)
		(width 0.12954)
		(layer "F.Cu")
		(net "OCP_SFF_PRSNT3_R_N")
	)
	(segment
		(start 391.246868 -11.74496)
		(end 390.92886 -12.062968)
		(width 0.12954)
		(layer "F.Cu")
		(net "OCP_SFF_PRSNT3_R_N")
	)
	(segment
		(start 455.296778 -102.598728)
		(end 456.339956 -102.598728)
		(width 0.12954)
		(layer "F.Cu")
		(net "OCP_SFF_PRSNT3_R_N")
	)
	(segment
		(start 444.11011 -37.480748)
		(end 444.11011 -38.388036)
		(width 0.12954)
		(layer "F.Cu")
		(net "OCP_SFF_PRSNT3_R_N")
	)
	(via
		(at 455.296778 -102.598728)
		(size 0.508)
		(drill 0.254)
		(layers "F.Cu" "B.Cu")
		(net "OCP_SFF_PRSNT3_R_N")
	)
	(via
		(at 390.22274 -12.062968)
		(size 0.508)
		(drill 0.254)
		(layers "F.Cu" "B.Cu")
		(net "OCP_SFF_PRSNT3_R_N")
	)
	(via
		(at 444.11011 -37.480748)
		(size 0.508)
		(drill 0.254)
		(layers "F.Cu" "B.Cu")
		(net "OCP_SFF_PRSNT3_R_N")
	)
	(segment
		(start 456.35291 -88.959436)
		(end 456.35291 -101.542596)
		(width 0.127)
		(layer "In2.Cu")
		(net "OCP_SFF_PRSNT3_R_N")
	)
	(segment
		(start 456.35291 -101.542596)
		(end 455.296778 -102.598728)
		(width 0.127)
		(layer "In2.Cu")
		(net "OCP_SFF_PRSNT3_R_N")
	)
	(segment
		(start 444.11011 -37.480748)
		(end 444.11011 -37.59708)
		(width 0.127)
		(layer "In2.Cu")
		(net "OCP_SFF_PRSNT3_R_N")
	)
	(segment
		(start 438.977532 -82.859118)
		(end 450.252592 -82.859118)
		(width 0.127)
		(layer "In2.Cu")
		(net "OCP_SFF_PRSNT3_R_N")
	)
	(segment
		(start 440.35091 -41.35628)
		(end 440.35091 -45.339)
		(width 0.127)
		(layer "In2.Cu")
		(net "OCP_SFF_PRSNT3_R_N")
	)
	(segment
		(start 439.73877 -45.95114)
		(end 439.73877 -60.072016)
		(width 0.127)
		(layer "In2.Cu")
		(net "OCP_SFF_PRSNT3_R_N")
	)
	(segment
		(start 444.11011 -37.59708)
		(end 440.35091 -41.35628)
		(width 0.127)
		(layer "In2.Cu")
		(net "OCP_SFF_PRSNT3_R_N")
	)
	(segment
		(start 439.73877 -60.072016)
		(end 436.03799 -63.772796)
		(width 0.127)
		(layer "In2.Cu")
		(net "OCP_SFF_PRSNT3_R_N")
	)
	(segment
		(start 436.03799 -63.772796)
		(end 436.03799 -79.919576)
		(width 0.127)
		(layer "In2.Cu")
		(net "OCP_SFF_PRSNT3_R_N")
	)
	(segment
		(start 436.03799 -79.919576)
		(end 438.977532 -82.859118)
		(width 0.127)
		(layer "In2.Cu")
		(net "OCP_SFF_PRSNT3_R_N")
	)
	(segment
		(start 440.35091 -45.339)
		(end 439.73877 -45.95114)
		(width 0.127)
		(layer "In2.Cu")
		(net "OCP_SFF_PRSNT3_R_N")
	)
	(segment
		(start 450.252592 -82.859118)
		(end 456.35291 -88.959436)
		(width 0.127)
		(layer "In2.Cu")
		(net "OCP_SFF_PRSNT3_R_N")
	)
	(segment
		(start 441.53328 -37.480748)
		(end 444.11011 -37.480748)
		(width 0.127)
		(layer "In6.Cu")
		(net "OCP_SFF_PRSNT3_R_N")
	)
	(segment
		(start 435.5973 -14.790928)
		(end 435.5973 -17.569688)
		(width 0.127)
		(layer "In6.Cu")
		(net "OCP_SFF_PRSNT3_R_N")
	)
	(segment
		(start 436.14848 -35.220148)
		(end 439.27268 -35.220148)
		(width 0.127)
		(layer "In6.Cu")
		(net "OCP_SFF_PRSNT3_R_N")
	)
	(segment
		(start 439.27268 -35.220148)
		(end 441.53328 -37.480748)
		(width 0.127)
		(layer "In6.Cu")
		(net "OCP_SFF_PRSNT3_R_N")
	)
	(segment
		(start 435.854348 -17.826736)
		(end 435.854348 -21.30806)
		(width 0.127)
		(layer "In6.Cu")
		(net "OCP_SFF_PRSNT3_R_N")
	)
	(segment
		(start 395.27988 -2.454148)
		(end 406.60828 -2.454148)
		(width 0.127)
		(layer "In6.Cu")
		(net "OCP_SFF_PRSNT3_R_N")
	)
	(segment
		(start 390.22274 -12.062968)
		(end 390.22274 -7.511288)
		(width 0.127)
		(layer "In6.Cu")
		(net "OCP_SFF_PRSNT3_R_N")
	)
	(segment
		(start 406.60828 -2.454148)
		(end 408.71648 -4.562348)
		(width 0.127)
		(layer "In6.Cu")
		(net "OCP_SFF_PRSNT3_R_N")
	)
	(segment
		(start 390.22274 -7.511288)
		(end 395.27988 -2.454148)
		(width 0.127)
		(layer "In6.Cu")
		(net "OCP_SFF_PRSNT3_R_N")
	)
	(segment
		(start 433.27828 -23.884128)
		(end 433.27828 -32.349948)
		(width 0.127)
		(layer "In6.Cu")
		(net "OCP_SFF_PRSNT3_R_N")
	)
	(segment
		(start 435.854348 -21.30806)
		(end 433.27828 -23.884128)
		(width 0.127)
		(layer "In6.Cu")
		(net "OCP_SFF_PRSNT3_R_N")
	)
	(segment
		(start 435.5973 -17.569688)
		(end 435.854348 -17.826736)
		(width 0.127)
		(layer "In6.Cu")
		(net "OCP_SFF_PRSNT3_R_N")
	)
	(segment
		(start 438.15508 -1.717548)
		(end 441.78728 -5.349748)
		(width 0.127)
		(layer "In6.Cu")
		(net "OCP_SFF_PRSNT3_R_N")
	)
	(segment
		(start 409.98648 -4.562348)
		(end 412.83128 -1.717548)
		(width 0.127)
		(layer "In6.Cu")
		(net "OCP_SFF_PRSNT3_R_N")
	)
	(segment
		(start 433.27828 -32.349948)
		(end 436.14848 -35.220148)
		(width 0.127)
		(layer "In6.Cu")
		(net "OCP_SFF_PRSNT3_R_N")
	)
	(segment
		(start 412.83128 -1.717548)
		(end 438.15508 -1.717548)
		(width 0.127)
		(layer "In6.Cu")
		(net "OCP_SFF_PRSNT3_R_N")
	)
	(segment
		(start 441.78728 -8.600948)
		(end 435.5973 -14.790928)
		(width 0.127)
		(layer "In6.Cu")
		(net "OCP_SFF_PRSNT3_R_N")
	)
	(segment
		(start 408.71648 -4.562348)
		(end 409.98648 -4.562348)
		(width 0.127)
		(layer "In6.Cu")
		(net "OCP_SFF_PRSNT3_R_N")
	)
	(segment
		(start 441.78728 -5.349748)
		(end 441.78728 -8.600948)
		(width 0.127)
		(layer "In6.Cu")
		(net "OCP_SFF_PRSNT3_R_N")
	)
	(segment
		(start 433.766976 -7.206742)
		(end 433.600606 -7.040372)
		(width 0.12954)
		(layer "F.Cu")
		(net "OCP_SFF_PRSNT2_R_N")
	)
	(segment
		(start 444.80988 -37.480748)
		(end 444.80988 -38.097968)
		(width 0.12954)
		(layer "F.Cu")
		(net "OCP_SFF_PRSNT2_R_N")
	)
	(segment
		(start 433.766976 -8.320024)
		(end 433.766976 -7.206742)
		(width 0.12954)
		(layer "F.Cu")
		(net "OCP_SFF_PRSNT2_R_N")
	)
	(segment
		(start 455.2823 -104.29621)
		(end 454.166478 -104.29621)
		(width 0.12954)
		(layer "F.Cu")
		(net "OCP_SFF_PRSNT2_R_N")
	)
	(segment
		(start 433.600606 -7.040372)
		(end 433.600606 -4.011422)
		(width 0.12954)
		(layer "F.Cu")
		(net "OCP_SFF_PRSNT2_R_N")
	)
	(segment
		(start 444.80988 -38.097968)
		(end 445.19977 -38.487858)
		(width 0.12954)
		(layer "F.Cu")
		(net "OCP_SFF_PRSNT2_R_N")
	)
	(segment
		(start 454.166478 -104.29621)
		(end 454.119996 -104.249728)
		(width 0.12954)
		(layer "F.Cu")
		(net "OCP_SFF_PRSNT2_R_N")
	)
	(segment
		(start 456.737466 -104.29621)
		(end 455.2823 -104.29621)
		(width 0.12954)
		(layer "F.Cu")
		(net "OCP_SFF_PRSNT2_R_N")
	)
	(segment
		(start 445.19977 -38.487858)
		(end 446.633092 -38.487858)
		(width 0.12954)
		(layer "F.Cu")
		(net "OCP_SFF_PRSNT2_R_N")
	)
	(segment
		(start 433.600606 -4.011422)
		(end 433.63388 -3.978148)
		(width 0.12954)
		(layer "F.Cu")
		(net "OCP_SFF_PRSNT2_R_N")
	)
	(via
		(at 444.80988 -37.480748)
		(size 0.508)
		(drill 0.254)
		(layers "F.Cu" "B.Cu")
		(net "OCP_SFF_PRSNT2_R_N")
	)
	(via
		(at 455.2823 -104.29621)
		(size 0.508)
		(drill 0.254)
		(layers "F.Cu" "B.Cu")
		(net "OCP_SFF_PRSNT2_R_N")
	)
	(via
		(at 433.63388 -3.978148)
		(size 0.508)
		(drill 0.254)
		(layers "F.Cu" "B.Cu")
		(net "OCP_SFF_PRSNT2_R_N")
	)
	(segment
		(start 436.38216 -79.776828)
		(end 439.12028 -82.514948)
		(width 0.127)
		(layer "In2.Cu")
		(net "OCP_SFF_PRSNT2_R_N")
	)
	(segment
		(start 456.692 -104.29621)
		(end 455.2823 -104.29621)
		(width 0.127)
		(layer "In2.Cu")
		(net "OCP_SFF_PRSNT2_R_N")
	)
	(segment
		(start 440.13628 -60.161424)
		(end 436.38216 -63.915544)
		(width 0.127)
		(layer "In2.Cu")
		(net "OCP_SFF_PRSNT2_R_N")
	)
	(segment
		(start 450.39534 -82.514948)
		(end 456.69708 -88.816688)
		(width 0.127)
		(layer "In2.Cu")
		(net "OCP_SFF_PRSNT2_R_N")
	)
	(segment
		(start 456.69708 -88.816688)
		(end 456.69708 -104.29113)
		(width 0.127)
		(layer "In2.Cu")
		(net "OCP_SFF_PRSNT2_R_N")
	)
	(segment
		(start 440.69508 -42.001948)
		(end 440.69508 -45.481748)
		(width 0.127)
		(layer "In2.Cu")
		(net "OCP_SFF_PRSNT2_R_N")
	)
	(segment
		(start 456.69708 -104.29113)
		(end 456.692 -104.29621)
		(width 0.127)
		(layer "In2.Cu")
		(net "OCP_SFF_PRSNT2_R_N")
	)
	(segment
		(start 436.38216 -63.915544)
		(end 436.38216 -79.776828)
		(width 0.127)
		(layer "In2.Cu")
		(net "OCP_SFF_PRSNT2_R_N")
	)
	(segment
		(start 440.13628 -46.040548)
		(end 440.13628 -60.161424)
		(width 0.127)
		(layer "In2.Cu")
		(net "OCP_SFF_PRSNT2_R_N")
	)
	(segment
		(start 439.12028 -82.514948)
		(end 450.39534 -82.514948)
		(width 0.127)
		(layer "In2.Cu")
		(net "OCP_SFF_PRSNT2_R_N")
	)
	(segment
		(start 444.80988 -37.480748)
		(end 444.80988 -37.887148)
		(width 0.127)
		(layer "In2.Cu")
		(net "OCP_SFF_PRSNT2_R_N")
	)
	(segment
		(start 440.69508 -45.481748)
		(end 440.13628 -46.040548)
		(width 0.127)
		(layer "In2.Cu")
		(net "OCP_SFF_PRSNT2_R_N")
	)
	(segment
		(start 444.80988 -37.887148)
		(end 440.69508 -42.001948)
		(width 0.127)
		(layer "In2.Cu")
		(net "OCP_SFF_PRSNT2_R_N")
	)
	(segment
		(start 438.967372 -35.956748)
		(end 440.97448 -37.963856)
		(width 0.127)
		(layer "In6.Cu")
		(net "OCP_SFF_PRSNT2_R_N")
	)
	(segment
		(start 443.10808 -39.182548)
		(end 444.80988 -37.480748)
		(width 0.127)
		(layer "In6.Cu")
		(net "OCP_SFF_PRSNT2_R_N")
	)
	(segment
		(start 435.08168 -2.454148)
		(end 437.849772 -2.454148)
		(width 0.127)
		(layer "In6.Cu")
		(net "OCP_SFF_PRSNT2_R_N")
	)
	(segment
		(start 435.193948 -18.126456)
		(end 435.193948 -20.926552)
		(width 0.127)
		(layer "In6.Cu")
		(net "OCP_SFF_PRSNT2_R_N")
	)
	(segment
		(start 440.97448 -38.801548)
		(end 441.35548 -39.182548)
		(width 0.127)
		(layer "In6.Cu")
		(net "OCP_SFF_PRSNT2_R_N")
	)
	(segment
		(start 433.63388 -3.901948)
		(end 435.08168 -2.454148)
		(width 0.127)
		(layer "In6.Cu")
		(net "OCP_SFF_PRSNT2_R_N")
	)
	(segment
		(start 435.193948 -20.926552)
		(end 432.54168 -23.57882)
		(width 0.127)
		(layer "In6.Cu")
		(net "OCP_SFF_PRSNT2_R_N")
	)
	(segment
		(start 432.54168 -23.57882)
		(end 432.54168 -32.655256)
		(width 0.127)
		(layer "In6.Cu")
		(net "OCP_SFF_PRSNT2_R_N")
	)
	(segment
		(start 435.843172 -35.956748)
		(end 438.967372 -35.956748)
		(width 0.127)
		(layer "In6.Cu")
		(net "OCP_SFF_PRSNT2_R_N")
	)
	(segment
		(start 437.849772 -2.454148)
		(end 441.05068 -5.655056)
		(width 0.127)
		(layer "In6.Cu")
		(net "OCP_SFF_PRSNT2_R_N")
	)
	(segment
		(start 441.05068 -8.29564)
		(end 434.9369 -14.40942)
		(width 0.127)
		(layer "In6.Cu")
		(net "OCP_SFF_PRSNT2_R_N")
	)
	(segment
		(start 434.9369 -14.40942)
		(end 434.9369 -17.869408)
		(width 0.127)
		(layer "In6.Cu")
		(net "OCP_SFF_PRSNT2_R_N")
	)
	(segment
		(start 441.35548 -39.182548)
		(end 443.10808 -39.182548)
		(width 0.127)
		(layer "In6.Cu")
		(net "OCP_SFF_PRSNT2_R_N")
	)
	(segment
		(start 433.63388 -3.978148)
		(end 433.63388 -3.901948)
		(width 0.127)
		(layer "In6.Cu")
		(net "OCP_SFF_PRSNT2_R_N")
	)
	(segment
		(start 434.9369 -17.869408)
		(end 435.193948 -18.126456)
		(width 0.127)
		(layer "In6.Cu")
		(net "OCP_SFF_PRSNT2_R_N")
	)
	(segment
		(start 432.54168 -32.655256)
		(end 435.843172 -35.956748)
		(width 0.127)
		(layer "In6.Cu")
		(net "OCP_SFF_PRSNT2_R_N")
	)
	(segment
		(start 441.05068 -5.655056)
		(end 441.05068 -8.29564)
		(width 0.127)
		(layer "In6.Cu")
		(net "OCP_SFF_PRSNT2_R_N")
	)
	(segment
		(start 440.97448 -37.963856)
		(end 440.97448 -38.801548)
		(width 0.127)
		(layer "In6.Cu")
		(net "OCP_SFF_PRSNT2_R_N")
	)
	(segment
		(start 412.356808 -8.320024)
		(end 412.356808 -6.983476)
		(width 0.12954)
		(layer "F.Cu")
		(net "OCP_SFF_PRSNT1_R_N")
	)
	(segment
		(start 441.58408 -38.445948)
		(end 441.58408 -39.400988)
		(width 0.12954)
		(layer "F.Cu")
		(net "OCP_SFF_PRSNT1_R_N")
	)
	(segment
		(start 455.25309 -106.36885)
		(end 454.159874 -106.36885)
		(width 0.12954)
		(layer "F.Cu")
		(net "OCP_SFF_PRSNT1_R_N")
	)
	(segment
		(start 456.734672 -106.36885)
		(end 455.25309 -106.36885)
		(width 0.12954)
		(layer "F.Cu")
		(net "OCP_SFF_PRSNT1_R_N")
	)
	(segment
		(start 412.356808 -6.983476)
		(end 411.96768 -6.594348)
		(width 0.12954)
		(layer "F.Cu")
		(net "OCP_SFF_PRSNT1_R_N")
	)
	(segment
		(start 442.02096 -39.837868)
		(end 443.083188 -39.837868)
		(width 0.12954)
		(layer "F.Cu")
		(net "OCP_SFF_PRSNT1_R_N")
	)
	(segment
		(start 441.58408 -39.400988)
		(end 442.02096 -39.837868)
		(width 0.12954)
		(layer "F.Cu")
		(net "OCP_SFF_PRSNT1_R_N")
	)
	(segment
		(start 454.159874 -106.36885)
		(end 454.119996 -106.408728)
		(width 0.12954)
		(layer "F.Cu")
		(net "OCP_SFF_PRSNT1_R_N")
	)
	(via
		(at 441.58408 -38.445948)
		(size 0.508)
		(drill 0.254)
		(layers "F.Cu" "B.Cu")
		(net "OCP_SFF_PRSNT1_R_N")
	)
	(via
		(at 455.25309 -106.36885)
		(size 0.508)
		(drill 0.254)
		(layers "F.Cu" "B.Cu")
		(net "OCP_SFF_PRSNT1_R_N")
	)
	(via
		(at 411.96768 -6.594348)
		(size 0.508)
		(drill 0.254)
		(layers "F.Cu" "B.Cu")
		(net "OCP_SFF_PRSNT1_R_N")
	)
	(segment
		(start 454.38568 -105.651554)
		(end 455.102976 -106.36885)
		(width 0.127)
		(layer "In2.Cu")
		(net "OCP_SFF_PRSNT1_R_N")
	)
	(segment
		(start 455.98588 -100.708968)
		(end 454.38568 -102.309168)
		(width 0.127)
		(layer "In2.Cu")
		(net "OCP_SFF_PRSNT1_R_N")
	)
	(segment
		(start 439.98388 -45.186854)
		(end 439.389774 -45.78096)
		(width 0.127)
		(layer "In2.Cu")
		(net "OCP_SFF_PRSNT1_R_N")
	)
	(segment
		(start 439.98388 -40.096948)
		(end 439.98388 -45.186854)
		(width 0.127)
		(layer "In2.Cu")
		(net "OCP_SFF_PRSNT1_R_N")
	)
	(segment
		(start 441.58408 -38.496748)
		(end 439.98388 -40.096948)
		(width 0.127)
		(layer "In2.Cu")
		(net "OCP_SFF_PRSNT1_R_N")
	)
	(segment
		(start 454.38568 -102.309168)
		(end 454.38568 -105.651554)
		(width 0.127)
		(layer "In2.Cu")
		(net "OCP_SFF_PRSNT1_R_N")
	)
	(segment
		(start 435.67096 -80.071722)
		(end 438.825386 -83.226148)
		(width 0.127)
		(layer "In2.Cu")
		(net "OCP_SFF_PRSNT1_R_N")
	)
	(segment
		(start 441.58408 -38.445948)
		(end 441.58408 -38.496748)
		(width 0.127)
		(layer "In2.Cu")
		(net "OCP_SFF_PRSNT1_R_N")
	)
	(segment
		(start 455.98588 -89.111582)
		(end 455.98588 -100.708968)
		(width 0.127)
		(layer "In2.Cu")
		(net "OCP_SFF_PRSNT1_R_N")
	)
	(segment
		(start 438.825386 -83.226148)
		(end 450.100446 -83.226148)
		(width 0.127)
		(layer "In2.Cu")
		(net "OCP_SFF_PRSNT1_R_N")
	)
	(segment
		(start 439.389774 -45.78096)
		(end 439.389774 -59.901836)
		(width 0.127)
		(layer "In2.Cu")
		(net "OCP_SFF_PRSNT1_R_N")
	)
	(segment
		(start 435.67096 -63.62065)
		(end 435.67096 -80.071722)
		(width 0.127)
		(layer "In2.Cu")
		(net "OCP_SFF_PRSNT1_R_N")
	)
	(segment
		(start 455.102976 -106.36885)
		(end 455.25309 -106.36885)
		(width 0.127)
		(layer "In2.Cu")
		(net "OCP_SFF_PRSNT1_R_N")
	)
	(segment
		(start 439.389774 -59.901836)
		(end 435.67096 -63.62065)
		(width 0.127)
		(layer "In2.Cu")
		(net "OCP_SFF_PRSNT1_R_N")
	)
	(segment
		(start 450.100446 -83.226148)
		(end 455.98588 -89.111582)
		(width 0.127)
		(layer "In2.Cu")
		(net "OCP_SFF_PRSNT1_R_N")
	)
	(segment
		(start 441.58408 -38.070536)
		(end 441.58408 -38.445948)
		(width 0.127)
		(layer "In6.Cu")
		(net "OCP_SFF_PRSNT1_R_N")
	)
	(segment
		(start 411.96768 -3.597148)
		(end 413.51708 -2.047748)
		(width 0.127)
		(layer "In6.Cu")
		(net "OCP_SFF_PRSNT1_R_N")
	)
	(segment
		(start 439.114692 -35.601148)
		(end 441.58408 -38.070536)
		(width 0.127)
		(layer "In6.Cu")
		(net "OCP_SFF_PRSNT1_R_N")
	)
	(segment
		(start 437.997092 -2.098548)
		(end 441.40628 -5.507736)
		(width 0.127)
		(layer "In6.Cu")
		(net "OCP_SFF_PRSNT1_R_N")
	)
	(segment
		(start 421.36568 -4.486148)
		(end 423.37228 -4.486148)
		(width 0.127)
		(layer "In6.Cu")
		(net "OCP_SFF_PRSNT1_R_N")
	)
	(segment
		(start 435.2671 -17.714468)
		(end 435.524148 -17.971516)
		(width 0.127)
		(layer "In6.Cu")
		(net "OCP_SFF_PRSNT1_R_N")
	)
	(segment
		(start 425.75988 -2.098548)
		(end 437.997092 -2.098548)
		(width 0.127)
		(layer "In6.Cu")
		(net "OCP_SFF_PRSNT1_R_N")
	)
	(segment
		(start 413.51708 -2.047748)
		(end 418.92728 -2.047748)
		(width 0.127)
		(layer "In6.Cu")
		(net "OCP_SFF_PRSNT1_R_N")
	)
	(segment
		(start 411.96768 -6.594348)
		(end 411.96768 -3.597148)
		(width 0.127)
		(layer "In6.Cu")
		(net "OCP_SFF_PRSNT1_R_N")
	)
	(segment
		(start 432.89728 -23.72614)
		(end 432.89728 -32.507936)
		(width 0.127)
		(layer "In6.Cu")
		(net "OCP_SFF_PRSNT1_R_N")
	)
	(segment
		(start 432.89728 -32.507936)
		(end 435.990492 -35.601148)
		(width 0.127)
		(layer "In6.Cu")
		(net "OCP_SFF_PRSNT1_R_N")
	)
	(segment
		(start 435.524148 -17.971516)
		(end 435.524148 -21.099272)
		(width 0.127)
		(layer "In6.Cu")
		(net "OCP_SFF_PRSNT1_R_N")
	)
	(segment
		(start 435.990492 -35.601148)
		(end 439.114692 -35.601148)
		(width 0.127)
		(layer "In6.Cu")
		(net "OCP_SFF_PRSNT1_R_N")
	)
	(segment
		(start 423.37228 -4.486148)
		(end 425.75988 -2.098548)
		(width 0.127)
		(layer "In6.Cu")
		(net "OCP_SFF_PRSNT1_R_N")
	)
	(segment
		(start 441.40628 -8.44296)
		(end 435.2671 -14.58214)
		(width 0.127)
		(layer "In6.Cu")
		(net "OCP_SFF_PRSNT1_R_N")
	)
	(segment
		(start 435.524148 -21.099272)
		(end 432.89728 -23.72614)
		(width 0.127)
		(layer "In6.Cu")
		(net "OCP_SFF_PRSNT1_R_N")
	)
	(segment
		(start 441.40628 -5.507736)
		(end 441.40628 -8.44296)
		(width 0.127)
		(layer "In6.Cu")
		(net "OCP_SFF_PRSNT1_R_N")
	)
	(segment
		(start 418.92728 -2.047748)
		(end 421.36568 -4.486148)
		(width 0.127)
		(layer "In6.Cu")
		(net "OCP_SFF_PRSNT1_R_N")
	)
	(segment
		(start 435.2671 -14.58214)
		(end 435.2671 -17.714468)
		(width 0.127)
		(layer "In6.Cu")
		(net "OCP_SFF_PRSNT1_R_N")
	)
	(segment
		(start 439.61431 -38.445948)
		(end 439.61431 -38.837616)
		(width 0.12954)
		(layer "F.Cu")
		(net "OCP_SFF_PRSNT0_R_N")
	)
	(segment
		(start 439.61431 -38.837616)
		(end 441.314332 -40.537638)
		(width 0.12954)
		(layer "F.Cu")
		(net "OCP_SFF_PRSNT0_R_N")
	)
	(segment
		(start 412.356808 -12.35202)
		(end 412.04388 -12.664948)
		(width 0.12954)
		(layer "F.Cu")
		(net "OCP_SFF_PRSNT0_R_N")
	)
	(segment
		(start 456.343766 -108.059728)
		(end 456.734672 -107.668822)
		(width 0.12954)
		(layer "F.Cu")
		(net "OCP_SFF_PRSNT0_R_N")
	)
	(segment
		(start 441.314332 -40.537638)
		(end 443.083188 -40.537638)
		(width 0.12954)
		(layer "F.Cu")
		(net "OCP_SFF_PRSNT0_R_N")
	)
	(segment
		(start 412.356808 -11.26998)
		(end 412.356808 -12.35202)
		(width 0.12954)
		(layer "F.Cu")
		(net "OCP_SFF_PRSNT0_R_N")
	)
	(segment
		(start 455.22388 -108.059728)
		(end 456.343766 -108.059728)
		(width 0.12954)
		(layer "F.Cu")
		(net "OCP_SFF_PRSNT0_R_N")
	)
	(segment
		(start 454.119996 -108.059728)
		(end 455.22388 -108.059728)
		(width 0.12954)
		(layer "F.Cu")
		(net "OCP_SFF_PRSNT0_R_N")
	)
	(via
		(at 412.04388 -12.664948)
		(size 0.508)
		(drill 0.254)
		(layers "F.Cu" "B.Cu")
		(net "OCP_SFF_PRSNT0_R_N")
	)
	(via
		(at 439.61431 -38.445948)
		(size 0.508)
		(drill 0.254)
		(layers "F.Cu" "B.Cu")
		(net "OCP_SFF_PRSNT0_R_N")
	)
	(via
		(at 455.22388 -108.059728)
		(size 0.508)
		(drill 0.254)
		(layers "F.Cu" "B.Cu")
		(net "OCP_SFF_PRSNT0_R_N")
	)
	(segment
		(start 454.01611 -101.439218)
		(end 454.01611 -106.851958)
		(width 0.127)
		(layer "In2.Cu")
		(net "OCP_SFF_PRSNT0_R_N")
	)
	(segment
		(start 439.61431 -45.033692)
		(end 439.03392 -45.614082)
		(width 0.127)
		(layer "In2.Cu")
		(net "OCP_SFF_PRSNT0_R_N")
	)
	(segment
		(start 455.61631 -99.839018)
		(end 454.01611 -101.439218)
		(width 0.127)
		(layer "In2.Cu")
		(net "OCP_SFF_PRSNT0_R_N")
	)
	(segment
		(start 439.03392 -59.734958)
		(end 435.30139 -63.467488)
		(width 0.127)
		(layer "In2.Cu")
		(net "OCP_SFF_PRSNT0_R_N")
	)
	(segment
		(start 455.61631 -89.264744)
		(end 455.61631 -99.839018)
		(width 0.127)
		(layer "In2.Cu")
		(net "OCP_SFF_PRSNT0_R_N")
	)
	(segment
		(start 435.30139 -80.224884)
		(end 438.672224 -83.595718)
		(width 0.127)
		(layer "In2.Cu")
		(net "OCP_SFF_PRSNT0_R_N")
	)
	(segment
		(start 454.01611 -106.851958)
		(end 455.22388 -108.059728)
		(width 0.127)
		(layer "In2.Cu")
		(net "OCP_SFF_PRSNT0_R_N")
	)
	(segment
		(start 439.03392 -45.614082)
		(end 439.03392 -59.734958)
		(width 0.127)
		(layer "In2.Cu")
		(net "OCP_SFF_PRSNT0_R_N")
	)
	(segment
		(start 435.30139 -63.467488)
		(end 435.30139 -80.224884)
		(width 0.127)
		(layer "In2.Cu")
		(net "OCP_SFF_PRSNT0_R_N")
	)
	(segment
		(start 439.61431 -38.445948)
		(end 439.61431 -45.033692)
		(width 0.127)
		(layer "In2.Cu")
		(net "OCP_SFF_PRSNT0_R_N")
	)
	(segment
		(start 449.947284 -83.595718)
		(end 455.61631 -89.264744)
		(width 0.127)
		(layer "In2.Cu")
		(net "OCP_SFF_PRSNT0_R_N")
	)
	(segment
		(start 438.672224 -83.595718)
		(end 449.947284 -83.595718)
		(width 0.127)
		(layer "In2.Cu")
		(net "OCP_SFF_PRSNT0_R_N")
	)
	(segment
		(start 413.49168 -13.985748)
		(end 412.17088 -12.664948)
		(width 0.127)
		(layer "In6.Cu")
		(net "OCP_SFF_PRSNT0_R_N")
	)
	(segment
		(start 432.08448 -13.985748)
		(end 413.49168 -13.985748)
		(width 0.127)
		(layer "In6.Cu")
		(net "OCP_SFF_PRSNT0_R_N")
	)
	(segment
		(start 431.60188 -22.338284)
		(end 434.330348 -19.609816)
		(width 0.127)
		(layer "In6.Cu")
		(net "OCP_SFF_PRSNT0_R_N")
	)
	(segment
		(start 439.61431 -38.441122)
		(end 438.417208 -37.24402)
		(width 0.127)
		(layer "In6.Cu")
		(net "OCP_SFF_PRSNT0_R_N")
	)
	(segment
		(start 438.417208 -37.24402)
		(end 434.786786 -37.24402)
		(width 0.127)
		(layer "In6.Cu")
		(net "OCP_SFF_PRSNT0_R_N")
	)
	(segment
		(start 434.330348 -19.609816)
		(end 434.330348 -18.520156)
		(width 0.127)
		(layer "In6.Cu")
		(net "OCP_SFF_PRSNT0_R_N")
	)
	(segment
		(start 439.61431 -38.445948)
		(end 439.61431 -38.441122)
		(width 0.127)
		(layer "In6.Cu")
		(net "OCP_SFF_PRSNT0_R_N")
	)
	(segment
		(start 434.0733 -18.263108)
		(end 434.0733 -15.974568)
		(width 0.127)
		(layer "In6.Cu")
		(net "OCP_SFF_PRSNT0_R_N")
	)
	(segment
		(start 431.60188 -34.059114)
		(end 431.60188 -22.338284)
		(width 0.127)
		(layer "In6.Cu")
		(net "OCP_SFF_PRSNT0_R_N")
	)
	(segment
		(start 434.786786 -37.24402)
		(end 431.60188 -34.059114)
		(width 0.127)
		(layer "In6.Cu")
		(net "OCP_SFF_PRSNT0_R_N")
	)
	(segment
		(start 434.0733 -15.974568)
		(end 432.08448 -13.985748)
		(width 0.127)
		(layer "In6.Cu")
		(net "OCP_SFF_PRSNT0_R_N")
	)
	(segment
		(start 412.17088 -12.664948)
		(end 412.04388 -12.664948)
		(width 0.127)
		(layer "In6.Cu")
		(net "OCP_SFF_PRSNT0_R_N")
	)
	(segment
		(start 434.330348 -18.520156)
		(end 434.0733 -18.263108)
		(width 0.127)
		(layer "In6.Cu")
		(net "OCP_SFF_PRSNT0_R_N")
	)
	(segment
		(start 182.155592 -118.575328)
		(end 182.555642 -118.975378)
		(width 0.12954)
		(layer "F.Cu")
		(net "OCP_SFF_MAIN_PWR_EN")
	)
	(via
		(at 457.17968 -13.358876)
		(size 0.508)
		(drill 0.254)
		(layers "F.Cu" "B.Cu")
		(net "OCP_SFF_MAIN_PWR_EN")
	)
	(via
		(at 182.555642 -118.975378)
		(size 0.4572)
		(drill 0.254)
		(layers "F.Cu" "B.Cu")
		(net "OCP_SFF_MAIN_PWR_EN")
	)
	(via
		(at 182.193184 -133.453378)
		(size 0.508)
		(drill 0.254)
		(layers "F.Cu" "B.Cu")
		(net "OCP_SFF_MAIN_PWR_EN")
	)
	(via
		(at 443.66688 -118.074948)
		(size 0.508)
		(drill 0.254)
		(layers "F.Cu" "B.Cu")
		(net "OCP_SFF_MAIN_PWR_EN")
	)
	(segment
		(start 455.207624 -12.80541)
		(end 455.093324 -12.69111)
		(width 0.12954)
		(layer "B.Cu")
		(net "OCP_SFF_MAIN_PWR_EN")
	)
	(segment
		(start 454.077324 -13.49121)
		(end 454.86701 -12.701524)
		(width 0.12954)
		(layer "B.Cu")
		(net "OCP_SFF_MAIN_PWR_EN")
	)
	(segment
		(start 454.86701 -12.701524)
		(end 455.08291 -12.701524)
		(width 0.12954)
		(layer "B.Cu")
		(net "OCP_SFF_MAIN_PWR_EN")
	)
	(segment
		(start 455.08291 -12.701524)
		(end 455.093324 -12.69111)
		(width 0.12954)
		(layer "B.Cu")
		(net "OCP_SFF_MAIN_PWR_EN")
	)
	(segment
		(start 456.626214 -12.80541)
		(end 455.207624 -12.80541)
		(width 0.12954)
		(layer "B.Cu")
		(net "OCP_SFF_MAIN_PWR_EN")
	)
	(segment
		(start 457.17968 -13.358876)
		(end 456.626214 -12.80541)
		(width 0.12954)
		(layer "B.Cu")
		(net "OCP_SFF_MAIN_PWR_EN")
	)
	(segment
		(start 439.13298 -113.46688)
		(end 428.96536 -113.46688)
		(width 0.127)
		(layer "In2.Cu")
		(net "OCP_SFF_MAIN_PWR_EN")
	)
	(segment
		(start 432.10988 -109.413548)
		(end 432.82108 -108.702348)
		(width 0.127)
		(layer "In2.Cu")
		(net "OCP_SFF_MAIN_PWR_EN")
	)
	(segment
		(start 432.82108 -108.702348)
		(end 455.48296 -108.702348)
		(width 0.127)
		(layer "In2.Cu")
		(net "OCP_SFF_MAIN_PWR_EN")
	)
	(segment
		(start 469.11768 -77.789024)
		(end 469.11768 -54.449472)
		(width 0.127)
		(layer "In2.Cu")
		(net "OCP_SFF_MAIN_PWR_EN")
	)
	(segment
		(start 427.69028 -109.896148)
		(end 428.17288 -109.413548)
		(width 0.127)
		(layer "In2.Cu")
		(net "OCP_SFF_MAIN_PWR_EN")
	)
	(segment
		(start 459.950566 -35.984434)
		(end 458.85862 -34.892488)
		(width 0.127)
		(layer "In2.Cu")
		(net "OCP_SFF_MAIN_PWR_EN")
	)
	(segment
		(start 443.66688 -118.074948)
		(end 443.66688 -118.00078)
		(width 0.127)
		(layer "In2.Cu")
		(net "OCP_SFF_MAIN_PWR_EN")
	)
	(segment
		(start 464.712558 -50.04435)
		(end 464.712558 -45.6438)
		(width 0.127)
		(layer "In2.Cu")
		(net "OCP_SFF_MAIN_PWR_EN")
	)
	(segment
		(start 427.69028 -112.1918)
		(end 427.69028 -109.896148)
		(width 0.127)
		(layer "In2.Cu")
		(net "OCP_SFF_MAIN_PWR_EN")
	)
	(segment
		(start 469.11768 -54.449472)
		(end 464.712558 -50.04435)
		(width 0.127)
		(layer "In2.Cu")
		(net "OCP_SFF_MAIN_PWR_EN")
	)
	(segment
		(start 458.85862 -16.249904)
		(end 457.17968 -14.570964)
		(width 0.127)
		(layer "In2.Cu")
		(net "OCP_SFF_MAIN_PWR_EN")
	)
	(segment
		(start 465.35848 -93.562424)
		(end 465.35848 -81.548224)
		(width 0.127)
		(layer "In2.Cu")
		(net "OCP_SFF_MAIN_PWR_EN")
	)
	(segment
		(start 457.17968 -14.570964)
		(end 457.17968 -13.358876)
		(width 0.127)
		(layer "In2.Cu")
		(net "OCP_SFF_MAIN_PWR_EN")
	)
	(segment
		(start 464.712558 -45.6438)
		(end 459.950566 -40.881808)
		(width 0.127)
		(layer "In2.Cu")
		(net "OCP_SFF_MAIN_PWR_EN")
	)
	(segment
		(start 443.66688 -118.00078)
		(end 439.13298 -113.46688)
		(width 0.127)
		(layer "In2.Cu")
		(net "OCP_SFF_MAIN_PWR_EN")
	)
	(segment
		(start 428.17288 -109.413548)
		(end 432.10988 -109.413548)
		(width 0.127)
		(layer "In2.Cu")
		(net "OCP_SFF_MAIN_PWR_EN")
	)
	(segment
		(start 465.35848 -81.548224)
		(end 469.11768 -77.789024)
		(width 0.127)
		(layer "In2.Cu")
		(net "OCP_SFF_MAIN_PWR_EN")
	)
	(segment
		(start 463.30108 -100.884228)
		(end 463.30108 -95.619824)
		(width 0.127)
		(layer "In2.Cu")
		(net "OCP_SFF_MAIN_PWR_EN")
	)
	(segment
		(start 455.48296 -108.702348)
		(end 463.30108 -100.884228)
		(width 0.127)
		(layer "In2.Cu")
		(net "OCP_SFF_MAIN_PWR_EN")
	)
	(segment
		(start 459.950566 -40.881808)
		(end 459.950566 -35.984434)
		(width 0.127)
		(layer "In2.Cu")
		(net "OCP_SFF_MAIN_PWR_EN")
	)
	(segment
		(start 458.85862 -34.892488)
		(end 458.85862 -16.249904)
		(width 0.127)
		(layer "In2.Cu")
		(net "OCP_SFF_MAIN_PWR_EN")
	)
	(segment
		(start 463.30108 -95.619824)
		(end 465.35848 -93.562424)
		(width 0.127)
		(layer "In2.Cu")
		(net "OCP_SFF_MAIN_PWR_EN")
	)
	(segment
		(start 428.96536 -113.46688)
		(end 427.69028 -112.1918)
		(width 0.127)
		(layer "In2.Cu")
		(net "OCP_SFF_MAIN_PWR_EN")
	)
	(segment
		(start 183.7563 -120.388888)
		(end 183.7563 -126.130812)
		(width 0.127)
		(layer "In11.Cu")
		(net "OCP_SFF_MAIN_PWR_EN")
	)
	(segment
		(start 182.9562 -119.967248)
		(end 183.169814 -120.180862)
		(width 0.127)
		(layer "In11.Cu")
		(net "OCP_SFF_MAIN_PWR_EN")
	)
	(segment
		(start 183.169814 -120.180862)
		(end 183.548274 -120.180862)
		(width 0.127)
		(layer "In11.Cu")
		(net "OCP_SFF_MAIN_PWR_EN")
	)
	(segment
		(start 182.28945 -133.453378)
		(end 182.193184 -133.453378)
		(width 0.127)
		(layer "In11.Cu")
		(net "OCP_SFF_MAIN_PWR_EN")
	)
	(segment
		(start 183.7563 -126.130812)
		(end 182.64378 -127.243332)
		(width 0.127)
		(layer "In11.Cu")
		(net "OCP_SFF_MAIN_PWR_EN")
	)
	(segment
		(start 183.548274 -120.180862)
		(end 183.7563 -120.388888)
		(width 0.127)
		(layer "In11.Cu")
		(net "OCP_SFF_MAIN_PWR_EN")
	)
	(segment
		(start 182.64378 -133.099048)
		(end 182.28945 -133.453378)
		(width 0.127)
		(layer "In11.Cu")
		(net "OCP_SFF_MAIN_PWR_EN")
	)
	(segment
		(start 182.64378 -127.243332)
		(end 182.64378 -133.099048)
		(width 0.127)
		(layer "In11.Cu")
		(net "OCP_SFF_MAIN_PWR_EN")
	)
	(segment
		(start 182.555642 -118.975378)
		(end 182.9562 -119.375936)
		(width 0.127)
		(layer "In11.Cu")
		(net "OCP_SFF_MAIN_PWR_EN")
	)
	(segment
		(start 182.9562 -119.375936)
		(end 182.9562 -119.967248)
		(width 0.127)
		(layer "In11.Cu")
		(net "OCP_SFF_MAIN_PWR_EN")
	)
	(segment
		(start 202.045062 -132.001006)
		(end 198.501 -132.001006)
		(width 0.127)
		(layer "In13.Cu")
		(net "OCP_SFF_MAIN_PWR_EN")
	)
	(segment
		(start 182.564532 -133.9596)
		(end 182.193184 -133.588252)
		(width 0.127)
		(layer "In13.Cu")
		(net "OCP_SFF_MAIN_PWR_EN")
	)
	(segment
		(start 424.503088 -130.38074)
		(end 415.257488 -130.38074)
		(width 0.127)
		(layer "In13.Cu")
		(net "OCP_SFF_MAIN_PWR_EN")
	)
	(segment
		(start 352.095816 -141.628368)
		(end 347.125036 -146.599148)
		(width 0.127)
		(layer "In13.Cu")
		(net "OCP_SFF_MAIN_PWR_EN")
	)
	(segment
		(start 425.22648 -129.657348)
		(end 424.503088 -130.38074)
		(width 0.127)
		(layer "In13.Cu")
		(net "OCP_SFF_MAIN_PWR_EN")
	)
	(segment
		(start 347.125036 -146.599148)
		(end 243.519452 -146.599148)
		(width 0.127)
		(layer "In13.Cu")
		(net "OCP_SFF_MAIN_PWR_EN")
	)
	(segment
		(start 185.932064 -133.810248)
		(end 185.782712 -133.9596)
		(width 0.127)
		(layer "In13.Cu")
		(net "OCP_SFF_MAIN_PWR_EN")
	)
	(segment
		(start 415.257488 -130.38074)
		(end 404.00986 -141.628368)
		(width 0.127)
		(layer "In13.Cu")
		(net "OCP_SFF_MAIN_PWR_EN")
	)
	(segment
		(start 243.519452 -146.599148)
		(end 242.733576 -145.813272)
		(width 0.127)
		(layer "In13.Cu")
		(net "OCP_SFF_MAIN_PWR_EN")
	)
	(segment
		(start 242.733576 -145.813272)
		(end 215.857328 -145.813272)
		(width 0.127)
		(layer "In13.Cu")
		(net "OCP_SFF_MAIN_PWR_EN")
	)
	(segment
		(start 434.5686 -129.885948)
		(end 431.9016 -129.885948)
		(width 0.127)
		(layer "In13.Cu")
		(net "OCP_SFF_MAIN_PWR_EN")
	)
	(segment
		(start 443.89548 -125.639068)
		(end 442.7601 -126.774448)
		(width 0.127)
		(layer "In13.Cu")
		(net "OCP_SFF_MAIN_PWR_EN")
	)
	(segment
		(start 431.673 -129.657348)
		(end 425.22648 -129.657348)
		(width 0.127)
		(layer "In13.Cu")
		(net "OCP_SFF_MAIN_PWR_EN")
	)
	(segment
		(start 197.96125 -132.540756)
		(end 191.812672 -132.540756)
		(width 0.127)
		(layer "In13.Cu")
		(net "OCP_SFF_MAIN_PWR_EN")
	)
	(segment
		(start 191.812672 -132.540756)
		(end 190.54318 -133.810248)
		(width 0.127)
		(layer "In13.Cu")
		(net "OCP_SFF_MAIN_PWR_EN")
	)
	(segment
		(start 443.89548 -118.303548)
		(end 443.89548 -125.639068)
		(width 0.127)
		(layer "In13.Cu")
		(net "OCP_SFF_MAIN_PWR_EN")
	)
	(segment
		(start 437.6801 -126.774448)
		(end 434.5686 -129.885948)
		(width 0.127)
		(layer "In13.Cu")
		(net "OCP_SFF_MAIN_PWR_EN")
	)
	(segment
		(start 443.66688 -118.074948)
		(end 443.89548 -118.303548)
		(width 0.127)
		(layer "In13.Cu")
		(net "OCP_SFF_MAIN_PWR_EN")
	)
	(segment
		(start 431.9016 -129.885948)
		(end 431.673 -129.657348)
		(width 0.127)
		(layer "In13.Cu")
		(net "OCP_SFF_MAIN_PWR_EN")
	)
	(segment
		(start 198.501 -132.001006)
		(end 197.96125 -132.540756)
		(width 0.127)
		(layer "In13.Cu")
		(net "OCP_SFF_MAIN_PWR_EN")
	)
	(segment
		(start 185.782712 -133.9596)
		(end 182.564532 -133.9596)
		(width 0.127)
		(layer "In13.Cu")
		(net "OCP_SFF_MAIN_PWR_EN")
	)
	(segment
		(start 182.193184 -133.588252)
		(end 182.193184 -133.453378)
		(width 0.127)
		(layer "In13.Cu")
		(net "OCP_SFF_MAIN_PWR_EN")
	)
	(segment
		(start 190.54318 -133.810248)
		(end 185.932064 -133.810248)
		(width 0.127)
		(layer "In13.Cu")
		(net "OCP_SFF_MAIN_PWR_EN")
	)
	(segment
		(start 442.7601 -126.774448)
		(end 437.6801 -126.774448)
		(width 0.127)
		(layer "In13.Cu")
		(net "OCP_SFF_MAIN_PWR_EN")
	)
	(segment
		(start 404.00986 -141.628368)
		(end 352.095816 -141.628368)
		(width 0.127)
		(layer "In13.Cu")
		(net "OCP_SFF_MAIN_PWR_EN")
	)
	(segment
		(start 215.857328 -145.813272)
		(end 202.045062 -132.001006)
		(width 0.127)
		(layer "In13.Cu")
		(net "OCP_SFF_MAIN_PWR_EN")
	)
	(segment
		(start 437.10733 -16.648176)
		(end 437.10733 -17.287748)
		(width 0.12954)
		(layer "F.Cu")
		(net "OCP_SFF_ISO_BIF2_EN")
	)
	(via
		(at 437.10733 -17.287748)
		(size 0.508)
		(drill 0.254)
		(layers "F.Cu" "B.Cu")
		(net "OCP_SFF_ISO_BIF2_EN")
	)
	(segment
		(start 437.10733 -17.287748)
		(end 431.546 -22.849078)
		(width 0.12954)
		(layer "B.Cu")
		(net "OCP_SFF_ISO_BIF2_EN")
	)
	(segment
		(start 431.546 -22.849078)
		(end 431.546 -23.694898)
		(width 0.12954)
		(layer "B.Cu")
		(net "OCP_SFF_ISO_BIF2_EN")
	)
	(segment
		(start 435.03088 -28.412948)
		(end 435.03088 -22.647148)
		(width 0.12954)
		(layer "F.Cu")
		(net "OCP_SFF_ISO_BIF1_EN")
	)
	(segment
		(start 436.10911 -21.568918)
		(end 436.10911 -20.011136)
		(width 0.12954)
		(layer "F.Cu")
		(net "OCP_SFF_ISO_BIF1_EN")
	)
	(segment
		(start 435.03088 -22.647148)
		(end 436.10911 -21.568918)
		(width 0.12954)
		(layer "F.Cu")
		(net "OCP_SFF_ISO_BIF1_EN")
	)
	(via
		(at 435.03088 -28.412948)
		(size 0.508)
		(drill 0.254)
		(layers "F.Cu" "B.Cu")
		(net "OCP_SFF_ISO_BIF1_EN")
	)
	(segment
		(start 435.03088 -24.532082)
		(end 434.193696 -23.694898)
		(width 0.12954)
		(layer "B.Cu")
		(net "OCP_SFF_ISO_BIF1_EN")
	)
	(segment
		(start 435.03088 -28.412948)
		(end 435.03088 -24.532082)
		(width 0.12954)
		(layer "B.Cu")
		(net "OCP_SFF_ISO_BIF1_EN")
	)
	(segment
		(start 434.193696 -23.694898)
		(end 433.832 -23.694898)
		(width 0.12954)
		(layer "B.Cu")
		(net "OCP_SFF_ISO_BIF1_EN")
	)
	(segment
		(start 438.23128 -17.262348)
		(end 438.28208 -17.211548)
		(width 0.12954)
		(layer "F.Cu")
		(net "OCP_SFF_ISO_BIF0_EN")
	)
	(segment
		(start 438.28208 -17.211548)
		(end 438.28208 -16.620998)
		(width 0.12954)
		(layer "F.Cu")
		(net "OCP_SFF_ISO_BIF0_EN")
	)
	(via
		(at 438.23128 -17.262348)
		(size 0.508)
		(drill 0.254)
		(layers "F.Cu" "B.Cu")
		(net "OCP_SFF_ISO_BIF0_EN")
	)
	(via
		(at 434.086 -22.189948)
		(size 0.6604)
		(drill 0.3302)
		(layers "F.Cu" "B.Cu")
		(net "OCP_SFF_ISO_BIF0_EN")
	)
	(segment
		(start 438.23128 -17.262348)
		(end 436.67934 -18.814288)
		(width 0.12954)
		(layer "B.Cu")
		(net "OCP_SFF_ISO_BIF0_EN")
	)
	(segment
		(start 432.562 -23.079202)
		(end 432.562 -23.694898)
		(width 0.12954)
		(layer "B.Cu")
		(net "OCP_SFF_ISO_BIF0_EN")
	)
	(segment
		(start 433.451254 -22.189948)
		(end 432.562 -23.079202)
		(width 0.12954)
		(layer "B.Cu")
		(net "OCP_SFF_ISO_BIF0_EN")
	)
	(segment
		(start 436.67934 -19.596608)
		(end 434.086 -22.189948)
		(width 0.12954)
		(layer "B.Cu")
		(net "OCP_SFF_ISO_BIF0_EN")
	)
	(segment
		(start 434.086 -22.189948)
		(end 433.451254 -22.189948)
		(width 0.12954)
		(layer "B.Cu")
		(net "OCP_SFF_ISO_BIF0_EN")
	)
	(segment
		(start 436.67934 -18.814288)
		(end 436.67934 -19.596608)
		(width 0.12954)
		(layer "B.Cu")
		(net "OCP_SFF_ISO_BIF0_EN")
	)
	(segment
		(start 449.49364 -6.552946)
		(end 449.49364 -7.315708)
		(width 0.12954)
		(layer "F.Cu")
		(net "OCP_SFF_ID1")
	)
	(segment
		(start 449.078604 -6.13791)
		(end 449.49364 -6.552946)
		(width 0.12954)
		(layer "F.Cu")
		(net "OCP_SFF_ID1")
	)
	(segment
		(start 449.49364 -7.315708)
		(end 449.561966 -7.384034)
		(width 0.12954)
		(layer "F.Cu")
		(net "OCP_SFF_ID1")
	)
	(segment
		(start 449.561966 -7.384034)
		(end 449.561966 -8.320024)
		(width 0.12954)
		(layer "F.Cu")
		(net "OCP_SFF_ID1")
	)
	(via
		(at 449.078604 -6.13791)
		(size 0.508)
		(drill 0.254)
		(layers "F.Cu" "B.Cu")
		(net "OCP_SFF_ID1")
	)
	(segment
		(start 449.078604 -6.13791)
		(end 449.48856 -6.547866)
		(width 0.12954)
		(layer "B.Cu")
		(net "OCP_SFF_ID1")
	)
	(segment
		(start 449.48856 -7.906512)
		(end 449.526914 -7.944866)
		(width 0.12954)
		(layer "B.Cu")
		(net "OCP_SFF_ID1")
	)
	(segment
		(start 449.48856 -6.547866)
		(end 449.48856 -7.906512)
		(width 0.12954)
		(layer "B.Cu")
		(net "OCP_SFF_ID1")
	)
	(segment
		(start 450.542914 -7.944866)
		(end 449.526914 -7.944866)
		(width 0.12954)
		(layer "B.Cu")
		(net "OCP_SFF_ID1")
	)
	(segment
		(start 448.961764 -11.26998)
		(end 448.961764 -12.302744)
		(width 0.12954)
		(layer "F.Cu")
		(net "OCP_SFF_ID0")
	)
	(segment
		(start 448.961764 -12.302744)
		(end 448.86499 -12.399518)
		(width 0.12954)
		(layer "F.Cu")
		(net "OCP_SFF_ID0")
	)
	(via
		(at 448.86499 -12.399518)
		(size 0.508)
		(drill 0.254)
		(layers "F.Cu" "B.Cu")
		(net "OCP_SFF_ID0")
	)
	(segment
		(start 446.55105 -10.994136)
		(end 447.56705 -10.994136)
		(width 0.12954)
		(layer "B.Cu")
		(net "OCP_SFF_ID0")
	)
	(segment
		(start 447.56705 -11.101578)
		(end 447.56705 -10.994136)
		(width 0.12954)
		(layer "B.Cu")
		(net "OCP_SFF_ID0")
	)
	(segment
		(start 448.86499 -12.399518)
		(end 447.56705 -11.101578)
		(width 0.12954)
		(layer "B.Cu")
		(net "OCP_SFF_ID0")
	)
	(segment
		(start 435.56682 -11.26998)
		(end 435.56682 -12.616688)
		(width 0.12954)
		(layer "F.Cu")
		(net "OCP_SFF_BIF2_R_N")
	)
	(segment
		(start 437.10733 -15.714218)
		(end 437.10733 -15.848076)
		(width 0.12954)
		(layer "F.Cu")
		(net "OCP_SFF_BIF2_R_N")
	)
	(segment
		(start 435.92242 -14.529308)
		(end 437.10733 -15.714218)
		(width 0.12954)
		(layer "F.Cu")
		(net "OCP_SFF_BIF2_R_N")
	)
	(segment
		(start 435.92242 -12.972288)
		(end 435.92242 -14.529308)
		(width 0.12954)
		(layer "F.Cu")
		(net "OCP_SFF_BIF2_R_N")
	)
	(segment
		(start 435.56682 -12.616688)
		(end 435.92242 -12.972288)
		(width 0.12954)
		(layer "F.Cu")
		(net "OCP_SFF_BIF2_R_N")
	)
	(via
		(at 435.92242 -14.529308)
		(size 0.762)
		(drill 0.381)
		(layers "F.Cu" "B.Cu")
		(net "OCP_SFF_BIF2_R_N")
	)
	(segment
		(start 437.19496 -13.381228)
		(end 437.19496 -14.585188)
		(width 0.12954)
		(layer "F.Cu")
		(net "OCP_SFF_BIF1_R_N")
	)
	(segment
		(start 436.166768 -12.353036)
		(end 437.19496 -13.381228)
		(width 0.12954)
		(layer "F.Cu")
		(net "OCP_SFF_BIF1_R_N")
	)
	(segment
		(start 436.166768 -11.26998)
		(end 436.166768 -12.353036)
		(width 0.12954)
		(layer "F.Cu")
		(net "OCP_SFF_BIF1_R_N")
	)
	(segment
		(start 437.19496 -14.643608)
		(end 437.72328 -15.171928)
		(width 0.12954)
		(layer "F.Cu")
		(net "OCP_SFF_BIF1_R_N")
	)
	(segment
		(start 436.19928 -19.120866)
		(end 436.10911 -19.211036)
		(width 0.12954)
		(layer "F.Cu")
		(net "OCP_SFF_BIF1_R_N")
	)
	(segment
		(start 437.19496 -14.585188)
		(end 437.19496 -14.643608)
		(width 0.12954)
		(layer "F.Cu")
		(net "OCP_SFF_BIF1_R_N")
	)
	(segment
		(start 437.72328 -15.171928)
		(end 437.72328 -17.363948)
		(width 0.12954)
		(layer "F.Cu")
		(net "OCP_SFF_BIF1_R_N")
	)
	(segment
		(start 436.19928 -18.887948)
		(end 436.19928 -19.120866)
		(width 0.12954)
		(layer "F.Cu")
		(net "OCP_SFF_BIF1_R_N")
	)
	(segment
		(start 437.72328 -17.363948)
		(end 436.19928 -18.887948)
		(width 0.12954)
		(layer "F.Cu")
		(net "OCP_SFF_BIF1_R_N")
	)
	(via
		(at 437.19496 -14.585188)
		(size 0.762)
		(drill 0.381)
		(layers "F.Cu" "B.Cu")
		(net "OCP_SFF_BIF1_R_N")
	)
	(segment
		(start 436.76697 -11.26998)
		(end 436.76697 -12.292838)
		(width 0.12954)
		(layer "F.Cu")
		(net "OCP_SFF_BIF0_R_N")
	)
	(segment
		(start 438.28208 -14.811248)
		(end 438.28208 -15.820898)
		(width 0.12954)
		(layer "F.Cu")
		(net "OCP_SFF_BIF0_R_N")
	)
	(segment
		(start 438.5564 -14.536928)
		(end 438.28208 -14.811248)
		(width 0.12954)
		(layer "F.Cu")
		(net "OCP_SFF_BIF0_R_N")
	)
	(segment
		(start 436.76697 -12.292838)
		(end 438.5564 -14.082268)
		(width 0.12954)
		(layer "F.Cu")
		(net "OCP_SFF_BIF0_R_N")
	)
	(segment
		(start 438.5564 -14.082268)
		(end 438.5564 -14.536928)
		(width 0.12954)
		(layer "F.Cu")
		(net "OCP_SFF_BIF0_R_N")
	)
	(via
		(at 438.5564 -14.536928)
		(size 0.762)
		(drill 0.381)
		(layers "F.Cu" "B.Cu")
		(net "OCP_SFF_BIF0_R_N")
	)
	(segment
		(start 457.20762 -99.164394)
		(end 456.300586 -99.164394)
		(width 0.12954)
		(layer "F.Cu")
		(net "OCP_SFF_AUX_PWR_EN_R1")
	)
	(segment
		(start 456.2602 -99.124008)
		(end 455.839576 -99.124008)
		(width 0.12954)
		(layer "F.Cu")
		(net "OCP_SFF_AUX_PWR_EN_R1")
	)
	(segment
		(start 458.629766 -99.164394)
		(end 457.20762 -99.164394)
		(width 0.12954)
		(layer "F.Cu")
		(net "OCP_SFF_AUX_PWR_EN_R1")
	)
	(segment
		(start 456.300586 -99.164394)
		(end 456.2602 -99.124008)
		(width 0.12954)
		(layer "F.Cu")
		(net "OCP_SFF_AUX_PWR_EN_R1")
	)
	(via
		(at 457.20762 -99.164394)
		(size 0.762)
		(drill 0.381)
		(layers "F.Cu" "B.Cu")
		(net "OCP_SFF_AUX_PWR_EN_R1")
	)
	(segment
		(start 433.508404 -14.491208)
		(end 434.805328 -15.788132)
		(width 0.12954)
		(layer "F.Cu")
		(net "OCP_SFF_AUX_PWR_EN_R")
	)
	(segment
		(start 433.3494 -13.581888)
		(end 433.3494 -14.491208)
		(width 0.12954)
		(layer "F.Cu")
		(net "OCP_SFF_AUX_PWR_EN_R")
	)
	(segment
		(start 433.766976 -13.164312)
		(end 433.3494 -13.581888)
		(width 0.12954)
		(layer "F.Cu")
		(net "OCP_SFF_AUX_PWR_EN_R")
	)
	(segment
		(start 433.3494 -14.491208)
		(end 433.508404 -14.491208)
		(width 0.12954)
		(layer "F.Cu")
		(net "OCP_SFF_AUX_PWR_EN_R")
	)
	(segment
		(start 433.766976 -11.26998)
		(end 433.766976 -13.164312)
		(width 0.12954)
		(layer "F.Cu")
		(net "OCP_SFF_AUX_PWR_EN_R")
	)
	(via
		(at 433.3494 -14.491208)
		(size 0.762)
		(drill 0.381)
		(layers "F.Cu" "B.Cu")
		(net "OCP_SFF_AUX_PWR_EN_R")
	)
	(segment
		(start 455.217784 -93.437964)
		(end 455.217784 -98.001836)
		(width 0.12954)
		(layer "F.Cu")
		(net "OCP_SFF_AUX_PWR_EN")
	)
	(segment
		(start 434.54828 -29.505148)
		(end 434.54828 -22.545548)
		(width 0.12954)
		(layer "F.Cu")
		(net "OCP_SFF_AUX_PWR_EN")
	)
	(segment
		(start 434.98008 -29.936948)
		(end 434.54828 -29.505148)
		(width 0.12954)
		(layer "F.Cu")
		(net "OCP_SFF_AUX_PWR_EN")
	)
	(segment
		(start 440.50966 -106.78541)
		(end 440.50966 -107.65028)
		(width 0.12954)
		(layer "F.Cu")
		(net "OCP_SFF_AUX_PWR_EN")
	)
	(segment
		(start 434.805328 -16.588232)
		(end 434.805328 -19.214084)
		(width 0.12954)
		(layer "F.Cu")
		(net "OCP_SFF_AUX_PWR_EN")
	)
	(segment
		(start 435.230016 -19.214084)
		(end 434.805328 -19.214084)
		(width 0.12954)
		(layer "F.Cu")
		(net "OCP_SFF_AUX_PWR_EN")
	)
	(segment
		(start 435.43728 -19.421348)
		(end 435.230016 -19.214084)
		(width 0.12954)
		(layer "F.Cu")
		(net "OCP_SFF_AUX_PWR_EN")
	)
	(segment
		(start 435.43728 -21.656548)
		(end 435.43728 -19.421348)
		(width 0.12954)
		(layer "F.Cu")
		(net "OCP_SFF_AUX_PWR_EN")
	)
	(segment
		(start 455.039476 -99.124008)
		(end 455.039476 -98.180144)
		(width 0.12954)
		(layer "F.Cu")
		(net "OCP_SFF_AUX_PWR_EN")
	)
	(segment
		(start 455.217784 -98.001836)
		(end 455.039476 -98.180144)
		(width 0.12954)
		(layer "F.Cu")
		(net "OCP_SFF_AUX_PWR_EN")
	)
	(segment
		(start 434.54828 -22.545548)
		(end 435.43728 -21.656548)
		(width 0.12954)
		(layer "F.Cu")
		(net "OCP_SFF_AUX_PWR_EN")
	)
	(via
		(at 455.039476 -98.180144)
		(size 0.508)
		(drill 0.254)
		(layers "F.Cu" "B.Cu")
		(net "OCP_SFF_AUX_PWR_EN")
	)
	(via
		(at 434.98008 -29.936948)
		(size 0.508)
		(drill 0.254)
		(layers "F.Cu" "B.Cu")
		(net "OCP_SFF_AUX_PWR_EN")
	)
	(via
		(at 309.59298 -106.192828)
		(size 0.508)
		(drill 0.254)
		(layers "F.Cu" "B.Cu")
		(net "OCP_SFF_AUX_PWR_EN")
	)
	(via
		(at 440.50966 -107.65028)
		(size 0.508)
		(drill 0.254)
		(layers "F.Cu" "B.Cu")
		(net "OCP_SFF_AUX_PWR_EN")
	)
	(segment
		(start 434.42128 -33.55848)
		(end 439.14441 -38.28161)
		(width 0.127)
		(layer "In2.Cu")
		(net "OCP_SFF_AUX_PWR_EN")
	)
	(segment
		(start 455.039476 -89.340944)
		(end 455.039476 -98.180144)
		(width 0.127)
		(layer "In2.Cu")
		(net "OCP_SFF_AUX_PWR_EN")
	)
	(segment
		(start 439.18251 -44.854622)
		(end 438.60212 -45.435012)
		(width 0.127)
		(layer "In2.Cu")
		(net "OCP_SFF_AUX_PWR_EN")
	)
	(segment
		(start 434.86959 -63.15329)
		(end 434.86959 -80.403954)
		(width 0.127)
		(layer "In2.Cu")
		(net "OCP_SFF_AUX_PWR_EN")
	)
	(segment
		(start 439.18251 -38.678866)
		(end 439.18251 -41.008808)
		(width 0.127)
		(layer "In2.Cu")
		(net "OCP_SFF_AUX_PWR_EN")
	)
	(segment
		(start 449.72605 -84.027518)
		(end 455.039476 -89.340944)
		(width 0.127)
		(layer "In2.Cu")
		(net "OCP_SFF_AUX_PWR_EN")
	)
	(segment
		(start 439.14441 -38.28161)
		(end 439.14441 -38.640766)
		(width 0.127)
		(layer "In2.Cu")
		(net "OCP_SFF_AUX_PWR_EN")
	)
	(segment
		(start 438.52338 -41.667938)
		(end 438.52338 -43.339766)
		(width 0.127)
		(layer "In2.Cu")
		(net "OCP_SFF_AUX_PWR_EN")
	)
	(segment
		(start 434.42128 -30.495748)
		(end 434.42128 -33.55848)
		(width 0.127)
		(layer "In2.Cu")
		(net "OCP_SFF_AUX_PWR_EN")
	)
	(segment
		(start 439.18251 -41.008808)
		(end 438.52338 -41.667938)
		(width 0.127)
		(layer "In2.Cu")
		(net "OCP_SFF_AUX_PWR_EN")
	)
	(segment
		(start 439.14441 -38.640766)
		(end 439.18251 -38.678866)
		(width 0.127)
		(layer "In2.Cu")
		(net "OCP_SFF_AUX_PWR_EN")
	)
	(segment
		(start 438.60212 -45.435012)
		(end 438.60212 -59.42076)
		(width 0.127)
		(layer "In2.Cu")
		(net "OCP_SFF_AUX_PWR_EN")
	)
	(segment
		(start 434.86959 -80.403954)
		(end 438.493154 -84.027518)
		(width 0.127)
		(layer "In2.Cu")
		(net "OCP_SFF_AUX_PWR_EN")
	)
	(segment
		(start 438.493154 -84.027518)
		(end 449.72605 -84.027518)
		(width 0.127)
		(layer "In2.Cu")
		(net "OCP_SFF_AUX_PWR_EN")
	)
	(segment
		(start 439.18251 -43.998896)
		(end 439.18251 -44.854622)
		(width 0.127)
		(layer "In2.Cu")
		(net "OCP_SFF_AUX_PWR_EN")
	)
	(segment
		(start 434.98008 -29.936948)
		(end 434.42128 -30.495748)
		(width 0.127)
		(layer "In2.Cu")
		(net "OCP_SFF_AUX_PWR_EN")
	)
	(segment
		(start 438.52338 -43.339766)
		(end 439.18251 -43.998896)
		(width 0.127)
		(layer "In2.Cu")
		(net "OCP_SFF_AUX_PWR_EN")
	)
	(segment
		(start 438.60212 -59.42076)
		(end 434.86959 -63.15329)
		(width 0.127)
		(layer "In2.Cu")
		(net "OCP_SFF_AUX_PWR_EN")
	)
	(segment
		(start 437.233822 -112.603788)
		(end 414.852358 -112.603788)
		(width 0.127)
		(layer "In4.Cu")
		(net "OCP_SFF_AUX_PWR_EN")
	)
	(segment
		(start 407.697178 -105.448608)
		(end 379.350524 -105.448608)
		(width 0.127)
		(layer "In4.Cu")
		(net "OCP_SFF_AUX_PWR_EN")
	)
	(segment
		(start 414.852358 -112.603788)
		(end 407.697178 -105.448608)
		(width 0.127)
		(layer "In4.Cu")
		(net "OCP_SFF_AUX_PWR_EN")
	)
	(segment
		(start 440.50966 -107.65028)
		(end 440.171078 -107.988862)
		(width 0.127)
		(layer "In4.Cu")
		(net "OCP_SFF_AUX_PWR_EN")
	)
	(segment
		(start 440.50966 -107.65028)
		(end 446.696592 -101.463348)
		(width 0.127)
		(layer "In4.Cu")
		(net "OCP_SFF_AUX_PWR_EN")
	)
	(segment
		(start 379.350524 -105.448608)
		(end 378.408184 -106.390948)
		(width 0.127)
		(layer "In4.Cu")
		(net "OCP_SFF_AUX_PWR_EN")
	)
	(segment
		(start 378.408184 -106.390948)
		(end 376.8344 -106.390948)
		(width 0.127)
		(layer "In4.Cu")
		(net "OCP_SFF_AUX_PWR_EN")
	)
	(segment
		(start 440.171078 -109.666532)
		(end 437.233822 -112.603788)
		(width 0.127)
		(layer "In4.Cu")
		(net "OCP_SFF_AUX_PWR_EN")
	)
	(segment
		(start 376.8344 -106.390948)
		(end 375.90222 -105.458768)
		(width 0.127)
		(layer "In4.Cu")
		(net "OCP_SFF_AUX_PWR_EN")
	)
	(segment
		(start 310.32704 -105.458768)
		(end 309.59298 -106.192828)
		(width 0.127)
		(layer "In4.Cu")
		(net "OCP_SFF_AUX_PWR_EN")
	)
	(segment
		(start 451.2691 -101.463348)
		(end 454.552304 -98.180144)
		(width 0.127)
		(layer "In4.Cu")
		(net "OCP_SFF_AUX_PWR_EN")
	)
	(segment
		(start 454.552304 -98.180144)
		(end 455.039476 -98.180144)
		(width 0.127)
		(layer "In4.Cu")
		(net "OCP_SFF_AUX_PWR_EN")
	)
	(segment
		(start 446.696592 -101.463348)
		(end 451.2691 -101.463348)
		(width 0.127)
		(layer "In4.Cu")
		(net "OCP_SFF_AUX_PWR_EN")
	)
	(segment
		(start 375.90222 -105.458768)
		(end 310.32704 -105.458768)
		(width 0.127)
		(layer "In4.Cu")
		(net "OCP_SFF_AUX_PWR_EN")
	)
	(segment
		(start 440.171078 -107.988862)
		(end 440.171078 -109.666532)
		(width 0.127)
		(layer "In4.Cu")
		(net "OCP_SFF_AUX_PWR_EN")
	)
	(segment
		(start 333.802736 -215.894412)
		(end 333.802736 -216.383362)
		(width 0.12954)
		(layer "F.Cu")
		(net "NC_XTAL_CPU0_25M_OUT")
	)
	(segment
		(start 333.802736 -216.383362)
		(end 334.205834 -216.78646)
		(width 0.12954)
		(layer "F.Cu")
		(net "NC_XTAL_CPU0_25M_OUT")
	)
	(via
		(at 333.802736 -215.894412)
		(size 0.4572)
		(drill 0.2032)
		(layers "F.Cu" "B.Cu")
		(net "NC_XTAL_CPU0_25M_OUT")
	)
	(segment
		(start 335.61528 -217.064336)
		(end 335.615534 -217.06459)
		(width 0.12954)
		(layer "F.Cu")
		(net "NC_XTAL_CPU0_25M_IN")
	)
	(segment
		(start 335.615534 -217.06459)
		(end 335.615534 -217.600276)
		(width 0.12954)
		(layer "F.Cu")
		(net "NC_XTAL_CPU0_25M_IN")
	)
	(via
		(at 335.61528 -217.064336)
		(size 0.4572)
		(drill 0.2032)
		(layers "F.Cu" "B.Cu")
		(net "NC_XTAL_CPU0_25M_IN")
	)
	(segment
		(start 121.148094 -271.289272)
		(end 121.148348 -271.825212)
		(width 0.12954)
		(layer "F.Cu")
		(net "NC_UART_IBL_CPU1_TXD")
	)
	(via
		(at 121.148348 -271.825212)
		(size 0.4572)
		(drill 0.2032)
		(layers "F.Cu" "B.Cu")
		(net "NC_UART_IBL_CPU1_TXD")
	)
	(segment
		(start 122.087894 -271.289272)
		(end 122.088148 -271.825212)
		(width 0.12954)
		(layer "F.Cu")
		(net "NC_UART_IBL_CPU1_RXD")
	)
	(via
		(at 122.088148 -271.825212)
		(size 0.4572)
		(drill 0.2032)
		(layers "F.Cu" "B.Cu")
		(net "NC_UART_IBL_CPU1_RXD")
	)
	(segment
		(start 122.087894 -272.917158)
		(end 122.088148 -272.917158)
		(width 0.12954)
		(layer "F.Cu")
		(net "NC_UART_IBL_CPU1_RTS")
	)
	(segment
		(start 122.088148 -272.917158)
		(end 122.088148 -273.453098)
		(width 0.12954)
		(layer "F.Cu")
		(net "NC_UART_IBL_CPU1_RTS")
	)
	(via
		(at 122.088148 -273.453098)
		(size 0.4572)
		(drill 0.2032)
		(layers "F.Cu" "B.Cu")
		(net "NC_UART_IBL_CPU1_RTS")
	)
	(segment
		(start 121.148094 -272.917158)
		(end 121.148094 -273.452844)
		(width 0.12954)
		(layer "F.Cu")
		(net "NC_UART_IBL_CPU1_CTS")
	)
	(segment
		(start 121.148094 -273.452844)
		(end 121.148348 -273.453098)
		(width 0.12954)
		(layer "F.Cu")
		(net "NC_UART_IBL_CPU1_CTS")
	)
	(via
		(at 121.148348 -273.453098)
		(size 0.4572)
		(drill 0.2032)
		(layers "F.Cu" "B.Cu")
		(net "NC_UART_IBL_CPU1_CTS")
	)
	(segment
		(start 369.088162 -271.289272)
		(end 369.088416 -271.825212)
		(width 0.12954)
		(layer "F.Cu")
		(net "NC_UART_IBL_CPU0_TXD")
	)
	(via
		(at 369.088416 -271.825212)
		(size 0.4572)
		(drill 0.2032)
		(layers "F.Cu" "B.Cu")
		(net "NC_UART_IBL_CPU0_TXD")
	)
	(segment
		(start 370.027962 -271.289272)
		(end 370.028216 -271.825212)
		(width 0.12954)
		(layer "F.Cu")
		(net "NC_UART_IBL_CPU0_RXD")
	)
	(via
		(at 370.028216 -271.825212)
		(size 0.4572)
		(drill 0.2032)
		(layers "F.Cu" "B.Cu")
		(net "NC_UART_IBL_CPU0_RXD")
	)
	(segment
		(start 370.027962 -272.917158)
		(end 370.028216 -272.917158)
		(width 0.12954)
		(layer "F.Cu")
		(net "NC_UART_IBL_CPU0_RTS")
	)
	(segment
		(start 370.028216 -272.917158)
		(end 370.028216 -273.453098)
		(width 0.12954)
		(layer "F.Cu")
		(net "NC_UART_IBL_CPU0_RTS")
	)
	(via
		(at 370.028216 -273.453098)
		(size 0.4572)
		(drill 0.2032)
		(layers "F.Cu" "B.Cu")
		(net "NC_UART_IBL_CPU0_RTS")
	)
	(segment
		(start 369.088162 -272.917158)
		(end 369.088416 -272.917412)
		(width 0.12954)
		(layer "F.Cu")
		(net "NC_UART_IBL_CPU0_CTS")
	)
	(segment
		(start 369.088416 -272.917412)
		(end 369.088416 -273.453098)
		(width 0.12954)
		(layer "F.Cu")
		(net "NC_UART_IBL_CPU0_CTS")
	)
	(via
		(at 369.088416 -273.453098)
		(size 0.4572)
		(drill 0.2032)
		(layers "F.Cu" "B.Cu")
		(net "NC_UART_IBL_CPU0_CTS")
	)
	(segment
		(start 314.400184 -13.7414)
		(end 315.887862 -15.229078)
		(width 0.12954)
		(layer "F.Cu")
		(net "NC_U157_NC1")
	)
	(segment
		(start 313.17057 -13.7414)
		(end 314.400184 -13.7414)
		(width 0.12954)
		(layer "F.Cu")
		(net "NC_U157_NC1")
	)
	(via
		(at 315.887862 -15.229078)
		(size 0.762)
		(drill 0.381)
		(layers "F.Cu" "B.Cu")
		(net "NC_U157_NC1")
	)
	(segment
		(start 388.90194 -27.480768)
		(end 389.106918 -27.27579)
		(width 0.12954)
		(layer "F.Cu")
		(net "NC_U104_NC1")
	)
	(segment
		(start 389.106918 -27.27579)
		(end 389.106918 -27.109928)
		(width 0.12954)
		(layer "F.Cu")
		(net "NC_U104_NC1")
	)
	(segment
		(start 387.58876 -27.480768)
		(end 388.90194 -27.480768)
		(width 0.12954)
		(layer "F.Cu")
		(net "NC_U104_NC1")
	)
	(via
		(at 387.58876 -27.480768)
		(size 0.762)
		(drill 0.381)
		(layers "F.Cu" "B.Cu")
		(net "NC_U104_NC1")
	)
	(segment
		(start 103.761794 -270.47571)
		(end 103.761794 -271.011396)
		(width 0.12954)
		(layer "F.Cu")
		(net "NC_SPI_S3M_CPU1_OE_LVC1_R_N")
	)
	(segment
		(start 103.762048 -270.475456)
		(end 103.761794 -270.47571)
		(width 0.12954)
		(layer "F.Cu")
		(net "NC_SPI_S3M_CPU1_OE_LVC1_R_N")
	)
	(via
		(at 103.761794 -271.011396)
		(size 0.4572)
		(drill 0.2032)
		(layers "F.Cu" "B.Cu")
		(net "NC_SPI_S3M_CPU1_OE_LVC1_R_N")
	)
	(via
		(at 83.989418 -270.28267)
		(size 0.6604)
		(drill 0.3302)
		(layers "F.Cu" "B.Cu")
		(net "NC_SPI_S3M_CPU1_OE_LVC1_R_N")
	)
	(segment
		(start 93.236796 -270.687038)
		(end 93.222064 -270.695674)
		(width 0.0889)
		(layer "B.Cu")
		(net "NC_SPI_S3M_CPU1_OE_LVC1_R_N")
	)
	(segment
		(start 97.935796 -270.687038)
		(end 97.921064 -270.695674)
		(width 0.0889)
		(layer "B.Cu")
		(net "NC_SPI_S3M_CPU1_OE_LVC1_R_N")
	)
	(segment
		(start 84.342986 -270.636238)
		(end 83.989418 -270.28267)
		(width 0.12954)
		(layer "B.Cu")
		(net "NC_SPI_S3M_CPU1_OE_LVC1_R_N")
	)
	(segment
		(start 96.056196 -270.687038)
		(end 96.041464 -270.695674)
		(width 0.0889)
		(layer "B.Cu")
		(net "NC_SPI_S3M_CPU1_OE_LVC1_R_N")
	)
	(segment
		(start 103.918258 -270.740378)
		(end 103.897176 -270.6624)
		(width 0.0889)
		(layer "B.Cu")
		(net "NC_SPI_S3M_CPU1_OE_LVC1_R_N")
	)
	(segment
		(start 91.357196 -270.687038)
		(end 91.342464 -270.695674)
		(width 0.0889)
		(layer "B.Cu")
		(net "NC_SPI_S3M_CPU1_OE_LVC1_R_N")
	)
	(segment
		(start 96.995996 -270.687038)
		(end 96.981264 -270.695674)
		(width 0.0889)
		(layer "B.Cu")
		(net "NC_SPI_S3M_CPU1_OE_LVC1_R_N")
	)
	(segment
		(start 95.116396 -270.687038)
		(end 95.105982 -270.693134)
		(width 0.0889)
		(layer "B.Cu")
		(net "NC_SPI_S3M_CPU1_OE_LVC1_R_N")
	)
	(segment
		(start 99.815396 -270.687038)
		(end 99.800664 -270.695674)
		(width 0.0889)
		(layer "B.Cu")
		(net "NC_SPI_S3M_CPU1_OE_LVC1_R_N")
	)
	(segment
		(start 86.84514 -270.636238)
		(end 86.107016 -270.636238)
		(width 0.0889)
		(layer "B.Cu")
		(net "NC_SPI_S3M_CPU1_OE_LVC1_R_N")
	)
	(segment
		(start 103.574596 -270.687038)
		(end 103.559864 -270.695674)
		(width 0.0889)
		(layer "B.Cu")
		(net "NC_SPI_S3M_CPU1_OE_LVC1_R_N")
	)
	(segment
		(start 100.75545 -270.687038)
		(end 100.745036 -270.693134)
		(width 0.0889)
		(layer "B.Cu")
		(net "NC_SPI_S3M_CPU1_OE_LVC1_R_N")
	)
	(segment
		(start 94.17685 -270.687038)
		(end 94.166436 -270.693134)
		(width 0.0889)
		(layer "B.Cu")
		(net "NC_SPI_S3M_CPU1_OE_LVC1_R_N")
	)
	(segment
		(start 86.107016 -270.636238)
		(end 84.342986 -270.636238)
		(width 0.12954)
		(layer "B.Cu")
		(net "NC_SPI_S3M_CPU1_OE_LVC1_R_N")
	)
	(segment
		(start 102.634796 -270.687038)
		(end 102.624382 -270.693134)
		(width 0.0889)
		(layer "B.Cu")
		(net "NC_SPI_S3M_CPU1_OE_LVC1_R_N")
	)
	(segment
		(start 103.761794 -271.011396)
		(end 103.918258 -270.740378)
		(width 0.0889)
		(layer "B.Cu")
		(net "NC_SPI_S3M_CPU1_OE_LVC1_R_N")
	)
	(arc
		(start 93.222064 -270.695674)
		(mid 92.945589 -270.762994)
		(end 92.671392 -270.687038)
		(width 0.0889)
		(layer "B.Cu")
		(net "NC_SPI_S3M_CPU1_OE_LVC1_R_N")
	)
	(arc
		(start 99.800664 -270.695674)
		(mid 99.524189 -270.762994)
		(end 99.249992 -270.687038)
		(width 0.0889)
		(layer "B.Cu")
		(net "NC_SPI_S3M_CPU1_OE_LVC1_R_N")
	)
	(arc
		(start 94.166436 -270.693134)
		(mid 93.888004 -270.76298)
		(end 93.611192 -270.687038)
		(width 0.0889)
		(layer "B.Cu")
		(net "NC_SPI_S3M_CPU1_OE_LVC1_R_N")
	)
	(arc
		(start 88.537796 -270.687038)
		(mid 88.255094 -270.762814)
		(end 87.972392 -270.687038)
		(width 0.0889)
		(layer "B.Cu")
		(net "NC_SPI_S3M_CPU1_OE_LVC1_R_N")
	)
	(arc
		(start 97.921064 -270.695674)
		(mid 97.644589 -270.762994)
		(end 97.370392 -270.687038)
		(width 0.0889)
		(layer "B.Cu")
		(net "NC_SPI_S3M_CPU1_OE_LVC1_R_N")
	)
	(arc
		(start 96.041464 -270.695674)
		(mid 95.764989 -270.762994)
		(end 95.490792 -270.687038)
		(width 0.0889)
		(layer "B.Cu")
		(net "NC_SPI_S3M_CPU1_OE_LVC1_R_N")
	)
	(arc
		(start 93.611192 -270.687038)
		(mid 93.423994 -270.636895)
		(end 93.236796 -270.687038)
		(width 0.0889)
		(layer "B.Cu")
		(net "NC_SPI_S3M_CPU1_OE_LVC1_R_N")
	)
	(arc
		(start 87.972392 -270.687038)
		(mid 87.785194 -270.636895)
		(end 87.597996 -270.687038)
		(width 0.0889)
		(layer "B.Cu")
		(net "NC_SPI_S3M_CPU1_OE_LVC1_R_N")
	)
	(arc
		(start 92.296996 -270.687038)
		(mid 92.014294 -270.762814)
		(end 91.731592 -270.687038)
		(width 0.0889)
		(layer "B.Cu")
		(net "NC_SPI_S3M_CPU1_OE_LVC1_R_N")
	)
	(arc
		(start 96.430592 -270.687038)
		(mid 96.243394 -270.636895)
		(end 96.056196 -270.687038)
		(width 0.0889)
		(layer "B.Cu")
		(net "NC_SPI_S3M_CPU1_OE_LVC1_R_N")
	)
	(arc
		(start 102.624382 -270.693134)
		(mid 102.346204 -270.762857)
		(end 102.069646 -270.687038)
		(width 0.0889)
		(layer "B.Cu")
		(net "NC_SPI_S3M_CPU1_OE_LVC1_R_N")
	)
	(arc
		(start 97.370392 -270.687038)
		(mid 97.183194 -270.636895)
		(end 96.995996 -270.687038)
		(width 0.0889)
		(layer "B.Cu")
		(net "NC_SPI_S3M_CPU1_OE_LVC1_R_N")
	)
	(arc
		(start 87.032592 -270.687038)
		(mid 86.942213 -270.649283)
		(end 86.84514 -270.636238)
		(width 0.0889)
		(layer "B.Cu")
		(net "NC_SPI_S3M_CPU1_OE_LVC1_R_N")
	)
	(arc
		(start 101.69525 -270.687038)
		(mid 101.412548 -270.762814)
		(end 101.129846 -270.687038)
		(width 0.0889)
		(layer "B.Cu")
		(net "NC_SPI_S3M_CPU1_OE_LVC1_R_N")
	)
	(arc
		(start 103.897176 -270.6624)
		(mid 103.73308 -270.638053)
		(end 103.574596 -270.687038)
		(width 0.0889)
		(layer "B.Cu")
		(net "NC_SPI_S3M_CPU1_OE_LVC1_R_N")
	)
	(arc
		(start 92.671392 -270.687038)
		(mid 92.484194 -270.636895)
		(end 92.296996 -270.687038)
		(width 0.0889)
		(layer "B.Cu")
		(net "NC_SPI_S3M_CPU1_OE_LVC1_R_N")
	)
	(arc
		(start 89.477596 -270.687038)
		(mid 89.194894 -270.762814)
		(end 88.912192 -270.687038)
		(width 0.0889)
		(layer "B.Cu")
		(net "NC_SPI_S3M_CPU1_OE_LVC1_R_N")
	)
	(arc
		(start 98.875596 -270.687038)
		(mid 98.592894 -270.762814)
		(end 98.310192 -270.687038)
		(width 0.0889)
		(layer "B.Cu")
		(net "NC_SPI_S3M_CPU1_OE_LVC1_R_N")
	)
	(arc
		(start 91.731592 -270.687038)
		(mid 91.544394 -270.636895)
		(end 91.357196 -270.687038)
		(width 0.0889)
		(layer "B.Cu")
		(net "NC_SPI_S3M_CPU1_OE_LVC1_R_N")
	)
	(arc
		(start 95.490792 -270.687038)
		(mid 95.303594 -270.636895)
		(end 95.116396 -270.687038)
		(width 0.0889)
		(layer "B.Cu")
		(net "NC_SPI_S3M_CPU1_OE_LVC1_R_N")
	)
	(arc
		(start 94.551246 -270.687038)
		(mid 94.364048 -270.636895)
		(end 94.17685 -270.687038)
		(width 0.0889)
		(layer "B.Cu")
		(net "NC_SPI_S3M_CPU1_OE_LVC1_R_N")
	)
	(arc
		(start 95.105982 -270.693134)
		(mid 94.827804 -270.762857)
		(end 94.551246 -270.687038)
		(width 0.0889)
		(layer "B.Cu")
		(net "NC_SPI_S3M_CPU1_OE_LVC1_R_N")
	)
	(arc
		(start 100.189792 -270.687038)
		(mid 100.002594 -270.636895)
		(end 99.815396 -270.687038)
		(width 0.0889)
		(layer "B.Cu")
		(net "NC_SPI_S3M_CPU1_OE_LVC1_R_N")
	)
	(arc
		(start 103.559864 -270.695674)
		(mid 103.283389 -270.762994)
		(end 103.009192 -270.687038)
		(width 0.0889)
		(layer "B.Cu")
		(net "NC_SPI_S3M_CPU1_OE_LVC1_R_N")
	)
	(arc
		(start 101.129846 -270.687038)
		(mid 100.942648 -270.636895)
		(end 100.75545 -270.687038)
		(width 0.0889)
		(layer "B.Cu")
		(net "NC_SPI_S3M_CPU1_OE_LVC1_R_N")
	)
	(arc
		(start 102.069646 -270.687038)
		(mid 101.882448 -270.636895)
		(end 101.69525 -270.687038)
		(width 0.0889)
		(layer "B.Cu")
		(net "NC_SPI_S3M_CPU1_OE_LVC1_R_N")
	)
	(arc
		(start 90.791792 -270.687038)
		(mid 90.604594 -270.636895)
		(end 90.417396 -270.687038)
		(width 0.0889)
		(layer "B.Cu")
		(net "NC_SPI_S3M_CPU1_OE_LVC1_R_N")
	)
	(arc
		(start 100.745036 -270.693134)
		(mid 100.466604 -270.76298)
		(end 100.189792 -270.687038)
		(width 0.0889)
		(layer "B.Cu")
		(net "NC_SPI_S3M_CPU1_OE_LVC1_R_N")
	)
	(arc
		(start 87.597996 -270.687038)
		(mid 87.315294 -270.762814)
		(end 87.032592 -270.687038)
		(width 0.0889)
		(layer "B.Cu")
		(net "NC_SPI_S3M_CPU1_OE_LVC1_R_N")
	)
	(arc
		(start 88.912192 -270.687038)
		(mid 88.724994 -270.636895)
		(end 88.537796 -270.687038)
		(width 0.0889)
		(layer "B.Cu")
		(net "NC_SPI_S3M_CPU1_OE_LVC1_R_N")
	)
	(arc
		(start 91.342464 -270.695674)
		(mid 91.065989 -270.762994)
		(end 90.791792 -270.687038)
		(width 0.0889)
		(layer "B.Cu")
		(net "NC_SPI_S3M_CPU1_OE_LVC1_R_N")
	)
	(arc
		(start 96.981264 -270.695674)
		(mid 96.704789 -270.762994)
		(end 96.430592 -270.687038)
		(width 0.0889)
		(layer "B.Cu")
		(net "NC_SPI_S3M_CPU1_OE_LVC1_R_N")
	)
	(arc
		(start 89.851992 -270.687038)
		(mid 89.664794 -270.636895)
		(end 89.477596 -270.687038)
		(width 0.0889)
		(layer "B.Cu")
		(net "NC_SPI_S3M_CPU1_OE_LVC1_R_N")
	)
	(arc
		(start 98.310192 -270.687038)
		(mid 98.122994 -270.636895)
		(end 97.935796 -270.687038)
		(width 0.0889)
		(layer "B.Cu")
		(net "NC_SPI_S3M_CPU1_OE_LVC1_R_N")
	)
	(arc
		(start 90.417396 -270.687038)
		(mid 90.134694 -270.762814)
		(end 89.851992 -270.687038)
		(width 0.0889)
		(layer "B.Cu")
		(net "NC_SPI_S3M_CPU1_OE_LVC1_R_N")
	)
	(arc
		(start 99.249992 -270.687038)
		(mid 99.062794 -270.636895)
		(end 98.875596 -270.687038)
		(width 0.0889)
		(layer "B.Cu")
		(net "NC_SPI_S3M_CPU1_OE_LVC1_R_N")
	)
	(arc
		(start 103.009192 -270.687038)
		(mid 102.821994 -270.636895)
		(end 102.634796 -270.687038)
		(width 0.0889)
		(layer "B.Cu")
		(net "NC_SPI_S3M_CPU1_OE_LVC1_R_N")
	)
	(segment
		(start 105.171494 -264.778236)
		(end 105.171494 -265.313922)
		(width 0.12954)
		(layer "F.Cu")
		(net "NC_SPI_S3M_CPU1_IO3_LVC1_R")
	)
	(segment
		(start 105.171494 -265.313922)
		(end 105.171748 -265.314176)
		(width 0.12954)
		(layer "F.Cu")
		(net "NC_SPI_S3M_CPU1_IO3_LVC1_R")
	)
	(via
		(at 73.508616 -258.423156)
		(size 0.6604)
		(drill 0.3302)
		(layers "F.Cu" "B.Cu")
		(net "NC_SPI_S3M_CPU1_IO3_LVC1_R")
	)
	(via
		(at 105.171748 -265.314176)
		(size 0.4572)
		(drill 0.2032)
		(layers "F.Cu" "B.Cu")
		(net "NC_SPI_S3M_CPU1_IO3_LVC1_R")
	)
	(segment
		(start 83.938618 -264.90295)
		(end 83.60664 -265.234928)
		(width 0.12954)
		(layer "B.Cu")
		(net "NC_SPI_S3M_CPU1_IO3_LVC1_R")
	)
	(segment
		(start 96.056196 -264.176002)
		(end 96.041464 -264.184638)
		(width 0.0889)
		(layer "B.Cu")
		(net "NC_SPI_S3M_CPU1_IO3_LVC1_R")
	)
	(segment
		(start 87.785194 -264.125456)
		(end 86.595458 -264.125456)
		(width 0.0889)
		(layer "B.Cu")
		(net "NC_SPI_S3M_CPU1_IO3_LVC1_R")
	)
	(segment
		(start 103.488236 -264.994898)
		(end 103.479346 -264.989818)
		(width 0.0889)
		(layer "B.Cu")
		(net "NC_SPI_S3M_CPU1_IO3_LVC1_R")
	)
	(segment
		(start 85.457538 -264.718292)
		(end 85.27288 -264.90295)
		(width 0.12954)
		(layer "B.Cu")
		(net "NC_SPI_S3M_CPU1_IO3_LVC1_R")
	)
	(segment
		(start 93.236796 -264.176002)
		(end 93.222064 -264.184638)
		(width 0.0889)
		(layer "B.Cu")
		(net "NC_SPI_S3M_CPU1_IO3_LVC1_R")
	)
	(segment
		(start 103.013256 -264.125456)
		(end 102.821994 -264.125456)
		(width 0.0889)
		(layer "B.Cu")
		(net "NC_SPI_S3M_CPU1_IO3_LVC1_R")
	)
	(segment
		(start 86.506812 -264.03681)
		(end 86.321138 -264.03681)
		(width 0.0889)
		(layer "B.Cu")
		(net "NC_SPI_S3M_CPU1_IO3_LVC1_R")
	)
	(segment
		(start 97.93605 -264.176002)
		(end 97.925636 -264.182098)
		(width 0.0889)
		(layer "B.Cu")
		(net "NC_SPI_S3M_CPU1_IO3_LVC1_R")
	)
	(segment
		(start 80.694784 -265.234928)
		(end 73.883012 -258.423156)
		(width 0.12954)
		(layer "B.Cu")
		(net "NC_SPI_S3M_CPU1_IO3_LVC1_R")
	)
	(segment
		(start 91.35745 -264.176002)
		(end 91.347036 -264.182098)
		(width 0.0889)
		(layer "B.Cu")
		(net "NC_SPI_S3M_CPU1_IO3_LVC1_R")
	)
	(segment
		(start 73.883012 -258.423156)
		(end 73.508616 -258.423156)
		(width 0.12954)
		(layer "B.Cu")
		(net "NC_SPI_S3M_CPU1_IO3_LVC1_R")
	)
	(segment
		(start 103.479346 -264.989818)
		(end 103.47325 -264.986262)
		(width 0.0889)
		(layer "B.Cu")
		(net "NC_SPI_S3M_CPU1_IO3_LVC1_R")
	)
	(segment
		(start 99.815396 -264.176002)
		(end 99.800664 -264.184638)
		(width 0.0889)
		(layer "B.Cu")
		(net "NC_SPI_S3M_CPU1_IO3_LVC1_R")
	)
	(segment
		(start 83.60664 -265.234928)
		(end 80.694784 -265.234928)
		(width 0.12954)
		(layer "B.Cu")
		(net "NC_SPI_S3M_CPU1_IO3_LVC1_R")
	)
	(segment
		(start 102.634796 -264.176002)
		(end 102.620064 -264.184638)
		(width 0.0889)
		(layer "B.Cu")
		(net "NC_SPI_S3M_CPU1_IO3_LVC1_R")
	)
	(segment
		(start 85.457538 -264.259314)
		(end 85.457538 -264.718292)
		(width 0.12954)
		(layer "B.Cu")
		(net "NC_SPI_S3M_CPU1_IO3_LVC1_R")
	)
	(segment
		(start 103.666798 -265.314938)
		(end 103.666798 -265.314176)
		(width 0.0889)
		(layer "B.Cu")
		(net "NC_SPI_S3M_CPU1_IO3_LVC1_R")
	)
	(segment
		(start 86.321138 -264.03681)
		(end 85.680042 -264.03681)
		(width 0.12954)
		(layer "B.Cu")
		(net "NC_SPI_S3M_CPU1_IO3_LVC1_R")
	)
	(segment
		(start 98.875596 -264.176002)
		(end 98.865182 -264.182098)
		(width 0.0889)
		(layer "B.Cu")
		(net "NC_SPI_S3M_CPU1_IO3_LVC1_R")
	)
	(segment
		(start 105.171748 -265.314176)
		(end 104.859074 -265.314176)
		(width 0.0889)
		(layer "B.Cu")
		(net "NC_SPI_S3M_CPU1_IO3_LVC1_R")
	)
	(segment
		(start 103.196644 -264.50036)
		(end 103.196644 -264.308844)
		(width 0.0889)
		(layer "B.Cu")
		(net "NC_SPI_S3M_CPU1_IO3_LVC1_R")
	)
	(segment
		(start 104.859074 -265.314176)
		(end 104.793288 -265.379962)
		(width 0.0889)
		(layer "B.Cu")
		(net "NC_SPI_S3M_CPU1_IO3_LVC1_R")
	)
	(segment
		(start 86.595458 -264.125456)
		(end 86.506812 -264.03681)
		(width 0.0889)
		(layer "B.Cu")
		(net "NC_SPI_S3M_CPU1_IO3_LVC1_R")
	)
	(segment
		(start 104.520492 -265.800078)
		(end 104.514396 -265.803888)
		(width 0.0889)
		(layer "B.Cu")
		(net "NC_SPI_S3M_CPU1_IO3_LVC1_R")
	)
	(segment
		(start 103.196644 -264.308844)
		(end 103.013256 -264.125456)
		(width 0.0889)
		(layer "B.Cu")
		(net "NC_SPI_S3M_CPU1_IO3_LVC1_R")
	)
	(segment
		(start 85.680042 -264.03681)
		(end 85.457538 -264.259314)
		(width 0.12954)
		(layer "B.Cu")
		(net "NC_SPI_S3M_CPU1_IO3_LVC1_R")
	)
	(segment
		(start 104.514396 -265.803888)
		(end 104.499664 -265.812524)
		(width 0.0889)
		(layer "B.Cu")
		(net "NC_SPI_S3M_CPU1_IO3_LVC1_R")
	)
	(segment
		(start 85.27288 -264.90295)
		(end 83.938618 -264.90295)
		(width 0.12954)
		(layer "B.Cu")
		(net "NC_SPI_S3M_CPU1_IO3_LVC1_R")
	)
	(segment
		(start 100.755196 -264.176002)
		(end 100.740464 -264.184638)
		(width 0.0889)
		(layer "B.Cu")
		(net "NC_SPI_S3M_CPU1_IO3_LVC1_R")
	)
	(segment
		(start 96.995996 -264.176002)
		(end 96.981264 -264.184638)
		(width 0.0889)
		(layer "B.Cu")
		(net "NC_SPI_S3M_CPU1_IO3_LVC1_R")
	)
	(segment
		(start 94.176596 -264.176002)
		(end 94.161864 -264.184638)
		(width 0.0889)
		(layer "B.Cu")
		(net "NC_SPI_S3M_CPU1_IO3_LVC1_R")
	)
	(segment
		(start 92.296996 -264.176002)
		(end 92.286582 -264.182098)
		(width 0.0889)
		(layer "B.Cu")
		(net "NC_SPI_S3M_CPU1_IO3_LVC1_R")
	)
	(arc
		(start 96.981264 -264.184638)
		(mid 96.704789 -264.251958)
		(end 96.430592 -264.176002)
		(width 0.0889)
		(layer "B.Cu")
		(net "NC_SPI_S3M_CPU1_IO3_LVC1_R")
	)
	(arc
		(start 97.925636 -264.182098)
		(mid 97.647204 -264.251944)
		(end 97.370392 -264.176002)
		(width 0.0889)
		(layer "B.Cu")
		(net "NC_SPI_S3M_CPU1_IO3_LVC1_R")
	)
	(arc
		(start 95.116396 -264.176002)
		(mid 94.833694 -264.251778)
		(end 94.550992 -264.176002)
		(width 0.0889)
		(layer "B.Cu")
		(net "NC_SPI_S3M_CPU1_IO3_LVC1_R")
	)
	(arc
		(start 101.129592 -264.176002)
		(mid 100.942394 -264.125859)
		(end 100.755196 -264.176002)
		(width 0.0889)
		(layer "B.Cu")
		(net "NC_SPI_S3M_CPU1_IO3_LVC1_R")
	)
	(arc
		(start 90.417396 -264.176002)
		(mid 90.134694 -264.251778)
		(end 89.851992 -264.176002)
		(width 0.0889)
		(layer "B.Cu")
		(net "NC_SPI_S3M_CPU1_IO3_LVC1_R")
	)
	(arc
		(start 89.477596 -264.176002)
		(mid 89.194894 -264.251778)
		(end 88.912192 -264.176002)
		(width 0.0889)
		(layer "B.Cu")
		(net "NC_SPI_S3M_CPU1_IO3_LVC1_R")
	)
	(arc
		(start 103.948992 -265.803888)
		(mid 103.742391 -265.597214)
		(end 103.666798 -265.314938)
		(width 0.0889)
		(layer "B.Cu")
		(net "NC_SPI_S3M_CPU1_IO3_LVC1_R")
	)
	(arc
		(start 92.671392 -264.176002)
		(mid 92.484194 -264.125859)
		(end 92.296996 -264.176002)
		(width 0.0889)
		(layer "B.Cu")
		(net "NC_SPI_S3M_CPU1_IO3_LVC1_R")
	)
	(arc
		(start 96.041464 -264.184638)
		(mid 95.764989 -264.251958)
		(end 95.490792 -264.176002)
		(width 0.0889)
		(layer "B.Cu")
		(net "NC_SPI_S3M_CPU1_IO3_LVC1_R")
	)
	(arc
		(start 96.430592 -264.176002)
		(mid 96.243394 -264.125859)
		(end 96.056196 -264.176002)
		(width 0.0889)
		(layer "B.Cu")
		(net "NC_SPI_S3M_CPU1_IO3_LVC1_R")
	)
	(arc
		(start 100.740464 -264.184638)
		(mid 100.463989 -264.251958)
		(end 100.189792 -264.176002)
		(width 0.0889)
		(layer "B.Cu")
		(net "NC_SPI_S3M_CPU1_IO3_LVC1_R")
	)
	(arc
		(start 104.499664 -265.812524)
		(mid 104.223223 -265.87969)
		(end 103.948992 -265.803888)
		(width 0.0889)
		(layer "B.Cu")
		(net "NC_SPI_S3M_CPU1_IO3_LVC1_R")
	)
	(arc
		(start 90.791792 -264.176002)
		(mid 90.604594 -264.125859)
		(end 90.417396 -264.176002)
		(width 0.0889)
		(layer "B.Cu")
		(net "NC_SPI_S3M_CPU1_IO3_LVC1_R")
	)
	(arc
		(start 103.666798 -265.314176)
		(mid 103.619119 -265.131276)
		(end 103.488236 -264.994898)
		(width 0.0889)
		(layer "B.Cu")
		(net "NC_SPI_S3M_CPU1_IO3_LVC1_R")
	)
	(arc
		(start 98.310446 -264.176002)
		(mid 98.123248 -264.125859)
		(end 97.93605 -264.176002)
		(width 0.0889)
		(layer "B.Cu")
		(net "NC_SPI_S3M_CPU1_IO3_LVC1_R")
	)
	(arc
		(start 91.731846 -264.176002)
		(mid 91.544648 -264.125859)
		(end 91.35745 -264.176002)
		(width 0.0889)
		(layer "B.Cu")
		(net "NC_SPI_S3M_CPU1_IO3_LVC1_R")
	)
	(arc
		(start 99.800664 -264.184638)
		(mid 99.524189 -264.251958)
		(end 99.249992 -264.176002)
		(width 0.0889)
		(layer "B.Cu")
		(net "NC_SPI_S3M_CPU1_IO3_LVC1_R")
	)
	(arc
		(start 88.912192 -264.176002)
		(mid 88.724994 -264.125859)
		(end 88.537796 -264.176002)
		(width 0.0889)
		(layer "B.Cu")
		(net "NC_SPI_S3M_CPU1_IO3_LVC1_R")
	)
	(arc
		(start 95.490792 -264.176002)
		(mid 95.303594 -264.125859)
		(end 95.116396 -264.176002)
		(width 0.0889)
		(layer "B.Cu")
		(net "NC_SPI_S3M_CPU1_IO3_LVC1_R")
	)
	(arc
		(start 99.249992 -264.176002)
		(mid 99.062794 -264.125859)
		(end 98.875596 -264.176002)
		(width 0.0889)
		(layer "B.Cu")
		(net "NC_SPI_S3M_CPU1_IO3_LVC1_R")
	)
	(arc
		(start 94.161864 -264.184638)
		(mid 93.885389 -264.251958)
		(end 93.611192 -264.176002)
		(width 0.0889)
		(layer "B.Cu")
		(net "NC_SPI_S3M_CPU1_IO3_LVC1_R")
	)
	(arc
		(start 93.222064 -264.184638)
		(mid 92.945589 -264.251958)
		(end 92.671392 -264.176002)
		(width 0.0889)
		(layer "B.Cu")
		(net "NC_SPI_S3M_CPU1_IO3_LVC1_R")
	)
	(arc
		(start 93.611192 -264.176002)
		(mid 93.423994 -264.125859)
		(end 93.236796 -264.176002)
		(width 0.0889)
		(layer "B.Cu")
		(net "NC_SPI_S3M_CPU1_IO3_LVC1_R")
	)
	(arc
		(start 92.286582 -264.182098)
		(mid 92.008404 -264.251821)
		(end 91.731846 -264.176002)
		(width 0.0889)
		(layer "B.Cu")
		(net "NC_SPI_S3M_CPU1_IO3_LVC1_R")
	)
	(arc
		(start 97.370392 -264.176002)
		(mid 97.183194 -264.125859)
		(end 96.995996 -264.176002)
		(width 0.0889)
		(layer "B.Cu")
		(net "NC_SPI_S3M_CPU1_IO3_LVC1_R")
	)
	(arc
		(start 102.821994 -264.125456)
		(mid 102.725071 -264.138414)
		(end 102.634796 -264.176002)
		(width 0.0889)
		(layer "B.Cu")
		(net "NC_SPI_S3M_CPU1_IO3_LVC1_R")
	)
	(arc
		(start 102.620064 -264.184638)
		(mid 102.343589 -264.251958)
		(end 102.069392 -264.176002)
		(width 0.0889)
		(layer "B.Cu")
		(net "NC_SPI_S3M_CPU1_IO3_LVC1_R")
	)
	(arc
		(start 103.47325 -264.986262)
		(mid 103.270663 -264.779911)
		(end 103.196644 -264.50036)
		(width 0.0889)
		(layer "B.Cu")
		(net "NC_SPI_S3M_CPU1_IO3_LVC1_R")
	)
	(arc
		(start 98.865182 -264.182098)
		(mid 98.587004 -264.251821)
		(end 98.310446 -264.176002)
		(width 0.0889)
		(layer "B.Cu")
		(net "NC_SPI_S3M_CPU1_IO3_LVC1_R")
	)
	(arc
		(start 101.694996 -264.176002)
		(mid 101.412294 -264.251778)
		(end 101.129592 -264.176002)
		(width 0.0889)
		(layer "B.Cu")
		(net "NC_SPI_S3M_CPU1_IO3_LVC1_R")
	)
	(arc
		(start 88.537796 -264.176002)
		(mid 88.255094 -264.251778)
		(end 87.972392 -264.176002)
		(width 0.0889)
		(layer "B.Cu")
		(net "NC_SPI_S3M_CPU1_IO3_LVC1_R")
	)
	(arc
		(start 89.851992 -264.176002)
		(mid 89.664794 -264.125859)
		(end 89.477596 -264.176002)
		(width 0.0889)
		(layer "B.Cu")
		(net "NC_SPI_S3M_CPU1_IO3_LVC1_R")
	)
	(arc
		(start 94.550992 -264.176002)
		(mid 94.363794 -264.125859)
		(end 94.176596 -264.176002)
		(width 0.0889)
		(layer "B.Cu")
		(net "NC_SPI_S3M_CPU1_IO3_LVC1_R")
	)
	(arc
		(start 91.347036 -264.182098)
		(mid 91.068604 -264.251944)
		(end 90.791792 -264.176002)
		(width 0.0889)
		(layer "B.Cu")
		(net "NC_SPI_S3M_CPU1_IO3_LVC1_R")
	)
	(arc
		(start 102.069392 -264.176002)
		(mid 101.882194 -264.125859)
		(end 101.694996 -264.176002)
		(width 0.0889)
		(layer "B.Cu")
		(net "NC_SPI_S3M_CPU1_IO3_LVC1_R")
	)
	(arc
		(start 87.972392 -264.176002)
		(mid 87.88212 -264.138403)
		(end 87.785194 -264.125456)
		(width 0.0889)
		(layer "B.Cu")
		(net "NC_SPI_S3M_CPU1_IO3_LVC1_R")
	)
	(arc
		(start 100.189792 -264.176002)
		(mid 100.002594 -264.125859)
		(end 99.815396 -264.176002)
		(width 0.0889)
		(layer "B.Cu")
		(net "NC_SPI_S3M_CPU1_IO3_LVC1_R")
	)
	(arc
		(start 104.793288 -265.379962)
		(mid 104.706 -265.621918)
		(end 104.520492 -265.800078)
		(width 0.0889)
		(layer "B.Cu")
		(net "NC_SPI_S3M_CPU1_IO3_LVC1_R")
	)
	(segment
		(start 105.171748 -268.034008)
		(end 105.171748 -268.569694)
		(width 0.12954)
		(layer "F.Cu")
		(net "NC_SPI_S3M_CPU1_IO2_LVC1_R")
	)
	(segment
		(start 105.171494 -268.033754)
		(end 105.171748 -268.034008)
		(width 0.12954)
		(layer "F.Cu")
		(net "NC_SPI_S3M_CPU1_IO2_LVC1_R")
	)
	(via
		(at 105.171748 -268.569694)
		(size 0.4572)
		(drill 0.2032)
		(layers "F.Cu" "B.Cu")
		(net "NC_SPI_S3M_CPU1_IO2_LVC1_R")
	)
	(via
		(at 75.337416 -261.527036)
		(size 0.6604)
		(drill 0.3302)
		(layers "F.Cu" "B.Cu")
		(net "NC_SPI_S3M_CPU1_IO2_LVC1_R")
	)
	(segment
		(start 105.171748 -268.569694)
		(end 105.015284 -268.298676)
		(width 0.0889)
		(layer "B.Cu")
		(net "NC_SPI_S3M_CPU1_IO2_LVC1_R")
	)
	(segment
		(start 104.433878 -268.253972)
		(end 104.419146 -268.245336)
		(width 0.0889)
		(layer "B.Cu")
		(net "NC_SPI_S3M_CPU1_IO2_LVC1_R")
	)
	(segment
		(start 80.32369 -266.51331)
		(end 75.337416 -261.527036)
		(width 0.12954)
		(layer "B.Cu")
		(net "NC_SPI_S3M_CPU1_IO2_LVC1_R")
	)
	(segment
		(start 105.015284 -268.298676)
		(end 104.92613 -268.2748)
		(width 0.0889)
		(layer "B.Cu")
		(net "NC_SPI_S3M_CPU1_IO2_LVC1_R")
	)
	(segment
		(start 81.80832 -266.51331)
		(end 80.32369 -266.51331)
		(width 0.12954)
		(layer "B.Cu")
		(net "NC_SPI_S3M_CPU1_IO2_LVC1_R")
	)
	(segment
		(start 104.419146 -268.245336)
		(end 104.41305 -268.24178)
		(width 0.0889)
		(layer "B.Cu")
		(net "NC_SPI_S3M_CPU1_IO2_LVC1_R")
	)
	(segment
		(start 102.726998 -265.32967)
		(end 102.726998 -265.314176)
		(width 0.0889)
		(layer "B.Cu")
		(net "NC_SPI_S3M_CPU1_IO2_LVC1_R")
	)
	(segment
		(start 93.156278 -264.998454)
		(end 93.141546 -264.989818)
		(width 0.0889)
		(layer "B.Cu")
		(net "NC_SPI_S3M_CPU1_IO2_LVC1_R")
	)
	(segment
		(start 101.614478 -264.998454)
		(end 101.599746 -264.989818)
		(width 0.0889)
		(layer "B.Cu")
		(net "NC_SPI_S3M_CPU1_IO2_LVC1_R")
	)
	(segment
		(start 103.957882 -267.4366)
		(end 103.948992 -267.43152)
		(width 0.0889)
		(layer "B.Cu")
		(net "NC_SPI_S3M_CPU1_IO2_LVC1_R")
	)
	(segment
		(start 90.332306 -264.995914)
		(end 90.321892 -264.989818)
		(width 0.0889)
		(layer "B.Cu")
		(net "NC_SPI_S3M_CPU1_IO2_LVC1_R")
	)
	(segment
		(start 98.405696 -264.989818)
		(end 98.395282 -264.995914)
		(width 0.0889)
		(layer "B.Cu")
		(net "NC_SPI_S3M_CPU1_IO2_LVC1_R")
	)
	(segment
		(start 92.211906 -264.995914)
		(end 92.201492 -264.989818)
		(width 0.0889)
		(layer "B.Cu")
		(net "NC_SPI_S3M_CPU1_IO2_LVC1_R")
	)
	(segment
		(start 94.096078 -264.998454)
		(end 94.081346 -264.989818)
		(width 0.0889)
		(layer "B.Cu")
		(net "NC_SPI_S3M_CPU1_IO2_LVC1_R")
	)
	(segment
		(start 98.790506 -264.995914)
		(end 98.780092 -264.989818)
		(width 0.0889)
		(layer "B.Cu")
		(net "NC_SPI_S3M_CPU1_IO2_LVC1_R")
	)
	(segment
		(start 103.018082 -265.808714)
		(end 103.009192 -265.803634)
		(width 0.0889)
		(layer "B.Cu")
		(net "NC_SPI_S3M_CPU1_IO2_LVC1_R")
	)
	(segment
		(start 103.479346 -266.61745)
		(end 103.47325 -266.613894)
		(width 0.0889)
		(layer "B.Cu")
		(net "NC_SPI_S3M_CPU1_IO2_LVC1_R")
	)
	(segment
		(start 99.734878 -264.998454)
		(end 99.720146 -264.989818)
		(width 0.0889)
		(layer "B.Cu")
		(net "NC_SPI_S3M_CPU1_IO2_LVC1_R")
	)
	(segment
		(start 95.975678 -264.998454)
		(end 95.960946 -264.989818)
		(width 0.0889)
		(layer "B.Cu")
		(net "NC_SPI_S3M_CPU1_IO2_LVC1_R")
	)
	(segment
		(start 86.75497 -265.344656)
		(end 85.58657 -266.513056)
		(width 0.12954)
		(layer "B.Cu")
		(net "NC_SPI_S3M_CPU1_IO2_LVC1_R")
	)
	(segment
		(start 95.035878 -264.998454)
		(end 95.021146 -264.989818)
		(width 0.0889)
		(layer "B.Cu")
		(net "NC_SPI_S3M_CPU1_IO2_LVC1_R")
	)
	(segment
		(start 85.58657 -266.513056)
		(end 81.808574 -266.513056)
		(width 0.12954)
		(layer "B.Cu")
		(net "NC_SPI_S3M_CPU1_IO2_LVC1_R")
	)
	(segment
		(start 91.827096 -264.989818)
		(end 91.816682 -264.995914)
		(width 0.0889)
		(layer "B.Cu")
		(net "NC_SPI_S3M_CPU1_IO2_LVC1_R")
	)
	(segment
		(start 96.915478 -264.998454)
		(end 96.900746 -264.989818)
		(width 0.0889)
		(layer "B.Cu")
		(net "NC_SPI_S3M_CPU1_IO2_LVC1_R")
	)
	(segment
		(start 103.666544 -266.96035)
		(end 103.666544 -266.933172)
		(width 0.0889)
		(layer "B.Cu")
		(net "NC_SPI_S3M_CPU1_IO2_LVC1_R")
	)
	(segment
		(start 87.050372 -265.049254)
		(end 86.75497 -265.344656)
		(width 0.0889)
		(layer "B.Cu")
		(net "NC_SPI_S3M_CPU1_IO2_LVC1_R")
	)
	(segment
		(start 81.808574 -266.513056)
		(end 81.80832 -266.51331)
		(width 0.12954)
		(layer "B.Cu")
		(net "NC_SPI_S3M_CPU1_IO2_LVC1_R")
	)
	(segment
		(start 100.674678 -264.998454)
		(end 100.659946 -264.989818)
		(width 0.0889)
		(layer "B.Cu")
		(net "NC_SPI_S3M_CPU1_IO2_LVC1_R")
	)
	(arc
		(start 90.88755 -264.989818)
		(mid 90.610737 -265.065688)
		(end 90.332306 -264.995914)
		(width 0.0889)
		(layer "B.Cu")
		(net "NC_SPI_S3M_CPU1_IO2_LVC1_R")
	)
	(arc
		(start 98.780092 -264.989818)
		(mid 98.592894 -264.939675)
		(end 98.405696 -264.989818)
		(width 0.0889)
		(layer "B.Cu")
		(net "NC_SPI_S3M_CPU1_IO2_LVC1_R")
	)
	(arc
		(start 90.321892 -264.989818)
		(mid 90.134694 -264.939675)
		(end 89.947496 -264.989818)
		(width 0.0889)
		(layer "B.Cu")
		(net "NC_SPI_S3M_CPU1_IO2_LVC1_R")
	)
	(arc
		(start 92.201492 -264.989818)
		(mid 92.014294 -264.939675)
		(end 91.827096 -264.989818)
		(width 0.0889)
		(layer "B.Cu")
		(net "NC_SPI_S3M_CPU1_IO2_LVC1_R")
	)
	(arc
		(start 103.196644 -266.127992)
		(mid 103.148965 -265.945092)
		(end 103.018082 -265.808714)
		(width 0.0889)
		(layer "B.Cu")
		(net "NC_SPI_S3M_CPU1_IO2_LVC1_R")
	)
	(arc
		(start 89.007696 -264.989818)
		(mid 88.724994 -265.065594)
		(end 88.442292 -264.989818)
		(width 0.0889)
		(layer "B.Cu")
		(net "NC_SPI_S3M_CPU1_IO2_LVC1_R")
	)
	(arc
		(start 104.41305 -268.24178)
		(mid 104.210463 -268.035429)
		(end 104.136444 -267.755878)
		(width 0.0889)
		(layer "B.Cu")
		(net "NC_SPI_S3M_CPU1_IO2_LVC1_R")
	)
	(arc
		(start 102.16515 -264.989818)
		(mid 101.890951 -265.065653)
		(end 101.614478 -264.998454)
		(width 0.0889)
		(layer "B.Cu")
		(net "NC_SPI_S3M_CPU1_IO2_LVC1_R")
	)
	(arc
		(start 97.46615 -264.989818)
		(mid 97.191951 -265.065653)
		(end 96.915478 -264.998454)
		(width 0.0889)
		(layer "B.Cu")
		(net "NC_SPI_S3M_CPU1_IO2_LVC1_R")
	)
	(arc
		(start 104.92613 -268.2748)
		(mid 104.677625 -268.320787)
		(end 104.433878 -268.253972)
		(width 0.0889)
		(layer "B.Cu")
		(net "NC_SPI_S3M_CPU1_IO2_LVC1_R")
	)
	(arc
		(start 96.52635 -264.989818)
		(mid 96.252151 -265.065653)
		(end 95.975678 -264.998454)
		(width 0.0889)
		(layer "B.Cu")
		(net "NC_SPI_S3M_CPU1_IO2_LVC1_R")
	)
	(arc
		(start 101.599746 -264.989818)
		(mid 101.412548 -264.939675)
		(end 101.22535 -264.989818)
		(width 0.0889)
		(layer "B.Cu")
		(net "NC_SPI_S3M_CPU1_IO2_LVC1_R")
	)
	(arc
		(start 103.666544 -266.933172)
		(mid 103.614274 -266.750807)
		(end 103.479346 -266.61745)
		(width 0.0889)
		(layer "B.Cu")
		(net "NC_SPI_S3M_CPU1_IO2_LVC1_R")
	)
	(arc
		(start 91.261946 -264.989818)
		(mid 91.074748 -264.939675)
		(end 90.88755 -264.989818)
		(width 0.0889)
		(layer "B.Cu")
		(net "NC_SPI_S3M_CPU1_IO2_LVC1_R")
	)
	(arc
		(start 92.76715 -264.989818)
		(mid 92.490337 -265.065688)
		(end 92.211906 -264.995914)
		(width 0.0889)
		(layer "B.Cu")
		(net "NC_SPI_S3M_CPU1_IO2_LVC1_R")
	)
	(arc
		(start 95.021146 -264.989818)
		(mid 94.833948 -264.939675)
		(end 94.64675 -264.989818)
		(width 0.0889)
		(layer "B.Cu")
		(net "NC_SPI_S3M_CPU1_IO2_LVC1_R")
	)
	(arc
		(start 99.34575 -264.989818)
		(mid 99.068937 -265.065688)
		(end 98.790506 -264.995914)
		(width 0.0889)
		(layer "B.Cu")
		(net "NC_SPI_S3M_CPU1_IO2_LVC1_R")
	)
	(arc
		(start 89.382092 -264.989818)
		(mid 89.194894 -264.939675)
		(end 89.007696 -264.989818)
		(width 0.0889)
		(layer "B.Cu")
		(net "NC_SPI_S3M_CPU1_IO2_LVC1_R")
	)
	(arc
		(start 103.47325 -266.613894)
		(mid 103.270663 -266.407543)
		(end 103.196644 -266.127992)
		(width 0.0889)
		(layer "B.Cu")
		(net "NC_SPI_S3M_CPU1_IO2_LVC1_R")
	)
	(arc
		(start 93.70695 -264.989818)
		(mid 93.432751 -265.065653)
		(end 93.156278 -264.998454)
		(width 0.0889)
		(layer "B.Cu")
		(net "NC_SPI_S3M_CPU1_IO2_LVC1_R")
	)
	(arc
		(start 100.659946 -264.989818)
		(mid 100.472748 -264.939675)
		(end 100.28555 -264.989818)
		(width 0.0889)
		(layer "B.Cu")
		(net "NC_SPI_S3M_CPU1_IO2_LVC1_R")
	)
	(arc
		(start 88.442292 -264.989818)
		(mid 88.255094 -264.939675)
		(end 88.067896 -264.989818)
		(width 0.0889)
		(layer "B.Cu")
		(net "NC_SPI_S3M_CPU1_IO2_LVC1_R")
	)
	(arc
		(start 93.141546 -264.989818)
		(mid 92.954348 -264.939675)
		(end 92.76715 -264.989818)
		(width 0.0889)
		(layer "B.Cu")
		(net "NC_SPI_S3M_CPU1_IO2_LVC1_R")
	)
	(arc
		(start 104.136444 -267.755878)
		(mid 104.088765 -267.572978)
		(end 103.957882 -267.4366)
		(width 0.0889)
		(layer "B.Cu")
		(net "NC_SPI_S3M_CPU1_IO2_LVC1_R")
	)
	(arc
		(start 94.64675 -264.989818)
		(mid 94.372551 -265.065653)
		(end 94.096078 -264.998454)
		(width 0.0889)
		(layer "B.Cu")
		(net "NC_SPI_S3M_CPU1_IO2_LVC1_R")
	)
	(arc
		(start 103.009192 -265.803634)
		(mid 102.806369 -265.603403)
		(end 102.726998 -265.32967)
		(width 0.0889)
		(layer "B.Cu")
		(net "NC_SPI_S3M_CPU1_IO2_LVC1_R")
	)
	(arc
		(start 101.22535 -264.989818)
		(mid 100.951151 -265.065653)
		(end 100.674678 -264.998454)
		(width 0.0889)
		(layer "B.Cu")
		(net "NC_SPI_S3M_CPU1_IO2_LVC1_R")
	)
	(arc
		(start 95.58655 -264.989818)
		(mid 95.312351 -265.065653)
		(end 95.035878 -264.998454)
		(width 0.0889)
		(layer "B.Cu")
		(net "NC_SPI_S3M_CPU1_IO2_LVC1_R")
	)
	(arc
		(start 98.395282 -264.995914)
		(mid 98.117104 -265.065637)
		(end 97.840546 -264.989818)
		(width 0.0889)
		(layer "B.Cu")
		(net "NC_SPI_S3M_CPU1_IO2_LVC1_R")
	)
	(arc
		(start 99.720146 -264.989818)
		(mid 99.532948 -264.939675)
		(end 99.34575 -264.989818)
		(width 0.0889)
		(layer "B.Cu")
		(net "NC_SPI_S3M_CPU1_IO2_LVC1_R")
	)
	(arc
		(start 87.128096 -264.989818)
		(mid 87.087287 -265.01699)
		(end 87.050372 -265.049254)
		(width 0.0889)
		(layer "B.Cu")
		(net "NC_SPI_S3M_CPU1_IO2_LVC1_R")
	)
	(arc
		(start 95.960946 -264.989818)
		(mid 95.773748 -264.939675)
		(end 95.58655 -264.989818)
		(width 0.0889)
		(layer "B.Cu")
		(net "NC_SPI_S3M_CPU1_IO2_LVC1_R")
	)
	(arc
		(start 89.947496 -264.989818)
		(mid 89.664794 -265.065594)
		(end 89.382092 -264.989818)
		(width 0.0889)
		(layer "B.Cu")
		(net "NC_SPI_S3M_CPU1_IO2_LVC1_R")
	)
	(arc
		(start 91.816682 -264.995914)
		(mid 91.538504 -265.065637)
		(end 91.261946 -264.989818)
		(width 0.0889)
		(layer "B.Cu")
		(net "NC_SPI_S3M_CPU1_IO2_LVC1_R")
	)
	(arc
		(start 94.081346 -264.989818)
		(mid 93.894148 -264.939675)
		(end 93.70695 -264.989818)
		(width 0.0889)
		(layer "B.Cu")
		(net "NC_SPI_S3M_CPU1_IO2_LVC1_R")
	)
	(arc
		(start 100.28555 -264.989818)
		(mid 100.011351 -265.065653)
		(end 99.734878 -264.998454)
		(width 0.0889)
		(layer "B.Cu")
		(net "NC_SPI_S3M_CPU1_IO2_LVC1_R")
	)
	(arc
		(start 96.900746 -264.989818)
		(mid 96.713548 -264.939675)
		(end 96.52635 -264.989818)
		(width 0.0889)
		(layer "B.Cu")
		(net "NC_SPI_S3M_CPU1_IO2_LVC1_R")
	)
	(arc
		(start 103.948992 -267.43152)
		(mid 103.746706 -267.232539)
		(end 103.666544 -266.96035)
		(width 0.0889)
		(layer "B.Cu")
		(net "NC_SPI_S3M_CPU1_IO2_LVC1_R")
	)
	(arc
		(start 88.067896 -264.989818)
		(mid 87.785194 -265.065594)
		(end 87.502492 -264.989818)
		(width 0.0889)
		(layer "B.Cu")
		(net "NC_SPI_S3M_CPU1_IO2_LVC1_R")
	)
	(arc
		(start 97.840546 -264.989818)
		(mid 97.653348 -264.939675)
		(end 97.46615 -264.989818)
		(width 0.0889)
		(layer "B.Cu")
		(net "NC_SPI_S3M_CPU1_IO2_LVC1_R")
	)
	(arc
		(start 87.502492 -264.989818)
		(mid 87.315294 -264.939675)
		(end 87.128096 -264.989818)
		(width 0.0889)
		(layer "B.Cu")
		(net "NC_SPI_S3M_CPU1_IO2_LVC1_R")
	)
	(arc
		(start 102.726998 -265.314176)
		(mid 102.539699 -264.989735)
		(end 102.16515 -264.989818)
		(width 0.0889)
		(layer "B.Cu")
		(net "NC_SPI_S3M_CPU1_IO2_LVC1_R")
	)
	(segment
		(start 102.821994 -267.220192)
		(end 102.821994 -267.755878)
		(width 0.12954)
		(layer "F.Cu")
		(net "NC_SPI_S3M_CPU1_IO1_LVC1_R")
	)
	(segment
		(start 102.822248 -267.219938)
		(end 102.821994 -267.220192)
		(width 0.12954)
		(layer "F.Cu")
		(net "NC_SPI_S3M_CPU1_IO1_LVC1_R")
	)
	(via
		(at 102.821994 -267.755878)
		(size 0.4572)
		(drill 0.2032)
		(layers "F.Cu" "B.Cu")
		(net "NC_SPI_S3M_CPU1_IO1_LVC1_R")
	)
	(segment
		(start 103.761794 -265.592306)
		(end 103.762048 -265.592306)
		(width 0.12954)
		(layer "F.Cu")
		(net "NC_SPI_S3M_CPU1_IO0_LVC1_R")
	)
	(segment
		(start 103.761794 -266.128246)
		(end 103.761794 -265.592306)
		(width 0.12954)
		(layer "F.Cu")
		(net "NC_SPI_S3M_CPU1_IO0_LVC1_R")
	)
	(via
		(at 103.761794 -266.128246)
		(size 0.4572)
		(drill 0.2032)
		(layers "F.Cu" "B.Cu")
		(net "NC_SPI_S3M_CPU1_IO0_LVC1_R")
	)
	(segment
		(start 102.352094 -266.405868)
		(end 102.352094 -266.941554)
		(width 0.12954)
		(layer "F.Cu")
		(net "NC_SPI_S3M_CPU1_CS1_LVC1_R_N")
	)
	(segment
		(start 102.352094 -266.941554)
		(end 102.352348 -266.941808)
		(width 0.12954)
		(layer "F.Cu")
		(net "NC_SPI_S3M_CPU1_CS1_LVC1_R_N")
	)
	(via
		(at 102.352348 -266.941808)
		(size 0.4572)
		(drill 0.2032)
		(layers "F.Cu" "B.Cu")
		(net "NC_SPI_S3M_CPU1_CS1_LVC1_R_N")
	)
	(segment
		(start 104.231694 -264.778236)
		(end 104.231948 -264.77849)
		(width 0.12954)
		(layer "F.Cu")
		(net "NC_SPI_S3M_CPU1_CS0_LVC1_R_N")
	)
	(segment
		(start 104.231948 -264.77849)
		(end 104.231948 -265.314176)
		(width 0.12954)
		(layer "F.Cu")
		(net "NC_SPI_S3M_CPU1_CS0_LVC1_R_N")
	)
	(via
		(at 104.231948 -265.314176)
		(size 0.4572)
		(drill 0.2032)
		(layers "F.Cu" "B.Cu")
		(net "NC_SPI_S3M_CPU1_CS0_LVC1_R_N")
	)
	(via
		(at 81.553812 -263.69391)
		(size 0.6604)
		(drill 0.3302)
		(layers "F.Cu" "B.Cu")
		(net "NC_SPI_S3M_CPU1_CS0_LVC1_R_N")
	)
	(segment
		(start 103.580692 -264.828274)
		(end 103.57739 -264.826242)
		(width 0.0889)
		(layer "B.Cu")
		(net "NC_SPI_S3M_CPU1_CS0_LVC1_R_N")
	)
	(segment
		(start 93.236796 -262.548116)
		(end 93.222064 -262.556752)
		(width 0.0889)
		(layer "B.Cu")
		(net "NC_SPI_S3M_CPU1_CS0_LVC1_R_N")
	)
	(segment
		(start 104.04475 -265.638534)
		(end 104.044496 -265.63828)
		(width 0.0889)
		(layer "B.Cu")
		(net "NC_SPI_S3M_CPU1_CS0_LVC1_R_N")
	)
	(segment
		(start 103.387144 -264.50036)
		(end 103.387144 -263.847072)
		(width 0.0889)
		(layer "B.Cu")
		(net "NC_SPI_S3M_CPU1_CS0_LVC1_R_N")
	)
	(segment
		(start 95.116396 -262.548116)
		(end 95.101664 -262.556752)
		(width 0.0889)
		(layer "B.Cu")
		(net "NC_SPI_S3M_CPU1_CS0_LVC1_R_N")
	)
	(segment
		(start 104.428036 -265.633454)
		(end 104.419146 -265.638534)
		(width 0.0889)
		(layer "B.Cu")
		(net "NC_SPI_S3M_CPU1_CS0_LVC1_R_N")
	)
	(segment
		(start 92.296996 -262.548116)
		(end 92.282264 -262.556752)
		(width 0.0889)
		(layer "B.Cu")
		(net "NC_SPI_S3M_CPU1_CS0_LVC1_R_N")
	)
	(segment
		(start 96.056196 -262.548116)
		(end 96.041464 -262.556752)
		(width 0.0889)
		(layer "B.Cu")
		(net "NC_SPI_S3M_CPU1_CS0_LVC1_R_N")
	)
	(segment
		(start 84.16163 -263.69391)
		(end 81.553812 -263.69391)
		(width 0.12954)
		(layer "B.Cu")
		(net "NC_SPI_S3M_CPU1_CS0_LVC1_R_N")
	)
	(segment
		(start 94.176596 -262.548116)
		(end 94.161864 -262.556752)
		(width 0.0889)
		(layer "B.Cu")
		(net "NC_SPI_S3M_CPU1_CS0_LVC1_R_N")
	)
	(segment
		(start 101.694996 -262.548116)
		(end 101.680264 -262.556752)
		(width 0.0889)
		(layer "B.Cu")
		(net "NC_SPI_S3M_CPU1_CS0_LVC1_R_N")
	)
	(segment
		(start 97.38106 -262.554212)
		(end 97.370646 -262.548116)
		(width 0.0889)
		(layer "B.Cu")
		(net "NC_SPI_S3M_CPU1_CS0_LVC1_R_N")
	)
	(segment
		(start 99.815396 -262.548116)
		(end 99.800664 -262.556752)
		(width 0.0889)
		(layer "B.Cu")
		(net "NC_SPI_S3M_CPU1_CS0_LVC1_R_N")
	)
	(segment
		(start 103.387144 -263.847072)
		(end 102.14737 -262.607298)
		(width 0.0889)
		(layer "B.Cu")
		(net "NC_SPI_S3M_CPU1_CS0_LVC1_R_N")
	)
	(segment
		(start 89.477596 -262.548116)
		(end 89.462864 -262.556752)
		(width 0.0889)
		(layer "B.Cu")
		(net "NC_SPI_S3M_CPU1_CS0_LVC1_R_N")
	)
	(segment
		(start 88.00465 -262.773922)
		(end 85.081618 -262.773922)
		(width 0.12954)
		(layer "B.Cu")
		(net "NC_SPI_S3M_CPU1_CS0_LVC1_R_N")
	)
	(segment
		(start 89.862406 -262.554212)
		(end 89.851992 -262.548116)
		(width 0.0889)
		(layer "B.Cu")
		(net "NC_SPI_S3M_CPU1_CS0_LVC1_R_N")
	)
	(segment
		(start 88.154764 -262.623808)
		(end 88.00465 -262.773922)
		(width 0.0889)
		(layer "B.Cu")
		(net "NC_SPI_S3M_CPU1_CS0_LVC1_R_N")
	)
	(segment
		(start 104.544622 -265.314176)
		(end 104.602026 -265.37158)
		(width 0.0889)
		(layer "B.Cu")
		(net "NC_SPI_S3M_CPU1_CS0_LVC1_R_N")
	)
	(segment
		(start 103.57739 -264.826242)
		(end 103.574596 -264.824718)
		(width 0.0889)
		(layer "B.Cu")
		(net "NC_SPI_S3M_CPU1_CS0_LVC1_R_N")
	)
	(segment
		(start 103.574596 -264.824718)
		(end 103.565706 -264.819638)
		(width 0.0889)
		(layer "B.Cu")
		(net "NC_SPI_S3M_CPU1_CS0_LVC1_R_N")
	)
	(segment
		(start 90.80246 -262.554212)
		(end 90.792046 -262.548116)
		(width 0.0889)
		(layer "B.Cu")
		(net "NC_SPI_S3M_CPU1_CS0_LVC1_R_N")
	)
	(segment
		(start 96.99625 -262.548116)
		(end 96.985836 -262.554212)
		(width 0.0889)
		(layer "B.Cu")
		(net "NC_SPI_S3M_CPU1_CS0_LVC1_R_N")
	)
	(segment
		(start 104.231948 -265.314176)
		(end 104.544622 -265.314176)
		(width 0.0889)
		(layer "B.Cu")
		(net "NC_SPI_S3M_CPU1_CS0_LVC1_R_N")
	)
	(segment
		(start 100.755196 -262.548116)
		(end 100.740464 -262.556752)
		(width 0.0889)
		(layer "B.Cu")
		(net "NC_SPI_S3M_CPU1_CS0_LVC1_R_N")
	)
	(segment
		(start 98.875596 -262.548116)
		(end 98.860864 -262.556752)
		(width 0.0889)
		(layer "B.Cu")
		(net "NC_SPI_S3M_CPU1_CS0_LVC1_R_N")
	)
	(segment
		(start 88.255094 -262.623808)
		(end 88.154764 -262.623808)
		(width 0.0889)
		(layer "B.Cu")
		(net "NC_SPI_S3M_CPU1_CS0_LVC1_R_N")
	)
	(segment
		(start 85.081618 -262.773922)
		(end 84.16163 -263.69391)
		(width 0.12954)
		(layer "B.Cu")
		(net "NC_SPI_S3M_CPU1_CS0_LVC1_R_N")
	)
	(arc
		(start 97.370646 -262.548116)
		(mid 97.183448 -262.497973)
		(end 96.99625 -262.548116)
		(width 0.0889)
		(layer "B.Cu")
		(net "NC_SPI_S3M_CPU1_CS0_LVC1_R_N")
	)
	(arc
		(start 92.282264 -262.556752)
		(mid 92.005789 -262.624072)
		(end 91.731592 -262.548116)
		(width 0.0889)
		(layer "B.Cu")
		(net "NC_SPI_S3M_CPU1_CS0_LVC1_R_N")
	)
	(arc
		(start 100.740464 -262.556752)
		(mid 100.463989 -262.624072)
		(end 100.189792 -262.548116)
		(width 0.0889)
		(layer "B.Cu")
		(net "NC_SPI_S3M_CPU1_CS0_LVC1_R_N")
	)
	(arc
		(start 103.857298 -265.314176)
		(mid 103.783307 -265.03461)
		(end 103.580692 -264.828274)
		(width 0.0889)
		(layer "B.Cu")
		(net "NC_SPI_S3M_CPU1_CS0_LVC1_R_N")
	)
	(arc
		(start 96.985836 -262.554212)
		(mid 96.707404 -262.624058)
		(end 96.430592 -262.548116)
		(width 0.0889)
		(layer "B.Cu")
		(net "NC_SPI_S3M_CPU1_CS0_LVC1_R_N")
	)
	(arc
		(start 97.935796 -262.548116)
		(mid 97.659237 -262.623859)
		(end 97.38106 -262.554212)
		(width 0.0889)
		(layer "B.Cu")
		(net "NC_SPI_S3M_CPU1_CS0_LVC1_R_N")
	)
	(arc
		(start 96.041464 -262.556752)
		(mid 95.764989 -262.624072)
		(end 95.490792 -262.548116)
		(width 0.0889)
		(layer "B.Cu")
		(net "NC_SPI_S3M_CPU1_CS0_LVC1_R_N")
	)
	(arc
		(start 104.419146 -265.638534)
		(mid 104.231948 -265.688677)
		(end 104.04475 -265.638534)
		(width 0.0889)
		(layer "B.Cu")
		(net "NC_SPI_S3M_CPU1_CS0_LVC1_R_N")
	)
	(arc
		(start 102.069392 -262.548116)
		(mid 101.882194 -262.497973)
		(end 101.694996 -262.548116)
		(width 0.0889)
		(layer "B.Cu")
		(net "NC_SPI_S3M_CPU1_CS0_LVC1_R_N")
	)
	(arc
		(start 94.550992 -262.548116)
		(mid 94.363794 -262.497973)
		(end 94.176596 -262.548116)
		(width 0.0889)
		(layer "B.Cu")
		(net "NC_SPI_S3M_CPU1_CS0_LVC1_R_N")
	)
	(arc
		(start 94.161864 -262.556752)
		(mid 93.885389 -262.624072)
		(end 93.611192 -262.548116)
		(width 0.0889)
		(layer "B.Cu")
		(net "NC_SPI_S3M_CPU1_CS0_LVC1_R_N")
	)
	(arc
		(start 96.430592 -262.548116)
		(mid 96.243394 -262.497973)
		(end 96.056196 -262.548116)
		(width 0.0889)
		(layer "B.Cu")
		(net "NC_SPI_S3M_CPU1_CS0_LVC1_R_N")
	)
	(arc
		(start 88.537796 -262.548116)
		(mid 88.401427 -262.604558)
		(end 88.255094 -262.623808)
		(width 0.0889)
		(layer "B.Cu")
		(net "NC_SPI_S3M_CPU1_CS0_LVC1_R_N")
	)
	(arc
		(start 95.101664 -262.556752)
		(mid 94.825189 -262.624072)
		(end 94.550992 -262.548116)
		(width 0.0889)
		(layer "B.Cu")
		(net "NC_SPI_S3M_CPU1_CS0_LVC1_R_N")
	)
	(arc
		(start 103.565706 -264.819638)
		(mid 103.434792 -264.683278)
		(end 103.387144 -264.50036)
		(width 0.0889)
		(layer "B.Cu")
		(net "NC_SPI_S3M_CPU1_CS0_LVC1_R_N")
	)
	(arc
		(start 95.490792 -262.548116)
		(mid 95.303594 -262.497973)
		(end 95.116396 -262.548116)
		(width 0.0889)
		(layer "B.Cu")
		(net "NC_SPI_S3M_CPU1_CS0_LVC1_R_N")
	)
	(arc
		(start 99.249992 -262.548116)
		(mid 99.062794 -262.497973)
		(end 98.875596 -262.548116)
		(width 0.0889)
		(layer "B.Cu")
		(net "NC_SPI_S3M_CPU1_CS0_LVC1_R_N")
	)
	(arc
		(start 99.800664 -262.556752)
		(mid 99.524189 -262.624072)
		(end 99.249992 -262.548116)
		(width 0.0889)
		(layer "B.Cu")
		(net "NC_SPI_S3M_CPU1_CS0_LVC1_R_N")
	)
	(arc
		(start 89.462864 -262.556752)
		(mid 89.186389 -262.624072)
		(end 88.912192 -262.548116)
		(width 0.0889)
		(layer "B.Cu")
		(net "NC_SPI_S3M_CPU1_CS0_LVC1_R_N")
	)
	(arc
		(start 104.602026 -265.37158)
		(mid 104.54387 -265.521693)
		(end 104.428036 -265.633454)
		(width 0.0889)
		(layer "B.Cu")
		(net "NC_SPI_S3M_CPU1_CS0_LVC1_R_N")
	)
	(arc
		(start 102.14737 -262.607298)
		(mid 102.11032 -262.575152)
		(end 102.069392 -262.548116)
		(width 0.0889)
		(layer "B.Cu")
		(net "NC_SPI_S3M_CPU1_CS0_LVC1_R_N")
	)
	(arc
		(start 100.189792 -262.548116)
		(mid 100.002594 -262.497973)
		(end 99.815396 -262.548116)
		(width 0.0889)
		(layer "B.Cu")
		(net "NC_SPI_S3M_CPU1_CS0_LVC1_R_N")
	)
	(arc
		(start 88.912192 -262.548116)
		(mid 88.724994 -262.497973)
		(end 88.537796 -262.548116)
		(width 0.0889)
		(layer "B.Cu")
		(net "NC_SPI_S3M_CPU1_CS0_LVC1_R_N")
	)
	(arc
		(start 98.860864 -262.556752)
		(mid 98.584389 -262.624072)
		(end 98.310192 -262.548116)
		(width 0.0889)
		(layer "B.Cu")
		(net "NC_SPI_S3M_CPU1_CS0_LVC1_R_N")
	)
	(arc
		(start 90.792046 -262.548116)
		(mid 90.604848 -262.497973)
		(end 90.41765 -262.548116)
		(width 0.0889)
		(layer "B.Cu")
		(net "NC_SPI_S3M_CPU1_CS0_LVC1_R_N")
	)
	(arc
		(start 93.611192 -262.548116)
		(mid 93.423994 -262.497973)
		(end 93.236796 -262.548116)
		(width 0.0889)
		(layer "B.Cu")
		(net "NC_SPI_S3M_CPU1_CS0_LVC1_R_N")
	)
	(arc
		(start 91.731592 -262.548116)
		(mid 91.544394 -262.497973)
		(end 91.357196 -262.548116)
		(width 0.0889)
		(layer "B.Cu")
		(net "NC_SPI_S3M_CPU1_CS0_LVC1_R_N")
	)
	(arc
		(start 91.357196 -262.548116)
		(mid 91.080637 -262.623859)
		(end 90.80246 -262.554212)
		(width 0.0889)
		(layer "B.Cu")
		(net "NC_SPI_S3M_CPU1_CS0_LVC1_R_N")
	)
	(arc
		(start 93.222064 -262.556752)
		(mid 92.945589 -262.624072)
		(end 92.671392 -262.548116)
		(width 0.0889)
		(layer "B.Cu")
		(net "NC_SPI_S3M_CPU1_CS0_LVC1_R_N")
	)
	(arc
		(start 98.310192 -262.548116)
		(mid 98.122994 -262.497973)
		(end 97.935796 -262.548116)
		(width 0.0889)
		(layer "B.Cu")
		(net "NC_SPI_S3M_CPU1_CS0_LVC1_R_N")
	)
	(arc
		(start 90.41765 -262.548116)
		(mid 90.140837 -262.623986)
		(end 89.862406 -262.554212)
		(width 0.0889)
		(layer "B.Cu")
		(net "NC_SPI_S3M_CPU1_CS0_LVC1_R_N")
	)
	(arc
		(start 104.044496 -265.63828)
		(mid 103.907451 -265.50132)
		(end 103.857298 -265.314176)
		(width 0.0889)
		(layer "B.Cu")
		(net "NC_SPI_S3M_CPU1_CS0_LVC1_R_N")
	)
	(arc
		(start 101.680264 -262.556752)
		(mid 101.403789 -262.624072)
		(end 101.129592 -262.548116)
		(width 0.0889)
		(layer "B.Cu")
		(net "NC_SPI_S3M_CPU1_CS0_LVC1_R_N")
	)
	(arc
		(start 101.129592 -262.548116)
		(mid 100.942394 -262.497973)
		(end 100.755196 -262.548116)
		(width 0.0889)
		(layer "B.Cu")
		(net "NC_SPI_S3M_CPU1_CS0_LVC1_R_N")
	)
	(arc
		(start 92.671392 -262.548116)
		(mid 92.484194 -262.497973)
		(end 92.296996 -262.548116)
		(width 0.0889)
		(layer "B.Cu")
		(net "NC_SPI_S3M_CPU1_CS0_LVC1_R_N")
	)
	(arc
		(start 89.851992 -262.548116)
		(mid 89.664794 -262.497973)
		(end 89.477596 -262.548116)
		(width 0.0889)
		(layer "B.Cu")
		(net "NC_SPI_S3M_CPU1_CS0_LVC1_R_N")
	)
	(segment
		(start 104.701848 -267.755624)
		(end 104.701594 -267.755878)
		(width 0.12954)
		(layer "F.Cu")
		(net "NC_SPI_S3M_CPU1_CLK_LVC1_R")
	)
	(segment
		(start 104.701848 -267.219938)
		(end 104.701848 -267.755624)
		(width 0.12954)
		(layer "F.Cu")
		(net "NC_SPI_S3M_CPU1_CLK_LVC1_R")
	)
	(via
		(at 74.040238 -260.09473)
		(size 0.6604)
		(drill 0.3302)
		(layers "F.Cu" "B.Cu")
		(net "NC_SPI_S3M_CPU1_CLK_LVC1_R")
	)
	(via
		(at 104.701594 -267.755878)
		(size 0.4572)
		(drill 0.2032)
		(layers "F.Cu" "B.Cu")
		(net "NC_SPI_S3M_CPU1_CLK_LVC1_R")
	)
	(segment
		(start 101.694996 -264.824718)
		(end 101.680264 -264.816082)
		(width 0.0889)
		(layer "B.Cu")
		(net "NC_SPI_S3M_CPU1_CLK_LVC1_R")
	)
	(segment
		(start 99.815396 -264.824718)
		(end 99.800664 -264.816082)
		(width 0.0889)
		(layer "B.Cu")
		(net "NC_SPI_S3M_CPU1_CLK_LVC1_R")
	)
	(segment
		(start 74.886058 -260.09473)
		(end 74.040238 -260.09473)
		(width 0.12954)
		(layer "B.Cu")
		(net "NC_SPI_S3M_CPU1_CLK_LVC1_R")
	)
	(segment
		(start 104.326944 -267.755878)
		(end 104.326944 -267.737336)
		(width 0.0889)
		(layer "B.Cu")
		(net "NC_SPI_S3M_CPU1_CLK_LVC1_R")
	)
	(segment
		(start 98.32086 -264.818622)
		(end 98.310446 -264.824718)
		(width 0.0889)
		(layer "B.Cu")
		(net "NC_SPI_S3M_CPU1_CLK_LVC1_R")
	)
	(segment
		(start 100.755196 -264.824718)
		(end 100.740464 -264.816082)
		(width 0.0889)
		(layer "B.Cu")
		(net "NC_SPI_S3M_CPU1_CLK_LVC1_R")
	)
	(segment
		(start 82.025998 -266.055856)
		(end 82.025744 -266.05611)
		(width 0.12954)
		(layer "B.Cu")
		(net "NC_SPI_S3M_CPU1_CLK_LVC1_R")
	)
	(segment
		(start 82.025744 -266.05611)
		(end 80.847438 -266.05611)
		(width 0.12954)
		(layer "B.Cu")
		(net "NC_SPI_S3M_CPU1_CLK_LVC1_R")
	)
	(segment
		(start 103.387144 -266.127992)
		(end 103.387144 -266.112498)
		(width 0.0889)
		(layer "B.Cu")
		(net "NC_SPI_S3M_CPU1_CLK_LVC1_R")
	)
	(segment
		(start 96.995996 -264.824718)
		(end 96.981264 -264.816082)
		(width 0.0889)
		(layer "B.Cu")
		(net "NC_SPI_S3M_CPU1_CLK_LVC1_R")
	)
	(segment
		(start 97.93605 -264.824718)
		(end 97.925636 -264.818622)
		(width 0.0889)
		(layer "B.Cu")
		(net "NC_SPI_S3M_CPU1_CLK_LVC1_R")
	)
	(segment
		(start 86.845394 -264.874756)
		(end 86.181184 -264.874756)
		(width 0.0889)
		(layer "B.Cu")
		(net "NC_SPI_S3M_CPU1_CLK_LVC1_R")
	)
	(segment
		(start 103.574596 -266.45235)
		(end 103.565706 -266.44727)
		(width 0.0889)
		(layer "B.Cu")
		(net "NC_SPI_S3M_CPU1_CLK_LVC1_R")
	)
	(segment
		(start 95.116396 -264.824718)
		(end 95.101664 -264.816082)
		(width 0.0889)
		(layer "B.Cu")
		(net "NC_SPI_S3M_CPU1_CLK_LVC1_R")
	)
	(segment
		(start 102.634796 -264.824718)
		(end 102.620064 -264.816082)
		(width 0.0889)
		(layer "B.Cu")
		(net "NC_SPI_S3M_CPU1_CLK_LVC1_R")
	)
	(segment
		(start 86.181184 -264.874756)
		(end 86.04885 -265.00709)
		(width 0.0889)
		(layer "B.Cu")
		(net "NC_SPI_S3M_CPU1_CLK_LVC1_R")
	)
	(segment
		(start 91.35745 -264.824718)
		(end 91.347036 -264.818622)
		(width 0.0889)
		(layer "B.Cu")
		(net "NC_SPI_S3M_CPU1_CLK_LVC1_R")
	)
	(segment
		(start 103.857298 -266.950444)
		(end 103.857298 -266.941808)
		(width 0.0889)
		(layer "B.Cu")
		(net "NC_SPI_S3M_CPU1_CLK_LVC1_R")
	)
	(segment
		(start 86.04885 -265.00709)
		(end 85.000084 -266.055856)
		(width 0.12954)
		(layer "B.Cu")
		(net "NC_SPI_S3M_CPU1_CLK_LVC1_R")
	)
	(segment
		(start 103.580692 -266.455906)
		(end 103.574596 -266.45235)
		(width 0.0889)
		(layer "B.Cu")
		(net "NC_SPI_S3M_CPU1_CLK_LVC1_R")
	)
	(segment
		(start 104.858058 -268.026896)
		(end 104.836976 -268.104874)
		(width 0.0889)
		(layer "B.Cu")
		(net "NC_SPI_S3M_CPU1_CLK_LVC1_R")
	)
	(segment
		(start 96.056196 -264.824718)
		(end 96.041464 -264.816082)
		(width 0.0889)
		(layer "B.Cu")
		(net "NC_SPI_S3M_CPU1_CLK_LVC1_R")
	)
	(segment
		(start 102.640892 -264.828274)
		(end 102.634796 -264.824718)
		(width 0.0889)
		(layer "B.Cu")
		(net "NC_SPI_S3M_CPU1_CLK_LVC1_R")
	)
	(segment
		(start 104.701594 -267.755878)
		(end 104.858058 -268.026896)
		(width 0.0889)
		(layer "B.Cu")
		(net "NC_SPI_S3M_CPU1_CLK_LVC1_R")
	)
	(segment
		(start 104.514396 -268.080236)
		(end 104.505506 -268.075156)
		(width 0.0889)
		(layer "B.Cu")
		(net "NC_SPI_S3M_CPU1_CLK_LVC1_R")
	)
	(segment
		(start 94.176596 -264.824718)
		(end 94.161864 -264.816082)
		(width 0.0889)
		(layer "B.Cu")
		(net "NC_SPI_S3M_CPU1_CLK_LVC1_R")
	)
	(segment
		(start 93.236796 -264.824718)
		(end 93.222064 -264.816082)
		(width 0.0889)
		(layer "B.Cu")
		(net "NC_SPI_S3M_CPU1_CLK_LVC1_R")
	)
	(segment
		(start 85.000084 -266.055856)
		(end 82.025998 -266.055856)
		(width 0.12954)
		(layer "B.Cu")
		(net "NC_SPI_S3M_CPU1_CLK_LVC1_R")
	)
	(segment
		(start 80.847438 -266.05611)
		(end 74.886058 -260.09473)
		(width 0.12954)
		(layer "B.Cu")
		(net "NC_SPI_S3M_CPU1_CLK_LVC1_R")
	)
	(segment
		(start 91.74226 -264.818622)
		(end 91.731846 -264.824718)
		(width 0.0889)
		(layer "B.Cu")
		(net "NC_SPI_S3M_CPU1_CLK_LVC1_R")
	)
	(segment
		(start 103.10495 -265.638534)
		(end 103.09606 -265.633454)
		(width 0.0889)
		(layer "B.Cu")
		(net "NC_SPI_S3M_CPU1_CLK_LVC1_R")
	)
	(arc
		(start 100.189792 -264.824718)
		(mid 100.002594 -264.874861)
		(end 99.815396 -264.824718)
		(width 0.0889)
		(layer "B.Cu")
		(net "NC_SPI_S3M_CPU1_CLK_LVC1_R")
	)
	(arc
		(start 91.347036 -264.818622)
		(mid 91.068604 -264.748776)
		(end 90.791792 -264.824718)
		(width 0.0889)
		(layer "B.Cu")
		(net "NC_SPI_S3M_CPU1_CLK_LVC1_R")
	)
	(arc
		(start 96.041464 -264.816082)
		(mid 95.764989 -264.748762)
		(end 95.490792 -264.824718)
		(width 0.0889)
		(layer "B.Cu")
		(net "NC_SPI_S3M_CPU1_CLK_LVC1_R")
	)
	(arc
		(start 104.044496 -267.266166)
		(mid 103.909563 -267.132812)
		(end 103.857298 -266.950444)
		(width 0.0889)
		(layer "B.Cu")
		(net "NC_SPI_S3M_CPU1_CLK_LVC1_R")
	)
	(arc
		(start 97.370392 -264.824718)
		(mid 97.183194 -264.874861)
		(end 96.995996 -264.824718)
		(width 0.0889)
		(layer "B.Cu")
		(net "NC_SPI_S3M_CPU1_CLK_LVC1_R")
	)
	(arc
		(start 87.032592 -264.824718)
		(mid 86.942285 -264.862047)
		(end 86.845394 -264.874756)
		(width 0.0889)
		(layer "B.Cu")
		(net "NC_SPI_S3M_CPU1_CLK_LVC1_R")
	)
	(arc
		(start 101.680264 -264.816082)
		(mid 101.403789 -264.748762)
		(end 101.129592 -264.824718)
		(width 0.0889)
		(layer "B.Cu")
		(net "NC_SPI_S3M_CPU1_CLK_LVC1_R")
	)
	(arc
		(start 87.972392 -264.824718)
		(mid 87.785194 -264.874861)
		(end 87.597996 -264.824718)
		(width 0.0889)
		(layer "B.Cu")
		(net "NC_SPI_S3M_CPU1_CLK_LVC1_R")
	)
	(arc
		(start 102.069392 -264.824718)
		(mid 101.882194 -264.874861)
		(end 101.694996 -264.824718)
		(width 0.0889)
		(layer "B.Cu")
		(net "NC_SPI_S3M_CPU1_CLK_LVC1_R")
	)
	(arc
		(start 89.851992 -264.824718)
		(mid 89.664794 -264.874861)
		(end 89.477596 -264.824718)
		(width 0.0889)
		(layer "B.Cu")
		(net "NC_SPI_S3M_CPU1_CLK_LVC1_R")
	)
	(arc
		(start 90.791792 -264.824718)
		(mid 90.604594 -264.874861)
		(end 90.417396 -264.824718)
		(width 0.0889)
		(layer "B.Cu")
		(net "NC_SPI_S3M_CPU1_CLK_LVC1_R")
	)
	(arc
		(start 104.505506 -268.075156)
		(mid 104.374592 -267.938796)
		(end 104.326944 -267.755878)
		(width 0.0889)
		(layer "B.Cu")
		(net "NC_SPI_S3M_CPU1_CLK_LVC1_R")
	)
	(arc
		(start 98.310446 -264.824718)
		(mid 98.123248 -264.874861)
		(end 97.93605 -264.824718)
		(width 0.0889)
		(layer "B.Cu")
		(net "NC_SPI_S3M_CPU1_CLK_LVC1_R")
	)
	(arc
		(start 94.550992 -264.824718)
		(mid 94.363794 -264.874861)
		(end 94.176596 -264.824718)
		(width 0.0889)
		(layer "B.Cu")
		(net "NC_SPI_S3M_CPU1_CLK_LVC1_R")
	)
	(arc
		(start 92.671392 -264.824718)
		(mid 92.484194 -264.874861)
		(end 92.296996 -264.824718)
		(width 0.0889)
		(layer "B.Cu")
		(net "NC_SPI_S3M_CPU1_CLK_LVC1_R")
	)
	(arc
		(start 100.740464 -264.816082)
		(mid 100.463989 -264.748762)
		(end 100.189792 -264.824718)
		(width 0.0889)
		(layer "B.Cu")
		(net "NC_SPI_S3M_CPU1_CLK_LVC1_R")
	)
	(arc
		(start 103.09606 -265.633454)
		(mid 102.965146 -265.497094)
		(end 102.917498 -265.314176)
		(width 0.0889)
		(layer "B.Cu")
		(net "NC_SPI_S3M_CPU1_CLK_LVC1_R")
	)
	(arc
		(start 90.417396 -264.824718)
		(mid 90.134694 -264.748942)
		(end 89.851992 -264.824718)
		(width 0.0889)
		(layer "B.Cu")
		(net "NC_SPI_S3M_CPU1_CLK_LVC1_R")
	)
	(arc
		(start 88.912192 -264.824718)
		(mid 88.724994 -264.874861)
		(end 88.537796 -264.824718)
		(width 0.0889)
		(layer "B.Cu")
		(net "NC_SPI_S3M_CPU1_CLK_LVC1_R")
	)
	(arc
		(start 99.800664 -264.816082)
		(mid 99.524189 -264.748762)
		(end 99.249992 -264.824718)
		(width 0.0889)
		(layer "B.Cu")
		(net "NC_SPI_S3M_CPU1_CLK_LVC1_R")
	)
	(arc
		(start 104.326944 -267.737336)
		(mid 104.246782 -267.465147)
		(end 104.044496 -267.266166)
		(width 0.0889)
		(layer "B.Cu")
		(net "NC_SPI_S3M_CPU1_CLK_LVC1_R")
	)
	(arc
		(start 102.620064 -264.816082)
		(mid 102.343589 -264.748762)
		(end 102.069392 -264.824718)
		(width 0.0889)
		(layer "B.Cu")
		(net "NC_SPI_S3M_CPU1_CLK_LVC1_R")
	)
	(arc
		(start 96.430592 -264.824718)
		(mid 96.243394 -264.874861)
		(end 96.056196 -264.824718)
		(width 0.0889)
		(layer "B.Cu")
		(net "NC_SPI_S3M_CPU1_CLK_LVC1_R")
	)
	(arc
		(start 89.477596 -264.824718)
		(mid 89.194894 -264.748942)
		(end 88.912192 -264.824718)
		(width 0.0889)
		(layer "B.Cu")
		(net "NC_SPI_S3M_CPU1_CLK_LVC1_R")
	)
	(arc
		(start 88.537796 -264.824718)
		(mid 88.255094 -264.748942)
		(end 87.972392 -264.824718)
		(width 0.0889)
		(layer "B.Cu")
		(net "NC_SPI_S3M_CPU1_CLK_LVC1_R")
	)
	(arc
		(start 93.222064 -264.816082)
		(mid 92.945589 -264.748762)
		(end 92.671392 -264.824718)
		(width 0.0889)
		(layer "B.Cu")
		(net "NC_SPI_S3M_CPU1_CLK_LVC1_R")
	)
	(arc
		(start 99.249992 -264.824718)
		(mid 99.062794 -264.874861)
		(end 98.875596 -264.824718)
		(width 0.0889)
		(layer "B.Cu")
		(net "NC_SPI_S3M_CPU1_CLK_LVC1_R")
	)
	(arc
		(start 98.875596 -264.824718)
		(mid 98.599037 -264.748975)
		(end 98.32086 -264.818622)
		(width 0.0889)
		(layer "B.Cu")
		(net "NC_SPI_S3M_CPU1_CLK_LVC1_R")
	)
	(arc
		(start 102.917498 -265.314176)
		(mid 102.843507 -265.03461)
		(end 102.640892 -264.828274)
		(width 0.0889)
		(layer "B.Cu")
		(net "NC_SPI_S3M_CPU1_CLK_LVC1_R")
	)
	(arc
		(start 95.101664 -264.816082)
		(mid 94.825189 -264.748762)
		(end 94.550992 -264.824718)
		(width 0.0889)
		(layer "B.Cu")
		(net "NC_SPI_S3M_CPU1_CLK_LVC1_R")
	)
	(arc
		(start 94.161864 -264.816082)
		(mid 93.885389 -264.748762)
		(end 93.611192 -264.824718)
		(width 0.0889)
		(layer "B.Cu")
		(net "NC_SPI_S3M_CPU1_CLK_LVC1_R")
	)
	(arc
		(start 103.565706 -266.44727)
		(mid 103.434792 -266.31091)
		(end 103.387144 -266.127992)
		(width 0.0889)
		(layer "B.Cu")
		(net "NC_SPI_S3M_CPU1_CLK_LVC1_R")
	)
	(arc
		(start 103.857298 -266.941808)
		(mid 103.783307 -266.662242)
		(end 103.580692 -266.455906)
		(width 0.0889)
		(layer "B.Cu")
		(net "NC_SPI_S3M_CPU1_CLK_LVC1_R")
	)
	(arc
		(start 103.387144 -266.112498)
		(mid 103.307774 -265.838764)
		(end 103.10495 -265.638534)
		(width 0.0889)
		(layer "B.Cu")
		(net "NC_SPI_S3M_CPU1_CLK_LVC1_R")
	)
	(arc
		(start 95.490792 -264.824718)
		(mid 95.303594 -264.874861)
		(end 95.116396 -264.824718)
		(width 0.0889)
		(layer "B.Cu")
		(net "NC_SPI_S3M_CPU1_CLK_LVC1_R")
	)
	(arc
		(start 97.925636 -264.818622)
		(mid 97.647204 -264.748776)
		(end 97.370392 -264.824718)
		(width 0.0889)
		(layer "B.Cu")
		(net "NC_SPI_S3M_CPU1_CLK_LVC1_R")
	)
	(arc
		(start 91.731846 -264.824718)
		(mid 91.544648 -264.874861)
		(end 91.35745 -264.824718)
		(width 0.0889)
		(layer "B.Cu")
		(net "NC_SPI_S3M_CPU1_CLK_LVC1_R")
	)
	(arc
		(start 96.981264 -264.816082)
		(mid 96.704789 -264.748762)
		(end 96.430592 -264.824718)
		(width 0.0889)
		(layer "B.Cu")
		(net "NC_SPI_S3M_CPU1_CLK_LVC1_R")
	)
	(arc
		(start 104.836976 -268.104874)
		(mid 104.67288 -268.129221)
		(end 104.514396 -268.080236)
		(width 0.0889)
		(layer "B.Cu")
		(net "NC_SPI_S3M_CPU1_CLK_LVC1_R")
	)
	(arc
		(start 93.611192 -264.824718)
		(mid 93.423994 -264.874861)
		(end 93.236796 -264.824718)
		(width 0.0889)
		(layer "B.Cu")
		(net "NC_SPI_S3M_CPU1_CLK_LVC1_R")
	)
	(arc
		(start 101.129592 -264.824718)
		(mid 100.942394 -264.874861)
		(end 100.755196 -264.824718)
		(width 0.0889)
		(layer "B.Cu")
		(net "NC_SPI_S3M_CPU1_CLK_LVC1_R")
	)
	(arc
		(start 87.597996 -264.824718)
		(mid 87.315294 -264.748942)
		(end 87.032592 -264.824718)
		(width 0.0889)
		(layer "B.Cu")
		(net "NC_SPI_S3M_CPU1_CLK_LVC1_R")
	)
	(arc
		(start 92.296996 -264.824718)
		(mid 92.020437 -264.748975)
		(end 91.74226 -264.818622)
		(width 0.0889)
		(layer "B.Cu")
		(net "NC_SPI_S3M_CPU1_CLK_LVC1_R")
	)
	(segment
		(start 104.231694 -269.66164)
		(end 104.231948 -269.661894)
		(width 0.12954)
		(layer "F.Cu")
		(net "NC_SPI_CPU1_NCM_OE_N")
	)
	(segment
		(start 104.231948 -269.661894)
		(end 104.231948 -270.19758)
		(width 0.12954)
		(layer "F.Cu")
		(net "NC_SPI_CPU1_NCM_OE_N")
	)
	(via
		(at 85.528658 -270.01597)
		(size 0.6604)
		(drill 0.3302)
		(layers "F.Cu" "B.Cu")
		(net "NC_SPI_CPU1_NCM_OE_N")
	)
	(via
		(at 104.231948 -270.19758)
		(size 0.4572)
		(drill 0.2032)
		(layers "F.Cu" "B.Cu")
		(net "NC_SPI_CPU1_NCM_OE_N")
	)
	(segment
		(start 99.734878 -270.513302)
		(end 99.720146 -270.521938)
		(width 0.0889)
		(layer "B.Cu")
		(net "NC_SPI_CPU1_NCM_OE_N")
	)
	(segment
		(start 103.494078 -270.513302)
		(end 103.479346 -270.521938)
		(width 0.0889)
		(layer "B.Cu")
		(net "NC_SPI_CPU1_NCM_OE_N")
	)
	(segment
		(start 104.075484 -270.468598)
		(end 103.98633 -270.492474)
		(width 0.0889)
		(layer "B.Cu")
		(net "NC_SPI_CPU1_NCM_OE_N")
	)
	(segment
		(start 98.790506 -270.515842)
		(end 98.780092 -270.521938)
		(width 0.0889)
		(layer "B.Cu")
		(net "NC_SPI_CPU1_NCM_OE_N")
	)
	(segment
		(start 97.85096 -270.515842)
		(end 97.840546 -270.521938)
		(width 0.0889)
		(layer "B.Cu")
		(net "NC_SPI_CPU1_NCM_OE_N")
	)
	(segment
		(start 86.86165 -270.38173)
		(end 86.107016 -270.38173)
		(width 0.0889)
		(layer "B.Cu")
		(net "NC_SPI_CPU1_NCM_OE_N")
	)
	(segment
		(start 93.156278 -270.513302)
		(end 93.141546 -270.521938)
		(width 0.0889)
		(layer "B.Cu")
		(net "NC_SPI_CPU1_NCM_OE_N")
	)
	(segment
		(start 95.975678 -270.513302)
		(end 95.960946 -270.521938)
		(width 0.0889)
		(layer "B.Cu")
		(net "NC_SPI_CPU1_NCM_OE_N")
	)
	(segment
		(start 96.915478 -270.513302)
		(end 96.900746 -270.521938)
		(width 0.0889)
		(layer "B.Cu")
		(net "NC_SPI_CPU1_NCM_OE_N")
	)
	(segment
		(start 95.035878 -270.513302)
		(end 95.021146 -270.521938)
		(width 0.0889)
		(layer "B.Cu")
		(net "NC_SPI_CPU1_NCM_OE_N")
	)
	(segment
		(start 91.27236 -270.515842)
		(end 91.261946 -270.521938)
		(width 0.0889)
		(layer "B.Cu")
		(net "NC_SPI_CPU1_NCM_OE_N")
	)
	(segment
		(start 104.231948 -270.19758)
		(end 104.075484 -270.468598)
		(width 0.0889)
		(layer "B.Cu")
		(net "NC_SPI_CPU1_NCM_OE_N")
	)
	(segment
		(start 90.332306 -270.515842)
		(end 90.321892 -270.521938)
		(width 0.0889)
		(layer "B.Cu")
		(net "NC_SPI_CPU1_NCM_OE_N")
	)
	(segment
		(start 86.107016 -270.38173)
		(end 85.894418 -270.38173)
		(width 0.12954)
		(layer "B.Cu")
		(net "NC_SPI_CPU1_NCM_OE_N")
	)
	(segment
		(start 102.554278 -270.513302)
		(end 102.539546 -270.521938)
		(width 0.0889)
		(layer "B.Cu")
		(net "NC_SPI_CPU1_NCM_OE_N")
	)
	(segment
		(start 87.128096 -270.521938)
		(end 86.906354 -270.393668)
		(width 0.0889)
		(layer "B.Cu")
		(net "NC_SPI_CPU1_NCM_OE_N")
	)
	(segment
		(start 85.894418 -270.38173)
		(end 85.528658 -270.01597)
		(width 0.12954)
		(layer "B.Cu")
		(net "NC_SPI_CPU1_NCM_OE_N")
	)
	(segment
		(start 92.211906 -270.515842)
		(end 92.201492 -270.521938)
		(width 0.0889)
		(layer "B.Cu")
		(net "NC_SPI_CPU1_NCM_OE_N")
	)
	(arc
		(start 103.10495 -270.521938)
		(mid 102.830751 -270.446103)
		(end 102.554278 -270.513302)
		(width 0.0889)
		(layer "B.Cu")
		(net "NC_SPI_CPU1_NCM_OE_N")
	)
	(arc
		(start 98.405696 -270.521938)
		(mid 98.129137 -270.446195)
		(end 97.85096 -270.515842)
		(width 0.0889)
		(layer "B.Cu")
		(net "NC_SPI_CPU1_NCM_OE_N")
	)
	(arc
		(start 88.067896 -270.521938)
		(mid 87.785194 -270.446162)
		(end 87.502492 -270.521938)
		(width 0.0889)
		(layer "B.Cu")
		(net "NC_SPI_CPU1_NCM_OE_N")
	)
	(arc
		(start 86.906354 -270.393668)
		(mid 86.884794 -270.384715)
		(end 86.86165 -270.38173)
		(width 0.0889)
		(layer "B.Cu")
		(net "NC_SPI_CPU1_NCM_OE_N")
	)
	(arc
		(start 93.141546 -270.521938)
		(mid 92.954348 -270.572081)
		(end 92.76715 -270.521938)
		(width 0.0889)
		(layer "B.Cu")
		(net "NC_SPI_CPU1_NCM_OE_N")
	)
	(arc
		(start 97.840546 -270.521938)
		(mid 97.653348 -270.572081)
		(end 97.46615 -270.521938)
		(width 0.0889)
		(layer "B.Cu")
		(net "NC_SPI_CPU1_NCM_OE_N")
	)
	(arc
		(start 103.479346 -270.521938)
		(mid 103.292148 -270.572081)
		(end 103.10495 -270.521938)
		(width 0.0889)
		(layer "B.Cu")
		(net "NC_SPI_CPU1_NCM_OE_N")
	)
	(arc
		(start 93.70695 -270.521938)
		(mid 93.432751 -270.446103)
		(end 93.156278 -270.513302)
		(width 0.0889)
		(layer "B.Cu")
		(net "NC_SPI_CPU1_NCM_OE_N")
	)
	(arc
		(start 96.900746 -270.521938)
		(mid 96.713548 -270.572081)
		(end 96.52635 -270.521938)
		(width 0.0889)
		(layer "B.Cu")
		(net "NC_SPI_CPU1_NCM_OE_N")
	)
	(arc
		(start 102.539546 -270.521938)
		(mid 102.352348 -270.572081)
		(end 102.16515 -270.521938)
		(width 0.0889)
		(layer "B.Cu")
		(net "NC_SPI_CPU1_NCM_OE_N")
	)
	(arc
		(start 97.46615 -270.521938)
		(mid 97.191951 -270.446103)
		(end 96.915478 -270.513302)
		(width 0.0889)
		(layer "B.Cu")
		(net "NC_SPI_CPU1_NCM_OE_N")
	)
	(arc
		(start 95.960946 -270.521938)
		(mid 95.773748 -270.572081)
		(end 95.58655 -270.521938)
		(width 0.0889)
		(layer "B.Cu")
		(net "NC_SPI_CPU1_NCM_OE_N")
	)
	(arc
		(start 96.52635 -270.521938)
		(mid 96.252151 -270.446103)
		(end 95.975678 -270.513302)
		(width 0.0889)
		(layer "B.Cu")
		(net "NC_SPI_CPU1_NCM_OE_N")
	)
	(arc
		(start 90.88755 -270.521938)
		(mid 90.610737 -270.446068)
		(end 90.332306 -270.515842)
		(width 0.0889)
		(layer "B.Cu")
		(net "NC_SPI_CPU1_NCM_OE_N")
	)
	(arc
		(start 91.827096 -270.521938)
		(mid 91.550537 -270.446195)
		(end 91.27236 -270.515842)
		(width 0.0889)
		(layer "B.Cu")
		(net "NC_SPI_CPU1_NCM_OE_N")
	)
	(arc
		(start 94.64675 -270.521938)
		(mid 94.364048 -270.446162)
		(end 94.081346 -270.521938)
		(width 0.0889)
		(layer "B.Cu")
		(net "NC_SPI_CPU1_NCM_OE_N")
	)
	(arc
		(start 95.021146 -270.521938)
		(mid 94.833948 -270.572081)
		(end 94.64675 -270.521938)
		(width 0.0889)
		(layer "B.Cu")
		(net "NC_SPI_CPU1_NCM_OE_N")
	)
	(arc
		(start 92.76715 -270.521938)
		(mid 92.490337 -270.446068)
		(end 92.211906 -270.515842)
		(width 0.0889)
		(layer "B.Cu")
		(net "NC_SPI_CPU1_NCM_OE_N")
	)
	(arc
		(start 89.007696 -270.521938)
		(mid 88.724994 -270.446162)
		(end 88.442292 -270.521938)
		(width 0.0889)
		(layer "B.Cu")
		(net "NC_SPI_CPU1_NCM_OE_N")
	)
	(arc
		(start 87.502492 -270.521938)
		(mid 87.315294 -270.572081)
		(end 87.128096 -270.521938)
		(width 0.0889)
		(layer "B.Cu")
		(net "NC_SPI_CPU1_NCM_OE_N")
	)
	(arc
		(start 101.599746 -270.521938)
		(mid 101.412548 -270.572081)
		(end 101.22535 -270.521938)
		(width 0.0889)
		(layer "B.Cu")
		(net "NC_SPI_CPU1_NCM_OE_N")
	)
	(arc
		(start 94.081346 -270.521938)
		(mid 93.894148 -270.572081)
		(end 93.70695 -270.521938)
		(width 0.0889)
		(layer "B.Cu")
		(net "NC_SPI_CPU1_NCM_OE_N")
	)
	(arc
		(start 100.28555 -270.521938)
		(mid 100.011351 -270.446103)
		(end 99.734878 -270.513302)
		(width 0.0889)
		(layer "B.Cu")
		(net "NC_SPI_CPU1_NCM_OE_N")
	)
	(arc
		(start 91.261946 -270.521938)
		(mid 91.074748 -270.572081)
		(end 90.88755 -270.521938)
		(width 0.0889)
		(layer "B.Cu")
		(net "NC_SPI_CPU1_NCM_OE_N")
	)
	(arc
		(start 89.382092 -270.521938)
		(mid 89.194894 -270.572081)
		(end 89.007696 -270.521938)
		(width 0.0889)
		(layer "B.Cu")
		(net "NC_SPI_CPU1_NCM_OE_N")
	)
	(arc
		(start 102.16515 -270.521938)
		(mid 101.882448 -270.446162)
		(end 101.599746 -270.521938)
		(width 0.0889)
		(layer "B.Cu")
		(net "NC_SPI_CPU1_NCM_OE_N")
	)
	(arc
		(start 95.58655 -270.521938)
		(mid 95.312351 -270.446103)
		(end 95.035878 -270.513302)
		(width 0.0889)
		(layer "B.Cu")
		(net "NC_SPI_CPU1_NCM_OE_N")
	)
	(arc
		(start 92.201492 -270.521938)
		(mid 92.014294 -270.572081)
		(end 91.827096 -270.521938)
		(width 0.0889)
		(layer "B.Cu")
		(net "NC_SPI_CPU1_NCM_OE_N")
	)
	(arc
		(start 98.780092 -270.521938)
		(mid 98.592894 -270.572081)
		(end 98.405696 -270.521938)
		(width 0.0889)
		(layer "B.Cu")
		(net "NC_SPI_CPU1_NCM_OE_N")
	)
	(arc
		(start 90.321892 -270.521938)
		(mid 90.134694 -270.572081)
		(end 89.947496 -270.521938)
		(width 0.0889)
		(layer "B.Cu")
		(net "NC_SPI_CPU1_NCM_OE_N")
	)
	(arc
		(start 99.720146 -270.521938)
		(mid 99.532948 -270.572081)
		(end 99.34575 -270.521938)
		(width 0.0889)
		(layer "B.Cu")
		(net "NC_SPI_CPU1_NCM_OE_N")
	)
	(arc
		(start 103.98633 -270.492474)
		(mid 103.737825 -270.446487)
		(end 103.494078 -270.513302)
		(width 0.0889)
		(layer "B.Cu")
		(net "NC_SPI_CPU1_NCM_OE_N")
	)
	(arc
		(start 101.22535 -270.521938)
		(mid 100.942648 -270.446162)
		(end 100.659946 -270.521938)
		(width 0.0889)
		(layer "B.Cu")
		(net "NC_SPI_CPU1_NCM_OE_N")
	)
	(arc
		(start 89.947496 -270.521938)
		(mid 89.664794 -270.446162)
		(end 89.382092 -270.521938)
		(width 0.0889)
		(layer "B.Cu")
		(net "NC_SPI_CPU1_NCM_OE_N")
	)
	(arc
		(start 100.659946 -270.521938)
		(mid 100.472748 -270.572081)
		(end 100.28555 -270.521938)
		(width 0.0889)
		(layer "B.Cu")
		(net "NC_SPI_CPU1_NCM_OE_N")
	)
	(arc
		(start 88.442292 -270.521938)
		(mid 88.255094 -270.572081)
		(end 88.067896 -270.521938)
		(width 0.0889)
		(layer "B.Cu")
		(net "NC_SPI_CPU1_NCM_OE_N")
	)
	(arc
		(start 99.34575 -270.521938)
		(mid 99.068937 -270.446068)
		(end 98.790506 -270.515842)
		(width 0.0889)
		(layer "B.Cu")
		(net "NC_SPI_CPU1_NCM_OE_N")
	)
	(segment
		(start 103.292148 -264.77849)
		(end 103.292148 -265.314176)
		(width 0.12954)
		(layer "F.Cu")
		(net "NC_SPI_CPU1_NCM_IO1")
	)
	(segment
		(start 103.291894 -264.778236)
		(end 103.292148 -264.77849)
		(width 0.12954)
		(layer "F.Cu")
		(net "NC_SPI_CPU1_NCM_IO1")
	)
	(via
		(at 103.292148 -265.314176)
		(size 0.4572)
		(drill 0.2032)
		(layers "F.Cu" "B.Cu")
		(net "NC_SPI_CPU1_NCM_IO1")
	)
	(segment
		(start 103.762048 -269.383256)
		(end 103.761794 -269.38351)
		(width 0.12954)
		(layer "F.Cu")
		(net "NC_SPI_CPU1_NCM_IO0")
	)
	(segment
		(start 103.762048 -268.84757)
		(end 103.762048 -269.383256)
		(width 0.12954)
		(layer "F.Cu")
		(net "NC_SPI_CPU1_NCM_IO0")
	)
	(via
		(at 103.761794 -269.38351)
		(size 0.4572)
		(drill 0.2032)
		(layers "F.Cu" "B.Cu")
		(net "NC_SPI_CPU1_NCM_IO0")
	)
	(via
		(at 83.085432 -268.400276)
		(size 0.6604)
		(drill 0.3302)
		(layers "F.Cu" "B.Cu")
		(net "NC_SPI_CPU1_NCM_IO0")
	)
	(segment
		(start 90.332306 -268.887956)
		(end 90.321892 -268.894052)
		(width 0.0889)
		(layer "B.Cu")
		(net "NC_SPI_CPU1_NCM_IO0")
	)
	(segment
		(start 98.795078 -268.885416)
		(end 98.780346 -268.894052)
		(width 0.0889)
		(layer "B.Cu")
		(net "NC_SPI_CPU1_NCM_IO0")
	)
	(segment
		(start 92.216478 -268.885416)
		(end 92.201746 -268.894052)
		(width 0.0889)
		(layer "B.Cu")
		(net "NC_SPI_CPU1_NCM_IO0")
	)
	(segment
		(start 95.031306 -268.887956)
		(end 95.020892 -268.894052)
		(width 0.0889)
		(layer "B.Cu")
		(net "NC_SPI_CPU1_NCM_IO0")
	)
	(segment
		(start 83.735672 -268.484858)
		(end 83.170014 -268.484858)
		(width 0.12954)
		(layer "B.Cu")
		(net "NC_SPI_CPU1_NCM_IO0")
	)
	(segment
		(start 85.031072 -268.484858)
		(end 83.735672 -268.484858)
		(width 0.0889)
		(layer "B.Cu")
		(net "NC_SPI_CPU1_NCM_IO0")
	)
	(segment
		(start 103.761794 -269.38351)
		(end 103.60533 -269.654528)
		(width 0.0889)
		(layer "B.Cu")
		(net "NC_SPI_CPU1_NCM_IO0")
	)
	(segment
		(start 83.170014 -268.484858)
		(end 83.085432 -268.400276)
		(width 0.12954)
		(layer "B.Cu")
		(net "NC_SPI_CPU1_NCM_IO0")
	)
	(segment
		(start 86.922864 -268.77264)
		(end 86.411054 -268.26083)
		(width 0.0889)
		(layer "B.Cu")
		(net "NC_SPI_CPU1_NCM_IO0")
	)
	(segment
		(start 87.10803 -268.881352)
		(end 86.922864 -268.77264)
		(width 0.0889)
		(layer "B.Cu")
		(net "NC_SPI_CPU1_NCM_IO0")
	)
	(segment
		(start 102.554278 -268.885416)
		(end 102.539546 -268.894052)
		(width 0.0889)
		(layer "B.Cu")
		(net "NC_SPI_CPU1_NCM_IO0")
	)
	(segment
		(start 101.233478 -268.898878)
		(end 101.225096 -268.894052)
		(width 0.0889)
		(layer "B.Cu")
		(net "NC_SPI_CPU1_NCM_IO0")
	)
	(segment
		(start 103.60533 -269.654528)
		(end 103.527098 -269.675356)
		(width 0.0889)
		(layer "B.Cu")
		(net "NC_SPI_CPU1_NCM_IO0")
	)
	(segment
		(start 100.67036 -268.887956)
		(end 100.659946 -268.894052)
		(width 0.0889)
		(layer "B.Cu")
		(net "NC_SPI_CPU1_NCM_IO0")
	)
	(segment
		(start 93.156278 -268.885416)
		(end 93.141546 -268.894052)
		(width 0.0889)
		(layer "B.Cu")
		(net "NC_SPI_CPU1_NCM_IO0")
	)
	(segment
		(start 96.915478 -268.885416)
		(end 96.900746 -268.894052)
		(width 0.0889)
		(layer "B.Cu")
		(net "NC_SPI_CPU1_NCM_IO0")
	)
	(segment
		(start 102.16515 -268.894052)
		(end 102.150418 -268.885416)
		(width 0.0889)
		(layer "B.Cu")
		(net "NC_SPI_CPU1_NCM_IO0")
	)
	(segment
		(start 87.152988 -268.907006)
		(end 87.12962 -268.893798)
		(width 0.0889)
		(layer "B.Cu")
		(net "NC_SPI_CPU1_NCM_IO0")
	)
	(segment
		(start 94.09176 -268.887956)
		(end 94.081346 -268.894052)
		(width 0.0889)
		(layer "B.Cu")
		(net "NC_SPI_CPU1_NCM_IO0")
	)
	(segment
		(start 85.2551 -268.26083)
		(end 85.031072 -268.484858)
		(width 0.0889)
		(layer "B.Cu")
		(net "NC_SPI_CPU1_NCM_IO0")
	)
	(segment
		(start 95.975678 -268.885416)
		(end 95.960946 -268.894052)
		(width 0.0889)
		(layer "B.Cu")
		(net "NC_SPI_CPU1_NCM_IO0")
	)
	(segment
		(start 99.734878 -268.885416)
		(end 99.720146 -268.894052)
		(width 0.0889)
		(layer "B.Cu")
		(net "NC_SPI_CPU1_NCM_IO0")
	)
	(segment
		(start 87.12962 -268.893798)
		(end 87.10803 -268.881352)
		(width 0.0889)
		(layer "B.Cu")
		(net "NC_SPI_CPU1_NCM_IO0")
	)
	(segment
		(start 86.411054 -268.26083)
		(end 85.2551 -268.26083)
		(width 0.0889)
		(layer "B.Cu")
		(net "NC_SPI_CPU1_NCM_IO0")
	)
	(segment
		(start 103.387144 -269.38351)
		(end 103.387144 -269.368016)
		(width 0.0889)
		(layer "B.Cu")
		(net "NC_SPI_CPU1_NCM_IO0")
	)
	(arc
		(start 103.527098 -269.675356)
		(mid 103.423953 -269.545331)
		(end 103.387144 -269.38351)
		(width 0.0889)
		(layer "B.Cu")
		(net "NC_SPI_CPU1_NCM_IO0")
	)
	(arc
		(start 89.382092 -268.894052)
		(mid 89.194894 -268.944195)
		(end 89.007696 -268.894052)
		(width 0.0889)
		(layer "B.Cu")
		(net "NC_SPI_CPU1_NCM_IO0")
	)
	(arc
		(start 101.599746 -268.894052)
		(mid 101.417241 -268.94429)
		(end 101.233478 -268.898878)
		(width 0.0889)
		(layer "B.Cu")
		(net "NC_SPI_CPU1_NCM_IO0")
	)
	(arc
		(start 91.261946 -268.894052)
		(mid 91.074748 -268.944195)
		(end 90.88755 -268.894052)
		(width 0.0889)
		(layer "B.Cu")
		(net "NC_SPI_CPU1_NCM_IO0")
	)
	(arc
		(start 91.82735 -268.894052)
		(mid 91.544648 -268.818276)
		(end 91.261946 -268.894052)
		(width 0.0889)
		(layer "B.Cu")
		(net "NC_SPI_CPU1_NCM_IO0")
	)
	(arc
		(start 95.020892 -268.894052)
		(mid 94.833694 -268.944195)
		(end 94.646496 -268.894052)
		(width 0.0889)
		(layer "B.Cu")
		(net "NC_SPI_CPU1_NCM_IO0")
	)
	(arc
		(start 89.007696 -268.894052)
		(mid 88.724994 -268.818276)
		(end 88.442292 -268.894052)
		(width 0.0889)
		(layer "B.Cu")
		(net "NC_SPI_CPU1_NCM_IO0")
	)
	(arc
		(start 103.387144 -269.368016)
		(mid 103.307774 -269.094282)
		(end 103.10495 -268.894052)
		(width 0.0889)
		(layer "B.Cu")
		(net "NC_SPI_CPU1_NCM_IO0")
	)
	(arc
		(start 101.225096 -268.894052)
		(mid 100.948537 -268.818309)
		(end 100.67036 -268.887956)
		(width 0.0889)
		(layer "B.Cu")
		(net "NC_SPI_CPU1_NCM_IO0")
	)
	(arc
		(start 100.659946 -268.894052)
		(mid 100.472748 -268.944195)
		(end 100.28555 -268.894052)
		(width 0.0889)
		(layer "B.Cu")
		(net "NC_SPI_CPU1_NCM_IO0")
	)
	(arc
		(start 88.442292 -268.894052)
		(mid 88.255094 -268.944195)
		(end 88.067896 -268.894052)
		(width 0.0889)
		(layer "B.Cu")
		(net "NC_SPI_CPU1_NCM_IO0")
	)
	(arc
		(start 88.067896 -268.894052)
		(mid 87.785194 -268.818276)
		(end 87.502492 -268.894052)
		(width 0.0889)
		(layer "B.Cu")
		(net "NC_SPI_CPU1_NCM_IO0")
	)
	(arc
		(start 99.34575 -268.894052)
		(mid 99.071551 -268.818217)
		(end 98.795078 -268.885416)
		(width 0.0889)
		(layer "B.Cu")
		(net "NC_SPI_CPU1_NCM_IO0")
	)
	(arc
		(start 90.321892 -268.894052)
		(mid 90.134694 -268.944195)
		(end 89.947496 -268.894052)
		(width 0.0889)
		(layer "B.Cu")
		(net "NC_SPI_CPU1_NCM_IO0")
	)
	(arc
		(start 102.539546 -268.894052)
		(mid 102.352348 -268.944195)
		(end 102.16515 -268.894052)
		(width 0.0889)
		(layer "B.Cu")
		(net "NC_SPI_CPU1_NCM_IO0")
	)
	(arc
		(start 97.840546 -268.894052)
		(mid 97.653348 -268.944195)
		(end 97.46615 -268.894052)
		(width 0.0889)
		(layer "B.Cu")
		(net "NC_SPI_CPU1_NCM_IO0")
	)
	(arc
		(start 93.141546 -268.894052)
		(mid 92.954348 -268.944195)
		(end 92.76715 -268.894052)
		(width 0.0889)
		(layer "B.Cu")
		(net "NC_SPI_CPU1_NCM_IO0")
	)
	(arc
		(start 90.88755 -268.894052)
		(mid 90.610737 -268.818182)
		(end 90.332306 -268.887956)
		(width 0.0889)
		(layer "B.Cu")
		(net "NC_SPI_CPU1_NCM_IO0")
	)
	(arc
		(start 87.502492 -268.894052)
		(mid 87.329352 -268.943814)
		(end 87.152988 -268.907006)
		(width 0.0889)
		(layer "B.Cu")
		(net "NC_SPI_CPU1_NCM_IO0")
	)
	(arc
		(start 96.52635 -268.894052)
		(mid 96.252151 -268.818217)
		(end 95.975678 -268.885416)
		(width 0.0889)
		(layer "B.Cu")
		(net "NC_SPI_CPU1_NCM_IO0")
	)
	(arc
		(start 102.150418 -268.885416)
		(mid 101.873943 -268.818096)
		(end 101.599746 -268.894052)
		(width 0.0889)
		(layer "B.Cu")
		(net "NC_SPI_CPU1_NCM_IO0")
	)
	(arc
		(start 89.947496 -268.894052)
		(mid 89.664794 -268.818276)
		(end 89.382092 -268.894052)
		(width 0.0889)
		(layer "B.Cu")
		(net "NC_SPI_CPU1_NCM_IO0")
	)
	(arc
		(start 92.201746 -268.894052)
		(mid 92.014548 -268.944195)
		(end 91.82735 -268.894052)
		(width 0.0889)
		(layer "B.Cu")
		(net "NC_SPI_CPU1_NCM_IO0")
	)
	(arc
		(start 93.70695 -268.894052)
		(mid 93.432751 -268.818217)
		(end 93.156278 -268.885416)
		(width 0.0889)
		(layer "B.Cu")
		(net "NC_SPI_CPU1_NCM_IO0")
	)
	(arc
		(start 95.58655 -268.894052)
		(mid 95.309737 -268.818182)
		(end 95.031306 -268.887956)
		(width 0.0889)
		(layer "B.Cu")
		(net "NC_SPI_CPU1_NCM_IO0")
	)
	(arc
		(start 98.40595 -268.894052)
		(mid 98.123248 -268.818276)
		(end 97.840546 -268.894052)
		(width 0.0889)
		(layer "B.Cu")
		(net "NC_SPI_CPU1_NCM_IO0")
	)
	(arc
		(start 100.28555 -268.894052)
		(mid 100.011351 -268.818217)
		(end 99.734878 -268.885416)
		(width 0.0889)
		(layer "B.Cu")
		(net "NC_SPI_CPU1_NCM_IO0")
	)
	(arc
		(start 97.46615 -268.894052)
		(mid 97.191951 -268.818217)
		(end 96.915478 -268.885416)
		(width 0.0889)
		(layer "B.Cu")
		(net "NC_SPI_CPU1_NCM_IO0")
	)
	(arc
		(start 92.76715 -268.894052)
		(mid 92.492951 -268.818217)
		(end 92.216478 -268.885416)
		(width 0.0889)
		(layer "B.Cu")
		(net "NC_SPI_CPU1_NCM_IO0")
	)
	(arc
		(start 96.900746 -268.894052)
		(mid 96.713548 -268.944195)
		(end 96.52635 -268.894052)
		(width 0.0889)
		(layer "B.Cu")
		(net "NC_SPI_CPU1_NCM_IO0")
	)
	(arc
		(start 98.780346 -268.894052)
		(mid 98.593148 -268.944195)
		(end 98.40595 -268.894052)
		(width 0.0889)
		(layer "B.Cu")
		(net "NC_SPI_CPU1_NCM_IO0")
	)
	(arc
		(start 103.10495 -268.894052)
		(mid 102.830751 -268.818217)
		(end 102.554278 -268.885416)
		(width 0.0889)
		(layer "B.Cu")
		(net "NC_SPI_CPU1_NCM_IO0")
	)
	(arc
		(start 94.081346 -268.894052)
		(mid 93.894148 -268.944195)
		(end 93.70695 -268.894052)
		(width 0.0889)
		(layer "B.Cu")
		(net "NC_SPI_CPU1_NCM_IO0")
	)
	(arc
		(start 95.960946 -268.894052)
		(mid 95.773748 -268.944195)
		(end 95.58655 -268.894052)
		(width 0.0889)
		(layer "B.Cu")
		(net "NC_SPI_CPU1_NCM_IO0")
	)
	(arc
		(start 99.720146 -268.894052)
		(mid 99.532948 -268.944195)
		(end 99.34575 -268.894052)
		(width 0.0889)
		(layer "B.Cu")
		(net "NC_SPI_CPU1_NCM_IO0")
	)
	(arc
		(start 94.646496 -268.894052)
		(mid 94.369937 -268.818309)
		(end 94.09176 -268.887956)
		(width 0.0889)
		(layer "B.Cu")
		(net "NC_SPI_CPU1_NCM_IO0")
	)
	(segment
		(start 103.291894 -269.66164)
		(end 103.292148 -269.661894)
		(width 0.12954)
		(layer "F.Cu")
		(net "NC_SPI_CPU1_NCM_CS0_N")
	)
	(segment
		(start 103.292148 -269.661894)
		(end 103.292148 -270.19758)
		(width 0.12954)
		(layer "F.Cu")
		(net "NC_SPI_CPU1_NCM_CS0_N")
	)
	(via
		(at 103.292148 -270.19758)
		(size 0.4572)
		(drill 0.2032)
		(layers "F.Cu" "B.Cu")
		(net "NC_SPI_CPU1_NCM_CS0_N")
	)
	(via
		(at 81.721706 -268.434312)
		(size 0.6604)
		(drill 0.3302)
		(layers "F.Cu" "B.Cu")
		(net "NC_SPI_CPU1_NCM_CS0_N")
	)
	(segment
		(start 91.35745 -269.059152)
		(end 91.347036 -269.065248)
		(width 0.0889)
		(layer "B.Cu")
		(net "NC_SPI_CPU1_NCM_CS0_N")
	)
	(segment
		(start 96.056196 -269.059152)
		(end 96.041464 -269.067788)
		(width 0.0889)
		(layer "B.Cu")
		(net "NC_SPI_CPU1_NCM_CS0_N")
	)
	(segment
		(start 82.252312 -268.964918)
		(end 81.721706 -268.434312)
		(width 0.12954)
		(layer "B.Cu")
		(net "NC_SPI_CPU1_NCM_CS0_N")
	)
	(segment
		(start 87.058246 -269.073122)
		(end 86.805516 -268.924532)
		(width 0.0889)
		(layer "B.Cu")
		(net "NC_SPI_CPU1_NCM_CS0_N")
	)
	(segment
		(start 86.805516 -268.924532)
		(end 86.33206 -268.451076)
		(width 0.0889)
		(layer "B.Cu")
		(net "NC_SPI_CPU1_NCM_CS0_N")
	)
	(segment
		(start 83.682332 -268.964918)
		(end 82.252312 -268.964918)
		(width 0.12954)
		(layer "B.Cu")
		(net "NC_SPI_CPU1_NCM_CS0_N")
	)
	(segment
		(start 83.858354 -268.964918)
		(end 83.682332 -268.964918)
		(width 0.0889)
		(layer "B.Cu")
		(net "NC_SPI_CPU1_NCM_CS0_N")
	)
	(segment
		(start 103.196644 -269.397734)
		(end 103.196644 -269.38351)
		(width 0.0889)
		(layer "B.Cu")
		(net "NC_SPI_CPU1_NCM_CS0_N")
	)
	(segment
		(start 86.33206 -268.451076)
		(end 85.395054 -268.451076)
		(width 0.0889)
		(layer "B.Cu")
		(net "NC_SPI_CPU1_NCM_CS0_N")
	)
	(segment
		(start 84.987638 -268.858492)
		(end 83.96478 -268.858492)
		(width 0.0889)
		(layer "B.Cu")
		(net "NC_SPI_CPU1_NCM_CS0_N")
	)
	(segment
		(start 94.176596 -269.059152)
		(end 94.161864 -269.067788)
		(width 0.0889)
		(layer "B.Cu")
		(net "NC_SPI_CPU1_NCM_CS0_N")
	)
	(segment
		(start 103.018082 -269.064232)
		(end 103.009192 -269.059152)
		(width 0.0889)
		(layer "B.Cu")
		(net "NC_SPI_CPU1_NCM_CS0_N")
	)
	(segment
		(start 103.292148 -270.19758)
		(end 103.448612 -269.926562)
		(width 0.0889)
		(layer "B.Cu")
		(net "NC_SPI_CPU1_NCM_CS0_N")
	)
	(segment
		(start 100.755196 -269.059152)
		(end 100.740464 -269.067788)
		(width 0.0889)
		(layer "B.Cu")
		(net "NC_SPI_CPU1_NCM_CS0_N")
	)
	(segment
		(start 97.93605 -269.059152)
		(end 97.925636 -269.065248)
		(width 0.0889)
		(layer "B.Cu")
		(net "NC_SPI_CPU1_NCM_CS0_N")
	)
	(segment
		(start 103.448612 -269.926562)
		(end 103.424482 -269.837408)
		(width 0.0889)
		(layer "B.Cu")
		(net "NC_SPI_CPU1_NCM_CS0_N")
	)
	(segment
		(start 93.236796 -269.059152)
		(end 93.222064 -269.067788)
		(width 0.0889)
		(layer "B.Cu")
		(net "NC_SPI_CPU1_NCM_CS0_N")
	)
	(segment
		(start 99.815396 -269.059152)
		(end 99.800664 -269.067788)
		(width 0.0889)
		(layer "B.Cu")
		(net "NC_SPI_CPU1_NCM_CS0_N")
	)
	(segment
		(start 102.0699 -269.059152)
		(end 102.061518 -269.054326)
		(width 0.0889)
		(layer "B.Cu")
		(net "NC_SPI_CPU1_NCM_CS0_N")
	)
	(segment
		(start 85.395054 -268.451076)
		(end 84.987638 -268.858492)
		(width 0.0889)
		(layer "B.Cu")
		(net "NC_SPI_CPU1_NCM_CS0_N")
	)
	(segment
		(start 96.995996 -269.059152)
		(end 96.981264 -269.067788)
		(width 0.0889)
		(layer "B.Cu")
		(net "NC_SPI_CPU1_NCM_CS0_N")
	)
	(segment
		(start 98.875596 -269.059152)
		(end 98.865182 -269.065248)
		(width 0.0889)
		(layer "B.Cu")
		(net "NC_SPI_CPU1_NCM_CS0_N")
	)
	(segment
		(start 92.296996 -269.059152)
		(end 92.286582 -269.065248)
		(width 0.0889)
		(layer "B.Cu")
		(net "NC_SPI_CPU1_NCM_CS0_N")
	)
	(segment
		(start 101.140006 -269.065248)
		(end 101.129592 -269.059152)
		(width 0.0889)
		(layer "B.Cu")
		(net "NC_SPI_CPU1_NCM_CS0_N")
	)
	(segment
		(start 83.96478 -268.858492)
		(end 83.858354 -268.964918)
		(width 0.0889)
		(layer "B.Cu")
		(net "NC_SPI_CPU1_NCM_CS0_N")
	)
	(arc
		(start 103.424482 -269.837408)
		(mid 103.259867 -269.643844)
		(end 103.196644 -269.397734)
		(width 0.0889)
		(layer "B.Cu")
		(net "NC_SPI_CPU1_NCM_CS0_N")
	)
	(arc
		(start 97.925636 -269.065248)
		(mid 97.647204 -269.135094)
		(end 97.370392 -269.059152)
		(width 0.0889)
		(layer "B.Cu")
		(net "NC_SPI_CPU1_NCM_CS0_N")
	)
	(arc
		(start 90.417396 -269.059152)
		(mid 90.134694 -269.134928)
		(end 89.851992 -269.059152)
		(width 0.0889)
		(layer "B.Cu")
		(net "NC_SPI_CPU1_NCM_CS0_N")
	)
	(arc
		(start 100.189792 -269.059152)
		(mid 100.002594 -269.009009)
		(end 99.815396 -269.059152)
		(width 0.0889)
		(layer "B.Cu")
		(net "NC_SPI_CPU1_NCM_CS0_N")
	)
	(arc
		(start 94.550992 -269.059152)
		(mid 94.363794 -269.009009)
		(end 94.176596 -269.059152)
		(width 0.0889)
		(layer "B.Cu")
		(net "NC_SPI_CPU1_NCM_CS0_N")
	)
	(arc
		(start 93.611192 -269.059152)
		(mid 93.423994 -269.009009)
		(end 93.236796 -269.059152)
		(width 0.0889)
		(layer "B.Cu")
		(net "NC_SPI_CPU1_NCM_CS0_N")
	)
	(arc
		(start 99.249992 -269.059152)
		(mid 99.062794 -269.009009)
		(end 98.875596 -269.059152)
		(width 0.0889)
		(layer "B.Cu")
		(net "NC_SPI_CPU1_NCM_CS0_N")
	)
	(arc
		(start 94.161864 -269.067788)
		(mid 93.885389 -269.135108)
		(end 93.611192 -269.059152)
		(width 0.0889)
		(layer "B.Cu")
		(net "NC_SPI_CPU1_NCM_CS0_N")
	)
	(arc
		(start 92.286582 -269.065248)
		(mid 92.008404 -269.134971)
		(end 91.731846 -269.059152)
		(width 0.0889)
		(layer "B.Cu")
		(net "NC_SPI_CPU1_NCM_CS0_N")
	)
	(arc
		(start 87.597996 -269.059152)
		(mid 87.329899 -269.134739)
		(end 87.058246 -269.073122)
		(width 0.0889)
		(layer "B.Cu")
		(net "NC_SPI_CPU1_NCM_CS0_N")
	)
	(arc
		(start 98.865182 -269.065248)
		(mid 98.587004 -269.134971)
		(end 98.310446 -269.059152)
		(width 0.0889)
		(layer "B.Cu")
		(net "NC_SPI_CPU1_NCM_CS0_N")
	)
	(arc
		(start 90.791792 -269.059152)
		(mid 90.604594 -269.009009)
		(end 90.417396 -269.059152)
		(width 0.0889)
		(layer "B.Cu")
		(net "NC_SPI_CPU1_NCM_CS0_N")
	)
	(arc
		(start 97.370392 -269.059152)
		(mid 97.183194 -269.009009)
		(end 96.995996 -269.059152)
		(width 0.0889)
		(layer "B.Cu")
		(net "NC_SPI_CPU1_NCM_CS0_N")
	)
	(arc
		(start 89.851992 -269.059152)
		(mid 89.664794 -269.009009)
		(end 89.477596 -269.059152)
		(width 0.0889)
		(layer "B.Cu")
		(net "NC_SPI_CPU1_NCM_CS0_N")
	)
	(arc
		(start 96.430592 -269.059152)
		(mid 96.243394 -269.009009)
		(end 96.056196 -269.059152)
		(width 0.0889)
		(layer "B.Cu")
		(net "NC_SPI_CPU1_NCM_CS0_N")
	)
	(arc
		(start 100.740464 -269.067788)
		(mid 100.463989 -269.135108)
		(end 100.189792 -269.059152)
		(width 0.0889)
		(layer "B.Cu")
		(net "NC_SPI_CPU1_NCM_CS0_N")
	)
	(arc
		(start 88.537796 -269.059152)
		(mid 88.255094 -269.134928)
		(end 87.972392 -269.059152)
		(width 0.0889)
		(layer "B.Cu")
		(net "NC_SPI_CPU1_NCM_CS0_N")
	)
	(arc
		(start 101.69525 -269.059152)
		(mid 101.418437 -269.135022)
		(end 101.140006 -269.065248)
		(width 0.0889)
		(layer "B.Cu")
		(net "NC_SPI_CPU1_NCM_CS0_N")
	)
	(arc
		(start 102.634796 -269.059152)
		(mid 102.352348 -269.134801)
		(end 102.0699 -269.059152)
		(width 0.0889)
		(layer "B.Cu")
		(net "NC_SPI_CPU1_NCM_CS0_N")
	)
	(arc
		(start 101.129592 -269.059152)
		(mid 100.942394 -269.009009)
		(end 100.755196 -269.059152)
		(width 0.0889)
		(layer "B.Cu")
		(net "NC_SPI_CPU1_NCM_CS0_N")
	)
	(arc
		(start 87.972392 -269.059152)
		(mid 87.785194 -269.009009)
		(end 87.597996 -269.059152)
		(width 0.0889)
		(layer "B.Cu")
		(net "NC_SPI_CPU1_NCM_CS0_N")
	)
	(arc
		(start 91.731846 -269.059152)
		(mid 91.544648 -269.009009)
		(end 91.35745 -269.059152)
		(width 0.0889)
		(layer "B.Cu")
		(net "NC_SPI_CPU1_NCM_CS0_N")
	)
	(arc
		(start 103.196644 -269.38351)
		(mid 103.148965 -269.20061)
		(end 103.018082 -269.064232)
		(width 0.0889)
		(layer "B.Cu")
		(net "NC_SPI_CPU1_NCM_CS0_N")
	)
	(arc
		(start 95.490792 -269.059152)
		(mid 95.303594 -269.009009)
		(end 95.116396 -269.059152)
		(width 0.0889)
		(layer "B.Cu")
		(net "NC_SPI_CPU1_NCM_CS0_N")
	)
	(arc
		(start 91.347036 -269.065248)
		(mid 91.068604 -269.135094)
		(end 90.791792 -269.059152)
		(width 0.0889)
		(layer "B.Cu")
		(net "NC_SPI_CPU1_NCM_CS0_N")
	)
	(arc
		(start 93.222064 -269.067788)
		(mid 92.945589 -269.135108)
		(end 92.671392 -269.059152)
		(width 0.0889)
		(layer "B.Cu")
		(net "NC_SPI_CPU1_NCM_CS0_N")
	)
	(arc
		(start 103.009192 -269.059152)
		(mid 102.821994 -269.009009)
		(end 102.634796 -269.059152)
		(width 0.0889)
		(layer "B.Cu")
		(net "NC_SPI_CPU1_NCM_CS0_N")
	)
	(arc
		(start 96.981264 -269.067788)
		(mid 96.704789 -269.135108)
		(end 96.430592 -269.059152)
		(width 0.0889)
		(layer "B.Cu")
		(net "NC_SPI_CPU1_NCM_CS0_N")
	)
	(arc
		(start 98.310446 -269.059152)
		(mid 98.123248 -269.009009)
		(end 97.93605 -269.059152)
		(width 0.0889)
		(layer "B.Cu")
		(net "NC_SPI_CPU1_NCM_CS0_N")
	)
	(arc
		(start 102.061518 -269.054326)
		(mid 101.877756 -269.008926)
		(end 101.69525 -269.059152)
		(width 0.0889)
		(layer "B.Cu")
		(net "NC_SPI_CPU1_NCM_CS0_N")
	)
	(arc
		(start 89.477596 -269.059152)
		(mid 89.194894 -269.134928)
		(end 88.912192 -269.059152)
		(width 0.0889)
		(layer "B.Cu")
		(net "NC_SPI_CPU1_NCM_CS0_N")
	)
	(arc
		(start 99.800664 -269.067788)
		(mid 99.524189 -269.135108)
		(end 99.249992 -269.059152)
		(width 0.0889)
		(layer "B.Cu")
		(net "NC_SPI_CPU1_NCM_CS0_N")
	)
	(arc
		(start 96.041464 -269.067788)
		(mid 95.764989 -269.135108)
		(end 95.490792 -269.059152)
		(width 0.0889)
		(layer "B.Cu")
		(net "NC_SPI_CPU1_NCM_CS0_N")
	)
	(arc
		(start 95.116396 -269.059152)
		(mid 94.833694 -269.134928)
		(end 94.550992 -269.059152)
		(width 0.0889)
		(layer "B.Cu")
		(net "NC_SPI_CPU1_NCM_CS0_N")
	)
	(arc
		(start 92.671392 -269.059152)
		(mid 92.484194 -269.009009)
		(end 92.296996 -269.059152)
		(width 0.0889)
		(layer "B.Cu")
		(net "NC_SPI_CPU1_NCM_CS0_N")
	)
	(arc
		(start 88.912192 -269.059152)
		(mid 88.724994 -269.009009)
		(end 88.537796 -269.059152)
		(width 0.0889)
		(layer "B.Cu")
		(net "NC_SPI_CPU1_NCM_CS0_N")
	)
	(segment
		(start 101.882448 -265.592306)
		(end 101.882448 -266.127992)
		(width 0.12954)
		(layer "F.Cu")
		(net "NC_SPI_CPU1_NCM_CLK")
	)
	(segment
		(start 101.882448 -266.127992)
		(end 101.882194 -266.128246)
		(width 0.12954)
		(layer "F.Cu")
		(net "NC_SPI_CPU1_NCM_CLK")
	)
	(via
		(at 101.882194 -266.128246)
		(size 0.4572)
		(drill 0.2032)
		(layers "F.Cu" "B.Cu")
		(net "NC_SPI_CPU1_NCM_CLK")
	)
	(via
		(at 86.620858 -266.425934)
		(size 0.6604)
		(drill 0.3302)
		(layers "F.Cu" "B.Cu")
		(net "NC_SPI_CPU1_NCM_CLK")
	)
	(segment
		(start 96.948244 -265.721084)
		(end 96.934782 -265.728958)
		(width 0.0889)
		(layer "B.Cu")
		(net "NC_SPI_CPU1_NCM_CLK")
	)
	(segment
		(start 95.068644 -265.721084)
		(end 95.055182 -265.728958)
		(width 0.0889)
		(layer "B.Cu")
		(net "NC_SPI_CPU1_NCM_CLK")
	)
	(segment
		(start 87.315294 -265.784076)
		(end 87.262716 -265.784076)
		(width 0.12954)
		(layer "B.Cu")
		(net "NC_SPI_CPU1_NCM_CLK")
	)
	(segment
		(start 91.309444 -265.721084)
		(end 91.295982 -265.728958)
		(width 0.0889)
		(layer "B.Cu")
		(net "NC_SPI_CPU1_NCM_CLK")
	)
	(segment
		(start 99.767644 -265.721084)
		(end 99.754182 -265.728958)
		(width 0.0889)
		(layer "B.Cu")
		(net "NC_SPI_CPU1_NCM_CLK")
	)
	(segment
		(start 94.128844 -265.721084)
		(end 94.115382 -265.728958)
		(width 0.0889)
		(layer "B.Cu")
		(net "NC_SPI_CPU1_NCM_CLK")
	)
	(segment
		(start 93.189044 -265.721084)
		(end 93.175582 -265.728958)
		(width 0.0889)
		(layer "B.Cu")
		(net "NC_SPI_CPU1_NCM_CLK")
	)
	(segment
		(start 96.008444 -265.721084)
		(end 95.994982 -265.728958)
		(width 0.0889)
		(layer "B.Cu")
		(net "NC_SPI_CPU1_NCM_CLK")
	)
	(segment
		(start 100.707444 -265.721084)
		(end 100.693982 -265.728958)
		(width 0.0889)
		(layer "B.Cu")
		(net "NC_SPI_CPU1_NCM_CLK")
	)
	(segment
		(start 101.882194 -266.128246)
		(end 101.177344 -265.721084)
		(width 0.0889)
		(layer "B.Cu")
		(net "NC_SPI_CPU1_NCM_CLK")
	)
	(segment
		(start 97.888044 -265.721084)
		(end 97.874582 -265.728958)
		(width 0.0889)
		(layer "B.Cu")
		(net "NC_SPI_CPU1_NCM_CLK")
	)
	(segment
		(start 87.262716 -265.784076)
		(end 86.620858 -266.425934)
		(width 0.12954)
		(layer "B.Cu")
		(net "NC_SPI_CPU1_NCM_CLK")
	)
	(arc
		(start 88.020144 -265.721084)
		(mid 87.785194 -265.658158)
		(end 87.550244 -265.721084)
		(width 0.0889)
		(layer "B.Cu")
		(net "NC_SPI_CPU1_NCM_CLK")
	)
	(arc
		(start 90.369644 -265.721084)
		(mid 90.134694 -265.784044)
		(end 89.899744 -265.721084)
		(width 0.0889)
		(layer "B.Cu")
		(net "NC_SPI_CPU1_NCM_CLK")
	)
	(arc
		(start 88.959944 -265.721084)
		(mid 88.724994 -265.658158)
		(end 88.490044 -265.721084)
		(width 0.0889)
		(layer "B.Cu")
		(net "NC_SPI_CPU1_NCM_CLK")
	)
	(arc
		(start 90.839544 -265.721084)
		(mid 90.604594 -265.658158)
		(end 90.369644 -265.721084)
		(width 0.0889)
		(layer "B.Cu")
		(net "NC_SPI_CPU1_NCM_CLK")
	)
	(arc
		(start 98.827844 -265.721084)
		(mid 98.592894 -265.784044)
		(end 98.357944 -265.721084)
		(width 0.0889)
		(layer "B.Cu")
		(net "NC_SPI_CPU1_NCM_CLK")
	)
	(arc
		(start 89.899744 -265.721084)
		(mid 89.664794 -265.658158)
		(end 89.429844 -265.721084)
		(width 0.0889)
		(layer "B.Cu")
		(net "NC_SPI_CPU1_NCM_CLK")
	)
	(arc
		(start 97.418144 -265.721084)
		(mid 97.183194 -265.658158)
		(end 96.948244 -265.721084)
		(width 0.0889)
		(layer "B.Cu")
		(net "NC_SPI_CPU1_NCM_CLK")
	)
	(arc
		(start 95.055182 -265.728958)
		(mid 94.825929 -265.784202)
		(end 94.598744 -265.721084)
		(width 0.0889)
		(layer "B.Cu")
		(net "NC_SPI_CPU1_NCM_CLK")
	)
	(arc
		(start 94.598744 -265.721084)
		(mid 94.363794 -265.658158)
		(end 94.128844 -265.721084)
		(width 0.0889)
		(layer "B.Cu")
		(net "NC_SPI_CPU1_NCM_CLK")
	)
	(arc
		(start 92.249244 -265.721084)
		(mid 92.014294 -265.784044)
		(end 91.779344 -265.721084)
		(width 0.0889)
		(layer "B.Cu")
		(net "NC_SPI_CPU1_NCM_CLK")
	)
	(arc
		(start 89.429844 -265.721084)
		(mid 89.194894 -265.784044)
		(end 88.959944 -265.721084)
		(width 0.0889)
		(layer "B.Cu")
		(net "NC_SPI_CPU1_NCM_CLK")
	)
	(arc
		(start 88.490044 -265.721084)
		(mid 88.255094 -265.784044)
		(end 88.020144 -265.721084)
		(width 0.0889)
		(layer "B.Cu")
		(net "NC_SPI_CPU1_NCM_CLK")
	)
	(arc
		(start 91.295982 -265.728958)
		(mid 91.066729 -265.784202)
		(end 90.839544 -265.721084)
		(width 0.0889)
		(layer "B.Cu")
		(net "NC_SPI_CPU1_NCM_CLK")
	)
	(arc
		(start 93.658944 -265.721084)
		(mid 93.423994 -265.658158)
		(end 93.189044 -265.721084)
		(width 0.0889)
		(layer "B.Cu")
		(net "NC_SPI_CPU1_NCM_CLK")
	)
	(arc
		(start 95.994982 -265.728958)
		(mid 95.765729 -265.784202)
		(end 95.538544 -265.721084)
		(width 0.0889)
		(layer "B.Cu")
		(net "NC_SPI_CPU1_NCM_CLK")
	)
	(arc
		(start 91.779344 -265.721084)
		(mid 91.544394 -265.658158)
		(end 91.309444 -265.721084)
		(width 0.0889)
		(layer "B.Cu")
		(net "NC_SPI_CPU1_NCM_CLK")
	)
	(arc
		(start 99.297744 -265.721084)
		(mid 99.062794 -265.658158)
		(end 98.827844 -265.721084)
		(width 0.0889)
		(layer "B.Cu")
		(net "NC_SPI_CPU1_NCM_CLK")
	)
	(arc
		(start 99.754182 -265.728958)
		(mid 99.524929 -265.784202)
		(end 99.297744 -265.721084)
		(width 0.0889)
		(layer "B.Cu")
		(net "NC_SPI_CPU1_NCM_CLK")
	)
	(arc
		(start 97.874582 -265.728958)
		(mid 97.645329 -265.784202)
		(end 97.418144 -265.721084)
		(width 0.0889)
		(layer "B.Cu")
		(net "NC_SPI_CPU1_NCM_CLK")
	)
	(arc
		(start 92.719144 -265.721084)
		(mid 92.484194 -265.658158)
		(end 92.249244 -265.721084)
		(width 0.0889)
		(layer "B.Cu")
		(net "NC_SPI_CPU1_NCM_CLK")
	)
	(arc
		(start 93.175582 -265.728958)
		(mid 92.946329 -265.784202)
		(end 92.719144 -265.721084)
		(width 0.0889)
		(layer "B.Cu")
		(net "NC_SPI_CPU1_NCM_CLK")
	)
	(arc
		(start 101.177344 -265.721084)
		(mid 100.942394 -265.658158)
		(end 100.707444 -265.721084)
		(width 0.0889)
		(layer "B.Cu")
		(net "NC_SPI_CPU1_NCM_CLK")
	)
	(arc
		(start 98.357944 -265.721084)
		(mid 98.122994 -265.658158)
		(end 97.888044 -265.721084)
		(width 0.0889)
		(layer "B.Cu")
		(net "NC_SPI_CPU1_NCM_CLK")
	)
	(arc
		(start 100.693982 -265.728958)
		(mid 100.464729 -265.784202)
		(end 100.237544 -265.721084)
		(width 0.0889)
		(layer "B.Cu")
		(net "NC_SPI_CPU1_NCM_CLK")
	)
	(arc
		(start 96.934782 -265.728958)
		(mid 96.705529 -265.784202)
		(end 96.478344 -265.721084)
		(width 0.0889)
		(layer "B.Cu")
		(net "NC_SPI_CPU1_NCM_CLK")
	)
	(arc
		(start 94.115382 -265.728958)
		(mid 93.886129 -265.784202)
		(end 93.658944 -265.721084)
		(width 0.0889)
		(layer "B.Cu")
		(net "NC_SPI_CPU1_NCM_CLK")
	)
	(arc
		(start 95.538544 -265.721084)
		(mid 95.303594 -265.658158)
		(end 95.068644 -265.721084)
		(width 0.0889)
		(layer "B.Cu")
		(net "NC_SPI_CPU1_NCM_CLK")
	)
	(arc
		(start 87.550244 -265.721084)
		(mid 87.436918 -265.768056)
		(end 87.315294 -265.784076)
		(width 0.0889)
		(layer "B.Cu")
		(net "NC_SPI_CPU1_NCM_CLK")
	)
	(arc
		(start 100.237544 -265.721084)
		(mid 100.002594 -265.658158)
		(end 99.767644 -265.721084)
		(width 0.0889)
		(layer "B.Cu")
		(net "NC_SPI_CPU1_NCM_CLK")
	)
	(arc
		(start 96.478344 -265.721084)
		(mid 96.243394 -265.658158)
		(end 96.008444 -265.721084)
		(width 0.0889)
		(layer "B.Cu")
		(net "NC_SPI_CPU1_NCM_CLK")
	)
	(segment
		(start 27.5717 -136.345168)
		(end 27.5717 -136.957562)
		(width 0.12954)
		(layer "F.Cu")
		(net "NC_PVCCINFAON_CPU1_ACSP7")
	)
	(segment
		(start 27.5717 -136.957562)
		(end 28.190698 -137.57656)
		(width 0.12954)
		(layer "F.Cu")
		(net "NC_PVCCINFAON_CPU1_ACSP7")
	)
	(segment
		(start 28.35148 -135.565388)
		(end 27.5717 -136.345168)
		(width 0.12954)
		(layer "F.Cu")
		(net "NC_PVCCINFAON_CPU1_ACSP7")
	)
	(segment
		(start 30.661102 -134.515606)
		(end 29.61132 -135.565388)
		(width 0.12954)
		(layer "F.Cu")
		(net "NC_PVCCINFAON_CPU1_ACSP7")
	)
	(segment
		(start 29.61132 -135.565388)
		(end 28.35148 -135.565388)
		(width 0.12954)
		(layer "F.Cu")
		(net "NC_PVCCINFAON_CPU1_ACSP7")
	)
	(segment
		(start 30.661102 -132.033518)
		(end 30.661102 -134.515606)
		(width 0.12954)
		(layer "F.Cu")
		(net "NC_PVCCINFAON_CPU1_ACSP7")
	)
	(via
		(at 27.5717 -136.345168)
		(size 0.762)
		(drill 0.381)
		(layers "F.Cu" "B.Cu")
		(net "NC_PVCCINFAON_CPU1_ACSP7")
	)
	(segment
		(start 28.8798 -136.345168)
		(end 28.8798 -137.232898)
		(width 0.12954)
		(layer "F.Cu")
		(net "NC_PVCCINFAON_CPU1_ACSP6")
	)
	(segment
		(start 29.3497 -135.875268)
		(end 28.8798 -136.345168)
		(width 0.12954)
		(layer "F.Cu")
		(net "NC_PVCCINFAON_CPU1_ACSP6")
	)
	(segment
		(start 31.061152 -132.403342)
		(end 30.98038 -132.484114)
		(width 0.12954)
		(layer "F.Cu")
		(net "NC_PVCCINFAON_CPU1_ACSP6")
	)
	(segment
		(start 30.98038 -132.484114)
		(end 30.98038 -134.734808)
		(width 0.12954)
		(layer "F.Cu")
		(net "NC_PVCCINFAON_CPU1_ACSP6")
	)
	(segment
		(start 29.83992 -135.875268)
		(end 29.3497 -135.875268)
		(width 0.12954)
		(layer "F.Cu")
		(net "NC_PVCCINFAON_CPU1_ACSP6")
	)
	(segment
		(start 30.98038 -134.734808)
		(end 29.83992 -135.875268)
		(width 0.12954)
		(layer "F.Cu")
		(net "NC_PVCCINFAON_CPU1_ACSP6")
	)
	(segment
		(start 31.061152 -132.033518)
		(end 31.061152 -132.403342)
		(width 0.12954)
		(layer "F.Cu")
		(net "NC_PVCCINFAON_CPU1_ACSP6")
	)
	(segment
		(start 28.8798 -137.232898)
		(end 29.22524 -137.578338)
		(width 0.12954)
		(layer "F.Cu")
		(net "NC_PVCCINFAON_CPU1_ACSP6")
	)
	(via
		(at 28.8798 -136.345168)
		(size 0.762)
		(drill 0.381)
		(layers "F.Cu" "B.Cu")
		(net "NC_PVCCINFAON_CPU1_ACSP6")
	)
	(segment
		(start 30.19552 -137.123678)
		(end 30.248098 -137.176256)
		(width 0.12954)
		(layer "F.Cu")
		(net "NC_PVCCINFAON_CPU1_ACSP5")
	)
	(segment
		(start 31.461202 -132.475986)
		(end 31.26994 -132.667248)
		(width 0.12954)
		(layer "F.Cu")
		(net "NC_PVCCINFAON_CPU1_ACSP5")
	)
	(segment
		(start 30.248098 -137.176256)
		(end 30.248098 -137.59688)
		(width 0.12954)
		(layer "F.Cu")
		(net "NC_PVCCINFAON_CPU1_ACSP5")
	)
	(segment
		(start 31.26994 -135.288528)
		(end 30.19552 -136.362948)
		(width 0.12954)
		(layer "F.Cu")
		(net "NC_PVCCINFAON_CPU1_ACSP5")
	)
	(segment
		(start 30.19552 -136.362948)
		(end 30.19552 -137.123678)
		(width 0.12954)
		(layer "F.Cu")
		(net "NC_PVCCINFAON_CPU1_ACSP5")
	)
	(segment
		(start 31.461202 -132.033518)
		(end 31.461202 -132.475986)
		(width 0.12954)
		(layer "F.Cu")
		(net "NC_PVCCINFAON_CPU1_ACSP5")
	)
	(segment
		(start 31.26994 -132.667248)
		(end 31.26994 -135.288528)
		(width 0.12954)
		(layer "F.Cu")
		(net "NC_PVCCINFAON_CPU1_ACSP5")
	)
	(via
		(at 30.19552 -136.362948)
		(size 0.762)
		(drill 0.381)
		(layers "F.Cu" "B.Cu")
		(net "NC_PVCCINFAON_CPU1_ACSP5")
	)
	(segment
		(start 31.60649 -136.328658)
		(end 31.60649 -136.899904)
		(width 0.12954)
		(layer "F.Cu")
		(net "NC_PVCCINFAON_CPU1_ACSP4")
	)
	(segment
		(start 31.60649 -136.899904)
		(end 31.307278 -137.199116)
		(width 0.12954)
		(layer "F.Cu")
		(net "NC_PVCCINFAON_CPU1_ACSP4")
	)
	(segment
		(start 31.307278 -137.199116)
		(end 31.307278 -137.61974)
		(width 0.12954)
		(layer "F.Cu")
		(net "NC_PVCCINFAON_CPU1_ACSP4")
	)
	(segment
		(start 31.861252 -132.500116)
		(end 31.58236 -132.779008)
		(width 0.12954)
		(layer "F.Cu")
		(net "NC_PVCCINFAON_CPU1_ACSP4")
	)
	(segment
		(start 31.58236 -132.779008)
		(end 31.58236 -136.304528)
		(width 0.12954)
		(layer "F.Cu")
		(net "NC_PVCCINFAON_CPU1_ACSP4")
	)
	(segment
		(start 31.861252 -132.033518)
		(end 31.861252 -132.500116)
		(width 0.12954)
		(layer "F.Cu")
		(net "NC_PVCCINFAON_CPU1_ACSP4")
	)
	(segment
		(start 31.58236 -136.304528)
		(end 31.60649 -136.328658)
		(width 0.12954)
		(layer "F.Cu")
		(net "NC_PVCCINFAON_CPU1_ACSP4")
	)
	(via
		(at 31.60649 -136.328658)
		(size 0.762)
		(drill 0.381)
		(layers "F.Cu" "B.Cu")
		(net "NC_PVCCINFAON_CPU1_ACSP4")
	)
	(segment
		(start 32.353758 -137.63752)
		(end 32.353758 -137.216896)
		(width 0.12954)
		(layer "F.Cu")
		(net "NC_PVCCINFAON_CPU1_ACSP3")
	)
	(segment
		(start 32.366458 -136.83361)
		(end 32.88792 -136.312148)
		(width 0.12954)
		(layer "F.Cu")
		(net "NC_PVCCINFAON_CPU1_ACSP3")
	)
	(segment
		(start 32.261048 -132.53974)
		(end 32.261048 -132.033518)
		(width 0.12954)
		(layer "F.Cu")
		(net "NC_PVCCINFAON_CPU1_ACSP3")
	)
	(segment
		(start 32.353758 -137.216896)
		(end 32.366458 -137.204196)
		(width 0.12954)
		(layer "F.Cu")
		(net "NC_PVCCINFAON_CPU1_ACSP3")
	)
	(segment
		(start 32.88792 -136.312148)
		(end 31.90494 -135.329168)
		(width 0.12954)
		(layer "F.Cu")
		(net "NC_PVCCINFAON_CPU1_ACSP3")
	)
	(segment
		(start 32.366458 -137.204196)
		(end 32.366458 -136.83361)
		(width 0.12954)
		(layer "F.Cu")
		(net "NC_PVCCINFAON_CPU1_ACSP3")
	)
	(segment
		(start 31.90494 -135.329168)
		(end 31.90494 -132.895848)
		(width 0.12954)
		(layer "F.Cu")
		(net "NC_PVCCINFAON_CPU1_ACSP3")
	)
	(segment
		(start 31.90494 -132.895848)
		(end 32.261048 -132.53974)
		(width 0.12954)
		(layer "F.Cu")
		(net "NC_PVCCINFAON_CPU1_ACSP3")
	)
	(via
		(at 32.88792 -136.312148)
		(size 0.762)
		(drill 0.381)
		(layers "F.Cu" "B.Cu")
		(net "NC_PVCCINFAON_CPU1_ACSP3")
	)
	(segment
		(start 425.35602 -132.390388)
		(end 425.105068 -132.64134)
		(width 0.12954)
		(layer "F.Cu")
		(net "NC_PVCCINFAON_CPU0_APWM5")
	)
	(segment
		(start 425.105068 -132.64134)
		(end 425.105068 -134.014464)
		(width 0.12954)
		(layer "F.Cu")
		(net "NC_PVCCINFAON_CPU0_APWM5")
	)
	(via
		(at 425.35602 -132.390388)
		(size 0.762)
		(drill 0.381)
		(layers "F.Cu" "B.Cu")
		(net "NC_PVCCINFAON_CPU0_APWM5")
	)
	(segment
		(start 424.069002 -140.442442)
		(end 424.069002 -140.55471)
		(width 0.12954)
		(layer "F.Cu")
		(net "NC_PVCCINFAON_CPU0_ACSP7")
	)
	(segment
		(start 424.304968 -139.154916)
		(end 424.304968 -138.814556)
		(width 0.12954)
		(layer "F.Cu")
		(net "NC_PVCCINFAON_CPU0_ACSP7")
	)
	(segment
		(start 423.330878 -141.757654)
		(end 423.330878 -142.269464)
		(width 0.12954)
		(layer "F.Cu")
		(net "NC_PVCCINFAON_CPU0_ACSP7")
	)
	(segment
		(start 422.66616 -142.934182)
		(end 422.66616 -143.275558)
		(width 0.12954)
		(layer "F.Cu")
		(net "NC_PVCCINFAON_CPU0_ACSP7")
	)
	(segment
		(start 424.541188 -139.391136)
		(end 424.304968 -139.154916)
		(width 0.12954)
		(layer "F.Cu")
		(net "NC_PVCCINFAON_CPU0_ACSP7")
	)
	(segment
		(start 424.541188 -139.970256)
		(end 424.541188 -139.391136)
		(width 0.12954)
		(layer "F.Cu")
		(net "NC_PVCCINFAON_CPU0_ACSP7")
	)
	(segment
		(start 424.069002 -140.55471)
		(end 423.740072 -141.34846)
		(width 0.12954)
		(layer "F.Cu")
		(net "NC_PVCCINFAON_CPU0_ACSP7")
	)
	(segment
		(start 424.069002 -140.442442)
		(end 424.541188 -139.970256)
		(width 0.12954)
		(layer "F.Cu")
		(net "NC_PVCCINFAON_CPU0_ACSP7")
	)
	(segment
		(start 423.740072 -141.34846)
		(end 423.330878 -141.757654)
		(width 0.12954)
		(layer "F.Cu")
		(net "NC_PVCCINFAON_CPU0_ACSP7")
	)
	(segment
		(start 423.330878 -142.269464)
		(end 422.66616 -142.934182)
		(width 0.12954)
		(layer "F.Cu")
		(net "NC_PVCCINFAON_CPU0_ACSP7")
	)
	(via
		(at 424.069002 -140.442442)
		(size 0.762)
		(drill 0.381)
		(layers "F.Cu" "B.Cu")
		(net "NC_PVCCINFAON_CPU0_ACSP7")
	)
	(segment
		(start 423.68216 -143.275558)
		(end 423.68216 -142.315946)
		(width 0.12954)
		(layer "F.Cu")
		(net "NC_PVCCINFAON_CPU0_ACSP6")
	)
	(segment
		(start 424.777662 -140.423392)
		(end 424.823128 -140.313918)
		(width 0.12954)
		(layer "F.Cu")
		(net "NC_PVCCINFAON_CPU0_ACSP6")
	)
	(segment
		(start 424.823128 -140.313918)
		(end 424.823128 -139.223242)
		(width 0.12954)
		(layer "F.Cu")
		(net "NC_PVCCINFAON_CPU0_ACSP6")
	)
	(segment
		(start 424.823128 -139.223242)
		(end 424.705018 -139.105132)
		(width 0.12954)
		(layer "F.Cu")
		(net "NC_PVCCINFAON_CPU0_ACSP6")
	)
	(segment
		(start 423.91965 -142.078456)
		(end 423.91965 -141.70787)
		(width 0.12954)
		(layer "F.Cu")
		(net "NC_PVCCINFAON_CPU0_ACSP6")
	)
	(segment
		(start 424.705018 -139.105132)
		(end 424.705018 -138.814556)
		(width 0.12954)
		(layer "F.Cu")
		(net "NC_PVCCINFAON_CPU0_ACSP6")
	)
	(segment
		(start 423.68216 -142.315946)
		(end 423.91965 -142.078456)
		(width 0.12954)
		(layer "F.Cu")
		(net "NC_PVCCINFAON_CPU0_ACSP6")
	)
	(segment
		(start 423.91965 -141.70787)
		(end 424.777662 -140.423392)
		(width 0.12954)
		(layer "F.Cu")
		(net "NC_PVCCINFAON_CPU0_ACSP6")
	)
	(via
		(at 423.91965 -142.078456)
		(size 0.762)
		(drill 0.381)
		(layers "F.Cu" "B.Cu")
		(net "NC_PVCCINFAON_CPU0_ACSP6")
	)
	(segment
		(start 424.789854 -141.230096)
		(end 425.105068 -140.468604)
		(width 0.12954)
		(layer "F.Cu")
		(net "NC_PVCCINFAON_CPU0_ACSP5")
	)
	(segment
		(start 424.69816 -141.530324)
		(end 424.789854 -141.43863)
		(width 0.12954)
		(layer "F.Cu")
		(net "NC_PVCCINFAON_CPU0_ACSP5")
	)
	(segment
		(start 424.789854 -141.43863)
		(end 424.789854 -141.230096)
		(width 0.12954)
		(layer "F.Cu")
		(net "NC_PVCCINFAON_CPU0_ACSP5")
	)
	(segment
		(start 424.69816 -143.275558)
		(end 424.69816 -141.530324)
		(width 0.12954)
		(layer "F.Cu")
		(net "NC_PVCCINFAON_CPU0_ACSP5")
	)
	(segment
		(start 425.105068 -140.468604)
		(end 425.105068 -138.814556)
		(width 0.12954)
		(layer "F.Cu")
		(net "NC_PVCCINFAON_CPU0_ACSP5")
	)
	(via
		(at 424.789854 -141.43863)
		(size 0.762)
		(drill 0.381)
		(layers "F.Cu" "B.Cu")
		(net "NC_PVCCINFAON_CPU0_ACSP5")
	)
	(segment
		(start 425.71416 -143.275558)
		(end 425.71416 -142.177262)
		(width 0.12954)
		(layer "F.Cu")
		(net "NC_PVCCINFAON_CPU0_ACSP4")
	)
	(segment
		(start 425.505118 -139.119356)
		(end 425.505118 -138.814556)
		(width 0.12954)
		(layer "F.Cu")
		(net "NC_PVCCINFAON_CPU0_ACSP4")
	)
	(segment
		(start 425.387008 -139.237466)
		(end 425.505118 -139.119356)
		(width 0.12954)
		(layer "F.Cu")
		(net "NC_PVCCINFAON_CPU0_ACSP4")
	)
	(segment
		(start 425.387008 -141.50721)
		(end 425.387008 -139.237466)
		(width 0.12954)
		(layer "F.Cu")
		(net "NC_PVCCINFAON_CPU0_ACSP4")
	)
	(segment
		(start 425.629324 -142.092426)
		(end 425.387008 -141.50721)
		(width 0.12954)
		(layer "F.Cu")
		(net "NC_PVCCINFAON_CPU0_ACSP4")
	)
	(segment
		(start 425.71416 -142.177262)
		(end 425.629324 -142.092426)
		(width 0.12954)
		(layer "F.Cu")
		(net "NC_PVCCINFAON_CPU0_ACSP4")
	)
	(via
		(at 425.629324 -142.092426)
		(size 0.762)
		(drill 0.381)
		(layers "F.Cu" "B.Cu")
		(net "NC_PVCCINFAON_CPU0_ACSP4")
	)
	(segment
		(start 427.20514 -142.560548)
		(end 427.20514 -142.08252)
		(width 0.12954)
		(layer "F.Cu")
		(net "NC_PVCCINFAON_CPU0_ACSP3")
	)
	(segment
		(start 427.01591 -141.88821)
		(end 426.238162 -141.88821)
		(width 0.12954)
		(layer "F.Cu")
		(net "NC_PVCCINFAON_CPU0_ACSP3")
	)
	(segment
		(start 426.238162 -141.88821)
		(end 425.958254 -141.608302)
		(width 0.12954)
		(layer "F.Cu")
		(net "NC_PVCCINFAON_CPU0_ACSP3")
	)
	(segment
		(start 425.958254 -141.608302)
		(end 425.76496 -141.142212)
		(width 0.12954)
		(layer "F.Cu")
		(net "NC_PVCCINFAON_CPU0_ACSP3")
	)
	(segment
		(start 427.20514 -142.08252)
		(end 427.20514 -142.07744)
		(width 0.12954)
		(layer "F.Cu")
		(net "NC_PVCCINFAON_CPU0_ACSP3")
	)
	(segment
		(start 427.20514 -142.07744)
		(end 427.01591 -141.88821)
		(width 0.12954)
		(layer "F.Cu")
		(net "NC_PVCCINFAON_CPU0_ACSP3")
	)
	(segment
		(start 425.76496 -141.142212)
		(end 425.76496 -139.273534)
		(width 0.12954)
		(layer "F.Cu")
		(net "NC_PVCCINFAON_CPU0_ACSP3")
	)
	(segment
		(start 426.99686 -142.768828)
		(end 427.20514 -142.560548)
		(width 0.12954)
		(layer "F.Cu")
		(net "NC_PVCCINFAON_CPU0_ACSP3")
	)
	(segment
		(start 426.99686 -143.008858)
		(end 426.99686 -142.768828)
		(width 0.12954)
		(layer "F.Cu")
		(net "NC_PVCCINFAON_CPU0_ACSP3")
	)
	(segment
		(start 425.76496 -139.273534)
		(end 425.904914 -139.13358)
		(width 0.12954)
		(layer "F.Cu")
		(net "NC_PVCCINFAON_CPU0_ACSP3")
	)
	(segment
		(start 425.904914 -139.13358)
		(end 425.904914 -138.814556)
		(width 0.12954)
		(layer "F.Cu")
		(net "NC_PVCCINFAON_CPU0_ACSP3")
	)
	(segment
		(start 426.73016 -143.275558)
		(end 426.99686 -143.008858)
		(width 0.12954)
		(layer "F.Cu")
		(net "NC_PVCCINFAON_CPU0_ACSP3")
	)
	(via
		(at 427.20514 -142.08252)
		(size 0.762)
		(drill 0.381)
		(layers "F.Cu" "B.Cu")
		(net "NC_PVCCINFAON_CPU0_ACSP3")
	)
	(segment
		(start 29.462984 -161.998914)
		(end 30.59176 -160.870138)
		(width 0.12954)
		(layer "F.Cu")
		(net "NC_PVCCD_HV_CPU1_ACSP8")
	)
	(segment
		(start 29.462984 -162.427158)
		(end 29.462984 -161.998914)
		(width 0.12954)
		(layer "F.Cu")
		(net "NC_PVCCD_HV_CPU1_ACSP8")
	)
	(via
		(at 29.82722 -161.557208)
		(size 0.6604)
		(drill 0.3302)
		(layers "F.Cu" "B.Cu")
		(net "NC_PVCCD_HV_CPU1_ACSP8")
	)
	(via
		(at 30.59176 -160.870138)
		(size 0.508)
		(drill 0.254)
		(layers "F.Cu" "B.Cu")
		(net "NC_PVCCD_HV_CPU1_ACSP8")
	)
	(segment
		(start 30.56763 -160.870138)
		(end 29.88056 -161.557208)
		(width 0.12954)
		(layer "B.Cu")
		(net "NC_PVCCD_HV_CPU1_ACSP8")
	)
	(segment
		(start 29.82722 -162.237166)
		(end 30.62605 -163.035996)
		(width 0.12954)
		(layer "B.Cu")
		(net "NC_PVCCD_HV_CPU1_ACSP8")
	)
	(segment
		(start 29.88056 -161.557208)
		(end 29.82722 -161.557208)
		(width 0.12954)
		(layer "B.Cu")
		(net "NC_PVCCD_HV_CPU1_ACSP8")
	)
	(segment
		(start 30.59176 -160.870138)
		(end 30.56763 -160.870138)
		(width 0.12954)
		(layer "B.Cu")
		(net "NC_PVCCD_HV_CPU1_ACSP8")
	)
	(segment
		(start 29.82722 -161.557208)
		(end 29.82722 -162.237166)
		(width 0.12954)
		(layer "B.Cu")
		(net "NC_PVCCD_HV_CPU1_ACSP8")
	)
	(segment
		(start 30.62605 -163.035996)
		(end 30.62605 -163.261548)
		(width 0.12954)
		(layer "B.Cu")
		(net "NC_PVCCD_HV_CPU1_ACSP8")
	)
	(segment
		(start 29.388816 -161.360612)
		(end 29.9085 -160.840928)
		(width 0.12954)
		(layer "F.Cu")
		(net "NC_PVCCD_HV_CPU1_ACSP7")
	)
	(segment
		(start 29.062934 -161.686494)
		(end 29.388816 -161.360612)
		(width 0.12954)
		(layer "F.Cu")
		(net "NC_PVCCD_HV_CPU1_ACSP7")
	)
	(segment
		(start 29.062934 -162.427158)
		(end 29.062934 -161.686494)
		(width 0.12954)
		(layer "F.Cu")
		(net "NC_PVCCD_HV_CPU1_ACSP7")
	)
	(via
		(at 29.388816 -161.360612)
		(size 0.4064)
		(drill 0.2032)
		(layers "F.Cu" "B.Cu")
		(net "NC_PVCCD_HV_CPU1_ACSP7")
	)
	(via
		(at 29.9085 -160.840928)
		(size 0.508)
		(drill 0.254)
		(layers "F.Cu" "B.Cu")
		(net "NC_PVCCD_HV_CPU1_ACSP7")
	)
	(segment
		(start 28.6766 -161.98088)
		(end 28.6766 -162.023298)
		(width 0.12954)
		(layer "B.Cu")
		(net "NC_PVCCD_HV_CPU1_ACSP7")
	)
	(segment
		(start 29.728668 -160.840928)
		(end 29.340048 -161.229548)
		(width 0.12954)
		(layer "B.Cu")
		(net "NC_PVCCD_HV_CPU1_ACSP7")
	)
	(segment
		(start 28.80614 -161.727134)
		(end 28.80614 -161.85134)
		(width 0.12954)
		(layer "B.Cu")
		(net "NC_PVCCD_HV_CPU1_ACSP7")
	)
	(segment
		(start 28.80614 -161.85134)
		(end 28.6766 -161.98088)
		(width 0.12954)
		(layer "B.Cu")
		(net "NC_PVCCD_HV_CPU1_ACSP7")
	)
	(segment
		(start 29.9085 -160.840928)
		(end 29.728668 -160.840928)
		(width 0.12954)
		(layer "B.Cu")
		(net "NC_PVCCD_HV_CPU1_ACSP7")
	)
	(segment
		(start 29.340048 -161.229548)
		(end 29.303726 -161.229548)
		(width 0.12954)
		(layer "B.Cu")
		(net "NC_PVCCD_HV_CPU1_ACSP7")
	)
	(segment
		(start 29.303726 -161.229548)
		(end 28.80614 -161.727134)
		(width 0.12954)
		(layer "B.Cu")
		(net "NC_PVCCD_HV_CPU1_ACSP7")
	)
	(segment
		(start 28.662884 -162.427158)
		(end 28.662884 -161.220404)
		(width 0.12954)
		(layer "F.Cu")
		(net "NC_PVCCD_HV_CPU1_ACSP6")
	)
	(segment
		(start 28.662884 -161.220404)
		(end 29.09316 -160.790128)
		(width 0.12954)
		(layer "F.Cu")
		(net "NC_PVCCD_HV_CPU1_ACSP6")
	)
	(via
		(at 29.09316 -160.790128)
		(size 0.508)
		(drill 0.254)
		(layers "F.Cu" "B.Cu")
		(net "NC_PVCCD_HV_CPU1_ACSP6")
	)
	(segment
		(start 28.636976 -161.246312)
		(end 27.940762 -161.246312)
		(width 0.12954)
		(layer "B.Cu")
		(net "NC_PVCCD_HV_CPU1_ACSP6")
	)
	(segment
		(start 27.7368 -161.450274)
		(end 27.7368 -161.870898)
		(width 0.12954)
		(layer "B.Cu")
		(net "NC_PVCCD_HV_CPU1_ACSP6")
	)
	(segment
		(start 29.09316 -160.790128)
		(end 28.636976 -161.246312)
		(width 0.12954)
		(layer "B.Cu")
		(net "NC_PVCCD_HV_CPU1_ACSP6")
	)
	(segment
		(start 27.940762 -161.246312)
		(end 27.7368 -161.450274)
		(width 0.12954)
		(layer "B.Cu")
		(net "NC_PVCCD_HV_CPU1_ACSP6")
	)
	(segment
		(start 28.262834 -160.927034)
		(end 28.42768 -160.762188)
		(width 0.12954)
		(layer "F.Cu")
		(net "NC_PVCCD_HV_CPU1_ACSP5")
	)
	(segment
		(start 28.262834 -162.427158)
		(end 28.262834 -160.927034)
		(width 0.12954)
		(layer "F.Cu")
		(net "NC_PVCCD_HV_CPU1_ACSP5")
	)
	(via
		(at 28.42768 -160.762188)
		(size 0.508)
		(drill 0.254)
		(layers "F.Cu" "B.Cu")
		(net "NC_PVCCD_HV_CPU1_ACSP5")
	)
	(via
		(at 24.78024 -161.956496)
		(size 0.6604)
		(drill 0.3302)
		(layers "F.Cu" "B.Cu")
		(net "NC_PVCCD_HV_CPU1_ACSP5")
	)
	(segment
		(start 26.370788 -162.057334)
		(end 25.46985 -162.057334)
		(width 0.12954)
		(layer "B.Cu")
		(net "NC_PVCCD_HV_CPU1_ACSP5")
	)
	(segment
		(start 27.017218 -161.568384)
		(end 26.859738 -161.568384)
		(width 0.12954)
		(layer "B.Cu")
		(net "NC_PVCCD_HV_CPU1_ACSP5")
	)
	(segment
		(start 28.42768 -160.762188)
		(end 27.823414 -160.762188)
		(width 0.12954)
		(layer "B.Cu")
		(net "NC_PVCCD_HV_CPU1_ACSP5")
	)
	(segment
		(start 27.823414 -160.762188)
		(end 27.017218 -161.568384)
		(width 0.12954)
		(layer "B.Cu")
		(net "NC_PVCCD_HV_CPU1_ACSP5")
	)
	(segment
		(start 24.898858 -162.429698)
		(end 26.7716 -162.429698)
		(width 0.12954)
		(layer "B.Cu")
		(net "NC_PVCCD_HV_CPU1_ACSP5")
	)
	(segment
		(start 24.78024 -161.956496)
		(end 24.78024 -162.31108)
		(width 0.12954)
		(layer "B.Cu")
		(net "NC_PVCCD_HV_CPU1_ACSP5")
	)
	(segment
		(start 25.46985 -162.057334)
		(end 25.369012 -161.956496)
		(width 0.12954)
		(layer "B.Cu")
		(net "NC_PVCCD_HV_CPU1_ACSP5")
	)
	(segment
		(start 26.859738 -161.568384)
		(end 26.370788 -162.057334)
		(width 0.12954)
		(layer "B.Cu")
		(net "NC_PVCCD_HV_CPU1_ACSP5")
	)
	(segment
		(start 24.78024 -162.31108)
		(end 24.898858 -162.429698)
		(width 0.12954)
		(layer "B.Cu")
		(net "NC_PVCCD_HV_CPU1_ACSP5")
	)
	(segment
		(start 25.369012 -161.956496)
		(end 24.78024 -161.956496)
		(width 0.12954)
		(layer "B.Cu")
		(net "NC_PVCCD_HV_CPU1_ACSP5")
	)
	(segment
		(start 27.862784 -160.415478)
		(end 28.034996 -160.243266)
		(width 0.12954)
		(layer "F.Cu")
		(net "NC_PVCCD_HV_CPU1_ACSP4")
	)
	(segment
		(start 27.862784 -162.427158)
		(end 27.862784 -160.415478)
		(width 0.12954)
		(layer "F.Cu")
		(net "NC_PVCCD_HV_CPU1_ACSP4")
	)
	(via
		(at 28.034996 -160.243266)
		(size 0.508)
		(drill 0.254)
		(layers "F.Cu" "B.Cu")
		(net "NC_PVCCD_HV_CPU1_ACSP4")
	)
	(via
		(at 23.00351 -161.699448)
		(size 0.6604)
		(drill 0.3302)
		(layers "F.Cu" "B.Cu")
		(net "NC_PVCCD_HV_CPU1_ACSP4")
	)
	(segment
		(start 22.49805 -162.204908)
		(end 23.00351 -161.699448)
		(width 0.12954)
		(layer "B.Cu")
		(net "NC_PVCCD_HV_CPU1_ACSP4")
	)
	(segment
		(start 28.034996 -160.243266)
		(end 26.531824 -158.740094)
		(width 0.12954)
		(layer "B.Cu")
		(net "NC_PVCCD_HV_CPU1_ACSP4")
	)
	(segment
		(start 24.477472 -165.059106)
		(end 23.674578 -164.256212)
		(width 0.12954)
		(layer "B.Cu")
		(net "NC_PVCCD_HV_CPU1_ACSP4")
	)
	(segment
		(start 22.957536 -164.256212)
		(end 22.49805 -163.796726)
		(width 0.12954)
		(layer "B.Cu")
		(net "NC_PVCCD_HV_CPU1_ACSP4")
	)
	(segment
		(start 23.00351 -160.302702)
		(end 23.00351 -161.699448)
		(width 0.12954)
		(layer "B.Cu")
		(net "NC_PVCCD_HV_CPU1_ACSP4")
	)
	(segment
		(start 23.674578 -164.256212)
		(end 22.957536 -164.256212)
		(width 0.12954)
		(layer "B.Cu")
		(net "NC_PVCCD_HV_CPU1_ACSP4")
	)
	(segment
		(start 26.531824 -158.740094)
		(end 24.566118 -158.740094)
		(width 0.12954)
		(layer "B.Cu")
		(net "NC_PVCCD_HV_CPU1_ACSP4")
	)
	(segment
		(start 22.49805 -163.796726)
		(end 22.49805 -162.204908)
		(width 0.12954)
		(layer "B.Cu")
		(net "NC_PVCCD_HV_CPU1_ACSP4")
	)
	(segment
		(start 24.566118 -158.740094)
		(end 23.00351 -160.302702)
		(width 0.12954)
		(layer "B.Cu")
		(net "NC_PVCCD_HV_CPU1_ACSP4")
	)
	(segment
		(start 27.462988 -160.4137)
		(end 27.302206 -160.252918)
		(width 0.12954)
		(layer "F.Cu")
		(net "NC_PVCCD_HV_CPU1_ACSP3")
	)
	(segment
		(start 27.462988 -162.427158)
		(end 27.462988 -160.4137)
		(width 0.12954)
		(layer "F.Cu")
		(net "NC_PVCCD_HV_CPU1_ACSP3")
	)
	(via
		(at 27.302206 -160.252918)
		(size 0.508)
		(drill 0.254)
		(layers "F.Cu" "B.Cu")
		(net "NC_PVCCD_HV_CPU1_ACSP3")
	)
	(via
		(at 23.639526 -160.506918)
		(size 0.6604)
		(drill 0.3302)
		(layers "F.Cu" "B.Cu")
		(net "NC_PVCCD_HV_CPU1_ACSP3")
	)
	(segment
		(start 24.64562 -159.32658)
		(end 23.639526 -160.332674)
		(width 0.12954)
		(layer "B.Cu")
		(net "NC_PVCCD_HV_CPU1_ACSP3")
	)
	(segment
		(start 26.375868 -159.32658)
		(end 24.64562 -159.32658)
		(width 0.12954)
		(layer "B.Cu")
		(net "NC_PVCCD_HV_CPU1_ACSP3")
	)
	(segment
		(start 27.302206 -160.252918)
		(end 26.375868 -159.32658)
		(width 0.12954)
		(layer "B.Cu")
		(net "NC_PVCCD_HV_CPU1_ACSP3")
	)
	(segment
		(start 23.639526 -160.506918)
		(end 23.639526 -163.23818)
		(width 0.12954)
		(layer "B.Cu")
		(net "NC_PVCCD_HV_CPU1_ACSP3")
	)
	(segment
		(start 23.639526 -160.332674)
		(end 23.639526 -160.506918)
		(width 0.12954)
		(layer "B.Cu")
		(net "NC_PVCCD_HV_CPU1_ACSP3")
	)
	(segment
		(start 23.639526 -163.23818)
		(end 24.487632 -164.086286)
		(width 0.12954)
		(layer "B.Cu")
		(net "NC_PVCCD_HV_CPU1_ACSP3")
	)
	(segment
		(start 27.062938 -162.427158)
		(end 27.062938 -161.078926)
		(width 0.12954)
		(layer "F.Cu")
		(net "NC_PVCCD_HV_CPU1_ACSP2")
	)
	(segment
		(start 27.062938 -161.078926)
		(end 26.95194 -160.967928)
		(width 0.12954)
		(layer "F.Cu")
		(net "NC_PVCCD_HV_CPU1_ACSP2")
	)
	(via
		(at 25.01646 -159.891984)
		(size 0.6604)
		(drill 0.3302)
		(layers "F.Cu" "B.Cu")
		(net "NC_PVCCD_HV_CPU1_ACSP2")
	)
	(via
		(at 26.95194 -160.967928)
		(size 0.508)
		(drill 0.254)
		(layers "F.Cu" "B.Cu")
		(net "NC_PVCCD_HV_CPU1_ACSP2")
	)
	(segment
		(start 25.01646 -159.891984)
		(end 26.051256 -159.891984)
		(width 0.12954)
		(layer "B.Cu")
		(net "NC_PVCCD_HV_CPU1_ACSP2")
	)
	(segment
		(start 26.95194 -160.792668)
		(end 26.95194 -160.967928)
		(width 0.12954)
		(layer "B.Cu")
		(net "NC_PVCCD_HV_CPU1_ACSP2")
	)
	(segment
		(start 24.495252 -163.105846)
		(end 24.194262 -162.804856)
		(width 0.12954)
		(layer "B.Cu")
		(net "NC_PVCCD_HV_CPU1_ACSP2")
	)
	(segment
		(start 24.194262 -162.804856)
		(end 24.194262 -160.714182)
		(width 0.12954)
		(layer "B.Cu")
		(net "NC_PVCCD_HV_CPU1_ACSP2")
	)
	(segment
		(start 24.194262 -160.714182)
		(end 25.01646 -159.891984)
		(width 0.12954)
		(layer "B.Cu")
		(net "NC_PVCCD_HV_CPU1_ACSP2")
	)
	(segment
		(start 26.051256 -159.891984)
		(end 26.95194 -160.792668)
		(width 0.12954)
		(layer "B.Cu")
		(net "NC_PVCCD_HV_CPU1_ACSP2")
	)
	(segment
		(start 430.28362 -126.544832)
		(end 430.28362 -126.014988)
		(width 0.12954)
		(layer "F.Cu")
		(net "NC_PVCCD_HV_CPU0_ACSP8")
	)
	(segment
		(start 430.700942 -125.597666)
		(end 430.700942 -125.388624)
		(width 0.12954)
		(layer "F.Cu")
		(net "NC_PVCCD_HV_CPU0_ACSP8")
	)
	(segment
		(start 430.28362 -126.014988)
		(end 430.700942 -125.597666)
		(width 0.12954)
		(layer "F.Cu")
		(net "NC_PVCCD_HV_CPU0_ACSP8")
	)
	(segment
		(start 430.202594 -126.625858)
		(end 430.28362 -126.544832)
		(width 0.12954)
		(layer "F.Cu")
		(net "NC_PVCCD_HV_CPU0_ACSP8")
	)
	(via
		(at 430.202594 -126.625858)
		(size 0.508)
		(drill 0.254)
		(layers "F.Cu" "B.Cu")
		(net "NC_PVCCD_HV_CPU0_ACSP8")
	)
	(segment
		(start 430.362614 -125.56617)
		(end 430.362106 -125.565662)
		(width 0.12954)
		(layer "B.Cu")
		(net "NC_PVCCD_HV_CPU0_ACSP8")
	)
	(segment
		(start 430.202594 -126.625858)
		(end 430.235614 -126.625858)
		(width 0.12954)
		(layer "B.Cu")
		(net "NC_PVCCD_HV_CPU0_ACSP8")
	)
	(segment
		(start 430.362614 -126.498858)
		(end 430.362614 -125.56617)
		(width 0.12954)
		(layer "B.Cu")
		(net "NC_PVCCD_HV_CPU0_ACSP8")
	)
	(segment
		(start 430.235614 -126.625858)
		(end 430.362614 -126.498858)
		(width 0.12954)
		(layer "B.Cu")
		(net "NC_PVCCD_HV_CPU0_ACSP8")
	)
	(segment
		(start 430.2887 -127.361188)
		(end 430.65319 -126.996698)
		(width 0.12954)
		(layer "F.Cu")
		(net "NC_PVCCD_HV_CPU0_ACSP7")
	)
	(segment
		(start 431.100992 -125.659896)
		(end 431.100992 -125.388624)
		(width 0.12954)
		(layer "F.Cu")
		(net "NC_PVCCD_HV_CPU0_ACSP7")
	)
	(segment
		(start 430.784 -125.976888)
		(end 431.100992 -125.659896)
		(width 0.12954)
		(layer "F.Cu")
		(net "NC_PVCCD_HV_CPU0_ACSP7")
	)
	(segment
		(start 430.65319 -126.996698)
		(end 430.784 -126.680722)
		(width 0.12954)
		(layer "F.Cu")
		(net "NC_PVCCD_HV_CPU0_ACSP7")
	)
	(segment
		(start 430.784 -126.680722)
		(end 430.784 -125.976888)
		(width 0.12954)
		(layer "F.Cu")
		(net "NC_PVCCD_HV_CPU0_ACSP7")
	)
	(via
		(at 430.316132 -128.23825)
		(size 0.6604)
		(drill 0.3302)
		(layers "F.Cu" "B.Cu")
		(net "NC_PVCCD_HV_CPU0_ACSP7")
	)
	(via
		(at 430.2887 -127.361188)
		(size 0.508)
		(drill 0.254)
		(layers "F.Cu" "B.Cu")
		(net "NC_PVCCD_HV_CPU0_ACSP7")
	)
	(segment
		(start 431.431192 -128.23825)
		(end 430.316132 -128.23825)
		(width 0.12954)
		(layer "B.Cu")
		(net "NC_PVCCD_HV_CPU0_ACSP7")
	)
	(segment
		(start 430.27346 -128.195578)
		(end 430.27346 -127.376428)
		(width 0.12954)
		(layer "B.Cu")
		(net "NC_PVCCD_HV_CPU0_ACSP7")
	)
	(segment
		(start 431.5841 -128.391158)
		(end 431.431192 -128.23825)
		(width 0.12954)
		(layer "B.Cu")
		(net "NC_PVCCD_HV_CPU0_ACSP7")
	)
	(segment
		(start 430.27346 -127.376428)
		(end 430.2887 -127.361188)
		(width 0.12954)
		(layer "B.Cu")
		(net "NC_PVCCD_HV_CPU0_ACSP7")
	)
	(segment
		(start 430.316132 -128.23825)
		(end 430.27346 -128.195578)
		(width 0.12954)
		(layer "B.Cu")
		(net "NC_PVCCD_HV_CPU0_ACSP7")
	)
	(segment
		(start 431.09134 -126.154688)
		(end 431.501042 -125.744986)
		(width 0.12954)
		(layer "F.Cu")
		(net "NC_PVCCD_HV_CPU0_ACSP6")
	)
	(segment
		(start 431.501042 -125.744986)
		(end 431.501042 -125.388624)
		(width 0.12954)
		(layer "F.Cu")
		(net "NC_PVCCD_HV_CPU0_ACSP6")
	)
	(segment
		(start 431.09134 -127.203708)
		(end 431.09134 -126.154688)
		(width 0.12954)
		(layer "F.Cu")
		(net "NC_PVCCD_HV_CPU0_ACSP6")
	)
	(via
		(at 431.09134 -127.203708)
		(size 0.508)
		(drill 0.254)
		(layers "F.Cu" "B.Cu")
		(net "NC_PVCCD_HV_CPU0_ACSP6")
	)
	(segment
		(start 431.09134 -127.203708)
		(end 431.09134 -125.945138)
		(width 0.12954)
		(layer "B.Cu")
		(net "NC_PVCCD_HV_CPU0_ACSP6")
	)
	(segment
		(start 431.70348 -125.332998)
		(end 431.72888 -125.332998)
		(width 0.12954)
		(layer "B.Cu")
		(net "NC_PVCCD_HV_CPU0_ACSP6")
	)
	(segment
		(start 431.09134 -125.945138)
		(end 431.70348 -125.332998)
		(width 0.12954)
		(layer "B.Cu")
		(net "NC_PVCCD_HV_CPU0_ACSP6")
	)
	(segment
		(start 431.6222 -126.055628)
		(end 431.901092 -125.776736)
		(width 0.12954)
		(layer "F.Cu")
		(net "NC_PVCCD_HV_CPU0_ACSP5")
	)
	(segment
		(start 431.901092 -125.776736)
		(end 431.901092 -125.388624)
		(width 0.12954)
		(layer "F.Cu")
		(net "NC_PVCCD_HV_CPU0_ACSP5")
	)
	(segment
		(start 431.6222 -126.652528)
		(end 431.6222 -126.055628)
		(width 0.12954)
		(layer "F.Cu")
		(net "NC_PVCCD_HV_CPU0_ACSP5")
	)
	(via
		(at 431.6222 -126.652528)
		(size 0.508)
		(drill 0.254)
		(layers "F.Cu" "B.Cu")
		(net "NC_PVCCD_HV_CPU0_ACSP5")
	)
	(segment
		(start 431.6222 -126.652528)
		(end 431.6222 -126.205488)
		(width 0.12954)
		(layer "B.Cu")
		(net "NC_PVCCD_HV_CPU0_ACSP5")
	)
	(segment
		(start 432.49469 -125.332998)
		(end 433.25288 -125.332998)
		(width 0.12954)
		(layer "B.Cu")
		(net "NC_PVCCD_HV_CPU0_ACSP5")
	)
	(segment
		(start 431.6222 -126.205488)
		(end 432.49469 -125.332998)
		(width 0.12954)
		(layer "B.Cu")
		(net "NC_PVCCD_HV_CPU0_ACSP5")
	)
	(segment
		(start 432.301142 -126.197106)
		(end 432.301142 -125.388624)
		(width 0.12954)
		(layer "F.Cu")
		(net "NC_PVCCD_HV_CPU0_ACSP4")
	)
	(segment
		(start 432.21529 -126.282958)
		(end 432.301142 -126.197106)
		(width 0.12954)
		(layer "F.Cu")
		(net "NC_PVCCD_HV_CPU0_ACSP4")
	)
	(via
		(at 432.21529 -126.282958)
		(size 0.508)
		(drill 0.254)
		(layers "F.Cu" "B.Cu")
		(net "NC_PVCCD_HV_CPU0_ACSP4")
	)
	(via
		(at 434.77688 -126.482856)
		(size 0.6604)
		(drill 0.3302)
		(layers "F.Cu" "B.Cu")
		(net "NC_PVCCD_HV_CPU0_ACSP4")
	)
	(segment
		(start 434.090572 -125.796548)
		(end 432.7017 -125.796548)
		(width 0.12954)
		(layer "B.Cu")
		(net "NC_PVCCD_HV_CPU0_ACSP4")
	)
	(segment
		(start 434.77688 -126.482856)
		(end 434.090572 -125.796548)
		(width 0.12954)
		(layer "B.Cu")
		(net "NC_PVCCD_HV_CPU0_ACSP4")
	)
	(segment
		(start 434.77688 -125.332998)
		(end 434.77688 -126.482856)
		(width 0.12954)
		(layer "B.Cu")
		(net "NC_PVCCD_HV_CPU0_ACSP4")
	)
	(segment
		(start 432.7017 -125.796548)
		(end 432.21529 -126.282958)
		(width 0.12954)
		(layer "B.Cu")
		(net "NC_PVCCD_HV_CPU0_ACSP4")
	)
	(segment
		(start 432.072542 -126.835916)
		(end 431.67173 -127.236728)
		(width 0.12954)
		(layer "F.Cu")
		(net "NC_PVCCD_HV_CPU0_ACSP3")
	)
	(segment
		(start 432.314858 -126.835916)
		(end 432.072542 -126.835916)
		(width 0.12954)
		(layer "F.Cu")
		(net "NC_PVCCD_HV_CPU0_ACSP3")
	)
	(segment
		(start 432.700938 -125.625606)
		(end 432.74488 -125.669548)
		(width 0.12954)
		(layer "F.Cu")
		(net "NC_PVCCD_HV_CPU0_ACSP3")
	)
	(segment
		(start 432.74488 -126.405894)
		(end 432.4858 -126.664974)
		(width 0.12954)
		(layer "F.Cu")
		(net "NC_PVCCD_HV_CPU0_ACSP3")
	)
	(segment
		(start 432.4858 -126.664974)
		(end 432.314858 -126.835916)
		(width 0.12954)
		(layer "F.Cu")
		(net "NC_PVCCD_HV_CPU0_ACSP3")
	)
	(segment
		(start 431.67173 -127.236728)
		(end 431.47488 -127.711708)
		(width 0.12954)
		(layer "F.Cu")
		(net "NC_PVCCD_HV_CPU0_ACSP3")
	)
	(segment
		(start 431.47488 -127.711708)
		(end 431.47488 -127.961898)
		(width 0.12954)
		(layer "F.Cu")
		(net "NC_PVCCD_HV_CPU0_ACSP3")
	)
	(segment
		(start 432.700938 -125.388624)
		(end 432.700938 -125.625606)
		(width 0.12954)
		(layer "F.Cu")
		(net "NC_PVCCD_HV_CPU0_ACSP3")
	)
	(segment
		(start 432.74488 -125.669548)
		(end 432.74488 -126.405894)
		(width 0.12954)
		(layer "F.Cu")
		(net "NC_PVCCD_HV_CPU0_ACSP3")
	)
	(via
		(at 432.4858 -126.664974)
		(size 0.4064)
		(drill 0.2032)
		(layers "F.Cu" "B.Cu")
		(net "NC_PVCCD_HV_CPU0_ACSP3")
	)
	(segment
		(start 433.100988 -125.61824)
		(end 433.100988 -125.388624)
		(width 0.12954)
		(layer "F.Cu")
		(net "NC_PVCCD_HV_CPU0_ACSP2")
	)
	(segment
		(start 432.74488 -127.819658)
		(end 432.259994 -127.334772)
		(width 0.12954)
		(layer "F.Cu")
		(net "NC_PVCCD_HV_CPU0_ACSP2")
	)
	(segment
		(start 432.259994 -127.334772)
		(end 433.02682 -126.567946)
		(width 0.12954)
		(layer "F.Cu")
		(net "NC_PVCCD_HV_CPU0_ACSP2")
	)
	(segment
		(start 433.02682 -126.567946)
		(end 433.02682 -125.692408)
		(width 0.12954)
		(layer "F.Cu")
		(net "NC_PVCCD_HV_CPU0_ACSP2")
	)
	(segment
		(start 432.74488 -127.961898)
		(end 432.74488 -127.819658)
		(width 0.12954)
		(layer "F.Cu")
		(net "NC_PVCCD_HV_CPU0_ACSP2")
	)
	(segment
		(start 433.02682 -125.692408)
		(end 433.100988 -125.61824)
		(width 0.12954)
		(layer "F.Cu")
		(net "NC_PVCCD_HV_CPU0_ACSP2")
	)
	(via
		(at 432.259994 -127.334772)
		(size 0.508)
		(drill 0.254)
		(layers "F.Cu" "B.Cu")
		(net "NC_PVCCD_HV_CPU0_ACSP2")
	)
	(segment
		(start 345.403932 -57.56021)
		(end 345.403932 -58.020204)
		(width 0.0889)
		(layer "F.Cu")
		(net "NC_PCH_RSVD<9>")
	)
	(segment
		(start 345.487244 -57.476898)
		(end 345.403932 -57.56021)
		(width 0.0889)
		(layer "F.Cu")
		(net "NC_PCH_RSVD<9>")
	)
	(segment
		(start 345.487244 -57.471056)
		(end 345.487244 -57.476898)
		(width 0.0889)
		(layer "F.Cu")
		(net "NC_PCH_RSVD<9>")
	)
	(via
		(at 345.487244 -57.471056)
		(size 0.4572)
		(drill 0.2032)
		(layers "F.Cu" "B.Cu")
		(net "NC_PCH_RSVD<9>")
	)
	(segment
		(start 345.69908 -58.971688)
		(end 345.876626 -58.754772)
		(width 0.0889)
		(layer "F.Cu")
		(net "NC_PCH_RSVD<8>")
	)
	(segment
		(start 346.456254 -60.19292)
		(end 345.967558 -59.704224)
		(width 0.0889)
		(layer "F.Cu")
		(net "NC_PCH_RSVD<8>")
	)
	(segment
		(start 345.876626 -58.754772)
		(end 345.904058 -58.688986)
		(width 0.0889)
		(layer "F.Cu")
		(net "NC_PCH_RSVD<8>")
	)
	(segment
		(start 345.547442 -59.49696)
		(end 345.547442 -59.138566)
		(width 0.0889)
		(layer "F.Cu")
		(net "NC_PCH_RSVD<8>")
	)
	(segment
		(start 345.904058 -58.688986)
		(end 345.904058 -58.43524)
		(width 0.0889)
		(layer "F.Cu")
		(net "NC_PCH_RSVD<8>")
	)
	(segment
		(start 345.967558 -59.704224)
		(end 345.604084 -59.553602)
		(width 0.0889)
		(layer "F.Cu")
		(net "NC_PCH_RSVD<8>")
	)
	(segment
		(start 345.604084 -59.553602)
		(end 345.547442 -59.49696)
		(width 0.0889)
		(layer "F.Cu")
		(net "NC_PCH_RSVD<8>")
	)
	(segment
		(start 348.33687 -60.19292)
		(end 346.456254 -60.19292)
		(width 0.12954)
		(layer "F.Cu")
		(net "NC_PCH_RSVD<8>")
	)
	(segment
		(start 345.547442 -59.138566)
		(end 345.69908 -58.971688)
		(width 0.0889)
		(layer "F.Cu")
		(net "NC_PCH_RSVD<8>")
	)
	(segment
		(start 349.407226 -60.010294)
		(end 348.519496 -60.010294)
		(width 0.12954)
		(layer "F.Cu")
		(net "NC_PCH_RSVD<8>")
	)
	(segment
		(start 348.519496 -60.010294)
		(end 348.33687 -60.19292)
		(width 0.12954)
		(layer "F.Cu")
		(net "NC_PCH_RSVD<8>")
	)
	(via
		(at 349.407226 -60.010294)
		(size 0.508)
		(drill 0.254)
		(layers "F.Cu" "B.Cu")
		(net "NC_PCH_RSVD<8>")
	)
	(segment
		(start 335.953608 -41.871646)
		(end 336.49285 -41.871646)
		(width 0.12954)
		(layer "F.Cu")
		(net "NC_PCH_RSVD<4>")
	)
	(via
		(at 346.269564 -39.548562)
		(size 0.6604)
		(drill 0.3302)
		(layers "F.Cu" "B.Cu")
		(net "NC_PCH_RSVD<4>")
	)
	(via
		(at 335.953608 -41.871646)
		(size 0.4572)
		(drill 0.2032)
		(layers "F.Cu" "B.Cu")
		(net "NC_PCH_RSVD<4>")
	)
	(segment
		(start 336.646774 -41.578784)
		(end 336.353912 -41.871646)
		(width 0.12954)
		(layer "B.Cu")
		(net "NC_PCH_RSVD<4>")
	)
	(segment
		(start 343.616534 -42.37482)
		(end 343.433146 -42.37482)
		(width 0.12954)
		(layer "B.Cu")
		(net "NC_PCH_RSVD<4>")
	)
	(segment
		(start 342.95588 -41.897554)
		(end 342.483186 -41.897554)
		(width 0.12954)
		(layer "B.Cu")
		(net "NC_PCH_RSVD<4>")
	)
	(segment
		(start 337.804506 -41.424606)
		(end 337.172554 -41.424606)
		(width 0.12954)
		(layer "B.Cu")
		(net "NC_PCH_RSVD<4>")
	)
	(segment
		(start 346.269564 -39.548562)
		(end 346.887038 -40.166036)
		(width 0.12954)
		(layer "B.Cu")
		(net "NC_PCH_RSVD<4>")
	)
	(segment
		(start 346.265246 -41.877996)
		(end 344.113358 -41.877996)
		(width 0.12954)
		(layer "B.Cu")
		(net "NC_PCH_RSVD<4>")
	)
	(segment
		(start 337.172554 -41.424606)
		(end 337.018376 -41.578784)
		(width 0.12954)
		(layer "B.Cu")
		(net "NC_PCH_RSVD<4>")
	)
	(segment
		(start 338.952332 -42.30243)
		(end 338.450682 -41.80078)
		(width 0.12954)
		(layer "B.Cu")
		(net "NC_PCH_RSVD<4>")
	)
	(segment
		(start 340.838282 -41.8973)
		(end 340.433152 -42.30243)
		(width 0.12954)
		(layer "B.Cu")
		(net "NC_PCH_RSVD<4>")
	)
	(segment
		(start 338.450682 -41.80078)
		(end 338.18068 -41.80078)
		(width 0.12954)
		(layer "B.Cu")
		(net "NC_PCH_RSVD<4>")
	)
	(segment
		(start 341.672926 -42.28338)
		(end 341.286846 -41.8973)
		(width 0.12954)
		(layer "B.Cu")
		(net "NC_PCH_RSVD<4>")
	)
	(segment
		(start 346.887038 -40.166036)
		(end 346.887038 -41.256204)
		(width 0.12954)
		(layer "B.Cu")
		(net "NC_PCH_RSVD<4>")
	)
	(segment
		(start 337.018376 -41.578784)
		(end 336.646774 -41.578784)
		(width 0.12954)
		(layer "B.Cu")
		(net "NC_PCH_RSVD<4>")
	)
	(segment
		(start 342.483186 -41.897554)
		(end 342.09736 -42.28338)
		(width 0.12954)
		(layer "B.Cu")
		(net "NC_PCH_RSVD<4>")
	)
	(segment
		(start 338.18068 -41.80078)
		(end 337.804506 -41.424606)
		(width 0.12954)
		(layer "B.Cu")
		(net "NC_PCH_RSVD<4>")
	)
	(segment
		(start 346.887038 -41.256204)
		(end 346.265246 -41.877996)
		(width 0.12954)
		(layer "B.Cu")
		(net "NC_PCH_RSVD<4>")
	)
	(segment
		(start 340.433152 -42.30243)
		(end 338.952332 -42.30243)
		(width 0.12954)
		(layer "B.Cu")
		(net "NC_PCH_RSVD<4>")
	)
	(segment
		(start 344.113358 -41.877996)
		(end 343.616534 -42.37482)
		(width 0.12954)
		(layer "B.Cu")
		(net "NC_PCH_RSVD<4>")
	)
	(segment
		(start 343.433146 -42.37482)
		(end 342.95588 -41.897554)
		(width 0.12954)
		(layer "B.Cu")
		(net "NC_PCH_RSVD<4>")
	)
	(segment
		(start 336.353912 -41.871646)
		(end 335.953608 -41.871646)
		(width 0.12954)
		(layer "B.Cu")
		(net "NC_PCH_RSVD<4>")
	)
	(segment
		(start 341.286846 -41.8973)
		(end 340.838282 -41.8973)
		(width 0.12954)
		(layer "B.Cu")
		(net "NC_PCH_RSVD<4>")
	)
	(segment
		(start 342.09736 -42.28338)
		(end 341.672926 -42.28338)
		(width 0.12954)
		(layer "B.Cu")
		(net "NC_PCH_RSVD<4>")
	)
	(segment
		(start 338.396072 -41.401746)
		(end 338.93506 -41.401746)
		(width 0.12954)
		(layer "F.Cu")
		(net "NC_PCH_RSVD<3>")
	)
	(via
		(at 338.396072 -41.401746)
		(size 0.4572)
		(drill 0.2032)
		(layers "F.Cu" "B.Cu")
		(net "NC_PCH_RSVD<3>")
	)
	(via
		(at 338.396072 -40.635428)
		(size 0.6604)
		(drill 0.3302)
		(layers "F.Cu" "B.Cu")
		(net "NC_PCH_RSVD<3>")
	)
	(segment
		(start 338.396072 -41.401746)
		(end 338.396072 -40.635428)
		(width 0.12954)
		(layer "B.Cu")
		(net "NC_PCH_RSVD<3>")
	)
	(segment
		(start 346.818204 -30.459426)
		(end 346.818204 -33.977834)
		(width 0.12954)
		(layer "F.Cu")
		(net "NC_PCH_RSVD<17>")
	)
	(segment
		(start 343.903046 -36.892992)
		(end 343.903046 -37.63518)
		(width 0.0889)
		(layer "F.Cu")
		(net "NC_PCH_RSVD<17>")
	)
	(segment
		(start 346.818204 -33.977834)
		(end 346.20327 -34.592768)
		(width 0.12954)
		(layer "F.Cu")
		(net "NC_PCH_RSVD<17>")
	)
	(segment
		(start 347.503496 -28.965906)
		(end 347.503496 -29.774134)
		(width 0.12954)
		(layer "F.Cu")
		(net "NC_PCH_RSVD<17>")
	)
	(segment
		(start 347.503496 -29.774134)
		(end 346.818204 -30.459426)
		(width 0.12954)
		(layer "F.Cu")
		(net "NC_PCH_RSVD<17>")
	)
	(segment
		(start 346.20327 -34.592768)
		(end 343.903046 -36.892992)
		(width 0.0889)
		(layer "F.Cu")
		(net "NC_PCH_RSVD<17>")
	)
	(via
		(at 347.503496 -28.965906)
		(size 0.762)
		(drill 0.381)
		(layers "F.Cu" "B.Cu")
		(net "NC_PCH_RSVD<17>")
	)
	(segment
		(start 382.55956 -62.578488)
		(end 383.6797 -62.578488)
		(width 0.12954)
		(layer "F.Cu")
		(net "NC_MIPI60_P9")
	)
	(segment
		(start 390.089136 -62.249812)
		(end 392.034776 -62.249812)
		(width 0.12954)
		(layer "F.Cu")
		(net "NC_MIPI60_P9")
	)
	(segment
		(start 383.6797 -62.578488)
		(end 383.93624 -62.321948)
		(width 0.12954)
		(layer "F.Cu")
		(net "NC_MIPI60_P9")
	)
	(segment
		(start 382.10744 -62.126368)
		(end 382.55956 -62.578488)
		(width 0.12954)
		(layer "F.Cu")
		(net "NC_MIPI60_P9")
	)
	(segment
		(start 389.5725 -62.766448)
		(end 390.089136 -62.249812)
		(width 0.12954)
		(layer "F.Cu")
		(net "NC_MIPI60_P9")
	)
	(segment
		(start 383.93624 -62.321948)
		(end 384.66268 -62.321948)
		(width 0.12954)
		(layer "F.Cu")
		(net "NC_MIPI60_P9")
	)
	(segment
		(start 385.10718 -62.766448)
		(end 389.5725 -62.766448)
		(width 0.12954)
		(layer "F.Cu")
		(net "NC_MIPI60_P9")
	)
	(segment
		(start 384.66268 -62.321948)
		(end 385.10718 -62.766448)
		(width 0.12954)
		(layer "F.Cu")
		(net "NC_MIPI60_P9")
	)
	(via
		(at 382.10744 -62.126368)
		(size 0.762)
		(drill 0.381)
		(layers "F.Cu" "B.Cu")
		(net "NC_MIPI60_P9")
	)
	(segment
		(start 167.25646 -38.959536)
		(end 167.846756 -39.549832)
		(width 0.12954)
		(layer "F.Cu")
		(net "NC_M2_0_SUSCLK")
	)
	(segment
		(start 167.25646 -35.34156)
		(end 167.25646 -38.959536)
		(width 0.12954)
		(layer "F.Cu")
		(net "NC_M2_0_SUSCLK")
	)
	(segment
		(start 167.846756 -39.549832)
		(end 169.557954 -39.549832)
		(width 0.12954)
		(layer "F.Cu")
		(net "NC_M2_0_SUSCLK")
	)
	(via
		(at 167.25646 -35.34156)
		(size 0.762)
		(drill 0.381)
		(layers "F.Cu" "B.Cu")
		(net "NC_M2_0_SUSCLK")
	)
	(segment
		(start 169.557954 -48.550068)
		(end 168.464738 -48.550068)
		(width 0.12954)
		(layer "F.Cu")
		(net "NC_M2_0_NC9")
	)
	(segment
		(start 165.46068 -48.35652)
		(end 162.46348 -48.35652)
		(width 0.12954)
		(layer "F.Cu")
		(net "NC_M2_0_NC9")
	)
	(segment
		(start 161.49828 -47.39132)
		(end 161.49828 -47.13478)
		(width 0.12954)
		(layer "F.Cu")
		(net "NC_M2_0_NC9")
	)
	(segment
		(start 165.73246 -48.6283)
		(end 165.46068 -48.35652)
		(width 0.12954)
		(layer "F.Cu")
		(net "NC_M2_0_NC9")
	)
	(segment
		(start 162.46348 -48.35652)
		(end 161.49828 -47.39132)
		(width 0.12954)
		(layer "F.Cu")
		(net "NC_M2_0_NC9")
	)
	(segment
		(start 168.464738 -48.550068)
		(end 168.386506 -48.6283)
		(width 0.12954)
		(layer "F.Cu")
		(net "NC_M2_0_NC9")
	)
	(segment
		(start 168.386506 -48.6283)
		(end 165.73246 -48.6283)
		(width 0.12954)
		(layer "F.Cu")
		(net "NC_M2_0_NC9")
	)
	(via
		(at 161.49828 -47.13478)
		(size 0.762)
		(drill 0.381)
		(layers "F.Cu" "B.Cu")
		(net "NC_M2_0_NC9")
	)
	(segment
		(start 161.49828 -48.40478)
		(end 161.85642 -48.76292)
		(width 0.12954)
		(layer "F.Cu")
		(net "NC_M2_0_NC8")
	)
	(segment
		(start 165.3286 -48.76292)
		(end 165.61562 -49.04994)
		(width 0.12954)
		(layer "F.Cu")
		(net "NC_M2_0_NC8")
	)
	(segment
		(start 165.61562 -49.04994)
		(end 169.557954 -49.04994)
		(width 0.12954)
		(layer "F.Cu")
		(net "NC_M2_0_NC8")
	)
	(segment
		(start 161.85642 -48.76292)
		(end 165.3286 -48.76292)
		(width 0.12954)
		(layer "F.Cu")
		(net "NC_M2_0_NC8")
	)
	(via
		(at 161.49828 -48.40478)
		(size 0.762)
		(drill 0.381)
		(layers "F.Cu" "B.Cu")
		(net "NC_M2_0_NC8")
	)
	(segment
		(start 180.205634 -41.985438)
		(end 178.020218 -39.800022)
		(width 0.12954)
		(layer "F.Cu")
		(net "NC_M2_0_NC19")
	)
	(segment
		(start 178.020218 -39.800022)
		(end 177.108104 -39.800022)
		(width 0.12954)
		(layer "F.Cu")
		(net "NC_M2_0_NC19")
	)
	(segment
		(start 182.385462 -41.985438)
		(end 180.205634 -41.985438)
		(width 0.12954)
		(layer "F.Cu")
		(net "NC_M2_0_NC19")
	)
	(via
		(at 182.385462 -41.985438)
		(size 0.762)
		(drill 0.381)
		(layers "F.Cu" "B.Cu")
		(net "NC_M2_0_NC19")
	)
	(segment
		(start 167.01262 -39.652448)
		(end 167.01262 -40.327072)
		(width 0.12954)
		(layer "F.Cu")
		(net "NC_M2_0_NC18")
	)
	(segment
		(start 168.735502 -42.049954)
		(end 169.557954 -42.049954)
		(width 0.12954)
		(layer "F.Cu")
		(net "NC_M2_0_NC18")
	)
	(segment
		(start 167.01262 -40.327072)
		(end 168.735502 -42.049954)
		(width 0.12954)
		(layer "F.Cu")
		(net "NC_M2_0_NC18")
	)
	(segment
		(start 166.21506 -38.854888)
		(end 167.01262 -39.652448)
		(width 0.12954)
		(layer "F.Cu")
		(net "NC_M2_0_NC18")
	)
	(via
		(at 166.21506 -38.854888)
		(size 0.762)
		(drill 0.381)
		(layers "F.Cu" "B.Cu")
		(net "NC_M2_0_NC18")
	)
	(segment
		(start 168.482518 -42.549826)
		(end 169.557954 -42.549826)
		(width 0.12954)
		(layer "F.Cu")
		(net "NC_M2_0_NC17")
	)
	(segment
		(start 166.20998 -40.277288)
		(end 168.482518 -42.549826)
		(width 0.12954)
		(layer "F.Cu")
		(net "NC_M2_0_NC17")
	)
	(via
		(at 166.20998 -40.277288)
		(size 0.762)
		(drill 0.381)
		(layers "F.Cu" "B.Cu")
		(net "NC_M2_0_NC17")
	)
	(segment
		(start 165.97376 -47.89932)
		(end 167.92702 -47.89932)
		(width 0.12954)
		(layer "F.Cu")
		(net "NC_M2_0_NC11")
	)
	(segment
		(start 162.70986 -46.210982)
		(end 162.70986 -47.41418)
		(width 0.12954)
		(layer "F.Cu")
		(net "NC_M2_0_NC11")
	)
	(segment
		(start 162.90798 -47.6123)
		(end 165.68674 -47.6123)
		(width 0.12954)
		(layer "F.Cu")
		(net "NC_M2_0_NC11")
	)
	(segment
		(start 168.276524 -47.549816)
		(end 169.557954 -47.549816)
		(width 0.12954)
		(layer "F.Cu")
		(net "NC_M2_0_NC11")
	)
	(segment
		(start 165.68674 -47.6123)
		(end 165.97376 -47.89932)
		(width 0.12954)
		(layer "F.Cu")
		(net "NC_M2_0_NC11")
	)
	(segment
		(start 162.70986 -47.41418)
		(end 162.90798 -47.6123)
		(width 0.12954)
		(layer "F.Cu")
		(net "NC_M2_0_NC11")
	)
	(segment
		(start 167.92702 -47.89932)
		(end 168.276524 -47.549816)
		(width 0.12954)
		(layer "F.Cu")
		(net "NC_M2_0_NC11")
	)
	(segment
		(start 163.008564 -45.912278)
		(end 162.70986 -46.210982)
		(width 0.12954)
		(layer "F.Cu")
		(net "NC_M2_0_NC11")
	)
	(via
		(at 163.008564 -45.912278)
		(size 0.762)
		(drill 0.381)
		(layers "F.Cu" "B.Cu")
		(net "NC_M2_0_NC11")
	)
	(segment
		(start 168.048686 -48.27016)
		(end 168.268904 -48.049942)
		(width 0.12954)
		(layer "F.Cu")
		(net "NC_M2_0_NC10")
	)
	(segment
		(start 161.49828 -45.86478)
		(end 162.18408 -46.55058)
		(width 0.12954)
		(layer "F.Cu")
		(net "NC_M2_0_NC10")
	)
	(segment
		(start 165.61816 -47.99076)
		(end 165.89756 -48.27016)
		(width 0.12954)
		(layer "F.Cu")
		(net "NC_M2_0_NC10")
	)
	(segment
		(start 162.18408 -47.50562)
		(end 162.66922 -47.99076)
		(width 0.12954)
		(layer "F.Cu")
		(net "NC_M2_0_NC10")
	)
	(segment
		(start 168.268904 -48.049942)
		(end 169.557954 -48.049942)
		(width 0.12954)
		(layer "F.Cu")
		(net "NC_M2_0_NC10")
	)
	(segment
		(start 162.18408 -46.55058)
		(end 162.18408 -47.50562)
		(width 0.12954)
		(layer "F.Cu")
		(net "NC_M2_0_NC10")
	)
	(segment
		(start 162.66922 -47.99076)
		(end 165.61816 -47.99076)
		(width 0.12954)
		(layer "F.Cu")
		(net "NC_M2_0_NC10")
	)
	(segment
		(start 165.89756 -48.27016)
		(end 168.048686 -48.27016)
		(width 0.12954)
		(layer "F.Cu")
		(net "NC_M2_0_NC10")
	)
	(via
		(at 161.49828 -45.86478)
		(size 0.762)
		(drill 0.381)
		(layers "F.Cu" "B.Cu")
		(net "NC_M2_0_NC10")
	)
	(segment
		(start 120.098312 -232.528364)
		(end 120.098312 -233.064304)
		(width 0.12954)
		(layer "F.Cu")
		(net "NC_FM_IBL_ADR_TRIGGER_CPU1_R")
	)
	(via
		(at 120.098312 -232.528364)
		(size 0.4572)
		(drill 0.2032)
		(layers "F.Cu" "B.Cu")
		(net "NC_FM_IBL_ADR_TRIGGER_CPU1_R")
	)
	(segment
		(start 119.158512 -233.064304)
		(end 119.158512 -232.528618)
		(width 0.12954)
		(layer "F.Cu")
		(net "NC_FM_IBL_ADR_COMPLETE_CPU1_R")
	)
	(segment
		(start 119.158512 -232.528618)
		(end 119.158766 -232.528364)
		(width 0.12954)
		(layer "F.Cu")
		(net "NC_FM_IBL_ADR_COMPLETE_CPU1_R")
	)
	(via
		(at 119.158766 -232.528364)
		(size 0.4572)
		(drill 0.2032)
		(layers "F.Cu" "B.Cu")
		(net "NC_FM_IBL_ADR_COMPLETE_CPU1_R")
	)
	(segment
		(start 118.688612 -232.250234)
		(end 118.688612 -231.714548)
		(width 0.12954)
		(layer "F.Cu")
		(net "NC_FM_IBL_ADR_ACK_CPU1")
	)
	(segment
		(start 118.688866 -232.250488)
		(end 118.688612 -232.250234)
		(width 0.12954)
		(layer "F.Cu")
		(net "NC_FM_IBL_ADR_ACK_CPU1")
	)
	(via
		(at 118.688612 -231.714548)
		(size 0.4572)
		(drill 0.2032)
		(layers "F.Cu" "B.Cu")
		(net "NC_FM_IBL_ADR_ACK_CPU1")
	)
	(segment
		(start 329.898756 -15.749016)
		(end 329.63739 -16.010382)
		(width 0.12954)
		(layer "F.Cu")
		(net "NC_ESPI_PLD_R_EN_BUF")
	)
	(segment
		(start 329.898756 -14.635734)
		(end 329.898756 -15.749016)
		(width 0.12954)
		(layer "F.Cu")
		(net "NC_ESPI_PLD_R_EN_BUF")
	)
	(via
		(at 329.63739 -16.010382)
		(size 0.762)
		(drill 0.381)
		(layers "F.Cu" "B.Cu")
		(net "NC_ESPI_PLD_R_EN_BUF")
	)
	(segment
		(start 106.581194 -267.220192)
		(end 106.581194 -267.755878)
		(width 0.12954)
		(layer "F.Cu")
		(net "NC_ESPI_IBL_CPU1_RESET_N")
	)
	(segment
		(start 106.581448 -267.219938)
		(end 106.581194 -267.220192)
		(width 0.12954)
		(layer "F.Cu")
		(net "NC_ESPI_IBL_CPU1_RESET_N")
	)
	(via
		(at 106.581194 -267.755878)
		(size 0.4572)
		(drill 0.2032)
		(layers "F.Cu" "B.Cu")
		(net "NC_ESPI_IBL_CPU1_RESET_N")
	)
	(segment
		(start 107.051348 -266.941808)
		(end 107.051348 -266.406122)
		(width 0.12954)
		(layer "F.Cu")
		(net "NC_ESPI_IBL_CPU1_OE_N")
	)
	(segment
		(start 107.051348 -266.406122)
		(end 107.051094 -266.405868)
		(width 0.12954)
		(layer "F.Cu")
		(net "NC_ESPI_IBL_CPU1_OE_N")
	)
	(via
		(at 107.051348 -266.941808)
		(size 0.4572)
		(drill 0.2032)
		(layers "F.Cu" "B.Cu")
		(net "NC_ESPI_IBL_CPU1_OE_N")
	)
	(segment
		(start 108.930948 -266.406122)
		(end 108.930694 -266.405868)
		(width 0.12954)
		(layer "F.Cu")
		(net "NC_ESPI_IBL_CPU1_IO3")
	)
	(segment
		(start 108.930948 -266.941808)
		(end 108.930948 -266.406122)
		(width 0.12954)
		(layer "F.Cu")
		(net "NC_ESPI_IBL_CPU1_IO3")
	)
	(via
		(at 108.930948 -266.941808)
		(size 0.4572)
		(drill 0.2032)
		(layers "F.Cu" "B.Cu")
		(net "NC_ESPI_IBL_CPU1_IO3")
	)
	(segment
		(start 101.882448 -267.755624)
		(end 101.882448 -267.219938)
		(width 0.12954)
		(layer "F.Cu")
		(net "NC_ESPI_IBL_CPU1_IO2")
	)
	(segment
		(start 101.882194 -267.755878)
		(end 101.882448 -267.755624)
		(width 0.12954)
		(layer "F.Cu")
		(net "NC_ESPI_IBL_CPU1_IO2")
	)
	(via
		(at 101.882194 -267.755878)
		(size 0.4572)
		(drill 0.2032)
		(layers "F.Cu" "B.Cu")
		(net "NC_ESPI_IBL_CPU1_IO2")
	)
	(segment
		(start 107.520994 -267.220192)
		(end 107.520994 -267.755878)
		(width 0.12954)
		(layer "F.Cu")
		(net "NC_ESPI_IBL_CPU1_IO1")
	)
	(segment
		(start 107.521248 -267.219938)
		(end 107.520994 -267.220192)
		(width 0.12954)
		(layer "F.Cu")
		(net "NC_ESPI_IBL_CPU1_IO1")
	)
	(via
		(at 107.520994 -267.755878)
		(size 0.4572)
		(drill 0.2032)
		(layers "F.Cu" "B.Cu")
		(net "NC_ESPI_IBL_CPU1_IO1")
	)
	(segment
		(start 107.990894 -266.405868)
		(end 107.991148 -266.406122)
		(width 0.12954)
		(layer "F.Cu")
		(net "NC_ESPI_IBL_CPU1_IO0")
	)
	(segment
		(start 107.991148 -266.406122)
		(end 107.991148 -266.941808)
		(width 0.12954)
		(layer "F.Cu")
		(net "NC_ESPI_IBL_CPU1_IO0")
	)
	(via
		(at 107.991148 -266.941808)
		(size 0.4572)
		(drill 0.2032)
		(layers "F.Cu" "B.Cu")
		(net "NC_ESPI_IBL_CPU1_IO0")
	)
	(segment
		(start 107.051094 -268.033754)
		(end 107.051348 -268.034008)
		(width 0.12954)
		(layer "F.Cu")
		(net "NC_ESPI_IBL_CPU1_CS1_N")
	)
	(segment
		(start 107.051348 -268.034008)
		(end 107.051348 -268.569694)
		(width 0.12954)
		(layer "F.Cu")
		(net "NC_ESPI_IBL_CPU1_CS1_N")
	)
	(via
		(at 107.051348 -268.569694)
		(size 0.4572)
		(drill 0.2032)
		(layers "F.Cu" "B.Cu")
		(net "NC_ESPI_IBL_CPU1_CS1_N")
	)
	(segment
		(start 106.111548 -268.569694)
		(end 106.111294 -268.56944)
		(width 0.12954)
		(layer "F.Cu")
		(net "NC_ESPI_IBL_CPU1_CS0_N")
	)
	(segment
		(start 106.111294 -268.56944)
		(end 106.111294 -268.033754)
		(width 0.12954)
		(layer "F.Cu")
		(net "NC_ESPI_IBL_CPU1_CS0_N")
	)
	(via
		(at 106.111548 -268.569694)
		(size 0.4572)
		(drill 0.2032)
		(layers "F.Cu" "B.Cu")
		(net "NC_ESPI_IBL_CPU1_CS0_N")
	)
	(segment
		(start 106.581448 -265.592306)
		(end 106.581448 -266.127992)
		(width 0.12954)
		(layer "F.Cu")
		(net "NC_ESPI_IBL_CPU1_CLK")
	)
	(segment
		(start 106.581448 -266.127992)
		(end 106.581194 -266.128246)
		(width 0.12954)
		(layer "F.Cu")
		(net "NC_ESPI_IBL_CPU1_CLK")
	)
	(via
		(at 106.581194 -266.128246)
		(size 0.4572)
		(drill 0.2032)
		(layers "F.Cu" "B.Cu")
		(net "NC_ESPI_IBL_CPU1_CLK")
	)
	(segment
		(start 105.17124 -266.941808)
		(end 105.17124 -266.405868)
		(width 0.12954)
		(layer "F.Cu")
		(net "NC_ESPI_IBL_CPU1_ALERT1_N")
	)
	(segment
		(start 105.17124 -266.405868)
		(end 105.171494 -266.405868)
		(width 0.12954)
		(layer "F.Cu")
		(net "NC_ESPI_IBL_CPU1_ALERT1_N")
	)
	(via
		(at 105.17124 -266.941808)
		(size 0.4572)
		(drill 0.2032)
		(layers "F.Cu" "B.Cu")
		(net "NC_ESPI_IBL_CPU1_ALERT1_N")
	)
	(segment
		(start 105.641648 -266.127992)
		(end 105.641648 -265.592306)
		(width 0.12954)
		(layer "F.Cu")
		(net "NC_ESPI_IBL_CPU1_ALERT0_N")
	)
	(segment
		(start 105.641394 -266.128246)
		(end 105.641648 -266.127992)
		(width 0.12954)
		(layer "F.Cu")
		(net "NC_ESPI_IBL_CPU1_ALERT0_N")
	)
	(via
		(at 105.641394 -266.128246)
		(size 0.4572)
		(drill 0.2032)
		(layers "F.Cu" "B.Cu")
		(net "NC_ESPI_IBL_CPU1_ALERT0_N")
	)
	(segment
		(start 399.612866 -50.749962)
		(end 397.765016 -50.749962)
		(width 0.12954)
		(layer "F.Cu")
		(net "NC_DBP_P56")
	)
	(segment
		(start 403.19452 -47.168308)
		(end 399.612866 -50.749962)
		(width 0.12954)
		(layer "F.Cu")
		(net "NC_DBP_P56")
	)
	(segment
		(start 403.4917 -47.168308)
		(end 403.19452 -47.168308)
		(width 0.12954)
		(layer "F.Cu")
		(net "NC_DBP_P56")
	)
	(via
		(at 403.4917 -47.168308)
		(size 0.762)
		(drill 0.381)
		(layers "F.Cu" "B.Cu")
		(net "NC_DBP_P56")
	)
	(segment
		(start 402.07184 -49.266348)
		(end 400.088354 -51.249834)
		(width 0.12954)
		(layer "F.Cu")
		(net "NC_DBP_P54")
	)
	(segment
		(start 403.53488 -49.266348)
		(end 402.07184 -49.266348)
		(width 0.12954)
		(layer "F.Cu")
		(net "NC_DBP_P54")
	)
	(segment
		(start 400.088354 -51.249834)
		(end 397.765016 -51.249834)
		(width 0.12954)
		(layer "F.Cu")
		(net "NC_DBP_P54")
	)
	(via
		(at 403.53488 -49.266348)
		(size 0.762)
		(drill 0.381)
		(layers "F.Cu" "B.Cu")
		(net "NC_DBP_P54")
	)
	(segment
		(start 403.3774 -52.182268)
		(end 402.309838 -53.24983)
		(width 0.12954)
		(layer "F.Cu")
		(net "NC_DBP_P46")
	)
	(segment
		(start 402.309838 -53.24983)
		(end 397.765016 -53.24983)
		(width 0.12954)
		(layer "F.Cu")
		(net "NC_DBP_P46")
	)
	(via
		(at 403.3774 -52.182268)
		(size 0.762)
		(drill 0.381)
		(layers "F.Cu" "B.Cu")
		(net "NC_DBP_P46")
	)
	(segment
		(start 403.803612 -53.749956)
		(end 397.765016 -53.749956)
		(width 0.12954)
		(layer "F.Cu")
		(net "NC_DBP_P44")
	)
	(segment
		(start 405.31542 -52.238148)
		(end 403.803612 -53.749956)
		(width 0.12954)
		(layer "F.Cu")
		(net "NC_DBP_P44")
	)
	(via
		(at 405.31542 -52.238148)
		(size 0.762)
		(drill 0.381)
		(layers "F.Cu" "B.Cu")
		(net "NC_DBP_P44")
	)
	(segment
		(start 401.78482 -55.240428)
		(end 400.775424 -56.249824)
		(width 0.12954)
		(layer "F.Cu")
		(net "NC_DBP_P34")
	)
	(segment
		(start 400.775424 -56.249824)
		(end 397.765016 -56.249824)
		(width 0.12954)
		(layer "F.Cu")
		(net "NC_DBP_P34")
	)
	(via
		(at 401.78482 -55.240428)
		(size 0.762)
		(drill 0.381)
		(layers "F.Cu" "B.Cu")
		(net "NC_DBP_P34")
	)
	(segment
		(start 401.545298 -56.74995)
		(end 397.765016 -56.74995)
		(width 0.12954)
		(layer "F.Cu")
		(net "NC_DBP_P32")
	)
	(segment
		(start 401.78482 -56.510428)
		(end 401.545298 -56.74995)
		(width 0.12954)
		(layer "F.Cu")
		(net "NC_DBP_P32")
	)
	(via
		(at 401.78482 -56.510428)
		(size 0.762)
		(drill 0.381)
		(layers "F.Cu" "B.Cu")
		(net "NC_DBP_P32")
	)
	(segment
		(start 401.254214 -57.249822)
		(end 397.765016 -57.249822)
		(width 0.12954)
		(layer "F.Cu")
		(net "NC_DBP_P30")
	)
	(segment
		(start 401.78482 -57.780428)
		(end 401.254214 -57.249822)
		(width 0.12954)
		(layer "F.Cu")
		(net "NC_DBP_P30")
	)
	(via
		(at 401.78482 -57.780428)
		(size 0.762)
		(drill 0.381)
		(layers "F.Cu" "B.Cu")
		(net "NC_DBP_P30")
	)
	(segment
		(start 401.78482 -59.050428)
		(end 400.48434 -57.749948)
		(width 0.12954)
		(layer "F.Cu")
		(net "NC_DBP_P28")
	)
	(segment
		(start 400.48434 -57.749948)
		(end 397.765016 -57.749948)
		(width 0.12954)
		(layer "F.Cu")
		(net "NC_DBP_P28")
	)
	(via
		(at 401.78482 -59.050428)
		(size 0.762)
		(drill 0.381)
		(layers "F.Cu" "B.Cu")
		(net "NC_DBP_P28")
	)
	(segment
		(start 403.05482 -59.050428)
		(end 402.45538 -59.649868)
		(width 0.12954)
		(layer "F.Cu")
		(net "NC_DBP_P26")
	)
	(segment
		(start 402.45538 -59.649868)
		(end 401.2946 -59.649868)
		(width 0.12954)
		(layer "F.Cu")
		(net "NC_DBP_P26")
	)
	(segment
		(start 401.2946 -59.649868)
		(end 399.894552 -58.24982)
		(width 0.12954)
		(layer "F.Cu")
		(net "NC_DBP_P26")
	)
	(segment
		(start 399.894552 -58.24982)
		(end 397.765016 -58.24982)
		(width 0.12954)
		(layer "F.Cu")
		(net "NC_DBP_P26")
	)
	(via
		(at 403.05482 -59.050428)
		(size 0.762)
		(drill 0.381)
		(layers "F.Cu" "B.Cu")
		(net "NC_DBP_P26")
	)
	(segment
		(start 404.32482 -59.050428)
		(end 403.33168 -60.043568)
		(width 0.12954)
		(layer "F.Cu")
		(net "NC_DBP_P24")
	)
	(segment
		(start 401.11426 -60.043568)
		(end 399.820638 -58.749946)
		(width 0.12954)
		(layer "F.Cu")
		(net "NC_DBP_P24")
	)
	(segment
		(start 403.33168 -60.043568)
		(end 401.11426 -60.043568)
		(width 0.12954)
		(layer "F.Cu")
		(net "NC_DBP_P24")
	)
	(segment
		(start 399.820638 -58.749946)
		(end 397.765016 -58.749946)
		(width 0.12954)
		(layer "F.Cu")
		(net "NC_DBP_P24")
	)
	(via
		(at 404.32482 -59.050428)
		(size 0.762)
		(drill 0.381)
		(layers "F.Cu" "B.Cu")
		(net "NC_DBP_P24")
	)
	(segment
		(start 404.0759 -60.462668)
		(end 400.92122 -60.462668)
		(width 0.12954)
		(layer "F.Cu")
		(net "NC_DBP_P22")
	)
	(segment
		(start 400.92122 -60.462668)
		(end 399.70837 -59.249818)
		(width 0.12954)
		(layer "F.Cu")
		(net "NC_DBP_P22")
	)
	(segment
		(start 405.59482 -59.050428)
		(end 405.26716 -59.378088)
		(width 0.12954)
		(layer "F.Cu")
		(net "NC_DBP_P22")
	)
	(segment
		(start 405.16048 -59.378088)
		(end 404.0759 -60.462668)
		(width 0.12954)
		(layer "F.Cu")
		(net "NC_DBP_P22")
	)
	(segment
		(start 399.70837 -59.249818)
		(end 397.765016 -59.249818)
		(width 0.12954)
		(layer "F.Cu")
		(net "NC_DBP_P22")
	)
	(segment
		(start 405.26716 -59.378088)
		(end 405.16048 -59.378088)
		(width 0.12954)
		(layer "F.Cu")
		(net "NC_DBP_P22")
	)
	(via
		(at 405.59482 -59.050428)
		(size 0.762)
		(drill 0.381)
		(layers "F.Cu" "B.Cu")
		(net "NC_DBP_P22")
	)
	(segment
		(start 400.7993 -60.874148)
		(end 399.675096 -59.749944)
		(width 0.12954)
		(layer "F.Cu")
		(net "NC_DBP_P20")
	)
	(segment
		(start 405.0411 -60.874148)
		(end 400.7993 -60.874148)
		(width 0.12954)
		(layer "F.Cu")
		(net "NC_DBP_P20")
	)
	(segment
		(start 405.59482 -60.320428)
		(end 405.0411 -60.874148)
		(width 0.12954)
		(layer "F.Cu")
		(net "NC_DBP_P20")
	)
	(segment
		(start 399.675096 -59.749944)
		(end 397.765016 -59.749944)
		(width 0.12954)
		(layer "F.Cu")
		(net "NC_DBP_P20")
	)
	(via
		(at 405.59482 -60.320428)
		(size 0.762)
		(drill 0.381)
		(layers "F.Cu" "B.Cu")
		(net "NC_DBP_P20")
	)
	(segment
		(start 399.273268 -60.249816)
		(end 397.765016 -60.249816)
		(width 0.12954)
		(layer "F.Cu")
		(net "NC_DBP_P18")
	)
	(segment
		(start 400.55038 -61.526928)
		(end 399.273268 -60.249816)
		(width 0.12954)
		(layer "F.Cu")
		(net "NC_DBP_P18")
	)
	(segment
		(start 401.38096 -61.526928)
		(end 400.55038 -61.526928)
		(width 0.12954)
		(layer "F.Cu")
		(net "NC_DBP_P18")
	)
	(via
		(at 401.38096 -61.526928)
		(size 0.762)
		(drill 0.381)
		(layers "F.Cu" "B.Cu")
		(net "NC_DBP_P18")
	)
	(segment
		(start 122.088148 -261.522972)
		(end 122.088148 -262.058658)
		(width 0.12954)
		(layer "F.Cu")
		(net "NC_CPU1_VIEWPIN_GNR3")
	)
	(segment
		(start 122.087894 -261.522718)
		(end 122.088148 -261.522972)
		(width 0.12954)
		(layer "F.Cu")
		(net "NC_CPU1_VIEWPIN_GNR3")
	)
	(via
		(at 136.705086 -260.919214)
		(size 0.6604)
		(drill 0.3302)
		(layers "F.Cu" "B.Cu")
		(net "NC_CPU1_VIEWPIN_GNR3")
	)
	(via
		(at 122.088148 -262.058658)
		(size 0.4572)
		(drill 0.2032)
		(layers "F.Cu" "B.Cu")
		(net "NC_CPU1_VIEWPIN_GNR3")
	)
	(segment
		(start 131.707382 -261.643876)
		(end 131.720844 -261.65175)
		(width 0.0889)
		(layer "B.Cu")
		(net "NC_CPU1_VIEWPIN_GNR3")
	)
	(segment
		(start 122.088148 -262.058658)
		(end 122.792744 -261.65175)
		(width 0.0889)
		(layer "B.Cu")
		(net "NC_CPU1_VIEWPIN_GNR3")
	)
	(segment
		(start 133.586982 -261.643876)
		(end 133.600444 -261.65175)
		(width 0.0889)
		(layer "B.Cu")
		(net "NC_CPU1_VIEWPIN_GNR3")
	)
	(segment
		(start 127.948182 -261.643876)
		(end 127.961644 -261.65175)
		(width 0.0889)
		(layer "B.Cu")
		(net "NC_CPU1_VIEWPIN_GNR3")
	)
	(segment
		(start 124.188982 -261.643876)
		(end 124.202444 -261.65175)
		(width 0.0889)
		(layer "B.Cu")
		(net "NC_CPU1_VIEWPIN_GNR3")
	)
	(segment
		(start 134.526782 -261.643876)
		(end 134.540244 -261.65175)
		(width 0.0889)
		(layer "B.Cu")
		(net "NC_CPU1_VIEWPIN_GNR3")
	)
	(segment
		(start 136.047226 -261.577074)
		(end 136.284208 -261.340092)
		(width 0.0889)
		(layer "B.Cu")
		(net "NC_CPU1_VIEWPIN_GNR3")
	)
	(segment
		(start 136.284208 -261.340092)
		(end 136.705086 -260.919214)
		(width 0.12954)
		(layer "B.Cu")
		(net "NC_CPU1_VIEWPIN_GNR3")
	)
	(segment
		(start 125.128782 -261.643876)
		(end 125.142244 -261.65175)
		(width 0.0889)
		(layer "B.Cu")
		(net "NC_CPU1_VIEWPIN_GNR3")
	)
	(segment
		(start 129.827782 -261.643876)
		(end 129.841244 -261.65175)
		(width 0.0889)
		(layer "B.Cu")
		(net "NC_CPU1_VIEWPIN_GNR3")
	)
	(segment
		(start 130.767582 -261.643876)
		(end 130.781044 -261.65175)
		(width 0.0889)
		(layer "B.Cu")
		(net "NC_CPU1_VIEWPIN_GNR3")
	)
	(segment
		(start 128.887982 -261.643876)
		(end 128.901444 -261.65175)
		(width 0.0889)
		(layer "B.Cu")
		(net "NC_CPU1_VIEWPIN_GNR3")
	)
	(segment
		(start 127.008382 -261.643876)
		(end 127.021844 -261.65175)
		(width 0.0889)
		(layer "B.Cu")
		(net "NC_CPU1_VIEWPIN_GNR3")
	)
	(arc
		(start 132.660644 -261.65175)
		(mid 132.895594 -261.71471)
		(end 133.130544 -261.65175)
		(width 0.0889)
		(layer "B.Cu")
		(net "NC_CPU1_VIEWPIN_GNR3")
	)
	(arc
		(start 130.311144 -261.65175)
		(mid 130.538331 -261.588732)
		(end 130.767582 -261.643876)
		(width 0.0889)
		(layer "B.Cu")
		(net "NC_CPU1_VIEWPIN_GNR3")
	)
	(arc
		(start 127.021844 -261.65175)
		(mid 127.256794 -261.71471)
		(end 127.491744 -261.65175)
		(width 0.0889)
		(layer "B.Cu")
		(net "NC_CPU1_VIEWPIN_GNR3")
	)
	(arc
		(start 135.010144 -261.65175)
		(mid 135.245094 -261.58879)
		(end 135.480044 -261.65175)
		(width 0.0889)
		(layer "B.Cu")
		(net "NC_CPU1_VIEWPIN_GNR3")
	)
	(arc
		(start 123.732544 -261.65175)
		(mid 123.959731 -261.588732)
		(end 124.188982 -261.643876)
		(width 0.0889)
		(layer "B.Cu")
		(net "NC_CPU1_VIEWPIN_GNR3")
	)
	(arc
		(start 129.371344 -261.65175)
		(mid 129.598531 -261.588732)
		(end 129.827782 -261.643876)
		(width 0.0889)
		(layer "B.Cu")
		(net "NC_CPU1_VIEWPIN_GNR3")
	)
	(arc
		(start 135.480044 -261.65175)
		(mid 135.714994 -261.71471)
		(end 135.949944 -261.65175)
		(width 0.0889)
		(layer "B.Cu")
		(net "NC_CPU1_VIEWPIN_GNR3")
	)
	(arc
		(start 125.612144 -261.65175)
		(mid 125.847094 -261.58879)
		(end 126.082044 -261.65175)
		(width 0.0889)
		(layer "B.Cu")
		(net "NC_CPU1_VIEWPIN_GNR3")
	)
	(arc
		(start 128.901444 -261.65175)
		(mid 129.136394 -261.71471)
		(end 129.371344 -261.65175)
		(width 0.0889)
		(layer "B.Cu")
		(net "NC_CPU1_VIEWPIN_GNR3")
	)
	(arc
		(start 124.202444 -261.65175)
		(mid 124.437394 -261.71471)
		(end 124.672344 -261.65175)
		(width 0.0889)
		(layer "B.Cu")
		(net "NC_CPU1_VIEWPIN_GNR3")
	)
	(arc
		(start 135.949944 -261.65175)
		(mid 136.001039 -261.617607)
		(end 136.047226 -261.577074)
		(width 0.0889)
		(layer "B.Cu")
		(net "NC_CPU1_VIEWPIN_GNR3")
	)
	(arc
		(start 124.672344 -261.65175)
		(mid 124.899531 -261.588732)
		(end 125.128782 -261.643876)
		(width 0.0889)
		(layer "B.Cu")
		(net "NC_CPU1_VIEWPIN_GNR3")
	)
	(arc
		(start 134.540244 -261.65175)
		(mid 134.775194 -261.71471)
		(end 135.010144 -261.65175)
		(width 0.0889)
		(layer "B.Cu")
		(net "NC_CPU1_VIEWPIN_GNR3")
	)
	(arc
		(start 131.720844 -261.65175)
		(mid 131.955794 -261.71471)
		(end 132.190744 -261.65175)
		(width 0.0889)
		(layer "B.Cu")
		(net "NC_CPU1_VIEWPIN_GNR3")
	)
	(arc
		(start 132.190744 -261.65175)
		(mid 132.425694 -261.58879)
		(end 132.660644 -261.65175)
		(width 0.0889)
		(layer "B.Cu")
		(net "NC_CPU1_VIEWPIN_GNR3")
	)
	(arc
		(start 133.600444 -261.65175)
		(mid 133.835394 -261.71471)
		(end 134.070344 -261.65175)
		(width 0.0889)
		(layer "B.Cu")
		(net "NC_CPU1_VIEWPIN_GNR3")
	)
	(arc
		(start 127.491744 -261.65175)
		(mid 127.718931 -261.588732)
		(end 127.948182 -261.643876)
		(width 0.0889)
		(layer "B.Cu")
		(net "NC_CPU1_VIEWPIN_GNR3")
	)
	(arc
		(start 130.781044 -261.65175)
		(mid 131.015994 -261.71471)
		(end 131.250944 -261.65175)
		(width 0.0889)
		(layer "B.Cu")
		(net "NC_CPU1_VIEWPIN_GNR3")
	)
	(arc
		(start 126.551944 -261.65175)
		(mid 126.779131 -261.588732)
		(end 127.008382 -261.643876)
		(width 0.0889)
		(layer "B.Cu")
		(net "NC_CPU1_VIEWPIN_GNR3")
	)
	(arc
		(start 127.961644 -261.65175)
		(mid 128.196594 -261.71471)
		(end 128.431544 -261.65175)
		(width 0.0889)
		(layer "B.Cu")
		(net "NC_CPU1_VIEWPIN_GNR3")
	)
	(arc
		(start 133.130544 -261.65175)
		(mid 133.357731 -261.588732)
		(end 133.586982 -261.643876)
		(width 0.0889)
		(layer "B.Cu")
		(net "NC_CPU1_VIEWPIN_GNR3")
	)
	(arc
		(start 134.070344 -261.65175)
		(mid 134.297531 -261.588732)
		(end 134.526782 -261.643876)
		(width 0.0889)
		(layer "B.Cu")
		(net "NC_CPU1_VIEWPIN_GNR3")
	)
	(arc
		(start 129.841244 -261.65175)
		(mid 130.076194 -261.71471)
		(end 130.311144 -261.65175)
		(width 0.0889)
		(layer "B.Cu")
		(net "NC_CPU1_VIEWPIN_GNR3")
	)
	(arc
		(start 128.431544 -261.65175)
		(mid 128.658731 -261.588732)
		(end 128.887982 -261.643876)
		(width 0.0889)
		(layer "B.Cu")
		(net "NC_CPU1_VIEWPIN_GNR3")
	)
	(arc
		(start 131.250944 -261.65175)
		(mid 131.478131 -261.588732)
		(end 131.707382 -261.643876)
		(width 0.0889)
		(layer "B.Cu")
		(net "NC_CPU1_VIEWPIN_GNR3")
	)
	(arc
		(start 123.262644 -261.65175)
		(mid 123.497594 -261.71471)
		(end 123.732544 -261.65175)
		(width 0.0889)
		(layer "B.Cu")
		(net "NC_CPU1_VIEWPIN_GNR3")
	)
	(arc
		(start 126.082044 -261.65175)
		(mid 126.316994 -261.71471)
		(end 126.551944 -261.65175)
		(width 0.0889)
		(layer "B.Cu")
		(net "NC_CPU1_VIEWPIN_GNR3")
	)
	(arc
		(start 122.792744 -261.65175)
		(mid 123.027694 -261.58879)
		(end 123.262644 -261.65175)
		(width 0.0889)
		(layer "B.Cu")
		(net "NC_CPU1_VIEWPIN_GNR3")
	)
	(arc
		(start 125.142244 -261.65175)
		(mid 125.377194 -261.71471)
		(end 125.612144 -261.65175)
		(width 0.0889)
		(layer "B.Cu")
		(net "NC_CPU1_VIEWPIN_GNR3")
	)
	(segment
		(start 119.628412 -233.34218)
		(end 119.628412 -233.877866)
		(width 0.12954)
		(layer "F.Cu")
		(net "NC_CPU1_VIEWPIN_GNR2")
	)
	(segment
		(start 119.628412 -233.877866)
		(end 119.628666 -233.87812)
		(width 0.12954)
		(layer "F.Cu")
		(net "NC_CPU1_VIEWPIN_GNR2")
	)
	(via
		(at 119.628412 -233.34218)
		(size 0.4572)
		(drill 0.2032)
		(layers "F.Cu" "B.Cu")
		(net "NC_CPU1_VIEWPIN_GNR2")
	)
	(segment
		(start 121.617994 -262.872474)
		(end 121.617994 -262.336788)
		(width 0.12954)
		(layer "F.Cu")
		(net "NC_CPU1_VIEWPIN_GNR1")
	)
	(segment
		(start 121.617994 -262.336788)
		(end 121.618248 -262.336534)
		(width 0.12954)
		(layer "F.Cu")
		(net "NC_CPU1_VIEWPIN_GNR1")
	)
	(via
		(at 121.617994 -262.872474)
		(size 0.4572)
		(drill 0.2032)
		(layers "F.Cu" "B.Cu")
		(net "NC_CPU1_VIEWPIN_GNR1")
	)
	(segment
		(start 120.098312 -234.69219)
		(end 120.098566 -234.691936)
		(width 0.12954)
		(layer "F.Cu")
		(net "NC_CPU1_VIEWPIN_GNR0")
	)
	(segment
		(start 120.098566 -234.691936)
		(end 120.098566 -234.15625)
		(width 0.12954)
		(layer "F.Cu")
		(net "NC_CPU1_VIEWPIN_GNR0")
	)
	(via
		(at 120.098566 -234.15625)
		(size 0.4572)
		(drill 0.2032)
		(layers "F.Cu" "B.Cu")
		(net "NC_CPU1_VIEWPIN_GNR0")
	)
	(via
		(at 120.574562 -235.158026)
		(size 0.6604)
		(drill 0.3302)
		(layers "F.Cu" "B.Cu")
		(net "NC_CPU1_VIEWPIN_GNR0")
	)
	(segment
		(start 120.574562 -234.632246)
		(end 120.574562 -235.158026)
		(width 0.12954)
		(layer "B.Cu")
		(net "NC_CPU1_VIEWPIN_GNR0")
	)
	(segment
		(start 120.098566 -234.15625)
		(end 120.574562 -234.632246)
		(width 0.12954)
		(layer "B.Cu")
		(net "NC_CPU1_VIEWPIN_GNR0")
	)
	(segment
		(start 119.738648 -271.011142)
		(end 119.738394 -271.011396)
		(width 0.12954)
		(layer "F.Cu")
		(net "NC_CPU1_UPI3_APROBE<1>")
	)
	(segment
		(start 119.738648 -270.475456)
		(end 119.738648 -271.011142)
		(width 0.12954)
		(layer "F.Cu")
		(net "NC_CPU1_UPI3_APROBE<1>")
	)
	(via
		(at 119.738394 -271.011396)
		(size 0.4572)
		(drill 0.2032)
		(layers "F.Cu" "B.Cu")
		(net "NC_CPU1_UPI3_APROBE<1>")
	)
	(segment
		(start 119.268494 -271.824958)
		(end 119.268494 -271.289272)
		(width 0.12954)
		(layer "F.Cu")
		(net "NC_CPU1_UPI3_APROBE<0>")
	)
	(segment
		(start 119.26824 -271.825212)
		(end 119.268494 -271.824958)
		(width 0.12954)
		(layer "F.Cu")
		(net "NC_CPU1_UPI3_APROBE<0>")
	)
	(via
		(at 119.26824 -271.825212)
		(size 0.4572)
		(drill 0.2032)
		(layers "F.Cu" "B.Cu")
		(net "NC_CPU1_UPI3_APROBE<0>")
	)
	(segment
		(start 101.412548 -269.661894)
		(end 101.412548 -270.19758)
		(width 0.12954)
		(layer "F.Cu")
		(net "NC_CPU1_UPI2_APROBE<1>")
	)
	(segment
		(start 101.412294 -269.66164)
		(end 101.412548 -269.661894)
		(width 0.12954)
		(layer "F.Cu")
		(net "NC_CPU1_UPI2_APROBE<1>")
	)
	(via
		(at 81.15681 -269.487396)
		(size 0.6604)
		(drill 0.3302)
		(layers "F.Cu" "B.Cu")
		(net "NC_CPU1_UPI2_APROBE<1>")
	)
	(via
		(at 101.412548 -270.19758)
		(size 0.4572)
		(drill 0.2032)
		(layers "F.Cu" "B.Cu")
		(net "NC_CPU1_UPI2_APROBE<1>")
	)
	(segment
		(start 81.668112 -269.998698)
		(end 81.15681 -269.487396)
		(width 0.12954)
		(layer "B.Cu")
		(net "NC_CPU1_UPI2_APROBE<1>")
	)
	(segment
		(start 86.319614 -269.502382)
		(end 86.319614 -269.160244)
		(width 0.0889)
		(layer "B.Cu")
		(net "NC_CPU1_UPI2_APROBE<1>")
	)
	(segment
		(start 86.760304 -269.943072)
		(end 86.319614 -269.502382)
		(width 0.0889)
		(layer "B.Cu")
		(net "NC_CPU1_UPI2_APROBE<1>")
	)
	(segment
		(start 91.827604 -269.873222)
		(end 91.81719 -269.879318)
		(width 0.0889)
		(layer "B.Cu")
		(net "NC_CPU1_UPI2_APROBE<1>")
	)
	(segment
		(start 85.491066 -268.962378)
		(end 84.966302 -269.487142)
		(width 0.0889)
		(layer "B.Cu")
		(net "NC_CPU1_UPI2_APROBE<1>")
	)
	(segment
		(start 83.28279 -269.721584)
		(end 83.005676 -269.998698)
		(width 0.12954)
		(layer "B.Cu")
		(net "NC_CPU1_UPI2_APROBE<1>")
	)
	(segment
		(start 84.241894 -269.721584)
		(end 83.28279 -269.721584)
		(width 0.12954)
		(layer "B.Cu")
		(net "NC_CPU1_UPI2_APROBE<1>")
	)
	(segment
		(start 94.64675 -269.873222)
		(end 94.632018 -269.881858)
		(width 0.0889)
		(layer "B.Cu")
		(net "NC_CPU1_UPI2_APROBE<1>")
	)
	(segment
		(start 89.00795 -269.873222)
		(end 88.993218 -269.881858)
		(width 0.0889)
		(layer "B.Cu")
		(net "NC_CPU1_UPI2_APROBE<1>")
	)
	(segment
		(start 86.121748 -268.962378)
		(end 85.491066 -268.962378)
		(width 0.0889)
		(layer "B.Cu")
		(net "NC_CPU1_UPI2_APROBE<1>")
	)
	(segment
		(start 93.70695 -269.873222)
		(end 93.692218 -269.881858)
		(width 0.0889)
		(layer "B.Cu")
		(net "NC_CPU1_UPI2_APROBE<1>")
	)
	(segment
		(start 83.005676 -269.998698)
		(end 81.668112 -269.998698)
		(width 0.12954)
		(layer "B.Cu")
		(net "NC_CPU1_UPI2_APROBE<1>")
	)
	(segment
		(start 101.569012 -269.926562)
		(end 101.54793 -269.848584)
		(width 0.0889)
		(layer "B.Cu")
		(net "NC_CPU1_UPI2_APROBE<1>")
	)
	(segment
		(start 95.58655 -269.873222)
		(end 95.571818 -269.881858)
		(width 0.0889)
		(layer "B.Cu")
		(net "NC_CPU1_UPI2_APROBE<1>")
	)
	(segment
		(start 98.406204 -269.873222)
		(end 98.39579 -269.879318)
		(width 0.0889)
		(layer "B.Cu")
		(net "NC_CPU1_UPI2_APROBE<1>")
	)
	(segment
		(start 86.319614 -269.160244)
		(end 86.121748 -268.962378)
		(width 0.0889)
		(layer "B.Cu")
		(net "NC_CPU1_UPI2_APROBE<1>")
	)
	(segment
		(start 84.966302 -269.487142)
		(end 84.476336 -269.487142)
		(width 0.0889)
		(layer "B.Cu")
		(net "NC_CPU1_UPI2_APROBE<1>")
	)
	(segment
		(start 90.88755 -269.873222)
		(end 90.872818 -269.881858)
		(width 0.0889)
		(layer "B.Cu")
		(net "NC_CPU1_UPI2_APROBE<1>")
	)
	(segment
		(start 84.476336 -269.487142)
		(end 84.241894 -269.721584)
		(width 0.0889)
		(layer "B.Cu")
		(net "NC_CPU1_UPI2_APROBE<1>")
	)
	(segment
		(start 100.28555 -269.873222)
		(end 100.275136 -269.879318)
		(width 0.0889)
		(layer "B.Cu")
		(net "NC_CPU1_UPI2_APROBE<1>")
	)
	(segment
		(start 101.412548 -270.19758)
		(end 101.569012 -269.926562)
		(width 0.0889)
		(layer "B.Cu")
		(net "NC_CPU1_UPI2_APROBE<1>")
	)
	(segment
		(start 97.46615 -269.873222)
		(end 97.451418 -269.881858)
		(width 0.0889)
		(layer "B.Cu")
		(net "NC_CPU1_UPI2_APROBE<1>")
	)
	(segment
		(start 101.22535 -269.873222)
		(end 101.210618 -269.881858)
		(width 0.0889)
		(layer "B.Cu")
		(net "NC_CPU1_UPI2_APROBE<1>")
	)
	(segment
		(start 92.76715 -269.873222)
		(end 92.756736 -269.879318)
		(width 0.0889)
		(layer "B.Cu")
		(net "NC_CPU1_UPI2_APROBE<1>")
	)
	(arc
		(start 95.021146 -269.873222)
		(mid 94.833948 -269.823079)
		(end 94.64675 -269.873222)
		(width 0.0889)
		(layer "B.Cu")
		(net "NC_CPU1_UPI2_APROBE<1>")
	)
	(arc
		(start 101.210618 -269.881858)
		(mid 100.934143 -269.949178)
		(end 100.659946 -269.873222)
		(width 0.0889)
		(layer "B.Cu")
		(net "NC_CPU1_UPI2_APROBE<1>")
	)
	(arc
		(start 87.004398 -269.926308)
		(mid 86.88327 -269.948031)
		(end 86.760304 -269.943072)
		(width 0.0889)
		(layer "B.Cu")
		(net "NC_CPU1_UPI2_APROBE<1>")
	)
	(arc
		(start 97.840546 -269.873222)
		(mid 97.653348 -269.823079)
		(end 97.46615 -269.873222)
		(width 0.0889)
		(layer "B.Cu")
		(net "NC_CPU1_UPI2_APROBE<1>")
	)
	(arc
		(start 96.900746 -269.873222)
		(mid 96.713548 -269.823079)
		(end 96.52635 -269.873222)
		(width 0.0889)
		(layer "B.Cu")
		(net "NC_CPU1_UPI2_APROBE<1>")
	)
	(arc
		(start 98.39579 -269.879318)
		(mid 98.117358 -269.949164)
		(end 97.840546 -269.873222)
		(width 0.0889)
		(layer "B.Cu")
		(net "NC_CPU1_UPI2_APROBE<1>")
	)
	(arc
		(start 91.81719 -269.879318)
		(mid 91.538758 -269.949164)
		(end 91.261946 -269.873222)
		(width 0.0889)
		(layer "B.Cu")
		(net "NC_CPU1_UPI2_APROBE<1>")
	)
	(arc
		(start 87.502746 -269.873222)
		(mid 87.315548 -269.823079)
		(end 87.12835 -269.873222)
		(width 0.0889)
		(layer "B.Cu")
		(net "NC_CPU1_UPI2_APROBE<1>")
	)
	(arc
		(start 91.261946 -269.873222)
		(mid 91.074748 -269.823079)
		(end 90.88755 -269.873222)
		(width 0.0889)
		(layer "B.Cu")
		(net "NC_CPU1_UPI2_APROBE<1>")
	)
	(arc
		(start 98.7806 -269.873222)
		(mid 98.593402 -269.823079)
		(end 98.406204 -269.873222)
		(width 0.0889)
		(layer "B.Cu")
		(net "NC_CPU1_UPI2_APROBE<1>")
	)
	(arc
		(start 90.872818 -269.881858)
		(mid 90.596343 -269.949178)
		(end 90.322146 -269.873222)
		(width 0.0889)
		(layer "B.Cu")
		(net "NC_CPU1_UPI2_APROBE<1>")
	)
	(arc
		(start 99.346004 -269.873222)
		(mid 99.063302 -269.948998)
		(end 98.7806 -269.873222)
		(width 0.0889)
		(layer "B.Cu")
		(net "NC_CPU1_UPI2_APROBE<1>")
	)
	(arc
		(start 93.692218 -269.881858)
		(mid 93.415743 -269.949178)
		(end 93.141546 -269.873222)
		(width 0.0889)
		(layer "B.Cu")
		(net "NC_CPU1_UPI2_APROBE<1>")
	)
	(arc
		(start 87.12835 -269.873222)
		(mid 87.067962 -269.903472)
		(end 87.004398 -269.926308)
		(width 0.0889)
		(layer "B.Cu")
		(net "NC_CPU1_UPI2_APROBE<1>")
	)
	(arc
		(start 93.141546 -269.873222)
		(mid 92.954348 -269.823079)
		(end 92.76715 -269.873222)
		(width 0.0889)
		(layer "B.Cu")
		(net "NC_CPU1_UPI2_APROBE<1>")
	)
	(arc
		(start 94.632018 -269.881858)
		(mid 94.355543 -269.949178)
		(end 94.081346 -269.873222)
		(width 0.0889)
		(layer "B.Cu")
		(net "NC_CPU1_UPI2_APROBE<1>")
	)
	(arc
		(start 89.94775 -269.873222)
		(mid 89.665048 -269.948998)
		(end 89.382346 -269.873222)
		(width 0.0889)
		(layer "B.Cu")
		(net "NC_CPU1_UPI2_APROBE<1>")
	)
	(arc
		(start 95.960946 -269.873222)
		(mid 95.773748 -269.823079)
		(end 95.58655 -269.873222)
		(width 0.0889)
		(layer "B.Cu")
		(net "NC_CPU1_UPI2_APROBE<1>")
	)
	(arc
		(start 100.659946 -269.873222)
		(mid 100.472748 -269.823079)
		(end 100.28555 -269.873222)
		(width 0.0889)
		(layer "B.Cu")
		(net "NC_CPU1_UPI2_APROBE<1>")
	)
	(arc
		(start 90.322146 -269.873222)
		(mid 90.134948 -269.823079)
		(end 89.94775 -269.873222)
		(width 0.0889)
		(layer "B.Cu")
		(net "NC_CPU1_UPI2_APROBE<1>")
	)
	(arc
		(start 99.7204 -269.873222)
		(mid 99.533202 -269.823079)
		(end 99.346004 -269.873222)
		(width 0.0889)
		(layer "B.Cu")
		(net "NC_CPU1_UPI2_APROBE<1>")
	)
	(arc
		(start 92.202 -269.873222)
		(mid 92.014802 -269.823079)
		(end 91.827604 -269.873222)
		(width 0.0889)
		(layer "B.Cu")
		(net "NC_CPU1_UPI2_APROBE<1>")
	)
	(arc
		(start 88.442546 -269.873222)
		(mid 88.255348 -269.823079)
		(end 88.06815 -269.873222)
		(width 0.0889)
		(layer "B.Cu")
		(net "NC_CPU1_UPI2_APROBE<1>")
	)
	(arc
		(start 88.993218 -269.881858)
		(mid 88.716743 -269.949178)
		(end 88.442546 -269.873222)
		(width 0.0889)
		(layer "B.Cu")
		(net "NC_CPU1_UPI2_APROBE<1>")
	)
	(arc
		(start 97.451418 -269.881858)
		(mid 97.174943 -269.949178)
		(end 96.900746 -269.873222)
		(width 0.0889)
		(layer "B.Cu")
		(net "NC_CPU1_UPI2_APROBE<1>")
	)
	(arc
		(start 95.571818 -269.881858)
		(mid 95.295343 -269.949178)
		(end 95.021146 -269.873222)
		(width 0.0889)
		(layer "B.Cu")
		(net "NC_CPU1_UPI2_APROBE<1>")
	)
	(arc
		(start 100.275136 -269.879318)
		(mid 99.996958 -269.949041)
		(end 99.7204 -269.873222)
		(width 0.0889)
		(layer "B.Cu")
		(net "NC_CPU1_UPI2_APROBE<1>")
	)
	(arc
		(start 96.52635 -269.873222)
		(mid 96.243648 -269.948998)
		(end 95.960946 -269.873222)
		(width 0.0889)
		(layer "B.Cu")
		(net "NC_CPU1_UPI2_APROBE<1>")
	)
	(arc
		(start 89.382346 -269.873222)
		(mid 89.195148 -269.823079)
		(end 89.00795 -269.873222)
		(width 0.0889)
		(layer "B.Cu")
		(net "NC_CPU1_UPI2_APROBE<1>")
	)
	(arc
		(start 92.756736 -269.879318)
		(mid 92.478558 -269.949041)
		(end 92.202 -269.873222)
		(width 0.0889)
		(layer "B.Cu")
		(net "NC_CPU1_UPI2_APROBE<1>")
	)
	(arc
		(start 101.54793 -269.848584)
		(mid 101.383834 -269.824237)
		(end 101.22535 -269.873222)
		(width 0.0889)
		(layer "B.Cu")
		(net "NC_CPU1_UPI2_APROBE<1>")
	)
	(arc
		(start 94.081346 -269.873222)
		(mid 93.894148 -269.823079)
		(end 93.70695 -269.873222)
		(width 0.0889)
		(layer "B.Cu")
		(net "NC_CPU1_UPI2_APROBE<1>")
	)
	(arc
		(start 88.06815 -269.873222)
		(mid 87.785448 -269.948998)
		(end 87.502746 -269.873222)
		(width 0.0889)
		(layer "B.Cu")
		(net "NC_CPU1_UPI2_APROBE<1>")
	)
	(segment
		(start 101.882448 -271.011396)
		(end 101.882448 -270.475456)
		(width 0.12954)
		(layer "F.Cu")
		(net "NC_CPU1_UPI2_APROBE<0>")
	)
	(via
		(at 101.882448 -271.011396)
		(size 0.4572)
		(drill 0.2032)
		(layers "F.Cu" "B.Cu")
		(net "NC_CPU1_UPI2_APROBE<0>")
	)
	(segment
		(start 113.050066 -231.714802)
		(end 113.05032 -231.714548)
		(width 0.12954)
		(layer "F.Cu")
		(net "NC_CPU1_UPI1_APROBE<1>")
	)
	(segment
		(start 113.050066 -232.250488)
		(end 113.050066 -231.714802)
		(width 0.12954)
		(layer "F.Cu")
		(net "NC_CPU1_UPI1_APROBE<1>")
	)
	(via
		(at 113.05032 -231.714548)
		(size 0.4572)
		(drill 0.2032)
		(layers "F.Cu" "B.Cu")
		(net "NC_CPU1_UPI1_APROBE<1>")
	)
	(segment
		(start 111.640112 -231.436418)
		(end 111.640112 -230.900732)
		(width 0.12954)
		(layer "F.Cu")
		(net "NC_CPU1_UPI1_APROBE<0>")
	)
	(segment
		(start 111.640112 -230.900732)
		(end 111.640366 -230.900478)
		(width 0.12954)
		(layer "F.Cu")
		(net "NC_CPU1_UPI1_APROBE<0>")
	)
	(via
		(at 111.640366 -230.900478)
		(size 0.4572)
		(drill 0.2032)
		(layers "F.Cu" "B.Cu")
		(net "NC_CPU1_UPI1_APROBE<0>")
	)
	(segment
		(start 100.832666 -227.367084)
		(end 100.832666 -226.831144)
		(width 0.12954)
		(layer "F.Cu")
		(net "NC_CPU1_UPI0_APROBE<1>")
	)
	(via
		(at 100.832666 -226.831144)
		(size 0.4572)
		(drill 0.2032)
		(layers "F.Cu" "B.Cu")
		(net "NC_CPU1_UPI0_APROBE<1>")
	)
	(segment
		(start 99.892866 -227.367084)
		(end 99.892866 -226.831144)
		(width 0.12954)
		(layer "F.Cu")
		(net "NC_CPU1_UPI0_APROBE<0>")
	)
	(via
		(at 99.892866 -226.831144)
		(size 0.4572)
		(drill 0.2032)
		(layers "F.Cu" "B.Cu")
		(net "NC_CPU1_UPI0_APROBE<0>")
	)
	(segment
		(start 102.242366 -243.922804)
		(end 102.242112 -243.923058)
		(width 0.12954)
		(layer "F.Cu")
		(net "NC_CPU1_THERMADC")
	)
	(segment
		(start 102.242112 -243.923058)
		(end 102.242112 -244.458744)
		(width 0.12954)
		(layer "F.Cu")
		(net "NC_CPU1_THERMADC")
	)
	(via
		(at 102.242366 -243.922804)
		(size 0.4572)
		(drill 0.2032)
		(layers "F.Cu" "B.Cu")
		(net "NC_CPU1_THERMADC")
	)
	(segment
		(start 102.242366 -245.55069)
		(end 102.242112 -245.550944)
		(width 0.12954)
		(layer "F.Cu")
		(net "NC_CPU1_THERMADA")
	)
	(segment
		(start 102.242112 -245.550944)
		(end 102.242112 -246.08663)
		(width 0.12954)
		(layer "F.Cu")
		(net "NC_CPU1_THERMADA")
	)
	(via
		(at 102.242366 -245.55069)
		(size 0.4572)
		(drill 0.2032)
		(layers "F.Cu" "B.Cu")
		(net "NC_CPU1_THERMADA")
	)
	(segment
		(start 109.870494 -268.033754)
		(end 109.870494 -268.569694)
		(width 0.12954)
		(layer "F.Cu")
		(net "NC_CPU1_SOC_SPARE5")
	)
	(via
		(at 109.870494 -268.569694)
		(size 0.4572)
		(drill 0.2032)
		(layers "F.Cu" "B.Cu")
		(net "NC_CPU1_SOC_SPARE5")
	)
	(segment
		(start 103.652066 -233.87812)
		(end 103.652066 -233.342434)
		(width 0.12954)
		(layer "F.Cu")
		(net "NC_CPU1_SOC_SPARE4")
	)
	(segment
		(start 103.652066 -233.342434)
		(end 103.651812 -233.34218)
		(width 0.12954)
		(layer "F.Cu")
		(net "NC_CPU1_SOC_SPARE4")
	)
	(via
		(at 103.651812 -233.34218)
		(size 0.4572)
		(drill 0.2032)
		(layers "F.Cu" "B.Cu")
		(net "NC_CPU1_SOC_SPARE4")
	)
	(segment
		(start 108.930694 -268.033754)
		(end 108.930694 -268.569694)
		(width 0.12954)
		(layer "F.Cu")
		(net "NC_CPU1_SOC_SPARE1")
	)
	(via
		(at 108.930694 -268.569694)
		(size 0.4572)
		(drill 0.2032)
		(layers "F.Cu" "B.Cu")
		(net "NC_CPU1_SOC_SPARE1")
	)
	(segment
		(start 103.181912 -232.528618)
		(end 103.181912 -233.064304)
		(width 0.12954)
		(layer "F.Cu")
		(net "NC_CPU1_SOC_SPARE0")
	)
	(segment
		(start 103.182166 -232.528364)
		(end 103.181912 -232.528618)
		(width 0.12954)
		(layer "F.Cu")
		(net "NC_CPU1_SOC_SPARE0")
	)
	(via
		(at 103.182166 -232.528364)
		(size 0.4572)
		(drill 0.2032)
		(layers "F.Cu" "B.Cu")
		(net "NC_CPU1_SOC_SPARE0")
	)
	(segment
		(start 101.882448 -268.84757)
		(end 101.882448 -269.383256)
		(width 0.12954)
		(layer "F.Cu")
		(net "NC_CPU1_PE4_APROBE<1>")
	)
	(segment
		(start 101.882448 -269.383256)
		(end 101.882702 -269.38351)
		(width 0.12954)
		(layer "F.Cu")
		(net "NC_CPU1_PE4_APROBE<1>")
	)
	(via
		(at 82.42681 -269.487396)
		(size 0.6604)
		(drill 0.3302)
		(layers "F.Cu" "B.Cu")
		(net "NC_CPU1_PE4_APROBE<1>")
	)
	(via
		(at 101.882702 -269.38351)
		(size 0.4572)
		(drill 0.2032)
		(layers "F.Cu" "B.Cu")
		(net "NC_CPU1_PE4_APROBE<1>")
	)
	(segment
		(start 84.191348 -269.225522)
		(end 84.046822 -269.370048)
		(width 0.12954)
		(layer "B.Cu")
		(net "NC_CPU1_PE4_APROBE<1>")
	)
	(segment
		(start 89.86266 -269.702026)
		(end 89.852246 -269.708122)
		(width 0.0889)
		(layer "B.Cu")
		(net "NC_CPU1_PE4_APROBE<1>")
	)
	(segment
		(start 84.046822 -269.370048)
		(end 83.021424 -269.370048)
		(width 0.12954)
		(layer "B.Cu")
		(net "NC_CPU1_PE4_APROBE<1>")
	)
	(segment
		(start 85.412072 -268.772132)
		(end 84.958682 -269.225522)
		(width 0.0889)
		(layer "B.Cu")
		(net "NC_CPU1_PE4_APROBE<1>")
	)
	(segment
		(start 82.495898 -269.556484)
		(end 82.42681 -269.487396)
		(width 0.12954)
		(layer "B.Cu")
		(net "NC_CPU1_PE4_APROBE<1>")
	)
	(segment
		(start 86.50986 -269.423388)
		(end 86.50986 -269.08125)
		(width 0.0889)
		(layer "B.Cu")
		(net "NC_CPU1_PE4_APROBE<1>")
	)
	(segment
		(start 87.98306 -269.702026)
		(end 87.972646 -269.708122)
		(width 0.0889)
		(layer "B.Cu")
		(net "NC_CPU1_PE4_APROBE<1>")
	)
	(segment
		(start 83.021424 -269.370048)
		(end 82.834988 -269.556484)
		(width 0.12954)
		(layer "B.Cu")
		(net "NC_CPU1_PE4_APROBE<1>")
	)
	(segment
		(start 86.200742 -268.772132)
		(end 85.412072 -268.772132)
		(width 0.0889)
		(layer "B.Cu")
		(net "NC_CPU1_PE4_APROBE<1>")
	)
	(segment
		(start 82.834988 -269.556484)
		(end 82.495898 -269.556484)
		(width 0.12954)
		(layer "B.Cu")
		(net "NC_CPU1_PE4_APROBE<1>")
	)
	(segment
		(start 94.566232 -269.699486)
		(end 94.5515 -269.708122)
		(width 0.0889)
		(layer "B.Cu")
		(net "NC_CPU1_PE4_APROBE<1>")
	)
	(segment
		(start 88.923114 -269.702026)
		(end 88.9127 -269.708122)
		(width 0.0889)
		(layer "B.Cu")
		(net "NC_CPU1_PE4_APROBE<1>")
	)
	(segment
		(start 86.50986 -269.08125)
		(end 86.200742 -268.772132)
		(width 0.0889)
		(layer "B.Cu")
		(net "NC_CPU1_PE4_APROBE<1>")
	)
	(segment
		(start 86.845394 -269.758922)
		(end 86.50986 -269.423388)
		(width 0.0889)
		(layer "B.Cu")
		(net "NC_CPU1_PE4_APROBE<1>")
	)
	(segment
		(start 84.958682 -269.225522)
		(end 84.191348 -269.225522)
		(width 0.0889)
		(layer "B.Cu")
		(net "NC_CPU1_PE4_APROBE<1>")
	)
	(segment
		(start 95.501714 -269.702026)
		(end 95.4913 -269.708122)
		(width 0.0889)
		(layer "B.Cu")
		(net "NC_CPU1_PE4_APROBE<1>")
	)
	(segment
		(start 100.205032 -269.699486)
		(end 100.1903 -269.708122)
		(width 0.0889)
		(layer "B.Cu")
		(net "NC_CPU1_PE4_APROBE<1>")
	)
	(segment
		(start 97.385632 -269.699486)
		(end 97.3709 -269.708122)
		(width 0.0889)
		(layer "B.Cu")
		(net "NC_CPU1_PE4_APROBE<1>")
	)
	(segment
		(start 92.686632 -269.699486)
		(end 92.6719 -269.708122)
		(width 0.0889)
		(layer "B.Cu")
		(net "NC_CPU1_PE4_APROBE<1>")
	)
	(segment
		(start 101.882702 -269.38351)
		(end 101.726238 -269.654782)
		(width 0.0889)
		(layer "B.Cu")
		(net "NC_CPU1_PE4_APROBE<1>")
	)
	(segment
		(start 101.726238 -269.654782)
		(end 101.637084 -269.678658)
		(width 0.0889)
		(layer "B.Cu")
		(net "NC_CPU1_PE4_APROBE<1>")
	)
	(segment
		(start 93.626432 -269.699486)
		(end 93.6117 -269.708122)
		(width 0.0889)
		(layer "B.Cu")
		(net "NC_CPU1_PE4_APROBE<1>")
	)
	(segment
		(start 96.44126 -269.702026)
		(end 96.430846 -269.708122)
		(width 0.0889)
		(layer "B.Cu")
		(net "NC_CPU1_PE4_APROBE<1>")
	)
	(segment
		(start 101.144832 -269.699486)
		(end 101.1301 -269.708122)
		(width 0.0889)
		(layer "B.Cu")
		(net "NC_CPU1_PE4_APROBE<1>")
	)
	(segment
		(start 90.807032 -269.699486)
		(end 90.7923 -269.708122)
		(width 0.0889)
		(layer "B.Cu")
		(net "NC_CPU1_PE4_APROBE<1>")
	)
	(arc
		(start 92.6719 -269.708122)
		(mid 92.484702 -269.758265)
		(end 92.297504 -269.708122)
		(width 0.0889)
		(layer "B.Cu")
		(net "NC_CPU1_PE4_APROBE<1>")
	)
	(arc
		(start 96.430846 -269.708122)
		(mid 96.243648 -269.758265)
		(end 96.05645 -269.708122)
		(width 0.0889)
		(layer "B.Cu")
		(net "NC_CPU1_PE4_APROBE<1>")
	)
	(arc
		(start 98.876104 -269.708122)
		(mid 98.593402 -269.632346)
		(end 98.3107 -269.708122)
		(width 0.0889)
		(layer "B.Cu")
		(net "NC_CPU1_PE4_APROBE<1>")
	)
	(arc
		(start 95.116904 -269.708122)
		(mid 94.842705 -269.632287)
		(end 94.566232 -269.699486)
		(width 0.0889)
		(layer "B.Cu")
		(net "NC_CPU1_PE4_APROBE<1>")
	)
	(arc
		(start 89.852246 -269.708122)
		(mid 89.665048 -269.758265)
		(end 89.47785 -269.708122)
		(width 0.0889)
		(layer "B.Cu")
		(net "NC_CPU1_PE4_APROBE<1>")
	)
	(arc
		(start 101.637084 -269.678658)
		(mid 101.388579 -269.632671)
		(end 101.144832 -269.699486)
		(width 0.0889)
		(layer "B.Cu")
		(net "NC_CPU1_PE4_APROBE<1>")
	)
	(arc
		(start 96.05645 -269.708122)
		(mid 95.779891 -269.632379)
		(end 95.501714 -269.702026)
		(width 0.0889)
		(layer "B.Cu")
		(net "NC_CPU1_PE4_APROBE<1>")
	)
	(arc
		(start 100.1903 -269.708122)
		(mid 100.003102 -269.758265)
		(end 99.815904 -269.708122)
		(width 0.0889)
		(layer "B.Cu")
		(net "NC_CPU1_PE4_APROBE<1>")
	)
	(arc
		(start 87.032846 -269.708122)
		(mid 86.942467 -269.745877)
		(end 86.845394 -269.758922)
		(width 0.0889)
		(layer "B.Cu")
		(net "NC_CPU1_PE4_APROBE<1>")
	)
	(arc
		(start 97.3709 -269.708122)
		(mid 97.183702 -269.758265)
		(end 96.996504 -269.708122)
		(width 0.0889)
		(layer "B.Cu")
		(net "NC_CPU1_PE4_APROBE<1>")
	)
	(arc
		(start 94.177104 -269.708122)
		(mid 93.902905 -269.632287)
		(end 93.626432 -269.699486)
		(width 0.0889)
		(layer "B.Cu")
		(net "NC_CPU1_PE4_APROBE<1>")
	)
	(arc
		(start 98.3107 -269.708122)
		(mid 98.123502 -269.758265)
		(end 97.936304 -269.708122)
		(width 0.0889)
		(layer "B.Cu")
		(net "NC_CPU1_PE4_APROBE<1>")
	)
	(arc
		(start 95.4913 -269.708122)
		(mid 95.304102 -269.758265)
		(end 95.116904 -269.708122)
		(width 0.0889)
		(layer "B.Cu")
		(net "NC_CPU1_PE4_APROBE<1>")
	)
	(arc
		(start 90.7923 -269.708122)
		(mid 90.605102 -269.758265)
		(end 90.417904 -269.708122)
		(width 0.0889)
		(layer "B.Cu")
		(net "NC_CPU1_PE4_APROBE<1>")
	)
	(arc
		(start 90.417904 -269.708122)
		(mid 90.141091 -269.632252)
		(end 89.86266 -269.702026)
		(width 0.0889)
		(layer "B.Cu")
		(net "NC_CPU1_PE4_APROBE<1>")
	)
	(arc
		(start 100.755704 -269.708122)
		(mid 100.481505 -269.632287)
		(end 100.205032 -269.699486)
		(width 0.0889)
		(layer "B.Cu")
		(net "NC_CPU1_PE4_APROBE<1>")
	)
	(arc
		(start 94.5515 -269.708122)
		(mid 94.364302 -269.758265)
		(end 94.177104 -269.708122)
		(width 0.0889)
		(layer "B.Cu")
		(net "NC_CPU1_PE4_APROBE<1>")
	)
	(arc
		(start 96.996504 -269.708122)
		(mid 96.719691 -269.632252)
		(end 96.44126 -269.702026)
		(width 0.0889)
		(layer "B.Cu")
		(net "NC_CPU1_PE4_APROBE<1>")
	)
	(arc
		(start 93.237304 -269.708122)
		(mid 92.963105 -269.632287)
		(end 92.686632 -269.699486)
		(width 0.0889)
		(layer "B.Cu")
		(net "NC_CPU1_PE4_APROBE<1>")
	)
	(arc
		(start 89.47785 -269.708122)
		(mid 89.201291 -269.632379)
		(end 88.923114 -269.702026)
		(width 0.0889)
		(layer "B.Cu")
		(net "NC_CPU1_PE4_APROBE<1>")
	)
	(arc
		(start 92.297504 -269.708122)
		(mid 92.014802 -269.632346)
		(end 91.7321 -269.708122)
		(width 0.0889)
		(layer "B.Cu")
		(net "NC_CPU1_PE4_APROBE<1>")
	)
	(arc
		(start 87.972646 -269.708122)
		(mid 87.785448 -269.758265)
		(end 87.59825 -269.708122)
		(width 0.0889)
		(layer "B.Cu")
		(net "NC_CPU1_PE4_APROBE<1>")
	)
	(arc
		(start 97.936304 -269.708122)
		(mid 97.662105 -269.632287)
		(end 97.385632 -269.699486)
		(width 0.0889)
		(layer "B.Cu")
		(net "NC_CPU1_PE4_APROBE<1>")
	)
	(arc
		(start 88.9127 -269.708122)
		(mid 88.725502 -269.758265)
		(end 88.538304 -269.708122)
		(width 0.0889)
		(layer "B.Cu")
		(net "NC_CPU1_PE4_APROBE<1>")
	)
	(arc
		(start 101.1301 -269.708122)
		(mid 100.942902 -269.758265)
		(end 100.755704 -269.708122)
		(width 0.0889)
		(layer "B.Cu")
		(net "NC_CPU1_PE4_APROBE<1>")
	)
	(arc
		(start 99.815904 -269.708122)
		(mid 99.533202 -269.632346)
		(end 99.2505 -269.708122)
		(width 0.0889)
		(layer "B.Cu")
		(net "NC_CPU1_PE4_APROBE<1>")
	)
	(arc
		(start 91.7321 -269.708122)
		(mid 91.544902 -269.758265)
		(end 91.357704 -269.708122)
		(width 0.0889)
		(layer "B.Cu")
		(net "NC_CPU1_PE4_APROBE<1>")
	)
	(arc
		(start 91.357704 -269.708122)
		(mid 91.083505 -269.632287)
		(end 90.807032 -269.699486)
		(width 0.0889)
		(layer "B.Cu")
		(net "NC_CPU1_PE4_APROBE<1>")
	)
	(arc
		(start 99.2505 -269.708122)
		(mid 99.063302 -269.758265)
		(end 98.876104 -269.708122)
		(width 0.0889)
		(layer "B.Cu")
		(net "NC_CPU1_PE4_APROBE<1>")
	)
	(arc
		(start 93.6117 -269.708122)
		(mid 93.424502 -269.758265)
		(end 93.237304 -269.708122)
		(width 0.0889)
		(layer "B.Cu")
		(net "NC_CPU1_PE4_APROBE<1>")
	)
	(arc
		(start 88.538304 -269.708122)
		(mid 88.261491 -269.632252)
		(end 87.98306 -269.702026)
		(width 0.0889)
		(layer "B.Cu")
		(net "NC_CPU1_PE4_APROBE<1>")
	)
	(arc
		(start 87.59825 -269.708122)
		(mid 87.315548 -269.632346)
		(end 87.032846 -269.708122)
		(width 0.0889)
		(layer "B.Cu")
		(net "NC_CPU1_PE4_APROBE<1>")
	)
	(segment
		(start 102.352348 -269.661894)
		(end 102.352094 -269.66164)
		(width 0.12954)
		(layer "F.Cu")
		(net "NC_CPU1_PE4_APROBE<0>")
	)
	(segment
		(start 102.352348 -270.19758)
		(end 102.352348 -269.661894)
		(width 0.12954)
		(layer "F.Cu")
		(net "NC_CPU1_PE4_APROBE<0>")
	)
	(via
		(at 102.352348 -270.19758)
		(size 0.4572)
		(drill 0.2032)
		(layers "F.Cu" "B.Cu")
		(net "NC_CPU1_PE4_APROBE<0>")
	)
	(segment
		(start 118.328694 -271.289272)
		(end 118.32844 -271.289526)
		(width 0.12954)
		(layer "F.Cu")
		(net "NC_CPU1_PE3_APROBE<1>")
	)
	(segment
		(start 118.32844 -271.289526)
		(end 118.32844 -271.825212)
		(width 0.12954)
		(layer "F.Cu")
		(net "NC_CPU1_PE3_APROBE<1>")
	)
	(via
		(at 118.32844 -271.825212)
		(size 0.4572)
		(drill 0.2032)
		(layers "F.Cu" "B.Cu")
		(net "NC_CPU1_PE3_APROBE<1>")
	)
	(segment
		(start 117.858794 -270.47571)
		(end 117.859048 -270.475456)
		(width 0.12954)
		(layer "F.Cu")
		(net "NC_CPU1_PE3_APROBE<0>")
	)
	(segment
		(start 117.858794 -271.011396)
		(end 117.858794 -270.47571)
		(width 0.12954)
		(layer "F.Cu")
		(net "NC_CPU1_PE3_APROBE<0>")
	)
	(via
		(at 117.858794 -271.011396)
		(size 0.4572)
		(drill 0.2032)
		(layers "F.Cu" "B.Cu")
		(net "NC_CPU1_PE3_APROBE<0>")
	)
	(segment
		(start 112.11052 -231.714548)
		(end 112.110266 -231.714802)
		(width 0.12954)
		(layer "F.Cu")
		(net "NC_CPU1_PE2_APROBE<1>")
	)
	(segment
		(start 112.110266 -231.714802)
		(end 112.110266 -232.250488)
		(width 0.12954)
		(layer "F.Cu")
		(net "NC_CPU1_PE2_APROBE<1>")
	)
	(via
		(at 112.11052 -231.714548)
		(size 0.4572)
		(drill 0.2032)
		(layers "F.Cu" "B.Cu")
		(net "NC_CPU1_PE2_APROBE<1>")
	)
	(segment
		(start 113.989866 -231.714802)
		(end 113.989866 -232.250488)
		(width 0.12954)
		(layer "F.Cu")
		(net "NC_CPU1_PE2_APROBE<0>")
	)
	(segment
		(start 113.99012 -231.714548)
		(end 113.989866 -231.714802)
		(width 0.12954)
		(layer "F.Cu")
		(net "NC_CPU1_PE2_APROBE<0>")
	)
	(via
		(at 113.99012 -231.714548)
		(size 0.4572)
		(drill 0.2032)
		(layers "F.Cu" "B.Cu")
		(net "NC_CPU1_PE2_APROBE<0>")
	)
	(segment
		(start 113.989612 -230.622348)
		(end 113.989612 -230.086916)
		(width 0.12954)
		(layer "F.Cu")
		(net "NC_CPU1_PE1_APROBE<1>")
	)
	(segment
		(start 113.989866 -230.622602)
		(end 113.989612 -230.622348)
		(width 0.12954)
		(layer "F.Cu")
		(net "NC_CPU1_PE1_APROBE<1>")
	)
	(segment
		(start 113.989612 -230.086916)
		(end 113.989866 -230.086662)
		(width 0.12954)
		(layer "F.Cu")
		(net "NC_CPU1_PE1_APROBE<1>")
	)
	(via
		(at 113.989866 -230.086662)
		(size 0.4572)
		(drill 0.2032)
		(layers "F.Cu" "B.Cu")
		(net "NC_CPU1_PE1_APROBE<1>")
	)
	(segment
		(start 114.929412 -230.622348)
		(end 114.929666 -230.622602)
		(width 0.12954)
		(layer "F.Cu")
		(net "NC_CPU1_PE1_APROBE<0>")
	)
	(segment
		(start 114.929412 -230.086916)
		(end 114.929412 -230.622348)
		(width 0.12954)
		(layer "F.Cu")
		(net "NC_CPU1_PE1_APROBE<0>")
	)
	(segment
		(start 114.929666 -230.086662)
		(end 114.929412 -230.086916)
		(width 0.12954)
		(layer "F.Cu")
		(net "NC_CPU1_PE1_APROBE<0>")
	)
	(via
		(at 114.929666 -230.086662)
		(size 0.4572)
		(drill 0.2032)
		(layers "F.Cu" "B.Cu")
		(net "NC_CPU1_PE1_APROBE<0>")
	)
	(segment
		(start 108.350812 -230.086662)
		(end 108.351066 -230.086916)
		(width 0.12954)
		(layer "F.Cu")
		(net "NC_CPU1_PE0_APROBE<1>")
	)
	(segment
		(start 108.351066 -230.086916)
		(end 108.351066 -230.622602)
		(width 0.12954)
		(layer "F.Cu")
		(net "NC_CPU1_PE0_APROBE<1>")
	)
	(via
		(at 108.350812 -230.086662)
		(size 0.4572)
		(drill 0.2032)
		(layers "F.Cu" "B.Cu")
		(net "NC_CPU1_PE0_APROBE<1>")
	)
	(segment
		(start 109.290612 -230.622348)
		(end 109.290612 -230.086662)
		(width 0.12954)
		(layer "F.Cu")
		(net "NC_CPU1_PE0_APROBE<0>")
	)
	(segment
		(start 109.290866 -230.622602)
		(end 109.290612 -230.622348)
		(width 0.12954)
		(layer "F.Cu")
		(net "NC_CPU1_PE0_APROBE<0>")
	)
	(via
		(at 109.290612 -230.086662)
		(size 0.4572)
		(drill 0.2032)
		(layers "F.Cu" "B.Cu")
		(net "NC_CPU1_PE0_APROBE<0>")
	)
	(segment
		(start 117.388894 -269.66164)
		(end 117.388894 -270.19758)
		(width 0.12954)
		(layer "F.Cu")
		(net "NC_CPU1_MDFI_DIE11_NS1")
	)
	(via
		(at 117.388894 -270.19758)
		(size 0.4572)
		(drill 0.2032)
		(layers "F.Cu" "B.Cu")
		(net "NC_CPU1_MDFI_DIE11_NS1")
	)
	(segment
		(start 116.918994 -270.47571)
		(end 116.918994 -271.011396)
		(width 0.12954)
		(layer "F.Cu")
		(net "NC_CPU1_MDFI_DIE11_NS0")
	)
	(segment
		(start 116.919248 -270.475456)
		(end 116.918994 -270.47571)
		(width 0.12954)
		(layer "F.Cu")
		(net "NC_CPU1_MDFI_DIE11_NS0")
	)
	(via
		(at 116.918994 -271.011396)
		(size 0.4572)
		(drill 0.2032)
		(layers "F.Cu" "B.Cu")
		(net "NC_CPU1_MDFI_DIE11_NS0")
	)
	(segment
		(start 116.449094 -271.824958)
		(end 116.449094 -271.289272)
		(width 0.12954)
		(layer "F.Cu")
		(net "NC_CPU1_MDFI_DIE11_EW1")
	)
	(segment
		(start 116.44884 -271.825212)
		(end 116.449094 -271.824958)
		(width 0.12954)
		(layer "F.Cu")
		(net "NC_CPU1_MDFI_DIE11_EW1")
	)
	(via
		(at 116.44884 -271.825212)
		(size 0.4572)
		(drill 0.2032)
		(layers "F.Cu" "B.Cu")
		(net "NC_CPU1_MDFI_DIE11_EW1")
	)
	(segment
		(start 116.919248 -272.639028)
		(end 116.918994 -272.639282)
		(width 0.12954)
		(layer "F.Cu")
		(net "NC_CPU1_MDFI_DIE11_EW0")
	)
	(segment
		(start 116.919248 -272.103342)
		(end 116.919248 -272.639028)
		(width 0.12954)
		(layer "F.Cu")
		(net "NC_CPU1_MDFI_DIE11_EW0")
	)
	(via
		(at 116.918994 -272.639282)
		(size 0.4572)
		(drill 0.2032)
		(layers "F.Cu" "B.Cu")
		(net "NC_CPU1_MDFI_DIE11_EW0")
	)
	(segment
		(start 114.459766 -231.436418)
		(end 114.459766 -230.900732)
		(width 0.12954)
		(layer "F.Cu")
		(net "NC_CPU1_MDFI_DIE10_NS1")
	)
	(segment
		(start 114.459766 -230.900732)
		(end 114.46002 -230.900478)
		(width 0.12954)
		(layer "F.Cu")
		(net "NC_CPU1_MDFI_DIE10_NS1")
	)
	(via
		(at 114.46002 -230.900478)
		(size 0.4572)
		(drill 0.2032)
		(layers "F.Cu" "B.Cu")
		(net "NC_CPU1_MDFI_DIE10_NS1")
	)
	(segment
		(start 115.399312 -230.900732)
		(end 115.399566 -230.900478)
		(width 0.12954)
		(layer "F.Cu")
		(net "NC_CPU1_MDFI_DIE10_NS0")
	)
	(segment
		(start 115.399312 -231.436418)
		(end 115.399312 -230.900732)
		(width 0.12954)
		(layer "F.Cu")
		(net "NC_CPU1_MDFI_DIE10_NS0")
	)
	(via
		(at 115.399566 -230.900478)
		(size 0.4572)
		(drill 0.2032)
		(layers "F.Cu" "B.Cu")
		(net "NC_CPU1_MDFI_DIE10_NS0")
	)
	(segment
		(start 114.459766 -234.69219)
		(end 114.459766 -234.15625)
		(width 0.12954)
		(layer "F.Cu")
		(net "NC_CPU1_MDFI_DIE10_EW0")
	)
	(via
		(at 114.459766 -234.15625)
		(size 0.4572)
		(drill 0.2032)
		(layers "F.Cu" "B.Cu")
		(net "NC_CPU1_MDFI_DIE10_EW0")
	)
	(segment
		(start 106.111548 -273.453098)
		(end 106.111548 -272.917412)
		(width 0.12954)
		(layer "F.Cu")
		(net "NC_CPU1_MDFI_DIE01_NS0")
	)
	(segment
		(start 106.111548 -272.917412)
		(end 106.111294 -272.917158)
		(width 0.12954)
		(layer "F.Cu")
		(net "NC_CPU1_MDFI_DIE01_NS0")
	)
	(via
		(at 106.111548 -273.453098)
		(size 0.4572)
		(drill 0.2032)
		(layers "F.Cu" "B.Cu")
		(net "NC_CPU1_MDFI_DIE01_NS0")
	)
	(segment
		(start 114.100102 -269.38351)
		(end 114.099848 -269.383256)
		(width 0.12954)
		(layer "F.Cu")
		(net "NC_CPU1_MDFI_DIE01_EW1")
	)
	(segment
		(start 114.099848 -269.383256)
		(end 114.099848 -268.84757)
		(width 0.12954)
		(layer "F.Cu")
		(net "NC_CPU1_MDFI_DIE01_EW1")
	)
	(via
		(at 114.100102 -269.38351)
		(size 0.4572)
		(drill 0.2032)
		(layers "F.Cu" "B.Cu")
		(net "NC_CPU1_MDFI_DIE01_EW1")
	)
	(segment
		(start 102.352094 -268.033754)
		(end 102.352348 -268.034008)
		(width 0.12954)
		(layer "F.Cu")
		(net "NC_CPU1_MDFI_DIE01_EW0")
	)
	(segment
		(start 102.352348 -268.034008)
		(end 102.352348 -268.569694)
		(width 0.12954)
		(layer "F.Cu")
		(net "NC_CPU1_MDFI_DIE01_EW0")
	)
	(via
		(at 86.926674 -267.984732)
		(size 0.6604)
		(drill 0.3302)
		(layers "F.Cu" "B.Cu")
		(net "NC_CPU1_MDFI_DIE01_EW0")
	)
	(via
		(at 102.352348 -268.569694)
		(size 0.4572)
		(drill 0.2032)
		(layers "F.Cu" "B.Cu")
		(net "NC_CPU1_MDFI_DIE01_EW0")
	)
	(segment
		(start 88.08212 -267.984732)
		(end 88.294718 -268.19733)
		(width 0.0889)
		(layer "B.Cu")
		(net "NC_CPU1_MDFI_DIE01_EW0")
	)
	(segment
		(start 99.33559 -268.251432)
		(end 99.346004 -268.245336)
		(width 0.0889)
		(layer "B.Cu")
		(net "NC_CPU1_MDFI_DIE01_EW0")
	)
	(segment
		(start 102.48773 -268.220698)
		(end 102.508812 -268.298676)
		(width 0.0889)
		(layer "B.Cu")
		(net "NC_CPU1_MDFI_DIE01_EW0")
	)
	(segment
		(start 86.926674 -267.984732)
		(end 88.08212 -267.984732)
		(width 0.12954)
		(layer "B.Cu")
		(net "NC_CPU1_MDFI_DIE01_EW0")
	)
	(segment
		(start 93.696536 -268.251432)
		(end 93.70695 -268.245336)
		(width 0.0889)
		(layer "B.Cu")
		(net "NC_CPU1_MDFI_DIE01_EW0")
	)
	(segment
		(start 98.391218 -268.253972)
		(end 98.40595 -268.245336)
		(width 0.0889)
		(layer "B.Cu")
		(net "NC_CPU1_MDFI_DIE01_EW0")
	)
	(segment
		(start 89.933018 -268.253972)
		(end 89.94775 -268.245336)
		(width 0.0889)
		(layer "B.Cu")
		(net "NC_CPU1_MDFI_DIE01_EW0")
	)
	(segment
		(start 102.150418 -268.253972)
		(end 102.16515 -268.245336)
		(width 0.0889)
		(layer "B.Cu")
		(net "NC_CPU1_MDFI_DIE01_EW0")
	)
	(segment
		(start 102.508812 -268.298676)
		(end 102.352348 -268.569694)
		(width 0.0889)
		(layer "B.Cu")
		(net "NC_CPU1_MDFI_DIE01_EW0")
	)
	(segment
		(start 101.214936 -268.251432)
		(end 101.22535 -268.245336)
		(width 0.0889)
		(layer "B.Cu")
		(net "NC_CPU1_MDFI_DIE01_EW0")
	)
	(segment
		(start 91.812618 -268.253972)
		(end 91.82735 -268.245336)
		(width 0.0889)
		(layer "B.Cu")
		(net "NC_CPU1_MDFI_DIE01_EW0")
	)
	(segment
		(start 95.571818 -268.253972)
		(end 95.58655 -268.245336)
		(width 0.0889)
		(layer "B.Cu")
		(net "NC_CPU1_MDFI_DIE01_EW0")
	)
	(segment
		(start 92.75699 -268.251432)
		(end 92.767404 -268.245336)
		(width 0.0889)
		(layer "B.Cu")
		(net "NC_CPU1_MDFI_DIE01_EW0")
	)
	(segment
		(start 94.632018 -268.253972)
		(end 94.64675 -268.245336)
		(width 0.0889)
		(layer "B.Cu")
		(net "NC_CPU1_MDFI_DIE01_EW0")
	)
	(segment
		(start 96.511618 -268.253972)
		(end 96.52635 -268.245336)
		(width 0.0889)
		(layer "B.Cu")
		(net "NC_CPU1_MDFI_DIE01_EW0")
	)
	(arc
		(start 92.201746 -268.245336)
		(mid 92.478559 -268.321206)
		(end 92.75699 -268.251432)
		(width 0.0889)
		(layer "B.Cu")
		(net "NC_CPU1_MDFI_DIE01_EW0")
	)
	(arc
		(start 94.081346 -268.245336)
		(mid 94.355545 -268.321171)
		(end 94.632018 -268.253972)
		(width 0.0889)
		(layer "B.Cu")
		(net "NC_CPU1_MDFI_DIE01_EW0")
	)
	(arc
		(start 98.40595 -268.245336)
		(mid 98.593148 -268.195193)
		(end 98.780346 -268.245336)
		(width 0.0889)
		(layer "B.Cu")
		(net "NC_CPU1_MDFI_DIE01_EW0")
	)
	(arc
		(start 88.442546 -268.245336)
		(mid 88.725248 -268.321112)
		(end 89.00795 -268.245336)
		(width 0.0889)
		(layer "B.Cu")
		(net "NC_CPU1_MDFI_DIE01_EW0")
	)
	(arc
		(start 99.7204 -268.245336)
		(mid 100.003102 -268.321112)
		(end 100.285804 -268.245336)
		(width 0.0889)
		(layer "B.Cu")
		(net "NC_CPU1_MDFI_DIE01_EW0")
	)
	(arc
		(start 97.840546 -268.245336)
		(mid 98.114745 -268.321171)
		(end 98.391218 -268.253972)
		(width 0.0889)
		(layer "B.Cu")
		(net "NC_CPU1_MDFI_DIE01_EW0")
	)
	(arc
		(start 91.261946 -268.245336)
		(mid 91.536145 -268.321171)
		(end 91.812618 -268.253972)
		(width 0.0889)
		(layer "B.Cu")
		(net "NC_CPU1_MDFI_DIE01_EW0")
	)
	(arc
		(start 89.94775 -268.245336)
		(mid 90.134948 -268.195193)
		(end 90.322146 -268.245336)
		(width 0.0889)
		(layer "B.Cu")
		(net "NC_CPU1_MDFI_DIE01_EW0")
	)
	(arc
		(start 99.346004 -268.245336)
		(mid 99.533202 -268.195193)
		(end 99.7204 -268.245336)
		(width 0.0889)
		(layer "B.Cu")
		(net "NC_CPU1_MDFI_DIE01_EW0")
	)
	(arc
		(start 94.64675 -268.245336)
		(mid 94.833948 -268.195193)
		(end 95.021146 -268.245336)
		(width 0.0889)
		(layer "B.Cu")
		(net "NC_CPU1_MDFI_DIE01_EW0")
	)
	(arc
		(start 93.1418 -268.245336)
		(mid 93.418359 -268.321079)
		(end 93.696536 -268.251432)
		(width 0.0889)
		(layer "B.Cu")
		(net "NC_CPU1_MDFI_DIE01_EW0")
	)
	(arc
		(start 101.22535 -268.245336)
		(mid 101.412548 -268.195193)
		(end 101.599746 -268.245336)
		(width 0.0889)
		(layer "B.Cu")
		(net "NC_CPU1_MDFI_DIE01_EW0")
	)
	(arc
		(start 89.00795 -268.245336)
		(mid 89.195148 -268.195193)
		(end 89.382346 -268.245336)
		(width 0.0889)
		(layer "B.Cu")
		(net "NC_CPU1_MDFI_DIE01_EW0")
	)
	(arc
		(start 102.16515 -268.245336)
		(mid 102.323638 -268.196403)
		(end 102.48773 -268.220698)
		(width 0.0889)
		(layer "B.Cu")
		(net "NC_CPU1_MDFI_DIE01_EW0")
	)
	(arc
		(start 91.82735 -268.245336)
		(mid 92.014548 -268.195193)
		(end 92.201746 -268.245336)
		(width 0.0889)
		(layer "B.Cu")
		(net "NC_CPU1_MDFI_DIE01_EW0")
	)
	(arc
		(start 90.88755 -268.245336)
		(mid 91.074748 -268.195193)
		(end 91.261946 -268.245336)
		(width 0.0889)
		(layer "B.Cu")
		(net "NC_CPU1_MDFI_DIE01_EW0")
	)
	(arc
		(start 88.294718 -268.19733)
		(mid 88.371158 -268.21356)
		(end 88.442546 -268.245336)
		(width 0.0889)
		(layer "B.Cu")
		(net "NC_CPU1_MDFI_DIE01_EW0")
	)
	(arc
		(start 98.780346 -268.245336)
		(mid 99.057159 -268.321206)
		(end 99.33559 -268.251432)
		(width 0.0889)
		(layer "B.Cu")
		(net "NC_CPU1_MDFI_DIE01_EW0")
	)
	(arc
		(start 100.285804 -268.245336)
		(mid 100.473002 -268.195193)
		(end 100.6602 -268.245336)
		(width 0.0889)
		(layer "B.Cu")
		(net "NC_CPU1_MDFI_DIE01_EW0")
	)
	(arc
		(start 97.46615 -268.245336)
		(mid 97.653348 -268.195193)
		(end 97.840546 -268.245336)
		(width 0.0889)
		(layer "B.Cu")
		(net "NC_CPU1_MDFI_DIE01_EW0")
	)
	(arc
		(start 90.322146 -268.245336)
		(mid 90.604848 -268.321112)
		(end 90.88755 -268.245336)
		(width 0.0889)
		(layer "B.Cu")
		(net "NC_CPU1_MDFI_DIE01_EW0")
	)
	(arc
		(start 89.382346 -268.245336)
		(mid 89.656545 -268.321171)
		(end 89.933018 -268.253972)
		(width 0.0889)
		(layer "B.Cu")
		(net "NC_CPU1_MDFI_DIE01_EW0")
	)
	(arc
		(start 101.599746 -268.245336)
		(mid 101.873945 -268.321171)
		(end 102.150418 -268.253972)
		(width 0.0889)
		(layer "B.Cu")
		(net "NC_CPU1_MDFI_DIE01_EW0")
	)
	(arc
		(start 95.021146 -268.245336)
		(mid 95.295345 -268.321171)
		(end 95.571818 -268.253972)
		(width 0.0889)
		(layer "B.Cu")
		(net "NC_CPU1_MDFI_DIE01_EW0")
	)
	(arc
		(start 96.900746 -268.245336)
		(mid 97.183448 -268.321112)
		(end 97.46615 -268.245336)
		(width 0.0889)
		(layer "B.Cu")
		(net "NC_CPU1_MDFI_DIE01_EW0")
	)
	(arc
		(start 95.58655 -268.245336)
		(mid 95.773748 -268.195193)
		(end 95.960946 -268.245336)
		(width 0.0889)
		(layer "B.Cu")
		(net "NC_CPU1_MDFI_DIE01_EW0")
	)
	(arc
		(start 92.767404 -268.245336)
		(mid 92.954602 -268.195193)
		(end 93.1418 -268.245336)
		(width 0.0889)
		(layer "B.Cu")
		(net "NC_CPU1_MDFI_DIE01_EW0")
	)
	(arc
		(start 95.960946 -268.245336)
		(mid 96.235145 -268.321171)
		(end 96.511618 -268.253972)
		(width 0.0889)
		(layer "B.Cu")
		(net "NC_CPU1_MDFI_DIE01_EW0")
	)
	(arc
		(start 96.52635 -268.245336)
		(mid 96.713548 -268.195193)
		(end 96.900746 -268.245336)
		(width 0.0889)
		(layer "B.Cu")
		(net "NC_CPU1_MDFI_DIE01_EW0")
	)
	(arc
		(start 93.70695 -268.245336)
		(mid 93.894148 -268.195193)
		(end 94.081346 -268.245336)
		(width 0.0889)
		(layer "B.Cu")
		(net "NC_CPU1_MDFI_DIE01_EW0")
	)
	(arc
		(start 100.6602 -268.245336)
		(mid 100.936759 -268.321079)
		(end 101.214936 -268.251432)
		(width 0.0889)
		(layer "B.Cu")
		(net "NC_CPU1_MDFI_DIE01_EW0")
	)
	(segment
		(start 107.411266 -230.622602)
		(end 107.411266 -230.086916)
		(width 0.12954)
		(layer "F.Cu")
		(net "NC_CPU1_MDFI_DIE00_NS1")
	)
	(segment
		(start 107.411266 -230.086916)
		(end 107.411012 -230.086662)
		(width 0.12954)
		(layer "F.Cu")
		(net "NC_CPU1_MDFI_DIE00_NS1")
	)
	(via
		(at 107.411012 -230.086662)
		(size 0.4572)
		(drill 0.2032)
		(layers "F.Cu" "B.Cu")
		(net "NC_CPU1_MDFI_DIE00_NS1")
	)
	(segment
		(start 107.880912 -230.900478)
		(end 107.880912 -231.436418)
		(width 0.12954)
		(layer "F.Cu")
		(net "NC_CPU1_MDFI_DIE00_NS0")
	)
	(via
		(at 107.880912 -230.900478)
		(size 0.4572)
		(drill 0.2032)
		(layers "F.Cu" "B.Cu")
		(net "NC_CPU1_MDFI_DIE00_NS0")
	)
	(segment
		(start 110.230412 -230.086662)
		(end 110.230412 -230.622348)
		(width 0.12954)
		(layer "F.Cu")
		(net "NC_CPU1_MDFI_DIE00_EW1")
	)
	(segment
		(start 110.230412 -230.622348)
		(end 110.230666 -230.622602)
		(width 0.12954)
		(layer "F.Cu")
		(net "NC_CPU1_MDFI_DIE00_EW1")
	)
	(via
		(at 110.230412 -230.086662)
		(size 0.4572)
		(drill 0.2032)
		(layers "F.Cu" "B.Cu")
		(net "NC_CPU1_MDFI_DIE00_EW1")
	)
	(segment
		(start 109.760512 -230.900478)
		(end 109.760512 -231.436418)
		(width 0.12954)
		(layer "F.Cu")
		(net "NC_CPU1_MDFI_DIE00_EW0")
	)
	(via
		(at 109.760512 -230.900478)
		(size 0.4572)
		(drill 0.2032)
		(layers "F.Cu" "B.Cu")
		(net "NC_CPU1_MDFI_DIE00_EW0")
	)
	(segment
		(start 119.268748 -264.77849)
		(end 119.268748 -265.314176)
		(width 0.12954)
		(layer "F.Cu")
		(net "NC_CPU1_LGSSPARE5")
	)
	(segment
		(start 119.268494 -264.778236)
		(end 119.268748 -264.77849)
		(width 0.12954)
		(layer "F.Cu")
		(net "NC_CPU1_LGSSPARE5")
	)
	(via
		(at 138.524234 -264.635234)
		(size 0.6604)
		(drill 0.3302)
		(layers "F.Cu" "B.Cu")
		(net "NC_CPU1_LGSSPARE5")
	)
	(via
		(at 119.268748 -265.314176)
		(size 0.4572)
		(drill 0.2032)
		(layers "F.Cu" "B.Cu")
		(net "NC_CPU1_LGSSPARE5")
	)
	(segment
		(start 127.994664 -264.816082)
		(end 128.009396 -264.824718)
		(width 0.0889)
		(layer "B.Cu")
		(net "NC_CPU1_LGSSPARE5")
	)
	(segment
		(start 120.476264 -264.816082)
		(end 120.490996 -264.824718)
		(width 0.0889)
		(layer "B.Cu")
		(net "NC_CPU1_LGSSPARE5")
	)
	(segment
		(start 132.698236 -264.818622)
		(end 132.70865 -264.824718)
		(width 0.0889)
		(layer "B.Cu")
		(net "NC_CPU1_LGSSPARE5")
	)
	(segment
		(start 136.883902 -264.76071)
		(end 137.947654 -264.76071)
		(width 0.0889)
		(layer "B.Cu")
		(net "NC_CPU1_LGSSPARE5")
	)
	(segment
		(start 135.714994 -264.875264)
		(end 136.769348 -264.875264)
		(width 0.0889)
		(layer "B.Cu")
		(net "NC_CPU1_LGSSPARE5")
	)
	(segment
		(start 126.119636 -264.818622)
		(end 126.13005 -264.824718)
		(width 0.0889)
		(layer "B.Cu")
		(net "NC_CPU1_LGSSPARE5")
	)
	(segment
		(start 131.753864 -264.816082)
		(end 131.768596 -264.824718)
		(width 0.0889)
		(layer "B.Cu")
		(net "NC_CPU1_LGSSPARE5")
	)
	(segment
		(start 130.814064 -264.816082)
		(end 130.828796 -264.824718)
		(width 0.0889)
		(layer "B.Cu")
		(net "NC_CPU1_LGSSPARE5")
	)
	(segment
		(start 119.542814 -265.377676)
		(end 119.643398 -265.314176)
		(width 0.0889)
		(layer "B.Cu")
		(net "NC_CPU1_LGSSPARE5")
	)
	(segment
		(start 136.769348 -264.875264)
		(end 136.883902 -264.76071)
		(width 0.0889)
		(layer "B.Cu")
		(net "NC_CPU1_LGSSPARE5")
	)
	(segment
		(start 128.934464 -264.816082)
		(end 128.949196 -264.824718)
		(width 0.0889)
		(layer "B.Cu")
		(net "NC_CPU1_LGSSPARE5")
	)
	(segment
		(start 134.573264 -264.816082)
		(end 134.587996 -264.824718)
		(width 0.0889)
		(layer "B.Cu")
		(net "NC_CPU1_LGSSPARE5")
	)
	(segment
		(start 124.235464 -264.816082)
		(end 124.250196 -264.824718)
		(width 0.0889)
		(layer "B.Cu")
		(net "NC_CPU1_LGSSPARE5")
	)
	(segment
		(start 123.295664 -264.816082)
		(end 123.310396 -264.824718)
		(width 0.0889)
		(layer "B.Cu")
		(net "NC_CPU1_LGSSPARE5")
	)
	(segment
		(start 137.947654 -264.76071)
		(end 138.398758 -264.76071)
		(width 0.12954)
		(layer "B.Cu")
		(net "NC_CPU1_LGSSPARE5")
	)
	(segment
		(start 121.416064 -264.816082)
		(end 121.430796 -264.824718)
		(width 0.0889)
		(layer "B.Cu")
		(net "NC_CPU1_LGSSPARE5")
	)
	(segment
		(start 119.643398 -265.314176)
		(end 119.643398 -265.313668)
		(width 0.0889)
		(layer "B.Cu")
		(net "NC_CPU1_LGSSPARE5")
	)
	(segment
		(start 125.175264 -264.816082)
		(end 125.189996 -264.824718)
		(width 0.0889)
		(layer "B.Cu")
		(net "NC_CPU1_LGSSPARE5")
	)
	(segment
		(start 121.453656 -264.83818)
		(end 121.482612 -264.849356)
		(width 0.0889)
		(layer "B.Cu")
		(net "NC_CPU1_LGSSPARE5")
	)
	(segment
		(start 133.083046 -264.824718)
		(end 133.09346 -264.818622)
		(width 0.0889)
		(layer "B.Cu")
		(net "NC_CPU1_LGSSPARE5")
	)
	(segment
		(start 119.268748 -265.314176)
		(end 119.542814 -265.377676)
		(width 0.0889)
		(layer "B.Cu")
		(net "NC_CPU1_LGSSPARE5")
	)
	(segment
		(start 126.504446 -264.824718)
		(end 126.51486 -264.818622)
		(width 0.0889)
		(layer "B.Cu")
		(net "NC_CPU1_LGSSPARE5")
	)
	(segment
		(start 129.874264 -264.816082)
		(end 129.888996 -264.824718)
		(width 0.0889)
		(layer "B.Cu")
		(net "NC_CPU1_LGSSPARE5")
	)
	(segment
		(start 121.430796 -264.824718)
		(end 121.453656 -264.83818)
		(width 0.0889)
		(layer "B.Cu")
		(net "NC_CPU1_LGSSPARE5")
	)
	(segment
		(start 138.398758 -264.76071)
		(end 138.524234 -264.635234)
		(width 0.12954)
		(layer "B.Cu")
		(net "NC_CPU1_LGSSPARE5")
	)
	(segment
		(start 122.355864 -264.816082)
		(end 122.370596 -264.824718)
		(width 0.0889)
		(layer "B.Cu")
		(net "NC_CPU1_LGSSPARE5")
	)
	(segment
		(start 135.513064 -264.816082)
		(end 135.527796 -264.824718)
		(width 0.0889)
		(layer "B.Cu")
		(net "NC_CPU1_LGSSPARE5")
	)
	(arc
		(start 131.768596 -264.824718)
		(mid 131.955794 -264.874861)
		(end 132.142992 -264.824718)
		(width 0.0889)
		(layer "B.Cu")
		(net "NC_CPU1_LGSSPARE5")
	)
	(arc
		(start 120.490996 -264.824718)
		(mid 120.678194 -264.874861)
		(end 120.865392 -264.824718)
		(width 0.0889)
		(layer "B.Cu")
		(net "NC_CPU1_LGSSPARE5")
	)
	(arc
		(start 124.250196 -264.824718)
		(mid 124.437394 -264.874861)
		(end 124.624592 -264.824718)
		(width 0.0889)
		(layer "B.Cu")
		(net "NC_CPU1_LGSSPARE5")
	)
	(arc
		(start 126.51486 -264.818622)
		(mid 126.793038 -264.748899)
		(end 127.069596 -264.824718)
		(width 0.0889)
		(layer "B.Cu")
		(net "NC_CPU1_LGSSPARE5")
	)
	(arc
		(start 127.069596 -264.824718)
		(mid 127.256794 -264.874861)
		(end 127.443992 -264.824718)
		(width 0.0889)
		(layer "B.Cu")
		(net "NC_CPU1_LGSSPARE5")
	)
	(arc
		(start 133.09346 -264.818622)
		(mid 133.371638 -264.748899)
		(end 133.648196 -264.824718)
		(width 0.0889)
		(layer "B.Cu")
		(net "NC_CPU1_LGSSPARE5")
	)
	(arc
		(start 119.643398 -265.313668)
		(mid 119.719013 -265.031404)
		(end 119.925592 -264.824718)
		(width 0.0889)
		(layer "B.Cu")
		(net "NC_CPU1_LGSSPARE5")
	)
	(arc
		(start 128.383792 -264.824718)
		(mid 128.657991 -264.748883)
		(end 128.934464 -264.816082)
		(width 0.0889)
		(layer "B.Cu")
		(net "NC_CPU1_LGSSPARE5")
	)
	(arc
		(start 129.888996 -264.824718)
		(mid 130.076194 -264.874861)
		(end 130.263392 -264.824718)
		(width 0.0889)
		(layer "B.Cu")
		(net "NC_CPU1_LGSSPARE5")
	)
	(arc
		(start 127.443992 -264.824718)
		(mid 127.718191 -264.748883)
		(end 127.994664 -264.816082)
		(width 0.0889)
		(layer "B.Cu")
		(net "NC_CPU1_LGSSPARE5")
	)
	(arc
		(start 130.828796 -264.824718)
		(mid 131.015994 -264.874861)
		(end 131.203192 -264.824718)
		(width 0.0889)
		(layer "B.Cu")
		(net "NC_CPU1_LGSSPARE5")
	)
	(arc
		(start 134.022592 -264.824718)
		(mid 134.296791 -264.748883)
		(end 134.573264 -264.816082)
		(width 0.0889)
		(layer "B.Cu")
		(net "NC_CPU1_LGSSPARE5")
	)
	(arc
		(start 134.587996 -264.824718)
		(mid 134.775194 -264.874861)
		(end 134.962392 -264.824718)
		(width 0.0889)
		(layer "B.Cu")
		(net "NC_CPU1_LGSSPARE5")
	)
	(arc
		(start 125.189996 -264.824718)
		(mid 125.377194 -264.874861)
		(end 125.564392 -264.824718)
		(width 0.0889)
		(layer "B.Cu")
		(net "NC_CPU1_LGSSPARE5")
	)
	(arc
		(start 122.370596 -264.824718)
		(mid 122.557794 -264.874861)
		(end 122.744992 -264.824718)
		(width 0.0889)
		(layer "B.Cu")
		(net "NC_CPU1_LGSSPARE5")
	)
	(arc
		(start 126.13005 -264.824718)
		(mid 126.317248 -264.874861)
		(end 126.504446 -264.824718)
		(width 0.0889)
		(layer "B.Cu")
		(net "NC_CPU1_LGSSPARE5")
	)
	(arc
		(start 131.203192 -264.824718)
		(mid 131.477391 -264.748883)
		(end 131.753864 -264.816082)
		(width 0.0889)
		(layer "B.Cu")
		(net "NC_CPU1_LGSSPARE5")
	)
	(arc
		(start 133.648196 -264.824718)
		(mid 133.835394 -264.874861)
		(end 134.022592 -264.824718)
		(width 0.0889)
		(layer "B.Cu")
		(net "NC_CPU1_LGSSPARE5")
	)
	(arc
		(start 129.323592 -264.824718)
		(mid 129.597791 -264.748883)
		(end 129.874264 -264.816082)
		(width 0.0889)
		(layer "B.Cu")
		(net "NC_CPU1_LGSSPARE5")
	)
	(arc
		(start 124.624592 -264.824718)
		(mid 124.898791 -264.748883)
		(end 125.175264 -264.816082)
		(width 0.0889)
		(layer "B.Cu")
		(net "NC_CPU1_LGSSPARE5")
	)
	(arc
		(start 120.865392 -264.824718)
		(mid 121.139591 -264.748883)
		(end 121.416064 -264.816082)
		(width 0.0889)
		(layer "B.Cu")
		(net "NC_CPU1_LGSSPARE5")
	)
	(arc
		(start 121.805192 -264.824718)
		(mid 122.079391 -264.748883)
		(end 122.355864 -264.816082)
		(width 0.0889)
		(layer "B.Cu")
		(net "NC_CPU1_LGSSPARE5")
	)
	(arc
		(start 128.949196 -264.824718)
		(mid 129.136394 -264.874861)
		(end 129.323592 -264.824718)
		(width 0.0889)
		(layer "B.Cu")
		(net "NC_CPU1_LGSSPARE5")
	)
	(arc
		(start 125.564392 -264.824718)
		(mid 125.841205 -264.748848)
		(end 126.119636 -264.818622)
		(width 0.0889)
		(layer "B.Cu")
		(net "NC_CPU1_LGSSPARE5")
	)
	(arc
		(start 122.744992 -264.824718)
		(mid 123.019191 -264.748883)
		(end 123.295664 -264.816082)
		(width 0.0889)
		(layer "B.Cu")
		(net "NC_CPU1_LGSSPARE5")
	)
	(arc
		(start 132.70865 -264.824718)
		(mid 132.895848 -264.874861)
		(end 133.083046 -264.824718)
		(width 0.0889)
		(layer "B.Cu")
		(net "NC_CPU1_LGSSPARE5")
	)
	(arc
		(start 135.527796 -264.824718)
		(mid 135.618068 -264.862317)
		(end 135.714994 -264.875264)
		(width 0.0889)
		(layer "B.Cu")
		(net "NC_CPU1_LGSSPARE5")
	)
	(arc
		(start 119.925592 -264.824718)
		(mid 120.199791 -264.748883)
		(end 120.476264 -264.816082)
		(width 0.0889)
		(layer "B.Cu")
		(net "NC_CPU1_LGSSPARE5")
	)
	(arc
		(start 128.009396 -264.824718)
		(mid 128.196594 -264.874861)
		(end 128.383792 -264.824718)
		(width 0.0889)
		(layer "B.Cu")
		(net "NC_CPU1_LGSSPARE5")
	)
	(arc
		(start 130.263392 -264.824718)
		(mid 130.537591 -264.748883)
		(end 130.814064 -264.816082)
		(width 0.0889)
		(layer "B.Cu")
		(net "NC_CPU1_LGSSPARE5")
	)
	(arc
		(start 132.142992 -264.824718)
		(mid 132.419805 -264.748848)
		(end 132.698236 -264.818622)
		(width 0.0889)
		(layer "B.Cu")
		(net "NC_CPU1_LGSSPARE5")
	)
	(arc
		(start 134.962392 -264.824718)
		(mid 135.236591 -264.748883)
		(end 135.513064 -264.816082)
		(width 0.0889)
		(layer "B.Cu")
		(net "NC_CPU1_LGSSPARE5")
	)
	(arc
		(start 121.482612 -264.849356)
		(mid 121.646708 -264.873703)
		(end 121.805192 -264.824718)
		(width 0.0889)
		(layer "B.Cu")
		(net "NC_CPU1_LGSSPARE5")
	)
	(arc
		(start 123.684792 -264.824718)
		(mid 123.958991 -264.748883)
		(end 124.235464 -264.816082)
		(width 0.0889)
		(layer "B.Cu")
		(net "NC_CPU1_LGSSPARE5")
	)
	(arc
		(start 123.310396 -264.824718)
		(mid 123.497594 -264.874861)
		(end 123.684792 -264.824718)
		(width 0.0889)
		(layer "B.Cu")
		(net "NC_CPU1_LGSSPARE5")
	)
	(segment
		(start 114.099848 -267.219938)
		(end 114.099594 -267.755878)
		(width 0.12954)
		(layer "F.Cu")
		(net "NC_CPU1_LGSSPARE4")
	)
	(via
		(at 114.099594 -267.755878)
		(size 0.4572)
		(drill 0.2032)
		(layers "F.Cu" "B.Cu")
		(net "NC_CPU1_LGSSPARE4")
	)
	(segment
		(start 115.039648 -266.127992)
		(end 115.039394 -266.128246)
		(width 0.12954)
		(layer "F.Cu")
		(net "NC_CPU1_LGSSPARE3")
	)
	(segment
		(start 115.039648 -265.592306)
		(end 115.039648 -266.127992)
		(width 0.12954)
		(layer "F.Cu")
		(net "NC_CPU1_LGSSPARE3")
	)
	(via
		(at 115.039394 -266.128246)
		(size 0.4572)
		(drill 0.2032)
		(layers "F.Cu" "B.Cu")
		(net "NC_CPU1_LGSSPARE3")
	)
	(segment
		(start 120.678194 -266.128246)
		(end 120.678194 -265.592306)
		(width 0.12954)
		(layer "F.Cu")
		(net "NC_CPU1_LGSSPARE2")
	)
	(segment
		(start 120.678194 -265.592306)
		(end 120.678448 -265.592306)
		(width 0.12954)
		(layer "F.Cu")
		(net "NC_CPU1_LGSSPARE2")
	)
	(via
		(at 120.678194 -266.128246)
		(size 0.4572)
		(drill 0.2032)
		(layers "F.Cu" "B.Cu")
		(net "NC_CPU1_LGSSPARE2")
	)
	(segment
		(start 118.798594 -263.964674)
		(end 118.798594 -264.50036)
		(width 0.12954)
		(layer "F.Cu")
		(net "NC_CPU1_LGSSPARE1")
	)
	(segment
		(start 118.798848 -263.96442)
		(end 118.798594 -263.964674)
		(width 0.12954)
		(layer "F.Cu")
		(net "NC_CPU1_LGSSPARE1")
	)
	(via
		(at 118.798594 -264.50036)
		(size 0.4572)
		(drill 0.2032)
		(layers "F.Cu" "B.Cu")
		(net "NC_CPU1_LGSSPARE1")
	)
	(segment
		(start 119.738394 -263.964674)
		(end 119.738648 -263.96442)
		(width 0.12954)
		(layer "F.Cu")
		(net "NC_CPU1_LGSSPARE0")
	)
	(segment
		(start 119.738394 -264.50036)
		(end 119.738394 -263.964674)
		(width 0.12954)
		(layer "F.Cu")
		(net "NC_CPU1_LGSSPARE0")
	)
	(via
		(at 119.738394 -264.50036)
		(size 0.4572)
		(drill 0.2032)
		(layers "F.Cu" "B.Cu")
		(net "NC_CPU1_LGSSPARE0")
	)
	(segment
		(start 108.461302 -264.500106)
		(end 108.461302 -263.964674)
		(width 0.12954)
		(layer "F.Cu")
		(net "NC_CPU1_HBM3_VIEWDIG1")
	)
	(segment
		(start 108.461048 -264.50036)
		(end 108.461302 -264.500106)
		(width 0.12954)
		(layer "F.Cu")
		(net "NC_CPU1_HBM3_VIEWDIG1")
	)
	(segment
		(start 108.461302 -263.964674)
		(end 108.461048 -263.96442)
		(width 0.12954)
		(layer "F.Cu")
		(net "NC_CPU1_HBM3_VIEWDIG1")
	)
	(via
		(at 108.461048 -264.50036)
		(size 0.4572)
		(drill 0.2032)
		(layers "F.Cu" "B.Cu")
		(net "NC_CPU1_HBM3_VIEWDIG1")
	)
	(segment
		(start 106.581448 -279.150318)
		(end 106.581448 -278.614378)
		(width 0.12954)
		(layer "F.Cu")
		(net "NC_CPU1_HBM3_VIEWDIG0")
	)
	(via
		(at 106.581448 -279.150318)
		(size 0.4572)
		(drill 0.2032)
		(layers "F.Cu" "B.Cu")
		(net "NC_CPU1_HBM3_VIEWDIG0")
	)
	(segment
		(start 95.303594 -279.150318)
		(end 95.303594 -278.614632)
		(width 0.12954)
		(layer "F.Cu")
		(net "NC_CPU1_HBM2_VIEWDIG0")
	)
	(segment
		(start 95.303594 -278.614632)
		(end 95.303848 -278.614378)
		(width 0.12954)
		(layer "F.Cu")
		(net "NC_CPU1_HBM2_VIEWDIG0")
	)
	(via
		(at 95.303594 -279.150318)
		(size 0.4572)
		(drill 0.2032)
		(layers "F.Cu" "B.Cu")
		(net "NC_CPU1_HBM2_VIEWDIG0")
	)
	(segment
		(start 121.508266 -246.900446)
		(end 121.508266 -246.364506)
		(width 0.12954)
		(layer "F.Cu")
		(net "NC_CPU1_HBM1_VIEWDIG1")
	)
	(via
		(at 121.508266 -246.364506)
		(size 0.4572)
		(drill 0.2032)
		(layers "F.Cu" "B.Cu")
		(net "NC_CPU1_HBM1_VIEWDIG1")
	)
	(segment
		(start 93.314266 -227.367084)
		(end 93.314266 -226.831144)
		(width 0.12954)
		(layer "F.Cu")
		(net "NC_CPU1_HBM1_VIEWDIG0")
	)
	(via
		(at 93.314266 -226.831144)
		(size 0.4572)
		(drill 0.2032)
		(layers "F.Cu" "B.Cu")
		(net "NC_CPU1_HBM1_VIEWDIG0")
	)
	(segment
		(start 134.665466 -226.831398)
		(end 134.665466 -227.367084)
		(width 0.12954)
		(layer "F.Cu")
		(net "NC_CPU1_HBM0_VIEWDIG1")
	)
	(segment
		(start 134.665212 -226.831144)
		(end 134.665466 -226.831398)
		(width 0.12954)
		(layer "F.Cu")
		(net "NC_CPU1_HBM0_VIEWDIG1")
	)
	(via
		(at 134.665212 -226.831144)
		(size 0.4572)
		(drill 0.2032)
		(layers "F.Cu" "B.Cu")
		(net "NC_CPU1_HBM0_VIEWDIG1")
	)
	(segment
		(start 92.374466 -227.367084)
		(end 92.374466 -226.831144)
		(width 0.12954)
		(layer "F.Cu")
		(net "NC_CPU1_HBM0_VIEWDIG0")
	)
	(via
		(at 92.374466 -226.831144)
		(size 0.4572)
		(drill 0.2032)
		(layers "F.Cu" "B.Cu")
		(net "NC_CPU1_HBM0_VIEWDIG0")
	)
	(segment
		(start 112.110266 -230.622602)
		(end 112.110012 -230.622348)
		(width 0.12954)
		(layer "F.Cu")
		(net "NC_CPU1_DMI_APROBE<1>")
	)
	(segment
		(start 112.110012 -230.622348)
		(end 112.110012 -230.086916)
		(width 0.12954)
		(layer "F.Cu")
		(net "NC_CPU1_DMI_APROBE<1>")
	)
	(segment
		(start 112.110012 -230.086916)
		(end 112.110266 -230.086662)
		(width 0.12954)
		(layer "F.Cu")
		(net "NC_CPU1_DMI_APROBE<1>")
	)
	(via
		(at 112.110266 -230.086662)
		(size 0.4572)
		(drill 0.2032)
		(layers "F.Cu" "B.Cu")
		(net "NC_CPU1_DMI_APROBE<1>")
	)
	(segment
		(start 113.050066 -230.086662)
		(end 113.049812 -230.086916)
		(width 0.12954)
		(layer "F.Cu")
		(net "NC_CPU1_DMI_APROBE<0>")
	)
	(segment
		(start 113.049812 -230.086916)
		(end 113.049812 -230.622348)
		(width 0.12954)
		(layer "F.Cu")
		(net "NC_CPU1_DMI_APROBE<0>")
	)
	(segment
		(start 113.049812 -230.622348)
		(end 113.050066 -230.622602)
		(width 0.12954)
		(layer "F.Cu")
		(net "NC_CPU1_DMI_APROBE<0>")
	)
	(via
		(at 113.050066 -230.086662)
		(size 0.4572)
		(drill 0.2032)
		(layers "F.Cu" "B.Cu")
		(net "NC_CPU1_DMI_APROBE<0>")
	)
	(segment
		(start 122.447812 -249.620024)
		(end 122.448066 -249.620278)
		(width 0.2032)
		(layer "F.Cu")
		(net "NC_CPU1_DDR67_VIEWDIG0")
	)
	(segment
		(start 122.448066 -249.620278)
		(end 122.448066 -250.155964)
		(width 0.2032)
		(layer "F.Cu")
		(net "NC_CPU1_DDR67_VIEWDIG0")
	)
	(via
		(at 122.447812 -249.620024)
		(size 0.4572)
		(drill 0.2032)
		(layers "F.Cu" "B.Cu")
		(net "NC_CPU1_DDR67_VIEWDIG0")
	)
	(segment
		(start 121.977912 -243.922804)
		(end 121.977912 -244.458744)
		(width 0.114554)
		(layer "F.Cu")
		(net "NC_CPU1_DDR45_VIEWDIG1")
	)
	(via
		(at 121.977912 -243.922804)
		(size 0.4572)
		(drill 0.2032)
		(layers "F.Cu" "B.Cu")
		(net "NC_CPU1_DDR45_VIEWDIG1")
	)
	(segment
		(start 121.977912 -233.064304)
		(end 121.978166 -233.06405)
		(width 0.129794)
		(layer "F.Cu")
		(net "NC_CPU1_DDR45_VIEWDIG0")
	)
	(segment
		(start 121.978166 -233.06405)
		(end 121.978166 -232.528364)
		(width 0.129794)
		(layer "F.Cu")
		(net "NC_CPU1_DDR45_VIEWDIG0")
	)
	(via
		(at 121.978166 -232.528364)
		(size 0.4572)
		(drill 0.2032)
		(layers "F.Cu" "B.Cu")
		(net "NC_CPU1_DDR45_VIEWDIG0")
	)
	(segment
		(start 101.772466 -240.389156)
		(end 101.772466 -239.853216)
		(width 0.129794)
		(layer "F.Cu")
		(net "NC_CPU1_DDR23_VIEWDIG1")
	)
	(via
		(at 101.772466 -239.853216)
		(size 0.4572)
		(drill 0.2032)
		(layers "F.Cu" "B.Cu")
		(net "NC_CPU1_DDR23_VIEWDIG1")
	)
	(segment
		(start 102.242366 -239.575086)
		(end 102.242366 -239.0394)
		(width 0.129794)
		(layer "F.Cu")
		(net "NC_CPU1_DDR23_VIEWDIG0")
	)
	(segment
		(start 102.242112 -239.57534)
		(end 102.242366 -239.575086)
		(width 0.129794)
		(layer "F.Cu")
		(net "NC_CPU1_DDR23_VIEWDIG0")
	)
	(via
		(at 102.242366 -239.0394)
		(size 0.4572)
		(drill 0.2032)
		(layers "F.Cu" "B.Cu")
		(net "NC_CPU1_DDR23_VIEWDIG0")
	)
	(segment
		(start 101.882194 -261.244842)
		(end 101.882194 -260.709156)
		(width 0.114554)
		(layer "F.Cu")
		(net "NC_CPU1_DDR01_VIEWDIG1")
	)
	(segment
		(start 101.882194 -260.709156)
		(end 101.882448 -260.708902)
		(width 0.114554)
		(layer "F.Cu")
		(net "NC_CPU1_DDR01_VIEWDIG1")
	)
	(via
		(at 101.882194 -261.244842)
		(size 0.4572)
		(drill 0.2032)
		(layers "F.Cu" "B.Cu")
		(net "NC_CPU1_DDR01_VIEWDIG1")
	)
	(segment
		(start 370.028216 -261.522972)
		(end 370.028216 -262.058658)
		(width 0.12954)
		(layer "F.Cu")
		(net "NC_CPU0_VIEWPIN_GNR3")
	)
	(segment
		(start 370.027962 -261.522718)
		(end 370.028216 -261.522972)
		(width 0.12954)
		(layer "F.Cu")
		(net "NC_CPU0_VIEWPIN_GNR3")
	)
	(via
		(at 370.028216 -262.058658)
		(size 0.4572)
		(drill 0.2032)
		(layers "F.Cu" "B.Cu")
		(net "NC_CPU0_VIEWPIN_GNR3")
	)
	(via
		(at 385.00558 -261.152386)
		(size 0.6604)
		(drill 0.3302)
		(layers "F.Cu" "B.Cu")
		(net "NC_CPU0_VIEWPIN_GNR3")
	)
	(segment
		(start 376.794014 -261.7343)
		(end 376.808746 -261.742936)
		(width 0.0889)
		(layer "B.Cu")
		(net "NC_CPU0_VIEWPIN_GNR3")
	)
	(segment
		(start 384.546856 -261.152386)
		(end 385.00558 -261.152386)
		(width 0.12954)
		(layer "B.Cu")
		(net "NC_CPU0_VIEWPIN_GNR3")
	)
	(segment
		(start 375.854214 -261.7343)
		(end 375.868946 -261.742936)
		(width 0.0889)
		(layer "B.Cu")
		(net "NC_CPU0_VIEWPIN_GNR3")
	)
	(segment
		(start 370.215414 -261.7343)
		(end 370.225828 -261.740396)
		(width 0.0889)
		(layer "B.Cu")
		(net "NC_CPU0_VIEWPIN_GNR3")
	)
	(segment
		(start 379.613414 -261.7343)
		(end 379.623828 -261.740396)
		(width 0.0889)
		(layer "B.Cu")
		(net "NC_CPU0_VIEWPIN_GNR3")
	)
	(segment
		(start 374.914414 -261.7343)
		(end 374.929146 -261.742936)
		(width 0.0889)
		(layer "B.Cu")
		(net "NC_CPU0_VIEWPIN_GNR3")
	)
	(segment
		(start 378.673614 -261.7343)
		(end 378.688346 -261.742936)
		(width 0.0889)
		(layer "B.Cu")
		(net "NC_CPU0_VIEWPIN_GNR3")
	)
	(segment
		(start 373.034814 -261.7343)
		(end 373.045228 -261.740396)
		(width 0.0889)
		(layer "B.Cu")
		(net "NC_CPU0_VIEWPIN_GNR3")
	)
	(segment
		(start 370.028216 -262.058658)
		(end 369.871752 -261.78764)
		(width 0.0889)
		(layer "B.Cu")
		(net "NC_CPU0_VIEWPIN_GNR3")
	)
	(segment
		(start 384.054604 -261.645146)
		(end 384.546856 -261.152386)
		(width 0.0889)
		(layer "B.Cu")
		(net "NC_CPU0_VIEWPIN_GNR3")
	)
	(segment
		(start 380.55296 -261.7343)
		(end 380.563374 -261.740396)
		(width 0.0889)
		(layer "B.Cu")
		(net "NC_CPU0_VIEWPIN_GNR3")
	)
	(segment
		(start 381.493014 -261.7343)
		(end 381.507746 -261.742936)
		(width 0.0889)
		(layer "B.Cu")
		(net "NC_CPU0_VIEWPIN_GNR3")
	)
	(segment
		(start 372.095014 -261.7343)
		(end 372.109746 -261.742936)
		(width 0.0889)
		(layer "B.Cu")
		(net "NC_CPU0_VIEWPIN_GNR3")
	)
	(segment
		(start 371.15496 -261.7343)
		(end 371.165374 -261.740396)
		(width 0.0889)
		(layer "B.Cu")
		(net "NC_CPU0_VIEWPIN_GNR3")
	)
	(segment
		(start 373.97436 -261.7343)
		(end 373.984774 -261.740396)
		(width 0.0889)
		(layer "B.Cu")
		(net "NC_CPU0_VIEWPIN_GNR3")
	)
	(segment
		(start 377.733814 -261.7343)
		(end 377.748546 -261.742936)
		(width 0.0889)
		(layer "B.Cu")
		(net "NC_CPU0_VIEWPIN_GNR3")
	)
	(segment
		(start 382.432814 -261.7343)
		(end 382.443228 -261.740396)
		(width 0.0889)
		(layer "B.Cu")
		(net "NC_CPU0_VIEWPIN_GNR3")
	)
	(segment
		(start 369.871752 -261.78764)
		(end 369.892834 -261.709662)
		(width 0.0889)
		(layer "B.Cu")
		(net "NC_CPU0_VIEWPIN_GNR3")
	)
	(arc
		(start 377.359418 -261.7343)
		(mid 377.546616 -261.684157)
		(end 377.733814 -261.7343)
		(width 0.0889)
		(layer "B.Cu")
		(net "NC_CPU0_VIEWPIN_GNR3")
	)
	(arc
		(start 375.868946 -261.742936)
		(mid 376.145421 -261.810256)
		(end 376.419618 -261.7343)
		(width 0.0889)
		(layer "B.Cu")
		(net "NC_CPU0_VIEWPIN_GNR3")
	)
	(arc
		(start 382.443228 -261.740396)
		(mid 382.721406 -261.810119)
		(end 382.997964 -261.7343)
		(width 0.0889)
		(layer "B.Cu")
		(net "NC_CPU0_VIEWPIN_GNR3")
	)
	(arc
		(start 382.058418 -261.7343)
		(mid 382.245616 -261.684157)
		(end 382.432814 -261.7343)
		(width 0.0889)
		(layer "B.Cu")
		(net "NC_CPU0_VIEWPIN_GNR3")
	)
	(arc
		(start 381.507746 -261.742936)
		(mid 381.784221 -261.810256)
		(end 382.058418 -261.7343)
		(width 0.0889)
		(layer "B.Cu")
		(net "NC_CPU0_VIEWPIN_GNR3")
	)
	(arc
		(start 370.780564 -261.7343)
		(mid 370.967762 -261.684157)
		(end 371.15496 -261.7343)
		(width 0.0889)
		(layer "B.Cu")
		(net "NC_CPU0_VIEWPIN_GNR3")
	)
	(arc
		(start 377.748546 -261.742936)
		(mid 378.025021 -261.810256)
		(end 378.299218 -261.7343)
		(width 0.0889)
		(layer "B.Cu")
		(net "NC_CPU0_VIEWPIN_GNR3")
	)
	(arc
		(start 372.660418 -261.7343)
		(mid 372.847616 -261.684157)
		(end 373.034814 -261.7343)
		(width 0.0889)
		(layer "B.Cu")
		(net "NC_CPU0_VIEWPIN_GNR3")
	)
	(arc
		(start 380.563374 -261.740396)
		(mid 380.841806 -261.810242)
		(end 381.118618 -261.7343)
		(width 0.0889)
		(layer "B.Cu")
		(net "NC_CPU0_VIEWPIN_GNR3")
	)
	(arc
		(start 378.688346 -261.742936)
		(mid 378.964821 -261.810256)
		(end 379.239018 -261.7343)
		(width 0.0889)
		(layer "B.Cu")
		(net "NC_CPU0_VIEWPIN_GNR3")
	)
	(arc
		(start 384.001772 -261.691374)
		(mid 384.028908 -261.669082)
		(end 384.054604 -261.645146)
		(width 0.0889)
		(layer "B.Cu")
		(net "NC_CPU0_VIEWPIN_GNR3")
	)
	(arc
		(start 379.623828 -261.740396)
		(mid 379.902006 -261.810119)
		(end 380.178564 -261.7343)
		(width 0.0889)
		(layer "B.Cu")
		(net "NC_CPU0_VIEWPIN_GNR3")
	)
	(arc
		(start 382.997964 -261.7343)
		(mid 383.185162 -261.684157)
		(end 383.37236 -261.7343)
		(width 0.0889)
		(layer "B.Cu")
		(net "NC_CPU0_VIEWPIN_GNR3")
	)
	(arc
		(start 383.937764 -261.7343)
		(mid 383.9705 -261.713929)
		(end 384.001772 -261.691374)
		(width 0.0889)
		(layer "B.Cu")
		(net "NC_CPU0_VIEWPIN_GNR3")
	)
	(arc
		(start 374.929146 -261.742936)
		(mid 375.205621 -261.810256)
		(end 375.479818 -261.7343)
		(width 0.0889)
		(layer "B.Cu")
		(net "NC_CPU0_VIEWPIN_GNR3")
	)
	(arc
		(start 372.109746 -261.742936)
		(mid 372.386221 -261.810256)
		(end 372.660418 -261.7343)
		(width 0.0889)
		(layer "B.Cu")
		(net "NC_CPU0_VIEWPIN_GNR3")
	)
	(arc
		(start 369.892834 -261.709662)
		(mid 370.05693 -261.685315)
		(end 370.215414 -261.7343)
		(width 0.0889)
		(layer "B.Cu")
		(net "NC_CPU0_VIEWPIN_GNR3")
	)
	(arc
		(start 371.165374 -261.740396)
		(mid 371.443806 -261.810242)
		(end 371.720618 -261.7343)
		(width 0.0889)
		(layer "B.Cu")
		(net "NC_CPU0_VIEWPIN_GNR3")
	)
	(arc
		(start 375.479818 -261.7343)
		(mid 375.667016 -261.684157)
		(end 375.854214 -261.7343)
		(width 0.0889)
		(layer "B.Cu")
		(net "NC_CPU0_VIEWPIN_GNR3")
	)
	(arc
		(start 373.599964 -261.7343)
		(mid 373.787162 -261.684157)
		(end 373.97436 -261.7343)
		(width 0.0889)
		(layer "B.Cu")
		(net "NC_CPU0_VIEWPIN_GNR3")
	)
	(arc
		(start 380.178564 -261.7343)
		(mid 380.365762 -261.684157)
		(end 380.55296 -261.7343)
		(width 0.0889)
		(layer "B.Cu")
		(net "NC_CPU0_VIEWPIN_GNR3")
	)
	(arc
		(start 378.299218 -261.7343)
		(mid 378.486416 -261.684157)
		(end 378.673614 -261.7343)
		(width 0.0889)
		(layer "B.Cu")
		(net "NC_CPU0_VIEWPIN_GNR3")
	)
	(arc
		(start 373.984774 -261.740396)
		(mid 374.263206 -261.810242)
		(end 374.540018 -261.7343)
		(width 0.0889)
		(layer "B.Cu")
		(net "NC_CPU0_VIEWPIN_GNR3")
	)
	(arc
		(start 381.118618 -261.7343)
		(mid 381.305816 -261.684157)
		(end 381.493014 -261.7343)
		(width 0.0889)
		(layer "B.Cu")
		(net "NC_CPU0_VIEWPIN_GNR3")
	)
	(arc
		(start 373.045228 -261.740396)
		(mid 373.323406 -261.810119)
		(end 373.599964 -261.7343)
		(width 0.0889)
		(layer "B.Cu")
		(net "NC_CPU0_VIEWPIN_GNR3")
	)
	(arc
		(start 379.239018 -261.7343)
		(mid 379.426216 -261.684157)
		(end 379.613414 -261.7343)
		(width 0.0889)
		(layer "B.Cu")
		(net "NC_CPU0_VIEWPIN_GNR3")
	)
	(arc
		(start 371.720618 -261.7343)
		(mid 371.907816 -261.684157)
		(end 372.095014 -261.7343)
		(width 0.0889)
		(layer "B.Cu")
		(net "NC_CPU0_VIEWPIN_GNR3")
	)
	(arc
		(start 383.37236 -261.7343)
		(mid 383.655062 -261.810076)
		(end 383.937764 -261.7343)
		(width 0.0889)
		(layer "B.Cu")
		(net "NC_CPU0_VIEWPIN_GNR3")
	)
	(arc
		(start 374.540018 -261.7343)
		(mid 374.727216 -261.684157)
		(end 374.914414 -261.7343)
		(width 0.0889)
		(layer "B.Cu")
		(net "NC_CPU0_VIEWPIN_GNR3")
	)
	(arc
		(start 370.225828 -261.740396)
		(mid 370.504006 -261.810119)
		(end 370.780564 -261.7343)
		(width 0.0889)
		(layer "B.Cu")
		(net "NC_CPU0_VIEWPIN_GNR3")
	)
	(arc
		(start 376.808746 -261.742936)
		(mid 377.085221 -261.810256)
		(end 377.359418 -261.7343)
		(width 0.0889)
		(layer "B.Cu")
		(net "NC_CPU0_VIEWPIN_GNR3")
	)
	(arc
		(start 376.419618 -261.7343)
		(mid 376.606816 -261.684157)
		(end 376.794014 -261.7343)
		(width 0.0889)
		(layer "B.Cu")
		(net "NC_CPU0_VIEWPIN_GNR3")
	)
	(segment
		(start 367.568734 -233.87812)
		(end 367.56848 -233.877866)
		(width 0.12954)
		(layer "F.Cu")
		(net "NC_CPU0_VIEWPIN_GNR2")
	)
	(segment
		(start 367.56848 -233.877866)
		(end 367.56848 -233.34218)
		(width 0.12954)
		(layer "F.Cu")
		(net "NC_CPU0_VIEWPIN_GNR2")
	)
	(via
		(at 367.56848 -233.34218)
		(size 0.4572)
		(drill 0.2032)
		(layers "F.Cu" "B.Cu")
		(net "NC_CPU0_VIEWPIN_GNR2")
	)
	(segment
		(start 369.558316 -262.336534)
		(end 369.558062 -262.336788)
		(width 0.12954)
		(layer "F.Cu")
		(net "NC_CPU0_VIEWPIN_GNR1")
	)
	(segment
		(start 369.558062 -262.336788)
		(end 369.558062 -262.872474)
		(width 0.12954)
		(layer "F.Cu")
		(net "NC_CPU0_VIEWPIN_GNR1")
	)
	(via
		(at 369.558062 -262.872474)
		(size 0.4572)
		(drill 0.2032)
		(layers "F.Cu" "B.Cu")
		(net "NC_CPU0_VIEWPIN_GNR1")
	)
	(segment
		(start 368.038634 -234.691936)
		(end 368.038634 -234.15625)
		(width 0.12954)
		(layer "F.Cu")
		(net "NC_CPU0_VIEWPIN_GNR0")
	)
	(segment
		(start 368.03838 -234.69219)
		(end 368.038634 -234.691936)
		(width 0.12954)
		(layer "F.Cu")
		(net "NC_CPU0_VIEWPIN_GNR0")
	)
	(via
		(at 368.553238 -235.120942)
		(size 0.6604)
		(drill 0.3302)
		(layers "F.Cu" "B.Cu")
		(net "NC_CPU0_VIEWPIN_GNR0")
	)
	(via
		(at 368.038634 -234.15625)
		(size 0.4572)
		(drill 0.2032)
		(layers "F.Cu" "B.Cu")
		(net "NC_CPU0_VIEWPIN_GNR0")
	)
	(segment
		(start 368.038634 -234.606338)
		(end 368.553238 -235.120942)
		(width 0.12954)
		(layer "B.Cu")
		(net "NC_CPU0_VIEWPIN_GNR0")
	)
	(segment
		(start 368.038634 -234.15625)
		(end 368.038634 -234.606338)
		(width 0.12954)
		(layer "B.Cu")
		(net "NC_CPU0_VIEWPIN_GNR0")
	)
	(segment
		(start 365.798862 -267.755878)
		(end 365.798862 -267.220192)
		(width 0.12954)
		(layer "F.Cu")
		(net "NC_CPU0_VIEWPIN_DIE11<3>")
	)
	(segment
		(start 365.798862 -267.220192)
		(end 365.799116 -267.219938)
		(width 0.12954)
		(layer "F.Cu")
		(net "NC_CPU0_VIEWPIN_DIE11<3>")
	)
	(via
		(at 365.798862 -267.755878)
		(size 0.4572)
		(drill 0.2032)
		(layers "F.Cu" "B.Cu")
		(net "NC_CPU0_VIEWPIN_DIE11<3>")
	)
	(segment
		(start 366.268508 -266.406122)
		(end 366.268508 -266.941808)
		(width 0.12954)
		(layer "F.Cu")
		(net "NC_CPU0_VIEWPIN_DIE11<2>")
	)
	(segment
		(start 366.268762 -266.405868)
		(end 366.268508 -266.406122)
		(width 0.12954)
		(layer "F.Cu")
		(net "NC_CPU0_VIEWPIN_DIE11<2>")
	)
	(via
		(at 366.268508 -266.941808)
		(size 0.4572)
		(drill 0.2032)
		(layers "F.Cu" "B.Cu")
		(net "NC_CPU0_VIEWPIN_DIE11<2>")
	)
	(segment
		(start 366.738662 -266.1285)
		(end 366.738662 -265.59256)
		(width 0.12954)
		(layer "F.Cu")
		(net "NC_CPU0_VIEWPIN_DIE11<1>")
	)
	(segment
		(start 366.738662 -265.59256)
		(end 366.738916 -265.592306)
		(width 0.12954)
		(layer "F.Cu")
		(net "NC_CPU0_VIEWPIN_DIE11<1>")
	)
	(via
		(at 366.738662 -266.1285)
		(size 0.4572)
		(drill 0.2032)
		(layers "F.Cu" "B.Cu")
		(net "NC_CPU0_VIEWPIN_DIE11<1>")
	)
	(segment
		(start 364.859316 -265.592306)
		(end 364.859062 -265.59256)
		(width 0.12954)
		(layer "F.Cu")
		(net "NC_CPU0_VIEWPIN_DIE11<0>")
	)
	(segment
		(start 364.859062 -265.59256)
		(end 364.859062 -266.1285)
		(width 0.12954)
		(layer "F.Cu")
		(net "NC_CPU0_VIEWPIN_DIE11<0>")
	)
	(via
		(at 364.859062 -266.1285)
		(size 0.4572)
		(drill 0.2032)
		(layers "F.Cu" "B.Cu")
		(net "NC_CPU0_VIEWPIN_DIE11<0>")
	)
	(segment
		(start 369.448334 -231.714802)
		(end 369.448588 -231.714548)
		(width 0.12954)
		(layer "F.Cu")
		(net "NC_CPU0_VIEWPIN_DIE10<3>")
	)
	(segment
		(start 369.448334 -232.250488)
		(end 369.448334 -231.714802)
		(width 0.12954)
		(layer "F.Cu")
		(net "NC_CPU0_VIEWPIN_DIE10<3>")
	)
	(via
		(at 369.448588 -231.714548)
		(size 0.4572)
		(drill 0.2032)
		(layers "F.Cu" "B.Cu")
		(net "NC_CPU0_VIEWPIN_DIE10<3>")
	)
	(segment
		(start 368.97818 -233.064304)
		(end 368.97818 -232.528618)
		(width 0.12954)
		(layer "F.Cu")
		(net "NC_CPU0_VIEWPIN_DIE10<2>")
	)
	(segment
		(start 368.97818 -232.528618)
		(end 368.978434 -232.528364)
		(width 0.12954)
		(layer "F.Cu")
		(net "NC_CPU0_VIEWPIN_DIE10<2>")
	)
	(via
		(at 368.978434 -232.528364)
		(size 0.4572)
		(drill 0.2032)
		(layers "F.Cu" "B.Cu")
		(net "NC_CPU0_VIEWPIN_DIE10<2>")
	)
	(segment
		(start 369.448334 -233.34218)
		(end 369.448334 -233.87812)
		(width 0.12954)
		(layer "F.Cu")
		(net "NC_CPU0_VIEWPIN_DIE10<1>")
	)
	(via
		(at 369.448334 -233.34218)
		(size 0.4572)
		(drill 0.2032)
		(layers "F.Cu" "B.Cu")
		(net "NC_CPU0_VIEWPIN_DIE10<1>")
	)
	(segment
		(start 367.568734 -232.250488)
		(end 367.568734 -231.714802)
		(width 0.12954)
		(layer "F.Cu")
		(net "NC_CPU0_VIEWPIN_DIE10<0>")
	)
	(segment
		(start 367.568734 -231.714802)
		(end 367.568988 -231.714548)
		(width 0.12954)
		(layer "F.Cu")
		(net "NC_CPU0_VIEWPIN_DIE10<0>")
	)
	(via
		(at 367.568988 -231.714548)
		(size 0.4572)
		(drill 0.2032)
		(layers "F.Cu" "B.Cu")
		(net "NC_CPU0_VIEWPIN_DIE10<0>")
	)
	(segment
		(start 355.461062 -272.103596)
		(end 355.461062 -272.639282)
		(width 0.12954)
		(layer "F.Cu")
		(net "NC_CPU0_VIEWPIN_DIE01<3>")
	)
	(segment
		(start 355.461316 -272.103342)
		(end 355.461062 -272.103596)
		(width 0.12954)
		(layer "F.Cu")
		(net "NC_CPU0_VIEWPIN_DIE01<3>")
	)
	(via
		(at 355.461062 -272.639282)
		(size 0.4572)
		(drill 0.2032)
		(layers "F.Cu" "B.Cu")
		(net "NC_CPU0_VIEWPIN_DIE01<3>")
	)
	(segment
		(start 351.232216 -268.034008)
		(end 351.232216 -268.569694)
		(width 0.12954)
		(layer "F.Cu")
		(net "NC_CPU0_VIEWPIN_DIE01<2>")
	)
	(segment
		(start 351.231962 -268.033754)
		(end 351.232216 -268.034008)
		(width 0.12954)
		(layer "F.Cu")
		(net "NC_CPU0_VIEWPIN_DIE01<2>")
	)
	(via
		(at 334.287368 -267.592302)
		(size 0.6604)
		(drill 0.3302)
		(layers "F.Cu" "B.Cu")
		(net "NC_CPU0_VIEWPIN_DIE01<2>")
	)
	(via
		(at 351.232216 -268.569694)
		(size 0.4572)
		(drill 0.2032)
		(layers "F.Cu" "B.Cu")
		(net "NC_CPU0_VIEWPIN_DIE01<2>")
	)
	(segment
		(start 348.695264 -268.080236)
		(end 348.680532 -268.0716)
		(width 0.0889)
		(layer "B.Cu")
		(net "NC_CPU0_VIEWPIN_DIE01<2>")
	)
	(segment
		(start 351.232216 -268.569694)
		(end 350.919542 -268.569694)
		(width 0.0889)
		(layer "B.Cu")
		(net "NC_CPU0_VIEWPIN_DIE01<2>")
	)
	(segment
		(start 350.574864 -268.080236)
		(end 350.560132 -268.0716)
		(width 0.0889)
		(layer "B.Cu")
		(net "NC_CPU0_VIEWPIN_DIE01<2>")
	)
	(segment
		(start 339.297264 -268.080236)
		(end 339.28685 -268.07414)
		(width 0.0889)
		(layer "B.Cu")
		(net "NC_CPU0_VIEWPIN_DIE01<2>")
	)
	(segment
		(start 337.802474 -268.07414)
		(end 337.79206 -268.080236)
		(width 0.0889)
		(layer "B.Cu")
		(net "NC_CPU0_VIEWPIN_DIE01<2>")
	)
	(segment
		(start 346.815664 -268.080236)
		(end 346.800932 -268.0716)
		(width 0.0889)
		(layer "B.Cu")
		(net "NC_CPU0_VIEWPIN_DIE01<2>")
	)
	(segment
		(start 343.996264 -268.080236)
		(end 343.981532 -268.0716)
		(width 0.0889)
		(layer "B.Cu")
		(net "NC_CPU0_VIEWPIN_DIE01<2>")
	)
	(segment
		(start 334.385412 -268.004544)
		(end 334.287368 -267.9065)
		(width 0.0889)
		(layer "B.Cu")
		(net "NC_CPU0_VIEWPIN_DIE01<2>")
	)
	(segment
		(start 334.287368 -267.9065)
		(end 334.287368 -267.592302)
		(width 0.12954)
		(layer "B.Cu")
		(net "NC_CPU0_VIEWPIN_DIE01<2>")
	)
	(segment
		(start 335.255362 -268.004544)
		(end 334.385412 -268.004544)
		(width 0.0889)
		(layer "B.Cu")
		(net "NC_CPU0_VIEWPIN_DIE01<2>")
	)
	(segment
		(start 341.176864 -268.080236)
		(end 341.162132 -268.0716)
		(width 0.0889)
		(layer "B.Cu")
		(net "NC_CPU0_VIEWPIN_DIE01<2>")
	)
	(segment
		(start 347.755464 -268.080236)
		(end 347.740732 -268.0716)
		(width 0.0889)
		(layer "B.Cu")
		(net "NC_CPU0_VIEWPIN_DIE01<2>")
	)
	(segment
		(start 350.919542 -268.569694)
		(end 350.853756 -268.503908)
		(width 0.0889)
		(layer "B.Cu")
		(net "NC_CPU0_VIEWPIN_DIE01<2>")
	)
	(segment
		(start 350.58096 -268.083792)
		(end 350.574864 -268.080236)
		(width 0.0889)
		(layer "B.Cu")
		(net "NC_CPU0_VIEWPIN_DIE01<2>")
	)
	(segment
		(start 342.116664 -268.080236)
		(end 342.101932 -268.0716)
		(width 0.0889)
		(layer "B.Cu")
		(net "NC_CPU0_VIEWPIN_DIE01<2>")
	)
	(segment
		(start 344.936318 -268.080236)
		(end 344.925904 -268.07414)
		(width 0.0889)
		(layer "B.Cu")
		(net "NC_CPU0_VIEWPIN_DIE01<2>")
	)
	(segment
		(start 345.875864 -268.080236)
		(end 345.86545 -268.07414)
		(width 0.0889)
		(layer "B.Cu")
		(net "NC_CPU0_VIEWPIN_DIE01<2>")
	)
	(segment
		(start 340.237064 -268.080236)
		(end 340.222332 -268.0716)
		(width 0.0889)
		(layer "B.Cu")
		(net "NC_CPU0_VIEWPIN_DIE01<2>")
	)
	(arc
		(start 346.25026 -268.080236)
		(mid 346.063062 -268.130379)
		(end 345.875864 -268.080236)
		(width 0.0889)
		(layer "B.Cu")
		(net "NC_CPU0_VIEWPIN_DIE01<2>")
	)
	(arc
		(start 350.00946 -268.080236)
		(mid 349.822262 -268.130379)
		(end 349.635064 -268.080236)
		(width 0.0889)
		(layer "B.Cu")
		(net "NC_CPU0_VIEWPIN_DIE01<2>")
	)
	(arc
		(start 342.49106 -268.080236)
		(mid 342.303862 -268.130379)
		(end 342.116664 -268.080236)
		(width 0.0889)
		(layer "B.Cu")
		(net "NC_CPU0_VIEWPIN_DIE01<2>")
	)
	(arc
		(start 347.740732 -268.0716)
		(mid 347.464257 -268.00428)
		(end 347.19006 -268.080236)
		(width 0.0889)
		(layer "B.Cu")
		(net "NC_CPU0_VIEWPIN_DIE01<2>")
	)
	(arc
		(start 344.925904 -268.07414)
		(mid 344.647472 -268.004294)
		(end 344.37066 -268.080236)
		(width 0.0889)
		(layer "B.Cu")
		(net "NC_CPU0_VIEWPIN_DIE01<2>")
	)
	(arc
		(start 336.477864 -268.080236)
		(mid 336.195162 -268.00446)
		(end 335.91246 -268.080236)
		(width 0.0889)
		(layer "B.Cu")
		(net "NC_CPU0_VIEWPIN_DIE01<2>")
	)
	(arc
		(start 350.560132 -268.0716)
		(mid 350.283657 -268.00428)
		(end 350.00946 -268.080236)
		(width 0.0889)
		(layer "B.Cu")
		(net "NC_CPU0_VIEWPIN_DIE01<2>")
	)
	(arc
		(start 347.19006 -268.080236)
		(mid 347.002862 -268.130379)
		(end 346.815664 -268.080236)
		(width 0.0889)
		(layer "B.Cu")
		(net "NC_CPU0_VIEWPIN_DIE01<2>")
	)
	(arc
		(start 339.28685 -268.07414)
		(mid 339.008672 -268.004417)
		(end 338.732114 -268.080236)
		(width 0.0889)
		(layer "B.Cu")
		(net "NC_CPU0_VIEWPIN_DIE01<2>")
	)
	(arc
		(start 343.981532 -268.0716)
		(mid 343.705057 -268.00428)
		(end 343.43086 -268.080236)
		(width 0.0889)
		(layer "B.Cu")
		(net "NC_CPU0_VIEWPIN_DIE01<2>")
	)
	(arc
		(start 341.162132 -268.0716)
		(mid 340.885657 -268.00428)
		(end 340.61146 -268.080236)
		(width 0.0889)
		(layer "B.Cu")
		(net "NC_CPU0_VIEWPIN_DIE01<2>")
	)
	(arc
		(start 339.67166 -268.080236)
		(mid 339.484462 -268.130379)
		(end 339.297264 -268.080236)
		(width 0.0889)
		(layer "B.Cu")
		(net "NC_CPU0_VIEWPIN_DIE01<2>")
	)
	(arc
		(start 350.853756 -268.503908)
		(mid 350.766468 -268.261952)
		(end 350.58096 -268.083792)
		(width 0.0889)
		(layer "B.Cu")
		(net "NC_CPU0_VIEWPIN_DIE01<2>")
	)
	(arc
		(start 349.06966 -268.080236)
		(mid 348.882462 -268.130379)
		(end 348.695264 -268.080236)
		(width 0.0889)
		(layer "B.Cu")
		(net "NC_CPU0_VIEWPIN_DIE01<2>")
	)
	(arc
		(start 343.056464 -268.080236)
		(mid 342.773762 -268.00446)
		(end 342.49106 -268.080236)
		(width 0.0889)
		(layer "B.Cu")
		(net "NC_CPU0_VIEWPIN_DIE01<2>")
	)
	(arc
		(start 344.37066 -268.080236)
		(mid 344.183462 -268.130379)
		(end 343.996264 -268.080236)
		(width 0.0889)
		(layer "B.Cu")
		(net "NC_CPU0_VIEWPIN_DIE01<2>")
	)
	(arc
		(start 336.85226 -268.080236)
		(mid 336.665062 -268.130379)
		(end 336.477864 -268.080236)
		(width 0.0889)
		(layer "B.Cu")
		(net "NC_CPU0_VIEWPIN_DIE01<2>")
	)
	(arc
		(start 341.55126 -268.080236)
		(mid 341.364062 -268.130379)
		(end 341.176864 -268.080236)
		(width 0.0889)
		(layer "B.Cu")
		(net "NC_CPU0_VIEWPIN_DIE01<2>")
	)
	(arc
		(start 348.12986 -268.080236)
		(mid 347.942662 -268.130379)
		(end 347.755464 -268.080236)
		(width 0.0889)
		(layer "B.Cu")
		(net "NC_CPU0_VIEWPIN_DIE01<2>")
	)
	(arc
		(start 343.43086 -268.080236)
		(mid 343.243662 -268.130379)
		(end 343.056464 -268.080236)
		(width 0.0889)
		(layer "B.Cu")
		(net "NC_CPU0_VIEWPIN_DIE01<2>")
	)
	(arc
		(start 338.732114 -268.080236)
		(mid 338.544916 -268.130379)
		(end 338.357718 -268.080236)
		(width 0.0889)
		(layer "B.Cu")
		(net "NC_CPU0_VIEWPIN_DIE01<2>")
	)
	(arc
		(start 340.222332 -268.0716)
		(mid 339.945857 -268.00428)
		(end 339.67166 -268.080236)
		(width 0.0889)
		(layer "B.Cu")
		(net "NC_CPU0_VIEWPIN_DIE01<2>")
	)
	(arc
		(start 342.101932 -268.0716)
		(mid 341.825457 -268.00428)
		(end 341.55126 -268.080236)
		(width 0.0889)
		(layer "B.Cu")
		(net "NC_CPU0_VIEWPIN_DIE01<2>")
	)
	(arc
		(start 338.357718 -268.080236)
		(mid 338.080905 -268.004366)
		(end 337.802474 -268.07414)
		(width 0.0889)
		(layer "B.Cu")
		(net "NC_CPU0_VIEWPIN_DIE01<2>")
	)
	(arc
		(start 345.86545 -268.07414)
		(mid 345.587272 -268.004417)
		(end 345.310714 -268.080236)
		(width 0.0889)
		(layer "B.Cu")
		(net "NC_CPU0_VIEWPIN_DIE01<2>")
	)
	(arc
		(start 348.680532 -268.0716)
		(mid 348.404057 -268.00428)
		(end 348.12986 -268.080236)
		(width 0.0889)
		(layer "B.Cu")
		(net "NC_CPU0_VIEWPIN_DIE01<2>")
	)
	(arc
		(start 346.800932 -268.0716)
		(mid 346.524457 -268.00428)
		(end 346.25026 -268.080236)
		(width 0.0889)
		(layer "B.Cu")
		(net "NC_CPU0_VIEWPIN_DIE01<2>")
	)
	(arc
		(start 337.79206 -268.080236)
		(mid 337.604862 -268.130379)
		(end 337.417664 -268.080236)
		(width 0.0889)
		(layer "B.Cu")
		(net "NC_CPU0_VIEWPIN_DIE01<2>")
	)
	(arc
		(start 345.310714 -268.080236)
		(mid 345.123516 -268.130379)
		(end 344.936318 -268.080236)
		(width 0.0889)
		(layer "B.Cu")
		(net "NC_CPU0_VIEWPIN_DIE01<2>")
	)
	(arc
		(start 340.61146 -268.080236)
		(mid 340.424262 -268.130379)
		(end 340.237064 -268.080236)
		(width 0.0889)
		(layer "B.Cu")
		(net "NC_CPU0_VIEWPIN_DIE01<2>")
	)
	(arc
		(start 335.538064 -268.080236)
		(mid 335.401695 -268.023794)
		(end 335.255362 -268.004544)
		(width 0.0889)
		(layer "B.Cu")
		(net "NC_CPU0_VIEWPIN_DIE01<2>")
	)
	(arc
		(start 337.417664 -268.080236)
		(mid 337.134962 -268.00446)
		(end 336.85226 -268.080236)
		(width 0.0889)
		(layer "B.Cu")
		(net "NC_CPU0_VIEWPIN_DIE01<2>")
	)
	(arc
		(start 335.91246 -268.080236)
		(mid 335.725262 -268.130379)
		(end 335.538064 -268.080236)
		(width 0.0889)
		(layer "B.Cu")
		(net "NC_CPU0_VIEWPIN_DIE01<2>")
	)
	(arc
		(start 349.635064 -268.080236)
		(mid 349.352362 -268.00446)
		(end 349.06966 -268.080236)
		(width 0.0889)
		(layer "B.Cu")
		(net "NC_CPU0_VIEWPIN_DIE01<2>")
	)
	(segment
		(start 357.810562 -269.66164)
		(end 357.810562 -270.19758)
		(width 0.12954)
		(layer "F.Cu")
		(net "NC_CPU0_VIEWPIN_DIE01<1>")
	)
	(via
		(at 357.810562 -270.19758)
		(size 0.4572)
		(drill 0.2032)
		(layers "F.Cu" "B.Cu")
		(net "NC_CPU0_VIEWPIN_DIE01<1>")
	)
	(segment
		(start 357.810308 -271.825212)
		(end 357.810562 -271.824958)
		(width 0.12954)
		(layer "F.Cu")
		(net "NC_CPU0_VIEWPIN_DIE01<0>")
	)
	(segment
		(start 357.810562 -271.824958)
		(end 357.810562 -271.289272)
		(width 0.12954)
		(layer "F.Cu")
		(net "NC_CPU0_VIEWPIN_DIE01<0>")
	)
	(via
		(at 357.810308 -271.825212)
		(size 0.4572)
		(drill 0.2032)
		(layers "F.Cu" "B.Cu")
		(net "NC_CPU0_VIEWPIN_DIE01<0>")
	)
	(segment
		(start 350.18218 -234.156504)
		(end 350.182434 -234.15625)
		(width 0.12954)
		(layer "F.Cu")
		(net "NC_CPU0_VIEWPIN_DIE00<3>")
	)
	(segment
		(start 350.18218 -234.69219)
		(end 350.18218 -234.156504)
		(width 0.12954)
		(layer "F.Cu")
		(net "NC_CPU0_VIEWPIN_DIE00<3>")
	)
	(via
		(at 350.182434 -234.15625)
		(size 0.4572)
		(drill 0.2032)
		(layers "F.Cu" "B.Cu")
		(net "NC_CPU0_VIEWPIN_DIE00<3>")
	)
	(segment
		(start 351.12198 -234.69219)
		(end 351.122234 -234.691936)
		(width 0.12954)
		(layer "F.Cu")
		(net "NC_CPU0_VIEWPIN_DIE00<0>")
	)
	(segment
		(start 351.122234 -234.691936)
		(end 351.122234 -234.15625)
		(width 0.12954)
		(layer "F.Cu")
		(net "NC_CPU0_VIEWPIN_DIE00<0>")
	)
	(via
		(at 351.122234 -234.15625)
		(size 0.4572)
		(drill 0.2032)
		(layers "F.Cu" "B.Cu")
		(net "NC_CPU0_VIEWPIN_DIE00<0>")
	)
	(segment
		(start 367.678716 -270.475456)
		(end 367.678462 -270.47571)
		(width 0.12954)
		(layer "F.Cu")
		(net "NC_CPU0_UPI3_APROBE<1>")
	)
	(segment
		(start 367.678462 -270.47571)
		(end 367.678462 -271.011396)
		(width 0.12954)
		(layer "F.Cu")
		(net "NC_CPU0_UPI3_APROBE<1>")
	)
	(via
		(at 367.678462 -271.011396)
		(size 0.4572)
		(drill 0.2032)
		(layers "F.Cu" "B.Cu")
		(net "NC_CPU0_UPI3_APROBE<1>")
	)
	(segment
		(start 367.208562 -271.824958)
		(end 367.208308 -271.825212)
		(width 0.12954)
		(layer "F.Cu")
		(net "NC_CPU0_UPI3_APROBE<0>")
	)
	(segment
		(start 367.208562 -271.289272)
		(end 367.208562 -271.824958)
		(width 0.12954)
		(layer "F.Cu")
		(net "NC_CPU0_UPI3_APROBE<0>")
	)
	(via
		(at 367.208308 -271.825212)
		(size 0.4572)
		(drill 0.2032)
		(layers "F.Cu" "B.Cu")
		(net "NC_CPU0_UPI3_APROBE<0>")
	)
	(segment
		(start 349.352362 -269.66164)
		(end 349.352616 -269.661894)
		(width 0.12954)
		(layer "F.Cu")
		(net "NC_CPU0_UPI2_APROBE<1>")
	)
	(segment
		(start 349.352616 -269.661894)
		(end 349.352616 -270.19758)
		(width 0.12954)
		(layer "F.Cu")
		(net "NC_CPU0_UPI2_APROBE<1>")
	)
	(via
		(at 349.352616 -270.19758)
		(size 0.4572)
		(drill 0.2032)
		(layers "F.Cu" "B.Cu")
		(net "NC_CPU0_UPI2_APROBE<1>")
	)
	(via
		(at 334.5561 -269.905988)
		(size 0.6604)
		(drill 0.3302)
		(layers "F.Cu" "B.Cu")
		(net "NC_CPU0_UPI2_APROBE<1>")
	)
	(segment
		(start 342.036146 -269.881858)
		(end 342.021414 -269.873222)
		(width 0.0889)
		(layer "B.Cu")
		(net "NC_CPU0_UPI2_APROBE<1>")
	)
	(segment
		(start 341.096346 -269.881858)
		(end 341.081614 -269.873222)
		(width 0.0889)
		(layer "B.Cu")
		(net "NC_CPU0_UPI2_APROBE<1>")
	)
	(segment
		(start 349.66529 -270.19758)
		(end 349.722694 -270.140176)
		(width 0.0889)
		(layer "B.Cu")
		(net "NC_CPU0_UPI2_APROBE<1>")
	)
	(segment
		(start 334.589374 -269.872714)
		(end 334.5561 -269.905988)
		(width 0.0889)
		(layer "B.Cu")
		(net "NC_CPU0_UPI2_APROBE<1>")
	)
	(segment
		(start 342.975946 -269.881858)
		(end 342.961214 -269.873222)
		(width 0.0889)
		(layer "B.Cu")
		(net "NC_CPU0_UPI2_APROBE<1>")
	)
	(segment
		(start 339.767164 -269.873222)
		(end 339.75675 -269.879318)
		(width 0.0889)
		(layer "B.Cu")
		(net "NC_CPU0_UPI2_APROBE<1>")
	)
	(segment
		(start 338.272374 -269.879318)
		(end 338.26196 -269.873222)
		(width 0.0889)
		(layer "B.Cu")
		(net "NC_CPU0_UPI2_APROBE<1>")
	)
	(segment
		(start 335.064862 -269.872714)
		(end 334.589374 -269.872714)
		(width 0.0889)
		(layer "B.Cu")
		(net "NC_CPU0_UPI2_APROBE<1>")
	)
	(segment
		(start 349.352616 -270.19758)
		(end 349.66529 -270.19758)
		(width 0.0889)
		(layer "B.Cu")
		(net "NC_CPU0_UPI2_APROBE<1>")
	)
	(segment
		(start 346.730574 -269.879318)
		(end 346.72016 -269.873222)
		(width 0.0889)
		(layer "B.Cu")
		(net "NC_CPU0_UPI2_APROBE<1>")
	)
	(segment
		(start 346.345764 -269.873222)
		(end 346.33535 -269.879318)
		(width 0.0889)
		(layer "B.Cu")
		(net "NC_CPU0_UPI2_APROBE<1>")
	)
	(segment
		(start 344.855546 -269.881858)
		(end 344.840814 -269.873222)
		(width 0.0889)
		(layer "B.Cu")
		(net "NC_CPU0_UPI2_APROBE<1>")
	)
	(segment
		(start 335.44256 -269.873222)
		(end 335.40827 -269.85341)
		(width 0.0889)
		(layer "B.Cu")
		(net "NC_CPU0_UPI2_APROBE<1>")
	)
	(segment
		(start 347.674946 -269.881858)
		(end 347.660214 -269.873222)
		(width 0.0889)
		(layer "B.Cu")
		(net "NC_CPU0_UPI2_APROBE<1>")
	)
	(segment
		(start 340.151974 -269.879318)
		(end 340.14156 -269.873222)
		(width 0.0889)
		(layer "B.Cu")
		(net "NC_CPU0_UPI2_APROBE<1>")
	)
	(segment
		(start 348.614746 -269.881858)
		(end 348.600014 -269.873222)
		(width 0.0889)
		(layer "B.Cu")
		(net "NC_CPU0_UPI2_APROBE<1>")
	)
	(segment
		(start 349.548704 -269.878302)
		(end 349.539814 -269.873222)
		(width 0.0889)
		(layer "B.Cu")
		(net "NC_CPU0_UPI2_APROBE<1>")
	)
	(segment
		(start 343.915746 -269.881858)
		(end 343.901014 -269.873222)
		(width 0.0889)
		(layer "B.Cu")
		(net "NC_CPU0_UPI2_APROBE<1>")
	)
	(arc
		(start 342.961214 -269.873222)
		(mid 342.774016 -269.823079)
		(end 342.586818 -269.873222)
		(width 0.0889)
		(layer "B.Cu")
		(net "NC_CPU0_UPI2_APROBE<1>")
	)
	(arc
		(start 337.887564 -269.873222)
		(mid 337.604862 -269.948964)
		(end 337.32216 -269.873222)
		(width 0.0889)
		(layer "B.Cu")
		(net "NC_CPU0_UPI2_APROBE<1>")
	)
	(arc
		(start 343.526618 -269.873222)
		(mid 343.252389 -269.949147)
		(end 342.975946 -269.881858)
		(width 0.0889)
		(layer "B.Cu")
		(net "NC_CPU0_UPI2_APROBE<1>")
	)
	(arc
		(start 344.840814 -269.873222)
		(mid 344.653616 -269.823079)
		(end 344.466418 -269.873222)
		(width 0.0889)
		(layer "B.Cu")
		(net "NC_CPU0_UPI2_APROBE<1>")
	)
	(arc
		(start 343.901014 -269.873222)
		(mid 343.713816 -269.823079)
		(end 343.526618 -269.873222)
		(width 0.0889)
		(layer "B.Cu")
		(net "NC_CPU0_UPI2_APROBE<1>")
	)
	(arc
		(start 349.722694 -270.140176)
		(mid 349.664538 -269.990063)
		(end 349.548704 -269.878302)
		(width 0.0889)
		(layer "B.Cu")
		(net "NC_CPU0_UPI2_APROBE<1>")
	)
	(arc
		(start 339.75675 -269.879318)
		(mid 339.478572 -269.94901)
		(end 339.202014 -269.873222)
		(width 0.0889)
		(layer "B.Cu")
		(net "NC_CPU0_UPI2_APROBE<1>")
	)
	(arc
		(start 335.40827 -269.85341)
		(mid 335.234232 -269.821565)
		(end 335.064862 -269.872714)
		(width 0.0889)
		(layer "B.Cu")
		(net "NC_CPU0_UPI2_APROBE<1>")
	)
	(arc
		(start 346.72016 -269.873222)
		(mid 346.532962 -269.823079)
		(end 346.345764 -269.873222)
		(width 0.0889)
		(layer "B.Cu")
		(net "NC_CPU0_UPI2_APROBE<1>")
	)
	(arc
		(start 347.285818 -269.873222)
		(mid 347.009005 -269.949058)
		(end 346.730574 -269.879318)
		(width 0.0889)
		(layer "B.Cu")
		(net "NC_CPU0_UPI2_APROBE<1>")
	)
	(arc
		(start 341.647018 -269.873222)
		(mid 341.372789 -269.949147)
		(end 341.096346 -269.881858)
		(width 0.0889)
		(layer "B.Cu")
		(net "NC_CPU0_UPI2_APROBE<1>")
	)
	(arc
		(start 341.081614 -269.873222)
		(mid 340.894416 -269.823079)
		(end 340.707218 -269.873222)
		(width 0.0889)
		(layer "B.Cu")
		(net "NC_CPU0_UPI2_APROBE<1>")
	)
	(arc
		(start 349.165418 -269.873222)
		(mid 348.891189 -269.949147)
		(end 348.614746 -269.881858)
		(width 0.0889)
		(layer "B.Cu")
		(net "NC_CPU0_UPI2_APROBE<1>")
	)
	(arc
		(start 340.14156 -269.873222)
		(mid 339.954362 -269.823079)
		(end 339.767164 -269.873222)
		(width 0.0889)
		(layer "B.Cu")
		(net "NC_CPU0_UPI2_APROBE<1>")
	)
	(arc
		(start 349.539814 -269.873222)
		(mid 349.352616 -269.823079)
		(end 349.165418 -269.873222)
		(width 0.0889)
		(layer "B.Cu")
		(net "NC_CPU0_UPI2_APROBE<1>")
	)
	(arc
		(start 336.947764 -269.873222)
		(mid 336.665062 -269.948964)
		(end 336.38236 -269.873222)
		(width 0.0889)
		(layer "B.Cu")
		(net "NC_CPU0_UPI2_APROBE<1>")
	)
	(arc
		(start 342.586818 -269.873222)
		(mid 342.312589 -269.949147)
		(end 342.036146 -269.881858)
		(width 0.0889)
		(layer "B.Cu")
		(net "NC_CPU0_UPI2_APROBE<1>")
	)
	(arc
		(start 336.38236 -269.873222)
		(mid 336.195162 -269.823079)
		(end 336.007964 -269.873222)
		(width 0.0889)
		(layer "B.Cu")
		(net "NC_CPU0_UPI2_APROBE<1>")
	)
	(arc
		(start 345.406218 -269.873222)
		(mid 345.131989 -269.949147)
		(end 344.855546 -269.881858)
		(width 0.0889)
		(layer "B.Cu")
		(net "NC_CPU0_UPI2_APROBE<1>")
	)
	(arc
		(start 348.600014 -269.873222)
		(mid 348.412816 -269.823079)
		(end 348.225618 -269.873222)
		(width 0.0889)
		(layer "B.Cu")
		(net "NC_CPU0_UPI2_APROBE<1>")
	)
	(arc
		(start 338.26196 -269.873222)
		(mid 338.074762 -269.823079)
		(end 337.887564 -269.873222)
		(width 0.0889)
		(layer "B.Cu")
		(net "NC_CPU0_UPI2_APROBE<1>")
	)
	(arc
		(start 342.021414 -269.873222)
		(mid 341.834216 -269.823079)
		(end 341.647018 -269.873222)
		(width 0.0889)
		(layer "B.Cu")
		(net "NC_CPU0_UPI2_APROBE<1>")
	)
	(arc
		(start 345.780614 -269.873222)
		(mid 345.593416 -269.823079)
		(end 345.406218 -269.873222)
		(width 0.0889)
		(layer "B.Cu")
		(net "NC_CPU0_UPI2_APROBE<1>")
	)
	(arc
		(start 339.202014 -269.873222)
		(mid 339.014816 -269.823079)
		(end 338.827618 -269.873222)
		(width 0.0889)
		(layer "B.Cu")
		(net "NC_CPU0_UPI2_APROBE<1>")
	)
	(arc
		(start 348.225618 -269.873222)
		(mid 347.951389 -269.949147)
		(end 347.674946 -269.881858)
		(width 0.0889)
		(layer "B.Cu")
		(net "NC_CPU0_UPI2_APROBE<1>")
	)
	(arc
		(start 336.007964 -269.873222)
		(mid 335.725262 -269.948964)
		(end 335.44256 -269.873222)
		(width 0.0889)
		(layer "B.Cu")
		(net "NC_CPU0_UPI2_APROBE<1>")
	)
	(arc
		(start 338.827618 -269.873222)
		(mid 338.550805 -269.949058)
		(end 338.272374 -269.879318)
		(width 0.0889)
		(layer "B.Cu")
		(net "NC_CPU0_UPI2_APROBE<1>")
	)
	(arc
		(start 346.33535 -269.879318)
		(mid 346.057172 -269.94901)
		(end 345.780614 -269.873222)
		(width 0.0889)
		(layer "B.Cu")
		(net "NC_CPU0_UPI2_APROBE<1>")
	)
	(arc
		(start 344.466418 -269.873222)
		(mid 344.192189 -269.949147)
		(end 343.915746 -269.881858)
		(width 0.0889)
		(layer "B.Cu")
		(net "NC_CPU0_UPI2_APROBE<1>")
	)
	(arc
		(start 337.32216 -269.873222)
		(mid 337.134962 -269.823079)
		(end 336.947764 -269.873222)
		(width 0.0889)
		(layer "B.Cu")
		(net "NC_CPU0_UPI2_APROBE<1>")
	)
	(arc
		(start 347.660214 -269.873222)
		(mid 347.473016 -269.823079)
		(end 347.285818 -269.873222)
		(width 0.0889)
		(layer "B.Cu")
		(net "NC_CPU0_UPI2_APROBE<1>")
	)
	(arc
		(start 340.707218 -269.873222)
		(mid 340.430405 -269.949058)
		(end 340.151974 -269.879318)
		(width 0.0889)
		(layer "B.Cu")
		(net "NC_CPU0_UPI2_APROBE<1>")
	)
	(segment
		(start 349.822516 -271.011396)
		(end 349.822516 -270.475456)
		(width 0.12954)
		(layer "F.Cu")
		(net "NC_CPU0_UPI2_APROBE<0>")
	)
	(via
		(at 349.822516 -271.011396)
		(size 0.4572)
		(drill 0.2032)
		(layers "F.Cu" "B.Cu")
		(net "NC_CPU0_UPI2_APROBE<0>")
	)
	(segment
		(start 360.990134 -231.714802)
		(end 360.990388 -231.714548)
		(width 0.12954)
		(layer "F.Cu")
		(net "NC_CPU0_UPI1_APROBE<1>")
	)
	(segment
		(start 360.990134 -232.250488)
		(end 360.990134 -231.714802)
		(width 0.12954)
		(layer "F.Cu")
		(net "NC_CPU0_UPI1_APROBE<1>")
	)
	(via
		(at 360.990388 -231.714548)
		(size 0.4572)
		(drill 0.2032)
		(layers "F.Cu" "B.Cu")
		(net "NC_CPU0_UPI1_APROBE<1>")
	)
	(segment
		(start 359.58018 -231.436418)
		(end 359.58018 -230.900732)
		(width 0.12954)
		(layer "F.Cu")
		(net "NC_CPU0_UPI1_APROBE<0>")
	)
	(segment
		(start 359.58018 -230.900732)
		(end 359.580434 -230.900478)
		(width 0.12954)
		(layer "F.Cu")
		(net "NC_CPU0_UPI1_APROBE<0>")
	)
	(via
		(at 359.580434 -230.900478)
		(size 0.4572)
		(drill 0.2032)
		(layers "F.Cu" "B.Cu")
		(net "NC_CPU0_UPI1_APROBE<0>")
	)
	(segment
		(start 348.772734 -227.367084)
		(end 348.772734 -226.831144)
		(width 0.12954)
		(layer "F.Cu")
		(net "NC_CPU0_UPI0_APROBE<1>")
	)
	(via
		(at 348.772734 -226.831144)
		(size 0.4572)
		(drill 0.2032)
		(layers "F.Cu" "B.Cu")
		(net "NC_CPU0_UPI0_APROBE<1>")
	)
	(segment
		(start 347.832934 -227.367084)
		(end 347.832934 -226.831144)
		(width 0.12954)
		(layer "F.Cu")
		(net "NC_CPU0_UPI0_APROBE<0>")
	)
	(via
		(at 347.832934 -226.831144)
		(size 0.4572)
		(drill 0.2032)
		(layers "F.Cu" "B.Cu")
		(net "NC_CPU0_UPI0_APROBE<0>")
	)
	(segment
		(start 350.18218 -243.923058)
		(end 350.182434 -243.922804)
		(width 0.12954)
		(layer "F.Cu")
		(net "NC_CPU0_THERMADC")
	)
	(segment
		(start 350.18218 -244.458744)
		(end 350.18218 -243.923058)
		(width 0.12954)
		(layer "F.Cu")
		(net "NC_CPU0_THERMADC")
	)
	(via
		(at 350.182434 -243.922804)
		(size 0.4572)
		(drill 0.2032)
		(layers "F.Cu" "B.Cu")
		(net "NC_CPU0_THERMADC")
	)
	(segment
		(start 350.18218 -246.08663)
		(end 350.18218 -245.550944)
		(width 0.12954)
		(layer "F.Cu")
		(net "NC_CPU0_THERMADA")
	)
	(segment
		(start 350.18218 -245.550944)
		(end 350.182434 -245.55069)
		(width 0.12954)
		(layer "F.Cu")
		(net "NC_CPU0_THERMADA")
	)
	(via
		(at 350.182434 -245.55069)
		(size 0.4572)
		(drill 0.2032)
		(layers "F.Cu" "B.Cu")
		(net "NC_CPU0_THERMADA")
	)
	(segment
		(start 357.810562 -268.033754)
		(end 357.810562 -268.569694)
		(width 0.12954)
		(layer "F.Cu")
		(net "NC_CPU0_SOC_SPARE5")
	)
	(via
		(at 357.810562 -268.569694)
		(size 0.4572)
		(drill 0.2032)
		(layers "F.Cu" "B.Cu")
		(net "NC_CPU0_SOC_SPARE5")
	)
	(segment
		(start 351.592134 -233.87812)
		(end 351.592134 -233.342434)
		(width 0.12954)
		(layer "F.Cu")
		(net "NC_CPU0_SOC_SPARE4")
	)
	(segment
		(start 351.592134 -233.342434)
		(end 351.59188 -233.34218)
		(width 0.12954)
		(layer "F.Cu")
		(net "NC_CPU0_SOC_SPARE4")
	)
	(via
		(at 351.59188 -233.34218)
		(size 0.4572)
		(drill 0.2032)
		(layers "F.Cu" "B.Cu")
		(net "NC_CPU0_SOC_SPARE4")
	)
	(segment
		(start 356.871016 -268.56944)
		(end 356.871016 -268.034008)
		(width 0.12954)
		(layer "F.Cu")
		(net "NC_CPU0_SOC_SPARE1")
	)
	(segment
		(start 356.870762 -268.569694)
		(end 356.871016 -268.56944)
		(width 0.12954)
		(layer "F.Cu")
		(net "NC_CPU0_SOC_SPARE1")
	)
	(segment
		(start 356.871016 -268.034008)
		(end 356.870762 -268.033754)
		(width 0.12954)
		(layer "F.Cu")
		(net "NC_CPU0_SOC_SPARE1")
	)
	(via
		(at 356.870762 -268.569694)
		(size 0.4572)
		(drill 0.2032)
		(layers "F.Cu" "B.Cu")
		(net "NC_CPU0_SOC_SPARE1")
	)
	(segment
		(start 351.12198 -233.064304)
		(end 351.12198 -232.528618)
		(width 0.12954)
		(layer "F.Cu")
		(net "NC_CPU0_SOC_SPARE0")
	)
	(segment
		(start 351.12198 -232.528618)
		(end 351.122234 -232.528364)
		(width 0.12954)
		(layer "F.Cu")
		(net "NC_CPU0_SOC_SPARE0")
	)
	(via
		(at 351.122234 -232.528364)
		(size 0.4572)
		(drill 0.2032)
		(layers "F.Cu" "B.Cu")
		(net "NC_CPU0_SOC_SPARE0")
	)
	(segment
		(start 369.558316 -271.011142)
		(end 369.558062 -271.011396)
		(width 0.12954)
		(layer "F.Cu")
		(net "NC_CPU0_RSVD<144>")
	)
	(segment
		(start 369.558316 -270.475456)
		(end 369.558316 -271.011142)
		(width 0.12954)
		(layer "F.Cu")
		(net "NC_CPU0_RSVD<144>")
	)
	(via
		(at 369.558062 -271.011396)
		(size 0.4572)
		(drill 0.2032)
		(layers "F.Cu" "B.Cu")
		(net "NC_CPU0_RSVD<144>")
	)
	(segment
		(start 349.822516 -268.84757)
		(end 349.822516 -269.383256)
		(width 0.12954)
		(layer "F.Cu")
		(net "NC_CPU0_PE4_APROBE<1>")
	)
	(segment
		(start 349.822516 -269.383256)
		(end 349.82277 -269.38351)
		(width 0.12954)
		(layer "F.Cu")
		(net "NC_CPU0_PE4_APROBE<1>")
	)
	(via
		(at 349.82277 -269.38351)
		(size 0.4572)
		(drill 0.2032)
		(layers "F.Cu" "B.Cu")
		(net "NC_CPU0_PE4_APROBE<1>")
	)
	(segment
		(start 350.292162 -269.66164)
		(end 350.292416 -269.661894)
		(width 0.12954)
		(layer "F.Cu")
		(net "NC_CPU0_PE4_APROBE<0>")
	)
	(segment
		(start 350.292416 -269.661894)
		(end 350.292416 -270.19758)
		(width 0.12954)
		(layer "F.Cu")
		(net "NC_CPU0_PE4_APROBE<0>")
	)
	(via
		(at 331.693012 -269.987522)
		(size 0.6604)
		(drill 0.3302)
		(layers "F.Cu" "B.Cu")
		(net "NC_CPU0_PE4_APROBE<0>")
	)
	(via
		(at 350.292416 -270.19758)
		(size 0.4572)
		(drill 0.2032)
		(layers "F.Cu" "B.Cu")
		(net "NC_CPU0_PE4_APROBE<0>")
	)
	(segment
		(start 334.325468 -269.422626)
		(end 334.637634 -269.422626)
		(width 0.0889)
		(layer "B.Cu")
		(net "NC_CPU0_PE4_APROBE<0>")
	)
	(segment
		(start 348.680532 -269.699232)
		(end 348.695264 -269.707868)
		(width 0.0889)
		(layer "B.Cu")
		(net "NC_CPU0_PE4_APROBE<0>")
	)
	(segment
		(start 332.937358 -269.529306)
		(end 333.21244 -269.804388)
		(width 0.12954)
		(layer "B.Cu")
		(net "NC_CPU0_PE4_APROBE<0>")
	)
	(segment
		(start 335.499456 -269.685516)
		(end 335.538064 -269.707868)
		(width 0.0889)
		(layer "B.Cu")
		(net "NC_CPU0_PE4_APROBE<0>")
	)
	(segment
		(start 339.287104 -269.701772)
		(end 339.297518 -269.707868)
		(width 0.0889)
		(layer "B.Cu")
		(net "NC_CPU0_PE4_APROBE<0>")
	)
	(segment
		(start 333.711804 -269.804388)
		(end 333.943706 -269.804388)
		(width 0.0889)
		(layer "B.Cu")
		(net "NC_CPU0_PE4_APROBE<0>")
	)
	(segment
		(start 349.914464 -270.132302)
		(end 349.979742 -270.19758)
		(width 0.0889)
		(layer "B.Cu")
		(net "NC_CPU0_PE4_APROBE<0>")
	)
	(segment
		(start 349.979742 -270.19758)
		(end 350.292416 -270.19758)
		(width 0.0889)
		(layer "B.Cu")
		(net "NC_CPU0_PE4_APROBE<0>")
	)
	(segment
		(start 333.21244 -269.804388)
		(end 333.711804 -269.804388)
		(width 0.12954)
		(layer "B.Cu")
		(net "NC_CPU0_PE4_APROBE<0>")
	)
	(segment
		(start 332.151228 -269.529306)
		(end 332.937358 -269.529306)
		(width 0.12954)
		(layer "B.Cu")
		(net "NC_CPU0_PE4_APROBE<0>")
	)
	(segment
		(start 343.981532 -269.699232)
		(end 343.996264 -269.707868)
		(width 0.0889)
		(layer "B.Cu")
		(net "NC_CPU0_PE4_APROBE<0>")
	)
	(segment
		(start 339.671914 -269.707868)
		(end 339.682328 -269.701772)
		(width 0.0889)
		(layer "B.Cu")
		(net "NC_CPU0_PE4_APROBE<0>")
	)
	(segment
		(start 343.041732 -269.699232)
		(end 343.056464 -269.707868)
		(width 0.0889)
		(layer "B.Cu")
		(net "NC_CPU0_PE4_APROBE<0>")
	)
	(segment
		(start 344.921332 -269.699232)
		(end 344.936064 -269.707868)
		(width 0.0889)
		(layer "B.Cu")
		(net "NC_CPU0_PE4_APROBE<0>")
	)
	(segment
		(start 345.865704 -269.701772)
		(end 345.876118 -269.707868)
		(width 0.0889)
		(layer "B.Cu")
		(net "NC_CPU0_PE4_APROBE<0>")
	)
	(segment
		(start 346.250514 -269.707868)
		(end 346.260928 -269.701772)
		(width 0.0889)
		(layer "B.Cu")
		(net "NC_CPU0_PE4_APROBE<0>")
	)
	(segment
		(start 341.162132 -269.699232)
		(end 341.176864 -269.707868)
		(width 0.0889)
		(layer "B.Cu")
		(net "NC_CPU0_PE4_APROBE<0>")
	)
	(segment
		(start 347.740732 -269.699232)
		(end 347.755464 -269.707868)
		(width 0.0889)
		(layer "B.Cu")
		(net "NC_CPU0_PE4_APROBE<0>")
	)
	(segment
		(start 334.637634 -269.422626)
		(end 335.159604 -269.638526)
		(width 0.0889)
		(layer "B.Cu")
		(net "NC_CPU0_PE4_APROBE<0>")
	)
	(segment
		(start 333.943706 -269.804388)
		(end 334.325468 -269.422626)
		(width 0.0889)
		(layer "B.Cu")
		(net "NC_CPU0_PE4_APROBE<0>")
	)
	(segment
		(start 342.101932 -269.699232)
		(end 342.116664 -269.707868)
		(width 0.0889)
		(layer "B.Cu")
		(net "NC_CPU0_PE4_APROBE<0>")
	)
	(segment
		(start 331.693012 -269.987522)
		(end 332.151228 -269.529306)
		(width 0.12954)
		(layer "B.Cu")
		(net "NC_CPU0_PE4_APROBE<0>")
	)
	(arc
		(start 337.417664 -269.707868)
		(mid 337.604862 -269.758011)
		(end 337.79206 -269.707868)
		(width 0.0889)
		(layer "B.Cu")
		(net "NC_CPU0_PE4_APROBE<0>")
	)
	(arc
		(start 339.682328 -269.701772)
		(mid 339.960506 -269.63208)
		(end 340.237064 -269.707868)
		(width 0.0889)
		(layer "B.Cu")
		(net "NC_CPU0_PE4_APROBE<0>")
	)
	(arc
		(start 349.06966 -269.707868)
		(mid 349.352616 -269.631999)
		(end 349.635572 -269.707868)
		(width 0.0889)
		(layer "B.Cu")
		(net "NC_CPU0_PE4_APROBE<0>")
	)
	(arc
		(start 340.237064 -269.707868)
		(mid 340.424262 -269.758011)
		(end 340.61146 -269.707868)
		(width 0.0889)
		(layer "B.Cu")
		(net "NC_CPU0_PE4_APROBE<0>")
	)
	(arc
		(start 344.37066 -269.707868)
		(mid 344.644889 -269.631943)
		(end 344.921332 -269.699232)
		(width 0.0889)
		(layer "B.Cu")
		(net "NC_CPU0_PE4_APROBE<0>")
	)
	(arc
		(start 341.55126 -269.707868)
		(mid 341.825489 -269.631943)
		(end 342.101932 -269.699232)
		(width 0.0889)
		(layer "B.Cu")
		(net "NC_CPU0_PE4_APROBE<0>")
	)
	(arc
		(start 346.815664 -269.707868)
		(mid 347.002862 -269.758011)
		(end 347.19006 -269.707868)
		(width 0.0889)
		(layer "B.Cu")
		(net "NC_CPU0_PE4_APROBE<0>")
	)
	(arc
		(start 343.43086 -269.707868)
		(mid 343.705089 -269.631943)
		(end 343.981532 -269.699232)
		(width 0.0889)
		(layer "B.Cu")
		(net "NC_CPU0_PE4_APROBE<0>")
	)
	(arc
		(start 342.49106 -269.707868)
		(mid 342.765289 -269.631943)
		(end 343.041732 -269.699232)
		(width 0.0889)
		(layer "B.Cu")
		(net "NC_CPU0_PE4_APROBE<0>")
	)
	(arc
		(start 345.31046 -269.707868)
		(mid 345.587273 -269.632032)
		(end 345.865704 -269.701772)
		(width 0.0889)
		(layer "B.Cu")
		(net "NC_CPU0_PE4_APROBE<0>")
	)
	(arc
		(start 343.056464 -269.707868)
		(mid 343.243662 -269.758011)
		(end 343.43086 -269.707868)
		(width 0.0889)
		(layer "B.Cu")
		(net "NC_CPU0_PE4_APROBE<0>")
	)
	(arc
		(start 344.936064 -269.707868)
		(mid 345.123262 -269.758011)
		(end 345.31046 -269.707868)
		(width 0.0889)
		(layer "B.Cu")
		(net "NC_CPU0_PE4_APROBE<0>")
	)
	(arc
		(start 336.477864 -269.707868)
		(mid 336.665062 -269.758011)
		(end 336.85226 -269.707868)
		(width 0.0889)
		(layer "B.Cu")
		(net "NC_CPU0_PE4_APROBE<0>")
	)
	(arc
		(start 335.538064 -269.707868)
		(mid 335.725262 -269.758011)
		(end 335.91246 -269.707868)
		(width 0.0889)
		(layer "B.Cu")
		(net "NC_CPU0_PE4_APROBE<0>")
	)
	(arc
		(start 343.996264 -269.707868)
		(mid 344.183462 -269.758011)
		(end 344.37066 -269.707868)
		(width 0.0889)
		(layer "B.Cu")
		(net "NC_CPU0_PE4_APROBE<0>")
	)
	(arc
		(start 348.695264 -269.707868)
		(mid 348.882462 -269.758011)
		(end 349.06966 -269.707868)
		(width 0.0889)
		(layer "B.Cu")
		(net "NC_CPU0_PE4_APROBE<0>")
	)
	(arc
		(start 342.116664 -269.707868)
		(mid 342.303862 -269.758011)
		(end 342.49106 -269.707868)
		(width 0.0889)
		(layer "B.Cu")
		(net "NC_CPU0_PE4_APROBE<0>")
	)
	(arc
		(start 347.19006 -269.707868)
		(mid 347.464289 -269.631943)
		(end 347.740732 -269.699232)
		(width 0.0889)
		(layer "B.Cu")
		(net "NC_CPU0_PE4_APROBE<0>")
	)
	(arc
		(start 335.91246 -269.707868)
		(mid 336.195162 -269.632126)
		(end 336.477864 -269.707868)
		(width 0.0889)
		(layer "B.Cu")
		(net "NC_CPU0_PE4_APROBE<0>")
	)
	(arc
		(start 337.79206 -269.707868)
		(mid 338.074762 -269.632126)
		(end 338.357464 -269.707868)
		(width 0.0889)
		(layer "B.Cu")
		(net "NC_CPU0_PE4_APROBE<0>")
	)
	(arc
		(start 347.755464 -269.707868)
		(mid 347.942662 -269.758011)
		(end 348.12986 -269.707868)
		(width 0.0889)
		(layer "B.Cu")
		(net "NC_CPU0_PE4_APROBE<0>")
	)
	(arc
		(start 340.61146 -269.707868)
		(mid 340.885689 -269.631943)
		(end 341.162132 -269.699232)
		(width 0.0889)
		(layer "B.Cu")
		(net "NC_CPU0_PE4_APROBE<0>")
	)
	(arc
		(start 339.297518 -269.707868)
		(mid 339.484716 -269.758011)
		(end 339.671914 -269.707868)
		(width 0.0889)
		(layer "B.Cu")
		(net "NC_CPU0_PE4_APROBE<0>")
	)
	(arc
		(start 338.73186 -269.707868)
		(mid 339.008673 -269.632032)
		(end 339.287104 -269.701772)
		(width 0.0889)
		(layer "B.Cu")
		(net "NC_CPU0_PE4_APROBE<0>")
	)
	(arc
		(start 341.176864 -269.707868)
		(mid 341.364062 -269.758011)
		(end 341.55126 -269.707868)
		(width 0.0889)
		(layer "B.Cu")
		(net "NC_CPU0_PE4_APROBE<0>")
	)
	(arc
		(start 349.635572 -269.707868)
		(mid 349.825312 -269.887031)
		(end 349.914464 -270.132302)
		(width 0.0889)
		(layer "B.Cu")
		(net "NC_CPU0_PE4_APROBE<0>")
	)
	(arc
		(start 346.260928 -269.701772)
		(mid 346.539106 -269.63208)
		(end 346.815664 -269.707868)
		(width 0.0889)
		(layer "B.Cu")
		(net "NC_CPU0_PE4_APROBE<0>")
	)
	(arc
		(start 338.357464 -269.707868)
		(mid 338.544662 -269.758011)
		(end 338.73186 -269.707868)
		(width 0.0889)
		(layer "B.Cu")
		(net "NC_CPU0_PE4_APROBE<0>")
	)
	(arc
		(start 336.85226 -269.707868)
		(mid 337.134962 -269.632126)
		(end 337.417664 -269.707868)
		(width 0.0889)
		(layer "B.Cu")
		(net "NC_CPU0_PE4_APROBE<0>")
	)
	(arc
		(start 335.159604 -269.638526)
		(mid 335.333158 -269.635745)
		(end 335.499456 -269.685516)
		(width 0.0889)
		(layer "B.Cu")
		(net "NC_CPU0_PE4_APROBE<0>")
	)
	(arc
		(start 345.876118 -269.707868)
		(mid 346.063316 -269.758011)
		(end 346.250514 -269.707868)
		(width 0.0889)
		(layer "B.Cu")
		(net "NC_CPU0_PE4_APROBE<0>")
	)
	(arc
		(start 348.12986 -269.707868)
		(mid 348.404089 -269.631943)
		(end 348.680532 -269.699232)
		(width 0.0889)
		(layer "B.Cu")
		(net "NC_CPU0_PE4_APROBE<0>")
	)
	(segment
		(start 366.268762 -271.824958)
		(end 366.268508 -271.825212)
		(width 0.12954)
		(layer "F.Cu")
		(net "NC_CPU0_PE3_APROBE<1>")
	)
	(segment
		(start 366.268762 -271.289272)
		(end 366.268762 -271.824958)
		(width 0.12954)
		(layer "F.Cu")
		(net "NC_CPU0_PE3_APROBE<1>")
	)
	(via
		(at 366.268508 -271.825212)
		(size 0.4572)
		(drill 0.2032)
		(layers "F.Cu" "B.Cu")
		(net "NC_CPU0_PE3_APROBE<1>")
	)
	(segment
		(start 365.799116 -271.011142)
		(end 365.798862 -271.011396)
		(width 0.12954)
		(layer "F.Cu")
		(net "NC_CPU0_PE3_APROBE<0>")
	)
	(segment
		(start 365.799116 -270.475456)
		(end 365.799116 -271.011142)
		(width 0.12954)
		(layer "F.Cu")
		(net "NC_CPU0_PE3_APROBE<0>")
	)
	(via
		(at 365.798862 -271.011396)
		(size 0.4572)
		(drill 0.2032)
		(layers "F.Cu" "B.Cu")
		(net "NC_CPU0_PE3_APROBE<0>")
	)
	(segment
		(start 360.050334 -231.714802)
		(end 360.050588 -231.714548)
		(width 0.12954)
		(layer "F.Cu")
		(net "NC_CPU0_PE2_APROBE<1>")
	)
	(segment
		(start 360.050334 -232.250488)
		(end 360.050334 -231.714802)
		(width 0.12954)
		(layer "F.Cu")
		(net "NC_CPU0_PE2_APROBE<1>")
	)
	(via
		(at 360.050588 -231.714548)
		(size 0.4572)
		(drill 0.2032)
		(layers "F.Cu" "B.Cu")
		(net "NC_CPU0_PE2_APROBE<1>")
	)
	(segment
		(start 361.929934 -231.714802)
		(end 361.930188 -231.714548)
		(width 0.12954)
		(layer "F.Cu")
		(net "NC_CPU0_PE2_APROBE<0>")
	)
	(segment
		(start 361.929934 -232.250488)
		(end 361.929934 -231.714802)
		(width 0.12954)
		(layer "F.Cu")
		(net "NC_CPU0_PE2_APROBE<0>")
	)
	(via
		(at 361.930188 -231.714548)
		(size 0.4572)
		(drill 0.2032)
		(layers "F.Cu" "B.Cu")
		(net "NC_CPU0_PE2_APROBE<0>")
	)
	(segment
		(start 361.92968 -230.086916)
		(end 361.929934 -230.086662)
		(width 0.12954)
		(layer "F.Cu")
		(net "NC_CPU0_PE1_APROBE<1>")
	)
	(segment
		(start 361.92968 -230.622348)
		(end 361.92968 -230.086916)
		(width 0.12954)
		(layer "F.Cu")
		(net "NC_CPU0_PE1_APROBE<1>")
	)
	(segment
		(start 361.929934 -230.622602)
		(end 361.92968 -230.622348)
		(width 0.12954)
		(layer "F.Cu")
		(net "NC_CPU0_PE1_APROBE<1>")
	)
	(via
		(at 361.929934 -230.086662)
		(size 0.4572)
		(drill 0.2032)
		(layers "F.Cu" "B.Cu")
		(net "NC_CPU0_PE1_APROBE<1>")
	)
	(segment
		(start 362.86948 -230.086916)
		(end 362.869734 -230.086662)
		(width 0.12954)
		(layer "F.Cu")
		(net "NC_CPU0_PE1_APROBE<0>")
	)
	(segment
		(start 362.869734 -230.622602)
		(end 362.86948 -230.622348)
		(width 0.12954)
		(layer "F.Cu")
		(net "NC_CPU0_PE1_APROBE<0>")
	)
	(segment
		(start 362.86948 -230.622348)
		(end 362.86948 -230.086916)
		(width 0.12954)
		(layer "F.Cu")
		(net "NC_CPU0_PE1_APROBE<0>")
	)
	(via
		(at 362.869734 -230.086662)
		(size 0.4572)
		(drill 0.2032)
		(layers "F.Cu" "B.Cu")
		(net "NC_CPU0_PE1_APROBE<0>")
	)
	(segment
		(start 356.291134 -230.086916)
		(end 356.29088 -230.086662)
		(width 0.12954)
		(layer "F.Cu")
		(net "NC_CPU0_PE0_APROBE<1>")
	)
	(segment
		(start 356.291134 -230.622602)
		(end 356.291134 -230.086916)
		(width 0.12954)
		(layer "F.Cu")
		(net "NC_CPU0_PE0_APROBE<1>")
	)
	(via
		(at 356.29088 -230.086662)
		(size 0.4572)
		(drill 0.2032)
		(layers "F.Cu" "B.Cu")
		(net "NC_CPU0_PE0_APROBE<1>")
	)
	(segment
		(start 357.23068 -230.622348)
		(end 357.23068 -230.086662)
		(width 0.12954)
		(layer "F.Cu")
		(net "NC_CPU0_PE0_APROBE<0>")
	)
	(segment
		(start 357.230934 -230.622602)
		(end 357.23068 -230.622348)
		(width 0.12954)
		(layer "F.Cu")
		(net "NC_CPU0_PE0_APROBE<0>")
	)
	(via
		(at 357.23068 -230.086662)
		(size 0.4572)
		(drill 0.2032)
		(layers "F.Cu" "B.Cu")
		(net "NC_CPU0_PE0_APROBE<0>")
	)
	(segment
		(start 365.328962 -269.66164)
		(end 365.328962 -270.19758)
		(width 0.12954)
		(layer "F.Cu")
		(net "NC_CPU0_MDFI_DIE11_NS1")
	)
	(via
		(at 365.328962 -270.19758)
		(size 0.4572)
		(drill 0.2032)
		(layers "F.Cu" "B.Cu")
		(net "NC_CPU0_MDFI_DIE11_NS1")
	)
	(segment
		(start 364.859062 -270.47571)
		(end 364.859062 -271.011396)
		(width 0.12954)
		(layer "F.Cu")
		(net "NC_CPU0_MDFI_DIE11_NS0")
	)
	(segment
		(start 364.859316 -270.475456)
		(end 364.859062 -270.47571)
		(width 0.12954)
		(layer "F.Cu")
		(net "NC_CPU0_MDFI_DIE11_NS0")
	)
	(via
		(at 364.859062 -271.011396)
		(size 0.4572)
		(drill 0.2032)
		(layers "F.Cu" "B.Cu")
		(net "NC_CPU0_MDFI_DIE11_NS0")
	)
	(segment
		(start 364.389162 -271.289272)
		(end 364.388908 -271.289526)
		(width 0.12954)
		(layer "F.Cu")
		(net "NC_CPU0_MDFI_DIE11_EW1")
	)
	(segment
		(start 364.388908 -271.289526)
		(end 364.388908 -271.825212)
		(width 0.12954)
		(layer "F.Cu")
		(net "NC_CPU0_MDFI_DIE11_EW1")
	)
	(via
		(at 364.388908 -271.825212)
		(size 0.4572)
		(drill 0.2032)
		(layers "F.Cu" "B.Cu")
		(net "NC_CPU0_MDFI_DIE11_EW1")
	)
	(segment
		(start 364.859316 -272.639028)
		(end 364.859062 -272.639282)
		(width 0.12954)
		(layer "F.Cu")
		(net "NC_CPU0_MDFI_DIE11_EW0")
	)
	(segment
		(start 364.859316 -272.103342)
		(end 364.859316 -272.639028)
		(width 0.12954)
		(layer "F.Cu")
		(net "NC_CPU0_MDFI_DIE11_EW0")
	)
	(via
		(at 364.859062 -272.639282)
		(size 0.4572)
		(drill 0.2032)
		(layers "F.Cu" "B.Cu")
		(net "NC_CPU0_MDFI_DIE11_EW0")
	)
	(segment
		(start 362.399834 -230.900732)
		(end 362.400088 -230.900478)
		(width 0.12954)
		(layer "F.Cu")
		(net "NC_CPU0_MDFI_DIE10_NS1")
	)
	(segment
		(start 362.399834 -231.436418)
		(end 362.399834 -230.900732)
		(width 0.12954)
		(layer "F.Cu")
		(net "NC_CPU0_MDFI_DIE10_NS1")
	)
	(via
		(at 362.400088 -230.900478)
		(size 0.4572)
		(drill 0.2032)
		(layers "F.Cu" "B.Cu")
		(net "NC_CPU0_MDFI_DIE10_NS1")
	)
	(segment
		(start 363.33938 -231.436418)
		(end 363.33938 -230.900732)
		(width 0.12954)
		(layer "F.Cu")
		(net "NC_CPU0_MDFI_DIE10_NS0")
	)
	(segment
		(start 363.33938 -230.900732)
		(end 363.339634 -230.900478)
		(width 0.12954)
		(layer "F.Cu")
		(net "NC_CPU0_MDFI_DIE10_NS0")
	)
	(via
		(at 363.339634 -230.900478)
		(size 0.4572)
		(drill 0.2032)
		(layers "F.Cu" "B.Cu")
		(net "NC_CPU0_MDFI_DIE10_NS0")
	)
	(segment
		(start 362.399834 -234.69219)
		(end 362.399834 -234.15625)
		(width 0.12954)
		(layer "F.Cu")
		(net "NC_CPU0_MDFI_DIE10_EW0")
	)
	(via
		(at 362.399834 -234.15625)
		(size 0.4572)
		(drill 0.2032)
		(layers "F.Cu" "B.Cu")
		(net "NC_CPU0_MDFI_DIE10_EW0")
	)
	(segment
		(start 354.051616 -273.453098)
		(end 354.051362 -273.452844)
		(width 0.12954)
		(layer "F.Cu")
		(net "NC_CPU0_MDFI_DIE01_NS0")
	)
	(segment
		(start 354.051362 -273.452844)
		(end 354.051362 -272.917158)
		(width 0.12954)
		(layer "F.Cu")
		(net "NC_CPU0_MDFI_DIE01_NS0")
	)
	(via
		(at 354.051616 -273.453098)
		(size 0.4572)
		(drill 0.2032)
		(layers "F.Cu" "B.Cu")
		(net "NC_CPU0_MDFI_DIE01_NS0")
	)
	(segment
		(start 362.039916 -268.84757)
		(end 362.04017 -268.847824)
		(width 0.12954)
		(layer "F.Cu")
		(net "NC_CPU0_MDFI_DIE01_EW1")
	)
	(segment
		(start 362.04017 -268.847824)
		(end 362.04017 -269.38351)
		(width 0.12954)
		(layer "F.Cu")
		(net "NC_CPU0_MDFI_DIE01_EW1")
	)
	(via
		(at 362.04017 -269.38351)
		(size 0.4572)
		(drill 0.2032)
		(layers "F.Cu" "B.Cu")
		(net "NC_CPU0_MDFI_DIE01_EW1")
	)
	(segment
		(start 350.292162 -268.033754)
		(end 350.292416 -268.034008)
		(width 0.12954)
		(layer "F.Cu")
		(net "NC_CPU0_MDFI_DIE01_EW0")
	)
	(segment
		(start 350.292416 -268.034008)
		(end 350.292416 -268.569694)
		(width 0.12954)
		(layer "F.Cu")
		(net "NC_CPU0_MDFI_DIE01_EW0")
	)
	(via
		(at 350.292416 -268.569694)
		(size 0.4572)
		(drill 0.2032)
		(layers "F.Cu" "B.Cu")
		(net "NC_CPU0_MDFI_DIE01_EW0")
	)
	(via
		(at 333.196692 -267.805916)
		(size 0.6604)
		(drill 0.3302)
		(layers "F.Cu" "B.Cu")
		(net "NC_CPU0_MDFI_DIE01_EW0")
	)
	(segment
		(start 341.081614 -268.245336)
		(end 341.096346 -268.253972)
		(width 0.0889)
		(layer "B.Cu")
		(net "NC_CPU0_MDFI_DIE01_EW0")
	)
	(segment
		(start 350.479614 -268.245336)
		(end 350.488504 -268.250416)
		(width 0.0889)
		(layer "B.Cu")
		(net "NC_CPU0_MDFI_DIE01_EW0")
	)
	(segment
		(start 350.60509 -268.569694)
		(end 350.292416 -268.569694)
		(width 0.0889)
		(layer "B.Cu")
		(net "NC_CPU0_MDFI_DIE01_EW0")
	)
	(segment
		(start 333.942182 -268.19479)
		(end 335.255362 -268.19479)
		(width 0.0889)
		(layer "B.Cu")
		(net "NC_CPU0_MDFI_DIE01_EW0")
	)
	(segment
		(start 346.720414 -268.245336)
		(end 346.735146 -268.253972)
		(width 0.0889)
		(layer "B.Cu")
		(net "NC_CPU0_MDFI_DIE01_EW0")
	)
	(segment
		(start 333.196692 -267.805916)
		(end 333.447644 -267.805916)
		(width 0.12954)
		(layer "B.Cu")
		(net "NC_CPU0_MDFI_DIE01_EW0")
	)
	(segment
		(start 342.96096 -268.245336)
		(end 342.971374 -268.251432)
		(width 0.0889)
		(layer "B.Cu")
		(net "NC_CPU0_MDFI_DIE01_EW0")
	)
	(segment
		(start 339.202014 -268.245336)
		(end 339.216746 -268.253972)
		(width 0.0889)
		(layer "B.Cu")
		(net "NC_CPU0_MDFI_DIE01_EW0")
	)
	(segment
		(start 347.660214 -268.245336)
		(end 347.674946 -268.253972)
		(width 0.0889)
		(layer "B.Cu")
		(net "NC_CPU0_MDFI_DIE01_EW0")
	)
	(segment
		(start 333.447644 -267.805916)
		(end 333.836518 -268.19479)
		(width 0.12954)
		(layer "B.Cu")
		(net "NC_CPU0_MDFI_DIE01_EW0")
	)
	(segment
		(start 338.817204 -268.251432)
		(end 338.827618 -268.245336)
		(width 0.0889)
		(layer "B.Cu")
		(net "NC_CPU0_MDFI_DIE01_EW0")
	)
	(segment
		(start 343.901014 -268.245336)
		(end 343.915746 -268.253972)
		(width 0.0889)
		(layer "B.Cu")
		(net "NC_CPU0_MDFI_DIE01_EW0")
	)
	(segment
		(start 340.141814 -268.245336)
		(end 340.156546 -268.253972)
		(width 0.0889)
		(layer "B.Cu")
		(net "NC_CPU0_MDFI_DIE01_EW0")
	)
	(segment
		(start 345.780614 -268.245336)
		(end 345.795346 -268.253972)
		(width 0.0889)
		(layer "B.Cu")
		(net "NC_CPU0_MDFI_DIE01_EW0")
	)
	(segment
		(start 348.600014 -268.245336)
		(end 348.610428 -268.251432)
		(width 0.0889)
		(layer "B.Cu")
		(net "NC_CPU0_MDFI_DIE01_EW0")
	)
	(segment
		(start 349.53956 -268.245336)
		(end 349.549974 -268.251432)
		(width 0.0889)
		(layer "B.Cu")
		(net "NC_CPU0_MDFI_DIE01_EW0")
	)
	(segment
		(start 333.836518 -268.19479)
		(end 333.942182 -268.19479)
		(width 0.12954)
		(layer "B.Cu")
		(net "NC_CPU0_MDFI_DIE01_EW0")
	)
	(segment
		(start 342.021414 -268.245336)
		(end 342.031828 -268.251432)
		(width 0.0889)
		(layer "B.Cu")
		(net "NC_CPU0_MDFI_DIE01_EW0")
	)
	(segment
		(start 350.662494 -268.51229)
		(end 350.60509 -268.569694)
		(width 0.0889)
		(layer "B.Cu")
		(net "NC_CPU0_MDFI_DIE01_EW0")
	)
	(arc
		(start 339.216746 -268.253972)
		(mid 339.493221 -268.321292)
		(end 339.767418 -268.245336)
		(width 0.0889)
		(layer "B.Cu")
		(net "NC_CPU0_MDFI_DIE01_EW0")
	)
	(arc
		(start 345.795346 -268.253972)
		(mid 346.071821 -268.321292)
		(end 346.346018 -268.245336)
		(width 0.0889)
		(layer "B.Cu")
		(net "NC_CPU0_MDFI_DIE01_EW0")
	)
	(arc
		(start 341.096346 -268.253972)
		(mid 341.372821 -268.321292)
		(end 341.647018 -268.245336)
		(width 0.0889)
		(layer "B.Cu")
		(net "NC_CPU0_MDFI_DIE01_EW0")
	)
	(arc
		(start 336.38236 -268.245336)
		(mid 336.665062 -268.321112)
		(end 336.947764 -268.245336)
		(width 0.0889)
		(layer "B.Cu")
		(net "NC_CPU0_MDFI_DIE01_EW0")
	)
	(arc
		(start 340.156546 -268.253972)
		(mid 340.433021 -268.321292)
		(end 340.707218 -268.245336)
		(width 0.0889)
		(layer "B.Cu")
		(net "NC_CPU0_MDFI_DIE01_EW0")
	)
	(arc
		(start 350.488504 -268.250416)
		(mid 350.604243 -268.36224)
		(end 350.662494 -268.51229)
		(width 0.0889)
		(layer "B.Cu")
		(net "NC_CPU0_MDFI_DIE01_EW0")
	)
	(arc
		(start 343.526618 -268.245336)
		(mid 343.713816 -268.195193)
		(end 343.901014 -268.245336)
		(width 0.0889)
		(layer "B.Cu")
		(net "NC_CPU0_MDFI_DIE01_EW0")
	)
	(arc
		(start 345.406218 -268.245336)
		(mid 345.593416 -268.195193)
		(end 345.780614 -268.245336)
		(width 0.0889)
		(layer "B.Cu")
		(net "NC_CPU0_MDFI_DIE01_EW0")
	)
	(arc
		(start 348.225618 -268.245336)
		(mid 348.412816 -268.195193)
		(end 348.600014 -268.245336)
		(width 0.0889)
		(layer "B.Cu")
		(net "NC_CPU0_MDFI_DIE01_EW0")
	)
	(arc
		(start 342.971374 -268.251432)
		(mid 343.249806 -268.321278)
		(end 343.526618 -268.245336)
		(width 0.0889)
		(layer "B.Cu")
		(net "NC_CPU0_MDFI_DIE01_EW0")
	)
	(arc
		(start 335.44256 -268.245336)
		(mid 335.725262 -268.321112)
		(end 336.007964 -268.245336)
		(width 0.0889)
		(layer "B.Cu")
		(net "NC_CPU0_MDFI_DIE01_EW0")
	)
	(arc
		(start 341.647018 -268.245336)
		(mid 341.834216 -268.195193)
		(end 342.021414 -268.245336)
		(width 0.0889)
		(layer "B.Cu")
		(net "NC_CPU0_MDFI_DIE01_EW0")
	)
	(arc
		(start 336.947764 -268.245336)
		(mid 337.134962 -268.195193)
		(end 337.32216 -268.245336)
		(width 0.0889)
		(layer "B.Cu")
		(net "NC_CPU0_MDFI_DIE01_EW0")
	)
	(arc
		(start 337.887564 -268.245336)
		(mid 338.074762 -268.195193)
		(end 338.26196 -268.245336)
		(width 0.0889)
		(layer "B.Cu")
		(net "NC_CPU0_MDFI_DIE01_EW0")
	)
	(arc
		(start 337.32216 -268.245336)
		(mid 337.604862 -268.321112)
		(end 337.887564 -268.245336)
		(width 0.0889)
		(layer "B.Cu")
		(net "NC_CPU0_MDFI_DIE01_EW0")
	)
	(arc
		(start 342.031828 -268.251432)
		(mid 342.310006 -268.321155)
		(end 342.586564 -268.245336)
		(width 0.0889)
		(layer "B.Cu")
		(net "NC_CPU0_MDFI_DIE01_EW0")
	)
	(arc
		(start 344.466418 -268.245336)
		(mid 344.653616 -268.195193)
		(end 344.840814 -268.245336)
		(width 0.0889)
		(layer "B.Cu")
		(net "NC_CPU0_MDFI_DIE01_EW0")
	)
	(arc
		(start 335.255362 -268.19479)
		(mid 335.352285 -268.207748)
		(end 335.44256 -268.245336)
		(width 0.0889)
		(layer "B.Cu")
		(net "NC_CPU0_MDFI_DIE01_EW0")
	)
	(arc
		(start 339.767418 -268.245336)
		(mid 339.954616 -268.195193)
		(end 340.141814 -268.245336)
		(width 0.0889)
		(layer "B.Cu")
		(net "NC_CPU0_MDFI_DIE01_EW0")
	)
	(arc
		(start 342.586564 -268.245336)
		(mid 342.773762 -268.195193)
		(end 342.96096 -268.245336)
		(width 0.0889)
		(layer "B.Cu")
		(net "NC_CPU0_MDFI_DIE01_EW0")
	)
	(arc
		(start 343.915746 -268.253972)
		(mid 344.192221 -268.321292)
		(end 344.466418 -268.245336)
		(width 0.0889)
		(layer "B.Cu")
		(net "NC_CPU0_MDFI_DIE01_EW0")
	)
	(arc
		(start 349.165164 -268.245336)
		(mid 349.352362 -268.195193)
		(end 349.53956 -268.245336)
		(width 0.0889)
		(layer "B.Cu")
		(net "NC_CPU0_MDFI_DIE01_EW0")
	)
	(arc
		(start 340.707218 -268.245336)
		(mid 340.894416 -268.195193)
		(end 341.081614 -268.245336)
		(width 0.0889)
		(layer "B.Cu")
		(net "NC_CPU0_MDFI_DIE01_EW0")
	)
	(arc
		(start 346.735146 -268.253972)
		(mid 347.011621 -268.321292)
		(end 347.285818 -268.245336)
		(width 0.0889)
		(layer "B.Cu")
		(net "NC_CPU0_MDFI_DIE01_EW0")
	)
	(arc
		(start 348.610428 -268.251432)
		(mid 348.888606 -268.321155)
		(end 349.165164 -268.245336)
		(width 0.0889)
		(layer "B.Cu")
		(net "NC_CPU0_MDFI_DIE01_EW0")
	)
	(arc
		(start 349.549974 -268.251432)
		(mid 349.828406 -268.321278)
		(end 350.105218 -268.245336)
		(width 0.0889)
		(layer "B.Cu")
		(net "NC_CPU0_MDFI_DIE01_EW0")
	)
	(arc
		(start 346.346018 -268.245336)
		(mid 346.533216 -268.195193)
		(end 346.720414 -268.245336)
		(width 0.0889)
		(layer "B.Cu")
		(net "NC_CPU0_MDFI_DIE01_EW0")
	)
	(arc
		(start 344.840814 -268.245336)
		(mid 345.123516 -268.321112)
		(end 345.406218 -268.245336)
		(width 0.0889)
		(layer "B.Cu")
		(net "NC_CPU0_MDFI_DIE01_EW0")
	)
	(arc
		(start 338.26196 -268.245336)
		(mid 338.538773 -268.321206)
		(end 338.817204 -268.251432)
		(width 0.0889)
		(layer "B.Cu")
		(net "NC_CPU0_MDFI_DIE01_EW0")
	)
	(arc
		(start 347.285818 -268.245336)
		(mid 347.473016 -268.195193)
		(end 347.660214 -268.245336)
		(width 0.0889)
		(layer "B.Cu")
		(net "NC_CPU0_MDFI_DIE01_EW0")
	)
	(arc
		(start 336.007964 -268.245336)
		(mid 336.195162 -268.195193)
		(end 336.38236 -268.245336)
		(width 0.0889)
		(layer "B.Cu")
		(net "NC_CPU0_MDFI_DIE01_EW0")
	)
	(arc
		(start 350.105218 -268.245336)
		(mid 350.292416 -268.195193)
		(end 350.479614 -268.245336)
		(width 0.0889)
		(layer "B.Cu")
		(net "NC_CPU0_MDFI_DIE01_EW0")
	)
	(arc
		(start 347.674946 -268.253972)
		(mid 347.951421 -268.321292)
		(end 348.225618 -268.245336)
		(width 0.0889)
		(layer "B.Cu")
		(net "NC_CPU0_MDFI_DIE01_EW0")
	)
	(arc
		(start 338.827618 -268.245336)
		(mid 339.014816 -268.195193)
		(end 339.202014 -268.245336)
		(width 0.0889)
		(layer "B.Cu")
		(net "NC_CPU0_MDFI_DIE01_EW0")
	)
	(segment
		(start 355.351334 -230.086916)
		(end 355.35108 -230.086662)
		(width 0.12954)
		(layer "F.Cu")
		(net "NC_CPU0_MDFI_DIE00_NS1")
	)
	(segment
		(start 355.351334 -230.622602)
		(end 355.351334 -230.086916)
		(width 0.12954)
		(layer "F.Cu")
		(net "NC_CPU0_MDFI_DIE00_NS1")
	)
	(via
		(at 355.35108 -230.086662)
		(size 0.4572)
		(drill 0.2032)
		(layers "F.Cu" "B.Cu")
		(net "NC_CPU0_MDFI_DIE00_NS1")
	)
	(segment
		(start 355.82098 -230.900478)
		(end 355.82098 -231.436418)
		(width 0.12954)
		(layer "F.Cu")
		(net "NC_CPU0_MDFI_DIE00_NS0")
	)
	(via
		(at 355.82098 -230.900478)
		(size 0.4572)
		(drill 0.2032)
		(layers "F.Cu" "B.Cu")
		(net "NC_CPU0_MDFI_DIE00_NS0")
	)
	(segment
		(start 358.17048 -230.622348)
		(end 358.17048 -230.086662)
		(width 0.12954)
		(layer "F.Cu")
		(net "NC_CPU0_MDFI_DIE00_EW1")
	)
	(segment
		(start 358.170734 -230.622602)
		(end 358.17048 -230.622348)
		(width 0.12954)
		(layer "F.Cu")
		(net "NC_CPU0_MDFI_DIE00_EW1")
	)
	(via
		(at 358.17048 -230.086662)
		(size 0.4572)
		(drill 0.2032)
		(layers "F.Cu" "B.Cu")
		(net "NC_CPU0_MDFI_DIE00_EW1")
	)
	(segment
		(start 357.70058 -230.900478)
		(end 357.70058 -231.436418)
		(width 0.12954)
		(layer "F.Cu")
		(net "NC_CPU0_MDFI_DIE00_EW0")
	)
	(via
		(at 357.70058 -230.900478)
		(size 0.4572)
		(drill 0.2032)
		(layers "F.Cu" "B.Cu")
		(net "NC_CPU0_MDFI_DIE00_EW0")
	)
	(segment
		(start 367.208816 -264.77849)
		(end 367.208562 -264.778236)
		(width 0.12954)
		(layer "F.Cu")
		(net "NC_CPU0_LGSSPARE5")
	)
	(segment
		(start 367.208816 -265.314176)
		(end 367.208816 -264.77849)
		(width 0.12954)
		(layer "F.Cu")
		(net "NC_CPU0_LGSSPARE5")
	)
	(via
		(at 384.170682 -264.981182)
		(size 0.6604)
		(drill 0.3302)
		(layers "F.Cu" "B.Cu")
		(net "NC_CPU0_LGSSPARE5")
	)
	(via
		(at 367.208816 -265.314176)
		(size 0.4572)
		(drill 0.2032)
		(layers "F.Cu" "B.Cu")
		(net "NC_CPU0_LGSSPARE5")
	)
	(segment
		(start 384.086354 -265.06551)
		(end 384.170682 -264.981182)
		(width 0.12954)
		(layer "B.Cu")
		(net "NC_CPU0_LGSSPARE5")
	)
	(segment
		(start 374.52935 -264.995914)
		(end 374.539764 -264.989818)
		(width 0.0889)
		(layer "B.Cu")
		(net "NC_CPU0_LGSSPARE5")
	)
	(segment
		(start 379.613414 -264.989818)
		(end 379.628146 -264.998454)
		(width 0.0889)
		(layer "B.Cu")
		(net "NC_CPU0_LGSSPARE5")
	)
	(segment
		(start 381.49276 -264.989818)
		(end 381.503174 -264.995914)
		(width 0.0889)
		(layer "B.Cu")
		(net "NC_CPU0_LGSSPARE5")
	)
	(segment
		(start 378.673614 -264.989818)
		(end 378.688346 -264.998454)
		(width 0.0889)
		(layer "B.Cu")
		(net "NC_CPU0_LGSSPARE5")
	)
	(segment
		(start 376.794014 -264.989818)
		(end 376.808746 -264.998454)
		(width 0.0889)
		(layer "B.Cu")
		(net "NC_CPU0_LGSSPARE5")
	)
	(segment
		(start 377.733814 -264.989818)
		(end 377.748546 -264.998454)
		(width 0.0889)
		(layer "B.Cu")
		(net "NC_CPU0_LGSSPARE5")
	)
	(segment
		(start 367.208816 -265.314176)
		(end 367.72088 -265.063986)
		(width 0.0889)
		(layer "B.Cu")
		(net "NC_CPU0_LGSSPARE5")
	)
	(segment
		(start 368.335814 -264.989818)
		(end 368.350546 -264.998454)
		(width 0.0889)
		(layer "B.Cu")
		(net "NC_CPU0_LGSSPARE5")
	)
	(segment
		(start 370.215414 -264.989818)
		(end 370.230146 -264.998454)
		(width 0.0889)
		(layer "B.Cu")
		(net "NC_CPU0_LGSSPARE5")
	)
	(segment
		(start 369.275614 -264.989818)
		(end 369.290346 -264.998454)
		(width 0.0889)
		(layer "B.Cu")
		(net "NC_CPU0_LGSSPARE5")
	)
	(segment
		(start 381.10795 -264.995914)
		(end 381.118364 -264.989818)
		(width 0.0889)
		(layer "B.Cu")
		(net "NC_CPU0_LGSSPARE5")
	)
	(segment
		(start 375.854214 -264.989818)
		(end 375.868946 -264.998454)
		(width 0.0889)
		(layer "B.Cu")
		(net "NC_CPU0_LGSSPARE5")
	)
	(segment
		(start 382.432814 -264.989818)
		(end 382.447546 -264.998454)
		(width 0.0889)
		(layer "B.Cu")
		(net "NC_CPU0_LGSSPARE5")
	)
	(segment
		(start 373.034814 -264.989818)
		(end 373.049546 -264.998454)
		(width 0.0889)
		(layer "B.Cu")
		(net "NC_CPU0_LGSSPARE5")
	)
	(segment
		(start 374.91416 -264.989818)
		(end 374.924574 -264.995914)
		(width 0.0889)
		(layer "B.Cu")
		(net "NC_CPU0_LGSSPARE5")
	)
	(segment
		(start 372.095014 -264.989818)
		(end 372.109746 -264.998454)
		(width 0.0889)
		(layer "B.Cu")
		(net "NC_CPU0_LGSSPARE5")
	)
	(segment
		(start 371.155214 -264.989818)
		(end 371.169946 -264.998454)
		(width 0.0889)
		(layer "B.Cu")
		(net "NC_CPU0_LGSSPARE5")
	)
	(segment
		(start 383.655062 -265.06551)
		(end 384.086354 -265.06551)
		(width 0.12954)
		(layer "B.Cu")
		(net "NC_CPU0_LGSSPARE5")
	)
	(arc
		(start 372.109746 -264.998454)
		(mid 372.386221 -265.065774)
		(end 372.660418 -264.989818)
		(width 0.0889)
		(layer "B.Cu")
		(net "NC_CPU0_LGSSPARE5")
	)
	(arc
		(start 379.239018 -264.989818)
		(mid 379.426216 -264.939675)
		(end 379.613414 -264.989818)
		(width 0.0889)
		(layer "B.Cu")
		(net "NC_CPU0_LGSSPARE5")
	)
	(arc
		(start 380.178818 -264.989818)
		(mid 380.366016 -264.939675)
		(end 380.553214 -264.989818)
		(width 0.0889)
		(layer "B.Cu")
		(net "NC_CPU0_LGSSPARE5")
	)
	(arc
		(start 368.350546 -264.998454)
		(mid 368.627021 -265.065774)
		(end 368.901218 -264.989818)
		(width 0.0889)
		(layer "B.Cu")
		(net "NC_CPU0_LGSSPARE5")
	)
	(arc
		(start 381.503174 -264.995914)
		(mid 381.781606 -265.06576)
		(end 382.058418 -264.989818)
		(width 0.0889)
		(layer "B.Cu")
		(net "NC_CPU0_LGSSPARE5")
	)
	(arc
		(start 382.998218 -264.989818)
		(mid 383.185416 -264.939675)
		(end 383.372614 -264.989818)
		(width 0.0889)
		(layer "B.Cu")
		(net "NC_CPU0_LGSSPARE5")
	)
	(arc
		(start 367.72088 -265.063986)
		(mid 367.845324 -265.040447)
		(end 367.961418 -264.989818)
		(width 0.0889)
		(layer "B.Cu")
		(net "NC_CPU0_LGSSPARE5")
	)
	(arc
		(start 381.118364 -264.989818)
		(mid 381.305562 -264.939675)
		(end 381.49276 -264.989818)
		(width 0.0889)
		(layer "B.Cu")
		(net "NC_CPU0_LGSSPARE5")
	)
	(arc
		(start 376.808746 -264.998454)
		(mid 377.085221 -265.065774)
		(end 377.359418 -264.989818)
		(width 0.0889)
		(layer "B.Cu")
		(net "NC_CPU0_LGSSPARE5")
	)
	(arc
		(start 380.553214 -264.989818)
		(mid 380.829773 -265.065561)
		(end 381.10795 -264.995914)
		(width 0.0889)
		(layer "B.Cu")
		(net "NC_CPU0_LGSSPARE5")
	)
	(arc
		(start 375.479818 -264.989818)
		(mid 375.667016 -264.939675)
		(end 375.854214 -264.989818)
		(width 0.0889)
		(layer "B.Cu")
		(net "NC_CPU0_LGSSPARE5")
	)
	(arc
		(start 376.419618 -264.989818)
		(mid 376.606816 -264.939675)
		(end 376.794014 -264.989818)
		(width 0.0889)
		(layer "B.Cu")
		(net "NC_CPU0_LGSSPARE5")
	)
	(arc
		(start 377.748546 -264.998454)
		(mid 378.025021 -265.065774)
		(end 378.299218 -264.989818)
		(width 0.0889)
		(layer "B.Cu")
		(net "NC_CPU0_LGSSPARE5")
	)
	(arc
		(start 382.058418 -264.989818)
		(mid 382.245616 -264.939675)
		(end 382.432814 -264.989818)
		(width 0.0889)
		(layer "B.Cu")
		(net "NC_CPU0_LGSSPARE5")
	)
	(arc
		(start 378.688346 -264.998454)
		(mid 378.964821 -265.065774)
		(end 379.239018 -264.989818)
		(width 0.0889)
		(layer "B.Cu")
		(net "NC_CPU0_LGSSPARE5")
	)
	(arc
		(start 374.539764 -264.989818)
		(mid 374.726962 -264.939675)
		(end 374.91416 -264.989818)
		(width 0.0889)
		(layer "B.Cu")
		(net "NC_CPU0_LGSSPARE5")
	)
	(arc
		(start 375.868946 -264.998454)
		(mid 376.145421 -265.065774)
		(end 376.419618 -264.989818)
		(width 0.0889)
		(layer "B.Cu")
		(net "NC_CPU0_LGSSPARE5")
	)
	(arc
		(start 383.372614 -264.989818)
		(mid 383.508856 -265.046252)
		(end 383.655062 -265.06551)
		(width 0.0889)
		(layer "B.Cu")
		(net "NC_CPU0_LGSSPARE5")
	)
	(arc
		(start 369.841018 -264.989818)
		(mid 370.028216 -264.939675)
		(end 370.215414 -264.989818)
		(width 0.0889)
		(layer "B.Cu")
		(net "NC_CPU0_LGSSPARE5")
	)
	(arc
		(start 370.780818 -264.989818)
		(mid 370.968016 -264.939675)
		(end 371.155214 -264.989818)
		(width 0.0889)
		(layer "B.Cu")
		(net "NC_CPU0_LGSSPARE5")
	)
	(arc
		(start 368.901218 -264.989818)
		(mid 369.088416 -264.939675)
		(end 369.275614 -264.989818)
		(width 0.0889)
		(layer "B.Cu")
		(net "NC_CPU0_LGSSPARE5")
	)
	(arc
		(start 382.447546 -264.998454)
		(mid 382.724021 -265.065774)
		(end 382.998218 -264.989818)
		(width 0.0889)
		(layer "B.Cu")
		(net "NC_CPU0_LGSSPARE5")
	)
	(arc
		(start 373.049546 -264.998454)
		(mid 373.326021 -265.065774)
		(end 373.600218 -264.989818)
		(width 0.0889)
		(layer "B.Cu")
		(net "NC_CPU0_LGSSPARE5")
	)
	(arc
		(start 371.169946 -264.998454)
		(mid 371.446421 -265.065774)
		(end 371.720618 -264.989818)
		(width 0.0889)
		(layer "B.Cu")
		(net "NC_CPU0_LGSSPARE5")
	)
	(arc
		(start 370.230146 -264.998454)
		(mid 370.506621 -265.065774)
		(end 370.780818 -264.989818)
		(width 0.0889)
		(layer "B.Cu")
		(net "NC_CPU0_LGSSPARE5")
	)
	(arc
		(start 378.299218 -264.989818)
		(mid 378.486416 -264.939675)
		(end 378.673614 -264.989818)
		(width 0.0889)
		(layer "B.Cu")
		(net "NC_CPU0_LGSSPARE5")
	)
	(arc
		(start 374.924574 -264.995914)
		(mid 375.203006 -265.06576)
		(end 375.479818 -264.989818)
		(width 0.0889)
		(layer "B.Cu")
		(net "NC_CPU0_LGSSPARE5")
	)
	(arc
		(start 379.628146 -264.998454)
		(mid 379.904621 -265.065774)
		(end 380.178818 -264.989818)
		(width 0.0889)
		(layer "B.Cu")
		(net "NC_CPU0_LGSSPARE5")
	)
	(arc
		(start 369.290346 -264.998454)
		(mid 369.566821 -265.065774)
		(end 369.841018 -264.989818)
		(width 0.0889)
		(layer "B.Cu")
		(net "NC_CPU0_LGSSPARE5")
	)
	(arc
		(start 377.359418 -264.989818)
		(mid 377.546616 -264.939675)
		(end 377.733814 -264.989818)
		(width 0.0889)
		(layer "B.Cu")
		(net "NC_CPU0_LGSSPARE5")
	)
	(arc
		(start 367.961418 -264.989818)
		(mid 368.148616 -264.939675)
		(end 368.335814 -264.989818)
		(width 0.0889)
		(layer "B.Cu")
		(net "NC_CPU0_LGSSPARE5")
	)
	(arc
		(start 372.660418 -264.989818)
		(mid 372.847616 -264.939675)
		(end 373.034814 -264.989818)
		(width 0.0889)
		(layer "B.Cu")
		(net "NC_CPU0_LGSSPARE5")
	)
	(arc
		(start 373.974614 -264.989818)
		(mid 374.251173 -265.065561)
		(end 374.52935 -264.995914)
		(width 0.0889)
		(layer "B.Cu")
		(net "NC_CPU0_LGSSPARE5")
	)
	(arc
		(start 373.600218 -264.989818)
		(mid 373.787416 -264.939675)
		(end 373.974614 -264.989818)
		(width 0.0889)
		(layer "B.Cu")
		(net "NC_CPU0_LGSSPARE5")
	)
	(arc
		(start 371.720618 -264.989818)
		(mid 371.907816 -264.939675)
		(end 372.095014 -264.989818)
		(width 0.0889)
		(layer "B.Cu")
		(net "NC_CPU0_LGSSPARE5")
	)
	(segment
		(start 362.039916 -267.219938)
		(end 362.039662 -267.755878)
		(width 0.12954)
		(layer "F.Cu")
		(net "NC_CPU0_LGSSPARE4")
	)
	(via
		(at 362.039662 -267.755878)
		(size 0.4572)
		(drill 0.2032)
		(layers "F.Cu" "B.Cu")
		(net "NC_CPU0_LGSSPARE4")
	)
	(segment
		(start 362.979462 -266.128246)
		(end 362.979716 -265.592306)
		(width 0.12954)
		(layer "F.Cu")
		(net "NC_CPU0_LGSSPARE3")
	)
	(via
		(at 362.979462 -266.128246)
		(size 0.4572)
		(drill 0.2032)
		(layers "F.Cu" "B.Cu")
		(net "NC_CPU0_LGSSPARE3")
	)
	(segment
		(start 368.618516 -265.592306)
		(end 368.618262 -265.592306)
		(width 0.12954)
		(layer "F.Cu")
		(net "NC_CPU0_LGSSPARE2")
	)
	(segment
		(start 368.618262 -265.592306)
		(end 368.618262 -266.128246)
		(width 0.12954)
		(layer "F.Cu")
		(net "NC_CPU0_LGSSPARE2")
	)
	(via
		(at 368.618262 -266.128246)
		(size 0.4572)
		(drill 0.2032)
		(layers "F.Cu" "B.Cu")
		(net "NC_CPU0_LGSSPARE2")
	)
	(segment
		(start 366.738916 -263.96442)
		(end 366.738662 -263.964674)
		(width 0.12954)
		(layer "F.Cu")
		(net "NC_CPU0_LGSSPARE1")
	)
	(segment
		(start 366.738662 -263.964674)
		(end 366.738662 -264.50036)
		(width 0.12954)
		(layer "F.Cu")
		(net "NC_CPU0_LGSSPARE1")
	)
	(via
		(at 366.738662 -264.50036)
		(size 0.4572)
		(drill 0.2032)
		(layers "F.Cu" "B.Cu")
		(net "NC_CPU0_LGSSPARE1")
	)
	(segment
		(start 367.678462 -263.964674)
		(end 367.678716 -263.96442)
		(width 0.12954)
		(layer "F.Cu")
		(net "NC_CPU0_LGSSPARE0")
	)
	(segment
		(start 367.678462 -264.50036)
		(end 367.678462 -263.964674)
		(width 0.12954)
		(layer "F.Cu")
		(net "NC_CPU0_LGSSPARE0")
	)
	(via
		(at 367.678462 -264.50036)
		(size 0.4572)
		(drill 0.2032)
		(layers "F.Cu" "B.Cu")
		(net "NC_CPU0_LGSSPARE0")
	)
	(segment
		(start 356.401116 -263.96442)
		(end 356.401116 -264.50036)
		(width 0.12954)
		(layer "F.Cu")
		(net "NC_CPU0_HBM3_VIEWDIG1")
	)
	(via
		(at 356.401116 -264.50036)
		(size 0.4572)
		(drill 0.2032)
		(layers "F.Cu" "B.Cu")
		(net "NC_CPU0_HBM3_VIEWDIG1")
	)
	(segment
		(start 354.521516 -279.150318)
		(end 354.521516 -278.614378)
		(width 0.12954)
		(layer "F.Cu")
		(net "NC_CPU0_HBM3_VIEWDIG0")
	)
	(via
		(at 354.521516 -279.150318)
		(size 0.4572)
		(drill 0.2032)
		(layers "F.Cu" "B.Cu")
		(net "NC_CPU0_HBM3_VIEWDIG0")
	)
	(segment
		(start 343.243916 -278.614378)
		(end 343.243916 -279.150318)
		(width 0.12954)
		(layer "F.Cu")
		(net "NC_CPU0_HBM2_VIEWDIG0")
	)
	(via
		(at 343.243916 -279.150318)
		(size 0.4572)
		(drill 0.2032)
		(layers "F.Cu" "B.Cu")
		(net "NC_CPU0_HBM2_VIEWDIG0")
	)
	(segment
		(start 369.448334 -246.900446)
		(end 369.448334 -246.364506)
		(width 0.12954)
		(layer "F.Cu")
		(net "NC_CPU0_HBM1_VIEWDIG1")
	)
	(via
		(at 369.448334 -246.364506)
		(size 0.4572)
		(drill 0.2032)
		(layers "F.Cu" "B.Cu")
		(net "NC_CPU0_HBM1_VIEWDIG1")
	)
	(segment
		(start 341.254334 -227.367084)
		(end 341.254334 -226.831144)
		(width 0.12954)
		(layer "F.Cu")
		(net "NC_CPU0_HBM1_VIEWDIG0")
	)
	(via
		(at 341.254334 -226.831144)
		(size 0.4572)
		(drill 0.2032)
		(layers "F.Cu" "B.Cu")
		(net "NC_CPU0_HBM1_VIEWDIG0")
	)
	(segment
		(start 382.605534 -226.831398)
		(end 382.60528 -226.831144)
		(width 0.12954)
		(layer "F.Cu")
		(net "NC_CPU0_HBM0_VIEWDIG1")
	)
	(segment
		(start 382.605534 -227.367084)
		(end 382.605534 -226.831398)
		(width 0.12954)
		(layer "F.Cu")
		(net "NC_CPU0_HBM0_VIEWDIG1")
	)
	(via
		(at 382.60528 -226.831144)
		(size 0.4572)
		(drill 0.2032)
		(layers "F.Cu" "B.Cu")
		(net "NC_CPU0_HBM0_VIEWDIG1")
	)
	(segment
		(start 340.314534 -227.367084)
		(end 340.314534 -226.831144)
		(width 0.12954)
		(layer "F.Cu")
		(net "NC_CPU0_HBM0_VIEWDIG0")
	)
	(via
		(at 340.314534 -226.831144)
		(size 0.4572)
		(drill 0.2032)
		(layers "F.Cu" "B.Cu")
		(net "NC_CPU0_HBM0_VIEWDIG0")
	)
	(segment
		(start 360.05008 -230.086916)
		(end 360.050334 -230.086662)
		(width 0.12954)
		(layer "F.Cu")
		(net "NC_CPU0_DMI_APROBE<1>")
	)
	(segment
		(start 360.050334 -230.622602)
		(end 360.05008 -230.622348)
		(width 0.12954)
		(layer "F.Cu")
		(net "NC_CPU0_DMI_APROBE<1>")
	)
	(segment
		(start 360.05008 -230.622348)
		(end 360.05008 -230.086916)
		(width 0.12954)
		(layer "F.Cu")
		(net "NC_CPU0_DMI_APROBE<1>")
	)
	(via
		(at 360.050334 -230.086662)
		(size 0.4572)
		(drill 0.2032)
		(layers "F.Cu" "B.Cu")
		(net "NC_CPU0_DMI_APROBE<1>")
	)
	(segment
		(start 360.990134 -230.622602)
		(end 360.98988 -230.622348)
		(width 0.12954)
		(layer "F.Cu")
		(net "NC_CPU0_DMI_APROBE<0>")
	)
	(segment
		(start 360.98988 -230.622348)
		(end 360.98988 -230.086916)
		(width 0.12954)
		(layer "F.Cu")
		(net "NC_CPU0_DMI_APROBE<0>")
	)
	(segment
		(start 360.98988 -230.086916)
		(end 360.990134 -230.086662)
		(width 0.12954)
		(layer "F.Cu")
		(net "NC_CPU0_DMI_APROBE<0>")
	)
	(via
		(at 360.990134 -230.086662)
		(size 0.4572)
		(drill 0.2032)
		(layers "F.Cu" "B.Cu")
		(net "NC_CPU0_DMI_APROBE<0>")
	)
	(segment
		(start 370.38788 -249.620024)
		(end 370.38788 -250.15571)
		(width 0.20066)
		(layer "F.Cu")
		(net "NC_CPU0_DDR67_VIEWDIG0")
	)
	(segment
		(start 370.38788 -250.15571)
		(end 370.388134 -250.155964)
		(width 0.20066)
		(layer "F.Cu")
		(net "NC_CPU0_DDR67_VIEWDIG0")
	)
	(via
		(at 370.38788 -249.620024)
		(size 0.4572)
		(drill 0.2032)
		(layers "F.Cu" "B.Cu")
		(net "NC_CPU0_DDR67_VIEWDIG0")
	)
	(segment
		(start 369.91798 -243.922804)
		(end 369.91798 -244.458744)
		(width 0.129794)
		(layer "F.Cu")
		(net "NC_CPU0_DDR45_VIEWDIG1")
	)
	(via
		(at 369.91798 -243.922804)
		(size 0.4572)
		(drill 0.2032)
		(layers "F.Cu" "B.Cu")
		(net "NC_CPU0_DDR45_VIEWDIG1")
	)
	(segment
		(start 369.91798 -233.064304)
		(end 369.91798 -232.528618)
		(width 0.129794)
		(layer "F.Cu")
		(net "NC_CPU0_DDR45_VIEWDIG0")
	)
	(segment
		(start 369.91798 -232.528618)
		(end 369.918234 -232.528364)
		(width 0.129794)
		(layer "F.Cu")
		(net "NC_CPU0_DDR45_VIEWDIG0")
	)
	(via
		(at 369.918234 -232.528364)
		(size 0.4572)
		(drill 0.2032)
		(layers "F.Cu" "B.Cu")
		(net "NC_CPU0_DDR45_VIEWDIG0")
	)
	(segment
		(start 349.822262 -260.709156)
		(end 349.822262 -261.244842)
		(width 0.129794)
		(layer "F.Cu")
		(net "NC_CPU0_DDR01_VIEWDIG1")
	)
	(segment
		(start 349.822516 -260.708902)
		(end 349.822262 -260.709156)
		(width 0.129794)
		(layer "F.Cu")
		(net "NC_CPU0_DDR01_VIEWDIG1")
	)
	(via
		(at 349.822262 -261.244842)
		(size 0.4572)
		(drill 0.2032)
		(layers "F.Cu" "B.Cu")
		(net "NC_CPU0_DDR01_VIEWDIG1")
	)
	(segment
		(start 362.509562 -272.917158)
		(end 362.509562 -273.453098)
		(width 0.12954)
		(layer "F.Cu")
		(net "NC_CLK_PFT_OUT_CPU0_DP")
	)
	(via
		(at 362.509562 -273.453098)
		(size 0.4572)
		(drill 0.2032)
		(layers "F.Cu" "B.Cu")
		(net "NC_CLK_PFT_OUT_CPU0_DP")
	)
	(segment
		(start 362.979716 -272.639028)
		(end 362.979462 -272.639282)
		(width 0.12954)
		(layer "F.Cu")
		(net "NC_CLK_PFT_OUT_CPU0_DN")
	)
	(segment
		(start 362.979716 -272.103342)
		(end 362.979716 -272.639028)
		(width 0.12954)
		(layer "F.Cu")
		(net "NC_CLK_PFT_OUT_CPU0_DN")
	)
	(via
		(at 362.979462 -272.639282)
		(size 0.4572)
		(drill 0.2032)
		(layers "F.Cu" "B.Cu")
		(net "NC_CLK_PFT_OUT_CPU0_DN")
	)
	(segment
		(start 257.43281 -104.586532)
		(end 258.094226 -105.247948)
		(width 0.12954)
		(layer "F.Cu")
		(net "NC_CLK_CK440_MXCK3_DP")
	)
	(segment
		(start 258.094226 -105.247948)
		(end 258.19608 -105.247948)
		(width 0.12954)
		(layer "F.Cu")
		(net "NC_CLK_CK440_MXCK3_DP")
	)
	(segment
		(start 257.43281 -103.438198)
		(end 257.43281 -104.586532)
		(width 0.12954)
		(layer "F.Cu")
		(net "NC_CLK_CK440_MXCK3_DP")
	)
	(via
		(at 258.19608 -105.247948)
		(size 0.762)
		(drill 0.381)
		(layers "F.Cu" "B.Cu")
		(net "NC_CLK_CK440_MXCK3_DP")
	)
	(segment
		(start 257.932682 -103.438198)
		(end 257.932682 -103.75773)
		(width 0.12954)
		(layer "F.Cu")
		(net "NC_CLK_CK440_MXCK3_DN")
	)
	(segment
		(start 257.932682 -103.75773)
		(end 258.37388 -104.198928)
		(width 0.12954)
		(layer "F.Cu")
		(net "NC_CLK_CK440_MXCK3_DN")
	)
	(segment
		(start 258.37388 -104.198928)
		(end 258.37388 -104.562148)
		(width 0.12954)
		(layer "F.Cu")
		(net "NC_CLK_CK440_MXCK3_DN")
	)
	(segment
		(start 258.37388 -104.562148)
		(end 258.8895 -105.077768)
		(width 0.12954)
		(layer "F.Cu")
		(net "NC_CLK_CK440_MXCK3_DN")
	)
	(segment
		(start 258.8895 -105.077768)
		(end 259.92582 -105.077768)
		(width 0.12954)
		(layer "F.Cu")
		(net "NC_CLK_CK440_MXCK3_DN")
	)
	(via
		(at 259.92582 -105.077768)
		(size 0.762)
		(drill 0.381)
		(layers "F.Cu" "B.Cu")
		(net "NC_CLK_CK440_MXCK3_DN")
	)
	(segment
		(start 236.783372 -126.825756)
		(end 236.975396 -127.01778)
		(width 0.12954)
		(layer "F.Cu")
		(net "NC_CLK_100M_DB2000_NC10")
	)
	(segment
		(start 236.975396 -127.01778)
		(end 237.247938 -127.01778)
		(width 0.12954)
		(layer "F.Cu")
		(net "NC_CLK_100M_DB2000_NC10")
	)
	(via
		(at 236.783372 -126.825756)
		(size 0.49022)
		(drill 0.254)
		(layers "F.Cu" "B.Cu")
		(net "NC_CLK_100M_DB2000_NC10")
	)
	(segment
		(start 252.557788 -99.063302)
		(end 251.159518 -99.063302)
		(width 0.0889)
		(layer "F.Cu")
		(net "NC_CK440_B7")
	)
	(segment
		(start 249.48388 -99.159568)
		(end 249.137424 -99.506024)
		(width 0.1143)
		(layer "F.Cu")
		(net "NC_CK440_B7")
	)
	(segment
		(start 249.876564 -99.159568)
		(end 249.48388 -99.159568)
		(width 0.1143)
		(layer "F.Cu")
		(net "NC_CK440_B7")
	)
	(segment
		(start 250.111514 -98.924618)
		(end 249.876564 -99.159568)
		(width 0.1143)
		(layer "F.Cu")
		(net "NC_CK440_B7")
	)
	(segment
		(start 251.020834 -98.924618)
		(end 250.111514 -98.924618)
		(width 0.0889)
		(layer "F.Cu")
		(net "NC_CK440_B7")
	)
	(segment
		(start 251.159518 -99.063302)
		(end 251.020834 -98.924618)
		(width 0.0889)
		(layer "F.Cu")
		(net "NC_CK440_B7")
	)
	(segment
		(start 249.137424 -99.506024)
		(end 249.137424 -99.695508)
		(width 0.1143)
		(layer "F.Cu")
		(net "NC_CK440_B7")
	)
	(via
		(at 249.137424 -99.695508)
		(size 0.508)
		(drill 0.254)
		(layers "F.Cu" "B.Cu")
		(net "NC_CK440_B7")
	)
	(segment
		(start 259.585968 -103.481124)
		(end 260.60527 -103.481124)
		(width 0.12954)
		(layer "F.Cu")
		(net "NC_CK440_B34")
	)
	(segment
		(start 258.79298 -102.688136)
		(end 259.585968 -103.481124)
		(width 0.12954)
		(layer "F.Cu")
		(net "NC_CK440_B34")
	)
	(segment
		(start 258.182872 -102.688136)
		(end 258.79298 -102.688136)
		(width 0.12954)
		(layer "F.Cu")
		(net "NC_CK440_B34")
	)
	(segment
		(start 260.60527 -103.481124)
		(end 261.89051 -104.766364)
		(width 0.12954)
		(layer "F.Cu")
		(net "NC_CK440_B34")
	)
	(segment
		(start 261.89051 -104.766364)
		(end 261.89051 -106.425746)
		(width 0.12954)
		(layer "F.Cu")
		(net "NC_CK440_B34")
	)
	(via
		(at 261.89051 -106.425746)
		(size 0.762)
		(drill 0.381)
		(layers "F.Cu" "B.Cu")
		(net "NC_CK440_B34")
	)
	(segment
		(start 263.474962 -104.375204)
		(end 264.173716 -104.375204)
		(width 0.12954)
		(layer "F.Cu")
		(net "NC_CK440_B33")
	)
	(segment
		(start 260.48335 -102.540816)
		(end 261.640574 -102.540816)
		(width 0.12954)
		(layer "F.Cu")
		(net "NC_CK440_B33")
	)
	(segment
		(start 264.390886 -104.592374)
		(end 264.390886 -106.208576)
		(width 0.12954)
		(layer "F.Cu")
		(net "NC_CK440_B33")
	)
	(segment
		(start 264.173716 -106.425746)
		(end 263.92251 -106.425746)
		(width 0.12954)
		(layer "F.Cu")
		(net "NC_CK440_B33")
	)
	(segment
		(start 261.640574 -102.540816)
		(end 263.474962 -104.375204)
		(width 0.12954)
		(layer "F.Cu")
		(net "NC_CK440_B33")
	)
	(segment
		(start 260.00583 -102.063296)
		(end 260.294882 -102.352348)
		(width 0.0889)
		(layer "F.Cu")
		(net "NC_CK440_B33")
	)
	(segment
		(start 264.173716 -104.375204)
		(end 264.390886 -104.592374)
		(width 0.12954)
		(layer "F.Cu")
		(net "NC_CK440_B33")
	)
	(segment
		(start 264.390886 -106.208576)
		(end 264.173716 -106.425746)
		(width 0.12954)
		(layer "F.Cu")
		(net "NC_CK440_B33")
	)
	(segment
		(start 258.807712 -102.063296)
		(end 260.00583 -102.063296)
		(width 0.0889)
		(layer "F.Cu")
		(net "NC_CK440_B33")
	)
	(segment
		(start 260.294882 -102.352348)
		(end 260.48335 -102.540816)
		(width 0.12954)
		(layer "F.Cu")
		(net "NC_CK440_B33")
	)
	(via
		(at 263.92251 -106.425746)
		(size 0.762)
		(drill 0.381)
		(layers "F.Cu" "B.Cu")
		(net "NC_CK440_B33")
	)
	(segment
		(start 252.43282 -96.136206)
		(end 252.651006 -96.354392)
		(width 0.12954)
		(layer "F.Cu")
		(net "NC_CK440_A15")
	)
	(segment
		(start 252.43282 -95.68815)
		(end 252.43282 -96.136206)
		(width 0.12954)
		(layer "F.Cu")
		(net "NC_CK440_A15")
	)
	(via
		(at 252.450854 -95.642176)
		(size 0.6604)
		(drill 0.3302)
		(layers "F.Cu" "B.Cu")
		(net "NC_CK440_A15")
	)
	(via
		(at 252.651006 -96.354392)
		(size 0.508)
		(drill 0.254)
		(layers "F.Cu" "B.Cu")
		(net "NC_CK440_A15")
	)
	(segment
		(start 252.651006 -96.354392)
		(end 252.651006 -95.842328)
		(width 0.12954)
		(layer "B.Cu")
		(net "NC_CK440_A15")
	)
	(segment
		(start 252.651006 -95.842328)
		(end 252.450854 -95.642176)
		(width 0.12954)
		(layer "B.Cu")
		(net "NC_CK440_A15")
	)
	(segment
		(start 448.87388 -6.848348)
		(end 448.961764 -6.936232)
		(width 0.12954)
		(layer "F.Cu")
		(net "NCSI_OCP_SFF_TX_EN")
	)
	(segment
		(start 366.42294 -82.187288)
		(end 357.422196 -91.188032)
		(width 0.12954)
		(layer "F.Cu")
		(net "NCSI_OCP_SFF_TX_EN")
	)
	(segment
		(start 419.170104 -55.829708)
		(end 416.425126 -58.574686)
		(width 0.12954)
		(layer "F.Cu")
		(net "NCSI_OCP_SFF_TX_EN")
	)
	(segment
		(start 215.923622 -77.17409)
		(end 215.923622 -72.80275)
		(width 0.12954)
		(layer "F.Cu")
		(net "NCSI_OCP_SFF_TX_EN")
	)
	(segment
		(start 299.791628 -86.611968)
		(end 282.1051 -86.611968)
		(width 0.12954)
		(layer "F.Cu")
		(net "NCSI_OCP_SFF_TX_EN")
	)
	(segment
		(start 416.425126 -58.574686)
		(end 413.679894 -65.202054)
		(width 0.12954)
		(layer "F.Cu")
		(net "NCSI_OCP_SFF_TX_EN")
	)
	(segment
		(start 304.367692 -91.188032)
		(end 299.791628 -86.611968)
		(width 0.12954)
		(layer "F.Cu")
		(net "NCSI_OCP_SFF_TX_EN")
	)
	(segment
		(start 426.464476 -55.176674)
		(end 426.301662 -55.176674)
		(width 0.12954)
		(layer "F.Cu")
		(net "NCSI_OCP_SFF_TX_EN")
	)
	(segment
		(start 238.60506 -88.262968)
		(end 227.0125 -88.262968)
		(width 0.12954)
		(layer "F.Cu")
		(net "NCSI_OCP_SFF_TX_EN")
	)
	(segment
		(start 422.195498 -54.576472)
		(end 419.170104 -55.829708)
		(width 0.12954)
		(layer "F.Cu")
		(net "NCSI_OCP_SFF_TX_EN")
	)
	(segment
		(start 252.963172 -83.450176)
		(end 251.92355 -82.410554)
		(width 0.12954)
		(layer "F.Cu")
		(net "NCSI_OCP_SFF_TX_EN")
	)
	(segment
		(start 426.301662 -55.176674)
		(end 425.70146 -54.576472)
		(width 0.12954)
		(layer "F.Cu")
		(net "NCSI_OCP_SFF_TX_EN")
	)
	(segment
		(start 282.1051 -86.611968)
		(end 278.943308 -83.450176)
		(width 0.12954)
		(layer "F.Cu")
		(net "NCSI_OCP_SFF_TX_EN")
	)
	(segment
		(start 396.69466 -82.187288)
		(end 366.42294 -82.187288)
		(width 0.12954)
		(layer "F.Cu")
		(net "NCSI_OCP_SFF_TX_EN")
	)
	(segment
		(start 413.679894 -65.202054)
		(end 396.69466 -82.187288)
		(width 0.12954)
		(layer "F.Cu")
		(net "NCSI_OCP_SFF_TX_EN")
	)
	(segment
		(start 278.943308 -83.450176)
		(end 252.963172 -83.450176)
		(width 0.12954)
		(layer "F.Cu")
		(net "NCSI_OCP_SFF_TX_EN")
	)
	(segment
		(start 357.422196 -91.188032)
		(end 304.367692 -91.188032)
		(width 0.12954)
		(layer "F.Cu")
		(net "NCSI_OCP_SFF_TX_EN")
	)
	(segment
		(start 448.961764 -6.936232)
		(end 448.961764 -8.320024)
		(width 0.12954)
		(layer "F.Cu")
		(net "NCSI_OCP_SFF_TX_EN")
	)
	(segment
		(start 244.457474 -82.410554)
		(end 238.60506 -88.262968)
		(width 0.12954)
		(layer "F.Cu")
		(net "NCSI_OCP_SFF_TX_EN")
	)
	(segment
		(start 251.92355 -82.410554)
		(end 244.457474 -82.410554)
		(width 0.12954)
		(layer "F.Cu")
		(net "NCSI_OCP_SFF_TX_EN")
	)
	(segment
		(start 227.0125 -88.262968)
		(end 215.923622 -77.17409)
		(width 0.12954)
		(layer "F.Cu")
		(net "NCSI_OCP_SFF_TX_EN")
	)
	(segment
		(start 425.70146 -54.576472)
		(end 422.195498 -54.576472)
		(width 0.12954)
		(layer "F.Cu")
		(net "NCSI_OCP_SFF_TX_EN")
	)
	(via
		(at 426.464476 -55.176674)
		(size 0.762)
		(drill 0.254)
		(layers "F.Cu" "B.Cu")
		(net "NCSI_OCP_SFF_TX_EN")
	)
	(via
		(at 215.923622 -72.80275)
		(size 0.508)
		(drill 0.254)
		(layers "F.Cu" "B.Cu")
		(net "NCSI_OCP_SFF_TX_EN")
	)
	(via
		(at 448.87388 -6.848348)
		(size 0.508)
		(drill 0.254)
		(layers "F.Cu" "B.Cu")
		(net "NCSI_OCP_SFF_TX_EN")
	)
	(segment
		(start 214.757 -72.80275)
		(end 215.923622 -72.80275)
		(width 0.12954)
		(layer "B.Cu")
		(net "NCSI_OCP_SFF_TX_EN")
	)
	(segment
		(start 432.3588 -44.872148)
		(end 432.2318 -44.999148)
		(width 0.127)
		(layer "In2.Cu")
		(net "NCSI_OCP_SFF_TX_EN")
	)
	(segment
		(start 432.2318 -45.636688)
		(end 432.3588 -45.763688)
		(width 0.127)
		(layer "In2.Cu")
		(net "NCSI_OCP_SFF_TX_EN")
	)
	(segment
		(start 432.2318 -48.824388)
		(end 431.04816 -48.824388)
		(width 0.127)
		(layer "In2.Cu")
		(net "NCSI_OCP_SFF_TX_EN")
	)
	(segment
		(start 431.83048 -46.274228)
		(end 431.70348 -46.401228)
		(width 0.127)
		(layer "In2.Cu")
		(net "NCSI_OCP_SFF_TX_EN")
	)
	(segment
		(start 443.45098 -14.01064)
		(end 431.70348 -25.75814)
		(width 0.127)
		(layer "In2.Cu")
		(net "NCSI_OCP_SFF_TX_EN")
	)
	(segment
		(start 432.3588 -45.763688)
		(end 432.3588 -46.147228)
		(width 0.127)
		(layer "In2.Cu")
		(net "NCSI_OCP_SFF_TX_EN")
	)
	(segment
		(start 431.83048 -47.549308)
		(end 431.70348 -47.676308)
		(width 0.127)
		(layer "In2.Cu")
		(net "NCSI_OCP_SFF_TX_EN")
	)
	(segment
		(start 431.83048 -43.086528)
		(end 432.2318 -43.086528)
		(width 0.127)
		(layer "In2.Cu")
		(net "NCSI_OCP_SFF_TX_EN")
	)
	(segment
		(start 432.2318 -44.999148)
		(end 431.83048 -44.999148)
		(width 0.127)
		(layer "In2.Cu")
		(net "NCSI_OCP_SFF_TX_EN")
	)
	(segment
		(start 431.70348 -46.401228)
		(end 431.70348 -46.784768)
		(width 0.127)
		(layer "In2.Cu")
		(net "NCSI_OCP_SFF_TX_EN")
	)
	(segment
		(start 431.70348 -45.509688)
		(end 431.83048 -45.636688)
		(width 0.127)
		(layer "In2.Cu")
		(net "NCSI_OCP_SFF_TX_EN")
	)
	(segment
		(start 432.3588 -47.038768)
		(end 432.3588 -47.422308)
		(width 0.127)
		(layer "In2.Cu")
		(net "NCSI_OCP_SFF_TX_EN")
	)
	(segment
		(start 432.2318 -46.911768)
		(end 432.3588 -47.038768)
		(width 0.127)
		(layer "In2.Cu")
		(net "NCSI_OCP_SFF_TX_EN")
	)
	(segment
		(start 431.83048 -46.911768)
		(end 432.2318 -46.911768)
		(width 0.127)
		(layer "In2.Cu")
		(net "NCSI_OCP_SFF_TX_EN")
	)
	(segment
		(start 432.2318 -43.086528)
		(end 432.3588 -43.213528)
		(width 0.127)
		(layer "In2.Cu")
		(net "NCSI_OCP_SFF_TX_EN")
	)
	(segment
		(start 432.2318 -43.724068)
		(end 431.83048 -43.724068)
		(width 0.127)
		(layer "In2.Cu")
		(net "NCSI_OCP_SFF_TX_EN")
	)
	(segment
		(start 431.83048 -44.999148)
		(end 431.70348 -45.126148)
		(width 0.127)
		(layer "In2.Cu")
		(net "NCSI_OCP_SFF_TX_EN")
	)
	(segment
		(start 432.3588 -43.597068)
		(end 432.2318 -43.724068)
		(width 0.127)
		(layer "In2.Cu")
		(net "NCSI_OCP_SFF_TX_EN")
	)
	(segment
		(start 432.2318 -48.186848)
		(end 432.3588 -48.313848)
		(width 0.127)
		(layer "In2.Cu")
		(net "NCSI_OCP_SFF_TX_EN")
	)
	(segment
		(start 432.2318 -47.549308)
		(end 431.83048 -47.549308)
		(width 0.127)
		(layer "In2.Cu")
		(net "NCSI_OCP_SFF_TX_EN")
	)
	(segment
		(start 431.83048 -43.724068)
		(end 431.70348 -43.851068)
		(width 0.127)
		(layer "In2.Cu")
		(net "NCSI_OCP_SFF_TX_EN")
	)
	(segment
		(start 445.425576 -5.580888)
		(end 443.45098 -7.555484)
		(width 0.127)
		(layer "In2.Cu")
		(net "NCSI_OCP_SFF_TX_EN")
	)
	(segment
		(start 431.83048 -45.636688)
		(end 432.2318 -45.636688)
		(width 0.127)
		(layer "In2.Cu")
		(net "NCSI_OCP_SFF_TX_EN")
	)
	(segment
		(start 432.3588 -47.422308)
		(end 432.2318 -47.549308)
		(width 0.127)
		(layer "In2.Cu")
		(net "NCSI_OCP_SFF_TX_EN")
	)
	(segment
		(start 431.70348 -46.784768)
		(end 431.83048 -46.911768)
		(width 0.127)
		(layer "In2.Cu")
		(net "NCSI_OCP_SFF_TX_EN")
	)
	(segment
		(start 431.70348 -25.75814)
		(end 431.70348 -42.959528)
		(width 0.127)
		(layer "In2.Cu")
		(net "NCSI_OCP_SFF_TX_EN")
	)
	(segment
		(start 432.3588 -43.213528)
		(end 432.3588 -43.597068)
		(width 0.127)
		(layer "In2.Cu")
		(net "NCSI_OCP_SFF_TX_EN")
	)
	(segment
		(start 431.70348 -44.234608)
		(end 431.83048 -44.361608)
		(width 0.127)
		(layer "In2.Cu")
		(net "NCSI_OCP_SFF_TX_EN")
	)
	(segment
		(start 431.83048 -48.186848)
		(end 432.2318 -48.186848)
		(width 0.127)
		(layer "In2.Cu")
		(net "NCSI_OCP_SFF_TX_EN")
	)
	(segment
		(start 431.70348 -42.959528)
		(end 431.83048 -43.086528)
		(width 0.127)
		(layer "In2.Cu")
		(net "NCSI_OCP_SFF_TX_EN")
	)
	(segment
		(start 448.361308 -6.848348)
		(end 447.093848 -5.580888)
		(width 0.127)
		(layer "In2.Cu")
		(net "NCSI_OCP_SFF_TX_EN")
	)
	(segment
		(start 443.45098 -7.555484)
		(end 443.45098 -14.01064)
		(width 0.127)
		(layer "In2.Cu")
		(net "NCSI_OCP_SFF_TX_EN")
	)
	(segment
		(start 448.87388 -6.848348)
		(end 448.361308 -6.848348)
		(width 0.127)
		(layer "In2.Cu")
		(net "NCSI_OCP_SFF_TX_EN")
	)
	(segment
		(start 432.2318 -44.361608)
		(end 432.3588 -44.488608)
		(width 0.127)
		(layer "In2.Cu")
		(net "NCSI_OCP_SFF_TX_EN")
	)
	(segment
		(start 432.3588 -48.697388)
		(end 432.2318 -48.824388)
		(width 0.127)
		(layer "In2.Cu")
		(net "NCSI_OCP_SFF_TX_EN")
	)
	(segment
		(start 431.70348 -45.126148)
		(end 431.70348 -45.509688)
		(width 0.127)
		(layer "In2.Cu")
		(net "NCSI_OCP_SFF_TX_EN")
	)
	(segment
		(start 426.802804 -54.838346)
		(end 426.464476 -55.176674)
		(width 0.127)
		(layer "In2.Cu")
		(net "NCSI_OCP_SFF_TX_EN")
	)
	(segment
		(start 426.802804 -53.069744)
		(end 426.802804 -54.838346)
		(width 0.127)
		(layer "In2.Cu")
		(net "NCSI_OCP_SFF_TX_EN")
	)
	(segment
		(start 447.093848 -5.580888)
		(end 445.425576 -5.580888)
		(width 0.127)
		(layer "In2.Cu")
		(net "NCSI_OCP_SFF_TX_EN")
	)
	(segment
		(start 431.70348 -43.851068)
		(end 431.70348 -44.234608)
		(width 0.127)
		(layer "In2.Cu")
		(net "NCSI_OCP_SFF_TX_EN")
	)
	(segment
		(start 432.3588 -48.313848)
		(end 432.3588 -48.697388)
		(width 0.127)
		(layer "In2.Cu")
		(net "NCSI_OCP_SFF_TX_EN")
	)
	(segment
		(start 431.04816 -48.824388)
		(end 426.802804 -53.069744)
		(width 0.127)
		(layer "In2.Cu")
		(net "NCSI_OCP_SFF_TX_EN")
	)
	(segment
		(start 432.3588 -46.147228)
		(end 432.2318 -46.274228)
		(width 0.127)
		(layer "In2.Cu")
		(net "NCSI_OCP_SFF_TX_EN")
	)
	(segment
		(start 431.70348 -47.676308)
		(end 431.70348 -48.059848)
		(width 0.127)
		(layer "In2.Cu")
		(net "NCSI_OCP_SFF_TX_EN")
	)
	(segment
		(start 432.3588 -44.488608)
		(end 432.3588 -44.872148)
		(width 0.127)
		(layer "In2.Cu")
		(net "NCSI_OCP_SFF_TX_EN")
	)
	(segment
		(start 432.2318 -46.274228)
		(end 431.83048 -46.274228)
		(width 0.127)
		(layer "In2.Cu")
		(net "NCSI_OCP_SFF_TX_EN")
	)
	(segment
		(start 431.70348 -48.059848)
		(end 431.83048 -48.186848)
		(width 0.127)
		(layer "In2.Cu")
		(net "NCSI_OCP_SFF_TX_EN")
	)
	(segment
		(start 431.83048 -44.361608)
		(end 432.2318 -44.361608)
		(width 0.127)
		(layer "In2.Cu")
		(net "NCSI_OCP_SFF_TX_EN")
	)
	(segment
		(start 424.839384 -56.017414)
		(end 424.683936 -55.861966)
		(width 0.12954)
		(layer "F.Cu")
		(net "NCSI_OCP_SFF_TXD1")
	)
	(segment
		(start 422.027096 -55.861966)
		(end 420.283132 -56.584342)
		(width 0.12954)
		(layer "F.Cu")
		(net "NCSI_OCP_SFF_TXD1")
	)
	(segment
		(start 303.893982 -92.331032)
		(end 299.317918 -87.754968)
		(width 0.12954)
		(layer "F.Cu")
		(net "NCSI_OCP_SFF_TXD1")
	)
	(segment
		(start 251.320046 -83.534758)
		(end 244.921532 -83.534758)
		(width 0.12954)
		(layer "F.Cu")
		(net "NCSI_OCP_SFF_TXD1")
	)
	(segment
		(start 417.643818 -59.223656)
		(end 415.121344 -65.313306)
		(width 0.12954)
		(layer "F.Cu")
		(net "NCSI_OCP_SFF_TXD1")
	)
	(segment
		(start 415.121344 -65.313306)
		(end 397.215106 -83.219544)
		(width 0.12954)
		(layer "F.Cu")
		(net "NCSI_OCP_SFF_TXD1")
	)
	(segment
		(start 278.447246 -84.745576)
		(end 252.530864 -84.745576)
		(width 0.12954)
		(layer "F.Cu")
		(net "NCSI_OCP_SFF_TXD1")
	)
	(segment
		(start 226.216718 -89.284048)
		(end 214.393018 -77.460348)
		(width 0.12954)
		(layer "F.Cu")
		(net "NCSI_OCP_SFF_TXD1")
	)
	(segment
		(start 358.045258 -92.331032)
		(end 303.893982 -92.331032)
		(width 0.12954)
		(layer "F.Cu")
		(net "NCSI_OCP_SFF_TXD1")
	)
	(segment
		(start 206.043784 -70.399148)
		(end 207.31988 -70.399148)
		(width 0.12954)
		(layer "F.Cu")
		(net "NCSI_OCP_SFF_TXD1")
	)
	(segment
		(start 205.50251 -72.905874)
		(end 205.50251 -70.940422)
		(width 0.12954)
		(layer "F.Cu")
		(net "NCSI_OCP_SFF_TXD1")
	)
	(segment
		(start 299.317918 -87.754968)
		(end 281.456638 -87.754968)
		(width 0.12954)
		(layer "F.Cu")
		(net "NCSI_OCP_SFF_TXD1")
	)
	(segment
		(start 244.921532 -83.534758)
		(end 239.172242 -89.284048)
		(width 0.12954)
		(layer "F.Cu")
		(net "NCSI_OCP_SFF_TXD1")
	)
	(segment
		(start 448.361816 -8.320024)
		(end 448.370452 -8.311388)
		(width 0.12954)
		(layer "F.Cu")
		(net "NCSI_OCP_SFF_TXD1")
	)
	(segment
		(start 397.215106 -83.219544)
		(end 367.156746 -83.219544)
		(width 0.12954)
		(layer "F.Cu")
		(net "NCSI_OCP_SFF_TXD1")
	)
	(segment
		(start 420.283132 -56.584342)
		(end 417.643818 -59.223656)
		(width 0.12954)
		(layer "F.Cu")
		(net "NCSI_OCP_SFF_TXD1")
	)
	(segment
		(start 205.50251 -70.940422)
		(end 206.043784 -70.399148)
		(width 0.12954)
		(layer "F.Cu")
		(net "NCSI_OCP_SFF_TXD1")
	)
	(segment
		(start 210.056984 -77.460348)
		(end 205.50251 -72.905874)
		(width 0.12954)
		(layer "F.Cu")
		(net "NCSI_OCP_SFF_TXD1")
	)
	(segment
		(start 424.683936 -55.861966)
		(end 422.027096 -55.861966)
		(width 0.12954)
		(layer "F.Cu")
		(net "NCSI_OCP_SFF_TXD1")
	)
	(segment
		(start 239.172242 -89.284048)
		(end 226.216718 -89.284048)
		(width 0.12954)
		(layer "F.Cu")
		(net "NCSI_OCP_SFF_TXD1")
	)
	(segment
		(start 214.393018 -77.460348)
		(end 210.056984 -77.460348)
		(width 0.12954)
		(layer "F.Cu")
		(net "NCSI_OCP_SFF_TXD1")
	)
	(segment
		(start 448.370452 -8.311388)
		(end 448.370452 -5.603748)
		(width 0.12954)
		(layer "F.Cu")
		(net "NCSI_OCP_SFF_TXD1")
	)
	(segment
		(start 281.456638 -87.754968)
		(end 278.447246 -84.745576)
		(width 0.12954)
		(layer "F.Cu")
		(net "NCSI_OCP_SFF_TXD1")
	)
	(segment
		(start 252.530864 -84.745576)
		(end 251.320046 -83.534758)
		(width 0.12954)
		(layer "F.Cu")
		(net "NCSI_OCP_SFF_TXD1")
	)
	(segment
		(start 367.156746 -83.219544)
		(end 358.045258 -92.331032)
		(width 0.12954)
		(layer "F.Cu")
		(net "NCSI_OCP_SFF_TXD1")
	)
	(via
		(at 207.31988 -70.399148)
		(size 0.508)
		(drill 0.254)
		(layers "F.Cu" "B.Cu")
		(net "NCSI_OCP_SFF_TXD1")
	)
	(via
		(at 424.839384 -56.017414)
		(size 0.762)
		(drill 0.254)
		(layers "F.Cu" "B.Cu")
		(net "NCSI_OCP_SFF_TXD1")
	)
	(via
		(at 448.370452 -5.603748)
		(size 0.508)
		(drill 0.254)
		(layers "F.Cu" "B.Cu")
		(net "NCSI_OCP_SFF_TXD1")
	)
	(segment
		(start 207.516222 -70.202806)
		(end 208.915 -70.202806)
		(width 0.12954)
		(layer "B.Cu")
		(net "NCSI_OCP_SFF_TXD1")
	)
	(segment
		(start 207.31988 -70.399148)
		(end 207.516222 -70.202806)
		(width 0.12954)
		(layer "B.Cu")
		(net "NCSI_OCP_SFF_TXD1")
	)
	(segment
		(start 441.46724 -8.316976)
		(end 441.46724 -14.772386)
		(width 0.127)
		(layer "In2.Cu")
		(net "NCSI_OCP_SFF_TXD1")
	)
	(segment
		(start 424.359324 -55.537354)
		(end 424.839384 -56.017414)
		(width 0.127)
		(layer "In2.Cu")
		(net "NCSI_OCP_SFF_TXD1")
	)
	(segment
		(start 430.83988 -46.089824)
		(end 424.359324 -52.57038)
		(width 0.127)
		(layer "In2.Cu")
		(net "NCSI_OCP_SFF_TXD1")
	)
	(segment
		(start 447.57848 -4.671568)
		(end 445.112648 -4.671568)
		(width 0.127)
		(layer "In2.Cu")
		(net "NCSI_OCP_SFF_TXD1")
	)
	(segment
		(start 445.112648 -4.671568)
		(end 441.46724 -8.316976)
		(width 0.127)
		(layer "In2.Cu")
		(net "NCSI_OCP_SFF_TXD1")
	)
	(segment
		(start 430.83988 -25.399746)
		(end 430.83988 -46.089824)
		(width 0.127)
		(layer "In2.Cu")
		(net "NCSI_OCP_SFF_TXD1")
	)
	(segment
		(start 441.46724 -14.772386)
		(end 430.83988 -25.399746)
		(width 0.127)
		(layer "In2.Cu")
		(net "NCSI_OCP_SFF_TXD1")
	)
	(segment
		(start 424.359324 -52.57038)
		(end 424.359324 -55.537354)
		(width 0.127)
		(layer "In2.Cu")
		(net "NCSI_OCP_SFF_TXD1")
	)
	(segment
		(start 448.370452 -5.46354)
		(end 447.57848 -4.671568)
		(width 0.127)
		(layer "In2.Cu")
		(net "NCSI_OCP_SFF_TXD1")
	)
	(segment
		(start 448.370452 -5.603748)
		(end 448.370452 -5.46354)
		(width 0.127)
		(layer "In2.Cu")
		(net "NCSI_OCP_SFF_TXD1")
	)
	(segment
		(start 419.819074 -56.222138)
		(end 417.01085 -59.030362)
		(width 0.12954)
		(layer "F.Cu")
		(net "NCSI_OCP_SFF_TXD0")
	)
	(segment
		(start 447.770504 -7.128256)
		(end 447.65468 -7.012432)
		(width 0.12954)
		(layer "F.Cu")
		(net "NCSI_OCP_SFF_TXD0")
	)
	(segment
		(start 210.805776 -76.876148)
		(end 209.78622 -75.856592)
		(width 0.12954)
		(layer "F.Cu")
		(net "NCSI_OCP_SFF_TXD0")
	)
	(segment
		(start 447.761868 -8.320024)
		(end 447.761868 -7.4041)
		(width 0.12954)
		(layer "F.Cu")
		(net "NCSI_OCP_SFF_TXD0")
	)
	(segment
		(start 447.65468 -7.012432)
		(end 447.65468 -5.476748)
		(width 0.12954)
		(layer "F.Cu")
		(net "NCSI_OCP_SFF_TXD0")
	)
	(segment
		(start 366.841024 -82.709004)
		(end 357.803196 -91.746832)
		(width 0.12954)
		(layer "F.Cu")
		(net "NCSI_OCP_SFF_TXD0")
	)
	(segment
		(start 422.188894 -55.240428)
		(end 419.819074 -56.222138)
		(width 0.12954)
		(layer "F.Cu")
		(net "NCSI_OCP_SFF_TXD0")
	)
	(segment
		(start 447.761868 -7.4041)
		(end 447.770504 -7.395464)
		(width 0.12954)
		(layer "F.Cu")
		(net "NCSI_OCP_SFF_TXD0")
	)
	(segment
		(start 299.55998 -87.170768)
		(end 281.6987 -87.170768)
		(width 0.12954)
		(layer "F.Cu")
		(net "NCSI_OCP_SFF_TXD0")
	)
	(segment
		(start 304.136044 -91.746832)
		(end 299.55998 -87.170768)
		(width 0.12954)
		(layer "F.Cu")
		(net "NCSI_OCP_SFF_TXD0")
	)
	(segment
		(start 251.614686 -82.999326)
		(end 244.630702 -82.999326)
		(width 0.12954)
		(layer "F.Cu")
		(net "NCSI_OCP_SFF_TXD0")
	)
	(segment
		(start 425.079668 -55.113174)
		(end 424.952414 -55.240428)
		(width 0.12954)
		(layer "F.Cu")
		(net "NCSI_OCP_SFF_TXD0")
	)
	(segment
		(start 214.63508 -76.876148)
		(end 210.805776 -76.876148)
		(width 0.12954)
		(layer "F.Cu")
		(net "NCSI_OCP_SFF_TXD0")
	)
	(segment
		(start 238.85652 -88.773508)
		(end 226.53244 -88.773508)
		(width 0.12954)
		(layer "F.Cu")
		(net "NCSI_OCP_SFF_TXD0")
	)
	(segment
		(start 424.952414 -55.240428)
		(end 422.188894 -55.240428)
		(width 0.12954)
		(layer "F.Cu")
		(net "NCSI_OCP_SFF_TXD0")
	)
	(segment
		(start 244.630702 -82.999326)
		(end 238.85652 -88.773508)
		(width 0.12954)
		(layer "F.Cu")
		(net "NCSI_OCP_SFF_TXD0")
	)
	(segment
		(start 357.803196 -91.746832)
		(end 304.136044 -91.746832)
		(width 0.12954)
		(layer "F.Cu")
		(net "NCSI_OCP_SFF_TXD0")
	)
	(segment
		(start 396.899384 -82.709004)
		(end 366.841024 -82.709004)
		(width 0.12954)
		(layer "F.Cu")
		(net "NCSI_OCP_SFF_TXD0")
	)
	(segment
		(start 417.01085 -59.030362)
		(end 414.488376 -65.120012)
		(width 0.12954)
		(layer "F.Cu")
		(net "NCSI_OCP_SFF_TXD0")
	)
	(segment
		(start 281.6987 -87.170768)
		(end 278.689308 -84.161376)
		(width 0.12954)
		(layer "F.Cu")
		(net "NCSI_OCP_SFF_TXD0")
	)
	(segment
		(start 252.776736 -84.161376)
		(end 251.614686 -82.999326)
		(width 0.12954)
		(layer "F.Cu")
		(net "NCSI_OCP_SFF_TXD0")
	)
	(segment
		(start 278.689308 -84.161376)
		(end 252.776736 -84.161376)
		(width 0.12954)
		(layer "F.Cu")
		(net "NCSI_OCP_SFF_TXD0")
	)
	(segment
		(start 447.770504 -7.395464)
		(end 447.770504 -7.128256)
		(width 0.12954)
		(layer "F.Cu")
		(net "NCSI_OCP_SFF_TXD0")
	)
	(segment
		(start 226.53244 -88.773508)
		(end 214.63508 -76.876148)
		(width 0.12954)
		(layer "F.Cu")
		(net "NCSI_OCP_SFF_TXD0")
	)
	(segment
		(start 209.78622 -75.856592)
		(end 209.78622 -75.324208)
		(width 0.12954)
		(layer "F.Cu")
		(net "NCSI_OCP_SFF_TXD0")
	)
	(segment
		(start 414.488376 -65.120012)
		(end 396.899384 -82.709004)
		(width 0.12954)
		(layer "F.Cu")
		(net "NCSI_OCP_SFF_TXD0")
	)
	(segment
		(start 425.305728 -55.113174)
		(end 425.079668 -55.113174)
		(width 0.12954)
		(layer "F.Cu")
		(net "NCSI_OCP_SFF_TXD0")
	)
	(segment
		(start 209.78622 -75.324208)
		(end 210.74888 -74.361548)
		(width 0.12954)
		(layer "F.Cu")
		(net "NCSI_OCP_SFF_TXD0")
	)
	(via
		(at 210.74888 -74.361548)
		(size 0.508)
		(drill 0.254)
		(layers "F.Cu" "B.Cu")
		(net "NCSI_OCP_SFF_TXD0")
	)
	(via
		(at 447.65468 -5.476748)
		(size 0.508)
		(drill 0.254)
		(layers "F.Cu" "B.Cu")
		(net "NCSI_OCP_SFF_TXD0")
	)
	(via
		(at 425.305728 -55.113174)
		(size 0.508)
		(drill 0.254)
		(layers "F.Cu" "B.Cu")
		(net "NCSI_OCP_SFF_TXD0")
	)
	(segment
		(start 211.12988 -73.025508)
		(end 210.257136 -72.152764)
		(width 0.12954)
		(layer "B.Cu")
		(net "NCSI_OCP_SFF_TXD0")
	)
	(segment
		(start 210.74888 -74.361548)
		(end 211.12988 -73.980548)
		(width 0.12954)
		(layer "B.Cu")
		(net "NCSI_OCP_SFF_TXD0")
	)
	(segment
		(start 210.257136 -72.152764)
		(end 208.915 -72.152764)
		(width 0.12954)
		(layer "B.Cu")
		(net "NCSI_OCP_SFF_TXD0")
	)
	(segment
		(start 211.12988 -73.980548)
		(end 211.12988 -73.025508)
		(width 0.12954)
		(layer "B.Cu")
		(net "NCSI_OCP_SFF_TXD0")
	)
	(segment
		(start 427.947074 -49.868582)
		(end 427.515528 -50.300128)
		(width 0.127)
		(layer "In2.Cu")
		(net "NCSI_OCP_SFF_TXD0")
	)
	(segment
		(start 442.030612 -11.030204)
		(end 441.903612 -11.157204)
		(width 0.127)
		(layer "In2.Cu")
		(net "NCSI_OCP_SFF_TXD0")
	)
	(segment
		(start 442.8617 -12.178284)
		(end 442.7347 -12.305284)
		(width 0.127)
		(layer "In2.Cu")
		(net "NCSI_OCP_SFF_TXD0")
	)
	(segment
		(start 426.418756 -52.005738)
		(end 425.305728 -53.118766)
		(width 0.127)
		(layer "In2.Cu")
		(net "NCSI_OCP_SFF_TXD0")
	)
	(segment
		(start 442.7347 -11.667744)
		(end 442.8617 -11.794744)
		(width 0.127)
		(layer "In2.Cu")
		(net "NCSI_OCP_SFF_TXD0")
	)
	(segment
		(start 442.8617 -13.453364)
		(end 442.7347 -13.580364)
		(width 0.127)
		(layer "In2.Cu")
		(net "NCSI_OCP_SFF_TXD0")
	)
	(segment
		(start 428.43069 -49.993804)
		(end 428.251366 -49.993804)
		(width 0.127)
		(layer "In2.Cu")
		(net "NCSI_OCP_SFF_TXD0")
	)
	(segment
		(start 442.8617 -10.519664)
		(end 442.8617 -10.903204)
		(width 0.127)
		(layer "In2.Cu")
		(net "NCSI_OCP_SFF_TXD0")
	)
	(segment
		(start 441.903612 -11.157204)
		(end 441.903612 -11.540744)
		(width 0.127)
		(layer "In2.Cu")
		(net "NCSI_OCP_SFF_TXD0")
	)
	(segment
		(start 427.20895 -51.215544)
		(end 427.029626 -51.215544)
		(width 0.127)
		(layer "In2.Cu")
		(net "NCSI_OCP_SFF_TXD0")
	)
	(segment
		(start 442.030612 -12.942824)
		(end 442.7347 -12.942824)
		(width 0.127)
		(layer "In2.Cu")
		(net "NCSI_OCP_SFF_TXD0")
	)
	(segment
		(start 427.029626 -51.215544)
		(end 426.904658 -51.090322)
		(width 0.127)
		(layer "In2.Cu")
		(net "NCSI_OCP_SFF_TXD0")
	)
	(segment
		(start 427.640496 -50.604674)
		(end 427.640496 -50.783998)
		(width 0.127)
		(layer "In2.Cu")
		(net "NCSI_OCP_SFF_TXD0")
	)
	(segment
		(start 442.8617 -11.794744)
		(end 442.8617 -12.178284)
		(width 0.127)
		(layer "In2.Cu")
		(net "NCSI_OCP_SFF_TXD0")
	)
	(segment
		(start 441.903612 -12.432284)
		(end 441.903612 -12.815824)
		(width 0.127)
		(layer "In2.Cu")
		(net "NCSI_OCP_SFF_TXD0")
	)
	(segment
		(start 426.293788 -51.521868)
		(end 426.293788 -51.701192)
		(width 0.127)
		(layer "In2.Cu")
		(net "NCSI_OCP_SFF_TXD0")
	)
	(segment
		(start 442.030612 -13.580364)
		(end 441.903612 -13.707364)
		(width 0.127)
		(layer "In2.Cu")
		(net "NCSI_OCP_SFF_TXD0")
	)
	(segment
		(start 447.65468 -5.476748)
		(end 447.32702 -5.149088)
		(width 0.127)
		(layer "In2.Cu")
		(net "NCSI_OCP_SFF_TXD0")
	)
	(segment
		(start 441.903612 -8.491728)
		(end 441.903612 -10.265664)
		(width 0.127)
		(layer "In2.Cu")
		(net "NCSI_OCP_SFF_TXD0")
	)
	(segment
		(start 426.904658 -51.090322)
		(end 426.725334 -51.090322)
		(width 0.127)
		(layer "In2.Cu")
		(net "NCSI_OCP_SFF_TXD0")
	)
	(segment
		(start 442.7347 -11.030204)
		(end 442.030612 -11.030204)
		(width 0.127)
		(layer "In2.Cu")
		(net "NCSI_OCP_SFF_TXD0")
	)
	(segment
		(start 426.293788 -51.701192)
		(end 426.418756 -51.826414)
		(width 0.127)
		(layer "In2.Cu")
		(net "NCSI_OCP_SFF_TXD0")
	)
	(segment
		(start 425.305728 -53.118766)
		(end 425.305728 -55.113174)
		(width 0.127)
		(layer "In2.Cu")
		(net "NCSI_OCP_SFF_TXD0")
	)
	(segment
		(start 442.8617 -13.069824)
		(end 442.8617 -13.453364)
		(width 0.127)
		(layer "In2.Cu")
		(net "NCSI_OCP_SFF_TXD0")
	)
	(segment
		(start 427.515528 -50.479452)
		(end 427.640496 -50.604674)
		(width 0.127)
		(layer "In2.Cu")
		(net "NCSI_OCP_SFF_TXD0")
	)
	(segment
		(start 441.903612 -10.265664)
		(end 442.030612 -10.392664)
		(width 0.127)
		(layer "In2.Cu")
		(net "NCSI_OCP_SFF_TXD0")
	)
	(segment
		(start 426.418756 -51.826414)
		(end 426.418756 -52.005738)
		(width 0.127)
		(layer "In2.Cu")
		(net "NCSI_OCP_SFF_TXD0")
	)
	(segment
		(start 447.32702 -5.149088)
		(end 445.246252 -5.149088)
		(width 0.127)
		(layer "In2.Cu")
		(net "NCSI_OCP_SFF_TXD0")
	)
	(segment
		(start 445.246252 -5.149088)
		(end 441.903612 -8.491728)
		(width 0.127)
		(layer "In2.Cu")
		(net "NCSI_OCP_SFF_TXD0")
	)
	(segment
		(start 442.030612 -12.305284)
		(end 441.903612 -12.432284)
		(width 0.127)
		(layer "In2.Cu")
		(net "NCSI_OCP_SFF_TXD0")
	)
	(segment
		(start 441.903612 -12.815824)
		(end 442.030612 -12.942824)
		(width 0.127)
		(layer "In2.Cu")
		(net "NCSI_OCP_SFF_TXD0")
	)
	(segment
		(start 442.7347 -13.580364)
		(end 442.030612 -13.580364)
		(width 0.127)
		(layer "In2.Cu")
		(net "NCSI_OCP_SFF_TXD0")
	)
	(segment
		(start 427.640496 -50.783998)
		(end 427.20895 -51.215544)
		(width 0.127)
		(layer "In2.Cu")
		(net "NCSI_OCP_SFF_TXD0")
	)
	(segment
		(start 428.251366 -49.993804)
		(end 428.126398 -49.868582)
		(width 0.127)
		(layer "In2.Cu")
		(net "NCSI_OCP_SFF_TXD0")
	)
	(segment
		(start 431.27168 -47.152814)
		(end 428.43069 -49.993804)
		(width 0.127)
		(layer "In2.Cu")
		(net "NCSI_OCP_SFF_TXD0")
	)
	(segment
		(start 442.8617 -10.903204)
		(end 442.7347 -11.030204)
		(width 0.127)
		(layer "In2.Cu")
		(net "NCSI_OCP_SFF_TXD0")
	)
	(segment
		(start 442.030612 -11.667744)
		(end 442.7347 -11.667744)
		(width 0.127)
		(layer "In2.Cu")
		(net "NCSI_OCP_SFF_TXD0")
	)
	(segment
		(start 442.7347 -10.392664)
		(end 442.8617 -10.519664)
		(width 0.127)
		(layer "In2.Cu")
		(net "NCSI_OCP_SFF_TXD0")
	)
	(segment
		(start 441.903612 -11.540744)
		(end 442.030612 -11.667744)
		(width 0.127)
		(layer "In2.Cu")
		(net "NCSI_OCP_SFF_TXD0")
	)
	(segment
		(start 441.903612 -13.707364)
		(end 441.903612 -14.947138)
		(width 0.127)
		(layer "In2.Cu")
		(net "NCSI_OCP_SFF_TXD0")
	)
	(segment
		(start 442.7347 -12.305284)
		(end 442.030612 -12.305284)
		(width 0.127)
		(layer "In2.Cu")
		(net "NCSI_OCP_SFF_TXD0")
	)
	(segment
		(start 441.903612 -14.947138)
		(end 431.27168 -25.57907)
		(width 0.127)
		(layer "In2.Cu")
		(net "NCSI_OCP_SFF_TXD0")
	)
	(segment
		(start 442.030612 -10.392664)
		(end 442.7347 -10.392664)
		(width 0.127)
		(layer "In2.Cu")
		(net "NCSI_OCP_SFF_TXD0")
	)
	(segment
		(start 427.515528 -50.300128)
		(end 427.515528 -50.479452)
		(width 0.127)
		(layer "In2.Cu")
		(net "NCSI_OCP_SFF_TXD0")
	)
	(segment
		(start 431.27168 -25.57907)
		(end 431.27168 -47.152814)
		(width 0.127)
		(layer "In2.Cu")
		(net "NCSI_OCP_SFF_TXD0")
	)
	(segment
		(start 442.7347 -12.942824)
		(end 442.8617 -13.069824)
		(width 0.127)
		(layer "In2.Cu")
		(net "NCSI_OCP_SFF_TXD0")
	)
	(segment
		(start 426.725334 -51.090322)
		(end 426.293788 -51.521868)
		(width 0.127)
		(layer "In2.Cu")
		(net "NCSI_OCP_SFF_TXD0")
	)
	(segment
		(start 428.126398 -49.868582)
		(end 427.947074 -49.868582)
		(width 0.127)
		(layer "In2.Cu")
		(net "NCSI_OCP_SFF_TXD0")
	)
	(segment
		(start 448.361816 -13.036804)
		(end 448.87388 -13.548868)
		(width 0.12954)
		(layer "F.Cu")
		(net "NCSI_OCP_SFF_RXD1")
	)
	(segment
		(start 204.29474 -80.124808)
		(end 201.63028 -77.460348)
		(width 0.12954)
		(layer "F.Cu")
		(net "NCSI_OCP_SFF_RXD1")
	)
	(segment
		(start 360.093768 -94.109032)
		(end 303.157128 -94.109032)
		(width 0.12954)
		(layer "F.Cu")
		(net "NCSI_OCP_SFF_RXD1")
	)
	(segment
		(start 369.451636 -84.751164)
		(end 360.093768 -94.109032)
		(width 0.12954)
		(layer "F.Cu")
		(net "NCSI_OCP_SFF_RXD1")
	)
	(segment
		(start 421.569134 -57.797192)
		(end 419.640258 -59.726068)
		(width 0.12954)
		(layer "F.Cu")
		(net "NCSI_OCP_SFF_RXD1")
	)
	(segment
		(start 421.858694 -57.797192)
		(end 421.569134 -57.797192)
		(width 0.12954)
		(layer "F.Cu")
		(net "NCSI_OCP_SFF_RXD1")
	)
	(segment
		(start 280.719784 -89.532968)
		(end 277.710392 -86.523576)
		(width 0.12954)
		(layer "F.Cu")
		(net "NCSI_OCP_SFF_RXD1")
	)
	(segment
		(start 250.356116 -85.235034)
		(end 245.73611 -85.235034)
		(width 0.12954)
		(layer "F.Cu")
		(net "NCSI_OCP_SFF_RXD1")
	)
	(segment
		(start 251.644658 -86.523576)
		(end 250.356116 -85.235034)
		(width 0.12954)
		(layer "F.Cu")
		(net "NCSI_OCP_SFF_RXD1")
	)
	(segment
		(start 225.479864 -91.062048)
		(end 214.542624 -80.124808)
		(width 0.12954)
		(layer "F.Cu")
		(net "NCSI_OCP_SFF_RXD1")
	)
	(segment
		(start 277.710392 -86.523576)
		(end 251.644658 -86.523576)
		(width 0.12954)
		(layer "F.Cu")
		(net "NCSI_OCP_SFF_RXD1")
	)
	(segment
		(start 239.909096 -91.062048)
		(end 225.479864 -91.062048)
		(width 0.12954)
		(layer "F.Cu")
		(net "NCSI_OCP_SFF_RXD1")
	)
	(segment
		(start 298.581064 -89.532968)
		(end 280.719784 -89.532968)
		(width 0.12954)
		(layer "F.Cu")
		(net "NCSI_OCP_SFF_RXD1")
	)
	(segment
		(start 214.542624 -80.124808)
		(end 204.29474 -80.124808)
		(width 0.12954)
		(layer "F.Cu")
		(net "NCSI_OCP_SFF_RXD1")
	)
	(segment
		(start 245.73611 -85.235034)
		(end 239.909096 -91.062048)
		(width 0.12954)
		(layer "F.Cu")
		(net "NCSI_OCP_SFF_RXD1")
	)
	(segment
		(start 419.640258 -59.726068)
		(end 417.106354 -65.84315)
		(width 0.12954)
		(layer "F.Cu")
		(net "NCSI_OCP_SFF_RXD1")
	)
	(segment
		(start 448.361816 -11.26998)
		(end 448.361816 -13.036804)
		(width 0.12954)
		(layer "F.Cu")
		(net "NCSI_OCP_SFF_RXD1")
	)
	(segment
		(start 303.157128 -94.109032)
		(end 298.581064 -89.532968)
		(width 0.12954)
		(layer "F.Cu")
		(net "NCSI_OCP_SFF_RXD1")
	)
	(segment
		(start 398.19834 -84.751164)
		(end 369.451636 -84.751164)
		(width 0.12954)
		(layer "F.Cu")
		(net "NCSI_OCP_SFF_RXD1")
	)
	(segment
		(start 417.106354 -65.84315)
		(end 398.19834 -84.751164)
		(width 0.12954)
		(layer "F.Cu")
		(net "NCSI_OCP_SFF_RXD1")
	)
	(via
		(at 421.858694 -57.797192)
		(size 0.508)
		(drill 0.254)
		(layers "F.Cu" "B.Cu")
		(net "NCSI_OCP_SFF_RXD1")
	)
	(via
		(at 201.63028 -77.460348)
		(size 0.508)
		(drill 0.254)
		(layers "F.Cu" "B.Cu")
		(net "NCSI_OCP_SFF_RXD1")
	)
	(via
		(at 448.87388 -13.548868)
		(size 0.508)
		(drill 0.254)
		(layers "F.Cu" "B.Cu")
		(net "NCSI_OCP_SFF_RXD1")
	)
	(segment
		(start 201.63028 -77.460348)
		(end 201.24801 -77.842618)
		(width 0.12954)
		(layer "B.Cu")
		(net "NCSI_OCP_SFF_RXD1")
	)
	(segment
		(start 201.24801 -77.842618)
		(end 200.146158 -77.842618)
		(width 0.12954)
		(layer "B.Cu")
		(net "NCSI_OCP_SFF_RXD1")
	)
	(segment
		(start 440.69508 -19.640804)
		(end 433.98948 -26.346404)
		(width 0.127)
		(layer "In2.Cu")
		(net "NCSI_OCP_SFF_RXD1")
	)
	(segment
		(start 433.98948 -26.346404)
		(end 433.98948 -49.67986)
		(width 0.127)
		(layer "In2.Cu")
		(net "NCSI_OCP_SFF_RXD1")
	)
	(segment
		(start 440.69508 -18.964148)
		(end 440.69508 -19.640804)
		(width 0.127)
		(layer "In2.Cu")
		(net "NCSI_OCP_SFF_RXD1")
	)
	(segment
		(start 426.196252 -57.797192)
		(end 421.858694 -57.797192)
		(width 0.127)
		(layer "In2.Cu")
		(net "NCSI_OCP_SFF_RXD1")
	)
	(segment
		(start 445.66078 -13.998448)
		(end 440.69508 -18.964148)
		(width 0.127)
		(layer "In2.Cu")
		(net "NCSI_OCP_SFF_RXD1")
	)
	(segment
		(start 428.945548 -53.4416)
		(end 428.945548 -55.047896)
		(width 0.127)
		(layer "In2.Cu")
		(net "NCSI_OCP_SFF_RXD1")
	)
	(segment
		(start 433.98948 -49.67986)
		(end 432.523392 -51.145948)
		(width 0.127)
		(layer "In2.Cu")
		(net "NCSI_OCP_SFF_RXD1")
	)
	(segment
		(start 448.87388 -13.548868)
		(end 448.4243 -13.998448)
		(width 0.127)
		(layer "In2.Cu")
		(net "NCSI_OCP_SFF_RXD1")
	)
	(segment
		(start 431.2412 -51.145948)
		(end 428.945548 -53.4416)
		(width 0.127)
		(layer "In2.Cu")
		(net "NCSI_OCP_SFF_RXD1")
	)
	(segment
		(start 432.523392 -51.145948)
		(end 431.2412 -51.145948)
		(width 0.127)
		(layer "In2.Cu")
		(net "NCSI_OCP_SFF_RXD1")
	)
	(segment
		(start 448.4243 -13.998448)
		(end 445.66078 -13.998448)
		(width 0.127)
		(layer "In2.Cu")
		(net "NCSI_OCP_SFF_RXD1")
	)
	(segment
		(start 428.945548 -55.047896)
		(end 426.196252 -57.797192)
		(width 0.127)
		(layer "In2.Cu")
		(net "NCSI_OCP_SFF_RXD1")
	)
	(segment
		(start 250.70435 -84.619084)
		(end 245.525798 -84.619084)
		(width 0.12954)
		(layer "F.Cu")
		(net "NCSI_OCP_SFF_RXD0")
	)
	(segment
		(start 421.588184 -57.191148)
		(end 421.20693 -57.349136)
		(width 0.12954)
		(layer "F.Cu")
		(net "NCSI_OCP_SFF_RXD0")
	)
	(segment
		(start 225.721926 -90.477848)
		(end 213.898226 -78.654148)
		(width 0.12954)
		(layer "F.Cu")
		(net "NCSI_OCP_SFF_RXD0")
	)
	(segment
		(start 447.761868 -13.502132)
		(end 447.735452 -13.528548)
		(width 0.12954)
		(layer "F.Cu")
		(net "NCSI_OCP_SFF_RXD0")
	)
	(segment
		(start 213.898226 -78.654148)
		(end 206.9973 -78.654148)
		(width 0.12954)
		(layer "F.Cu")
		(net "NCSI_OCP_SFF_RXD0")
	)
	(segment
		(start 277.952454 -85.939376)
		(end 252.024642 -85.939376)
		(width 0.12954)
		(layer "F.Cu")
		(net "NCSI_OCP_SFF_RXD0")
	)
	(segment
		(start 421.20693 -57.349136)
		(end 418.965634 -59.590432)
		(width 0.12954)
		(layer "F.Cu")
		(net "NCSI_OCP_SFF_RXD0")
	)
	(segment
		(start 280.961846 -88.948768)
		(end 277.952454 -85.939376)
		(width 0.12954)
		(layer "F.Cu")
		(net "NCSI_OCP_SFF_RXD0")
	)
	(segment
		(start 418.965634 -59.590432)
		(end 416.44316 -65.680082)
		(width 0.12954)
		(layer "F.Cu")
		(net "NCSI_OCP_SFF_RXD0")
	)
	(segment
		(start 206.9973 -78.654148)
		(end 203.5429 -75.199748)
		(width 0.12954)
		(layer "F.Cu")
		(net "NCSI_OCP_SFF_RXD0")
	)
	(segment
		(start 203.5429 -75.199748)
		(end 201.73188 -75.199748)
		(width 0.12954)
		(layer "F.Cu")
		(net "NCSI_OCP_SFF_RXD0")
	)
	(segment
		(start 422.875964 -57.191148)
		(end 421.588184 -57.191148)
		(width 0.12954)
		(layer "F.Cu")
		(net "NCSI_OCP_SFF_RXD0")
	)
	(segment
		(start 303.39919 -93.524832)
		(end 298.823126 -88.948768)
		(width 0.12954)
		(layer "F.Cu")
		(net "NCSI_OCP_SFF_RXD0")
	)
	(segment
		(start 397.882618 -84.240624)
		(end 369.135914 -84.240624)
		(width 0.12954)
		(layer "F.Cu")
		(net "NCSI_OCP_SFF_RXD0")
	)
	(segment
		(start 369.135914 -84.240624)
		(end 359.851706 -93.524832)
		(width 0.12954)
		(layer "F.Cu")
		(net "NCSI_OCP_SFF_RXD0")
	)
	(segment
		(start 245.525798 -84.619084)
		(end 239.667034 -90.477848)
		(width 0.12954)
		(layer "F.Cu")
		(net "NCSI_OCP_SFF_RXD0")
	)
	(segment
		(start 416.44316 -65.680082)
		(end 397.882618 -84.240624)
		(width 0.12954)
		(layer "F.Cu")
		(net "NCSI_OCP_SFF_RXD0")
	)
	(segment
		(start 447.761868 -11.26998)
		(end 447.761868 -13.502132)
		(width 0.12954)
		(layer "F.Cu")
		(net "NCSI_OCP_SFF_RXD0")
	)
	(segment
		(start 252.024642 -85.939376)
		(end 250.70435 -84.619084)
		(width 0.12954)
		(layer "F.Cu")
		(net "NCSI_OCP_SFF_RXD0")
	)
	(segment
		(start 298.823126 -88.948768)
		(end 280.961846 -88.948768)
		(width 0.12954)
		(layer "F.Cu")
		(net "NCSI_OCP_SFF_RXD0")
	)
	(segment
		(start 239.667034 -90.477848)
		(end 225.721926 -90.477848)
		(width 0.12954)
		(layer "F.Cu")
		(net "NCSI_OCP_SFF_RXD0")
	)
	(segment
		(start 359.851706 -93.524832)
		(end 303.39919 -93.524832)
		(width 0.12954)
		(layer "F.Cu")
		(net "NCSI_OCP_SFF_RXD0")
	)
	(via
		(at 201.73188 -75.199748)
		(size 0.508)
		(drill 0.254)
		(layers "F.Cu" "B.Cu")
		(net "NCSI_OCP_SFF_RXD0")
	)
	(via
		(at 422.875964 -57.191148)
		(size 0.762)
		(drill 0.254)
		(layers "F.Cu" "B.Cu")
		(net "NCSI_OCP_SFF_RXD0")
	)
	(via
		(at 447.735452 -13.528548)
		(size 0.508)
		(drill 0.254)
		(layers "F.Cu" "B.Cu")
		(net "NCSI_OCP_SFF_RXD0")
	)
	(segment
		(start 201.40168 -75.199748)
		(end 200.708768 -75.89266)
		(width 0.12954)
		(layer "B.Cu")
		(net "NCSI_OCP_SFF_RXD0")
	)
	(segment
		(start 200.708768 -75.89266)
		(end 200.146158 -75.89266)
		(width 0.12954)
		(layer "B.Cu")
		(net "NCSI_OCP_SFF_RXD0")
	)
	(segment
		(start 201.73188 -75.199748)
		(end 201.40168 -75.199748)
		(width 0.12954)
		(layer "B.Cu")
		(net "NCSI_OCP_SFF_RXD0")
	)
	(segment
		(start 445.483996 -13.528548)
		(end 440.23788 -18.774664)
		(width 0.127)
		(layer "In2.Cu")
		(net "NCSI_OCP_SFF_RXD0")
	)
	(segment
		(start 426.109892 -57.191148)
		(end 422.875964 -57.191148)
		(width 0.127)
		(layer "In2.Cu")
		(net "NCSI_OCP_SFF_RXD0")
	)
	(segment
		(start 428.307246 -54.993794)
		(end 426.109892 -57.191148)
		(width 0.127)
		(layer "In2.Cu")
		(net "NCSI_OCP_SFF_RXD0")
	)
	(segment
		(start 432.59248 -50.206148)
		(end 431.292 -50.206148)
		(width 0.127)
		(layer "In2.Cu")
		(net "NCSI_OCP_SFF_RXD0")
	)
	(segment
		(start 433.55768 -49.240948)
		(end 432.59248 -50.206148)
		(width 0.127)
		(layer "In2.Cu")
		(net "NCSI_OCP_SFF_RXD0")
	)
	(segment
		(start 431.292 -50.206148)
		(end 428.307246 -53.190902)
		(width 0.127)
		(layer "In2.Cu")
		(net "NCSI_OCP_SFF_RXD0")
	)
	(segment
		(start 440.23788 -19.45132)
		(end 433.55768 -26.13152)
		(width 0.127)
		(layer "In2.Cu")
		(net "NCSI_OCP_SFF_RXD0")
	)
	(segment
		(start 440.23788 -18.774664)
		(end 440.23788 -19.45132)
		(width 0.127)
		(layer "In2.Cu")
		(net "NCSI_OCP_SFF_RXD0")
	)
	(segment
		(start 447.735452 -13.528548)
		(end 445.483996 -13.528548)
		(width 0.127)
		(layer "In2.Cu")
		(net "NCSI_OCP_SFF_RXD0")
	)
	(segment
		(start 428.307246 -53.190902)
		(end 428.307246 -54.993794)
		(width 0.127)
		(layer "In2.Cu")
		(net "NCSI_OCP_SFF_RXD0")
	)
	(segment
		(start 433.55768 -26.13152)
		(end 433.55768 -49.240948)
		(width 0.127)
		(layer "In2.Cu")
		(net "NCSI_OCP_SFF_RXD0")
	)
	(segment
		(start 245.234968 -84.083652)
		(end 239.424972 -89.893648)
		(width 0.12954)
		(layer "F.Cu")
		(net "NCSI_OCP_SFF_CRS_DV")
	)
	(segment
		(start 252.36424 -85.355176)
		(end 251.092716 -84.083652)
		(width 0.12954)
		(layer "F.Cu")
		(net "NCSI_OCP_SFF_CRS_DV")
	)
	(segment
		(start 278.194516 -85.355176)
		(end 252.36424 -85.355176)
		(width 0.12954)
		(layer "F.Cu")
		(net "NCSI_OCP_SFF_CRS_DV")
	)
	(segment
		(start 444.761874 -9.918954)
		(end 444.761874 -11.26998)
		(width 0.12954)
		(layer "F.Cu")
		(net "NCSI_OCP_SFF_CRS_DV")
	)
	(segment
		(start 239.424972 -89.893648)
		(end 225.963988 -89.893648)
		(width 0.12954)
		(layer "F.Cu")
		(net "NCSI_OCP_SFF_CRS_DV")
	)
	(segment
		(start 207.135476 -78.069948)
		(end 203.477876 -74.412348)
		(width 0.12954)
		(layer "F.Cu")
		(net "NCSI_OCP_SFF_CRS_DV")
	)
	(segment
		(start 444.77051 -9.910318)
		(end 444.761874 -9.918954)
		(width 0.12954)
		(layer "F.Cu")
		(net "NCSI_OCP_SFF_CRS_DV")
	)
	(segment
		(start 195.526406 -74.902822)
		(end 195.526406 -75.242674)
		(width 0.12954)
		(layer "F.Cu")
		(net "NCSI_OCP_SFF_CRS_DV")
	)
	(segment
		(start 225.963988 -89.893648)
		(end 214.140288 -78.069948)
		(width 0.12954)
		(layer "F.Cu")
		(net "NCSI_OCP_SFF_CRS_DV")
	)
	(segment
		(start 420.7891 -56.940704)
		(end 418.376608 -59.353196)
		(width 0.12954)
		(layer "F.Cu")
		(net "NCSI_OCP_SFF_CRS_DV")
	)
	(segment
		(start 415.854134 -65.442846)
		(end 397.566896 -83.730084)
		(width 0.12954)
		(layer "F.Cu")
		(net "NCSI_OCP_SFF_CRS_DV")
	)
	(segment
		(start 251.092716 -84.083652)
		(end 245.234968 -84.083652)
		(width 0.12954)
		(layer "F.Cu")
		(net "NCSI_OCP_SFF_CRS_DV")
	)
	(segment
		(start 418.376608 -59.353196)
		(end 415.854134 -65.442846)
		(width 0.12954)
		(layer "F.Cu")
		(net "NCSI_OCP_SFF_CRS_DV")
	)
	(segment
		(start 423.780204 -56.497728)
		(end 421.858694 -56.497728)
		(width 0.12954)
		(layer "F.Cu")
		(net "NCSI_OCP_SFF_CRS_DV")
	)
	(segment
		(start 196.01688 -74.412348)
		(end 195.526406 -74.902822)
		(width 0.12954)
		(layer "F.Cu")
		(net "NCSI_OCP_SFF_CRS_DV")
	)
	(segment
		(start 299.065188 -88.364568)
		(end 281.203908 -88.364568)
		(width 0.12954)
		(layer "F.Cu")
		(net "NCSI_OCP_SFF_CRS_DV")
	)
	(segment
		(start 421.858694 -56.497728)
		(end 420.7891 -56.940704)
		(width 0.12954)
		(layer "F.Cu")
		(net "NCSI_OCP_SFF_CRS_DV")
	)
	(segment
		(start 397.566896 -83.730084)
		(end 367.406936 -83.730084)
		(width 0.12954)
		(layer "F.Cu")
		(net "NCSI_OCP_SFF_CRS_DV")
	)
	(segment
		(start 367.406936 -83.730084)
		(end 358.196388 -92.940632)
		(width 0.12954)
		(layer "F.Cu")
		(net "NCSI_OCP_SFF_CRS_DV")
	)
	(segment
		(start 214.140288 -78.069948)
		(end 207.135476 -78.069948)
		(width 0.12954)
		(layer "F.Cu")
		(net "NCSI_OCP_SFF_CRS_DV")
	)
	(segment
		(start 358.196388 -92.940632)
		(end 303.641252 -92.940632)
		(width 0.12954)
		(layer "F.Cu")
		(net "NCSI_OCP_SFF_CRS_DV")
	)
	(segment
		(start 281.203908 -88.364568)
		(end 278.194516 -85.355176)
		(width 0.12954)
		(layer "F.Cu")
		(net "NCSI_OCP_SFF_CRS_DV")
	)
	(segment
		(start 203.477876 -74.412348)
		(end 196.01688 -74.412348)
		(width 0.12954)
		(layer "F.Cu")
		(net "NCSI_OCP_SFF_CRS_DV")
	)
	(segment
		(start 303.641252 -92.940632)
		(end 299.065188 -88.364568)
		(width 0.12954)
		(layer "F.Cu")
		(net "NCSI_OCP_SFF_CRS_DV")
	)
	(via
		(at 195.526406 -75.242674)
		(size 0.508)
		(drill 0.254)
		(layers "F.Cu" "B.Cu")
		(net "NCSI_OCP_SFF_CRS_DV")
	)
	(via
		(at 423.780204 -56.497728)
		(size 0.508)
		(drill 0.254)
		(layers "F.Cu" "B.Cu")
		(net "NCSI_OCP_SFF_CRS_DV")
	)
	(via
		(at 444.77051 -9.910318)
		(size 0.508)
		(drill 0.254)
		(layers "F.Cu" "B.Cu")
		(net "NCSI_OCP_SFF_CRS_DV")
	)
	(segment
		(start 194.304158 -75.242674)
		(end 195.526406 -75.242674)
		(width 0.12954)
		(layer "B.Cu")
		(net "NCSI_OCP_SFF_CRS_DV")
	)
	(segment
		(start 434.425852 -24.044656)
		(end 434.540406 -24.15921)
		(width 0.127)
		(layer "In2.Cu")
		(net "NCSI_OCP_SFF_CRS_DV")
	)
	(segment
		(start 436.794656 -21.90496)
		(end 436.680102 -21.790406)
		(width 0.127)
		(layer "In2.Cu")
		(net "NCSI_OCP_SFF_CRS_DV")
	)
	(segment
		(start 434.991256 -23.70836)
		(end 434.876702 -23.593806)
		(width 0.127)
		(layer "In2.Cu")
		(net "NCSI_OCP_SFF_CRS_DV")
	)
	(segment
		(start 437.245506 -21.45411)
		(end 437.245506 -21.633942)
		(width 0.127)
		(layer "In2.Cu")
		(net "NCSI_OCP_SFF_CRS_DV")
	)
	(segment
		(start 434.425852 -23.864824)
		(end 434.425852 -24.044656)
		(width 0.127)
		(layer "In2.Cu")
		(net "NCSI_OCP_SFF_CRS_DV")
	)
	(segment
		(start 434.540406 -24.15921)
		(end 434.540406 -24.339042)
		(width 0.127)
		(layer "In2.Cu")
		(net "NCSI_OCP_SFF_CRS_DV")
	)
	(segment
		(start 437.130952 -21.339556)
		(end 437.245506 -21.45411)
		(width 0.127)
		(layer "In2.Cu")
		(net "NCSI_OCP_SFF_CRS_DV")
	)
	(segment
		(start 435.327552 -22.963124)
		(end 435.327552 -23.142956)
		(width 0.127)
		(layer "In2.Cu")
		(net "NCSI_OCP_SFF_CRS_DV")
	)
	(segment
		(start 427.631098 -54.9783)
		(end 426.11167 -56.497728)
		(width 0.127)
		(layer "In2.Cu")
		(net "NCSI_OCP_SFF_CRS_DV")
	)
	(segment
		(start 426.11167 -56.497728)
		(end 423.780204 -56.497728)
		(width 0.127)
		(layer "In2.Cu")
		(net "NCSI_OCP_SFF_CRS_DV")
	)
	(segment
		(start 436.229252 -22.241256)
		(end 436.343806 -22.35581)
		(width 0.127)
		(layer "In2.Cu")
		(net "NCSI_OCP_SFF_CRS_DV")
	)
	(segment
		(start 444.77051 -13.520166)
		(end 437.130952 -21.159724)
		(width 0.127)
		(layer "In2.Cu")
		(net "NCSI_OCP_SFF_CRS_DV")
	)
	(segment
		(start 444.77051 -9.910318)
		(end 444.77051 -13.520166)
		(width 0.127)
		(layer "In2.Cu")
		(net "NCSI_OCP_SFF_CRS_DV")
	)
	(segment
		(start 436.072788 -22.80666)
		(end 435.892956 -22.80666)
		(width 0.127)
		(layer "In2.Cu")
		(net "NCSI_OCP_SFF_CRS_DV")
	)
	(segment
		(start 435.778402 -22.692106)
		(end 435.59857 -22.692106)
		(width 0.127)
		(layer "In2.Cu")
		(net "NCSI_OCP_SFF_CRS_DV")
	)
	(segment
		(start 437.130952 -21.159724)
		(end 437.130952 -21.339556)
		(width 0.127)
		(layer "In2.Cu")
		(net "NCSI_OCP_SFF_CRS_DV")
	)
	(segment
		(start 434.089556 -24.61006)
		(end 433.975002 -24.495506)
		(width 0.127)
		(layer "In2.Cu")
		(net "NCSI_OCP_SFF_CRS_DV")
	)
	(segment
		(start 432.961796 -49.139348)
		(end 432.504596 -49.596548)
		(width 0.127)
		(layer "In2.Cu")
		(net "NCSI_OCP_SFF_CRS_DV")
	)
	(segment
		(start 434.876702 -23.593806)
		(end 434.69687 -23.593806)
		(width 0.127)
		(layer "In2.Cu")
		(net "NCSI_OCP_SFF_CRS_DV")
	)
	(segment
		(start 427.631098 -53.18125)
		(end 427.631098 -54.9783)
		(width 0.127)
		(layer "In2.Cu")
		(net "NCSI_OCP_SFF_CRS_DV")
	)
	(segment
		(start 436.50027 -21.790406)
		(end 436.229252 -22.061424)
		(width 0.127)
		(layer "In2.Cu")
		(net "NCSI_OCP_SFF_CRS_DV")
	)
	(segment
		(start 435.442106 -23.437342)
		(end 435.171088 -23.70836)
		(width 0.127)
		(layer "In2.Cu")
		(net "NCSI_OCP_SFF_CRS_DV")
	)
	(segment
		(start 432.504596 -49.596548)
		(end 431.2158 -49.596548)
		(width 0.127)
		(layer "In2.Cu")
		(net "NCSI_OCP_SFF_CRS_DV")
	)
	(segment
		(start 431.2158 -49.596548)
		(end 427.631098 -53.18125)
		(width 0.127)
		(layer "In2.Cu")
		(net "NCSI_OCP_SFF_CRS_DV")
	)
	(segment
		(start 435.171088 -23.70836)
		(end 434.991256 -23.70836)
		(width 0.127)
		(layer "In2.Cu")
		(net "NCSI_OCP_SFF_CRS_DV")
	)
	(segment
		(start 436.343806 -22.535642)
		(end 436.072788 -22.80666)
		(width 0.127)
		(layer "In2.Cu")
		(net "NCSI_OCP_SFF_CRS_DV")
	)
	(segment
		(start 434.69687 -23.593806)
		(end 434.425852 -23.864824)
		(width 0.127)
		(layer "In2.Cu")
		(net "NCSI_OCP_SFF_CRS_DV")
	)
	(segment
		(start 435.892956 -22.80666)
		(end 435.778402 -22.692106)
		(width 0.127)
		(layer "In2.Cu")
		(net "NCSI_OCP_SFF_CRS_DV")
	)
	(segment
		(start 435.59857 -22.692106)
		(end 435.327552 -22.963124)
		(width 0.127)
		(layer "In2.Cu")
		(net "NCSI_OCP_SFF_CRS_DV")
	)
	(segment
		(start 433.79517 -24.495506)
		(end 432.961796 -25.32888)
		(width 0.127)
		(layer "In2.Cu")
		(net "NCSI_OCP_SFF_CRS_DV")
	)
	(segment
		(start 436.974488 -21.90496)
		(end 436.794656 -21.90496)
		(width 0.127)
		(layer "In2.Cu")
		(net "NCSI_OCP_SFF_CRS_DV")
	)
	(segment
		(start 434.540406 -24.339042)
		(end 434.269388 -24.61006)
		(width 0.127)
		(layer "In2.Cu")
		(net "NCSI_OCP_SFF_CRS_DV")
	)
	(segment
		(start 436.229252 -22.061424)
		(end 436.229252 -22.241256)
		(width 0.127)
		(layer "In2.Cu")
		(net "NCSI_OCP_SFF_CRS_DV")
	)
	(segment
		(start 433.975002 -24.495506)
		(end 433.79517 -24.495506)
		(width 0.127)
		(layer "In2.Cu")
		(net "NCSI_OCP_SFF_CRS_DV")
	)
	(segment
		(start 435.442106 -23.25751)
		(end 435.442106 -23.437342)
		(width 0.127)
		(layer "In2.Cu")
		(net "NCSI_OCP_SFF_CRS_DV")
	)
	(segment
		(start 437.245506 -21.633942)
		(end 436.974488 -21.90496)
		(width 0.127)
		(layer "In2.Cu")
		(net "NCSI_OCP_SFF_CRS_DV")
	)
	(segment
		(start 434.269388 -24.61006)
		(end 434.089556 -24.61006)
		(width 0.127)
		(layer "In2.Cu")
		(net "NCSI_OCP_SFF_CRS_DV")
	)
	(segment
		(start 436.680102 -21.790406)
		(end 436.50027 -21.790406)
		(width 0.127)
		(layer "In2.Cu")
		(net "NCSI_OCP_SFF_CRS_DV")
	)
	(segment
		(start 435.327552 -23.142956)
		(end 435.442106 -23.25751)
		(width 0.127)
		(layer "In2.Cu")
		(net "NCSI_OCP_SFF_CRS_DV")
	)
	(segment
		(start 432.961796 -25.32888)
		(end 432.961796 -49.139348)
		(width 0.127)
		(layer "In2.Cu")
		(net "NCSI_OCP_SFF_CRS_DV")
	)
	(segment
		(start 436.343806 -22.35581)
		(end 436.343806 -22.535642)
		(width 0.127)
		(layer "In2.Cu")
		(net "NCSI_OCP_SFF_CRS_DV")
	)
	(segment
		(start 213.376002 -72.395588)
		(end 213.529926 -72.241664)
		(width 0.12954)
		(layer "F.Cu")
		(net "NCSI_BMC_TX_EN_R")
	)
	(segment
		(start 213.529926 -72.241664)
		(end 214.75827 -72.241664)
		(width 0.12954)
		(layer "F.Cu")
		(net "NCSI_BMC_TX_EN_R")
	)
	(via
		(at 213.376002 -72.395588)
		(size 0.762)
		(drill 0.254)
		(layers "F.Cu" "B.Cu")
		(net "NCSI_BMC_TX_EN_R")
	)
	(segment
		(start 213.618826 -72.152764)
		(end 214.757 -72.152764)
		(width 0.12954)
		(layer "B.Cu")
		(net "NCSI_BMC_TX_EN_R")
	)
	(segment
		(start 213.376002 -72.395588)
		(end 213.618826 -72.152764)
		(width 0.12954)
		(layer "B.Cu")
		(net "NCSI_BMC_TX_EN_R")
	)
	(segment
		(start 206.62646 -69.560948)
		(end 206.886302 -69.82079)
		(width 0.12954)
		(layer "F.Cu")
		(net "NCSI_BMC_TXD1_R")
	)
	(segment
		(start 206.886302 -69.82079)
		(end 208.669382 -69.82079)
		(width 0.12954)
		(layer "F.Cu")
		(net "NCSI_BMC_TXD1_R")
	)
	(via
		(at 206.62646 -69.560948)
		(size 0.762)
		(drill 0.254)
		(layers "F.Cu" "B.Cu")
		(net "NCSI_BMC_TXD1_R")
	)
	(segment
		(start 208.906872 -69.560948)
		(end 208.915 -69.55282)
		(width 0.12954)
		(layer "B.Cu")
		(net "NCSI_BMC_TXD1_R")
	)
	(segment
		(start 206.62646 -69.560948)
		(end 208.906872 -69.560948)
		(width 0.12954)
		(layer "B.Cu")
		(net "NCSI_BMC_TXD1_R")
	)
	(segment
		(start 207.02524 -71.138288)
		(end 208.621884 -71.138288)
		(width 0.12954)
		(layer "F.Cu")
		(net "NCSI_BMC_TXD0_R")
	)
	(segment
		(start 208.621884 -71.138288)
		(end 208.669382 -71.09079)
		(width 0.12954)
		(layer "F.Cu")
		(net "NCSI_BMC_TXD0_R")
	)
	(via
		(at 207.02524 -71.138288)
		(size 0.762)
		(drill 0.254)
		(layers "F.Cu" "B.Cu")
		(net "NCSI_BMC_TXD0_R")
	)
	(segment
		(start 207.38973 -71.502778)
		(end 208.915 -71.502778)
		(width 0.12954)
		(layer "B.Cu")
		(net "NCSI_BMC_TXD0_R")
	)
	(segment
		(start 207.02524 -71.138288)
		(end 207.38973 -71.502778)
		(width 0.12954)
		(layer "B.Cu")
		(net "NCSI_BMC_TXD0_R")
	)
	(segment
		(start 200.504298 -78.492604)
		(end 200.435464 -78.42377)
		(width 0.12954)
		(layer "F.Cu")
		(net "NCSI_BMC_RXD1_R")
	)
	(segment
		(start 201.649584 -78.492604)
		(end 200.504298 -78.492604)
		(width 0.12954)
		(layer "F.Cu")
		(net "NCSI_BMC_RXD1_R")
	)
	(via
		(at 201.649584 -78.492604)
		(size 0.762)
		(drill 0.254)
		(layers "F.Cu" "B.Cu")
		(net "NCSI_BMC_RXD1_R")
	)
	(segment
		(start 200.146158 -78.492604)
		(end 201.649584 -78.492604)
		(width 0.12954)
		(layer "B.Cu")
		(net "NCSI_BMC_RXD1_R")
	)
	(segment
		(start 201.690478 -76.598526)
		(end 200.924668 -76.598526)
		(width 0.12954)
		(layer "F.Cu")
		(net "NCSI_BMC_RXD0_R")
	)
	(segment
		(start 200.924668 -76.598526)
		(end 200.457054 -77.06614)
		(width 0.12954)
		(layer "F.Cu")
		(net "NCSI_BMC_RXD0_R")
	)
	(via
		(at 201.690478 -76.598526)
		(size 0.762)
		(drill 0.254)
		(layers "F.Cu" "B.Cu")
		(net "NCSI_BMC_RXD0_R")
	)
	(segment
		(start 201.634598 -76.542646)
		(end 200.146158 -76.542646)
		(width 0.12954)
		(layer "B.Cu")
		(net "NCSI_BMC_RXD0_R")
	)
	(segment
		(start 201.690478 -76.598526)
		(end 201.634598 -76.542646)
		(width 0.12954)
		(layer "B.Cu")
		(net "NCSI_BMC_RXD0_R")
	)
	(segment
		(start 192.636648 -75.89266)
		(end 193.847212 -75.89266)
		(width 0.12954)
		(layer "F.Cu")
		(net "NCSI_BMC_CRS_DV_R")
	)
	(segment
		(start 193.847212 -75.89266)
		(end 193.971418 -76.016866)
		(width 0.12954)
		(layer "F.Cu")
		(net "NCSI_BMC_CRS_DV_R")
	)
	(via
		(at 192.636648 -75.89266)
		(size 0.508)
		(drill 0.254)
		(layers "F.Cu" "B.Cu")
		(net "NCSI_BMC_CRS_DV_R")
	)
	(segment
		(start 194.304158 -75.89266)
		(end 192.636648 -75.89266)
		(width 0.12954)
		(layer "B.Cu")
		(net "NCSI_BMC_CRS_DV_R")
	)
	(segment
		(start 204.076046 -243.216684)
		(end 202.971146 -243.216684)
		(width 0.20066)
		(layer "F.Cu")
		(net "M_H_CPU1_SB_RSP<1>")
	)
	(segment
		(start 133.365494 -253.383796)
		(end 133.365748 -253.38405)
		(width 0.20066)
		(layer "F.Cu")
		(net "M_H_CPU1_SB_RSP<1>")
	)
	(segment
		(start 133.365748 -253.38405)
		(end 133.365748 -253.919736)
		(width 0.20066)
		(layer "F.Cu")
		(net "M_H_CPU1_SB_RSP<1>")
	)
	(segment
		(start 135.149844 -254.752094)
		(end 135.149844 -254.733552)
		(width 0.088646)
		(layer "In6.Cu")
		(net "M_H_CPU1_SB_RSP<1>")
	)
	(segment
		(start 202.971146 -243.242084)
		(end 203.446126 -243.717064)
		(width 0.18288)
		(layer "In6.Cu")
		(net "M_H_CPU1_SB_RSP<1>")
	)
	(segment
		(start 145.697702 -257.097276)
		(end 144.110202 -256.781554)
		(width 0.18288)
		(layer "In6.Cu")
		(net "M_H_CPU1_SB_RSP<1>")
	)
	(segment
		(start 188.80328 -253.865126)
		(end 188.80328 -254.123698)
		(width 0.18288)
		(layer "In6.Cu")
		(net "M_H_CPU1_SB_RSP<1>")
	)
	(segment
		(start 142.220188 -255.998726)
		(end 141.393672 -255.17221)
		(width 0.18288)
		(layer "In6.Cu")
		(net "M_H_CPU1_SB_RSP<1>")
	)
	(segment
		(start 191.376046 -251.29236)
		(end 188.80328 -253.865126)
		(width 0.18288)
		(layer "In6.Cu")
		(net "M_H_CPU1_SB_RSP<1>")
	)
	(segment
		(start 139.93495 -255.17221)
		(end 139.004548 -255.17221)
		(width 0.088646)
		(layer "In6.Cu")
		(net "M_H_CPU1_SB_RSP<1>")
	)
	(segment
		(start 203.217526 -244.490748)
		(end 202.770994 -244.490748)
		(width 0.18288)
		(layer "In6.Cu")
		(net "M_H_CPU1_SB_RSP<1>")
	)
	(segment
		(start 202.971146 -243.216684)
		(end 202.971146 -243.242084)
		(width 0.18288)
		(layer "In6.Cu")
		(net "M_H_CPU1_SB_RSP<1>")
	)
	(segment
		(start 150.262082 -255.892046)
		(end 149.056852 -257.097276)
		(width 0.18288)
		(layer "In6.Cu")
		(net "M_H_CPU1_SB_RSP<1>")
	)
	(segment
		(start 202.290426 -244.971316)
		(end 202.290426 -246.369078)
		(width 0.18288)
		(layer "In6.Cu")
		(net "M_H_CPU1_SB_RSP<1>")
	)
	(segment
		(start 202.770994 -244.490748)
		(end 202.290426 -244.971316)
		(width 0.18288)
		(layer "In6.Cu")
		(net "M_H_CPU1_SB_RSP<1>")
	)
	(segment
		(start 200.896474 -246.722646)
		(end 199.326754 -248.292366)
		(width 0.18288)
		(layer "In6.Cu")
		(net "M_H_CPU1_SB_RSP<1>")
	)
	(segment
		(start 188.86424 -254.907034)
		(end 188.605668 -254.907034)
		(width 0.18288)
		(layer "In6.Cu")
		(net "M_H_CPU1_SB_RSP<1>")
	)
	(segment
		(start 134.822184 -254.329184)
		(end 134.074662 -254.329184)
		(width 0.088646)
		(layer "In6.Cu")
		(net "M_H_CPU1_SB_RSP<1>")
	)
	(segment
		(start 187.073286 -255.59512)
		(end 186.77636 -255.892046)
		(width 0.18288)
		(layer "In6.Cu")
		(net "M_H_CPU1_SB_RSP<1>")
	)
	(segment
		(start 144.110202 -256.781554)
		(end 142.220188 -255.998726)
		(width 0.18288)
		(layer "In6.Cu")
		(net "M_H_CPU1_SB_RSP<1>")
	)
	(segment
		(start 189.096142 -254.675132)
		(end 188.86424 -254.907034)
		(width 0.18288)
		(layer "In6.Cu")
		(net "M_H_CPU1_SB_RSP<1>")
	)
	(segment
		(start 186.77636 -255.892046)
		(end 150.262082 -255.892046)
		(width 0.18288)
		(layer "In6.Cu")
		(net "M_H_CPU1_SB_RSP<1>")
	)
	(segment
		(start 193.794126 -251.29236)
		(end 193.611246 -251.47524)
		(width 0.18288)
		(layer "In6.Cu")
		(net "M_H_CPU1_SB_RSP<1>")
	)
	(segment
		(start 137.326878 -255.231646)
		(end 137.312146 -255.22301)
		(width 0.088646)
		(layer "In6.Cu")
		(net "M_H_CPU1_SB_RSP<1>")
	)
	(segment
		(start 198.861426 -248.292366)
		(end 197.997826 -249.155966)
		(width 0.18288)
		(layer "In6.Cu")
		(net "M_H_CPU1_SB_RSP<1>")
	)
	(segment
		(start 197.167246 -249.155966)
		(end 195.030852 -251.29236)
		(width 0.18288)
		(layer "In6.Cu")
		(net "M_H_CPU1_SB_RSP<1>")
	)
	(segment
		(start 199.326754 -248.292366)
		(end 198.861426 -248.292366)
		(width 0.18288)
		(layer "In6.Cu")
		(net "M_H_CPU1_SB_RSP<1>")
	)
	(segment
		(start 189.096142 -254.41656)
		(end 189.096142 -254.675132)
		(width 0.18288)
		(layer "In6.Cu")
		(net "M_H_CPU1_SB_RSP<1>")
	)
	(segment
		(start 192.734946 -251.29236)
		(end 191.376046 -251.29236)
		(width 0.18288)
		(layer "In6.Cu")
		(net "M_H_CPU1_SB_RSP<1>")
	)
	(segment
		(start 134.074662 -254.329184)
		(end 133.365748 -253.919736)
		(width 0.088646)
		(layer "In6.Cu")
		(net "M_H_CPU1_SB_RSP<1>")
	)
	(segment
		(start 141.393672 -255.17221)
		(end 139.93495 -255.17221)
		(width 0.18288)
		(layer "In6.Cu")
		(net "M_H_CPU1_SB_RSP<1>")
	)
	(segment
		(start 136.93775 -255.22301)
		(end 136.92886 -255.228344)
		(width 0.088646)
		(layer "In6.Cu")
		(net "M_H_CPU1_SB_RSP<1>")
	)
	(segment
		(start 197.997826 -249.155966)
		(end 197.167246 -249.155966)
		(width 0.18288)
		(layer "In6.Cu")
		(net "M_H_CPU1_SB_RSP<1>")
	)
	(segment
		(start 195.030852 -251.29236)
		(end 193.794126 -251.29236)
		(width 0.18288)
		(layer "In6.Cu")
		(net "M_H_CPU1_SB_RSP<1>")
	)
	(segment
		(start 193.428366 -252.10389)
		(end 193.100706 -252.10389)
		(width 0.18288)
		(layer "In6.Cu")
		(net "M_H_CPU1_SB_RSP<1>")
	)
	(segment
		(start 188.80328 -254.123698)
		(end 189.096142 -254.41656)
		(width 0.18288)
		(layer "In6.Cu")
		(net "M_H_CPU1_SB_RSP<1>")
	)
	(segment
		(start 188.054234 -254.614172)
		(end 187.822332 -254.846074)
		(width 0.18288)
		(layer "In6.Cu")
		(net "M_H_CPU1_SB_RSP<1>")
	)
	(segment
		(start 202.290426 -246.369078)
		(end 201.936858 -246.722646)
		(width 0.18288)
		(layer "In6.Cu")
		(net "M_H_CPU1_SB_RSP<1>")
	)
	(segment
		(start 203.446126 -244.262148)
		(end 203.217526 -244.490748)
		(width 0.18288)
		(layer "In6.Cu")
		(net "M_H_CPU1_SB_RSP<1>")
	)
	(segment
		(start 187.883292 -255.887982)
		(end 187.62472 -255.887982)
		(width 0.18288)
		(layer "In6.Cu")
		(net "M_H_CPU1_SB_RSP<1>")
	)
	(segment
		(start 192.917826 -251.47524)
		(end 192.734946 -251.29236)
		(width 0.18288)
		(layer "In6.Cu")
		(net "M_H_CPU1_SB_RSP<1>")
	)
	(segment
		(start 138.266678 -255.231646)
		(end 138.251946 -255.22301)
		(width 0.088646)
		(layer "In6.Cu")
		(net "M_H_CPU1_SB_RSP<1>")
	)
	(segment
		(start 188.115194 -255.65608)
		(end 187.883292 -255.887982)
		(width 0.18288)
		(layer "In6.Cu")
		(net "M_H_CPU1_SB_RSP<1>")
	)
	(segment
		(start 193.100706 -252.10389)
		(end 192.917826 -251.92101)
		(width 0.18288)
		(layer "In6.Cu")
		(net "M_H_CPU1_SB_RSP<1>")
	)
	(segment
		(start 201.936858 -246.722646)
		(end 200.896474 -246.722646)
		(width 0.18288)
		(layer "In6.Cu")
		(net "M_H_CPU1_SB_RSP<1>")
	)
	(segment
		(start 193.611246 -251.47524)
		(end 193.611246 -251.92101)
		(width 0.18288)
		(layer "In6.Cu")
		(net "M_H_CPU1_SB_RSP<1>")
	)
	(segment
		(start 187.822332 -255.104646)
		(end 188.115194 -255.397508)
		(width 0.18288)
		(layer "In6.Cu")
		(net "M_H_CPU1_SB_RSP<1>")
	)
	(segment
		(start 188.312806 -254.614172)
		(end 188.054234 -254.614172)
		(width 0.18288)
		(layer "In6.Cu")
		(net "M_H_CPU1_SB_RSP<1>")
	)
	(segment
		(start 192.917826 -251.92101)
		(end 192.917826 -251.47524)
		(width 0.18288)
		(layer "In6.Cu")
		(net "M_H_CPU1_SB_RSP<1>")
	)
	(segment
		(start 187.62472 -255.887982)
		(end 187.331858 -255.59512)
		(width 0.18288)
		(layer "In6.Cu")
		(net "M_H_CPU1_SB_RSP<1>")
	)
	(segment
		(start 187.822332 -254.846074)
		(end 187.822332 -255.104646)
		(width 0.18288)
		(layer "In6.Cu")
		(net "M_H_CPU1_SB_RSP<1>")
	)
	(segment
		(start 203.446126 -243.717064)
		(end 203.446126 -244.262148)
		(width 0.18288)
		(layer "In6.Cu")
		(net "M_H_CPU1_SB_RSP<1>")
	)
	(segment
		(start 188.605668 -254.907034)
		(end 188.312806 -254.614172)
		(width 0.18288)
		(layer "In6.Cu")
		(net "M_H_CPU1_SB_RSP<1>")
	)
	(segment
		(start 193.611246 -251.92101)
		(end 193.428366 -252.10389)
		(width 0.18288)
		(layer "In6.Cu")
		(net "M_H_CPU1_SB_RSP<1>")
	)
	(segment
		(start 134.971282 -254.414274)
		(end 134.822184 -254.329184)
		(width 0.088646)
		(layer "In6.Cu")
		(net "M_H_CPU1_SB_RSP<1>")
	)
	(segment
		(start 187.331858 -255.59512)
		(end 187.073286 -255.59512)
		(width 0.18288)
		(layer "In6.Cu")
		(net "M_H_CPU1_SB_RSP<1>")
	)
	(segment
		(start 149.056852 -257.097276)
		(end 145.697702 -257.097276)
		(width 0.18288)
		(layer "In6.Cu")
		(net "M_H_CPU1_SB_RSP<1>")
	)
	(segment
		(start 188.115194 -255.397508)
		(end 188.115194 -255.65608)
		(width 0.18288)
		(layer "In6.Cu")
		(net "M_H_CPU1_SB_RSP<1>")
	)
	(arc
		(start 139.004548 -255.17221)
		(mid 138.907609 -255.1853)
		(end 138.81735 -255.22301)
		(width 0.088646)
		(layer "In6.Cu")
		(net "M_H_CPU1_SB_RSP<1>")
	)
	(arc
		(start 137.87755 -255.22301)
		(mid 137.603351 -255.298845)
		(end 137.326878 -255.231646)
		(width 0.088646)
		(layer "In6.Cu")
		(net "M_H_CPU1_SB_RSP<1>")
	)
	(arc
		(start 138.251946 -255.22301)
		(mid 138.064748 -255.172867)
		(end 137.87755 -255.22301)
		(width 0.088646)
		(layer "In6.Cu")
		(net "M_H_CPU1_SB_RSP<1>")
	)
	(arc
		(start 135.997696 -255.223264)
		(mid 135.714994 -255.299006)
		(end 135.432292 -255.223264)
		(width 0.088646)
		(layer "In6.Cu")
		(net "M_H_CPU1_SB_RSP<1>")
	)
	(arc
		(start 136.92886 -255.228344)
		(mid 136.649818 -255.299029)
		(end 136.372092 -255.223264)
		(width 0.088646)
		(layer "In6.Cu")
		(net "M_H_CPU1_SB_RSP<1>")
	)
	(arc
		(start 138.81735 -255.22301)
		(mid 138.543151 -255.298845)
		(end 138.266678 -255.231646)
		(width 0.088646)
		(layer "In6.Cu")
		(net "M_H_CPU1_SB_RSP<1>")
	)
	(arc
		(start 135.432292 -255.223264)
		(mid 135.230006 -255.024283)
		(end 135.149844 -254.752094)
		(width 0.088646)
		(layer "In6.Cu")
		(net "M_H_CPU1_SB_RSP<1>")
	)
	(arc
		(start 135.149844 -254.733552)
		(mid 135.102165 -254.550652)
		(end 134.971282 -254.414274)
		(width 0.088646)
		(layer "In6.Cu")
		(net "M_H_CPU1_SB_RSP<1>")
	)
	(arc
		(start 136.372092 -255.223264)
		(mid 136.184894 -255.173121)
		(end 135.997696 -255.223264)
		(width 0.088646)
		(layer "In6.Cu")
		(net "M_H_CPU1_SB_RSP<1>")
	)
	(arc
		(start 137.312146 -255.22301)
		(mid 137.124948 -255.172867)
		(end 136.93775 -255.22301)
		(width 0.088646)
		(layer "In6.Cu")
		(net "M_H_CPU1_SB_RSP<1>")
	)
	(segment
		(start 211.619846 -243.216684)
		(end 210.514946 -243.216684)
		(width 0.20066)
		(layer "F.Cu")
		(net "M_H_CPU1_SB_RSP<0>")
	)
	(segment
		(start 133.835648 -254.733298)
		(end 133.835394 -254.733552)
		(width 0.20066)
		(layer "F.Cu")
		(net "M_H_CPU1_SB_RSP<0>")
	)
	(segment
		(start 133.835648 -254.197612)
		(end 133.835648 -254.733298)
		(width 0.20066)
		(layer "F.Cu")
		(net "M_H_CPU1_SB_RSP<0>")
	)
	(segment
		(start 134.148322 -254.733552)
		(end 133.835394 -254.733552)
		(width 0.088646)
		(layer "In6.Cu")
		(net "M_H_CPU1_SB_RSP<0>")
	)
	(segment
		(start 141.151102 -256.676906)
		(end 140.716508 -256.242312)
		(width 0.18288)
		(layer "In6.Cu")
		(net "M_H_CPU1_SB_RSP<0>")
	)
	(segment
		(start 207.501998 -247.892316)
		(end 204.88656 -247.892316)
		(width 0.18288)
		(layer "In6.Cu")
		(net "M_H_CPU1_SB_RSP<0>")
	)
	(segment
		(start 138.359388 -256.030222)
		(end 138.34745 -256.03708)
		(width 0.088646)
		(layer "In6.Cu")
		(net "M_H_CPU1_SB_RSP<0>")
	)
	(segment
		(start 208.767426 -245.610126)
		(end 208.767426 -246.626888)
		(width 0.18288)
		(layer "In6.Cu")
		(net "M_H_CPU1_SB_RSP<0>")
	)
	(segment
		(start 196.294248 -252.887226)
		(end 192.290192 -256.891282)
		(width 0.18288)
		(layer "In6.Cu")
		(net "M_H_CPU1_SB_RSP<0>")
	)
	(segment
		(start 209.88528 -244.492272)
		(end 208.767426 -245.610126)
		(width 0.18288)
		(layer "In6.Cu")
		(net "M_H_CPU1_SB_RSP<0>")
	)
	(segment
		(start 150.396194 -258.092956)
		(end 145.598388 -258.092956)
		(width 0.18288)
		(layer "In6.Cu")
		(net "M_H_CPU1_SB_RSP<0>")
	)
	(segment
		(start 211.076286 -244.218206)
		(end 210.80222 -244.492272)
		(width 0.18288)
		(layer "In6.Cu")
		(net "M_H_CPU1_SB_RSP<0>")
	)
	(segment
		(start 134.679944 -255.557528)
		(end 134.679944 -255.538986)
		(width 0.088646)
		(layer "In6.Cu")
		(net "M_H_CPU1_SB_RSP<0>")
	)
	(segment
		(start 151.597868 -256.891282)
		(end 150.396194 -258.092956)
		(width 0.18288)
		(layer "In6.Cu")
		(net "M_H_CPU1_SB_RSP<0>")
	)
	(segment
		(start 210.514946 -243.216684)
		(end 210.514946 -243.242084)
		(width 0.18288)
		(layer "In6.Cu")
		(net "M_H_CPU1_SB_RSP<0>")
	)
	(segment
		(start 204.88656 -247.892316)
		(end 203.186538 -249.592338)
		(width 0.18288)
		(layer "In6.Cu")
		(net "M_H_CPU1_SB_RSP<0>")
	)
	(segment
		(start 208.767426 -246.626888)
		(end 207.501998 -247.892316)
		(width 0.18288)
		(layer "In6.Cu")
		(net "M_H_CPU1_SB_RSP<0>")
	)
	(segment
		(start 143.61922 -257.699256)
		(end 141.151102 -256.676906)
		(width 0.18288)
		(layer "In6.Cu")
		(net "M_H_CPU1_SB_RSP<0>")
	)
	(segment
		(start 201.935334 -249.592338)
		(end 199.664066 -251.863606)
		(width 0.18288)
		(layer "In6.Cu")
		(net "M_H_CPU1_SB_RSP<0>")
	)
	(segment
		(start 145.598388 -258.092956)
		(end 143.61922 -257.699256)
		(width 0.18288)
		(layer "In6.Cu")
		(net "M_H_CPU1_SB_RSP<0>")
	)
	(segment
		(start 197.096126 -252.887226)
		(end 196.294248 -252.887226)
		(width 0.18288)
		(layer "In6.Cu")
		(net "M_H_CPU1_SB_RSP<0>")
	)
	(segment
		(start 134.2136 -254.79883)
		(end 134.148322 -254.733552)
		(width 0.088646)
		(layer "In6.Cu")
		(net "M_H_CPU1_SB_RSP<0>")
	)
	(segment
		(start 199.664066 -251.863606)
		(end 198.119746 -251.863606)
		(width 0.18288)
		(layer "In6.Cu")
		(net "M_H_CPU1_SB_RSP<0>")
	)
	(segment
		(start 192.290192 -256.891282)
		(end 151.597868 -256.891282)
		(width 0.18288)
		(layer "In6.Cu")
		(net "M_H_CPU1_SB_RSP<0>")
	)
	(segment
		(start 137.407396 -256.03708)
		(end 137.392664 -256.045716)
		(width 0.088646)
		(layer "In6.Cu")
		(net "M_H_CPU1_SB_RSP<0>")
	)
	(segment
		(start 138.945874 -256.242312)
		(end 138.79957 -256.096008)
		(width 0.088646)
		(layer "In6.Cu")
		(net "M_H_CPU1_SB_RSP<0>")
	)
	(segment
		(start 211.076286 -243.803424)
		(end 211.076286 -244.218206)
		(width 0.18288)
		(layer "In6.Cu")
		(net "M_H_CPU1_SB_RSP<0>")
	)
	(segment
		(start 203.186538 -249.592338)
		(end 201.935334 -249.592338)
		(width 0.18288)
		(layer "In6.Cu")
		(net "M_H_CPU1_SB_RSP<0>")
	)
	(segment
		(start 210.80222 -244.492272)
		(end 209.88528 -244.492272)
		(width 0.18288)
		(layer "In6.Cu")
		(net "M_H_CPU1_SB_RSP<0>")
	)
	(segment
		(start 198.119746 -251.863606)
		(end 197.096126 -252.887226)
		(width 0.18288)
		(layer "In6.Cu")
		(net "M_H_CPU1_SB_RSP<0>")
	)
	(segment
		(start 137.415778 -256.032254)
		(end 137.407396 -256.03708)
		(width 0.088646)
		(layer "In6.Cu")
		(net "M_H_CPU1_SB_RSP<0>")
	)
	(segment
		(start 210.514946 -243.242084)
		(end 211.076286 -243.803424)
		(width 0.18288)
		(layer "In6.Cu")
		(net "M_H_CPU1_SB_RSP<0>")
	)
	(segment
		(start 139.93495 -256.242312)
		(end 138.945874 -256.242312)
		(width 0.088646)
		(layer "In6.Cu")
		(net "M_H_CPU1_SB_RSP<0>")
	)
	(segment
		(start 140.716508 -256.242312)
		(end 139.93495 -256.242312)
		(width 0.18288)
		(layer "In6.Cu")
		(net "M_H_CPU1_SB_RSP<0>")
	)
	(segment
		(start 138.34745 -256.03708)
		(end 138.332718 -256.045716)
		(width 0.088646)
		(layer "In6.Cu")
		(net "M_H_CPU1_SB_RSP<0>")
	)
	(arc
		(start 135.902192 -256.03708)
		(mid 135.714994 -255.986937)
		(end 135.527796 -256.03708)
		(width 0.088646)
		(layer "In6.Cu")
		(net "M_H_CPU1_SB_RSP<0>")
	)
	(arc
		(start 134.679944 -255.538986)
		(mid 134.627674 -255.356621)
		(end 134.492746 -255.223264)
		(width 0.088646)
		(layer "In6.Cu")
		(net "M_H_CPU1_SB_RSP<0>")
	)
	(arc
		(start 136.841992 -256.03708)
		(mid 136.654794 -255.986937)
		(end 136.467596 -256.03708)
		(width 0.088646)
		(layer "In6.Cu")
		(net "M_H_CPU1_SB_RSP<0>")
	)
	(arc
		(start 136.467596 -256.03708)
		(mid 136.184894 -256.112856)
		(end 135.902192 -256.03708)
		(width 0.088646)
		(layer "In6.Cu")
		(net "M_H_CPU1_SB_RSP<0>")
	)
	(arc
		(start 134.492746 -255.223264)
		(mid 134.302839 -255.044158)
		(end 134.2136 -254.79883)
		(width 0.088646)
		(layer "In6.Cu")
		(net "M_H_CPU1_SB_RSP<0>")
	)
	(arc
		(start 134.962392 -256.03708)
		(mid 134.758057 -255.834475)
		(end 134.679944 -255.557528)
		(width 0.088646)
		(layer "In6.Cu")
		(net "M_H_CPU1_SB_RSP<0>")
	)
	(arc
		(start 137.782046 -256.03708)
		(mid 137.599541 -255.986842)
		(end 137.415778 -256.032254)
		(width 0.088646)
		(layer "In6.Cu")
		(net "M_H_CPU1_SB_RSP<0>")
	)
	(arc
		(start 138.721846 -256.03708)
		(mid 138.541499 -255.986877)
		(end 138.359388 -256.030222)
		(width 0.088646)
		(layer "In6.Cu")
		(net "M_H_CPU1_SB_RSP<0>")
	)
	(arc
		(start 138.79957 -256.096008)
		(mid 138.762634 -256.064003)
		(end 138.721846 -256.03708)
		(width 0.088646)
		(layer "In6.Cu")
		(net "M_H_CPU1_SB_RSP<0>")
	)
	(arc
		(start 138.332718 -256.045716)
		(mid 138.056277 -256.112882)
		(end 137.782046 -256.03708)
		(width 0.088646)
		(layer "In6.Cu")
		(net "M_H_CPU1_SB_RSP<0>")
	)
	(arc
		(start 135.527796 -256.03708)
		(mid 135.245094 -256.112856)
		(end 134.962392 -256.03708)
		(width 0.088646)
		(layer "In6.Cu")
		(net "M_H_CPU1_SB_RSP<0>")
	)
	(arc
		(start 137.392664 -256.045716)
		(mid 137.116223 -256.112882)
		(end 136.841992 -256.03708)
		(width 0.088646)
		(layer "In6.Cu")
		(net "M_H_CPU1_SB_RSP<0>")
	)
	(segment
		(start 214.605362 -246.616728)
		(end 215.719914 -246.616728)
		(width 0.20066)
		(layer "F.Cu")
		(net "M_H_CPU1_SB_PAR")
	)
	(segment
		(start 210.247484 -247.052338)
		(end 210.598258 -247.052338)
		(width 0.20066)
		(layer "F.Cu")
		(net "M_H_CPU1_SB_PAR")
	)
	(segment
		(start 208.176114 -246.616728)
		(end 209.811874 -246.616728)
		(width 0.20066)
		(layer "F.Cu")
		(net "M_H_CPU1_SB_PAR")
	)
	(segment
		(start 214.1728 -246.184166)
		(end 214.605362 -246.616728)
		(width 0.20066)
		(layer "F.Cu")
		(net "M_H_CPU1_SB_PAR")
	)
	(segment
		(start 210.613752 -247.04167)
		(end 212.622892 -247.04167)
		(width 0.1016)
		(layer "F.Cu")
		(net "M_H_CPU1_SB_PAR")
	)
	(segment
		(start 212.630258 -247.049036)
		(end 212.904324 -247.049036)
		(width 0.20066)
		(layer "F.Cu")
		(net "M_H_CPU1_SB_PAR")
	)
	(segment
		(start 213.769194 -246.184166)
		(end 214.1728 -246.184166)
		(width 0.20066)
		(layer "F.Cu")
		(net "M_H_CPU1_SB_PAR")
	)
	(segment
		(start 209.811874 -246.616728)
		(end 210.247484 -247.052338)
		(width 0.20066)
		(layer "F.Cu")
		(net "M_H_CPU1_SB_PAR")
	)
	(segment
		(start 210.603084 -247.052338)
		(end 210.613752 -247.04167)
		(width 0.1016)
		(layer "F.Cu")
		(net "M_H_CPU1_SB_PAR")
	)
	(segment
		(start 129.026666 -245.27256)
		(end 129.026412 -245.272306)
		(width 0.20066)
		(layer "F.Cu")
		(net "M_H_CPU1_SB_PAR")
	)
	(segment
		(start 207.071214 -246.616728)
		(end 208.176114 -246.616728)
		(width 0.20066)
		(layer "F.Cu")
		(net "M_H_CPU1_SB_PAR")
	)
	(segment
		(start 212.622892 -247.04167)
		(end 212.630258 -247.049036)
		(width 0.1016)
		(layer "F.Cu")
		(net "M_H_CPU1_SB_PAR")
	)
	(segment
		(start 212.904324 -247.049036)
		(end 213.769194 -246.184166)
		(width 0.20066)
		(layer "F.Cu")
		(net "M_H_CPU1_SB_PAR")
	)
	(segment
		(start 129.026412 -245.272306)
		(end 129.026412 -244.73662)
		(width 0.20066)
		(layer "F.Cu")
		(net "M_H_CPU1_SB_PAR")
	)
	(segment
		(start 210.598258 -247.052338)
		(end 210.603084 -247.052338)
		(width 0.101854)
		(layer "F.Cu")
		(net "M_H_CPU1_SB_PAR")
	)
	(segment
		(start 191.85255 -247.891046)
		(end 191.852296 -247.8913)
		(width 0.18288)
		(layer "In11.Cu")
		(net "M_H_CPU1_SB_PAR")
	)
	(segment
		(start 154.877262 -247.06072)
		(end 154.559762 -247.06072)
		(width 0.18288)
		(layer "In11.Cu")
		(net "M_H_CPU1_SB_PAR")
	)
	(segment
		(start 182.244746 -247.1547)
		(end 182.084726 -246.99468)
		(width 0.18288)
		(layer "In11.Cu")
		(net "M_H_CPU1_SB_PAR")
	)
	(segment
		(start 155.773882 -246.623332)
		(end 155.580842 -246.430292)
		(width 0.18288)
		(layer "In11.Cu")
		(net "M_H_CPU1_SB_PAR")
	)
	(segment
		(start 178.390296 -246.19077)
		(end 176.305718 -246.19077)
		(width 0.18288)
		(layer "In11.Cu")
		(net "M_H_CPU1_SB_PAR")
	)
	(segment
		(start 193.015362 -248.03735)
		(end 192.869058 -247.891046)
		(width 0.18288)
		(layer "In11.Cu")
		(net "M_H_CPU1_SB_PAR")
	)
	(segment
		(start 185.502804 -246.994426)
		(end 183.0578 -246.994426)
		(width 0.18288)
		(layer "In11.Cu")
		(net "M_H_CPU1_SB_PAR")
	)
	(segment
		(start 155.263342 -246.430292)
		(end 155.070302 -246.623332)
		(width 0.18288)
		(layer "In11.Cu")
		(net "M_H_CPU1_SB_PAR")
	)
	(segment
		(start 162.549078 -246.628666)
		(end 162.356038 -246.435626)
		(width 0.18288)
		(layer "In11.Cu")
		(net "M_H_CPU1_SB_PAR")
	)
	(segment
		(start 136.170416 -246.364506)
		(end 136.170416 -246.3546)
		(width 0.088646)
		(layer "In11.Cu")
		(net "M_H_CPU1_SB_PAR")
	)
	(segment
		(start 186.523122 -248.014744)
		(end 185.502804 -246.994426)
		(width 0.18288)
		(layer "In11.Cu")
		(net "M_H_CPU1_SB_PAR")
	)
	(segment
		(start 172.278802 -247.041162)
		(end 171.49699 -246.25935)
		(width 0.18288)
		(layer "In11.Cu")
		(net "M_H_CPU1_SB_PAR")
	)
	(segment
		(start 187.234322 -248.014744)
		(end 186.523122 -248.014744)
		(width 0.18288)
		(layer "In11.Cu")
		(net "M_H_CPU1_SB_PAR")
	)
	(segment
		(start 156.477462 -246.623332)
		(end 156.477462 -246.86768)
		(width 0.18288)
		(layer "In11.Cu")
		(net "M_H_CPU1_SB_PAR")
	)
	(segment
		(start 175.28794 -247.208548)
		(end 174.354236 -247.208548)
		(width 0.18288)
		(layer "In11.Cu")
		(net "M_H_CPU1_SB_PAR")
	)
	(segment
		(start 129.121916 -245.55069)
		(end 129.121916 -245.536466)
		(width 0.088646)
		(layer "In11.Cu")
		(net "M_H_CPU1_SB_PAR")
	)
	(segment
		(start 182.084726 -246.54383)
		(end 181.734206 -246.19331)
		(width 0.18288)
		(layer "In11.Cu")
		(net "M_H_CPU1_SB_PAR")
	)
	(segment
		(start 160.636204 -247.06072)
		(end 157.374082 -247.06072)
		(width 0.18288)
		(layer "In11.Cu")
		(net "M_H_CPU1_SB_PAR")
	)
	(segment
		(start 143.188436 -246.55907)
		(end 138.309604 -246.55907)
		(width 0.18288)
		(layer "In11.Cu")
		(net "M_H_CPU1_SB_PAR")
	)
	(segment
		(start 163.445698 -246.435626)
		(end 163.252658 -246.628666)
		(width 0.18288)
		(layer "In11.Cu")
		(net "M_H_CPU1_SB_PAR")
	)
	(segment
		(start 155.966922 -247.06072)
		(end 155.773882 -246.86768)
		(width 0.18288)
		(layer "In11.Cu")
		(net "M_H_CPU1_SB_PAR")
	)
	(segment
		(start 203.94168 -247.26773)
		(end 203.714604 -247.040654)
		(width 0.18288)
		(layer "In11.Cu")
		(net "M_H_CPU1_SB_PAR")
	)
	(segment
		(start 168.490646 -245.927626)
		(end 165.117526 -245.927626)
		(width 0.18288)
		(layer "In11.Cu")
		(net "M_H_CPU1_SB_PAR")
	)
	(segment
		(start 153.856182 -246.430292)
		(end 153.663142 -246.623332)
		(width 0.18288)
		(layer "In11.Cu")
		(net "M_H_CPU1_SB_PAR")
	)
	(segment
		(start 188.992002 -247.8913)
		(end 187.941712 -247.8913)
		(width 0.18288)
		(layer "In11.Cu")
		(net "M_H_CPU1_SB_PAR")
	)
	(segment
		(start 182.084726 -246.99468)
		(end 182.084726 -246.54383)
		(width 0.18288)
		(layer "In11.Cu")
		(net "M_H_CPU1_SB_PAR")
	)
	(segment
		(start 162.742118 -247.507506)
		(end 162.549078 -247.314466)
		(width 0.18288)
		(layer "In11.Cu")
		(net "M_H_CPU1_SB_PAR")
	)
	(segment
		(start 165.117526 -245.927626)
		(end 164.609526 -246.435626)
		(width 0.18288)
		(layer "In11.Cu")
		(net "M_H_CPU1_SB_PAR")
	)
	(segment
		(start 153.663142 -246.623332)
		(end 153.663142 -246.86768)
		(width 0.18288)
		(layer "In11.Cu")
		(net "M_H_CPU1_SB_PAR")
	)
	(segment
		(start 189.204092 -247.67921)
		(end 188.992002 -247.8913)
		(width 0.18288)
		(layer "In11.Cu")
		(net "M_H_CPU1_SB_PAR")
	)
	(segment
		(start 174.18685 -247.041162)
		(end 172.278802 -247.041162)
		(width 0.18288)
		(layer "In11.Cu")
		(net "M_H_CPU1_SB_PAR")
	)
	(segment
		(start 171.49699 -246.25935)
		(end 168.82237 -246.25935)
		(width 0.18288)
		(layer "In11.Cu")
		(net "M_H_CPU1_SB_PAR")
	)
	(segment
		(start 198.302626 -247.527826)
		(end 194.924426 -247.527826)
		(width 0.18288)
		(layer "In11.Cu")
		(net "M_H_CPU1_SB_PAR")
	)
	(segment
		(start 164.609526 -246.435626)
		(end 163.445698 -246.435626)
		(width 0.18288)
		(layer "In11.Cu")
		(net "M_H_CPU1_SB_PAR")
	)
	(segment
		(start 178.564286 -246.36476)
		(end 178.390296 -246.19077)
		(width 0.18288)
		(layer "In11.Cu")
		(net "M_H_CPU1_SB_PAR")
	)
	(segment
		(start 163.252658 -246.628666)
		(end 163.252658 -247.314466)
		(width 0.18288)
		(layer "In11.Cu")
		(net "M_H_CPU1_SB_PAR")
	)
	(segment
		(start 132.513324 -245.868952)
		(end 132.50291 -245.875048)
		(width 0.088646)
		(layer "In11.Cu")
		(net "M_H_CPU1_SB_PAR")
	)
	(segment
		(start 155.580842 -246.430292)
		(end 155.263342 -246.430292)
		(width 0.18288)
		(layer "In11.Cu")
		(net "M_H_CPU1_SB_PAR")
	)
	(segment
		(start 155.773882 -246.86768)
		(end 155.773882 -246.623332)
		(width 0.18288)
		(layer "In11.Cu")
		(net "M_H_CPU1_SB_PAR")
	)
	(segment
		(start 155.070302 -246.86768)
		(end 154.877262 -247.06072)
		(width 0.18288)
		(layer "In11.Cu")
		(net "M_H_CPU1_SB_PAR")
	)
	(segment
		(start 154.173682 -246.430292)
		(end 153.856182 -246.430292)
		(width 0.18288)
		(layer "In11.Cu")
		(net "M_H_CPU1_SB_PAR")
	)
	(segment
		(start 153.470102 -247.06072)
		(end 151.01316 -247.06072)
		(width 0.18288)
		(layer "In11.Cu")
		(net "M_H_CPU1_SB_PAR")
	)
	(segment
		(start 150.039578 -246.19585)
		(end 150.037038 -246.19585)
		(width 0.183134)
		(layer "In11.Cu")
		(net "M_H_CPU1_SB_PAR")
	)
	(segment
		(start 191.852296 -247.8913)
		(end 190.761112 -247.8913)
		(width 0.18288)
		(layer "In11.Cu")
		(net "M_H_CPU1_SB_PAR")
	)
	(segment
		(start 202.037442 -246.766842)
		(end 199.06361 -246.766842)
		(width 0.18288)
		(layer "In11.Cu")
		(net "M_H_CPU1_SB_PAR")
	)
	(segment
		(start 163.059618 -247.507506)
		(end 162.742118 -247.507506)
		(width 0.18288)
		(layer "In11.Cu")
		(net "M_H_CPU1_SB_PAR")
	)
	(segment
		(start 138.309604 -246.55907)
		(end 137.832338 -246.55907)
		(width 0.088646)
		(layer "In11.Cu")
		(net "M_H_CPU1_SB_PAR")
	)
	(segment
		(start 192.869058 -247.891046)
		(end 191.85255 -247.891046)
		(width 0.18288)
		(layer "In11.Cu")
		(net "M_H_CPU1_SB_PAR")
	)
	(segment
		(start 179.2859 -246.36476)
		(end 178.564286 -246.36476)
		(width 0.18288)
		(layer "In11.Cu")
		(net "M_H_CPU1_SB_PAR")
	)
	(segment
		(start 154.366722 -246.623332)
		(end 154.173682 -246.430292)
		(width 0.18288)
		(layer "In11.Cu")
		(net "M_H_CPU1_SB_PAR")
	)
	(segment
		(start 157.181042 -246.86768)
		(end 157.181042 -246.623332)
		(width 0.18288)
		(layer "In11.Cu")
		(net "M_H_CPU1_SB_PAR")
	)
	(segment
		(start 150.14829 -246.19585)
		(end 150.039578 -246.19585)
		(width 0.18288)
		(layer "In11.Cu")
		(net "M_H_CPU1_SB_PAR")
	)
	(segment
		(start 162.356038 -246.435626)
		(end 161.261298 -246.435626)
		(width 0.18288)
		(layer "In11.Cu")
		(net "M_H_CPU1_SB_PAR")
	)
	(segment
		(start 199.06361 -246.766842)
		(end 198.302626 -247.527826)
		(width 0.18288)
		(layer "In11.Cu")
		(net "M_H_CPU1_SB_PAR")
	)
	(segment
		(start 157.181042 -246.623332)
		(end 156.988002 -246.430292)
		(width 0.18288)
		(layer "In11.Cu")
		(net "M_H_CPU1_SB_PAR")
	)
	(segment
		(start 153.663142 -246.86768)
		(end 153.470102 -247.06072)
		(width 0.18288)
		(layer "In11.Cu")
		(net "M_H_CPU1_SB_PAR")
	)
	(segment
		(start 187.829444 -247.8913)
		(end 187.357766 -247.8913)
		(width 0.18288)
		(layer "In11.Cu")
		(net "M_H_CPU1_SB_PAR")
	)
	(segment
		(start 207.071214 -246.616728)
		(end 206.420212 -247.26773)
		(width 0.18288)
		(layer "In11.Cu")
		(net "M_H_CPU1_SB_PAR")
	)
	(segment
		(start 183.0578 -246.994426)
		(end 182.897526 -247.1547)
		(width 0.18288)
		(layer "In11.Cu")
		(net "M_H_CPU1_SB_PAR")
	)
	(segment
		(start 187.941712 -247.8913)
		(end 187.941458 -247.891046)
		(width 0.18288)
		(layer "In11.Cu")
		(net "M_H_CPU1_SB_PAR")
	)
	(segment
		(start 156.670502 -246.430292)
		(end 156.477462 -246.623332)
		(width 0.18288)
		(layer "In11.Cu")
		(net "M_H_CPU1_SB_PAR")
	)
	(segment
		(start 156.477462 -246.86768)
		(end 156.284422 -247.06072)
		(width 0.18288)
		(layer "In11.Cu")
		(net "M_H_CPU1_SB_PAR")
	)
	(segment
		(start 187.941458 -247.891046)
		(end 187.829698 -247.891046)
		(width 0.18288)
		(layer "In11.Cu")
		(net "M_H_CPU1_SB_PAR")
	)
	(segment
		(start 130.638296 -245.866412)
		(end 130.623564 -245.875048)
		(width 0.088646)
		(layer "In11.Cu")
		(net "M_H_CPU1_SB_PAR")
	)
	(segment
		(start 168.82237 -246.25935)
		(end 168.490646 -245.927626)
		(width 0.18288)
		(layer "In11.Cu")
		(net "M_H_CPU1_SB_PAR")
	)
	(segment
		(start 129.698496 -245.866412)
		(end 129.683764 -245.875048)
		(width 0.088646)
		(layer "In11.Cu")
		(net "M_H_CPU1_SB_PAR")
	)
	(segment
		(start 181.734206 -246.19331)
		(end 179.45735 -246.19331)
		(width 0.18288)
		(layer "In11.Cu")
		(net "M_H_CPU1_SB_PAR")
	)
	(segment
		(start 155.070302 -246.623332)
		(end 155.070302 -246.86768)
		(width 0.18288)
		(layer "In11.Cu")
		(net "M_H_CPU1_SB_PAR")
	)
	(segment
		(start 174.354236 -247.208548)
		(end 174.18685 -247.041162)
		(width 0.18288)
		(layer "In11.Cu")
		(net "M_H_CPU1_SB_PAR")
	)
	(segment
		(start 154.366722 -246.86768)
		(end 154.366722 -246.623332)
		(width 0.18288)
		(layer "In11.Cu")
		(net "M_H_CPU1_SB_PAR")
	)
	(segment
		(start 179.45735 -246.19331)
		(end 179.2859 -246.36476)
		(width 0.18288)
		(layer "In11.Cu")
		(net "M_H_CPU1_SB_PAR")
	)
	(segment
		(start 156.284422 -247.06072)
		(end 155.966922 -247.06072)
		(width 0.18288)
		(layer "In11.Cu")
		(net "M_H_CPU1_SB_PAR")
	)
	(segment
		(start 137.652506 -246.738902)
		(end 137.486898 -246.738902)
		(width 0.088646)
		(layer "In11.Cu")
		(net "M_H_CPU1_SB_PAR")
	)
	(segment
		(start 145.014188 -246.19585)
		(end 143.188436 -246.55907)
		(width 0.18288)
		(layer "In11.Cu")
		(net "M_H_CPU1_SB_PAR")
	)
	(segment
		(start 206.420212 -247.26773)
		(end 203.94168 -247.26773)
		(width 0.18288)
		(layer "In11.Cu")
		(net "M_H_CPU1_SB_PAR")
	)
	(segment
		(start 194.924426 -247.527826)
		(end 194.414902 -248.03735)
		(width 0.18288)
		(layer "In11.Cu")
		(net "M_H_CPU1_SB_PAR")
	)
	(segment
		(start 161.261298 -246.435626)
		(end 160.636204 -247.06072)
		(width 0.18288)
		(layer "In11.Cu")
		(net "M_H_CPU1_SB_PAR")
	)
	(segment
		(start 151.01316 -247.06072)
		(end 150.14829 -246.19585)
		(width 0.18288)
		(layer "In11.Cu")
		(net "M_H_CPU1_SB_PAR")
	)
	(segment
		(start 131.573778 -245.868952)
		(end 131.563364 -245.875048)
		(width 0.088646)
		(layer "In11.Cu")
		(net "M_H_CPU1_SB_PAR")
	)
	(segment
		(start 194.414902 -248.03735)
		(end 193.015362 -248.03735)
		(width 0.18288)
		(layer "In11.Cu")
		(net "M_H_CPU1_SB_PAR")
	)
	(segment
		(start 187.829698 -247.891046)
		(end 187.829444 -247.8913)
		(width 0.18288)
		(layer "In11.Cu")
		(net "M_H_CPU1_SB_PAR")
	)
	(segment
		(start 190.761112 -247.8913)
		(end 190.549022 -247.67921)
		(width 0.18288)
		(layer "In11.Cu")
		(net "M_H_CPU1_SB_PAR")
	)
	(segment
		(start 157.374082 -247.06072)
		(end 157.181042 -246.86768)
		(width 0.18288)
		(layer "In11.Cu")
		(net "M_H_CPU1_SB_PAR")
	)
	(segment
		(start 154.559762 -247.06072)
		(end 154.366722 -246.86768)
		(width 0.18288)
		(layer "In11.Cu")
		(net "M_H_CPU1_SB_PAR")
	)
	(segment
		(start 176.305718 -246.19077)
		(end 175.28794 -247.208548)
		(width 0.18288)
		(layer "In11.Cu")
		(net "M_H_CPU1_SB_PAR")
	)
	(segment
		(start 190.549022 -247.67921)
		(end 189.204092 -247.67921)
		(width 0.18288)
		(layer "In11.Cu")
		(net "M_H_CPU1_SB_PAR")
	)
	(segment
		(start 203.714604 -247.040654)
		(end 202.311254 -247.040654)
		(width 0.18288)
		(layer "In11.Cu")
		(net "M_H_CPU1_SB_PAR")
	)
	(segment
		(start 136.357868 -246.688864)
		(end 136.348978 -246.683784)
		(width 0.088646)
		(layer "In11.Cu")
		(net "M_H_CPU1_SB_PAR")
	)
	(segment
		(start 202.311254 -247.040654)
		(end 202.037442 -246.766842)
		(width 0.18288)
		(layer "In11.Cu")
		(net "M_H_CPU1_SB_PAR")
	)
	(segment
		(start 137.832338 -246.55907)
		(end 137.652506 -246.738902)
		(width 0.088646)
		(layer "In11.Cu")
		(net "M_H_CPU1_SB_PAR")
	)
	(segment
		(start 156.988002 -246.430292)
		(end 156.670502 -246.430292)
		(width 0.18288)
		(layer "In11.Cu")
		(net "M_H_CPU1_SB_PAR")
	)
	(segment
		(start 162.549078 -247.314466)
		(end 162.549078 -246.628666)
		(width 0.18288)
		(layer "In11.Cu")
		(net "M_H_CPU1_SB_PAR")
	)
	(segment
		(start 187.357766 -247.8913)
		(end 187.234322 -248.014744)
		(width 0.18288)
		(layer "In11.Cu")
		(net "M_H_CPU1_SB_PAR")
	)
	(segment
		(start 129.026412 -245.153434)
		(end 129.026412 -244.73662)
		(width 0.088646)
		(layer "In11.Cu")
		(net "M_H_CPU1_SB_PAR")
	)
	(segment
		(start 150.037038 -246.19585)
		(end 145.014188 -246.19585)
		(width 0.18288)
		(layer "In11.Cu")
		(net "M_H_CPU1_SB_PAR")
	)
	(segment
		(start 182.897526 -247.1547)
		(end 182.244746 -247.1547)
		(width 0.18288)
		(layer "In11.Cu")
		(net "M_H_CPU1_SB_PAR")
	)
	(segment
		(start 163.252658 -247.314466)
		(end 163.059618 -247.507506)
		(width 0.18288)
		(layer "In11.Cu")
		(net "M_H_CPU1_SB_PAR")
	)
	(arc
		(start 136.170416 -246.3546)
		(mid 136.092305 -246.077651)
		(end 135.887968 -245.875048)
		(width 0.088646)
		(layer "In11.Cu")
		(net "M_H_CPU1_SB_PAR")
	)
	(arc
		(start 136.732264 -246.688864)
		(mid 136.545066 -246.739007)
		(end 136.357868 -246.688864)
		(width 0.088646)
		(layer "In11.Cu")
		(net "M_H_CPU1_SB_PAR")
	)
	(arc
		(start 129.683764 -245.875048)
		(mid 129.594928 -245.911981)
		(end 129.499614 -245.925086)
		(width 0.088646)
		(layer "In11.Cu")
		(net "M_H_CPU1_SB_PAR")
	)
	(arc
		(start 134.008368 -245.875048)
		(mid 133.725666 -245.799272)
		(end 133.442964 -245.875048)
		(width 0.088646)
		(layer "In11.Cu")
		(net "M_H_CPU1_SB_PAR")
	)
	(arc
		(start 133.068568 -245.875048)
		(mid 132.791755 -245.799178)
		(end 132.513324 -245.868952)
		(width 0.088646)
		(layer "In11.Cu")
		(net "M_H_CPU1_SB_PAR")
	)
	(arc
		(start 134.382764 -245.875048)
		(mid 134.195566 -245.925191)
		(end 134.008368 -245.875048)
		(width 0.088646)
		(layer "In11.Cu")
		(net "M_H_CPU1_SB_PAR")
	)
	(arc
		(start 134.948168 -245.875048)
		(mid 134.665466 -245.799272)
		(end 134.382764 -245.875048)
		(width 0.088646)
		(layer "In11.Cu")
		(net "M_H_CPU1_SB_PAR")
	)
	(arc
		(start 130.623564 -245.875048)
		(mid 130.436366 -245.925191)
		(end 130.249168 -245.875048)
		(width 0.088646)
		(layer "In11.Cu")
		(net "M_H_CPU1_SB_PAR")
	)
	(arc
		(start 135.322564 -245.875048)
		(mid 135.135366 -245.925191)
		(end 134.948168 -245.875048)
		(width 0.088646)
		(layer "In11.Cu")
		(net "M_H_CPU1_SB_PAR")
	)
	(arc
		(start 133.442964 -245.875048)
		(mid 133.255766 -245.925191)
		(end 133.068568 -245.875048)
		(width 0.088646)
		(layer "In11.Cu")
		(net "M_H_CPU1_SB_PAR")
	)
	(arc
		(start 130.249168 -245.875048)
		(mid 129.974969 -245.799213)
		(end 129.698496 -245.866412)
		(width 0.088646)
		(layer "In11.Cu")
		(net "M_H_CPU1_SB_PAR")
	)
	(arc
		(start 135.887968 -245.875048)
		(mid 135.605266 -245.799272)
		(end 135.322564 -245.875048)
		(width 0.088646)
		(layer "In11.Cu")
		(net "M_H_CPU1_SB_PAR")
	)
	(arc
		(start 137.297668 -246.688864)
		(mid 137.014966 -246.613088)
		(end 136.732264 -246.688864)
		(width 0.088646)
		(layer "In11.Cu")
		(net "M_H_CPU1_SB_PAR")
	)
	(arc
		(start 137.486898 -246.738902)
		(mid 137.38895 -246.726482)
		(end 137.297668 -246.688864)
		(width 0.088646)
		(layer "In11.Cu")
		(net "M_H_CPU1_SB_PAR")
	)
	(arc
		(start 129.499614 -245.925086)
		(mid 129.30001 -245.869355)
		(end 129.160524 -245.716044)
		(width 0.088646)
		(layer "In11.Cu")
		(net "M_H_CPU1_SB_PAR")
	)
	(arc
		(start 132.128514 -245.875048)
		(mid 131.851955 -245.799305)
		(end 131.573778 -245.868952)
		(width 0.088646)
		(layer "In11.Cu")
		(net "M_H_CPU1_SB_PAR")
	)
	(arc
		(start 136.348978 -246.683784)
		(mid 136.218064 -246.547424)
		(end 136.170416 -246.364506)
		(width 0.088646)
		(layer "In11.Cu")
		(net "M_H_CPU1_SB_PAR")
	)
	(arc
		(start 131.188968 -245.875048)
		(mid 130.914769 -245.799213)
		(end 130.638296 -245.866412)
		(width 0.088646)
		(layer "In11.Cu")
		(net "M_H_CPU1_SB_PAR")
	)
	(arc
		(start 129.160524 -245.716044)
		(mid 129.131721 -245.635582)
		(end 129.121916 -245.55069)
		(width 0.088646)
		(layer "In11.Cu")
		(net "M_H_CPU1_SB_PAR")
	)
	(arc
		(start 129.121916 -245.536466)
		(mid 129.104659 -245.411598)
		(end 129.060194 -245.293642)
		(width 0.088646)
		(layer "In11.Cu")
		(net "M_H_CPU1_SB_PAR")
	)
	(arc
		(start 132.50291 -245.875048)
		(mid 132.315712 -245.925191)
		(end 132.128514 -245.875048)
		(width 0.088646)
		(layer "In11.Cu")
		(net "M_H_CPU1_SB_PAR")
	)
	(arc
		(start 131.563364 -245.875048)
		(mid 131.376166 -245.925191)
		(end 131.188968 -245.875048)
		(width 0.088646)
		(layer "In11.Cu")
		(net "M_H_CPU1_SB_PAR")
	)
	(arc
		(start 129.060194 -245.293642)
		(mid 129.035018 -245.225538)
		(end 129.026412 -245.153434)
		(width 0.088646)
		(layer "In11.Cu")
		(net "M_H_CPU1_SB_PAR")
	)
	(segment
		(start 206.9973 -238.541814)
		(end 207.023208 -238.541814)
		(width 0.101854)
		(layer "F.Cu")
		(net "M_H_CPU1_SB_DQS_DP<9>")
	)
	(segment
		(start 122.917712 -242.830858)
		(end 122.917966 -242.830604)
		(width 0.20066)
		(layer "F.Cu")
		(net "M_H_CPU1_SB_DQS_DP<9>")
	)
	(segment
		(start 206.606648 -238.290608)
		(end 206.857854 -238.541814)
		(width 0.20066)
		(layer "F.Cu")
		(net "M_H_CPU1_SB_DQS_DP<9>")
	)
	(segment
		(start 210.182968 -238.245396)
		(end 210.593432 -237.834932)
		(width 0.20066)
		(layer "F.Cu")
		(net "M_H_CPU1_SB_DQS_DP<9>")
	)
	(segment
		(start 210.593432 -237.834932)
		(end 210.78952 -237.834932)
		(width 0.20066)
		(layer "F.Cu")
		(net "M_H_CPU1_SB_DQS_DP<9>")
	)
	(segment
		(start 210.78952 -237.834932)
		(end 211.071206 -238.116618)
		(width 0.20066)
		(layer "F.Cu")
		(net "M_H_CPU1_SB_DQS_DP<9>")
	)
	(segment
		(start 204.665326 -238.116618)
		(end 204.905864 -237.87608)
		(width 0.20066)
		(layer "F.Cu")
		(net "M_H_CPU1_SB_DQS_DP<9>")
	)
	(segment
		(start 204.905864 -237.87608)
		(end 205.50632 -237.87608)
		(width 0.20066)
		(layer "F.Cu")
		(net "M_H_CPU1_SB_DQS_DP<9>")
	)
	(segment
		(start 206.857854 -238.541814)
		(end 206.9973 -238.541814)
		(width 0.20066)
		(layer "F.Cu")
		(net "M_H_CPU1_SB_DQS_DP<9>")
	)
	(segment
		(start 122.917966 -242.830604)
		(end 122.917966 -242.294918)
		(width 0.20066)
		(layer "F.Cu")
		(net "M_H_CPU1_SB_DQS_DP<9>")
	)
	(segment
		(start 209.812382 -238.245396)
		(end 210.182968 -238.245396)
		(width 0.20066)
		(layer "F.Cu")
		(net "M_H_CPU1_SB_DQS_DP<9>")
	)
	(segment
		(start 204.076046 -238.116618)
		(end 204.665326 -238.116618)
		(width 0.20066)
		(layer "F.Cu")
		(net "M_H_CPU1_SB_DQS_DP<9>")
	)
	(segment
		(start 205.50632 -237.87608)
		(end 205.920848 -238.290608)
		(width 0.20066)
		(layer "F.Cu")
		(net "M_H_CPU1_SB_DQS_DP<9>")
	)
	(segment
		(start 209.186526 -238.54791)
		(end 209.509868 -238.54791)
		(width 0.20066)
		(layer "F.Cu")
		(net "M_H_CPU1_SB_DQS_DP<9>")
	)
	(segment
		(start 207.023208 -238.541814)
		(end 209.18043 -238.541814)
		(width 0.1016)
		(layer "F.Cu")
		(net "M_H_CPU1_SB_DQS_DP<9>")
	)
	(segment
		(start 205.920848 -238.290608)
		(end 206.606648 -238.290608)
		(width 0.20066)
		(layer "F.Cu")
		(net "M_H_CPU1_SB_DQS_DP<9>")
	)
	(segment
		(start 211.071206 -238.116618)
		(end 211.619846 -238.116618)
		(width 0.20066)
		(layer "F.Cu")
		(net "M_H_CPU1_SB_DQS_DP<9>")
	)
	(segment
		(start 209.509868 -238.54791)
		(end 209.812382 -238.245396)
		(width 0.20066)
		(layer "F.Cu")
		(net "M_H_CPU1_SB_DQS_DP<9>")
	)
	(segment
		(start 202.971146 -238.116618)
		(end 204.076046 -238.116618)
		(width 0.20066)
		(layer "F.Cu")
		(net "M_H_CPU1_SB_DQS_DP<9>")
	)
	(segment
		(start 209.18043 -238.541814)
		(end 209.186526 -238.54791)
		(width 0.1016)
		(layer "F.Cu")
		(net "M_H_CPU1_SB_DQS_DP<9>")
	)
	(segment
		(start 160.200086 -237.292134)
		(end 158.985966 -238.506254)
		(width 0.18288)
		(layer "In11.Cu")
		(net "M_H_CPU1_SB_DQS_DP<9>")
	)
	(segment
		(start 188.376306 -236.575854)
		(end 188.111384 -236.840776)
		(width 0.18288)
		(layer "In11.Cu")
		(net "M_H_CPU1_SB_DQS_DP<9>")
	)
	(segment
		(start 126.404878 -242.790726)
		(end 126.394464 -242.78463)
		(width 0.088646)
		(layer "In11.Cu")
		(net "M_H_CPU1_SB_DQS_DP<9>")
	)
	(segment
		(start 179.388516 -236.353858)
		(end 178.69408 -236.353858)
		(width 0.18288)
		(layer "In11.Cu")
		(net "M_H_CPU1_SB_DQS_DP<9>")
	)
	(segment
		(start 192.198498 -238.542322)
		(end 191.75349 -238.542322)
		(width 0.18288)
		(layer "In11.Cu")
		(net "M_H_CPU1_SB_DQS_DP<9>")
	)
	(segment
		(start 172.251878 -236.59211)
		(end 168.574212 -236.59211)
		(width 0.18288)
		(layer "In11.Cu")
		(net "M_H_CPU1_SB_DQS_DP<9>")
	)
	(segment
		(start 199.165464 -237.388146)
		(end 194.239642 -237.388146)
		(width 0.18288)
		(layer "In11.Cu")
		(net "M_H_CPU1_SB_DQS_DP<9>")
	)
	(segment
		(start 148.066506 -243.460524)
		(end 141.103096 -243.460524)
		(width 0.18288)
		(layer "In11.Cu")
		(net "M_H_CPU1_SB_DQS_DP<9>")
	)
	(segment
		(start 190.442596 -238.233966)
		(end 188.784484 -236.575854)
		(width 0.18288)
		(layer "In11.Cu")
		(net "M_H_CPU1_SB_DQS_DP<9>")
	)
	(segment
		(start 134.478014 -242.78463)
		(end 134.4676 -242.790726)
		(width 0.088646)
		(layer "In11.Cu")
		(net "M_H_CPU1_SB_DQS_DP<9>")
	)
	(segment
		(start 191.75349 -238.542322)
		(end 191.445134 -238.233966)
		(width 0.18288)
		(layer "In11.Cu")
		(net "M_H_CPU1_SB_DQS_DP<9>")
	)
	(segment
		(start 137.36701 -243.40058)
		(end 136.810242 -242.843812)
		(width 0.088646)
		(layer "In11.Cu")
		(net "M_H_CPU1_SB_DQS_DP<9>")
	)
	(segment
		(start 123.295918 -242.360196)
		(end 123.23064 -242.294918)
		(width 0.088646)
		(layer "In11.Cu")
		(net "M_H_CPU1_SB_DQS_DP<9>")
	)
	(segment
		(start 132.598668 -242.78463)
		(end 132.588254 -242.790726)
		(width 0.088646)
		(layer "In11.Cu")
		(net "M_H_CPU1_SB_DQS_DP<9>")
	)
	(segment
		(start 135.418068 -242.78463)
		(end 135.407654 -242.790726)
		(width 0.088646)
		(layer "In11.Cu")
		(net "M_H_CPU1_SB_DQS_DP<9>")
	)
	(segment
		(start 202.971146 -238.116618)
		(end 202.714098 -237.85957)
		(width 0.18288)
		(layer "In11.Cu")
		(net "M_H_CPU1_SB_DQS_DP<9>")
	)
	(segment
		(start 202.714098 -237.85957)
		(end 202.243436 -237.85957)
		(width 0.18288)
		(layer "In11.Cu")
		(net "M_H_CPU1_SB_DQS_DP<9>")
	)
	(segment
		(start 176.695354 -235.991146)
		(end 176.403762 -235.699554)
		(width 0.18288)
		(layer "In11.Cu")
		(net "M_H_CPU1_SB_DQS_DP<9>")
	)
	(segment
		(start 168.574212 -236.59211)
		(end 167.874188 -237.292134)
		(width 0.18288)
		(layer "In11.Cu")
		(net "M_H_CPU1_SB_DQS_DP<9>")
	)
	(segment
		(start 202.243436 -237.85957)
		(end 202.061826 -237.67796)
		(width 0.18288)
		(layer "In11.Cu")
		(net "M_H_CPU1_SB_DQS_DP<9>")
	)
	(segment
		(start 178.69408 -236.353858)
		(end 178.0667 -235.726478)
		(width 0.18288)
		(layer "In11.Cu")
		(net "M_H_CPU1_SB_DQS_DP<9>")
	)
	(segment
		(start 176.403762 -235.699554)
		(end 175.199548 -235.699554)
		(width 0.18288)
		(layer "In11.Cu")
		(net "M_H_CPU1_SB_DQS_DP<9>")
	)
	(segment
		(start 124.140214 -242.78463)
		(end 124.125482 -242.793266)
		(width 0.088646)
		(layer "In11.Cu")
		(net "M_H_CPU1_SB_DQS_DP<9>")
	)
	(segment
		(start 179.866798 -235.875576)
		(end 179.388516 -236.353858)
		(width 0.18288)
		(layer "In11.Cu")
		(net "M_H_CPU1_SB_DQS_DP<9>")
	)
	(segment
		(start 194.239642 -237.388146)
		(end 193.351404 -238.276384)
		(width 0.18288)
		(layer "In11.Cu")
		(net "M_H_CPU1_SB_DQS_DP<9>")
	)
	(segment
		(start 193.351404 -238.276384)
		(end 192.464436 -238.276384)
		(width 0.18288)
		(layer "In11.Cu")
		(net "M_H_CPU1_SB_DQS_DP<9>")
	)
	(segment
		(start 126.020068 -242.78463)
		(end 126.009654 -242.790726)
		(width 0.088646)
		(layer "In11.Cu")
		(net "M_H_CPU1_SB_DQS_DP<9>")
	)
	(segment
		(start 188.111384 -236.840776)
		(end 187.589668 -236.840776)
		(width 0.18288)
		(layer "In11.Cu")
		(net "M_H_CPU1_SB_DQS_DP<9>")
	)
	(segment
		(start 129.779014 -242.78463)
		(end 129.764282 -242.793266)
		(width 0.088646)
		(layer "In11.Cu")
		(net "M_H_CPU1_SB_DQS_DP<9>")
	)
	(segment
		(start 153.020776 -238.506254)
		(end 148.066506 -243.460524)
		(width 0.18288)
		(layer "In11.Cu")
		(net "M_H_CPU1_SB_DQS_DP<9>")
	)
	(segment
		(start 167.874188 -237.292134)
		(end 160.200086 -237.292134)
		(width 0.18288)
		(layer "In11.Cu")
		(net "M_H_CPU1_SB_DQS_DP<9>")
	)
	(segment
		(start 172.500798 -236.84103)
		(end 172.251878 -236.59211)
		(width 0.18288)
		(layer "In11.Cu")
		(net "M_H_CPU1_SB_DQS_DP<9>")
	)
	(segment
		(start 131.658614 -242.78463)
		(end 131.643882 -242.793266)
		(width 0.088646)
		(layer "In11.Cu")
		(net "M_H_CPU1_SB_DQS_DP<9>")
	)
	(segment
		(start 125.080014 -242.78463)
		(end 125.065282 -242.793266)
		(width 0.088646)
		(layer "In11.Cu")
		(net "M_H_CPU1_SB_DQS_DP<9>")
	)
	(segment
		(start 188.784484 -236.575854)
		(end 188.376306 -236.575854)
		(width 0.18288)
		(layer "In11.Cu")
		(net "M_H_CPU1_SB_DQS_DP<9>")
	)
	(segment
		(start 141.103096 -243.460524)
		(end 141.043152 -243.40058)
		(width 0.088646)
		(layer "In11.Cu")
		(net "M_H_CPU1_SB_DQS_DP<9>")
	)
	(segment
		(start 191.445134 -238.233966)
		(end 190.442596 -238.233966)
		(width 0.18288)
		(layer "In11.Cu")
		(net "M_H_CPU1_SB_DQS_DP<9>")
	)
	(segment
		(start 173.288706 -236.576362)
		(end 173.024038 -236.84103)
		(width 0.18288)
		(layer "In11.Cu")
		(net "M_H_CPU1_SB_DQS_DP<9>")
	)
	(segment
		(start 175.199548 -235.699554)
		(end 174.32274 -236.576362)
		(width 0.18288)
		(layer "In11.Cu")
		(net "M_H_CPU1_SB_DQS_DP<9>")
	)
	(segment
		(start 199.866504 -237.67796)
		(end 199.165464 -237.388146)
		(width 0.18288)
		(layer "In11.Cu")
		(net "M_H_CPU1_SB_DQS_DP<9>")
	)
	(segment
		(start 178.0667 -235.726478)
		(end 177.388774 -235.726478)
		(width 0.18288)
		(layer "In11.Cu")
		(net "M_H_CPU1_SB_DQS_DP<9>")
	)
	(segment
		(start 158.985966 -238.506254)
		(end 153.020776 -238.506254)
		(width 0.18288)
		(layer "In11.Cu")
		(net "M_H_CPU1_SB_DQS_DP<9>")
	)
	(segment
		(start 174.32274 -236.576362)
		(end 173.288706 -236.576362)
		(width 0.18288)
		(layer "In11.Cu")
		(net "M_H_CPU1_SB_DQS_DP<9>")
	)
	(segment
		(start 177.388774 -235.726478)
		(end 177.124106 -235.991146)
		(width 0.18288)
		(layer "In11.Cu")
		(net "M_H_CPU1_SB_DQS_DP<9>")
	)
	(segment
		(start 184.329324 -236.580426)
		(end 183.624474 -235.875576)
		(width 0.18288)
		(layer "In11.Cu")
		(net "M_H_CPU1_SB_DQS_DP<9>")
	)
	(segment
		(start 202.061826 -237.67796)
		(end 199.866504 -237.67796)
		(width 0.18288)
		(layer "In11.Cu")
		(net "M_H_CPU1_SB_DQS_DP<9>")
	)
	(segment
		(start 177.124106 -235.991146)
		(end 176.695354 -235.991146)
		(width 0.18288)
		(layer "In11.Cu")
		(net "M_H_CPU1_SB_DQS_DP<9>")
	)
	(segment
		(start 187.329318 -236.580426)
		(end 184.329324 -236.580426)
		(width 0.18288)
		(layer "In11.Cu")
		(net "M_H_CPU1_SB_DQS_DP<9>")
	)
	(segment
		(start 187.589668 -236.840776)
		(end 187.329318 -236.580426)
		(width 0.18288)
		(layer "In11.Cu")
		(net "M_H_CPU1_SB_DQS_DP<9>")
	)
	(segment
		(start 183.624474 -235.875576)
		(end 179.866798 -235.875576)
		(width 0.18288)
		(layer "In11.Cu")
		(net "M_H_CPU1_SB_DQS_DP<9>")
	)
	(segment
		(start 123.23064 -242.294918)
		(end 122.917966 -242.294918)
		(width 0.088646)
		(layer "In11.Cu")
		(net "M_H_CPU1_SB_DQS_DP<9>")
	)
	(segment
		(start 192.464436 -238.276384)
		(end 192.198498 -238.542322)
		(width 0.18288)
		(layer "In11.Cu")
		(net "M_H_CPU1_SB_DQS_DP<9>")
	)
	(segment
		(start 127.899414 -242.78463)
		(end 127.884682 -242.793266)
		(width 0.088646)
		(layer "In11.Cu")
		(net "M_H_CPU1_SB_DQS_DP<9>")
	)
	(segment
		(start 173.024038 -236.84103)
		(end 172.500798 -236.84103)
		(width 0.18288)
		(layer "In11.Cu")
		(net "M_H_CPU1_SB_DQS_DP<9>")
	)
	(segment
		(start 130.718814 -242.78463)
		(end 130.704082 -242.793266)
		(width 0.088646)
		(layer "In11.Cu")
		(net "M_H_CPU1_SB_DQS_DP<9>")
	)
	(segment
		(start 128.839214 -242.78463)
		(end 128.824482 -242.793266)
		(width 0.088646)
		(layer "In11.Cu")
		(net "M_H_CPU1_SB_DQS_DP<9>")
	)
	(segment
		(start 141.043152 -243.40058)
		(end 137.36701 -243.40058)
		(width 0.088646)
		(layer "In11.Cu")
		(net "M_H_CPU1_SB_DQS_DP<9>")
	)
	(arc
		(start 128.27381 -242.78463)
		(mid 128.086612 -242.734487)
		(end 127.899414 -242.78463)
		(width 0.088646)
		(layer "In11.Cu")
		(net "M_H_CPU1_SB_DQS_DP<9>")
	)
	(arc
		(start 131.643882 -242.793266)
		(mid 131.367441 -242.860432)
		(end 131.09321 -242.78463)
		(width 0.088646)
		(layer "In11.Cu")
		(net "M_H_CPU1_SB_DQS_DP<9>")
	)
	(arc
		(start 134.4676 -242.790726)
		(mid 134.189422 -242.860418)
		(end 133.912864 -242.78463)
		(width 0.088646)
		(layer "In11.Cu")
		(net "M_H_CPU1_SB_DQS_DP<9>")
	)
	(arc
		(start 127.884682 -242.793266)
		(mid 127.608241 -242.860432)
		(end 127.33401 -242.78463)
		(width 0.088646)
		(layer "In11.Cu")
		(net "M_H_CPU1_SB_DQS_DP<9>")
	)
	(arc
		(start 126.009654 -242.790726)
		(mid 125.731222 -242.860572)
		(end 125.45441 -242.78463)
		(width 0.088646)
		(layer "In11.Cu")
		(net "M_H_CPU1_SB_DQS_DP<9>")
	)
	(arc
		(start 127.33401 -242.78463)
		(mid 127.146812 -242.734487)
		(end 126.959614 -242.78463)
		(width 0.088646)
		(layer "In11.Cu")
		(net "M_H_CPU1_SB_DQS_DP<9>")
	)
	(arc
		(start 136.732264 -242.78463)
		(mid 136.545066 -242.734487)
		(end 136.357868 -242.78463)
		(width 0.088646)
		(layer "In11.Cu")
		(net "M_H_CPU1_SB_DQS_DP<9>")
	)
	(arc
		(start 125.45441 -242.78463)
		(mid 125.267212 -242.734487)
		(end 125.080014 -242.78463)
		(width 0.088646)
		(layer "In11.Cu")
		(net "M_H_CPU1_SB_DQS_DP<9>")
	)
	(arc
		(start 132.588254 -242.790726)
		(mid 132.309822 -242.86054)
		(end 132.03301 -242.78463)
		(width 0.088646)
		(layer "In11.Cu")
		(net "M_H_CPU1_SB_DQS_DP<9>")
	)
	(arc
		(start 123.298712 -242.381532)
		(mid 123.297214 -242.370877)
		(end 123.295918 -242.360196)
		(width 0.088646)
		(layer "In11.Cu")
		(net "M_H_CPU1_SB_DQS_DP<9>")
	)
	(arc
		(start 135.792464 -242.78463)
		(mid 135.605266 -242.734487)
		(end 135.418068 -242.78463)
		(width 0.088646)
		(layer "In11.Cu")
		(net "M_H_CPU1_SB_DQS_DP<9>")
	)
	(arc
		(start 135.407654 -242.790726)
		(mid 135.129222 -242.86054)
		(end 134.85241 -242.78463)
		(width 0.088646)
		(layer "In11.Cu")
		(net "M_H_CPU1_SB_DQS_DP<9>")
	)
	(arc
		(start 133.912864 -242.78463)
		(mid 133.725666 -242.734487)
		(end 133.538468 -242.78463)
		(width 0.088646)
		(layer "In11.Cu")
		(net "M_H_CPU1_SB_DQS_DP<9>")
	)
	(arc
		(start 123.57481 -242.78463)
		(mid 123.390986 -242.614436)
		(end 123.298712 -242.381532)
		(width 0.088646)
		(layer "In11.Cu")
		(net "M_H_CPU1_SB_DQS_DP<9>")
	)
	(arc
		(start 131.09321 -242.78463)
		(mid 130.906012 -242.734487)
		(end 130.718814 -242.78463)
		(width 0.088646)
		(layer "In11.Cu")
		(net "M_H_CPU1_SB_DQS_DP<9>")
	)
	(arc
		(start 124.125482 -242.793266)
		(mid 123.849007 -242.860556)
		(end 123.57481 -242.78463)
		(width 0.088646)
		(layer "In11.Cu")
		(net "M_H_CPU1_SB_DQS_DP<9>")
	)
	(arc
		(start 136.810242 -242.843812)
		(mid 136.773192 -242.811666)
		(end 136.732264 -242.78463)
		(width 0.088646)
		(layer "In11.Cu")
		(net "M_H_CPU1_SB_DQS_DP<9>")
	)
	(arc
		(start 128.824482 -242.793266)
		(mid 128.548041 -242.860432)
		(end 128.27381 -242.78463)
		(width 0.088646)
		(layer "In11.Cu")
		(net "M_H_CPU1_SB_DQS_DP<9>")
	)
	(arc
		(start 132.973064 -242.78463)
		(mid 132.785866 -242.734487)
		(end 132.598668 -242.78463)
		(width 0.088646)
		(layer "In11.Cu")
		(net "M_H_CPU1_SB_DQS_DP<9>")
	)
	(arc
		(start 134.85241 -242.78463)
		(mid 134.665212 -242.734487)
		(end 134.478014 -242.78463)
		(width 0.088646)
		(layer "In11.Cu")
		(net "M_H_CPU1_SB_DQS_DP<9>")
	)
	(arc
		(start 129.21361 -242.78463)
		(mid 129.026412 -242.734487)
		(end 128.839214 -242.78463)
		(width 0.088646)
		(layer "In11.Cu")
		(net "M_H_CPU1_SB_DQS_DP<9>")
	)
	(arc
		(start 126.394464 -242.78463)
		(mid 126.207266 -242.734487)
		(end 126.020068 -242.78463)
		(width 0.088646)
		(layer "In11.Cu")
		(net "M_H_CPU1_SB_DQS_DP<9>")
	)
	(arc
		(start 133.538468 -242.78463)
		(mid 133.255766 -242.860372)
		(end 132.973064 -242.78463)
		(width 0.088646)
		(layer "In11.Cu")
		(net "M_H_CPU1_SB_DQS_DP<9>")
	)
	(arc
		(start 130.15341 -242.78463)
		(mid 129.966212 -242.734487)
		(end 129.779014 -242.78463)
		(width 0.088646)
		(layer "In11.Cu")
		(net "M_H_CPU1_SB_DQS_DP<9>")
	)
	(arc
		(start 125.065282 -242.793266)
		(mid 124.788807 -242.860586)
		(end 124.51461 -242.78463)
		(width 0.088646)
		(layer "In11.Cu")
		(net "M_H_CPU1_SB_DQS_DP<9>")
	)
	(arc
		(start 136.357868 -242.78463)
		(mid 136.075166 -242.860372)
		(end 135.792464 -242.78463)
		(width 0.088646)
		(layer "In11.Cu")
		(net "M_H_CPU1_SB_DQS_DP<9>")
	)
	(arc
		(start 130.704082 -242.793266)
		(mid 130.427641 -242.860432)
		(end 130.15341 -242.78463)
		(width 0.088646)
		(layer "In11.Cu")
		(net "M_H_CPU1_SB_DQS_DP<9>")
	)
	(arc
		(start 126.959614 -242.78463)
		(mid 126.683055 -242.860373)
		(end 126.404878 -242.790726)
		(width 0.088646)
		(layer "In11.Cu")
		(net "M_H_CPU1_SB_DQS_DP<9>")
	)
	(arc
		(start 132.03301 -242.78463)
		(mid 131.845812 -242.734487)
		(end 131.658614 -242.78463)
		(width 0.088646)
		(layer "In11.Cu")
		(net "M_H_CPU1_SB_DQS_DP<9>")
	)
	(arc
		(start 124.51461 -242.78463)
		(mid 124.327412 -242.734487)
		(end 124.140214 -242.78463)
		(width 0.088646)
		(layer "In11.Cu")
		(net "M_H_CPU1_SB_DQS_DP<9>")
	)
	(arc
		(start 129.764282 -242.793266)
		(mid 129.487841 -242.860432)
		(end 129.21361 -242.78463)
		(width 0.088646)
		(layer "In11.Cu")
		(net "M_H_CPU1_SB_DQS_DP<9>")
	)
	(segment
		(start 209.020664 -199.267826)
		(end 209.325464 -199.267826)
		(width 0.20066)
		(layer "F.Cu")
		(net "M_H_CPU1_SB_DQS_DP<8>")
	)
	(segment
		(start 209.325464 -199.267826)
		(end 209.750406 -198.842884)
		(width 0.20066)
		(layer "F.Cu")
		(net "M_H_CPU1_SB_DQS_DP<8>")
	)
	(segment
		(start 125.737366 -228.180646)
		(end 125.737366 -227.64496)
		(width 0.20066)
		(layer "F.Cu")
		(net "M_H_CPU1_SB_DQS_DP<8>")
	)
	(segment
		(start 207.071214 -199.01662)
		(end 208.176114 -199.01662)
		(width 0.20066)
		(layer "F.Cu")
		(net "M_H_CPU1_SB_DQS_DP<8>")
	)
	(segment
		(start 212.622892 -198.591678)
		(end 212.630258 -198.584312)
		(width 0.1016)
		(layer "F.Cu")
		(net "M_H_CPU1_SB_DQS_DP<8>")
	)
	(segment
		(start 210.598258 -198.584566)
		(end 210.603084 -198.584566)
		(width 0.101854)
		(layer "F.Cu")
		(net "M_H_CPU1_SB_DQS_DP<8>")
	)
	(segment
		(start 213.207092 -198.839328)
		(end 213.860634 -198.839328)
		(width 0.20066)
		(layer "F.Cu")
		(net "M_H_CPU1_SB_DQS_DP<8>")
	)
	(segment
		(start 210.287108 -198.584566)
		(end 210.598258 -198.584566)
		(width 0.20066)
		(layer "F.Cu")
		(net "M_H_CPU1_SB_DQS_DP<8>")
	)
	(segment
		(start 210.603084 -198.584566)
		(end 210.610196 -198.591678)
		(width 0.1016)
		(layer "F.Cu")
		(net "M_H_CPU1_SB_DQS_DP<8>")
	)
	(segment
		(start 213.860634 -198.839328)
		(end 214.30615 -199.284844)
		(width 0.20066)
		(layer "F.Cu")
		(net "M_H_CPU1_SB_DQS_DP<8>")
	)
	(segment
		(start 212.630258 -198.584312)
		(end 212.952076 -198.584312)
		(width 0.20066)
		(layer "F.Cu")
		(net "M_H_CPU1_SB_DQS_DP<8>")
	)
	(segment
		(start 215.15197 -199.01662)
		(end 215.719914 -199.01662)
		(width 0.20066)
		(layer "F.Cu")
		(net "M_H_CPU1_SB_DQS_DP<8>")
	)
	(segment
		(start 208.769458 -199.01662)
		(end 209.020664 -199.267826)
		(width 0.20066)
		(layer "F.Cu")
		(net "M_H_CPU1_SB_DQS_DP<8>")
	)
	(segment
		(start 214.883746 -199.284844)
		(end 215.15197 -199.01662)
		(width 0.20066)
		(layer "F.Cu")
		(net "M_H_CPU1_SB_DQS_DP<8>")
	)
	(segment
		(start 208.176114 -199.01662)
		(end 208.769458 -199.01662)
		(width 0.20066)
		(layer "F.Cu")
		(net "M_H_CPU1_SB_DQS_DP<8>")
	)
	(segment
		(start 210.610196 -198.591678)
		(end 212.622892 -198.591678)
		(width 0.1016)
		(layer "F.Cu")
		(net "M_H_CPU1_SB_DQS_DP<8>")
	)
	(segment
		(start 212.952076 -198.584312)
		(end 213.207092 -198.839328)
		(width 0.20066)
		(layer "F.Cu")
		(net "M_H_CPU1_SB_DQS_DP<8>")
	)
	(segment
		(start 214.30615 -199.284844)
		(end 214.883746 -199.284844)
		(width 0.20066)
		(layer "F.Cu")
		(net "M_H_CPU1_SB_DQS_DP<8>")
	)
	(segment
		(start 125.737112 -228.1809)
		(end 125.737366 -228.180646)
		(width 0.20066)
		(layer "F.Cu")
		(net "M_H_CPU1_SB_DQS_DP<8>")
	)
	(segment
		(start 209.750406 -198.842884)
		(end 210.02879 -198.842884)
		(width 0.20066)
		(layer "F.Cu")
		(net "M_H_CPU1_SB_DQS_DP<8>")
	)
	(segment
		(start 210.02879 -198.842884)
		(end 210.287108 -198.584566)
		(width 0.20066)
		(layer "F.Cu")
		(net "M_H_CPU1_SB_DQS_DP<8>")
	)
	(segment
		(start 125.842268 -227.875084)
		(end 125.82017 -227.865686)
		(width 0.088646)
		(layer "In11.Cu")
		(net "M_H_CPU1_SB_DQS_DP<8>")
	)
	(segment
		(start 194.46367 -201.213466)
		(end 193.962782 -201.213466)
		(width 0.18288)
		(layer "In11.Cu")
		(net "M_H_CPU1_SB_DQS_DP<8>")
	)
	(segment
		(start 166.604696 -202.003914)
		(end 166.480236 -201.879454)
		(width 0.18288)
		(layer "In11.Cu")
		(net "M_H_CPU1_SB_DQS_DP<8>")
	)
	(segment
		(start 176.62779 -200.291192)
		(end 176.35855 -200.560432)
		(width 0.18288)
		(layer "In11.Cu")
		(net "M_H_CPU1_SB_DQS_DP<8>")
	)
	(segment
		(start 158.30169 -201.874374)
		(end 158.17723 -201.998834)
		(width 0.18288)
		(layer "In11.Cu")
		(net "M_H_CPU1_SB_DQS_DP<8>")
	)
	(segment
		(start 178.238404 -200.566528)
		(end 177.371502 -200.566528)
		(width 0.18288)
		(layer "In11.Cu")
		(net "M_H_CPU1_SB_DQS_DP<8>")
	)
	(segment
		(start 203.163678 -201.14133)
		(end 202.742038 -201.14133)
		(width 0.18288)
		(layer "In11.Cu")
		(net "M_H_CPU1_SB_DQS_DP<8>")
	)
	(segment
		(start 134.397496 -227.960682)
		(end 134.382764 -227.969318)
		(width 0.088646)
		(layer "In11.Cu")
		(net "M_H_CPU1_SB_DQS_DP<8>")
	)
	(segment
		(start 185.149236 -201.276966)
		(end 185.024776 -201.401426)
		(width 0.18288)
		(layer "In11.Cu")
		(net "M_H_CPU1_SB_DQS_DP<8>")
	)
	(segment
		(start 130.638296 -227.960682)
		(end 130.623564 -227.969318)
		(width 0.088646)
		(layer "In11.Cu")
		(net "M_H_CPU1_SB_DQS_DP<8>")
	)
	(segment
		(start 201.315574 -201.290936)
		(end 200.766934 -201.290936)
		(width 0.18288)
		(layer "In11.Cu")
		(net "M_H_CPU1_SB_DQS_DP<8>")
	)
	(segment
		(start 163.272216 -201.467466)
		(end 163.147756 -201.343006)
		(width 0.18288)
		(layer "In11.Cu")
		(net "M_H_CPU1_SB_DQS_DP<8>")
	)
	(segment
		(start 155.980892 -204.844142)
		(end 147.739862 -213.085172)
		(width 0.18288)
		(layer "In11.Cu")
		(net "M_H_CPU1_SB_DQS_DP<8>")
	)
	(segment
		(start 198.20382 -200.810622)
		(end 194.866514 -200.810622)
		(width 0.18288)
		(layer "In11.Cu")
		(net "M_H_CPU1_SB_DQS_DP<8>")
	)
	(segment
		(start 165.807136 -202.003914)
		(end 165.157404 -202.003914)
		(width 0.18288)
		(layer "In11.Cu")
		(net "M_H_CPU1_SB_DQS_DP<8>")
	)
	(segment
		(start 181.16296 -201.876152)
		(end 181.0385 -202.000612)
		(width 0.18288)
		(layer "In11.Cu")
		(net "M_H_CPU1_SB_DQS_DP<8>")
	)
	(segment
		(start 173.612048 -201.285602)
		(end 173.481238 -201.416666)
		(width 0.18288)
		(layer "In11.Cu")
		(net "M_H_CPU1_SB_DQS_DP<8>")
	)
	(segment
		(start 138.79957 -226.617784)
		(end 138.79957 -226.839018)
		(width 0.088646)
		(layer "In11.Cu")
		(net "M_H_CPU1_SB_DQS_DP<8>")
	)
	(segment
		(start 136.449816 -227.635054)
		(end 136.449816 -227.64496)
		(width 0.088646)
		(layer "In11.Cu")
		(net "M_H_CPU1_SB_DQS_DP<8>")
	)
	(segment
		(start 126.489968 -227.969318)
		(end 126.332742 -227.884482)
		(width 0.088646)
		(layer "In11.Cu")
		(net "M_H_CPU1_SB_DQS_DP<8>")
	)
	(segment
		(start 188.064394 -201.14133)
		(end 187.615322 -201.14133)
		(width 0.18288)
		(layer "In11.Cu")
		(net "M_H_CPU1_SB_DQS_DP<8>")
	)
	(segment
		(start 168.319196 -201.839068)
		(end 167.49014 -202.003914)
		(width 0.18288)
		(layer "In11.Cu")
		(net "M_H_CPU1_SB_DQS_DP<8>")
	)
	(segment
		(start 172.527722 -201.14133)
		(end 172.239178 -201.429874)
		(width 0.18288)
		(layer "In11.Cu")
		(net "M_H_CPU1_SB_DQS_DP<8>")
	)
	(segment
		(start 167.49014 -202.003914)
		(end 166.604696 -202.003914)
		(width 0.18288)
		(layer "In11.Cu")
		(net "M_H_CPU1_SB_DQS_DP<8>")
	)
	(segment
		(start 206.803244 -199.28459)
		(end 206.11846 -199.28459)
		(width 0.18288)
		(layer "In11.Cu")
		(net "M_H_CPU1_SB_DQS_DP<8>")
	)
	(segment
		(start 162.474656 -201.467466)
		(end 161.522918 -201.467466)
		(width 0.18288)
		(layer "In11.Cu")
		(net "M_H_CPU1_SB_DQS_DP<8>")
	)
	(segment
		(start 147.739862 -215.885522)
		(end 141.184884 -222.4405)
		(width 0.18288)
		(layer "In11.Cu")
		(net "M_H_CPU1_SB_DQS_DP<8>")
	)
	(segment
		(start 189.906148 -200.578466)
		(end 189.052454 -201.43216)
		(width 0.18288)
		(layer "In11.Cu")
		(net "M_H_CPU1_SB_DQS_DP<8>")
	)
	(segment
		(start 192.467738 -200.5711)
		(end 192.18783 -200.291192)
		(width 0.18288)
		(layer "In11.Cu")
		(net "M_H_CPU1_SB_DQS_DP<8>")
	)
	(segment
		(start 141.184884 -223.472502)
		(end 140.123418 -224.533968)
		(width 0.18288)
		(layer "In11.Cu")
		(net "M_H_CPU1_SB_DQS_DP<8>")
	)
	(segment
		(start 187.615322 -201.14133)
		(end 187.355226 -201.401426)
		(width 0.18288)
		(layer "In11.Cu")
		(net "M_H_CPU1_SB_DQS_DP<8>")
	)
	(segment
		(start 166.480236 -201.879454)
		(end 165.931596 -201.879454)
		(width 0.18288)
		(layer "In11.Cu")
		(net "M_H_CPU1_SB_DQS_DP<8>")
	)
	(segment
		(start 169.10177 -201.683112)
		(end 168.955466 -201.585322)
		(width 0.18288)
		(layer "In11.Cu")
		(net "M_H_CPU1_SB_DQS_DP<8>")
	)
	(segment
		(start 185.024776 -201.401426)
		(end 184.341262 -201.401426)
		(width 0.18288)
		(layer "In11.Cu")
		(net "M_H_CPU1_SB_DQS_DP<8>")
	)
	(segment
		(start 168.416986 -201.69251)
		(end 168.319196 -201.839068)
		(width 0.18288)
		(layer "In11.Cu")
		(net "M_H_CPU1_SB_DQS_DP<8>")
	)
	(segment
		(start 173.276514 -201.416666)
		(end 173.001178 -201.14133)
		(width 0.18288)
		(layer "In11.Cu")
		(net "M_H_CPU1_SB_DQS_DP<8>")
	)
	(segment
		(start 185.822336 -201.401426)
		(end 185.697876 -201.276966)
		(width 0.18288)
		(layer "In11.Cu")
		(net "M_H_CPU1_SB_DQS_DP<8>")
	)
	(segment
		(start 162.599116 -201.343006)
		(end 162.474656 -201.467466)
		(width 0.18288)
		(layer "In11.Cu")
		(net "M_H_CPU1_SB_DQS_DP<8>")
	)
	(segment
		(start 181.83606 -202.000612)
		(end 181.7116 -201.876152)
		(width 0.18288)
		(layer "In11.Cu")
		(net "M_H_CPU1_SB_DQS_DP<8>")
	)
	(segment
		(start 185.697876 -201.276966)
		(end 185.149236 -201.276966)
		(width 0.18288)
		(layer "In11.Cu")
		(net "M_H_CPU1_SB_DQS_DP<8>")
	)
	(segment
		(start 141.184884 -222.4405)
		(end 141.184884 -223.472502)
		(width 0.18288)
		(layer "In11.Cu")
		(net "M_H_CPU1_SB_DQS_DP<8>")
	)
	(segment
		(start 194.866514 -200.810622)
		(end 194.46367 -201.213466)
		(width 0.18288)
		(layer "In11.Cu")
		(net "M_H_CPU1_SB_DQS_DP<8>")
	)
	(segment
		(start 187.355226 -201.401426)
		(end 185.822336 -201.401426)
		(width 0.18288)
		(layer "In11.Cu")
		(net "M_H_CPU1_SB_DQS_DP<8>")
	)
	(segment
		(start 147.739862 -213.085172)
		(end 147.739862 -215.885522)
		(width 0.18288)
		(layer "In11.Cu")
		(net "M_H_CPU1_SB_DQS_DP<8>")
	)
	(segment
		(start 182.894732 -202.000612)
		(end 181.83606 -202.000612)
		(width 0.18288)
		(layer "In11.Cu")
		(net "M_H_CPU1_SB_DQS_DP<8>")
	)
	(segment
		(start 126.332742 -227.884482)
		(end 125.842268 -227.875084)
		(width 0.088646)
		(layer "In11.Cu")
		(net "M_H_CPU1_SB_DQS_DP<8>")
	)
	(segment
		(start 177.096166 -200.291192)
		(end 176.62779 -200.291192)
		(width 0.18288)
		(layer "In11.Cu")
		(net "M_H_CPU1_SB_DQS_DP<8>")
	)
	(segment
		(start 125.737366 -227.769928)
		(end 125.737366 -227.64496)
		(width 0.088646)
		(layer "In11.Cu")
		(net "M_H_CPU1_SB_DQS_DP<8>")
	)
	(segment
		(start 126.874778 -227.963222)
		(end 126.864364 -227.969318)
		(width 0.088646)
		(layer "In11.Cu")
		(net "M_H_CPU1_SB_DQS_DP<8>")
	)
	(segment
		(start 139.00785 -226.409504)
		(end 138.79957 -226.617784)
		(width 0.088646)
		(layer "In11.Cu")
		(net "M_H_CPU1_SB_DQS_DP<8>")
	)
	(segment
		(start 191.428116 -200.578466)
		(end 189.906148 -200.578466)
		(width 0.18288)
		(layer "In11.Cu")
		(net "M_H_CPU1_SB_DQS_DP<8>")
	)
	(segment
		(start 140.123418 -224.533968)
		(end 140.123418 -224.618296)
		(width 0.088646)
		(layer "In11.Cu")
		(net "M_H_CPU1_SB_DQS_DP<8>")
	)
	(segment
		(start 184.341262 -201.401426)
		(end 182.894732 -202.000612)
		(width 0.18288)
		(layer "In11.Cu")
		(net "M_H_CPU1_SB_DQS_DP<8>")
	)
	(segment
		(start 202.742038 -201.14133)
		(end 202.467972 -201.415396)
		(width 0.18288)
		(layer "In11.Cu")
		(net "M_H_CPU1_SB_DQS_DP<8>")
	)
	(segment
		(start 129.698496 -227.960682)
		(end 129.683764 -227.969318)
		(width 0.088646)
		(layer "In11.Cu")
		(net "M_H_CPU1_SB_DQS_DP<8>")
	)
	(segment
		(start 200.642474 -201.415396)
		(end 199.663812 -201.415396)
		(width 0.18288)
		(layer "In11.Cu")
		(net "M_H_CPU1_SB_DQS_DP<8>")
	)
	(segment
		(start 181.7116 -201.876152)
		(end 181.16296 -201.876152)
		(width 0.18288)
		(layer "In11.Cu")
		(net "M_H_CPU1_SB_DQS_DP<8>")
	)
	(segment
		(start 160.99155 -201.998834)
		(end 158.97479 -201.998834)
		(width 0.18288)
		(layer "In11.Cu")
		(net "M_H_CPU1_SB_DQS_DP<8>")
	)
	(segment
		(start 201.440034 -201.415396)
		(end 201.315574 -201.290936)
		(width 0.18288)
		(layer "In11.Cu")
		(net "M_H_CPU1_SB_DQS_DP<8>")
	)
	(segment
		(start 168.955466 -201.585322)
		(end 168.416986 -201.69251)
		(width 0.18288)
		(layer "In11.Cu")
		(net "M_H_CPU1_SB_DQS_DP<8>")
	)
	(segment
		(start 176.35855 -200.560432)
		(end 175.363378 -200.560432)
		(width 0.18288)
		(layer "In11.Cu")
		(net "M_H_CPU1_SB_DQS_DP<8>")
	)
	(segment
		(start 175.363378 -200.560432)
		(end 173.612048 -201.285602)
		(width 0.18288)
		(layer "In11.Cu")
		(net "M_H_CPU1_SB_DQS_DP<8>")
	)
	(segment
		(start 193.320416 -200.5711)
		(end 192.467738 -200.5711)
		(width 0.18288)
		(layer "In11.Cu")
		(net "M_H_CPU1_SB_DQS_DP<8>")
	)
	(segment
		(start 193.962782 -201.213466)
		(end 193.320416 -200.5711)
		(width 0.18288)
		(layer "In11.Cu")
		(net "M_H_CPU1_SB_DQS_DP<8>")
	)
	(segment
		(start 131.578096 -227.960682)
		(end 131.563364 -227.969318)
		(width 0.088646)
		(layer "In11.Cu")
		(net "M_H_CPU1_SB_DQS_DP<8>")
	)
	(segment
		(start 180.25618 -202.000612)
		(end 179.259738 -201.587608)
		(width 0.18288)
		(layer "In11.Cu")
		(net "M_H_CPU1_SB_DQS_DP<8>")
	)
	(segment
		(start 202.467972 -201.415396)
		(end 201.440034 -201.415396)
		(width 0.18288)
		(layer "In11.Cu")
		(net "M_H_CPU1_SB_DQS_DP<8>")
	)
	(segment
		(start 189.052454 -201.43216)
		(end 188.355224 -201.43216)
		(width 0.18288)
		(layer "In11.Cu")
		(net "M_H_CPU1_SB_DQS_DP<8>")
	)
	(segment
		(start 177.371502 -200.566528)
		(end 177.096166 -200.291192)
		(width 0.18288)
		(layer "In11.Cu")
		(net "M_H_CPU1_SB_DQS_DP<8>")
	)
	(segment
		(start 125.82017 -227.865686)
		(end 125.746764 -227.79228)
		(width 0.088646)
		(layer "In11.Cu")
		(net "M_H_CPU1_SB_DQS_DP<8>")
	)
	(segment
		(start 188.355224 -201.43216)
		(end 188.064394 -201.14133)
		(width 0.18288)
		(layer "In11.Cu")
		(net "M_H_CPU1_SB_DQS_DP<8>")
	)
	(segment
		(start 158.97479 -201.998834)
		(end 158.85033 -201.874374)
		(width 0.18288)
		(layer "In11.Cu")
		(net "M_H_CPU1_SB_DQS_DP<8>")
	)
	(segment
		(start 203.97089 -201.43216)
		(end 203.454508 -201.43216)
		(width 0.18288)
		(layer "In11.Cu")
		(net "M_H_CPU1_SB_DQS_DP<8>")
	)
	(segment
		(start 199.663812 -201.415396)
		(end 198.20382 -200.810622)
		(width 0.18288)
		(layer "In11.Cu")
		(net "M_H_CPU1_SB_DQS_DP<8>")
	)
	(segment
		(start 158.17723 -201.998834)
		(end 157.428692 -201.998834)
		(width 0.18288)
		(layer "In11.Cu")
		(net "M_H_CPU1_SB_DQS_DP<8>")
	)
	(segment
		(start 181.0385 -202.000612)
		(end 180.25618 -202.000612)
		(width 0.18288)
		(layer "In11.Cu")
		(net "M_H_CPU1_SB_DQS_DP<8>")
	)
	(segment
		(start 139.00785 -225.733864)
		(end 139.00785 -226.409504)
		(width 0.088646)
		(layer "In11.Cu")
		(net "M_H_CPU1_SB_DQS_DP<8>")
	)
	(segment
		(start 163.863528 -201.467466)
		(end 163.272216 -201.467466)
		(width 0.18288)
		(layer "In11.Cu")
		(net "M_H_CPU1_SB_DQS_DP<8>")
	)
	(segment
		(start 157.428692 -201.998834)
		(end 155.980892 -203.446634)
		(width 0.18288)
		(layer "In11.Cu")
		(net "M_H_CPU1_SB_DQS_DP<8>")
	)
	(segment
		(start 172.239178 -201.429874)
		(end 170.375834 -201.429874)
		(width 0.18288)
		(layer "In11.Cu")
		(net "M_H_CPU1_SB_DQS_DP<8>")
	)
	(segment
		(start 165.931596 -201.879454)
		(end 165.807136 -202.003914)
		(width 0.18288)
		(layer "In11.Cu")
		(net "M_H_CPU1_SB_DQS_DP<8>")
	)
	(segment
		(start 203.454508 -201.43216)
		(end 203.163678 -201.14133)
		(width 0.18288)
		(layer "In11.Cu")
		(net "M_H_CPU1_SB_DQS_DP<8>")
	)
	(segment
		(start 191.71539 -200.291192)
		(end 191.428116 -200.578466)
		(width 0.18288)
		(layer "In11.Cu")
		(net "M_H_CPU1_SB_DQS_DP<8>")
	)
	(segment
		(start 161.522918 -201.467466)
		(end 160.99155 -201.998834)
		(width 0.18288)
		(layer "In11.Cu")
		(net "M_H_CPU1_SB_DQS_DP<8>")
	)
	(segment
		(start 200.766934 -201.290936)
		(end 200.642474 -201.415396)
		(width 0.18288)
		(layer "In11.Cu")
		(net "M_H_CPU1_SB_DQS_DP<8>")
	)
	(segment
		(start 140.123418 -224.618296)
		(end 139.00785 -225.733864)
		(width 0.088646)
		(layer "In11.Cu")
		(net "M_H_CPU1_SB_DQS_DP<8>")
	)
	(segment
		(start 165.157404 -202.003914)
		(end 163.863528 -201.467466)
		(width 0.18288)
		(layer "In11.Cu")
		(net "M_H_CPU1_SB_DQS_DP<8>")
	)
	(segment
		(start 125.746764 -227.79228)
		(end 125.737366 -227.769928)
		(width 0.088646)
		(layer "In11.Cu")
		(net "M_H_CPU1_SB_DQS_DP<8>")
	)
	(segment
		(start 158.85033 -201.874374)
		(end 158.30169 -201.874374)
		(width 0.18288)
		(layer "In11.Cu")
		(net "M_H_CPU1_SB_DQS_DP<8>")
	)
	(segment
		(start 155.980892 -203.446634)
		(end 155.980892 -204.844142)
		(width 0.18288)
		(layer "In11.Cu")
		(net "M_H_CPU1_SB_DQS_DP<8>")
	)
	(segment
		(start 163.147756 -201.343006)
		(end 162.599116 -201.343006)
		(width 0.18288)
		(layer "In11.Cu")
		(net "M_H_CPU1_SB_DQS_DP<8>")
	)
	(segment
		(start 192.18783 -200.291192)
		(end 191.71539 -200.291192)
		(width 0.18288)
		(layer "In11.Cu")
		(net "M_H_CPU1_SB_DQS_DP<8>")
	)
	(segment
		(start 207.071214 -199.01662)
		(end 206.803244 -199.28459)
		(width 0.18288)
		(layer "In11.Cu")
		(net "M_H_CPU1_SB_DQS_DP<8>")
	)
	(segment
		(start 173.001178 -201.14133)
		(end 172.527722 -201.14133)
		(width 0.18288)
		(layer "In11.Cu")
		(net "M_H_CPU1_SB_DQS_DP<8>")
	)
	(segment
		(start 170.375834 -201.429874)
		(end 169.10177 -201.683112)
		(width 0.18288)
		(layer "In11.Cu")
		(net "M_H_CPU1_SB_DQS_DP<8>")
	)
	(segment
		(start 128.754124 -227.963222)
		(end 128.74371 -227.969318)
		(width 0.088646)
		(layer "In11.Cu")
		(net "M_H_CPU1_SB_DQS_DP<8>")
	)
	(segment
		(start 179.259738 -201.587608)
		(end 178.238404 -200.566528)
		(width 0.18288)
		(layer "In11.Cu")
		(net "M_H_CPU1_SB_DQS_DP<8>")
	)
	(segment
		(start 206.11846 -199.28459)
		(end 203.97089 -201.43216)
		(width 0.18288)
		(layer "In11.Cu")
		(net "M_H_CPU1_SB_DQS_DP<8>")
	)
	(segment
		(start 173.481238 -201.416666)
		(end 173.276514 -201.416666)
		(width 0.18288)
		(layer "In11.Cu")
		(net "M_H_CPU1_SB_DQS_DP<8>")
	)
	(arc
		(start 127.429514 -227.969318)
		(mid 127.152955 -227.893609)
		(end 126.874778 -227.963222)
		(width 0.088646)
		(layer "In11.Cu")
		(net "M_H_CPU1_SB_DQS_DP<8>")
	)
	(arc
		(start 135.887968 -227.969318)
		(mid 135.605266 -227.893576)
		(end 135.322564 -227.969318)
		(width 0.088646)
		(layer "In11.Cu")
		(net "M_H_CPU1_SB_DQS_DP<8>")
	)
	(arc
		(start 134.382764 -227.969318)
		(mid 134.195566 -228.019461)
		(end 134.008368 -227.969318)
		(width 0.088646)
		(layer "In11.Cu")
		(net "M_H_CPU1_SB_DQS_DP<8>")
	)
	(arc
		(start 132.128768 -227.969318)
		(mid 131.854539 -227.893393)
		(end 131.578096 -227.960682)
		(width 0.088646)
		(layer "In11.Cu")
		(net "M_H_CPU1_SB_DQS_DP<8>")
	)
	(arc
		(start 129.309368 -227.969318)
		(mid 129.032555 -227.893482)
		(end 128.754124 -227.963222)
		(width 0.088646)
		(layer "In11.Cu")
		(net "M_H_CPU1_SB_DQS_DP<8>")
	)
	(arc
		(start 134.008368 -227.969318)
		(mid 133.725666 -227.893576)
		(end 133.442964 -227.969318)
		(width 0.088646)
		(layer "In11.Cu")
		(net "M_H_CPU1_SB_DQS_DP<8>")
	)
	(arc
		(start 137.672064 -227.155502)
		(mid 137.484866 -227.205645)
		(end 137.297668 -227.155502)
		(width 0.088646)
		(layer "In11.Cu")
		(net "M_H_CPU1_SB_DQS_DP<8>")
	)
	(arc
		(start 138.237468 -227.155502)
		(mid 137.954766 -227.079726)
		(end 137.672064 -227.155502)
		(width 0.088646)
		(layer "In11.Cu")
		(net "M_H_CPU1_SB_DQS_DP<8>")
	)
	(arc
		(start 131.188968 -227.969318)
		(mid 130.914739 -227.893393)
		(end 130.638296 -227.960682)
		(width 0.088646)
		(layer "In11.Cu")
		(net "M_H_CPU1_SB_DQS_DP<8>")
	)
	(arc
		(start 130.249168 -227.969318)
		(mid 129.974939 -227.893393)
		(end 129.698496 -227.960682)
		(width 0.088646)
		(layer "In11.Cu")
		(net "M_H_CPU1_SB_DQS_DP<8>")
	)
	(arc
		(start 128.74371 -227.969318)
		(mid 128.556512 -228.019461)
		(end 128.369314 -227.969318)
		(width 0.088646)
		(layer "In11.Cu")
		(net "M_H_CPU1_SB_DQS_DP<8>")
	)
	(arc
		(start 129.683764 -227.969318)
		(mid 129.496566 -228.019461)
		(end 129.309368 -227.969318)
		(width 0.088646)
		(layer "In11.Cu")
		(net "M_H_CPU1_SB_DQS_DP<8>")
	)
	(arc
		(start 133.068568 -227.969318)
		(mid 132.785866 -227.893576)
		(end 132.503164 -227.969318)
		(width 0.088646)
		(layer "In11.Cu")
		(net "M_H_CPU1_SB_DQS_DP<8>")
	)
	(arc
		(start 131.563364 -227.969318)
		(mid 131.376166 -228.019461)
		(end 131.188968 -227.969318)
		(width 0.088646)
		(layer "In11.Cu")
		(net "M_H_CPU1_SB_DQS_DP<8>")
	)
	(arc
		(start 136.449816 -227.64496)
		(mid 136.262462 -227.969179)
		(end 135.887968 -227.969318)
		(width 0.088646)
		(layer "In11.Cu")
		(net "M_H_CPU1_SB_DQS_DP<8>")
	)
	(arc
		(start 138.79957 -226.839018)
		(mid 138.608797 -227.157662)
		(end 138.237468 -227.155502)
		(width 0.088646)
		(layer "In11.Cu")
		(net "M_H_CPU1_SB_DQS_DP<8>")
	)
	(arc
		(start 126.864364 -227.969318)
		(mid 126.677166 -228.019461)
		(end 126.489968 -227.969318)
		(width 0.088646)
		(layer "In11.Cu")
		(net "M_H_CPU1_SB_DQS_DP<8>")
	)
	(arc
		(start 137.297668 -227.155502)
		(mid 136.736692 -227.152971)
		(end 136.449816 -227.635054)
		(width 0.088646)
		(layer "In11.Cu")
		(net "M_H_CPU1_SB_DQS_DP<8>")
	)
	(arc
		(start 134.948168 -227.969318)
		(mid 134.673939 -227.893393)
		(end 134.397496 -227.960682)
		(width 0.088646)
		(layer "In11.Cu")
		(net "M_H_CPU1_SB_DQS_DP<8>")
	)
	(arc
		(start 130.623564 -227.969318)
		(mid 130.436366 -228.019461)
		(end 130.249168 -227.969318)
		(width 0.088646)
		(layer "In11.Cu")
		(net "M_H_CPU1_SB_DQS_DP<8>")
	)
	(arc
		(start 132.503164 -227.969318)
		(mid 132.315966 -228.019461)
		(end 132.128768 -227.969318)
		(width 0.088646)
		(layer "In11.Cu")
		(net "M_H_CPU1_SB_DQS_DP<8>")
	)
	(arc
		(start 135.322564 -227.969318)
		(mid 135.135366 -228.019461)
		(end 134.948168 -227.969318)
		(width 0.088646)
		(layer "In11.Cu")
		(net "M_H_CPU1_SB_DQS_DP<8>")
	)
	(arc
		(start 128.369314 -227.969318)
		(mid 128.086612 -227.893576)
		(end 127.80391 -227.969318)
		(width 0.088646)
		(layer "In11.Cu")
		(net "M_H_CPU1_SB_DQS_DP<8>")
	)
	(arc
		(start 127.80391 -227.969318)
		(mid 127.616712 -228.019461)
		(end 127.429514 -227.969318)
		(width 0.088646)
		(layer "In11.Cu")
		(net "M_H_CPU1_SB_DQS_DP<8>")
	)
	(arc
		(start 133.442964 -227.969318)
		(mid 133.255766 -228.019461)
		(end 133.068568 -227.969318)
		(width 0.088646)
		(layer "In11.Cu")
		(net "M_H_CPU1_SB_DQS_DP<8>")
	)
	(segment
		(start 214.883746 -208.634838)
		(end 215.15197 -208.366614)
		(width 0.20066)
		(layer "F.Cu")
		(net "M_H_CPU1_SB_DQS_DP<7>")
	)
	(segment
		(start 208.176114 -208.366614)
		(end 208.769458 -208.366614)
		(width 0.20066)
		(layer "F.Cu")
		(net "M_H_CPU1_SB_DQS_DP<7>")
	)
	(segment
		(start 212.952076 -207.934306)
		(end 213.207092 -208.189322)
		(width 0.20066)
		(layer "F.Cu")
		(net "M_H_CPU1_SB_DQS_DP<7>")
	)
	(segment
		(start 213.207092 -208.189322)
		(end 213.860634 -208.189322)
		(width 0.20066)
		(layer "F.Cu")
		(net "M_H_CPU1_SB_DQS_DP<7>")
	)
	(segment
		(start 207.071214 -208.366614)
		(end 208.176114 -208.366614)
		(width 0.20066)
		(layer "F.Cu")
		(net "M_H_CPU1_SB_DQS_DP<7>")
	)
	(segment
		(start 210.287108 -207.93456)
		(end 210.598258 -207.93456)
		(width 0.20066)
		(layer "F.Cu")
		(net "M_H_CPU1_SB_DQS_DP<7>")
	)
	(segment
		(start 215.15197 -208.366614)
		(end 215.719914 -208.366614)
		(width 0.20066)
		(layer "F.Cu")
		(net "M_H_CPU1_SB_DQS_DP<7>")
	)
	(segment
		(start 210.598258 -207.93456)
		(end 210.603084 -207.93456)
		(width 0.101854)
		(layer "F.Cu")
		(net "M_H_CPU1_SB_DQS_DP<7>")
	)
	(segment
		(start 213.860634 -208.189322)
		(end 214.30615 -208.634838)
		(width 0.20066)
		(layer "F.Cu")
		(net "M_H_CPU1_SB_DQS_DP<7>")
	)
	(segment
		(start 128.086866 -230.622602)
		(end 128.086612 -230.622348)
		(width 0.20066)
		(layer "F.Cu")
		(net "M_H_CPU1_SB_DQS_DP<7>")
	)
	(segment
		(start 209.750406 -208.192878)
		(end 210.02879 -208.192878)
		(width 0.20066)
		(layer "F.Cu")
		(net "M_H_CPU1_SB_DQS_DP<7>")
	)
	(segment
		(start 128.086612 -230.622348)
		(end 128.086612 -230.086662)
		(width 0.20066)
		(layer "F.Cu")
		(net "M_H_CPU1_SB_DQS_DP<7>")
	)
	(segment
		(start 210.610196 -207.941672)
		(end 212.622892 -207.941672)
		(width 0.1016)
		(layer "F.Cu")
		(net "M_H_CPU1_SB_DQS_DP<7>")
	)
	(segment
		(start 210.603084 -207.93456)
		(end 210.610196 -207.941672)
		(width 0.1016)
		(layer "F.Cu")
		(net "M_H_CPU1_SB_DQS_DP<7>")
	)
	(segment
		(start 209.325464 -208.61782)
		(end 209.750406 -208.192878)
		(width 0.20066)
		(layer "F.Cu")
		(net "M_H_CPU1_SB_DQS_DP<7>")
	)
	(segment
		(start 214.30615 -208.634838)
		(end 214.883746 -208.634838)
		(width 0.20066)
		(layer "F.Cu")
		(net "M_H_CPU1_SB_DQS_DP<7>")
	)
	(segment
		(start 210.02879 -208.192878)
		(end 210.287108 -207.93456)
		(width 0.20066)
		(layer "F.Cu")
		(net "M_H_CPU1_SB_DQS_DP<7>")
	)
	(segment
		(start 209.020664 -208.61782)
		(end 209.325464 -208.61782)
		(width 0.20066)
		(layer "F.Cu")
		(net "M_H_CPU1_SB_DQS_DP<7>")
	)
	(segment
		(start 212.630258 -207.934306)
		(end 212.952076 -207.934306)
		(width 0.20066)
		(layer "F.Cu")
		(net "M_H_CPU1_SB_DQS_DP<7>")
	)
	(segment
		(start 212.622892 -207.941672)
		(end 212.630258 -207.934306)
		(width 0.1016)
		(layer "F.Cu")
		(net "M_H_CPU1_SB_DQS_DP<7>")
	)
	(segment
		(start 208.769458 -208.366614)
		(end 209.020664 -208.61782)
		(width 0.20066)
		(layer "F.Cu")
		(net "M_H_CPU1_SB_DQS_DP<7>")
	)
	(segment
		(start 130.15341 -228.783388)
		(end 130.147314 -228.786944)
		(width 0.088646)
		(layer "In6.Cu")
		(net "M_H_CPU1_SB_DQS_DP<7>")
	)
	(segment
		(start 176.711356 -209.64271)
		(end 176.454308 -209.899758)
		(width 0.18288)
		(layer "In6.Cu")
		(net "M_H_CPU1_SB_DQS_DP<7>")
	)
	(segment
		(start 206.792322 -208.645506)
		(end 206.215488 -208.645506)
		(width 0.18288)
		(layer "In6.Cu")
		(net "M_H_CPU1_SB_DQS_DP<7>")
	)
	(segment
		(start 188.33719 -208.220564)
		(end 188.05906 -207.942434)
		(width 0.18288)
		(layer "In6.Cu")
		(net "M_H_CPU1_SB_DQS_DP<7>")
	)
	(segment
		(start 185.107326 -208.931256)
		(end 178.660044 -208.931256)
		(width 0.18288)
		(layer "In6.Cu")
		(net "M_H_CPU1_SB_DQS_DP<7>")
	)
	(segment
		(start 128.656334 -230.029512)
		(end 128.599184 -230.086662)
		(width 0.088646)
		(layer "In6.Cu")
		(net "M_H_CPU1_SB_DQS_DP<7>")
	)
	(segment
		(start 157.516576 -208.871566)
		(end 155.092146 -211.295996)
		(width 0.18288)
		(layer "In6.Cu")
		(net "M_H_CPU1_SB_DQS_DP<7>")
	)
	(segment
		(start 193.077338 -207.37068)
		(end 192.445894 -207.37068)
		(width 0.18288)
		(layer "In6.Cu")
		(net "M_H_CPU1_SB_DQS_DP<7>")
	)
	(segment
		(start 188.93663 -208.220564)
		(end 188.33719 -208.220564)
		(width 0.18288)
		(layer "In6.Cu")
		(net "M_H_CPU1_SB_DQS_DP<7>")
	)
	(segment
		(start 203.15936 -207.942434)
		(end 202.759564 -207.942434)
		(width 0.18288)
		(layer "In6.Cu")
		(net "M_H_CPU1_SB_DQS_DP<7>")
	)
	(segment
		(start 177.078132 -209.64271)
		(end 176.711356 -209.64271)
		(width 0.18288)
		(layer "In6.Cu")
		(net "M_H_CPU1_SB_DQS_DP<7>")
	)
	(segment
		(start 128.839214 -229.762304)
		(end 128.83769 -229.763066)
		(width 0.088646)
		(layer "In6.Cu")
		(net "M_H_CPU1_SB_DQS_DP<7>")
	)
	(segment
		(start 129.693924 -229.591616)
		(end 129.6924 -229.592378)
		(width 0.088646)
		(layer "In6.Cu")
		(net "M_H_CPU1_SB_DQS_DP<7>")
	)
	(segment
		(start 128.83769 -229.763066)
		(end 128.830324 -229.767384)
		(width 0.088646)
		(layer "In6.Cu")
		(net "M_H_CPU1_SB_DQS_DP<7>")
	)
	(segment
		(start 136.35736 -228.783642)
		(end 136.357614 -228.783134)
		(width 0.088646)
		(layer "In6.Cu")
		(net "M_H_CPU1_SB_DQS_DP<7>")
	)
	(segment
		(start 174.694342 -209.899758)
		(end 173.823122 -210.770978)
		(width 0.18288)
		(layer "In6.Cu")
		(net "M_H_CPU1_SB_DQS_DP<7>")
	)
	(segment
		(start 195.973192 -207.576166)
		(end 195.381626 -207.576166)
		(width 0.18288)
		(layer "In6.Cu")
		(net "M_H_CPU1_SB_DQS_DP<7>")
	)
	(segment
		(start 207.071214 -208.366614)
		(end 206.792322 -208.645506)
		(width 0.18288)
		(layer "In6.Cu")
		(net "M_H_CPU1_SB_DQS_DP<7>")
	)
	(segment
		(start 197.260972 -208.863946)
		(end 195.973192 -207.576166)
		(width 0.18288)
		(layer "In6.Cu")
		(net "M_H_CPU1_SB_DQS_DP<7>")
	)
	(segment
		(start 172.615352 -210.492848)
		(end 172.344334 -210.763866)
		(width 0.18288)
		(layer "In6.Cu")
		(net "M_H_CPU1_SB_DQS_DP<7>")
	)
	(segment
		(start 138.983974 -226.713034)
		(end 138.8364 -226.860608)
		(width 0.088646)
		(layer "In6.Cu")
		(net "M_H_CPU1_SB_DQS_DP<7>")
	)
	(segment
		(start 138.8364 -226.860608)
		(end 138.717782 -227.146866)
		(width 0.088646)
		(layer "In6.Cu")
		(net "M_H_CPU1_SB_DQS_DP<7>")
	)
	(segment
		(start 188.05906 -207.942434)
		(end 187.691268 -207.942434)
		(width 0.18288)
		(layer "In6.Cu")
		(net "M_H_CPU1_SB_DQS_DP<7>")
	)
	(segment
		(start 138.717782 -227.146866)
		(end 137.680192 -228.184456)
		(width 0.088646)
		(layer "In6.Cu")
		(net "M_H_CPU1_SB_DQS_DP<7>")
	)
	(segment
		(start 204.239622 -208.220564)
		(end 203.43749 -208.220564)
		(width 0.18288)
		(layer "In6.Cu")
		(net "M_H_CPU1_SB_DQS_DP<7>")
	)
	(segment
		(start 172.975016 -210.492848)
		(end 172.615352 -210.492848)
		(width 0.18288)
		(layer "In6.Cu")
		(net "M_H_CPU1_SB_DQS_DP<7>")
	)
	(segment
		(start 171.53763 -210.763866)
		(end 169.64533 -208.871566)
		(width 0.18288)
		(layer "In6.Cu")
		(net "M_H_CPU1_SB_DQS_DP<7>")
	)
	(segment
		(start 177.670206 -209.921094)
		(end 177.356516 -209.921094)
		(width 0.18288)
		(layer "In6.Cu")
		(net "M_H_CPU1_SB_DQS_DP<7>")
	)
	(segment
		(start 173.823122 -210.770978)
		(end 173.253146 -210.770978)
		(width 0.18288)
		(layer "In6.Cu")
		(net "M_H_CPU1_SB_DQS_DP<7>")
	)
	(segment
		(start 169.64533 -208.871566)
		(end 157.516576 -208.871566)
		(width 0.18288)
		(layer "In6.Cu")
		(net "M_H_CPU1_SB_DQS_DP<7>")
	)
	(segment
		(start 194.507104 -207.93837)
		(end 193.645028 -207.93837)
		(width 0.18288)
		(layer "In6.Cu")
		(net "M_H_CPU1_SB_DQS_DP<7>")
	)
	(segment
		(start 205.841346 -209.019648)
		(end 205.038706 -209.019648)
		(width 0.18288)
		(layer "In6.Cu")
		(net "M_H_CPU1_SB_DQS_DP<7>")
	)
	(segment
		(start 178.660044 -208.931256)
		(end 177.670206 -209.921094)
		(width 0.18288)
		(layer "In6.Cu")
		(net "M_H_CPU1_SB_DQS_DP<7>")
	)
	(segment
		(start 155.092146 -211.50199)
		(end 139.940792 -226.653344)
		(width 0.18288)
		(layer "In6.Cu")
		(net "M_H_CPU1_SB_DQS_DP<7>")
	)
	(segment
		(start 173.253146 -210.770978)
		(end 172.975016 -210.492848)
		(width 0.18288)
		(layer "In6.Cu")
		(net "M_H_CPU1_SB_DQS_DP<7>")
	)
	(segment
		(start 128.599184 -230.086662)
		(end 128.086612 -230.086662)
		(width 0.088646)
		(layer "In6.Cu")
		(net "M_H_CPU1_SB_DQS_DP<7>")
	)
	(segment
		(start 134.478014 -228.783388)
		(end 134.4676 -228.777292)
		(width 0.088646)
		(layer "In6.Cu")
		(net "M_H_CPU1_SB_DQS_DP<7>")
	)
	(segment
		(start 177.356516 -209.921094)
		(end 177.078132 -209.64271)
		(width 0.18288)
		(layer "In6.Cu")
		(net "M_H_CPU1_SB_DQS_DP<7>")
	)
	(segment
		(start 197.839584 -208.863946)
		(end 197.260972 -208.863946)
		(width 0.18288)
		(layer "In6.Cu")
		(net "M_H_CPU1_SB_DQS_DP<7>")
	)
	(segment
		(start 202.759564 -207.942434)
		(end 202.480672 -208.221326)
		(width 0.18288)
		(layer "In6.Cu")
		(net "M_H_CPU1_SB_DQS_DP<7>")
	)
	(segment
		(start 137.680192 -228.184456)
		(end 137.680192 -228.55809)
		(width 0.088646)
		(layer "In6.Cu")
		(net "M_H_CPU1_SB_DQS_DP<7>")
	)
	(segment
		(start 202.480672 -208.221326)
		(end 199.391016 -208.221326)
		(width 0.18288)
		(layer "In6.Cu")
		(net "M_H_CPU1_SB_DQS_DP<7>")
	)
	(segment
		(start 130.718814 -228.783388)
		(end 130.704082 -228.774752)
		(width 0.088646)
		(layer "In6.Cu")
		(net "M_H_CPU1_SB_DQS_DP<7>")
	)
	(segment
		(start 129.538476 -229.663752)
		(end 129.183384 -229.663752)
		(width 0.088646)
		(layer "In6.Cu")
		(net "M_H_CPU1_SB_DQS_DP<7>")
	)
	(segment
		(start 131.658614 -228.783388)
		(end 131.643882 -228.774752)
		(width 0.088646)
		(layer "In6.Cu")
		(net "M_H_CPU1_SB_DQS_DP<7>")
	)
	(segment
		(start 195.381626 -207.576166)
		(end 194.507104 -207.93837)
		(width 0.18288)
		(layer "In6.Cu")
		(net "M_H_CPU1_SB_DQS_DP<7>")
	)
	(segment
		(start 205.038706 -209.019648)
		(end 204.239622 -208.220564)
		(width 0.18288)
		(layer "In6.Cu")
		(net "M_H_CPU1_SB_DQS_DP<7>")
	)
	(segment
		(start 199.391016 -208.221326)
		(end 197.839584 -208.863946)
		(width 0.18288)
		(layer "In6.Cu")
		(net "M_H_CPU1_SB_DQS_DP<7>")
	)
	(segment
		(start 155.092146 -211.295996)
		(end 155.092146 -211.50199)
		(width 0.18288)
		(layer "In6.Cu")
		(net "M_H_CPU1_SB_DQS_DP<7>")
	)
	(segment
		(start 129.6924 -229.592378)
		(end 129.667762 -229.606348)
		(width 0.088646)
		(layer "In6.Cu")
		(net "M_H_CPU1_SB_DQS_DP<7>")
	)
	(segment
		(start 192.167764 -207.09255)
		(end 191.809624 -207.09255)
		(width 0.18288)
		(layer "In6.Cu")
		(net "M_H_CPU1_SB_DQS_DP<7>")
	)
	(segment
		(start 191.529716 -207.372458)
		(end 189.784736 -207.372458)
		(width 0.18288)
		(layer "In6.Cu")
		(net "M_H_CPU1_SB_DQS_DP<7>")
	)
	(segment
		(start 186.842146 -208.21269)
		(end 185.107326 -208.931256)
		(width 0.18288)
		(layer "In6.Cu")
		(net "M_H_CPU1_SB_DQS_DP<7>")
	)
	(segment
		(start 132.598668 -228.783388)
		(end 132.588254 -228.777292)
		(width 0.088646)
		(layer "In6.Cu")
		(net "M_H_CPU1_SB_DQS_DP<7>")
	)
	(segment
		(start 192.445894 -207.37068)
		(end 192.167764 -207.09255)
		(width 0.18288)
		(layer "In6.Cu")
		(net "M_H_CPU1_SB_DQS_DP<7>")
	)
	(segment
		(start 139.250674 -226.653344)
		(end 139.190984 -226.713034)
		(width 0.088646)
		(layer "In6.Cu")
		(net "M_H_CPU1_SB_DQS_DP<7>")
	)
	(segment
		(start 187.691268 -207.942434)
		(end 187.421012 -208.21269)
		(width 0.18288)
		(layer "In6.Cu")
		(net "M_H_CPU1_SB_DQS_DP<7>")
	)
	(segment
		(start 139.190984 -226.713034)
		(end 138.983974 -226.713034)
		(width 0.088646)
		(layer "In6.Cu")
		(net "M_H_CPU1_SB_DQS_DP<7>")
	)
	(segment
		(start 203.43749 -208.220564)
		(end 203.15936 -207.942434)
		(width 0.18288)
		(layer "In6.Cu")
		(net "M_H_CPU1_SB_DQS_DP<7>")
	)
	(segment
		(start 137.680192 -228.55809)
		(end 137.478262 -228.76002)
		(width 0.088646)
		(layer "In6.Cu")
		(net "M_H_CPU1_SB_DQS_DP<7>")
	)
	(segment
		(start 139.274042 -226.653344)
		(end 139.250674 -226.653344)
		(width 0.088646)
		(layer "In6.Cu")
		(net "M_H_CPU1_SB_DQS_DP<7>")
	)
	(segment
		(start 191.809624 -207.09255)
		(end 191.529716 -207.372458)
		(width 0.18288)
		(layer "In6.Cu")
		(net "M_H_CPU1_SB_DQS_DP<7>")
	)
	(segment
		(start 187.421012 -208.21269)
		(end 186.842146 -208.21269)
		(width 0.18288)
		(layer "In6.Cu")
		(net "M_H_CPU1_SB_DQS_DP<7>")
	)
	(segment
		(start 189.784736 -207.372458)
		(end 188.93663 -208.220564)
		(width 0.18288)
		(layer "In6.Cu")
		(net "M_H_CPU1_SB_DQS_DP<7>")
	)
	(segment
		(start 206.215488 -208.645506)
		(end 205.841346 -209.019648)
		(width 0.18288)
		(layer "In6.Cu")
		(net "M_H_CPU1_SB_DQS_DP<7>")
	)
	(segment
		(start 139.940792 -226.653344)
		(end 139.274042 -226.653344)
		(width 0.18288)
		(layer "In6.Cu")
		(net "M_H_CPU1_SB_DQS_DP<7>")
	)
	(segment
		(start 137.297668 -228.783896)
		(end 137.297414 -228.783642)
		(width 0.088646)
		(layer "In6.Cu")
		(net "M_H_CPU1_SB_DQS_DP<7>")
	)
	(segment
		(start 129.183384 -229.663752)
		(end 129.02946 -229.694486)
		(width 0.088646)
		(layer "In6.Cu")
		(net "M_H_CPU1_SB_DQS_DP<7>")
	)
	(segment
		(start 193.645028 -207.93837)
		(end 193.077338 -207.37068)
		(width 0.18288)
		(layer "In6.Cu")
		(net "M_H_CPU1_SB_DQS_DP<7>")
	)
	(segment
		(start 130.140202 -228.791008)
		(end 130.140456 -228.791516)
		(width 0.088646)
		(layer "In6.Cu")
		(net "M_H_CPU1_SB_DQS_DP<7>")
	)
	(segment
		(start 176.454308 -209.899758)
		(end 174.694342 -209.899758)
		(width 0.18288)
		(layer "In6.Cu")
		(net "M_H_CPU1_SB_DQS_DP<7>")
	)
	(segment
		(start 129.02946 -229.694486)
		(end 128.979676 -229.71506)
		(width 0.088646)
		(layer "In6.Cu")
		(net "M_H_CPU1_SB_DQS_DP<7>")
	)
	(segment
		(start 129.667762 -229.606348)
		(end 129.538476 -229.663752)
		(width 0.088646)
		(layer "In6.Cu")
		(net "M_H_CPU1_SB_DQS_DP<7>")
	)
	(segment
		(start 135.418068 -228.783388)
		(end 135.407654 -228.777292)
		(width 0.088646)
		(layer "In6.Cu")
		(net "M_H_CPU1_SB_DQS_DP<7>")
	)
	(segment
		(start 172.344334 -210.763866)
		(end 171.53763 -210.763866)
		(width 0.18288)
		(layer "In6.Cu")
		(net "M_H_CPU1_SB_DQS_DP<7>")
	)
	(arc
		(start 137.478262 -228.76002)
		(mid 137.392008 -228.802596)
		(end 137.297668 -228.783896)
		(width 0.088646)
		(layer "In6.Cu")
		(net "M_H_CPU1_SB_DQS_DP<7>")
	)
	(arc
		(start 137.297414 -228.783642)
		(mid 137.014966 -228.707959)
		(end 136.732518 -228.783642)
		(width 0.088646)
		(layer "In6.Cu")
		(net "M_H_CPU1_SB_DQS_DP<7>")
	)
	(arc
		(start 130.704082 -228.774752)
		(mid 130.427607 -228.707432)
		(end 130.15341 -228.783388)
		(width 0.088646)
		(layer "In6.Cu")
		(net "M_H_CPU1_SB_DQS_DP<7>")
	)
	(arc
		(start 135.792464 -228.783388)
		(mid 135.605266 -228.833531)
		(end 135.418068 -228.783388)
		(width 0.088646)
		(layer "In6.Cu")
		(net "M_H_CPU1_SB_DQS_DP<7>")
	)
	(arc
		(start 131.643882 -228.774752)
		(mid 131.367407 -228.707432)
		(end 131.09321 -228.783388)
		(width 0.088646)
		(layer "In6.Cu")
		(net "M_H_CPU1_SB_DQS_DP<7>")
	)
	(arc
		(start 130.147314 -228.786944)
		(mid 130.14375 -228.788962)
		(end 130.140202 -228.791008)
		(width 0.088646)
		(layer "In6.Cu")
		(net "M_H_CPU1_SB_DQS_DP<7>")
	)
	(arc
		(start 132.973064 -228.783388)
		(mid 132.785866 -228.833531)
		(end 132.598668 -228.783388)
		(width 0.088646)
		(layer "In6.Cu")
		(net "M_H_CPU1_SB_DQS_DP<7>")
	)
	(arc
		(start 132.588254 -228.777292)
		(mid 132.309822 -228.707446)
		(end 132.03301 -228.783388)
		(width 0.088646)
		(layer "In6.Cu")
		(net "M_H_CPU1_SB_DQS_DP<7>")
	)
	(arc
		(start 134.4676 -228.777292)
		(mid 134.189422 -228.707569)
		(end 133.912864 -228.783388)
		(width 0.088646)
		(layer "In6.Cu")
		(net "M_H_CPU1_SB_DQS_DP<7>")
	)
	(arc
		(start 133.912864 -228.783388)
		(mid 133.725666 -228.833531)
		(end 133.538468 -228.783388)
		(width 0.088646)
		(layer "In6.Cu")
		(net "M_H_CPU1_SB_DQS_DP<7>")
	)
	(arc
		(start 130.140456 -228.791516)
		(mid 129.94328 -228.997151)
		(end 129.87147 -229.272846)
		(width 0.088646)
		(layer "In6.Cu")
		(net "M_H_CPU1_SB_DQS_DP<7>")
	)
	(arc
		(start 128.830324 -229.767384)
		(mid 128.714515 -229.879313)
		(end 128.656334 -230.029512)
		(width 0.088646)
		(layer "In6.Cu")
		(net "M_H_CPU1_SB_DQS_DP<7>")
	)
	(arc
		(start 133.538468 -228.783388)
		(mid 133.255766 -228.707612)
		(end 132.973064 -228.783388)
		(width 0.088646)
		(layer "In6.Cu")
		(net "M_H_CPU1_SB_DQS_DP<7>")
	)
	(arc
		(start 134.85241 -228.783388)
		(mid 134.665212 -228.833531)
		(end 134.478014 -228.783388)
		(width 0.088646)
		(layer "In6.Cu")
		(net "M_H_CPU1_SB_DQS_DP<7>")
	)
	(arc
		(start 131.09321 -228.783388)
		(mid 130.906012 -228.833531)
		(end 130.718814 -228.783388)
		(width 0.088646)
		(layer "In6.Cu")
		(net "M_H_CPU1_SB_DQS_DP<7>")
	)
	(arc
		(start 136.357614 -228.783134)
		(mid 136.074993 -228.707519)
		(end 135.792464 -228.783388)
		(width 0.088646)
		(layer "In6.Cu")
		(net "M_H_CPU1_SB_DQS_DP<7>")
	)
	(arc
		(start 135.407654 -228.777292)
		(mid 135.129222 -228.707446)
		(end 134.85241 -228.783388)
		(width 0.088646)
		(layer "In6.Cu")
		(net "M_H_CPU1_SB_DQS_DP<7>")
	)
	(arc
		(start 132.03301 -228.783388)
		(mid 131.845812 -228.833531)
		(end 131.658614 -228.783388)
		(width 0.088646)
		(layer "In6.Cu")
		(net "M_H_CPU1_SB_DQS_DP<7>")
	)
	(arc
		(start 136.732518 -228.783642)
		(mid 136.544956 -228.833878)
		(end 136.35736 -228.783642)
		(width 0.088646)
		(layer "In6.Cu")
		(net "M_H_CPU1_SB_DQS_DP<7>")
	)
	(arc
		(start 128.979676 -229.71506)
		(mid 128.907079 -229.731652)
		(end 128.839214 -229.762304)
		(width 0.088646)
		(layer "In6.Cu")
		(net "M_H_CPU1_SB_DQS_DP<7>")
	)
	(arc
		(start 129.87147 -229.272846)
		(mid 129.824087 -229.455282)
		(end 129.693924 -229.591616)
		(width 0.088646)
		(layer "In6.Cu")
		(net "M_H_CPU1_SB_DQS_DP<7>")
	)
	(segment
		(start 124.797312 -232.528618)
		(end 124.797566 -232.528364)
		(width 0.20066)
		(layer "F.Cu")
		(net "M_H_CPU1_SB_DQS_DP<6>")
	)
	(segment
		(start 209.750406 -217.542872)
		(end 210.02879 -217.542872)
		(width 0.20066)
		(layer "F.Cu")
		(net "M_H_CPU1_SB_DQS_DP<6>")
	)
	(segment
		(start 215.15197 -217.716608)
		(end 215.719914 -217.716608)
		(width 0.20066)
		(layer "F.Cu")
		(net "M_H_CPU1_SB_DQS_DP<6>")
	)
	(segment
		(start 212.952076 -217.2843)
		(end 213.207092 -217.539316)
		(width 0.20066)
		(layer "F.Cu")
		(net "M_H_CPU1_SB_DQS_DP<6>")
	)
	(segment
		(start 210.287108 -217.284554)
		(end 210.598258 -217.284554)
		(width 0.20066)
		(layer "F.Cu")
		(net "M_H_CPU1_SB_DQS_DP<6>")
	)
	(segment
		(start 207.071214 -217.716608)
		(end 208.176114 -217.716608)
		(width 0.20066)
		(layer "F.Cu")
		(net "M_H_CPU1_SB_DQS_DP<6>")
	)
	(segment
		(start 213.207092 -217.539316)
		(end 213.860634 -217.539316)
		(width 0.20066)
		(layer "F.Cu")
		(net "M_H_CPU1_SB_DQS_DP<6>")
	)
	(segment
		(start 208.769458 -217.716608)
		(end 209.020664 -217.967814)
		(width 0.20066)
		(layer "F.Cu")
		(net "M_H_CPU1_SB_DQS_DP<6>")
	)
	(segment
		(start 214.883746 -217.984832)
		(end 215.15197 -217.716608)
		(width 0.20066)
		(layer "F.Cu")
		(net "M_H_CPU1_SB_DQS_DP<6>")
	)
	(segment
		(start 209.325464 -217.967814)
		(end 209.750406 -217.542872)
		(width 0.20066)
		(layer "F.Cu")
		(net "M_H_CPU1_SB_DQS_DP<6>")
	)
	(segment
		(start 212.622892 -217.291666)
		(end 212.630258 -217.2843)
		(width 0.1016)
		(layer "F.Cu")
		(net "M_H_CPU1_SB_DQS_DP<6>")
	)
	(segment
		(start 214.30615 -217.984832)
		(end 214.883746 -217.984832)
		(width 0.20066)
		(layer "F.Cu")
		(net "M_H_CPU1_SB_DQS_DP<6>")
	)
	(segment
		(start 208.176114 -217.716608)
		(end 208.769458 -217.716608)
		(width 0.20066)
		(layer "F.Cu")
		(net "M_H_CPU1_SB_DQS_DP<6>")
	)
	(segment
		(start 210.598258 -217.284554)
		(end 210.603084 -217.284554)
		(width 0.101854)
		(layer "F.Cu")
		(net "M_H_CPU1_SB_DQS_DP<6>")
	)
	(segment
		(start 124.797312 -233.064304)
		(end 124.797312 -232.528618)
		(width 0.20066)
		(layer "F.Cu")
		(net "M_H_CPU1_SB_DQS_DP<6>")
	)
	(segment
		(start 210.02879 -217.542872)
		(end 210.287108 -217.284554)
		(width 0.20066)
		(layer "F.Cu")
		(net "M_H_CPU1_SB_DQS_DP<6>")
	)
	(segment
		(start 210.610196 -217.291666)
		(end 212.622892 -217.291666)
		(width 0.1016)
		(layer "F.Cu")
		(net "M_H_CPU1_SB_DQS_DP<6>")
	)
	(segment
		(start 212.630258 -217.2843)
		(end 212.952076 -217.2843)
		(width 0.20066)
		(layer "F.Cu")
		(net "M_H_CPU1_SB_DQS_DP<6>")
	)
	(segment
		(start 209.020664 -217.967814)
		(end 209.325464 -217.967814)
		(width 0.20066)
		(layer "F.Cu")
		(net "M_H_CPU1_SB_DQS_DP<6>")
	)
	(segment
		(start 213.860634 -217.539316)
		(end 214.30615 -217.984832)
		(width 0.20066)
		(layer "F.Cu")
		(net "M_H_CPU1_SB_DQS_DP<6>")
	)
	(segment
		(start 210.603084 -217.284554)
		(end 210.610196 -217.291666)
		(width 0.1016)
		(layer "F.Cu")
		(net "M_H_CPU1_SB_DQS_DP<6>")
	)
	(segment
		(start 184.209944 -210.767422)
		(end 183.344312 -209.90179)
		(width 0.18288)
		(layer "In11.Cu")
		(net "M_H_CPU1_SB_DQS_DP<6>")
	)
	(segment
		(start 139.487148 -230.769414)
		(end 138.799316 -231.4575)
		(width 0.088646)
		(layer "In11.Cu")
		(net "M_H_CPU1_SB_DQS_DP<6>")
	)
	(segment
		(start 130.73126 -232.046526)
		(end 130.719322 -232.039414)
		(width 0.088646)
		(layer "In11.Cu")
		(net "M_H_CPU1_SB_DQS_DP<6>")
	)
	(segment
		(start 178.919632 -210.652106)
		(end 177.955194 -211.616544)
		(width 0.18288)
		(layer "In11.Cu")
		(net "M_H_CPU1_SB_DQS_DP<6>")
	)
	(segment
		(start 139.7762 -230.269034)
		(end 139.487148 -230.558086)
		(width 0.088646)
		(layer "In11.Cu")
		(net "M_H_CPU1_SB_DQS_DP<6>")
	)
	(segment
		(start 179.979828 -209.90179)
		(end 179.229512 -210.652106)
		(width 0.18288)
		(layer "In11.Cu")
		(net "M_H_CPU1_SB_DQS_DP<6>")
	)
	(segment
		(start 189.266576 -210.766406)
		(end 188.37021 -210.766406)
		(width 0.18288)
		(layer "In11.Cu")
		(net "M_H_CPU1_SB_DQS_DP<6>")
	)
	(segment
		(start 127.899414 -232.038906)
		(end 127.884682 -232.03027)
		(width 0.088646)
		(layer "In11.Cu")
		(net "M_H_CPU1_SB_DQS_DP<6>")
	)
	(segment
		(start 187.615322 -210.49107)
		(end 187.33897 -210.767422)
		(width 0.18288)
		(layer "In11.Cu")
		(net "M_H_CPU1_SB_DQS_DP<6>")
	)
	(segment
		(start 199.09663 -215.477852)
		(end 198.889112 -215.270334)
		(width 0.18288)
		(layer "In11.Cu")
		(net "M_H_CPU1_SB_DQS_DP<6>")
	)
	(segment
		(start 157.314138 -211.864448)
		(end 153.93162 -215.246966)
		(width 0.18288)
		(layer "In11.Cu")
		(net "M_H_CPU1_SB_DQS_DP<6>")
	)
	(segment
		(start 153.93162 -215.246966)
		(end 153.93162 -217.276172)
		(width 0.18288)
		(layer "In11.Cu")
		(net "M_H_CPU1_SB_DQS_DP<6>")
	)
	(segment
		(start 139.487148 -230.558086)
		(end 139.487148 -230.769414)
		(width 0.088646)
		(layer "In11.Cu")
		(net "M_H_CPU1_SB_DQS_DP<6>")
	)
	(segment
		(start 141.916912 -230.209344)
		(end 140.163296 -230.209344)
		(width 0.18288)
		(layer "In11.Cu")
		(net "M_H_CPU1_SB_DQS_DP<6>")
	)
	(segment
		(start 172.527722 -212.191092)
		(end 172.245782 -212.473032)
		(width 0.18288)
		(layer "In11.Cu")
		(net "M_H_CPU1_SB_DQS_DP<6>")
	)
	(segment
		(start 174.789592 -211.631276)
		(end 173.95444 -212.466428)
		(width 0.18288)
		(layer "In11.Cu")
		(net "M_H_CPU1_SB_DQS_DP<6>")
	)
	(segment
		(start 195.102226 -211.236306)
		(end 194.582034 -211.021422)
		(width 0.18288)
		(layer "In11.Cu")
		(net "M_H_CPU1_SB_DQS_DP<6>")
	)
	(segment
		(start 197.664578 -213.274402)
		(end 196.767958 -212.902038)
		(width 0.18288)
		(layer "In11.Cu")
		(net "M_H_CPU1_SB_DQS_DP<6>")
	)
	(segment
		(start 132.607304 -232.04424)
		(end 132.598922 -232.039414)
		(width 0.088646)
		(layer "In11.Cu")
		(net "M_H_CPU1_SB_DQS_DP<6>")
	)
	(segment
		(start 146.568922 -225.557334)
		(end 141.916912 -230.209344)
		(width 0.18288)
		(layer "In11.Cu")
		(net "M_H_CPU1_SB_DQS_DP<6>")
	)
	(segment
		(start 129.79146 -232.046526)
		(end 129.779522 -232.039414)
		(width 0.088646)
		(layer "In11.Cu")
		(net "M_H_CPU1_SB_DQS_DP<6>")
	)
	(segment
		(start 176.62779 -211.341208)
		(end 176.337722 -211.631276)
		(width 0.18288)
		(layer "In11.Cu")
		(net "M_H_CPU1_SB_DQS_DP<6>")
	)
	(segment
		(start 126.959614 -232.038906)
		(end 126.95936 -232.038906)
		(width 0.088646)
		(layer "In11.Cu")
		(net "M_H_CPU1_SB_DQS_DP<6>")
	)
	(segment
		(start 198.34479 -213.954614)
		(end 197.664578 -213.274402)
		(width 0.18288)
		(layer "In11.Cu")
		(net "M_H_CPU1_SB_DQS_DP<6>")
	)
	(segment
		(start 133.91261 -232.039414)
		(end 133.904228 -232.044494)
		(width 0.088646)
		(layer "In11.Cu")
		(net "M_H_CPU1_SB_DQS_DP<6>")
	)
	(segment
		(start 125.370082 -232.454196)
		(end 125.295914 -232.528364)
		(width 0.088646)
		(layer "In11.Cu")
		(net "M_H_CPU1_SB_DQS_DP<6>")
	)
	(segment
		(start 193.028316 -211.535264)
		(end 192.832482 -211.616544)
		(width 0.18288)
		(layer "In11.Cu")
		(net "M_H_CPU1_SB_DQS_DP<6>")
	)
	(segment
		(start 201.330052 -217.198956)
		(end 199.971406 -215.84031)
		(width 0.18288)
		(layer "In11.Cu")
		(net "M_H_CPU1_SB_DQS_DP<6>")
	)
	(segment
		(start 134.852664 -232.038906)
		(end 134.85241 -232.038906)
		(width 0.088646)
		(layer "In11.Cu")
		(net "M_H_CPU1_SB_DQS_DP<6>")
	)
	(segment
		(start 205.47711 -218.239086)
		(end 205.054708 -218.239086)
		(width 0.18288)
		(layer "In11.Cu")
		(net "M_H_CPU1_SB_DQS_DP<6>")
	)
	(segment
		(start 206.816706 -217.9701)
		(end 206.127604 -217.9701)
		(width 0.18288)
		(layer "In11.Cu")
		(net "M_H_CPU1_SB_DQS_DP<6>")
	)
	(segment
		(start 125.676914 -232.136188)
		(end 125.550168 -232.204006)
		(width 0.088646)
		(layer "In11.Cu")
		(net "M_H_CPU1_SB_DQS_DP<6>")
	)
	(segment
		(start 177.10531 -211.341208)
		(end 176.62779 -211.341208)
		(width 0.18288)
		(layer "In11.Cu")
		(net "M_H_CPU1_SB_DQS_DP<6>")
	)
	(segment
		(start 160.11652 -211.864448)
		(end 157.314138 -211.864448)
		(width 0.18288)
		(layer "In11.Cu")
		(net "M_H_CPU1_SB_DQS_DP<6>")
	)
	(segment
		(start 188.37021 -210.766406)
		(end 188.094874 -210.49107)
		(width 0.18288)
		(layer "In11.Cu")
		(net "M_H_CPU1_SB_DQS_DP<6>")
	)
	(segment
		(start 167.972994 -211.866988)
		(end 164.826696 -211.866988)
		(width 0.18288)
		(layer "In11.Cu")
		(net "M_H_CPU1_SB_DQS_DP<6>")
	)
	(segment
		(start 160.929574 -212.201252)
		(end 160.11652 -211.864448)
		(width 0.18288)
		(layer "In11.Cu")
		(net "M_H_CPU1_SB_DQS_DP<6>")
	)
	(segment
		(start 191.71539 -211.341208)
		(end 191.434466 -211.622132)
		(width 0.18288)
		(layer "In11.Cu")
		(net "M_H_CPU1_SB_DQS_DP<6>")
	)
	(segment
		(start 206.127604 -217.9701)
		(end 205.47711 -218.239086)
		(width 0.18288)
		(layer "In11.Cu")
		(net "M_H_CPU1_SB_DQS_DP<6>")
	)
	(segment
		(start 188.094874 -210.49107)
		(end 187.615322 -210.49107)
		(width 0.18288)
		(layer "In11.Cu")
		(net "M_H_CPU1_SB_DQS_DP<6>")
	)
	(segment
		(start 202.196954 -217.558112)
		(end 201.330052 -217.198956)
		(width 0.18288)
		(layer "In11.Cu")
		(net "M_H_CPU1_SB_DQS_DP<6>")
	)
	(segment
		(start 125.295914 -232.528364)
		(end 124.797566 -232.528364)
		(width 0.088646)
		(layer "In11.Cu")
		(net "M_H_CPU1_SB_DQS_DP<6>")
	)
	(segment
		(start 177.955194 -211.616544)
		(end 177.380646 -211.616544)
		(width 0.18288)
		(layer "In11.Cu")
		(net "M_H_CPU1_SB_DQS_DP<6>")
	)
	(segment
		(start 179.229512 -210.652106)
		(end 178.919632 -210.652106)
		(width 0.18288)
		(layer "In11.Cu")
		(net "M_H_CPU1_SB_DQS_DP<6>")
	)
	(segment
		(start 126.287276 -232.098088)
		(end 126.28499 -232.099104)
		(width 0.088646)
		(layer "In11.Cu")
		(net "M_H_CPU1_SB_DQS_DP<6>")
	)
	(segment
		(start 126.308612 -232.089452)
		(end 126.287276 -232.098088)
		(width 0.088646)
		(layer "In11.Cu")
		(net "M_H_CPU1_SB_DQS_DP<6>")
	)
	(segment
		(start 173.012354 -212.191092)
		(end 172.527722 -212.191092)
		(width 0.18288)
		(layer "In11.Cu")
		(net "M_H_CPU1_SB_DQS_DP<6>")
	)
	(segment
		(start 173.28769 -212.466428)
		(end 173.012354 -212.191092)
		(width 0.18288)
		(layer "In11.Cu")
		(net "M_H_CPU1_SB_DQS_DP<6>")
	)
	(segment
		(start 153.93162 -217.276172)
		(end 146.568922 -224.63887)
		(width 0.18288)
		(layer "In11.Cu")
		(net "M_H_CPU1_SB_DQS_DP<6>")
	)
	(segment
		(start 127.91186 -232.046526)
		(end 127.899414 -232.038906)
		(width 0.088646)
		(layer "In11.Cu")
		(net "M_H_CPU1_SB_DQS_DP<6>")
	)
	(segment
		(start 140.163296 -230.209344)
		(end 140.103606 -230.269034)
		(width 0.088646)
		(layer "In11.Cu")
		(net "M_H_CPU1_SB_DQS_DP<6>")
	)
	(segment
		(start 177.380646 -211.616544)
		(end 177.10531 -211.341208)
		(width 0.18288)
		(layer "In11.Cu")
		(net "M_H_CPU1_SB_DQS_DP<6>")
	)
	(segment
		(start 191.434466 -211.622132)
		(end 190.122302 -211.622132)
		(width 0.18288)
		(layer "In11.Cu")
		(net "M_H_CPU1_SB_DQS_DP<6>")
	)
	(segment
		(start 192.194942 -211.341208)
		(end 191.71539 -211.341208)
		(width 0.18288)
		(layer "In11.Cu")
		(net "M_H_CPU1_SB_DQS_DP<6>")
	)
	(segment
		(start 183.344312 -209.90179)
		(end 179.979828 -209.90179)
		(width 0.18288)
		(layer "In11.Cu")
		(net "M_H_CPU1_SB_DQS_DP<6>")
	)
	(segment
		(start 125.550168 -232.204006)
		(end 125.541278 -232.209086)
		(width 0.088646)
		(layer "In11.Cu")
		(net "M_H_CPU1_SB_DQS_DP<6>")
	)
	(segment
		(start 192.832482 -211.616544)
		(end 192.470278 -211.616544)
		(width 0.18288)
		(layer "In11.Cu")
		(net "M_H_CPU1_SB_DQS_DP<6>")
	)
	(segment
		(start 203.975716 -217.556842)
		(end 203.47051 -217.556842)
		(width 0.18288)
		(layer "In11.Cu")
		(net "M_H_CPU1_SB_DQS_DP<6>")
	)
	(segment
		(start 199.971406 -215.84031)
		(end 199.09663 -215.477852)
		(width 0.18288)
		(layer "In11.Cu")
		(net "M_H_CPU1_SB_DQS_DP<6>")
	)
	(segment
		(start 126.28499 -232.099104)
		(end 125.798834 -232.108502)
		(width 0.088646)
		(layer "In11.Cu")
		(net "M_H_CPU1_SB_DQS_DP<6>")
	)
	(segment
		(start 140.103606 -230.269034)
		(end 139.7762 -230.269034)
		(width 0.088646)
		(layer "In11.Cu")
		(net "M_H_CPU1_SB_DQS_DP<6>")
	)
	(segment
		(start 194.582034 -211.021422)
		(end 193.542158 -211.021422)
		(width 0.18288)
		(layer "In11.Cu")
		(net "M_H_CPU1_SB_DQS_DP<6>")
	)
	(segment
		(start 192.470278 -211.616544)
		(end 192.194942 -211.341208)
		(width 0.18288)
		(layer "In11.Cu")
		(net "M_H_CPU1_SB_DQS_DP<6>")
	)
	(segment
		(start 202.702922 -217.291158)
		(end 202.435968 -217.558112)
		(width 0.18288)
		(layer "In11.Cu")
		(net "M_H_CPU1_SB_DQS_DP<6>")
	)
	(segment
		(start 138.799316 -231.4575)
		(end 138.799316 -231.714548)
		(width 0.088646)
		(layer "In11.Cu")
		(net "M_H_CPU1_SB_DQS_DP<6>")
	)
	(segment
		(start 207.071214 -217.716608)
		(end 206.816706 -217.9701)
		(width 0.18288)
		(layer "In11.Cu")
		(net "M_H_CPU1_SB_DQS_DP<6>")
	)
	(segment
		(start 202.435968 -217.558112)
		(end 202.196954 -217.558112)
		(width 0.18288)
		(layer "In11.Cu")
		(net "M_H_CPU1_SB_DQS_DP<6>")
	)
	(segment
		(start 131.67106 -232.046526)
		(end 131.659122 -232.039414)
		(width 0.088646)
		(layer "In11.Cu")
		(net "M_H_CPU1_SB_DQS_DP<6>")
	)
	(segment
		(start 168.579038 -212.473032)
		(end 167.972994 -211.866988)
		(width 0.18288)
		(layer "In11.Cu")
		(net "M_H_CPU1_SB_DQS_DP<6>")
	)
	(segment
		(start 203.204826 -217.291158)
		(end 202.702922 -217.291158)
		(width 0.18288)
		(layer "In11.Cu")
		(net "M_H_CPU1_SB_DQS_DP<6>")
	)
	(segment
		(start 198.889112 -215.270334)
		(end 198.34479 -213.954614)
		(width 0.18288)
		(layer "In11.Cu")
		(net "M_H_CPU1_SB_DQS_DP<6>")
	)
	(segment
		(start 203.47051 -217.556842)
		(end 203.204826 -217.291158)
		(width 0.18288)
		(layer "In11.Cu")
		(net "M_H_CPU1_SB_DQS_DP<6>")
	)
	(segment
		(start 164.492432 -212.201252)
		(end 160.929574 -212.201252)
		(width 0.18288)
		(layer "In11.Cu")
		(net "M_H_CPU1_SB_DQS_DP<6>")
	)
	(segment
		(start 164.826696 -211.866988)
		(end 164.492432 -212.201252)
		(width 0.18288)
		(layer "In11.Cu")
		(net "M_H_CPU1_SB_DQS_DP<6>")
	)
	(segment
		(start 205.054708 -218.239086)
		(end 204.261212 -217.842338)
		(width 0.18288)
		(layer "In11.Cu")
		(net "M_H_CPU1_SB_DQS_DP<6>")
	)
	(segment
		(start 126.393448 -232.039414)
		(end 126.308612 -232.089452)
		(width 0.088646)
		(layer "In11.Cu")
		(net "M_H_CPU1_SB_DQS_DP<6>")
	)
	(segment
		(start 125.774196 -232.111804)
		(end 125.676914 -232.136188)
		(width 0.088646)
		(layer "In11.Cu")
		(net "M_H_CPU1_SB_DQS_DP<6>")
	)
	(segment
		(start 196.767958 -212.902038)
		(end 195.102226 -211.236306)
		(width 0.18288)
		(layer "In11.Cu")
		(net "M_H_CPU1_SB_DQS_DP<6>")
	)
	(segment
		(start 204.261212 -217.842338)
		(end 203.975716 -217.556842)
		(width 0.18288)
		(layer "In11.Cu")
		(net "M_H_CPU1_SB_DQS_DP<6>")
	)
	(segment
		(start 146.568922 -224.63887)
		(end 146.568922 -225.557334)
		(width 0.18288)
		(layer "In11.Cu")
		(net "M_H_CPU1_SB_DQS_DP<6>")
	)
	(segment
		(start 176.337722 -211.631276)
		(end 174.789592 -211.631276)
		(width 0.18288)
		(layer "In11.Cu")
		(net "M_H_CPU1_SB_DQS_DP<6>")
	)
	(segment
		(start 193.542158 -211.021422)
		(end 193.028316 -211.535264)
		(width 0.18288)
		(layer "In11.Cu")
		(net "M_H_CPU1_SB_DQS_DP<6>")
	)
	(segment
		(start 172.245782 -212.473032)
		(end 168.579038 -212.473032)
		(width 0.18288)
		(layer "In11.Cu")
		(net "M_H_CPU1_SB_DQS_DP<6>")
	)
	(segment
		(start 190.122302 -211.622132)
		(end 189.266576 -210.766406)
		(width 0.18288)
		(layer "In11.Cu")
		(net "M_H_CPU1_SB_DQS_DP<6>")
	)
	(segment
		(start 173.95444 -212.466428)
		(end 173.28769 -212.466428)
		(width 0.18288)
		(layer "In11.Cu")
		(net "M_H_CPU1_SB_DQS_DP<6>")
	)
	(segment
		(start 187.33897 -210.767422)
		(end 184.209944 -210.767422)
		(width 0.18288)
		(layer "In11.Cu")
		(net "M_H_CPU1_SB_DQS_DP<6>")
	)
	(arc
		(start 130.719322 -232.039414)
		(mid 130.436649 -231.963443)
		(end 130.153918 -232.03916)
		(width 0.088646)
		(layer "In11.Cu")
		(net "M_H_CPU1_SB_DQS_DP<6>")
	)
	(arc
		(start 125.798834 -232.108502)
		(mid 125.786419 -232.10944)
		(end 125.774196 -232.111804)
		(width 0.088646)
		(layer "In11.Cu")
		(net "M_H_CPU1_SB_DQS_DP<6>")
	)
	(arc
		(start 134.85241 -232.038906)
		(mid 134.665131 -232.089176)
		(end 134.47776 -232.03916)
		(width 0.088646)
		(layer "In11.Cu")
		(net "M_H_CPU1_SB_DQS_DP<6>")
	)
	(arc
		(start 135.418068 -232.038906)
		(mid 135.135366 -231.96313)
		(end 134.852664 -232.038906)
		(width 0.088646)
		(layer "In11.Cu")
		(net "M_H_CPU1_SB_DQS_DP<6>")
	)
	(arc
		(start 136.732264 -232.038906)
		(mid 136.545066 -232.089049)
		(end 136.357868 -232.038906)
		(width 0.088646)
		(layer "In11.Cu")
		(net "M_H_CPU1_SB_DQS_DP<6>")
	)
	(arc
		(start 137.672064 -232.038906)
		(mid 137.484866 -232.089049)
		(end 137.297668 -232.038906)
		(width 0.088646)
		(layer "In11.Cu")
		(net "M_H_CPU1_SB_DQS_DP<6>")
	)
	(arc
		(start 132.033518 -232.03916)
		(mid 131.853231 -232.089572)
		(end 131.67106 -232.046526)
		(width 0.088646)
		(layer "In11.Cu")
		(net "M_H_CPU1_SB_DQS_DP<6>")
	)
	(arc
		(start 136.357868 -232.038906)
		(mid 136.075166 -231.96313)
		(end 135.792464 -232.038906)
		(width 0.088646)
		(layer "In11.Cu")
		(net "M_H_CPU1_SB_DQS_DP<6>")
	)
	(arc
		(start 134.47776 -232.03916)
		(mid 134.195138 -231.963477)
		(end 133.91261 -232.039414)
		(width 0.088646)
		(layer "In11.Cu")
		(net "M_H_CPU1_SB_DQS_DP<6>")
	)
	(arc
		(start 131.659122 -232.039414)
		(mid 131.376449 -231.963443)
		(end 131.093718 -232.03916)
		(width 0.088646)
		(layer "In11.Cu")
		(net "M_H_CPU1_SB_DQS_DP<6>")
	)
	(arc
		(start 128.839214 -232.03916)
		(mid 128.556766 -231.963477)
		(end 128.274318 -232.03916)
		(width 0.088646)
		(layer "In11.Cu")
		(net "M_H_CPU1_SB_DQS_DP<6>")
	)
	(arc
		(start 129.214118 -232.03916)
		(mid 129.026666 -232.089396)
		(end 128.839214 -232.03916)
		(width 0.088646)
		(layer "In11.Cu")
		(net "M_H_CPU1_SB_DQS_DP<6>")
	)
	(arc
		(start 127.884682 -232.03027)
		(mid 127.608207 -231.96295)
		(end 127.33401 -232.038906)
		(width 0.088646)
		(layer "In11.Cu")
		(net "M_H_CPU1_SB_DQS_DP<6>")
	)
	(arc
		(start 138.799316 -231.714548)
		(mid 138.612017 -232.038989)
		(end 138.237468 -232.038906)
		(width 0.088646)
		(layer "In11.Cu")
		(net "M_H_CPU1_SB_DQS_DP<6>")
	)
	(arc
		(start 128.274318 -232.03916)
		(mid 128.094031 -232.089572)
		(end 127.91186 -232.046526)
		(width 0.088646)
		(layer "In11.Cu")
		(net "M_H_CPU1_SB_DQS_DP<6>")
	)
	(arc
		(start 130.153918 -232.03916)
		(mid 129.973631 -232.089572)
		(end 129.79146 -232.046526)
		(width 0.088646)
		(layer "In11.Cu")
		(net "M_H_CPU1_SB_DQS_DP<6>")
	)
	(arc
		(start 126.95936 -232.038906)
		(mid 126.676345 -231.963257)
		(end 126.393448 -232.039414)
		(width 0.088646)
		(layer "In11.Cu")
		(net "M_H_CPU1_SB_DQS_DP<6>")
	)
	(arc
		(start 125.541278 -232.209086)
		(mid 125.43018 -232.313829)
		(end 125.370082 -232.454196)
		(width 0.088646)
		(layer "In11.Cu")
		(net "M_H_CPU1_SB_DQS_DP<6>")
	)
	(arc
		(start 133.904228 -232.044494)
		(mid 133.720407 -232.089552)
		(end 133.53796 -232.03916)
		(width 0.088646)
		(layer "In11.Cu")
		(net "M_H_CPU1_SB_DQS_DP<6>")
	)
	(arc
		(start 133.53796 -232.03916)
		(mid 133.255512 -231.963477)
		(end 132.973064 -232.03916)
		(width 0.088646)
		(layer "In11.Cu")
		(net "M_H_CPU1_SB_DQS_DP<6>")
	)
	(arc
		(start 132.973064 -232.03916)
		(mid 132.790842 -232.08936)
		(end 132.607304 -232.04424)
		(width 0.088646)
		(layer "In11.Cu")
		(net "M_H_CPU1_SB_DQS_DP<6>")
	)
	(arc
		(start 137.297668 -232.038906)
		(mid 137.014966 -231.96313)
		(end 136.732264 -232.038906)
		(width 0.088646)
		(layer "In11.Cu")
		(net "M_H_CPU1_SB_DQS_DP<6>")
	)
	(arc
		(start 131.093718 -232.03916)
		(mid 130.913431 -232.089572)
		(end 130.73126 -232.046526)
		(width 0.088646)
		(layer "In11.Cu")
		(net "M_H_CPU1_SB_DQS_DP<6>")
	)
	(arc
		(start 132.598922 -232.039414)
		(mid 132.316249 -231.963443)
		(end 132.033518 -232.03916)
		(width 0.088646)
		(layer "In11.Cu")
		(net "M_H_CPU1_SB_DQS_DP<6>")
	)
	(arc
		(start 129.779522 -232.039414)
		(mid 129.496849 -231.963443)
		(end 129.214118 -232.03916)
		(width 0.088646)
		(layer "In11.Cu")
		(net "M_H_CPU1_SB_DQS_DP<6>")
	)
	(arc
		(start 138.237468 -232.038906)
		(mid 137.954766 -231.96313)
		(end 137.672064 -232.038906)
		(width 0.088646)
		(layer "In11.Cu")
		(net "M_H_CPU1_SB_DQS_DP<6>")
	)
	(arc
		(start 127.33401 -232.038906)
		(mid 127.146812 -232.089049)
		(end 126.959614 -232.038906)
		(width 0.088646)
		(layer "In11.Cu")
		(net "M_H_CPU1_SB_DQS_DP<6>")
	)
	(arc
		(start 135.792464 -232.038906)
		(mid 135.605266 -232.089049)
		(end 135.418068 -232.038906)
		(width 0.088646)
		(layer "In11.Cu")
		(net "M_H_CPU1_SB_DQS_DP<6>")
	)
	(segment
		(start 215.15197 -227.066602)
		(end 215.719914 -227.066602)
		(width 0.20066)
		(layer "F.Cu")
		(net "M_H_CPU1_SB_DQS_DP<5>")
	)
	(segment
		(start 210.610196 -226.64166)
		(end 212.622892 -226.64166)
		(width 0.1016)
		(layer "F.Cu")
		(net "M_H_CPU1_SB_DQS_DP<5>")
	)
	(segment
		(start 207.071214 -227.066602)
		(end 208.176114 -227.066602)
		(width 0.20066)
		(layer "F.Cu")
		(net "M_H_CPU1_SB_DQS_DP<5>")
	)
	(segment
		(start 210.598258 -226.634548)
		(end 210.603084 -226.634548)
		(width 0.101854)
		(layer "F.Cu")
		(net "M_H_CPU1_SB_DQS_DP<5>")
	)
	(segment
		(start 209.020664 -227.317808)
		(end 209.325464 -227.317808)
		(width 0.20066)
		(layer "F.Cu")
		(net "M_H_CPU1_SB_DQS_DP<5>")
	)
	(segment
		(start 210.02879 -226.892866)
		(end 210.287108 -226.634548)
		(width 0.20066)
		(layer "F.Cu")
		(net "M_H_CPU1_SB_DQS_DP<5>")
	)
	(segment
		(start 209.325464 -227.317808)
		(end 209.750406 -226.892866)
		(width 0.20066)
		(layer "F.Cu")
		(net "M_H_CPU1_SB_DQS_DP<5>")
	)
	(segment
		(start 209.750406 -226.892866)
		(end 210.02879 -226.892866)
		(width 0.20066)
		(layer "F.Cu")
		(net "M_H_CPU1_SB_DQS_DP<5>")
	)
	(segment
		(start 210.603084 -226.634548)
		(end 210.610196 -226.64166)
		(width 0.1016)
		(layer "F.Cu")
		(net "M_H_CPU1_SB_DQS_DP<5>")
	)
	(segment
		(start 210.287108 -226.634548)
		(end 210.598258 -226.634548)
		(width 0.20066)
		(layer "F.Cu")
		(net "M_H_CPU1_SB_DQS_DP<5>")
	)
	(segment
		(start 124.797312 -237.947454)
		(end 124.797312 -237.411768)
		(width 0.20066)
		(layer "F.Cu")
		(net "M_H_CPU1_SB_DQS_DP<5>")
	)
	(segment
		(start 208.176114 -227.066602)
		(end 208.769458 -227.066602)
		(width 0.20066)
		(layer "F.Cu")
		(net "M_H_CPU1_SB_DQS_DP<5>")
	)
	(segment
		(start 213.207092 -226.88931)
		(end 213.860634 -226.88931)
		(width 0.20066)
		(layer "F.Cu")
		(net "M_H_CPU1_SB_DQS_DP<5>")
	)
	(segment
		(start 214.883746 -227.334826)
		(end 215.15197 -227.066602)
		(width 0.20066)
		(layer "F.Cu")
		(net "M_H_CPU1_SB_DQS_DP<5>")
	)
	(segment
		(start 212.630258 -226.634294)
		(end 212.952076 -226.634294)
		(width 0.20066)
		(layer "F.Cu")
		(net "M_H_CPU1_SB_DQS_DP<5>")
	)
	(segment
		(start 124.797312 -237.411768)
		(end 124.797566 -237.411514)
		(width 0.20066)
		(layer "F.Cu")
		(net "M_H_CPU1_SB_DQS_DP<5>")
	)
	(segment
		(start 212.952076 -226.634294)
		(end 213.207092 -226.88931)
		(width 0.20066)
		(layer "F.Cu")
		(net "M_H_CPU1_SB_DQS_DP<5>")
	)
	(segment
		(start 212.622892 -226.64166)
		(end 212.630258 -226.634294)
		(width 0.1016)
		(layer "F.Cu")
		(net "M_H_CPU1_SB_DQS_DP<5>")
	)
	(segment
		(start 214.30615 -227.334826)
		(end 214.883746 -227.334826)
		(width 0.20066)
		(layer "F.Cu")
		(net "M_H_CPU1_SB_DQS_DP<5>")
	)
	(segment
		(start 213.860634 -226.88931)
		(end 214.30615 -227.334826)
		(width 0.20066)
		(layer "F.Cu")
		(net "M_H_CPU1_SB_DQS_DP<5>")
	)
	(segment
		(start 208.769458 -227.066602)
		(end 209.020664 -227.317808)
		(width 0.20066)
		(layer "F.Cu")
		(net "M_H_CPU1_SB_DQS_DP<5>")
	)
	(segment
		(start 144.670526 -236.307884)
		(end 141.103096 -236.307884)
		(width 0.18288)
		(layer "In11.Cu")
		(net "M_H_CPU1_SB_DQS_DP<5>")
	)
	(segment
		(start 197.134734 -225.712528)
		(end 195.949824 -224.527618)
		(width 0.18288)
		(layer "In11.Cu")
		(net "M_H_CPU1_SB_DQS_DP<5>")
	)
	(segment
		(start 162.016186 -224.090992)
		(end 161.602166 -224.090992)
		(width 0.18288)
		(layer "In11.Cu")
		(net "M_H_CPU1_SB_DQS_DP<5>")
	)
	(segment
		(start 184.737756 -221.809818)
		(end 183.215534 -222.440246)
		(width 0.18288)
		(layer "In11.Cu")
		(net "M_H_CPU1_SB_DQS_DP<5>")
	)
	(segment
		(start 172.298868 -223.52889)
		(end 168.230804 -223.52889)
		(width 0.18288)
		(layer "In11.Cu")
		(net "M_H_CPU1_SB_DQS_DP<5>")
	)
	(segment
		(start 127.901192 -236.923326)
		(end 127.88265 -236.912404)
		(width 0.088646)
		(layer "In11.Cu")
		(net "M_H_CPU1_SB_DQS_DP<5>")
	)
	(segment
		(start 178.10988 -222.642938)
		(end 177.360326 -222.642938)
		(width 0.18288)
		(layer "In11.Cu")
		(net "M_H_CPU1_SB_DQS_DP<5>")
	)
	(segment
		(start 125.370082 -237.337346)
		(end 125.295914 -237.411514)
		(width 0.088646)
		(layer "In11.Cu")
		(net "M_H_CPU1_SB_DQS_DP<5>")
	)
	(segment
		(start 125.295914 -237.411514)
		(end 124.797566 -237.411514)
		(width 0.088646)
		(layer "In11.Cu")
		(net "M_H_CPU1_SB_DQS_DP<5>")
	)
	(segment
		(start 125.676914 -237.019338)
		(end 125.550168 -237.087156)
		(width 0.088646)
		(layer "In11.Cu")
		(net "M_H_CPU1_SB_DQS_DP<5>")
	)
	(segment
		(start 195.806568 -224.468182)
		(end 193.110104 -222.666306)
		(width 0.18288)
		(layer "In11.Cu")
		(net "M_H_CPU1_SB_DQS_DP<5>")
	)
	(segment
		(start 158.659576 -225.216212)
		(end 158.18104 -225.216212)
		(width 0.18288)
		(layer "In11.Cu")
		(net "M_H_CPU1_SB_DQS_DP<5>")
	)
	(segment
		(start 125.774196 -236.994954)
		(end 125.676914 -237.019338)
		(width 0.088646)
		(layer "In11.Cu")
		(net "M_H_CPU1_SB_DQS_DP<5>")
	)
	(segment
		(start 126.959614 -236.922056)
		(end 126.944882 -236.91342)
		(width 0.088646)
		(layer "In11.Cu")
		(net "M_H_CPU1_SB_DQS_DP<5>")
	)
	(segment
		(start 200.053702 -226.921822)
		(end 197.134734 -225.712528)
		(width 0.18288)
		(layer "In11.Cu")
		(net "M_H_CPU1_SB_DQS_DP<5>")
	)
	(segment
		(start 203.48956 -226.910646)
		(end 203.220066 -226.641152)
		(width 0.18288)
		(layer "In11.Cu")
		(net "M_H_CPU1_SB_DQS_DP<5>")
	)
	(segment
		(start 157.479238 -224.94494)
		(end 157.187646 -225.236532)
		(width 0.18288)
		(layer "In11.Cu")
		(net "M_H_CPU1_SB_DQS_DP<5>")
	)
	(segment
		(start 187.667646 -221.541086)
		(end 187.398914 -221.809818)
		(width 0.18288)
		(layer "In11.Cu")
		(net "M_H_CPU1_SB_DQS_DP<5>")
	)
	(segment
		(start 155.741878 -225.236532)
		(end 144.670526 -236.307884)
		(width 0.18288)
		(layer "In11.Cu")
		(net "M_H_CPU1_SB_DQS_DP<5>")
	)
	(segment
		(start 206.801212 -227.336604)
		(end 206.515462 -227.336604)
		(width 0.18288)
		(layer "In11.Cu")
		(net "M_H_CPU1_SB_DQS_DP<5>")
	)
	(segment
		(start 188.367416 -221.818708)
		(end 188.089794 -221.541086)
		(width 0.18288)
		(layer "In11.Cu")
		(net "M_H_CPU1_SB_DQS_DP<5>")
	)
	(segment
		(start 180.01488 -222.440246)
		(end 179.597812 -222.023178)
		(width 0.18288)
		(layer "In11.Cu")
		(net "M_H_CPU1_SB_DQS_DP<5>")
	)
	(segment
		(start 129.79146 -236.92993)
		(end 129.779522 -236.922818)
		(width 0.088646)
		(layer "In11.Cu")
		(net "M_H_CPU1_SB_DQS_DP<5>")
	)
	(segment
		(start 136.357614 -236.922056)
		(end 136.342882 -236.91342)
		(width 0.088646)
		(layer "In11.Cu")
		(net "M_H_CPU1_SB_DQS_DP<5>")
	)
	(segment
		(start 161.602166 -224.090992)
		(end 161.332926 -224.360232)
		(width 0.18288)
		(layer "In11.Cu")
		(net "M_H_CPU1_SB_DQS_DP<5>")
	)
	(segment
		(start 139.210034 -237.048294)
		(end 138.99515 -236.959394)
		(width 0.088646)
		(layer "In11.Cu")
		(net "M_H_CPU1_SB_DQS_DP<5>")
	)
	(segment
		(start 206.515462 -227.336604)
		(end 206.121762 -227.499672)
		(width 0.18288)
		(layer "In11.Cu")
		(net "M_H_CPU1_SB_DQS_DP<5>")
	)
	(segment
		(start 164.305996 -223.522286)
		(end 163.673282 -223.522286)
		(width 0.18288)
		(layer "In11.Cu")
		(net "M_H_CPU1_SB_DQS_DP<5>")
	)
	(segment
		(start 132.607304 -236.927644)
		(end 132.598922 -236.922818)
		(width 0.088646)
		(layer "In11.Cu")
		(net "M_H_CPU1_SB_DQS_DP<5>")
	)
	(segment
		(start 140.406374 -236.367574)
		(end 139.7254 -237.048548)
		(width 0.088646)
		(layer "In11.Cu")
		(net "M_H_CPU1_SB_DQS_DP<5>")
	)
	(segment
		(start 127.903478 -236.92485)
		(end 127.901192 -236.923326)
		(width 0.088646)
		(layer "In11.Cu")
		(net "M_H_CPU1_SB_DQS_DP<5>")
	)
	(segment
		(start 137.297414 -236.922056)
		(end 137.282682 -236.91342)
		(width 0.088646)
		(layer "In11.Cu")
		(net "M_H_CPU1_SB_DQS_DP<5>")
	)
	(segment
		(start 158.18104 -225.216212)
		(end 157.909768 -224.94494)
		(width 0.18288)
		(layer "In11.Cu")
		(net "M_H_CPU1_SB_DQS_DP<5>")
	)
	(segment
		(start 135.417814 -236.922056)
		(end 135.417814 -236.922564)
		(width 0.088646)
		(layer "In11.Cu")
		(net "M_H_CPU1_SB_DQS_DP<5>")
	)
	(segment
		(start 195.949824 -224.527618)
		(end 195.806568 -224.468182)
		(width 0.18288)
		(layer "In11.Cu")
		(net "M_H_CPU1_SB_DQS_DP<5>")
	)
	(segment
		(start 174.32909 -222.677736)
		(end 173.475142 -223.531684)
		(width 0.18288)
		(layer "In11.Cu")
		(net "M_H_CPU1_SB_DQS_DP<5>")
	)
	(segment
		(start 126.39421 -236.922056)
		(end 126.384304 -236.927898)
		(width 0.088646)
		(layer "In11.Cu")
		(net "M_H_CPU1_SB_DQS_DP<5>")
	)
	(segment
		(start 192.223898 -222.39097)
		(end 191.758062 -222.39097)
		(width 0.18288)
		(layer "In11.Cu")
		(net "M_H_CPU1_SB_DQS_DP<5>")
	)
	(segment
		(start 178.72964 -222.023178)
		(end 178.10988 -222.642938)
		(width 0.18288)
		(layer "In11.Cu")
		(net "M_H_CPU1_SB_DQS_DP<5>")
	)
	(segment
		(start 159.515556 -224.360232)
		(end 158.659576 -225.216212)
		(width 0.18288)
		(layer "In11.Cu")
		(net "M_H_CPU1_SB_DQS_DP<5>")
	)
	(segment
		(start 133.91261 -236.922818)
		(end 133.904228 -236.927898)
		(width 0.088646)
		(layer "In11.Cu")
		(net "M_H_CPU1_SB_DQS_DP<5>")
	)
	(segment
		(start 131.67106 -236.92993)
		(end 131.659122 -236.922818)
		(width 0.088646)
		(layer "In11.Cu")
		(net "M_H_CPU1_SB_DQS_DP<5>")
	)
	(segment
		(start 139.7254 -237.048548)
		(end 139.725146 -237.048294)
		(width 0.088646)
		(layer "In11.Cu")
		(net "M_H_CPU1_SB_DQS_DP<5>")
	)
	(segment
		(start 207.071214 -227.066602)
		(end 206.801212 -227.336604)
		(width 0.18288)
		(layer "In11.Cu")
		(net "M_H_CPU1_SB_DQS_DP<5>")
	)
	(segment
		(start 138.99515 -236.959394)
		(end 138.400028 -236.959394)
		(width 0.088646)
		(layer "In11.Cu")
		(net "M_H_CPU1_SB_DQS_DP<5>")
	)
	(segment
		(start 168.230804 -223.52889)
		(end 167.346376 -224.413318)
		(width 0.18288)
		(layer "In11.Cu")
		(net "M_H_CPU1_SB_DQS_DP<5>")
	)
	(segment
		(start 127.91186 -236.92993)
		(end 127.911098 -236.929422)
		(width 0.088646)
		(layer "In11.Cu")
		(net "M_H_CPU1_SB_DQS_DP<5>")
	)
	(segment
		(start 141.103096 -236.307884)
		(end 141.043406 -236.367574)
		(width 0.088646)
		(layer "In11.Cu")
		(net "M_H_CPU1_SB_DQS_DP<5>")
	)
	(segment
		(start 125.550168 -237.087156)
		(end 125.541278 -237.092236)
		(width 0.088646)
		(layer "In11.Cu")
		(net "M_H_CPU1_SB_DQS_DP<5>")
	)
	(segment
		(start 176.690782 -222.39097)
		(end 176.404016 -222.677736)
		(width 0.18288)
		(layer "In11.Cu")
		(net "M_H_CPU1_SB_DQS_DP<5>")
	)
	(segment
		(start 141.043406 -236.367574)
		(end 140.406374 -236.367574)
		(width 0.088646)
		(layer "In11.Cu")
		(net "M_H_CPU1_SB_DQS_DP<5>")
	)
	(segment
		(start 139.725146 -237.048294)
		(end 139.210034 -237.048294)
		(width 0.088646)
		(layer "In11.Cu")
		(net "M_H_CPU1_SB_DQS_DP<5>")
	)
	(segment
		(start 127.88265 -236.912404)
		(end 127.884682 -236.91342)
		(width 0.088646)
		(layer "In11.Cu")
		(net "M_H_CPU1_SB_DQS_DP<5>")
	)
	(segment
		(start 127.90932 -236.928406)
		(end 127.908558 -236.927898)
		(width 0.088646)
		(layer "In11.Cu")
		(net "M_H_CPU1_SB_DQS_DP<5>")
	)
	(segment
		(start 162.82924 -224.366328)
		(end 162.291522 -224.366328)
		(width 0.18288)
		(layer "In11.Cu")
		(net "M_H_CPU1_SB_DQS_DP<5>")
	)
	(segment
		(start 183.215534 -222.440246)
		(end 180.01488 -222.440246)
		(width 0.18288)
		(layer "In11.Cu")
		(net "M_H_CPU1_SB_DQS_DP<5>")
	)
	(segment
		(start 203.933044 -226.910646)
		(end 203.48956 -226.910646)
		(width 0.18288)
		(layer "In11.Cu")
		(net "M_H_CPU1_SB_DQS_DP<5>")
	)
	(segment
		(start 204.52207 -227.499672)
		(end 203.933044 -226.910646)
		(width 0.18288)
		(layer "In11.Cu")
		(net "M_H_CPU1_SB_DQS_DP<5>")
	)
	(segment
		(start 188.089794 -221.541086)
		(end 187.667646 -221.541086)
		(width 0.18288)
		(layer "In11.Cu")
		(net "M_H_CPU1_SB_DQS_DP<5>")
	)
	(segment
		(start 191.758062 -222.39097)
		(end 191.48806 -222.660972)
		(width 0.18288)
		(layer "In11.Cu")
		(net "M_H_CPU1_SB_DQS_DP<5>")
	)
	(segment
		(start 167.346376 -224.413318)
		(end 165.197028 -224.413318)
		(width 0.18288)
		(layer "In11.Cu")
		(net "M_H_CPU1_SB_DQS_DP<5>")
	)
	(segment
		(start 179.597812 -222.023178)
		(end 178.72964 -222.023178)
		(width 0.18288)
		(layer "In11.Cu")
		(net "M_H_CPU1_SB_DQS_DP<5>")
	)
	(segment
		(start 127.907542 -236.92739)
		(end 127.906018 -236.926374)
		(width 0.088646)
		(layer "In11.Cu")
		(net "M_H_CPU1_SB_DQS_DP<5>")
	)
	(segment
		(start 126.384304 -236.927898)
		(end 126.273306 -236.982508)
		(width 0.088646)
		(layer "In11.Cu")
		(net "M_H_CPU1_SB_DQS_DP<5>")
	)
	(segment
		(start 126.273306 -236.982508)
		(end 125.798834 -236.991652)
		(width 0.088646)
		(layer "In11.Cu")
		(net "M_H_CPU1_SB_DQS_DP<5>")
	)
	(segment
		(start 173.005242 -223.241108)
		(end 172.58665 -223.241108)
		(width 0.18288)
		(layer "In11.Cu")
		(net "M_H_CPU1_SB_DQS_DP<5>")
	)
	(segment
		(start 202.465432 -226.921822)
		(end 200.053702 -226.921822)
		(width 0.18288)
		(layer "In11.Cu")
		(net "M_H_CPU1_SB_DQS_DP<5>")
	)
	(segment
		(start 161.332926 -224.360232)
		(end 159.515556 -224.360232)
		(width 0.18288)
		(layer "In11.Cu")
		(net "M_H_CPU1_SB_DQS_DP<5>")
	)
	(segment
		(start 176.404016 -222.677736)
		(end 174.32909 -222.677736)
		(width 0.18288)
		(layer "In11.Cu")
		(net "M_H_CPU1_SB_DQS_DP<5>")
	)
	(segment
		(start 177.360326 -222.642938)
		(end 177.108358 -222.39097)
		(width 0.18288)
		(layer "In11.Cu")
		(net "M_H_CPU1_SB_DQS_DP<5>")
	)
	(segment
		(start 157.909768 -224.94494)
		(end 157.479238 -224.94494)
		(width 0.18288)
		(layer "In11.Cu")
		(net "M_H_CPU1_SB_DQS_DP<5>")
	)
	(segment
		(start 173.475142 -223.531684)
		(end 173.295818 -223.531684)
		(width 0.18288)
		(layer "In11.Cu")
		(net "M_H_CPU1_SB_DQS_DP<5>")
	)
	(segment
		(start 127.908558 -236.927898)
		(end 127.907542 -236.92739)
		(width 0.088646)
		(layer "In11.Cu")
		(net "M_H_CPU1_SB_DQS_DP<5>")
	)
	(segment
		(start 202.746102 -226.641152)
		(end 202.465432 -226.921822)
		(width 0.18288)
		(layer "In11.Cu")
		(net "M_H_CPU1_SB_DQS_DP<5>")
	)
	(segment
		(start 192.499234 -222.666306)
		(end 192.223898 -222.39097)
		(width 0.18288)
		(layer "In11.Cu")
		(net "M_H_CPU1_SB_DQS_DP<5>")
	)
	(segment
		(start 203.220066 -226.641152)
		(end 202.746102 -226.641152)
		(width 0.18288)
		(layer "In11.Cu")
		(net "M_H_CPU1_SB_DQS_DP<5>")
	)
	(segment
		(start 193.110104 -222.666306)
		(end 192.499234 -222.666306)
		(width 0.18288)
		(layer "In11.Cu")
		(net "M_H_CPU1_SB_DQS_DP<5>")
	)
	(segment
		(start 130.73126 -236.92993)
		(end 130.719322 -236.922818)
		(width 0.088646)
		(layer "In11.Cu")
		(net "M_H_CPU1_SB_DQS_DP<5>")
	)
	(segment
		(start 172.58665 -223.241108)
		(end 172.298868 -223.52889)
		(width 0.18288)
		(layer "In11.Cu")
		(net "M_H_CPU1_SB_DQS_DP<5>")
	)
	(segment
		(start 206.121762 -227.499672)
		(end 204.52207 -227.499672)
		(width 0.18288)
		(layer "In11.Cu")
		(net "M_H_CPU1_SB_DQS_DP<5>")
	)
	(segment
		(start 173.295818 -223.531684)
		(end 173.005242 -223.241108)
		(width 0.18288)
		(layer "In11.Cu")
		(net "M_H_CPU1_SB_DQS_DP<5>")
	)
	(segment
		(start 188.594492 -221.818708)
		(end 188.367416 -221.818708)
		(width 0.18288)
		(layer "In11.Cu")
		(net "M_H_CPU1_SB_DQS_DP<5>")
	)
	(segment
		(start 127.911098 -236.929422)
		(end 127.90932 -236.928406)
		(width 0.088646)
		(layer "In11.Cu")
		(net "M_H_CPU1_SB_DQS_DP<5>")
	)
	(segment
		(start 157.187646 -225.236532)
		(end 155.741878 -225.236532)
		(width 0.18288)
		(layer "In11.Cu")
		(net "M_H_CPU1_SB_DQS_DP<5>")
	)
	(segment
		(start 127.906018 -236.926374)
		(end 127.903478 -236.92485)
		(width 0.088646)
		(layer "In11.Cu")
		(net "M_H_CPU1_SB_DQS_DP<5>")
	)
	(segment
		(start 177.108358 -222.39097)
		(end 176.690782 -222.39097)
		(width 0.18288)
		(layer "In11.Cu")
		(net "M_H_CPU1_SB_DQS_DP<5>")
	)
	(segment
		(start 187.398914 -221.809818)
		(end 184.737756 -221.809818)
		(width 0.18288)
		(layer "In11.Cu")
		(net "M_H_CPU1_SB_DQS_DP<5>")
	)
	(segment
		(start 191.48806 -222.660972)
		(end 190.628016 -222.660972)
		(width 0.18288)
		(layer "In11.Cu")
		(net "M_H_CPU1_SB_DQS_DP<5>")
	)
	(segment
		(start 163.673282 -223.522286)
		(end 162.82924 -224.366328)
		(width 0.18288)
		(layer "In11.Cu")
		(net "M_H_CPU1_SB_DQS_DP<5>")
	)
	(segment
		(start 190.628016 -222.660972)
		(end 188.594492 -221.818708)
		(width 0.18288)
		(layer "In11.Cu")
		(net "M_H_CPU1_SB_DQS_DP<5>")
	)
	(segment
		(start 165.197028 -224.413318)
		(end 164.305996 -223.522286)
		(width 0.18288)
		(layer "In11.Cu")
		(net "M_H_CPU1_SB_DQS_DP<5>")
	)
	(segment
		(start 162.291522 -224.366328)
		(end 162.016186 -224.090992)
		(width 0.18288)
		(layer "In11.Cu")
		(net "M_H_CPU1_SB_DQS_DP<5>")
	)
	(arc
		(start 135.417814 -236.922564)
		(mid 135.135366 -236.846847)
		(end 134.852918 -236.922564)
		(width 0.088646)
		(layer "In11.Cu")
		(net "M_H_CPU1_SB_DQS_DP<5>")
	)
	(arc
		(start 134.852918 -236.922564)
		(mid 134.665466 -236.9728)
		(end 134.478014 -236.922564)
		(width 0.088646)
		(layer "In11.Cu")
		(net "M_H_CPU1_SB_DQS_DP<5>")
	)
	(arc
		(start 137.282682 -236.91342)
		(mid 137.006207 -236.8461)
		(end 136.73201 -236.922056)
		(width 0.088646)
		(layer "In11.Cu")
		(net "M_H_CPU1_SB_DQS_DP<5>")
	)
	(arc
		(start 137.67181 -236.922056)
		(mid 137.484612 -236.972233)
		(end 137.297414 -236.922056)
		(width 0.088646)
		(layer "In11.Cu")
		(net "M_H_CPU1_SB_DQS_DP<5>")
	)
	(arc
		(start 133.904228 -236.927898)
		(mid 133.720407 -236.972956)
		(end 133.53796 -236.922564)
		(width 0.088646)
		(layer "In11.Cu")
		(net "M_H_CPU1_SB_DQS_DP<5>")
	)
	(arc
		(start 128.274318 -236.922564)
		(mid 128.094031 -236.972976)
		(end 127.91186 -236.92993)
		(width 0.088646)
		(layer "In11.Cu")
		(net "M_H_CPU1_SB_DQS_DP<5>")
	)
	(arc
		(start 138.222482 -236.91342)
		(mid 137.946007 -236.8461)
		(end 137.67181 -236.922056)
		(width 0.088646)
		(layer "In11.Cu")
		(net "M_H_CPU1_SB_DQS_DP<5>")
	)
	(arc
		(start 126.944882 -236.91342)
		(mid 126.668407 -236.8461)
		(end 126.39421 -236.922056)
		(width 0.088646)
		(layer "In11.Cu")
		(net "M_H_CPU1_SB_DQS_DP<5>")
	)
	(arc
		(start 125.798834 -236.991652)
		(mid 125.786419 -236.99259)
		(end 125.774196 -236.994954)
		(width 0.088646)
		(layer "In11.Cu")
		(net "M_H_CPU1_SB_DQS_DP<5>")
	)
	(arc
		(start 130.719322 -236.922818)
		(mid 130.436649 -236.846812)
		(end 130.153918 -236.922564)
		(width 0.088646)
		(layer "In11.Cu")
		(net "M_H_CPU1_SB_DQS_DP<5>")
	)
	(arc
		(start 136.73201 -236.922056)
		(mid 136.544812 -236.972233)
		(end 136.357614 -236.922056)
		(width 0.088646)
		(layer "In11.Cu")
		(net "M_H_CPU1_SB_DQS_DP<5>")
	)
	(arc
		(start 125.541278 -237.092236)
		(mid 125.43018 -237.196979)
		(end 125.370082 -237.337346)
		(width 0.088646)
		(layer "In11.Cu")
		(net "M_H_CPU1_SB_DQS_DP<5>")
	)
	(arc
		(start 132.598922 -236.922818)
		(mid 132.316249 -236.846812)
		(end 132.033518 -236.922564)
		(width 0.088646)
		(layer "In11.Cu")
		(net "M_H_CPU1_SB_DQS_DP<5>")
	)
	(arc
		(start 132.973064 -236.922564)
		(mid 132.790842 -236.972764)
		(end 132.607304 -236.927644)
		(width 0.088646)
		(layer "In11.Cu")
		(net "M_H_CPU1_SB_DQS_DP<5>")
	)
	(arc
		(start 131.093718 -236.922564)
		(mid 130.913431 -236.972976)
		(end 130.73126 -236.92993)
		(width 0.088646)
		(layer "In11.Cu")
		(net "M_H_CPU1_SB_DQS_DP<5>")
	)
	(arc
		(start 129.779522 -236.922818)
		(mid 129.496849 -236.846812)
		(end 129.214118 -236.922564)
		(width 0.088646)
		(layer "In11.Cu")
		(net "M_H_CPU1_SB_DQS_DP<5>")
	)
	(arc
		(start 127.884682 -236.91342)
		(mid 127.608207 -236.8461)
		(end 127.33401 -236.922056)
		(width 0.088646)
		(layer "In11.Cu")
		(net "M_H_CPU1_SB_DQS_DP<5>")
	)
	(arc
		(start 138.400028 -236.959394)
		(mid 138.308394 -236.947446)
		(end 138.222482 -236.91342)
		(width 0.088646)
		(layer "In11.Cu")
		(net "M_H_CPU1_SB_DQS_DP<5>")
	)
	(arc
		(start 134.478014 -236.922564)
		(mid 134.195283 -236.846847)
		(end 133.91261 -236.922818)
		(width 0.088646)
		(layer "In11.Cu")
		(net "M_H_CPU1_SB_DQS_DP<5>")
	)
	(arc
		(start 135.79221 -236.922056)
		(mid 135.605012 -236.972233)
		(end 135.417814 -236.922056)
		(width 0.088646)
		(layer "In11.Cu")
		(net "M_H_CPU1_SB_DQS_DP<5>")
	)
	(arc
		(start 128.839214 -236.922564)
		(mid 128.556766 -236.846847)
		(end 128.274318 -236.922564)
		(width 0.088646)
		(layer "In11.Cu")
		(net "M_H_CPU1_SB_DQS_DP<5>")
	)
	(arc
		(start 131.659122 -236.922818)
		(mid 131.376449 -236.846812)
		(end 131.093718 -236.922564)
		(width 0.088646)
		(layer "In11.Cu")
		(net "M_H_CPU1_SB_DQS_DP<5>")
	)
	(arc
		(start 129.214118 -236.922564)
		(mid 129.026666 -236.9728)
		(end 128.839214 -236.922564)
		(width 0.088646)
		(layer "In11.Cu")
		(net "M_H_CPU1_SB_DQS_DP<5>")
	)
	(arc
		(start 133.53796 -236.922564)
		(mid 133.255512 -236.846847)
		(end 132.973064 -236.922564)
		(width 0.088646)
		(layer "In11.Cu")
		(net "M_H_CPU1_SB_DQS_DP<5>")
	)
	(arc
		(start 127.33401 -236.922056)
		(mid 127.146812 -236.972233)
		(end 126.959614 -236.922056)
		(width 0.088646)
		(layer "In11.Cu")
		(net "M_H_CPU1_SB_DQS_DP<5>")
	)
	(arc
		(start 136.342882 -236.91342)
		(mid 136.066407 -236.8461)
		(end 135.79221 -236.922056)
		(width 0.088646)
		(layer "In11.Cu")
		(net "M_H_CPU1_SB_DQS_DP<5>")
	)
	(arc
		(start 130.153918 -236.922564)
		(mid 129.973631 -236.972976)
		(end 129.79146 -236.92993)
		(width 0.088646)
		(layer "In11.Cu")
		(net "M_H_CPU1_SB_DQS_DP<5>")
	)
	(arc
		(start 132.033518 -236.922564)
		(mid 131.853231 -236.972976)
		(end 131.67106 -236.92993)
		(width 0.088646)
		(layer "In11.Cu")
		(net "M_H_CPU1_SB_DQS_DP<5>")
	)
	(segment
		(start 213.207092 -236.239304)
		(end 213.860634 -236.239304)
		(width 0.20066)
		(layer "F.Cu")
		(net "M_H_CPU1_SB_DQS_DP<4>")
	)
	(segment
		(start 210.610196 -235.991654)
		(end 212.622892 -235.991654)
		(width 0.1016)
		(layer "F.Cu")
		(net "M_H_CPU1_SB_DQS_DP<4>")
	)
	(segment
		(start 212.622892 -235.991654)
		(end 212.630258 -235.984288)
		(width 0.1016)
		(layer "F.Cu")
		(net "M_H_CPU1_SB_DQS_DP<4>")
	)
	(segment
		(start 124.797312 -242.830858)
		(end 124.797566 -242.830604)
		(width 0.20066)
		(layer "F.Cu")
		(net "M_H_CPU1_SB_DQS_DP<4>")
	)
	(segment
		(start 208.176114 -236.416596)
		(end 208.769458 -236.416596)
		(width 0.20066)
		(layer "F.Cu")
		(net "M_H_CPU1_SB_DQS_DP<4>")
	)
	(segment
		(start 212.952076 -235.984288)
		(end 213.207092 -236.239304)
		(width 0.20066)
		(layer "F.Cu")
		(net "M_H_CPU1_SB_DQS_DP<4>")
	)
	(segment
		(start 210.287108 -235.984542)
		(end 210.598258 -235.984542)
		(width 0.20066)
		(layer "F.Cu")
		(net "M_H_CPU1_SB_DQS_DP<4>")
	)
	(segment
		(start 214.883746 -236.68482)
		(end 215.15197 -236.416596)
		(width 0.20066)
		(layer "F.Cu")
		(net "M_H_CPU1_SB_DQS_DP<4>")
	)
	(segment
		(start 210.603084 -235.984542)
		(end 210.610196 -235.991654)
		(width 0.1016)
		(layer "F.Cu")
		(net "M_H_CPU1_SB_DQS_DP<4>")
	)
	(segment
		(start 209.325464 -236.667802)
		(end 209.750406 -236.24286)
		(width 0.20066)
		(layer "F.Cu")
		(net "M_H_CPU1_SB_DQS_DP<4>")
	)
	(segment
		(start 210.598258 -235.984542)
		(end 210.603084 -235.984542)
		(width 0.101854)
		(layer "F.Cu")
		(net "M_H_CPU1_SB_DQS_DP<4>")
	)
	(segment
		(start 209.020664 -236.667802)
		(end 209.325464 -236.667802)
		(width 0.20066)
		(layer "F.Cu")
		(net "M_H_CPU1_SB_DQS_DP<4>")
	)
	(segment
		(start 208.769458 -236.416596)
		(end 209.020664 -236.667802)
		(width 0.20066)
		(layer "F.Cu")
		(net "M_H_CPU1_SB_DQS_DP<4>")
	)
	(segment
		(start 209.750406 -236.24286)
		(end 210.02879 -236.24286)
		(width 0.20066)
		(layer "F.Cu")
		(net "M_H_CPU1_SB_DQS_DP<4>")
	)
	(segment
		(start 213.860634 -236.239304)
		(end 214.30615 -236.68482)
		(width 0.20066)
		(layer "F.Cu")
		(net "M_H_CPU1_SB_DQS_DP<4>")
	)
	(segment
		(start 124.797566 -242.830604)
		(end 124.797566 -242.294918)
		(width 0.20066)
		(layer "F.Cu")
		(net "M_H_CPU1_SB_DQS_DP<4>")
	)
	(segment
		(start 212.630258 -235.984288)
		(end 212.952076 -235.984288)
		(width 0.20066)
		(layer "F.Cu")
		(net "M_H_CPU1_SB_DQS_DP<4>")
	)
	(segment
		(start 207.071214 -236.416596)
		(end 208.176114 -236.416596)
		(width 0.20066)
		(layer "F.Cu")
		(net "M_H_CPU1_SB_DQS_DP<4>")
	)
	(segment
		(start 215.15197 -236.416596)
		(end 215.719914 -236.416596)
		(width 0.20066)
		(layer "F.Cu")
		(net "M_H_CPU1_SB_DQS_DP<4>")
	)
	(segment
		(start 210.02879 -236.24286)
		(end 210.287108 -235.984542)
		(width 0.20066)
		(layer "F.Cu")
		(net "M_H_CPU1_SB_DQS_DP<4>")
	)
	(segment
		(start 214.30615 -236.68482)
		(end 214.883746 -236.68482)
		(width 0.20066)
		(layer "F.Cu")
		(net "M_H_CPU1_SB_DQS_DP<4>")
	)
	(segment
		(start 140.231114 -242.382294)
		(end 140.01623 -242.597178)
		(width 0.088646)
		(layer "In11.Cu")
		(net "M_H_CPU1_SB_DQS_DP<4>")
	)
	(segment
		(start 173.301406 -234.573064)
		(end 173.019466 -234.291124)
		(width 0.18288)
		(layer "In11.Cu")
		(net "M_H_CPU1_SB_DQS_DP<4>")
	)
	(segment
		(start 127.91186 -241.81308)
		(end 127.899922 -241.805968)
		(width 0.088646)
		(layer "In11.Cu")
		(net "M_H_CPU1_SB_DQS_DP<4>")
	)
	(segment
		(start 179.071524 -234.321096)
		(end 177.612294 -233.716576)
		(width 0.18288)
		(layer "In11.Cu")
		(net "M_H_CPU1_SB_DQS_DP<4>")
	)
	(segment
		(start 129.79146 -241.81308)
		(end 129.779522 -241.805968)
		(width 0.088646)
		(layer "In11.Cu")
		(net "M_H_CPU1_SB_DQS_DP<4>")
	)
	(segment
		(start 206.8068 -236.68101)
		(end 206.177134 -236.68101)
		(width 0.18288)
		(layer "In11.Cu")
		(net "M_H_CPU1_SB_DQS_DP<4>")
	)
	(segment
		(start 176.666398 -233.44124)
		(end 176.403762 -233.703876)
		(width 0.18288)
		(layer "In11.Cu")
		(net "M_H_CPU1_SB_DQS_DP<4>")
	)
	(segment
		(start 197.768972 -235.67136)
		(end 195.285614 -235.67136)
		(width 0.18288)
		(layer "In11.Cu")
		(net "M_H_CPU1_SB_DQS_DP<4>")
	)
	(segment
		(start 159.965644 -235.65231)
		(end 158.754318 -236.15396)
		(width 0.18288)
		(layer "In11.Cu")
		(net "M_H_CPU1_SB_DQS_DP<4>")
	)
	(segment
		(start 202.875642 -235.991146)
		(end 202.766422 -235.991146)
		(width 0.18288)
		(layer "In11.Cu")
		(net "M_H_CPU1_SB_DQS_DP<4>")
	)
	(segment
		(start 161.413444 -236.013244)
		(end 160.541716 -235.65231)
		(width 0.18288)
		(layer "In11.Cu")
		(net "M_H_CPU1_SB_DQS_DP<4>")
	)
	(segment
		(start 206.177134 -236.68101)
		(end 205.64729 -236.900466)
		(width 0.18288)
		(layer "In11.Cu")
		(net "M_H_CPU1_SB_DQS_DP<4>")
	)
	(segment
		(start 192.18275 -235.141262)
		(end 191.71539 -235.141262)
		(width 0.18288)
		(layer "In11.Cu")
		(net "M_H_CPU1_SB_DQS_DP<4>")
	)
	(segment
		(start 194.243706 -236.102906)
		(end 194.06997 -236.102906)
		(width 0.18288)
		(layer "In11.Cu")
		(net "M_H_CPU1_SB_DQS_DP<4>")
	)
	(segment
		(start 130.73126 -241.81308)
		(end 130.719322 -241.805968)
		(width 0.088646)
		(layer "In11.Cu")
		(net "M_H_CPU1_SB_DQS_DP<4>")
	)
	(segment
		(start 192.484756 -235.443268)
		(end 192.18275 -235.141262)
		(width 0.18288)
		(layer "In11.Cu")
		(net "M_H_CPU1_SB_DQS_DP<4>")
	)
	(segment
		(start 204.125322 -236.287818)
		(end 203.514706 -236.287818)
		(width 0.18288)
		(layer "In11.Cu")
		(net "M_H_CPU1_SB_DQS_DP<4>")
	)
	(segment
		(start 202.766422 -235.991146)
		(end 202.50023 -236.257338)
		(width 0.18288)
		(layer "In11.Cu")
		(net "M_H_CPU1_SB_DQS_DP<4>")
	)
	(segment
		(start 163.49599 -234.843574)
		(end 161.745676 -236.013244)
		(width 0.18288)
		(layer "In11.Cu")
		(net "M_H_CPU1_SB_DQS_DP<4>")
	)
	(segment
		(start 203.051918 -235.991146)
		(end 202.875642 -235.991146)
		(width 0.16002)
		(layer "In11.Cu")
		(net "M_H_CPU1_SB_DQS_DP<4>")
	)
	(segment
		(start 191.443864 -235.412788)
		(end 189.787784 -235.412788)
		(width 0.18288)
		(layer "In11.Cu")
		(net "M_H_CPU1_SB_DQS_DP<4>")
	)
	(segment
		(start 175.490378 -233.703876)
		(end 173.39183 -234.573064)
		(width 0.18288)
		(layer "In11.Cu")
		(net "M_H_CPU1_SB_DQS_DP<4>")
	)
	(segment
		(start 180.124354 -233.967528)
		(end 179.270152 -234.321096)
		(width 0.18288)
		(layer "In11.Cu")
		(net "M_H_CPU1_SB_DQS_DP<4>")
	)
	(segment
		(start 194.06997 -236.102906)
		(end 193.834258 -236.005116)
		(width 0.18288)
		(layer "In11.Cu")
		(net "M_H_CPU1_SB_DQS_DP<4>")
	)
	(segment
		(start 164.392356 -234.843574)
		(end 163.49599 -234.843574)
		(width 0.18288)
		(layer "In11.Cu")
		(net "M_H_CPU1_SB_DQS_DP<4>")
	)
	(segment
		(start 126.384304 -241.811302)
		(end 126.273306 -241.865912)
		(width 0.088646)
		(layer "In11.Cu")
		(net "M_H_CPU1_SB_DQS_DP<4>")
	)
	(segment
		(start 185.815224 -234.586272)
		(end 182.704486 -233.967528)
		(width 0.18288)
		(layer "In11.Cu")
		(net "M_H_CPU1_SB_DQS_DP<4>")
	)
	(segment
		(start 158.754318 -236.15396)
		(end 157.997906 -236.910626)
		(width 0.18288)
		(layer "In11.Cu")
		(net "M_H_CPU1_SB_DQS_DP<4>")
	)
	(segment
		(start 161.745676 -236.013244)
		(end 161.413444 -236.013244)
		(width 0.18288)
		(layer "In11.Cu")
		(net "M_H_CPU1_SB_DQS_DP<4>")
	)
	(segment
		(start 160.541716 -235.65231)
		(end 159.965644 -235.65231)
		(width 0.18288)
		(layer "In11.Cu")
		(net "M_H_CPU1_SB_DQS_DP<4>")
	)
	(segment
		(start 203.514706 -236.287818)
		(end 203.218034 -235.991146)
		(width 0.18288)
		(layer "In11.Cu")
		(net "M_H_CPU1_SB_DQS_DP<4>")
	)
	(segment
		(start 176.403762 -233.703876)
		(end 175.490378 -233.703876)
		(width 0.18288)
		(layer "In11.Cu")
		(net "M_H_CPU1_SB_DQS_DP<4>")
	)
	(segment
		(start 165.911276 -235.472732)
		(end 164.392356 -234.843574)
		(width 0.18288)
		(layer "In11.Cu")
		(net "M_H_CPU1_SB_DQS_DP<4>")
	)
	(segment
		(start 193.598546 -235.769404)
		(end 192.810892 -235.443268)
		(width 0.18288)
		(layer "In11.Cu")
		(net "M_H_CPU1_SB_DQS_DP<4>")
	)
	(segment
		(start 131.67106 -241.81308)
		(end 131.659122 -241.805968)
		(width 0.088646)
		(layer "In11.Cu")
		(net "M_H_CPU1_SB_DQS_DP<4>")
	)
	(segment
		(start 202.50023 -236.257338)
		(end 200.716896 -236.257338)
		(width 0.18288)
		(layer "In11.Cu")
		(net "M_H_CPU1_SB_DQS_DP<4>")
	)
	(segment
		(start 126.39421 -241.80546)
		(end 126.384304 -241.811302)
		(width 0.088646)
		(layer "In11.Cu")
		(net "M_H_CPU1_SB_DQS_DP<4>")
	)
	(segment
		(start 172.264832 -234.599734)
		(end 169.246042 -234.599734)
		(width 0.18288)
		(layer "In11.Cu")
		(net "M_H_CPU1_SB_DQS_DP<4>")
	)
	(segment
		(start 126.273306 -241.865912)
		(end 125.798834 -241.875056)
		(width 0.088646)
		(layer "In11.Cu")
		(net "M_H_CPU1_SB_DQS_DP<4>")
	)
	(segment
		(start 134.478014 -241.80546)
		(end 134.4676 -241.799364)
		(width 0.088646)
		(layer "In11.Cu")
		(net "M_H_CPU1_SB_DQS_DP<4>")
	)
	(segment
		(start 188.152532 -234.290108)
		(end 187.590684 -234.290108)
		(width 0.18288)
		(layer "In11.Cu")
		(net "M_H_CPU1_SB_DQS_DP<4>")
	)
	(segment
		(start 187.29452 -234.586272)
		(end 185.815224 -234.586272)
		(width 0.18288)
		(layer "In11.Cu")
		(net "M_H_CPU1_SB_DQS_DP<4>")
	)
	(segment
		(start 205.64729 -236.900466)
		(end 205.075028 -236.900466)
		(width 0.18288)
		(layer "In11.Cu")
		(net "M_H_CPU1_SB_DQS_DP<4>")
	)
	(segment
		(start 192.810892 -235.443268)
		(end 192.484756 -235.443268)
		(width 0.18288)
		(layer "In11.Cu")
		(net "M_H_CPU1_SB_DQS_DP<4>")
	)
	(segment
		(start 141.043406 -242.382294)
		(end 140.231114 -242.382294)
		(width 0.088646)
		(layer "In11.Cu")
		(net "M_H_CPU1_SB_DQS_DP<4>")
	)
	(segment
		(start 173.39183 -234.573064)
		(end 173.301406 -234.573064)
		(width 0.18288)
		(layer "In11.Cu")
		(net "M_H_CPU1_SB_DQS_DP<4>")
	)
	(segment
		(start 177.37455 -233.716576)
		(end 177.099214 -233.44124)
		(width 0.18288)
		(layer "In11.Cu")
		(net "M_H_CPU1_SB_DQS_DP<4>")
	)
	(segment
		(start 195.285614 -235.67136)
		(end 194.243706 -236.102906)
		(width 0.18288)
		(layer "In11.Cu")
		(net "M_H_CPU1_SB_DQS_DP<4>")
	)
	(segment
		(start 173.019466 -234.291124)
		(end 172.573442 -234.291124)
		(width 0.18288)
		(layer "In11.Cu")
		(net "M_H_CPU1_SB_DQS_DP<4>")
	)
	(segment
		(start 125.774196 -241.878358)
		(end 125.676914 -241.902742)
		(width 0.088646)
		(layer "In11.Cu")
		(net "M_H_CPU1_SB_DQS_DP<4>")
	)
	(segment
		(start 205.075028 -236.900466)
		(end 204.499718 -236.66196)
		(width 0.18288)
		(layer "In11.Cu")
		(net "M_H_CPU1_SB_DQS_DP<4>")
	)
	(segment
		(start 187.590684 -234.290108)
		(end 187.29452 -234.586272)
		(width 0.18288)
		(layer "In11.Cu")
		(net "M_H_CPU1_SB_DQS_DP<4>")
	)
	(segment
		(start 193.834258 -236.005116)
		(end 193.598546 -235.769404)
		(width 0.18288)
		(layer "In11.Cu")
		(net "M_H_CPU1_SB_DQS_DP<4>")
	)
	(segment
		(start 177.612294 -233.716576)
		(end 177.37455 -233.716576)
		(width 0.18288)
		(layer "In11.Cu")
		(net "M_H_CPU1_SB_DQS_DP<4>")
	)
	(segment
		(start 172.573442 -234.291124)
		(end 172.264832 -234.599734)
		(width 0.18288)
		(layer "In11.Cu")
		(net "M_H_CPU1_SB_DQS_DP<4>")
	)
	(segment
		(start 207.071214 -236.416596)
		(end 206.8068 -236.68101)
		(width 0.18288)
		(layer "In11.Cu")
		(net "M_H_CPU1_SB_DQS_DP<4>")
	)
	(segment
		(start 203.218034 -235.991146)
		(end 203.051918 -235.991146)
		(width 0.18288)
		(layer "In11.Cu")
		(net "M_H_CPU1_SB_DQS_DP<4>")
	)
	(segment
		(start 157.997906 -236.910626)
		(end 152.988518 -236.910626)
		(width 0.18288)
		(layer "In11.Cu")
		(net "M_H_CPU1_SB_DQS_DP<4>")
	)
	(segment
		(start 126.959614 -241.80546)
		(end 126.944882 -241.796824)
		(width 0.088646)
		(layer "In11.Cu")
		(net "M_H_CPU1_SB_DQS_DP<4>")
	)
	(segment
		(start 191.71539 -235.141262)
		(end 191.443864 -235.412788)
		(width 0.18288)
		(layer "In11.Cu")
		(net "M_H_CPU1_SB_DQS_DP<4>")
	)
	(segment
		(start 188.968888 -234.593892)
		(end 188.456316 -234.593892)
		(width 0.18288)
		(layer "In11.Cu")
		(net "M_H_CPU1_SB_DQS_DP<4>")
	)
	(segment
		(start 152.988518 -236.910626)
		(end 147.57654 -242.322604)
		(width 0.18288)
		(layer "In11.Cu")
		(net "M_H_CPU1_SB_DQS_DP<4>")
	)
	(segment
		(start 169.246042 -234.599734)
		(end 167.136572 -235.472732)
		(width 0.18288)
		(layer "In11.Cu")
		(net "M_H_CPU1_SB_DQS_DP<4>")
	)
	(segment
		(start 182.704486 -233.967528)
		(end 180.124354 -233.967528)
		(width 0.18288)
		(layer "In11.Cu")
		(net "M_H_CPU1_SB_DQS_DP<4>")
	)
	(segment
		(start 127.334518 -241.805714)
		(end 127.33401 -241.80546)
		(width 0.088646)
		(layer "In11.Cu")
		(net "M_H_CPU1_SB_DQS_DP<4>")
	)
	(segment
		(start 189.787784 -235.412788)
		(end 188.968888 -234.593892)
		(width 0.18288)
		(layer "In11.Cu")
		(net "M_H_CPU1_SB_DQS_DP<4>")
	)
	(segment
		(start 140.01623 -242.597178)
		(end 138.226038 -242.597178)
		(width 0.088646)
		(layer "In11.Cu")
		(net "M_H_CPU1_SB_DQS_DP<4>")
	)
	(segment
		(start 204.499718 -236.66196)
		(end 204.125322 -236.287818)
		(width 0.18288)
		(layer "In11.Cu")
		(net "M_H_CPU1_SB_DQS_DP<4>")
	)
	(segment
		(start 141.103096 -242.322604)
		(end 141.043406 -242.382294)
		(width 0.088646)
		(layer "In11.Cu")
		(net "M_H_CPU1_SB_DQS_DP<4>")
	)
	(segment
		(start 188.456316 -234.593892)
		(end 188.152532 -234.290108)
		(width 0.18288)
		(layer "In11.Cu")
		(net "M_H_CPU1_SB_DQS_DP<4>")
	)
	(segment
		(start 138.226038 -242.597178)
		(end 137.48512 -241.85626)
		(width 0.088646)
		(layer "In11.Cu")
		(net "M_H_CPU1_SB_DQS_DP<4>")
	)
	(segment
		(start 179.270152 -234.321096)
		(end 179.071524 -234.321096)
		(width 0.18288)
		(layer "In11.Cu")
		(net "M_H_CPU1_SB_DQS_DP<4>")
	)
	(segment
		(start 133.912864 -241.80546)
		(end 133.913118 -241.805714)
		(width 0.088646)
		(layer "In11.Cu")
		(net "M_H_CPU1_SB_DQS_DP<4>")
	)
	(segment
		(start 135.418068 -241.80546)
		(end 135.407654 -241.799364)
		(width 0.088646)
		(layer "In11.Cu")
		(net "M_H_CPU1_SB_DQS_DP<4>")
	)
	(segment
		(start 167.136572 -235.472732)
		(end 165.911276 -235.472732)
		(width 0.18288)
		(layer "In11.Cu")
		(net "M_H_CPU1_SB_DQS_DP<4>")
	)
	(segment
		(start 147.57654 -242.322604)
		(end 141.103096 -242.322604)
		(width 0.18288)
		(layer "In11.Cu")
		(net "M_H_CPU1_SB_DQS_DP<4>")
	)
	(segment
		(start 132.61086 -241.81308)
		(end 132.598922 -241.805968)
		(width 0.088646)
		(layer "In11.Cu")
		(net "M_H_CPU1_SB_DQS_DP<4>")
	)
	(segment
		(start 125.676914 -241.902742)
		(end 125.550168 -241.97056)
		(width 0.088646)
		(layer "In11.Cu")
		(net "M_H_CPU1_SB_DQS_DP<4>")
	)
	(segment
		(start 200.716896 -236.257338)
		(end 197.768972 -235.67136)
		(width 0.18288)
		(layer "In11.Cu")
		(net "M_H_CPU1_SB_DQS_DP<4>")
	)
	(segment
		(start 177.099214 -233.44124)
		(end 176.666398 -233.44124)
		(width 0.18288)
		(layer "In11.Cu")
		(net "M_H_CPU1_SB_DQS_DP<4>")
	)
	(arc
		(start 132.973318 -241.805714)
		(mid 132.793031 -241.856126)
		(end 132.61086 -241.81308)
		(width 0.088646)
		(layer "In11.Cu")
		(net "M_H_CPU1_SB_DQS_DP<4>")
	)
	(arc
		(start 134.85241 -241.80546)
		(mid 134.665212 -241.855603)
		(end 134.478014 -241.80546)
		(width 0.088646)
		(layer "In11.Cu")
		(net "M_H_CPU1_SB_DQS_DP<4>")
	)
	(arc
		(start 131.659122 -241.805968)
		(mid 131.376449 -241.729997)
		(end 131.093718 -241.805714)
		(width 0.088646)
		(layer "In11.Cu")
		(net "M_H_CPU1_SB_DQS_DP<4>")
	)
	(arc
		(start 127.899922 -241.805968)
		(mid 127.617249 -241.729997)
		(end 127.334518 -241.805714)
		(width 0.088646)
		(layer "In11.Cu")
		(net "M_H_CPU1_SB_DQS_DP<4>")
	)
	(arc
		(start 133.538214 -241.805714)
		(mid 133.255766 -241.730031)
		(end 132.973318 -241.805714)
		(width 0.088646)
		(layer "In11.Cu")
		(net "M_H_CPU1_SB_DQS_DP<4>")
	)
	(arc
		(start 131.093718 -241.805714)
		(mid 130.913431 -241.856126)
		(end 130.73126 -241.81308)
		(width 0.088646)
		(layer "In11.Cu")
		(net "M_H_CPU1_SB_DQS_DP<4>")
	)
	(arc
		(start 128.274318 -241.805714)
		(mid 128.094031 -241.856126)
		(end 127.91186 -241.81308)
		(width 0.088646)
		(layer "In11.Cu")
		(net "M_H_CPU1_SB_DQS_DP<4>")
	)
	(arc
		(start 129.214118 -241.805714)
		(mid 129.026666 -241.85595)
		(end 128.839214 -241.805714)
		(width 0.088646)
		(layer "In11.Cu")
		(net "M_H_CPU1_SB_DQS_DP<4>")
	)
	(arc
		(start 137.428732 -241.851942)
		(mid 137.361027 -241.834828)
		(end 137.297668 -241.80546)
		(width 0.088646)
		(layer "In11.Cu")
		(net "M_H_CPU1_SB_DQS_DP<4>")
	)
	(arc
		(start 136.357868 -241.80546)
		(mid 136.075166 -241.729684)
		(end 135.792464 -241.80546)
		(width 0.088646)
		(layer "In11.Cu")
		(net "M_H_CPU1_SB_DQS_DP<4>")
	)
	(arc
		(start 135.407654 -241.799364)
		(mid 135.129222 -241.729518)
		(end 134.85241 -241.80546)
		(width 0.088646)
		(layer "In11.Cu")
		(net "M_H_CPU1_SB_DQS_DP<4>")
	)
	(arc
		(start 130.719322 -241.805968)
		(mid 130.436649 -241.729997)
		(end 130.153918 -241.805714)
		(width 0.088646)
		(layer "In11.Cu")
		(net "M_H_CPU1_SB_DQS_DP<4>")
	)
	(arc
		(start 128.839214 -241.805714)
		(mid 128.556766 -241.730031)
		(end 128.274318 -241.805714)
		(width 0.088646)
		(layer "In11.Cu")
		(net "M_H_CPU1_SB_DQS_DP<4>")
	)
	(arc
		(start 129.779522 -241.805968)
		(mid 129.496849 -241.729997)
		(end 129.214118 -241.805714)
		(width 0.088646)
		(layer "In11.Cu")
		(net "M_H_CPU1_SB_DQS_DP<4>")
	)
	(arc
		(start 132.033518 -241.805714)
		(mid 131.853231 -241.856126)
		(end 131.67106 -241.81308)
		(width 0.088646)
		(layer "In11.Cu")
		(net "M_H_CPU1_SB_DQS_DP<4>")
	)
	(arc
		(start 135.792464 -241.80546)
		(mid 135.605266 -241.855603)
		(end 135.418068 -241.80546)
		(width 0.088646)
		(layer "In11.Cu")
		(net "M_H_CPU1_SB_DQS_DP<4>")
	)
	(arc
		(start 130.153918 -241.805714)
		(mid 129.973631 -241.856126)
		(end 129.79146 -241.81308)
		(width 0.088646)
		(layer "In11.Cu")
		(net "M_H_CPU1_SB_DQS_DP<4>")
	)
	(arc
		(start 125.798834 -241.875056)
		(mid 125.786419 -241.875994)
		(end 125.774196 -241.878358)
		(width 0.088646)
		(layer "In11.Cu")
		(net "M_H_CPU1_SB_DQS_DP<4>")
	)
	(arc
		(start 133.913118 -241.805714)
		(mid 133.725666 -241.85595)
		(end 133.538214 -241.805714)
		(width 0.088646)
		(layer "In11.Cu")
		(net "M_H_CPU1_SB_DQS_DP<4>")
	)
	(arc
		(start 137.297668 -241.80546)
		(mid 137.014966 -241.729684)
		(end 136.732264 -241.80546)
		(width 0.088646)
		(layer "In11.Cu")
		(net "M_H_CPU1_SB_DQS_DP<4>")
	)
	(arc
		(start 136.732264 -241.80546)
		(mid 136.545066 -241.855603)
		(end 136.357868 -241.80546)
		(width 0.088646)
		(layer "In11.Cu")
		(net "M_H_CPU1_SB_DQS_DP<4>")
	)
	(arc
		(start 126.944882 -241.796824)
		(mid 126.668407 -241.729504)
		(end 126.39421 -241.80546)
		(width 0.088646)
		(layer "In11.Cu")
		(net "M_H_CPU1_SB_DQS_DP<4>")
	)
	(arc
		(start 125.550168 -241.97056)
		(mid 125.180711 -242.148618)
		(end 124.797566 -242.294918)
		(width 0.088646)
		(layer "In11.Cu")
		(net "M_H_CPU1_SB_DQS_DP<4>")
	)
	(arc
		(start 127.33401 -241.80546)
		(mid 127.146812 -241.855637)
		(end 126.959614 -241.80546)
		(width 0.088646)
		(layer "In11.Cu")
		(net "M_H_CPU1_SB_DQS_DP<4>")
	)
	(arc
		(start 134.4676 -241.799364)
		(mid 134.189422 -241.729641)
		(end 133.912864 -241.80546)
		(width 0.088646)
		(layer "In11.Cu")
		(net "M_H_CPU1_SB_DQS_DP<4>")
	)
	(arc
		(start 137.48512 -241.85626)
		(mid 137.456844 -241.855173)
		(end 137.428732 -241.851942)
		(width 0.088646)
		(layer "In11.Cu")
		(net "M_H_CPU1_SB_DQS_DP<4>")
	)
	(arc
		(start 132.598922 -241.805968)
		(mid 132.316249 -241.729997)
		(end 132.033518 -241.805714)
		(width 0.088646)
		(layer "In11.Cu")
		(net "M_H_CPU1_SB_DQS_DP<4>")
	)
	(segment
		(start 205.920848 -200.890632)
		(end 206.606648 -200.890632)
		(width 0.20066)
		(layer "F.Cu")
		(net "M_H_CPU1_SB_DQS_DP<3>")
	)
	(segment
		(start 206.606648 -200.890632)
		(end 206.857854 -201.141838)
		(width 0.20066)
		(layer "F.Cu")
		(net "M_H_CPU1_SB_DQS_DP<3>")
	)
	(segment
		(start 204.076046 -200.716642)
		(end 204.665326 -200.716642)
		(width 0.20066)
		(layer "F.Cu")
		(net "M_H_CPU1_SB_DQS_DP<3>")
	)
	(segment
		(start 205.50632 -200.476104)
		(end 205.920848 -200.890632)
		(width 0.20066)
		(layer "F.Cu")
		(net "M_H_CPU1_SB_DQS_DP<3>")
	)
	(segment
		(start 206.857854 -201.141838)
		(end 206.9973 -201.141838)
		(width 0.20066)
		(layer "F.Cu")
		(net "M_H_CPU1_SB_DQS_DP<3>")
	)
	(segment
		(start 210.182968 -200.84542)
		(end 210.593432 -200.434956)
		(width 0.20066)
		(layer "F.Cu")
		(net "M_H_CPU1_SB_DQS_DP<3>")
	)
	(segment
		(start 209.18043 -201.141838)
		(end 209.186526 -201.147934)
		(width 0.1016)
		(layer "F.Cu")
		(net "M_H_CPU1_SB_DQS_DP<3>")
	)
	(segment
		(start 123.857766 -228.180646)
		(end 123.857766 -227.64496)
		(width 0.20066)
		(layer "F.Cu")
		(net "M_H_CPU1_SB_DQS_DP<3>")
	)
	(segment
		(start 204.665326 -200.716642)
		(end 204.905864 -200.476104)
		(width 0.20066)
		(layer "F.Cu")
		(net "M_H_CPU1_SB_DQS_DP<3>")
	)
	(segment
		(start 204.905864 -200.476104)
		(end 205.50632 -200.476104)
		(width 0.20066)
		(layer "F.Cu")
		(net "M_H_CPU1_SB_DQS_DP<3>")
	)
	(segment
		(start 211.071206 -200.716642)
		(end 211.619846 -200.716642)
		(width 0.20066)
		(layer "F.Cu")
		(net "M_H_CPU1_SB_DQS_DP<3>")
	)
	(segment
		(start 202.971146 -200.716642)
		(end 204.076046 -200.716642)
		(width 0.20066)
		(layer "F.Cu")
		(net "M_H_CPU1_SB_DQS_DP<3>")
	)
	(segment
		(start 210.78952 -200.434956)
		(end 211.071206 -200.716642)
		(width 0.20066)
		(layer "F.Cu")
		(net "M_H_CPU1_SB_DQS_DP<3>")
	)
	(segment
		(start 209.812382 -200.84542)
		(end 210.182968 -200.84542)
		(width 0.20066)
		(layer "F.Cu")
		(net "M_H_CPU1_SB_DQS_DP<3>")
	)
	(segment
		(start 209.186526 -201.147934)
		(end 209.509868 -201.147934)
		(width 0.20066)
		(layer "F.Cu")
		(net "M_H_CPU1_SB_DQS_DP<3>")
	)
	(segment
		(start 210.593432 -200.434956)
		(end 210.78952 -200.434956)
		(width 0.20066)
		(layer "F.Cu")
		(net "M_H_CPU1_SB_DQS_DP<3>")
	)
	(segment
		(start 206.9973 -201.141838)
		(end 207.023208 -201.141838)
		(width 0.101854)
		(layer "F.Cu")
		(net "M_H_CPU1_SB_DQS_DP<3>")
	)
	(segment
		(start 209.509868 -201.147934)
		(end 209.812382 -200.84542)
		(width 0.20066)
		(layer "F.Cu")
		(net "M_H_CPU1_SB_DQS_DP<3>")
	)
	(segment
		(start 123.857512 -228.1809)
		(end 123.857766 -228.180646)
		(width 0.20066)
		(layer "F.Cu")
		(net "M_H_CPU1_SB_DQS_DP<3>")
	)
	(segment
		(start 207.023208 -201.141838)
		(end 209.18043 -201.141838)
		(width 0.1016)
		(layer "F.Cu")
		(net "M_H_CPU1_SB_DQS_DP<3>")
	)
	(segment
		(start 185.93435 -200.121012)
		(end 185.556906 -200.498456)
		(width 0.18288)
		(layer "In11.Cu")
		(net "M_H_CPU1_SB_DQS_DP<3>")
	)
	(segment
		(start 140.818108 -221.941136)
		(end 140.654786 -222.104458)
		(width 0.088646)
		(layer "In11.Cu")
		(net "M_H_CPU1_SB_DQS_DP<3>")
	)
	(segment
		(start 181.696614 -199.781668)
		(end 181.572154 -199.906128)
		(width 0.18288)
		(layer "In11.Cu")
		(net "M_H_CPU1_SB_DQS_DP<3>")
	)
	(segment
		(start 181.023514 -199.906128)
		(end 180.899054 -199.781668)
		(width 0.18288)
		(layer "In11.Cu")
		(net "M_H_CPU1_SB_DQS_DP<3>")
	)
	(segment
		(start 162.392106 -200.28281)
		(end 161.51733 -200.28281)
		(width 0.18288)
		(layer "In11.Cu")
		(net "M_H_CPU1_SB_DQS_DP<3>")
	)
	(segment
		(start 181.572154 -199.906128)
		(end 181.023514 -199.906128)
		(width 0.18288)
		(layer "In11.Cu")
		(net "M_H_CPU1_SB_DQS_DP<3>")
	)
	(segment
		(start 160.71088 -201.08926)
		(end 157.25648 -201.08926)
		(width 0.18288)
		(layer "In11.Cu")
		(net "M_H_CPU1_SB_DQS_DP<3>")
	)
	(segment
		(start 172.22597 -199.16521)
		(end 171.55541 -199.16521)
		(width 0.18288)
		(layer "In11.Cu")
		(net "M_H_CPU1_SB_DQS_DP<3>")
	)
	(segment
		(start 174.526448 -198.320152)
		(end 173.670214 -199.176386)
		(width 0.18288)
		(layer "In11.Cu")
		(net "M_H_CPU1_SB_DQS_DP<3>")
	)
	(segment
		(start 185.93435 -199.384666)
		(end 185.93435 -200.121012)
		(width 0.18288)
		(layer "In11.Cu")
		(net "M_H_CPU1_SB_DQS_DP<3>")
	)
	(segment
		(start 202.205336 -200.441306)
		(end 201.8411 -200.07707)
		(width 0.18288)
		(layer "In11.Cu")
		(net "M_H_CPU1_SB_DQS_DP<3>")
	)
	(segment
		(start 184.404762 -199.188578)
		(end 183.495442 -199.188578)
		(width 0.18288)
		(layer "In11.Cu")
		(net "M_H_CPU1_SB_DQS_DP<3>")
	)
	(segment
		(start 188.111384 -199.441308)
		(end 187.589668 -199.441308)
		(width 0.18288)
		(layer "In11.Cu")
		(net "M_H_CPU1_SB_DQS_DP<3>")
	)
	(segment
		(start 178.943762 -199.280272)
		(end 178.55565 -198.89216)
		(width 0.18288)
		(layer "In11.Cu")
		(net "M_H_CPU1_SB_DQS_DP<3>")
	)
	(segment
		(start 127.429514 -227.320602)
		(end 127.4191 -227.326698)
		(width 0.088646)
		(layer "In11.Cu")
		(net "M_H_CPU1_SB_DQS_DP<3>")
	)
	(segment
		(start 125.939296 -227.329238)
		(end 125.924564 -227.320602)
		(width 0.088646)
		(layer "In11.Cu")
		(net "M_H_CPU1_SB_DQS_DP<3>")
	)
	(segment
		(start 187.336938 -199.188578)
		(end 186.130438 -199.188578)
		(width 0.18288)
		(layer "In11.Cu")
		(net "M_H_CPU1_SB_DQS_DP<3>")
	)
	(segment
		(start 172.504608 -199.443848)
		(end 172.22597 -199.16521)
		(width 0.18288)
		(layer "In11.Cu")
		(net "M_H_CPU1_SB_DQS_DP<3>")
	)
	(segment
		(start 192.211706 -198.59117)
		(end 191.689482 -198.59117)
		(width 0.18288)
		(layer "In11.Cu")
		(net "M_H_CPU1_SB_DQS_DP<3>")
	)
	(segment
		(start 202.971146 -200.716642)
		(end 202.69581 -200.441306)
		(width 0.18288)
		(layer "In11.Cu")
		(net "M_H_CPU1_SB_DQS_DP<3>")
	)
	(segment
		(start 170.75785 -199.16521)
		(end 170.20921 -199.16521)
		(width 0.18288)
		(layer "In11.Cu")
		(net "M_H_CPU1_SB_DQS_DP<3>")
	)
	(segment
		(start 139.49807 -224.546668)
		(end 139.49807 -224.929446)
		(width 0.088646)
		(layer "In11.Cu")
		(net "M_H_CPU1_SB_DQS_DP<3>")
	)
	(segment
		(start 182.902352 -199.781668)
		(end 181.696614 -199.781668)
		(width 0.18288)
		(layer "In11.Cu")
		(net "M_H_CPU1_SB_DQS_DP<3>")
	)
	(segment
		(start 155.414726 -202.931014)
		(end 155.414726 -204.565504)
		(width 0.18288)
		(layer "In11.Cu")
		(net "M_H_CPU1_SB_DQS_DP<3>")
	)
	(segment
		(start 131.578096 -227.329238)
		(end 131.563364 -227.320602)
		(width 0.088646)
		(layer "In11.Cu")
		(net "M_H_CPU1_SB_DQS_DP<3>")
	)
	(segment
		(start 169.09161 -200.28281)
		(end 163.189666 -200.28281)
		(width 0.18288)
		(layer "In11.Cu")
		(net "M_H_CPU1_SB_DQS_DP<3>")
	)
	(segment
		(start 138.707368 -225.69297)
		(end 138.698478 -225.69805)
		(width 0.088646)
		(layer "In11.Cu")
		(net "M_H_CPU1_SB_DQS_DP<3>")
	)
	(segment
		(start 179.119784 -199.280272)
		(end 178.943762 -199.280272)
		(width 0.18288)
		(layer "In11.Cu")
		(net "M_H_CPU1_SB_DQS_DP<3>")
	)
	(segment
		(start 188.376306 -199.176386)
		(end 188.111384 -199.441308)
		(width 0.18288)
		(layer "In11.Cu")
		(net "M_H_CPU1_SB_DQS_DP<3>")
	)
	(segment
		(start 177.386996 -198.32828)
		(end 177.124106 -198.59117)
		(width 0.18288)
		(layer "In11.Cu")
		(net "M_H_CPU1_SB_DQS_DP<3>")
	)
	(segment
		(start 132.517896 -227.329238)
		(end 132.503164 -227.320602)
		(width 0.088646)
		(layer "In11.Cu")
		(net "M_H_CPU1_SB_DQS_DP<3>")
	)
	(segment
		(start 161.51733 -200.28281)
		(end 160.71088 -201.08926)
		(width 0.18288)
		(layer "In11.Cu")
		(net "M_H_CPU1_SB_DQS_DP<3>")
	)
	(segment
		(start 179.62118 -199.781668)
		(end 179.119784 -199.280272)
		(width 0.18288)
		(layer "In11.Cu")
		(net "M_H_CPU1_SB_DQS_DP<3>")
	)
	(segment
		(start 176.601882 -198.59117)
		(end 176.330864 -198.320152)
		(width 0.18288)
		(layer "In11.Cu")
		(net "M_H_CPU1_SB_DQS_DP<3>")
	)
	(segment
		(start 184.60085 -199.384666)
		(end 184.404762 -199.188578)
		(width 0.18288)
		(layer "In11.Cu")
		(net "M_H_CPU1_SB_DQS_DP<3>")
	)
	(segment
		(start 184.60085 -200.121012)
		(end 184.60085 -199.384666)
		(width 0.18288)
		(layer "In11.Cu")
		(net "M_H_CPU1_SB_DQS_DP<3>")
	)
	(segment
		(start 202.69581 -200.441306)
		(end 202.205336 -200.441306)
		(width 0.18288)
		(layer "In11.Cu")
		(net "M_H_CPU1_SB_DQS_DP<3>")
	)
	(segment
		(start 147.187158 -212.793072)
		(end 147.187158 -215.656922)
		(width 0.18288)
		(layer "In11.Cu")
		(net "M_H_CPU1_SB_DQS_DP<3>")
	)
	(segment
		(start 171.55541 -199.16521)
		(end 171.43095 -199.28967)
		(width 0.18288)
		(layer "In11.Cu")
		(net "M_H_CPU1_SB_DQS_DP<3>")
	)
	(segment
		(start 173.288706 -199.176386)
		(end 173.021244 -199.443848)
		(width 0.18288)
		(layer "In11.Cu")
		(net "M_H_CPU1_SB_DQS_DP<3>")
	)
	(segment
		(start 123.545092 -227.64496)
		(end 123.857766 -227.64496)
		(width 0.088646)
		(layer "In11.Cu")
		(net "M_H_CPU1_SB_DQS_DP<3>")
	)
	(segment
		(start 180.899054 -199.781668)
		(end 179.62118 -199.781668)
		(width 0.18288)
		(layer "In11.Cu")
		(net "M_H_CPU1_SB_DQS_DP<3>")
	)
	(segment
		(start 147.187158 -215.656922)
		(end 140.902944 -221.941136)
		(width 0.18288)
		(layer "In11.Cu")
		(net "M_H_CPU1_SB_DQS_DP<3>")
	)
	(segment
		(start 128.369314 -227.320602)
		(end 128.354582 -227.329238)
		(width 0.088646)
		(layer "In11.Cu")
		(net "M_H_CPU1_SB_DQS_DP<3>")
	)
	(segment
		(start 163.065206 -200.40727)
		(end 162.516566 -200.40727)
		(width 0.18288)
		(layer "In11.Cu")
		(net "M_H_CPU1_SB_DQS_DP<3>")
	)
	(segment
		(start 178.55565 -198.89216)
		(end 178.55565 -198.716138)
		(width 0.18288)
		(layer "In11.Cu")
		(net "M_H_CPU1_SB_DQS_DP<3>")
	)
	(segment
		(start 192.476374 -198.326502)
		(end 192.211706 -198.59117)
		(width 0.18288)
		(layer "In11.Cu")
		(net "M_H_CPU1_SB_DQS_DP<3>")
	)
	(segment
		(start 176.330864 -198.320152)
		(end 174.526448 -198.320152)
		(width 0.18288)
		(layer "In11.Cu")
		(net "M_H_CPU1_SB_DQS_DP<3>")
	)
	(segment
		(start 194.801744 -200.07707)
		(end 193.051176 -198.326502)
		(width 0.18288)
		(layer "In11.Cu")
		(net "M_H_CPU1_SB_DQS_DP<3>")
	)
	(segment
		(start 140.902944 -221.941136)
		(end 140.818108 -221.941136)
		(width 0.088646)
		(layer "In11.Cu")
		(net "M_H_CPU1_SB_DQS_DP<3>")
	)
	(segment
		(start 123.670568 -227.320602)
		(end 123.661678 -227.325682)
		(width 0.088646)
		(layer "In11.Cu")
		(net "M_H_CPU1_SB_DQS_DP<3>")
	)
	(segment
		(start 140.654786 -222.104458)
		(end 140.654786 -223.389952)
		(width 0.088646)
		(layer "In11.Cu")
		(net "M_H_CPU1_SB_DQS_DP<3>")
	)
	(segment
		(start 178.55565 -198.716138)
		(end 178.167792 -198.32828)
		(width 0.18288)
		(layer "In11.Cu")
		(net "M_H_CPU1_SB_DQS_DP<3>")
	)
	(segment
		(start 162.516566 -200.40727)
		(end 162.392106 -200.28281)
		(width 0.18288)
		(layer "In11.Cu")
		(net "M_H_CPU1_SB_DQS_DP<3>")
	)
	(segment
		(start 183.495442 -199.188578)
		(end 182.902352 -199.781668)
		(width 0.18288)
		(layer "In11.Cu")
		(net "M_H_CPU1_SB_DQS_DP<3>")
	)
	(segment
		(start 189.314836 -199.176386)
		(end 188.376306 -199.176386)
		(width 0.18288)
		(layer "In11.Cu")
		(net "M_H_CPU1_SB_DQS_DP<3>")
	)
	(segment
		(start 139.49807 -224.929446)
		(end 138.824208 -225.603308)
		(width 0.088646)
		(layer "In11.Cu")
		(net "M_H_CPU1_SB_DQS_DP<3>")
	)
	(segment
		(start 128.754124 -227.326698)
		(end 128.74371 -227.320602)
		(width 0.088646)
		(layer "In11.Cu")
		(net "M_H_CPU1_SB_DQS_DP<3>")
	)
	(segment
		(start 191.689482 -198.59117)
		(end 191.438276 -198.339964)
		(width 0.18288)
		(layer "In11.Cu")
		(net "M_H_CPU1_SB_DQS_DP<3>")
	)
	(segment
		(start 163.189666 -200.28281)
		(end 163.065206 -200.40727)
		(width 0.18288)
		(layer "In11.Cu")
		(net "M_H_CPU1_SB_DQS_DP<3>")
	)
	(segment
		(start 136.357868 -226.506786)
		(end 136.348978 -226.511866)
		(width 0.088646)
		(layer "In11.Cu")
		(net "M_H_CPU1_SB_DQS_DP<3>")
	)
	(segment
		(start 124.999496 -227.329238)
		(end 124.984764 -227.320602)
		(width 0.088646)
		(layer "In11.Cu")
		(net "M_H_CPU1_SB_DQS_DP<3>")
	)
	(segment
		(start 173.021244 -199.443848)
		(end 172.504608 -199.443848)
		(width 0.18288)
		(layer "In11.Cu")
		(net "M_H_CPU1_SB_DQS_DP<3>")
	)
	(segment
		(start 138.519916 -226.017328)
		(end 138.519916 -226.027234)
		(width 0.088646)
		(layer "In11.Cu")
		(net "M_H_CPU1_SB_DQS_DP<3>")
	)
	(segment
		(start 201.8411 -200.07707)
		(end 194.801744 -200.07707)
		(width 0.18288)
		(layer "In11.Cu")
		(net "M_H_CPU1_SB_DQS_DP<3>")
	)
	(segment
		(start 173.670214 -199.176386)
		(end 173.288706 -199.176386)
		(width 0.18288)
		(layer "In11.Cu")
		(net "M_H_CPU1_SB_DQS_DP<3>")
	)
	(segment
		(start 184.978294 -200.498456)
		(end 184.60085 -200.121012)
		(width 0.18288)
		(layer "In11.Cu")
		(net "M_H_CPU1_SB_DQS_DP<3>")
	)
	(segment
		(start 193.051176 -198.326502)
		(end 192.476374 -198.326502)
		(width 0.18288)
		(layer "In11.Cu")
		(net "M_H_CPU1_SB_DQS_DP<3>")
	)
	(segment
		(start 134.397496 -227.329238)
		(end 134.382764 -227.320602)
		(width 0.088646)
		(layer "In11.Cu")
		(net "M_H_CPU1_SB_DQS_DP<3>")
	)
	(segment
		(start 123.487688 -227.587556)
		(end 123.545092 -227.64496)
		(width 0.088646)
		(layer "In11.Cu")
		(net "M_H_CPU1_SB_DQS_DP<3>")
	)
	(segment
		(start 177.124106 -198.59117)
		(end 176.601882 -198.59117)
		(width 0.18288)
		(layer "In11.Cu")
		(net "M_H_CPU1_SB_DQS_DP<3>")
	)
	(segment
		(start 191.438276 -198.339964)
		(end 190.151258 -198.339964)
		(width 0.18288)
		(layer "In11.Cu")
		(net "M_H_CPU1_SB_DQS_DP<3>")
	)
	(segment
		(start 170.20921 -199.16521)
		(end 169.09161 -200.28281)
		(width 0.18288)
		(layer "In11.Cu")
		(net "M_H_CPU1_SB_DQS_DP<3>")
	)
	(segment
		(start 186.130438 -199.188578)
		(end 185.93435 -199.384666)
		(width 0.18288)
		(layer "In11.Cu")
		(net "M_H_CPU1_SB_DQS_DP<3>")
	)
	(segment
		(start 178.167792 -198.32828)
		(end 177.386996 -198.32828)
		(width 0.18288)
		(layer "In11.Cu")
		(net "M_H_CPU1_SB_DQS_DP<3>")
	)
	(segment
		(start 157.25648 -201.08926)
		(end 155.414726 -202.931014)
		(width 0.18288)
		(layer "In11.Cu")
		(net "M_H_CPU1_SB_DQS_DP<3>")
	)
	(segment
		(start 187.589668 -199.441308)
		(end 187.336938 -199.188578)
		(width 0.18288)
		(layer "In11.Cu")
		(net "M_H_CPU1_SB_DQS_DP<3>")
	)
	(segment
		(start 136.170416 -226.831144)
		(end 136.170416 -226.84105)
		(width 0.088646)
		(layer "In11.Cu")
		(net "M_H_CPU1_SB_DQS_DP<3>")
	)
	(segment
		(start 185.556906 -200.498456)
		(end 184.978294 -200.498456)
		(width 0.18288)
		(layer "In11.Cu")
		(net "M_H_CPU1_SB_DQS_DP<3>")
	)
	(segment
		(start 129.698496 -227.329238)
		(end 129.683764 -227.320602)
		(width 0.088646)
		(layer "In11.Cu")
		(net "M_H_CPU1_SB_DQS_DP<3>")
	)
	(segment
		(start 140.654786 -223.389952)
		(end 139.49807 -224.546668)
		(width 0.088646)
		(layer "In11.Cu")
		(net "M_H_CPU1_SB_DQS_DP<3>")
	)
	(segment
		(start 170.88231 -199.28967)
		(end 170.75785 -199.16521)
		(width 0.18288)
		(layer "In11.Cu")
		(net "M_H_CPU1_SB_DQS_DP<3>")
	)
	(segment
		(start 190.151258 -198.339964)
		(end 189.314836 -199.176386)
		(width 0.18288)
		(layer "In11.Cu")
		(net "M_H_CPU1_SB_DQS_DP<3>")
	)
	(segment
		(start 155.414726 -204.565504)
		(end 147.187158 -212.793072)
		(width 0.18288)
		(layer "In11.Cu")
		(net "M_H_CPU1_SB_DQS_DP<3>")
	)
	(segment
		(start 171.43095 -199.28967)
		(end 170.88231 -199.28967)
		(width 0.18288)
		(layer "In11.Cu")
		(net "M_H_CPU1_SB_DQS_DP<3>")
	)
	(arc
		(start 133.068568 -227.320602)
		(mid 132.794369 -227.396437)
		(end 132.517896 -227.329238)
		(width 0.088646)
		(layer "In11.Cu")
		(net "M_H_CPU1_SB_DQS_DP<3>")
	)
	(arc
		(start 136.170416 -226.84105)
		(mid 136.092305 -227.117999)
		(end 135.887968 -227.320602)
		(width 0.088646)
		(layer "In11.Cu")
		(net "M_H_CPU1_SB_DQS_DP<3>")
	)
	(arc
		(start 124.044964 -227.320602)
		(mid 123.857766 -227.270459)
		(end 123.670568 -227.320602)
		(width 0.088646)
		(layer "In11.Cu")
		(net "M_H_CPU1_SB_DQS_DP<3>")
	)
	(arc
		(start 131.188968 -227.320602)
		(mid 130.906266 -227.396378)
		(end 130.623564 -227.320602)
		(width 0.088646)
		(layer "In11.Cu")
		(net "M_H_CPU1_SB_DQS_DP<3>")
	)
	(arc
		(start 130.623564 -227.320602)
		(mid 130.436366 -227.270459)
		(end 130.249168 -227.320602)
		(width 0.088646)
		(layer "In11.Cu")
		(net "M_H_CPU1_SB_DQS_DP<3>")
	)
	(arc
		(start 132.128768 -227.320602)
		(mid 131.854569 -227.396437)
		(end 131.578096 -227.329238)
		(width 0.088646)
		(layer "In11.Cu")
		(net "M_H_CPU1_SB_DQS_DP<3>")
	)
	(arc
		(start 127.4191 -227.326698)
		(mid 127.140922 -227.396421)
		(end 126.864364 -227.320602)
		(width 0.088646)
		(layer "In11.Cu")
		(net "M_H_CPU1_SB_DQS_DP<3>")
	)
	(arc
		(start 134.008368 -227.320602)
		(mid 133.725666 -227.396378)
		(end 133.442964 -227.320602)
		(width 0.088646)
		(layer "In11.Cu")
		(net "M_H_CPU1_SB_DQS_DP<3>")
	)
	(arc
		(start 126.489968 -227.320602)
		(mid 126.215769 -227.396437)
		(end 125.939296 -227.329238)
		(width 0.088646)
		(layer "In11.Cu")
		(net "M_H_CPU1_SB_DQS_DP<3>")
	)
	(arc
		(start 133.442964 -227.320602)
		(mid 133.255766 -227.270459)
		(end 133.068568 -227.320602)
		(width 0.088646)
		(layer "In11.Cu")
		(net "M_H_CPU1_SB_DQS_DP<3>")
	)
	(arc
		(start 136.348978 -226.511866)
		(mid 136.218064 -226.648226)
		(end 136.170416 -226.831144)
		(width 0.088646)
		(layer "In11.Cu")
		(net "M_H_CPU1_SB_DQS_DP<3>")
	)
	(arc
		(start 128.74371 -227.320602)
		(mid 128.556512 -227.270459)
		(end 128.369314 -227.320602)
		(width 0.088646)
		(layer "In11.Cu")
		(net "M_H_CPU1_SB_DQS_DP<3>")
	)
	(arc
		(start 134.382764 -227.320602)
		(mid 134.195566 -227.270459)
		(end 134.008368 -227.320602)
		(width 0.088646)
		(layer "In11.Cu")
		(net "M_H_CPU1_SB_DQS_DP<3>")
	)
	(arc
		(start 135.322564 -227.320602)
		(mid 135.135366 -227.270459)
		(end 134.948168 -227.320602)
		(width 0.088646)
		(layer "In11.Cu")
		(net "M_H_CPU1_SB_DQS_DP<3>")
	)
	(arc
		(start 129.683764 -227.320602)
		(mid 129.496566 -227.270459)
		(end 129.309368 -227.320602)
		(width 0.088646)
		(layer "In11.Cu")
		(net "M_H_CPU1_SB_DQS_DP<3>")
	)
	(arc
		(start 129.309368 -227.320602)
		(mid 129.032555 -227.396472)
		(end 128.754124 -227.326698)
		(width 0.088646)
		(layer "In11.Cu")
		(net "M_H_CPU1_SB_DQS_DP<3>")
	)
	(arc
		(start 136.732264 -226.506786)
		(mid 136.545066 -226.456643)
		(end 136.357868 -226.506786)
		(width 0.088646)
		(layer "In11.Cu")
		(net "M_H_CPU1_SB_DQS_DP<3>")
	)
	(arc
		(start 130.249168 -227.320602)
		(mid 129.974969 -227.396437)
		(end 129.698496 -227.329238)
		(width 0.088646)
		(layer "In11.Cu")
		(net "M_H_CPU1_SB_DQS_DP<3>")
	)
	(arc
		(start 126.864364 -227.320602)
		(mid 126.677166 -227.270459)
		(end 126.489968 -227.320602)
		(width 0.088646)
		(layer "In11.Cu")
		(net "M_H_CPU1_SB_DQS_DP<3>")
	)
	(arc
		(start 138.698478 -225.69805)
		(mid 138.567564 -225.83441)
		(end 138.519916 -226.017328)
		(width 0.088646)
		(layer "In11.Cu")
		(net "M_H_CPU1_SB_DQS_DP<3>")
	)
	(arc
		(start 135.887968 -227.320602)
		(mid 135.605266 -227.396378)
		(end 135.322564 -227.320602)
		(width 0.088646)
		(layer "In11.Cu")
		(net "M_H_CPU1_SB_DQS_DP<3>")
	)
	(arc
		(start 125.550168 -227.320602)
		(mid 125.275969 -227.396437)
		(end 124.999496 -227.329238)
		(width 0.088646)
		(layer "In11.Cu")
		(net "M_H_CPU1_SB_DQS_DP<3>")
	)
	(arc
		(start 138.824208 -225.603308)
		(mid 138.768718 -225.651957)
		(end 138.707368 -225.69297)
		(width 0.088646)
		(layer "In11.Cu")
		(net "M_H_CPU1_SB_DQS_DP<3>")
	)
	(arc
		(start 131.563364 -227.320602)
		(mid 131.376166 -227.270459)
		(end 131.188968 -227.320602)
		(width 0.088646)
		(layer "In11.Cu")
		(net "M_H_CPU1_SB_DQS_DP<3>")
	)
	(arc
		(start 128.354582 -227.329238)
		(mid 128.078107 -227.396558)
		(end 127.80391 -227.320602)
		(width 0.088646)
		(layer "In11.Cu")
		(net "M_H_CPU1_SB_DQS_DP<3>")
	)
	(arc
		(start 123.661678 -227.325682)
		(mid 123.545939 -227.437506)
		(end 123.487688 -227.587556)
		(width 0.088646)
		(layer "In11.Cu")
		(net "M_H_CPU1_SB_DQS_DP<3>")
	)
	(arc
		(start 134.948168 -227.320602)
		(mid 134.673969 -227.396437)
		(end 134.397496 -227.329238)
		(width 0.088646)
		(layer "In11.Cu")
		(net "M_H_CPU1_SB_DQS_DP<3>")
	)
	(arc
		(start 124.610368 -227.320602)
		(mid 124.327666 -227.396378)
		(end 124.044964 -227.320602)
		(width 0.088646)
		(layer "In11.Cu")
		(net "M_H_CPU1_SB_DQS_DP<3>")
	)
	(arc
		(start 138.519916 -226.027234)
		(mid 138.441805 -226.304183)
		(end 138.237468 -226.506786)
		(width 0.088646)
		(layer "In11.Cu")
		(net "M_H_CPU1_SB_DQS_DP<3>")
	)
	(arc
		(start 138.237468 -226.506786)
		(mid 137.954766 -226.582562)
		(end 137.672064 -226.506786)
		(width 0.088646)
		(layer "In11.Cu")
		(net "M_H_CPU1_SB_DQS_DP<3>")
	)
	(arc
		(start 124.984764 -227.320602)
		(mid 124.797566 -227.270459)
		(end 124.610368 -227.320602)
		(width 0.088646)
		(layer "In11.Cu")
		(net "M_H_CPU1_SB_DQS_DP<3>")
	)
	(arc
		(start 137.297668 -226.506786)
		(mid 137.014966 -226.582562)
		(end 136.732264 -226.506786)
		(width 0.088646)
		(layer "In11.Cu")
		(net "M_H_CPU1_SB_DQS_DP<3>")
	)
	(arc
		(start 127.80391 -227.320602)
		(mid 127.616712 -227.270459)
		(end 127.429514 -227.320602)
		(width 0.088646)
		(layer "In11.Cu")
		(net "M_H_CPU1_SB_DQS_DP<3>")
	)
	(arc
		(start 125.924564 -227.320602)
		(mid 125.737366 -227.270459)
		(end 125.550168 -227.320602)
		(width 0.088646)
		(layer "In11.Cu")
		(net "M_H_CPU1_SB_DQS_DP<3>")
	)
	(arc
		(start 137.672064 -226.506786)
		(mid 137.484866 -226.456643)
		(end 137.297668 -226.506786)
		(width 0.088646)
		(layer "In11.Cu")
		(net "M_H_CPU1_SB_DQS_DP<3>")
	)
	(arc
		(start 132.503164 -227.320602)
		(mid 132.315966 -227.270459)
		(end 132.128768 -227.320602)
		(width 0.088646)
		(layer "In11.Cu")
		(net "M_H_CPU1_SB_DQS_DP<3>")
	)
	(segment
		(start 204.076046 -210.066636)
		(end 204.665326 -210.066636)
		(width 0.20066)
		(layer "F.Cu")
		(net "M_H_CPU1_SB_DQS_DP<2>")
	)
	(segment
		(start 210.593432 -209.78495)
		(end 210.78952 -209.78495)
		(width 0.20066)
		(layer "F.Cu")
		(net "M_H_CPU1_SB_DQS_DP<2>")
	)
	(segment
		(start 206.606648 -210.240626)
		(end 206.857854 -210.491832)
		(width 0.20066)
		(layer "F.Cu")
		(net "M_H_CPU1_SB_DQS_DP<2>")
	)
	(segment
		(start 204.905864 -209.826098)
		(end 205.50632 -209.826098)
		(width 0.20066)
		(layer "F.Cu")
		(net "M_H_CPU1_SB_DQS_DP<2>")
	)
	(segment
		(start 209.186526 -210.497928)
		(end 209.509868 -210.497928)
		(width 0.20066)
		(layer "F.Cu")
		(net "M_H_CPU1_SB_DQS_DP<2>")
	)
	(segment
		(start 205.920848 -210.240626)
		(end 206.606648 -210.240626)
		(width 0.20066)
		(layer "F.Cu")
		(net "M_H_CPU1_SB_DQS_DP<2>")
	)
	(segment
		(start 205.50632 -209.826098)
		(end 205.920848 -210.240626)
		(width 0.20066)
		(layer "F.Cu")
		(net "M_H_CPU1_SB_DQS_DP<2>")
	)
	(segment
		(start 210.78952 -209.78495)
		(end 211.071206 -210.066636)
		(width 0.20066)
		(layer "F.Cu")
		(net "M_H_CPU1_SB_DQS_DP<2>")
	)
	(segment
		(start 126.207012 -230.622348)
		(end 126.207012 -230.086662)
		(width 0.20066)
		(layer "F.Cu")
		(net "M_H_CPU1_SB_DQS_DP<2>")
	)
	(segment
		(start 126.207266 -230.622602)
		(end 126.207012 -230.622348)
		(width 0.20066)
		(layer "F.Cu")
		(net "M_H_CPU1_SB_DQS_DP<2>")
	)
	(segment
		(start 207.023208 -210.491832)
		(end 209.18043 -210.491832)
		(width 0.1016)
		(layer "F.Cu")
		(net "M_H_CPU1_SB_DQS_DP<2>")
	)
	(segment
		(start 209.812382 -210.195414)
		(end 210.182968 -210.195414)
		(width 0.20066)
		(layer "F.Cu")
		(net "M_H_CPU1_SB_DQS_DP<2>")
	)
	(segment
		(start 211.071206 -210.066636)
		(end 211.619846 -210.066636)
		(width 0.20066)
		(layer "F.Cu")
		(net "M_H_CPU1_SB_DQS_DP<2>")
	)
	(segment
		(start 209.509868 -210.497928)
		(end 209.812382 -210.195414)
		(width 0.20066)
		(layer "F.Cu")
		(net "M_H_CPU1_SB_DQS_DP<2>")
	)
	(segment
		(start 204.665326 -210.066636)
		(end 204.905864 -209.826098)
		(width 0.20066)
		(layer "F.Cu")
		(net "M_H_CPU1_SB_DQS_DP<2>")
	)
	(segment
		(start 206.9973 -210.491832)
		(end 207.023208 -210.491832)
		(width 0.101854)
		(layer "F.Cu")
		(net "M_H_CPU1_SB_DQS_DP<2>")
	)
	(segment
		(start 209.18043 -210.491832)
		(end 209.186526 -210.497928)
		(width 0.1016)
		(layer "F.Cu")
		(net "M_H_CPU1_SB_DQS_DP<2>")
	)
	(segment
		(start 210.182968 -210.195414)
		(end 210.593432 -209.78495)
		(width 0.20066)
		(layer "F.Cu")
		(net "M_H_CPU1_SB_DQS_DP<2>")
	)
	(segment
		(start 202.971146 -210.066636)
		(end 204.076046 -210.066636)
		(width 0.20066)
		(layer "F.Cu")
		(net "M_H_CPU1_SB_DQS_DP<2>")
	)
	(segment
		(start 206.857854 -210.491832)
		(end 206.9973 -210.491832)
		(width 0.20066)
		(layer "F.Cu")
		(net "M_H_CPU1_SB_DQS_DP<2>")
	)
	(segment
		(start 191.550798 -210.230466)
		(end 189.734952 -210.230466)
		(width 0.18288)
		(layer "In6.Cu")
		(net "M_H_CPU1_SB_DQS_DP<2>")
	)
	(segment
		(start 126.585472 -230.152194)
		(end 126.51994 -230.086662)
		(width 0.088646)
		(layer "In6.Cu")
		(net "M_H_CPU1_SB_DQS_DP<2>")
	)
	(segment
		(start 177.35931 -211.914994)
		(end 177.083212 -212.191092)
		(width 0.18288)
		(layer "In6.Cu")
		(net "M_H_CPU1_SB_DQS_DP<2>")
	)
	(segment
		(start 130.71729 -229.763066)
		(end 130.709924 -229.767384)
		(width 0.088646)
		(layer "In6.Cu")
		(net "M_H_CPU1_SB_DQS_DP<2>")
	)
	(segment
		(start 192.878964 -210.230466)
		(end 192.418462 -210.230466)
		(width 0.18288)
		(layer "In6.Cu")
		(net "M_H_CPU1_SB_DQS_DP<2>")
	)
	(segment
		(start 184.530238 -211.071968)
		(end 182.8927 -210.393788)
		(width 0.18288)
		(layer "In6.Cu")
		(net "M_H_CPU1_SB_DQS_DP<2>")
	)
	(segment
		(start 133.538468 -229.762304)
		(end 133.528054 -229.7684)
		(width 0.088646)
		(layer "In6.Cu")
		(net "M_H_CPU1_SB_DQS_DP<2>")
	)
	(segment
		(start 177.669952 -211.914994)
		(end 177.35931 -211.914994)
		(width 0.18288)
		(layer "In6.Cu")
		(net "M_H_CPU1_SB_DQS_DP<2>")
	)
	(segment
		(start 178.7525 -210.832446)
		(end 177.669952 -211.914994)
		(width 0.18288)
		(layer "In6.Cu")
		(net "M_H_CPU1_SB_DQS_DP<2>")
	)
	(segment
		(start 139.250674 -227.782882)
		(end 139.19073 -227.722938)
		(width 0.088646)
		(layer "In6.Cu")
		(net "M_H_CPU1_SB_DQS_DP<2>")
	)
	(segment
		(start 172.350176 -212.779102)
		(end 171.517818 -212.779102)
		(width 0.18288)
		(layer "In6.Cu")
		(net "M_H_CPU1_SB_DQS_DP<2>")
	)
	(segment
		(start 171.517818 -212.779102)
		(end 169.695622 -210.956906)
		(width 0.18288)
		(layer "In6.Cu")
		(net "M_H_CPU1_SB_DQS_DP<2>")
	)
	(segment
		(start 156.279088 -212.024976)
		(end 140.521182 -227.782882)
		(width 0.18288)
		(layer "In6.Cu")
		(net "M_H_CPU1_SB_DQS_DP<2>")
	)
	(segment
		(start 193.648584 -209.460846)
		(end 192.878964 -210.230466)
		(width 0.18288)
		(layer "In6.Cu")
		(net "M_H_CPU1_SB_DQS_DP<2>")
	)
	(segment
		(start 126.879096 -230.584756)
		(end 126.864364 -230.57612)
		(width 0.088646)
		(layer "In6.Cu")
		(net "M_H_CPU1_SB_DQS_DP<2>")
	)
	(segment
		(start 156.279088 -211.743036)
		(end 156.279088 -212.024976)
		(width 0.18288)
		(layer "In6.Cu")
		(net "M_H_CPU1_SB_DQS_DP<2>")
	)
	(segment
		(start 176.711864 -212.191092)
		(end 176.441862 -211.92109)
		(width 0.18288)
		(layer "In6.Cu")
		(net "M_H_CPU1_SB_DQS_DP<2>")
	)
	(segment
		(start 138.36269 -229.111302)
		(end 137.762488 -229.711504)
		(width 0.088646)
		(layer "In6.Cu")
		(net "M_H_CPU1_SB_DQS_DP<2>")
	)
	(segment
		(start 192.158112 -210.490816)
		(end 191.811148 -210.490816)
		(width 0.18288)
		(layer "In6.Cu")
		(net "M_H_CPU1_SB_DQS_DP<2>")
	)
	(segment
		(start 201.853546 -209.447892)
		(end 199.38238 -209.447892)
		(width 0.18288)
		(layer "In6.Cu")
		(net "M_H_CPU1_SB_DQS_DP<2>")
	)
	(segment
		(start 199.38238 -209.447892)
		(end 197.68312 -210.151726)
		(width 0.18288)
		(layer "In6.Cu")
		(net "M_H_CPU1_SB_DQS_DP<2>")
	)
	(segment
		(start 179.88661 -210.393788)
		(end 179.447952 -210.832446)
		(width 0.18288)
		(layer "In6.Cu")
		(net "M_H_CPU1_SB_DQS_DP<2>")
	)
	(segment
		(start 140.521182 -227.782882)
		(end 139.274042 -227.782882)
		(width 0.18288)
		(layer "In6.Cu")
		(net "M_H_CPU1_SB_DQS_DP<2>")
	)
	(segment
		(start 179.447952 -210.832446)
		(end 178.7525 -210.832446)
		(width 0.18288)
		(layer "In6.Cu")
		(net "M_H_CPU1_SB_DQS_DP<2>")
	)
	(segment
		(start 168.333674 -210.956906)
		(end 167.56888 -210.192112)
		(width 0.18288)
		(layer "In6.Cu")
		(net "M_H_CPU1_SB_DQS_DP<2>")
	)
	(segment
		(start 126.51994 -230.086662)
		(end 126.207012 -230.086662)
		(width 0.088646)
		(layer "In6.Cu")
		(net "M_H_CPU1_SB_DQS_DP<2>")
	)
	(segment
		(start 126.863602 -230.575612)
		(end 126.858268 -230.572564)
		(width 0.088646)
		(layer "In6.Cu")
		(net "M_H_CPU1_SB_DQS_DP<2>")
	)
	(segment
		(start 160.163256 -210.299046)
		(end 157.723078 -210.299046)
		(width 0.18288)
		(layer "In6.Cu")
		(net "M_H_CPU1_SB_DQS_DP<2>")
	)
	(segment
		(start 174.65802 -211.92109)
		(end 173.79823 -212.78088)
		(width 0.18288)
		(layer "In6.Cu")
		(net "M_H_CPU1_SB_DQS_DP<2>")
	)
	(segment
		(start 194.064382 -209.460846)
		(end 193.648584 -209.460846)
		(width 0.18288)
		(layer "In6.Cu")
		(net "M_H_CPU1_SB_DQS_DP<2>")
	)
	(segment
		(start 188.318394 -211.080604)
		(end 188.058044 -211.340954)
		(width 0.18288)
		(layer "In6.Cu")
		(net "M_H_CPU1_SB_DQS_DP<2>")
	)
	(segment
		(start 157.723078 -210.299046)
		(end 156.279088 -211.743036)
		(width 0.18288)
		(layer "In6.Cu")
		(net "M_H_CPU1_SB_DQS_DP<2>")
	)
	(segment
		(start 197.68312 -210.151726)
		(end 195.7324 -210.151726)
		(width 0.18288)
		(layer "In6.Cu")
		(net "M_H_CPU1_SB_DQS_DP<2>")
	)
	(segment
		(start 182.8927 -210.393788)
		(end 179.88661 -210.393788)
		(width 0.18288)
		(layer "In6.Cu")
		(net "M_H_CPU1_SB_DQS_DP<2>")
	)
	(segment
		(start 192.418462 -210.230466)
		(end 192.158112 -210.490816)
		(width 0.18288)
		(layer "In6.Cu")
		(net "M_H_CPU1_SB_DQS_DP<2>")
	)
	(segment
		(start 189.734952 -210.230466)
		(end 188.884814 -211.080604)
		(width 0.18288)
		(layer "In6.Cu")
		(net "M_H_CPU1_SB_DQS_DP<2>")
	)
	(segment
		(start 188.058044 -211.340954)
		(end 187.701428 -211.340954)
		(width 0.18288)
		(layer "In6.Cu")
		(net "M_H_CPU1_SB_DQS_DP<2>")
	)
	(segment
		(start 130.531362 -230.086662)
		(end 130.531362 -230.102156)
		(width 0.088646)
		(layer "In6.Cu")
		(net "M_H_CPU1_SB_DQS_DP<2>")
	)
	(segment
		(start 202.971146 -210.066636)
		(end 202.687936 -209.783426)
		(width 0.18288)
		(layer "In6.Cu")
		(net "M_H_CPU1_SB_DQS_DP<2>")
	)
	(segment
		(start 187.432442 -211.071968)
		(end 184.530238 -211.071968)
		(width 0.18288)
		(layer "In6.Cu")
		(net "M_H_CPU1_SB_DQS_DP<2>")
	)
	(segment
		(start 128.758696 -230.584756)
		(end 128.743964 -230.57612)
		(width 0.088646)
		(layer "In6.Cu")
		(net "M_H_CPU1_SB_DQS_DP<2>")
	)
	(segment
		(start 202.687936 -209.783426)
		(end 202.18908 -209.783426)
		(width 0.18288)
		(layer "In6.Cu")
		(net "M_H_CPU1_SB_DQS_DP<2>")
	)
	(segment
		(start 131.658868 -229.762304)
		(end 131.648454 -229.7684)
		(width 0.088646)
		(layer "In6.Cu")
		(net "M_H_CPU1_SB_DQS_DP<2>")
	)
	(segment
		(start 188.884814 -211.080604)
		(end 188.318394 -211.080604)
		(width 0.18288)
		(layer "In6.Cu")
		(net "M_H_CPU1_SB_DQS_DP<2>")
	)
	(segment
		(start 172.612304 -213.04123)
		(end 172.350176 -212.779102)
		(width 0.18288)
		(layer "In6.Cu")
		(net "M_H_CPU1_SB_DQS_DP<2>")
	)
	(segment
		(start 176.441862 -211.92109)
		(end 174.65802 -211.92109)
		(width 0.18288)
		(layer "In6.Cu")
		(net "M_H_CPU1_SB_DQS_DP<2>")
	)
	(segment
		(start 173.79823 -212.78088)
		(end 173.234858 -212.78088)
		(width 0.18288)
		(layer "In6.Cu")
		(net "M_H_CPU1_SB_DQS_DP<2>")
	)
	(segment
		(start 139.062968 -227.722938)
		(end 138.36269 -228.423216)
		(width 0.088646)
		(layer "In6.Cu")
		(net "M_H_CPU1_SB_DQS_DP<2>")
	)
	(segment
		(start 138.36269 -228.423216)
		(end 138.36269 -229.111302)
		(width 0.088646)
		(layer "In6.Cu")
		(net "M_H_CPU1_SB_DQS_DP<2>")
	)
	(segment
		(start 164.339016 -210.828382)
		(end 160.692592 -210.828382)
		(width 0.18288)
		(layer "In6.Cu")
		(net "M_H_CPU1_SB_DQS_DP<2>")
	)
	(segment
		(start 177.083212 -212.191092)
		(end 176.711864 -212.191092)
		(width 0.18288)
		(layer "In6.Cu")
		(net "M_H_CPU1_SB_DQS_DP<2>")
	)
	(segment
		(start 137.762488 -229.711504)
		(end 137.484866 -229.711504)
		(width 0.088646)
		(layer "In6.Cu")
		(net "M_H_CPU1_SB_DQS_DP<2>")
	)
	(segment
		(start 132.598414 -229.762304)
		(end 132.588 -229.7684)
		(width 0.088646)
		(layer "In6.Cu")
		(net "M_H_CPU1_SB_DQS_DP<2>")
	)
	(segment
		(start 191.811148 -210.490816)
		(end 191.550798 -210.230466)
		(width 0.18288)
		(layer "In6.Cu")
		(net "M_H_CPU1_SB_DQS_DP<2>")
	)
	(segment
		(start 169.695622 -210.956906)
		(end 168.333674 -210.956906)
		(width 0.18288)
		(layer "In6.Cu")
		(net "M_H_CPU1_SB_DQS_DP<2>")
	)
	(segment
		(start 173.234858 -212.78088)
		(end 172.974508 -213.04123)
		(width 0.18288)
		(layer "In6.Cu")
		(net "M_H_CPU1_SB_DQS_DP<2>")
	)
	(segment
		(start 126.864364 -230.57612)
		(end 126.863602 -230.575612)
		(width 0.088646)
		(layer "In6.Cu")
		(net "M_H_CPU1_SB_DQS_DP<2>")
	)
	(segment
		(start 167.56888 -210.192112)
		(end 164.975286 -210.192112)
		(width 0.18288)
		(layer "In6.Cu")
		(net "M_H_CPU1_SB_DQS_DP<2>")
	)
	(segment
		(start 202.18908 -209.783426)
		(end 201.853546 -209.447892)
		(width 0.18288)
		(layer "In6.Cu")
		(net "M_H_CPU1_SB_DQS_DP<2>")
	)
	(segment
		(start 195.7324 -210.151726)
		(end 194.064382 -209.460846)
		(width 0.18288)
		(layer "In6.Cu")
		(net "M_H_CPU1_SB_DQS_DP<2>")
	)
	(segment
		(start 164.975286 -210.192112)
		(end 164.339016 -210.828382)
		(width 0.18288)
		(layer "In6.Cu")
		(net "M_H_CPU1_SB_DQS_DP<2>")
	)
	(segment
		(start 129.698496 -230.584756)
		(end 129.683764 -230.57612)
		(width 0.088646)
		(layer "In6.Cu")
		(net "M_H_CPU1_SB_DQS_DP<2>")
	)
	(segment
		(start 139.274042 -227.782882)
		(end 139.250674 -227.782882)
		(width 0.088646)
		(layer "In6.Cu")
		(net "M_H_CPU1_SB_DQS_DP<2>")
	)
	(segment
		(start 187.701428 -211.340954)
		(end 187.432442 -211.071968)
		(width 0.18288)
		(layer "In6.Cu")
		(net "M_H_CPU1_SB_DQS_DP<2>")
	)
	(segment
		(start 172.974508 -213.04123)
		(end 172.612304 -213.04123)
		(width 0.18288)
		(layer "In6.Cu")
		(net "M_H_CPU1_SB_DQS_DP<2>")
	)
	(segment
		(start 160.692592 -210.828382)
		(end 160.163256 -210.299046)
		(width 0.18288)
		(layer "In6.Cu")
		(net "M_H_CPU1_SB_DQS_DP<2>")
	)
	(segment
		(start 139.19073 -227.722938)
		(end 139.062968 -227.722938)
		(width 0.088646)
		(layer "In6.Cu")
		(net "M_H_CPU1_SB_DQS_DP<2>")
	)
	(segment
		(start 127.818896 -230.584756)
		(end 127.804164 -230.57612)
		(width 0.088646)
		(layer "In6.Cu")
		(net "M_H_CPU1_SB_DQS_DP<2>")
	)
	(segment
		(start 130.718814 -229.762304)
		(end 130.71729 -229.763066)
		(width 0.088646)
		(layer "In6.Cu")
		(net "M_H_CPU1_SB_DQS_DP<2>")
	)
	(arc
		(start 127.429768 -230.57612)
		(mid 127.155569 -230.651955)
		(end 126.879096 -230.584756)
		(width 0.088646)
		(layer "In6.Cu")
		(net "M_H_CPU1_SB_DQS_DP<2>")
	)
	(arc
		(start 137.484866 -229.711504)
		(mid 137.468848 -229.711922)
		(end 137.452862 -229.713028)
		(width 0.088646)
		(layer "In6.Cu")
		(net "M_H_CPU1_SB_DQS_DP<2>")
	)
	(arc
		(start 132.97281 -229.762304)
		(mid 132.785612 -229.712161)
		(end 132.598414 -229.762304)
		(width 0.088646)
		(layer "In6.Cu")
		(net "M_H_CPU1_SB_DQS_DP<2>")
	)
	(arc
		(start 130.709924 -229.767384)
		(mid 130.57901 -229.903744)
		(end 130.531362 -230.086662)
		(width 0.088646)
		(layer "In6.Cu")
		(net "M_H_CPU1_SB_DQS_DP<2>")
	)
	(arc
		(start 135.792464 -229.762304)
		(mid 135.605266 -229.712161)
		(end 135.418068 -229.762304)
		(width 0.088646)
		(layer "In6.Cu")
		(net "M_H_CPU1_SB_DQS_DP<2>")
	)
	(arc
		(start 128.743964 -230.57612)
		(mid 128.556766 -230.525977)
		(end 128.369568 -230.57612)
		(width 0.088646)
		(layer "In6.Cu")
		(net "M_H_CPU1_SB_DQS_DP<2>")
	)
	(arc
		(start 133.528054 -229.7684)
		(mid 133.249622 -229.838246)
		(end 132.97281 -229.762304)
		(width 0.088646)
		(layer "In6.Cu")
		(net "M_H_CPU1_SB_DQS_DP<2>")
	)
	(arc
		(start 130.249168 -230.57612)
		(mid 129.974969 -230.651955)
		(end 129.698496 -230.584756)
		(width 0.088646)
		(layer "In6.Cu")
		(net "M_H_CPU1_SB_DQS_DP<2>")
	)
	(arc
		(start 134.852664 -229.762304)
		(mid 134.665466 -229.712161)
		(end 134.478268 -229.762304)
		(width 0.088646)
		(layer "In6.Cu")
		(net "M_H_CPU1_SB_DQS_DP<2>")
	)
	(arc
		(start 137.297668 -229.762304)
		(mid 137.014966 -229.83808)
		(end 136.732264 -229.762304)
		(width 0.088646)
		(layer "In6.Cu")
		(net "M_H_CPU1_SB_DQS_DP<2>")
	)
	(arc
		(start 137.452862 -229.713028)
		(mid 137.372547 -229.729115)
		(end 137.297668 -229.762304)
		(width 0.088646)
		(layer "In6.Cu")
		(net "M_H_CPU1_SB_DQS_DP<2>")
	)
	(arc
		(start 132.033264 -229.762304)
		(mid 131.846066 -229.712161)
		(end 131.658868 -229.762304)
		(width 0.088646)
		(layer "In6.Cu")
		(net "M_H_CPU1_SB_DQS_DP<2>")
	)
	(arc
		(start 130.531362 -230.102156)
		(mid 130.451992 -230.37589)
		(end 130.249168 -230.57612)
		(width 0.088646)
		(layer "In6.Cu")
		(net "M_H_CPU1_SB_DQS_DP<2>")
	)
	(arc
		(start 126.858268 -230.572564)
		(mid 126.672745 -230.394263)
		(end 126.585472 -230.152194)
		(width 0.088646)
		(layer "In6.Cu")
		(net "M_H_CPU1_SB_DQS_DP<2>")
	)
	(arc
		(start 135.418068 -229.762304)
		(mid 135.135366 -229.83808)
		(end 134.852664 -229.762304)
		(width 0.088646)
		(layer "In6.Cu")
		(net "M_H_CPU1_SB_DQS_DP<2>")
	)
	(arc
		(start 129.309368 -230.57612)
		(mid 129.035169 -230.651955)
		(end 128.758696 -230.584756)
		(width 0.088646)
		(layer "In6.Cu")
		(net "M_H_CPU1_SB_DQS_DP<2>")
	)
	(arc
		(start 131.648454 -229.7684)
		(mid 131.370022 -229.838246)
		(end 131.09321 -229.762304)
		(width 0.088646)
		(layer "In6.Cu")
		(net "M_H_CPU1_SB_DQS_DP<2>")
	)
	(arc
		(start 128.369568 -230.57612)
		(mid 128.095369 -230.651955)
		(end 127.818896 -230.584756)
		(width 0.088646)
		(layer "In6.Cu")
		(net "M_H_CPU1_SB_DQS_DP<2>")
	)
	(arc
		(start 136.732264 -229.762304)
		(mid 136.545066 -229.712161)
		(end 136.357868 -229.762304)
		(width 0.088646)
		(layer "In6.Cu")
		(net "M_H_CPU1_SB_DQS_DP<2>")
	)
	(arc
		(start 127.804164 -230.57612)
		(mid 127.616966 -230.525977)
		(end 127.429768 -230.57612)
		(width 0.088646)
		(layer "In6.Cu")
		(net "M_H_CPU1_SB_DQS_DP<2>")
	)
	(arc
		(start 136.357868 -229.762304)
		(mid 136.075166 -229.83808)
		(end 135.792464 -229.762304)
		(width 0.088646)
		(layer "In6.Cu")
		(net "M_H_CPU1_SB_DQS_DP<2>")
	)
	(arc
		(start 129.683764 -230.57612)
		(mid 129.496566 -230.525977)
		(end 129.309368 -230.57612)
		(width 0.088646)
		(layer "In6.Cu")
		(net "M_H_CPU1_SB_DQS_DP<2>")
	)
	(arc
		(start 132.588 -229.7684)
		(mid 132.309822 -229.838123)
		(end 132.033264 -229.762304)
		(width 0.088646)
		(layer "In6.Cu")
		(net "M_H_CPU1_SB_DQS_DP<2>")
	)
	(arc
		(start 131.09321 -229.762304)
		(mid 130.906012 -229.712161)
		(end 130.718814 -229.762304)
		(width 0.088646)
		(layer "In6.Cu")
		(net "M_H_CPU1_SB_DQS_DP<2>")
	)
	(arc
		(start 133.912864 -229.762304)
		(mid 133.725666 -229.712161)
		(end 133.538468 -229.762304)
		(width 0.088646)
		(layer "In6.Cu")
		(net "M_H_CPU1_SB_DQS_DP<2>")
	)
	(arc
		(start 134.478268 -229.762304)
		(mid 134.195566 -229.83808)
		(end 133.912864 -229.762304)
		(width 0.088646)
		(layer "In6.Cu")
		(net "M_H_CPU1_SB_DQS_DP<2>")
	)
	(segment
		(start 204.665326 -219.41663)
		(end 204.905864 -219.176092)
		(width 0.20066)
		(layer "F.Cu")
		(net "M_H_CPU1_SB_DQS_DP<1>")
	)
	(segment
		(start 209.18043 -219.841826)
		(end 209.186526 -219.847922)
		(width 0.1016)
		(layer "F.Cu")
		(net "M_H_CPU1_SB_DQS_DP<1>")
	)
	(segment
		(start 207.023208 -219.841826)
		(end 209.18043 -219.841826)
		(width 0.1016)
		(layer "F.Cu")
		(net "M_H_CPU1_SB_DQS_DP<1>")
	)
	(segment
		(start 205.920848 -219.59062)
		(end 206.606648 -219.59062)
		(width 0.20066)
		(layer "F.Cu")
		(net "M_H_CPU1_SB_DQS_DP<1>")
	)
	(segment
		(start 211.071206 -219.41663)
		(end 211.619846 -219.41663)
		(width 0.20066)
		(layer "F.Cu")
		(net "M_H_CPU1_SB_DQS_DP<1>")
	)
	(segment
		(start 202.971146 -219.41663)
		(end 204.076046 -219.41663)
		(width 0.20066)
		(layer "F.Cu")
		(net "M_H_CPU1_SB_DQS_DP<1>")
	)
	(segment
		(start 210.182968 -219.545408)
		(end 210.593432 -219.134944)
		(width 0.20066)
		(layer "F.Cu")
		(net "M_H_CPU1_SB_DQS_DP<1>")
	)
	(segment
		(start 206.857854 -219.841826)
		(end 206.9973 -219.841826)
		(width 0.20066)
		(layer "F.Cu")
		(net "M_H_CPU1_SB_DQS_DP<1>")
	)
	(segment
		(start 122.917712 -233.064304)
		(end 122.917712 -232.528618)
		(width 0.20066)
		(layer "F.Cu")
		(net "M_H_CPU1_SB_DQS_DP<1>")
	)
	(segment
		(start 209.509868 -219.847922)
		(end 209.812382 -219.545408)
		(width 0.20066)
		(layer "F.Cu")
		(net "M_H_CPU1_SB_DQS_DP<1>")
	)
	(segment
		(start 205.50632 -219.176092)
		(end 205.920848 -219.59062)
		(width 0.20066)
		(layer "F.Cu")
		(net "M_H_CPU1_SB_DQS_DP<1>")
	)
	(segment
		(start 206.606648 -219.59062)
		(end 206.857854 -219.841826)
		(width 0.20066)
		(layer "F.Cu")
		(net "M_H_CPU1_SB_DQS_DP<1>")
	)
	(segment
		(start 206.9973 -219.841826)
		(end 207.023208 -219.841826)
		(width 0.101854)
		(layer "F.Cu")
		(net "M_H_CPU1_SB_DQS_DP<1>")
	)
	(segment
		(start 210.78952 -219.134944)
		(end 211.071206 -219.41663)
		(width 0.20066)
		(layer "F.Cu")
		(net "M_H_CPU1_SB_DQS_DP<1>")
	)
	(segment
		(start 122.917712 -232.528618)
		(end 122.917966 -232.528364)
		(width 0.20066)
		(layer "F.Cu")
		(net "M_H_CPU1_SB_DQS_DP<1>")
	)
	(segment
		(start 209.186526 -219.847922)
		(end 209.509868 -219.847922)
		(width 0.20066)
		(layer "F.Cu")
		(net "M_H_CPU1_SB_DQS_DP<1>")
	)
	(segment
		(start 204.076046 -219.41663)
		(end 204.665326 -219.41663)
		(width 0.20066)
		(layer "F.Cu")
		(net "M_H_CPU1_SB_DQS_DP<1>")
	)
	(segment
		(start 209.812382 -219.545408)
		(end 210.182968 -219.545408)
		(width 0.20066)
		(layer "F.Cu")
		(net "M_H_CPU1_SB_DQS_DP<1>")
	)
	(segment
		(start 204.905864 -219.176092)
		(end 205.50632 -219.176092)
		(width 0.20066)
		(layer "F.Cu")
		(net "M_H_CPU1_SB_DQS_DP<1>")
	)
	(segment
		(start 210.593432 -219.134944)
		(end 210.78952 -219.134944)
		(width 0.20066)
		(layer "F.Cu")
		(net "M_H_CPU1_SB_DQS_DP<1>")
	)
	(segment
		(start 140.103352 -231.310688)
		(end 140.019024 -231.310688)
		(width 0.088646)
		(layer "In11.Cu")
		(net "M_H_CPU1_SB_DQS_DP<1>")
	)
	(segment
		(start 160.707832 -213.786466)
		(end 159.599122 -213.786466)
		(width 0.18288)
		(layer "In11.Cu")
		(net "M_H_CPU1_SB_DQS_DP<1>")
	)
	(segment
		(start 193.785998 -214.426546)
		(end 192.985898 -213.626446)
		(width 0.18288)
		(layer "In11.Cu")
		(net "M_H_CPU1_SB_DQS_DP<1>")
	)
	(segment
		(start 184.20461 -212.793326)
		(end 183.392318 -211.981034)
		(width 0.18288)
		(layer "In11.Cu")
		(net "M_H_CPU1_SB_DQS_DP<1>")
	)
	(segment
		(start 155.18765 -217.636852)
		(end 147.829778 -224.994724)
		(width 0.18288)
		(layer "In11.Cu")
		(net "M_H_CPU1_SB_DQS_DP<1>")
	)
	(segment
		(start 140.019024 -231.310688)
		(end 139.930378 -231.399334)
		(width 0.088646)
		(layer "In11.Cu")
		(net "M_H_CPU1_SB_DQS_DP<1>")
	)
	(segment
		(start 139.161012 -232.416096)
		(end 138.48334 -233.093768)
		(width 0.088646)
		(layer "In11.Cu")
		(net "M_H_CPU1_SB_DQS_DP<1>")
	)
	(segment
		(start 180.092096 -211.981034)
		(end 179.236878 -212.836252)
		(width 0.18288)
		(layer "In11.Cu")
		(net "M_H_CPU1_SB_DQS_DP<1>")
	)
	(segment
		(start 202.245722 -219.18168)
		(end 201.749406 -218.685364)
		(width 0.18288)
		(layer "In11.Cu")
		(net "M_H_CPU1_SB_DQS_DP<1>")
	)
	(segment
		(start 192.985898 -213.626446)
		(end 192.476374 -213.626446)
		(width 0.18288)
		(layer "In11.Cu")
		(net "M_H_CPU1_SB_DQS_DP<1>")
	)
	(segment
		(start 158.507938 -213.20633)
		(end 158.507938 -213.409022)
		(width 0.18288)
		(layer "In11.Cu")
		(net "M_H_CPU1_SB_DQS_DP<1>")
	)
	(segment
		(start 188.376306 -212.776308)
		(end 188.111638 -213.040976)
		(width 0.18288)
		(layer "In11.Cu")
		(net "M_H_CPU1_SB_DQS_DP<1>")
	)
	(segment
		(start 192.476374 -213.626446)
		(end 192.211706 -213.891114)
		(width 0.18288)
		(layer "In11.Cu")
		(net "M_H_CPU1_SB_DQS_DP<1>")
	)
	(segment
		(start 172.501814 -214.740998)
		(end 172.249592 -214.488776)
		(width 0.18288)
		(layer "In11.Cu")
		(net "M_H_CPU1_SB_DQS_DP<1>")
	)
	(segment
		(start 168.06164 -213.799166)
		(end 164.99332 -213.799166)
		(width 0.18288)
		(layer "In11.Cu")
		(net "M_H_CPU1_SB_DQS_DP<1>")
	)
	(segment
		(start 155.18765 -216.083388)
		(end 155.18765 -217.636852)
		(width 0.18288)
		(layer "In11.Cu")
		(net "M_H_CPU1_SB_DQS_DP<1>")
	)
	(segment
		(start 130.718814 -233.017822)
		(end 130.704082 -233.026458)
		(width 0.088646)
		(layer "In11.Cu")
		(net "M_H_CPU1_SB_DQS_DP<1>")
	)
	(segment
		(start 125.460506 -233.021124)
		(end 125.448822 -233.01452)
		(width 0.088646)
		(layer "In11.Cu")
		(net "M_H_CPU1_SB_DQS_DP<1>")
	)
	(segment
		(start 202.736196 -219.18168)
		(end 202.245722 -219.18168)
		(width 0.18288)
		(layer "In11.Cu")
		(net "M_H_CPU1_SB_DQS_DP<1>")
	)
	(segment
		(start 173.279816 -214.48522)
		(end 173.024038 -214.740998)
		(width 0.18288)
		(layer "In11.Cu")
		(net "M_H_CPU1_SB_DQS_DP<1>")
	)
	(segment
		(start 159.599122 -213.786466)
		(end 159.221678 -213.409022)
		(width 0.18288)
		(layer "In11.Cu")
		(net "M_H_CPU1_SB_DQS_DP<1>")
	)
	(segment
		(start 123.23064 -232.528364)
		(end 122.917966 -232.528364)
		(width 0.088646)
		(layer "In11.Cu")
		(net "M_H_CPU1_SB_DQS_DP<1>")
	)
	(segment
		(start 191.689482 -213.891114)
		(end 191.42202 -213.623652)
		(width 0.18288)
		(layer "In11.Cu")
		(net "M_H_CPU1_SB_DQS_DP<1>")
	)
	(segment
		(start 189.904116 -213.623652)
		(end 189.056772 -212.776308)
		(width 0.18288)
		(layer "In11.Cu")
		(net "M_H_CPU1_SB_DQS_DP<1>")
	)
	(segment
		(start 123.296172 -232.593896)
		(end 123.23064 -232.528364)
		(width 0.088646)
		(layer "In11.Cu")
		(net "M_H_CPU1_SB_DQS_DP<1>")
	)
	(segment
		(start 158.130494 -213.786466)
		(end 157.484572 -213.786466)
		(width 0.18288)
		(layer "In11.Cu")
		(net "M_H_CPU1_SB_DQS_DP<1>")
	)
	(segment
		(start 124.520706 -233.021124)
		(end 124.509022 -233.01452)
		(width 0.088646)
		(layer "In11.Cu")
		(net "M_H_CPU1_SB_DQS_DP<1>")
	)
	(segment
		(start 188.111638 -213.040976)
		(end 187.589414 -213.040976)
		(width 0.18288)
		(layer "In11.Cu")
		(net "M_H_CPU1_SB_DQS_DP<1>")
	)
	(segment
		(start 198.435468 -216.833704)
		(end 197.282816 -216.833704)
		(width 0.18288)
		(layer "In11.Cu")
		(net "M_H_CPU1_SB_DQS_DP<1>")
	)
	(segment
		(start 131.658614 -233.017822)
		(end 131.643882 -233.026458)
		(width 0.088646)
		(layer "In11.Cu")
		(net "M_H_CPU1_SB_DQS_DP<1>")
	)
	(segment
		(start 201.749406 -218.685364)
		(end 200.287128 -218.685364)
		(width 0.18288)
		(layer "In11.Cu")
		(net "M_H_CPU1_SB_DQS_DP<1>")
	)
	(segment
		(start 178.734466 -212.836252)
		(end 177.960528 -213.61019)
		(width 0.18288)
		(layer "In11.Cu")
		(net "M_H_CPU1_SB_DQS_DP<1>")
	)
	(segment
		(start 173.848522 -214.48522)
		(end 173.279816 -214.48522)
		(width 0.18288)
		(layer "In11.Cu")
		(net "M_H_CPU1_SB_DQS_DP<1>")
	)
	(segment
		(start 187.589414 -213.040976)
		(end 187.341764 -212.793326)
		(width 0.18288)
		(layer "In11.Cu")
		(net "M_H_CPU1_SB_DQS_DP<1>")
	)
	(segment
		(start 173.024038 -214.740998)
		(end 172.501814 -214.740998)
		(width 0.18288)
		(layer "In11.Cu")
		(net "M_H_CPU1_SB_DQS_DP<1>")
	)
	(segment
		(start 187.341764 -212.793326)
		(end 184.20461 -212.793326)
		(width 0.18288)
		(layer "In11.Cu")
		(net "M_H_CPU1_SB_DQS_DP<1>")
	)
	(segment
		(start 161.132774 -214.211408)
		(end 160.707832 -213.786466)
		(width 0.18288)
		(layer "In11.Cu")
		(net "M_H_CPU1_SB_DQS_DP<1>")
	)
	(segment
		(start 179.236878 -212.836252)
		(end 178.734466 -212.836252)
		(width 0.18288)
		(layer "In11.Cu")
		(net "M_H_CPU1_SB_DQS_DP<1>")
	)
	(segment
		(start 192.211706 -213.891114)
		(end 191.689482 -213.891114)
		(width 0.18288)
		(layer "In11.Cu")
		(net "M_H_CPU1_SB_DQS_DP<1>")
	)
	(segment
		(start 172.249592 -214.488776)
		(end 169.72661 -214.488776)
		(width 0.18288)
		(layer "In11.Cu")
		(net "M_H_CPU1_SB_DQS_DP<1>")
	)
	(segment
		(start 169.72661 -214.488776)
		(end 168.06164 -213.799166)
		(width 0.18288)
		(layer "In11.Cu")
		(net "M_H_CPU1_SB_DQS_DP<1>")
	)
	(segment
		(start 140.163296 -231.370632)
		(end 140.103352 -231.310688)
		(width 0.088646)
		(layer "In11.Cu")
		(net "M_H_CPU1_SB_DQS_DP<1>")
	)
	(segment
		(start 176.345596 -213.634828)
		(end 174.698914 -213.634828)
		(width 0.18288)
		(layer "In11.Cu")
		(net "M_H_CPU1_SB_DQS_DP<1>")
	)
	(segment
		(start 183.392318 -211.981034)
		(end 180.092096 -211.981034)
		(width 0.18288)
		(layer "In11.Cu")
		(net "M_H_CPU1_SB_DQS_DP<1>")
	)
	(segment
		(start 197.282816 -216.833704)
		(end 195.792598 -215.343486)
		(width 0.18288)
		(layer "In11.Cu")
		(net "M_H_CPU1_SB_DQS_DP<1>")
	)
	(segment
		(start 159.221678 -213.409022)
		(end 159.221678 -213.20633)
		(width 0.18288)
		(layer "In11.Cu")
		(net "M_H_CPU1_SB_DQS_DP<1>")
	)
	(segment
		(start 174.698914 -213.634828)
		(end 173.848522 -214.48522)
		(width 0.18288)
		(layer "In11.Cu")
		(net "M_H_CPU1_SB_DQS_DP<1>")
	)
	(segment
		(start 189.056772 -212.776308)
		(end 188.376306 -212.776308)
		(width 0.18288)
		(layer "In11.Cu")
		(net "M_H_CPU1_SB_DQS_DP<1>")
	)
	(segment
		(start 127.899414 -233.017822)
		(end 127.884682 -233.026458)
		(width 0.088646)
		(layer "In11.Cu")
		(net "M_H_CPU1_SB_DQS_DP<1>")
	)
	(segment
		(start 139.842748 -232.0417)
		(end 139.685776 -232.198672)
		(width 0.088646)
		(layer "In11.Cu")
		(net "M_H_CPU1_SB_DQS_DP<1>")
	)
	(segment
		(start 159.221678 -213.20633)
		(end 159.02432 -213.008972)
		(width 0.18288)
		(layer "In11.Cu")
		(net "M_H_CPU1_SB_DQS_DP<1>")
	)
	(segment
		(start 177.960528 -213.61019)
		(end 177.40503 -213.61019)
		(width 0.18288)
		(layer "In11.Cu")
		(net "M_H_CPU1_SB_DQS_DP<1>")
	)
	(segment
		(start 147.829778 -225.914204)
		(end 142.37335 -231.370632)
		(width 0.18288)
		(layer "In11.Cu")
		(net "M_H_CPU1_SB_DQS_DP<1>")
	)
	(segment
		(start 139.685776 -232.198672)
		(end 139.161012 -232.416096)
		(width 0.088646)
		(layer "In11.Cu")
		(net "M_H_CPU1_SB_DQS_DP<1>")
	)
	(segment
		(start 164.581078 -214.211408)
		(end 161.132774 -214.211408)
		(width 0.18288)
		(layer "In11.Cu")
		(net "M_H_CPU1_SB_DQS_DP<1>")
	)
	(segment
		(start 191.42202 -213.623652)
		(end 189.904116 -213.623652)
		(width 0.18288)
		(layer "In11.Cu")
		(net "M_H_CPU1_SB_DQS_DP<1>")
	)
	(segment
		(start 139.930378 -231.831134)
		(end 139.842748 -232.0417)
		(width 0.088646)
		(layer "In11.Cu")
		(net "M_H_CPU1_SB_DQS_DP<1>")
	)
	(segment
		(start 200.287128 -218.685364)
		(end 198.435468 -216.833704)
		(width 0.18288)
		(layer "In11.Cu")
		(net "M_H_CPU1_SB_DQS_DP<1>")
	)
	(segment
		(start 158.705296 -213.008972)
		(end 158.507938 -213.20633)
		(width 0.18288)
		(layer "In11.Cu")
		(net "M_H_CPU1_SB_DQS_DP<1>")
	)
	(segment
		(start 164.99332 -213.799166)
		(end 164.581078 -214.211408)
		(width 0.18288)
		(layer "In11.Cu")
		(net "M_H_CPU1_SB_DQS_DP<1>")
	)
	(segment
		(start 194.414394 -214.426546)
		(end 193.785998 -214.426546)
		(width 0.18288)
		(layer "In11.Cu")
		(net "M_H_CPU1_SB_DQS_DP<1>")
	)
	(segment
		(start 132.987796 -233.026458)
		(end 132.973064 -233.017822)
		(width 0.088646)
		(layer "In11.Cu")
		(net "M_H_CPU1_SB_DQS_DP<1>")
	)
	(segment
		(start 177.40503 -213.61019)
		(end 177.124106 -213.891114)
		(width 0.18288)
		(layer "In11.Cu")
		(net "M_H_CPU1_SB_DQS_DP<1>")
	)
	(segment
		(start 202.971146 -219.41663)
		(end 202.736196 -219.18168)
		(width 0.18288)
		(layer "In11.Cu")
		(net "M_H_CPU1_SB_DQS_DP<1>")
	)
	(segment
		(start 176.601882 -213.891114)
		(end 176.345596 -213.634828)
		(width 0.18288)
		(layer "In11.Cu")
		(net "M_H_CPU1_SB_DQS_DP<1>")
	)
	(segment
		(start 137.672318 -233.017568)
		(end 137.672064 -233.017822)
		(width 0.088646)
		(layer "In11.Cu")
		(net "M_H_CPU1_SB_DQS_DP<1>")
	)
	(segment
		(start 142.37335 -231.370632)
		(end 140.163296 -231.370632)
		(width 0.18288)
		(layer "In11.Cu")
		(net "M_H_CPU1_SB_DQS_DP<1>")
	)
	(segment
		(start 129.779014 -233.017822)
		(end 129.764282 -233.026458)
		(width 0.088646)
		(layer "In11.Cu")
		(net "M_H_CPU1_SB_DQS_DP<1>")
	)
	(segment
		(start 158.507938 -213.409022)
		(end 158.130494 -213.786466)
		(width 0.18288)
		(layer "In11.Cu")
		(net "M_H_CPU1_SB_DQS_DP<1>")
	)
	(segment
		(start 128.839214 -233.017822)
		(end 128.824482 -233.026458)
		(width 0.088646)
		(layer "In11.Cu")
		(net "M_H_CPU1_SB_DQS_DP<1>")
	)
	(segment
		(start 195.331334 -215.343486)
		(end 194.414394 -214.426546)
		(width 0.18288)
		(layer "In11.Cu")
		(net "M_H_CPU1_SB_DQS_DP<1>")
	)
	(segment
		(start 139.930378 -231.399334)
		(end 139.930378 -231.831134)
		(width 0.088646)
		(layer "In11.Cu")
		(net "M_H_CPU1_SB_DQS_DP<1>")
	)
	(segment
		(start 159.02432 -213.008972)
		(end 158.705296 -213.008972)
		(width 0.18288)
		(layer "In11.Cu")
		(net "M_H_CPU1_SB_DQS_DP<1>")
	)
	(segment
		(start 147.829778 -224.994724)
		(end 147.829778 -225.914204)
		(width 0.18288)
		(layer "In11.Cu")
		(net "M_H_CPU1_SB_DQS_DP<1>")
	)
	(segment
		(start 132.598668 -233.017822)
		(end 132.588254 -233.023918)
		(width 0.088646)
		(layer "In11.Cu")
		(net "M_H_CPU1_SB_DQS_DP<1>")
	)
	(segment
		(start 195.792598 -215.343486)
		(end 195.331334 -215.343486)
		(width 0.18288)
		(layer "In11.Cu")
		(net "M_H_CPU1_SB_DQS_DP<1>")
	)
	(segment
		(start 177.124106 -213.891114)
		(end 176.601882 -213.891114)
		(width 0.18288)
		(layer "In11.Cu")
		(net "M_H_CPU1_SB_DQS_DP<1>")
	)
	(segment
		(start 157.484572 -213.786466)
		(end 155.18765 -216.083388)
		(width 0.18288)
		(layer "In11.Cu")
		(net "M_H_CPU1_SB_DQS_DP<1>")
	)
	(segment
		(start 138.48334 -233.093768)
		(end 137.954766 -233.093768)
		(width 0.088646)
		(layer "In11.Cu")
		(net "M_H_CPU1_SB_DQS_DP<1>")
	)
	(arc
		(start 135.792464 -233.017822)
		(mid 135.605266 -232.967679)
		(end 135.418068 -233.017822)
		(width 0.088646)
		(layer "In11.Cu")
		(net "M_H_CPU1_SB_DQS_DP<1>")
	)
	(arc
		(start 128.824482 -233.026458)
		(mid 128.548007 -233.093778)
		(end 128.27381 -233.017822)
		(width 0.088646)
		(layer "In11.Cu")
		(net "M_H_CPU1_SB_DQS_DP<1>")
	)
	(arc
		(start 135.418068 -233.017822)
		(mid 135.135366 -233.093598)
		(end 134.852664 -233.017822)
		(width 0.088646)
		(layer "In11.Cu")
		(net "M_H_CPU1_SB_DQS_DP<1>")
	)
	(arc
		(start 124.140214 -233.017822)
		(mid 123.613392 -233.038163)
		(end 123.298966 -232.614978)
		(width 0.088646)
		(layer "In11.Cu")
		(net "M_H_CPU1_SB_DQS_DP<1>")
	)
	(arc
		(start 133.538468 -233.017822)
		(mid 133.264269 -233.093657)
		(end 132.987796 -233.026458)
		(width 0.088646)
		(layer "In11.Cu")
		(net "M_H_CPU1_SB_DQS_DP<1>")
	)
	(arc
		(start 125.448822 -233.01452)
		(mid 125.263967 -232.96757)
		(end 125.080014 -233.017822)
		(width 0.088646)
		(layer "In11.Cu")
		(net "M_H_CPU1_SB_DQS_DP<1>")
	)
	(arc
		(start 127.884682 -233.026458)
		(mid 127.608207 -233.093778)
		(end 127.33401 -233.017822)
		(width 0.088646)
		(layer "In11.Cu")
		(net "M_H_CPU1_SB_DQS_DP<1>")
	)
	(arc
		(start 126.019814 -233.017822)
		(mid 125.740611 -233.093462)
		(end 125.460506 -233.021124)
		(width 0.088646)
		(layer "In11.Cu")
		(net "M_H_CPU1_SB_DQS_DP<1>")
	)
	(arc
		(start 123.298966 -232.614978)
		(mid 123.297469 -232.60445)
		(end 123.296172 -232.593896)
		(width 0.088646)
		(layer "In11.Cu")
		(net "M_H_CPU1_SB_DQS_DP<1>")
	)
	(arc
		(start 130.704082 -233.026458)
		(mid 130.427607 -233.093778)
		(end 130.15341 -233.017822)
		(width 0.088646)
		(layer "In11.Cu")
		(net "M_H_CPU1_SB_DQS_DP<1>")
	)
	(arc
		(start 126.39167 -233.016298)
		(mid 126.390145 -233.015411)
		(end 126.388622 -233.01452)
		(width 0.088646)
		(layer "In11.Cu")
		(net "M_H_CPU1_SB_DQS_DP<1>")
	)
	(arc
		(start 134.478268 -233.017822)
		(mid 134.195566 -233.093598)
		(end 133.912864 -233.017822)
		(width 0.088646)
		(layer "In11.Cu")
		(net "M_H_CPU1_SB_DQS_DP<1>")
	)
	(arc
		(start 127.33401 -233.017822)
		(mid 127.146812 -232.967679)
		(end 126.959614 -233.017822)
		(width 0.088646)
		(layer "In11.Cu")
		(net "M_H_CPU1_SB_DQS_DP<1>")
	)
	(arc
		(start 128.27381 -233.017822)
		(mid 128.086612 -232.967679)
		(end 127.899414 -233.017822)
		(width 0.088646)
		(layer "In11.Cu")
		(net "M_H_CPU1_SB_DQS_DP<1>")
	)
	(arc
		(start 132.03301 -233.017822)
		(mid 131.845812 -232.967679)
		(end 131.658614 -233.017822)
		(width 0.088646)
		(layer "In11.Cu")
		(net "M_H_CPU1_SB_DQS_DP<1>")
	)
	(arc
		(start 129.21361 -233.017822)
		(mid 129.026412 -232.967679)
		(end 128.839214 -233.017822)
		(width 0.088646)
		(layer "In11.Cu")
		(net "M_H_CPU1_SB_DQS_DP<1>")
	)
	(arc
		(start 133.912864 -233.017822)
		(mid 133.725666 -232.967679)
		(end 133.538468 -233.017822)
		(width 0.088646)
		(layer "In11.Cu")
		(net "M_H_CPU1_SB_DQS_DP<1>")
	)
	(arc
		(start 131.09321 -233.017822)
		(mid 130.906012 -232.967679)
		(end 130.718814 -233.017822)
		(width 0.088646)
		(layer "In11.Cu")
		(net "M_H_CPU1_SB_DQS_DP<1>")
	)
	(arc
		(start 126.394464 -233.017822)
		(mid 126.393064 -233.017066)
		(end 126.39167 -233.016298)
		(width 0.088646)
		(layer "In11.Cu")
		(net "M_H_CPU1_SB_DQS_DP<1>")
	)
	(arc
		(start 132.973064 -233.017822)
		(mid 132.785866 -232.967679)
		(end 132.598668 -233.017822)
		(width 0.088646)
		(layer "In11.Cu")
		(net "M_H_CPU1_SB_DQS_DP<1>")
	)
	(arc
		(start 126.956058 -233.019854)
		(mid 126.674974 -233.093591)
		(end 126.394464 -233.017822)
		(width 0.088646)
		(layer "In11.Cu")
		(net "M_H_CPU1_SB_DQS_DP<1>")
	)
	(arc
		(start 134.852664 -233.017822)
		(mid 134.665466 -232.967679)
		(end 134.478268 -233.017822)
		(width 0.088646)
		(layer "In11.Cu")
		(net "M_H_CPU1_SB_DQS_DP<1>")
	)
	(arc
		(start 126.959614 -233.017822)
		(mid 126.957838 -233.018841)
		(end 126.956058 -233.019854)
		(width 0.088646)
		(layer "In11.Cu")
		(net "M_H_CPU1_SB_DQS_DP<1>")
	)
	(arc
		(start 126.388622 -233.01452)
		(mid 126.203801 -232.967727)
		(end 126.019814 -233.017822)
		(width 0.088646)
		(layer "In11.Cu")
		(net "M_H_CPU1_SB_DQS_DP<1>")
	)
	(arc
		(start 124.509022 -233.01452)
		(mid 124.324167 -232.96757)
		(end 124.140214 -233.017822)
		(width 0.088646)
		(layer "In11.Cu")
		(net "M_H_CPU1_SB_DQS_DP<1>")
	)
	(arc
		(start 125.080014 -233.017822)
		(mid 124.800811 -233.093462)
		(end 124.520706 -233.021124)
		(width 0.088646)
		(layer "In11.Cu")
		(net "M_H_CPU1_SB_DQS_DP<1>")
	)
	(arc
		(start 132.588254 -233.023918)
		(mid 132.309822 -233.093764)
		(end 132.03301 -233.017822)
		(width 0.088646)
		(layer "In11.Cu")
		(net "M_H_CPU1_SB_DQS_DP<1>")
	)
	(arc
		(start 131.643882 -233.026458)
		(mid 131.367407 -233.093778)
		(end 131.09321 -233.017822)
		(width 0.088646)
		(layer "In11.Cu")
		(net "M_H_CPU1_SB_DQS_DP<1>")
	)
	(arc
		(start 137.672064 -233.017822)
		(mid 137.484866 -232.967679)
		(end 137.297668 -233.017822)
		(width 0.088646)
		(layer "In11.Cu")
		(net "M_H_CPU1_SB_DQS_DP<1>")
	)
	(arc
		(start 130.15341 -233.017822)
		(mid 129.966212 -232.967679)
		(end 129.779014 -233.017822)
		(width 0.088646)
		(layer "In11.Cu")
		(net "M_H_CPU1_SB_DQS_DP<1>")
	)
	(arc
		(start 137.954766 -233.093768)
		(mid 137.808531 -233.074249)
		(end 137.672318 -233.017568)
		(width 0.088646)
		(layer "In11.Cu")
		(net "M_H_CPU1_SB_DQS_DP<1>")
	)
	(arc
		(start 129.764282 -233.026458)
		(mid 129.487807 -233.093778)
		(end 129.21361 -233.017822)
		(width 0.088646)
		(layer "In11.Cu")
		(net "M_H_CPU1_SB_DQS_DP<1>")
	)
	(arc
		(start 136.357868 -233.017822)
		(mid 136.075166 -233.093598)
		(end 135.792464 -233.017822)
		(width 0.088646)
		(layer "In11.Cu")
		(net "M_H_CPU1_SB_DQS_DP<1>")
	)
	(arc
		(start 137.297668 -233.017822)
		(mid 137.014966 -233.093598)
		(end 136.732264 -233.017822)
		(width 0.088646)
		(layer "In11.Cu")
		(net "M_H_CPU1_SB_DQS_DP<1>")
	)
	(arc
		(start 136.732264 -233.017822)
		(mid 136.545066 -232.967679)
		(end 136.357868 -233.017822)
		(width 0.088646)
		(layer "In11.Cu")
		(net "M_H_CPU1_SB_DQS_DP<1>")
	)
	(segment
		(start 204.905864 -228.526086)
		(end 205.50632 -228.526086)
		(width 0.20066)
		(layer "F.Cu")
		(net "M_H_CPU1_SB_DQS_DP<0>")
	)
	(segment
		(start 210.78952 -228.484938)
		(end 211.071206 -228.766624)
		(width 0.20066)
		(layer "F.Cu")
		(net "M_H_CPU1_SB_DQS_DP<0>")
	)
	(segment
		(start 209.18043 -229.19182)
		(end 209.186526 -229.197916)
		(width 0.1016)
		(layer "F.Cu")
		(net "M_H_CPU1_SB_DQS_DP<0>")
	)
	(segment
		(start 209.186526 -229.197916)
		(end 209.509868 -229.197916)
		(width 0.20066)
		(layer "F.Cu")
		(net "M_H_CPU1_SB_DQS_DP<0>")
	)
	(segment
		(start 205.920848 -228.940614)
		(end 206.606648 -228.940614)
		(width 0.20066)
		(layer "F.Cu")
		(net "M_H_CPU1_SB_DQS_DP<0>")
	)
	(segment
		(start 209.509868 -229.197916)
		(end 209.812382 -228.895402)
		(width 0.20066)
		(layer "F.Cu")
		(net "M_H_CPU1_SB_DQS_DP<0>")
	)
	(segment
		(start 204.076046 -228.766624)
		(end 204.665326 -228.766624)
		(width 0.20066)
		(layer "F.Cu")
		(net "M_H_CPU1_SB_DQS_DP<0>")
	)
	(segment
		(start 211.071206 -228.766624)
		(end 211.619846 -228.766624)
		(width 0.20066)
		(layer "F.Cu")
		(net "M_H_CPU1_SB_DQS_DP<0>")
	)
	(segment
		(start 206.857854 -229.19182)
		(end 206.9973 -229.19182)
		(width 0.20066)
		(layer "F.Cu")
		(net "M_H_CPU1_SB_DQS_DP<0>")
	)
	(segment
		(start 210.593432 -228.484938)
		(end 210.78952 -228.484938)
		(width 0.20066)
		(layer "F.Cu")
		(net "M_H_CPU1_SB_DQS_DP<0>")
	)
	(segment
		(start 207.023208 -229.19182)
		(end 209.18043 -229.19182)
		(width 0.1016)
		(layer "F.Cu")
		(net "M_H_CPU1_SB_DQS_DP<0>")
	)
	(segment
		(start 210.182968 -228.895402)
		(end 210.593432 -228.484938)
		(width 0.20066)
		(layer "F.Cu")
		(net "M_H_CPU1_SB_DQS_DP<0>")
	)
	(segment
		(start 209.812382 -228.895402)
		(end 210.182968 -228.895402)
		(width 0.20066)
		(layer "F.Cu")
		(net "M_H_CPU1_SB_DQS_DP<0>")
	)
	(segment
		(start 204.665326 -228.766624)
		(end 204.905864 -228.526086)
		(width 0.20066)
		(layer "F.Cu")
		(net "M_H_CPU1_SB_DQS_DP<0>")
	)
	(segment
		(start 206.9973 -229.19182)
		(end 207.023208 -229.19182)
		(width 0.101854)
		(layer "F.Cu")
		(net "M_H_CPU1_SB_DQS_DP<0>")
	)
	(segment
		(start 206.606648 -228.940614)
		(end 206.857854 -229.19182)
		(width 0.20066)
		(layer "F.Cu")
		(net "M_H_CPU1_SB_DQS_DP<0>")
	)
	(segment
		(start 202.971146 -228.766624)
		(end 204.076046 -228.766624)
		(width 0.20066)
		(layer "F.Cu")
		(net "M_H_CPU1_SB_DQS_DP<0>")
	)
	(segment
		(start 205.50632 -228.526086)
		(end 205.920848 -228.940614)
		(width 0.20066)
		(layer "F.Cu")
		(net "M_H_CPU1_SB_DQS_DP<0>")
	)
	(segment
		(start 122.917712 -237.411768)
		(end 122.917966 -237.411514)
		(width 0.20066)
		(layer "F.Cu")
		(net "M_H_CPU1_SB_DQS_DP<0>")
	)
	(segment
		(start 122.917712 -237.947454)
		(end 122.917712 -237.411768)
		(width 0.20066)
		(layer "F.Cu")
		(net "M_H_CPU1_SB_DQS_DP<0>")
	)
	(segment
		(start 201.83983 -228.0793)
		(end 197.403466 -228.0793)
		(width 0.18288)
		(layer "In11.Cu")
		(net "M_H_CPU1_SB_DQS_DP<0>")
	)
	(segment
		(start 177.935636 -224.676208)
		(end 177.388774 -224.676208)
		(width 0.18288)
		(layer "In11.Cu")
		(net "M_H_CPU1_SB_DQS_DP<0>")
	)
	(segment
		(start 130.718814 -237.901226)
		(end 130.704082 -237.909862)
		(width 0.088646)
		(layer "In11.Cu")
		(net "M_H_CPU1_SB_DQS_DP<0>")
	)
	(segment
		(start 125.080014 -237.901226)
		(end 125.065282 -237.909862)
		(width 0.088646)
		(layer "In11.Cu")
		(net "M_H_CPU1_SB_DQS_DP<0>")
	)
	(segment
		(start 140.510006 -237.38586)
		(end 140.045694 -237.850172)
		(width 0.088646)
		(layer "In11.Cu")
		(net "M_H_CPU1_SB_DQS_DP<0>")
	)
	(segment
		(start 179.714906 -224.484946)
		(end 179.283106 -224.053146)
		(width 0.18288)
		(layer "In11.Cu")
		(net "M_H_CPU1_SB_DQS_DP<0>")
	)
	(segment
		(start 187.691014 -224.090992)
		(end 187.410598 -223.810576)
		(width 0.18288)
		(layer "In11.Cu")
		(net "M_H_CPU1_SB_DQS_DP<0>")
	)
	(segment
		(start 179.283106 -224.053146)
		(end 178.558698 -224.053146)
		(width 0.18288)
		(layer "In11.Cu")
		(net "M_H_CPU1_SB_DQS_DP<0>")
	)
	(segment
		(start 173.288706 -225.526346)
		(end 173.024038 -225.791014)
		(width 0.18288)
		(layer "In11.Cu")
		(net "M_H_CPU1_SB_DQS_DP<0>")
	)
	(segment
		(start 155.388056 -227.214938)
		(end 145.15719 -237.445804)
		(width 0.18288)
		(layer "In11.Cu")
		(net "M_H_CPU1_SB_DQS_DP<0>")
	)
	(segment
		(start 191.492886 -224.702624)
		(end 190.928244 -224.702624)
		(width 0.18288)
		(layer "In11.Cu")
		(net "M_H_CPU1_SB_DQS_DP<0>")
	)
	(segment
		(start 132.987796 -237.909862)
		(end 132.973064 -237.901226)
		(width 0.088646)
		(layer "In11.Cu")
		(net "M_H_CPU1_SB_DQS_DP<0>")
	)
	(segment
		(start 172.300646 -225.528378)
		(end 168.859962 -225.528378)
		(width 0.18288)
		(layer "In11.Cu")
		(net "M_H_CPU1_SB_DQS_DP<0>")
	)
	(segment
		(start 164.95776 -226.164648)
		(end 164.497258 -225.704146)
		(width 0.18288)
		(layer "In11.Cu")
		(net "M_H_CPU1_SB_DQS_DP<0>")
	)
	(segment
		(start 163.141406 -226.37623)
		(end 162.30981 -226.37623)
		(width 0.18288)
		(layer "In11.Cu")
		(net "M_H_CPU1_SB_DQS_DP<0>")
	)
	(segment
		(start 129.779014 -237.901226)
		(end 129.764282 -237.909862)
		(width 0.088646)
		(layer "In11.Cu")
		(net "M_H_CPU1_SB_DQS_DP<0>")
	)
	(segment
		(start 123.22302 -237.498128)
		(end 123.219972 -237.49508)
		(width 0.088646)
		(layer "In11.Cu")
		(net "M_H_CPU1_SB_DQS_DP<0>")
	)
	(segment
		(start 183.83377 -223.810576)
		(end 183.1594 -224.484946)
		(width 0.18288)
		(layer "In11.Cu")
		(net "M_H_CPU1_SB_DQS_DP<0>")
	)
	(segment
		(start 134.852918 -237.901226)
		(end 134.852664 -237.901226)
		(width 0.088646)
		(layer "In11.Cu")
		(net "M_H_CPU1_SB_DQS_DP<0>")
	)
	(segment
		(start 132.598668 -237.901226)
		(end 132.588254 -237.907322)
		(width 0.088646)
		(layer "In11.Cu")
		(net "M_H_CPU1_SB_DQS_DP<0>")
	)
	(segment
		(start 176.425098 -224.715324)
		(end 174.905416 -224.715324)
		(width 0.18288)
		(layer "In11.Cu")
		(net "M_H_CPU1_SB_DQS_DP<0>")
	)
	(segment
		(start 188.376306 -223.826324)
		(end 188.111638 -224.090992)
		(width 0.18288)
		(layer "In11.Cu")
		(net "M_H_CPU1_SB_DQS_DP<0>")
	)
	(segment
		(start 145.15719 -237.445804)
		(end 141.103096 -237.445804)
		(width 0.18288)
		(layer "In11.Cu")
		(net "M_H_CPU1_SB_DQS_DP<0>")
	)
	(segment
		(start 163.81349 -225.704146)
		(end 163.141406 -226.37623)
		(width 0.18288)
		(layer "In11.Cu")
		(net "M_H_CPU1_SB_DQS_DP<0>")
	)
	(segment
		(start 191.731138 -224.940876)
		(end 191.492886 -224.702624)
		(width 0.18288)
		(layer "In11.Cu")
		(net "M_H_CPU1_SB_DQS_DP<0>")
	)
	(segment
		(start 192.211706 -224.940876)
		(end 191.731138 -224.940876)
		(width 0.18288)
		(layer "In11.Cu")
		(net "M_H_CPU1_SB_DQS_DP<0>")
	)
	(segment
		(start 159.77108 -226.364292)
		(end 158.909258 -227.226114)
		(width 0.18288)
		(layer "In11.Cu")
		(net "M_H_CPU1_SB_DQS_DP<0>")
	)
	(segment
		(start 128.839214 -237.901226)
		(end 128.824482 -237.909862)
		(width 0.088646)
		(layer "In11.Cu")
		(net "M_H_CPU1_SB_DQS_DP<0>")
	)
	(segment
		(start 168.859962 -225.528378)
		(end 168.223692 -226.164648)
		(width 0.18288)
		(layer "In11.Cu")
		(net "M_H_CPU1_SB_DQS_DP<0>")
	)
	(segment
		(start 194.266312 -225.424746)
		(end 193.964814 -225.424746)
		(width 0.18288)
		(layer "In11.Cu")
		(net "M_H_CPU1_SB_DQS_DP<0>")
	)
	(segment
		(start 162.045142 -226.640898)
		(end 161.592514 -226.640898)
		(width 0.18288)
		(layer "In11.Cu")
		(net "M_H_CPU1_SB_DQS_DP<0>")
	)
	(segment
		(start 140.045694 -237.850172)
		(end 138.42492 -237.850172)
		(width 0.088646)
		(layer "In11.Cu")
		(net "M_H_CPU1_SB_DQS_DP<0>")
	)
	(segment
		(start 202.971146 -228.766624)
		(end 202.705208 -228.500686)
		(width 0.18288)
		(layer "In11.Cu")
		(net "M_H_CPU1_SB_DQS_DP<0>")
	)
	(segment
		(start 131.658614 -237.901226)
		(end 131.643882 -237.909862)
		(width 0.088646)
		(layer "In11.Cu")
		(net "M_H_CPU1_SB_DQS_DP<0>")
	)
	(segment
		(start 158.909258 -227.226114)
		(end 158.16326 -227.226114)
		(width 0.18288)
		(layer "In11.Cu")
		(net "M_H_CPU1_SB_DQS_DP<0>")
	)
	(segment
		(start 195.686934 -226.362768)
		(end 195.204334 -226.362768)
		(width 0.18288)
		(layer "In11.Cu")
		(net "M_H_CPU1_SB_DQS_DP<0>")
	)
	(segment
		(start 164.497258 -225.704146)
		(end 163.81349 -225.704146)
		(width 0.18288)
		(layer "In11.Cu")
		(net "M_H_CPU1_SB_DQS_DP<0>")
	)
	(segment
		(start 173.024038 -225.791014)
		(end 172.563282 -225.791014)
		(width 0.18288)
		(layer "In11.Cu")
		(net "M_H_CPU1_SB_DQS_DP<0>")
	)
	(segment
		(start 122.91822 -237.411768)
		(end 122.917966 -237.411514)
		(width 0.088646)
		(layer "In11.Cu")
		(net "M_H_CPU1_SB_DQS_DP<0>")
	)
	(segment
		(start 172.563282 -225.791014)
		(end 172.300646 -225.528378)
		(width 0.18288)
		(layer "In11.Cu")
		(net "M_H_CPU1_SB_DQS_DP<0>")
	)
	(segment
		(start 174.094394 -225.526346)
		(end 173.288706 -225.526346)
		(width 0.18288)
		(layer "In11.Cu")
		(net "M_H_CPU1_SB_DQS_DP<0>")
	)
	(segment
		(start 123.15444 -237.411768)
		(end 122.91822 -237.411768)
		(width 0.088646)
		(layer "In11.Cu")
		(net "M_H_CPU1_SB_DQS_DP<0>")
	)
	(segment
		(start 161.315908 -226.364292)
		(end 159.77108 -226.364292)
		(width 0.18288)
		(layer "In11.Cu")
		(net "M_H_CPU1_SB_DQS_DP<0>")
	)
	(segment
		(start 123.575318 -237.901226)
		(end 123.45162 -237.83036)
		(width 0.088646)
		(layer "In11.Cu")
		(net "M_H_CPU1_SB_DQS_DP<0>")
	)
	(segment
		(start 190.63462 -224.409)
		(end 189.737746 -224.409)
		(width 0.18288)
		(layer "In11.Cu")
		(net "M_H_CPU1_SB_DQS_DP<0>")
	)
	(segment
		(start 162.30981 -226.37623)
		(end 162.045142 -226.640898)
		(width 0.18288)
		(layer "In11.Cu")
		(net "M_H_CPU1_SB_DQS_DP<0>")
	)
	(segment
		(start 183.1594 -224.484946)
		(end 179.714906 -224.484946)
		(width 0.18288)
		(layer "In11.Cu")
		(net "M_H_CPU1_SB_DQS_DP<0>")
	)
	(segment
		(start 126.020068 -237.901226)
		(end 126.009654 -237.907322)
		(width 0.088646)
		(layer "In11.Cu")
		(net "M_H_CPU1_SB_DQS_DP<0>")
	)
	(segment
		(start 202.261216 -228.500686)
		(end 201.83983 -228.0793)
		(width 0.18288)
		(layer "In11.Cu")
		(net "M_H_CPU1_SB_DQS_DP<0>")
	)
	(segment
		(start 178.558698 -224.053146)
		(end 177.935636 -224.676208)
		(width 0.18288)
		(layer "In11.Cu")
		(net "M_H_CPU1_SB_DQS_DP<0>")
	)
	(segment
		(start 157.498542 -227.489004)
		(end 157.224476 -227.214938)
		(width 0.18288)
		(layer "In11.Cu")
		(net "M_H_CPU1_SB_DQS_DP<0>")
	)
	(segment
		(start 176.65065 -224.940876)
		(end 176.425098 -224.715324)
		(width 0.18288)
		(layer "In11.Cu")
		(net "M_H_CPU1_SB_DQS_DP<0>")
	)
	(segment
		(start 188.111638 -224.090992)
		(end 187.691014 -224.090992)
		(width 0.18288)
		(layer "In11.Cu")
		(net "M_H_CPU1_SB_DQS_DP<0>")
	)
	(segment
		(start 189.15507 -223.826324)
		(end 188.376306 -223.826324)
		(width 0.18288)
		(layer "In11.Cu")
		(net "M_H_CPU1_SB_DQS_DP<0>")
	)
	(segment
		(start 126.959614 -237.901226)
		(end 126.9492 -237.907322)
		(width 0.088646)
		(layer "In11.Cu")
		(net "M_H_CPU1_SB_DQS_DP<0>")
	)
	(segment
		(start 157.90037 -227.489004)
		(end 157.498542 -227.489004)
		(width 0.18288)
		(layer "In11.Cu")
		(net "M_H_CPU1_SB_DQS_DP<0>")
	)
	(segment
		(start 193.964814 -225.424746)
		(end 193.216276 -224.676208)
		(width 0.18288)
		(layer "In11.Cu")
		(net "M_H_CPU1_SB_DQS_DP<0>")
	)
	(segment
		(start 168.223692 -226.164648)
		(end 164.95776 -226.164648)
		(width 0.18288)
		(layer "In11.Cu")
		(net "M_H_CPU1_SB_DQS_DP<0>")
	)
	(segment
		(start 157.224476 -227.214938)
		(end 155.388056 -227.214938)
		(width 0.18288)
		(layer "In11.Cu")
		(net "M_H_CPU1_SB_DQS_DP<0>")
	)
	(segment
		(start 192.476374 -224.676208)
		(end 192.211706 -224.940876)
		(width 0.18288)
		(layer "In11.Cu")
		(net "M_H_CPU1_SB_DQS_DP<0>")
	)
	(segment
		(start 190.928244 -224.702624)
		(end 190.63462 -224.409)
		(width 0.18288)
		(layer "In11.Cu")
		(net "M_H_CPU1_SB_DQS_DP<0>")
	)
	(segment
		(start 202.705208 -228.500686)
		(end 202.261216 -228.500686)
		(width 0.18288)
		(layer "In11.Cu")
		(net "M_H_CPU1_SB_DQS_DP<0>")
	)
	(segment
		(start 189.737746 -224.409)
		(end 189.15507 -223.826324)
		(width 0.18288)
		(layer "In11.Cu")
		(net "M_H_CPU1_SB_DQS_DP<0>")
	)
	(segment
		(start 174.905416 -224.715324)
		(end 174.094394 -225.526346)
		(width 0.18288)
		(layer "In11.Cu")
		(net "M_H_CPU1_SB_DQS_DP<0>")
	)
	(segment
		(start 161.592514 -226.640898)
		(end 161.315908 -226.364292)
		(width 0.18288)
		(layer "In11.Cu")
		(net "M_H_CPU1_SB_DQS_DP<0>")
	)
	(segment
		(start 127.899414 -237.901226)
		(end 127.884682 -237.909862)
		(width 0.088646)
		(layer "In11.Cu")
		(net "M_H_CPU1_SB_DQS_DP<0>")
	)
	(segment
		(start 177.388774 -224.676208)
		(end 177.124106 -224.940876)
		(width 0.18288)
		(layer "In11.Cu")
		(net "M_H_CPU1_SB_DQS_DP<0>")
	)
	(segment
		(start 123.219972 -237.49508)
		(end 123.219972 -237.4773)
		(width 0.088646)
		(layer "In11.Cu")
		(net "M_H_CPU1_SB_DQS_DP<0>")
	)
	(segment
		(start 141.103096 -237.445804)
		(end 141.043152 -237.38586)
		(width 0.088646)
		(layer "In11.Cu")
		(net "M_H_CPU1_SB_DQS_DP<0>")
	)
	(segment
		(start 158.16326 -227.226114)
		(end 157.90037 -227.489004)
		(width 0.18288)
		(layer "In11.Cu")
		(net "M_H_CPU1_SB_DQS_DP<0>")
	)
	(segment
		(start 177.124106 -224.940876)
		(end 176.65065 -224.940876)
		(width 0.18288)
		(layer "In11.Cu")
		(net "M_H_CPU1_SB_DQS_DP<0>")
	)
	(segment
		(start 197.403466 -228.0793)
		(end 195.686934 -226.362768)
		(width 0.18288)
		(layer "In11.Cu")
		(net "M_H_CPU1_SB_DQS_DP<0>")
	)
	(segment
		(start 193.216276 -224.676208)
		(end 192.476374 -224.676208)
		(width 0.18288)
		(layer "In11.Cu")
		(net "M_H_CPU1_SB_DQS_DP<0>")
	)
	(segment
		(start 141.043152 -237.38586)
		(end 140.510006 -237.38586)
		(width 0.088646)
		(layer "In11.Cu")
		(net "M_H_CPU1_SB_DQS_DP<0>")
	)
	(segment
		(start 135.418068 -237.901226)
		(end 135.417814 -237.901226)
		(width 0.088646)
		(layer "In11.Cu")
		(net "M_H_CPU1_SB_DQS_DP<0>")
	)
	(segment
		(start 123.219972 -237.4773)
		(end 123.15444 -237.411768)
		(width 0.088646)
		(layer "In11.Cu")
		(net "M_H_CPU1_SB_DQS_DP<0>")
	)
	(segment
		(start 187.410598 -223.810576)
		(end 183.83377 -223.810576)
		(width 0.18288)
		(layer "In11.Cu")
		(net "M_H_CPU1_SB_DQS_DP<0>")
	)
	(segment
		(start 195.204334 -226.362768)
		(end 194.266312 -225.424746)
		(width 0.18288)
		(layer "In11.Cu")
		(net "M_H_CPU1_SB_DQS_DP<0>")
	)
	(arc
		(start 137.297668 -237.901226)
		(mid 137.014966 -237.976968)
		(end 136.732264 -237.901226)
		(width 0.088646)
		(layer "In11.Cu")
		(net "M_H_CPU1_SB_DQS_DP<0>")
	)
	(arc
		(start 126.009654 -237.907322)
		(mid 125.731222 -237.977168)
		(end 125.45441 -237.901226)
		(width 0.088646)
		(layer "In11.Cu")
		(net "M_H_CPU1_SB_DQS_DP<0>")
	)
	(arc
		(start 131.09321 -237.901226)
		(mid 130.906012 -237.851083)
		(end 130.718814 -237.901226)
		(width 0.088646)
		(layer "In11.Cu")
		(net "M_H_CPU1_SB_DQS_DP<0>")
	)
	(arc
		(start 138.42492 -237.850172)
		(mid 138.327839 -237.863368)
		(end 138.237468 -237.901226)
		(width 0.088646)
		(layer "In11.Cu")
		(net "M_H_CPU1_SB_DQS_DP<0>")
	)
	(arc
		(start 137.672064 -237.901226)
		(mid 137.484866 -237.851083)
		(end 137.297668 -237.901226)
		(width 0.088646)
		(layer "In11.Cu")
		(net "M_H_CPU1_SB_DQS_DP<0>")
	)
	(arc
		(start 132.588254 -237.907322)
		(mid 132.309822 -237.977168)
		(end 132.03301 -237.901226)
		(width 0.088646)
		(layer "In11.Cu")
		(net "M_H_CPU1_SB_DQS_DP<0>")
	)
	(arc
		(start 132.973064 -237.901226)
		(mid 132.785866 -237.851083)
		(end 132.598668 -237.901226)
		(width 0.088646)
		(layer "In11.Cu")
		(net "M_H_CPU1_SB_DQS_DP<0>")
	)
	(arc
		(start 129.764282 -237.909862)
		(mid 129.487807 -237.977182)
		(end 129.21361 -237.901226)
		(width 0.088646)
		(layer "In11.Cu")
		(net "M_H_CPU1_SB_DQS_DP<0>")
	)
	(arc
		(start 134.852664 -237.901226)
		(mid 134.665466 -237.851083)
		(end 134.478268 -237.901226)
		(width 0.088646)
		(layer "In11.Cu")
		(net "M_H_CPU1_SB_DQS_DP<0>")
	)
	(arc
		(start 123.45162 -237.83036)
		(mid 123.299356 -237.690367)
		(end 123.22302 -237.498128)
		(width 0.088646)
		(layer "In11.Cu")
		(net "M_H_CPU1_SB_DQS_DP<0>")
	)
	(arc
		(start 133.912864 -237.901226)
		(mid 133.725666 -237.851083)
		(end 133.538468 -237.901226)
		(width 0.088646)
		(layer "In11.Cu")
		(net "M_H_CPU1_SB_DQS_DP<0>")
	)
	(arc
		(start 128.27381 -237.901226)
		(mid 128.086612 -237.851083)
		(end 127.899414 -237.901226)
		(width 0.088646)
		(layer "In11.Cu")
		(net "M_H_CPU1_SB_DQS_DP<0>")
	)
	(arc
		(start 132.03301 -237.901226)
		(mid 131.845812 -237.851083)
		(end 131.658614 -237.901226)
		(width 0.088646)
		(layer "In11.Cu")
		(net "M_H_CPU1_SB_DQS_DP<0>")
	)
	(arc
		(start 129.21361 -237.901226)
		(mid 129.026412 -237.851083)
		(end 128.839214 -237.901226)
		(width 0.088646)
		(layer "In11.Cu")
		(net "M_H_CPU1_SB_DQS_DP<0>")
	)
	(arc
		(start 126.394464 -237.901226)
		(mid 126.207266 -237.851083)
		(end 126.020068 -237.901226)
		(width 0.088646)
		(layer "In11.Cu")
		(net "M_H_CPU1_SB_DQS_DP<0>")
	)
	(arc
		(start 138.237468 -237.901226)
		(mid 137.954766 -237.976968)
		(end 137.672064 -237.901226)
		(width 0.088646)
		(layer "In11.Cu")
		(net "M_H_CPU1_SB_DQS_DP<0>")
	)
	(arc
		(start 127.33401 -237.901226)
		(mid 127.146812 -237.851083)
		(end 126.959614 -237.901226)
		(width 0.088646)
		(layer "In11.Cu")
		(net "M_H_CPU1_SB_DQS_DP<0>")
	)
	(arc
		(start 136.357868 -237.901226)
		(mid 136.075166 -237.976968)
		(end 135.792464 -237.901226)
		(width 0.088646)
		(layer "In11.Cu")
		(net "M_H_CPU1_SB_DQS_DP<0>")
	)
	(arc
		(start 133.538468 -237.901226)
		(mid 133.264269 -237.977061)
		(end 132.987796 -237.909862)
		(width 0.088646)
		(layer "In11.Cu")
		(net "M_H_CPU1_SB_DQS_DP<0>")
	)
	(arc
		(start 128.824482 -237.909862)
		(mid 128.548007 -237.977182)
		(end 128.27381 -237.901226)
		(width 0.088646)
		(layer "In11.Cu")
		(net "M_H_CPU1_SB_DQS_DP<0>")
	)
	(arc
		(start 124.51461 -237.901226)
		(mid 124.327412 -237.851083)
		(end 124.140214 -237.901226)
		(width 0.088646)
		(layer "In11.Cu")
		(net "M_H_CPU1_SB_DQS_DP<0>")
	)
	(arc
		(start 136.732264 -237.901226)
		(mid 136.545066 -237.851083)
		(end 136.357868 -237.901226)
		(width 0.088646)
		(layer "In11.Cu")
		(net "M_H_CPU1_SB_DQS_DP<0>")
	)
	(arc
		(start 131.643882 -237.909862)
		(mid 131.367407 -237.977182)
		(end 131.09321 -237.901226)
		(width 0.088646)
		(layer "In11.Cu")
		(net "M_H_CPU1_SB_DQS_DP<0>")
	)
	(arc
		(start 124.140214 -237.901226)
		(mid 123.857766 -237.976875)
		(end 123.575318 -237.901226)
		(width 0.088646)
		(layer "In11.Cu")
		(net "M_H_CPU1_SB_DQS_DP<0>")
	)
	(arc
		(start 130.704082 -237.909862)
		(mid 130.427607 -237.977182)
		(end 130.15341 -237.901226)
		(width 0.088646)
		(layer "In11.Cu")
		(net "M_H_CPU1_SB_DQS_DP<0>")
	)
	(arc
		(start 135.792464 -237.901226)
		(mid 135.605266 -237.851083)
		(end 135.418068 -237.901226)
		(width 0.088646)
		(layer "In11.Cu")
		(net "M_H_CPU1_SB_DQS_DP<0>")
	)
	(arc
		(start 134.478268 -237.901226)
		(mid 134.195566 -237.977002)
		(end 133.912864 -237.901226)
		(width 0.088646)
		(layer "In11.Cu")
		(net "M_H_CPU1_SB_DQS_DP<0>")
	)
	(arc
		(start 125.065282 -237.909862)
		(mid 124.788807 -237.977182)
		(end 124.51461 -237.901226)
		(width 0.088646)
		(layer "In11.Cu")
		(net "M_H_CPU1_SB_DQS_DP<0>")
	)
	(arc
		(start 126.9492 -237.907322)
		(mid 126.671022 -237.977014)
		(end 126.394464 -237.901226)
		(width 0.088646)
		(layer "In11.Cu")
		(net "M_H_CPU1_SB_DQS_DP<0>")
	)
	(arc
		(start 135.417814 -237.901226)
		(mid 135.135366 -237.976875)
		(end 134.852918 -237.901226)
		(width 0.088646)
		(layer "In11.Cu")
		(net "M_H_CPU1_SB_DQS_DP<0>")
	)
	(arc
		(start 130.15341 -237.901226)
		(mid 129.966212 -237.851083)
		(end 129.779014 -237.901226)
		(width 0.088646)
		(layer "In11.Cu")
		(net "M_H_CPU1_SB_DQS_DP<0>")
	)
	(arc
		(start 127.884682 -237.909862)
		(mid 127.608207 -237.977182)
		(end 127.33401 -237.901226)
		(width 0.088646)
		(layer "In11.Cu")
		(net "M_H_CPU1_SB_DQS_DP<0>")
	)
	(arc
		(start 125.45441 -237.901226)
		(mid 125.267212 -237.851083)
		(end 125.080014 -237.901226)
		(width 0.088646)
		(layer "In11.Cu")
		(net "M_H_CPU1_SB_DQS_DP<0>")
	)
	(segment
		(start 206.056738 -237.962948)
		(end 206.578454 -237.962948)
		(width 0.20066)
		(layer "F.Cu")
		(net "M_H_CPU1_SB_DQS_DN<9>")
	)
	(segment
		(start 210.047078 -237.917736)
		(end 210.457542 -237.507272)
		(width 0.20066)
		(layer "F.Cu")
		(net "M_H_CPU1_SB_DQS_DN<9>")
	)
	(segment
		(start 204.076046 -237.266734)
		(end 204.624686 -237.266734)
		(width 0.20066)
		(layer "F.Cu")
		(net "M_H_CPU1_SB_DQS_DN<9>")
	)
	(segment
		(start 204.624686 -237.266734)
		(end 204.906372 -237.54842)
		(width 0.20066)
		(layer "F.Cu")
		(net "M_H_CPU1_SB_DQS_DN<9>")
	)
	(segment
		(start 206.578454 -237.962948)
		(end 206.849726 -237.691676)
		(width 0.20066)
		(layer "F.Cu")
		(net "M_H_CPU1_SB_DQS_DN<9>")
	)
	(segment
		(start 207.001618 -237.691676)
		(end 209.181192 -237.691676)
		(width 0.1016)
		(layer "F.Cu")
		(net "M_H_CPU1_SB_DQS_DN<9>")
	)
	(segment
		(start 209.742024 -237.917736)
		(end 210.047078 -237.917736)
		(width 0.20066)
		(layer "F.Cu")
		(net "M_H_CPU1_SB_DQS_DN<9>")
	)
	(segment
		(start 206.849726 -237.691676)
		(end 206.9973 -237.691676)
		(width 0.20066)
		(layer "F.Cu")
		(net "M_H_CPU1_SB_DQS_DN<9>")
	)
	(segment
		(start 211.030566 -237.266734)
		(end 211.619846 -237.266734)
		(width 0.20066)
		(layer "F.Cu")
		(net "M_H_CPU1_SB_DQS_DN<9>")
	)
	(segment
		(start 209.186526 -237.686342)
		(end 209.51063 -237.686342)
		(width 0.20066)
		(layer "F.Cu")
		(net "M_H_CPU1_SB_DQS_DN<9>")
	)
	(segment
		(start 209.181192 -237.691676)
		(end 209.186526 -237.686342)
		(width 0.1016)
		(layer "F.Cu")
		(net "M_H_CPU1_SB_DQS_DN<9>")
	)
	(segment
		(start 205.64221 -237.54842)
		(end 206.056738 -237.962948)
		(width 0.20066)
		(layer "F.Cu")
		(net "M_H_CPU1_SB_DQS_DN<9>")
	)
	(segment
		(start 123.857766 -242.830604)
		(end 123.857766 -242.294918)
		(width 0.20066)
		(layer "F.Cu")
		(net "M_H_CPU1_SB_DQS_DN<9>")
	)
	(segment
		(start 123.857512 -242.830858)
		(end 123.857766 -242.830604)
		(width 0.20066)
		(layer "F.Cu")
		(net "M_H_CPU1_SB_DQS_DN<9>")
	)
	(segment
		(start 204.906372 -237.54842)
		(end 205.64221 -237.54842)
		(width 0.20066)
		(layer "F.Cu")
		(net "M_H_CPU1_SB_DQS_DN<9>")
	)
	(segment
		(start 210.457542 -237.507272)
		(end 210.790028 -237.507272)
		(width 0.20066)
		(layer "F.Cu")
		(net "M_H_CPU1_SB_DQS_DN<9>")
	)
	(segment
		(start 209.51063 -237.686342)
		(end 209.742024 -237.917736)
		(width 0.20066)
		(layer "F.Cu")
		(net "M_H_CPU1_SB_DQS_DN<9>")
	)
	(segment
		(start 202.971146 -237.266734)
		(end 204.076046 -237.266734)
		(width 0.20066)
		(layer "F.Cu")
		(net "M_H_CPU1_SB_DQS_DN<9>")
	)
	(segment
		(start 206.9973 -237.691676)
		(end 207.001618 -237.691676)
		(width 0.101854)
		(layer "F.Cu")
		(net "M_H_CPU1_SB_DQS_DN<9>")
	)
	(segment
		(start 210.790028 -237.507272)
		(end 211.030566 -237.266734)
		(width 0.20066)
		(layer "F.Cu")
		(net "M_H_CPU1_SB_DQS_DN<9>")
	)
	(segment
		(start 147.937982 -243.150644)
		(end 141.103096 -243.150644)
		(width 0.18288)
		(layer "In11.Cu")
		(net "M_H_CPU1_SB_DQS_DN<9>")
	)
	(segment
		(start 190.57112 -237.924086)
		(end 188.913008 -236.265974)
		(width 0.18288)
		(layer "In11.Cu")
		(net "M_H_CPU1_SB_DQS_DN<9>")
	)
	(segment
		(start 191.482472 -237.924086)
		(end 190.57112 -237.924086)
		(width 0.18288)
		(layer "In11.Cu")
		(net "M_H_CPU1_SB_DQS_DN<9>")
	)
	(segment
		(start 167.745664 -236.982254)
		(end 166.490396 -236.982254)
		(width 0.18288)
		(layer "In11.Cu")
		(net "M_H_CPU1_SB_DQS_DN<9>")
	)
	(segment
		(start 176.435258 -235.389674)
		(end 175.071024 -235.389674)
		(width 0.18288)
		(layer "In11.Cu")
		(net "M_H_CPU1_SB_DQS_DN<9>")
	)
	(segment
		(start 163.951412 -236.982254)
		(end 163.826952 -236.857794)
		(width 0.18288)
		(layer "In11.Cu")
		(net "M_H_CPU1_SB_DQS_DN<9>")
	)
	(segment
		(start 166.365936 -236.857794)
		(end 165.817296 -236.857794)
		(width 0.18288)
		(layer "In11.Cu")
		(net "M_H_CPU1_SB_DQS_DN<9>")
	)
	(segment
		(start 163.278312 -236.857794)
		(end 163.153852 -236.982254)
		(width 0.18288)
		(layer "In11.Cu")
		(net "M_H_CPU1_SB_DQS_DN<9>")
	)
	(segment
		(start 202.19035 -237.36808)
		(end 199.928734 -237.36808)
		(width 0.18288)
		(layer "In11.Cu")
		(net "M_H_CPU1_SB_DQS_DN<9>")
	)
	(segment
		(start 199.227694 -237.078266)
		(end 194.111118 -237.078266)
		(width 0.18288)
		(layer "In11.Cu")
		(net "M_H_CPU1_SB_DQS_DN<9>")
	)
	(segment
		(start 137.446004 -243.210334)
		(end 136.944608 -242.708684)
		(width 0.088646)
		(layer "In11.Cu")
		(net "M_H_CPU1_SB_DQS_DN<9>")
	)
	(segment
		(start 188.913008 -236.265974)
		(end 188.351922 -236.265974)
		(width 0.18288)
		(layer "In11.Cu")
		(net "M_H_CPU1_SB_DQS_DN<9>")
	)
	(segment
		(start 168.445688 -236.28223)
		(end 167.745664 -236.982254)
		(width 0.18288)
		(layer "In11.Cu")
		(net "M_H_CPU1_SB_DQS_DN<9>")
	)
	(segment
		(start 134.397496 -242.61064)
		(end 134.382764 -242.619276)
		(width 0.088646)
		(layer "In11.Cu")
		(net "M_H_CPU1_SB_DQS_DN<9>")
	)
	(segment
		(start 124.999496 -242.610894)
		(end 124.984764 -242.61953)
		(width 0.088646)
		(layer "In11.Cu")
		(net "M_H_CPU1_SB_DQS_DN<9>")
	)
	(segment
		(start 179.738274 -235.565696)
		(end 179.259992 -236.043978)
		(width 0.18288)
		(layer "In11.Cu")
		(net "M_H_CPU1_SB_DQS_DN<9>")
	)
	(segment
		(start 188.076586 -235.990638)
		(end 187.615322 -235.990638)
		(width 0.18288)
		(layer "In11.Cu")
		(net "M_H_CPU1_SB_DQS_DN<9>")
	)
	(segment
		(start 199.928734 -237.36808)
		(end 199.227694 -237.078266)
		(width 0.18288)
		(layer "In11.Cu")
		(net "M_H_CPU1_SB_DQS_DN<9>")
	)
	(segment
		(start 202.971146 -237.266734)
		(end 202.68819 -237.54969)
		(width 0.18288)
		(layer "In11.Cu")
		(net "M_H_CPU1_SB_DQS_DN<9>")
	)
	(segment
		(start 183.752998 -235.565696)
		(end 179.738274 -235.565696)
		(width 0.18288)
		(layer "In11.Cu")
		(net "M_H_CPU1_SB_DQS_DN<9>")
	)
	(segment
		(start 184.457848 -236.270546)
		(end 183.752998 -235.565696)
		(width 0.18288)
		(layer "In11.Cu")
		(net "M_H_CPU1_SB_DQS_DN<9>")
	)
	(segment
		(start 174.194216 -236.266482)
		(end 173.26991 -236.266482)
		(width 0.18288)
		(layer "In11.Cu")
		(net "M_H_CPU1_SB_DQS_DN<9>")
	)
	(segment
		(start 178.195224 -235.416598)
		(end 177.388266 -235.416598)
		(width 0.18288)
		(layer "In11.Cu")
		(net "M_H_CPU1_SB_DQS_DN<9>")
	)
	(segment
		(start 160.071562 -236.982254)
		(end 158.857442 -238.196374)
		(width 0.18288)
		(layer "In11.Cu")
		(net "M_H_CPU1_SB_DQS_DN<9>")
	)
	(segment
		(start 194.111118 -237.078266)
		(end 193.22288 -237.966504)
		(width 0.18288)
		(layer "In11.Cu")
		(net "M_H_CPU1_SB_DQS_DN<9>")
	)
	(segment
		(start 127.818896 -242.61064)
		(end 127.804164 -242.619276)
		(width 0.088646)
		(layer "In11.Cu")
		(net "M_H_CPU1_SB_DQS_DN<9>")
	)
	(segment
		(start 141.103096 -243.150644)
		(end 141.043406 -243.210334)
		(width 0.088646)
		(layer "In11.Cu")
		(net "M_H_CPU1_SB_DQS_DN<9>")
	)
	(segment
		(start 187.335414 -236.270546)
		(end 184.457848 -236.270546)
		(width 0.18288)
		(layer "In11.Cu")
		(net "M_H_CPU1_SB_DQS_DN<9>")
	)
	(segment
		(start 165.692836 -236.982254)
		(end 163.951412 -236.982254)
		(width 0.18288)
		(layer "In11.Cu")
		(net "M_H_CPU1_SB_DQS_DN<9>")
	)
	(segment
		(start 172.994574 -235.991146)
		(end 172.552106 -235.991146)
		(width 0.18288)
		(layer "In11.Cu")
		(net "M_H_CPU1_SB_DQS_DN<9>")
	)
	(segment
		(start 177.388266 -235.416598)
		(end 177.11293 -235.141262)
		(width 0.18288)
		(layer "In11.Cu")
		(net "M_H_CPU1_SB_DQS_DN<9>")
	)
	(segment
		(start 123.670568 -242.619276)
		(end 123.661678 -242.614196)
		(width 0.088646)
		(layer "In11.Cu")
		(net "M_H_CPU1_SB_DQS_DN<9>")
	)
	(segment
		(start 126.489714 -242.61953)
		(end 126.4793 -242.613434)
		(width 0.088646)
		(layer "In11.Cu")
		(net "M_H_CPU1_SB_DQS_DN<9>")
	)
	(segment
		(start 163.826952 -236.857794)
		(end 163.278312 -236.857794)
		(width 0.18288)
		(layer "In11.Cu")
		(net "M_H_CPU1_SB_DQS_DN<9>")
	)
	(segment
		(start 187.615322 -235.990638)
		(end 187.335414 -236.270546)
		(width 0.18288)
		(layer "In11.Cu")
		(net "M_H_CPU1_SB_DQS_DN<9>")
	)
	(segment
		(start 131.578096 -242.61064)
		(end 131.563364 -242.619276)
		(width 0.088646)
		(layer "In11.Cu")
		(net "M_H_CPU1_SB_DQS_DN<9>")
	)
	(segment
		(start 123.545092 -242.294918)
		(end 123.857766 -242.294918)
		(width 0.088646)
		(layer "In11.Cu")
		(net "M_H_CPU1_SB_DQS_DN<9>")
	)
	(segment
		(start 128.758696 -242.61064)
		(end 128.743964 -242.619276)
		(width 0.088646)
		(layer "In11.Cu")
		(net "M_H_CPU1_SB_DQS_DN<9>")
	)
	(segment
		(start 129.698496 -242.61064)
		(end 129.683764 -242.619276)
		(width 0.088646)
		(layer "In11.Cu")
		(net "M_H_CPU1_SB_DQS_DN<9>")
	)
	(segment
		(start 165.817296 -236.857794)
		(end 165.692836 -236.982254)
		(width 0.18288)
		(layer "In11.Cu")
		(net "M_H_CPU1_SB_DQS_DN<9>")
	)
	(segment
		(start 152.892252 -238.196374)
		(end 147.937982 -243.150644)
		(width 0.18288)
		(layer "In11.Cu")
		(net "M_H_CPU1_SB_DQS_DN<9>")
	)
	(segment
		(start 202.68819 -237.54969)
		(end 202.37196 -237.54969)
		(width 0.18288)
		(layer "In11.Cu")
		(net "M_H_CPU1_SB_DQS_DN<9>")
	)
	(segment
		(start 123.487688 -242.352322)
		(end 123.545092 -242.294918)
		(width 0.088646)
		(layer "In11.Cu")
		(net "M_H_CPU1_SB_DQS_DN<9>")
	)
	(segment
		(start 177.11293 -235.141262)
		(end 176.68367 -235.141262)
		(width 0.18288)
		(layer "In11.Cu")
		(net "M_H_CPU1_SB_DQS_DN<9>")
	)
	(segment
		(start 166.490396 -236.982254)
		(end 166.365936 -236.857794)
		(width 0.18288)
		(layer "In11.Cu")
		(net "M_H_CPU1_SB_DQS_DN<9>")
	)
	(segment
		(start 188.351922 -236.265974)
		(end 188.076586 -235.990638)
		(width 0.18288)
		(layer "In11.Cu")
		(net "M_H_CPU1_SB_DQS_DN<9>")
	)
	(segment
		(start 172.552106 -235.991146)
		(end 172.261022 -236.28223)
		(width 0.18288)
		(layer "In11.Cu")
		(net "M_H_CPU1_SB_DQS_DN<9>")
	)
	(segment
		(start 126.874524 -242.613434)
		(end 126.86411 -242.61953)
		(width 0.088646)
		(layer "In11.Cu")
		(net "M_H_CPU1_SB_DQS_DN<9>")
	)
	(segment
		(start 163.153852 -236.982254)
		(end 160.071562 -236.982254)
		(width 0.18288)
		(layer "In11.Cu")
		(net "M_H_CPU1_SB_DQS_DN<9>")
	)
	(segment
		(start 178.822604 -236.043978)
		(end 178.195224 -235.416598)
		(width 0.18288)
		(layer "In11.Cu")
		(net "M_H_CPU1_SB_DQS_DN<9>")
	)
	(segment
		(start 172.261022 -236.28223)
		(end 168.445688 -236.28223)
		(width 0.18288)
		(layer "In11.Cu")
		(net "M_H_CPU1_SB_DQS_DN<9>")
	)
	(segment
		(start 173.26991 -236.266482)
		(end 172.994574 -235.991146)
		(width 0.18288)
		(layer "In11.Cu")
		(net "M_H_CPU1_SB_DQS_DN<9>")
	)
	(segment
		(start 192.468246 -237.966504)
		(end 192.19291 -237.691168)
		(width 0.18288)
		(layer "In11.Cu")
		(net "M_H_CPU1_SB_DQS_DN<9>")
	)
	(segment
		(start 176.68367 -235.141262)
		(end 176.435258 -235.389674)
		(width 0.18288)
		(layer "In11.Cu")
		(net "M_H_CPU1_SB_DQS_DN<9>")
	)
	(segment
		(start 193.22288 -237.966504)
		(end 192.468246 -237.966504)
		(width 0.18288)
		(layer "In11.Cu")
		(net "M_H_CPU1_SB_DQS_DN<9>")
	)
	(segment
		(start 202.37196 -237.54969)
		(end 202.19035 -237.36808)
		(width 0.18288)
		(layer "In11.Cu")
		(net "M_H_CPU1_SB_DQS_DN<9>")
	)
	(segment
		(start 158.857442 -238.196374)
		(end 152.892252 -238.196374)
		(width 0.18288)
		(layer "In11.Cu")
		(net "M_H_CPU1_SB_DQS_DN<9>")
	)
	(segment
		(start 179.259992 -236.043978)
		(end 178.822604 -236.043978)
		(width 0.18288)
		(layer "In11.Cu")
		(net "M_H_CPU1_SB_DQS_DN<9>")
	)
	(segment
		(start 175.071024 -235.389674)
		(end 174.194216 -236.266482)
		(width 0.18288)
		(layer "In11.Cu")
		(net "M_H_CPU1_SB_DQS_DN<9>")
	)
	(segment
		(start 191.71539 -237.691168)
		(end 191.482472 -237.924086)
		(width 0.18288)
		(layer "In11.Cu")
		(net "M_H_CPU1_SB_DQS_DN<9>")
	)
	(segment
		(start 192.19291 -237.691168)
		(end 191.71539 -237.691168)
		(width 0.18288)
		(layer "In11.Cu")
		(net "M_H_CPU1_SB_DQS_DN<9>")
	)
	(segment
		(start 141.043406 -243.210334)
		(end 137.446004 -243.210334)
		(width 0.088646)
		(layer "In11.Cu")
		(net "M_H_CPU1_SB_DQS_DN<9>")
	)
	(segment
		(start 130.638296 -242.61064)
		(end 130.623564 -242.619276)
		(width 0.088646)
		(layer "In11.Cu")
		(net "M_H_CPU1_SB_DQS_DN<9>")
	)
	(arc
		(start 125.924564 -242.61953)
		(mid 125.737366 -242.669673)
		(end 125.550168 -242.61953)
		(width 0.088646)
		(layer "In11.Cu")
		(net "M_H_CPU1_SB_DQS_DN<9>")
	)
	(arc
		(start 136.944608 -242.708684)
		(mid 136.932707 -242.697206)
		(end 136.920478 -242.686078)
		(width 0.088646)
		(layer "In11.Cu")
		(net "M_H_CPU1_SB_DQS_DN<9>")
	)
	(arc
		(start 124.610368 -242.61953)
		(mid 124.336169 -242.543695)
		(end 124.059696 -242.610894)
		(width 0.088646)
		(layer "In11.Cu")
		(net "M_H_CPU1_SB_DQS_DN<9>")
	)
	(arc
		(start 136.262364 -242.619276)
		(mid 136.075166 -242.669419)
		(end 135.887968 -242.619276)
		(width 0.088646)
		(layer "In11.Cu")
		(net "M_H_CPU1_SB_DQS_DN<9>")
	)
	(arc
		(start 128.369568 -242.619276)
		(mid 128.095339 -242.543351)
		(end 127.818896 -242.61064)
		(width 0.088646)
		(layer "In11.Cu")
		(net "M_H_CPU1_SB_DQS_DN<9>")
	)
	(arc
		(start 129.309368 -242.619276)
		(mid 129.035139 -242.543351)
		(end 128.758696 -242.61064)
		(width 0.088646)
		(layer "In11.Cu")
		(net "M_H_CPU1_SB_DQS_DN<9>")
	)
	(arc
		(start 123.661678 -242.614196)
		(mid 123.545939 -242.502372)
		(end 123.487688 -242.352322)
		(width 0.088646)
		(layer "In11.Cu")
		(net "M_H_CPU1_SB_DQS_DN<9>")
	)
	(arc
		(start 124.984764 -242.61953)
		(mid 124.797566 -242.669673)
		(end 124.610368 -242.61953)
		(width 0.088646)
		(layer "In11.Cu")
		(net "M_H_CPU1_SB_DQS_DN<9>")
	)
	(arc
		(start 131.188968 -242.619276)
		(mid 130.914739 -242.543351)
		(end 130.638296 -242.61064)
		(width 0.088646)
		(layer "In11.Cu")
		(net "M_H_CPU1_SB_DQS_DN<9>")
	)
	(arc
		(start 124.035058 -242.624864)
		(mid 123.949169 -242.658097)
		(end 123.857766 -242.669314)
		(width 0.088646)
		(layer "In11.Cu")
		(net "M_H_CPU1_SB_DQS_DN<9>")
	)
	(arc
		(start 134.008368 -242.619276)
		(mid 133.725666 -242.543534)
		(end 133.442964 -242.619276)
		(width 0.088646)
		(layer "In11.Cu")
		(net "M_H_CPU1_SB_DQS_DN<9>")
	)
	(arc
		(start 134.948168 -242.619276)
		(mid 134.673939 -242.543351)
		(end 134.397496 -242.61064)
		(width 0.088646)
		(layer "In11.Cu")
		(net "M_H_CPU1_SB_DQS_DN<9>")
	)
	(arc
		(start 124.052584 -242.614704)
		(mid 124.043891 -242.619904)
		(end 124.035058 -242.624864)
		(width 0.088646)
		(layer "In11.Cu")
		(net "M_H_CPU1_SB_DQS_DN<9>")
	)
	(arc
		(start 133.442964 -242.619276)
		(mid 133.255766 -242.669419)
		(end 133.068568 -242.619276)
		(width 0.088646)
		(layer "In11.Cu")
		(net "M_H_CPU1_SB_DQS_DN<9>")
	)
	(arc
		(start 126.4793 -242.613434)
		(mid 126.201122 -242.543711)
		(end 125.924564 -242.61953)
		(width 0.088646)
		(layer "In11.Cu")
		(net "M_H_CPU1_SB_DQS_DN<9>")
	)
	(arc
		(start 130.249168 -242.619276)
		(mid 129.974939 -242.543351)
		(end 129.698496 -242.61064)
		(width 0.088646)
		(layer "In11.Cu")
		(net "M_H_CPU1_SB_DQS_DN<9>")
	)
	(arc
		(start 135.322564 -242.619276)
		(mid 135.135366 -242.669419)
		(end 134.948168 -242.619276)
		(width 0.088646)
		(layer "In11.Cu")
		(net "M_H_CPU1_SB_DQS_DN<9>")
	)
	(arc
		(start 124.059696 -242.610894)
		(mid 124.056149 -242.612815)
		(end 124.052584 -242.614704)
		(width 0.088646)
		(layer "In11.Cu")
		(net "M_H_CPU1_SB_DQS_DN<9>")
	)
	(arc
		(start 132.128768 -242.619276)
		(mid 131.854539 -242.543351)
		(end 131.578096 -242.61064)
		(width 0.088646)
		(layer "In11.Cu")
		(net "M_H_CPU1_SB_DQS_DN<9>")
	)
	(arc
		(start 125.550168 -242.61953)
		(mid 125.275969 -242.543695)
		(end 124.999496 -242.610894)
		(width 0.088646)
		(layer "In11.Cu")
		(net "M_H_CPU1_SB_DQS_DN<9>")
	)
	(arc
		(start 129.683764 -242.619276)
		(mid 129.496566 -242.669419)
		(end 129.309368 -242.619276)
		(width 0.088646)
		(layer "In11.Cu")
		(net "M_H_CPU1_SB_DQS_DN<9>")
	)
	(arc
		(start 136.920478 -242.686078)
		(mid 136.602203 -242.546385)
		(end 136.262364 -242.619276)
		(width 0.088646)
		(layer "In11.Cu")
		(net "M_H_CPU1_SB_DQS_DN<9>")
	)
	(arc
		(start 130.623564 -242.619276)
		(mid 130.436366 -242.669419)
		(end 130.249168 -242.619276)
		(width 0.088646)
		(layer "In11.Cu")
		(net "M_H_CPU1_SB_DQS_DN<9>")
	)
	(arc
		(start 135.887968 -242.619276)
		(mid 135.605266 -242.543534)
		(end 135.322564 -242.619276)
		(width 0.088646)
		(layer "In11.Cu")
		(net "M_H_CPU1_SB_DQS_DN<9>")
	)
	(arc
		(start 134.382764 -242.619276)
		(mid 134.195566 -242.669419)
		(end 134.008368 -242.619276)
		(width 0.088646)
		(layer "In11.Cu")
		(net "M_H_CPU1_SB_DQS_DN<9>")
	)
	(arc
		(start 123.857766 -242.669314)
		(mid 123.761585 -242.656816)
		(end 123.671838 -242.620038)
		(width 0.088646)
		(layer "In11.Cu")
		(net "M_H_CPU1_SB_DQS_DN<9>")
	)
	(arc
		(start 126.86411 -242.61953)
		(mid 126.676912 -242.669673)
		(end 126.489714 -242.61953)
		(width 0.088646)
		(layer "In11.Cu")
		(net "M_H_CPU1_SB_DQS_DN<9>")
	)
	(arc
		(start 133.068568 -242.619276)
		(mid 132.785866 -242.543534)
		(end 132.503164 -242.619276)
		(width 0.088646)
		(layer "In11.Cu")
		(net "M_H_CPU1_SB_DQS_DN<9>")
	)
	(arc
		(start 128.743964 -242.619276)
		(mid 128.556766 -242.669419)
		(end 128.369568 -242.619276)
		(width 0.088646)
		(layer "In11.Cu")
		(net "M_H_CPU1_SB_DQS_DN<9>")
	)
	(arc
		(start 131.563364 -242.619276)
		(mid 131.376166 -242.669419)
		(end 131.188968 -242.619276)
		(width 0.088646)
		(layer "In11.Cu")
		(net "M_H_CPU1_SB_DQS_DN<9>")
	)
	(arc
		(start 127.804164 -242.619276)
		(mid 127.616995 -242.670167)
		(end 127.429768 -242.61953)
		(width 0.088646)
		(layer "In11.Cu")
		(net "M_H_CPU1_SB_DQS_DN<9>")
	)
	(arc
		(start 123.671838 -242.620038)
		(mid 123.671203 -242.619657)
		(end 123.670568 -242.619276)
		(width 0.088646)
		(layer "In11.Cu")
		(net "M_H_CPU1_SB_DQS_DN<9>")
	)
	(arc
		(start 132.503164 -242.619276)
		(mid 132.315966 -242.669419)
		(end 132.128768 -242.619276)
		(width 0.088646)
		(layer "In11.Cu")
		(net "M_H_CPU1_SB_DQS_DN<9>")
	)
	(arc
		(start 127.429768 -242.61953)
		(mid 127.152955 -242.54366)
		(end 126.874524 -242.613434)
		(width 0.088646)
		(layer "In11.Cu")
		(net "M_H_CPU1_SB_DQS_DN<9>")
	)
	(segment
		(start 209.461354 -199.595486)
		(end 209.886296 -199.170544)
		(width 0.20066)
		(layer "F.Cu")
		(net "M_H_CPU1_SB_DQS_DN<8>")
	)
	(segment
		(start 215.216232 -199.866758)
		(end 215.719914 -199.866758)
		(width 0.20066)
		(layer "F.Cu")
		(net "M_H_CPU1_SB_DQS_DN<8>")
	)
	(segment
		(start 210.286092 -199.447912)
		(end 210.598258 -199.447912)
		(width 0.20066)
		(layer "F.Cu")
		(net "M_H_CPU1_SB_DQS_DN<8>")
	)
	(segment
		(start 213.234778 -199.166988)
		(end 213.724744 -199.166988)
		(width 0.20066)
		(layer "F.Cu")
		(net "M_H_CPU1_SB_DQS_DN<8>")
	)
	(segment
		(start 214.17026 -199.612504)
		(end 214.961978 -199.612504)
		(width 0.20066)
		(layer "F.Cu")
		(net "M_H_CPU1_SB_DQS_DN<8>")
	)
	(segment
		(start 212.619336 -199.441816)
		(end 212.630258 -199.452738)
		(width 0.1016)
		(layer "F.Cu")
		(net "M_H_CPU1_SB_DQS_DN<8>")
	)
	(segment
		(start 208.176114 -199.866758)
		(end 208.70672 -199.866758)
		(width 0.20066)
		(layer "F.Cu")
		(net "M_H_CPU1_SB_DQS_DN<8>")
	)
	(segment
		(start 210.603084 -199.447912)
		(end 210.60918 -199.441816)
		(width 0.1016)
		(layer "F.Cu")
		(net "M_H_CPU1_SB_DQS_DN<8>")
	)
	(segment
		(start 208.70672 -199.866758)
		(end 208.977992 -199.595486)
		(width 0.20066)
		(layer "F.Cu")
		(net "M_H_CPU1_SB_DQS_DN<8>")
	)
	(segment
		(start 208.977992 -199.595486)
		(end 209.461354 -199.595486)
		(width 0.20066)
		(layer "F.Cu")
		(net "M_H_CPU1_SB_DQS_DN<8>")
	)
	(segment
		(start 212.949028 -199.452738)
		(end 213.234778 -199.166988)
		(width 0.20066)
		(layer "F.Cu")
		(net "M_H_CPU1_SB_DQS_DN<8>")
	)
	(segment
		(start 124.797312 -228.1809)
		(end 124.797566 -228.180646)
		(width 0.20066)
		(layer "F.Cu")
		(net "M_H_CPU1_SB_DQS_DN<8>")
	)
	(segment
		(start 212.630258 -199.452738)
		(end 212.949028 -199.452738)
		(width 0.20066)
		(layer "F.Cu")
		(net "M_H_CPU1_SB_DQS_DN<8>")
	)
	(segment
		(start 210.598258 -199.447912)
		(end 210.603084 -199.447912)
		(width 0.101854)
		(layer "F.Cu")
		(net "M_H_CPU1_SB_DQS_DN<8>")
	)
	(segment
		(start 209.886296 -199.170544)
		(end 210.008724 -199.170544)
		(width 0.20066)
		(layer "F.Cu")
		(net "M_H_CPU1_SB_DQS_DN<8>")
	)
	(segment
		(start 210.60918 -199.441816)
		(end 212.619336 -199.441816)
		(width 0.1016)
		(layer "F.Cu")
		(net "M_H_CPU1_SB_DQS_DN<8>")
	)
	(segment
		(start 124.797566 -228.180646)
		(end 124.797566 -227.64496)
		(width 0.20066)
		(layer "F.Cu")
		(net "M_H_CPU1_SB_DQS_DN<8>")
	)
	(segment
		(start 213.724744 -199.166988)
		(end 214.17026 -199.612504)
		(width 0.20066)
		(layer "F.Cu")
		(net "M_H_CPU1_SB_DQS_DN<8>")
	)
	(segment
		(start 207.071214 -199.866758)
		(end 208.176114 -199.866758)
		(width 0.20066)
		(layer "F.Cu")
		(net "M_H_CPU1_SB_DQS_DN<8>")
	)
	(segment
		(start 210.008724 -199.170544)
		(end 210.286092 -199.447912)
		(width 0.20066)
		(layer "F.Cu")
		(net "M_H_CPU1_SB_DQS_DN<8>")
	)
	(segment
		(start 214.961978 -199.612504)
		(end 215.216232 -199.866758)
		(width 0.20066)
		(layer "F.Cu")
		(net "M_H_CPU1_SB_DQS_DN<8>")
	)
	(segment
		(start 126.38913 -228.13137)
		(end 126.282958 -228.073966)
		(width 0.088646)
		(layer "In11.Cu")
		(net "M_H_CPU1_SB_DQS_DN<8>")
	)
	(segment
		(start 187.309506 -201.711306)
		(end 184.404 -201.711306)
		(width 0.18288)
		(layer "In11.Cu")
		(net "M_H_CPU1_SB_DQS_DN<8>")
	)
	(segment
		(start 172.250354 -201.739754)
		(end 170.40733 -201.739754)
		(width 0.18288)
		(layer "In11.Cu")
		(net "M_H_CPU1_SB_DQS_DN<8>")
	)
	(segment
		(start 125.295914 -227.64496)
		(end 124.797566 -227.64496)
		(width 0.088646)
		(layer "In11.Cu")
		(net "M_H_CPU1_SB_DQS_DN<8>")
	)
	(segment
		(start 129.779014 -228.134672)
		(end 129.764282 -228.143308)
		(width 0.088646)
		(layer "In11.Cu")
		(net "M_H_CPU1_SB_DQS_DN<8>")
	)
	(segment
		(start 188.111638 -201.991214)
		(end 187.589414 -201.991214)
		(width 0.18288)
		(layer "In11.Cu")
		(net "M_H_CPU1_SB_DQS_DN<8>")
	)
	(segment
		(start 125.370082 -227.719128)
		(end 125.295914 -227.64496)
		(width 0.088646)
		(layer "In11.Cu")
		(net "M_H_CPU1_SB_DQS_DN<8>")
	)
	(segment
		(start 194.995038 -201.120502)
		(end 194.592194 -201.523346)
		(width 0.18288)
		(layer "In11.Cu")
		(net "M_H_CPU1_SB_DQS_DN<8>")
	)
	(segment
		(start 199.601074 -201.725276)
		(end 198.141082 -201.120502)
		(width 0.18288)
		(layer "In11.Cu")
		(net "M_H_CPU1_SB_DQS_DN<8>")
	)
	(segment
		(start 125.676914 -228.037136)
		(end 125.550168 -227.969318)
		(width 0.088646)
		(layer "In11.Cu")
		(net "M_H_CPU1_SB_DQS_DN<8>")
	)
	(segment
		(start 130.718814 -228.134672)
		(end 130.704082 -228.143308)
		(width 0.088646)
		(layer "In11.Cu")
		(net "M_H_CPU1_SB_DQS_DN<8>")
	)
	(segment
		(start 132.598668 -228.134672)
		(end 132.588254 -228.140768)
		(width 0.088646)
		(layer "In11.Cu")
		(net "M_H_CPU1_SB_DQS_DN<8>")
	)
	(segment
		(start 188.360812 -201.74204)
		(end 188.111638 -201.991214)
		(width 0.18288)
		(layer "In11.Cu")
		(net "M_H_CPU1_SB_DQS_DN<8>")
	)
	(segment
		(start 138.989816 -226.696778)
		(end 138.989816 -226.84105)
		(width 0.088646)
		(layer "In11.Cu")
		(net "M_H_CPU1_SB_DQS_DN<8>")
	)
	(segment
		(start 173.788324 -201.548492)
		(end 173.61027 -201.726546)
		(width 0.18288)
		(layer "In11.Cu")
		(net "M_H_CPU1_SB_DQS_DN<8>")
	)
	(segment
		(start 157.557216 -202.308714)
		(end 156.290772 -203.575158)
		(width 0.18288)
		(layer "In11.Cu")
		(net "M_H_CPU1_SB_DQS_DN<8>")
	)
	(segment
		(start 148.049742 -216.014046)
		(end 141.494764 -222.569024)
		(width 0.18288)
		(layer "In11.Cu")
		(net "M_H_CPU1_SB_DQS_DN<8>")
	)
	(segment
		(start 176.601374 -201.140568)
		(end 176.331118 -200.870312)
		(width 0.18288)
		(layer "In11.Cu")
		(net "M_H_CPU1_SB_DQS_DN<8>")
	)
	(segment
		(start 156.290772 -203.575158)
		(end 156.290772 -204.972666)
		(width 0.18288)
		(layer "In11.Cu")
		(net "M_H_CPU1_SB_DQS_DN<8>")
	)
	(segment
		(start 161.120074 -202.308714)
		(end 157.557216 -202.308714)
		(width 0.18288)
		(layer "In11.Cu")
		(net "M_H_CPU1_SB_DQS_DN<8>")
	)
	(segment
		(start 140.257784 -224.75317)
		(end 139.198096 -225.812858)
		(width 0.088646)
		(layer "In11.Cu")
		(net "M_H_CPU1_SB_DQS_DN<8>")
	)
	(segment
		(start 148.049742 -213.213696)
		(end 148.049742 -216.014046)
		(width 0.18288)
		(layer "In11.Cu")
		(net "M_H_CPU1_SB_DQS_DN<8>")
	)
	(segment
		(start 179.084478 -201.851006)
		(end 178.10988 -200.876408)
		(width 0.18288)
		(layer "In11.Cu")
		(net "M_H_CPU1_SB_DQS_DN<8>")
	)
	(segment
		(start 139.198096 -226.488498)
		(end 138.989816 -226.696778)
		(width 0.088646)
		(layer "In11.Cu")
		(net "M_H_CPU1_SB_DQS_DN<8>")
	)
	(segment
		(start 206.246984 -199.59447)
		(end 204.099414 -201.74204)
		(width 0.18288)
		(layer "In11.Cu")
		(net "M_H_CPU1_SB_DQS_DN<8>")
	)
	(segment
		(start 163.801806 -201.777346)
		(end 161.651442 -201.777346)
		(width 0.18288)
		(layer "In11.Cu")
		(net "M_H_CPU1_SB_DQS_DN<8>")
	)
	(segment
		(start 190.034672 -200.888346)
		(end 189.180978 -201.74204)
		(width 0.18288)
		(layer "In11.Cu")
		(net "M_H_CPU1_SB_DQS_DN<8>")
	)
	(segment
		(start 165.095682 -202.313794)
		(end 163.801806 -201.777346)
		(width 0.18288)
		(layer "In11.Cu")
		(net "M_H_CPU1_SB_DQS_DN<8>")
	)
	(segment
		(start 136.827768 -227.320602)
		(end 136.818878 -227.325682)
		(width 0.088646)
		(layer "In11.Cu")
		(net "M_H_CPU1_SB_DQS_DN<8>")
	)
	(segment
		(start 187.589414 -201.991214)
		(end 187.309506 -201.711306)
		(width 0.18288)
		(layer "In11.Cu")
		(net "M_H_CPU1_SB_DQS_DN<8>")
	)
	(segment
		(start 175.426116 -200.870312)
		(end 173.788324 -201.548492)
		(width 0.18288)
		(layer "In11.Cu")
		(net "M_H_CPU1_SB_DQS_DN<8>")
	)
	(segment
		(start 192.209674 -201.143108)
		(end 191.691514 -201.143108)
		(width 0.18288)
		(layer "In11.Cu")
		(net "M_H_CPU1_SB_DQS_DN<8>")
	)
	(segment
		(start 173.024038 -201.991214)
		(end 172.501814 -201.991214)
		(width 0.18288)
		(layer "In11.Cu")
		(net "M_H_CPU1_SB_DQS_DN<8>")
	)
	(segment
		(start 182.95747 -202.310492)
		(end 180.193442 -202.310492)
		(width 0.18288)
		(layer "In11.Cu")
		(net "M_H_CPU1_SB_DQS_DN<8>")
	)
	(segment
		(start 177.388774 -200.876408)
		(end 177.124614 -201.140568)
		(width 0.18288)
		(layer "In11.Cu")
		(net "M_H_CPU1_SB_DQS_DN<8>")
	)
	(segment
		(start 184.404 -201.711306)
		(end 182.95747 -202.310492)
		(width 0.18288)
		(layer "In11.Cu")
		(net "M_H_CPU1_SB_DQS_DN<8>")
	)
	(segment
		(start 167.520874 -202.313794)
		(end 165.095682 -202.313794)
		(width 0.18288)
		(layer "In11.Cu")
		(net "M_H_CPU1_SB_DQS_DN<8>")
	)
	(segment
		(start 136.640316 -227.64496)
		(end 136.640316 -227.663502)
		(width 0.088646)
		(layer "In11.Cu")
		(net "M_H_CPU1_SB_DQS_DN<8>")
	)
	(segment
		(start 141.494764 -222.569024)
		(end 141.494764 -223.601026)
		(width 0.18288)
		(layer "In11.Cu")
		(net "M_H_CPU1_SB_DQS_DN<8>")
	)
	(segment
		(start 193.834258 -201.523346)
		(end 193.191892 -200.88098)
		(width 0.18288)
		(layer "In11.Cu")
		(net "M_H_CPU1_SB_DQS_DN<8>")
	)
	(segment
		(start 192.471802 -200.88098)
		(end 192.209674 -201.143108)
		(width 0.18288)
		(layer "In11.Cu")
		(net "M_H_CPU1_SB_DQS_DN<8>")
	)
	(segment
		(start 172.501814 -201.991214)
		(end 172.250354 -201.739754)
		(width 0.18288)
		(layer "In11.Cu")
		(net "M_H_CPU1_SB_DQS_DN<8>")
	)
	(segment
		(start 170.40733 -201.739754)
		(end 167.520874 -202.313794)
		(width 0.18288)
		(layer "In11.Cu")
		(net "M_H_CPU1_SB_DQS_DN<8>")
	)
	(segment
		(start 173.61027 -201.726546)
		(end 173.288706 -201.726546)
		(width 0.18288)
		(layer "In11.Cu")
		(net "M_H_CPU1_SB_DQS_DN<8>")
	)
	(segment
		(start 131.658614 -228.134672)
		(end 131.643882 -228.143308)
		(width 0.088646)
		(layer "In11.Cu")
		(net "M_H_CPU1_SB_DQS_DN<8>")
	)
	(segment
		(start 177.124614 -201.140568)
		(end 176.601374 -201.140568)
		(width 0.18288)
		(layer "In11.Cu")
		(net "M_H_CPU1_SB_DQS_DN<8>")
	)
	(segment
		(start 125.550168 -227.969318)
		(end 125.541278 -227.964238)
		(width 0.088646)
		(layer "In11.Cu")
		(net "M_H_CPU1_SB_DQS_DN<8>")
	)
	(segment
		(start 193.191892 -200.88098)
		(end 192.471802 -200.88098)
		(width 0.18288)
		(layer "In11.Cu")
		(net "M_H_CPU1_SB_DQS_DN<8>")
	)
	(segment
		(start 202.505564 -201.725276)
		(end 199.601074 -201.725276)
		(width 0.18288)
		(layer "In11.Cu")
		(net "M_H_CPU1_SB_DQS_DN<8>")
	)
	(segment
		(start 156.290772 -204.972666)
		(end 148.049742 -213.213696)
		(width 0.18288)
		(layer "In11.Cu")
		(net "M_H_CPU1_SB_DQS_DN<8>")
	)
	(segment
		(start 139.198096 -225.812858)
		(end 139.198096 -226.488498)
		(width 0.088646)
		(layer "In11.Cu")
		(net "M_H_CPU1_SB_DQS_DN<8>")
	)
	(segment
		(start 141.494764 -223.601026)
		(end 140.34262 -224.75317)
		(width 0.18288)
		(layer "In11.Cu")
		(net "M_H_CPU1_SB_DQS_DN<8>")
	)
	(segment
		(start 137.76706 -227.320348)
		(end 137.767314 -227.320856)
		(width 0.088646)
		(layer "In11.Cu")
		(net "M_H_CPU1_SB_DQS_DN<8>")
	)
	(segment
		(start 191.691514 -201.143108)
		(end 191.436752 -200.888346)
		(width 0.18288)
		(layer "In11.Cu")
		(net "M_H_CPU1_SB_DQS_DN<8>")
	)
	(segment
		(start 206.798926 -199.59447)
		(end 206.246984 -199.59447)
		(width 0.18288)
		(layer "In11.Cu")
		(net "M_H_CPU1_SB_DQS_DN<8>")
	)
	(segment
		(start 203.199238 -201.991214)
		(end 202.771502 -201.991214)
		(width 0.18288)
		(layer "In11.Cu")
		(net "M_H_CPU1_SB_DQS_DN<8>")
	)
	(segment
		(start 191.436752 -200.888346)
		(end 190.034672 -200.888346)
		(width 0.18288)
		(layer "In11.Cu")
		(net "M_H_CPU1_SB_DQS_DN<8>")
	)
	(segment
		(start 202.771502 -201.991214)
		(end 202.505564 -201.725276)
		(width 0.18288)
		(layer "In11.Cu")
		(net "M_H_CPU1_SB_DQS_DN<8>")
	)
	(segment
		(start 189.180978 -201.74204)
		(end 188.360812 -201.74204)
		(width 0.18288)
		(layer "In11.Cu")
		(net "M_H_CPU1_SB_DQS_DN<8>")
	)
	(segment
		(start 207.071214 -199.866758)
		(end 206.798926 -199.59447)
		(width 0.18288)
		(layer "In11.Cu")
		(net "M_H_CPU1_SB_DQS_DN<8>")
	)
	(segment
		(start 126.282958 -228.073966)
		(end 125.798834 -228.064822)
		(width 0.088646)
		(layer "In11.Cu")
		(net "M_H_CPU1_SB_DQS_DN<8>")
	)
	(segment
		(start 135.418068 -228.134672)
		(end 135.407654 -228.140768)
		(width 0.088646)
		(layer "In11.Cu")
		(net "M_H_CPU1_SB_DQS_DN<8>")
	)
	(segment
		(start 161.651442 -201.777346)
		(end 161.120074 -202.308714)
		(width 0.18288)
		(layer "In11.Cu")
		(net "M_H_CPU1_SB_DQS_DN<8>")
	)
	(segment
		(start 173.288706 -201.726546)
		(end 173.024038 -201.991214)
		(width 0.18288)
		(layer "In11.Cu")
		(net "M_H_CPU1_SB_DQS_DN<8>")
	)
	(segment
		(start 203.448412 -201.74204)
		(end 203.199238 -201.991214)
		(width 0.18288)
		(layer "In11.Cu")
		(net "M_H_CPU1_SB_DQS_DN<8>")
	)
	(segment
		(start 180.193442 -202.310492)
		(end 179.084478 -201.851006)
		(width 0.18288)
		(layer "In11.Cu")
		(net "M_H_CPU1_SB_DQS_DN<8>")
	)
	(segment
		(start 178.10988 -200.876408)
		(end 177.388774 -200.876408)
		(width 0.18288)
		(layer "In11.Cu")
		(net "M_H_CPU1_SB_DQS_DN<8>")
	)
	(segment
		(start 204.099414 -201.74204)
		(end 203.448412 -201.74204)
		(width 0.18288)
		(layer "In11.Cu")
		(net "M_H_CPU1_SB_DQS_DN<8>")
	)
	(segment
		(start 198.141082 -201.120502)
		(end 194.995038 -201.120502)
		(width 0.18288)
		(layer "In11.Cu")
		(net "M_H_CPU1_SB_DQS_DN<8>")
	)
	(segment
		(start 134.478014 -228.134672)
		(end 134.4676 -228.140768)
		(width 0.088646)
		(layer "In11.Cu")
		(net "M_H_CPU1_SB_DQS_DN<8>")
	)
	(segment
		(start 126.959614 -228.134672)
		(end 126.9492 -228.140768)
		(width 0.088646)
		(layer "In11.Cu")
		(net "M_H_CPU1_SB_DQS_DN<8>")
	)
	(segment
		(start 140.34262 -224.75317)
		(end 140.257784 -224.75317)
		(width 0.088646)
		(layer "In11.Cu")
		(net "M_H_CPU1_SB_DQS_DN<8>")
	)
	(segment
		(start 176.331118 -200.870312)
		(end 175.426116 -200.870312)
		(width 0.18288)
		(layer "In11.Cu")
		(net "M_H_CPU1_SB_DQS_DN<8>")
	)
	(segment
		(start 125.774196 -228.06152)
		(end 125.676914 -228.037136)
		(width 0.088646)
		(layer "In11.Cu")
		(net "M_H_CPU1_SB_DQS_DN<8>")
	)
	(segment
		(start 194.592194 -201.523346)
		(end 193.834258 -201.523346)
		(width 0.18288)
		(layer "In11.Cu")
		(net "M_H_CPU1_SB_DQS_DN<8>")
	)
	(arc
		(start 134.85241 -228.134672)
		(mid 134.665212 -228.084529)
		(end 134.478014 -228.134672)
		(width 0.088646)
		(layer "In11.Cu")
		(net "M_H_CPU1_SB_DQS_DN<8>")
	)
	(arc
		(start 132.03301 -228.134672)
		(mid 131.845812 -228.084529)
		(end 131.658614 -228.134672)
		(width 0.088646)
		(layer "In11.Cu")
		(net "M_H_CPU1_SB_DQS_DN<8>")
	)
	(arc
		(start 134.4676 -228.140768)
		(mid 134.189422 -228.21046)
		(end 133.912864 -228.134672)
		(width 0.088646)
		(layer "In11.Cu")
		(net "M_H_CPU1_SB_DQS_DN<8>")
	)
	(arc
		(start 132.973064 -228.134672)
		(mid 132.785866 -228.084529)
		(end 132.598668 -228.134672)
		(width 0.088646)
		(layer "In11.Cu")
		(net "M_H_CPU1_SB_DQS_DN<8>")
	)
	(arc
		(start 130.15341 -228.134672)
		(mid 129.966212 -228.084529)
		(end 129.779014 -228.134672)
		(width 0.088646)
		(layer "In11.Cu")
		(net "M_H_CPU1_SB_DQS_DN<8>")
	)
	(arc
		(start 128.27381 -228.134672)
		(mid 128.086612 -228.084529)
		(end 127.899414 -228.134672)
		(width 0.088646)
		(layer "In11.Cu")
		(net "M_H_CPU1_SB_DQS_DN<8>")
	)
	(arc
		(start 127.33401 -228.134672)
		(mid 127.146812 -228.084529)
		(end 126.959614 -228.134672)
		(width 0.088646)
		(layer "In11.Cu")
		(net "M_H_CPU1_SB_DQS_DN<8>")
	)
	(arc
		(start 133.912864 -228.134672)
		(mid 133.725666 -228.084529)
		(end 133.538468 -228.134672)
		(width 0.088646)
		(layer "In11.Cu")
		(net "M_H_CPU1_SB_DQS_DN<8>")
	)
	(arc
		(start 136.640316 -227.663502)
		(mid 136.560154 -227.935691)
		(end 136.357868 -228.134672)
		(width 0.088646)
		(layer "In11.Cu")
		(net "M_H_CPU1_SB_DQS_DN<8>")
	)
	(arc
		(start 125.798834 -228.064822)
		(mid 125.786419 -228.063884)
		(end 125.774196 -228.06152)
		(width 0.088646)
		(layer "In11.Cu")
		(net "M_H_CPU1_SB_DQS_DN<8>")
	)
	(arc
		(start 127.899414 -228.134672)
		(mid 127.616712 -228.210414)
		(end 127.33401 -228.134672)
		(width 0.088646)
		(layer "In11.Cu")
		(net "M_H_CPU1_SB_DQS_DN<8>")
	)
	(arc
		(start 128.839214 -228.134672)
		(mid 128.556512 -228.210414)
		(end 128.27381 -228.134672)
		(width 0.088646)
		(layer "In11.Cu")
		(net "M_H_CPU1_SB_DQS_DN<8>")
	)
	(arc
		(start 132.588254 -228.140768)
		(mid 132.309822 -228.210582)
		(end 132.03301 -228.134672)
		(width 0.088646)
		(layer "In11.Cu")
		(net "M_H_CPU1_SB_DQS_DN<8>")
	)
	(arc
		(start 138.989816 -226.84105)
		(mid 138.703013 -227.322947)
		(end 138.142218 -227.320348)
		(width 0.088646)
		(layer "In11.Cu")
		(net "M_H_CPU1_SB_DQS_DN<8>")
	)
	(arc
		(start 138.142218 -227.320348)
		(mid 137.954656 -227.270112)
		(end 137.76706 -227.320348)
		(width 0.088646)
		(layer "In11.Cu")
		(net "M_H_CPU1_SB_DQS_DN<8>")
	)
	(arc
		(start 136.818878 -227.325682)
		(mid 136.687964 -227.462042)
		(end 136.640316 -227.64496)
		(width 0.088646)
		(layer "In11.Cu")
		(net "M_H_CPU1_SB_DQS_DN<8>")
	)
	(arc
		(start 131.09321 -228.134672)
		(mid 130.906012 -228.084529)
		(end 130.718814 -228.134672)
		(width 0.088646)
		(layer "In11.Cu")
		(net "M_H_CPU1_SB_DQS_DN<8>")
	)
	(arc
		(start 129.764282 -228.143308)
		(mid 129.487841 -228.210474)
		(end 129.21361 -228.134672)
		(width 0.088646)
		(layer "In11.Cu")
		(net "M_H_CPU1_SB_DQS_DN<8>")
	)
	(arc
		(start 136.357868 -228.134672)
		(mid 136.075166 -228.210414)
		(end 135.792464 -228.134672)
		(width 0.088646)
		(layer "In11.Cu")
		(net "M_H_CPU1_SB_DQS_DN<8>")
	)
	(arc
		(start 126.393194 -228.133656)
		(mid 126.391156 -228.132524)
		(end 126.38913 -228.13137)
		(width 0.088646)
		(layer "In11.Cu")
		(net "M_H_CPU1_SB_DQS_DN<8>")
	)
	(arc
		(start 135.407654 -228.140768)
		(mid 135.129222 -228.210582)
		(end 134.85241 -228.134672)
		(width 0.088646)
		(layer "In11.Cu")
		(net "M_H_CPU1_SB_DQS_DN<8>")
	)
	(arc
		(start 131.643882 -228.143308)
		(mid 131.367441 -228.210474)
		(end 131.09321 -228.134672)
		(width 0.088646)
		(layer "In11.Cu")
		(net "M_H_CPU1_SB_DQS_DN<8>")
	)
	(arc
		(start 129.21361 -228.134672)
		(mid 129.026412 -228.084529)
		(end 128.839214 -228.134672)
		(width 0.088646)
		(layer "In11.Cu")
		(net "M_H_CPU1_SB_DQS_DN<8>")
	)
	(arc
		(start 126.394464 -228.134672)
		(mid 126.393829 -228.134163)
		(end 126.393194 -228.133656)
		(width 0.088646)
		(layer "In11.Cu")
		(net "M_H_CPU1_SB_DQS_DN<8>")
	)
	(arc
		(start 130.704082 -228.143308)
		(mid 130.427641 -228.210474)
		(end 130.15341 -228.134672)
		(width 0.088646)
		(layer "In11.Cu")
		(net "M_H_CPU1_SB_DQS_DN<8>")
	)
	(arc
		(start 137.202164 -227.320602)
		(mid 137.014966 -227.270459)
		(end 136.827768 -227.320602)
		(width 0.088646)
		(layer "In11.Cu")
		(net "M_H_CPU1_SB_DQS_DN<8>")
	)
	(arc
		(start 133.538468 -228.134672)
		(mid 133.255766 -228.210414)
		(end 132.973064 -228.134672)
		(width 0.088646)
		(layer "In11.Cu")
		(net "M_H_CPU1_SB_DQS_DN<8>")
	)
	(arc
		(start 126.9492 -228.140768)
		(mid 126.671022 -228.21046)
		(end 126.394464 -228.134672)
		(width 0.088646)
		(layer "In11.Cu")
		(net "M_H_CPU1_SB_DQS_DN<8>")
	)
	(arc
		(start 125.541278 -227.964238)
		(mid 125.43018 -227.859495)
		(end 125.370082 -227.719128)
		(width 0.088646)
		(layer "In11.Cu")
		(net "M_H_CPU1_SB_DQS_DN<8>")
	)
	(arc
		(start 137.767314 -227.320856)
		(mid 137.484693 -227.396471)
		(end 137.202164 -227.320602)
		(width 0.088646)
		(layer "In11.Cu")
		(net "M_H_CPU1_SB_DQS_DN<8>")
	)
	(arc
		(start 135.792464 -228.134672)
		(mid 135.605266 -228.084529)
		(end 135.418068 -228.134672)
		(width 0.088646)
		(layer "In11.Cu")
		(net "M_H_CPU1_SB_DQS_DN<8>")
	)
	(segment
		(start 210.286092 -208.797906)
		(end 210.598258 -208.797906)
		(width 0.20066)
		(layer "F.Cu")
		(net "M_H_CPU1_SB_DQS_DN<7>")
	)
	(segment
		(start 212.949028 -208.802732)
		(end 213.234778 -208.516982)
		(width 0.20066)
		(layer "F.Cu")
		(net "M_H_CPU1_SB_DQS_DN<7>")
	)
	(segment
		(start 215.216232 -209.216752)
		(end 215.719914 -209.216752)
		(width 0.20066)
		(layer "F.Cu")
		(net "M_H_CPU1_SB_DQS_DN<7>")
	)
	(segment
		(start 208.70672 -209.216752)
		(end 208.977992 -208.94548)
		(width 0.20066)
		(layer "F.Cu")
		(net "M_H_CPU1_SB_DQS_DN<7>")
	)
	(segment
		(start 208.176114 -209.216752)
		(end 208.70672 -209.216752)
		(width 0.20066)
		(layer "F.Cu")
		(net "M_H_CPU1_SB_DQS_DN<7>")
	)
	(segment
		(start 214.961978 -208.962498)
		(end 215.216232 -209.216752)
		(width 0.20066)
		(layer "F.Cu")
		(net "M_H_CPU1_SB_DQS_DN<7>")
	)
	(segment
		(start 208.977992 -208.94548)
		(end 209.461354 -208.94548)
		(width 0.20066)
		(layer "F.Cu")
		(net "M_H_CPU1_SB_DQS_DN<7>")
	)
	(segment
		(start 212.630258 -208.802732)
		(end 212.949028 -208.802732)
		(width 0.20066)
		(layer "F.Cu")
		(net "M_H_CPU1_SB_DQS_DN<7>")
	)
	(segment
		(start 210.598258 -208.797906)
		(end 210.603084 -208.797906)
		(width 0.101854)
		(layer "F.Cu")
		(net "M_H_CPU1_SB_DQS_DN<7>")
	)
	(segment
		(start 209.461354 -208.94548)
		(end 209.886296 -208.520538)
		(width 0.20066)
		(layer "F.Cu")
		(net "M_H_CPU1_SB_DQS_DN<7>")
	)
	(segment
		(start 210.60918 -208.79181)
		(end 212.619336 -208.79181)
		(width 0.1016)
		(layer "F.Cu")
		(net "M_H_CPU1_SB_DQS_DN<7>")
	)
	(segment
		(start 210.603084 -208.797906)
		(end 210.60918 -208.79181)
		(width 0.1016)
		(layer "F.Cu")
		(net "M_H_CPU1_SB_DQS_DN<7>")
	)
	(segment
		(start 214.17026 -208.962498)
		(end 214.961978 -208.962498)
		(width 0.20066)
		(layer "F.Cu")
		(net "M_H_CPU1_SB_DQS_DN<7>")
	)
	(segment
		(start 129.026666 -230.622602)
		(end 129.026412 -230.622348)
		(width 0.20066)
		(layer "F.Cu")
		(net "M_H_CPU1_SB_DQS_DN<7>")
	)
	(segment
		(start 213.234778 -208.516982)
		(end 213.724744 -208.516982)
		(width 0.20066)
		(layer "F.Cu")
		(net "M_H_CPU1_SB_DQS_DN<7>")
	)
	(segment
		(start 212.619336 -208.79181)
		(end 212.630258 -208.802732)
		(width 0.1016)
		(layer "F.Cu")
		(net "M_H_CPU1_SB_DQS_DN<7>")
	)
	(segment
		(start 209.886296 -208.520538)
		(end 210.008724 -208.520538)
		(width 0.20066)
		(layer "F.Cu")
		(net "M_H_CPU1_SB_DQS_DN<7>")
	)
	(segment
		(start 213.724744 -208.516982)
		(end 214.17026 -208.962498)
		(width 0.20066)
		(layer "F.Cu")
		(net "M_H_CPU1_SB_DQS_DN<7>")
	)
	(segment
		(start 207.071214 -209.216752)
		(end 208.176114 -209.216752)
		(width 0.20066)
		(layer "F.Cu")
		(net "M_H_CPU1_SB_DQS_DN<7>")
	)
	(segment
		(start 210.008724 -208.520538)
		(end 210.286092 -208.797906)
		(width 0.20066)
		(layer "F.Cu")
		(net "M_H_CPU1_SB_DQS_DN<7>")
	)
	(segment
		(start 129.026412 -230.622348)
		(end 129.026412 -230.086662)
		(width 0.20066)
		(layer "F.Cu")
		(net "M_H_CPU1_SB_DQS_DN<7>")
	)
	(segment
		(start 172.356526 -211.073746)
		(end 171.409106 -211.073746)
		(width 0.18288)
		(layer "In6.Cu")
		(net "M_H_CPU1_SB_DQS_DN<7>")
	)
	(segment
		(start 157.6451 -209.181446)
		(end 155.402026 -211.42452)
		(width 0.18288)
		(layer "In6.Cu")
		(net "M_H_CPU1_SB_DQS_DN<7>")
	)
	(segment
		(start 163.987988 -209.305906)
		(end 163.863528 -209.181446)
		(width 0.18288)
		(layer "In6.Cu")
		(net "M_H_CPU1_SB_DQS_DN<7>")
	)
	(segment
		(start 193.516504 -208.24825)
		(end 192.948814 -207.68056)
		(width 0.18288)
		(layer "In6.Cu")
		(net "M_H_CPU1_SB_DQS_DN<7>")
	)
	(segment
		(start 203.158852 -208.790794)
		(end 202.753976 -208.790794)
		(width 0.18288)
		(layer "In6.Cu")
		(net "M_H_CPU1_SB_DQS_DN<7>")
	)
	(segment
		(start 192.948814 -207.68056)
		(end 192.430654 -207.68056)
		(width 0.18288)
		(layer "In6.Cu")
		(net "M_H_CPU1_SB_DQS_DN<7>")
	)
	(segment
		(start 197.901306 -209.173826)
		(end 197.132448 -209.173826)
		(width 0.18288)
		(layer "In6.Cu")
		(net "M_H_CPU1_SB_DQS_DN<7>")
	)
	(segment
		(start 137.870438 -228.637084)
		(end 137.612882 -228.89464)
		(width 0.088646)
		(layer "In6.Cu")
		(net "M_H_CPU1_SB_DQS_DN<7>")
	)
	(segment
		(start 169.516806 -209.181446)
		(end 168.681908 -209.181446)
		(width 0.18288)
		(layer "In6.Cu")
		(net "M_H_CPU1_SB_DQS_DN<7>")
	)
	(segment
		(start 139.250674 -226.963224)
		(end 139.19073 -226.90328)
		(width 0.088646)
		(layer "In6.Cu")
		(net "M_H_CPU1_SB_DQS_DN<7>")
	)
	(segment
		(start 158.1912 -209.181446)
		(end 157.6451 -209.181446)
		(width 0.18288)
		(layer "In6.Cu")
		(net "M_H_CPU1_SB_DQS_DN<7>")
	)
	(segment
		(start 165.329108 -209.305906)
		(end 165.204648 -209.181446)
		(width 0.18288)
		(layer "In6.Cu")
		(net "M_H_CPU1_SB_DQS_DN<7>")
	)
	(segment
		(start 197.132448 -209.173826)
		(end 195.844668 -207.886046)
		(width 0.18288)
		(layer "In6.Cu")
		(net "M_H_CPU1_SB_DQS_DN<7>")
	)
	(segment
		(start 177.336704 -210.230974)
		(end 177.076608 -210.49107)
		(width 0.18288)
		(layer "In6.Cu")
		(net "M_H_CPU1_SB_DQS_DN<7>")
	)
	(segment
		(start 161.976308 -209.181446)
		(end 161.851848 -209.305906)
		(width 0.18288)
		(layer "In6.Cu")
		(net "M_H_CPU1_SB_DQS_DN<7>")
	)
	(segment
		(start 170.123104 -209.963766)
		(end 170.123104 -209.787744)
		(width 0.18288)
		(layer "In6.Cu")
		(net "M_H_CPU1_SB_DQS_DN<7>")
	)
	(segment
		(start 186.903868 -208.52257)
		(end 185.169048 -209.241136)
		(width 0.18288)
		(layer "In6.Cu")
		(net "M_H_CPU1_SB_DQS_DN<7>")
	)
	(segment
		(start 165.875208 -209.305906)
		(end 165.329108 -209.305906)
		(width 0.18288)
		(layer "In6.Cu")
		(net "M_H_CPU1_SB_DQS_DN<7>")
	)
	(segment
		(start 188.062108 -208.790794)
		(end 187.692284 -208.790794)
		(width 0.18288)
		(layer "In6.Cu")
		(net "M_H_CPU1_SB_DQS_DN<7>")
	)
	(segment
		(start 187.692284 -208.790794)
		(end 187.42406 -208.52257)
		(width 0.18288)
		(layer "In6.Cu")
		(net "M_H_CPU1_SB_DQS_DN<7>")
	)
	(segment
		(start 177.076608 -210.49107)
		(end 176.716944 -210.49107)
		(width 0.18288)
		(layer "In6.Cu")
		(net "M_H_CPU1_SB_DQS_DN<7>")
	)
	(segment
		(start 177.79873 -210.230974)
		(end 177.336704 -210.230974)
		(width 0.18288)
		(layer "In6.Cu")
		(net "M_H_CPU1_SB_DQS_DN<7>")
	)
	(segment
		(start 159.840168 -209.181446)
		(end 158.98622 -209.181446)
		(width 0.18288)
		(layer "In6.Cu")
		(net "M_H_CPU1_SB_DQS_DN<7>")
	)
	(segment
		(start 173.951646 -211.080858)
		(end 173.22927 -211.080858)
		(width 0.18288)
		(layer "In6.Cu")
		(net "M_H_CPU1_SB_DQS_DN<7>")
	)
	(segment
		(start 180.129688 -209.241136)
		(end 180.005228 -209.365596)
		(width 0.18288)
		(layer "In6.Cu")
		(net "M_H_CPU1_SB_DQS_DN<7>")
	)
	(segment
		(start 202.494388 -208.531206)
		(end 199.452738 -208.531206)
		(width 0.18288)
		(layer "In6.Cu")
		(net "M_H_CPU1_SB_DQS_DN<7>")
	)
	(segment
		(start 139.274042 -226.963224)
		(end 139.250674 -226.963224)
		(width 0.088646)
		(layer "In6.Cu")
		(net "M_H_CPU1_SB_DQS_DN<7>")
	)
	(segment
		(start 161.851848 -209.305906)
		(end 161.305748 -209.305906)
		(width 0.18288)
		(layer "In6.Cu")
		(net "M_H_CPU1_SB_DQS_DN<7>")
	)
	(segment
		(start 163.317428 -209.181446)
		(end 163.192968 -209.305906)
		(width 0.18288)
		(layer "In6.Cu")
		(net "M_H_CPU1_SB_DQS_DN<7>")
	)
	(segment
		(start 162.522408 -209.181446)
		(end 161.976308 -209.181446)
		(width 0.18288)
		(layer "In6.Cu")
		(net "M_H_CPU1_SB_DQS_DN<7>")
	)
	(segment
		(start 161.181288 -209.181446)
		(end 160.635188 -209.181446)
		(width 0.18288)
		(layer "In6.Cu")
		(net "M_H_CPU1_SB_DQS_DN<7>")
	)
	(segment
		(start 167.886888 -209.181446)
		(end 167.340788 -209.181446)
		(width 0.18288)
		(layer "In6.Cu")
		(net "M_H_CPU1_SB_DQS_DN<7>")
	)
	(segment
		(start 191.797432 -207.94091)
		(end 191.53886 -207.682338)
		(width 0.18288)
		(layer "In6.Cu")
		(net "M_H_CPU1_SB_DQS_DN<7>")
	)
	(segment
		(start 178.788568 -209.241136)
		(end 177.79873 -210.230974)
		(width 0.18288)
		(layer "In6.Cu")
		(net "M_H_CPU1_SB_DQS_DN<7>")
	)
	(segment
		(start 172.623988 -211.341208)
		(end 172.356526 -211.073746)
		(width 0.18288)
		(layer "In6.Cu")
		(net "M_H_CPU1_SB_DQS_DN<7>")
	)
	(segment
		(start 199.452738 -208.531206)
		(end 197.901306 -209.173826)
		(width 0.18288)
		(layer "In6.Cu")
		(net "M_H_CPU1_SB_DQS_DN<7>")
	)
	(segment
		(start 129.578862 -229.853998)
		(end 129.202434 -229.853998)
		(width 0.088646)
		(layer "In6.Cu")
		(net "M_H_CPU1_SB_DQS_DN<7>")
	)
	(segment
		(start 129.791206 -229.755192)
		(end 129.787396 -229.757478)
		(width 0.088646)
		(layer "In6.Cu")
		(net "M_H_CPU1_SB_DQS_DN<7>")
	)
	(segment
		(start 155.402026 -211.630514)
		(end 140.069316 -226.963224)
		(width 0.18288)
		(layer "In6.Cu")
		(net "M_H_CPU1_SB_DQS_DN<7>")
	)
	(segment
		(start 163.192968 -209.305906)
		(end 162.646868 -209.305906)
		(width 0.18288)
		(layer "In6.Cu")
		(net "M_H_CPU1_SB_DQS_DN<7>")
	)
	(segment
		(start 170.123104 -209.787744)
		(end 169.516806 -209.181446)
		(width 0.18288)
		(layer "In6.Cu")
		(net "M_H_CPU1_SB_DQS_DN<7>")
	)
	(segment
		(start 139.062968 -226.90328)
		(end 138.997944 -226.968558)
		(width 0.088646)
		(layer "In6.Cu")
		(net "M_H_CPU1_SB_DQS_DN<7>")
	)
	(segment
		(start 137.870438 -228.26345)
		(end 137.870438 -228.637084)
		(width 0.088646)
		(layer "In6.Cu")
		(net "M_H_CPU1_SB_DQS_DN<7>")
	)
	(segment
		(start 171.409106 -211.073746)
		(end 170.685714 -210.350354)
		(width 0.18288)
		(layer "In6.Cu")
		(net "M_H_CPU1_SB_DQS_DN<7>")
	)
	(segment
		(start 137.202672 -228.948742)
		(end 137.202164 -228.948488)
		(width 0.088646)
		(layer "In6.Cu")
		(net "M_H_CPU1_SB_DQS_DN<7>")
	)
	(segment
		(start 194.568826 -208.24825)
		(end 193.516504 -208.24825)
		(width 0.18288)
		(layer "In6.Cu")
		(net "M_H_CPU1_SB_DQS_DN<7>")
	)
	(segment
		(start 188.322458 -208.530444)
		(end 188.062108 -208.790794)
		(width 0.18288)
		(layer "In6.Cu")
		(net "M_H_CPU1_SB_DQS_DN<7>")
	)
	(segment
		(start 204.910182 -209.329528)
		(end 204.111098 -208.530444)
		(width 0.18288)
		(layer "In6.Cu")
		(net "M_H_CPU1_SB_DQS_DN<7>")
	)
	(segment
		(start 129.754122 -229.776528)
		(end 129.578862 -229.853998)
		(width 0.088646)
		(layer "In6.Cu")
		(net "M_H_CPU1_SB_DQS_DN<7>")
	)
	(segment
		(start 158.31566 -209.305906)
		(end 158.1912 -209.181446)
		(width 0.18288)
		(layer "In6.Cu")
		(net "M_H_CPU1_SB_DQS_DN<7>")
	)
	(segment
		(start 164.658548 -209.181446)
		(end 164.534088 -209.305906)
		(width 0.18288)
		(layer "In6.Cu")
		(net "M_H_CPU1_SB_DQS_DN<7>")
	)
	(segment
		(start 129.787396 -229.757478)
		(end 129.754122 -229.776528)
		(width 0.088646)
		(layer "In6.Cu")
		(net "M_H_CPU1_SB_DQS_DN<7>")
	)
	(segment
		(start 165.999668 -209.181446)
		(end 165.875208 -209.305906)
		(width 0.18288)
		(layer "In6.Cu")
		(net "M_H_CPU1_SB_DQS_DN<7>")
	)
	(segment
		(start 187.42406 -208.52257)
		(end 186.903868 -208.52257)
		(width 0.18288)
		(layer "In6.Cu")
		(net "M_H_CPU1_SB_DQS_DN<7>")
	)
	(segment
		(start 195.844668 -207.886046)
		(end 195.443348 -207.886046)
		(width 0.18288)
		(layer "In6.Cu")
		(net "M_H_CPU1_SB_DQS_DN<7>")
	)
	(segment
		(start 139.19073 -226.90328)
		(end 139.062968 -226.90328)
		(width 0.088646)
		(layer "In6.Cu")
		(net "M_H_CPU1_SB_DQS_DN<7>")
	)
	(segment
		(start 170.509692 -210.350354)
		(end 170.123104 -209.963766)
		(width 0.18288)
		(layer "In6.Cu")
		(net "M_H_CPU1_SB_DQS_DN<7>")
	)
	(segment
		(start 191.53886 -207.682338)
		(end 189.91326 -207.682338)
		(width 0.18288)
		(layer "In6.Cu")
		(net "M_H_CPU1_SB_DQS_DN<7>")
	)
	(segment
		(start 172.96892 -211.341208)
		(end 172.623988 -211.341208)
		(width 0.18288)
		(layer "In6.Cu")
		(net "M_H_CPU1_SB_DQS_DN<7>")
	)
	(segment
		(start 164.534088 -209.305906)
		(end 163.987988 -209.305906)
		(width 0.18288)
		(layer "In6.Cu")
		(net "M_H_CPU1_SB_DQS_DN<7>")
	)
	(segment
		(start 189.91326 -207.682338)
		(end 189.065154 -208.530444)
		(width 0.18288)
		(layer "In6.Cu")
		(net "M_H_CPU1_SB_DQS_DN<7>")
	)
	(segment
		(start 168.681908 -209.181446)
		(end 168.557448 -209.305906)
		(width 0.18288)
		(layer "In6.Cu")
		(net "M_H_CPU1_SB_DQS_DN<7>")
	)
	(segment
		(start 174.822866 -210.209638)
		(end 173.951646 -211.080858)
		(width 0.18288)
		(layer "In6.Cu")
		(net "M_H_CPU1_SB_DQS_DN<7>")
	)
	(segment
		(start 130.638296 -228.957124)
		(end 130.623564 -228.948488)
		(width 0.088646)
		(layer "In6.Cu")
		(net "M_H_CPU1_SB_DQS_DN<7>")
	)
	(segment
		(start 206.344012 -208.955386)
		(end 205.96987 -209.329528)
		(width 0.18288)
		(layer "In6.Cu")
		(net "M_H_CPU1_SB_DQS_DN<7>")
	)
	(segment
		(start 159.964628 -209.305906)
		(end 159.840168 -209.181446)
		(width 0.18288)
		(layer "In6.Cu")
		(net "M_H_CPU1_SB_DQS_DN<7>")
	)
	(segment
		(start 166.670228 -209.305906)
		(end 166.545768 -209.181446)
		(width 0.18288)
		(layer "In6.Cu")
		(net "M_H_CPU1_SB_DQS_DN<7>")
	)
	(segment
		(start 180.005228 -209.365596)
		(end 179.459128 -209.365596)
		(width 0.18288)
		(layer "In6.Cu")
		(net "M_H_CPU1_SB_DQS_DN<7>")
	)
	(segment
		(start 170.685714 -210.350354)
		(end 170.509692 -210.350354)
		(width 0.18288)
		(layer "In6.Cu")
		(net "M_H_CPU1_SB_DQS_DN<7>")
	)
	(segment
		(start 140.069316 -226.963224)
		(end 139.274042 -226.963224)
		(width 0.18288)
		(layer "In6.Cu")
		(net "M_H_CPU1_SB_DQS_DN<7>")
	)
	(segment
		(start 138.997944 -226.968558)
		(end 138.879326 -227.254816)
		(width 0.088646)
		(layer "In6.Cu")
		(net "M_H_CPU1_SB_DQS_DN<7>")
	)
	(segment
		(start 176.716944 -210.49107)
		(end 176.435512 -210.209638)
		(width 0.18288)
		(layer "In6.Cu")
		(net "M_H_CPU1_SB_DQS_DN<7>")
	)
	(segment
		(start 207.071214 -209.216752)
		(end 206.809848 -208.955386)
		(width 0.18288)
		(layer "In6.Cu")
		(net "M_H_CPU1_SB_DQS_DN<7>")
	)
	(segment
		(start 179.334668 -209.241136)
		(end 178.788568 -209.241136)
		(width 0.18288)
		(layer "In6.Cu")
		(net "M_H_CPU1_SB_DQS_DN<7>")
	)
	(segment
		(start 167.340788 -209.181446)
		(end 167.216328 -209.305906)
		(width 0.18288)
		(layer "In6.Cu")
		(net "M_H_CPU1_SB_DQS_DN<7>")
	)
	(segment
		(start 166.545768 -209.181446)
		(end 165.999668 -209.181446)
		(width 0.18288)
		(layer "In6.Cu")
		(net "M_H_CPU1_SB_DQS_DN<7>")
	)
	(segment
		(start 158.98622 -209.181446)
		(end 158.86176 -209.305906)
		(width 0.18288)
		(layer "In6.Cu")
		(net "M_H_CPU1_SB_DQS_DN<7>")
	)
	(segment
		(start 189.065154 -208.530444)
		(end 188.322458 -208.530444)
		(width 0.18288)
		(layer "In6.Cu")
		(net "M_H_CPU1_SB_DQS_DN<7>")
	)
	(segment
		(start 134.397496 -228.957124)
		(end 134.382764 -228.948488)
		(width 0.088646)
		(layer "In6.Cu")
		(net "M_H_CPU1_SB_DQS_DN<7>")
	)
	(segment
		(start 161.305748 -209.305906)
		(end 161.181288 -209.181446)
		(width 0.18288)
		(layer "In6.Cu")
		(net "M_H_CPU1_SB_DQS_DN<7>")
	)
	(segment
		(start 129.086864 -229.877112)
		(end 129.026412 -229.937564)
		(width 0.088646)
		(layer "In6.Cu")
		(net "M_H_CPU1_SB_DQS_DN<7>")
	)
	(segment
		(start 205.96987 -209.329528)
		(end 204.910182 -209.329528)
		(width 0.18288)
		(layer "In6.Cu")
		(net "M_H_CPU1_SB_DQS_DN<7>")
	)
	(segment
		(start 192.430654 -207.68056)
		(end 192.170304 -207.94091)
		(width 0.18288)
		(layer "In6.Cu")
		(net "M_H_CPU1_SB_DQS_DN<7>")
	)
	(segment
		(start 206.809848 -208.955386)
		(end 206.344012 -208.955386)
		(width 0.18288)
		(layer "In6.Cu")
		(net "M_H_CPU1_SB_DQS_DN<7>")
	)
	(segment
		(start 195.443348 -207.886046)
		(end 194.568826 -208.24825)
		(width 0.18288)
		(layer "In6.Cu")
		(net "M_H_CPU1_SB_DQS_DN<7>")
	)
	(segment
		(start 168.011348 -209.305906)
		(end 167.886888 -209.181446)
		(width 0.18288)
		(layer "In6.Cu")
		(net "M_H_CPU1_SB_DQS_DN<7>")
	)
	(segment
		(start 160.635188 -209.181446)
		(end 160.510728 -209.305906)
		(width 0.18288)
		(layer "In6.Cu")
		(net "M_H_CPU1_SB_DQS_DN<7>")
	)
	(segment
		(start 202.753976 -208.790794)
		(end 202.494388 -208.531206)
		(width 0.18288)
		(layer "In6.Cu")
		(net "M_H_CPU1_SB_DQS_DN<7>")
	)
	(segment
		(start 173.22927 -211.080858)
		(end 172.96892 -211.341208)
		(width 0.18288)
		(layer "In6.Cu")
		(net "M_H_CPU1_SB_DQS_DN<7>")
	)
	(segment
		(start 204.111098 -208.530444)
		(end 203.419202 -208.530444)
		(width 0.18288)
		(layer "In6.Cu")
		(net "M_H_CPU1_SB_DQS_DN<7>")
	)
	(segment
		(start 138.879326 -227.254816)
		(end 137.870438 -228.26345)
		(width 0.088646)
		(layer "In6.Cu")
		(net "M_H_CPU1_SB_DQS_DN<7>")
	)
	(segment
		(start 168.557448 -209.305906)
		(end 168.011348 -209.305906)
		(width 0.18288)
		(layer "In6.Cu")
		(net "M_H_CPU1_SB_DQS_DN<7>")
	)
	(segment
		(start 192.170304 -207.94091)
		(end 191.797432 -207.94091)
		(width 0.18288)
		(layer "In6.Cu")
		(net "M_H_CPU1_SB_DQS_DN<7>")
	)
	(segment
		(start 155.402026 -211.42452)
		(end 155.402026 -211.630514)
		(width 0.18288)
		(layer "In6.Cu")
		(net "M_H_CPU1_SB_DQS_DN<7>")
	)
	(segment
		(start 160.510728 -209.305906)
		(end 159.964628 -209.305906)
		(width 0.18288)
		(layer "In6.Cu")
		(net "M_H_CPU1_SB_DQS_DN<7>")
	)
	(segment
		(start 167.216328 -209.305906)
		(end 166.670228 -209.305906)
		(width 0.18288)
		(layer "In6.Cu")
		(net "M_H_CPU1_SB_DQS_DN<7>")
	)
	(segment
		(start 176.435512 -210.209638)
		(end 174.822866 -210.209638)
		(width 0.18288)
		(layer "In6.Cu")
		(net "M_H_CPU1_SB_DQS_DN<7>")
	)
	(segment
		(start 179.459128 -209.365596)
		(end 179.334668 -209.241136)
		(width 0.18288)
		(layer "In6.Cu")
		(net "M_H_CPU1_SB_DQS_DN<7>")
	)
	(segment
		(start 163.863528 -209.181446)
		(end 163.317428 -209.181446)
		(width 0.18288)
		(layer "In6.Cu")
		(net "M_H_CPU1_SB_DQS_DN<7>")
	)
	(segment
		(start 130.249168 -228.948488)
		(end 130.240278 -228.953568)
		(width 0.088646)
		(layer "In6.Cu")
		(net "M_H_CPU1_SB_DQS_DN<7>")
	)
	(segment
		(start 129.026412 -229.937564)
		(end 129.026412 -230.086662)
		(width 0.088646)
		(layer "In6.Cu")
		(net "M_H_CPU1_SB_DQS_DN<7>")
	)
	(segment
		(start 162.646868 -209.305906)
		(end 162.522408 -209.181446)
		(width 0.18288)
		(layer "In6.Cu")
		(net "M_H_CPU1_SB_DQS_DN<7>")
	)
	(segment
		(start 129.202434 -229.853998)
		(end 129.086864 -229.877112)
		(width 0.088646)
		(layer "In6.Cu")
		(net "M_H_CPU1_SB_DQS_DN<7>")
	)
	(segment
		(start 185.169048 -209.241136)
		(end 180.129688 -209.241136)
		(width 0.18288)
		(layer "In6.Cu")
		(net "M_H_CPU1_SB_DQS_DN<7>")
	)
	(segment
		(start 203.419202 -208.530444)
		(end 203.158852 -208.790794)
		(width 0.18288)
		(layer "In6.Cu")
		(net "M_H_CPU1_SB_DQS_DN<7>")
	)
	(segment
		(start 158.86176 -209.305906)
		(end 158.31566 -209.305906)
		(width 0.18288)
		(layer "In6.Cu")
		(net "M_H_CPU1_SB_DQS_DN<7>")
	)
	(segment
		(start 165.204648 -209.181446)
		(end 164.658548 -209.181446)
		(width 0.18288)
		(layer "In6.Cu")
		(net "M_H_CPU1_SB_DQS_DN<7>")
	)
	(segment
		(start 131.578096 -228.957124)
		(end 131.563364 -228.948488)
		(width 0.088646)
		(layer "In6.Cu")
		(net "M_H_CPU1_SB_DQS_DN<7>")
	)
	(arc
		(start 131.563364 -228.948488)
		(mid 131.376166 -228.898345)
		(end 131.188968 -228.948488)
		(width 0.088646)
		(layer "In6.Cu")
		(net "M_H_CPU1_SB_DQS_DN<7>")
	)
	(arc
		(start 137.202164 -228.948488)
		(mid 137.014966 -228.898345)
		(end 136.827768 -228.948488)
		(width 0.088646)
		(layer "In6.Cu")
		(net "M_H_CPU1_SB_DQS_DN<7>")
	)
	(arc
		(start 134.948168 -228.948488)
		(mid 134.673969 -229.024323)
		(end 134.397496 -228.957124)
		(width 0.088646)
		(layer "In6.Cu")
		(net "M_H_CPU1_SB_DQS_DN<7>")
	)
	(arc
		(start 136.262364 -228.948488)
		(mid 136.075166 -228.898345)
		(end 135.887968 -228.948488)
		(width 0.088646)
		(layer "In6.Cu")
		(net "M_H_CPU1_SB_DQS_DN<7>")
	)
	(arc
		(start 132.128768 -228.948488)
		(mid 131.854569 -229.024323)
		(end 131.578096 -228.957124)
		(width 0.088646)
		(layer "In6.Cu")
		(net "M_H_CPU1_SB_DQS_DN<7>")
	)
	(arc
		(start 130.240278 -228.953568)
		(mid 130.109364 -229.089928)
		(end 130.061716 -229.272846)
		(width 0.088646)
		(layer "In6.Cu")
		(net "M_H_CPU1_SB_DQS_DN<7>")
	)
	(arc
		(start 134.008368 -228.948488)
		(mid 133.725666 -229.024264)
		(end 133.442964 -228.948488)
		(width 0.088646)
		(layer "In6.Cu")
		(net "M_H_CPU1_SB_DQS_DN<7>")
	)
	(arc
		(start 130.061716 -229.272846)
		(mid 129.989481 -229.54937)
		(end 129.791206 -229.755192)
		(width 0.088646)
		(layer "In6.Cu")
		(net "M_H_CPU1_SB_DQS_DN<7>")
	)
	(arc
		(start 134.382764 -228.948488)
		(mid 134.195566 -228.898345)
		(end 134.008368 -228.948488)
		(width 0.088646)
		(layer "In6.Cu")
		(net "M_H_CPU1_SB_DQS_DN<7>")
	)
	(arc
		(start 133.068568 -228.948488)
		(mid 132.785866 -229.024264)
		(end 132.503164 -228.948488)
		(width 0.088646)
		(layer "In6.Cu")
		(net "M_H_CPU1_SB_DQS_DN<7>")
	)
	(arc
		(start 132.503164 -228.948488)
		(mid 132.315966 -228.898345)
		(end 132.128768 -228.948488)
		(width 0.088646)
		(layer "In6.Cu")
		(net "M_H_CPU1_SB_DQS_DN<7>")
	)
	(arc
		(start 131.188968 -228.948488)
		(mid 130.914769 -229.024323)
		(end 130.638296 -228.957124)
		(width 0.088646)
		(layer "In6.Cu")
		(net "M_H_CPU1_SB_DQS_DN<7>")
	)
	(arc
		(start 136.827768 -228.948488)
		(mid 136.545066 -229.024264)
		(end 136.262364 -228.948488)
		(width 0.088646)
		(layer "In6.Cu")
		(net "M_H_CPU1_SB_DQS_DN<7>")
	)
	(arc
		(start 137.612882 -228.89464)
		(mid 137.416966 -228.991187)
		(end 137.202672 -228.948742)
		(width 0.088646)
		(layer "In6.Cu")
		(net "M_H_CPU1_SB_DQS_DN<7>")
	)
	(arc
		(start 130.623564 -228.948488)
		(mid 130.436366 -228.898345)
		(end 130.249168 -228.948488)
		(width 0.088646)
		(layer "In6.Cu")
		(net "M_H_CPU1_SB_DQS_DN<7>")
	)
	(arc
		(start 135.887968 -228.948488)
		(mid 135.605266 -229.024264)
		(end 135.322564 -228.948488)
		(width 0.088646)
		(layer "In6.Cu")
		(net "M_H_CPU1_SB_DQS_DN<7>")
	)
	(arc
		(start 135.322564 -228.948488)
		(mid 135.135366 -228.898345)
		(end 134.948168 -228.948488)
		(width 0.088646)
		(layer "In6.Cu")
		(net "M_H_CPU1_SB_DQS_DN<7>")
	)
	(arc
		(start 133.442964 -228.948488)
		(mid 133.255766 -228.898345)
		(end 133.068568 -228.948488)
		(width 0.088646)
		(layer "In6.Cu")
		(net "M_H_CPU1_SB_DQS_DN<7>")
	)
	(segment
		(start 208.977992 -218.295474)
		(end 209.461354 -218.295474)
		(width 0.20066)
		(layer "F.Cu")
		(net "M_H_CPU1_SB_DQS_DN<6>")
	)
	(segment
		(start 208.176114 -218.566746)
		(end 208.70672 -218.566746)
		(width 0.20066)
		(layer "F.Cu")
		(net "M_H_CPU1_SB_DQS_DN<6>")
	)
	(segment
		(start 210.603084 -218.1479)
		(end 210.60918 -218.141804)
		(width 0.1016)
		(layer "F.Cu")
		(net "M_H_CPU1_SB_DQS_DN<6>")
	)
	(segment
		(start 212.619336 -218.141804)
		(end 212.630258 -218.152726)
		(width 0.1016)
		(layer "F.Cu")
		(net "M_H_CPU1_SB_DQS_DN<6>")
	)
	(segment
		(start 209.886296 -217.870532)
		(end 210.008724 -217.870532)
		(width 0.20066)
		(layer "F.Cu")
		(net "M_H_CPU1_SB_DQS_DN<6>")
	)
	(segment
		(start 213.234778 -217.866976)
		(end 213.724744 -217.866976)
		(width 0.20066)
		(layer "F.Cu")
		(net "M_H_CPU1_SB_DQS_DN<6>")
	)
	(segment
		(start 207.071214 -218.566746)
		(end 208.176114 -218.566746)
		(width 0.20066)
		(layer "F.Cu")
		(net "M_H_CPU1_SB_DQS_DN<6>")
	)
	(segment
		(start 212.630258 -218.152726)
		(end 212.949028 -218.152726)
		(width 0.20066)
		(layer "F.Cu")
		(net "M_H_CPU1_SB_DQS_DN<6>")
	)
	(segment
		(start 210.008724 -217.870532)
		(end 210.286092 -218.1479)
		(width 0.20066)
		(layer "F.Cu")
		(net "M_H_CPU1_SB_DQS_DN<6>")
	)
	(segment
		(start 210.286092 -218.1479)
		(end 210.598258 -218.1479)
		(width 0.20066)
		(layer "F.Cu")
		(net "M_H_CPU1_SB_DQS_DN<6>")
	)
	(segment
		(start 125.737112 -233.064304)
		(end 125.737112 -232.528618)
		(width 0.20066)
		(layer "F.Cu")
		(net "M_H_CPU1_SB_DQS_DN<6>")
	)
	(segment
		(start 212.949028 -218.152726)
		(end 213.234778 -217.866976)
		(width 0.20066)
		(layer "F.Cu")
		(net "M_H_CPU1_SB_DQS_DN<6>")
	)
	(segment
		(start 214.17026 -218.312492)
		(end 214.961978 -218.312492)
		(width 0.20066)
		(layer "F.Cu")
		(net "M_H_CPU1_SB_DQS_DN<6>")
	)
	(segment
		(start 208.70672 -218.566746)
		(end 208.977992 -218.295474)
		(width 0.20066)
		(layer "F.Cu")
		(net "M_H_CPU1_SB_DQS_DN<6>")
	)
	(segment
		(start 215.216232 -218.566746)
		(end 215.719914 -218.566746)
		(width 0.20066)
		(layer "F.Cu")
		(net "M_H_CPU1_SB_DQS_DN<6>")
	)
	(segment
		(start 214.961978 -218.312492)
		(end 215.216232 -218.566746)
		(width 0.20066)
		(layer "F.Cu")
		(net "M_H_CPU1_SB_DQS_DN<6>")
	)
	(segment
		(start 210.598258 -218.1479)
		(end 210.603084 -218.1479)
		(width 0.101854)
		(layer "F.Cu")
		(net "M_H_CPU1_SB_DQS_DN<6>")
	)
	(segment
		(start 210.60918 -218.141804)
		(end 212.619336 -218.141804)
		(width 0.1016)
		(layer "F.Cu")
		(net "M_H_CPU1_SB_DQS_DN<6>")
	)
	(segment
		(start 213.724744 -217.866976)
		(end 214.17026 -218.312492)
		(width 0.20066)
		(layer "F.Cu")
		(net "M_H_CPU1_SB_DQS_DN<6>")
	)
	(segment
		(start 125.737112 -232.528618)
		(end 125.737366 -232.528364)
		(width 0.20066)
		(layer "F.Cu")
		(net "M_H_CPU1_SB_DQS_DN<6>")
	)
	(segment
		(start 209.461354 -218.295474)
		(end 209.886296 -217.870532)
		(width 0.20066)
		(layer "F.Cu")
		(net "M_H_CPU1_SB_DQS_DN<6>")
	)
	(segment
		(start 139.677394 -230.63708)
		(end 139.677394 -230.848408)
		(width 0.088646)
		(layer "In11.Cu")
		(net "M_H_CPU1_SB_DQS_DN<6>")
	)
	(segment
		(start 138.142472 -232.203752)
		(end 138.141964 -232.204006)
		(width 0.088646)
		(layer "In11.Cu")
		(net "M_H_CPU1_SB_DQS_DN<6>")
	)
	(segment
		(start 169.095166 -212.782912)
		(end 168.450514 -212.782912)
		(width 0.18288)
		(layer "In11.Cu")
		(net "M_H_CPU1_SB_DQS_DN<6>")
	)
	(segment
		(start 156.444188 -213.172802)
		(end 156.444188 -213.348824)
		(width 0.18288)
		(layer "In11.Cu")
		(net "M_H_CPU1_SB_DQS_DN<6>")
	)
	(segment
		(start 140.103352 -230.45928)
		(end 139.855194 -230.45928)
		(width 0.088646)
		(layer "In11.Cu")
		(net "M_H_CPU1_SB_DQS_DN<6>")
	)
	(segment
		(start 204.07884 -218.09837)
		(end 203.847192 -217.866722)
		(width 0.18288)
		(layer "In11.Cu")
		(net "M_H_CPU1_SB_DQS_DN<6>")
	)
	(segment
		(start 130.638296 -232.212642)
		(end 130.623564 -232.204006)
		(width 0.088646)
		(layer "In11.Cu")
		(net "M_H_CPU1_SB_DQS_DN<6>")
	)
	(segment
		(start 154.2415 -215.37549)
		(end 154.2415 -217.404696)
		(width 0.18288)
		(layer "In11.Cu")
		(net "M_H_CPU1_SB_DQS_DN<6>")
	)
	(segment
		(start 142.045436 -230.519224)
		(end 140.163296 -230.519224)
		(width 0.18288)
		(layer "In11.Cu")
		(net "M_H_CPU1_SB_DQS_DN<6>")
	)
	(segment
		(start 169.768266 -212.907372)
		(end 169.219626 -212.907372)
		(width 0.18288)
		(layer "In11.Cu")
		(net "M_H_CPU1_SB_DQS_DN<6>")
	)
	(segment
		(start 156.056076 -213.736936)
		(end 155.880054 -213.736936)
		(width 0.18288)
		(layer "In11.Cu")
		(net "M_H_CPU1_SB_DQS_DN<6>")
	)
	(segment
		(start 193.670682 -211.331302)
		(end 193.203576 -211.798408)
		(width 0.18288)
		(layer "In11.Cu")
		(net "M_H_CPU1_SB_DQS_DN<6>")
	)
	(segment
		(start 162.088576 -212.635592)
		(end 161.539936 -212.635592)
		(width 0.18288)
		(layer "In11.Cu")
		(net "M_H_CPU1_SB_DQS_DN<6>")
	)
	(segment
		(start 167.84447 -212.176868)
		(end 166.909242 -212.176868)
		(width 0.18288)
		(layer "In11.Cu")
		(net "M_H_CPU1_SB_DQS_DN<6>")
	)
	(segment
		(start 191.689482 -212.191092)
		(end 191.430402 -211.932012)
		(width 0.18288)
		(layer "In11.Cu")
		(net "M_H_CPU1_SB_DQS_DN<6>")
	)
	(segment
		(start 146.878802 -225.685858)
		(end 142.045436 -230.519224)
		(width 0.18288)
		(layer "In11.Cu")
		(net "M_H_CPU1_SB_DQS_DN<6>")
	)
	(segment
		(start 176.351946 -211.941156)
		(end 174.918116 -211.941156)
		(width 0.18288)
		(layer "In11.Cu")
		(net "M_H_CPU1_SB_DQS_DN<6>")
	)
	(segment
		(start 166.236142 -212.301328)
		(end 166.111682 -212.176868)
		(width 0.18288)
		(layer "In11.Cu")
		(net "M_H_CPU1_SB_DQS_DN<6>")
	)
	(segment
		(start 160.053782 -212.174328)
		(end 157.442662 -212.174328)
		(width 0.18288)
		(layer "In11.Cu")
		(net "M_H_CPU1_SB_DQS_DN<6>")
	)
	(segment
		(start 171.393358 -212.907372)
		(end 170.844718 -212.907372)
		(width 0.18288)
		(layer "In11.Cu")
		(net "M_H_CPU1_SB_DQS_DN<6>")
	)
	(segment
		(start 169.892726 -212.782912)
		(end 169.768266 -212.907372)
		(width 0.18288)
		(layer "In11.Cu")
		(net "M_H_CPU1_SB_DQS_DN<6>")
	)
	(segment
		(start 189.993778 -211.932012)
		(end 189.138052 -211.076286)
		(width 0.18288)
		(layer "In11.Cu")
		(net "M_H_CPU1_SB_DQS_DN<6>")
	)
	(segment
		(start 201.154792 -217.462354)
		(end 199.796146 -216.103708)
		(width 0.18288)
		(layer "In11.Cu")
		(net "M_H_CPU1_SB_DQS_DN<6>")
	)
	(segment
		(start 192.895474 -211.926424)
		(end 192.476374 -211.926424)
		(width 0.18288)
		(layer "In11.Cu")
		(net "M_H_CPU1_SB_DQS_DN<6>")
	)
	(segment
		(start 125.746764 -232.381044)
		(end 125.737366 -232.403396)
		(width 0.088646)
		(layer "In11.Cu")
		(net "M_H_CPU1_SB_DQS_DN<6>")
	)
	(segment
		(start 163.434776 -212.635592)
		(end 162.886136 -212.635592)
		(width 0.18288)
		(layer "In11.Cu")
		(net "M_H_CPU1_SB_DQS_DN<6>")
	)
	(segment
		(start 131.578096 -232.212642)
		(end 131.563364 -232.204006)
		(width 0.088646)
		(layer "In11.Cu")
		(net "M_H_CPU1_SB_DQS_DN<6>")
	)
	(segment
		(start 166.909242 -212.176868)
		(end 166.784782 -212.301328)
		(width 0.18288)
		(layer "In11.Cu")
		(net "M_H_CPU1_SB_DQS_DN<6>")
	)
	(segment
		(start 168.450514 -212.782912)
		(end 167.84447 -212.176868)
		(width 0.18288)
		(layer "In11.Cu")
		(net "M_H_CPU1_SB_DQS_DN<6>")
	)
	(segment
		(start 181.549294 -210.33613)
		(end 181.000654 -210.33613)
		(width 0.18288)
		(layer "In11.Cu")
		(net "M_H_CPU1_SB_DQS_DN<6>")
	)
	(segment
		(start 173.024038 -213.040976)
		(end 172.501814 -213.040976)
		(width 0.18288)
		(layer "In11.Cu")
		(net "M_H_CPU1_SB_DQS_DN<6>")
	)
	(segment
		(start 198.625714 -215.445594)
		(end 198.081392 -214.129874)
		(width 0.18288)
		(layer "In11.Cu")
		(net "M_H_CPU1_SB_DQS_DN<6>")
	)
	(segment
		(start 164.95522 -212.176868)
		(end 164.620956 -212.511132)
		(width 0.18288)
		(layer "In11.Cu")
		(net "M_H_CPU1_SB_DQS_DN<6>")
	)
	(segment
		(start 172.24375 -212.782912)
		(end 171.517818 -212.782912)
		(width 0.18288)
		(layer "In11.Cu")
		(net "M_H_CPU1_SB_DQS_DN<6>")
	)
	(segment
		(start 178.083718 -211.926424)
		(end 177.388774 -211.926424)
		(width 0.18288)
		(layer "In11.Cu")
		(net "M_H_CPU1_SB_DQS_DN<6>")
	)
	(segment
		(start 139.855194 -230.45928)
		(end 139.677394 -230.63708)
		(width 0.088646)
		(layer "In11.Cu")
		(net "M_H_CPU1_SB_DQS_DN<6>")
	)
	(segment
		(start 139.677394 -230.848408)
		(end 138.989562 -231.536494)
		(width 0.088646)
		(layer "In11.Cu")
		(net "M_H_CPU1_SB_DQS_DN<6>")
	)
	(segment
		(start 204.980032 -218.548966)
		(end 204.07884 -218.09837)
		(width 0.18288)
		(layer "In11.Cu")
		(net "M_H_CPU1_SB_DQS_DN<6>")
	)
	(segment
		(start 202.677014 -218.141042)
		(end 202.403964 -217.867992)
		(width 0.18288)
		(layer "In11.Cu")
		(net "M_H_CPU1_SB_DQS_DN<6>")
	)
	(segment
		(start 125.842268 -232.29824)
		(end 125.82017 -232.307638)
		(width 0.088646)
		(layer "In11.Cu")
		(net "M_H_CPU1_SB_DQS_DN<6>")
	)
	(segment
		(start 154.801062 -214.815928)
		(end 154.2415 -215.37549)
		(width 0.18288)
		(layer "In11.Cu")
		(net "M_H_CPU1_SB_DQS_DN<6>")
	)
	(segment
		(start 184.08142 -211.077302)
		(end 183.215788 -210.21167)
		(width 0.18288)
		(layer "In11.Cu")
		(net "M_H_CPU1_SB_DQS_DN<6>")
	)
	(segment
		(start 202.134216 -217.867992)
		(end 201.154792 -217.462354)
		(width 0.18288)
		(layer "In11.Cu")
		(net "M_H_CPU1_SB_DQS_DN<6>")
	)
	(segment
		(start 161.415476 -212.511132)
		(end 160.866836 -212.511132)
		(width 0.18288)
		(layer "In11.Cu")
		(net "M_H_CPU1_SB_DQS_DN<6>")
	)
	(segment
		(start 194.519804 -211.331302)
		(end 193.670682 -211.331302)
		(width 0.18288)
		(layer "In11.Cu")
		(net "M_H_CPU1_SB_DQS_DN<6>")
	)
	(segment
		(start 188.111638 -211.340954)
		(end 187.589414 -211.340954)
		(width 0.18288)
		(layer "In11.Cu")
		(net "M_H_CPU1_SB_DQS_DN<6>")
	)
	(segment
		(start 189.138052 -211.076286)
		(end 188.376306 -211.076286)
		(width 0.18288)
		(layer "In11.Cu")
		(net "M_H_CPU1_SB_DQS_DN<6>")
	)
	(segment
		(start 126.390146 -232.262426)
		(end 126.322328 -232.288842)
		(width 0.088646)
		(layer "In11.Cu")
		(net "M_H_CPU1_SB_DQS_DN<6>")
	)
	(segment
		(start 185.78703 -211.077302)
		(end 185.66257 -211.201762)
		(width 0.18288)
		(layer "In11.Cu")
		(net "M_H_CPU1_SB_DQS_DN<6>")
	)
	(segment
		(start 179.048156 -210.961986)
		(end 178.083718 -211.926424)
		(width 0.18288)
		(layer "In11.Cu")
		(net "M_H_CPU1_SB_DQS_DN<6>")
	)
	(segment
		(start 173.288706 -212.776308)
		(end 173.024038 -213.040976)
		(width 0.18288)
		(layer "In11.Cu")
		(net "M_H_CPU1_SB_DQS_DN<6>")
	)
	(segment
		(start 180.108352 -210.21167)
		(end 179.358036 -210.961986)
		(width 0.18288)
		(layer "In11.Cu")
		(net "M_H_CPU1_SB_DQS_DN<6>")
	)
	(segment
		(start 194.92722 -211.499704)
		(end 194.519804 -211.331302)
		(width 0.18288)
		(layer "In11.Cu")
		(net "M_H_CPU1_SB_DQS_DN<6>")
	)
	(segment
		(start 192.211706 -212.191092)
		(end 191.689482 -212.191092)
		(width 0.18288)
		(layer "In11.Cu")
		(net "M_H_CPU1_SB_DQS_DN<6>")
	)
	(segment
		(start 176.601882 -212.191092)
		(end 176.351946 -211.941156)
		(width 0.18288)
		(layer "In11.Cu")
		(net "M_H_CPU1_SB_DQS_DN<6>")
	)
	(segment
		(start 193.203576 -211.798408)
		(end 192.895474 -211.926424)
		(width 0.18288)
		(layer "In11.Cu")
		(net "M_H_CPU1_SB_DQS_DN<6>")
	)
	(segment
		(start 183.215788 -210.21167)
		(end 181.673754 -210.21167)
		(width 0.18288)
		(layer "In11.Cu")
		(net "M_H_CPU1_SB_DQS_DN<6>")
	)
	(segment
		(start 126.874524 -232.210102)
		(end 126.86411 -232.204006)
		(width 0.088646)
		(layer "In11.Cu")
		(net "M_H_CPU1_SB_DQS_DN<6>")
	)
	(segment
		(start 184.98947 -211.077302)
		(end 184.08142 -211.077302)
		(width 0.18288)
		(layer "In11.Cu")
		(net "M_H_CPU1_SB_DQS_DN<6>")
	)
	(segment
		(start 127.818896 -232.212642)
		(end 127.804164 -232.204006)
		(width 0.088646)
		(layer "In11.Cu")
		(net "M_H_CPU1_SB_DQS_DN<6>")
	)
	(segment
		(start 205.53934 -218.548966)
		(end 204.980032 -218.548966)
		(width 0.18288)
		(layer "In11.Cu")
		(net "M_H_CPU1_SB_DQS_DN<6>")
	)
	(segment
		(start 134.948168 -232.204006)
		(end 134.94766 -232.203752)
		(width 0.088646)
		(layer "In11.Cu")
		(net "M_H_CPU1_SB_DQS_DN<6>")
	)
	(segment
		(start 156.444188 -213.348824)
		(end 156.056076 -213.736936)
		(width 0.18288)
		(layer "In11.Cu")
		(net "M_H_CPU1_SB_DQS_DN<6>")
	)
	(segment
		(start 192.476374 -211.926424)
		(end 192.211706 -212.191092)
		(width 0.18288)
		(layer "In11.Cu")
		(net "M_H_CPU1_SB_DQS_DN<6>")
	)
	(segment
		(start 170.844718 -212.907372)
		(end 170.720258 -212.782912)
		(width 0.18288)
		(layer "In11.Cu")
		(net "M_H_CPU1_SB_DQS_DN<6>")
	)
	(segment
		(start 206.783178 -218.27998)
		(end 206.189834 -218.27998)
		(width 0.18288)
		(layer "In11.Cu")
		(net "M_H_CPU1_SB_DQS_DN<6>")
	)
	(segment
		(start 188.376306 -211.076286)
		(end 188.111638 -211.340954)
		(width 0.18288)
		(layer "In11.Cu")
		(net "M_H_CPU1_SB_DQS_DN<6>")
	)
	(segment
		(start 140.163296 -230.519224)
		(end 140.103352 -230.45928)
		(width 0.088646)
		(layer "In11.Cu")
		(net "M_H_CPU1_SB_DQS_DN<6>")
	)
	(segment
		(start 180.876194 -210.21167)
		(end 180.108352 -210.21167)
		(width 0.18288)
		(layer "In11.Cu")
		(net "M_H_CPU1_SB_DQS_DN<6>")
	)
	(segment
		(start 154.977084 -214.815928)
		(end 154.801062 -214.815928)
		(width 0.18288)
		(layer "In11.Cu")
		(net "M_H_CPU1_SB_DQS_DN<6>")
	)
	(segment
		(start 126.48946 -232.203752)
		(end 126.390146 -232.262426)
		(width 0.088646)
		(layer "In11.Cu")
		(net "M_H_CPU1_SB_DQS_DN<6>")
	)
	(segment
		(start 160.866836 -212.511132)
		(end 160.053782 -212.174328)
		(width 0.18288)
		(layer "In11.Cu")
		(net "M_H_CPU1_SB_DQS_DN<6>")
	)
	(segment
		(start 171.517818 -212.782912)
		(end 171.393358 -212.907372)
		(width 0.18288)
		(layer "In11.Cu")
		(net "M_H_CPU1_SB_DQS_DN<6>")
	)
	(segment
		(start 197.489318 -213.537546)
		(end 196.592698 -213.165182)
		(width 0.18288)
		(layer "In11.Cu")
		(net "M_H_CPU1_SB_DQS_DN<6>")
	)
	(segment
		(start 187.589414 -211.340954)
		(end 187.325762 -211.077302)
		(width 0.18288)
		(layer "In11.Cu")
		(net "M_H_CPU1_SB_DQS_DN<6>")
	)
	(segment
		(start 155.365196 -214.251794)
		(end 155.365196 -214.427816)
		(width 0.18288)
		(layer "In11.Cu")
		(net "M_H_CPU1_SB_DQS_DN<6>")
	)
	(segment
		(start 154.2415 -217.404696)
		(end 146.878802 -224.767394)
		(width 0.18288)
		(layer "In11.Cu")
		(net "M_H_CPU1_SB_DQS_DN<6>")
	)
	(segment
		(start 187.325762 -211.077302)
		(end 185.78703 -211.077302)
		(width 0.18288)
		(layer "In11.Cu")
		(net "M_H_CPU1_SB_DQS_DN<6>")
	)
	(segment
		(start 174.918116 -211.941156)
		(end 174.082964 -212.776308)
		(width 0.18288)
		(layer "In11.Cu")
		(net "M_H_CPU1_SB_DQS_DN<6>")
	)
	(segment
		(start 172.501814 -213.040976)
		(end 172.24375 -212.782912)
		(width 0.18288)
		(layer "In11.Cu")
		(net "M_H_CPU1_SB_DQS_DN<6>")
	)
	(segment
		(start 170.720258 -212.782912)
		(end 169.892726 -212.782912)
		(width 0.18288)
		(layer "In11.Cu")
		(net "M_H_CPU1_SB_DQS_DN<6>")
	)
	(segment
		(start 166.784782 -212.301328)
		(end 166.236142 -212.301328)
		(width 0.18288)
		(layer "In11.Cu")
		(net "M_H_CPU1_SB_DQS_DN<6>")
	)
	(segment
		(start 138.989562 -231.536494)
		(end 138.989562 -231.714548)
		(width 0.088646)
		(layer "In11.Cu")
		(net "M_H_CPU1_SB_DQS_DN<6>")
	)
	(segment
		(start 191.430402 -211.932012)
		(end 189.993778 -211.932012)
		(width 0.18288)
		(layer "In11.Cu")
		(net "M_H_CPU1_SB_DQS_DN<6>")
	)
	(segment
		(start 164.620956 -212.511132)
		(end 163.559236 -212.511132)
		(width 0.18288)
		(layer "In11.Cu")
		(net "M_H_CPU1_SB_DQS_DN<6>")
	)
	(segment
		(start 198.92137 -215.74125)
		(end 198.625714 -215.445594)
		(width 0.18288)
		(layer "In11.Cu")
		(net "M_H_CPU1_SB_DQS_DN<6>")
	)
	(segment
		(start 207.071214 -218.566746)
		(end 206.783178 -218.27998)
		(width 0.18288)
		(layer "In11.Cu")
		(net "M_H_CPU1_SB_DQS_DN<6>")
	)
	(segment
		(start 126.322328 -232.288842)
		(end 125.842268 -232.29824)
		(width 0.088646)
		(layer "In11.Cu")
		(net "M_H_CPU1_SB_DQS_DN<6>")
	)
	(segment
		(start 125.82017 -232.307638)
		(end 125.746764 -232.381044)
		(width 0.088646)
		(layer "In11.Cu")
		(net "M_H_CPU1_SB_DQS_DN<6>")
	)
	(segment
		(start 203.199238 -218.141042)
		(end 202.677014 -218.141042)
		(width 0.18288)
		(layer "In11.Cu")
		(net "M_H_CPU1_SB_DQS_DN<6>")
	)
	(segment
		(start 177.124106 -212.191092)
		(end 176.601882 -212.191092)
		(width 0.18288)
		(layer "In11.Cu")
		(net "M_H_CPU1_SB_DQS_DN<6>")
	)
	(segment
		(start 203.847192 -217.866722)
		(end 203.473558 -217.866722)
		(width 0.18288)
		(layer "In11.Cu")
		(net "M_H_CPU1_SB_DQS_DN<6>")
	)
	(segment
		(start 163.559236 -212.511132)
		(end 163.434776 -212.635592)
		(width 0.18288)
		(layer "In11.Cu")
		(net "M_H_CPU1_SB_DQS_DN<6>")
	)
	(segment
		(start 174.082964 -212.776308)
		(end 173.288706 -212.776308)
		(width 0.18288)
		(layer "In11.Cu")
		(net "M_H_CPU1_SB_DQS_DN<6>")
	)
	(segment
		(start 157.442662 -212.174328)
		(end 156.444188 -213.172802)
		(width 0.18288)
		(layer "In11.Cu")
		(net "M_H_CPU1_SB_DQS_DN<6>")
	)
	(segment
		(start 162.886136 -212.635592)
		(end 162.761676 -212.511132)
		(width 0.18288)
		(layer "In11.Cu")
		(net "M_H_CPU1_SB_DQS_DN<6>")
	)
	(segment
		(start 134.008368 -232.204006)
		(end 133.997954 -232.210102)
		(width 0.088646)
		(layer "In11.Cu")
		(net "M_H_CPU1_SB_DQS_DN<6>")
	)
	(segment
		(start 179.358036 -210.961986)
		(end 179.048156 -210.961986)
		(width 0.18288)
		(layer "In11.Cu")
		(net "M_H_CPU1_SB_DQS_DN<6>")
	)
	(segment
		(start 162.761676 -212.511132)
		(end 162.213036 -212.511132)
		(width 0.18288)
		(layer "In11.Cu")
		(net "M_H_CPU1_SB_DQS_DN<6>")
	)
	(segment
		(start 181.000654 -210.33613)
		(end 180.876194 -210.21167)
		(width 0.18288)
		(layer "In11.Cu")
		(net "M_H_CPU1_SB_DQS_DN<6>")
	)
	(segment
		(start 206.189834 -218.27998)
		(end 205.53934 -218.548966)
		(width 0.18288)
		(layer "In11.Cu")
		(net "M_H_CPU1_SB_DQS_DN<6>")
	)
	(segment
		(start 198.081392 -214.129874)
		(end 197.489318 -213.537546)
		(width 0.18288)
		(layer "In11.Cu")
		(net "M_H_CPU1_SB_DQS_DN<6>")
	)
	(segment
		(start 155.365196 -214.427816)
		(end 154.977084 -214.815928)
		(width 0.18288)
		(layer "In11.Cu")
		(net "M_H_CPU1_SB_DQS_DN<6>")
	)
	(segment
		(start 196.592698 -213.165182)
		(end 194.92722 -211.499704)
		(width 0.18288)
		(layer "In11.Cu")
		(net "M_H_CPU1_SB_DQS_DN<6>")
	)
	(segment
		(start 132.513578 -232.210102)
		(end 132.503164 -232.204006)
		(width 0.088646)
		(layer "In11.Cu")
		(net "M_H_CPU1_SB_DQS_DN<6>")
	)
	(segment
		(start 202.403964 -217.867992)
		(end 202.134216 -217.867992)
		(width 0.18288)
		(layer "In11.Cu")
		(net "M_H_CPU1_SB_DQS_DN<6>")
	)
	(segment
		(start 126.86411 -232.204006)
		(end 126.864364 -232.203752)
		(width 0.088646)
		(layer "In11.Cu")
		(net "M_H_CPU1_SB_DQS_DN<6>")
	)
	(segment
		(start 125.737366 -232.403396)
		(end 125.737366 -232.528364)
		(width 0.088646)
		(layer "In11.Cu")
		(net "M_H_CPU1_SB_DQS_DN<6>")
	)
	(segment
		(start 161.539936 -212.635592)
		(end 161.415476 -212.511132)
		(width 0.18288)
		(layer "In11.Cu")
		(net "M_H_CPU1_SB_DQS_DN<6>")
	)
	(segment
		(start 166.111682 -212.176868)
		(end 164.95522 -212.176868)
		(width 0.18288)
		(layer "In11.Cu")
		(net "M_H_CPU1_SB_DQS_DN<6>")
	)
	(segment
		(start 199.796146 -216.103708)
		(end 198.92137 -215.74125)
		(width 0.18288)
		(layer "In11.Cu")
		(net "M_H_CPU1_SB_DQS_DN<6>")
	)
	(segment
		(start 181.673754 -210.21167)
		(end 181.549294 -210.33613)
		(width 0.18288)
		(layer "In11.Cu")
		(net "M_H_CPU1_SB_DQS_DN<6>")
	)
	(segment
		(start 129.698496 -232.212642)
		(end 129.683764 -232.204006)
		(width 0.088646)
		(layer "In11.Cu")
		(net "M_H_CPU1_SB_DQS_DN<6>")
	)
	(segment
		(start 203.473558 -217.866722)
		(end 203.199238 -218.141042)
		(width 0.18288)
		(layer "In11.Cu")
		(net "M_H_CPU1_SB_DQS_DN<6>")
	)
	(segment
		(start 185.11393 -211.201762)
		(end 184.98947 -211.077302)
		(width 0.18288)
		(layer "In11.Cu")
		(net "M_H_CPU1_SB_DQS_DN<6>")
	)
	(segment
		(start 162.213036 -212.511132)
		(end 162.088576 -212.635592)
		(width 0.18288)
		(layer "In11.Cu")
		(net "M_H_CPU1_SB_DQS_DN<6>")
	)
	(segment
		(start 185.66257 -211.201762)
		(end 185.11393 -211.201762)
		(width 0.18288)
		(layer "In11.Cu")
		(net "M_H_CPU1_SB_DQS_DN<6>")
	)
	(segment
		(start 169.219626 -212.907372)
		(end 169.095166 -212.782912)
		(width 0.18288)
		(layer "In11.Cu")
		(net "M_H_CPU1_SB_DQS_DN<6>")
	)
	(segment
		(start 146.878802 -224.767394)
		(end 146.878802 -225.685858)
		(width 0.18288)
		(layer "In11.Cu")
		(net "M_H_CPU1_SB_DQS_DN<6>")
	)
	(segment
		(start 155.880054 -213.736936)
		(end 155.365196 -214.251794)
		(width 0.18288)
		(layer "In11.Cu")
		(net "M_H_CPU1_SB_DQS_DN<6>")
	)
	(segment
		(start 177.388774 -211.926424)
		(end 177.124106 -212.191092)
		(width 0.18288)
		(layer "In11.Cu")
		(net "M_H_CPU1_SB_DQS_DN<6>")
	)
	(arc
		(start 138.989562 -231.714548)
		(mid 138.707207 -232.203709)
		(end 138.142472 -232.203752)
		(width 0.088646)
		(layer "In11.Cu")
		(net "M_H_CPU1_SB_DQS_DN<6>")
	)
	(arc
		(start 130.623564 -232.204006)
		(mid 130.436366 -232.153863)
		(end 130.249168 -232.204006)
		(width 0.088646)
		(layer "In11.Cu")
		(net "M_H_CPU1_SB_DQS_DN<6>")
	)
	(arc
		(start 126.864364 -232.203752)
		(mid 126.676912 -232.153516)
		(end 126.48946 -232.203752)
		(width 0.088646)
		(layer "In11.Cu")
		(net "M_H_CPU1_SB_DQS_DN<6>")
	)
	(arc
		(start 131.188968 -232.204006)
		(mid 130.914769 -232.279841)
		(end 130.638296 -232.212642)
		(width 0.088646)
		(layer "In11.Cu")
		(net "M_H_CPU1_SB_DQS_DN<6>")
	)
	(arc
		(start 133.44271 -232.204006)
		(mid 133.255512 -232.153863)
		(end 133.068314 -232.204006)
		(width 0.088646)
		(layer "In11.Cu")
		(net "M_H_CPU1_SB_DQS_DN<6>")
	)
	(arc
		(start 132.128768 -232.204006)
		(mid 131.854569 -232.279841)
		(end 131.578096 -232.212642)
		(width 0.088646)
		(layer "In11.Cu")
		(net "M_H_CPU1_SB_DQS_DN<6>")
	)
	(arc
		(start 133.068314 -232.204006)
		(mid 132.791755 -232.279749)
		(end 132.513578 -232.210102)
		(width 0.088646)
		(layer "In11.Cu")
		(net "M_H_CPU1_SB_DQS_DN<6>")
	)
	(arc
		(start 132.503164 -232.204006)
		(mid 132.315966 -232.153863)
		(end 132.128768 -232.204006)
		(width 0.088646)
		(layer "In11.Cu")
		(net "M_H_CPU1_SB_DQS_DN<6>")
	)
	(arc
		(start 128.369568 -232.204006)
		(mid 128.095369 -232.279841)
		(end 127.818896 -232.212642)
		(width 0.088646)
		(layer "In11.Cu")
		(net "M_H_CPU1_SB_DQS_DN<6>")
	)
	(arc
		(start 130.249168 -232.204006)
		(mid 129.974969 -232.279841)
		(end 129.698496 -232.212642)
		(width 0.088646)
		(layer "In11.Cu")
		(net "M_H_CPU1_SB_DQS_DN<6>")
	)
	(arc
		(start 131.563364 -232.204006)
		(mid 131.376166 -232.153863)
		(end 131.188968 -232.204006)
		(width 0.088646)
		(layer "In11.Cu")
		(net "M_H_CPU1_SB_DQS_DN<6>")
	)
	(arc
		(start 134.94766 -232.203752)
		(mid 134.665241 -232.279562)
		(end 134.382764 -232.204006)
		(width 0.088646)
		(layer "In11.Cu")
		(net "M_H_CPU1_SB_DQS_DN<6>")
	)
	(arc
		(start 135.322564 -232.204006)
		(mid 135.135366 -232.153863)
		(end 134.948168 -232.204006)
		(width 0.088646)
		(layer "In11.Cu")
		(net "M_H_CPU1_SB_DQS_DN<6>")
	)
	(arc
		(start 127.804164 -232.204006)
		(mid 127.616966 -232.153863)
		(end 127.429768 -232.204006)
		(width 0.088646)
		(layer "In11.Cu")
		(net "M_H_CPU1_SB_DQS_DN<6>")
	)
	(arc
		(start 129.683764 -232.204006)
		(mid 129.496566 -232.153863)
		(end 129.309368 -232.204006)
		(width 0.088646)
		(layer "In11.Cu")
		(net "M_H_CPU1_SB_DQS_DN<6>")
	)
	(arc
		(start 134.382764 -232.204006)
		(mid 134.195566 -232.153863)
		(end 134.008368 -232.204006)
		(width 0.088646)
		(layer "In11.Cu")
		(net "M_H_CPU1_SB_DQS_DN<6>")
	)
	(arc
		(start 128.743964 -232.204006)
		(mid 128.556766 -232.153863)
		(end 128.369568 -232.204006)
		(width 0.088646)
		(layer "In11.Cu")
		(net "M_H_CPU1_SB_DQS_DN<6>")
	)
	(arc
		(start 133.997954 -232.210102)
		(mid 133.719522 -232.279948)
		(end 133.44271 -232.204006)
		(width 0.088646)
		(layer "In11.Cu")
		(net "M_H_CPU1_SB_DQS_DN<6>")
	)
	(arc
		(start 138.141964 -232.204006)
		(mid 137.954766 -232.153863)
		(end 137.767568 -232.204006)
		(width 0.088646)
		(layer "In11.Cu")
		(net "M_H_CPU1_SB_DQS_DN<6>")
	)
	(arc
		(start 129.309368 -232.204006)
		(mid 129.026666 -232.279782)
		(end 128.743964 -232.204006)
		(width 0.088646)
		(layer "In11.Cu")
		(net "M_H_CPU1_SB_DQS_DN<6>")
	)
	(arc
		(start 127.429768 -232.204006)
		(mid 127.152955 -232.279876)
		(end 126.874524 -232.210102)
		(width 0.088646)
		(layer "In11.Cu")
		(net "M_H_CPU1_SB_DQS_DN<6>")
	)
	(arc
		(start 136.827768 -232.204006)
		(mid 136.545066 -232.279782)
		(end 136.262364 -232.204006)
		(width 0.088646)
		(layer "In11.Cu")
		(net "M_H_CPU1_SB_DQS_DN<6>")
	)
	(arc
		(start 137.202164 -232.204006)
		(mid 137.014966 -232.153863)
		(end 136.827768 -232.204006)
		(width 0.088646)
		(layer "In11.Cu")
		(net "M_H_CPU1_SB_DQS_DN<6>")
	)
	(arc
		(start 136.262364 -232.204006)
		(mid 136.075166 -232.153863)
		(end 135.887968 -232.204006)
		(width 0.088646)
		(layer "In11.Cu")
		(net "M_H_CPU1_SB_DQS_DN<6>")
	)
	(arc
		(start 137.767568 -232.204006)
		(mid 137.484866 -232.279782)
		(end 137.202164 -232.204006)
		(width 0.088646)
		(layer "In11.Cu")
		(net "M_H_CPU1_SB_DQS_DN<6>")
	)
	(arc
		(start 135.887968 -232.204006)
		(mid 135.605266 -232.279782)
		(end 135.322564 -232.204006)
		(width 0.088646)
		(layer "In11.Cu")
		(net "M_H_CPU1_SB_DQS_DN<6>")
	)
	(segment
		(start 125.737112 -237.947454)
		(end 125.737112 -237.411768)
		(width 0.20066)
		(layer "F.Cu")
		(net "M_H_CPU1_SB_DQS_DN<5>")
	)
	(segment
		(start 213.234778 -227.21697)
		(end 213.724744 -227.21697)
		(width 0.20066)
		(layer "F.Cu")
		(net "M_H_CPU1_SB_DQS_DN<5>")
	)
	(segment
		(start 207.071214 -227.91674)
		(end 208.176114 -227.91674)
		(width 0.20066)
		(layer "F.Cu")
		(net "M_H_CPU1_SB_DQS_DN<5>")
	)
	(segment
		(start 210.603084 -227.497894)
		(end 210.60918 -227.491798)
		(width 0.1016)
		(layer "F.Cu")
		(net "M_H_CPU1_SB_DQS_DN<5>")
	)
	(segment
		(start 208.70672 -227.91674)
		(end 208.977992 -227.645468)
		(width 0.20066)
		(layer "F.Cu")
		(net "M_H_CPU1_SB_DQS_DN<5>")
	)
	(segment
		(start 125.737112 -237.411768)
		(end 125.737366 -237.411514)
		(width 0.20066)
		(layer "F.Cu")
		(net "M_H_CPU1_SB_DQS_DN<5>")
	)
	(segment
		(start 212.949028 -227.50272)
		(end 213.234778 -227.21697)
		(width 0.20066)
		(layer "F.Cu")
		(net "M_H_CPU1_SB_DQS_DN<5>")
	)
	(segment
		(start 210.008724 -227.220526)
		(end 210.286092 -227.497894)
		(width 0.20066)
		(layer "F.Cu")
		(net "M_H_CPU1_SB_DQS_DN<5>")
	)
	(segment
		(start 210.286092 -227.497894)
		(end 210.598258 -227.497894)
		(width 0.20066)
		(layer "F.Cu")
		(net "M_H_CPU1_SB_DQS_DN<5>")
	)
	(segment
		(start 208.977992 -227.645468)
		(end 209.461354 -227.645468)
		(width 0.20066)
		(layer "F.Cu")
		(net "M_H_CPU1_SB_DQS_DN<5>")
	)
	(segment
		(start 208.176114 -227.91674)
		(end 208.70672 -227.91674)
		(width 0.20066)
		(layer "F.Cu")
		(net "M_H_CPU1_SB_DQS_DN<5>")
	)
	(segment
		(start 209.461354 -227.645468)
		(end 209.886296 -227.220526)
		(width 0.20066)
		(layer "F.Cu")
		(net "M_H_CPU1_SB_DQS_DN<5>")
	)
	(segment
		(start 209.886296 -227.220526)
		(end 210.008724 -227.220526)
		(width 0.20066)
		(layer "F.Cu")
		(net "M_H_CPU1_SB_DQS_DN<5>")
	)
	(segment
		(start 214.961978 -227.662486)
		(end 215.216232 -227.91674)
		(width 0.20066)
		(layer "F.Cu")
		(net "M_H_CPU1_SB_DQS_DN<5>")
	)
	(segment
		(start 210.60918 -227.491798)
		(end 212.619336 -227.491798)
		(width 0.1016)
		(layer "F.Cu")
		(net "M_H_CPU1_SB_DQS_DN<5>")
	)
	(segment
		(start 212.630258 -227.50272)
		(end 212.949028 -227.50272)
		(width 0.20066)
		(layer "F.Cu")
		(net "M_H_CPU1_SB_DQS_DN<5>")
	)
	(segment
		(start 210.598258 -227.497894)
		(end 210.603084 -227.497894)
		(width 0.101854)
		(layer "F.Cu")
		(net "M_H_CPU1_SB_DQS_DN<5>")
	)
	(segment
		(start 214.17026 -227.662486)
		(end 214.961978 -227.662486)
		(width 0.20066)
		(layer "F.Cu")
		(net "M_H_CPU1_SB_DQS_DN<5>")
	)
	(segment
		(start 212.619336 -227.491798)
		(end 212.630258 -227.50272)
		(width 0.1016)
		(layer "F.Cu")
		(net "M_H_CPU1_SB_DQS_DN<5>")
	)
	(segment
		(start 215.216232 -227.91674)
		(end 215.719914 -227.91674)
		(width 0.20066)
		(layer "F.Cu")
		(net "M_H_CPU1_SB_DQS_DN<5>")
	)
	(segment
		(start 213.724744 -227.21697)
		(end 214.17026 -227.662486)
		(width 0.20066)
		(layer "F.Cu")
		(net "M_H_CPU1_SB_DQS_DN<5>")
	)
	(segment
		(start 134.008368 -237.08741)
		(end 133.997954 -237.093506)
		(width 0.088646)
		(layer "In11.Cu")
		(net "M_H_CPU1_SB_DQS_DN<5>")
	)
	(segment
		(start 170.758866 -223.83877)
		(end 170.210226 -223.83877)
		(width 0.18288)
		(layer "In11.Cu")
		(net "M_H_CPU1_SB_DQS_DN<5>")
	)
	(segment
		(start 198.908416 -226.918012)
		(end 198.401178 -226.707954)
		(width 0.18288)
		(layer "In11.Cu")
		(net "M_H_CPU1_SB_DQS_DN<5>")
	)
	(segment
		(start 155.870402 -225.546412)
		(end 144.79905 -236.617764)
		(width 0.18288)
		(layer "In11.Cu")
		(net "M_H_CPU1_SB_DQS_DN<5>")
	)
	(segment
		(start 132.513578 -237.093506)
		(end 132.503164 -237.08741)
		(width 0.088646)
		(layer "In11.Cu")
		(net "M_H_CPU1_SB_DQS_DN<5>")
	)
	(segment
		(start 161.60369 -224.940876)
		(end 161.332926 -224.670112)
		(width 0.18288)
		(layer "In11.Cu")
		(net "M_H_CPU1_SB_DQS_DN<5>")
	)
	(segment
		(start 158.179262 -225.526092)
		(end 157.916626 -225.788728)
		(width 0.18288)
		(layer "In11.Cu")
		(net "M_H_CPU1_SB_DQS_DN<5>")
	)
	(segment
		(start 206.338932 -227.74529)
		(end 206.183738 -227.809552)
		(width 0.18288)
		(layer "In11.Cu")
		(net "M_H_CPU1_SB_DQS_DN<5>")
	)
	(segment
		(start 177.124106 -223.240854)
		(end 176.647602 -223.240854)
		(width 0.18288)
		(layer "In11.Cu")
		(net "M_H_CPU1_SB_DQS_DN<5>")
	)
	(segment
		(start 136.277096 -237.096046)
		(end 136.262364 -237.08741)
		(width 0.088646)
		(layer "In11.Cu")
		(net "M_H_CPU1_SB_DQS_DN<5>")
	)
	(segment
		(start 182.715408 -222.750126)
		(end 182.590948 -222.874586)
		(width 0.18288)
		(layer "In11.Cu")
		(net "M_H_CPU1_SB_DQS_DN<5>")
	)
	(segment
		(start 166.594536 -224.847658)
		(end 166.045896 -224.847658)
		(width 0.18288)
		(layer "In11.Cu")
		(net "M_H_CPU1_SB_DQS_DN<5>")
	)
	(segment
		(start 157.916626 -225.788728)
		(end 157.470094 -225.788728)
		(width 0.18288)
		(layer "In11.Cu")
		(net "M_H_CPU1_SB_DQS_DN<5>")
	)
	(segment
		(start 203.225654 -227.491036)
		(end 202.726798 -227.491036)
		(width 0.18288)
		(layer "In11.Cu")
		(net "M_H_CPU1_SB_DQS_DN<5>")
	)
	(segment
		(start 170.883326 -223.96323)
		(end 170.758866 -223.83877)
		(width 0.18288)
		(layer "In11.Cu")
		(net "M_H_CPU1_SB_DQS_DN<5>")
	)
	(segment
		(start 204.393546 -227.809552)
		(end 203.80452 -227.220526)
		(width 0.18288)
		(layer "In11.Cu")
		(net "M_H_CPU1_SB_DQS_DN<5>")
	)
	(segment
		(start 166.718996 -224.723198)
		(end 166.594536 -224.847658)
		(width 0.18288)
		(layer "In11.Cu")
		(net "M_H_CPU1_SB_DQS_DN<5>")
	)
	(segment
		(start 130.638296 -237.096046)
		(end 130.623564 -237.08741)
		(width 0.088646)
		(layer "In11.Cu")
		(net "M_H_CPU1_SB_DQS_DN<5>")
	)
	(segment
		(start 191.704722 -223.240854)
		(end 191.43472 -222.970852)
		(width 0.18288)
		(layer "In11.Cu")
		(net "M_H_CPU1_SB_DQS_DN<5>")
	)
	(segment
		(start 186.022234 -222.244158)
		(end 185.473594 -222.244158)
		(width 0.18288)
		(layer "In11.Cu")
		(net "M_H_CPU1_SB_DQS_DN<5>")
	)
	(segment
		(start 173.273466 -223.841564)
		(end 173.024038 -224.090992)
		(width 0.18288)
		(layer "In11.Cu")
		(net "M_H_CPU1_SB_DQS_DN<5>")
	)
	(segment
		(start 141.103096 -236.617764)
		(end 141.043152 -236.55782)
		(width 0.088646)
		(layer "In11.Cu")
		(net "M_H_CPU1_SB_DQS_DN<5>")
	)
	(segment
		(start 162.01517 -224.940876)
		(end 161.60369 -224.940876)
		(width 0.18288)
		(layer "In11.Cu")
		(net "M_H_CPU1_SB_DQS_DN<5>")
	)
	(segment
		(start 126.879096 -237.096046)
		(end 126.864364 -237.08741)
		(width 0.088646)
		(layer "In11.Cu")
		(net "M_H_CPU1_SB_DQS_DN<5>")
	)
	(segment
		(start 177.412142 -222.952818)
		(end 177.124106 -223.240854)
		(width 0.18288)
		(layer "In11.Cu")
		(net "M_H_CPU1_SB_DQS_DN<5>")
	)
	(segment
		(start 170.210226 -223.83877)
		(end 170.085766 -223.96323)
		(width 0.18288)
		(layer "In11.Cu")
		(net "M_H_CPU1_SB_DQS_DN<5>")
	)
	(segment
		(start 157.470094 -225.788728)
		(end 157.227778 -225.546412)
		(width 0.18288)
		(layer "In11.Cu")
		(net "M_H_CPU1_SB_DQS_DN<5>")
	)
	(segment
		(start 159.64408 -224.670112)
		(end 158.7881 -225.526092)
		(width 0.18288)
		(layer "In11.Cu")
		(net "M_H_CPU1_SB_DQS_DN<5>")
	)
	(segment
		(start 193.01587 -222.976186)
		(end 192.476374 -222.976186)
		(width 0.18288)
		(layer "In11.Cu")
		(net "M_H_CPU1_SB_DQS_DN<5>")
	)
	(segment
		(start 191.43472 -222.970852)
		(end 190.565278 -222.970852)
		(width 0.18288)
		(layer "In11.Cu")
		(net "M_H_CPU1_SB_DQS_DN<5>")
	)
	(segment
		(start 144.79905 -236.617764)
		(end 141.103096 -236.617764)
		(width 0.18288)
		(layer "In11.Cu")
		(net "M_H_CPU1_SB_DQS_DN<5>")
	)
	(segment
		(start 137.216896 -237.096046)
		(end 137.202164 -237.08741)
		(width 0.088646)
		(layer "In11.Cu")
		(net "M_H_CPU1_SB_DQS_DN<5>")
	)
	(segment
		(start 205.635098 -227.809552)
		(end 205.510638 -227.934012)
		(width 0.18288)
		(layer "In11.Cu")
		(net "M_H_CPU1_SB_DQS_DN<5>")
	)
	(segment
		(start 158.7881 -225.526092)
		(end 158.179262 -225.526092)
		(width 0.18288)
		(layer "In11.Cu")
		(net "M_H_CPU1_SB_DQS_DN<5>")
	)
	(segment
		(start 166.045896 -224.847658)
		(end 165.921436 -224.723198)
		(width 0.18288)
		(layer "In11.Cu")
		(net "M_H_CPU1_SB_DQS_DN<5>")
	)
	(segment
		(start 170.085766 -223.96323)
		(end 169.537126 -223.96323)
		(width 0.18288)
		(layer "In11.Cu")
		(net "M_H_CPU1_SB_DQS_DN<5>")
	)
	(segment
		(start 172.554646 -224.090992)
		(end 172.302424 -223.83877)
		(width 0.18288)
		(layer "In11.Cu")
		(net "M_H_CPU1_SB_DQS_DN<5>")
	)
	(segment
		(start 195.774056 -224.790508)
		(end 195.659502 -224.74301)
		(width 0.18288)
		(layer "In11.Cu")
		(net "M_H_CPU1_SB_DQS_DN<5>")
	)
	(segment
		(start 160.685734 -224.799652)
		(end 160.109154 -224.799652)
		(width 0.18288)
		(layer "In11.Cu")
		(net "M_H_CPU1_SB_DQS_DN<5>")
	)
	(segment
		(start 139.804394 -237.238794)
		(end 139.172696 -237.238794)
		(width 0.088646)
		(layer "In11.Cu")
		(net "M_H_CPU1_SB_DQS_DN<5>")
	)
	(segment
		(start 179.886356 -222.750126)
		(end 179.469288 -222.333058)
		(width 0.18288)
		(layer "In11.Cu")
		(net "M_H_CPU1_SB_DQS_DN<5>")
	)
	(segment
		(start 203.80452 -227.220526)
		(end 203.496164 -227.220526)
		(width 0.18288)
		(layer "In11.Cu")
		(net "M_H_CPU1_SB_DQS_DN<5>")
	)
	(segment
		(start 181.244748 -222.874586)
		(end 180.696108 -222.874586)
		(width 0.18288)
		(layer "In11.Cu")
		(net "M_H_CPU1_SB_DQS_DN<5>")
	)
	(segment
		(start 167.4749 -224.723198)
		(end 166.718996 -224.723198)
		(width 0.18288)
		(layer "In11.Cu")
		(net "M_H_CPU1_SB_DQS_DN<5>")
	)
	(segment
		(start 138.957304 -237.14964)
		(end 138.399774 -237.14964)
		(width 0.088646)
		(layer "In11.Cu")
		(net "M_H_CPU1_SB_DQS_DN<5>")
	)
	(segment
		(start 171.556426 -223.83877)
		(end 171.431966 -223.96323)
		(width 0.18288)
		(layer "In11.Cu")
		(net "M_H_CPU1_SB_DQS_DN<5>")
	)
	(segment
		(start 204.837538 -227.809552)
		(end 204.393546 -227.809552)
		(width 0.18288)
		(layer "In11.Cu")
		(net "M_H_CPU1_SB_DQS_DN<5>")
	)
	(segment
		(start 139.172696 -237.238794)
		(end 138.957304 -237.14964)
		(width 0.088646)
		(layer "In11.Cu")
		(net "M_H_CPU1_SB_DQS_DN<5>")
	)
	(segment
		(start 184.800494 -222.119698)
		(end 183.278272 -222.750126)
		(width 0.18288)
		(layer "In11.Cu")
		(net "M_H_CPU1_SB_DQS_DN<5>")
	)
	(segment
		(start 173.603666 -223.841564)
		(end 173.273466 -223.841564)
		(width 0.18288)
		(layer "In11.Cu")
		(net "M_H_CPU1_SB_DQS_DN<5>")
	)
	(segment
		(start 206.5782 -227.646484)
		(end 206.338932 -227.74529)
		(width 0.18288)
		(layer "In11.Cu")
		(net "M_H_CPU1_SB_DQS_DN<5>")
	)
	(segment
		(start 125.737366 -237.286546)
		(end 125.737366 -237.411514)
		(width 0.088646)
		(layer "In11.Cu")
		(net "M_H_CPU1_SB_DQS_DN<5>")
	)
	(segment
		(start 182.042308 -222.874586)
		(end 181.917848 -222.750126)
		(width 0.18288)
		(layer "In11.Cu")
		(net "M_H_CPU1_SB_DQS_DN<5>")
	)
	(segment
		(start 183.278272 -222.750126)
		(end 182.715408 -222.750126)
		(width 0.18288)
		(layer "In11.Cu")
		(net "M_H_CPU1_SB_DQS_DN<5>")
	)
	(segment
		(start 165.068504 -224.723198)
		(end 164.177472 -223.832166)
		(width 0.18288)
		(layer "In11.Cu")
		(net "M_H_CPU1_SB_DQS_DN<5>")
	)
	(segment
		(start 185.349134 -222.119698)
		(end 184.800494 -222.119698)
		(width 0.18288)
		(layer "In11.Cu")
		(net "M_H_CPU1_SB_DQS_DN<5>")
	)
	(segment
		(start 196.958966 -225.975418)
		(end 195.774056 -224.790508)
		(width 0.18288)
		(layer "In11.Cu")
		(net "M_H_CPU1_SB_DQS_DN<5>")
	)
	(segment
		(start 168.359328 -223.83877)
		(end 167.4749 -224.723198)
		(width 0.18288)
		(layer "In11.Cu")
		(net "M_H_CPU1_SB_DQS_DN<5>")
	)
	(segment
		(start 190.565278 -222.970852)
		(end 188.531754 -222.128588)
		(width 0.18288)
		(layer "In11.Cu")
		(net "M_H_CPU1_SB_DQS_DN<5>")
	)
	(segment
		(start 180.571648 -222.750126)
		(end 179.886356 -222.750126)
		(width 0.18288)
		(layer "In11.Cu")
		(net "M_H_CPU1_SB_DQS_DN<5>")
	)
	(segment
		(start 163.801806 -223.832166)
		(end 162.957764 -224.676208)
		(width 0.18288)
		(layer "In11.Cu")
		(net "M_H_CPU1_SB_DQS_DN<5>")
	)
	(segment
		(start 192.476374 -222.976186)
		(end 192.211706 -223.240854)
		(width 0.18288)
		(layer "In11.Cu")
		(net "M_H_CPU1_SB_DQS_DN<5>")
	)
	(segment
		(start 125.842776 -237.181136)
		(end 125.842268 -237.18139)
		(width 0.088646)
		(layer "In11.Cu")
		(net "M_H_CPU1_SB_DQS_DN<5>")
	)
	(segment
		(start 185.473594 -222.244158)
		(end 185.349134 -222.119698)
		(width 0.18288)
		(layer "In11.Cu")
		(net "M_H_CPU1_SB_DQS_DN<5>")
	)
	(segment
		(start 140.485368 -236.55782)
		(end 139.804394 -237.238794)
		(width 0.088646)
		(layer "In11.Cu")
		(net "M_H_CPU1_SB_DQS_DN<5>")
	)
	(segment
		(start 172.302424 -223.83877)
		(end 171.556426 -223.83877)
		(width 0.18288)
		(layer "In11.Cu")
		(net "M_H_CPU1_SB_DQS_DN<5>")
	)
	(segment
		(start 182.590948 -222.874586)
		(end 182.042308 -222.874586)
		(width 0.18288)
		(layer "In11.Cu")
		(net "M_H_CPU1_SB_DQS_DN<5>")
	)
	(segment
		(start 179.469288 -222.333058)
		(end 178.858164 -222.333058)
		(width 0.18288)
		(layer "In11.Cu")
		(net "M_H_CPU1_SB_DQS_DN<5>")
	)
	(segment
		(start 125.746764 -237.264194)
		(end 125.737366 -237.286546)
		(width 0.088646)
		(layer "In11.Cu")
		(net "M_H_CPU1_SB_DQS_DN<5>")
	)
	(segment
		(start 127.811276 -237.091474)
		(end 127.804164 -237.08741)
		(width 0.088646)
		(layer "In11.Cu")
		(net "M_H_CPU1_SB_DQS_DN<5>")
	)
	(segment
		(start 205.510638 -227.934012)
		(end 204.961998 -227.934012)
		(width 0.18288)
		(layer "In11.Cu")
		(net "M_H_CPU1_SB_DQS_DN<5>")
	)
	(segment
		(start 204.961998 -227.934012)
		(end 204.837538 -227.809552)
		(width 0.18288)
		(layer "In11.Cu")
		(net "M_H_CPU1_SB_DQS_DN<5>")
	)
	(segment
		(start 199.070976 -226.850448)
		(end 198.908416 -226.918012)
		(width 0.18288)
		(layer "In11.Cu")
		(net "M_H_CPU1_SB_DQS_DN<5>")
	)
	(segment
		(start 135.337296 -237.096046)
		(end 135.322564 -237.08741)
		(width 0.088646)
		(layer "In11.Cu")
		(net "M_H_CPU1_SB_DQS_DN<5>")
	)
	(segment
		(start 127.814324 -237.093252)
		(end 127.813308 -237.092744)
		(width 0.088646)
		(layer "In11.Cu")
		(net "M_H_CPU1_SB_DQS_DN<5>")
	)
	(segment
		(start 188.531754 -222.128588)
		(end 188.375544 -222.128588)
		(width 0.18288)
		(layer "In11.Cu")
		(net "M_H_CPU1_SB_DQS_DN<5>")
	)
	(segment
		(start 169.412666 -223.83877)
		(end 168.359328 -223.83877)
		(width 0.18288)
		(layer "In11.Cu")
		(net "M_H_CPU1_SB_DQS_DN<5>")
	)
	(segment
		(start 174.457614 -222.987616)
		(end 173.603666 -223.841564)
		(width 0.18288)
		(layer "In11.Cu")
		(net "M_H_CPU1_SB_DQS_DN<5>")
	)
	(segment
		(start 187.639198 -222.39097)
		(end 187.367926 -222.119698)
		(width 0.18288)
		(layer "In11.Cu")
		(net "M_H_CPU1_SB_DQS_DN<5>")
	)
	(segment
		(start 127.813308 -237.092744)
		(end 127.811276 -237.091474)
		(width 0.088646)
		(layer "In11.Cu")
		(net "M_H_CPU1_SB_DQS_DN<5>")
	)
	(segment
		(start 126.489968 -237.08741)
		(end 126.468378 -237.098586)
		(width 0.088646)
		(layer "In11.Cu")
		(net "M_H_CPU1_SB_DQS_DN<5>")
	)
	(segment
		(start 178.858164 -222.333058)
		(end 178.238404 -222.952818)
		(width 0.18288)
		(layer "In11.Cu")
		(net "M_H_CPU1_SB_DQS_DN<5>")
	)
	(segment
		(start 180.696108 -222.874586)
		(end 180.571648 -222.750126)
		(width 0.18288)
		(layer "In11.Cu")
		(net "M_H_CPU1_SB_DQS_DN<5>")
	)
	(segment
		(start 160.815274 -224.670112)
		(end 160.685734 -224.799652)
		(width 0.18288)
		(layer "In11.Cu")
		(net "M_H_CPU1_SB_DQS_DN<5>")
	)
	(segment
		(start 176.647602 -223.240854)
		(end 176.394364 -222.987616)
		(width 0.18288)
		(layer "In11.Cu")
		(net "M_H_CPU1_SB_DQS_DN<5>")
	)
	(segment
		(start 188.113162 -222.39097)
		(end 187.639198 -222.39097)
		(width 0.18288)
		(layer "In11.Cu")
		(net "M_H_CPU1_SB_DQS_DN<5>")
	)
	(segment
		(start 178.238404 -222.952818)
		(end 177.412142 -222.952818)
		(width 0.18288)
		(layer "In11.Cu")
		(net "M_H_CPU1_SB_DQS_DN<5>")
	)
	(segment
		(start 207.071214 -227.91674)
		(end 206.800958 -227.646484)
		(width 0.18288)
		(layer "In11.Cu")
		(net "M_H_CPU1_SB_DQS_DN<5>")
	)
	(segment
		(start 203.496164 -227.220526)
		(end 203.225654 -227.491036)
		(width 0.18288)
		(layer "In11.Cu")
		(net "M_H_CPU1_SB_DQS_DN<5>")
	)
	(segment
		(start 181.369208 -222.750126)
		(end 181.244748 -222.874586)
		(width 0.18288)
		(layer "In11.Cu")
		(net "M_H_CPU1_SB_DQS_DN<5>")
	)
	(segment
		(start 187.367926 -222.119698)
		(end 186.146694 -222.119698)
		(width 0.18288)
		(layer "In11.Cu")
		(net "M_H_CPU1_SB_DQS_DN<5>")
	)
	(segment
		(start 206.183738 -227.809552)
		(end 205.635098 -227.809552)
		(width 0.18288)
		(layer "In11.Cu")
		(net "M_H_CPU1_SB_DQS_DN<5>")
	)
	(segment
		(start 125.842268 -237.18139)
		(end 125.82017 -237.190788)
		(width 0.088646)
		(layer "In11.Cu")
		(net "M_H_CPU1_SB_DQS_DN<5>")
	)
	(segment
		(start 126.468378 -237.098586)
		(end 126.31928 -237.171992)
		(width 0.088646)
		(layer "In11.Cu")
		(net "M_H_CPU1_SB_DQS_DN<5>")
	)
	(segment
		(start 188.375544 -222.128588)
		(end 188.113162 -222.39097)
		(width 0.18288)
		(layer "In11.Cu")
		(net "M_H_CPU1_SB_DQS_DN<5>")
	)
	(segment
		(start 186.146694 -222.119698)
		(end 186.022234 -222.244158)
		(width 0.18288)
		(layer "In11.Cu")
		(net "M_H_CPU1_SB_DQS_DN<5>")
	)
	(segment
		(start 169.537126 -223.96323)
		(end 169.412666 -223.83877)
		(width 0.18288)
		(layer "In11.Cu")
		(net "M_H_CPU1_SB_DQS_DN<5>")
	)
	(segment
		(start 195.659502 -224.74301)
		(end 193.01587 -222.976186)
		(width 0.18288)
		(layer "In11.Cu")
		(net "M_H_CPU1_SB_DQS_DN<5>")
	)
	(segment
		(start 176.394364 -222.987616)
		(end 174.457614 -222.987616)
		(width 0.18288)
		(layer "In11.Cu")
		(net "M_H_CPU1_SB_DQS_DN<5>")
	)
	(segment
		(start 131.578096 -237.096046)
		(end 131.563364 -237.08741)
		(width 0.088646)
		(layer "In11.Cu")
		(net "M_H_CPU1_SB_DQS_DN<5>")
	)
	(segment
		(start 160.109154 -224.799652)
		(end 159.979614 -224.670112)
		(width 0.18288)
		(layer "In11.Cu")
		(net "M_H_CPU1_SB_DQS_DN<5>")
	)
	(segment
		(start 206.800958 -227.646484)
		(end 206.5782 -227.646484)
		(width 0.18288)
		(layer "In11.Cu")
		(net "M_H_CPU1_SB_DQS_DN<5>")
	)
	(segment
		(start 162.279838 -224.676208)
		(end 162.01517 -224.940876)
		(width 0.18288)
		(layer "In11.Cu")
		(net "M_H_CPU1_SB_DQS_DN<5>")
	)
	(segment
		(start 157.227778 -225.546412)
		(end 155.870402 -225.546412)
		(width 0.18288)
		(layer "In11.Cu")
		(net "M_H_CPU1_SB_DQS_DN<5>")
	)
	(segment
		(start 202.467464 -227.231702)
		(end 199.990964 -227.231702)
		(width 0.18288)
		(layer "In11.Cu")
		(net "M_H_CPU1_SB_DQS_DN<5>")
	)
	(segment
		(start 199.990964 -227.231702)
		(end 199.070976 -226.850448)
		(width 0.18288)
		(layer "In11.Cu")
		(net "M_H_CPU1_SB_DQS_DN<5>")
	)
	(segment
		(start 159.979614 -224.670112)
		(end 159.64408 -224.670112)
		(width 0.18288)
		(layer "In11.Cu")
		(net "M_H_CPU1_SB_DQS_DN<5>")
	)
	(segment
		(start 192.211706 -223.240854)
		(end 191.704722 -223.240854)
		(width 0.18288)
		(layer "In11.Cu")
		(net "M_H_CPU1_SB_DQS_DN<5>")
	)
	(segment
		(start 164.177472 -223.832166)
		(end 163.801806 -223.832166)
		(width 0.18288)
		(layer "In11.Cu")
		(net "M_H_CPU1_SB_DQS_DN<5>")
	)
	(segment
		(start 161.332926 -224.670112)
		(end 160.815274 -224.670112)
		(width 0.18288)
		(layer "In11.Cu")
		(net "M_H_CPU1_SB_DQS_DN<5>")
	)
	(segment
		(start 162.957764 -224.676208)
		(end 162.279838 -224.676208)
		(width 0.18288)
		(layer "In11.Cu")
		(net "M_H_CPU1_SB_DQS_DN<5>")
	)
	(segment
		(start 126.31928 -237.171992)
		(end 125.842776 -237.181136)
		(width 0.088646)
		(layer "In11.Cu")
		(net "M_H_CPU1_SB_DQS_DN<5>")
	)
	(segment
		(start 173.024038 -224.090992)
		(end 172.554646 -224.090992)
		(width 0.18288)
		(layer "In11.Cu")
		(net "M_H_CPU1_SB_DQS_DN<5>")
	)
	(segment
		(start 198.333868 -226.54514)
		(end 196.958966 -225.975418)
		(width 0.18288)
		(layer "In11.Cu")
		(net "M_H_CPU1_SB_DQS_DN<5>")
	)
	(segment
		(start 198.401178 -226.707954)
		(end 198.333868 -226.54514)
		(width 0.18288)
		(layer "In11.Cu")
		(net "M_H_CPU1_SB_DQS_DN<5>")
	)
	(segment
		(start 181.917848 -222.750126)
		(end 181.369208 -222.750126)
		(width 0.18288)
		(layer "In11.Cu")
		(net "M_H_CPU1_SB_DQS_DN<5>")
	)
	(segment
		(start 127.818896 -237.096046)
		(end 127.814324 -237.093252)
		(width 0.088646)
		(layer "In11.Cu")
		(net "M_H_CPU1_SB_DQS_DN<5>")
	)
	(segment
		(start 171.431966 -223.96323)
		(end 170.883326 -223.96323)
		(width 0.18288)
		(layer "In11.Cu")
		(net "M_H_CPU1_SB_DQS_DN<5>")
	)
	(segment
		(start 141.043152 -236.55782)
		(end 140.485368 -236.55782)
		(width 0.088646)
		(layer "In11.Cu")
		(net "M_H_CPU1_SB_DQS_DN<5>")
	)
	(segment
		(start 125.82017 -237.190788)
		(end 125.746764 -237.264194)
		(width 0.088646)
		(layer "In11.Cu")
		(net "M_H_CPU1_SB_DQS_DN<5>")
	)
	(segment
		(start 165.921436 -224.723198)
		(end 165.068504 -224.723198)
		(width 0.18288)
		(layer "In11.Cu")
		(net "M_H_CPU1_SB_DQS_DN<5>")
	)
	(segment
		(start 129.698496 -237.096046)
		(end 129.683764 -237.08741)
		(width 0.088646)
		(layer "In11.Cu")
		(net "M_H_CPU1_SB_DQS_DN<5>")
	)
	(segment
		(start 202.726798 -227.491036)
		(end 202.467464 -227.231702)
		(width 0.18288)
		(layer "In11.Cu")
		(net "M_H_CPU1_SB_DQS_DN<5>")
	)
	(arc
		(start 133.997954 -237.093506)
		(mid 133.719522 -237.163352)
		(end 133.44271 -237.08741)
		(width 0.088646)
		(layer "In11.Cu")
		(net "M_H_CPU1_SB_DQS_DN<5>")
	)
	(arc
		(start 137.767568 -237.08741)
		(mid 137.493369 -237.163245)
		(end 137.216896 -237.096046)
		(width 0.088646)
		(layer "In11.Cu")
		(net "M_H_CPU1_SB_DQS_DN<5>")
	)
	(arc
		(start 134.948168 -237.08741)
		(mid 134.665466 -237.163186)
		(end 134.382764 -237.08741)
		(width 0.088646)
		(layer "In11.Cu")
		(net "M_H_CPU1_SB_DQS_DN<5>")
	)
	(arc
		(start 130.249168 -237.08741)
		(mid 129.974969 -237.163245)
		(end 129.698496 -237.096046)
		(width 0.088646)
		(layer "In11.Cu")
		(net "M_H_CPU1_SB_DQS_DN<5>")
	)
	(arc
		(start 133.068314 -237.08741)
		(mid 132.791755 -237.163153)
		(end 132.513578 -237.093506)
		(width 0.088646)
		(layer "In11.Cu")
		(net "M_H_CPU1_SB_DQS_DN<5>")
	)
	(arc
		(start 127.429768 -237.08741)
		(mid 127.155569 -237.163245)
		(end 126.879096 -237.096046)
		(width 0.088646)
		(layer "In11.Cu")
		(net "M_H_CPU1_SB_DQS_DN<5>")
	)
	(arc
		(start 130.623564 -237.08741)
		(mid 130.436366 -237.037233)
		(end 130.249168 -237.08741)
		(width 0.088646)
		(layer "In11.Cu")
		(net "M_H_CPU1_SB_DQS_DN<5>")
	)
	(arc
		(start 126.864364 -237.08741)
		(mid 126.677166 -237.037233)
		(end 126.489968 -237.08741)
		(width 0.088646)
		(layer "In11.Cu")
		(net "M_H_CPU1_SB_DQS_DN<5>")
	)
	(arc
		(start 131.563364 -237.08741)
		(mid 131.376166 -237.037233)
		(end 131.188968 -237.08741)
		(width 0.088646)
		(layer "In11.Cu")
		(net "M_H_CPU1_SB_DQS_DN<5>")
	)
	(arc
		(start 132.503164 -237.08741)
		(mid 132.315966 -237.037233)
		(end 132.128768 -237.08741)
		(width 0.088646)
		(layer "In11.Cu")
		(net "M_H_CPU1_SB_DQS_DN<5>")
	)
	(arc
		(start 136.827768 -237.08741)
		(mid 136.553569 -237.163245)
		(end 136.277096 -237.096046)
		(width 0.088646)
		(layer "In11.Cu")
		(net "M_H_CPU1_SB_DQS_DN<5>")
	)
	(arc
		(start 131.188968 -237.08741)
		(mid 130.914769 -237.163245)
		(end 130.638296 -237.096046)
		(width 0.088646)
		(layer "In11.Cu")
		(net "M_H_CPU1_SB_DQS_DN<5>")
	)
	(arc
		(start 137.202164 -237.08741)
		(mid 137.014966 -237.037233)
		(end 136.827768 -237.08741)
		(width 0.088646)
		(layer "In11.Cu")
		(net "M_H_CPU1_SB_DQS_DN<5>")
	)
	(arc
		(start 132.128768 -237.08741)
		(mid 131.854569 -237.163245)
		(end 131.578096 -237.096046)
		(width 0.088646)
		(layer "In11.Cu")
		(net "M_H_CPU1_SB_DQS_DN<5>")
	)
	(arc
		(start 136.262364 -237.08741)
		(mid 136.075166 -237.037233)
		(end 135.887968 -237.08741)
		(width 0.088646)
		(layer "In11.Cu")
		(net "M_H_CPU1_SB_DQS_DN<5>")
	)
	(arc
		(start 129.683764 -237.08741)
		(mid 129.496566 -237.037233)
		(end 129.309368 -237.08741)
		(width 0.088646)
		(layer "In11.Cu")
		(net "M_H_CPU1_SB_DQS_DN<5>")
	)
	(arc
		(start 128.369568 -237.08741)
		(mid 128.095369 -237.163245)
		(end 127.818896 -237.096046)
		(width 0.088646)
		(layer "In11.Cu")
		(net "M_H_CPU1_SB_DQS_DN<5>")
	)
	(arc
		(start 138.399774 -237.14964)
		(mid 138.267178 -237.133826)
		(end 138.141964 -237.08741)
		(width 0.088646)
		(layer "In11.Cu")
		(net "M_H_CPU1_SB_DQS_DN<5>")
	)
	(arc
		(start 135.887968 -237.08741)
		(mid 135.613769 -237.163245)
		(end 135.337296 -237.096046)
		(width 0.088646)
		(layer "In11.Cu")
		(net "M_H_CPU1_SB_DQS_DN<5>")
	)
	(arc
		(start 135.322564 -237.08741)
		(mid 135.135366 -237.037233)
		(end 134.948168 -237.08741)
		(width 0.088646)
		(layer "In11.Cu")
		(net "M_H_CPU1_SB_DQS_DN<5>")
	)
	(arc
		(start 134.382764 -237.08741)
		(mid 134.195566 -237.037233)
		(end 134.008368 -237.08741)
		(width 0.088646)
		(layer "In11.Cu")
		(net "M_H_CPU1_SB_DQS_DN<5>")
	)
	(arc
		(start 133.44271 -237.08741)
		(mid 133.255512 -237.037233)
		(end 133.068314 -237.08741)
		(width 0.088646)
		(layer "In11.Cu")
		(net "M_H_CPU1_SB_DQS_DN<5>")
	)
	(arc
		(start 138.141964 -237.08741)
		(mid 137.954766 -237.037233)
		(end 137.767568 -237.08741)
		(width 0.088646)
		(layer "In11.Cu")
		(net "M_H_CPU1_SB_DQS_DN<5>")
	)
	(arc
		(start 129.309368 -237.08741)
		(mid 129.026666 -237.163186)
		(end 128.743964 -237.08741)
		(width 0.088646)
		(layer "In11.Cu")
		(net "M_H_CPU1_SB_DQS_DN<5>")
	)
	(arc
		(start 128.743964 -237.08741)
		(mid 128.556766 -237.037233)
		(end 128.369568 -237.08741)
		(width 0.088646)
		(layer "In11.Cu")
		(net "M_H_CPU1_SB_DQS_DN<5>")
	)
	(arc
		(start 127.804164 -237.08741)
		(mid 127.616966 -237.037233)
		(end 127.429768 -237.08741)
		(width 0.088646)
		(layer "In11.Cu")
		(net "M_H_CPU1_SB_DQS_DN<5>")
	)
	(segment
		(start 210.286092 -236.847888)
		(end 210.598258 -236.847888)
		(width 0.20066)
		(layer "F.Cu")
		(net "M_H_CPU1_SB_DQS_DN<4>")
	)
	(segment
		(start 213.234778 -236.566964)
		(end 213.724744 -236.566964)
		(width 0.20066)
		(layer "F.Cu")
		(net "M_H_CPU1_SB_DQS_DN<4>")
	)
	(segment
		(start 208.176114 -237.266734)
		(end 208.70672 -237.266734)
		(width 0.20066)
		(layer "F.Cu")
		(net "M_H_CPU1_SB_DQS_DN<4>")
	)
	(segment
		(start 215.216232 -237.266734)
		(end 215.719914 -237.266734)
		(width 0.20066)
		(layer "F.Cu")
		(net "M_H_CPU1_SB_DQS_DN<4>")
	)
	(segment
		(start 214.961978 -237.01248)
		(end 215.216232 -237.266734)
		(width 0.20066)
		(layer "F.Cu")
		(net "M_H_CPU1_SB_DQS_DN<4>")
	)
	(segment
		(start 213.724744 -236.566964)
		(end 214.17026 -237.01248)
		(width 0.20066)
		(layer "F.Cu")
		(net "M_H_CPU1_SB_DQS_DN<4>")
	)
	(segment
		(start 208.70672 -237.266734)
		(end 208.977992 -236.995462)
		(width 0.20066)
		(layer "F.Cu")
		(net "M_H_CPU1_SB_DQS_DN<4>")
	)
	(segment
		(start 210.603084 -236.847888)
		(end 210.60918 -236.841792)
		(width 0.1016)
		(layer "F.Cu")
		(net "M_H_CPU1_SB_DQS_DN<4>")
	)
	(segment
		(start 212.630258 -236.852714)
		(end 212.949028 -236.852714)
		(width 0.20066)
		(layer "F.Cu")
		(net "M_H_CPU1_SB_DQS_DN<4>")
	)
	(segment
		(start 207.071214 -237.266734)
		(end 208.176114 -237.266734)
		(width 0.20066)
		(layer "F.Cu")
		(net "M_H_CPU1_SB_DQS_DN<4>")
	)
	(segment
		(start 125.737366 -242.830604)
		(end 125.737366 -242.294918)
		(width 0.20066)
		(layer "F.Cu")
		(net "M_H_CPU1_SB_DQS_DN<4>")
	)
	(segment
		(start 212.619336 -236.841792)
		(end 212.630258 -236.852714)
		(width 0.1016)
		(layer "F.Cu")
		(net "M_H_CPU1_SB_DQS_DN<4>")
	)
	(segment
		(start 212.949028 -236.852714)
		(end 213.234778 -236.566964)
		(width 0.20066)
		(layer "F.Cu")
		(net "M_H_CPU1_SB_DQS_DN<4>")
	)
	(segment
		(start 209.886296 -236.57052)
		(end 210.008724 -236.57052)
		(width 0.20066)
		(layer "F.Cu")
		(net "M_H_CPU1_SB_DQS_DN<4>")
	)
	(segment
		(start 125.737112 -242.830858)
		(end 125.737366 -242.830604)
		(width 0.20066)
		(layer "F.Cu")
		(net "M_H_CPU1_SB_DQS_DN<4>")
	)
	(segment
		(start 208.977992 -236.995462)
		(end 209.461354 -236.995462)
		(width 0.20066)
		(layer "F.Cu")
		(net "M_H_CPU1_SB_DQS_DN<4>")
	)
	(segment
		(start 209.461354 -236.995462)
		(end 209.886296 -236.57052)
		(width 0.20066)
		(layer "F.Cu")
		(net "M_H_CPU1_SB_DQS_DN<4>")
	)
	(segment
		(start 210.598258 -236.847888)
		(end 210.603084 -236.847888)
		(width 0.101854)
		(layer "F.Cu")
		(net "M_H_CPU1_SB_DQS_DN<4>")
	)
	(segment
		(start 210.008724 -236.57052)
		(end 210.286092 -236.847888)
		(width 0.20066)
		(layer "F.Cu")
		(net "M_H_CPU1_SB_DQS_DN<4>")
	)
	(segment
		(start 214.17026 -237.01248)
		(end 214.961978 -237.01248)
		(width 0.20066)
		(layer "F.Cu")
		(net "M_H_CPU1_SB_DQS_DN<4>")
	)
	(segment
		(start 210.60918 -236.841792)
		(end 212.619336 -236.841792)
		(width 0.1016)
		(layer "F.Cu")
		(net "M_H_CPU1_SB_DQS_DN<4>")
	)
	(segment
		(start 125.842776 -242.06454)
		(end 125.842268 -242.064794)
		(width 0.088646)
		(layer "In11.Cu")
		(net "M_H_CPU1_SB_DQS_DN<4>")
	)
	(segment
		(start 187.344812 -234.896152)
		(end 185.783728 -234.896152)
		(width 0.18288)
		(layer "In11.Cu")
		(net "M_H_CPU1_SB_DQS_DN<4>")
	)
	(segment
		(start 155.809442 -237.220506)
		(end 155.684982 -237.344966)
		(width 0.18288)
		(layer "In11.Cu")
		(net "M_H_CPU1_SB_DQS_DN<4>")
	)
	(segment
		(start 192.442084 -235.753148)
		(end 192.204086 -235.991146)
		(width 0.18288)
		(layer "In11.Cu")
		(net "M_H_CPU1_SB_DQS_DN<4>")
	)
	(segment
		(start 177.116486 -234.291124)
		(end 176.648618 -234.291124)
		(width 0.18288)
		(layer "In11.Cu")
		(net "M_H_CPU1_SB_DQS_DN<4>")
	)
	(segment
		(start 132.517896 -241.979196)
		(end 132.503164 -241.97056)
		(width 0.088646)
		(layer "In11.Cu")
		(net "M_H_CPU1_SB_DQS_DN<4>")
	)
	(segment
		(start 185.099198 -234.760008)
		(end 184.952894 -234.857798)
		(width 0.18288)
		(layer "In11.Cu")
		(net "M_H_CPU1_SB_DQS_DN<4>")
	)
	(segment
		(start 192.748154 -235.753148)
		(end 192.442084 -235.753148)
		(width 0.18288)
		(layer "In11.Cu")
		(net "M_H_CPU1_SB_DQS_DN<4>")
	)
	(segment
		(start 190.747904 -235.847128)
		(end 190.199264 -235.847128)
		(width 0.18288)
		(layer "In11.Cu")
		(net "M_H_CPU1_SB_DQS_DN<4>")
	)
	(segment
		(start 188.129164 -235.138468)
		(end 187.587128 -235.138468)
		(width 0.18288)
		(layer "In11.Cu")
		(net "M_H_CPU1_SB_DQS_DN<4>")
	)
	(segment
		(start 126.31928 -242.055396)
		(end 125.842776 -242.06454)
		(width 0.088646)
		(layer "In11.Cu")
		(net "M_H_CPU1_SB_DQS_DN<4>")
	)
	(segment
		(start 199.17664 -236.394244)
		(end 198.638414 -236.28731)
		(width 0.18288)
		(layer "In11.Cu")
		(net "M_H_CPU1_SB_DQS_DN<4>")
	)
	(segment
		(start 170.832018 -235.034074)
		(end 170.707558 -234.909614)
		(width 0.18288)
		(layer "In11.Cu")
		(net "M_H_CPU1_SB_DQS_DN<4>")
	)
	(segment
		(start 173.454568 -234.882944)
		(end 173.302676 -234.882944)
		(width 0.18288)
		(layer "In11.Cu")
		(net "M_H_CPU1_SB_DQS_DN<4>")
	)
	(segment
		(start 156.482542 -237.344966)
		(end 156.358082 -237.220506)
		(width 0.18288)
		(layer "In11.Cu")
		(net "M_H_CPU1_SB_DQS_DN<4>")
	)
	(segment
		(start 194.007232 -236.412786)
		(end 193.658998 -236.268514)
		(width 0.18288)
		(layer "In11.Cu")
		(net "M_H_CPU1_SB_DQS_DN<4>")
	)
	(segment
		(start 140.310108 -242.57254)
		(end 140.095224 -242.787424)
		(width 0.088646)
		(layer "In11.Cu")
		(net "M_H_CPU1_SB_DQS_DN<4>")
	)
	(segment
		(start 158.929578 -236.417358)
		(end 158.12643 -237.220506)
		(width 0.18288)
		(layer "In11.Cu")
		(net "M_H_CPU1_SB_DQS_DN<4>")
	)
	(segment
		(start 196.008752 -235.98124)
		(end 195.348352 -235.98124)
		(width 0.18288)
		(layer "In11.Cu")
		(net "M_H_CPU1_SB_DQS_DN<4>")
	)
	(segment
		(start 141.043152 -242.57254)
		(end 140.310108 -242.57254)
		(width 0.088646)
		(layer "In11.Cu")
		(net "M_H_CPU1_SB_DQS_DN<4>")
	)
	(segment
		(start 155.136342 -237.344966)
		(end 155.011882 -237.220506)
		(width 0.18288)
		(layer "In11.Cu")
		(net "M_H_CPU1_SB_DQS_DN<4>")
	)
	(segment
		(start 160.478978 -235.96219)
		(end 160.028382 -235.96219)
		(width 0.18288)
		(layer "In11.Cu")
		(net "M_H_CPU1_SB_DQS_DN<4>")
	)
	(segment
		(start 187.587128 -235.138468)
		(end 187.344812 -234.896152)
		(width 0.18288)
		(layer "In11.Cu")
		(net "M_H_CPU1_SB_DQS_DN<4>")
	)
	(segment
		(start 182.673752 -234.277408)
		(end 181.711854 -234.277408)
		(width 0.18288)
		(layer "In11.Cu")
		(net "M_H_CPU1_SB_DQS_DN<4>")
	)
	(segment
		(start 204.324458 -236.925358)
		(end 203.996798 -236.597698)
		(width 0.18288)
		(layer "In11.Cu")
		(net "M_H_CPU1_SB_DQS_DN<4>")
	)
	(segment
		(start 173.302676 -234.882944)
		(end 173.044612 -235.141008)
		(width 0.18288)
		(layer "In11.Cu")
		(net "M_H_CPU1_SB_DQS_DN<4>")
	)
	(segment
		(start 196.806312 -235.98124)
		(end 196.681852 -236.1057)
		(width 0.18288)
		(layer "In11.Cu")
		(net "M_H_CPU1_SB_DQS_DN<4>")
	)
	(segment
		(start 161.840418 -236.323124)
		(end 161.350706 -236.323124)
		(width 0.18288)
		(layer "In11.Cu")
		(net "M_H_CPU1_SB_DQS_DN<4>")
	)
	(segment
		(start 131.578096 -241.979196)
		(end 131.563364 -241.97056)
		(width 0.088646)
		(layer "In11.Cu")
		(net "M_H_CPU1_SB_DQS_DN<4>")
	)
	(segment
		(start 155.684982 -237.344966)
		(end 155.136342 -237.344966)
		(width 0.18288)
		(layer "In11.Cu")
		(net "M_H_CPU1_SB_DQS_DN<4>")
	)
	(segment
		(start 193.423286 -236.032802)
		(end 192.748154 -235.753148)
		(width 0.18288)
		(layer "In11.Cu")
		(net "M_H_CPU1_SB_DQS_DN<4>")
	)
	(segment
		(start 184.414414 -234.750864)
		(end 184.316624 -234.604306)
		(width 0.18288)
		(layer "In11.Cu")
		(net "M_H_CPU1_SB_DQS_DN<4>")
	)
	(segment
		(start 173.044612 -235.141008)
		(end 172.50791 -235.141008)
		(width 0.18288)
		(layer "In11.Cu")
		(net "M_H_CPU1_SB_DQS_DN<4>")
	)
	(segment
		(start 163.590732 -235.153454)
		(end 161.840418 -236.323124)
		(width 0.18288)
		(layer "In11.Cu")
		(net "M_H_CPU1_SB_DQS_DN<4>")
	)
	(segment
		(start 171.505118 -234.909614)
		(end 171.380658 -235.034074)
		(width 0.18288)
		(layer "In11.Cu")
		(net "M_H_CPU1_SB_DQS_DN<4>")
	)
	(segment
		(start 179.33289 -234.630976)
		(end 179.008786 -234.630976)
		(width 0.18288)
		(layer "In11.Cu")
		(net "M_H_CPU1_SB_DQS_DN<4>")
	)
	(segment
		(start 199.322944 -236.296454)
		(end 199.17664 -236.394244)
		(width 0.18288)
		(layer "In11.Cu")
		(net "M_H_CPU1_SB_DQS_DN<4>")
	)
	(segment
		(start 200.68413 -236.567218)
		(end 200.68413 -236.566964)
		(width 0.18288)
		(layer "In11.Cu")
		(net "M_H_CPU1_SB_DQS_DN<4>")
	)
	(segment
		(start 192.204086 -235.991146)
		(end 191.689482 -235.991146)
		(width 0.18288)
		(layer "In11.Cu")
		(net "M_H_CPU1_SB_DQS_DN<4>")
	)
	(segment
		(start 168.37533 -235.430568)
		(end 167.868092 -235.640372)
		(width 0.18288)
		(layer "In11.Cu")
		(net "M_H_CPU1_SB_DQS_DN<4>")
	)
	(segment
		(start 126.474728 -241.978942)
		(end 126.31928 -242.055396)
		(width 0.088646)
		(layer "In11.Cu")
		(net "M_H_CPU1_SB_DQS_DN<4>")
	)
	(segment
		(start 184.952894 -234.857798)
		(end 184.414414 -234.750864)
		(width 0.18288)
		(layer "In11.Cu")
		(net "M_H_CPU1_SB_DQS_DN<4>")
	)
	(segment
		(start 126.489968 -241.970814)
		(end 126.481586 -241.975132)
		(width 0.088646)
		(layer "In11.Cu")
		(net "M_H_CPU1_SB_DQS_DN<4>")
	)
	(segment
		(start 207.071214 -237.266734)
		(end 206.79537 -236.99089)
		(width 0.18288)
		(layer "In11.Cu")
		(net "M_H_CPU1_SB_DQS_DN<4>")
	)
	(segment
		(start 180.187092 -234.277408)
		(end 179.33289 -234.630976)
		(width 0.18288)
		(layer "In11.Cu")
		(net "M_H_CPU1_SB_DQS_DN<4>")
	)
	(segment
		(start 129.698496 -241.979196)
		(end 129.683764 -241.97056)
		(width 0.088646)
		(layer "In11.Cu")
		(net "M_H_CPU1_SB_DQS_DN<4>")
	)
	(segment
		(start 125.82017 -242.074192)
		(end 125.746764 -242.147598)
		(width 0.088646)
		(layer "In11.Cu")
		(net "M_H_CPU1_SB_DQS_DN<4>")
	)
	(segment
		(start 195.348352 -235.98124)
		(end 194.306444 -236.412786)
		(width 0.18288)
		(layer "In11.Cu")
		(net "M_H_CPU1_SB_DQS_DN<4>")
	)
	(segment
		(start 200.68413 -236.566964)
		(end 199.322944 -236.296454)
		(width 0.18288)
		(layer "In11.Cu")
		(net "M_H_CPU1_SB_DQS_DN<4>")
	)
	(segment
		(start 171.380658 -235.034074)
		(end 170.832018 -235.034074)
		(width 0.18288)
		(layer "In11.Cu")
		(net "M_H_CPU1_SB_DQS_DN<4>")
	)
	(segment
		(start 202.763882 -236.8423)
		(end 202.4888 -236.567218)
		(width 0.18288)
		(layer "In11.Cu")
		(net "M_H_CPU1_SB_DQS_DN<4>")
	)
	(segment
		(start 167.705532 -235.572808)
		(end 167.198802 -235.782612)
		(width 0.18288)
		(layer "In11.Cu")
		(net "M_H_CPU1_SB_DQS_DN<4>")
	)
	(segment
		(start 169.307764 -234.909614)
		(end 168.442894 -235.2675)
		(width 0.18288)
		(layer "In11.Cu")
		(net "M_H_CPU1_SB_DQS_DN<4>")
	)
	(segment
		(start 202.912218 -236.8423)
		(end 202.763882 -236.8423)
		(width 0.18288)
		(layer "In11.Cu")
		(net "M_H_CPU1_SB_DQS_DN<4>")
	)
	(segment
		(start 176.37125 -234.013756)
		(end 175.553116 -234.013756)
		(width 0.18288)
		(layer "In11.Cu")
		(net "M_H_CPU1_SB_DQS_DN<4>")
	)
	(segment
		(start 188.840364 -234.903772)
		(end 188.36386 -234.903772)
		(width 0.18288)
		(layer "In11.Cu")
		(net "M_H_CPU1_SB_DQS_DN<4>")
	)
	(segment
		(start 157.155642 -237.220506)
		(end 157.031182 -237.344966)
		(width 0.18288)
		(layer "In11.Cu")
		(net "M_H_CPU1_SB_DQS_DN<4>")
	)
	(segment
		(start 134.397496 -241.979196)
		(end 134.382764 -241.97056)
		(width 0.088646)
		(layer "In11.Cu")
		(net "M_H_CPU1_SB_DQS_DN<4>")
	)
	(segment
		(start 161.350706 -236.323124)
		(end 160.478978 -235.96219)
		(width 0.18288)
		(layer "In11.Cu")
		(net "M_H_CPU1_SB_DQS_DN<4>")
	)
	(segment
		(start 138.147044 -242.787424)
		(end 137.399776 -242.040156)
		(width 0.088646)
		(layer "In11.Cu")
		(net "M_H_CPU1_SB_DQS_DN<4>")
	)
	(segment
		(start 170.707558 -234.909614)
		(end 169.307764 -234.909614)
		(width 0.18288)
		(layer "In11.Cu")
		(net "M_H_CPU1_SB_DQS_DN<4>")
	)
	(segment
		(start 191.421004 -235.722668)
		(end 190.872364 -235.722668)
		(width 0.18288)
		(layer "In11.Cu")
		(net "M_H_CPU1_SB_DQS_DN<4>")
	)
	(segment
		(start 147.705064 -242.632484)
		(end 141.103096 -242.632484)
		(width 0.18288)
		(layer "In11.Cu")
		(net "M_H_CPU1_SB_DQS_DN<4>")
	)
	(segment
		(start 137.202418 -241.970306)
		(end 137.202164 -241.97056)
		(width 0.088646)
		(layer "In11.Cu")
		(net "M_H_CPU1_SB_DQS_DN<4>")
	)
	(segment
		(start 130.638296 -241.979196)
		(end 130.623564 -241.97056)
		(width 0.088646)
		(layer "In11.Cu")
		(net "M_H_CPU1_SB_DQS_DN<4>")
	)
	(segment
		(start 167.198802 -235.782612)
		(end 165.848538 -235.782612)
		(width 0.18288)
		(layer "In11.Cu")
		(net "M_H_CPU1_SB_DQS_DN<4>")
	)
	(segment
		(start 189.65926 -235.722668)
		(end 188.840364 -234.903772)
		(width 0.18288)
		(layer "In11.Cu")
		(net "M_H_CPU1_SB_DQS_DN<4>")
	)
	(segment
		(start 197.738238 -235.98124)
		(end 196.806312 -235.98124)
		(width 0.18288)
		(layer "In11.Cu")
		(net "M_H_CPU1_SB_DQS_DN<4>")
	)
	(segment
		(start 196.681852 -236.1057)
		(end 196.133212 -236.1057)
		(width 0.18288)
		(layer "In11.Cu")
		(net "M_H_CPU1_SB_DQS_DN<4>")
	)
	(segment
		(start 125.842268 -242.064794)
		(end 125.82017 -242.074192)
		(width 0.088646)
		(layer "In11.Cu")
		(net "M_H_CPU1_SB_DQS_DN<4>")
	)
	(segment
		(start 203.242926 -236.8423)
		(end 203.094082 -236.8423)
		(width 0.18288)
		(layer "In11.Cu")
		(net "M_H_CPU1_SB_DQS_DN<4>")
	)
	(segment
		(start 184.316624 -234.604306)
		(end 182.673752 -234.277408)
		(width 0.18288)
		(layer "In11.Cu")
		(net "M_H_CPU1_SB_DQS_DN<4>")
	)
	(segment
		(start 158.12643 -237.220506)
		(end 157.155642 -237.220506)
		(width 0.18288)
		(layer "In11.Cu")
		(net "M_H_CPU1_SB_DQS_DN<4>")
	)
	(segment
		(start 155.011882 -237.220506)
		(end 154.463242 -237.220506)
		(width 0.18288)
		(layer "In11.Cu")
		(net "M_H_CPU1_SB_DQS_DN<4>")
	)
	(segment
		(start 193.658998 -236.268514)
		(end 193.423286 -236.032802)
		(width 0.18288)
		(layer "In11.Cu")
		(net "M_H_CPU1_SB_DQS_DN<4>")
	)
	(segment
		(start 202.4888 -236.567218)
		(end 200.68413 -236.567218)
		(width 0.18288)
		(layer "In11.Cu")
		(net "M_H_CPU1_SB_DQS_DN<4>")
	)
	(segment
		(start 140.095224 -242.787424)
		(end 138.147044 -242.787424)
		(width 0.088646)
		(layer "In11.Cu")
		(net "M_H_CPU1_SB_DQS_DN<4>")
	)
	(segment
		(start 154.338782 -237.344966)
		(end 153.790142 -237.344966)
		(width 0.18288)
		(layer "In11.Cu")
		(net "M_H_CPU1_SB_DQS_DN<4>")
	)
	(segment
		(start 172.276516 -234.909614)
		(end 171.505118 -234.909614)
		(width 0.18288)
		(layer "In11.Cu")
		(net "M_H_CPU1_SB_DQS_DN<4>")
	)
	(segment
		(start 126.481586 -241.975132)
		(end 126.474728 -241.978942)
		(width 0.088646)
		(layer "In11.Cu")
		(net "M_H_CPU1_SB_DQS_DN<4>")
	)
	(segment
		(start 168.442894 -235.2675)
		(end 168.37533 -235.430568)
		(width 0.18288)
		(layer "In11.Cu")
		(net "M_H_CPU1_SB_DQS_DN<4>")
	)
	(segment
		(start 203.487528 -236.597698)
		(end 203.242926 -236.8423)
		(width 0.18288)
		(layer "In11.Cu")
		(net "M_H_CPU1_SB_DQS_DN<4>")
	)
	(segment
		(start 181.587394 -234.401868)
		(end 181.038754 -234.401868)
		(width 0.18288)
		(layer "In11.Cu")
		(net "M_H_CPU1_SB_DQS_DN<4>")
	)
	(segment
		(start 156.358082 -237.220506)
		(end 155.809442 -237.220506)
		(width 0.18288)
		(layer "In11.Cu")
		(net "M_H_CPU1_SB_DQS_DN<4>")
	)
	(segment
		(start 177.381154 -234.026456)
		(end 177.116486 -234.291124)
		(width 0.18288)
		(layer "In11.Cu")
		(net "M_H_CPU1_SB_DQS_DN<4>")
	)
	(segment
		(start 160.028382 -235.96219)
		(end 158.929578 -236.417358)
		(width 0.18288)
		(layer "In11.Cu")
		(net "M_H_CPU1_SB_DQS_DN<4>")
	)
	(segment
		(start 179.008786 -234.630976)
		(end 177.549556 -234.026456)
		(width 0.18288)
		(layer "In11.Cu")
		(net "M_H_CPU1_SB_DQS_DN<4>")
	)
	(segment
		(start 127.429768 -241.97056)
		(end 127.429768 -241.970814)
		(width 0.088646)
		(layer "In11.Cu")
		(net "M_H_CPU1_SB_DQS_DN<4>")
	)
	(segment
		(start 180.914294 -234.277408)
		(end 180.187092 -234.277408)
		(width 0.18288)
		(layer "In11.Cu")
		(net "M_H_CPU1_SB_DQS_DN<4>")
	)
	(segment
		(start 141.103096 -242.632484)
		(end 141.043152 -242.57254)
		(width 0.088646)
		(layer "In11.Cu")
		(net "M_H_CPU1_SB_DQS_DN<4>")
	)
	(segment
		(start 153.665682 -237.220506)
		(end 153.117042 -237.220506)
		(width 0.18288)
		(layer "In11.Cu")
		(net "M_H_CPU1_SB_DQS_DN<4>")
	)
	(segment
		(start 157.031182 -237.344966)
		(end 156.482542 -237.344966)
		(width 0.18288)
		(layer "In11.Cu")
		(net "M_H_CPU1_SB_DQS_DN<4>")
	)
	(segment
		(start 198.540624 -236.140752)
		(end 197.738238 -235.98124)
		(width 0.18288)
		(layer "In11.Cu")
		(net "M_H_CPU1_SB_DQS_DN<4>")
	)
	(segment
		(start 126.879096 -241.97945)
		(end 126.864364 -241.970814)
		(width 0.088646)
		(layer "In11.Cu")
		(net "M_H_CPU1_SB_DQS_DN<4>")
	)
	(segment
		(start 206.79537 -236.99089)
		(end 206.239872 -236.99089)
		(width 0.18288)
		(layer "In11.Cu")
		(net "M_H_CPU1_SB_DQS_DN<4>")
	)
	(segment
		(start 205.710028 -237.210346)
		(end 205.01229 -237.210346)
		(width 0.18288)
		(layer "In11.Cu")
		(net "M_H_CPU1_SB_DQS_DN<4>")
	)
	(segment
		(start 125.746764 -242.147598)
		(end 125.737366 -242.16995)
		(width 0.088646)
		(layer "In11.Cu")
		(net "M_H_CPU1_SB_DQS_DN<4>")
	)
	(segment
		(start 205.01229 -237.210346)
		(end 204.324458 -236.925358)
		(width 0.18288)
		(layer "In11.Cu")
		(net "M_H_CPU1_SB_DQS_DN<4>")
	)
	(segment
		(start 153.117042 -237.220506)
		(end 147.705064 -242.632484)
		(width 0.18288)
		(layer "In11.Cu")
		(net "M_H_CPU1_SB_DQS_DN<4>")
	)
	(segment
		(start 164.329618 -235.153454)
		(end 163.590732 -235.153454)
		(width 0.18288)
		(layer "In11.Cu")
		(net "M_H_CPU1_SB_DQS_DN<4>")
	)
	(segment
		(start 196.133212 -236.1057)
		(end 196.008752 -235.98124)
		(width 0.18288)
		(layer "In11.Cu")
		(net "M_H_CPU1_SB_DQS_DN<4>")
	)
	(segment
		(start 185.783728 -234.896152)
		(end 185.099198 -234.760008)
		(width 0.18288)
		(layer "In11.Cu")
		(net "M_H_CPU1_SB_DQS_DN<4>")
	)
	(segment
		(start 194.306444 -236.412786)
		(end 194.007232 -236.412786)
		(width 0.18288)
		(layer "In11.Cu")
		(net "M_H_CPU1_SB_DQS_DN<4>")
	)
	(segment
		(start 198.638414 -236.28731)
		(end 198.540624 -236.140752)
		(width 0.18288)
		(layer "In11.Cu")
		(net "M_H_CPU1_SB_DQS_DN<4>")
	)
	(segment
		(start 181.038754 -234.401868)
		(end 180.914294 -234.277408)
		(width 0.18288)
		(layer "In11.Cu")
		(net "M_H_CPU1_SB_DQS_DN<4>")
	)
	(segment
		(start 190.074804 -235.722668)
		(end 189.65926 -235.722668)
		(width 0.18288)
		(layer "In11.Cu")
		(net "M_H_CPU1_SB_DQS_DN<4>")
	)
	(segment
		(start 190.199264 -235.847128)
		(end 190.074804 -235.722668)
		(width 0.18288)
		(layer "In11.Cu")
		(net "M_H_CPU1_SB_DQS_DN<4>")
	)
	(segment
		(start 190.872364 -235.722668)
		(end 190.747904 -235.847128)
		(width 0.18288)
		(layer "In11.Cu")
		(net "M_H_CPU1_SB_DQS_DN<4>")
	)
	(segment
		(start 165.848538 -235.782612)
		(end 164.329618 -235.153454)
		(width 0.18288)
		(layer "In11.Cu")
		(net "M_H_CPU1_SB_DQS_DN<4>")
	)
	(segment
		(start 191.689482 -235.991146)
		(end 191.421004 -235.722668)
		(width 0.18288)
		(layer "In11.Cu")
		(net "M_H_CPU1_SB_DQS_DN<4>")
	)
	(segment
		(start 153.790142 -237.344966)
		(end 153.665682 -237.220506)
		(width 0.18288)
		(layer "In11.Cu")
		(net "M_H_CPU1_SB_DQS_DN<4>")
	)
	(segment
		(start 154.463242 -237.220506)
		(end 154.338782 -237.344966)
		(width 0.18288)
		(layer "In11.Cu")
		(net "M_H_CPU1_SB_DQS_DN<4>")
	)
	(segment
		(start 203.094082 -236.8423)
		(end 202.912218 -236.8423)
		(width 0.16002)
		(layer "In11.Cu")
		(net "M_H_CPU1_SB_DQS_DN<4>")
	)
	(segment
		(start 175.553116 -234.013756)
		(end 173.454568 -234.882944)
		(width 0.18288)
		(layer "In11.Cu")
		(net "M_H_CPU1_SB_DQS_DN<4>")
	)
	(segment
		(start 172.50791 -235.141008)
		(end 172.276516 -234.909614)
		(width 0.18288)
		(layer "In11.Cu")
		(net "M_H_CPU1_SB_DQS_DN<4>")
	)
	(segment
		(start 176.648618 -234.291124)
		(end 176.37125 -234.013756)
		(width 0.18288)
		(layer "In11.Cu")
		(net "M_H_CPU1_SB_DQS_DN<4>")
	)
	(segment
		(start 177.549556 -234.026456)
		(end 177.381154 -234.026456)
		(width 0.18288)
		(layer "In11.Cu")
		(net "M_H_CPU1_SB_DQS_DN<4>")
	)
	(segment
		(start 137.399776 -242.040156)
		(end 137.399522 -242.040156)
		(width 0.088646)
		(layer "In11.Cu")
		(net "M_H_CPU1_SB_DQS_DN<4>")
	)
	(segment
		(start 188.36386 -234.903772)
		(end 188.129164 -235.138468)
		(width 0.18288)
		(layer "In11.Cu")
		(net "M_H_CPU1_SB_DQS_DN<4>")
	)
	(segment
		(start 181.711854 -234.277408)
		(end 181.587394 -234.401868)
		(width 0.18288)
		(layer "In11.Cu")
		(net "M_H_CPU1_SB_DQS_DN<4>")
	)
	(segment
		(start 206.239872 -236.99089)
		(end 205.710028 -237.210346)
		(width 0.18288)
		(layer "In11.Cu")
		(net "M_H_CPU1_SB_DQS_DN<4>")
	)
	(segment
		(start 167.868092 -235.640372)
		(end 167.705532 -235.572808)
		(width 0.18288)
		(layer "In11.Cu")
		(net "M_H_CPU1_SB_DQS_DN<4>")
	)
	(segment
		(start 125.737366 -242.16995)
		(end 125.737366 -242.294918)
		(width 0.088646)
		(layer "In11.Cu")
		(net "M_H_CPU1_SB_DQS_DN<4>")
	)
	(segment
		(start 203.996798 -236.597698)
		(end 203.487528 -236.597698)
		(width 0.18288)
		(layer "In11.Cu")
		(net "M_H_CPU1_SB_DQS_DN<4>")
	)
	(segment
		(start 127.818896 -241.979196)
		(end 127.804164 -241.97056)
		(width 0.088646)
		(layer "In11.Cu")
		(net "M_H_CPU1_SB_DQS_DN<4>")
	)
	(arc
		(start 135.322564 -241.97056)
		(mid 135.135366 -241.920417)
		(end 134.948168 -241.97056)
		(width 0.088646)
		(layer "In11.Cu")
		(net "M_H_CPU1_SB_DQS_DN<4>")
	)
	(arc
		(start 127.429768 -241.970814)
		(mid 127.155569 -242.046649)
		(end 126.879096 -241.97945)
		(width 0.088646)
		(layer "In11.Cu")
		(net "M_H_CPU1_SB_DQS_DN<4>")
	)
	(arc
		(start 129.309368 -241.97056)
		(mid 129.026666 -242.046336)
		(end 128.743964 -241.97056)
		(width 0.088646)
		(layer "In11.Cu")
		(net "M_H_CPU1_SB_DQS_DN<4>")
	)
	(arc
		(start 131.563364 -241.97056)
		(mid 131.376166 -241.920417)
		(end 131.188968 -241.97056)
		(width 0.088646)
		(layer "In11.Cu")
		(net "M_H_CPU1_SB_DQS_DN<4>")
	)
	(arc
		(start 137.399522 -242.040156)
		(mid 137.29772 -242.014406)
		(end 137.202418 -241.970306)
		(width 0.088646)
		(layer "In11.Cu")
		(net "M_H_CPU1_SB_DQS_DN<4>")
	)
	(arc
		(start 134.948168 -241.97056)
		(mid 134.673969 -242.046395)
		(end 134.397496 -241.979196)
		(width 0.088646)
		(layer "In11.Cu")
		(net "M_H_CPU1_SB_DQS_DN<4>")
	)
	(arc
		(start 133.068568 -241.97056)
		(mid 132.794369 -242.046395)
		(end 132.517896 -241.979196)
		(width 0.088646)
		(layer "In11.Cu")
		(net "M_H_CPU1_SB_DQS_DN<4>")
	)
	(arc
		(start 128.369568 -241.97056)
		(mid 128.095369 -242.046395)
		(end 127.818896 -241.979196)
		(width 0.088646)
		(layer "In11.Cu")
		(net "M_H_CPU1_SB_DQS_DN<4>")
	)
	(arc
		(start 126.864364 -241.970814)
		(mid 126.677166 -241.920637)
		(end 126.489968 -241.970814)
		(width 0.088646)
		(layer "In11.Cu")
		(net "M_H_CPU1_SB_DQS_DN<4>")
	)
	(arc
		(start 137.202164 -241.97056)
		(mid 137.014966 -241.920417)
		(end 136.827768 -241.97056)
		(width 0.088646)
		(layer "In11.Cu")
		(net "M_H_CPU1_SB_DQS_DN<4>")
	)
	(arc
		(start 134.008368 -241.97056)
		(mid 133.725666 -242.046336)
		(end 133.442964 -241.97056)
		(width 0.088646)
		(layer "In11.Cu")
		(net "M_H_CPU1_SB_DQS_DN<4>")
	)
	(arc
		(start 134.382764 -241.97056)
		(mid 134.195566 -241.920417)
		(end 134.008368 -241.97056)
		(width 0.088646)
		(layer "In11.Cu")
		(net "M_H_CPU1_SB_DQS_DN<4>")
	)
	(arc
		(start 129.683764 -241.97056)
		(mid 129.496566 -241.920417)
		(end 129.309368 -241.97056)
		(width 0.088646)
		(layer "In11.Cu")
		(net "M_H_CPU1_SB_DQS_DN<4>")
	)
	(arc
		(start 136.827768 -241.97056)
		(mid 136.545066 -242.046336)
		(end 136.262364 -241.97056)
		(width 0.088646)
		(layer "In11.Cu")
		(net "M_H_CPU1_SB_DQS_DN<4>")
	)
	(arc
		(start 136.262364 -241.97056)
		(mid 136.075166 -241.920417)
		(end 135.887968 -241.97056)
		(width 0.088646)
		(layer "In11.Cu")
		(net "M_H_CPU1_SB_DQS_DN<4>")
	)
	(arc
		(start 131.188968 -241.97056)
		(mid 130.914769 -242.046395)
		(end 130.638296 -241.979196)
		(width 0.088646)
		(layer "In11.Cu")
		(net "M_H_CPU1_SB_DQS_DN<4>")
	)
	(arc
		(start 128.743964 -241.97056)
		(mid 128.556766 -241.920417)
		(end 128.369568 -241.97056)
		(width 0.088646)
		(layer "In11.Cu")
		(net "M_H_CPU1_SB_DQS_DN<4>")
	)
	(arc
		(start 127.804164 -241.97056)
		(mid 127.616966 -241.920417)
		(end 127.429768 -241.97056)
		(width 0.088646)
		(layer "In11.Cu")
		(net "M_H_CPU1_SB_DQS_DN<4>")
	)
	(arc
		(start 130.623564 -241.97056)
		(mid 130.436366 -241.920417)
		(end 130.249168 -241.97056)
		(width 0.088646)
		(layer "In11.Cu")
		(net "M_H_CPU1_SB_DQS_DN<4>")
	)
	(arc
		(start 130.249168 -241.97056)
		(mid 129.974969 -242.046395)
		(end 129.698496 -241.979196)
		(width 0.088646)
		(layer "In11.Cu")
		(net "M_H_CPU1_SB_DQS_DN<4>")
	)
	(arc
		(start 132.503164 -241.97056)
		(mid 132.315966 -241.920417)
		(end 132.128768 -241.97056)
		(width 0.088646)
		(layer "In11.Cu")
		(net "M_H_CPU1_SB_DQS_DN<4>")
	)
	(arc
		(start 133.442964 -241.97056)
		(mid 133.255766 -241.920417)
		(end 133.068568 -241.97056)
		(width 0.088646)
		(layer "In11.Cu")
		(net "M_H_CPU1_SB_DQS_DN<4>")
	)
	(arc
		(start 132.128768 -241.97056)
		(mid 131.854569 -242.046395)
		(end 131.578096 -241.979196)
		(width 0.088646)
		(layer "In11.Cu")
		(net "M_H_CPU1_SB_DQS_DN<4>")
	)
	(arc
		(start 135.887968 -241.97056)
		(mid 135.605266 -242.046336)
		(end 135.322564 -241.97056)
		(width 0.088646)
		(layer "In11.Cu")
		(net "M_H_CPU1_SB_DQS_DN<4>")
	)
	(segment
		(start 210.047078 -200.51776)
		(end 210.457542 -200.107296)
		(width 0.20066)
		(layer "F.Cu")
		(net "M_H_CPU1_SB_DQS_DN<3>")
	)
	(segment
		(start 204.076046 -199.866758)
		(end 204.624686 -199.866758)
		(width 0.20066)
		(layer "F.Cu")
		(net "M_H_CPU1_SB_DQS_DN<3>")
	)
	(segment
		(start 209.186526 -200.286366)
		(end 209.51063 -200.286366)
		(width 0.20066)
		(layer "F.Cu")
		(net "M_H_CPU1_SB_DQS_DN<3>")
	)
	(segment
		(start 206.849726 -200.2917)
		(end 206.9973 -200.2917)
		(width 0.20066)
		(layer "F.Cu")
		(net "M_H_CPU1_SB_DQS_DN<3>")
	)
	(segment
		(start 210.457542 -200.107296)
		(end 210.790028 -200.107296)
		(width 0.20066)
		(layer "F.Cu")
		(net "M_H_CPU1_SB_DQS_DN<3>")
	)
	(segment
		(start 211.030566 -199.866758)
		(end 211.619846 -199.866758)
		(width 0.20066)
		(layer "F.Cu")
		(net "M_H_CPU1_SB_DQS_DN<3>")
	)
	(segment
		(start 209.51063 -200.286366)
		(end 209.742024 -200.51776)
		(width 0.20066)
		(layer "F.Cu")
		(net "M_H_CPU1_SB_DQS_DN<3>")
	)
	(segment
		(start 206.9973 -200.2917)
		(end 207.001618 -200.2917)
		(width 0.101854)
		(layer "F.Cu")
		(net "M_H_CPU1_SB_DQS_DN<3>")
	)
	(segment
		(start 202.971146 -199.866758)
		(end 204.076046 -199.866758)
		(width 0.20066)
		(layer "F.Cu")
		(net "M_H_CPU1_SB_DQS_DN<3>")
	)
	(segment
		(start 204.624686 -199.866758)
		(end 204.906372 -200.148444)
		(width 0.20066)
		(layer "F.Cu")
		(net "M_H_CPU1_SB_DQS_DN<3>")
	)
	(segment
		(start 206.056738 -200.562972)
		(end 206.578454 -200.562972)
		(width 0.20066)
		(layer "F.Cu")
		(net "M_H_CPU1_SB_DQS_DN<3>")
	)
	(segment
		(start 207.001618 -200.2917)
		(end 209.181192 -200.2917)
		(width 0.1016)
		(layer "F.Cu")
		(net "M_H_CPU1_SB_DQS_DN<3>")
	)
	(segment
		(start 205.64221 -200.148444)
		(end 206.056738 -200.562972)
		(width 0.20066)
		(layer "F.Cu")
		(net "M_H_CPU1_SB_DQS_DN<3>")
	)
	(segment
		(start 204.906372 -200.148444)
		(end 205.64221 -200.148444)
		(width 0.20066)
		(layer "F.Cu")
		(net "M_H_CPU1_SB_DQS_DN<3>")
	)
	(segment
		(start 122.917712 -228.1809)
		(end 122.917966 -228.180646)
		(width 0.20066)
		(layer "F.Cu")
		(net "M_H_CPU1_SB_DQS_DN<3>")
	)
	(segment
		(start 206.578454 -200.562972)
		(end 206.849726 -200.2917)
		(width 0.20066)
		(layer "F.Cu")
		(net "M_H_CPU1_SB_DQS_DN<3>")
	)
	(segment
		(start 122.917966 -228.180646)
		(end 122.917966 -227.64496)
		(width 0.20066)
		(layer "F.Cu")
		(net "M_H_CPU1_SB_DQS_DN<3>")
	)
	(segment
		(start 209.742024 -200.51776)
		(end 210.047078 -200.51776)
		(width 0.20066)
		(layer "F.Cu")
		(net "M_H_CPU1_SB_DQS_DN<3>")
	)
	(segment
		(start 209.181192 -200.2917)
		(end 209.186526 -200.286366)
		(width 0.1016)
		(layer "F.Cu")
		(net "M_H_CPU1_SB_DQS_DN<3>")
	)
	(segment
		(start 210.790028 -200.107296)
		(end 211.030566 -199.866758)
		(width 0.20066)
		(layer "F.Cu")
		(net "M_H_CPU1_SB_DQS_DN<3>")
	)
	(segment
		(start 177.104294 -197.741286)
		(end 176.62779 -197.741286)
		(width 0.18288)
		(layer "In11.Cu")
		(net "M_H_CPU1_SB_DQS_DN<3>")
	)
	(segment
		(start 146.877278 -215.528398)
		(end 140.683742 -221.721934)
		(width 0.18288)
		(layer "In11.Cu")
		(net "M_H_CPU1_SB_DQS_DN<3>")
	)
	(segment
		(start 131.658614 -227.155502)
		(end 131.6482 -227.149406)
		(width 0.088646)
		(layer "In11.Cu")
		(net "M_H_CPU1_SB_DQS_DN<3>")
	)
	(segment
		(start 132.598414 -227.155502)
		(end 132.583682 -227.146866)
		(width 0.088646)
		(layer "In11.Cu")
		(net "M_H_CPU1_SB_DQS_DN<3>")
	)
	(segment
		(start 183.366918 -198.878698)
		(end 182.773828 -199.471788)
		(width 0.18288)
		(layer "In11.Cu")
		(net "M_H_CPU1_SB_DQS_DN<3>")
	)
	(segment
		(start 191.71539 -197.741286)
		(end 191.426592 -198.030084)
		(width 0.18288)
		(layer "In11.Cu")
		(net "M_H_CPU1_SB_DQS_DN<3>")
	)
	(segment
		(start 187.327794 -198.878698)
		(end 186.001914 -198.878698)
		(width 0.18288)
		(layer "In11.Cu")
		(net "M_H_CPU1_SB_DQS_DN<3>")
	)
	(segment
		(start 129.779014 -227.155502)
		(end 129.764282 -227.146866)
		(width 0.088646)
		(layer "In11.Cu")
		(net "M_H_CPU1_SB_DQS_DN<3>")
	)
	(segment
		(start 160.582356 -200.77938)
		(end 157.127956 -200.77938)
		(width 0.18288)
		(layer "In11.Cu")
		(net "M_H_CPU1_SB_DQS_DN<3>")
	)
	(segment
		(start 177.381408 -198.0184)
		(end 177.104294 -197.741286)
		(width 0.18288)
		(layer "In11.Cu")
		(net "M_H_CPU1_SB_DQS_DN<3>")
	)
	(segment
		(start 194.930268 -199.76719)
		(end 193.1797 -198.016622)
		(width 0.18288)
		(layer "In11.Cu")
		(net "M_H_CPU1_SB_DQS_DN<3>")
	)
	(segment
		(start 178.296316 -198.0184)
		(end 177.381408 -198.0184)
		(width 0.18288)
		(layer "In11.Cu")
		(net "M_H_CPU1_SB_DQS_DN<3>")
	)
	(segment
		(start 139.307824 -224.850452)
		(end 138.689588 -225.468688)
		(width 0.088646)
		(layer "In11.Cu")
		(net "M_H_CPU1_SB_DQS_DN<3>")
	)
	(segment
		(start 146.877278 -212.664548)
		(end 146.877278 -215.528398)
		(width 0.18288)
		(layer "In11.Cu")
		(net "M_H_CPU1_SB_DQS_DN<3>")
	)
	(segment
		(start 174.397924 -198.010272)
		(end 173.54169 -198.866506)
		(width 0.18288)
		(layer "In11.Cu")
		(net "M_H_CPU1_SB_DQS_DN<3>")
	)
	(segment
		(start 127.348996 -227.146866)
		(end 127.334264 -227.155502)
		(width 0.088646)
		(layer "In11.Cu")
		(net "M_H_CPU1_SB_DQS_DN<3>")
	)
	(segment
		(start 168.963086 -199.97293)
		(end 161.388806 -199.97293)
		(width 0.18288)
		(layer "In11.Cu")
		(net "M_H_CPU1_SB_DQS_DN<3>")
	)
	(segment
		(start 185.106818 -200.188576)
		(end 184.91073 -199.992488)
		(width 0.18288)
		(layer "In11.Cu")
		(net "M_H_CPU1_SB_DQS_DN<3>")
	)
	(segment
		(start 188.366654 -198.866506)
		(end 188.091318 -198.59117)
		(width 0.18288)
		(layer "In11.Cu")
		(net "M_H_CPU1_SB_DQS_DN<3>")
	)
	(segment
		(start 140.46454 -223.310958)
		(end 139.307824 -224.467674)
		(width 0.088646)
		(layer "In11.Cu")
		(net "M_H_CPU1_SB_DQS_DN<3>")
	)
	(segment
		(start 155.104846 -204.43698)
		(end 146.877278 -212.664548)
		(width 0.18288)
		(layer "In11.Cu")
		(net "M_H_CPU1_SB_DQS_DN<3>")
	)
	(segment
		(start 202.971146 -199.866758)
		(end 202.706478 -200.131426)
		(width 0.18288)
		(layer "In11.Cu")
		(net "M_H_CPU1_SB_DQS_DN<3>")
	)
	(segment
		(start 186.001914 -198.878698)
		(end 185.62447 -199.256142)
		(width 0.18288)
		(layer "In11.Cu")
		(net "M_H_CPU1_SB_DQS_DN<3>")
	)
	(segment
		(start 134.478014 -227.155502)
		(end 134.4676 -227.149406)
		(width 0.088646)
		(layer "In11.Cu")
		(net "M_H_CPU1_SB_DQS_DN<3>")
	)
	(segment
		(start 170.080686 -198.85533)
		(end 168.963086 -199.97293)
		(width 0.18288)
		(layer "In11.Cu")
		(net "M_H_CPU1_SB_DQS_DN<3>")
	)
	(segment
		(start 184.533286 -198.878698)
		(end 183.366918 -198.878698)
		(width 0.18288)
		(layer "In11.Cu")
		(net "M_H_CPU1_SB_DQS_DN<3>")
	)
	(segment
		(start 185.428382 -200.188576)
		(end 185.106818 -200.188576)
		(width 0.18288)
		(layer "In11.Cu")
		(net "M_H_CPU1_SB_DQS_DN<3>")
	)
	(segment
		(start 192.202054 -197.741286)
		(end 191.71539 -197.741286)
		(width 0.18288)
		(layer "In11.Cu")
		(net "M_H_CPU1_SB_DQS_DN<3>")
	)
	(segment
		(start 135.418068 -227.155502)
		(end 135.407654 -227.149406)
		(width 0.088646)
		(layer "In11.Cu")
		(net "M_H_CPU1_SB_DQS_DN<3>")
	)
	(segment
		(start 173.276514 -198.866506)
		(end 173.001178 -198.59117)
		(width 0.18288)
		(layer "In11.Cu")
		(net "M_H_CPU1_SB_DQS_DN<3>")
	)
	(segment
		(start 139.307824 -224.467674)
		(end 139.307824 -224.850452)
		(width 0.088646)
		(layer "In11.Cu")
		(net "M_H_CPU1_SB_DQS_DN<3>")
	)
	(segment
		(start 140.683742 -221.721934)
		(end 140.683742 -221.806262)
		(width 0.088646)
		(layer "In11.Cu")
		(net "M_H_CPU1_SB_DQS_DN<3>")
	)
	(segment
		(start 125.080014 -227.155502)
		(end 125.0696 -227.149406)
		(width 0.088646)
		(layer "In11.Cu")
		(net "M_H_CPU1_SB_DQS_DN<3>")
	)
	(segment
		(start 179.749704 -199.471788)
		(end 178.296316 -198.0184)
		(width 0.18288)
		(layer "In11.Cu")
		(net "M_H_CPU1_SB_DQS_DN<3>")
	)
	(segment
		(start 190.022734 -198.030084)
		(end 189.186312 -198.866506)
		(width 0.18288)
		(layer "In11.Cu")
		(net "M_H_CPU1_SB_DQS_DN<3>")
	)
	(segment
		(start 184.91073 -199.992488)
		(end 184.91073 -199.256142)
		(width 0.18288)
		(layer "In11.Cu")
		(net "M_H_CPU1_SB_DQS_DN<3>")
	)
	(segment
		(start 185.62447 -199.256142)
		(end 185.62447 -199.992488)
		(width 0.18288)
		(layer "In11.Cu")
		(net "M_H_CPU1_SB_DQS_DN<3>")
	)
	(segment
		(start 140.683742 -221.806262)
		(end 140.46454 -222.025464)
		(width 0.088646)
		(layer "In11.Cu")
		(net "M_H_CPU1_SB_DQS_DN<3>")
	)
	(segment
		(start 130.719068 -227.155502)
		(end 130.708654 -227.149406)
		(width 0.088646)
		(layer "In11.Cu")
		(net "M_H_CPU1_SB_DQS_DN<3>")
	)
	(segment
		(start 202.706478 -200.131426)
		(end 202.33386 -200.131426)
		(width 0.18288)
		(layer "In11.Cu")
		(net "M_H_CPU1_SB_DQS_DN<3>")
	)
	(segment
		(start 173.001178 -198.59117)
		(end 172.527722 -198.59117)
		(width 0.18288)
		(layer "In11.Cu")
		(net "M_H_CPU1_SB_DQS_DN<3>")
	)
	(segment
		(start 161.388806 -199.97293)
		(end 160.582356 -200.77938)
		(width 0.18288)
		(layer "In11.Cu")
		(net "M_H_CPU1_SB_DQS_DN<3>")
	)
	(segment
		(start 182.773828 -199.471788)
		(end 179.749704 -199.471788)
		(width 0.18288)
		(layer "In11.Cu")
		(net "M_H_CPU1_SB_DQS_DN<3>")
	)
	(segment
		(start 193.1797 -198.016622)
		(end 192.47739 -198.016622)
		(width 0.18288)
		(layer "In11.Cu")
		(net "M_H_CPU1_SB_DQS_DN<3>")
	)
	(segment
		(start 173.54169 -198.866506)
		(end 173.276514 -198.866506)
		(width 0.18288)
		(layer "In11.Cu")
		(net "M_H_CPU1_SB_DQS_DN<3>")
	)
	(segment
		(start 185.62447 -199.992488)
		(end 185.428382 -200.188576)
		(width 0.18288)
		(layer "In11.Cu")
		(net "M_H_CPU1_SB_DQS_DN<3>")
	)
	(segment
		(start 172.527722 -198.59117)
		(end 172.263562 -198.85533)
		(width 0.18288)
		(layer "In11.Cu")
		(net "M_H_CPU1_SB_DQS_DN<3>")
	)
	(segment
		(start 184.91073 -199.256142)
		(end 184.533286 -198.878698)
		(width 0.18288)
		(layer "In11.Cu")
		(net "M_H_CPU1_SB_DQS_DN<3>")
	)
	(segment
		(start 126.019814 -227.155502)
		(end 126.005082 -227.146866)
		(width 0.088646)
		(layer "In11.Cu")
		(net "M_H_CPU1_SB_DQS_DN<3>")
	)
	(segment
		(start 123.23064 -227.64496)
		(end 122.917966 -227.64496)
		(width 0.088646)
		(layer "In11.Cu")
		(net "M_H_CPU1_SB_DQS_DN<3>")
	)
	(segment
		(start 128.284478 -227.149406)
		(end 128.274064 -227.155502)
		(width 0.088646)
		(layer "In11.Cu")
		(net "M_H_CPU1_SB_DQS_DN<3>")
	)
	(segment
		(start 188.091318 -198.59117)
		(end 187.615322 -198.59117)
		(width 0.18288)
		(layer "In11.Cu")
		(net "M_H_CPU1_SB_DQS_DN<3>")
	)
	(segment
		(start 135.979916 -226.821238)
		(end 135.979916 -226.831144)
		(width 0.088646)
		(layer "In11.Cu")
		(net "M_H_CPU1_SB_DQS_DN<3>")
	)
	(segment
		(start 126.959868 -227.155502)
		(end 126.949454 -227.149406)
		(width 0.088646)
		(layer "In11.Cu")
		(net "M_H_CPU1_SB_DQS_DN<3>")
	)
	(segment
		(start 187.615322 -198.59117)
		(end 187.327794 -198.878698)
		(width 0.18288)
		(layer "In11.Cu")
		(net "M_H_CPU1_SB_DQS_DN<3>")
	)
	(segment
		(start 157.127956 -200.77938)
		(end 155.104846 -202.80249)
		(width 0.18288)
		(layer "In11.Cu")
		(net "M_H_CPU1_SB_DQS_DN<3>")
	)
	(segment
		(start 192.47739 -198.016622)
		(end 192.202054 -197.741286)
		(width 0.18288)
		(layer "In11.Cu")
		(net "M_H_CPU1_SB_DQS_DN<3>")
	)
	(segment
		(start 189.186312 -198.866506)
		(end 188.366654 -198.866506)
		(width 0.18288)
		(layer "In11.Cu")
		(net "M_H_CPU1_SB_DQS_DN<3>")
	)
	(segment
		(start 123.296172 -227.579428)
		(end 123.23064 -227.64496)
		(width 0.088646)
		(layer "In11.Cu")
		(net "M_H_CPU1_SB_DQS_DN<3>")
	)
	(segment
		(start 140.46454 -222.025464)
		(end 140.46454 -223.310958)
		(width 0.088646)
		(layer "In11.Cu")
		(net "M_H_CPU1_SB_DQS_DN<3>")
	)
	(segment
		(start 176.358804 -198.010272)
		(end 174.397924 -198.010272)
		(width 0.18288)
		(layer "In11.Cu")
		(net "M_H_CPU1_SB_DQS_DN<3>")
	)
	(segment
		(start 176.62779 -197.741286)
		(end 176.358804 -198.010272)
		(width 0.18288)
		(layer "In11.Cu")
		(net "M_H_CPU1_SB_DQS_DN<3>")
	)
	(segment
		(start 201.969624 -199.76719)
		(end 194.930268 -199.76719)
		(width 0.18288)
		(layer "In11.Cu")
		(net "M_H_CPU1_SB_DQS_DN<3>")
	)
	(segment
		(start 133.538468 -227.155502)
		(end 133.528054 -227.149406)
		(width 0.088646)
		(layer "In11.Cu")
		(net "M_H_CPU1_SB_DQS_DN<3>")
	)
	(segment
		(start 124.140468 -227.155502)
		(end 124.130054 -227.149406)
		(width 0.088646)
		(layer "In11.Cu")
		(net "M_H_CPU1_SB_DQS_DN<3>")
	)
	(segment
		(start 138.329416 -225.998786)
		(end 138.329416 -226.017328)
		(width 0.088646)
		(layer "In11.Cu")
		(net "M_H_CPU1_SB_DQS_DN<3>")
	)
	(segment
		(start 191.426592 -198.030084)
		(end 190.022734 -198.030084)
		(width 0.18288)
		(layer "In11.Cu")
		(net "M_H_CPU1_SB_DQS_DN<3>")
	)
	(segment
		(start 172.263562 -198.85533)
		(end 170.080686 -198.85533)
		(width 0.18288)
		(layer "In11.Cu")
		(net "M_H_CPU1_SB_DQS_DN<3>")
	)
	(segment
		(start 155.104846 -202.80249)
		(end 155.104846 -204.43698)
		(width 0.18288)
		(layer "In11.Cu")
		(net "M_H_CPU1_SB_DQS_DN<3>")
	)
	(segment
		(start 202.33386 -200.131426)
		(end 201.969624 -199.76719)
		(width 0.18288)
		(layer "In11.Cu")
		(net "M_H_CPU1_SB_DQS_DN<3>")
	)
	(arc
		(start 129.764282 -227.146866)
		(mid 129.487807 -227.079546)
		(end 129.21361 -227.155502)
		(width 0.088646)
		(layer "In11.Cu")
		(net "M_H_CPU1_SB_DQS_DN<3>")
	)
	(arc
		(start 124.130054 -227.149406)
		(mid 123.608114 -227.137625)
		(end 123.298966 -227.558346)
		(width 0.088646)
		(layer "In11.Cu")
		(net "M_H_CPU1_SB_DQS_DN<3>")
	)
	(arc
		(start 137.202164 -226.341686)
		(mid 137.014966 -226.391829)
		(end 136.827768 -226.341686)
		(width 0.088646)
		(layer "In11.Cu")
		(net "M_H_CPU1_SB_DQS_DN<3>")
	)
	(arc
		(start 125.45441 -227.155502)
		(mid 125.267212 -227.205645)
		(end 125.080014 -227.155502)
		(width 0.088646)
		(layer "In11.Cu")
		(net "M_H_CPU1_SB_DQS_DN<3>")
	)
	(arc
		(start 132.03301 -227.155502)
		(mid 131.845812 -227.205645)
		(end 131.658614 -227.155502)
		(width 0.088646)
		(layer "In11.Cu")
		(net "M_H_CPU1_SB_DQS_DN<3>")
	)
	(arc
		(start 130.15341 -227.155502)
		(mid 129.966212 -227.205645)
		(end 129.779014 -227.155502)
		(width 0.088646)
		(layer "In11.Cu")
		(net "M_H_CPU1_SB_DQS_DN<3>")
	)
	(arc
		(start 131.6482 -227.149406)
		(mid 131.370022 -227.079683)
		(end 131.093464 -227.155502)
		(width 0.088646)
		(layer "In11.Cu")
		(net "M_H_CPU1_SB_DQS_DN<3>")
	)
	(arc
		(start 128.274064 -227.155502)
		(mid 128.086866 -227.205645)
		(end 127.899668 -227.155502)
		(width 0.088646)
		(layer "In11.Cu")
		(net "M_H_CPU1_SB_DQS_DN<3>")
	)
	(arc
		(start 135.979916 -226.831144)
		(mid 135.792617 -227.155585)
		(end 135.418068 -227.155502)
		(width 0.088646)
		(layer "In11.Cu")
		(net "M_H_CPU1_SB_DQS_DN<3>")
	)
	(arc
		(start 128.839214 -227.155502)
		(mid 128.562655 -227.079759)
		(end 128.284478 -227.149406)
		(width 0.088646)
		(layer "In11.Cu")
		(net "M_H_CPU1_SB_DQS_DN<3>")
	)
	(arc
		(start 133.912864 -227.155502)
		(mid 133.725666 -227.205645)
		(end 133.538468 -227.155502)
		(width 0.088646)
		(layer "In11.Cu")
		(net "M_H_CPU1_SB_DQS_DN<3>")
	)
	(arc
		(start 132.583682 -227.146866)
		(mid 132.307207 -227.079546)
		(end 132.03301 -227.155502)
		(width 0.088646)
		(layer "In11.Cu")
		(net "M_H_CPU1_SB_DQS_DN<3>")
	)
	(arc
		(start 125.0696 -227.149406)
		(mid 124.791422 -227.079683)
		(end 124.514864 -227.155502)
		(width 0.088646)
		(layer "In11.Cu")
		(net "M_H_CPU1_SB_DQS_DN<3>")
	)
	(arc
		(start 135.407654 -227.149406)
		(mid 135.129222 -227.07956)
		(end 134.85241 -227.155502)
		(width 0.088646)
		(layer "In11.Cu")
		(net "M_H_CPU1_SB_DQS_DN<3>")
	)
	(arc
		(start 138.329416 -226.017328)
		(mid 138.142117 -226.341769)
		(end 137.767568 -226.341686)
		(width 0.088646)
		(layer "In11.Cu")
		(net "M_H_CPU1_SB_DQS_DN<3>")
	)
	(arc
		(start 132.97281 -227.155502)
		(mid 132.785612 -227.205645)
		(end 132.598414 -227.155502)
		(width 0.088646)
		(layer "In11.Cu")
		(net "M_H_CPU1_SB_DQS_DN<3>")
	)
	(arc
		(start 126.949454 -227.149406)
		(mid 126.671022 -227.07956)
		(end 126.39421 -227.155502)
		(width 0.088646)
		(layer "In11.Cu")
		(net "M_H_CPU1_SB_DQS_DN<3>")
	)
	(arc
		(start 131.093464 -227.155502)
		(mid 130.906266 -227.205645)
		(end 130.719068 -227.155502)
		(width 0.088646)
		(layer "In11.Cu")
		(net "M_H_CPU1_SB_DQS_DN<3>")
	)
	(arc
		(start 126.005082 -227.146866)
		(mid 125.728607 -227.079546)
		(end 125.45441 -227.155502)
		(width 0.088646)
		(layer "In11.Cu")
		(net "M_H_CPU1_SB_DQS_DN<3>")
	)
	(arc
		(start 134.4676 -227.149406)
		(mid 134.189422 -227.079683)
		(end 133.912864 -227.155502)
		(width 0.088646)
		(layer "In11.Cu")
		(net "M_H_CPU1_SB_DQS_DN<3>")
	)
	(arc
		(start 134.85241 -227.155502)
		(mid 134.665212 -227.205645)
		(end 134.478014 -227.155502)
		(width 0.088646)
		(layer "In11.Cu")
		(net "M_H_CPU1_SB_DQS_DN<3>")
	)
	(arc
		(start 124.514864 -227.155502)
		(mid 124.327666 -227.205645)
		(end 124.140468 -227.155502)
		(width 0.088646)
		(layer "In11.Cu")
		(net "M_H_CPU1_SB_DQS_DN<3>")
	)
	(arc
		(start 133.528054 -227.149406)
		(mid 133.249622 -227.07956)
		(end 132.97281 -227.155502)
		(width 0.088646)
		(layer "In11.Cu")
		(net "M_H_CPU1_SB_DQS_DN<3>")
	)
	(arc
		(start 127.334264 -227.155502)
		(mid 127.147066 -227.205645)
		(end 126.959868 -227.155502)
		(width 0.088646)
		(layer "In11.Cu")
		(net "M_H_CPU1_SB_DQS_DN<3>")
	)
	(arc
		(start 136.827768 -226.341686)
		(mid 136.266792 -226.339155)
		(end 135.979916 -226.821238)
		(width 0.088646)
		(layer "In11.Cu")
		(net "M_H_CPU1_SB_DQS_DN<3>")
	)
	(arc
		(start 137.767568 -226.341686)
		(mid 137.484866 -226.26591)
		(end 137.202164 -226.341686)
		(width 0.088646)
		(layer "In11.Cu")
		(net "M_H_CPU1_SB_DQS_DN<3>")
	)
	(arc
		(start 138.689588 -225.468688)
		(mid 138.65265 -225.50069)
		(end 138.611864 -225.527616)
		(width 0.088646)
		(layer "In11.Cu")
		(net "M_H_CPU1_SB_DQS_DN<3>")
	)
	(arc
		(start 138.611864 -225.527616)
		(mid 138.409578 -225.726597)
		(end 138.329416 -225.998786)
		(width 0.088646)
		(layer "In11.Cu")
		(net "M_H_CPU1_SB_DQS_DN<3>")
	)
	(arc
		(start 127.899668 -227.155502)
		(mid 127.625469 -227.079667)
		(end 127.348996 -227.146866)
		(width 0.088646)
		(layer "In11.Cu")
		(net "M_H_CPU1_SB_DQS_DN<3>")
	)
	(arc
		(start 126.39421 -227.155502)
		(mid 126.207012 -227.205645)
		(end 126.019814 -227.155502)
		(width 0.088646)
		(layer "In11.Cu")
		(net "M_H_CPU1_SB_DQS_DN<3>")
	)
	(arc
		(start 123.298966 -227.558346)
		(mid 123.29747 -227.568874)
		(end 123.296172 -227.579428)
		(width 0.088646)
		(layer "In11.Cu")
		(net "M_H_CPU1_SB_DQS_DN<3>")
	)
	(arc
		(start 130.708654 -227.149406)
		(mid 130.430222 -227.07956)
		(end 130.15341 -227.155502)
		(width 0.088646)
		(layer "In11.Cu")
		(net "M_H_CPU1_SB_DQS_DN<3>")
	)
	(arc
		(start 129.21361 -227.155502)
		(mid 129.026412 -227.205645)
		(end 128.839214 -227.155502)
		(width 0.088646)
		(layer "In11.Cu")
		(net "M_H_CPU1_SB_DQS_DN<3>")
	)
	(segment
		(start 204.076046 -209.216752)
		(end 204.624686 -209.216752)
		(width 0.20066)
		(layer "F.Cu")
		(net "M_H_CPU1_SB_DQS_DN<2>")
	)
	(segment
		(start 205.64221 -209.498438)
		(end 206.056738 -209.912966)
		(width 0.20066)
		(layer "F.Cu")
		(net "M_H_CPU1_SB_DQS_DN<2>")
	)
	(segment
		(start 207.001618 -209.641694)
		(end 209.181192 -209.641694)
		(width 0.1016)
		(layer "F.Cu")
		(net "M_H_CPU1_SB_DQS_DN<2>")
	)
	(segment
		(start 210.790028 -209.45729)
		(end 211.030566 -209.216752)
		(width 0.20066)
		(layer "F.Cu")
		(net "M_H_CPU1_SB_DQS_DN<2>")
	)
	(segment
		(start 202.971146 -209.216752)
		(end 204.076046 -209.216752)
		(width 0.20066)
		(layer "F.Cu")
		(net "M_H_CPU1_SB_DQS_DN<2>")
	)
	(segment
		(start 206.849726 -209.641694)
		(end 206.9973 -209.641694)
		(width 0.20066)
		(layer "F.Cu")
		(net "M_H_CPU1_SB_DQS_DN<2>")
	)
	(segment
		(start 210.047078 -209.867754)
		(end 210.457542 -209.45729)
		(width 0.20066)
		(layer "F.Cu")
		(net "M_H_CPU1_SB_DQS_DN<2>")
	)
	(segment
		(start 210.457542 -209.45729)
		(end 210.790028 -209.45729)
		(width 0.20066)
		(layer "F.Cu")
		(net "M_H_CPU1_SB_DQS_DN<2>")
	)
	(segment
		(start 206.9973 -209.641694)
		(end 207.001618 -209.641694)
		(width 0.101854)
		(layer "F.Cu")
		(net "M_H_CPU1_SB_DQS_DN<2>")
	)
	(segment
		(start 209.51063 -209.63636)
		(end 209.742024 -209.867754)
		(width 0.20066)
		(layer "F.Cu")
		(net "M_H_CPU1_SB_DQS_DN<2>")
	)
	(segment
		(start 206.056738 -209.912966)
		(end 206.578454 -209.912966)
		(width 0.20066)
		(layer "F.Cu")
		(net "M_H_CPU1_SB_DQS_DN<2>")
	)
	(segment
		(start 127.146812 -230.622348)
		(end 127.146812 -230.086662)
		(width 0.20066)
		(layer "F.Cu")
		(net "M_H_CPU1_SB_DQS_DN<2>")
	)
	(segment
		(start 209.181192 -209.641694)
		(end 209.186526 -209.63636)
		(width 0.1016)
		(layer "F.Cu")
		(net "M_H_CPU1_SB_DQS_DN<2>")
	)
	(segment
		(start 127.147066 -230.622602)
		(end 127.146812 -230.622348)
		(width 0.20066)
		(layer "F.Cu")
		(net "M_H_CPU1_SB_DQS_DN<2>")
	)
	(segment
		(start 209.186526 -209.63636)
		(end 209.51063 -209.63636)
		(width 0.20066)
		(layer "F.Cu")
		(net "M_H_CPU1_SB_DQS_DN<2>")
	)
	(segment
		(start 211.030566 -209.216752)
		(end 211.619846 -209.216752)
		(width 0.20066)
		(layer "F.Cu")
		(net "M_H_CPU1_SB_DQS_DN<2>")
	)
	(segment
		(start 206.578454 -209.912966)
		(end 206.849726 -209.641694)
		(width 0.20066)
		(layer "F.Cu")
		(net "M_H_CPU1_SB_DQS_DN<2>")
	)
	(segment
		(start 204.624686 -209.216752)
		(end 204.906372 -209.498438)
		(width 0.20066)
		(layer "F.Cu")
		(net "M_H_CPU1_SB_DQS_DN<2>")
	)
	(segment
		(start 209.742024 -209.867754)
		(end 210.047078 -209.867754)
		(width 0.20066)
		(layer "F.Cu")
		(net "M_H_CPU1_SB_DQS_DN<2>")
	)
	(segment
		(start 204.906372 -209.498438)
		(end 205.64221 -209.498438)
		(width 0.20066)
		(layer "F.Cu")
		(net "M_H_CPU1_SB_DQS_DN<2>")
	)
	(segment
		(start 167.697404 -209.882232)
		(end 164.846762 -209.882232)
		(width 0.18288)
		(layer "In6.Cu")
		(net "M_H_CPU1_SB_DQS_DN<2>")
	)
	(segment
		(start 138.172444 -228.344222)
		(end 138.172444 -229.032308)
		(width 0.088646)
		(layer "In6.Cu")
		(net "M_H_CPU1_SB_DQS_DN<2>")
	)
	(segment
		(start 201.98207 -209.138012)
		(end 199.320658 -209.138012)
		(width 0.18288)
		(layer "In6.Cu")
		(net "M_H_CPU1_SB_DQS_DN<2>")
	)
	(segment
		(start 139.250674 -227.473002)
		(end 139.190984 -227.532692)
		(width 0.088646)
		(layer "In6.Cu")
		(net "M_H_CPU1_SB_DQS_DN<2>")
	)
	(segment
		(start 128.839214 -230.41102)
		(end 128.824482 -230.402384)
		(width 0.088646)
		(layer "In6.Cu")
		(net "M_H_CPU1_SB_DQS_DN<2>")
	)
	(segment
		(start 158.71571 -209.864706)
		(end 158.59125 -209.989166)
		(width 0.18288)
		(layer "In6.Cu")
		(net "M_H_CPU1_SB_DQS_DN<2>")
	)
	(segment
		(start 163.149788 -210.518502)
		(end 163.025328 -210.394042)
		(width 0.18288)
		(layer "In6.Cu")
		(net "M_H_CPU1_SB_DQS_DN<2>")
	)
	(segment
		(start 195.794122 -209.841846)
		(end 194.126104 -209.150966)
		(width 0.18288)
		(layer "In6.Cu")
		(net "M_H_CPU1_SB_DQS_DN<2>")
	)
	(segment
		(start 176.719992 -211.342732)
		(end 176.451514 -211.61121)
		(width 0.18288)
		(layer "In6.Cu")
		(net "M_H_CPU1_SB_DQS_DN<2>")
	)
	(segment
		(start 138.172444 -229.032308)
		(end 137.683494 -229.521258)
		(width 0.088646)
		(layer "In6.Cu")
		(net "M_H_CPU1_SB_DQS_DN<2>")
	)
	(segment
		(start 188.0616 -210.492594)
		(end 187.704476 -210.492594)
		(width 0.18288)
		(layer "In6.Cu")
		(net "M_H_CPU1_SB_DQS_DN<2>")
	)
	(segment
		(start 182.954422 -210.083908)
		(end 179.758086 -210.083908)
		(width 0.18288)
		(layer "In6.Cu")
		(net "M_H_CPU1_SB_DQS_DN<2>")
	)
	(segment
		(start 184.59196 -210.762088)
		(end 182.954422 -210.083908)
		(width 0.18288)
		(layer "In6.Cu")
		(net "M_H_CPU1_SB_DQS_DN<2>")
	)
	(segment
		(start 155.969208 -211.896452)
		(end 140.392658 -227.473002)
		(width 0.18288)
		(layer "In6.Cu")
		(net "M_H_CPU1_SB_DQS_DN<2>")
	)
	(segment
		(start 188.33973 -210.770724)
		(end 188.0616 -210.492594)
		(width 0.18288)
		(layer "In6.Cu")
		(net "M_H_CPU1_SB_DQS_DN<2>")
	)
	(segment
		(start 191.53251 -209.920586)
		(end 189.606428 -209.920586)
		(width 0.18288)
		(layer "In6.Cu")
		(net "M_H_CPU1_SB_DQS_DN<2>")
	)
	(segment
		(start 130.1623 -230.40594)
		(end 130.15341 -230.41102)
		(width 0.088646)
		(layer "In6.Cu")
		(net "M_H_CPU1_SB_DQS_DN<2>")
	)
	(segment
		(start 160.821116 -210.518502)
		(end 160.29178 -209.989166)
		(width 0.18288)
		(layer "In6.Cu")
		(net "M_H_CPU1_SB_DQS_DN<2>")
	)
	(segment
		(start 177.331878 -211.605114)
		(end 177.069496 -211.342732)
		(width 0.18288)
		(layer "In6.Cu")
		(net "M_H_CPU1_SB_DQS_DN<2>")
	)
	(segment
		(start 159.26181 -209.864706)
		(end 158.71571 -209.864706)
		(width 0.18288)
		(layer "In6.Cu")
		(net "M_H_CPU1_SB_DQS_DN<2>")
	)
	(segment
		(start 172.621956 -212.19287)
		(end 172.345604 -212.469222)
		(width 0.18288)
		(layer "In6.Cu")
		(net "M_H_CPU1_SB_DQS_DN<2>")
	)
	(segment
		(start 199.320658 -209.138012)
		(end 197.621398 -209.841846)
		(width 0.18288)
		(layer "In6.Cu")
		(net "M_H_CPU1_SB_DQS_DN<2>")
	)
	(segment
		(start 192.436242 -209.920586)
		(end 192.158112 -209.642456)
		(width 0.18288)
		(layer "In6.Cu")
		(net "M_H_CPU1_SB_DQS_DN<2>")
	)
	(segment
		(start 129.779014 -230.41102)
		(end 129.764282 -230.402384)
		(width 0.088646)
		(layer "In6.Cu")
		(net "M_H_CPU1_SB_DQS_DN<2>")
	)
	(segment
		(start 202.714352 -209.473546)
		(end 202.317604 -209.473546)
		(width 0.18288)
		(layer "In6.Cu")
		(net "M_H_CPU1_SB_DQS_DN<2>")
	)
	(segment
		(start 188.75629 -210.770724)
		(end 188.33973 -210.770724)
		(width 0.18288)
		(layer "In6.Cu")
		(net "M_H_CPU1_SB_DQS_DN<2>")
	)
	(segment
		(start 171.646342 -212.469222)
		(end 169.824146 -210.647026)
		(width 0.18288)
		(layer "In6.Cu")
		(net "M_H_CPU1_SB_DQS_DN<2>")
	)
	(segment
		(start 160.29178 -209.989166)
		(end 159.38627 -209.989166)
		(width 0.18288)
		(layer "In6.Cu")
		(net "M_H_CPU1_SB_DQS_DN<2>")
	)
	(segment
		(start 193.52006 -209.150966)
		(end 192.75044 -209.920586)
		(width 0.18288)
		(layer "In6.Cu")
		(net "M_H_CPU1_SB_DQS_DN<2>")
	)
	(segment
		(start 132.517896 -229.588568)
		(end 132.503164 -229.597204)
		(width 0.088646)
		(layer "In6.Cu")
		(net "M_H_CPU1_SB_DQS_DN<2>")
	)
	(segment
		(start 155.969208 -211.614512)
		(end 155.969208 -211.896452)
		(width 0.18288)
		(layer "In6.Cu")
		(net "M_H_CPU1_SB_DQS_DN<2>")
	)
	(segment
		(start 177.541428 -211.605114)
		(end 177.331878 -211.605114)
		(width 0.18288)
		(layer "In6.Cu")
		(net "M_H_CPU1_SB_DQS_DN<2>")
	)
	(segment
		(start 126.776734 -230.143812)
		(end 126.833884 -230.086662)
		(width 0.088646)
		(layer "In6.Cu")
		(net "M_H_CPU1_SB_DQS_DN<2>")
	)
	(segment
		(start 172.345604 -212.469222)
		(end 171.646342 -212.469222)
		(width 0.18288)
		(layer "In6.Cu")
		(net "M_H_CPU1_SB_DQS_DN<2>")
	)
	(segment
		(start 192.158112 -209.642456)
		(end 191.81064 -209.642456)
		(width 0.18288)
		(layer "In6.Cu")
		(net "M_H_CPU1_SB_DQS_DN<2>")
	)
	(segment
		(start 173.669706 -212.471)
		(end 173.248066 -212.471)
		(width 0.18288)
		(layer "In6.Cu")
		(net "M_H_CPU1_SB_DQS_DN<2>")
	)
	(segment
		(start 168.462198 -210.647026)
		(end 167.697404 -209.882232)
		(width 0.18288)
		(layer "In6.Cu")
		(net "M_H_CPU1_SB_DQS_DN<2>")
	)
	(segment
		(start 162.354768 -210.518502)
		(end 160.821116 -210.518502)
		(width 0.18288)
		(layer "In6.Cu")
		(net "M_H_CPU1_SB_DQS_DN<2>")
	)
	(segment
		(start 179.319428 -210.522566)
		(end 178.623976 -210.522566)
		(width 0.18288)
		(layer "In6.Cu")
		(net "M_H_CPU1_SB_DQS_DN<2>")
	)
	(segment
		(start 187.434982 -210.762088)
		(end 184.59196 -210.762088)
		(width 0.18288)
		(layer "In6.Cu")
		(net "M_H_CPU1_SB_DQS_DN<2>")
	)
	(segment
		(start 202.317604 -209.473546)
		(end 201.98207 -209.138012)
		(width 0.18288)
		(layer "In6.Cu")
		(net "M_H_CPU1_SB_DQS_DN<2>")
	)
	(segment
		(start 179.758086 -210.083908)
		(end 179.319428 -210.522566)
		(width 0.18288)
		(layer "In6.Cu")
		(net "M_H_CPU1_SB_DQS_DN<2>")
	)
	(segment
		(start 158.59125 -209.989166)
		(end 157.594554 -209.989166)
		(width 0.18288)
		(layer "In6.Cu")
		(net "M_H_CPU1_SB_DQS_DN<2>")
	)
	(segment
		(start 169.824146 -210.647026)
		(end 168.462198 -210.647026)
		(width 0.18288)
		(layer "In6.Cu")
		(net "M_H_CPU1_SB_DQS_DN<2>")
	)
	(segment
		(start 162.479228 -210.394042)
		(end 162.354768 -210.518502)
		(width 0.18288)
		(layer "In6.Cu")
		(net "M_H_CPU1_SB_DQS_DN<2>")
	)
	(segment
		(start 197.621398 -209.841846)
		(end 195.794122 -209.841846)
		(width 0.18288)
		(layer "In6.Cu")
		(net "M_H_CPU1_SB_DQS_DN<2>")
	)
	(segment
		(start 139.274042 -227.473002)
		(end 139.250674 -227.473002)
		(width 0.088646)
		(layer "In6.Cu")
		(net "M_H_CPU1_SB_DQS_DN<2>")
	)
	(segment
		(start 164.210492 -210.518502)
		(end 163.149788 -210.518502)
		(width 0.18288)
		(layer "In6.Cu")
		(net "M_H_CPU1_SB_DQS_DN<2>")
	)
	(segment
		(start 187.704476 -210.492594)
		(end 187.434982 -210.762088)
		(width 0.18288)
		(layer "In6.Cu")
		(net "M_H_CPU1_SB_DQS_DN<2>")
	)
	(segment
		(start 130.622802 -229.597712)
		(end 130.617468 -229.60076)
		(width 0.088646)
		(layer "In6.Cu")
		(net "M_H_CPU1_SB_DQS_DN<2>")
	)
	(segment
		(start 126.95809 -230.410258)
		(end 126.950724 -230.40594)
		(width 0.088646)
		(layer "In6.Cu")
		(net "M_H_CPU1_SB_DQS_DN<2>")
	)
	(segment
		(start 173.248066 -212.471)
		(end 172.969936 -212.19287)
		(width 0.18288)
		(layer "In6.Cu")
		(net "M_H_CPU1_SB_DQS_DN<2>")
	)
	(segment
		(start 172.969936 -212.19287)
		(end 172.621956 -212.19287)
		(width 0.18288)
		(layer "In6.Cu")
		(net "M_H_CPU1_SB_DQS_DN<2>")
	)
	(segment
		(start 163.025328 -210.394042)
		(end 162.479228 -210.394042)
		(width 0.18288)
		(layer "In6.Cu")
		(net "M_H_CPU1_SB_DQS_DN<2>")
	)
	(segment
		(start 192.75044 -209.920586)
		(end 192.436242 -209.920586)
		(width 0.18288)
		(layer "In6.Cu")
		(net "M_H_CPU1_SB_DQS_DN<2>")
	)
	(segment
		(start 140.392658 -227.473002)
		(end 139.274042 -227.473002)
		(width 0.18288)
		(layer "In6.Cu")
		(net "M_H_CPU1_SB_DQS_DN<2>")
	)
	(segment
		(start 177.069496 -211.342732)
		(end 176.719992 -211.342732)
		(width 0.18288)
		(layer "In6.Cu")
		(net "M_H_CPU1_SB_DQS_DN<2>")
	)
	(segment
		(start 130.638296 -229.588568)
		(end 130.623564 -229.597204)
		(width 0.088646)
		(layer "In6.Cu")
		(net "M_H_CPU1_SB_DQS_DN<2>")
	)
	(segment
		(start 176.451514 -211.61121)
		(end 174.529496 -211.61121)
		(width 0.18288)
		(layer "In6.Cu")
		(net "M_H_CPU1_SB_DQS_DN<2>")
	)
	(segment
		(start 194.126104 -209.150966)
		(end 193.52006 -209.150966)
		(width 0.18288)
		(layer "In6.Cu")
		(net "M_H_CPU1_SB_DQS_DN<2>")
	)
	(segment
		(start 164.846762 -209.882232)
		(end 164.210492 -210.518502)
		(width 0.18288)
		(layer "In6.Cu")
		(net "M_H_CPU1_SB_DQS_DN<2>")
	)
	(segment
		(start 130.623564 -229.597204)
		(end 130.622802 -229.597712)
		(width 0.088646)
		(layer "In6.Cu")
		(net "M_H_CPU1_SB_DQS_DN<2>")
	)
	(segment
		(start 157.594554 -209.989166)
		(end 155.969208 -211.614512)
		(width 0.18288)
		(layer "In6.Cu")
		(net "M_H_CPU1_SB_DQS_DN<2>")
	)
	(segment
		(start 189.606428 -209.920586)
		(end 188.75629 -210.770724)
		(width 0.18288)
		(layer "In6.Cu")
		(net "M_H_CPU1_SB_DQS_DN<2>")
	)
	(segment
		(start 126.959614 -230.41102)
		(end 126.95809 -230.410258)
		(width 0.088646)
		(layer "In6.Cu")
		(net "M_H_CPU1_SB_DQS_DN<2>")
	)
	(segment
		(start 202.971146 -209.216752)
		(end 202.714352 -209.473546)
		(width 0.18288)
		(layer "In6.Cu")
		(net "M_H_CPU1_SB_DQS_DN<2>")
	)
	(segment
		(start 159.38627 -209.989166)
		(end 159.26181 -209.864706)
		(width 0.18288)
		(layer "In6.Cu")
		(net "M_H_CPU1_SB_DQS_DN<2>")
	)
	(segment
		(start 127.899414 -230.41102)
		(end 127.884682 -230.402384)
		(width 0.088646)
		(layer "In6.Cu")
		(net "M_H_CPU1_SB_DQS_DN<2>")
	)
	(segment
		(start 139.190984 -227.532692)
		(end 138.983974 -227.532692)
		(width 0.088646)
		(layer "In6.Cu")
		(net "M_H_CPU1_SB_DQS_DN<2>")
	)
	(segment
		(start 126.833884 -230.086662)
		(end 127.146812 -230.086662)
		(width 0.088646)
		(layer "In6.Cu")
		(net "M_H_CPU1_SB_DQS_DN<2>")
	)
	(segment
		(start 178.623976 -210.522566)
		(end 177.541428 -211.605114)
		(width 0.18288)
		(layer "In6.Cu")
		(net "M_H_CPU1_SB_DQS_DN<2>")
	)
	(segment
		(start 174.529496 -211.61121)
		(end 173.669706 -212.471)
		(width 0.18288)
		(layer "In6.Cu")
		(net "M_H_CPU1_SB_DQS_DN<2>")
	)
	(segment
		(start 138.983974 -227.532692)
		(end 138.172444 -228.344222)
		(width 0.088646)
		(layer "In6.Cu")
		(net "M_H_CPU1_SB_DQS_DN<2>")
	)
	(segment
		(start 191.81064 -209.642456)
		(end 191.53251 -209.920586)
		(width 0.18288)
		(layer "In6.Cu")
		(net "M_H_CPU1_SB_DQS_DN<2>")
	)
	(segment
		(start 137.683494 -229.521258)
		(end 137.484866 -229.521258)
		(width 0.088646)
		(layer "In6.Cu")
		(net "M_H_CPU1_SB_DQS_DN<2>")
	)
	(arc
		(start 130.340862 -230.086662)
		(mid 130.293183 -230.269562)
		(end 130.1623 -230.40594)
		(width 0.088646)
		(layer "In6.Cu")
		(net "M_H_CPU1_SB_DQS_DN<2>")
	)
	(arc
		(start 126.950724 -230.40594)
		(mid 126.834915 -230.294011)
		(end 126.776734 -230.143812)
		(width 0.088646)
		(layer "In6.Cu")
		(net "M_H_CPU1_SB_DQS_DN<2>")
	)
	(arc
		(start 133.442964 -229.597204)
		(mid 133.255766 -229.647347)
		(end 133.068568 -229.597204)
		(width 0.088646)
		(layer "In6.Cu")
		(net "M_H_CPU1_SB_DQS_DN<2>")
	)
	(arc
		(start 135.322564 -229.597204)
		(mid 135.135366 -229.647347)
		(end 134.948168 -229.597204)
		(width 0.088646)
		(layer "In6.Cu")
		(net "M_H_CPU1_SB_DQS_DN<2>")
	)
	(arc
		(start 133.068568 -229.597204)
		(mid 132.794369 -229.521369)
		(end 132.517896 -229.588568)
		(width 0.088646)
		(layer "In6.Cu")
		(net "M_H_CPU1_SB_DQS_DN<2>")
	)
	(arc
		(start 129.764282 -230.402384)
		(mid 129.487807 -230.335064)
		(end 129.21361 -230.41102)
		(width 0.088646)
		(layer "In6.Cu")
		(net "M_H_CPU1_SB_DQS_DN<2>")
	)
	(arc
		(start 131.188968 -229.597204)
		(mid 130.914769 -229.521369)
		(end 130.638296 -229.588568)
		(width 0.088646)
		(layer "In6.Cu")
		(net "M_H_CPU1_SB_DQS_DN<2>")
	)
	(arc
		(start 129.21361 -230.41102)
		(mid 129.026412 -230.461163)
		(end 128.839214 -230.41102)
		(width 0.088646)
		(layer "In6.Cu")
		(net "M_H_CPU1_SB_DQS_DN<2>")
	)
	(arc
		(start 137.484866 -229.521258)
		(mid 137.460333 -229.521746)
		(end 137.435844 -229.52329)
		(width 0.088646)
		(layer "In6.Cu")
		(net "M_H_CPU1_SB_DQS_DN<2>")
	)
	(arc
		(start 130.15341 -230.41102)
		(mid 129.966212 -230.461163)
		(end 129.779014 -230.41102)
		(width 0.088646)
		(layer "In6.Cu")
		(net "M_H_CPU1_SB_DQS_DN<2>")
	)
	(arc
		(start 134.948168 -229.597204)
		(mid 134.665466 -229.521428)
		(end 134.382764 -229.597204)
		(width 0.088646)
		(layer "In6.Cu")
		(net "M_H_CPU1_SB_DQS_DN<2>")
	)
	(arc
		(start 131.563364 -229.597204)
		(mid 131.376166 -229.647347)
		(end 131.188968 -229.597204)
		(width 0.088646)
		(layer "In6.Cu")
		(net "M_H_CPU1_SB_DQS_DN<2>")
	)
	(arc
		(start 127.884682 -230.402384)
		(mid 127.608207 -230.335064)
		(end 127.33401 -230.41102)
		(width 0.088646)
		(layer "In6.Cu")
		(net "M_H_CPU1_SB_DQS_DN<2>")
	)
	(arc
		(start 128.27381 -230.41102)
		(mid 128.086612 -230.461163)
		(end 127.899414 -230.41102)
		(width 0.088646)
		(layer "In6.Cu")
		(net "M_H_CPU1_SB_DQS_DN<2>")
	)
	(arc
		(start 127.33401 -230.41102)
		(mid 127.146812 -230.461163)
		(end 126.959614 -230.41102)
		(width 0.088646)
		(layer "In6.Cu")
		(net "M_H_CPU1_SB_DQS_DN<2>")
	)
	(arc
		(start 136.827768 -229.597204)
		(mid 136.545066 -229.521428)
		(end 136.262364 -229.597204)
		(width 0.088646)
		(layer "In6.Cu")
		(net "M_H_CPU1_SB_DQS_DN<2>")
	)
	(arc
		(start 132.503164 -229.597204)
		(mid 132.315966 -229.647347)
		(end 132.128768 -229.597204)
		(width 0.088646)
		(layer "In6.Cu")
		(net "M_H_CPU1_SB_DQS_DN<2>")
	)
	(arc
		(start 132.128768 -229.597204)
		(mid 131.846066 -229.521428)
		(end 131.563364 -229.597204)
		(width 0.088646)
		(layer "In6.Cu")
		(net "M_H_CPU1_SB_DQS_DN<2>")
	)
	(arc
		(start 136.262364 -229.597204)
		(mid 136.075166 -229.647347)
		(end 135.887968 -229.597204)
		(width 0.088646)
		(layer "In6.Cu")
		(net "M_H_CPU1_SB_DQS_DN<2>")
	)
	(arc
		(start 134.008368 -229.597204)
		(mid 133.725666 -229.521428)
		(end 133.442964 -229.597204)
		(width 0.088646)
		(layer "In6.Cu")
		(net "M_H_CPU1_SB_DQS_DN<2>")
	)
	(arc
		(start 134.382764 -229.597204)
		(mid 134.195566 -229.647347)
		(end 134.008368 -229.597204)
		(width 0.088646)
		(layer "In6.Cu")
		(net "M_H_CPU1_SB_DQS_DN<2>")
	)
	(arc
		(start 137.202164 -229.597204)
		(mid 137.014966 -229.647347)
		(end 136.827768 -229.597204)
		(width 0.088646)
		(layer "In6.Cu")
		(net "M_H_CPU1_SB_DQS_DN<2>")
	)
	(arc
		(start 135.887968 -229.597204)
		(mid 135.605266 -229.521428)
		(end 135.322564 -229.597204)
		(width 0.088646)
		(layer "In6.Cu")
		(net "M_H_CPU1_SB_DQS_DN<2>")
	)
	(arc
		(start 128.824482 -230.402384)
		(mid 128.548007 -230.335064)
		(end 128.27381 -230.41102)
		(width 0.088646)
		(layer "In6.Cu")
		(net "M_H_CPU1_SB_DQS_DN<2>")
	)
	(arc
		(start 137.435844 -229.52329)
		(mid 137.31494 -229.547409)
		(end 137.202164 -229.597204)
		(width 0.088646)
		(layer "In6.Cu")
		(net "M_H_CPU1_SB_DQS_DN<2>")
	)
	(arc
		(start 130.617468 -229.60076)
		(mid 130.414881 -229.807111)
		(end 130.340862 -230.086662)
		(width 0.088646)
		(layer "In6.Cu")
		(net "M_H_CPU1_SB_DQS_DN<2>")
	)
	(segment
		(start 123.857512 -233.064304)
		(end 123.857512 -232.528618)
		(width 0.20066)
		(layer "F.Cu")
		(net "M_H_CPU1_SB_DQS_DN<1>")
	)
	(segment
		(start 210.457542 -218.807284)
		(end 210.790028 -218.807284)
		(width 0.20066)
		(layer "F.Cu")
		(net "M_H_CPU1_SB_DQS_DN<1>")
	)
	(segment
		(start 205.64221 -218.848432)
		(end 206.056738 -219.26296)
		(width 0.20066)
		(layer "F.Cu")
		(net "M_H_CPU1_SB_DQS_DN<1>")
	)
	(segment
		(start 206.849726 -218.991688)
		(end 206.9973 -218.991688)
		(width 0.20066)
		(layer "F.Cu")
		(net "M_H_CPU1_SB_DQS_DN<1>")
	)
	(segment
		(start 206.056738 -219.26296)
		(end 206.578454 -219.26296)
		(width 0.20066)
		(layer "F.Cu")
		(net "M_H_CPU1_SB_DQS_DN<1>")
	)
	(segment
		(start 209.742024 -219.217748)
		(end 210.047078 -219.217748)
		(width 0.20066)
		(layer "F.Cu")
		(net "M_H_CPU1_SB_DQS_DN<1>")
	)
	(segment
		(start 209.51063 -218.986354)
		(end 209.742024 -219.217748)
		(width 0.20066)
		(layer "F.Cu")
		(net "M_H_CPU1_SB_DQS_DN<1>")
	)
	(segment
		(start 206.9973 -218.991688)
		(end 207.001618 -218.991688)
		(width 0.101854)
		(layer "F.Cu")
		(net "M_H_CPU1_SB_DQS_DN<1>")
	)
	(segment
		(start 204.624686 -218.566746)
		(end 204.906372 -218.848432)
		(width 0.20066)
		(layer "F.Cu")
		(net "M_H_CPU1_SB_DQS_DN<1>")
	)
	(segment
		(start 210.790028 -218.807284)
		(end 211.030566 -218.566746)
		(width 0.20066)
		(layer "F.Cu")
		(net "M_H_CPU1_SB_DQS_DN<1>")
	)
	(segment
		(start 123.857512 -232.528618)
		(end 123.857766 -232.528364)
		(width 0.20066)
		(layer "F.Cu")
		(net "M_H_CPU1_SB_DQS_DN<1>")
	)
	(segment
		(start 209.186526 -218.986354)
		(end 209.51063 -218.986354)
		(width 0.20066)
		(layer "F.Cu")
		(net "M_H_CPU1_SB_DQS_DN<1>")
	)
	(segment
		(start 204.906372 -218.848432)
		(end 205.64221 -218.848432)
		(width 0.20066)
		(layer "F.Cu")
		(net "M_H_CPU1_SB_DQS_DN<1>")
	)
	(segment
		(start 202.971146 -218.566746)
		(end 204.076046 -218.566746)
		(width 0.20066)
		(layer "F.Cu")
		(net "M_H_CPU1_SB_DQS_DN<1>")
	)
	(segment
		(start 206.578454 -219.26296)
		(end 206.849726 -218.991688)
		(width 0.20066)
		(layer "F.Cu")
		(net "M_H_CPU1_SB_DQS_DN<1>")
	)
	(segment
		(start 210.047078 -219.217748)
		(end 210.457542 -218.807284)
		(width 0.20066)
		(layer "F.Cu")
		(net "M_H_CPU1_SB_DQS_DN<1>")
	)
	(segment
		(start 209.181192 -218.991688)
		(end 209.186526 -218.986354)
		(width 0.1016)
		(layer "F.Cu")
		(net "M_H_CPU1_SB_DQS_DN<1>")
	)
	(segment
		(start 207.001618 -218.991688)
		(end 209.181192 -218.991688)
		(width 0.1016)
		(layer "F.Cu")
		(net "M_H_CPU1_SB_DQS_DN<1>")
	)
	(segment
		(start 204.076046 -218.566746)
		(end 204.624686 -218.566746)
		(width 0.20066)
		(layer "F.Cu")
		(net "M_H_CPU1_SB_DQS_DN<1>")
	)
	(segment
		(start 211.030566 -218.566746)
		(end 211.619846 -218.566746)
		(width 0.20066)
		(layer "F.Cu")
		(net "M_H_CPU1_SB_DQS_DN<1>")
	)
	(segment
		(start 154.87777 -215.954864)
		(end 154.87777 -217.508328)
		(width 0.18288)
		(layer "In11.Cu")
		(net "M_H_CPU1_SB_DQS_DN<1>")
	)
	(segment
		(start 188.079634 -212.191092)
		(end 187.615322 -212.191092)
		(width 0.18288)
		(layer "In11.Cu")
		(net "M_H_CPU1_SB_DQS_DN<1>")
	)
	(segment
		(start 158.198058 -213.280498)
		(end 158.00197 -213.476586)
		(width 0.18288)
		(layer "In11.Cu")
		(net "M_H_CPU1_SB_DQS_DN<1>")
	)
	(segment
		(start 140.103606 -231.120442)
		(end 139.94003 -231.120442)
		(width 0.088646)
		(layer "In11.Cu")
		(net "M_H_CPU1_SB_DQS_DN<1>")
	)
	(segment
		(start 140.163296 -231.060752)
		(end 140.103606 -231.120442)
		(width 0.088646)
		(layer "In11.Cu")
		(net "M_H_CPU1_SB_DQS_DN<1>")
	)
	(segment
		(start 126.874524 -232.846626)
		(end 126.86411 -232.852722)
		(width 0.088646)
		(layer "In11.Cu")
		(net "M_H_CPU1_SB_DQS_DN<1>")
	)
	(segment
		(start 192.190878 -213.04123)
		(end 191.701166 -213.04123)
		(width 0.18288)
		(layer "In11.Cu")
		(net "M_H_CPU1_SB_DQS_DN<1>")
	)
	(segment
		(start 174.57039 -213.324948)
		(end 173.719998 -214.17534)
		(width 0.18288)
		(layer "In11.Cu")
		(net "M_H_CPU1_SB_DQS_DN<1>")
	)
	(segment
		(start 137.767822 -232.852976)
		(end 137.767568 -232.852722)
		(width 0.088646)
		(layer "In11.Cu")
		(net "M_H_CPU1_SB_DQS_DN<1>")
	)
	(segment
		(start 184.333134 -212.483446)
		(end 183.520842 -211.671154)
		(width 0.18288)
		(layer "In11.Cu")
		(net "M_H_CPU1_SB_DQS_DN<1>")
	)
	(segment
		(start 159.531558 -213.077806)
		(end 159.152844 -212.699092)
		(width 0.18288)
		(layer "In11.Cu")
		(net "M_H_CPU1_SB_DQS_DN<1>")
	)
	(segment
		(start 170.462448 -214.054436)
		(end 170.337988 -214.178896)
		(width 0.18288)
		(layer "In11.Cu")
		(net "M_H_CPU1_SB_DQS_DN<1>")
	)
	(segment
		(start 128.758696 -232.844086)
		(end 128.743964 -232.852722)
		(width 0.088646)
		(layer "In11.Cu")
		(net "M_H_CPU1_SB_DQS_DN<1>")
	)
	(segment
		(start 139.94003 -231.120442)
		(end 139.740132 -231.32034)
		(width 0.088646)
		(layer "In11.Cu")
		(net "M_H_CPU1_SB_DQS_DN<1>")
	)
	(segment
		(start 139.740132 -231.32034)
		(end 139.740132 -231.793034)
		(width 0.088646)
		(layer "In11.Cu")
		(net "M_H_CPU1_SB_DQS_DN<1>")
	)
	(segment
		(start 123.852178 -232.522776)
		(end 123.857766 -232.528364)
		(width 0.088646)
		(layer "In11.Cu")
		(net "M_H_CPU1_SB_DQS_DN<1>")
	)
	(segment
		(start 170.337988 -214.178896)
		(end 169.789348 -214.178896)
		(width 0.18288)
		(layer "In11.Cu")
		(net "M_H_CPU1_SB_DQS_DN<1>")
	)
	(segment
		(start 159.531558 -213.280498)
		(end 159.531558 -213.077806)
		(width 0.18288)
		(layer "In11.Cu")
		(net "M_H_CPU1_SB_DQS_DN<1>")
	)
	(segment
		(start 187.615322 -212.191092)
		(end 187.322968 -212.483446)
		(width 0.18288)
		(layer "In11.Cu")
		(net "M_H_CPU1_SB_DQS_DN<1>")
	)
	(segment
		(start 193.914522 -214.116666)
		(end 193.114422 -213.316566)
		(width 0.18288)
		(layer "In11.Cu")
		(net "M_H_CPU1_SB_DQS_DN<1>")
	)
	(segment
		(start 130.638296 -232.844086)
		(end 130.623564 -232.852722)
		(width 0.088646)
		(layer "In11.Cu")
		(net "M_H_CPU1_SB_DQS_DN<1>")
	)
	(segment
		(start 139.740132 -231.793034)
		(end 139.681712 -231.933242)
		(width 0.088646)
		(layer "In11.Cu")
		(net "M_H_CPU1_SB_DQS_DN<1>")
	)
	(segment
		(start 172.527722 -213.891114)
		(end 172.23994 -214.178896)
		(width 0.18288)
		(layer "In11.Cu")
		(net "M_H_CPU1_SB_DQS_DN<1>")
	)
	(segment
		(start 159.152844 -212.699092)
		(end 158.576772 -212.699092)
		(width 0.18288)
		(layer "In11.Cu")
		(net "M_H_CPU1_SB_DQS_DN<1>")
	)
	(segment
		(start 188.35497 -212.466428)
		(end 188.079634 -212.191092)
		(width 0.18288)
		(layer "In11.Cu")
		(net "M_H_CPU1_SB_DQS_DN<1>")
	)
	(segment
		(start 195.459858 -215.033606)
		(end 194.542918 -214.116666)
		(width 0.18288)
		(layer "In11.Cu")
		(net "M_H_CPU1_SB_DQS_DN<1>")
	)
	(segment
		(start 179.963572 -211.671154)
		(end 179.108354 -212.526372)
		(width 0.18288)
		(layer "In11.Cu")
		(net "M_H_CPU1_SB_DQS_DN<1>")
	)
	(segment
		(start 202.971146 -218.566746)
		(end 202.666092 -218.8718)
		(width 0.18288)
		(layer "In11.Cu")
		(net "M_H_CPU1_SB_DQS_DN<1>")
	)
	(segment
		(start 123.487434 -232.585768)
		(end 123.550426 -232.522776)
		(width 0.088646)
		(layer "In11.Cu")
		(net "M_H_CPU1_SB_DQS_DN<1>")
	)
	(segment
		(start 201.87793 -218.375484)
		(end 200.415652 -218.375484)
		(width 0.18288)
		(layer "In11.Cu")
		(net "M_H_CPU1_SB_DQS_DN<1>")
	)
	(segment
		(start 164.452554 -213.901528)
		(end 161.261298 -213.901528)
		(width 0.18288)
		(layer "In11.Cu")
		(net "M_H_CPU1_SB_DQS_DN<1>")
	)
	(segment
		(start 191.428624 -213.313772)
		(end 190.03264 -213.313772)
		(width 0.18288)
		(layer "In11.Cu")
		(net "M_H_CPU1_SB_DQS_DN<1>")
	)
	(segment
		(start 154.87777 -217.508328)
		(end 147.519898 -224.8662)
		(width 0.18288)
		(layer "In11.Cu")
		(net "M_H_CPU1_SB_DQS_DN<1>")
	)
	(segment
		(start 157.356048 -213.476586)
		(end 154.87777 -215.954864)
		(width 0.18288)
		(layer "In11.Cu")
		(net "M_H_CPU1_SB_DQS_DN<1>")
	)
	(segment
		(start 123.550426 -232.522776)
		(end 123.852178 -232.522776)
		(width 0.088646)
		(layer "In11.Cu")
		(net "M_H_CPU1_SB_DQS_DN<1>")
	)
	(segment
		(start 183.520842 -211.671154)
		(end 179.963572 -211.671154)
		(width 0.18288)
		(layer "In11.Cu")
		(net "M_H_CPU1_SB_DQS_DN<1>")
	)
	(segment
		(start 161.261298 -213.901528)
		(end 160.836356 -213.476586)
		(width 0.18288)
		(layer "In11.Cu")
		(net "M_H_CPU1_SB_DQS_DN<1>")
	)
	(segment
		(start 164.864796 -213.489286)
		(end 164.452554 -213.901528)
		(width 0.18288)
		(layer "In11.Cu")
		(net "M_H_CPU1_SB_DQS_DN<1>")
	)
	(segment
		(start 176.62779 -213.04123)
		(end 176.344072 -213.324948)
		(width 0.18288)
		(layer "In11.Cu")
		(net "M_H_CPU1_SB_DQS_DN<1>")
	)
	(segment
		(start 139.577826 -232.037128)
		(end 139.053062 -232.254552)
		(width 0.088646)
		(layer "In11.Cu")
		(net "M_H_CPU1_SB_DQS_DN<1>")
	)
	(segment
		(start 198.563992 -216.523824)
		(end 197.41134 -216.523824)
		(width 0.18288)
		(layer "In11.Cu")
		(net "M_H_CPU1_SB_DQS_DN<1>")
	)
	(segment
		(start 134.008368 -232.852722)
		(end 133.997954 -232.846626)
		(width 0.088646)
		(layer "In11.Cu")
		(net "M_H_CPU1_SB_DQS_DN<1>")
	)
	(segment
		(start 147.519898 -225.78568)
		(end 142.244826 -231.060752)
		(width 0.18288)
		(layer "In11.Cu")
		(net "M_H_CPU1_SB_DQS_DN<1>")
	)
	(segment
		(start 202.666092 -218.8718)
		(end 202.374246 -218.8718)
		(width 0.18288)
		(layer "In11.Cu")
		(net "M_H_CPU1_SB_DQS_DN<1>")
	)
	(segment
		(start 159.727646 -213.476586)
		(end 159.531558 -213.280498)
		(width 0.18288)
		(layer "In11.Cu")
		(net "M_H_CPU1_SB_DQS_DN<1>")
	)
	(segment
		(start 173.719998 -214.17534)
		(end 173.271688 -214.17534)
		(width 0.18288)
		(layer "In11.Cu")
		(net "M_H_CPU1_SB_DQS_DN<1>")
	)
	(segment
		(start 172.23994 -214.178896)
		(end 171.135548 -214.178896)
		(width 0.18288)
		(layer "In11.Cu")
		(net "M_H_CPU1_SB_DQS_DN<1>")
	)
	(segment
		(start 178.605942 -212.526372)
		(end 177.832004 -213.30031)
		(width 0.18288)
		(layer "In11.Cu")
		(net "M_H_CPU1_SB_DQS_DN<1>")
	)
	(segment
		(start 191.701166 -213.04123)
		(end 191.428624 -213.313772)
		(width 0.18288)
		(layer "In11.Cu")
		(net "M_H_CPU1_SB_DQS_DN<1>")
	)
	(segment
		(start 133.068314 -232.852722)
		(end 133.0579 -232.846626)
		(width 0.088646)
		(layer "In11.Cu")
		(net "M_H_CPU1_SB_DQS_DN<1>")
	)
	(segment
		(start 168.124378 -213.489286)
		(end 164.864796 -213.489286)
		(width 0.18288)
		(layer "In11.Cu")
		(net "M_H_CPU1_SB_DQS_DN<1>")
	)
	(segment
		(start 131.578096 -232.844086)
		(end 131.563364 -232.852722)
		(width 0.088646)
		(layer "In11.Cu")
		(net "M_H_CPU1_SB_DQS_DN<1>")
	)
	(segment
		(start 192.466214 -213.316566)
		(end 192.190878 -213.04123)
		(width 0.18288)
		(layer "In11.Cu")
		(net "M_H_CPU1_SB_DQS_DN<1>")
	)
	(segment
		(start 187.322968 -212.483446)
		(end 184.333134 -212.483446)
		(width 0.18288)
		(layer "In11.Cu")
		(net "M_H_CPU1_SB_DQS_DN<1>")
	)
	(segment
		(start 129.698496 -232.844086)
		(end 129.683764 -232.852722)
		(width 0.088646)
		(layer "In11.Cu")
		(net "M_H_CPU1_SB_DQS_DN<1>")
	)
	(segment
		(start 171.135548 -214.178896)
		(end 171.011088 -214.054436)
		(width 0.18288)
		(layer "In11.Cu")
		(net "M_H_CPU1_SB_DQS_DN<1>")
	)
	(segment
		(start 171.011088 -214.054436)
		(end 170.462448 -214.054436)
		(width 0.18288)
		(layer "In11.Cu")
		(net "M_H_CPU1_SB_DQS_DN<1>")
	)
	(segment
		(start 200.415652 -218.375484)
		(end 198.563992 -216.523824)
		(width 0.18288)
		(layer "In11.Cu")
		(net "M_H_CPU1_SB_DQS_DN<1>")
	)
	(segment
		(start 177.108358 -213.04123)
		(end 176.62779 -213.04123)
		(width 0.18288)
		(layer "In11.Cu")
		(net "M_H_CPU1_SB_DQS_DN<1>")
	)
	(segment
		(start 124.615956 -232.856024)
		(end 124.604272 -232.84942)
		(width 0.088646)
		(layer "In11.Cu")
		(net "M_H_CPU1_SB_DQS_DN<1>")
	)
	(segment
		(start 127.818896 -232.844086)
		(end 127.804164 -232.852722)
		(width 0.088646)
		(layer "In11.Cu")
		(net "M_H_CPU1_SB_DQS_DN<1>")
	)
	(segment
		(start 176.344072 -213.324948)
		(end 174.57039 -213.324948)
		(width 0.18288)
		(layer "In11.Cu")
		(net "M_H_CPU1_SB_DQS_DN<1>")
	)
	(segment
		(start 197.41134 -216.523824)
		(end 195.921122 -215.033606)
		(width 0.18288)
		(layer "In11.Cu")
		(net "M_H_CPU1_SB_DQS_DN<1>")
	)
	(segment
		(start 173.271688 -214.17534)
		(end 172.987462 -213.891114)
		(width 0.18288)
		(layer "In11.Cu")
		(net "M_H_CPU1_SB_DQS_DN<1>")
	)
	(segment
		(start 126.489714 -232.852722)
		(end 126.495556 -232.856024)
		(width 0.088646)
		(layer "In11.Cu")
		(net "M_H_CPU1_SB_DQS_DN<1>")
	)
	(segment
		(start 160.836356 -213.476586)
		(end 159.727646 -213.476586)
		(width 0.18288)
		(layer "In11.Cu")
		(net "M_H_CPU1_SB_DQS_DN<1>")
	)
	(segment
		(start 139.053062 -232.254552)
		(end 138.404346 -232.903522)
		(width 0.088646)
		(layer "In11.Cu")
		(net "M_H_CPU1_SB_DQS_DN<1>")
	)
	(segment
		(start 158.00197 -213.476586)
		(end 157.356048 -213.476586)
		(width 0.18288)
		(layer "In11.Cu")
		(net "M_H_CPU1_SB_DQS_DN<1>")
	)
	(segment
		(start 193.114422 -213.316566)
		(end 192.466214 -213.316566)
		(width 0.18288)
		(layer "In11.Cu")
		(net "M_H_CPU1_SB_DQS_DN<1>")
	)
	(segment
		(start 190.03264 -213.313772)
		(end 189.185296 -212.466428)
		(width 0.18288)
		(layer "In11.Cu")
		(net "M_H_CPU1_SB_DQS_DN<1>")
	)
	(segment
		(start 177.367438 -213.30031)
		(end 177.108358 -213.04123)
		(width 0.18288)
		(layer "In11.Cu")
		(net "M_H_CPU1_SB_DQS_DN<1>")
	)
	(segment
		(start 195.921122 -215.033606)
		(end 195.459858 -215.033606)
		(width 0.18288)
		(layer "In11.Cu")
		(net "M_H_CPU1_SB_DQS_DN<1>")
	)
	(segment
		(start 158.198058 -213.077806)
		(end 158.198058 -213.280498)
		(width 0.18288)
		(layer "In11.Cu")
		(net "M_H_CPU1_SB_DQS_DN<1>")
	)
	(segment
		(start 194.542918 -214.116666)
		(end 193.914522 -214.116666)
		(width 0.18288)
		(layer "In11.Cu")
		(net "M_H_CPU1_SB_DQS_DN<1>")
	)
	(segment
		(start 189.185296 -212.466428)
		(end 188.35497 -212.466428)
		(width 0.18288)
		(layer "In11.Cu")
		(net "M_H_CPU1_SB_DQS_DN<1>")
	)
	(segment
		(start 169.789348 -214.178896)
		(end 168.124378 -213.489286)
		(width 0.18288)
		(layer "In11.Cu")
		(net "M_H_CPU1_SB_DQS_DN<1>")
	)
	(segment
		(start 147.519898 -224.8662)
		(end 147.519898 -225.78568)
		(width 0.18288)
		(layer "In11.Cu")
		(net "M_H_CPU1_SB_DQS_DN<1>")
	)
	(segment
		(start 125.555756 -232.856024)
		(end 125.544072 -232.84942)
		(width 0.088646)
		(layer "In11.Cu")
		(net "M_H_CPU1_SB_DQS_DN<1>")
	)
	(segment
		(start 158.576772 -212.699092)
		(end 158.198058 -213.077806)
		(width 0.18288)
		(layer "In11.Cu")
		(net "M_H_CPU1_SB_DQS_DN<1>")
	)
	(segment
		(start 202.374246 -218.8718)
		(end 201.87793 -218.375484)
		(width 0.18288)
		(layer "In11.Cu")
		(net "M_H_CPU1_SB_DQS_DN<1>")
	)
	(segment
		(start 179.108354 -212.526372)
		(end 178.605942 -212.526372)
		(width 0.18288)
		(layer "In11.Cu")
		(net "M_H_CPU1_SB_DQS_DN<1>")
	)
	(segment
		(start 139.681712 -231.933242)
		(end 139.577826 -232.037128)
		(width 0.088646)
		(layer "In11.Cu")
		(net "M_H_CPU1_SB_DQS_DN<1>")
	)
	(segment
		(start 177.832004 -213.30031)
		(end 177.367438 -213.30031)
		(width 0.18288)
		(layer "In11.Cu")
		(net "M_H_CPU1_SB_DQS_DN<1>")
	)
	(segment
		(start 172.987462 -213.891114)
		(end 172.527722 -213.891114)
		(width 0.18288)
		(layer "In11.Cu")
		(net "M_H_CPU1_SB_DQS_DN<1>")
	)
	(segment
		(start 138.404346 -232.903522)
		(end 137.95502 -232.903522)
		(width 0.088646)
		(layer "In11.Cu")
		(net "M_H_CPU1_SB_DQS_DN<1>")
	)
	(segment
		(start 142.244826 -231.060752)
		(end 140.163296 -231.060752)
		(width 0.18288)
		(layer "In11.Cu")
		(net "M_H_CPU1_SB_DQS_DN<1>")
	)
	(arc
		(start 137.202164 -232.852722)
		(mid 137.014966 -232.902865)
		(end 136.827768 -232.852722)
		(width 0.088646)
		(layer "In11.Cu")
		(net "M_H_CPU1_SB_DQS_DN<1>")
	)
	(arc
		(start 129.683764 -232.852722)
		(mid 129.496566 -232.902865)
		(end 129.309368 -232.852722)
		(width 0.088646)
		(layer "In11.Cu")
		(net "M_H_CPU1_SB_DQS_DN<1>")
	)
	(arc
		(start 132.128768 -232.852722)
		(mid 131.854569 -232.776887)
		(end 131.578096 -232.844086)
		(width 0.088646)
		(layer "In11.Cu")
		(net "M_H_CPU1_SB_DQS_DN<1>")
	)
	(arc
		(start 136.827768 -232.852722)
		(mid 136.545066 -232.776946)
		(end 136.262364 -232.852722)
		(width 0.088646)
		(layer "In11.Cu")
		(net "M_H_CPU1_SB_DQS_DN<1>")
	)
	(arc
		(start 124.044964 -232.852722)
		(mid 123.695763 -232.866274)
		(end 123.487434 -232.585768)
		(width 0.088646)
		(layer "In11.Cu")
		(net "M_H_CPU1_SB_DQS_DN<1>")
	)
	(arc
		(start 131.563364 -232.852722)
		(mid 131.376166 -232.902865)
		(end 131.188968 -232.852722)
		(width 0.088646)
		(layer "In11.Cu")
		(net "M_H_CPU1_SB_DQS_DN<1>")
	)
	(arc
		(start 127.429768 -232.852722)
		(mid 127.152955 -232.776852)
		(end 126.874524 -232.846626)
		(width 0.088646)
		(layer "In11.Cu")
		(net "M_H_CPU1_SB_DQS_DN<1>")
	)
	(arc
		(start 124.604272 -232.84942)
		(mid 124.324167 -232.776978)
		(end 124.044964 -232.852722)
		(width 0.088646)
		(layer "In11.Cu")
		(net "M_H_CPU1_SB_DQS_DN<1>")
	)
	(arc
		(start 132.503164 -232.852722)
		(mid 132.315966 -232.902865)
		(end 132.128768 -232.852722)
		(width 0.088646)
		(layer "In11.Cu")
		(net "M_H_CPU1_SB_DQS_DN<1>")
	)
	(arc
		(start 131.188968 -232.852722)
		(mid 130.914769 -232.776887)
		(end 130.638296 -232.844086)
		(width 0.088646)
		(layer "In11.Cu")
		(net "M_H_CPU1_SB_DQS_DN<1>")
	)
	(arc
		(start 130.623564 -232.852722)
		(mid 130.436366 -232.902865)
		(end 130.249168 -232.852722)
		(width 0.088646)
		(layer "In11.Cu")
		(net "M_H_CPU1_SB_DQS_DN<1>")
	)
	(arc
		(start 133.0579 -232.846626)
		(mid 132.779722 -232.776903)
		(end 132.503164 -232.852722)
		(width 0.088646)
		(layer "In11.Cu")
		(net "M_H_CPU1_SB_DQS_DN<1>")
	)
	(arc
		(start 133.997954 -232.846626)
		(mid 133.719522 -232.77678)
		(end 133.44271 -232.852722)
		(width 0.088646)
		(layer "In11.Cu")
		(net "M_H_CPU1_SB_DQS_DN<1>")
	)
	(arc
		(start 129.309368 -232.852722)
		(mid 129.035169 -232.776887)
		(end 128.758696 -232.844086)
		(width 0.088646)
		(layer "In11.Cu")
		(net "M_H_CPU1_SB_DQS_DN<1>")
	)
	(arc
		(start 136.262364 -232.852722)
		(mid 136.075166 -232.902865)
		(end 135.887968 -232.852722)
		(width 0.088646)
		(layer "In11.Cu")
		(net "M_H_CPU1_SB_DQS_DN<1>")
	)
	(arc
		(start 130.249168 -232.852722)
		(mid 129.974969 -232.776887)
		(end 129.698496 -232.844086)
		(width 0.088646)
		(layer "In11.Cu")
		(net "M_H_CPU1_SB_DQS_DN<1>")
	)
	(arc
		(start 133.44271 -232.852722)
		(mid 133.255512 -232.902865)
		(end 133.068314 -232.852722)
		(width 0.088646)
		(layer "In11.Cu")
		(net "M_H_CPU1_SB_DQS_DN<1>")
	)
	(arc
		(start 128.743964 -232.852722)
		(mid 128.556766 -232.902865)
		(end 128.369568 -232.852722)
		(width 0.088646)
		(layer "In11.Cu")
		(net "M_H_CPU1_SB_DQS_DN<1>")
	)
	(arc
		(start 128.369568 -232.852722)
		(mid 128.095369 -232.776887)
		(end 127.818896 -232.844086)
		(width 0.088646)
		(layer "In11.Cu")
		(net "M_H_CPU1_SB_DQS_DN<1>")
	)
	(arc
		(start 126.86411 -232.852722)
		(mid 126.676912 -232.902865)
		(end 126.489714 -232.852722)
		(width 0.088646)
		(layer "In11.Cu")
		(net "M_H_CPU1_SB_DQS_DN<1>")
	)
	(arc
		(start 134.382764 -232.852722)
		(mid 134.195566 -232.902865)
		(end 134.008368 -232.852722)
		(width 0.088646)
		(layer "In11.Cu")
		(net "M_H_CPU1_SB_DQS_DN<1>")
	)
	(arc
		(start 137.767568 -232.852722)
		(mid 137.484866 -232.776946)
		(end 137.202164 -232.852722)
		(width 0.088646)
		(layer "In11.Cu")
		(net "M_H_CPU1_SB_DQS_DN<1>")
	)
	(arc
		(start 125.924564 -232.852722)
		(mid 125.74061 -232.902851)
		(end 125.555756 -232.856024)
		(width 0.088646)
		(layer "In11.Cu")
		(net "M_H_CPU1_SB_DQS_DN<1>")
	)
	(arc
		(start 135.887968 -232.852722)
		(mid 135.605266 -232.776946)
		(end 135.322564 -232.852722)
		(width 0.088646)
		(layer "In11.Cu")
		(net "M_H_CPU1_SB_DQS_DN<1>")
	)
	(arc
		(start 125.544072 -232.84942)
		(mid 125.263967 -232.776978)
		(end 124.984764 -232.852722)
		(width 0.088646)
		(layer "In11.Cu")
		(net "M_H_CPU1_SB_DQS_DN<1>")
	)
	(arc
		(start 135.322564 -232.852722)
		(mid 135.135366 -232.902865)
		(end 134.948168 -232.852722)
		(width 0.088646)
		(layer "In11.Cu")
		(net "M_H_CPU1_SB_DQS_DN<1>")
	)
	(arc
		(start 137.95502 -232.903522)
		(mid 137.858092 -232.890571)
		(end 137.767822 -232.852976)
		(width 0.088646)
		(layer "In11.Cu")
		(net "M_H_CPU1_SB_DQS_DN<1>")
	)
	(arc
		(start 124.984764 -232.852722)
		(mid 124.80081 -232.902851)
		(end 124.615956 -232.856024)
		(width 0.088646)
		(layer "In11.Cu")
		(net "M_H_CPU1_SB_DQS_DN<1>")
	)
	(arc
		(start 134.948168 -232.852722)
		(mid 134.665466 -232.776946)
		(end 134.382764 -232.852722)
		(width 0.088646)
		(layer "In11.Cu")
		(net "M_H_CPU1_SB_DQS_DN<1>")
	)
	(arc
		(start 126.495556 -232.856024)
		(mid 126.210511 -232.777018)
		(end 125.924564 -232.852722)
		(width 0.088646)
		(layer "In11.Cu")
		(net "M_H_CPU1_SB_DQS_DN<1>")
	)
	(arc
		(start 127.804164 -232.852722)
		(mid 127.616966 -232.902865)
		(end 127.429768 -232.852722)
		(width 0.088646)
		(layer "In11.Cu")
		(net "M_H_CPU1_SB_DQS_DN<1>")
	)
	(segment
		(start 206.056738 -228.612954)
		(end 206.578454 -228.612954)
		(width 0.20066)
		(layer "F.Cu")
		(net "M_H_CPU1_SB_DQS_DN<0>")
	)
	(segment
		(start 206.578454 -228.612954)
		(end 206.849726 -228.341682)
		(width 0.20066)
		(layer "F.Cu")
		(net "M_H_CPU1_SB_DQS_DN<0>")
	)
	(segment
		(start 204.624686 -227.91674)
		(end 204.906372 -228.198426)
		(width 0.20066)
		(layer "F.Cu")
		(net "M_H_CPU1_SB_DQS_DN<0>")
	)
	(segment
		(start 210.790028 -228.157278)
		(end 211.030566 -227.91674)
		(width 0.20066)
		(layer "F.Cu")
		(net "M_H_CPU1_SB_DQS_DN<0>")
	)
	(segment
		(start 206.849726 -228.341682)
		(end 206.9973 -228.341682)
		(width 0.20066)
		(layer "F.Cu")
		(net "M_H_CPU1_SB_DQS_DN<0>")
	)
	(segment
		(start 202.971146 -227.91674)
		(end 204.076046 -227.91674)
		(width 0.20066)
		(layer "F.Cu")
		(net "M_H_CPU1_SB_DQS_DN<0>")
	)
	(segment
		(start 209.51063 -228.336348)
		(end 209.742024 -228.567742)
		(width 0.20066)
		(layer "F.Cu")
		(net "M_H_CPU1_SB_DQS_DN<0>")
	)
	(segment
		(start 210.047078 -228.567742)
		(end 210.457542 -228.157278)
		(width 0.20066)
		(layer "F.Cu")
		(net "M_H_CPU1_SB_DQS_DN<0>")
	)
	(segment
		(start 204.906372 -228.198426)
		(end 205.64221 -228.198426)
		(width 0.20066)
		(layer "F.Cu")
		(net "M_H_CPU1_SB_DQS_DN<0>")
	)
	(segment
		(start 209.742024 -228.567742)
		(end 210.047078 -228.567742)
		(width 0.20066)
		(layer "F.Cu")
		(net "M_H_CPU1_SB_DQS_DN<0>")
	)
	(segment
		(start 206.9973 -228.341682)
		(end 207.001618 -228.341682)
		(width 0.101854)
		(layer "F.Cu")
		(net "M_H_CPU1_SB_DQS_DN<0>")
	)
	(segment
		(start 210.457542 -228.157278)
		(end 210.790028 -228.157278)
		(width 0.20066)
		(layer "F.Cu")
		(net "M_H_CPU1_SB_DQS_DN<0>")
	)
	(segment
		(start 207.001618 -228.341682)
		(end 209.181192 -228.341682)
		(width 0.1016)
		(layer "F.Cu")
		(net "M_H_CPU1_SB_DQS_DN<0>")
	)
	(segment
		(start 205.64221 -228.198426)
		(end 206.056738 -228.612954)
		(width 0.20066)
		(layer "F.Cu")
		(net "M_H_CPU1_SB_DQS_DN<0>")
	)
	(segment
		(start 123.857512 -237.947454)
		(end 123.857512 -237.411768)
		(width 0.20066)
		(layer "F.Cu")
		(net "M_H_CPU1_SB_DQS_DN<0>")
	)
	(segment
		(start 204.076046 -227.91674)
		(end 204.624686 -227.91674)
		(width 0.20066)
		(layer "F.Cu")
		(net "M_H_CPU1_SB_DQS_DN<0>")
	)
	(segment
		(start 211.030566 -227.91674)
		(end 211.619846 -227.91674)
		(width 0.20066)
		(layer "F.Cu")
		(net "M_H_CPU1_SB_DQS_DN<0>")
	)
	(segment
		(start 123.857512 -237.411768)
		(end 123.857766 -237.411514)
		(width 0.20066)
		(layer "F.Cu")
		(net "M_H_CPU1_SB_DQS_DN<0>")
	)
	(segment
		(start 209.181192 -228.341682)
		(end 209.186526 -228.336348)
		(width 0.1016)
		(layer "F.Cu")
		(net "M_H_CPU1_SB_DQS_DN<0>")
	)
	(segment
		(start 209.186526 -228.336348)
		(end 209.51063 -228.336348)
		(width 0.20066)
		(layer "F.Cu")
		(net "M_H_CPU1_SB_DQS_DN<0>")
	)
	(segment
		(start 123.670568 -237.736126)
		(end 123.546362 -237.665006)
		(width 0.088646)
		(layer "In11.Cu")
		(net "M_H_CPU1_SB_DQS_DN<0>")
	)
	(segment
		(start 145.028666 -237.135924)
		(end 141.103096 -237.135924)
		(width 0.18288)
		(layer "In11.Cu")
		(net "M_H_CPU1_SB_DQS_DN<0>")
	)
	(segment
		(start 197.53199 -227.76942)
		(end 195.815458 -226.052888)
		(width 0.18288)
		(layer "In11.Cu")
		(net "M_H_CPU1_SB_DQS_DN<0>")
	)
	(segment
		(start 176.352962 -224.405444)
		(end 174.776892 -224.405444)
		(width 0.18288)
		(layer "In11.Cu")
		(net "M_H_CPU1_SB_DQS_DN<0>")
	)
	(segment
		(start 192.191894 -224.090992)
		(end 191.785494 -224.090992)
		(width 0.18288)
		(layer "In11.Cu")
		(net "M_H_CPU1_SB_DQS_DN<0>")
	)
	(segment
		(start 126.879096 -237.727236)
		(end 126.864364 -237.735872)
		(width 0.088646)
		(layer "In11.Cu")
		(net "M_H_CPU1_SB_DQS_DN<0>")
	)
	(segment
		(start 158.162752 -226.916234)
		(end 157.888432 -226.641914)
		(width 0.18288)
		(layer "In11.Cu")
		(net "M_H_CPU1_SB_DQS_DN<0>")
	)
	(segment
		(start 179.41163 -223.743266)
		(end 178.430174 -223.743266)
		(width 0.18288)
		(layer "In11.Cu")
		(net "M_H_CPU1_SB_DQS_DN<0>")
	)
	(segment
		(start 157.236668 -226.905058)
		(end 155.259532 -226.905058)
		(width 0.18288)
		(layer "In11.Cu")
		(net "M_H_CPU1_SB_DQS_DN<0>")
	)
	(segment
		(start 178.430174 -223.743266)
		(end 177.807112 -224.366328)
		(width 0.18288)
		(layer "In11.Cu")
		(net "M_H_CPU1_SB_DQS_DN<0>")
	)
	(segment
		(start 139.9667 -237.659926)
		(end 138.424412 -237.659926)
		(width 0.088646)
		(layer "In11.Cu")
		(net "M_H_CPU1_SB_DQS_DN<0>")
	)
	(segment
		(start 130.638296 -237.72749)
		(end 130.623564 -237.736126)
		(width 0.088646)
		(layer "In11.Cu")
		(net "M_H_CPU1_SB_DQS_DN<0>")
	)
	(segment
		(start 176.667414 -224.090992)
		(end 176.352962 -224.405444)
		(width 0.18288)
		(layer "In11.Cu")
		(net "M_H_CPU1_SB_DQS_DN<0>")
	)
	(segment
		(start 129.698496 -237.72749)
		(end 129.683764 -237.736126)
		(width 0.088646)
		(layer "In11.Cu")
		(net "M_H_CPU1_SB_DQS_DN<0>")
	)
	(segment
		(start 179.84343 -224.175066)
		(end 179.41163 -223.743266)
		(width 0.18288)
		(layer "In11.Cu")
		(net "M_H_CPU1_SB_DQS_DN<0>")
	)
	(segment
		(start 191.056768 -224.392744)
		(end 190.763144 -224.09912)
		(width 0.18288)
		(layer "In11.Cu")
		(net "M_H_CPU1_SB_DQS_DN<0>")
	)
	(segment
		(start 188.352938 -223.516444)
		(end 188.077602 -223.241108)
		(width 0.18288)
		(layer "In11.Cu")
		(net "M_H_CPU1_SB_DQS_DN<0>")
	)
	(segment
		(start 127.429768 -237.736126)
		(end 127.429768 -237.735872)
		(width 0.088646)
		(layer "In11.Cu")
		(net "M_H_CPU1_SB_DQS_DN<0>")
	)
	(segment
		(start 157.888432 -226.641914)
		(end 157.499812 -226.641914)
		(width 0.18288)
		(layer "In11.Cu")
		(net "M_H_CPU1_SB_DQS_DN<0>")
	)
	(segment
		(start 189.283594 -223.516444)
		(end 188.352938 -223.516444)
		(width 0.18288)
		(layer "In11.Cu")
		(net "M_H_CPU1_SB_DQS_DN<0>")
	)
	(segment
		(start 191.785494 -224.090992)
		(end 191.483742 -224.392744)
		(width 0.18288)
		(layer "In11.Cu")
		(net "M_H_CPU1_SB_DQS_DN<0>")
	)
	(segment
		(start 172.581062 -224.94113)
		(end 172.303694 -225.218498)
		(width 0.18288)
		(layer "In11.Cu")
		(net "M_H_CPU1_SB_DQS_DN<0>")
	)
	(segment
		(start 163.684966 -225.394266)
		(end 163.012882 -226.06635)
		(width 0.18288)
		(layer "In11.Cu")
		(net "M_H_CPU1_SB_DQS_DN<0>")
	)
	(segment
		(start 140.431012 -237.195614)
		(end 139.9667 -237.659926)
		(width 0.088646)
		(layer "In11.Cu")
		(net "M_H_CPU1_SB_DQS_DN<0>")
	)
	(segment
		(start 164.625782 -225.394266)
		(end 163.684966 -225.394266)
		(width 0.18288)
		(layer "In11.Cu")
		(net "M_H_CPU1_SB_DQS_DN<0>")
	)
	(segment
		(start 193.3448 -224.366328)
		(end 192.46723 -224.366328)
		(width 0.18288)
		(layer "In11.Cu")
		(net "M_H_CPU1_SB_DQS_DN<0>")
	)
	(segment
		(start 159.642556 -226.054412)
		(end 158.780734 -226.916234)
		(width 0.18288)
		(layer "In11.Cu")
		(net "M_H_CPU1_SB_DQS_DN<0>")
	)
	(segment
		(start 183.030876 -224.175066)
		(end 179.84343 -224.175066)
		(width 0.18288)
		(layer "In11.Cu")
		(net "M_H_CPU1_SB_DQS_DN<0>")
	)
	(segment
		(start 123.857512 -237.411768)
		(end 123.857766 -237.411514)
		(width 0.088646)
		(layer "In11.Cu")
		(net "M_H_CPU1_SB_DQS_DN<0>")
	)
	(segment
		(start 201.968354 -227.76942)
		(end 197.53199 -227.76942)
		(width 0.18288)
		(layer "In11.Cu")
		(net "M_H_CPU1_SB_DQS_DN<0>")
	)
	(segment
		(start 162.316922 -226.06635)
		(end 162.041586 -225.791014)
		(width 0.18288)
		(layer "In11.Cu")
		(net "M_H_CPU1_SB_DQS_DN<0>")
	)
	(segment
		(start 191.483742 -224.392744)
		(end 191.056768 -224.392744)
		(width 0.18288)
		(layer "In11.Cu")
		(net "M_H_CPU1_SB_DQS_DN<0>")
	)
	(segment
		(start 173.268894 -225.216466)
		(end 172.993558 -224.94113)
		(width 0.18288)
		(layer "In11.Cu")
		(net "M_H_CPU1_SB_DQS_DN<0>")
	)
	(segment
		(start 123.468892 -237.411768)
		(end 123.857512 -237.411768)
		(width 0.088646)
		(layer "In11.Cu")
		(net "M_H_CPU1_SB_DQS_DN<0>")
	)
	(segment
		(start 189.86627 -224.09912)
		(end 189.283594 -223.516444)
		(width 0.18288)
		(layer "In11.Cu")
		(net "M_H_CPU1_SB_DQS_DN<0>")
	)
	(segment
		(start 194.093338 -225.114866)
		(end 193.3448 -224.366328)
		(width 0.18288)
		(layer "In11.Cu")
		(net "M_H_CPU1_SB_DQS_DN<0>")
	)
	(segment
		(start 195.815458 -226.052888)
		(end 195.332858 -226.052888)
		(width 0.18288)
		(layer "In11.Cu")
		(net "M_H_CPU1_SB_DQS_DN<0>")
	)
	(segment
		(start 163.012882 -226.06635)
		(end 162.316922 -226.06635)
		(width 0.18288)
		(layer "In11.Cu")
		(net "M_H_CPU1_SB_DQS_DN<0>")
	)
	(segment
		(start 141.043406 -237.195614)
		(end 140.431012 -237.195614)
		(width 0.088646)
		(layer "In11.Cu")
		(net "M_H_CPU1_SB_DQS_DN<0>")
	)
	(segment
		(start 187.68949 -223.241108)
		(end 187.429902 -223.500696)
		(width 0.18288)
		(layer "In11.Cu")
		(net "M_H_CPU1_SB_DQS_DN<0>")
	)
	(segment
		(start 161.577782 -225.791014)
		(end 161.314384 -226.054412)
		(width 0.18288)
		(layer "In11.Cu")
		(net "M_H_CPU1_SB_DQS_DN<0>")
	)
	(segment
		(start 194.394836 -225.114866)
		(end 194.093338 -225.114866)
		(width 0.18288)
		(layer "In11.Cu")
		(net "M_H_CPU1_SB_DQS_DN<0>")
	)
	(segment
		(start 138.142218 -237.73638)
		(end 138.141964 -237.735872)
		(width 0.088646)
		(layer "In11.Cu")
		(net "M_H_CPU1_SB_DQS_DN<0>")
	)
	(segment
		(start 173.96587 -225.216466)
		(end 173.268894 -225.216466)
		(width 0.18288)
		(layer "In11.Cu")
		(net "M_H_CPU1_SB_DQS_DN<0>")
	)
	(segment
		(start 177.106326 -224.090992)
		(end 176.667414 -224.090992)
		(width 0.18288)
		(layer "In11.Cu")
		(net "M_H_CPU1_SB_DQS_DN<0>")
	)
	(segment
		(start 202.38974 -228.190806)
		(end 201.968354 -227.76942)
		(width 0.18288)
		(layer "In11.Cu")
		(net "M_H_CPU1_SB_DQS_DN<0>")
	)
	(segment
		(start 177.381662 -224.366328)
		(end 177.106326 -224.090992)
		(width 0.18288)
		(layer "In11.Cu")
		(net "M_H_CPU1_SB_DQS_DN<0>")
	)
	(segment
		(start 192.46723 -224.366328)
		(end 192.191894 -224.090992)
		(width 0.18288)
		(layer "In11.Cu")
		(net "M_H_CPU1_SB_DQS_DN<0>")
	)
	(segment
		(start 161.314384 -226.054412)
		(end 159.642556 -226.054412)
		(width 0.18288)
		(layer "In11.Cu")
		(net "M_H_CPU1_SB_DQS_DN<0>")
	)
	(segment
		(start 190.763144 -224.09912)
		(end 189.86627 -224.09912)
		(width 0.18288)
		(layer "In11.Cu")
		(net "M_H_CPU1_SB_DQS_DN<0>")
	)
	(segment
		(start 195.332858 -226.052888)
		(end 194.394836 -225.114866)
		(width 0.18288)
		(layer "In11.Cu")
		(net "M_H_CPU1_SB_DQS_DN<0>")
	)
	(segment
		(start 165.086284 -225.854768)
		(end 164.625782 -225.394266)
		(width 0.18288)
		(layer "In11.Cu")
		(net "M_H_CPU1_SB_DQS_DN<0>")
	)
	(segment
		(start 124.059696 -237.72749)
		(end 124.044964 -237.736126)
		(width 0.088646)
		(layer "In11.Cu")
		(net "M_H_CPU1_SB_DQS_DN<0>")
	)
	(segment
		(start 168.095168 -225.854768)
		(end 165.086284 -225.854768)
		(width 0.18288)
		(layer "In11.Cu")
		(net "M_H_CPU1_SB_DQS_DN<0>")
	)
	(segment
		(start 157.499812 -226.641914)
		(end 157.236668 -226.905058)
		(width 0.18288)
		(layer "In11.Cu")
		(net "M_H_CPU1_SB_DQS_DN<0>")
	)
	(segment
		(start 187.429902 -223.500696)
		(end 183.705246 -223.500696)
		(width 0.18288)
		(layer "In11.Cu")
		(net "M_H_CPU1_SB_DQS_DN<0>")
	)
	(segment
		(start 172.993558 -224.94113)
		(end 172.581062 -224.94113)
		(width 0.18288)
		(layer "In11.Cu")
		(net "M_H_CPU1_SB_DQS_DN<0>")
	)
	(segment
		(start 124.999496 -237.72749)
		(end 124.984764 -237.736126)
		(width 0.088646)
		(layer "In11.Cu")
		(net "M_H_CPU1_SB_DQS_DN<0>")
	)
	(segment
		(start 202.69708 -228.190806)
		(end 202.38974 -228.190806)
		(width 0.18288)
		(layer "In11.Cu")
		(net "M_H_CPU1_SB_DQS_DN<0>")
	)
	(segment
		(start 141.103096 -237.135924)
		(end 141.043406 -237.195614)
		(width 0.088646)
		(layer "In11.Cu")
		(net "M_H_CPU1_SB_DQS_DN<0>")
	)
	(segment
		(start 131.578096 -237.72749)
		(end 131.563364 -237.736126)
		(width 0.088646)
		(layer "In11.Cu")
		(net "M_H_CPU1_SB_DQS_DN<0>")
	)
	(segment
		(start 128.758696 -237.72749)
		(end 128.743964 -237.736126)
		(width 0.088646)
		(layer "In11.Cu")
		(net "M_H_CPU1_SB_DQS_DN<0>")
	)
	(segment
		(start 202.971146 -227.91674)
		(end 202.69708 -228.190806)
		(width 0.18288)
		(layer "In11.Cu")
		(net "M_H_CPU1_SB_DQS_DN<0>")
	)
	(segment
		(start 174.776892 -224.405444)
		(end 173.96587 -225.216466)
		(width 0.18288)
		(layer "In11.Cu")
		(net "M_H_CPU1_SB_DQS_DN<0>")
	)
	(segment
		(start 183.705246 -223.500696)
		(end 183.030876 -224.175066)
		(width 0.18288)
		(layer "In11.Cu")
		(net "M_H_CPU1_SB_DQS_DN<0>")
	)
	(segment
		(start 135.322564 -237.735872)
		(end 135.322564 -237.736126)
		(width 0.088646)
		(layer "In11.Cu")
		(net "M_H_CPU1_SB_DQS_DN<0>")
	)
	(segment
		(start 126.489968 -237.735872)
		(end 126.4793 -237.73003)
		(width 0.088646)
		(layer "In11.Cu")
		(net "M_H_CPU1_SB_DQS_DN<0>")
	)
	(segment
		(start 168.731438 -225.218498)
		(end 168.095168 -225.854768)
		(width 0.18288)
		(layer "In11.Cu")
		(net "M_H_CPU1_SB_DQS_DN<0>")
	)
	(segment
		(start 134.008368 -237.736126)
		(end 133.997954 -237.73003)
		(width 0.088646)
		(layer "In11.Cu")
		(net "M_H_CPU1_SB_DQS_DN<0>")
	)
	(segment
		(start 127.818896 -237.72749)
		(end 127.804164 -237.736126)
		(width 0.088646)
		(layer "In11.Cu")
		(net "M_H_CPU1_SB_DQS_DN<0>")
	)
	(segment
		(start 188.077602 -223.241108)
		(end 187.68949 -223.241108)
		(width 0.18288)
		(layer "In11.Cu")
		(net "M_H_CPU1_SB_DQS_DN<0>")
	)
	(segment
		(start 133.068314 -237.736126)
		(end 133.0579 -237.73003)
		(width 0.088646)
		(layer "In11.Cu")
		(net "M_H_CPU1_SB_DQS_DN<0>")
	)
	(segment
		(start 162.041586 -225.791014)
		(end 161.577782 -225.791014)
		(width 0.18288)
		(layer "In11.Cu")
		(net "M_H_CPU1_SB_DQS_DN<0>")
	)
	(segment
		(start 155.259532 -226.905058)
		(end 145.028666 -237.135924)
		(width 0.18288)
		(layer "In11.Cu")
		(net "M_H_CPU1_SB_DQS_DN<0>")
	)
	(segment
		(start 172.303694 -225.218498)
		(end 168.731438 -225.218498)
		(width 0.18288)
		(layer "In11.Cu")
		(net "M_H_CPU1_SB_DQS_DN<0>")
	)
	(segment
		(start 177.807112 -224.366328)
		(end 177.381662 -224.366328)
		(width 0.18288)
		(layer "In11.Cu")
		(net "M_H_CPU1_SB_DQS_DN<0>")
	)
	(segment
		(start 123.411488 -237.469172)
		(end 123.468892 -237.411768)
		(width 0.088646)
		(layer "In11.Cu")
		(net "M_H_CPU1_SB_DQS_DN<0>")
	)
	(segment
		(start 158.780734 -226.916234)
		(end 158.162752 -226.916234)
		(width 0.18288)
		(layer "In11.Cu")
		(net "M_H_CPU1_SB_DQS_DN<0>")
	)
	(arc
		(start 126.4793 -237.73003)
		(mid 126.201122 -237.660307)
		(end 125.924564 -237.736126)
		(width 0.088646)
		(layer "In11.Cu")
		(net "M_H_CPU1_SB_DQS_DN<0>")
	)
	(arc
		(start 131.563364 -237.736126)
		(mid 131.376166 -237.786269)
		(end 131.188968 -237.736126)
		(width 0.088646)
		(layer "In11.Cu")
		(net "M_H_CPU1_SB_DQS_DN<0>")
	)
	(arc
		(start 128.369568 -237.736126)
		(mid 128.095369 -237.660291)
		(end 127.818896 -237.72749)
		(width 0.088646)
		(layer "In11.Cu")
		(net "M_H_CPU1_SB_DQS_DN<0>")
	)
	(arc
		(start 130.623564 -237.736126)
		(mid 130.436366 -237.786269)
		(end 130.249168 -237.736126)
		(width 0.088646)
		(layer "In11.Cu")
		(net "M_H_CPU1_SB_DQS_DN<0>")
	)
	(arc
		(start 137.767568 -237.735872)
		(mid 137.484866 -237.66013)
		(end 137.202164 -237.735872)
		(width 0.088646)
		(layer "In11.Cu")
		(net "M_H_CPU1_SB_DQS_DN<0>")
	)
	(arc
		(start 138.141964 -237.735872)
		(mid 137.954766 -237.786015)
		(end 137.767568 -237.735872)
		(width 0.088646)
		(layer "In11.Cu")
		(net "M_H_CPU1_SB_DQS_DN<0>")
	)
	(arc
		(start 138.424412 -237.659926)
		(mid 138.278293 -237.679609)
		(end 138.142218 -237.73638)
		(width 0.088646)
		(layer "In11.Cu")
		(net "M_H_CPU1_SB_DQS_DN<0>")
	)
	(arc
		(start 129.309368 -237.736126)
		(mid 129.035169 -237.660291)
		(end 128.758696 -237.72749)
		(width 0.088646)
		(layer "In11.Cu")
		(net "M_H_CPU1_SB_DQS_DN<0>")
	)
	(arc
		(start 124.984764 -237.736126)
		(mid 124.797566 -237.786269)
		(end 124.610368 -237.736126)
		(width 0.088646)
		(layer "In11.Cu")
		(net "M_H_CPU1_SB_DQS_DN<0>")
	)
	(arc
		(start 127.804164 -237.736126)
		(mid 127.616966 -237.786269)
		(end 127.429768 -237.736126)
		(width 0.088646)
		(layer "In11.Cu")
		(net "M_H_CPU1_SB_DQS_DN<0>")
	)
	(arc
		(start 135.322564 -237.736126)
		(mid 135.135366 -237.786269)
		(end 134.948168 -237.736126)
		(width 0.088646)
		(layer "In11.Cu")
		(net "M_H_CPU1_SB_DQS_DN<0>")
	)
	(arc
		(start 133.997954 -237.73003)
		(mid 133.719522 -237.660184)
		(end 133.44271 -237.736126)
		(width 0.088646)
		(layer "In11.Cu")
		(net "M_H_CPU1_SB_DQS_DN<0>")
	)
	(arc
		(start 137.202164 -237.735872)
		(mid 137.014966 -237.786015)
		(end 136.827768 -237.735872)
		(width 0.088646)
		(layer "In11.Cu")
		(net "M_H_CPU1_SB_DQS_DN<0>")
	)
	(arc
		(start 125.924564 -237.736126)
		(mid 125.737366 -237.786269)
		(end 125.550168 -237.736126)
		(width 0.088646)
		(layer "In11.Cu")
		(net "M_H_CPU1_SB_DQS_DN<0>")
	)
	(arc
		(start 124.610368 -237.736126)
		(mid 124.336169 -237.660291)
		(end 124.059696 -237.72749)
		(width 0.088646)
		(layer "In11.Cu")
		(net "M_H_CPU1_SB_DQS_DN<0>")
	)
	(arc
		(start 136.262364 -237.735872)
		(mid 136.075166 -237.786015)
		(end 135.887968 -237.735872)
		(width 0.088646)
		(layer "In11.Cu")
		(net "M_H_CPU1_SB_DQS_DN<0>")
	)
	(arc
		(start 128.743964 -237.736126)
		(mid 128.556766 -237.786269)
		(end 128.369568 -237.736126)
		(width 0.088646)
		(layer "In11.Cu")
		(net "M_H_CPU1_SB_DQS_DN<0>")
	)
	(arc
		(start 135.887968 -237.735872)
		(mid 135.605266 -237.66013)
		(end 135.322564 -237.735872)
		(width 0.088646)
		(layer "In11.Cu")
		(net "M_H_CPU1_SB_DQS_DN<0>")
	)
	(arc
		(start 123.546362 -237.665006)
		(mid 123.456484 -237.582531)
		(end 123.411488 -237.469172)
		(width 0.088646)
		(layer "In11.Cu")
		(net "M_H_CPU1_SB_DQS_DN<0>")
	)
	(arc
		(start 136.827768 -237.735872)
		(mid 136.545066 -237.66013)
		(end 136.262364 -237.735872)
		(width 0.088646)
		(layer "In11.Cu")
		(net "M_H_CPU1_SB_DQS_DN<0>")
	)
	(arc
		(start 133.0579 -237.73003)
		(mid 132.779722 -237.660307)
		(end 132.503164 -237.736126)
		(width 0.088646)
		(layer "In11.Cu")
		(net "M_H_CPU1_SB_DQS_DN<0>")
	)
	(arc
		(start 127.429768 -237.735872)
		(mid 127.155539 -237.659947)
		(end 126.879096 -237.727236)
		(width 0.088646)
		(layer "In11.Cu")
		(net "M_H_CPU1_SB_DQS_DN<0>")
	)
	(arc
		(start 134.948168 -237.736126)
		(mid 134.665466 -237.66035)
		(end 134.382764 -237.736126)
		(width 0.088646)
		(layer "In11.Cu")
		(net "M_H_CPU1_SB_DQS_DN<0>")
	)
	(arc
		(start 132.503164 -237.736126)
		(mid 132.315966 -237.786269)
		(end 132.128768 -237.736126)
		(width 0.088646)
		(layer "In11.Cu")
		(net "M_H_CPU1_SB_DQS_DN<0>")
	)
	(arc
		(start 125.550168 -237.736126)
		(mid 125.275969 -237.660291)
		(end 124.999496 -237.72749)
		(width 0.088646)
		(layer "In11.Cu")
		(net "M_H_CPU1_SB_DQS_DN<0>")
	)
	(arc
		(start 130.249168 -237.736126)
		(mid 129.974969 -237.660291)
		(end 129.698496 -237.72749)
		(width 0.088646)
		(layer "In11.Cu")
		(net "M_H_CPU1_SB_DQS_DN<0>")
	)
	(arc
		(start 132.128768 -237.736126)
		(mid 131.854569 -237.660291)
		(end 131.578096 -237.72749)
		(width 0.088646)
		(layer "In11.Cu")
		(net "M_H_CPU1_SB_DQS_DN<0>")
	)
	(arc
		(start 129.683764 -237.736126)
		(mid 129.496566 -237.786269)
		(end 129.309368 -237.736126)
		(width 0.088646)
		(layer "In11.Cu")
		(net "M_H_CPU1_SB_DQS_DN<0>")
	)
	(arc
		(start 124.044964 -237.736126)
		(mid 123.857766 -237.786269)
		(end 123.670568 -237.736126)
		(width 0.088646)
		(layer "In11.Cu")
		(net "M_H_CPU1_SB_DQS_DN<0>")
	)
	(arc
		(start 133.44271 -237.736126)
		(mid 133.255512 -237.786269)
		(end 133.068314 -237.736126)
		(width 0.088646)
		(layer "In11.Cu")
		(net "M_H_CPU1_SB_DQS_DN<0>")
	)
	(arc
		(start 131.188968 -237.736126)
		(mid 130.914769 -237.660291)
		(end 130.638296 -237.72749)
		(width 0.088646)
		(layer "In11.Cu")
		(net "M_H_CPU1_SB_DQS_DN<0>")
	)
	(arc
		(start 134.382764 -237.736126)
		(mid 134.195566 -237.786269)
		(end 134.008368 -237.736126)
		(width 0.088646)
		(layer "In11.Cu")
		(net "M_H_CPU1_SB_DQS_DN<0>")
	)
	(arc
		(start 126.864364 -237.735872)
		(mid 126.677166 -237.786015)
		(end 126.489968 -237.735872)
		(width 0.088646)
		(layer "In11.Cu")
		(net "M_H_CPU1_SB_DQS_DN<0>")
	)
	(segment
		(start 206.991458 -220.69171)
		(end 206.971392 -220.69171)
		(width 0.101854)
		(layer "F.Cu")
		(net "M_H_CPU1_SB_DQ<9>")
	)
	(segment
		(start 209.186526 -220.68536)
		(end 209.180176 -220.69171)
		(width 0.1016)
		(layer "F.Cu")
		(net "M_H_CPU1_SB_DQ<9>")
	)
	(segment
		(start 211.619846 -221.116652)
		(end 211.619592 -221.116906)
		(width 0.20066)
		(layer "F.Cu")
		(net "M_H_CPU1_SB_DQ<9>")
	)
	(segment
		(start 206.508604 -220.80982)
		(end 206.508604 -221.177358)
		(width 0.20066)
		(layer "F.Cu")
		(net "M_H_CPU1_SB_DQ<9>")
	)
	(segment
		(start 205.596744 -221.116652)
		(end 204.076046 -221.116652)
		(width 0.20066)
		(layer "F.Cu")
		(net "M_H_CPU1_SB_DQ<9>")
	)
	(segment
		(start 209.596482 -220.68536)
		(end 209.186526 -220.68536)
		(width 0.20066)
		(layer "F.Cu")
		(net "M_H_CPU1_SB_DQ<9>")
	)
	(segment
		(start 206.971392 -220.69171)
		(end 206.626714 -220.69171)
		(width 0.20066)
		(layer "F.Cu")
		(net "M_H_CPU1_SB_DQ<9>")
	)
	(segment
		(start 210.028028 -221.116906)
		(end 209.596482 -220.68536)
		(width 0.20066)
		(layer "F.Cu")
		(net "M_H_CPU1_SB_DQ<9>")
	)
	(segment
		(start 206.508604 -221.177358)
		(end 206.320644 -221.365318)
		(width 0.20066)
		(layer "F.Cu")
		(net "M_H_CPU1_SB_DQ<9>")
	)
	(segment
		(start 209.180176 -220.69171)
		(end 206.991458 -220.69171)
		(width 0.1016)
		(layer "F.Cu")
		(net "M_H_CPU1_SB_DQ<9>")
	)
	(segment
		(start 206.320644 -221.365318)
		(end 205.84541 -221.365318)
		(width 0.20066)
		(layer "F.Cu")
		(net "M_H_CPU1_SB_DQ<9>")
	)
	(segment
		(start 204.076046 -221.116652)
		(end 202.971146 -221.116652)
		(width 0.20066)
		(layer "F.Cu")
		(net "M_H_CPU1_SB_DQ<9>")
	)
	(segment
		(start 206.626714 -220.69171)
		(end 206.508604 -220.80982)
		(width 0.20066)
		(layer "F.Cu")
		(net "M_H_CPU1_SB_DQ<9>")
	)
	(segment
		(start 123.387866 -233.87812)
		(end 123.387612 -233.877866)
		(width 0.20066)
		(layer "F.Cu")
		(net "M_H_CPU1_SB_DQ<9>")
	)
	(segment
		(start 123.387612 -233.877866)
		(end 123.387612 -233.34218)
		(width 0.20066)
		(layer "F.Cu")
		(net "M_H_CPU1_SB_DQ<9>")
	)
	(segment
		(start 205.84541 -221.365318)
		(end 205.596744 -221.116652)
		(width 0.20066)
		(layer "F.Cu")
		(net "M_H_CPU1_SB_DQ<9>")
	)
	(segment
		(start 211.619592 -221.116906)
		(end 210.028028 -221.116906)
		(width 0.20066)
		(layer "F.Cu")
		(net "M_H_CPU1_SB_DQ<9>")
	)
	(segment
		(start 159.648144 -215.964516)
		(end 159.455104 -216.157556)
		(width 0.18288)
		(layer "In11.Cu")
		(net "M_H_CPU1_SB_DQ<9>")
	)
	(segment
		(start 186.111642 -214.605362)
		(end 185.918602 -214.798402)
		(width 0.18288)
		(layer "In11.Cu")
		(net "M_H_CPU1_SB_DQ<9>")
	)
	(segment
		(start 181.54142 -213.797388)
		(end 181.22392 -213.797388)
		(width 0.18288)
		(layer "In11.Cu")
		(net "M_H_CPU1_SB_DQ<9>")
	)
	(segment
		(start 158.330646 -216.707466)
		(end 158.330646 -216.980262)
		(width 0.18288)
		(layer "In11.Cu")
		(net "M_H_CPU1_SB_DQ<9>")
	)
	(segment
		(start 181.9275 -214.888826)
		(end 181.73446 -214.695786)
		(width 0.18288)
		(layer "In11.Cu")
		(net "M_H_CPU1_SB_DQ<9>")
	)
	(segment
		(start 158.944564 -215.964516)
		(end 158.944564 -215.742266)
		(width 0.18288)
		(layer "In11.Cu")
		(net "M_H_CPU1_SB_DQ<9>")
	)
	(segment
		(start 174.64151 -215.435942)
		(end 173.637194 -216.440258)
		(width 0.18288)
		(layer "In11.Cu")
		(net "M_H_CPU1_SB_DQ<9>")
	)
	(segment
		(start 157.704028 -217.07602)
		(end 157.256226 -217.07602)
		(width 0.18288)
		(layer "In11.Cu")
		(net "M_H_CPU1_SB_DQ<9>")
	)
	(segment
		(start 179.938426 -214.888826)
		(end 179.735226 -214.685626)
		(width 0.18288)
		(layer "In11.Cu")
		(net "M_H_CPU1_SB_DQ<9>")
	)
	(segment
		(start 158.105856 -217.205052)
		(end 157.83306 -217.205052)
		(width 0.18288)
		(layer "In11.Cu")
		(net "M_H_CPU1_SB_DQ<9>")
	)
	(segment
		(start 156.14523 -218.459812)
		(end 155.872434 -218.459812)
		(width 0.18288)
		(layer "In11.Cu")
		(net "M_H_CPU1_SB_DQ<9>")
	)
	(segment
		(start 156.854398 -218.173808)
		(end 156.854398 -218.446604)
		(width 0.18288)
		(layer "In11.Cu")
		(net "M_H_CPU1_SB_DQ<9>")
	)
	(segment
		(start 166.850822 -215.666066)
		(end 166.850822 -215.837008)
		(width 0.18288)
		(layer "In11.Cu")
		(net "M_H_CPU1_SB_DQ<9>")
	)
	(segment
		(start 156.642816 -217.962226)
		(end 156.854398 -218.173808)
		(width 0.18288)
		(layer "In11.Cu")
		(net "M_H_CPU1_SB_DQ<9>")
	)
	(segment
		(start 155.634436 -219.666566)
		(end 155.36164 -219.666566)
		(width 0.18288)
		(layer "In11.Cu")
		(net "M_H_CPU1_SB_DQ<9>")
	)
	(segment
		(start 166.147242 -215.837008)
		(end 166.147242 -215.666066)
		(width 0.18288)
		(layer "In11.Cu")
		(net "M_H_CPU1_SB_DQ<9>")
	)
	(segment
		(start 129.693924 -233.837988)
		(end 129.68351 -233.831892)
		(width 0.088646)
		(layer "In11.Cu")
		(net "M_H_CPU1_SB_DQ<9>")
	)
	(segment
		(start 202.971146 -221.116652)
		(end 202.35672 -220.502226)
		(width 0.18288)
		(layer "In11.Cu")
		(net "M_H_CPU1_SB_DQ<9>")
	)
	(segment
		(start 156.854398 -218.446604)
		(end 156.629608 -218.671394)
		(width 0.18288)
		(layer "In11.Cu")
		(net "M_H_CPU1_SB_DQ<9>")
	)
	(segment
		(start 163.458652 -215.877648)
		(end 163.265612 -215.684608)
		(width 0.18288)
		(layer "In11.Cu")
		(net "M_H_CPU1_SB_DQ<9>")
	)
	(segment
		(start 162.755072 -215.246966)
		(end 162.562032 -215.440006)
		(width 0.18288)
		(layer "In11.Cu")
		(net "M_H_CPU1_SB_DQ<9>")
	)
	(segment
		(start 163.265612 -215.440006)
		(end 163.072572 -215.246966)
		(width 0.18288)
		(layer "In11.Cu")
		(net "M_H_CPU1_SB_DQ<9>")
	)
	(segment
		(start 185.918602 -214.798402)
		(end 185.918602 -215.025224)
		(width 0.18288)
		(layer "In11.Cu")
		(net "M_H_CPU1_SB_DQ<9>")
	)
	(segment
		(start 199.394826 -219.968826)
		(end 198.251826 -218.825826)
		(width 0.18288)
		(layer "In11.Cu")
		(net "M_H_CPU1_SB_DQ<9>")
	)
	(segment
		(start 167.894762 -215.473026)
		(end 167.043862 -215.473026)
		(width 0.18288)
		(layer "In11.Cu")
		(net "M_H_CPU1_SB_DQ<9>")
	)
	(segment
		(start 185.408062 -215.218264)
		(end 185.215022 -215.025224)
		(width 0.18288)
		(layer "In11.Cu")
		(net "M_H_CPU1_SB_DQ<9>")
	)
	(segment
		(start 126.879096 -233.840528)
		(end 126.864364 -233.831892)
		(width 0.088646)
		(layer "In11.Cu")
		(net "M_H_CPU1_SB_DQ<9>")
	)
	(segment
		(start 199.953626 -219.968826)
		(end 199.394826 -219.968826)
		(width 0.18288)
		(layer "In11.Cu")
		(net "M_H_CPU1_SB_DQ<9>")
	)
	(segment
		(start 155.36164 -219.666566)
		(end 155.150058 -219.454984)
		(width 0.18288)
		(layer "In11.Cu")
		(net "M_H_CPU1_SB_DQ<9>")
	)
	(segment
		(start 158.944564 -215.742266)
		(end 158.751524 -215.549226)
		(width 0.18288)
		(layer "In11.Cu")
		(net "M_H_CPU1_SB_DQ<9>")
	)
	(segment
		(start 155.859226 -219.16898)
		(end 155.859226 -219.441776)
		(width 0.18288)
		(layer "In11.Cu")
		(net "M_H_CPU1_SB_DQ<9>")
	)
	(segment
		(start 166.340282 -216.030048)
		(end 166.147242 -215.837008)
		(width 0.18288)
		(layer "In11.Cu")
		(net "M_H_CPU1_SB_DQ<9>")
	)
	(segment
		(start 198.251826 -218.825826)
		(end 197.185026 -218.825826)
		(width 0.18288)
		(layer "In11.Cu")
		(net "M_H_CPU1_SB_DQ<9>")
	)
	(segment
		(start 157.83306 -217.205052)
		(end 157.704028 -217.07602)
		(width 0.18288)
		(layer "In11.Cu")
		(net "M_H_CPU1_SB_DQ<9>")
	)
	(segment
		(start 162.368992 -215.877648)
		(end 160.759648 -215.877648)
		(width 0.18288)
		(layer "In11.Cu")
		(net "M_H_CPU1_SB_DQ<9>")
	)
	(segment
		(start 156.629608 -218.671394)
		(end 156.356812 -218.671394)
		(width 0.18288)
		(layer "In11.Cu")
		(net "M_H_CPU1_SB_DQ<9>")
	)
	(segment
		(start 158.751524 -215.549226)
		(end 158.394654 -215.549226)
		(width 0.18288)
		(layer "In11.Cu")
		(net "M_H_CPU1_SB_DQ<9>")
	)
	(segment
		(start 181.73446 -213.990428)
		(end 181.54142 -213.797388)
		(width 0.18288)
		(layer "In11.Cu")
		(net "M_H_CPU1_SB_DQ<9>")
	)
	(segment
		(start 179.735226 -214.685626)
		(end 178.970686 -214.685626)
		(width 0.18288)
		(layer "In11.Cu")
		(net "M_H_CPU1_SB_DQ<9>")
	)
	(segment
		(start 195.153026 -217.174826)
		(end 194.314826 -216.336626)
		(width 0.18288)
		(layer "In11.Cu")
		(net "M_H_CPU1_SB_DQ<9>")
	)
	(segment
		(start 188.883798 -214.740998)
		(end 187.131198 -214.740998)
		(width 0.18288)
		(layer "In11.Cu")
		(net "M_H_CPU1_SB_DQ<9>")
	)
	(segment
		(start 130.638296 -233.840528)
		(end 130.623564 -233.831892)
		(width 0.088646)
		(layer "In11.Cu")
		(net "M_H_CPU1_SB_DQ<9>")
	)
	(segment
		(start 149.091396 -226.172268)
		(end 142.815056 -232.450386)
		(width 0.18288)
		(layer "In11.Cu")
		(net "M_H_CPU1_SB_DQ<9>")
	)
	(segment
		(start 155.647644 -218.957398)
		(end 155.859226 -219.16898)
		(width 0.18288)
		(layer "In11.Cu")
		(net "M_H_CPU1_SB_DQ<9>")
	)
	(segment
		(start 165.954202 -215.473026)
		(end 165.130226 -215.473026)
		(width 0.18288)
		(layer "In11.Cu")
		(net "M_H_CPU1_SB_DQ<9>")
	)
	(segment
		(start 142.815056 -232.450386)
		(end 140.163296 -232.450386)
		(width 0.18288)
		(layer "In11.Cu")
		(net "M_H_CPU1_SB_DQ<9>")
	)
	(segment
		(start 185.725562 -215.218264)
		(end 185.408062 -215.218264)
		(width 0.18288)
		(layer "In11.Cu")
		(net "M_H_CPU1_SB_DQ<9>")
	)
	(segment
		(start 173.636178 -216.439242)
		(end 172.141642 -216.439242)
		(width 0.18288)
		(layer "In11.Cu")
		(net "M_H_CPU1_SB_DQ<9>")
	)
	(segment
		(start 187.131198 -214.740998)
		(end 186.995562 -214.605362)
		(width 0.18288)
		(layer "In11.Cu")
		(net "M_H_CPU1_SB_DQ<9>")
	)
	(segment
		(start 131.578096 -233.840528)
		(end 131.563364 -233.831892)
		(width 0.088646)
		(layer "In11.Cu")
		(net "M_H_CPU1_SB_DQ<9>")
	)
	(segment
		(start 180.83784 -214.888826)
		(end 179.938426 -214.888826)
		(width 0.18288)
		(layer "In11.Cu")
		(net "M_H_CPU1_SB_DQ<9>")
	)
	(segment
		(start 155.150058 -219.454984)
		(end 154.877262 -219.454984)
		(width 0.18288)
		(layer "In11.Cu")
		(net "M_H_CPU1_SB_DQ<9>")
	)
	(segment
		(start 160.431226 -215.549226)
		(end 159.841184 -215.549226)
		(width 0.18288)
		(layer "In11.Cu")
		(net "M_H_CPU1_SB_DQ<9>")
	)
	(segment
		(start 127.818896 -233.840528)
		(end 127.804164 -233.831892)
		(width 0.088646)
		(layer "In11.Cu")
		(net "M_H_CPU1_SB_DQ<9>")
	)
	(segment
		(start 124.999496 -233.840528)
		(end 124.984764 -233.831892)
		(width 0.088646)
		(layer "In11.Cu")
		(net "M_H_CPU1_SB_DQ<9>")
	)
	(segment
		(start 185.021982 -214.605362)
		(end 183.39689 -214.605362)
		(width 0.18288)
		(layer "In11.Cu")
		(net "M_H_CPU1_SB_DQ<9>")
	)
	(segment
		(start 193.113406 -215.592406)
		(end 191.259206 -215.592406)
		(width 0.18288)
		(layer "In11.Cu")
		(net "M_H_CPU1_SB_DQ<9>")
	)
	(segment
		(start 159.137604 -216.157556)
		(end 158.944564 -215.964516)
		(width 0.18288)
		(layer "In11.Cu")
		(net "M_H_CPU1_SB_DQ<9>")
	)
	(segment
		(start 181.03088 -213.990428)
		(end 181.03088 -214.695786)
		(width 0.18288)
		(layer "In11.Cu")
		(net "M_H_CPU1_SB_DQ<9>")
	)
	(segment
		(start 156.642816 -217.68943)
		(end 156.642816 -217.962226)
		(width 0.18288)
		(layer "In11.Cu")
		(net "M_H_CPU1_SB_DQ<9>")
	)
	(segment
		(start 173.637194 -216.440258)
		(end 173.636178 -216.439242)
		(width 0.18288)
		(layer "In11.Cu")
		(net "M_H_CPU1_SB_DQ<9>")
	)
	(segment
		(start 166.850822 -215.837008)
		(end 166.657782 -216.030048)
		(width 0.18288)
		(layer "In11.Cu")
		(net "M_H_CPU1_SB_DQ<9>")
	)
	(segment
		(start 189.565026 -215.422226)
		(end 188.883798 -214.740998)
		(width 0.18288)
		(layer "In11.Cu")
		(net "M_H_CPU1_SB_DQ<9>")
	)
	(segment
		(start 178.06543 -215.590882)
		(end 176.381664 -215.590882)
		(width 0.18288)
		(layer "In11.Cu")
		(net "M_H_CPU1_SB_DQ<9>")
	)
	(segment
		(start 194.314826 -216.336626)
		(end 193.857626 -216.336626)
		(width 0.18288)
		(layer "In11.Cu")
		(net "M_H_CPU1_SB_DQ<9>")
	)
	(segment
		(start 181.03088 -214.695786)
		(end 180.83784 -214.888826)
		(width 0.18288)
		(layer "In11.Cu")
		(net "M_H_CPU1_SB_DQ<9>")
	)
	(segment
		(start 162.562032 -215.684608)
		(end 162.368992 -215.877648)
		(width 0.18288)
		(layer "In11.Cu")
		(net "M_H_CPU1_SB_DQ<9>")
	)
	(segment
		(start 163.072572 -215.246966)
		(end 162.755072 -215.246966)
		(width 0.18288)
		(layer "In11.Cu")
		(net "M_H_CPU1_SB_DQ<9>")
	)
	(segment
		(start 166.147242 -215.666066)
		(end 165.954202 -215.473026)
		(width 0.18288)
		(layer "In11.Cu")
		(net "M_H_CPU1_SB_DQ<9>")
	)
	(segment
		(start 168.707562 -216.285826)
		(end 167.894762 -215.473026)
		(width 0.18288)
		(layer "In11.Cu")
		(net "M_H_CPU1_SB_DQ<9>")
	)
	(segment
		(start 185.215022 -215.025224)
		(end 185.215022 -214.798402)
		(width 0.18288)
		(layer "In11.Cu")
		(net "M_H_CPU1_SB_DQ<9>")
	)
	(segment
		(start 155.872434 -218.459812)
		(end 155.647644 -218.684602)
		(width 0.18288)
		(layer "In11.Cu")
		(net "M_H_CPU1_SB_DQ<9>")
	)
	(segment
		(start 158.330646 -216.980262)
		(end 158.105856 -217.205052)
		(width 0.18288)
		(layer "In11.Cu")
		(net "M_H_CPU1_SB_DQ<9>")
	)
	(segment
		(start 160.759648 -215.877648)
		(end 160.431226 -215.549226)
		(width 0.18288)
		(layer "In11.Cu")
		(net "M_H_CPU1_SB_DQ<9>")
	)
	(segment
		(start 202.35672 -220.502226)
		(end 200.487026 -220.502226)
		(width 0.18288)
		(layer "In11.Cu")
		(net "M_H_CPU1_SB_DQ<9>")
	)
	(segment
		(start 171.988226 -216.285826)
		(end 168.707562 -216.285826)
		(width 0.18288)
		(layer "In11.Cu")
		(net "M_H_CPU1_SB_DQ<9>")
	)
	(segment
		(start 183.39689 -214.605362)
		(end 183.113426 -214.888826)
		(width 0.18288)
		(layer "In11.Cu")
		(net "M_H_CPU1_SB_DQ<9>")
	)
	(segment
		(start 156.356812 -218.671394)
		(end 156.14523 -218.459812)
		(width 0.18288)
		(layer "In11.Cu")
		(net "M_H_CPU1_SB_DQ<9>")
	)
	(segment
		(start 185.918602 -215.025224)
		(end 185.725562 -215.218264)
		(width 0.18288)
		(layer "In11.Cu")
		(net "M_H_CPU1_SB_DQ<9>")
	)
	(segment
		(start 193.857626 -216.336626)
		(end 193.113406 -215.592406)
		(width 0.18288)
		(layer "In11.Cu")
		(net "M_H_CPU1_SB_DQ<9>")
	)
	(segment
		(start 159.455104 -216.157556)
		(end 159.137604 -216.157556)
		(width 0.18288)
		(layer "In11.Cu")
		(net "M_H_CPU1_SB_DQ<9>")
	)
	(segment
		(start 186.995562 -214.605362)
		(end 186.111642 -214.605362)
		(width 0.18288)
		(layer "In11.Cu")
		(net "M_H_CPU1_SB_DQ<9>")
	)
	(segment
		(start 158.201614 -215.742266)
		(end 158.201614 -216.578434)
		(width 0.18288)
		(layer "In11.Cu")
		(net "M_H_CPU1_SB_DQ<9>")
	)
	(segment
		(start 162.562032 -215.440006)
		(end 162.562032 -215.684608)
		(width 0.18288)
		(layer "In11.Cu")
		(net "M_H_CPU1_SB_DQ<9>")
	)
	(segment
		(start 166.657782 -216.030048)
		(end 166.340282 -216.030048)
		(width 0.18288)
		(layer "In11.Cu")
		(net "M_H_CPU1_SB_DQ<9>")
	)
	(segment
		(start 149.091396 -225.242628)
		(end 149.091396 -226.172268)
		(width 0.18288)
		(layer "In11.Cu")
		(net "M_H_CPU1_SB_DQ<9>")
	)
	(segment
		(start 158.201614 -216.578434)
		(end 158.330646 -216.707466)
		(width 0.18288)
		(layer "In11.Cu")
		(net "M_H_CPU1_SB_DQ<9>")
	)
	(segment
		(start 185.215022 -214.798402)
		(end 185.021982 -214.605362)
		(width 0.18288)
		(layer "In11.Cu")
		(net "M_H_CPU1_SB_DQ<9>")
	)
	(segment
		(start 172.141642 -216.439242)
		(end 171.988226 -216.285826)
		(width 0.18288)
		(layer "In11.Cu")
		(net "M_H_CPU1_SB_DQ<9>")
	)
	(segment
		(start 138.529314 -233.907838)
		(end 138.42492 -233.907838)
		(width 0.088646)
		(layer "In11.Cu")
		(net "M_H_CPU1_SB_DQ<9>")
	)
	(segment
		(start 165.130226 -215.473026)
		(end 164.725604 -215.877648)
		(width 0.18288)
		(layer "In11.Cu")
		(net "M_H_CPU1_SB_DQ<9>")
	)
	(segment
		(start 159.841184 -215.549226)
		(end 159.648144 -215.742266)
		(width 0.18288)
		(layer "In11.Cu")
		(net "M_H_CPU1_SB_DQ<9>")
	)
	(segment
		(start 159.648144 -215.742266)
		(end 159.648144 -215.964516)
		(width 0.18288)
		(layer "In11.Cu")
		(net "M_H_CPU1_SB_DQ<9>")
	)
	(segment
		(start 167.043862 -215.473026)
		(end 166.850822 -215.666066)
		(width 0.18288)
		(layer "In11.Cu")
		(net "M_H_CPU1_SB_DQ<9>")
	)
	(segment
		(start 200.487026 -220.502226)
		(end 199.953626 -219.968826)
		(width 0.18288)
		(layer "In11.Cu")
		(net "M_H_CPU1_SB_DQ<9>")
	)
	(segment
		(start 163.265612 -215.684608)
		(end 163.265612 -215.440006)
		(width 0.18288)
		(layer "In11.Cu")
		(net "M_H_CPU1_SB_DQ<9>")
	)
	(segment
		(start 183.113426 -214.888826)
		(end 181.9275 -214.888826)
		(width 0.18288)
		(layer "In11.Cu")
		(net "M_H_CPU1_SB_DQ<9>")
	)
	(segment
		(start 124.059696 -233.840528)
		(end 123.947682 -233.774742)
		(width 0.088646)
		(layer "In11.Cu")
		(net "M_H_CPU1_SB_DQ<9>")
	)
	(segment
		(start 197.185026 -218.825826)
		(end 195.534026 -217.174826)
		(width 0.18288)
		(layer "In11.Cu")
		(net "M_H_CPU1_SB_DQ<9>")
	)
	(segment
		(start 139.986766 -232.450386)
		(end 138.529314 -233.907838)
		(width 0.088646)
		(layer "In11.Cu")
		(net "M_H_CPU1_SB_DQ<9>")
	)
	(segment
		(start 164.725604 -215.877648)
		(end 163.458652 -215.877648)
		(width 0.18288)
		(layer "In11.Cu")
		(net "M_H_CPU1_SB_DQ<9>")
	)
	(segment
		(start 176.226724 -215.435942)
		(end 174.64151 -215.435942)
		(width 0.18288)
		(layer "In11.Cu")
		(net "M_H_CPU1_SB_DQ<9>")
	)
	(segment
		(start 155.647644 -218.684602)
		(end 155.647644 -218.957398)
		(width 0.18288)
		(layer "In11.Cu")
		(net "M_H_CPU1_SB_DQ<9>")
	)
	(segment
		(start 158.394654 -215.549226)
		(end 158.201614 -215.742266)
		(width 0.18288)
		(layer "In11.Cu")
		(net "M_H_CPU1_SB_DQ<9>")
	)
	(segment
		(start 191.089026 -215.422226)
		(end 189.565026 -215.422226)
		(width 0.18288)
		(layer "In11.Cu")
		(net "M_H_CPU1_SB_DQ<9>")
	)
	(segment
		(start 176.381664 -215.590882)
		(end 176.226724 -215.435942)
		(width 0.18288)
		(layer "In11.Cu")
		(net "M_H_CPU1_SB_DQ<9>")
	)
	(segment
		(start 128.754378 -233.837988)
		(end 128.743964 -233.831892)
		(width 0.088646)
		(layer "In11.Cu")
		(net "M_H_CPU1_SB_DQ<9>")
	)
	(segment
		(start 195.534026 -217.174826)
		(end 195.153026 -217.174826)
		(width 0.18288)
		(layer "In11.Cu")
		(net "M_H_CPU1_SB_DQ<9>")
	)
	(segment
		(start 154.877262 -219.454984)
		(end 149.091396 -225.242628)
		(width 0.18288)
		(layer "In11.Cu")
		(net "M_H_CPU1_SB_DQ<9>")
	)
	(segment
		(start 191.259206 -215.592406)
		(end 191.089026 -215.422226)
		(width 0.18288)
		(layer "In11.Cu")
		(net "M_H_CPU1_SB_DQ<9>")
	)
	(segment
		(start 157.256226 -217.07602)
		(end 156.642816 -217.68943)
		(width 0.18288)
		(layer "In11.Cu")
		(net "M_H_CPU1_SB_DQ<9>")
	)
	(segment
		(start 181.73446 -214.695786)
		(end 181.73446 -213.990428)
		(width 0.18288)
		(layer "In11.Cu")
		(net "M_H_CPU1_SB_DQ<9>")
	)
	(segment
		(start 178.970686 -214.685626)
		(end 178.06543 -215.590882)
		(width 0.18288)
		(layer "In11.Cu")
		(net "M_H_CPU1_SB_DQ<9>")
	)
	(segment
		(start 155.859226 -219.441776)
		(end 155.634436 -219.666566)
		(width 0.18288)
		(layer "In11.Cu")
		(net "M_H_CPU1_SB_DQ<9>")
	)
	(segment
		(start 140.163296 -232.450386)
		(end 139.986766 -232.450386)
		(width 0.088646)
		(layer "In11.Cu")
		(net "M_H_CPU1_SB_DQ<9>")
	)
	(segment
		(start 181.22392 -213.797388)
		(end 181.03088 -213.990428)
		(width 0.18288)
		(layer "In11.Cu")
		(net "M_H_CPU1_SB_DQ<9>")
	)
	(arc
		(start 130.623564 -233.831892)
		(mid 130.436366 -233.781749)
		(end 130.249168 -233.831892)
		(width 0.088646)
		(layer "In11.Cu")
		(net "M_H_CPU1_SB_DQ<9>")
	)
	(arc
		(start 128.743964 -233.831892)
		(mid 128.556766 -233.781749)
		(end 128.369568 -233.831892)
		(width 0.088646)
		(layer "In11.Cu")
		(net "M_H_CPU1_SB_DQ<9>")
	)
	(arc
		(start 133.068568 -233.831892)
		(mid 132.785866 -233.907634)
		(end 132.503164 -233.831892)
		(width 0.088646)
		(layer "In11.Cu")
		(net "M_H_CPU1_SB_DQ<9>")
	)
	(arc
		(start 123.947682 -233.774742)
		(mid 123.65382 -233.576363)
		(end 123.387612 -233.34218)
		(width 0.088646)
		(layer "In11.Cu")
		(net "M_H_CPU1_SB_DQ<9>")
	)
	(arc
		(start 135.887968 -233.831892)
		(mid 135.605266 -233.907634)
		(end 135.322564 -233.831892)
		(width 0.088646)
		(layer "In11.Cu")
		(net "M_H_CPU1_SB_DQ<9>")
	)
	(arc
		(start 133.442964 -233.831892)
		(mid 133.255766 -233.781749)
		(end 133.068568 -233.831892)
		(width 0.088646)
		(layer "In11.Cu")
		(net "M_H_CPU1_SB_DQ<9>")
	)
	(arc
		(start 124.984764 -233.831892)
		(mid 124.797566 -233.781749)
		(end 124.610368 -233.831892)
		(width 0.088646)
		(layer "In11.Cu")
		(net "M_H_CPU1_SB_DQ<9>")
	)
	(arc
		(start 124.610368 -233.831892)
		(mid 124.336139 -233.907817)
		(end 124.059696 -233.840528)
		(width 0.088646)
		(layer "In11.Cu")
		(net "M_H_CPU1_SB_DQ<9>")
	)
	(arc
		(start 132.128768 -233.831892)
		(mid 131.854539 -233.907817)
		(end 131.578096 -233.840528)
		(width 0.088646)
		(layer "In11.Cu")
		(net "M_H_CPU1_SB_DQ<9>")
	)
	(arc
		(start 136.827768 -233.831892)
		(mid 136.545066 -233.907634)
		(end 136.262364 -233.831892)
		(width 0.088646)
		(layer "In11.Cu")
		(net "M_H_CPU1_SB_DQ<9>")
	)
	(arc
		(start 125.550168 -233.831892)
		(mid 125.275939 -233.907817)
		(end 124.999496 -233.840528)
		(width 0.088646)
		(layer "In11.Cu")
		(net "M_H_CPU1_SB_DQ<9>")
	)
	(arc
		(start 138.141964 -233.831892)
		(mid 137.954766 -233.781749)
		(end 137.767568 -233.831892)
		(width 0.088646)
		(layer "In11.Cu")
		(net "M_H_CPU1_SB_DQ<9>")
	)
	(arc
		(start 137.767568 -233.831892)
		(mid 137.484866 -233.907634)
		(end 137.202164 -233.831892)
		(width 0.088646)
		(layer "In11.Cu")
		(net "M_H_CPU1_SB_DQ<9>")
	)
	(arc
		(start 137.202164 -233.831892)
		(mid 137.014966 -233.781749)
		(end 136.827768 -233.831892)
		(width 0.088646)
		(layer "In11.Cu")
		(net "M_H_CPU1_SB_DQ<9>")
	)
	(arc
		(start 136.262364 -233.831892)
		(mid 136.075166 -233.781749)
		(end 135.887968 -233.831892)
		(width 0.088646)
		(layer "In11.Cu")
		(net "M_H_CPU1_SB_DQ<9>")
	)
	(arc
		(start 130.249168 -233.831892)
		(mid 129.972355 -233.907728)
		(end 129.693924 -233.837988)
		(width 0.088646)
		(layer "In11.Cu")
		(net "M_H_CPU1_SB_DQ<9>")
	)
	(arc
		(start 127.804164 -233.831892)
		(mid 127.616966 -233.781749)
		(end 127.429768 -233.831892)
		(width 0.088646)
		(layer "In11.Cu")
		(net "M_H_CPU1_SB_DQ<9>")
	)
	(arc
		(start 125.924564 -233.831892)
		(mid 125.737366 -233.781749)
		(end 125.550168 -233.831892)
		(width 0.088646)
		(layer "In11.Cu")
		(net "M_H_CPU1_SB_DQ<9>")
	)
	(arc
		(start 134.382764 -233.831892)
		(mid 134.195566 -233.781749)
		(end 134.008368 -233.831892)
		(width 0.088646)
		(layer "In11.Cu")
		(net "M_H_CPU1_SB_DQ<9>")
	)
	(arc
		(start 132.503164 -233.831892)
		(mid 132.315966 -233.781749)
		(end 132.128768 -233.831892)
		(width 0.088646)
		(layer "In11.Cu")
		(net "M_H_CPU1_SB_DQ<9>")
	)
	(arc
		(start 128.369568 -233.831892)
		(mid 128.095339 -233.907817)
		(end 127.818896 -233.840528)
		(width 0.088646)
		(layer "In11.Cu")
		(net "M_H_CPU1_SB_DQ<9>")
	)
	(arc
		(start 131.563364 -233.831892)
		(mid 131.376166 -233.781749)
		(end 131.188968 -233.831892)
		(width 0.088646)
		(layer "In11.Cu")
		(net "M_H_CPU1_SB_DQ<9>")
	)
	(arc
		(start 126.864364 -233.831892)
		(mid 126.677166 -233.781749)
		(end 126.489968 -233.831892)
		(width 0.088646)
		(layer "In11.Cu")
		(net "M_H_CPU1_SB_DQ<9>")
	)
	(arc
		(start 126.489968 -233.831892)
		(mid 126.207266 -233.907634)
		(end 125.924564 -233.831892)
		(width 0.088646)
		(layer "In11.Cu")
		(net "M_H_CPU1_SB_DQ<9>")
	)
	(arc
		(start 134.948168 -233.831892)
		(mid 134.665466 -233.907634)
		(end 134.382764 -233.831892)
		(width 0.088646)
		(layer "In11.Cu")
		(net "M_H_CPU1_SB_DQ<9>")
	)
	(arc
		(start 138.42492 -233.907838)
		(mid 138.27845 -233.888478)
		(end 138.141964 -233.831892)
		(width 0.088646)
		(layer "In11.Cu")
		(net "M_H_CPU1_SB_DQ<9>")
	)
	(arc
		(start 127.429768 -233.831892)
		(mid 127.155539 -233.907817)
		(end 126.879096 -233.840528)
		(width 0.088646)
		(layer "In11.Cu")
		(net "M_H_CPU1_SB_DQ<9>")
	)
	(arc
		(start 129.68351 -233.831892)
		(mid 129.496312 -233.781749)
		(end 129.309114 -233.831892)
		(width 0.088646)
		(layer "In11.Cu")
		(net "M_H_CPU1_SB_DQ<9>")
	)
	(arc
		(start 129.309114 -233.831892)
		(mid 129.032555 -233.907601)
		(end 128.754378 -233.837988)
		(width 0.088646)
		(layer "In11.Cu")
		(net "M_H_CPU1_SB_DQ<9>")
	)
	(arc
		(start 135.322564 -233.831892)
		(mid 135.135366 -233.781749)
		(end 134.948168 -233.831892)
		(width 0.088646)
		(layer "In11.Cu")
		(net "M_H_CPU1_SB_DQ<9>")
	)
	(arc
		(start 131.188968 -233.831892)
		(mid 130.914739 -233.907817)
		(end 130.638296 -233.840528)
		(width 0.088646)
		(layer "In11.Cu")
		(net "M_H_CPU1_SB_DQ<9>")
	)
	(arc
		(start 134.008368 -233.831892)
		(mid 133.725666 -233.907634)
		(end 133.442964 -233.831892)
		(width 0.088646)
		(layer "In11.Cu")
		(net "M_H_CPU1_SB_DQ<9>")
	)
	(segment
		(start 209.596482 -222.385382)
		(end 209.186526 -222.385382)
		(width 0.20066)
		(layer "F.Cu")
		(net "M_H_CPU1_SB_DQ<8>")
	)
	(segment
		(start 206.508604 -222.509842)
		(end 206.508604 -222.87738)
		(width 0.20066)
		(layer "F.Cu")
		(net "M_H_CPU1_SB_DQ<8>")
	)
	(segment
		(start 206.320644 -223.06534)
		(end 205.84541 -223.06534)
		(width 0.20066)
		(layer "F.Cu")
		(net "M_H_CPU1_SB_DQ<8>")
	)
	(segment
		(start 211.619592 -222.816928)
		(end 210.028028 -222.816928)
		(width 0.20066)
		(layer "F.Cu")
		(net "M_H_CPU1_SB_DQ<8>")
	)
	(segment
		(start 123.857512 -234.69219)
		(end 123.857766 -234.691936)
		(width 0.20066)
		(layer "F.Cu")
		(net "M_H_CPU1_SB_DQ<8>")
	)
	(segment
		(start 211.619846 -222.816674)
		(end 211.619592 -222.816928)
		(width 0.20066)
		(layer "F.Cu")
		(net "M_H_CPU1_SB_DQ<8>")
	)
	(segment
		(start 206.971392 -222.391732)
		(end 206.626714 -222.391732)
		(width 0.20066)
		(layer "F.Cu")
		(net "M_H_CPU1_SB_DQ<8>")
	)
	(segment
		(start 210.028028 -222.816928)
		(end 209.596482 -222.385382)
		(width 0.20066)
		(layer "F.Cu")
		(net "M_H_CPU1_SB_DQ<8>")
	)
	(segment
		(start 209.186526 -222.385382)
		(end 209.180176 -222.391732)
		(width 0.1016)
		(layer "F.Cu")
		(net "M_H_CPU1_SB_DQ<8>")
	)
	(segment
		(start 123.857766 -234.691936)
		(end 123.857766 -234.15625)
		(width 0.20066)
		(layer "F.Cu")
		(net "M_H_CPU1_SB_DQ<8>")
	)
	(segment
		(start 205.596744 -222.816674)
		(end 204.076046 -222.816674)
		(width 0.20066)
		(layer "F.Cu")
		(net "M_H_CPU1_SB_DQ<8>")
	)
	(segment
		(start 204.076046 -222.816674)
		(end 202.971146 -222.816674)
		(width 0.20066)
		(layer "F.Cu")
		(net "M_H_CPU1_SB_DQ<8>")
	)
	(segment
		(start 209.180176 -222.391732)
		(end 207.018382 -222.391732)
		(width 0.1016)
		(layer "F.Cu")
		(net "M_H_CPU1_SB_DQ<8>")
	)
	(segment
		(start 206.508604 -222.87738)
		(end 206.320644 -223.06534)
		(width 0.20066)
		(layer "F.Cu")
		(net "M_H_CPU1_SB_DQ<8>")
	)
	(segment
		(start 206.626714 -222.391732)
		(end 206.508604 -222.509842)
		(width 0.20066)
		(layer "F.Cu")
		(net "M_H_CPU1_SB_DQ<8>")
	)
	(segment
		(start 205.84541 -223.06534)
		(end 205.596744 -222.816674)
		(width 0.20066)
		(layer "F.Cu")
		(net "M_H_CPU1_SB_DQ<8>")
	)
	(segment
		(start 207.018382 -222.391732)
		(end 206.971392 -222.391732)
		(width 0.101854)
		(layer "F.Cu")
		(net "M_H_CPU1_SB_DQ<8>")
	)
	(segment
		(start 163.252404 -217.621866)
		(end 163.252404 -218.137232)
		(width 0.18288)
		(layer "In11.Cu")
		(net "M_H_CPU1_SB_DQ<8>")
	)
	(segment
		(start 171.101766 -219.10802)
		(end 170.908726 -218.91498)
		(width 0.18288)
		(layer "In11.Cu")
		(net "M_H_CPU1_SB_DQ<8>")
	)
	(segment
		(start 187.949078 -216.444322)
		(end 187.816998 -216.444068)
		(width 0.18288)
		(layer "In11.Cu")
		(net "M_H_CPU1_SB_DQ<8>")
	)
	(segment
		(start 193.95948 -218.432634)
		(end 193.499994 -218.891866)
		(width 0.18288)
		(layer "In11.Cu")
		(net "M_H_CPU1_SB_DQ<8>")
	)
	(segment
		(start 170.398186 -218.138756)
		(end 170.205146 -218.331796)
		(width 0.18288)
		(layer "In11.Cu")
		(net "M_H_CPU1_SB_DQ<8>")
	)
	(segment
		(start 162.355784 -217.387678)
		(end 161.158428 -217.387678)
		(width 0.18288)
		(layer "In11.Cu")
		(net "M_H_CPU1_SB_DQ<8>")
	)
	(segment
		(start 185.05297 -216.571322)
		(end 184.85993 -216.378282)
		(width 0.18288)
		(layer "In11.Cu")
		(net "M_H_CPU1_SB_DQ<8>")
	)
	(segment
		(start 170.908726 -218.331796)
		(end 170.715686 -218.138756)
		(width 0.18288)
		(layer "In11.Cu")
		(net "M_H_CPU1_SB_DQ<8>")
	)
	(segment
		(start 179.281582 -217.437716)
		(end 177.635916 -217.437716)
		(width 0.18288)
		(layer "In11.Cu")
		(net "M_H_CPU1_SB_DQ<8>")
	)
	(segment
		(start 163.252404 -218.137232)
		(end 163.059364 -218.330272)
		(width 0.18288)
		(layer "In11.Cu")
		(net "M_H_CPU1_SB_DQ<8>")
	)
	(segment
		(start 158.625286 -219.682822)
		(end 158.35249 -219.682822)
		(width 0.18288)
		(layer "In11.Cu")
		(net "M_H_CPU1_SB_DQ<8>")
	)
	(segment
		(start 185.75655 -217.130122)
		(end 185.56351 -217.323162)
		(width 0.18288)
		(layer "In11.Cu")
		(net "M_H_CPU1_SB_DQ<8>")
	)
	(segment
		(start 139.719558 -233.468164)
		(end 138.592814 -234.594908)
		(width 0.088646)
		(layer "In11.Cu")
		(net "M_H_CPU1_SB_DQ<8>")
	)
	(segment
		(start 183.63057 -216.378282)
		(end 183.215026 -216.793826)
		(width 0.18288)
		(layer "In11.Cu")
		(net "M_H_CPU1_SB_DQ<8>")
	)
	(segment
		(start 195.55587 -219.756228)
		(end 194.232276 -218.432634)
		(width 0.18288)
		(layer "In11.Cu")
		(net "M_H_CPU1_SB_DQ<8>")
	)
	(segment
		(start 157.911292 -219.241624)
		(end 157.638496 -219.241624)
		(width 0.18288)
		(layer "In11.Cu")
		(net "M_H_CPU1_SB_DQ<8>")
	)
	(segment
		(start 198.340726 -220.845126)
		(end 197.096126 -220.845126)
		(width 0.18288)
		(layer "In11.Cu")
		(net "M_H_CPU1_SB_DQ<8>")
	)
	(segment
		(start 170.205146 -218.91498)
		(end 170.012106 -219.10802)
		(width 0.18288)
		(layer "In11.Cu")
		(net "M_H_CPU1_SB_DQ<8>")
	)
	(segment
		(start 185.94959 -216.378282)
		(end 185.75655 -216.571322)
		(width 0.18288)
		(layer "In11.Cu")
		(net "M_H_CPU1_SB_DQ<8>")
	)
	(segment
		(start 124.18822 -234.355132)
		(end 123.857766 -234.15625)
		(width 0.088646)
		(layer "In11.Cu")
		(net "M_H_CPU1_SB_DQ<8>")
	)
	(segment
		(start 158.408878 -218.471242)
		(end 158.408878 -218.744038)
		(width 0.18288)
		(layer "In11.Cu")
		(net "M_H_CPU1_SB_DQ<8>")
	)
	(segment
		(start 177.395124 -217.29065)
		(end 176.958752 -217.28938)
		(width 0.18288)
		(layer "In11.Cu")
		(net "M_H_CPU1_SB_DQ<8>")
	)
	(segment
		(start 185.56351 -217.323162)
		(end 185.24601 -217.323162)
		(width 0.18288)
		(layer "In11.Cu")
		(net "M_H_CPU1_SB_DQ<8>")
	)
	(segment
		(start 199.674226 -222.178626)
		(end 198.340726 -220.845126)
		(width 0.18288)
		(layer "In11.Cu")
		(net "M_H_CPU1_SB_DQ<8>")
	)
	(segment
		(start 127.899414 -234.645708)
		(end 127.884682 -234.654344)
		(width 0.088646)
		(layer "In11.Cu")
		(net "M_H_CPU1_SB_DQ<8>")
	)
	(segment
		(start 189.387226 -217.124026)
		(end 188.707776 -216.444576)
		(width 0.18288)
		(layer "In11.Cu")
		(net "M_H_CPU1_SB_DQ<8>")
	)
	(segment
		(start 182.091838 -216.793826)
		(end 181.898798 -216.986866)
		(width 0.18288)
		(layer "In11.Cu")
		(net "M_H_CPU1_SB_DQ<8>")
	)
	(segment
		(start 158.35249 -219.682822)
		(end 157.911292 -219.241624)
		(width 0.18288)
		(layer "In11.Cu")
		(net "M_H_CPU1_SB_DQ<8>")
	)
	(segment
		(start 177.635916 -217.437716)
		(end 177.48885 -217.29065)
		(width 0.18288)
		(layer "In11.Cu")
		(net "M_H_CPU1_SB_DQ<8>")
	)
	(segment
		(start 202.518264 -222.178626)
		(end 199.674226 -222.178626)
		(width 0.18288)
		(layer "In11.Cu")
		(net "M_H_CPU1_SB_DQ<8>")
	)
	(segment
		(start 162.548824 -218.137232)
		(end 162.548824 -217.580718)
		(width 0.18288)
		(layer "In11.Cu")
		(net "M_H_CPU1_SB_DQ<8>")
	)
	(segment
		(start 171.612306 -218.331796)
		(end 171.612306 -218.91498)
		(width 0.18288)
		(layer "In11.Cu")
		(net "M_H_CPU1_SB_DQ<8>")
	)
	(segment
		(start 174.712376 -217.143076)
		(end 173.716696 -218.138756)
		(width 0.18288)
		(layer "In11.Cu")
		(net "M_H_CPU1_SB_DQ<8>")
	)
	(segment
		(start 162.741864 -218.330272)
		(end 162.548824 -218.137232)
		(width 0.18288)
		(layer "In11.Cu")
		(net "M_H_CPU1_SB_DQ<8>")
	)
	(segment
		(start 197.096126 -220.845126)
		(end 196.007228 -219.756228)
		(width 0.18288)
		(layer "In11.Cu")
		(net "M_H_CPU1_SB_DQ<8>")
	)
	(segment
		(start 158.850076 -219.458032)
		(end 158.625286 -219.682822)
		(width 0.18288)
		(layer "In11.Cu")
		(net "M_H_CPU1_SB_DQ<8>")
	)
	(segment
		(start 169.694606 -219.10802)
		(end 169.501566 -218.91498)
		(width 0.18288)
		(layer "In11.Cu")
		(net "M_H_CPU1_SB_DQ<8>")
	)
	(segment
		(start 185.05297 -217.130122)
		(end 185.05297 -216.571322)
		(width 0.18288)
		(layer "In11.Cu")
		(net "M_H_CPU1_SB_DQ<8>")
	)
	(segment
		(start 130.718814 -234.645708)
		(end 130.704082 -234.654344)
		(width 0.088646)
		(layer "In11.Cu")
		(net "M_H_CPU1_SB_DQ<8>")
	)
	(segment
		(start 160.970976 -217.200226)
		(end 159.679894 -217.200226)
		(width 0.18288)
		(layer "In11.Cu")
		(net "M_H_CPU1_SB_DQ<8>")
	)
	(segment
		(start 196.007228 -219.756228)
		(end 195.55587 -219.756228)
		(width 0.18288)
		(layer "In11.Cu")
		(net "M_H_CPU1_SB_DQ<8>")
	)
	(segment
		(start 193.461894 -217.662252)
		(end 193.091308 -217.291666)
		(width 0.18288)
		(layer "In11.Cu")
		(net "M_H_CPU1_SB_DQ<8>")
	)
	(segment
		(start 193.002408 -218.39428)
		(end 193.461894 -217.935048)
		(width 0.18288)
		(layer "In11.Cu")
		(net "M_H_CPU1_SB_DQ<8>")
	)
	(segment
		(start 169.501566 -218.91498)
		(end 169.501566 -218.331796)
		(width 0.18288)
		(layer "In11.Cu")
		(net "M_H_CPU1_SB_DQ<8>")
	)
	(segment
		(start 161.158428 -217.387678)
		(end 160.970976 -217.200226)
		(width 0.18288)
		(layer "In11.Cu")
		(net "M_H_CPU1_SB_DQ<8>")
	)
	(segment
		(start 176.665382 -217.28938)
		(end 176.519078 -217.143076)
		(width 0.18288)
		(layer "In11.Cu")
		(net "M_H_CPU1_SB_DQ<8>")
	)
	(segment
		(start 126.959614 -234.645708)
		(end 126.944882 -234.654344)
		(width 0.088646)
		(layer "In11.Cu")
		(net "M_H_CPU1_SB_DQ<8>")
	)
	(segment
		(start 202.971146 -222.510858)
		(end 202.882246 -222.421958)
		(width 0.18288)
		(layer "In11.Cu")
		(net "M_H_CPU1_SB_DQ<8>")
	)
	(segment
		(start 169.501566 -218.331796)
		(end 169.308526 -218.138756)
		(width 0.18288)
		(layer "In11.Cu")
		(net "M_H_CPU1_SB_DQ<8>")
	)
	(segment
		(start 185.75655 -216.571322)
		(end 185.75655 -217.130122)
		(width 0.18288)
		(layer "In11.Cu")
		(net "M_H_CPU1_SB_DQ<8>")
	)
	(segment
		(start 176.519078 -217.143076)
		(end 174.712376 -217.143076)
		(width 0.18288)
		(layer "In11.Cu")
		(net "M_H_CPU1_SB_DQ<8>")
	)
	(segment
		(start 163.445444 -217.428826)
		(end 163.252404 -217.621866)
		(width 0.18288)
		(layer "In11.Cu")
		(net "M_H_CPU1_SB_DQ<8>")
	)
	(segment
		(start 168.862756 -218.138756)
		(end 167.924226 -217.200226)
		(width 0.18288)
		(layer "In11.Cu")
		(net "M_H_CPU1_SB_DQ<8>")
	)
	(segment
		(start 170.205146 -218.331796)
		(end 170.205146 -218.91498)
		(width 0.18288)
		(layer "In11.Cu")
		(net "M_H_CPU1_SB_DQ<8>")
	)
	(segment
		(start 128.839214 -234.645708)
		(end 128.824482 -234.654344)
		(width 0.088646)
		(layer "In11.Cu")
		(net "M_H_CPU1_SB_DQ<8>")
	)
	(segment
		(start 170.715686 -218.138756)
		(end 170.398186 -218.138756)
		(width 0.18288)
		(layer "In11.Cu")
		(net "M_H_CPU1_SB_DQ<8>")
	)
	(segment
		(start 159.679894 -217.200226)
		(end 158.408878 -218.471242)
		(width 0.18288)
		(layer "In11.Cu")
		(net "M_H_CPU1_SB_DQ<8>")
	)
	(segment
		(start 171.419266 -219.10802)
		(end 171.101766 -219.10802)
		(width 0.18288)
		(layer "In11.Cu")
		(net "M_H_CPU1_SB_DQ<8>")
	)
	(segment
		(start 140.163296 -233.468164)
		(end 139.719558 -233.468164)
		(width 0.088646)
		(layer "In11.Cu")
		(net "M_H_CPU1_SB_DQ<8>")
	)
	(segment
		(start 194.232276 -218.432634)
		(end 193.95948 -218.432634)
		(width 0.18288)
		(layer "In11.Cu")
		(net "M_H_CPU1_SB_DQ<8>")
	)
	(segment
		(start 181.898798 -217.43289)
		(end 181.705758 -217.62593)
		(width 0.18288)
		(layer "In11.Cu")
		(net "M_H_CPU1_SB_DQ<8>")
	)
	(segment
		(start 170.908726 -218.91498)
		(end 170.908726 -218.331796)
		(width 0.18288)
		(layer "In11.Cu")
		(net "M_H_CPU1_SB_DQ<8>")
	)
	(segment
		(start 131.658868 -234.645708)
		(end 131.648454 -234.651804)
		(width 0.088646)
		(layer "In11.Cu")
		(net "M_H_CPU1_SB_DQ<8>")
	)
	(segment
		(start 170.012106 -219.10802)
		(end 169.694606 -219.10802)
		(width 0.18288)
		(layer "In11.Cu")
		(net "M_H_CPU1_SB_DQ<8>")
	)
	(segment
		(start 181.388258 -217.62593)
		(end 181.195218 -217.43289)
		(width 0.18288)
		(layer "In11.Cu")
		(net "M_H_CPU1_SB_DQ<8>")
	)
	(segment
		(start 132.598414 -234.645708)
		(end 132.588 -234.651804)
		(width 0.088646)
		(layer "In11.Cu")
		(net "M_H_CPU1_SB_DQ<8>")
	)
	(segment
		(start 143.281908 -233.468164)
		(end 140.163296 -233.468164)
		(width 0.18288)
		(layer "In11.Cu")
		(net "M_H_CPU1_SB_DQ<8>")
	)
	(segment
		(start 183.215026 -216.793826)
		(end 182.091838 -216.793826)
		(width 0.18288)
		(layer "In11.Cu")
		(net "M_H_CPU1_SB_DQ<8>")
	)
	(segment
		(start 158.408878 -218.744038)
		(end 158.850076 -219.185236)
		(width 0.18288)
		(layer "In11.Cu")
		(net "M_H_CPU1_SB_DQ<8>")
	)
	(segment
		(start 176.958752 -217.28938)
		(end 176.665382 -217.28938)
		(width 0.18288)
		(layer "In11.Cu")
		(net "M_H_CPU1_SB_DQ<8>")
	)
	(segment
		(start 138.592814 -234.594908)
		(end 138.42492 -234.594908)
		(width 0.088646)
		(layer "In11.Cu")
		(net "M_H_CPU1_SB_DQ<8>")
	)
	(segment
		(start 177.48885 -217.29065)
		(end 177.395124 -217.29065)
		(width 0.18288)
		(layer "In11.Cu")
		(net "M_H_CPU1_SB_DQ<8>")
	)
	(segment
		(start 181.898798 -216.986866)
		(end 181.898798 -217.43289)
		(width 0.18288)
		(layer "In11.Cu")
		(net "M_H_CPU1_SB_DQ<8>")
	)
	(segment
		(start 173.716696 -218.138756)
		(end 171.805346 -218.138756)
		(width 0.18288)
		(layer "In11.Cu")
		(net "M_H_CPU1_SB_DQ<8>")
	)
	(segment
		(start 185.24601 -217.323162)
		(end 185.05297 -217.130122)
		(width 0.18288)
		(layer "In11.Cu")
		(net "M_H_CPU1_SB_DQ<8>")
	)
	(segment
		(start 167.924226 -217.200226)
		(end 164.803328 -217.200226)
		(width 0.18288)
		(layer "In11.Cu")
		(net "M_H_CPU1_SB_DQ<8>")
	)
	(segment
		(start 184.85993 -216.378282)
		(end 183.63057 -216.378282)
		(width 0.18288)
		(layer "In11.Cu")
		(net "M_H_CPU1_SB_DQ<8>")
	)
	(segment
		(start 136.357614 -234.645708)
		(end 136.3472 -234.651804)
		(width 0.088646)
		(layer "In11.Cu")
		(net "M_H_CPU1_SB_DQ<8>")
	)
	(segment
		(start 171.612306 -218.91498)
		(end 171.419266 -219.10802)
		(width 0.18288)
		(layer "In11.Cu")
		(net "M_H_CPU1_SB_DQ<8>")
	)
	(segment
		(start 181.705758 -217.62593)
		(end 181.388258 -217.62593)
		(width 0.18288)
		(layer "In11.Cu")
		(net "M_H_CPU1_SB_DQ<8>")
	)
	(segment
		(start 190.977266 -217.291666)
		(end 190.809626 -217.124026)
		(width 0.18288)
		(layer "In11.Cu")
		(net "M_H_CPU1_SB_DQ<8>")
	)
	(segment
		(start 193.227198 -218.891866)
		(end 193.002408 -218.667076)
		(width 0.18288)
		(layer "In11.Cu")
		(net "M_H_CPU1_SB_DQ<8>")
	)
	(segment
		(start 137.297668 -234.645708)
		(end 137.287254 -234.651804)
		(width 0.088646)
		(layer "In11.Cu")
		(net "M_H_CPU1_SB_DQ<8>")
	)
	(segment
		(start 202.971146 -222.816674)
		(end 202.971146 -222.510858)
		(width 0.18288)
		(layer "In11.Cu")
		(net "M_H_CPU1_SB_DQ<8>")
	)
	(segment
		(start 164.803328 -217.200226)
		(end 164.574728 -217.428826)
		(width 0.18288)
		(layer "In11.Cu")
		(net "M_H_CPU1_SB_DQ<8>")
	)
	(segment
		(start 193.091308 -217.291666)
		(end 190.977266 -217.291666)
		(width 0.18288)
		(layer "In11.Cu")
		(net "M_H_CPU1_SB_DQ<8>")
	)
	(segment
		(start 187.353194 -216.443052)
		(end 187.288424 -216.378282)
		(width 0.18288)
		(layer "In11.Cu")
		(net "M_H_CPU1_SB_DQ<8>")
	)
	(segment
		(start 163.059364 -218.330272)
		(end 162.741864 -218.330272)
		(width 0.18288)
		(layer "In11.Cu")
		(net "M_H_CPU1_SB_DQ<8>")
	)
	(segment
		(start 187.816998 -216.444068)
		(end 187.353194 -216.443052)
		(width 0.18288)
		(layer "In11.Cu")
		(net "M_H_CPU1_SB_DQ<8>")
	)
	(segment
		(start 158.850076 -219.185236)
		(end 158.850076 -219.458032)
		(width 0.18288)
		(layer "In11.Cu")
		(net "M_H_CPU1_SB_DQ<8>")
	)
	(segment
		(start 187.288424 -216.378282)
		(end 185.94959 -216.378282)
		(width 0.18288)
		(layer "In11.Cu")
		(net "M_H_CPU1_SB_DQ<8>")
	)
	(segment
		(start 181.002178 -216.793826)
		(end 179.925472 -216.793826)
		(width 0.18288)
		(layer "In11.Cu")
		(net "M_H_CPU1_SB_DQ<8>")
	)
	(segment
		(start 188.707776 -216.444576)
		(end 187.949332 -216.444576)
		(width 0.18288)
		(layer "In11.Cu")
		(net "M_H_CPU1_SB_DQ<8>")
	)
	(segment
		(start 179.925472 -216.793826)
		(end 179.281582 -217.437716)
		(width 0.18288)
		(layer "In11.Cu")
		(net "M_H_CPU1_SB_DQ<8>")
	)
	(segment
		(start 125.460506 -234.64901)
		(end 125.454664 -234.645708)
		(width 0.088646)
		(layer "In11.Cu")
		(net "M_H_CPU1_SB_DQ<8>")
	)
	(segment
		(start 125.454664 -234.645708)
		(end 125.448822 -234.642152)
		(width 0.088646)
		(layer "In11.Cu")
		(net "M_H_CPU1_SB_DQ<8>")
	)
	(segment
		(start 181.195218 -216.986866)
		(end 181.002178 -216.793826)
		(width 0.18288)
		(layer "In11.Cu")
		(net "M_H_CPU1_SB_DQ<8>")
	)
	(segment
		(start 190.809626 -217.124026)
		(end 189.387226 -217.124026)
		(width 0.18288)
		(layer "In11.Cu")
		(net "M_H_CPU1_SB_DQ<8>")
	)
	(segment
		(start 169.308526 -218.138756)
		(end 168.862756 -218.138756)
		(width 0.18288)
		(layer "In11.Cu")
		(net "M_H_CPU1_SB_DQ<8>")
	)
	(segment
		(start 193.002408 -218.667076)
		(end 193.002408 -218.39428)
		(width 0.18288)
		(layer "In11.Cu")
		(net "M_H_CPU1_SB_DQ<8>")
	)
	(segment
		(start 164.574728 -217.428826)
		(end 163.445444 -217.428826)
		(width 0.18288)
		(layer "In11.Cu")
		(net "M_H_CPU1_SB_DQ<8>")
	)
	(segment
		(start 171.805346 -218.138756)
		(end 171.612306 -218.331796)
		(width 0.18288)
		(layer "In11.Cu")
		(net "M_H_CPU1_SB_DQ<8>")
	)
	(segment
		(start 193.499994 -218.891866)
		(end 193.227198 -218.891866)
		(width 0.18288)
		(layer "In11.Cu")
		(net "M_H_CPU1_SB_DQ<8>")
	)
	(segment
		(start 193.461894 -217.935048)
		(end 193.461894 -217.662252)
		(width 0.18288)
		(layer "In11.Cu")
		(net "M_H_CPU1_SB_DQ<8>")
	)
	(segment
		(start 157.271466 -219.608654)
		(end 157.141418 -219.608654)
		(width 0.18288)
		(layer "In11.Cu")
		(net "M_H_CPU1_SB_DQ<8>")
	)
	(segment
		(start 181.195218 -217.43289)
		(end 181.195218 -216.986866)
		(width 0.18288)
		(layer "In11.Cu")
		(net "M_H_CPU1_SB_DQ<8>")
	)
	(segment
		(start 187.949332 -216.444576)
		(end 187.949078 -216.444322)
		(width 0.18288)
		(layer "In11.Cu")
		(net "M_H_CPU1_SB_DQ<8>")
	)
	(segment
		(start 133.538468 -234.645708)
		(end 133.528054 -234.651804)
		(width 0.088646)
		(layer "In11.Cu")
		(net "M_H_CPU1_SB_DQ<8>")
	)
	(segment
		(start 157.638496 -219.241624)
		(end 157.271466 -219.608654)
		(width 0.18288)
		(layer "In11.Cu")
		(net "M_H_CPU1_SB_DQ<8>")
	)
	(segment
		(start 157.141418 -219.608654)
		(end 143.281908 -233.468164)
		(width 0.18288)
		(layer "In11.Cu")
		(net "M_H_CPU1_SB_DQ<8>")
	)
	(segment
		(start 162.548824 -217.580718)
		(end 162.355784 -217.387678)
		(width 0.18288)
		(layer "In11.Cu")
		(net "M_H_CPU1_SB_DQ<8>")
	)
	(segment
		(start 202.882246 -222.421958)
		(end 202.518264 -222.178626)
		(width 0.18288)
		(layer "In11.Cu")
		(net "M_H_CPU1_SB_DQ<8>")
	)
	(arc
		(start 127.884682 -234.654344)
		(mid 127.608207 -234.721664)
		(end 127.33401 -234.645708)
		(width 0.088646)
		(layer "In11.Cu")
		(net "M_H_CPU1_SB_DQ<8>")
	)
	(arc
		(start 137.672064 -234.645708)
		(mid 137.484866 -234.595565)
		(end 137.297668 -234.645708)
		(width 0.088646)
		(layer "In11.Cu")
		(net "M_H_CPU1_SB_DQ<8>")
	)
	(arc
		(start 132.033264 -234.645708)
		(mid 131.846066 -234.595565)
		(end 131.658868 -234.645708)
		(width 0.088646)
		(layer "In11.Cu")
		(net "M_H_CPU1_SB_DQ<8>")
	)
	(arc
		(start 137.287254 -234.651804)
		(mid 137.008822 -234.72165)
		(end 136.73201 -234.645708)
		(width 0.088646)
		(layer "In11.Cu")
		(net "M_H_CPU1_SB_DQ<8>")
	)
	(arc
		(start 130.15341 -234.645708)
		(mid 129.966212 -234.595565)
		(end 129.779014 -234.645708)
		(width 0.088646)
		(layer "In11.Cu")
		(net "M_H_CPU1_SB_DQ<8>")
	)
	(arc
		(start 132.97281 -234.645708)
		(mid 132.785612 -234.595565)
		(end 132.598414 -234.645708)
		(width 0.088646)
		(layer "In11.Cu")
		(net "M_H_CPU1_SB_DQ<8>")
	)
	(arc
		(start 126.019814 -234.645708)
		(mid 125.740611 -234.721348)
		(end 125.460506 -234.64901)
		(width 0.088646)
		(layer "In11.Cu")
		(net "M_H_CPU1_SB_DQ<8>")
	)
	(arc
		(start 132.588 -234.651804)
		(mid 132.309822 -234.721527)
		(end 132.033264 -234.645708)
		(width 0.088646)
		(layer "In11.Cu")
		(net "M_H_CPU1_SB_DQ<8>")
	)
	(arc
		(start 135.418068 -234.645708)
		(mid 135.135366 -234.721484)
		(end 134.852664 -234.645708)
		(width 0.088646)
		(layer "In11.Cu")
		(net "M_H_CPU1_SB_DQ<8>")
	)
	(arc
		(start 138.237468 -234.645708)
		(mid 137.954766 -234.721484)
		(end 137.672064 -234.645708)
		(width 0.088646)
		(layer "In11.Cu")
		(net "M_H_CPU1_SB_DQ<8>")
	)
	(arc
		(start 130.704082 -234.654344)
		(mid 130.427607 -234.721664)
		(end 130.15341 -234.645708)
		(width 0.088646)
		(layer "In11.Cu")
		(net "M_H_CPU1_SB_DQ<8>")
	)
	(arc
		(start 128.27381 -234.645708)
		(mid 128.086612 -234.595565)
		(end 127.899414 -234.645708)
		(width 0.088646)
		(layer "In11.Cu")
		(net "M_H_CPU1_SB_DQ<8>")
	)
	(arc
		(start 125.080014 -234.645708)
		(mid 124.685553 -234.710296)
		(end 124.34697 -234.49788)
		(width 0.088646)
		(layer "In11.Cu")
		(net "M_H_CPU1_SB_DQ<8>")
	)
	(arc
		(start 128.824482 -234.654344)
		(mid 128.548007 -234.721664)
		(end 128.27381 -234.645708)
		(width 0.088646)
		(layer "In11.Cu")
		(net "M_H_CPU1_SB_DQ<8>")
	)
	(arc
		(start 125.448822 -234.642152)
		(mid 125.263937 -234.595359)
		(end 125.080014 -234.645708)
		(width 0.088646)
		(layer "In11.Cu")
		(net "M_H_CPU1_SB_DQ<8>")
	)
	(arc
		(start 127.33401 -234.645708)
		(mid 127.146812 -234.595565)
		(end 126.959614 -234.645708)
		(width 0.088646)
		(layer "In11.Cu")
		(net "M_H_CPU1_SB_DQ<8>")
	)
	(arc
		(start 124.34697 -234.49788)
		(mid 124.274401 -234.418935)
		(end 124.18822 -234.355132)
		(width 0.088646)
		(layer "In11.Cu")
		(net "M_H_CPU1_SB_DQ<8>")
	)
	(arc
		(start 129.21361 -234.645708)
		(mid 129.026412 -234.595565)
		(end 128.839214 -234.645708)
		(width 0.088646)
		(layer "In11.Cu")
		(net "M_H_CPU1_SB_DQ<8>")
	)
	(arc
		(start 133.528054 -234.651804)
		(mid 133.249622 -234.72165)
		(end 132.97281 -234.645708)
		(width 0.088646)
		(layer "In11.Cu")
		(net "M_H_CPU1_SB_DQ<8>")
	)
	(arc
		(start 136.73201 -234.645708)
		(mid 136.544812 -234.595565)
		(end 136.357614 -234.645708)
		(width 0.088646)
		(layer "In11.Cu")
		(net "M_H_CPU1_SB_DQ<8>")
	)
	(arc
		(start 129.779014 -234.645708)
		(mid 129.496312 -234.721484)
		(end 129.21361 -234.645708)
		(width 0.088646)
		(layer "In11.Cu")
		(net "M_H_CPU1_SB_DQ<8>")
	)
	(arc
		(start 133.912864 -234.645708)
		(mid 133.725666 -234.595565)
		(end 133.538468 -234.645708)
		(width 0.088646)
		(layer "In11.Cu")
		(net "M_H_CPU1_SB_DQ<8>")
	)
	(arc
		(start 126.39421 -234.645708)
		(mid 126.207012 -234.595565)
		(end 126.019814 -234.645708)
		(width 0.088646)
		(layer "In11.Cu")
		(net "M_H_CPU1_SB_DQ<8>")
	)
	(arc
		(start 131.09321 -234.645708)
		(mid 130.906012 -234.595565)
		(end 130.718814 -234.645708)
		(width 0.088646)
		(layer "In11.Cu")
		(net "M_H_CPU1_SB_DQ<8>")
	)
	(arc
		(start 126.944882 -234.654344)
		(mid 126.668407 -234.721664)
		(end 126.39421 -234.645708)
		(width 0.088646)
		(layer "In11.Cu")
		(net "M_H_CPU1_SB_DQ<8>")
	)
	(arc
		(start 134.478268 -234.645708)
		(mid 134.195566 -234.721484)
		(end 133.912864 -234.645708)
		(width 0.088646)
		(layer "In11.Cu")
		(net "M_H_CPU1_SB_DQ<8>")
	)
	(arc
		(start 134.852664 -234.645708)
		(mid 134.665466 -234.595565)
		(end 134.478268 -234.645708)
		(width 0.088646)
		(layer "In11.Cu")
		(net "M_H_CPU1_SB_DQ<8>")
	)
	(arc
		(start 136.3472 -234.651804)
		(mid 136.069022 -234.721527)
		(end 135.792464 -234.645708)
		(width 0.088646)
		(layer "In11.Cu")
		(net "M_H_CPU1_SB_DQ<8>")
	)
	(arc
		(start 135.792464 -234.645708)
		(mid 135.605266 -234.595565)
		(end 135.418068 -234.645708)
		(width 0.088646)
		(layer "In11.Cu")
		(net "M_H_CPU1_SB_DQ<8>")
	)
	(arc
		(start 138.42492 -234.594908)
		(mid 138.32785 -234.607965)
		(end 138.237468 -234.645708)
		(width 0.088646)
		(layer "In11.Cu")
		(net "M_H_CPU1_SB_DQ<8>")
	)
	(arc
		(start 131.648454 -234.651804)
		(mid 131.370022 -234.72165)
		(end 131.09321 -234.645708)
		(width 0.088646)
		(layer "In11.Cu")
		(net "M_H_CPU1_SB_DQ<8>")
	)
	(segment
		(start 123.857766 -236.319568)
		(end 123.857766 -235.783882)
		(width 0.20066)
		(layer "F.Cu")
		(net "M_H_CPU1_SB_DQ<7>")
	)
	(segment
		(start 214.385652 -223.666558)
		(end 215.719914 -223.666558)
		(width 0.20066)
		(layer "F.Cu")
		(net "M_H_CPU1_SB_DQ<7>")
	)
	(segment
		(start 213.515448 -223.89973)
		(end 213.515448 -223.648778)
		(width 0.20066)
		(layer "F.Cu")
		(net "M_H_CPU1_SB_DQ<7>")
	)
	(segment
		(start 210.306412 -224.098612)
		(end 210.598258 -224.098612)
		(width 0.20066)
		(layer "F.Cu")
		(net "M_H_CPU1_SB_DQ<7>")
	)
	(segment
		(start 207.071214 -223.666558)
		(end 208.176114 -223.666558)
		(width 0.20066)
		(layer "F.Cu")
		(net "M_H_CPU1_SB_DQ<7>")
	)
	(segment
		(start 123.857512 -236.319822)
		(end 123.857766 -236.319568)
		(width 0.20066)
		(layer "F.Cu")
		(net "M_H_CPU1_SB_DQ<7>")
	)
	(segment
		(start 213.311486 -224.103692)
		(end 213.515448 -223.89973)
		(width 0.20066)
		(layer "F.Cu")
		(net "M_H_CPU1_SB_DQ<7>")
	)
	(segment
		(start 210.598258 -224.098612)
		(end 210.603084 -224.098612)
		(width 0.101854)
		(layer "F.Cu")
		(net "M_H_CPU1_SB_DQ<7>")
	)
	(segment
		(start 209.874358 -223.666558)
		(end 210.306412 -224.098612)
		(width 0.20066)
		(layer "F.Cu")
		(net "M_H_CPU1_SB_DQ<7>")
	)
	(segment
		(start 213.515448 -223.648778)
		(end 213.749636 -223.41459)
		(width 0.20066)
		(layer "F.Cu")
		(net "M_H_CPU1_SB_DQ<7>")
	)
	(segment
		(start 214.133684 -223.41459)
		(end 214.385652 -223.666558)
		(width 0.20066)
		(layer "F.Cu")
		(net "M_H_CPU1_SB_DQ<7>")
	)
	(segment
		(start 210.610196 -224.0915)
		(end 212.618066 -224.0915)
		(width 0.1016)
		(layer "F.Cu")
		(net "M_H_CPU1_SB_DQ<7>")
	)
	(segment
		(start 213.749636 -223.41459)
		(end 214.133684 -223.41459)
		(width 0.20066)
		(layer "F.Cu")
		(net "M_H_CPU1_SB_DQ<7>")
	)
	(segment
		(start 210.603084 -224.098612)
		(end 210.610196 -224.0915)
		(width 0.1016)
		(layer "F.Cu")
		(net "M_H_CPU1_SB_DQ<7>")
	)
	(segment
		(start 212.630258 -224.103692)
		(end 213.311486 -224.103692)
		(width 0.20066)
		(layer "F.Cu")
		(net "M_H_CPU1_SB_DQ<7>")
	)
	(segment
		(start 208.176114 -223.666558)
		(end 209.874358 -223.666558)
		(width 0.20066)
		(layer "F.Cu")
		(net "M_H_CPU1_SB_DQ<7>")
	)
	(segment
		(start 212.618066 -224.0915)
		(end 212.630258 -224.103692)
		(width 0.1016)
		(layer "F.Cu")
		(net "M_H_CPU1_SB_DQ<7>")
	)
	(segment
		(start 192.16497 -218.99245)
		(end 191.76365 -218.99245)
		(width 0.18288)
		(layer "In11.Cu")
		(net "M_H_CPU1_SB_DQ<7>")
	)
	(segment
		(start 160.139126 -220.756226)
		(end 158.689802 -220.756226)
		(width 0.18288)
		(layer "In11.Cu")
		(net "M_H_CPU1_SB_DQ<7>")
	)
	(segment
		(start 168.151556 -219.432886)
		(end 164.866574 -219.432886)
		(width 0.18288)
		(layer "In11.Cu")
		(net "M_H_CPU1_SB_DQ<7>")
	)
	(segment
		(start 191.76365 -218.99245)
		(end 191.749426 -218.978226)
		(width 0.18288)
		(layer "In11.Cu")
		(net "M_H_CPU1_SB_DQ<7>")
	)
	(segment
		(start 127.340106 -235.291122)
		(end 127.328422 -235.297726)
		(width 0.088646)
		(layer "In11.Cu")
		(net "M_H_CPU1_SB_DQ<7>")
	)
	(segment
		(start 129.779014 -235.294424)
		(end 129.764282 -235.285788)
		(width 0.088646)
		(layer "In11.Cu")
		(net "M_H_CPU1_SB_DQ<7>")
	)
	(segment
		(start 198.226426 -222.661226)
		(end 197.60819 -222.661226)
		(width 0.18288)
		(layer "In11.Cu")
		(net "M_H_CPU1_SB_DQ<7>")
	)
	(segment
		(start 197.60819 -222.661226)
		(end 195.649342 -220.702378)
		(width 0.18288)
		(layer "In11.Cu")
		(net "M_H_CPU1_SB_DQ<7>")
	)
	(segment
		(start 183.420258 -218.130374)
		(end 181.861968 -218.436698)
		(width 0.18288)
		(layer "In11.Cu")
		(net "M_H_CPU1_SB_DQ<7>")
	)
	(segment
		(start 139.752832 -235.05033)
		(end 139.752832 -235.130086)
		(width 0.088646)
		(layer "In11.Cu")
		(net "M_H_CPU1_SB_DQ<7>")
	)
	(segment
		(start 191.458088 -218.978226)
		(end 190.643002 -218.16314)
		(width 0.18288)
		(layer "In11.Cu")
		(net "M_H_CPU1_SB_DQ<7>")
	)
	(segment
		(start 202.208384 -223.243394)
		(end 202.035918 -223.41586)
		(width 0.18288)
		(layer "In11.Cu")
		(net "M_H_CPU1_SB_DQ<7>")
	)
	(segment
		(start 160.977326 -219.918026)
		(end 160.139126 -220.756226)
		(width 0.18288)
		(layer "In11.Cu")
		(net "M_H_CPU1_SB_DQ<7>")
	)
	(segment
		(start 193.065146 -219.892626)
		(end 192.16497 -218.99245)
		(width 0.18288)
		(layer "In11.Cu")
		(net "M_H_CPU1_SB_DQ<7>")
	)
	(segment
		(start 202.035918 -223.41586)
		(end 199.503284 -223.41586)
		(width 0.18288)
		(layer "In11.Cu")
		(net "M_H_CPU1_SB_DQ<7>")
	)
	(segment
		(start 177.411126 -218.990926)
		(end 174.559976 -218.990926)
		(width 0.18288)
		(layer "In11.Cu")
		(net "M_H_CPU1_SB_DQ<7>")
	)
	(segment
		(start 195.649342 -220.702378)
		(end 195.25615 -220.702378)
		(width 0.18288)
		(layer "In11.Cu")
		(net "M_H_CPU1_SB_DQ<7>")
	)
	(segment
		(start 124.712984 -235.33989)
		(end 123.857766 -235.783882)
		(width 0.088646)
		(layer "In11.Cu")
		(net "M_H_CPU1_SB_DQ<7>")
	)
	(segment
		(start 168.659302 -219.940632)
		(end 168.151556 -219.432886)
		(width 0.18288)
		(layer "In11.Cu")
		(net "M_H_CPU1_SB_DQ<7>")
	)
	(segment
		(start 138.356848 -235.38688)
		(end 138.354308 -235.384086)
		(width 0.088646)
		(layer "In11.Cu")
		(net "M_H_CPU1_SB_DQ<7>")
	)
	(segment
		(start 164.381434 -219.918026)
		(end 160.977326 -219.918026)
		(width 0.18288)
		(layer "In11.Cu")
		(net "M_H_CPU1_SB_DQ<7>")
	)
	(segment
		(start 139.752832 -235.130086)
		(end 139.496038 -235.38688)
		(width 0.088646)
		(layer "In11.Cu")
		(net "M_H_CPU1_SB_DQ<7>")
	)
	(segment
		(start 136.357614 -235.294424)
		(end 136.3472 -235.288328)
		(width 0.088646)
		(layer "In11.Cu")
		(net "M_H_CPU1_SB_DQ<7>")
	)
	(segment
		(start 126.400306 -235.291122)
		(end 126.388622 -235.297726)
		(width 0.088646)
		(layer "In11.Cu")
		(net "M_H_CPU1_SB_DQ<7>")
	)
	(segment
		(start 191.749426 -218.978226)
		(end 191.458088 -218.978226)
		(width 0.18288)
		(layer "In11.Cu")
		(net "M_H_CPU1_SB_DQ<7>")
	)
	(segment
		(start 157.92831 -221.001082)
		(end 156.89072 -221.001082)
		(width 0.18288)
		(layer "In11.Cu")
		(net "M_H_CPU1_SB_DQ<7>")
	)
	(segment
		(start 140.247116 -234.556046)
		(end 139.752832 -235.05033)
		(width 0.088646)
		(layer "In11.Cu")
		(net "M_H_CPU1_SB_DQ<7>")
	)
	(segment
		(start 156.89072 -221.001082)
		(end 143.620998 -234.270804)
		(width 0.18288)
		(layer "In11.Cu")
		(net "M_H_CPU1_SB_DQ<7>")
	)
	(segment
		(start 137.297414 -235.294424)
		(end 137.282682 -235.285788)
		(width 0.088646)
		(layer "In11.Cu")
		(net "M_H_CPU1_SB_DQ<7>")
	)
	(segment
		(start 186.559444 -218.130374)
		(end 183.420258 -218.130374)
		(width 0.18288)
		(layer "In11.Cu")
		(net "M_H_CPU1_SB_DQ<7>")
	)
	(segment
		(start 190.643002 -218.16314)
		(end 189.129924 -218.16314)
		(width 0.18288)
		(layer "In11.Cu")
		(net "M_H_CPU1_SB_DQ<7>")
	)
	(segment
		(start 174.559976 -218.990926)
		(end 174.012606 -219.227146)
		(width 0.18288)
		(layer "In11.Cu")
		(net "M_H_CPU1_SB_DQ<7>")
	)
	(segment
		(start 188.257434 -217.29065)
		(end 187.399168 -217.29065)
		(width 0.18288)
		(layer "In11.Cu")
		(net "M_H_CPU1_SB_DQ<7>")
	)
	(segment
		(start 172.229526 -219.841826)
		(end 172.13072 -219.940632)
		(width 0.18288)
		(layer "In11.Cu")
		(net "M_H_CPU1_SB_DQ<7>")
	)
	(segment
		(start 158.689802 -220.756226)
		(end 157.92831 -221.001082)
		(width 0.18288)
		(layer "In11.Cu")
		(net "M_H_CPU1_SB_DQ<7>")
	)
	(segment
		(start 138.237214 -235.294424)
		(end 138.222482 -235.285788)
		(width 0.088646)
		(layer "In11.Cu")
		(net "M_H_CPU1_SB_DQ<7>")
	)
	(segment
		(start 132.043678 -235.288328)
		(end 132.033264 -235.294424)
		(width 0.088646)
		(layer "In11.Cu")
		(net "M_H_CPU1_SB_DQ<7>")
	)
	(segment
		(start 206.1972 -222.79356)
		(end 205.391004 -222.79356)
		(width 0.18288)
		(layer "In11.Cu")
		(net "M_H_CPU1_SB_DQ<7>")
	)
	(segment
		(start 204.94117 -223.243394)
		(end 202.208384 -223.243394)
		(width 0.18288)
		(layer "In11.Cu")
		(net "M_H_CPU1_SB_DQ<7>")
	)
	(segment
		(start 140.532358 -234.270804)
		(end 140.247116 -234.556046)
		(width 0.18288)
		(layer "In11.Cu")
		(net "M_H_CPU1_SB_DQ<7>")
	)
	(segment
		(start 172.13072 -219.940632)
		(end 168.659302 -219.940632)
		(width 0.18288)
		(layer "In11.Cu")
		(net "M_H_CPU1_SB_DQ<7>")
	)
	(segment
		(start 189.129924 -218.16314)
		(end 188.257434 -217.29065)
		(width 0.18288)
		(layer "In11.Cu")
		(net "M_H_CPU1_SB_DQ<7>")
	)
	(segment
		(start 199.503284 -223.41586)
		(end 198.226426 -222.661226)
		(width 0.18288)
		(layer "In11.Cu")
		(net "M_H_CPU1_SB_DQ<7>")
	)
	(segment
		(start 143.620998 -234.270804)
		(end 140.532358 -234.270804)
		(width 0.18288)
		(layer "In11.Cu")
		(net "M_H_CPU1_SB_DQ<7>")
	)
	(segment
		(start 177.965354 -218.436698)
		(end 177.411126 -218.990926)
		(width 0.18288)
		(layer "In11.Cu")
		(net "M_H_CPU1_SB_DQ<7>")
	)
	(segment
		(start 125.460506 -235.291122)
		(end 125.454664 -235.294424)
		(width 0.088646)
		(layer "In11.Cu")
		(net "M_H_CPU1_SB_DQ<7>")
	)
	(segment
		(start 195.25615 -220.702378)
		(end 194.446398 -219.892626)
		(width 0.18288)
		(layer "In11.Cu")
		(net "M_H_CPU1_SB_DQ<7>")
	)
	(segment
		(start 128.839214 -235.294424)
		(end 128.824482 -235.285788)
		(width 0.088646)
		(layer "In11.Cu")
		(net "M_H_CPU1_SB_DQ<7>")
	)
	(segment
		(start 130.718814 -235.294424)
		(end 130.704082 -235.285788)
		(width 0.088646)
		(layer "In11.Cu")
		(net "M_H_CPU1_SB_DQ<7>")
	)
	(segment
		(start 205.391004 -222.79356)
		(end 204.94117 -223.243394)
		(width 0.18288)
		(layer "In11.Cu")
		(net "M_H_CPU1_SB_DQ<7>")
	)
	(segment
		(start 187.399168 -217.29065)
		(end 186.559444 -218.130374)
		(width 0.18288)
		(layer "In11.Cu")
		(net "M_H_CPU1_SB_DQ<7>")
	)
	(segment
		(start 174.012606 -219.227146)
		(end 173.232826 -219.841826)
		(width 0.18288)
		(layer "In11.Cu")
		(net "M_H_CPU1_SB_DQ<7>")
	)
	(segment
		(start 207.071214 -223.666558)
		(end 206.1972 -222.79356)
		(width 0.18288)
		(layer "In11.Cu")
		(net "M_H_CPU1_SB_DQ<7>")
	)
	(segment
		(start 139.496038 -235.38688)
		(end 138.356848 -235.38688)
		(width 0.088646)
		(layer "In11.Cu")
		(net "M_H_CPU1_SB_DQ<7>")
	)
	(segment
		(start 164.866574 -219.432886)
		(end 164.381434 -219.918026)
		(width 0.18288)
		(layer "In11.Cu")
		(net "M_H_CPU1_SB_DQ<7>")
	)
	(segment
		(start 173.232826 -219.841826)
		(end 172.229526 -219.841826)
		(width 0.18288)
		(layer "In11.Cu")
		(net "M_H_CPU1_SB_DQ<7>")
	)
	(segment
		(start 181.861968 -218.436698)
		(end 177.965354 -218.436698)
		(width 0.18288)
		(layer "In11.Cu")
		(net "M_H_CPU1_SB_DQ<7>")
	)
	(segment
		(start 133.538468 -235.294424)
		(end 133.528054 -235.288328)
		(width 0.088646)
		(layer "In11.Cu")
		(net "M_H_CPU1_SB_DQ<7>")
	)
	(segment
		(start 131.658868 -235.294424)
		(end 131.648454 -235.288328)
		(width 0.088646)
		(layer "In11.Cu")
		(net "M_H_CPU1_SB_DQ<7>")
	)
	(segment
		(start 194.446398 -219.892626)
		(end 193.065146 -219.892626)
		(width 0.18288)
		(layer "In11.Cu")
		(net "M_H_CPU1_SB_DQ<7>")
	)
	(arc
		(start 129.764282 -235.285788)
		(mid 129.487807 -235.218468)
		(end 129.21361 -235.294424)
		(width 0.088646)
		(layer "In11.Cu")
		(net "M_H_CPU1_SB_DQ<7>")
	)
	(arc
		(start 132.97281 -235.294424)
		(mid 132.785612 -235.344567)
		(end 132.598414 -235.294424)
		(width 0.088646)
		(layer "In11.Cu")
		(net "M_H_CPU1_SB_DQ<7>")
	)
	(arc
		(start 131.648454 -235.288328)
		(mid 131.370022 -235.218482)
		(end 131.09321 -235.294424)
		(width 0.088646)
		(layer "In11.Cu")
		(net "M_H_CPU1_SB_DQ<7>")
	)
	(arc
		(start 125.454664 -235.294424)
		(mid 125.267466 -235.344567)
		(end 125.080268 -235.294424)
		(width 0.088646)
		(layer "In11.Cu")
		(net "M_H_CPU1_SB_DQ<7>")
	)
	(arc
		(start 127.328422 -235.297726)
		(mid 127.143567 -235.344676)
		(end 126.959614 -235.294424)
		(width 0.088646)
		(layer "In11.Cu")
		(net "M_H_CPU1_SB_DQ<7>")
	)
	(arc
		(start 130.15341 -235.294424)
		(mid 129.966212 -235.344567)
		(end 129.779014 -235.294424)
		(width 0.088646)
		(layer "In11.Cu")
		(net "M_H_CPU1_SB_DQ<7>")
	)
	(arc
		(start 133.912864 -235.294424)
		(mid 133.725666 -235.344567)
		(end 133.538468 -235.294424)
		(width 0.088646)
		(layer "In11.Cu")
		(net "M_H_CPU1_SB_DQ<7>")
	)
	(arc
		(start 132.033264 -235.294424)
		(mid 131.846066 -235.344567)
		(end 131.658868 -235.294424)
		(width 0.088646)
		(layer "In11.Cu")
		(net "M_H_CPU1_SB_DQ<7>")
	)
	(arc
		(start 137.282682 -235.285788)
		(mid 137.006207 -235.218468)
		(end 136.73201 -235.294424)
		(width 0.088646)
		(layer "In11.Cu")
		(net "M_H_CPU1_SB_DQ<7>")
	)
	(arc
		(start 126.959614 -235.294424)
		(mid 126.680411 -235.218784)
		(end 126.400306 -235.291122)
		(width 0.088646)
		(layer "In11.Cu")
		(net "M_H_CPU1_SB_DQ<7>")
	)
	(arc
		(start 132.598414 -235.294424)
		(mid 132.321855 -235.218681)
		(end 132.043678 -235.288328)
		(width 0.088646)
		(layer "In11.Cu")
		(net "M_H_CPU1_SB_DQ<7>")
	)
	(arc
		(start 138.3284 -235.359702)
		(mid 138.284425 -235.324803)
		(end 138.237214 -235.294424)
		(width 0.088646)
		(layer "In11.Cu")
		(net "M_H_CPU1_SB_DQ<7>")
	)
	(arc
		(start 127.899414 -235.294424)
		(mid 127.620211 -235.218784)
		(end 127.340106 -235.291122)
		(width 0.088646)
		(layer "In11.Cu")
		(net "M_H_CPU1_SB_DQ<7>")
	)
	(arc
		(start 134.852664 -235.294424)
		(mid 134.665466 -235.344567)
		(end 134.478268 -235.294424)
		(width 0.088646)
		(layer "In11.Cu")
		(net "M_H_CPU1_SB_DQ<7>")
	)
	(arc
		(start 128.27381 -235.294424)
		(mid 128.086612 -235.344567)
		(end 127.899414 -235.294424)
		(width 0.088646)
		(layer "In11.Cu")
		(net "M_H_CPU1_SB_DQ<7>")
	)
	(arc
		(start 128.824482 -235.285788)
		(mid 128.548007 -235.218468)
		(end 128.27381 -235.294424)
		(width 0.088646)
		(layer "In11.Cu")
		(net "M_H_CPU1_SB_DQ<7>")
	)
	(arc
		(start 124.790708 -235.296456)
		(mid 124.752167 -235.318747)
		(end 124.712984 -235.33989)
		(width 0.088646)
		(layer "In11.Cu")
		(net "M_H_CPU1_SB_DQ<7>")
	)
	(arc
		(start 135.418068 -235.294424)
		(mid 135.135366 -235.218648)
		(end 134.852664 -235.294424)
		(width 0.088646)
		(layer "In11.Cu")
		(net "M_H_CPU1_SB_DQ<7>")
	)
	(arc
		(start 136.73201 -235.294424)
		(mid 136.544812 -235.344567)
		(end 136.357614 -235.294424)
		(width 0.088646)
		(layer "In11.Cu")
		(net "M_H_CPU1_SB_DQ<7>")
	)
	(arc
		(start 138.354308 -235.384086)
		(mid 138.341547 -235.371689)
		(end 138.3284 -235.359702)
		(width 0.088646)
		(layer "In11.Cu")
		(net "M_H_CPU1_SB_DQ<7>")
	)
	(arc
		(start 137.67181 -235.294424)
		(mid 137.484612 -235.344567)
		(end 137.297414 -235.294424)
		(width 0.088646)
		(layer "In11.Cu")
		(net "M_H_CPU1_SB_DQ<7>")
	)
	(arc
		(start 131.09321 -235.294424)
		(mid 130.906012 -235.344567)
		(end 130.718814 -235.294424)
		(width 0.088646)
		(layer "In11.Cu")
		(net "M_H_CPU1_SB_DQ<7>")
	)
	(arc
		(start 130.704082 -235.285788)
		(mid 130.427607 -235.218468)
		(end 130.15341 -235.294424)
		(width 0.088646)
		(layer "In11.Cu")
		(net "M_H_CPU1_SB_DQ<7>")
	)
	(arc
		(start 125.080268 -235.294424)
		(mid 124.935218 -235.256109)
		(end 124.790708 -235.296456)
		(width 0.088646)
		(layer "In11.Cu")
		(net "M_H_CPU1_SB_DQ<7>")
	)
	(arc
		(start 135.792464 -235.294424)
		(mid 135.605266 -235.344567)
		(end 135.418068 -235.294424)
		(width 0.088646)
		(layer "In11.Cu")
		(net "M_H_CPU1_SB_DQ<7>")
	)
	(arc
		(start 138.222482 -235.285788)
		(mid 137.946007 -235.218468)
		(end 137.67181 -235.294424)
		(width 0.088646)
		(layer "In11.Cu")
		(net "M_H_CPU1_SB_DQ<7>")
	)
	(arc
		(start 126.019814 -235.294424)
		(mid 125.740611 -235.218784)
		(end 125.460506 -235.291122)
		(width 0.088646)
		(layer "In11.Cu")
		(net "M_H_CPU1_SB_DQ<7>")
	)
	(arc
		(start 133.528054 -235.288328)
		(mid 133.249622 -235.218482)
		(end 132.97281 -235.294424)
		(width 0.088646)
		(layer "In11.Cu")
		(net "M_H_CPU1_SB_DQ<7>")
	)
	(arc
		(start 134.478268 -235.294424)
		(mid 134.195566 -235.218648)
		(end 133.912864 -235.294424)
		(width 0.088646)
		(layer "In11.Cu")
		(net "M_H_CPU1_SB_DQ<7>")
	)
	(arc
		(start 136.3472 -235.288328)
		(mid 136.069022 -235.218605)
		(end 135.792464 -235.294424)
		(width 0.088646)
		(layer "In11.Cu")
		(net "M_H_CPU1_SB_DQ<7>")
	)
	(arc
		(start 126.388622 -235.297726)
		(mid 126.203767 -235.344676)
		(end 126.019814 -235.294424)
		(width 0.088646)
		(layer "In11.Cu")
		(net "M_H_CPU1_SB_DQ<7>")
	)
	(arc
		(start 129.21361 -235.294424)
		(mid 129.026412 -235.344567)
		(end 128.839214 -235.294424)
		(width 0.088646)
		(layer "In11.Cu")
		(net "M_H_CPU1_SB_DQ<7>")
	)
	(segment
		(start 213.515448 -225.3488)
		(end 213.749636 -225.114612)
		(width 0.20066)
		(layer "F.Cu")
		(net "M_H_CPU1_SB_DQ<6>")
	)
	(segment
		(start 214.133684 -225.114612)
		(end 214.385652 -225.36658)
		(width 0.20066)
		(layer "F.Cu")
		(net "M_H_CPU1_SB_DQ<6>")
	)
	(segment
		(start 207.071214 -225.36658)
		(end 208.176114 -225.36658)
		(width 0.20066)
		(layer "F.Cu")
		(net "M_H_CPU1_SB_DQ<6>")
	)
	(segment
		(start 212.630258 -225.803714)
		(end 213.311486 -225.803714)
		(width 0.20066)
		(layer "F.Cu")
		(net "M_H_CPU1_SB_DQ<6>")
	)
	(segment
		(start 212.618066 -225.791522)
		(end 212.630258 -225.803714)
		(width 0.1016)
		(layer "F.Cu")
		(net "M_H_CPU1_SB_DQ<6>")
	)
	(segment
		(start 208.176114 -225.36658)
		(end 209.874358 -225.36658)
		(width 0.20066)
		(layer "F.Cu")
		(net "M_H_CPU1_SB_DQ<6>")
	)
	(segment
		(start 125.267212 -237.133638)
		(end 125.267212 -236.597952)
		(width 0.20066)
		(layer "F.Cu")
		(net "M_H_CPU1_SB_DQ<6>")
	)
	(segment
		(start 210.610196 -225.791522)
		(end 212.618066 -225.791522)
		(width 0.1016)
		(layer "F.Cu")
		(net "M_H_CPU1_SB_DQ<6>")
	)
	(segment
		(start 210.598258 -225.798634)
		(end 210.603084 -225.798634)
		(width 0.101854)
		(layer "F.Cu")
		(net "M_H_CPU1_SB_DQ<6>")
	)
	(segment
		(start 214.385652 -225.36658)
		(end 215.719914 -225.36658)
		(width 0.20066)
		(layer "F.Cu")
		(net "M_H_CPU1_SB_DQ<6>")
	)
	(segment
		(start 210.306412 -225.798634)
		(end 210.598258 -225.798634)
		(width 0.20066)
		(layer "F.Cu")
		(net "M_H_CPU1_SB_DQ<6>")
	)
	(segment
		(start 209.874358 -225.36658)
		(end 210.306412 -225.798634)
		(width 0.20066)
		(layer "F.Cu")
		(net "M_H_CPU1_SB_DQ<6>")
	)
	(segment
		(start 125.267466 -237.133892)
		(end 125.267212 -237.133638)
		(width 0.20066)
		(layer "F.Cu")
		(net "M_H_CPU1_SB_DQ<6>")
	)
	(segment
		(start 213.749636 -225.114612)
		(end 214.133684 -225.114612)
		(width 0.20066)
		(layer "F.Cu")
		(net "M_H_CPU1_SB_DQ<6>")
	)
	(segment
		(start 213.311486 -225.803714)
		(end 213.515448 -225.599752)
		(width 0.20066)
		(layer "F.Cu")
		(net "M_H_CPU1_SB_DQ<6>")
	)
	(segment
		(start 210.603084 -225.798634)
		(end 210.610196 -225.791522)
		(width 0.1016)
		(layer "F.Cu")
		(net "M_H_CPU1_SB_DQ<6>")
	)
	(segment
		(start 213.515448 -225.599752)
		(end 213.515448 -225.3488)
		(width 0.20066)
		(layer "F.Cu")
		(net "M_H_CPU1_SB_DQ<6>")
	)
	(segment
		(start 141.103096 -235.286804)
		(end 140.271246 -235.286804)
		(width 0.088646)
		(layer "In11.Cu")
		(net "M_H_CPU1_SB_DQ<6>")
	)
	(segment
		(start 131.573778 -236.102144)
		(end 131.563364 -236.10824)
		(width 0.088646)
		(layer "In11.Cu")
		(net "M_H_CPU1_SB_DQ<6>")
	)
	(segment
		(start 129.698496 -236.099604)
		(end 129.683764 -236.10824)
		(width 0.088646)
		(layer "In11.Cu")
		(net "M_H_CPU1_SB_DQ<6>")
	)
	(segment
		(start 130.638296 -236.099604)
		(end 130.623564 -236.10824)
		(width 0.088646)
		(layer "In11.Cu")
		(net "M_H_CPU1_SB_DQ<6>")
	)
	(segment
		(start 181.250844 -219.704666)
		(end 181.057804 -219.511626)
		(width 0.18288)
		(layer "In11.Cu")
		(net "M_H_CPU1_SB_DQ<6>")
	)
	(segment
		(start 166.979092 -221.53118)
		(end 164.838126 -221.53118)
		(width 0.18288)
		(layer "In11.Cu")
		(net "M_H_CPU1_SB_DQ<6>")
	)
	(segment
		(start 207.071214 -225.36658)
		(end 206.063342 -224.358708)
		(width 0.18288)
		(layer "In11.Cu")
		(net "M_H_CPU1_SB_DQ<6>")
	)
	(segment
		(start 191.924178 -220.690948)
		(end 191.923162 -220.689932)
		(width 0.18288)
		(layer "In11.Cu")
		(net "M_H_CPU1_SB_DQ<6>")
	)
	(segment
		(start 168.680892 -221.676976)
		(end 168.543986 -221.54007)
		(width 0.18288)
		(layer "In11.Cu")
		(net "M_H_CPU1_SB_DQ<6>")
	)
	(segment
		(start 164.838126 -221.53118)
		(end 164.64788 -221.721426)
		(width 0.18288)
		(layer "In11.Cu")
		(net "M_H_CPU1_SB_DQ<6>")
	)
	(segment
		(start 195.429886 -222.585026)
		(end 194.464686 -221.619826)
		(width 0.18288)
		(layer "In11.Cu")
		(net "M_H_CPU1_SB_DQ<6>")
	)
	(segment
		(start 144.095724 -235.286804)
		(end 141.103096 -235.286804)
		(width 0.18288)
		(layer "In11.Cu")
		(net "M_H_CPU1_SB_DQ<6>")
	)
	(segment
		(start 181.250844 -220.206062)
		(end 181.250844 -219.704666)
		(width 0.18288)
		(layer "In11.Cu")
		(net "M_H_CPU1_SB_DQ<6>")
	)
	(segment
		(start 181.954424 -219.704666)
		(end 181.954424 -220.206062)
		(width 0.18288)
		(layer "In11.Cu")
		(net "M_H_CPU1_SB_DQ<6>")
	)
	(segment
		(start 188.033406 -219.840048)
		(end 188.032644 -219.84081)
		(width 0.18288)
		(layer "In11.Cu")
		(net "M_H_CPU1_SB_DQ<6>")
	)
	(segment
		(start 126.879096 -236.099604)
		(end 126.864364 -236.10824)
		(width 0.088646)
		(layer "In11.Cu")
		(net "M_H_CPU1_SB_DQ<6>")
	)
	(segment
		(start 176.69256 -220.689932)
		(end 175.86452 -220.689932)
		(width 0.18288)
		(layer "In11.Cu")
		(net "M_H_CPU1_SB_DQ<6>")
	)
	(segment
		(start 198.226426 -224.210626)
		(end 197.515226 -224.210626)
		(width 0.18288)
		(layer "In11.Cu")
		(net "M_H_CPU1_SB_DQ<6>")
	)
	(segment
		(start 187.193682 -219.840048)
		(end 187.072778 -219.960952)
		(width 0.18288)
		(layer "In11.Cu")
		(net "M_H_CPU1_SB_DQ<6>")
	)
	(segment
		(start 168.543986 -221.54007)
		(end 166.987982 -221.54007)
		(width 0.18288)
		(layer "In11.Cu")
		(net "M_H_CPU1_SB_DQ<6>")
	)
	(segment
		(start 176.693576 -220.690948)
		(end 176.69256 -220.689932)
		(width 0.18288)
		(layer "In11.Cu")
		(net "M_H_CPU1_SB_DQ<6>")
	)
	(segment
		(start 191.923162 -220.689932)
		(end 191.479932 -220.689932)
		(width 0.18288)
		(layer "In11.Cu")
		(net "M_H_CPU1_SB_DQ<6>")
	)
	(segment
		(start 199.090026 -225.074226)
		(end 198.226426 -224.210626)
		(width 0.18288)
		(layer "In11.Cu")
		(net "M_H_CPU1_SB_DQ<6>")
	)
	(segment
		(start 135.337296 -236.099604)
		(end 135.322564 -236.10824)
		(width 0.088646)
		(layer "In11.Cu")
		(net "M_H_CPU1_SB_DQ<6>")
	)
	(segment
		(start 187.680346 -219.840048)
		(end 187.193682 -219.840048)
		(width 0.18288)
		(layer "In11.Cu")
		(net "M_H_CPU1_SB_DQ<6>")
	)
	(segment
		(start 194.464686 -221.619826)
		(end 193.310002 -221.619826)
		(width 0.18288)
		(layer "In11.Cu")
		(net "M_H_CPU1_SB_DQ<6>")
	)
	(segment
		(start 183.062626 -219.511626)
		(end 182.147464 -219.511626)
		(width 0.18288)
		(layer "In11.Cu")
		(net "M_H_CPU1_SB_DQ<6>")
	)
	(segment
		(start 181.954424 -220.206062)
		(end 181.761384 -220.399102)
		(width 0.18288)
		(layer "In11.Cu")
		(net "M_H_CPU1_SB_DQ<6>")
	)
	(segment
		(start 175.722026 -220.832426)
		(end 174.299626 -220.832426)
		(width 0.18288)
		(layer "In11.Cu")
		(net "M_H_CPU1_SB_DQ<6>")
	)
	(segment
		(start 190.630048 -219.840048)
		(end 188.033406 -219.840048)
		(width 0.18288)
		(layer "In11.Cu")
		(net "M_H_CPU1_SB_DQ<6>")
	)
	(segment
		(start 159.382714 -222.508826)
		(end 158.747714 -223.143826)
		(width 0.18288)
		(layer "In11.Cu")
		(net "M_H_CPU1_SB_DQ<6>")
	)
	(segment
		(start 197.515226 -224.210626)
		(end 195.889626 -222.585026)
		(width 0.18288)
		(layer "In11.Cu")
		(net "M_H_CPU1_SB_DQ<6>")
	)
	(segment
		(start 201.960226 -225.074226)
		(end 199.090026 -225.074226)
		(width 0.18288)
		(layer "In11.Cu")
		(net "M_H_CPU1_SB_DQ<6>")
	)
	(segment
		(start 183.511952 -219.960952)
		(end 183.062626 -219.511626)
		(width 0.18288)
		(layer "In11.Cu")
		(net "M_H_CPU1_SB_DQ<6>")
	)
	(segment
		(start 182.147464 -219.511626)
		(end 181.954424 -219.704666)
		(width 0.18288)
		(layer "In11.Cu")
		(net "M_H_CPU1_SB_DQ<6>")
	)
	(segment
		(start 204.364844 -224.358708)
		(end 203.781406 -224.942146)
		(width 0.18288)
		(layer "In11.Cu")
		(net "M_H_CPU1_SB_DQ<6>")
	)
	(segment
		(start 177.743104 -220.690948)
		(end 176.693576 -220.690948)
		(width 0.18288)
		(layer "In11.Cu")
		(net "M_H_CPU1_SB_DQ<6>")
	)
	(segment
		(start 139.525502 -236.032548)
		(end 138.424412 -236.032548)
		(width 0.088646)
		(layer "In11.Cu")
		(net "M_H_CPU1_SB_DQ<6>")
	)
	(segment
		(start 187.072778 -219.960952)
		(end 183.511952 -219.960952)
		(width 0.18288)
		(layer "In11.Cu")
		(net "M_H_CPU1_SB_DQ<6>")
	)
	(segment
		(start 171.989242 -221.54261)
		(end 171.854876 -221.676976)
		(width 0.18288)
		(layer "In11.Cu")
		(net "M_H_CPU1_SB_DQ<6>")
	)
	(segment
		(start 203.781406 -224.942146)
		(end 202.092306 -224.942146)
		(width 0.18288)
		(layer "In11.Cu")
		(net "M_H_CPU1_SB_DQ<6>")
	)
	(segment
		(start 193.310002 -221.619826)
		(end 192.381124 -220.690948)
		(width 0.18288)
		(layer "In11.Cu")
		(net "M_H_CPU1_SB_DQ<6>")
	)
	(segment
		(start 192.381124 -220.690948)
		(end 191.924178 -220.690948)
		(width 0.18288)
		(layer "In11.Cu")
		(net "M_H_CPU1_SB_DQ<6>")
	)
	(segment
		(start 202.092306 -224.942146)
		(end 201.960226 -225.074226)
		(width 0.18288)
		(layer "In11.Cu")
		(net "M_H_CPU1_SB_DQ<6>")
	)
	(segment
		(start 181.443884 -220.399102)
		(end 181.250844 -220.206062)
		(width 0.18288)
		(layer "In11.Cu")
		(net "M_H_CPU1_SB_DQ<6>")
	)
	(segment
		(start 140.271246 -235.286804)
		(end 139.525502 -236.032548)
		(width 0.088646)
		(layer "In11.Cu")
		(net "M_H_CPU1_SB_DQ<6>")
	)
	(segment
		(start 195.889626 -222.585026)
		(end 195.429886 -222.585026)
		(width 0.18288)
		(layer "In11.Cu")
		(net "M_H_CPU1_SB_DQ<6>")
	)
	(segment
		(start 187.681108 -219.84081)
		(end 187.680346 -219.840048)
		(width 0.18288)
		(layer "In11.Cu")
		(net "M_H_CPU1_SB_DQ<6>")
	)
	(segment
		(start 158.747714 -223.143826)
		(end 156.238702 -223.143826)
		(width 0.18288)
		(layer "In11.Cu")
		(net "M_H_CPU1_SB_DQ<6>")
	)
	(segment
		(start 181.057804 -219.511626)
		(end 179.786026 -219.511626)
		(width 0.18288)
		(layer "In11.Cu")
		(net "M_H_CPU1_SB_DQ<6>")
	)
	(segment
		(start 179.303426 -219.994226)
		(end 178.439826 -219.994226)
		(width 0.18288)
		(layer "In11.Cu")
		(net "M_H_CPU1_SB_DQ<6>")
	)
	(segment
		(start 125.934724 -236.102144)
		(end 125.895608 -236.125004)
		(width 0.088646)
		(layer "In11.Cu")
		(net "M_H_CPU1_SB_DQ<6>")
	)
	(segment
		(start 178.439826 -219.994226)
		(end 177.743104 -220.690948)
		(width 0.18288)
		(layer "In11.Cu")
		(net "M_H_CPU1_SB_DQ<6>")
	)
	(segment
		(start 127.818896 -236.099604)
		(end 127.804164 -236.10824)
		(width 0.088646)
		(layer "In11.Cu")
		(net "M_H_CPU1_SB_DQ<6>")
	)
	(segment
		(start 179.786026 -219.511626)
		(end 179.303426 -219.994226)
		(width 0.18288)
		(layer "In11.Cu")
		(net "M_H_CPU1_SB_DQ<6>")
	)
	(segment
		(start 156.238702 -223.143826)
		(end 144.095724 -235.286804)
		(width 0.18288)
		(layer "In11.Cu")
		(net "M_H_CPU1_SB_DQ<6>")
	)
	(segment
		(start 181.761384 -220.399102)
		(end 181.443884 -220.399102)
		(width 0.18288)
		(layer "In11.Cu")
		(net "M_H_CPU1_SB_DQ<6>")
	)
	(segment
		(start 160.443926 -222.508826)
		(end 159.382714 -222.508826)
		(width 0.18288)
		(layer "In11.Cu")
		(net "M_H_CPU1_SB_DQ<6>")
	)
	(segment
		(start 132.513324 -236.102144)
		(end 132.50291 -236.10824)
		(width 0.088646)
		(layer "In11.Cu")
		(net "M_H_CPU1_SB_DQ<6>")
	)
	(segment
		(start 161.231326 -221.721426)
		(end 160.443926 -222.508826)
		(width 0.18288)
		(layer "In11.Cu")
		(net "M_H_CPU1_SB_DQ<6>")
	)
	(segment
		(start 188.032644 -219.84081)
		(end 187.681108 -219.84081)
		(width 0.18288)
		(layer "In11.Cu")
		(net "M_H_CPU1_SB_DQ<6>")
	)
	(segment
		(start 173.589442 -221.54261)
		(end 171.989242 -221.54261)
		(width 0.18288)
		(layer "In11.Cu")
		(net "M_H_CPU1_SB_DQ<6>")
	)
	(segment
		(start 125.838712 -236.168946)
		(end 125.267212 -236.597952)
		(width 0.088646)
		(layer "In11.Cu")
		(net "M_H_CPU1_SB_DQ<6>")
	)
	(segment
		(start 137.216896 -236.099604)
		(end 137.202164 -236.10824)
		(width 0.088646)
		(layer "In11.Cu")
		(net "M_H_CPU1_SB_DQ<6>")
	)
	(segment
		(start 174.299626 -220.832426)
		(end 173.589442 -221.54261)
		(width 0.18288)
		(layer "In11.Cu")
		(net "M_H_CPU1_SB_DQ<6>")
	)
	(segment
		(start 191.479932 -220.689932)
		(end 190.630048 -219.840048)
		(width 0.18288)
		(layer "In11.Cu")
		(net "M_H_CPU1_SB_DQ<6>")
	)
	(segment
		(start 164.64788 -221.721426)
		(end 161.231326 -221.721426)
		(width 0.18288)
		(layer "In11.Cu")
		(net "M_H_CPU1_SB_DQ<6>")
	)
	(segment
		(start 175.86452 -220.689932)
		(end 175.722026 -220.832426)
		(width 0.18288)
		(layer "In11.Cu")
		(net "M_H_CPU1_SB_DQ<6>")
	)
	(segment
		(start 136.277096 -236.099604)
		(end 136.262364 -236.10824)
		(width 0.088646)
		(layer "In11.Cu")
		(net "M_H_CPU1_SB_DQ<6>")
	)
	(segment
		(start 206.063342 -224.358708)
		(end 204.364844 -224.358708)
		(width 0.18288)
		(layer "In11.Cu")
		(net "M_H_CPU1_SB_DQ<6>")
	)
	(segment
		(start 171.854876 -221.676976)
		(end 168.680892 -221.676976)
		(width 0.18288)
		(layer "In11.Cu")
		(net "M_H_CPU1_SB_DQ<6>")
	)
	(segment
		(start 166.987982 -221.54007)
		(end 166.979092 -221.53118)
		(width 0.18288)
		(layer "In11.Cu")
		(net "M_H_CPU1_SB_DQ<6>")
	)
	(arc
		(start 129.309368 -236.10824)
		(mid 129.026666 -236.032498)
		(end 128.743964 -236.10824)
		(width 0.088646)
		(layer "In11.Cu")
		(net "M_H_CPU1_SB_DQ<6>")
	)
	(arc
		(start 136.262364 -236.10824)
		(mid 136.075166 -236.158383)
		(end 135.887968 -236.10824)
		(width 0.088646)
		(layer "In11.Cu")
		(net "M_H_CPU1_SB_DQ<6>")
	)
	(arc
		(start 132.50291 -236.10824)
		(mid 132.315712 -236.158383)
		(end 132.128514 -236.10824)
		(width 0.088646)
		(layer "In11.Cu")
		(net "M_H_CPU1_SB_DQ<6>")
	)
	(arc
		(start 126.864364 -236.10824)
		(mid 126.677166 -236.158383)
		(end 126.489968 -236.10824)
		(width 0.088646)
		(layer "In11.Cu")
		(net "M_H_CPU1_SB_DQ<6>")
	)
	(arc
		(start 126.489968 -236.10824)
		(mid 126.213155 -236.032404)
		(end 125.934724 -236.102144)
		(width 0.088646)
		(layer "In11.Cu")
		(net "M_H_CPU1_SB_DQ<6>")
	)
	(arc
		(start 128.743964 -236.10824)
		(mid 128.556766 -236.158383)
		(end 128.369568 -236.10824)
		(width 0.088646)
		(layer "In11.Cu")
		(net "M_H_CPU1_SB_DQ<6>")
	)
	(arc
		(start 137.767568 -236.10824)
		(mid 137.493339 -236.032315)
		(end 137.216896 -236.099604)
		(width 0.088646)
		(layer "In11.Cu")
		(net "M_H_CPU1_SB_DQ<6>")
	)
	(arc
		(start 137.202164 -236.10824)
		(mid 137.014966 -236.158383)
		(end 136.827768 -236.10824)
		(width 0.088646)
		(layer "In11.Cu")
		(net "M_H_CPU1_SB_DQ<6>")
	)
	(arc
		(start 132.128514 -236.10824)
		(mid 131.851955 -236.032531)
		(end 131.573778 -236.102144)
		(width 0.088646)
		(layer "In11.Cu")
		(net "M_H_CPU1_SB_DQ<6>")
	)
	(arc
		(start 131.563364 -236.10824)
		(mid 131.376166 -236.158383)
		(end 131.188968 -236.10824)
		(width 0.088646)
		(layer "In11.Cu")
		(net "M_H_CPU1_SB_DQ<6>")
	)
	(arc
		(start 127.429768 -236.10824)
		(mid 127.155539 -236.032315)
		(end 126.879096 -236.099604)
		(width 0.088646)
		(layer "In11.Cu")
		(net "M_H_CPU1_SB_DQ<6>")
	)
	(arc
		(start 127.804164 -236.10824)
		(mid 127.616966 -236.158383)
		(end 127.429768 -236.10824)
		(width 0.088646)
		(layer "In11.Cu")
		(net "M_H_CPU1_SB_DQ<6>")
	)
	(arc
		(start 133.068568 -236.10824)
		(mid 132.791755 -236.032404)
		(end 132.513324 -236.102144)
		(width 0.088646)
		(layer "In11.Cu")
		(net "M_H_CPU1_SB_DQ<6>")
	)
	(arc
		(start 135.322564 -236.10824)
		(mid 135.135366 -236.158383)
		(end 134.948168 -236.10824)
		(width 0.088646)
		(layer "In11.Cu")
		(net "M_H_CPU1_SB_DQ<6>")
	)
	(arc
		(start 135.887968 -236.10824)
		(mid 135.613739 -236.032315)
		(end 135.337296 -236.099604)
		(width 0.088646)
		(layer "In11.Cu")
		(net "M_H_CPU1_SB_DQ<6>")
	)
	(arc
		(start 129.683764 -236.10824)
		(mid 129.496566 -236.158383)
		(end 129.309368 -236.10824)
		(width 0.088646)
		(layer "In11.Cu")
		(net "M_H_CPU1_SB_DQ<6>")
	)
	(arc
		(start 138.141964 -236.10824)
		(mid 137.954766 -236.158383)
		(end 137.767568 -236.10824)
		(width 0.088646)
		(layer "In11.Cu")
		(net "M_H_CPU1_SB_DQ<6>")
	)
	(arc
		(start 134.948168 -236.10824)
		(mid 134.665466 -236.032498)
		(end 134.382764 -236.10824)
		(width 0.088646)
		(layer "In11.Cu")
		(net "M_H_CPU1_SB_DQ<6>")
	)
	(arc
		(start 133.442964 -236.10824)
		(mid 133.255766 -236.158383)
		(end 133.068568 -236.10824)
		(width 0.088646)
		(layer "In11.Cu")
		(net "M_H_CPU1_SB_DQ<6>")
	)
	(arc
		(start 134.382764 -236.10824)
		(mid 134.195566 -236.158383)
		(end 134.008368 -236.10824)
		(width 0.088646)
		(layer "In11.Cu")
		(net "M_H_CPU1_SB_DQ<6>")
	)
	(arc
		(start 138.424412 -236.032548)
		(mid 138.278216 -236.051835)
		(end 138.141964 -236.10824)
		(width 0.088646)
		(layer "In11.Cu")
		(net "M_H_CPU1_SB_DQ<6>")
	)
	(arc
		(start 131.188968 -236.10824)
		(mid 130.914739 -236.032315)
		(end 130.638296 -236.099604)
		(width 0.088646)
		(layer "In11.Cu")
		(net "M_H_CPU1_SB_DQ<6>")
	)
	(arc
		(start 125.895608 -236.125004)
		(mid 125.865753 -236.145153)
		(end 125.838712 -236.168946)
		(width 0.088646)
		(layer "In11.Cu")
		(net "M_H_CPU1_SB_DQ<6>")
	)
	(arc
		(start 130.249168 -236.10824)
		(mid 129.974939 -236.032315)
		(end 129.698496 -236.099604)
		(width 0.088646)
		(layer "In11.Cu")
		(net "M_H_CPU1_SB_DQ<6>")
	)
	(arc
		(start 136.827768 -236.10824)
		(mid 136.553539 -236.032315)
		(end 136.277096 -236.099604)
		(width 0.088646)
		(layer "In11.Cu")
		(net "M_H_CPU1_SB_DQ<6>")
	)
	(arc
		(start 128.369568 -236.10824)
		(mid 128.095339 -236.032315)
		(end 127.818896 -236.099604)
		(width 0.088646)
		(layer "In11.Cu")
		(net "M_H_CPU1_SB_DQ<6>")
	)
	(arc
		(start 130.623564 -236.10824)
		(mid 130.436366 -236.158383)
		(end 130.249168 -236.10824)
		(width 0.088646)
		(layer "In11.Cu")
		(net "M_H_CPU1_SB_DQ<6>")
	)
	(arc
		(start 134.008368 -236.10824)
		(mid 133.725666 -236.032498)
		(end 133.442964 -236.10824)
		(width 0.088646)
		(layer "In11.Cu")
		(net "M_H_CPU1_SB_DQ<6>")
	)
	(segment
		(start 209.186526 -224.085404)
		(end 209.180176 -224.091754)
		(width 0.1016)
		(layer "F.Cu")
		(net "M_H_CPU1_SB_DQ<5>")
	)
	(segment
		(start 206.508604 -224.209864)
		(end 206.508604 -224.577402)
		(width 0.20066)
		(layer "F.Cu")
		(net "M_H_CPU1_SB_DQ<5>")
	)
	(segment
		(start 206.626714 -224.091754)
		(end 206.508604 -224.209864)
		(width 0.20066)
		(layer "F.Cu")
		(net "M_H_CPU1_SB_DQ<5>")
	)
	(segment
		(start 205.84541 -224.765362)
		(end 205.596744 -224.516696)
		(width 0.20066)
		(layer "F.Cu")
		(net "M_H_CPU1_SB_DQ<5>")
	)
	(segment
		(start 211.619592 -224.51695)
		(end 210.028028 -224.51695)
		(width 0.20066)
		(layer "F.Cu")
		(net "M_H_CPU1_SB_DQ<5>")
	)
	(segment
		(start 124.797566 -236.319568)
		(end 124.797566 -235.783882)
		(width 0.20066)
		(layer "F.Cu")
		(net "M_H_CPU1_SB_DQ<5>")
	)
	(segment
		(start 209.596482 -224.085404)
		(end 209.186526 -224.085404)
		(width 0.20066)
		(layer "F.Cu")
		(net "M_H_CPU1_SB_DQ<5>")
	)
	(segment
		(start 209.180176 -224.091754)
		(end 206.991458 -224.091754)
		(width 0.1016)
		(layer "F.Cu")
		(net "M_H_CPU1_SB_DQ<5>")
	)
	(segment
		(start 206.991458 -224.091754)
		(end 206.971392 -224.091754)
		(width 0.101854)
		(layer "F.Cu")
		(net "M_H_CPU1_SB_DQ<5>")
	)
	(segment
		(start 206.971392 -224.091754)
		(end 206.626714 -224.091754)
		(width 0.20066)
		(layer "F.Cu")
		(net "M_H_CPU1_SB_DQ<5>")
	)
	(segment
		(start 210.028028 -224.51695)
		(end 209.596482 -224.085404)
		(width 0.20066)
		(layer "F.Cu")
		(net "M_H_CPU1_SB_DQ<5>")
	)
	(segment
		(start 206.508604 -224.577402)
		(end 206.320644 -224.765362)
		(width 0.20066)
		(layer "F.Cu")
		(net "M_H_CPU1_SB_DQ<5>")
	)
	(segment
		(start 204.076046 -224.516696)
		(end 202.971146 -224.516696)
		(width 0.20066)
		(layer "F.Cu")
		(net "M_H_CPU1_SB_DQ<5>")
	)
	(segment
		(start 205.596744 -224.516696)
		(end 204.076046 -224.516696)
		(width 0.20066)
		(layer "F.Cu")
		(net "M_H_CPU1_SB_DQ<5>")
	)
	(segment
		(start 124.797312 -236.319822)
		(end 124.797566 -236.319568)
		(width 0.20066)
		(layer "F.Cu")
		(net "M_H_CPU1_SB_DQ<5>")
	)
	(segment
		(start 211.619846 -224.516696)
		(end 211.619592 -224.51695)
		(width 0.20066)
		(layer "F.Cu")
		(net "M_H_CPU1_SB_DQ<5>")
	)
	(segment
		(start 206.320644 -224.765362)
		(end 205.84541 -224.765362)
		(width 0.20066)
		(layer "F.Cu")
		(net "M_H_CPU1_SB_DQ<5>")
	)
	(segment
		(start 126.495556 -235.456222)
		(end 126.483872 -235.462826)
		(width 0.088646)
		(layer "In11.Cu")
		(net "M_H_CPU1_SB_DQ<5>")
	)
	(segment
		(start 189.647576 -219.325952)
		(end 189.330076 -219.325952)
		(width 0.18288)
		(layer "In11.Cu")
		(net "M_H_CPU1_SB_DQ<5>")
	)
	(segment
		(start 191.920876 -219.840048)
		(end 191.591184 -219.840048)
		(width 0.18288)
		(layer "In11.Cu")
		(net "M_H_CPU1_SB_DQ<5>")
	)
	(segment
		(start 173.476666 -220.690186)
		(end 172.150786 -220.690186)
		(width 0.18288)
		(layer "In11.Cu")
		(net "M_H_CPU1_SB_DQ<5>")
	)
	(segment
		(start 166.50081 -220.690186)
		(end 166.50081 -220.272864)
		(width 0.18288)
		(layer "In11.Cu")
		(net "M_H_CPU1_SB_DQ<5>")
	)
	(segment
		(start 161.300922 -220.578426)
		(end 160.437322 -221.442026)
		(width 0.18288)
		(layer "In11.Cu")
		(net "M_H_CPU1_SB_DQ<5>")
	)
	(segment
		(start 195.255896 -221.443296)
		(end 194.343274 -220.530674)
		(width 0.18288)
		(layer "In11.Cu")
		(net "M_H_CPU1_SB_DQ<5>")
	)
	(segment
		(start 186.93638 -218.642438)
		(end 186.267852 -218.642438)
		(width 0.18288)
		(layer "In11.Cu")
		(net "M_H_CPU1_SB_DQ<5>")
	)
	(segment
		(start 183.646826 -218.952826)
		(end 178.541426 -218.952826)
		(width 0.18288)
		(layer "In11.Cu")
		(net "M_H_CPU1_SB_DQ<5>")
	)
	(segment
		(start 137.216896 -235.46816)
		(end 137.202164 -235.459524)
		(width 0.088646)
		(layer "In11.Cu")
		(net "M_H_CPU1_SB_DQ<5>")
	)
	(segment
		(start 158.555182 -222.44177)
		(end 158.37408 -222.622872)
		(width 0.18288)
		(layer "In11.Cu")
		(net "M_H_CPU1_SB_DQ<5>")
	)
	(segment
		(start 185.564272 -219.326206)
		(end 185.371232 -219.133166)
		(width 0.18288)
		(layer "In11.Cu")
		(net "M_H_CPU1_SB_DQ<5>")
	)
	(segment
		(start 191.921638 -219.84081)
		(end 191.920876 -219.840048)
		(width 0.18288)
		(layer "In11.Cu")
		(net "M_H_CPU1_SB_DQ<5>")
	)
	(segment
		(start 194.343274 -220.530674)
		(end 192.957958 -220.530674)
		(width 0.18288)
		(layer "In11.Cu")
		(net "M_H_CPU1_SB_DQ<5>")
	)
	(segment
		(start 178.541426 -218.952826)
		(end 177.654204 -219.840048)
		(width 0.18288)
		(layer "In11.Cu")
		(net "M_H_CPU1_SB_DQ<5>")
	)
	(segment
		(start 158.37408 -222.622872)
		(end 156.022802 -222.622872)
		(width 0.18288)
		(layer "In11.Cu")
		(net "M_H_CPU1_SB_DQ<5>")
	)
	(segment
		(start 166.30777 -220.079824)
		(end 165.99027 -220.079824)
		(width 0.18288)
		(layer "In11.Cu")
		(net "M_H_CPU1_SB_DQ<5>")
	)
	(segment
		(start 166.50081 -220.272864)
		(end 166.30777 -220.079824)
		(width 0.18288)
		(layer "In11.Cu")
		(net "M_H_CPU1_SB_DQ<5>")
	)
	(segment
		(start 136.277096 -235.46816)
		(end 136.262364 -235.459524)
		(width 0.088646)
		(layer "In11.Cu")
		(net "M_H_CPU1_SB_DQ<5>")
	)
	(segment
		(start 132.128514 -235.459524)
		(end 132.1181 -235.46562)
		(width 0.088646)
		(layer "In11.Cu")
		(net "M_H_CPU1_SB_DQ<5>")
	)
	(segment
		(start 164.507926 -220.578426)
		(end 163.393374 -220.578426)
		(width 0.18288)
		(layer "In11.Cu")
		(net "M_H_CPU1_SB_DQ<5>")
	)
	(segment
		(start 185.371232 -219.133166)
		(end 185.371232 -218.835478)
		(width 0.18288)
		(layer "In11.Cu")
		(net "M_H_CPU1_SB_DQ<5>")
	)
	(segment
		(start 159.554926 -221.442026)
		(end 159.325564 -221.671388)
		(width 0.18288)
		(layer "In11.Cu")
		(net "M_H_CPU1_SB_DQ<5>")
	)
	(segment
		(start 130.638296 -235.46816)
		(end 130.623564 -235.459524)
		(width 0.088646)
		(layer "In11.Cu")
		(net "M_H_CPU1_SB_DQ<5>")
	)
	(segment
		(start 168.190926 -220.883226)
		(end 166.69385 -220.883226)
		(width 0.18288)
		(layer "In11.Cu")
		(net "M_H_CPU1_SB_DQ<5>")
	)
	(segment
		(start 183.957214 -218.642438)
		(end 183.646826 -218.952826)
		(width 0.18288)
		(layer "In11.Cu")
		(net "M_H_CPU1_SB_DQ<5>")
	)
	(segment
		(start 202.75042 -224.032826)
		(end 198.836026 -224.032826)
		(width 0.18288)
		(layer "In11.Cu")
		(net "M_H_CPU1_SB_DQ<5>")
	)
	(segment
		(start 127.435356 -235.456222)
		(end 127.423672 -235.462826)
		(width 0.088646)
		(layer "In11.Cu")
		(net "M_H_CPU1_SB_DQ<5>")
	)
	(segment
		(start 162.303714 -220.578426)
		(end 161.300922 -220.578426)
		(width 0.18288)
		(layer "In11.Cu")
		(net "M_H_CPU1_SB_DQ<5>")
	)
	(segment
		(start 162.689794 -221.185486)
		(end 162.496754 -220.992446)
		(width 0.18288)
		(layer "In11.Cu")
		(net "M_H_CPU1_SB_DQ<5>")
	)
	(segment
		(start 162.496754 -220.771466)
		(end 162.303714 -220.578426)
		(width 0.18288)
		(layer "In11.Cu")
		(net "M_H_CPU1_SB_DQ<5>")
	)
	(segment
		(start 165.79723 -220.272864)
		(end 165.79723 -220.690186)
		(width 0.18288)
		(layer "In11.Cu")
		(net "M_H_CPU1_SB_DQ<5>")
	)
	(segment
		(start 159.052768 -221.671388)
		(end 158.746952 -221.365572)
		(width 0.18288)
		(layer "In11.Cu")
		(net "M_H_CPU1_SB_DQ<5>")
	)
	(segment
		(start 141.103096 -234.778804)
		(end 140.426694 -234.778804)
		(width 0.088646)
		(layer "In11.Cu")
		(net "M_H_CPU1_SB_DQ<5>")
	)
	(segment
		(start 159.325564 -221.671388)
		(end 159.052768 -221.671388)
		(width 0.18288)
		(layer "In11.Cu")
		(net "M_H_CPU1_SB_DQ<5>")
	)
	(segment
		(start 185.881772 -219.326206)
		(end 185.564272 -219.326206)
		(width 0.18288)
		(layer "In11.Cu")
		(net "M_H_CPU1_SB_DQ<5>")
	)
	(segment
		(start 127.818896 -235.46816)
		(end 127.804164 -235.459524)
		(width 0.088646)
		(layer "In11.Cu")
		(net "M_H_CPU1_SB_DQ<5>")
	)
	(segment
		(start 192.957958 -220.530674)
		(end 192.268094 -219.84081)
		(width 0.18288)
		(layer "In11.Cu")
		(net "M_H_CPU1_SB_DQ<5>")
	)
	(segment
		(start 185.178192 -218.642438)
		(end 183.957214 -218.642438)
		(width 0.18288)
		(layer "In11.Cu")
		(net "M_H_CPU1_SB_DQ<5>")
	)
	(segment
		(start 188.943996 -218.67495)
		(end 188.820298 -218.67495)
		(width 0.18288)
		(layer "In11.Cu")
		(net "M_H_CPU1_SB_DQ<5>")
	)
	(segment
		(start 158.746952 -221.365572)
		(end 158.474156 -221.365572)
		(width 0.18288)
		(layer "In11.Cu")
		(net "M_H_CPU1_SB_DQ<5>")
	)
	(segment
		(start 132.513324 -235.46562)
		(end 132.50291 -235.459524)
		(width 0.088646)
		(layer "In11.Cu")
		(net "M_H_CPU1_SB_DQ<5>")
	)
	(segment
		(start 158.474156 -221.365572)
		(end 158.249366 -221.590362)
		(width 0.18288)
		(layer "In11.Cu")
		(net "M_H_CPU1_SB_DQ<5>")
	)
	(segment
		(start 202.971146 -224.253552)
		(end 202.75042 -224.032826)
		(width 0.18288)
		(layer "In11.Cu")
		(net "M_H_CPU1_SB_DQ<5>")
	)
	(segment
		(start 202.971146 -224.516696)
		(end 202.971146 -224.253552)
		(width 0.18288)
		(layer "In11.Cu")
		(net "M_H_CPU1_SB_DQ<5>")
	)
	(segment
		(start 158.249366 -221.590362)
		(end 158.249366 -221.863158)
		(width 0.18288)
		(layer "In11.Cu")
		(net "M_H_CPU1_SB_DQ<5>")
	)
	(segment
		(start 198.836026 -224.032826)
		(end 197.997826 -223.194626)
		(width 0.18288)
		(layer "In11.Cu")
		(net "M_H_CPU1_SB_DQ<5>")
	)
	(segment
		(start 192.268094 -219.84081)
		(end 191.921638 -219.84081)
		(width 0.18288)
		(layer "In11.Cu")
		(net "M_H_CPU1_SB_DQ<5>")
	)
	(segment
		(start 197.413626 -223.194626)
		(end 195.662296 -221.443296)
		(width 0.18288)
		(layer "In11.Cu")
		(net "M_H_CPU1_SB_DQ<5>")
	)
	(segment
		(start 140.426694 -234.778804)
		(end 139.628372 -235.577126)
		(width 0.088646)
		(layer "In11.Cu")
		(net "M_H_CPU1_SB_DQ<5>")
	)
	(segment
		(start 138.277854 -235.577126)
		(end 138.219688 -235.51896)
		(width 0.088646)
		(layer "In11.Cu")
		(net "M_H_CPU1_SB_DQ<5>")
	)
	(segment
		(start 197.997826 -223.194626)
		(end 197.413626 -223.194626)
		(width 0.18288)
		(layer "In11.Cu")
		(net "M_H_CPU1_SB_DQ<5>")
	)
	(segment
		(start 165.79723 -220.690186)
		(end 165.60419 -220.883226)
		(width 0.18288)
		(layer "In11.Cu")
		(net "M_H_CPU1_SB_DQ<5>")
	)
	(segment
		(start 174.440342 -219.72651)
		(end 173.476666 -220.690186)
		(width 0.18288)
		(layer "In11.Cu")
		(net "M_H_CPU1_SB_DQ<5>")
	)
	(segment
		(start 166.69385 -220.883226)
		(end 166.50081 -220.690186)
		(width 0.18288)
		(layer "In11.Cu")
		(net "M_H_CPU1_SB_DQ<5>")
	)
	(segment
		(start 168.571926 -220.502226)
		(end 168.190926 -220.883226)
		(width 0.18288)
		(layer "In11.Cu")
		(net "M_H_CPU1_SB_DQ<5>")
	)
	(segment
		(start 189.330076 -219.325952)
		(end 189.137036 -219.132912)
		(width 0.18288)
		(layer "In11.Cu")
		(net "M_H_CPU1_SB_DQ<5>")
	)
	(segment
		(start 125.170692 -235.783882)
		(end 124.797566 -235.783882)
		(width 0.088646)
		(layer "In11.Cu")
		(net "M_H_CPU1_SB_DQ<5>")
	)
	(segment
		(start 189.840616 -218.86799)
		(end 189.840616 -219.132912)
		(width 0.18288)
		(layer "In11.Cu")
		(net "M_H_CPU1_SB_DQ<5>")
	)
	(segment
		(start 165.60419 -220.883226)
		(end 164.812726 -220.883226)
		(width 0.18288)
		(layer "In11.Cu")
		(net "M_H_CPU1_SB_DQ<5>")
	)
	(segment
		(start 163.200334 -220.771466)
		(end 163.200334 -220.992446)
		(width 0.18288)
		(layer "In11.Cu")
		(net "M_H_CPU1_SB_DQ<5>")
	)
	(segment
		(start 188.820298 -218.67495)
		(end 188.288168 -218.14282)
		(width 0.18288)
		(layer "In11.Cu")
		(net "M_H_CPU1_SB_DQ<5>")
	)
	(segment
		(start 191.591184 -219.840048)
		(end 190.426086 -218.67495)
		(width 0.18288)
		(layer "In11.Cu")
		(net "M_H_CPU1_SB_DQ<5>")
	)
	(segment
		(start 158.555182 -222.168974)
		(end 158.555182 -222.44177)
		(width 0.18288)
		(layer "In11.Cu")
		(net "M_H_CPU1_SB_DQ<5>")
	)
	(segment
		(start 163.200334 -220.992446)
		(end 163.007294 -221.185486)
		(width 0.18288)
		(layer "In11.Cu")
		(net "M_H_CPU1_SB_DQ<5>")
	)
	(segment
		(start 143.86687 -234.778804)
		(end 141.103096 -234.778804)
		(width 0.18288)
		(layer "In11.Cu")
		(net "M_H_CPU1_SB_DQ<5>")
	)
	(segment
		(start 163.007294 -221.185486)
		(end 162.689794 -221.185486)
		(width 0.18288)
		(layer "In11.Cu")
		(net "M_H_CPU1_SB_DQ<5>")
	)
	(segment
		(start 187.435998 -218.14282)
		(end 186.93638 -218.642438)
		(width 0.18288)
		(layer "In11.Cu")
		(net "M_H_CPU1_SB_DQ<5>")
	)
	(segment
		(start 185.371232 -218.835478)
		(end 185.178192 -218.642438)
		(width 0.18288)
		(layer "In11.Cu")
		(net "M_H_CPU1_SB_DQ<5>")
	)
	(segment
		(start 171.962826 -220.502226)
		(end 168.571926 -220.502226)
		(width 0.18288)
		(layer "In11.Cu")
		(net "M_H_CPU1_SB_DQ<5>")
	)
	(segment
		(start 188.288168 -218.14282)
		(end 187.435998 -218.14282)
		(width 0.18288)
		(layer "In11.Cu")
		(net "M_H_CPU1_SB_DQ<5>")
	)
	(segment
		(start 125.472952 -235.518452)
		(end 125.233684 -235.75772)
		(width 0.088646)
		(layer "In11.Cu")
		(net "M_H_CPU1_SB_DQ<5>")
	)
	(segment
		(start 177.654204 -219.840048)
		(end 176.32299 -219.840048)
		(width 0.18288)
		(layer "In11.Cu")
		(net "M_H_CPU1_SB_DQ<5>")
	)
	(segment
		(start 186.074812 -218.835478)
		(end 186.074812 -219.133166)
		(width 0.18288)
		(layer "In11.Cu")
		(net "M_H_CPU1_SB_DQ<5>")
	)
	(segment
		(start 189.137036 -219.132912)
		(end 189.137036 -218.86799)
		(width 0.18288)
		(layer "In11.Cu")
		(net "M_H_CPU1_SB_DQ<5>")
	)
	(segment
		(start 186.267852 -218.642438)
		(end 186.074812 -218.835478)
		(width 0.18288)
		(layer "In11.Cu")
		(net "M_H_CPU1_SB_DQ<5>")
	)
	(segment
		(start 139.628372 -235.577126)
		(end 138.277854 -235.577126)
		(width 0.088646)
		(layer "In11.Cu")
		(net "M_H_CPU1_SB_DQ<5>")
	)
	(segment
		(start 162.496754 -220.992446)
		(end 162.496754 -220.771466)
		(width 0.18288)
		(layer "In11.Cu")
		(net "M_H_CPU1_SB_DQ<5>")
	)
	(segment
		(start 189.137036 -218.86799)
		(end 188.943996 -218.67495)
		(width 0.18288)
		(layer "In11.Cu")
		(net "M_H_CPU1_SB_DQ<5>")
	)
	(segment
		(start 189.840616 -219.132912)
		(end 189.647576 -219.325952)
		(width 0.18288)
		(layer "In11.Cu")
		(net "M_H_CPU1_SB_DQ<5>")
	)
	(segment
		(start 172.150786 -220.690186)
		(end 171.962826 -220.502226)
		(width 0.18288)
		(layer "In11.Cu")
		(net "M_H_CPU1_SB_DQ<5>")
	)
	(segment
		(start 164.812726 -220.883226)
		(end 164.507926 -220.578426)
		(width 0.18288)
		(layer "In11.Cu")
		(net "M_H_CPU1_SB_DQ<5>")
	)
	(segment
		(start 190.033656 -218.67495)
		(end 189.840616 -218.86799)
		(width 0.18288)
		(layer "In11.Cu")
		(net "M_H_CPU1_SB_DQ<5>")
	)
	(segment
		(start 128.758696 -235.46816)
		(end 128.743964 -235.459524)
		(width 0.088646)
		(layer "In11.Cu")
		(net "M_H_CPU1_SB_DQ<5>")
	)
	(segment
		(start 186.074812 -219.133166)
		(end 185.881772 -219.326206)
		(width 0.18288)
		(layer "In11.Cu")
		(net "M_H_CPU1_SB_DQ<5>")
	)
	(segment
		(start 165.99027 -220.079824)
		(end 165.79723 -220.272864)
		(width 0.18288)
		(layer "In11.Cu")
		(net "M_H_CPU1_SB_DQ<5>")
	)
	(segment
		(start 163.393374 -220.578426)
		(end 163.200334 -220.771466)
		(width 0.18288)
		(layer "In11.Cu")
		(net "M_H_CPU1_SB_DQ<5>")
	)
	(segment
		(start 158.249366 -221.863158)
		(end 158.555182 -222.168974)
		(width 0.18288)
		(layer "In11.Cu")
		(net "M_H_CPU1_SB_DQ<5>")
	)
	(segment
		(start 160.437322 -221.442026)
		(end 159.554926 -221.442026)
		(width 0.18288)
		(layer "In11.Cu")
		(net "M_H_CPU1_SB_DQ<5>")
	)
	(segment
		(start 156.022802 -222.622872)
		(end 143.86687 -234.778804)
		(width 0.18288)
		(layer "In11.Cu")
		(net "M_H_CPU1_SB_DQ<5>")
	)
	(segment
		(start 176.32299 -219.840048)
		(end 176.209452 -219.72651)
		(width 0.18288)
		(layer "In11.Cu")
		(net "M_H_CPU1_SB_DQ<5>")
	)
	(segment
		(start 176.209452 -219.72651)
		(end 174.440342 -219.72651)
		(width 0.18288)
		(layer "In11.Cu")
		(net "M_H_CPU1_SB_DQ<5>")
	)
	(segment
		(start 129.698496 -235.46816)
		(end 129.683764 -235.459524)
		(width 0.088646)
		(layer "In11.Cu")
		(net "M_H_CPU1_SB_DQ<5>")
	)
	(segment
		(start 190.426086 -218.67495)
		(end 190.033656 -218.67495)
		(width 0.18288)
		(layer "In11.Cu")
		(net "M_H_CPU1_SB_DQ<5>")
	)
	(segment
		(start 195.662296 -221.443296)
		(end 195.255896 -221.443296)
		(width 0.18288)
		(layer "In11.Cu")
		(net "M_H_CPU1_SB_DQ<5>")
	)
	(arc
		(start 133.442964 -235.459524)
		(mid 133.255766 -235.409381)
		(end 133.068568 -235.459524)
		(width 0.088646)
		(layer "In11.Cu")
		(net "M_H_CPU1_SB_DQ<5>")
	)
	(arc
		(start 137.767568 -235.459524)
		(mid 137.493369 -235.535359)
		(end 137.216896 -235.46816)
		(width 0.088646)
		(layer "In11.Cu")
		(net "M_H_CPU1_SB_DQ<5>")
	)
	(arc
		(start 135.887968 -235.459524)
		(mid 135.605266 -235.5353)
		(end 135.322564 -235.459524)
		(width 0.088646)
		(layer "In11.Cu")
		(net "M_H_CPU1_SB_DQ<5>")
	)
	(arc
		(start 130.249168 -235.459524)
		(mid 129.974969 -235.535359)
		(end 129.698496 -235.46816)
		(width 0.088646)
		(layer "In11.Cu")
		(net "M_H_CPU1_SB_DQ<5>")
	)
	(arc
		(start 126.483872 -235.462826)
		(mid 126.203767 -235.535268)
		(end 125.924564 -235.459524)
		(width 0.088646)
		(layer "In11.Cu")
		(net "M_H_CPU1_SB_DQ<5>")
	)
	(arc
		(start 134.008368 -235.459524)
		(mid 133.725666 -235.5353)
		(end 133.442964 -235.459524)
		(width 0.088646)
		(layer "In11.Cu")
		(net "M_H_CPU1_SB_DQ<5>")
	)
	(arc
		(start 135.322564 -235.459524)
		(mid 135.135366 -235.409381)
		(end 134.948168 -235.459524)
		(width 0.088646)
		(layer "In11.Cu")
		(net "M_H_CPU1_SB_DQ<5>")
	)
	(arc
		(start 127.804164 -235.459524)
		(mid 127.62021 -235.409395)
		(end 127.435356 -235.456222)
		(width 0.088646)
		(layer "In11.Cu")
		(net "M_H_CPU1_SB_DQ<5>")
	)
	(arc
		(start 137.202164 -235.459524)
		(mid 137.014966 -235.409381)
		(end 136.827768 -235.459524)
		(width 0.088646)
		(layer "In11.Cu")
		(net "M_H_CPU1_SB_DQ<5>")
	)
	(arc
		(start 133.068568 -235.459524)
		(mid 132.791755 -235.535394)
		(end 132.513324 -235.46562)
		(width 0.088646)
		(layer "In11.Cu")
		(net "M_H_CPU1_SB_DQ<5>")
	)
	(arc
		(start 134.382764 -235.459524)
		(mid 134.195566 -235.409381)
		(end 134.008368 -235.459524)
		(width 0.088646)
		(layer "In11.Cu")
		(net "M_H_CPU1_SB_DQ<5>")
	)
	(arc
		(start 129.309368 -235.459524)
		(mid 129.035169 -235.535359)
		(end 128.758696 -235.46816)
		(width 0.088646)
		(layer "In11.Cu")
		(net "M_H_CPU1_SB_DQ<5>")
	)
	(arc
		(start 131.188968 -235.459524)
		(mid 130.914769 -235.535359)
		(end 130.638296 -235.46816)
		(width 0.088646)
		(layer "In11.Cu")
		(net "M_H_CPU1_SB_DQ<5>")
	)
	(arc
		(start 132.1181 -235.46562)
		(mid 131.839922 -235.535343)
		(end 131.563364 -235.459524)
		(width 0.088646)
		(layer "In11.Cu")
		(net "M_H_CPU1_SB_DQ<5>")
	)
	(arc
		(start 128.369568 -235.459524)
		(mid 128.095369 -235.535359)
		(end 127.818896 -235.46816)
		(width 0.088646)
		(layer "In11.Cu")
		(net "M_H_CPU1_SB_DQ<5>")
	)
	(arc
		(start 138.219688 -235.51896)
		(mid 138.182778 -235.486689)
		(end 138.141964 -235.459524)
		(width 0.088646)
		(layer "In11.Cu")
		(net "M_H_CPU1_SB_DQ<5>")
	)
	(arc
		(start 132.50291 -235.459524)
		(mid 132.315712 -235.409381)
		(end 132.128514 -235.459524)
		(width 0.088646)
		(layer "In11.Cu")
		(net "M_H_CPU1_SB_DQ<5>")
	)
	(arc
		(start 125.233684 -235.75772)
		(mid 125.204797 -235.777085)
		(end 125.170692 -235.783882)
		(width 0.088646)
		(layer "In11.Cu")
		(net "M_H_CPU1_SB_DQ<5>")
	)
	(arc
		(start 131.563364 -235.459524)
		(mid 131.376166 -235.409381)
		(end 131.188968 -235.459524)
		(width 0.088646)
		(layer "In11.Cu")
		(net "M_H_CPU1_SB_DQ<5>")
	)
	(arc
		(start 136.262364 -235.459524)
		(mid 136.075166 -235.409381)
		(end 135.887968 -235.459524)
		(width 0.088646)
		(layer "In11.Cu")
		(net "M_H_CPU1_SB_DQ<5>")
	)
	(arc
		(start 134.948168 -235.459524)
		(mid 134.665466 -235.5353)
		(end 134.382764 -235.459524)
		(width 0.088646)
		(layer "In11.Cu")
		(net "M_H_CPU1_SB_DQ<5>")
	)
	(arc
		(start 130.623564 -235.459524)
		(mid 130.436366 -235.409381)
		(end 130.249168 -235.459524)
		(width 0.088646)
		(layer "In11.Cu")
		(net "M_H_CPU1_SB_DQ<5>")
	)
	(arc
		(start 125.555756 -235.455968)
		(mid 125.512183 -235.484333)
		(end 125.472952 -235.518452)
		(width 0.088646)
		(layer "In11.Cu")
		(net "M_H_CPU1_SB_DQ<5>")
	)
	(arc
		(start 125.924564 -235.459524)
		(mid 125.74064 -235.40927)
		(end 125.555756 -235.455968)
		(width 0.088646)
		(layer "In11.Cu")
		(net "M_H_CPU1_SB_DQ<5>")
	)
	(arc
		(start 127.423672 -235.462826)
		(mid 127.143567 -235.535268)
		(end 126.864364 -235.459524)
		(width 0.088646)
		(layer "In11.Cu")
		(net "M_H_CPU1_SB_DQ<5>")
	)
	(arc
		(start 128.743964 -235.459524)
		(mid 128.556766 -235.409381)
		(end 128.369568 -235.459524)
		(width 0.088646)
		(layer "In11.Cu")
		(net "M_H_CPU1_SB_DQ<5>")
	)
	(arc
		(start 126.864364 -235.459524)
		(mid 126.68041 -235.409395)
		(end 126.495556 -235.456222)
		(width 0.088646)
		(layer "In11.Cu")
		(net "M_H_CPU1_SB_DQ<5>")
	)
	(arc
		(start 129.683764 -235.459524)
		(mid 129.496566 -235.409381)
		(end 129.309368 -235.459524)
		(width 0.088646)
		(layer "In11.Cu")
		(net "M_H_CPU1_SB_DQ<5>")
	)
	(arc
		(start 136.827768 -235.459524)
		(mid 136.553569 -235.535359)
		(end 136.277096 -235.46816)
		(width 0.088646)
		(layer "In11.Cu")
		(net "M_H_CPU1_SB_DQ<5>")
	)
	(arc
		(start 138.141964 -235.459524)
		(mid 137.954766 -235.409381)
		(end 137.767568 -235.459524)
		(width 0.088646)
		(layer "In11.Cu")
		(net "M_H_CPU1_SB_DQ<5>")
	)
	(segment
		(start 123.387612 -237.133638)
		(end 123.387612 -236.597952)
		(width 0.20066)
		(layer "F.Cu")
		(net "M_H_CPU1_SB_DQ<4>")
	)
	(segment
		(start 206.508604 -226.277424)
		(end 206.320644 -226.465384)
		(width 0.20066)
		(layer "F.Cu")
		(net "M_H_CPU1_SB_DQ<4>")
	)
	(segment
		(start 205.596744 -226.216718)
		(end 204.076046 -226.216718)
		(width 0.20066)
		(layer "F.Cu")
		(net "M_H_CPU1_SB_DQ<4>")
	)
	(segment
		(start 123.387866 -237.133892)
		(end 123.387612 -237.133638)
		(width 0.20066)
		(layer "F.Cu")
		(net "M_H_CPU1_SB_DQ<4>")
	)
	(segment
		(start 205.84541 -226.465384)
		(end 205.596744 -226.216718)
		(width 0.20066)
		(layer "F.Cu")
		(net "M_H_CPU1_SB_DQ<4>")
	)
	(segment
		(start 211.619592 -226.216972)
		(end 210.028028 -226.216972)
		(width 0.20066)
		(layer "F.Cu")
		(net "M_H_CPU1_SB_DQ<4>")
	)
	(segment
		(start 207.018382 -225.791776)
		(end 206.971392 -225.791776)
		(width 0.101854)
		(layer "F.Cu")
		(net "M_H_CPU1_SB_DQ<4>")
	)
	(segment
		(start 209.180176 -225.791776)
		(end 207.018382 -225.791776)
		(width 0.1016)
		(layer "F.Cu")
		(net "M_H_CPU1_SB_DQ<4>")
	)
	(segment
		(start 209.596482 -225.785426)
		(end 209.186526 -225.785426)
		(width 0.20066)
		(layer "F.Cu")
		(net "M_H_CPU1_SB_DQ<4>")
	)
	(segment
		(start 206.971392 -225.791776)
		(end 206.626714 -225.791776)
		(width 0.20066)
		(layer "F.Cu")
		(net "M_H_CPU1_SB_DQ<4>")
	)
	(segment
		(start 204.076046 -226.216718)
		(end 202.971146 -226.216718)
		(width 0.20066)
		(layer "F.Cu")
		(net "M_H_CPU1_SB_DQ<4>")
	)
	(segment
		(start 206.626714 -225.791776)
		(end 206.508604 -225.909886)
		(width 0.20066)
		(layer "F.Cu")
		(net "M_H_CPU1_SB_DQ<4>")
	)
	(segment
		(start 206.320644 -226.465384)
		(end 205.84541 -226.465384)
		(width 0.20066)
		(layer "F.Cu")
		(net "M_H_CPU1_SB_DQ<4>")
	)
	(segment
		(start 209.186526 -225.785426)
		(end 209.180176 -225.791776)
		(width 0.1016)
		(layer "F.Cu")
		(net "M_H_CPU1_SB_DQ<4>")
	)
	(segment
		(start 210.028028 -226.216972)
		(end 209.596482 -225.785426)
		(width 0.20066)
		(layer "F.Cu")
		(net "M_H_CPU1_SB_DQ<4>")
	)
	(segment
		(start 211.619846 -226.216718)
		(end 211.619592 -226.216972)
		(width 0.20066)
		(layer "F.Cu")
		(net "M_H_CPU1_SB_DQ<4>")
	)
	(segment
		(start 206.508604 -225.909886)
		(end 206.508604 -226.277424)
		(width 0.20066)
		(layer "F.Cu")
		(net "M_H_CPU1_SB_DQ<4>")
	)
	(segment
		(start 173.944026 -222.127826)
		(end 173.385226 -222.127826)
		(width 0.18288)
		(layer "In11.Cu")
		(net "M_H_CPU1_SB_DQ<4>")
	)
	(segment
		(start 136.357614 -236.273594)
		(end 136.342882 -236.28223)
		(width 0.088646)
		(layer "In11.Cu")
		(net "M_H_CPU1_SB_DQ<4>")
	)
	(segment
		(start 169.970958 -222.229426)
		(end 168.927526 -222.229426)
		(width 0.18288)
		(layer "In11.Cu")
		(net "M_H_CPU1_SB_DQ<4>")
	)
	(segment
		(start 166.851838 -223.650302)
		(end 166.658798 -223.843342)
		(width 0.18288)
		(layer "In11.Cu")
		(net "M_H_CPU1_SB_DQ<4>")
	)
	(segment
		(start 138.237214 -236.273594)
		(end 138.222482 -236.28223)
		(width 0.088646)
		(layer "In11.Cu")
		(net "M_H_CPU1_SB_DQ<4>")
	)
	(segment
		(start 168.927526 -222.229426)
		(end 168.190926 -222.966026)
		(width 0.18288)
		(layer "In11.Cu")
		(net "M_H_CPU1_SB_DQ<4>")
	)
	(segment
		(start 166.851838 -223.159066)
		(end 166.851838 -223.650302)
		(width 0.18288)
		(layer "In11.Cu")
		(net "M_H_CPU1_SB_DQ<4>")
	)
	(segment
		(start 158.740602 -224.090738)
		(end 156.143198 -224.090738)
		(width 0.18288)
		(layer "In11.Cu")
		(net "M_H_CPU1_SB_DQ<4>")
	)
	(segment
		(start 168.190926 -222.966026)
		(end 167.044878 -222.966026)
		(width 0.18288)
		(layer "In11.Cu")
		(net "M_H_CPU1_SB_DQ<4>")
	)
	(segment
		(start 135.417814 -236.273594)
		(end 135.4074 -236.27969)
		(width 0.088646)
		(layer "In11.Cu")
		(net "M_H_CPU1_SB_DQ<4>")
	)
	(segment
		(start 141.103096 -235.794804)
		(end 140.415264 -235.794804)
		(width 0.088646)
		(layer "In11.Cu")
		(net "M_H_CPU1_SB_DQ<4>")
	)
	(segment
		(start 131.658614 -236.273594)
		(end 131.643882 -236.28223)
		(width 0.088646)
		(layer "In11.Cu")
		(net "M_H_CPU1_SB_DQ<4>")
	)
	(segment
		(start 195.203826 -223.118426)
		(end 194.232022 -222.146622)
		(width 0.18288)
		(layer "In11.Cu")
		(net "M_H_CPU1_SB_DQ<4>")
	)
	(segment
		(start 170.357038 -223.00692)
		(end 170.163998 -222.81388)
		(width 0.18288)
		(layer "In11.Cu")
		(net "M_H_CPU1_SB_DQ<4>")
	)
	(segment
		(start 125.763274 -236.661452)
		(end 125.660658 -236.764068)
		(width 0.088646)
		(layer "In11.Cu")
		(net "M_H_CPU1_SB_DQ<4>")
	)
	(segment
		(start 178.759358 -220.538294)
		(end 177.755042 -221.54261)
		(width 0.18288)
		(layer "In11.Cu")
		(net "M_H_CPU1_SB_DQ<4>")
	)
	(segment
		(start 170.163998 -222.422466)
		(end 169.970958 -222.229426)
		(width 0.18288)
		(layer "In11.Cu")
		(net "M_H_CPU1_SB_DQ<4>")
	)
	(segment
		(start 190.33236 -221.540832)
		(end 189.484254 -220.692726)
		(width 0.18288)
		(layer "In11.Cu")
		(net "M_H_CPU1_SB_DQ<4>")
	)
	(segment
		(start 174.706026 -221.365826)
		(end 173.944026 -222.127826)
		(width 0.18288)
		(layer "In11.Cu")
		(net "M_H_CPU1_SB_DQ<4>")
	)
	(segment
		(start 170.163998 -222.81388)
		(end 170.163998 -222.422466)
		(width 0.18288)
		(layer "In11.Cu")
		(net "M_H_CPU1_SB_DQ<4>")
	)
	(segment
		(start 159.687514 -223.143826)
		(end 158.740602 -224.090738)
		(width 0.18288)
		(layer "In11.Cu")
		(net "M_H_CPU1_SB_DQ<4>")
	)
	(segment
		(start 166.341298 -223.843342)
		(end 166.148258 -223.650302)
		(width 0.18288)
		(layer "In11.Cu")
		(net "M_H_CPU1_SB_DQ<4>")
	)
	(segment
		(start 130.718814 -236.273594)
		(end 130.704082 -236.28223)
		(width 0.088646)
		(layer "In11.Cu")
		(net "M_H_CPU1_SB_DQ<4>")
	)
	(segment
		(start 173.123098 -222.389954)
		(end 172.431202 -222.389954)
		(width 0.18288)
		(layer "In11.Cu")
		(net "M_H_CPU1_SB_DQ<4>")
	)
	(segment
		(start 170.867578 -222.81388)
		(end 170.674538 -223.00692)
		(width 0.18288)
		(layer "In11.Cu")
		(net "M_H_CPU1_SB_DQ<4>")
	)
	(segment
		(start 176.026826 -221.365826)
		(end 174.706026 -221.365826)
		(width 0.18288)
		(layer "In11.Cu")
		(net "M_H_CPU1_SB_DQ<4>")
	)
	(segment
		(start 180.959506 -220.82506)
		(end 180.119528 -220.82506)
		(width 0.18288)
		(layer "In11.Cu")
		(net "M_H_CPU1_SB_DQ<4>")
	)
	(segment
		(start 166.148258 -223.650302)
		(end 166.148258 -223.159066)
		(width 0.18288)
		(layer "In11.Cu")
		(net "M_H_CPU1_SB_DQ<4>")
	)
	(segment
		(start 193.101722 -222.146622)
		(end 192.495932 -221.540832)
		(width 0.18288)
		(layer "In11.Cu")
		(net "M_H_CPU1_SB_DQ<4>")
	)
	(segment
		(start 187.4901 -220.692726)
		(end 187.282582 -220.485208)
		(width 0.18288)
		(layer "In11.Cu")
		(net "M_H_CPU1_SB_DQ<4>")
	)
	(segment
		(start 181.152546 -221.246192)
		(end 181.152546 -221.0181)
		(width 0.18288)
		(layer "In11.Cu")
		(net "M_H_CPU1_SB_DQ<4>")
	)
	(segment
		(start 173.385226 -222.127826)
		(end 173.123098 -222.389954)
		(width 0.18288)
		(layer "In11.Cu")
		(net "M_H_CPU1_SB_DQ<4>")
	)
	(segment
		(start 198.048626 -224.845626)
		(end 197.388226 -224.845626)
		(width 0.18288)
		(layer "In11.Cu")
		(net "M_H_CPU1_SB_DQ<4>")
	)
	(segment
		(start 127.899414 -236.273594)
		(end 127.884682 -236.28223)
		(width 0.088646)
		(layer "In11.Cu")
		(net "M_H_CPU1_SB_DQ<4>")
	)
	(segment
		(start 163.104322 -223.360234)
		(end 162.786822 -223.360234)
		(width 0.18288)
		(layer "In11.Cu")
		(net "M_H_CPU1_SB_DQ<4>")
	)
	(segment
		(start 137.297414 -236.273594)
		(end 137.282682 -236.28223)
		(width 0.088646)
		(layer "In11.Cu")
		(net "M_H_CPU1_SB_DQ<4>")
	)
	(segment
		(start 126.959614 -236.273594)
		(end 126.944882 -236.28223)
		(width 0.088646)
		(layer "In11.Cu")
		(net "M_H_CPU1_SB_DQ<4>")
	)
	(segment
		(start 180.119528 -220.82506)
		(end 179.832762 -220.538294)
		(width 0.18288)
		(layer "In11.Cu")
		(net "M_H_CPU1_SB_DQ<4>")
	)
	(segment
		(start 133.538468 -236.273594)
		(end 133.528054 -236.27969)
		(width 0.088646)
		(layer "In11.Cu")
		(net "M_H_CPU1_SB_DQ<4>")
	)
	(segment
		(start 162.593782 -223.167194)
		(end 162.593782 -222.524066)
		(width 0.18288)
		(layer "In11.Cu")
		(net "M_H_CPU1_SB_DQ<4>")
	)
	(segment
		(start 194.232022 -222.146622)
		(end 193.101722 -222.146622)
		(width 0.18288)
		(layer "In11.Cu")
		(net "M_H_CPU1_SB_DQ<4>")
	)
	(segment
		(start 198.861426 -225.658426)
		(end 198.048626 -224.845626)
		(width 0.18288)
		(layer "In11.Cu")
		(net "M_H_CPU1_SB_DQ<4>")
	)
	(segment
		(start 183.671464 -220.485208)
		(end 183.331612 -220.82506)
		(width 0.18288)
		(layer "In11.Cu")
		(net "M_H_CPU1_SB_DQ<4>")
	)
	(segment
		(start 195.661026 -223.118426)
		(end 195.203826 -223.118426)
		(width 0.18288)
		(layer "In11.Cu")
		(net "M_H_CPU1_SB_DQ<4>")
	)
	(segment
		(start 162.786822 -223.360234)
		(end 162.593782 -223.167194)
		(width 0.18288)
		(layer "In11.Cu")
		(net "M_H_CPU1_SB_DQ<4>")
	)
	(segment
		(start 166.148258 -223.159066)
		(end 165.955218 -222.966026)
		(width 0.18288)
		(layer "In11.Cu")
		(net "M_H_CPU1_SB_DQ<4>")
	)
	(segment
		(start 181.663086 -221.439232)
		(end 181.345586 -221.439232)
		(width 0.18288)
		(layer "In11.Cu")
		(net "M_H_CPU1_SB_DQ<4>")
	)
	(segment
		(start 167.044878 -222.966026)
		(end 166.851838 -223.159066)
		(width 0.18288)
		(layer "In11.Cu")
		(net "M_H_CPU1_SB_DQ<4>")
	)
	(segment
		(start 163.490402 -222.331026)
		(end 163.297362 -222.524066)
		(width 0.18288)
		(layer "In11.Cu")
		(net "M_H_CPU1_SB_DQ<4>")
	)
	(segment
		(start 197.388226 -224.845626)
		(end 195.661026 -223.118426)
		(width 0.18288)
		(layer "In11.Cu")
		(net "M_H_CPU1_SB_DQ<4>")
	)
	(segment
		(start 170.867578 -222.422466)
		(end 170.867578 -222.81388)
		(width 0.18288)
		(layer "In11.Cu")
		(net "M_H_CPU1_SB_DQ<4>")
	)
	(segment
		(start 129.779014 -236.273594)
		(end 129.7686 -236.27969)
		(width 0.088646)
		(layer "In11.Cu")
		(net "M_H_CPU1_SB_DQ<4>")
	)
	(segment
		(start 202.971146 -226.216718)
		(end 202.971146 -225.964242)
		(width 0.18288)
		(layer "In11.Cu")
		(net "M_H_CPU1_SB_DQ<4>")
	)
	(segment
		(start 163.297362 -223.167194)
		(end 163.104322 -223.360234)
		(width 0.18288)
		(layer "In11.Cu")
		(net "M_H_CPU1_SB_DQ<4>")
	)
	(segment
		(start 156.143198 -224.090738)
		(end 144.439132 -235.794804)
		(width 0.18288)
		(layer "In11.Cu")
		(net "M_H_CPU1_SB_DQ<4>")
	)
	(segment
		(start 171.060618 -222.229426)
		(end 170.867578 -222.422466)
		(width 0.18288)
		(layer "In11.Cu")
		(net "M_H_CPU1_SB_DQ<4>")
	)
	(segment
		(start 161.498026 -222.331026)
		(end 160.685226 -223.143826)
		(width 0.18288)
		(layer "In11.Cu")
		(net "M_H_CPU1_SB_DQ<4>")
	)
	(segment
		(start 202.971146 -225.964242)
		(end 202.815444 -225.80854)
		(width 0.18288)
		(layer "In11.Cu")
		(net "M_H_CPU1_SB_DQ<4>")
	)
	(segment
		(start 181.856126 -221.0181)
		(end 181.856126 -221.246192)
		(width 0.18288)
		(layer "In11.Cu")
		(net "M_H_CPU1_SB_DQ<4>")
	)
	(segment
		(start 177.755042 -221.54261)
		(end 176.20361 -221.54261)
		(width 0.18288)
		(layer "In11.Cu")
		(net "M_H_CPU1_SB_DQ<4>")
	)
	(segment
		(start 182.049166 -220.82506)
		(end 181.856126 -221.0181)
		(width 0.18288)
		(layer "In11.Cu")
		(net "M_H_CPU1_SB_DQ<4>")
	)
	(segment
		(start 163.297362 -222.524066)
		(end 163.297362 -223.167194)
		(width 0.18288)
		(layer "In11.Cu")
		(net "M_H_CPU1_SB_DQ<4>")
	)
	(segment
		(start 165.955218 -222.966026)
		(end 164.863526 -222.966026)
		(width 0.18288)
		(layer "In11.Cu")
		(net "M_H_CPU1_SB_DQ<4>")
	)
	(segment
		(start 192.495932 -221.540832)
		(end 190.33236 -221.540832)
		(width 0.18288)
		(layer "In11.Cu")
		(net "M_H_CPU1_SB_DQ<4>")
	)
	(segment
		(start 189.484254 -220.692726)
		(end 187.4901 -220.692726)
		(width 0.18288)
		(layer "In11.Cu")
		(net "M_H_CPU1_SB_DQ<4>")
	)
	(segment
		(start 181.856126 -221.246192)
		(end 181.663086 -221.439232)
		(width 0.18288)
		(layer "In11.Cu")
		(net "M_H_CPU1_SB_DQ<4>")
	)
	(segment
		(start 179.832762 -220.538294)
		(end 178.759358 -220.538294)
		(width 0.18288)
		(layer "In11.Cu")
		(net "M_H_CPU1_SB_DQ<4>")
	)
	(segment
		(start 140.415264 -235.794804)
		(end 139.986512 -236.223556)
		(width 0.088646)
		(layer "In11.Cu")
		(net "M_H_CPU1_SB_DQ<4>")
	)
	(segment
		(start 172.043344 -222.229426)
		(end 171.060618 -222.229426)
		(width 0.18288)
		(layer "In11.Cu")
		(net "M_H_CPU1_SB_DQ<4>")
	)
	(segment
		(start 181.152546 -221.0181)
		(end 180.959506 -220.82506)
		(width 0.18288)
		(layer "In11.Cu")
		(net "M_H_CPU1_SB_DQ<4>")
	)
	(segment
		(start 125.080014 -236.92231)
		(end 125.065282 -236.913674)
		(width 0.088646)
		(layer "In11.Cu")
		(net "M_H_CPU1_SB_DQ<4>")
	)
	(segment
		(start 176.20361 -221.54261)
		(end 176.026826 -221.365826)
		(width 0.18288)
		(layer "In11.Cu")
		(net "M_H_CPU1_SB_DQ<4>")
	)
	(segment
		(start 162.593782 -222.524066)
		(end 162.400742 -222.331026)
		(width 0.18288)
		(layer "In11.Cu")
		(net "M_H_CPU1_SB_DQ<4>")
	)
	(segment
		(start 164.228526 -222.331026)
		(end 163.490402 -222.331026)
		(width 0.18288)
		(layer "In11.Cu")
		(net "M_H_CPU1_SB_DQ<4>")
	)
	(segment
		(start 183.331612 -220.82506)
		(end 182.049166 -220.82506)
		(width 0.18288)
		(layer "In11.Cu")
		(net "M_H_CPU1_SB_DQ<4>")
	)
	(segment
		(start 162.400742 -222.331026)
		(end 161.498026 -222.331026)
		(width 0.18288)
		(layer "In11.Cu")
		(net "M_H_CPU1_SB_DQ<4>")
	)
	(segment
		(start 170.674538 -223.00692)
		(end 170.357038 -223.00692)
		(width 0.18288)
		(layer "In11.Cu")
		(net "M_H_CPU1_SB_DQ<4>")
	)
	(segment
		(start 166.658798 -223.843342)
		(end 166.341298 -223.843342)
		(width 0.18288)
		(layer "In11.Cu")
		(net "M_H_CPU1_SB_DQ<4>")
	)
	(segment
		(start 172.431202 -222.389954)
		(end 172.043344 -222.229426)
		(width 0.18288)
		(layer "In11.Cu")
		(net "M_H_CPU1_SB_DQ<4>")
	)
	(segment
		(start 160.685226 -223.143826)
		(end 159.687514 -223.143826)
		(width 0.18288)
		(layer "In11.Cu")
		(net "M_H_CPU1_SB_DQ<4>")
	)
	(segment
		(start 202.815444 -225.80854)
		(end 202.45324 -225.658426)
		(width 0.18288)
		(layer "In11.Cu")
		(net "M_H_CPU1_SB_DQ<4>")
	)
	(segment
		(start 181.345586 -221.439232)
		(end 181.152546 -221.246192)
		(width 0.18288)
		(layer "In11.Cu")
		(net "M_H_CPU1_SB_DQ<4>")
	)
	(segment
		(start 128.839468 -236.273594)
		(end 128.829054 -236.27969)
		(width 0.088646)
		(layer "In11.Cu")
		(net "M_H_CPU1_SB_DQ<4>")
	)
	(segment
		(start 139.986512 -236.223556)
		(end 138.422888 -236.223556)
		(width 0.088646)
		(layer "In11.Cu")
		(net "M_H_CPU1_SB_DQ<4>")
	)
	(segment
		(start 187.282582 -220.485208)
		(end 183.671464 -220.485208)
		(width 0.18288)
		(layer "In11.Cu")
		(net "M_H_CPU1_SB_DQ<4>")
	)
	(segment
		(start 144.439132 -235.794804)
		(end 141.103096 -235.794804)
		(width 0.18288)
		(layer "In11.Cu")
		(net "M_H_CPU1_SB_DQ<4>")
	)
	(segment
		(start 164.863526 -222.966026)
		(end 164.228526 -222.331026)
		(width 0.18288)
		(layer "In11.Cu")
		(net "M_H_CPU1_SB_DQ<4>")
	)
	(segment
		(start 202.45324 -225.658426)
		(end 198.861426 -225.658426)
		(width 0.18288)
		(layer "In11.Cu")
		(net "M_H_CPU1_SB_DQ<4>")
	)
	(segment
		(start 124.140214 -236.92231)
		(end 123.75896 -236.69879)
		(width 0.088646)
		(layer "In11.Cu")
		(net "M_H_CPU1_SB_DQ<4>")
	)
	(arc
		(start 132.03301 -236.273594)
		(mid 131.845812 -236.223451)
		(end 131.658614 -236.273594)
		(width 0.088646)
		(layer "In11.Cu")
		(net "M_H_CPU1_SB_DQ<4>")
	)
	(arc
		(start 129.213864 -236.273594)
		(mid 129.026666 -236.223451)
		(end 128.839468 -236.273594)
		(width 0.088646)
		(layer "In11.Cu")
		(net "M_H_CPU1_SB_DQ<4>")
	)
	(arc
		(start 133.528054 -236.27969)
		(mid 133.249622 -236.349504)
		(end 132.97281 -236.273594)
		(width 0.088646)
		(layer "In11.Cu")
		(net "M_H_CPU1_SB_DQ<4>")
	)
	(arc
		(start 138.422888 -236.223556)
		(mid 138.326742 -236.236291)
		(end 138.237214 -236.273594)
		(width 0.088646)
		(layer "In11.Cu")
		(net "M_H_CPU1_SB_DQ<4>")
	)
	(arc
		(start 128.829054 -236.27969)
		(mid 128.550622 -236.349504)
		(end 128.27381 -236.273594)
		(width 0.088646)
		(layer "In11.Cu")
		(net "M_H_CPU1_SB_DQ<4>")
	)
	(arc
		(start 138.222482 -236.28223)
		(mid 137.946041 -236.349396)
		(end 137.67181 -236.273594)
		(width 0.088646)
		(layer "In11.Cu")
		(net "M_H_CPU1_SB_DQ<4>")
	)
	(arc
		(start 126.39421 -236.273594)
		(mid 126.207012 -236.223451)
		(end 126.019814 -236.273594)
		(width 0.088646)
		(layer "In11.Cu")
		(net "M_H_CPU1_SB_DQ<4>")
	)
	(arc
		(start 137.67181 -236.273594)
		(mid 137.484612 -236.223451)
		(end 137.297414 -236.273594)
		(width 0.088646)
		(layer "In11.Cu")
		(net "M_H_CPU1_SB_DQ<4>")
	)
	(arc
		(start 132.598414 -236.273594)
		(mid 132.315712 -236.349336)
		(end 132.03301 -236.273594)
		(width 0.088646)
		(layer "In11.Cu")
		(net "M_H_CPU1_SB_DQ<4>")
	)
	(arc
		(start 131.643882 -236.28223)
		(mid 131.367441 -236.349396)
		(end 131.09321 -236.273594)
		(width 0.088646)
		(layer "In11.Cu")
		(net "M_H_CPU1_SB_DQ<4>")
	)
	(arc
		(start 133.912864 -236.273594)
		(mid 133.725666 -236.223451)
		(end 133.538468 -236.273594)
		(width 0.088646)
		(layer "In11.Cu")
		(net "M_H_CPU1_SB_DQ<4>")
	)
	(arc
		(start 131.09321 -236.273594)
		(mid 130.906012 -236.223451)
		(end 130.718814 -236.273594)
		(width 0.088646)
		(layer "In11.Cu")
		(net "M_H_CPU1_SB_DQ<4>")
	)
	(arc
		(start 132.97281 -236.273594)
		(mid 132.785612 -236.223451)
		(end 132.598414 -236.273594)
		(width 0.088646)
		(layer "In11.Cu")
		(net "M_H_CPU1_SB_DQ<4>")
	)
	(arc
		(start 126.019814 -236.273594)
		(mid 126.016231 -236.275709)
		(end 126.012702 -236.277912)
		(width 0.088646)
		(layer "In11.Cu")
		(net "M_H_CPU1_SB_DQ<4>")
	)
	(arc
		(start 130.15341 -236.273594)
		(mid 129.966212 -236.223451)
		(end 129.779014 -236.273594)
		(width 0.088646)
		(layer "In11.Cu")
		(net "M_H_CPU1_SB_DQ<4>")
	)
	(arc
		(start 134.852664 -236.273594)
		(mid 134.665466 -236.223451)
		(end 134.478268 -236.273594)
		(width 0.088646)
		(layer "In11.Cu")
		(net "M_H_CPU1_SB_DQ<4>")
	)
	(arc
		(start 125.840998 -236.518958)
		(mid 125.812401 -236.595802)
		(end 125.763274 -236.661452)
		(width 0.088646)
		(layer "In11.Cu")
		(net "M_H_CPU1_SB_DQ<4>")
	)
	(arc
		(start 125.065282 -236.913674)
		(mid 124.788807 -236.846354)
		(end 124.51461 -236.92231)
		(width 0.088646)
		(layer "In11.Cu")
		(net "M_H_CPU1_SB_DQ<4>")
	)
	(arc
		(start 137.282682 -236.28223)
		(mid 137.006241 -236.349396)
		(end 136.73201 -236.273594)
		(width 0.088646)
		(layer "In11.Cu")
		(net "M_H_CPU1_SB_DQ<4>")
	)
	(arc
		(start 124.51461 -236.92231)
		(mid 124.327412 -236.972453)
		(end 124.140214 -236.92231)
		(width 0.088646)
		(layer "In11.Cu")
		(net "M_H_CPU1_SB_DQ<4>")
	)
	(arc
		(start 126.012702 -236.277912)
		(mid 125.902039 -236.380757)
		(end 125.840998 -236.518958)
		(width 0.088646)
		(layer "In11.Cu")
		(net "M_H_CPU1_SB_DQ<4>")
	)
	(arc
		(start 130.704082 -236.28223)
		(mid 130.427641 -236.349396)
		(end 130.15341 -236.273594)
		(width 0.088646)
		(layer "In11.Cu")
		(net "M_H_CPU1_SB_DQ<4>")
	)
	(arc
		(start 128.27381 -236.273594)
		(mid 128.086612 -236.223451)
		(end 127.899414 -236.273594)
		(width 0.088646)
		(layer "In11.Cu")
		(net "M_H_CPU1_SB_DQ<4>")
	)
	(arc
		(start 127.33401 -236.273594)
		(mid 127.146812 -236.223451)
		(end 126.959614 -236.273594)
		(width 0.088646)
		(layer "In11.Cu")
		(net "M_H_CPU1_SB_DQ<4>")
	)
	(arc
		(start 126.944882 -236.28223)
		(mid 126.668441 -236.349396)
		(end 126.39421 -236.273594)
		(width 0.088646)
		(layer "In11.Cu")
		(net "M_H_CPU1_SB_DQ<4>")
	)
	(arc
		(start 135.79221 -236.273594)
		(mid 135.605012 -236.223451)
		(end 135.417814 -236.273594)
		(width 0.088646)
		(layer "In11.Cu")
		(net "M_H_CPU1_SB_DQ<4>")
	)
	(arc
		(start 134.478268 -236.273594)
		(mid 134.195566 -236.349336)
		(end 133.912864 -236.273594)
		(width 0.088646)
		(layer "In11.Cu")
		(net "M_H_CPU1_SB_DQ<4>")
	)
	(arc
		(start 127.884682 -236.28223)
		(mid 127.608241 -236.349396)
		(end 127.33401 -236.273594)
		(width 0.088646)
		(layer "In11.Cu")
		(net "M_H_CPU1_SB_DQ<4>")
	)
	(arc
		(start 136.342882 -236.28223)
		(mid 136.066441 -236.349396)
		(end 135.79221 -236.273594)
		(width 0.088646)
		(layer "In11.Cu")
		(net "M_H_CPU1_SB_DQ<4>")
	)
	(arc
		(start 123.75896 -236.69879)
		(mid 123.580012 -236.623597)
		(end 123.387612 -236.597952)
		(width 0.088646)
		(layer "In11.Cu")
		(net "M_H_CPU1_SB_DQ<4>")
	)
	(arc
		(start 125.45441 -236.92231)
		(mid 125.267212 -236.972453)
		(end 125.080014 -236.92231)
		(width 0.088646)
		(layer "In11.Cu")
		(net "M_H_CPU1_SB_DQ<4>")
	)
	(arc
		(start 135.4074 -236.27969)
		(mid 135.129222 -236.349382)
		(end 134.852664 -236.273594)
		(width 0.088646)
		(layer "In11.Cu")
		(net "M_H_CPU1_SB_DQ<4>")
	)
	(arc
		(start 129.7686 -236.27969)
		(mid 129.490422 -236.349382)
		(end 129.213864 -236.273594)
		(width 0.088646)
		(layer "In11.Cu")
		(net "M_H_CPU1_SB_DQ<4>")
	)
	(arc
		(start 125.660658 -236.764068)
		(mid 125.56272 -236.849948)
		(end 125.45441 -236.92231)
		(width 0.088646)
		(layer "In11.Cu")
		(net "M_H_CPU1_SB_DQ<4>")
	)
	(arc
		(start 136.73201 -236.273594)
		(mid 136.544812 -236.223451)
		(end 136.357614 -236.273594)
		(width 0.088646)
		(layer "In11.Cu")
		(net "M_H_CPU1_SB_DQ<4>")
	)
	(segment
		(start 212.618066 -230.041704)
		(end 212.630258 -230.053896)
		(width 0.1016)
		(layer "F.Cu")
		(net "M_H_CPU1_SB_DQ<3>")
	)
	(segment
		(start 213.515448 -229.598982)
		(end 213.749636 -229.364794)
		(width 0.20066)
		(layer "F.Cu")
		(net "M_H_CPU1_SB_DQ<3>")
	)
	(segment
		(start 125.267466 -238.761524)
		(end 125.267212 -238.76127)
		(width 0.20066)
		(layer "F.Cu")
		(net "M_H_CPU1_SB_DQ<3>")
	)
	(segment
		(start 210.603084 -230.048816)
		(end 210.610196 -230.041704)
		(width 0.1016)
		(layer "F.Cu")
		(net "M_H_CPU1_SB_DQ<3>")
	)
	(segment
		(start 125.267212 -238.76127)
		(end 125.267212 -238.225584)
		(width 0.20066)
		(layer "F.Cu")
		(net "M_H_CPU1_SB_DQ<3>")
	)
	(segment
		(start 213.515448 -229.849934)
		(end 213.515448 -229.598982)
		(width 0.20066)
		(layer "F.Cu")
		(net "M_H_CPU1_SB_DQ<3>")
	)
	(segment
		(start 213.749636 -229.364794)
		(end 214.133684 -229.364794)
		(width 0.20066)
		(layer "F.Cu")
		(net "M_H_CPU1_SB_DQ<3>")
	)
	(segment
		(start 209.874358 -229.616762)
		(end 210.306412 -230.048816)
		(width 0.20066)
		(layer "F.Cu")
		(net "M_H_CPU1_SB_DQ<3>")
	)
	(segment
		(start 208.176114 -229.616762)
		(end 209.874358 -229.616762)
		(width 0.20066)
		(layer "F.Cu")
		(net "M_H_CPU1_SB_DQ<3>")
	)
	(segment
		(start 210.306412 -230.048816)
		(end 210.598258 -230.048816)
		(width 0.20066)
		(layer "F.Cu")
		(net "M_H_CPU1_SB_DQ<3>")
	)
	(segment
		(start 210.610196 -230.041704)
		(end 212.618066 -230.041704)
		(width 0.1016)
		(layer "F.Cu")
		(net "M_H_CPU1_SB_DQ<3>")
	)
	(segment
		(start 207.071214 -229.616762)
		(end 208.176114 -229.616762)
		(width 0.20066)
		(layer "F.Cu")
		(net "M_H_CPU1_SB_DQ<3>")
	)
	(segment
		(start 214.385652 -229.616762)
		(end 215.719914 -229.616762)
		(width 0.20066)
		(layer "F.Cu")
		(net "M_H_CPU1_SB_DQ<3>")
	)
	(segment
		(start 214.133684 -229.364794)
		(end 214.385652 -229.616762)
		(width 0.20066)
		(layer "F.Cu")
		(net "M_H_CPU1_SB_DQ<3>")
	)
	(segment
		(start 212.630258 -230.053896)
		(end 213.311486 -230.053896)
		(width 0.20066)
		(layer "F.Cu")
		(net "M_H_CPU1_SB_DQ<3>")
	)
	(segment
		(start 210.598258 -230.048816)
		(end 210.603084 -230.048816)
		(width 0.101854)
		(layer "F.Cu")
		(net "M_H_CPU1_SB_DQ<3>")
	)
	(segment
		(start 213.311486 -230.053896)
		(end 213.515448 -229.849934)
		(width 0.20066)
		(layer "F.Cu")
		(net "M_H_CPU1_SB_DQ<3>")
	)
	(segment
		(start 194.137026 -226.903026)
		(end 193.02476 -225.79076)
		(width 0.18288)
		(layer "In11.Cu")
		(net "M_H_CPU1_SB_DQ<3>")
	)
	(segment
		(start 159.47898 -228.342444)
		(end 158.883604 -228.342444)
		(width 0.18288)
		(layer "In11.Cu")
		(net "M_H_CPU1_SB_DQ<3>")
	)
	(segment
		(start 185.770774 -224.881186)
		(end 185.770774 -224.518982)
		(width 0.18288)
		(layer "In11.Cu")
		(net "M_H_CPU1_SB_DQ<3>")
	)
	(segment
		(start 166.578534 -226.678744)
		(end 166.261034 -226.678744)
		(width 0.18288)
		(layer "In11.Cu")
		(net "M_H_CPU1_SB_DQ<3>")
	)
	(segment
		(start 196.118226 -227.639626)
		(end 195.305426 -227.639626)
		(width 0.18288)
		(layer "In11.Cu")
		(net "M_H_CPU1_SB_DQ<3>")
	)
	(segment
		(start 203.5937 -229.195122)
		(end 199.172322 -229.195122)
		(width 0.18288)
		(layer "In11.Cu")
		(net "M_H_CPU1_SB_DQ<3>")
	)
	(segment
		(start 163.20008 -227.284026)
		(end 162.141662 -228.342444)
		(width 0.18288)
		(layer "In11.Cu")
		(net "M_H_CPU1_SB_DQ<3>")
	)
	(segment
		(start 176.038002 -225.79076)
		(end 175.837596 -225.991166)
		(width 0.18288)
		(layer "In11.Cu")
		(net "M_H_CPU1_SB_DQ<3>")
	)
	(segment
		(start 194.568826 -226.903026)
		(end 194.137026 -226.903026)
		(width 0.18288)
		(layer "In11.Cu")
		(net "M_H_CPU1_SB_DQ<3>")
	)
	(segment
		(start 164.544756 -227.284026)
		(end 163.20008 -227.284026)
		(width 0.18288)
		(layer "In11.Cu")
		(net "M_H_CPU1_SB_DQ<3>")
	)
	(segment
		(start 166.771574 -226.871784)
		(end 166.578534 -226.678744)
		(width 0.18288)
		(layer "In11.Cu")
		(net "M_H_CPU1_SB_DQ<3>")
	)
	(segment
		(start 207.071214 -229.616762)
		(end 206.42199 -228.967538)
		(width 0.18288)
		(layer "In11.Cu")
		(net "M_H_CPU1_SB_DQ<3>")
	)
	(segment
		(start 171.211494 -226.930966)
		(end 171.004738 -226.72421)
		(width 0.18288)
		(layer "In11.Cu")
		(net "M_H_CPU1_SB_DQ<3>")
	)
	(segment
		(start 182.045356 -225.810826)
		(end 181.852316 -225.617786)
		(width 0.18288)
		(layer "In11.Cu")
		(net "M_H_CPU1_SB_DQ<3>")
	)
	(segment
		(start 139.83716 -238.498126)
		(end 138.186414 -238.498126)
		(width 0.088646)
		(layer "In11.Cu")
		(net "M_H_CPU1_SB_DQ<3>")
	)
	(segment
		(start 160.3756 -228.149404)
		(end 160.3756 -227.724462)
		(width 0.18288)
		(layer "In11.Cu")
		(net "M_H_CPU1_SB_DQ<3>")
	)
	(segment
		(start 174.500286 -225.991166)
		(end 173.850554 -226.640898)
		(width 0.18288)
		(layer "In11.Cu")
		(net "M_H_CPU1_SB_DQ<3>")
	)
	(segment
		(start 177.677064 -225.367088)
		(end 177.253392 -225.79076)
		(width 0.18288)
		(layer "In11.Cu")
		(net "M_H_CPU1_SB_DQ<3>")
	)
	(segment
		(start 179.418488 -225.367088)
		(end 177.677064 -225.367088)
		(width 0.18288)
		(layer "In11.Cu")
		(net "M_H_CPU1_SB_DQ<3>")
	)
	(segment
		(start 159.67202 -227.724462)
		(end 159.67202 -228.149404)
		(width 0.18288)
		(layer "In11.Cu")
		(net "M_H_CPU1_SB_DQ<3>")
	)
	(segment
		(start 166.067994 -227.34905)
		(end 165.874954 -227.54209)
		(width 0.18288)
		(layer "In11.Cu")
		(net "M_H_CPU1_SB_DQ<3>")
	)
	(segment
		(start 185.770774 -224.518982)
		(end 185.577734 -224.325942)
		(width 0.18288)
		(layer "In11.Cu")
		(net "M_H_CPU1_SB_DQ<3>")
	)
	(segment
		(start 131.658614 -238.549942)
		(end 131.643882 -238.541306)
		(width 0.088646)
		(layer "In11.Cu")
		(net "M_H_CPU1_SB_DQ<3>")
	)
	(segment
		(start 183.570626 -225.074226)
		(end 182.834026 -225.810826)
		(width 0.18288)
		(layer "In11.Cu")
		(net "M_H_CPU1_SB_DQ<3>")
	)
	(segment
		(start 198.648574 -228.671374)
		(end 197.149974 -228.671374)
		(width 0.18288)
		(layer "In11.Cu")
		(net "M_H_CPU1_SB_DQ<3>")
	)
	(segment
		(start 132.598668 -238.549942)
		(end 132.588254 -238.543846)
		(width 0.088646)
		(layer "In11.Cu")
		(net "M_H_CPU1_SB_DQ<3>")
	)
	(segment
		(start 184.874154 -225.074226)
		(end 183.570626 -225.074226)
		(width 0.18288)
		(layer "In11.Cu")
		(net "M_H_CPU1_SB_DQ<3>")
	)
	(segment
		(start 188.640974 -225.13417)
		(end 188.446918 -224.940114)
		(width 0.18288)
		(layer "In11.Cu")
		(net "M_H_CPU1_SB_DQ<3>")
	)
	(segment
		(start 181.148736 -225.617786)
		(end 180.955696 -225.810826)
		(width 0.18288)
		(layer "In11.Cu")
		(net "M_H_CPU1_SB_DQ<3>")
	)
	(segment
		(start 160.3756 -227.724462)
		(end 160.18256 -227.531422)
		(width 0.18288)
		(layer "In11.Cu")
		(net "M_H_CPU1_SB_DQ<3>")
	)
	(segment
		(start 172.275754 -226.640898)
		(end 171.985686 -226.930966)
		(width 0.18288)
		(layer "In11.Cu")
		(net "M_H_CPU1_SB_DQ<3>")
	)
	(segment
		(start 206.42199 -228.967538)
		(end 203.821284 -228.967538)
		(width 0.18288)
		(layer "In11.Cu")
		(net "M_H_CPU1_SB_DQ<3>")
	)
	(segment
		(start 185.260234 -224.325942)
		(end 185.067194 -224.518982)
		(width 0.18288)
		(layer "In11.Cu")
		(net "M_H_CPU1_SB_DQ<3>")
	)
	(segment
		(start 160.18256 -227.531422)
		(end 159.86506 -227.531422)
		(width 0.18288)
		(layer "In11.Cu")
		(net "M_H_CPU1_SB_DQ<3>")
	)
	(segment
		(start 189.398402 -225.13417)
		(end 188.640974 -225.13417)
		(width 0.18288)
		(layer "In11.Cu")
		(net "M_H_CPU1_SB_DQ<3>")
	)
	(segment
		(start 185.067194 -224.518982)
		(end 185.067194 -224.881186)
		(width 0.18288)
		(layer "In11.Cu")
		(net "M_H_CPU1_SB_DQ<3>")
	)
	(segment
		(start 140.376402 -237.958884)
		(end 139.83716 -238.498126)
		(width 0.088646)
		(layer "In11.Cu")
		(net "M_H_CPU1_SB_DQ<3>")
	)
	(segment
		(start 164.80282 -227.54209)
		(end 164.544756 -227.284026)
		(width 0.18288)
		(layer "In11.Cu")
		(net "M_H_CPU1_SB_DQ<3>")
	)
	(segment
		(start 191.27216 -225.79076)
		(end 190.408814 -224.927414)
		(width 0.18288)
		(layer "In11.Cu")
		(net "M_H_CPU1_SB_DQ<3>")
	)
	(segment
		(start 127.899414 -238.549942)
		(end 127.884682 -238.541306)
		(width 0.088646)
		(layer "In11.Cu")
		(net "M_H_CPU1_SB_DQ<3>")
	)
	(segment
		(start 182.834026 -225.810826)
		(end 182.045356 -225.810826)
		(width 0.18288)
		(layer "In11.Cu")
		(net "M_H_CPU1_SB_DQ<3>")
	)
	(segment
		(start 185.067194 -224.881186)
		(end 184.874154 -225.074226)
		(width 0.18288)
		(layer "In11.Cu")
		(net "M_H_CPU1_SB_DQ<3>")
	)
	(segment
		(start 188.446918 -224.940114)
		(end 187.006738 -224.940114)
		(width 0.18288)
		(layer "In11.Cu")
		(net "M_H_CPU1_SB_DQ<3>")
	)
	(segment
		(start 126.959614 -238.549942)
		(end 126.9492 -238.543846)
		(width 0.088646)
		(layer "In11.Cu")
		(net "M_H_CPU1_SB_DQ<3>")
	)
	(segment
		(start 190.408814 -224.927414)
		(end 189.605158 -224.927414)
		(width 0.18288)
		(layer "In11.Cu")
		(net "M_H_CPU1_SB_DQ<3>")
	)
	(segment
		(start 128.839214 -238.549942)
		(end 128.824482 -238.541306)
		(width 0.088646)
		(layer "In11.Cu")
		(net "M_H_CPU1_SB_DQ<3>")
	)
	(segment
		(start 166.067994 -226.871784)
		(end 166.067994 -227.34905)
		(width 0.18288)
		(layer "In11.Cu")
		(net "M_H_CPU1_SB_DQ<3>")
	)
	(segment
		(start 185.577734 -224.325942)
		(end 185.260234 -224.325942)
		(width 0.18288)
		(layer "In11.Cu")
		(net "M_H_CPU1_SB_DQ<3>")
	)
	(segment
		(start 177.253392 -225.79076)
		(end 176.038002 -225.79076)
		(width 0.18288)
		(layer "In11.Cu")
		(net "M_H_CPU1_SB_DQ<3>")
	)
	(segment
		(start 181.341776 -225.009456)
		(end 181.148736 -225.202496)
		(width 0.18288)
		(layer "In11.Cu")
		(net "M_H_CPU1_SB_DQ<3>")
	)
	(segment
		(start 158.036768 -229.18928)
		(end 154.1907 -229.18928)
		(width 0.18288)
		(layer "In11.Cu")
		(net "M_H_CPU1_SB_DQ<3>")
	)
	(segment
		(start 186.872626 -225.074226)
		(end 185.963814 -225.074226)
		(width 0.18288)
		(layer "In11.Cu")
		(net "M_H_CPU1_SB_DQ<3>")
	)
	(segment
		(start 165.874954 -227.54209)
		(end 164.80282 -227.54209)
		(width 0.18288)
		(layer "In11.Cu")
		(net "M_H_CPU1_SB_DQ<3>")
	)
	(segment
		(start 179.862226 -225.810826)
		(end 179.418488 -225.367088)
		(width 0.18288)
		(layer "In11.Cu")
		(net "M_H_CPU1_SB_DQ<3>")
	)
	(segment
		(start 199.172322 -229.195122)
		(end 198.648574 -228.671374)
		(width 0.18288)
		(layer "In11.Cu")
		(net "M_H_CPU1_SB_DQ<3>")
	)
	(segment
		(start 180.955696 -225.810826)
		(end 179.862226 -225.810826)
		(width 0.18288)
		(layer "In11.Cu")
		(net "M_H_CPU1_SB_DQ<3>")
	)
	(segment
		(start 130.718814 -238.549942)
		(end 130.704082 -238.541306)
		(width 0.088646)
		(layer "In11.Cu")
		(net "M_H_CPU1_SB_DQ<3>")
	)
	(segment
		(start 168.11244 -227.54209)
		(end 166.964614 -227.54209)
		(width 0.18288)
		(layer "In11.Cu")
		(net "M_H_CPU1_SB_DQ<3>")
	)
	(segment
		(start 189.605158 -224.927414)
		(end 189.398402 -225.13417)
		(width 0.18288)
		(layer "In11.Cu")
		(net "M_H_CPU1_SB_DQ<3>")
	)
	(segment
		(start 181.659276 -225.009456)
		(end 181.341776 -225.009456)
		(width 0.18288)
		(layer "In11.Cu")
		(net "M_H_CPU1_SB_DQ<3>")
	)
	(segment
		(start 181.852316 -225.202496)
		(end 181.659276 -225.009456)
		(width 0.18288)
		(layer "In11.Cu")
		(net "M_H_CPU1_SB_DQ<3>")
	)
	(segment
		(start 168.93032 -226.72421)
		(end 168.11244 -227.54209)
		(width 0.18288)
		(layer "In11.Cu")
		(net "M_H_CPU1_SB_DQ<3>")
	)
	(segment
		(start 197.149974 -228.671374)
		(end 196.118226 -227.639626)
		(width 0.18288)
		(layer "In11.Cu")
		(net "M_H_CPU1_SB_DQ<3>")
	)
	(segment
		(start 203.821284 -228.967538)
		(end 203.5937 -229.195122)
		(width 0.18288)
		(layer "In11.Cu")
		(net "M_H_CPU1_SB_DQ<3>")
	)
	(segment
		(start 171.004738 -226.72421)
		(end 168.93032 -226.72421)
		(width 0.18288)
		(layer "In11.Cu")
		(net "M_H_CPU1_SB_DQ<3>")
	)
	(segment
		(start 181.852316 -225.617786)
		(end 181.852316 -225.202496)
		(width 0.18288)
		(layer "In11.Cu")
		(net "M_H_CPU1_SB_DQ<3>")
	)
	(segment
		(start 175.837596 -225.991166)
		(end 174.500286 -225.991166)
		(width 0.18288)
		(layer "In11.Cu")
		(net "M_H_CPU1_SB_DQ<3>")
	)
	(segment
		(start 154.1907 -229.18928)
		(end 145.421096 -237.958884)
		(width 0.18288)
		(layer "In11.Cu")
		(net "M_H_CPU1_SB_DQ<3>")
	)
	(segment
		(start 126.020068 -238.549942)
		(end 125.637544 -238.325914)
		(width 0.088646)
		(layer "In11.Cu")
		(net "M_H_CPU1_SB_DQ<3>")
	)
	(segment
		(start 171.985686 -226.930966)
		(end 171.211494 -226.930966)
		(width 0.18288)
		(layer "In11.Cu")
		(net "M_H_CPU1_SB_DQ<3>")
	)
	(segment
		(start 166.261034 -226.678744)
		(end 166.067994 -226.871784)
		(width 0.18288)
		(layer "In11.Cu")
		(net "M_H_CPU1_SB_DQ<3>")
	)
	(segment
		(start 159.67202 -228.149404)
		(end 159.47898 -228.342444)
		(width 0.18288)
		(layer "In11.Cu")
		(net "M_H_CPU1_SB_DQ<3>")
	)
	(segment
		(start 166.771574 -227.34905)
		(end 166.771574 -226.871784)
		(width 0.18288)
		(layer "In11.Cu")
		(net "M_H_CPU1_SB_DQ<3>")
	)
	(segment
		(start 162.141662 -228.342444)
		(end 160.56864 -228.342444)
		(width 0.18288)
		(layer "In11.Cu")
		(net "M_H_CPU1_SB_DQ<3>")
	)
	(segment
		(start 141.103096 -237.958884)
		(end 140.376402 -237.958884)
		(width 0.088646)
		(layer "In11.Cu")
		(net "M_H_CPU1_SB_DQ<3>")
	)
	(segment
		(start 187.006738 -224.940114)
		(end 186.872626 -225.074226)
		(width 0.18288)
		(layer "In11.Cu")
		(net "M_H_CPU1_SB_DQ<3>")
	)
	(segment
		(start 185.963814 -225.074226)
		(end 185.770774 -224.881186)
		(width 0.18288)
		(layer "In11.Cu")
		(net "M_H_CPU1_SB_DQ<3>")
	)
	(segment
		(start 160.56864 -228.342444)
		(end 160.3756 -228.149404)
		(width 0.18288)
		(layer "In11.Cu")
		(net "M_H_CPU1_SB_DQ<3>")
	)
	(segment
		(start 159.86506 -227.531422)
		(end 159.67202 -227.724462)
		(width 0.18288)
		(layer "In11.Cu")
		(net "M_H_CPU1_SB_DQ<3>")
	)
	(segment
		(start 158.883604 -228.342444)
		(end 158.036768 -229.18928)
		(width 0.18288)
		(layer "In11.Cu")
		(net "M_H_CPU1_SB_DQ<3>")
	)
	(segment
		(start 181.148736 -225.202496)
		(end 181.148736 -225.617786)
		(width 0.18288)
		(layer "In11.Cu")
		(net "M_H_CPU1_SB_DQ<3>")
	)
	(segment
		(start 145.421096 -237.958884)
		(end 141.103096 -237.958884)
		(width 0.18288)
		(layer "In11.Cu")
		(net "M_H_CPU1_SB_DQ<3>")
	)
	(segment
		(start 193.02476 -225.79076)
		(end 191.27216 -225.79076)
		(width 0.18288)
		(layer "In11.Cu")
		(net "M_H_CPU1_SB_DQ<3>")
	)
	(segment
		(start 166.964614 -227.54209)
		(end 166.771574 -227.34905)
		(width 0.18288)
		(layer "In11.Cu")
		(net "M_H_CPU1_SB_DQ<3>")
	)
	(segment
		(start 195.305426 -227.639626)
		(end 194.568826 -226.903026)
		(width 0.18288)
		(layer "In11.Cu")
		(net "M_H_CPU1_SB_DQ<3>")
	)
	(segment
		(start 173.850554 -226.640898)
		(end 172.275754 -226.640898)
		(width 0.18288)
		(layer "In11.Cu")
		(net "M_H_CPU1_SB_DQ<3>")
	)
	(arc
		(start 132.03301 -238.549942)
		(mid 131.845812 -238.600085)
		(end 131.658614 -238.549942)
		(width 0.088646)
		(layer "In11.Cu")
		(net "M_H_CPU1_SB_DQ<3>")
	)
	(arc
		(start 134.852664 -238.549942)
		(mid 134.665466 -238.600085)
		(end 134.478268 -238.549942)
		(width 0.088646)
		(layer "In11.Cu")
		(net "M_H_CPU1_SB_DQ<3>")
	)
	(arc
		(start 127.884682 -238.541306)
		(mid 127.608207 -238.473986)
		(end 127.33401 -238.549942)
		(width 0.088646)
		(layer "In11.Cu")
		(net "M_H_CPU1_SB_DQ<3>")
	)
	(arc
		(start 133.912864 -238.549942)
		(mid 133.725666 -238.600085)
		(end 133.538468 -238.549942)
		(width 0.088646)
		(layer "In11.Cu")
		(net "M_H_CPU1_SB_DQ<3>")
	)
	(arc
		(start 129.779014 -238.549942)
		(mid 129.496312 -238.474166)
		(end 129.21361 -238.549942)
		(width 0.088646)
		(layer "In11.Cu")
		(net "M_H_CPU1_SB_DQ<3>")
	)
	(arc
		(start 127.33401 -238.549942)
		(mid 127.146812 -238.600085)
		(end 126.959614 -238.549942)
		(width 0.088646)
		(layer "In11.Cu")
		(net "M_H_CPU1_SB_DQ<3>")
	)
	(arc
		(start 129.21361 -238.549942)
		(mid 129.026412 -238.600085)
		(end 128.839214 -238.549942)
		(width 0.088646)
		(layer "In11.Cu")
		(net "M_H_CPU1_SB_DQ<3>")
	)
	(arc
		(start 135.418068 -238.549942)
		(mid 135.135366 -238.474166)
		(end 134.852664 -238.549942)
		(width 0.088646)
		(layer "In11.Cu")
		(net "M_H_CPU1_SB_DQ<3>")
	)
	(arc
		(start 130.15341 -238.549942)
		(mid 129.966212 -238.600085)
		(end 129.779014 -238.549942)
		(width 0.088646)
		(layer "In11.Cu")
		(net "M_H_CPU1_SB_DQ<3>")
	)
	(arc
		(start 134.478268 -238.549942)
		(mid 134.195566 -238.474166)
		(end 133.912864 -238.549942)
		(width 0.088646)
		(layer "In11.Cu")
		(net "M_H_CPU1_SB_DQ<3>")
	)
	(arc
		(start 138.186414 -238.498126)
		(mid 138.128188 -238.495013)
		(end 138.07059 -238.485934)
		(width 0.088646)
		(layer "In11.Cu")
		(net "M_H_CPU1_SB_DQ<3>")
	)
	(arc
		(start 137.297668 -238.549942)
		(mid 137.014966 -238.474166)
		(end 136.732264 -238.549942)
		(width 0.088646)
		(layer "In11.Cu")
		(net "M_H_CPU1_SB_DQ<3>")
	)
	(arc
		(start 130.704082 -238.541306)
		(mid 130.427607 -238.473986)
		(end 130.15341 -238.549942)
		(width 0.088646)
		(layer "In11.Cu")
		(net "M_H_CPU1_SB_DQ<3>")
	)
	(arc
		(start 126.9492 -238.543846)
		(mid 126.671022 -238.474123)
		(end 126.394464 -238.549942)
		(width 0.088646)
		(layer "In11.Cu")
		(net "M_H_CPU1_SB_DQ<3>")
	)
	(arc
		(start 137.672064 -238.549942)
		(mid 137.484866 -238.600085)
		(end 137.297668 -238.549942)
		(width 0.088646)
		(layer "In11.Cu")
		(net "M_H_CPU1_SB_DQ<3>")
	)
	(arc
		(start 131.09321 -238.549942)
		(mid 130.906012 -238.600085)
		(end 130.718814 -238.549942)
		(width 0.088646)
		(layer "In11.Cu")
		(net "M_H_CPU1_SB_DQ<3>")
	)
	(arc
		(start 128.824482 -238.541306)
		(mid 128.548007 -238.473986)
		(end 128.27381 -238.549942)
		(width 0.088646)
		(layer "In11.Cu")
		(net "M_H_CPU1_SB_DQ<3>")
	)
	(arc
		(start 128.27381 -238.549942)
		(mid 128.086612 -238.600085)
		(end 127.899414 -238.549942)
		(width 0.088646)
		(layer "In11.Cu")
		(net "M_H_CPU1_SB_DQ<3>")
	)
	(arc
		(start 135.792464 -238.549942)
		(mid 135.605266 -238.600085)
		(end 135.418068 -238.549942)
		(width 0.088646)
		(layer "In11.Cu")
		(net "M_H_CPU1_SB_DQ<3>")
	)
	(arc
		(start 132.973064 -238.549942)
		(mid 132.785866 -238.600085)
		(end 132.598668 -238.549942)
		(width 0.088646)
		(layer "In11.Cu")
		(net "M_H_CPU1_SB_DQ<3>")
	)
	(arc
		(start 138.07059 -238.485934)
		(mid 137.865416 -238.48114)
		(end 137.672064 -238.549942)
		(width 0.088646)
		(layer "In11.Cu")
		(net "M_H_CPU1_SB_DQ<3>")
	)
	(arc
		(start 136.732264 -238.549942)
		(mid 136.545066 -238.600085)
		(end 136.357868 -238.549942)
		(width 0.088646)
		(layer "In11.Cu")
		(net "M_H_CPU1_SB_DQ<3>")
	)
	(arc
		(start 133.538468 -238.549942)
		(mid 133.255766 -238.474166)
		(end 132.973064 -238.549942)
		(width 0.088646)
		(layer "In11.Cu")
		(net "M_H_CPU1_SB_DQ<3>")
	)
	(arc
		(start 131.643882 -238.541306)
		(mid 131.367407 -238.473986)
		(end 131.09321 -238.549942)
		(width 0.088646)
		(layer "In11.Cu")
		(net "M_H_CPU1_SB_DQ<3>")
	)
	(arc
		(start 136.357868 -238.549942)
		(mid 136.075166 -238.474166)
		(end 135.792464 -238.549942)
		(width 0.088646)
		(layer "In11.Cu")
		(net "M_H_CPU1_SB_DQ<3>")
	)
	(arc
		(start 132.588254 -238.543846)
		(mid 132.309822 -238.474)
		(end 132.03301 -238.549942)
		(width 0.088646)
		(layer "In11.Cu")
		(net "M_H_CPU1_SB_DQ<3>")
	)
	(arc
		(start 125.637544 -238.325914)
		(mid 125.459056 -238.251113)
		(end 125.267212 -238.225584)
		(width 0.088646)
		(layer "In11.Cu")
		(net "M_H_CPU1_SB_DQ<3>")
	)
	(arc
		(start 126.394464 -238.549942)
		(mid 126.207266 -238.600085)
		(end 126.020068 -238.549942)
		(width 0.088646)
		(layer "In11.Cu")
		(net "M_H_CPU1_SB_DQ<3>")
	)
	(segment
		(start 123.387612 -227.36683)
		(end 123.387612 -226.831144)
		(width 0.20066)
		(layer "F.Cu")
		(net "M_H_CPU1_SB_DQ<31>")
	)
	(segment
		(start 212.630258 -196.05371)
		(end 213.311486 -196.05371)
		(width 0.20066)
		(layer "F.Cu")
		(net "M_H_CPU1_SB_DQ<31>")
	)
	(segment
		(start 214.133684 -195.364608)
		(end 214.385652 -195.616576)
		(width 0.20066)
		(layer "F.Cu")
		(net "M_H_CPU1_SB_DQ<31>")
	)
	(segment
		(start 210.598258 -196.04863)
		(end 210.603084 -196.04863)
		(width 0.101854)
		(layer "F.Cu")
		(net "M_H_CPU1_SB_DQ<31>")
	)
	(segment
		(start 213.311486 -196.05371)
		(end 213.515448 -195.849748)
		(width 0.20066)
		(layer "F.Cu")
		(net "M_H_CPU1_SB_DQ<31>")
	)
	(segment
		(start 214.385652 -195.616576)
		(end 215.719914 -195.616576)
		(width 0.20066)
		(layer "F.Cu")
		(net "M_H_CPU1_SB_DQ<31>")
	)
	(segment
		(start 123.387866 -227.367084)
		(end 123.387612 -227.36683)
		(width 0.20066)
		(layer "F.Cu")
		(net "M_H_CPU1_SB_DQ<31>")
	)
	(segment
		(start 212.618066 -196.041518)
		(end 212.630258 -196.05371)
		(width 0.1016)
		(layer "F.Cu")
		(net "M_H_CPU1_SB_DQ<31>")
	)
	(segment
		(start 213.515448 -195.598796)
		(end 213.749636 -195.364608)
		(width 0.20066)
		(layer "F.Cu")
		(net "M_H_CPU1_SB_DQ<31>")
	)
	(segment
		(start 213.749636 -195.364608)
		(end 214.133684 -195.364608)
		(width 0.20066)
		(layer "F.Cu")
		(net "M_H_CPU1_SB_DQ<31>")
	)
	(segment
		(start 210.603084 -196.04863)
		(end 210.610196 -196.041518)
		(width 0.1016)
		(layer "F.Cu")
		(net "M_H_CPU1_SB_DQ<31>")
	)
	(segment
		(start 207.071214 -195.616576)
		(end 208.176114 -195.616576)
		(width 0.20066)
		(layer "F.Cu")
		(net "M_H_CPU1_SB_DQ<31>")
	)
	(segment
		(start 210.610196 -196.041518)
		(end 212.618066 -196.041518)
		(width 0.1016)
		(layer "F.Cu")
		(net "M_H_CPU1_SB_DQ<31>")
	)
	(segment
		(start 210.306412 -196.04863)
		(end 210.598258 -196.04863)
		(width 0.20066)
		(layer "F.Cu")
		(net "M_H_CPU1_SB_DQ<31>")
	)
	(segment
		(start 208.176114 -195.616576)
		(end 209.874358 -195.616576)
		(width 0.20066)
		(layer "F.Cu")
		(net "M_H_CPU1_SB_DQ<31>")
	)
	(segment
		(start 209.874358 -195.616576)
		(end 210.306412 -196.04863)
		(width 0.20066)
		(layer "F.Cu")
		(net "M_H_CPU1_SB_DQ<31>")
	)
	(segment
		(start 213.515448 -195.849748)
		(end 213.515448 -195.598796)
		(width 0.20066)
		(layer "F.Cu")
		(net "M_H_CPU1_SB_DQ<31>")
	)
	(segment
		(start 175.1965 -195.051426)
		(end 174.07255 -195.051426)
		(width 0.18288)
		(layer "In11.Cu")
		(net "M_H_CPU1_SB_DQ<31>")
	)
	(segment
		(start 145.14195 -214.973916)
		(end 140.049758 -220.066108)
		(width 0.18288)
		(layer "In11.Cu")
		(net "M_H_CPU1_SB_DQ<31>")
	)
	(segment
		(start 194.949826 -196.550026)
		(end 194.264026 -195.864226)
		(width 0.18288)
		(layer "In11.Cu")
		(net "M_H_CPU1_SB_DQ<31>")
	)
	(segment
		(start 197.705726 -196.804026)
		(end 195.604892 -196.804026)
		(width 0.18288)
		(layer "In11.Cu")
		(net "M_H_CPU1_SB_DQ<31>")
	)
	(segment
		(start 203.256642 -197.742048)
		(end 202.602084 -197.742048)
		(width 0.18288)
		(layer "In11.Cu")
		(net "M_H_CPU1_SB_DQ<31>")
	)
	(segment
		(start 128.758696 -225.701606)
		(end 128.743964 -225.69297)
		(width 0.088646)
		(layer "In11.Cu")
		(net "M_H_CPU1_SB_DQ<31>")
	)
	(segment
		(start 189.72911 -195.083684)
		(end 188.187076 -196.041518)
		(width 0.18288)
		(layer "In11.Cu")
		(net "M_H_CPU1_SB_DQ<31>")
	)
	(segment
		(start 124.140468 -226.506786)
		(end 124.130054 -226.512882)
		(width 0.088646)
		(layer "In11.Cu")
		(net "M_H_CPU1_SB_DQ<31>")
	)
	(segment
		(start 191.142366 -195.191634)
		(end 190.44793 -195.083684)
		(width 0.18288)
		(layer "In11.Cu")
		(net "M_H_CPU1_SB_DQ<31>")
	)
	(segment
		(start 194.264026 -195.864226)
		(end 193.451226 -195.864226)
		(width 0.18288)
		(layer "In11.Cu")
		(net "M_H_CPU1_SB_DQ<31>")
	)
	(segment
		(start 165.981126 -196.677026)
		(end 165.469062 -196.677026)
		(width 0.18288)
		(layer "In11.Cu")
		(net "M_H_CPU1_SB_DQ<31>")
	)
	(segment
		(start 207.05064 -195.68541)
		(end 203.256642 -197.742048)
		(width 0.18288)
		(layer "In11.Cu")
		(net "M_H_CPU1_SB_DQ<31>")
	)
	(segment
		(start 123.200414 -226.506786)
		(end 123.191524 -226.511866)
		(width 0.088646)
		(layer "In11.Cu")
		(net "M_H_CPU1_SB_DQ<31>")
	)
	(segment
		(start 187.590176 -196.041518)
		(end 186.900312 -195.92798)
		(width 0.18288)
		(layer "In11.Cu")
		(net "M_H_CPU1_SB_DQ<31>")
	)
	(segment
		(start 139.55141 -222.963994)
		(end 139.32408 -223.191324)
		(width 0.088646)
		(layer "In11.Cu")
		(net "M_H_CPU1_SB_DQ<31>")
	)
	(segment
		(start 138.237468 -223.251268)
		(end 138.228578 -223.256348)
		(width 0.088646)
		(layer "In11.Cu")
		(net "M_H_CPU1_SB_DQ<31>")
	)
	(segment
		(start 186.900312 -195.92798)
		(end 184.610502 -195.92798)
		(width 0.18288)
		(layer "In11.Cu")
		(net "M_H_CPU1_SB_DQ<31>")
	)
	(segment
		(start 182.307992 -196.265038)
		(end 180.655214 -196.265038)
		(width 0.18288)
		(layer "In11.Cu")
		(net "M_H_CPU1_SB_DQ<31>")
	)
	(segment
		(start 165.469062 -196.677026)
		(end 164.29228 -197.007226)
		(width 0.18288)
		(layer "In11.Cu")
		(net "M_H_CPU1_SB_DQ<31>")
	)
	(segment
		(start 123.074938 -226.831144)
		(end 123.387612 -226.831144)
		(width 0.088646)
		(layer "In11.Cu")
		(net "M_H_CPU1_SB_DQ<31>")
	)
	(segment
		(start 131.578096 -225.701606)
		(end 131.563364 -225.69297)
		(width 0.088646)
		(layer "In11.Cu")
		(net "M_H_CPU1_SB_DQ<31>")
	)
	(segment
		(start 153.04897 -203.971652)
		(end 145.14195 -211.878672)
		(width 0.18288)
		(layer "In11.Cu")
		(net "M_H_CPU1_SB_DQ<31>")
	)
	(segment
		(start 177.399188 -195.191634)
		(end 176.23409 -195.191634)
		(width 0.18288)
		(layer "In11.Cu")
		(net "M_H_CPU1_SB_DQ<31>")
	)
	(segment
		(start 153.04897 -201.962766)
		(end 153.04897 -203.971652)
		(width 0.18288)
		(layer "In11.Cu")
		(net "M_H_CPU1_SB_DQ<31>")
	)
	(segment
		(start 125.939296 -225.701606)
		(end 125.924564 -225.69297)
		(width 0.088646)
		(layer "In11.Cu")
		(net "M_H_CPU1_SB_DQ<31>")
	)
	(segment
		(start 145.14195 -211.878672)
		(end 145.14195 -214.973916)
		(width 0.18288)
		(layer "In11.Cu")
		(net "M_H_CPU1_SB_DQ<31>")
	)
	(segment
		(start 164.29228 -197.007226)
		(end 163.796726 -197.007226)
		(width 0.18288)
		(layer "In11.Cu")
		(net "M_H_CPU1_SB_DQ<31>")
	)
	(segment
		(start 190.44793 -195.083684)
		(end 189.72911 -195.083684)
		(width 0.18288)
		(layer "In11.Cu")
		(net "M_H_CPU1_SB_DQ<31>")
	)
	(segment
		(start 161.16554 -197.57898)
		(end 159.302704 -198.543418)
		(width 0.18288)
		(layer "In11.Cu")
		(net "M_H_CPU1_SB_DQ<31>")
	)
	(segment
		(start 202.602084 -197.742048)
		(end 201.31786 -197.139052)
		(width 0.18288)
		(layer "In11.Cu")
		(net "M_H_CPU1_SB_DQ<31>")
	)
	(segment
		(start 135.230616 -225.203258)
		(end 135.230616 -225.2218)
		(width 0.088646)
		(layer "In11.Cu")
		(net "M_H_CPU1_SB_DQ<31>")
	)
	(segment
		(start 176.23409 -195.191634)
		(end 175.1965 -195.051426)
		(width 0.18288)
		(layer "In11.Cu")
		(net "M_H_CPU1_SB_DQ<31>")
	)
	(segment
		(start 184.610502 -195.92798)
		(end 182.307992 -196.265038)
		(width 0.18288)
		(layer "In11.Cu")
		(net "M_H_CPU1_SB_DQ<31>")
	)
	(segment
		(start 138.050016 -223.575626)
		(end 138.050016 -223.585532)
		(width 0.088646)
		(layer "In11.Cu")
		(net "M_H_CPU1_SB_DQ<31>")
	)
	(segment
		(start 132.517896 -225.701606)
		(end 132.503164 -225.69297)
		(width 0.088646)
		(layer "In11.Cu")
		(net "M_H_CPU1_SB_DQ<31>")
	)
	(segment
		(start 139.55141 -220.564456)
		(end 139.55141 -222.963994)
		(width 0.088646)
		(layer "In11.Cu")
		(net "M_H_CPU1_SB_DQ<31>")
	)
	(segment
		(start 169.543984 -195.85051)
		(end 167.89527 -196.394578)
		(width 0.18288)
		(layer "In11.Cu")
		(net "M_H_CPU1_SB_DQ<31>")
	)
	(segment
		(start 123.017534 -226.77374)
		(end 123.074938 -226.831144)
		(width 0.088646)
		(layer "In11.Cu")
		(net "M_H_CPU1_SB_DQ<31>")
	)
	(segment
		(start 129.698496 -225.701606)
		(end 129.683764 -225.69297)
		(width 0.088646)
		(layer "In11.Cu")
		(net "M_H_CPU1_SB_DQ<31>")
	)
	(segment
		(start 192.778634 -195.191634)
		(end 191.142366 -195.191634)
		(width 0.18288)
		(layer "In11.Cu")
		(net "M_H_CPU1_SB_DQ<31>")
	)
	(segment
		(start 137.767568 -224.065084)
		(end 137.758678 -224.070164)
		(width 0.088646)
		(layer "In11.Cu")
		(net "M_H_CPU1_SB_DQ<31>")
	)
	(segment
		(start 172.193458 -196.04101)
		(end 172.002958 -195.85051)
		(width 0.18288)
		(layer "In11.Cu")
		(net "M_H_CPU1_SB_DQ<31>")
	)
	(segment
		(start 159.302704 -198.543418)
		(end 156.468318 -198.543418)
		(width 0.18288)
		(layer "In11.Cu")
		(net "M_H_CPU1_SB_DQ<31>")
	)
	(segment
		(start 125.08611 -226.50323)
		(end 125.080014 -226.506786)
		(width 0.088646)
		(layer "In11.Cu")
		(net "M_H_CPU1_SB_DQ<31>")
	)
	(segment
		(start 130.638296 -225.701606)
		(end 130.623564 -225.69297)
		(width 0.088646)
		(layer "In11.Cu")
		(net "M_H_CPU1_SB_DQ<31>")
	)
	(segment
		(start 207.071214 -195.616576)
		(end 207.05064 -195.68541)
		(width 0.18288)
		(layer "In11.Cu")
		(net "M_H_CPU1_SB_DQ<31>")
	)
	(segment
		(start 174.07255 -195.051426)
		(end 173.082966 -196.04101)
		(width 0.18288)
		(layer "In11.Cu")
		(net "M_H_CPU1_SB_DQ<31>")
	)
	(segment
		(start 173.082966 -196.04101)
		(end 172.193458 -196.04101)
		(width 0.18288)
		(layer "In11.Cu")
		(net "M_H_CPU1_SB_DQ<31>")
	)
	(segment
		(start 188.187076 -196.041518)
		(end 187.590176 -196.041518)
		(width 0.18288)
		(layer "In11.Cu")
		(net "M_H_CPU1_SB_DQ<31>")
	)
	(segment
		(start 135.418068 -224.8789)
		(end 135.409178 -224.88398)
		(width 0.088646)
		(layer "In11.Cu")
		(net "M_H_CPU1_SB_DQ<31>")
	)
	(segment
		(start 156.468318 -198.543418)
		(end 153.04897 -201.962766)
		(width 0.18288)
		(layer "In11.Cu")
		(net "M_H_CPU1_SB_DQ<31>")
	)
	(segment
		(start 137.580116 -224.389442)
		(end 137.580116 -224.399348)
		(width 0.088646)
		(layer "In11.Cu")
		(net "M_H_CPU1_SB_DQ<31>")
	)
	(segment
		(start 126.879096 -225.701606)
		(end 126.864364 -225.69297)
		(width 0.088646)
		(layer "In11.Cu")
		(net "M_H_CPU1_SB_DQ<31>")
	)
	(segment
		(start 172.002958 -195.85051)
		(end 169.543984 -195.85051)
		(width 0.18288)
		(layer "In11.Cu")
		(net "M_H_CPU1_SB_DQ<31>")
	)
	(segment
		(start 180.655214 -196.265038)
		(end 177.399188 -195.191634)
		(width 0.18288)
		(layer "In11.Cu")
		(net "M_H_CPU1_SB_DQ<31>")
	)
	(segment
		(start 125.550168 -225.69297)
		(end 125.541278 -225.69805)
		(width 0.088646)
		(layer "In11.Cu")
		(net "M_H_CPU1_SB_DQ<31>")
	)
	(segment
		(start 140.049758 -220.066108)
		(end 139.55141 -220.564456)
		(width 0.088646)
		(layer "In11.Cu")
		(net "M_H_CPU1_SB_DQ<31>")
	)
	(segment
		(start 193.451226 -195.864226)
		(end 192.778634 -195.191634)
		(width 0.18288)
		(layer "In11.Cu")
		(net "M_H_CPU1_SB_DQ<31>")
	)
	(segment
		(start 195.604892 -196.804026)
		(end 194.949826 -196.550026)
		(width 0.18288)
		(layer "In11.Cu")
		(net "M_H_CPU1_SB_DQ<31>")
	)
	(segment
		(start 125.080014 -226.506786)
		(end 125.0696 -226.512882)
		(width 0.088646)
		(layer "In11.Cu")
		(net "M_H_CPU1_SB_DQ<31>")
	)
	(segment
		(start 138.659616 -223.279208)
		(end 138.611864 -223.251268)
		(width 0.088646)
		(layer "In11.Cu")
		(net "M_H_CPU1_SB_DQ<31>")
	)
	(segment
		(start 167.89527 -196.394578)
		(end 165.981126 -196.677026)
		(width 0.18288)
		(layer "In11.Cu")
		(net "M_H_CPU1_SB_DQ<31>")
	)
	(segment
		(start 201.31786 -197.139052)
		(end 197.705726 -196.804026)
		(width 0.18288)
		(layer "In11.Cu")
		(net "M_H_CPU1_SB_DQ<31>")
	)
	(segment
		(start 127.818896 -225.701606)
		(end 127.804164 -225.69297)
		(width 0.088646)
		(layer "In11.Cu")
		(net "M_H_CPU1_SB_DQ<31>")
	)
	(segment
		(start 163.796726 -197.007226)
		(end 161.16554 -197.57898)
		(width 0.18288)
		(layer "In11.Cu")
		(net "M_H_CPU1_SB_DQ<31>")
	)
	(arc
		(start 133.442964 -225.69297)
		(mid 133.255766 -225.642827)
		(end 133.068568 -225.69297)
		(width 0.088646)
		(layer "In11.Cu")
		(net "M_H_CPU1_SB_DQ<31>")
	)
	(arc
		(start 126.864364 -225.69297)
		(mid 126.677166 -225.642827)
		(end 126.489968 -225.69297)
		(width 0.088646)
		(layer "In11.Cu")
		(net "M_H_CPU1_SB_DQ<31>")
	)
	(arc
		(start 125.541278 -225.69805)
		(mid 125.410364 -225.83441)
		(end 125.362716 -226.017328)
		(width 0.088646)
		(layer "In11.Cu")
		(net "M_H_CPU1_SB_DQ<31>")
	)
	(arc
		(start 129.309368 -225.69297)
		(mid 129.035139 -225.768895)
		(end 128.758696 -225.701606)
		(width 0.088646)
		(layer "In11.Cu")
		(net "M_H_CPU1_SB_DQ<31>")
	)
	(arc
		(start 138.228578 -223.256348)
		(mid 138.097664 -223.392708)
		(end 138.050016 -223.575626)
		(width 0.088646)
		(layer "In11.Cu")
		(net "M_H_CPU1_SB_DQ<31>")
	)
	(arc
		(start 139.32408 -223.191324)
		(mid 139.268464 -223.239982)
		(end 139.206986 -223.280986)
		(width 0.088646)
		(layer "In11.Cu")
		(net "M_H_CPU1_SB_DQ<31>")
	)
	(arc
		(start 128.369568 -225.69297)
		(mid 128.095339 -225.768895)
		(end 127.818896 -225.701606)
		(width 0.088646)
		(layer "In11.Cu")
		(net "M_H_CPU1_SB_DQ<31>")
	)
	(arc
		(start 138.611864 -223.251268)
		(mid 138.424666 -223.201125)
		(end 138.237468 -223.251268)
		(width 0.088646)
		(layer "In11.Cu")
		(net "M_H_CPU1_SB_DQ<31>")
	)
	(arc
		(start 136.732264 -224.8789)
		(mid 136.545066 -224.828757)
		(end 136.357868 -224.8789)
		(width 0.088646)
		(layer "In11.Cu")
		(net "M_H_CPU1_SB_DQ<31>")
	)
	(arc
		(start 135.792464 -224.8789)
		(mid 135.605266 -224.828757)
		(end 135.418068 -224.8789)
		(width 0.088646)
		(layer "In11.Cu")
		(net "M_H_CPU1_SB_DQ<31>")
	)
	(arc
		(start 135.230616 -225.2218)
		(mid 135.150454 -225.493989)
		(end 134.948168 -225.69297)
		(width 0.088646)
		(layer "In11.Cu")
		(net "M_H_CPU1_SB_DQ<31>")
	)
	(arc
		(start 134.948168 -225.69297)
		(mid 134.665466 -225.768712)
		(end 134.382764 -225.69297)
		(width 0.088646)
		(layer "In11.Cu")
		(net "M_H_CPU1_SB_DQ<31>")
	)
	(arc
		(start 127.429768 -225.69297)
		(mid 127.155539 -225.768895)
		(end 126.879096 -225.701606)
		(width 0.088646)
		(layer "In11.Cu")
		(net "M_H_CPU1_SB_DQ<31>")
	)
	(arc
		(start 139.206986 -223.280986)
		(mid 138.933078 -223.353909)
		(end 138.659616 -223.279208)
		(width 0.088646)
		(layer "In11.Cu")
		(net "M_H_CPU1_SB_DQ<31>")
	)
	(arc
		(start 130.623564 -225.69297)
		(mid 130.436366 -225.642827)
		(end 130.249168 -225.69297)
		(width 0.088646)
		(layer "In11.Cu")
		(net "M_H_CPU1_SB_DQ<31>")
	)
	(arc
		(start 131.563364 -225.69297)
		(mid 131.376166 -225.642827)
		(end 131.188968 -225.69297)
		(width 0.088646)
		(layer "In11.Cu")
		(net "M_H_CPU1_SB_DQ<31>")
	)
	(arc
		(start 136.357868 -224.8789)
		(mid 136.075166 -224.954676)
		(end 135.792464 -224.8789)
		(width 0.088646)
		(layer "In11.Cu")
		(net "M_H_CPU1_SB_DQ<31>")
	)
	(arc
		(start 125.0696 -226.512882)
		(mid 124.791422 -226.582605)
		(end 124.514864 -226.506786)
		(width 0.088646)
		(layer "In11.Cu")
		(net "M_H_CPU1_SB_DQ<31>")
	)
	(arc
		(start 133.068568 -225.69297)
		(mid 132.794339 -225.768895)
		(end 132.517896 -225.701606)
		(width 0.088646)
		(layer "In11.Cu")
		(net "M_H_CPU1_SB_DQ<31>")
	)
	(arc
		(start 124.514864 -226.506786)
		(mid 124.327666 -226.456643)
		(end 124.140468 -226.506786)
		(width 0.088646)
		(layer "In11.Cu")
		(net "M_H_CPU1_SB_DQ<31>")
	)
	(arc
		(start 137.297668 -224.8789)
		(mid 137.014966 -224.954676)
		(end 136.732264 -224.8789)
		(width 0.088646)
		(layer "In11.Cu")
		(net "M_H_CPU1_SB_DQ<31>")
	)
	(arc
		(start 137.580116 -224.399348)
		(mid 137.502005 -224.676297)
		(end 137.297668 -224.8789)
		(width 0.088646)
		(layer "In11.Cu")
		(net "M_H_CPU1_SB_DQ<31>")
	)
	(arc
		(start 132.128768 -225.69297)
		(mid 131.854539 -225.768895)
		(end 131.578096 -225.701606)
		(width 0.088646)
		(layer "In11.Cu")
		(net "M_H_CPU1_SB_DQ<31>")
	)
	(arc
		(start 138.050016 -223.585532)
		(mid 137.971905 -223.862481)
		(end 137.767568 -224.065084)
		(width 0.088646)
		(layer "In11.Cu")
		(net "M_H_CPU1_SB_DQ<31>")
	)
	(arc
		(start 134.008368 -225.69297)
		(mid 133.725666 -225.768712)
		(end 133.442964 -225.69297)
		(width 0.088646)
		(layer "In11.Cu")
		(net "M_H_CPU1_SB_DQ<31>")
	)
	(arc
		(start 125.924564 -225.69297)
		(mid 125.737366 -225.642827)
		(end 125.550168 -225.69297)
		(width 0.088646)
		(layer "In11.Cu")
		(net "M_H_CPU1_SB_DQ<31>")
	)
	(arc
		(start 127.804164 -225.69297)
		(mid 127.616966 -225.642827)
		(end 127.429768 -225.69297)
		(width 0.088646)
		(layer "In11.Cu")
		(net "M_H_CPU1_SB_DQ<31>")
	)
	(arc
		(start 123.57481 -226.506786)
		(mid 123.387612 -226.456643)
		(end 123.200414 -226.506786)
		(width 0.088646)
		(layer "In11.Cu")
		(net "M_H_CPU1_SB_DQ<31>")
	)
	(arc
		(start 126.489968 -225.69297)
		(mid 126.215739 -225.768895)
		(end 125.939296 -225.701606)
		(width 0.088646)
		(layer "In11.Cu")
		(net "M_H_CPU1_SB_DQ<31>")
	)
	(arc
		(start 128.743964 -225.69297)
		(mid 128.556766 -225.642827)
		(end 128.369568 -225.69297)
		(width 0.088646)
		(layer "In11.Cu")
		(net "M_H_CPU1_SB_DQ<31>")
	)
	(arc
		(start 125.362716 -226.017328)
		(mid 125.288725 -226.296894)
		(end 125.08611 -226.50323)
		(width 0.088646)
		(layer "In11.Cu")
		(net "M_H_CPU1_SB_DQ<31>")
	)
	(arc
		(start 123.191524 -226.511866)
		(mid 123.075785 -226.62369)
		(end 123.017534 -226.77374)
		(width 0.088646)
		(layer "In11.Cu")
		(net "M_H_CPU1_SB_DQ<31>")
	)
	(arc
		(start 137.758678 -224.070164)
		(mid 137.627764 -224.206524)
		(end 137.580116 -224.389442)
		(width 0.088646)
		(layer "In11.Cu")
		(net "M_H_CPU1_SB_DQ<31>")
	)
	(arc
		(start 129.683764 -225.69297)
		(mid 129.496566 -225.642827)
		(end 129.309368 -225.69297)
		(width 0.088646)
		(layer "In11.Cu")
		(net "M_H_CPU1_SB_DQ<31>")
	)
	(arc
		(start 130.249168 -225.69297)
		(mid 129.974939 -225.768895)
		(end 129.698496 -225.701606)
		(width 0.088646)
		(layer "In11.Cu")
		(net "M_H_CPU1_SB_DQ<31>")
	)
	(arc
		(start 132.503164 -225.69297)
		(mid 132.315966 -225.642827)
		(end 132.128768 -225.69297)
		(width 0.088646)
		(layer "In11.Cu")
		(net "M_H_CPU1_SB_DQ<31>")
	)
	(arc
		(start 131.188968 -225.69297)
		(mid 130.914739 -225.768895)
		(end 130.638296 -225.701606)
		(width 0.088646)
		(layer "In11.Cu")
		(net "M_H_CPU1_SB_DQ<31>")
	)
	(arc
		(start 134.382764 -225.69297)
		(mid 134.195566 -225.642827)
		(end 134.008368 -225.69297)
		(width 0.088646)
		(layer "In11.Cu")
		(net "M_H_CPU1_SB_DQ<31>")
	)
	(arc
		(start 124.130054 -226.512882)
		(mid 123.851622 -226.582728)
		(end 123.57481 -226.506786)
		(width 0.088646)
		(layer "In11.Cu")
		(net "M_H_CPU1_SB_DQ<31>")
	)
	(arc
		(start 135.409178 -224.88398)
		(mid 135.278264 -225.02034)
		(end 135.230616 -225.203258)
		(width 0.088646)
		(layer "In11.Cu")
		(net "M_H_CPU1_SB_DQ<31>")
	)
	(segment
		(start 126.207266 -227.367084)
		(end 126.207012 -227.36683)
		(width 0.20066)
		(layer "F.Cu")
		(net "M_H_CPU1_SB_DQ<30>")
	)
	(segment
		(start 213.749636 -197.06463)
		(end 214.133684 -197.06463)
		(width 0.20066)
		(layer "F.Cu")
		(net "M_H_CPU1_SB_DQ<30>")
	)
	(segment
		(start 208.176114 -197.316598)
		(end 209.874358 -197.316598)
		(width 0.20066)
		(layer "F.Cu")
		(net "M_H_CPU1_SB_DQ<30>")
	)
	(segment
		(start 213.311486 -197.753732)
		(end 213.515448 -197.54977)
		(width 0.20066)
		(layer "F.Cu")
		(net "M_H_CPU1_SB_DQ<30>")
	)
	(segment
		(start 210.610196 -197.74154)
		(end 212.618066 -197.74154)
		(width 0.1016)
		(layer "F.Cu")
		(net "M_H_CPU1_SB_DQ<30>")
	)
	(segment
		(start 210.306412 -197.748652)
		(end 210.598258 -197.748652)
		(width 0.20066)
		(layer "F.Cu")
		(net "M_H_CPU1_SB_DQ<30>")
	)
	(segment
		(start 210.598258 -197.748652)
		(end 210.603084 -197.748652)
		(width 0.101854)
		(layer "F.Cu")
		(net "M_H_CPU1_SB_DQ<30>")
	)
	(segment
		(start 209.874358 -197.316598)
		(end 210.306412 -197.748652)
		(width 0.20066)
		(layer "F.Cu")
		(net "M_H_CPU1_SB_DQ<30>")
	)
	(segment
		(start 213.515448 -197.54977)
		(end 213.515448 -197.298818)
		(width 0.20066)
		(layer "F.Cu")
		(net "M_H_CPU1_SB_DQ<30>")
	)
	(segment
		(start 126.207012 -227.36683)
		(end 126.207012 -226.831144)
		(width 0.20066)
		(layer "F.Cu")
		(net "M_H_CPU1_SB_DQ<30>")
	)
	(segment
		(start 207.071214 -197.316598)
		(end 208.176114 -197.316598)
		(width 0.20066)
		(layer "F.Cu")
		(net "M_H_CPU1_SB_DQ<30>")
	)
	(segment
		(start 214.133684 -197.06463)
		(end 214.385652 -197.316598)
		(width 0.20066)
		(layer "F.Cu")
		(net "M_H_CPU1_SB_DQ<30>")
	)
	(segment
		(start 212.618066 -197.74154)
		(end 212.630258 -197.753732)
		(width 0.1016)
		(layer "F.Cu")
		(net "M_H_CPU1_SB_DQ<30>")
	)
	(segment
		(start 210.603084 -197.748652)
		(end 210.610196 -197.74154)
		(width 0.1016)
		(layer "F.Cu")
		(net "M_H_CPU1_SB_DQ<30>")
	)
	(segment
		(start 212.630258 -197.753732)
		(end 213.311486 -197.753732)
		(width 0.20066)
		(layer "F.Cu")
		(net "M_H_CPU1_SB_DQ<30>")
	)
	(segment
		(start 213.515448 -197.298818)
		(end 213.749636 -197.06463)
		(width 0.20066)
		(layer "F.Cu")
		(net "M_H_CPU1_SB_DQ<30>")
	)
	(segment
		(start 214.385652 -197.316598)
		(end 215.719914 -197.316598)
		(width 0.20066)
		(layer "F.Cu")
		(net "M_H_CPU1_SB_DQ<30>")
	)
	(segment
		(start 182.991252 -198.501)
		(end 180.39334 -198.501)
		(width 0.18288)
		(layer "In11.Cu")
		(net "M_H_CPU1_SB_DQ<30>")
	)
	(segment
		(start 125.894338 -226.831144)
		(end 126.207012 -226.831144)
		(width 0.088646)
		(layer "In11.Cu")
		(net "M_H_CPU1_SB_DQ<30>")
	)
	(segment
		(start 160.349946 -200.238106)
		(end 156.584396 -200.238106)
		(width 0.18288)
		(layer "In11.Cu")
		(net "M_H_CPU1_SB_DQ<30>")
	)
	(segment
		(start 198.607426 -199.242426)
		(end 197.921626 -198.556626)
		(width 0.18288)
		(layer "In11.Cu")
		(net "M_H_CPU1_SB_DQ<30>")
	)
	(segment
		(start 170.679618 -197.489826)
		(end 168.717214 -199.45223)
		(width 0.18288)
		(layer "In11.Cu")
		(net "M_H_CPU1_SB_DQ<30>")
	)
	(segment
		(start 178.617626 -197.388226)
		(end 177.830226 -197.388226)
		(width 0.18288)
		(layer "In11.Cu")
		(net "M_H_CPU1_SB_DQ<30>")
	)
	(segment
		(start 180.39334 -198.501)
		(end 179.496466 -197.604126)
		(width 0.18288)
		(layer "In11.Cu")
		(net "M_H_CPU1_SB_DQ<30>")
	)
	(segment
		(start 154.513534 -202.308968)
		(end 154.513534 -204.200506)
		(width 0.18288)
		(layer "In11.Cu")
		(net "M_H_CPU1_SB_DQ<30>")
	)
	(segment
		(start 134.478014 -226.506786)
		(end 134.4676 -226.512882)
		(width 0.088646)
		(layer "In11.Cu")
		(net "M_H_CPU1_SB_DQ<30>")
	)
	(segment
		(start 132.598414 -226.506786)
		(end 132.583682 -226.515422)
		(width 0.088646)
		(layer "In11.Cu")
		(net "M_H_CPU1_SB_DQ<30>")
	)
	(segment
		(start 156.584396 -200.238106)
		(end 154.513534 -202.308968)
		(width 0.18288)
		(layer "In11.Cu")
		(net "M_H_CPU1_SB_DQ<30>")
	)
	(segment
		(start 163.910518 -199.369934)
		(end 161.218118 -199.369934)
		(width 0.18288)
		(layer "In11.Cu")
		(net "M_H_CPU1_SB_DQ<30>")
	)
	(segment
		(start 140.084556 -223.217994)
		(end 139.288012 -224.014538)
		(width 0.088646)
		(layer "In11.Cu")
		(net "M_H_CPU1_SB_DQ<30>")
	)
	(segment
		(start 138.237468 -224.8789)
		(end 138.228578 -224.88398)
		(width 0.088646)
		(layer "In11.Cu")
		(net "M_H_CPU1_SB_DQ<30>")
	)
	(segment
		(start 202.46848 -199.441816)
		(end 202.26909 -199.242426)
		(width 0.18288)
		(layer "In11.Cu")
		(net "M_H_CPU1_SB_DQ<30>")
	)
	(segment
		(start 138.519916 -224.389442)
		(end 138.519916 -224.399348)
		(width 0.088646)
		(layer "In11.Cu")
		(net "M_H_CPU1_SB_DQ<30>")
	)
	(segment
		(start 129.779014 -226.506786)
		(end 129.764282 -226.515422)
		(width 0.088646)
		(layer "In11.Cu")
		(net "M_H_CPU1_SB_DQ<30>")
	)
	(segment
		(start 194.238626 -197.566026)
		(end 193.425826 -197.566026)
		(width 0.18288)
		(layer "In11.Cu")
		(net "M_H_CPU1_SB_DQ<30>")
	)
	(segment
		(start 174.122588 -196.777864)
		(end 173.159166 -197.741286)
		(width 0.18288)
		(layer "In11.Cu")
		(net "M_H_CPU1_SB_DQ<30>")
	)
	(segment
		(start 197.921626 -198.556626)
		(end 195.229226 -198.556626)
		(width 0.18288)
		(layer "In11.Cu")
		(net "M_H_CPU1_SB_DQ<30>")
	)
	(segment
		(start 133.538468 -226.506786)
		(end 133.528054 -226.512882)
		(width 0.088646)
		(layer "In11.Cu")
		(net "M_H_CPU1_SB_DQ<30>")
	)
	(segment
		(start 171.810426 -197.489826)
		(end 170.679618 -197.489826)
		(width 0.18288)
		(layer "In11.Cu")
		(net "M_H_CPU1_SB_DQ<30>")
	)
	(segment
		(start 187.022486 -197.741286)
		(end 186.909202 -197.628002)
		(width 0.18288)
		(layer "In11.Cu")
		(net "M_H_CPU1_SB_DQ<30>")
	)
	(segment
		(start 178.833526 -197.604126)
		(end 178.617626 -197.388226)
		(width 0.18288)
		(layer "In11.Cu")
		(net "M_H_CPU1_SB_DQ<30>")
	)
	(segment
		(start 126.019814 -226.506786)
		(end 126.010924 -226.511866)
		(width 0.088646)
		(layer "In11.Cu")
		(net "M_H_CPU1_SB_DQ<30>")
	)
	(segment
		(start 190.741046 -196.891402)
		(end 190.581026 -196.731382)
		(width 0.18288)
		(layer "In11.Cu")
		(net "M_H_CPU1_SB_DQ<30>")
	)
	(segment
		(start 135.700516 -226.017328)
		(end 135.700516 -226.027234)
		(width 0.088646)
		(layer "In11.Cu")
		(net "M_H_CPU1_SB_DQ<30>")
	)
	(segment
		(start 140.264642 -221.309692)
		(end 140.084556 -221.489778)
		(width 0.088646)
		(layer "In11.Cu")
		(net "M_H_CPU1_SB_DQ<30>")
	)
	(segment
		(start 177.333402 -196.891402)
		(end 175.428402 -196.891402)
		(width 0.18288)
		(layer "In11.Cu")
		(net "M_H_CPU1_SB_DQ<30>")
	)
	(segment
		(start 125.836934 -226.77374)
		(end 125.894338 -226.831144)
		(width 0.088646)
		(layer "In11.Cu")
		(net "M_H_CPU1_SB_DQ<30>")
	)
	(segment
		(start 135.418068 -226.506786)
		(end 135.407654 -226.512882)
		(width 0.088646)
		(layer "In11.Cu")
		(net "M_H_CPU1_SB_DQ<30>")
	)
	(segment
		(start 206.150464 -197.316598)
		(end 204.025246 -199.441816)
		(width 0.18288)
		(layer "In11.Cu")
		(net "M_H_CPU1_SB_DQ<30>")
	)
	(segment
		(start 139.288012 -224.014538)
		(end 138.894566 -224.014538)
		(width 0.088646)
		(layer "In11.Cu")
		(net "M_H_CPU1_SB_DQ<30>")
	)
	(segment
		(start 175.428402 -196.891402)
		(end 175.314864 -196.777864)
		(width 0.18288)
		(layer "In11.Cu")
		(net "M_H_CPU1_SB_DQ<30>")
	)
	(segment
		(start 193.425826 -197.566026)
		(end 192.751202 -196.891402)
		(width 0.18288)
		(layer "In11.Cu")
		(net "M_H_CPU1_SB_DQ<30>")
	)
	(segment
		(start 195.229226 -198.556626)
		(end 194.238626 -197.566026)
		(width 0.18288)
		(layer "In11.Cu")
		(net "M_H_CPU1_SB_DQ<30>")
	)
	(segment
		(start 166.68623 -199.45223)
		(end 165.790626 -198.556626)
		(width 0.18288)
		(layer "In11.Cu")
		(net "M_H_CPU1_SB_DQ<30>")
	)
	(segment
		(start 146.283426 -212.430614)
		(end 146.283426 -215.290908)
		(width 0.18288)
		(layer "In11.Cu")
		(net "M_H_CPU1_SB_DQ<30>")
	)
	(segment
		(start 135.887968 -225.69297)
		(end 135.879078 -225.69805)
		(width 0.088646)
		(layer "In11.Cu")
		(net "M_H_CPU1_SB_DQ<30>")
	)
	(segment
		(start 175.314864 -196.777864)
		(end 174.122588 -196.777864)
		(width 0.18288)
		(layer "In11.Cu")
		(net "M_H_CPU1_SB_DQ<30>")
	)
	(segment
		(start 126.959868 -226.506786)
		(end 126.949454 -226.512882)
		(width 0.088646)
		(layer "In11.Cu")
		(net "M_H_CPU1_SB_DQ<30>")
	)
	(segment
		(start 172.061886 -197.741286)
		(end 171.810426 -197.489826)
		(width 0.18288)
		(layer "In11.Cu")
		(net "M_H_CPU1_SB_DQ<30>")
	)
	(segment
		(start 204.025246 -199.441816)
		(end 202.46848 -199.441816)
		(width 0.18288)
		(layer "In11.Cu")
		(net "M_H_CPU1_SB_DQ<30>")
	)
	(segment
		(start 165.790626 -198.556626)
		(end 164.723826 -198.556626)
		(width 0.18288)
		(layer "In11.Cu")
		(net "M_H_CPU1_SB_DQ<30>")
	)
	(segment
		(start 161.218118 -199.369934)
		(end 160.349946 -200.238106)
		(width 0.18288)
		(layer "In11.Cu")
		(net "M_H_CPU1_SB_DQ<30>")
	)
	(segment
		(start 190.581026 -196.731382)
		(end 190.01867 -196.731382)
		(width 0.18288)
		(layer "In11.Cu")
		(net "M_H_CPU1_SB_DQ<30>")
	)
	(segment
		(start 154.513534 -204.200506)
		(end 146.283426 -212.430614)
		(width 0.18288)
		(layer "In11.Cu")
		(net "M_H_CPU1_SB_DQ<30>")
	)
	(segment
		(start 168.717214 -199.45223)
		(end 166.68623 -199.45223)
		(width 0.18288)
		(layer "In11.Cu")
		(net "M_H_CPU1_SB_DQ<30>")
	)
	(segment
		(start 183.86425 -197.628002)
		(end 182.991252 -198.501)
		(width 0.18288)
		(layer "In11.Cu")
		(net "M_H_CPU1_SB_DQ<30>")
	)
	(segment
		(start 140.084556 -221.489778)
		(end 140.084556 -223.217994)
		(width 0.088646)
		(layer "In11.Cu")
		(net "M_H_CPU1_SB_DQ<30>")
	)
	(segment
		(start 207.071214 -197.316598)
		(end 206.150464 -197.316598)
		(width 0.18288)
		(layer "In11.Cu")
		(net "M_H_CPU1_SB_DQ<30>")
	)
	(segment
		(start 179.496466 -197.604126)
		(end 178.833526 -197.604126)
		(width 0.18288)
		(layer "In11.Cu")
		(net "M_H_CPU1_SB_DQ<30>")
	)
	(segment
		(start 164.723826 -198.556626)
		(end 163.910518 -199.369934)
		(width 0.18288)
		(layer "In11.Cu")
		(net "M_H_CPU1_SB_DQ<30>")
	)
	(segment
		(start 138.050016 -225.203258)
		(end 138.050016 -225.2218)
		(width 0.088646)
		(layer "In11.Cu")
		(net "M_H_CPU1_SB_DQ<30>")
	)
	(segment
		(start 173.159166 -197.741286)
		(end 172.061886 -197.741286)
		(width 0.18288)
		(layer "In11.Cu")
		(net "M_H_CPU1_SB_DQ<30>")
	)
	(segment
		(start 146.283426 -215.290908)
		(end 140.264642 -221.309692)
		(width 0.18288)
		(layer "In11.Cu")
		(net "M_H_CPU1_SB_DQ<30>")
	)
	(segment
		(start 189.008766 -197.741286)
		(end 187.022486 -197.741286)
		(width 0.18288)
		(layer "In11.Cu")
		(net "M_H_CPU1_SB_DQ<30>")
	)
	(segment
		(start 192.751202 -196.891402)
		(end 190.741046 -196.891402)
		(width 0.18288)
		(layer "In11.Cu")
		(net "M_H_CPU1_SB_DQ<30>")
	)
	(segment
		(start 130.719068 -226.506786)
		(end 130.708654 -226.512882)
		(width 0.088646)
		(layer "In11.Cu")
		(net "M_H_CPU1_SB_DQ<30>")
	)
	(segment
		(start 202.26909 -199.242426)
		(end 198.607426 -199.242426)
		(width 0.18288)
		(layer "In11.Cu")
		(net "M_H_CPU1_SB_DQ<30>")
	)
	(segment
		(start 177.830226 -197.388226)
		(end 177.333402 -196.891402)
		(width 0.18288)
		(layer "In11.Cu")
		(net "M_H_CPU1_SB_DQ<30>")
	)
	(segment
		(start 131.658614 -226.506786)
		(end 131.6482 -226.512882)
		(width 0.088646)
		(layer "In11.Cu")
		(net "M_H_CPU1_SB_DQ<30>")
	)
	(segment
		(start 186.909202 -197.628002)
		(end 183.86425 -197.628002)
		(width 0.18288)
		(layer "In11.Cu")
		(net "M_H_CPU1_SB_DQ<30>")
	)
	(segment
		(start 128.839214 -226.506786)
		(end 128.8288 -226.512882)
		(width 0.088646)
		(layer "In11.Cu")
		(net "M_H_CPU1_SB_DQ<30>")
	)
	(segment
		(start 190.01867 -196.731382)
		(end 189.008766 -197.741286)
		(width 0.18288)
		(layer "In11.Cu")
		(net "M_H_CPU1_SB_DQ<30>")
	)
	(arc
		(start 126.010924 -226.511866)
		(mid 125.895185 -226.62369)
		(end 125.836934 -226.77374)
		(width 0.088646)
		(layer "In11.Cu")
		(net "M_H_CPU1_SB_DQ<30>")
	)
	(arc
		(start 134.4676 -226.512882)
		(mid 134.189422 -226.582605)
		(end 133.912864 -226.506786)
		(width 0.088646)
		(layer "In11.Cu")
		(net "M_H_CPU1_SB_DQ<30>")
	)
	(arc
		(start 133.912864 -226.506786)
		(mid 133.725666 -226.456643)
		(end 133.538468 -226.506786)
		(width 0.088646)
		(layer "In11.Cu")
		(net "M_H_CPU1_SB_DQ<30>")
	)
	(arc
		(start 133.528054 -226.512882)
		(mid 133.249622 -226.582728)
		(end 132.97281 -226.506786)
		(width 0.088646)
		(layer "In11.Cu")
		(net "M_H_CPU1_SB_DQ<30>")
	)
	(arc
		(start 126.949454 -226.512882)
		(mid 126.671022 -226.582728)
		(end 126.39421 -226.506786)
		(width 0.088646)
		(layer "In11.Cu")
		(net "M_H_CPU1_SB_DQ<30>")
	)
	(arc
		(start 128.8288 -226.512882)
		(mid 128.550622 -226.582605)
		(end 128.274064 -226.506786)
		(width 0.088646)
		(layer "In11.Cu")
		(net "M_H_CPU1_SB_DQ<30>")
	)
	(arc
		(start 138.050016 -225.2218)
		(mid 137.969854 -225.493989)
		(end 137.767568 -225.69297)
		(width 0.088646)
		(layer "In11.Cu")
		(net "M_H_CPU1_SB_DQ<30>")
	)
	(arc
		(start 131.093464 -226.506786)
		(mid 130.906266 -226.456643)
		(end 130.719068 -226.506786)
		(width 0.088646)
		(layer "In11.Cu")
		(net "M_H_CPU1_SB_DQ<30>")
	)
	(arc
		(start 136.262364 -225.69297)
		(mid 136.075166 -225.642827)
		(end 135.887968 -225.69297)
		(width 0.088646)
		(layer "In11.Cu")
		(net "M_H_CPU1_SB_DQ<30>")
	)
	(arc
		(start 131.6482 -226.512882)
		(mid 131.370022 -226.582605)
		(end 131.093464 -226.506786)
		(width 0.088646)
		(layer "In11.Cu")
		(net "M_H_CPU1_SB_DQ<30>")
	)
	(arc
		(start 138.519916 -224.399348)
		(mid 138.441805 -224.676297)
		(end 138.237468 -224.8789)
		(width 0.088646)
		(layer "In11.Cu")
		(net "M_H_CPU1_SB_DQ<30>")
	)
	(arc
		(start 132.97281 -226.506786)
		(mid 132.785612 -226.456643)
		(end 132.598414 -226.506786)
		(width 0.088646)
		(layer "In11.Cu")
		(net "M_H_CPU1_SB_DQ<30>")
	)
	(arc
		(start 137.202164 -225.69297)
		(mid 137.014966 -225.642827)
		(end 136.827768 -225.69297)
		(width 0.088646)
		(layer "In11.Cu")
		(net "M_H_CPU1_SB_DQ<30>")
	)
	(arc
		(start 129.764282 -226.515422)
		(mid 129.487807 -226.582742)
		(end 129.21361 -226.506786)
		(width 0.088646)
		(layer "In11.Cu")
		(net "M_H_CPU1_SB_DQ<30>")
	)
	(arc
		(start 138.228578 -224.88398)
		(mid 138.097664 -225.02034)
		(end 138.050016 -225.203258)
		(width 0.088646)
		(layer "In11.Cu")
		(net "M_H_CPU1_SB_DQ<30>")
	)
	(arc
		(start 137.767568 -225.69297)
		(mid 137.484866 -225.768712)
		(end 137.202164 -225.69297)
		(width 0.088646)
		(layer "In11.Cu")
		(net "M_H_CPU1_SB_DQ<30>")
	)
	(arc
		(start 129.21361 -226.506786)
		(mid 129.026412 -226.456643)
		(end 128.839214 -226.506786)
		(width 0.088646)
		(layer "In11.Cu")
		(net "M_H_CPU1_SB_DQ<30>")
	)
	(arc
		(start 126.39421 -226.506786)
		(mid 126.207012 -226.456643)
		(end 126.019814 -226.506786)
		(width 0.088646)
		(layer "In11.Cu")
		(net "M_H_CPU1_SB_DQ<30>")
	)
	(arc
		(start 130.15341 -226.506786)
		(mid 129.966212 -226.456643)
		(end 129.779014 -226.506786)
		(width 0.088646)
		(layer "In11.Cu")
		(net "M_H_CPU1_SB_DQ<30>")
	)
	(arc
		(start 127.334264 -226.506786)
		(mid 127.147066 -226.456643)
		(end 126.959868 -226.506786)
		(width 0.088646)
		(layer "In11.Cu")
		(net "M_H_CPU1_SB_DQ<30>")
	)
	(arc
		(start 135.407654 -226.512882)
		(mid 135.129222 -226.582728)
		(end 134.85241 -226.506786)
		(width 0.088646)
		(layer "In11.Cu")
		(net "M_H_CPU1_SB_DQ<30>")
	)
	(arc
		(start 138.894566 -224.014538)
		(mid 138.629633 -224.124435)
		(end 138.519916 -224.389442)
		(width 0.088646)
		(layer "In11.Cu")
		(net "M_H_CPU1_SB_DQ<30>")
	)
	(arc
		(start 132.583682 -226.515422)
		(mid 132.307207 -226.582742)
		(end 132.03301 -226.506786)
		(width 0.088646)
		(layer "In11.Cu")
		(net "M_H_CPU1_SB_DQ<30>")
	)
	(arc
		(start 135.879078 -225.69805)
		(mid 135.748164 -225.83441)
		(end 135.700516 -226.017328)
		(width 0.088646)
		(layer "In11.Cu")
		(net "M_H_CPU1_SB_DQ<30>")
	)
	(arc
		(start 136.827768 -225.69297)
		(mid 136.545066 -225.768712)
		(end 136.262364 -225.69297)
		(width 0.088646)
		(layer "In11.Cu")
		(net "M_H_CPU1_SB_DQ<30>")
	)
	(arc
		(start 135.700516 -226.027234)
		(mid 135.622405 -226.304183)
		(end 135.418068 -226.506786)
		(width 0.088646)
		(layer "In11.Cu")
		(net "M_H_CPU1_SB_DQ<30>")
	)
	(arc
		(start 132.03301 -226.506786)
		(mid 131.845812 -226.456643)
		(end 131.658614 -226.506786)
		(width 0.088646)
		(layer "In11.Cu")
		(net "M_H_CPU1_SB_DQ<30>")
	)
	(arc
		(start 130.708654 -226.512882)
		(mid 130.430222 -226.582728)
		(end 130.15341 -226.506786)
		(width 0.088646)
		(layer "In11.Cu")
		(net "M_H_CPU1_SB_DQ<30>")
	)
	(arc
		(start 127.899668 -226.506786)
		(mid 127.616966 -226.582562)
		(end 127.334264 -226.506786)
		(width 0.088646)
		(layer "In11.Cu")
		(net "M_H_CPU1_SB_DQ<30>")
	)
	(arc
		(start 134.85241 -226.506786)
		(mid 134.665212 -226.456643)
		(end 134.478014 -226.506786)
		(width 0.088646)
		(layer "In11.Cu")
		(net "M_H_CPU1_SB_DQ<30>")
	)
	(arc
		(start 128.274064 -226.506786)
		(mid 128.086866 -226.456643)
		(end 127.899668 -226.506786)
		(width 0.088646)
		(layer "In11.Cu")
		(net "M_H_CPU1_SB_DQ<30>")
	)
	(segment
		(start 213.515448 -231.549956)
		(end 213.515448 -231.299004)
		(width 0.20066)
		(layer "F.Cu")
		(net "M_H_CPU1_SB_DQ<2>")
	)
	(segment
		(start 213.515448 -231.299004)
		(end 213.749636 -231.064816)
		(width 0.20066)
		(layer "F.Cu")
		(net "M_H_CPU1_SB_DQ<2>")
	)
	(segment
		(start 210.598258 -231.748838)
		(end 210.603084 -231.748838)
		(width 0.101854)
		(layer "F.Cu")
		(net "M_H_CPU1_SB_DQ<2>")
	)
	(segment
		(start 207.071214 -231.316784)
		(end 208.176114 -231.316784)
		(width 0.20066)
		(layer "F.Cu")
		(net "M_H_CPU1_SB_DQ<2>")
	)
	(segment
		(start 212.618066 -231.741726)
		(end 212.630258 -231.753918)
		(width 0.1016)
		(layer "F.Cu")
		(net "M_H_CPU1_SB_DQ<2>")
	)
	(segment
		(start 210.603084 -231.748838)
		(end 210.610196 -231.741726)
		(width 0.1016)
		(layer "F.Cu")
		(net "M_H_CPU1_SB_DQ<2>")
	)
	(segment
		(start 124.797312 -239.57534)
		(end 124.797566 -239.575086)
		(width 0.20066)
		(layer "F.Cu")
		(net "M_H_CPU1_SB_DQ<2>")
	)
	(segment
		(start 124.797566 -239.575086)
		(end 124.797566 -239.0394)
		(width 0.20066)
		(layer "F.Cu")
		(net "M_H_CPU1_SB_DQ<2>")
	)
	(segment
		(start 213.749636 -231.064816)
		(end 214.133684 -231.064816)
		(width 0.20066)
		(layer "F.Cu")
		(net "M_H_CPU1_SB_DQ<2>")
	)
	(segment
		(start 212.630258 -231.753918)
		(end 213.311486 -231.753918)
		(width 0.20066)
		(layer "F.Cu")
		(net "M_H_CPU1_SB_DQ<2>")
	)
	(segment
		(start 209.874358 -231.316784)
		(end 210.306412 -231.748838)
		(width 0.20066)
		(layer "F.Cu")
		(net "M_H_CPU1_SB_DQ<2>")
	)
	(segment
		(start 213.311486 -231.753918)
		(end 213.515448 -231.549956)
		(width 0.20066)
		(layer "F.Cu")
		(net "M_H_CPU1_SB_DQ<2>")
	)
	(segment
		(start 214.385652 -231.316784)
		(end 215.719914 -231.316784)
		(width 0.20066)
		(layer "F.Cu")
		(net "M_H_CPU1_SB_DQ<2>")
	)
	(segment
		(start 208.176114 -231.316784)
		(end 209.874358 -231.316784)
		(width 0.20066)
		(layer "F.Cu")
		(net "M_H_CPU1_SB_DQ<2>")
	)
	(segment
		(start 210.306412 -231.748838)
		(end 210.598258 -231.748838)
		(width 0.20066)
		(layer "F.Cu")
		(net "M_H_CPU1_SB_DQ<2>")
	)
	(segment
		(start 210.610196 -231.741726)
		(end 212.618066 -231.741726)
		(width 0.1016)
		(layer "F.Cu")
		(net "M_H_CPU1_SB_DQ<2>")
	)
	(segment
		(start 214.133684 -231.064816)
		(end 214.385652 -231.316784)
		(width 0.20066)
		(layer "F.Cu")
		(net "M_H_CPU1_SB_DQ<2>")
	)
	(segment
		(start 175.234092 -228.162358)
		(end 175.041052 -228.355398)
		(width 0.18288)
		(layer "In11.Cu")
		(net "M_H_CPU1_SB_DQ<2>")
	)
	(segment
		(start 163.507166 -229.354126)
		(end 162.818826 -230.042466)
		(width 0.18288)
		(layer "In11.Cu")
		(net "M_H_CPU1_SB_DQ<2>")
	)
	(segment
		(start 141.103096 -238.974884)
		(end 140.581126 -238.974884)
		(width 0.088646)
		(layer "In11.Cu")
		(net "M_H_CPU1_SB_DQ<2>")
	)
	(segment
		(start 175.041052 -228.355398)
		(end 174.066454 -228.355398)
		(width 0.18288)
		(layer "In11.Cu")
		(net "M_H_CPU1_SB_DQ<2>")
	)
	(segment
		(start 194.213226 -228.096826)
		(end 192.709546 -228.096826)
		(width 0.18288)
		(layer "In11.Cu")
		(net "M_H_CPU1_SB_DQ<2>")
	)
	(segment
		(start 126.879096 -239.355122)
		(end 126.864364 -239.363758)
		(width 0.088646)
		(layer "In11.Cu")
		(net "M_H_CPU1_SB_DQ<2>")
	)
	(segment
		(start 166.179754 -229.986078)
		(end 165.986714 -229.793038)
		(width 0.18288)
		(layer "In11.Cu")
		(net "M_H_CPU1_SB_DQ<2>")
	)
	(segment
		(start 170.908472 -229.347014)
		(end 170.715432 -229.153974)
		(width 0.18288)
		(layer "In11.Cu")
		(net "M_H_CPU1_SB_DQ<2>")
	)
	(segment
		(start 202.621642 -230.891842)
		(end 202.495658 -231.017826)
		(width 0.18288)
		(layer "In11.Cu")
		(net "M_H_CPU1_SB_DQ<2>")
	)
	(segment
		(start 128.754378 -239.357662)
		(end 128.743964 -239.363758)
		(width 0.088646)
		(layer "In11.Cu")
		(net "M_H_CPU1_SB_DQ<2>")
	)
	(segment
		(start 138.903202 -239.25276)
		(end 138.74115 -239.414812)
		(width 0.088646)
		(layer "In11.Cu")
		(net "M_H_CPU1_SB_DQ<2>")
	)
	(segment
		(start 170.011852 -229.153974)
		(end 169.818812 -229.347014)
		(width 0.18288)
		(layer "In11.Cu")
		(net "M_H_CPU1_SB_DQ<2>")
	)
	(segment
		(start 174.066454 -228.355398)
		(end 173.229524 -229.192328)
		(width 0.18288)
		(layer "In11.Cu")
		(net "M_H_CPU1_SB_DQ<2>")
	)
	(segment
		(start 170.204892 -228.282754)
		(end 170.011852 -228.475794)
		(width 0.18288)
		(layer "In11.Cu")
		(net "M_H_CPU1_SB_DQ<2>")
	)
	(segment
		(start 187.81776 -226.640644)
		(end 187.109608 -226.640644)
		(width 0.18288)
		(layer "In11.Cu")
		(net "M_H_CPU1_SB_DQ<2>")
	)
	(segment
		(start 186.948826 -226.801426)
		(end 183.537098 -226.801426)
		(width 0.18288)
		(layer "In11.Cu")
		(net "M_H_CPU1_SB_DQ<2>")
	)
	(segment
		(start 125.550168 -239.363758)
		(end 125.152658 -239.134396)
		(width 0.088646)
		(layer "In11.Cu")
		(net "M_H_CPU1_SB_DQ<2>")
	)
	(segment
		(start 140.581126 -238.974884)
		(end 140.30325 -239.25276)
		(width 0.088646)
		(layer "In11.Cu")
		(net "M_H_CPU1_SB_DQ<2>")
	)
	(segment
		(start 130.638296 -239.355122)
		(end 130.623564 -239.363758)
		(width 0.088646)
		(layer "In11.Cu")
		(net "M_H_CPU1_SB_DQ<2>")
	)
	(segment
		(start 134.397496 -239.355122)
		(end 134.382764 -239.363758)
		(width 0.088646)
		(layer "In11.Cu")
		(net "M_H_CPU1_SB_DQ<2>")
	)
	(segment
		(start 160.844738 -230.042466)
		(end 160.733994 -230.15321)
		(width 0.18288)
		(layer "In11.Cu")
		(net "M_H_CPU1_SB_DQ<2>")
	)
	(segment
		(start 195.889626 -229.011226)
		(end 195.127626 -229.011226)
		(width 0.18288)
		(layer "In11.Cu")
		(net "M_H_CPU1_SB_DQ<2>")
	)
	(segment
		(start 203.746862 -230.729536)
		(end 203.584048 -230.89235)
		(width 0.18288)
		(layer "In11.Cu")
		(net "M_H_CPU1_SB_DQ<2>")
	)
	(segment
		(start 207.071214 -231.316784)
		(end 206.483966 -230.729536)
		(width 0.18288)
		(layer "In11.Cu")
		(net "M_H_CPU1_SB_DQ<2>")
	)
	(segment
		(start 198.378826 -230.255826)
		(end 197.134226 -230.255826)
		(width 0.18288)
		(layer "In11.Cu")
		(net "M_H_CPU1_SB_DQ<2>")
	)
	(segment
		(start 175.937672 -227.751894)
		(end 175.744632 -227.558854)
		(width 0.18288)
		(layer "In11.Cu")
		(net "M_H_CPU1_SB_DQ<2>")
	)
	(segment
		(start 175.427132 -227.558854)
		(end 175.234092 -227.751894)
		(width 0.18288)
		(layer "In11.Cu")
		(net "M_H_CPU1_SB_DQ<2>")
	)
	(segment
		(start 178.079654 -227.563426)
		(end 177.300382 -228.342698)
		(width 0.18288)
		(layer "In11.Cu")
		(net "M_H_CPU1_SB_DQ<2>")
	)
	(segment
		(start 166.690294 -229.793038)
		(end 166.497254 -229.986078)
		(width 0.18288)
		(layer "In11.Cu")
		(net "M_H_CPU1_SB_DQ<2>")
	)
	(segment
		(start 162.818826 -230.042466)
		(end 160.844738 -230.042466)
		(width 0.18288)
		(layer "In11.Cu")
		(net "M_H_CPU1_SB_DQ<2>")
	)
	(segment
		(start 195.127626 -229.011226)
		(end 194.213226 -228.096826)
		(width 0.18288)
		(layer "In11.Cu")
		(net "M_H_CPU1_SB_DQ<2>")
	)
	(segment
		(start 166.497254 -229.986078)
		(end 166.179754 -229.986078)
		(width 0.18288)
		(layer "In11.Cu")
		(net "M_H_CPU1_SB_DQ<2>")
	)
	(segment
		(start 203.018898 -230.891842)
		(end 202.621642 -230.891842)
		(width 0.18288)
		(layer "In11.Cu")
		(net "M_H_CPU1_SB_DQ<2>")
	)
	(segment
		(start 190.327026 -226.522026)
		(end 189.494922 -226.522026)
		(width 0.18288)
		(layer "In11.Cu")
		(net "M_H_CPU1_SB_DQ<2>")
	)
	(segment
		(start 187.109608 -226.640644)
		(end 186.948826 -226.801426)
		(width 0.18288)
		(layer "In11.Cu")
		(net "M_H_CPU1_SB_DQ<2>")
	)
	(segment
		(start 192.709546 -228.096826)
		(end 192.466468 -228.339904)
		(width 0.18288)
		(layer "In11.Cu")
		(net "M_H_CPU1_SB_DQ<2>")
	)
	(segment
		(start 189.494922 -226.522026)
		(end 189.374526 -226.642422)
		(width 0.18288)
		(layer "In11.Cu")
		(net "M_H_CPU1_SB_DQ<2>")
	)
	(segment
		(start 177.300382 -228.342698)
		(end 176.130712 -228.342698)
		(width 0.18288)
		(layer "In11.Cu")
		(net "M_H_CPU1_SB_DQ<2>")
	)
	(segment
		(start 197.134226 -230.255826)
		(end 195.889626 -229.011226)
		(width 0.18288)
		(layer "In11.Cu")
		(net "M_H_CPU1_SB_DQ<2>")
	)
	(segment
		(start 206.483966 -230.729536)
		(end 203.746862 -230.729536)
		(width 0.18288)
		(layer "In11.Cu")
		(net "M_H_CPU1_SB_DQ<2>")
	)
	(segment
		(start 169.818812 -229.347014)
		(end 168.615614 -229.347014)
		(width 0.18288)
		(layer "In11.Cu")
		(net "M_H_CPU1_SB_DQ<2>")
	)
	(segment
		(start 146.068034 -238.974884)
		(end 141.103096 -238.974884)
		(width 0.18288)
		(layer "In11.Cu")
		(net "M_H_CPU1_SB_DQ<2>")
	)
	(segment
		(start 203.584048 -230.89235)
		(end 203.018898 -230.891842)
		(width 0.18288)
		(layer "In11.Cu")
		(net "M_H_CPU1_SB_DQ<2>")
	)
	(segment
		(start 158.769558 -230.15321)
		(end 158.030418 -230.89235)
		(width 0.18288)
		(layer "In11.Cu")
		(net "M_H_CPU1_SB_DQ<2>")
	)
	(segment
		(start 172.27931 -229.347014)
		(end 170.908472 -229.347014)
		(width 0.18288)
		(layer "In11.Cu")
		(net "M_H_CPU1_SB_DQ<2>")
	)
	(segment
		(start 154.150568 -230.89235)
		(end 146.068034 -238.974884)
		(width 0.18288)
		(layer "In11.Cu")
		(net "M_H_CPU1_SB_DQ<2>")
	)
	(segment
		(start 125.939296 -239.355122)
		(end 125.924564 -239.363758)
		(width 0.088646)
		(layer "In11.Cu")
		(net "M_H_CPU1_SB_DQ<2>")
	)
	(segment
		(start 168.152826 -228.884226)
		(end 166.883334 -228.884226)
		(width 0.18288)
		(layer "In11.Cu")
		(net "M_H_CPU1_SB_DQ<2>")
	)
	(segment
		(start 175.744632 -227.558854)
		(end 175.427132 -227.558854)
		(width 0.18288)
		(layer "In11.Cu")
		(net "M_H_CPU1_SB_DQ<2>")
	)
	(segment
		(start 165.793674 -228.884226)
		(end 164.608002 -228.884226)
		(width 0.18288)
		(layer "In11.Cu")
		(net "M_H_CPU1_SB_DQ<2>")
	)
	(segment
		(start 160.733994 -230.15321)
		(end 158.769558 -230.15321)
		(width 0.18288)
		(layer "In11.Cu")
		(net "M_H_CPU1_SB_DQ<2>")
	)
	(segment
		(start 187.819538 -226.642422)
		(end 187.81776 -226.640644)
		(width 0.18288)
		(layer "In11.Cu")
		(net "M_H_CPU1_SB_DQ<2>")
	)
	(segment
		(start 173.229524 -229.192328)
		(end 172.433996 -229.192328)
		(width 0.18288)
		(layer "In11.Cu")
		(net "M_H_CPU1_SB_DQ<2>")
	)
	(segment
		(start 165.986714 -229.793038)
		(end 165.986714 -229.077266)
		(width 0.18288)
		(layer "In11.Cu")
		(net "M_H_CPU1_SB_DQ<2>")
	)
	(segment
		(start 199.140826 -231.017826)
		(end 198.378826 -230.255826)
		(width 0.18288)
		(layer "In11.Cu")
		(net "M_H_CPU1_SB_DQ<2>")
	)
	(segment
		(start 202.495658 -231.017826)
		(end 199.140826 -231.017826)
		(width 0.18288)
		(layer "In11.Cu")
		(net "M_H_CPU1_SB_DQ<2>")
	)
	(segment
		(start 136.277096 -239.355122)
		(end 136.262364 -239.363758)
		(width 0.088646)
		(layer "In11.Cu")
		(net "M_H_CPU1_SB_DQ<2>")
	)
	(segment
		(start 189.374526 -226.642422)
		(end 187.819538 -226.642422)
		(width 0.18288)
		(layer "In11.Cu")
		(net "M_H_CPU1_SB_DQ<2>")
	)
	(segment
		(start 190.89116 -227.84689)
		(end 190.89116 -227.08616)
		(width 0.18288)
		(layer "In11.Cu")
		(net "M_H_CPU1_SB_DQ<2>")
	)
	(segment
		(start 166.883334 -228.884226)
		(end 166.690294 -229.077266)
		(width 0.18288)
		(layer "In11.Cu")
		(net "M_H_CPU1_SB_DQ<2>")
	)
	(segment
		(start 132.517896 -239.355122)
		(end 132.503164 -239.363758)
		(width 0.088646)
		(layer "In11.Cu")
		(net "M_H_CPU1_SB_DQ<2>")
	)
	(segment
		(start 170.522392 -228.282754)
		(end 170.204892 -228.282754)
		(width 0.18288)
		(layer "In11.Cu")
		(net "M_H_CPU1_SB_DQ<2>")
	)
	(segment
		(start 168.615614 -229.347014)
		(end 168.152826 -228.884226)
		(width 0.18288)
		(layer "In11.Cu")
		(net "M_H_CPU1_SB_DQ<2>")
	)
	(segment
		(start 129.693924 -239.357662)
		(end 129.68351 -239.363758)
		(width 0.088646)
		(layer "In11.Cu")
		(net "M_H_CPU1_SB_DQ<2>")
	)
	(segment
		(start 190.89116 -227.08616)
		(end 190.327026 -226.522026)
		(width 0.18288)
		(layer "In11.Cu")
		(net "M_H_CPU1_SB_DQ<2>")
	)
	(segment
		(start 192.466468 -228.339904)
		(end 191.384174 -228.339904)
		(width 0.18288)
		(layer "In11.Cu")
		(net "M_H_CPU1_SB_DQ<2>")
	)
	(segment
		(start 137.216896 -239.355122)
		(end 137.202164 -239.363758)
		(width 0.088646)
		(layer "In11.Cu")
		(net "M_H_CPU1_SB_DQ<2>")
	)
	(segment
		(start 164.138102 -229.354126)
		(end 163.507166 -229.354126)
		(width 0.18288)
		(layer "In11.Cu")
		(net "M_H_CPU1_SB_DQ<2>")
	)
	(segment
		(start 158.030418 -230.89235)
		(end 154.150568 -230.89235)
		(width 0.18288)
		(layer "In11.Cu")
		(net "M_H_CPU1_SB_DQ<2>")
	)
	(segment
		(start 176.130712 -228.342698)
		(end 175.937672 -228.149658)
		(width 0.18288)
		(layer "In11.Cu")
		(net "M_H_CPU1_SB_DQ<2>")
	)
	(segment
		(start 175.234092 -227.751894)
		(end 175.234092 -228.162358)
		(width 0.18288)
		(layer "In11.Cu")
		(net "M_H_CPU1_SB_DQ<2>")
	)
	(segment
		(start 191.384174 -228.339904)
		(end 190.89116 -227.84689)
		(width 0.18288)
		(layer "In11.Cu")
		(net "M_H_CPU1_SB_DQ<2>")
	)
	(segment
		(start 183.537098 -226.801426)
		(end 182.775098 -227.563426)
		(width 0.18288)
		(layer "In11.Cu")
		(net "M_H_CPU1_SB_DQ<2>")
	)
	(segment
		(start 170.011852 -228.475794)
		(end 170.011852 -229.153974)
		(width 0.18288)
		(layer "In11.Cu")
		(net "M_H_CPU1_SB_DQ<2>")
	)
	(segment
		(start 175.937672 -228.149658)
		(end 175.937672 -227.751894)
		(width 0.18288)
		(layer "In11.Cu")
		(net "M_H_CPU1_SB_DQ<2>")
	)
	(segment
		(start 165.986714 -229.077266)
		(end 165.793674 -228.884226)
		(width 0.18288)
		(layer "In11.Cu")
		(net "M_H_CPU1_SB_DQ<2>")
	)
	(segment
		(start 140.30325 -239.25276)
		(end 138.903202 -239.25276)
		(width 0.088646)
		(layer "In11.Cu")
		(net "M_H_CPU1_SB_DQ<2>")
	)
	(segment
		(start 138.74115 -239.414812)
		(end 137.955274 -239.414812)
		(width 0.088646)
		(layer "In11.Cu")
		(net "M_H_CPU1_SB_DQ<2>")
	)
	(segment
		(start 182.775098 -227.563426)
		(end 178.079654 -227.563426)
		(width 0.18288)
		(layer "In11.Cu")
		(net "M_H_CPU1_SB_DQ<2>")
	)
	(segment
		(start 164.608002 -228.884226)
		(end 164.138102 -229.354126)
		(width 0.18288)
		(layer "In11.Cu")
		(net "M_H_CPU1_SB_DQ<2>")
	)
	(segment
		(start 170.715432 -228.475794)
		(end 170.522392 -228.282754)
		(width 0.18288)
		(layer "In11.Cu")
		(net "M_H_CPU1_SB_DQ<2>")
	)
	(segment
		(start 172.433996 -229.192328)
		(end 172.27931 -229.347014)
		(width 0.18288)
		(layer "In11.Cu")
		(net "M_H_CPU1_SB_DQ<2>")
	)
	(segment
		(start 170.715432 -229.153974)
		(end 170.715432 -228.475794)
		(width 0.18288)
		(layer "In11.Cu")
		(net "M_H_CPU1_SB_DQ<2>")
	)
	(segment
		(start 127.818896 -239.355122)
		(end 127.804164 -239.363758)
		(width 0.088646)
		(layer "In11.Cu")
		(net "M_H_CPU1_SB_DQ<2>")
	)
	(segment
		(start 166.690294 -229.077266)
		(end 166.690294 -229.793038)
		(width 0.18288)
		(layer "In11.Cu")
		(net "M_H_CPU1_SB_DQ<2>")
	)
	(arc
		(start 133.442964 -239.363758)
		(mid 133.255766 -239.413901)
		(end 133.068568 -239.363758)
		(width 0.088646)
		(layer "In11.Cu")
		(net "M_H_CPU1_SB_DQ<2>")
	)
	(arc
		(start 135.322564 -239.363758)
		(mid 135.135366 -239.413901)
		(end 134.948168 -239.363758)
		(width 0.088646)
		(layer "In11.Cu")
		(net "M_H_CPU1_SB_DQ<2>")
	)
	(arc
		(start 129.68351 -239.363758)
		(mid 129.496312 -239.413901)
		(end 129.309114 -239.363758)
		(width 0.088646)
		(layer "In11.Cu")
		(net "M_H_CPU1_SB_DQ<2>")
	)
	(arc
		(start 132.128768 -239.363758)
		(mid 131.846066 -239.287982)
		(end 131.563364 -239.363758)
		(width 0.088646)
		(layer "In11.Cu")
		(net "M_H_CPU1_SB_DQ<2>")
	)
	(arc
		(start 129.309114 -239.363758)
		(mid 129.032555 -239.288015)
		(end 128.754378 -239.357662)
		(width 0.088646)
		(layer "In11.Cu")
		(net "M_H_CPU1_SB_DQ<2>")
	)
	(arc
		(start 133.068568 -239.363758)
		(mid 132.794369 -239.287923)
		(end 132.517896 -239.355122)
		(width 0.088646)
		(layer "In11.Cu")
		(net "M_H_CPU1_SB_DQ<2>")
	)
	(arc
		(start 128.743964 -239.363758)
		(mid 128.556766 -239.413901)
		(end 128.369568 -239.363758)
		(width 0.088646)
		(layer "In11.Cu")
		(net "M_H_CPU1_SB_DQ<2>")
	)
	(arc
		(start 134.948168 -239.363758)
		(mid 134.673969 -239.287923)
		(end 134.397496 -239.355122)
		(width 0.088646)
		(layer "In11.Cu")
		(net "M_H_CPU1_SB_DQ<2>")
	)
	(arc
		(start 137.202164 -239.363758)
		(mid 137.014966 -239.413901)
		(end 136.827768 -239.363758)
		(width 0.088646)
		(layer "In11.Cu")
		(net "M_H_CPU1_SB_DQ<2>")
	)
	(arc
		(start 134.008368 -239.363758)
		(mid 133.725666 -239.287982)
		(end 133.442964 -239.363758)
		(width 0.088646)
		(layer "In11.Cu")
		(net "M_H_CPU1_SB_DQ<2>")
	)
	(arc
		(start 131.563364 -239.363758)
		(mid 131.376166 -239.413901)
		(end 131.188968 -239.363758)
		(width 0.088646)
		(layer "In11.Cu")
		(net "M_H_CPU1_SB_DQ<2>")
	)
	(arc
		(start 137.767568 -239.363758)
		(mid 137.493369 -239.287923)
		(end 137.216896 -239.355122)
		(width 0.088646)
		(layer "In11.Cu")
		(net "M_H_CPU1_SB_DQ<2>")
	)
	(arc
		(start 130.249168 -239.363758)
		(mid 129.972355 -239.287888)
		(end 129.693924 -239.357662)
		(width 0.088646)
		(layer "In11.Cu")
		(net "M_H_CPU1_SB_DQ<2>")
	)
	(arc
		(start 134.382764 -239.363758)
		(mid 134.195566 -239.413901)
		(end 134.008368 -239.363758)
		(width 0.088646)
		(layer "In11.Cu")
		(net "M_H_CPU1_SB_DQ<2>")
	)
	(arc
		(start 126.489968 -239.363758)
		(mid 126.215769 -239.287923)
		(end 125.939296 -239.355122)
		(width 0.088646)
		(layer "In11.Cu")
		(net "M_H_CPU1_SB_DQ<2>")
	)
	(arc
		(start 137.955274 -239.414812)
		(mid 137.858057 -239.401656)
		(end 137.767568 -239.363758)
		(width 0.088646)
		(layer "In11.Cu")
		(net "M_H_CPU1_SB_DQ<2>")
	)
	(arc
		(start 125.152658 -239.134396)
		(mid 124.981364 -239.063513)
		(end 124.797566 -239.0394)
		(width 0.088646)
		(layer "In11.Cu")
		(net "M_H_CPU1_SB_DQ<2>")
	)
	(arc
		(start 128.369568 -239.363758)
		(mid 128.095369 -239.287923)
		(end 127.818896 -239.355122)
		(width 0.088646)
		(layer "In11.Cu")
		(net "M_H_CPU1_SB_DQ<2>")
	)
	(arc
		(start 136.827768 -239.363758)
		(mid 136.553569 -239.287923)
		(end 136.277096 -239.355122)
		(width 0.088646)
		(layer "In11.Cu")
		(net "M_H_CPU1_SB_DQ<2>")
	)
	(arc
		(start 126.864364 -239.363758)
		(mid 126.677166 -239.413901)
		(end 126.489968 -239.363758)
		(width 0.088646)
		(layer "In11.Cu")
		(net "M_H_CPU1_SB_DQ<2>")
	)
	(arc
		(start 132.503164 -239.363758)
		(mid 132.315966 -239.413901)
		(end 132.128768 -239.363758)
		(width 0.088646)
		(layer "In11.Cu")
		(net "M_H_CPU1_SB_DQ<2>")
	)
	(arc
		(start 127.429768 -239.363758)
		(mid 127.155569 -239.287923)
		(end 126.879096 -239.355122)
		(width 0.088646)
		(layer "In11.Cu")
		(net "M_H_CPU1_SB_DQ<2>")
	)
	(arc
		(start 125.924564 -239.363758)
		(mid 125.737366 -239.413901)
		(end 125.550168 -239.363758)
		(width 0.088646)
		(layer "In11.Cu")
		(net "M_H_CPU1_SB_DQ<2>")
	)
	(arc
		(start 136.262364 -239.363758)
		(mid 136.075166 -239.413901)
		(end 135.887968 -239.363758)
		(width 0.088646)
		(layer "In11.Cu")
		(net "M_H_CPU1_SB_DQ<2>")
	)
	(arc
		(start 131.188968 -239.363758)
		(mid 130.914769 -239.287923)
		(end 130.638296 -239.355122)
		(width 0.088646)
		(layer "In11.Cu")
		(net "M_H_CPU1_SB_DQ<2>")
	)
	(arc
		(start 135.887968 -239.363758)
		(mid 135.605266 -239.287982)
		(end 135.322564 -239.363758)
		(width 0.088646)
		(layer "In11.Cu")
		(net "M_H_CPU1_SB_DQ<2>")
	)
	(arc
		(start 127.804164 -239.363758)
		(mid 127.616966 -239.413901)
		(end 127.429768 -239.363758)
		(width 0.088646)
		(layer "In11.Cu")
		(net "M_H_CPU1_SB_DQ<2>")
	)
	(arc
		(start 130.623564 -239.363758)
		(mid 130.436366 -239.413901)
		(end 130.249168 -239.363758)
		(width 0.088646)
		(layer "In11.Cu")
		(net "M_H_CPU1_SB_DQ<2>")
	)
	(segment
		(start 209.180176 -196.041772)
		(end 206.991458 -196.041772)
		(width 0.1016)
		(layer "F.Cu")
		(net "M_H_CPU1_SB_DQ<29>")
	)
	(segment
		(start 206.971392 -196.041772)
		(end 206.626714 -196.041772)
		(width 0.20066)
		(layer "F.Cu")
		(net "M_H_CPU1_SB_DQ<29>")
	)
	(segment
		(start 209.596482 -196.035422)
		(end 209.186526 -196.035422)
		(width 0.20066)
		(layer "F.Cu")
		(net "M_H_CPU1_SB_DQ<29>")
	)
	(segment
		(start 211.619846 -196.466714)
		(end 211.619592 -196.466968)
		(width 0.20066)
		(layer "F.Cu")
		(net "M_H_CPU1_SB_DQ<29>")
	)
	(segment
		(start 206.626714 -196.041772)
		(end 206.508604 -196.159882)
		(width 0.20066)
		(layer "F.Cu")
		(net "M_H_CPU1_SB_DQ<29>")
	)
	(segment
		(start 205.84541 -196.71538)
		(end 205.596744 -196.466714)
		(width 0.20066)
		(layer "F.Cu")
		(net "M_H_CPU1_SB_DQ<29>")
	)
	(segment
		(start 210.028028 -196.466968)
		(end 209.596482 -196.035422)
		(width 0.20066)
		(layer "F.Cu")
		(net "M_H_CPU1_SB_DQ<29>")
	)
	(segment
		(start 206.508604 -196.159882)
		(end 206.508604 -196.52742)
		(width 0.20066)
		(layer "F.Cu")
		(net "M_H_CPU1_SB_DQ<29>")
	)
	(segment
		(start 122.448066 -227.367084)
		(end 122.447812 -227.36683)
		(width 0.20066)
		(layer "F.Cu")
		(net "M_H_CPU1_SB_DQ<29>")
	)
	(segment
		(start 211.619592 -196.466968)
		(end 210.028028 -196.466968)
		(width 0.20066)
		(layer "F.Cu")
		(net "M_H_CPU1_SB_DQ<29>")
	)
	(segment
		(start 206.320644 -196.71538)
		(end 205.84541 -196.71538)
		(width 0.20066)
		(layer "F.Cu")
		(net "M_H_CPU1_SB_DQ<29>")
	)
	(segment
		(start 122.447812 -227.36683)
		(end 122.447812 -226.831144)
		(width 0.20066)
		(layer "F.Cu")
		(net "M_H_CPU1_SB_DQ<29>")
	)
	(segment
		(start 206.508604 -196.52742)
		(end 206.320644 -196.71538)
		(width 0.20066)
		(layer "F.Cu")
		(net "M_H_CPU1_SB_DQ<29>")
	)
	(segment
		(start 205.596744 -196.466714)
		(end 204.076046 -196.466714)
		(width 0.20066)
		(layer "F.Cu")
		(net "M_H_CPU1_SB_DQ<29>")
	)
	(segment
		(start 209.186526 -196.035422)
		(end 209.180176 -196.041772)
		(width 0.1016)
		(layer "F.Cu")
		(net "M_H_CPU1_SB_DQ<29>")
	)
	(segment
		(start 206.991458 -196.041772)
		(end 206.971392 -196.041772)
		(width 0.101854)
		(layer "F.Cu")
		(net "M_H_CPU1_SB_DQ<29>")
	)
	(segment
		(start 204.076046 -196.466714)
		(end 202.971146 -196.466714)
		(width 0.20066)
		(layer "F.Cu")
		(net "M_H_CPU1_SB_DQ<29>")
	)
	(segment
		(start 182.399178 -194.505326)
		(end 182.206138 -194.698366)
		(width 0.18288)
		(layer "In11.Cu")
		(net "M_H_CPU1_SB_DQ<29>")
	)
	(segment
		(start 131.658614 -225.527616)
		(end 131.643882 -225.51898)
		(width 0.088646)
		(layer "In11.Cu")
		(net "M_H_CPU1_SB_DQ<29>")
	)
	(segment
		(start 197.996302 -195.96735)
		(end 197.820026 -196.143626)
		(width 0.18288)
		(layer "In11.Cu")
		(net "M_H_CPU1_SB_DQ<29>")
	)
	(segment
		(start 127.899414 -225.527616)
		(end 127.884682 -225.51898)
		(width 0.088646)
		(layer "In11.Cu")
		(net "M_H_CPU1_SB_DQ<29>")
	)
	(segment
		(start 139.672568 -219.688918)
		(end 139.672568 -219.93606)
		(width 0.088646)
		(layer "In11.Cu")
		(net "M_H_CPU1_SB_DQ<29>")
	)
	(segment
		(start 129.779014 -225.527616)
		(end 129.764282 -225.51898)
		(width 0.088646)
		(layer "In11.Cu")
		(net "M_H_CPU1_SB_DQ<29>")
	)
	(segment
		(start 192.460626 -193.959226)
		(end 182.592218 -193.959226)
		(width 0.18288)
		(layer "In11.Cu")
		(net "M_H_CPU1_SB_DQ<29>")
	)
	(segment
		(start 138.707114 -223.085914)
		(end 138.6967 -223.079818)
		(width 0.088646)
		(layer "In11.Cu")
		(net "M_H_CPU1_SB_DQ<29>")
	)
	(segment
		(start 167.865552 -195.026534)
		(end 167.305736 -195.026534)
		(width 0.18288)
		(layer "In11.Cu")
		(net "M_H_CPU1_SB_DQ<29>")
	)
	(segment
		(start 122.826272 -226.765358)
		(end 122.760486 -226.831144)
		(width 0.088646)
		(layer "In11.Cu")
		(net "M_H_CPU1_SB_DQ<29>")
	)
	(segment
		(start 181.888638 -194.698366)
		(end 181.695598 -194.505326)
		(width 0.18288)
		(layer "In11.Cu")
		(net "M_H_CPU1_SB_DQ<29>")
	)
	(segment
		(start 135.040116 -225.187764)
		(end 135.040116 -225.203258)
		(width 0.088646)
		(layer "In11.Cu")
		(net "M_H_CPU1_SB_DQ<29>")
	)
	(segment
		(start 169.647616 -195.27266)
		(end 168.459912 -195.27266)
		(width 0.18288)
		(layer "In11.Cu")
		(net "M_H_CPU1_SB_DQ<29>")
	)
	(segment
		(start 181.502558 -193.959226)
		(end 171.505626 -193.959226)
		(width 0.18288)
		(layer "In11.Cu")
		(net "M_H_CPU1_SB_DQ<29>")
	)
	(segment
		(start 202.471782 -195.96735)
		(end 197.996302 -195.96735)
		(width 0.18288)
		(layer "In11.Cu")
		(net "M_H_CPU1_SB_DQ<29>")
	)
	(segment
		(start 167.305736 -195.026534)
		(end 167.146478 -195.092574)
		(width 0.18288)
		(layer "In11.Cu")
		(net "M_H_CPU1_SB_DQ<29>")
	)
	(segment
		(start 161.371026 -195.915026)
		(end 160.685226 -196.600826)
		(width 0.18288)
		(layer "In11.Cu")
		(net "M_H_CPU1_SB_DQ<29>")
	)
	(segment
		(start 139.276328 -220.3323)
		(end 139.276328 -222.9104)
		(width 0.088646)
		(layer "In11.Cu")
		(net "M_H_CPU1_SB_DQ<29>")
	)
	(segment
		(start 126.959614 -225.527616)
		(end 126.944882 -225.51898)
		(width 0.088646)
		(layer "In11.Cu")
		(net "M_H_CPU1_SB_DQ<29>")
	)
	(segment
		(start 181.695598 -194.152266)
		(end 181.502558 -193.959226)
		(width 0.18288)
		(layer "In11.Cu")
		(net "M_H_CPU1_SB_DQ<29>")
	)
	(segment
		(start 122.760486 -226.831144)
		(end 122.447812 -226.831144)
		(width 0.088646)
		(layer "In11.Cu")
		(net "M_H_CPU1_SB_DQ<29>")
	)
	(segment
		(start 124.993654 -226.336606)
		(end 124.984764 -226.341686)
		(width 0.088646)
		(layer "In11.Cu")
		(net "M_H_CPU1_SB_DQ<29>")
	)
	(segment
		(start 166.120826 -196.118226)
		(end 164.622226 -196.118226)
		(width 0.18288)
		(layer "In11.Cu")
		(net "M_H_CPU1_SB_DQ<29>")
	)
	(segment
		(start 137.859516 -223.557084)
		(end 137.859516 -223.575626)
		(width 0.088646)
		(layer "In11.Cu")
		(net "M_H_CPU1_SB_DQ<29>")
	)
	(segment
		(start 125.172216 -225.99523)
		(end 125.172216 -226.017328)
		(width 0.088646)
		(layer "In11.Cu")
		(net "M_H_CPU1_SB_DQ<29>")
	)
	(segment
		(start 139.276328 -222.9104)
		(end 139.159742 -223.026986)
		(width 0.088646)
		(layer "In11.Cu")
		(net "M_H_CPU1_SB_DQ<29>")
	)
	(segment
		(start 137.389616 -224.379536)
		(end 137.389616 -224.389442)
		(width 0.088646)
		(layer "In11.Cu")
		(net "M_H_CPU1_SB_DQ<29>")
	)
	(segment
		(start 195.343018 -196.143626)
		(end 194.479418 -195.280026)
		(width 0.18288)
		(layer "In11.Cu")
		(net "M_H_CPU1_SB_DQ<29>")
	)
	(segment
		(start 182.592218 -193.959226)
		(end 182.399178 -194.152266)
		(width 0.18288)
		(layer "In11.Cu")
		(net "M_H_CPU1_SB_DQ<29>")
	)
	(segment
		(start 194.479418 -195.280026)
		(end 193.781426 -195.280026)
		(width 0.18288)
		(layer "In11.Cu")
		(net "M_H_CPU1_SB_DQ<29>")
	)
	(segment
		(start 182.206138 -194.698366)
		(end 181.888638 -194.698366)
		(width 0.18288)
		(layer "In11.Cu")
		(net "M_H_CPU1_SB_DQ<29>")
	)
	(segment
		(start 126.019814 -225.527616)
		(end 126.005082 -225.51898)
		(width 0.088646)
		(layer "In11.Cu")
		(net "M_H_CPU1_SB_DQ<29>")
	)
	(segment
		(start 132.598414 -225.527616)
		(end 132.583682 -225.51898)
		(width 0.088646)
		(layer "In11.Cu")
		(net "M_H_CPU1_SB_DQ<29>")
	)
	(segment
		(start 202.971146 -196.466714)
		(end 202.471782 -195.96735)
		(width 0.18288)
		(layer "In11.Cu")
		(net "M_H_CPU1_SB_DQ<29>")
	)
	(segment
		(start 158.361634 -197.93331)
		(end 156.312362 -197.93331)
		(width 0.18288)
		(layer "In11.Cu")
		(net "M_H_CPU1_SB_DQ<29>")
	)
	(segment
		(start 164.622226 -196.118226)
		(end 164.419026 -195.915026)
		(width 0.18288)
		(layer "In11.Cu")
		(net "M_H_CPU1_SB_DQ<29>")
	)
	(segment
		(start 137.211054 -224.70872)
		(end 137.202164 -224.7138)
		(width 0.088646)
		(layer "In11.Cu")
		(net "M_H_CPU1_SB_DQ<29>")
	)
	(segment
		(start 144.588484 -214.499952)
		(end 139.672568 -219.415868)
		(width 0.18288)
		(layer "In11.Cu")
		(net "M_H_CPU1_SB_DQ<29>")
	)
	(segment
		(start 181.695598 -194.505326)
		(end 181.695598 -194.152266)
		(width 0.18288)
		(layer "In11.Cu")
		(net "M_H_CPU1_SB_DQ<29>")
	)
	(segment
		(start 139.672568 -219.415868)
		(end 139.672568 -219.688918)
		(width 0.18288)
		(layer "In11.Cu")
		(net "M_H_CPU1_SB_DQ<29>")
	)
	(segment
		(start 152.528524 -201.717148)
		(end 152.528524 -203.77277)
		(width 0.18288)
		(layer "In11.Cu")
		(net "M_H_CPU1_SB_DQ<29>")
	)
	(segment
		(start 123.105164 -226.341686)
		(end 123.099068 -226.345242)
		(width 0.088646)
		(layer "In11.Cu")
		(net "M_H_CPU1_SB_DQ<29>")
	)
	(segment
		(start 133.538468 -225.527616)
		(end 133.528054 -225.52152)
		(width 0.088646)
		(layer "In11.Cu")
		(net "M_H_CPU1_SB_DQ<29>")
	)
	(segment
		(start 130.718814 -225.527616)
		(end 130.704082 -225.51898)
		(width 0.088646)
		(layer "In11.Cu")
		(net "M_H_CPU1_SB_DQ<29>")
	)
	(segment
		(start 164.419026 -195.915026)
		(end 161.371026 -195.915026)
		(width 0.18288)
		(layer "In11.Cu")
		(net "M_H_CPU1_SB_DQ<29>")
	)
	(segment
		(start 170.577256 -194.887596)
		(end 169.647616 -195.27266)
		(width 0.18288)
		(layer "In11.Cu")
		(net "M_H_CPU1_SB_DQ<29>")
	)
	(segment
		(start 152.528524 -203.77277)
		(end 144.588484 -211.71281)
		(width 0.18288)
		(layer "In11.Cu")
		(net "M_H_CPU1_SB_DQ<29>")
	)
	(segment
		(start 156.312362 -197.93331)
		(end 152.528524 -201.717148)
		(width 0.18288)
		(layer "In11.Cu")
		(net "M_H_CPU1_SB_DQ<29>")
	)
	(segment
		(start 193.781426 -195.280026)
		(end 192.460626 -193.959226)
		(width 0.18288)
		(layer "In11.Cu")
		(net "M_H_CPU1_SB_DQ<29>")
	)
	(segment
		(start 159.694118 -196.600826)
		(end 158.361634 -197.93331)
		(width 0.18288)
		(layer "In11.Cu")
		(net "M_H_CPU1_SB_DQ<29>")
	)
	(segment
		(start 197.820026 -196.143626)
		(end 195.343018 -196.143626)
		(width 0.18288)
		(layer "In11.Cu")
		(net "M_H_CPU1_SB_DQ<29>")
	)
	(segment
		(start 182.399178 -194.152266)
		(end 182.399178 -194.505326)
		(width 0.18288)
		(layer "In11.Cu")
		(net "M_H_CPU1_SB_DQ<29>")
	)
	(segment
		(start 123.119896 -226.33305)
		(end 123.105164 -226.341686)
		(width 0.088646)
		(layer "In11.Cu")
		(net "M_H_CPU1_SB_DQ<29>")
	)
	(segment
		(start 171.505626 -193.959226)
		(end 170.577256 -194.887596)
		(width 0.18288)
		(layer "In11.Cu")
		(net "M_H_CPU1_SB_DQ<29>")
	)
	(segment
		(start 168.459912 -195.27266)
		(end 167.865552 -195.026534)
		(width 0.18288)
		(layer "In11.Cu")
		(net "M_H_CPU1_SB_DQ<29>")
	)
	(segment
		(start 137.680954 -223.894904)
		(end 137.672064 -223.899984)
		(width 0.088646)
		(layer "In11.Cu")
		(net "M_H_CPU1_SB_DQ<29>")
	)
	(segment
		(start 135.887968 -224.7138)
		(end 135.877554 -224.707704)
		(width 0.088646)
		(layer "In11.Cu")
		(net "M_H_CPU1_SB_DQ<29>")
	)
	(segment
		(start 128.839214 -225.527616)
		(end 128.824482 -225.51898)
		(width 0.088646)
		(layer "In11.Cu")
		(net "M_H_CPU1_SB_DQ<29>")
	)
	(segment
		(start 160.685226 -196.600826)
		(end 159.694118 -196.600826)
		(width 0.18288)
		(layer "In11.Cu")
		(net "M_H_CPU1_SB_DQ<29>")
	)
	(segment
		(start 139.672568 -219.93606)
		(end 139.276328 -220.3323)
		(width 0.088646)
		(layer "In11.Cu")
		(net "M_H_CPU1_SB_DQ<29>")
	)
	(segment
		(start 167.146478 -195.092574)
		(end 166.120826 -196.118226)
		(width 0.18288)
		(layer "In11.Cu")
		(net "M_H_CPU1_SB_DQ<29>")
	)
	(segment
		(start 144.588484 -211.71281)
		(end 144.588484 -214.499952)
		(width 0.18288)
		(layer "In11.Cu")
		(net "M_H_CPU1_SB_DQ<29>")
	)
	(segment
		(start 134.861554 -225.522536)
		(end 134.852664 -225.527616)
		(width 0.088646)
		(layer "In11.Cu")
		(net "M_H_CPU1_SB_DQ<29>")
	)
	(arc
		(start 135.040116 -225.203258)
		(mid 134.992437 -225.386158)
		(end 134.861554 -225.522536)
		(width 0.088646)
		(layer "In11.Cu")
		(net "M_H_CPU1_SB_DQ<29>")
	)
	(arc
		(start 127.884682 -225.51898)
		(mid 127.608241 -225.451814)
		(end 127.33401 -225.527616)
		(width 0.088646)
		(layer "In11.Cu")
		(net "M_H_CPU1_SB_DQ<29>")
	)
	(arc
		(start 136.827768 -224.7138)
		(mid 136.545066 -224.638024)
		(end 136.262364 -224.7138)
		(width 0.088646)
		(layer "In11.Cu")
		(net "M_H_CPU1_SB_DQ<29>")
	)
	(arc
		(start 134.852664 -225.527616)
		(mid 134.665466 -225.577759)
		(end 134.478268 -225.527616)
		(width 0.088646)
		(layer "In11.Cu")
		(net "M_H_CPU1_SB_DQ<29>")
	)
	(arc
		(start 126.39421 -225.527616)
		(mid 126.207012 -225.577759)
		(end 126.019814 -225.527616)
		(width 0.088646)
		(layer "In11.Cu")
		(net "M_H_CPU1_SB_DQ<29>")
	)
	(arc
		(start 130.15341 -225.527616)
		(mid 129.966212 -225.577759)
		(end 129.779014 -225.527616)
		(width 0.088646)
		(layer "In11.Cu")
		(net "M_H_CPU1_SB_DQ<29>")
	)
	(arc
		(start 124.610368 -226.341686)
		(mid 124.327666 -226.26591)
		(end 124.044964 -226.341686)
		(width 0.088646)
		(layer "In11.Cu")
		(net "M_H_CPU1_SB_DQ<29>")
	)
	(arc
		(start 133.528054 -225.52152)
		(mid 133.249622 -225.451706)
		(end 132.97281 -225.527616)
		(width 0.088646)
		(layer "In11.Cu")
		(net "M_H_CPU1_SB_DQ<29>")
	)
	(arc
		(start 127.33401 -225.527616)
		(mid 127.146812 -225.577759)
		(end 126.959614 -225.527616)
		(width 0.088646)
		(layer "In11.Cu")
		(net "M_H_CPU1_SB_DQ<29>")
	)
	(arc
		(start 138.141964 -223.085914)
		(mid 137.939678 -223.284895)
		(end 137.859516 -223.557084)
		(width 0.088646)
		(layer "In11.Cu")
		(net "M_H_CPU1_SB_DQ<29>")
	)
	(arc
		(start 135.32231 -224.7138)
		(mid 135.119487 -224.914031)
		(end 135.040116 -225.187764)
		(width 0.088646)
		(layer "In11.Cu")
		(net "M_H_CPU1_SB_DQ<29>")
	)
	(arc
		(start 123.670568 -226.341686)
		(mid 123.396369 -226.265851)
		(end 123.119896 -226.33305)
		(width 0.088646)
		(layer "In11.Cu")
		(net "M_H_CPU1_SB_DQ<29>")
	)
	(arc
		(start 134.478268 -225.527616)
		(mid 134.195566 -225.451874)
		(end 133.912864 -225.527616)
		(width 0.088646)
		(layer "In11.Cu")
		(net "M_H_CPU1_SB_DQ<29>")
	)
	(arc
		(start 132.583682 -225.51898)
		(mid 132.307241 -225.451814)
		(end 132.03301 -225.527616)
		(width 0.088646)
		(layer "In11.Cu")
		(net "M_H_CPU1_SB_DQ<29>")
	)
	(arc
		(start 130.704082 -225.51898)
		(mid 130.427641 -225.451814)
		(end 130.15341 -225.527616)
		(width 0.088646)
		(layer "In11.Cu")
		(net "M_H_CPU1_SB_DQ<29>")
	)
	(arc
		(start 131.09321 -225.527616)
		(mid 130.906012 -225.577759)
		(end 130.718814 -225.527616)
		(width 0.088646)
		(layer "In11.Cu")
		(net "M_H_CPU1_SB_DQ<29>")
	)
	(arc
		(start 129.764282 -225.51898)
		(mid 129.487841 -225.451814)
		(end 129.21361 -225.527616)
		(width 0.088646)
		(layer "In11.Cu")
		(net "M_H_CPU1_SB_DQ<29>")
	)
	(arc
		(start 125.45441 -225.527616)
		(mid 125.253128 -225.725103)
		(end 125.172216 -225.99523)
		(width 0.088646)
		(layer "In11.Cu")
		(net "M_H_CPU1_SB_DQ<29>")
	)
	(arc
		(start 139.159742 -223.026986)
		(mid 139.122551 -223.059004)
		(end 139.08151 -223.085914)
		(width 0.088646)
		(layer "In11.Cu")
		(net "M_H_CPU1_SB_DQ<29>")
	)
	(arc
		(start 128.27381 -225.527616)
		(mid 128.086612 -225.577759)
		(end 127.899414 -225.527616)
		(width 0.088646)
		(layer "In11.Cu")
		(net "M_H_CPU1_SB_DQ<29>")
	)
	(arc
		(start 123.099068 -226.345242)
		(mid 122.913613 -226.523437)
		(end 122.826272 -226.765358)
		(width 0.088646)
		(layer "In11.Cu")
		(net "M_H_CPU1_SB_DQ<29>")
	)
	(arc
		(start 139.08151 -223.085914)
		(mid 138.894312 -223.136057)
		(end 138.707114 -223.085914)
		(width 0.088646)
		(layer "In11.Cu")
		(net "M_H_CPU1_SB_DQ<29>")
	)
	(arc
		(start 128.824482 -225.51898)
		(mid 128.548041 -225.451814)
		(end 128.27381 -225.527616)
		(width 0.088646)
		(layer "In11.Cu")
		(net "M_H_CPU1_SB_DQ<29>")
	)
	(arc
		(start 135.877554 -224.707704)
		(mid 135.599122 -224.637858)
		(end 135.32231 -224.7138)
		(width 0.088646)
		(layer "In11.Cu")
		(net "M_H_CPU1_SB_DQ<29>")
	)
	(arc
		(start 126.005082 -225.51898)
		(mid 125.728641 -225.451814)
		(end 125.45441 -225.527616)
		(width 0.088646)
		(layer "In11.Cu")
		(net "M_H_CPU1_SB_DQ<29>")
	)
	(arc
		(start 131.643882 -225.51898)
		(mid 131.367441 -225.451814)
		(end 131.09321 -225.527616)
		(width 0.088646)
		(layer "In11.Cu")
		(net "M_H_CPU1_SB_DQ<29>")
	)
	(arc
		(start 133.912864 -225.527616)
		(mid 133.725666 -225.577759)
		(end 133.538468 -225.527616)
		(width 0.088646)
		(layer "In11.Cu")
		(net "M_H_CPU1_SB_DQ<29>")
	)
	(arc
		(start 137.859516 -223.575626)
		(mid 137.811837 -223.758526)
		(end 137.680954 -223.894904)
		(width 0.088646)
		(layer "In11.Cu")
		(net "M_H_CPU1_SB_DQ<29>")
	)
	(arc
		(start 124.984764 -226.341686)
		(mid 124.797566 -226.391829)
		(end 124.610368 -226.341686)
		(width 0.088646)
		(layer "In11.Cu")
		(net "M_H_CPU1_SB_DQ<29>")
	)
	(arc
		(start 137.672064 -223.899984)
		(mid 137.467729 -224.102589)
		(end 137.389616 -224.379536)
		(width 0.088646)
		(layer "In11.Cu")
		(net "M_H_CPU1_SB_DQ<29>")
	)
	(arc
		(start 136.262364 -224.7138)
		(mid 136.075166 -224.763943)
		(end 135.887968 -224.7138)
		(width 0.088646)
		(layer "In11.Cu")
		(net "M_H_CPU1_SB_DQ<29>")
	)
	(arc
		(start 137.389616 -224.389442)
		(mid 137.341937 -224.572342)
		(end 137.211054 -224.70872)
		(width 0.088646)
		(layer "In11.Cu")
		(net "M_H_CPU1_SB_DQ<29>")
	)
	(arc
		(start 124.044964 -226.341686)
		(mid 123.857766 -226.391829)
		(end 123.670568 -226.341686)
		(width 0.088646)
		(layer "In11.Cu")
		(net "M_H_CPU1_SB_DQ<29>")
	)
	(arc
		(start 126.944882 -225.51898)
		(mid 126.668441 -225.451814)
		(end 126.39421 -225.527616)
		(width 0.088646)
		(layer "In11.Cu")
		(net "M_H_CPU1_SB_DQ<29>")
	)
	(arc
		(start 137.202164 -224.7138)
		(mid 137.014966 -224.763943)
		(end 136.827768 -224.7138)
		(width 0.088646)
		(layer "In11.Cu")
		(net "M_H_CPU1_SB_DQ<29>")
	)
	(arc
		(start 132.97281 -225.527616)
		(mid 132.785612 -225.577759)
		(end 132.598414 -225.527616)
		(width 0.088646)
		(layer "In11.Cu")
		(net "M_H_CPU1_SB_DQ<29>")
	)
	(arc
		(start 129.21361 -225.527616)
		(mid 129.026412 -225.577759)
		(end 128.839214 -225.527616)
		(width 0.088646)
		(layer "In11.Cu")
		(net "M_H_CPU1_SB_DQ<29>")
	)
	(arc
		(start 125.172216 -226.017328)
		(mid 125.124537 -226.200228)
		(end 124.993654 -226.336606)
		(width 0.088646)
		(layer "In11.Cu")
		(net "M_H_CPU1_SB_DQ<29>")
	)
	(arc
		(start 132.03301 -225.527616)
		(mid 131.845812 -225.577759)
		(end 131.658614 -225.527616)
		(width 0.088646)
		(layer "In11.Cu")
		(net "M_H_CPU1_SB_DQ<29>")
	)
	(arc
		(start 138.6967 -223.079818)
		(mid 138.418522 -223.010126)
		(end 138.141964 -223.085914)
		(width 0.088646)
		(layer "In11.Cu")
		(net "M_H_CPU1_SB_DQ<29>")
	)
	(segment
		(start 209.186526 -197.735444)
		(end 209.180176 -197.741794)
		(width 0.1016)
		(layer "F.Cu")
		(net "M_H_CPU1_SB_DQ<28>")
	)
	(segment
		(start 211.619846 -198.166736)
		(end 211.619592 -198.16699)
		(width 0.20066)
		(layer "F.Cu")
		(net "M_H_CPU1_SB_DQ<28>")
	)
	(segment
		(start 211.619592 -198.16699)
		(end 210.028028 -198.16699)
		(width 0.20066)
		(layer "F.Cu")
		(net "M_H_CPU1_SB_DQ<28>")
	)
	(segment
		(start 206.320644 -198.415402)
		(end 205.84541 -198.415402)
		(width 0.20066)
		(layer "F.Cu")
		(net "M_H_CPU1_SB_DQ<28>")
	)
	(segment
		(start 125.267466 -227.367084)
		(end 125.267212 -227.36683)
		(width 0.20066)
		(layer "F.Cu")
		(net "M_H_CPU1_SB_DQ<28>")
	)
	(segment
		(start 125.267212 -227.36683)
		(end 125.267212 -226.831144)
		(width 0.20066)
		(layer "F.Cu")
		(net "M_H_CPU1_SB_DQ<28>")
	)
	(segment
		(start 204.076046 -198.166736)
		(end 202.971146 -198.166736)
		(width 0.20066)
		(layer "F.Cu")
		(net "M_H_CPU1_SB_DQ<28>")
	)
	(segment
		(start 206.508604 -198.227442)
		(end 206.320644 -198.415402)
		(width 0.20066)
		(layer "F.Cu")
		(net "M_H_CPU1_SB_DQ<28>")
	)
	(segment
		(start 209.596482 -197.735444)
		(end 209.186526 -197.735444)
		(width 0.20066)
		(layer "F.Cu")
		(net "M_H_CPU1_SB_DQ<28>")
	)
	(segment
		(start 210.028028 -198.16699)
		(end 209.596482 -197.735444)
		(width 0.20066)
		(layer "F.Cu")
		(net "M_H_CPU1_SB_DQ<28>")
	)
	(segment
		(start 206.626714 -197.741794)
		(end 206.508604 -197.859904)
		(width 0.20066)
		(layer "F.Cu")
		(net "M_H_CPU1_SB_DQ<28>")
	)
	(segment
		(start 205.84541 -198.415402)
		(end 205.596744 -198.166736)
		(width 0.20066)
		(layer "F.Cu")
		(net "M_H_CPU1_SB_DQ<28>")
	)
	(segment
		(start 206.971392 -197.741794)
		(end 206.626714 -197.741794)
		(width 0.20066)
		(layer "F.Cu")
		(net "M_H_CPU1_SB_DQ<28>")
	)
	(segment
		(start 209.180176 -197.741794)
		(end 207.018382 -197.741794)
		(width 0.1016)
		(layer "F.Cu")
		(net "M_H_CPU1_SB_DQ<28>")
	)
	(segment
		(start 206.508604 -197.859904)
		(end 206.508604 -198.227442)
		(width 0.20066)
		(layer "F.Cu")
		(net "M_H_CPU1_SB_DQ<28>")
	)
	(segment
		(start 205.596744 -198.166736)
		(end 204.076046 -198.166736)
		(width 0.20066)
		(layer "F.Cu")
		(net "M_H_CPU1_SB_DQ<28>")
	)
	(segment
		(start 207.018382 -197.741794)
		(end 206.971392 -197.741794)
		(width 0.101854)
		(layer "F.Cu")
		(net "M_H_CPU1_SB_DQ<28>")
	)
	(segment
		(start 135.331454 -226.336606)
		(end 135.322564 -226.341686)
		(width 0.088646)
		(layer "In11.Cu")
		(net "M_H_CPU1_SB_DQ<28>")
	)
	(segment
		(start 175.341534 -196.041518)
		(end 175.188626 -196.194426)
		(width 0.18288)
		(layer "In11.Cu")
		(net "M_H_CPU1_SB_DQ<28>")
	)
	(segment
		(start 195.432426 -197.972426)
		(end 194.492626 -197.032626)
		(width 0.18288)
		(layer "In11.Cu")
		(net "M_H_CPU1_SB_DQ<28>")
	)
	(segment
		(start 190.937134 -196.041518)
		(end 190.758826 -196.219826)
		(width 0.18288)
		(layer "In11.Cu")
		(net "M_H_CPU1_SB_DQ<28>")
	)
	(segment
		(start 183.392826 -196.854826)
		(end 181.942232 -196.854826)
		(width 0.18288)
		(layer "In11.Cu")
		(net "M_H_CPU1_SB_DQ<28>")
	)
	(segment
		(start 200.838308 -198.024242)
		(end 200.452228 -198.024242)
		(width 0.18288)
		(layer "In11.Cu")
		(net "M_H_CPU1_SB_DQ<28>")
	)
	(segment
		(start 186.98845 -196.891402)
		(end 186.764422 -197.11543)
		(width 0.18288)
		(layer "In11.Cu")
		(net "M_H_CPU1_SB_DQ<28>")
	)
	(segment
		(start 181.749192 -197.047866)
		(end 181.749192 -197.672198)
		(width 0.18288)
		(layer "In11.Cu")
		(net "M_H_CPU1_SB_DQ<28>")
	)
	(segment
		(start 139.821158 -223.088708)
		(end 139.085574 -223.824292)
		(width 0.088646)
		(layer "In11.Cu")
		(net "M_H_CPU1_SB_DQ<28>")
	)
	(segment
		(start 200.066148 -198.658226)
		(end 198.912226 -198.658226)
		(width 0.18288)
		(layer "In11.Cu")
		(net "M_H_CPU1_SB_DQ<28>")
	)
	(segment
		(start 125.579886 -226.831144)
		(end 125.267212 -226.831144)
		(width 0.088646)
		(layer "In11.Cu")
		(net "M_H_CPU1_SB_DQ<28>")
	)
	(segment
		(start 170.130978 -197.092316)
		(end 170.130978 -197.293992)
		(width 0.18288)
		(layer "In11.Cu")
		(net "M_H_CPU1_SB_DQ<28>")
	)
	(segment
		(start 193.679826 -197.032626)
		(end 192.688718 -196.041518)
		(width 0.18288)
		(layer "In11.Cu")
		(net "M_H_CPU1_SB_DQ<28>")
	)
	(segment
		(start 137.859516 -225.193352)
		(end 137.859516 -225.203258)
		(width 0.088646)
		(layer "In11.Cu")
		(net "M_H_CPU1_SB_DQ<28>")
	)
	(segment
		(start 178.973226 -196.981826)
		(end 178.668426 -196.677026)
		(width 0.18288)
		(layer "In11.Cu")
		(net "M_H_CPU1_SB_DQ<28>")
	)
	(segment
		(start 164.342826 -197.693026)
		(end 163.669726 -197.693026)
		(width 0.18288)
		(layer "In11.Cu")
		(net "M_H_CPU1_SB_DQ<28>")
	)
	(segment
		(start 198.226426 -197.972426)
		(end 195.432426 -197.972426)
		(width 0.18288)
		(layer "In11.Cu")
		(net "M_H_CPU1_SB_DQ<28>")
	)
	(segment
		(start 138.150854 -224.70872)
		(end 138.141964 -224.7138)
		(width 0.088646)
		(layer "In11.Cu")
		(net "M_H_CPU1_SB_DQ<28>")
	)
	(segment
		(start 161.218626 -198.632826)
		(end 160.329626 -199.521826)
		(width 0.18288)
		(layer "In11.Cu")
		(net "M_H_CPU1_SB_DQ<28>")
	)
	(segment
		(start 190.758826 -196.219826)
		(end 189.488826 -196.219826)
		(width 0.18288)
		(layer "In11.Cu")
		(net "M_H_CPU1_SB_DQ<28>")
	)
	(segment
		(start 201.031348 -198.217282)
		(end 200.838308 -198.024242)
		(width 0.18288)
		(layer "In11.Cu")
		(net "M_H_CPU1_SB_DQ<28>")
	)
	(segment
		(start 125.924564 -226.341686)
		(end 125.918468 -226.345242)
		(width 0.088646)
		(layer "In11.Cu")
		(net "M_H_CPU1_SB_DQ<28>")
	)
	(segment
		(start 200.452228 -198.024242)
		(end 200.259188 -198.217282)
		(width 0.18288)
		(layer "In11.Cu")
		(net "M_H_CPU1_SB_DQ<28>")
	)
	(segment
		(start 180.783992 -196.854826)
		(end 179.506626 -196.854826)
		(width 0.18288)
		(layer "In11.Cu")
		(net "M_H_CPU1_SB_DQ<28>")
	)
	(segment
		(start 145.65884 -212.16747)
		(end 145.65884 -215.17864)
		(width 0.18288)
		(layer "In11.Cu")
		(net "M_H_CPU1_SB_DQ<28>")
	)
	(segment
		(start 166.415974 -197.921626)
		(end 164.571426 -197.921626)
		(width 0.18288)
		(layer "In11.Cu")
		(net "M_H_CPU1_SB_DQ<28>")
	)
	(segment
		(start 162.729926 -198.632826)
		(end 161.218626 -198.632826)
		(width 0.18288)
		(layer "In11.Cu")
		(net "M_H_CPU1_SB_DQ<28>")
	)
	(segment
		(start 125.939296 -226.33305)
		(end 125.924564 -226.341686)
		(width 0.088646)
		(layer "In11.Cu")
		(net "M_H_CPU1_SB_DQ<28>")
	)
	(segment
		(start 201.031348 -198.465186)
		(end 201.031348 -198.217282)
		(width 0.18288)
		(layer "In11.Cu")
		(net "M_H_CPU1_SB_DQ<28>")
	)
	(segment
		(start 166.784782 -198.290434)
		(end 166.415974 -197.921626)
		(width 0.18288)
		(layer "In11.Cu")
		(net "M_H_CPU1_SB_DQ<28>")
	)
	(segment
		(start 200.259188 -198.217282)
		(end 200.259188 -198.465186)
		(width 0.18288)
		(layer "In11.Cu")
		(net "M_H_CPU1_SB_DQ<28>")
	)
	(segment
		(start 177.982626 -196.677026)
		(end 177.347118 -196.041518)
		(width 0.18288)
		(layer "In11.Cu")
		(net "M_H_CPU1_SB_DQ<28>")
	)
	(segment
		(start 140.264642 -220.572838)
		(end 139.821158 -221.016322)
		(width 0.088646)
		(layer "In11.Cu")
		(net "M_H_CPU1_SB_DQ<28>")
	)
	(segment
		(start 168.5671 -197.227952)
		(end 168.5671 -197.809612)
		(width 0.18288)
		(layer "In11.Cu")
		(net "M_H_CPU1_SB_DQ<28>")
	)
	(segment
		(start 202.858878 -198.5772)
		(end 202.663044 -198.658226)
		(width 0.18288)
		(layer "In11.Cu")
		(net "M_H_CPU1_SB_DQ<28>")
	)
	(segment
		(start 153.710894 -202.340464)
		(end 153.710894 -204.115416)
		(width 0.18288)
		(layer "In11.Cu")
		(net "M_H_CPU1_SB_DQ<28>")
	)
	(segment
		(start 169.620438 -197.487032)
		(end 169.427398 -197.293992)
		(width 0.18288)
		(layer "In11.Cu")
		(net "M_H_CPU1_SB_DQ<28>")
	)
	(segment
		(start 138.32967 -224.389442)
		(end 138.329416 -224.389442)
		(width 0.088646)
		(layer "In11.Cu")
		(net "M_H_CPU1_SB_DQ<28>")
	)
	(segment
		(start 185.870342 -196.62902)
		(end 185.677302 -196.43598)
		(width 0.18288)
		(layer "In11.Cu")
		(net "M_H_CPU1_SB_DQ<28>")
	)
	(segment
		(start 139.085574 -223.824292)
		(end 138.894312 -223.824292)
		(width 0.088646)
		(layer "In11.Cu")
		(net "M_H_CPU1_SB_DQ<28>")
	)
	(segment
		(start 153.710894 -204.115416)
		(end 145.65884 -212.16747)
		(width 0.18288)
		(layer "In11.Cu")
		(net "M_H_CPU1_SB_DQ<28>")
	)
	(segment
		(start 175.188626 -196.194426)
		(end 173.944026 -196.194426)
		(width 0.18288)
		(layer "In11.Cu")
		(net "M_H_CPU1_SB_DQ<28>")
	)
	(segment
		(start 134.397496 -226.33305)
		(end 134.382764 -226.341686)
		(width 0.088646)
		(layer "In11.Cu")
		(net "M_H_CPU1_SB_DQ<28>")
	)
	(segment
		(start 200.259188 -198.465186)
		(end 200.066148 -198.658226)
		(width 0.18288)
		(layer "In11.Cu")
		(net "M_H_CPU1_SB_DQ<28>")
	)
	(segment
		(start 125.645672 -226.765358)
		(end 125.579886 -226.831144)
		(width 0.088646)
		(layer "In11.Cu")
		(net "M_H_CPU1_SB_DQ<28>")
	)
	(segment
		(start 168.086278 -198.290434)
		(end 166.784782 -198.290434)
		(width 0.18288)
		(layer "In11.Cu")
		(net "M_H_CPU1_SB_DQ<28>")
	)
	(segment
		(start 181.556152 -197.865238)
		(end 181.170072 -197.865238)
		(width 0.18288)
		(layer "In11.Cu")
		(net "M_H_CPU1_SB_DQ<28>")
	)
	(segment
		(start 201.224388 -198.658226)
		(end 201.031348 -198.465186)
		(width 0.18288)
		(layer "In11.Cu")
		(net "M_H_CPU1_SB_DQ<28>")
	)
	(segment
		(start 185.098182 -196.62902)
		(end 185.098182 -196.92239)
		(width 0.18288)
		(layer "In11.Cu")
		(net "M_H_CPU1_SB_DQ<28>")
	)
	(segment
		(start 198.912226 -198.658226)
		(end 198.226426 -197.972426)
		(width 0.18288)
		(layer "In11.Cu")
		(net "M_H_CPU1_SB_DQ<28>")
	)
	(segment
		(start 131.578096 -226.33305)
		(end 131.563364 -226.341686)
		(width 0.088646)
		(layer "In11.Cu")
		(net "M_H_CPU1_SB_DQ<28>")
	)
	(segment
		(start 135.510016 -225.998786)
		(end 135.510016 -226.017328)
		(width 0.088646)
		(layer "In11.Cu")
		(net "M_H_CPU1_SB_DQ<28>")
	)
	(segment
		(start 192.688718 -196.041518)
		(end 190.937134 -196.041518)
		(width 0.18288)
		(layer "In11.Cu")
		(net "M_H_CPU1_SB_DQ<28>")
	)
	(segment
		(start 164.571426 -197.921626)
		(end 164.342826 -197.693026)
		(width 0.18288)
		(layer "In11.Cu")
		(net "M_H_CPU1_SB_DQ<28>")
	)
	(segment
		(start 181.942232 -196.854826)
		(end 181.749192 -197.047866)
		(width 0.18288)
		(layer "In11.Cu")
		(net "M_H_CPU1_SB_DQ<28>")
	)
	(segment
		(start 173.244256 -196.894196)
		(end 170.329098 -196.894196)
		(width 0.18288)
		(layer "In11.Cu")
		(net "M_H_CPU1_SB_DQ<28>")
	)
	(segment
		(start 129.698496 -226.33305)
		(end 129.683764 -226.341686)
		(width 0.088646)
		(layer "In11.Cu")
		(net "M_H_CPU1_SB_DQ<28>")
	)
	(segment
		(start 179.379626 -196.981826)
		(end 178.973226 -196.981826)
		(width 0.18288)
		(layer "In11.Cu")
		(net "M_H_CPU1_SB_DQ<28>")
	)
	(segment
		(start 145.65884 -215.17864)
		(end 140.264642 -220.572838)
		(width 0.18288)
		(layer "In11.Cu")
		(net "M_H_CPU1_SB_DQ<28>")
	)
	(segment
		(start 202.971146 -198.166736)
		(end 202.971146 -198.464932)
		(width 0.18288)
		(layer "In11.Cu")
		(net "M_H_CPU1_SB_DQ<28>")
	)
	(segment
		(start 180.977032 -197.672198)
		(end 180.977032 -197.047866)
		(width 0.18288)
		(layer "In11.Cu")
		(net "M_H_CPU1_SB_DQ<28>")
	)
	(segment
		(start 169.937938 -197.487032)
		(end 169.620438 -197.487032)
		(width 0.18288)
		(layer "In11.Cu")
		(net "M_H_CPU1_SB_DQ<28>")
	)
	(segment
		(start 185.677302 -196.43598)
		(end 185.291222 -196.43598)
		(width 0.18288)
		(layer "In11.Cu")
		(net "M_H_CPU1_SB_DQ<28>")
	)
	(segment
		(start 186.063382 -197.11543)
		(end 185.870342 -196.92239)
		(width 0.18288)
		(layer "In11.Cu")
		(net "M_H_CPU1_SB_DQ<28>")
	)
	(segment
		(start 160.329626 -199.521826)
		(end 156.529532 -199.521826)
		(width 0.18288)
		(layer "In11.Cu")
		(net "M_H_CPU1_SB_DQ<28>")
	)
	(segment
		(start 169.234358 -196.899276)
		(end 168.895776 -196.899276)
		(width 0.18288)
		(layer "In11.Cu")
		(net "M_H_CPU1_SB_DQ<28>")
	)
	(segment
		(start 181.170072 -197.865238)
		(end 180.977032 -197.672198)
		(width 0.18288)
		(layer "In11.Cu")
		(net "M_H_CPU1_SB_DQ<28>")
	)
	(segment
		(start 181.749192 -197.672198)
		(end 181.556152 -197.865238)
		(width 0.18288)
		(layer "In11.Cu")
		(net "M_H_CPU1_SB_DQ<28>")
	)
	(segment
		(start 137.680954 -225.522536)
		(end 137.672064 -225.527616)
		(width 0.088646)
		(layer "In11.Cu")
		(net "M_H_CPU1_SB_DQ<28>")
	)
	(segment
		(start 189.488826 -196.219826)
		(end 188.81725 -196.891402)
		(width 0.18288)
		(layer "In11.Cu")
		(net "M_H_CPU1_SB_DQ<28>")
	)
	(segment
		(start 185.870342 -196.92239)
		(end 185.870342 -196.62902)
		(width 0.18288)
		(layer "In11.Cu")
		(net "M_H_CPU1_SB_DQ<28>")
	)
	(segment
		(start 186.764422 -197.11543)
		(end 186.063382 -197.11543)
		(width 0.18288)
		(layer "In11.Cu")
		(net "M_H_CPU1_SB_DQ<28>")
	)
	(segment
		(start 156.529532 -199.521826)
		(end 153.710894 -202.340464)
		(width 0.18288)
		(layer "In11.Cu")
		(net "M_H_CPU1_SB_DQ<28>")
	)
	(segment
		(start 163.669726 -197.693026)
		(end 162.729926 -198.632826)
		(width 0.18288)
		(layer "In11.Cu")
		(net "M_H_CPU1_SB_DQ<28>")
	)
	(segment
		(start 185.098182 -196.92239)
		(end 184.905142 -197.11543)
		(width 0.18288)
		(layer "In11.Cu")
		(net "M_H_CPU1_SB_DQ<28>")
	)
	(segment
		(start 132.517896 -226.33305)
		(end 132.503164 -226.341686)
		(width 0.088646)
		(layer "In11.Cu")
		(net "M_H_CPU1_SB_DQ<28>")
	)
	(segment
		(start 128.758696 -226.33305)
		(end 128.743964 -226.341686)
		(width 0.088646)
		(layer "In11.Cu")
		(net "M_H_CPU1_SB_DQ<28>")
	)
	(segment
		(start 183.65343 -197.11543)
		(end 183.392826 -196.854826)
		(width 0.18288)
		(layer "In11.Cu")
		(net "M_H_CPU1_SB_DQ<28>")
	)
	(segment
		(start 168.895776 -196.899276)
		(end 168.5671 -197.227952)
		(width 0.18288)
		(layer "In11.Cu")
		(net "M_H_CPU1_SB_DQ<28>")
	)
	(segment
		(start 178.668426 -196.677026)
		(end 177.982626 -196.677026)
		(width 0.18288)
		(layer "In11.Cu")
		(net "M_H_CPU1_SB_DQ<28>")
	)
	(segment
		(start 180.977032 -197.047866)
		(end 180.783992 -196.854826)
		(width 0.18288)
		(layer "In11.Cu")
		(net "M_H_CPU1_SB_DQ<28>")
	)
	(segment
		(start 170.329098 -196.894196)
		(end 170.130978 -197.092316)
		(width 0.18288)
		(layer "In11.Cu")
		(net "M_H_CPU1_SB_DQ<28>")
	)
	(segment
		(start 169.427398 -197.092316)
		(end 169.234358 -196.899276)
		(width 0.18288)
		(layer "In11.Cu")
		(net "M_H_CPU1_SB_DQ<28>")
	)
	(segment
		(start 177.347118 -196.041518)
		(end 175.341534 -196.041518)
		(width 0.18288)
		(layer "In11.Cu")
		(net "M_H_CPU1_SB_DQ<28>")
	)
	(segment
		(start 184.905142 -197.11543)
		(end 183.65343 -197.11543)
		(width 0.18288)
		(layer "In11.Cu")
		(net "M_H_CPU1_SB_DQ<28>")
	)
	(segment
		(start 170.130978 -197.293992)
		(end 169.937938 -197.487032)
		(width 0.18288)
		(layer "In11.Cu")
		(net "M_H_CPU1_SB_DQ<28>")
	)
	(segment
		(start 185.291222 -196.43598)
		(end 185.098182 -196.62902)
		(width 0.18288)
		(layer "In11.Cu")
		(net "M_H_CPU1_SB_DQ<28>")
	)
	(segment
		(start 202.663044 -198.658226)
		(end 201.224388 -198.658226)
		(width 0.18288)
		(layer "In11.Cu")
		(net "M_H_CPU1_SB_DQ<28>")
	)
	(segment
		(start 168.5671 -197.809612)
		(end 168.086278 -198.290434)
		(width 0.18288)
		(layer "In11.Cu")
		(net "M_H_CPU1_SB_DQ<28>")
	)
	(segment
		(start 202.971146 -198.464932)
		(end 202.858878 -198.5772)
		(width 0.18288)
		(layer "In11.Cu")
		(net "M_H_CPU1_SB_DQ<28>")
	)
	(segment
		(start 179.506626 -196.854826)
		(end 179.379626 -196.981826)
		(width 0.18288)
		(layer "In11.Cu")
		(net "M_H_CPU1_SB_DQ<28>")
	)
	(segment
		(start 169.427398 -197.293992)
		(end 169.427398 -197.092316)
		(width 0.18288)
		(layer "In11.Cu")
		(net "M_H_CPU1_SB_DQ<28>")
	)
	(segment
		(start 139.821158 -221.016322)
		(end 139.821158 -223.088708)
		(width 0.088646)
		(layer "In11.Cu")
		(net "M_H_CPU1_SB_DQ<28>")
	)
	(segment
		(start 194.492626 -197.032626)
		(end 193.679826 -197.032626)
		(width 0.18288)
		(layer "In11.Cu")
		(net "M_H_CPU1_SB_DQ<28>")
	)
	(segment
		(start 188.81725 -196.891402)
		(end 186.98845 -196.891402)
		(width 0.18288)
		(layer "In11.Cu")
		(net "M_H_CPU1_SB_DQ<28>")
	)
	(segment
		(start 173.944026 -196.194426)
		(end 173.244256 -196.894196)
		(width 0.18288)
		(layer "In11.Cu")
		(net "M_H_CPU1_SB_DQ<28>")
	)
	(arc
		(start 135.792464 -225.527616)
		(mid 135.590178 -225.726597)
		(end 135.510016 -225.998786)
		(width 0.088646)
		(layer "In11.Cu")
		(net "M_H_CPU1_SB_DQ<28>")
	)
	(arc
		(start 138.141964 -224.7138)
		(mid 137.937629 -224.916405)
		(end 137.859516 -225.193352)
		(width 0.088646)
		(layer "In11.Cu")
		(net "M_H_CPU1_SB_DQ<28>")
	)
	(arc
		(start 130.249168 -226.341686)
		(mid 129.974969 -226.265851)
		(end 129.698496 -226.33305)
		(width 0.088646)
		(layer "In11.Cu")
		(net "M_H_CPU1_SB_DQ<28>")
	)
	(arc
		(start 126.864364 -226.341686)
		(mid 126.677166 -226.391829)
		(end 126.489968 -226.341686)
		(width 0.088646)
		(layer "In11.Cu")
		(net "M_H_CPU1_SB_DQ<28>")
	)
	(arc
		(start 131.188968 -226.341686)
		(mid 130.906266 -226.26591)
		(end 130.623564 -226.341686)
		(width 0.088646)
		(layer "In11.Cu")
		(net "M_H_CPU1_SB_DQ<28>")
	)
	(arc
		(start 137.672064 -225.527616)
		(mid 137.484866 -225.577759)
		(end 137.297668 -225.527616)
		(width 0.088646)
		(layer "In11.Cu")
		(net "M_H_CPU1_SB_DQ<28>")
	)
	(arc
		(start 134.008368 -226.341686)
		(mid 133.725666 -226.26591)
		(end 133.442964 -226.341686)
		(width 0.088646)
		(layer "In11.Cu")
		(net "M_H_CPU1_SB_DQ<28>")
	)
	(arc
		(start 129.309368 -226.341686)
		(mid 129.035169 -226.265851)
		(end 128.758696 -226.33305)
		(width 0.088646)
		(layer "In11.Cu")
		(net "M_H_CPU1_SB_DQ<28>")
	)
	(arc
		(start 137.859516 -225.203258)
		(mid 137.811837 -225.386158)
		(end 137.680954 -225.522536)
		(width 0.088646)
		(layer "In11.Cu")
		(net "M_H_CPU1_SB_DQ<28>")
	)
	(arc
		(start 134.948168 -226.341686)
		(mid 134.673969 -226.265851)
		(end 134.397496 -226.33305)
		(width 0.088646)
		(layer "In11.Cu")
		(net "M_H_CPU1_SB_DQ<28>")
	)
	(arc
		(start 129.683764 -226.341686)
		(mid 129.496566 -226.391829)
		(end 129.309368 -226.341686)
		(width 0.088646)
		(layer "In11.Cu")
		(net "M_H_CPU1_SB_DQ<28>")
	)
	(arc
		(start 134.382764 -226.341686)
		(mid 134.195566 -226.391829)
		(end 134.008368 -226.341686)
		(width 0.088646)
		(layer "In11.Cu")
		(net "M_H_CPU1_SB_DQ<28>")
	)
	(arc
		(start 132.503164 -226.341686)
		(mid 132.315966 -226.391829)
		(end 132.128768 -226.341686)
		(width 0.088646)
		(layer "In11.Cu")
		(net "M_H_CPU1_SB_DQ<28>")
	)
	(arc
		(start 132.128768 -226.341686)
		(mid 131.854569 -226.265851)
		(end 131.578096 -226.33305)
		(width 0.088646)
		(layer "In11.Cu")
		(net "M_H_CPU1_SB_DQ<28>")
	)
	(arc
		(start 130.623564 -226.341686)
		(mid 130.436366 -226.391829)
		(end 130.249168 -226.341686)
		(width 0.088646)
		(layer "In11.Cu")
		(net "M_H_CPU1_SB_DQ<28>")
	)
	(arc
		(start 125.918468 -226.345242)
		(mid 125.733013 -226.523437)
		(end 125.645672 -226.765358)
		(width 0.088646)
		(layer "In11.Cu")
		(net "M_H_CPU1_SB_DQ<28>")
	)
	(arc
		(start 127.804164 -226.341686)
		(mid 127.616966 -226.391829)
		(end 127.429768 -226.341686)
		(width 0.088646)
		(layer "In11.Cu")
		(net "M_H_CPU1_SB_DQ<28>")
	)
	(arc
		(start 136.357868 -225.527616)
		(mid 136.075166 -225.451874)
		(end 135.792464 -225.527616)
		(width 0.088646)
		(layer "In11.Cu")
		(net "M_H_CPU1_SB_DQ<28>")
	)
	(arc
		(start 128.369568 -226.341686)
		(mid 128.086866 -226.26591)
		(end 127.804164 -226.341686)
		(width 0.088646)
		(layer "In11.Cu")
		(net "M_H_CPU1_SB_DQ<28>")
	)
	(arc
		(start 138.894312 -223.824292)
		(mid 138.495019 -223.99)
		(end 138.32967 -224.389442)
		(width 0.088646)
		(layer "In11.Cu")
		(net "M_H_CPU1_SB_DQ<28>")
	)
	(arc
		(start 136.732264 -225.527616)
		(mid 136.545066 -225.577759)
		(end 136.357868 -225.527616)
		(width 0.088646)
		(layer "In11.Cu")
		(net "M_H_CPU1_SB_DQ<28>")
	)
	(arc
		(start 138.329416 -224.389442)
		(mid 138.281737 -224.572342)
		(end 138.150854 -224.70872)
		(width 0.088646)
		(layer "In11.Cu")
		(net "M_H_CPU1_SB_DQ<28>")
	)
	(arc
		(start 137.297668 -225.527616)
		(mid 137.014966 -225.451874)
		(end 136.732264 -225.527616)
		(width 0.088646)
		(layer "In11.Cu")
		(net "M_H_CPU1_SB_DQ<28>")
	)
	(arc
		(start 135.322564 -226.341686)
		(mid 135.135366 -226.391829)
		(end 134.948168 -226.341686)
		(width 0.088646)
		(layer "In11.Cu")
		(net "M_H_CPU1_SB_DQ<28>")
	)
	(arc
		(start 126.489968 -226.341686)
		(mid 126.215769 -226.265851)
		(end 125.939296 -226.33305)
		(width 0.088646)
		(layer "In11.Cu")
		(net "M_H_CPU1_SB_DQ<28>")
	)
	(arc
		(start 127.429768 -226.341686)
		(mid 127.147066 -226.26591)
		(end 126.864364 -226.341686)
		(width 0.088646)
		(layer "In11.Cu")
		(net "M_H_CPU1_SB_DQ<28>")
	)
	(arc
		(start 128.743964 -226.341686)
		(mid 128.556766 -226.391829)
		(end 128.369568 -226.341686)
		(width 0.088646)
		(layer "In11.Cu")
		(net "M_H_CPU1_SB_DQ<28>")
	)
	(arc
		(start 133.068568 -226.341686)
		(mid 132.794369 -226.265851)
		(end 132.517896 -226.33305)
		(width 0.088646)
		(layer "In11.Cu")
		(net "M_H_CPU1_SB_DQ<28>")
	)
	(arc
		(start 133.442964 -226.341686)
		(mid 133.255766 -226.391829)
		(end 133.068568 -226.341686)
		(width 0.088646)
		(layer "In11.Cu")
		(net "M_H_CPU1_SB_DQ<28>")
	)
	(arc
		(start 135.510016 -226.017328)
		(mid 135.462337 -226.200228)
		(end 135.331454 -226.336606)
		(width 0.088646)
		(layer "In11.Cu")
		(net "M_H_CPU1_SB_DQ<28>")
	)
	(arc
		(start 131.563364 -226.341686)
		(mid 131.376166 -226.391829)
		(end 131.188968 -226.341686)
		(width 0.088646)
		(layer "In11.Cu")
		(net "M_H_CPU1_SB_DQ<28>")
	)
	(segment
		(start 213.515448 -201.549)
		(end 213.749636 -201.314812)
		(width 0.20066)
		(layer "F.Cu")
		(net "M_H_CPU1_SB_DQ<27>")
	)
	(segment
		(start 210.610196 -201.991722)
		(end 212.618066 -201.991722)
		(width 0.1016)
		(layer "F.Cu")
		(net "M_H_CPU1_SB_DQ<27>")
	)
	(segment
		(start 210.603084 -201.998834)
		(end 210.610196 -201.991722)
		(width 0.1016)
		(layer "F.Cu")
		(net "M_H_CPU1_SB_DQ<27>")
	)
	(segment
		(start 212.618066 -201.991722)
		(end 212.630258 -202.003914)
		(width 0.1016)
		(layer "F.Cu")
		(net "M_H_CPU1_SB_DQ<27>")
	)
	(segment
		(start 210.598258 -201.998834)
		(end 210.603084 -201.998834)
		(width 0.101854)
		(layer "F.Cu")
		(net "M_H_CPU1_SB_DQ<27>")
	)
	(segment
		(start 213.515448 -201.799952)
		(end 213.515448 -201.549)
		(width 0.20066)
		(layer "F.Cu")
		(net "M_H_CPU1_SB_DQ<27>")
	)
	(segment
		(start 213.749636 -201.314812)
		(end 214.133684 -201.314812)
		(width 0.20066)
		(layer "F.Cu")
		(net "M_H_CPU1_SB_DQ<27>")
	)
	(segment
		(start 125.267466 -228.99497)
		(end 125.267212 -228.994716)
		(width 0.20066)
		(layer "F.Cu")
		(net "M_H_CPU1_SB_DQ<27>")
	)
	(segment
		(start 208.176114 -201.56678)
		(end 209.874358 -201.56678)
		(width 0.20066)
		(layer "F.Cu")
		(net "M_H_CPU1_SB_DQ<27>")
	)
	(segment
		(start 125.267212 -228.994716)
		(end 125.267212 -228.45903)
		(width 0.20066)
		(layer "F.Cu")
		(net "M_H_CPU1_SB_DQ<27>")
	)
	(segment
		(start 213.311486 -202.003914)
		(end 213.515448 -201.799952)
		(width 0.20066)
		(layer "F.Cu")
		(net "M_H_CPU1_SB_DQ<27>")
	)
	(segment
		(start 212.630258 -202.003914)
		(end 213.311486 -202.003914)
		(width 0.20066)
		(layer "F.Cu")
		(net "M_H_CPU1_SB_DQ<27>")
	)
	(segment
		(start 210.306412 -201.998834)
		(end 210.598258 -201.998834)
		(width 0.20066)
		(layer "F.Cu")
		(net "M_H_CPU1_SB_DQ<27>")
	)
	(segment
		(start 209.874358 -201.56678)
		(end 210.306412 -201.998834)
		(width 0.20066)
		(layer "F.Cu")
		(net "M_H_CPU1_SB_DQ<27>")
	)
	(segment
		(start 207.071214 -201.56678)
		(end 208.176114 -201.56678)
		(width 0.20066)
		(layer "F.Cu")
		(net "M_H_CPU1_SB_DQ<27>")
	)
	(segment
		(start 214.133684 -201.314812)
		(end 214.385652 -201.56678)
		(width 0.20066)
		(layer "F.Cu")
		(net "M_H_CPU1_SB_DQ<27>")
	)
	(segment
		(start 214.385652 -201.56678)
		(end 215.719914 -201.56678)
		(width 0.20066)
		(layer "F.Cu")
		(net "M_H_CPU1_SB_DQ<27>")
	)
	(segment
		(start 173.93539 -202.93457)
		(end 173.74235 -203.12761)
		(width 0.18288)
		(layer "In11.Cu")
		(net "M_H_CPU1_SB_DQ<27>")
	)
	(segment
		(start 204.989176 -202.110086)
		(end 203.407518 -203.691744)
		(width 0.18288)
		(layer "In11.Cu")
		(net "M_H_CPU1_SB_DQ<27>")
	)
	(segment
		(start 176.84369 -203.690728)
		(end 175.972724 -203.690728)
		(width 0.18288)
		(layer "In11.Cu")
		(net "M_H_CPU1_SB_DQ<27>")
	)
	(segment
		(start 186.19724 -203.55306)
		(end 186.0042 -203.7461)
		(width 0.18288)
		(layer "In11.Cu")
		(net "M_H_CPU1_SB_DQ<27>")
	)
	(segment
		(start 203.146406 -203.691744)
		(end 203.097638 -203.69149)
		(width 0.18288)
		(layer "In11.Cu")
		(net "M_H_CPU1_SB_DQ<27>")
	)
	(segment
		(start 188.97473 -203.690982)
		(end 187.307982 -203.690982)
		(width 0.18288)
		(layer "In11.Cu")
		(net "M_H_CPU1_SB_DQ<27>")
	)
	(segment
		(start 176.940718 -203.69149)
		(end 176.844198 -203.691236)
		(width 0.18288)
		(layer "In11.Cu")
		(net "M_H_CPU1_SB_DQ<27>")
	)
	(segment
		(start 172.144182 -203.690982)
		(end 171.962064 -203.508864)
		(width 0.18288)
		(layer "In11.Cu")
		(net "M_H_CPU1_SB_DQ<27>")
	)
	(segment
		(start 125.924564 -228.948488)
		(end 125.912372 -228.941376)
		(width 0.088646)
		(layer "In11.Cu")
		(net "M_H_CPU1_SB_DQ<27>")
	)
	(segment
		(start 192.562226 -203.585826)
		(end 192.45707 -203.690982)
		(width 0.18288)
		(layer "In11.Cu")
		(net "M_H_CPU1_SB_DQ<27>")
	)
	(segment
		(start 200.994518 -203.67879)
		(end 200.994518 -203.940156)
		(width 0.18288)
		(layer "In11.Cu")
		(net "M_H_CPU1_SB_DQ<27>")
	)
	(segment
		(start 196.837554 -202.814682)
		(end 196.520054 -202.814682)
		(width 0.18288)
		(layer "In11.Cu")
		(net "M_H_CPU1_SB_DQ<27>")
	)
	(segment
		(start 182.770018 -203.814426)
		(end 179.506626 -203.814426)
		(width 0.18288)
		(layer "In11.Cu")
		(net "M_H_CPU1_SB_DQ<27>")
	)
	(segment
		(start 189.161928 -203.87818)
		(end 188.97473 -203.690982)
		(width 0.18288)
		(layer "In11.Cu")
		(net "M_H_CPU1_SB_DQ<27>")
	)
	(segment
		(start 139.395454 -227.493068)
		(end 138.80465 -228.083872)
		(width 0.088646)
		(layer "In11.Cu")
		(net "M_H_CPU1_SB_DQ<27>")
	)
	(segment
		(start 177.550826 -203.636626)
		(end 177.495962 -203.69149)
		(width 0.18288)
		(layer "In11.Cu")
		(net "M_H_CPU1_SB_DQ<27>")
	)
	(segment
		(start 149.270466 -213.729824)
		(end 149.270466 -216.297256)
		(width 0.18288)
		(layer "In11.Cu")
		(net "M_H_CPU1_SB_DQ<27>")
	)
	(segment
		(start 131.578096 -228.957124)
		(end 131.563364 -228.948488)
		(width 0.088646)
		(layer "In11.Cu")
		(net "M_H_CPU1_SB_DQ<27>")
	)
	(segment
		(start 196.133974 -203.865226)
		(end 194.924426 -203.865226)
		(width 0.18288)
		(layer "In11.Cu")
		(net "M_H_CPU1_SB_DQ<27>")
	)
	(segment
		(start 205.581504 -202.109832)
		(end 204.989176 -202.110086)
		(width 0.18288)
		(layer "In11.Cu")
		(net "M_H_CPU1_SB_DQ<27>")
	)
	(segment
		(start 207.071214 -201.56678)
		(end 206.124556 -201.56678)
		(width 0.18288)
		(layer "In11.Cu")
		(net "M_H_CPU1_SB_DQ<27>")
	)
	(segment
		(start 173.54931 -203.822554)
		(end 173.276006 -203.822554)
		(width 0.18288)
		(layer "In11.Cu")
		(net "M_H_CPU1_SB_DQ<27>")
	)
	(segment
		(start 171.962064 -203.508864)
		(end 168.788588 -203.508864)
		(width 0.18288)
		(layer "In11.Cu")
		(net "M_H_CPU1_SB_DQ<27>")
	)
	(segment
		(start 198.048626 -203.865226)
		(end 197.223634 -203.865226)
		(width 0.18288)
		(layer "In11.Cu")
		(net "M_H_CPU1_SB_DQ<27>")
	)
	(segment
		(start 160.405826 -203.890626)
		(end 158.634684 -203.890626)
		(width 0.18288)
		(layer "In11.Cu")
		(net "M_H_CPU1_SB_DQ<27>")
	)
	(segment
		(start 179.506626 -203.814426)
		(end 179.328826 -203.636626)
		(width 0.18288)
		(layer "In11.Cu")
		(net "M_H_CPU1_SB_DQ<27>")
	)
	(segment
		(start 168.788588 -203.508864)
		(end 168.508426 -203.789026)
		(width 0.18288)
		(layer "In11.Cu")
		(net "M_H_CPU1_SB_DQ<27>")
	)
	(segment
		(start 194.924426 -203.865226)
		(end 194.645026 -203.585826)
		(width 0.18288)
		(layer "In11.Cu")
		(net "M_H_CPU1_SB_DQ<27>")
	)
	(segment
		(start 203.407518 -203.691744)
		(end 203.146406 -203.691744)
		(width 0.18288)
		(layer "In11.Cu")
		(net "M_H_CPU1_SB_DQ<27>")
	)
	(segment
		(start 137.297668 -228.134672)
		(end 137.288778 -228.139752)
		(width 0.088646)
		(layer "In11.Cu")
		(net "M_H_CPU1_SB_DQ<27>")
	)
	(segment
		(start 128.754378 -228.954584)
		(end 128.743964 -228.948488)
		(width 0.088646)
		(layer "In11.Cu")
		(net "M_H_CPU1_SB_DQ<27>")
	)
	(segment
		(start 185.30316 -203.7461)
		(end 185.11012 -203.55306)
		(width 0.18288)
		(layer "In11.Cu")
		(net "M_H_CPU1_SB_DQ<27>")
	)
	(segment
		(start 174.63897 -203.858368)
		(end 174.44593 -203.665328)
		(width 0.18288)
		(layer "In11.Cu")
		(net "M_H_CPU1_SB_DQ<27>")
	)
	(segment
		(start 185.11012 -203.55306)
		(end 183.031384 -203.55306)
		(width 0.18288)
		(layer "In11.Cu")
		(net "M_H_CPU1_SB_DQ<27>")
	)
	(segment
		(start 142.547848 -224.0407)
		(end 140.435838 -226.15271)
		(width 0.18288)
		(layer "In11.Cu")
		(net "M_H_CPU1_SB_DQ<27>")
	)
	(segment
		(start 198.428102 -203.48575)
		(end 198.048626 -203.865226)
		(width 0.18288)
		(layer "In11.Cu")
		(net "M_H_CPU1_SB_DQ<27>")
	)
	(segment
		(start 158.127954 -204.872336)
		(end 149.270466 -213.729824)
		(width 0.18288)
		(layer "In11.Cu")
		(net "M_H_CPU1_SB_DQ<27>")
	)
	(segment
		(start 185.4962 -204.195426)
		(end 185.30316 -204.002386)
		(width 0.18288)
		(layer "In11.Cu")
		(net "M_H_CPU1_SB_DQ<27>")
	)
	(segment
		(start 173.276006 -203.822554)
		(end 173.144434 -203.690982)
		(width 0.18288)
		(layer "In11.Cu")
		(net "M_H_CPU1_SB_DQ<27>")
	)
	(segment
		(start 174.216568 -202.93457)
		(end 173.93539 -202.93457)
		(width 0.18288)
		(layer "In11.Cu")
		(net "M_H_CPU1_SB_DQ<27>")
	)
	(segment
		(start 173.74235 -203.629514)
		(end 173.54931 -203.822554)
		(width 0.18288)
		(layer "In11.Cu")
		(net "M_H_CPU1_SB_DQ<27>")
	)
	(segment
		(start 140.435838 -226.15271)
		(end 140.072618 -226.51593)
		(width 0.088646)
		(layer "In11.Cu")
		(net "M_H_CPU1_SB_DQ<27>")
	)
	(segment
		(start 129.693924 -228.954584)
		(end 129.68351 -228.948488)
		(width 0.088646)
		(layer "In11.Cu")
		(net "M_H_CPU1_SB_DQ<27>")
	)
	(segment
		(start 202.80503 -203.691744)
		(end 202.647296 -203.691744)
		(width 0.18288)
		(layer "In11.Cu")
		(net "M_H_CPU1_SB_DQ<27>")
	)
	(segment
		(start 166.04488 -203.54925)
		(end 165.805104 -203.789026)
		(width 0.18288)
		(layer "In11.Cu")
		(net "M_H_CPU1_SB_DQ<27>")
	)
	(segment
		(start 185.81116 -204.195426)
		(end 185.4962 -204.195426)
		(width 0.18288)
		(layer "In11.Cu")
		(net "M_H_CPU1_SB_DQ<27>")
	)
	(segment
		(start 185.30316 -204.002386)
		(end 185.30316 -203.7461)
		(width 0.18288)
		(layer "In11.Cu")
		(net "M_H_CPU1_SB_DQ<27>")
	)
	(segment
		(start 175.805084 -203.858368)
		(end 174.63897 -203.858368)
		(width 0.18288)
		(layer "In11.Cu")
		(net "M_H_CPU1_SB_DQ<27>")
	)
	(segment
		(start 201.187558 -203.48575)
		(end 200.994518 -203.67879)
		(width 0.18288)
		(layer "In11.Cu")
		(net "M_H_CPU1_SB_DQ<27>")
	)
	(segment
		(start 190.57747 -203.690982)
		(end 190.390272 -203.87818)
		(width 0.18288)
		(layer "In11.Cu")
		(net "M_H_CPU1_SB_DQ<27>")
	)
	(segment
		(start 203.097638 -203.69149)
		(end 202.82154 -203.690728)
		(width 0.18288)
		(layer "In11.Cu")
		(net "M_H_CPU1_SB_DQ<27>")
	)
	(segment
		(start 200.290938 -203.67879)
		(end 200.097898 -203.48575)
		(width 0.18288)
		(layer "In11.Cu")
		(net "M_H_CPU1_SB_DQ<27>")
	)
	(segment
		(start 137.110216 -228.45903)
		(end 137.110216 -228.468936)
		(width 0.088646)
		(layer "In11.Cu")
		(net "M_H_CPU1_SB_DQ<27>")
	)
	(segment
		(start 186.0042 -203.7461)
		(end 186.0042 -204.002386)
		(width 0.18288)
		(layer "In11.Cu")
		(net "M_H_CPU1_SB_DQ<27>")
	)
	(segment
		(start 174.44593 -203.163932)
		(end 174.216568 -202.93457)
		(width 0.18288)
		(layer "In11.Cu")
		(net "M_H_CPU1_SB_DQ<27>")
	)
	(segment
		(start 126.879096 -228.957124)
		(end 126.864364 -228.948488)
		(width 0.088646)
		(layer "In11.Cu")
		(net "M_H_CPU1_SB_DQ<27>")
	)
	(segment
		(start 173.74235 -203.12761)
		(end 173.74235 -203.629514)
		(width 0.18288)
		(layer "In11.Cu")
		(net "M_H_CPU1_SB_DQ<27>")
	)
	(segment
		(start 202.441302 -203.48575)
		(end 201.187558 -203.48575)
		(width 0.18288)
		(layer "In11.Cu")
		(net "M_H_CPU1_SB_DQ<27>")
	)
	(segment
		(start 200.097898 -203.48575)
		(end 198.428102 -203.48575)
		(width 0.18288)
		(layer "In11.Cu")
		(net "M_H_CPU1_SB_DQ<27>")
	)
	(segment
		(start 179.328826 -203.636626)
		(end 177.550826 -203.636626)
		(width 0.18288)
		(layer "In11.Cu")
		(net "M_H_CPU1_SB_DQ<27>")
	)
	(segment
		(start 174.44593 -203.665328)
		(end 174.44593 -203.163932)
		(width 0.18288)
		(layer "In11.Cu")
		(net "M_H_CPU1_SB_DQ<27>")
	)
	(segment
		(start 196.327014 -203.007722)
		(end 196.327014 -203.672186)
		(width 0.18288)
		(layer "In11.Cu")
		(net "M_H_CPU1_SB_DQ<27>")
	)
	(segment
		(start 173.144434 -203.690982)
		(end 172.144182 -203.690982)
		(width 0.18288)
		(layer "In11.Cu")
		(net "M_H_CPU1_SB_DQ<27>")
	)
	(segment
		(start 206.124556 -201.56678)
		(end 205.581504 -202.109832)
		(width 0.18288)
		(layer "In11.Cu")
		(net "M_H_CPU1_SB_DQ<27>")
	)
	(segment
		(start 200.994518 -203.940156)
		(end 200.801478 -204.133196)
		(width 0.18288)
		(layer "In11.Cu")
		(net "M_H_CPU1_SB_DQ<27>")
	)
	(segment
		(start 158.127954 -204.397356)
		(end 158.127954 -204.872336)
		(width 0.18288)
		(layer "In11.Cu")
		(net "M_H_CPU1_SB_DQ<27>")
	)
	(segment
		(start 127.818896 -228.957124)
		(end 127.804164 -228.948488)
		(width 0.088646)
		(layer "In11.Cu")
		(net "M_H_CPU1_SB_DQ<27>")
	)
	(segment
		(start 196.520054 -202.814682)
		(end 196.327014 -203.007722)
		(width 0.18288)
		(layer "In11.Cu")
		(net "M_H_CPU1_SB_DQ<27>")
	)
	(segment
		(start 175.972724 -203.690728)
		(end 175.805084 -203.858368)
		(width 0.18288)
		(layer "In11.Cu")
		(net "M_H_CPU1_SB_DQ<27>")
	)
	(segment
		(start 140.072618 -226.51593)
		(end 139.756642 -226.51593)
		(width 0.088646)
		(layer "In11.Cu")
		(net "M_H_CPU1_SB_DQ<27>")
	)
	(segment
		(start 177.495962 -203.69149)
		(end 176.940718 -203.69149)
		(width 0.18288)
		(layer "In11.Cu")
		(net "M_H_CPU1_SB_DQ<27>")
	)
	(segment
		(start 166.473124 -203.54925)
		(end 166.04488 -203.54925)
		(width 0.18288)
		(layer "In11.Cu")
		(net "M_H_CPU1_SB_DQ<27>")
	)
	(segment
		(start 186.0042 -204.002386)
		(end 185.81116 -204.195426)
		(width 0.18288)
		(layer "In11.Cu")
		(net "M_H_CPU1_SB_DQ<27>")
	)
	(segment
		(start 194.645026 -203.585826)
		(end 192.562226 -203.585826)
		(width 0.18288)
		(layer "In11.Cu")
		(net "M_H_CPU1_SB_DQ<27>")
	)
	(segment
		(start 187.17006 -203.55306)
		(end 186.19724 -203.55306)
		(width 0.18288)
		(layer "In11.Cu")
		(net "M_H_CPU1_SB_DQ<27>")
	)
	(segment
		(start 197.223634 -203.865226)
		(end 197.030594 -203.672186)
		(width 0.18288)
		(layer "In11.Cu")
		(net "M_H_CPU1_SB_DQ<27>")
	)
	(segment
		(start 158.634684 -203.890626)
		(end 158.127954 -204.397356)
		(width 0.18288)
		(layer "In11.Cu")
		(net "M_H_CPU1_SB_DQ<27>")
	)
	(segment
		(start 183.031384 -203.55306)
		(end 182.770018 -203.814426)
		(width 0.18288)
		(layer "In11.Cu")
		(net "M_H_CPU1_SB_DQ<27>")
	)
	(segment
		(start 200.801478 -204.133196)
		(end 200.483978 -204.133196)
		(width 0.18288)
		(layer "In11.Cu")
		(net "M_H_CPU1_SB_DQ<27>")
	)
	(segment
		(start 149.270466 -216.297256)
		(end 142.547848 -223.019874)
		(width 0.18288)
		(layer "In11.Cu")
		(net "M_H_CPU1_SB_DQ<27>")
	)
	(segment
		(start 142.547848 -223.019874)
		(end 142.547848 -224.0407)
		(width 0.18288)
		(layer "In11.Cu")
		(net "M_H_CPU1_SB_DQ<27>")
	)
	(segment
		(start 200.483978 -204.133196)
		(end 200.290938 -203.940156)
		(width 0.18288)
		(layer "In11.Cu")
		(net "M_H_CPU1_SB_DQ<27>")
	)
	(segment
		(start 160.659826 -203.636626)
		(end 160.405826 -203.890626)
		(width 0.18288)
		(layer "In11.Cu")
		(net "M_H_CPU1_SB_DQ<27>")
	)
	(segment
		(start 202.806046 -203.690728)
		(end 202.80503 -203.691744)
		(width 0.18288)
		(layer "In11.Cu")
		(net "M_H_CPU1_SB_DQ<27>")
	)
	(segment
		(start 202.647296 -203.691744)
		(end 202.441302 -203.48575)
		(width 0.18288)
		(layer "In11.Cu")
		(net "M_H_CPU1_SB_DQ<27>")
	)
	(segment
		(start 138.80465 -228.083872)
		(end 138.424666 -228.083872)
		(width 0.088646)
		(layer "In11.Cu")
		(net "M_H_CPU1_SB_DQ<27>")
	)
	(segment
		(start 139.756642 -226.51593)
		(end 139.395454 -226.877118)
		(width 0.088646)
		(layer "In11.Cu")
		(net "M_H_CPU1_SB_DQ<27>")
	)
	(segment
		(start 176.844198 -203.691236)
		(end 176.84369 -203.690728)
		(width 0.18288)
		(layer "In11.Cu")
		(net "M_H_CPU1_SB_DQ<27>")
	)
	(segment
		(start 166.7129 -203.789026)
		(end 166.473124 -203.54925)
		(width 0.18288)
		(layer "In11.Cu")
		(net "M_H_CPU1_SB_DQ<27>")
	)
	(segment
		(start 139.395454 -226.877118)
		(end 139.395454 -227.493068)
		(width 0.088646)
		(layer "In11.Cu")
		(net "M_H_CPU1_SB_DQ<27>")
	)
	(segment
		(start 202.82154 -203.690728)
		(end 202.806046 -203.690728)
		(width 0.18288)
		(layer "In11.Cu")
		(net "M_H_CPU1_SB_DQ<27>")
	)
	(segment
		(start 164.469826 -203.636626)
		(end 160.659826 -203.636626)
		(width 0.18288)
		(layer "In11.Cu")
		(net "M_H_CPU1_SB_DQ<27>")
	)
	(segment
		(start 130.638296 -228.957124)
		(end 130.623564 -228.948488)
		(width 0.088646)
		(layer "In11.Cu")
		(net "M_H_CPU1_SB_DQ<27>")
	)
	(segment
		(start 197.030594 -203.672186)
		(end 197.030594 -203.007722)
		(width 0.18288)
		(layer "In11.Cu")
		(net "M_H_CPU1_SB_DQ<27>")
	)
	(segment
		(start 165.805104 -203.789026)
		(end 164.622226 -203.789026)
		(width 0.18288)
		(layer "In11.Cu")
		(net "M_H_CPU1_SB_DQ<27>")
	)
	(segment
		(start 187.307982 -203.690982)
		(end 187.17006 -203.55306)
		(width 0.18288)
		(layer "In11.Cu")
		(net "M_H_CPU1_SB_DQ<27>")
	)
	(segment
		(start 196.327014 -203.672186)
		(end 196.133974 -203.865226)
		(width 0.18288)
		(layer "In11.Cu")
		(net "M_H_CPU1_SB_DQ<27>")
	)
	(segment
		(start 134.397496 -228.957124)
		(end 134.382764 -228.948488)
		(width 0.088646)
		(layer "In11.Cu")
		(net "M_H_CPU1_SB_DQ<27>")
	)
	(segment
		(start 192.45707 -203.690982)
		(end 190.57747 -203.690982)
		(width 0.18288)
		(layer "In11.Cu")
		(net "M_H_CPU1_SB_DQ<27>")
	)
	(segment
		(start 200.290938 -203.940156)
		(end 200.290938 -203.67879)
		(width 0.18288)
		(layer "In11.Cu")
		(net "M_H_CPU1_SB_DQ<27>")
	)
	(segment
		(start 164.622226 -203.789026)
		(end 164.469826 -203.636626)
		(width 0.18288)
		(layer "In11.Cu")
		(net "M_H_CPU1_SB_DQ<27>")
	)
	(segment
		(start 168.508426 -203.789026)
		(end 166.7129 -203.789026)
		(width 0.18288)
		(layer "In11.Cu")
		(net "M_H_CPU1_SB_DQ<27>")
	)
	(segment
		(start 197.030594 -203.007722)
		(end 196.837554 -202.814682)
		(width 0.18288)
		(layer "In11.Cu")
		(net "M_H_CPU1_SB_DQ<27>")
	)
	(segment
		(start 190.390272 -203.87818)
		(end 189.161928 -203.87818)
		(width 0.18288)
		(layer "In11.Cu")
		(net "M_H_CPU1_SB_DQ<27>")
	)
	(arc
		(start 127.804164 -228.948488)
		(mid 127.616966 -228.898345)
		(end 127.429768 -228.948488)
		(width 0.088646)
		(layer "In11.Cu")
		(net "M_H_CPU1_SB_DQ<27>")
	)
	(arc
		(start 127.429768 -228.948488)
		(mid 127.155569 -229.024323)
		(end 126.879096 -228.957124)
		(width 0.088646)
		(layer "In11.Cu")
		(net "M_H_CPU1_SB_DQ<27>")
	)
	(arc
		(start 135.887968 -228.948488)
		(mid 135.605266 -229.024264)
		(end 135.322564 -228.948488)
		(width 0.088646)
		(layer "In11.Cu")
		(net "M_H_CPU1_SB_DQ<27>")
	)
	(arc
		(start 137.110216 -228.468936)
		(mid 137.032105 -228.745885)
		(end 136.827768 -228.948488)
		(width 0.088646)
		(layer "In11.Cu")
		(net "M_H_CPU1_SB_DQ<27>")
	)
	(arc
		(start 138.424666 -228.083872)
		(mid 138.327727 -228.096962)
		(end 138.237468 -228.134672)
		(width 0.088646)
		(layer "In11.Cu")
		(net "M_H_CPU1_SB_DQ<27>")
	)
	(arc
		(start 129.309114 -228.948488)
		(mid 129.032555 -229.024231)
		(end 128.754378 -228.954584)
		(width 0.088646)
		(layer "In11.Cu")
		(net "M_H_CPU1_SB_DQ<27>")
	)
	(arc
		(start 136.262364 -228.948488)
		(mid 136.075166 -228.898345)
		(end 135.887968 -228.948488)
		(width 0.088646)
		(layer "In11.Cu")
		(net "M_H_CPU1_SB_DQ<27>")
	)
	(arc
		(start 128.369568 -228.948488)
		(mid 128.095369 -229.024323)
		(end 127.818896 -228.957124)
		(width 0.088646)
		(layer "In11.Cu")
		(net "M_H_CPU1_SB_DQ<27>")
	)
	(arc
		(start 137.288778 -228.139752)
		(mid 137.157864 -228.276112)
		(end 137.110216 -228.45903)
		(width 0.088646)
		(layer "In11.Cu")
		(net "M_H_CPU1_SB_DQ<27>")
	)
	(arc
		(start 132.503164 -228.948488)
		(mid 132.315966 -228.898345)
		(end 132.128768 -228.948488)
		(width 0.088646)
		(layer "In11.Cu")
		(net "M_H_CPU1_SB_DQ<27>")
	)
	(arc
		(start 132.128768 -228.948488)
		(mid 131.854569 -229.024323)
		(end 131.578096 -228.957124)
		(width 0.088646)
		(layer "In11.Cu")
		(net "M_H_CPU1_SB_DQ<27>")
	)
	(arc
		(start 133.442964 -228.948488)
		(mid 133.255766 -228.898345)
		(end 133.068568 -228.948488)
		(width 0.088646)
		(layer "In11.Cu")
		(net "M_H_CPU1_SB_DQ<27>")
	)
	(arc
		(start 135.322564 -228.948488)
		(mid 135.135366 -228.898345)
		(end 134.948168 -228.948488)
		(width 0.088646)
		(layer "In11.Cu")
		(net "M_H_CPU1_SB_DQ<27>")
	)
	(arc
		(start 130.623564 -228.948488)
		(mid 130.436366 -228.898345)
		(end 130.249168 -228.948488)
		(width 0.088646)
		(layer "In11.Cu")
		(net "M_H_CPU1_SB_DQ<27>")
	)
	(arc
		(start 131.188968 -228.948488)
		(mid 130.914769 -229.024323)
		(end 130.638296 -228.957124)
		(width 0.088646)
		(layer "In11.Cu")
		(net "M_H_CPU1_SB_DQ<27>")
	)
	(arc
		(start 136.827768 -228.948488)
		(mid 136.545066 -229.024264)
		(end 136.262364 -228.948488)
		(width 0.088646)
		(layer "In11.Cu")
		(net "M_H_CPU1_SB_DQ<27>")
	)
	(arc
		(start 133.068568 -228.948488)
		(mid 132.785866 -229.024264)
		(end 132.503164 -228.948488)
		(width 0.088646)
		(layer "In11.Cu")
		(net "M_H_CPU1_SB_DQ<27>")
	)
	(arc
		(start 138.237468 -228.134672)
		(mid 137.954766 -228.210414)
		(end 137.672064 -228.134672)
		(width 0.088646)
		(layer "In11.Cu")
		(net "M_H_CPU1_SB_DQ<27>")
	)
	(arc
		(start 131.563364 -228.948488)
		(mid 131.376166 -228.898345)
		(end 131.188968 -228.948488)
		(width 0.088646)
		(layer "In11.Cu")
		(net "M_H_CPU1_SB_DQ<27>")
	)
	(arc
		(start 134.008368 -228.948488)
		(mid 133.725666 -229.024264)
		(end 133.442964 -228.948488)
		(width 0.088646)
		(layer "In11.Cu")
		(net "M_H_CPU1_SB_DQ<27>")
	)
	(arc
		(start 137.672064 -228.134672)
		(mid 137.484866 -228.084529)
		(end 137.297668 -228.134672)
		(width 0.088646)
		(layer "In11.Cu")
		(net "M_H_CPU1_SB_DQ<27>")
	)
	(arc
		(start 128.743964 -228.948488)
		(mid 128.556766 -228.898345)
		(end 128.369568 -228.948488)
		(width 0.088646)
		(layer "In11.Cu")
		(net "M_H_CPU1_SB_DQ<27>")
	)
	(arc
		(start 134.382764 -228.948488)
		(mid 134.195566 -228.898345)
		(end 134.008368 -228.948488)
		(width 0.088646)
		(layer "In11.Cu")
		(net "M_H_CPU1_SB_DQ<27>")
	)
	(arc
		(start 129.68351 -228.948488)
		(mid 129.496312 -228.898345)
		(end 129.309114 -228.948488)
		(width 0.088646)
		(layer "In11.Cu")
		(net "M_H_CPU1_SB_DQ<27>")
	)
	(arc
		(start 126.489968 -228.948488)
		(mid 126.207266 -229.024264)
		(end 125.924564 -228.948488)
		(width 0.088646)
		(layer "In11.Cu")
		(net "M_H_CPU1_SB_DQ<27>")
	)
	(arc
		(start 134.948168 -228.948488)
		(mid 134.673969 -229.024323)
		(end 134.397496 -228.957124)
		(width 0.088646)
		(layer "In11.Cu")
		(net "M_H_CPU1_SB_DQ<27>")
	)
	(arc
		(start 125.912372 -228.941376)
		(mid 125.576038 -228.718599)
		(end 125.267212 -228.45903)
		(width 0.088646)
		(layer "In11.Cu")
		(net "M_H_CPU1_SB_DQ<27>")
	)
	(arc
		(start 130.249168 -228.948488)
		(mid 129.972355 -229.024358)
		(end 129.693924 -228.954584)
		(width 0.088646)
		(layer "In11.Cu")
		(net "M_H_CPU1_SB_DQ<27>")
	)
	(arc
		(start 126.864364 -228.948488)
		(mid 126.677166 -228.898345)
		(end 126.489968 -228.948488)
		(width 0.088646)
		(layer "In11.Cu")
		(net "M_H_CPU1_SB_DQ<27>")
	)
	(segment
		(start 213.311486 -203.703936)
		(end 213.515448 -203.499974)
		(width 0.20066)
		(layer "F.Cu")
		(net "M_H_CPU1_SB_DQ<26>")
	)
	(segment
		(start 213.515448 -203.249022)
		(end 213.749636 -203.014834)
		(width 0.20066)
		(layer "F.Cu")
		(net "M_H_CPU1_SB_DQ<26>")
	)
	(segment
		(start 213.749636 -203.014834)
		(end 214.133684 -203.014834)
		(width 0.20066)
		(layer "F.Cu")
		(net "M_H_CPU1_SB_DQ<26>")
	)
	(segment
		(start 208.176114 -203.266802)
		(end 209.874358 -203.266802)
		(width 0.20066)
		(layer "F.Cu")
		(net "M_H_CPU1_SB_DQ<26>")
	)
	(segment
		(start 210.598258 -203.698856)
		(end 210.603084 -203.698856)
		(width 0.101854)
		(layer "F.Cu")
		(net "M_H_CPU1_SB_DQ<26>")
	)
	(segment
		(start 210.603084 -203.698856)
		(end 210.610196 -203.691744)
		(width 0.1016)
		(layer "F.Cu")
		(net "M_H_CPU1_SB_DQ<26>")
	)
	(segment
		(start 212.618066 -203.691744)
		(end 212.630258 -203.703936)
		(width 0.1016)
		(layer "F.Cu")
		(net "M_H_CPU1_SB_DQ<26>")
	)
	(segment
		(start 214.133684 -203.014834)
		(end 214.385652 -203.266802)
		(width 0.20066)
		(layer "F.Cu")
		(net "M_H_CPU1_SB_DQ<26>")
	)
	(segment
		(start 124.797566 -229.808532)
		(end 124.797566 -229.272846)
		(width 0.20066)
		(layer "F.Cu")
		(net "M_H_CPU1_SB_DQ<26>")
	)
	(segment
		(start 212.630258 -203.703936)
		(end 213.311486 -203.703936)
		(width 0.20066)
		(layer "F.Cu")
		(net "M_H_CPU1_SB_DQ<26>")
	)
	(segment
		(start 209.874358 -203.266802)
		(end 210.306412 -203.698856)
		(width 0.20066)
		(layer "F.Cu")
		(net "M_H_CPU1_SB_DQ<26>")
	)
	(segment
		(start 213.515448 -203.499974)
		(end 213.515448 -203.249022)
		(width 0.20066)
		(layer "F.Cu")
		(net "M_H_CPU1_SB_DQ<26>")
	)
	(segment
		(start 210.610196 -203.691744)
		(end 212.618066 -203.691744)
		(width 0.1016)
		(layer "F.Cu")
		(net "M_H_CPU1_SB_DQ<26>")
	)
	(segment
		(start 207.071214 -203.266802)
		(end 208.176114 -203.266802)
		(width 0.20066)
		(layer "F.Cu")
		(net "M_H_CPU1_SB_DQ<26>")
	)
	(segment
		(start 210.306412 -203.698856)
		(end 210.598258 -203.698856)
		(width 0.20066)
		(layer "F.Cu")
		(net "M_H_CPU1_SB_DQ<26>")
	)
	(segment
		(start 124.797312 -229.808786)
		(end 124.797566 -229.808532)
		(width 0.20066)
		(layer "F.Cu")
		(net "M_H_CPU1_SB_DQ<26>")
	)
	(segment
		(start 214.385652 -203.266802)
		(end 215.719914 -203.266802)
		(width 0.20066)
		(layer "F.Cu")
		(net "M_H_CPU1_SB_DQ<26>")
	)
	(segment
		(start 157.669738 -207.854042)
		(end 157.037278 -207.854042)
		(width 0.18288)
		(layer "In11.Cu")
		(net "M_H_CPU1_SB_DQ<26>")
	)
	(segment
		(start 139.817602 -227.425504)
		(end 139.817602 -227.69068)
		(width 0.088646)
		(layer "In11.Cu")
		(net "M_H_CPU1_SB_DQ<26>")
	)
	(segment
		(start 188.628782 -205.39456)
		(end 187.943998 -205.393798)
		(width 0.18288)
		(layer "In11.Cu")
		(net "M_H_CPU1_SB_DQ<26>")
	)
	(segment
		(start 183.233568 -205.225904)
		(end 182.816246 -205.643226)
		(width 0.18288)
		(layer "In11.Cu")
		(net "M_H_CPU1_SB_DQ<26>")
	)
	(segment
		(start 164.393626 -205.236826)
		(end 161.142426 -205.236826)
		(width 0.18288)
		(layer "In11.Cu")
		(net "M_H_CPU1_SB_DQ<26>")
	)
	(segment
		(start 157.037278 -207.854042)
		(end 150.59279 -214.29853)
		(width 0.18288)
		(layer "In11.Cu")
		(net "M_H_CPU1_SB_DQ<26>")
	)
	(segment
		(start 161.142426 -205.236826)
		(end 160.676336 -205.702916)
		(width 0.18288)
		(layer "In11.Cu")
		(net "M_H_CPU1_SB_DQ<26>")
	)
	(segment
		(start 193.471038 -205.336394)
		(end 193.412872 -205.39456)
		(width 0.18288)
		(layer "In11.Cu")
		(net "M_H_CPU1_SB_DQ<26>")
	)
	(segment
		(start 196.165216 -206.743808)
		(end 196.165216 -205.734666)
		(width 0.18288)
		(layer "In11.Cu")
		(net "M_H_CPU1_SB_DQ<26>")
	)
	(segment
		(start 177.173636 -205.390496)
		(end 176.945798 -205.391004)
		(width 0.18288)
		(layer "In11.Cu")
		(net "M_H_CPU1_SB_DQ<26>")
	)
	(segment
		(start 150.59279 -214.29853)
		(end 150.59279 -216.432892)
		(width 0.18288)
		(layer "In11.Cu")
		(net "M_H_CPU1_SB_DQ<26>")
	)
	(segment
		(start 177.327306 -205.236826)
		(end 177.173636 -205.390496)
		(width 0.18288)
		(layer "In11.Cu")
		(net "M_H_CPU1_SB_DQ<26>")
	)
	(segment
		(start 200.385934 -207.09001)
		(end 200.192894 -206.89697)
		(width 0.18288)
		(layer "In11.Cu")
		(net "M_H_CPU1_SB_DQ<26>")
	)
	(segment
		(start 143.661384 -223.364298)
		(end 143.661384 -224.404682)
		(width 0.18288)
		(layer "In11.Cu")
		(net "M_H_CPU1_SB_DQ<26>")
	)
	(segment
		(start 164.749226 -205.592426)
		(end 164.393626 -205.236826)
		(width 0.18288)
		(layer "In11.Cu")
		(net "M_H_CPU1_SB_DQ<26>")
	)
	(segment
		(start 182.816246 -205.643226)
		(end 180.141626 -205.643226)
		(width 0.18288)
		(layer "In11.Cu")
		(net "M_H_CPU1_SB_DQ<26>")
	)
	(segment
		(start 201.169016 -205.296262)
		(end 200.896474 -205.568804)
		(width 0.18288)
		(layer "In11.Cu")
		(net "M_H_CPU1_SB_DQ<26>")
	)
	(segment
		(start 199.999854 -205.375764)
		(end 199.254872 -205.375764)
		(width 0.18288)
		(layer "In11.Cu")
		(net "M_H_CPU1_SB_DQ<26>")
	)
	(segment
		(start 196.866256 -206.743808)
		(end 196.673216 -206.936848)
		(width 0.18288)
		(layer "In11.Cu")
		(net "M_H_CPU1_SB_DQ<26>")
	)
	(segment
		(start 131.658868 -229.762304)
		(end 131.648454 -229.7684)
		(width 0.088646)
		(layer "In11.Cu")
		(net "M_H_CPU1_SB_DQ<26>")
	)
	(segment
		(start 168.127426 -205.592426)
		(end 164.749226 -205.592426)
		(width 0.18288)
		(layer "In11.Cu")
		(net "M_H_CPU1_SB_DQ<26>")
	)
	(segment
		(start 198.854314 -205.541626)
		(end 197.059296 -205.541626)
		(width 0.18288)
		(layer "In11.Cu")
		(net "M_H_CPU1_SB_DQ<26>")
	)
	(segment
		(start 187.827412 -205.393798)
		(end 187.827158 -205.393544)
		(width 0.18288)
		(layer "In11.Cu")
		(net "M_H_CPU1_SB_DQ<26>")
	)
	(segment
		(start 180.141626 -205.643226)
		(end 179.735226 -205.236826)
		(width 0.18288)
		(layer "In11.Cu")
		(net "M_H_CPU1_SB_DQ<26>")
	)
	(segment
		(start 187.029598 -205.225904)
		(end 183.233568 -205.225904)
		(width 0.18288)
		(layer "In11.Cu")
		(net "M_H_CPU1_SB_DQ<26>")
	)
	(segment
		(start 207.071214 -203.266802)
		(end 206.21879 -203.266802)
		(width 0.18288)
		(layer "In11.Cu")
		(net "M_H_CPU1_SB_DQ<26>")
	)
	(segment
		(start 204.093318 -205.392274)
		(end 202.212194 -205.392274)
		(width 0.18288)
		(layer "In11.Cu")
		(net "M_H_CPU1_SB_DQ<26>")
	)
	(segment
		(start 202.212194 -205.392274)
		(end 202.116182 -205.296262)
		(width 0.18288)
		(layer "In11.Cu")
		(net "M_H_CPU1_SB_DQ<26>")
	)
	(segment
		(start 127.899414 -229.762304)
		(end 127.884682 -229.77094)
		(width 0.088646)
		(layer "In11.Cu")
		(net "M_H_CPU1_SB_DQ<26>")
	)
	(segment
		(start 196.673216 -206.936848)
		(end 196.358256 -206.936848)
		(width 0.18288)
		(layer "In11.Cu")
		(net "M_H_CPU1_SB_DQ<26>")
	)
	(segment
		(start 139.817602 -227.69068)
		(end 139.203176 -228.305106)
		(width 0.088646)
		(layer "In11.Cu")
		(net "M_H_CPU1_SB_DQ<26>")
	)
	(segment
		(start 128.839214 -229.762304)
		(end 128.824482 -229.77094)
		(width 0.088646)
		(layer "In11.Cu")
		(net "M_H_CPU1_SB_DQ<26>")
	)
	(segment
		(start 150.59279 -216.432892)
		(end 143.661384 -223.364298)
		(width 0.18288)
		(layer "In11.Cu")
		(net "M_H_CPU1_SB_DQ<26>")
	)
	(segment
		(start 133.538468 -229.762304)
		(end 133.528054 -229.7684)
		(width 0.088646)
		(layer "In11.Cu")
		(net "M_H_CPU1_SB_DQ<26>")
	)
	(segment
		(start 175.48225 -205.393036)
		(end 175.28286 -205.592426)
		(width 0.18288)
		(layer "In11.Cu")
		(net "M_H_CPU1_SB_DQ<26>")
	)
	(segment
		(start 196.358256 -206.936848)
		(end 196.165216 -206.743808)
		(width 0.18288)
		(layer "In11.Cu")
		(net "M_H_CPU1_SB_DQ<26>")
	)
	(segment
		(start 140.163042 -227.32873)
		(end 139.914376 -227.32873)
		(width 0.088646)
		(layer "In11.Cu")
		(net "M_H_CPU1_SB_DQ<26>")
	)
	(segment
		(start 194.93611 -205.336394)
		(end 193.471038 -205.336394)
		(width 0.18288)
		(layer "In11.Cu")
		(net "M_H_CPU1_SB_DQ<26>")
	)
	(segment
		(start 139.914376 -227.32873)
		(end 139.817602 -227.425504)
		(width 0.088646)
		(layer "In11.Cu")
		(net "M_H_CPU1_SB_DQ<26>")
	)
	(segment
		(start 130.718814 -229.762304)
		(end 130.704082 -229.77094)
		(width 0.088646)
		(layer "In11.Cu")
		(net "M_H_CPU1_SB_DQ<26>")
	)
	(segment
		(start 140.737336 -227.32873)
		(end 140.163042 -227.32873)
		(width 0.18288)
		(layer "In11.Cu")
		(net "M_H_CPU1_SB_DQ<26>")
	)
	(segment
		(start 179.735226 -205.236826)
		(end 177.327306 -205.236826)
		(width 0.18288)
		(layer "In11.Cu")
		(net "M_H_CPU1_SB_DQ<26>")
	)
	(segment
		(start 176.849278 -205.391004)
		(end 175.48225 -205.393036)
		(width 0.18288)
		(layer "In11.Cu")
		(net "M_H_CPU1_SB_DQ<26>")
	)
	(segment
		(start 200.703434 -207.09001)
		(end 200.385934 -207.09001)
		(width 0.18288)
		(layer "In11.Cu")
		(net "M_H_CPU1_SB_DQ<26>")
	)
	(segment
		(start 187.827158 -205.393544)
		(end 187.197238 -205.393544)
		(width 0.18288)
		(layer "In11.Cu")
		(net "M_H_CPU1_SB_DQ<26>")
	)
	(segment
		(start 196.866256 -205.734666)
		(end 196.866256 -206.743808)
		(width 0.18288)
		(layer "In11.Cu")
		(net "M_H_CPU1_SB_DQ<26>")
	)
	(segment
		(start 187.197238 -205.393544)
		(end 187.029598 -205.225904)
		(width 0.18288)
		(layer "In11.Cu")
		(net "M_H_CPU1_SB_DQ<26>")
	)
	(segment
		(start 132.598414 -229.762304)
		(end 132.588 -229.7684)
		(width 0.088646)
		(layer "In11.Cu")
		(net "M_H_CPU1_SB_DQ<26>")
	)
	(segment
		(start 195.971668 -205.541118)
		(end 195.140834 -205.541118)
		(width 0.18288)
		(layer "In11.Cu")
		(net "M_H_CPU1_SB_DQ<26>")
	)
	(segment
		(start 200.896474 -206.89697)
		(end 200.703434 -207.09001)
		(width 0.18288)
		(layer "In11.Cu")
		(net "M_H_CPU1_SB_DQ<26>")
	)
	(segment
		(start 196.165216 -205.734666)
		(end 195.971668 -205.541118)
		(width 0.18288)
		(layer "In11.Cu")
		(net "M_H_CPU1_SB_DQ<26>")
	)
	(segment
		(start 200.896474 -205.568804)
		(end 200.896474 -206.89697)
		(width 0.18288)
		(layer "In11.Cu")
		(net "M_H_CPU1_SB_DQ<26>")
	)
	(segment
		(start 168.332912 -205.38694)
		(end 168.127426 -205.592426)
		(width 0.18288)
		(layer "In11.Cu")
		(net "M_H_CPU1_SB_DQ<26>")
	)
	(segment
		(start 137.767568 -228.948488)
		(end 137.758678 -228.953568)
		(width 0.088646)
		(layer "In11.Cu")
		(net "M_H_CPU1_SB_DQ<26>")
	)
	(segment
		(start 175.28286 -205.592426)
		(end 173.661578 -205.592426)
		(width 0.18288)
		(layer "In11.Cu")
		(net "M_H_CPU1_SB_DQ<26>")
	)
	(segment
		(start 137.580116 -229.272846)
		(end 137.580116 -229.282752)
		(width 0.088646)
		(layer "In11.Cu")
		(net "M_H_CPU1_SB_DQ<26>")
	)
	(segment
		(start 125.113288 -229.537768)
		(end 124.797566 -229.272846)
		(width 0.088646)
		(layer "In11.Cu")
		(net "M_H_CPU1_SB_DQ<26>")
	)
	(segment
		(start 202.116182 -205.296262)
		(end 201.169016 -205.296262)
		(width 0.18288)
		(layer "In11.Cu")
		(net "M_H_CPU1_SB_DQ<26>")
	)
	(segment
		(start 173.457616 -205.388464)
		(end 172.719238 -205.388464)
		(width 0.18288)
		(layer "In11.Cu")
		(net "M_H_CPU1_SB_DQ<26>")
	)
	(segment
		(start 195.140834 -205.541118)
		(end 194.93611 -205.336394)
		(width 0.18288)
		(layer "In11.Cu")
		(net "M_H_CPU1_SB_DQ<26>")
	)
	(segment
		(start 126.019814 -229.762304)
		(end 126.0094 -229.7684)
		(width 0.088646)
		(layer "In11.Cu")
		(net "M_H_CPU1_SB_DQ<26>")
	)
	(segment
		(start 172.717714 -205.38694)
		(end 168.332912 -205.38694)
		(width 0.18288)
		(layer "In11.Cu")
		(net "M_H_CPU1_SB_DQ<26>")
	)
	(segment
		(start 139.203176 -228.491288)
		(end 138.872722 -228.821742)
		(width 0.088646)
		(layer "In11.Cu")
		(net "M_H_CPU1_SB_DQ<26>")
	)
	(segment
		(start 197.059296 -205.541626)
		(end 196.866256 -205.734666)
		(width 0.18288)
		(layer "In11.Cu")
		(net "M_H_CPU1_SB_DQ<26>")
	)
	(segment
		(start 200.192894 -205.568804)
		(end 199.999854 -205.375764)
		(width 0.18288)
		(layer "In11.Cu")
		(net "M_H_CPU1_SB_DQ<26>")
	)
	(segment
		(start 200.192894 -206.89697)
		(end 200.192894 -205.568804)
		(width 0.18288)
		(layer "In11.Cu")
		(net "M_H_CPU1_SB_DQ<26>")
	)
	(segment
		(start 172.719238 -205.388464)
		(end 172.717714 -205.38694)
		(width 0.18288)
		(layer "In11.Cu")
		(net "M_H_CPU1_SB_DQ<26>")
	)
	(segment
		(start 143.661384 -224.404682)
		(end 140.737336 -227.32873)
		(width 0.18288)
		(layer "In11.Cu")
		(net "M_H_CPU1_SB_DQ<26>")
	)
	(segment
		(start 126.959614 -229.762304)
		(end 126.944882 -229.77094)
		(width 0.088646)
		(layer "In11.Cu")
		(net "M_H_CPU1_SB_DQ<26>")
	)
	(segment
		(start 176.945798 -205.391004)
		(end 176.849278 -205.391004)
		(width 0.18288)
		(layer "In11.Cu")
		(net "M_H_CPU1_SB_DQ<26>")
	)
	(segment
		(start 206.21879 -203.266802)
		(end 204.093318 -205.392274)
		(width 0.18288)
		(layer "In11.Cu")
		(net "M_H_CPU1_SB_DQ<26>")
	)
	(segment
		(start 187.943998 -205.393798)
		(end 187.827412 -205.393798)
		(width 0.18288)
		(layer "In11.Cu")
		(net "M_H_CPU1_SB_DQ<26>")
	)
	(segment
		(start 160.676336 -205.702916)
		(end 159.820864 -205.702916)
		(width 0.18288)
		(layer "In11.Cu")
		(net "M_H_CPU1_SB_DQ<26>")
	)
	(segment
		(start 173.661578 -205.592426)
		(end 173.457616 -205.388464)
		(width 0.18288)
		(layer "In11.Cu")
		(net "M_H_CPU1_SB_DQ<26>")
	)
	(segment
		(start 193.412872 -205.39456)
		(end 188.628782 -205.39456)
		(width 0.18288)
		(layer "In11.Cu")
		(net "M_H_CPU1_SB_DQ<26>")
	)
	(segment
		(start 139.203176 -228.305106)
		(end 139.203176 -228.491288)
		(width 0.088646)
		(layer "In11.Cu")
		(net "M_H_CPU1_SB_DQ<26>")
	)
	(segment
		(start 159.820864 -205.702916)
		(end 157.669738 -207.854042)
		(width 0.18288)
		(layer "In11.Cu")
		(net "M_H_CPU1_SB_DQ<26>")
	)
	(segment
		(start 199.254872 -205.375764)
		(end 198.854314 -205.541626)
		(width 0.18288)
		(layer "In11.Cu")
		(net "M_H_CPU1_SB_DQ<26>")
	)
	(arc
		(start 137.758678 -228.953568)
		(mid 137.627764 -229.089928)
		(end 137.580116 -229.272846)
		(width 0.088646)
		(layer "In11.Cu")
		(net "M_H_CPU1_SB_DQ<26>")
	)
	(arc
		(start 137.580116 -229.282752)
		(mid 137.502005 -229.559701)
		(end 137.297668 -229.762304)
		(width 0.088646)
		(layer "In11.Cu")
		(net "M_H_CPU1_SB_DQ<26>")
	)
	(arc
		(start 130.15341 -229.762304)
		(mid 129.966212 -229.712161)
		(end 129.779014 -229.762304)
		(width 0.088646)
		(layer "In11.Cu")
		(net "M_H_CPU1_SB_DQ<26>")
	)
	(arc
		(start 138.141964 -228.948488)
		(mid 137.954766 -228.898345)
		(end 137.767568 -228.948488)
		(width 0.088646)
		(layer "In11.Cu")
		(net "M_H_CPU1_SB_DQ<26>")
	)
	(arc
		(start 129.779014 -229.762304)
		(mid 129.496312 -229.83808)
		(end 129.21361 -229.762304)
		(width 0.088646)
		(layer "In11.Cu")
		(net "M_H_CPU1_SB_DQ<26>")
	)
	(arc
		(start 128.824482 -229.77094)
		(mid 128.548007 -229.83826)
		(end 128.27381 -229.762304)
		(width 0.088646)
		(layer "In11.Cu")
		(net "M_H_CPU1_SB_DQ<26>")
	)
	(arc
		(start 136.732264 -229.762304)
		(mid 136.545066 -229.712161)
		(end 136.357868 -229.762304)
		(width 0.088646)
		(layer "In11.Cu")
		(net "M_H_CPU1_SB_DQ<26>")
	)
	(arc
		(start 128.27381 -229.762304)
		(mid 128.086612 -229.712161)
		(end 127.899414 -229.762304)
		(width 0.088646)
		(layer "In11.Cu")
		(net "M_H_CPU1_SB_DQ<26>")
	)
	(arc
		(start 125.454664 -229.762304)
		(mid 125.280721 -229.654984)
		(end 125.113288 -229.537768)
		(width 0.088646)
		(layer "In11.Cu")
		(net "M_H_CPU1_SB_DQ<26>")
	)
	(arc
		(start 133.912864 -229.762304)
		(mid 133.725666 -229.712161)
		(end 133.538468 -229.762304)
		(width 0.088646)
		(layer "In11.Cu")
		(net "M_H_CPU1_SB_DQ<26>")
	)
	(arc
		(start 131.09321 -229.762304)
		(mid 130.906012 -229.712161)
		(end 130.718814 -229.762304)
		(width 0.088646)
		(layer "In11.Cu")
		(net "M_H_CPU1_SB_DQ<26>")
	)
	(arc
		(start 126.39421 -229.762304)
		(mid 126.207012 -229.712161)
		(end 126.019814 -229.762304)
		(width 0.088646)
		(layer "In11.Cu")
		(net "M_H_CPU1_SB_DQ<26>")
	)
	(arc
		(start 126.0094 -229.7684)
		(mid 125.731222 -229.838123)
		(end 125.454664 -229.762304)
		(width 0.088646)
		(layer "In11.Cu")
		(net "M_H_CPU1_SB_DQ<26>")
	)
	(arc
		(start 133.528054 -229.7684)
		(mid 133.249622 -229.838246)
		(end 132.97281 -229.762304)
		(width 0.088646)
		(layer "In11.Cu")
		(net "M_H_CPU1_SB_DQ<26>")
	)
	(arc
		(start 126.944882 -229.77094)
		(mid 126.668407 -229.83826)
		(end 126.39421 -229.762304)
		(width 0.088646)
		(layer "In11.Cu")
		(net "M_H_CPU1_SB_DQ<26>")
	)
	(arc
		(start 137.297668 -229.762304)
		(mid 137.014966 -229.83808)
		(end 136.732264 -229.762304)
		(width 0.088646)
		(layer "In11.Cu")
		(net "M_H_CPU1_SB_DQ<26>")
	)
	(arc
		(start 136.357868 -229.762304)
		(mid 136.075166 -229.83808)
		(end 135.792464 -229.762304)
		(width 0.088646)
		(layer "In11.Cu")
		(net "M_H_CPU1_SB_DQ<26>")
	)
	(arc
		(start 134.478268 -229.762304)
		(mid 134.195566 -229.83808)
		(end 133.912864 -229.762304)
		(width 0.088646)
		(layer "In11.Cu")
		(net "M_H_CPU1_SB_DQ<26>")
	)
	(arc
		(start 138.872722 -228.821742)
		(mid 138.794218 -228.89056)
		(end 138.707368 -228.948488)
		(width 0.088646)
		(layer "In11.Cu")
		(net "M_H_CPU1_SB_DQ<26>")
	)
	(arc
		(start 130.704082 -229.77094)
		(mid 130.427607 -229.83826)
		(end 130.15341 -229.762304)
		(width 0.088646)
		(layer "In11.Cu")
		(net "M_H_CPU1_SB_DQ<26>")
	)
	(arc
		(start 127.884682 -229.77094)
		(mid 127.608207 -229.83826)
		(end 127.33401 -229.762304)
		(width 0.088646)
		(layer "In11.Cu")
		(net "M_H_CPU1_SB_DQ<26>")
	)
	(arc
		(start 127.33401 -229.762304)
		(mid 127.146812 -229.712161)
		(end 126.959614 -229.762304)
		(width 0.088646)
		(layer "In11.Cu")
		(net "M_H_CPU1_SB_DQ<26>")
	)
	(arc
		(start 135.418068 -229.762304)
		(mid 135.135366 -229.83808)
		(end 134.852664 -229.762304)
		(width 0.088646)
		(layer "In11.Cu")
		(net "M_H_CPU1_SB_DQ<26>")
	)
	(arc
		(start 131.648454 -229.7684)
		(mid 131.370022 -229.838246)
		(end 131.09321 -229.762304)
		(width 0.088646)
		(layer "In11.Cu")
		(net "M_H_CPU1_SB_DQ<26>")
	)
	(arc
		(start 132.033264 -229.762304)
		(mid 131.846066 -229.712161)
		(end 131.658868 -229.762304)
		(width 0.088646)
		(layer "In11.Cu")
		(net "M_H_CPU1_SB_DQ<26>")
	)
	(arc
		(start 134.852664 -229.762304)
		(mid 134.665466 -229.712161)
		(end 134.478268 -229.762304)
		(width 0.088646)
		(layer "In11.Cu")
		(net "M_H_CPU1_SB_DQ<26>")
	)
	(arc
		(start 138.707368 -228.948488)
		(mid 138.424666 -229.024264)
		(end 138.141964 -228.948488)
		(width 0.088646)
		(layer "In11.Cu")
		(net "M_H_CPU1_SB_DQ<26>")
	)
	(arc
		(start 129.21361 -229.762304)
		(mid 129.026412 -229.712161)
		(end 128.839214 -229.762304)
		(width 0.088646)
		(layer "In11.Cu")
		(net "M_H_CPU1_SB_DQ<26>")
	)
	(arc
		(start 135.792464 -229.762304)
		(mid 135.605266 -229.712161)
		(end 135.418068 -229.762304)
		(width 0.088646)
		(layer "In11.Cu")
		(net "M_H_CPU1_SB_DQ<26>")
	)
	(arc
		(start 132.588 -229.7684)
		(mid 132.309822 -229.838123)
		(end 132.033264 -229.762304)
		(width 0.088646)
		(layer "In11.Cu")
		(net "M_H_CPU1_SB_DQ<26>")
	)
	(arc
		(start 132.97281 -229.762304)
		(mid 132.785612 -229.712161)
		(end 132.598414 -229.762304)
		(width 0.088646)
		(layer "In11.Cu")
		(net "M_H_CPU1_SB_DQ<26>")
	)
	(segment
		(start 205.84541 -202.66533)
		(end 205.596744 -202.416664)
		(width 0.20066)
		(layer "F.Cu")
		(net "M_H_CPU1_SB_DQ<25>")
	)
	(segment
		(start 211.619592 -202.416918)
		(end 210.028028 -202.416918)
		(width 0.20066)
		(layer "F.Cu")
		(net "M_H_CPU1_SB_DQ<25>")
	)
	(segment
		(start 206.320644 -202.66533)
		(end 205.84541 -202.66533)
		(width 0.20066)
		(layer "F.Cu")
		(net "M_H_CPU1_SB_DQ<25>")
	)
	(segment
		(start 206.991458 -201.991722)
		(end 206.971392 -201.991722)
		(width 0.101854)
		(layer "F.Cu")
		(net "M_H_CPU1_SB_DQ<25>")
	)
	(segment
		(start 209.180176 -201.991722)
		(end 206.991458 -201.991722)
		(width 0.1016)
		(layer "F.Cu")
		(net "M_H_CPU1_SB_DQ<25>")
	)
	(segment
		(start 211.619846 -202.416664)
		(end 211.619592 -202.416918)
		(width 0.20066)
		(layer "F.Cu")
		(net "M_H_CPU1_SB_DQ<25>")
	)
	(segment
		(start 205.596744 -202.416664)
		(end 204.076046 -202.416664)
		(width 0.20066)
		(layer "F.Cu")
		(net "M_H_CPU1_SB_DQ<25>")
	)
	(segment
		(start 206.508604 -202.109832)
		(end 206.508604 -202.47737)
		(width 0.20066)
		(layer "F.Cu")
		(net "M_H_CPU1_SB_DQ<25>")
	)
	(segment
		(start 204.076046 -202.416664)
		(end 202.971146 -202.416664)
		(width 0.20066)
		(layer "F.Cu")
		(net "M_H_CPU1_SB_DQ<25>")
	)
	(segment
		(start 123.387866 -228.99497)
		(end 123.387866 -228.459284)
		(width 0.20066)
		(layer "F.Cu")
		(net "M_H_CPU1_SB_DQ<25>")
	)
	(segment
		(start 206.971392 -201.991722)
		(end 206.626714 -201.991722)
		(width 0.20066)
		(layer "F.Cu")
		(net "M_H_CPU1_SB_DQ<25>")
	)
	(segment
		(start 206.508604 -202.47737)
		(end 206.320644 -202.66533)
		(width 0.20066)
		(layer "F.Cu")
		(net "M_H_CPU1_SB_DQ<25>")
	)
	(segment
		(start 210.028028 -202.416918)
		(end 209.596482 -201.985372)
		(width 0.20066)
		(layer "F.Cu")
		(net "M_H_CPU1_SB_DQ<25>")
	)
	(segment
		(start 123.387866 -228.459284)
		(end 123.387612 -228.45903)
		(width 0.20066)
		(layer "F.Cu")
		(net "M_H_CPU1_SB_DQ<25>")
	)
	(segment
		(start 206.626714 -201.991722)
		(end 206.508604 -202.109832)
		(width 0.20066)
		(layer "F.Cu")
		(net "M_H_CPU1_SB_DQ<25>")
	)
	(segment
		(start 209.596482 -201.985372)
		(end 209.186526 -201.985372)
		(width 0.20066)
		(layer "F.Cu")
		(net "M_H_CPU1_SB_DQ<25>")
	)
	(segment
		(start 209.186526 -201.985372)
		(end 209.180176 -201.991722)
		(width 0.1016)
		(layer "F.Cu")
		(net "M_H_CPU1_SB_DQ<25>")
	)
	(segment
		(start 202.971146 -202.416664)
		(end 202.971146 -202.69835)
		(width 0.18288)
		(layer "In11.Cu")
		(net "M_H_CPU1_SB_DQ<25>")
	)
	(segment
		(start 194.460876 -203.058776)
		(end 193.539364 -203.058776)
		(width 0.18288)
		(layer "In11.Cu")
		(net "M_H_CPU1_SB_DQ<25>")
	)
	(segment
		(start 185.579766 -202.23099)
		(end 185.262266 -202.23099)
		(width 0.18288)
		(layer "In11.Cu")
		(net "M_H_CPU1_SB_DQ<25>")
	)
	(segment
		(start 164.94506 -202.831192)
		(end 164.749226 -203.027026)
		(width 0.18288)
		(layer "In11.Cu")
		(net "M_H_CPU1_SB_DQ<25>")
	)
	(segment
		(start 125.080014 -228.134672)
		(end 125.065282 -228.143308)
		(width 0.088646)
		(layer "In11.Cu")
		(net "M_H_CPU1_SB_DQ<25>")
	)
	(segment
		(start 174.77359 -202.76693)
		(end 174.58055 -202.57389)
		(width 0.18288)
		(layer "In11.Cu")
		(net "M_H_CPU1_SB_DQ<25>")
	)
	(segment
		(start 185.772806 -202.757786)
		(end 185.772806 -202.42403)
		(width 0.18288)
		(layer "In11.Cu")
		(net "M_H_CPU1_SB_DQ<25>")
	)
	(segment
		(start 178.407822 -202.808586)
		(end 178.407822 -202.286108)
		(width 0.18288)
		(layer "In11.Cu")
		(net "M_H_CPU1_SB_DQ<25>")
	)
	(segment
		(start 136.741154 -228.778308)
		(end 136.732264 -228.783388)
		(width 0.088646)
		(layer "In11.Cu")
		(net "M_H_CPU1_SB_DQ<25>")
	)
	(segment
		(start 170.363134 -202.2729)
		(end 170.170094 -202.46594)
		(width 0.18288)
		(layer "In11.Cu")
		(net "M_H_CPU1_SB_DQ<25>")
	)
	(segment
		(start 196.204078 -201.86142)
		(end 196.204078 -202.097386)
		(width 0.18288)
		(layer "In11.Cu")
		(net "M_H_CPU1_SB_DQ<25>")
	)
	(segment
		(start 184.876186 -202.950826)
		(end 183.490362 -202.950826)
		(width 0.18288)
		(layer "In11.Cu")
		(net "M_H_CPU1_SB_DQ<25>")
	)
	(segment
		(start 156.858462 -205.270862)
		(end 148.65223 -213.477094)
		(width 0.18288)
		(layer "In11.Cu")
		(net "M_H_CPU1_SB_DQ<25>")
	)
	(segment
		(start 196.204078 -202.097386)
		(end 196.011038 -202.290426)
		(width 0.18288)
		(layer "In11.Cu")
		(net "M_H_CPU1_SB_DQ<25>")
	)
	(segment
		(start 187.259722 -202.84313)
		(end 187.152026 -202.950826)
		(width 0.18288)
		(layer "In11.Cu")
		(net "M_H_CPU1_SB_DQ<25>")
	)
	(segment
		(start 140.306298 -225.55581)
		(end 139.757912 -225.55581)
		(width 0.088646)
		(layer "In11.Cu")
		(net "M_H_CPU1_SB_DQ<25>")
	)
	(segment
		(start 142.015464 -222.802196)
		(end 142.015464 -223.846644)
		(width 0.18288)
		(layer "In11.Cu")
		(net "M_H_CPU1_SB_DQ<25>")
	)
	(segment
		(start 202.971146 -202.69835)
		(end 202.834494 -202.835002)
		(width 0.18288)
		(layer "In11.Cu")
		(net "M_H_CPU1_SB_DQ<25>")
	)
	(segment
		(start 128.839214 -228.783388)
		(end 128.824482 -228.774752)
		(width 0.088646)
		(layer "In11.Cu")
		(net "M_H_CPU1_SB_DQ<25>")
	)
	(segment
		(start 198.556626 -202.290426)
		(end 197.100698 -202.290426)
		(width 0.18288)
		(layer "In11.Cu")
		(net "M_H_CPU1_SB_DQ<25>")
	)
	(segment
		(start 158.444438 -203.27239)
		(end 157.76448 -203.952348)
		(width 0.18288)
		(layer "In11.Cu")
		(net "M_H_CPU1_SB_DQ<25>")
	)
	(segment
		(start 196.011038 -202.290426)
		(end 195.229226 -202.290426)
		(width 0.18288)
		(layer "In11.Cu")
		(net "M_H_CPU1_SB_DQ<25>")
	)
	(segment
		(start 178.600862 -203.001626)
		(end 178.407822 -202.808586)
		(width 0.18288)
		(layer "In11.Cu")
		(net "M_H_CPU1_SB_DQ<25>")
	)
	(segment
		(start 160.36417 -202.83297)
		(end 159.716978 -202.83297)
		(width 0.18288)
		(layer "In11.Cu")
		(net "M_H_CPU1_SB_DQ<25>")
	)
	(segment
		(start 174.58055 -202.57389)
		(end 174.58055 -202.182476)
		(width 0.18288)
		(layer "In11.Cu")
		(net "M_H_CPU1_SB_DQ<25>")
	)
	(segment
		(start 179.659026 -202.823826)
		(end 179.481226 -203.001626)
		(width 0.18288)
		(layer "In11.Cu")
		(net "M_H_CPU1_SB_DQ<25>")
	)
	(segment
		(start 170.170094 -202.783186)
		(end 169.977054 -202.976226)
		(width 0.18288)
		(layer "In11.Cu")
		(net "M_H_CPU1_SB_DQ<25>")
	)
	(segment
		(start 148.65223 -213.477094)
		(end 148.65223 -216.16543)
		(width 0.18288)
		(layer "In11.Cu")
		(net "M_H_CPU1_SB_DQ<25>")
	)
	(segment
		(start 195.229226 -202.290426)
		(end 194.460876 -203.058776)
		(width 0.18288)
		(layer "In11.Cu")
		(net "M_H_CPU1_SB_DQ<25>")
	)
	(segment
		(start 193.321686 -202.841098)
		(end 191.563752 -202.841098)
		(width 0.18288)
		(layer "In11.Cu")
		(net "M_H_CPU1_SB_DQ<25>")
	)
	(segment
		(start 177.706782 -202.80503)
		(end 177.513742 -202.99807)
		(width 0.18288)
		(layer "In11.Cu")
		(net "M_H_CPU1_SB_DQ<25>")
	)
	(segment
		(start 132.598668 -228.783388)
		(end 132.588254 -228.777292)
		(width 0.088646)
		(layer "In11.Cu")
		(net "M_H_CPU1_SB_DQ<25>")
	)
	(segment
		(start 170.942254 -202.783186)
		(end 170.942254 -202.46594)
		(width 0.18288)
		(layer "In11.Cu")
		(net "M_H_CPU1_SB_DQ<25>")
	)
	(segment
		(start 185.262266 -202.23099)
		(end 185.069226 -202.42403)
		(width 0.18288)
		(layer "In11.Cu")
		(net "M_H_CPU1_SB_DQ<25>")
	)
	(segment
		(start 175.47463 -201.944224)
		(end 175.28159 -202.137264)
		(width 0.18288)
		(layer "In11.Cu")
		(net "M_H_CPU1_SB_DQ<25>")
	)
	(segment
		(start 170.942254 -202.46594)
		(end 170.749214 -202.2729)
		(width 0.18288)
		(layer "In11.Cu")
		(net "M_H_CPU1_SB_DQ<25>")
	)
	(segment
		(start 131.658614 -228.783388)
		(end 131.643882 -228.774752)
		(width 0.088646)
		(layer "In11.Cu")
		(net "M_H_CPU1_SB_DQ<25>")
	)
	(segment
		(start 175.28159 -202.57389)
		(end 175.08855 -202.76693)
		(width 0.18288)
		(layer "In11.Cu")
		(net "M_H_CPU1_SB_DQ<25>")
	)
	(segment
		(start 185.069226 -202.42403)
		(end 185.069226 -202.757786)
		(width 0.18288)
		(layer "In11.Cu")
		(net "M_H_CPU1_SB_DQ<25>")
	)
	(segment
		(start 159.277558 -203.27239)
		(end 158.444438 -203.27239)
		(width 0.18288)
		(layer "In11.Cu")
		(net "M_H_CPU1_SB_DQ<25>")
	)
	(segment
		(start 175.78959 -201.944224)
		(end 175.47463 -201.944224)
		(width 0.18288)
		(layer "In11.Cu")
		(net "M_H_CPU1_SB_DQ<25>")
	)
	(segment
		(start 156.858462 -204.860144)
		(end 156.858462 -205.270862)
		(width 0.18288)
		(layer "In11.Cu")
		(net "M_H_CPU1_SB_DQ<25>")
	)
	(segment
		(start 196.907658 -202.097386)
		(end 196.907658 -201.86142)
		(width 0.18288)
		(layer "In11.Cu")
		(net "M_H_CPU1_SB_DQ<25>")
	)
	(segment
		(start 127.899414 -228.783388)
		(end 127.884682 -228.774752)
		(width 0.088646)
		(layer "In11.Cu")
		(net "M_H_CPU1_SB_DQ<25>")
	)
	(segment
		(start 177.084736 -202.842368)
		(end 176.251108 -202.842368)
		(width 0.18288)
		(layer "In11.Cu")
		(net "M_H_CPU1_SB_DQ<25>")
	)
	(segment
		(start 187.152026 -202.950826)
		(end 185.965846 -202.950826)
		(width 0.18288)
		(layer "In11.Cu")
		(net "M_H_CPU1_SB_DQ<25>")
	)
	(segment
		(start 172.19295 -202.842622)
		(end 172.059346 -202.976226)
		(width 0.18288)
		(layer "In11.Cu")
		(net "M_H_CPU1_SB_DQ<25>")
	)
	(segment
		(start 202.616054 -202.925426)
		(end 199.191626 -202.925426)
		(width 0.18288)
		(layer "In11.Cu")
		(net "M_H_CPU1_SB_DQ<25>")
	)
	(segment
		(start 172.059346 -202.976226)
		(end 171.135294 -202.976226)
		(width 0.18288)
		(layer "In11.Cu")
		(net "M_H_CPU1_SB_DQ<25>")
	)
	(segment
		(start 183.490362 -202.950826)
		(end 183.363362 -202.823826)
		(width 0.18288)
		(layer "In11.Cu")
		(net "M_H_CPU1_SB_DQ<25>")
	)
	(segment
		(start 196.714618 -201.66838)
		(end 196.397118 -201.66838)
		(width 0.18288)
		(layer "In11.Cu")
		(net "M_H_CPU1_SB_DQ<25>")
	)
	(segment
		(start 185.772806 -202.42403)
		(end 185.579766 -202.23099)
		(width 0.18288)
		(layer "In11.Cu")
		(net "M_H_CPU1_SB_DQ<25>")
	)
	(segment
		(start 174.58055 -202.182476)
		(end 174.38751 -201.989436)
		(width 0.18288)
		(layer "In11.Cu")
		(net "M_H_CPU1_SB_DQ<25>")
	)
	(segment
		(start 139.41933 -226.55022)
		(end 139.203176 -226.766374)
		(width 0.088646)
		(layer "In11.Cu")
		(net "M_H_CPU1_SB_DQ<25>")
	)
	(segment
		(start 136.919716 -228.440488)
		(end 136.919716 -228.45903)
		(width 0.088646)
		(layer "In11.Cu")
		(net "M_H_CPU1_SB_DQ<25>")
	)
	(segment
		(start 197.100698 -202.290426)
		(end 196.907658 -202.097386)
		(width 0.18288)
		(layer "In11.Cu")
		(net "M_H_CPU1_SB_DQ<25>")
	)
	(segment
		(start 169.977054 -202.976226)
		(end 168.000426 -202.976226)
		(width 0.18288)
		(layer "In11.Cu")
		(net "M_H_CPU1_SB_DQ<25>")
	)
	(segment
		(start 167.855392 -202.831192)
		(end 164.94506 -202.831192)
		(width 0.18288)
		(layer "In11.Cu")
		(net "M_H_CPU1_SB_DQ<25>")
	)
	(segment
		(start 196.907658 -201.86142)
		(end 196.714618 -201.66838)
		(width 0.18288)
		(layer "In11.Cu")
		(net "M_H_CPU1_SB_DQ<25>")
	)
	(segment
		(start 175.28159 -202.137264)
		(end 175.28159 -202.57389)
		(width 0.18288)
		(layer "In11.Cu")
		(net "M_H_CPU1_SB_DQ<25>")
	)
	(segment
		(start 178.214782 -202.093068)
		(end 177.899822 -202.093068)
		(width 0.18288)
		(layer "In11.Cu")
		(net "M_H_CPU1_SB_DQ<25>")
	)
	(segment
		(start 130.718814 -228.783388)
		(end 130.704082 -228.774752)
		(width 0.088646)
		(layer "In11.Cu")
		(net "M_H_CPU1_SB_DQ<25>")
	)
	(segment
		(start 185.965846 -202.950826)
		(end 185.772806 -202.757786)
		(width 0.18288)
		(layer "In11.Cu")
		(net "M_H_CPU1_SB_DQ<25>")
	)
	(segment
		(start 140.725906 -225.136202)
		(end 140.306298 -225.55581)
		(width 0.088646)
		(layer "In11.Cu")
		(net "M_H_CPU1_SB_DQ<25>")
	)
	(segment
		(start 170.170094 -202.46594)
		(end 170.170094 -202.783186)
		(width 0.18288)
		(layer "In11.Cu")
		(net "M_H_CPU1_SB_DQ<25>")
	)
	(segment
		(start 139.203176 -227.400866)
		(end 138.710416 -227.893626)
		(width 0.088646)
		(layer "In11.Cu")
		(net "M_H_CPU1_SB_DQ<25>")
	)
	(segment
		(start 199.191626 -202.925426)
		(end 198.556626 -202.290426)
		(width 0.18288)
		(layer "In11.Cu")
		(net "M_H_CPU1_SB_DQ<25>")
	)
	(segment
		(start 159.716978 -202.83297)
		(end 159.277558 -203.27239)
		(width 0.18288)
		(layer "In11.Cu")
		(net "M_H_CPU1_SB_DQ<25>")
	)
	(segment
		(start 179.481226 -203.001626)
		(end 178.600862 -203.001626)
		(width 0.18288)
		(layer "In11.Cu")
		(net "M_H_CPU1_SB_DQ<25>")
	)
	(segment
		(start 177.513742 -202.99807)
		(end 177.240438 -202.99807)
		(width 0.18288)
		(layer "In11.Cu")
		(net "M_H_CPU1_SB_DQ<25>")
	)
	(segment
		(start 135.418068 -228.783388)
		(end 135.407654 -228.777292)
		(width 0.088646)
		(layer "In11.Cu")
		(net "M_H_CPU1_SB_DQ<25>")
	)
	(segment
		(start 177.899822 -202.093068)
		(end 177.706782 -202.286108)
		(width 0.18288)
		(layer "In11.Cu")
		(net "M_H_CPU1_SB_DQ<25>")
	)
	(segment
		(start 178.407822 -202.286108)
		(end 178.214782 -202.093068)
		(width 0.18288)
		(layer "In11.Cu")
		(net "M_H_CPU1_SB_DQ<25>")
	)
	(segment
		(start 171.135294 -202.976226)
		(end 170.942254 -202.783186)
		(width 0.18288)
		(layer "In11.Cu")
		(net "M_H_CPU1_SB_DQ<25>")
	)
	(segment
		(start 193.539364 -203.058776)
		(end 193.321686 -202.841098)
		(width 0.18288)
		(layer "In11.Cu")
		(net "M_H_CPU1_SB_DQ<25>")
	)
	(segment
		(start 160.558226 -203.027026)
		(end 160.36417 -202.83297)
		(width 0.18288)
		(layer "In11.Cu")
		(net "M_H_CPU1_SB_DQ<25>")
	)
	(segment
		(start 148.65223 -216.16543)
		(end 142.015464 -222.802196)
		(width 0.18288)
		(layer "In11.Cu")
		(net "M_H_CPU1_SB_DQ<25>")
	)
	(segment
		(start 185.069226 -202.757786)
		(end 184.876186 -202.950826)
		(width 0.18288)
		(layer "In11.Cu")
		(net "M_H_CPU1_SB_DQ<25>")
	)
	(segment
		(start 191.563752 -202.841098)
		(end 191.377824 -202.65517)
		(width 0.18288)
		(layer "In11.Cu")
		(net "M_H_CPU1_SB_DQ<25>")
	)
	(segment
		(start 188.787278 -202.84313)
		(end 187.259722 -202.84313)
		(width 0.18288)
		(layer "In11.Cu")
		(net "M_H_CPU1_SB_DQ<25>")
	)
	(segment
		(start 139.757912 -225.55581)
		(end 139.41933 -225.894392)
		(width 0.088646)
		(layer "In11.Cu")
		(net "M_H_CPU1_SB_DQ<25>")
	)
	(segment
		(start 177.706782 -202.286108)
		(end 177.706782 -202.80503)
		(width 0.18288)
		(layer "In11.Cu")
		(net "M_H_CPU1_SB_DQ<25>")
	)
	(segment
		(start 175.98263 -202.137264)
		(end 175.78959 -201.944224)
		(width 0.18288)
		(layer "In11.Cu")
		(net "M_H_CPU1_SB_DQ<25>")
	)
	(segment
		(start 139.203176 -226.766374)
		(end 139.203176 -227.400866)
		(width 0.088646)
		(layer "In11.Cu")
		(net "M_H_CPU1_SB_DQ<25>")
	)
	(segment
		(start 157.76448 -203.952348)
		(end 157.76448 -203.954126)
		(width 0.18288)
		(layer "In11.Cu")
		(net "M_H_CPU1_SB_DQ<25>")
	)
	(segment
		(start 139.41933 -225.894392)
		(end 139.41933 -226.55022)
		(width 0.088646)
		(layer "In11.Cu")
		(net "M_H_CPU1_SB_DQ<25>")
	)
	(segment
		(start 142.015464 -223.846644)
		(end 140.725906 -225.136202)
		(width 0.18288)
		(layer "In11.Cu")
		(net "M_H_CPU1_SB_DQ<25>")
	)
	(segment
		(start 126.020068 -228.783388)
		(end 126.011178 -228.778308)
		(width 0.088646)
		(layer "In11.Cu")
		(net "M_H_CPU1_SB_DQ<25>")
	)
	(segment
		(start 176.251108 -202.842368)
		(end 175.98263 -202.57389)
		(width 0.18288)
		(layer "In11.Cu")
		(net "M_H_CPU1_SB_DQ<25>")
	)
	(segment
		(start 170.749214 -202.2729)
		(end 170.363134 -202.2729)
		(width 0.18288)
		(layer "In11.Cu")
		(net "M_H_CPU1_SB_DQ<25>")
	)
	(segment
		(start 202.834494 -202.835002)
		(end 202.616054 -202.925426)
		(width 0.18288)
		(layer "In11.Cu")
		(net "M_H_CPU1_SB_DQ<25>")
	)
	(segment
		(start 173.219364 -202.842622)
		(end 172.19295 -202.842622)
		(width 0.18288)
		(layer "In11.Cu")
		(net "M_H_CPU1_SB_DQ<25>")
	)
	(segment
		(start 126.959614 -228.783388)
		(end 126.9492 -228.777292)
		(width 0.088646)
		(layer "In11.Cu")
		(net "M_H_CPU1_SB_DQ<25>")
	)
	(segment
		(start 183.363362 -202.823826)
		(end 179.659026 -202.823826)
		(width 0.18288)
		(layer "In11.Cu")
		(net "M_H_CPU1_SB_DQ<25>")
	)
	(segment
		(start 188.975238 -202.65517)
		(end 188.787278 -202.84313)
		(width 0.18288)
		(layer "In11.Cu")
		(net "M_H_CPU1_SB_DQ<25>")
	)
	(segment
		(start 134.478014 -228.783388)
		(end 134.4676 -228.777292)
		(width 0.088646)
		(layer "In11.Cu")
		(net "M_H_CPU1_SB_DQ<25>")
	)
	(segment
		(start 177.240438 -202.99807)
		(end 177.084736 -202.842368)
		(width 0.18288)
		(layer "In11.Cu")
		(net "M_H_CPU1_SB_DQ<25>")
	)
	(segment
		(start 138.710416 -227.893626)
		(end 138.424666 -227.893626)
		(width 0.088646)
		(layer "In11.Cu")
		(net "M_H_CPU1_SB_DQ<25>")
	)
	(segment
		(start 164.749226 -203.027026)
		(end 160.558226 -203.027026)
		(width 0.18288)
		(layer "In11.Cu")
		(net "M_H_CPU1_SB_DQ<25>")
	)
	(segment
		(start 196.397118 -201.66838)
		(end 196.204078 -201.86142)
		(width 0.18288)
		(layer "In11.Cu")
		(net "M_H_CPU1_SB_DQ<25>")
	)
	(segment
		(start 175.98263 -202.57389)
		(end 175.98263 -202.137264)
		(width 0.18288)
		(layer "In11.Cu")
		(net "M_H_CPU1_SB_DQ<25>")
	)
	(segment
		(start 157.76448 -203.954126)
		(end 156.858462 -204.860144)
		(width 0.18288)
		(layer "In11.Cu")
		(net "M_H_CPU1_SB_DQ<25>")
	)
	(segment
		(start 174.38751 -201.989436)
		(end 174.07255 -201.989436)
		(width 0.18288)
		(layer "In11.Cu")
		(net "M_H_CPU1_SB_DQ<25>")
	)
	(segment
		(start 174.07255 -201.989436)
		(end 173.219364 -202.842622)
		(width 0.18288)
		(layer "In11.Cu")
		(net "M_H_CPU1_SB_DQ<25>")
	)
	(segment
		(start 191.377824 -202.65517)
		(end 188.975238 -202.65517)
		(width 0.18288)
		(layer "In11.Cu")
		(net "M_H_CPU1_SB_DQ<25>")
	)
	(segment
		(start 168.000426 -202.976226)
		(end 167.855392 -202.831192)
		(width 0.18288)
		(layer "In11.Cu")
		(net "M_H_CPU1_SB_DQ<25>")
	)
	(segment
		(start 175.08855 -202.76693)
		(end 174.77359 -202.76693)
		(width 0.18288)
		(layer "In11.Cu")
		(net "M_H_CPU1_SB_DQ<25>")
	)
	(arc
		(start 130.15341 -228.783388)
		(mid 129.966212 -228.833531)
		(end 129.779014 -228.783388)
		(width 0.088646)
		(layer "In11.Cu")
		(net "M_H_CPU1_SB_DQ<25>")
	)
	(arc
		(start 135.792464 -228.783388)
		(mid 135.605266 -228.833531)
		(end 135.418068 -228.783388)
		(width 0.088646)
		(layer "In11.Cu")
		(net "M_H_CPU1_SB_DQ<25>")
	)
	(arc
		(start 132.03301 -228.783388)
		(mid 131.845812 -228.833531)
		(end 131.658614 -228.783388)
		(width 0.088646)
		(layer "In11.Cu")
		(net "M_H_CPU1_SB_DQ<25>")
	)
	(arc
		(start 131.643882 -228.774752)
		(mid 131.367407 -228.707432)
		(end 131.09321 -228.783388)
		(width 0.088646)
		(layer "In11.Cu")
		(net "M_H_CPU1_SB_DQ<25>")
	)
	(arc
		(start 133.538468 -228.783388)
		(mid 133.255766 -228.707612)
		(end 132.973064 -228.783388)
		(width 0.088646)
		(layer "In11.Cu")
		(net "M_H_CPU1_SB_DQ<25>")
	)
	(arc
		(start 134.4676 -228.777292)
		(mid 134.189422 -228.707569)
		(end 133.912864 -228.783388)
		(width 0.088646)
		(layer "In11.Cu")
		(net "M_H_CPU1_SB_DQ<25>")
	)
	(arc
		(start 125.45441 -228.134672)
		(mid 125.267212 -228.084529)
		(end 125.080014 -228.134672)
		(width 0.088646)
		(layer "In11.Cu")
		(net "M_H_CPU1_SB_DQ<25>")
	)
	(arc
		(start 127.33401 -228.783388)
		(mid 127.146812 -228.833531)
		(end 126.959614 -228.783388)
		(width 0.088646)
		(layer "In11.Cu")
		(net "M_H_CPU1_SB_DQ<25>")
	)
	(arc
		(start 124.51461 -228.134672)
		(mid 123.882102 -228.057106)
		(end 123.387612 -228.45903)
		(width 0.088646)
		(layer "In11.Cu")
		(net "M_H_CPU1_SB_DQ<25>")
	)
	(arc
		(start 129.21361 -228.783388)
		(mid 129.026412 -228.833531)
		(end 128.839214 -228.783388)
		(width 0.088646)
		(layer "In11.Cu")
		(net "M_H_CPU1_SB_DQ<25>")
	)
	(arc
		(start 125.684026 -228.401626)
		(mid 125.591908 -228.248637)
		(end 125.45441 -228.134672)
		(width 0.088646)
		(layer "In11.Cu")
		(net "M_H_CPU1_SB_DQ<25>")
	)
	(arc
		(start 125.065282 -228.143308)
		(mid 124.788841 -228.210474)
		(end 124.51461 -228.134672)
		(width 0.088646)
		(layer "In11.Cu")
		(net "M_H_CPU1_SB_DQ<25>")
	)
	(arc
		(start 129.779014 -228.783388)
		(mid 129.496312 -228.707612)
		(end 129.21361 -228.783388)
		(width 0.088646)
		(layer "In11.Cu")
		(net "M_H_CPU1_SB_DQ<25>")
	)
	(arc
		(start 126.394464 -228.783388)
		(mid 126.207266 -228.833531)
		(end 126.020068 -228.783388)
		(width 0.088646)
		(layer "In11.Cu")
		(net "M_H_CPU1_SB_DQ<25>")
	)
	(arc
		(start 130.704082 -228.774752)
		(mid 130.427607 -228.707432)
		(end 130.15341 -228.783388)
		(width 0.088646)
		(layer "In11.Cu")
		(net "M_H_CPU1_SB_DQ<25>")
	)
	(arc
		(start 138.141964 -227.969318)
		(mid 137.954766 -228.019461)
		(end 137.767568 -227.969318)
		(width 0.088646)
		(layer "In11.Cu")
		(net "M_H_CPU1_SB_DQ<25>")
	)
	(arc
		(start 136.732264 -228.783388)
		(mid 136.545066 -228.833531)
		(end 136.357868 -228.783388)
		(width 0.088646)
		(layer "In11.Cu")
		(net "M_H_CPU1_SB_DQ<25>")
	)
	(arc
		(start 133.912864 -228.783388)
		(mid 133.725666 -228.833531)
		(end 133.538468 -228.783388)
		(width 0.088646)
		(layer "In11.Cu")
		(net "M_H_CPU1_SB_DQ<25>")
	)
	(arc
		(start 134.85241 -228.783388)
		(mid 134.665212 -228.833531)
		(end 134.478014 -228.783388)
		(width 0.088646)
		(layer "In11.Cu")
		(net "M_H_CPU1_SB_DQ<25>")
	)
	(arc
		(start 126.9492 -228.777292)
		(mid 126.671022 -228.707569)
		(end 126.394464 -228.783388)
		(width 0.088646)
		(layer "In11.Cu")
		(net "M_H_CPU1_SB_DQ<25>")
	)
	(arc
		(start 128.824482 -228.774752)
		(mid 128.548007 -228.707432)
		(end 128.27381 -228.783388)
		(width 0.088646)
		(layer "In11.Cu")
		(net "M_H_CPU1_SB_DQ<25>")
	)
	(arc
		(start 137.767568 -227.969318)
		(mid 137.484866 -227.893576)
		(end 137.202164 -227.969318)
		(width 0.088646)
		(layer "In11.Cu")
		(net "M_H_CPU1_SB_DQ<25>")
	)
	(arc
		(start 131.09321 -228.783388)
		(mid 130.906012 -228.833531)
		(end 130.718814 -228.783388)
		(width 0.088646)
		(layer "In11.Cu")
		(net "M_H_CPU1_SB_DQ<25>")
	)
	(arc
		(start 128.27381 -228.783388)
		(mid 128.086612 -228.833531)
		(end 127.899414 -228.783388)
		(width 0.088646)
		(layer "In11.Cu")
		(net "M_H_CPU1_SB_DQ<25>")
	)
	(arc
		(start 136.919716 -228.45903)
		(mid 136.872037 -228.64193)
		(end 136.741154 -228.778308)
		(width 0.088646)
		(layer "In11.Cu")
		(net "M_H_CPU1_SB_DQ<25>")
	)
	(arc
		(start 127.884682 -228.774752)
		(mid 127.608207 -228.707432)
		(end 127.33401 -228.783388)
		(width 0.088646)
		(layer "In11.Cu")
		(net "M_H_CPU1_SB_DQ<25>")
	)
	(arc
		(start 132.973064 -228.783388)
		(mid 132.785866 -228.833531)
		(end 132.598668 -228.783388)
		(width 0.088646)
		(layer "In11.Cu")
		(net "M_H_CPU1_SB_DQ<25>")
	)
	(arc
		(start 137.202164 -227.969318)
		(mid 136.999878 -228.168299)
		(end 136.919716 -228.440488)
		(width 0.088646)
		(layer "In11.Cu")
		(net "M_H_CPU1_SB_DQ<25>")
	)
	(arc
		(start 136.357868 -228.783388)
		(mid 136.075166 -228.707612)
		(end 135.792464 -228.783388)
		(width 0.088646)
		(layer "In11.Cu")
		(net "M_H_CPU1_SB_DQ<25>")
	)
	(arc
		(start 138.424666 -227.893626)
		(mid 138.278343 -227.912888)
		(end 138.141964 -227.969318)
		(width 0.088646)
		(layer "In11.Cu")
		(net "M_H_CPU1_SB_DQ<25>")
	)
	(arc
		(start 126.011178 -228.778308)
		(mid 125.81565 -228.617728)
		(end 125.684026 -228.401626)
		(width 0.088646)
		(layer "In11.Cu")
		(net "M_H_CPU1_SB_DQ<25>")
	)
	(arc
		(start 135.407654 -228.777292)
		(mid 135.129222 -228.707446)
		(end 134.85241 -228.783388)
		(width 0.088646)
		(layer "In11.Cu")
		(net "M_H_CPU1_SB_DQ<25>")
	)
	(arc
		(start 132.588254 -228.777292)
		(mid 132.309822 -228.707446)
		(end 132.03301 -228.783388)
		(width 0.088646)
		(layer "In11.Cu")
		(net "M_H_CPU1_SB_DQ<25>")
	)
	(segment
		(start 205.596744 -204.116686)
		(end 204.076046 -204.116686)
		(width 0.20066)
		(layer "F.Cu")
		(net "M_H_CPU1_SB_DQ<24>")
	)
	(segment
		(start 204.076046 -204.116686)
		(end 202.971146 -204.116686)
		(width 0.20066)
		(layer "F.Cu")
		(net "M_H_CPU1_SB_DQ<24>")
	)
	(segment
		(start 205.84541 -204.365352)
		(end 205.596744 -204.116686)
		(width 0.20066)
		(layer "F.Cu")
		(net "M_H_CPU1_SB_DQ<24>")
	)
	(segment
		(start 210.028028 -204.11694)
		(end 209.596482 -203.685394)
		(width 0.20066)
		(layer "F.Cu")
		(net "M_H_CPU1_SB_DQ<24>")
	)
	(segment
		(start 209.596482 -203.685394)
		(end 209.186526 -203.685394)
		(width 0.20066)
		(layer "F.Cu")
		(net "M_H_CPU1_SB_DQ<24>")
	)
	(segment
		(start 209.180176 -203.691744)
		(end 207.018382 -203.691744)
		(width 0.1016)
		(layer "F.Cu")
		(net "M_H_CPU1_SB_DQ<24>")
	)
	(segment
		(start 206.320644 -204.365352)
		(end 205.84541 -204.365352)
		(width 0.20066)
		(layer "F.Cu")
		(net "M_H_CPU1_SB_DQ<24>")
	)
	(segment
		(start 207.018382 -203.691744)
		(end 206.971392 -203.691744)
		(width 0.101854)
		(layer "F.Cu")
		(net "M_H_CPU1_SB_DQ<24>")
	)
	(segment
		(start 123.857512 -229.808786)
		(end 123.857512 -229.2731)
		(width 0.20066)
		(layer "F.Cu")
		(net "M_H_CPU1_SB_DQ<24>")
	)
	(segment
		(start 206.971392 -203.691744)
		(end 206.626714 -203.691744)
		(width 0.20066)
		(layer "F.Cu")
		(net "M_H_CPU1_SB_DQ<24>")
	)
	(segment
		(start 206.626714 -203.691744)
		(end 206.508604 -203.809854)
		(width 0.20066)
		(layer "F.Cu")
		(net "M_H_CPU1_SB_DQ<24>")
	)
	(segment
		(start 211.619592 -204.11694)
		(end 210.028028 -204.11694)
		(width 0.20066)
		(layer "F.Cu")
		(net "M_H_CPU1_SB_DQ<24>")
	)
	(segment
		(start 211.619846 -204.116686)
		(end 211.619592 -204.11694)
		(width 0.20066)
		(layer "F.Cu")
		(net "M_H_CPU1_SB_DQ<24>")
	)
	(segment
		(start 209.186526 -203.685394)
		(end 209.180176 -203.691744)
		(width 0.1016)
		(layer "F.Cu")
		(net "M_H_CPU1_SB_DQ<24>")
	)
	(segment
		(start 206.508604 -203.809854)
		(end 206.508604 -204.177392)
		(width 0.20066)
		(layer "F.Cu")
		(net "M_H_CPU1_SB_DQ<24>")
	)
	(segment
		(start 123.857512 -229.2731)
		(end 123.857766 -229.272846)
		(width 0.20066)
		(layer "F.Cu")
		(net "M_H_CPU1_SB_DQ<24>")
	)
	(segment
		(start 206.508604 -204.177392)
		(end 206.320644 -204.365352)
		(width 0.20066)
		(layer "F.Cu")
		(net "M_H_CPU1_SB_DQ<24>")
	)
	(segment
		(start 196.374258 -205.18882)
		(end 196.181218 -204.99578)
		(width 0.18288)
		(layer "In11.Cu")
		(net "M_H_CPU1_SB_DQ<24>")
	)
	(segment
		(start 170.865292 -204.668374)
		(end 170.865292 -204.216762)
		(width 0.18288)
		(layer "In11.Cu")
		(net "M_H_CPU1_SB_DQ<24>")
	)
	(segment
		(start 197.077838 -204.398626)
		(end 196.884798 -204.591666)
		(width 0.18288)
		(layer "In11.Cu")
		(net "M_H_CPU1_SB_DQ<24>")
	)
	(segment
		(start 158.849822 -205.944724)
		(end 158.577026 -205.944724)
		(width 0.18288)
		(layer "In11.Cu")
		(net "M_H_CPU1_SB_DQ<24>")
	)
	(segment
		(start 158.097474 -205.737968)
		(end 157.872684 -205.962758)
		(width 0.18288)
		(layer "In11.Cu")
		(net "M_H_CPU1_SB_DQ<24>")
	)
	(segment
		(start 137.211054 -229.592124)
		(end 137.202164 -229.597204)
		(width 0.088646)
		(layer "In11.Cu")
		(net "M_H_CPU1_SB_DQ<24>")
	)
	(segment
		(start 194.559936 -204.813154)
		(end 193.963036 -204.813154)
		(width 0.18288)
		(layer "In11.Cu")
		(net "M_H_CPU1_SB_DQ<24>")
	)
	(segment
		(start 158.07944 -206.715106)
		(end 157.50413 -207.290416)
		(width 0.18288)
		(layer "In11.Cu")
		(net "M_H_CPU1_SB_DQ<24>")
	)
	(segment
		(start 196.691758 -205.18882)
		(end 196.374258 -205.18882)
		(width 0.18288)
		(layer "In11.Cu")
		(net "M_H_CPU1_SB_DQ<24>")
	)
	(segment
		(start 166.276782 -205.071726)
		(end 166.083742 -204.878686)
		(width 0.18288)
		(layer "In11.Cu")
		(net "M_H_CPU1_SB_DQ<24>")
	)
	(segment
		(start 191.231266 -204.540866)
		(end 191.088772 -204.398372)
		(width 0.18288)
		(layer "In11.Cu")
		(net "M_H_CPU1_SB_DQ<24>")
	)
	(segment
		(start 177.903124 -204.34681)
		(end 177.903124 -204.508354)
		(width 0.18288)
		(layer "In11.Cu")
		(net "M_H_CPU1_SB_DQ<24>")
	)
	(segment
		(start 126.879096 -229.588568)
		(end 126.864364 -229.597204)
		(width 0.088646)
		(layer "In11.Cu")
		(net "M_H_CPU1_SB_DQ<24>")
	)
	(segment
		(start 125.071124 -228.833426)
		(end 124.617226 -228.833426)
		(width 0.088646)
		(layer "In11.Cu")
		(net "M_H_CPU1_SB_DQ<24>")
	)
	(segment
		(start 193.068956 -204.300582)
		(end 193.068956 -204.620114)
		(width 0.18288)
		(layer "In11.Cu")
		(net "M_H_CPU1_SB_DQ<24>")
	)
	(segment
		(start 188.039248 -204.54239)
		(end 187.974986 -204.542136)
		(width 0.18288)
		(layer "In11.Cu")
		(net "M_H_CPU1_SB_DQ<24>")
	)
	(segment
		(start 158.577026 -205.944724)
		(end 158.37027 -205.737968)
		(width 0.18288)
		(layer "In11.Cu")
		(net "M_H_CPU1_SB_DQ<24>")
	)
	(segment
		(start 177.903124 -204.508354)
		(end 177.710084 -204.701394)
		(width 0.18288)
		(layer "In11.Cu")
		(net "M_H_CPU1_SB_DQ<24>")
	)
	(segment
		(start 180.92039 -204.904594)
		(end 180.490622 -204.474826)
		(width 0.18288)
		(layer "In11.Cu")
		(net "M_H_CPU1_SB_DQ<24>")
	)
	(segment
		(start 166.787322 -204.878686)
		(end 166.594282 -205.071726)
		(width 0.18288)
		(layer "In11.Cu")
		(net "M_H_CPU1_SB_DQ<24>")
	)
	(segment
		(start 173.972474 -205.083156)
		(end 173.779434 -204.890116)
		(width 0.18288)
		(layer "In11.Cu")
		(net "M_H_CPU1_SB_DQ<24>")
	)
	(segment
		(start 129.693924 -229.591108)
		(end 129.68351 -229.597204)
		(width 0.088646)
		(layer "In11.Cu")
		(net "M_H_CPU1_SB_DQ<24>")
	)
	(segment
		(start 175.452024 -204.382624)
		(end 174.676054 -204.382624)
		(width 0.18288)
		(layer "In11.Cu")
		(net "M_H_CPU1_SB_DQ<24>")
	)
	(segment
		(start 196.181218 -204.99578)
		(end 196.181218 -204.591666)
		(width 0.18288)
		(layer "In11.Cu")
		(net "M_H_CPU1_SB_DQ<24>")
	)
	(segment
		(start 143.08836 -223.216724)
		(end 143.08836 -224.224088)
		(width 0.18288)
		(layer "In11.Cu")
		(net "M_H_CPU1_SB_DQ<24>")
	)
	(segment
		(start 193.068956 -204.620114)
		(end 192.875916 -204.813154)
		(width 0.18288)
		(layer "In11.Cu")
		(net "M_H_CPU1_SB_DQ<24>")
	)
	(segment
		(start 173.022514 -204.540866)
		(end 172.252386 -204.540866)
		(width 0.18288)
		(layer "In11.Cu")
		(net "M_H_CPU1_SB_DQ<24>")
	)
	(segment
		(start 183.265318 -204.703426)
		(end 183.036718 -204.474826)
		(width 0.18288)
		(layer "In11.Cu")
		(net "M_H_CPU1_SB_DQ<24>")
	)
	(segment
		(start 192.445386 -204.813154)
		(end 192.173098 -204.540866)
		(width 0.18288)
		(layer "In11.Cu")
		(net "M_H_CPU1_SB_DQ<24>")
	)
	(segment
		(start 174.483014 -204.890116)
		(end 174.289974 -205.083156)
		(width 0.18288)
		(layer "In11.Cu")
		(net "M_H_CPU1_SB_DQ<24>")
	)
	(segment
		(start 198.479664 -204.398626)
		(end 197.077838 -204.398626)
		(width 0.18288)
		(layer "In11.Cu")
		(net "M_H_CPU1_SB_DQ<24>")
	)
	(segment
		(start 196.884798 -204.99578)
		(end 196.691758 -205.18882)
		(width 0.18288)
		(layer "In11.Cu")
		(net "M_H_CPU1_SB_DQ<24>")
	)
	(segment
		(start 187.034424 -204.541628)
		(end 186.872626 -204.703426)
		(width 0.18288)
		(layer "In11.Cu")
		(net "M_H_CPU1_SB_DQ<24>")
	)
	(segment
		(start 202.391772 -204.728826)
		(end 198.809864 -204.728826)
		(width 0.18288)
		(layer "In11.Cu")
		(net "M_H_CPU1_SB_DQ<24>")
	)
	(segment
		(start 125.939296 -229.588568)
		(end 125.924564 -229.597204)
		(width 0.088646)
		(layer "In11.Cu")
		(net "M_H_CPU1_SB_DQ<24>")
	)
	(segment
		(start 180.490622 -204.474826)
		(end 179.862226 -204.474826)
		(width 0.18288)
		(layer "In11.Cu")
		(net "M_H_CPU1_SB_DQ<24>")
	)
	(segment
		(start 187.974986 -204.542136)
		(end 187.756292 -204.541628)
		(width 0.18288)
		(layer "In11.Cu")
		(net "M_H_CPU1_SB_DQ<24>")
	)
	(segment
		(start 137.389616 -229.26294)
		(end 137.389616 -229.272846)
		(width 0.088646)
		(layer "In11.Cu")
		(net "M_H_CPU1_SB_DQ<24>")
	)
	(segment
		(start 178.868324 -204.701394)
		(end 178.675284 -204.508354)
		(width 0.18288)
		(layer "In11.Cu")
		(net "M_H_CPU1_SB_DQ<24>")
	)
	(segment
		(start 178.096164 -204.15377)
		(end 177.903124 -204.34681)
		(width 0.18288)
		(layer "In11.Cu")
		(net "M_H_CPU1_SB_DQ<24>")
	)
	(segment
		(start 193.769996 -204.300582)
		(end 193.576956 -204.107542)
		(width 0.18288)
		(layer "In11.Cu")
		(net "M_H_CPU1_SB_DQ<24>")
	)
	(segment
		(start 139.00658 -228.222302)
		(end 139.00658 -228.407722)
		(width 0.088646)
		(layer "In11.Cu")
		(net "M_H_CPU1_SB_DQ<24>")
	)
	(segment
		(start 157.872684 -205.962758)
		(end 157.872684 -206.235554)
		(width 0.18288)
		(layer "In11.Cu")
		(net "M_H_CPU1_SB_DQ<24>")
	)
	(segment
		(start 128.754378 -229.591108)
		(end 128.743964 -229.597204)
		(width 0.088646)
		(layer "In11.Cu")
		(net "M_H_CPU1_SB_DQ<24>")
	)
	(segment
		(start 160.748726 -204.703426)
		(end 160.443926 -204.398626)
		(width 0.18288)
		(layer "In11.Cu")
		(net "M_H_CPU1_SB_DQ<24>")
	)
	(segment
		(start 177.436018 -204.701394)
		(end 177.276506 -204.541882)
		(width 0.18288)
		(layer "In11.Cu")
		(net "M_H_CPU1_SB_DQ<24>")
	)
	(segment
		(start 130.638296 -229.588568)
		(end 130.623564 -229.597204)
		(width 0.088646)
		(layer "In11.Cu")
		(net "M_H_CPU1_SB_DQ<24>")
	)
	(segment
		(start 170.672252 -204.023722)
		(end 170.354752 -204.023722)
		(width 0.18288)
		(layer "In11.Cu")
		(net "M_H_CPU1_SB_DQ<24>")
	)
	(segment
		(start 170.865292 -204.216762)
		(end 170.672252 -204.023722)
		(width 0.18288)
		(layer "In11.Cu")
		(net "M_H_CPU1_SB_DQ<24>")
	)
	(segment
		(start 193.963036 -204.813154)
		(end 193.769996 -204.620114)
		(width 0.18288)
		(layer "In11.Cu")
		(net "M_H_CPU1_SB_DQ<24>")
	)
	(segment
		(start 162.833304 -204.347826)
		(end 162.477704 -204.703426)
		(width 0.18288)
		(layer "In11.Cu")
		(net "M_H_CPU1_SB_DQ<24>")
	)
	(segment
		(start 165.890702 -204.398626)
		(end 164.749226 -204.398626)
		(width 0.18288)
		(layer "In11.Cu")
		(net "M_H_CPU1_SB_DQ<24>")
	)
	(segment
		(start 177.276506 -204.541882)
		(end 175.611282 -204.541882)
		(width 0.18288)
		(layer "In11.Cu")
		(net "M_H_CPU1_SB_DQ<24>")
	)
	(segment
		(start 124.070872 -229.05974)
		(end 123.857766 -229.272846)
		(width 0.088646)
		(layer "In11.Cu")
		(net "M_H_CPU1_SB_DQ<24>")
	)
	(segment
		(start 196.884798 -204.591666)
		(end 196.884798 -204.99578)
		(width 0.18288)
		(layer "In11.Cu")
		(net "M_H_CPU1_SB_DQ<24>")
	)
	(segment
		(start 164.444426 -204.703426)
		(end 163.811204 -204.703426)
		(width 0.18288)
		(layer "In11.Cu")
		(net "M_H_CPU1_SB_DQ<24>")
	)
	(segment
		(start 166.083742 -204.591666)
		(end 165.890702 -204.398626)
		(width 0.18288)
		(layer "In11.Cu")
		(net "M_H_CPU1_SB_DQ<24>")
	)
	(segment
		(start 139.59332 -227.039424)
		(end 139.59332 -227.635562)
		(width 0.088646)
		(layer "In11.Cu")
		(net "M_H_CPU1_SB_DQ<24>")
	)
	(segment
		(start 125.362462 -229.272846)
		(end 125.362462 -229.124764)
		(width 0.088646)
		(layer "In11.Cu")
		(net "M_H_CPU1_SB_DQ<24>")
	)
	(segment
		(start 170.161712 -204.668374)
		(end 169.968672 -204.861414)
		(width 0.18288)
		(layer "In11.Cu")
		(net "M_H_CPU1_SB_DQ<24>")
	)
	(segment
		(start 178.482244 -204.15377)
		(end 178.096164 -204.15377)
		(width 0.18288)
		(layer "In11.Cu")
		(net "M_H_CPU1_SB_DQ<24>")
	)
	(segment
		(start 195.988178 -204.398626)
		(end 194.974464 -204.398626)
		(width 0.18288)
		(layer "In11.Cu")
		(net "M_H_CPU1_SB_DQ<24>")
	)
	(segment
		(start 173.180756 -204.382624)
		(end 173.022514 -204.540866)
		(width 0.18288)
		(layer "In11.Cu")
		(net "M_H_CPU1_SB_DQ<24>")
	)
	(segment
		(start 139.813538 -226.819206)
		(end 139.59332 -227.039424)
		(width 0.088646)
		(layer "In11.Cu")
		(net "M_H_CPU1_SB_DQ<24>")
	)
	(segment
		(start 169.968672 -204.861414)
		(end 168.869614 -204.861414)
		(width 0.18288)
		(layer "In11.Cu")
		(net "M_H_CPU1_SB_DQ<24>")
	)
	(segment
		(start 202.971146 -204.116686)
		(end 202.971146 -204.43571)
		(width 0.18288)
		(layer "In11.Cu")
		(net "M_H_CPU1_SB_DQ<24>")
	)
	(segment
		(start 168.869614 -204.861414)
		(end 168.406826 -204.398626)
		(width 0.18288)
		(layer "In11.Cu")
		(net "M_H_CPU1_SB_DQ<24>")
	)
	(segment
		(start 163.811204 -204.703426)
		(end 163.455604 -204.347826)
		(width 0.18288)
		(layer "In11.Cu")
		(net "M_H_CPU1_SB_DQ<24>")
	)
	(segment
		(start 160.443926 -204.398626)
		(end 159.743902 -204.398626)
		(width 0.18288)
		(layer "In11.Cu")
		(net "M_H_CPU1_SB_DQ<24>")
	)
	(segment
		(start 166.594282 -205.071726)
		(end 166.276782 -205.071726)
		(width 0.18288)
		(layer "In11.Cu")
		(net "M_H_CPU1_SB_DQ<24>")
	)
	(segment
		(start 156.602684 -207.290416)
		(end 149.906736 -213.986364)
		(width 0.18288)
		(layer "In11.Cu")
		(net "M_H_CPU1_SB_DQ<24>")
	)
	(segment
		(start 173.779434 -204.890116)
		(end 173.779434 -204.575664)
		(width 0.18288)
		(layer "In11.Cu")
		(net "M_H_CPU1_SB_DQ<24>")
	)
	(segment
		(start 149.906736 -216.398348)
		(end 143.08836 -223.216724)
		(width 0.18288)
		(layer "In11.Cu")
		(net "M_H_CPU1_SB_DQ<24>")
	)
	(segment
		(start 132.517896 -229.588568)
		(end 132.503164 -229.597204)
		(width 0.088646)
		(layer "In11.Cu")
		(net "M_H_CPU1_SB_DQ<24>")
	)
	(segment
		(start 196.181218 -204.591666)
		(end 195.988178 -204.398626)
		(width 0.18288)
		(layer "In11.Cu")
		(net "M_H_CPU1_SB_DQ<24>")
	)
	(segment
		(start 194.974464 -204.398626)
		(end 194.559936 -204.813154)
		(width 0.18288)
		(layer "In11.Cu")
		(net "M_H_CPU1_SB_DQ<24>")
	)
	(segment
		(start 174.483014 -204.575664)
		(end 174.483014 -204.890116)
		(width 0.18288)
		(layer "In11.Cu")
		(net "M_H_CPU1_SB_DQ<24>")
	)
	(segment
		(start 181.480206 -204.904594)
		(end 180.92039 -204.904594)
		(width 0.18288)
		(layer "In11.Cu")
		(net "M_H_CPU1_SB_DQ<24>")
	)
	(segment
		(start 158.37027 -205.737968)
		(end 158.097474 -205.737968)
		(width 0.18288)
		(layer "In11.Cu")
		(net "M_H_CPU1_SB_DQ<24>")
	)
	(segment
		(start 140.163042 -226.819206)
		(end 139.813538 -226.819206)
		(width 0.088646)
		(layer "In11.Cu")
		(net "M_H_CPU1_SB_DQ<24>")
	)
	(segment
		(start 139.00658 -228.407722)
		(end 138.689842 -228.724206)
		(width 0.088646)
		(layer "In11.Cu")
		(net "M_H_CPU1_SB_DQ<24>")
	)
	(segment
		(start 170.354752 -204.023722)
		(end 170.161712 -204.216762)
		(width 0.18288)
		(layer "In11.Cu")
		(net "M_H_CPU1_SB_DQ<24>")
	)
	(segment
		(start 192.875916 -204.813154)
		(end 192.445386 -204.813154)
		(width 0.18288)
		(layer "In11.Cu")
		(net "M_H_CPU1_SB_DQ<24>")
	)
	(segment
		(start 159.743902 -204.398626)
		(end 159.249618 -204.89291)
		(width 0.18288)
		(layer "In11.Cu")
		(net "M_H_CPU1_SB_DQ<24>")
	)
	(segment
		(start 178.675284 -204.34681)
		(end 178.482244 -204.15377)
		(width 0.18288)
		(layer "In11.Cu")
		(net "M_H_CPU1_SB_DQ<24>")
	)
	(segment
		(start 157.50413 -207.290416)
		(end 156.602684 -207.290416)
		(width 0.18288)
		(layer "In11.Cu")
		(net "M_H_CPU1_SB_DQ<24>")
	)
	(segment
		(start 166.980362 -204.398626)
		(end 166.787322 -204.591666)
		(width 0.18288)
		(layer "In11.Cu")
		(net "M_H_CPU1_SB_DQ<24>")
	)
	(segment
		(start 198.809864 -204.728826)
		(end 198.479664 -204.398626)
		(width 0.18288)
		(layer "In11.Cu")
		(net "M_H_CPU1_SB_DQ<24>")
	)
	(segment
		(start 187.756292 -204.541628)
		(end 187.034424 -204.541628)
		(width 0.18288)
		(layer "In11.Cu")
		(net "M_H_CPU1_SB_DQ<24>")
	)
	(segment
		(start 170.161712 -204.216762)
		(end 170.161712 -204.668374)
		(width 0.18288)
		(layer "In11.Cu")
		(net "M_H_CPU1_SB_DQ<24>")
	)
	(segment
		(start 171.931838 -204.861414)
		(end 171.058332 -204.861414)
		(width 0.18288)
		(layer "In11.Cu")
		(net "M_H_CPU1_SB_DQ<24>")
	)
	(segment
		(start 192.173098 -204.540866)
		(end 191.231266 -204.540866)
		(width 0.18288)
		(layer "In11.Cu")
		(net "M_H_CPU1_SB_DQ<24>")
	)
	(segment
		(start 172.252386 -204.540866)
		(end 171.931838 -204.861414)
		(width 0.18288)
		(layer "In11.Cu")
		(net "M_H_CPU1_SB_DQ<24>")
	)
	(segment
		(start 159.249618 -204.89291)
		(end 159.249618 -205.544928)
		(width 0.18288)
		(layer "In11.Cu")
		(net "M_H_CPU1_SB_DQ<24>")
	)
	(segment
		(start 177.710084 -204.701394)
		(end 177.436018 -204.701394)
		(width 0.18288)
		(layer "In11.Cu")
		(net "M_H_CPU1_SB_DQ<24>")
	)
	(segment
		(start 175.611282 -204.541882)
		(end 175.452024 -204.382624)
		(width 0.18288)
		(layer "In11.Cu")
		(net "M_H_CPU1_SB_DQ<24>")
	)
	(segment
		(start 179.862226 -204.474826)
		(end 179.635658 -204.701394)
		(width 0.18288)
		(layer "In11.Cu")
		(net "M_H_CPU1_SB_DQ<24>")
	)
	(segment
		(start 183.036718 -204.474826)
		(end 181.909974 -204.474826)
		(width 0.18288)
		(layer "In11.Cu")
		(net "M_H_CPU1_SB_DQ<24>")
	)
	(segment
		(start 174.676054 -204.382624)
		(end 174.483014 -204.575664)
		(width 0.18288)
		(layer "In11.Cu")
		(net "M_H_CPU1_SB_DQ<24>")
	)
	(segment
		(start 140.493242 -226.819206)
		(end 140.163042 -226.819206)
		(width 0.18288)
		(layer "In11.Cu")
		(net "M_H_CPU1_SB_DQ<24>")
	)
	(segment
		(start 173.779434 -204.575664)
		(end 173.586394 -204.382624)
		(width 0.18288)
		(layer "In11.Cu")
		(net "M_H_CPU1_SB_DQ<24>")
	)
	(segment
		(start 193.261996 -204.107542)
		(end 193.068956 -204.300582)
		(width 0.18288)
		(layer "In11.Cu")
		(net "M_H_CPU1_SB_DQ<24>")
	)
	(segment
		(start 202.971146 -204.43571)
		(end 202.880468 -204.526388)
		(width 0.18288)
		(layer "In11.Cu")
		(net "M_H_CPU1_SB_DQ<24>")
	)
	(segment
		(start 139.59332 -227.635562)
		(end 139.00658 -228.222302)
		(width 0.088646)
		(layer "In11.Cu")
		(net "M_H_CPU1_SB_DQ<24>")
	)
	(segment
		(start 171.058332 -204.861414)
		(end 170.865292 -204.668374)
		(width 0.18288)
		(layer "In11.Cu")
		(net "M_H_CPU1_SB_DQ<24>")
	)
	(segment
		(start 164.749226 -204.398626)
		(end 164.444426 -204.703426)
		(width 0.18288)
		(layer "In11.Cu")
		(net "M_H_CPU1_SB_DQ<24>")
	)
	(segment
		(start 179.635658 -204.701394)
		(end 178.868324 -204.701394)
		(width 0.18288)
		(layer "In11.Cu")
		(net "M_H_CPU1_SB_DQ<24>")
	)
	(segment
		(start 166.787322 -204.591666)
		(end 166.787322 -204.878686)
		(width 0.18288)
		(layer "In11.Cu")
		(net "M_H_CPU1_SB_DQ<24>")
	)
	(segment
		(start 149.906736 -213.986364)
		(end 149.906736 -216.398348)
		(width 0.18288)
		(layer "In11.Cu")
		(net "M_H_CPU1_SB_DQ<24>")
	)
	(segment
		(start 178.675284 -204.508354)
		(end 178.675284 -204.34681)
		(width 0.18288)
		(layer "In11.Cu")
		(net "M_H_CPU1_SB_DQ<24>")
	)
	(segment
		(start 127.818896 -229.588568)
		(end 127.804164 -229.597204)
		(width 0.088646)
		(layer "In11.Cu")
		(net "M_H_CPU1_SB_DQ<24>")
	)
	(segment
		(start 168.406826 -204.398626)
		(end 166.980362 -204.398626)
		(width 0.18288)
		(layer "In11.Cu")
		(net "M_H_CPU1_SB_DQ<24>")
	)
	(segment
		(start 162.477704 -204.703426)
		(end 160.748726 -204.703426)
		(width 0.18288)
		(layer "In11.Cu")
		(net "M_H_CPU1_SB_DQ<24>")
	)
	(segment
		(start 202.880468 -204.526388)
		(end 202.391772 -204.728826)
		(width 0.18288)
		(layer "In11.Cu")
		(net "M_H_CPU1_SB_DQ<24>")
	)
	(segment
		(start 163.455604 -204.347826)
		(end 162.833304 -204.347826)
		(width 0.18288)
		(layer "In11.Cu")
		(net "M_H_CPU1_SB_DQ<24>")
	)
	(segment
		(start 189.938152 -204.54239)
		(end 188.039248 -204.54239)
		(width 0.18288)
		(layer "In11.Cu")
		(net "M_H_CPU1_SB_DQ<24>")
	)
	(segment
		(start 190.08217 -204.398372)
		(end 189.938152 -204.54239)
		(width 0.18288)
		(layer "In11.Cu")
		(net "M_H_CPU1_SB_DQ<24>")
	)
	(segment
		(start 186.872626 -204.703426)
		(end 183.265318 -204.703426)
		(width 0.18288)
		(layer "In11.Cu")
		(net "M_H_CPU1_SB_DQ<24>")
	)
	(segment
		(start 173.586394 -204.382624)
		(end 173.180756 -204.382624)
		(width 0.18288)
		(layer "In11.Cu")
		(net "M_H_CPU1_SB_DQ<24>")
	)
	(segment
		(start 193.769996 -204.620114)
		(end 193.769996 -204.300582)
		(width 0.18288)
		(layer "In11.Cu")
		(net "M_H_CPU1_SB_DQ<24>")
	)
	(segment
		(start 166.083742 -204.878686)
		(end 166.083742 -204.591666)
		(width 0.18288)
		(layer "In11.Cu")
		(net "M_H_CPU1_SB_DQ<24>")
	)
	(segment
		(start 143.08836 -224.224088)
		(end 140.493242 -226.819206)
		(width 0.18288)
		(layer "In11.Cu")
		(net "M_H_CPU1_SB_DQ<24>")
	)
	(segment
		(start 174.289974 -205.083156)
		(end 173.972474 -205.083156)
		(width 0.18288)
		(layer "In11.Cu")
		(net "M_H_CPU1_SB_DQ<24>")
	)
	(segment
		(start 157.872684 -206.235554)
		(end 158.07944 -206.44231)
		(width 0.18288)
		(layer "In11.Cu")
		(net "M_H_CPU1_SB_DQ<24>")
	)
	(segment
		(start 191.088772 -204.398372)
		(end 190.08217 -204.398372)
		(width 0.18288)
		(layer "In11.Cu")
		(net "M_H_CPU1_SB_DQ<24>")
	)
	(segment
		(start 193.576956 -204.107542)
		(end 193.261996 -204.107542)
		(width 0.18288)
		(layer "In11.Cu")
		(net "M_H_CPU1_SB_DQ<24>")
	)
	(segment
		(start 158.07944 -206.44231)
		(end 158.07944 -206.715106)
		(width 0.18288)
		(layer "In11.Cu")
		(net "M_H_CPU1_SB_DQ<24>")
	)
	(segment
		(start 181.909974 -204.474826)
		(end 181.480206 -204.904594)
		(width 0.18288)
		(layer "In11.Cu")
		(net "M_H_CPU1_SB_DQ<24>")
	)
	(segment
		(start 159.249618 -205.544928)
		(end 158.849822 -205.944724)
		(width 0.18288)
		(layer "In11.Cu")
		(net "M_H_CPU1_SB_DQ<24>")
	)
	(arc
		(start 130.249168 -229.597204)
		(mid 129.972355 -229.521334)
		(end 129.693924 -229.591108)
		(width 0.088646)
		(layer "In11.Cu")
		(net "M_H_CPU1_SB_DQ<24>")
	)
	(arc
		(start 134.382764 -229.597204)
		(mid 134.195566 -229.647347)
		(end 134.008368 -229.597204)
		(width 0.088646)
		(layer "In11.Cu")
		(net "M_H_CPU1_SB_DQ<24>")
	)
	(arc
		(start 135.322564 -229.597204)
		(mid 135.135366 -229.647347)
		(end 134.948168 -229.597204)
		(width 0.088646)
		(layer "In11.Cu")
		(net "M_H_CPU1_SB_DQ<24>")
	)
	(arc
		(start 137.672064 -228.783388)
		(mid 137.467729 -228.985993)
		(end 137.389616 -229.26294)
		(width 0.088646)
		(layer "In11.Cu")
		(net "M_H_CPU1_SB_DQ<24>")
	)
	(arc
		(start 128.743964 -229.597204)
		(mid 128.556766 -229.647347)
		(end 128.369568 -229.597204)
		(width 0.088646)
		(layer "In11.Cu")
		(net "M_H_CPU1_SB_DQ<24>")
	)
	(arc
		(start 127.429768 -229.597204)
		(mid 127.155569 -229.521369)
		(end 126.879096 -229.588568)
		(width 0.088646)
		(layer "In11.Cu")
		(net "M_H_CPU1_SB_DQ<24>")
	)
	(arc
		(start 129.309114 -229.597204)
		(mid 129.032555 -229.521461)
		(end 128.754378 -229.591108)
		(width 0.088646)
		(layer "In11.Cu")
		(net "M_H_CPU1_SB_DQ<24>")
	)
	(arc
		(start 134.008368 -229.597204)
		(mid 133.725666 -229.521428)
		(end 133.442964 -229.597204)
		(width 0.088646)
		(layer "In11.Cu")
		(net "M_H_CPU1_SB_DQ<24>")
	)
	(arc
		(start 137.389616 -229.272846)
		(mid 137.341937 -229.455746)
		(end 137.211054 -229.592124)
		(width 0.088646)
		(layer "In11.Cu")
		(net "M_H_CPU1_SB_DQ<24>")
	)
	(arc
		(start 125.550168 -229.597204)
		(mid 125.412946 -229.460122)
		(end 125.362462 -229.272846)
		(width 0.088646)
		(layer "In11.Cu")
		(net "M_H_CPU1_SB_DQ<24>")
	)
	(arc
		(start 134.948168 -229.597204)
		(mid 134.665466 -229.521428)
		(end 134.382764 -229.597204)
		(width 0.088646)
		(layer "In11.Cu")
		(net "M_H_CPU1_SB_DQ<24>")
	)
	(arc
		(start 127.804164 -229.597204)
		(mid 127.616966 -229.647347)
		(end 127.429768 -229.597204)
		(width 0.088646)
		(layer "In11.Cu")
		(net "M_H_CPU1_SB_DQ<24>")
	)
	(arc
		(start 138.237468 -228.783388)
		(mid 137.954766 -228.707612)
		(end 137.672064 -228.783388)
		(width 0.088646)
		(layer "In11.Cu")
		(net "M_H_CPU1_SB_DQ<24>")
	)
	(arc
		(start 126.489968 -229.597204)
		(mid 126.215769 -229.521369)
		(end 125.939296 -229.588568)
		(width 0.088646)
		(layer "In11.Cu")
		(net "M_H_CPU1_SB_DQ<24>")
	)
	(arc
		(start 128.369568 -229.597204)
		(mid 128.095369 -229.521369)
		(end 127.818896 -229.588568)
		(width 0.088646)
		(layer "In11.Cu")
		(net "M_H_CPU1_SB_DQ<24>")
	)
	(arc
		(start 125.924564 -229.597204)
		(mid 125.737366 -229.647347)
		(end 125.550168 -229.597204)
		(width 0.088646)
		(layer "In11.Cu")
		(net "M_H_CPU1_SB_DQ<24>")
	)
	(arc
		(start 132.128768 -229.597204)
		(mid 131.846066 -229.521428)
		(end 131.563364 -229.597204)
		(width 0.088646)
		(layer "In11.Cu")
		(net "M_H_CPU1_SB_DQ<24>")
	)
	(arc
		(start 136.262364 -229.597204)
		(mid 136.075166 -229.647347)
		(end 135.887968 -229.597204)
		(width 0.088646)
		(layer "In11.Cu")
		(net "M_H_CPU1_SB_DQ<24>")
	)
	(arc
		(start 124.617226 -228.833426)
		(mid 124.321539 -228.892242)
		(end 124.070872 -229.05974)
		(width 0.088646)
		(layer "In11.Cu")
		(net "M_H_CPU1_SB_DQ<24>")
	)
	(arc
		(start 132.503164 -229.597204)
		(mid 132.315966 -229.647347)
		(end 132.128768 -229.597204)
		(width 0.088646)
		(layer "In11.Cu")
		(net "M_H_CPU1_SB_DQ<24>")
	)
	(arc
		(start 126.864364 -229.597204)
		(mid 126.677166 -229.647347)
		(end 126.489968 -229.597204)
		(width 0.088646)
		(layer "In11.Cu")
		(net "M_H_CPU1_SB_DQ<24>")
	)
	(arc
		(start 136.827768 -229.597204)
		(mid 136.545066 -229.521428)
		(end 136.262364 -229.597204)
		(width 0.088646)
		(layer "In11.Cu")
		(net "M_H_CPU1_SB_DQ<24>")
	)
	(arc
		(start 135.887968 -229.597204)
		(mid 135.605266 -229.521428)
		(end 135.322564 -229.597204)
		(width 0.088646)
		(layer "In11.Cu")
		(net "M_H_CPU1_SB_DQ<24>")
	)
	(arc
		(start 125.362462 -229.124764)
		(mid 125.277131 -228.918757)
		(end 125.071124 -228.833426)
		(width 0.088646)
		(layer "In11.Cu")
		(net "M_H_CPU1_SB_DQ<24>")
	)
	(arc
		(start 133.442964 -229.597204)
		(mid 133.255766 -229.647347)
		(end 133.068568 -229.597204)
		(width 0.088646)
		(layer "In11.Cu")
		(net "M_H_CPU1_SB_DQ<24>")
	)
	(arc
		(start 131.188968 -229.597204)
		(mid 130.914769 -229.521369)
		(end 130.638296 -229.588568)
		(width 0.088646)
		(layer "In11.Cu")
		(net "M_H_CPU1_SB_DQ<24>")
	)
	(arc
		(start 130.623564 -229.597204)
		(mid 130.436366 -229.647347)
		(end 130.249168 -229.597204)
		(width 0.088646)
		(layer "In11.Cu")
		(net "M_H_CPU1_SB_DQ<24>")
	)
	(arc
		(start 131.563364 -229.597204)
		(mid 131.376166 -229.647347)
		(end 131.188968 -229.597204)
		(width 0.088646)
		(layer "In11.Cu")
		(net "M_H_CPU1_SB_DQ<24>")
	)
	(arc
		(start 138.689842 -228.724206)
		(mid 138.652792 -228.756352)
		(end 138.611864 -228.783388)
		(width 0.088646)
		(layer "In11.Cu")
		(net "M_H_CPU1_SB_DQ<24>")
	)
	(arc
		(start 129.68351 -229.597204)
		(mid 129.496312 -229.647347)
		(end 129.309114 -229.597204)
		(width 0.088646)
		(layer "In11.Cu")
		(net "M_H_CPU1_SB_DQ<24>")
	)
	(arc
		(start 133.068568 -229.597204)
		(mid 132.794369 -229.521369)
		(end 132.517896 -229.588568)
		(width 0.088646)
		(layer "In11.Cu")
		(net "M_H_CPU1_SB_DQ<24>")
	)
	(arc
		(start 137.202164 -229.597204)
		(mid 137.014966 -229.647347)
		(end 136.827768 -229.597204)
		(width 0.088646)
		(layer "In11.Cu")
		(net "M_H_CPU1_SB_DQ<24>")
	)
	(arc
		(start 138.611864 -228.783388)
		(mid 138.424666 -228.833531)
		(end 138.237468 -228.783388)
		(width 0.088646)
		(layer "In11.Cu")
		(net "M_H_CPU1_SB_DQ<24>")
	)
	(segment
		(start 210.610196 -205.391512)
		(end 212.618066 -205.391512)
		(width 0.1016)
		(layer "F.Cu")
		(net "M_H_CPU1_SB_DQ<23>")
	)
	(segment
		(start 209.874358 -204.96657)
		(end 210.306412 -205.398624)
		(width 0.20066)
		(layer "F.Cu")
		(net "M_H_CPU1_SB_DQ<23>")
	)
	(segment
		(start 213.749636 -204.714602)
		(end 214.133684 -204.714602)
		(width 0.20066)
		(layer "F.Cu")
		(net "M_H_CPU1_SB_DQ<23>")
	)
	(segment
		(start 210.603084 -205.398624)
		(end 210.610196 -205.391512)
		(width 0.1016)
		(layer "F.Cu")
		(net "M_H_CPU1_SB_DQ<23>")
	)
	(segment
		(start 213.311486 -205.403704)
		(end 213.515448 -205.199742)
		(width 0.20066)
		(layer "F.Cu")
		(net "M_H_CPU1_SB_DQ<23>")
	)
	(segment
		(start 212.630258 -205.403704)
		(end 213.311486 -205.403704)
		(width 0.20066)
		(layer "F.Cu")
		(net "M_H_CPU1_SB_DQ<23>")
	)
	(segment
		(start 207.071214 -204.96657)
		(end 208.176114 -204.96657)
		(width 0.20066)
		(layer "F.Cu")
		(net "M_H_CPU1_SB_DQ<23>")
	)
	(segment
		(start 210.306412 -205.398624)
		(end 210.598258 -205.398624)
		(width 0.20066)
		(layer "F.Cu")
		(net "M_H_CPU1_SB_DQ<23>")
	)
	(segment
		(start 212.618066 -205.391512)
		(end 212.630258 -205.403704)
		(width 0.1016)
		(layer "F.Cu")
		(net "M_H_CPU1_SB_DQ<23>")
	)
	(segment
		(start 214.385652 -204.96657)
		(end 215.719914 -204.96657)
		(width 0.20066)
		(layer "F.Cu")
		(net "M_H_CPU1_SB_DQ<23>")
	)
	(segment
		(start 214.133684 -204.714602)
		(end 214.385652 -204.96657)
		(width 0.20066)
		(layer "F.Cu")
		(net "M_H_CPU1_SB_DQ<23>")
	)
	(segment
		(start 128.086866 -228.99497)
		(end 128.086612 -228.994716)
		(width 0.20066)
		(layer "F.Cu")
		(net "M_H_CPU1_SB_DQ<23>")
	)
	(segment
		(start 128.086612 -228.994716)
		(end 128.086612 -228.45903)
		(width 0.20066)
		(layer "F.Cu")
		(net "M_H_CPU1_SB_DQ<23>")
	)
	(segment
		(start 210.598258 -205.398624)
		(end 210.603084 -205.398624)
		(width 0.101854)
		(layer "F.Cu")
		(net "M_H_CPU1_SB_DQ<23>")
	)
	(segment
		(start 208.176114 -204.96657)
		(end 209.874358 -204.96657)
		(width 0.20066)
		(layer "F.Cu")
		(net "M_H_CPU1_SB_DQ<23>")
	)
	(segment
		(start 213.515448 -204.94879)
		(end 213.749636 -204.714602)
		(width 0.20066)
		(layer "F.Cu")
		(net "M_H_CPU1_SB_DQ<23>")
	)
	(segment
		(start 213.515448 -205.199742)
		(end 213.515448 -204.94879)
		(width 0.20066)
		(layer "F.Cu")
		(net "M_H_CPU1_SB_DQ<23>")
	)
	(segment
		(start 200.33869 -203.993242)
		(end 200.33869 -204.35951)
		(width 0.18288)
		(layer "In6.Cu")
		(net "M_H_CPU1_SB_DQ<23>")
	)
	(segment
		(start 129.779014 -227.155502)
		(end 129.764282 -227.146866)
		(width 0.088646)
		(layer "In6.Cu")
		(net "M_H_CPU1_SB_DQ<23>")
	)
	(segment
		(start 132.598414 -227.155502)
		(end 132.583682 -227.146866)
		(width 0.088646)
		(layer "In6.Cu")
		(net "M_H_CPU1_SB_DQ<23>")
	)
	(segment
		(start 134.478014 -227.155502)
		(end 134.4676 -227.149406)
		(width 0.088646)
		(layer "In6.Cu")
		(net "M_H_CPU1_SB_DQ<23>")
	)
	(segment
		(start 201.03211 -203.993242)
		(end 200.84923 -203.810362)
		(width 0.18288)
		(layer "In6.Cu")
		(net "M_H_CPU1_SB_DQ<23>")
	)
	(segment
		(start 205.468982 -206.065882)
		(end 203.94549 -204.54239)
		(width 0.18288)
		(layer "In6.Cu")
		(net "M_H_CPU1_SB_DQ<23>")
	)
	(segment
		(start 186.398662 -204.54239)
		(end 185.549794 -205.391258)
		(width 0.18288)
		(layer "In6.Cu")
		(net "M_H_CPU1_SB_DQ<23>")
	)
	(segment
		(start 139.077192 -223.61779)
		(end 138.812778 -223.882204)
		(width 0.18288)
		(layer "In6.Cu")
		(net "M_H_CPU1_SB_DQ<23>")
	)
	(segment
		(start 200.33869 -204.35951)
		(end 200.15581 -204.54239)
		(width 0.18288)
		(layer "In6.Cu")
		(net "M_H_CPU1_SB_DQ<23>")
	)
	(segment
		(start 197.894194 -203.692506)
		(end 191.75857 -203.692506)
		(width 0.18288)
		(layer "In6.Cu")
		(net "M_H_CPU1_SB_DQ<23>")
	)
	(segment
		(start 138.368532 -224.545906)
		(end 137.862818 -225.05162)
		(width 0.088646)
		(layer "In6.Cu")
		(net "M_H_CPU1_SB_DQ<23>")
	)
	(segment
		(start 203.94549 -204.54239)
		(end 201.21499 -204.54239)
		(width 0.18288)
		(layer "In6.Cu")
		(net "M_H_CPU1_SB_DQ<23>")
	)
	(segment
		(start 140.304774 -222.410274)
		(end 140.045694 -222.669354)
		(width 0.18288)
		(layer "In6.Cu")
		(net "M_H_CPU1_SB_DQ<23>")
	)
	(segment
		(start 191.53505 -203.916026)
		(end 189.742826 -203.916026)
		(width 0.18288)
		(layer "In6.Cu")
		(net "M_H_CPU1_SB_DQ<23>")
	)
	(segment
		(start 140.563346 -222.41002)
		(end 140.304774 -222.410274)
		(width 0.18288)
		(layer "In6.Cu")
		(net "M_H_CPU1_SB_DQ<23>")
	)
	(segment
		(start 140.045694 -222.870014)
		(end 140.045948 -223.128078)
		(width 0.18288)
		(layer "In6.Cu")
		(net "M_H_CPU1_SB_DQ<23>")
	)
	(segment
		(start 185.549794 -205.391258)
		(end 178.844194 -205.391258)
		(width 0.18288)
		(layer "In6.Cu")
		(net "M_H_CPU1_SB_DQ<23>")
	)
	(segment
		(start 174.333408 -205.392274)
		(end 161.088324 -205.392274)
		(width 0.18288)
		(layer "In6.Cu")
		(net "M_H_CPU1_SB_DQ<23>")
	)
	(segment
		(start 157.052772 -205.569058)
		(end 152.655524 -209.966306)
		(width 0.18288)
		(layer "In6.Cu")
		(net "M_H_CPU1_SB_DQ<23>")
	)
	(segment
		(start 189.742826 -203.916026)
		(end 188.117226 -204.54239)
		(width 0.18288)
		(layer "In6.Cu")
		(net "M_H_CPU1_SB_DQ<23>")
	)
	(segment
		(start 129.21361 -227.155502)
		(end 129.209292 -227.158042)
		(width 0.088646)
		(layer "In6.Cu")
		(net "M_H_CPU1_SB_DQ<23>")
	)
	(segment
		(start 160.91154 -205.569058)
		(end 157.052772 -205.569058)
		(width 0.18288)
		(layer "In6.Cu")
		(net "M_H_CPU1_SB_DQ<23>")
	)
	(segment
		(start 161.088324 -205.392274)
		(end 160.91154 -205.569058)
		(width 0.18288)
		(layer "In6.Cu")
		(net "M_H_CPU1_SB_DQ<23>")
	)
	(segment
		(start 139.556236 -223.61779)
		(end 139.077192 -223.61779)
		(width 0.18288)
		(layer "In6.Cu")
		(net "M_H_CPU1_SB_DQ<23>")
	)
	(segment
		(start 131.658614 -227.155502)
		(end 131.6482 -227.149406)
		(width 0.088646)
		(layer "In6.Cu")
		(net "M_H_CPU1_SB_DQ<23>")
	)
	(segment
		(start 129.209292 -227.158042)
		(end 129.207514 -227.159058)
		(width 0.088646)
		(layer "In6.Cu")
		(net "M_H_CPU1_SB_DQ<23>")
	)
	(segment
		(start 140.045948 -223.128078)
		(end 139.556236 -223.61779)
		(width 0.18288)
		(layer "In6.Cu")
		(net "M_H_CPU1_SB_DQ<23>")
	)
	(segment
		(start 152.655524 -210.518502)
		(end 140.764006 -222.41002)
		(width 0.18288)
		(layer "In6.Cu")
		(net "M_H_CPU1_SB_DQ<23>")
	)
	(segment
		(start 200.15581 -204.54239)
		(end 198.744078 -204.54239)
		(width 0.18288)
		(layer "In6.Cu")
		(net "M_H_CPU1_SB_DQ<23>")
	)
	(segment
		(start 176.320196 -206.24419)
		(end 175.96231 -205.886304)
		(width 0.18288)
		(layer "In6.Cu")
		(net "M_H_CPU1_SB_DQ<23>")
	)
	(segment
		(start 130.719068 -227.155502)
		(end 130.708654 -227.149406)
		(width 0.088646)
		(layer "In6.Cu")
		(net "M_H_CPU1_SB_DQ<23>")
	)
	(segment
		(start 201.03211 -204.35951)
		(end 201.03211 -203.993242)
		(width 0.18288)
		(layer "In6.Cu")
		(net "M_H_CPU1_SB_DQ<23>")
	)
	(segment
		(start 174.827438 -205.886304)
		(end 174.333408 -205.392274)
		(width 0.18288)
		(layer "In6.Cu")
		(net "M_H_CPU1_SB_DQ<23>")
	)
	(segment
		(start 128.670304 -228.019864)
		(end 128.086612 -228.45903)
		(width 0.088646)
		(layer "In6.Cu")
		(net "M_H_CPU1_SB_DQ<23>")
	)
	(segment
		(start 201.21499 -204.54239)
		(end 201.03211 -204.35951)
		(width 0.18288)
		(layer "In6.Cu")
		(net "M_H_CPU1_SB_DQ<23>")
	)
	(segment
		(start 152.655524 -209.966306)
		(end 152.655524 -210.518502)
		(width 0.18288)
		(layer "In6.Cu")
		(net "M_H_CPU1_SB_DQ<23>")
	)
	(segment
		(start 207.071214 -204.96657)
		(end 205.971902 -206.065882)
		(width 0.18288)
		(layer "In6.Cu")
		(net "M_H_CPU1_SB_DQ<23>")
	)
	(segment
		(start 133.538468 -227.155502)
		(end 133.528054 -227.149406)
		(width 0.088646)
		(layer "In6.Cu")
		(net "M_H_CPU1_SB_DQ<23>")
	)
	(segment
		(start 140.045694 -222.669354)
		(end 140.045694 -222.870014)
		(width 0.18288)
		(layer "In6.Cu")
		(net "M_H_CPU1_SB_DQ<23>")
	)
	(segment
		(start 191.75857 -203.692506)
		(end 191.53505 -203.916026)
		(width 0.18288)
		(layer "In6.Cu")
		(net "M_H_CPU1_SB_DQ<23>")
	)
	(segment
		(start 178.573684 -205.661768)
		(end 177.9778 -205.661768)
		(width 0.18288)
		(layer "In6.Cu")
		(net "M_H_CPU1_SB_DQ<23>")
	)
	(segment
		(start 128.7526 -227.964238)
		(end 128.74371 -227.969318)
		(width 0.088646)
		(layer "In6.Cu")
		(net "M_H_CPU1_SB_DQ<23>")
	)
	(segment
		(start 138.812778 -223.882204)
		(end 138.368532 -224.32645)
		(width 0.088646)
		(layer "In6.Cu")
		(net "M_H_CPU1_SB_DQ<23>")
	)
	(segment
		(start 200.84923 -203.810362)
		(end 200.52157 -203.810362)
		(width 0.18288)
		(layer "In6.Cu")
		(net "M_H_CPU1_SB_DQ<23>")
	)
	(segment
		(start 140.764006 -222.41002)
		(end 140.563346 -222.41002)
		(width 0.18288)
		(layer "In6.Cu")
		(net "M_H_CPU1_SB_DQ<23>")
	)
	(segment
		(start 175.96231 -205.886304)
		(end 174.827438 -205.886304)
		(width 0.18288)
		(layer "In6.Cu")
		(net "M_H_CPU1_SB_DQ<23>")
	)
	(segment
		(start 205.971902 -206.065882)
		(end 205.468982 -206.065882)
		(width 0.18288)
		(layer "In6.Cu")
		(net "M_H_CPU1_SB_DQ<23>")
	)
	(segment
		(start 138.368532 -224.32645)
		(end 138.368532 -224.545906)
		(width 0.088646)
		(layer "In6.Cu")
		(net "M_H_CPU1_SB_DQ<23>")
	)
	(segment
		(start 188.117226 -204.54239)
		(end 186.398662 -204.54239)
		(width 0.18288)
		(layer "In6.Cu")
		(net "M_H_CPU1_SB_DQ<23>")
	)
	(segment
		(start 178.844194 -205.391258)
		(end 178.573684 -205.661768)
		(width 0.18288)
		(layer "In6.Cu")
		(net "M_H_CPU1_SB_DQ<23>")
	)
	(segment
		(start 137.862818 -226.043744)
		(end 136.810242 -227.09632)
		(width 0.088646)
		(layer "In6.Cu")
		(net "M_H_CPU1_SB_DQ<23>")
	)
	(segment
		(start 135.418068 -227.155502)
		(end 135.407654 -227.149406)
		(width 0.088646)
		(layer "In6.Cu")
		(net "M_H_CPU1_SB_DQ<23>")
	)
	(segment
		(start 198.744078 -204.54239)
		(end 197.894194 -203.692506)
		(width 0.18288)
		(layer "In6.Cu")
		(net "M_H_CPU1_SB_DQ<23>")
	)
	(segment
		(start 137.862818 -225.05162)
		(end 137.862818 -226.043744)
		(width 0.088646)
		(layer "In6.Cu")
		(net "M_H_CPU1_SB_DQ<23>")
	)
	(segment
		(start 177.395378 -206.24419)
		(end 176.320196 -206.24419)
		(width 0.18288)
		(layer "In6.Cu")
		(net "M_H_CPU1_SB_DQ<23>")
	)
	(segment
		(start 177.9778 -205.661768)
		(end 177.395378 -206.24419)
		(width 0.18288)
		(layer "In6.Cu")
		(net "M_H_CPU1_SB_DQ<23>")
	)
	(segment
		(start 200.52157 -203.810362)
		(end 200.33869 -203.993242)
		(width 0.18288)
		(layer "In6.Cu")
		(net "M_H_CPU1_SB_DQ<23>")
	)
	(arc
		(start 131.6482 -227.149406)
		(mid 131.370022 -227.079683)
		(end 131.093464 -227.155502)
		(width 0.088646)
		(layer "In6.Cu")
		(net "M_H_CPU1_SB_DQ<23>")
	)
	(arc
		(start 132.97281 -227.155502)
		(mid 132.785612 -227.205645)
		(end 132.598414 -227.155502)
		(width 0.088646)
		(layer "In6.Cu")
		(net "M_H_CPU1_SB_DQ<23>")
	)
	(arc
		(start 135.407654 -227.149406)
		(mid 135.129222 -227.07956)
		(end 134.85241 -227.155502)
		(width 0.088646)
		(layer "In6.Cu")
		(net "M_H_CPU1_SB_DQ<23>")
	)
	(arc
		(start 134.4676 -227.149406)
		(mid 134.189422 -227.079683)
		(end 133.912864 -227.155502)
		(width 0.088646)
		(layer "In6.Cu")
		(net "M_H_CPU1_SB_DQ<23>")
	)
	(arc
		(start 136.357868 -227.155502)
		(mid 136.075166 -227.079726)
		(end 135.792464 -227.155502)
		(width 0.088646)
		(layer "In6.Cu")
		(net "M_H_CPU1_SB_DQ<23>")
	)
	(arc
		(start 129.207514 -227.159058)
		(mid 129.005101 -227.365471)
		(end 128.931162 -227.64496)
		(width 0.088646)
		(layer "In6.Cu")
		(net "M_H_CPU1_SB_DQ<23>")
	)
	(arc
		(start 130.708654 -227.149406)
		(mid 130.430222 -227.07956)
		(end 130.15341 -227.155502)
		(width 0.088646)
		(layer "In6.Cu")
		(net "M_H_CPU1_SB_DQ<23>")
	)
	(arc
		(start 130.15341 -227.155502)
		(mid 129.966212 -227.205645)
		(end 129.779014 -227.155502)
		(width 0.088646)
		(layer "In6.Cu")
		(net "M_H_CPU1_SB_DQ<23>")
	)
	(arc
		(start 132.03301 -227.155502)
		(mid 131.845812 -227.205645)
		(end 131.658614 -227.155502)
		(width 0.088646)
		(layer "In6.Cu")
		(net "M_H_CPU1_SB_DQ<23>")
	)
	(arc
		(start 134.85241 -227.155502)
		(mid 134.665212 -227.205645)
		(end 134.478014 -227.155502)
		(width 0.088646)
		(layer "In6.Cu")
		(net "M_H_CPU1_SB_DQ<23>")
	)
	(arc
		(start 131.093464 -227.155502)
		(mid 130.906266 -227.205645)
		(end 130.719068 -227.155502)
		(width 0.088646)
		(layer "In6.Cu")
		(net "M_H_CPU1_SB_DQ<23>")
	)
	(arc
		(start 129.764282 -227.146866)
		(mid 129.487807 -227.079546)
		(end 129.21361 -227.155502)
		(width 0.088646)
		(layer "In6.Cu")
		(net "M_H_CPU1_SB_DQ<23>")
	)
	(arc
		(start 132.583682 -227.146866)
		(mid 132.307207 -227.079546)
		(end 132.03301 -227.155502)
		(width 0.088646)
		(layer "In6.Cu")
		(net "M_H_CPU1_SB_DQ<23>")
	)
	(arc
		(start 135.792464 -227.155502)
		(mid 135.605266 -227.205645)
		(end 135.418068 -227.155502)
		(width 0.088646)
		(layer "In6.Cu")
		(net "M_H_CPU1_SB_DQ<23>")
	)
	(arc
		(start 128.74371 -227.969318)
		(mid 128.706011 -227.993144)
		(end 128.670304 -228.019864)
		(width 0.088646)
		(layer "In6.Cu")
		(net "M_H_CPU1_SB_DQ<23>")
	)
	(arc
		(start 136.732264 -227.155502)
		(mid 136.545066 -227.205645)
		(end 136.357868 -227.155502)
		(width 0.088646)
		(layer "In6.Cu")
		(net "M_H_CPU1_SB_DQ<23>")
	)
	(arc
		(start 136.810242 -227.09632)
		(mid 136.773192 -227.128466)
		(end 136.732264 -227.155502)
		(width 0.088646)
		(layer "In6.Cu")
		(net "M_H_CPU1_SB_DQ<23>")
	)
	(arc
		(start 133.528054 -227.149406)
		(mid 133.249622 -227.07956)
		(end 132.97281 -227.155502)
		(width 0.088646)
		(layer "In6.Cu")
		(net "M_H_CPU1_SB_DQ<23>")
	)
	(arc
		(start 128.931162 -227.64496)
		(mid 128.883483 -227.82786)
		(end 128.7526 -227.964238)
		(width 0.088646)
		(layer "In6.Cu")
		(net "M_H_CPU1_SB_DQ<23>")
	)
	(arc
		(start 133.912864 -227.155502)
		(mid 133.725666 -227.205645)
		(end 133.538468 -227.155502)
		(width 0.088646)
		(layer "In6.Cu")
		(net "M_H_CPU1_SB_DQ<23>")
	)
	(segment
		(start 212.630258 -207.103726)
		(end 213.311486 -207.103726)
		(width 0.20066)
		(layer "F.Cu")
		(net "M_H_CPU1_SB_DQ<22>")
	)
	(segment
		(start 212.618066 -207.091534)
		(end 212.630258 -207.103726)
		(width 0.1016)
		(layer "F.Cu")
		(net "M_H_CPU1_SB_DQ<22>")
	)
	(segment
		(start 213.515448 -206.899764)
		(end 213.515448 -206.648812)
		(width 0.20066)
		(layer "F.Cu")
		(net "M_H_CPU1_SB_DQ<22>")
	)
	(segment
		(start 210.603084 -207.098646)
		(end 210.610196 -207.091534)
		(width 0.1016)
		(layer "F.Cu")
		(net "M_H_CPU1_SB_DQ<22>")
	)
	(segment
		(start 213.515448 -206.648812)
		(end 213.749636 -206.414624)
		(width 0.20066)
		(layer "F.Cu")
		(net "M_H_CPU1_SB_DQ<22>")
	)
	(segment
		(start 210.598258 -207.098646)
		(end 210.603084 -207.098646)
		(width 0.101854)
		(layer "F.Cu")
		(net "M_H_CPU1_SB_DQ<22>")
	)
	(segment
		(start 213.311486 -207.103726)
		(end 213.515448 -206.899764)
		(width 0.20066)
		(layer "F.Cu")
		(net "M_H_CPU1_SB_DQ<22>")
	)
	(segment
		(start 214.133684 -206.414624)
		(end 214.385652 -206.666592)
		(width 0.20066)
		(layer "F.Cu")
		(net "M_H_CPU1_SB_DQ<22>")
	)
	(segment
		(start 210.306412 -207.098646)
		(end 210.598258 -207.098646)
		(width 0.20066)
		(layer "F.Cu")
		(net "M_H_CPU1_SB_DQ<22>")
	)
	(segment
		(start 128.556512 -229.808786)
		(end 128.556766 -229.808532)
		(width 0.20066)
		(layer "F.Cu")
		(net "M_H_CPU1_SB_DQ<22>")
	)
	(segment
		(start 214.385652 -206.666592)
		(end 215.719914 -206.666592)
		(width 0.20066)
		(layer "F.Cu")
		(net "M_H_CPU1_SB_DQ<22>")
	)
	(segment
		(start 207.071214 -206.666592)
		(end 208.176114 -206.666592)
		(width 0.20066)
		(layer "F.Cu")
		(net "M_H_CPU1_SB_DQ<22>")
	)
	(segment
		(start 209.874358 -206.666592)
		(end 210.306412 -207.098646)
		(width 0.20066)
		(layer "F.Cu")
		(net "M_H_CPU1_SB_DQ<22>")
	)
	(segment
		(start 128.556766 -229.808532)
		(end 128.556766 -229.272846)
		(width 0.20066)
		(layer "F.Cu")
		(net "M_H_CPU1_SB_DQ<22>")
	)
	(segment
		(start 208.176114 -206.666592)
		(end 209.874358 -206.666592)
		(width 0.20066)
		(layer "F.Cu")
		(net "M_H_CPU1_SB_DQ<22>")
	)
	(segment
		(start 210.610196 -207.091534)
		(end 212.618066 -207.091534)
		(width 0.1016)
		(layer "F.Cu")
		(net "M_H_CPU1_SB_DQ<22>")
	)
	(segment
		(start 213.749636 -206.414624)
		(end 214.133684 -206.414624)
		(width 0.20066)
		(layer "F.Cu")
		(net "M_H_CPU1_SB_DQ<22>")
	)
	(segment
		(start 174.809404 -207.828896)
		(end 174.072804 -207.092296)
		(width 0.18288)
		(layer "In6.Cu")
		(net "M_H_CPU1_SB_DQ<22>")
	)
	(segment
		(start 162.54095 -207.227678)
		(end 162.29584 -206.982568)
		(width 0.18288)
		(layer "In6.Cu")
		(net "M_H_CPU1_SB_DQ<22>")
	)
	(segment
		(start 138.193018 -226.99726)
		(end 137.280142 -227.910136)
		(width 0.088646)
		(layer "In6.Cu")
		(net "M_H_CPU1_SB_DQ<22>")
	)
	(segment
		(start 198.941436 -206.459836)
		(end 198.505826 -206.024226)
		(width 0.18288)
		(layer "In6.Cu")
		(net "M_H_CPU1_SB_DQ<22>")
	)
	(segment
		(start 178.693572 -206.835756)
		(end 177.590958 -207.93837)
		(width 0.18288)
		(layer "In6.Cu")
		(net "M_H_CPU1_SB_DQ<22>")
	)
	(segment
		(start 138.429746 -226.189286)
		(end 138.429746 -226.64293)
		(width 0.088646)
		(layer "In6.Cu")
		(net "M_H_CPU1_SB_DQ<22>")
	)
	(segment
		(start 203.65974 -206.242412)
		(end 202.37704 -206.242412)
		(width 0.18288)
		(layer "In6.Cu")
		(net "M_H_CPU1_SB_DQ<22>")
	)
	(segment
		(start 201.271632 -206.155036)
		(end 199.849232 -206.155036)
		(width 0.18288)
		(layer "In6.Cu")
		(net "M_H_CPU1_SB_DQ<22>")
	)
	(segment
		(start 186.948826 -206.456026)
		(end 186.03468 -206.456026)
		(width 0.18288)
		(layer "In6.Cu")
		(net "M_H_CPU1_SB_DQ<22>")
	)
	(segment
		(start 202.37704 -206.242412)
		(end 202.134216 -206.485236)
		(width 0.18288)
		(layer "In6.Cu")
		(net "M_H_CPU1_SB_DQ<22>")
	)
	(segment
		(start 165.542722 -207.283304)
		(end 164.662104 -207.283304)
		(width 0.18288)
		(layer "In6.Cu")
		(net "M_H_CPU1_SB_DQ<22>")
	)
	(segment
		(start 129.2225 -228.778308)
		(end 129.21361 -228.783388)
		(width 0.088646)
		(layer "In6.Cu")
		(net "M_H_CPU1_SB_DQ<22>")
	)
	(segment
		(start 202.134216 -206.485236)
		(end 201.601832 -206.485236)
		(width 0.18288)
		(layer "In6.Cu")
		(net "M_H_CPU1_SB_DQ<22>")
	)
	(segment
		(start 175.83277 -207.93837)
		(end 175.723296 -207.828896)
		(width 0.18288)
		(layer "In6.Cu")
		(net "M_H_CPU1_SB_DQ<22>")
	)
	(segment
		(start 196.223128 -205.392528)
		(end 189.942978 -205.392528)
		(width 0.18288)
		(layer "In6.Cu")
		(net "M_H_CPU1_SB_DQ<22>")
	)
	(segment
		(start 162.29584 -206.982568)
		(end 161.22523 -206.982568)
		(width 0.18288)
		(layer "In6.Cu")
		(net "M_H_CPU1_SB_DQ<22>")
	)
	(segment
		(start 167.189404 -206.726028)
		(end 166.099998 -206.726028)
		(width 0.18288)
		(layer "In6.Cu")
		(net "M_H_CPU1_SB_DQ<22>")
	)
	(segment
		(start 138.429746 -226.64293)
		(end 138.193018 -226.99726)
		(width 0.088646)
		(layer "In6.Cu")
		(net "M_H_CPU1_SB_DQ<22>")
	)
	(segment
		(start 179.808124 -207.268826)
		(end 179.375054 -206.835756)
		(width 0.18288)
		(layer "In6.Cu")
		(net "M_H_CPU1_SB_DQ<22>")
	)
	(segment
		(start 206.120238 -207.617568)
		(end 205.034896 -207.617568)
		(width 0.18288)
		(layer "In6.Cu")
		(net "M_H_CPU1_SB_DQ<22>")
	)
	(segment
		(start 186.03468 -206.456026)
		(end 185.45048 -207.040226)
		(width 0.18288)
		(layer "In6.Cu")
		(net "M_H_CPU1_SB_DQ<22>")
	)
	(segment
		(start 129.401062 -228.444806)
		(end 129.401062 -228.45903)
		(width 0.088646)
		(layer "In6.Cu")
		(net "M_H_CPU1_SB_DQ<22>")
	)
	(segment
		(start 162.701224 -207.82534)
		(end 162.54095 -207.665066)
		(width 0.18288)
		(layer "In6.Cu")
		(net "M_H_CPU1_SB_DQ<22>")
	)
	(segment
		(start 164.662104 -207.283304)
		(end 164.361368 -206.982568)
		(width 0.18288)
		(layer "In6.Cu")
		(net "M_H_CPU1_SB_DQ<22>")
	)
	(segment
		(start 207.071214 -206.666592)
		(end 206.120238 -207.617568)
		(width 0.18288)
		(layer "In6.Cu")
		(net "M_H_CPU1_SB_DQ<22>")
	)
	(segment
		(start 199.849232 -206.155036)
		(end 199.544432 -206.459836)
		(width 0.18288)
		(layer "In6.Cu")
		(net "M_H_CPU1_SB_DQ<22>")
	)
	(segment
		(start 183.189626 -207.040226)
		(end 182.961026 -207.268826)
		(width 0.18288)
		(layer "In6.Cu")
		(net "M_H_CPU1_SB_DQ<22>")
	)
	(segment
		(start 189.093348 -206.242158)
		(end 187.162694 -206.242158)
		(width 0.18288)
		(layer "In6.Cu")
		(net "M_H_CPU1_SB_DQ<22>")
	)
	(segment
		(start 164.361368 -206.982568)
		(end 163.5252 -206.982568)
		(width 0.18288)
		(layer "In6.Cu")
		(net "M_H_CPU1_SB_DQ<22>")
	)
	(segment
		(start 157.230064 -207.218026)
		(end 153.791666 -210.656424)
		(width 0.18288)
		(layer "In6.Cu")
		(net "M_H_CPU1_SB_DQ<22>")
	)
	(segment
		(start 138.821414 -225.797618)
		(end 138.429746 -226.189286)
		(width 0.088646)
		(layer "In6.Cu")
		(net "M_H_CPU1_SB_DQ<22>")
	)
	(segment
		(start 153.791666 -210.656424)
		(end 153.791666 -210.827366)
		(width 0.18288)
		(layer "In6.Cu")
		(net "M_H_CPU1_SB_DQ<22>")
	)
	(segment
		(start 153.791666 -210.827366)
		(end 138.821414 -225.797618)
		(width 0.18288)
		(layer "In6.Cu")
		(net "M_H_CPU1_SB_DQ<22>")
	)
	(segment
		(start 167.555672 -207.092296)
		(end 167.189404 -206.726028)
		(width 0.18288)
		(layer "In6.Cu")
		(net "M_H_CPU1_SB_DQ<22>")
	)
	(segment
		(start 161.22523 -206.982568)
		(end 160.989772 -207.218026)
		(width 0.18288)
		(layer "In6.Cu")
		(net "M_H_CPU1_SB_DQ<22>")
	)
	(segment
		(start 128.994408 -229.013004)
		(end 128.556766 -229.272846)
		(width 0.088646)
		(layer "In6.Cu")
		(net "M_H_CPU1_SB_DQ<22>")
	)
	(segment
		(start 175.723296 -207.828896)
		(end 174.809404 -207.828896)
		(width 0.18288)
		(layer "In6.Cu")
		(net "M_H_CPU1_SB_DQ<22>")
	)
	(segment
		(start 187.162694 -206.242158)
		(end 186.948826 -206.456026)
		(width 0.18288)
		(layer "In6.Cu")
		(net "M_H_CPU1_SB_DQ<22>")
	)
	(segment
		(start 162.54095 -207.665066)
		(end 162.54095 -207.227678)
		(width 0.18288)
		(layer "In6.Cu")
		(net "M_H_CPU1_SB_DQ<22>")
	)
	(segment
		(start 163.095432 -207.82534)
		(end 162.701224 -207.82534)
		(width 0.18288)
		(layer "In6.Cu")
		(net "M_H_CPU1_SB_DQ<22>")
	)
	(segment
		(start 201.601832 -206.485236)
		(end 201.271632 -206.155036)
		(width 0.18288)
		(layer "In6.Cu")
		(net "M_H_CPU1_SB_DQ<22>")
	)
	(segment
		(start 129.698496 -227.960682)
		(end 129.683764 -227.969318)
		(width 0.088646)
		(layer "In6.Cu")
		(net "M_H_CPU1_SB_DQ<22>")
	)
	(segment
		(start 185.45048 -207.040226)
		(end 183.189626 -207.040226)
		(width 0.18288)
		(layer "In6.Cu")
		(net "M_H_CPU1_SB_DQ<22>")
	)
	(segment
		(start 130.638296 -227.960682)
		(end 130.623564 -227.969318)
		(width 0.088646)
		(layer "In6.Cu")
		(net "M_H_CPU1_SB_DQ<22>")
	)
	(segment
		(start 163.5252 -206.982568)
		(end 163.292536 -207.215232)
		(width 0.18288)
		(layer "In6.Cu")
		(net "M_H_CPU1_SB_DQ<22>")
	)
	(segment
		(start 196.854826 -206.024226)
		(end 196.223128 -205.392528)
		(width 0.18288)
		(layer "In6.Cu")
		(net "M_H_CPU1_SB_DQ<22>")
	)
	(segment
		(start 177.590958 -207.93837)
		(end 175.83277 -207.93837)
		(width 0.18288)
		(layer "In6.Cu")
		(net "M_H_CPU1_SB_DQ<22>")
	)
	(segment
		(start 179.375054 -206.835756)
		(end 178.693572 -206.835756)
		(width 0.18288)
		(layer "In6.Cu")
		(net "M_H_CPU1_SB_DQ<22>")
	)
	(segment
		(start 189.942978 -205.392528)
		(end 189.093348 -206.242158)
		(width 0.18288)
		(layer "In6.Cu")
		(net "M_H_CPU1_SB_DQ<22>")
	)
	(segment
		(start 163.292536 -207.215232)
		(end 163.292536 -207.628236)
		(width 0.18288)
		(layer "In6.Cu")
		(net "M_H_CPU1_SB_DQ<22>")
	)
	(segment
		(start 199.544432 -206.459836)
		(end 198.941436 -206.459836)
		(width 0.18288)
		(layer "In6.Cu")
		(net "M_H_CPU1_SB_DQ<22>")
	)
	(segment
		(start 134.397496 -227.960682)
		(end 134.382764 -227.969318)
		(width 0.088646)
		(layer "In6.Cu")
		(net "M_H_CPU1_SB_DQ<22>")
	)
	(segment
		(start 174.072804 -207.092296)
		(end 167.555672 -207.092296)
		(width 0.18288)
		(layer "In6.Cu")
		(net "M_H_CPU1_SB_DQ<22>")
	)
	(segment
		(start 131.578096 -227.960682)
		(end 131.563364 -227.969318)
		(width 0.088646)
		(layer "In6.Cu")
		(net "M_H_CPU1_SB_DQ<22>")
	)
	(segment
		(start 205.034896 -207.617568)
		(end 203.65974 -206.242412)
		(width 0.18288)
		(layer "In6.Cu")
		(net "M_H_CPU1_SB_DQ<22>")
	)
	(segment
		(start 163.292536 -207.628236)
		(end 163.095432 -207.82534)
		(width 0.18288)
		(layer "In6.Cu")
		(net "M_H_CPU1_SB_DQ<22>")
	)
	(segment
		(start 166.099998 -206.726028)
		(end 165.542722 -207.283304)
		(width 0.18288)
		(layer "In6.Cu")
		(net "M_H_CPU1_SB_DQ<22>")
	)
	(segment
		(start 198.505826 -206.024226)
		(end 196.854826 -206.024226)
		(width 0.18288)
		(layer "In6.Cu")
		(net "M_H_CPU1_SB_DQ<22>")
	)
	(segment
		(start 160.989772 -207.218026)
		(end 157.230064 -207.218026)
		(width 0.18288)
		(layer "In6.Cu")
		(net "M_H_CPU1_SB_DQ<22>")
	)
	(segment
		(start 182.961026 -207.268826)
		(end 179.808124 -207.268826)
		(width 0.18288)
		(layer "In6.Cu")
		(net "M_H_CPU1_SB_DQ<22>")
	)
	(arc
		(start 137.202164 -227.969318)
		(mid 137.014966 -228.019461)
		(end 136.827768 -227.969318)
		(width 0.088646)
		(layer "In6.Cu")
		(net "M_H_CPU1_SB_DQ<22>")
	)
	(arc
		(start 131.563364 -227.969318)
		(mid 131.376166 -228.019461)
		(end 131.188968 -227.969318)
		(width 0.088646)
		(layer "In6.Cu")
		(net "M_H_CPU1_SB_DQ<22>")
	)
	(arc
		(start 134.948168 -227.969318)
		(mid 134.673939 -227.893393)
		(end 134.397496 -227.960682)
		(width 0.088646)
		(layer "In6.Cu")
		(net "M_H_CPU1_SB_DQ<22>")
	)
	(arc
		(start 136.262364 -227.969318)
		(mid 136.075166 -228.019461)
		(end 135.887968 -227.969318)
		(width 0.088646)
		(layer "In6.Cu")
		(net "M_H_CPU1_SB_DQ<22>")
	)
	(arc
		(start 129.683764 -227.969318)
		(mid 129.480283 -228.170122)
		(end 129.401062 -228.444806)
		(width 0.088646)
		(layer "In6.Cu")
		(net "M_H_CPU1_SB_DQ<22>")
	)
	(arc
		(start 129.401062 -228.45903)
		(mid 129.353383 -228.64193)
		(end 129.2225 -228.778308)
		(width 0.088646)
		(layer "In6.Cu")
		(net "M_H_CPU1_SB_DQ<22>")
	)
	(arc
		(start 131.188968 -227.969318)
		(mid 130.914739 -227.893393)
		(end 130.638296 -227.960682)
		(width 0.088646)
		(layer "In6.Cu")
		(net "M_H_CPU1_SB_DQ<22>")
	)
	(arc
		(start 133.442964 -227.969318)
		(mid 133.255766 -228.019461)
		(end 133.068568 -227.969318)
		(width 0.088646)
		(layer "In6.Cu")
		(net "M_H_CPU1_SB_DQ<22>")
	)
	(arc
		(start 134.382764 -227.969318)
		(mid 134.195566 -228.019461)
		(end 134.008368 -227.969318)
		(width 0.088646)
		(layer "In6.Cu")
		(net "M_H_CPU1_SB_DQ<22>")
	)
	(arc
		(start 133.068568 -227.969318)
		(mid 132.785866 -227.893576)
		(end 132.503164 -227.969318)
		(width 0.088646)
		(layer "In6.Cu")
		(net "M_H_CPU1_SB_DQ<22>")
	)
	(arc
		(start 137.280142 -227.910136)
		(mid 137.243092 -227.942282)
		(end 137.202164 -227.969318)
		(width 0.088646)
		(layer "In6.Cu")
		(net "M_H_CPU1_SB_DQ<22>")
	)
	(arc
		(start 132.503164 -227.969318)
		(mid 132.315966 -228.019461)
		(end 132.128768 -227.969318)
		(width 0.088646)
		(layer "In6.Cu")
		(net "M_H_CPU1_SB_DQ<22>")
	)
	(arc
		(start 134.008368 -227.969318)
		(mid 133.725666 -227.893576)
		(end 133.442964 -227.969318)
		(width 0.088646)
		(layer "In6.Cu")
		(net "M_H_CPU1_SB_DQ<22>")
	)
	(arc
		(start 135.887968 -227.969318)
		(mid 135.605266 -227.893576)
		(end 135.322564 -227.969318)
		(width 0.088646)
		(layer "In6.Cu")
		(net "M_H_CPU1_SB_DQ<22>")
	)
	(arc
		(start 130.249168 -227.969318)
		(mid 129.974939 -227.893393)
		(end 129.698496 -227.960682)
		(width 0.088646)
		(layer "In6.Cu")
		(net "M_H_CPU1_SB_DQ<22>")
	)
	(arc
		(start 129.21361 -228.783388)
		(mid 129.087534 -228.882474)
		(end 128.994408 -229.013004)
		(width 0.088646)
		(layer "In6.Cu")
		(net "M_H_CPU1_SB_DQ<22>")
	)
	(arc
		(start 130.623564 -227.969318)
		(mid 130.436366 -228.019461)
		(end 130.249168 -227.969318)
		(width 0.088646)
		(layer "In6.Cu")
		(net "M_H_CPU1_SB_DQ<22>")
	)
	(arc
		(start 135.322564 -227.969318)
		(mid 135.135366 -228.019461)
		(end 134.948168 -227.969318)
		(width 0.088646)
		(layer "In6.Cu")
		(net "M_H_CPU1_SB_DQ<22>")
	)
	(arc
		(start 132.128768 -227.969318)
		(mid 131.854539 -227.893393)
		(end 131.578096 -227.960682)
		(width 0.088646)
		(layer "In6.Cu")
		(net "M_H_CPU1_SB_DQ<22>")
	)
	(arc
		(start 136.827768 -227.969318)
		(mid 136.545066 -227.893576)
		(end 136.262364 -227.969318)
		(width 0.088646)
		(layer "In6.Cu")
		(net "M_H_CPU1_SB_DQ<22>")
	)
	(segment
		(start 206.508604 -205.877414)
		(end 206.320644 -206.065374)
		(width 0.20066)
		(layer "F.Cu")
		(net "M_H_CPU1_SB_DQ<21>")
	)
	(segment
		(start 206.320644 -206.065374)
		(end 205.84541 -206.065374)
		(width 0.20066)
		(layer "F.Cu")
		(net "M_H_CPU1_SB_DQ<21>")
	)
	(segment
		(start 211.619592 -205.816962)
		(end 210.028028 -205.816962)
		(width 0.20066)
		(layer "F.Cu")
		(net "M_H_CPU1_SB_DQ<21>")
	)
	(segment
		(start 127.146812 -228.994716)
		(end 127.146812 -228.45903)
		(width 0.20066)
		(layer "F.Cu")
		(net "M_H_CPU1_SB_DQ<21>")
	)
	(segment
		(start 206.971392 -205.391766)
		(end 206.626714 -205.391766)
		(width 0.20066)
		(layer "F.Cu")
		(net "M_H_CPU1_SB_DQ<21>")
	)
	(segment
		(start 209.186526 -205.385416)
		(end 209.180176 -205.391766)
		(width 0.1016)
		(layer "F.Cu")
		(net "M_H_CPU1_SB_DQ<21>")
	)
	(segment
		(start 127.147066 -228.99497)
		(end 127.146812 -228.994716)
		(width 0.20066)
		(layer "F.Cu")
		(net "M_H_CPU1_SB_DQ<21>")
	)
	(segment
		(start 209.180176 -205.391766)
		(end 206.991458 -205.391766)
		(width 0.1016)
		(layer "F.Cu")
		(net "M_H_CPU1_SB_DQ<21>")
	)
	(segment
		(start 211.619846 -205.816708)
		(end 211.619592 -205.816962)
		(width 0.20066)
		(layer "F.Cu")
		(net "M_H_CPU1_SB_DQ<21>")
	)
	(segment
		(start 204.076046 -205.816708)
		(end 202.971146 -205.816708)
		(width 0.20066)
		(layer "F.Cu")
		(net "M_H_CPU1_SB_DQ<21>")
	)
	(segment
		(start 206.626714 -205.391766)
		(end 206.508604 -205.509876)
		(width 0.20066)
		(layer "F.Cu")
		(net "M_H_CPU1_SB_DQ<21>")
	)
	(segment
		(start 205.596744 -205.816708)
		(end 204.076046 -205.816708)
		(width 0.20066)
		(layer "F.Cu")
		(net "M_H_CPU1_SB_DQ<21>")
	)
	(segment
		(start 210.028028 -205.816962)
		(end 209.596482 -205.385416)
		(width 0.20066)
		(layer "F.Cu")
		(net "M_H_CPU1_SB_DQ<21>")
	)
	(segment
		(start 206.508604 -205.509876)
		(end 206.508604 -205.877414)
		(width 0.20066)
		(layer "F.Cu")
		(net "M_H_CPU1_SB_DQ<21>")
	)
	(segment
		(start 209.596482 -205.385416)
		(end 209.186526 -205.385416)
		(width 0.20066)
		(layer "F.Cu")
		(net "M_H_CPU1_SB_DQ<21>")
	)
	(segment
		(start 206.991458 -205.391766)
		(end 206.971392 -205.391766)
		(width 0.101854)
		(layer "F.Cu")
		(net "M_H_CPU1_SB_DQ<21>")
	)
	(segment
		(start 205.84541 -206.065374)
		(end 205.596744 -205.816708)
		(width 0.20066)
		(layer "F.Cu")
		(net "M_H_CPU1_SB_DQ<21>")
	)
	(segment
		(start 198.596504 -205.070964)
		(end 198.172832 -205.494636)
		(width 0.18288)
		(layer "In6.Cu")
		(net "M_H_CPU1_SB_DQ<21>")
	)
	(segment
		(start 200.959466 -205.070964)
		(end 200.799446 -205.230984)
		(width 0.18288)
		(layer "In6.Cu")
		(net "M_H_CPU1_SB_DQ<21>")
	)
	(segment
		(start 193.973704 -204.887068)
		(end 193.629026 -204.54239)
		(width 0.18288)
		(layer "In6.Cu")
		(net "M_H_CPU1_SB_DQ<21>")
	)
	(segment
		(start 186.285632 -205.39202)
		(end 185.231532 -206.44612)
		(width 0.18288)
		(layer "In6.Cu")
		(net "M_H_CPU1_SB_DQ<21>")
	)
	(segment
		(start 139.412218 -224.48139)
		(end 138.890502 -225.003106)
		(width 0.088646)
		(layer "In6.Cu")
		(net "M_H_CPU1_SB_DQ<21>")
	)
	(segment
		(start 198.172832 -205.494636)
		(end 197.290436 -205.494636)
		(width 0.18288)
		(layer "In6.Cu")
		(net "M_H_CPU1_SB_DQ<21>")
	)
	(segment
		(start 173.93412 -206.242412)
		(end 168.821862 -206.242412)
		(width 0.18288)
		(layer "In6.Cu")
		(net "M_H_CPU1_SB_DQ<21>")
	)
	(segment
		(start 200.106026 -205.495652)
		(end 200.106026 -205.230984)
		(width 0.18288)
		(layer "In6.Cu")
		(net "M_H_CPU1_SB_DQ<21>")
	)
	(segment
		(start 138.599672 -225.57613)
		(end 136.944862 -227.23094)
		(width 0.088646)
		(layer "In6.Cu")
		(net "M_H_CPU1_SB_DQ<21>")
	)
	(segment
		(start 202.971146 -205.816708)
		(end 202.225402 -205.070964)
		(width 0.18288)
		(layer "In6.Cu")
		(net "M_H_CPU1_SB_DQ<21>")
	)
	(segment
		(start 162.802824 -205.897734)
		(end 162.269678 -206.43088)
		(width 0.18288)
		(layer "In6.Cu")
		(net "M_H_CPU1_SB_DQ<21>")
	)
	(segment
		(start 197.278498 -204.46619)
		(end 197.014084 -204.201776)
		(width 0.18288)
		(layer "In6.Cu")
		(net "M_H_CPU1_SB_DQ<21>")
	)
	(segment
		(start 129.121916 -227.64496)
		(end 129.121916 -227.65258)
		(width 0.088646)
		(layer "In6.Cu")
		(net "M_H_CPU1_SB_DQ<21>")
	)
	(segment
		(start 161.422334 -206.43088)
		(end 161.070798 -206.079344)
		(width 0.18288)
		(layer "In6.Cu")
		(net "M_H_CPU1_SB_DQ<21>")
	)
	(segment
		(start 167.118284 -206.208376)
		(end 166.698422 -206.208376)
		(width 0.18288)
		(layer "In6.Cu")
		(net "M_H_CPU1_SB_DQ<21>")
	)
	(segment
		(start 132.517896 -227.329238)
		(end 132.503164 -227.320602)
		(width 0.088646)
		(layer "In6.Cu")
		(net "M_H_CPU1_SB_DQ<21>")
	)
	(segment
		(start 177.451258 -207.09001)
		(end 175.63973 -207.09001)
		(width 0.18288)
		(layer "In6.Cu")
		(net "M_H_CPU1_SB_DQ<21>")
	)
	(segment
		(start 131.578096 -227.329238)
		(end 131.563364 -227.320602)
		(width 0.088646)
		(layer "In6.Cu")
		(net "M_H_CPU1_SB_DQ<21>")
	)
	(segment
		(start 196.788024 -204.201776)
		(end 196.641974 -204.347826)
		(width 0.18288)
		(layer "In6.Cu")
		(net "M_H_CPU1_SB_DQ<21>")
	)
	(segment
		(start 199.946006 -205.070964)
		(end 198.596504 -205.070964)
		(width 0.18288)
		(layer "In6.Cu")
		(net "M_H_CPU1_SB_DQ<21>")
	)
	(segment
		(start 180.81752 -205.968854)
		(end 179.741576 -205.968854)
		(width 0.18288)
		(layer "In6.Cu")
		(net "M_H_CPU1_SB_DQ<21>")
	)
	(segment
		(start 161.070798 -206.079344)
		(end 157.456378 -206.079344)
		(width 0.18288)
		(layer "In6.Cu")
		(net "M_H_CPU1_SB_DQ<21>")
	)
	(segment
		(start 200.266046 -205.655672)
		(end 200.106026 -205.495652)
		(width 0.18288)
		(layer "In6.Cu")
		(net "M_H_CPU1_SB_DQ<21>")
	)
	(segment
		(start 167.391842 -205.934818)
		(end 167.118284 -206.208376)
		(width 0.18288)
		(layer "In6.Cu")
		(net "M_H_CPU1_SB_DQ<21>")
	)
	(segment
		(start 175.63973 -207.09001)
		(end 175.486314 -207.243426)
		(width 0.18288)
		(layer "In6.Cu")
		(net "M_H_CPU1_SB_DQ<21>")
	)
	(segment
		(start 127.76073 -228.91369)
		(end 127.146812 -228.45903)
		(width 0.088646)
		(layer "In6.Cu")
		(net "M_H_CPU1_SB_DQ<21>")
	)
	(segment
		(start 185.231532 -206.44612)
		(end 183.469026 -206.44612)
		(width 0.18288)
		(layer "In6.Cu")
		(net "M_H_CPU1_SB_DQ<21>")
	)
	(segment
		(start 194.664584 -204.887068)
		(end 193.973704 -204.887068)
		(width 0.18288)
		(layer "In6.Cu")
		(net "M_H_CPU1_SB_DQ<21>")
	)
	(segment
		(start 180.97754 -206.590646)
		(end 180.97754 -206.128874)
		(width 0.18288)
		(layer "In6.Cu")
		(net "M_H_CPU1_SB_DQ<21>")
	)
	(segment
		(start 178.300126 -206.241142)
		(end 177.451258 -207.09001)
		(width 0.18288)
		(layer "In6.Cu")
		(net "M_H_CPU1_SB_DQ<21>")
	)
	(segment
		(start 183.469026 -206.44612)
		(end 183.469026 -206.430626)
		(width 0.18288)
		(layer "In6.Cu")
		(net "M_H_CPU1_SB_DQ<21>")
	)
	(segment
		(start 165.695376 -206.244444)
		(end 163.521898 -206.244444)
		(width 0.18288)
		(layer "In6.Cu")
		(net "M_H_CPU1_SB_DQ<21>")
	)
	(segment
		(start 162.269678 -206.43088)
		(end 161.422334 -206.43088)
		(width 0.18288)
		(layer "In6.Cu")
		(net "M_H_CPU1_SB_DQ<21>")
	)
	(segment
		(start 196.996304 -205.200504)
		(end 196.996304 -204.974444)
		(width 0.18288)
		(layer "In6.Cu")
		(net "M_H_CPU1_SB_DQ<21>")
	)
	(segment
		(start 181.67096 -206.590646)
		(end 181.51094 -206.750666)
		(width 0.18288)
		(layer "In6.Cu")
		(net "M_H_CPU1_SB_DQ<21>")
	)
	(segment
		(start 189.878462 -204.54239)
		(end 189.028832 -205.39202)
		(width 0.18288)
		(layer "In6.Cu")
		(net "M_H_CPU1_SB_DQ<21>")
	)
	(segment
		(start 163.521898 -206.244444)
		(end 163.175188 -205.897734)
		(width 0.18288)
		(layer "In6.Cu")
		(net "M_H_CPU1_SB_DQ<21>")
	)
	(segment
		(start 168.821862 -206.242412)
		(end 168.514268 -205.934818)
		(width 0.18288)
		(layer "In6.Cu")
		(net "M_H_CPU1_SB_DQ<21>")
	)
	(segment
		(start 181.13756 -206.750666)
		(end 180.97754 -206.590646)
		(width 0.18288)
		(layer "In6.Cu")
		(net "M_H_CPU1_SB_DQ<21>")
	)
	(segment
		(start 138.890502 -225.003106)
		(end 138.890502 -225.285046)
		(width 0.088646)
		(layer "In6.Cu")
		(net "M_H_CPU1_SB_DQ<21>")
	)
	(segment
		(start 183.007254 -205.968854)
		(end 181.83098 -205.968854)
		(width 0.18288)
		(layer "In6.Cu")
		(net "M_H_CPU1_SB_DQ<21>")
	)
	(segment
		(start 197.278498 -204.69225)
		(end 197.278498 -204.46619)
		(width 0.18288)
		(layer "In6.Cu")
		(net "M_H_CPU1_SB_DQ<21>")
	)
	(segment
		(start 196.996304 -204.974444)
		(end 197.278498 -204.69225)
		(width 0.18288)
		(layer "In6.Cu")
		(net "M_H_CPU1_SB_DQ<21>")
	)
	(segment
		(start 157.456378 -206.079344)
		(end 153.2255 -210.310222)
		(width 0.18288)
		(layer "In6.Cu")
		(net "M_H_CPU1_SB_DQ<21>")
	)
	(segment
		(start 153.2255 -210.310222)
		(end 153.2255 -210.668108)
		(width 0.18288)
		(layer "In6.Cu")
		(net "M_H_CPU1_SB_DQ<21>")
	)
	(segment
		(start 200.799446 -205.495652)
		(end 200.639426 -205.655672)
		(width 0.18288)
		(layer "In6.Cu")
		(net "M_H_CPU1_SB_DQ<21>")
	)
	(segment
		(start 175.486314 -207.243426)
		(end 174.935134 -207.243426)
		(width 0.18288)
		(layer "In6.Cu")
		(net "M_H_CPU1_SB_DQ<21>")
	)
	(segment
		(start 153.2255 -210.668108)
		(end 139.412218 -224.48139)
		(width 0.18288)
		(layer "In6.Cu")
		(net "M_H_CPU1_SB_DQ<21>")
	)
	(segment
		(start 196.641974 -204.347826)
		(end 195.203826 -204.347826)
		(width 0.18288)
		(layer "In6.Cu")
		(net "M_H_CPU1_SB_DQ<21>")
	)
	(segment
		(start 200.106026 -205.230984)
		(end 199.946006 -205.070964)
		(width 0.18288)
		(layer "In6.Cu")
		(net "M_H_CPU1_SB_DQ<21>")
	)
	(segment
		(start 181.51094 -206.750666)
		(end 181.13756 -206.750666)
		(width 0.18288)
		(layer "In6.Cu")
		(net "M_H_CPU1_SB_DQ<21>")
	)
	(segment
		(start 129.309368 -227.320602)
		(end 129.300478 -227.325682)
		(width 0.088646)
		(layer "In6.Cu")
		(net "M_H_CPU1_SB_DQ<21>")
	)
	(segment
		(start 138.599672 -225.575876)
		(end 138.599672 -225.57613)
		(width 0.088646)
		(layer "In6.Cu")
		(net "M_H_CPU1_SB_DQ<21>")
	)
	(segment
		(start 183.469026 -206.430626)
		(end 183.007254 -205.968854)
		(width 0.18288)
		(layer "In6.Cu")
		(net "M_H_CPU1_SB_DQ<21>")
	)
	(segment
		(start 134.397496 -227.329238)
		(end 134.382764 -227.320602)
		(width 0.088646)
		(layer "In6.Cu")
		(net "M_H_CPU1_SB_DQ<21>")
	)
	(segment
		(start 180.97754 -206.128874)
		(end 180.81752 -205.968854)
		(width 0.18288)
		(layer "In6.Cu")
		(net "M_H_CPU1_SB_DQ<21>")
	)
	(segment
		(start 179.469288 -206.241142)
		(end 178.300126 -206.241142)
		(width 0.18288)
		(layer "In6.Cu")
		(net "M_H_CPU1_SB_DQ<21>")
	)
	(segment
		(start 166.005002 -205.934818)
		(end 165.695376 -206.244444)
		(width 0.18288)
		(layer "In6.Cu")
		(net "M_H_CPU1_SB_DQ<21>")
	)
	(segment
		(start 138.890502 -225.285046)
		(end 138.599672 -225.575876)
		(width 0.088646)
		(layer "In6.Cu")
		(net "M_H_CPU1_SB_DQ<21>")
	)
	(segment
		(start 128.839214 -228.134672)
		(end 128.830324 -228.139752)
		(width 0.088646)
		(layer "In6.Cu")
		(net "M_H_CPU1_SB_DQ<21>")
	)
	(segment
		(start 179.741576 -205.968854)
		(end 179.469288 -206.241142)
		(width 0.18288)
		(layer "In6.Cu")
		(net "M_H_CPU1_SB_DQ<21>")
	)
	(segment
		(start 166.698422 -206.208376)
		(end 166.424864 -205.934818)
		(width 0.18288)
		(layer "In6.Cu")
		(net "M_H_CPU1_SB_DQ<21>")
	)
	(segment
		(start 200.639426 -205.655672)
		(end 200.266046 -205.655672)
		(width 0.18288)
		(layer "In6.Cu")
		(net "M_H_CPU1_SB_DQ<21>")
	)
	(segment
		(start 181.67096 -206.128874)
		(end 181.67096 -206.590646)
		(width 0.18288)
		(layer "In6.Cu")
		(net "M_H_CPU1_SB_DQ<21>")
	)
	(segment
		(start 181.83098 -205.968854)
		(end 181.67096 -206.128874)
		(width 0.18288)
		(layer "In6.Cu")
		(net "M_H_CPU1_SB_DQ<21>")
	)
	(segment
		(start 197.014084 -204.201776)
		(end 196.788024 -204.201776)
		(width 0.18288)
		(layer "In6.Cu")
		(net "M_H_CPU1_SB_DQ<21>")
	)
	(segment
		(start 168.514268 -205.934818)
		(end 167.391842 -205.934818)
		(width 0.18288)
		(layer "In6.Cu")
		(net "M_H_CPU1_SB_DQ<21>")
	)
	(segment
		(start 195.203826 -204.347826)
		(end 194.664584 -204.887068)
		(width 0.18288)
		(layer "In6.Cu")
		(net "M_H_CPU1_SB_DQ<21>")
	)
	(segment
		(start 129.698496 -227.329238)
		(end 129.683764 -227.320602)
		(width 0.088646)
		(layer "In6.Cu")
		(net "M_H_CPU1_SB_DQ<21>")
	)
	(segment
		(start 193.629026 -204.54239)
		(end 189.878462 -204.54239)
		(width 0.18288)
		(layer "In6.Cu")
		(net "M_H_CPU1_SB_DQ<21>")
	)
	(segment
		(start 202.225402 -205.070964)
		(end 200.959466 -205.070964)
		(width 0.18288)
		(layer "In6.Cu")
		(net "M_H_CPU1_SB_DQ<21>")
	)
	(segment
		(start 189.028832 -205.39202)
		(end 186.285632 -205.39202)
		(width 0.18288)
		(layer "In6.Cu")
		(net "M_H_CPU1_SB_DQ<21>")
	)
	(segment
		(start 166.424864 -205.934818)
		(end 166.005002 -205.934818)
		(width 0.18288)
		(layer "In6.Cu")
		(net "M_H_CPU1_SB_DQ<21>")
	)
	(segment
		(start 128.651762 -228.45903)
		(end 128.651762 -228.474524)
		(width 0.088646)
		(layer "In6.Cu")
		(net "M_H_CPU1_SB_DQ<21>")
	)
	(segment
		(start 163.175188 -205.897734)
		(end 162.802824 -205.897734)
		(width 0.18288)
		(layer "In6.Cu")
		(net "M_H_CPU1_SB_DQ<21>")
	)
	(segment
		(start 200.799446 -205.230984)
		(end 200.799446 -205.495652)
		(width 0.18288)
		(layer "In6.Cu")
		(net "M_H_CPU1_SB_DQ<21>")
	)
	(segment
		(start 174.935134 -207.243426)
		(end 173.93412 -206.242412)
		(width 0.18288)
		(layer "In6.Cu")
		(net "M_H_CPU1_SB_DQ<21>")
	)
	(segment
		(start 197.290436 -205.494636)
		(end 196.996304 -205.200504)
		(width 0.18288)
		(layer "In6.Cu")
		(net "M_H_CPU1_SB_DQ<21>")
	)
	(arc
		(start 135.322564 -227.320602)
		(mid 135.135366 -227.270459)
		(end 134.948168 -227.320602)
		(width 0.088646)
		(layer "In6.Cu")
		(net "M_H_CPU1_SB_DQ<21>")
	)
	(arc
		(start 135.887968 -227.320602)
		(mid 135.605266 -227.396378)
		(end 135.322564 -227.320602)
		(width 0.088646)
		(layer "In6.Cu")
		(net "M_H_CPU1_SB_DQ<21>")
	)
	(arc
		(start 128.369568 -228.948488)
		(mid 128.059956 -229.022101)
		(end 127.76073 -228.91369)
		(width 0.088646)
		(layer "In6.Cu")
		(net "M_H_CPU1_SB_DQ<21>")
	)
	(arc
		(start 133.442964 -227.320602)
		(mid 133.255766 -227.270459)
		(end 133.068568 -227.320602)
		(width 0.088646)
		(layer "In6.Cu")
		(net "M_H_CPU1_SB_DQ<21>")
	)
	(arc
		(start 129.300478 -227.325682)
		(mid 129.169564 -227.462042)
		(end 129.121916 -227.64496)
		(width 0.088646)
		(layer "In6.Cu")
		(net "M_H_CPU1_SB_DQ<21>")
	)
	(arc
		(start 134.382764 -227.320602)
		(mid 134.195566 -227.270459)
		(end 134.008368 -227.320602)
		(width 0.088646)
		(layer "In6.Cu")
		(net "M_H_CPU1_SB_DQ<21>")
	)
	(arc
		(start 130.249168 -227.320602)
		(mid 129.974969 -227.396437)
		(end 129.698496 -227.329238)
		(width 0.088646)
		(layer "In6.Cu")
		(net "M_H_CPU1_SB_DQ<21>")
	)
	(arc
		(start 136.827768 -227.320602)
		(mid 136.545066 -227.396378)
		(end 136.262364 -227.320602)
		(width 0.088646)
		(layer "In6.Cu")
		(net "M_H_CPU1_SB_DQ<21>")
	)
	(arc
		(start 129.683764 -227.320602)
		(mid 129.496566 -227.270459)
		(end 129.309368 -227.320602)
		(width 0.088646)
		(layer "In6.Cu")
		(net "M_H_CPU1_SB_DQ<21>")
	)
	(arc
		(start 131.563364 -227.320602)
		(mid 131.376166 -227.270459)
		(end 131.188968 -227.320602)
		(width 0.088646)
		(layer "In6.Cu")
		(net "M_H_CPU1_SB_DQ<21>")
	)
	(arc
		(start 134.008368 -227.320602)
		(mid 133.725666 -227.396378)
		(end 133.442964 -227.320602)
		(width 0.088646)
		(layer "In6.Cu")
		(net "M_H_CPU1_SB_DQ<21>")
	)
	(arc
		(start 132.503164 -227.320602)
		(mid 132.315966 -227.270459)
		(end 132.128768 -227.320602)
		(width 0.088646)
		(layer "In6.Cu")
		(net "M_H_CPU1_SB_DQ<21>")
	)
	(arc
		(start 129.121916 -227.65258)
		(mid 129.044287 -227.930993)
		(end 128.839214 -228.134672)
		(width 0.088646)
		(layer "In6.Cu")
		(net "M_H_CPU1_SB_DQ<21>")
	)
	(arc
		(start 130.623564 -227.320602)
		(mid 130.436366 -227.270459)
		(end 130.249168 -227.320602)
		(width 0.088646)
		(layer "In6.Cu")
		(net "M_H_CPU1_SB_DQ<21>")
	)
	(arc
		(start 128.651762 -228.474524)
		(mid 128.572392 -228.748258)
		(end 128.369568 -228.948488)
		(width 0.088646)
		(layer "In6.Cu")
		(net "M_H_CPU1_SB_DQ<21>")
	)
	(arc
		(start 132.128768 -227.320602)
		(mid 131.854569 -227.396437)
		(end 131.578096 -227.329238)
		(width 0.088646)
		(layer "In6.Cu")
		(net "M_H_CPU1_SB_DQ<21>")
	)
	(arc
		(start 136.262364 -227.320602)
		(mid 136.075166 -227.270459)
		(end 135.887968 -227.320602)
		(width 0.088646)
		(layer "In6.Cu")
		(net "M_H_CPU1_SB_DQ<21>")
	)
	(arc
		(start 134.948168 -227.320602)
		(mid 134.673969 -227.396437)
		(end 134.397496 -227.329238)
		(width 0.088646)
		(layer "In6.Cu")
		(net "M_H_CPU1_SB_DQ<21>")
	)
	(arc
		(start 133.068568 -227.320602)
		(mid 132.794369 -227.396437)
		(end 132.517896 -227.329238)
		(width 0.088646)
		(layer "In6.Cu")
		(net "M_H_CPU1_SB_DQ<21>")
	)
	(arc
		(start 136.944862 -227.23094)
		(mid 136.889257 -227.279614)
		(end 136.827768 -227.320602)
		(width 0.088646)
		(layer "In6.Cu")
		(net "M_H_CPU1_SB_DQ<21>")
	)
	(arc
		(start 131.188968 -227.320602)
		(mid 130.906266 -227.396378)
		(end 130.623564 -227.320602)
		(width 0.088646)
		(layer "In6.Cu")
		(net "M_H_CPU1_SB_DQ<21>")
	)
	(arc
		(start 128.830324 -228.139752)
		(mid 128.69941 -228.276112)
		(end 128.651762 -228.45903)
		(width 0.088646)
		(layer "In6.Cu")
		(net "M_H_CPU1_SB_DQ<21>")
	)
	(segment
		(start 206.971392 -207.091788)
		(end 206.626714 -207.091788)
		(width 0.20066)
		(layer "F.Cu")
		(net "M_H_CPU1_SB_DQ<20>")
	)
	(segment
		(start 209.596482 -207.085438)
		(end 209.186526 -207.085438)
		(width 0.20066)
		(layer "F.Cu")
		(net "M_H_CPU1_SB_DQ<20>")
	)
	(segment
		(start 206.508604 -207.577436)
		(end 206.320644 -207.765396)
		(width 0.20066)
		(layer "F.Cu")
		(net "M_H_CPU1_SB_DQ<20>")
	)
	(segment
		(start 209.186526 -207.085438)
		(end 209.180176 -207.091788)
		(width 0.1016)
		(layer "F.Cu")
		(net "M_H_CPU1_SB_DQ<20>")
	)
	(segment
		(start 211.619592 -207.516984)
		(end 210.028028 -207.516984)
		(width 0.20066)
		(layer "F.Cu")
		(net "M_H_CPU1_SB_DQ<20>")
	)
	(segment
		(start 210.028028 -207.516984)
		(end 209.596482 -207.085438)
		(width 0.20066)
		(layer "F.Cu")
		(net "M_H_CPU1_SB_DQ<20>")
	)
	(segment
		(start 206.320644 -207.765396)
		(end 205.84541 -207.765396)
		(width 0.20066)
		(layer "F.Cu")
		(net "M_H_CPU1_SB_DQ<20>")
	)
	(segment
		(start 204.076046 -207.51673)
		(end 202.971146 -207.51673)
		(width 0.20066)
		(layer "F.Cu")
		(net "M_H_CPU1_SB_DQ<20>")
	)
	(segment
		(start 206.508604 -207.209898)
		(end 206.508604 -207.577436)
		(width 0.20066)
		(layer "F.Cu")
		(net "M_H_CPU1_SB_DQ<20>")
	)
	(segment
		(start 126.676912 -229.808786)
		(end 126.677166 -229.808532)
		(width 0.20066)
		(layer "F.Cu")
		(net "M_H_CPU1_SB_DQ<20>")
	)
	(segment
		(start 207.018382 -207.091788)
		(end 206.971392 -207.091788)
		(width 0.101854)
		(layer "F.Cu")
		(net "M_H_CPU1_SB_DQ<20>")
	)
	(segment
		(start 205.84541 -207.765396)
		(end 205.596744 -207.51673)
		(width 0.20066)
		(layer "F.Cu")
		(net "M_H_CPU1_SB_DQ<20>")
	)
	(segment
		(start 211.619846 -207.51673)
		(end 211.619592 -207.516984)
		(width 0.20066)
		(layer "F.Cu")
		(net "M_H_CPU1_SB_DQ<20>")
	)
	(segment
		(start 206.626714 -207.091788)
		(end 206.508604 -207.209898)
		(width 0.20066)
		(layer "F.Cu")
		(net "M_H_CPU1_SB_DQ<20>")
	)
	(segment
		(start 126.677166 -229.808532)
		(end 126.677166 -229.272846)
		(width 0.20066)
		(layer "F.Cu")
		(net "M_H_CPU1_SB_DQ<20>")
	)
	(segment
		(start 205.596744 -207.51673)
		(end 204.076046 -207.51673)
		(width 0.20066)
		(layer "F.Cu")
		(net "M_H_CPU1_SB_DQ<20>")
	)
	(segment
		(start 209.180176 -207.091788)
		(end 207.018382 -207.091788)
		(width 0.1016)
		(layer "F.Cu")
		(net "M_H_CPU1_SB_DQ<20>")
	)
	(segment
		(start 175.52289 -208.919826)
		(end 175.087534 -208.919826)
		(width 0.18288)
		(layer "In6.Cu")
		(net "M_H_CPU1_SB_DQ<20>")
	)
	(segment
		(start 127.818896 -229.588568)
		(end 127.804164 -229.597204)
		(width 0.088646)
		(layer "In6.Cu")
		(net "M_H_CPU1_SB_DQ<20>")
	)
	(segment
		(start 173.455838 -209.18297)
		(end 173.234858 -208.96199)
		(width 0.18288)
		(layer "In6.Cu")
		(net "M_H_CPU1_SB_DQ<20>")
	)
	(segment
		(start 201.047604 -207.53832)
		(end 200.887584 -207.69834)
		(width 0.18288)
		(layer "In6.Cu")
		(net "M_H_CPU1_SB_DQ<20>")
	)
	(segment
		(start 129.779014 -228.134672)
		(end 129.770124 -228.139752)
		(width 0.088646)
		(layer "In6.Cu")
		(net "M_H_CPU1_SB_DQ<20>")
	)
	(segment
		(start 181.827678 -208.355184)
		(end 181.024784 -208.355184)
		(width 0.18288)
		(layer "In6.Cu")
		(net "M_H_CPU1_SB_DQ<20>")
	)
	(segment
		(start 135.418068 -228.134672)
		(end 135.407654 -228.140768)
		(width 0.088646)
		(layer "In6.Cu")
		(net "M_H_CPU1_SB_DQ<20>")
	)
	(segment
		(start 160.86328 -207.878426)
		(end 157.536642 -207.878426)
		(width 0.18288)
		(layer "In6.Cu")
		(net "M_H_CPU1_SB_DQ<20>")
	)
	(segment
		(start 170.154092 -207.942434)
		(end 164.609018 -207.942434)
		(width 0.18288)
		(layer "In6.Cu")
		(net "M_H_CPU1_SB_DQ<20>")
	)
	(segment
		(start 131.658614 -228.134672)
		(end 131.643882 -228.143308)
		(width 0.088646)
		(layer "In6.Cu")
		(net "M_H_CPU1_SB_DQ<20>")
	)
	(segment
		(start 170.474132 -208.957672)
		(end 170.314112 -208.797652)
		(width 0.18288)
		(layer "In6.Cu")
		(net "M_H_CPU1_SB_DQ<20>")
	)
	(segment
		(start 138.637772 -226.668076)
		(end 138.528806 -226.930712)
		(width 0.088646)
		(layer "In6.Cu")
		(net "M_H_CPU1_SB_DQ<20>")
	)
	(segment
		(start 175.65116 -208.791556)
		(end 175.52289 -208.919826)
		(width 0.18288)
		(layer "In6.Cu")
		(net "M_H_CPU1_SB_DQ<20>")
	)
	(segment
		(start 183.642508 -208.305908)
		(end 183.189626 -207.853026)
		(width 0.18288)
		(layer "In6.Cu")
		(net "M_H_CPU1_SB_DQ<20>")
	)
	(segment
		(start 182.329836 -207.853026)
		(end 181.827678 -208.355184)
		(width 0.18288)
		(layer "In6.Cu")
		(net "M_H_CPU1_SB_DQ<20>")
	)
	(segment
		(start 164.609018 -207.942434)
		(end 164.224208 -208.327244)
		(width 0.18288)
		(layer "In6.Cu")
		(net "M_H_CPU1_SB_DQ<20>")
	)
	(segment
		(start 201.047604 -207.174846)
		(end 201.047604 -207.53832)
		(width 0.18288)
		(layer "In6.Cu")
		(net "M_H_CPU1_SB_DQ<20>")
	)
	(segment
		(start 174.108618 -208.38541)
		(end 173.925738 -208.56829)
		(width 0.18288)
		(layer "In6.Cu")
		(net "M_H_CPU1_SB_DQ<20>")
	)
	(segment
		(start 184.946544 -208.305908)
		(end 183.642508 -208.305908)
		(width 0.18288)
		(layer "In6.Cu")
		(net "M_H_CPU1_SB_DQ<20>")
	)
	(segment
		(start 171.167552 -207.942434)
		(end 171.007532 -208.102454)
		(width 0.18288)
		(layer "In6.Cu")
		(net "M_H_CPU1_SB_DQ<20>")
	)
	(segment
		(start 178.082956 -208.79181)
		(end 175.65116 -208.791556)
		(width 0.18288)
		(layer "In6.Cu")
		(net "M_H_CPU1_SB_DQ<20>")
	)
	(segment
		(start 200.354184 -207.174846)
		(end 200.194164 -207.014826)
		(width 0.18288)
		(layer "In6.Cu")
		(net "M_H_CPU1_SB_DQ<20>")
	)
	(segment
		(start 127.401066 -229.58044)
		(end 126.677166 -229.272846)
		(width 0.088646)
		(layer "In6.Cu")
		(net "M_H_CPU1_SB_DQ<20>")
	)
	(segment
		(start 170.314112 -208.797652)
		(end 170.314112 -208.102454)
		(width 0.18288)
		(layer "In6.Cu")
		(net "M_H_CPU1_SB_DQ<20>")
	)
	(segment
		(start 171.007532 -208.797652)
		(end 170.847512 -208.957672)
		(width 0.18288)
		(layer "In6.Cu")
		(net "M_H_CPU1_SB_DQ<20>")
	)
	(segment
		(start 127.429768 -229.597204)
		(end 127.401066 -229.58044)
		(width 0.088646)
		(layer "In6.Cu")
		(net "M_H_CPU1_SB_DQ<20>")
	)
	(segment
		(start 200.354184 -207.53832)
		(end 200.354184 -207.174846)
		(width 0.18288)
		(layer "In6.Cu")
		(net "M_H_CPU1_SB_DQ<20>")
	)
	(segment
		(start 189.85484 -206.242412)
		(end 189.004956 -207.092296)
		(width 0.18288)
		(layer "In6.Cu")
		(net "M_H_CPU1_SB_DQ<20>")
	)
	(segment
		(start 164.224208 -208.327244)
		(end 161.312098 -208.327244)
		(width 0.18288)
		(layer "In6.Cu")
		(net "M_H_CPU1_SB_DQ<20>")
	)
	(segment
		(start 196.035422 -206.100426)
		(end 195.222622 -206.100426)
		(width 0.18288)
		(layer "In6.Cu")
		(net "M_H_CPU1_SB_DQ<20>")
	)
	(segment
		(start 183.189626 -207.853026)
		(end 182.329836 -207.853026)
		(width 0.18288)
		(layer "In6.Cu")
		(net "M_H_CPU1_SB_DQ<20>")
	)
	(segment
		(start 173.038262 -207.942434)
		(end 171.167552 -207.942434)
		(width 0.18288)
		(layer "In6.Cu")
		(net "M_H_CPU1_SB_DQ<20>")
	)
	(segment
		(start 200.514204 -207.69834)
		(end 200.354184 -207.53832)
		(width 0.18288)
		(layer "In6.Cu")
		(net "M_H_CPU1_SB_DQ<20>")
	)
	(segment
		(start 192.736216 -206.242412)
		(end 189.85484 -206.242412)
		(width 0.18288)
		(layer "In6.Cu")
		(net "M_H_CPU1_SB_DQ<20>")
	)
	(segment
		(start 189.004956 -207.092296)
		(end 186.160156 -207.092296)
		(width 0.18288)
		(layer "In6.Cu")
		(net "M_H_CPU1_SB_DQ<20>")
	)
	(segment
		(start 181.024784 -208.355184)
		(end 180.611018 -207.941418)
		(width 0.18288)
		(layer "In6.Cu")
		(net "M_H_CPU1_SB_DQ<20>")
	)
	(segment
		(start 171.007532 -208.102454)
		(end 171.007532 -208.797652)
		(width 0.18288)
		(layer "In6.Cu")
		(net "M_H_CPU1_SB_DQ<20>")
	)
	(segment
		(start 198.43623 -207.014826)
		(end 198.121016 -207.33004)
		(width 0.18288)
		(layer "In6.Cu")
		(net "M_H_CPU1_SB_DQ<20>")
	)
	(segment
		(start 157.536642 -207.878426)
		(end 139.915138 -225.49993)
		(width 0.18288)
		(layer "In6.Cu")
		(net "M_H_CPU1_SB_DQ<20>")
	)
	(segment
		(start 180.611018 -207.941418)
		(end 178.440334 -207.941672)
		(width 0.18288)
		(layer "In6.Cu")
		(net "M_H_CPU1_SB_DQ<20>")
	)
	(segment
		(start 139.680188 -225.62566)
		(end 138.637772 -226.668076)
		(width 0.088646)
		(layer "In6.Cu")
		(net "M_H_CPU1_SB_DQ<20>")
	)
	(segment
		(start 178.280314 -208.101692)
		(end 178.280314 -208.594452)
		(width 0.18288)
		(layer "In6.Cu")
		(net "M_H_CPU1_SB_DQ<20>")
	)
	(segment
		(start 173.925738 -208.56829)
		(end 173.925738 -209.00009)
		(width 0.18288)
		(layer "In6.Cu")
		(net "M_H_CPU1_SB_DQ<20>")
	)
	(segment
		(start 175.087534 -208.919826)
		(end 174.553118 -208.38541)
		(width 0.18288)
		(layer "In6.Cu")
		(net "M_H_CPU1_SB_DQ<20>")
	)
	(segment
		(start 186.160156 -207.092296)
		(end 184.946544 -208.305908)
		(width 0.18288)
		(layer "In6.Cu")
		(net "M_H_CPU1_SB_DQ<20>")
	)
	(segment
		(start 200.194164 -207.014826)
		(end 198.43623 -207.014826)
		(width 0.18288)
		(layer "In6.Cu")
		(net "M_H_CPU1_SB_DQ<20>")
	)
	(segment
		(start 197.265036 -207.33004)
		(end 196.035422 -206.100426)
		(width 0.18288)
		(layer "In6.Cu")
		(net "M_H_CPU1_SB_DQ<20>")
	)
	(segment
		(start 194.695826 -206.627222)
		(end 193.121026 -206.627222)
		(width 0.18288)
		(layer "In6.Cu")
		(net "M_H_CPU1_SB_DQ<20>")
	)
	(segment
		(start 202.469242 -207.014826)
		(end 201.207624 -207.014826)
		(width 0.18288)
		(layer "In6.Cu")
		(net "M_H_CPU1_SB_DQ<20>")
	)
	(segment
		(start 161.312098 -208.327244)
		(end 160.86328 -207.878426)
		(width 0.18288)
		(layer "In6.Cu")
		(net "M_H_CPU1_SB_DQ<20>")
	)
	(segment
		(start 173.925738 -209.00009)
		(end 173.742858 -209.18297)
		(width 0.18288)
		(layer "In6.Cu")
		(net "M_H_CPU1_SB_DQ<20>")
	)
	(segment
		(start 178.440334 -207.941672)
		(end 178.280314 -208.101692)
		(width 0.18288)
		(layer "In6.Cu")
		(net "M_H_CPU1_SB_DQ<20>")
	)
	(segment
		(start 173.234858 -208.96199)
		(end 173.234858 -208.13903)
		(width 0.18288)
		(layer "In6.Cu")
		(net "M_H_CPU1_SB_DQ<20>")
	)
	(segment
		(start 170.314112 -208.102454)
		(end 170.154092 -207.942434)
		(width 0.18288)
		(layer "In6.Cu")
		(net "M_H_CPU1_SB_DQ<20>")
	)
	(segment
		(start 170.847512 -208.957672)
		(end 170.474132 -208.957672)
		(width 0.18288)
		(layer "In6.Cu")
		(net "M_H_CPU1_SB_DQ<20>")
	)
	(segment
		(start 201.207624 -207.014826)
		(end 201.047604 -207.174846)
		(width 0.18288)
		(layer "In6.Cu")
		(net "M_H_CPU1_SB_DQ<20>")
	)
	(segment
		(start 173.742858 -209.18297)
		(end 173.455838 -209.18297)
		(width 0.18288)
		(layer "In6.Cu")
		(net "M_H_CPU1_SB_DQ<20>")
	)
	(segment
		(start 129.140458 -229.15626)
		(end 128.915922 -229.400354)
		(width 0.088646)
		(layer "In6.Cu")
		(net "M_H_CPU1_SB_DQ<20>")
	)
	(segment
		(start 134.478014 -228.134672)
		(end 134.4676 -228.140768)
		(width 0.088646)
		(layer "In6.Cu")
		(net "M_H_CPU1_SB_DQ<20>")
	)
	(segment
		(start 138.528806 -226.930712)
		(end 137.414762 -228.044756)
		(width 0.088646)
		(layer "In6.Cu")
		(net "M_H_CPU1_SB_DQ<20>")
	)
	(segment
		(start 193.121026 -206.627222)
		(end 192.736216 -206.242412)
		(width 0.18288)
		(layer "In6.Cu")
		(net "M_H_CPU1_SB_DQ<20>")
	)
	(segment
		(start 129.591562 -228.45903)
		(end 129.591562 -228.468936)
		(width 0.088646)
		(layer "In6.Cu")
		(net "M_H_CPU1_SB_DQ<20>")
	)
	(segment
		(start 139.789408 -225.62566)
		(end 139.680188 -225.62566)
		(width 0.088646)
		(layer "In6.Cu")
		(net "M_H_CPU1_SB_DQ<20>")
	)
	(segment
		(start 198.121016 -207.33004)
		(end 197.265036 -207.33004)
		(width 0.18288)
		(layer "In6.Cu")
		(net "M_H_CPU1_SB_DQ<20>")
	)
	(segment
		(start 130.718814 -228.134672)
		(end 130.704082 -228.143308)
		(width 0.088646)
		(layer "In6.Cu")
		(net "M_H_CPU1_SB_DQ<20>")
	)
	(segment
		(start 174.553118 -208.38541)
		(end 174.108618 -208.38541)
		(width 0.18288)
		(layer "In6.Cu")
		(net "M_H_CPU1_SB_DQ<20>")
	)
	(segment
		(start 132.598668 -228.134672)
		(end 132.588254 -228.140768)
		(width 0.088646)
		(layer "In6.Cu")
		(net "M_H_CPU1_SB_DQ<20>")
	)
	(segment
		(start 139.915138 -225.49993)
		(end 139.789408 -225.62566)
		(width 0.088646)
		(layer "In6.Cu")
		(net "M_H_CPU1_SB_DQ<20>")
	)
	(segment
		(start 173.234858 -208.13903)
		(end 173.038262 -207.942434)
		(width 0.18288)
		(layer "In6.Cu")
		(net "M_H_CPU1_SB_DQ<20>")
	)
	(segment
		(start 195.222622 -206.100426)
		(end 194.695826 -206.627222)
		(width 0.18288)
		(layer "In6.Cu")
		(net "M_H_CPU1_SB_DQ<20>")
	)
	(segment
		(start 202.971146 -207.51673)
		(end 202.469242 -207.014826)
		(width 0.18288)
		(layer "In6.Cu")
		(net "M_H_CPU1_SB_DQ<20>")
	)
	(segment
		(start 178.280314 -208.594452)
		(end 178.082956 -208.79181)
		(width 0.18288)
		(layer "In6.Cu")
		(net "M_H_CPU1_SB_DQ<20>")
	)
	(segment
		(start 200.887584 -207.69834)
		(end 200.514204 -207.69834)
		(width 0.18288)
		(layer "In6.Cu")
		(net "M_H_CPU1_SB_DQ<20>")
	)
	(arc
		(start 132.03301 -228.134672)
		(mid 131.845812 -228.084529)
		(end 131.658614 -228.134672)
		(width 0.088646)
		(layer "In6.Cu")
		(net "M_H_CPU1_SB_DQ<20>")
	)
	(arc
		(start 133.538468 -228.134672)
		(mid 133.255766 -228.210414)
		(end 132.973064 -228.134672)
		(width 0.088646)
		(layer "In6.Cu")
		(net "M_H_CPU1_SB_DQ<20>")
	)
	(arc
		(start 137.297668 -228.134672)
		(mid 137.014966 -228.210414)
		(end 136.732264 -228.134672)
		(width 0.088646)
		(layer "In6.Cu")
		(net "M_H_CPU1_SB_DQ<20>")
	)
	(arc
		(start 128.915922 -229.400354)
		(mid 128.845811 -229.51264)
		(end 128.743964 -229.597204)
		(width 0.088646)
		(layer "In6.Cu")
		(net "M_H_CPU1_SB_DQ<20>")
	)
	(arc
		(start 129.591562 -228.468936)
		(mid 129.513451 -228.745885)
		(end 129.309114 -228.948488)
		(width 0.088646)
		(layer "In6.Cu")
		(net "M_H_CPU1_SB_DQ<20>")
	)
	(arc
		(start 132.588254 -228.140768)
		(mid 132.309822 -228.210582)
		(end 132.03301 -228.134672)
		(width 0.088646)
		(layer "In6.Cu")
		(net "M_H_CPU1_SB_DQ<20>")
	)
	(arc
		(start 131.643882 -228.143308)
		(mid 131.367441 -228.210474)
		(end 131.09321 -228.134672)
		(width 0.088646)
		(layer "In6.Cu")
		(net "M_H_CPU1_SB_DQ<20>")
	)
	(arc
		(start 135.407654 -228.140768)
		(mid 135.129222 -228.210582)
		(end 134.85241 -228.134672)
		(width 0.088646)
		(layer "In6.Cu")
		(net "M_H_CPU1_SB_DQ<20>")
	)
	(arc
		(start 136.732264 -228.134672)
		(mid 136.545066 -228.084529)
		(end 136.357868 -228.134672)
		(width 0.088646)
		(layer "In6.Cu")
		(net "M_H_CPU1_SB_DQ<20>")
	)
	(arc
		(start 130.704082 -228.143308)
		(mid 130.427641 -228.210474)
		(end 130.15341 -228.134672)
		(width 0.088646)
		(layer "In6.Cu")
		(net "M_H_CPU1_SB_DQ<20>")
	)
	(arc
		(start 129.309114 -228.948488)
		(mid 129.205577 -229.036786)
		(end 129.140458 -229.15626)
		(width 0.088646)
		(layer "In6.Cu")
		(net "M_H_CPU1_SB_DQ<20>")
	)
	(arc
		(start 127.804164 -229.597204)
		(mid 127.616966 -229.647347)
		(end 127.429768 -229.597204)
		(width 0.088646)
		(layer "In6.Cu")
		(net "M_H_CPU1_SB_DQ<20>")
	)
	(arc
		(start 135.792464 -228.134672)
		(mid 135.605266 -228.084529)
		(end 135.418068 -228.134672)
		(width 0.088646)
		(layer "In6.Cu")
		(net "M_H_CPU1_SB_DQ<20>")
	)
	(arc
		(start 131.09321 -228.134672)
		(mid 130.906012 -228.084529)
		(end 130.718814 -228.134672)
		(width 0.088646)
		(layer "In6.Cu")
		(net "M_H_CPU1_SB_DQ<20>")
	)
	(arc
		(start 129.770124 -228.139752)
		(mid 129.63921 -228.276112)
		(end 129.591562 -228.45903)
		(width 0.088646)
		(layer "In6.Cu")
		(net "M_H_CPU1_SB_DQ<20>")
	)
	(arc
		(start 134.85241 -228.134672)
		(mid 134.665212 -228.084529)
		(end 134.478014 -228.134672)
		(width 0.088646)
		(layer "In6.Cu")
		(net "M_H_CPU1_SB_DQ<20>")
	)
	(arc
		(start 130.15341 -228.134672)
		(mid 129.966212 -228.084529)
		(end 129.779014 -228.134672)
		(width 0.088646)
		(layer "In6.Cu")
		(net "M_H_CPU1_SB_DQ<20>")
	)
	(arc
		(start 137.414762 -228.044756)
		(mid 137.35916 -228.093549)
		(end 137.297668 -228.134672)
		(width 0.088646)
		(layer "In6.Cu")
		(net "M_H_CPU1_SB_DQ<20>")
	)
	(arc
		(start 128.369568 -229.597204)
		(mid 128.095369 -229.521369)
		(end 127.818896 -229.588568)
		(width 0.088646)
		(layer "In6.Cu")
		(net "M_H_CPU1_SB_DQ<20>")
	)
	(arc
		(start 128.743964 -229.597204)
		(mid 128.556766 -229.647347)
		(end 128.369568 -229.597204)
		(width 0.088646)
		(layer "In6.Cu")
		(net "M_H_CPU1_SB_DQ<20>")
	)
	(arc
		(start 134.4676 -228.140768)
		(mid 134.189422 -228.21046)
		(end 133.912864 -228.134672)
		(width 0.088646)
		(layer "In6.Cu")
		(net "M_H_CPU1_SB_DQ<20>")
	)
	(arc
		(start 136.357868 -228.134672)
		(mid 136.075166 -228.210414)
		(end 135.792464 -228.134672)
		(width 0.088646)
		(layer "In6.Cu")
		(net "M_H_CPU1_SB_DQ<20>")
	)
	(arc
		(start 133.912864 -228.134672)
		(mid 133.725666 -228.084529)
		(end 133.538468 -228.134672)
		(width 0.088646)
		(layer "In6.Cu")
		(net "M_H_CPU1_SB_DQ<20>")
	)
	(arc
		(start 132.973064 -228.134672)
		(mid 132.785866 -228.084529)
		(end 132.598668 -228.134672)
		(width 0.088646)
		(layer "In6.Cu")
		(net "M_H_CPU1_SB_DQ<20>")
	)
	(segment
		(start 209.596482 -230.035354)
		(end 209.186526 -230.035354)
		(width 0.20066)
		(layer "F.Cu")
		(net "M_H_CPU1_SB_DQ<1>")
	)
	(segment
		(start 123.387866 -238.761524)
		(end 123.387612 -238.76127)
		(width 0.20066)
		(layer "F.Cu")
		(net "M_H_CPU1_SB_DQ<1>")
	)
	(segment
		(start 206.626714 -230.041704)
		(end 206.508604 -230.159814)
		(width 0.20066)
		(layer "F.Cu")
		(net "M_H_CPU1_SB_DQ<1>")
	)
	(segment
		(start 205.84541 -230.715312)
		(end 205.596744 -230.466646)
		(width 0.20066)
		(layer "F.Cu")
		(net "M_H_CPU1_SB_DQ<1>")
	)
	(segment
		(start 204.076046 -230.466646)
		(end 202.971146 -230.466646)
		(width 0.20066)
		(layer "F.Cu")
		(net "M_H_CPU1_SB_DQ<1>")
	)
	(segment
		(start 209.180176 -230.041704)
		(end 206.991458 -230.041704)
		(width 0.1016)
		(layer "F.Cu")
		(net "M_H_CPU1_SB_DQ<1>")
	)
	(segment
		(start 206.971392 -230.041704)
		(end 206.626714 -230.041704)
		(width 0.20066)
		(layer "F.Cu")
		(net "M_H_CPU1_SB_DQ<1>")
	)
	(segment
		(start 206.320644 -230.715312)
		(end 205.84541 -230.715312)
		(width 0.20066)
		(layer "F.Cu")
		(net "M_H_CPU1_SB_DQ<1>")
	)
	(segment
		(start 206.508604 -230.527352)
		(end 206.320644 -230.715312)
		(width 0.20066)
		(layer "F.Cu")
		(net "M_H_CPU1_SB_DQ<1>")
	)
	(segment
		(start 209.186526 -230.035354)
		(end 209.180176 -230.041704)
		(width 0.1016)
		(layer "F.Cu")
		(net "M_H_CPU1_SB_DQ<1>")
	)
	(segment
		(start 210.028028 -230.4669)
		(end 209.596482 -230.035354)
		(width 0.20066)
		(layer "F.Cu")
		(net "M_H_CPU1_SB_DQ<1>")
	)
	(segment
		(start 205.596744 -230.466646)
		(end 204.076046 -230.466646)
		(width 0.20066)
		(layer "F.Cu")
		(net "M_H_CPU1_SB_DQ<1>")
	)
	(segment
		(start 211.619846 -230.466646)
		(end 211.619592 -230.4669)
		(width 0.20066)
		(layer "F.Cu")
		(net "M_H_CPU1_SB_DQ<1>")
	)
	(segment
		(start 211.619592 -230.4669)
		(end 210.028028 -230.4669)
		(width 0.20066)
		(layer "F.Cu")
		(net "M_H_CPU1_SB_DQ<1>")
	)
	(segment
		(start 206.991458 -230.041704)
		(end 206.971392 -230.041704)
		(width 0.101854)
		(layer "F.Cu")
		(net "M_H_CPU1_SB_DQ<1>")
	)
	(segment
		(start 123.387612 -238.76127)
		(end 123.387612 -238.225584)
		(width 0.20066)
		(layer "F.Cu")
		(net "M_H_CPU1_SB_DQ<1>")
	)
	(segment
		(start 206.508604 -230.159814)
		(end 206.508604 -230.527352)
		(width 0.20066)
		(layer "F.Cu")
		(net "M_H_CPU1_SB_DQ<1>")
	)
	(segment
		(start 200.635108 -230.497634)
		(end 200.442068 -230.304594)
		(width 0.18288)
		(layer "In11.Cu")
		(net "M_H_CPU1_SB_DQ<1>")
	)
	(segment
		(start 145.781522 -238.466884)
		(end 141.103096 -238.466884)
		(width 0.18288)
		(layer "In11.Cu")
		(net "M_H_CPU1_SB_DQ<1>")
	)
	(segment
		(start 141.103096 -238.466884)
		(end 140.44168 -238.466884)
		(width 0.088646)
		(layer "In11.Cu")
		(net "M_H_CPU1_SB_DQ<1>")
	)
	(segment
		(start 200.952608 -230.497634)
		(end 200.635108 -230.497634)
		(width 0.18288)
		(layer "In11.Cu")
		(net "M_H_CPU1_SB_DQ<1>")
	)
	(segment
		(start 177.549302 -226.638866)
		(end 176.309274 -226.638866)
		(width 0.18288)
		(layer "In11.Cu")
		(net "M_H_CPU1_SB_DQ<1>")
	)
	(segment
		(start 200.249028 -229.824026)
		(end 199.013826 -229.824026)
		(width 0.18288)
		(layer "In11.Cu")
		(net "M_H_CPU1_SB_DQ<1>")
	)
	(segment
		(start 181.479444 -227.043742)
		(end 181.161944 -227.043742)
		(width 0.18288)
		(layer "In11.Cu")
		(net "M_H_CPU1_SB_DQ<1>")
	)
	(segment
		(start 129.693924 -238.721138)
		(end 129.68351 -238.715042)
		(width 0.088646)
		(layer "In11.Cu")
		(net "M_H_CPU1_SB_DQ<1>")
	)
	(segment
		(start 188.245242 -225.963226)
		(end 188.072776 -225.79076)
		(width 0.18288)
		(layer "In11.Cu")
		(net "M_H_CPU1_SB_DQ<1>")
	)
	(segment
		(start 163.240466 -228.90099)
		(end 163.015676 -229.12578)
		(width 0.18288)
		(layer "In11.Cu")
		(net "M_H_CPU1_SB_DQ<1>")
	)
	(segment
		(start 201.145648 -230.017066)
		(end 201.145648 -230.304594)
		(width 0.18288)
		(layer "In11.Cu")
		(net "M_H_CPU1_SB_DQ<1>")
	)
	(segment
		(start 180.968904 -226.516184)
		(end 180.775864 -226.323144)
		(width 0.18288)
		(layer "In11.Cu")
		(net "M_H_CPU1_SB_DQ<1>")
	)
	(segment
		(start 173.735746 -227.490782)
		(end 172.021754 -227.490782)
		(width 0.18288)
		(layer "In11.Cu")
		(net "M_H_CPU1_SB_DQ<1>")
	)
	(segment
		(start 187.41136 -225.79076)
		(end 187.206636 -225.586036)
		(width 0.18288)
		(layer "In11.Cu")
		(net "M_H_CPU1_SB_DQ<1>")
	)
	(segment
		(start 164.522912 -228.124512)
		(end 164.292026 -227.893626)
		(width 0.18288)
		(layer "In11.Cu")
		(net "M_H_CPU1_SB_DQ<1>")
	)
	(segment
		(start 177.742342 -226.445826)
		(end 177.549302 -226.638866)
		(width 0.18288)
		(layer "In11.Cu")
		(net "M_H_CPU1_SB_DQ<1>")
	)
	(segment
		(start 140.44168 -238.466884)
		(end 140.195554 -238.71301)
		(width 0.088646)
		(layer "In11.Cu")
		(net "M_H_CPU1_SB_DQ<1>")
	)
	(segment
		(start 171.828714 -228.138736)
		(end 171.635674 -228.331776)
		(width 0.18288)
		(layer "In11.Cu")
		(net "M_H_CPU1_SB_DQ<1>")
	)
	(segment
		(start 124.059696 -238.723678)
		(end 124.044964 -238.715042)
		(width 0.088646)
		(layer "In11.Cu")
		(net "M_H_CPU1_SB_DQ<1>")
	)
	(segment
		(start 179.883308 -226.323144)
		(end 179.557426 -226.649026)
		(width 0.18288)
		(layer "In11.Cu")
		(net "M_H_CPU1_SB_DQ<1>")
	)
	(segment
		(start 196.821044 -229.180644)
		(end 195.940426 -228.300026)
		(width 0.18288)
		(layer "In11.Cu")
		(net "M_H_CPU1_SB_DQ<1>")
	)
	(segment
		(start 202.796394 -230.016558)
		(end 202.331574 -229.824026)
		(width 0.18288)
		(layer "In11.Cu")
		(net "M_H_CPU1_SB_DQ<1>")
	)
	(segment
		(start 178.445922 -226.108768)
		(end 178.252882 -225.915728)
		(width 0.18288)
		(layer "In11.Cu")
		(net "M_H_CPU1_SB_DQ<1>")
	)
	(segment
		(start 187.206636 -225.586036)
		(end 186.164982 -225.586036)
		(width 0.18288)
		(layer "In11.Cu")
		(net "M_H_CPU1_SB_DQ<1>")
	)
	(segment
		(start 200.442068 -230.304594)
		(end 200.442068 -230.017066)
		(width 0.18288)
		(layer "In11.Cu")
		(net "M_H_CPU1_SB_DQ<1>")
	)
	(segment
		(start 194.34937 -227.411026)
		(end 193.857626 -227.411026)
		(width 0.18288)
		(layer "In11.Cu")
		(net "M_H_CPU1_SB_DQ<1>")
	)
	(segment
		(start 168.91127 -227.490782)
		(end 168.27754 -228.124512)
		(width 0.18288)
		(layer "In11.Cu")
		(net "M_H_CPU1_SB_DQ<1>")
	)
	(segment
		(start 176.309274 -226.638866)
		(end 176.173384 -226.502976)
		(width 0.18288)
		(layer "In11.Cu")
		(net "M_H_CPU1_SB_DQ<1>")
	)
	(segment
		(start 180.968904 -226.850702)
		(end 180.968904 -226.516184)
		(width 0.18288)
		(layer "In11.Cu")
		(net "M_H_CPU1_SB_DQ<1>")
	)
	(segment
		(start 195.23837 -228.300026)
		(end 194.34937 -227.411026)
		(width 0.18288)
		(layer "In11.Cu")
		(net "M_H_CPU1_SB_DQ<1>")
	)
	(segment
		(start 178.252882 -225.915728)
		(end 177.935382 -225.915728)
		(width 0.18288)
		(layer "In11.Cu")
		(net "M_H_CPU1_SB_DQ<1>")
	)
	(segment
		(start 181.865524 -226.323144)
		(end 181.672484 -226.516184)
		(width 0.18288)
		(layer "In11.Cu")
		(net "M_H_CPU1_SB_DQ<1>")
	)
	(segment
		(start 191.336422 -226.642422)
		(end 190.657226 -225.963226)
		(width 0.18288)
		(layer "In11.Cu")
		(net "M_H_CPU1_SB_DQ<1>")
	)
	(segment
		(start 177.935382 -225.915728)
		(end 177.742342 -226.108768)
		(width 0.18288)
		(layer "In11.Cu")
		(net "M_H_CPU1_SB_DQ<1>")
	)
	(segment
		(start 180.775864 -226.323144)
		(end 179.883308 -226.323144)
		(width 0.18288)
		(layer "In11.Cu")
		(net "M_H_CPU1_SB_DQ<1>")
	)
	(segment
		(start 191.93256 -226.642422)
		(end 191.336422 -226.642422)
		(width 0.18288)
		(layer "In11.Cu")
		(net "M_H_CPU1_SB_DQ<1>")
	)
	(segment
		(start 185.778902 -226.290378)
		(end 185.461402 -226.290378)
		(width 0.18288)
		(layer "In11.Cu")
		(net "M_H_CPU1_SB_DQ<1>")
	)
	(segment
		(start 124.044964 -238.715042)
		(end 123.952762 -238.661194)
		(width 0.088646)
		(layer "In11.Cu")
		(net "M_H_CPU1_SB_DQ<1>")
	)
	(segment
		(start 170.932094 -227.490782)
		(end 170.372532 -227.490782)
		(width 0.18288)
		(layer "In11.Cu")
		(net "M_H_CPU1_SB_DQ<1>")
	)
	(segment
		(start 198.370444 -229.180644)
		(end 196.821044 -229.180644)
		(width 0.18288)
		(layer "In11.Cu")
		(net "M_H_CPU1_SB_DQ<1>")
	)
	(segment
		(start 162.07867 -229.192582)
		(end 160.900618 -229.192582)
		(width 0.18288)
		(layer "In11.Cu")
		(net "M_H_CPU1_SB_DQ<1>")
	)
	(segment
		(start 159.056578 -229.04577)
		(end 158.059882 -230.042466)
		(width 0.18288)
		(layer "In11.Cu")
		(net "M_H_CPU1_SB_DQ<1>")
	)
	(segment
		(start 202.331574 -229.824026)
		(end 201.338688 -229.824026)
		(width 0.18288)
		(layer "In11.Cu")
		(net "M_H_CPU1_SB_DQ<1>")
	)
	(segment
		(start 131.578096 -238.723678)
		(end 131.563364 -238.715042)
		(width 0.088646)
		(layer "In11.Cu")
		(net "M_H_CPU1_SB_DQ<1>")
	)
	(segment
		(start 171.125134 -227.683822)
		(end 170.932094 -227.490782)
		(width 0.18288)
		(layer "In11.Cu")
		(net "M_H_CPU1_SB_DQ<1>")
	)
	(segment
		(start 164.292026 -227.893626)
		(end 163.377626 -227.893626)
		(width 0.18288)
		(layer "In11.Cu")
		(net "M_H_CPU1_SB_DQ<1>")
	)
	(segment
		(start 172.021754 -227.490782)
		(end 171.828714 -227.683822)
		(width 0.18288)
		(layer "In11.Cu")
		(net "M_H_CPU1_SB_DQ<1>")
	)
	(segment
		(start 138.197336 -238.71301)
		(end 138.185652 -238.701326)
		(width 0.088646)
		(layer "In11.Cu")
		(net "M_H_CPU1_SB_DQ<1>")
	)
	(segment
		(start 191.934338 -226.640644)
		(end 191.93256 -226.642422)
		(width 0.18288)
		(layer "In11.Cu")
		(net "M_H_CPU1_SB_DQ<1>")
	)
	(segment
		(start 181.672484 -226.516184)
		(end 181.672484 -226.850702)
		(width 0.18288)
		(layer "In11.Cu")
		(net "M_H_CPU1_SB_DQ<1>")
	)
	(segment
		(start 163.240466 -228.628194)
		(end 163.240466 -228.90099)
		(width 0.18288)
		(layer "In11.Cu")
		(net "M_H_CPU1_SB_DQ<1>")
	)
	(segment
		(start 171.635674 -228.331776)
		(end 171.318174 -228.331776)
		(width 0.18288)
		(layer "In11.Cu")
		(net "M_H_CPU1_SB_DQ<1>")
	)
	(segment
		(start 200.442068 -230.017066)
		(end 200.249028 -229.824026)
		(width 0.18288)
		(layer "In11.Cu")
		(net "M_H_CPU1_SB_DQ<1>")
	)
	(segment
		(start 162.307778 -228.963474)
		(end 162.07867 -229.192582)
		(width 0.18288)
		(layer "In11.Cu")
		(net "M_H_CPU1_SB_DQ<1>")
	)
	(segment
		(start 185.971942 -226.097338)
		(end 185.778902 -226.290378)
		(width 0.18288)
		(layer "In11.Cu")
		(net "M_H_CPU1_SB_DQ<1>")
	)
	(segment
		(start 170.07586 -227.787454)
		(end 169.668952 -227.787454)
		(width 0.18288)
		(layer "In11.Cu")
		(net "M_H_CPU1_SB_DQ<1>")
	)
	(segment
		(start 185.971942 -225.779076)
		(end 185.971942 -226.097338)
		(width 0.18288)
		(layer "In11.Cu")
		(net "M_H_CPU1_SB_DQ<1>")
	)
	(segment
		(start 193.857626 -227.411026)
		(end 193.087244 -226.640644)
		(width 0.18288)
		(layer "In11.Cu")
		(net "M_H_CPU1_SB_DQ<1>")
	)
	(segment
		(start 185.268362 -225.779076)
		(end 185.075322 -225.586036)
		(width 0.18288)
		(layer "In11.Cu")
		(net "M_H_CPU1_SB_DQ<1>")
	)
	(segment
		(start 181.161944 -227.043742)
		(end 180.968904 -226.850702)
		(width 0.18288)
		(layer "In11.Cu")
		(net "M_H_CPU1_SB_DQ<1>")
	)
	(segment
		(start 158.059882 -230.042466)
		(end 154.20594 -230.042466)
		(width 0.18288)
		(layer "In11.Cu")
		(net "M_H_CPU1_SB_DQ<1>")
	)
	(segment
		(start 188.072776 -225.79076)
		(end 187.41136 -225.79076)
		(width 0.18288)
		(layer "In11.Cu")
		(net "M_H_CPU1_SB_DQ<1>")
	)
	(segment
		(start 185.461402 -226.290378)
		(end 185.268362 -226.097338)
		(width 0.18288)
		(layer "In11.Cu")
		(net "M_H_CPU1_SB_DQ<1>")
	)
	(segment
		(start 163.015676 -229.12578)
		(end 162.74288 -229.12578)
		(width 0.18288)
		(layer "In11.Cu")
		(net "M_H_CPU1_SB_DQ<1>")
	)
	(segment
		(start 162.74288 -229.12578)
		(end 162.580574 -228.963474)
		(width 0.18288)
		(layer "In11.Cu")
		(net "M_H_CPU1_SB_DQ<1>")
	)
	(segment
		(start 126.879096 -238.723678)
		(end 126.864364 -238.715042)
		(width 0.088646)
		(layer "In11.Cu")
		(net "M_H_CPU1_SB_DQ<1>")
	)
	(segment
		(start 171.828714 -227.683822)
		(end 171.828714 -228.138736)
		(width 0.18288)
		(layer "In11.Cu")
		(net "M_H_CPU1_SB_DQ<1>")
	)
	(segment
		(start 130.638296 -238.723678)
		(end 130.623564 -238.715042)
		(width 0.088646)
		(layer "In11.Cu")
		(net "M_H_CPU1_SB_DQ<1>")
	)
	(segment
		(start 202.971146 -230.466646)
		(end 202.971146 -230.19131)
		(width 0.18288)
		(layer "In11.Cu")
		(net "M_H_CPU1_SB_DQ<1>")
	)
	(segment
		(start 168.27754 -228.124512)
		(end 164.522912 -228.124512)
		(width 0.18288)
		(layer "In11.Cu")
		(net "M_H_CPU1_SB_DQ<1>")
	)
	(segment
		(start 124.999496 -238.723678)
		(end 124.984764 -238.715042)
		(width 0.088646)
		(layer "In11.Cu")
		(net "M_H_CPU1_SB_DQ<1>")
	)
	(segment
		(start 160.900618 -229.192582)
		(end 160.753806 -229.04577)
		(width 0.18288)
		(layer "In11.Cu")
		(net "M_H_CPU1_SB_DQ<1>")
	)
	(segment
		(start 186.164982 -225.586036)
		(end 185.971942 -225.779076)
		(width 0.18288)
		(layer "In11.Cu")
		(net "M_H_CPU1_SB_DQ<1>")
	)
	(segment
		(start 185.268362 -226.097338)
		(end 185.268362 -225.779076)
		(width 0.18288)
		(layer "In11.Cu")
		(net "M_H_CPU1_SB_DQ<1>")
	)
	(segment
		(start 202.971146 -230.19131)
		(end 202.796394 -230.016558)
		(width 0.18288)
		(layer "In11.Cu")
		(net "M_H_CPU1_SB_DQ<1>")
	)
	(segment
		(start 171.125134 -228.138736)
		(end 171.125134 -227.683822)
		(width 0.18288)
		(layer "In11.Cu")
		(net "M_H_CPU1_SB_DQ<1>")
	)
	(segment
		(start 199.013826 -229.824026)
		(end 198.370444 -229.180644)
		(width 0.18288)
		(layer "In11.Cu")
		(net "M_H_CPU1_SB_DQ<1>")
	)
	(segment
		(start 178.638962 -226.649026)
		(end 178.445922 -226.455986)
		(width 0.18288)
		(layer "In11.Cu")
		(net "M_H_CPU1_SB_DQ<1>")
	)
	(segment
		(start 185.075322 -225.586036)
		(end 183.818784 -225.586036)
		(width 0.18288)
		(layer "In11.Cu")
		(net "M_H_CPU1_SB_DQ<1>")
	)
	(segment
		(start 183.818784 -225.586036)
		(end 183.081676 -226.323144)
		(width 0.18288)
		(layer "In11.Cu")
		(net "M_H_CPU1_SB_DQ<1>")
	)
	(segment
		(start 163.07816 -228.193092)
		(end 163.07816 -228.465888)
		(width 0.18288)
		(layer "In11.Cu")
		(net "M_H_CPU1_SB_DQ<1>")
	)
	(segment
		(start 162.580574 -228.963474)
		(end 162.307778 -228.963474)
		(width 0.18288)
		(layer "In11.Cu")
		(net "M_H_CPU1_SB_DQ<1>")
	)
	(segment
		(start 169.668952 -227.787454)
		(end 169.37228 -227.490782)
		(width 0.18288)
		(layer "In11.Cu")
		(net "M_H_CPU1_SB_DQ<1>")
	)
	(segment
		(start 179.557426 -226.649026)
		(end 178.638962 -226.649026)
		(width 0.18288)
		(layer "In11.Cu")
		(net "M_H_CPU1_SB_DQ<1>")
	)
	(segment
		(start 163.377626 -227.893626)
		(end 163.07816 -228.193092)
		(width 0.18288)
		(layer "In11.Cu")
		(net "M_H_CPU1_SB_DQ<1>")
	)
	(segment
		(start 127.818896 -238.723678)
		(end 127.804164 -238.715042)
		(width 0.088646)
		(layer "In11.Cu")
		(net "M_H_CPU1_SB_DQ<1>")
	)
	(segment
		(start 176.173384 -226.502976)
		(end 174.723552 -226.502976)
		(width 0.18288)
		(layer "In11.Cu")
		(net "M_H_CPU1_SB_DQ<1>")
	)
	(segment
		(start 181.672484 -226.850702)
		(end 181.479444 -227.043742)
		(width 0.18288)
		(layer "In11.Cu")
		(net "M_H_CPU1_SB_DQ<1>")
	)
	(segment
		(start 163.07816 -228.465888)
		(end 163.240466 -228.628194)
		(width 0.18288)
		(layer "In11.Cu")
		(net "M_H_CPU1_SB_DQ<1>")
	)
	(segment
		(start 190.657226 -225.963226)
		(end 188.245242 -225.963226)
		(width 0.18288)
		(layer "In11.Cu")
		(net "M_H_CPU1_SB_DQ<1>")
	)
	(segment
		(start 140.195554 -238.71301)
		(end 138.197336 -238.71301)
		(width 0.088646)
		(layer "In11.Cu")
		(net "M_H_CPU1_SB_DQ<1>")
	)
	(segment
		(start 174.723552 -226.502976)
		(end 173.735746 -227.490782)
		(width 0.18288)
		(layer "In11.Cu")
		(net "M_H_CPU1_SB_DQ<1>")
	)
	(segment
		(start 160.753806 -229.04577)
		(end 159.056578 -229.04577)
		(width 0.18288)
		(layer "In11.Cu")
		(net "M_H_CPU1_SB_DQ<1>")
	)
	(segment
		(start 171.318174 -228.331776)
		(end 171.125134 -228.138736)
		(width 0.18288)
		(layer "In11.Cu")
		(net "M_H_CPU1_SB_DQ<1>")
	)
	(segment
		(start 201.338688 -229.824026)
		(end 201.145648 -230.017066)
		(width 0.18288)
		(layer "In11.Cu")
		(net "M_H_CPU1_SB_DQ<1>")
	)
	(segment
		(start 195.940426 -228.300026)
		(end 195.23837 -228.300026)
		(width 0.18288)
		(layer "In11.Cu")
		(net "M_H_CPU1_SB_DQ<1>")
	)
	(segment
		(start 154.20594 -230.042466)
		(end 145.781522 -238.466884)
		(width 0.18288)
		(layer "In11.Cu")
		(net "M_H_CPU1_SB_DQ<1>")
	)
	(segment
		(start 169.37228 -227.490782)
		(end 168.91127 -227.490782)
		(width 0.18288)
		(layer "In11.Cu")
		(net "M_H_CPU1_SB_DQ<1>")
	)
	(segment
		(start 170.372532 -227.490782)
		(end 170.07586 -227.787454)
		(width 0.18288)
		(layer "In11.Cu")
		(net "M_H_CPU1_SB_DQ<1>")
	)
	(segment
		(start 183.081676 -226.323144)
		(end 181.865524 -226.323144)
		(width 0.18288)
		(layer "In11.Cu")
		(net "M_H_CPU1_SB_DQ<1>")
	)
	(segment
		(start 201.145648 -230.304594)
		(end 200.952608 -230.497634)
		(width 0.18288)
		(layer "In11.Cu")
		(net "M_H_CPU1_SB_DQ<1>")
	)
	(segment
		(start 177.742342 -226.108768)
		(end 177.742342 -226.445826)
		(width 0.18288)
		(layer "In11.Cu")
		(net "M_H_CPU1_SB_DQ<1>")
	)
	(segment
		(start 128.754378 -238.721138)
		(end 128.743964 -238.715042)
		(width 0.088646)
		(layer "In11.Cu")
		(net "M_H_CPU1_SB_DQ<1>")
	)
	(segment
		(start 193.087244 -226.640644)
		(end 191.934338 -226.640644)
		(width 0.18288)
		(layer "In11.Cu")
		(net "M_H_CPU1_SB_DQ<1>")
	)
	(segment
		(start 178.445922 -226.455986)
		(end 178.445922 -226.108768)
		(width 0.18288)
		(layer "In11.Cu")
		(net "M_H_CPU1_SB_DQ<1>")
	)
	(arc
		(start 128.743964 -238.715042)
		(mid 128.556766 -238.664899)
		(end 128.369568 -238.715042)
		(width 0.088646)
		(layer "In11.Cu")
		(net "M_H_CPU1_SB_DQ<1>")
	)
	(arc
		(start 133.068568 -238.715042)
		(mid 132.785866 -238.790818)
		(end 132.503164 -238.715042)
		(width 0.088646)
		(layer "In11.Cu")
		(net "M_H_CPU1_SB_DQ<1>")
	)
	(arc
		(start 136.262364 -238.715042)
		(mid 136.075166 -238.664899)
		(end 135.887968 -238.715042)
		(width 0.088646)
		(layer "In11.Cu")
		(net "M_H_CPU1_SB_DQ<1>")
	)
	(arc
		(start 138.185652 -238.701326)
		(mid 138.127276 -238.696707)
		(end 138.070336 -238.683038)
		(width 0.088646)
		(layer "In11.Cu")
		(net "M_H_CPU1_SB_DQ<1>")
	)
	(arc
		(start 137.767568 -238.715042)
		(mid 137.484866 -238.790818)
		(end 137.202164 -238.715042)
		(width 0.088646)
		(layer "In11.Cu")
		(net "M_H_CPU1_SB_DQ<1>")
	)
	(arc
		(start 132.503164 -238.715042)
		(mid 132.315966 -238.664899)
		(end 132.128768 -238.715042)
		(width 0.088646)
		(layer "In11.Cu")
		(net "M_H_CPU1_SB_DQ<1>")
	)
	(arc
		(start 134.382764 -238.715042)
		(mid 134.195566 -238.664899)
		(end 134.008368 -238.715042)
		(width 0.088646)
		(layer "In11.Cu")
		(net "M_H_CPU1_SB_DQ<1>")
	)
	(arc
		(start 130.623564 -238.715042)
		(mid 130.436366 -238.664899)
		(end 130.249168 -238.715042)
		(width 0.088646)
		(layer "In11.Cu")
		(net "M_H_CPU1_SB_DQ<1>")
	)
	(arc
		(start 127.429768 -238.715042)
		(mid 127.155569 -238.790877)
		(end 126.879096 -238.723678)
		(width 0.088646)
		(layer "In11.Cu")
		(net "M_H_CPU1_SB_DQ<1>")
	)
	(arc
		(start 125.550168 -238.715042)
		(mid 125.275969 -238.790877)
		(end 124.999496 -238.723678)
		(width 0.088646)
		(layer "In11.Cu")
		(net "M_H_CPU1_SB_DQ<1>")
	)
	(arc
		(start 123.952762 -238.661194)
		(mid 123.656159 -238.461589)
		(end 123.387612 -238.225584)
		(width 0.088646)
		(layer "In11.Cu")
		(net "M_H_CPU1_SB_DQ<1>")
	)
	(arc
		(start 131.188968 -238.715042)
		(mid 130.914769 -238.790877)
		(end 130.638296 -238.723678)
		(width 0.088646)
		(layer "In11.Cu")
		(net "M_H_CPU1_SB_DQ<1>")
	)
	(arc
		(start 130.249168 -238.715042)
		(mid 129.972355 -238.790912)
		(end 129.693924 -238.721138)
		(width 0.088646)
		(layer "In11.Cu")
		(net "M_H_CPU1_SB_DQ<1>")
	)
	(arc
		(start 135.887968 -238.715042)
		(mid 135.605266 -238.790818)
		(end 135.322564 -238.715042)
		(width 0.088646)
		(layer "In11.Cu")
		(net "M_H_CPU1_SB_DQ<1>")
	)
	(arc
		(start 131.563364 -238.715042)
		(mid 131.376166 -238.664899)
		(end 131.188968 -238.715042)
		(width 0.088646)
		(layer "In11.Cu")
		(net "M_H_CPU1_SB_DQ<1>")
	)
	(arc
		(start 134.008368 -238.715042)
		(mid 133.725666 -238.790818)
		(end 133.442964 -238.715042)
		(width 0.088646)
		(layer "In11.Cu")
		(net "M_H_CPU1_SB_DQ<1>")
	)
	(arc
		(start 128.369568 -238.715042)
		(mid 128.095369 -238.790877)
		(end 127.818896 -238.723678)
		(width 0.088646)
		(layer "In11.Cu")
		(net "M_H_CPU1_SB_DQ<1>")
	)
	(arc
		(start 129.309114 -238.715042)
		(mid 129.032555 -238.790785)
		(end 128.754378 -238.721138)
		(width 0.088646)
		(layer "In11.Cu")
		(net "M_H_CPU1_SB_DQ<1>")
	)
	(arc
		(start 127.804164 -238.715042)
		(mid 127.616966 -238.664899)
		(end 127.429768 -238.715042)
		(width 0.088646)
		(layer "In11.Cu")
		(net "M_H_CPU1_SB_DQ<1>")
	)
	(arc
		(start 138.070336 -238.683038)
		(mid 137.915565 -238.666929)
		(end 137.767568 -238.715042)
		(width 0.088646)
		(layer "In11.Cu")
		(net "M_H_CPU1_SB_DQ<1>")
	)
	(arc
		(start 126.864364 -238.715042)
		(mid 126.677166 -238.664899)
		(end 126.489968 -238.715042)
		(width 0.088646)
		(layer "In11.Cu")
		(net "M_H_CPU1_SB_DQ<1>")
	)
	(arc
		(start 129.68351 -238.715042)
		(mid 129.496312 -238.664899)
		(end 129.309114 -238.715042)
		(width 0.088646)
		(layer "In11.Cu")
		(net "M_H_CPU1_SB_DQ<1>")
	)
	(arc
		(start 136.827768 -238.715042)
		(mid 136.545066 -238.790818)
		(end 136.262364 -238.715042)
		(width 0.088646)
		(layer "In11.Cu")
		(net "M_H_CPU1_SB_DQ<1>")
	)
	(arc
		(start 135.322564 -238.715042)
		(mid 135.135366 -238.664899)
		(end 134.948168 -238.715042)
		(width 0.088646)
		(layer "In11.Cu")
		(net "M_H_CPU1_SB_DQ<1>")
	)
	(arc
		(start 124.610368 -238.715042)
		(mid 124.336169 -238.790877)
		(end 124.059696 -238.723678)
		(width 0.088646)
		(layer "In11.Cu")
		(net "M_H_CPU1_SB_DQ<1>")
	)
	(arc
		(start 126.489968 -238.715042)
		(mid 126.207266 -238.790818)
		(end 125.924564 -238.715042)
		(width 0.088646)
		(layer "In11.Cu")
		(net "M_H_CPU1_SB_DQ<1>")
	)
	(arc
		(start 137.202164 -238.715042)
		(mid 137.014966 -238.664899)
		(end 136.827768 -238.715042)
		(width 0.088646)
		(layer "In11.Cu")
		(net "M_H_CPU1_SB_DQ<1>")
	)
	(arc
		(start 132.128768 -238.715042)
		(mid 131.854569 -238.790877)
		(end 131.578096 -238.723678)
		(width 0.088646)
		(layer "In11.Cu")
		(net "M_H_CPU1_SB_DQ<1>")
	)
	(arc
		(start 124.984764 -238.715042)
		(mid 124.797566 -238.664899)
		(end 124.610368 -238.715042)
		(width 0.088646)
		(layer "In11.Cu")
		(net "M_H_CPU1_SB_DQ<1>")
	)
	(arc
		(start 133.442964 -238.715042)
		(mid 133.255766 -238.664899)
		(end 133.068568 -238.715042)
		(width 0.088646)
		(layer "In11.Cu")
		(net "M_H_CPU1_SB_DQ<1>")
	)
	(arc
		(start 125.924564 -238.715042)
		(mid 125.737366 -238.664899)
		(end 125.550168 -238.715042)
		(width 0.088646)
		(layer "In11.Cu")
		(net "M_H_CPU1_SB_DQ<1>")
	)
	(arc
		(start 134.948168 -238.715042)
		(mid 134.665466 -238.790818)
		(end 134.382764 -238.715042)
		(width 0.088646)
		(layer "In11.Cu")
		(net "M_H_CPU1_SB_DQ<1>")
	)
	(segment
		(start 212.618066 -211.341716)
		(end 212.630258 -211.353908)
		(width 0.1016)
		(layer "F.Cu")
		(net "M_H_CPU1_SB_DQ<19>")
	)
	(segment
		(start 210.598258 -211.348828)
		(end 210.603084 -211.348828)
		(width 0.101854)
		(layer "F.Cu")
		(net "M_H_CPU1_SB_DQ<19>")
	)
	(segment
		(start 213.749636 -210.664806)
		(end 214.133684 -210.664806)
		(width 0.20066)
		(layer "F.Cu")
		(net "M_H_CPU1_SB_DQ<19>")
	)
	(segment
		(start 207.071214 -210.916774)
		(end 208.176114 -210.916774)
		(width 0.20066)
		(layer "F.Cu")
		(net "M_H_CPU1_SB_DQ<19>")
	)
	(segment
		(start 208.176114 -210.916774)
		(end 209.874358 -210.916774)
		(width 0.20066)
		(layer "F.Cu")
		(net "M_H_CPU1_SB_DQ<19>")
	)
	(segment
		(start 209.874358 -210.916774)
		(end 210.306412 -211.348828)
		(width 0.20066)
		(layer "F.Cu")
		(net "M_H_CPU1_SB_DQ<19>")
	)
	(segment
		(start 214.133684 -210.664806)
		(end 214.385652 -210.916774)
		(width 0.20066)
		(layer "F.Cu")
		(net "M_H_CPU1_SB_DQ<19>")
	)
	(segment
		(start 214.385652 -210.916774)
		(end 215.719914 -210.916774)
		(width 0.20066)
		(layer "F.Cu")
		(net "M_H_CPU1_SB_DQ<19>")
	)
	(segment
		(start 210.603084 -211.348828)
		(end 210.610196 -211.341716)
		(width 0.1016)
		(layer "F.Cu")
		(net "M_H_CPU1_SB_DQ<19>")
	)
	(segment
		(start 210.306412 -211.348828)
		(end 210.598258 -211.348828)
		(width 0.20066)
		(layer "F.Cu")
		(net "M_H_CPU1_SB_DQ<19>")
	)
	(segment
		(start 213.515448 -210.898994)
		(end 213.749636 -210.664806)
		(width 0.20066)
		(layer "F.Cu")
		(net "M_H_CPU1_SB_DQ<19>")
	)
	(segment
		(start 213.515448 -211.149946)
		(end 213.515448 -210.898994)
		(width 0.20066)
		(layer "F.Cu")
		(net "M_H_CPU1_SB_DQ<19>")
	)
	(segment
		(start 128.556512 -231.436418)
		(end 128.556512 -230.900732)
		(width 0.20066)
		(layer "F.Cu")
		(net "M_H_CPU1_SB_DQ<19>")
	)
	(segment
		(start 212.630258 -211.353908)
		(end 213.311486 -211.353908)
		(width 0.20066)
		(layer "F.Cu")
		(net "M_H_CPU1_SB_DQ<19>")
	)
	(segment
		(start 210.610196 -211.341716)
		(end 212.618066 -211.341716)
		(width 0.1016)
		(layer "F.Cu")
		(net "M_H_CPU1_SB_DQ<19>")
	)
	(segment
		(start 128.556512 -230.900732)
		(end 128.556766 -230.900478)
		(width 0.20066)
		(layer "F.Cu")
		(net "M_H_CPU1_SB_DQ<19>")
	)
	(segment
		(start 213.311486 -211.353908)
		(end 213.515448 -211.149946)
		(width 0.20066)
		(layer "F.Cu")
		(net "M_H_CPU1_SB_DQ<19>")
	)
	(segment
		(start 131.658868 -230.41102)
		(end 131.648454 -230.404924)
		(width 0.088646)
		(layer "In6.Cu")
		(net "M_H_CPU1_SB_DQ<19>")
	)
	(segment
		(start 161.37128 -212.32368)
		(end 160.871916 -211.824316)
		(width 0.18288)
		(layer "In6.Cu")
		(net "M_H_CPU1_SB_DQ<19>")
	)
	(segment
		(start 166.96944 -211.340954)
		(end 166.78656 -211.158074)
		(width 0.18288)
		(layer "In6.Cu")
		(net "M_H_CPU1_SB_DQ<19>")
	)
	(segment
		(start 166.78656 -210.873848)
		(end 166.60368 -210.690968)
		(width 0.18288)
		(layer "In6.Cu")
		(net "M_H_CPU1_SB_DQ<19>")
	)
	(segment
		(start 159.412178 -211.824316)
		(end 159.229298 -211.641436)
		(width 0.18288)
		(layer "In6.Cu")
		(net "M_H_CPU1_SB_DQ<19>")
	)
	(segment
		(start 193.127884 -210.665568)
		(end 192.450974 -211.342478)
		(width 0.18288)
		(layer "In6.Cu")
		(net "M_H_CPU1_SB_DQ<19>")
	)
	(segment
		(start 200.982834 -210.921092)
		(end 200.822814 -210.761072)
		(width 0.18288)
		(layer "In6.Cu")
		(net "M_H_CPU1_SB_DQ<19>")
	)
	(segment
		(start 177.832004 -212.386672)
		(end 177.176176 -213.0425)
		(width 0.18288)
		(layer "In6.Cu")
		(net "M_H_CPU1_SB_DQ<19>")
	)
	(segment
		(start 171.271184 -213.892384)
		(end 169.753026 -212.374226)
		(width 0.18288)
		(layer "In6.Cu")
		(net "M_H_CPU1_SB_DQ<19>")
	)
	(segment
		(start 169.753026 -212.374226)
		(end 169.033698 -212.374226)
		(width 0.18288)
		(layer "In6.Cu")
		(net "M_H_CPU1_SB_DQ<19>")
	)
	(segment
		(start 159.229298 -211.641436)
		(end 159.229298 -210.99526)
		(width 0.18288)
		(layer "In6.Cu")
		(net "M_H_CPU1_SB_DQ<19>")
	)
	(segment
		(start 132.043678 -230.404924)
		(end 132.033264 -230.41102)
		(width 0.088646)
		(layer "In6.Cu")
		(net "M_H_CPU1_SB_DQ<19>")
	)
	(segment
		(start 179.132484 -212.386672)
		(end 177.832004 -212.386672)
		(width 0.18288)
		(layer "In6.Cu")
		(net "M_H_CPU1_SB_DQ<19>")
	)
	(segment
		(start 205.899512 -212.088476)
		(end 204.48143 -212.088476)
		(width 0.18288)
		(layer "In6.Cu")
		(net "M_H_CPU1_SB_DQ<19>")
	)
	(segment
		(start 190.723774 -211.342478)
		(end 190.504826 -211.561426)
		(width 0.18288)
		(layer "In6.Cu")
		(net "M_H_CPU1_SB_DQ<19>")
	)
	(segment
		(start 200.129394 -211.342224)
		(end 195.109338 -211.342224)
		(width 0.18288)
		(layer "In6.Cu")
		(net "M_H_CPU1_SB_DQ<19>")
	)
	(segment
		(start 179.96535 -211.553806)
		(end 179.132484 -212.386672)
		(width 0.18288)
		(layer "In6.Cu")
		(net "M_H_CPU1_SB_DQ<19>")
	)
	(segment
		(start 140.735812 -228.28631)
		(end 139.274042 -228.28631)
		(width 0.18288)
		(layer "In6.Cu")
		(net "M_H_CPU1_SB_DQ<19>")
	)
	(segment
		(start 189.285626 -211.561426)
		(end 188.65469 -212.192362)
		(width 0.18288)
		(layer "In6.Cu")
		(net "M_H_CPU1_SB_DQ<19>")
	)
	(segment
		(start 207.071214 -210.916774)
		(end 205.899512 -212.088476)
		(width 0.18288)
		(layer "In6.Cu")
		(net "M_H_CPU1_SB_DQ<19>")
	)
	(segment
		(start 173.391322 -213.892384)
		(end 171.271184 -213.892384)
		(width 0.18288)
		(layer "In6.Cu")
		(net "M_H_CPU1_SB_DQ<19>")
	)
	(segment
		(start 129.698496 -231.2162)
		(end 129.683764 -231.224836)
		(width 0.088646)
		(layer "In6.Cu")
		(net "M_H_CPU1_SB_DQ<19>")
	)
	(segment
		(start 166.60368 -210.690968)
		(end 166.27602 -210.690968)
		(width 0.18288)
		(layer "In6.Cu")
		(net "M_H_CPU1_SB_DQ<19>")
	)
	(segment
		(start 166.09314 -210.873848)
		(end 166.09314 -211.158074)
		(width 0.18288)
		(layer "In6.Cu")
		(net "M_H_CPU1_SB_DQ<19>")
	)
	(segment
		(start 168.000426 -211.340954)
		(end 166.96944 -211.340954)
		(width 0.18288)
		(layer "In6.Cu")
		(net "M_H_CPU1_SB_DQ<19>")
	)
	(segment
		(start 160.871916 -211.824316)
		(end 159.412178 -211.824316)
		(width 0.18288)
		(layer "In6.Cu")
		(net "M_H_CPU1_SB_DQ<19>")
	)
	(segment
		(start 166.27602 -210.690968)
		(end 166.09314 -210.873848)
		(width 0.18288)
		(layer "In6.Cu")
		(net "M_H_CPU1_SB_DQ<19>")
	)
	(segment
		(start 129.281428 -231.20858)
		(end 128.556766 -230.900478)
		(width 0.088646)
		(layer "In6.Cu")
		(net "M_H_CPU1_SB_DQ<19>")
	)
	(segment
		(start 163.519358 -211.340954)
		(end 162.536632 -212.32368)
		(width 0.18288)
		(layer "In6.Cu")
		(net "M_H_CPU1_SB_DQ<19>")
	)
	(segment
		(start 174.241206 -213.0425)
		(end 173.391322 -213.892384)
		(width 0.18288)
		(layer "In6.Cu")
		(net "M_H_CPU1_SB_DQ<19>")
	)
	(segment
		(start 200.982834 -211.182204)
		(end 200.982834 -210.921092)
		(width 0.18288)
		(layer "In6.Cu")
		(net "M_H_CPU1_SB_DQ<19>")
	)
	(segment
		(start 138.962892 -228.28631)
		(end 138.780012 -228.46919)
		(width 0.088646)
		(layer "In6.Cu")
		(net "M_H_CPU1_SB_DQ<19>")
	)
	(segment
		(start 138.780012 -228.46919)
		(end 138.780012 -229.3112)
		(width 0.088646)
		(layer "In6.Cu")
		(net "M_H_CPU1_SB_DQ<19>")
	)
	(segment
		(start 162.536632 -212.32368)
		(end 161.37128 -212.32368)
		(width 0.18288)
		(layer "In6.Cu")
		(net "M_H_CPU1_SB_DQ<19>")
	)
	(segment
		(start 158.535878 -210.99526)
		(end 158.535878 -211.641436)
		(width 0.18288)
		(layer "In6.Cu")
		(net "M_H_CPU1_SB_DQ<19>")
	)
	(segment
		(start 130.632454 -231.219756)
		(end 130.623564 -231.224836)
		(width 0.088646)
		(layer "In6.Cu")
		(net "M_H_CPU1_SB_DQ<19>")
	)
	(segment
		(start 195.109338 -211.342224)
		(end 194.432682 -210.665568)
		(width 0.18288)
		(layer "In6.Cu")
		(net "M_H_CPU1_SB_DQ<19>")
	)
	(segment
		(start 183.309006 -211.553806)
		(end 179.96535 -211.553806)
		(width 0.18288)
		(layer "In6.Cu")
		(net "M_H_CPU1_SB_DQ<19>")
	)
	(segment
		(start 188.65469 -212.192362)
		(end 183.947562 -212.192362)
		(width 0.18288)
		(layer "In6.Cu")
		(net "M_H_CPU1_SB_DQ<19>")
	)
	(segment
		(start 166.09314 -211.158074)
		(end 165.91026 -211.340954)
		(width 0.18288)
		(layer "In6.Cu")
		(net "M_H_CPU1_SB_DQ<19>")
	)
	(segment
		(start 159.046418 -210.81238)
		(end 158.718758 -210.81238)
		(width 0.18288)
		(layer "In6.Cu")
		(net "M_H_CPU1_SB_DQ<19>")
	)
	(segment
		(start 194.432682 -210.665568)
		(end 193.127884 -210.665568)
		(width 0.18288)
		(layer "In6.Cu")
		(net "M_H_CPU1_SB_DQ<19>")
	)
	(segment
		(start 200.449434 -210.761072)
		(end 200.289414 -210.921092)
		(width 0.18288)
		(layer "In6.Cu")
		(net "M_H_CPU1_SB_DQ<19>")
	)
	(segment
		(start 166.78656 -211.158074)
		(end 166.78656 -210.873848)
		(width 0.18288)
		(layer "In6.Cu")
		(net "M_H_CPU1_SB_DQ<19>")
	)
	(segment
		(start 158.352998 -211.824316)
		(end 157.197806 -211.824316)
		(width 0.18288)
		(layer "In6.Cu")
		(net "M_H_CPU1_SB_DQ<19>")
	)
	(segment
		(start 200.289414 -211.182204)
		(end 200.129394 -211.342224)
		(width 0.18288)
		(layer "In6.Cu")
		(net "M_H_CPU1_SB_DQ<19>")
	)
	(segment
		(start 204.48143 -212.088476)
		(end 203.735178 -211.342224)
		(width 0.18288)
		(layer "In6.Cu")
		(net "M_H_CPU1_SB_DQ<19>")
	)
	(segment
		(start 203.735178 -211.342224)
		(end 201.142854 -211.342224)
		(width 0.18288)
		(layer "In6.Cu")
		(net "M_H_CPU1_SB_DQ<19>")
	)
	(segment
		(start 201.142854 -211.342224)
		(end 200.982834 -211.182204)
		(width 0.18288)
		(layer "In6.Cu")
		(net "M_H_CPU1_SB_DQ<19>")
	)
	(segment
		(start 139.274042 -228.28631)
		(end 138.962892 -228.28631)
		(width 0.088646)
		(layer "In6.Cu")
		(net "M_H_CPU1_SB_DQ<19>")
	)
	(segment
		(start 159.229298 -210.99526)
		(end 159.046418 -210.81238)
		(width 0.18288)
		(layer "In6.Cu")
		(net "M_H_CPU1_SB_DQ<19>")
	)
	(segment
		(start 183.947562 -212.192362)
		(end 183.309006 -211.553806)
		(width 0.18288)
		(layer "In6.Cu")
		(net "M_H_CPU1_SB_DQ<19>")
	)
	(segment
		(start 129.309368 -231.224836)
		(end 129.281428 -231.20858)
		(width 0.088646)
		(layer "In6.Cu")
		(net "M_H_CPU1_SB_DQ<19>")
	)
	(segment
		(start 177.176176 -213.0425)
		(end 174.241206 -213.0425)
		(width 0.18288)
		(layer "In6.Cu")
		(net "M_H_CPU1_SB_DQ<19>")
	)
	(segment
		(start 158.718758 -210.81238)
		(end 158.535878 -210.99526)
		(width 0.18288)
		(layer "In6.Cu")
		(net "M_H_CPU1_SB_DQ<19>")
	)
	(segment
		(start 157.197806 -211.824316)
		(end 140.735812 -228.28631)
		(width 0.18288)
		(layer "In6.Cu")
		(net "M_H_CPU1_SB_DQ<19>")
	)
	(segment
		(start 133.538468 -230.41102)
		(end 133.528054 -230.404924)
		(width 0.088646)
		(layer "In6.Cu")
		(net "M_H_CPU1_SB_DQ<19>")
	)
	(segment
		(start 165.91026 -211.340954)
		(end 163.519358 -211.340954)
		(width 0.18288)
		(layer "In6.Cu")
		(net "M_H_CPU1_SB_DQ<19>")
	)
	(segment
		(start 192.450974 -211.342478)
		(end 190.723774 -211.342478)
		(width 0.18288)
		(layer "In6.Cu")
		(net "M_H_CPU1_SB_DQ<19>")
	)
	(segment
		(start 200.822814 -210.761072)
		(end 200.449434 -210.761072)
		(width 0.18288)
		(layer "In6.Cu")
		(net "M_H_CPU1_SB_DQ<19>")
	)
	(segment
		(start 190.504826 -211.561426)
		(end 189.285626 -211.561426)
		(width 0.18288)
		(layer "In6.Cu")
		(net "M_H_CPU1_SB_DQ<19>")
	)
	(segment
		(start 138.780012 -229.3112)
		(end 137.706354 -230.384858)
		(width 0.088646)
		(layer "In6.Cu")
		(net "M_H_CPU1_SB_DQ<19>")
	)
	(segment
		(start 169.033698 -212.374226)
		(end 168.000426 -211.340954)
		(width 0.18288)
		(layer "In6.Cu")
		(net "M_H_CPU1_SB_DQ<19>")
	)
	(segment
		(start 200.289414 -210.921092)
		(end 200.289414 -211.182204)
		(width 0.18288)
		(layer "In6.Cu")
		(net "M_H_CPU1_SB_DQ<19>")
	)
	(segment
		(start 158.535878 -211.641436)
		(end 158.352998 -211.824316)
		(width 0.18288)
		(layer "In6.Cu")
		(net "M_H_CPU1_SB_DQ<19>")
	)
	(segment
		(start 130.811016 -230.884984)
		(end 130.811016 -230.900478)
		(width 0.088646)
		(layer "In6.Cu")
		(net "M_H_CPU1_SB_DQ<19>")
	)
	(arc
		(start 137.297668 -230.41102)
		(mid 137.014966 -230.335244)
		(end 136.732264 -230.41102)
		(width 0.088646)
		(layer "In6.Cu")
		(net "M_H_CPU1_SB_DQ<19>")
	)
	(arc
		(start 136.357868 -230.41102)
		(mid 136.075166 -230.335244)
		(end 135.792464 -230.41102)
		(width 0.088646)
		(layer "In6.Cu")
		(net "M_H_CPU1_SB_DQ<19>")
	)
	(arc
		(start 130.811016 -230.900478)
		(mid 130.763337 -231.083378)
		(end 130.632454 -231.219756)
		(width 0.088646)
		(layer "In6.Cu")
		(net "M_H_CPU1_SB_DQ<19>")
	)
	(arc
		(start 134.852664 -230.41102)
		(mid 134.665466 -230.461163)
		(end 134.478268 -230.41102)
		(width 0.088646)
		(layer "In6.Cu")
		(net "M_H_CPU1_SB_DQ<19>")
	)
	(arc
		(start 132.97281 -230.41102)
		(mid 132.785612 -230.461163)
		(end 132.598414 -230.41102)
		(width 0.088646)
		(layer "In6.Cu")
		(net "M_H_CPU1_SB_DQ<19>")
	)
	(arc
		(start 133.912864 -230.41102)
		(mid 133.725666 -230.461163)
		(end 133.538468 -230.41102)
		(width 0.088646)
		(layer "In6.Cu")
		(net "M_H_CPU1_SB_DQ<19>")
	)
	(arc
		(start 135.792464 -230.41102)
		(mid 135.605266 -230.461163)
		(end 135.418068 -230.41102)
		(width 0.088646)
		(layer "In6.Cu")
		(net "M_H_CPU1_SB_DQ<19>")
	)
	(arc
		(start 133.528054 -230.404924)
		(mid 133.249622 -230.335078)
		(end 132.97281 -230.41102)
		(width 0.088646)
		(layer "In6.Cu")
		(net "M_H_CPU1_SB_DQ<19>")
	)
	(arc
		(start 134.478268 -230.41102)
		(mid 134.195566 -230.335244)
		(end 133.912864 -230.41102)
		(width 0.088646)
		(layer "In6.Cu")
		(net "M_H_CPU1_SB_DQ<19>")
	)
	(arc
		(start 131.09321 -230.41102)
		(mid 130.890387 -230.611251)
		(end 130.811016 -230.884984)
		(width 0.088646)
		(layer "In6.Cu")
		(net "M_H_CPU1_SB_DQ<19>")
	)
	(arc
		(start 137.672064 -230.41102)
		(mid 137.484866 -230.461163)
		(end 137.297668 -230.41102)
		(width 0.088646)
		(layer "In6.Cu")
		(net "M_H_CPU1_SB_DQ<19>")
	)
	(arc
		(start 129.683764 -231.224836)
		(mid 129.496566 -231.274979)
		(end 129.309368 -231.224836)
		(width 0.088646)
		(layer "In6.Cu")
		(net "M_H_CPU1_SB_DQ<19>")
	)
	(arc
		(start 135.418068 -230.41102)
		(mid 135.135366 -230.335244)
		(end 134.852664 -230.41102)
		(width 0.088646)
		(layer "In6.Cu")
		(net "M_H_CPU1_SB_DQ<19>")
	)
	(arc
		(start 137.706354 -230.384858)
		(mid 137.690085 -230.399088)
		(end 137.672064 -230.41102)
		(width 0.088646)
		(layer "In6.Cu")
		(net "M_H_CPU1_SB_DQ<19>")
	)
	(arc
		(start 131.648454 -230.404924)
		(mid 131.370022 -230.335078)
		(end 131.09321 -230.41102)
		(width 0.088646)
		(layer "In6.Cu")
		(net "M_H_CPU1_SB_DQ<19>")
	)
	(arc
		(start 132.598414 -230.41102)
		(mid 132.321855 -230.335277)
		(end 132.043678 -230.404924)
		(width 0.088646)
		(layer "In6.Cu")
		(net "M_H_CPU1_SB_DQ<19>")
	)
	(arc
		(start 132.033264 -230.41102)
		(mid 131.846066 -230.461163)
		(end 131.658868 -230.41102)
		(width 0.088646)
		(layer "In6.Cu")
		(net "M_H_CPU1_SB_DQ<19>")
	)
	(arc
		(start 136.732264 -230.41102)
		(mid 136.545066 -230.461163)
		(end 136.357868 -230.41102)
		(width 0.088646)
		(layer "In6.Cu")
		(net "M_H_CPU1_SB_DQ<19>")
	)
	(arc
		(start 130.249168 -231.224836)
		(mid 129.974939 -231.148911)
		(end 129.698496 -231.2162)
		(width 0.088646)
		(layer "In6.Cu")
		(net "M_H_CPU1_SB_DQ<19>")
	)
	(arc
		(start 130.623564 -231.224836)
		(mid 130.436366 -231.274979)
		(end 130.249168 -231.224836)
		(width 0.088646)
		(layer "In6.Cu")
		(net "M_H_CPU1_SB_DQ<19>")
	)
	(segment
		(start 214.133684 -212.364828)
		(end 214.385652 -212.616796)
		(width 0.20066)
		(layer "F.Cu")
		(net "M_H_CPU1_SB_DQ<18>")
	)
	(segment
		(start 212.618066 -213.041738)
		(end 212.630258 -213.05393)
		(width 0.1016)
		(layer "F.Cu")
		(net "M_H_CPU1_SB_DQ<18>")
	)
	(segment
		(start 128.086866 -232.250488)
		(end 128.086612 -232.250234)
		(width 0.20066)
		(layer "F.Cu")
		(net "M_H_CPU1_SB_DQ<18>")
	)
	(segment
		(start 212.630258 -213.05393)
		(end 213.311486 -213.05393)
		(width 0.20066)
		(layer "F.Cu")
		(net "M_H_CPU1_SB_DQ<18>")
	)
	(segment
		(start 208.176114 -212.616796)
		(end 209.874358 -212.616796)
		(width 0.20066)
		(layer "F.Cu")
		(net "M_H_CPU1_SB_DQ<18>")
	)
	(segment
		(start 210.598258 -213.04885)
		(end 210.603084 -213.04885)
		(width 0.101854)
		(layer "F.Cu")
		(net "M_H_CPU1_SB_DQ<18>")
	)
	(segment
		(start 209.874358 -212.616796)
		(end 210.306412 -213.04885)
		(width 0.20066)
		(layer "F.Cu")
		(net "M_H_CPU1_SB_DQ<18>")
	)
	(segment
		(start 213.311486 -213.05393)
		(end 213.515448 -212.849968)
		(width 0.20066)
		(layer "F.Cu")
		(net "M_H_CPU1_SB_DQ<18>")
	)
	(segment
		(start 207.071214 -212.616796)
		(end 208.176114 -212.616796)
		(width 0.20066)
		(layer "F.Cu")
		(net "M_H_CPU1_SB_DQ<18>")
	)
	(segment
		(start 213.515448 -212.599016)
		(end 213.749636 -212.364828)
		(width 0.20066)
		(layer "F.Cu")
		(net "M_H_CPU1_SB_DQ<18>")
	)
	(segment
		(start 214.385652 -212.616796)
		(end 215.719914 -212.616796)
		(width 0.20066)
		(layer "F.Cu")
		(net "M_H_CPU1_SB_DQ<18>")
	)
	(segment
		(start 128.086612 -232.250234)
		(end 128.086612 -231.714548)
		(width 0.20066)
		(layer "F.Cu")
		(net "M_H_CPU1_SB_DQ<18>")
	)
	(segment
		(start 210.306412 -213.04885)
		(end 210.598258 -213.04885)
		(width 0.20066)
		(layer "F.Cu")
		(net "M_H_CPU1_SB_DQ<18>")
	)
	(segment
		(start 213.515448 -212.849968)
		(end 213.515448 -212.599016)
		(width 0.20066)
		(layer "F.Cu")
		(net "M_H_CPU1_SB_DQ<18>")
	)
	(segment
		(start 210.610196 -213.041738)
		(end 212.618066 -213.041738)
		(width 0.1016)
		(layer "F.Cu")
		(net "M_H_CPU1_SB_DQ<18>")
	)
	(segment
		(start 213.749636 -212.364828)
		(end 214.133684 -212.364828)
		(width 0.20066)
		(layer "F.Cu")
		(net "M_H_CPU1_SB_DQ<18>")
	)
	(segment
		(start 210.603084 -213.04885)
		(end 210.610196 -213.041738)
		(width 0.1016)
		(layer "F.Cu")
		(net "M_H_CPU1_SB_DQ<18>")
	)
	(segment
		(start 130.718814 -232.038906)
		(end 130.704082 -232.03027)
		(width 0.088646)
		(layer "In6.Cu")
		(net "M_H_CPU1_SB_DQ<18>")
	)
	(segment
		(start 189.012322 -213.89213)
		(end 183.86933 -213.89213)
		(width 0.18288)
		(layer "In6.Cu")
		(net "M_H_CPU1_SB_DQ<18>")
	)
	(segment
		(start 183.316626 -213.339426)
		(end 182.16753 -213.339426)
		(width 0.18288)
		(layer "In6.Cu")
		(net "M_H_CPU1_SB_DQ<18>")
	)
	(segment
		(start 131.1021 -232.033826)
		(end 131.09321 -232.038906)
		(width 0.088646)
		(layer "In6.Cu")
		(net "M_H_CPU1_SB_DQ<18>")
	)
	(segment
		(start 204.309218 -213.945216)
		(end 203.981558 -213.945216)
		(width 0.18288)
		(layer "In6.Cu")
		(net "M_H_CPU1_SB_DQ<18>")
	)
	(segment
		(start 200.408286 -213.699852)
		(end 200.408286 -213.202266)
		(width 0.18288)
		(layer "In6.Cu")
		(net "M_H_CPU1_SB_DQ<18>")
	)
	(segment
		(start 168.762172 -213.999826)
		(end 168.000172 -213.237826)
		(width 0.18288)
		(layer "In6.Cu")
		(net "M_H_CPU1_SB_DQ<18>")
	)
	(segment
		(start 180.95976 -214.547196)
		(end 180.71973 -214.787226)
		(width 0.18288)
		(layer "In6.Cu")
		(net "M_H_CPU1_SB_DQ<18>")
	)
	(segment
		(start 180.66512 -214.026496)
		(end 180.95976 -214.321136)
		(width 0.18288)
		(layer "In6.Cu")
		(net "M_H_CPU1_SB_DQ<18>")
	)
	(segment
		(start 173.123352 -215.589866)
		(end 171.375578 -215.589866)
		(width 0.18288)
		(layer "In6.Cu")
		(net "M_H_CPU1_SB_DQ<18>")
	)
	(segment
		(start 206.645764 -213.042246)
		(end 204.674978 -213.042246)
		(width 0.18288)
		(layer "In6.Cu")
		(net "M_H_CPU1_SB_DQ<18>")
	)
	(segment
		(start 131.573778 -231.21874)
		(end 131.563364 -231.224836)
		(width 0.088646)
		(layer "In6.Cu")
		(net "M_H_CPU1_SB_DQ<18>")
	)
	(segment
		(start 132.513324 -231.21874)
		(end 132.50291 -231.224836)
		(width 0.088646)
		(layer "In6.Cu")
		(net "M_H_CPU1_SB_DQ<18>")
	)
	(segment
		(start 201.101706 -213.699852)
		(end 200.941686 -213.859872)
		(width 0.18288)
		(layer "In6.Cu")
		(net "M_H_CPU1_SB_DQ<18>")
	)
	(segment
		(start 162.768026 -213.923626)
		(end 161.396426 -213.923626)
		(width 0.18288)
		(layer "In6.Cu")
		(net "M_H_CPU1_SB_DQ<18>")
	)
	(segment
		(start 200.408286 -213.202266)
		(end 200.248266 -213.042246)
		(width 0.18288)
		(layer "In6.Cu")
		(net "M_H_CPU1_SB_DQ<18>")
	)
	(segment
		(start 207.071214 -212.616796)
		(end 206.645764 -213.042246)
		(width 0.18288)
		(layer "In6.Cu")
		(net "M_H_CPU1_SB_DQ<18>")
	)
	(segment
		(start 139.700254 -229.300024)
		(end 139.397232 -229.603046)
		(width 0.18288)
		(layer "In6.Cu")
		(net "M_H_CPU1_SB_DQ<18>")
	)
	(segment
		(start 182.16753 -213.339426)
		(end 181.676294 -213.830662)
		(width 0.18288)
		(layer "In6.Cu")
		(net "M_H_CPU1_SB_DQ<18>")
	)
	(segment
		(start 204.674978 -213.042246)
		(end 204.492098 -213.225126)
		(width 0.18288)
		(layer "In6.Cu")
		(net "M_H_CPU1_SB_DQ<18>")
	)
	(segment
		(start 200.941686 -213.859872)
		(end 200.568306 -213.859872)
		(width 0.18288)
		(layer "In6.Cu")
		(net "M_H_CPU1_SB_DQ<18>")
	)
	(segment
		(start 164.266626 -212.983826)
		(end 163.707826 -212.983826)
		(width 0.18288)
		(layer "In6.Cu")
		(net "M_H_CPU1_SB_DQ<18>")
	)
	(segment
		(start 139.397232 -229.603046)
		(end 139.286488 -229.71379)
		(width 0.088646)
		(layer "In6.Cu")
		(net "M_H_CPU1_SB_DQ<18>")
	)
	(segment
		(start 177.368962 -214.742268)
		(end 173.97095 -214.742268)
		(width 0.18288)
		(layer "In6.Cu")
		(net "M_H_CPU1_SB_DQ<18>")
	)
	(segment
		(start 179.435252 -214.512652)
		(end 177.598578 -214.512652)
		(width 0.18288)
		(layer "In6.Cu")
		(net "M_H_CPU1_SB_DQ<18>")
	)
	(segment
		(start 139.024614 -229.71379)
		(end 138.824716 -229.913688)
		(width 0.088646)
		(layer "In6.Cu")
		(net "M_H_CPU1_SB_DQ<18>")
	)
	(segment
		(start 203.798678 -213.762336)
		(end 203.798678 -213.225126)
		(width 0.18288)
		(layer "In6.Cu")
		(net "M_H_CPU1_SB_DQ<18>")
	)
	(segment
		(start 201.101706 -213.202266)
		(end 201.101706 -213.699852)
		(width 0.18288)
		(layer "In6.Cu")
		(net "M_H_CPU1_SB_DQ<18>")
	)
	(segment
		(start 180.66512 -213.800436)
		(end 180.66512 -214.026496)
		(width 0.18288)
		(layer "In6.Cu")
		(net "M_H_CPU1_SB_DQ<18>")
	)
	(segment
		(start 177.598578 -214.512652)
		(end 177.368962 -214.742268)
		(width 0.18288)
		(layer "In6.Cu")
		(net "M_H_CPU1_SB_DQ<18>")
	)
	(segment
		(start 128.839468 -232.038906)
		(end 128.810004 -232.021634)
		(width 0.088646)
		(layer "In6.Cu")
		(net "M_H_CPU1_SB_DQ<18>")
	)
	(segment
		(start 180.71973 -214.787226)
		(end 179.709826 -214.787226)
		(width 0.18288)
		(layer "In6.Cu")
		(net "M_H_CPU1_SB_DQ<18>")
	)
	(segment
		(start 173.97095 -214.742268)
		(end 173.123352 -215.589866)
		(width 0.18288)
		(layer "In6.Cu")
		(net "M_H_CPU1_SB_DQ<18>")
	)
	(segment
		(start 156.75864 -213.759288)
		(end 141.217904 -229.300024)
		(width 0.18288)
		(layer "In6.Cu")
		(net "M_H_CPU1_SB_DQ<18>")
	)
	(segment
		(start 171.375578 -215.589866)
		(end 169.785538 -213.999826)
		(width 0.18288)
		(layer "In6.Cu")
		(net "M_H_CPU1_SB_DQ<18>")
	)
	(segment
		(start 163.707826 -212.983826)
		(end 162.768026 -213.923626)
		(width 0.18288)
		(layer "In6.Cu")
		(net "M_H_CPU1_SB_DQ<18>")
	)
	(segment
		(start 203.798678 -213.225126)
		(end 203.615798 -213.042246)
		(width 0.18288)
		(layer "In6.Cu")
		(net "M_H_CPU1_SB_DQ<18>")
	)
	(segment
		(start 141.217904 -229.300024)
		(end 139.700254 -229.300024)
		(width 0.18288)
		(layer "In6.Cu")
		(net "M_H_CPU1_SB_DQ<18>")
	)
	(segment
		(start 204.492098 -213.225126)
		(end 204.492098 -213.762336)
		(width 0.18288)
		(layer "In6.Cu")
		(net "M_H_CPU1_SB_DQ<18>")
	)
	(segment
		(start 161.396426 -213.923626)
		(end 161.232088 -213.759288)
		(width 0.18288)
		(layer "In6.Cu")
		(net "M_H_CPU1_SB_DQ<18>")
	)
	(segment
		(start 203.615798 -213.042246)
		(end 201.261726 -213.042246)
		(width 0.18288)
		(layer "In6.Cu")
		(net "M_H_CPU1_SB_DQ<18>")
	)
	(segment
		(start 183.86933 -213.89213)
		(end 183.316626 -213.339426)
		(width 0.18288)
		(layer "In6.Cu")
		(net "M_H_CPU1_SB_DQ<18>")
	)
	(segment
		(start 164.520626 -213.237826)
		(end 164.266626 -212.983826)
		(width 0.18288)
		(layer "In6.Cu")
		(net "M_H_CPU1_SB_DQ<18>")
	)
	(segment
		(start 200.248266 -213.042246)
		(end 189.862206 -213.042246)
		(width 0.18288)
		(layer "In6.Cu")
		(net "M_H_CPU1_SB_DQ<18>")
	)
	(segment
		(start 168.000172 -213.237826)
		(end 164.520626 -213.237826)
		(width 0.18288)
		(layer "In6.Cu")
		(net "M_H_CPU1_SB_DQ<18>")
	)
	(segment
		(start 180.929534 -213.536022)
		(end 180.66512 -213.800436)
		(width 0.18288)
		(layer "In6.Cu")
		(net "M_H_CPU1_SB_DQ<18>")
	)
	(segment
		(start 138.824716 -229.913688)
		(end 138.824716 -230.56088)
		(width 0.088646)
		(layer "In6.Cu")
		(net "M_H_CPU1_SB_DQ<18>")
	)
	(segment
		(start 200.568306 -213.859872)
		(end 200.408286 -213.699852)
		(width 0.18288)
		(layer "In6.Cu")
		(net "M_H_CPU1_SB_DQ<18>")
	)
	(segment
		(start 129.779014 -232.038906)
		(end 129.7686 -232.03281)
		(width 0.088646)
		(layer "In6.Cu")
		(net "M_H_CPU1_SB_DQ<18>")
	)
	(segment
		(start 181.450234 -213.830662)
		(end 181.155594 -213.536022)
		(width 0.18288)
		(layer "In6.Cu")
		(net "M_H_CPU1_SB_DQ<18>")
	)
	(segment
		(start 179.709826 -214.787226)
		(end 179.435252 -214.512652)
		(width 0.18288)
		(layer "In6.Cu")
		(net "M_H_CPU1_SB_DQ<18>")
	)
	(segment
		(start 189.862206 -213.042246)
		(end 189.012322 -213.89213)
		(width 0.18288)
		(layer "In6.Cu")
		(net "M_H_CPU1_SB_DQ<18>")
	)
	(segment
		(start 180.95976 -214.321136)
		(end 180.95976 -214.547196)
		(width 0.18288)
		(layer "In6.Cu")
		(net "M_H_CPU1_SB_DQ<18>")
	)
	(segment
		(start 203.981558 -213.945216)
		(end 203.798678 -213.762336)
		(width 0.18288)
		(layer "In6.Cu")
		(net "M_H_CPU1_SB_DQ<18>")
	)
	(segment
		(start 201.261726 -213.042246)
		(end 201.101706 -213.202266)
		(width 0.18288)
		(layer "In6.Cu")
		(net "M_H_CPU1_SB_DQ<18>")
	)
	(segment
		(start 128.810004 -232.021634)
		(end 128.086612 -231.714548)
		(width 0.088646)
		(layer "In6.Cu")
		(net "M_H_CPU1_SB_DQ<18>")
	)
	(segment
		(start 181.155594 -213.536022)
		(end 180.929534 -213.536022)
		(width 0.18288)
		(layer "In6.Cu")
		(net "M_H_CPU1_SB_DQ<18>")
	)
	(segment
		(start 181.676294 -213.830662)
		(end 181.450234 -213.830662)
		(width 0.18288)
		(layer "In6.Cu")
		(net "M_H_CPU1_SB_DQ<18>")
	)
	(segment
		(start 204.492098 -213.762336)
		(end 204.309218 -213.945216)
		(width 0.18288)
		(layer "In6.Cu")
		(net "M_H_CPU1_SB_DQ<18>")
	)
	(segment
		(start 131.280662 -231.700324)
		(end 131.280662 -231.714548)
		(width 0.088646)
		(layer "In6.Cu")
		(net "M_H_CPU1_SB_DQ<18>")
	)
	(segment
		(start 169.785538 -213.999826)
		(end 168.762172 -213.999826)
		(width 0.18288)
		(layer "In6.Cu")
		(net "M_H_CPU1_SB_DQ<18>")
	)
	(segment
		(start 138.824716 -230.56088)
		(end 138.219942 -231.165654)
		(width 0.088646)
		(layer "In6.Cu")
		(net "M_H_CPU1_SB_DQ<18>")
	)
	(segment
		(start 139.286488 -229.71379)
		(end 139.024614 -229.71379)
		(width 0.088646)
		(layer "In6.Cu")
		(net "M_H_CPU1_SB_DQ<18>")
	)
	(segment
		(start 161.232088 -213.759288)
		(end 156.75864 -213.759288)
		(width 0.18288)
		(layer "In6.Cu")
		(net "M_H_CPU1_SB_DQ<18>")
	)
	(arc
		(start 129.7686 -232.03281)
		(mid 129.490422 -231.963087)
		(end 129.213864 -232.038906)
		(width 0.088646)
		(layer "In6.Cu")
		(net "M_H_CPU1_SB_DQ<18>")
	)
	(arc
		(start 134.948168 -231.224836)
		(mid 134.665466 -231.149094)
		(end 134.382764 -231.224836)
		(width 0.088646)
		(layer "In6.Cu")
		(net "M_H_CPU1_SB_DQ<18>")
	)
	(arc
		(start 131.280662 -231.714548)
		(mid 131.232983 -231.897448)
		(end 131.1021 -232.033826)
		(width 0.088646)
		(layer "In6.Cu")
		(net "M_H_CPU1_SB_DQ<18>")
	)
	(arc
		(start 132.128514 -231.224836)
		(mid 131.851955 -231.149127)
		(end 131.573778 -231.21874)
		(width 0.088646)
		(layer "In6.Cu")
		(net "M_H_CPU1_SB_DQ<18>")
	)
	(arc
		(start 137.202164 -231.224836)
		(mid 137.014966 -231.274979)
		(end 136.827768 -231.224836)
		(width 0.088646)
		(layer "In6.Cu")
		(net "M_H_CPU1_SB_DQ<18>")
	)
	(arc
		(start 137.767568 -231.224836)
		(mid 137.484866 -231.149094)
		(end 137.202164 -231.224836)
		(width 0.088646)
		(layer "In6.Cu")
		(net "M_H_CPU1_SB_DQ<18>")
	)
	(arc
		(start 133.442964 -231.224836)
		(mid 133.255766 -231.274979)
		(end 133.068568 -231.224836)
		(width 0.088646)
		(layer "In6.Cu")
		(net "M_H_CPU1_SB_DQ<18>")
	)
	(arc
		(start 138.141964 -231.224836)
		(mid 137.954766 -231.274979)
		(end 137.767568 -231.224836)
		(width 0.088646)
		(layer "In6.Cu")
		(net "M_H_CPU1_SB_DQ<18>")
	)
	(arc
		(start 130.704082 -232.03027)
		(mid 130.427607 -231.96295)
		(end 130.15341 -232.038906)
		(width 0.088646)
		(layer "In6.Cu")
		(net "M_H_CPU1_SB_DQ<18>")
	)
	(arc
		(start 134.008368 -231.224836)
		(mid 133.725666 -231.149094)
		(end 133.442964 -231.224836)
		(width 0.088646)
		(layer "In6.Cu")
		(net "M_H_CPU1_SB_DQ<18>")
	)
	(arc
		(start 133.068568 -231.224836)
		(mid 132.791755 -231.149)
		(end 132.513324 -231.21874)
		(width 0.088646)
		(layer "In6.Cu")
		(net "M_H_CPU1_SB_DQ<18>")
	)
	(arc
		(start 130.15341 -232.038906)
		(mid 129.966212 -232.089049)
		(end 129.779014 -232.038906)
		(width 0.088646)
		(layer "In6.Cu")
		(net "M_H_CPU1_SB_DQ<18>")
	)
	(arc
		(start 132.50291 -231.224836)
		(mid 132.315712 -231.274979)
		(end 132.128514 -231.224836)
		(width 0.088646)
		(layer "In6.Cu")
		(net "M_H_CPU1_SB_DQ<18>")
	)
	(arc
		(start 131.563364 -231.224836)
		(mid 131.359883 -231.42564)
		(end 131.280662 -231.700324)
		(width 0.088646)
		(layer "In6.Cu")
		(net "M_H_CPU1_SB_DQ<18>")
	)
	(arc
		(start 131.09321 -232.038906)
		(mid 130.906012 -232.089049)
		(end 130.718814 -232.038906)
		(width 0.088646)
		(layer "In6.Cu")
		(net "M_H_CPU1_SB_DQ<18>")
	)
	(arc
		(start 136.262364 -231.224836)
		(mid 136.075166 -231.274979)
		(end 135.887968 -231.224836)
		(width 0.088646)
		(layer "In6.Cu")
		(net "M_H_CPU1_SB_DQ<18>")
	)
	(arc
		(start 135.887968 -231.224836)
		(mid 135.605266 -231.149094)
		(end 135.322564 -231.224836)
		(width 0.088646)
		(layer "In6.Cu")
		(net "M_H_CPU1_SB_DQ<18>")
	)
	(arc
		(start 138.219942 -231.165654)
		(mid 138.182892 -231.1978)
		(end 138.141964 -231.224836)
		(width 0.088646)
		(layer "In6.Cu")
		(net "M_H_CPU1_SB_DQ<18>")
	)
	(arc
		(start 135.322564 -231.224836)
		(mid 135.135366 -231.274979)
		(end 134.948168 -231.224836)
		(width 0.088646)
		(layer "In6.Cu")
		(net "M_H_CPU1_SB_DQ<18>")
	)
	(arc
		(start 134.382764 -231.224836)
		(mid 134.195566 -231.274979)
		(end 134.008368 -231.224836)
		(width 0.088646)
		(layer "In6.Cu")
		(net "M_H_CPU1_SB_DQ<18>")
	)
	(arc
		(start 136.827768 -231.224836)
		(mid 136.545066 -231.149094)
		(end 136.262364 -231.224836)
		(width 0.088646)
		(layer "In6.Cu")
		(net "M_H_CPU1_SB_DQ<18>")
	)
	(arc
		(start 129.213864 -232.038906)
		(mid 129.026666 -232.089049)
		(end 128.839468 -232.038906)
		(width 0.088646)
		(layer "In6.Cu")
		(net "M_H_CPU1_SB_DQ<18>")
	)
	(segment
		(start 209.186526 -211.335366)
		(end 209.180176 -211.341716)
		(width 0.1016)
		(layer "F.Cu")
		(net "M_H_CPU1_SB_DQ<17>")
	)
	(segment
		(start 205.596744 -211.766658)
		(end 204.076046 -211.766658)
		(width 0.20066)
		(layer "F.Cu")
		(net "M_H_CPU1_SB_DQ<17>")
	)
	(segment
		(start 126.676912 -231.436418)
		(end 126.676912 -230.900732)
		(width 0.20066)
		(layer "F.Cu")
		(net "M_H_CPU1_SB_DQ<17>")
	)
	(segment
		(start 209.180176 -211.341716)
		(end 206.991458 -211.341716)
		(width 0.1016)
		(layer "F.Cu")
		(net "M_H_CPU1_SB_DQ<17>")
	)
	(segment
		(start 206.626714 -211.341716)
		(end 206.508604 -211.459826)
		(width 0.20066)
		(layer "F.Cu")
		(net "M_H_CPU1_SB_DQ<17>")
	)
	(segment
		(start 206.508604 -211.459826)
		(end 206.508604 -211.827364)
		(width 0.20066)
		(layer "F.Cu")
		(net "M_H_CPU1_SB_DQ<17>")
	)
	(segment
		(start 211.619592 -211.766912)
		(end 210.028028 -211.766912)
		(width 0.20066)
		(layer "F.Cu")
		(net "M_H_CPU1_SB_DQ<17>")
	)
	(segment
		(start 205.84541 -212.015324)
		(end 205.596744 -211.766658)
		(width 0.20066)
		(layer "F.Cu")
		(net "M_H_CPU1_SB_DQ<17>")
	)
	(segment
		(start 206.971392 -211.341716)
		(end 206.626714 -211.341716)
		(width 0.20066)
		(layer "F.Cu")
		(net "M_H_CPU1_SB_DQ<17>")
	)
	(segment
		(start 204.076046 -211.766658)
		(end 202.971146 -211.766658)
		(width 0.20066)
		(layer "F.Cu")
		(net "M_H_CPU1_SB_DQ<17>")
	)
	(segment
		(start 126.676912 -230.900732)
		(end 126.677166 -230.900478)
		(width 0.20066)
		(layer "F.Cu")
		(net "M_H_CPU1_SB_DQ<17>")
	)
	(segment
		(start 209.596482 -211.335366)
		(end 209.186526 -211.335366)
		(width 0.20066)
		(layer "F.Cu")
		(net "M_H_CPU1_SB_DQ<17>")
	)
	(segment
		(start 206.508604 -211.827364)
		(end 206.320644 -212.015324)
		(width 0.20066)
		(layer "F.Cu")
		(net "M_H_CPU1_SB_DQ<17>")
	)
	(segment
		(start 210.028028 -211.766912)
		(end 209.596482 -211.335366)
		(width 0.20066)
		(layer "F.Cu")
		(net "M_H_CPU1_SB_DQ<17>")
	)
	(segment
		(start 206.991458 -211.341716)
		(end 206.971392 -211.341716)
		(width 0.101854)
		(layer "F.Cu")
		(net "M_H_CPU1_SB_DQ<17>")
	)
	(segment
		(start 211.619846 -211.766658)
		(end 211.619592 -211.766912)
		(width 0.20066)
		(layer "F.Cu")
		(net "M_H_CPU1_SB_DQ<17>")
	)
	(segment
		(start 206.320644 -212.015324)
		(end 205.84541 -212.015324)
		(width 0.20066)
		(layer "F.Cu")
		(net "M_H_CPU1_SB_DQ<17>")
	)
	(segment
		(start 156.586682 -213.191344)
		(end 140.98397 -228.794056)
		(width 0.18288)
		(layer "In6.Cu")
		(net "M_H_CPU1_SB_DQ<17>")
	)
	(segment
		(start 201.080116 -212.352128)
		(end 201.080116 -212.480652)
		(width 0.18288)
		(layer "In6.Cu")
		(net "M_H_CPU1_SB_DQ<17>")
	)
	(segment
		(start 177.899822 -213.73211)
		(end 177.739802 -213.89213)
		(width 0.18288)
		(layer "In6.Cu")
		(net "M_H_CPU1_SB_DQ<17>")
	)
	(segment
		(start 162.869626 -212.933026)
		(end 161.218626 -212.933026)
		(width 0.18288)
		(layer "In6.Cu")
		(net "M_H_CPU1_SB_DQ<17>")
	)
	(segment
		(start 178.059842 -212.894672)
		(end 177.899822 -213.054692)
		(width 0.18288)
		(layer "In6.Cu")
		(net "M_H_CPU1_SB_DQ<17>")
	)
	(segment
		(start 130.718814 -231.39019)
		(end 130.704082 -231.398826)
		(width 0.088646)
		(layer "In6.Cu")
		(net "M_H_CPU1_SB_DQ<17>")
	)
	(segment
		(start 127.33401 -231.39019)
		(end 127.306324 -231.374442)
		(width 0.088646)
		(layer "In6.Cu")
		(net "M_H_CPU1_SB_DQ<17>")
	)
	(segment
		(start 126.743206 -230.950262)
		(end 126.677166 -230.900478)
		(width 0.088646)
		(layer "In6.Cu")
		(net "M_H_CPU1_SB_DQ<17>")
	)
	(segment
		(start 166.74973 -212.52815)
		(end 166.56685 -212.71103)
		(width 0.18288)
		(layer "In6.Cu")
		(net "M_H_CPU1_SB_DQ<17>")
	)
	(segment
		(start 174.102014 -213.89213)
		(end 173.25213 -214.742014)
		(width 0.18288)
		(layer "In6.Cu")
		(net "M_H_CPU1_SB_DQ<17>")
	)
	(segment
		(start 158.781242 -212.326474)
		(end 158.598362 -212.509354)
		(width 0.18288)
		(layer "In6.Cu")
		(net "M_H_CPU1_SB_DQ<17>")
	)
	(segment
		(start 164.330126 -212.361526)
		(end 163.441126 -212.361526)
		(width 0.18288)
		(layer "In6.Cu")
		(net "M_H_CPU1_SB_DQ<17>")
	)
	(segment
		(start 160.960308 -213.191344)
		(end 159.474662 -213.191344)
		(width 0.18288)
		(layer "In6.Cu")
		(net "M_H_CPU1_SB_DQ<17>")
	)
	(segment
		(start 175.506634 -213.89213)
		(end 174.102014 -213.89213)
		(width 0.18288)
		(layer "In6.Cu")
		(net "M_H_CPU1_SB_DQ<17>")
	)
	(segment
		(start 166.56685 -212.71103)
		(end 166.23919 -212.71103)
		(width 0.18288)
		(layer "In6.Cu")
		(net "M_H_CPU1_SB_DQ<17>")
	)
	(segment
		(start 202.971146 -211.766658)
		(end 202.558396 -212.192108)
		(width 0.18288)
		(layer "In6.Cu")
		(net "M_H_CPU1_SB_DQ<17>")
	)
	(segment
		(start 189.44209 -212.192108)
		(end 188.592206 -213.041992)
		(width 0.18288)
		(layer "In6.Cu")
		(net "M_H_CPU1_SB_DQ<17>")
	)
	(segment
		(start 177.739802 -213.89213)
		(end 176.497996 -213.89213)
		(width 0.18288)
		(layer "In6.Cu")
		(net "M_H_CPU1_SB_DQ<17>")
	)
	(segment
		(start 161.218626 -212.933026)
		(end 160.960308 -213.191344)
		(width 0.18288)
		(layer "In6.Cu")
		(net "M_H_CPU1_SB_DQ<17>")
	)
	(segment
		(start 164.770054 -211.921598)
		(end 164.330126 -212.361526)
		(width 0.18288)
		(layer "In6.Cu")
		(net "M_H_CPU1_SB_DQ<17>")
	)
	(segment
		(start 171.384214 -214.742014)
		(end 169.606976 -212.964776)
		(width 0.18288)
		(layer "In6.Cu")
		(net "M_H_CPU1_SB_DQ<17>")
	)
	(segment
		(start 200.920096 -212.640672)
		(end 200.546716 -212.640672)
		(width 0.18288)
		(layer "In6.Cu")
		(net "M_H_CPU1_SB_DQ<17>")
	)
	(segment
		(start 132.128514 -230.57612)
		(end 132.1181 -230.582216)
		(width 0.088646)
		(layer "In6.Cu")
		(net "M_H_CPU1_SB_DQ<17>")
	)
	(segment
		(start 138.978894 -229.392226)
		(end 137.884662 -230.486458)
		(width 0.088646)
		(layer "In6.Cu")
		(net "M_H_CPU1_SB_DQ<17>")
	)
	(segment
		(start 200.386696 -212.480652)
		(end 200.386696 -212.352128)
		(width 0.18288)
		(layer "In6.Cu")
		(net "M_H_CPU1_SB_DQ<17>")
	)
	(segment
		(start 159.291782 -212.509354)
		(end 159.108902 -212.326474)
		(width 0.18288)
		(layer "In6.Cu")
		(net "M_H_CPU1_SB_DQ<17>")
	)
	(segment
		(start 193.756026 -212.192108)
		(end 193.573146 -212.009228)
		(width 0.18288)
		(layer "In6.Cu")
		(net "M_H_CPU1_SB_DQ<17>")
	)
	(segment
		(start 127.306324 -231.374442)
		(end 126.743206 -230.950262)
		(width 0.088646)
		(layer "In6.Cu")
		(net "M_H_CPU1_SB_DQ<17>")
	)
	(segment
		(start 192.696846 -212.192108)
		(end 189.44209 -212.192108)
		(width 0.18288)
		(layer "In6.Cu")
		(net "M_H_CPU1_SB_DQ<17>")
	)
	(segment
		(start 176.200054 -214.190072)
		(end 175.804576 -214.190072)
		(width 0.18288)
		(layer "In6.Cu")
		(net "M_H_CPU1_SB_DQ<17>")
	)
	(segment
		(start 192.879726 -212.009228)
		(end 192.696846 -212.192108)
		(width 0.18288)
		(layer "In6.Cu")
		(net "M_H_CPU1_SB_DQ<17>")
	)
	(segment
		(start 177.899822 -213.054692)
		(end 177.899822 -213.73211)
		(width 0.18288)
		(layer "In6.Cu")
		(net "M_H_CPU1_SB_DQ<17>")
	)
	(segment
		(start 138.978894 -228.949758)
		(end 138.978894 -229.392226)
		(width 0.088646)
		(layer "In6.Cu")
		(net "M_H_CPU1_SB_DQ<17>")
	)
	(segment
		(start 200.226676 -212.192108)
		(end 193.756026 -212.192108)
		(width 0.18288)
		(layer "In6.Cu")
		(net "M_H_CPU1_SB_DQ<17>")
	)
	(segment
		(start 159.108902 -212.326474)
		(end 158.781242 -212.326474)
		(width 0.18288)
		(layer "In6.Cu")
		(net "M_H_CPU1_SB_DQ<17>")
	)
	(segment
		(start 166.05631 -212.104478)
		(end 165.87343 -211.921598)
		(width 0.18288)
		(layer "In6.Cu")
		(net "M_H_CPU1_SB_DQ<17>")
	)
	(segment
		(start 178.593242 -213.054692)
		(end 178.433222 -212.894672)
		(width 0.18288)
		(layer "In6.Cu")
		(net "M_H_CPU1_SB_DQ<17>")
	)
	(segment
		(start 166.05631 -212.52815)
		(end 166.05631 -212.104478)
		(width 0.18288)
		(layer "In6.Cu")
		(net "M_H_CPU1_SB_DQ<17>")
	)
	(segment
		(start 192.879726 -211.638388)
		(end 192.879726 -212.009228)
		(width 0.18288)
		(layer "In6.Cu")
		(net "M_H_CPU1_SB_DQ<17>")
	)
	(segment
		(start 129.779014 -231.39019)
		(end 129.7686 -231.396286)
		(width 0.088646)
		(layer "In6.Cu")
		(net "M_H_CPU1_SB_DQ<17>")
	)
	(segment
		(start 127.899414 -231.39019)
		(end 127.884682 -231.398826)
		(width 0.088646)
		(layer "In6.Cu")
		(net "M_H_CPU1_SB_DQ<17>")
	)
	(segment
		(start 201.080116 -212.480652)
		(end 200.920096 -212.640672)
		(width 0.18288)
		(layer "In6.Cu")
		(net "M_H_CPU1_SB_DQ<17>")
	)
	(segment
		(start 158.598362 -212.509354)
		(end 158.598362 -213.008464)
		(width 0.18288)
		(layer "In6.Cu")
		(net "M_H_CPU1_SB_DQ<17>")
	)
	(segment
		(start 176.497996 -213.89213)
		(end 176.200054 -214.190072)
		(width 0.18288)
		(layer "In6.Cu")
		(net "M_H_CPU1_SB_DQ<17>")
	)
	(segment
		(start 181.589426 -212.171026)
		(end 179.868322 -213.89213)
		(width 0.18288)
		(layer "In6.Cu")
		(net "M_H_CPU1_SB_DQ<17>")
	)
	(segment
		(start 193.390266 -211.455508)
		(end 193.062606 -211.455508)
		(width 0.18288)
		(layer "In6.Cu")
		(net "M_H_CPU1_SB_DQ<17>")
	)
	(segment
		(start 193.573146 -211.638388)
		(end 193.390266 -211.455508)
		(width 0.18288)
		(layer "In6.Cu")
		(net "M_H_CPU1_SB_DQ<17>")
	)
	(segment
		(start 200.546716 -212.640672)
		(end 200.386696 -212.480652)
		(width 0.18288)
		(layer "In6.Cu")
		(net "M_H_CPU1_SB_DQ<17>")
	)
	(segment
		(start 169.606976 -212.964776)
		(end 168.743376 -212.964776)
		(width 0.18288)
		(layer "In6.Cu")
		(net "M_H_CPU1_SB_DQ<17>")
	)
	(segment
		(start 178.433222 -212.894672)
		(end 178.059842 -212.894672)
		(width 0.18288)
		(layer "In6.Cu")
		(net "M_H_CPU1_SB_DQ<17>")
	)
	(segment
		(start 183.037226 -212.171026)
		(end 181.589426 -212.171026)
		(width 0.18288)
		(layer "In6.Cu")
		(net "M_H_CPU1_SB_DQ<17>")
	)
	(segment
		(start 139.134596 -228.794056)
		(end 138.978894 -228.949758)
		(width 0.088646)
		(layer "In6.Cu")
		(net "M_H_CPU1_SB_DQ<17>")
	)
	(segment
		(start 132.513324 -230.582216)
		(end 132.50291 -230.57612)
		(width 0.088646)
		(layer "In6.Cu")
		(net "M_H_CPU1_SB_DQ<17>")
	)
	(segment
		(start 166.74973 -212.104478)
		(end 166.74973 -212.52815)
		(width 0.18288)
		(layer "In6.Cu")
		(net "M_H_CPU1_SB_DQ<17>")
	)
	(segment
		(start 166.93261 -211.921598)
		(end 166.74973 -212.104478)
		(width 0.18288)
		(layer "In6.Cu")
		(net "M_H_CPU1_SB_DQ<17>")
	)
	(segment
		(start 166.23919 -212.71103)
		(end 166.05631 -212.52815)
		(width 0.18288)
		(layer "In6.Cu")
		(net "M_H_CPU1_SB_DQ<17>")
	)
	(segment
		(start 140.98397 -228.794056)
		(end 139.274042 -228.794056)
		(width 0.18288)
		(layer "In6.Cu")
		(net "M_H_CPU1_SB_DQ<17>")
	)
	(segment
		(start 158.598362 -213.008464)
		(end 158.415482 -213.191344)
		(width 0.18288)
		(layer "In6.Cu")
		(net "M_H_CPU1_SB_DQ<17>")
	)
	(segment
		(start 175.804576 -214.190072)
		(end 175.506634 -213.89213)
		(width 0.18288)
		(layer "In6.Cu")
		(net "M_H_CPU1_SB_DQ<17>")
	)
	(segment
		(start 139.274042 -228.794056)
		(end 139.134596 -228.794056)
		(width 0.088646)
		(layer "In6.Cu")
		(net "M_H_CPU1_SB_DQ<17>")
	)
	(segment
		(start 201.240136 -212.192108)
		(end 201.080116 -212.352128)
		(width 0.18288)
		(layer "In6.Cu")
		(net "M_H_CPU1_SB_DQ<17>")
	)
	(segment
		(start 193.062606 -211.455508)
		(end 192.879726 -211.638388)
		(width 0.18288)
		(layer "In6.Cu")
		(net "M_H_CPU1_SB_DQ<17>")
	)
	(segment
		(start 159.291782 -213.008464)
		(end 159.291782 -212.509354)
		(width 0.18288)
		(layer "In6.Cu")
		(net "M_H_CPU1_SB_DQ<17>")
	)
	(segment
		(start 193.573146 -212.009228)
		(end 193.573146 -211.638388)
		(width 0.18288)
		(layer "In6.Cu")
		(net "M_H_CPU1_SB_DQ<17>")
	)
	(segment
		(start 131.001516 -230.900478)
		(end 131.001516 -230.914702)
		(width 0.088646)
		(layer "In6.Cu")
		(net "M_H_CPU1_SB_DQ<17>")
	)
	(segment
		(start 202.558396 -212.192108)
		(end 201.240136 -212.192108)
		(width 0.18288)
		(layer "In6.Cu")
		(net "M_H_CPU1_SB_DQ<17>")
	)
	(segment
		(start 167.700198 -211.921598)
		(end 166.93261 -211.921598)
		(width 0.18288)
		(layer "In6.Cu")
		(net "M_H_CPU1_SB_DQ<17>")
	)
	(segment
		(start 173.25213 -214.742014)
		(end 171.384214 -214.742014)
		(width 0.18288)
		(layer "In6.Cu")
		(net "M_H_CPU1_SB_DQ<17>")
	)
	(segment
		(start 179.868322 -213.89213)
		(end 178.753262 -213.89213)
		(width 0.18288)
		(layer "In6.Cu")
		(net "M_H_CPU1_SB_DQ<17>")
	)
	(segment
		(start 178.753262 -213.89213)
		(end 178.593242 -213.73211)
		(width 0.18288)
		(layer "In6.Cu")
		(net "M_H_CPU1_SB_DQ<17>")
	)
	(segment
		(start 131.188968 -230.57612)
		(end 131.180078 -230.5812)
		(width 0.088646)
		(layer "In6.Cu")
		(net "M_H_CPU1_SB_DQ<17>")
	)
	(segment
		(start 178.593242 -213.73211)
		(end 178.593242 -213.054692)
		(width 0.18288)
		(layer "In6.Cu")
		(net "M_H_CPU1_SB_DQ<17>")
	)
	(segment
		(start 200.386696 -212.352128)
		(end 200.226676 -212.192108)
		(width 0.18288)
		(layer "In6.Cu")
		(net "M_H_CPU1_SB_DQ<17>")
	)
	(segment
		(start 168.743376 -212.964776)
		(end 167.700198 -211.921598)
		(width 0.18288)
		(layer "In6.Cu")
		(net "M_H_CPU1_SB_DQ<17>")
	)
	(segment
		(start 165.87343 -211.921598)
		(end 164.770054 -211.921598)
		(width 0.18288)
		(layer "In6.Cu")
		(net "M_H_CPU1_SB_DQ<17>")
	)
	(segment
		(start 159.474662 -213.191344)
		(end 159.291782 -213.008464)
		(width 0.18288)
		(layer "In6.Cu")
		(net "M_H_CPU1_SB_DQ<17>")
	)
	(segment
		(start 163.441126 -212.361526)
		(end 162.869626 -212.933026)
		(width 0.18288)
		(layer "In6.Cu")
		(net "M_H_CPU1_SB_DQ<17>")
	)
	(segment
		(start 188.592206 -213.041992)
		(end 183.908192 -213.041992)
		(width 0.18288)
		(layer "In6.Cu")
		(net "M_H_CPU1_SB_DQ<17>")
	)
	(segment
		(start 158.415482 -213.191344)
		(end 156.586682 -213.191344)
		(width 0.18288)
		(layer "In6.Cu")
		(net "M_H_CPU1_SB_DQ<17>")
	)
	(segment
		(start 128.839468 -231.39019)
		(end 128.829054 -231.396286)
		(width 0.088646)
		(layer "In6.Cu")
		(net "M_H_CPU1_SB_DQ<17>")
	)
	(segment
		(start 183.908192 -213.041992)
		(end 183.037226 -212.171026)
		(width 0.18288)
		(layer "In6.Cu")
		(net "M_H_CPU1_SB_DQ<17>")
	)
	(arc
		(start 129.7686 -231.396286)
		(mid 129.490422 -231.465978)
		(end 129.213864 -231.39019)
		(width 0.088646)
		(layer "In6.Cu")
		(net "M_H_CPU1_SB_DQ<17>")
	)
	(arc
		(start 131.180078 -230.5812)
		(mid 131.049164 -230.71756)
		(end 131.001516 -230.900478)
		(width 0.088646)
		(layer "In6.Cu")
		(net "M_H_CPU1_SB_DQ<17>")
	)
	(arc
		(start 131.001516 -230.914702)
		(mid 130.922297 -231.189387)
		(end 130.718814 -231.39019)
		(width 0.088646)
		(layer "In6.Cu")
		(net "M_H_CPU1_SB_DQ<17>")
	)
	(arc
		(start 131.563364 -230.57612)
		(mid 131.376166 -230.525977)
		(end 131.188968 -230.57612)
		(width 0.088646)
		(layer "In6.Cu")
		(net "M_H_CPU1_SB_DQ<17>")
	)
	(arc
		(start 130.15341 -231.39019)
		(mid 129.966212 -231.340047)
		(end 129.779014 -231.39019)
		(width 0.088646)
		(layer "In6.Cu")
		(net "M_H_CPU1_SB_DQ<17>")
	)
	(arc
		(start 130.704082 -231.398826)
		(mid 130.427641 -231.465992)
		(end 130.15341 -231.39019)
		(width 0.088646)
		(layer "In6.Cu")
		(net "M_H_CPU1_SB_DQ<17>")
	)
	(arc
		(start 135.887968 -230.57612)
		(mid 135.605266 -230.651896)
		(end 135.322564 -230.57612)
		(width 0.088646)
		(layer "In6.Cu")
		(net "M_H_CPU1_SB_DQ<17>")
	)
	(arc
		(start 132.1181 -230.582216)
		(mid 131.839922 -230.651939)
		(end 131.563364 -230.57612)
		(width 0.088646)
		(layer "In6.Cu")
		(net "M_H_CPU1_SB_DQ<17>")
	)
	(arc
		(start 134.008368 -230.57612)
		(mid 133.725666 -230.651896)
		(end 133.442964 -230.57612)
		(width 0.088646)
		(layer "In6.Cu")
		(net "M_H_CPU1_SB_DQ<17>")
	)
	(arc
		(start 137.884662 -230.486458)
		(mid 137.829057 -230.535132)
		(end 137.767568 -230.57612)
		(width 0.088646)
		(layer "In6.Cu")
		(net "M_H_CPU1_SB_DQ<17>")
	)
	(arc
		(start 134.948168 -230.57612)
		(mid 134.665466 -230.651896)
		(end 134.382764 -230.57612)
		(width 0.088646)
		(layer "In6.Cu")
		(net "M_H_CPU1_SB_DQ<17>")
	)
	(arc
		(start 137.767568 -230.57612)
		(mid 137.484866 -230.651896)
		(end 137.202164 -230.57612)
		(width 0.088646)
		(layer "In6.Cu")
		(net "M_H_CPU1_SB_DQ<17>")
	)
	(arc
		(start 129.213864 -231.39019)
		(mid 129.026666 -231.340047)
		(end 128.839468 -231.39019)
		(width 0.088646)
		(layer "In6.Cu")
		(net "M_H_CPU1_SB_DQ<17>")
	)
	(arc
		(start 136.827768 -230.57612)
		(mid 136.545066 -230.651896)
		(end 136.262364 -230.57612)
		(width 0.088646)
		(layer "In6.Cu")
		(net "M_H_CPU1_SB_DQ<17>")
	)
	(arc
		(start 128.27381 -231.39019)
		(mid 128.086612 -231.340047)
		(end 127.899414 -231.39019)
		(width 0.088646)
		(layer "In6.Cu")
		(net "M_H_CPU1_SB_DQ<17>")
	)
	(arc
		(start 134.382764 -230.57612)
		(mid 134.195566 -230.525977)
		(end 134.008368 -230.57612)
		(width 0.088646)
		(layer "In6.Cu")
		(net "M_H_CPU1_SB_DQ<17>")
	)
	(arc
		(start 127.884682 -231.398826)
		(mid 127.608241 -231.465992)
		(end 127.33401 -231.39019)
		(width 0.088646)
		(layer "In6.Cu")
		(net "M_H_CPU1_SB_DQ<17>")
	)
	(arc
		(start 128.829054 -231.396286)
		(mid 128.550622 -231.4661)
		(end 128.27381 -231.39019)
		(width 0.088646)
		(layer "In6.Cu")
		(net "M_H_CPU1_SB_DQ<17>")
	)
	(arc
		(start 133.068568 -230.57612)
		(mid 132.791755 -230.65199)
		(end 132.513324 -230.582216)
		(width 0.088646)
		(layer "In6.Cu")
		(net "M_H_CPU1_SB_DQ<17>")
	)
	(arc
		(start 136.262364 -230.57612)
		(mid 136.075166 -230.525977)
		(end 135.887968 -230.57612)
		(width 0.088646)
		(layer "In6.Cu")
		(net "M_H_CPU1_SB_DQ<17>")
	)
	(arc
		(start 133.442964 -230.57612)
		(mid 133.255766 -230.525977)
		(end 133.068568 -230.57612)
		(width 0.088646)
		(layer "In6.Cu")
		(net "M_H_CPU1_SB_DQ<17>")
	)
	(arc
		(start 132.50291 -230.57612)
		(mid 132.315712 -230.525977)
		(end 132.128514 -230.57612)
		(width 0.088646)
		(layer "In6.Cu")
		(net "M_H_CPU1_SB_DQ<17>")
	)
	(arc
		(start 137.202164 -230.57612)
		(mid 137.014966 -230.525977)
		(end 136.827768 -230.57612)
		(width 0.088646)
		(layer "In6.Cu")
		(net "M_H_CPU1_SB_DQ<17>")
	)
	(arc
		(start 135.322564 -230.57612)
		(mid 135.135366 -230.525977)
		(end 134.948168 -230.57612)
		(width 0.088646)
		(layer "In6.Cu")
		(net "M_H_CPU1_SB_DQ<17>")
	)
	(segment
		(start 211.619592 -213.466934)
		(end 210.028028 -213.466934)
		(width 0.20066)
		(layer "F.Cu")
		(net "M_H_CPU1_SB_DQ<16>")
	)
	(segment
		(start 211.619846 -213.46668)
		(end 211.619592 -213.466934)
		(width 0.20066)
		(layer "F.Cu")
		(net "M_H_CPU1_SB_DQ<16>")
	)
	(segment
		(start 209.180176 -213.041738)
		(end 207.018382 -213.041738)
		(width 0.1016)
		(layer "F.Cu")
		(net "M_H_CPU1_SB_DQ<16>")
	)
	(segment
		(start 127.146812 -232.250234)
		(end 127.146812 -231.714548)
		(width 0.20066)
		(layer "F.Cu")
		(net "M_H_CPU1_SB_DQ<16>")
	)
	(segment
		(start 207.018382 -213.041738)
		(end 206.971392 -213.041738)
		(width 0.101854)
		(layer "F.Cu")
		(net "M_H_CPU1_SB_DQ<16>")
	)
	(segment
		(start 127.147066 -232.250488)
		(end 127.146812 -232.250234)
		(width 0.20066)
		(layer "F.Cu")
		(net "M_H_CPU1_SB_DQ<16>")
	)
	(segment
		(start 206.508604 -213.159848)
		(end 206.508604 -213.527386)
		(width 0.20066)
		(layer "F.Cu")
		(net "M_H_CPU1_SB_DQ<16>")
	)
	(segment
		(start 209.596482 -213.035388)
		(end 209.186526 -213.035388)
		(width 0.20066)
		(layer "F.Cu")
		(net "M_H_CPU1_SB_DQ<16>")
	)
	(segment
		(start 205.596744 -213.46668)
		(end 204.076046 -213.46668)
		(width 0.20066)
		(layer "F.Cu")
		(net "M_H_CPU1_SB_DQ<16>")
	)
	(segment
		(start 206.626714 -213.041738)
		(end 206.508604 -213.159848)
		(width 0.20066)
		(layer "F.Cu")
		(net "M_H_CPU1_SB_DQ<16>")
	)
	(segment
		(start 204.076046 -213.46668)
		(end 202.971146 -213.46668)
		(width 0.20066)
		(layer "F.Cu")
		(net "M_H_CPU1_SB_DQ<16>")
	)
	(segment
		(start 205.84541 -213.715346)
		(end 205.596744 -213.46668)
		(width 0.20066)
		(layer "F.Cu")
		(net "M_H_CPU1_SB_DQ<16>")
	)
	(segment
		(start 206.971392 -213.041738)
		(end 206.626714 -213.041738)
		(width 0.20066)
		(layer "F.Cu")
		(net "M_H_CPU1_SB_DQ<16>")
	)
	(segment
		(start 206.320644 -213.715346)
		(end 205.84541 -213.715346)
		(width 0.20066)
		(layer "F.Cu")
		(net "M_H_CPU1_SB_DQ<16>")
	)
	(segment
		(start 209.186526 -213.035388)
		(end 209.180176 -213.041738)
		(width 0.1016)
		(layer "F.Cu")
		(net "M_H_CPU1_SB_DQ<16>")
	)
	(segment
		(start 210.028028 -213.466934)
		(end 209.596482 -213.035388)
		(width 0.20066)
		(layer "F.Cu")
		(net "M_H_CPU1_SB_DQ<16>")
	)
	(segment
		(start 206.508604 -213.527386)
		(end 206.320644 -213.715346)
		(width 0.20066)
		(layer "F.Cu")
		(net "M_H_CPU1_SB_DQ<16>")
	)
	(segment
		(start 173.842172 -215.594946)
		(end 172.998892 -216.438226)
		(width 0.18288)
		(layer "In6.Cu")
		(net "M_H_CPU1_SB_DQ<16>")
	)
	(segment
		(start 164.485828 -214.091774)
		(end 163.596828 -214.091774)
		(width 0.18288)
		(layer "In6.Cu")
		(net "M_H_CPU1_SB_DQ<16>")
	)
	(segment
		(start 200.343516 -214.919052)
		(end 200.343516 -214.512144)
		(width 0.18288)
		(layer "In6.Cu")
		(net "M_H_CPU1_SB_DQ<16>")
	)
	(segment
		(start 202.085702 -214.352124)
		(end 201.196956 -214.352124)
		(width 0.18288)
		(layer "In6.Cu")
		(net "M_H_CPU1_SB_DQ<16>")
	)
	(segment
		(start 169.764456 -214.704676)
		(end 168.654476 -214.704676)
		(width 0.18288)
		(layer "In6.Cu")
		(net "M_H_CPU1_SB_DQ<16>")
	)
	(segment
		(start 166.588948 -214.528654)
		(end 166.261288 -214.528654)
		(width 0.18288)
		(layer "In6.Cu")
		(net "M_H_CPU1_SB_DQ<16>")
	)
	(segment
		(start 186.319414 -214.740998)
		(end 186.108594 -214.530178)
		(width 0.18288)
		(layer "In6.Cu")
		(net "M_H_CPU1_SB_DQ<16>")
	)
	(segment
		(start 159.452564 -215.148668)
		(end 159.269684 -214.965788)
		(width 0.18288)
		(layer "In6.Cu")
		(net "M_H_CPU1_SB_DQ<16>")
	)
	(segment
		(start 166.771828 -213.979506)
		(end 166.771828 -214.345774)
		(width 0.18288)
		(layer "In6.Cu")
		(net "M_H_CPU1_SB_DQ<16>")
	)
	(segment
		(start 139.757404 -230.255064)
		(end 139.535154 -230.477314)
		(width 0.088646)
		(layer "In6.Cu")
		(net "M_H_CPU1_SB_DQ<16>")
	)
	(segment
		(start 172.998892 -216.438226)
		(end 172.61967 -216.438226)
		(width 0.18288)
		(layer "In6.Cu")
		(net "M_H_CPU1_SB_DQ<16>")
	)
	(segment
		(start 171.255436 -216.195656)
		(end 169.764456 -214.704676)
		(width 0.18288)
		(layer "In6.Cu")
		(net "M_H_CPU1_SB_DQ<16>")
	)
	(segment
		(start 194.741038 -214.254334)
		(end 193.985134 -214.254334)
		(width 0.18288)
		(layer "In6.Cu")
		(net "M_H_CPU1_SB_DQ<16>")
	)
	(segment
		(start 166.078408 -213.979506)
		(end 165.895528 -213.796626)
		(width 0.18288)
		(layer "In6.Cu")
		(net "M_H_CPU1_SB_DQ<16>")
	)
	(segment
		(start 200.503536 -215.079072)
		(end 200.343516 -214.919052)
		(width 0.18288)
		(layer "In6.Cu")
		(net "M_H_CPU1_SB_DQ<16>")
	)
	(segment
		(start 196.108066 -214.034116)
		(end 195.925186 -213.851236)
		(width 0.18288)
		(layer "In6.Cu")
		(net "M_H_CPU1_SB_DQ<16>")
	)
	(segment
		(start 139.177522 -230.477314)
		(end 138.354562 -231.300274)
		(width 0.088646)
		(layer "In6.Cu")
		(net "M_H_CPU1_SB_DQ<16>")
	)
	(segment
		(start 200.183496 -214.352124)
		(end 198.807324 -214.352124)
		(width 0.18288)
		(layer "In6.Cu")
		(net "M_H_CPU1_SB_DQ<16>")
	)
	(segment
		(start 201.036936 -214.919052)
		(end 200.876916 -215.079072)
		(width 0.18288)
		(layer "In6.Cu")
		(net "M_H_CPU1_SB_DQ<16>")
	)
	(segment
		(start 129.698496 -232.212642)
		(end 129.683764 -232.204006)
		(width 0.088646)
		(layer "In6.Cu")
		(net "M_H_CPU1_SB_DQ<16>")
	)
	(segment
		(start 200.343516 -214.512144)
		(end 200.183496 -214.352124)
		(width 0.18288)
		(layer "In6.Cu")
		(net "M_H_CPU1_SB_DQ<16>")
	)
	(segment
		(start 130.638296 -232.212642)
		(end 130.623564 -232.204006)
		(width 0.088646)
		(layer "In6.Cu")
		(net "M_H_CPU1_SB_DQ<16>")
	)
	(segment
		(start 159.269684 -214.965788)
		(end 159.269684 -214.466932)
		(width 0.18288)
		(layer "In6.Cu")
		(net "M_H_CPU1_SB_DQ<16>")
	)
	(segment
		(start 200.876916 -215.079072)
		(end 200.503536 -215.079072)
		(width 0.18288)
		(layer "In6.Cu")
		(net "M_H_CPU1_SB_DQ<16>")
	)
	(segment
		(start 196.801486 -215.040464)
		(end 196.618606 -215.223344)
		(width 0.18288)
		(layer "In6.Cu")
		(net "M_H_CPU1_SB_DQ<16>")
	)
	(segment
		(start 139.757404 -229.897686)
		(end 139.757404 -230.255064)
		(width 0.088646)
		(layer "In6.Cu")
		(net "M_H_CPU1_SB_DQ<16>")
	)
	(segment
		(start 196.290946 -215.223344)
		(end 196.108066 -215.040464)
		(width 0.18288)
		(layer "In6.Cu")
		(net "M_H_CPU1_SB_DQ<16>")
	)
	(segment
		(start 166.078408 -214.345774)
		(end 166.078408 -213.979506)
		(width 0.18288)
		(layer "In6.Cu")
		(net "M_H_CPU1_SB_DQ<16>")
	)
	(segment
		(start 189.893702 -213.89213)
		(end 189.044834 -214.740998)
		(width 0.18288)
		(layer "In6.Cu")
		(net "M_H_CPU1_SB_DQ<16>")
	)
	(segment
		(start 195.925186 -213.851236)
		(end 195.144136 -213.851236)
		(width 0.18288)
		(layer "In6.Cu")
		(net "M_H_CPU1_SB_DQ<16>")
	)
	(segment
		(start 131.658614 -231.39019)
		(end 131.649724 -231.39527)
		(width 0.088646)
		(layer "In6.Cu")
		(net "M_H_CPU1_SB_DQ<16>")
	)
	(segment
		(start 163.596828 -214.091774)
		(end 163.098226 -214.590376)
		(width 0.18288)
		(layer "In6.Cu")
		(net "M_H_CPU1_SB_DQ<16>")
	)
	(segment
		(start 139.853416 -229.801674)
		(end 139.757404 -229.897686)
		(width 0.088646)
		(layer "In6.Cu")
		(net "M_H_CPU1_SB_DQ<16>")
	)
	(segment
		(start 186.108594 -214.530178)
		(end 183.770778 -214.530178)
		(width 0.18288)
		(layer "In6.Cu")
		(net "M_H_CPU1_SB_DQ<16>")
	)
	(segment
		(start 156.221684 -215.148668)
		(end 141.568678 -229.801674)
		(width 0.18288)
		(layer "In6.Cu")
		(net "M_H_CPU1_SB_DQ<16>")
	)
	(segment
		(start 141.568678 -229.801674)
		(end 140.061442 -229.801674)
		(width 0.18288)
		(layer "In6.Cu")
		(net "M_H_CPU1_SB_DQ<16>")
	)
	(segment
		(start 193.985134 -214.254334)
		(end 193.62293 -213.89213)
		(width 0.18288)
		(layer "In6.Cu")
		(net "M_H_CPU1_SB_DQ<16>")
	)
	(segment
		(start 202.971146 -213.46668)
		(end 202.085702 -214.352124)
		(width 0.18288)
		(layer "In6.Cu")
		(net "M_H_CPU1_SB_DQ<16>")
	)
	(segment
		(start 140.061442 -229.801674)
		(end 139.853416 -229.801674)
		(width 0.088646)
		(layer "In6.Cu")
		(net "M_H_CPU1_SB_DQ<16>")
	)
	(segment
		(start 172.3771 -216.195656)
		(end 171.255436 -216.195656)
		(width 0.18288)
		(layer "In6.Cu")
		(net "M_H_CPU1_SB_DQ<16>")
	)
	(segment
		(start 158.576264 -214.965788)
		(end 158.393384 -215.148668)
		(width 0.18288)
		(layer "In6.Cu")
		(net "M_H_CPU1_SB_DQ<16>")
	)
	(segment
		(start 198.306436 -213.851236)
		(end 196.984366 -213.851236)
		(width 0.18288)
		(layer "In6.Cu")
		(net "M_H_CPU1_SB_DQ<16>")
	)
	(segment
		(start 193.62293 -213.89213)
		(end 189.893702 -213.89213)
		(width 0.18288)
		(layer "In6.Cu")
		(net "M_H_CPU1_SB_DQ<16>")
	)
	(segment
		(start 127.818896 -232.212642)
		(end 127.804164 -232.204006)
		(width 0.088646)
		(layer "In6.Cu")
		(net "M_H_CPU1_SB_DQ<16>")
	)
	(segment
		(start 182.376826 -213.847426)
		(end 180.629306 -215.594946)
		(width 0.18288)
		(layer "In6.Cu")
		(net "M_H_CPU1_SB_DQ<16>")
	)
	(segment
		(start 158.576264 -214.466932)
		(end 158.576264 -214.965788)
		(width 0.18288)
		(layer "In6.Cu")
		(net "M_H_CPU1_SB_DQ<16>")
	)
	(segment
		(start 163.098226 -214.590376)
		(end 161.275776 -214.590376)
		(width 0.18288)
		(layer "In6.Cu")
		(net "M_H_CPU1_SB_DQ<16>")
	)
	(segment
		(start 168.654476 -214.704676)
		(end 167.746426 -213.796626)
		(width 0.18288)
		(layer "In6.Cu")
		(net "M_H_CPU1_SB_DQ<16>")
	)
	(segment
		(start 198.807324 -214.352124)
		(end 198.306436 -213.851236)
		(width 0.18288)
		(layer "In6.Cu")
		(net "M_H_CPU1_SB_DQ<16>")
	)
	(segment
		(start 172.61967 -216.438226)
		(end 172.3771 -216.195656)
		(width 0.18288)
		(layer "In6.Cu")
		(net "M_H_CPU1_SB_DQ<16>")
	)
	(segment
		(start 159.086804 -214.284052)
		(end 158.759144 -214.284052)
		(width 0.18288)
		(layer "In6.Cu")
		(net "M_H_CPU1_SB_DQ<16>")
	)
	(segment
		(start 166.954708 -213.796626)
		(end 166.771828 -213.979506)
		(width 0.18288)
		(layer "In6.Cu")
		(net "M_H_CPU1_SB_DQ<16>")
	)
	(segment
		(start 196.618606 -215.223344)
		(end 196.290946 -215.223344)
		(width 0.18288)
		(layer "In6.Cu")
		(net "M_H_CPU1_SB_DQ<16>")
	)
	(segment
		(start 127.804164 -232.204006)
		(end 127.773938 -232.186734)
		(width 0.088646)
		(layer "In6.Cu")
		(net "M_H_CPU1_SB_DQ<16>")
	)
	(segment
		(start 196.108066 -215.040464)
		(end 196.108066 -214.034116)
		(width 0.18288)
		(layer "In6.Cu")
		(net "M_H_CPU1_SB_DQ<16>")
	)
	(segment
		(start 183.770778 -214.530178)
		(end 183.088026 -213.847426)
		(width 0.18288)
		(layer "In6.Cu")
		(net "M_H_CPU1_SB_DQ<16>")
	)
	(segment
		(start 166.261288 -214.528654)
		(end 166.078408 -214.345774)
		(width 0.18288)
		(layer "In6.Cu")
		(net "M_H_CPU1_SB_DQ<16>")
	)
	(segment
		(start 196.801486 -214.034116)
		(end 196.801486 -215.040464)
		(width 0.18288)
		(layer "In6.Cu")
		(net "M_H_CPU1_SB_DQ<16>")
	)
	(segment
		(start 160.717484 -215.148668)
		(end 159.452564 -215.148668)
		(width 0.18288)
		(layer "In6.Cu")
		(net "M_H_CPU1_SB_DQ<16>")
	)
	(segment
		(start 159.269684 -214.466932)
		(end 159.086804 -214.284052)
		(width 0.18288)
		(layer "In6.Cu")
		(net "M_H_CPU1_SB_DQ<16>")
	)
	(segment
		(start 189.044834 -214.740998)
		(end 186.319414 -214.740998)
		(width 0.18288)
		(layer "In6.Cu")
		(net "M_H_CPU1_SB_DQ<16>")
	)
	(segment
		(start 167.746426 -213.796626)
		(end 166.954708 -213.796626)
		(width 0.18288)
		(layer "In6.Cu")
		(net "M_H_CPU1_SB_DQ<16>")
	)
	(segment
		(start 196.984366 -213.851236)
		(end 196.801486 -214.034116)
		(width 0.18288)
		(layer "In6.Cu")
		(net "M_H_CPU1_SB_DQ<16>")
	)
	(segment
		(start 158.393384 -215.148668)
		(end 156.221684 -215.148668)
		(width 0.18288)
		(layer "In6.Cu")
		(net "M_H_CPU1_SB_DQ<16>")
	)
	(segment
		(start 158.759144 -214.284052)
		(end 158.576264 -214.466932)
		(width 0.18288)
		(layer "In6.Cu")
		(net "M_H_CPU1_SB_DQ<16>")
	)
	(segment
		(start 201.036936 -214.512144)
		(end 201.036936 -214.919052)
		(width 0.18288)
		(layer "In6.Cu")
		(net "M_H_CPU1_SB_DQ<16>")
	)
	(segment
		(start 166.771828 -214.345774)
		(end 166.588948 -214.528654)
		(width 0.18288)
		(layer "In6.Cu")
		(net "M_H_CPU1_SB_DQ<16>")
	)
	(segment
		(start 131.471162 -231.714548)
		(end 131.471162 -231.730042)
		(width 0.088646)
		(layer "In6.Cu")
		(net "M_H_CPU1_SB_DQ<16>")
	)
	(segment
		(start 161.275776 -214.590376)
		(end 160.717484 -215.148668)
		(width 0.18288)
		(layer "In6.Cu")
		(net "M_H_CPU1_SB_DQ<16>")
	)
	(segment
		(start 201.196956 -214.352124)
		(end 201.036936 -214.512144)
		(width 0.18288)
		(layer "In6.Cu")
		(net "M_H_CPU1_SB_DQ<16>")
	)
	(segment
		(start 195.144136 -213.851236)
		(end 194.741038 -214.254334)
		(width 0.18288)
		(layer "In6.Cu")
		(net "M_H_CPU1_SB_DQ<16>")
	)
	(segment
		(start 133.538468 -231.39019)
		(end 133.528054 -231.396286)
		(width 0.088646)
		(layer "In6.Cu")
		(net "M_H_CPU1_SB_DQ<16>")
	)
	(segment
		(start 139.535154 -230.477314)
		(end 139.177522 -230.477314)
		(width 0.088646)
		(layer "In6.Cu")
		(net "M_H_CPU1_SB_DQ<16>")
	)
	(segment
		(start 127.773938 -232.186734)
		(end 127.146812 -231.714548)
		(width 0.088646)
		(layer "In6.Cu")
		(net "M_H_CPU1_SB_DQ<16>")
	)
	(segment
		(start 180.629306 -215.594946)
		(end 173.842172 -215.594946)
		(width 0.18288)
		(layer "In6.Cu")
		(net "M_H_CPU1_SB_DQ<16>")
	)
	(segment
		(start 164.780976 -213.796626)
		(end 164.485828 -214.091774)
		(width 0.18288)
		(layer "In6.Cu")
		(net "M_H_CPU1_SB_DQ<16>")
	)
	(segment
		(start 183.088026 -213.847426)
		(end 182.376826 -213.847426)
		(width 0.18288)
		(layer "In6.Cu")
		(net "M_H_CPU1_SB_DQ<16>")
	)
	(segment
		(start 165.895528 -213.796626)
		(end 164.780976 -213.796626)
		(width 0.18288)
		(layer "In6.Cu")
		(net "M_H_CPU1_SB_DQ<16>")
	)
	(arc
		(start 132.03301 -231.39019)
		(mid 131.845812 -231.340047)
		(end 131.658614 -231.39019)
		(width 0.088646)
		(layer "In6.Cu")
		(net "M_H_CPU1_SB_DQ<16>")
	)
	(arc
		(start 131.188968 -232.204006)
		(mid 130.914769 -232.279841)
		(end 130.638296 -232.212642)
		(width 0.088646)
		(layer "In6.Cu")
		(net "M_H_CPU1_SB_DQ<16>")
	)
	(arc
		(start 129.309368 -232.204006)
		(mid 129.026666 -232.279782)
		(end 128.743964 -232.204006)
		(width 0.088646)
		(layer "In6.Cu")
		(net "M_H_CPU1_SB_DQ<16>")
	)
	(arc
		(start 131.649724 -231.39527)
		(mid 131.51881 -231.53163)
		(end 131.471162 -231.714548)
		(width 0.088646)
		(layer "In6.Cu")
		(net "M_H_CPU1_SB_DQ<16>")
	)
	(arc
		(start 129.683764 -232.204006)
		(mid 129.496566 -232.153863)
		(end 129.309368 -232.204006)
		(width 0.088646)
		(layer "In6.Cu")
		(net "M_H_CPU1_SB_DQ<16>")
	)
	(arc
		(start 128.743964 -232.204006)
		(mid 128.556766 -232.153863)
		(end 128.369568 -232.204006)
		(width 0.088646)
		(layer "In6.Cu")
		(net "M_H_CPU1_SB_DQ<16>")
	)
	(arc
		(start 132.598414 -231.39019)
		(mid 132.315712 -231.465932)
		(end 132.03301 -231.39019)
		(width 0.088646)
		(layer "In6.Cu")
		(net "M_H_CPU1_SB_DQ<16>")
	)
	(arc
		(start 134.478268 -231.39019)
		(mid 134.195566 -231.465932)
		(end 133.912864 -231.39019)
		(width 0.088646)
		(layer "In6.Cu")
		(net "M_H_CPU1_SB_DQ<16>")
	)
	(arc
		(start 136.357868 -231.39019)
		(mid 136.075166 -231.465932)
		(end 135.792464 -231.39019)
		(width 0.088646)
		(layer "In6.Cu")
		(net "M_H_CPU1_SB_DQ<16>")
	)
	(arc
		(start 135.792464 -231.39019)
		(mid 135.605266 -231.340047)
		(end 135.418068 -231.39019)
		(width 0.088646)
		(layer "In6.Cu")
		(net "M_H_CPU1_SB_DQ<16>")
	)
	(arc
		(start 138.354562 -231.300274)
		(mid 138.028579 -231.461036)
		(end 137.672064 -231.39019)
		(width 0.088646)
		(layer "In6.Cu")
		(net "M_H_CPU1_SB_DQ<16>")
	)
	(arc
		(start 131.471162 -231.730042)
		(mid 131.391792 -232.003776)
		(end 131.188968 -232.204006)
		(width 0.088646)
		(layer "In6.Cu")
		(net "M_H_CPU1_SB_DQ<16>")
	)
	(arc
		(start 130.249168 -232.204006)
		(mid 129.974969 -232.279841)
		(end 129.698496 -232.212642)
		(width 0.088646)
		(layer "In6.Cu")
		(net "M_H_CPU1_SB_DQ<16>")
	)
	(arc
		(start 135.418068 -231.39019)
		(mid 135.135366 -231.465932)
		(end 134.852664 -231.39019)
		(width 0.088646)
		(layer "In6.Cu")
		(net "M_H_CPU1_SB_DQ<16>")
	)
	(arc
		(start 137.672064 -231.39019)
		(mid 137.484866 -231.340047)
		(end 137.297668 -231.39019)
		(width 0.088646)
		(layer "In6.Cu")
		(net "M_H_CPU1_SB_DQ<16>")
	)
	(arc
		(start 130.623564 -232.204006)
		(mid 130.436366 -232.153863)
		(end 130.249168 -232.204006)
		(width 0.088646)
		(layer "In6.Cu")
		(net "M_H_CPU1_SB_DQ<16>")
	)
	(arc
		(start 133.912864 -231.39019)
		(mid 133.725666 -231.340047)
		(end 133.538468 -231.39019)
		(width 0.088646)
		(layer "In6.Cu")
		(net "M_H_CPU1_SB_DQ<16>")
	)
	(arc
		(start 133.528054 -231.396286)
		(mid 133.249622 -231.4661)
		(end 132.97281 -231.39019)
		(width 0.088646)
		(layer "In6.Cu")
		(net "M_H_CPU1_SB_DQ<16>")
	)
	(arc
		(start 134.852664 -231.39019)
		(mid 134.665466 -231.340047)
		(end 134.478268 -231.39019)
		(width 0.088646)
		(layer "In6.Cu")
		(net "M_H_CPU1_SB_DQ<16>")
	)
	(arc
		(start 128.369568 -232.204006)
		(mid 128.095369 -232.279841)
		(end 127.818896 -232.212642)
		(width 0.088646)
		(layer "In6.Cu")
		(net "M_H_CPU1_SB_DQ<16>")
	)
	(arc
		(start 137.297668 -231.39019)
		(mid 137.014966 -231.465932)
		(end 136.732264 -231.39019)
		(width 0.088646)
		(layer "In6.Cu")
		(net "M_H_CPU1_SB_DQ<16>")
	)
	(arc
		(start 132.97281 -231.39019)
		(mid 132.785612 -231.340047)
		(end 132.598414 -231.39019)
		(width 0.088646)
		(layer "In6.Cu")
		(net "M_H_CPU1_SB_DQ<16>")
	)
	(arc
		(start 136.732264 -231.39019)
		(mid 136.545066 -231.340047)
		(end 136.357868 -231.39019)
		(width 0.088646)
		(layer "In6.Cu")
		(net "M_H_CPU1_SB_DQ<16>")
	)
	(segment
		(start 214.133684 -214.064596)
		(end 214.385652 -214.316564)
		(width 0.20066)
		(layer "F.Cu")
		(net "M_H_CPU1_SB_DQ<15>")
	)
	(segment
		(start 212.618066 -214.741506)
		(end 212.630258 -214.753698)
		(width 0.1016)
		(layer "F.Cu")
		(net "M_H_CPU1_SB_DQ<15>")
	)
	(segment
		(start 124.797312 -231.436418)
		(end 124.797312 -230.900732)
		(width 0.20066)
		(layer "F.Cu")
		(net "M_H_CPU1_SB_DQ<15>")
	)
	(segment
		(start 208.176114 -214.316564)
		(end 209.874358 -214.316564)
		(width 0.20066)
		(layer "F.Cu")
		(net "M_H_CPU1_SB_DQ<15>")
	)
	(segment
		(start 207.071214 -214.316564)
		(end 208.176114 -214.316564)
		(width 0.20066)
		(layer "F.Cu")
		(net "M_H_CPU1_SB_DQ<15>")
	)
	(segment
		(start 124.797312 -230.900732)
		(end 124.797566 -230.900478)
		(width 0.20066)
		(layer "F.Cu")
		(net "M_H_CPU1_SB_DQ<15>")
	)
	(segment
		(start 210.306412 -214.748618)
		(end 210.598258 -214.748618)
		(width 0.20066)
		(layer "F.Cu")
		(net "M_H_CPU1_SB_DQ<15>")
	)
	(segment
		(start 213.515448 -214.549736)
		(end 213.515448 -214.298784)
		(width 0.20066)
		(layer "F.Cu")
		(net "M_H_CPU1_SB_DQ<15>")
	)
	(segment
		(start 210.610196 -214.741506)
		(end 212.618066 -214.741506)
		(width 0.1016)
		(layer "F.Cu")
		(net "M_H_CPU1_SB_DQ<15>")
	)
	(segment
		(start 213.311486 -214.753698)
		(end 213.515448 -214.549736)
		(width 0.20066)
		(layer "F.Cu")
		(net "M_H_CPU1_SB_DQ<15>")
	)
	(segment
		(start 214.385652 -214.316564)
		(end 215.719914 -214.316564)
		(width 0.20066)
		(layer "F.Cu")
		(net "M_H_CPU1_SB_DQ<15>")
	)
	(segment
		(start 212.630258 -214.753698)
		(end 213.311486 -214.753698)
		(width 0.20066)
		(layer "F.Cu")
		(net "M_H_CPU1_SB_DQ<15>")
	)
	(segment
		(start 213.515448 -214.298784)
		(end 213.749636 -214.064596)
		(width 0.20066)
		(layer "F.Cu")
		(net "M_H_CPU1_SB_DQ<15>")
	)
	(segment
		(start 210.598258 -214.748618)
		(end 210.603084 -214.748618)
		(width 0.101854)
		(layer "F.Cu")
		(net "M_H_CPU1_SB_DQ<15>")
	)
	(segment
		(start 213.749636 -214.064596)
		(end 214.133684 -214.064596)
		(width 0.20066)
		(layer "F.Cu")
		(net "M_H_CPU1_SB_DQ<15>")
	)
	(segment
		(start 209.874358 -214.316564)
		(end 210.306412 -214.748618)
		(width 0.20066)
		(layer "F.Cu")
		(net "M_H_CPU1_SB_DQ<15>")
	)
	(segment
		(start 210.603084 -214.748618)
		(end 210.610196 -214.741506)
		(width 0.1016)
		(layer "F.Cu")
		(net "M_H_CPU1_SB_DQ<15>")
	)
	(segment
		(start 138.482578 -229.521512)
		(end 138.424666 -229.521512)
		(width 0.088646)
		(layer "In11.Cu")
		(net "M_H_CPU1_SB_DQ<15>")
	)
	(segment
		(start 131.658868 -230.41102)
		(end 131.648454 -230.404924)
		(width 0.088646)
		(layer "In11.Cu")
		(net "M_H_CPU1_SB_DQ<15>")
	)
	(segment
		(start 137.680954 -230.40594)
		(end 137.672064 -230.41102)
		(width 0.088646)
		(layer "In11.Cu")
		(net "M_H_CPU1_SB_DQ<15>")
	)
	(segment
		(start 202.036426 -211.307426)
		(end 200.178416 -209.919824)
		(width 0.18288)
		(layer "In11.Cu")
		(net "M_H_CPU1_SB_DQ<15>")
	)
	(segment
		(start 160.73247 -208.405222)
		(end 160.657032 -208.618328)
		(width 0.18288)
		(layer "In11.Cu")
		(net "M_H_CPU1_SB_DQ<15>")
	)
	(segment
		(start 202.678538 -212.190838)
		(end 202.341226 -211.853526)
		(width 0.18288)
		(layer "In11.Cu")
		(net "M_H_CPU1_SB_DQ<15>")
	)
	(segment
		(start 205.13802 -213.310216)
		(end 204.018642 -212.190838)
		(width 0.18288)
		(layer "In11.Cu")
		(net "M_H_CPU1_SB_DQ<15>")
	)
	(segment
		(start 139.53109 -228.473)
		(end 138.482578 -229.521512)
		(width 0.088646)
		(layer "In11.Cu")
		(net "M_H_CPU1_SB_DQ<15>")
	)
	(segment
		(start 161.358326 -208.106264)
		(end 160.98393 -207.322928)
		(width 0.18288)
		(layer "In11.Cu")
		(net "M_H_CPU1_SB_DQ<15>")
	)
	(segment
		(start 179.637182 -207.117188)
		(end 178.761136 -206.241142)
		(width 0.18288)
		(layer "In11.Cu")
		(net "M_H_CPU1_SB_DQ<15>")
	)
	(segment
		(start 160.026096 -208.919826)
		(end 157.12059 -208.919826)
		(width 0.18288)
		(layer "In11.Cu")
		(net "M_H_CPU1_SB_DQ<15>")
	)
	(segment
		(start 160.433512 -207.40878)
		(end 160.358074 -207.621886)
		(width 0.18288)
		(layer "In11.Cu")
		(net "M_H_CPU1_SB_DQ<15>")
	)
	(segment
		(start 130.718814 -230.41102)
		(end 130.704082 -230.402384)
		(width 0.088646)
		(layer "In11.Cu")
		(net "M_H_CPU1_SB_DQ<15>")
	)
	(segment
		(start 126.019814 -230.41102)
		(end 126.0094 -230.404924)
		(width 0.088646)
		(layer "In11.Cu")
		(net "M_H_CPU1_SB_DQ<15>")
	)
	(segment
		(start 160.98393 -207.322928)
		(end 160.770824 -207.24749)
		(width 0.18288)
		(layer "In11.Cu")
		(net "M_H_CPU1_SB_DQ<15>")
	)
	(segment
		(start 207.071214 -214.316564)
		(end 205.13802 -213.310216)
		(width 0.18288)
		(layer "In11.Cu")
		(net "M_H_CPU1_SB_DQ<15>")
	)
	(segment
		(start 176.335182 -206.241142)
		(end 175.434498 -207.141826)
		(width 0.18288)
		(layer "In11.Cu")
		(net "M_H_CPU1_SB_DQ<15>")
	)
	(segment
		(start 144.476724 -224.724468)
		(end 141.054328 -228.146864)
		(width 0.18288)
		(layer "In11.Cu")
		(net "M_H_CPU1_SB_DQ<15>")
	)
	(segment
		(start 125.454664 -230.41102)
		(end 125.376432 -230.456232)
		(width 0.088646)
		(layer "In11.Cu")
		(net "M_H_CPU1_SB_DQ<15>")
	)
	(segment
		(start 187.111894 -206.238602)
		(end 186.953906 -206.39659)
		(width 0.18288)
		(layer "In11.Cu")
		(net "M_H_CPU1_SB_DQ<15>")
	)
	(segment
		(start 160.657032 -208.618328)
		(end 160.026096 -208.919826)
		(width 0.18288)
		(layer "In11.Cu")
		(net "M_H_CPU1_SB_DQ<15>")
	)
	(segment
		(start 128.839214 -230.41102)
		(end 128.824482 -230.402384)
		(width 0.088646)
		(layer "In11.Cu")
		(net "M_H_CPU1_SB_DQ<15>")
	)
	(segment
		(start 175.434498 -207.141826)
		(end 174.084742 -207.141826)
		(width 0.18288)
		(layer "In11.Cu")
		(net "M_H_CPU1_SB_DQ<15>")
	)
	(segment
		(start 164.537644 -206.990442)
		(end 164.064696 -206.990442)
		(width 0.18288)
		(layer "In11.Cu")
		(net "M_H_CPU1_SB_DQ<15>")
	)
	(segment
		(start 157.12059 -208.919826)
		(end 151.396446 -214.64397)
		(width 0.18288)
		(layer "In11.Cu")
		(net "M_H_CPU1_SB_DQ<15>")
	)
	(segment
		(start 164.064696 -206.990442)
		(end 161.571432 -208.181702)
		(width 0.18288)
		(layer "In11.Cu")
		(net "M_H_CPU1_SB_DQ<15>")
	)
	(segment
		(start 172.420534 -206.243936)
		(end 171.981368 -206.683102)
		(width 0.18288)
		(layer "In11.Cu")
		(net "M_H_CPU1_SB_DQ<15>")
	)
	(segment
		(start 202.341226 -211.612226)
		(end 202.036426 -211.307426)
		(width 0.18288)
		(layer "In11.Cu")
		(net "M_H_CPU1_SB_DQ<15>")
	)
	(segment
		(start 151.396446 -214.64397)
		(end 151.396446 -216.775538)
		(width 0.18288)
		(layer "In11.Cu")
		(net "M_H_CPU1_SB_DQ<15>")
	)
	(segment
		(start 197.99808 -207.739488)
		(end 195.226686 -207.739488)
		(width 0.18288)
		(layer "In11.Cu")
		(net "M_H_CPU1_SB_DQ<15>")
	)
	(segment
		(start 193.7258 -206.238602)
		(end 187.111894 -206.238602)
		(width 0.18288)
		(layer "In11.Cu")
		(net "M_H_CPU1_SB_DQ<15>")
	)
	(segment
		(start 132.043678 -230.404924)
		(end 132.033264 -230.41102)
		(width 0.088646)
		(layer "In11.Cu")
		(net "M_H_CPU1_SB_DQ<15>")
	)
	(segment
		(start 171.274994 -206.97571)
		(end 168.44391 -206.97571)
		(width 0.18288)
		(layer "In11.Cu")
		(net "M_H_CPU1_SB_DQ<15>")
	)
	(segment
		(start 133.538468 -230.41102)
		(end 133.528054 -230.404924)
		(width 0.088646)
		(layer "In11.Cu")
		(net "M_H_CPU1_SB_DQ<15>")
	)
	(segment
		(start 160.358074 -207.621886)
		(end 160.73247 -208.405222)
		(width 0.18288)
		(layer "In11.Cu")
		(net "M_H_CPU1_SB_DQ<15>")
	)
	(segment
		(start 141.054328 -228.146864)
		(end 140.163042 -228.146864)
		(width 0.18288)
		(layer "In11.Cu")
		(net "M_H_CPU1_SB_DQ<15>")
	)
	(segment
		(start 200.178416 -209.919824)
		(end 197.99808 -207.739488)
		(width 0.18288)
		(layer "In11.Cu")
		(net "M_H_CPU1_SB_DQ<15>")
	)
	(segment
		(start 178.761136 -206.241142)
		(end 176.335182 -206.241142)
		(width 0.18288)
		(layer "In11.Cu")
		(net "M_H_CPU1_SB_DQ<15>")
	)
	(segment
		(start 161.571432 -208.181702)
		(end 161.358326 -208.106264)
		(width 0.18288)
		(layer "In11.Cu")
		(net "M_H_CPU1_SB_DQ<15>")
	)
	(segment
		(start 139.53109 -228.379782)
		(end 139.53109 -228.473)
		(width 0.088646)
		(layer "In11.Cu")
		(net "M_H_CPU1_SB_DQ<15>")
	)
	(segment
		(start 144.476724 -223.69526)
		(end 144.476724 -224.724468)
		(width 0.18288)
		(layer "In11.Cu")
		(net "M_H_CPU1_SB_DQ<15>")
	)
	(segment
		(start 140.163042 -228.146864)
		(end 139.764008 -228.146864)
		(width 0.088646)
		(layer "In11.Cu")
		(net "M_H_CPU1_SB_DQ<15>")
	)
	(segment
		(start 160.770824 -207.24749)
		(end 160.433512 -207.40878)
		(width 0.18288)
		(layer "In11.Cu")
		(net "M_H_CPU1_SB_DQ<15>")
	)
	(segment
		(start 195.226686 -207.739488)
		(end 193.7258 -206.238602)
		(width 0.18288)
		(layer "In11.Cu")
		(net "M_H_CPU1_SB_DQ<15>")
	)
	(segment
		(start 151.396446 -216.775538)
		(end 144.476724 -223.69526)
		(width 0.18288)
		(layer "In11.Cu")
		(net "M_H_CPU1_SB_DQ<15>")
	)
	(segment
		(start 171.981368 -206.683102)
		(end 171.274994 -206.97571)
		(width 0.18288)
		(layer "In11.Cu")
		(net "M_H_CPU1_SB_DQ<15>")
	)
	(segment
		(start 182.78221 -207.117188)
		(end 179.637182 -207.117188)
		(width 0.18288)
		(layer "In11.Cu")
		(net "M_H_CPU1_SB_DQ<15>")
	)
	(segment
		(start 173.186852 -206.243936)
		(end 172.420534 -206.243936)
		(width 0.18288)
		(layer "In11.Cu")
		(net "M_H_CPU1_SB_DQ<15>")
	)
	(segment
		(start 127.899414 -230.41102)
		(end 127.884682 -230.402384)
		(width 0.088646)
		(layer "In11.Cu")
		(net "M_H_CPU1_SB_DQ<15>")
	)
	(segment
		(start 168.44391 -206.97571)
		(end 168.127426 -207.292194)
		(width 0.18288)
		(layer "In11.Cu")
		(net "M_H_CPU1_SB_DQ<15>")
	)
	(segment
		(start 165.58768 -207.292194)
		(end 164.537644 -206.990442)
		(width 0.18288)
		(layer "In11.Cu")
		(net "M_H_CPU1_SB_DQ<15>")
	)
	(segment
		(start 186.953906 -206.39659)
		(end 183.502808 -206.39659)
		(width 0.18288)
		(layer "In11.Cu")
		(net "M_H_CPU1_SB_DQ<15>")
	)
	(segment
		(start 168.127426 -207.292194)
		(end 165.58768 -207.292194)
		(width 0.18288)
		(layer "In11.Cu")
		(net "M_H_CPU1_SB_DQ<15>")
	)
	(segment
		(start 174.084742 -207.141826)
		(end 173.186852 -206.243936)
		(width 0.18288)
		(layer "In11.Cu")
		(net "M_H_CPU1_SB_DQ<15>")
	)
	(segment
		(start 183.502808 -206.39659)
		(end 182.78221 -207.117188)
		(width 0.18288)
		(layer "In11.Cu")
		(net "M_H_CPU1_SB_DQ<15>")
	)
	(segment
		(start 139.764008 -228.146864)
		(end 139.53109 -228.379782)
		(width 0.088646)
		(layer "In11.Cu")
		(net "M_H_CPU1_SB_DQ<15>")
	)
	(segment
		(start 129.779014 -230.41102)
		(end 129.764282 -230.402384)
		(width 0.088646)
		(layer "In11.Cu")
		(net "M_H_CPU1_SB_DQ<15>")
	)
	(segment
		(start 137.859516 -230.076756)
		(end 137.859516 -230.086662)
		(width 0.088646)
		(layer "In11.Cu")
		(net "M_H_CPU1_SB_DQ<15>")
	)
	(segment
		(start 204.018642 -212.190838)
		(end 202.678538 -212.190838)
		(width 0.18288)
		(layer "In11.Cu")
		(net "M_H_CPU1_SB_DQ<15>")
	)
	(segment
		(start 202.341226 -211.853526)
		(end 202.341226 -211.612226)
		(width 0.18288)
		(layer "In11.Cu")
		(net "M_H_CPU1_SB_DQ<15>")
	)
	(segment
		(start 126.959614 -230.41102)
		(end 126.944882 -230.402384)
		(width 0.088646)
		(layer "In11.Cu")
		(net "M_H_CPU1_SB_DQ<15>")
	)
	(arc
		(start 126.0094 -230.404924)
		(mid 125.731222 -230.335201)
		(end 125.454664 -230.41102)
		(width 0.088646)
		(layer "In11.Cu")
		(net "M_H_CPU1_SB_DQ<15>")
	)
	(arc
		(start 136.732264 -230.41102)
		(mid 136.545066 -230.461163)
		(end 136.357868 -230.41102)
		(width 0.088646)
		(layer "In11.Cu")
		(net "M_H_CPU1_SB_DQ<15>")
	)
	(arc
		(start 127.884682 -230.402384)
		(mid 127.608207 -230.335064)
		(end 127.33401 -230.41102)
		(width 0.088646)
		(layer "In11.Cu")
		(net "M_H_CPU1_SB_DQ<15>")
	)
	(arc
		(start 128.824482 -230.402384)
		(mid 128.548007 -230.335064)
		(end 128.27381 -230.41102)
		(width 0.088646)
		(layer "In11.Cu")
		(net "M_H_CPU1_SB_DQ<15>")
	)
	(arc
		(start 131.09321 -230.41102)
		(mid 130.906012 -230.461163)
		(end 130.718814 -230.41102)
		(width 0.088646)
		(layer "In11.Cu")
		(net "M_H_CPU1_SB_DQ<15>")
	)
	(arc
		(start 137.297668 -230.41102)
		(mid 137.014966 -230.335244)
		(end 136.732264 -230.41102)
		(width 0.088646)
		(layer "In11.Cu")
		(net "M_H_CPU1_SB_DQ<15>")
	)
	(arc
		(start 126.944882 -230.402384)
		(mid 126.668407 -230.335064)
		(end 126.39421 -230.41102)
		(width 0.088646)
		(layer "In11.Cu")
		(net "M_H_CPU1_SB_DQ<15>")
	)
	(arc
		(start 134.852664 -230.41102)
		(mid 134.665466 -230.461163)
		(end 134.478268 -230.41102)
		(width 0.088646)
		(layer "In11.Cu")
		(net "M_H_CPU1_SB_DQ<15>")
	)
	(arc
		(start 136.357868 -230.41102)
		(mid 136.075166 -230.335244)
		(end 135.792464 -230.41102)
		(width 0.088646)
		(layer "In11.Cu")
		(net "M_H_CPU1_SB_DQ<15>")
	)
	(arc
		(start 133.528054 -230.404924)
		(mid 133.249622 -230.335078)
		(end 132.97281 -230.41102)
		(width 0.088646)
		(layer "In11.Cu")
		(net "M_H_CPU1_SB_DQ<15>")
	)
	(arc
		(start 127.33401 -230.41102)
		(mid 127.146812 -230.461163)
		(end 126.959614 -230.41102)
		(width 0.088646)
		(layer "In11.Cu")
		(net "M_H_CPU1_SB_DQ<15>")
	)
	(arc
		(start 135.418068 -230.41102)
		(mid 135.135366 -230.335244)
		(end 134.852664 -230.41102)
		(width 0.088646)
		(layer "In11.Cu")
		(net "M_H_CPU1_SB_DQ<15>")
	)
	(arc
		(start 137.672064 -230.41102)
		(mid 137.484866 -230.461163)
		(end 137.297668 -230.41102)
		(width 0.088646)
		(layer "In11.Cu")
		(net "M_H_CPU1_SB_DQ<15>")
	)
	(arc
		(start 132.97281 -230.41102)
		(mid 132.785612 -230.461163)
		(end 132.598414 -230.41102)
		(width 0.088646)
		(layer "In11.Cu")
		(net "M_H_CPU1_SB_DQ<15>")
	)
	(arc
		(start 128.27381 -230.41102)
		(mid 128.086612 -230.461163)
		(end 127.899414 -230.41102)
		(width 0.088646)
		(layer "In11.Cu")
		(net "M_H_CPU1_SB_DQ<15>")
	)
	(arc
		(start 137.859516 -230.086662)
		(mid 137.811837 -230.269562)
		(end 137.680954 -230.40594)
		(width 0.088646)
		(layer "In11.Cu")
		(net "M_H_CPU1_SB_DQ<15>")
	)
	(arc
		(start 125.376432 -230.456232)
		(mid 125.072444 -230.65939)
		(end 124.797566 -230.900478)
		(width 0.088646)
		(layer "In11.Cu")
		(net "M_H_CPU1_SB_DQ<15>")
	)
	(arc
		(start 138.424666 -229.521512)
		(mid 138.028562 -229.683554)
		(end 137.859516 -230.076756)
		(width 0.088646)
		(layer "In11.Cu")
		(net "M_H_CPU1_SB_DQ<15>")
	)
	(arc
		(start 126.39421 -230.41102)
		(mid 126.207012 -230.461163)
		(end 126.019814 -230.41102)
		(width 0.088646)
		(layer "In11.Cu")
		(net "M_H_CPU1_SB_DQ<15>")
	)
	(arc
		(start 135.792464 -230.41102)
		(mid 135.605266 -230.461163)
		(end 135.418068 -230.41102)
		(width 0.088646)
		(layer "In11.Cu")
		(net "M_H_CPU1_SB_DQ<15>")
	)
	(arc
		(start 131.648454 -230.404924)
		(mid 131.370022 -230.335078)
		(end 131.09321 -230.41102)
		(width 0.088646)
		(layer "In11.Cu")
		(net "M_H_CPU1_SB_DQ<15>")
	)
	(arc
		(start 132.033264 -230.41102)
		(mid 131.846066 -230.461163)
		(end 131.658868 -230.41102)
		(width 0.088646)
		(layer "In11.Cu")
		(net "M_H_CPU1_SB_DQ<15>")
	)
	(arc
		(start 133.912864 -230.41102)
		(mid 133.725666 -230.461163)
		(end 133.538468 -230.41102)
		(width 0.088646)
		(layer "In11.Cu")
		(net "M_H_CPU1_SB_DQ<15>")
	)
	(arc
		(start 130.15341 -230.41102)
		(mid 129.966212 -230.461163)
		(end 129.779014 -230.41102)
		(width 0.088646)
		(layer "In11.Cu")
		(net "M_H_CPU1_SB_DQ<15>")
	)
	(arc
		(start 129.21361 -230.41102)
		(mid 129.026412 -230.461163)
		(end 128.839214 -230.41102)
		(width 0.088646)
		(layer "In11.Cu")
		(net "M_H_CPU1_SB_DQ<15>")
	)
	(arc
		(start 129.764282 -230.402384)
		(mid 129.487807 -230.335064)
		(end 129.21361 -230.41102)
		(width 0.088646)
		(layer "In11.Cu")
		(net "M_H_CPU1_SB_DQ<15>")
	)
	(arc
		(start 130.704082 -230.402384)
		(mid 130.427607 -230.335064)
		(end 130.15341 -230.41102)
		(width 0.088646)
		(layer "In11.Cu")
		(net "M_H_CPU1_SB_DQ<15>")
	)
	(arc
		(start 134.478268 -230.41102)
		(mid 134.195566 -230.335244)
		(end 133.912864 -230.41102)
		(width 0.088646)
		(layer "In11.Cu")
		(net "M_H_CPU1_SB_DQ<15>")
	)
	(arc
		(start 132.598414 -230.41102)
		(mid 132.321855 -230.335277)
		(end 132.043678 -230.404924)
		(width 0.088646)
		(layer "In11.Cu")
		(net "M_H_CPU1_SB_DQ<15>")
	)
	(segment
		(start 214.385652 -216.016586)
		(end 215.719914 -216.016586)
		(width 0.20066)
		(layer "F.Cu")
		(net "M_H_CPU1_SB_DQ<14>")
	)
	(segment
		(start 213.515448 -216.249758)
		(end 213.515448 -215.998806)
		(width 0.20066)
		(layer "F.Cu")
		(net "M_H_CPU1_SB_DQ<14>")
	)
	(segment
		(start 125.267212 -232.250234)
		(end 125.267212 -231.714548)
		(width 0.20066)
		(layer "F.Cu")
		(net "M_H_CPU1_SB_DQ<14>")
	)
	(segment
		(start 213.515448 -215.998806)
		(end 213.749636 -215.764618)
		(width 0.20066)
		(layer "F.Cu")
		(net "M_H_CPU1_SB_DQ<14>")
	)
	(segment
		(start 207.071214 -216.016586)
		(end 208.176114 -216.016586)
		(width 0.20066)
		(layer "F.Cu")
		(net "M_H_CPU1_SB_DQ<14>")
	)
	(segment
		(start 209.874358 -216.016586)
		(end 210.306412 -216.44864)
		(width 0.20066)
		(layer "F.Cu")
		(net "M_H_CPU1_SB_DQ<14>")
	)
	(segment
		(start 213.311486 -216.45372)
		(end 213.515448 -216.249758)
		(width 0.20066)
		(layer "F.Cu")
		(net "M_H_CPU1_SB_DQ<14>")
	)
	(segment
		(start 208.176114 -216.016586)
		(end 209.874358 -216.016586)
		(width 0.20066)
		(layer "F.Cu")
		(net "M_H_CPU1_SB_DQ<14>")
	)
	(segment
		(start 213.749636 -215.764618)
		(end 214.133684 -215.764618)
		(width 0.20066)
		(layer "F.Cu")
		(net "M_H_CPU1_SB_DQ<14>")
	)
	(segment
		(start 210.306412 -216.44864)
		(end 210.598258 -216.44864)
		(width 0.20066)
		(layer "F.Cu")
		(net "M_H_CPU1_SB_DQ<14>")
	)
	(segment
		(start 210.598258 -216.44864)
		(end 210.603084 -216.44864)
		(width 0.101854)
		(layer "F.Cu")
		(net "M_H_CPU1_SB_DQ<14>")
	)
	(segment
		(start 214.133684 -215.764618)
		(end 214.385652 -216.016586)
		(width 0.20066)
		(layer "F.Cu")
		(net "M_H_CPU1_SB_DQ<14>")
	)
	(segment
		(start 212.618066 -216.441528)
		(end 212.630258 -216.45372)
		(width 0.1016)
		(layer "F.Cu")
		(net "M_H_CPU1_SB_DQ<14>")
	)
	(segment
		(start 125.267466 -232.250488)
		(end 125.267212 -232.250234)
		(width 0.20066)
		(layer "F.Cu")
		(net "M_H_CPU1_SB_DQ<14>")
	)
	(segment
		(start 210.610196 -216.441528)
		(end 212.618066 -216.441528)
		(width 0.1016)
		(layer "F.Cu")
		(net "M_H_CPU1_SB_DQ<14>")
	)
	(segment
		(start 210.603084 -216.44864)
		(end 210.610196 -216.441528)
		(width 0.1016)
		(layer "F.Cu")
		(net "M_H_CPU1_SB_DQ<14>")
	)
	(segment
		(start 212.630258 -216.45372)
		(end 213.311486 -216.45372)
		(width 0.20066)
		(layer "F.Cu")
		(net "M_H_CPU1_SB_DQ<14>")
	)
	(segment
		(start 178.330352 -208.814162)
		(end 177.500026 -209.644488)
		(width 0.18288)
		(layer "In11.Cu")
		(net "M_H_CPU1_SB_DQ<14>")
	)
	(segment
		(start 145.518886 -225.152458)
		(end 141.492986 -229.178358)
		(width 0.18288)
		(layer "In11.Cu")
		(net "M_H_CPU1_SB_DQ<14>")
	)
	(segment
		(start 145.518886 -224.198942)
		(end 145.518886 -225.152458)
		(width 0.18288)
		(layer "In11.Cu")
		(net "M_H_CPU1_SB_DQ<14>")
	)
	(segment
		(start 172.749718 -208.791556)
		(end 168.327832 -208.791556)
		(width 0.18288)
		(layer "In11.Cu")
		(net "M_H_CPU1_SB_DQ<14>")
	)
	(segment
		(start 202.541632 -215.591136)
		(end 202.368912 -215.763856)
		(width 0.18288)
		(layer "In11.Cu")
		(net "M_H_CPU1_SB_DQ<14>")
	)
	(segment
		(start 161.330386 -210.545426)
		(end 160.425892 -210.367626)
		(width 0.18288)
		(layer "In11.Cu")
		(net "M_H_CPU1_SB_DQ<14>")
	)
	(segment
		(start 125.939296 -231.2162)
		(end 125.827282 -231.281986)
		(width 0.088646)
		(layer "In11.Cu")
		(net "M_H_CPU1_SB_DQ<14>")
	)
	(segment
		(start 206.33055 -216.75725)
		(end 204.68844 -216.75725)
		(width 0.18288)
		(layer "In11.Cu")
		(net "M_H_CPU1_SB_DQ<14>")
	)
	(segment
		(start 140.163296 -229.178358)
		(end 139.395708 -229.178358)
		(width 0.088646)
		(layer "In11.Cu")
		(net "M_H_CPU1_SB_DQ<14>")
	)
	(segment
		(start 175.316134 -209.644488)
		(end 174.464218 -208.792572)
		(width 0.18288)
		(layer "In11.Cu")
		(net "M_H_CPU1_SB_DQ<14>")
	)
	(segment
		(start 168.096184 -209.023204)
		(end 165.507924 -209.023204)
		(width 0.18288)
		(layer "In11.Cu")
		(net "M_H_CPU1_SB_DQ<14>")
	)
	(segment
		(start 157.246574 -210.367626)
		(end 152.797002 -214.817198)
		(width 0.18288)
		(layer "In11.Cu")
		(net "M_H_CPU1_SB_DQ<14>")
	)
	(segment
		(start 197.518782 -209.405474)
		(end 194.930522 -209.405474)
		(width 0.18288)
		(layer "In11.Cu")
		(net "M_H_CPU1_SB_DQ<14>")
	)
	(segment
		(start 152.797002 -214.817198)
		(end 152.797002 -216.920826)
		(width 0.18288)
		(layer "In11.Cu")
		(net "M_H_CPU1_SB_DQ<14>")
	)
	(segment
		(start 138.329416 -230.890572)
		(end 138.329416 -230.900478)
		(width 0.088646)
		(layer "In11.Cu")
		(net "M_H_CPU1_SB_DQ<14>")
	)
	(segment
		(start 139.395708 -229.178358)
		(end 138.762994 -229.811072)
		(width 0.088646)
		(layer "In11.Cu")
		(net "M_H_CPU1_SB_DQ<14>")
	)
	(segment
		(start 131.573778 -231.21874)
		(end 131.563364 -231.224836)
		(width 0.088646)
		(layer "In11.Cu")
		(net "M_H_CPU1_SB_DQ<14>")
	)
	(segment
		(start 168.327832 -208.791556)
		(end 168.096184 -209.023204)
		(width 0.18288)
		(layer "In11.Cu")
		(net "M_H_CPU1_SB_DQ<14>")
	)
	(segment
		(start 127.818896 -231.2162)
		(end 127.804164 -231.224836)
		(width 0.088646)
		(layer "In11.Cu")
		(net "M_H_CPU1_SB_DQ<14>")
	)
	(segment
		(start 187.621672 -207.939132)
		(end 186.924442 -208.636362)
		(width 0.18288)
		(layer "In11.Cu")
		(net "M_H_CPU1_SB_DQ<14>")
	)
	(segment
		(start 201.172826 -212.729826)
		(end 199.572626 -211.129626)
		(width 0.18288)
		(layer "In11.Cu")
		(net "M_H_CPU1_SB_DQ<14>")
	)
	(segment
		(start 177.500026 -209.644488)
		(end 175.316134 -209.644488)
		(width 0.18288)
		(layer "In11.Cu")
		(net "M_H_CPU1_SB_DQ<14>")
	)
	(segment
		(start 203.522326 -215.591136)
		(end 202.541632 -215.591136)
		(width 0.18288)
		(layer "In11.Cu")
		(net "M_H_CPU1_SB_DQ<14>")
	)
	(segment
		(start 192.904872 -207.939132)
		(end 187.621672 -207.939132)
		(width 0.18288)
		(layer "In11.Cu")
		(net "M_H_CPU1_SB_DQ<14>")
	)
	(segment
		(start 162.3568 -210.427062)
		(end 162.211512 -210.545426)
		(width 0.18288)
		(layer "In11.Cu")
		(net "M_H_CPU1_SB_DQ<14>")
	)
	(segment
		(start 204.68844 -216.75725)
		(end 203.522326 -215.591136)
		(width 0.18288)
		(layer "In11.Cu")
		(net "M_H_CPU1_SB_DQ<14>")
	)
	(segment
		(start 174.464218 -208.792572)
		(end 172.750734 -208.792572)
		(width 0.18288)
		(layer "In11.Cu")
		(net "M_H_CPU1_SB_DQ<14>")
	)
	(segment
		(start 138.150854 -231.219756)
		(end 138.141964 -231.224836)
		(width 0.088646)
		(layer "In11.Cu")
		(net "M_H_CPU1_SB_DQ<14>")
	)
	(segment
		(start 199.242934 -211.129626)
		(end 197.518782 -209.405474)
		(width 0.18288)
		(layer "In11.Cu")
		(net "M_H_CPU1_SB_DQ<14>")
	)
	(segment
		(start 165.507924 -209.023204)
		(end 164.571426 -209.402426)
		(width 0.18288)
		(layer "In11.Cu")
		(net "M_H_CPU1_SB_DQ<14>")
	)
	(segment
		(start 138.762994 -229.811072)
		(end 138.762994 -230.278178)
		(width 0.088646)
		(layer "In11.Cu")
		(net "M_H_CPU1_SB_DQ<14>")
	)
	(segment
		(start 199.572626 -211.129626)
		(end 199.242934 -211.129626)
		(width 0.18288)
		(layer "In11.Cu")
		(net "M_H_CPU1_SB_DQ<14>")
	)
	(segment
		(start 202.368912 -215.763856)
		(end 201.559668 -215.763856)
		(width 0.18288)
		(layer "In11.Cu")
		(net "M_H_CPU1_SB_DQ<14>")
	)
	(segment
		(start 207.071214 -216.016586)
		(end 206.33055 -216.75725)
		(width 0.18288)
		(layer "In11.Cu")
		(net "M_H_CPU1_SB_DQ<14>")
	)
	(segment
		(start 125.795786 -231.300528)
		(end 125.676914 -231.370378)
		(width 0.088646)
		(layer "In11.Cu")
		(net "M_H_CPU1_SB_DQ<14>")
	)
	(segment
		(start 141.492986 -229.178358)
		(end 140.163296 -229.178358)
		(width 0.18288)
		(layer "In11.Cu")
		(net "M_H_CPU1_SB_DQ<14>")
	)
	(segment
		(start 186.924442 -208.636362)
		(end 183.138826 -208.636362)
		(width 0.18288)
		(layer "In11.Cu")
		(net "M_H_CPU1_SB_DQ<14>")
	)
	(segment
		(start 164.571426 -209.402426)
		(end 163.613846 -209.402426)
		(width 0.18288)
		(layer "In11.Cu")
		(net "M_H_CPU1_SB_DQ<14>")
	)
	(segment
		(start 201.559668 -215.763856)
		(end 201.172826 -215.377014)
		(width 0.18288)
		(layer "In11.Cu")
		(net "M_H_CPU1_SB_DQ<14>")
	)
	(segment
		(start 163.613846 -209.402426)
		(end 162.3568 -210.427062)
		(width 0.18288)
		(layer "In11.Cu")
		(net "M_H_CPU1_SB_DQ<14>")
	)
	(segment
		(start 183.138826 -208.636362)
		(end 182.961026 -208.814162)
		(width 0.18288)
		(layer "In11.Cu")
		(net "M_H_CPU1_SB_DQ<14>")
	)
	(segment
		(start 201.172826 -215.377014)
		(end 201.172826 -212.729826)
		(width 0.18288)
		(layer "In11.Cu")
		(net "M_H_CPU1_SB_DQ<14>")
	)
	(segment
		(start 162.211512 -210.545426)
		(end 161.330386 -210.545426)
		(width 0.18288)
		(layer "In11.Cu")
		(net "M_H_CPU1_SB_DQ<14>")
	)
	(segment
		(start 194.930522 -209.405474)
		(end 194.598544 -209.073496)
		(width 0.18288)
		(layer "In11.Cu")
		(net "M_H_CPU1_SB_DQ<14>")
	)
	(segment
		(start 132.513324 -231.21874)
		(end 132.50291 -231.224836)
		(width 0.088646)
		(layer "In11.Cu")
		(net "M_H_CPU1_SB_DQ<14>")
	)
	(segment
		(start 194.039236 -209.073496)
		(end 192.904872 -207.939132)
		(width 0.18288)
		(layer "In11.Cu")
		(net "M_H_CPU1_SB_DQ<14>")
	)
	(segment
		(start 152.797002 -216.920826)
		(end 145.518886 -224.198942)
		(width 0.18288)
		(layer "In11.Cu")
		(net "M_H_CPU1_SB_DQ<14>")
	)
	(segment
		(start 129.698496 -231.2162)
		(end 129.683764 -231.224836)
		(width 0.088646)
		(layer "In11.Cu")
		(net "M_H_CPU1_SB_DQ<14>")
	)
	(segment
		(start 126.879096 -231.2162)
		(end 126.864364 -231.224836)
		(width 0.088646)
		(layer "In11.Cu")
		(net "M_H_CPU1_SB_DQ<14>")
	)
	(segment
		(start 172.750734 -208.792572)
		(end 172.749718 -208.791556)
		(width 0.18288)
		(layer "In11.Cu")
		(net "M_H_CPU1_SB_DQ<14>")
	)
	(segment
		(start 160.425892 -210.367626)
		(end 157.246574 -210.367626)
		(width 0.18288)
		(layer "In11.Cu")
		(net "M_H_CPU1_SB_DQ<14>")
	)
	(segment
		(start 182.961026 -208.814162)
		(end 178.330352 -208.814162)
		(width 0.18288)
		(layer "In11.Cu")
		(net "M_H_CPU1_SB_DQ<14>")
	)
	(segment
		(start 130.638296 -231.2162)
		(end 130.623564 -231.224836)
		(width 0.088646)
		(layer "In11.Cu")
		(net "M_H_CPU1_SB_DQ<14>")
	)
	(segment
		(start 194.598544 -209.073496)
		(end 194.039236 -209.073496)
		(width 0.18288)
		(layer "In11.Cu")
		(net "M_H_CPU1_SB_DQ<14>")
	)
	(arc
		(start 135.887968 -231.224836)
		(mid 135.605266 -231.149094)
		(end 135.322564 -231.224836)
		(width 0.088646)
		(layer "In11.Cu")
		(net "M_H_CPU1_SB_DQ<14>")
	)
	(arc
		(start 138.762994 -230.278178)
		(mid 138.672627 -230.360509)
		(end 138.575034 -230.434134)
		(width 0.088646)
		(layer "In11.Cu")
		(net "M_H_CPU1_SB_DQ<14>")
	)
	(arc
		(start 136.827768 -231.224836)
		(mid 136.545066 -231.149094)
		(end 136.262364 -231.224836)
		(width 0.088646)
		(layer "In11.Cu")
		(net "M_H_CPU1_SB_DQ<14>")
	)
	(arc
		(start 137.202164 -231.224836)
		(mid 137.014966 -231.274979)
		(end 136.827768 -231.224836)
		(width 0.088646)
		(layer "In11.Cu")
		(net "M_H_CPU1_SB_DQ<14>")
	)
	(arc
		(start 138.141964 -231.224836)
		(mid 137.954766 -231.274979)
		(end 137.767568 -231.224836)
		(width 0.088646)
		(layer "In11.Cu")
		(net "M_H_CPU1_SB_DQ<14>")
	)
	(arc
		(start 132.128514 -231.224836)
		(mid 131.851955 -231.149127)
		(end 131.573778 -231.21874)
		(width 0.088646)
		(layer "In11.Cu")
		(net "M_H_CPU1_SB_DQ<14>")
	)
	(arc
		(start 137.767568 -231.224836)
		(mid 137.484866 -231.149094)
		(end 137.202164 -231.224836)
		(width 0.088646)
		(layer "In11.Cu")
		(net "M_H_CPU1_SB_DQ<14>")
	)
	(arc
		(start 130.623564 -231.224836)
		(mid 130.436366 -231.274979)
		(end 130.249168 -231.224836)
		(width 0.088646)
		(layer "In11.Cu")
		(net "M_H_CPU1_SB_DQ<14>")
	)
	(arc
		(start 131.188968 -231.224836)
		(mid 130.914739 -231.148911)
		(end 130.638296 -231.2162)
		(width 0.088646)
		(layer "In11.Cu")
		(net "M_H_CPU1_SB_DQ<14>")
	)
	(arc
		(start 129.309368 -231.224836)
		(mid 129.026666 -231.149094)
		(end 128.743964 -231.224836)
		(width 0.088646)
		(layer "In11.Cu")
		(net "M_H_CPU1_SB_DQ<14>")
	)
	(arc
		(start 136.262364 -231.224836)
		(mid 136.075166 -231.274979)
		(end 135.887968 -231.224836)
		(width 0.088646)
		(layer "In11.Cu")
		(net "M_H_CPU1_SB_DQ<14>")
	)
	(arc
		(start 135.322564 -231.224836)
		(mid 135.135366 -231.274979)
		(end 134.948168 -231.224836)
		(width 0.088646)
		(layer "In11.Cu")
		(net "M_H_CPU1_SB_DQ<14>")
	)
	(arc
		(start 133.068568 -231.224836)
		(mid 132.791755 -231.149)
		(end 132.513324 -231.21874)
		(width 0.088646)
		(layer "In11.Cu")
		(net "M_H_CPU1_SB_DQ<14>")
	)
	(arc
		(start 125.827282 -231.281986)
		(mid 125.811504 -231.291206)
		(end 125.795786 -231.300528)
		(width 0.088646)
		(layer "In11.Cu")
		(net "M_H_CPU1_SB_DQ<14>")
	)
	(arc
		(start 125.561598 -231.45877)
		(mid 125.409916 -231.581493)
		(end 125.267212 -231.714548)
		(width 0.088646)
		(layer "In11.Cu")
		(net "M_H_CPU1_SB_DQ<14>")
	)
	(arc
		(start 134.948168 -231.224836)
		(mid 134.665466 -231.149094)
		(end 134.382764 -231.224836)
		(width 0.088646)
		(layer "In11.Cu")
		(net "M_H_CPU1_SB_DQ<14>")
	)
	(arc
		(start 128.369568 -231.224836)
		(mid 128.095339 -231.148911)
		(end 127.818896 -231.2162)
		(width 0.088646)
		(layer "In11.Cu")
		(net "M_H_CPU1_SB_DQ<14>")
	)
	(arc
		(start 129.683764 -231.224836)
		(mid 129.496566 -231.274979)
		(end 129.309368 -231.224836)
		(width 0.088646)
		(layer "In11.Cu")
		(net "M_H_CPU1_SB_DQ<14>")
	)
	(arc
		(start 134.382764 -231.224836)
		(mid 134.195566 -231.274979)
		(end 134.008368 -231.224836)
		(width 0.088646)
		(layer "In11.Cu")
		(net "M_H_CPU1_SB_DQ<14>")
	)
	(arc
		(start 132.50291 -231.224836)
		(mid 132.315712 -231.274979)
		(end 132.128514 -231.224836)
		(width 0.088646)
		(layer "In11.Cu")
		(net "M_H_CPU1_SB_DQ<14>")
	)
	(arc
		(start 127.804164 -231.224836)
		(mid 127.616966 -231.274979)
		(end 127.429768 -231.224836)
		(width 0.088646)
		(layer "In11.Cu")
		(net "M_H_CPU1_SB_DQ<14>")
	)
	(arc
		(start 126.864364 -231.224836)
		(mid 126.677166 -231.274979)
		(end 126.489968 -231.224836)
		(width 0.088646)
		(layer "In11.Cu")
		(net "M_H_CPU1_SB_DQ<14>")
	)
	(arc
		(start 128.743964 -231.224836)
		(mid 128.556766 -231.274979)
		(end 128.369568 -231.224836)
		(width 0.088646)
		(layer "In11.Cu")
		(net "M_H_CPU1_SB_DQ<14>")
	)
	(arc
		(start 134.008368 -231.224836)
		(mid 133.725666 -231.149094)
		(end 133.442964 -231.224836)
		(width 0.088646)
		(layer "In11.Cu")
		(net "M_H_CPU1_SB_DQ<14>")
	)
	(arc
		(start 125.676914 -231.370378)
		(mid 125.635332 -231.397701)
		(end 125.596904 -231.429306)
		(width 0.088646)
		(layer "In11.Cu")
		(net "M_H_CPU1_SB_DQ<14>")
	)
	(arc
		(start 138.329416 -230.900478)
		(mid 138.281737 -231.083378)
		(end 138.150854 -231.219756)
		(width 0.088646)
		(layer "In11.Cu")
		(net "M_H_CPU1_SB_DQ<14>")
	)
	(arc
		(start 127.429768 -231.224836)
		(mid 127.155539 -231.148911)
		(end 126.879096 -231.2162)
		(width 0.088646)
		(layer "In11.Cu")
		(net "M_H_CPU1_SB_DQ<14>")
	)
	(arc
		(start 138.575034 -230.434134)
		(mid 138.396789 -230.632532)
		(end 138.329416 -230.890572)
		(width 0.088646)
		(layer "In11.Cu")
		(net "M_H_CPU1_SB_DQ<14>")
	)
	(arc
		(start 133.442964 -231.224836)
		(mid 133.255766 -231.274979)
		(end 133.068568 -231.224836)
		(width 0.088646)
		(layer "In11.Cu")
		(net "M_H_CPU1_SB_DQ<14>")
	)
	(arc
		(start 126.489968 -231.224836)
		(mid 126.215739 -231.148911)
		(end 125.939296 -231.2162)
		(width 0.088646)
		(layer "In11.Cu")
		(net "M_H_CPU1_SB_DQ<14>")
	)
	(arc
		(start 125.596904 -231.429306)
		(mid 125.57962 -231.444481)
		(end 125.561598 -231.45877)
		(width 0.088646)
		(layer "In11.Cu")
		(net "M_H_CPU1_SB_DQ<14>")
	)
	(arc
		(start 130.249168 -231.224836)
		(mid 129.974939 -231.148911)
		(end 129.698496 -231.2162)
		(width 0.088646)
		(layer "In11.Cu")
		(net "M_H_CPU1_SB_DQ<14>")
	)
	(arc
		(start 131.563364 -231.224836)
		(mid 131.376166 -231.274979)
		(end 131.188968 -231.224836)
		(width 0.088646)
		(layer "In11.Cu")
		(net "M_H_CPU1_SB_DQ<14>")
	)
	(segment
		(start 205.596744 -215.166702)
		(end 204.076046 -215.166702)
		(width 0.20066)
		(layer "F.Cu")
		(net "M_H_CPU1_SB_DQ<13>")
	)
	(segment
		(start 123.857512 -231.436418)
		(end 123.857512 -230.900732)
		(width 0.20066)
		(layer "F.Cu")
		(net "M_H_CPU1_SB_DQ<13>")
	)
	(segment
		(start 123.857512 -230.900732)
		(end 123.857766 -230.900478)
		(width 0.20066)
		(layer "F.Cu")
		(net "M_H_CPU1_SB_DQ<13>")
	)
	(segment
		(start 209.596482 -214.73541)
		(end 209.186526 -214.73541)
		(width 0.20066)
		(layer "F.Cu")
		(net "M_H_CPU1_SB_DQ<13>")
	)
	(segment
		(start 210.028028 -215.166956)
		(end 209.596482 -214.73541)
		(width 0.20066)
		(layer "F.Cu")
		(net "M_H_CPU1_SB_DQ<13>")
	)
	(segment
		(start 206.320644 -215.415368)
		(end 205.84541 -215.415368)
		(width 0.20066)
		(layer "F.Cu")
		(net "M_H_CPU1_SB_DQ<13>")
	)
	(segment
		(start 204.076046 -215.166702)
		(end 202.971146 -215.166702)
		(width 0.20066)
		(layer "F.Cu")
		(net "M_H_CPU1_SB_DQ<13>")
	)
	(segment
		(start 206.508604 -214.85987)
		(end 206.508604 -215.227408)
		(width 0.20066)
		(layer "F.Cu")
		(net "M_H_CPU1_SB_DQ<13>")
	)
	(segment
		(start 206.626714 -214.74176)
		(end 206.508604 -214.85987)
		(width 0.20066)
		(layer "F.Cu")
		(net "M_H_CPU1_SB_DQ<13>")
	)
	(segment
		(start 206.991458 -214.74176)
		(end 206.971392 -214.74176)
		(width 0.101854)
		(layer "F.Cu")
		(net "M_H_CPU1_SB_DQ<13>")
	)
	(segment
		(start 211.619846 -215.166702)
		(end 211.619592 -215.166956)
		(width 0.20066)
		(layer "F.Cu")
		(net "M_H_CPU1_SB_DQ<13>")
	)
	(segment
		(start 209.180176 -214.74176)
		(end 206.991458 -214.74176)
		(width 0.1016)
		(layer "F.Cu")
		(net "M_H_CPU1_SB_DQ<13>")
	)
	(segment
		(start 206.971392 -214.74176)
		(end 206.626714 -214.74176)
		(width 0.20066)
		(layer "F.Cu")
		(net "M_H_CPU1_SB_DQ<13>")
	)
	(segment
		(start 211.619592 -215.166956)
		(end 210.028028 -215.166956)
		(width 0.20066)
		(layer "F.Cu")
		(net "M_H_CPU1_SB_DQ<13>")
	)
	(segment
		(start 205.84541 -215.415368)
		(end 205.596744 -215.166702)
		(width 0.20066)
		(layer "F.Cu")
		(net "M_H_CPU1_SB_DQ<13>")
	)
	(segment
		(start 209.186526 -214.73541)
		(end 209.180176 -214.74176)
		(width 0.1016)
		(layer "F.Cu")
		(net "M_H_CPU1_SB_DQ<13>")
	)
	(segment
		(start 206.508604 -215.227408)
		(end 206.320644 -215.415368)
		(width 0.20066)
		(layer "F.Cu")
		(net "M_H_CPU1_SB_DQ<13>")
	)
	(segment
		(start 165.125146 -207.85201)
		(end 164.20973 -208.767426)
		(width 0.18288)
		(layer "In11.Cu")
		(net "M_H_CPU1_SB_DQ<13>")
	)
	(segment
		(start 202.902312 -214.865204)
		(end 202.392026 -214.354918)
		(width 0.18288)
		(layer "In11.Cu")
		(net "M_H_CPU1_SB_DQ<13>")
	)
	(segment
		(start 176.963578 -207.938624)
		(end 176.828958 -207.938624)
		(width 0.18288)
		(layer "In11.Cu")
		(net "M_H_CPU1_SB_DQ<13>")
	)
	(segment
		(start 199.438514 -210.596226)
		(end 197.715632 -208.873344)
		(width 0.18288)
		(layer "In11.Cu")
		(net "M_H_CPU1_SB_DQ<13>")
	)
	(segment
		(start 144.989042 -223.987106)
		(end 144.989042 -224.96145)
		(width 0.18288)
		(layer "In11.Cu")
		(net "M_H_CPU1_SB_DQ<13>")
	)
	(segment
		(start 162.961574 -208.574386)
		(end 162.768534 -208.767426)
		(width 0.18288)
		(layer "In11.Cu")
		(net "M_H_CPU1_SB_DQ<13>")
	)
	(segment
		(start 187.484512 -207.09382)
		(end 187.269882 -207.30845)
		(width 0.18288)
		(layer "In11.Cu")
		(net "M_H_CPU1_SB_DQ<13>")
	)
	(segment
		(start 185.918856 -207.113632)
		(end 185.725816 -206.920592)
		(width 0.18288)
		(layer "In11.Cu")
		(net "M_H_CPU1_SB_DQ<13>")
	)
	(segment
		(start 195.139564 -208.873344)
		(end 194.373246 -208.107026)
		(width 0.18288)
		(layer "In11.Cu")
		(net "M_H_CPU1_SB_DQ<13>")
	)
	(segment
		(start 162.961574 -208.181956)
		(end 162.961574 -208.574386)
		(width 0.18288)
		(layer "In11.Cu")
		(net "M_H_CPU1_SB_DQ<13>")
	)
	(segment
		(start 187.269882 -207.562958)
		(end 186.868562 -207.964278)
		(width 0.18288)
		(layer "In11.Cu")
		(net "M_H_CPU1_SB_DQ<13>")
	)
	(segment
		(start 129.698496 -230.584756)
		(end 129.683764 -230.57612)
		(width 0.088646)
		(layer "In11.Cu")
		(net "M_H_CPU1_SB_DQ<13>")
	)
	(segment
		(start 202.392026 -214.354918)
		(end 202.392026 -213.085426)
		(width 0.18288)
		(layer "In11.Cu")
		(net "M_H_CPU1_SB_DQ<13>")
	)
	(segment
		(start 128.758696 -230.584756)
		(end 128.743964 -230.57612)
		(width 0.088646)
		(layer "In11.Cu")
		(net "M_H_CPU1_SB_DQ<13>")
	)
	(segment
		(start 144.989042 -224.96145)
		(end 141.280134 -228.670358)
		(width 0.18288)
		(layer "In11.Cu")
		(net "M_H_CPU1_SB_DQ<13>")
	)
	(segment
		(start 168.931082 -208.268316)
		(end 168.514776 -207.85201)
		(width 0.18288)
		(layer "In11.Cu")
		(net "M_H_CPU1_SB_DQ<13>")
	)
	(segment
		(start 202.971146 -215.166702)
		(end 202.971146 -215.03132)
		(width 0.18288)
		(layer "In11.Cu")
		(net "M_H_CPU1_SB_DQ<13>")
	)
	(segment
		(start 172.351446 -207.938624)
		(end 172.021754 -208.268316)
		(width 0.18288)
		(layer "In11.Cu")
		(net "M_H_CPU1_SB_DQ<13>")
	)
	(segment
		(start 132.128514 -230.57612)
		(end 132.1181 -230.582216)
		(width 0.088646)
		(layer "In11.Cu")
		(net "M_H_CPU1_SB_DQ<13>")
	)
	(segment
		(start 163.154614 -207.988916)
		(end 162.961574 -208.181956)
		(width 0.18288)
		(layer "In11.Cu")
		(net "M_H_CPU1_SB_DQ<13>")
	)
	(segment
		(start 176.828958 -207.938624)
		(end 176.142142 -207.939132)
		(width 0.18288)
		(layer "In11.Cu")
		(net "M_H_CPU1_SB_DQ<13>")
	)
	(segment
		(start 177.713132 -208.12887)
		(end 177.524664 -207.940402)
		(width 0.18288)
		(layer "In11.Cu")
		(net "M_H_CPU1_SB_DQ<13>")
	)
	(segment
		(start 185.215276 -207.113632)
		(end 185.215276 -207.771238)
		(width 0.18288)
		(layer "In11.Cu")
		(net "M_H_CPU1_SB_DQ<13>")
	)
	(segment
		(start 176.142142 -207.939132)
		(end 172.731938 -207.939132)
		(width 0.18288)
		(layer "In11.Cu")
		(net "M_H_CPU1_SB_DQ<13>")
	)
	(segment
		(start 186.868562 -207.964278)
		(end 186.111896 -207.964278)
		(width 0.18288)
		(layer "In11.Cu")
		(net "M_H_CPU1_SB_DQ<13>")
	)
	(segment
		(start 138.586972 -229.711758)
		(end 138.424666 -229.711758)
		(width 0.088646)
		(layer "In11.Cu")
		(net "M_H_CPU1_SB_DQ<13>")
	)
	(segment
		(start 152.109932 -216.866216)
		(end 144.989042 -223.987106)
		(width 0.18288)
		(layer "In11.Cu")
		(net "M_H_CPU1_SB_DQ<13>")
	)
	(segment
		(start 185.022236 -207.964278)
		(end 183.615584 -207.964278)
		(width 0.18288)
		(layer "In11.Cu")
		(net "M_H_CPU1_SB_DQ<13>")
	)
	(segment
		(start 181.85638 -208.108296)
		(end 181.66334 -208.301336)
		(width 0.18288)
		(layer "In11.Cu")
		(net "M_H_CPU1_SB_DQ<13>")
	)
	(segment
		(start 185.408316 -206.920592)
		(end 185.215276 -207.113632)
		(width 0.18288)
		(layer "In11.Cu")
		(net "M_H_CPU1_SB_DQ<13>")
	)
	(segment
		(start 183.615584 -207.964278)
		(end 183.280812 -207.629506)
		(width 0.18288)
		(layer "In11.Cu")
		(net "M_H_CPU1_SB_DQ<13>")
	)
	(segment
		(start 183.280812 -207.629506)
		(end 182.04942 -207.629506)
		(width 0.18288)
		(layer "In11.Cu")
		(net "M_H_CPU1_SB_DQ<13>")
	)
	(segment
		(start 157.21076 -209.681826)
		(end 152.109932 -214.782654)
		(width 0.18288)
		(layer "In11.Cu")
		(net "M_H_CPU1_SB_DQ<13>")
	)
	(segment
		(start 152.109932 -214.782654)
		(end 152.109932 -216.866216)
		(width 0.18288)
		(layer "In11.Cu")
		(net "M_H_CPU1_SB_DQ<13>")
	)
	(segment
		(start 180.95976 -207.629506)
		(end 179.860956 -207.629506)
		(width 0.18288)
		(layer "In11.Cu")
		(net "M_H_CPU1_SB_DQ<13>")
	)
	(segment
		(start 139.628372 -228.670358)
		(end 138.586972 -229.711758)
		(width 0.088646)
		(layer "In11.Cu")
		(net "M_H_CPU1_SB_DQ<13>")
	)
	(segment
		(start 181.34584 -208.301336)
		(end 181.1528 -208.108296)
		(width 0.18288)
		(layer "In11.Cu")
		(net "M_H_CPU1_SB_DQ<13>")
	)
	(segment
		(start 186.111896 -207.964278)
		(end 185.918856 -207.771238)
		(width 0.18288)
		(layer "In11.Cu")
		(net "M_H_CPU1_SB_DQ<13>")
	)
	(segment
		(start 163.665154 -208.181956)
		(end 163.472114 -207.988916)
		(width 0.18288)
		(layer "In11.Cu")
		(net "M_H_CPU1_SB_DQ<13>")
	)
	(segment
		(start 192.94602 -207.09382)
		(end 187.484512 -207.09382)
		(width 0.18288)
		(layer "In11.Cu")
		(net "M_H_CPU1_SB_DQ<13>")
	)
	(segment
		(start 202.392026 -213.085426)
		(end 199.902826 -210.596226)
		(width 0.18288)
		(layer "In11.Cu")
		(net "M_H_CPU1_SB_DQ<13>")
	)
	(segment
		(start 179.361592 -208.12887)
		(end 177.713132 -208.12887)
		(width 0.18288)
		(layer "In11.Cu")
		(net "M_H_CPU1_SB_DQ<13>")
	)
	(segment
		(start 141.280134 -228.670358)
		(end 140.163042 -228.670358)
		(width 0.18288)
		(layer "In11.Cu")
		(net "M_H_CPU1_SB_DQ<13>")
	)
	(segment
		(start 132.513324 -230.582216)
		(end 132.50291 -230.57612)
		(width 0.088646)
		(layer "In11.Cu")
		(net "M_H_CPU1_SB_DQ<13>")
	)
	(segment
		(start 177.524664 -207.940402)
		(end 176.963578 -207.938624)
		(width 0.18288)
		(layer "In11.Cu")
		(net "M_H_CPU1_SB_DQ<13>")
	)
	(segment
		(start 179.860956 -207.629506)
		(end 179.361592 -208.12887)
		(width 0.18288)
		(layer "In11.Cu")
		(net "M_H_CPU1_SB_DQ<13>")
	)
	(segment
		(start 185.725816 -206.920592)
		(end 185.408316 -206.920592)
		(width 0.18288)
		(layer "In11.Cu")
		(net "M_H_CPU1_SB_DQ<13>")
	)
	(segment
		(start 172.021754 -208.268316)
		(end 168.931082 -208.268316)
		(width 0.18288)
		(layer "In11.Cu")
		(net "M_H_CPU1_SB_DQ<13>")
	)
	(segment
		(start 181.1528 -208.108296)
		(end 181.1528 -207.822546)
		(width 0.18288)
		(layer "In11.Cu")
		(net "M_H_CPU1_SB_DQ<13>")
	)
	(segment
		(start 163.858194 -208.767426)
		(end 163.665154 -208.574386)
		(width 0.18288)
		(layer "In11.Cu")
		(net "M_H_CPU1_SB_DQ<13>")
	)
	(segment
		(start 194.373246 -208.107026)
		(end 193.959226 -208.107026)
		(width 0.18288)
		(layer "In11.Cu")
		(net "M_H_CPU1_SB_DQ<13>")
	)
	(segment
		(start 182.04942 -207.629506)
		(end 181.85638 -207.822546)
		(width 0.18288)
		(layer "In11.Cu")
		(net "M_H_CPU1_SB_DQ<13>")
	)
	(segment
		(start 125.939296 -230.584756)
		(end 125.924564 -230.57612)
		(width 0.088646)
		(layer "In11.Cu")
		(net "M_H_CPU1_SB_DQ<13>")
	)
	(segment
		(start 126.879096 -230.584756)
		(end 126.864364 -230.57612)
		(width 0.088646)
		(layer "In11.Cu")
		(net "M_H_CPU1_SB_DQ<13>")
	)
	(segment
		(start 199.902826 -210.596226)
		(end 199.438514 -210.596226)
		(width 0.18288)
		(layer "In11.Cu")
		(net "M_H_CPU1_SB_DQ<13>")
	)
	(segment
		(start 164.20973 -208.767426)
		(end 163.858194 -208.767426)
		(width 0.18288)
		(layer "In11.Cu")
		(net "M_H_CPU1_SB_DQ<13>")
	)
	(segment
		(start 181.66334 -208.301336)
		(end 181.34584 -208.301336)
		(width 0.18288)
		(layer "In11.Cu")
		(net "M_H_CPU1_SB_DQ<13>")
	)
	(segment
		(start 161.142426 -209.681826)
		(end 157.21076 -209.681826)
		(width 0.18288)
		(layer "In11.Cu")
		(net "M_H_CPU1_SB_DQ<13>")
	)
	(segment
		(start 124.235718 -230.96601)
		(end 124.170186 -230.900478)
		(width 0.088646)
		(layer "In11.Cu")
		(net "M_H_CPU1_SB_DQ<13>")
	)
	(segment
		(start 172.731938 -207.939132)
		(end 172.351446 -207.938624)
		(width 0.18288)
		(layer "In11.Cu")
		(net "M_H_CPU1_SB_DQ<13>")
	)
	(segment
		(start 140.163042 -228.670358)
		(end 139.628372 -228.670358)
		(width 0.088646)
		(layer "In11.Cu")
		(net "M_H_CPU1_SB_DQ<13>")
	)
	(segment
		(start 162.768534 -208.767426)
		(end 162.056826 -208.767426)
		(width 0.18288)
		(layer "In11.Cu")
		(net "M_H_CPU1_SB_DQ<13>")
	)
	(segment
		(start 197.715632 -208.873344)
		(end 195.139564 -208.873344)
		(width 0.18288)
		(layer "In11.Cu")
		(net "M_H_CPU1_SB_DQ<13>")
	)
	(segment
		(start 185.918856 -207.771238)
		(end 185.918856 -207.113632)
		(width 0.18288)
		(layer "In11.Cu")
		(net "M_H_CPU1_SB_DQ<13>")
	)
	(segment
		(start 162.056826 -208.767426)
		(end 161.142426 -209.681826)
		(width 0.18288)
		(layer "In11.Cu")
		(net "M_H_CPU1_SB_DQ<13>")
	)
	(segment
		(start 125.362462 -230.90124)
		(end 125.362462 -230.922576)
		(width 0.088646)
		(layer "In11.Cu")
		(net "M_H_CPU1_SB_DQ<13>")
	)
	(segment
		(start 185.215276 -207.771238)
		(end 185.022236 -207.964278)
		(width 0.18288)
		(layer "In11.Cu")
		(net "M_H_CPU1_SB_DQ<13>")
	)
	(segment
		(start 138.050016 -230.086662)
		(end 138.050016 -230.096568)
		(width 0.088646)
		(layer "In11.Cu")
		(net "M_H_CPU1_SB_DQ<13>")
	)
	(segment
		(start 130.638296 -230.584756)
		(end 130.623564 -230.57612)
		(width 0.088646)
		(layer "In11.Cu")
		(net "M_H_CPU1_SB_DQ<13>")
	)
	(segment
		(start 163.472114 -207.988916)
		(end 163.154614 -207.988916)
		(width 0.18288)
		(layer "In11.Cu")
		(net "M_H_CPU1_SB_DQ<13>")
	)
	(segment
		(start 187.269882 -207.30845)
		(end 187.269882 -207.562958)
		(width 0.18288)
		(layer "In11.Cu")
		(net "M_H_CPU1_SB_DQ<13>")
	)
	(segment
		(start 181.85638 -207.822546)
		(end 181.85638 -208.108296)
		(width 0.18288)
		(layer "In11.Cu")
		(net "M_H_CPU1_SB_DQ<13>")
	)
	(segment
		(start 202.971146 -215.03132)
		(end 202.902312 -214.865204)
		(width 0.18288)
		(layer "In11.Cu")
		(net "M_H_CPU1_SB_DQ<13>")
	)
	(segment
		(start 127.818896 -230.584756)
		(end 127.804164 -230.57612)
		(width 0.088646)
		(layer "In11.Cu")
		(net "M_H_CPU1_SB_DQ<13>")
	)
	(segment
		(start 124.170186 -230.900478)
		(end 123.857766 -230.900478)
		(width 0.088646)
		(layer "In11.Cu")
		(net "M_H_CPU1_SB_DQ<13>")
	)
	(segment
		(start 168.514776 -207.85201)
		(end 165.125146 -207.85201)
		(width 0.18288)
		(layer "In11.Cu")
		(net "M_H_CPU1_SB_DQ<13>")
	)
	(segment
		(start 193.959226 -208.107026)
		(end 192.94602 -207.09382)
		(width 0.18288)
		(layer "In11.Cu")
		(net "M_H_CPU1_SB_DQ<13>")
	)
	(segment
		(start 181.1528 -207.822546)
		(end 180.95976 -207.629506)
		(width 0.18288)
		(layer "In11.Cu")
		(net "M_H_CPU1_SB_DQ<13>")
	)
	(segment
		(start 163.665154 -208.574386)
		(end 163.665154 -208.181956)
		(width 0.18288)
		(layer "In11.Cu")
		(net "M_H_CPU1_SB_DQ<13>")
	)
	(arc
		(start 137.767568 -230.57612)
		(mid 137.484866 -230.651896)
		(end 137.202164 -230.57612)
		(width 0.088646)
		(layer "In11.Cu")
		(net "M_H_CPU1_SB_DQ<13>")
	)
	(arc
		(start 134.948168 -230.57612)
		(mid 134.665466 -230.651896)
		(end 134.382764 -230.57612)
		(width 0.088646)
		(layer "In11.Cu")
		(net "M_H_CPU1_SB_DQ<13>")
	)
	(arc
		(start 136.827768 -230.57612)
		(mid 136.545066 -230.651896)
		(end 136.262364 -230.57612)
		(width 0.088646)
		(layer "In11.Cu")
		(net "M_H_CPU1_SB_DQ<13>")
	)
	(arc
		(start 128.743964 -230.57612)
		(mid 128.556766 -230.525977)
		(end 128.369568 -230.57612)
		(width 0.088646)
		(layer "In11.Cu")
		(net "M_H_CPU1_SB_DQ<13>")
	)
	(arc
		(start 135.322564 -230.57612)
		(mid 135.135366 -230.525977)
		(end 134.948168 -230.57612)
		(width 0.088646)
		(layer "In11.Cu")
		(net "M_H_CPU1_SB_DQ<13>")
	)
	(arc
		(start 133.442964 -230.57612)
		(mid 133.255766 -230.525977)
		(end 133.068568 -230.57612)
		(width 0.088646)
		(layer "In11.Cu")
		(net "M_H_CPU1_SB_DQ<13>")
	)
	(arc
		(start 129.683764 -230.57612)
		(mid 129.496566 -230.525977)
		(end 129.309368 -230.57612)
		(width 0.088646)
		(layer "In11.Cu")
		(net "M_H_CPU1_SB_DQ<13>")
	)
	(arc
		(start 134.382764 -230.57612)
		(mid 134.195566 -230.525977)
		(end 134.008368 -230.57612)
		(width 0.088646)
		(layer "In11.Cu")
		(net "M_H_CPU1_SB_DQ<13>")
	)
	(arc
		(start 138.050016 -230.096568)
		(mid 137.971905 -230.373517)
		(end 137.767568 -230.57612)
		(width 0.088646)
		(layer "In11.Cu")
		(net "M_H_CPU1_SB_DQ<13>")
	)
	(arc
		(start 137.202164 -230.57612)
		(mid 137.014966 -230.525977)
		(end 136.827768 -230.57612)
		(width 0.088646)
		(layer "In11.Cu")
		(net "M_H_CPU1_SB_DQ<13>")
	)
	(arc
		(start 127.429768 -230.57612)
		(mid 127.155569 -230.651955)
		(end 126.879096 -230.584756)
		(width 0.088646)
		(layer "In11.Cu")
		(net "M_H_CPU1_SB_DQ<13>")
	)
	(arc
		(start 127.804164 -230.57612)
		(mid 127.616966 -230.525977)
		(end 127.429768 -230.57612)
		(width 0.088646)
		(layer "In11.Cu")
		(net "M_H_CPU1_SB_DQ<13>")
	)
	(arc
		(start 125.550168 -230.57612)
		(mid 125.412755 -230.713532)
		(end 125.362462 -230.90124)
		(width 0.088646)
		(layer "In11.Cu")
		(net "M_H_CPU1_SB_DQ<13>")
	)
	(arc
		(start 130.623564 -230.57612)
		(mid 130.436366 -230.525977)
		(end 130.249168 -230.57612)
		(width 0.088646)
		(layer "In11.Cu")
		(net "M_H_CPU1_SB_DQ<13>")
	)
	(arc
		(start 136.262364 -230.57612)
		(mid 136.075166 -230.525977)
		(end 135.887968 -230.57612)
		(width 0.088646)
		(layer "In11.Cu")
		(net "M_H_CPU1_SB_DQ<13>")
	)
	(arc
		(start 133.068568 -230.57612)
		(mid 132.791755 -230.65199)
		(end 132.513324 -230.582216)
		(width 0.088646)
		(layer "In11.Cu")
		(net "M_H_CPU1_SB_DQ<13>")
	)
	(arc
		(start 131.563364 -230.57612)
		(mid 131.376166 -230.525977)
		(end 131.188968 -230.57612)
		(width 0.088646)
		(layer "In11.Cu")
		(net "M_H_CPU1_SB_DQ<13>")
	)
	(arc
		(start 126.489968 -230.57612)
		(mid 126.215769 -230.651955)
		(end 125.939296 -230.584756)
		(width 0.088646)
		(layer "In11.Cu")
		(net "M_H_CPU1_SB_DQ<13>")
	)
	(arc
		(start 132.1181 -230.582216)
		(mid 131.839922 -230.651939)
		(end 131.563364 -230.57612)
		(width 0.088646)
		(layer "In11.Cu")
		(net "M_H_CPU1_SB_DQ<13>")
	)
	(arc
		(start 125.924564 -230.57612)
		(mid 125.737366 -230.525977)
		(end 125.550168 -230.57612)
		(width 0.088646)
		(layer "In11.Cu")
		(net "M_H_CPU1_SB_DQ<13>")
	)
	(arc
		(start 125.362462 -230.922576)
		(mid 124.819105 -231.46564)
		(end 124.235718 -230.96601)
		(width 0.088646)
		(layer "In11.Cu")
		(net "M_H_CPU1_SB_DQ<13>")
	)
	(arc
		(start 134.008368 -230.57612)
		(mid 133.725666 -230.651896)
		(end 133.442964 -230.57612)
		(width 0.088646)
		(layer "In11.Cu")
		(net "M_H_CPU1_SB_DQ<13>")
	)
	(arc
		(start 126.864364 -230.57612)
		(mid 126.677166 -230.525977)
		(end 126.489968 -230.57612)
		(width 0.088646)
		(layer "In11.Cu")
		(net "M_H_CPU1_SB_DQ<13>")
	)
	(arc
		(start 130.249168 -230.57612)
		(mid 129.974969 -230.651955)
		(end 129.698496 -230.584756)
		(width 0.088646)
		(layer "In11.Cu")
		(net "M_H_CPU1_SB_DQ<13>")
	)
	(arc
		(start 129.309368 -230.57612)
		(mid 129.035169 -230.651955)
		(end 128.758696 -230.584756)
		(width 0.088646)
		(layer "In11.Cu")
		(net "M_H_CPU1_SB_DQ<13>")
	)
	(arc
		(start 128.369568 -230.57612)
		(mid 128.095369 -230.651955)
		(end 127.818896 -230.584756)
		(width 0.088646)
		(layer "In11.Cu")
		(net "M_H_CPU1_SB_DQ<13>")
	)
	(arc
		(start 132.50291 -230.57612)
		(mid 132.315712 -230.525977)
		(end 132.128514 -230.57612)
		(width 0.088646)
		(layer "In11.Cu")
		(net "M_H_CPU1_SB_DQ<13>")
	)
	(arc
		(start 131.188968 -230.57612)
		(mid 130.914769 -230.651955)
		(end 130.638296 -230.584756)
		(width 0.088646)
		(layer "In11.Cu")
		(net "M_H_CPU1_SB_DQ<13>")
	)
	(arc
		(start 138.424666 -229.711758)
		(mid 138.159733 -229.821655)
		(end 138.050016 -230.086662)
		(width 0.088646)
		(layer "In11.Cu")
		(net "M_H_CPU1_SB_DQ<13>")
	)
	(arc
		(start 135.887968 -230.57612)
		(mid 135.605266 -230.651896)
		(end 135.322564 -230.57612)
		(width 0.088646)
		(layer "In11.Cu")
		(net "M_H_CPU1_SB_DQ<13>")
	)
	(segment
		(start 209.180176 -216.441782)
		(end 207.018382 -216.441782)
		(width 0.1016)
		(layer "F.Cu")
		(net "M_H_CPU1_SB_DQ<12>")
	)
	(segment
		(start 209.596482 -216.435432)
		(end 209.186526 -216.435432)
		(width 0.20066)
		(layer "F.Cu")
		(net "M_H_CPU1_SB_DQ<12>")
	)
	(segment
		(start 206.508604 -216.559892)
		(end 206.508604 -216.92743)
		(width 0.20066)
		(layer "F.Cu")
		(net "M_H_CPU1_SB_DQ<12>")
	)
	(segment
		(start 206.971392 -216.441782)
		(end 206.626714 -216.441782)
		(width 0.20066)
		(layer "F.Cu")
		(net "M_H_CPU1_SB_DQ<12>")
	)
	(segment
		(start 207.018382 -216.441782)
		(end 206.971392 -216.441782)
		(width 0.101854)
		(layer "F.Cu")
		(net "M_H_CPU1_SB_DQ<12>")
	)
	(segment
		(start 205.596744 -216.866724)
		(end 204.076046 -216.866724)
		(width 0.20066)
		(layer "F.Cu")
		(net "M_H_CPU1_SB_DQ<12>")
	)
	(segment
		(start 205.84541 -217.11539)
		(end 205.596744 -216.866724)
		(width 0.20066)
		(layer "F.Cu")
		(net "M_H_CPU1_SB_DQ<12>")
	)
	(segment
		(start 204.076046 -216.866724)
		(end 202.971146 -216.866724)
		(width 0.20066)
		(layer "F.Cu")
		(net "M_H_CPU1_SB_DQ<12>")
	)
	(segment
		(start 206.626714 -216.441782)
		(end 206.508604 -216.559892)
		(width 0.20066)
		(layer "F.Cu")
		(net "M_H_CPU1_SB_DQ<12>")
	)
	(segment
		(start 209.186526 -216.435432)
		(end 209.180176 -216.441782)
		(width 0.1016)
		(layer "F.Cu")
		(net "M_H_CPU1_SB_DQ<12>")
	)
	(segment
		(start 123.387612 -232.250234)
		(end 123.387612 -231.714548)
		(width 0.20066)
		(layer "F.Cu")
		(net "M_H_CPU1_SB_DQ<12>")
	)
	(segment
		(start 210.028028 -216.866978)
		(end 209.596482 -216.435432)
		(width 0.20066)
		(layer "F.Cu")
		(net "M_H_CPU1_SB_DQ<12>")
	)
	(segment
		(start 206.508604 -216.92743)
		(end 206.320644 -217.11539)
		(width 0.20066)
		(layer "F.Cu")
		(net "M_H_CPU1_SB_DQ<12>")
	)
	(segment
		(start 123.387866 -232.250488)
		(end 123.387612 -232.250234)
		(width 0.20066)
		(layer "F.Cu")
		(net "M_H_CPU1_SB_DQ<12>")
	)
	(segment
		(start 206.320644 -217.11539)
		(end 205.84541 -217.11539)
		(width 0.20066)
		(layer "F.Cu")
		(net "M_H_CPU1_SB_DQ<12>")
	)
	(segment
		(start 211.619592 -216.866978)
		(end 210.028028 -216.866978)
		(width 0.20066)
		(layer "F.Cu")
		(net "M_H_CPU1_SB_DQ<12>")
	)
	(segment
		(start 211.619846 -216.866724)
		(end 211.619592 -216.866978)
		(width 0.20066)
		(layer "F.Cu")
		(net "M_H_CPU1_SB_DQ<12>")
	)
	(segment
		(start 197.642226 -212.094826)
		(end 195.719954 -210.172554)
		(width 0.18288)
		(layer "In11.Cu")
		(net "M_H_CPU1_SB_DQ<12>")
	)
	(segment
		(start 124.140214 -232.038906)
		(end 124.125482 -232.03027)
		(width 0.088646)
		(layer "In11.Cu")
		(net "M_H_CPU1_SB_DQ<12>")
	)
	(segment
		(start 153.40203 -217.069416)
		(end 146.055334 -224.416112)
		(width 0.18288)
		(layer "In11.Cu")
		(net "M_H_CPU1_SB_DQ<12>")
	)
	(segment
		(start 125.4633 -232.033826)
		(end 125.45441 -232.038906)
		(width 0.088646)
		(layer "In11.Cu")
		(net "M_H_CPU1_SB_DQ<12>")
	)
	(segment
		(start 168.709594 -209.453226)
		(end 168.053512 -210.109308)
		(width 0.18288)
		(layer "In11.Cu")
		(net "M_H_CPU1_SB_DQ<12>")
	)
	(segment
		(start 146.055334 -224.416112)
		(end 146.055334 -225.344736)
		(width 0.18288)
		(layer "In11.Cu")
		(net "M_H_CPU1_SB_DQ<12>")
	)
	(segment
		(start 171.581064 -210.49361)
		(end 170.54068 -209.453226)
		(width 0.18288)
		(layer "In11.Cu")
		(net "M_H_CPU1_SB_DQ<12>")
	)
	(segment
		(start 190.269622 -208.805018)
		(end 190.269622 -209.449416)
		(width 0.18288)
		(layer "In11.Cu")
		(net "M_H_CPU1_SB_DQ<12>")
	)
	(segment
		(start 139.230608 -229.687628)
		(end 138.986768 -229.931468)
		(width 0.088646)
		(layer "In11.Cu")
		(net "M_H_CPU1_SB_DQ<12>")
	)
	(segment
		(start 138.986768 -230.347012)
		(end 138.824716 -230.509064)
		(width 0.088646)
		(layer "In11.Cu")
		(net "M_H_CPU1_SB_DQ<12>")
	)
	(segment
		(start 201.22007 -216.28227)
		(end 200.309226 -215.371426)
		(width 0.18288)
		(layer "In11.Cu")
		(net "M_H_CPU1_SB_DQ<12>")
	)
	(segment
		(start 194.957954 -210.172554)
		(end 194.373246 -209.587846)
		(width 0.18288)
		(layer "In11.Cu")
		(net "M_H_CPU1_SB_DQ<12>")
	)
	(segment
		(start 141.712442 -229.687628)
		(end 140.163296 -229.687628)
		(width 0.18288)
		(layer "In11.Cu")
		(net "M_H_CPU1_SB_DQ<12>")
	)
	(segment
		(start 157.096968 -211.344002)
		(end 153.40203 -215.03894)
		(width 0.18288)
		(layer "In11.Cu")
		(net "M_H_CPU1_SB_DQ<12>")
	)
	(segment
		(start 164.804344 -210.109308)
		(end 163.791392 -211.12226)
		(width 0.18288)
		(layer "In11.Cu")
		(net "M_H_CPU1_SB_DQ<12>")
	)
	(segment
		(start 202.608688 -216.28227)
		(end 201.22007 -216.28227)
		(width 0.18288)
		(layer "In11.Cu")
		(net "M_H_CPU1_SB_DQ<12>")
	)
	(segment
		(start 123.515628 -231.842564)
		(end 123.387612 -231.714548)
		(width 0.088646)
		(layer "In11.Cu")
		(net "M_H_CPU1_SB_DQ<12>")
	)
	(segment
		(start 174.187358 -210.49361)
		(end 171.581064 -210.49361)
		(width 0.18288)
		(layer "In11.Cu")
		(net "M_H_CPU1_SB_DQ<12>")
	)
	(segment
		(start 138.824716 -230.509064)
		(end 138.698478 -230.5812)
		(width 0.088646)
		(layer "In11.Cu")
		(net "M_H_CPU1_SB_DQ<12>")
	)
	(segment
		(start 166.58717 -211.062316)
		(end 166.26967 -211.062316)
		(width 0.18288)
		(layer "In11.Cu")
		(net "M_H_CPU1_SB_DQ<12>")
	)
	(segment
		(start 127.899414 -231.39019)
		(end 127.884682 -231.398826)
		(width 0.088646)
		(layer "In11.Cu")
		(net "M_H_CPU1_SB_DQ<12>")
	)
	(segment
		(start 195.719954 -210.172554)
		(end 194.957954 -210.172554)
		(width 0.18288)
		(layer "In11.Cu")
		(net "M_H_CPU1_SB_DQ<12>")
	)
	(segment
		(start 178.742848 -209.377026)
		(end 177.628804 -210.49107)
		(width 0.18288)
		(layer "In11.Cu")
		(net "M_H_CPU1_SB_DQ<12>")
	)
	(segment
		(start 189.204346 -209.642456)
		(end 188.353192 -208.791302)
		(width 0.18288)
		(layer "In11.Cu")
		(net "M_H_CPU1_SB_DQ<12>")
	)
	(segment
		(start 140.163296 -229.687628)
		(end 139.230608 -229.687628)
		(width 0.088646)
		(layer "In11.Cu")
		(net "M_H_CPU1_SB_DQ<12>")
	)
	(segment
		(start 190.462662 -208.611978)
		(end 190.269622 -208.805018)
		(width 0.18288)
		(layer "In11.Cu")
		(net "M_H_CPU1_SB_DQ<12>")
	)
	(segment
		(start 190.269622 -209.449416)
		(end 190.076582 -209.642456)
		(width 0.18288)
		(layer "In11.Cu")
		(net "M_H_CPU1_SB_DQ<12>")
	)
	(segment
		(start 176.220882 -210.49107)
		(end 175.915574 -210.185762)
		(width 0.18288)
		(layer "In11.Cu")
		(net "M_H_CPU1_SB_DQ<12>")
	)
	(segment
		(start 130.718814 -231.39019)
		(end 130.704082 -231.398826)
		(width 0.088646)
		(layer "In11.Cu")
		(net "M_H_CPU1_SB_DQ<12>")
	)
	(segment
		(start 190.076582 -209.642456)
		(end 189.204346 -209.642456)
		(width 0.18288)
		(layer "In11.Cu")
		(net "M_H_CPU1_SB_DQ<12>")
	)
	(segment
		(start 165.88359 -210.109308)
		(end 164.804344 -210.109308)
		(width 0.18288)
		(layer "In11.Cu")
		(net "M_H_CPU1_SB_DQ<12>")
	)
	(segment
		(start 126.959614 -231.39019)
		(end 126.944882 -231.398826)
		(width 0.088646)
		(layer "In11.Cu")
		(net "M_H_CPU1_SB_DQ<12>")
	)
	(segment
		(start 200.309226 -215.371426)
		(end 200.309226 -213.623398)
		(width 0.18288)
		(layer "In11.Cu")
		(net "M_H_CPU1_SB_DQ<12>")
	)
	(segment
		(start 191.166242 -209.642456)
		(end 190.973202 -209.449416)
		(width 0.18288)
		(layer "In11.Cu")
		(net "M_H_CPU1_SB_DQ<12>")
	)
	(segment
		(start 168.053512 -210.109308)
		(end 166.97325 -210.109308)
		(width 0.18288)
		(layer "In11.Cu")
		(net "M_H_CPU1_SB_DQ<12>")
	)
	(segment
		(start 192.44945 -209.806794)
		(end 192.285112 -209.642456)
		(width 0.18288)
		(layer "In11.Cu")
		(net "M_H_CPU1_SB_DQ<12>")
	)
	(segment
		(start 166.97325 -210.109308)
		(end 166.78021 -210.302348)
		(width 0.18288)
		(layer "In11.Cu")
		(net "M_H_CPU1_SB_DQ<12>")
	)
	(segment
		(start 131.658614 -231.39019)
		(end 131.643882 -231.398826)
		(width 0.088646)
		(layer "In11.Cu")
		(net "M_H_CPU1_SB_DQ<12>")
	)
	(segment
		(start 175.915574 -210.185762)
		(end 174.495206 -210.185762)
		(width 0.18288)
		(layer "In11.Cu")
		(net "M_H_CPU1_SB_DQ<12>")
	)
	(segment
		(start 202.971146 -216.866724)
		(end 202.971146 -216.748106)
		(width 0.18288)
		(layer "In11.Cu")
		(net "M_H_CPU1_SB_DQ<12>")
	)
	(segment
		(start 138.986768 -229.931468)
		(end 138.986768 -230.347012)
		(width 0.088646)
		(layer "In11.Cu")
		(net "M_H_CPU1_SB_DQ<12>")
	)
	(segment
		(start 194.373246 -209.587846)
		(end 193.492374 -209.587846)
		(width 0.18288)
		(layer "In11.Cu")
		(net "M_H_CPU1_SB_DQ<12>")
	)
	(segment
		(start 166.26967 -211.062316)
		(end 166.07663 -210.869276)
		(width 0.18288)
		(layer "In11.Cu")
		(net "M_H_CPU1_SB_DQ<12>")
	)
	(segment
		(start 202.897994 -216.571576)
		(end 202.608688 -216.28227)
		(width 0.18288)
		(layer "In11.Cu")
		(net "M_H_CPU1_SB_DQ<12>")
	)
	(segment
		(start 138.519916 -230.900478)
		(end 138.519916 -230.91902)
		(width 0.088646)
		(layer "In11.Cu")
		(net "M_H_CPU1_SB_DQ<12>")
	)
	(segment
		(start 170.54068 -209.453226)
		(end 168.709594 -209.453226)
		(width 0.18288)
		(layer "In11.Cu")
		(net "M_H_CPU1_SB_DQ<12>")
	)
	(segment
		(start 166.78021 -210.869276)
		(end 166.58717 -211.062316)
		(width 0.18288)
		(layer "In11.Cu")
		(net "M_H_CPU1_SB_DQ<12>")
	)
	(segment
		(start 126.019814 -231.39019)
		(end 125.77318 -231.534716)
		(width 0.088646)
		(layer "In11.Cu")
		(net "M_H_CPU1_SB_DQ<12>")
	)
	(segment
		(start 129.779014 -231.39019)
		(end 129.7686 -231.396286)
		(width 0.088646)
		(layer "In11.Cu")
		(net "M_H_CPU1_SB_DQ<12>")
	)
	(segment
		(start 200.309226 -213.623398)
		(end 198.780654 -212.094826)
		(width 0.18288)
		(layer "In11.Cu")
		(net "M_H_CPU1_SB_DQ<12>")
	)
	(segment
		(start 190.973202 -209.449416)
		(end 190.973202 -208.805018)
		(width 0.18288)
		(layer "In11.Cu")
		(net "M_H_CPU1_SB_DQ<12>")
	)
	(segment
		(start 177.628804 -210.49107)
		(end 176.220882 -210.49107)
		(width 0.18288)
		(layer "In11.Cu")
		(net "M_H_CPU1_SB_DQ<12>")
	)
	(segment
		(start 190.973202 -208.805018)
		(end 190.780162 -208.611978)
		(width 0.18288)
		(layer "In11.Cu")
		(net "M_H_CPU1_SB_DQ<12>")
	)
	(segment
		(start 166.78021 -210.302348)
		(end 166.78021 -210.869276)
		(width 0.18288)
		(layer "In11.Cu")
		(net "M_H_CPU1_SB_DQ<12>")
	)
	(segment
		(start 186.95543 -209.377026)
		(end 178.742848 -209.377026)
		(width 0.18288)
		(layer "In11.Cu")
		(net "M_H_CPU1_SB_DQ<12>")
	)
	(segment
		(start 125.080014 -232.038906)
		(end 125.065282 -232.03027)
		(width 0.088646)
		(layer "In11.Cu")
		(net "M_H_CPU1_SB_DQ<12>")
	)
	(segment
		(start 192.285112 -209.642456)
		(end 191.166242 -209.642456)
		(width 0.18288)
		(layer "In11.Cu")
		(net "M_H_CPU1_SB_DQ<12>")
	)
	(segment
		(start 160.81883 -211.344002)
		(end 157.096968 -211.344002)
		(width 0.18288)
		(layer "In11.Cu")
		(net "M_H_CPU1_SB_DQ<12>")
	)
	(segment
		(start 153.40203 -215.03894)
		(end 153.40203 -217.069416)
		(width 0.18288)
		(layer "In11.Cu")
		(net "M_H_CPU1_SB_DQ<12>")
	)
	(segment
		(start 161.040572 -211.12226)
		(end 160.81883 -211.344002)
		(width 0.18288)
		(layer "In11.Cu")
		(net "M_H_CPU1_SB_DQ<12>")
	)
	(segment
		(start 193.492374 -209.587846)
		(end 193.273426 -209.806794)
		(width 0.18288)
		(layer "In11.Cu")
		(net "M_H_CPU1_SB_DQ<12>")
	)
	(segment
		(start 163.791392 -211.12226)
		(end 161.040572 -211.12226)
		(width 0.18288)
		(layer "In11.Cu")
		(net "M_H_CPU1_SB_DQ<12>")
	)
	(segment
		(start 128.839468 -231.39019)
		(end 128.829054 -231.396286)
		(width 0.088646)
		(layer "In11.Cu")
		(net "M_H_CPU1_SB_DQ<12>")
	)
	(segment
		(start 190.780162 -208.611978)
		(end 190.462662 -208.611978)
		(width 0.18288)
		(layer "In11.Cu")
		(net "M_H_CPU1_SB_DQ<12>")
	)
	(segment
		(start 188.353192 -208.791302)
		(end 187.541154 -208.791302)
		(width 0.18288)
		(layer "In11.Cu")
		(net "M_H_CPU1_SB_DQ<12>")
	)
	(segment
		(start 198.780654 -212.094826)
		(end 197.642226 -212.094826)
		(width 0.18288)
		(layer "In11.Cu")
		(net "M_H_CPU1_SB_DQ<12>")
	)
	(segment
		(start 174.495206 -210.185762)
		(end 174.187358 -210.49361)
		(width 0.18288)
		(layer "In11.Cu")
		(net "M_H_CPU1_SB_DQ<12>")
	)
	(segment
		(start 202.971146 -216.748106)
		(end 202.897994 -216.571576)
		(width 0.18288)
		(layer "In11.Cu")
		(net "M_H_CPU1_SB_DQ<12>")
	)
	(segment
		(start 193.273426 -209.806794)
		(end 192.44945 -209.806794)
		(width 0.18288)
		(layer "In11.Cu")
		(net "M_H_CPU1_SB_DQ<12>")
	)
	(segment
		(start 146.055334 -225.344736)
		(end 141.712442 -229.687628)
		(width 0.18288)
		(layer "In11.Cu")
		(net "M_H_CPU1_SB_DQ<12>")
	)
	(segment
		(start 187.541154 -208.791302)
		(end 186.95543 -209.377026)
		(width 0.18288)
		(layer "In11.Cu")
		(net "M_H_CPU1_SB_DQ<12>")
	)
	(segment
		(start 133.538468 -231.39019)
		(end 133.528054 -231.396286)
		(width 0.088646)
		(layer "In11.Cu")
		(net "M_H_CPU1_SB_DQ<12>")
	)
	(segment
		(start 166.07663 -210.302348)
		(end 165.88359 -210.109308)
		(width 0.18288)
		(layer "In11.Cu")
		(net "M_H_CPU1_SB_DQ<12>")
	)
	(segment
		(start 166.07663 -210.869276)
		(end 166.07663 -210.302348)
		(width 0.18288)
		(layer "In11.Cu")
		(net "M_H_CPU1_SB_DQ<12>")
	)
	(arc
		(start 124.125482 -232.03027)
		(mid 123.982321 -231.976836)
		(end 123.83008 -231.963722)
		(width 0.088646)
		(layer "In11.Cu")
		(net "M_H_CPU1_SB_DQ<12>")
	)
	(arc
		(start 132.03301 -231.39019)
		(mid 131.845812 -231.340047)
		(end 131.658614 -231.39019)
		(width 0.088646)
		(layer "In11.Cu")
		(net "M_H_CPU1_SB_DQ<12>")
	)
	(arc
		(start 132.598414 -231.39019)
		(mid 132.315712 -231.465932)
		(end 132.03301 -231.39019)
		(width 0.088646)
		(layer "In11.Cu")
		(net "M_H_CPU1_SB_DQ<12>")
	)
	(arc
		(start 125.63729 -231.771952)
		(mid 125.579134 -231.922065)
		(end 125.4633 -232.033826)
		(width 0.088646)
		(layer "In11.Cu")
		(net "M_H_CPU1_SB_DQ<12>")
	)
	(arc
		(start 132.97281 -231.39019)
		(mid 132.785612 -231.340047)
		(end 132.598414 -231.39019)
		(width 0.088646)
		(layer "In11.Cu")
		(net "M_H_CPU1_SB_DQ<12>")
	)
	(arc
		(start 129.7686 -231.396286)
		(mid 129.490422 -231.465978)
		(end 129.213864 -231.39019)
		(width 0.088646)
		(layer "In11.Cu")
		(net "M_H_CPU1_SB_DQ<12>")
	)
	(arc
		(start 131.09321 -231.39019)
		(mid 130.906012 -231.340047)
		(end 130.718814 -231.39019)
		(width 0.088646)
		(layer "In11.Cu")
		(net "M_H_CPU1_SB_DQ<12>")
	)
	(arc
		(start 123.83008 -231.963722)
		(mid 123.660026 -231.936433)
		(end 123.515628 -231.842564)
		(width 0.088646)
		(layer "In11.Cu")
		(net "M_H_CPU1_SB_DQ<12>")
	)
	(arc
		(start 125.45441 -232.038906)
		(mid 125.267212 -232.089049)
		(end 125.080014 -232.038906)
		(width 0.088646)
		(layer "In11.Cu")
		(net "M_H_CPU1_SB_DQ<12>")
	)
	(arc
		(start 138.698478 -230.5812)
		(mid 138.567564 -230.71756)
		(end 138.519916 -230.900478)
		(width 0.088646)
		(layer "In11.Cu")
		(net "M_H_CPU1_SB_DQ<12>")
	)
	(arc
		(start 138.519916 -230.91902)
		(mid 138.439754 -231.191209)
		(end 138.237468 -231.39019)
		(width 0.088646)
		(layer "In11.Cu")
		(net "M_H_CPU1_SB_DQ<12>")
	)
	(arc
		(start 135.792464 -231.39019)
		(mid 135.605266 -231.340047)
		(end 135.418068 -231.39019)
		(width 0.088646)
		(layer "In11.Cu")
		(net "M_H_CPU1_SB_DQ<12>")
	)
	(arc
		(start 129.213864 -231.39019)
		(mid 129.026666 -231.340047)
		(end 128.839468 -231.39019)
		(width 0.088646)
		(layer "In11.Cu")
		(net "M_H_CPU1_SB_DQ<12>")
	)
	(arc
		(start 136.732264 -231.39019)
		(mid 136.545066 -231.340047)
		(end 136.357868 -231.39019)
		(width 0.088646)
		(layer "In11.Cu")
		(net "M_H_CPU1_SB_DQ<12>")
	)
	(arc
		(start 137.297668 -231.39019)
		(mid 137.014966 -231.465932)
		(end 136.732264 -231.39019)
		(width 0.088646)
		(layer "In11.Cu")
		(net "M_H_CPU1_SB_DQ<12>")
	)
	(arc
		(start 127.884682 -231.398826)
		(mid 127.608241 -231.465992)
		(end 127.33401 -231.39019)
		(width 0.088646)
		(layer "In11.Cu")
		(net "M_H_CPU1_SB_DQ<12>")
	)
	(arc
		(start 133.912864 -231.39019)
		(mid 133.725666 -231.340047)
		(end 133.538468 -231.39019)
		(width 0.088646)
		(layer "In11.Cu")
		(net "M_H_CPU1_SB_DQ<12>")
	)
	(arc
		(start 125.63729 -231.771444)
		(mid 125.63729 -231.771698)
		(end 125.63729 -231.771952)
		(width 0.088646)
		(layer "In11.Cu")
		(net "M_H_CPU1_SB_DQ<12>")
	)
	(arc
		(start 128.27381 -231.39019)
		(mid 128.086612 -231.340047)
		(end 127.899414 -231.39019)
		(width 0.088646)
		(layer "In11.Cu")
		(net "M_H_CPU1_SB_DQ<12>")
	)
	(arc
		(start 134.478268 -231.39019)
		(mid 134.195566 -231.465932)
		(end 133.912864 -231.39019)
		(width 0.088646)
		(layer "In11.Cu")
		(net "M_H_CPU1_SB_DQ<12>")
	)
	(arc
		(start 131.643882 -231.398826)
		(mid 131.367441 -231.465992)
		(end 131.09321 -231.39019)
		(width 0.088646)
		(layer "In11.Cu")
		(net "M_H_CPU1_SB_DQ<12>")
	)
	(arc
		(start 130.15341 -231.39019)
		(mid 129.966212 -231.340047)
		(end 129.779014 -231.39019)
		(width 0.088646)
		(layer "In11.Cu")
		(net "M_H_CPU1_SB_DQ<12>")
	)
	(arc
		(start 137.672064 -231.39019)
		(mid 137.484866 -231.340047)
		(end 137.297668 -231.39019)
		(width 0.088646)
		(layer "In11.Cu")
		(net "M_H_CPU1_SB_DQ<12>")
	)
	(arc
		(start 135.418068 -231.39019)
		(mid 135.135366 -231.465932)
		(end 134.852664 -231.39019)
		(width 0.088646)
		(layer "In11.Cu")
		(net "M_H_CPU1_SB_DQ<12>")
	)
	(arc
		(start 126.944882 -231.398826)
		(mid 126.668441 -231.465992)
		(end 126.39421 -231.39019)
		(width 0.088646)
		(layer "In11.Cu")
		(net "M_H_CPU1_SB_DQ<12>")
	)
	(arc
		(start 125.662944 -231.65562)
		(mid 125.647967 -231.697794)
		(end 125.640846 -231.74198)
		(width 0.088646)
		(layer "In11.Cu")
		(net "M_H_CPU1_SB_DQ<12>")
	)
	(arc
		(start 136.357868 -231.39019)
		(mid 136.075166 -231.465932)
		(end 135.792464 -231.39019)
		(width 0.088646)
		(layer "In11.Cu")
		(net "M_H_CPU1_SB_DQ<12>")
	)
	(arc
		(start 133.528054 -231.396286)
		(mid 133.249622 -231.4661)
		(end 132.97281 -231.39019)
		(width 0.088646)
		(layer "In11.Cu")
		(net "M_H_CPU1_SB_DQ<12>")
	)
	(arc
		(start 125.065282 -232.03027)
		(mid 124.788807 -231.96295)
		(end 124.51461 -232.038906)
		(width 0.088646)
		(layer "In11.Cu")
		(net "M_H_CPU1_SB_DQ<12>")
	)
	(arc
		(start 125.77318 -231.534716)
		(mid 125.708839 -231.586763)
		(end 125.662944 -231.65562)
		(width 0.088646)
		(layer "In11.Cu")
		(net "M_H_CPU1_SB_DQ<12>")
	)
	(arc
		(start 130.704082 -231.398826)
		(mid 130.427641 -231.465992)
		(end 130.15341 -231.39019)
		(width 0.088646)
		(layer "In11.Cu")
		(net "M_H_CPU1_SB_DQ<12>")
	)
	(arc
		(start 126.39421 -231.39019)
		(mid 126.207012 -231.340047)
		(end 126.019814 -231.39019)
		(width 0.088646)
		(layer "In11.Cu")
		(net "M_H_CPU1_SB_DQ<12>")
	)
	(arc
		(start 124.51461 -232.038906)
		(mid 124.327412 -232.089049)
		(end 124.140214 -232.038906)
		(width 0.088646)
		(layer "In11.Cu")
		(net "M_H_CPU1_SB_DQ<12>")
	)
	(arc
		(start 127.33401 -231.39019)
		(mid 127.146812 -231.340047)
		(end 126.959614 -231.39019)
		(width 0.088646)
		(layer "In11.Cu")
		(net "M_H_CPU1_SB_DQ<12>")
	)
	(arc
		(start 134.852664 -231.39019)
		(mid 134.665466 -231.340047)
		(end 134.478268 -231.39019)
		(width 0.088646)
		(layer "In11.Cu")
		(net "M_H_CPU1_SB_DQ<12>")
	)
	(arc
		(start 138.237468 -231.39019)
		(mid 137.954766 -231.465932)
		(end 137.672064 -231.39019)
		(width 0.088646)
		(layer "In11.Cu")
		(net "M_H_CPU1_SB_DQ<12>")
	)
	(arc
		(start 125.640846 -231.74198)
		(mid 125.639356 -231.756747)
		(end 125.63729 -231.771444)
		(width 0.088646)
		(layer "In11.Cu")
		(net "M_H_CPU1_SB_DQ<12>")
	)
	(arc
		(start 128.829054 -231.396286)
		(mid 128.550622 -231.4661)
		(end 128.27381 -231.39019)
		(width 0.088646)
		(layer "In11.Cu")
		(net "M_H_CPU1_SB_DQ<12>")
	)
	(segment
		(start 209.874358 -220.266768)
		(end 210.306412 -220.698822)
		(width 0.20066)
		(layer "F.Cu")
		(net "M_H_CPU1_SB_DQ<11>")
	)
	(segment
		(start 212.630258 -220.703902)
		(end 213.311486 -220.703902)
		(width 0.20066)
		(layer "F.Cu")
		(net "M_H_CPU1_SB_DQ<11>")
	)
	(segment
		(start 125.267212 -233.877866)
		(end 125.267212 -233.34218)
		(width 0.20066)
		(layer "F.Cu")
		(net "M_H_CPU1_SB_DQ<11>")
	)
	(segment
		(start 214.385652 -220.266768)
		(end 215.719914 -220.266768)
		(width 0.20066)
		(layer "F.Cu")
		(net "M_H_CPU1_SB_DQ<11>")
	)
	(segment
		(start 213.515448 -220.248988)
		(end 213.749636 -220.0148)
		(width 0.20066)
		(layer "F.Cu")
		(net "M_H_CPU1_SB_DQ<11>")
	)
	(segment
		(start 210.610196 -220.69171)
		(end 212.618066 -220.69171)
		(width 0.1016)
		(layer "F.Cu")
		(net "M_H_CPU1_SB_DQ<11>")
	)
	(segment
		(start 213.515448 -220.49994)
		(end 213.515448 -220.248988)
		(width 0.20066)
		(layer "F.Cu")
		(net "M_H_CPU1_SB_DQ<11>")
	)
	(segment
		(start 125.267466 -233.87812)
		(end 125.267212 -233.877866)
		(width 0.20066)
		(layer "F.Cu")
		(net "M_H_CPU1_SB_DQ<11>")
	)
	(segment
		(start 214.133684 -220.0148)
		(end 214.385652 -220.266768)
		(width 0.20066)
		(layer "F.Cu")
		(net "M_H_CPU1_SB_DQ<11>")
	)
	(segment
		(start 208.176114 -220.266768)
		(end 209.874358 -220.266768)
		(width 0.20066)
		(layer "F.Cu")
		(net "M_H_CPU1_SB_DQ<11>")
	)
	(segment
		(start 212.618066 -220.69171)
		(end 212.630258 -220.703902)
		(width 0.1016)
		(layer "F.Cu")
		(net "M_H_CPU1_SB_DQ<11>")
	)
	(segment
		(start 210.603084 -220.698822)
		(end 210.610196 -220.69171)
		(width 0.1016)
		(layer "F.Cu")
		(net "M_H_CPU1_SB_DQ<11>")
	)
	(segment
		(start 207.071214 -220.266768)
		(end 208.176114 -220.266768)
		(width 0.20066)
		(layer "F.Cu")
		(net "M_H_CPU1_SB_DQ<11>")
	)
	(segment
		(start 213.749636 -220.0148)
		(end 214.133684 -220.0148)
		(width 0.20066)
		(layer "F.Cu")
		(net "M_H_CPU1_SB_DQ<11>")
	)
	(segment
		(start 210.306412 -220.698822)
		(end 210.598258 -220.698822)
		(width 0.20066)
		(layer "F.Cu")
		(net "M_H_CPU1_SB_DQ<11>")
	)
	(segment
		(start 213.311486 -220.703902)
		(end 213.515448 -220.49994)
		(width 0.20066)
		(layer "F.Cu")
		(net "M_H_CPU1_SB_DQ<11>")
	)
	(segment
		(start 210.598258 -220.698822)
		(end 210.603084 -220.698822)
		(width 0.101854)
		(layer "F.Cu")
		(net "M_H_CPU1_SB_DQ<11>")
	)
	(segment
		(start 155.720796 -216.311734)
		(end 155.720796 -217.854022)
		(width 0.18288)
		(layer "In11.Cu")
		(net "M_H_CPU1_SB_DQ<11>")
	)
	(segment
		(start 176.30902 -214.883238)
		(end 174.330614 -214.883238)
		(width 0.18288)
		(layer "In11.Cu")
		(net "M_H_CPU1_SB_DQ<11>")
	)
	(segment
		(start 206.308706 -219.50426)
		(end 206.005684 -219.201238)
		(width 0.18288)
		(layer "In11.Cu")
		(net "M_H_CPU1_SB_DQ<11>")
	)
	(segment
		(start 164.583872 -214.914226)
		(end 164.408358 -214.738712)
		(width 0.18288)
		(layer "In11.Cu")
		(net "M_H_CPU1_SB_DQ<11>")
	)
	(segment
		(start 187.006738 -213.891114)
		(end 186.8932 -214.004652)
		(width 0.18288)
		(layer "In11.Cu")
		(net "M_H_CPU1_SB_DQ<11>")
	)
	(segment
		(start 179.811426 -213.453472)
		(end 179.214272 -214.050626)
		(width 0.18288)
		(layer "In11.Cu")
		(net "M_H_CPU1_SB_DQ<11>")
	)
	(segment
		(start 161.55924 -214.738712)
		(end 161.358326 -214.939626)
		(width 0.18288)
		(layer "In11.Cu")
		(net "M_H_CPU1_SB_DQ<11>")
	)
	(segment
		(start 157.092904 -214.939626)
		(end 156.743146 -215.289384)
		(width 0.18288)
		(layer "In11.Cu")
		(net "M_H_CPU1_SB_DQ<11>")
	)
	(segment
		(start 195.813426 -216.616026)
		(end 195.330826 -216.616026)
		(width 0.18288)
		(layer "In11.Cu")
		(net "M_H_CPU1_SB_DQ<11>")
	)
	(segment
		(start 125.646942 -233.566462)
		(end 125.53823 -233.566462)
		(width 0.088646)
		(layer "In11.Cu")
		(net "M_H_CPU1_SB_DQ<11>")
	)
	(segment
		(start 190.46571 -214.902542)
		(end 189.786006 -214.902542)
		(width 0.18288)
		(layer "In11.Cu")
		(net "M_H_CPU1_SB_DQ<11>")
	)
	(segment
		(start 173.625002 -215.58885)
		(end 172.156374 -215.58885)
		(width 0.18288)
		(layer "In11.Cu")
		(net "M_H_CPU1_SB_DQ<11>")
	)
	(segment
		(start 157.051756 -215.871044)
		(end 157.051756 -216.14384)
		(width 0.18288)
		(layer "In11.Cu")
		(net "M_H_CPU1_SB_DQ<11>")
	)
	(segment
		(start 127.899414 -233.666538)
		(end 127.884682 -233.657902)
		(width 0.088646)
		(layer "In11.Cu")
		(net "M_H_CPU1_SB_DQ<11>")
	)
	(segment
		(start 204.238606 -219.201238)
		(end 203.597256 -219.842588)
		(width 0.18288)
		(layer "In11.Cu")
		(net "M_H_CPU1_SB_DQ<11>")
	)
	(segment
		(start 181.726332 -212.720936)
		(end 181.533292 -212.527896)
		(width 0.18288)
		(layer "In11.Cu")
		(net "M_H_CPU1_SB_DQ<11>")
	)
	(segment
		(start 193.099944 -214.740744)
		(end 190.627508 -214.740744)
		(width 0.18288)
		(layer "In11.Cu")
		(net "M_H_CPU1_SB_DQ<11>")
	)
	(segment
		(start 156.743146 -215.56218)
		(end 157.051756 -215.871044)
		(width 0.18288)
		(layer "In11.Cu")
		(net "M_H_CPU1_SB_DQ<11>")
	)
	(segment
		(start 186.8932 -214.004652)
		(end 186.234578 -214.004652)
		(width 0.18288)
		(layer "In11.Cu")
		(net "M_H_CPU1_SB_DQ<11>")
	)
	(segment
		(start 203.0349 -219.842588)
		(end 203.034138 -219.841826)
		(width 0.18288)
		(layer "In11.Cu")
		(net "M_H_CPU1_SB_DQ<11>")
	)
	(segment
		(start 155.720796 -217.854022)
		(end 148.487892 -225.086926)
		(width 0.18288)
		(layer "In11.Cu")
		(net "M_H_CPU1_SB_DQ<11>")
	)
	(segment
		(start 185.337958 -213.811612)
		(end 185.144918 -214.004652)
		(width 0.18288)
		(layer "In11.Cu")
		(net "M_H_CPU1_SB_DQ<11>")
	)
	(segment
		(start 176.451514 -214.740744)
		(end 176.30902 -214.883238)
		(width 0.18288)
		(layer "In11.Cu")
		(net "M_H_CPU1_SB_DQ<11>")
	)
	(segment
		(start 186.041538 -213.503002)
		(end 185.848498 -213.309962)
		(width 0.18288)
		(layer "In11.Cu")
		(net "M_H_CPU1_SB_DQ<11>")
	)
	(segment
		(start 181.533292 -212.527896)
		(end 181.215792 -212.527896)
		(width 0.18288)
		(layer "In11.Cu")
		(net "M_H_CPU1_SB_DQ<11>")
	)
	(segment
		(start 202.138026 -219.841826)
		(end 202.024742 -219.95511)
		(width 0.18288)
		(layer "In11.Cu")
		(net "M_H_CPU1_SB_DQ<11>")
	)
	(segment
		(start 140.372338 -231.902762)
		(end 140.20038 -231.902762)
		(width 0.088646)
		(layer "In11.Cu")
		(net "M_H_CPU1_SB_DQ<11>")
	)
	(segment
		(start 189.786006 -214.902542)
		(end 188.774578 -213.891114)
		(width 0.18288)
		(layer "In11.Cu")
		(net "M_H_CPU1_SB_DQ<11>")
	)
	(segment
		(start 164.408358 -214.738712)
		(end 161.55924 -214.738712)
		(width 0.18288)
		(layer "In11.Cu")
		(net "M_H_CPU1_SB_DQ<11>")
	)
	(segment
		(start 207.071214 -220.266768)
		(end 206.501746 -220.266768)
		(width 0.18288)
		(layer "In11.Cu")
		(net "M_H_CPU1_SB_DQ<11>")
	)
	(segment
		(start 186.234578 -214.004652)
		(end 186.041538 -213.811612)
		(width 0.18288)
		(layer "In11.Cu")
		(net "M_H_CPU1_SB_DQ<11>")
	)
	(segment
		(start 203.034138 -219.841826)
		(end 202.138026 -219.841826)
		(width 0.18288)
		(layer "In11.Cu")
		(net "M_H_CPU1_SB_DQ<11>")
	)
	(segment
		(start 197.439026 -218.241626)
		(end 195.813426 -216.616026)
		(width 0.18288)
		(layer "In11.Cu")
		(net "M_H_CPU1_SB_DQ<11>")
	)
	(segment
		(start 185.848498 -213.309962)
		(end 185.530998 -213.309962)
		(width 0.18288)
		(layer "In11.Cu")
		(net "M_H_CPU1_SB_DQ<11>")
	)
	(segment
		(start 140.20038 -231.902762)
		(end 140.040614 -232.062528)
		(width 0.088646)
		(layer "In11.Cu")
		(net "M_H_CPU1_SB_DQ<11>")
	)
	(segment
		(start 128.839468 -233.666538)
		(end 128.829054 -233.660442)
		(width 0.088646)
		(layer "In11.Cu")
		(net "M_H_CPU1_SB_DQ<11>")
	)
	(segment
		(start 156.743146 -215.289384)
		(end 156.743146 -215.56218)
		(width 0.18288)
		(layer "In11.Cu")
		(net "M_H_CPU1_SB_DQ<11>")
	)
	(segment
		(start 180.829712 -213.453472)
		(end 179.811426 -213.453472)
		(width 0.18288)
		(layer "In11.Cu")
		(net "M_H_CPU1_SB_DQ<11>")
	)
	(segment
		(start 181.215792 -212.527896)
		(end 181.022752 -212.720936)
		(width 0.18288)
		(layer "In11.Cu")
		(net "M_H_CPU1_SB_DQ<11>")
	)
	(segment
		(start 194.010026 -215.650826)
		(end 193.099944 -214.740744)
		(width 0.18288)
		(layer "In11.Cu")
		(net "M_H_CPU1_SB_DQ<11>")
	)
	(segment
		(start 194.365626 -215.650826)
		(end 194.010026 -215.650826)
		(width 0.18288)
		(layer "In11.Cu")
		(net "M_H_CPU1_SB_DQ<11>")
	)
	(segment
		(start 178.471322 -214.050626)
		(end 177.781204 -214.740744)
		(width 0.18288)
		(layer "In11.Cu")
		(net "M_H_CPU1_SB_DQ<11>")
	)
	(segment
		(start 185.337958 -213.503002)
		(end 185.337958 -213.811612)
		(width 0.18288)
		(layer "In11.Cu")
		(net "M_H_CPU1_SB_DQ<11>")
	)
	(segment
		(start 156.55417 -216.36863)
		(end 156.24556 -216.059766)
		(width 0.18288)
		(layer "In11.Cu")
		(net "M_H_CPU1_SB_DQ<11>")
	)
	(segment
		(start 155.972764 -216.059766)
		(end 155.720796 -216.311734)
		(width 0.18288)
		(layer "In11.Cu")
		(net "M_H_CPU1_SB_DQ<11>")
	)
	(segment
		(start 156.24556 -216.059766)
		(end 155.972764 -216.059766)
		(width 0.18288)
		(layer "In11.Cu")
		(net "M_H_CPU1_SB_DQ<11>")
	)
	(segment
		(start 128.274318 -233.666538)
		(end 128.27381 -233.666538)
		(width 0.088646)
		(layer "In11.Cu")
		(net "M_H_CPU1_SB_DQ<11>")
	)
	(segment
		(start 140.040614 -232.062528)
		(end 140.040614 -232.12425)
		(width 0.088646)
		(layer "In11.Cu")
		(net "M_H_CPU1_SB_DQ<11>")
	)
	(segment
		(start 186.041538 -213.811612)
		(end 186.041538 -213.503002)
		(width 0.18288)
		(layer "In11.Cu")
		(net "M_H_CPU1_SB_DQ<11>")
	)
	(segment
		(start 177.781204 -214.740744)
		(end 176.451514 -214.740744)
		(width 0.18288)
		(layer "In11.Cu")
		(net "M_H_CPU1_SB_DQ<11>")
	)
	(segment
		(start 188.774578 -213.891114)
		(end 187.006738 -213.891114)
		(width 0.18288)
		(layer "In11.Cu")
		(net "M_H_CPU1_SB_DQ<11>")
	)
	(segment
		(start 183.011826 -213.453472)
		(end 181.919372 -213.453472)
		(width 0.18288)
		(layer "In11.Cu")
		(net "M_H_CPU1_SB_DQ<11>")
	)
	(segment
		(start 181.726332 -213.260432)
		(end 181.726332 -212.720936)
		(width 0.18288)
		(layer "In11.Cu")
		(net "M_H_CPU1_SB_DQ<11>")
	)
	(segment
		(start 203.597256 -219.842588)
		(end 203.0349 -219.842588)
		(width 0.18288)
		(layer "In11.Cu")
		(net "M_H_CPU1_SB_DQ<11>")
	)
	(segment
		(start 200.72731 -219.95511)
		(end 199.013826 -218.241626)
		(width 0.18288)
		(layer "In11.Cu")
		(net "M_H_CPU1_SB_DQ<11>")
	)
	(segment
		(start 202.024742 -219.95511)
		(end 200.72731 -219.95511)
		(width 0.18288)
		(layer "In11.Cu")
		(net "M_H_CPU1_SB_DQ<11>")
	)
	(segment
		(start 131.658868 -233.666538)
		(end 131.644136 -233.657902)
		(width 0.088646)
		(layer "In11.Cu")
		(net "M_H_CPU1_SB_DQ<11>")
	)
	(segment
		(start 126.959614 -233.666538)
		(end 126.945136 -233.657902)
		(width 0.088646)
		(layer "In11.Cu")
		(net "M_H_CPU1_SB_DQ<11>")
	)
	(segment
		(start 156.826966 -216.36863)
		(end 156.55417 -216.36863)
		(width 0.18288)
		(layer "In11.Cu")
		(net "M_H_CPU1_SB_DQ<11>")
	)
	(segment
		(start 132.973064 -233.666538)
		(end 132.973318 -233.666538)
		(width 0.088646)
		(layer "In11.Cu")
		(net "M_H_CPU1_SB_DQ<11>")
	)
	(segment
		(start 132.043678 -233.660442)
		(end 132.033264 -233.666538)
		(width 0.088646)
		(layer "In11.Cu")
		(net "M_H_CPU1_SB_DQ<11>")
	)
	(segment
		(start 174.330614 -214.883238)
		(end 173.625002 -215.58885)
		(width 0.18288)
		(layer "In11.Cu")
		(net "M_H_CPU1_SB_DQ<11>")
	)
	(segment
		(start 206.501746 -220.266768)
		(end 206.308706 -220.073728)
		(width 0.18288)
		(layer "In11.Cu")
		(net "M_H_CPU1_SB_DQ<11>")
	)
	(segment
		(start 183.563006 -214.004652)
		(end 183.011826 -213.453472)
		(width 0.18288)
		(layer "In11.Cu")
		(net "M_H_CPU1_SB_DQ<11>")
	)
	(segment
		(start 129.779268 -233.666538)
		(end 129.764536 -233.657902)
		(width 0.088646)
		(layer "In11.Cu")
		(net "M_H_CPU1_SB_DQ<11>")
	)
	(segment
		(start 172.018198 -215.727026)
		(end 168.90619 -215.727026)
		(width 0.18288)
		(layer "In11.Cu")
		(net "M_H_CPU1_SB_DQ<11>")
	)
	(segment
		(start 161.358326 -214.939626)
		(end 157.092904 -214.939626)
		(width 0.18288)
		(layer "In11.Cu")
		(net "M_H_CPU1_SB_DQ<11>")
	)
	(segment
		(start 181.022752 -213.260432)
		(end 180.829712 -213.453472)
		(width 0.18288)
		(layer "In11.Cu")
		(net "M_H_CPU1_SB_DQ<11>")
	)
	(segment
		(start 157.051756 -216.14384)
		(end 156.826966 -216.36863)
		(width 0.18288)
		(layer "In11.Cu")
		(net "M_H_CPU1_SB_DQ<11>")
	)
	(segment
		(start 168.90619 -215.727026)
		(end 168.09339 -214.914226)
		(width 0.18288)
		(layer "In11.Cu")
		(net "M_H_CPU1_SB_DQ<11>")
	)
	(segment
		(start 185.530998 -213.309962)
		(end 185.337958 -213.503002)
		(width 0.18288)
		(layer "In11.Cu")
		(net "M_H_CPU1_SB_DQ<11>")
	)
	(segment
		(start 138.447272 -233.717592)
		(end 138.425174 -233.717592)
		(width 0.088646)
		(layer "In11.Cu")
		(net "M_H_CPU1_SB_DQ<11>")
	)
	(segment
		(start 168.09339 -214.914226)
		(end 164.583872 -214.914226)
		(width 0.18288)
		(layer "In11.Cu")
		(net "M_H_CPU1_SB_DQ<11>")
	)
	(segment
		(start 206.005684 -219.201238)
		(end 204.238606 -219.201238)
		(width 0.18288)
		(layer "In11.Cu")
		(net "M_H_CPU1_SB_DQ<11>")
	)
	(segment
		(start 195.330826 -216.616026)
		(end 194.365626 -215.650826)
		(width 0.18288)
		(layer "In11.Cu")
		(net "M_H_CPU1_SB_DQ<11>")
	)
	(segment
		(start 181.022752 -212.720936)
		(end 181.022752 -213.260432)
		(width 0.18288)
		(layer "In11.Cu")
		(net "M_H_CPU1_SB_DQ<11>")
	)
	(segment
		(start 142.57782 -231.902762)
		(end 140.372338 -231.902762)
		(width 0.18288)
		(layer "In11.Cu")
		(net "M_H_CPU1_SB_DQ<11>")
	)
	(segment
		(start 206.308706 -220.073728)
		(end 206.308706 -219.50426)
		(width 0.18288)
		(layer "In11.Cu")
		(net "M_H_CPU1_SB_DQ<11>")
	)
	(segment
		(start 140.040614 -232.12425)
		(end 138.447272 -233.717592)
		(width 0.088646)
		(layer "In11.Cu")
		(net "M_H_CPU1_SB_DQ<11>")
	)
	(segment
		(start 199.013826 -218.241626)
		(end 197.439026 -218.241626)
		(width 0.18288)
		(layer "In11.Cu")
		(net "M_H_CPU1_SB_DQ<11>")
	)
	(segment
		(start 148.487892 -225.086926)
		(end 148.487892 -225.99269)
		(width 0.18288)
		(layer "In11.Cu")
		(net "M_H_CPU1_SB_DQ<11>")
	)
	(segment
		(start 125.458474 -233.533442)
		(end 125.267212 -233.34218)
		(width 0.088646)
		(layer "In11.Cu")
		(net "M_H_CPU1_SB_DQ<11>")
	)
	(segment
		(start 190.627508 -214.740744)
		(end 190.46571 -214.902542)
		(width 0.18288)
		(layer "In11.Cu")
		(net "M_H_CPU1_SB_DQ<11>")
	)
	(segment
		(start 148.487892 -225.99269)
		(end 142.57782 -231.902762)
		(width 0.18288)
		(layer "In11.Cu")
		(net "M_H_CPU1_SB_DQ<11>")
	)
	(segment
		(start 172.156374 -215.58885)
		(end 172.018198 -215.727026)
		(width 0.18288)
		(layer "In11.Cu")
		(net "M_H_CPU1_SB_DQ<11>")
	)
	(segment
		(start 181.919372 -213.453472)
		(end 181.726332 -213.260432)
		(width 0.18288)
		(layer "In11.Cu")
		(net "M_H_CPU1_SB_DQ<11>")
	)
	(segment
		(start 179.214272 -214.050626)
		(end 178.471322 -214.050626)
		(width 0.18288)
		(layer "In11.Cu")
		(net "M_H_CPU1_SB_DQ<11>")
	)
	(segment
		(start 130.719068 -233.666538)
		(end 130.704336 -233.657902)
		(width 0.088646)
		(layer "In11.Cu")
		(net "M_H_CPU1_SB_DQ<11>")
	)
	(segment
		(start 185.144918 -214.004652)
		(end 183.563006 -214.004652)
		(width 0.18288)
		(layer "In11.Cu")
		(net "M_H_CPU1_SB_DQ<11>")
	)
	(arc
		(start 131.093464 -233.666538)
		(mid 130.906266 -233.716681)
		(end 130.719068 -233.666538)
		(width 0.088646)
		(layer "In11.Cu")
		(net "M_H_CPU1_SB_DQ<11>")
	)
	(arc
		(start 125.53823 -233.566462)
		(mid 125.495072 -233.557877)
		(end 125.458474 -233.533442)
		(width 0.088646)
		(layer "In11.Cu")
		(net "M_H_CPU1_SB_DQ<11>")
	)
	(arc
		(start 129.764536 -233.657902)
		(mid 129.488061 -233.590582)
		(end 129.213864 -233.666538)
		(width 0.088646)
		(layer "In11.Cu")
		(net "M_H_CPU1_SB_DQ<11>")
	)
	(arc
		(start 128.829054 -233.660442)
		(mid 128.550876 -233.590719)
		(end 128.274318 -233.666538)
		(width 0.088646)
		(layer "In11.Cu")
		(net "M_H_CPU1_SB_DQ<11>")
	)
	(arc
		(start 130.704336 -233.657902)
		(mid 130.427861 -233.590582)
		(end 130.153664 -233.666538)
		(width 0.088646)
		(layer "In11.Cu")
		(net "M_H_CPU1_SB_DQ<11>")
	)
	(arc
		(start 136.357868 -233.666538)
		(mid 136.075166 -233.590796)
		(end 135.792464 -233.666538)
		(width 0.088646)
		(layer "In11.Cu")
		(net "M_H_CPU1_SB_DQ<11>")
	)
	(arc
		(start 135.792464 -233.666538)
		(mid 135.605266 -233.716681)
		(end 135.418068 -233.666538)
		(width 0.088646)
		(layer "In11.Cu")
		(net "M_H_CPU1_SB_DQ<11>")
	)
	(arc
		(start 127.884682 -233.657902)
		(mid 127.608241 -233.590736)
		(end 127.33401 -233.666538)
		(width 0.088646)
		(layer "In11.Cu")
		(net "M_H_CPU1_SB_DQ<11>")
	)
	(arc
		(start 138.237468 -233.666538)
		(mid 137.954766 -233.590796)
		(end 137.672064 -233.666538)
		(width 0.088646)
		(layer "In11.Cu")
		(net "M_H_CPU1_SB_DQ<11>")
	)
	(arc
		(start 132.598922 -233.666538)
		(mid 132.322109 -233.590668)
		(end 132.043678 -233.660442)
		(width 0.088646)
		(layer "In11.Cu")
		(net "M_H_CPU1_SB_DQ<11>")
	)
	(arc
		(start 137.297668 -233.666538)
		(mid 137.014966 -233.590796)
		(end 136.732264 -233.666538)
		(width 0.088646)
		(layer "In11.Cu")
		(net "M_H_CPU1_SB_DQ<11>")
	)
	(arc
		(start 131.644136 -233.657902)
		(mid 131.367661 -233.590582)
		(end 131.093464 -233.666538)
		(width 0.088646)
		(layer "In11.Cu")
		(net "M_H_CPU1_SB_DQ<11>")
	)
	(arc
		(start 128.27381 -233.666538)
		(mid 128.086612 -233.716681)
		(end 127.899414 -233.666538)
		(width 0.088646)
		(layer "In11.Cu")
		(net "M_H_CPU1_SB_DQ<11>")
	)
	(arc
		(start 126.945136 -233.657902)
		(mid 126.668661 -233.590582)
		(end 126.394464 -233.666538)
		(width 0.088646)
		(layer "In11.Cu")
		(net "M_H_CPU1_SB_DQ<11>")
	)
	(arc
		(start 129.213864 -233.666538)
		(mid 129.026666 -233.716681)
		(end 128.839468 -233.666538)
		(width 0.088646)
		(layer "In11.Cu")
		(net "M_H_CPU1_SB_DQ<11>")
	)
	(arc
		(start 133.912864 -233.666538)
		(mid 133.725666 -233.716681)
		(end 133.538468 -233.666538)
		(width 0.088646)
		(layer "In11.Cu")
		(net "M_H_CPU1_SB_DQ<11>")
	)
	(arc
		(start 126.020068 -233.666538)
		(mid 125.840097 -233.591927)
		(end 125.646942 -233.566462)
		(width 0.088646)
		(layer "In11.Cu")
		(net "M_H_CPU1_SB_DQ<11>")
	)
	(arc
		(start 132.973318 -233.666538)
		(mid 132.78612 -233.716681)
		(end 132.598922 -233.666538)
		(width 0.088646)
		(layer "In11.Cu")
		(net "M_H_CPU1_SB_DQ<11>")
	)
	(arc
		(start 134.478268 -233.666538)
		(mid 134.195566 -233.590796)
		(end 133.912864 -233.666538)
		(width 0.088646)
		(layer "In11.Cu")
		(net "M_H_CPU1_SB_DQ<11>")
	)
	(arc
		(start 127.33401 -233.666538)
		(mid 127.146812 -233.716681)
		(end 126.959614 -233.666538)
		(width 0.088646)
		(layer "In11.Cu")
		(net "M_H_CPU1_SB_DQ<11>")
	)
	(arc
		(start 130.153664 -233.666538)
		(mid 129.966466 -233.716681)
		(end 129.779268 -233.666538)
		(width 0.088646)
		(layer "In11.Cu")
		(net "M_H_CPU1_SB_DQ<11>")
	)
	(arc
		(start 134.852664 -233.666538)
		(mid 134.665466 -233.716681)
		(end 134.478268 -233.666538)
		(width 0.088646)
		(layer "In11.Cu")
		(net "M_H_CPU1_SB_DQ<11>")
	)
	(arc
		(start 137.672064 -233.666538)
		(mid 137.484866 -233.716681)
		(end 137.297668 -233.666538)
		(width 0.088646)
		(layer "In11.Cu")
		(net "M_H_CPU1_SB_DQ<11>")
	)
	(arc
		(start 138.425174 -233.717592)
		(mid 138.327962 -233.704428)
		(end 138.237468 -233.666538)
		(width 0.088646)
		(layer "In11.Cu")
		(net "M_H_CPU1_SB_DQ<11>")
	)
	(arc
		(start 136.732264 -233.666538)
		(mid 136.545066 -233.716681)
		(end 136.357868 -233.666538)
		(width 0.088646)
		(layer "In11.Cu")
		(net "M_H_CPU1_SB_DQ<11>")
	)
	(arc
		(start 135.418068 -233.666538)
		(mid 135.135366 -233.590796)
		(end 134.852664 -233.666538)
		(width 0.088646)
		(layer "In11.Cu")
		(net "M_H_CPU1_SB_DQ<11>")
	)
	(arc
		(start 132.033264 -233.666538)
		(mid 131.846066 -233.716681)
		(end 131.658868 -233.666538)
		(width 0.088646)
		(layer "In11.Cu")
		(net "M_H_CPU1_SB_DQ<11>")
	)
	(arc
		(start 133.538468 -233.666538)
		(mid 133.255766 -233.590796)
		(end 132.973064 -233.666538)
		(width 0.088646)
		(layer "In11.Cu")
		(net "M_H_CPU1_SB_DQ<11>")
	)
	(arc
		(start 126.394464 -233.666538)
		(mid 126.207266 -233.716681)
		(end 126.020068 -233.666538)
		(width 0.088646)
		(layer "In11.Cu")
		(net "M_H_CPU1_SB_DQ<11>")
	)
	(segment
		(start 212.618066 -222.391732)
		(end 212.630258 -222.403924)
		(width 0.1016)
		(layer "F.Cu")
		(net "M_H_CPU1_SB_DQ<10>")
	)
	(segment
		(start 214.385652 -221.96679)
		(end 215.719914 -221.96679)
		(width 0.20066)
		(layer "F.Cu")
		(net "M_H_CPU1_SB_DQ<10>")
	)
	(segment
		(start 208.176114 -221.96679)
		(end 209.874358 -221.96679)
		(width 0.20066)
		(layer "F.Cu")
		(net "M_H_CPU1_SB_DQ<10>")
	)
	(segment
		(start 209.874358 -221.96679)
		(end 210.306412 -222.398844)
		(width 0.20066)
		(layer "F.Cu")
		(net "M_H_CPU1_SB_DQ<10>")
	)
	(segment
		(start 214.133684 -221.714822)
		(end 214.385652 -221.96679)
		(width 0.20066)
		(layer "F.Cu")
		(net "M_H_CPU1_SB_DQ<10>")
	)
	(segment
		(start 210.603084 -222.398844)
		(end 210.610196 -222.391732)
		(width 0.1016)
		(layer "F.Cu")
		(net "M_H_CPU1_SB_DQ<10>")
	)
	(segment
		(start 207.071214 -221.96679)
		(end 208.176114 -221.96679)
		(width 0.20066)
		(layer "F.Cu")
		(net "M_H_CPU1_SB_DQ<10>")
	)
	(segment
		(start 210.598258 -222.398844)
		(end 210.603084 -222.398844)
		(width 0.101854)
		(layer "F.Cu")
		(net "M_H_CPU1_SB_DQ<10>")
	)
	(segment
		(start 124.797566 -234.691936)
		(end 124.797566 -234.15625)
		(width 0.20066)
		(layer "F.Cu")
		(net "M_H_CPU1_SB_DQ<10>")
	)
	(segment
		(start 124.797312 -234.69219)
		(end 124.797566 -234.691936)
		(width 0.20066)
		(layer "F.Cu")
		(net "M_H_CPU1_SB_DQ<10>")
	)
	(segment
		(start 210.610196 -222.391732)
		(end 212.618066 -222.391732)
		(width 0.1016)
		(layer "F.Cu")
		(net "M_H_CPU1_SB_DQ<10>")
	)
	(segment
		(start 213.311486 -222.403924)
		(end 213.515448 -222.199962)
		(width 0.20066)
		(layer "F.Cu")
		(net "M_H_CPU1_SB_DQ<10>")
	)
	(segment
		(start 213.515448 -221.94901)
		(end 213.749636 -221.714822)
		(width 0.20066)
		(layer "F.Cu")
		(net "M_H_CPU1_SB_DQ<10>")
	)
	(segment
		(start 213.515448 -222.199962)
		(end 213.515448 -221.94901)
		(width 0.20066)
		(layer "F.Cu")
		(net "M_H_CPU1_SB_DQ<10>")
	)
	(segment
		(start 213.749636 -221.714822)
		(end 214.133684 -221.714822)
		(width 0.20066)
		(layer "F.Cu")
		(net "M_H_CPU1_SB_DQ<10>")
	)
	(segment
		(start 212.630258 -222.403924)
		(end 213.311486 -222.403924)
		(width 0.20066)
		(layer "F.Cu")
		(net "M_H_CPU1_SB_DQ<10>")
	)
	(segment
		(start 210.306412 -222.398844)
		(end 210.598258 -222.398844)
		(width 0.20066)
		(layer "F.Cu")
		(net "M_H_CPU1_SB_DQ<10>")
	)
	(segment
		(start 187.980066 -215.589866)
		(end 187.822078 -215.589612)
		(width 0.18288)
		(layer "In11.Cu")
		(net "M_H_CPU1_SB_DQ<10>")
	)
	(segment
		(start 196.397626 -219.410026)
		(end 194.543426 -217.555826)
		(width 0.18288)
		(layer "In11.Cu")
		(net "M_H_CPU1_SB_DQ<10>")
	)
	(segment
		(start 154.175968 -221.582742)
		(end 153.959052 -221.365572)
		(width 0.18288)
		(layer "In11.Cu")
		(net "M_H_CPU1_SB_DQ<10>")
	)
	(segment
		(start 138.512296 -234.404662)
		(end 138.424666 -234.404662)
		(width 0.088646)
		(layer "In11.Cu")
		(net "M_H_CPU1_SB_DQ<10>")
	)
	(segment
		(start 184.231026 -215.727026)
		(end 183.977026 -215.473026)
		(width 0.18288)
		(layer "In11.Cu")
		(net "M_H_CPU1_SB_DQ<10>")
	)
	(segment
		(start 153.686256 -221.365572)
		(end 153.461466 -221.590362)
		(width 0.18288)
		(layer "In11.Cu")
		(net "M_H_CPU1_SB_DQ<10>")
	)
	(segment
		(start 173.726856 -217.290396)
		(end 172.409612 -217.290396)
		(width 0.18288)
		(layer "In11.Cu")
		(net "M_H_CPU1_SB_DQ<10>")
	)
	(segment
		(start 154.456638 -220.867986)
		(end 154.673554 -221.085156)
		(width 0.18288)
		(layer "In11.Cu")
		(net "M_H_CPU1_SB_DQ<10>")
	)
	(segment
		(start 181.732428 -215.666066)
		(end 181.732428 -215.919812)
		(width 0.18288)
		(layer "In11.Cu")
		(net "M_H_CPU1_SB_DQ<10>")
	)
	(segment
		(start 143.071342 -232.960164)
		(end 140.163296 -232.960164)
		(width 0.18288)
		(layer "In11.Cu")
		(net "M_H_CPU1_SB_DQ<10>")
	)
	(segment
		(start 207.071214 -221.96679)
		(end 206.593186 -221.489524)
		(width 0.18288)
		(layer "In11.Cu")
		(net "M_H_CPU1_SB_DQ<10>")
	)
	(segment
		(start 198.074026 -219.410026)
		(end 196.397626 -219.410026)
		(width 0.18288)
		(layer "In11.Cu")
		(net "M_H_CPU1_SB_DQ<10>")
	)
	(segment
		(start 170.827954 -217.001852)
		(end 170.634914 -216.808812)
		(width 0.18288)
		(layer "In11.Cu")
		(net "M_H_CPU1_SB_DQ<10>")
	)
	(segment
		(start 125.555756 -234.48391)
		(end 125.549914 -234.480608)
		(width 0.088646)
		(layer "In11.Cu")
		(net "M_H_CPU1_SB_DQ<10>")
	)
	(segment
		(start 202.24242 -221.542356)
		(end 202.241658 -221.541594)
		(width 0.18288)
		(layer "In11.Cu")
		(net "M_H_CPU1_SB_DQ<10>")
	)
	(segment
		(start 126.879096 -234.471972)
		(end 126.864364 -234.480608)
		(width 0.088646)
		(layer "In11.Cu")
		(net "M_H_CPU1_SB_DQ<10>")
	)
	(segment
		(start 174.385986 -216.631266)
		(end 173.726856 -217.290396)
		(width 0.18288)
		(layer "In11.Cu")
		(net "M_H_CPU1_SB_DQ<10>")
	)
	(segment
		(start 162.790886 -217.046556)
		(end 162.597846 -216.853516)
		(width 0.18288)
		(layer "In11.Cu")
		(net "M_H_CPU1_SB_DQ<10>")
	)
	(segment
		(start 187.165742 -215.727026)
		(end 184.231026 -215.727026)
		(width 0.18288)
		(layer "In11.Cu")
		(net "M_H_CPU1_SB_DQ<10>")
	)
	(segment
		(start 154.673554 -221.085156)
		(end 154.673554 -221.357952)
		(width 0.18288)
		(layer "In11.Cu")
		(net "M_H_CPU1_SB_DQ<10>")
	)
	(segment
		(start 169.133266 -217.545666)
		(end 168.278048 -216.690448)
		(width 0.18288)
		(layer "In11.Cu")
		(net "M_H_CPU1_SB_DQ<10>")
	)
	(segment
		(start 140.163296 -232.960164)
		(end 139.956794 -232.960164)
		(width 0.088646)
		(layer "In11.Cu")
		(net "M_H_CPU1_SB_DQ<10>")
	)
	(segment
		(start 127.818896 -234.471972)
		(end 127.804164 -234.480608)
		(width 0.088646)
		(layer "In11.Cu")
		(net "M_H_CPU1_SB_DQ<10>")
	)
	(segment
		(start 160.581848 -216.668604)
		(end 159.362902 -216.668604)
		(width 0.18288)
		(layer "In11.Cu")
		(net "M_H_CPU1_SB_DQ<10>")
	)
	(segment
		(start 187.303156 -215.589612)
		(end 187.165742 -215.727026)
		(width 0.18288)
		(layer "In11.Cu")
		(net "M_H_CPU1_SB_DQ<10>")
	)
	(segment
		(start 172.409612 -217.290396)
		(end 172.154342 -217.545666)
		(width 0.18288)
		(layer "In11.Cu")
		(net "M_H_CPU1_SB_DQ<10>")
	)
	(segment
		(start 181.028848 -215.666066)
		(end 180.835808 -215.473026)
		(width 0.18288)
		(layer "In11.Cu")
		(net "M_H_CPU1_SB_DQ<10>")
	)
	(segment
		(start 181.539388 -216.112852)
		(end 181.221888 -216.112852)
		(width 0.18288)
		(layer "In11.Cu")
		(net "M_H_CPU1_SB_DQ<10>")
	)
	(segment
		(start 163.301426 -216.853516)
		(end 163.108386 -217.046556)
		(width 0.18288)
		(layer "In11.Cu")
		(net "M_H_CPU1_SB_DQ<10>")
	)
	(segment
		(start 181.221888 -216.112852)
		(end 181.028848 -215.919812)
		(width 0.18288)
		(layer "In11.Cu")
		(net "M_H_CPU1_SB_DQ<10>")
	)
	(segment
		(start 194.543426 -217.555826)
		(end 194.238626 -217.555826)
		(width 0.18288)
		(layer "In11.Cu")
		(net "M_H_CPU1_SB_DQ<10>")
	)
	(segment
		(start 129.693924 -234.474512)
		(end 129.68351 -234.480608)
		(width 0.088646)
		(layer "In11.Cu")
		(net "M_H_CPU1_SB_DQ<10>")
	)
	(segment
		(start 159.362902 -216.668604)
		(end 155.443936 -220.58757)
		(width 0.18288)
		(layer "In11.Cu")
		(net "M_H_CPU1_SB_DQ<10>")
	)
	(segment
		(start 193.123058 -216.440258)
		(end 190.981838 -216.440258)
		(width 0.18288)
		(layer "In11.Cu")
		(net "M_H_CPU1_SB_DQ<10>")
	)
	(segment
		(start 180.835808 -215.473026)
		(end 179.829714 -215.473026)
		(width 0.18288)
		(layer "In11.Cu")
		(net "M_H_CPU1_SB_DQ<10>")
	)
	(segment
		(start 162.597846 -216.580466)
		(end 162.404806 -216.387426)
		(width 0.18288)
		(layer "In11.Cu")
		(net "M_H_CPU1_SB_DQ<10>")
	)
	(segment
		(start 181.028848 -215.919812)
		(end 181.028848 -215.666066)
		(width 0.18288)
		(layer "In11.Cu")
		(net "M_H_CPU1_SB_DQ<10>")
	)
	(segment
		(start 132.517896 -234.471972)
		(end 132.503164 -234.480608)
		(width 0.088646)
		(layer "In11.Cu")
		(net "M_H_CPU1_SB_DQ<10>")
	)
	(segment
		(start 153.678382 -222.353124)
		(end 143.071342 -232.960164)
		(width 0.18288)
		(layer "In11.Cu")
		(net "M_H_CPU1_SB_DQ<10>")
	)
	(segment
		(start 172.154342 -217.545666)
		(end 171.020994 -217.545666)
		(width 0.18288)
		(layer "In11.Cu")
		(net "M_H_CPU1_SB_DQ<10>")
	)
	(segment
		(start 130.638296 -234.471972)
		(end 130.623564 -234.480608)
		(width 0.088646)
		(layer "In11.Cu")
		(net "M_H_CPU1_SB_DQ<10>")
	)
	(segment
		(start 170.827954 -217.352626)
		(end 170.827954 -217.001852)
		(width 0.18288)
		(layer "In11.Cu")
		(net "M_H_CPU1_SB_DQ<10>")
	)
	(segment
		(start 153.461466 -221.590362)
		(end 153.461466 -221.863158)
		(width 0.18288)
		(layer "In11.Cu")
		(net "M_H_CPU1_SB_DQ<10>")
	)
	(segment
		(start 170.634914 -216.808812)
		(end 170.317414 -216.808812)
		(width 0.18288)
		(layer "In11.Cu")
		(net "M_H_CPU1_SB_DQ<10>")
	)
	(segment
		(start 176.232058 -216.442036)
		(end 176.042828 -216.631266)
		(width 0.18288)
		(layer "In11.Cu")
		(net "M_H_CPU1_SB_DQ<10>")
	)
	(segment
		(start 204.350874 -222.246444)
		(end 204.157834 -222.439484)
		(width 0.18288)
		(layer "In11.Cu")
		(net "M_H_CPU1_SB_DQ<10>")
	)
	(segment
		(start 187.822078 -215.589612)
		(end 187.303156 -215.589612)
		(width 0.18288)
		(layer "In11.Cu")
		(net "M_H_CPU1_SB_DQ<10>")
	)
	(segment
		(start 178.856132 -216.446608)
		(end 176.955958 -216.442544)
		(width 0.18288)
		(layer "In11.Cu")
		(net "M_H_CPU1_SB_DQ<10>")
	)
	(segment
		(start 164.760148 -216.690448)
		(end 164.457126 -216.387426)
		(width 0.18288)
		(layer "In11.Cu")
		(net "M_H_CPU1_SB_DQ<10>")
	)
	(segment
		(start 199.775826 -220.553026)
		(end 199.217026 -220.553026)
		(width 0.18288)
		(layer "In11.Cu")
		(net "M_H_CPU1_SB_DQ<10>")
	)
	(segment
		(start 170.317414 -216.808812)
		(end 170.124374 -217.001852)
		(width 0.18288)
		(layer "In11.Cu")
		(net "M_H_CPU1_SB_DQ<10>")
	)
	(segment
		(start 124.610114 -234.480608)
		(end 124.605034 -234.477814)
		(width 0.088646)
		(layer "In11.Cu")
		(net "M_H_CPU1_SB_DQ<10>")
	)
	(segment
		(start 136.277096 -234.471972)
		(end 136.262364 -234.480608)
		(width 0.088646)
		(layer "In11.Cu")
		(net "M_H_CPU1_SB_DQ<10>")
	)
	(segment
		(start 183.977026 -215.473026)
		(end 181.925468 -215.473026)
		(width 0.18288)
		(layer "In11.Cu")
		(net "M_H_CPU1_SB_DQ<10>")
	)
	(segment
		(start 203.454254 -221.542356)
		(end 202.24242 -221.542356)
		(width 0.18288)
		(layer "In11.Cu")
		(net "M_H_CPU1_SB_DQ<10>")
	)
	(segment
		(start 171.020994 -217.545666)
		(end 170.827954 -217.352626)
		(width 0.18288)
		(layer "In11.Cu")
		(net "M_H_CPU1_SB_DQ<10>")
	)
	(segment
		(start 163.494466 -216.387426)
		(end 163.301426 -216.580466)
		(width 0.18288)
		(layer "In11.Cu")
		(net "M_H_CPU1_SB_DQ<10>")
	)
	(segment
		(start 199.217026 -220.553026)
		(end 198.074026 -219.410026)
		(width 0.18288)
		(layer "In11.Cu")
		(net "M_H_CPU1_SB_DQ<10>")
	)
	(segment
		(start 170.124374 -217.352626)
		(end 169.931334 -217.545666)
		(width 0.18288)
		(layer "In11.Cu")
		(net "M_H_CPU1_SB_DQ<10>")
	)
	(segment
		(start 179.829714 -215.473026)
		(end 178.856132 -216.446608)
		(width 0.18288)
		(layer "In11.Cu")
		(net "M_H_CPU1_SB_DQ<10>")
	)
	(segment
		(start 154.954224 -220.3704)
		(end 154.681428 -220.3704)
		(width 0.18288)
		(layer "In11.Cu")
		(net "M_H_CPU1_SB_DQ<10>")
	)
	(segment
		(start 176.841404 -216.442036)
		(end 176.232058 -216.442036)
		(width 0.18288)
		(layer "In11.Cu")
		(net "M_H_CPU1_SB_DQ<10>")
	)
	(segment
		(start 153.678382 -222.080328)
		(end 153.678382 -222.353124)
		(width 0.18288)
		(layer "In11.Cu")
		(net "M_H_CPU1_SB_DQ<10>")
	)
	(segment
		(start 176.841658 -216.44229)
		(end 176.841404 -216.442036)
		(width 0.18288)
		(layer "In11.Cu")
		(net "M_H_CPU1_SB_DQ<10>")
	)
	(segment
		(start 124.615956 -234.48391)
		(end 124.610114 -234.480608)
		(width 0.088646)
		(layer "In11.Cu")
		(net "M_H_CPU1_SB_DQ<10>")
	)
	(segment
		(start 204.596492 -221.489778)
		(end 204.350874 -221.735396)
		(width 0.18288)
		(layer "In11.Cu")
		(net "M_H_CPU1_SB_DQ<10>")
	)
	(segment
		(start 206.593186 -221.489524)
		(end 206.34706 -221.489778)
		(width 0.18288)
		(layer "In11.Cu")
		(net "M_H_CPU1_SB_DQ<10>")
	)
	(segment
		(start 162.404806 -216.387426)
		(end 160.863026 -216.387426)
		(width 0.18288)
		(layer "In11.Cu")
		(net "M_H_CPU1_SB_DQ<10>")
	)
	(segment
		(start 204.157834 -222.439484)
		(end 203.840334 -222.439484)
		(width 0.18288)
		(layer "In11.Cu")
		(net "M_H_CPU1_SB_DQ<10>")
	)
	(segment
		(start 128.754378 -234.474512)
		(end 128.743964 -234.480608)
		(width 0.088646)
		(layer "In11.Cu")
		(net "M_H_CPU1_SB_DQ<10>")
	)
	(segment
		(start 176.042828 -216.631266)
		(end 174.385986 -216.631266)
		(width 0.18288)
		(layer "In11.Cu")
		(net "M_H_CPU1_SB_DQ<10>")
	)
	(segment
		(start 124.484638 -234.15625)
		(end 124.797566 -234.15625)
		(width 0.088646)
		(layer "In11.Cu")
		(net "M_H_CPU1_SB_DQ<10>")
	)
	(segment
		(start 164.457126 -216.387426)
		(end 163.494466 -216.387426)
		(width 0.18288)
		(layer "In11.Cu")
		(net "M_H_CPU1_SB_DQ<10>")
	)
	(segment
		(start 154.448764 -221.582742)
		(end 154.175968 -221.582742)
		(width 0.18288)
		(layer "In11.Cu")
		(net "M_H_CPU1_SB_DQ<10>")
	)
	(segment
		(start 124.427234 -234.213654)
		(end 124.484638 -234.15625)
		(width 0.088646)
		(layer "In11.Cu")
		(net "M_H_CPU1_SB_DQ<10>")
	)
	(segment
		(start 176.955958 -216.442544)
		(end 176.841658 -216.44229)
		(width 0.18288)
		(layer "In11.Cu")
		(net "M_H_CPU1_SB_DQ<10>")
	)
	(segment
		(start 188.69152 -215.589866)
		(end 187.980066 -215.589866)
		(width 0.18288)
		(layer "In11.Cu")
		(net "M_H_CPU1_SB_DQ<10>")
	)
	(segment
		(start 200.893426 -221.670626)
		(end 199.775826 -220.553026)
		(width 0.18288)
		(layer "In11.Cu")
		(net "M_H_CPU1_SB_DQ<10>")
	)
	(segment
		(start 170.124374 -217.001852)
		(end 170.124374 -217.352626)
		(width 0.18288)
		(layer "In11.Cu")
		(net "M_H_CPU1_SB_DQ<10>")
	)
	(segment
		(start 169.931334 -217.545666)
		(end 169.133266 -217.545666)
		(width 0.18288)
		(layer "In11.Cu")
		(net "M_H_CPU1_SB_DQ<10>")
	)
	(segment
		(start 155.17114 -220.58757)
		(end 154.954224 -220.3704)
		(width 0.18288)
		(layer "In11.Cu")
		(net "M_H_CPU1_SB_DQ<10>")
	)
	(segment
		(start 153.959052 -221.365572)
		(end 153.686256 -221.365572)
		(width 0.18288)
		(layer "In11.Cu")
		(net "M_H_CPU1_SB_DQ<10>")
	)
	(segment
		(start 203.840334 -222.439484)
		(end 203.647294 -222.246444)
		(width 0.18288)
		(layer "In11.Cu")
		(net "M_H_CPU1_SB_DQ<10>")
	)
	(segment
		(start 160.863026 -216.387426)
		(end 160.581848 -216.668604)
		(width 0.18288)
		(layer "In11.Cu")
		(net "M_H_CPU1_SB_DQ<10>")
	)
	(segment
		(start 194.238626 -217.555826)
		(end 193.123058 -216.440258)
		(width 0.18288)
		(layer "In11.Cu")
		(net "M_H_CPU1_SB_DQ<10>")
	)
	(segment
		(start 155.443936 -220.58757)
		(end 155.17114 -220.58757)
		(width 0.18288)
		(layer "In11.Cu")
		(net "M_H_CPU1_SB_DQ<10>")
	)
	(segment
		(start 189.701424 -216.59977)
		(end 188.69152 -215.589866)
		(width 0.18288)
		(layer "In11.Cu")
		(net "M_H_CPU1_SB_DQ<10>")
	)
	(segment
		(start 168.278048 -216.690448)
		(end 164.760148 -216.690448)
		(width 0.18288)
		(layer "In11.Cu")
		(net "M_H_CPU1_SB_DQ<10>")
	)
	(segment
		(start 206.34706 -221.489778)
		(end 204.596492 -221.489778)
		(width 0.18288)
		(layer "In11.Cu")
		(net "M_H_CPU1_SB_DQ<10>")
	)
	(segment
		(start 154.456638 -220.59519)
		(end 154.456638 -220.867986)
		(width 0.18288)
		(layer "In11.Cu")
		(net "M_H_CPU1_SB_DQ<10>")
	)
	(segment
		(start 181.732428 -215.919812)
		(end 181.539388 -216.112852)
		(width 0.18288)
		(layer "In11.Cu")
		(net "M_H_CPU1_SB_DQ<10>")
	)
	(segment
		(start 203.647294 -222.246444)
		(end 203.647294 -221.735396)
		(width 0.18288)
		(layer "In11.Cu")
		(net "M_H_CPU1_SB_DQ<10>")
	)
	(segment
		(start 154.681428 -220.3704)
		(end 154.456638 -220.59519)
		(width 0.18288)
		(layer "In11.Cu")
		(net "M_H_CPU1_SB_DQ<10>")
	)
	(segment
		(start 125.549914 -234.480608)
		(end 125.544072 -234.477052)
		(width 0.088646)
		(layer "In11.Cu")
		(net "M_H_CPU1_SB_DQ<10>")
	)
	(segment
		(start 190.822326 -216.59977)
		(end 189.701424 -216.59977)
		(width 0.18288)
		(layer "In11.Cu")
		(net "M_H_CPU1_SB_DQ<10>")
	)
	(segment
		(start 163.108386 -217.046556)
		(end 162.790886 -217.046556)
		(width 0.18288)
		(layer "In11.Cu")
		(net "M_H_CPU1_SB_DQ<10>")
	)
	(segment
		(start 162.597846 -216.853516)
		(end 162.597846 -216.580466)
		(width 0.18288)
		(layer "In11.Cu")
		(net "M_H_CPU1_SB_DQ<10>")
	)
	(segment
		(start 153.461466 -221.863158)
		(end 153.678382 -222.080328)
		(width 0.18288)
		(layer "In11.Cu")
		(net "M_H_CPU1_SB_DQ<10>")
	)
	(segment
		(start 154.673554 -221.357952)
		(end 154.448764 -221.582742)
		(width 0.18288)
		(layer "In11.Cu")
		(net "M_H_CPU1_SB_DQ<10>")
	)
	(segment
		(start 190.981838 -216.440258)
		(end 190.822326 -216.59977)
		(width 0.18288)
		(layer "In11.Cu")
		(net "M_H_CPU1_SB_DQ<10>")
	)
	(segment
		(start 125.939296 -234.471972)
		(end 125.924564 -234.480608)
		(width 0.088646)
		(layer "In11.Cu")
		(net "M_H_CPU1_SB_DQ<10>")
	)
	(segment
		(start 181.925468 -215.473026)
		(end 181.732428 -215.666066)
		(width 0.18288)
		(layer "In11.Cu")
		(net "M_H_CPU1_SB_DQ<10>")
	)
	(segment
		(start 163.301426 -216.580466)
		(end 163.301426 -216.853516)
		(width 0.18288)
		(layer "In11.Cu")
		(net "M_H_CPU1_SB_DQ<10>")
	)
	(segment
		(start 202.241658 -221.541594)
		(end 202.112626 -221.670626)
		(width 0.18288)
		(layer "In11.Cu")
		(net "M_H_CPU1_SB_DQ<10>")
	)
	(segment
		(start 202.112626 -221.670626)
		(end 200.893426 -221.670626)
		(width 0.18288)
		(layer "In11.Cu")
		(net "M_H_CPU1_SB_DQ<10>")
	)
	(segment
		(start 139.956794 -232.960164)
		(end 138.512296 -234.404662)
		(width 0.088646)
		(layer "In11.Cu")
		(net "M_H_CPU1_SB_DQ<10>")
	)
	(segment
		(start 203.647294 -221.735396)
		(end 203.454254 -221.542356)
		(width 0.18288)
		(layer "In11.Cu")
		(net "M_H_CPU1_SB_DQ<10>")
	)
	(segment
		(start 204.350874 -221.735396)
		(end 204.350874 -222.246444)
		(width 0.18288)
		(layer "In11.Cu")
		(net "M_H_CPU1_SB_DQ<10>")
	)
	(arc
		(start 133.068568 -234.480608)
		(mid 132.794369 -234.404773)
		(end 132.517896 -234.471972)
		(width 0.088646)
		(layer "In11.Cu")
		(net "M_H_CPU1_SB_DQ<10>")
	)
	(arc
		(start 134.948168 -234.480608)
		(mid 134.665466 -234.404832)
		(end 134.382764 -234.480608)
		(width 0.088646)
		(layer "In11.Cu")
		(net "M_H_CPU1_SB_DQ<10>")
	)
	(arc
		(start 132.128768 -234.480608)
		(mid 131.846066 -234.404832)
		(end 131.563364 -234.480608)
		(width 0.088646)
		(layer "In11.Cu")
		(net "M_H_CPU1_SB_DQ<10>")
	)
	(arc
		(start 137.767568 -234.480608)
		(mid 137.484866 -234.404832)
		(end 137.202164 -234.480608)
		(width 0.088646)
		(layer "In11.Cu")
		(net "M_H_CPU1_SB_DQ<10>")
	)
	(arc
		(start 131.188968 -234.480608)
		(mid 130.914769 -234.404773)
		(end 130.638296 -234.471972)
		(width 0.088646)
		(layer "In11.Cu")
		(net "M_H_CPU1_SB_DQ<10>")
	)
	(arc
		(start 136.262364 -234.480608)
		(mid 136.075166 -234.530751)
		(end 135.887968 -234.480608)
		(width 0.088646)
		(layer "In11.Cu")
		(net "M_H_CPU1_SB_DQ<10>")
	)
	(arc
		(start 127.429768 -234.480608)
		(mid 127.155569 -234.404773)
		(end 126.879096 -234.471972)
		(width 0.088646)
		(layer "In11.Cu")
		(net "M_H_CPU1_SB_DQ<10>")
	)
	(arc
		(start 130.249168 -234.480608)
		(mid 129.972355 -234.404738)
		(end 129.693924 -234.474512)
		(width 0.088646)
		(layer "In11.Cu")
		(net "M_H_CPU1_SB_DQ<10>")
	)
	(arc
		(start 136.827768 -234.480608)
		(mid 136.553569 -234.404773)
		(end 136.277096 -234.471972)
		(width 0.088646)
		(layer "In11.Cu")
		(net "M_H_CPU1_SB_DQ<10>")
	)
	(arc
		(start 135.322564 -234.480608)
		(mid 135.135366 -234.530751)
		(end 134.948168 -234.480608)
		(width 0.088646)
		(layer "In11.Cu")
		(net "M_H_CPU1_SB_DQ<10>")
	)
	(arc
		(start 127.804164 -234.480608)
		(mid 127.616966 -234.530751)
		(end 127.429768 -234.480608)
		(width 0.088646)
		(layer "In11.Cu")
		(net "M_H_CPU1_SB_DQ<10>")
	)
	(arc
		(start 124.605034 -234.477814)
		(mid 124.486664 -234.365564)
		(end 124.427234 -234.213654)
		(width 0.088646)
		(layer "In11.Cu")
		(net "M_H_CPU1_SB_DQ<10>")
	)
	(arc
		(start 126.489968 -234.480608)
		(mid 126.215769 -234.404773)
		(end 125.939296 -234.471972)
		(width 0.088646)
		(layer "In11.Cu")
		(net "M_H_CPU1_SB_DQ<10>")
	)
	(arc
		(start 128.743964 -234.480608)
		(mid 128.556766 -234.530751)
		(end 128.369568 -234.480608)
		(width 0.088646)
		(layer "In11.Cu")
		(net "M_H_CPU1_SB_DQ<10>")
	)
	(arc
		(start 137.202164 -234.480608)
		(mid 137.014966 -234.530751)
		(end 136.827768 -234.480608)
		(width 0.088646)
		(layer "In11.Cu")
		(net "M_H_CPU1_SB_DQ<10>")
	)
	(arc
		(start 129.309114 -234.480608)
		(mid 129.032555 -234.404865)
		(end 128.754378 -234.474512)
		(width 0.088646)
		(layer "In11.Cu")
		(net "M_H_CPU1_SB_DQ<10>")
	)
	(arc
		(start 132.503164 -234.480608)
		(mid 132.315966 -234.530751)
		(end 132.128768 -234.480608)
		(width 0.088646)
		(layer "In11.Cu")
		(net "M_H_CPU1_SB_DQ<10>")
	)
	(arc
		(start 129.68351 -234.480608)
		(mid 129.496312 -234.530751)
		(end 129.309114 -234.480608)
		(width 0.088646)
		(layer "In11.Cu")
		(net "M_H_CPU1_SB_DQ<10>")
	)
	(arc
		(start 131.563364 -234.480608)
		(mid 131.376166 -234.530751)
		(end 131.188968 -234.480608)
		(width 0.088646)
		(layer "In11.Cu")
		(net "M_H_CPU1_SB_DQ<10>")
	)
	(arc
		(start 134.382764 -234.480608)
		(mid 134.195566 -234.530751)
		(end 134.008368 -234.480608)
		(width 0.088646)
		(layer "In11.Cu")
		(net "M_H_CPU1_SB_DQ<10>")
	)
	(arc
		(start 134.008368 -234.480608)
		(mid 133.725666 -234.404832)
		(end 133.442964 -234.480608)
		(width 0.088646)
		(layer "In11.Cu")
		(net "M_H_CPU1_SB_DQ<10>")
	)
	(arc
		(start 125.544072 -234.477052)
		(mid 125.263937 -234.404769)
		(end 124.984764 -234.480608)
		(width 0.088646)
		(layer "In11.Cu")
		(net "M_H_CPU1_SB_DQ<10>")
	)
	(arc
		(start 130.623564 -234.480608)
		(mid 130.436366 -234.530751)
		(end 130.249168 -234.480608)
		(width 0.088646)
		(layer "In11.Cu")
		(net "M_H_CPU1_SB_DQ<10>")
	)
	(arc
		(start 126.864364 -234.480608)
		(mid 126.677166 -234.530751)
		(end 126.489968 -234.480608)
		(width 0.088646)
		(layer "In11.Cu")
		(net "M_H_CPU1_SB_DQ<10>")
	)
	(arc
		(start 133.442964 -234.480608)
		(mid 133.255766 -234.530751)
		(end 133.068568 -234.480608)
		(width 0.088646)
		(layer "In11.Cu")
		(net "M_H_CPU1_SB_DQ<10>")
	)
	(arc
		(start 138.141964 -234.480608)
		(mid 137.954766 -234.530751)
		(end 137.767568 -234.480608)
		(width 0.088646)
		(layer "In11.Cu")
		(net "M_H_CPU1_SB_DQ<10>")
	)
	(arc
		(start 138.424666 -234.404662)
		(mid 138.400133 -234.40515)
		(end 138.375644 -234.406694)
		(width 0.088646)
		(layer "In11.Cu")
		(net "M_H_CPU1_SB_DQ<10>")
	)
	(arc
		(start 125.924564 -234.480608)
		(mid 125.74061 -234.530737)
		(end 125.555756 -234.48391)
		(width 0.088646)
		(layer "In11.Cu")
		(net "M_H_CPU1_SB_DQ<10>")
	)
	(arc
		(start 124.984764 -234.480608)
		(mid 124.80081 -234.530737)
		(end 124.615956 -234.48391)
		(width 0.088646)
		(layer "In11.Cu")
		(net "M_H_CPU1_SB_DQ<10>")
	)
	(arc
		(start 128.369568 -234.480608)
		(mid 128.095369 -234.404773)
		(end 127.818896 -234.471972)
		(width 0.088646)
		(layer "In11.Cu")
		(net "M_H_CPU1_SB_DQ<10>")
	)
	(arc
		(start 135.887968 -234.480608)
		(mid 135.605266 -234.404832)
		(end 135.322564 -234.480608)
		(width 0.088646)
		(layer "In11.Cu")
		(net "M_H_CPU1_SB_DQ<10>")
	)
	(arc
		(start 138.375644 -234.406694)
		(mid 138.25474 -234.430813)
		(end 138.141964 -234.480608)
		(width 0.088646)
		(layer "In11.Cu")
		(net "M_H_CPU1_SB_DQ<10>")
	)
	(segment
		(start 209.180176 -231.741726)
		(end 207.018382 -231.741726)
		(width 0.1016)
		(layer "F.Cu")
		(net "M_H_CPU1_SB_DQ<0>")
	)
	(segment
		(start 210.028028 -232.166922)
		(end 209.596482 -231.735376)
		(width 0.20066)
		(layer "F.Cu")
		(net "M_H_CPU1_SB_DQ<0>")
	)
	(segment
		(start 206.971392 -231.741726)
		(end 206.626714 -231.741726)
		(width 0.20066)
		(layer "F.Cu")
		(net "M_H_CPU1_SB_DQ<0>")
	)
	(segment
		(start 206.508604 -231.859836)
		(end 206.508604 -232.227374)
		(width 0.20066)
		(layer "F.Cu")
		(net "M_H_CPU1_SB_DQ<0>")
	)
	(segment
		(start 206.626714 -231.741726)
		(end 206.508604 -231.859836)
		(width 0.20066)
		(layer "F.Cu")
		(net "M_H_CPU1_SB_DQ<0>")
	)
	(segment
		(start 211.619592 -232.166922)
		(end 210.028028 -232.166922)
		(width 0.20066)
		(layer "F.Cu")
		(net "M_H_CPU1_SB_DQ<0>")
	)
	(segment
		(start 209.596482 -231.735376)
		(end 209.186526 -231.735376)
		(width 0.20066)
		(layer "F.Cu")
		(net "M_H_CPU1_SB_DQ<0>")
	)
	(segment
		(start 206.320644 -232.415334)
		(end 205.84541 -232.415334)
		(width 0.20066)
		(layer "F.Cu")
		(net "M_H_CPU1_SB_DQ<0>")
	)
	(segment
		(start 205.84541 -232.415334)
		(end 205.596744 -232.166668)
		(width 0.20066)
		(layer "F.Cu")
		(net "M_H_CPU1_SB_DQ<0>")
	)
	(segment
		(start 211.619846 -232.166668)
		(end 211.619592 -232.166922)
		(width 0.20066)
		(layer "F.Cu")
		(net "M_H_CPU1_SB_DQ<0>")
	)
	(segment
		(start 207.018382 -231.741726)
		(end 206.971392 -231.741726)
		(width 0.101854)
		(layer "F.Cu")
		(net "M_H_CPU1_SB_DQ<0>")
	)
	(segment
		(start 205.596744 -232.166668)
		(end 204.076046 -232.166668)
		(width 0.20066)
		(layer "F.Cu")
		(net "M_H_CPU1_SB_DQ<0>")
	)
	(segment
		(start 123.857512 -239.57534)
		(end 123.857766 -239.575086)
		(width 0.20066)
		(layer "F.Cu")
		(net "M_H_CPU1_SB_DQ<0>")
	)
	(segment
		(start 123.857766 -239.575086)
		(end 123.857766 -239.0394)
		(width 0.20066)
		(layer "F.Cu")
		(net "M_H_CPU1_SB_DQ<0>")
	)
	(segment
		(start 206.508604 -232.227374)
		(end 206.320644 -232.415334)
		(width 0.20066)
		(layer "F.Cu")
		(net "M_H_CPU1_SB_DQ<0>")
	)
	(segment
		(start 209.186526 -231.735376)
		(end 209.180176 -231.741726)
		(width 0.1016)
		(layer "F.Cu")
		(net "M_H_CPU1_SB_DQ<0>")
	)
	(segment
		(start 204.076046 -232.166668)
		(end 202.971146 -232.166668)
		(width 0.20066)
		(layer "F.Cu")
		(net "M_H_CPU1_SB_DQ<0>")
	)
	(segment
		(start 132.598414 -239.528858)
		(end 132.588 -239.534954)
		(width 0.088646)
		(layer "In11.Cu")
		(net "M_H_CPU1_SB_DQ<0>")
	)
	(segment
		(start 183.011826 -228.096826)
		(end 181.263036 -228.096826)
		(width 0.18288)
		(layer "In11.Cu")
		(net "M_H_CPU1_SB_DQ<0>")
	)
	(segment
		(start 135.418068 -239.528858)
		(end 135.407654 -239.534954)
		(width 0.088646)
		(layer "In11.Cu")
		(net "M_H_CPU1_SB_DQ<0>")
	)
	(segment
		(start 172.200824 -229.888034)
		(end 168.647618 -229.888034)
		(width 0.18288)
		(layer "In11.Cu")
		(net "M_H_CPU1_SB_DQ<0>")
	)
	(segment
		(start 188.513974 -229.856538)
		(end 188.513974 -227.683568)
		(width 0.18288)
		(layer "In11.Cu")
		(net "M_H_CPU1_SB_DQ<0>")
	)
	(segment
		(start 126.019814 -239.528858)
		(end 126.0094 -239.534954)
		(width 0.088646)
		(layer "In11.Cu")
		(net "M_H_CPU1_SB_DQ<0>")
	)
	(segment
		(start 180.173376 -228.096826)
		(end 178.31435 -228.096826)
		(width 0.18288)
		(layer "In11.Cu")
		(net "M_H_CPU1_SB_DQ<0>")
	)
	(segment
		(start 125.162818 -239.450626)
		(end 124.566426 -239.450626)
		(width 0.088646)
		(layer "In11.Cu")
		(net "M_H_CPU1_SB_DQ<0>")
	)
	(segment
		(start 159.015938 -230.76789)
		(end 158.04134 -231.742488)
		(width 0.18288)
		(layer "In11.Cu")
		(net "M_H_CPU1_SB_DQ<0>")
	)
	(segment
		(start 186.125104 -227.915216)
		(end 186.125104 -227.683568)
		(width 0.18288)
		(layer "In11.Cu")
		(net "M_H_CPU1_SB_DQ<0>")
	)
	(segment
		(start 192.776856 -229.193852)
		(end 191.498728 -229.193852)
		(width 0.18288)
		(layer "In11.Cu")
		(net "M_H_CPU1_SB_DQ<0>")
	)
	(segment
		(start 174.3456 -228.889052)
		(end 173.191424 -230.043228)
		(width 0.18288)
		(layer "In11.Cu")
		(net "M_H_CPU1_SB_DQ<0>")
	)
	(segment
		(start 184.717944 -227.683568)
		(end 184.524904 -227.490528)
		(width 0.18288)
		(layer "In11.Cu")
		(net "M_H_CPU1_SB_DQ<0>")
	)
	(segment
		(start 134.478014 -239.528858)
		(end 134.4676 -239.534954)
		(width 0.088646)
		(layer "In11.Cu")
		(net "M_H_CPU1_SB_DQ<0>")
	)
	(segment
		(start 196.346826 -230.332026)
		(end 195.407026 -230.332026)
		(width 0.18288)
		(layer "In11.Cu")
		(net "M_H_CPU1_SB_DQ<0>")
	)
	(segment
		(start 186.635644 -228.108256)
		(end 186.318144 -228.108256)
		(width 0.18288)
		(layer "In11.Cu")
		(net "M_H_CPU1_SB_DQ<0>")
	)
	(segment
		(start 185.421524 -227.683568)
		(end 185.421524 -227.915216)
		(width 0.18288)
		(layer "In11.Cu")
		(net "M_H_CPU1_SB_DQ<0>")
	)
	(segment
		(start 180.876956 -228.875336)
		(end 180.559456 -228.875336)
		(width 0.18288)
		(layer "In11.Cu")
		(net "M_H_CPU1_SB_DQ<0>")
	)
	(segment
		(start 130.718814 -239.528858)
		(end 130.704082 -239.537494)
		(width 0.088646)
		(layer "In11.Cu")
		(net "M_H_CPU1_SB_DQ<0>")
	)
	(segment
		(start 141.103096 -239.482884)
		(end 140.601954 -239.482884)
		(width 0.088646)
		(layer "In11.Cu")
		(net "M_H_CPU1_SB_DQ<0>")
	)
	(segment
		(start 137.297414 -239.528858)
		(end 137.282682 -239.537494)
		(width 0.088646)
		(layer "In11.Cu")
		(net "M_H_CPU1_SB_DQ<0>")
	)
	(segment
		(start 181.069996 -228.682296)
		(end 180.876956 -228.875336)
		(width 0.18288)
		(layer "In11.Cu")
		(net "M_H_CPU1_SB_DQ<0>")
	)
	(segment
		(start 180.366416 -228.289866)
		(end 180.173376 -228.096826)
		(width 0.18288)
		(layer "In11.Cu")
		(net "M_H_CPU1_SB_DQ<0>")
	)
	(segment
		(start 146.28114 -239.482884)
		(end 141.103096 -239.482884)
		(width 0.18288)
		(layer "In11.Cu")
		(net "M_H_CPU1_SB_DQ<0>")
	)
	(segment
		(start 131.658868 -239.528858)
		(end 131.648454 -239.534954)
		(width 0.088646)
		(layer "In11.Cu")
		(net "M_H_CPU1_SB_DQ<0>")
	)
	(segment
		(start 124.05868 -239.240314)
		(end 123.857766 -239.0394)
		(width 0.088646)
		(layer "In11.Cu")
		(net "M_H_CPU1_SB_DQ<0>")
	)
	(segment
		(start 138.820144 -239.605058)
		(end 137.955274 -239.605058)
		(width 0.088646)
		(layer "In11.Cu")
		(net "M_H_CPU1_SB_DQ<0>")
	)
	(segment
		(start 173.191424 -230.043228)
		(end 172.356018 -230.043228)
		(width 0.18288)
		(layer "In11.Cu")
		(net "M_H_CPU1_SB_DQ<0>")
	)
	(segment
		(start 136.357614 -239.528858)
		(end 136.3472 -239.534954)
		(width 0.088646)
		(layer "In11.Cu")
		(net "M_H_CPU1_SB_DQ<0>")
	)
	(segment
		(start 186.318144 -228.108256)
		(end 186.125104 -227.915216)
		(width 0.18288)
		(layer "In11.Cu")
		(net "M_H_CPU1_SB_DQ<0>")
	)
	(segment
		(start 172.356018 -230.043228)
		(end 172.200824 -229.888034)
		(width 0.18288)
		(layer "In11.Cu")
		(net "M_H_CPU1_SB_DQ<0>")
	)
	(segment
		(start 193.313558 -229.730554)
		(end 192.776856 -229.193852)
		(width 0.18288)
		(layer "In11.Cu")
		(net "M_H_CPU1_SB_DQ<0>")
	)
	(segment
		(start 161.083498 -230.890826)
		(end 160.960562 -230.76789)
		(width 0.18288)
		(layer "In11.Cu")
		(net "M_H_CPU1_SB_DQ<0>")
	)
	(segment
		(start 133.538468 -239.528858)
		(end 133.528054 -239.534954)
		(width 0.088646)
		(layer "In11.Cu")
		(net "M_H_CPU1_SB_DQ<0>")
	)
	(segment
		(start 187.933838 -227.49256)
		(end 187.814458 -227.49256)
		(width 0.18288)
		(layer "In11.Cu")
		(net "M_H_CPU1_SB_DQ<0>")
	)
	(segment
		(start 186.125104 -227.683568)
		(end 185.932064 -227.490528)
		(width 0.18288)
		(layer "In11.Cu")
		(net "M_H_CPU1_SB_DQ<0>")
	)
	(segment
		(start 138.982196 -239.443006)
		(end 138.820144 -239.605058)
		(width 0.088646)
		(layer "In11.Cu")
		(net "M_H_CPU1_SB_DQ<0>")
	)
	(segment
		(start 185.614564 -227.490528)
		(end 185.421524 -227.683568)
		(width 0.18288)
		(layer "In11.Cu")
		(net "M_H_CPU1_SB_DQ<0>")
	)
	(segment
		(start 187.93587 -227.490528)
		(end 187.933838 -227.49256)
		(width 0.18288)
		(layer "In11.Cu")
		(net "M_H_CPU1_SB_DQ<0>")
	)
	(segment
		(start 176.06518 -229.194106)
		(end 175.760126 -228.889052)
		(width 0.18288)
		(layer "In11.Cu")
		(net "M_H_CPU1_SB_DQ<0>")
	)
	(segment
		(start 185.421524 -227.915216)
		(end 185.228484 -228.108256)
		(width 0.18288)
		(layer "In11.Cu")
		(net "M_H_CPU1_SB_DQ<0>")
	)
	(segment
		(start 165.084252 -230.514652)
		(end 164.546026 -229.976426)
		(width 0.18288)
		(layer "In11.Cu")
		(net "M_H_CPU1_SB_DQ<0>")
	)
	(segment
		(start 196.880226 -230.865426)
		(end 196.346826 -230.332026)
		(width 0.18288)
		(layer "In11.Cu")
		(net "M_H_CPU1_SB_DQ<0>")
	)
	(segment
		(start 184.910984 -228.108256)
		(end 184.717944 -227.915216)
		(width 0.18288)
		(layer "In11.Cu")
		(net "M_H_CPU1_SB_DQ<0>")
	)
	(segment
		(start 162.971226 -230.890826)
		(end 161.083498 -230.890826)
		(width 0.18288)
		(layer "In11.Cu")
		(net "M_H_CPU1_SB_DQ<0>")
	)
	(segment
		(start 185.228484 -228.108256)
		(end 184.910984 -228.108256)
		(width 0.18288)
		(layer "In11.Cu")
		(net "M_H_CPU1_SB_DQ<0>")
	)
	(segment
		(start 186.828684 -227.915216)
		(end 186.635644 -228.108256)
		(width 0.18288)
		(layer "In11.Cu")
		(net "M_H_CPU1_SB_DQ<0>")
	)
	(segment
		(start 126.959614 -239.528858)
		(end 126.944882 -239.537494)
		(width 0.088646)
		(layer "In11.Cu")
		(net "M_H_CPU1_SB_DQ<0>")
	)
	(segment
		(start 185.932064 -227.490528)
		(end 185.614564 -227.490528)
		(width 0.18288)
		(layer "In11.Cu")
		(net "M_H_CPU1_SB_DQ<0>")
	)
	(segment
		(start 202.431904 -231.627426)
		(end 198.734426 -231.627426)
		(width 0.18288)
		(layer "In11.Cu")
		(net "M_H_CPU1_SB_DQ<0>")
	)
	(segment
		(start 140.562076 -239.443006)
		(end 138.982196 -239.443006)
		(width 0.088646)
		(layer "In11.Cu")
		(net "M_H_CPU1_SB_DQ<0>")
	)
	(segment
		(start 175.760126 -228.889052)
		(end 174.3456 -228.889052)
		(width 0.18288)
		(layer "In11.Cu")
		(net "M_H_CPU1_SB_DQ<0>")
	)
	(segment
		(start 180.366416 -228.682296)
		(end 180.366416 -228.289866)
		(width 0.18288)
		(layer "In11.Cu")
		(net "M_H_CPU1_SB_DQ<0>")
	)
	(segment
		(start 197.972426 -230.865426)
		(end 196.880226 -230.865426)
		(width 0.18288)
		(layer "In11.Cu")
		(net "M_H_CPU1_SB_DQ<0>")
	)
	(segment
		(start 189.024514 -230.049578)
		(end 188.707014 -230.049578)
		(width 0.18288)
		(layer "In11.Cu")
		(net "M_H_CPU1_SB_DQ<0>")
	)
	(segment
		(start 180.559456 -228.875336)
		(end 180.366416 -228.682296)
		(width 0.18288)
		(layer "In11.Cu")
		(net "M_H_CPU1_SB_DQ<0>")
	)
	(segment
		(start 184.524904 -227.490528)
		(end 183.618124 -227.490528)
		(width 0.18288)
		(layer "In11.Cu")
		(net "M_H_CPU1_SB_DQ<0>")
	)
	(segment
		(start 191.498728 -229.193852)
		(end 189.795404 -227.490528)
		(width 0.18288)
		(layer "In11.Cu")
		(net "M_H_CPU1_SB_DQ<0>")
	)
	(segment
		(start 183.618124 -227.490528)
		(end 183.011826 -228.096826)
		(width 0.18288)
		(layer "In11.Cu")
		(net "M_H_CPU1_SB_DQ<0>")
	)
	(segment
		(start 189.410594 -227.490528)
		(end 189.217554 -227.683568)
		(width 0.18288)
		(layer "In11.Cu")
		(net "M_H_CPU1_SB_DQ<0>")
	)
	(segment
		(start 128.839214 -239.528858)
		(end 128.824482 -239.537494)
		(width 0.088646)
		(layer "In11.Cu")
		(net "M_H_CPU1_SB_DQ<0>")
	)
	(segment
		(start 187.812426 -227.490528)
		(end 187.021724 -227.490528)
		(width 0.18288)
		(layer "In11.Cu")
		(net "M_H_CPU1_SB_DQ<0>")
	)
	(segment
		(start 189.217554 -227.683568)
		(end 189.217554 -229.856538)
		(width 0.18288)
		(layer "In11.Cu")
		(net "M_H_CPU1_SB_DQ<0>")
	)
	(segment
		(start 187.814458 -227.49256)
		(end 187.812426 -227.490528)
		(width 0.18288)
		(layer "In11.Cu")
		(net "M_H_CPU1_SB_DQ<0>")
	)
	(segment
		(start 181.069996 -228.289866)
		(end 181.069996 -228.682296)
		(width 0.18288)
		(layer "In11.Cu")
		(net "M_H_CPU1_SB_DQ<0>")
	)
	(segment
		(start 140.601954 -239.482884)
		(end 140.562076 -239.443006)
		(width 0.088646)
		(layer "In11.Cu")
		(net "M_H_CPU1_SB_DQ<0>")
	)
	(segment
		(start 163.885626 -229.976426)
		(end 162.971226 -230.890826)
		(width 0.18288)
		(layer "In11.Cu")
		(net "M_H_CPU1_SB_DQ<0>")
	)
	(segment
		(start 195.407026 -230.332026)
		(end 194.805554 -229.730554)
		(width 0.18288)
		(layer "In11.Cu")
		(net "M_H_CPU1_SB_DQ<0>")
	)
	(segment
		(start 194.805554 -229.730554)
		(end 193.313558 -229.730554)
		(width 0.18288)
		(layer "In11.Cu")
		(net "M_H_CPU1_SB_DQ<0>")
	)
	(segment
		(start 187.021724 -227.490528)
		(end 186.828684 -227.683568)
		(width 0.18288)
		(layer "In11.Cu")
		(net "M_H_CPU1_SB_DQ<0>")
	)
	(segment
		(start 127.899414 -239.528858)
		(end 127.884682 -239.537494)
		(width 0.088646)
		(layer "In11.Cu")
		(net "M_H_CPU1_SB_DQ<0>")
	)
	(segment
		(start 160.960562 -230.76789)
		(end 159.015938 -230.76789)
		(width 0.18288)
		(layer "In11.Cu")
		(net "M_H_CPU1_SB_DQ<0>")
	)
	(segment
		(start 189.217554 -229.856538)
		(end 189.024514 -230.049578)
		(width 0.18288)
		(layer "In11.Cu")
		(net "M_H_CPU1_SB_DQ<0>")
	)
	(segment
		(start 164.546026 -229.976426)
		(end 163.885626 -229.976426)
		(width 0.18288)
		(layer "In11.Cu")
		(net "M_H_CPU1_SB_DQ<0>")
	)
	(segment
		(start 168.021 -230.514652)
		(end 165.084252 -230.514652)
		(width 0.18288)
		(layer "In11.Cu")
		(net "M_H_CPU1_SB_DQ<0>")
	)
	(segment
		(start 189.795404 -227.490528)
		(end 189.410594 -227.490528)
		(width 0.18288)
		(layer "In11.Cu")
		(net "M_H_CPU1_SB_DQ<0>")
	)
	(segment
		(start 168.647618 -229.888034)
		(end 168.021 -230.514652)
		(width 0.18288)
		(layer "In11.Cu")
		(net "M_H_CPU1_SB_DQ<0>")
	)
	(segment
		(start 202.971146 -232.166668)
		(end 202.431904 -231.627426)
		(width 0.18288)
		(layer "In11.Cu")
		(net "M_H_CPU1_SB_DQ<0>")
	)
	(segment
		(start 188.513974 -227.683568)
		(end 188.320934 -227.490528)
		(width 0.18288)
		(layer "In11.Cu")
		(net "M_H_CPU1_SB_DQ<0>")
	)
	(segment
		(start 181.263036 -228.096826)
		(end 181.069996 -228.289866)
		(width 0.18288)
		(layer "In11.Cu")
		(net "M_H_CPU1_SB_DQ<0>")
	)
	(segment
		(start 188.320934 -227.490528)
		(end 187.93587 -227.490528)
		(width 0.18288)
		(layer "In11.Cu")
		(net "M_H_CPU1_SB_DQ<0>")
	)
	(segment
		(start 158.04134 -231.742488)
		(end 154.021536 -231.742488)
		(width 0.18288)
		(layer "In11.Cu")
		(net "M_H_CPU1_SB_DQ<0>")
	)
	(segment
		(start 188.707014 -230.049578)
		(end 188.513974 -229.856538)
		(width 0.18288)
		(layer "In11.Cu")
		(net "M_H_CPU1_SB_DQ<0>")
	)
	(segment
		(start 186.828684 -227.683568)
		(end 186.828684 -227.915216)
		(width 0.18288)
		(layer "In11.Cu")
		(net "M_H_CPU1_SB_DQ<0>")
	)
	(segment
		(start 177.21707 -229.194106)
		(end 176.06518 -229.194106)
		(width 0.18288)
		(layer "In11.Cu")
		(net "M_H_CPU1_SB_DQ<0>")
	)
	(segment
		(start 184.717944 -227.915216)
		(end 184.717944 -227.683568)
		(width 0.18288)
		(layer "In11.Cu")
		(net "M_H_CPU1_SB_DQ<0>")
	)
	(segment
		(start 198.734426 -231.627426)
		(end 197.972426 -230.865426)
		(width 0.18288)
		(layer "In11.Cu")
		(net "M_H_CPU1_SB_DQ<0>")
	)
	(segment
		(start 154.021536 -231.742488)
		(end 146.28114 -239.482884)
		(width 0.18288)
		(layer "In11.Cu")
		(net "M_H_CPU1_SB_DQ<0>")
	)
	(segment
		(start 178.31435 -228.096826)
		(end 177.21707 -229.194106)
		(width 0.18288)
		(layer "In11.Cu")
		(net "M_H_CPU1_SB_DQ<0>")
	)
	(arc
		(start 134.85241 -239.528858)
		(mid 134.665212 -239.478715)
		(end 134.478014 -239.528858)
		(width 0.088646)
		(layer "In11.Cu")
		(net "M_H_CPU1_SB_DQ<0>")
	)
	(arc
		(start 128.824482 -239.537494)
		(mid 128.548007 -239.604814)
		(end 128.27381 -239.528858)
		(width 0.088646)
		(layer "In11.Cu")
		(net "M_H_CPU1_SB_DQ<0>")
	)
	(arc
		(start 134.4676 -239.534954)
		(mid 134.189422 -239.604677)
		(end 133.912864 -239.528858)
		(width 0.088646)
		(layer "In11.Cu")
		(net "M_H_CPU1_SB_DQ<0>")
	)
	(arc
		(start 132.588 -239.534954)
		(mid 132.309822 -239.604677)
		(end 132.033264 -239.528858)
		(width 0.088646)
		(layer "In11.Cu")
		(net "M_H_CPU1_SB_DQ<0>")
	)
	(arc
		(start 125.454664 -239.528858)
		(mid 125.313894 -239.470519)
		(end 125.162818 -239.450626)
		(width 0.088646)
		(layer "In11.Cu")
		(net "M_H_CPU1_SB_DQ<0>")
	)
	(arc
		(start 131.09321 -239.528858)
		(mid 130.906012 -239.478715)
		(end 130.718814 -239.528858)
		(width 0.088646)
		(layer "In11.Cu")
		(net "M_H_CPU1_SB_DQ<0>")
	)
	(arc
		(start 126.39421 -239.528858)
		(mid 126.207012 -239.478715)
		(end 126.019814 -239.528858)
		(width 0.088646)
		(layer "In11.Cu")
		(net "M_H_CPU1_SB_DQ<0>")
	)
	(arc
		(start 126.944882 -239.537494)
		(mid 126.668407 -239.604814)
		(end 126.39421 -239.528858)
		(width 0.088646)
		(layer "In11.Cu")
		(net "M_H_CPU1_SB_DQ<0>")
	)
	(arc
		(start 135.792464 -239.528858)
		(mid 135.605266 -239.478715)
		(end 135.418068 -239.528858)
		(width 0.088646)
		(layer "In11.Cu")
		(net "M_H_CPU1_SB_DQ<0>")
	)
	(arc
		(start 133.912864 -239.528858)
		(mid 133.725666 -239.478715)
		(end 133.538468 -239.528858)
		(width 0.088646)
		(layer "In11.Cu")
		(net "M_H_CPU1_SB_DQ<0>")
	)
	(arc
		(start 130.704082 -239.537494)
		(mid 130.427607 -239.604814)
		(end 130.15341 -239.528858)
		(width 0.088646)
		(layer "In11.Cu")
		(net "M_H_CPU1_SB_DQ<0>")
	)
	(arc
		(start 129.779014 -239.528858)
		(mid 129.496312 -239.604634)
		(end 129.21361 -239.528858)
		(width 0.088646)
		(layer "In11.Cu")
		(net "M_H_CPU1_SB_DQ<0>")
	)
	(arc
		(start 132.033264 -239.528858)
		(mid 131.846066 -239.478715)
		(end 131.658868 -239.528858)
		(width 0.088646)
		(layer "In11.Cu")
		(net "M_H_CPU1_SB_DQ<0>")
	)
	(arc
		(start 132.97281 -239.528858)
		(mid 132.785612 -239.478715)
		(end 132.598414 -239.528858)
		(width 0.088646)
		(layer "In11.Cu")
		(net "M_H_CPU1_SB_DQ<0>")
	)
	(arc
		(start 136.3472 -239.534954)
		(mid 136.069022 -239.604677)
		(end 135.792464 -239.528858)
		(width 0.088646)
		(layer "In11.Cu")
		(net "M_H_CPU1_SB_DQ<0>")
	)
	(arc
		(start 130.15341 -239.528858)
		(mid 129.966212 -239.478715)
		(end 129.779014 -239.528858)
		(width 0.088646)
		(layer "In11.Cu")
		(net "M_H_CPU1_SB_DQ<0>")
	)
	(arc
		(start 133.528054 -239.534954)
		(mid 133.249622 -239.6048)
		(end 132.97281 -239.528858)
		(width 0.088646)
		(layer "In11.Cu")
		(net "M_H_CPU1_SB_DQ<0>")
	)
	(arc
		(start 127.884682 -239.537494)
		(mid 127.608207 -239.604814)
		(end 127.33401 -239.528858)
		(width 0.088646)
		(layer "In11.Cu")
		(net "M_H_CPU1_SB_DQ<0>")
	)
	(arc
		(start 124.566426 -239.450626)
		(mid 124.291637 -239.395967)
		(end 124.05868 -239.240314)
		(width 0.088646)
		(layer "In11.Cu")
		(net "M_H_CPU1_SB_DQ<0>")
	)
	(arc
		(start 126.0094 -239.534954)
		(mid 125.731222 -239.604677)
		(end 125.454664 -239.528858)
		(width 0.088646)
		(layer "In11.Cu")
		(net "M_H_CPU1_SB_DQ<0>")
	)
	(arc
		(start 135.407654 -239.534954)
		(mid 135.129222 -239.6048)
		(end 134.85241 -239.528858)
		(width 0.088646)
		(layer "In11.Cu")
		(net "M_H_CPU1_SB_DQ<0>")
	)
	(arc
		(start 137.67181 -239.528858)
		(mid 137.484612 -239.478715)
		(end 137.297414 -239.528858)
		(width 0.088646)
		(layer "In11.Cu")
		(net "M_H_CPU1_SB_DQ<0>")
	)
	(arc
		(start 129.21361 -239.528858)
		(mid 129.026412 -239.478715)
		(end 128.839214 -239.528858)
		(width 0.088646)
		(layer "In11.Cu")
		(net "M_H_CPU1_SB_DQ<0>")
	)
	(arc
		(start 131.648454 -239.534954)
		(mid 131.370022 -239.6048)
		(end 131.09321 -239.528858)
		(width 0.088646)
		(layer "In11.Cu")
		(net "M_H_CPU1_SB_DQ<0>")
	)
	(arc
		(start 127.33401 -239.528858)
		(mid 127.146812 -239.478715)
		(end 126.959614 -239.528858)
		(width 0.088646)
		(layer "In11.Cu")
		(net "M_H_CPU1_SB_DQ<0>")
	)
	(arc
		(start 137.282682 -239.537494)
		(mid 137.006207 -239.604814)
		(end 136.73201 -239.528858)
		(width 0.088646)
		(layer "In11.Cu")
		(net "M_H_CPU1_SB_DQ<0>")
	)
	(arc
		(start 137.955274 -239.605058)
		(mid 137.808509 -239.585678)
		(end 137.67181 -239.528858)
		(width 0.088646)
		(layer "In11.Cu")
		(net "M_H_CPU1_SB_DQ<0>")
	)
	(arc
		(start 128.27381 -239.528858)
		(mid 128.086612 -239.478715)
		(end 127.899414 -239.528858)
		(width 0.088646)
		(layer "In11.Cu")
		(net "M_H_CPU1_SB_DQ<0>")
	)
	(arc
		(start 136.73201 -239.528858)
		(mid 136.544812 -239.478715)
		(end 136.357614 -239.528858)
		(width 0.088646)
		(layer "In11.Cu")
		(net "M_H_CPU1_SB_DQ<0>")
	)
	(segment
		(start 128.556512 -244.458744)
		(end 128.556766 -244.45849)
		(width 0.20066)
		(layer "F.Cu")
		(net "M_H_CPU1_SB_CS_N<3>")
	)
	(segment
		(start 128.556766 -244.45849)
		(end 128.556766 -243.922804)
		(width 0.20066)
		(layer "F.Cu")
		(net "M_H_CPU1_SB_CS_N<3>")
	)
	(segment
		(start 208.176114 -244.916706)
		(end 207.071214 -244.916706)
		(width 0.20066)
		(layer "F.Cu")
		(net "M_H_CPU1_SB_CS_N<3>")
	)
	(segment
		(start 139.96543 -244.895624)
		(end 139.508738 -244.895624)
		(width 0.18288)
		(layer "In6.Cu")
		(net "M_H_CPU1_SB_CS_N<3>")
	)
	(segment
		(start 168.645586 -241.942366)
		(end 167.960294 -241.257074)
		(width 0.18288)
		(layer "In6.Cu")
		(net "M_H_CPU1_SB_CS_N<3>")
	)
	(segment
		(start 207.071214 -244.916706)
		(end 204.986382 -242.831874)
		(width 0.18288)
		(layer "In6.Cu")
		(net "M_H_CPU1_SB_CS_N<3>")
	)
	(segment
		(start 204.563726 -242.831874)
		(end 203.674218 -241.942366)
		(width 0.18288)
		(layer "In6.Cu")
		(net "M_H_CPU1_SB_CS_N<3>")
	)
	(segment
		(start 204.986382 -242.831874)
		(end 204.563726 -242.831874)
		(width 0.18288)
		(layer "In6.Cu")
		(net "M_H_CPU1_SB_CS_N<3>")
	)
	(segment
		(start 132.517896 -244.238526)
		(end 132.503164 -244.247162)
		(width 0.088646)
		(layer "In6.Cu")
		(net "M_H_CPU1_SB_CS_N<3>")
	)
	(segment
		(start 137.114026 -244.352826)
		(end 136.96061 -244.352826)
		(width 0.088646)
		(layer "In6.Cu")
		(net "M_H_CPU1_SB_CS_N<3>")
	)
	(segment
		(start 130.638296 -244.238526)
		(end 130.623564 -244.247162)
		(width 0.088646)
		(layer "In6.Cu")
		(net "M_H_CPU1_SB_CS_N<3>")
	)
	(segment
		(start 199.773794 -241.942366)
		(end 198.259446 -241.942366)
		(width 0.18288)
		(layer "In6.Cu")
		(net "M_H_CPU1_SB_CS_N<3>")
	)
	(segment
		(start 178.554888 -240.478564)
		(end 177.94097 -241.092482)
		(width 0.18288)
		(layer "In6.Cu")
		(net "M_H_CPU1_SB_CS_N<3>")
	)
	(segment
		(start 182.63616 -241.41811)
		(end 180.42763 -241.41811)
		(width 0.18288)
		(layer "In6.Cu")
		(net "M_H_CPU1_SB_CS_N<3>")
	)
	(segment
		(start 137.40257 -244.64137)
		(end 137.310622 -244.549422)
		(width 0.18288)
		(layer "In6.Cu")
		(net "M_H_CPU1_SB_CS_N<3>")
	)
	(segment
		(start 164.922962 -241.257074)
		(end 164.221922 -241.958114)
		(width 0.18288)
		(layer "In6.Cu")
		(net "M_H_CPU1_SB_CS_N<3>")
	)
	(segment
		(start 160.451292 -239.912652)
		(end 157.472888 -239.912652)
		(width 0.18288)
		(layer "In6.Cu")
		(net "M_H_CPU1_SB_CS_N<3>")
	)
	(segment
		(start 128.564894 -243.930932)
		(end 128.556766 -243.922804)
		(width 0.088646)
		(layer "In6.Cu")
		(net "M_H_CPU1_SB_CS_N<3>")
	)
	(segment
		(start 162.244024 -240.461292)
		(end 160.999932 -240.461292)
		(width 0.18288)
		(layer "In6.Cu")
		(net "M_H_CPU1_SB_CS_N<3>")
	)
	(segment
		(start 136.277096 -244.238526)
		(end 136.262364 -244.247162)
		(width 0.088646)
		(layer "In6.Cu")
		(net "M_H_CPU1_SB_CS_N<3>")
	)
	(segment
		(start 197.525386 -241.208306)
		(end 194.878706 -241.208306)
		(width 0.18288)
		(layer "In6.Cu")
		(net "M_H_CPU1_SB_CS_N<3>")
	)
	(segment
		(start 201.995786 -242.196366)
		(end 200.027794 -242.196366)
		(width 0.18288)
		(layer "In6.Cu")
		(net "M_H_CPU1_SB_CS_N<3>")
	)
	(segment
		(start 138.894566 -244.64137)
		(end 137.40257 -244.64137)
		(width 0.18288)
		(layer "In6.Cu")
		(net "M_H_CPU1_SB_CS_N<3>")
	)
	(segment
		(start 177.94097 -241.092482)
		(end 176.235614 -241.092482)
		(width 0.18288)
		(layer "In6.Cu")
		(net "M_H_CPU1_SB_CS_N<3>")
	)
	(segment
		(start 180.42763 -241.41811)
		(end 179.488084 -240.478564)
		(width 0.18288)
		(layer "In6.Cu")
		(net "M_H_CPU1_SB_CS_N<3>")
	)
	(segment
		(start 175.38573 -241.942366)
		(end 168.645586 -241.942366)
		(width 0.18288)
		(layer "In6.Cu")
		(net "M_H_CPU1_SB_CS_N<3>")
	)
	(segment
		(start 137.310622 -244.549422)
		(end 137.114026 -244.352826)
		(width 0.088646)
		(layer "In6.Cu")
		(net "M_H_CPU1_SB_CS_N<3>")
	)
	(segment
		(start 163.740846 -241.958114)
		(end 162.244024 -240.461292)
		(width 0.18288)
		(layer "In6.Cu")
		(net "M_H_CPU1_SB_CS_N<3>")
	)
	(segment
		(start 200.027794 -242.196366)
		(end 199.773794 -241.942366)
		(width 0.18288)
		(layer "In6.Cu")
		(net "M_H_CPU1_SB_CS_N<3>")
	)
	(segment
		(start 202.249786 -241.942366)
		(end 201.995786 -242.196366)
		(width 0.18288)
		(layer "In6.Cu")
		(net "M_H_CPU1_SB_CS_N<3>")
	)
	(segment
		(start 179.488084 -240.478564)
		(end 178.554888 -240.478564)
		(width 0.18288)
		(layer "In6.Cu")
		(net "M_H_CPU1_SB_CS_N<3>")
	)
	(segment
		(start 194.718686 -241.048286)
		(end 193.715386 -241.048286)
		(width 0.18288)
		(layer "In6.Cu")
		(net "M_H_CPU1_SB_CS_N<3>")
	)
	(segment
		(start 192.821306 -241.942366)
		(end 191.393826 -241.942366)
		(width 0.18288)
		(layer "In6.Cu")
		(net "M_H_CPU1_SB_CS_N<3>")
	)
	(segment
		(start 190.543942 -241.092482)
		(end 182.961788 -241.092482)
		(width 0.18288)
		(layer "In6.Cu")
		(net "M_H_CPU1_SB_CS_N<3>")
	)
	(segment
		(start 160.999932 -240.461292)
		(end 160.451292 -239.912652)
		(width 0.18288)
		(layer "In6.Cu")
		(net "M_H_CPU1_SB_CS_N<3>")
	)
	(segment
		(start 134.397496 -244.238526)
		(end 134.382764 -244.247162)
		(width 0.088646)
		(layer "In6.Cu")
		(net "M_H_CPU1_SB_CS_N<3>")
	)
	(segment
		(start 156.588968 -240.796572)
		(end 153.662126 -240.796572)
		(width 0.18288)
		(layer "In6.Cu")
		(net "M_H_CPU1_SB_CS_N<3>")
	)
	(segment
		(start 193.715386 -241.048286)
		(end 192.821306 -241.942366)
		(width 0.18288)
		(layer "In6.Cu")
		(net "M_H_CPU1_SB_CS_N<3>")
	)
	(segment
		(start 129.693924 -244.241066)
		(end 129.68351 -244.247162)
		(width 0.088646)
		(layer "In6.Cu")
		(net "M_H_CPU1_SB_CS_N<3>")
	)
	(segment
		(start 164.221922 -241.958114)
		(end 163.740846 -241.958114)
		(width 0.18288)
		(layer "In6.Cu")
		(net "M_H_CPU1_SB_CS_N<3>")
	)
	(segment
		(start 153.662126 -240.796572)
		(end 150.414482 -244.044216)
		(width 0.18288)
		(layer "In6.Cu")
		(net "M_H_CPU1_SB_CS_N<3>")
	)
	(segment
		(start 194.878706 -241.208306)
		(end 194.718686 -241.048286)
		(width 0.18288)
		(layer "In6.Cu")
		(net "M_H_CPU1_SB_CS_N<3>")
	)
	(segment
		(start 139.508738 -244.895624)
		(end 138.894566 -244.64137)
		(width 0.18288)
		(layer "In6.Cu")
		(net "M_H_CPU1_SB_CS_N<3>")
	)
	(segment
		(start 136.96061 -244.352826)
		(end 136.944608 -244.336824)
		(width 0.088646)
		(layer "In6.Cu")
		(net "M_H_CPU1_SB_CS_N<3>")
	)
	(segment
		(start 191.393826 -241.942366)
		(end 190.543942 -241.092482)
		(width 0.18288)
		(layer "In6.Cu")
		(net "M_H_CPU1_SB_CS_N<3>")
	)
	(segment
		(start 176.235614 -241.092482)
		(end 175.38573 -241.942366)
		(width 0.18288)
		(layer "In6.Cu")
		(net "M_H_CPU1_SB_CS_N<3>")
	)
	(segment
		(start 182.961788 -241.092482)
		(end 182.63616 -241.41811)
		(width 0.18288)
		(layer "In6.Cu")
		(net "M_H_CPU1_SB_CS_N<3>")
	)
	(segment
		(start 157.472888 -239.912652)
		(end 156.588968 -240.796572)
		(width 0.18288)
		(layer "In6.Cu")
		(net "M_H_CPU1_SB_CS_N<3>")
	)
	(segment
		(start 203.674218 -241.942366)
		(end 202.249786 -241.942366)
		(width 0.18288)
		(layer "In6.Cu")
		(net "M_H_CPU1_SB_CS_N<3>")
	)
	(segment
		(start 150.414482 -244.044216)
		(end 140.816838 -244.044216)
		(width 0.18288)
		(layer "In6.Cu")
		(net "M_H_CPU1_SB_CS_N<3>")
	)
	(segment
		(start 140.816838 -244.044216)
		(end 139.96543 -244.895624)
		(width 0.18288)
		(layer "In6.Cu")
		(net "M_H_CPU1_SB_CS_N<3>")
	)
	(segment
		(start 198.259446 -241.942366)
		(end 197.525386 -241.208306)
		(width 0.18288)
		(layer "In6.Cu")
		(net "M_H_CPU1_SB_CS_N<3>")
	)
	(segment
		(start 167.960294 -241.257074)
		(end 164.922962 -241.257074)
		(width 0.18288)
		(layer "In6.Cu")
		(net "M_H_CPU1_SB_CS_N<3>")
	)
	(arc
		(start 129.080514 -244.17401)
		(mid 128.801552 -244.09734)
		(end 128.564894 -243.930932)
		(width 0.088646)
		(layer "In6.Cu")
		(net "M_H_CPU1_SB_CS_N<3>")
	)
	(arc
		(start 130.249168 -244.247162)
		(mid 129.972355 -244.171292)
		(end 129.693924 -244.241066)
		(width 0.088646)
		(layer "In6.Cu")
		(net "M_H_CPU1_SB_CS_N<3>")
	)
	(arc
		(start 135.887968 -244.247162)
		(mid 135.605266 -244.171386)
		(end 135.322564 -244.247162)
		(width 0.088646)
		(layer "In6.Cu")
		(net "M_H_CPU1_SB_CS_N<3>")
	)
	(arc
		(start 134.008368 -244.247162)
		(mid 133.725666 -244.171386)
		(end 133.442964 -244.247162)
		(width 0.088646)
		(layer "In6.Cu")
		(net "M_H_CPU1_SB_CS_N<3>")
	)
	(arc
		(start 135.322564 -244.247162)
		(mid 135.135366 -244.297305)
		(end 134.948168 -244.247162)
		(width 0.088646)
		(layer "In6.Cu")
		(net "M_H_CPU1_SB_CS_N<3>")
	)
	(arc
		(start 133.068568 -244.247162)
		(mid 132.794369 -244.171327)
		(end 132.517896 -244.238526)
		(width 0.088646)
		(layer "In6.Cu")
		(net "M_H_CPU1_SB_CS_N<3>")
	)
	(arc
		(start 133.442964 -244.247162)
		(mid 133.255766 -244.297305)
		(end 133.068568 -244.247162)
		(width 0.088646)
		(layer "In6.Cu")
		(net "M_H_CPU1_SB_CS_N<3>")
	)
	(arc
		(start 131.563364 -244.247162)
		(mid 131.376166 -244.297305)
		(end 131.188968 -244.247162)
		(width 0.088646)
		(layer "In6.Cu")
		(net "M_H_CPU1_SB_CS_N<3>")
	)
	(arc
		(start 134.382764 -244.247162)
		(mid 134.195566 -244.297305)
		(end 134.008368 -244.247162)
		(width 0.088646)
		(layer "In6.Cu")
		(net "M_H_CPU1_SB_CS_N<3>")
	)
	(arc
		(start 134.948168 -244.247162)
		(mid 134.673969 -244.171327)
		(end 134.397496 -244.238526)
		(width 0.088646)
		(layer "In6.Cu")
		(net "M_H_CPU1_SB_CS_N<3>")
	)
	(arc
		(start 129.68351 -244.247162)
		(mid 129.496312 -244.297305)
		(end 129.309114 -244.247162)
		(width 0.088646)
		(layer "In6.Cu")
		(net "M_H_CPU1_SB_CS_N<3>")
	)
	(arc
		(start 129.309114 -244.247162)
		(mid 129.198745 -244.198298)
		(end 129.080514 -244.17401)
		(width 0.088646)
		(layer "In6.Cu")
		(net "M_H_CPU1_SB_CS_N<3>")
	)
	(arc
		(start 132.128768 -244.247162)
		(mid 131.846066 -244.171386)
		(end 131.563364 -244.247162)
		(width 0.088646)
		(layer "In6.Cu")
		(net "M_H_CPU1_SB_CS_N<3>")
	)
	(arc
		(start 132.503164 -244.247162)
		(mid 132.315966 -244.297305)
		(end 132.128768 -244.247162)
		(width 0.088646)
		(layer "In6.Cu")
		(net "M_H_CPU1_SB_CS_N<3>")
	)
	(arc
		(start 136.944608 -244.336824)
		(mid 136.627128 -244.177247)
		(end 136.277096 -244.238526)
		(width 0.088646)
		(layer "In6.Cu")
		(net "M_H_CPU1_SB_CS_N<3>")
	)
	(arc
		(start 131.188968 -244.247162)
		(mid 130.914769 -244.171327)
		(end 130.638296 -244.238526)
		(width 0.088646)
		(layer "In6.Cu")
		(net "M_H_CPU1_SB_CS_N<3>")
	)
	(arc
		(start 130.623564 -244.247162)
		(mid 130.436366 -244.297305)
		(end 130.249168 -244.247162)
		(width 0.088646)
		(layer "In6.Cu")
		(net "M_H_CPU1_SB_CS_N<3>")
	)
	(arc
		(start 136.262364 -244.247162)
		(mid 136.075166 -244.297305)
		(end 135.887968 -244.247162)
		(width 0.088646)
		(layer "In6.Cu")
		(net "M_H_CPU1_SB_CS_N<3>")
	)
	(segment
		(start 202.971146 -245.76659)
		(end 204.076046 -245.76659)
		(width 0.20066)
		(layer "F.Cu")
		(net "M_H_CPU1_SB_CS_N<2>")
	)
	(segment
		(start 126.677166 -244.45849)
		(end 126.677166 -243.922804)
		(width 0.20066)
		(layer "F.Cu")
		(net "M_H_CPU1_SB_CS_N<2>")
	)
	(segment
		(start 126.676912 -244.458744)
		(end 126.677166 -244.45849)
		(width 0.20066)
		(layer "F.Cu")
		(net "M_H_CPU1_SB_CS_N<2>")
	)
	(segment
		(start 127.334264 -244.412262)
		(end 127.256032 -244.36705)
		(width 0.088646)
		(layer "In6.Cu")
		(net "M_H_CPU1_SB_CS_N<2>")
	)
	(segment
		(start 190.573406 -241.942366)
		(end 180.200046 -241.942366)
		(width 0.18288)
		(layer "In6.Cu")
		(net "M_H_CPU1_SB_CS_N<2>")
	)
	(segment
		(start 161.185352 -241.046)
		(end 160.742884 -241.488468)
		(width 0.18288)
		(layer "In6.Cu")
		(net "M_H_CPU1_SB_CS_N<2>")
	)
	(segment
		(start 203.43495 -242.792504)
		(end 197.303644 -242.792504)
		(width 0.18288)
		(layer "In6.Cu")
		(net "M_H_CPU1_SB_CS_N<2>")
	)
	(segment
		(start 135.418068 -244.412262)
		(end 135.407654 -244.418358)
		(width 0.088646)
		(layer "In6.Cu")
		(net "M_H_CPU1_SB_CS_N<2>")
	)
	(segment
		(start 197.303644 -242.792504)
		(end 196.450458 -241.939318)
		(width 0.18288)
		(layer "In6.Cu")
		(net "M_H_CPU1_SB_CS_N<2>")
	)
	(segment
		(start 136.919716 -245.120668)
		(end 136.919716 -244.73662)
		(width 0.088646)
		(layer "In6.Cu")
		(net "M_H_CPU1_SB_CS_N<2>")
	)
	(segment
		(start 203.954126 -244.75821)
		(end 203.954126 -243.31168)
		(width 0.18288)
		(layer "In6.Cu")
		(net "M_H_CPU1_SB_CS_N<2>")
	)
	(segment
		(start 140.529056 -245.54688)
		(end 139.75207 -245.54688)
		(width 0.18288)
		(layer "In6.Cu")
		(net "M_H_CPU1_SB_CS_N<2>")
	)
	(segment
		(start 165.099746 -241.840766)
		(end 164.40404 -242.536472)
		(width 0.18288)
		(layer "In6.Cu")
		(net "M_H_CPU1_SB_CS_N<2>")
	)
	(segment
		(start 137.743946 -245.218458)
		(end 137.17143 -245.218458)
		(width 0.18288)
		(layer "In6.Cu")
		(net "M_H_CPU1_SB_CS_N<2>")
	)
	(segment
		(start 191.423544 -242.792504)
		(end 190.573406 -241.942366)
		(width 0.18288)
		(layer "In6.Cu")
		(net "M_H_CPU1_SB_CS_N<2>")
	)
	(segment
		(start 133.538468 -244.412262)
		(end 133.528054 -244.418358)
		(width 0.088646)
		(layer "In6.Cu")
		(net "M_H_CPU1_SB_CS_N<2>")
	)
	(segment
		(start 137.017506 -245.218458)
		(end 136.919716 -245.120668)
		(width 0.088646)
		(layer "In6.Cu")
		(net "M_H_CPU1_SB_CS_N<2>")
	)
	(segment
		(start 164.40404 -242.536472)
		(end 163.526216 -242.536472)
		(width 0.18288)
		(layer "In6.Cu")
		(net "M_H_CPU1_SB_CS_N<2>")
	)
	(segment
		(start 153.715974 -241.488468)
		(end 150.662386 -244.542056)
		(width 0.18288)
		(layer "In6.Cu")
		(net "M_H_CPU1_SB_CS_N<2>")
	)
	(segment
		(start 136.349232 -244.417088)
		(end 136.3472 -244.418358)
		(width 0.088646)
		(layer "In6.Cu")
		(net "M_H_CPU1_SB_CS_N<2>")
	)
	(segment
		(start 193.564002 -241.939318)
		(end 192.710816 -242.792504)
		(width 0.18288)
		(layer "In6.Cu")
		(net "M_H_CPU1_SB_CS_N<2>")
	)
	(segment
		(start 176.464214 -241.942366)
		(end 175.61433 -242.79225)
		(width 0.18288)
		(layer "In6.Cu")
		(net "M_H_CPU1_SB_CS_N<2>")
	)
	(segment
		(start 177.842926 -241.942366)
		(end 176.464214 -241.942366)
		(width 0.18288)
		(layer "In6.Cu")
		(net "M_H_CPU1_SB_CS_N<2>")
	)
	(segment
		(start 179.267866 -241.010186)
		(end 178.775106 -241.010186)
		(width 0.18288)
		(layer "In6.Cu")
		(net "M_H_CPU1_SB_CS_N<2>")
	)
	(segment
		(start 163.526216 -242.536472)
		(end 162.035744 -241.046)
		(width 0.18288)
		(layer "In6.Cu")
		(net "M_H_CPU1_SB_CS_N<2>")
	)
	(segment
		(start 139.75207 -245.54688)
		(end 139.31138 -245.729252)
		(width 0.18288)
		(layer "In6.Cu")
		(net "M_H_CPU1_SB_CS_N<2>")
	)
	(segment
		(start 131.658868 -244.412262)
		(end 131.648454 -244.418358)
		(width 0.088646)
		(layer "In6.Cu")
		(net "M_H_CPU1_SB_CS_N<2>")
	)
	(segment
		(start 136.357868 -244.412262)
		(end 136.349232 -244.417088)
		(width 0.088646)
		(layer "In6.Cu")
		(net "M_H_CPU1_SB_CS_N<2>")
	)
	(segment
		(start 160.742884 -241.488468)
		(end 153.715974 -241.488468)
		(width 0.18288)
		(layer "In6.Cu")
		(net "M_H_CPU1_SB_CS_N<2>")
	)
	(segment
		(start 192.710816 -242.792504)
		(end 191.423544 -242.792504)
		(width 0.18288)
		(layer "In6.Cu")
		(net "M_H_CPU1_SB_CS_N<2>")
	)
	(segment
		(start 168.66997 -242.79225)
		(end 167.718486 -241.840766)
		(width 0.18288)
		(layer "In6.Cu")
		(net "M_H_CPU1_SB_CS_N<2>")
	)
	(segment
		(start 132.598414 -244.412262)
		(end 132.588 -244.418358)
		(width 0.088646)
		(layer "In6.Cu")
		(net "M_H_CPU1_SB_CS_N<2>")
	)
	(segment
		(start 167.718486 -241.840766)
		(end 165.099746 -241.840766)
		(width 0.18288)
		(layer "In6.Cu")
		(net "M_H_CPU1_SB_CS_N<2>")
	)
	(segment
		(start 203.954126 -243.31168)
		(end 203.43495 -242.792504)
		(width 0.18288)
		(layer "In6.Cu")
		(net "M_H_CPU1_SB_CS_N<2>")
	)
	(segment
		(start 175.61433 -242.79225)
		(end 168.66997 -242.79225)
		(width 0.18288)
		(layer "In6.Cu")
		(net "M_H_CPU1_SB_CS_N<2>")
	)
	(segment
		(start 128.839214 -244.412262)
		(end 128.824482 -244.420898)
		(width 0.088646)
		(layer "In6.Cu")
		(net "M_H_CPU1_SB_CS_N<2>")
	)
	(segment
		(start 130.718814 -244.412262)
		(end 130.704082 -244.420898)
		(width 0.088646)
		(layer "In6.Cu")
		(net "M_H_CPU1_SB_CS_N<2>")
	)
	(segment
		(start 180.200046 -241.942366)
		(end 179.267866 -241.010186)
		(width 0.18288)
		(layer "In6.Cu")
		(net "M_H_CPU1_SB_CS_N<2>")
	)
	(segment
		(start 136.732518 -244.412516)
		(end 136.732264 -244.412262)
		(width 0.088646)
		(layer "In6.Cu")
		(net "M_H_CPU1_SB_CS_N<2>")
	)
	(segment
		(start 134.478014 -244.412262)
		(end 134.4676 -244.418358)
		(width 0.088646)
		(layer "In6.Cu")
		(net "M_H_CPU1_SB_CS_N<2>")
	)
	(segment
		(start 150.662386 -244.542056)
		(end 141.53388 -244.542056)
		(width 0.18288)
		(layer "In6.Cu")
		(net "M_H_CPU1_SB_CS_N<2>")
	)
	(segment
		(start 202.971146 -245.76659)
		(end 202.971146 -245.74119)
		(width 0.18288)
		(layer "In6.Cu")
		(net "M_H_CPU1_SB_CS_N<2>")
	)
	(segment
		(start 162.035744 -241.046)
		(end 161.185352 -241.046)
		(width 0.18288)
		(layer "In6.Cu")
		(net "M_H_CPU1_SB_CS_N<2>")
	)
	(segment
		(start 137.17143 -245.218458)
		(end 137.017506 -245.218458)
		(width 0.088646)
		(layer "In6.Cu")
		(net "M_H_CPU1_SB_CS_N<2>")
	)
	(segment
		(start 141.53388 -244.542056)
		(end 140.529056 -245.54688)
		(width 0.18288)
		(layer "In6.Cu")
		(net "M_H_CPU1_SB_CS_N<2>")
	)
	(segment
		(start 139.31138 -245.729252)
		(end 138.25474 -245.729252)
		(width 0.18288)
		(layer "In6.Cu")
		(net "M_H_CPU1_SB_CS_N<2>")
	)
	(segment
		(start 138.25474 -245.729252)
		(end 137.743946 -245.218458)
		(width 0.18288)
		(layer "In6.Cu")
		(net "M_H_CPU1_SB_CS_N<2>")
	)
	(segment
		(start 127.899414 -244.412262)
		(end 127.889 -244.418358)
		(width 0.088646)
		(layer "In6.Cu")
		(net "M_H_CPU1_SB_CS_N<2>")
	)
	(segment
		(start 178.775106 -241.010186)
		(end 177.842926 -241.942366)
		(width 0.18288)
		(layer "In6.Cu")
		(net "M_H_CPU1_SB_CS_N<2>")
	)
	(segment
		(start 202.971146 -245.74119)
		(end 203.954126 -244.75821)
		(width 0.18288)
		(layer "In6.Cu")
		(net "M_H_CPU1_SB_CS_N<2>")
	)
	(segment
		(start 196.450458 -241.939318)
		(end 193.564002 -241.939318)
		(width 0.18288)
		(layer "In6.Cu")
		(net "M_H_CPU1_SB_CS_N<2>")
	)
	(arc
		(start 132.97281 -244.412262)
		(mid 132.785612 -244.362119)
		(end 132.598414 -244.412262)
		(width 0.088646)
		(layer "In6.Cu")
		(net "M_H_CPU1_SB_CS_N<2>")
	)
	(arc
		(start 127.889 -244.418358)
		(mid 127.610822 -244.488081)
		(end 127.334264 -244.412262)
		(width 0.088646)
		(layer "In6.Cu")
		(net "M_H_CPU1_SB_CS_N<2>")
	)
	(arc
		(start 127.256032 -244.36705)
		(mid 126.952044 -244.163892)
		(end 126.677166 -243.922804)
		(width 0.088646)
		(layer "In6.Cu")
		(net "M_H_CPU1_SB_CS_N<2>")
	)
	(arc
		(start 129.21361 -244.412262)
		(mid 129.026412 -244.362119)
		(end 128.839214 -244.412262)
		(width 0.088646)
		(layer "In6.Cu")
		(net "M_H_CPU1_SB_CS_N<2>")
	)
	(arc
		(start 131.648454 -244.418358)
		(mid 131.370022 -244.488204)
		(end 131.09321 -244.412262)
		(width 0.088646)
		(layer "In6.Cu")
		(net "M_H_CPU1_SB_CS_N<2>")
	)
	(arc
		(start 129.779014 -244.412262)
		(mid 129.496312 -244.488038)
		(end 129.21361 -244.412262)
		(width 0.088646)
		(layer "In6.Cu")
		(net "M_H_CPU1_SB_CS_N<2>")
	)
	(arc
		(start 136.3472 -244.418358)
		(mid 136.069022 -244.488081)
		(end 135.792464 -244.412262)
		(width 0.088646)
		(layer "In6.Cu")
		(net "M_H_CPU1_SB_CS_N<2>")
	)
	(arc
		(start 128.824482 -244.420898)
		(mid 128.548007 -244.488218)
		(end 128.27381 -244.412262)
		(width 0.088646)
		(layer "In6.Cu")
		(net "M_H_CPU1_SB_CS_N<2>")
	)
	(arc
		(start 134.4676 -244.418358)
		(mid 134.189422 -244.488081)
		(end 133.912864 -244.412262)
		(width 0.088646)
		(layer "In6.Cu")
		(net "M_H_CPU1_SB_CS_N<2>")
	)
	(arc
		(start 135.407654 -244.418358)
		(mid 135.129222 -244.488204)
		(end 134.85241 -244.412262)
		(width 0.088646)
		(layer "In6.Cu")
		(net "M_H_CPU1_SB_CS_N<2>")
	)
	(arc
		(start 132.033264 -244.412262)
		(mid 131.846066 -244.362119)
		(end 131.658868 -244.412262)
		(width 0.088646)
		(layer "In6.Cu")
		(net "M_H_CPU1_SB_CS_N<2>")
	)
	(arc
		(start 133.528054 -244.418358)
		(mid 133.249622 -244.488204)
		(end 132.97281 -244.412262)
		(width 0.088646)
		(layer "In6.Cu")
		(net "M_H_CPU1_SB_CS_N<2>")
	)
	(arc
		(start 130.704082 -244.420898)
		(mid 130.427607 -244.488218)
		(end 130.15341 -244.412262)
		(width 0.088646)
		(layer "In6.Cu")
		(net "M_H_CPU1_SB_CS_N<2>")
	)
	(arc
		(start 135.792464 -244.412262)
		(mid 135.605266 -244.362119)
		(end 135.418068 -244.412262)
		(width 0.088646)
		(layer "In6.Cu")
		(net "M_H_CPU1_SB_CS_N<2>")
	)
	(arc
		(start 131.09321 -244.412262)
		(mid 130.906012 -244.362119)
		(end 130.718814 -244.412262)
		(width 0.088646)
		(layer "In6.Cu")
		(net "M_H_CPU1_SB_CS_N<2>")
	)
	(arc
		(start 132.588 -244.418358)
		(mid 132.309822 -244.488081)
		(end 132.033264 -244.412262)
		(width 0.088646)
		(layer "In6.Cu")
		(net "M_H_CPU1_SB_CS_N<2>")
	)
	(arc
		(start 134.85241 -244.412262)
		(mid 134.665212 -244.362119)
		(end 134.478014 -244.412262)
		(width 0.088646)
		(layer "In6.Cu")
		(net "M_H_CPU1_SB_CS_N<2>")
	)
	(arc
		(start 130.15341 -244.412262)
		(mid 129.966212 -244.362119)
		(end 129.779014 -244.412262)
		(width 0.088646)
		(layer "In6.Cu")
		(net "M_H_CPU1_SB_CS_N<2>")
	)
	(arc
		(start 136.732264 -244.412262)
		(mid 136.545066 -244.362119)
		(end 136.357868 -244.412262)
		(width 0.088646)
		(layer "In6.Cu")
		(net "M_H_CPU1_SB_CS_N<2>")
	)
	(arc
		(start 133.912864 -244.412262)
		(mid 133.725666 -244.362119)
		(end 133.538468 -244.412262)
		(width 0.088646)
		(layer "In6.Cu")
		(net "M_H_CPU1_SB_CS_N<2>")
	)
	(arc
		(start 128.27381 -244.412262)
		(mid 128.086612 -244.362119)
		(end 127.899414 -244.412262)
		(width 0.088646)
		(layer "In6.Cu")
		(net "M_H_CPU1_SB_CS_N<2>")
	)
	(arc
		(start 136.919716 -244.73662)
		(mid 136.869552 -244.549482)
		(end 136.732518 -244.412516)
		(width 0.088646)
		(layer "In6.Cu")
		(net "M_H_CPU1_SB_CS_N<2>")
	)
	(segment
		(start 128.086612 -243.644674)
		(end 128.086612 -243.108988)
		(width 0.20066)
		(layer "F.Cu")
		(net "M_H_CPU1_SB_CS_N<1>")
	)
	(segment
		(start 215.719914 -244.916706)
		(end 214.615014 -244.916706)
		(width 0.20066)
		(layer "F.Cu")
		(net "M_H_CPU1_SB_CS_N<1>")
	)
	(segment
		(start 128.086866 -243.644928)
		(end 128.086612 -243.644674)
		(width 0.20066)
		(layer "F.Cu")
		(net "M_H_CPU1_SB_CS_N<1>")
	)
	(segment
		(start 196.436742 -238.652558)
		(end 196.436742 -239.374426)
		(width 0.18288)
		(layer "In6.Cu")
		(net "M_H_CPU1_SB_CS_N<1>")
	)
	(segment
		(start 176.678844 -239.395)
		(end 176.38268 -239.691164)
		(width 0.18288)
		(layer "In6.Cu")
		(net "M_H_CPU1_SB_CS_N<1>")
	)
	(segment
		(start 128.839214 -243.433346)
		(end 128.824482 -243.42471)
		(width 0.088646)
		(layer "In6.Cu")
		(net "M_H_CPU1_SB_CS_N<1>")
	)
	(segment
		(start 214.615014 -244.916706)
		(end 213.874604 -244.176296)
		(width 0.18288)
		(layer "In6.Cu")
		(net "M_H_CPU1_SB_CS_N<1>")
	)
	(segment
		(start 197.313042 -239.557306)
		(end 197.130162 -239.374426)
		(width 0.18288)
		(layer "In6.Cu")
		(net "M_H_CPU1_SB_CS_N<1>")
	)
	(segment
		(start 127.773684 -243.108988)
		(end 128.086612 -243.108988)
		(width 0.088646)
		(layer "In6.Cu")
		(net "M_H_CPU1_SB_CS_N<1>")
	)
	(segment
		(start 198.853044 -240.242344)
		(end 198.168006 -239.557306)
		(width 0.18288)
		(layer "In6.Cu")
		(net "M_H_CPU1_SB_CS_N<1>")
	)
	(segment
		(start 175.172624 -240.242344)
		(end 168.731184 -240.242344)
		(width 0.18288)
		(layer "In6.Cu")
		(net "M_H_CPU1_SB_CS_N<1>")
	)
	(segment
		(start 196.436742 -239.374426)
		(end 196.253862 -239.557306)
		(width 0.18288)
		(layer "In6.Cu")
		(net "M_H_CPU1_SB_CS_N<1>")
	)
	(segment
		(start 197.130162 -239.374426)
		(end 197.130162 -238.652558)
		(width 0.18288)
		(layer "In6.Cu")
		(net "M_H_CPU1_SB_CS_N<1>")
	)
	(segment
		(start 156.602938 -238.539274)
		(end 155.556204 -239.586008)
		(width 0.18288)
		(layer "In6.Cu")
		(net "M_H_CPU1_SB_CS_N<1>")
	)
	(segment
		(start 127.716534 -243.166138)
		(end 127.773684 -243.108988)
		(width 0.088646)
		(layer "In6.Cu")
		(net "M_H_CPU1_SB_CS_N<1>")
	)
	(segment
		(start 163.530534 -238.539274)
		(end 156.602938 -238.539274)
		(width 0.18288)
		(layer "In6.Cu")
		(net "M_H_CPU1_SB_CS_N<1>")
	)
	(segment
		(start 179.53482 -238.84128)
		(end 178.517804 -238.84128)
		(width 0.18288)
		(layer "In6.Cu")
		(net "M_H_CPU1_SB_CS_N<1>")
	)
	(segment
		(start 180.086 -239.39246)
		(end 179.53482 -238.84128)
		(width 0.18288)
		(layer "In6.Cu")
		(net "M_H_CPU1_SB_CS_N<1>")
	)
	(segment
		(start 178.517804 -238.84128)
		(end 177.964084 -239.395)
		(width 0.18288)
		(layer "In6.Cu")
		(net "M_H_CPU1_SB_CS_N<1>")
	)
	(segment
		(start 137.507218 -243.001038)
		(end 137.150602 -243.357654)
		(width 0.088646)
		(layer "In6.Cu")
		(net "M_H_CPU1_SB_CS_N<1>")
	)
	(segment
		(start 155.556204 -239.586008)
		(end 153.374598 -239.586008)
		(width 0.18288)
		(layer "In6.Cu")
		(net "M_H_CPU1_SB_CS_N<1>")
	)
	(segment
		(start 190.79972 -239.39246)
		(end 180.086 -239.39246)
		(width 0.18288)
		(layer "In6.Cu")
		(net "M_H_CPU1_SB_CS_N<1>")
	)
	(segment
		(start 205.609444 -240.242344)
		(end 198.853044 -240.242344)
		(width 0.18288)
		(layer "In6.Cu")
		(net "M_H_CPU1_SB_CS_N<1>")
	)
	(segment
		(start 149.959568 -243.001038)
		(end 137.712958 -243.001038)
		(width 0.18288)
		(layer "In6.Cu")
		(net "M_H_CPU1_SB_CS_N<1>")
	)
	(segment
		(start 196.947282 -238.469678)
		(end 196.619622 -238.469678)
		(width 0.18288)
		(layer "In6.Cu")
		(net "M_H_CPU1_SB_CS_N<1>")
	)
	(segment
		(start 135.418068 -243.433346)
		(end 135.407654 -243.42725)
		(width 0.088646)
		(layer "In6.Cu")
		(net "M_H_CPU1_SB_CS_N<1>")
	)
	(segment
		(start 192.717928 -240.242344)
		(end 191.649604 -240.242344)
		(width 0.18288)
		(layer "In6.Cu")
		(net "M_H_CPU1_SB_CS_N<1>")
	)
	(segment
		(start 191.649604 -240.242344)
		(end 190.79972 -239.39246)
		(width 0.18288)
		(layer "In6.Cu")
		(net "M_H_CPU1_SB_CS_N<1>")
	)
	(segment
		(start 164.518594 -239.527334)
		(end 163.530534 -238.539274)
		(width 0.18288)
		(layer "In6.Cu")
		(net "M_H_CPU1_SB_CS_N<1>")
	)
	(segment
		(start 194.733926 -239.300766)
		(end 193.659506 -239.300766)
		(width 0.18288)
		(layer "In6.Cu")
		(net "M_H_CPU1_SB_CS_N<1>")
	)
	(segment
		(start 213.874604 -244.176296)
		(end 213.874604 -241.779806)
		(width 0.18288)
		(layer "In6.Cu")
		(net "M_H_CPU1_SB_CS_N<1>")
	)
	(segment
		(start 176.38268 -239.691164)
		(end 175.723804 -239.691164)
		(width 0.18288)
		(layer "In6.Cu")
		(net "M_H_CPU1_SB_CS_N<1>")
	)
	(segment
		(start 153.374598 -239.586008)
		(end 149.959568 -243.001038)
		(width 0.18288)
		(layer "In6.Cu")
		(net "M_H_CPU1_SB_CS_N<1>")
	)
	(segment
		(start 213.874604 -241.779806)
		(end 213.186518 -241.09172)
		(width 0.18288)
		(layer "In6.Cu")
		(net "M_H_CPU1_SB_CS_N<1>")
	)
	(segment
		(start 137.150602 -243.357654)
		(end 137.014966 -243.357654)
		(width 0.088646)
		(layer "In6.Cu")
		(net "M_H_CPU1_SB_CS_N<1>")
	)
	(segment
		(start 196.253862 -239.557306)
		(end 194.990466 -239.557306)
		(width 0.18288)
		(layer "In6.Cu")
		(net "M_H_CPU1_SB_CS_N<1>")
	)
	(segment
		(start 131.658614 -243.433346)
		(end 131.643882 -243.42471)
		(width 0.088646)
		(layer "In6.Cu")
		(net "M_H_CPU1_SB_CS_N<1>")
	)
	(segment
		(start 132.598668 -243.433346)
		(end 132.588254 -243.42725)
		(width 0.088646)
		(layer "In6.Cu")
		(net "M_H_CPU1_SB_CS_N<1>")
	)
	(segment
		(start 177.964084 -239.395)
		(end 176.678844 -239.395)
		(width 0.18288)
		(layer "In6.Cu")
		(net "M_H_CPU1_SB_CS_N<1>")
	)
	(segment
		(start 175.723804 -239.691164)
		(end 175.172624 -240.242344)
		(width 0.18288)
		(layer "In6.Cu")
		(net "M_H_CPU1_SB_CS_N<1>")
	)
	(segment
		(start 194.990466 -239.557306)
		(end 194.733926 -239.300766)
		(width 0.18288)
		(layer "In6.Cu")
		(net "M_H_CPU1_SB_CS_N<1>")
	)
	(segment
		(start 168.016174 -239.527334)
		(end 164.518594 -239.527334)
		(width 0.18288)
		(layer "In6.Cu")
		(net "M_H_CPU1_SB_CS_N<1>")
	)
	(segment
		(start 197.130162 -238.652558)
		(end 196.947282 -238.469678)
		(width 0.18288)
		(layer "In6.Cu")
		(net "M_H_CPU1_SB_CS_N<1>")
	)
	(segment
		(start 196.619622 -238.469678)
		(end 196.436742 -238.652558)
		(width 0.18288)
		(layer "In6.Cu")
		(net "M_H_CPU1_SB_CS_N<1>")
	)
	(segment
		(start 130.718814 -243.433346)
		(end 130.704082 -243.42471)
		(width 0.088646)
		(layer "In6.Cu")
		(net "M_H_CPU1_SB_CS_N<1>")
	)
	(segment
		(start 137.712958 -243.001038)
		(end 137.507218 -243.001038)
		(width 0.088646)
		(layer "In6.Cu")
		(net "M_H_CPU1_SB_CS_N<1>")
	)
	(segment
		(start 134.478014 -243.433346)
		(end 134.4676 -243.42725)
		(width 0.088646)
		(layer "In6.Cu")
		(net "M_H_CPU1_SB_CS_N<1>")
	)
	(segment
		(start 193.659506 -239.300766)
		(end 192.717928 -240.242344)
		(width 0.18288)
		(layer "In6.Cu")
		(net "M_H_CPU1_SB_CS_N<1>")
	)
	(segment
		(start 198.168006 -239.557306)
		(end 197.313042 -239.557306)
		(width 0.18288)
		(layer "In6.Cu")
		(net "M_H_CPU1_SB_CS_N<1>")
	)
	(segment
		(start 206.45882 -241.09172)
		(end 205.609444 -240.242344)
		(width 0.18288)
		(layer "In6.Cu")
		(net "M_H_CPU1_SB_CS_N<1>")
	)
	(segment
		(start 213.186518 -241.09172)
		(end 206.45882 -241.09172)
		(width 0.18288)
		(layer "In6.Cu")
		(net "M_H_CPU1_SB_CS_N<1>")
	)
	(segment
		(start 127.899414 -243.433346)
		(end 127.890524 -243.428266)
		(width 0.088646)
		(layer "In6.Cu")
		(net "M_H_CPU1_SB_CS_N<1>")
	)
	(segment
		(start 168.731184 -240.242344)
		(end 168.016174 -239.527334)
		(width 0.18288)
		(layer "In6.Cu")
		(net "M_H_CPU1_SB_CS_N<1>")
	)
	(arc
		(start 134.85241 -243.433346)
		(mid 134.665212 -243.483489)
		(end 134.478014 -243.433346)
		(width 0.088646)
		(layer "In6.Cu")
		(net "M_H_CPU1_SB_CS_N<1>")
	)
	(arc
		(start 137.014966 -243.357654)
		(mid 136.868622 -243.376862)
		(end 136.732264 -243.433346)
		(width 0.088646)
		(layer "In6.Cu")
		(net "M_H_CPU1_SB_CS_N<1>")
	)
	(arc
		(start 128.27381 -243.433346)
		(mid 128.086612 -243.483489)
		(end 127.899414 -243.433346)
		(width 0.088646)
		(layer "In6.Cu")
		(net "M_H_CPU1_SB_CS_N<1>")
	)
	(arc
		(start 130.15341 -243.433346)
		(mid 129.966212 -243.483489)
		(end 129.779014 -243.433346)
		(width 0.088646)
		(layer "In6.Cu")
		(net "M_H_CPU1_SB_CS_N<1>")
	)
	(arc
		(start 132.973064 -243.433346)
		(mid 132.785866 -243.483489)
		(end 132.598668 -243.433346)
		(width 0.088646)
		(layer "In6.Cu")
		(net "M_H_CPU1_SB_CS_N<1>")
	)
	(arc
		(start 130.704082 -243.42471)
		(mid 130.427607 -243.35739)
		(end 130.15341 -243.433346)
		(width 0.088646)
		(layer "In6.Cu")
		(net "M_H_CPU1_SB_CS_N<1>")
	)
	(arc
		(start 133.912864 -243.433346)
		(mid 133.725666 -243.483489)
		(end 133.538468 -243.433346)
		(width 0.088646)
		(layer "In6.Cu")
		(net "M_H_CPU1_SB_CS_N<1>")
	)
	(arc
		(start 136.357868 -243.433346)
		(mid 136.075166 -243.35757)
		(end 135.792464 -243.433346)
		(width 0.088646)
		(layer "In6.Cu")
		(net "M_H_CPU1_SB_CS_N<1>")
	)
	(arc
		(start 128.824482 -243.42471)
		(mid 128.548007 -243.35739)
		(end 128.27381 -243.433346)
		(width 0.088646)
		(layer "In6.Cu")
		(net "M_H_CPU1_SB_CS_N<1>")
	)
	(arc
		(start 136.732264 -243.433346)
		(mid 136.545066 -243.483489)
		(end 136.357868 -243.433346)
		(width 0.088646)
		(layer "In6.Cu")
		(net "M_H_CPU1_SB_CS_N<1>")
	)
	(arc
		(start 132.588254 -243.42725)
		(mid 132.309822 -243.357404)
		(end 132.03301 -243.433346)
		(width 0.088646)
		(layer "In6.Cu")
		(net "M_H_CPU1_SB_CS_N<1>")
	)
	(arc
		(start 132.03301 -243.433346)
		(mid 131.845812 -243.483489)
		(end 131.658614 -243.433346)
		(width 0.088646)
		(layer "In6.Cu")
		(net "M_H_CPU1_SB_CS_N<1>")
	)
	(arc
		(start 135.407654 -243.42725)
		(mid 135.129222 -243.357404)
		(end 134.85241 -243.433346)
		(width 0.088646)
		(layer "In6.Cu")
		(net "M_H_CPU1_SB_CS_N<1>")
	)
	(arc
		(start 135.792464 -243.433346)
		(mid 135.605266 -243.483489)
		(end 135.418068 -243.433346)
		(width 0.088646)
		(layer "In6.Cu")
		(net "M_H_CPU1_SB_CS_N<1>")
	)
	(arc
		(start 134.4676 -243.42725)
		(mid 134.189422 -243.357527)
		(end 133.912864 -243.433346)
		(width 0.088646)
		(layer "In6.Cu")
		(net "M_H_CPU1_SB_CS_N<1>")
	)
	(arc
		(start 131.09321 -243.433346)
		(mid 130.906012 -243.483489)
		(end 130.718814 -243.433346)
		(width 0.088646)
		(layer "In6.Cu")
		(net "M_H_CPU1_SB_CS_N<1>")
	)
	(arc
		(start 133.538468 -243.433346)
		(mid 133.255766 -243.35757)
		(end 132.973064 -243.433346)
		(width 0.088646)
		(layer "In6.Cu")
		(net "M_H_CPU1_SB_CS_N<1>")
	)
	(arc
		(start 127.890524 -243.428266)
		(mid 127.774715 -243.316337)
		(end 127.716534 -243.166138)
		(width 0.088646)
		(layer "In6.Cu")
		(net "M_H_CPU1_SB_CS_N<1>")
	)
	(arc
		(start 129.21361 -243.433346)
		(mid 129.026412 -243.483489)
		(end 128.839214 -243.433346)
		(width 0.088646)
		(layer "In6.Cu")
		(net "M_H_CPU1_SB_CS_N<1>")
	)
	(arc
		(start 131.643882 -243.42471)
		(mid 131.367407 -243.35739)
		(end 131.09321 -243.433346)
		(width 0.088646)
		(layer "In6.Cu")
		(net "M_H_CPU1_SB_CS_N<1>")
	)
	(arc
		(start 129.779014 -243.433346)
		(mid 129.496312 -243.35757)
		(end 129.21361 -243.433346)
		(width 0.088646)
		(layer "In6.Cu")
		(net "M_H_CPU1_SB_CS_N<1>")
	)
	(segment
		(start 127.146812 -243.644674)
		(end 127.146812 -243.108988)
		(width 0.20066)
		(layer "F.Cu")
		(net "M_H_CPU1_SB_CS_N<0>")
	)
	(segment
		(start 211.619846 -245.76659)
		(end 210.514946 -245.76659)
		(width 0.20066)
		(layer "F.Cu")
		(net "M_H_CPU1_SB_CS_N<0>")
	)
	(segment
		(start 127.147066 -243.644928)
		(end 127.146812 -243.644674)
		(width 0.20066)
		(layer "F.Cu")
		(net "M_H_CPU1_SB_CS_N<0>")
	)
	(segment
		(start 196.701156 -240.704116)
		(end 196.373496 -240.704116)
		(width 0.18288)
		(layer "In6.Cu")
		(net "M_H_CPU1_SB_CS_N<0>")
	)
	(segment
		(start 194.523106 -240.492026)
		(end 193.380106 -240.492026)
		(width 0.18288)
		(layer "In6.Cu")
		(net "M_H_CPU1_SB_CS_N<0>")
	)
	(segment
		(start 130.638296 -243.607082)
		(end 130.623564 -243.598446)
		(width 0.088646)
		(layer "In6.Cu")
		(net "M_H_CPU1_SB_CS_N<0>")
	)
	(segment
		(start 190.476632 -240.242344)
		(end 183.417718 -240.242344)
		(width 0.18288)
		(layer "In6.Cu")
		(net "M_H_CPU1_SB_CS_N<0>")
	)
	(segment
		(start 127.818896 -243.607082)
		(end 127.804164 -243.598446)
		(width 0.088646)
		(layer "In6.Cu")
		(net "M_H_CPU1_SB_CS_N<0>")
	)
	(segment
		(start 196.884036 -240.329466)
		(end 196.884036 -240.521236)
		(width 0.18288)
		(layer "In6.Cu")
		(net "M_H_CPU1_SB_CS_N<0>")
	)
	(segment
		(start 180.965094 -239.932718)
		(end 179.912518 -239.932718)
		(width 0.18288)
		(layer "In6.Cu")
		(net "M_H_CPU1_SB_CS_N<0>")
	)
	(segment
		(start 167.774366 -240.111026)
		(end 165.155626 -240.111026)
		(width 0.18288)
		(layer "In6.Cu")
		(net "M_H_CPU1_SB_CS_N<0>")
	)
	(segment
		(start 181.330854 -240.848642)
		(end 181.147974 -240.665762)
		(width 0.18288)
		(layer "In6.Cu")
		(net "M_H_CPU1_SB_CS_N<0>")
	)
	(segment
		(start 179.912518 -239.932718)
		(end 179.333906 -239.354106)
		(width 0.18288)
		(layer "In6.Cu")
		(net "M_H_CPU1_SB_CS_N<0>")
	)
	(segment
		(start 183.417718 -240.242344)
		(end 183.108092 -239.932718)
		(width 0.18288)
		(layer "In6.Cu")
		(net "M_H_CPU1_SB_CS_N<0>")
	)
	(segment
		(start 165.155626 -240.111026)
		(end 164.431726 -240.834926)
		(width 0.18288)
		(layer "In6.Cu")
		(net "M_H_CPU1_SB_CS_N<0>")
	)
	(segment
		(start 200.33869 -241.492278)
		(end 200.33869 -240.931446)
		(width 0.18288)
		(layer "In6.Cu")
		(net "M_H_CPU1_SB_CS_N<0>")
	)
	(segment
		(start 127.525272 -243.17452)
		(end 127.45974 -243.108988)
		(width 0.088646)
		(layer "In6.Cu")
		(net "M_H_CPU1_SB_CS_N<0>")
	)
	(segment
		(start 181.147974 -240.115598)
		(end 180.965094 -239.932718)
		(width 0.18288)
		(layer "In6.Cu")
		(net "M_H_CPU1_SB_CS_N<0>")
	)
	(segment
		(start 196.190616 -240.521236)
		(end 196.190616 -240.329466)
		(width 0.18288)
		(layer "In6.Cu")
		(net "M_H_CPU1_SB_CS_N<0>")
	)
	(segment
		(start 196.884036 -240.521236)
		(end 196.701156 -240.704116)
		(width 0.18288)
		(layer "In6.Cu")
		(net "M_H_CPU1_SB_CS_N<0>")
	)
	(segment
		(start 127.45974 -243.108988)
		(end 127.146812 -243.108988)
		(width 0.088646)
		(layer "In6.Cu")
		(net "M_H_CPU1_SB_CS_N<0>")
	)
	(segment
		(start 179.333906 -239.354106)
		(end 178.787806 -239.354106)
		(width 0.18288)
		(layer "In6.Cu")
		(net "M_H_CPU1_SB_CS_N<0>")
	)
	(segment
		(start 129.693924 -243.604542)
		(end 129.68351 -243.598446)
		(width 0.088646)
		(layer "In6.Cu")
		(net "M_H_CPU1_SB_CS_N<0>")
	)
	(segment
		(start 156.181552 -240.246154)
		(end 153.484072 -240.246154)
		(width 0.18288)
		(layer "In6.Cu")
		(net "M_H_CPU1_SB_CS_N<0>")
	)
	(segment
		(start 181.658514 -240.848642)
		(end 181.330854 -240.848642)
		(width 0.18288)
		(layer "In6.Cu")
		(net "M_H_CPU1_SB_CS_N<0>")
	)
	(segment
		(start 134.397496 -243.607082)
		(end 134.382764 -243.598446)
		(width 0.088646)
		(layer "In6.Cu")
		(net "M_H_CPU1_SB_CS_N<0>")
	)
	(segment
		(start 198.546466 -240.748566)
		(end 197.944486 -240.146586)
		(width 0.18288)
		(layer "In6.Cu")
		(net "M_H_CPU1_SB_CS_N<0>")
	)
	(segment
		(start 194.868546 -240.146586)
		(end 194.523106 -240.492026)
		(width 0.18288)
		(layer "In6.Cu")
		(net "M_H_CPU1_SB_CS_N<0>")
	)
	(segment
		(start 181.147974 -240.665762)
		(end 181.147974 -240.115598)
		(width 0.18288)
		(layer "In6.Cu")
		(net "M_H_CPU1_SB_CS_N<0>")
	)
	(segment
		(start 204.732382 -241.092482)
		(end 202.636628 -241.092482)
		(width 0.18288)
		(layer "In6.Cu")
		(net "M_H_CPU1_SB_CS_N<0>")
	)
	(segment
		(start 181.841394 -240.665762)
		(end 181.658514 -240.848642)
		(width 0.18288)
		(layer "In6.Cu")
		(net "M_H_CPU1_SB_CS_N<0>")
	)
	(segment
		(start 157.034484 -239.393222)
		(end 156.181552 -240.246154)
		(width 0.18288)
		(layer "In6.Cu")
		(net "M_H_CPU1_SB_CS_N<0>")
	)
	(segment
		(start 175.194722 -241.092228)
		(end 168.755568 -241.092228)
		(width 0.18288)
		(layer "In6.Cu")
		(net "M_H_CPU1_SB_CS_N<0>")
	)
	(segment
		(start 202.636628 -241.092482)
		(end 202.292712 -240.748566)
		(width 0.18288)
		(layer "In6.Cu")
		(net "M_H_CPU1_SB_CS_N<0>")
	)
	(segment
		(start 192.77965 -241.092482)
		(end 191.32677 -241.092482)
		(width 0.18288)
		(layer "In6.Cu")
		(net "M_H_CPU1_SB_CS_N<0>")
	)
	(segment
		(start 181.841394 -240.115598)
		(end 181.841394 -240.665762)
		(width 0.18288)
		(layer "In6.Cu")
		(net "M_H_CPU1_SB_CS_N<0>")
	)
	(segment
		(start 131.578096 -243.607082)
		(end 131.563364 -243.598446)
		(width 0.088646)
		(layer "In6.Cu")
		(net "M_H_CPU1_SB_CS_N<0>")
	)
	(segment
		(start 137.813034 -243.866416)
		(end 137.470134 -243.866416)
		(width 0.088646)
		(layer "In6.Cu")
		(net "M_H_CPU1_SB_CS_N<0>")
	)
	(segment
		(start 176.044606 -240.242344)
		(end 175.194722 -241.092228)
		(width 0.18288)
		(layer "In6.Cu")
		(net "M_H_CPU1_SB_CS_N<0>")
	)
	(segment
		(start 150.18385 -243.546376)
		(end 138.947906 -243.546376)
		(width 0.18288)
		(layer "In6.Cu")
		(net "M_H_CPU1_SB_CS_N<0>")
	)
	(segment
		(start 193.380106 -240.492026)
		(end 192.77965 -241.092482)
		(width 0.18288)
		(layer "In6.Cu")
		(net "M_H_CPU1_SB_CS_N<0>")
	)
	(segment
		(start 196.373496 -240.704116)
		(end 196.190616 -240.521236)
		(width 0.18288)
		(layer "In6.Cu")
		(net "M_H_CPU1_SB_CS_N<0>")
	)
	(segment
		(start 211.243672 -241.944906)
		(end 205.584806 -241.944906)
		(width 0.18288)
		(layer "In6.Cu")
		(net "M_H_CPU1_SB_CS_N<0>")
	)
	(segment
		(start 205.584806 -241.944906)
		(end 204.732382 -241.092482)
		(width 0.18288)
		(layer "In6.Cu")
		(net "M_H_CPU1_SB_CS_N<0>")
	)
	(segment
		(start 128.754378 -243.604542)
		(end 128.743964 -243.598446)
		(width 0.088646)
		(layer "In6.Cu")
		(net "M_H_CPU1_SB_CS_N<0>")
	)
	(segment
		(start 197.066916 -240.146586)
		(end 196.884036 -240.329466)
		(width 0.18288)
		(layer "In6.Cu")
		(net "M_H_CPU1_SB_CS_N<0>")
	)
	(segment
		(start 127.804164 -243.598446)
		(end 127.798068 -243.59489)
		(width 0.088646)
		(layer "In6.Cu")
		(net "M_H_CPU1_SB_CS_N<0>")
	)
	(segment
		(start 196.190616 -240.329466)
		(end 196.007736 -240.146586)
		(width 0.18288)
		(layer "In6.Cu")
		(net "M_H_CPU1_SB_CS_N<0>")
	)
	(segment
		(start 201.03211 -241.492278)
		(end 200.84923 -241.675158)
		(width 0.18288)
		(layer "In6.Cu")
		(net "M_H_CPU1_SB_CS_N<0>")
	)
	(segment
		(start 177.899568 -240.242344)
		(end 176.044606 -240.242344)
		(width 0.18288)
		(layer "In6.Cu")
		(net "M_H_CPU1_SB_CS_N<0>")
	)
	(segment
		(start 138.627866 -243.866416)
		(end 137.813034 -243.866416)
		(width 0.18288)
		(layer "In6.Cu")
		(net "M_H_CPU1_SB_CS_N<0>")
	)
	(segment
		(start 182.024274 -239.932718)
		(end 181.841394 -240.115598)
		(width 0.18288)
		(layer "In6.Cu")
		(net "M_H_CPU1_SB_CS_N<0>")
	)
	(segment
		(start 211.700872 -244.580664)
		(end 211.700872 -242.402106)
		(width 0.18288)
		(layer "In6.Cu")
		(net "M_H_CPU1_SB_CS_N<0>")
	)
	(segment
		(start 201.21499 -240.748566)
		(end 201.03211 -240.931446)
		(width 0.18288)
		(layer "In6.Cu")
		(net "M_H_CPU1_SB_CS_N<0>")
	)
	(segment
		(start 183.108092 -239.932718)
		(end 182.024274 -239.932718)
		(width 0.18288)
		(layer "In6.Cu")
		(net "M_H_CPU1_SB_CS_N<0>")
	)
	(segment
		(start 197.944486 -240.146586)
		(end 197.066916 -240.146586)
		(width 0.18288)
		(layer "In6.Cu")
		(net "M_H_CPU1_SB_CS_N<0>")
	)
	(segment
		(start 168.755568 -241.092228)
		(end 167.774366 -240.111026)
		(width 0.18288)
		(layer "In6.Cu")
		(net "M_H_CPU1_SB_CS_N<0>")
	)
	(segment
		(start 200.33869 -240.931446)
		(end 200.15581 -240.748566)
		(width 0.18288)
		(layer "In6.Cu")
		(net "M_H_CPU1_SB_CS_N<0>")
	)
	(segment
		(start 137.470134 -243.866416)
		(end 137.202164 -243.598446)
		(width 0.088646)
		(layer "In6.Cu")
		(net "M_H_CPU1_SB_CS_N<0>")
	)
	(segment
		(start 211.700872 -242.402106)
		(end 211.243672 -241.944906)
		(width 0.18288)
		(layer "In6.Cu")
		(net "M_H_CPU1_SB_CS_N<0>")
	)
	(segment
		(start 200.15581 -240.748566)
		(end 198.546466 -240.748566)
		(width 0.18288)
		(layer "In6.Cu")
		(net "M_H_CPU1_SB_CS_N<0>")
	)
	(segment
		(start 138.947906 -243.546376)
		(end 138.627866 -243.866416)
		(width 0.18288)
		(layer "In6.Cu")
		(net "M_H_CPU1_SB_CS_N<0>")
	)
	(segment
		(start 178.787806 -239.354106)
		(end 177.899568 -240.242344)
		(width 0.18288)
		(layer "In6.Cu")
		(net "M_H_CPU1_SB_CS_N<0>")
	)
	(segment
		(start 191.32677 -241.092482)
		(end 190.476632 -240.242344)
		(width 0.18288)
		(layer "In6.Cu")
		(net "M_H_CPU1_SB_CS_N<0>")
	)
	(segment
		(start 157.804866 -239.393222)
		(end 157.034484 -239.393222)
		(width 0.18288)
		(layer "In6.Cu")
		(net "M_H_CPU1_SB_CS_N<0>")
	)
	(segment
		(start 163.557966 -240.834926)
		(end 162.116516 -239.393476)
		(width 0.18288)
		(layer "In6.Cu")
		(net "M_H_CPU1_SB_CS_N<0>")
	)
	(segment
		(start 200.52157 -241.675158)
		(end 200.33869 -241.492278)
		(width 0.18288)
		(layer "In6.Cu")
		(net "M_H_CPU1_SB_CS_N<0>")
	)
	(segment
		(start 162.116516 -239.393476)
		(end 157.80512 -239.393476)
		(width 0.18288)
		(layer "In6.Cu")
		(net "M_H_CPU1_SB_CS_N<0>")
	)
	(segment
		(start 202.292712 -240.748566)
		(end 201.21499 -240.748566)
		(width 0.18288)
		(layer "In6.Cu")
		(net "M_H_CPU1_SB_CS_N<0>")
	)
	(segment
		(start 200.84923 -241.675158)
		(end 200.52157 -241.675158)
		(width 0.18288)
		(layer "In6.Cu")
		(net "M_H_CPU1_SB_CS_N<0>")
	)
	(segment
		(start 153.484072 -240.246154)
		(end 150.18385 -243.546376)
		(width 0.18288)
		(layer "In6.Cu")
		(net "M_H_CPU1_SB_CS_N<0>")
	)
	(segment
		(start 201.03211 -240.931446)
		(end 201.03211 -241.492278)
		(width 0.18288)
		(layer "In6.Cu")
		(net "M_H_CPU1_SB_CS_N<0>")
	)
	(segment
		(start 210.514946 -245.76659)
		(end 211.700872 -244.580664)
		(width 0.18288)
		(layer "In6.Cu")
		(net "M_H_CPU1_SB_CS_N<0>")
	)
	(segment
		(start 196.007736 -240.146586)
		(end 194.868546 -240.146586)
		(width 0.18288)
		(layer "In6.Cu")
		(net "M_H_CPU1_SB_CS_N<0>")
	)
	(segment
		(start 157.80512 -239.393476)
		(end 157.804866 -239.393222)
		(width 0.18288)
		(layer "In6.Cu")
		(net "M_H_CPU1_SB_CS_N<0>")
	)
	(segment
		(start 164.431726 -240.834926)
		(end 163.557966 -240.834926)
		(width 0.18288)
		(layer "In6.Cu")
		(net "M_H_CPU1_SB_CS_N<0>")
	)
	(arc
		(start 132.503164 -243.598446)
		(mid 132.315966 -243.548303)
		(end 132.128768 -243.598446)
		(width 0.088646)
		(layer "In6.Cu")
		(net "M_H_CPU1_SB_CS_N<0>")
	)
	(arc
		(start 131.188968 -243.598446)
		(mid 130.914769 -243.674281)
		(end 130.638296 -243.607082)
		(width 0.088646)
		(layer "In6.Cu")
		(net "M_H_CPU1_SB_CS_N<0>")
	)
	(arc
		(start 130.623564 -243.598446)
		(mid 130.436366 -243.548303)
		(end 130.249168 -243.598446)
		(width 0.088646)
		(layer "In6.Cu")
		(net "M_H_CPU1_SB_CS_N<0>")
	)
	(arc
		(start 128.369568 -243.598446)
		(mid 128.095369 -243.674281)
		(end 127.818896 -243.607082)
		(width 0.088646)
		(layer "In6.Cu")
		(net "M_H_CPU1_SB_CS_N<0>")
	)
	(arc
		(start 134.008368 -243.598446)
		(mid 133.725666 -243.674222)
		(end 133.442964 -243.598446)
		(width 0.088646)
		(layer "In6.Cu")
		(net "M_H_CPU1_SB_CS_N<0>")
	)
	(arc
		(start 131.563364 -243.598446)
		(mid 131.376166 -243.548303)
		(end 131.188968 -243.598446)
		(width 0.088646)
		(layer "In6.Cu")
		(net "M_H_CPU1_SB_CS_N<0>")
	)
	(arc
		(start 134.948168 -243.598446)
		(mid 134.673969 -243.674281)
		(end 134.397496 -243.607082)
		(width 0.088646)
		(layer "In6.Cu")
		(net "M_H_CPU1_SB_CS_N<0>")
	)
	(arc
		(start 130.249168 -243.598446)
		(mid 129.972355 -243.674316)
		(end 129.693924 -243.604542)
		(width 0.088646)
		(layer "In6.Cu")
		(net "M_H_CPU1_SB_CS_N<0>")
	)
	(arc
		(start 128.743964 -243.598446)
		(mid 128.556766 -243.548303)
		(end 128.369568 -243.598446)
		(width 0.088646)
		(layer "In6.Cu")
		(net "M_H_CPU1_SB_CS_N<0>")
	)
	(arc
		(start 135.322564 -243.598446)
		(mid 135.135366 -243.548303)
		(end 134.948168 -243.598446)
		(width 0.088646)
		(layer "In6.Cu")
		(net "M_H_CPU1_SB_CS_N<0>")
	)
	(arc
		(start 136.827768 -243.598446)
		(mid 136.545066 -243.674222)
		(end 136.262364 -243.598446)
		(width 0.088646)
		(layer "In6.Cu")
		(net "M_H_CPU1_SB_CS_N<0>")
	)
	(arc
		(start 127.798068 -243.59489)
		(mid 127.612545 -243.416589)
		(end 127.525272 -243.17452)
		(width 0.088646)
		(layer "In6.Cu")
		(net "M_H_CPU1_SB_CS_N<0>")
	)
	(arc
		(start 133.442964 -243.598446)
		(mid 133.255766 -243.548303)
		(end 133.068568 -243.598446)
		(width 0.088646)
		(layer "In6.Cu")
		(net "M_H_CPU1_SB_CS_N<0>")
	)
	(arc
		(start 137.202164 -243.598446)
		(mid 137.014966 -243.548303)
		(end 136.827768 -243.598446)
		(width 0.088646)
		(layer "In6.Cu")
		(net "M_H_CPU1_SB_CS_N<0>")
	)
	(arc
		(start 135.887968 -243.598446)
		(mid 135.605266 -243.674222)
		(end 135.322564 -243.598446)
		(width 0.088646)
		(layer "In6.Cu")
		(net "M_H_CPU1_SB_CS_N<0>")
	)
	(arc
		(start 132.128768 -243.598446)
		(mid 131.854569 -243.674281)
		(end 131.578096 -243.607082)
		(width 0.088646)
		(layer "In6.Cu")
		(net "M_H_CPU1_SB_CS_N<0>")
	)
	(arc
		(start 129.309114 -243.598446)
		(mid 129.032555 -243.674189)
		(end 128.754378 -243.604542)
		(width 0.088646)
		(layer "In6.Cu")
		(net "M_H_CPU1_SB_CS_N<0>")
	)
	(arc
		(start 136.262364 -243.598446)
		(mid 136.075166 -243.548303)
		(end 135.887968 -243.598446)
		(width 0.088646)
		(layer "In6.Cu")
		(net "M_H_CPU1_SB_CS_N<0>")
	)
	(arc
		(start 129.68351 -243.598446)
		(mid 129.496312 -243.548303)
		(end 129.309114 -243.598446)
		(width 0.088646)
		(layer "In6.Cu")
		(net "M_H_CPU1_SB_CS_N<0>")
	)
	(arc
		(start 133.068568 -243.598446)
		(mid 132.785866 -243.674222)
		(end 132.503164 -243.598446)
		(width 0.088646)
		(layer "In6.Cu")
		(net "M_H_CPU1_SB_CS_N<0>")
	)
	(arc
		(start 134.382764 -243.598446)
		(mid 134.195566 -243.548303)
		(end 134.008368 -243.598446)
		(width 0.088646)
		(layer "In6.Cu")
		(net "M_H_CPU1_SB_CS_N<0>")
	)
	(segment
		(start 210.610196 -239.391698)
		(end 212.618066 -239.391698)
		(width 0.1016)
		(layer "F.Cu")
		(net "M_H_CPU1_SB_CB<7>")
	)
	(segment
		(start 214.385652 -238.966756)
		(end 215.719914 -238.966756)
		(width 0.20066)
		(layer "F.Cu")
		(net "M_H_CPU1_SB_CB<7>")
	)
	(segment
		(start 213.515448 -238.948976)
		(end 213.749636 -238.714788)
		(width 0.20066)
		(layer "F.Cu")
		(net "M_H_CPU1_SB_CB<7>")
	)
	(segment
		(start 210.306412 -239.39881)
		(end 210.598258 -239.39881)
		(width 0.20066)
		(layer "F.Cu")
		(net "M_H_CPU1_SB_CB<7>")
	)
	(segment
		(start 212.630258 -239.40389)
		(end 213.311486 -239.40389)
		(width 0.20066)
		(layer "F.Cu")
		(net "M_H_CPU1_SB_CB<7>")
	)
	(segment
		(start 210.598258 -239.39881)
		(end 210.603084 -239.39881)
		(width 0.101854)
		(layer "F.Cu")
		(net "M_H_CPU1_SB_CB<7>")
	)
	(segment
		(start 213.311486 -239.40389)
		(end 213.515448 -239.199928)
		(width 0.20066)
		(layer "F.Cu")
		(net "M_H_CPU1_SB_CB<7>")
	)
	(segment
		(start 123.387866 -243.644928)
		(end 123.387612 -243.644674)
		(width 0.20066)
		(layer "F.Cu")
		(net "M_H_CPU1_SB_CB<7>")
	)
	(segment
		(start 207.071214 -238.966756)
		(end 208.176114 -238.966756)
		(width 0.20066)
		(layer "F.Cu")
		(net "M_H_CPU1_SB_CB<7>")
	)
	(segment
		(start 214.133684 -238.714788)
		(end 214.385652 -238.966756)
		(width 0.20066)
		(layer "F.Cu")
		(net "M_H_CPU1_SB_CB<7>")
	)
	(segment
		(start 210.603084 -239.39881)
		(end 210.610196 -239.391698)
		(width 0.1016)
		(layer "F.Cu")
		(net "M_H_CPU1_SB_CB<7>")
	)
	(segment
		(start 123.387612 -243.644674)
		(end 123.387612 -243.108988)
		(width 0.20066)
		(layer "F.Cu")
		(net "M_H_CPU1_SB_CB<7>")
	)
	(segment
		(start 212.618066 -239.391698)
		(end 212.630258 -239.40389)
		(width 0.1016)
		(layer "F.Cu")
		(net "M_H_CPU1_SB_CB<7>")
	)
	(segment
		(start 209.874358 -238.966756)
		(end 210.306412 -239.39881)
		(width 0.20066)
		(layer "F.Cu")
		(net "M_H_CPU1_SB_CB<7>")
	)
	(segment
		(start 213.749636 -238.714788)
		(end 214.133684 -238.714788)
		(width 0.20066)
		(layer "F.Cu")
		(net "M_H_CPU1_SB_CB<7>")
	)
	(segment
		(start 208.176114 -238.966756)
		(end 209.874358 -238.966756)
		(width 0.20066)
		(layer "F.Cu")
		(net "M_H_CPU1_SB_CB<7>")
	)
	(segment
		(start 213.515448 -239.199928)
		(end 213.515448 -238.948976)
		(width 0.20066)
		(layer "F.Cu")
		(net "M_H_CPU1_SB_CB<7>")
	)
	(segment
		(start 193.819526 -239.323626)
		(end 192.624202 -240.241582)
		(width 0.18288)
		(layer "In11.Cu")
		(net "M_H_CPU1_SB_CB<7>")
	)
	(segment
		(start 165.411404 -239.46358)
		(end 164.55898 -239.46358)
		(width 0.18288)
		(layer "In11.Cu")
		(net "M_H_CPU1_SB_CB<7>")
	)
	(segment
		(start 199.874378 -239.349026)
		(end 199.128126 -239.349026)
		(width 0.18288)
		(layer "In11.Cu")
		(net "M_H_CPU1_SB_CB<7>")
	)
	(segment
		(start 140.292582 -244.482112)
		(end 139.871196 -244.060726)
		(width 0.088646)
		(layer "In11.Cu")
		(net "M_H_CPU1_SB_CB<7>")
	)
	(segment
		(start 185.739786 -239.1791)
		(end 185.004456 -238.764826)
		(width 0.18288)
		(layer "In11.Cu")
		(net "M_H_CPU1_SB_CB<7>")
	)
	(segment
		(start 130.638296 -243.607082)
		(end 130.623564 -243.598446)
		(width 0.088646)
		(layer "In11.Cu")
		(net "M_H_CPU1_SB_CB<7>")
	)
	(segment
		(start 143.023082 -244.482112)
		(end 140.569696 -244.482112)
		(width 0.18288)
		(layer "In11.Cu")
		(net "M_H_CPU1_SB_CB<7>")
	)
	(segment
		(start 174.01794 -238.538512)
		(end 173.165008 -239.391444)
		(width 0.18288)
		(layer "In11.Cu")
		(net "M_H_CPU1_SB_CB<7>")
	)
	(segment
		(start 180.849778 -237.953804)
		(end 180.849778 -238.345472)
		(width 0.18288)
		(layer "In11.Cu")
		(net "M_H_CPU1_SB_CB<7>")
	)
	(segment
		(start 125.924564 -243.598446)
		(end 125.83287 -243.545614)
		(width 0.088646)
		(layer "In11.Cu")
		(net "M_H_CPU1_SB_CB<7>")
	)
	(segment
		(start 164.55898 -239.46358)
		(end 164.367718 -239.272318)
		(width 0.18288)
		(layer "In11.Cu")
		(net "M_H_CPU1_SB_CB<7>")
	)
	(segment
		(start 151.938736 -241.165634)
		(end 148.7678 -244.33657)
		(width 0.18288)
		(layer "In11.Cu")
		(net "M_H_CPU1_SB_CB<7>")
	)
	(segment
		(start 167.028368 -238.510826)
		(end 165.411404 -239.46358)
		(width 0.18288)
		(layer "In11.Cu")
		(net "M_H_CPU1_SB_CB<7>")
	)
	(segment
		(start 179.52212 -238.733838)
		(end 178.483514 -238.733838)
		(width 0.18288)
		(layer "In11.Cu")
		(net "M_H_CPU1_SB_CB<7>")
	)
	(segment
		(start 200.890378 -240.365026)
		(end 199.874378 -239.349026)
		(width 0.18288)
		(layer "In11.Cu")
		(net "M_H_CPU1_SB_CB<7>")
	)
	(segment
		(start 134.397496 -243.607082)
		(end 134.382764 -243.598446)
		(width 0.088646)
		(layer "In11.Cu")
		(net "M_H_CPU1_SB_CB<7>")
	)
	(segment
		(start 197.699884 -239.628426)
		(end 195.051426 -239.628426)
		(width 0.18288)
		(layer "In11.Cu")
		(net "M_H_CPU1_SB_CB<7>")
	)
	(segment
		(start 128.754378 -243.604542)
		(end 128.743964 -243.598446)
		(width 0.088646)
		(layer "In11.Cu")
		(net "M_H_CPU1_SB_CB<7>")
	)
	(segment
		(start 202.1205 -240.365026)
		(end 200.890378 -240.365026)
		(width 0.18288)
		(layer "In11.Cu")
		(net "M_H_CPU1_SB_CB<7>")
	)
	(segment
		(start 136.74344 -244.060726)
		(end 136.340342 -243.657628)
		(width 0.088646)
		(layer "In11.Cu")
		(net "M_H_CPU1_SB_CB<7>")
	)
	(segment
		(start 178.288188 -238.538512)
		(end 174.01794 -238.538512)
		(width 0.18288)
		(layer "In11.Cu")
		(net "M_H_CPU1_SB_CB<7>")
	)
	(segment
		(start 189.74181 -240.060226)
		(end 189.07252 -239.390936)
		(width 0.18288)
		(layer "In11.Cu")
		(net "M_H_CPU1_SB_CB<7>")
	)
	(segment
		(start 184.142126 -238.764826)
		(end 183.737758 -238.538512)
		(width 0.18288)
		(layer "In11.Cu")
		(net "M_H_CPU1_SB_CB<7>")
	)
	(segment
		(start 168.305226 -238.739426)
		(end 168.076626 -238.510826)
		(width 0.18288)
		(layer "In11.Cu")
		(net "M_H_CPU1_SB_CB<7>")
	)
	(segment
		(start 148.7678 -244.33657)
		(end 143.168624 -244.33657)
		(width 0.18288)
		(layer "In11.Cu")
		(net "M_H_CPU1_SB_CB<7>")
	)
	(segment
		(start 202.243182 -240.242344)
		(end 202.1205 -240.365026)
		(width 0.18288)
		(layer "In11.Cu")
		(net "M_H_CPU1_SB_CB<7>")
	)
	(segment
		(start 179.717446 -238.538512)
		(end 179.52212 -238.733838)
		(width 0.18288)
		(layer "In11.Cu")
		(net "M_H_CPU1_SB_CB<7>")
	)
	(segment
		(start 181.746398 -238.538512)
		(end 181.553358 -238.345472)
		(width 0.18288)
		(layer "In11.Cu")
		(net "M_H_CPU1_SB_CB<7>")
	)
	(segment
		(start 123.464828 -243.108988)
		(end 123.387612 -243.108988)
		(width 0.088646)
		(layer "In11.Cu")
		(net "M_H_CPU1_SB_CB<7>")
	)
	(segment
		(start 160.640014 -239.272318)
		(end 159.191706 -240.720626)
		(width 0.18288)
		(layer "In11.Cu")
		(net "M_H_CPU1_SB_CB<7>")
	)
	(segment
		(start 199.128126 -239.349026)
		(end 197.699884 -239.628426)
		(width 0.18288)
		(layer "In11.Cu")
		(net "M_H_CPU1_SB_CB<7>")
	)
	(segment
		(start 125.83287 -243.545614)
		(end 125.458474 -243.555774)
		(width 0.088646)
		(layer "In11.Cu")
		(net "M_H_CPU1_SB_CB<7>")
	)
	(segment
		(start 169.829226 -238.739426)
		(end 168.305226 -238.739426)
		(width 0.18288)
		(layer "In11.Cu")
		(net "M_H_CPU1_SB_CB<7>")
	)
	(segment
		(start 195.051426 -239.628426)
		(end 194.746626 -239.323626)
		(width 0.18288)
		(layer "In11.Cu")
		(net "M_H_CPU1_SB_CB<7>")
	)
	(segment
		(start 164.367718 -239.272318)
		(end 160.640014 -239.272318)
		(width 0.18288)
		(layer "In11.Cu")
		(net "M_H_CPU1_SB_CB<7>")
	)
	(segment
		(start 143.168624 -244.33657)
		(end 143.023082 -244.482112)
		(width 0.18288)
		(layer "In11.Cu")
		(net "M_H_CPU1_SB_CB<7>")
	)
	(segment
		(start 168.076626 -238.510826)
		(end 167.028368 -238.510826)
		(width 0.18288)
		(layer "In11.Cu")
		(net "M_H_CPU1_SB_CB<7>")
	)
	(segment
		(start 129.693924 -243.604542)
		(end 129.68351 -243.598446)
		(width 0.088646)
		(layer "In11.Cu")
		(net "M_H_CPU1_SB_CB<7>")
	)
	(segment
		(start 139.871196 -244.060726)
		(end 136.74344 -244.060726)
		(width 0.088646)
		(layer "In11.Cu")
		(net "M_H_CPU1_SB_CB<7>")
	)
	(segment
		(start 178.483514 -238.733838)
		(end 178.288188 -238.538512)
		(width 0.18288)
		(layer "In11.Cu")
		(net "M_H_CPU1_SB_CB<7>")
	)
	(segment
		(start 191.063626 -240.060226)
		(end 189.74181 -240.060226)
		(width 0.18288)
		(layer "In11.Cu")
		(net "M_H_CPU1_SB_CB<7>")
	)
	(segment
		(start 181.360318 -237.760764)
		(end 181.042818 -237.760764)
		(width 0.18288)
		(layer "In11.Cu")
		(net "M_H_CPU1_SB_CB<7>")
	)
	(segment
		(start 173.165008 -239.391444)
		(end 172.106844 -239.391444)
		(width 0.18288)
		(layer "In11.Cu")
		(net "M_H_CPU1_SB_CB<7>")
	)
	(segment
		(start 189.07252 -239.390936)
		(end 186.98845 -239.390936)
		(width 0.18288)
		(layer "In11.Cu")
		(net "M_H_CPU1_SB_CB<7>")
	)
	(segment
		(start 181.553358 -237.953804)
		(end 181.360318 -237.760764)
		(width 0.18288)
		(layer "In11.Cu")
		(net "M_H_CPU1_SB_CB<7>")
	)
	(segment
		(start 172.106844 -239.391444)
		(end 171.988226 -239.272826)
		(width 0.18288)
		(layer "In11.Cu")
		(net "M_H_CPU1_SB_CB<7>")
	)
	(segment
		(start 185.004456 -238.764826)
		(end 184.142126 -238.764826)
		(width 0.18288)
		(layer "In11.Cu")
		(net "M_H_CPU1_SB_CB<7>")
	)
	(segment
		(start 206.71409 -239.099852)
		(end 203.867766 -240.242344)
		(width 0.18288)
		(layer "In11.Cu")
		(net "M_H_CPU1_SB_CB<7>")
	)
	(segment
		(start 158.117794 -241.165634)
		(end 151.938736 -241.165634)
		(width 0.18288)
		(layer "In11.Cu")
		(net "M_H_CPU1_SB_CB<7>")
	)
	(segment
		(start 131.578096 -243.607082)
		(end 131.563364 -243.598446)
		(width 0.088646)
		(layer "In11.Cu")
		(net "M_H_CPU1_SB_CB<7>")
	)
	(segment
		(start 180.656738 -238.538512)
		(end 179.717446 -238.538512)
		(width 0.18288)
		(layer "In11.Cu")
		(net "M_H_CPU1_SB_CB<7>")
	)
	(segment
		(start 170.362626 -239.272826)
		(end 169.829226 -238.739426)
		(width 0.18288)
		(layer "In11.Cu")
		(net "M_H_CPU1_SB_CB<7>")
	)
	(segment
		(start 180.849778 -238.345472)
		(end 180.656738 -238.538512)
		(width 0.18288)
		(layer "In11.Cu")
		(net "M_H_CPU1_SB_CB<7>")
	)
	(segment
		(start 203.867766 -240.242344)
		(end 202.243182 -240.242344)
		(width 0.18288)
		(layer "In11.Cu")
		(net "M_H_CPU1_SB_CB<7>")
	)
	(segment
		(start 159.191706 -240.720626)
		(end 158.117794 -241.165634)
		(width 0.18288)
		(layer "In11.Cu")
		(net "M_H_CPU1_SB_CB<7>")
	)
	(segment
		(start 181.553358 -238.345472)
		(end 181.553358 -237.953804)
		(width 0.18288)
		(layer "In11.Cu")
		(net "M_H_CPU1_SB_CB<7>")
	)
	(segment
		(start 191.244982 -240.241582)
		(end 191.063626 -240.060226)
		(width 0.18288)
		(layer "In11.Cu")
		(net "M_H_CPU1_SB_CB<7>")
	)
	(segment
		(start 186.776614 -239.1791)
		(end 185.739786 -239.1791)
		(width 0.18288)
		(layer "In11.Cu")
		(net "M_H_CPU1_SB_CB<7>")
	)
	(segment
		(start 194.746626 -239.323626)
		(end 193.819526 -239.323626)
		(width 0.18288)
		(layer "In11.Cu")
		(net "M_H_CPU1_SB_CB<7>")
	)
	(segment
		(start 140.569696 -244.482112)
		(end 140.292582 -244.482112)
		(width 0.088646)
		(layer "In11.Cu")
		(net "M_H_CPU1_SB_CB<7>")
	)
	(segment
		(start 171.988226 -239.272826)
		(end 170.362626 -239.272826)
		(width 0.18288)
		(layer "In11.Cu")
		(net "M_H_CPU1_SB_CB<7>")
	)
	(segment
		(start 207.071214 -238.966756)
		(end 207.059022 -238.961422)
		(width 0.18288)
		(layer "In11.Cu")
		(net "M_H_CPU1_SB_CB<7>")
	)
	(segment
		(start 192.624202 -240.241582)
		(end 191.244982 -240.241582)
		(width 0.18288)
		(layer "In11.Cu")
		(net "M_H_CPU1_SB_CB<7>")
	)
	(segment
		(start 126.879096 -243.607082)
		(end 126.864364 -243.598446)
		(width 0.088646)
		(layer "In11.Cu")
		(net "M_H_CPU1_SB_CB<7>")
	)
	(segment
		(start 207.059022 -238.961422)
		(end 206.71409 -239.099852)
		(width 0.18288)
		(layer "In11.Cu")
		(net "M_H_CPU1_SB_CB<7>")
	)
	(segment
		(start 183.737758 -238.538512)
		(end 181.746398 -238.538512)
		(width 0.18288)
		(layer "In11.Cu")
		(net "M_H_CPU1_SB_CB<7>")
	)
	(segment
		(start 181.042818 -237.760764)
		(end 180.849778 -237.953804)
		(width 0.18288)
		(layer "In11.Cu")
		(net "M_H_CPU1_SB_CB<7>")
	)
	(segment
		(start 186.98845 -239.390936)
		(end 186.776614 -239.1791)
		(width 0.18288)
		(layer "In11.Cu")
		(net "M_H_CPU1_SB_CB<7>")
	)
	(segment
		(start 127.818896 -243.607082)
		(end 127.804164 -243.598446)
		(width 0.088646)
		(layer "In11.Cu")
		(net "M_H_CPU1_SB_CB<7>")
	)
	(arc
		(start 126.864364 -243.598446)
		(mid 126.677166 -243.548303)
		(end 126.489968 -243.598446)
		(width 0.088646)
		(layer "In11.Cu")
		(net "M_H_CPU1_SB_CB<7>")
	)
	(arc
		(start 134.008368 -243.598446)
		(mid 133.725666 -243.674222)
		(end 133.442964 -243.598446)
		(width 0.088646)
		(layer "In11.Cu")
		(net "M_H_CPU1_SB_CB<7>")
	)
	(arc
		(start 127.804164 -243.598446)
		(mid 127.616966 -243.548303)
		(end 127.429768 -243.598446)
		(width 0.088646)
		(layer "In11.Cu")
		(net "M_H_CPU1_SB_CB<7>")
	)
	(arc
		(start 124.558044 -243.40439)
		(mid 124.298273 -243.482448)
		(end 124.053854 -243.364766)
		(width 0.088646)
		(layer "In11.Cu")
		(net "M_H_CPU1_SB_CB<7>")
	)
	(arc
		(start 124.053854 -243.364766)
		(mid 123.785921 -243.175652)
		(end 123.464828 -243.108988)
		(width 0.088646)
		(layer "In11.Cu")
		(net "M_H_CPU1_SB_CB<7>")
	)
	(arc
		(start 131.563364 -243.598446)
		(mid 131.376166 -243.548303)
		(end 131.188968 -243.598446)
		(width 0.088646)
		(layer "In11.Cu")
		(net "M_H_CPU1_SB_CB<7>")
	)
	(arc
		(start 134.382764 -243.598446)
		(mid 134.195566 -243.548303)
		(end 134.008368 -243.598446)
		(width 0.088646)
		(layer "In11.Cu")
		(net "M_H_CPU1_SB_CB<7>")
	)
	(arc
		(start 128.369568 -243.598446)
		(mid 128.095369 -243.674281)
		(end 127.818896 -243.607082)
		(width 0.088646)
		(layer "In11.Cu")
		(net "M_H_CPU1_SB_CB<7>")
	)
	(arc
		(start 134.948168 -243.598446)
		(mid 134.673969 -243.674281)
		(end 134.397496 -243.607082)
		(width 0.088646)
		(layer "In11.Cu")
		(net "M_H_CPU1_SB_CB<7>")
	)
	(arc
		(start 131.188968 -243.598446)
		(mid 130.914769 -243.674281)
		(end 130.638296 -243.607082)
		(width 0.088646)
		(layer "In11.Cu")
		(net "M_H_CPU1_SB_CB<7>")
	)
	(arc
		(start 132.503164 -243.598446)
		(mid 132.315966 -243.548303)
		(end 132.128768 -243.598446)
		(width 0.088646)
		(layer "In11.Cu")
		(net "M_H_CPU1_SB_CB<7>")
	)
	(arc
		(start 136.262364 -243.598446)
		(mid 136.075166 -243.548303)
		(end 135.887968 -243.598446)
		(width 0.088646)
		(layer "In11.Cu")
		(net "M_H_CPU1_SB_CB<7>")
	)
	(arc
		(start 129.68351 -243.598446)
		(mid 129.496312 -243.548303)
		(end 129.309114 -243.598446)
		(width 0.088646)
		(layer "In11.Cu")
		(net "M_H_CPU1_SB_CB<7>")
	)
	(arc
		(start 125.024134 -243.408708)
		(mid 124.791853 -243.325198)
		(end 124.558044 -243.40439)
		(width 0.088646)
		(layer "In11.Cu")
		(net "M_H_CPU1_SB_CB<7>")
	)
	(arc
		(start 129.309114 -243.598446)
		(mid 129.032555 -243.674189)
		(end 128.754378 -243.604542)
		(width 0.088646)
		(layer "In11.Cu")
		(net "M_H_CPU1_SB_CB<7>")
	)
	(arc
		(start 132.128768 -243.598446)
		(mid 131.854569 -243.674281)
		(end 131.578096 -243.607082)
		(width 0.088646)
		(layer "In11.Cu")
		(net "M_H_CPU1_SB_CB<7>")
	)
	(arc
		(start 135.322564 -243.598446)
		(mid 135.135366 -243.548303)
		(end 134.948168 -243.598446)
		(width 0.088646)
		(layer "In11.Cu")
		(net "M_H_CPU1_SB_CB<7>")
	)
	(arc
		(start 127.429768 -243.598446)
		(mid 127.155569 -243.674281)
		(end 126.879096 -243.607082)
		(width 0.088646)
		(layer "In11.Cu")
		(net "M_H_CPU1_SB_CB<7>")
	)
	(arc
		(start 125.458474 -243.555774)
		(mid 125.228136 -243.521114)
		(end 125.024134 -243.408708)
		(width 0.088646)
		(layer "In11.Cu")
		(net "M_H_CPU1_SB_CB<7>")
	)
	(arc
		(start 136.340342 -243.657628)
		(mid 136.303292 -243.625482)
		(end 136.262364 -243.598446)
		(width 0.088646)
		(layer "In11.Cu")
		(net "M_H_CPU1_SB_CB<7>")
	)
	(arc
		(start 130.249168 -243.598446)
		(mid 129.972355 -243.674316)
		(end 129.693924 -243.604542)
		(width 0.088646)
		(layer "In11.Cu")
		(net "M_H_CPU1_SB_CB<7>")
	)
	(arc
		(start 128.743964 -243.598446)
		(mid 128.556766 -243.548303)
		(end 128.369568 -243.598446)
		(width 0.088646)
		(layer "In11.Cu")
		(net "M_H_CPU1_SB_CB<7>")
	)
	(arc
		(start 133.442964 -243.598446)
		(mid 133.255766 -243.548303)
		(end 133.068568 -243.598446)
		(width 0.088646)
		(layer "In11.Cu")
		(net "M_H_CPU1_SB_CB<7>")
	)
	(arc
		(start 133.068568 -243.598446)
		(mid 132.785866 -243.674222)
		(end 132.503164 -243.598446)
		(width 0.088646)
		(layer "In11.Cu")
		(net "M_H_CPU1_SB_CB<7>")
	)
	(arc
		(start 130.623564 -243.598446)
		(mid 130.436366 -243.548303)
		(end 130.249168 -243.598446)
		(width 0.088646)
		(layer "In11.Cu")
		(net "M_H_CPU1_SB_CB<7>")
	)
	(arc
		(start 126.489968 -243.598446)
		(mid 126.207266 -243.674222)
		(end 125.924564 -243.598446)
		(width 0.088646)
		(layer "In11.Cu")
		(net "M_H_CPU1_SB_CB<7>")
	)
	(arc
		(start 135.887968 -243.598446)
		(mid 135.605266 -243.674222)
		(end 135.322564 -243.598446)
		(width 0.088646)
		(layer "In11.Cu")
		(net "M_H_CPU1_SB_CB<7>")
	)
	(segment
		(start 213.515448 -240.648998)
		(end 213.749636 -240.41481)
		(width 0.20066)
		(layer "F.Cu")
		(net "M_H_CPU1_SB_CB<6>")
	)
	(segment
		(start 207.071214 -240.666778)
		(end 208.176114 -240.666778)
		(width 0.20066)
		(layer "F.Cu")
		(net "M_H_CPU1_SB_CB<6>")
	)
	(segment
		(start 210.306412 -241.098832)
		(end 210.598258 -241.098832)
		(width 0.20066)
		(layer "F.Cu")
		(net "M_H_CPU1_SB_CB<6>")
	)
	(segment
		(start 210.603084 -241.098832)
		(end 210.610196 -241.09172)
		(width 0.1016)
		(layer "F.Cu")
		(net "M_H_CPU1_SB_CB<6>")
	)
	(segment
		(start 212.630258 -241.103912)
		(end 213.311486 -241.103912)
		(width 0.20066)
		(layer "F.Cu")
		(net "M_H_CPU1_SB_CB<6>")
	)
	(segment
		(start 210.610196 -241.09172)
		(end 212.618066 -241.09172)
		(width 0.1016)
		(layer "F.Cu")
		(net "M_H_CPU1_SB_CB<6>")
	)
	(segment
		(start 213.749636 -240.41481)
		(end 214.133684 -240.41481)
		(width 0.20066)
		(layer "F.Cu")
		(net "M_H_CPU1_SB_CB<6>")
	)
	(segment
		(start 208.176114 -240.666778)
		(end 209.874358 -240.666778)
		(width 0.20066)
		(layer "F.Cu")
		(net "M_H_CPU1_SB_CB<6>")
	)
	(segment
		(start 214.133684 -240.41481)
		(end 214.385652 -240.666778)
		(width 0.20066)
		(layer "F.Cu")
		(net "M_H_CPU1_SB_CB<6>")
	)
	(segment
		(start 213.515448 -240.89995)
		(end 213.515448 -240.648998)
		(width 0.20066)
		(layer "F.Cu")
		(net "M_H_CPU1_SB_CB<6>")
	)
	(segment
		(start 209.874358 -240.666778)
		(end 210.306412 -241.098832)
		(width 0.20066)
		(layer "F.Cu")
		(net "M_H_CPU1_SB_CB<6>")
	)
	(segment
		(start 212.618066 -241.09172)
		(end 212.630258 -241.103912)
		(width 0.1016)
		(layer "F.Cu")
		(net "M_H_CPU1_SB_CB<6>")
	)
	(segment
		(start 210.598258 -241.098832)
		(end 210.603084 -241.098832)
		(width 0.101854)
		(layer "F.Cu")
		(net "M_H_CPU1_SB_CB<6>")
	)
	(segment
		(start 123.857766 -244.45849)
		(end 123.857766 -243.922804)
		(width 0.20066)
		(layer "F.Cu")
		(net "M_H_CPU1_SB_CB<6>")
	)
	(segment
		(start 123.857512 -244.458744)
		(end 123.857766 -244.45849)
		(width 0.20066)
		(layer "F.Cu")
		(net "M_H_CPU1_SB_CB<6>")
	)
	(segment
		(start 213.311486 -241.103912)
		(end 213.515448 -240.89995)
		(width 0.20066)
		(layer "F.Cu")
		(net "M_H_CPU1_SB_CB<6>")
	)
	(segment
		(start 214.385652 -240.666778)
		(end 215.719914 -240.666778)
		(width 0.20066)
		(layer "F.Cu")
		(net "M_H_CPU1_SB_CB<6>")
	)
	(segment
		(start 135.979916 -244.755162)
		(end 135.979916 -244.73662)
		(width 0.088646)
		(layer "In11.Cu")
		(net "M_H_CPU1_SB_CB<6>")
	)
	(segment
		(start 176.318418 -240.240566)
		(end 176.169574 -240.38941)
		(width 0.18288)
		(layer "In11.Cu")
		(net "M_H_CPU1_SB_CB<6>")
	)
	(segment
		(start 172.15612 -241.09172)
		(end 171.986194 -240.921794)
		(width 0.18288)
		(layer "In11.Cu")
		(net "M_H_CPU1_SB_CB<6>")
	)
	(segment
		(start 191.67475 -241.94135)
		(end 191.571626 -241.838226)
		(width 0.18288)
		(layer "In11.Cu")
		(net "M_H_CPU1_SB_CB<6>")
	)
	(segment
		(start 143.856202 -245.21287)
		(end 143.570198 -245.498874)
		(width 0.18288)
		(layer "In11.Cu")
		(net "M_H_CPU1_SB_CB<6>")
	)
	(segment
		(start 125.080268 -244.412262)
		(end 125.069854 -244.418358)
		(width 0.088646)
		(layer "In11.Cu")
		(net "M_H_CPU1_SB_CB<6>")
	)
	(segment
		(start 184.772046 -240.649506)
		(end 182.922926 -240.238026)
		(width 0.18288)
		(layer "In11.Cu")
		(net "M_H_CPU1_SB_CB<6>")
	)
	(segment
		(start 187.116212 -241.091212)
		(end 186.948826 -240.923826)
		(width 0.18288)
		(layer "In11.Cu")
		(net "M_H_CPU1_SB_CB<6>")
	)
	(segment
		(start 182.922926 -240.238026)
		(end 179.79517 -240.238026)
		(width 0.18288)
		(layer "In11.Cu")
		(net "M_H_CPU1_SB_CB<6>")
	)
	(segment
		(start 139.058396 -245.660926)
		(end 138.699494 -245.302024)
		(width 0.088646)
		(layer "In11.Cu")
		(net "M_H_CPU1_SB_CB<6>")
	)
	(segment
		(start 128.839214 -244.412262)
		(end 128.824482 -244.420898)
		(width 0.088646)
		(layer "In11.Cu")
		(net "M_H_CPU1_SB_CB<6>")
	)
	(segment
		(start 131.658868 -244.412262)
		(end 131.648454 -244.418358)
		(width 0.088646)
		(layer "In11.Cu")
		(net "M_H_CPU1_SB_CB<6>")
	)
	(segment
		(start 206.71409 -240.831878)
		(end 204.816456 -241.741706)
		(width 0.18288)
		(layer "In11.Cu")
		(net "M_H_CPU1_SB_CB<6>")
	)
	(segment
		(start 127.899414 -244.412262)
		(end 127.889 -244.418358)
		(width 0.088646)
		(layer "In11.Cu")
		(net "M_H_CPU1_SB_CB<6>")
	)
	(segment
		(start 204.816456 -241.741706)
		(end 203.239116 -241.941096)
		(width 0.18288)
		(layer "In11.Cu")
		(net "M_H_CPU1_SB_CB<6>")
	)
	(segment
		(start 207.071214 -240.666778)
		(end 207.063594 -240.664238)
		(width 0.18288)
		(layer "In11.Cu")
		(net "M_H_CPU1_SB_CB<6>")
	)
	(segment
		(start 194.505326 -241.076226)
		(end 193.973958 -241.076226)
		(width 0.18288)
		(layer "In11.Cu")
		(net "M_H_CPU1_SB_CB<6>")
	)
	(segment
		(start 175.386238 -240.238026)
		(end 174.553372 -240.238026)
		(width 0.18288)
		(layer "In11.Cu")
		(net "M_H_CPU1_SB_CB<6>")
	)
	(segment
		(start 192.206626 -241.94135)
		(end 191.67475 -241.94135)
		(width 0.18288)
		(layer "In11.Cu")
		(net "M_H_CPU1_SB_CB<6>")
	)
	(segment
		(start 135.801354 -244.417342)
		(end 135.792464 -244.412262)
		(width 0.088646)
		(layer "In11.Cu")
		(net "M_H_CPU1_SB_CB<6>")
	)
	(segment
		(start 202.27925 -241.942366)
		(end 202.20559 -242.016026)
		(width 0.18288)
		(layer "In11.Cu")
		(net "M_H_CPU1_SB_CB<6>")
	)
	(segment
		(start 169.979594 -240.921794)
		(end 169.524426 -240.466626)
		(width 0.18288)
		(layer "In11.Cu")
		(net "M_H_CPU1_SB_CB<6>")
	)
	(segment
		(start 177.905918 -240.240566)
		(end 176.318418 -240.240566)
		(width 0.18288)
		(layer "In11.Cu")
		(net "M_H_CPU1_SB_CB<6>")
	)
	(segment
		(start 150.628858 -245.21287)
		(end 143.856202 -245.21287)
		(width 0.18288)
		(layer "In11.Cu")
		(net "M_H_CPU1_SB_CB<6>")
	)
	(segment
		(start 160.530794 -243.618258)
		(end 158.783782 -245.36527)
		(width 0.18288)
		(layer "In11.Cu")
		(net "M_H_CPU1_SB_CB<6>")
	)
	(segment
		(start 192.43675 -241.711226)
		(end 192.206626 -241.94135)
		(width 0.18288)
		(layer "In11.Cu")
		(net "M_H_CPU1_SB_CB<6>")
	)
	(segment
		(start 195.724526 -241.330226)
		(end 194.505326 -241.076226)
		(width 0.18288)
		(layer "In11.Cu")
		(net "M_H_CPU1_SB_CB<6>")
	)
	(segment
		(start 165.95217 -241.228626)
		(end 164.952426 -241.228626)
		(width 0.18288)
		(layer "In11.Cu")
		(net "M_H_CPU1_SB_CB<6>")
	)
	(segment
		(start 189.869826 -241.838226)
		(end 188.129926 -241.091212)
		(width 0.18288)
		(layer "In11.Cu")
		(net "M_H_CPU1_SB_CB<6>")
	)
	(segment
		(start 185.386726 -240.923826)
		(end 184.772046 -240.649506)
		(width 0.18288)
		(layer "In11.Cu")
		(net "M_H_CPU1_SB_CB<6>")
	)
	(segment
		(start 161.523426 -241.050826)
		(end 160.530794 -242.043458)
		(width 0.18288)
		(layer "In11.Cu")
		(net "M_H_CPU1_SB_CB<6>")
	)
	(segment
		(start 174.553372 -240.238026)
		(end 173.699678 -241.09172)
		(width 0.18288)
		(layer "In11.Cu")
		(net "M_H_CPU1_SB_CB<6>")
	)
	(segment
		(start 202.20559 -242.016026)
		(end 201.503026 -242.016026)
		(width 0.18288)
		(layer "In11.Cu")
		(net "M_H_CPU1_SB_CB<6>")
	)
	(segment
		(start 171.986194 -240.921794)
		(end 169.979594 -240.921794)
		(width 0.18288)
		(layer "In11.Cu")
		(net "M_H_CPU1_SB_CB<6>")
	)
	(segment
		(start 168.178226 -240.466626)
		(end 167.848026 -240.136426)
		(width 0.18288)
		(layer "In11.Cu")
		(net "M_H_CPU1_SB_CB<6>")
	)
	(segment
		(start 150.781258 -245.36527)
		(end 150.628858 -245.21287)
		(width 0.18288)
		(layer "In11.Cu")
		(net "M_H_CPU1_SB_CB<6>")
	)
	(segment
		(start 173.699678 -241.09172)
		(end 172.15612 -241.09172)
		(width 0.18288)
		(layer "In11.Cu")
		(net "M_H_CPU1_SB_CB<6>")
	)
	(segment
		(start 133.538468 -244.412262)
		(end 133.528054 -244.418358)
		(width 0.088646)
		(layer "In11.Cu")
		(net "M_H_CPU1_SB_CB<6>")
	)
	(segment
		(start 132.598414 -244.412262)
		(end 132.588 -244.418358)
		(width 0.088646)
		(layer "In11.Cu")
		(net "M_H_CPU1_SB_CB<6>")
	)
	(segment
		(start 200.485502 -241.66195)
		(end 199.801226 -240.977674)
		(width 0.18288)
		(layer "In11.Cu")
		(net "M_H_CPU1_SB_CB<6>")
	)
	(segment
		(start 124.235972 -243.988336)
		(end 124.17044 -243.922804)
		(width 0.088646)
		(layer "In11.Cu")
		(net "M_H_CPU1_SB_CB<6>")
	)
	(segment
		(start 158.783782 -245.36527)
		(end 150.781258 -245.36527)
		(width 0.18288)
		(layer "In11.Cu")
		(net "M_H_CPU1_SB_CB<6>")
	)
	(segment
		(start 141.103096 -245.498874)
		(end 139.728448 -245.498874)
		(width 0.088646)
		(layer "In11.Cu")
		(net "M_H_CPU1_SB_CB<6>")
	)
	(segment
		(start 188.129926 -241.091212)
		(end 187.116212 -241.091212)
		(width 0.18288)
		(layer "In11.Cu")
		(net "M_H_CPU1_SB_CB<6>")
	)
	(segment
		(start 201.503026 -242.016026)
		(end 201.366374 -241.968528)
		(width 0.18288)
		(layer "In11.Cu")
		(net "M_H_CPU1_SB_CB<6>")
	)
	(segment
		(start 197.273926 -241.330226)
		(end 195.724526 -241.330226)
		(width 0.18288)
		(layer "In11.Cu")
		(net "M_H_CPU1_SB_CB<6>")
	)
	(segment
		(start 169.524426 -240.466626)
		(end 168.178226 -240.466626)
		(width 0.18288)
		(layer "In11.Cu")
		(net "M_H_CPU1_SB_CB<6>")
	)
	(segment
		(start 186.948826 -240.923826)
		(end 185.386726 -240.923826)
		(width 0.18288)
		(layer "In11.Cu")
		(net "M_H_CPU1_SB_CB<6>")
	)
	(segment
		(start 193.338958 -241.711226)
		(end 192.43675 -241.711226)
		(width 0.18288)
		(layer "In11.Cu")
		(net "M_H_CPU1_SB_CB<6>")
	)
	(segment
		(start 193.973958 -241.076226)
		(end 193.338958 -241.711226)
		(width 0.18288)
		(layer "In11.Cu")
		(net "M_H_CPU1_SB_CB<6>")
	)
	(segment
		(start 124.17044 -243.922804)
		(end 123.857766 -243.922804)
		(width 0.088646)
		(layer "In11.Cu")
		(net "M_H_CPU1_SB_CB<6>")
	)
	(segment
		(start 134.478014 -244.412262)
		(end 134.4676 -244.418358)
		(width 0.088646)
		(layer "In11.Cu")
		(net "M_H_CPU1_SB_CB<6>")
	)
	(segment
		(start 203.239116 -241.941096)
		(end 203.229718 -241.942366)
		(width 0.18288)
		(layer "In11.Cu")
		(net "M_H_CPU1_SB_CB<6>")
	)
	(segment
		(start 139.566396 -245.660926)
		(end 139.058396 -245.660926)
		(width 0.088646)
		(layer "In11.Cu")
		(net "M_H_CPU1_SB_CB<6>")
	)
	(segment
		(start 143.570198 -245.498874)
		(end 141.103096 -245.498874)
		(width 0.18288)
		(layer "In11.Cu")
		(net "M_H_CPU1_SB_CB<6>")
	)
	(segment
		(start 176.169574 -240.38941)
		(end 175.537622 -240.38941)
		(width 0.18288)
		(layer "In11.Cu")
		(net "M_H_CPU1_SB_CB<6>")
	)
	(segment
		(start 199.001126 -240.977674)
		(end 197.273926 -241.330226)
		(width 0.18288)
		(layer "In11.Cu")
		(net "M_H_CPU1_SB_CB<6>")
	)
	(segment
		(start 160.530794 -242.043458)
		(end 160.530794 -243.618258)
		(width 0.18288)
		(layer "In11.Cu")
		(net "M_H_CPU1_SB_CB<6>")
	)
	(segment
		(start 203.229718 -241.942366)
		(end 202.27925 -241.942366)
		(width 0.18288)
		(layer "In11.Cu")
		(net "M_H_CPU1_SB_CB<6>")
	)
	(segment
		(start 164.774626 -241.050826)
		(end 161.523426 -241.050826)
		(width 0.18288)
		(layer "In11.Cu")
		(net "M_H_CPU1_SB_CB<6>")
	)
	(segment
		(start 199.801226 -240.977674)
		(end 199.001126 -240.977674)
		(width 0.18288)
		(layer "In11.Cu")
		(net "M_H_CPU1_SB_CB<6>")
	)
	(segment
		(start 126.959868 -244.412262)
		(end 126.949454 -244.418358)
		(width 0.088646)
		(layer "In11.Cu")
		(net "M_H_CPU1_SB_CB<6>")
	)
	(segment
		(start 139.728448 -245.498874)
		(end 139.566396 -245.660926)
		(width 0.088646)
		(layer "In11.Cu")
		(net "M_H_CPU1_SB_CB<6>")
	)
	(segment
		(start 138.699494 -245.302024)
		(end 136.545066 -245.302024)
		(width 0.088646)
		(layer "In11.Cu")
		(net "M_H_CPU1_SB_CB<6>")
	)
	(segment
		(start 175.537622 -240.38941)
		(end 175.386238 -240.238026)
		(width 0.18288)
		(layer "In11.Cu")
		(net "M_H_CPU1_SB_CB<6>")
	)
	(segment
		(start 207.063594 -240.664238)
		(end 206.71409 -240.831878)
		(width 0.18288)
		(layer "In11.Cu")
		(net "M_H_CPU1_SB_CB<6>")
	)
	(segment
		(start 135.418068 -244.412262)
		(end 135.407654 -244.418358)
		(width 0.088646)
		(layer "In11.Cu")
		(net "M_H_CPU1_SB_CB<6>")
	)
	(segment
		(start 191.571626 -241.838226)
		(end 189.869826 -241.838226)
		(width 0.18288)
		(layer "In11.Cu")
		(net "M_H_CPU1_SB_CB<6>")
	)
	(segment
		(start 167.04437 -240.136426)
		(end 165.95217 -241.228626)
		(width 0.18288)
		(layer "In11.Cu")
		(net "M_H_CPU1_SB_CB<6>")
	)
	(segment
		(start 201.366374 -241.968528)
		(end 200.485502 -241.66195)
		(width 0.18288)
		(layer "In11.Cu")
		(net "M_H_CPU1_SB_CB<6>")
	)
	(segment
		(start 130.718814 -244.412262)
		(end 130.704082 -244.420898)
		(width 0.088646)
		(layer "In11.Cu")
		(net "M_H_CPU1_SB_CB<6>")
	)
	(segment
		(start 179.548536 -240.48466)
		(end 178.150012 -240.48466)
		(width 0.18288)
		(layer "In11.Cu")
		(net "M_H_CPU1_SB_CB<6>")
	)
	(segment
		(start 126.019814 -244.412262)
		(end 126.0094 -244.418358)
		(width 0.088646)
		(layer "In11.Cu")
		(net "M_H_CPU1_SB_CB<6>")
	)
	(segment
		(start 167.848026 -240.136426)
		(end 167.04437 -240.136426)
		(width 0.18288)
		(layer "In11.Cu")
		(net "M_H_CPU1_SB_CB<6>")
	)
	(segment
		(start 164.952426 -241.228626)
		(end 164.774626 -241.050826)
		(width 0.18288)
		(layer "In11.Cu")
		(net "M_H_CPU1_SB_CB<6>")
	)
	(segment
		(start 179.79517 -240.238026)
		(end 179.548536 -240.48466)
		(width 0.18288)
		(layer "In11.Cu")
		(net "M_H_CPU1_SB_CB<6>")
	)
	(segment
		(start 178.150012 -240.48466)
		(end 177.905918 -240.240566)
		(width 0.18288)
		(layer "In11.Cu")
		(net "M_H_CPU1_SB_CB<6>")
	)
	(arc
		(start 126.0094 -244.418358)
		(mid 125.731222 -244.488081)
		(end 125.454664 -244.412262)
		(width 0.088646)
		(layer "In11.Cu")
		(net "M_H_CPU1_SB_CB<6>")
	)
	(arc
		(start 127.889 -244.418358)
		(mid 127.610822 -244.488081)
		(end 127.334264 -244.412262)
		(width 0.088646)
		(layer "In11.Cu")
		(net "M_H_CPU1_SB_CB<6>")
	)
	(arc
		(start 130.704082 -244.420898)
		(mid 130.427607 -244.488218)
		(end 130.15341 -244.412262)
		(width 0.088646)
		(layer "In11.Cu")
		(net "M_H_CPU1_SB_CB<6>")
	)
	(arc
		(start 126.949454 -244.418358)
		(mid 126.671022 -244.488204)
		(end 126.39421 -244.412262)
		(width 0.088646)
		(layer "In11.Cu")
		(net "M_H_CPU1_SB_CB<6>")
	)
	(arc
		(start 132.033264 -244.412262)
		(mid 131.846066 -244.362119)
		(end 131.658868 -244.412262)
		(width 0.088646)
		(layer "In11.Cu")
		(net "M_H_CPU1_SB_CB<6>")
	)
	(arc
		(start 129.779014 -244.412262)
		(mid 129.496312 -244.488038)
		(end 129.21361 -244.412262)
		(width 0.088646)
		(layer "In11.Cu")
		(net "M_H_CPU1_SB_CB<6>")
	)
	(arc
		(start 125.454664 -244.412262)
		(mid 125.267466 -244.362119)
		(end 125.080268 -244.412262)
		(width 0.088646)
		(layer "In11.Cu")
		(net "M_H_CPU1_SB_CB<6>")
	)
	(arc
		(start 133.912864 -244.412262)
		(mid 133.725666 -244.362119)
		(end 133.538468 -244.412262)
		(width 0.088646)
		(layer "In11.Cu")
		(net "M_H_CPU1_SB_CB<6>")
	)
	(arc
		(start 128.27381 -244.412262)
		(mid 128.086612 -244.362119)
		(end 127.899414 -244.412262)
		(width 0.088646)
		(layer "In11.Cu")
		(net "M_H_CPU1_SB_CB<6>")
	)
	(arc
		(start 128.824482 -244.420898)
		(mid 128.548007 -244.488218)
		(end 128.27381 -244.412262)
		(width 0.088646)
		(layer "In11.Cu")
		(net "M_H_CPU1_SB_CB<6>")
	)
	(arc
		(start 132.97281 -244.412262)
		(mid 132.785612 -244.362119)
		(end 132.598414 -244.412262)
		(width 0.088646)
		(layer "In11.Cu")
		(net "M_H_CPU1_SB_CB<6>")
	)
	(arc
		(start 133.528054 -244.418358)
		(mid 133.249622 -244.488204)
		(end 132.97281 -244.412262)
		(width 0.088646)
		(layer "In11.Cu")
		(net "M_H_CPU1_SB_CB<6>")
	)
	(arc
		(start 135.407654 -244.418358)
		(mid 135.129222 -244.488204)
		(end 134.85241 -244.412262)
		(width 0.088646)
		(layer "In11.Cu")
		(net "M_H_CPU1_SB_CB<6>")
	)
	(arc
		(start 130.15341 -244.412262)
		(mid 129.966212 -244.362119)
		(end 129.779014 -244.412262)
		(width 0.088646)
		(layer "In11.Cu")
		(net "M_H_CPU1_SB_CB<6>")
	)
	(arc
		(start 135.792464 -244.412262)
		(mid 135.605266 -244.362119)
		(end 135.418068 -244.412262)
		(width 0.088646)
		(layer "In11.Cu")
		(net "M_H_CPU1_SB_CB<6>")
	)
	(arc
		(start 135.979916 -244.73662)
		(mid 135.932237 -244.55372)
		(end 135.801354 -244.417342)
		(width 0.088646)
		(layer "In11.Cu")
		(net "M_H_CPU1_SB_CB<6>")
	)
	(arc
		(start 134.85241 -244.412262)
		(mid 134.665212 -244.362119)
		(end 134.478014 -244.412262)
		(width 0.088646)
		(layer "In11.Cu")
		(net "M_H_CPU1_SB_CB<6>")
	)
	(arc
		(start 132.588 -244.418358)
		(mid 132.309822 -244.488081)
		(end 132.033264 -244.412262)
		(width 0.088646)
		(layer "In11.Cu")
		(net "M_H_CPU1_SB_CB<6>")
	)
	(arc
		(start 131.09321 -244.412262)
		(mid 130.906012 -244.362119)
		(end 130.718814 -244.412262)
		(width 0.088646)
		(layer "In11.Cu")
		(net "M_H_CPU1_SB_CB<6>")
	)
	(arc
		(start 127.334264 -244.412262)
		(mid 127.147066 -244.362119)
		(end 126.959868 -244.412262)
		(width 0.088646)
		(layer "In11.Cu")
		(net "M_H_CPU1_SB_CB<6>")
	)
	(arc
		(start 129.21361 -244.412262)
		(mid 129.026412 -244.362119)
		(end 128.839214 -244.412262)
		(width 0.088646)
		(layer "In11.Cu")
		(net "M_H_CPU1_SB_CB<6>")
	)
	(arc
		(start 136.545066 -245.302024)
		(mid 136.151875 -245.142923)
		(end 135.979916 -244.755162)
		(width 0.088646)
		(layer "In11.Cu")
		(net "M_H_CPU1_SB_CB<6>")
	)
	(arc
		(start 126.39421 -244.412262)
		(mid 126.207012 -244.362119)
		(end 126.019814 -244.412262)
		(width 0.088646)
		(layer "In11.Cu")
		(net "M_H_CPU1_SB_CB<6>")
	)
	(arc
		(start 125.069854 -244.418358)
		(mid 124.791422 -244.488204)
		(end 124.51461 -244.412262)
		(width 0.088646)
		(layer "In11.Cu")
		(net "M_H_CPU1_SB_CB<6>")
	)
	(arc
		(start 124.51461 -244.412262)
		(mid 124.325097 -244.233297)
		(end 124.235972 -243.988336)
		(width 0.088646)
		(layer "In11.Cu")
		(net "M_H_CPU1_SB_CB<6>")
	)
	(arc
		(start 134.4676 -244.418358)
		(mid 134.189422 -244.488081)
		(end 133.912864 -244.412262)
		(width 0.088646)
		(layer "In11.Cu")
		(net "M_H_CPU1_SB_CB<6>")
	)
	(arc
		(start 131.648454 -244.418358)
		(mid 131.370022 -244.488204)
		(end 131.09321 -244.412262)
		(width 0.088646)
		(layer "In11.Cu")
		(net "M_H_CPU1_SB_CB<6>")
	)
	(segment
		(start 209.596482 -239.385348)
		(end 209.186526 -239.385348)
		(width 0.20066)
		(layer "F.Cu")
		(net "M_H_CPU1_SB_CB<5>")
	)
	(segment
		(start 125.267212 -243.644674)
		(end 125.267212 -243.108988)
		(width 0.20066)
		(layer "F.Cu")
		(net "M_H_CPU1_SB_CB<5>")
	)
	(segment
		(start 209.186526 -239.385348)
		(end 209.180176 -239.391698)
		(width 0.1016)
		(layer "F.Cu")
		(net "M_H_CPU1_SB_CB<5>")
	)
	(segment
		(start 204.076046 -239.81664)
		(end 202.971146 -239.81664)
		(width 0.20066)
		(layer "F.Cu")
		(net "M_H_CPU1_SB_CB<5>")
	)
	(segment
		(start 206.626714 -239.391698)
		(end 206.508604 -239.509808)
		(width 0.20066)
		(layer "F.Cu")
		(net "M_H_CPU1_SB_CB<5>")
	)
	(segment
		(start 209.180176 -239.391698)
		(end 206.991458 -239.391698)
		(width 0.1016)
		(layer "F.Cu")
		(net "M_H_CPU1_SB_CB<5>")
	)
	(segment
		(start 210.028028 -239.816894)
		(end 209.596482 -239.385348)
		(width 0.20066)
		(layer "F.Cu")
		(net "M_H_CPU1_SB_CB<5>")
	)
	(segment
		(start 211.619592 -239.816894)
		(end 210.028028 -239.816894)
		(width 0.20066)
		(layer "F.Cu")
		(net "M_H_CPU1_SB_CB<5>")
	)
	(segment
		(start 205.596744 -239.81664)
		(end 204.076046 -239.81664)
		(width 0.20066)
		(layer "F.Cu")
		(net "M_H_CPU1_SB_CB<5>")
	)
	(segment
		(start 206.971392 -239.391698)
		(end 206.626714 -239.391698)
		(width 0.20066)
		(layer "F.Cu")
		(net "M_H_CPU1_SB_CB<5>")
	)
	(segment
		(start 125.267466 -243.644928)
		(end 125.267212 -243.644674)
		(width 0.20066)
		(layer "F.Cu")
		(net "M_H_CPU1_SB_CB<5>")
	)
	(segment
		(start 206.508604 -239.509808)
		(end 206.508604 -239.877346)
		(width 0.20066)
		(layer "F.Cu")
		(net "M_H_CPU1_SB_CB<5>")
	)
	(segment
		(start 206.320644 -240.065306)
		(end 205.84541 -240.065306)
		(width 0.20066)
		(layer "F.Cu")
		(net "M_H_CPU1_SB_CB<5>")
	)
	(segment
		(start 206.508604 -239.877346)
		(end 206.320644 -240.065306)
		(width 0.20066)
		(layer "F.Cu")
		(net "M_H_CPU1_SB_CB<5>")
	)
	(segment
		(start 206.991458 -239.391698)
		(end 206.971392 -239.391698)
		(width 0.101854)
		(layer "F.Cu")
		(net "M_H_CPU1_SB_CB<5>")
	)
	(segment
		(start 205.84541 -240.065306)
		(end 205.596744 -239.81664)
		(width 0.20066)
		(layer "F.Cu")
		(net "M_H_CPU1_SB_CB<5>")
	)
	(segment
		(start 211.619846 -239.81664)
		(end 211.619592 -239.816894)
		(width 0.20066)
		(layer "F.Cu")
		(net "M_H_CPU1_SB_CB<5>")
	)
	(segment
		(start 125.87478 -243.349526)
		(end 125.707902 -243.358162)
		(width 0.088646)
		(layer "In11.Cu")
		(net "M_H_CPU1_SB_CB<5>")
	)
	(segment
		(start 187.1218 -238.541052)
		(end 187.00496 -238.657892)
		(width 0.18288)
		(layer "In11.Cu")
		(net "M_H_CPU1_SB_CB<5>")
	)
	(segment
		(start 159.022034 -239.463072)
		(end 152.789636 -239.463072)
		(width 0.18288)
		(layer "In11.Cu")
		(net "M_H_CPU1_SB_CB<5>")
	)
	(segment
		(start 200.803256 -239.388904)
		(end 200.004426 -238.590074)
		(width 0.18288)
		(layer "In11.Cu")
		(net "M_H_CPU1_SB_CB<5>")
	)
	(segment
		(start 191.675512 -239.51438)
		(end 191.424814 -239.51438)
		(width 0.18288)
		(layer "In11.Cu")
		(net "M_H_CPU1_SB_CB<5>")
	)
	(segment
		(start 190.528194 -239.32134)
		(end 190.335154 -239.51438)
		(width 0.18288)
		(layer "In11.Cu")
		(net "M_H_CPU1_SB_CB<5>")
	)
	(segment
		(start 148.278596 -243.974112)
		(end 140.569696 -243.974112)
		(width 0.18288)
		(layer "In11.Cu")
		(net "M_H_CPU1_SB_CB<5>")
	)
	(segment
		(start 190.528194 -238.94161)
		(end 190.528194 -239.32134)
		(width 0.18288)
		(layer "In11.Cu")
		(net "M_H_CPU1_SB_CB<5>")
	)
	(segment
		(start 196.301106 -238.924084)
		(end 196.301106 -238.399066)
		(width 0.18288)
		(layer "In11.Cu")
		(net "M_H_CPU1_SB_CB<5>")
	)
	(segment
		(start 191.231774 -239.32134)
		(end 191.231774 -238.94161)
		(width 0.18288)
		(layer "In11.Cu")
		(net "M_H_CPU1_SB_CB<5>")
	)
	(segment
		(start 197.004686 -238.399066)
		(end 197.004686 -238.924084)
		(width 0.18288)
		(layer "In11.Cu")
		(net "M_H_CPU1_SB_CB<5>")
	)
	(segment
		(start 196.108066 -238.206026)
		(end 195.280026 -238.206026)
		(width 0.18288)
		(layer "In11.Cu")
		(net "M_H_CPU1_SB_CB<5>")
	)
	(segment
		(start 140.053822 -243.974112)
		(end 139.95019 -243.87048)
		(width 0.088646)
		(layer "In11.Cu")
		(net "M_H_CPU1_SB_CB<5>")
	)
	(segment
		(start 187.00496 -238.657892)
		(end 185.973212 -238.657892)
		(width 0.18288)
		(layer "In11.Cu")
		(net "M_H_CPU1_SB_CB<5>")
	)
	(segment
		(start 152.789636 -239.463072)
		(end 148.278596 -243.974112)
		(width 0.18288)
		(layer "In11.Cu")
		(net "M_H_CPU1_SB_CB<5>")
	)
	(segment
		(start 136.822688 -243.87048)
		(end 136.474708 -243.5225)
		(width 0.088646)
		(layer "In11.Cu")
		(net "M_H_CPU1_SB_CB<5>")
	)
	(segment
		(start 139.95019 -243.87048)
		(end 136.822688 -243.87048)
		(width 0.088646)
		(layer "In11.Cu")
		(net "M_H_CPU1_SB_CB<5>")
	)
	(segment
		(start 171.683934 -238.616744)
		(end 171.035472 -238.347758)
		(width 0.18288)
		(layer "In11.Cu")
		(net "M_H_CPU1_SB_CB<5>")
	)
	(segment
		(start 161.040826 -238.383826)
		(end 160.10128 -238.383826)
		(width 0.18288)
		(layer "In11.Cu")
		(net "M_H_CPU1_SB_CB<5>")
	)
	(segment
		(start 126.020068 -243.433346)
		(end 125.87478 -243.349526)
		(width 0.088646)
		(layer "In11.Cu")
		(net "M_H_CPU1_SB_CB<5>")
	)
	(segment
		(start 194.670426 -238.815626)
		(end 193.200274 -238.815626)
		(width 0.18288)
		(layer "In11.Cu")
		(net "M_H_CPU1_SB_CB<5>")
	)
	(segment
		(start 198.175626 -238.206026)
		(end 197.197726 -238.206026)
		(width 0.18288)
		(layer "In11.Cu")
		(net "M_H_CPU1_SB_CB<5>")
	)
	(segment
		(start 201.18324 -239.388904)
		(end 200.803256 -239.388904)
		(width 0.18288)
		(layer "In11.Cu")
		(net "M_H_CPU1_SB_CB<5>")
	)
	(segment
		(start 202.2729 -239.348264)
		(end 202.07986 -239.155224)
		(width 0.18288)
		(layer "In11.Cu")
		(net "M_H_CPU1_SB_CB<5>")
	)
	(segment
		(start 169.317416 -237.636304)
		(end 167.857424 -237.926626)
		(width 0.18288)
		(layer "In11.Cu")
		(net "M_H_CPU1_SB_CB<5>")
	)
	(segment
		(start 166.125906 -238.370872)
		(end 164.76218 -238.370872)
		(width 0.18288)
		(layer "In11.Cu")
		(net "M_H_CPU1_SB_CB<5>")
	)
	(segment
		(start 184.543192 -237.227872)
		(end 177.84572 -237.227872)
		(width 0.18288)
		(layer "In11.Cu")
		(net "M_H_CPU1_SB_CB<5>")
	)
	(segment
		(start 202.07986 -239.155224)
		(end 202.07986 -238.73841)
		(width 0.18288)
		(layer "In11.Cu")
		(net "M_H_CPU1_SB_CB<5>")
	)
	(segment
		(start 202.07986 -238.73841)
		(end 201.88682 -238.54537)
		(width 0.18288)
		(layer "In11.Cu")
		(net "M_H_CPU1_SB_CB<5>")
	)
	(segment
		(start 191.424814 -239.51438)
		(end 191.231774 -239.32134)
		(width 0.18288)
		(layer "In11.Cu")
		(net "M_H_CPU1_SB_CB<5>")
	)
	(segment
		(start 171.035472 -238.347758)
		(end 170.930824 -238.09579)
		(width 0.18288)
		(layer "In11.Cu")
		(net "M_H_CPU1_SB_CB<5>")
	)
	(segment
		(start 171.183554 -237.48619)
		(end 171.079414 -237.234476)
		(width 0.18288)
		(layer "In11.Cu")
		(net "M_H_CPU1_SB_CB<5>")
	)
	(segment
		(start 166.570152 -237.926626)
		(end 166.125906 -238.370872)
		(width 0.18288)
		(layer "In11.Cu")
		(net "M_H_CPU1_SB_CB<5>")
	)
	(segment
		(start 177.3809 -237.692692)
		(end 173.926246 -237.692692)
		(width 0.18288)
		(layer "In11.Cu")
		(net "M_H_CPU1_SB_CB<5>")
	)
	(segment
		(start 201.37628 -239.195864)
		(end 201.18324 -239.388904)
		(width 0.18288)
		(layer "In11.Cu")
		(net "M_H_CPU1_SB_CB<5>")
	)
	(segment
		(start 201.56932 -238.54537)
		(end 201.37628 -238.73841)
		(width 0.18288)
		(layer "In11.Cu")
		(net "M_H_CPU1_SB_CB<5>")
	)
	(segment
		(start 131.658614 -243.433346)
		(end 131.643882 -243.42471)
		(width 0.088646)
		(layer "In11.Cu")
		(net "M_H_CPU1_SB_CB<5>")
	)
	(segment
		(start 201.88682 -238.54537)
		(end 201.56932 -238.54537)
		(width 0.18288)
		(layer "In11.Cu")
		(net "M_H_CPU1_SB_CB<5>")
	)
	(segment
		(start 173.077378 -238.54156)
		(end 172.266864 -238.54156)
		(width 0.18288)
		(layer "In11.Cu")
		(net "M_H_CPU1_SB_CB<5>")
	)
	(segment
		(start 128.839214 -243.433346)
		(end 128.824482 -243.42471)
		(width 0.088646)
		(layer "In11.Cu")
		(net "M_H_CPU1_SB_CB<5>")
	)
	(segment
		(start 189.95898 -239.51438)
		(end 188.985652 -238.541052)
		(width 0.18288)
		(layer "In11.Cu")
		(net "M_H_CPU1_SB_CB<5>")
	)
	(segment
		(start 188.985652 -238.541052)
		(end 187.1218 -238.541052)
		(width 0.18288)
		(layer "In11.Cu")
		(net "M_H_CPU1_SB_CB<5>")
	)
	(segment
		(start 196.494146 -239.117124)
		(end 196.301106 -238.924084)
		(width 0.18288)
		(layer "In11.Cu")
		(net "M_H_CPU1_SB_CB<5>")
	)
	(segment
		(start 160.10128 -238.383826)
		(end 159.022034 -239.463072)
		(width 0.18288)
		(layer "In11.Cu")
		(net "M_H_CPU1_SB_CB<5>")
	)
	(segment
		(start 170.930824 -238.09579)
		(end 171.183554 -237.48619)
		(width 0.18288)
		(layer "In11.Cu")
		(net "M_H_CPU1_SB_CB<5>")
	)
	(segment
		(start 201.37628 -238.73841)
		(end 201.37628 -239.195864)
		(width 0.18288)
		(layer "In11.Cu")
		(net "M_H_CPU1_SB_CB<5>")
	)
	(segment
		(start 197.197726 -238.206026)
		(end 197.004686 -238.399066)
		(width 0.18288)
		(layer "In11.Cu")
		(net "M_H_CPU1_SB_CB<5>")
	)
	(segment
		(start 164.520626 -238.612426)
		(end 161.269426 -238.612426)
		(width 0.18288)
		(layer "In11.Cu")
		(net "M_H_CPU1_SB_CB<5>")
	)
	(segment
		(start 170.533568 -237.21695)
		(end 170.280838 -237.826296)
		(width 0.18288)
		(layer "In11.Cu")
		(net "M_H_CPU1_SB_CB<5>")
	)
	(segment
		(start 161.269426 -238.612426)
		(end 161.040826 -238.383826)
		(width 0.18288)
		(layer "In11.Cu")
		(net "M_H_CPU1_SB_CB<5>")
	)
	(segment
		(start 202.971146 -239.543844)
		(end 202.775566 -239.348264)
		(width 0.18288)
		(layer "In11.Cu")
		(net "M_H_CPU1_SB_CB<5>")
	)
	(segment
		(start 135.418068 -243.433346)
		(end 135.407654 -243.42725)
		(width 0.088646)
		(layer "In11.Cu")
		(net "M_H_CPU1_SB_CB<5>")
	)
	(segment
		(start 172.266864 -238.54156)
		(end 172.19168 -238.616744)
		(width 0.18288)
		(layer "In11.Cu")
		(net "M_H_CPU1_SB_CB<5>")
	)
	(segment
		(start 177.84572 -237.227872)
		(end 177.3809 -237.692692)
		(width 0.18288)
		(layer "In11.Cu")
		(net "M_H_CPU1_SB_CB<5>")
	)
	(segment
		(start 167.857424 -237.926626)
		(end 166.570152 -237.926626)
		(width 0.18288)
		(layer "In11.Cu")
		(net "M_H_CPU1_SB_CB<5>")
	)
	(segment
		(start 202.971146 -239.81664)
		(end 202.971146 -239.543844)
		(width 0.18288)
		(layer "In11.Cu")
		(net "M_H_CPU1_SB_CB<5>")
	)
	(segment
		(start 132.598668 -243.433346)
		(end 132.588254 -243.42725)
		(width 0.088646)
		(layer "In11.Cu")
		(net "M_H_CPU1_SB_CB<5>")
	)
	(segment
		(start 140.569696 -243.974112)
		(end 140.053822 -243.974112)
		(width 0.088646)
		(layer "In11.Cu")
		(net "M_H_CPU1_SB_CB<5>")
	)
	(segment
		(start 125.397006 -243.238782)
		(end 125.267212 -243.108988)
		(width 0.088646)
		(layer "In11.Cu")
		(net "M_H_CPU1_SB_CB<5>")
	)
	(segment
		(start 190.335154 -239.51438)
		(end 189.95898 -239.51438)
		(width 0.18288)
		(layer "In11.Cu")
		(net "M_H_CPU1_SB_CB<5>")
	)
	(segment
		(start 190.721234 -238.74857)
		(end 190.528194 -238.94161)
		(width 0.18288)
		(layer "In11.Cu")
		(net "M_H_CPU1_SB_CB<5>")
	)
	(segment
		(start 193.200274 -238.815626)
		(end 192.624202 -239.391698)
		(width 0.18288)
		(layer "In11.Cu")
		(net "M_H_CPU1_SB_CB<5>")
	)
	(segment
		(start 195.280026 -238.206026)
		(end 194.670426 -238.815626)
		(width 0.18288)
		(layer "In11.Cu")
		(net "M_H_CPU1_SB_CB<5>")
	)
	(segment
		(start 164.76218 -238.370872)
		(end 164.520626 -238.612426)
		(width 0.18288)
		(layer "In11.Cu")
		(net "M_H_CPU1_SB_CB<5>")
	)
	(segment
		(start 172.19168 -238.616744)
		(end 171.683934 -238.616744)
		(width 0.18288)
		(layer "In11.Cu")
		(net "M_H_CPU1_SB_CB<5>")
	)
	(segment
		(start 185.973212 -238.657892)
		(end 184.543192 -237.227872)
		(width 0.18288)
		(layer "In11.Cu")
		(net "M_H_CPU1_SB_CB<5>")
	)
	(segment
		(start 191.231774 -238.94161)
		(end 191.038734 -238.74857)
		(width 0.18288)
		(layer "In11.Cu")
		(net "M_H_CPU1_SB_CB<5>")
	)
	(segment
		(start 196.811646 -239.117124)
		(end 196.494146 -239.117124)
		(width 0.18288)
		(layer "In11.Cu")
		(net "M_H_CPU1_SB_CB<5>")
	)
	(segment
		(start 197.004686 -238.924084)
		(end 196.811646 -239.117124)
		(width 0.18288)
		(layer "In11.Cu")
		(net "M_H_CPU1_SB_CB<5>")
	)
	(segment
		(start 202.775566 -239.348264)
		(end 202.2729 -239.348264)
		(width 0.18288)
		(layer "In11.Cu")
		(net "M_H_CPU1_SB_CB<5>")
	)
	(segment
		(start 130.718814 -243.433346)
		(end 130.704082 -243.42471)
		(width 0.088646)
		(layer "In11.Cu")
		(net "M_H_CPU1_SB_CB<5>")
	)
	(segment
		(start 134.478014 -243.433346)
		(end 134.4676 -243.42725)
		(width 0.088646)
		(layer "In11.Cu")
		(net "M_H_CPU1_SB_CB<5>")
	)
	(segment
		(start 198.559674 -238.590074)
		(end 198.175626 -238.206026)
		(width 0.18288)
		(layer "In11.Cu")
		(net "M_H_CPU1_SB_CB<5>")
	)
	(segment
		(start 170.028616 -237.930944)
		(end 169.317416 -237.636304)
		(width 0.18288)
		(layer "In11.Cu")
		(net "M_H_CPU1_SB_CB<5>")
	)
	(segment
		(start 196.301106 -238.399066)
		(end 196.108066 -238.206026)
		(width 0.18288)
		(layer "In11.Cu")
		(net "M_H_CPU1_SB_CB<5>")
	)
	(segment
		(start 191.798194 -239.391698)
		(end 191.675512 -239.51438)
		(width 0.18288)
		(layer "In11.Cu")
		(net "M_H_CPU1_SB_CB<5>")
	)
	(segment
		(start 170.785282 -237.112556)
		(end 170.533568 -237.21695)
		(width 0.18288)
		(layer "In11.Cu")
		(net "M_H_CPU1_SB_CB<5>")
	)
	(segment
		(start 200.004426 -238.590074)
		(end 198.559674 -238.590074)
		(width 0.18288)
		(layer "In11.Cu")
		(net "M_H_CPU1_SB_CB<5>")
	)
	(segment
		(start 127.899414 -243.433346)
		(end 127.884682 -243.42471)
		(width 0.088646)
		(layer "In11.Cu")
		(net "M_H_CPU1_SB_CB<5>")
	)
	(segment
		(start 170.280838 -237.826296)
		(end 170.028616 -237.930944)
		(width 0.18288)
		(layer "In11.Cu")
		(net "M_H_CPU1_SB_CB<5>")
	)
	(segment
		(start 171.079414 -237.234476)
		(end 170.785282 -237.112556)
		(width 0.18288)
		(layer "In11.Cu")
		(net "M_H_CPU1_SB_CB<5>")
	)
	(segment
		(start 126.959614 -243.433346)
		(end 126.9492 -243.42725)
		(width 0.088646)
		(layer "In11.Cu")
		(net "M_H_CPU1_SB_CB<5>")
	)
	(segment
		(start 173.926246 -237.692692)
		(end 173.077378 -238.54156)
		(width 0.18288)
		(layer "In11.Cu")
		(net "M_H_CPU1_SB_CB<5>")
	)
	(segment
		(start 192.624202 -239.391698)
		(end 191.798194 -239.391698)
		(width 0.18288)
		(layer "In11.Cu")
		(net "M_H_CPU1_SB_CB<5>")
	)
	(segment
		(start 191.038734 -238.74857)
		(end 190.721234 -238.74857)
		(width 0.18288)
		(layer "In11.Cu")
		(net "M_H_CPU1_SB_CB<5>")
	)
	(arc
		(start 132.03301 -243.433346)
		(mid 131.845812 -243.483489)
		(end 131.658614 -243.433346)
		(width 0.088646)
		(layer "In11.Cu")
		(net "M_H_CPU1_SB_CB<5>")
	)
	(arc
		(start 130.704082 -243.42471)
		(mid 130.427607 -243.35739)
		(end 130.15341 -243.433346)
		(width 0.088646)
		(layer "In11.Cu")
		(net "M_H_CPU1_SB_CB<5>")
	)
	(arc
		(start 135.792464 -243.433346)
		(mid 135.605266 -243.483489)
		(end 135.418068 -243.433346)
		(width 0.088646)
		(layer "In11.Cu")
		(net "M_H_CPU1_SB_CB<5>")
	)
	(arc
		(start 134.4676 -243.42725)
		(mid 134.189422 -243.357527)
		(end 133.912864 -243.433346)
		(width 0.088646)
		(layer "In11.Cu")
		(net "M_H_CPU1_SB_CB<5>")
	)
	(arc
		(start 132.588254 -243.42725)
		(mid 132.309822 -243.357404)
		(end 132.03301 -243.433346)
		(width 0.088646)
		(layer "In11.Cu")
		(net "M_H_CPU1_SB_CB<5>")
	)
	(arc
		(start 136.474708 -243.5225)
		(mid 136.44901 -243.498566)
		(end 136.421876 -243.476272)
		(width 0.088646)
		(layer "In11.Cu")
		(net "M_H_CPU1_SB_CB<5>")
	)
	(arc
		(start 131.643882 -243.42471)
		(mid 131.367407 -243.35739)
		(end 131.09321 -243.433346)
		(width 0.088646)
		(layer "In11.Cu")
		(net "M_H_CPU1_SB_CB<5>")
	)
	(arc
		(start 129.779014 -243.433346)
		(mid 129.496312 -243.35757)
		(end 129.21361 -243.433346)
		(width 0.088646)
		(layer "In11.Cu")
		(net "M_H_CPU1_SB_CB<5>")
	)
	(arc
		(start 132.973064 -243.433346)
		(mid 132.785866 -243.483489)
		(end 132.598668 -243.433346)
		(width 0.088646)
		(layer "In11.Cu")
		(net "M_H_CPU1_SB_CB<5>")
	)
	(arc
		(start 136.421876 -243.476272)
		(mid 136.390604 -243.453717)
		(end 136.357868 -243.433346)
		(width 0.088646)
		(layer "In11.Cu")
		(net "M_H_CPU1_SB_CB<5>")
	)
	(arc
		(start 136.357868 -243.433346)
		(mid 136.075166 -243.35757)
		(end 135.792464 -243.433346)
		(width 0.088646)
		(layer "In11.Cu")
		(net "M_H_CPU1_SB_CB<5>")
	)
	(arc
		(start 128.27381 -243.433346)
		(mid 128.086612 -243.483489)
		(end 127.899414 -243.433346)
		(width 0.088646)
		(layer "In11.Cu")
		(net "M_H_CPU1_SB_CB<5>")
	)
	(arc
		(start 133.912864 -243.433346)
		(mid 133.725666 -243.483489)
		(end 133.538468 -243.433346)
		(width 0.088646)
		(layer "In11.Cu")
		(net "M_H_CPU1_SB_CB<5>")
	)
	(arc
		(start 128.824482 -243.42471)
		(mid 128.548007 -243.35739)
		(end 128.27381 -243.433346)
		(width 0.088646)
		(layer "In11.Cu")
		(net "M_H_CPU1_SB_CB<5>")
	)
	(arc
		(start 127.884682 -243.42471)
		(mid 127.608207 -243.35739)
		(end 127.33401 -243.433346)
		(width 0.088646)
		(layer "In11.Cu")
		(net "M_H_CPU1_SB_CB<5>")
	)
	(arc
		(start 135.407654 -243.42725)
		(mid 135.129222 -243.357404)
		(end 134.85241 -243.433346)
		(width 0.088646)
		(layer "In11.Cu")
		(net "M_H_CPU1_SB_CB<5>")
	)
	(arc
		(start 131.09321 -243.433346)
		(mid 130.906012 -243.483489)
		(end 130.718814 -243.433346)
		(width 0.088646)
		(layer "In11.Cu")
		(net "M_H_CPU1_SB_CB<5>")
	)
	(arc
		(start 126.394464 -243.433346)
		(mid 126.207266 -243.483489)
		(end 126.020068 -243.433346)
		(width 0.088646)
		(layer "In11.Cu")
		(net "M_H_CPU1_SB_CB<5>")
	)
	(arc
		(start 130.15341 -243.433346)
		(mid 129.966212 -243.483489)
		(end 129.779014 -243.433346)
		(width 0.088646)
		(layer "In11.Cu")
		(net "M_H_CPU1_SB_CB<5>")
	)
	(arc
		(start 127.33401 -243.433346)
		(mid 127.146812 -243.483489)
		(end 126.959614 -243.433346)
		(width 0.088646)
		(layer "In11.Cu")
		(net "M_H_CPU1_SB_CB<5>")
	)
	(arc
		(start 129.21361 -243.433346)
		(mid 129.026412 -243.483489)
		(end 128.839214 -243.433346)
		(width 0.088646)
		(layer "In11.Cu")
		(net "M_H_CPU1_SB_CB<5>")
	)
	(arc
		(start 125.707902 -243.358162)
		(mid 125.539771 -243.331503)
		(end 125.397006 -243.238782)
		(width 0.088646)
		(layer "In11.Cu")
		(net "M_H_CPU1_SB_CB<5>")
	)
	(arc
		(start 134.85241 -243.433346)
		(mid 134.665212 -243.483489)
		(end 134.478014 -243.433346)
		(width 0.088646)
		(layer "In11.Cu")
		(net "M_H_CPU1_SB_CB<5>")
	)
	(arc
		(start 133.538468 -243.433346)
		(mid 133.255766 -243.35757)
		(end 132.973064 -243.433346)
		(width 0.088646)
		(layer "In11.Cu")
		(net "M_H_CPU1_SB_CB<5>")
	)
	(arc
		(start 126.9492 -243.42725)
		(mid 126.671022 -243.357527)
		(end 126.394464 -243.433346)
		(width 0.088646)
		(layer "In11.Cu")
		(net "M_H_CPU1_SB_CB<5>")
	)
	(segment
		(start 210.028028 -241.516916)
		(end 209.596482 -241.08537)
		(width 0.20066)
		(layer "F.Cu")
		(net "M_H_CPU1_SB_CB<4>")
	)
	(segment
		(start 124.797312 -244.458744)
		(end 124.797566 -244.45849)
		(width 0.20066)
		(layer "F.Cu")
		(net "M_H_CPU1_SB_CB<4>")
	)
	(segment
		(start 209.180176 -241.09172)
		(end 207.018382 -241.09172)
		(width 0.1016)
		(layer "F.Cu")
		(net "M_H_CPU1_SB_CB<4>")
	)
	(segment
		(start 206.971392 -241.09172)
		(end 206.626714 -241.09172)
		(width 0.20066)
		(layer "F.Cu")
		(net "M_H_CPU1_SB_CB<4>")
	)
	(segment
		(start 205.84541 -241.765328)
		(end 205.596744 -241.516662)
		(width 0.20066)
		(layer "F.Cu")
		(net "M_H_CPU1_SB_CB<4>")
	)
	(segment
		(start 204.076046 -241.516662)
		(end 202.971146 -241.516662)
		(width 0.20066)
		(layer "F.Cu")
		(net "M_H_CPU1_SB_CB<4>")
	)
	(segment
		(start 206.626714 -241.09172)
		(end 206.508604 -241.20983)
		(width 0.20066)
		(layer "F.Cu")
		(net "M_H_CPU1_SB_CB<4>")
	)
	(segment
		(start 124.797566 -244.45849)
		(end 124.797566 -243.922804)
		(width 0.20066)
		(layer "F.Cu")
		(net "M_H_CPU1_SB_CB<4>")
	)
	(segment
		(start 207.018382 -241.09172)
		(end 206.971392 -241.09172)
		(width 0.101854)
		(layer "F.Cu")
		(net "M_H_CPU1_SB_CB<4>")
	)
	(segment
		(start 211.619846 -241.516662)
		(end 211.619592 -241.516916)
		(width 0.20066)
		(layer "F.Cu")
		(net "M_H_CPU1_SB_CB<4>")
	)
	(segment
		(start 206.508604 -241.577368)
		(end 206.320644 -241.765328)
		(width 0.20066)
		(layer "F.Cu")
		(net "M_H_CPU1_SB_CB<4>")
	)
	(segment
		(start 206.320644 -241.765328)
		(end 205.84541 -241.765328)
		(width 0.20066)
		(layer "F.Cu")
		(net "M_H_CPU1_SB_CB<4>")
	)
	(segment
		(start 205.596744 -241.516662)
		(end 204.076046 -241.516662)
		(width 0.20066)
		(layer "F.Cu")
		(net "M_H_CPU1_SB_CB<4>")
	)
	(segment
		(start 209.596482 -241.08537)
		(end 209.186526 -241.08537)
		(width 0.20066)
		(layer "F.Cu")
		(net "M_H_CPU1_SB_CB<4>")
	)
	(segment
		(start 209.186526 -241.08537)
		(end 209.180176 -241.09172)
		(width 0.1016)
		(layer "F.Cu")
		(net "M_H_CPU1_SB_CB<4>")
	)
	(segment
		(start 211.619592 -241.516916)
		(end 210.028028 -241.516916)
		(width 0.20066)
		(layer "F.Cu")
		(net "M_H_CPU1_SB_CB<4>")
	)
	(segment
		(start 206.508604 -241.20983)
		(end 206.508604 -241.577368)
		(width 0.20066)
		(layer "F.Cu")
		(net "M_H_CPU1_SB_CB<4>")
	)
	(segment
		(start 181.79923 -239.70488)
		(end 181.60619 -239.51184)
		(width 0.18288)
		(layer "In11.Cu")
		(net "M_H_CPU1_SB_CB<4>")
	)
	(segment
		(start 172.050456 -240.404396)
		(end 170.556428 -240.404396)
		(width 0.18288)
		(layer "In11.Cu")
		(net "M_H_CPU1_SB_CB<4>")
	)
	(segment
		(start 175.752506 -239.725962)
		(end 173.593252 -239.725962)
		(width 0.18288)
		(layer "In11.Cu")
		(net "M_H_CPU1_SB_CB<4>")
	)
	(segment
		(start 184.059068 -239.365028)
		(end 183.719216 -239.70488)
		(width 0.18288)
		(layer "In11.Cu")
		(net "M_H_CPU1_SB_CB<4>")
	)
	(segment
		(start 189.026038 -240.24082)
		(end 187.073032 -240.24082)
		(width 0.18288)
		(layer "In11.Cu")
		(net "M_H_CPU1_SB_CB<4>")
	)
	(segment
		(start 128.754378 -244.241066)
		(end 128.743964 -244.247162)
		(width 0.088646)
		(layer "In11.Cu")
		(net "M_H_CPU1_SB_CB<4>")
	)
	(segment
		(start 198.404226 -240.161826)
		(end 194.721226 -240.161826)
		(width 0.18288)
		(layer "In11.Cu")
		(net "M_H_CPU1_SB_CB<4>")
	)
	(segment
		(start 152.082754 -241.840766)
		(end 149.13483 -244.78869)
		(width 0.18288)
		(layer "In11.Cu")
		(net "M_H_CPU1_SB_CB<4>")
	)
	(segment
		(start 190.809626 -241.279426)
		(end 190.064644 -241.279426)
		(width 0.18288)
		(layer "In11.Cu")
		(net "M_H_CPU1_SB_CB<4>")
	)
	(segment
		(start 177.41646 -239.251998)
		(end 177.276506 -239.391952)
		(width 0.18288)
		(layer "In11.Cu")
		(net "M_H_CPU1_SB_CB<4>")
	)
	(segment
		(start 181.41315 -238.931196)
		(end 181.09565 -238.931196)
		(width 0.18288)
		(layer "In11.Cu")
		(net "M_H_CPU1_SB_CB<4>")
	)
	(segment
		(start 166.247826 -239.984026)
		(end 164.927026 -239.984026)
		(width 0.18288)
		(layer "In11.Cu")
		(net "M_H_CPU1_SB_CB<4>")
	)
	(segment
		(start 199.996298 -240.368074)
		(end 198.610474 -240.368074)
		(width 0.18288)
		(layer "In11.Cu")
		(net "M_H_CPU1_SB_CB<4>")
	)
	(segment
		(start 158.418784 -242.033806)
		(end 158.225744 -241.840766)
		(width 0.18288)
		(layer "In11.Cu")
		(net "M_H_CPU1_SB_CB<4>")
	)
	(segment
		(start 173.593252 -239.725962)
		(end 173.077886 -240.241328)
		(width 0.18288)
		(layer "In11.Cu")
		(net "M_H_CPU1_SB_CB<4>")
	)
	(segment
		(start 124.427488 -243.980208)
		(end 124.484892 -243.922804)
		(width 0.088646)
		(layer "In11.Cu")
		(net "M_H_CPU1_SB_CB<4>")
	)
	(segment
		(start 158.611824 -243.943886)
		(end 158.418784 -243.750846)
		(width 0.18288)
		(layer "In11.Cu")
		(net "M_H_CPU1_SB_CB<4>")
	)
	(segment
		(start 193.504058 -240.504726)
		(end 192.917318 -241.091466)
		(width 0.18288)
		(layer "In11.Cu")
		(net "M_H_CPU1_SB_CB<4>")
	)
	(segment
		(start 124.484892 -243.922804)
		(end 124.797566 -243.922804)
		(width 0.088646)
		(layer "In11.Cu")
		(net "M_H_CPU1_SB_CB<4>")
	)
	(segment
		(start 124.610368 -244.247162)
		(end 124.601478 -244.242082)
		(width 0.088646)
		(layer "In11.Cu")
		(net "M_H_CPU1_SB_CB<4>")
	)
	(segment
		(start 194.721226 -240.161826)
		(end 194.378326 -240.504726)
		(width 0.18288)
		(layer "In11.Cu")
		(net "M_H_CPU1_SB_CB<4>")
	)
	(segment
		(start 180.70957 -239.70488)
		(end 180.010816 -239.70488)
		(width 0.18288)
		(layer "In11.Cu")
		(net "M_H_CPU1_SB_CB<4>")
	)
	(segment
		(start 143.316198 -244.990112)
		(end 141.103096 -244.990112)
		(width 0.18288)
		(layer "In11.Cu")
		(net "M_H_CPU1_SB_CB<4>")
	)
	(segment
		(start 132.517896 -244.238526)
		(end 132.503164 -244.247162)
		(width 0.088646)
		(layer "In11.Cu")
		(net "M_H_CPU1_SB_CB<4>")
	)
	(segment
		(start 181.60619 -239.124236)
		(end 181.41315 -238.931196)
		(width 0.18288)
		(layer "In11.Cu")
		(net "M_H_CPU1_SB_CB<4>")
	)
	(segment
		(start 169.474642 -239.32261)
		(end 168.509442 -239.32261)
		(width 0.18288)
		(layer "In11.Cu")
		(net "M_H_CPU1_SB_CB<4>")
	)
	(segment
		(start 187.073032 -240.24082)
		(end 186.923426 -240.390426)
		(width 0.18288)
		(layer "In11.Cu")
		(net "M_H_CPU1_SB_CB<4>")
	)
	(segment
		(start 129.693924 -244.241066)
		(end 129.68351 -244.247162)
		(width 0.088646)
		(layer "In11.Cu")
		(net "M_H_CPU1_SB_CB<4>")
	)
	(segment
		(start 180.90261 -239.51184)
		(end 180.70957 -239.70488)
		(width 0.18288)
		(layer "In11.Cu")
		(net "M_H_CPU1_SB_CB<4>")
	)
	(segment
		(start 138.820144 -245.111778)
		(end 136.545066 -245.111778)
		(width 0.088646)
		(layer "In11.Cu")
		(net "M_H_CPU1_SB_CB<4>")
	)
	(segment
		(start 198.610474 -240.368074)
		(end 198.404226 -240.161826)
		(width 0.18288)
		(layer "In11.Cu")
		(net "M_H_CPU1_SB_CB<4>")
	)
	(segment
		(start 186.923426 -240.390426)
		(end 185.793126 -240.390426)
		(width 0.18288)
		(layer "In11.Cu")
		(net "M_H_CPU1_SB_CB<4>")
	)
	(segment
		(start 161.294826 -240.441226)
		(end 159.895286 -241.840766)
		(width 0.18288)
		(layer "In11.Cu")
		(net "M_H_CPU1_SB_CB<4>")
	)
	(segment
		(start 177.276506 -239.391952)
		(end 176.086516 -239.391952)
		(width 0.18288)
		(layer "In11.Cu")
		(net "M_H_CPU1_SB_CB<4>")
	)
	(segment
		(start 176.086516 -239.391952)
		(end 175.752506 -239.725962)
		(width 0.18288)
		(layer "In11.Cu")
		(net "M_H_CPU1_SB_CB<4>")
	)
	(segment
		(start 141.103096 -244.990112)
		(end 139.733782 -244.990112)
		(width 0.088646)
		(layer "In11.Cu")
		(net "M_H_CPU1_SB_CB<4>")
	)
	(segment
		(start 168.509442 -239.32261)
		(end 168.279826 -239.552226)
		(width 0.18288)
		(layer "In11.Cu")
		(net "M_H_CPU1_SB_CB<4>")
	)
	(segment
		(start 158.225744 -241.840766)
		(end 152.082754 -241.840766)
		(width 0.18288)
		(layer "In11.Cu")
		(net "M_H_CPU1_SB_CB<4>")
	)
	(segment
		(start 168.279826 -239.552226)
		(end 166.679626 -239.552226)
		(width 0.18288)
		(layer "In11.Cu")
		(net "M_H_CPU1_SB_CB<4>")
	)
	(segment
		(start 170.556428 -240.404396)
		(end 169.474642 -239.32261)
		(width 0.18288)
		(layer "In11.Cu")
		(net "M_H_CPU1_SB_CB<4>")
	)
	(segment
		(start 164.469826 -240.441226)
		(end 161.294826 -240.441226)
		(width 0.18288)
		(layer "In11.Cu")
		(net "M_H_CPU1_SB_CB<4>")
	)
	(segment
		(start 202.80757 -241.097562)
		(end 202.327002 -240.898426)
		(width 0.18288)
		(layer "In11.Cu")
		(net "M_H_CPU1_SB_CB<4>")
	)
	(segment
		(start 179.557934 -239.251998)
		(end 177.41646 -239.251998)
		(width 0.18288)
		(layer "In11.Cu")
		(net "M_H_CPU1_SB_CB<4>")
	)
	(segment
		(start 192.917318 -241.091466)
		(end 190.997586 -241.091466)
		(width 0.18288)
		(layer "In11.Cu")
		(net "M_H_CPU1_SB_CB<4>")
	)
	(segment
		(start 127.818896 -244.238526)
		(end 127.804164 -244.247162)
		(width 0.088646)
		(layer "In11.Cu")
		(net "M_H_CPU1_SB_CB<4>")
	)
	(segment
		(start 184.767728 -239.365028)
		(end 184.059068 -239.365028)
		(width 0.18288)
		(layer "In11.Cu")
		(net "M_H_CPU1_SB_CB<4>")
	)
	(segment
		(start 159.315404 -241.840766)
		(end 159.122364 -242.033806)
		(width 0.18288)
		(layer "In11.Cu")
		(net "M_H_CPU1_SB_CB<4>")
	)
	(segment
		(start 164.927026 -239.984026)
		(end 164.469826 -240.441226)
		(width 0.18288)
		(layer "In11.Cu")
		(net "M_H_CPU1_SB_CB<4>")
	)
	(segment
		(start 202.327002 -240.898426)
		(end 200.52665 -240.898426)
		(width 0.18288)
		(layer "In11.Cu")
		(net "M_H_CPU1_SB_CB<4>")
	)
	(segment
		(start 172.213524 -240.241328)
		(end 172.050456 -240.404396)
		(width 0.18288)
		(layer "In11.Cu")
		(net "M_H_CPU1_SB_CB<4>")
	)
	(segment
		(start 190.064644 -241.279426)
		(end 189.026038 -240.24082)
		(width 0.18288)
		(layer "In11.Cu")
		(net "M_H_CPU1_SB_CB<4>")
	)
	(segment
		(start 158.418784 -243.750846)
		(end 158.418784 -242.033806)
		(width 0.18288)
		(layer "In11.Cu")
		(net "M_H_CPU1_SB_CB<4>")
	)
	(segment
		(start 139.058396 -244.873526)
		(end 138.820144 -245.111778)
		(width 0.088646)
		(layer "In11.Cu")
		(net "M_H_CPU1_SB_CB<4>")
	)
	(segment
		(start 166.679626 -239.552226)
		(end 166.247826 -239.984026)
		(width 0.18288)
		(layer "In11.Cu")
		(net "M_H_CPU1_SB_CB<4>")
	)
	(segment
		(start 134.397496 -244.238526)
		(end 134.382764 -244.247162)
		(width 0.088646)
		(layer "In11.Cu")
		(net "M_H_CPU1_SB_CB<4>")
	)
	(segment
		(start 181.60619 -239.51184)
		(end 181.60619 -239.124236)
		(width 0.18288)
		(layer "In11.Cu")
		(net "M_H_CPU1_SB_CB<4>")
	)
	(segment
		(start 200.52665 -240.898426)
		(end 199.996298 -240.368074)
		(width 0.18288)
		(layer "In11.Cu")
		(net "M_H_CPU1_SB_CB<4>")
	)
	(segment
		(start 158.929324 -243.943886)
		(end 158.611824 -243.943886)
		(width 0.18288)
		(layer "In11.Cu")
		(net "M_H_CPU1_SB_CB<4>")
	)
	(segment
		(start 149.13483 -244.78869)
		(end 143.51762 -244.78869)
		(width 0.18288)
		(layer "In11.Cu")
		(net "M_H_CPU1_SB_CB<4>")
	)
	(segment
		(start 185.793126 -240.390426)
		(end 184.767728 -239.365028)
		(width 0.18288)
		(layer "In11.Cu")
		(net "M_H_CPU1_SB_CB<4>")
	)
	(segment
		(start 159.122364 -243.750846)
		(end 158.929324 -243.943886)
		(width 0.18288)
		(layer "In11.Cu")
		(net "M_H_CPU1_SB_CB<4>")
	)
	(segment
		(start 173.077886 -240.241328)
		(end 172.213524 -240.241328)
		(width 0.18288)
		(layer "In11.Cu")
		(net "M_H_CPU1_SB_CB<4>")
	)
	(segment
		(start 139.733782 -244.990112)
		(end 139.617196 -244.873526)
		(width 0.088646)
		(layer "In11.Cu")
		(net "M_H_CPU1_SB_CB<4>")
	)
	(segment
		(start 159.895286 -241.840766)
		(end 159.315404 -241.840766)
		(width 0.18288)
		(layer "In11.Cu")
		(net "M_H_CPU1_SB_CB<4>")
	)
	(segment
		(start 202.971146 -241.516662)
		(end 202.971146 -241.261138)
		(width 0.18288)
		(layer "In11.Cu")
		(net "M_H_CPU1_SB_CB<4>")
	)
	(segment
		(start 125.939296 -244.238526)
		(end 125.924564 -244.247162)
		(width 0.088646)
		(layer "In11.Cu")
		(net "M_H_CPU1_SB_CB<4>")
	)
	(segment
		(start 159.122364 -242.033806)
		(end 159.122364 -243.750846)
		(width 0.18288)
		(layer "In11.Cu")
		(net "M_H_CPU1_SB_CB<4>")
	)
	(segment
		(start 143.51762 -244.78869)
		(end 143.316198 -244.990112)
		(width 0.18288)
		(layer "In11.Cu")
		(net "M_H_CPU1_SB_CB<4>")
	)
	(segment
		(start 181.09565 -238.931196)
		(end 180.90261 -239.124236)
		(width 0.18288)
		(layer "In11.Cu")
		(net "M_H_CPU1_SB_CB<4>")
	)
	(segment
		(start 190.997586 -241.091466)
		(end 190.809626 -241.279426)
		(width 0.18288)
		(layer "In11.Cu")
		(net "M_H_CPU1_SB_CB<4>")
	)
	(segment
		(start 183.719216 -239.70488)
		(end 181.79923 -239.70488)
		(width 0.18288)
		(layer "In11.Cu")
		(net "M_H_CPU1_SB_CB<4>")
	)
	(segment
		(start 136.170416 -244.73662)
		(end 136.170416 -244.726714)
		(width 0.088646)
		(layer "In11.Cu")
		(net "M_H_CPU1_SB_CB<4>")
	)
	(segment
		(start 130.638296 -244.238526)
		(end 130.623564 -244.247162)
		(width 0.088646)
		(layer "In11.Cu")
		(net "M_H_CPU1_SB_CB<4>")
	)
	(segment
		(start 139.617196 -244.873526)
		(end 139.058396 -244.873526)
		(width 0.088646)
		(layer "In11.Cu")
		(net "M_H_CPU1_SB_CB<4>")
	)
	(segment
		(start 194.378326 -240.504726)
		(end 193.504058 -240.504726)
		(width 0.18288)
		(layer "In11.Cu")
		(net "M_H_CPU1_SB_CB<4>")
	)
	(segment
		(start 180.010816 -239.70488)
		(end 179.557934 -239.251998)
		(width 0.18288)
		(layer "In11.Cu")
		(net "M_H_CPU1_SB_CB<4>")
	)
	(segment
		(start 180.90261 -239.124236)
		(end 180.90261 -239.51184)
		(width 0.18288)
		(layer "In11.Cu")
		(net "M_H_CPU1_SB_CB<4>")
	)
	(segment
		(start 202.971146 -241.261138)
		(end 202.80757 -241.097562)
		(width 0.18288)
		(layer "In11.Cu")
		(net "M_H_CPU1_SB_CB<4>")
	)
	(arc
		(start 133.068568 -244.247162)
		(mid 132.794369 -244.171327)
		(end 132.517896 -244.238526)
		(width 0.088646)
		(layer "In11.Cu")
		(net "M_H_CPU1_SB_CB<4>")
	)
	(arc
		(start 130.249168 -244.247162)
		(mid 129.972355 -244.171292)
		(end 129.693924 -244.241066)
		(width 0.088646)
		(layer "In11.Cu")
		(net "M_H_CPU1_SB_CB<4>")
	)
	(arc
		(start 136.348978 -245.055898)
		(mid 136.218064 -244.919538)
		(end 136.170416 -244.73662)
		(width 0.088646)
		(layer "In11.Cu")
		(net "M_H_CPU1_SB_CB<4>")
	)
	(arc
		(start 131.188968 -244.247162)
		(mid 130.914769 -244.171327)
		(end 130.638296 -244.238526)
		(width 0.088646)
		(layer "In11.Cu")
		(net "M_H_CPU1_SB_CB<4>")
	)
	(arc
		(start 130.623564 -244.247162)
		(mid 130.436366 -244.297305)
		(end 130.249168 -244.247162)
		(width 0.088646)
		(layer "In11.Cu")
		(net "M_H_CPU1_SB_CB<4>")
	)
	(arc
		(start 135.887968 -244.247162)
		(mid 135.605266 -244.171386)
		(end 135.322564 -244.247162)
		(width 0.088646)
		(layer "In11.Cu")
		(net "M_H_CPU1_SB_CB<4>")
	)
	(arc
		(start 134.948168 -244.247162)
		(mid 134.673969 -244.171327)
		(end 134.397496 -244.238526)
		(width 0.088646)
		(layer "In11.Cu")
		(net "M_H_CPU1_SB_CB<4>")
	)
	(arc
		(start 126.489968 -244.247162)
		(mid 126.215769 -244.171327)
		(end 125.939296 -244.238526)
		(width 0.088646)
		(layer "In11.Cu")
		(net "M_H_CPU1_SB_CB<4>")
	)
	(arc
		(start 124.601478 -244.242082)
		(mid 124.485739 -244.130258)
		(end 124.427488 -243.980208)
		(width 0.088646)
		(layer "In11.Cu")
		(net "M_H_CPU1_SB_CB<4>")
	)
	(arc
		(start 135.322564 -244.247162)
		(mid 135.135366 -244.297305)
		(end 134.948168 -244.247162)
		(width 0.088646)
		(layer "In11.Cu")
		(net "M_H_CPU1_SB_CB<4>")
	)
	(arc
		(start 132.128768 -244.247162)
		(mid 131.846066 -244.171386)
		(end 131.563364 -244.247162)
		(width 0.088646)
		(layer "In11.Cu")
		(net "M_H_CPU1_SB_CB<4>")
	)
	(arc
		(start 136.170416 -244.726714)
		(mid 136.092305 -244.449765)
		(end 135.887968 -244.247162)
		(width 0.088646)
		(layer "In11.Cu")
		(net "M_H_CPU1_SB_CB<4>")
	)
	(arc
		(start 131.563364 -244.247162)
		(mid 131.376166 -244.297305)
		(end 131.188968 -244.247162)
		(width 0.088646)
		(layer "In11.Cu")
		(net "M_H_CPU1_SB_CB<4>")
	)
	(arc
		(start 127.804164 -244.247162)
		(mid 127.616966 -244.297305)
		(end 127.429768 -244.247162)
		(width 0.088646)
		(layer "In11.Cu")
		(net "M_H_CPU1_SB_CB<4>")
	)
	(arc
		(start 134.382764 -244.247162)
		(mid 134.195566 -244.297305)
		(end 134.008368 -244.247162)
		(width 0.088646)
		(layer "In11.Cu")
		(net "M_H_CPU1_SB_CB<4>")
	)
	(arc
		(start 126.864364 -244.247162)
		(mid 126.677166 -244.297305)
		(end 126.489968 -244.247162)
		(width 0.088646)
		(layer "In11.Cu")
		(net "M_H_CPU1_SB_CB<4>")
	)
	(arc
		(start 132.503164 -244.247162)
		(mid 132.315966 -244.297305)
		(end 132.128768 -244.247162)
		(width 0.088646)
		(layer "In11.Cu")
		(net "M_H_CPU1_SB_CB<4>")
	)
	(arc
		(start 133.442964 -244.247162)
		(mid 133.255766 -244.297305)
		(end 133.068568 -244.247162)
		(width 0.088646)
		(layer "In11.Cu")
		(net "M_H_CPU1_SB_CB<4>")
	)
	(arc
		(start 136.545066 -245.111778)
		(mid 136.443143 -245.097442)
		(end 136.348978 -245.055898)
		(width 0.088646)
		(layer "In11.Cu")
		(net "M_H_CPU1_SB_CB<4>")
	)
	(arc
		(start 134.008368 -244.247162)
		(mid 133.725666 -244.171386)
		(end 133.442964 -244.247162)
		(width 0.088646)
		(layer "In11.Cu")
		(net "M_H_CPU1_SB_CB<4>")
	)
	(arc
		(start 127.429768 -244.247162)
		(mid 127.147066 -244.171386)
		(end 126.864364 -244.247162)
		(width 0.088646)
		(layer "In11.Cu")
		(net "M_H_CPU1_SB_CB<4>")
	)
	(arc
		(start 129.309114 -244.247162)
		(mid 129.032555 -244.171419)
		(end 128.754378 -244.241066)
		(width 0.088646)
		(layer "In11.Cu")
		(net "M_H_CPU1_SB_CB<4>")
	)
	(arc
		(start 125.924564 -244.247162)
		(mid 125.737366 -244.297305)
		(end 125.550168 -244.247162)
		(width 0.088646)
		(layer "In11.Cu")
		(net "M_H_CPU1_SB_CB<4>")
	)
	(arc
		(start 128.743964 -244.247162)
		(mid 128.556766 -244.297305)
		(end 128.369568 -244.247162)
		(width 0.088646)
		(layer "In11.Cu")
		(net "M_H_CPU1_SB_CB<4>")
	)
	(arc
		(start 124.984764 -244.247162)
		(mid 124.797566 -244.297305)
		(end 124.610368 -244.247162)
		(width 0.088646)
		(layer "In11.Cu")
		(net "M_H_CPU1_SB_CB<4>")
	)
	(arc
		(start 128.369568 -244.247162)
		(mid 128.095369 -244.171327)
		(end 127.818896 -244.238526)
		(width 0.088646)
		(layer "In11.Cu")
		(net "M_H_CPU1_SB_CB<4>")
	)
	(arc
		(start 125.550168 -244.247162)
		(mid 125.267466 -244.171386)
		(end 124.984764 -244.247162)
		(width 0.088646)
		(layer "In11.Cu")
		(net "M_H_CPU1_SB_CB<4>")
	)
	(arc
		(start 129.68351 -244.247162)
		(mid 129.496312 -244.297305)
		(end 129.309114 -244.247162)
		(width 0.088646)
		(layer "In11.Cu")
		(net "M_H_CPU1_SB_CB<4>")
	)
	(segment
		(start 210.603084 -233.44886)
		(end 210.610196 -233.441748)
		(width 0.1016)
		(layer "F.Cu")
		(net "M_H_CPU1_SB_CB<3>")
	)
	(segment
		(start 213.515448 -232.999026)
		(end 213.749636 -232.764838)
		(width 0.20066)
		(layer "F.Cu")
		(net "M_H_CPU1_SB_CB<3>")
	)
	(segment
		(start 212.630258 -233.45394)
		(end 213.311486 -233.45394)
		(width 0.20066)
		(layer "F.Cu")
		(net "M_H_CPU1_SB_CB<3>")
	)
	(segment
		(start 212.618066 -233.441748)
		(end 212.630258 -233.45394)
		(width 0.1016)
		(layer "F.Cu")
		(net "M_H_CPU1_SB_CB<3>")
	)
	(segment
		(start 210.306412 -233.44886)
		(end 210.598258 -233.44886)
		(width 0.20066)
		(layer "F.Cu")
		(net "M_H_CPU1_SB_CB<3>")
	)
	(segment
		(start 213.515448 -233.249978)
		(end 213.515448 -232.999026)
		(width 0.20066)
		(layer "F.Cu")
		(net "M_H_CPU1_SB_CB<3>")
	)
	(segment
		(start 213.311486 -233.45394)
		(end 213.515448 -233.249978)
		(width 0.20066)
		(layer "F.Cu")
		(net "M_H_CPU1_SB_CB<3>")
	)
	(segment
		(start 214.133684 -232.764838)
		(end 214.385652 -233.016806)
		(width 0.20066)
		(layer "F.Cu")
		(net "M_H_CPU1_SB_CB<3>")
	)
	(segment
		(start 208.176114 -233.016806)
		(end 209.874358 -233.016806)
		(width 0.20066)
		(layer "F.Cu")
		(net "M_H_CPU1_SB_CB<3>")
	)
	(segment
		(start 209.874358 -233.016806)
		(end 210.306412 -233.44886)
		(width 0.20066)
		(layer "F.Cu")
		(net "M_H_CPU1_SB_CB<3>")
	)
	(segment
		(start 124.797566 -241.202972)
		(end 124.797566 -240.667286)
		(width 0.20066)
		(layer "F.Cu")
		(net "M_H_CPU1_SB_CB<3>")
	)
	(segment
		(start 210.598258 -233.44886)
		(end 210.603084 -233.44886)
		(width 0.101854)
		(layer "F.Cu")
		(net "M_H_CPU1_SB_CB<3>")
	)
	(segment
		(start 210.610196 -233.441748)
		(end 212.618066 -233.441748)
		(width 0.1016)
		(layer "F.Cu")
		(net "M_H_CPU1_SB_CB<3>")
	)
	(segment
		(start 124.797312 -241.203226)
		(end 124.797566 -241.202972)
		(width 0.20066)
		(layer "F.Cu")
		(net "M_H_CPU1_SB_CB<3>")
	)
	(segment
		(start 214.385652 -233.016806)
		(end 215.719914 -233.016806)
		(width 0.20066)
		(layer "F.Cu")
		(net "M_H_CPU1_SB_CB<3>")
	)
	(segment
		(start 213.749636 -232.764838)
		(end 214.133684 -232.764838)
		(width 0.20066)
		(layer "F.Cu")
		(net "M_H_CPU1_SB_CB<3>")
	)
	(segment
		(start 207.071214 -233.016806)
		(end 208.176114 -233.016806)
		(width 0.20066)
		(layer "F.Cu")
		(net "M_H_CPU1_SB_CB<3>")
	)
	(segment
		(start 171.82719 -231.031796)
		(end 169.053256 -231.031796)
		(width 0.18288)
		(layer "In11.Cu")
		(net "M_H_CPU1_SB_CB<3>")
	)
	(segment
		(start 185.94578 -230.19131)
		(end 185.75274 -229.99827)
		(width 0.18288)
		(layer "In11.Cu")
		(net "M_H_CPU1_SB_CB<3>")
	)
	(segment
		(start 207.071214 -233.016806)
		(end 207.059276 -233.011472)
		(width 0.18288)
		(layer "In11.Cu")
		(net "M_H_CPU1_SB_CB<3>")
	)
	(segment
		(start 131.658868 -240.177574)
		(end 131.648454 -240.171478)
		(width 0.088646)
		(layer "In11.Cu")
		(net "M_H_CPU1_SB_CB<3>")
	)
	(segment
		(start 136.357614 -240.177574)
		(end 136.3472 -240.171478)
		(width 0.088646)
		(layer "In11.Cu")
		(net "M_H_CPU1_SB_CB<3>")
	)
	(segment
		(start 192.422526 -231.741726)
		(end 191.794638 -231.741726)
		(width 0.18288)
		(layer "In11.Cu")
		(net "M_H_CPU1_SB_CB<3>")
	)
	(segment
		(start 135.418068 -240.177574)
		(end 135.407654 -240.171478)
		(width 0.088646)
		(layer "In11.Cu")
		(net "M_H_CPU1_SB_CB<3>")
	)
	(segment
		(start 178.477926 -229.824026)
		(end 177.182526 -230.041704)
		(width 0.18288)
		(layer "In11.Cu")
		(net "M_H_CPU1_SB_CB<3>")
	)
	(segment
		(start 157.951678 -233.503216)
		(end 153.415492 -233.503216)
		(width 0.18288)
		(layer "In11.Cu")
		(net "M_H_CPU1_SB_CB<3>")
	)
	(segment
		(start 168.33342 -231.751632)
		(end 164.625528 -231.751632)
		(width 0.18288)
		(layer "In11.Cu")
		(net "M_H_CPU1_SB_CB<3>")
	)
	(segment
		(start 161.86785 -232.706418)
		(end 161.597086 -232.670858)
		(width 0.18288)
		(layer "In11.Cu")
		(net "M_H_CPU1_SB_CB<3>")
	)
	(segment
		(start 137.297668 -240.177574)
		(end 137.287254 -240.171478)
		(width 0.088646)
		(layer "In11.Cu")
		(net "M_H_CPU1_SB_CB<3>")
	)
	(segment
		(start 185.75274 -229.99827)
		(end 185.43524 -229.99827)
		(width 0.18288)
		(layer "In11.Cu")
		(net "M_H_CPU1_SB_CB<3>")
	)
	(segment
		(start 186.847226 -231.094026)
		(end 186.13882 -231.094026)
		(width 0.18288)
		(layer "In11.Cu")
		(net "M_H_CPU1_SB_CB<3>")
	)
	(segment
		(start 184.294526 -231.094026)
		(end 182.491126 -230.433626)
		(width 0.18288)
		(layer "In11.Cu")
		(net "M_H_CPU1_SB_CB<3>")
	)
	(segment
		(start 146.633184 -240.285524)
		(end 141.103096 -240.285524)
		(width 0.18288)
		(layer "In11.Cu")
		(net "M_H_CPU1_SB_CB<3>")
	)
	(segment
		(start 186.13882 -231.094026)
		(end 185.94578 -230.900986)
		(width 0.18288)
		(layer "In11.Cu")
		(net "M_H_CPU1_SB_CB<3>")
	)
	(segment
		(start 194.593718 -231.602026)
		(end 193.616326 -231.602026)
		(width 0.18288)
		(layer "In11.Cu")
		(net "M_H_CPU1_SB_CB<3>")
	)
	(segment
		(start 175.150526 -230.230426)
		(end 174.578772 -230.230426)
		(width 0.18288)
		(layer "In11.Cu")
		(net "M_H_CPU1_SB_CB<3>")
	)
	(segment
		(start 129.779014 -240.177574)
		(end 129.764282 -240.168938)
		(width 0.088646)
		(layer "In11.Cu")
		(net "M_H_CPU1_SB_CB<3>")
	)
	(segment
		(start 169.053256 -231.031796)
		(end 168.33342 -231.751632)
		(width 0.18288)
		(layer "In11.Cu")
		(net "M_H_CPU1_SB_CB<3>")
	)
	(segment
		(start 177.182526 -230.041704)
		(end 176.318926 -230.041704)
		(width 0.18288)
		(layer "In11.Cu")
		(net "M_H_CPU1_SB_CB<3>")
	)
	(segment
		(start 180.713126 -230.433626)
		(end 179.214526 -229.824026)
		(width 0.18288)
		(layer "In11.Cu")
		(net "M_H_CPU1_SB_CB<3>")
	)
	(segment
		(start 189.821566 -230.706168)
		(end 189.6364 -230.891334)
		(width 0.18288)
		(layer "In11.Cu")
		(net "M_H_CPU1_SB_CB<3>")
	)
	(segment
		(start 141.103096 -240.285524)
		(end 140.116306 -240.285524)
		(width 0.088646)
		(layer "In11.Cu")
		(net "M_H_CPU1_SB_CB<3>")
	)
	(segment
		(start 126.959614 -240.177574)
		(end 126.944882 -240.168938)
		(width 0.088646)
		(layer "In11.Cu")
		(net "M_H_CPU1_SB_CB<3>")
	)
	(segment
		(start 160.956498 -232.03027)
		(end 159.424624 -232.03027)
		(width 0.18288)
		(layer "In11.Cu")
		(net "M_H_CPU1_SB_CB<3>")
	)
	(segment
		(start 133.538468 -240.177574)
		(end 133.528054 -240.171478)
		(width 0.088646)
		(layer "In11.Cu")
		(net "M_H_CPU1_SB_CB<3>")
	)
	(segment
		(start 195.546726 -232.033826)
		(end 194.593718 -231.602026)
		(width 0.18288)
		(layer "In11.Cu")
		(net "M_H_CPU1_SB_CB<3>")
	)
	(segment
		(start 185.04916 -231.094026)
		(end 184.294526 -231.094026)
		(width 0.18288)
		(layer "In11.Cu")
		(net "M_H_CPU1_SB_CB<3>")
	)
	(segment
		(start 202.688698 -233.444796)
		(end 201.978514 -232.734612)
		(width 0.18288)
		(layer "In11.Cu")
		(net "M_H_CPU1_SB_CB<3>")
	)
	(segment
		(start 134.478014 -240.177574)
		(end 134.4676 -240.171478)
		(width 0.088646)
		(layer "In11.Cu")
		(net "M_H_CPU1_SB_CB<3>")
	)
	(segment
		(start 161.597086 -232.670858)
		(end 160.956498 -232.03027)
		(width 0.18288)
		(layer "In11.Cu")
		(net "M_H_CPU1_SB_CB<3>")
	)
	(segment
		(start 201.978514 -232.734612)
		(end 200.03135 -232.734612)
		(width 0.18288)
		(layer "In11.Cu")
		(net "M_H_CPU1_SB_CB<3>")
	)
	(segment
		(start 206.71409 -233.145838)
		(end 205.452726 -233.637074)
		(width 0.18288)
		(layer "In11.Cu")
		(net "M_H_CPU1_SB_CB<3>")
	)
	(segment
		(start 207.059276 -233.011472)
		(end 206.71409 -233.145838)
		(width 0.18288)
		(layer "In11.Cu")
		(net "M_H_CPU1_SB_CB<3>")
	)
	(segment
		(start 185.2422 -230.900986)
		(end 185.04916 -231.094026)
		(width 0.18288)
		(layer "In11.Cu")
		(net "M_H_CPU1_SB_CB<3>")
	)
	(segment
		(start 196.643752 -232.033826)
		(end 195.546726 -232.033826)
		(width 0.18288)
		(layer "In11.Cu")
		(net "M_H_CPU1_SB_CB<3>")
	)
	(segment
		(start 190.555118 -230.706168)
		(end 189.821566 -230.706168)
		(width 0.18288)
		(layer "In11.Cu")
		(net "M_H_CPU1_SB_CB<3>")
	)
	(segment
		(start 140.116306 -240.285524)
		(end 139.83335 -240.56848)
		(width 0.088646)
		(layer "In11.Cu")
		(net "M_H_CPU1_SB_CB<3>")
	)
	(segment
		(start 153.415492 -233.503216)
		(end 146.633184 -240.285524)
		(width 0.18288)
		(layer "In11.Cu")
		(net "M_H_CPU1_SB_CB<3>")
	)
	(segment
		(start 205.452726 -233.637074)
		(end 205.071726 -233.637074)
		(width 0.18288)
		(layer "In11.Cu")
		(net "M_H_CPU1_SB_CB<3>")
	)
	(segment
		(start 203.642722 -233.444796)
		(end 202.688698 -233.444796)
		(width 0.18288)
		(layer "In11.Cu")
		(net "M_H_CPU1_SB_CB<3>")
	)
	(segment
		(start 182.491126 -230.433626)
		(end 180.713126 -230.433626)
		(width 0.18288)
		(layer "In11.Cu")
		(net "M_H_CPU1_SB_CB<3>")
	)
	(segment
		(start 127.899414 -240.177574)
		(end 127.884682 -240.168938)
		(width 0.088646)
		(layer "In11.Cu")
		(net "M_H_CPU1_SB_CB<3>")
	)
	(segment
		(start 159.424624 -232.03027)
		(end 157.951678 -233.503216)
		(width 0.18288)
		(layer "In11.Cu")
		(net "M_H_CPU1_SB_CB<3>")
	)
	(segment
		(start 187.049918 -230.891334)
		(end 186.847226 -231.094026)
		(width 0.18288)
		(layer "In11.Cu")
		(net "M_H_CPU1_SB_CB<3>")
	)
	(segment
		(start 173.334172 -230.891588)
		(end 171.967398 -230.891588)
		(width 0.18288)
		(layer "In11.Cu")
		(net "M_H_CPU1_SB_CB<3>")
	)
	(segment
		(start 193.616326 -231.602026)
		(end 192.422526 -231.741726)
		(width 0.18288)
		(layer "In11.Cu")
		(net "M_H_CPU1_SB_CB<3>")
	)
	(segment
		(start 185.94578 -230.900986)
		(end 185.94578 -230.19131)
		(width 0.18288)
		(layer "In11.Cu")
		(net "M_H_CPU1_SB_CB<3>")
	)
	(segment
		(start 200.03135 -232.734612)
		(end 198.574152 -232.665524)
		(width 0.18288)
		(layer "In11.Cu")
		(net "M_H_CPU1_SB_CB<3>")
	)
	(segment
		(start 174.578772 -230.230426)
		(end 173.334172 -230.891588)
		(width 0.18288)
		(layer "In11.Cu")
		(net "M_H_CPU1_SB_CB<3>")
	)
	(segment
		(start 130.718814 -240.177574)
		(end 130.704082 -240.168938)
		(width 0.088646)
		(layer "In11.Cu")
		(net "M_H_CPU1_SB_CB<3>")
	)
	(segment
		(start 171.967398 -230.891588)
		(end 171.82719 -231.031796)
		(width 0.18288)
		(layer "In11.Cu")
		(net "M_H_CPU1_SB_CB<3>")
	)
	(segment
		(start 189.6364 -230.891334)
		(end 187.049918 -230.891334)
		(width 0.18288)
		(layer "In11.Cu")
		(net "M_H_CPU1_SB_CB<3>")
	)
	(segment
		(start 139.83335 -240.56848)
		(end 138.655552 -240.56848)
		(width 0.088646)
		(layer "In11.Cu")
		(net "M_H_CPU1_SB_CB<3>")
	)
	(segment
		(start 164.380926 -231.652826)
		(end 163.695126 -231.652826)
		(width 0.18288)
		(layer "In11.Cu")
		(net "M_H_CPU1_SB_CB<3>")
	)
	(segment
		(start 138.655552 -240.56848)
		(end 138.354562 -240.26749)
		(width 0.088646)
		(layer "In11.Cu")
		(net "M_H_CPU1_SB_CB<3>")
	)
	(segment
		(start 198.574152 -232.665524)
		(end 196.643752 -232.033826)
		(width 0.18288)
		(layer "In11.Cu")
		(net "M_H_CPU1_SB_CB<3>")
	)
	(segment
		(start 124.901706 -240.563146)
		(end 124.797566 -240.667286)
		(width 0.088646)
		(layer "In11.Cu")
		(net "M_H_CPU1_SB_CB<3>")
	)
	(segment
		(start 185.43524 -229.99827)
		(end 185.2422 -230.19131)
		(width 0.18288)
		(layer "In11.Cu")
		(net "M_H_CPU1_SB_CB<3>")
	)
	(segment
		(start 163.695126 -231.652826)
		(end 161.86785 -232.706418)
		(width 0.18288)
		(layer "In11.Cu")
		(net "M_H_CPU1_SB_CB<3>")
	)
	(segment
		(start 205.071726 -233.637074)
		(end 203.642722 -233.444796)
		(width 0.18288)
		(layer "In11.Cu")
		(net "M_H_CPU1_SB_CB<3>")
	)
	(segment
		(start 132.043678 -240.171478)
		(end 132.033264 -240.177574)
		(width 0.088646)
		(layer "In11.Cu")
		(net "M_H_CPU1_SB_CB<3>")
	)
	(segment
		(start 176.318926 -230.041704)
		(end 175.150526 -230.230426)
		(width 0.18288)
		(layer "In11.Cu")
		(net "M_H_CPU1_SB_CB<3>")
	)
	(segment
		(start 191.794638 -231.741726)
		(end 190.555118 -230.706168)
		(width 0.18288)
		(layer "In11.Cu")
		(net "M_H_CPU1_SB_CB<3>")
	)
	(segment
		(start 164.625528 -231.751632)
		(end 164.380926 -231.652826)
		(width 0.18288)
		(layer "In11.Cu")
		(net "M_H_CPU1_SB_CB<3>")
	)
	(segment
		(start 185.2422 -230.19131)
		(end 185.2422 -230.900986)
		(width 0.18288)
		(layer "In11.Cu")
		(net "M_H_CPU1_SB_CB<3>")
	)
	(segment
		(start 179.214526 -229.824026)
		(end 178.477926 -229.824026)
		(width 0.18288)
		(layer "In11.Cu")
		(net "M_H_CPU1_SB_CB<3>")
	)
	(segment
		(start 128.839214 -240.177574)
		(end 128.824482 -240.168938)
		(width 0.088646)
		(layer "In11.Cu")
		(net "M_H_CPU1_SB_CB<3>")
	)
	(arc
		(start 132.033264 -240.177574)
		(mid 131.846066 -240.227717)
		(end 131.658868 -240.177574)
		(width 0.088646)
		(layer "In11.Cu")
		(net "M_H_CPU1_SB_CB<3>")
	)
	(arc
		(start 138.354562 -240.26749)
		(mid 138.028579 -240.106728)
		(end 137.672064 -240.177574)
		(width 0.088646)
		(layer "In11.Cu")
		(net "M_H_CPU1_SB_CB<3>")
	)
	(arc
		(start 134.85241 -240.177574)
		(mid 134.665212 -240.227717)
		(end 134.478014 -240.177574)
		(width 0.088646)
		(layer "In11.Cu")
		(net "M_H_CPU1_SB_CB<3>")
	)
	(arc
		(start 132.97281 -240.177574)
		(mid 132.785612 -240.227717)
		(end 132.598414 -240.177574)
		(width 0.088646)
		(layer "In11.Cu")
		(net "M_H_CPU1_SB_CB<3>")
	)
	(arc
		(start 131.648454 -240.171478)
		(mid 131.370022 -240.101664)
		(end 131.09321 -240.177574)
		(width 0.088646)
		(layer "In11.Cu")
		(net "M_H_CPU1_SB_CB<3>")
	)
	(arc
		(start 133.912864 -240.177574)
		(mid 133.725666 -240.227717)
		(end 133.538468 -240.177574)
		(width 0.088646)
		(layer "In11.Cu")
		(net "M_H_CPU1_SB_CB<3>")
	)
	(arc
		(start 135.407654 -240.171478)
		(mid 135.129222 -240.101664)
		(end 134.85241 -240.177574)
		(width 0.088646)
		(layer "In11.Cu")
		(net "M_H_CPU1_SB_CB<3>")
	)
	(arc
		(start 136.3472 -240.171478)
		(mid 136.069022 -240.101786)
		(end 135.792464 -240.177574)
		(width 0.088646)
		(layer "In11.Cu")
		(net "M_H_CPU1_SB_CB<3>")
	)
	(arc
		(start 126.019814 -240.177574)
		(mid 125.769824 -240.102779)
		(end 125.51283 -240.14811)
		(width 0.088646)
		(layer "In11.Cu")
		(net "M_H_CPU1_SB_CB<3>")
	)
	(arc
		(start 126.944882 -240.168938)
		(mid 126.668441 -240.101772)
		(end 126.39421 -240.177574)
		(width 0.088646)
		(layer "In11.Cu")
		(net "M_H_CPU1_SB_CB<3>")
	)
	(arc
		(start 125.331728 -240.237518)
		(mid 125.105508 -240.38553)
		(end 124.901706 -240.563146)
		(width 0.088646)
		(layer "In11.Cu")
		(net "M_H_CPU1_SB_CB<3>")
	)
	(arc
		(start 137.672064 -240.177574)
		(mid 137.484866 -240.227717)
		(end 137.297668 -240.177574)
		(width 0.088646)
		(layer "In11.Cu")
		(net "M_H_CPU1_SB_CB<3>")
	)
	(arc
		(start 130.15341 -240.177574)
		(mid 129.966212 -240.227717)
		(end 129.779014 -240.177574)
		(width 0.088646)
		(layer "In11.Cu")
		(net "M_H_CPU1_SB_CB<3>")
	)
	(arc
		(start 131.09321 -240.177574)
		(mid 130.906012 -240.227717)
		(end 130.718814 -240.177574)
		(width 0.088646)
		(layer "In11.Cu")
		(net "M_H_CPU1_SB_CB<3>")
	)
	(arc
		(start 132.598414 -240.177574)
		(mid 132.321855 -240.101865)
		(end 132.043678 -240.171478)
		(width 0.088646)
		(layer "In11.Cu")
		(net "M_H_CPU1_SB_CB<3>")
	)
	(arc
		(start 134.4676 -240.171478)
		(mid 134.189422 -240.101786)
		(end 133.912864 -240.177574)
		(width 0.088646)
		(layer "In11.Cu")
		(net "M_H_CPU1_SB_CB<3>")
	)
	(arc
		(start 130.704082 -240.168938)
		(mid 130.427641 -240.101772)
		(end 130.15341 -240.177574)
		(width 0.088646)
		(layer "In11.Cu")
		(net "M_H_CPU1_SB_CB<3>")
	)
	(arc
		(start 127.884682 -240.168938)
		(mid 127.608241 -240.101772)
		(end 127.33401 -240.177574)
		(width 0.088646)
		(layer "In11.Cu")
		(net "M_H_CPU1_SB_CB<3>")
	)
	(arc
		(start 136.73201 -240.177574)
		(mid 136.544812 -240.227717)
		(end 136.357614 -240.177574)
		(width 0.088646)
		(layer "In11.Cu")
		(net "M_H_CPU1_SB_CB<3>")
	)
	(arc
		(start 128.824482 -240.168938)
		(mid 128.548041 -240.101772)
		(end 128.27381 -240.177574)
		(width 0.088646)
		(layer "In11.Cu")
		(net "M_H_CPU1_SB_CB<3>")
	)
	(arc
		(start 125.411738 -240.19891)
		(mid 125.37118 -240.217068)
		(end 125.331728 -240.237518)
		(width 0.088646)
		(layer "In11.Cu")
		(net "M_H_CPU1_SB_CB<3>")
	)
	(arc
		(start 129.21361 -240.177574)
		(mid 129.026412 -240.227717)
		(end 128.839214 -240.177574)
		(width 0.088646)
		(layer "In11.Cu")
		(net "M_H_CPU1_SB_CB<3>")
	)
	(arc
		(start 137.287254 -240.171478)
		(mid 137.008822 -240.101664)
		(end 136.73201 -240.177574)
		(width 0.088646)
		(layer "In11.Cu")
		(net "M_H_CPU1_SB_CB<3>")
	)
	(arc
		(start 135.792464 -240.177574)
		(mid 135.605266 -240.227717)
		(end 135.418068 -240.177574)
		(width 0.088646)
		(layer "In11.Cu")
		(net "M_H_CPU1_SB_CB<3>")
	)
	(arc
		(start 126.39421 -240.177574)
		(mid 126.207012 -240.227717)
		(end 126.019814 -240.177574)
		(width 0.088646)
		(layer "In11.Cu")
		(net "M_H_CPU1_SB_CB<3>")
	)
	(arc
		(start 128.27381 -240.177574)
		(mid 128.086612 -240.227717)
		(end 127.899414 -240.177574)
		(width 0.088646)
		(layer "In11.Cu")
		(net "M_H_CPU1_SB_CB<3>")
	)
	(arc
		(start 125.51283 -240.14811)
		(mid 125.493735 -240.156519)
		(end 125.47473 -240.165128)
		(width 0.088646)
		(layer "In11.Cu")
		(net "M_H_CPU1_SB_CB<3>")
	)
	(arc
		(start 125.47473 -240.165128)
		(mid 125.444045 -240.183531)
		(end 125.411738 -240.19891)
		(width 0.088646)
		(layer "In11.Cu")
		(net "M_H_CPU1_SB_CB<3>")
	)
	(arc
		(start 133.528054 -240.171478)
		(mid 133.249622 -240.101664)
		(end 132.97281 -240.177574)
		(width 0.088646)
		(layer "In11.Cu")
		(net "M_H_CPU1_SB_CB<3>")
	)
	(arc
		(start 129.764282 -240.168938)
		(mid 129.487841 -240.101772)
		(end 129.21361 -240.177574)
		(width 0.088646)
		(layer "In11.Cu")
		(net "M_H_CPU1_SB_CB<3>")
	)
	(arc
		(start 127.33401 -240.177574)
		(mid 127.146812 -240.227717)
		(end 126.959614 -240.177574)
		(width 0.088646)
		(layer "In11.Cu")
		(net "M_H_CPU1_SB_CB<3>")
	)
	(segment
		(start 213.515448 -234.698794)
		(end 213.749636 -234.464606)
		(width 0.20066)
		(layer "F.Cu")
		(net "M_H_CPU1_SB_CB<2>")
	)
	(segment
		(start 125.267212 -242.016788)
		(end 125.267212 -241.481102)
		(width 0.20066)
		(layer "F.Cu")
		(net "M_H_CPU1_SB_CB<2>")
	)
	(segment
		(start 210.603084 -235.148628)
		(end 210.610196 -235.141516)
		(width 0.1016)
		(layer "F.Cu")
		(net "M_H_CPU1_SB_CB<2>")
	)
	(segment
		(start 213.311486 -235.153708)
		(end 213.515448 -234.949746)
		(width 0.20066)
		(layer "F.Cu")
		(net "M_H_CPU1_SB_CB<2>")
	)
	(segment
		(start 212.618066 -235.141516)
		(end 212.630258 -235.153708)
		(width 0.1016)
		(layer "F.Cu")
		(net "M_H_CPU1_SB_CB<2>")
	)
	(segment
		(start 214.133684 -234.464606)
		(end 214.385652 -234.716574)
		(width 0.20066)
		(layer "F.Cu")
		(net "M_H_CPU1_SB_CB<2>")
	)
	(segment
		(start 213.749636 -234.464606)
		(end 214.133684 -234.464606)
		(width 0.20066)
		(layer "F.Cu")
		(net "M_H_CPU1_SB_CB<2>")
	)
	(segment
		(start 210.598258 -235.148628)
		(end 210.603084 -235.148628)
		(width 0.101854)
		(layer "F.Cu")
		(net "M_H_CPU1_SB_CB<2>")
	)
	(segment
		(start 212.630258 -235.153708)
		(end 213.311486 -235.153708)
		(width 0.20066)
		(layer "F.Cu")
		(net "M_H_CPU1_SB_CB<2>")
	)
	(segment
		(start 125.267466 -242.017042)
		(end 125.267212 -242.016788)
		(width 0.20066)
		(layer "F.Cu")
		(net "M_H_CPU1_SB_CB<2>")
	)
	(segment
		(start 214.385652 -234.716574)
		(end 215.719914 -234.716574)
		(width 0.20066)
		(layer "F.Cu")
		(net "M_H_CPU1_SB_CB<2>")
	)
	(segment
		(start 209.874358 -234.716574)
		(end 210.306412 -235.148628)
		(width 0.20066)
		(layer "F.Cu")
		(net "M_H_CPU1_SB_CB<2>")
	)
	(segment
		(start 207.071214 -234.716574)
		(end 208.176114 -234.716574)
		(width 0.20066)
		(layer "F.Cu")
		(net "M_H_CPU1_SB_CB<2>")
	)
	(segment
		(start 210.610196 -235.141516)
		(end 212.618066 -235.141516)
		(width 0.1016)
		(layer "F.Cu")
		(net "M_H_CPU1_SB_CB<2>")
	)
	(segment
		(start 210.306412 -235.148628)
		(end 210.598258 -235.148628)
		(width 0.20066)
		(layer "F.Cu")
		(net "M_H_CPU1_SB_CB<2>")
	)
	(segment
		(start 208.176114 -234.716574)
		(end 209.874358 -234.716574)
		(width 0.20066)
		(layer "F.Cu")
		(net "M_H_CPU1_SB_CB<2>")
	)
	(segment
		(start 213.515448 -234.949746)
		(end 213.515448 -234.698794)
		(width 0.20066)
		(layer "F.Cu")
		(net "M_H_CPU1_SB_CB<2>")
	)
	(segment
		(start 173.72965 -232.591356)
		(end 172.218096 -232.591356)
		(width 0.18288)
		(layer "In11.Cu")
		(net "M_H_CPU1_SB_CB<2>")
	)
	(segment
		(start 207.071214 -234.716574)
		(end 206.490316 -235.297472)
		(width 0.18288)
		(layer "In11.Cu")
		(net "M_H_CPU1_SB_CB<2>")
	)
	(segment
		(start 132.513324 -240.985548)
		(end 132.50291 -240.991644)
		(width 0.088646)
		(layer "In11.Cu")
		(net "M_H_CPU1_SB_CB<2>")
	)
	(segment
		(start 190.290704 -232.454704)
		(end 189.41542 -232.454704)
		(width 0.18288)
		(layer "In11.Cu")
		(net "M_H_CPU1_SB_CB<2>")
	)
	(segment
		(start 179.334668 -231.734868)
		(end 178.425348 -231.734868)
		(width 0.18288)
		(layer "In11.Cu")
		(net "M_H_CPU1_SB_CB<2>")
	)
	(segment
		(start 195.836286 -234.039918)
		(end 195.609718 -234.039918)
		(width 0.18288)
		(layer "In11.Cu")
		(net "M_H_CPU1_SB_CB<2>")
	)
	(segment
		(start 192.928748 -233.748072)
		(end 192.62217 -233.441494)
		(width 0.18288)
		(layer "In11.Cu")
		(net "M_H_CPU1_SB_CB<2>")
	)
	(segment
		(start 178.425348 -231.734868)
		(end 178.113944 -232.046272)
		(width 0.18288)
		(layer "In11.Cu")
		(net "M_H_CPU1_SB_CB<2>")
	)
	(segment
		(start 171.99356 -232.815892)
		(end 168.74236 -232.815892)
		(width 0.18288)
		(layer "In11.Cu")
		(net "M_H_CPU1_SB_CB<2>")
	)
	(segment
		(start 138.667236 -241.86388)
		(end 137.884408 -241.080798)
		(width 0.088646)
		(layer "In11.Cu")
		(net "M_H_CPU1_SB_CB<2>")
	)
	(segment
		(start 202.653646 -235.142278)
		(end 201.935842 -234.424474)
		(width 0.18288)
		(layer "In11.Cu")
		(net "M_H_CPU1_SB_CB<2>")
	)
	(segment
		(start 168.000426 -233.557826)
		(end 164.927026 -233.557826)
		(width 0.18288)
		(layer "In11.Cu")
		(net "M_H_CPU1_SB_CB<2>")
	)
	(segment
		(start 196.051932 -233.824272)
		(end 195.836286 -234.039918)
		(width 0.18288)
		(layer "In11.Cu")
		(net "M_H_CPU1_SB_CB<2>")
	)
	(segment
		(start 198.762874 -234.424474)
		(end 198.455026 -234.116626)
		(width 0.18288)
		(layer "In11.Cu")
		(net "M_H_CPU1_SB_CB<2>")
	)
	(segment
		(start 125.934724 -240.985548)
		(end 125.93066 -240.987834)
		(width 0.088646)
		(layer "In11.Cu")
		(net "M_H_CPU1_SB_CB<2>")
	)
	(segment
		(start 140.145262 -241.301524)
		(end 139.582906 -241.86388)
		(width 0.088646)
		(layer "In11.Cu")
		(net "M_H_CPU1_SB_CB<2>")
	)
	(segment
		(start 188.343032 -232.591102)
		(end 186.98845 -232.591102)
		(width 0.18288)
		(layer "In11.Cu")
		(net "M_H_CPU1_SB_CB<2>")
	)
	(segment
		(start 177.725324 -232.046272)
		(end 177.420524 -231.741472)
		(width 0.18288)
		(layer "In11.Cu")
		(net "M_H_CPU1_SB_CB<2>")
	)
	(segment
		(start 193.628772 -233.43489)
		(end 193.31559 -233.748072)
		(width 0.18288)
		(layer "In11.Cu")
		(net "M_H_CPU1_SB_CB<2>")
	)
	(segment
		(start 174.510446 -231.81056)
		(end 173.72965 -232.591356)
		(width 0.18288)
		(layer "In11.Cu")
		(net "M_H_CPU1_SB_CB<2>")
	)
	(segment
		(start 134.397496 -240.983008)
		(end 134.382764 -240.991644)
		(width 0.088646)
		(layer "In11.Cu")
		(net "M_H_CPU1_SB_CB<2>")
	)
	(segment
		(start 172.218096 -232.591356)
		(end 171.99356 -232.815892)
		(width 0.18288)
		(layer "In11.Cu")
		(net "M_H_CPU1_SB_CB<2>")
	)
	(segment
		(start 206.490316 -235.297472)
		(end 204.76718 -235.297472)
		(width 0.18288)
		(layer "In11.Cu")
		(net "M_H_CPU1_SB_CB<2>")
	)
	(segment
		(start 195.609718 -234.039918)
		(end 195.00469 -233.43489)
		(width 0.18288)
		(layer "In11.Cu")
		(net "M_H_CPU1_SB_CB<2>")
	)
	(segment
		(start 159.415734 -233.61269)
		(end 157.85211 -235.176314)
		(width 0.18288)
		(layer "In11.Cu")
		(net "M_H_CPU1_SB_CB<2>")
	)
	(segment
		(start 129.698496 -240.983008)
		(end 129.683764 -240.991644)
		(width 0.088646)
		(layer "In11.Cu")
		(net "M_H_CPU1_SB_CB<2>")
	)
	(segment
		(start 186.98845 -232.591102)
		(end 186.751722 -232.82783)
		(width 0.18288)
		(layer "In11.Cu")
		(net "M_H_CPU1_SB_CB<2>")
	)
	(segment
		(start 131.573778 -240.985548)
		(end 131.563364 -240.991644)
		(width 0.088646)
		(layer "In11.Cu")
		(net "M_H_CPU1_SB_CB<2>")
	)
	(segment
		(start 153.265632 -235.176314)
		(end 147.140422 -241.301524)
		(width 0.18288)
		(layer "In11.Cu")
		(net "M_H_CPU1_SB_CB<2>")
	)
	(segment
		(start 164.927026 -233.557826)
		(end 164.647626 -233.278426)
		(width 0.18288)
		(layer "In11.Cu")
		(net "M_H_CPU1_SB_CB<2>")
	)
	(segment
		(start 204.76718 -235.297472)
		(end 204.611986 -235.142278)
		(width 0.18288)
		(layer "In11.Cu")
		(net "M_H_CPU1_SB_CB<2>")
	)
	(segment
		(start 141.103096 -241.301524)
		(end 140.145262 -241.301524)
		(width 0.088646)
		(layer "In11.Cu")
		(net "M_H_CPU1_SB_CB<2>")
	)
	(segment
		(start 160.534858 -233.61269)
		(end 159.415734 -233.61269)
		(width 0.18288)
		(layer "In11.Cu")
		(net "M_H_CPU1_SB_CB<2>")
	)
	(segment
		(start 201.935842 -234.424474)
		(end 198.762874 -234.424474)
		(width 0.18288)
		(layer "In11.Cu")
		(net "M_H_CPU1_SB_CB<2>")
	)
	(segment
		(start 196.452998 -233.824272)
		(end 196.051932 -233.824272)
		(width 0.18288)
		(layer "In11.Cu")
		(net "M_H_CPU1_SB_CB<2>")
	)
	(segment
		(start 198.455026 -234.116626)
		(end 196.745352 -234.116626)
		(width 0.18288)
		(layer "In11.Cu")
		(net "M_H_CPU1_SB_CB<2>")
	)
	(segment
		(start 186.751722 -232.82783)
		(end 183.65343 -232.82783)
		(width 0.18288)
		(layer "In11.Cu")
		(net "M_H_CPU1_SB_CB<2>")
	)
	(segment
		(start 130.638296 -240.983008)
		(end 130.623564 -240.991644)
		(width 0.088646)
		(layer "In11.Cu")
		(net "M_H_CPU1_SB_CB<2>")
	)
	(segment
		(start 178.113944 -232.046272)
		(end 177.725324 -232.046272)
		(width 0.18288)
		(layer "In11.Cu")
		(net "M_H_CPU1_SB_CB<2>")
	)
	(segment
		(start 175.48098 -231.81056)
		(end 174.510446 -231.81056)
		(width 0.18288)
		(layer "In11.Cu")
		(net "M_H_CPU1_SB_CB<2>")
	)
	(segment
		(start 161.225738 -234.30357)
		(end 160.534858 -233.61269)
		(width 0.18288)
		(layer "In11.Cu")
		(net "M_H_CPU1_SB_CB<2>")
	)
	(segment
		(start 175.550068 -231.741472)
		(end 175.48098 -231.81056)
		(width 0.18288)
		(layer "In11.Cu")
		(net "M_H_CPU1_SB_CB<2>")
	)
	(segment
		(start 195.00469 -233.43489)
		(end 193.628772 -233.43489)
		(width 0.18288)
		(layer "In11.Cu")
		(net "M_H_CPU1_SB_CB<2>")
	)
	(segment
		(start 163.246054 -233.278426)
		(end 162.22091 -234.30357)
		(width 0.18288)
		(layer "In11.Cu")
		(net "M_H_CPU1_SB_CB<2>")
	)
	(segment
		(start 193.31559 -233.748072)
		(end 192.928748 -233.748072)
		(width 0.18288)
		(layer "In11.Cu")
		(net "M_H_CPU1_SB_CB<2>")
	)
	(segment
		(start 157.85211 -235.176314)
		(end 153.265632 -235.176314)
		(width 0.18288)
		(layer "In11.Cu")
		(net "M_H_CPU1_SB_CB<2>")
	)
	(segment
		(start 192.62217 -233.441494)
		(end 191.277494 -233.441494)
		(width 0.18288)
		(layer "In11.Cu")
		(net "M_H_CPU1_SB_CB<2>")
	)
	(segment
		(start 168.74236 -232.815892)
		(end 168.000426 -233.557826)
		(width 0.18288)
		(layer "In11.Cu")
		(net "M_H_CPU1_SB_CB<2>")
	)
	(segment
		(start 147.140422 -241.301524)
		(end 141.103096 -241.301524)
		(width 0.18288)
		(layer "In11.Cu")
		(net "M_H_CPU1_SB_CB<2>")
	)
	(segment
		(start 189.41542 -232.454704)
		(end 189.036452 -232.833672)
		(width 0.18288)
		(layer "In11.Cu")
		(net "M_H_CPU1_SB_CB<2>")
	)
	(segment
		(start 180.090826 -232.491026)
		(end 179.334668 -231.734868)
		(width 0.18288)
		(layer "In11.Cu")
		(net "M_H_CPU1_SB_CB<2>")
	)
	(segment
		(start 183.65343 -232.82783)
		(end 183.316626 -232.491026)
		(width 0.18288)
		(layer "In11.Cu")
		(net "M_H_CPU1_SB_CB<2>")
	)
	(segment
		(start 177.420524 -231.741472)
		(end 175.550068 -231.741472)
		(width 0.18288)
		(layer "In11.Cu")
		(net "M_H_CPU1_SB_CB<2>")
	)
	(segment
		(start 127.818896 -240.983008)
		(end 127.804164 -240.991644)
		(width 0.088646)
		(layer "In11.Cu")
		(net "M_H_CPU1_SB_CB<2>")
	)
	(segment
		(start 183.316626 -232.491026)
		(end 180.090826 -232.491026)
		(width 0.18288)
		(layer "In11.Cu")
		(net "M_H_CPU1_SB_CB<2>")
	)
	(segment
		(start 126.879096 -240.983008)
		(end 126.864364 -240.991644)
		(width 0.088646)
		(layer "In11.Cu")
		(net "M_H_CPU1_SB_CB<2>")
	)
	(segment
		(start 164.647626 -233.278426)
		(end 163.246054 -233.278426)
		(width 0.18288)
		(layer "In11.Cu")
		(net "M_H_CPU1_SB_CB<2>")
	)
	(segment
		(start 196.745352 -234.116626)
		(end 196.452998 -233.824272)
		(width 0.18288)
		(layer "In11.Cu")
		(net "M_H_CPU1_SB_CB<2>")
	)
	(segment
		(start 191.277494 -233.441494)
		(end 190.290704 -232.454704)
		(width 0.18288)
		(layer "In11.Cu")
		(net "M_H_CPU1_SB_CB<2>")
	)
	(segment
		(start 188.585602 -232.833672)
		(end 188.343032 -232.591102)
		(width 0.18288)
		(layer "In11.Cu")
		(net "M_H_CPU1_SB_CB<2>")
	)
	(segment
		(start 204.611986 -235.142278)
		(end 202.653646 -235.142278)
		(width 0.18288)
		(layer "In11.Cu")
		(net "M_H_CPU1_SB_CB<2>")
	)
	(segment
		(start 162.22091 -234.30357)
		(end 161.225738 -234.30357)
		(width 0.18288)
		(layer "In11.Cu")
		(net "M_H_CPU1_SB_CB<2>")
	)
	(segment
		(start 139.582906 -241.86388)
		(end 138.667236 -241.86388)
		(width 0.088646)
		(layer "In11.Cu")
		(net "M_H_CPU1_SB_CB<2>")
	)
	(segment
		(start 189.036452 -232.833672)
		(end 188.585602 -232.833672)
		(width 0.18288)
		(layer "In11.Cu")
		(net "M_H_CPU1_SB_CB<2>")
	)
	(arc
		(start 127.804164 -240.991644)
		(mid 127.616966 -241.041787)
		(end 127.429768 -240.991644)
		(width 0.088646)
		(layer "In11.Cu")
		(net "M_H_CPU1_SB_CB<2>")
	)
	(arc
		(start 134.008368 -240.991644)
		(mid 133.725666 -240.915868)
		(end 133.442964 -240.991644)
		(width 0.088646)
		(layer "In11.Cu")
		(net "M_H_CPU1_SB_CB<2>")
	)
	(arc
		(start 126.489968 -240.991644)
		(mid 126.213155 -240.915774)
		(end 125.934724 -240.985548)
		(width 0.088646)
		(layer "In11.Cu")
		(net "M_H_CPU1_SB_CB<2>")
	)
	(arc
		(start 132.128514 -240.991644)
		(mid 131.851955 -240.915901)
		(end 131.573778 -240.985548)
		(width 0.088646)
		(layer "In11.Cu")
		(net "M_H_CPU1_SB_CB<2>")
	)
	(arc
		(start 128.369568 -240.991644)
		(mid 128.095369 -240.915809)
		(end 127.818896 -240.983008)
		(width 0.088646)
		(layer "In11.Cu")
		(net "M_H_CPU1_SB_CB<2>")
	)
	(arc
		(start 131.188968 -240.991644)
		(mid 130.914769 -240.915809)
		(end 130.638296 -240.983008)
		(width 0.088646)
		(layer "In11.Cu")
		(net "M_H_CPU1_SB_CB<2>")
	)
	(arc
		(start 135.887968 -240.991644)
		(mid 135.605266 -240.915868)
		(end 135.322564 -240.991644)
		(width 0.088646)
		(layer "In11.Cu")
		(net "M_H_CPU1_SB_CB<2>")
	)
	(arc
		(start 132.50291 -240.991644)
		(mid 132.315712 -241.041787)
		(end 132.128514 -240.991644)
		(width 0.088646)
		(layer "In11.Cu")
		(net "M_H_CPU1_SB_CB<2>")
	)
	(arc
		(start 137.202164 -240.991644)
		(mid 137.014966 -241.041787)
		(end 136.827768 -240.991644)
		(width 0.088646)
		(layer "In11.Cu")
		(net "M_H_CPU1_SB_CB<2>")
	)
	(arc
		(start 127.429768 -240.991644)
		(mid 127.155569 -240.915809)
		(end 126.879096 -240.983008)
		(width 0.088646)
		(layer "In11.Cu")
		(net "M_H_CPU1_SB_CB<2>")
	)
	(arc
		(start 134.382764 -240.991644)
		(mid 134.195566 -241.041787)
		(end 134.008368 -240.991644)
		(width 0.088646)
		(layer "In11.Cu")
		(net "M_H_CPU1_SB_CB<2>")
	)
	(arc
		(start 130.623564 -240.991644)
		(mid 130.436366 -241.041787)
		(end 130.249168 -240.991644)
		(width 0.088646)
		(layer "In11.Cu")
		(net "M_H_CPU1_SB_CB<2>")
	)
	(arc
		(start 137.884408 -241.080798)
		(mid 137.85871 -241.056864)
		(end 137.831576 -241.03457)
		(width 0.088646)
		(layer "In11.Cu")
		(net "M_H_CPU1_SB_CB<2>")
	)
	(arc
		(start 129.309368 -240.991644)
		(mid 129.026666 -240.915868)
		(end 128.743964 -240.991644)
		(width 0.088646)
		(layer "In11.Cu")
		(net "M_H_CPU1_SB_CB<2>")
	)
	(arc
		(start 136.827768 -240.991644)
		(mid 136.545066 -240.915868)
		(end 136.262364 -240.991644)
		(width 0.088646)
		(layer "In11.Cu")
		(net "M_H_CPU1_SB_CB<2>")
	)
	(arc
		(start 128.743964 -240.991644)
		(mid 128.556766 -241.041787)
		(end 128.369568 -240.991644)
		(width 0.088646)
		(layer "In11.Cu")
		(net "M_H_CPU1_SB_CB<2>")
	)
	(arc
		(start 133.442964 -240.991644)
		(mid 133.255766 -241.041787)
		(end 133.068568 -240.991644)
		(width 0.088646)
		(layer "In11.Cu")
		(net "M_H_CPU1_SB_CB<2>")
	)
	(arc
		(start 137.831576 -241.03457)
		(mid 137.800304 -241.012015)
		(end 137.767568 -240.991644)
		(width 0.088646)
		(layer "In11.Cu")
		(net "M_H_CPU1_SB_CB<2>")
	)
	(arc
		(start 126.864364 -240.991644)
		(mid 126.677166 -241.041787)
		(end 126.489968 -240.991644)
		(width 0.088646)
		(layer "In11.Cu")
		(net "M_H_CPU1_SB_CB<2>")
	)
	(arc
		(start 125.902466 -241.003328)
		(mid 125.568026 -241.21986)
		(end 125.267212 -241.481102)
		(width 0.088646)
		(layer "In11.Cu")
		(net "M_H_CPU1_SB_CB<2>")
	)
	(arc
		(start 134.948168 -240.991644)
		(mid 134.673969 -240.915809)
		(end 134.397496 -240.983008)
		(width 0.088646)
		(layer "In11.Cu")
		(net "M_H_CPU1_SB_CB<2>")
	)
	(arc
		(start 131.563364 -240.991644)
		(mid 131.376166 -241.041787)
		(end 131.188968 -240.991644)
		(width 0.088646)
		(layer "In11.Cu")
		(net "M_H_CPU1_SB_CB<2>")
	)
	(arc
		(start 135.322564 -240.991644)
		(mid 135.135366 -241.041787)
		(end 134.948168 -240.991644)
		(width 0.088646)
		(layer "In11.Cu")
		(net "M_H_CPU1_SB_CB<2>")
	)
	(arc
		(start 125.93066 -240.987834)
		(mid 125.916731 -240.995887)
		(end 125.902466 -241.003328)
		(width 0.088646)
		(layer "In11.Cu")
		(net "M_H_CPU1_SB_CB<2>")
	)
	(arc
		(start 137.767568 -240.991644)
		(mid 137.484866 -240.915868)
		(end 137.202164 -240.991644)
		(width 0.088646)
		(layer "In11.Cu")
		(net "M_H_CPU1_SB_CB<2>")
	)
	(arc
		(start 129.683764 -240.991644)
		(mid 129.496566 -241.041787)
		(end 129.309368 -240.991644)
		(width 0.088646)
		(layer "In11.Cu")
		(net "M_H_CPU1_SB_CB<2>")
	)
	(arc
		(start 130.249168 -240.991644)
		(mid 129.974969 -240.915809)
		(end 129.698496 -240.983008)
		(width 0.088646)
		(layer "In11.Cu")
		(net "M_H_CPU1_SB_CB<2>")
	)
	(arc
		(start 136.262364 -240.991644)
		(mid 136.075166 -241.041787)
		(end 135.887968 -240.991644)
		(width 0.088646)
		(layer "In11.Cu")
		(net "M_H_CPU1_SB_CB<2>")
	)
	(arc
		(start 133.068568 -240.991644)
		(mid 132.791755 -240.915774)
		(end 132.513324 -240.985548)
		(width 0.088646)
		(layer "In11.Cu")
		(net "M_H_CPU1_SB_CB<2>")
	)
	(segment
		(start 206.320644 -234.115356)
		(end 205.84541 -234.115356)
		(width 0.20066)
		(layer "F.Cu")
		(net "M_H_CPU1_SB_CB<1>")
	)
	(segment
		(start 204.076046 -233.86669)
		(end 202.971146 -233.86669)
		(width 0.20066)
		(layer "F.Cu")
		(net "M_H_CPU1_SB_CB<1>")
	)
	(segment
		(start 209.596482 -233.435398)
		(end 209.186526 -233.435398)
		(width 0.20066)
		(layer "F.Cu")
		(net "M_H_CPU1_SB_CB<1>")
	)
	(segment
		(start 206.971392 -233.441748)
		(end 206.626714 -233.441748)
		(width 0.20066)
		(layer "F.Cu")
		(net "M_H_CPU1_SB_CB<1>")
	)
	(segment
		(start 206.626714 -233.441748)
		(end 206.508604 -233.559858)
		(width 0.20066)
		(layer "F.Cu")
		(net "M_H_CPU1_SB_CB<1>")
	)
	(segment
		(start 210.028028 -233.866944)
		(end 209.596482 -233.435398)
		(width 0.20066)
		(layer "F.Cu")
		(net "M_H_CPU1_SB_CB<1>")
	)
	(segment
		(start 209.186526 -233.435398)
		(end 209.180176 -233.441748)
		(width 0.1016)
		(layer "F.Cu")
		(net "M_H_CPU1_SB_CB<1>")
	)
	(segment
		(start 206.508604 -233.927396)
		(end 206.320644 -234.115356)
		(width 0.20066)
		(layer "F.Cu")
		(net "M_H_CPU1_SB_CB<1>")
	)
	(segment
		(start 211.619592 -233.866944)
		(end 210.028028 -233.866944)
		(width 0.20066)
		(layer "F.Cu")
		(net "M_H_CPU1_SB_CB<1>")
	)
	(segment
		(start 205.84541 -234.115356)
		(end 205.596744 -233.86669)
		(width 0.20066)
		(layer "F.Cu")
		(net "M_H_CPU1_SB_CB<1>")
	)
	(segment
		(start 206.991458 -233.441748)
		(end 206.971392 -233.441748)
		(width 0.101854)
		(layer "F.Cu")
		(net "M_H_CPU1_SB_CB<1>")
	)
	(segment
		(start 205.596744 -233.86669)
		(end 204.076046 -233.86669)
		(width 0.20066)
		(layer "F.Cu")
		(net "M_H_CPU1_SB_CB<1>")
	)
	(segment
		(start 209.180176 -233.441748)
		(end 206.991458 -233.441748)
		(width 0.1016)
		(layer "F.Cu")
		(net "M_H_CPU1_SB_CB<1>")
	)
	(segment
		(start 211.619846 -233.86669)
		(end 211.619592 -233.866944)
		(width 0.20066)
		(layer "F.Cu")
		(net "M_H_CPU1_SB_CB<1>")
	)
	(segment
		(start 123.857766 -241.202972)
		(end 123.857766 -240.667286)
		(width 0.20066)
		(layer "F.Cu")
		(net "M_H_CPU1_SB_CB<1>")
	)
	(segment
		(start 206.508604 -233.559858)
		(end 206.508604 -233.927396)
		(width 0.20066)
		(layer "F.Cu")
		(net "M_H_CPU1_SB_CB<1>")
	)
	(segment
		(start 123.857512 -241.203226)
		(end 123.857766 -241.202972)
		(width 0.20066)
		(layer "F.Cu")
		(net "M_H_CPU1_SB_CB<1>")
	)
	(segment
		(start 185.34888 -232.319576)
		(end 185.15584 -232.126536)
		(width 0.18288)
		(layer "In11.Cu")
		(net "M_H_CPU1_SB_CB<1>")
	)
	(segment
		(start 179.530248 -231.193848)
		(end 177.838862 -231.193848)
		(width 0.18288)
		(layer "In11.Cu")
		(net "M_H_CPU1_SB_CB<1>")
	)
	(segment
		(start 124.501402 -241.004598)
		(end 123.857766 -240.667286)
		(width 0.088646)
		(layer "In11.Cu")
		(net "M_H_CPU1_SB_CB<1>")
	)
	(segment
		(start 198.836026 -233.383074)
		(end 198.661274 -233.557826)
		(width 0.18288)
		(layer "In11.Cu")
		(net "M_H_CPU1_SB_CB<1>")
	)
	(segment
		(start 170.514264 -232.30586)
		(end 170.196764 -232.30586)
		(width 0.18288)
		(layer "In11.Cu")
		(net "M_H_CPU1_SB_CB<1>")
	)
	(segment
		(start 185.15584 -232.126536)
		(end 185.15584 -231.795066)
		(width 0.18288)
		(layer "In11.Cu")
		(net "M_H_CPU1_SB_CB<1>")
	)
	(segment
		(start 185.15584 -231.795066)
		(end 184.9628 -231.602026)
		(width 0.18288)
		(layer "In11.Cu")
		(net "M_H_CPU1_SB_CB<1>")
	)
	(segment
		(start 196.956426 -233.557826)
		(end 195.940426 -232.541826)
		(width 0.18288)
		(layer "In11.Cu")
		(net "M_H_CPU1_SB_CB<1>")
	)
	(segment
		(start 169.810684 -231.551226)
		(end 169.295826 -231.551226)
		(width 0.18288)
		(layer "In11.Cu")
		(net "M_H_CPU1_SB_CB<1>")
	)
	(segment
		(start 139.702794 -240.793524)
		(end 139.667996 -240.758726)
		(width 0.088646)
		(layer "In11.Cu")
		(net "M_H_CPU1_SB_CB<1>")
	)
	(segment
		(start 194.398646 -232.915206)
		(end 193.997834 -232.915206)
		(width 0.18288)
		(layer "In11.Cu")
		(net "M_H_CPU1_SB_CB<1>")
	)
	(segment
		(start 166.68242 -232.264458)
		(end 166.48938 -232.457498)
		(width 0.18288)
		(layer "In11.Cu")
		(net "M_H_CPU1_SB_CB<1>")
	)
	(segment
		(start 153.512774 -234.200446)
		(end 146.919696 -240.793524)
		(width 0.18288)
		(layer "In11.Cu")
		(net "M_H_CPU1_SB_CB<1>")
	)
	(segment
		(start 188.797946 -231.525826)
		(end 188.582554 -231.741218)
		(width 0.18288)
		(layer "In11.Cu")
		(net "M_H_CPU1_SB_CB<1>")
	)
	(segment
		(start 164.899594 -232.264458)
		(end 164.520626 -232.643426)
		(width 0.18288)
		(layer "In11.Cu")
		(net "M_H_CPU1_SB_CB<1>")
	)
	(segment
		(start 193.674238 -232.59161)
		(end 191.353186 -232.59161)
		(width 0.18288)
		(layer "In11.Cu")
		(net "M_H_CPU1_SB_CB<1>")
	)
	(segment
		(start 165.59276 -232.264458)
		(end 164.899594 -232.264458)
		(width 0.18288)
		(layer "In11.Cu")
		(net "M_H_CPU1_SB_CB<1>")
	)
	(segment
		(start 195.940426 -232.541826)
		(end 194.772026 -232.541826)
		(width 0.18288)
		(layer "In11.Cu")
		(net "M_H_CPU1_SB_CB<1>")
	)
	(segment
		(start 202.971146 -233.86669)
		(end 202.971146 -233.959908)
		(width 0.18288)
		(layer "In11.Cu")
		(net "M_H_CPU1_SB_CB<1>")
	)
	(segment
		(start 174.002192 -231.50195)
		(end 173.423834 -231.741472)
		(width 0.18288)
		(layer "In11.Cu")
		(net "M_H_CPU1_SB_CB<1>")
	)
	(segment
		(start 175.875188 -230.891588)
		(end 175.722026 -230.738426)
		(width 0.18288)
		(layer "In11.Cu")
		(net "M_H_CPU1_SB_CB<1>")
	)
	(segment
		(start 165.7858 -232.853484)
		(end 165.7858 -232.457498)
		(width 0.18288)
		(layer "In11.Cu")
		(net "M_H_CPU1_SB_CB<1>")
	)
	(segment
		(start 161.719768 -233.329226)
		(end 161.247074 -233.329226)
		(width 0.18288)
		(layer "In11.Cu")
		(net "M_H_CPU1_SB_CB<1>")
	)
	(segment
		(start 169.295826 -231.551226)
		(end 168.582594 -232.264458)
		(width 0.18288)
		(layer "In11.Cu")
		(net "M_H_CPU1_SB_CB<1>")
	)
	(segment
		(start 202.971146 -233.959908)
		(end 202.777852 -234.153202)
		(width 0.18288)
		(layer "In11.Cu")
		(net "M_H_CPU1_SB_CB<1>")
	)
	(segment
		(start 183.265826 -231.983026)
		(end 180.319426 -231.983026)
		(width 0.18288)
		(layer "In11.Cu")
		(net "M_H_CPU1_SB_CB<1>")
	)
	(segment
		(start 157.973014 -234.200446)
		(end 153.512774 -234.200446)
		(width 0.18288)
		(layer "In11.Cu")
		(net "M_H_CPU1_SB_CB<1>")
	)
	(segment
		(start 189.770766 -231.934766)
		(end 189.361826 -231.525826)
		(width 0.18288)
		(layer "In11.Cu")
		(net "M_H_CPU1_SB_CB<1>")
	)
	(segment
		(start 132.513324 -240.349024)
		(end 132.50291 -240.342928)
		(width 0.088646)
		(layer "In11.Cu")
		(net "M_H_CPU1_SB_CB<1>")
	)
	(segment
		(start 174.765716 -230.738426)
		(end 174.002192 -231.50195)
		(width 0.18288)
		(layer "In11.Cu")
		(net "M_H_CPU1_SB_CB<1>")
	)
	(segment
		(start 161.247074 -233.329226)
		(end 160.471358 -232.55351)
		(width 0.18288)
		(layer "In11.Cu")
		(net "M_H_CPU1_SB_CB<1>")
	)
	(segment
		(start 170.003724 -231.744266)
		(end 169.810684 -231.551226)
		(width 0.18288)
		(layer "In11.Cu")
		(net "M_H_CPU1_SB_CB<1>")
	)
	(segment
		(start 185.85942 -231.795066)
		(end 185.85942 -232.126536)
		(width 0.18288)
		(layer "In11.Cu")
		(net "M_H_CPU1_SB_CB<1>")
	)
	(segment
		(start 170.900344 -231.551226)
		(end 170.707304 -231.744266)
		(width 0.18288)
		(layer "In11.Cu")
		(net "M_H_CPU1_SB_CB<1>")
	)
	(segment
		(start 165.97884 -233.046524)
		(end 165.7858 -232.853484)
		(width 0.18288)
		(layer "In11.Cu")
		(net "M_H_CPU1_SB_CB<1>")
	)
	(segment
		(start 164.520626 -232.643426)
		(end 163.375594 -232.643426)
		(width 0.18288)
		(layer "In11.Cu")
		(net "M_H_CPU1_SB_CB<1>")
	)
	(segment
		(start 170.196764 -232.30586)
		(end 170.003724 -232.11282)
		(width 0.18288)
		(layer "In11.Cu")
		(net "M_H_CPU1_SB_CB<1>")
	)
	(segment
		(start 193.997834 -232.915206)
		(end 193.674238 -232.59161)
		(width 0.18288)
		(layer "In11.Cu")
		(net "M_H_CPU1_SB_CB<1>")
	)
	(segment
		(start 202.284838 -234.026202)
		(end 202.128882 -233.649774)
		(width 0.18288)
		(layer "In11.Cu")
		(net "M_H_CPU1_SB_CB<1>")
	)
	(segment
		(start 128.758696 -240.351564)
		(end 128.743964 -240.342928)
		(width 0.088646)
		(layer "In11.Cu")
		(net "M_H_CPU1_SB_CB<1>")
	)
	(segment
		(start 134.397496 -240.351564)
		(end 134.382764 -240.342928)
		(width 0.088646)
		(layer "In11.Cu")
		(net "M_H_CPU1_SB_CB<1>")
	)
	(segment
		(start 185.85942 -232.126536)
		(end 185.66638 -232.319576)
		(width 0.18288)
		(layer "In11.Cu")
		(net "M_H_CPU1_SB_CB<1>")
	)
	(segment
		(start 165.7858 -232.457498)
		(end 165.59276 -232.264458)
		(width 0.18288)
		(layer "In11.Cu")
		(net "M_H_CPU1_SB_CB<1>")
	)
	(segment
		(start 188.582554 -231.741218)
		(end 186.986418 -231.741218)
		(width 0.18288)
		(layer "In11.Cu")
		(net "M_H_CPU1_SB_CB<1>")
	)
	(segment
		(start 189.361826 -231.525826)
		(end 188.797946 -231.525826)
		(width 0.18288)
		(layer "In11.Cu")
		(net "M_H_CPU1_SB_CB<1>")
	)
	(segment
		(start 201.862182 -233.383074)
		(end 198.836026 -233.383074)
		(width 0.18288)
		(layer "In11.Cu")
		(net "M_H_CPU1_SB_CB<1>")
	)
	(segment
		(start 160.471358 -232.55351)
		(end 159.61995 -232.55351)
		(width 0.18288)
		(layer "In11.Cu")
		(net "M_H_CPU1_SB_CB<1>")
	)
	(segment
		(start 168.582594 -232.264458)
		(end 166.68242 -232.264458)
		(width 0.18288)
		(layer "In11.Cu")
		(net "M_H_CPU1_SB_CB<1>")
	)
	(segment
		(start 130.638296 -240.351564)
		(end 130.623564 -240.342928)
		(width 0.088646)
		(layer "In11.Cu")
		(net "M_H_CPU1_SB_CB<1>")
	)
	(segment
		(start 186.05246 -231.602026)
		(end 185.85942 -231.795066)
		(width 0.18288)
		(layer "In11.Cu")
		(net "M_H_CPU1_SB_CB<1>")
	)
	(segment
		(start 190.696342 -231.934766)
		(end 189.770766 -231.934766)
		(width 0.18288)
		(layer "In11.Cu")
		(net "M_H_CPU1_SB_CB<1>")
	)
	(segment
		(start 194.772026 -232.541826)
		(end 194.398646 -232.915206)
		(width 0.18288)
		(layer "In11.Cu")
		(net "M_H_CPU1_SB_CB<1>")
	)
	(segment
		(start 132.128514 -240.342928)
		(end 132.1181 -240.349024)
		(width 0.088646)
		(layer "In11.Cu")
		(net "M_H_CPU1_SB_CB<1>")
	)
	(segment
		(start 127.818896 -240.351564)
		(end 127.804164 -240.342928)
		(width 0.088646)
		(layer "In11.Cu")
		(net "M_H_CPU1_SB_CB<1>")
	)
	(segment
		(start 126.879096 -240.351564)
		(end 126.864364 -240.342928)
		(width 0.088646)
		(layer "In11.Cu")
		(net "M_H_CPU1_SB_CB<1>")
	)
	(segment
		(start 125.362716 -240.667032)
		(end 125.362462 -240.667286)
		(width 0.088646)
		(layer "In11.Cu")
		(net "M_H_CPU1_SB_CB<1>")
	)
	(segment
		(start 202.777852 -234.153202)
		(end 202.411838 -234.153202)
		(width 0.18288)
		(layer "In11.Cu")
		(net "M_H_CPU1_SB_CB<1>")
	)
	(segment
		(start 159.61995 -232.55351)
		(end 157.973014 -234.200446)
		(width 0.18288)
		(layer "In11.Cu")
		(net "M_H_CPU1_SB_CB<1>")
	)
	(segment
		(start 170.003724 -232.11282)
		(end 170.003724 -231.744266)
		(width 0.18288)
		(layer "In11.Cu")
		(net "M_H_CPU1_SB_CB<1>")
	)
	(segment
		(start 175.722026 -230.738426)
		(end 174.765716 -230.738426)
		(width 0.18288)
		(layer "In11.Cu")
		(net "M_H_CPU1_SB_CB<1>")
	)
	(segment
		(start 173.423834 -231.741472)
		(end 171.873672 -231.741472)
		(width 0.18288)
		(layer "In11.Cu")
		(net "M_H_CPU1_SB_CB<1>")
	)
	(segment
		(start 166.48938 -232.457498)
		(end 166.48938 -232.853484)
		(width 0.18288)
		(layer "In11.Cu")
		(net "M_H_CPU1_SB_CB<1>")
	)
	(segment
		(start 129.698496 -240.351564)
		(end 129.683764 -240.342928)
		(width 0.088646)
		(layer "In11.Cu")
		(net "M_H_CPU1_SB_CB<1>")
	)
	(segment
		(start 170.707304 -231.744266)
		(end 170.707304 -232.11282)
		(width 0.18288)
		(layer "In11.Cu")
		(net "M_H_CPU1_SB_CB<1>")
	)
	(segment
		(start 171.873672 -231.741472)
		(end 171.683426 -231.551226)
		(width 0.18288)
		(layer "In11.Cu")
		(net "M_H_CPU1_SB_CB<1>")
	)
	(segment
		(start 138.576558 -240.758726)
		(end 138.219942 -240.40211)
		(width 0.088646)
		(layer "In11.Cu")
		(net "M_H_CPU1_SB_CB<1>")
	)
	(segment
		(start 186.847226 -231.602026)
		(end 186.05246 -231.602026)
		(width 0.18288)
		(layer "In11.Cu")
		(net "M_H_CPU1_SB_CB<1>")
	)
	(segment
		(start 170.707304 -232.11282)
		(end 170.514264 -232.30586)
		(width 0.18288)
		(layer "In11.Cu")
		(net "M_H_CPU1_SB_CB<1>")
	)
	(segment
		(start 136.277096 -240.351564)
		(end 136.262364 -240.342928)
		(width 0.088646)
		(layer "In11.Cu")
		(net "M_H_CPU1_SB_CB<1>")
	)
	(segment
		(start 202.128882 -233.649774)
		(end 201.862182 -233.383074)
		(width 0.18288)
		(layer "In11.Cu")
		(net "M_H_CPU1_SB_CB<1>")
	)
	(segment
		(start 163.375594 -232.643426)
		(end 161.719768 -233.329226)
		(width 0.18288)
		(layer "In11.Cu")
		(net "M_H_CPU1_SB_CB<1>")
	)
	(segment
		(start 186.986418 -231.741218)
		(end 186.847226 -231.602026)
		(width 0.18288)
		(layer "In11.Cu")
		(net "M_H_CPU1_SB_CB<1>")
	)
	(segment
		(start 198.661274 -233.557826)
		(end 196.956426 -233.557826)
		(width 0.18288)
		(layer "In11.Cu")
		(net "M_H_CPU1_SB_CB<1>")
	)
	(segment
		(start 180.319426 -231.983026)
		(end 179.530248 -231.193848)
		(width 0.18288)
		(layer "In11.Cu")
		(net "M_H_CPU1_SB_CB<1>")
	)
	(segment
		(start 166.29634 -233.046524)
		(end 165.97884 -233.046524)
		(width 0.18288)
		(layer "In11.Cu")
		(net "M_H_CPU1_SB_CB<1>")
	)
	(segment
		(start 139.667996 -240.758726)
		(end 138.576558 -240.758726)
		(width 0.088646)
		(layer "In11.Cu")
		(net "M_H_CPU1_SB_CB<1>")
	)
	(segment
		(start 177.838862 -231.193848)
		(end 177.536602 -230.891588)
		(width 0.18288)
		(layer "In11.Cu")
		(net "M_H_CPU1_SB_CB<1>")
	)
	(segment
		(start 125.362462 -240.667286)
		(end 125.362462 -240.68278)
		(width 0.088646)
		(layer "In11.Cu")
		(net "M_H_CPU1_SB_CB<1>")
	)
	(segment
		(start 141.103096 -240.793524)
		(end 139.702794 -240.793524)
		(width 0.088646)
		(layer "In11.Cu")
		(net "M_H_CPU1_SB_CB<1>")
	)
	(segment
		(start 183.646826 -231.602026)
		(end 183.265826 -231.983026)
		(width 0.18288)
		(layer "In11.Cu")
		(net "M_H_CPU1_SB_CB<1>")
	)
	(segment
		(start 125.934724 -240.349024)
		(end 125.92431 -240.342928)
		(width 0.088646)
		(layer "In11.Cu")
		(net "M_H_CPU1_SB_CB<1>")
	)
	(segment
		(start 146.919696 -240.793524)
		(end 141.103096 -240.793524)
		(width 0.18288)
		(layer "In11.Cu")
		(net "M_H_CPU1_SB_CB<1>")
	)
	(segment
		(start 185.66638 -232.319576)
		(end 185.34888 -232.319576)
		(width 0.18288)
		(layer "In11.Cu")
		(net "M_H_CPU1_SB_CB<1>")
	)
	(segment
		(start 184.9628 -231.602026)
		(end 183.646826 -231.602026)
		(width 0.18288)
		(layer "In11.Cu")
		(net "M_H_CPU1_SB_CB<1>")
	)
	(segment
		(start 171.683426 -231.551226)
		(end 170.900344 -231.551226)
		(width 0.18288)
		(layer "In11.Cu")
		(net "M_H_CPU1_SB_CB<1>")
	)
	(segment
		(start 177.536602 -230.891588)
		(end 175.875188 -230.891588)
		(width 0.18288)
		(layer "In11.Cu")
		(net "M_H_CPU1_SB_CB<1>")
	)
	(segment
		(start 202.411838 -234.153202)
		(end 202.284838 -234.026202)
		(width 0.18288)
		(layer "In11.Cu")
		(net "M_H_CPU1_SB_CB<1>")
	)
	(segment
		(start 191.353186 -232.59161)
		(end 190.696342 -231.934766)
		(width 0.18288)
		(layer "In11.Cu")
		(net "M_H_CPU1_SB_CB<1>")
	)
	(segment
		(start 166.48938 -232.853484)
		(end 166.29634 -233.046524)
		(width 0.18288)
		(layer "In11.Cu")
		(net "M_H_CPU1_SB_CB<1>")
	)
	(arc
		(start 125.92431 -240.342928)
		(mid 125.835474 -240.305995)
		(end 125.74016 -240.29289)
		(width 0.088646)
		(layer "In11.Cu")
		(net "M_H_CPU1_SB_CB<1>")
	)
	(arc
		(start 130.623564 -240.342928)
		(mid 130.436366 -240.292785)
		(end 130.249168 -240.342928)
		(width 0.088646)
		(layer "In11.Cu")
		(net "M_H_CPU1_SB_CB<1>")
	)
	(arc
		(start 125.362462 -240.68278)
		(mid 125.256007 -240.941677)
		(end 124.998226 -241.050826)
		(width 0.088646)
		(layer "In11.Cu")
		(net "M_H_CPU1_SB_CB<1>")
	)
	(arc
		(start 133.442964 -240.342928)
		(mid 133.255766 -240.292785)
		(end 133.068568 -240.342928)
		(width 0.088646)
		(layer "In11.Cu")
		(net "M_H_CPU1_SB_CB<1>")
	)
	(arc
		(start 138.219942 -240.40211)
		(mid 138.182892 -240.369964)
		(end 138.141964 -240.342928)
		(width 0.088646)
		(layer "In11.Cu")
		(net "M_H_CPU1_SB_CB<1>")
	)
	(arc
		(start 132.1181 -240.349024)
		(mid 131.839922 -240.418716)
		(end 131.563364 -240.342928)
		(width 0.088646)
		(layer "In11.Cu")
		(net "M_H_CPU1_SB_CB<1>")
	)
	(arc
		(start 128.743964 -240.342928)
		(mid 128.556766 -240.292785)
		(end 128.369568 -240.342928)
		(width 0.088646)
		(layer "In11.Cu")
		(net "M_H_CPU1_SB_CB<1>")
	)
	(arc
		(start 134.382764 -240.342928)
		(mid 134.195566 -240.292785)
		(end 134.008368 -240.342928)
		(width 0.088646)
		(layer "In11.Cu")
		(net "M_H_CPU1_SB_CB<1>")
	)
	(arc
		(start 136.827768 -240.342928)
		(mid 136.553539 -240.418853)
		(end 136.277096 -240.351564)
		(width 0.088646)
		(layer "In11.Cu")
		(net "M_H_CPU1_SB_CB<1>")
	)
	(arc
		(start 134.948168 -240.342928)
		(mid 134.673939 -240.418853)
		(end 134.397496 -240.351564)
		(width 0.088646)
		(layer "In11.Cu")
		(net "M_H_CPU1_SB_CB<1>")
	)
	(arc
		(start 134.008368 -240.342928)
		(mid 133.725666 -240.41867)
		(end 133.442964 -240.342928)
		(width 0.088646)
		(layer "In11.Cu")
		(net "M_H_CPU1_SB_CB<1>")
	)
	(arc
		(start 127.804164 -240.342928)
		(mid 127.616966 -240.292785)
		(end 127.429768 -240.342928)
		(width 0.088646)
		(layer "In11.Cu")
		(net "M_H_CPU1_SB_CB<1>")
	)
	(arc
		(start 138.141964 -240.342928)
		(mid 137.954766 -240.292785)
		(end 137.767568 -240.342928)
		(width 0.088646)
		(layer "In11.Cu")
		(net "M_H_CPU1_SB_CB<1>")
	)
	(arc
		(start 135.887968 -240.342928)
		(mid 135.605266 -240.41867)
		(end 135.322564 -240.342928)
		(width 0.088646)
		(layer "In11.Cu")
		(net "M_H_CPU1_SB_CB<1>")
	)
	(arc
		(start 129.309368 -240.342928)
		(mid 129.035139 -240.418853)
		(end 128.758696 -240.351564)
		(width 0.088646)
		(layer "In11.Cu")
		(net "M_H_CPU1_SB_CB<1>")
	)
	(arc
		(start 132.50291 -240.342928)
		(mid 132.315712 -240.292785)
		(end 132.128514 -240.342928)
		(width 0.088646)
		(layer "In11.Cu")
		(net "M_H_CPU1_SB_CB<1>")
	)
	(arc
		(start 131.188968 -240.342928)
		(mid 130.914739 -240.418853)
		(end 130.638296 -240.351564)
		(width 0.088646)
		(layer "In11.Cu")
		(net "M_H_CPU1_SB_CB<1>")
	)
	(arc
		(start 124.998226 -241.050826)
		(mid 124.792106 -241.045803)
		(end 124.586492 -241.030506)
		(width 0.088646)
		(layer "In11.Cu")
		(net "M_H_CPU1_SB_CB<1>")
	)
	(arc
		(start 129.683764 -240.342928)
		(mid 129.496566 -240.292785)
		(end 129.309368 -240.342928)
		(width 0.088646)
		(layer "In11.Cu")
		(net "M_H_CPU1_SB_CB<1>")
	)
	(arc
		(start 128.369568 -240.342928)
		(mid 128.095339 -240.418853)
		(end 127.818896 -240.351564)
		(width 0.088646)
		(layer "In11.Cu")
		(net "M_H_CPU1_SB_CB<1>")
	)
	(arc
		(start 135.322564 -240.342928)
		(mid 135.135366 -240.292785)
		(end 134.948168 -240.342928)
		(width 0.088646)
		(layer "In11.Cu")
		(net "M_H_CPU1_SB_CB<1>")
	)
	(arc
		(start 131.563364 -240.342928)
		(mid 131.376166 -240.292785)
		(end 131.188968 -240.342928)
		(width 0.088646)
		(layer "In11.Cu")
		(net "M_H_CPU1_SB_CB<1>")
	)
	(arc
		(start 126.489968 -240.342928)
		(mid 126.213155 -240.418764)
		(end 125.934724 -240.349024)
		(width 0.088646)
		(layer "In11.Cu")
		(net "M_H_CPU1_SB_CB<1>")
	)
	(arc
		(start 137.767568 -240.342928)
		(mid 137.484866 -240.41867)
		(end 137.202164 -240.342928)
		(width 0.088646)
		(layer "In11.Cu")
		(net "M_H_CPU1_SB_CB<1>")
	)
	(arc
		(start 136.262364 -240.342928)
		(mid 136.075166 -240.292785)
		(end 135.887968 -240.342928)
		(width 0.088646)
		(layer "In11.Cu")
		(net "M_H_CPU1_SB_CB<1>")
	)
	(arc
		(start 137.202164 -240.342928)
		(mid 137.014966 -240.292785)
		(end 136.827768 -240.342928)
		(width 0.088646)
		(layer "In11.Cu")
		(net "M_H_CPU1_SB_CB<1>")
	)
	(arc
		(start 124.586492 -241.030506)
		(mid 124.542711 -241.021619)
		(end 124.501402 -241.004598)
		(width 0.088646)
		(layer "In11.Cu")
		(net "M_H_CPU1_SB_CB<1>")
	)
	(arc
		(start 133.068568 -240.342928)
		(mid 132.791755 -240.418764)
		(end 132.513324 -240.349024)
		(width 0.088646)
		(layer "In11.Cu")
		(net "M_H_CPU1_SB_CB<1>")
	)
	(arc
		(start 125.74016 -240.29289)
		(mid 125.473535 -240.401374)
		(end 125.362716 -240.667032)
		(width 0.088646)
		(layer "In11.Cu")
		(net "M_H_CPU1_SB_CB<1>")
	)
	(arc
		(start 126.864364 -240.342928)
		(mid 126.677166 -240.292785)
		(end 126.489968 -240.342928)
		(width 0.088646)
		(layer "In11.Cu")
		(net "M_H_CPU1_SB_CB<1>")
	)
	(arc
		(start 130.249168 -240.342928)
		(mid 129.974939 -240.418853)
		(end 129.698496 -240.351564)
		(width 0.088646)
		(layer "In11.Cu")
		(net "M_H_CPU1_SB_CB<1>")
	)
	(arc
		(start 127.429768 -240.342928)
		(mid 127.155539 -240.418853)
		(end 126.879096 -240.351564)
		(width 0.088646)
		(layer "In11.Cu")
		(net "M_H_CPU1_SB_CB<1>")
	)
	(segment
		(start 204.076046 -235.566712)
		(end 202.971146 -235.566712)
		(width 0.20066)
		(layer "F.Cu")
		(net "M_H_CPU1_SB_CB<0>")
	)
	(segment
		(start 205.596744 -235.566712)
		(end 204.076046 -235.566712)
		(width 0.20066)
		(layer "F.Cu")
		(net "M_H_CPU1_SB_CB<0>")
	)
	(segment
		(start 207.018382 -235.14177)
		(end 206.971392 -235.14177)
		(width 0.101854)
		(layer "F.Cu")
		(net "M_H_CPU1_SB_CB<0>")
	)
	(segment
		(start 206.508604 -235.25988)
		(end 206.508604 -235.627418)
		(width 0.20066)
		(layer "F.Cu")
		(net "M_H_CPU1_SB_CB<0>")
	)
	(segment
		(start 209.596482 -235.13542)
		(end 209.186526 -235.13542)
		(width 0.20066)
		(layer "F.Cu")
		(net "M_H_CPU1_SB_CB<0>")
	)
	(segment
		(start 206.320644 -235.815378)
		(end 205.84541 -235.815378)
		(width 0.20066)
		(layer "F.Cu")
		(net "M_H_CPU1_SB_CB<0>")
	)
	(segment
		(start 206.971392 -235.14177)
		(end 206.626714 -235.14177)
		(width 0.20066)
		(layer "F.Cu")
		(net "M_H_CPU1_SB_CB<0>")
	)
	(segment
		(start 123.387612 -242.016788)
		(end 123.387612 -241.481102)
		(width 0.20066)
		(layer "F.Cu")
		(net "M_H_CPU1_SB_CB<0>")
	)
	(segment
		(start 210.028028 -235.566966)
		(end 209.596482 -235.13542)
		(width 0.20066)
		(layer "F.Cu")
		(net "M_H_CPU1_SB_CB<0>")
	)
	(segment
		(start 206.626714 -235.14177)
		(end 206.508604 -235.25988)
		(width 0.20066)
		(layer "F.Cu")
		(net "M_H_CPU1_SB_CB<0>")
	)
	(segment
		(start 123.387866 -242.017042)
		(end 123.387612 -242.016788)
		(width 0.20066)
		(layer "F.Cu")
		(net "M_H_CPU1_SB_CB<0>")
	)
	(segment
		(start 205.84541 -235.815378)
		(end 205.596744 -235.566712)
		(width 0.20066)
		(layer "F.Cu")
		(net "M_H_CPU1_SB_CB<0>")
	)
	(segment
		(start 211.619846 -235.566712)
		(end 211.619592 -235.566966)
		(width 0.20066)
		(layer "F.Cu")
		(net "M_H_CPU1_SB_CB<0>")
	)
	(segment
		(start 211.619592 -235.566966)
		(end 210.028028 -235.566966)
		(width 0.20066)
		(layer "F.Cu")
		(net "M_H_CPU1_SB_CB<0>")
	)
	(segment
		(start 206.508604 -235.627418)
		(end 206.320644 -235.815378)
		(width 0.20066)
		(layer "F.Cu")
		(net "M_H_CPU1_SB_CB<0>")
	)
	(segment
		(start 209.186526 -235.13542)
		(end 209.180176 -235.14177)
		(width 0.1016)
		(layer "F.Cu")
		(net "M_H_CPU1_SB_CB<0>")
	)
	(segment
		(start 209.180176 -235.14177)
		(end 207.018382 -235.14177)
		(width 0.1016)
		(layer "F.Cu")
		(net "M_H_CPU1_SB_CB<0>")
	)
	(segment
		(start 178.021234 -232.591356)
		(end 175.726852 -232.591356)
		(width 0.18288)
		(layer "In11.Cu")
		(net "M_H_CPU1_SB_CB<0>")
	)
	(segment
		(start 166.778432 -234.7595)
		(end 166.585392 -234.95254)
		(width 0.18288)
		(layer "In11.Cu")
		(net "M_H_CPU1_SB_CB<0>")
	)
	(segment
		(start 178.200304 -232.770426)
		(end 178.021234 -232.591356)
		(width 0.18288)
		(layer "In11.Cu")
		(net "M_H_CPU1_SB_CB<0>")
	)
	(segment
		(start 126.959614 -241.156744)
		(end 126.944882 -241.16538)
		(width 0.088646)
		(layer "In11.Cu")
		(net "M_H_CPU1_SB_CB<0>")
	)
	(segment
		(start 194.032378 -234.291378)
		(end 193.85407 -234.291378)
		(width 0.18288)
		(layer "In11.Cu")
		(net "M_H_CPU1_SB_CB<0>")
	)
	(segment
		(start 159.516318 -234.24769)
		(end 158.051246 -235.712762)
		(width 0.18288)
		(layer "In11.Cu")
		(net "M_H_CPU1_SB_CB<0>")
	)
	(segment
		(start 160.838134 -234.827826)
		(end 160.257998 -234.24769)
		(width 0.18288)
		(layer "In11.Cu")
		(net "M_H_CPU1_SB_CB<0>")
	)
	(segment
		(start 202.971146 -235.566712)
		(end 202.352656 -235.566712)
		(width 0.18288)
		(layer "In11.Cu")
		(net "M_H_CPU1_SB_CB<0>")
	)
	(segment
		(start 166.778432 -234.284266)
		(end 166.778432 -234.7595)
		(width 0.18288)
		(layer "In11.Cu")
		(net "M_H_CPU1_SB_CB<0>")
	)
	(segment
		(start 155.316174 -236.191298)
		(end 155.123134 -236.384338)
		(width 0.18288)
		(layer "In11.Cu")
		(net "M_H_CPU1_SB_CB<0>")
	)
	(segment
		(start 198.569326 -235.043726)
		(end 198.455026 -235.158026)
		(width 0.18288)
		(layer "In11.Cu")
		(net "M_H_CPU1_SB_CB<0>")
	)
	(segment
		(start 133.538468 -241.156744)
		(end 133.528054 -241.16284)
		(width 0.088646)
		(layer "In11.Cu")
		(net "M_H_CPU1_SB_CB<0>")
	)
	(segment
		(start 125.766068 -241.563144)
		(end 125.505718 -241.772186)
		(width 0.088646)
		(layer "In11.Cu")
		(net "M_H_CPU1_SB_CB<0>")
	)
	(segment
		(start 156.019754 -236.191298)
		(end 156.019754 -235.905802)
		(width 0.18288)
		(layer "In11.Cu")
		(net "M_H_CPU1_SB_CB<0>")
	)
	(segment
		(start 155.316174 -235.905802)
		(end 155.316174 -236.191298)
		(width 0.18288)
		(layer "In11.Cu")
		(net "M_H_CPU1_SB_CB<0>")
	)
	(segment
		(start 194.899026 -235.158026)
		(end 194.032378 -234.291378)
		(width 0.18288)
		(layer "In11.Cu")
		(net "M_H_CPU1_SB_CB<0>")
	)
	(segment
		(start 193.571368 -234.57408)
		(end 193.123312 -234.57408)
		(width 0.18288)
		(layer "In11.Cu")
		(net "M_H_CPU1_SB_CB<0>")
	)
	(segment
		(start 156.212794 -236.384338)
		(end 156.019754 -236.191298)
		(width 0.18288)
		(layer "In11.Cu")
		(net "M_H_CPU1_SB_CB<0>")
	)
	(segment
		(start 131.658614 -241.156744)
		(end 131.643882 -241.16538)
		(width 0.088646)
		(layer "In11.Cu")
		(net "M_H_CPU1_SB_CB<0>")
	)
	(segment
		(start 156.723334 -236.191298)
		(end 156.530294 -236.384338)
		(width 0.18288)
		(layer "In11.Cu")
		(net "M_H_CPU1_SB_CB<0>")
	)
	(segment
		(start 183.64708 -233.405172)
		(end 183.601614 -233.450638)
		(width 0.18288)
		(layer "In11.Cu")
		(net "M_H_CPU1_SB_CB<0>")
	)
	(segment
		(start 129.779014 -241.156744)
		(end 129.7686 -241.16284)
		(width 0.088646)
		(layer "In11.Cu")
		(net "M_H_CPU1_SB_CB<0>")
	)
	(segment
		(start 154.612594 -235.905802)
		(end 154.419554 -235.712762)
		(width 0.18288)
		(layer "In11.Cu")
		(net "M_H_CPU1_SB_CB<0>")
	)
	(segment
		(start 165.881812 -234.091226)
		(end 164.838126 -234.091226)
		(width 0.18288)
		(layer "In11.Cu")
		(net "M_H_CPU1_SB_CB<0>")
	)
	(segment
		(start 170.350434 -234.058968)
		(end 170.157394 -233.865928)
		(width 0.18288)
		(layer "In11.Cu")
		(net "M_H_CPU1_SB_CB<0>")
	)
	(segment
		(start 169.964354 -233.325162)
		(end 169.09669 -233.325162)
		(width 0.18288)
		(layer "In11.Cu")
		(net "M_H_CPU1_SB_CB<0>")
	)
	(segment
		(start 193.85407 -234.291378)
		(end 193.571368 -234.57408)
		(width 0.18288)
		(layer "In11.Cu")
		(net "M_H_CPU1_SB_CB<0>")
	)
	(segment
		(start 173.921166 -233.44124)
		(end 171.89704 -233.44124)
		(width 0.18288)
		(layer "In11.Cu")
		(net "M_H_CPU1_SB_CB<0>")
	)
	(segment
		(start 179.252626 -232.770426)
		(end 178.200304 -232.770426)
		(width 0.18288)
		(layer "In11.Cu")
		(net "M_H_CPU1_SB_CB<0>")
	)
	(segment
		(start 170.860974 -233.518202)
		(end 170.860974 -233.865928)
		(width 0.18288)
		(layer "In11.Cu")
		(net "M_H_CPU1_SB_CB<0>")
	)
	(segment
		(start 166.074852 -234.7595)
		(end 166.074852 -234.284266)
		(width 0.18288)
		(layer "In11.Cu")
		(net "M_H_CPU1_SB_CB<0>")
	)
	(segment
		(start 128.839468 -241.156744)
		(end 128.829054 -241.16284)
		(width 0.088646)
		(layer "In11.Cu")
		(net "M_H_CPU1_SB_CB<0>")
	)
	(segment
		(start 154.612594 -236.191298)
		(end 154.612594 -235.905802)
		(width 0.18288)
		(layer "In11.Cu")
		(net "M_H_CPU1_SB_CB<0>")
	)
	(segment
		(start 154.805634 -236.384338)
		(end 154.612594 -236.191298)
		(width 0.18288)
		(layer "In11.Cu")
		(net "M_H_CPU1_SB_CB<0>")
	)
	(segment
		(start 201.82967 -235.043726)
		(end 198.569326 -235.043726)
		(width 0.18288)
		(layer "In11.Cu")
		(net "M_H_CPU1_SB_CB<0>")
	)
	(segment
		(start 175.726852 -232.591356)
		(end 175.559212 -232.423716)
		(width 0.18288)
		(layer "In11.Cu")
		(net "M_H_CPU1_SB_CB<0>")
	)
	(segment
		(start 202.352656 -235.566712)
		(end 201.82967 -235.043726)
		(width 0.18288)
		(layer "In11.Cu")
		(net "M_H_CPU1_SB_CB<0>")
	)
	(segment
		(start 155.123134 -236.384338)
		(end 154.805634 -236.384338)
		(width 0.18288)
		(layer "In11.Cu")
		(net "M_H_CPU1_SB_CB<0>")
	)
	(segment
		(start 170.157394 -233.865928)
		(end 170.157394 -233.518202)
		(width 0.18288)
		(layer "In11.Cu")
		(net "M_H_CPU1_SB_CB<0>")
	)
	(segment
		(start 130.718814 -241.156744)
		(end 130.704082 -241.16538)
		(width 0.088646)
		(layer "In11.Cu")
		(net "M_H_CPU1_SB_CB<0>")
	)
	(segment
		(start 190.579756 -233.74858)
		(end 189.41542 -233.74858)
		(width 0.18288)
		(layer "In11.Cu")
		(net "M_H_CPU1_SB_CB<0>")
	)
	(segment
		(start 175.559212 -232.423716)
		(end 174.93869 -232.423716)
		(width 0.18288)
		(layer "In11.Cu")
		(net "M_H_CPU1_SB_CB<0>")
	)
	(segment
		(start 166.585392 -234.95254)
		(end 166.267892 -234.95254)
		(width 0.18288)
		(layer "In11.Cu")
		(net "M_H_CPU1_SB_CB<0>")
	)
	(segment
		(start 139.936474 -241.809524)
		(end 139.67206 -242.073938)
		(width 0.088646)
		(layer "In11.Cu")
		(net "M_H_CPU1_SB_CB<0>")
	)
	(segment
		(start 170.860974 -233.865928)
		(end 170.667934 -234.058968)
		(width 0.18288)
		(layer "In11.Cu")
		(net "M_H_CPU1_SB_CB<0>")
	)
	(segment
		(start 147.360894 -241.809524)
		(end 141.103096 -241.809524)
		(width 0.18288)
		(layer "In11.Cu")
		(net "M_H_CPU1_SB_CB<0>")
	)
	(segment
		(start 198.455026 -235.158026)
		(end 194.899026 -235.158026)
		(width 0.18288)
		(layer "In11.Cu")
		(net "M_H_CPU1_SB_CB<0>")
	)
	(segment
		(start 170.157394 -233.518202)
		(end 169.964354 -233.325162)
		(width 0.18288)
		(layer "In11.Cu")
		(net "M_H_CPU1_SB_CB<0>")
	)
	(segment
		(start 162.429698 -234.827826)
		(end 160.838134 -234.827826)
		(width 0.18288)
		(layer "In11.Cu")
		(net "M_H_CPU1_SB_CB<0>")
	)
	(segment
		(start 171.780962 -233.325162)
		(end 171.054014 -233.325162)
		(width 0.18288)
		(layer "In11.Cu")
		(net "M_H_CPU1_SB_CB<0>")
	)
	(segment
		(start 174.93869 -232.423716)
		(end 173.921166 -233.44124)
		(width 0.18288)
		(layer "In11.Cu")
		(net "M_H_CPU1_SB_CB<0>")
	)
	(segment
		(start 179.932838 -233.450638)
		(end 179.252626 -232.770426)
		(width 0.18288)
		(layer "In11.Cu")
		(net "M_H_CPU1_SB_CB<0>")
	)
	(segment
		(start 166.267892 -234.95254)
		(end 166.074852 -234.7595)
		(width 0.18288)
		(layer "In11.Cu")
		(net "M_H_CPU1_SB_CB<0>")
	)
	(segment
		(start 135.418068 -241.156744)
		(end 135.407654 -241.16284)
		(width 0.088646)
		(layer "In11.Cu")
		(net "M_H_CPU1_SB_CB<0>")
	)
	(segment
		(start 191.122554 -234.291378)
		(end 190.579756 -233.74858)
		(width 0.18288)
		(layer "In11.Cu")
		(net "M_H_CPU1_SB_CB<0>")
	)
	(segment
		(start 189.110366 -233.443526)
		(end 186.859926 -233.443526)
		(width 0.18288)
		(layer "In11.Cu")
		(net "M_H_CPU1_SB_CB<0>")
	)
	(segment
		(start 166.074852 -234.284266)
		(end 165.881812 -234.091226)
		(width 0.18288)
		(layer "In11.Cu")
		(net "M_H_CPU1_SB_CB<0>")
	)
	(segment
		(start 156.723334 -235.905802)
		(end 156.723334 -236.191298)
		(width 0.18288)
		(layer "In11.Cu")
		(net "M_H_CPU1_SB_CB<0>")
	)
	(segment
		(start 155.509214 -235.712762)
		(end 155.316174 -235.905802)
		(width 0.18288)
		(layer "In11.Cu")
		(net "M_H_CPU1_SB_CB<0>")
	)
	(segment
		(start 154.419554 -235.712762)
		(end 153.457656 -235.712762)
		(width 0.18288)
		(layer "In11.Cu")
		(net "M_H_CPU1_SB_CB<0>")
	)
	(segment
		(start 162.940238 -234.317286)
		(end 162.429698 -234.827826)
		(width 0.18288)
		(layer "In11.Cu")
		(net "M_H_CPU1_SB_CB<0>")
	)
	(segment
		(start 156.530294 -236.384338)
		(end 156.212794 -236.384338)
		(width 0.18288)
		(layer "In11.Cu")
		(net "M_H_CPU1_SB_CB<0>")
	)
	(segment
		(start 164.612066 -234.317286)
		(end 162.940238 -234.317286)
		(width 0.18288)
		(layer "In11.Cu")
		(net "M_H_CPU1_SB_CB<0>")
	)
	(segment
		(start 164.838126 -234.091226)
		(end 164.612066 -234.317286)
		(width 0.18288)
		(layer "In11.Cu")
		(net "M_H_CPU1_SB_CB<0>")
	)
	(segment
		(start 124.140214 -241.80546)
		(end 123.743212 -241.576352)
		(width 0.088646)
		(layer "In11.Cu")
		(net "M_H_CPU1_SB_CB<0>")
	)
	(segment
		(start 153.457656 -235.712762)
		(end 147.360894 -241.809524)
		(width 0.18288)
		(layer "In11.Cu")
		(net "M_H_CPU1_SB_CB<0>")
	)
	(segment
		(start 193.123312 -234.57408)
		(end 192.84061 -234.291378)
		(width 0.18288)
		(layer "In11.Cu")
		(net "M_H_CPU1_SB_CB<0>")
	)
	(segment
		(start 166.971472 -234.091226)
		(end 166.778432 -234.284266)
		(width 0.18288)
		(layer "In11.Cu")
		(net "M_H_CPU1_SB_CB<0>")
	)
	(segment
		(start 139.67206 -242.073938)
		(end 138.608054 -242.073938)
		(width 0.088646)
		(layer "In11.Cu")
		(net "M_H_CPU1_SB_CB<0>")
	)
	(segment
		(start 171.054014 -233.325162)
		(end 170.860974 -233.518202)
		(width 0.18288)
		(layer "In11.Cu")
		(net "M_H_CPU1_SB_CB<0>")
	)
	(segment
		(start 189.41542 -233.74858)
		(end 189.110366 -233.443526)
		(width 0.18288)
		(layer "In11.Cu")
		(net "M_H_CPU1_SB_CB<0>")
	)
	(segment
		(start 141.103096 -241.809524)
		(end 139.936474 -241.809524)
		(width 0.088646)
		(layer "In11.Cu")
		(net "M_H_CPU1_SB_CB<0>")
	)
	(segment
		(start 183.601614 -233.450638)
		(end 179.932838 -233.450638)
		(width 0.18288)
		(layer "In11.Cu")
		(net "M_H_CPU1_SB_CB<0>")
	)
	(segment
		(start 156.916374 -235.712762)
		(end 156.723334 -235.905802)
		(width 0.18288)
		(layer "In11.Cu")
		(net "M_H_CPU1_SB_CB<0>")
	)
	(segment
		(start 158.051246 -235.712762)
		(end 156.916374 -235.712762)
		(width 0.18288)
		(layer "In11.Cu")
		(net "M_H_CPU1_SB_CB<0>")
	)
	(segment
		(start 138.608054 -242.073938)
		(end 137.750042 -241.215926)
		(width 0.088646)
		(layer "In11.Cu")
		(net "M_H_CPU1_SB_CB<0>")
	)
	(segment
		(start 134.478014 -241.156744)
		(end 134.4676 -241.16284)
		(width 0.088646)
		(layer "In11.Cu")
		(net "M_H_CPU1_SB_CB<0>")
	)
	(segment
		(start 186.859926 -233.443526)
		(end 186.821572 -233.405172)
		(width 0.18288)
		(layer "In11.Cu")
		(net "M_H_CPU1_SB_CB<0>")
	)
	(segment
		(start 169.09669 -233.325162)
		(end 168.330626 -234.091226)
		(width 0.18288)
		(layer "In11.Cu")
		(net "M_H_CPU1_SB_CB<0>")
	)
	(segment
		(start 192.84061 -234.291378)
		(end 191.122554 -234.291378)
		(width 0.18288)
		(layer "In11.Cu")
		(net "M_H_CPU1_SB_CB<0>")
	)
	(segment
		(start 186.821572 -233.405172)
		(end 183.64708 -233.405172)
		(width 0.18288)
		(layer "In11.Cu")
		(net "M_H_CPU1_SB_CB<0>")
	)
	(segment
		(start 127.899414 -241.156744)
		(end 127.884682 -241.16538)
		(width 0.088646)
		(layer "In11.Cu")
		(net "M_H_CPU1_SB_CB<0>")
	)
	(segment
		(start 170.667934 -234.058968)
		(end 170.350434 -234.058968)
		(width 0.18288)
		(layer "In11.Cu")
		(net "M_H_CPU1_SB_CB<0>")
	)
	(segment
		(start 171.89704 -233.44124)
		(end 171.780962 -233.325162)
		(width 0.18288)
		(layer "In11.Cu")
		(net "M_H_CPU1_SB_CB<0>")
	)
	(segment
		(start 155.826714 -235.712762)
		(end 155.509214 -235.712762)
		(width 0.18288)
		(layer "In11.Cu")
		(net "M_H_CPU1_SB_CB<0>")
	)
	(segment
		(start 160.257998 -234.24769)
		(end 159.516318 -234.24769)
		(width 0.18288)
		(layer "In11.Cu")
		(net "M_H_CPU1_SB_CB<0>")
	)
	(segment
		(start 156.019754 -235.905802)
		(end 155.826714 -235.712762)
		(width 0.18288)
		(layer "In11.Cu")
		(net "M_H_CPU1_SB_CB<0>")
	)
	(segment
		(start 168.330626 -234.091226)
		(end 166.971472 -234.091226)
		(width 0.18288)
		(layer "In11.Cu")
		(net "M_H_CPU1_SB_CB<0>")
	)
	(arc
		(start 127.33401 -241.156744)
		(mid 127.146812 -241.106601)
		(end 126.959614 -241.156744)
		(width 0.088646)
		(layer "In11.Cu")
		(net "M_H_CPU1_SB_CB<0>")
	)
	(arc
		(start 125.505718 -241.772186)
		(mid 125.48586 -241.786661)
		(end 125.464824 -241.799364)
		(width 0.088646)
		(layer "In11.Cu")
		(net "M_H_CPU1_SB_CB<0>")
	)
	(arc
		(start 127.884682 -241.16538)
		(mid 127.608207 -241.2327)
		(end 127.33401 -241.156744)
		(width 0.088646)
		(layer "In11.Cu")
		(net "M_H_CPU1_SB_CB<0>")
	)
	(arc
		(start 132.03301 -241.156744)
		(mid 131.845812 -241.106601)
		(end 131.658614 -241.156744)
		(width 0.088646)
		(layer "In11.Cu")
		(net "M_H_CPU1_SB_CB<0>")
	)
	(arc
		(start 125.9713 -241.190018)
		(mid 125.886673 -241.287134)
		(end 125.839982 -241.407188)
		(width 0.088646)
		(layer "In11.Cu")
		(net "M_H_CPU1_SB_CB<0>")
	)
	(arc
		(start 125.839982 -241.407188)
		(mid 125.837111 -241.422755)
		(end 125.834902 -241.43843)
		(width 0.088646)
		(layer "In11.Cu")
		(net "M_H_CPU1_SB_CB<0>")
	)
	(arc
		(start 125.464824 -241.799364)
		(mid 125.459601 -241.802384)
		(end 125.45441 -241.80546)
		(width 0.088646)
		(layer "In11.Cu")
		(net "M_H_CPU1_SB_CB<0>")
	)
	(arc
		(start 126.944882 -241.16538)
		(mid 126.668407 -241.2327)
		(end 126.39421 -241.156744)
		(width 0.088646)
		(layer "In11.Cu")
		(net "M_H_CPU1_SB_CB<0>")
	)
	(arc
		(start 135.407654 -241.16284)
		(mid 135.129222 -241.232686)
		(end 134.85241 -241.156744)
		(width 0.088646)
		(layer "In11.Cu")
		(net "M_H_CPU1_SB_CB<0>")
	)
	(arc
		(start 137.750042 -241.215926)
		(mid 137.712992 -241.18378)
		(end 137.672064 -241.156744)
		(width 0.088646)
		(layer "In11.Cu")
		(net "M_H_CPU1_SB_CB<0>")
	)
	(arc
		(start 137.672064 -241.156744)
		(mid 137.484866 -241.106601)
		(end 137.297668 -241.156744)
		(width 0.088646)
		(layer "In11.Cu")
		(net "M_H_CPU1_SB_CB<0>")
	)
	(arc
		(start 128.27381 -241.156744)
		(mid 128.086612 -241.106601)
		(end 127.899414 -241.156744)
		(width 0.088646)
		(layer "In11.Cu")
		(net "M_H_CPU1_SB_CB<0>")
	)
	(arc
		(start 125.45441 -241.80546)
		(mid 125.265375 -241.858154)
		(end 125.074426 -241.812826)
		(width 0.088646)
		(layer "In11.Cu")
		(net "M_H_CPU1_SB_CB<0>")
	)
	(arc
		(start 132.97281 -241.156744)
		(mid 132.785612 -241.106601)
		(end 132.598414 -241.156744)
		(width 0.088646)
		(layer "In11.Cu")
		(net "M_H_CPU1_SB_CB<0>")
	)
	(arc
		(start 125.074426 -241.812826)
		(mid 124.795414 -241.741753)
		(end 124.51461 -241.80546)
		(width 0.088646)
		(layer "In11.Cu")
		(net "M_H_CPU1_SB_CB<0>")
	)
	(arc
		(start 136.732264 -241.156744)
		(mid 136.545066 -241.106601)
		(end 136.357868 -241.156744)
		(width 0.088646)
		(layer "In11.Cu")
		(net "M_H_CPU1_SB_CB<0>")
	)
	(arc
		(start 136.357868 -241.156744)
		(mid 136.075166 -241.23252)
		(end 135.792464 -241.156744)
		(width 0.088646)
		(layer "In11.Cu")
		(net "M_H_CPU1_SB_CB<0>")
	)
	(arc
		(start 128.829054 -241.16284)
		(mid 128.550622 -241.232686)
		(end 128.27381 -241.156744)
		(width 0.088646)
		(layer "In11.Cu")
		(net "M_H_CPU1_SB_CB<0>")
	)
	(arc
		(start 134.4676 -241.16284)
		(mid 134.189422 -241.232563)
		(end 133.912864 -241.156744)
		(width 0.088646)
		(layer "In11.Cu")
		(net "M_H_CPU1_SB_CB<0>")
	)
	(arc
		(start 130.15341 -241.156744)
		(mid 129.966212 -241.106601)
		(end 129.779014 -241.156744)
		(width 0.088646)
		(layer "In11.Cu")
		(net "M_H_CPU1_SB_CB<0>")
	)
	(arc
		(start 130.704082 -241.16538)
		(mid 130.427607 -241.2327)
		(end 130.15341 -241.156744)
		(width 0.088646)
		(layer "In11.Cu")
		(net "M_H_CPU1_SB_CB<0>")
	)
	(arc
		(start 131.09321 -241.156744)
		(mid 130.906012 -241.106601)
		(end 130.718814 -241.156744)
		(width 0.088646)
		(layer "In11.Cu")
		(net "M_H_CPU1_SB_CB<0>")
	)
	(arc
		(start 131.643882 -241.16538)
		(mid 131.367407 -241.2327)
		(end 131.09321 -241.156744)
		(width 0.088646)
		(layer "In11.Cu")
		(net "M_H_CPU1_SB_CB<0>")
	)
	(arc
		(start 126.019814 -241.156744)
		(mid 125.994889 -241.172408)
		(end 125.9713 -241.190018)
		(width 0.088646)
		(layer "In11.Cu")
		(net "M_H_CPU1_SB_CB<0>")
	)
	(arc
		(start 133.528054 -241.16284)
		(mid 133.249622 -241.232686)
		(end 132.97281 -241.156744)
		(width 0.088646)
		(layer "In11.Cu")
		(net "M_H_CPU1_SB_CB<0>")
	)
	(arc
		(start 133.912864 -241.156744)
		(mid 133.725666 -241.106601)
		(end 133.538468 -241.156744)
		(width 0.088646)
		(layer "In11.Cu")
		(net "M_H_CPU1_SB_CB<0>")
	)
	(arc
		(start 124.51461 -241.80546)
		(mid 124.327412 -241.855603)
		(end 124.140214 -241.80546)
		(width 0.088646)
		(layer "In11.Cu")
		(net "M_H_CPU1_SB_CB<0>")
	)
	(arc
		(start 135.792464 -241.156744)
		(mid 135.605266 -241.106601)
		(end 135.418068 -241.156744)
		(width 0.088646)
		(layer "In11.Cu")
		(net "M_H_CPU1_SB_CB<0>")
	)
	(arc
		(start 125.834902 -241.43843)
		(mid 125.812795 -241.507576)
		(end 125.766068 -241.563144)
		(width 0.088646)
		(layer "In11.Cu")
		(net "M_H_CPU1_SB_CB<0>")
	)
	(arc
		(start 126.39421 -241.156744)
		(mid 126.207012 -241.106601)
		(end 126.019814 -241.156744)
		(width 0.088646)
		(layer "In11.Cu")
		(net "M_H_CPU1_SB_CB<0>")
	)
	(arc
		(start 134.85241 -241.156744)
		(mid 134.665212 -241.106601)
		(end 134.478014 -241.156744)
		(width 0.088646)
		(layer "In11.Cu")
		(net "M_H_CPU1_SB_CB<0>")
	)
	(arc
		(start 123.743212 -241.576352)
		(mid 123.571679 -241.505331)
		(end 123.387612 -241.481102)
		(width 0.088646)
		(layer "In11.Cu")
		(net "M_H_CPU1_SB_CB<0>")
	)
	(arc
		(start 137.297668 -241.156744)
		(mid 137.014966 -241.23252)
		(end 136.732264 -241.156744)
		(width 0.088646)
		(layer "In11.Cu")
		(net "M_H_CPU1_SB_CB<0>")
	)
	(arc
		(start 132.598414 -241.156744)
		(mid 132.315712 -241.23252)
		(end 132.03301 -241.156744)
		(width 0.088646)
		(layer "In11.Cu")
		(net "M_H_CPU1_SB_CB<0>")
	)
	(arc
		(start 129.7686 -241.16284)
		(mid 129.490422 -241.232563)
		(end 129.213864 -241.156744)
		(width 0.088646)
		(layer "In11.Cu")
		(net "M_H_CPU1_SB_CB<0>")
	)
	(arc
		(start 129.213864 -241.156744)
		(mid 129.026666 -241.106601)
		(end 128.839468 -241.156744)
		(width 0.088646)
		(layer "In11.Cu")
		(net "M_H_CPU1_SB_CB<0>")
	)
	(segment
		(start 202.971146 -247.466612)
		(end 204.076046 -247.466612)
		(width 0.20066)
		(layer "F.Cu")
		(net "M_H_CPU1_SB_CA<6>")
	)
	(segment
		(start 207.001618 -247.891554)
		(end 209.17408 -247.891554)
		(width 0.1016)
		(layer "F.Cu")
		(net "M_H_CPU1_SB_CA<6>")
	)
	(segment
		(start 205.961234 -246.972328)
		(end 206.88046 -247.891554)
		(width 0.20066)
		(layer "F.Cu")
		(net "M_H_CPU1_SB_CA<6>")
	)
	(segment
		(start 210.04022 -247.466358)
		(end 211.619592 -247.466358)
		(width 0.20066)
		(layer "F.Cu")
		(net "M_H_CPU1_SB_CA<6>")
	)
	(segment
		(start 209.602578 -247.904)
		(end 210.04022 -247.466358)
		(width 0.20066)
		(layer "F.Cu")
		(net "M_H_CPU1_SB_CA<6>")
	)
	(segment
		(start 211.619592 -247.466358)
		(end 211.619846 -247.466612)
		(width 0.20066)
		(layer "F.Cu")
		(net "M_H_CPU1_SB_CA<6>")
	)
	(segment
		(start 204.076046 -247.466612)
		(end 205.141576 -247.466612)
		(width 0.20066)
		(layer "F.Cu")
		(net "M_H_CPU1_SB_CA<6>")
	)
	(segment
		(start 206.88046 -247.891554)
		(end 206.987902 -247.891554)
		(width 0.20066)
		(layer "F.Cu")
		(net "M_H_CPU1_SB_CA<6>")
	)
	(segment
		(start 205.141576 -247.466612)
		(end 205.63586 -246.972328)
		(width 0.20066)
		(layer "F.Cu")
		(net "M_H_CPU1_SB_CA<6>")
	)
	(segment
		(start 206.987902 -247.891554)
		(end 207.001618 -247.891554)
		(width 0.101854)
		(layer "F.Cu")
		(net "M_H_CPU1_SB_CA<6>")
	)
	(segment
		(start 126.207266 -245.27256)
		(end 126.207012 -245.272306)
		(width 0.20066)
		(layer "F.Cu")
		(net "M_H_CPU1_SB_CA<6>")
	)
	(segment
		(start 209.186526 -247.904)
		(end 209.602578 -247.904)
		(width 0.20066)
		(layer "F.Cu")
		(net "M_H_CPU1_SB_CA<6>")
	)
	(segment
		(start 205.63586 -246.972328)
		(end 205.961234 -246.972328)
		(width 0.20066)
		(layer "F.Cu")
		(net "M_H_CPU1_SB_CA<6>")
	)
	(segment
		(start 126.207012 -245.272306)
		(end 126.207012 -244.73662)
		(width 0.20066)
		(layer "F.Cu")
		(net "M_H_CPU1_SB_CA<6>")
	)
	(segment
		(start 209.17408 -247.891554)
		(end 209.186526 -247.904)
		(width 0.1016)
		(layer "F.Cu")
		(net "M_H_CPU1_SB_CA<6>")
	)
	(segment
		(start 202.867006 -247.882156)
		(end 202.412854 -248.07037)
		(width 0.18288)
		(layer "In11.Cu")
		(net "M_H_CPU1_SB_CA<6>")
	)
	(segment
		(start 202.971146 -247.778016)
		(end 202.867006 -247.882156)
		(width 0.18288)
		(layer "In11.Cu")
		(net "M_H_CPU1_SB_CA<6>")
	)
	(segment
		(start 177.877724 -247.041162)
		(end 176.20869 -247.041162)
		(width 0.18288)
		(layer "In11.Cu")
		(net "M_H_CPU1_SB_CA<6>")
	)
	(segment
		(start 156.046424 -247.806972)
		(end 155.728924 -247.806972)
		(width 0.18288)
		(layer "In11.Cu")
		(net "M_H_CPU1_SB_CA<6>")
	)
	(segment
		(start 138.1125 -247.069864)
		(end 137.62355 -247.069864)
		(width 0.088646)
		(layer "In11.Cu")
		(net "M_H_CPU1_SB_CA<6>")
	)
	(segment
		(start 192.892426 -248.741184)
		(end 190.650622 -248.741184)
		(width 0.18288)
		(layer "In11.Cu")
		(net "M_H_CPU1_SB_CA<6>")
	)
	(segment
		(start 128.931416 -245.560596)
		(end 128.931416 -245.55069)
		(width 0.088646)
		(layer "In11.Cu")
		(net "M_H_CPU1_SB_CA<6>")
	)
	(segment
		(start 139.105132 -247.069864)
		(end 138.1125 -247.069864)
		(width 0.18288)
		(layer "In11.Cu")
		(net "M_H_CPU1_SB_CA<6>")
	)
	(segment
		(start 181.833266 -247.77319)
		(end 181.337458 -247.277382)
		(width 0.18288)
		(layer "In11.Cu")
		(net "M_H_CPU1_SB_CA<6>")
	)
	(segment
		(start 164.482526 -248.061226)
		(end 161.510726 -248.061226)
		(width 0.18288)
		(layer "In11.Cu")
		(net "M_H_CPU1_SB_CA<6>")
	)
	(segment
		(start 131.658614 -246.040148)
		(end 131.643882 -246.048784)
		(width 0.088646)
		(layer "In11.Cu")
		(net "M_H_CPU1_SB_CA<6>")
	)
	(segment
		(start 157.136084 -247.806972)
		(end 156.943044 -248.000012)
		(width 0.18288)
		(layer "In11.Cu")
		(net "M_H_CPU1_SB_CA<6>")
	)
	(segment
		(start 128.752854 -245.231412)
		(end 128.743964 -245.226332)
		(width 0.088646)
		(layer "In11.Cu")
		(net "M_H_CPU1_SB_CA<6>")
	)
	(segment
		(start 130.718814 -246.040148)
		(end 130.704082 -246.048784)
		(width 0.088646)
		(layer "In11.Cu")
		(net "M_H_CPU1_SB_CA<6>")
	)
	(segment
		(start 194.568572 -248.594372)
		(end 193.039238 -248.594372)
		(width 0.18288)
		(layer "In11.Cu")
		(net "M_H_CPU1_SB_CA<6>")
	)
	(segment
		(start 179.686458 -247.277382)
		(end 179.30495 -246.895874)
		(width 0.18288)
		(layer "In11.Cu")
		(net "M_H_CPU1_SB_CA<6>")
	)
	(segment
		(start 166.769796 -247.518174)
		(end 166.769796 -246.680736)
		(width 0.18288)
		(layer "In11.Cu")
		(net "M_H_CPU1_SB_CA<6>")
	)
	(segment
		(start 139.761214 -247.725946)
		(end 139.105132 -247.069864)
		(width 0.18288)
		(layer "In11.Cu")
		(net "M_H_CPU1_SB_CA<6>")
	)
	(segment
		(start 183.397906 -247.77319)
		(end 181.833266 -247.77319)
		(width 0.18288)
		(layer "In11.Cu")
		(net "M_H_CPU1_SB_CA<6>")
	)
	(segment
		(start 145.132044 -246.54637)
		(end 143.210788 -246.92864)
		(width 0.18288)
		(layer "In11.Cu")
		(net "M_H_CPU1_SB_CA<6>")
	)
	(segment
		(start 181.337458 -247.277382)
		(end 179.686458 -247.277382)
		(width 0.18288)
		(layer "In11.Cu")
		(net "M_H_CPU1_SB_CA<6>")
	)
	(segment
		(start 178.023012 -246.895874)
		(end 177.877724 -247.041162)
		(width 0.18288)
		(layer "In11.Cu")
		(net "M_H_CPU1_SB_CA<6>")
	)
	(segment
		(start 156.432504 -248.626122)
		(end 156.239464 -248.433082)
		(width 0.18288)
		(layer "In11.Cu")
		(net "M_H_CPU1_SB_CA<6>")
	)
	(segment
		(start 141.285468 -247.725946)
		(end 139.761214 -247.725946)
		(width 0.18288)
		(layer "In11.Cu")
		(net "M_H_CPU1_SB_CA<6>")
	)
	(segment
		(start 174.399956 -247.724676)
		(end 174.233586 -247.891046)
		(width 0.18288)
		(layer "In11.Cu")
		(net "M_H_CPU1_SB_CA<6>")
	)
	(segment
		(start 169.886122 -248.063512)
		(end 168.6814 -248.063512)
		(width 0.18288)
		(layer "In11.Cu")
		(net "M_H_CPU1_SB_CA<6>")
	)
	(segment
		(start 199.284082 -248.07037)
		(end 198.429626 -248.924826)
		(width 0.18288)
		(layer "In11.Cu")
		(net "M_H_CPU1_SB_CA<6>")
	)
	(segment
		(start 166.259256 -246.487696)
		(end 166.066216 -246.680736)
		(width 0.18288)
		(layer "In11.Cu")
		(net "M_H_CPU1_SB_CA<6>")
	)
	(segment
		(start 170.782742 -246.983504)
		(end 170.589702 -246.790464)
		(width 0.18288)
		(layer "In11.Cu")
		(net "M_H_CPU1_SB_CA<6>")
	)
	(segment
		(start 166.769796 -246.680736)
		(end 166.576756 -246.487696)
		(width 0.18288)
		(layer "In11.Cu")
		(net "M_H_CPU1_SB_CA<6>")
	)
	(segment
		(start 155.025344 -248.626122)
		(end 154.832304 -248.433082)
		(width 0.18288)
		(layer "In11.Cu")
		(net "M_H_CPU1_SB_CA<6>")
	)
	(segment
		(start 187.275978 -248.741184)
		(end 187.069476 -248.534682)
		(width 0.18288)
		(layer "In11.Cu")
		(net "M_H_CPU1_SB_CA<6>")
	)
	(segment
		(start 172.742098 -247.891046)
		(end 172.741844 -247.8913)
		(width 0.18288)
		(layer "In11.Cu")
		(net "M_H_CPU1_SB_CA<6>")
	)
	(segment
		(start 137.62355 -247.069864)
		(end 137.355326 -246.91467)
		(width 0.088646)
		(layer "In11.Cu")
		(net "M_H_CPU1_SB_CA<6>")
	)
	(segment
		(start 193.039238 -248.594372)
		(end 192.892426 -248.741184)
		(width 0.18288)
		(layer "In11.Cu")
		(net "M_H_CPU1_SB_CA<6>")
	)
	(segment
		(start 149.778212 -246.54637)
		(end 145.132044 -246.54637)
		(width 0.18288)
		(layer "In11.Cu")
		(net "M_H_CPU1_SB_CA<6>")
	)
	(segment
		(start 155.535884 -248.433082)
		(end 155.342844 -248.626122)
		(width 0.18288)
		(layer "In11.Cu")
		(net "M_H_CPU1_SB_CA<6>")
	)
	(segment
		(start 190.488062 -248.903744)
		(end 189.641988 -248.903744)
		(width 0.18288)
		(layer "In11.Cu")
		(net "M_H_CPU1_SB_CA<6>")
	)
	(segment
		(start 126.864364 -245.226332)
		(end 126.787148 -245.181882)
		(width 0.088646)
		(layer "In11.Cu")
		(net "M_H_CPU1_SB_CA<6>")
	)
	(segment
		(start 154.639264 -247.806972)
		(end 153.096976 -247.806972)
		(width 0.18288)
		(layer "In11.Cu")
		(net "M_H_CPU1_SB_CA<6>")
	)
	(segment
		(start 166.066216 -247.518174)
		(end 165.873176 -247.711214)
		(width 0.18288)
		(layer "In11.Cu")
		(net "M_H_CPU1_SB_CA<6>")
	)
	(segment
		(start 155.728924 -247.806972)
		(end 155.535884 -248.000012)
		(width 0.18288)
		(layer "In11.Cu")
		(net "M_H_CPU1_SB_CA<6>")
	)
	(segment
		(start 174.233586 -247.891046)
		(end 172.742098 -247.891046)
		(width 0.18288)
		(layer "In11.Cu")
		(net "M_H_CPU1_SB_CA<6>")
	)
	(segment
		(start 153.096976 -247.806972)
		(end 152.936448 -247.646444)
		(width 0.18288)
		(layer "In11.Cu")
		(net "M_H_CPU1_SB_CA<6>")
	)
	(segment
		(start 176.20869 -247.041162)
		(end 175.525176 -247.724676)
		(width 0.18288)
		(layer "In11.Cu")
		(net "M_H_CPU1_SB_CA<6>")
	)
	(segment
		(start 152.936448 -247.646444)
		(end 150.878286 -247.646444)
		(width 0.18288)
		(layer "In11.Cu")
		(net "M_H_CPU1_SB_CA<6>")
	)
	(segment
		(start 202.971146 -247.466612)
		(end 202.971146 -247.778016)
		(width 0.18288)
		(layer "In11.Cu")
		(net "M_H_CPU1_SB_CA<6>")
	)
	(segment
		(start 170.975782 -248.063512)
		(end 170.782742 -247.870472)
		(width 0.18288)
		(layer "In11.Cu")
		(net "M_H_CPU1_SB_CA<6>")
	)
	(segment
		(start 189.641988 -248.903744)
		(end 189.479428 -248.741184)
		(width 0.18288)
		(layer "In11.Cu")
		(net "M_H_CPU1_SB_CA<6>")
	)
	(segment
		(start 166.066216 -246.680736)
		(end 166.066216 -247.518174)
		(width 0.18288)
		(layer "In11.Cu")
		(net "M_H_CPU1_SB_CA<6>")
	)
	(segment
		(start 168.329102 -247.711214)
		(end 166.962836 -247.711214)
		(width 0.18288)
		(layer "In11.Cu")
		(net "M_H_CPU1_SB_CA<6>")
	)
	(segment
		(start 154.832304 -248.000012)
		(end 154.639264 -247.806972)
		(width 0.18288)
		(layer "In11.Cu")
		(net "M_H_CPU1_SB_CA<6>")
	)
	(segment
		(start 170.782742 -247.870472)
		(end 170.782742 -246.983504)
		(width 0.18288)
		(layer "In11.Cu")
		(net "M_H_CPU1_SB_CA<6>")
	)
	(segment
		(start 150.878286 -247.646444)
		(end 149.778212 -246.54637)
		(width 0.18288)
		(layer "In11.Cu")
		(net "M_H_CPU1_SB_CA<6>")
	)
	(segment
		(start 127.814324 -245.232428)
		(end 127.80391 -245.226332)
		(width 0.088646)
		(layer "In11.Cu")
		(net "M_H_CPU1_SB_CA<6>")
	)
	(segment
		(start 202.412854 -248.07037)
		(end 199.284082 -248.07037)
		(width 0.18288)
		(layer "In11.Cu")
		(net "M_H_CPU1_SB_CA<6>")
	)
	(segment
		(start 164.832538 -247.711214)
		(end 164.482526 -248.061226)
		(width 0.18288)
		(layer "In11.Cu")
		(net "M_H_CPU1_SB_CA<6>")
	)
	(segment
		(start 156.239464 -248.433082)
		(end 156.239464 -248.000012)
		(width 0.18288)
		(layer "In11.Cu")
		(net "M_H_CPU1_SB_CA<6>")
	)
	(segment
		(start 129.779014 -246.040148)
		(end 129.7686 -246.046244)
		(width 0.088646)
		(layer "In11.Cu")
		(net "M_H_CPU1_SB_CA<6>")
	)
	(segment
		(start 155.535884 -248.000012)
		(end 155.535884 -248.433082)
		(width 0.18288)
		(layer "In11.Cu")
		(net "M_H_CPU1_SB_CA<6>")
	)
	(segment
		(start 175.525176 -247.724676)
		(end 174.399956 -247.724676)
		(width 0.18288)
		(layer "In11.Cu")
		(net "M_H_CPU1_SB_CA<6>")
	)
	(segment
		(start 171.948602 -247.8913)
		(end 171.77639 -248.063512)
		(width 0.18288)
		(layer "In11.Cu")
		(net "M_H_CPU1_SB_CA<6>")
	)
	(segment
		(start 156.239464 -248.000012)
		(end 156.046424 -247.806972)
		(width 0.18288)
		(layer "In11.Cu")
		(net "M_H_CPU1_SB_CA<6>")
	)
	(segment
		(start 190.650622 -248.741184)
		(end 190.488062 -248.903744)
		(width 0.18288)
		(layer "In11.Cu")
		(net "M_H_CPU1_SB_CA<6>")
	)
	(segment
		(start 133.538468 -246.040148)
		(end 133.528054 -246.046244)
		(width 0.088646)
		(layer "In11.Cu")
		(net "M_H_CPU1_SB_CA<6>")
	)
	(segment
		(start 198.429626 -248.924826)
		(end 194.899026 -248.924826)
		(width 0.18288)
		(layer "In11.Cu")
		(net "M_H_CPU1_SB_CA<6>")
	)
	(segment
		(start 165.873176 -247.711214)
		(end 164.832538 -247.711214)
		(width 0.18288)
		(layer "In11.Cu")
		(net "M_H_CPU1_SB_CA<6>")
	)
	(segment
		(start 161.256472 -247.806972)
		(end 157.136084 -247.806972)
		(width 0.18288)
		(layer "In11.Cu")
		(net "M_H_CPU1_SB_CA<6>")
	)
	(segment
		(start 156.750004 -248.626122)
		(end 156.432504 -248.626122)
		(width 0.18288)
		(layer "In11.Cu")
		(net "M_H_CPU1_SB_CA<6>")
	)
	(segment
		(start 154.832304 -248.433082)
		(end 154.832304 -248.000012)
		(width 0.18288)
		(layer "In11.Cu")
		(net "M_H_CPU1_SB_CA<6>")
	)
	(segment
		(start 170.589702 -246.790464)
		(end 170.272202 -246.790464)
		(width 0.18288)
		(layer "In11.Cu")
		(net "M_H_CPU1_SB_CA<6>")
	)
	(segment
		(start 143.210788 -246.92864)
		(end 141.285468 -247.725946)
		(width 0.18288)
		(layer "In11.Cu")
		(net "M_H_CPU1_SB_CA<6>")
	)
	(segment
		(start 183.709056 -248.08434)
		(end 183.397906 -247.77319)
		(width 0.18288)
		(layer "In11.Cu")
		(net "M_H_CPU1_SB_CA<6>")
	)
	(segment
		(start 166.962836 -247.711214)
		(end 166.769796 -247.518174)
		(width 0.18288)
		(layer "In11.Cu")
		(net "M_H_CPU1_SB_CA<6>")
	)
	(segment
		(start 127.429514 -245.226332)
		(end 127.4191 -245.232428)
		(width 0.088646)
		(layer "In11.Cu")
		(net "M_H_CPU1_SB_CA<6>")
	)
	(segment
		(start 194.899026 -248.924826)
		(end 194.568572 -248.594372)
		(width 0.18288)
		(layer "In11.Cu")
		(net "M_H_CPU1_SB_CA<6>")
	)
	(segment
		(start 161.510726 -248.061226)
		(end 161.256472 -247.806972)
		(width 0.18288)
		(layer "In11.Cu")
		(net "M_H_CPU1_SB_CA<6>")
	)
	(segment
		(start 156.943044 -248.000012)
		(end 156.943044 -248.433082)
		(width 0.18288)
		(layer "In11.Cu")
		(net "M_H_CPU1_SB_CA<6>")
	)
	(segment
		(start 184.870852 -248.08434)
		(end 183.709056 -248.08434)
		(width 0.18288)
		(layer "In11.Cu")
		(net "M_H_CPU1_SB_CA<6>")
	)
	(segment
		(start 135.979916 -246.374412)
		(end 135.979916 -246.364506)
		(width 0.088646)
		(layer "In11.Cu")
		(net "M_H_CPU1_SB_CA<6>")
	)
	(segment
		(start 155.342844 -248.626122)
		(end 155.025344 -248.626122)
		(width 0.18288)
		(layer "In11.Cu")
		(net "M_H_CPU1_SB_CA<6>")
	)
	(segment
		(start 170.079162 -246.983504)
		(end 170.079162 -247.870472)
		(width 0.18288)
		(layer "In11.Cu")
		(net "M_H_CPU1_SB_CA<6>")
	)
	(segment
		(start 179.30495 -246.895874)
		(end 178.023012 -246.895874)
		(width 0.18288)
		(layer "In11.Cu")
		(net "M_H_CPU1_SB_CA<6>")
	)
	(segment
		(start 156.943044 -248.433082)
		(end 156.750004 -248.626122)
		(width 0.18288)
		(layer "In11.Cu")
		(net "M_H_CPU1_SB_CA<6>")
	)
	(segment
		(start 187.069476 -248.534682)
		(end 186.186318 -248.534682)
		(width 0.18288)
		(layer "In11.Cu")
		(net "M_H_CPU1_SB_CA<6>")
	)
	(segment
		(start 171.77639 -248.063512)
		(end 170.975782 -248.063512)
		(width 0.18288)
		(layer "In11.Cu")
		(net "M_H_CPU1_SB_CA<6>")
	)
	(segment
		(start 135.801354 -246.045228)
		(end 135.792464 -246.040148)
		(width 0.088646)
		(layer "In11.Cu")
		(net "M_H_CPU1_SB_CA<6>")
	)
	(segment
		(start 185.542682 -247.891046)
		(end 185.064146 -247.891046)
		(width 0.18288)
		(layer "In11.Cu")
		(net "M_H_CPU1_SB_CA<6>")
	)
	(segment
		(start 168.6814 -248.063512)
		(end 168.329102 -247.711214)
		(width 0.18288)
		(layer "In11.Cu")
		(net "M_H_CPU1_SB_CA<6>")
	)
	(segment
		(start 185.064146 -247.891046)
		(end 184.870852 -248.08434)
		(width 0.18288)
		(layer "In11.Cu")
		(net "M_H_CPU1_SB_CA<6>")
	)
	(segment
		(start 170.272202 -246.790464)
		(end 170.079162 -246.983504)
		(width 0.18288)
		(layer "In11.Cu")
		(net "M_H_CPU1_SB_CA<6>")
	)
	(segment
		(start 189.479428 -248.741184)
		(end 187.275978 -248.741184)
		(width 0.18288)
		(layer "In11.Cu")
		(net "M_H_CPU1_SB_CA<6>")
	)
	(segment
		(start 170.079162 -247.870472)
		(end 169.886122 -248.063512)
		(width 0.18288)
		(layer "In11.Cu")
		(net "M_H_CPU1_SB_CA<6>")
	)
	(segment
		(start 172.741844 -247.8913)
		(end 171.948602 -247.8913)
		(width 0.18288)
		(layer "In11.Cu")
		(net "M_H_CPU1_SB_CA<6>")
	)
	(segment
		(start 166.576756 -246.487696)
		(end 166.259256 -246.487696)
		(width 0.18288)
		(layer "In11.Cu")
		(net "M_H_CPU1_SB_CA<6>")
	)
	(segment
		(start 186.186318 -248.534682)
		(end 185.542682 -247.891046)
		(width 0.18288)
		(layer "In11.Cu")
		(net "M_H_CPU1_SB_CA<6>")
	)
	(arc
		(start 135.792464 -246.040148)
		(mid 135.605266 -245.990005)
		(end 135.418068 -246.040148)
		(width 0.088646)
		(layer "In11.Cu")
		(net "M_H_CPU1_SB_CA<6>")
	)
	(arc
		(start 131.643882 -246.048784)
		(mid 131.367407 -246.116104)
		(end 131.09321 -246.040148)
		(width 0.088646)
		(layer "In11.Cu")
		(net "M_H_CPU1_SB_CA<6>")
	)
	(arc
		(start 135.418068 -246.040148)
		(mid 135.135366 -246.115924)
		(end 134.852664 -246.040148)
		(width 0.088646)
		(layer "In11.Cu")
		(net "M_H_CPU1_SB_CA<6>")
	)
	(arc
		(start 133.528054 -246.046244)
		(mid 133.249622 -246.11609)
		(end 132.97281 -246.040148)
		(width 0.088646)
		(layer "In11.Cu")
		(net "M_H_CPU1_SB_CA<6>")
	)
	(arc
		(start 135.979916 -246.364506)
		(mid 135.932237 -246.181606)
		(end 135.801354 -246.045228)
		(width 0.088646)
		(layer "In11.Cu")
		(net "M_H_CPU1_SB_CA<6>")
	)
	(arc
		(start 128.743964 -245.226332)
		(mid 128.556766 -245.176189)
		(end 128.369568 -245.226332)
		(width 0.088646)
		(layer "In11.Cu")
		(net "M_H_CPU1_SB_CA<6>")
	)
	(arc
		(start 131.09321 -246.040148)
		(mid 130.906012 -245.990005)
		(end 130.718814 -246.040148)
		(width 0.088646)
		(layer "In11.Cu")
		(net "M_H_CPU1_SB_CA<6>")
	)
	(arc
		(start 127.4191 -245.232428)
		(mid 127.140922 -245.30212)
		(end 126.864364 -245.226332)
		(width 0.088646)
		(layer "In11.Cu")
		(net "M_H_CPU1_SB_CA<6>")
	)
	(arc
		(start 137.355326 -246.91467)
		(mid 137.276527 -246.889916)
		(end 137.202164 -246.853964)
		(width 0.088646)
		(layer "In11.Cu")
		(net "M_H_CPU1_SB_CA<6>")
	)
	(arc
		(start 137.202164 -246.853964)
		(mid 137.014966 -246.803821)
		(end 136.827768 -246.853964)
		(width 0.088646)
		(layer "In11.Cu")
		(net "M_H_CPU1_SB_CA<6>")
	)
	(arc
		(start 130.704082 -246.048784)
		(mid 130.427607 -246.116104)
		(end 130.15341 -246.040148)
		(width 0.088646)
		(layer "In11.Cu")
		(net "M_H_CPU1_SB_CA<6>")
	)
	(arc
		(start 132.598414 -246.040148)
		(mid 132.315712 -246.115924)
		(end 132.03301 -246.040148)
		(width 0.088646)
		(layer "In11.Cu")
		(net "M_H_CPU1_SB_CA<6>")
	)
	(arc
		(start 132.97281 -246.040148)
		(mid 132.785612 -245.990005)
		(end 132.598414 -246.040148)
		(width 0.088646)
		(layer "In11.Cu")
		(net "M_H_CPU1_SB_CA<6>")
	)
	(arc
		(start 128.931416 -245.55069)
		(mid 128.883737 -245.36779)
		(end 128.752854 -245.231412)
		(width 0.088646)
		(layer "In11.Cu")
		(net "M_H_CPU1_SB_CA<6>")
	)
	(arc
		(start 132.03301 -246.040148)
		(mid 131.845812 -245.990005)
		(end 131.658614 -246.040148)
		(width 0.088646)
		(layer "In11.Cu")
		(net "M_H_CPU1_SB_CA<6>")
	)
	(arc
		(start 128.369568 -245.226332)
		(mid 128.092755 -245.302168)
		(end 127.814324 -245.232428)
		(width 0.088646)
		(layer "In11.Cu")
		(net "M_H_CPU1_SB_CA<6>")
	)
	(arc
		(start 136.262364 -246.853964)
		(mid 136.058029 -246.651359)
		(end 135.979916 -246.374412)
		(width 0.088646)
		(layer "In11.Cu")
		(net "M_H_CPU1_SB_CA<6>")
	)
	(arc
		(start 129.7686 -246.046244)
		(mid 129.212923 -246.039692)
		(end 128.931416 -245.560596)
		(width 0.088646)
		(layer "In11.Cu")
		(net "M_H_CPU1_SB_CA<6>")
	)
	(arc
		(start 126.787148 -245.181882)
		(mid 126.48248 -244.978272)
		(end 126.207012 -244.73662)
		(width 0.088646)
		(layer "In11.Cu")
		(net "M_H_CPU1_SB_CA<6>")
	)
	(arc
		(start 134.852664 -246.040148)
		(mid 134.665466 -245.990005)
		(end 134.478268 -246.040148)
		(width 0.088646)
		(layer "In11.Cu")
		(net "M_H_CPU1_SB_CA<6>")
	)
	(arc
		(start 127.80391 -245.226332)
		(mid 127.616712 -245.176189)
		(end 127.429514 -245.226332)
		(width 0.088646)
		(layer "In11.Cu")
		(net "M_H_CPU1_SB_CA<6>")
	)
	(arc
		(start 134.478268 -246.040148)
		(mid 134.195566 -246.115924)
		(end 133.912864 -246.040148)
		(width 0.088646)
		(layer "In11.Cu")
		(net "M_H_CPU1_SB_CA<6>")
	)
	(arc
		(start 136.827768 -246.853964)
		(mid 136.545066 -246.92974)
		(end 136.262364 -246.853964)
		(width 0.088646)
		(layer "In11.Cu")
		(net "M_H_CPU1_SB_CA<6>")
	)
	(arc
		(start 130.15341 -246.040148)
		(mid 129.966212 -245.990005)
		(end 129.779014 -246.040148)
		(width 0.088646)
		(layer "In11.Cu")
		(net "M_H_CPU1_SB_CA<6>")
	)
	(arc
		(start 133.912864 -246.040148)
		(mid 133.725666 -245.990005)
		(end 133.538468 -246.040148)
		(width 0.088646)
		(layer "In11.Cu")
		(net "M_H_CPU1_SB_CA<6>")
	)
	(segment
		(start 128.556512 -246.08663)
		(end 128.556766 -246.086376)
		(width 0.20066)
		(layer "F.Cu")
		(net "M_H_CPU1_SB_CA<5>")
	)
	(segment
		(start 212.904324 -248.749058)
		(end 213.769194 -247.884188)
		(width 0.20066)
		(layer "F.Cu")
		(net "M_H_CPU1_SB_CA<5>")
	)
	(segment
		(start 214.605362 -248.31675)
		(end 215.719914 -248.31675)
		(width 0.20066)
		(layer "F.Cu")
		(net "M_H_CPU1_SB_CA<5>")
	)
	(segment
		(start 212.630258 -248.749058)
		(end 212.904324 -248.749058)
		(width 0.20066)
		(layer "F.Cu")
		(net "M_H_CPU1_SB_CA<5>")
	)
	(segment
		(start 210.247484 -248.75236)
		(end 210.598258 -248.75236)
		(width 0.20066)
		(layer "F.Cu")
		(net "M_H_CPU1_SB_CA<5>")
	)
	(segment
		(start 214.1728 -247.884188)
		(end 214.605362 -248.31675)
		(width 0.20066)
		(layer "F.Cu")
		(net "M_H_CPU1_SB_CA<5>")
	)
	(segment
		(start 210.598258 -248.75236)
		(end 210.603084 -248.75236)
		(width 0.101854)
		(layer "F.Cu")
		(net "M_H_CPU1_SB_CA<5>")
	)
	(segment
		(start 213.769194 -247.884188)
		(end 214.1728 -247.884188)
		(width 0.20066)
		(layer "F.Cu")
		(net "M_H_CPU1_SB_CA<5>")
	)
	(segment
		(start 209.811874 -248.31675)
		(end 210.247484 -248.75236)
		(width 0.20066)
		(layer "F.Cu")
		(net "M_H_CPU1_SB_CA<5>")
	)
	(segment
		(start 208.176114 -248.31675)
		(end 209.811874 -248.31675)
		(width 0.20066)
		(layer "F.Cu")
		(net "M_H_CPU1_SB_CA<5>")
	)
	(segment
		(start 210.613752 -248.741692)
		(end 212.622892 -248.741692)
		(width 0.1016)
		(layer "F.Cu")
		(net "M_H_CPU1_SB_CA<5>")
	)
	(segment
		(start 212.622892 -248.741692)
		(end 212.630258 -248.749058)
		(width 0.1016)
		(layer "F.Cu")
		(net "M_H_CPU1_SB_CA<5>")
	)
	(segment
		(start 128.556766 -246.086376)
		(end 128.556766 -245.55069)
		(width 0.20066)
		(layer "F.Cu")
		(net "M_H_CPU1_SB_CA<5>")
	)
	(segment
		(start 207.071214 -248.31675)
		(end 208.176114 -248.31675)
		(width 0.20066)
		(layer "F.Cu")
		(net "M_H_CPU1_SB_CA<5>")
	)
	(segment
		(start 210.603084 -248.75236)
		(end 210.613752 -248.741692)
		(width 0.1016)
		(layer "F.Cu")
		(net "M_H_CPU1_SB_CA<5>")
	)
	(segment
		(start 168.107614 -248.980706)
		(end 166.90975 -248.980706)
		(width 0.18288)
		(layer "In11.Cu")
		(net "M_H_CPU1_SB_CA<5>")
	)
	(segment
		(start 189.101222 -249.591068)
		(end 186.968384 -249.591068)
		(width 0.18288)
		(layer "In11.Cu")
		(net "M_H_CPU1_SB_CA<5>")
	)
	(segment
		(start 183.466486 -248.724166)
		(end 183.31434 -248.876312)
		(width 0.18288)
		(layer "In11.Cu")
		(net "M_H_CPU1_SB_CA<5>")
	)
	(segment
		(start 170.766486 -248.772426)
		(end 170.766486 -249.058684)
		(width 0.18288)
		(layer "In11.Cu")
		(net "M_H_CPU1_SB_CA<5>")
	)
	(segment
		(start 198.668386 -249.442986)
		(end 195.001896 -249.442986)
		(width 0.18288)
		(layer "In11.Cu")
		(net "M_H_CPU1_SB_CA<5>")
	)
	(segment
		(start 183.31434 -248.876312)
		(end 182.155084 -248.876312)
		(width 0.18288)
		(layer "In11.Cu")
		(net "M_H_CPU1_SB_CA<5>")
	)
	(segment
		(start 189.27572 -249.41657)
		(end 189.101222 -249.591068)
		(width 0.18288)
		(layer "In11.Cu")
		(net "M_H_CPU1_SB_CA<5>")
	)
	(segment
		(start 177.506884 -248.741184)
		(end 176.011332 -248.741184)
		(width 0.18288)
		(layer "In11.Cu")
		(net "M_H_CPU1_SB_CA<5>")
	)
	(segment
		(start 207.071214 -248.31675)
		(end 206.513684 -248.31675)
		(width 0.18288)
		(layer "In11.Cu")
		(net "M_H_CPU1_SB_CA<5>")
	)
	(segment
		(start 169.869866 -248.579386)
		(end 168.508934 -248.579386)
		(width 0.18288)
		(layer "In11.Cu")
		(net "M_H_CPU1_SB_CA<5>")
	)
	(segment
		(start 129.779014 -246.688864)
		(end 129.7686 -246.682768)
		(width 0.088646)
		(layer "In11.Cu")
		(net "M_H_CPU1_SB_CA<5>")
	)
	(segment
		(start 177.892964 -247.700292)
		(end 177.699924 -247.893332)
		(width 0.18288)
		(layer "In11.Cu")
		(net "M_H_CPU1_SB_CA<5>")
	)
	(segment
		(start 166.20617 -248.101612)
		(end 166.01313 -248.294652)
		(width 0.18288)
		(layer "In11.Cu")
		(net "M_H_CPU1_SB_CA<5>")
	)
	(segment
		(start 166.71671 -248.787666)
		(end 166.71671 -248.294652)
		(width 0.18288)
		(layer "In11.Cu")
		(net "M_H_CPU1_SB_CA<5>")
	)
	(segment
		(start 205.920594 -248.90984)
		(end 203.578968 -248.90984)
		(width 0.18288)
		(layer "In11.Cu")
		(net "M_H_CPU1_SB_CA<5>")
	)
	(segment
		(start 176.011332 -248.741184)
		(end 175.840644 -248.911872)
		(width 0.18288)
		(layer "In11.Cu")
		(net "M_H_CPU1_SB_CA<5>")
	)
	(segment
		(start 168.508934 -248.579386)
		(end 168.107614 -248.980706)
		(width 0.18288)
		(layer "In11.Cu")
		(net "M_H_CPU1_SB_CA<5>")
	)
	(segment
		(start 203.578968 -248.90984)
		(end 203.412852 -248.743724)
		(width 0.18288)
		(layer "In11.Cu")
		(net "M_H_CPU1_SB_CA<5>")
	)
	(segment
		(start 181.111398 -247.832626)
		(end 179.92979 -247.832626)
		(width 0.18288)
		(layer "In11.Cu")
		(net "M_H_CPU1_SB_CA<5>")
	)
	(segment
		(start 143.443452 -247.244616)
		(end 141.430756 -248.078244)
		(width 0.18288)
		(layer "In11.Cu")
		(net "M_H_CPU1_SB_CA<5>")
	)
	(segment
		(start 149.387814 -246.89689)
		(end 145.19148 -246.89689)
		(width 0.18288)
		(layer "In11.Cu")
		(net "M_H_CPU1_SB_CA<5>")
	)
	(segment
		(start 194.66814 -249.776742)
		(end 193.134488 -249.776742)
		(width 0.18288)
		(layer "In11.Cu")
		(net "M_H_CPU1_SB_CA<5>")
	)
	(segment
		(start 177.699924 -248.548144)
		(end 177.506884 -248.741184)
		(width 0.18288)
		(layer "In11.Cu")
		(net "M_H_CPU1_SB_CA<5>")
	)
	(segment
		(start 185.253122 -248.724166)
		(end 183.466486 -248.724166)
		(width 0.18288)
		(layer "In11.Cu")
		(net "M_H_CPU1_SB_CA<5>")
	)
	(segment
		(start 186.336432 -249.807476)
		(end 185.253122 -248.724166)
		(width 0.18288)
		(layer "In11.Cu")
		(net "M_H_CPU1_SB_CA<5>")
	)
	(segment
		(start 193.134488 -249.776742)
		(end 192.948814 -249.591068)
		(width 0.18288)
		(layer "In11.Cu")
		(net "M_H_CPU1_SB_CA<5>")
	)
	(segment
		(start 171.87672 -248.579386)
		(end 170.959526 -248.579386)
		(width 0.18288)
		(layer "In11.Cu")
		(net "M_H_CPU1_SB_CA<5>")
	)
	(segment
		(start 154.482546 -249.142504)
		(end 153.774394 -248.434352)
		(width 0.18288)
		(layer "In11.Cu")
		(net "M_H_CPU1_SB_CA<5>")
	)
	(segment
		(start 190.724536 -249.41657)
		(end 189.27572 -249.41657)
		(width 0.18288)
		(layer "In11.Cu")
		(net "M_H_CPU1_SB_CA<5>")
	)
	(segment
		(start 152.948132 -248.31167)
		(end 150.802594 -248.31167)
		(width 0.18288)
		(layer "In11.Cu")
		(net "M_H_CPU1_SB_CA<5>")
	)
	(segment
		(start 202.290426 -248.743724)
		(end 202.142598 -248.595896)
		(width 0.18288)
		(layer "In11.Cu")
		(net "M_H_CPU1_SB_CA<5>")
	)
	(segment
		(start 161.602928 -248.58345)
		(end 161.43224 -248.754138)
		(width 0.18288)
		(layer "In11.Cu")
		(net "M_H_CPU1_SB_CA<5>")
	)
	(segment
		(start 186.751976 -249.807476)
		(end 186.336432 -249.807476)
		(width 0.18288)
		(layer "In11.Cu")
		(net "M_H_CPU1_SB_CA<5>")
	)
	(segment
		(start 192.948814 -249.591068)
		(end 190.899034 -249.591068)
		(width 0.18288)
		(layer "In11.Cu")
		(net "M_H_CPU1_SB_CA<5>")
	)
	(segment
		(start 178.403504 -247.893332)
		(end 178.210464 -247.700292)
		(width 0.18288)
		(layer "In11.Cu")
		(net "M_H_CPU1_SB_CA<5>")
	)
	(segment
		(start 166.90975 -248.980706)
		(end 166.71671 -248.787666)
		(width 0.18288)
		(layer "In11.Cu")
		(net "M_H_CPU1_SB_CA<5>")
	)
	(segment
		(start 138.1125 -247.58269)
		(end 137.898378 -247.58269)
		(width 0.088646)
		(layer "In11.Cu")
		(net "M_H_CPU1_SB_CA<5>")
	)
	(segment
		(start 135.700516 -247.178322)
		(end 135.700516 -247.168416)
		(width 0.088646)
		(layer "In11.Cu")
		(net "M_H_CPU1_SB_CA<5>")
	)
	(segment
		(start 200.998328 -248.595896)
		(end 199.805798 -249.788426)
		(width 0.18288)
		(layer "In11.Cu")
		(net "M_H_CPU1_SB_CA<5>")
	)
	(segment
		(start 170.062906 -248.772426)
		(end 169.869866 -248.579386)
		(width 0.18288)
		(layer "In11.Cu")
		(net "M_H_CPU1_SB_CA<5>")
	)
	(segment
		(start 206.513684 -248.31675)
		(end 205.920594 -248.90984)
		(width 0.18288)
		(layer "In11.Cu")
		(net "M_H_CPU1_SB_CA<5>")
	)
	(segment
		(start 166.01313 -248.787666)
		(end 165.82009 -248.980706)
		(width 0.18288)
		(layer "In11.Cu")
		(net "M_H_CPU1_SB_CA<5>")
	)
	(segment
		(start 173.947582 -248.741184)
		(end 172.038518 -248.741184)
		(width 0.18288)
		(layer "In11.Cu")
		(net "M_H_CPU1_SB_CA<5>")
	)
	(segment
		(start 157.05709 -249.142504)
		(end 154.482546 -249.142504)
		(width 0.18288)
		(layer "In11.Cu")
		(net "M_H_CPU1_SB_CA<5>")
	)
	(segment
		(start 177.699924 -247.893332)
		(end 177.699924 -248.548144)
		(width 0.18288)
		(layer "In11.Cu")
		(net "M_H_CPU1_SB_CA<5>")
	)
	(segment
		(start 153.774394 -248.434352)
		(end 153.070814 -248.434352)
		(width 0.18288)
		(layer "In11.Cu")
		(net "M_H_CPU1_SB_CA<5>")
	)
	(segment
		(start 170.959526 -248.579386)
		(end 170.766486 -248.772426)
		(width 0.18288)
		(layer "In11.Cu")
		(net "M_H_CPU1_SB_CA<5>")
	)
	(segment
		(start 145.19148 -246.89689)
		(end 143.443452 -247.244616)
		(width 0.18288)
		(layer "In11.Cu")
		(net "M_H_CPU1_SB_CA<5>")
	)
	(segment
		(start 170.573446 -249.251724)
		(end 170.255946 -249.251724)
		(width 0.18288)
		(layer "In11.Cu")
		(net "M_H_CPU1_SB_CA<5>")
	)
	(segment
		(start 132.983224 -246.682768)
		(end 132.97281 -246.688864)
		(width 0.088646)
		(layer "In11.Cu")
		(net "M_H_CPU1_SB_CA<5>")
	)
	(segment
		(start 157.445456 -248.754138)
		(end 157.05709 -249.142504)
		(width 0.18288)
		(layer "In11.Cu")
		(net "M_H_CPU1_SB_CA<5>")
	)
	(segment
		(start 128.556766 -245.961154)
		(end 128.556766 -245.55069)
		(width 0.088646)
		(layer "In11.Cu")
		(net "M_H_CPU1_SB_CA<5>")
	)
	(segment
		(start 137.898378 -247.58269)
		(end 137.86104 -247.545352)
		(width 0.088646)
		(layer "In11.Cu")
		(net "M_H_CPU1_SB_CA<5>")
	)
	(segment
		(start 199.013826 -249.788426)
		(end 198.668386 -249.442986)
		(width 0.18288)
		(layer "In11.Cu")
		(net "M_H_CPU1_SB_CA<5>")
	)
	(segment
		(start 128.839468 -246.688864)
		(end 128.830578 -246.683784)
		(width 0.088646)
		(layer "In11.Cu")
		(net "M_H_CPU1_SB_CA<5>")
	)
	(segment
		(start 141.430756 -248.078244)
		(end 139.354052 -248.078244)
		(width 0.18288)
		(layer "In11.Cu")
		(net "M_H_CPU1_SB_CA<5>")
	)
	(segment
		(start 166.52367 -248.101612)
		(end 166.20617 -248.101612)
		(width 0.18288)
		(layer "In11.Cu")
		(net "M_H_CPU1_SB_CA<5>")
	)
	(segment
		(start 165.82009 -248.980706)
		(end 164.796978 -248.980706)
		(width 0.18288)
		(layer "In11.Cu")
		(net "M_H_CPU1_SB_CA<5>")
	)
	(segment
		(start 203.412852 -248.743724)
		(end 202.290426 -248.743724)
		(width 0.18288)
		(layer "In11.Cu")
		(net "M_H_CPU1_SB_CA<5>")
	)
	(segment
		(start 182.155084 -248.876312)
		(end 181.111398 -247.832626)
		(width 0.18288)
		(layer "In11.Cu")
		(net "M_H_CPU1_SB_CA<5>")
	)
	(segment
		(start 190.899034 -249.591068)
		(end 190.724536 -249.41657)
		(width 0.18288)
		(layer "In11.Cu")
		(net "M_H_CPU1_SB_CA<5>")
	)
	(segment
		(start 153.070814 -248.434352)
		(end 152.948132 -248.31167)
		(width 0.18288)
		(layer "In11.Cu")
		(net "M_H_CPU1_SB_CA<5>")
	)
	(segment
		(start 170.062906 -249.058684)
		(end 170.062906 -248.772426)
		(width 0.18288)
		(layer "In11.Cu")
		(net "M_H_CPU1_SB_CA<5>")
	)
	(segment
		(start 202.142598 -248.595896)
		(end 200.998328 -248.595896)
		(width 0.18288)
		(layer "In11.Cu")
		(net "M_H_CPU1_SB_CA<5>")
	)
	(segment
		(start 166.01313 -248.294652)
		(end 166.01313 -248.787666)
		(width 0.18288)
		(layer "In11.Cu")
		(net "M_H_CPU1_SB_CA<5>")
	)
	(segment
		(start 174.11827 -248.911872)
		(end 173.947582 -248.741184)
		(width 0.18288)
		(layer "In11.Cu")
		(net "M_H_CPU1_SB_CA<5>")
	)
	(segment
		(start 170.766486 -249.058684)
		(end 170.573446 -249.251724)
		(width 0.18288)
		(layer "In11.Cu")
		(net "M_H_CPU1_SB_CA<5>")
	)
	(segment
		(start 139.354052 -248.078244)
		(end 138.858498 -247.58269)
		(width 0.18288)
		(layer "In11.Cu")
		(net "M_H_CPU1_SB_CA<5>")
	)
	(segment
		(start 179.021232 -248.741184)
		(end 178.596544 -248.741184)
		(width 0.18288)
		(layer "In11.Cu")
		(net "M_H_CPU1_SB_CA<5>")
	)
	(segment
		(start 178.210464 -247.700292)
		(end 177.892964 -247.700292)
		(width 0.18288)
		(layer "In11.Cu")
		(net "M_H_CPU1_SB_CA<5>")
	)
	(segment
		(start 172.038518 -248.741184)
		(end 171.87672 -248.579386)
		(width 0.18288)
		(layer "In11.Cu")
		(net "M_H_CPU1_SB_CA<5>")
	)
	(segment
		(start 166.71671 -248.294652)
		(end 166.52367 -248.101612)
		(width 0.18288)
		(layer "In11.Cu")
		(net "M_H_CPU1_SB_CA<5>")
	)
	(segment
		(start 186.968384 -249.591068)
		(end 186.751976 -249.807476)
		(width 0.18288)
		(layer "In11.Cu")
		(net "M_H_CPU1_SB_CA<5>")
	)
	(segment
		(start 175.840644 -248.911872)
		(end 174.11827 -248.911872)
		(width 0.18288)
		(layer "In11.Cu")
		(net "M_H_CPU1_SB_CA<5>")
	)
	(segment
		(start 150.802594 -248.31167)
		(end 149.387814 -246.89689)
		(width 0.18288)
		(layer "In11.Cu")
		(net "M_H_CPU1_SB_CA<5>")
	)
	(segment
		(start 164.399722 -248.58345)
		(end 161.602928 -248.58345)
		(width 0.18288)
		(layer "In11.Cu")
		(net "M_H_CPU1_SB_CA<5>")
	)
	(segment
		(start 179.92979 -247.832626)
		(end 179.021232 -248.741184)
		(width 0.18288)
		(layer "In11.Cu")
		(net "M_H_CPU1_SB_CA<5>")
	)
	(segment
		(start 130.718814 -246.688864)
		(end 130.704082 -246.680228)
		(width 0.088646)
		(layer "In11.Cu")
		(net "M_H_CPU1_SB_CA<5>")
	)
	(segment
		(start 199.805798 -249.788426)
		(end 199.013826 -249.788426)
		(width 0.18288)
		(layer "In11.Cu")
		(net "M_H_CPU1_SB_CA<5>")
	)
	(segment
		(start 132.598414 -246.688864)
		(end 132.583682 -246.680228)
		(width 0.088646)
		(layer "In11.Cu")
		(net "M_H_CPU1_SB_CA<5>")
	)
	(segment
		(start 195.001896 -249.442986)
		(end 194.66814 -249.776742)
		(width 0.18288)
		(layer "In11.Cu")
		(net "M_H_CPU1_SB_CA<5>")
	)
	(segment
		(start 135.887968 -247.50268)
		(end 135.879078 -247.4976)
		(width 0.088646)
		(layer "In11.Cu")
		(net "M_H_CPU1_SB_CA<5>")
	)
	(segment
		(start 178.596544 -248.741184)
		(end 178.403504 -248.548144)
		(width 0.18288)
		(layer "In11.Cu")
		(net "M_H_CPU1_SB_CA<5>")
	)
	(segment
		(start 178.403504 -248.548144)
		(end 178.403504 -247.893332)
		(width 0.18288)
		(layer "In11.Cu")
		(net "M_H_CPU1_SB_CA<5>")
	)
	(segment
		(start 164.796978 -248.980706)
		(end 164.399722 -248.58345)
		(width 0.18288)
		(layer "In11.Cu")
		(net "M_H_CPU1_SB_CA<5>")
	)
	(segment
		(start 161.43224 -248.754138)
		(end 157.445456 -248.754138)
		(width 0.18288)
		(layer "In11.Cu")
		(net "M_H_CPU1_SB_CA<5>")
	)
	(segment
		(start 138.858498 -247.58269)
		(end 138.1125 -247.58269)
		(width 0.18288)
		(layer "In11.Cu")
		(net "M_H_CPU1_SB_CA<5>")
	)
	(segment
		(start 170.255946 -249.251724)
		(end 170.062906 -249.058684)
		(width 0.18288)
		(layer "In11.Cu")
		(net "M_H_CPU1_SB_CA<5>")
	)
	(arc
		(start 133.912864 -246.688864)
		(mid 133.725666 -246.739007)
		(end 133.538468 -246.688864)
		(width 0.088646)
		(layer "In11.Cu")
		(net "M_H_CPU1_SB_CA<5>")
	)
	(arc
		(start 128.652016 -246.364506)
		(mid 128.636904 -246.234658)
		(end 128.592326 -246.111776)
		(width 0.088646)
		(layer "In11.Cu")
		(net "M_H_CPU1_SB_CA<5>")
	)
	(arc
		(start 135.700516 -247.168416)
		(mid 135.622405 -246.891467)
		(end 135.418068 -246.688864)
		(width 0.088646)
		(layer "In11.Cu")
		(net "M_H_CPU1_SB_CA<5>")
	)
	(arc
		(start 128.830578 -246.683784)
		(mid 128.699664 -246.547424)
		(end 128.652016 -246.364506)
		(width 0.088646)
		(layer "In11.Cu")
		(net "M_H_CPU1_SB_CA<5>")
	)
	(arc
		(start 132.03301 -246.688864)
		(mid 131.845812 -246.739007)
		(end 131.658614 -246.688864)
		(width 0.088646)
		(layer "In11.Cu")
		(net "M_H_CPU1_SB_CA<5>")
	)
	(arc
		(start 135.879078 -247.4976)
		(mid 135.748164 -247.36124)
		(end 135.700516 -247.178322)
		(width 0.088646)
		(layer "In11.Cu")
		(net "M_H_CPU1_SB_CA<5>")
	)
	(arc
		(start 131.658614 -246.688864)
		(mid 131.375912 -246.613088)
		(end 131.09321 -246.688864)
		(width 0.088646)
		(layer "In11.Cu")
		(net "M_H_CPU1_SB_CA<5>")
	)
	(arc
		(start 130.15341 -246.688864)
		(mid 129.966212 -246.739007)
		(end 129.779014 -246.688864)
		(width 0.088646)
		(layer "In11.Cu")
		(net "M_H_CPU1_SB_CA<5>")
	)
	(arc
		(start 131.09321 -246.688864)
		(mid 130.906012 -246.739007)
		(end 130.718814 -246.688864)
		(width 0.088646)
		(layer "In11.Cu")
		(net "M_H_CPU1_SB_CA<5>")
	)
	(arc
		(start 128.592326 -246.111776)
		(mid 128.565799 -246.038532)
		(end 128.556766 -245.961154)
		(width 0.088646)
		(layer "In11.Cu")
		(net "M_H_CPU1_SB_CA<5>")
	)
	(arc
		(start 134.852664 -246.688864)
		(mid 134.665466 -246.739007)
		(end 134.478268 -246.688864)
		(width 0.088646)
		(layer "In11.Cu")
		(net "M_H_CPU1_SB_CA<5>")
	)
	(arc
		(start 136.262364 -247.50268)
		(mid 136.075166 -247.552823)
		(end 135.887968 -247.50268)
		(width 0.088646)
		(layer "In11.Cu")
		(net "M_H_CPU1_SB_CA<5>")
	)
	(arc
		(start 137.202164 -247.50268)
		(mid 137.014966 -247.552823)
		(end 136.827768 -247.50268)
		(width 0.088646)
		(layer "In11.Cu")
		(net "M_H_CPU1_SB_CA<5>")
	)
	(arc
		(start 129.7686 -246.682768)
		(mid 129.490422 -246.613045)
		(end 129.213864 -246.688864)
		(width 0.088646)
		(layer "In11.Cu")
		(net "M_H_CPU1_SB_CA<5>")
	)
	(arc
		(start 129.213864 -246.688864)
		(mid 129.026666 -246.739007)
		(end 128.839468 -246.688864)
		(width 0.088646)
		(layer "In11.Cu")
		(net "M_H_CPU1_SB_CA<5>")
	)
	(arc
		(start 136.827768 -247.50268)
		(mid 136.545066 -247.426904)
		(end 136.262364 -247.50268)
		(width 0.088646)
		(layer "In11.Cu")
		(net "M_H_CPU1_SB_CA<5>")
	)
	(arc
		(start 132.583682 -246.680228)
		(mid 132.307207 -246.612908)
		(end 132.03301 -246.688864)
		(width 0.088646)
		(layer "In11.Cu")
		(net "M_H_CPU1_SB_CA<5>")
	)
	(arc
		(start 134.478268 -246.688864)
		(mid 134.195566 -246.613088)
		(end 133.912864 -246.688864)
		(width 0.088646)
		(layer "In11.Cu")
		(net "M_H_CPU1_SB_CA<5>")
	)
	(arc
		(start 130.704082 -246.680228)
		(mid 130.427607 -246.612908)
		(end 130.15341 -246.688864)
		(width 0.088646)
		(layer "In11.Cu")
		(net "M_H_CPU1_SB_CA<5>")
	)
	(arc
		(start 137.86104 -247.545352)
		(mid 137.538063 -247.424141)
		(end 137.202164 -247.50268)
		(width 0.088646)
		(layer "In11.Cu")
		(net "M_H_CPU1_SB_CA<5>")
	)
	(arc
		(start 135.418068 -246.688864)
		(mid 135.135366 -246.613088)
		(end 134.852664 -246.688864)
		(width 0.088646)
		(layer "In11.Cu")
		(net "M_H_CPU1_SB_CA<5>")
	)
	(arc
		(start 133.538468 -246.688864)
		(mid 133.261655 -246.612994)
		(end 132.983224 -246.682768)
		(width 0.088646)
		(layer "In11.Cu")
		(net "M_H_CPU1_SB_CA<5>")
	)
	(arc
		(start 132.97281 -246.688864)
		(mid 132.785612 -246.739007)
		(end 132.598414 -246.688864)
		(width 0.088646)
		(layer "In11.Cu")
		(net "M_H_CPU1_SB_CA<5>")
	)
	(segment
		(start 211.619592 -249.16638)
		(end 211.619846 -249.166634)
		(width 0.20066)
		(layer "F.Cu")
		(net "M_H_CPU1_SB_CA<4>")
	)
	(segment
		(start 209.186526 -249.604022)
		(end 209.602578 -249.604022)
		(width 0.20066)
		(layer "F.Cu")
		(net "M_H_CPU1_SB_CA<4>")
	)
	(segment
		(start 209.602578 -249.604022)
		(end 210.04022 -249.16638)
		(width 0.20066)
		(layer "F.Cu")
		(net "M_H_CPU1_SB_CA<4>")
	)
	(segment
		(start 205.63586 -248.67235)
		(end 205.961234 -248.67235)
		(width 0.20066)
		(layer "F.Cu")
		(net "M_H_CPU1_SB_CA<4>")
	)
	(segment
		(start 207.001618 -249.591576)
		(end 209.17408 -249.591576)
		(width 0.1016)
		(layer "F.Cu")
		(net "M_H_CPU1_SB_CA<4>")
	)
	(segment
		(start 126.676912 -246.08663)
		(end 126.677166 -246.086376)
		(width 0.20066)
		(layer "F.Cu")
		(net "M_H_CPU1_SB_CA<4>")
	)
	(segment
		(start 202.971146 -249.166634)
		(end 204.076046 -249.166634)
		(width 0.20066)
		(layer "F.Cu")
		(net "M_H_CPU1_SB_CA<4>")
	)
	(segment
		(start 205.961234 -248.67235)
		(end 206.88046 -249.591576)
		(width 0.20066)
		(layer "F.Cu")
		(net "M_H_CPU1_SB_CA<4>")
	)
	(segment
		(start 204.076046 -249.166634)
		(end 205.141576 -249.166634)
		(width 0.20066)
		(layer "F.Cu")
		(net "M_H_CPU1_SB_CA<4>")
	)
	(segment
		(start 206.88046 -249.591576)
		(end 206.987902 -249.591576)
		(width 0.20066)
		(layer "F.Cu")
		(net "M_H_CPU1_SB_CA<4>")
	)
	(segment
		(start 210.04022 -249.16638)
		(end 211.619592 -249.16638)
		(width 0.20066)
		(layer "F.Cu")
		(net "M_H_CPU1_SB_CA<4>")
	)
	(segment
		(start 205.141576 -249.166634)
		(end 205.63586 -248.67235)
		(width 0.20066)
		(layer "F.Cu")
		(net "M_H_CPU1_SB_CA<4>")
	)
	(segment
		(start 206.987902 -249.591576)
		(end 207.001618 -249.591576)
		(width 0.101854)
		(layer "F.Cu")
		(net "M_H_CPU1_SB_CA<4>")
	)
	(segment
		(start 126.677166 -246.086376)
		(end 126.677166 -245.55069)
		(width 0.20066)
		(layer "F.Cu")
		(net "M_H_CPU1_SB_CA<4>")
	)
	(segment
		(start 209.17408 -249.591576)
		(end 209.186526 -249.604022)
		(width 0.1016)
		(layer "F.Cu")
		(net "M_H_CPU1_SB_CA<4>")
	)
	(segment
		(start 137.868152 -248.22023)
		(end 137.867898 -248.22023)
		(width 0.088646)
		(layer "In11.Cu")
		(net "M_H_CPU1_SB_CA<4>")
	)
	(segment
		(start 130.633978 -246.86006)
		(end 130.623564 -246.853964)
		(width 0.088646)
		(layer "In11.Cu")
		(net "M_H_CPU1_SB_CA<4>")
	)
	(segment
		(start 179.112926 -249.752866)
		(end 178.346862 -249.752866)
		(width 0.18288)
		(layer "In11.Cu")
		(net "M_H_CPU1_SB_CA<4>")
	)
	(segment
		(start 188.92393 -250.441206)
		(end 187.299346 -250.441206)
		(width 0.18288)
		(layer "In11.Cu")
		(net "M_H_CPU1_SB_CA<4>")
	)
	(segment
		(start 180.902356 -249.396504)
		(end 180.902356 -248.942352)
		(width 0.18288)
		(layer "In11.Cu")
		(net "M_H_CPU1_SB_CA<4>")
	)
	(segment
		(start 191.49949 -250.441206)
		(end 191.333628 -250.607068)
		(width 0.18288)
		(layer "In11.Cu")
		(net "M_H_CPU1_SB_CA<4>")
	)
	(segment
		(start 185.62828 -251.271786)
		(end 185.62828 -250.158504)
		(width 0.18288)
		(layer "In11.Cu")
		(net "M_H_CPU1_SB_CA<4>")
	)
	(segment
		(start 180.198776 -248.942352)
		(end 180.198776 -249.396504)
		(width 0.18288)
		(layer "In11.Cu")
		(net "M_H_CPU1_SB_CA<4>")
	)
	(segment
		(start 193.102992 -250.288552)
		(end 192.950338 -250.441206)
		(width 0.18288)
		(layer "In11.Cu")
		(net "M_H_CPU1_SB_CA<4>")
	)
	(segment
		(start 157.812232 -249.278394)
		(end 157.237176 -249.85345)
		(width 0.18288)
		(layer "In11.Cu")
		(net "M_H_CPU1_SB_CA<4>")
	)
	(segment
		(start 174.126144 -249.591068)
		(end 172.098208 -249.591068)
		(width 0.18288)
		(layer "In11.Cu")
		(net "M_H_CPU1_SB_CA<4>")
	)
	(segment
		(start 127.055118 -245.615968)
		(end 126.98984 -245.55069)
		(width 0.088646)
		(layer "In11.Cu")
		(net "M_H_CPU1_SB_CA<4>")
	)
	(segment
		(start 180.005736 -249.589544)
		(end 179.276248 -249.589544)
		(width 0.18288)
		(layer "In11.Cu")
		(net "M_H_CPU1_SB_CA<4>")
	)
	(segment
		(start 172.098208 -249.591068)
		(end 171.91863 -249.770646)
		(width 0.18288)
		(layer "In11.Cu")
		(net "M_H_CPU1_SB_CA<4>")
	)
	(segment
		(start 159.361632 -249.278394)
		(end 159.168592 -249.471434)
		(width 0.18288)
		(layer "In11.Cu")
		(net "M_H_CPU1_SB_CA<4>")
	)
	(segment
		(start 151.202898 -249.440954)
		(end 149.004274 -247.24233)
		(width 0.18288)
		(layer "In11.Cu")
		(net "M_H_CPU1_SB_CA<4>")
	)
	(segment
		(start 199.997822 -250.317254)
		(end 198.65721 -250.317254)
		(width 0.18288)
		(layer "In11.Cu")
		(net "M_H_CPU1_SB_CA<4>")
	)
	(segment
		(start 202.839066 -249.573034)
		(end 202.383898 -249.761502)
		(width 0.18288)
		(layer "In11.Cu")
		(net "M_H_CPU1_SB_CA<4>")
	)
	(segment
		(start 200.553574 -249.761502)
		(end 199.997822 -250.317254)
		(width 0.18288)
		(layer "In11.Cu")
		(net "M_H_CPU1_SB_CA<4>")
	)
	(segment
		(start 202.971146 -249.166634)
		(end 202.971146 -249.440954)
		(width 0.18288)
		(layer "In11.Cu")
		(net "M_H_CPU1_SB_CA<4>")
	)
	(segment
		(start 137.779252 -247.774968)
		(end 137.672064 -247.66778)
		(width 0.088646)
		(layer "In11.Cu")
		(net "M_H_CPU1_SB_CA<4>")
	)
	(segment
		(start 202.383898 -249.761502)
		(end 200.553574 -249.761502)
		(width 0.18288)
		(layer "In11.Cu")
		(net "M_H_CPU1_SB_CA<4>")
	)
	(segment
		(start 140.145262 -249.146822)
		(end 139.767056 -249.146822)
		(width 0.18288)
		(layer "In11.Cu")
		(net "M_H_CPU1_SB_CA<4>")
	)
	(segment
		(start 135.331454 -246.859044)
		(end 135.322564 -246.853964)
		(width 0.088646)
		(layer "In11.Cu")
		(net "M_H_CPU1_SB_CA<4>")
	)
	(segment
		(start 194.74434 -250.288552)
		(end 193.102992 -250.288552)
		(width 0.18288)
		(layer "In11.Cu")
		(net "M_H_CPU1_SB_CA<4>")
	)
	(segment
		(start 129.698496 -246.8626)
		(end 129.683764 -246.853964)
		(width 0.088646)
		(layer "In11.Cu")
		(net "M_H_CPU1_SB_CA<4>")
	)
	(segment
		(start 178.185064 -249.591068)
		(end 175.870362 -249.591068)
		(width 0.18288)
		(layer "In11.Cu")
		(net "M_H_CPU1_SB_CA<4>")
	)
	(segment
		(start 163.456366 -250.25604)
		(end 162.879786 -249.67946)
		(width 0.18288)
		(layer "In11.Cu")
		(net "M_H_CPU1_SB_CA<4>")
	)
	(segment
		(start 153.873962 -249.440954)
		(end 151.202898 -249.440954)
		(width 0.18288)
		(layer "In11.Cu")
		(net "M_H_CPU1_SB_CA<4>")
	)
	(segment
		(start 187.299346 -250.441206)
		(end 187.139326 -250.601226)
		(width 0.18288)
		(layer "In11.Cu")
		(net "M_H_CPU1_SB_CA<4>")
	)
	(segment
		(start 162.879786 -249.67946)
		(end 161.392616 -249.67946)
		(width 0.18288)
		(layer "In11.Cu")
		(net "M_H_CPU1_SB_CA<4>")
	)
	(segment
		(start 164.571426 -250.525026)
		(end 164.30244 -250.25604)
		(width 0.18288)
		(layer "In11.Cu")
		(net "M_H_CPU1_SB_CA<4>")
	)
	(segment
		(start 139.767056 -249.146822)
		(end 138.85926 -248.239026)
		(width 0.18288)
		(layer "In11.Cu")
		(net "M_H_CPU1_SB_CA<4>")
	)
	(segment
		(start 135.510016 -247.188228)
		(end 135.510016 -247.178322)
		(width 0.088646)
		(layer "In11.Cu")
		(net "M_H_CPU1_SB_CA<4>")
	)
	(segment
		(start 185.82132 -251.464826)
		(end 185.62828 -251.271786)
		(width 0.18288)
		(layer "In11.Cu")
		(net "M_H_CPU1_SB_CA<4>")
	)
	(segment
		(start 185.62828 -250.158504)
		(end 185.43524 -249.965464)
		(width 0.18288)
		(layer "In11.Cu")
		(net "M_H_CPU1_SB_CA<4>")
	)
	(segment
		(start 138.1125 -248.239026)
		(end 137.886948 -248.239026)
		(width 0.088646)
		(layer "In11.Cu")
		(net "M_H_CPU1_SB_CA<4>")
	)
	(segment
		(start 126.98984 -245.55069)
		(end 126.677166 -245.55069)
		(width 0.088646)
		(layer "In11.Cu")
		(net "M_H_CPU1_SB_CA<4>")
	)
	(segment
		(start 145.373598 -247.24233)
		(end 144.160748 -247.48363)
		(width 0.18288)
		(layer "In11.Cu")
		(net "M_H_CPU1_SB_CA<4>")
	)
	(segment
		(start 154.869896 -249.85345)
		(end 153.873962 -249.440954)
		(width 0.18288)
		(layer "In11.Cu")
		(net "M_H_CPU1_SB_CA<4>")
	)
	(segment
		(start 158.465012 -249.471434)
		(end 158.271972 -249.278394)
		(width 0.18288)
		(layer "In11.Cu")
		(net "M_H_CPU1_SB_CA<4>")
	)
	(segment
		(start 189.089792 -250.607068)
		(end 188.92393 -250.441206)
		(width 0.18288)
		(layer "In11.Cu")
		(net "M_H_CPU1_SB_CA<4>")
	)
	(segment
		(start 159.168592 -249.838718)
		(end 158.975552 -250.031758)
		(width 0.18288)
		(layer "In11.Cu")
		(net "M_H_CPU1_SB_CA<4>")
	)
	(segment
		(start 165.939724 -250.365006)
		(end 165.779704 -250.525026)
		(width 0.18288)
		(layer "In11.Cu")
		(net "M_H_CPU1_SB_CA<4>")
	)
	(segment
		(start 138.85926 -248.239026)
		(end 138.1125 -248.239026)
		(width 0.18288)
		(layer "In11.Cu")
		(net "M_H_CPU1_SB_CA<4>")
	)
	(segment
		(start 195.057522 -250.601734)
		(end 194.74434 -250.288552)
		(width 0.18288)
		(layer "In11.Cu")
		(net "M_H_CPU1_SB_CA<4>")
	)
	(segment
		(start 137.886948 -248.239026)
		(end 137.868152 -248.22023)
		(width 0.088646)
		(layer "In11.Cu")
		(net "M_H_CPU1_SB_CA<4>")
	)
	(segment
		(start 180.391816 -248.749312)
		(end 180.198776 -248.942352)
		(width 0.18288)
		(layer "In11.Cu")
		(net "M_H_CPU1_SB_CA<4>")
	)
	(segment
		(start 128.2827 -246.045228)
		(end 128.27381 -246.040148)
		(width 0.088646)
		(layer "In11.Cu")
		(net "M_H_CPU1_SB_CA<4>")
	)
	(segment
		(start 149.004274 -247.24233)
		(end 145.373598 -247.24233)
		(width 0.18288)
		(layer "In11.Cu")
		(net "M_H_CPU1_SB_CA<4>")
	)
	(segment
		(start 166.137082 -249.55373)
		(end 165.939724 -249.751088)
		(width 0.18288)
		(layer "In11.Cu")
		(net "M_H_CPU1_SB_CA<4>")
	)
	(segment
		(start 137.867898 -248.22023)
		(end 137.779252 -248.131584)
		(width 0.088646)
		(layer "In11.Cu")
		(net "M_H_CPU1_SB_CA<4>")
	)
	(segment
		(start 161.392616 -249.67946)
		(end 160.99155 -249.278394)
		(width 0.18288)
		(layer "In11.Cu")
		(net "M_H_CPU1_SB_CA<4>")
	)
	(segment
		(start 198.65721 -250.317254)
		(end 198.37273 -250.601734)
		(width 0.18288)
		(layer "In11.Cu")
		(net "M_H_CPU1_SB_CA<4>")
	)
	(segment
		(start 159.168592 -249.471434)
		(end 159.168592 -249.838718)
		(width 0.18288)
		(layer "In11.Cu")
		(net "M_H_CPU1_SB_CA<4>")
	)
	(segment
		(start 183.859424 -249.965464)
		(end 183.483504 -249.589544)
		(width 0.18288)
		(layer "In11.Cu")
		(net "M_H_CPU1_SB_CA<4>")
	)
	(segment
		(start 158.658052 -250.031758)
		(end 158.465012 -249.838718)
		(width 0.18288)
		(layer "In11.Cu")
		(net "M_H_CPU1_SB_CA<4>")
	)
	(segment
		(start 160.99155 -249.278394)
		(end 159.361632 -249.278394)
		(width 0.18288)
		(layer "In11.Cu")
		(net "M_H_CPU1_SB_CA<4>")
	)
	(segment
		(start 128.743964 -246.853964)
		(end 128.731772 -246.846852)
		(width 0.088646)
		(layer "In11.Cu")
		(net "M_H_CPU1_SB_CA<4>")
	)
	(segment
		(start 181.095396 -249.589544)
		(end 180.902356 -249.396504)
		(width 0.18288)
		(layer "In11.Cu")
		(net "M_H_CPU1_SB_CA<4>")
	)
	(segment
		(start 179.276248 -249.589544)
		(end 179.112926 -249.752866)
		(width 0.18288)
		(layer "In11.Cu")
		(net "M_H_CPU1_SB_CA<4>")
	)
	(segment
		(start 180.198776 -249.396504)
		(end 180.005736 -249.589544)
		(width 0.18288)
		(layer "In11.Cu")
		(net "M_H_CPU1_SB_CA<4>")
	)
	(segment
		(start 158.975552 -250.031758)
		(end 158.658052 -250.031758)
		(width 0.18288)
		(layer "In11.Cu")
		(net "M_H_CPU1_SB_CA<4>")
	)
	(segment
		(start 131.573524 -246.86006)
		(end 131.56311 -246.853964)
		(width 0.088646)
		(layer "In11.Cu")
		(net "M_H_CPU1_SB_CA<4>")
	)
	(segment
		(start 164.30244 -250.25604)
		(end 163.456366 -250.25604)
		(width 0.18288)
		(layer "In11.Cu")
		(net "M_H_CPU1_SB_CA<4>")
	)
	(segment
		(start 174.296832 -249.42038)
		(end 174.126144 -249.591068)
		(width 0.18288)
		(layer "In11.Cu")
		(net "M_H_CPU1_SB_CA<4>")
	)
	(segment
		(start 171.91863 -249.770646)
		(end 168.981628 -249.770646)
		(width 0.18288)
		(layer "In11.Cu")
		(net "M_H_CPU1_SB_CA<4>")
	)
	(segment
		(start 175.699674 -249.42038)
		(end 174.296832 -249.42038)
		(width 0.18288)
		(layer "In11.Cu")
		(net "M_H_CPU1_SB_CA<4>")
	)
	(segment
		(start 183.483504 -249.589544)
		(end 181.095396 -249.589544)
		(width 0.18288)
		(layer "In11.Cu")
		(net "M_H_CPU1_SB_CA<4>")
	)
	(segment
		(start 157.237176 -249.85345)
		(end 154.869896 -249.85345)
		(width 0.18288)
		(layer "In11.Cu")
		(net "M_H_CPU1_SB_CA<4>")
	)
	(segment
		(start 168.981628 -249.770646)
		(end 168.764712 -249.55373)
		(width 0.18288)
		(layer "In11.Cu")
		(net "M_H_CPU1_SB_CA<4>")
	)
	(segment
		(start 180.902356 -248.942352)
		(end 180.709316 -248.749312)
		(width 0.18288)
		(layer "In11.Cu")
		(net "M_H_CPU1_SB_CA<4>")
	)
	(segment
		(start 165.779704 -250.525026)
		(end 164.571426 -250.525026)
		(width 0.18288)
		(layer "In11.Cu")
		(net "M_H_CPU1_SB_CA<4>")
	)
	(segment
		(start 187.139326 -250.601226)
		(end 187.139326 -251.254006)
		(width 0.18288)
		(layer "In11.Cu")
		(net "M_H_CPU1_SB_CA<4>")
	)
	(segment
		(start 132.513578 -246.86006)
		(end 132.503164 -246.853964)
		(width 0.088646)
		(layer "In11.Cu")
		(net "M_H_CPU1_SB_CA<4>")
	)
	(segment
		(start 175.870362 -249.591068)
		(end 175.699674 -249.42038)
		(width 0.18288)
		(layer "In11.Cu")
		(net "M_H_CPU1_SB_CA<4>")
	)
	(segment
		(start 192.950338 -250.441206)
		(end 191.49949 -250.441206)
		(width 0.18288)
		(layer "In11.Cu")
		(net "M_H_CPU1_SB_CA<4>")
	)
	(segment
		(start 185.43524 -249.965464)
		(end 183.859424 -249.965464)
		(width 0.18288)
		(layer "In11.Cu")
		(net "M_H_CPU1_SB_CA<4>")
	)
	(segment
		(start 178.346862 -249.752866)
		(end 178.185064 -249.591068)
		(width 0.18288)
		(layer "In11.Cu")
		(net "M_H_CPU1_SB_CA<4>")
	)
	(segment
		(start 144.160748 -247.48363)
		(end 140.145262 -249.146822)
		(width 0.18288)
		(layer "In11.Cu")
		(net "M_H_CPU1_SB_CA<4>")
	)
	(segment
		(start 180.709316 -248.749312)
		(end 180.391816 -248.749312)
		(width 0.18288)
		(layer "In11.Cu")
		(net "M_H_CPU1_SB_CA<4>")
	)
	(segment
		(start 158.271972 -249.278394)
		(end 157.812232 -249.278394)
		(width 0.18288)
		(layer "In11.Cu")
		(net "M_H_CPU1_SB_CA<4>")
	)
	(segment
		(start 202.971146 -249.440954)
		(end 202.839066 -249.573034)
		(width 0.18288)
		(layer "In11.Cu")
		(net "M_H_CPU1_SB_CA<4>")
	)
	(segment
		(start 134.008368 -246.853964)
		(end 133.997954 -246.86006)
		(width 0.088646)
		(layer "In11.Cu")
		(net "M_H_CPU1_SB_CA<4>")
	)
	(segment
		(start 137.779252 -248.131584)
		(end 137.779252 -247.774968)
		(width 0.088646)
		(layer "In11.Cu")
		(net "M_H_CPU1_SB_CA<4>")
	)
	(segment
		(start 165.939724 -249.751088)
		(end 165.939724 -250.365006)
		(width 0.18288)
		(layer "In11.Cu")
		(net "M_H_CPU1_SB_CA<4>")
	)
	(segment
		(start 158.465012 -249.838718)
		(end 158.465012 -249.471434)
		(width 0.18288)
		(layer "In11.Cu")
		(net "M_H_CPU1_SB_CA<4>")
	)
	(segment
		(start 191.333628 -250.607068)
		(end 189.089792 -250.607068)
		(width 0.18288)
		(layer "In11.Cu")
		(net "M_H_CPU1_SB_CA<4>")
	)
	(segment
		(start 198.37273 -250.601734)
		(end 195.057522 -250.601734)
		(width 0.18288)
		(layer "In11.Cu")
		(net "M_H_CPU1_SB_CA<4>")
	)
	(segment
		(start 187.139326 -251.254006)
		(end 186.928506 -251.464826)
		(width 0.18288)
		(layer "In11.Cu")
		(net "M_H_CPU1_SB_CA<4>")
	)
	(segment
		(start 186.928506 -251.464826)
		(end 185.82132 -251.464826)
		(width 0.18288)
		(layer "In11.Cu")
		(net "M_H_CPU1_SB_CA<4>")
	)
	(segment
		(start 168.764712 -249.55373)
		(end 166.137082 -249.55373)
		(width 0.18288)
		(layer "In11.Cu")
		(net "M_H_CPU1_SB_CA<4>")
	)
	(arc
		(start 128.461262 -246.364506)
		(mid 128.413583 -246.181606)
		(end 128.2827 -246.045228)
		(width 0.088646)
		(layer "In11.Cu")
		(net "M_H_CPU1_SB_CA<4>")
	)
	(arc
		(start 136.357868 -247.66778)
		(mid 136.075166 -247.743556)
		(end 135.792464 -247.66778)
		(width 0.088646)
		(layer "In11.Cu")
		(net "M_H_CPU1_SB_CA<4>")
	)
	(arc
		(start 135.322564 -246.853964)
		(mid 135.135366 -246.803821)
		(end 134.948168 -246.853964)
		(width 0.088646)
		(layer "In11.Cu")
		(net "M_H_CPU1_SB_CA<4>")
	)
	(arc
		(start 135.792464 -247.66778)
		(mid 135.588129 -247.465175)
		(end 135.510016 -247.188228)
		(width 0.088646)
		(layer "In11.Cu")
		(net "M_H_CPU1_SB_CA<4>")
	)
	(arc
		(start 127.899414 -246.040148)
		(mid 127.616712 -246.115924)
		(end 127.33401 -246.040148)
		(width 0.088646)
		(layer "In11.Cu")
		(net "M_H_CPU1_SB_CA<4>")
	)
	(arc
		(start 135.510016 -247.178322)
		(mid 135.462337 -246.995422)
		(end 135.331454 -246.859044)
		(width 0.088646)
		(layer "In11.Cu")
		(net "M_H_CPU1_SB_CA<4>")
	)
	(arc
		(start 128.27381 -246.040148)
		(mid 128.086612 -245.990005)
		(end 127.899414 -246.040148)
		(width 0.088646)
		(layer "In11.Cu")
		(net "M_H_CPU1_SB_CA<4>")
	)
	(arc
		(start 132.128768 -246.853964)
		(mid 131.851955 -246.929834)
		(end 131.573524 -246.86006)
		(width 0.088646)
		(layer "In11.Cu")
		(net "M_H_CPU1_SB_CA<4>")
	)
	(arc
		(start 129.683764 -246.853964)
		(mid 129.496566 -246.803821)
		(end 129.309368 -246.853964)
		(width 0.088646)
		(layer "In11.Cu")
		(net "M_H_CPU1_SB_CA<4>")
	)
	(arc
		(start 128.731772 -246.846852)
		(mid 128.533544 -246.641004)
		(end 128.461262 -246.364506)
		(width 0.088646)
		(layer "In11.Cu")
		(net "M_H_CPU1_SB_CA<4>")
	)
	(arc
		(start 131.56311 -246.853964)
		(mid 131.375912 -246.803821)
		(end 131.188714 -246.853964)
		(width 0.088646)
		(layer "In11.Cu")
		(net "M_H_CPU1_SB_CA<4>")
	)
	(arc
		(start 136.732264 -247.66778)
		(mid 136.545066 -247.617637)
		(end 136.357868 -247.66778)
		(width 0.088646)
		(layer "In11.Cu")
		(net "M_H_CPU1_SB_CA<4>")
	)
	(arc
		(start 132.503164 -246.853964)
		(mid 132.315966 -246.803821)
		(end 132.128768 -246.853964)
		(width 0.088646)
		(layer "In11.Cu")
		(net "M_H_CPU1_SB_CA<4>")
	)
	(arc
		(start 127.33401 -246.040148)
		(mid 127.14426 -245.861134)
		(end 127.055118 -245.615968)
		(width 0.088646)
		(layer "In11.Cu")
		(net "M_H_CPU1_SB_CA<4>")
	)
	(arc
		(start 130.249168 -246.853964)
		(mid 129.974969 -246.929799)
		(end 129.698496 -246.8626)
		(width 0.088646)
		(layer "In11.Cu")
		(net "M_H_CPU1_SB_CA<4>")
	)
	(arc
		(start 131.188714 -246.853964)
		(mid 130.912155 -246.929707)
		(end 130.633978 -246.86006)
		(width 0.088646)
		(layer "In11.Cu")
		(net "M_H_CPU1_SB_CA<4>")
	)
	(arc
		(start 137.672064 -247.66778)
		(mid 137.484866 -247.617637)
		(end 137.297668 -247.66778)
		(width 0.088646)
		(layer "In11.Cu")
		(net "M_H_CPU1_SB_CA<4>")
	)
	(arc
		(start 133.068314 -246.853964)
		(mid 132.791755 -246.929707)
		(end 132.513578 -246.86006)
		(width 0.088646)
		(layer "In11.Cu")
		(net "M_H_CPU1_SB_CA<4>")
	)
	(arc
		(start 137.297668 -247.66778)
		(mid 137.014966 -247.743556)
		(end 136.732264 -247.66778)
		(width 0.088646)
		(layer "In11.Cu")
		(net "M_H_CPU1_SB_CA<4>")
	)
	(arc
		(start 129.309368 -246.853964)
		(mid 129.026666 -246.92974)
		(end 128.743964 -246.853964)
		(width 0.088646)
		(layer "In11.Cu")
		(net "M_H_CPU1_SB_CA<4>")
	)
	(arc
		(start 134.382764 -246.853964)
		(mid 134.195566 -246.803821)
		(end 134.008368 -246.853964)
		(width 0.088646)
		(layer "In11.Cu")
		(net "M_H_CPU1_SB_CA<4>")
	)
	(arc
		(start 133.44271 -246.853964)
		(mid 133.255512 -246.803821)
		(end 133.068314 -246.853964)
		(width 0.088646)
		(layer "In11.Cu")
		(net "M_H_CPU1_SB_CA<4>")
	)
	(arc
		(start 130.623564 -246.853964)
		(mid 130.436366 -246.803821)
		(end 130.249168 -246.853964)
		(width 0.088646)
		(layer "In11.Cu")
		(net "M_H_CPU1_SB_CA<4>")
	)
	(arc
		(start 133.997954 -246.86006)
		(mid 133.719522 -246.929906)
		(end 133.44271 -246.853964)
		(width 0.088646)
		(layer "In11.Cu")
		(net "M_H_CPU1_SB_CA<4>")
	)
	(arc
		(start 134.948168 -246.853964)
		(mid 134.665466 -246.92974)
		(end 134.382764 -246.853964)
		(width 0.088646)
		(layer "In11.Cu")
		(net "M_H_CPU1_SB_CA<4>")
	)
	(segment
		(start 128.086612 -246.900192)
		(end 128.086612 -246.364506)
		(width 0.20066)
		(layer "F.Cu")
		(net "M_H_CPU1_SB_CA<3>")
	)
	(segment
		(start 212.904324 -250.44908)
		(end 213.769194 -249.58421)
		(width 0.20066)
		(layer "F.Cu")
		(net "M_H_CPU1_SB_CA<3>")
	)
	(segment
		(start 207.071214 -250.016772)
		(end 208.176114 -250.016772)
		(width 0.20066)
		(layer "F.Cu")
		(net "M_H_CPU1_SB_CA<3>")
	)
	(segment
		(start 209.811874 -250.016772)
		(end 210.247484 -250.452382)
		(width 0.20066)
		(layer "F.Cu")
		(net "M_H_CPU1_SB_CA<3>")
	)
	(segment
		(start 210.598258 -250.452382)
		(end 210.603084 -250.452382)
		(width 0.101854)
		(layer "F.Cu")
		(net "M_H_CPU1_SB_CA<3>")
	)
	(segment
		(start 210.603084 -250.452382)
		(end 210.613752 -250.441714)
		(width 0.1016)
		(layer "F.Cu")
		(net "M_H_CPU1_SB_CA<3>")
	)
	(segment
		(start 213.769194 -249.58421)
		(end 214.1728 -249.58421)
		(width 0.20066)
		(layer "F.Cu")
		(net "M_H_CPU1_SB_CA<3>")
	)
	(segment
		(start 128.086866 -246.900446)
		(end 128.086612 -246.900192)
		(width 0.20066)
		(layer "F.Cu")
		(net "M_H_CPU1_SB_CA<3>")
	)
	(segment
		(start 210.613752 -250.441714)
		(end 212.622892 -250.441714)
		(width 0.1016)
		(layer "F.Cu")
		(net "M_H_CPU1_SB_CA<3>")
	)
	(segment
		(start 208.176114 -250.016772)
		(end 209.811874 -250.016772)
		(width 0.20066)
		(layer "F.Cu")
		(net "M_H_CPU1_SB_CA<3>")
	)
	(segment
		(start 214.1728 -249.58421)
		(end 214.605362 -250.016772)
		(width 0.20066)
		(layer "F.Cu")
		(net "M_H_CPU1_SB_CA<3>")
	)
	(segment
		(start 210.247484 -250.452382)
		(end 210.598258 -250.452382)
		(width 0.20066)
		(layer "F.Cu")
		(net "M_H_CPU1_SB_CA<3>")
	)
	(segment
		(start 214.605362 -250.016772)
		(end 215.719914 -250.016772)
		(width 0.20066)
		(layer "F.Cu")
		(net "M_H_CPU1_SB_CA<3>")
	)
	(segment
		(start 212.630258 -250.44908)
		(end 212.904324 -250.44908)
		(width 0.20066)
		(layer "F.Cu")
		(net "M_H_CPU1_SB_CA<3>")
	)
	(segment
		(start 212.622892 -250.441714)
		(end 212.630258 -250.44908)
		(width 0.1016)
		(layer "F.Cu")
		(net "M_H_CPU1_SB_CA<3>")
	)
	(segment
		(start 174.171864 -250.441206)
		(end 171.897548 -250.441206)
		(width 0.18288)
		(layer "In11.Cu")
		(net "M_H_CPU1_SB_CA<3>")
	)
	(segment
		(start 177.82921 -250.563888)
		(end 177.82921 -251.051314)
		(width 0.18288)
		(layer "In11.Cu")
		(net "M_H_CPU1_SB_CA<3>")
	)
	(segment
		(start 176.490376 -251.291344)
		(end 175.82515 -250.626118)
		(width 0.18288)
		(layer "In11.Cu")
		(net "M_H_CPU1_SB_CA<3>")
	)
	(segment
		(start 161.021268 -250.308618)
		(end 160.783524 -250.546362)
		(width 0.18288)
		(layer "In11.Cu")
		(net "M_H_CPU1_SB_CA<3>")
	)
	(segment
		(start 140.06322 -249.58675)
		(end 139.590272 -249.58675)
		(width 0.18288)
		(layer "In11.Cu")
		(net "M_H_CPU1_SB_CA<3>")
	)
	(segment
		(start 160.783524 -250.546362)
		(end 157.287722 -250.546362)
		(width 0.18288)
		(layer "In11.Cu")
		(net "M_H_CPU1_SB_CA<3>")
	)
	(segment
		(start 168.784778 -250.515882)
		(end 166.507922 -250.515882)
		(width 0.18288)
		(layer "In11.Cu")
		(net "M_H_CPU1_SB_CA<3>")
	)
	(segment
		(start 157.287722 -250.546362)
		(end 157.287468 -250.546108)
		(width 0.18288)
		(layer "In11.Cu")
		(net "M_H_CPU1_SB_CA<3>")
	)
	(segment
		(start 139.590272 -249.58675)
		(end 138.62939 -248.625868)
		(width 0.18288)
		(layer "In11.Cu")
		(net "M_H_CPU1_SB_CA<3>")
	)
	(segment
		(start 177.82921 -251.051314)
		(end 177.58918 -251.291344)
		(width 0.18288)
		(layer "In11.Cu")
		(net "M_H_CPU1_SB_CA<3>")
	)
	(segment
		(start 162.581336 -250.308618)
		(end 161.021268 -250.308618)
		(width 0.18288)
		(layer "In11.Cu")
		(net "M_H_CPU1_SB_CA<3>")
	)
	(segment
		(start 203.778104 -250.441968)
		(end 202.416664 -250.441968)
		(width 0.18288)
		(layer "In11.Cu")
		(net "M_H_CPU1_SB_CA<3>")
	)
	(segment
		(start 127.899414 -246.688864)
		(end 127.890524 -246.683784)
		(width 0.088646)
		(layer "In11.Cu")
		(net "M_H_CPU1_SB_CA<3>")
	)
	(segment
		(start 171.750228 -250.293886)
		(end 169.006774 -250.293886)
		(width 0.18288)
		(layer "In11.Cu")
		(net "M_H_CPU1_SB_CA<3>")
	)
	(segment
		(start 148.60397 -247.58777)
		(end 145.536158 -247.58777)
		(width 0.18288)
		(layer "In11.Cu")
		(net "M_H_CPU1_SB_CA<3>")
	)
	(segment
		(start 127.716534 -246.42191)
		(end 127.773938 -246.364506)
		(width 0.088646)
		(layer "In11.Cu")
		(net "M_H_CPU1_SB_CA<3>")
	)
	(segment
		(start 145.536158 -247.58777)
		(end 144.291304 -247.83542)
		(width 0.18288)
		(layer "In11.Cu")
		(net "M_H_CPU1_SB_CA<3>")
	)
	(segment
		(start 150.972774 -249.956574)
		(end 148.60397 -247.58777)
		(width 0.18288)
		(layer "In11.Cu")
		(net "M_H_CPU1_SB_CA<3>")
	)
	(segment
		(start 175.82515 -250.626118)
		(end 174.356776 -250.626118)
		(width 0.18288)
		(layer "In11.Cu")
		(net "M_H_CPU1_SB_CA<3>")
	)
	(segment
		(start 202.416664 -250.441968)
		(end 202.281282 -250.306586)
		(width 0.18288)
		(layer "In11.Cu")
		(net "M_H_CPU1_SB_CA<3>")
	)
	(segment
		(start 189.30493 -251.116846)
		(end 188.280548 -252.141228)
		(width 0.18288)
		(layer "In11.Cu")
		(net "M_H_CPU1_SB_CA<3>")
	)
	(segment
		(start 153.780998 -249.956574)
		(end 150.972774 -249.956574)
		(width 0.18288)
		(layer "In11.Cu")
		(net "M_H_CPU1_SB_CA<3>")
	)
	(segment
		(start 200.55332 -251.42444)
		(end 198.62292 -251.42444)
		(width 0.18288)
		(layer "In11.Cu")
		(net "M_H_CPU1_SB_CA<3>")
	)
	(segment
		(start 137.634218 -248.625868)
		(end 137.414762 -248.406412)
		(width 0.088646)
		(layer "In11.Cu")
		(net "M_H_CPU1_SB_CA<3>")
	)
	(segment
		(start 133.538468 -248.316496)
		(end 133.529578 -248.311416)
		(width 0.088646)
		(layer "In11.Cu")
		(net "M_H_CPU1_SB_CA<3>")
	)
	(segment
		(start 163.686744 -251.414026)
		(end 162.581336 -250.308618)
		(width 0.18288)
		(layer "In11.Cu")
		(net "M_H_CPU1_SB_CA<3>")
	)
	(segment
		(start 182.515764 -250.716034)
		(end 179.822348 -250.716034)
		(width 0.18288)
		(layer "In11.Cu")
		(net "M_H_CPU1_SB_CA<3>")
	)
	(segment
		(start 195.068444 -251.247148)
		(end 194.783456 -251.532136)
		(width 0.18288)
		(layer "In11.Cu")
		(net "M_H_CPU1_SB_CA<3>")
	)
	(segment
		(start 138.62939 -248.625868)
		(end 138.1125 -248.625868)
		(width 0.18288)
		(layer "In11.Cu")
		(net "M_H_CPU1_SB_CA<3>")
	)
	(segment
		(start 192.953132 -251.29109)
		(end 190.918338 -251.29109)
		(width 0.18288)
		(layer "In11.Cu")
		(net "M_H_CPU1_SB_CA<3>")
	)
	(segment
		(start 178.033172 -250.359926)
		(end 177.82921 -250.563888)
		(width 0.18288)
		(layer "In11.Cu")
		(net "M_H_CPU1_SB_CA<3>")
	)
	(segment
		(start 133.068314 -247.50268)
		(end 133.0579 -247.496584)
		(width 0.088646)
		(layer "In11.Cu")
		(net "M_H_CPU1_SB_CA<3>")
	)
	(segment
		(start 171.897548 -250.441206)
		(end 171.750228 -250.293886)
		(width 0.18288)
		(layer "In11.Cu")
		(net "M_H_CPU1_SB_CA<3>")
	)
	(segment
		(start 127.90551 -246.69242)
		(end 127.899414 -246.688864)
		(width 0.088646)
		(layer "In11.Cu")
		(net "M_H_CPU1_SB_CA<3>")
	)
	(segment
		(start 164.419026 -251.210826)
		(end 164.215826 -251.414026)
		(width 0.18288)
		(layer "In11.Cu")
		(net "M_H_CPU1_SB_CA<3>")
	)
	(segment
		(start 202.281282 -250.306586)
		(end 201.671174 -250.306586)
		(width 0.18288)
		(layer "In11.Cu")
		(net "M_H_CPU1_SB_CA<3>")
	)
	(segment
		(start 174.356776 -250.626118)
		(end 174.171864 -250.441206)
		(width 0.18288)
		(layer "In11.Cu")
		(net "M_H_CPU1_SB_CA<3>")
	)
	(segment
		(start 201.671174 -250.306586)
		(end 200.55332 -251.42444)
		(width 0.18288)
		(layer "In11.Cu")
		(net "M_H_CPU1_SB_CA<3>")
	)
	(segment
		(start 190.744094 -251.116846)
		(end 189.30493 -251.116846)
		(width 0.18288)
		(layer "In11.Cu")
		(net "M_H_CPU1_SB_CA<3>")
	)
	(segment
		(start 179.822348 -250.716034)
		(end 179.46624 -250.359926)
		(width 0.18288)
		(layer "In11.Cu")
		(net "M_H_CPU1_SB_CA<3>")
	)
	(segment
		(start 169.006774 -250.293886)
		(end 168.784778 -250.515882)
		(width 0.18288)
		(layer "In11.Cu")
		(net "M_H_CPU1_SB_CA<3>")
	)
	(segment
		(start 190.918338 -251.29109)
		(end 190.744094 -251.116846)
		(width 0.18288)
		(layer "In11.Cu")
		(net "M_H_CPU1_SB_CA<3>")
	)
	(segment
		(start 127.773938 -246.364506)
		(end 128.086612 -246.364506)
		(width 0.088646)
		(layer "In11.Cu")
		(net "M_H_CPU1_SB_CA<3>")
	)
	(segment
		(start 165.812978 -251.210826)
		(end 164.419026 -251.210826)
		(width 0.18288)
		(layer "In11.Cu")
		(net "M_H_CPU1_SB_CA<3>")
	)
	(segment
		(start 207.071214 -250.016772)
		(end 206.582772 -250.016772)
		(width 0.18288)
		(layer "In11.Cu")
		(net "M_H_CPU1_SB_CA<3>")
	)
	(segment
		(start 206.582772 -250.016772)
		(end 206.014828 -250.584716)
		(width 0.18288)
		(layer "In11.Cu")
		(net "M_H_CPU1_SB_CA<3>")
	)
	(segment
		(start 185.458608 -252.141228)
		(end 184.807606 -251.490226)
		(width 0.18288)
		(layer "In11.Cu")
		(net "M_H_CPU1_SB_CA<3>")
	)
	(segment
		(start 136.732264 -248.316496)
		(end 136.71423 -248.32691)
		(width 0.088646)
		(layer "In11.Cu")
		(net "M_H_CPU1_SB_CA<3>")
	)
	(segment
		(start 157.287468 -250.546108)
		(end 155.20416 -250.546108)
		(width 0.18288)
		(layer "In11.Cu")
		(net "M_H_CPU1_SB_CA<3>")
	)
	(segment
		(start 198.62292 -251.42444)
		(end 198.445628 -251.247148)
		(width 0.18288)
		(layer "In11.Cu")
		(net "M_H_CPU1_SB_CA<3>")
	)
	(segment
		(start 164.215826 -251.414026)
		(end 163.686744 -251.414026)
		(width 0.18288)
		(layer "In11.Cu")
		(net "M_H_CPU1_SB_CA<3>")
	)
	(segment
		(start 155.20416 -250.546108)
		(end 153.780998 -249.956574)
		(width 0.18288)
		(layer "In11.Cu")
		(net "M_H_CPU1_SB_CA<3>")
	)
	(segment
		(start 179.46624 -250.359926)
		(end 178.033172 -250.359926)
		(width 0.18288)
		(layer "In11.Cu")
		(net "M_H_CPU1_SB_CA<3>")
	)
	(segment
		(start 136.71423 -248.32691)
		(end 136.695688 -248.335038)
		(width 0.088646)
		(layer "In11.Cu")
		(net "M_H_CPU1_SB_CA<3>")
	)
	(segment
		(start 128.369568 -247.50268)
		(end 128.360678 -247.4976)
		(width 0.088646)
		(layer "In11.Cu")
		(net "M_H_CPU1_SB_CA<3>")
	)
	(segment
		(start 193.194178 -251.532136)
		(end 192.953132 -251.29109)
		(width 0.18288)
		(layer "In11.Cu")
		(net "M_H_CPU1_SB_CA<3>")
	)
	(segment
		(start 203.920852 -250.584716)
		(end 203.778104 -250.441968)
		(width 0.18288)
		(layer "In11.Cu")
		(net "M_H_CPU1_SB_CA<3>")
	)
	(segment
		(start 131.573524 -247.496584)
		(end 131.56311 -247.50268)
		(width 0.088646)
		(layer "In11.Cu")
		(net "M_H_CPU1_SB_CA<3>")
	)
	(segment
		(start 144.291304 -247.83542)
		(end 140.06322 -249.58675)
		(width 0.18288)
		(layer "In11.Cu")
		(net "M_H_CPU1_SB_CA<3>")
	)
	(segment
		(start 133.07441 -247.506236)
		(end 133.068314 -247.50268)
		(width 0.088646)
		(layer "In11.Cu")
		(net "M_H_CPU1_SB_CA<3>")
	)
	(segment
		(start 198.445628 -251.247148)
		(end 195.068444 -251.247148)
		(width 0.18288)
		(layer "In11.Cu")
		(net "M_H_CPU1_SB_CA<3>")
	)
	(segment
		(start 128.758696 -247.494044)
		(end 128.743964 -247.50268)
		(width 0.088646)
		(layer "In11.Cu")
		(net "M_H_CPU1_SB_CA<3>")
	)
	(segment
		(start 166.507922 -250.515882)
		(end 165.812978 -251.210826)
		(width 0.18288)
		(layer "In11.Cu")
		(net "M_H_CPU1_SB_CA<3>")
	)
	(segment
		(start 194.783456 -251.532136)
		(end 193.194178 -251.532136)
		(width 0.18288)
		(layer "In11.Cu")
		(net "M_H_CPU1_SB_CA<3>")
	)
	(segment
		(start 206.014828 -250.584716)
		(end 203.920852 -250.584716)
		(width 0.18288)
		(layer "In11.Cu")
		(net "M_H_CPU1_SB_CA<3>")
	)
	(segment
		(start 184.807606 -251.490226)
		(end 183.289956 -251.490226)
		(width 0.18288)
		(layer "In11.Cu")
		(net "M_H_CPU1_SB_CA<3>")
	)
	(segment
		(start 138.1125 -248.625868)
		(end 137.634218 -248.625868)
		(width 0.088646)
		(layer "In11.Cu")
		(net "M_H_CPU1_SB_CA<3>")
	)
	(segment
		(start 183.289956 -251.490226)
		(end 182.515764 -250.716034)
		(width 0.18288)
		(layer "In11.Cu")
		(net "M_H_CPU1_SB_CA<3>")
	)
	(segment
		(start 129.698496 -247.494044)
		(end 129.683764 -247.50268)
		(width 0.088646)
		(layer "In11.Cu")
		(net "M_H_CPU1_SB_CA<3>")
	)
	(segment
		(start 188.280548 -252.141228)
		(end 185.458608 -252.141228)
		(width 0.18288)
		(layer "In11.Cu")
		(net "M_H_CPU1_SB_CA<3>")
	)
	(segment
		(start 131.188714 -247.50268)
		(end 131.1783 -247.496584)
		(width 0.088646)
		(layer "In11.Cu")
		(net "M_H_CPU1_SB_CA<3>")
	)
	(segment
		(start 177.58918 -251.291344)
		(end 176.490376 -251.291344)
		(width 0.18288)
		(layer "In11.Cu")
		(net "M_H_CPU1_SB_CA<3>")
	)
	(arc
		(start 132.128768 -247.50268)
		(mid 131.851955 -247.42681)
		(end 131.573524 -247.496584)
		(width 0.088646)
		(layer "In11.Cu")
		(net "M_H_CPU1_SB_CA<3>")
	)
	(arc
		(start 131.1783 -247.496584)
		(mid 130.900122 -247.426861)
		(end 130.623564 -247.50268)
		(width 0.088646)
		(layer "In11.Cu")
		(net "M_H_CPU1_SB_CA<3>")
	)
	(arc
		(start 137.297668 -248.316496)
		(mid 137.014966 -248.240754)
		(end 136.732264 -248.316496)
		(width 0.088646)
		(layer "In11.Cu")
		(net "M_H_CPU1_SB_CA<3>")
	)
	(arc
		(start 132.503164 -247.50268)
		(mid 132.315966 -247.552823)
		(end 132.128768 -247.50268)
		(width 0.088646)
		(layer "In11.Cu")
		(net "M_H_CPU1_SB_CA<3>")
	)
	(arc
		(start 129.309368 -247.50268)
		(mid 129.035169 -247.426845)
		(end 128.758696 -247.494044)
		(width 0.088646)
		(layer "In11.Cu")
		(net "M_H_CPU1_SB_CA<3>")
	)
	(arc
		(start 133.529578 -248.311416)
		(mid 133.398664 -248.175056)
		(end 133.351016 -247.992138)
		(width 0.088646)
		(layer "In11.Cu")
		(net "M_H_CPU1_SB_CA<3>")
	)
	(arc
		(start 130.249168 -247.50268)
		(mid 129.974969 -247.426845)
		(end 129.698496 -247.494044)
		(width 0.088646)
		(layer "In11.Cu")
		(net "M_H_CPU1_SB_CA<3>")
	)
	(arc
		(start 135.418068 -248.316496)
		(mid 135.135366 -248.240754)
		(end 134.852664 -248.316496)
		(width 0.088646)
		(layer "In11.Cu")
		(net "M_H_CPU1_SB_CA<3>")
	)
	(arc
		(start 134.852664 -248.316496)
		(mid 134.665466 -248.366639)
		(end 134.478268 -248.316496)
		(width 0.088646)
		(layer "In11.Cu")
		(net "M_H_CPU1_SB_CA<3>")
	)
	(arc
		(start 129.683764 -247.50268)
		(mid 129.496566 -247.552823)
		(end 129.309368 -247.50268)
		(width 0.088646)
		(layer "In11.Cu")
		(net "M_H_CPU1_SB_CA<3>")
	)
	(arc
		(start 128.182116 -247.178322)
		(mid 128.108125 -246.898756)
		(end 127.90551 -246.69242)
		(width 0.088646)
		(layer "In11.Cu")
		(net "M_H_CPU1_SB_CA<3>")
	)
	(arc
		(start 133.351016 -247.992138)
		(mid 133.277025 -247.712572)
		(end 133.07441 -247.506236)
		(width 0.088646)
		(layer "In11.Cu")
		(net "M_H_CPU1_SB_CA<3>")
	)
	(arc
		(start 128.743964 -247.50268)
		(mid 128.556766 -247.552823)
		(end 128.369568 -247.50268)
		(width 0.088646)
		(layer "In11.Cu")
		(net "M_H_CPU1_SB_CA<3>")
	)
	(arc
		(start 136.695688 -248.335038)
		(mid 136.524562 -248.366099)
		(end 136.357868 -248.316496)
		(width 0.088646)
		(layer "In11.Cu")
		(net "M_H_CPU1_SB_CA<3>")
	)
	(arc
		(start 133.0579 -247.496584)
		(mid 132.779722 -247.426861)
		(end 132.503164 -247.50268)
		(width 0.088646)
		(layer "In11.Cu")
		(net "M_H_CPU1_SB_CA<3>")
	)
	(arc
		(start 133.912864 -248.316496)
		(mid 133.725666 -248.366639)
		(end 133.538468 -248.316496)
		(width 0.088646)
		(layer "In11.Cu")
		(net "M_H_CPU1_SB_CA<3>")
	)
	(arc
		(start 130.623564 -247.50268)
		(mid 130.436366 -247.552823)
		(end 130.249168 -247.50268)
		(width 0.088646)
		(layer "In11.Cu")
		(net "M_H_CPU1_SB_CA<3>")
	)
	(arc
		(start 134.478268 -248.316496)
		(mid 134.195566 -248.240754)
		(end 133.912864 -248.316496)
		(width 0.088646)
		(layer "In11.Cu")
		(net "M_H_CPU1_SB_CA<3>")
	)
	(arc
		(start 128.360678 -247.4976)
		(mid 128.229764 -247.36124)
		(end 128.182116 -247.178322)
		(width 0.088646)
		(layer "In11.Cu")
		(net "M_H_CPU1_SB_CA<3>")
	)
	(arc
		(start 135.792464 -248.316496)
		(mid 135.605266 -248.366639)
		(end 135.418068 -248.316496)
		(width 0.088646)
		(layer "In11.Cu")
		(net "M_H_CPU1_SB_CA<3>")
	)
	(arc
		(start 136.357868 -248.316496)
		(mid 136.075166 -248.240754)
		(end 135.792464 -248.316496)
		(width 0.088646)
		(layer "In11.Cu")
		(net "M_H_CPU1_SB_CA<3>")
	)
	(arc
		(start 127.890524 -246.683784)
		(mid 127.774785 -246.57196)
		(end 127.716534 -246.42191)
		(width 0.088646)
		(layer "In11.Cu")
		(net "M_H_CPU1_SB_CA<3>")
	)
	(arc
		(start 137.414762 -248.406412)
		(mid 137.35916 -248.357619)
		(end 137.297668 -248.316496)
		(width 0.088646)
		(layer "In11.Cu")
		(net "M_H_CPU1_SB_CA<3>")
	)
	(arc
		(start 131.56311 -247.50268)
		(mid 131.375912 -247.552823)
		(end 131.188714 -247.50268)
		(width 0.088646)
		(layer "In11.Cu")
		(net "M_H_CPU1_SB_CA<3>")
	)
	(segment
		(start 202.971146 -250.866656)
		(end 204.076046 -250.866656)
		(width 0.20066)
		(layer "F.Cu")
		(net "M_H_CPU1_SB_CA<2>")
	)
	(segment
		(start 209.602578 -251.304044)
		(end 210.04022 -250.866402)
		(width 0.20066)
		(layer "F.Cu")
		(net "M_H_CPU1_SB_CA<2>")
	)
	(segment
		(start 205.63586 -250.372372)
		(end 205.961234 -250.372372)
		(width 0.20066)
		(layer "F.Cu")
		(net "M_H_CPU1_SB_CA<2>")
	)
	(segment
		(start 204.076046 -250.866656)
		(end 205.141576 -250.866656)
		(width 0.20066)
		(layer "F.Cu")
		(net "M_H_CPU1_SB_CA<2>")
	)
	(segment
		(start 127.146812 -246.900192)
		(end 127.146812 -246.364506)
		(width 0.20066)
		(layer "F.Cu")
		(net "M_H_CPU1_SB_CA<2>")
	)
	(segment
		(start 205.141576 -250.866656)
		(end 205.63586 -250.372372)
		(width 0.20066)
		(layer "F.Cu")
		(net "M_H_CPU1_SB_CA<2>")
	)
	(segment
		(start 210.04022 -250.866402)
		(end 211.619592 -250.866402)
		(width 0.20066)
		(layer "F.Cu")
		(net "M_H_CPU1_SB_CA<2>")
	)
	(segment
		(start 209.17408 -251.291598)
		(end 209.186526 -251.304044)
		(width 0.1016)
		(layer "F.Cu")
		(net "M_H_CPU1_SB_CA<2>")
	)
	(segment
		(start 207.001618 -251.291598)
		(end 209.17408 -251.291598)
		(width 0.1016)
		(layer "F.Cu")
		(net "M_H_CPU1_SB_CA<2>")
	)
	(segment
		(start 206.88046 -251.291598)
		(end 206.987902 -251.291598)
		(width 0.20066)
		(layer "F.Cu")
		(net "M_H_CPU1_SB_CA<2>")
	)
	(segment
		(start 206.987902 -251.291598)
		(end 207.001618 -251.291598)
		(width 0.101854)
		(layer "F.Cu")
		(net "M_H_CPU1_SB_CA<2>")
	)
	(segment
		(start 205.961234 -250.372372)
		(end 206.88046 -251.291598)
		(width 0.20066)
		(layer "F.Cu")
		(net "M_H_CPU1_SB_CA<2>")
	)
	(segment
		(start 211.619592 -250.866402)
		(end 211.619846 -250.866656)
		(width 0.20066)
		(layer "F.Cu")
		(net "M_H_CPU1_SB_CA<2>")
	)
	(segment
		(start 127.147066 -246.900446)
		(end 127.146812 -246.900192)
		(width 0.20066)
		(layer "F.Cu")
		(net "M_H_CPU1_SB_CA<2>")
	)
	(segment
		(start 209.186526 -251.304044)
		(end 209.602578 -251.304044)
		(width 0.20066)
		(layer "F.Cu")
		(net "M_H_CPU1_SB_CA<2>")
	)
	(segment
		(start 153.741628 -250.497086)
		(end 150.792942 -250.497086)
		(width 0.18288)
		(layer "In11.Cu")
		(net "M_H_CPU1_SB_CA<2>")
	)
	(segment
		(start 129.779014 -247.66778)
		(end 129.764282 -247.676416)
		(width 0.088646)
		(layer "In11.Cu")
		(net "M_H_CPU1_SB_CA<2>")
	)
	(segment
		(start 194.989196 -252.328172)
		(end 194.802252 -252.141228)
		(width 0.18288)
		(layer "In11.Cu")
		(net "M_H_CPU1_SB_CA<2>")
	)
	(segment
		(start 167.077898 -251.063252)
		(end 165.972236 -252.168914)
		(width 0.18288)
		(layer "In11.Cu")
		(net "M_H_CPU1_SB_CA<2>")
	)
	(segment
		(start 162.755326 -251.333762)
		(end 160.71215 -251.333762)
		(width 0.18288)
		(layer "In11.Cu")
		(net "M_H_CPU1_SB_CA<2>")
	)
	(segment
		(start 171.696634 -251.501402)
		(end 169.00906 -251.501402)
		(width 0.18288)
		(layer "In11.Cu")
		(net "M_H_CPU1_SB_CA<2>")
	)
	(segment
		(start 140.10386 -249.961654)
		(end 139.322302 -249.961654)
		(width 0.18288)
		(layer "In11.Cu")
		(net "M_H_CPU1_SB_CA<2>")
	)
	(segment
		(start 174.414688 -251.295408)
		(end 174.221648 -251.488448)
		(width 0.18288)
		(layer "In11.Cu")
		(net "M_H_CPU1_SB_CA<2>")
	)
	(segment
		(start 178.546506 -251.248672)
		(end 178.353466 -251.441712)
		(width 0.18288)
		(layer "In11.Cu")
		(net "M_H_CPU1_SB_CA<2>")
	)
	(segment
		(start 171.907708 -251.290328)
		(end 171.696634 -251.501402)
		(width 0.18288)
		(layer "In11.Cu")
		(net "M_H_CPU1_SB_CA<2>")
	)
	(segment
		(start 180.357018 -252.341634)
		(end 180.156612 -252.141228)
		(width 0.18288)
		(layer "In11.Cu")
		(net "M_H_CPU1_SB_CA<2>")
	)
	(segment
		(start 185.82005 -253.301246)
		(end 184.53481 -252.016006)
		(width 0.18288)
		(layer "In11.Cu")
		(net "M_H_CPU1_SB_CA<2>")
	)
	(segment
		(start 163.590478 -252.168914)
		(end 162.755326 -251.333762)
		(width 0.18288)
		(layer "In11.Cu")
		(net "M_H_CPU1_SB_CA<2>")
	)
	(segment
		(start 160.433512 -251.055124)
		(end 155.089098 -251.055124)
		(width 0.18288)
		(layer "In11.Cu")
		(net "M_H_CPU1_SB_CA<2>")
	)
	(segment
		(start 155.089098 -251.055124)
		(end 153.741628 -250.497086)
		(width 0.18288)
		(layer "In11.Cu")
		(net "M_H_CPU1_SB_CA<2>")
	)
	(segment
		(start 138.1125 -248.98096)
		(end 137.72007 -248.98096)
		(width 0.088646)
		(layer "In11.Cu")
		(net "M_H_CPU1_SB_CA<2>")
	)
	(segment
		(start 169.00906 -251.501402)
		(end 168.57091 -251.063252)
		(width 0.18288)
		(layer "In11.Cu")
		(net "M_H_CPU1_SB_CA<2>")
	)
	(segment
		(start 178.353466 -251.441712)
		(end 178.353466 -251.948188)
		(width 0.18288)
		(layer "In11.Cu")
		(net "M_H_CPU1_SB_CA<2>")
	)
	(segment
		(start 182.02275 -252.341634)
		(end 181.82971 -252.148594)
		(width 0.18288)
		(layer "In11.Cu")
		(net "M_H_CPU1_SB_CA<2>")
	)
	(segment
		(start 127.804164 -246.853964)
		(end 127.798068 -246.850408)
		(width 0.088646)
		(layer "In11.Cu")
		(net "M_H_CPU1_SB_CA<2>")
	)
	(segment
		(start 194.802252 -252.141228)
		(end 191.258444 -252.141228)
		(width 0.18288)
		(layer "In11.Cu")
		(net "M_H_CPU1_SB_CA<2>")
	)
	(segment
		(start 168.57091 -251.063252)
		(end 167.077898 -251.063252)
		(width 0.18288)
		(layer "In11.Cu")
		(net "M_H_CPU1_SB_CA<2>")
	)
	(segment
		(start 178.353466 -251.948188)
		(end 178.160426 -252.141228)
		(width 0.18288)
		(layer "In11.Cu")
		(net "M_H_CPU1_SB_CA<2>")
	)
	(segment
		(start 174.73803 -251.295408)
		(end 174.414688 -251.295408)
		(width 0.18288)
		(layer "In11.Cu")
		(net "M_H_CPU1_SB_CA<2>")
	)
	(segment
		(start 132.981954 -247.67286)
		(end 132.973064 -247.66778)
		(width 0.088646)
		(layer "In11.Cu")
		(net "M_H_CPU1_SB_CA<2>")
	)
	(segment
		(start 174.871634 -251.161804)
		(end 174.73803 -251.295408)
		(width 0.18288)
		(layer "In11.Cu")
		(net "M_H_CPU1_SB_CA<2>")
	)
	(segment
		(start 165.972236 -252.168914)
		(end 163.590478 -252.168914)
		(width 0.18288)
		(layer "In11.Cu")
		(net "M_H_CPU1_SB_CA<2>")
	)
	(segment
		(start 198.3613 -251.964952)
		(end 197.99808 -252.328172)
		(width 0.18288)
		(layer "In11.Cu")
		(net "M_H_CPU1_SB_CA<2>")
	)
	(segment
		(start 181.31917 -251.235972)
		(end 181.12613 -251.429012)
		(width 0.18288)
		(layer "In11.Cu")
		(net "M_H_CPU1_SB_CA<2>")
	)
	(segment
		(start 202.843892 -251.297694)
		(end 202.337162 -251.507752)
		(width 0.18288)
		(layer "In11.Cu")
		(net "M_H_CPU1_SB_CA<2>")
	)
	(segment
		(start 202.337162 -251.507752)
		(end 201.879962 -251.964952)
		(width 0.18288)
		(layer "In11.Cu")
		(net "M_H_CPU1_SB_CA<2>")
	)
	(segment
		(start 174.221648 -251.488448)
		(end 174.221648 -252.070616)
		(width 0.18288)
		(layer "In11.Cu")
		(net "M_H_CPU1_SB_CA<2>")
	)
	(segment
		(start 160.71215 -251.333762)
		(end 160.433512 -251.055124)
		(width 0.18288)
		(layer "In11.Cu")
		(net "M_H_CPU1_SB_CA<2>")
	)
	(segment
		(start 127.991616 -247.193816)
		(end 127.991616 -247.178322)
		(width 0.088646)
		(layer "In11.Cu")
		(net "M_H_CPU1_SB_CA<2>")
	)
	(segment
		(start 127.813054 -246.859044)
		(end 127.804164 -246.853964)
		(width 0.088646)
		(layer "In11.Cu")
		(net "M_H_CPU1_SB_CA<2>")
	)
	(segment
		(start 139.322302 -249.961654)
		(end 138.341608 -248.98096)
		(width 0.18288)
		(layer "In11.Cu")
		(net "M_H_CPU1_SB_CA<2>")
	)
	(segment
		(start 181.82971 -251.429012)
		(end 181.63667 -251.235972)
		(width 0.18288)
		(layer "In11.Cu")
		(net "M_H_CPU1_SB_CA<2>")
	)
	(segment
		(start 137.72007 -248.98096)
		(end 137.280142 -248.541032)
		(width 0.088646)
		(layer "In11.Cu")
		(net "M_H_CPU1_SB_CA<2>")
	)
	(segment
		(start 178.160426 -252.141228)
		(end 176.383188 -252.141228)
		(width 0.18288)
		(layer "In11.Cu")
		(net "M_H_CPU1_SB_CA<2>")
	)
	(segment
		(start 130.719068 -247.66778)
		(end 130.708654 -247.673876)
		(width 0.088646)
		(layer "In11.Cu")
		(net "M_H_CPU1_SB_CA<2>")
	)
	(segment
		(start 189.117224 -252.377194)
		(end 188.193172 -253.301246)
		(width 0.18288)
		(layer "In11.Cu")
		(net "M_H_CPU1_SB_CA<2>")
	)
	(segment
		(start 173.518068 -252.070616)
		(end 173.518068 -251.488448)
		(width 0.18288)
		(layer "In11.Cu")
		(net "M_H_CPU1_SB_CA<2>")
	)
	(segment
		(start 179.057046 -251.948188)
		(end 179.057046 -251.441712)
		(width 0.18288)
		(layer "In11.Cu")
		(net "M_H_CPU1_SB_CA<2>")
	)
	(segment
		(start 181.63667 -251.235972)
		(end 181.31917 -251.235972)
		(width 0.18288)
		(layer "In11.Cu")
		(net "M_H_CPU1_SB_CA<2>")
	)
	(segment
		(start 202.971146 -251.17044)
		(end 202.843892 -251.297694)
		(width 0.18288)
		(layer "In11.Cu")
		(net "M_H_CPU1_SB_CA<2>")
	)
	(segment
		(start 180.156612 -252.141228)
		(end 179.250086 -252.141228)
		(width 0.18288)
		(layer "In11.Cu")
		(net "M_H_CPU1_SB_CA<2>")
	)
	(segment
		(start 132.598668 -247.66778)
		(end 132.588254 -247.673876)
		(width 0.088646)
		(layer "In11.Cu")
		(net "M_H_CPU1_SB_CA<2>")
	)
	(segment
		(start 197.99808 -252.328172)
		(end 194.989196 -252.328172)
		(width 0.18288)
		(layer "In11.Cu")
		(net "M_H_CPU1_SB_CA<2>")
	)
	(segment
		(start 178.864006 -251.248672)
		(end 178.546506 -251.248672)
		(width 0.18288)
		(layer "In11.Cu")
		(net "M_H_CPU1_SB_CA<2>")
	)
	(segment
		(start 201.879962 -251.964952)
		(end 198.3613 -251.964952)
		(width 0.18288)
		(layer "In11.Cu")
		(net "M_H_CPU1_SB_CA<2>")
	)
	(segment
		(start 128.839214 -247.66778)
		(end 128.824482 -247.676416)
		(width 0.088646)
		(layer "In11.Cu")
		(net "M_H_CPU1_SB_CA<2>")
	)
	(segment
		(start 174.028608 -252.263656)
		(end 173.711108 -252.263656)
		(width 0.18288)
		(layer "In11.Cu")
		(net "M_H_CPU1_SB_CA<2>")
	)
	(segment
		(start 180.93309 -252.341634)
		(end 180.357018 -252.341634)
		(width 0.18288)
		(layer "In11.Cu")
		(net "M_H_CPU1_SB_CA<2>")
	)
	(segment
		(start 136.827768 -248.48185)
		(end 136.803892 -248.495566)
		(width 0.088646)
		(layer "In11.Cu")
		(net "M_H_CPU1_SB_CA<2>")
	)
	(segment
		(start 191.022478 -252.377194)
		(end 189.117224 -252.377194)
		(width 0.18288)
		(layer "In11.Cu")
		(net "M_H_CPU1_SB_CA<2>")
	)
	(segment
		(start 173.518068 -251.488448)
		(end 173.319948 -251.290328)
		(width 0.18288)
		(layer "In11.Cu")
		(net "M_H_CPU1_SB_CA<2>")
	)
	(segment
		(start 188.193172 -253.301246)
		(end 185.82005 -253.301246)
		(width 0.18288)
		(layer "In11.Cu")
		(net "M_H_CPU1_SB_CA<2>")
	)
	(segment
		(start 183.59501 -252.341634)
		(end 182.02275 -252.341634)
		(width 0.18288)
		(layer "In11.Cu")
		(net "M_H_CPU1_SB_CA<2>")
	)
	(segment
		(start 179.250086 -252.141228)
		(end 179.057046 -251.948188)
		(width 0.18288)
		(layer "In11.Cu")
		(net "M_H_CPU1_SB_CA<2>")
	)
	(segment
		(start 202.971146 -250.866656)
		(end 202.971146 -251.17044)
		(width 0.18288)
		(layer "In11.Cu")
		(net "M_H_CPU1_SB_CA<2>")
	)
	(segment
		(start 184.53481 -252.016006)
		(end 183.920638 -252.016006)
		(width 0.18288)
		(layer "In11.Cu")
		(net "M_H_CPU1_SB_CA<2>")
	)
	(segment
		(start 133.160516 -248.01068)
		(end 133.160516 -247.992138)
		(width 0.088646)
		(layer "In11.Cu")
		(net "M_H_CPU1_SB_CA<2>")
	)
	(segment
		(start 175.403764 -251.161804)
		(end 174.871634 -251.161804)
		(width 0.18288)
		(layer "In11.Cu")
		(net "M_H_CPU1_SB_CA<2>")
	)
	(segment
		(start 131.103878 -247.673876)
		(end 131.093464 -247.66778)
		(width 0.088646)
		(layer "In11.Cu")
		(net "M_H_CPU1_SB_CA<2>")
	)
	(segment
		(start 145.580354 -247.93829)
		(end 144.442688 -248.164604)
		(width 0.18288)
		(layer "In11.Cu")
		(net "M_H_CPU1_SB_CA<2>")
	)
	(segment
		(start 127.525272 -246.430292)
		(end 127.459486 -246.364506)
		(width 0.088646)
		(layer "In11.Cu")
		(net "M_H_CPU1_SB_CA<2>")
	)
	(segment
		(start 173.319948 -251.290328)
		(end 171.907708 -251.290328)
		(width 0.18288)
		(layer "In11.Cu")
		(net "M_H_CPU1_SB_CA<2>")
	)
	(segment
		(start 174.221648 -252.070616)
		(end 174.028608 -252.263656)
		(width 0.18288)
		(layer "In11.Cu")
		(net "M_H_CPU1_SB_CA<2>")
	)
	(segment
		(start 127.459486 -246.364506)
		(end 127.146812 -246.364506)
		(width 0.088646)
		(layer "In11.Cu")
		(net "M_H_CPU1_SB_CA<2>")
	)
	(segment
		(start 138.341608 -248.98096)
		(end 138.1125 -248.98096)
		(width 0.18288)
		(layer "In11.Cu")
		(net "M_H_CPU1_SB_CA<2>")
	)
	(segment
		(start 150.792942 -250.497086)
		(end 148.234146 -247.93829)
		(width 0.18288)
		(layer "In11.Cu")
		(net "M_H_CPU1_SB_CA<2>")
	)
	(segment
		(start 181.12613 -251.429012)
		(end 181.12613 -252.148594)
		(width 0.18288)
		(layer "In11.Cu")
		(net "M_H_CPU1_SB_CA<2>")
	)
	(segment
		(start 181.12613 -252.148594)
		(end 180.93309 -252.341634)
		(width 0.18288)
		(layer "In11.Cu")
		(net "M_H_CPU1_SB_CA<2>")
	)
	(segment
		(start 148.234146 -247.93829)
		(end 145.580354 -247.93829)
		(width 0.18288)
		(layer "In11.Cu")
		(net "M_H_CPU1_SB_CA<2>")
	)
	(segment
		(start 181.82971 -252.148594)
		(end 181.82971 -251.429012)
		(width 0.18288)
		(layer "In11.Cu")
		(net "M_H_CPU1_SB_CA<2>")
	)
	(segment
		(start 144.442688 -248.164604)
		(end 140.10386 -249.961654)
		(width 0.18288)
		(layer "In11.Cu")
		(net "M_H_CPU1_SB_CA<2>")
	)
	(segment
		(start 183.920638 -252.016006)
		(end 183.59501 -252.341634)
		(width 0.18288)
		(layer "In11.Cu")
		(net "M_H_CPU1_SB_CA<2>")
	)
	(segment
		(start 136.803892 -248.495566)
		(end 136.780778 -248.506234)
		(width 0.088646)
		(layer "In11.Cu")
		(net "M_H_CPU1_SB_CA<2>")
	)
	(segment
		(start 176.383188 -252.141228)
		(end 175.403764 -251.161804)
		(width 0.18288)
		(layer "In11.Cu")
		(net "M_H_CPU1_SB_CA<2>")
	)
	(segment
		(start 179.057046 -251.441712)
		(end 178.864006 -251.248672)
		(width 0.18288)
		(layer "In11.Cu")
		(net "M_H_CPU1_SB_CA<2>")
	)
	(segment
		(start 191.258444 -252.141228)
		(end 191.022478 -252.377194)
		(width 0.18288)
		(layer "In11.Cu")
		(net "M_H_CPU1_SB_CA<2>")
	)
	(segment
		(start 173.711108 -252.263656)
		(end 173.518068 -252.070616)
		(width 0.18288)
		(layer "In11.Cu")
		(net "M_H_CPU1_SB_CA<2>")
	)
	(arc
		(start 128.824482 -247.676416)
		(mid 128.548007 -247.743736)
		(end 128.27381 -247.66778)
		(width 0.088646)
		(layer "In11.Cu")
		(net "M_H_CPU1_SB_CA<2>")
	)
	(arc
		(start 131.093464 -247.66778)
		(mid 130.906266 -247.617637)
		(end 130.719068 -247.66778)
		(width 0.088646)
		(layer "In11.Cu")
		(net "M_H_CPU1_SB_CA<2>")
	)
	(arc
		(start 130.15341 -247.66778)
		(mid 129.966212 -247.617637)
		(end 129.779014 -247.66778)
		(width 0.088646)
		(layer "In11.Cu")
		(net "M_H_CPU1_SB_CA<2>")
	)
	(arc
		(start 129.764282 -247.676416)
		(mid 129.487807 -247.743736)
		(end 129.21361 -247.66778)
		(width 0.088646)
		(layer "In11.Cu")
		(net "M_H_CPU1_SB_CA<2>")
	)
	(arc
		(start 136.780778 -248.506234)
		(mid 136.518594 -248.557075)
		(end 136.262364 -248.48185)
		(width 0.088646)
		(layer "In11.Cu")
		(net "M_H_CPU1_SB_CA<2>")
	)
	(arc
		(start 136.262364 -248.48185)
		(mid 136.075166 -248.431707)
		(end 135.887968 -248.48185)
		(width 0.088646)
		(layer "In11.Cu")
		(net "M_H_CPU1_SB_CA<2>")
	)
	(arc
		(start 133.160516 -247.992138)
		(mid 133.112837 -247.809238)
		(end 132.981954 -247.67286)
		(width 0.088646)
		(layer "In11.Cu")
		(net "M_H_CPU1_SB_CA<2>")
	)
	(arc
		(start 129.21361 -247.66778)
		(mid 129.026412 -247.617637)
		(end 128.839214 -247.66778)
		(width 0.088646)
		(layer "In11.Cu")
		(net "M_H_CPU1_SB_CA<2>")
	)
	(arc
		(start 137.202164 -248.48185)
		(mid 137.014966 -248.431707)
		(end 136.827768 -248.48185)
		(width 0.088646)
		(layer "In11.Cu")
		(net "M_H_CPU1_SB_CA<2>")
	)
	(arc
		(start 132.03301 -247.66778)
		(mid 131.845812 -247.617637)
		(end 131.658614 -247.66778)
		(width 0.088646)
		(layer "In11.Cu")
		(net "M_H_CPU1_SB_CA<2>")
	)
	(arc
		(start 135.322564 -248.48185)
		(mid 135.135366 -248.431707)
		(end 134.948168 -248.48185)
		(width 0.088646)
		(layer "In11.Cu")
		(net "M_H_CPU1_SB_CA<2>")
	)
	(arc
		(start 127.798068 -246.850408)
		(mid 127.612613 -246.672213)
		(end 127.525272 -246.430292)
		(width 0.088646)
		(layer "In11.Cu")
		(net "M_H_CPU1_SB_CA<2>")
	)
	(arc
		(start 133.442964 -248.48185)
		(mid 133.240678 -248.282869)
		(end 133.160516 -248.01068)
		(width 0.088646)
		(layer "In11.Cu")
		(net "M_H_CPU1_SB_CA<2>")
	)
	(arc
		(start 134.008368 -248.48185)
		(mid 133.725666 -248.557592)
		(end 133.442964 -248.48185)
		(width 0.088646)
		(layer "In11.Cu")
		(net "M_H_CPU1_SB_CA<2>")
	)
	(arc
		(start 134.382764 -248.48185)
		(mid 134.195566 -248.431707)
		(end 134.008368 -248.48185)
		(width 0.088646)
		(layer "In11.Cu")
		(net "M_H_CPU1_SB_CA<2>")
	)
	(arc
		(start 131.658614 -247.66778)
		(mid 131.382055 -247.743523)
		(end 131.103878 -247.673876)
		(width 0.088646)
		(layer "In11.Cu")
		(net "M_H_CPU1_SB_CA<2>")
	)
	(arc
		(start 127.991616 -247.178322)
		(mid 127.943937 -246.995422)
		(end 127.813054 -246.859044)
		(width 0.088646)
		(layer "In11.Cu")
		(net "M_H_CPU1_SB_CA<2>")
	)
	(arc
		(start 134.948168 -248.48185)
		(mid 134.665466 -248.557592)
		(end 134.382764 -248.48185)
		(width 0.088646)
		(layer "In11.Cu")
		(net "M_H_CPU1_SB_CA<2>")
	)
	(arc
		(start 132.973064 -247.66778)
		(mid 132.785866 -247.617637)
		(end 132.598668 -247.66778)
		(width 0.088646)
		(layer "In11.Cu")
		(net "M_H_CPU1_SB_CA<2>")
	)
	(arc
		(start 130.708654 -247.673876)
		(mid 130.430222 -247.743722)
		(end 130.15341 -247.66778)
		(width 0.088646)
		(layer "In11.Cu")
		(net "M_H_CPU1_SB_CA<2>")
	)
	(arc
		(start 137.280142 -248.541032)
		(mid 137.243092 -248.508886)
		(end 137.202164 -248.48185)
		(width 0.088646)
		(layer "In11.Cu")
		(net "M_H_CPU1_SB_CA<2>")
	)
	(arc
		(start 135.887968 -248.48185)
		(mid 135.605266 -248.557592)
		(end 135.322564 -248.48185)
		(width 0.088646)
		(layer "In11.Cu")
		(net "M_H_CPU1_SB_CA<2>")
	)
	(arc
		(start 128.27381 -247.66778)
		(mid 128.070987 -247.467549)
		(end 127.991616 -247.193816)
		(width 0.088646)
		(layer "In11.Cu")
		(net "M_H_CPU1_SB_CA<2>")
	)
	(arc
		(start 132.588254 -247.673876)
		(mid 132.309822 -247.743722)
		(end 132.03301 -247.66778)
		(width 0.088646)
		(layer "In11.Cu")
		(net "M_H_CPU1_SB_CA<2>")
	)
	(segment
		(start 207.071214 -251.716794)
		(end 208.176114 -251.716794)
		(width 0.20066)
		(layer "F.Cu")
		(net "M_H_CPU1_SB_CA<1>")
	)
	(segment
		(start 208.176114 -251.716794)
		(end 209.811874 -251.716794)
		(width 0.20066)
		(layer "F.Cu")
		(net "M_H_CPU1_SB_CA<1>")
	)
	(segment
		(start 125.267212 -246.900192)
		(end 125.267212 -246.364506)
		(width 0.20066)
		(layer "F.Cu")
		(net "M_H_CPU1_SB_CA<1>")
	)
	(segment
		(start 212.904324 -252.149102)
		(end 213.769194 -251.284232)
		(width 0.20066)
		(layer "F.Cu")
		(net "M_H_CPU1_SB_CA<1>")
	)
	(segment
		(start 125.267466 -246.900446)
		(end 125.267212 -246.900192)
		(width 0.20066)
		(layer "F.Cu")
		(net "M_H_CPU1_SB_CA<1>")
	)
	(segment
		(start 212.622892 -252.141736)
		(end 212.630258 -252.149102)
		(width 0.1016)
		(layer "F.Cu")
		(net "M_H_CPU1_SB_CA<1>")
	)
	(segment
		(start 210.247484 -252.152404)
		(end 210.598258 -252.152404)
		(width 0.20066)
		(layer "F.Cu")
		(net "M_H_CPU1_SB_CA<1>")
	)
	(segment
		(start 213.769194 -251.284232)
		(end 214.1728 -251.284232)
		(width 0.20066)
		(layer "F.Cu")
		(net "M_H_CPU1_SB_CA<1>")
	)
	(segment
		(start 214.605362 -251.716794)
		(end 215.719914 -251.716794)
		(width 0.20066)
		(layer "F.Cu")
		(net "M_H_CPU1_SB_CA<1>")
	)
	(segment
		(start 210.598258 -252.152404)
		(end 210.603084 -252.152404)
		(width 0.101854)
		(layer "F.Cu")
		(net "M_H_CPU1_SB_CA<1>")
	)
	(segment
		(start 214.1728 -251.284232)
		(end 214.605362 -251.716794)
		(width 0.20066)
		(layer "F.Cu")
		(net "M_H_CPU1_SB_CA<1>")
	)
	(segment
		(start 210.613752 -252.141736)
		(end 212.622892 -252.141736)
		(width 0.1016)
		(layer "F.Cu")
		(net "M_H_CPU1_SB_CA<1>")
	)
	(segment
		(start 210.603084 -252.152404)
		(end 210.613752 -252.141736)
		(width 0.1016)
		(layer "F.Cu")
		(net "M_H_CPU1_SB_CA<1>")
	)
	(segment
		(start 212.630258 -252.149102)
		(end 212.904324 -252.149102)
		(width 0.20066)
		(layer "F.Cu")
		(net "M_H_CPU1_SB_CA<1>")
	)
	(segment
		(start 209.811874 -251.716794)
		(end 210.247484 -252.152404)
		(width 0.20066)
		(layer "F.Cu")
		(net "M_H_CPU1_SB_CA<1>")
	)
	(segment
		(start 162.462464 -251.912374)
		(end 160.571942 -251.912374)
		(width 0.18288)
		(layer "In11.Cu")
		(net "M_H_CPU1_SB_CA<1>")
	)
	(segment
		(start 207.071214 -251.716794)
		(end 206.409544 -252.378464)
		(width 0.18288)
		(layer "In11.Cu")
		(net "M_H_CPU1_SB_CA<1>")
	)
	(segment
		(start 144.642078 -248.480326)
		(end 140.199618 -250.320556)
		(width 0.18288)
		(layer "In11.Cu")
		(net "M_H_CPU1_SB_CA<1>")
	)
	(segment
		(start 138.928348 -250.320556)
		(end 138.292586 -249.684794)
		(width 0.18288)
		(layer "In11.Cu")
		(net "M_H_CPU1_SB_CA<1>")
	)
	(segment
		(start 150.596346 -251.021088)
		(end 147.858988 -248.28373)
		(width 0.18288)
		(layer "In11.Cu")
		(net "M_H_CPU1_SB_CA<1>")
	)
	(segment
		(start 127.899414 -248.316496)
		(end 127.884682 -248.30786)
		(width 0.088646)
		(layer "In11.Cu")
		(net "M_H_CPU1_SB_CA<1>")
	)
	(segment
		(start 126.02591 -246.69242)
		(end 126.010924 -246.683784)
		(width 0.088646)
		(layer "In11.Cu")
		(net "M_H_CPU1_SB_CA<1>")
	)
	(segment
		(start 160.137348 -252.346968)
		(end 156.807662 -252.346968)
		(width 0.18288)
		(layer "In11.Cu")
		(net "M_H_CPU1_SB_CA<1>")
	)
	(segment
		(start 171.458128 -252.363732)
		(end 166.929308 -252.363732)
		(width 0.18288)
		(layer "In11.Cu")
		(net "M_H_CPU1_SB_CA<1>")
	)
	(segment
		(start 145.6309 -248.28373)
		(end 144.642078 -248.480326)
		(width 0.18288)
		(layer "In11.Cu")
		(net "M_H_CPU1_SB_CA<1>")
	)
	(segment
		(start 172.164502 -253.070106)
		(end 171.458128 -252.363732)
		(width 0.18288)
		(layer "In11.Cu")
		(net "M_H_CPU1_SB_CA<1>")
	)
	(segment
		(start 135.915654 -249.460258)
		(end 135.305292 -249.460258)
		(width 0.088646)
		(layer "In11.Cu")
		(net "M_H_CPU1_SB_CA<1>")
	)
	(segment
		(start 136.155938 -249.219974)
		(end 135.915654 -249.460258)
		(width 0.088646)
		(layer "In11.Cu")
		(net "M_H_CPU1_SB_CA<1>")
	)
	(segment
		(start 163.267898 -252.717808)
		(end 162.462464 -251.912374)
		(width 0.18288)
		(layer "In11.Cu")
		(net "M_H_CPU1_SB_CA<1>")
	)
	(segment
		(start 126.772416 -248.000774)
		(end 126.772416 -247.992138)
		(width 0.088646)
		(layer "In11.Cu")
		(net "M_H_CPU1_SB_CA<1>")
	)
	(segment
		(start 130.719068 -248.316496)
		(end 130.708654 -248.3104)
		(width 0.088646)
		(layer "In11.Cu")
		(net "M_H_CPU1_SB_CA<1>")
	)
	(segment
		(start 185.701178 -253.90348)
		(end 184.867804 -253.070106)
		(width 0.18288)
		(layer "In11.Cu")
		(net "M_H_CPU1_SB_CA<1>")
	)
	(segment
		(start 136.960102 -249.219974)
		(end 136.155938 -249.219974)
		(width 0.088646)
		(layer "In11.Cu")
		(net "M_H_CPU1_SB_CA<1>")
	)
	(segment
		(start 132.881116 -248.806208)
		(end 132.881116 -248.787666)
		(width 0.088646)
		(layer "In11.Cu")
		(net "M_H_CPU1_SB_CA<1>")
	)
	(segment
		(start 189.443868 -253.016004)
		(end 188.556392 -253.90348)
		(width 0.18288)
		(layer "In11.Cu")
		(net "M_H_CPU1_SB_CA<1>")
	)
	(segment
		(start 160.571942 -251.912374)
		(end 160.137348 -252.346968)
		(width 0.18288)
		(layer "In11.Cu")
		(net "M_H_CPU1_SB_CA<1>")
	)
	(segment
		(start 166.929308 -252.363732)
		(end 166.575232 -252.717808)
		(width 0.18288)
		(layer "In11.Cu")
		(net "M_H_CPU1_SB_CA<1>")
	)
	(segment
		(start 138.292586 -249.684794)
		(end 138.07694 -249.684794)
		(width 0.18288)
		(layer "In11.Cu")
		(net "M_H_CPU1_SB_CA<1>")
	)
	(segment
		(start 126.302516 -247.186958)
		(end 126.302516 -247.178322)
		(width 0.088646)
		(layer "In11.Cu")
		(net "M_H_CPU1_SB_CA<1>")
	)
	(segment
		(start 206.409544 -252.378464)
		(end 203.914248 -252.378464)
		(width 0.18288)
		(layer "In11.Cu")
		(net "M_H_CPU1_SB_CA<1>")
	)
	(segment
		(start 188.556392 -253.90348)
		(end 185.701178 -253.90348)
		(width 0.18288)
		(layer "In11.Cu")
		(net "M_H_CPU1_SB_CA<1>")
	)
	(segment
		(start 166.575232 -252.717808)
		(end 163.267898 -252.717808)
		(width 0.18288)
		(layer "In11.Cu")
		(net "M_H_CPU1_SB_CA<1>")
	)
	(segment
		(start 201.806048 -253.016004)
		(end 189.443868 -253.016004)
		(width 0.18288)
		(layer "In11.Cu")
		(net "M_H_CPU1_SB_CA<1>")
	)
	(segment
		(start 202.680824 -252.141228)
		(end 201.806048 -253.016004)
		(width 0.18288)
		(layer "In11.Cu")
		(net "M_H_CPU1_SB_CA<1>")
	)
	(segment
		(start 203.677012 -252.141228)
		(end 202.680824 -252.141228)
		(width 0.18288)
		(layer "In11.Cu")
		(net "M_H_CPU1_SB_CA<1>")
	)
	(segment
		(start 140.199618 -250.320556)
		(end 138.928348 -250.320556)
		(width 0.18288)
		(layer "In11.Cu")
		(net "M_H_CPU1_SB_CA<1>")
	)
	(segment
		(start 184.867804 -253.070106)
		(end 172.164502 -253.070106)
		(width 0.18288)
		(layer "In11.Cu")
		(net "M_H_CPU1_SB_CA<1>")
	)
	(segment
		(start 138.07694 -249.684794)
		(end 137.424922 -249.684794)
		(width 0.088646)
		(layer "In11.Cu")
		(net "M_H_CPU1_SB_CA<1>")
	)
	(segment
		(start 153.6065 -251.021088)
		(end 150.596346 -251.021088)
		(width 0.18288)
		(layer "In11.Cu")
		(net "M_H_CPU1_SB_CA<1>")
	)
	(segment
		(start 131.658614 -248.316496)
		(end 131.6482 -248.3104)
		(width 0.088646)
		(layer "In11.Cu")
		(net "M_H_CPU1_SB_CA<1>")
	)
	(segment
		(start 156.807662 -252.346968)
		(end 153.6065 -251.021088)
		(width 0.18288)
		(layer "In11.Cu")
		(net "M_H_CPU1_SB_CA<1>")
	)
	(segment
		(start 125.60046 -246.364506)
		(end 125.267212 -246.364506)
		(width 0.088646)
		(layer "In11.Cu")
		(net "M_H_CPU1_SB_CA<1>")
	)
	(segment
		(start 132.598668 -248.316496)
		(end 132.588254 -248.3104)
		(width 0.088646)
		(layer "In11.Cu")
		(net "M_H_CPU1_SB_CA<1>")
	)
	(segment
		(start 203.914248 -252.378464)
		(end 203.677012 -252.141228)
		(width 0.18288)
		(layer "In11.Cu")
		(net "M_H_CPU1_SB_CA<1>")
	)
	(segment
		(start 137.424922 -249.684794)
		(end 136.960102 -249.219974)
		(width 0.088646)
		(layer "In11.Cu")
		(net "M_H_CPU1_SB_CA<1>")
	)
	(segment
		(start 133.068568 -249.130566)
		(end 133.059678 -249.125486)
		(width 0.088646)
		(layer "In11.Cu")
		(net "M_H_CPU1_SB_CA<1>")
	)
	(segment
		(start 135.305292 -249.460258)
		(end 135.065262 -249.220228)
		(width 0.088646)
		(layer "In11.Cu")
		(net "M_H_CPU1_SB_CA<1>")
	)
	(segment
		(start 147.858988 -248.28373)
		(end 145.6309 -248.28373)
		(width 0.18288)
		(layer "In11.Cu")
		(net "M_H_CPU1_SB_CA<1>")
	)
	(segment
		(start 126.49581 -247.506236)
		(end 126.489714 -247.50268)
		(width 0.088646)
		(layer "In11.Cu")
		(net "M_H_CPU1_SB_CA<1>")
	)
	(segment
		(start 128.839214 -248.316496)
		(end 128.824482 -248.30786)
		(width 0.088646)
		(layer "In11.Cu")
		(net "M_H_CPU1_SB_CA<1>")
	)
	(arc
		(start 126.302516 -247.178322)
		(mid 126.228525 -246.898756)
		(end 126.02591 -246.69242)
		(width 0.088646)
		(layer "In11.Cu")
		(net "M_H_CPU1_SB_CA<1>")
	)
	(arc
		(start 127.884682 -248.30786)
		(mid 127.608241 -248.240694)
		(end 127.33401 -248.316496)
		(width 0.088646)
		(layer "In11.Cu")
		(net "M_H_CPU1_SB_CA<1>")
	)
	(arc
		(start 128.27381 -248.316496)
		(mid 128.086612 -248.366639)
		(end 127.899414 -248.316496)
		(width 0.088646)
		(layer "In11.Cu")
		(net "M_H_CPU1_SB_CA<1>")
	)
	(arc
		(start 126.010924 -246.683784)
		(mid 125.930822 -246.617702)
		(end 125.871986 -246.532146)
		(width 0.088646)
		(layer "In11.Cu")
		(net "M_H_CPU1_SB_CA<1>")
	)
	(arc
		(start 125.871986 -246.532146)
		(mid 125.760019 -246.409818)
		(end 125.60046 -246.364506)
		(width 0.088646)
		(layer "In11.Cu")
		(net "M_H_CPU1_SB_CA<1>")
	)
	(arc
		(start 133.059678 -249.125486)
		(mid 132.928764 -248.989126)
		(end 132.881116 -248.806208)
		(width 0.088646)
		(layer "In11.Cu")
		(net "M_H_CPU1_SB_CA<1>")
	)
	(arc
		(start 132.881116 -248.787666)
		(mid 132.800954 -248.515477)
		(end 132.598668 -248.316496)
		(width 0.088646)
		(layer "In11.Cu")
		(net "M_H_CPU1_SB_CA<1>")
	)
	(arc
		(start 130.708654 -248.3104)
		(mid 130.430222 -248.240586)
		(end 130.15341 -248.316496)
		(width 0.088646)
		(layer "In11.Cu")
		(net "M_H_CPU1_SB_CA<1>")
	)
	(arc
		(start 134.008368 -249.130566)
		(mid 133.725666 -249.05479)
		(end 133.442964 -249.130566)
		(width 0.088646)
		(layer "In11.Cu")
		(net "M_H_CPU1_SB_CA<1>")
	)
	(arc
		(start 133.442964 -249.130566)
		(mid 133.255766 -249.180709)
		(end 133.068568 -249.130566)
		(width 0.088646)
		(layer "In11.Cu")
		(net "M_H_CPU1_SB_CA<1>")
	)
	(arc
		(start 129.779014 -248.316496)
		(mid 129.496312 -248.240754)
		(end 129.21361 -248.316496)
		(width 0.088646)
		(layer "In11.Cu")
		(net "M_H_CPU1_SB_CA<1>")
	)
	(arc
		(start 126.959614 -248.316496)
		(mid 126.824681 -248.183142)
		(end 126.772416 -248.000774)
		(width 0.088646)
		(layer "In11.Cu")
		(net "M_H_CPU1_SB_CA<1>")
	)
	(arc
		(start 126.772416 -247.992138)
		(mid 126.698425 -247.712572)
		(end 126.49581 -247.506236)
		(width 0.088646)
		(layer "In11.Cu")
		(net "M_H_CPU1_SB_CA<1>")
	)
	(arc
		(start 129.21361 -248.316496)
		(mid 129.026412 -248.366639)
		(end 128.839214 -248.316496)
		(width 0.088646)
		(layer "In11.Cu")
		(net "M_H_CPU1_SB_CA<1>")
	)
	(arc
		(start 128.824482 -248.30786)
		(mid 128.548041 -248.240694)
		(end 128.27381 -248.316496)
		(width 0.088646)
		(layer "In11.Cu")
		(net "M_H_CPU1_SB_CA<1>")
	)
	(arc
		(start 134.382764 -249.130566)
		(mid 134.195566 -249.180709)
		(end 134.008368 -249.130566)
		(width 0.088646)
		(layer "In11.Cu")
		(net "M_H_CPU1_SB_CA<1>")
	)
	(arc
		(start 130.15341 -248.316496)
		(mid 129.966212 -248.366639)
		(end 129.779014 -248.316496)
		(width 0.088646)
		(layer "In11.Cu")
		(net "M_H_CPU1_SB_CA<1>")
	)
	(arc
		(start 132.588254 -248.3104)
		(mid 132.309822 -248.240586)
		(end 132.03301 -248.316496)
		(width 0.088646)
		(layer "In11.Cu")
		(net "M_H_CPU1_SB_CA<1>")
	)
	(arc
		(start 126.489714 -247.50268)
		(mid 126.354781 -247.369326)
		(end 126.302516 -247.186958)
		(width 0.088646)
		(layer "In11.Cu")
		(net "M_H_CPU1_SB_CA<1>")
	)
	(arc
		(start 131.093464 -248.316496)
		(mid 130.906266 -248.366639)
		(end 130.719068 -248.316496)
		(width 0.088646)
		(layer "In11.Cu")
		(net "M_H_CPU1_SB_CA<1>")
	)
	(arc
		(start 135.065262 -249.220228)
		(mid 135.009657 -249.171554)
		(end 134.948168 -249.130566)
		(width 0.088646)
		(layer "In11.Cu")
		(net "M_H_CPU1_SB_CA<1>")
	)
	(arc
		(start 127.33401 -248.316496)
		(mid 127.146812 -248.366639)
		(end 126.959614 -248.316496)
		(width 0.088646)
		(layer "In11.Cu")
		(net "M_H_CPU1_SB_CA<1>")
	)
	(arc
		(start 131.6482 -248.3104)
		(mid 131.370022 -248.240708)
		(end 131.093464 -248.316496)
		(width 0.088646)
		(layer "In11.Cu")
		(net "M_H_CPU1_SB_CA<1>")
	)
	(arc
		(start 134.948168 -249.130566)
		(mid 134.665466 -249.05479)
		(end 134.382764 -249.130566)
		(width 0.088646)
		(layer "In11.Cu")
		(net "M_H_CPU1_SB_CA<1>")
	)
	(arc
		(start 132.03301 -248.316496)
		(mid 131.845812 -248.366639)
		(end 131.658614 -248.316496)
		(width 0.088646)
		(layer "In11.Cu")
		(net "M_H_CPU1_SB_CA<1>")
	)
	(segment
		(start 205.298294 -252.566678)
		(end 205.60284 -252.262132)
		(width 0.20066)
		(layer "F.Cu")
		(net "M_H_CPU1_SB_CA<0>")
	)
	(segment
		(start 210.518756 -252.566678)
		(end 211.619846 -252.566678)
		(width 0.20066)
		(layer "F.Cu")
		(net "M_H_CPU1_SB_CA<0>")
	)
	(segment
		(start 124.797566 -246.086376)
		(end 124.797566 -245.55069)
		(width 0.20066)
		(layer "F.Cu")
		(net "M_H_CPU1_SB_CA<0>")
	)
	(segment
		(start 207.066388 -253.17958)
		(end 209.905854 -253.17958)
		(width 0.20066)
		(layer "F.Cu")
		(net "M_H_CPU1_SB_CA<0>")
	)
	(segment
		(start 206.14894 -252.262132)
		(end 207.066388 -253.17958)
		(width 0.20066)
		(layer "F.Cu")
		(net "M_H_CPU1_SB_CA<0>")
	)
	(segment
		(start 202.971146 -252.566678)
		(end 204.076046 -252.566678)
		(width 0.20066)
		(layer "F.Cu")
		(net "M_H_CPU1_SB_CA<0>")
	)
	(segment
		(start 204.076046 -252.566678)
		(end 205.298294 -252.566678)
		(width 0.20066)
		(layer "F.Cu")
		(net "M_H_CPU1_SB_CA<0>")
	)
	(segment
		(start 205.60284 -252.262132)
		(end 206.14894 -252.262132)
		(width 0.20066)
		(layer "F.Cu")
		(net "M_H_CPU1_SB_CA<0>")
	)
	(segment
		(start 209.905854 -253.17958)
		(end 210.518756 -252.566678)
		(width 0.20066)
		(layer "F.Cu")
		(net "M_H_CPU1_SB_CA<0>")
	)
	(segment
		(start 124.797312 -246.08663)
		(end 124.797566 -246.086376)
		(width 0.20066)
		(layer "F.Cu")
		(net "M_H_CPU1_SB_CA<0>")
	)
	(segment
		(start 126.394464 -247.66778)
		(end 126.388368 -247.664224)
		(width 0.088646)
		(layer "In11.Cu")
		(net "M_H_CPU1_SB_CA<0>")
	)
	(segment
		(start 131.578096 -248.490486)
		(end 131.563364 -248.48185)
		(width 0.088646)
		(layer "In11.Cu")
		(net "M_H_CPU1_SB_CA<0>")
	)
	(segment
		(start 137.773156 -250.684284)
		(end 137.294366 -250.205494)
		(width 0.18288)
		(layer "In11.Cu")
		(net "M_H_CPU1_SB_CA<0>")
	)
	(segment
		(start 126.879096 -248.490486)
		(end 126.864364 -248.48185)
		(width 0.088646)
		(layer "In11.Cu")
		(net "M_H_CPU1_SB_CA<0>")
	)
	(segment
		(start 202.741276 -255.541526)
		(end 202.39355 -255.541526)
		(width 0.18288)
		(layer "In11.Cu")
		(net "M_H_CPU1_SB_CA<0>")
	)
	(segment
		(start 124.797566 -246.422672)
		(end 124.797566 -245.55069)
		(width 0.088646)
		(layer "In11.Cu")
		(net "M_H_CPU1_SB_CA<0>")
	)
	(segment
		(start 126.581662 -248.006362)
		(end 126.581662 -247.983502)
		(width 0.088646)
		(layer "In11.Cu")
		(net "M_H_CPU1_SB_CA<0>")
	)
	(segment
		(start 144.793462 -248.802652)
		(end 140.250926 -250.684284)
		(width 0.18288)
		(layer "In11.Cu")
		(net "M_H_CPU1_SB_CA<0>")
	)
	(segment
		(start 167.03548 -253.090172)
		(end 166.840662 -253.28499)
		(width 0.18288)
		(layer "In11.Cu")
		(net "M_H_CPU1_SB_CA<0>")
	)
	(segment
		(start 137.294366 -250.205494)
		(end 137.10412 -250.015248)
		(width 0.088646)
		(layer "In11.Cu")
		(net "M_H_CPU1_SB_CA<0>")
	)
	(segment
		(start 132.512054 -248.48693)
		(end 132.503164 -248.48185)
		(width 0.088646)
		(layer "In11.Cu")
		(net "M_H_CPU1_SB_CA<0>")
	)
	(segment
		(start 132.690616 -248.816114)
		(end 132.690616 -248.806208)
		(width 0.088646)
		(layer "In11.Cu")
		(net "M_H_CPU1_SB_CA<0>")
	)
	(segment
		(start 128.754378 -248.487946)
		(end 128.743964 -248.48185)
		(width 0.088646)
		(layer "In11.Cu")
		(net "M_H_CPU1_SB_CA<0>")
	)
	(segment
		(start 202.094592 -255.242568)
		(end 173.61027 -255.242568)
		(width 0.18288)
		(layer "In11.Cu")
		(net "M_H_CPU1_SB_CA<0>")
	)
	(segment
		(start 202.971146 -255.311656)
		(end 202.741276 -255.541526)
		(width 0.18288)
		(layer "In11.Cu")
		(net "M_H_CPU1_SB_CA<0>")
	)
	(segment
		(start 163.030408 -253.28499)
		(end 162.810444 -253.065026)
		(width 0.18288)
		(layer "In11.Cu")
		(net "M_H_CPU1_SB_CA<0>")
	)
	(segment
		(start 166.840662 -253.28499)
		(end 163.030408 -253.28499)
		(width 0.18288)
		(layer "In11.Cu")
		(net "M_H_CPU1_SB_CA<0>")
	)
	(segment
		(start 145.665952 -248.62917)
		(end 144.793462 -248.802652)
		(width 0.18288)
		(layer "In11.Cu")
		(net "M_H_CPU1_SB_CA<0>")
	)
	(segment
		(start 153.520902 -251.5616)
		(end 150.400004 -251.5616)
		(width 0.18288)
		(layer "In11.Cu")
		(net "M_H_CPU1_SB_CA<0>")
	)
	(segment
		(start 140.250926 -250.684284)
		(end 137.773156 -250.684284)
		(width 0.18288)
		(layer "In11.Cu")
		(net "M_H_CPU1_SB_CA<0>")
	)
	(segment
		(start 135.591042 -250.015248)
		(end 134.930642 -249.354848)
		(width 0.088646)
		(layer "In11.Cu")
		(net "M_H_CPU1_SB_CA<0>")
	)
	(segment
		(start 202.971146 -252.566678)
		(end 202.971146 -255.311656)
		(width 0.18288)
		(layer "In11.Cu")
		(net "M_H_CPU1_SB_CA<0>")
	)
	(segment
		(start 137.10412 -250.015248)
		(end 135.591042 -250.015248)
		(width 0.088646)
		(layer "In11.Cu")
		(net "M_H_CPU1_SB_CA<0>")
	)
	(segment
		(start 162.810444 -253.065026)
		(end 157.150562 -253.065026)
		(width 0.18288)
		(layer "In11.Cu")
		(net "M_H_CPU1_SB_CA<0>")
	)
	(segment
		(start 127.818896 -248.490486)
		(end 127.804164 -248.48185)
		(width 0.088646)
		(layer "In11.Cu")
		(net "M_H_CPU1_SB_CA<0>")
	)
	(segment
		(start 129.693924 -248.487946)
		(end 129.68351 -248.48185)
		(width 0.088646)
		(layer "In11.Cu")
		(net "M_H_CPU1_SB_CA<0>")
	)
	(segment
		(start 147.467574 -248.62917)
		(end 145.665952 -248.62917)
		(width 0.18288)
		(layer "In11.Cu")
		(net "M_H_CPU1_SB_CA<0>")
	)
	(segment
		(start 171.457874 -253.090172)
		(end 167.03548 -253.090172)
		(width 0.18288)
		(layer "In11.Cu")
		(net "M_H_CPU1_SB_CA<0>")
	)
	(segment
		(start 126.111762 -247.178322)
		(end 126.111762 -247.169686)
		(width 0.088646)
		(layer "In11.Cu")
		(net "M_H_CPU1_SB_CA<0>")
	)
	(segment
		(start 157.150562 -253.065026)
		(end 153.520902 -251.5616)
		(width 0.18288)
		(layer "In11.Cu")
		(net "M_H_CPU1_SB_CA<0>")
	)
	(segment
		(start 150.400004 -251.5616)
		(end 147.467574 -248.62917)
		(width 0.18288)
		(layer "In11.Cu")
		(net "M_H_CPU1_SB_CA<0>")
	)
	(segment
		(start 202.39355 -255.541526)
		(end 202.094592 -255.242568)
		(width 0.18288)
		(layer "In11.Cu")
		(net "M_H_CPU1_SB_CA<0>")
	)
	(segment
		(start 173.61027 -255.242568)
		(end 171.457874 -253.090172)
		(width 0.18288)
		(layer "In11.Cu")
		(net "M_H_CPU1_SB_CA<0>")
	)
	(arc
		(start 133.912864 -249.295666)
		(mid 133.725666 -249.245523)
		(end 133.538468 -249.295666)
		(width 0.088646)
		(layer "In11.Cu")
		(net "M_H_CPU1_SB_CA<0>")
	)
	(arc
		(start 128.743964 -248.48185)
		(mid 128.556766 -248.431707)
		(end 128.369568 -248.48185)
		(width 0.088646)
		(layer "In11.Cu")
		(net "M_H_CPU1_SB_CA<0>")
	)
	(arc
		(start 132.128768 -248.48185)
		(mid 131.854539 -248.557775)
		(end 131.578096 -248.490486)
		(width 0.088646)
		(layer "In11.Cu")
		(net "M_H_CPU1_SB_CA<0>")
	)
	(arc
		(start 128.369568 -248.48185)
		(mid 128.095339 -248.557775)
		(end 127.818896 -248.490486)
		(width 0.088646)
		(layer "In11.Cu")
		(net "M_H_CPU1_SB_CA<0>")
	)
	(arc
		(start 125.910086 -246.84609)
		(mid 125.728386 -246.803983)
		(end 125.548898 -246.854726)
		(width 0.088646)
		(layer "In11.Cu")
		(net "M_H_CPU1_SB_CA<0>")
	)
	(arc
		(start 134.852664 -249.295666)
		(mid 134.665466 -249.245523)
		(end 134.478268 -249.295666)
		(width 0.088646)
		(layer "In11.Cu")
		(net "M_H_CPU1_SB_CA<0>")
	)
	(arc
		(start 129.309114 -248.48185)
		(mid 129.032555 -248.557559)
		(end 128.754378 -248.487946)
		(width 0.088646)
		(layer "In11.Cu")
		(net "M_H_CPU1_SB_CA<0>")
	)
	(arc
		(start 131.563364 -248.48185)
		(mid 131.376166 -248.431707)
		(end 131.188968 -248.48185)
		(width 0.088646)
		(layer "In11.Cu")
		(net "M_H_CPU1_SB_CA<0>")
	)
	(arc
		(start 127.804164 -248.48185)
		(mid 127.616966 -248.431707)
		(end 127.429768 -248.48185)
		(width 0.088646)
		(layer "In11.Cu")
		(net "M_H_CPU1_SB_CA<0>")
	)
	(arc
		(start 132.503164 -248.48185)
		(mid 132.315966 -248.431707)
		(end 132.128768 -248.48185)
		(width 0.088646)
		(layer "In11.Cu")
		(net "M_H_CPU1_SB_CA<0>")
	)
	(arc
		(start 131.188968 -248.48185)
		(mid 130.906266 -248.557592)
		(end 130.623564 -248.48185)
		(width 0.088646)
		(layer "In11.Cu")
		(net "M_H_CPU1_SB_CA<0>")
	)
	(arc
		(start 126.581662 -247.983502)
		(mid 126.529392 -247.801137)
		(end 126.394464 -247.66778)
		(width 0.088646)
		(layer "In11.Cu")
		(net "M_H_CPU1_SB_CA<0>")
	)
	(arc
		(start 129.68351 -248.48185)
		(mid 129.496312 -248.431707)
		(end 129.309114 -248.48185)
		(width 0.088646)
		(layer "In11.Cu")
		(net "M_H_CPU1_SB_CA<0>")
	)
	(arc
		(start 126.111762 -247.169686)
		(mid 126.059492 -246.987321)
		(end 125.924564 -246.853964)
		(width 0.088646)
		(layer "In11.Cu")
		(net "M_H_CPU1_SB_CA<0>")
	)
	(arc
		(start 133.538468 -249.295666)
		(mid 133.255766 -249.371442)
		(end 132.973064 -249.295666)
		(width 0.088646)
		(layer "In11.Cu")
		(net "M_H_CPU1_SB_CA<0>")
	)
	(arc
		(start 132.690616 -248.806208)
		(mid 132.642937 -248.623308)
		(end 132.512054 -248.48693)
		(width 0.088646)
		(layer "In11.Cu")
		(net "M_H_CPU1_SB_CA<0>")
	)
	(arc
		(start 126.388368 -247.664224)
		(mid 126.185781 -247.457873)
		(end 126.111762 -247.178322)
		(width 0.088646)
		(layer "In11.Cu")
		(net "M_H_CPU1_SB_CA<0>")
	)
	(arc
		(start 127.429768 -248.48185)
		(mid 127.155539 -248.557775)
		(end 126.879096 -248.490486)
		(width 0.088646)
		(layer "In11.Cu")
		(net "M_H_CPU1_SB_CA<0>")
	)
	(arc
		(start 126.864364 -248.48185)
		(mid 126.660883 -248.281046)
		(end 126.581662 -248.006362)
		(width 0.088646)
		(layer "In11.Cu")
		(net "M_H_CPU1_SB_CA<0>")
	)
	(arc
		(start 134.478268 -249.295666)
		(mid 134.195566 -249.371442)
		(end 133.912864 -249.295666)
		(width 0.088646)
		(layer "In11.Cu")
		(net "M_H_CPU1_SB_CA<0>")
	)
	(arc
		(start 130.623564 -248.48185)
		(mid 130.436366 -248.431707)
		(end 130.249168 -248.48185)
		(width 0.088646)
		(layer "In11.Cu")
		(net "M_H_CPU1_SB_CA<0>")
	)
	(arc
		(start 132.973064 -249.295666)
		(mid 132.768729 -249.093061)
		(end 132.690616 -248.816114)
		(width 0.088646)
		(layer "In11.Cu")
		(net "M_H_CPU1_SB_CA<0>")
	)
	(arc
		(start 134.930642 -249.354848)
		(mid 134.893592 -249.322702)
		(end 134.852664 -249.295666)
		(width 0.088646)
		(layer "In11.Cu")
		(net "M_H_CPU1_SB_CA<0>")
	)
	(arc
		(start 125.924564 -246.853964)
		(mid 125.917382 -246.849922)
		(end 125.910086 -246.84609)
		(width 0.088646)
		(layer "In11.Cu")
		(net "M_H_CPU1_SB_CA<0>")
	)
	(arc
		(start 130.249168 -248.48185)
		(mid 129.972355 -248.557686)
		(end 129.693924 -248.487946)
		(width 0.088646)
		(layer "In11.Cu")
		(net "M_H_CPU1_SB_CA<0>")
	)
	(arc
		(start 125.548898 -246.854726)
		(mid 125.048297 -246.856068)
		(end 124.797566 -246.422672)
		(width 0.088646)
		(layer "In11.Cu")
		(net "M_H_CPU1_SB_CA<0>")
	)
	(segment
		(start 135.245094 -253.383796)
		(end 135.245094 -253.919736)
		(width 0.20066)
		(layer "F.Cu")
		(net "M_H_CPU1_SA_RSP<1>")
	)
	(segment
		(start 202.971146 -244.066568)
		(end 204.076046 -244.066568)
		(width 0.20066)
		(layer "F.Cu")
		(net "M_H_CPU1_SA_RSP<1>")
	)
	(segment
		(start 135.527796 -255.05791)
		(end 135.518906 -255.05283)
		(width 0.088646)
		(layer "In6.Cu")
		(net "M_H_CPU1_SA_RSP<1>")
	)
	(segment
		(start 138.347196 -255.05791)
		(end 138.332464 -255.049274)
		(width 0.088646)
		(layer "In6.Cu")
		(net "M_H_CPU1_SA_RSP<1>")
	)
	(segment
		(start 185.376058 -253.05766)
		(end 185.144156 -253.289562)
		(width 0.18288)
		(layer "In6.Cu")
		(net "M_H_CPU1_SA_RSP<1>")
	)
	(segment
		(start 200.31583 -246.150892)
		(end 195.780406 -248.602246)
		(width 0.18288)
		(layer "In6.Cu")
		(net "M_H_CPU1_SA_RSP<1>")
	)
	(segment
		(start 195.780406 -248.602246)
		(end 193.940176 -250.442476)
		(width 0.18288)
		(layer "In6.Cu")
		(net "M_H_CPU1_SA_RSP<1>")
	)
	(segment
		(start 185.63463 -253.05766)
		(end 185.376058 -253.05766)
		(width 0.18288)
		(layer "In6.Cu")
		(net "M_H_CPU1_SA_RSP<1>")
	)
	(segment
		(start 187.186062 -253.886716)
		(end 186.95416 -254.118618)
		(width 0.18288)
		(layer "In6.Cu")
		(net "M_H_CPU1_SA_RSP<1>")
	)
	(segment
		(start 186.125104 -252.567186)
		(end 187.186062 -253.628144)
		(width 0.18288)
		(layer "In6.Cu")
		(net "M_H_CPU1_SA_RSP<1>")
	)
	(segment
		(start 148.678392 -256.59842)
		(end 145.741644 -256.59842)
		(width 0.18288)
		(layer "In6.Cu")
		(net "M_H_CPU1_SA_RSP<1>")
	)
	(segment
		(start 187.676536 -253.13767)
		(end 186.615578 -252.076712)
		(width 0.18288)
		(layer "In6.Cu")
		(net "M_H_CPU1_SA_RSP<1>")
	)
	(segment
		(start 186.205114 -254.609092)
		(end 186.205114 -254.867664)
		(width 0.18288)
		(layer "In6.Cu")
		(net "M_H_CPU1_SA_RSP<1>")
	)
	(segment
		(start 135.245094 -254.235966)
		(end 135.245094 -253.919736)
		(width 0.088646)
		(layer "In6.Cu")
		(net "M_H_CPU1_SA_RSP<1>")
	)
	(segment
		(start 186.357006 -252.076712)
		(end 186.125104 -252.308614)
		(width 0.18288)
		(layer "In6.Cu")
		(net "M_H_CPU1_SA_RSP<1>")
	)
	(segment
		(start 137.407396 -255.05791)
		(end 137.392664 -255.049274)
		(width 0.088646)
		(layer "In6.Cu")
		(net "M_H_CPU1_SA_RSP<1>")
	)
	(segment
		(start 139.272264 -254.981964)
		(end 139.004548 -254.981964)
		(width 0.088646)
		(layer "In6.Cu")
		(net "M_H_CPU1_SA_RSP<1>")
	)
	(segment
		(start 186.95416 -254.118618)
		(end 186.695588 -254.118618)
		(width 0.18288)
		(layer "In6.Cu")
		(net "M_H_CPU1_SA_RSP<1>")
	)
	(segment
		(start 187.935108 -253.13767)
		(end 187.676536 -253.13767)
		(width 0.18288)
		(layer "In6.Cu")
		(net "M_H_CPU1_SA_RSP<1>")
	)
	(segment
		(start 139.93495 -254.577596)
		(end 139.676632 -254.577596)
		(width 0.088646)
		(layer "In6.Cu")
		(net "M_H_CPU1_SA_RSP<1>")
	)
	(segment
		(start 186.615578 -252.076712)
		(end 186.357006 -252.076712)
		(width 0.18288)
		(layer "In6.Cu")
		(net "M_H_CPU1_SA_RSP<1>")
	)
	(segment
		(start 202.971146 -244.066568)
		(end 202.682856 -243.947188)
		(width 0.18288)
		(layer "In6.Cu")
		(net "M_H_CPU1_SA_RSP<1>")
	)
	(segment
		(start 164.904674 -255.381252)
		(end 149.89556 -255.381252)
		(width 0.18288)
		(layer "In6.Cu")
		(net "M_H_CPU1_SA_RSP<1>")
	)
	(segment
		(start 187.186062 -253.628144)
		(end 187.186062 -253.886716)
		(width 0.18288)
		(layer "In6.Cu")
		(net "M_H_CPU1_SA_RSP<1>")
	)
	(segment
		(start 135.340344 -254.331216)
		(end 135.245094 -254.235966)
		(width 0.088646)
		(layer "In6.Cu")
		(net "M_H_CPU1_SA_RSP<1>")
	)
	(segment
		(start 185.144156 -253.548134)
		(end 186.205114 -254.609092)
		(width 0.18288)
		(layer "In6.Cu")
		(net "M_H_CPU1_SA_RSP<1>")
	)
	(segment
		(start 202.682856 -243.947188)
		(end 202.519534 -243.947188)
		(width 0.18288)
		(layer "In6.Cu")
		(net "M_H_CPU1_SA_RSP<1>")
	)
	(segment
		(start 185.691272 -255.381506)
		(end 164.904674 -255.381506)
		(width 0.18288)
		(layer "In6.Cu")
		(net "M_H_CPU1_SA_RSP<1>")
	)
	(segment
		(start 142.81785 -255.685036)
		(end 141.71041 -254.577596)
		(width 0.18288)
		(layer "In6.Cu")
		(net "M_H_CPU1_SA_RSP<1>")
	)
	(segment
		(start 202.519534 -243.947188)
		(end 200.31583 -246.150892)
		(width 0.18288)
		(layer "In6.Cu")
		(net "M_H_CPU1_SA_RSP<1>")
	)
	(segment
		(start 135.340344 -254.733552)
		(end 135.340344 -254.331216)
		(width 0.088646)
		(layer "In6.Cu")
		(net "M_H_CPU1_SA_RSP<1>")
	)
	(segment
		(start 164.904674 -255.381506)
		(end 164.904674 -255.381252)
		(width 0.18288)
		(layer "In6.Cu")
		(net "M_H_CPU1_SA_RSP<1>")
	)
	(segment
		(start 190.630302 -250.442476)
		(end 187.935108 -253.13767)
		(width 0.18288)
		(layer "In6.Cu")
		(net "M_H_CPU1_SA_RSP<1>")
	)
	(segment
		(start 185.144156 -253.289562)
		(end 185.144156 -253.548134)
		(width 0.18288)
		(layer "In6.Cu")
		(net "M_H_CPU1_SA_RSP<1>")
	)
	(segment
		(start 139.676632 -254.577596)
		(end 139.272264 -254.981964)
		(width 0.088646)
		(layer "In6.Cu")
		(net "M_H_CPU1_SA_RSP<1>")
	)
	(segment
		(start 186.125104 -252.308614)
		(end 186.125104 -252.567186)
		(width 0.18288)
		(layer "In6.Cu")
		(net "M_H_CPU1_SA_RSP<1>")
	)
	(segment
		(start 149.89556 -255.381252)
		(end 148.678392 -256.59842)
		(width 0.18288)
		(layer "In6.Cu")
		(net "M_H_CPU1_SA_RSP<1>")
	)
	(segment
		(start 193.940176 -250.442476)
		(end 190.630302 -250.442476)
		(width 0.18288)
		(layer "In6.Cu")
		(net "M_H_CPU1_SA_RSP<1>")
	)
	(segment
		(start 141.71041 -254.577596)
		(end 139.93495 -254.577596)
		(width 0.18288)
		(layer "In6.Cu")
		(net "M_H_CPU1_SA_RSP<1>")
	)
	(segment
		(start 186.695588 -254.118618)
		(end 185.63463 -253.05766)
		(width 0.18288)
		(layer "In6.Cu")
		(net "M_H_CPU1_SA_RSP<1>")
	)
	(segment
		(start 145.741644 -256.59842)
		(end 144.358868 -256.323338)
		(width 0.18288)
		(layer "In6.Cu")
		(net "M_H_CPU1_SA_RSP<1>")
	)
	(segment
		(start 144.358868 -256.323338)
		(end 142.81785 -255.685036)
		(width 0.18288)
		(layer "In6.Cu")
		(net "M_H_CPU1_SA_RSP<1>")
	)
	(segment
		(start 186.205114 -254.867664)
		(end 185.691272 -255.381506)
		(width 0.18288)
		(layer "In6.Cu")
		(net "M_H_CPU1_SA_RSP<1>")
	)
	(arc
		(start 136.841992 -255.05791)
		(mid 136.654794 -255.108053)
		(end 136.467596 -255.05791)
		(width 0.088646)
		(layer "In6.Cu")
		(net "M_H_CPU1_SA_RSP<1>")
	)
	(arc
		(start 138.721592 -255.05791)
		(mid 138.534394 -255.108053)
		(end 138.347196 -255.05791)
		(width 0.088646)
		(layer "In6.Cu")
		(net "M_H_CPU1_SA_RSP<1>")
	)
	(arc
		(start 135.902192 -255.05791)
		(mid 135.714994 -255.108053)
		(end 135.527796 -255.05791)
		(width 0.088646)
		(layer "In6.Cu")
		(net "M_H_CPU1_SA_RSP<1>")
	)
	(arc
		(start 137.781792 -255.05791)
		(mid 137.594594 -255.108053)
		(end 137.407396 -255.05791)
		(width 0.088646)
		(layer "In6.Cu")
		(net "M_H_CPU1_SA_RSP<1>")
	)
	(arc
		(start 137.392664 -255.049274)
		(mid 137.116189 -254.981954)
		(end 136.841992 -255.05791)
		(width 0.088646)
		(layer "In6.Cu")
		(net "M_H_CPU1_SA_RSP<1>")
	)
	(arc
		(start 135.518906 -255.05283)
		(mid 135.387992 -254.91647)
		(end 135.340344 -254.733552)
		(width 0.088646)
		(layer "In6.Cu")
		(net "M_H_CPU1_SA_RSP<1>")
	)
	(arc
		(start 138.332464 -255.049274)
		(mid 138.055989 -254.981954)
		(end 137.781792 -255.05791)
		(width 0.088646)
		(layer "In6.Cu")
		(net "M_H_CPU1_SA_RSP<1>")
	)
	(arc
		(start 139.004548 -254.981964)
		(mid 138.858061 -255.001279)
		(end 138.721592 -255.05791)
		(width 0.088646)
		(layer "In6.Cu")
		(net "M_H_CPU1_SA_RSP<1>")
	)
	(arc
		(start 136.467596 -255.05791)
		(mid 136.184894 -254.982168)
		(end 135.902192 -255.05791)
		(width 0.088646)
		(layer "In6.Cu")
		(net "M_H_CPU1_SA_RSP<1>")
	)
	(segment
		(start 134.775448 -254.197612)
		(end 134.775448 -254.733298)
		(width 0.20066)
		(layer "F.Cu")
		(net "M_H_CPU1_SA_RSP<0>")
	)
	(segment
		(start 210.514946 -244.066568)
		(end 211.619846 -244.066568)
		(width 0.20066)
		(layer "F.Cu")
		(net "M_H_CPU1_SA_RSP<0>")
	)
	(segment
		(start 134.775448 -254.733298)
		(end 134.775194 -254.733552)
		(width 0.20066)
		(layer "F.Cu")
		(net "M_H_CPU1_SA_RSP<0>")
	)
	(segment
		(start 189.403228 -256.391664)
		(end 151.35606 -256.391664)
		(width 0.18288)
		(layer "In6.Cu")
		(net "M_H_CPU1_SA_RSP<0>")
	)
	(segment
		(start 204.935328 -247.042432)
		(end 203.235306 -248.742454)
		(width 0.18288)
		(layer "In6.Cu")
		(net "M_H_CPU1_SA_RSP<0>")
	)
	(segment
		(start 150.152608 -257.595116)
		(end 145.647918 -257.595116)
		(width 0.18288)
		(layer "In6.Cu")
		(net "M_H_CPU1_SA_RSP<0>")
	)
	(segment
		(start 207.917542 -246.533416)
		(end 207.408526 -247.042432)
		(width 0.18288)
		(layer "In6.Cu")
		(net "M_H_CPU1_SA_RSP<0>")
	)
	(segment
		(start 190.279528 -255.419352)
		(end 190.096648 -255.236472)
		(width 0.18288)
		(layer "In6.Cu")
		(net "M_H_CPU1_SA_RSP<0>")
	)
	(segment
		(start 191.682116 -256.391918)
		(end 191.681862 -256.391664)
		(width 0.18288)
		(layer "In6.Cu")
		(net "M_H_CPU1_SA_RSP<0>")
	)
	(segment
		(start 203.235306 -248.742454)
		(end 200.649586 -248.742454)
		(width 0.18288)
		(layer "In6.Cu")
		(net "M_H_CPU1_SA_RSP<0>")
	)
	(segment
		(start 189.586108 -256.208784)
		(end 189.403228 -256.391664)
		(width 0.18288)
		(layer "In6.Cu")
		(net "M_H_CPU1_SA_RSP<0>")
	)
	(segment
		(start 199.347074 -250.044966)
		(end 198.314564 -250.044966)
		(width 0.18288)
		(layer "In6.Cu")
		(net "M_H_CPU1_SA_RSP<0>")
	)
	(segment
		(start 136.389364 -255.86182)
		(end 136.372092 -255.87198)
		(width 0.088646)
		(layer "In6.Cu")
		(net "M_H_CPU1_SA_RSP<0>")
	)
	(segment
		(start 139.024868 -256.052066)
		(end 138.93419 -255.961388)
		(width 0.088646)
		(layer "In6.Cu")
		(net "M_H_CPU1_SA_RSP<0>")
	)
	(segment
		(start 190.279528 -256.208784)
		(end 190.279528 -255.419352)
		(width 0.18288)
		(layer "In6.Cu")
		(net "M_H_CPU1_SA_RSP<0>")
	)
	(segment
		(start 141.549628 -256.266696)
		(end 140.959332 -255.6764)
		(width 0.18288)
		(layer "In6.Cu")
		(net "M_H_CPU1_SA_RSP<0>")
	)
	(segment
		(start 210.514946 -244.066568)
		(end 210.489546 -244.066568)
		(width 0.18288)
		(layer "In6.Cu")
		(net "M_H_CPU1_SA_RSP<0>")
	)
	(segment
		(start 143.933164 -257.253994)
		(end 141.549628 -256.266696)
		(width 0.18288)
		(layer "In6.Cu")
		(net "M_H_CPU1_SA_RSP<0>")
	)
	(segment
		(start 139.93495 -255.6764)
		(end 139.587224 -255.6764)
		(width 0.088646)
		(layer "In6.Cu")
		(net "M_H_CPU1_SA_RSP<0>")
	)
	(segment
		(start 191.967612 -256.391918)
		(end 191.682116 -256.391918)
		(width 0.18288)
		(layer "In6.Cu")
		(net "M_H_CPU1_SA_RSP<0>")
	)
	(segment
		(start 145.647918 -257.595116)
		(end 143.933164 -257.253994)
		(width 0.18288)
		(layer "In6.Cu")
		(net "M_H_CPU1_SA_RSP<0>")
	)
	(segment
		(start 189.586108 -255.419352)
		(end 189.586108 -256.208784)
		(width 0.18288)
		(layer "In6.Cu")
		(net "M_H_CPU1_SA_RSP<0>")
	)
	(segment
		(start 134.587996 -255.05791)
		(end 134.579106 -255.05283)
		(width 0.088646)
		(layer "In6.Cu")
		(net "M_H_CPU1_SA_RSP<0>")
	)
	(segment
		(start 198.314564 -250.044966)
		(end 191.967612 -256.391918)
		(width 0.18288)
		(layer "In6.Cu")
		(net "M_H_CPU1_SA_RSP<0>")
	)
	(segment
		(start 210.489546 -244.066568)
		(end 209.884264 -243.461286)
		(width 0.18288)
		(layer "In6.Cu")
		(net "M_H_CPU1_SA_RSP<0>")
	)
	(segment
		(start 207.917542 -244.772942)
		(end 207.917542 -246.533416)
		(width 0.18288)
		(layer "In6.Cu")
		(net "M_H_CPU1_SA_RSP<0>")
	)
	(segment
		(start 190.462408 -256.391664)
		(end 190.279528 -256.208784)
		(width 0.18288)
		(layer "In6.Cu")
		(net "M_H_CPU1_SA_RSP<0>")
	)
	(segment
		(start 140.959332 -255.6764)
		(end 139.93495 -255.6764)
		(width 0.18288)
		(layer "In6.Cu")
		(net "M_H_CPU1_SA_RSP<0>")
	)
	(segment
		(start 200.649586 -248.742454)
		(end 199.347074 -250.044966)
		(width 0.18288)
		(layer "In6.Cu")
		(net "M_H_CPU1_SA_RSP<0>")
	)
	(segment
		(start 209.229198 -243.461286)
		(end 207.917542 -244.772942)
		(width 0.18288)
		(layer "In6.Cu")
		(net "M_H_CPU1_SA_RSP<0>")
	)
	(segment
		(start 209.884264 -243.461286)
		(end 209.229198 -243.461286)
		(width 0.18288)
		(layer "In6.Cu")
		(net "M_H_CPU1_SA_RSP<0>")
	)
	(segment
		(start 134.870698 -255.556258)
		(end 134.870698 -255.533398)
		(width 0.088646)
		(layer "In6.Cu")
		(net "M_H_CPU1_SA_RSP<0>")
	)
	(segment
		(start 137.326878 -255.86309)
		(end 137.312146 -255.871726)
		(width 0.088646)
		(layer "In6.Cu")
		(net "M_H_CPU1_SA_RSP<0>")
	)
	(segment
		(start 134.462266 -254.733552)
		(end 134.775194 -254.733552)
		(width 0.088646)
		(layer "In6.Cu")
		(net "M_H_CPU1_SA_RSP<0>")
	)
	(segment
		(start 139.587224 -255.6764)
		(end 139.211558 -256.052066)
		(width 0.088646)
		(layer "In6.Cu")
		(net "M_H_CPU1_SA_RSP<0>")
	)
	(segment
		(start 191.681862 -256.391664)
		(end 190.462408 -256.391664)
		(width 0.18288)
		(layer "In6.Cu")
		(net "M_H_CPU1_SA_RSP<0>")
	)
	(segment
		(start 207.408526 -247.042432)
		(end 204.935328 -247.042432)
		(width 0.18288)
		(layer "In6.Cu")
		(net "M_H_CPU1_SA_RSP<0>")
	)
	(segment
		(start 189.768988 -255.236472)
		(end 189.586108 -255.419352)
		(width 0.18288)
		(layer "In6.Cu")
		(net "M_H_CPU1_SA_RSP<0>")
	)
	(segment
		(start 190.096648 -255.236472)
		(end 189.768988 -255.236472)
		(width 0.18288)
		(layer "In6.Cu")
		(net "M_H_CPU1_SA_RSP<0>")
	)
	(segment
		(start 134.405116 -254.790702)
		(end 134.462266 -254.733552)
		(width 0.088646)
		(layer "In6.Cu")
		(net "M_H_CPU1_SA_RSP<0>")
	)
	(segment
		(start 151.35606 -256.391664)
		(end 150.152608 -257.595116)
		(width 0.18288)
		(layer "In6.Cu")
		(net "M_H_CPU1_SA_RSP<0>")
	)
	(segment
		(start 139.211558 -256.052066)
		(end 139.024868 -256.052066)
		(width 0.088646)
		(layer "In6.Cu")
		(net "M_H_CPU1_SA_RSP<0>")
	)
	(segment
		(start 138.266678 -255.86309)
		(end 138.240008 -255.878584)
		(width 0.088646)
		(layer "In6.Cu")
		(net "M_H_CPU1_SA_RSP<0>")
	)
	(arc
		(start 136.93775 -255.871726)
		(mid 136.664828 -255.795823)
		(end 136.389364 -255.86182)
		(width 0.088646)
		(layer "In6.Cu")
		(net "M_H_CPU1_SA_RSP<0>")
	)
	(arc
		(start 135.432292 -255.87198)
		(mid 135.245094 -255.922123)
		(end 135.057896 -255.87198)
		(width 0.088646)
		(layer "In6.Cu")
		(net "M_H_CPU1_SA_RSP<0>")
	)
	(arc
		(start 137.312146 -255.871726)
		(mid 137.124948 -255.921869)
		(end 136.93775 -255.871726)
		(width 0.088646)
		(layer "In6.Cu")
		(net "M_H_CPU1_SA_RSP<0>")
	)
	(arc
		(start 135.997696 -255.87198)
		(mid 135.714994 -255.796204)
		(end 135.432292 -255.87198)
		(width 0.088646)
		(layer "In6.Cu")
		(net "M_H_CPU1_SA_RSP<0>")
	)
	(arc
		(start 138.93419 -255.961388)
		(mid 138.616707 -255.801883)
		(end 138.266678 -255.86309)
		(width 0.088646)
		(layer "In6.Cu")
		(net "M_H_CPU1_SA_RSP<0>")
	)
	(arc
		(start 136.372092 -255.87198)
		(mid 136.184894 -255.922123)
		(end 135.997696 -255.87198)
		(width 0.088646)
		(layer "In6.Cu")
		(net "M_H_CPU1_SA_RSP<0>")
	)
	(arc
		(start 135.057896 -255.87198)
		(mid 134.922963 -255.738626)
		(end 134.870698 -255.556258)
		(width 0.088646)
		(layer "In6.Cu")
		(net "M_H_CPU1_SA_RSP<0>")
	)
	(arc
		(start 138.240008 -255.878584)
		(mid 138.057897 -255.921909)
		(end 137.87755 -255.871726)
		(width 0.088646)
		(layer "In6.Cu")
		(net "M_H_CPU1_SA_RSP<0>")
	)
	(arc
		(start 134.870698 -255.533398)
		(mid 134.791479 -255.258713)
		(end 134.587996 -255.05791)
		(width 0.088646)
		(layer "In6.Cu")
		(net "M_H_CPU1_SA_RSP<0>")
	)
	(arc
		(start 137.87755 -255.871726)
		(mid 137.603321 -255.795801)
		(end 137.326878 -255.86309)
		(width 0.088646)
		(layer "In6.Cu")
		(net "M_H_CPU1_SA_RSP<0>")
	)
	(arc
		(start 134.579106 -255.05283)
		(mid 134.463297 -254.940901)
		(end 134.405116 -254.790702)
		(width 0.088646)
		(layer "In6.Cu")
		(net "M_H_CPU1_SA_RSP<0>")
	)
	(segment
		(start 206.978758 -258.941824)
		(end 206.999078 -258.941824)
		(width 0.101854)
		(layer "F.Cu")
		(net "M_H_CPU1_SA_PAR")
	)
	(segment
		(start 123.857766 -246.086376)
		(end 123.857766 -245.55069)
		(width 0.20066)
		(layer "F.Cu")
		(net "M_H_CPU1_SA_PAR")
	)
	(segment
		(start 206.699866 -258.941824)
		(end 206.978758 -258.941824)
		(width 0.20066)
		(layer "F.Cu")
		(net "M_H_CPU1_SA_PAR")
	)
	(segment
		(start 209.17408 -258.941824)
		(end 209.186526 -258.95427)
		(width 0.1016)
		(layer "F.Cu")
		(net "M_H_CPU1_SA_PAR")
	)
	(segment
		(start 209.741008 -258.95427)
		(end 210.153504 -259.366766)
		(width 0.20066)
		(layer "F.Cu")
		(net "M_H_CPU1_SA_PAR")
	)
	(segment
		(start 209.186526 -258.95427)
		(end 209.741008 -258.95427)
		(width 0.20066)
		(layer "F.Cu")
		(net "M_H_CPU1_SA_PAR")
	)
	(segment
		(start 123.857512 -246.08663)
		(end 123.857766 -246.086376)
		(width 0.20066)
		(layer "F.Cu")
		(net "M_H_CPU1_SA_PAR")
	)
	(segment
		(start 206.232506 -258.474464)
		(end 206.699866 -258.941824)
		(width 0.20066)
		(layer "F.Cu")
		(net "M_H_CPU1_SA_PAR")
	)
	(segment
		(start 206.999078 -258.941824)
		(end 209.17408 -258.941824)
		(width 0.1016)
		(layer "F.Cu")
		(net "M_H_CPU1_SA_PAR")
	)
	(segment
		(start 210.153504 -259.366766)
		(end 211.619846 -259.366766)
		(width 0.20066)
		(layer "F.Cu")
		(net "M_H_CPU1_SA_PAR")
	)
	(segment
		(start 205.856078 -258.474464)
		(end 206.232506 -258.474464)
		(width 0.20066)
		(layer "F.Cu")
		(net "M_H_CPU1_SA_PAR")
	)
	(segment
		(start 202.971146 -259.366766)
		(end 204.076046 -259.366766)
		(width 0.20066)
		(layer "F.Cu")
		(net "M_H_CPU1_SA_PAR")
	)
	(segment
		(start 204.076046 -259.366766)
		(end 204.963776 -259.366766)
		(width 0.20066)
		(layer "F.Cu")
		(net "M_H_CPU1_SA_PAR")
	)
	(segment
		(start 204.963776 -259.366766)
		(end 205.856078 -258.474464)
		(width 0.20066)
		(layer "F.Cu")
		(net "M_H_CPU1_SA_PAR")
	)
	(segment
		(start 123.012962 -247.992138)
		(end 123.012962 -247.976644)
		(width 0.088646)
		(layer "In11.Cu")
		(net "M_H_CPU1_SA_PAR")
	)
	(segment
		(start 124.568458 -252.438408)
		(end 124.427742 -252.438408)
		(width 0.088646)
		(layer "In11.Cu")
		(net "M_H_CPU1_SA_PAR")
	)
	(segment
		(start 123.200414 -248.316496)
		(end 123.191524 -248.311416)
		(width 0.088646)
		(layer "In11.Cu")
		(net "M_H_CPU1_SA_PAR")
	)
	(segment
		(start 152.795732 -253.86792)
		(end 148.535644 -253.86792)
		(width 0.18288)
		(layer "In11.Cu")
		(net "M_H_CPU1_SA_PAR")
	)
	(segment
		(start 193.286888 -257.576066)
		(end 160.685734 -257.576066)
		(width 0.18288)
		(layer "In11.Cu")
		(net "M_H_CPU1_SA_PAR")
	)
	(segment
		(start 123.952762 -251.963428)
		(end 123.952762 -249.60453)
		(width 0.088646)
		(layer "In11.Cu")
		(net "M_H_CPU1_SA_PAR")
	)
	(segment
		(start 199.658732 -258.075176)
		(end 197.873112 -258.075176)
		(width 0.18288)
		(layer "In11.Cu")
		(net "M_H_CPU1_SA_PAR")
	)
	(segment
		(start 201.528426 -259.009642)
		(end 201.255122 -258.736338)
		(width 0.18288)
		(layer "In11.Cu")
		(net "M_H_CPU1_SA_PAR")
	)
	(segment
		(start 157.099254 -256.7813)
		(end 155.1686 -254.850646)
		(width 0.18288)
		(layer "In11.Cu")
		(net "M_H_CPU1_SA_PAR")
	)
	(segment
		(start 148.535644 -253.86792)
		(end 147.505928 -254.897636)
		(width 0.18288)
		(layer "In11.Cu")
		(net "M_H_CPU1_SA_PAR")
	)
	(segment
		(start 142.157196 -252.438408)
		(end 124.568458 -252.438408)
		(width 0.18288)
		(layer "In11.Cu")
		(net "M_H_CPU1_SA_PAR")
	)
	(segment
		(start 202.971146 -259.366766)
		(end 202.614022 -259.009642)
		(width 0.18288)
		(layer "In11.Cu")
		(net "M_H_CPU1_SA_PAR")
	)
	(segment
		(start 123.701302 -245.821708)
		(end 123.857766 -245.55069)
		(width 0.088646)
		(layer "In11.Cu")
		(net "M_H_CPU1_SA_PAR")
	)
	(segment
		(start 147.505928 -254.897636)
		(end 144.616424 -254.897636)
		(width 0.18288)
		(layer "In11.Cu")
		(net "M_H_CPU1_SA_PAR")
	)
	(segment
		(start 202.614022 -259.009642)
		(end 201.528426 -259.009642)
		(width 0.18288)
		(layer "In11.Cu")
		(net "M_H_CPU1_SA_PAR")
	)
	(segment
		(start 197.873112 -258.075176)
		(end 193.286888 -257.576066)
		(width 0.18288)
		(layer "In11.Cu")
		(net "M_H_CPU1_SA_PAR")
	)
	(segment
		(start 122.721878 -246.859044)
		(end 122.730768 -246.853964)
		(width 0.088646)
		(layer "In11.Cu")
		(net "M_H_CPU1_SA_PAR")
	)
	(segment
		(start 123.105164 -246.853964)
		(end 123.119896 -246.8626)
		(width 0.088646)
		(layer "In11.Cu")
		(net "M_H_CPU1_SA_PAR")
	)
	(segment
		(start 123.952762 -246.38)
		(end 123.952762 -246.349012)
		(width 0.088646)
		(layer "In11.Cu")
		(net "M_H_CPU1_SA_PAR")
	)
	(segment
		(start 122.730768 -247.50268)
		(end 122.721878 -247.4976)
		(width 0.088646)
		(layer "In11.Cu")
		(net "M_H_CPU1_SA_PAR")
	)
	(segment
		(start 123.725432 -245.910862)
		(end 123.701302 -245.821708)
		(width 0.088646)
		(layer "In11.Cu")
		(net "M_H_CPU1_SA_PAR")
	)
	(segment
		(start 160.685734 -257.576066)
		(end 158.361634 -256.7813)
		(width 0.18288)
		(layer "In11.Cu")
		(net "M_H_CPU1_SA_PAR")
	)
	(segment
		(start 201.255122 -258.736338)
		(end 199.658732 -258.075176)
		(width 0.18288)
		(layer "In11.Cu")
		(net "M_H_CPU1_SA_PAR")
	)
	(segment
		(start 123.483116 -248.806208)
		(end 123.483116 -248.798588)
		(width 0.088646)
		(layer "In11.Cu")
		(net "M_H_CPU1_SA_PAR")
	)
	(segment
		(start 123.670568 -249.130566)
		(end 123.661678 -249.125486)
		(width 0.088646)
		(layer "In11.Cu")
		(net "M_H_CPU1_SA_PAR")
	)
	(segment
		(start 124.427742 -252.438408)
		(end 123.952762 -251.963428)
		(width 0.088646)
		(layer "In11.Cu")
		(net "M_H_CPU1_SA_PAR")
	)
	(segment
		(start 158.361634 -256.7813)
		(end 157.099254 -256.7813)
		(width 0.18288)
		(layer "In11.Cu")
		(net "M_H_CPU1_SA_PAR")
	)
	(segment
		(start 144.616424 -254.897636)
		(end 142.157196 -252.438408)
		(width 0.18288)
		(layer "In11.Cu")
		(net "M_H_CPU1_SA_PAR")
	)
	(segment
		(start 155.1686 -254.850646)
		(end 152.795732 -253.86792)
		(width 0.18288)
		(layer "In11.Cu")
		(net "M_H_CPU1_SA_PAR")
	)
	(arc
		(start 123.952762 -246.349012)
		(mid 123.889418 -246.103835)
		(end 123.725432 -245.910862)
		(width 0.088646)
		(layer "In11.Cu")
		(net "M_H_CPU1_SA_PAR")
	)
	(arc
		(start 122.730768 -246.853964)
		(mid 122.917966 -246.803821)
		(end 123.105164 -246.853964)
		(width 0.088646)
		(layer "In11.Cu")
		(net "M_H_CPU1_SA_PAR")
	)
	(arc
		(start 123.483116 -248.798588)
		(mid 123.405487 -248.520175)
		(end 123.200414 -248.316496)
		(width 0.088646)
		(layer "In11.Cu")
		(net "M_H_CPU1_SA_PAR")
	)
	(arc
		(start 123.661678 -249.125486)
		(mid 123.530764 -248.989126)
		(end 123.483116 -248.806208)
		(width 0.088646)
		(layer "In11.Cu")
		(net "M_H_CPU1_SA_PAR")
	)
	(arc
		(start 123.119896 -246.8626)
		(mid 123.396371 -246.92992)
		(end 123.670568 -246.853964)
		(width 0.088646)
		(layer "In11.Cu")
		(net "M_H_CPU1_SA_PAR")
	)
	(arc
		(start 123.952762 -249.60453)
		(mid 123.873392 -249.330796)
		(end 123.670568 -249.130566)
		(width 0.088646)
		(layer "In11.Cu")
		(net "M_H_CPU1_SA_PAR")
	)
	(arc
		(start 123.012962 -247.976644)
		(mid 122.933592 -247.70291)
		(end 122.730768 -247.50268)
		(width 0.088646)
		(layer "In11.Cu")
		(net "M_H_CPU1_SA_PAR")
	)
	(arc
		(start 122.721878 -247.4976)
		(mid 122.543281 -247.178322)
		(end 122.721878 -246.859044)
		(width 0.088646)
		(layer "In11.Cu")
		(net "M_H_CPU1_SA_PAR")
	)
	(arc
		(start 123.670568 -246.853964)
		(mid 123.873391 -246.653733)
		(end 123.952762 -246.38)
		(width 0.088646)
		(layer "In11.Cu")
		(net "M_H_CPU1_SA_PAR")
	)
	(arc
		(start 123.191524 -248.311416)
		(mid 123.06061 -248.175056)
		(end 123.012962 -247.992138)
		(width 0.088646)
		(layer "In11.Cu")
		(net "M_H_CPU1_SA_PAR")
	)
	(segment
		(start 214.883746 -274.084796)
		(end 215.15197 -273.816572)
		(width 0.20066)
		(layer "F.Cu")
		(net "M_H_CPU1_SA_DQS_DP<9>")
	)
	(segment
		(start 209.020664 -274.067778)
		(end 209.325464 -274.067778)
		(width 0.20066)
		(layer "F.Cu")
		(net "M_H_CPU1_SA_DQS_DP<9>")
	)
	(segment
		(start 210.598258 -273.384518)
		(end 210.603084 -273.384518)
		(width 0.101854)
		(layer "F.Cu")
		(net "M_H_CPU1_SA_DQS_DP<9>")
	)
	(segment
		(start 215.15197 -273.816572)
		(end 215.719914 -273.816572)
		(width 0.20066)
		(layer "F.Cu")
		(net "M_H_CPU1_SA_DQS_DP<9>")
	)
	(segment
		(start 210.610196 -273.39163)
		(end 212.622892 -273.39163)
		(width 0.1016)
		(layer "F.Cu")
		(net "M_H_CPU1_SA_DQS_DP<9>")
	)
	(segment
		(start 208.176114 -273.816572)
		(end 208.769458 -273.816572)
		(width 0.20066)
		(layer "F.Cu")
		(net "M_H_CPU1_SA_DQS_DP<9>")
	)
	(segment
		(start 214.30615 -274.084796)
		(end 214.883746 -274.084796)
		(width 0.20066)
		(layer "F.Cu")
		(net "M_H_CPU1_SA_DQS_DP<9>")
	)
	(segment
		(start 210.287108 -273.384518)
		(end 210.598258 -273.384518)
		(width 0.20066)
		(layer "F.Cu")
		(net "M_H_CPU1_SA_DQS_DP<9>")
	)
	(segment
		(start 212.630258 -273.384264)
		(end 212.952076 -273.384264)
		(width 0.20066)
		(layer "F.Cu")
		(net "M_H_CPU1_SA_DQS_DP<9>")
	)
	(segment
		(start 212.952076 -273.384264)
		(end 213.207092 -273.63928)
		(width 0.20066)
		(layer "F.Cu")
		(net "M_H_CPU1_SA_DQS_DP<9>")
	)
	(segment
		(start 208.769458 -273.816572)
		(end 209.020664 -274.067778)
		(width 0.20066)
		(layer "F.Cu")
		(net "M_H_CPU1_SA_DQS_DP<9>")
	)
	(segment
		(start 124.907294 -260.430518)
		(end 124.907548 -260.430772)
		(width 0.20066)
		(layer "F.Cu")
		(net "M_H_CPU1_SA_DQS_DP<9>")
	)
	(segment
		(start 207.071214 -273.816572)
		(end 208.176114 -273.816572)
		(width 0.20066)
		(layer "F.Cu")
		(net "M_H_CPU1_SA_DQS_DP<9>")
	)
	(segment
		(start 213.207092 -273.63928)
		(end 213.860634 -273.63928)
		(width 0.20066)
		(layer "F.Cu")
		(net "M_H_CPU1_SA_DQS_DP<9>")
	)
	(segment
		(start 209.325464 -274.067778)
		(end 209.750406 -273.642836)
		(width 0.20066)
		(layer "F.Cu")
		(net "M_H_CPU1_SA_DQS_DP<9>")
	)
	(segment
		(start 209.750406 -273.642836)
		(end 210.02879 -273.642836)
		(width 0.20066)
		(layer "F.Cu")
		(net "M_H_CPU1_SA_DQS_DP<9>")
	)
	(segment
		(start 212.622892 -273.39163)
		(end 212.630258 -273.384264)
		(width 0.1016)
		(layer "F.Cu")
		(net "M_H_CPU1_SA_DQS_DP<9>")
	)
	(segment
		(start 210.02879 -273.642836)
		(end 210.287108 -273.384518)
		(width 0.20066)
		(layer "F.Cu")
		(net "M_H_CPU1_SA_DQS_DP<9>")
	)
	(segment
		(start 213.860634 -273.63928)
		(end 214.30615 -274.084796)
		(width 0.20066)
		(layer "F.Cu")
		(net "M_H_CPU1_SA_DQS_DP<9>")
	)
	(segment
		(start 210.603084 -273.384518)
		(end 210.610196 -273.39163)
		(width 0.1016)
		(layer "F.Cu")
		(net "M_H_CPU1_SA_DQS_DP<9>")
	)
	(segment
		(start 124.907294 -259.894832)
		(end 124.907294 -260.430518)
		(width 0.20066)
		(layer "F.Cu")
		(net "M_H_CPU1_SA_DQS_DP<9>")
	)
	(segment
		(start 172.527722 -273.390868)
		(end 172.240194 -273.678396)
		(width 0.18288)
		(layer "In11.Cu")
		(net "M_H_CPU1_SA_DQS_DP<9>")
	)
	(segment
		(start 175.664876 -275.369528)
		(end 173.994572 -273.699224)
		(width 0.18288)
		(layer "In11.Cu")
		(net "M_H_CPU1_SA_DQS_DP<9>")
	)
	(segment
		(start 192.487296 -275.394928)
		(end 192.183258 -275.09089)
		(width 0.18288)
		(layer "In11.Cu")
		(net "M_H_CPU1_SA_DQS_DP<9>")
	)
	(segment
		(start 192.911984 -275.232114)
		(end 192.74917 -275.394928)
		(width 0.18288)
		(layer "In11.Cu")
		(net "M_H_CPU1_SA_DQS_DP<9>")
	)
	(segment
		(start 194.33794 -274.768564)
		(end 194.029838 -274.768564)
		(width 0.18288)
		(layer "In11.Cu")
		(net "M_H_CPU1_SA_DQS_DP<9>")
	)
	(segment
		(start 173.049946 -273.390868)
		(end 172.527722 -273.390868)
		(width 0.18288)
		(layer "In11.Cu")
		(net "M_H_CPU1_SA_DQS_DP<9>")
	)
	(segment
		(start 202.493372 -273.600926)
		(end 202.493372 -273.816826)
		(width 0.18288)
		(layer "In11.Cu")
		(net "M_H_CPU1_SA_DQS_DP<9>")
	)
	(segment
		(start 177.419254 -275.38553)
		(end 177.124614 -275.09089)
		(width 0.18288)
		(layer "In11.Cu")
		(net "M_H_CPU1_SA_DQS_DP<9>")
	)
	(segment
		(start 138.732514 -261.562596)
		(end 138.7221 -261.568692)
		(width 0.088646)
		(layer "In11.Cu")
		(net "M_H_CPU1_SA_DQS_DP<9>")
	)
	(segment
		(start 126.347474 -260.002528)
		(end 125.908816 -260.01091)
		(width 0.088646)
		(layer "In11.Cu")
		(net "M_H_CPU1_SA_DQS_DP<9>")
	)
	(segment
		(start 177.775616 -275.38553)
		(end 177.419254 -275.38553)
		(width 0.18288)
		(layer "In11.Cu")
		(net "M_H_CPU1_SA_DQS_DP<9>")
	)
	(segment
		(start 126.503938 -259.941822)
		(end 126.440946 -259.976874)
		(width 0.088646)
		(layer "In11.Cu")
		(net "M_H_CPU1_SA_DQS_DP<9>")
	)
	(segment
		(start 188.3918 -273.694906)
		(end 188.087762 -273.390868)
		(width 0.18288)
		(layer "In11.Cu")
		(net "M_H_CPU1_SA_DQS_DP<9>")
	)
	(segment
		(start 125.786896 -260.038596)
		(end 125.66015 -260.106414)
		(width 0.088646)
		(layer "In11.Cu")
		(net "M_H_CPU1_SA_DQS_DP<9>")
	)
	(segment
		(start 192.183258 -275.09089)
		(end 191.71539 -275.09089)
		(width 0.18288)
		(layer "In11.Cu")
		(net "M_H_CPU1_SA_DQS_DP<9>")
	)
	(segment
		(start 173.994572 -273.699224)
		(end 173.358302 -273.699224)
		(width 0.18288)
		(layer "In11.Cu")
		(net "M_H_CPU1_SA_DQS_DP<9>")
	)
	(segment
		(start 162.767772 -273.415506)
		(end 161.150046 -273.415506)
		(width 0.18288)
		(layer "In11.Cu")
		(net "M_H_CPU1_SA_DQS_DP<9>")
	)
	(segment
		(start 206.344266 -274.086574)
		(end 205.953614 -274.248372)
		(width 0.18288)
		(layer "In11.Cu")
		(net "M_H_CPU1_SA_DQS_DP<9>")
	)
	(segment
		(start 167.803068 -274.32254)
		(end 164.958014 -274.32254)
		(width 0.18288)
		(layer "In11.Cu")
		(net "M_H_CPU1_SA_DQS_DP<9>")
	)
	(segment
		(start 156.703014 -273.074384)
		(end 146.125184 -262.496554)
		(width 0.18288)
		(layer "In11.Cu")
		(net "M_H_CPU1_SA_DQS_DP<9>")
	)
	(segment
		(start 178.45786 -275.10232)
		(end 177.775616 -275.38553)
		(width 0.18288)
		(layer "In11.Cu")
		(net "M_H_CPU1_SA_DQS_DP<9>")
	)
	(segment
		(start 185.228484 -273.685)
		(end 183.801004 -274.276058)
		(width 0.18288)
		(layer "In11.Cu")
		(net "M_H_CPU1_SA_DQS_DP<9>")
	)
	(segment
		(start 180.1241 -274.276058)
		(end 178.688238 -274.871434)
		(width 0.18288)
		(layer "In11.Cu")
		(net "M_H_CPU1_SA_DQS_DP<9>")
	)
	(segment
		(start 161.150046 -273.415506)
		(end 160.32607 -273.074384)
		(width 0.18288)
		(layer "In11.Cu")
		(net "M_H_CPU1_SA_DQS_DP<9>")
	)
	(segment
		(start 203.069698 -273.391376)
		(end 202.85456 -273.391376)
		(width 0.16002)
		(layer "In11.Cu")
		(net "M_H_CPU1_SA_DQS_DP<9>")
	)
	(segment
		(start 195.595748 -275.29028)
		(end 194.33794 -274.768564)
		(width 0.18288)
		(layer "In11.Cu")
		(net "M_H_CPU1_SA_DQS_DP<9>")
	)
	(segment
		(start 203.461874 -273.666712)
		(end 203.186538 -273.391376)
		(width 0.18288)
		(layer "In11.Cu")
		(net "M_H_CPU1_SA_DQS_DP<9>")
	)
	(segment
		(start 137.877296 -260.75513)
		(end 137.876534 -260.754622)
		(width 0.088646)
		(layer "In11.Cu")
		(net "M_H_CPU1_SA_DQS_DP<9>")
	)
	(segment
		(start 136.467342 -259.941314)
		(end 136.45261 -259.932678)
		(width 0.088646)
		(layer "In11.Cu")
		(net "M_H_CPU1_SA_DQS_DP<9>")
	)
	(segment
		(start 204.387958 -274.248372)
		(end 203.806298 -273.666712)
		(width 0.18288)
		(layer "In11.Cu")
		(net "M_H_CPU1_SA_DQS_DP<9>")
	)
	(segment
		(start 190.687452 -275.234654)
		(end 189.147704 -273.694906)
		(width 0.18288)
		(layer "In11.Cu")
		(net "M_H_CPU1_SA_DQS_DP<9>")
	)
	(segment
		(start 189.147704 -273.694906)
		(end 188.3918 -273.694906)
		(width 0.18288)
		(layer "In11.Cu")
		(net "M_H_CPU1_SA_DQS_DP<9>")
	)
	(segment
		(start 137.876534 -260.754622)
		(end 137.868406 -260.75005)
		(width 0.088646)
		(layer "In11.Cu")
		(net "M_H_CPU1_SA_DQS_DP<9>")
	)
	(segment
		(start 200.883266 -273.9263)
		(end 197.601586 -275.29028)
		(width 0.18288)
		(layer "In11.Cu")
		(net "M_H_CPU1_SA_DQS_DP<9>")
	)
	(segment
		(start 206.801212 -274.086574)
		(end 206.344266 -274.086574)
		(width 0.18288)
		(layer "In11.Cu")
		(net "M_H_CPU1_SA_DQS_DP<9>")
	)
	(segment
		(start 197.601586 -275.29028)
		(end 195.595748 -275.29028)
		(width 0.18288)
		(layer "In11.Cu")
		(net "M_H_CPU1_SA_DQS_DP<9>")
	)
	(segment
		(start 191.71539 -275.09089)
		(end 191.44361 -275.362162)
		(width 0.18288)
		(layer "In11.Cu")
		(net "M_H_CPU1_SA_DQS_DP<9>")
	)
	(segment
		(start 137.413238 -259.94487)
		(end 137.407904 -259.941822)
		(width 0.088646)
		(layer "In11.Cu")
		(net "M_H_CPU1_SA_DQS_DP<9>")
	)
	(segment
		(start 125.66015 -260.106414)
		(end 125.65126 -260.111494)
		(width 0.088646)
		(layer "In11.Cu")
		(net "M_H_CPU1_SA_DQS_DP<9>")
	)
	(segment
		(start 140.390626 -262.556244)
		(end 140.26769 -262.433308)
		(width 0.088646)
		(layer "In11.Cu")
		(net "M_H_CPU1_SA_DQS_DP<9>")
	)
	(segment
		(start 125.884178 -260.014212)
		(end 125.786896 -260.038596)
		(width 0.088646)
		(layer "In11.Cu")
		(net "M_H_CPU1_SA_DQS_DP<9>")
	)
	(segment
		(start 188.087762 -273.390868)
		(end 187.615322 -273.390868)
		(width 0.18288)
		(layer "In11.Cu")
		(net "M_H_CPU1_SA_DQS_DP<9>")
	)
	(segment
		(start 203.806298 -273.666712)
		(end 203.461874 -273.666712)
		(width 0.18288)
		(layer "In11.Cu")
		(net "M_H_CPU1_SA_DQS_DP<9>")
	)
	(segment
		(start 173.358302 -273.699224)
		(end 173.049946 -273.390868)
		(width 0.18288)
		(layer "In11.Cu")
		(net "M_H_CPU1_SA_DQS_DP<9>")
	)
	(segment
		(start 131.768596 -259.941314)
		(end 131.753864 -259.932678)
		(width 0.088646)
		(layer "In11.Cu")
		(net "M_H_CPU1_SA_DQS_DP<9>")
	)
	(segment
		(start 135.527542 -259.941314)
		(end 135.517128 -259.935218)
		(width 0.088646)
		(layer "In11.Cu")
		(net "M_H_CPU1_SA_DQS_DP<9>")
	)
	(segment
		(start 205.953614 -274.248372)
		(end 204.387958 -274.248372)
		(width 0.18288)
		(layer "In11.Cu")
		(net "M_H_CPU1_SA_DQS_DP<9>")
	)
	(segment
		(start 202.383898 -273.9263)
		(end 200.883266 -273.9263)
		(width 0.18288)
		(layer "In11.Cu")
		(net "M_H_CPU1_SA_DQS_DP<9>")
	)
	(segment
		(start 130.828796 -259.941314)
		(end 130.814064 -259.932678)
		(width 0.088646)
		(layer "In11.Cu")
		(net "M_H_CPU1_SA_DQS_DP<9>")
	)
	(segment
		(start 187.615322 -273.390868)
		(end 187.32119 -273.685)
		(width 0.18288)
		(layer "In11.Cu")
		(net "M_H_CPU1_SA_DQS_DP<9>")
	)
	(segment
		(start 134.587996 -259.941314)
		(end 134.573264 -259.932678)
		(width 0.088646)
		(layer "In11.Cu")
		(net "M_H_CPU1_SA_DQS_DP<9>")
	)
	(segment
		(start 183.801004 -274.276058)
		(end 180.1241 -274.276058)
		(width 0.18288)
		(layer "In11.Cu")
		(net "M_H_CPU1_SA_DQS_DP<9>")
	)
	(segment
		(start 187.32119 -273.685)
		(end 185.228484 -273.685)
		(width 0.18288)
		(layer "In11.Cu")
		(net "M_H_CPU1_SA_DQS_DP<9>")
	)
	(segment
		(start 202.702922 -273.391376)
		(end 202.493372 -273.600926)
		(width 0.18288)
		(layer "In11.Cu")
		(net "M_H_CPU1_SA_DQS_DP<9>")
	)
	(segment
		(start 176.62779 -275.09089)
		(end 176.349152 -275.369528)
		(width 0.18288)
		(layer "In11.Cu")
		(net "M_H_CPU1_SA_DQS_DP<9>")
	)
	(segment
		(start 178.688238 -274.871434)
		(end 178.45786 -275.10232)
		(width 0.18288)
		(layer "In11.Cu")
		(net "M_H_CPU1_SA_DQS_DP<9>")
	)
	(segment
		(start 177.124614 -275.09089)
		(end 176.62779 -275.09089)
		(width 0.18288)
		(layer "In11.Cu")
		(net "M_H_CPU1_SA_DQS_DP<9>")
	)
	(segment
		(start 140.26769 -262.433308)
		(end 139.944348 -262.433308)
		(width 0.088646)
		(layer "In11.Cu")
		(net "M_H_CPU1_SA_DQS_DP<9>")
	)
	(segment
		(start 203.186538 -273.391376)
		(end 203.069698 -273.391376)
		(width 0.18288)
		(layer "In11.Cu")
		(net "M_H_CPU1_SA_DQS_DP<9>")
	)
	(segment
		(start 202.493372 -273.816826)
		(end 202.383898 -273.9263)
		(width 0.18288)
		(layer "In11.Cu")
		(net "M_H_CPU1_SA_DQS_DP<9>")
	)
	(segment
		(start 128.009396 -259.941314)
		(end 127.994664 -259.932678)
		(width 0.088646)
		(layer "In11.Cu")
		(net "M_H_CPU1_SA_DQS_DP<9>")
	)
	(segment
		(start 125.480064 -260.356604)
		(end 125.405896 -260.430772)
		(width 0.088646)
		(layer "In11.Cu")
		(net "M_H_CPU1_SA_DQS_DP<9>")
	)
	(segment
		(start 164.958014 -274.32254)
		(end 162.767518 -273.41576)
		(width 0.18288)
		(layer "In11.Cu")
		(net "M_H_CPU1_SA_DQS_DP<9>")
	)
	(segment
		(start 138.7221 -261.568692)
		(end 138.721592 -261.5692)
		(width 0.088646)
		(layer "In11.Cu")
		(net "M_H_CPU1_SA_DQS_DP<9>")
	)
	(segment
		(start 191.44361 -275.362162)
		(end 190.996316 -275.362162)
		(width 0.18288)
		(layer "In11.Cu")
		(net "M_H_CPU1_SA_DQS_DP<9>")
	)
	(segment
		(start 127.069596 -259.941314)
		(end 127.069596 -259.941568)
		(width 0.088646)
		(layer "In11.Cu")
		(net "M_H_CPU1_SA_DQS_DP<9>")
	)
	(segment
		(start 140.842746 -262.556244)
		(end 140.390626 -262.556244)
		(width 0.088646)
		(layer "In11.Cu")
		(net "M_H_CPU1_SA_DQS_DP<9>")
	)
	(segment
		(start 160.32607 -273.074384)
		(end 156.703014 -273.074384)
		(width 0.18288)
		(layer "In11.Cu")
		(net "M_H_CPU1_SA_DQS_DP<9>")
	)
	(segment
		(start 137.407904 -259.941822)
		(end 137.39241 -259.932678)
		(width 0.088646)
		(layer "In11.Cu")
		(net "M_H_CPU1_SA_DQS_DP<9>")
	)
	(segment
		(start 192.74917 -275.394928)
		(end 192.487296 -275.394928)
		(width 0.18288)
		(layer "In11.Cu")
		(net "M_H_CPU1_SA_DQS_DP<9>")
	)
	(segment
		(start 128.949196 -259.941314)
		(end 128.934464 -259.932678)
		(width 0.088646)
		(layer "In11.Cu")
		(net "M_H_CPU1_SA_DQS_DP<9>")
	)
	(segment
		(start 172.240194 -273.678396)
		(end 171.040552 -273.678396)
		(width 0.18288)
		(layer "In11.Cu")
		(net "M_H_CPU1_SA_DQS_DP<9>")
	)
	(segment
		(start 194.029838 -274.768564)
		(end 192.911984 -275.232114)
		(width 0.18288)
		(layer "In11.Cu")
		(net "M_H_CPU1_SA_DQS_DP<9>")
	)
	(segment
		(start 202.85456 -273.391376)
		(end 202.702922 -273.391376)
		(width 0.18288)
		(layer "In11.Cu")
		(net "M_H_CPU1_SA_DQS_DP<9>")
	)
	(segment
		(start 126.440946 -259.976874)
		(end 126.347474 -260.002528)
		(width 0.088646)
		(layer "In11.Cu")
		(net "M_H_CPU1_SA_DQS_DP<9>")
	)
	(segment
		(start 176.349152 -275.369528)
		(end 175.664876 -275.369528)
		(width 0.18288)
		(layer "In11.Cu")
		(net "M_H_CPU1_SA_DQS_DP<9>")
	)
	(segment
		(start 190.996316 -275.362162)
		(end 190.687452 -275.234654)
		(width 0.18288)
		(layer "In11.Cu")
		(net "M_H_CPU1_SA_DQS_DP<9>")
	)
	(segment
		(start 162.767518 -273.41576)
		(end 162.767772 -273.415506)
		(width 0.18288)
		(layer "In11.Cu")
		(net "M_H_CPU1_SA_DQS_DP<9>")
	)
	(segment
		(start 129.888996 -259.941314)
		(end 129.874264 -259.932678)
		(width 0.088646)
		(layer "In11.Cu")
		(net "M_H_CPU1_SA_DQS_DP<9>")
	)
	(segment
		(start 207.071214 -273.816572)
		(end 206.801212 -274.086574)
		(width 0.18288)
		(layer "In11.Cu")
		(net "M_H_CPU1_SA_DQS_DP<9>")
	)
	(segment
		(start 125.405896 -260.430772)
		(end 124.907548 -260.430772)
		(width 0.088646)
		(layer "In11.Cu")
		(net "M_H_CPU1_SA_DQS_DP<9>")
	)
	(segment
		(start 140.902436 -262.496554)
		(end 140.842746 -262.556244)
		(width 0.088646)
		(layer "In11.Cu")
		(net "M_H_CPU1_SA_DQS_DP<9>")
	)
	(segment
		(start 139.569698 -262.06704)
		(end 139.569698 -262.030464)
		(width 0.088646)
		(layer "In11.Cu")
		(net "M_H_CPU1_SA_DQS_DP<9>")
	)
	(segment
		(start 132.708396 -259.941314)
		(end 132.693664 -259.932678)
		(width 0.088646)
		(layer "In11.Cu")
		(net "M_H_CPU1_SA_DQS_DP<9>")
	)
	(segment
		(start 138.159744 -261.244842)
		(end 138.159744 -261.2263)
		(width 0.088646)
		(layer "In11.Cu")
		(net "M_H_CPU1_SA_DQS_DP<9>")
	)
	(segment
		(start 146.125184 -262.496554)
		(end 140.902436 -262.496554)
		(width 0.18288)
		(layer "In11.Cu")
		(net "M_H_CPU1_SA_DQS_DP<9>")
	)
	(segment
		(start 171.040552 -273.678396)
		(end 167.803068 -274.32254)
		(width 0.18288)
		(layer "In11.Cu")
		(net "M_H_CPU1_SA_DQS_DP<9>")
	)
	(arc
		(start 125.65126 -260.111494)
		(mid 125.540162 -260.216237)
		(end 125.480064 -260.356604)
		(width 0.088646)
		(layer "In11.Cu")
		(net "M_H_CPU1_SA_DQS_DP<9>")
	)
	(arc
		(start 134.573264 -259.932678)
		(mid 134.296789 -259.865358)
		(end 134.022592 -259.941314)
		(width 0.088646)
		(layer "In11.Cu")
		(net "M_H_CPU1_SA_DQS_DP<9>")
	)
	(arc
		(start 131.753864 -259.932678)
		(mid 131.477389 -259.865358)
		(end 131.203192 -259.941314)
		(width 0.088646)
		(layer "In11.Cu")
		(net "M_H_CPU1_SA_DQS_DP<9>")
	)
	(arc
		(start 130.263392 -259.941314)
		(mid 130.076194 -259.991457)
		(end 129.888996 -259.941314)
		(width 0.088646)
		(layer "In11.Cu")
		(net "M_H_CPU1_SA_DQS_DP<9>")
	)
	(arc
		(start 132.693664 -259.932678)
		(mid 132.417189 -259.865358)
		(end 132.142992 -259.941314)
		(width 0.088646)
		(layer "In11.Cu")
		(net "M_H_CPU1_SA_DQS_DP<9>")
	)
	(arc
		(start 137.39241 -259.932678)
		(mid 137.115935 -259.865358)
		(end 136.841738 -259.941314)
		(width 0.088646)
		(layer "In11.Cu")
		(net "M_H_CPU1_SA_DQS_DP<9>")
	)
	(arc
		(start 139.569698 -262.030464)
		(mid 139.280702 -261.564676)
		(end 138.732514 -261.562596)
		(width 0.088646)
		(layer "In11.Cu")
		(net "M_H_CPU1_SA_DQS_DP<9>")
	)
	(arc
		(start 130.814064 -259.932678)
		(mid 130.537589 -259.865358)
		(end 130.263392 -259.941314)
		(width 0.088646)
		(layer "In11.Cu")
		(net "M_H_CPU1_SA_DQS_DP<9>")
	)
	(arc
		(start 134.962392 -259.941314)
		(mid 134.775194 -259.991457)
		(end 134.587996 -259.941314)
		(width 0.088646)
		(layer "In11.Cu")
		(net "M_H_CPU1_SA_DQS_DP<9>")
	)
	(arc
		(start 129.874264 -259.932678)
		(mid 129.597789 -259.865358)
		(end 129.323592 -259.941314)
		(width 0.088646)
		(layer "In11.Cu")
		(net "M_H_CPU1_SA_DQS_DP<9>")
	)
	(arc
		(start 135.901938 -259.941314)
		(mid 135.71474 -259.991457)
		(end 135.527542 -259.941314)
		(width 0.088646)
		(layer "In11.Cu")
		(net "M_H_CPU1_SA_DQS_DP<9>")
	)
	(arc
		(start 134.022592 -259.941314)
		(mid 133.835394 -259.991457)
		(end 133.648196 -259.941314)
		(width 0.088646)
		(layer "In11.Cu")
		(net "M_H_CPU1_SA_DQS_DP<9>")
	)
	(arc
		(start 127.069596 -259.941568)
		(mid 126.78672 -259.865758)
		(end 126.503938 -259.941822)
		(width 0.088646)
		(layer "In11.Cu")
		(net "M_H_CPU1_SA_DQS_DP<9>")
	)
	(arc
		(start 128.383792 -259.941314)
		(mid 128.196594 -259.991457)
		(end 128.009396 -259.941314)
		(width 0.088646)
		(layer "In11.Cu")
		(net "M_H_CPU1_SA_DQS_DP<9>")
	)
	(arc
		(start 136.45261 -259.932678)
		(mid 136.176135 -259.865358)
		(end 135.901938 -259.941314)
		(width 0.088646)
		(layer "In11.Cu")
		(net "M_H_CPU1_SA_DQS_DP<9>")
	)
	(arc
		(start 138.159744 -261.2263)
		(mid 138.079582 -260.954111)
		(end 137.877296 -260.75513)
		(width 0.088646)
		(layer "In11.Cu")
		(net "M_H_CPU1_SA_DQS_DP<9>")
	)
	(arc
		(start 133.082792 -259.941314)
		(mid 132.895594 -259.991457)
		(end 132.708396 -259.941314)
		(width 0.088646)
		(layer "In11.Cu")
		(net "M_H_CPU1_SA_DQS_DP<9>")
	)
	(arc
		(start 132.142992 -259.941314)
		(mid 131.955794 -259.991457)
		(end 131.768596 -259.941314)
		(width 0.088646)
		(layer "In11.Cu")
		(net "M_H_CPU1_SA_DQS_DP<9>")
	)
	(arc
		(start 131.203192 -259.941314)
		(mid 131.015994 -259.991457)
		(end 130.828796 -259.941314)
		(width 0.088646)
		(layer "In11.Cu")
		(net "M_H_CPU1_SA_DQS_DP<9>")
	)
	(arc
		(start 135.517128 -259.935218)
		(mid 135.23895 -259.865495)
		(end 134.962392 -259.941314)
		(width 0.088646)
		(layer "In11.Cu")
		(net "M_H_CPU1_SA_DQS_DP<9>")
	)
	(arc
		(start 127.994664 -259.932678)
		(mid 127.718189 -259.865358)
		(end 127.443992 -259.941314)
		(width 0.088646)
		(layer "In11.Cu")
		(net "M_H_CPU1_SA_DQS_DP<9>")
	)
	(arc
		(start 138.721592 -261.5692)
		(mid 138.347117 -261.569154)
		(end 138.159744 -261.244842)
		(width 0.088646)
		(layer "In11.Cu")
		(net "M_H_CPU1_SA_DQS_DP<9>")
	)
	(arc
		(start 125.908816 -260.01091)
		(mid 125.896401 -260.011848)
		(end 125.884178 -260.014212)
		(width 0.088646)
		(layer "In11.Cu")
		(net "M_H_CPU1_SA_DQS_DP<9>")
	)
	(arc
		(start 139.944348 -262.433308)
		(mid 139.847298 -262.420374)
		(end 139.756896 -262.382762)
		(width 0.088646)
		(layer "In11.Cu")
		(net "M_H_CPU1_SA_DQS_DP<9>")
	)
	(arc
		(start 137.868406 -260.75005)
		(mid 137.737492 -260.61369)
		(end 137.689844 -260.430772)
		(width 0.088646)
		(layer "In11.Cu")
		(net "M_H_CPU1_SA_DQS_DP<9>")
	)
	(arc
		(start 127.443992 -259.941314)
		(mid 127.256794 -259.991457)
		(end 127.069596 -259.941314)
		(width 0.088646)
		(layer "In11.Cu")
		(net "M_H_CPU1_SA_DQS_DP<9>")
	)
	(arc
		(start 139.756896 -262.382762)
		(mid 139.621963 -262.249408)
		(end 139.569698 -262.06704)
		(width 0.088646)
		(layer "In11.Cu")
		(net "M_H_CPU1_SA_DQS_DP<9>")
	)
	(arc
		(start 133.648196 -259.941314)
		(mid 133.365494 -259.865538)
		(end 133.082792 -259.941314)
		(width 0.088646)
		(layer "In11.Cu")
		(net "M_H_CPU1_SA_DQS_DP<9>")
	)
	(arc
		(start 129.323592 -259.941314)
		(mid 129.136394 -259.991457)
		(end 128.949196 -259.941314)
		(width 0.088646)
		(layer "In11.Cu")
		(net "M_H_CPU1_SA_DQS_DP<9>")
	)
	(arc
		(start 128.934464 -259.932678)
		(mid 128.657989 -259.865358)
		(end 128.383792 -259.941314)
		(width 0.088646)
		(layer "In11.Cu")
		(net "M_H_CPU1_SA_DQS_DP<9>")
	)
	(arc
		(start 137.689844 -260.430772)
		(mid 137.615853 -260.151206)
		(end 137.413238 -259.94487)
		(width 0.088646)
		(layer "In11.Cu")
		(net "M_H_CPU1_SA_DQS_DP<9>")
	)
	(arc
		(start 136.841738 -259.941314)
		(mid 136.65454 -259.991457)
		(end 136.467342 -259.941314)
		(width 0.088646)
		(layer "In11.Cu")
		(net "M_H_CPU1_SA_DQS_DP<9>")
	)
	(segment
		(start 214.30615 -283.43479)
		(end 214.883746 -283.43479)
		(width 0.20066)
		(layer "F.Cu")
		(net "M_H_CPU1_SA_DQS_DP<8>")
	)
	(segment
		(start 213.207092 -282.989274)
		(end 213.860634 -282.989274)
		(width 0.20066)
		(layer "F.Cu")
		(net "M_H_CPU1_SA_DQS_DP<8>")
	)
	(segment
		(start 215.15197 -283.166566)
		(end 215.719914 -283.166566)
		(width 0.20066)
		(layer "F.Cu")
		(net "M_H_CPU1_SA_DQS_DP<8>")
	)
	(segment
		(start 207.071214 -283.166566)
		(end 208.176114 -283.166566)
		(width 0.20066)
		(layer "F.Cu")
		(net "M_H_CPU1_SA_DQS_DP<8>")
	)
	(segment
		(start 214.883746 -283.43479)
		(end 215.15197 -283.166566)
		(width 0.20066)
		(layer "F.Cu")
		(net "M_H_CPU1_SA_DQS_DP<8>")
	)
	(segment
		(start 210.610196 -282.741624)
		(end 212.622892 -282.741624)
		(width 0.1016)
		(layer "F.Cu")
		(net "M_H_CPU1_SA_DQS_DP<8>")
	)
	(segment
		(start 210.603084 -282.734512)
		(end 210.610196 -282.741624)
		(width 0.1016)
		(layer "F.Cu")
		(net "M_H_CPU1_SA_DQS_DP<8>")
	)
	(segment
		(start 212.630258 -282.734258)
		(end 212.952076 -282.734258)
		(width 0.20066)
		(layer "F.Cu")
		(net "M_H_CPU1_SA_DQS_DP<8>")
	)
	(segment
		(start 209.325464 -283.417772)
		(end 209.750406 -282.99283)
		(width 0.20066)
		(layer "F.Cu")
		(net "M_H_CPU1_SA_DQS_DP<8>")
	)
	(segment
		(start 124.907294 -264.778236)
		(end 124.907294 -265.313922)
		(width 0.20066)
		(layer "F.Cu")
		(net "M_H_CPU1_SA_DQS_DP<8>")
	)
	(segment
		(start 210.02879 -282.99283)
		(end 210.287108 -282.734512)
		(width 0.20066)
		(layer "F.Cu")
		(net "M_H_CPU1_SA_DQS_DP<8>")
	)
	(segment
		(start 209.750406 -282.99283)
		(end 210.02879 -282.99283)
		(width 0.20066)
		(layer "F.Cu")
		(net "M_H_CPU1_SA_DQS_DP<8>")
	)
	(segment
		(start 124.907294 -265.313922)
		(end 124.907548 -265.314176)
		(width 0.20066)
		(layer "F.Cu")
		(net "M_H_CPU1_SA_DQS_DP<8>")
	)
	(segment
		(start 208.769458 -283.166566)
		(end 209.020664 -283.417772)
		(width 0.20066)
		(layer "F.Cu")
		(net "M_H_CPU1_SA_DQS_DP<8>")
	)
	(segment
		(start 212.952076 -282.734258)
		(end 213.207092 -282.989274)
		(width 0.20066)
		(layer "F.Cu")
		(net "M_H_CPU1_SA_DQS_DP<8>")
	)
	(segment
		(start 210.287108 -282.734512)
		(end 210.598258 -282.734512)
		(width 0.20066)
		(layer "F.Cu")
		(net "M_H_CPU1_SA_DQS_DP<8>")
	)
	(segment
		(start 210.598258 -282.734512)
		(end 210.603084 -282.734512)
		(width 0.101854)
		(layer "F.Cu")
		(net "M_H_CPU1_SA_DQS_DP<8>")
	)
	(segment
		(start 209.020664 -283.417772)
		(end 209.325464 -283.417772)
		(width 0.20066)
		(layer "F.Cu")
		(net "M_H_CPU1_SA_DQS_DP<8>")
	)
	(segment
		(start 213.860634 -282.989274)
		(end 214.30615 -283.43479)
		(width 0.20066)
		(layer "F.Cu")
		(net "M_H_CPU1_SA_DQS_DP<8>")
	)
	(segment
		(start 212.622892 -282.741624)
		(end 212.630258 -282.734258)
		(width 0.1016)
		(layer "F.Cu")
		(net "M_H_CPU1_SA_DQS_DP<8>")
	)
	(segment
		(start 208.176114 -283.166566)
		(end 208.769458 -283.166566)
		(width 0.20066)
		(layer "F.Cu")
		(net "M_H_CPU1_SA_DQS_DP<8>")
	)
	(segment
		(start 135.340344 -266.128246)
		(end 135.340344 -266.106148)
		(width 0.088646)
		(layer "In11.Cu")
		(net "M_H_CPU1_SA_DQS_DP<8>")
	)
	(segment
		(start 188.353446 -285.566358)
		(end 188.07811 -285.291022)
		(width 0.18288)
		(layer "In11.Cu")
		(net "M_H_CPU1_SA_DQS_DP<8>")
	)
	(segment
		(start 206.791814 -283.445966)
		(end 205.6892 -283.445966)
		(width 0.18288)
		(layer "In11.Cu")
		(net "M_H_CPU1_SA_DQS_DP<8>")
	)
	(segment
		(start 130.828796 -264.824718)
		(end 130.814064 -264.816082)
		(width 0.088646)
		(layer "In11.Cu")
		(net "M_H_CPU1_SA_DQS_DP<8>")
	)
	(segment
		(start 178.73726 -285.533338)
		(end 177.85461 -286.416242)
		(width 0.18288)
		(layer "In11.Cu")
		(net "M_H_CPU1_SA_DQS_DP<8>")
	)
	(segment
		(start 125.480064 -265.240008)
		(end 125.405896 -265.314176)
		(width 0.088646)
		(layer "In11.Cu")
		(net "M_H_CPU1_SA_DQS_DP<8>")
	)
	(segment
		(start 187.319412 -285.586932)
		(end 184.370472 -285.586932)
		(width 0.18288)
		(layer "In11.Cu")
		(net "M_H_CPU1_SA_DQS_DP<8>")
	)
	(segment
		(start 139.104624 -268.145514)
		(end 138.589004 -268.145514)
		(width 0.088646)
		(layer "In11.Cu")
		(net "M_H_CPU1_SA_DQS_DP<8>")
	)
	(segment
		(start 136.280144 -267.755878)
		(end 136.280144 -267.737336)
		(width 0.088646)
		(layer "In11.Cu")
		(net "M_H_CPU1_SA_DQS_DP<8>")
	)
	(segment
		(start 157.458664 -282.409392)
		(end 143.640048 -268.590776)
		(width 0.18288)
		(layer "In11.Cu")
		(net "M_H_CPU1_SA_DQS_DP<8>")
	)
	(segment
		(start 187.615322 -285.291022)
		(end 187.319412 -285.586932)
		(width 0.18288)
		(layer "In11.Cu")
		(net "M_H_CPU1_SA_DQS_DP<8>")
	)
	(segment
		(start 129.323846 -264.824718)
		(end 129.319274 -264.827512)
		(width 0.088646)
		(layer "In11.Cu")
		(net "M_H_CPU1_SA_DQS_DP<8>")
	)
	(segment
		(start 175.215804 -286.408114)
		(end 174.32909 -286.77616)
		(width 0.18288)
		(layer "In11.Cu")
		(net "M_H_CPU1_SA_DQS_DP<8>")
	)
	(segment
		(start 204.126592 -282.996132)
		(end 203.472034 -282.996132)
		(width 0.18288)
		(layer "In11.Cu")
		(net "M_H_CPU1_SA_DQS_DP<8>")
	)
	(segment
		(start 135.05815 -265.638534)
		(end 135.057134 -265.638026)
		(width 0.088646)
		(layer "In11.Cu")
		(net "M_H_CPU1_SA_DQS_DP<8>")
	)
	(segment
		(start 134.594092 -264.828274)
		(end 134.588758 -264.825226)
		(width 0.088646)
		(layer "In11.Cu")
		(net "M_H_CPU1_SA_DQS_DP<8>")
	)
	(segment
		(start 128.391412 -264.8204)
		(end 128.384046 -264.824718)
		(width 0.088646)
		(layer "In11.Cu")
		(net "M_H_CPU1_SA_DQS_DP<8>")
	)
	(segment
		(start 200.94194 -283.275532)
		(end 200.14692 -284.070552)
		(width 0.18288)
		(layer "In11.Cu")
		(net "M_H_CPU1_SA_DQS_DP<8>")
	)
	(segment
		(start 126.511812 -264.8204)
		(end 126.499874 -264.827512)
		(width 0.088646)
		(layer "In11.Cu")
		(net "M_H_CPU1_SA_DQS_DP<8>")
	)
	(segment
		(start 134.588758 -264.825226)
		(end 134.573264 -264.816082)
		(width 0.088646)
		(layer "In11.Cu")
		(net "M_H_CPU1_SA_DQS_DP<8>")
	)
	(segment
		(start 174.32909 -286.77616)
		(end 173.925738 -287.179258)
		(width 0.18288)
		(layer "In11.Cu")
		(net "M_H_CPU1_SA_DQS_DP<8>")
	)
	(segment
		(start 167.844724 -284.949392)
		(end 165.486842 -284.949392)
		(width 0.18288)
		(layer "In11.Cu")
		(net "M_H_CPU1_SA_DQS_DP<8>")
	)
	(segment
		(start 164.37864 -284.12059)
		(end 162.221418 -284.12059)
		(width 0.18288)
		(layer "In11.Cu")
		(net "M_H_CPU1_SA_DQS_DP<8>")
	)
	(segment
		(start 131.768596 -264.824718)
		(end 131.753864 -264.816082)
		(width 0.088646)
		(layer "In11.Cu")
		(net "M_H_CPU1_SA_DQS_DP<8>")
	)
	(segment
		(start 203.450952 -282.988512)
		(end 203.203556 -282.741116)
		(width 0.18288)
		(layer "In11.Cu")
		(net "M_H_CPU1_SA_DQS_DP<8>")
	)
	(segment
		(start 203.464414 -282.988512)
		(end 203.450952 -282.988512)
		(width 0.18288)
		(layer "In11.Cu")
		(net "M_H_CPU1_SA_DQS_DP<8>")
	)
	(segment
		(start 138.406886 -268.109954)
		(end 138.406886 -268.1097)
		(width 0.088646)
		(layer "In11.Cu")
		(net "M_H_CPU1_SA_DQS_DP<8>")
	)
	(segment
		(start 125.884178 -264.897616)
		(end 125.786896 -264.922)
		(width 0.088646)
		(layer "In11.Cu")
		(net "M_H_CPU1_SA_DQS_DP<8>")
	)
	(segment
		(start 202.782932 -282.741116)
		(end 202.509882 -283.014166)
		(width 0.18288)
		(layer "In11.Cu")
		(net "M_H_CPU1_SA_DQS_DP<8>")
	)
	(segment
		(start 172.22597 -287.292796)
		(end 171.911264 -287.292796)
		(width 0.18288)
		(layer "In11.Cu")
		(net "M_H_CPU1_SA_DQS_DP<8>")
	)
	(segment
		(start 192.46469 -286.416242)
		(end 192.189354 -286.140906)
		(width 0.18288)
		(layer "In11.Cu")
		(net "M_H_CPU1_SA_DQS_DP<8>")
	)
	(segment
		(start 195.267834 -284.807406)
		(end 194.422268 -285.652718)
		(width 0.18288)
		(layer "In11.Cu")
		(net "M_H_CPU1_SA_DQS_DP<8>")
	)
	(segment
		(start 184.370472 -285.586932)
		(end 182.714138 -284.900878)
		(width 0.18288)
		(layer "In11.Cu")
		(net "M_H_CPU1_SA_DQS_DP<8>")
	)
	(segment
		(start 133.09346 -264.818622)
		(end 133.083046 -264.824718)
		(width 0.088646)
		(layer "In11.Cu")
		(net "M_H_CPU1_SA_DQS_DP<8>")
	)
	(segment
		(start 191.441832 -286.413702)
		(end 190.623698 -286.413702)
		(width 0.18288)
		(layer "In11.Cu")
		(net "M_H_CPU1_SA_DQS_DP<8>")
	)
	(segment
		(start 127.451612 -264.8204)
		(end 127.444246 -264.824718)
		(width 0.088646)
		(layer "In11.Cu")
		(net "M_H_CPU1_SA_DQS_DP<8>")
	)
	(segment
		(start 165.010084 -284.752034)
		(end 164.37864 -284.12059)
		(width 0.18288)
		(layer "In11.Cu")
		(net "M_H_CPU1_SA_DQS_DP<8>")
	)
	(segment
		(start 188.07811 -285.291022)
		(end 187.615322 -285.291022)
		(width 0.18288)
		(layer "In11.Cu")
		(net "M_H_CPU1_SA_DQS_DP<8>")
	)
	(segment
		(start 160.51022 -282.409392)
		(end 157.458664 -282.409392)
		(width 0.18288)
		(layer "In11.Cu")
		(net "M_H_CPU1_SA_DQS_DP<8>")
	)
	(segment
		(start 139.33424 -268.375384)
		(end 139.104624 -268.145514)
		(width 0.088646)
		(layer "In11.Cu")
		(net "M_H_CPU1_SA_DQS_DP<8>")
	)
	(segment
		(start 135.810498 -266.950444)
		(end 135.810498 -266.941808)
		(width 0.088646)
		(layer "In11.Cu")
		(net "M_H_CPU1_SA_DQS_DP<8>")
	)
	(segment
		(start 201.968862 -283.275532)
		(end 200.94194 -283.275532)
		(width 0.18288)
		(layer "In11.Cu")
		(net "M_H_CPU1_SA_DQS_DP<8>")
	)
	(segment
		(start 140.684504 -268.590776)
		(end 140.624814 -268.650466)
		(width 0.088646)
		(layer "In11.Cu")
		(net "M_H_CPU1_SA_DQS_DP<8>")
	)
	(segment
		(start 205.302104 -283.60624)
		(end 205.047088 -283.60624)
		(width 0.18288)
		(layer "In11.Cu")
		(net "M_H_CPU1_SA_DQS_DP<8>")
	)
	(segment
		(start 198.069962 -284.807406)
		(end 195.267834 -284.807406)
		(width 0.18288)
		(layer "In11.Cu")
		(net "M_H_CPU1_SA_DQS_DP<8>")
	)
	(segment
		(start 200.14692 -284.070552)
		(end 198.806816 -284.070552)
		(width 0.18288)
		(layer "In11.Cu")
		(net "M_H_CPU1_SA_DQS_DP<8>")
	)
	(segment
		(start 172.981874 -286.991044)
		(end 172.527722 -286.991044)
		(width 0.18288)
		(layer "In11.Cu")
		(net "M_H_CPU1_SA_DQS_DP<8>")
	)
	(segment
		(start 128.384046 -264.824718)
		(end 128.379474 -264.827512)
		(width 0.088646)
		(layer "In11.Cu")
		(net "M_H_CPU1_SA_DQS_DP<8>")
	)
	(segment
		(start 173.25721 -287.26638)
		(end 172.981874 -286.991044)
		(width 0.18288)
		(layer "In11.Cu")
		(net "M_H_CPU1_SA_DQS_DP<8>")
	)
	(segment
		(start 173.715426 -287.26638)
		(end 173.25721 -287.26638)
		(width 0.18288)
		(layer "In11.Cu")
		(net "M_H_CPU1_SA_DQS_DP<8>")
	)
	(segment
		(start 140.624814 -268.650466)
		(end 139.839954 -268.650466)
		(width 0.088646)
		(layer "In11.Cu")
		(net "M_H_CPU1_SA_DQS_DP<8>")
	)
	(segment
		(start 127.444246 -264.824718)
		(end 127.439674 -264.827512)
		(width 0.088646)
		(layer "In11.Cu")
		(net "M_H_CPU1_SA_DQS_DP<8>")
	)
	(segment
		(start 135.057134 -265.638026)
		(end 135.04926 -265.633454)
		(width 0.088646)
		(layer "In11.Cu")
		(net "M_H_CPU1_SA_DQS_DP<8>")
	)
	(segment
		(start 202.509882 -283.014166)
		(end 202.230228 -283.014166)
		(width 0.18288)
		(layer "In11.Cu")
		(net "M_H_CPU1_SA_DQS_DP<8>")
	)
	(segment
		(start 162.221418 -284.12059)
		(end 160.51022 -282.409392)
		(width 0.18288)
		(layer "In11.Cu")
		(net "M_H_CPU1_SA_DQS_DP<8>")
	)
	(segment
		(start 173.925738 -287.179258)
		(end 173.715426 -287.26638)
		(width 0.18288)
		(layer "In11.Cu")
		(net "M_H_CPU1_SA_DQS_DP<8>")
	)
	(segment
		(start 203.05141 -282.741116)
		(end 202.917298 -282.741116)
		(width 0.16002)
		(layer "In11.Cu")
		(net "M_H_CPU1_SA_DQS_DP<8>")
	)
	(segment
		(start 172.527722 -286.991044)
		(end 172.22597 -287.292796)
		(width 0.18288)
		(layer "In11.Cu")
		(net "M_H_CPU1_SA_DQS_DP<8>")
	)
	(segment
		(start 169.829988 -285.771336)
		(end 167.844724 -284.949392)
		(width 0.18288)
		(layer "In11.Cu")
		(net "M_H_CPU1_SA_DQS_DP<8>")
	)
	(segment
		(start 205.6892 -283.445966)
		(end 205.302104 -283.60624)
		(width 0.18288)
		(layer "In11.Cu")
		(net "M_H_CPU1_SA_DQS_DP<8>")
	)
	(segment
		(start 165.486842 -284.949392)
		(end 165.010084 -284.752034)
		(width 0.18288)
		(layer "In11.Cu")
		(net "M_H_CPU1_SA_DQS_DP<8>")
	)
	(segment
		(start 190.623698 -286.413702)
		(end 189.766448 -286.058356)
		(width 0.18288)
		(layer "In11.Cu")
		(net "M_H_CPU1_SA_DQS_DP<8>")
	)
	(segment
		(start 132.70865 -264.824718)
		(end 132.698236 -264.818622)
		(width 0.088646)
		(layer "In11.Cu")
		(net "M_H_CPU1_SA_DQS_DP<8>")
	)
	(segment
		(start 171.911264 -287.292796)
		(end 170.791124 -286.732726)
		(width 0.18288)
		(layer "In11.Cu")
		(net "M_H_CPU1_SA_DQS_DP<8>")
	)
	(segment
		(start 192.993264 -286.416242)
		(end 192.46469 -286.416242)
		(width 0.18288)
		(layer "In11.Cu")
		(net "M_H_CPU1_SA_DQS_DP<8>")
	)
	(segment
		(start 126.499874 -264.827512)
		(end 126.497588 -264.829036)
		(width 0.088646)
		(layer "In11.Cu")
		(net "M_H_CPU1_SA_DQS_DP<8>")
	)
	(segment
		(start 189.274196 -285.566358)
		(end 188.353446 -285.566358)
		(width 0.18288)
		(layer "In11.Cu")
		(net "M_H_CPU1_SA_DQS_DP<8>")
	)
	(segment
		(start 205.047088 -283.60624)
		(end 204.517498 -283.386784)
		(width 0.18288)
		(layer "In11.Cu")
		(net "M_H_CPU1_SA_DQS_DP<8>")
	)
	(segment
		(start 180.264308 -284.900878)
		(end 178.73726 -285.533338)
		(width 0.18288)
		(layer "In11.Cu")
		(net "M_H_CPU1_SA_DQS_DP<8>")
	)
	(segment
		(start 129.331212 -264.8204)
		(end 129.323846 -264.824718)
		(width 0.088646)
		(layer "In11.Cu")
		(net "M_H_CPU1_SA_DQS_DP<8>")
	)
	(segment
		(start 177.092102 -286.140906)
		(end 176.62779 -286.140906)
		(width 0.18288)
		(layer "In11.Cu")
		(net "M_H_CPU1_SA_DQS_DP<8>")
	)
	(segment
		(start 203.472034 -282.996132)
		(end 203.464414 -282.988512)
		(width 0.18288)
		(layer "In11.Cu")
		(net "M_H_CPU1_SA_DQS_DP<8>")
	)
	(segment
		(start 176.62779 -286.140906)
		(end 176.360582 -286.408114)
		(width 0.18288)
		(layer "In11.Cu")
		(net "M_H_CPU1_SA_DQS_DP<8>")
	)
	(segment
		(start 177.85461 -286.416242)
		(end 177.367438 -286.416242)
		(width 0.18288)
		(layer "In11.Cu")
		(net "M_H_CPU1_SA_DQS_DP<8>")
	)
	(segment
		(start 126.277878 -264.887456)
		(end 125.908816 -264.894314)
		(width 0.088646)
		(layer "In11.Cu")
		(net "M_H_CPU1_SA_DQS_DP<8>")
	)
	(segment
		(start 194.422268 -285.652718)
		(end 193.285618 -286.123634)
		(width 0.18288)
		(layer "In11.Cu")
		(net "M_H_CPU1_SA_DQS_DP<8>")
	)
	(segment
		(start 203.203556 -282.741116)
		(end 203.05141 -282.741116)
		(width 0.18288)
		(layer "In11.Cu")
		(net "M_H_CPU1_SA_DQS_DP<8>")
	)
	(segment
		(start 204.517498 -283.386784)
		(end 204.126592 -282.996132)
		(width 0.18288)
		(layer "In11.Cu")
		(net "M_H_CPU1_SA_DQS_DP<8>")
	)
	(segment
		(start 189.766448 -286.058356)
		(end 189.274196 -285.566358)
		(width 0.18288)
		(layer "In11.Cu")
		(net "M_H_CPU1_SA_DQS_DP<8>")
	)
	(segment
		(start 202.230228 -283.014166)
		(end 201.968862 -283.275532)
		(width 0.18288)
		(layer "In11.Cu")
		(net "M_H_CPU1_SA_DQS_DP<8>")
	)
	(segment
		(start 182.714138 -284.900878)
		(end 180.264308 -284.900878)
		(width 0.18288)
		(layer "In11.Cu")
		(net "M_H_CPU1_SA_DQS_DP<8>")
	)
	(segment
		(start 207.071214 -283.166566)
		(end 206.791814 -283.445966)
		(width 0.18288)
		(layer "In11.Cu")
		(net "M_H_CPU1_SA_DQS_DP<8>")
	)
	(segment
		(start 125.405896 -265.314176)
		(end 124.907548 -265.314176)
		(width 0.088646)
		(layer "In11.Cu")
		(net "M_H_CPU1_SA_DQS_DP<8>")
	)
	(segment
		(start 193.285618 -286.123634)
		(end 192.993264 -286.416242)
		(width 0.18288)
		(layer "In11.Cu")
		(net "M_H_CPU1_SA_DQS_DP<8>")
	)
	(segment
		(start 198.806816 -284.070552)
		(end 198.069962 -284.807406)
		(width 0.18288)
		(layer "In11.Cu")
		(net "M_H_CPU1_SA_DQS_DP<8>")
	)
	(segment
		(start 170.791124 -286.732726)
		(end 169.829988 -285.771336)
		(width 0.18288)
		(layer "In11.Cu")
		(net "M_H_CPU1_SA_DQS_DP<8>")
	)
	(segment
		(start 125.66015 -264.989818)
		(end 125.65126 -264.994898)
		(width 0.088646)
		(layer "In11.Cu")
		(net "M_H_CPU1_SA_DQS_DP<8>")
	)
	(segment
		(start 202.917298 -282.741116)
		(end 202.782932 -282.741116)
		(width 0.18288)
		(layer "In11.Cu")
		(net "M_H_CPU1_SA_DQS_DP<8>")
	)
	(segment
		(start 191.71539 -286.140906)
		(end 191.441832 -286.413702)
		(width 0.18288)
		(layer "In11.Cu")
		(net "M_H_CPU1_SA_DQS_DP<8>")
	)
	(segment
		(start 143.640048 -268.590776)
		(end 140.684504 -268.590776)
		(width 0.18288)
		(layer "In11.Cu")
		(net "M_H_CPU1_SA_DQS_DP<8>")
	)
	(segment
		(start 177.367438 -286.416242)
		(end 177.092102 -286.140906)
		(width 0.18288)
		(layer "In11.Cu")
		(net "M_H_CPU1_SA_DQS_DP<8>")
	)
	(segment
		(start 125.786896 -264.922)
		(end 125.66015 -264.989818)
		(width 0.088646)
		(layer "In11.Cu")
		(net "M_H_CPU1_SA_DQS_DP<8>")
	)
	(segment
		(start 192.189354 -286.140906)
		(end 191.71539 -286.140906)
		(width 0.18288)
		(layer "In11.Cu")
		(net "M_H_CPU1_SA_DQS_DP<8>")
	)
	(segment
		(start 139.564872 -268.375384)
		(end 139.33424 -268.375384)
		(width 0.088646)
		(layer "In11.Cu")
		(net "M_H_CPU1_SA_DQS_DP<8>")
	)
	(segment
		(start 139.839954 -268.650466)
		(end 139.564872 -268.375384)
		(width 0.088646)
		(layer "In11.Cu")
		(net "M_H_CPU1_SA_DQS_DP<8>")
	)
	(segment
		(start 176.360582 -286.408114)
		(end 175.215804 -286.408114)
		(width 0.18288)
		(layer "In11.Cu")
		(net "M_H_CPU1_SA_DQS_DP<8>")
	)
	(segment
		(start 135.533892 -266.455906)
		(end 135.513572 -266.444222)
		(width 0.088646)
		(layer "In11.Cu")
		(net "M_H_CPU1_SA_DQS_DP<8>")
	)
	(arc
		(start 134.573264 -264.816082)
		(mid 134.296789 -264.748762)
		(end 134.022592 -264.824718)
		(width 0.088646)
		(layer "In11.Cu")
		(net "M_H_CPU1_SA_DQS_DP<8>")
	)
	(arc
		(start 125.65126 -264.994898)
		(mid 125.540162 -265.099641)
		(end 125.480064 -265.240008)
		(width 0.088646)
		(layer "In11.Cu")
		(net "M_H_CPU1_SA_DQS_DP<8>")
	)
	(arc
		(start 127.439674 -264.827512)
		(mid 127.25426 -264.875024)
		(end 127.069596 -264.824718)
		(width 0.088646)
		(layer "In11.Cu")
		(net "M_H_CPU1_SA_DQS_DP<8>")
	)
	(arc
		(start 128.009396 -264.824718)
		(mid 127.731073 -264.748959)
		(end 127.451612 -264.8204)
		(width 0.088646)
		(layer "In11.Cu")
		(net "M_H_CPU1_SA_DQS_DP<8>")
	)
	(arc
		(start 129.319274 -264.827512)
		(mid 129.13386 -264.875024)
		(end 128.949196 -264.824718)
		(width 0.088646)
		(layer "In11.Cu")
		(net "M_H_CPU1_SA_DQS_DP<8>")
	)
	(arc
		(start 129.888996 -264.824718)
		(mid 129.610673 -264.748959)
		(end 129.331212 -264.8204)
		(width 0.088646)
		(layer "In11.Cu")
		(net "M_H_CPU1_SA_DQS_DP<8>")
	)
	(arc
		(start 135.513572 -266.444222)
		(mid 135.386529 -266.308406)
		(end 135.340344 -266.128246)
		(width 0.088646)
		(layer "In11.Cu")
		(net "M_H_CPU1_SA_DQS_DP<8>")
	)
	(arc
		(start 138.406886 -268.1097)
		(mid 138.376511 -268.096041)
		(end 138.347196 -268.080236)
		(width 0.088646)
		(layer "In11.Cu")
		(net "M_H_CPU1_SA_DQS_DP<8>")
	)
	(arc
		(start 138.347196 -268.080236)
		(mid 138.064494 -268.00446)
		(end 137.781792 -268.080236)
		(width 0.088646)
		(layer "In11.Cu")
		(net "M_H_CPU1_SA_DQS_DP<8>")
	)
	(arc
		(start 135.810498 -266.941808)
		(mid 135.736507 -266.662242)
		(end 135.533892 -266.455906)
		(width 0.088646)
		(layer "In11.Cu")
		(net "M_H_CPU1_SA_DQS_DP<8>")
	)
	(arc
		(start 133.648196 -264.824718)
		(mid 133.371637 -264.748975)
		(end 133.09346 -264.818622)
		(width 0.088646)
		(layer "In11.Cu")
		(net "M_H_CPU1_SA_DQS_DP<8>")
	)
	(arc
		(start 134.870698 -265.314176)
		(mid 134.796707 -265.03461)
		(end 134.594092 -264.828274)
		(width 0.088646)
		(layer "In11.Cu")
		(net "M_H_CPU1_SA_DQS_DP<8>")
	)
	(arc
		(start 128.379474 -264.827512)
		(mid 128.19406 -264.875024)
		(end 128.009396 -264.824718)
		(width 0.088646)
		(layer "In11.Cu")
		(net "M_H_CPU1_SA_DQS_DP<8>")
	)
	(arc
		(start 130.814064 -264.816082)
		(mid 130.537589 -264.748762)
		(end 130.263392 -264.824718)
		(width 0.088646)
		(layer "In11.Cu")
		(net "M_H_CPU1_SA_DQS_DP<8>")
	)
	(arc
		(start 134.870952 -265.328908)
		(mid 134.870755 -265.321543)
		(end 134.870698 -265.314176)
		(width 0.088646)
		(layer "In11.Cu")
		(net "M_H_CPU1_SA_DQS_DP<8>")
	)
	(arc
		(start 138.589004 -268.145514)
		(mid 138.496234 -268.136507)
		(end 138.406886 -268.109954)
		(width 0.088646)
		(layer "In11.Cu")
		(net "M_H_CPU1_SA_DQS_DP<8>")
	)
	(arc
		(start 135.04926 -265.633454)
		(mid 134.922006 -265.503488)
		(end 134.870952 -265.328908)
		(width 0.088646)
		(layer "In11.Cu")
		(net "M_H_CPU1_SA_DQS_DP<8>")
	)
	(arc
		(start 137.781792 -268.080236)
		(mid 137.594594 -268.130379)
		(end 137.407396 -268.080236)
		(width 0.088646)
		(layer "In11.Cu")
		(net "M_H_CPU1_SA_DQS_DP<8>")
	)
	(arc
		(start 128.949196 -264.824718)
		(mid 128.670873 -264.748959)
		(end 128.391412 -264.8204)
		(width 0.088646)
		(layer "In11.Cu")
		(net "M_H_CPU1_SA_DQS_DP<8>")
	)
	(arc
		(start 131.753864 -264.816082)
		(mid 131.477389 -264.748762)
		(end 131.203192 -264.824718)
		(width 0.088646)
		(layer "In11.Cu")
		(net "M_H_CPU1_SA_DQS_DP<8>")
	)
	(arc
		(start 133.083046 -264.824718)
		(mid 132.895848 -264.874861)
		(end 132.70865 -264.824718)
		(width 0.088646)
		(layer "In11.Cu")
		(net "M_H_CPU1_SA_DQS_DP<8>")
	)
	(arc
		(start 130.263392 -264.824718)
		(mid 130.076194 -264.874861)
		(end 129.888996 -264.824718)
		(width 0.088646)
		(layer "In11.Cu")
		(net "M_H_CPU1_SA_DQS_DP<8>")
	)
	(arc
		(start 135.997696 -267.266166)
		(mid 135.862763 -267.132812)
		(end 135.810498 -266.950444)
		(width 0.088646)
		(layer "In11.Cu")
		(net "M_H_CPU1_SA_DQS_DP<8>")
	)
	(arc
		(start 131.203192 -264.824718)
		(mid 131.015994 -264.874861)
		(end 130.828796 -264.824718)
		(width 0.088646)
		(layer "In11.Cu")
		(net "M_H_CPU1_SA_DQS_DP<8>")
	)
	(arc
		(start 135.340344 -266.106148)
		(mid 135.259433 -265.83602)
		(end 135.05815 -265.638534)
		(width 0.088646)
		(layer "In11.Cu")
		(net "M_H_CPU1_SA_DQS_DP<8>")
	)
	(arc
		(start 137.407396 -268.080236)
		(mid 137.124694 -268.00446)
		(end 136.841992 -268.080236)
		(width 0.088646)
		(layer "In11.Cu")
		(net "M_H_CPU1_SA_DQS_DP<8>")
	)
	(arc
		(start 136.841992 -268.080236)
		(mid 136.467517 -268.08019)
		(end 136.280144 -267.755878)
		(width 0.088646)
		(layer "In11.Cu")
		(net "M_H_CPU1_SA_DQS_DP<8>")
	)
	(arc
		(start 136.280144 -267.737336)
		(mid 136.199982 -267.465147)
		(end 135.997696 -267.266166)
		(width 0.088646)
		(layer "In11.Cu")
		(net "M_H_CPU1_SA_DQS_DP<8>")
	)
	(arc
		(start 126.497588 -264.829036)
		(mid 126.391265 -264.871531)
		(end 126.277878 -264.887456)
		(width 0.088646)
		(layer "In11.Cu")
		(net "M_H_CPU1_SA_DQS_DP<8>")
	)
	(arc
		(start 125.908816 -264.894314)
		(mid 125.896401 -264.895252)
		(end 125.884178 -264.897616)
		(width 0.088646)
		(layer "In11.Cu")
		(net "M_H_CPU1_SA_DQS_DP<8>")
	)
	(arc
		(start 132.698236 -264.818622)
		(mid 132.419804 -264.748776)
		(end 132.142992 -264.824718)
		(width 0.088646)
		(layer "In11.Cu")
		(net "M_H_CPU1_SA_DQS_DP<8>")
	)
	(arc
		(start 132.142992 -264.824718)
		(mid 131.955794 -264.874861)
		(end 131.768596 -264.824718)
		(width 0.088646)
		(layer "In11.Cu")
		(net "M_H_CPU1_SA_DQS_DP<8>")
	)
	(arc
		(start 134.022592 -264.824718)
		(mid 133.835394 -264.874861)
		(end 133.648196 -264.824718)
		(width 0.088646)
		(layer "In11.Cu")
		(net "M_H_CPU1_SA_DQS_DP<8>")
	)
	(arc
		(start 127.069596 -264.824718)
		(mid 126.791273 -264.748959)
		(end 126.511812 -264.8204)
		(width 0.088646)
		(layer "In11.Cu")
		(net "M_H_CPU1_SA_DQS_DP<8>")
	)
	(segment
		(start 212.95233 -292.084506)
		(end 213.207092 -292.339268)
		(width 0.20066)
		(layer "F.Cu")
		(net "M_H_CPU1_SA_DQS_DP<7>")
	)
	(segment
		(start 209.750406 -292.342824)
		(end 210.02879 -292.342824)
		(width 0.20066)
		(layer "F.Cu")
		(net "M_H_CPU1_SA_DQS_DP<7>")
	)
	(segment
		(start 208.176114 -292.516814)
		(end 208.769712 -292.516814)
		(width 0.20066)
		(layer "F.Cu")
		(net "M_H_CPU1_SA_DQS_DP<7>")
	)
	(segment
		(start 213.860634 -292.339268)
		(end 214.30615 -292.784784)
		(width 0.20066)
		(layer "F.Cu")
		(net "M_H_CPU1_SA_DQS_DP<7>")
	)
	(segment
		(start 209.020664 -292.767766)
		(end 209.325464 -292.767766)
		(width 0.20066)
		(layer "F.Cu")
		(net "M_H_CPU1_SA_DQS_DP<7>")
	)
	(segment
		(start 215.151716 -292.516814)
		(end 215.719914 -292.516814)
		(width 0.20066)
		(layer "F.Cu")
		(net "M_H_CPU1_SA_DQS_DP<7>")
	)
	(segment
		(start 208.769712 -292.516814)
		(end 209.020664 -292.767766)
		(width 0.20066)
		(layer "F.Cu")
		(net "M_H_CPU1_SA_DQS_DP<7>")
	)
	(segment
		(start 214.30615 -292.784784)
		(end 214.883746 -292.784784)
		(width 0.20066)
		(layer "F.Cu")
		(net "M_H_CPU1_SA_DQS_DP<7>")
	)
	(segment
		(start 214.883746 -292.784784)
		(end 215.151716 -292.516814)
		(width 0.20066)
		(layer "F.Cu")
		(net "M_H_CPU1_SA_DQS_DP<7>")
	)
	(segment
		(start 210.603084 -292.08476)
		(end 210.610196 -292.091872)
		(width 0.1016)
		(layer "F.Cu")
		(net "M_H_CPU1_SA_DQS_DP<7>")
	)
	(segment
		(start 212.622892 -292.091872)
		(end 212.630258 -292.084506)
		(width 0.1016)
		(layer "F.Cu")
		(net "M_H_CPU1_SA_DQS_DP<7>")
	)
	(segment
		(start 210.02879 -292.342824)
		(end 210.286854 -292.08476)
		(width 0.20066)
		(layer "F.Cu")
		(net "M_H_CPU1_SA_DQS_DP<7>")
	)
	(segment
		(start 213.207092 -292.339268)
		(end 213.860634 -292.339268)
		(width 0.20066)
		(layer "F.Cu")
		(net "M_H_CPU1_SA_DQS_DP<7>")
	)
	(segment
		(start 207.071214 -292.51656)
		(end 207.071468 -292.516814)
		(width 0.20066)
		(layer "F.Cu")
		(net "M_H_CPU1_SA_DQS_DP<7>")
	)
	(segment
		(start 209.325464 -292.767766)
		(end 209.750406 -292.342824)
		(width 0.20066)
		(layer "F.Cu")
		(net "M_H_CPU1_SA_DQS_DP<7>")
	)
	(segment
		(start 124.907548 -270.167862)
		(end 124.907548 -270.19758)
		(width 0.20066)
		(layer "F.Cu")
		(net "M_H_CPU1_SA_DQS_DP<7>")
	)
	(segment
		(start 124.907294 -269.66164)
		(end 124.907548 -270.167862)
		(width 0.20066)
		(layer "F.Cu")
		(net "M_H_CPU1_SA_DQS_DP<7>")
	)
	(segment
		(start 212.630258 -292.084506)
		(end 212.95233 -292.084506)
		(width 0.20066)
		(layer "F.Cu")
		(net "M_H_CPU1_SA_DQS_DP<7>")
	)
	(segment
		(start 210.610196 -292.091872)
		(end 212.622892 -292.091872)
		(width 0.1016)
		(layer "F.Cu")
		(net "M_H_CPU1_SA_DQS_DP<7>")
	)
	(segment
		(start 210.286854 -292.08476)
		(end 210.598258 -292.08476)
		(width 0.20066)
		(layer "F.Cu")
		(net "M_H_CPU1_SA_DQS_DP<7>")
	)
	(segment
		(start 207.071468 -292.516814)
		(end 208.176114 -292.516814)
		(width 0.20066)
		(layer "F.Cu")
		(net "M_H_CPU1_SA_DQS_DP<7>")
	)
	(segment
		(start 210.598258 -292.08476)
		(end 210.603084 -292.08476)
		(width 0.101854)
		(layer "F.Cu")
		(net "M_H_CPU1_SA_DQS_DP<7>")
	)
	(segment
		(start 163.557966 -295.168574)
		(end 163.08324 -294.693848)
		(width 0.18288)
		(layer "In11.Cu")
		(net "M_H_CPU1_SA_DQS_DP<7>")
	)
	(segment
		(start 164.376608 -295.168574)
		(end 163.557966 -295.168574)
		(width 0.18288)
		(layer "In11.Cu")
		(net "M_H_CPU1_SA_DQS_DP<7>")
	)
	(segment
		(start 160.685734 -294.693848)
		(end 159.910018 -293.918132)
		(width 0.18288)
		(layer "In11.Cu")
		(net "M_H_CPU1_SA_DQS_DP<7>")
	)
	(segment
		(start 125.66015 -269.873222)
		(end 125.65126 -269.878302)
		(width 0.088646)
		(layer "In11.Cu")
		(net "M_H_CPU1_SA_DQS_DP<7>")
	)
	(segment
		(start 128.949196 -269.707868)
		(end 128.934464 -269.699232)
		(width 0.088646)
		(layer "In11.Cu")
		(net "M_H_CPU1_SA_DQS_DP<7>")
	)
	(segment
		(start 172.250608 -298.341288)
		(end 171.646088 -298.341288)
		(width 0.18288)
		(layer "In11.Cu")
		(net "M_H_CPU1_SA_DQS_DP<7>")
	)
	(segment
		(start 130.834892 -271.33931)
		(end 130.828796 -271.335754)
		(width 0.088646)
		(layer "In11.Cu")
		(net "M_H_CPU1_SA_DQS_DP<7>")
	)
	(segment
		(start 125.976634 -269.757906)
		(end 125.786896 -269.805404)
		(width 0.088646)
		(layer "In11.Cu")
		(net "M_H_CPU1_SA_DQS_DP<7>")
	)
	(segment
		(start 203.191618 -292.091364)
		(end 203.05776 -292.091364)
		(width 0.18288)
		(layer "In11.Cu")
		(net "M_H_CPU1_SA_DQS_DP<7>")
	)
	(segment
		(start 125.405896 -270.19758)
		(end 124.907548 -270.19758)
		(width 0.088646)
		(layer "In11.Cu")
		(net "M_H_CPU1_SA_DQS_DP<7>")
	)
	(segment
		(start 130.641344 -271.011396)
		(end 130.641344 -270.995902)
		(width 0.088646)
		(layer "In11.Cu")
		(net "M_H_CPU1_SA_DQS_DP<7>")
	)
	(segment
		(start 203.456032 -292.355778)
		(end 203.191618 -292.091364)
		(width 0.18288)
		(layer "In11.Cu")
		(net "M_H_CPU1_SA_DQS_DP<7>")
	)
	(segment
		(start 197.269354 -294.235886)
		(end 195.635372 -295.869868)
		(width 0.18288)
		(layer "In11.Cu")
		(net "M_H_CPU1_SA_DQS_DP<7>")
	)
	(segment
		(start 173.473364 -298.280328)
		(end 173.318932 -298.280328)
		(width 0.18288)
		(layer "In11.Cu")
		(net "M_H_CPU1_SA_DQS_DP<7>")
	)
	(segment
		(start 129.41935 -270.521938)
		(end 129.41046 -270.516858)
		(width 0.088646)
		(layer "In11.Cu")
		(net "M_H_CPU1_SA_DQS_DP<7>")
	)
	(segment
		(start 200.039478 -293.465504)
		(end 199.023478 -293.465504)
		(width 0.18288)
		(layer "In11.Cu")
		(net "M_H_CPU1_SA_DQS_DP<7>")
	)
	(segment
		(start 188.076586 -296.341038)
		(end 187.615322 -296.341038)
		(width 0.18288)
		(layer "In11.Cu")
		(net "M_H_CPU1_SA_DQS_DP<7>")
	)
	(segment
		(start 165.229032 -296.020998)
		(end 164.376608 -295.168574)
		(width 0.18288)
		(layer "In11.Cu")
		(net "M_H_CPU1_SA_DQS_DP<7>")
	)
	(segment
		(start 181.742588 -296.01287)
		(end 180.551836 -297.203622)
		(width 0.18288)
		(layer "In11.Cu")
		(net "M_H_CPU1_SA_DQS_DP<7>")
	)
	(segment
		(start 172.550074 -298.041822)
		(end 172.250608 -298.341288)
		(width 0.18288)
		(layer "In11.Cu")
		(net "M_H_CPU1_SA_DQS_DP<7>")
	)
	(segment
		(start 201.670412 -292.630606)
		(end 200.874376 -292.630606)
		(width 0.18288)
		(layer "In11.Cu")
		(net "M_H_CPU1_SA_DQS_DP<7>")
	)
	(segment
		(start 167.656002 -296.020998)
		(end 165.229032 -296.020998)
		(width 0.18288)
		(layer "In11.Cu")
		(net "M_H_CPU1_SA_DQS_DP<7>")
	)
	(segment
		(start 206.78521 -292.802564)
		(end 206.40421 -292.802564)
		(width 0.18288)
		(layer "In11.Cu")
		(net "M_H_CPU1_SA_DQS_DP<7>")
	)
	(segment
		(start 203.05776 -292.091364)
		(end 202.879198 -292.091364)
		(width 0.16002)
		(layer "In11.Cu")
		(net "M_H_CPU1_SA_DQS_DP<7>")
	)
	(segment
		(start 192.460626 -297.466258)
		(end 192.18529 -297.190922)
		(width 0.18288)
		(layer "In11.Cu")
		(net "M_H_CPU1_SA_DQS_DP<7>")
	)
	(segment
		(start 135.527796 -272.96364)
		(end 135.513064 -272.955004)
		(width 0.088646)
		(layer "In11.Cu")
		(net "M_H_CPU1_SA_DQS_DP<7>")
	)
	(segment
		(start 153.096468 -287.768284)
		(end 139.666726 -274.338542)
		(width 0.18288)
		(layer "In11.Cu")
		(net "M_H_CPU1_SA_DQS_DP<7>")
	)
	(segment
		(start 139.266168 -274.398232)
		(end 138.86942 -274.398232)
		(width 0.088646)
		(layer "In11.Cu")
		(net "M_H_CPU1_SA_DQS_DP<7>")
	)
	(segment
		(start 194.977004 -295.869868)
		(end 194.067684 -296.779188)
		(width 0.18288)
		(layer "In11.Cu")
		(net "M_H_CPU1_SA_DQS_DP<7>")
	)
	(segment
		(start 180.551836 -297.203622)
		(end 179.84851 -297.203622)
		(width 0.18288)
		(layer "In11.Cu")
		(net "M_H_CPU1_SA_DQS_DP<7>")
	)
	(segment
		(start 133.648196 -272.96364)
		(end 133.633464 -272.955004)
		(width 0.088646)
		(layer "In11.Cu")
		(net "M_H_CPU1_SA_DQS_DP<7>")
	)
	(segment
		(start 131.760722 -272.959068)
		(end 131.75996 -272.95856)
		(width 0.088646)
		(layer "In11.Cu")
		(net "M_H_CPU1_SA_DQS_DP<7>")
	)
	(segment
		(start 131.76885 -272.96364)
		(end 131.767072 -272.962624)
		(width 0.088646)
		(layer "In11.Cu")
		(net "M_H_CPU1_SA_DQS_DP<7>")
	)
	(segment
		(start 177.412142 -297.499278)
		(end 177.103786 -297.190922)
		(width 0.18288)
		(layer "In11.Cu")
		(net "M_H_CPU1_SA_DQS_DP<7>")
	)
	(segment
		(start 187.328556 -296.627804)
		(end 183.63184 -296.627804)
		(width 0.18288)
		(layer "In11.Cu")
		(net "M_H_CPU1_SA_DQS_DP<7>")
	)
	(segment
		(start 126.320296 -269.757906)
		(end 125.976634 -269.757906)
		(width 0.088646)
		(layer "In11.Cu")
		(net "M_H_CPU1_SA_DQS_DP<7>")
	)
	(segment
		(start 173.318932 -298.280328)
		(end 173.080426 -298.041822)
		(width 0.18288)
		(layer "In11.Cu")
		(net "M_H_CPU1_SA_DQS_DP<7>")
	)
	(segment
		(start 187.615322 -296.341038)
		(end 187.328556 -296.627804)
		(width 0.18288)
		(layer "In11.Cu")
		(net "M_H_CPU1_SA_DQS_DP<7>")
	)
	(segment
		(start 177.103786 -297.190922)
		(end 176.62779 -297.190922)
		(width 0.18288)
		(layer "In11.Cu")
		(net "M_H_CPU1_SA_DQS_DP<7>")
	)
	(segment
		(start 202.879198 -292.091364)
		(end 202.752198 -292.091364)
		(width 0.18288)
		(layer "In11.Cu")
		(net "M_H_CPU1_SA_DQS_DP<7>")
	)
	(segment
		(start 183.016906 -296.01287)
		(end 181.742588 -296.01287)
		(width 0.18288)
		(layer "In11.Cu")
		(net "M_H_CPU1_SA_DQS_DP<7>")
	)
	(segment
		(start 200.874376 -292.630606)
		(end 200.039478 -293.465504)
		(width 0.18288)
		(layer "In11.Cu")
		(net "M_H_CPU1_SA_DQS_DP<7>")
	)
	(segment
		(start 157.676342 -292.99281)
		(end 156.717746 -292.99281)
		(width 0.18288)
		(layer "In11.Cu")
		(net "M_H_CPU1_SA_DQS_DP<7>")
	)
	(segment
		(start 198.253096 -294.235886)
		(end 197.269354 -294.235886)
		(width 0.18288)
		(layer "In11.Cu")
		(net "M_H_CPU1_SA_DQS_DP<7>")
	)
	(segment
		(start 159.910018 -293.918132)
		(end 157.676342 -292.99281)
		(width 0.18288)
		(layer "In11.Cu")
		(net "M_H_CPU1_SA_DQS_DP<7>")
	)
	(segment
		(start 203.913232 -292.355778)
		(end 203.456032 -292.355778)
		(width 0.18288)
		(layer "In11.Cu")
		(net "M_H_CPU1_SA_DQS_DP<7>")
	)
	(segment
		(start 170.003978 -296.699178)
		(end 169.293286 -296.699178)
		(width 0.18288)
		(layer "In11.Cu")
		(net "M_H_CPU1_SA_DQS_DP<7>")
	)
	(segment
		(start 199.023478 -293.465504)
		(end 198.253096 -294.235886)
		(width 0.18288)
		(layer "In11.Cu")
		(net "M_H_CPU1_SA_DQS_DP<7>")
	)
	(segment
		(start 193.482976 -296.779188)
		(end 192.795906 -297.466258)
		(width 0.18288)
		(layer "In11.Cu")
		(net "M_H_CPU1_SA_DQS_DP<7>")
	)
	(segment
		(start 188.384942 -296.649394)
		(end 188.076586 -296.341038)
		(width 0.18288)
		(layer "In11.Cu")
		(net "M_H_CPU1_SA_DQS_DP<7>")
	)
	(segment
		(start 129.808478 -270.513302)
		(end 129.793746 -270.521938)
		(width 0.088646)
		(layer "In11.Cu")
		(net "M_H_CPU1_SA_DQS_DP<7>")
	)
	(segment
		(start 125.786896 -269.805404)
		(end 125.66015 -269.873222)
		(width 0.088646)
		(layer "In11.Cu")
		(net "M_H_CPU1_SA_DQS_DP<7>")
	)
	(segment
		(start 134.587996 -272.96364)
		(end 134.573264 -272.955004)
		(width 0.088646)
		(layer "In11.Cu")
		(net "M_H_CPU1_SA_DQS_DP<7>")
	)
	(segment
		(start 129.231898 -270.19758)
		(end 129.231898 -270.183356)
		(width 0.088646)
		(layer "In11.Cu")
		(net "M_H_CPU1_SA_DQS_DP<7>")
	)
	(segment
		(start 139.666726 -274.338542)
		(end 139.325858 -274.338542)
		(width 0.18288)
		(layer "In11.Cu")
		(net "M_H_CPU1_SA_DQS_DP<7>")
	)
	(segment
		(start 204.521308 -292.963854)
		(end 203.913232 -292.355778)
		(width 0.18288)
		(layer "In11.Cu")
		(net "M_H_CPU1_SA_DQS_DP<7>")
	)
	(segment
		(start 202.752198 -292.091364)
		(end 202.52309 -292.320472)
		(width 0.18288)
		(layer "In11.Cu")
		(net "M_H_CPU1_SA_DQS_DP<7>")
	)
	(segment
		(start 171.646088 -298.341288)
		(end 170.003978 -296.699178)
		(width 0.18288)
		(layer "In11.Cu")
		(net "M_H_CPU1_SA_DQS_DP<7>")
	)
	(segment
		(start 176.62779 -297.190922)
		(end 176.359058 -297.459654)
		(width 0.18288)
		(layer "In11.Cu")
		(net "M_H_CPU1_SA_DQS_DP<7>")
	)
	(segment
		(start 176.359058 -297.459654)
		(end 175.454818 -297.459654)
		(width 0.18288)
		(layer "In11.Cu")
		(net "M_H_CPU1_SA_DQS_DP<7>")
	)
	(segment
		(start 128.009396 -269.707868)
		(end 127.994664 -269.699232)
		(width 0.088646)
		(layer "In11.Cu")
		(net "M_H_CPU1_SA_DQS_DP<7>")
	)
	(segment
		(start 201.980546 -292.320472)
		(end 201.670412 -292.630606)
		(width 0.18288)
		(layer "In11.Cu")
		(net "M_H_CPU1_SA_DQS_DP<7>")
	)
	(segment
		(start 191.71539 -297.190922)
		(end 191.41948 -297.48607)
		(width 0.18288)
		(layer "In11.Cu")
		(net "M_H_CPU1_SA_DQS_DP<7>")
	)
	(segment
		(start 132.708396 -272.96364)
		(end 132.697982 -272.957544)
		(width 0.088646)
		(layer "In11.Cu")
		(net "M_H_CPU1_SA_DQS_DP<7>")
	)
	(segment
		(start 137.471404 -273.00682)
		(end 137.471404 -273.006566)
		(width 0.088646)
		(layer "In11.Cu")
		(net "M_H_CPU1_SA_DQS_DP<7>")
	)
	(segment
		(start 175.454818 -297.459654)
		(end 173.473364 -298.280328)
		(width 0.18288)
		(layer "In11.Cu")
		(net "M_H_CPU1_SA_DQS_DP<7>")
	)
	(segment
		(start 190.192914 -297.48607)
		(end 189.356238 -296.649394)
		(width 0.18288)
		(layer "In11.Cu")
		(net "M_H_CPU1_SA_DQS_DP<7>")
	)
	(segment
		(start 202.52309 -292.320472)
		(end 201.980546 -292.320472)
		(width 0.18288)
		(layer "In11.Cu")
		(net "M_H_CPU1_SA_DQS_DP<7>")
	)
	(segment
		(start 179.84851 -297.203622)
		(end 179.516024 -296.871136)
		(width 0.18288)
		(layer "In11.Cu")
		(net "M_H_CPU1_SA_DQS_DP<7>")
	)
	(segment
		(start 125.480064 -270.123412)
		(end 125.405896 -270.19758)
		(width 0.088646)
		(layer "In11.Cu")
		(net "M_H_CPU1_SA_DQS_DP<7>")
	)
	(segment
		(start 131.765548 -272.961608)
		(end 131.760722 -272.959068)
		(width 0.088646)
		(layer "In11.Cu")
		(net "M_H_CPU1_SA_DQS_DP<7>")
	)
	(segment
		(start 206.40421 -292.802564)
		(end 206.24292 -292.963854)
		(width 0.18288)
		(layer "In11.Cu")
		(net "M_H_CPU1_SA_DQS_DP<7>")
	)
	(segment
		(start 131.581398 -272.639282)
		(end 131.581398 -272.625058)
		(width 0.088646)
		(layer "In11.Cu")
		(net "M_H_CPU1_SA_DQS_DP<7>")
	)
	(segment
		(start 153.096468 -289.371532)
		(end 153.096468 -287.768284)
		(width 0.18288)
		(layer "In11.Cu")
		(net "M_H_CPU1_SA_DQS_DP<7>")
	)
	(segment
		(start 127.069596 -269.707868)
		(end 127.069596 -269.708122)
		(width 0.088646)
		(layer "In11.Cu")
		(net "M_H_CPU1_SA_DQS_DP<7>")
	)
	(segment
		(start 139.325858 -274.338542)
		(end 139.266168 -274.398232)
		(width 0.088646)
		(layer "In11.Cu")
		(net "M_H_CPU1_SA_DQS_DP<7>")
	)
	(segment
		(start 206.24292 -292.963854)
		(end 204.521308 -292.963854)
		(width 0.18288)
		(layer "In11.Cu")
		(net "M_H_CPU1_SA_DQS_DP<7>")
	)
	(segment
		(start 163.08324 -294.693848)
		(end 160.685734 -294.693848)
		(width 0.18288)
		(layer "In11.Cu")
		(net "M_H_CPU1_SA_DQS_DP<7>")
	)
	(segment
		(start 192.795906 -297.466258)
		(end 192.460626 -297.466258)
		(width 0.18288)
		(layer "In11.Cu")
		(net "M_H_CPU1_SA_DQS_DP<7>")
	)
	(segment
		(start 179.516024 -296.871136)
		(end 178.735482 -296.871136)
		(width 0.18288)
		(layer "In11.Cu")
		(net "M_H_CPU1_SA_DQS_DP<7>")
	)
	(segment
		(start 173.080426 -298.041822)
		(end 172.550074 -298.041822)
		(width 0.18288)
		(layer "In11.Cu")
		(net "M_H_CPU1_SA_DQS_DP<7>")
	)
	(segment
		(start 131.29895 -272.14957)
		(end 131.29006 -272.14449)
		(width 0.088646)
		(layer "In11.Cu")
		(net "M_H_CPU1_SA_DQS_DP<7>")
	)
	(segment
		(start 192.18529 -297.190922)
		(end 191.71539 -297.190922)
		(width 0.18288)
		(layer "In11.Cu")
		(net "M_H_CPU1_SA_DQS_DP<7>")
	)
	(segment
		(start 195.635372 -295.869868)
		(end 194.977004 -295.869868)
		(width 0.18288)
		(layer "In11.Cu")
		(net "M_H_CPU1_SA_DQS_DP<7>")
	)
	(segment
		(start 191.41948 -297.48607)
		(end 190.192914 -297.48607)
		(width 0.18288)
		(layer "In11.Cu")
		(net "M_H_CPU1_SA_DQS_DP<7>")
	)
	(segment
		(start 207.071214 -292.51656)
		(end 206.78521 -292.802564)
		(width 0.18288)
		(layer "In11.Cu")
		(net "M_H_CPU1_SA_DQS_DP<7>")
	)
	(segment
		(start 131.767072 -272.962624)
		(end 131.765548 -272.961608)
		(width 0.088646)
		(layer "In11.Cu")
		(net "M_H_CPU1_SA_DQS_DP<7>")
	)
	(segment
		(start 194.067684 -296.779188)
		(end 193.482976 -296.779188)
		(width 0.18288)
		(layer "In11.Cu")
		(net "M_H_CPU1_SA_DQS_DP<7>")
	)
	(segment
		(start 178.735482 -296.871136)
		(end 178.10734 -297.499278)
		(width 0.18288)
		(layer "In11.Cu")
		(net "M_H_CPU1_SA_DQS_DP<7>")
	)
	(segment
		(start 183.63184 -296.627804)
		(end 183.016906 -296.01287)
		(width 0.18288)
		(layer "In11.Cu")
		(net "M_H_CPU1_SA_DQS_DP<7>")
	)
	(segment
		(start 189.356238 -296.649394)
		(end 188.384942 -296.649394)
		(width 0.18288)
		(layer "In11.Cu")
		(net "M_H_CPU1_SA_DQS_DP<7>")
	)
	(segment
		(start 178.10734 -297.499278)
		(end 177.412142 -297.499278)
		(width 0.18288)
		(layer "In11.Cu")
		(net "M_H_CPU1_SA_DQS_DP<7>")
	)
	(segment
		(start 130.828796 -271.335754)
		(end 130.819906 -271.330674)
		(width 0.088646)
		(layer "In11.Cu")
		(net "M_H_CPU1_SA_DQS_DP<7>")
	)
	(segment
		(start 138.86942 -274.398232)
		(end 137.524236 -273.053048)
		(width 0.088646)
		(layer "In11.Cu")
		(net "M_H_CPU1_SA_DQS_DP<7>")
	)
	(segment
		(start 169.293286 -296.699178)
		(end 167.656002 -296.020998)
		(width 0.18288)
		(layer "In11.Cu")
		(net "M_H_CPU1_SA_DQS_DP<7>")
	)
	(segment
		(start 156.717746 -292.99281)
		(end 153.096468 -289.371532)
		(width 0.18288)
		(layer "In11.Cu")
		(net "M_H_CPU1_SA_DQS_DP<7>")
	)
	(arc
		(start 135.902192 -272.96364)
		(mid 135.714994 -273.013783)
		(end 135.527796 -272.96364)
		(width 0.088646)
		(layer "In11.Cu")
		(net "M_H_CPU1_SA_DQS_DP<7>")
	)
	(arc
		(start 134.962392 -272.96364)
		(mid 134.775194 -273.013783)
		(end 134.587996 -272.96364)
		(width 0.088646)
		(layer "In11.Cu")
		(net "M_H_CPU1_SA_DQS_DP<7>")
	)
	(arc
		(start 131.581398 -272.625058)
		(mid 131.502257 -272.350435)
		(end 131.29895 -272.14957)
		(width 0.088646)
		(layer "In11.Cu")
		(net "M_H_CPU1_SA_DQS_DP<7>")
	)
	(arc
		(start 133.082792 -272.96364)
		(mid 132.895594 -273.013783)
		(end 132.708396 -272.96364)
		(width 0.088646)
		(layer "In11.Cu")
		(net "M_H_CPU1_SA_DQS_DP<7>")
	)
	(arc
		(start 129.793746 -270.521938)
		(mid 129.606548 -270.572081)
		(end 129.41935 -270.521938)
		(width 0.088646)
		(layer "In11.Cu")
		(net "M_H_CPU1_SA_DQS_DP<7>")
	)
	(arc
		(start 125.65126 -269.878302)
		(mid 125.540162 -269.983045)
		(end 125.480064 -270.123412)
		(width 0.088646)
		(layer "In11.Cu")
		(net "M_H_CPU1_SA_DQS_DP<7>")
	)
	(arc
		(start 129.41046 -270.516858)
		(mid 129.279546 -270.380498)
		(end 129.231898 -270.19758)
		(width 0.088646)
		(layer "In11.Cu")
		(net "M_H_CPU1_SA_DQS_DP<7>")
	)
	(arc
		(start 137.524236 -273.053048)
		(mid 137.498538 -273.029114)
		(end 137.471404 -273.00682)
		(width 0.088646)
		(layer "In11.Cu")
		(net "M_H_CPU1_SA_DQS_DP<7>")
	)
	(arc
		(start 126.5047 -269.708376)
		(mid 126.41577 -269.745333)
		(end 126.320296 -269.757906)
		(width 0.088646)
		(layer "In11.Cu")
		(net "M_H_CPU1_SA_DQS_DP<7>")
	)
	(arc
		(start 137.471404 -273.006566)
		(mid 137.440132 -272.984011)
		(end 137.407396 -272.96364)
		(width 0.088646)
		(layer "In11.Cu")
		(net "M_H_CPU1_SA_DQS_DP<7>")
	)
	(arc
		(start 135.513064 -272.955004)
		(mid 135.236589 -272.887684)
		(end 134.962392 -272.96364)
		(width 0.088646)
		(layer "In11.Cu")
		(net "M_H_CPU1_SA_DQS_DP<7>")
	)
	(arc
		(start 137.407396 -272.96364)
		(mid 137.124694 -272.887864)
		(end 136.841992 -272.96364)
		(width 0.088646)
		(layer "In11.Cu")
		(net "M_H_CPU1_SA_DQS_DP<7>")
	)
	(arc
		(start 130.35915 -270.521938)
		(mid 130.084951 -270.446103)
		(end 129.808478 -270.513302)
		(width 0.088646)
		(layer "In11.Cu")
		(net "M_H_CPU1_SA_DQS_DP<7>")
	)
	(arc
		(start 131.111498 -271.825212)
		(mid 131.037507 -271.545646)
		(end 130.834892 -271.33931)
		(width 0.088646)
		(layer "In11.Cu")
		(net "M_H_CPU1_SA_DQS_DP<7>")
	)
	(arc
		(start 134.022592 -272.96364)
		(mid 133.835394 -273.013783)
		(end 133.648196 -272.96364)
		(width 0.088646)
		(layer "In11.Cu")
		(net "M_H_CPU1_SA_DQS_DP<7>")
	)
	(arc
		(start 127.994664 -269.699232)
		(mid 127.718223 -269.632066)
		(end 127.443992 -269.707868)
		(width 0.088646)
		(layer "In11.Cu")
		(net "M_H_CPU1_SA_DQS_DP<7>")
	)
	(arc
		(start 128.934464 -269.699232)
		(mid 128.658023 -269.632066)
		(end 128.383792 -269.707868)
		(width 0.088646)
		(layer "In11.Cu")
		(net "M_H_CPU1_SA_DQS_DP<7>")
	)
	(arc
		(start 130.819906 -271.330674)
		(mid 130.688992 -271.194314)
		(end 130.641344 -271.011396)
		(width 0.088646)
		(layer "In11.Cu")
		(net "M_H_CPU1_SA_DQS_DP<7>")
	)
	(arc
		(start 136.467596 -272.96364)
		(mid 136.184894 -272.887864)
		(end 135.902192 -272.96364)
		(width 0.088646)
		(layer "In11.Cu")
		(net "M_H_CPU1_SA_DQS_DP<7>")
	)
	(arc
		(start 131.75996 -272.95856)
		(mid 131.629046 -272.8222)
		(end 131.581398 -272.639282)
		(width 0.088646)
		(layer "In11.Cu")
		(net "M_H_CPU1_SA_DQS_DP<7>")
	)
	(arc
		(start 136.841992 -272.96364)
		(mid 136.654794 -273.013783)
		(end 136.467596 -272.96364)
		(width 0.088646)
		(layer "In11.Cu")
		(net "M_H_CPU1_SA_DQS_DP<7>")
	)
	(arc
		(start 131.111752 -271.839944)
		(mid 131.111555 -271.832579)
		(end 131.111498 -271.825212)
		(width 0.088646)
		(layer "In11.Cu")
		(net "M_H_CPU1_SA_DQS_DP<7>")
	)
	(arc
		(start 127.443992 -269.707868)
		(mid 127.256794 -269.758011)
		(end 127.069596 -269.707868)
		(width 0.088646)
		(layer "In11.Cu")
		(net "M_H_CPU1_SA_DQS_DP<7>")
	)
	(arc
		(start 133.633464 -272.955004)
		(mid 133.356989 -272.887684)
		(end 133.082792 -272.96364)
		(width 0.088646)
		(layer "In11.Cu")
		(net "M_H_CPU1_SA_DQS_DP<7>")
	)
	(arc
		(start 132.143246 -272.96364)
		(mid 131.956048 -273.013783)
		(end 131.76885 -272.96364)
		(width 0.088646)
		(layer "In11.Cu")
		(net "M_H_CPU1_SA_DQS_DP<7>")
	)
	(arc
		(start 131.29006 -272.14449)
		(mid 131.162806 -272.014524)
		(end 131.111752 -271.839944)
		(width 0.088646)
		(layer "In11.Cu")
		(net "M_H_CPU1_SA_DQS_DP<7>")
	)
	(arc
		(start 127.069596 -269.708122)
		(mid 126.787119 -269.6326)
		(end 126.5047 -269.708376)
		(width 0.088646)
		(layer "In11.Cu")
		(net "M_H_CPU1_SA_DQS_DP<7>")
	)
	(arc
		(start 128.383792 -269.707868)
		(mid 128.196594 -269.758011)
		(end 128.009396 -269.707868)
		(width 0.088646)
		(layer "In11.Cu")
		(net "M_H_CPU1_SA_DQS_DP<7>")
	)
	(arc
		(start 134.573264 -272.955004)
		(mid 134.296789 -272.887684)
		(end 134.022592 -272.96364)
		(width 0.088646)
		(layer "In11.Cu")
		(net "M_H_CPU1_SA_DQS_DP<7>")
	)
	(arc
		(start 129.231898 -270.183356)
		(mid 129.152679 -269.908671)
		(end 128.949196 -269.707868)
		(width 0.088646)
		(layer "In11.Cu")
		(net "M_H_CPU1_SA_DQS_DP<7>")
	)
	(arc
		(start 130.641344 -270.995902)
		(mid 130.561974 -270.722168)
		(end 130.35915 -270.521938)
		(width 0.088646)
		(layer "In11.Cu")
		(net "M_H_CPU1_SA_DQS_DP<7>")
	)
	(arc
		(start 132.697982 -272.957544)
		(mid 132.419804 -272.887821)
		(end 132.143246 -272.96364)
		(width 0.088646)
		(layer "In11.Cu")
		(net "M_H_CPU1_SA_DQS_DP<7>")
	)
	(segment
		(start 207.071214 -301.866554)
		(end 207.071468 -301.866808)
		(width 0.20066)
		(layer "F.Cu")
		(net "M_H_CPU1_SA_DQS_DP<6>")
	)
	(segment
		(start 210.610196 -301.441866)
		(end 212.622892 -301.441866)
		(width 0.1016)
		(layer "F.Cu")
		(net "M_H_CPU1_SA_DQS_DP<6>")
	)
	(segment
		(start 215.151716 -301.866808)
		(end 215.719914 -301.866808)
		(width 0.20066)
		(layer "F.Cu")
		(net "M_H_CPU1_SA_DQS_DP<6>")
	)
	(segment
		(start 208.176114 -301.866808)
		(end 208.769712 -301.866808)
		(width 0.20066)
		(layer "F.Cu")
		(net "M_H_CPU1_SA_DQS_DP<6>")
	)
	(segment
		(start 209.020664 -302.11776)
		(end 209.325464 -302.11776)
		(width 0.20066)
		(layer "F.Cu")
		(net "M_H_CPU1_SA_DQS_DP<6>")
	)
	(segment
		(start 124.907294 -274.54479)
		(end 124.907548 -274.545044)
		(width 0.20066)
		(layer "F.Cu")
		(net "M_H_CPU1_SA_DQS_DP<6>")
	)
	(segment
		(start 212.630258 -301.4345)
		(end 212.95233 -301.4345)
		(width 0.20066)
		(layer "F.Cu")
		(net "M_H_CPU1_SA_DQS_DP<6>")
	)
	(segment
		(start 212.622892 -301.441866)
		(end 212.630258 -301.4345)
		(width 0.1016)
		(layer "F.Cu")
		(net "M_H_CPU1_SA_DQS_DP<6>")
	)
	(segment
		(start 209.750406 -301.692818)
		(end 210.02879 -301.692818)
		(width 0.20066)
		(layer "F.Cu")
		(net "M_H_CPU1_SA_DQS_DP<6>")
	)
	(segment
		(start 210.02879 -301.692818)
		(end 210.286854 -301.434754)
		(width 0.20066)
		(layer "F.Cu")
		(net "M_H_CPU1_SA_DQS_DP<6>")
	)
	(segment
		(start 210.603084 -301.434754)
		(end 210.610196 -301.441866)
		(width 0.1016)
		(layer "F.Cu")
		(net "M_H_CPU1_SA_DQS_DP<6>")
	)
	(segment
		(start 213.860634 -301.689262)
		(end 214.30615 -302.134778)
		(width 0.20066)
		(layer "F.Cu")
		(net "M_H_CPU1_SA_DQS_DP<6>")
	)
	(segment
		(start 210.286854 -301.434754)
		(end 210.598258 -301.434754)
		(width 0.20066)
		(layer "F.Cu")
		(net "M_H_CPU1_SA_DQS_DP<6>")
	)
	(segment
		(start 214.30615 -302.134778)
		(end 214.883746 -302.134778)
		(width 0.20066)
		(layer "F.Cu")
		(net "M_H_CPU1_SA_DQS_DP<6>")
	)
	(segment
		(start 214.883746 -302.134778)
		(end 215.151716 -301.866808)
		(width 0.20066)
		(layer "F.Cu")
		(net "M_H_CPU1_SA_DQS_DP<6>")
	)
	(segment
		(start 124.907548 -274.545044)
		(end 124.907548 -275.08073)
		(width 0.20066)
		(layer "F.Cu")
		(net "M_H_CPU1_SA_DQS_DP<6>")
	)
	(segment
		(start 209.325464 -302.11776)
		(end 209.750406 -301.692818)
		(width 0.20066)
		(layer "F.Cu")
		(net "M_H_CPU1_SA_DQS_DP<6>")
	)
	(segment
		(start 208.769712 -301.866808)
		(end 209.020664 -302.11776)
		(width 0.20066)
		(layer "F.Cu")
		(net "M_H_CPU1_SA_DQS_DP<6>")
	)
	(segment
		(start 210.598258 -301.434754)
		(end 210.603084 -301.434754)
		(width 0.101854)
		(layer "F.Cu")
		(net "M_H_CPU1_SA_DQS_DP<6>")
	)
	(segment
		(start 213.207092 -301.689262)
		(end 213.860634 -301.689262)
		(width 0.20066)
		(layer "F.Cu")
		(net "M_H_CPU1_SA_DQS_DP<6>")
	)
	(segment
		(start 212.95233 -301.4345)
		(end 213.207092 -301.689262)
		(width 0.20066)
		(layer "F.Cu")
		(net "M_H_CPU1_SA_DQS_DP<6>")
	)
	(segment
		(start 207.071468 -301.866808)
		(end 208.176114 -301.866808)
		(width 0.20066)
		(layer "F.Cu")
		(net "M_H_CPU1_SA_DQS_DP<6>")
	)
	(segment
		(start 199.978264 -303.889918)
		(end 199.472296 -304.395886)
		(width 0.18288)
		(layer "In11.Cu")
		(net "M_H_CPU1_SA_DQS_DP<6>")
	)
	(segment
		(start 127.07239 -276.220682)
		(end 127.069596 -276.219158)
		(width 0.088646)
		(layer "In11.Cu")
		(net "M_H_CPU1_SA_DQS_DP<6>")
	)
	(segment
		(start 139.112244 -281.840178)
		(end 138.46429 -281.192224)
		(width 0.088646)
		(layer "In11.Cu")
		(net "M_H_CPU1_SA_DQS_DP<6>")
	)
	(segment
		(start 203.852018 -301.716694)
		(end 203.475082 -301.716694)
		(width 0.18288)
		(layer "In11.Cu")
		(net "M_H_CPU1_SA_DQS_DP<6>")
	)
	(segment
		(start 172.527722 -309.091076)
		(end 172.228764 -309.390034)
		(width 0.18288)
		(layer "In11.Cu")
		(net "M_H_CPU1_SA_DQS_DP<6>")
	)
	(segment
		(start 173.276514 -309.366412)
		(end 173.001178 -309.091076)
		(width 0.18288)
		(layer "In11.Cu")
		(net "M_H_CPU1_SA_DQS_DP<6>")
	)
	(segment
		(start 176.321466 -308.547262)
		(end 174.244508 -308.547262)
		(width 0.18288)
		(layer "In11.Cu")
		(net "M_H_CPU1_SA_DQS_DP<6>")
	)
	(segment
		(start 206.221584 -302.303434)
		(end 204.438758 -302.303434)
		(width 0.18288)
		(layer "In11.Cu")
		(net "M_H_CPU1_SA_DQS_DP<6>")
	)
	(segment
		(start 203.475082 -301.716694)
		(end 203.199746 -301.441358)
		(width 0.18288)
		(layer "In11.Cu")
		(net "M_H_CPU1_SA_DQS_DP<6>")
	)
	(segment
		(start 178.165252 -308.541928)
		(end 177.389536 -308.541928)
		(width 0.18288)
		(layer "In11.Cu")
		(net "M_H_CPU1_SA_DQS_DP<6>")
	)
	(segment
		(start 125.42012 -275.08073)
		(end 124.907548 -275.08073)
		(width 0.088646)
		(layer "In11.Cu")
		(net "M_H_CPU1_SA_DQS_DP<6>")
	)
	(segment
		(start 127.069596 -276.219158)
		(end 127.068072 -276.218396)
		(width 0.088646)
		(layer "In11.Cu")
		(net "M_H_CPU1_SA_DQS_DP<6>")
	)
	(segment
		(start 127.075692 -276.222714)
		(end 127.07239 -276.220682)
		(width 0.088646)
		(layer "In11.Cu")
		(net "M_H_CPU1_SA_DQS_DP<6>")
	)
	(segment
		(start 194.530726 -307.474112)
		(end 193.75247 -307.474112)
		(width 0.18288)
		(layer "In11.Cu")
		(net "M_H_CPU1_SA_DQS_DP<6>")
	)
	(segment
		(start 202.512676 -301.711106)
		(end 201.302112 -301.711106)
		(width 0.18288)
		(layer "In11.Cu")
		(net "M_H_CPU1_SA_DQS_DP<6>")
	)
	(segment
		(start 173.001178 -309.091076)
		(end 172.527722 -309.091076)
		(width 0.18288)
		(layer "In11.Cu")
		(net "M_H_CPU1_SA_DQS_DP<6>")
	)
	(segment
		(start 136.467596 -279.474676)
		(end 136.458706 -279.469596)
		(width 0.088646)
		(layer "In11.Cu")
		(net "M_H_CPU1_SA_DQS_DP<6>")
	)
	(segment
		(start 140.3096 -283.87167)
		(end 140.250418 -283.812488)
		(width 0.088646)
		(layer "In11.Cu")
		(net "M_H_CPU1_SA_DQS_DP<6>")
	)
	(segment
		(start 188.07049 -307.391054)
		(end 187.67679 -307.391054)
		(width 0.18288)
		(layer "In11.Cu")
		(net "M_H_CPU1_SA_DQS_DP<6>")
	)
	(segment
		(start 191.412876 -308.54269)
		(end 189.53988 -308.54269)
		(width 0.18288)
		(layer "In11.Cu")
		(net "M_H_CPU1_SA_DQS_DP<6>")
	)
	(segment
		(start 126.599696 -275.405088)
		(end 126.453646 -275.323046)
		(width 0.088646)
		(layer "In11.Cu")
		(net "M_H_CPU1_SA_DQS_DP<6>")
	)
	(segment
		(start 193.75247 -307.474112)
		(end 192.706244 -308.520338)
		(width 0.18288)
		(layer "In11.Cu")
		(net "M_H_CPU1_SA_DQS_DP<6>")
	)
	(segment
		(start 195.246752 -306.758086)
		(end 194.530726 -307.474112)
		(width 0.18288)
		(layer "In11.Cu")
		(net "M_H_CPU1_SA_DQS_DP<6>")
	)
	(segment
		(start 191.71539 -308.240938)
		(end 191.412876 -308.54269)
		(width 0.18288)
		(layer "In11.Cu")
		(net "M_H_CPU1_SA_DQS_DP<6>")
	)
	(segment
		(start 206.806546 -302.131222)
		(end 206.393796 -302.131222)
		(width 0.18288)
		(layer "In11.Cu")
		(net "M_H_CPU1_SA_DQS_DP<6>")
	)
	(segment
		(start 136.280144 -279.150318)
		(end 136.280144 -279.140412)
		(width 0.088646)
		(layer "In11.Cu")
		(net "M_H_CPU1_SA_DQS_DP<6>")
	)
	(segment
		(start 192.460626 -308.520338)
		(end 192.181226 -308.240938)
		(width 0.18288)
		(layer "In11.Cu")
		(net "M_H_CPU1_SA_DQS_DP<6>")
	)
	(segment
		(start 201.302112 -301.711106)
		(end 199.978264 -303.034954)
		(width 0.18288)
		(layer "In11.Cu")
		(net "M_H_CPU1_SA_DQS_DP<6>")
	)
	(segment
		(start 126.882144 -275.8948)
		(end 126.882144 -275.876258)
		(width 0.088646)
		(layer "In11.Cu")
		(net "M_H_CPU1_SA_DQS_DP<6>")
	)
	(segment
		(start 126.285498 -275.194014)
		(end 126.221998 -275.08073)
		(width 0.088646)
		(layer "In11.Cu")
		(net "M_H_CPU1_SA_DQS_DP<6>")
	)
	(segment
		(start 178.79441 -307.91277)
		(end 178.165252 -308.541928)
		(width 0.18288)
		(layer "In11.Cu")
		(net "M_H_CPU1_SA_DQS_DP<6>")
	)
	(segment
		(start 139.112244 -282.465272)
		(end 139.112244 -281.840178)
		(width 0.088646)
		(layer "In11.Cu")
		(net "M_H_CPU1_SA_DQS_DP<6>")
	)
	(segment
		(start 204.438758 -302.303434)
		(end 203.852018 -301.716694)
		(width 0.18288)
		(layer "In11.Cu")
		(net "M_H_CPU1_SA_DQS_DP<6>")
	)
	(segment
		(start 176.62779 -308.240938)
		(end 176.321466 -308.547262)
		(width 0.18288)
		(layer "In11.Cu")
		(net "M_H_CPU1_SA_DQS_DP<6>")
	)
	(segment
		(start 164.189664 -307.40858)
		(end 160.59912 -307.40858)
		(width 0.18288)
		(layer "In11.Cu")
		(net "M_H_CPU1_SA_DQS_DP<6>")
	)
	(segment
		(start 170.076622 -307.813456)
		(end 169.447718 -307.813456)
		(width 0.18288)
		(layer "In11.Cu")
		(net "M_H_CPU1_SA_DQS_DP<6>")
	)
	(segment
		(start 126.297182 -275.205698)
		(end 126.285498 -275.194014)
		(width 0.088646)
		(layer "In11.Cu")
		(net "M_H_CPU1_SA_DQS_DP<6>")
	)
	(segment
		(start 203.045568 -301.441358)
		(end 202.912218 -301.441358)
		(width 0.16002)
		(layer "In11.Cu")
		(net "M_H_CPU1_SA_DQS_DP<6>")
	)
	(segment
		(start 177.088546 -308.240938)
		(end 176.62779 -308.240938)
		(width 0.18288)
		(layer "In11.Cu")
		(net "M_H_CPU1_SA_DQS_DP<6>")
	)
	(segment
		(start 206.393796 -302.131222)
		(end 206.221584 -302.303434)
		(width 0.18288)
		(layer "In11.Cu")
		(net "M_H_CPU1_SA_DQS_DP<6>")
	)
	(segment
		(start 183.039512 -308.518306)
		(end 180.397404 -308.518306)
		(width 0.18288)
		(layer "In11.Cu")
		(net "M_H_CPU1_SA_DQS_DP<6>")
	)
	(segment
		(start 171.653962 -309.390034)
		(end 170.076622 -307.813456)
		(width 0.18288)
		(layer "In11.Cu")
		(net "M_H_CPU1_SA_DQS_DP<6>")
	)
	(segment
		(start 183.863234 -307.694584)
		(end 183.039512 -308.518306)
		(width 0.18288)
		(layer "In11.Cu")
		(net "M_H_CPU1_SA_DQS_DP<6>")
	)
	(segment
		(start 160.59912 -307.40858)
		(end 159.156908 -305.966368)
		(width 0.18288)
		(layer "In11.Cu")
		(net "M_H_CPU1_SA_DQS_DP<6>")
	)
	(segment
		(start 140.250418 -283.603446)
		(end 139.112244 -282.465272)
		(width 0.088646)
		(layer "In11.Cu")
		(net "M_H_CPU1_SA_DQS_DP<6>")
	)
	(segment
		(start 133.56336 -278.654764)
		(end 133.552946 -278.66086)
		(width 0.088646)
		(layer "In11.Cu")
		(net "M_H_CPU1_SA_DQS_DP<6>")
	)
	(segment
		(start 127.068072 -276.218396)
		(end 127.060706 -276.214078)
		(width 0.088646)
		(layer "In11.Cu")
		(net "M_H_CPU1_SA_DQS_DP<6>")
	)
	(segment
		(start 188.362082 -307.682646)
		(end 188.07049 -307.391054)
		(width 0.18288)
		(layer "In11.Cu")
		(net "M_H_CPU1_SA_DQS_DP<6>")
	)
	(segment
		(start 146.703542 -292.070028)
		(end 146.703542 -290.54679)
		(width 0.18288)
		(layer "In11.Cu")
		(net "M_H_CPU1_SA_DQS_DP<6>")
	)
	(segment
		(start 189.53988 -308.54269)
		(end 188.679836 -307.682646)
		(width 0.18288)
		(layer "In11.Cu")
		(net "M_H_CPU1_SA_DQS_DP<6>")
	)
	(segment
		(start 202.912218 -301.441358)
		(end 202.782424 -301.441358)
		(width 0.18288)
		(layer "In11.Cu")
		(net "M_H_CPU1_SA_DQS_DP<6>")
	)
	(segment
		(start 140.3096 -284.152848)
		(end 140.3096 -283.87167)
		(width 0.18288)
		(layer "In11.Cu")
		(net "M_H_CPU1_SA_DQS_DP<6>")
	)
	(segment
		(start 157.028642 -305.949604)
		(end 154.872944 -303.793906)
		(width 0.18288)
		(layer "In11.Cu")
		(net "M_H_CPU1_SA_DQS_DP<6>")
	)
	(segment
		(start 192.706244 -308.520338)
		(end 192.460626 -308.520338)
		(width 0.18288)
		(layer "In11.Cu")
		(net "M_H_CPU1_SA_DQS_DP<6>")
	)
	(segment
		(start 154.872944 -303.793906)
		(end 154.872944 -300.23943)
		(width 0.18288)
		(layer "In11.Cu")
		(net "M_H_CPU1_SA_DQS_DP<6>")
	)
	(segment
		(start 180.397404 -308.518306)
		(end 179.791868 -307.91277)
		(width 0.18288)
		(layer "In11.Cu")
		(net "M_H_CPU1_SA_DQS_DP<6>")
	)
	(segment
		(start 146.703542 -290.54679)
		(end 140.3096 -284.152848)
		(width 0.18288)
		(layer "In11.Cu")
		(net "M_H_CPU1_SA_DQS_DP<6>")
	)
	(segment
		(start 157.27172 -305.949604)
		(end 157.028642 -305.949604)
		(width 0.18288)
		(layer "In11.Cu")
		(net "M_H_CPU1_SA_DQS_DP<6>")
	)
	(segment
		(start 159.156908 -305.966368)
		(end 158.169356 -305.966368)
		(width 0.18288)
		(layer "In11.Cu")
		(net "M_H_CPU1_SA_DQS_DP<6>")
	)
	(segment
		(start 127.821944 -277.522432)
		(end 127.821944 -277.506938)
		(width 0.088646)
		(layer "In11.Cu")
		(net "M_H_CPU1_SA_DQS_DP<6>")
	)
	(segment
		(start 125.47727 -275.02358)
		(end 125.42012 -275.08073)
		(width 0.088646)
		(layer "In11.Cu")
		(net "M_H_CPU1_SA_DQS_DP<6>")
	)
	(segment
		(start 154.872944 -300.23943)
		(end 146.703542 -292.070028)
		(width 0.18288)
		(layer "In11.Cu")
		(net "M_H_CPU1_SA_DQS_DP<6>")
	)
	(segment
		(start 136.750044 -279.964134)
		(end 136.750044 -279.954228)
		(width 0.088646)
		(layer "In11.Cu")
		(net "M_H_CPU1_SA_DQS_DP<6>")
	)
	(segment
		(start 140.250418 -283.812488)
		(end 140.250418 -283.603446)
		(width 0.088646)
		(layer "In11.Cu")
		(net "M_H_CPU1_SA_DQS_DP<6>")
	)
	(segment
		(start 207.071214 -301.866554)
		(end 206.806546 -302.131222)
		(width 0.18288)
		(layer "In11.Cu")
		(net "M_H_CPU1_SA_DQS_DP<6>")
	)
	(segment
		(start 129.231898 -278.336502)
		(end 129.231898 -278.322278)
		(width 0.088646)
		(layer "In11.Cu")
		(net "M_H_CPU1_SA_DQS_DP<6>")
	)
	(segment
		(start 130.743706 -278.654764)
		(end 130.733292 -278.66086)
		(width 0.088646)
		(layer "In11.Cu")
		(net "M_H_CPU1_SA_DQS_DP<6>")
	)
	(segment
		(start 198.21652 -305.361086)
		(end 197.287896 -305.361086)
		(width 0.18288)
		(layer "In11.Cu")
		(net "M_H_CPU1_SA_DQS_DP<6>")
	)
	(segment
		(start 192.181226 -308.240938)
		(end 191.71539 -308.240938)
		(width 0.18288)
		(layer "In11.Cu")
		(net "M_H_CPU1_SA_DQS_DP<6>")
	)
	(segment
		(start 172.228764 -309.390034)
		(end 171.653962 -309.390034)
		(width 0.18288)
		(layer "In11.Cu")
		(net "M_H_CPU1_SA_DQS_DP<6>")
	)
	(segment
		(start 187.67679 -307.391054)
		(end 187.37326 -307.694584)
		(width 0.18288)
		(layer "In11.Cu")
		(net "M_H_CPU1_SA_DQS_DP<6>")
	)
	(segment
		(start 199.18172 -304.395886)
		(end 198.21652 -305.361086)
		(width 0.18288)
		(layer "In11.Cu")
		(net "M_H_CPU1_SA_DQS_DP<6>")
	)
	(segment
		(start 199.978264 -303.034954)
		(end 199.978264 -303.889918)
		(width 0.18288)
		(layer "In11.Cu")
		(net "M_H_CPU1_SA_DQS_DP<6>")
	)
	(segment
		(start 174.244508 -308.547262)
		(end 173.425358 -309.366412)
		(width 0.18288)
		(layer "In11.Cu")
		(net "M_H_CPU1_SA_DQS_DP<6>")
	)
	(segment
		(start 188.679836 -307.682646)
		(end 188.362082 -307.682646)
		(width 0.18288)
		(layer "In11.Cu")
		(net "M_H_CPU1_SA_DQS_DP<6>")
	)
	(segment
		(start 169.447718 -307.813456)
		(end 168.327324 -306.693062)
		(width 0.18288)
		(layer "In11.Cu")
		(net "M_H_CPU1_SA_DQS_DP<6>")
	)
	(segment
		(start 177.389536 -308.541928)
		(end 177.088546 -308.240938)
		(width 0.18288)
		(layer "In11.Cu")
		(net "M_H_CPU1_SA_DQS_DP<6>")
	)
	(segment
		(start 126.453646 -275.323046)
		(end 126.297182 -275.205698)
		(width 0.088646)
		(layer "In11.Cu")
		(net "M_H_CPU1_SA_DQS_DP<6>")
	)
	(segment
		(start 173.425358 -309.366412)
		(end 173.276514 -309.366412)
		(width 0.18288)
		(layer "In11.Cu")
		(net "M_H_CPU1_SA_DQS_DP<6>")
	)
	(segment
		(start 130.358896 -278.66086)
		(end 130.348482 -278.654764)
		(width 0.088646)
		(layer "In11.Cu")
		(net "M_H_CPU1_SA_DQS_DP<6>")
	)
	(segment
		(start 203.199746 -301.441358)
		(end 203.045568 -301.441358)
		(width 0.18288)
		(layer "In11.Cu")
		(net "M_H_CPU1_SA_DQS_DP<6>")
	)
	(segment
		(start 195.890896 -306.758086)
		(end 195.246752 -306.758086)
		(width 0.18288)
		(layer "In11.Cu")
		(net "M_H_CPU1_SA_DQS_DP<6>")
	)
	(segment
		(start 157.892496 -305.689508)
		(end 157.531816 -305.689508)
		(width 0.18288)
		(layer "In11.Cu")
		(net "M_H_CPU1_SA_DQS_DP<6>")
	)
	(segment
		(start 158.169356 -305.966368)
		(end 157.892496 -305.689508)
		(width 0.18288)
		(layer "In11.Cu")
		(net "M_H_CPU1_SA_DQS_DP<6>")
	)
	(segment
		(start 138.159998 -280.778204)
		(end 138.159998 -280.76398)
		(width 0.088646)
		(layer "In11.Cu")
		(net "M_H_CPU1_SA_DQS_DP<6>")
	)
	(segment
		(start 127.53975 -277.032974)
		(end 127.53086 -277.027894)
		(width 0.088646)
		(layer "In11.Cu")
		(net "M_H_CPU1_SA_DQS_DP<6>")
	)
	(segment
		(start 187.37326 -307.694584)
		(end 183.863234 -307.694584)
		(width 0.18288)
		(layer "In11.Cu")
		(net "M_H_CPU1_SA_DQS_DP<6>")
	)
	(segment
		(start 164.905182 -306.693062)
		(end 164.189664 -307.40858)
		(width 0.18288)
		(layer "In11.Cu")
		(net "M_H_CPU1_SA_DQS_DP<6>")
	)
	(segment
		(start 157.531816 -305.689508)
		(end 157.27172 -305.949604)
		(width 0.18288)
		(layer "In11.Cu")
		(net "M_H_CPU1_SA_DQS_DP<6>")
	)
	(segment
		(start 168.327324 -306.693062)
		(end 164.905182 -306.693062)
		(width 0.18288)
		(layer "In11.Cu")
		(net "M_H_CPU1_SA_DQS_DP<6>")
	)
	(segment
		(start 199.472296 -304.395886)
		(end 199.18172 -304.395886)
		(width 0.18288)
		(layer "In11.Cu")
		(net "M_H_CPU1_SA_DQS_DP<6>")
	)
	(segment
		(start 197.287896 -305.361086)
		(end 195.890896 -306.758086)
		(width 0.18288)
		(layer "In11.Cu")
		(net "M_H_CPU1_SA_DQS_DP<6>")
	)
	(segment
		(start 202.782424 -301.441358)
		(end 202.512676 -301.711106)
		(width 0.18288)
		(layer "In11.Cu")
		(net "M_H_CPU1_SA_DQS_DP<6>")
	)
	(segment
		(start 179.791868 -307.91277)
		(end 178.79441 -307.91277)
		(width 0.18288)
		(layer "In11.Cu")
		(net "M_H_CPU1_SA_DQS_DP<6>")
	)
	(arc
		(start 127.53086 -277.027894)
		(mid 127.399946 -276.891534)
		(end 127.352298 -276.708616)
		(width 0.088646)
		(layer "In11.Cu")
		(net "M_H_CPU1_SA_DQS_DP<6>")
	)
	(arc
		(start 127.821944 -277.506938)
		(mid 127.742574 -277.233204)
		(end 127.53975 -277.032974)
		(width 0.088646)
		(layer "In11.Cu")
		(net "M_H_CPU1_SA_DQS_DP<6>")
	)
	(arc
		(start 127.352298 -276.708616)
		(mid 127.278307 -276.42905)
		(end 127.075692 -276.222714)
		(width 0.088646)
		(layer "In11.Cu")
		(net "M_H_CPU1_SA_DQS_DP<6>")
	)
	(arc
		(start 126.882144 -275.876258)
		(mid 126.801982 -275.604069)
		(end 126.599696 -275.405088)
		(width 0.088646)
		(layer "In11.Cu")
		(net "M_H_CPU1_SA_DQS_DP<6>")
	)
	(arc
		(start 131.673346 -278.66086)
		(mid 131.486148 -278.711003)
		(end 131.29895 -278.66086)
		(width 0.088646)
		(layer "In11.Cu")
		(net "M_H_CPU1_SA_DQS_DP<6>")
	)
	(arc
		(start 138.33856 -281.097482)
		(mid 138.207646 -280.961122)
		(end 138.159998 -280.778204)
		(width 0.088646)
		(layer "In11.Cu")
		(net "M_H_CPU1_SA_DQS_DP<6>")
	)
	(arc
		(start 135.057896 -278.66086)
		(mid 134.775194 -278.585084)
		(end 134.492492 -278.66086)
		(width 0.088646)
		(layer "In11.Cu")
		(net "M_H_CPU1_SA_DQS_DP<6>")
	)
	(arc
		(start 138.46429 -281.192224)
		(mid 138.404737 -281.140458)
		(end 138.33856 -281.097482)
		(width 0.088646)
		(layer "In11.Cu")
		(net "M_H_CPU1_SA_DQS_DP<6>")
	)
	(arc
		(start 130.733292 -278.66086)
		(mid 130.546094 -278.711003)
		(end 130.358896 -278.66086)
		(width 0.088646)
		(layer "In11.Cu")
		(net "M_H_CPU1_SA_DQS_DP<6>")
	)
	(arc
		(start 138.159998 -280.76398)
		(mid 137.871216 -280.284884)
		(end 137.311892 -280.288492)
		(width 0.088646)
		(layer "In11.Cu")
		(net "M_H_CPU1_SA_DQS_DP<6>")
	)
	(arc
		(start 133.17855 -278.66086)
		(mid 132.895848 -278.585084)
		(end 132.613146 -278.66086)
		(width 0.088646)
		(layer "In11.Cu")
		(net "M_H_CPU1_SA_DQS_DP<6>")
	)
	(arc
		(start 133.552946 -278.66086)
		(mid 133.365748 -278.711003)
		(end 133.17855 -278.66086)
		(width 0.088646)
		(layer "In11.Cu")
		(net "M_H_CPU1_SA_DQS_DP<6>")
	)
	(arc
		(start 132.613146 -278.66086)
		(mid 132.425948 -278.711003)
		(end 132.23875 -278.66086)
		(width 0.088646)
		(layer "In11.Cu")
		(net "M_H_CPU1_SA_DQS_DP<6>")
	)
	(arc
		(start 136.750044 -279.954228)
		(mid 136.671933 -279.677279)
		(end 136.467596 -279.474676)
		(width 0.088646)
		(layer "In11.Cu")
		(net "M_H_CPU1_SA_DQS_DP<6>")
	)
	(arc
		(start 137.311892 -280.288492)
		(mid 136.937417 -280.288446)
		(end 136.750044 -279.964134)
		(width 0.088646)
		(layer "In11.Cu")
		(net "M_H_CPU1_SA_DQS_DP<6>")
	)
	(arc
		(start 127.060706 -276.214078)
		(mid 126.929792 -276.077718)
		(end 126.882144 -275.8948)
		(width 0.088646)
		(layer "In11.Cu")
		(net "M_H_CPU1_SA_DQS_DP<6>")
	)
	(arc
		(start 134.118096 -278.66086)
		(mid 133.841537 -278.585117)
		(end 133.56336 -278.654764)
		(width 0.088646)
		(layer "In11.Cu")
		(net "M_H_CPU1_SA_DQS_DP<6>")
	)
	(arc
		(start 135.432292 -278.66086)
		(mid 135.245094 -278.711003)
		(end 135.057896 -278.66086)
		(width 0.088646)
		(layer "In11.Cu")
		(net "M_H_CPU1_SA_DQS_DP<6>")
	)
	(arc
		(start 132.23875 -278.66086)
		(mid 131.956048 -278.585084)
		(end 131.673346 -278.66086)
		(width 0.088646)
		(layer "In11.Cu")
		(net "M_H_CPU1_SA_DQS_DP<6>")
	)
	(arc
		(start 128.383792 -277.84679)
		(mid 128.009317 -277.846744)
		(end 127.821944 -277.522432)
		(width 0.088646)
		(layer "In11.Cu")
		(net "M_H_CPU1_SA_DQS_DP<6>")
	)
	(arc
		(start 130.348482 -278.654764)
		(mid 130.070304 -278.585041)
		(end 129.793746 -278.66086)
		(width 0.088646)
		(layer "In11.Cu")
		(net "M_H_CPU1_SA_DQS_DP<6>")
	)
	(arc
		(start 129.231898 -278.322278)
		(mid 128.943116 -277.843182)
		(end 128.383792 -277.84679)
		(width 0.088646)
		(layer "In11.Cu")
		(net "M_H_CPU1_SA_DQS_DP<6>")
	)
	(arc
		(start 129.793746 -278.66086)
		(mid 129.419271 -278.660814)
		(end 129.231898 -278.336502)
		(width 0.088646)
		(layer "In11.Cu")
		(net "M_H_CPU1_SA_DQS_DP<6>")
	)
	(arc
		(start 134.492492 -278.66086)
		(mid 134.305294 -278.711003)
		(end 134.118096 -278.66086)
		(width 0.088646)
		(layer "In11.Cu")
		(net "M_H_CPU1_SA_DQS_DP<6>")
	)
	(arc
		(start 126.221998 -275.08073)
		(mid 125.876023 -274.706925)
		(end 125.47727 -275.02358)
		(width 0.088646)
		(layer "In11.Cu")
		(net "M_H_CPU1_SA_DQS_DP<6>")
	)
	(arc
		(start 136.280144 -279.140412)
		(mid 135.993269 -278.658327)
		(end 135.432292 -278.66086)
		(width 0.088646)
		(layer "In11.Cu")
		(net "M_H_CPU1_SA_DQS_DP<6>")
	)
	(arc
		(start 136.458706 -279.469596)
		(mid 136.327792 -279.333236)
		(end 136.280144 -279.150318)
		(width 0.088646)
		(layer "In11.Cu")
		(net "M_H_CPU1_SA_DQS_DP<6>")
	)
	(arc
		(start 131.29895 -278.66086)
		(mid 131.022137 -278.58499)
		(end 130.743706 -278.654764)
		(width 0.088646)
		(layer "In11.Cu")
		(net "M_H_CPU1_SA_DQS_DP<6>")
	)
	(segment
		(start 213.860634 -311.039256)
		(end 214.30615 -311.484772)
		(width 0.20066)
		(layer "F.Cu")
		(net "M_H_CPU1_SA_DQS_DP<5>")
	)
	(segment
		(start 207.071214 -311.216802)
		(end 208.176114 -311.216802)
		(width 0.20066)
		(layer "F.Cu")
		(net "M_H_CPU1_SA_DQS_DP<5>")
	)
	(segment
		(start 210.02879 -311.042812)
		(end 210.286854 -310.784748)
		(width 0.20066)
		(layer "F.Cu")
		(net "M_H_CPU1_SA_DQS_DP<5>")
	)
	(segment
		(start 209.325464 -311.467754)
		(end 209.750406 -311.042812)
		(width 0.20066)
		(layer "F.Cu")
		(net "M_H_CPU1_SA_DQS_DP<5>")
	)
	(segment
		(start 210.286854 -310.784748)
		(end 210.598258 -310.784748)
		(width 0.20066)
		(layer "F.Cu")
		(net "M_H_CPU1_SA_DQS_DP<5>")
	)
	(segment
		(start 215.151716 -311.216802)
		(end 215.719914 -311.216802)
		(width 0.20066)
		(layer "F.Cu")
		(net "M_H_CPU1_SA_DQS_DP<5>")
	)
	(segment
		(start 213.207092 -311.039256)
		(end 213.860634 -311.039256)
		(width 0.20066)
		(layer "F.Cu")
		(net "M_H_CPU1_SA_DQS_DP<5>")
	)
	(segment
		(start 128.196848 -277.522178)
		(end 128.196594 -277.522432)
		(width 0.20066)
		(layer "F.Cu")
		(net "M_H_CPU1_SA_DQS_DP<5>")
	)
	(segment
		(start 210.598258 -310.784748)
		(end 210.603084 -310.784748)
		(width 0.101854)
		(layer "F.Cu")
		(net "M_H_CPU1_SA_DQS_DP<5>")
	)
	(segment
		(start 214.30615 -311.484772)
		(end 214.883746 -311.484772)
		(width 0.20066)
		(layer "F.Cu")
		(net "M_H_CPU1_SA_DQS_DP<5>")
	)
	(segment
		(start 210.610196 -310.79186)
		(end 212.622892 -310.79186)
		(width 0.1016)
		(layer "F.Cu")
		(net "M_H_CPU1_SA_DQS_DP<5>")
	)
	(segment
		(start 128.196848 -276.986492)
		(end 128.196848 -277.522178)
		(width 0.20066)
		(layer "F.Cu")
		(net "M_H_CPU1_SA_DQS_DP<5>")
	)
	(segment
		(start 209.750406 -311.042812)
		(end 210.02879 -311.042812)
		(width 0.20066)
		(layer "F.Cu")
		(net "M_H_CPU1_SA_DQS_DP<5>")
	)
	(segment
		(start 208.769712 -311.216802)
		(end 209.020664 -311.467754)
		(width 0.20066)
		(layer "F.Cu")
		(net "M_H_CPU1_SA_DQS_DP<5>")
	)
	(segment
		(start 214.883746 -311.484772)
		(end 215.151716 -311.216802)
		(width 0.20066)
		(layer "F.Cu")
		(net "M_H_CPU1_SA_DQS_DP<5>")
	)
	(segment
		(start 208.176114 -311.216802)
		(end 208.769712 -311.216802)
		(width 0.20066)
		(layer "F.Cu")
		(net "M_H_CPU1_SA_DQS_DP<5>")
	)
	(segment
		(start 209.020664 -311.467754)
		(end 209.325464 -311.467754)
		(width 0.20066)
		(layer "F.Cu")
		(net "M_H_CPU1_SA_DQS_DP<5>")
	)
	(segment
		(start 210.603084 -310.784748)
		(end 210.610196 -310.79186)
		(width 0.1016)
		(layer "F.Cu")
		(net "M_H_CPU1_SA_DQS_DP<5>")
	)
	(segment
		(start 212.622892 -310.79186)
		(end 212.630258 -310.784494)
		(width 0.1016)
		(layer "F.Cu")
		(net "M_H_CPU1_SA_DQS_DP<5>")
	)
	(segment
		(start 212.95233 -310.784494)
		(end 213.207092 -311.039256)
		(width 0.20066)
		(layer "F.Cu")
		(net "M_H_CPU1_SA_DQS_DP<5>")
	)
	(segment
		(start 212.630258 -310.784494)
		(end 212.95233 -310.784494)
		(width 0.20066)
		(layer "F.Cu")
		(net "M_H_CPU1_SA_DQS_DP<5>")
	)
	(segment
		(start 202.792076 -310.792622)
		(end 202.513438 -311.07126)
		(width 0.18288)
		(layer "In6.Cu")
		(net "M_H_CPU1_SA_DQS_DP<5>")
	)
	(segment
		(start 204.239622 -311.070752)
		(end 203.426314 -311.070752)
		(width 0.18288)
		(layer "In6.Cu")
		(net "M_H_CPU1_SA_DQS_DP<5>")
	)
	(segment
		(start 157.073092 -304.28184)
		(end 156.840428 -304.049176)
		(width 0.18288)
		(layer "In6.Cu")
		(net "M_H_CPU1_SA_DQS_DP<5>")
	)
	(segment
		(start 203.148184 -310.792622)
		(end 202.792076 -310.792622)
		(width 0.18288)
		(layer "In6.Cu")
		(net "M_H_CPU1_SA_DQS_DP<5>")
	)
	(segment
		(start 162.250628 -303.407826)
		(end 161.985452 -303.14265)
		(width 0.18288)
		(layer "In6.Cu")
		(net "M_H_CPU1_SA_DQS_DP<5>")
	)
	(segment
		(start 129.900172 -276.98319)
		(end 129.854198 -277.002748)
		(width 0.088646)
		(layer "In6.Cu")
		(net "M_H_CPU1_SA_DQS_DP<5>")
	)
	(segment
		(start 172.62348 -307.392832)
		(end 172.29836 -307.717952)
		(width 0.18288)
		(layer "In6.Cu")
		(net "M_H_CPU1_SA_DQS_DP<5>")
	)
	(segment
		(start 161.35096 -303.425606)
		(end 159.777176 -303.425606)
		(width 0.18288)
		(layer "In6.Cu")
		(net "M_H_CPU1_SA_DQS_DP<5>")
	)
	(segment
		(start 184.344564 -311.059322)
		(end 183.416448 -310.131206)
		(width 0.18288)
		(layer "In6.Cu")
		(net "M_H_CPU1_SA_DQS_DP<5>")
	)
	(segment
		(start 129.645156 -277.099522)
		(end 129.29362 -277.099522)
		(width 0.088646)
		(layer "In6.Cu")
		(net "M_H_CPU1_SA_DQS_DP<5>")
	)
	(segment
		(start 138.629644 -278.336502)
		(end 138.629644 -278.31796)
		(width 0.088646)
		(layer "In6.Cu")
		(net "M_H_CPU1_SA_DQS_DP<5>")
	)
	(segment
		(start 183.416448 -310.131206)
		(end 182.464456 -310.131206)
		(width 0.18288)
		(layer "In6.Cu")
		(net "M_H_CPU1_SA_DQS_DP<5>")
	)
	(segment
		(start 205.634844 -311.648856)
		(end 204.817726 -311.648856)
		(width 0.18288)
		(layer "In6.Cu")
		(net "M_H_CPU1_SA_DQS_DP<5>")
	)
	(segment
		(start 182.464456 -310.131206)
		(end 180.940456 -308.607206)
		(width 0.18288)
		(layer "In6.Cu")
		(net "M_H_CPU1_SA_DQS_DP<5>")
	)
	(segment
		(start 156.840428 -300.622208)
		(end 148.971762 -292.753542)
		(width 0.18288)
		(layer "In6.Cu")
		(net "M_H_CPU1_SA_DQS_DP<5>")
	)
	(segment
		(start 204.817726 -311.648856)
		(end 204.239622 -311.070752)
		(width 0.18288)
		(layer "In6.Cu")
		(net "M_H_CPU1_SA_DQS_DP<5>")
	)
	(segment
		(start 140.2842 -279.83561)
		(end 140.184632 -279.83561)
		(width 0.088646)
		(layer "In6.Cu")
		(net "M_H_CPU1_SA_DQS_DP<5>")
	)
	(segment
		(start 194.626484 -310.848756)
		(end 194.0052 -310.848756)
		(width 0.18288)
		(layer "In6.Cu")
		(net "M_H_CPU1_SA_DQS_DP<5>")
	)
	(segment
		(start 198.607426 -311.07126)
		(end 197.941692 -311.736994)
		(width 0.18288)
		(layer "In6.Cu")
		(net "M_H_CPU1_SA_DQS_DP<5>")
	)
	(segment
		(start 140.184632 -279.83561)
		(end 140.100558 -279.751536)
		(width 0.088646)
		(layer "In6.Cu")
		(net "M_H_CPU1_SA_DQS_DP<5>")
	)
	(segment
		(start 140.524738 -279.77592)
		(end 140.367258 -279.77592)
		(width 0.18288)
		(layer "In6.Cu")
		(net "M_H_CPU1_SA_DQS_DP<5>")
	)
	(segment
		(start 138.159744 -277.522432)
		(end 138.159744 -277.512526)
		(width 0.088646)
		(layer "In6.Cu")
		(net "M_H_CPU1_SA_DQS_DP<5>")
	)
	(segment
		(start 179.044854 -307.384704)
		(end 178.59375 -307.384704)
		(width 0.18288)
		(layer "In6.Cu")
		(net "M_H_CPU1_SA_DQS_DP<5>")
	)
	(segment
		(start 173.02988 -307.392832)
		(end 172.62348 -307.392832)
		(width 0.18288)
		(layer "In6.Cu")
		(net "M_H_CPU1_SA_DQS_DP<5>")
	)
	(segment
		(start 140.34389 -279.77592)
		(end 140.2842 -279.83561)
		(width 0.088646)
		(layer "In6.Cu")
		(net "M_H_CPU1_SA_DQS_DP<5>")
	)
	(segment
		(start 163.25977 -303.407826)
		(end 162.250628 -303.407826)
		(width 0.18288)
		(layer "In6.Cu")
		(net "M_H_CPU1_SA_DQS_DP<5>")
	)
	(segment
		(start 159.777176 -303.425606)
		(end 158.926022 -304.27676)
		(width 0.18288)
		(layer "In6.Cu")
		(net "M_H_CPU1_SA_DQS_DP<5>")
	)
	(segment
		(start 157.520132 -303.988216)
		(end 157.226508 -304.28184)
		(width 0.18288)
		(layer "In6.Cu")
		(net "M_H_CPU1_SA_DQS_DP<5>")
	)
	(segment
		(start 177.34026 -306.800758)
		(end 177.082958 -306.543456)
		(width 0.18288)
		(layer "In6.Cu")
		(net "M_H_CPU1_SA_DQS_DP<5>")
	)
	(segment
		(start 195.026026 -310.449214)
		(end 194.626484 -310.848756)
		(width 0.18288)
		(layer "In6.Cu")
		(net "M_H_CPU1_SA_DQS_DP<5>")
	)
	(segment
		(start 191.803274 -309.94096)
		(end 191.513714 -310.23052)
		(width 0.18288)
		(layer "In6.Cu")
		(net "M_H_CPU1_SA_DQS_DP<5>")
	)
	(segment
		(start 176.421542 -306.824888)
		(end 174.349664 -306.824888)
		(width 0.18288)
		(layer "In6.Cu")
		(net "M_H_CPU1_SA_DQS_DP<5>")
	)
	(segment
		(start 140.100558 -279.751536)
		(end 140.005054 -279.522174)
		(width 0.088646)
		(layer "In6.Cu")
		(net "M_H_CPU1_SA_DQS_DP<5>")
	)
	(segment
		(start 131.68376 -277.026878)
		(end 131.673346 -277.032974)
		(width 0.088646)
		(layer "In6.Cu")
		(net "M_H_CPU1_SA_DQS_DP<5>")
	)
	(segment
		(start 134.507478 -277.024338)
		(end 134.492746 -277.032974)
		(width 0.088646)
		(layer "In6.Cu")
		(net "M_H_CPU1_SA_DQS_DP<5>")
	)
	(segment
		(start 194.0052 -310.848756)
		(end 193.365374 -310.20893)
		(width 0.18288)
		(layer "In6.Cu")
		(net "M_H_CPU1_SA_DQS_DP<5>")
	)
	(segment
		(start 129.78892 -277.035768)
		(end 129.756408 -277.05304)
		(width 0.088646)
		(layer "In6.Cu")
		(net "M_H_CPU1_SA_DQS_DP<5>")
	)
	(segment
		(start 180.267356 -308.607206)
		(end 179.044854 -307.384704)
		(width 0.18288)
		(layer "In6.Cu")
		(net "M_H_CPU1_SA_DQS_DP<5>")
	)
	(segment
		(start 187.425584 -311.059322)
		(end 184.344564 -311.059322)
		(width 0.18288)
		(layer "In6.Cu")
		(net "M_H_CPU1_SA_DQS_DP<5>")
	)
	(segment
		(start 156.840428 -304.049176)
		(end 156.840428 -300.622208)
		(width 0.18288)
		(layer "In6.Cu")
		(net "M_H_CPU1_SA_DQS_DP<5>")
	)
	(segment
		(start 157.896814 -303.988216)
		(end 157.520132 -303.988216)
		(width 0.18288)
		(layer "In6.Cu")
		(net "M_H_CPU1_SA_DQS_DP<5>")
	)
	(segment
		(start 158.185358 -304.27676)
		(end 157.896814 -303.988216)
		(width 0.18288)
		(layer "In6.Cu")
		(net "M_H_CPU1_SA_DQS_DP<5>")
	)
	(segment
		(start 129.159254 -277.126446)
		(end 129.159254 -277.126192)
		(width 0.088646)
		(layer "In6.Cu")
		(net "M_H_CPU1_SA_DQS_DP<5>")
	)
	(segment
		(start 130.30962 -277.007574)
		(end 130.309112 -277.007574)
		(width 0.088646)
		(layer "In6.Cu")
		(net "M_H_CPU1_SA_DQS_DP<5>")
	)
	(segment
		(start 176.702974 -306.543456)
		(end 176.421542 -306.824888)
		(width 0.18288)
		(layer "In6.Cu")
		(net "M_H_CPU1_SA_DQS_DP<5>")
	)
	(segment
		(start 206.807562 -311.480454)
		(end 206.041498 -311.480454)
		(width 0.18288)
		(layer "In6.Cu")
		(net "M_H_CPU1_SA_DQS_DP<5>")
	)
	(segment
		(start 141.04239 -279.990296)
		(end 140.524738 -279.77592)
		(width 0.18288)
		(layer "In6.Cu")
		(net "M_H_CPU1_SA_DQS_DP<5>")
	)
	(segment
		(start 206.041498 -311.480454)
		(end 205.634844 -311.648856)
		(width 0.18288)
		(layer "In6.Cu")
		(net "M_H_CPU1_SA_DQS_DP<5>")
	)
	(segment
		(start 128.949196 -277.198074)
		(end 128.947672 -277.198836)
		(width 0.088646)
		(layer "In6.Cu")
		(net "M_H_CPU1_SA_DQS_DP<5>")
	)
	(segment
		(start 192.160398 -309.94096)
		(end 191.803274 -309.94096)
		(width 0.18288)
		(layer "In6.Cu")
		(net "M_H_CPU1_SA_DQS_DP<5>")
	)
	(segment
		(start 164.81933 -304.967386)
		(end 163.25977 -303.407826)
		(width 0.18288)
		(layer "In6.Cu")
		(net "M_H_CPU1_SA_DQS_DP<5>")
	)
	(segment
		(start 145.812002 -279.990296)
		(end 141.04239 -279.990296)
		(width 0.18288)
		(layer "In6.Cu")
		(net "M_H_CPU1_SA_DQS_DP<5>")
	)
	(segment
		(start 138.347196 -277.84679)
		(end 138.338306 -277.84171)
		(width 0.088646)
		(layer "In6.Cu")
		(net "M_H_CPU1_SA_DQS_DP<5>")
	)
	(segment
		(start 189.4586 -310.23052)
		(end 188.633608 -311.055512)
		(width 0.18288)
		(layer "In6.Cu")
		(net "M_H_CPU1_SA_DQS_DP<5>")
	)
	(segment
		(start 148.971762 -283.150056)
		(end 145.812002 -279.990296)
		(width 0.18288)
		(layer "In6.Cu")
		(net "M_H_CPU1_SA_DQS_DP<5>")
	)
	(segment
		(start 129.756408 -277.05304)
		(end 129.755646 -277.053548)
		(width 0.088646)
		(layer "In6.Cu")
		(net "M_H_CPU1_SA_DQS_DP<5>")
	)
	(segment
		(start 133.567678 -277.024338)
		(end 133.552946 -277.032974)
		(width 0.088646)
		(layer "In6.Cu")
		(net "M_H_CPU1_SA_DQS_DP<5>")
	)
	(segment
		(start 187.692284 -310.792622)
		(end 187.425584 -311.059322)
		(width 0.18288)
		(layer "In6.Cu")
		(net "M_H_CPU1_SA_DQS_DP<5>")
	)
	(segment
		(start 188.064648 -310.792622)
		(end 187.692284 -310.792622)
		(width 0.18288)
		(layer "In6.Cu")
		(net "M_H_CPU1_SA_DQS_DP<5>")
	)
	(segment
		(start 140.367258 -279.77592)
		(end 140.34389 -279.77592)
		(width 0.088646)
		(layer "In6.Cu")
		(net "M_H_CPU1_SA_DQS_DP<5>")
	)
	(segment
		(start 191.513714 -310.23052)
		(end 189.4586 -310.23052)
		(width 0.18288)
		(layer "In6.Cu")
		(net "M_H_CPU1_SA_DQS_DP<5>")
	)
	(segment
		(start 197.941692 -311.736994)
		(end 197.343014 -311.736994)
		(width 0.18288)
		(layer "In6.Cu")
		(net "M_H_CPU1_SA_DQS_DP<5>")
	)
	(segment
		(start 161.985452 -303.14265)
		(end 161.633916 -303.14265)
		(width 0.18288)
		(layer "In6.Cu")
		(net "M_H_CPU1_SA_DQS_DP<5>")
	)
	(segment
		(start 193.365374 -310.20893)
		(end 192.428368 -310.20893)
		(width 0.18288)
		(layer "In6.Cu")
		(net "M_H_CPU1_SA_DQS_DP<5>")
	)
	(segment
		(start 188.327538 -311.055512)
		(end 188.064648 -310.792622)
		(width 0.18288)
		(layer "In6.Cu")
		(net "M_H_CPU1_SA_DQS_DP<5>")
	)
	(segment
		(start 130.309112 -277.007574)
		(end 130.263646 -276.987)
		(width 0.088646)
		(layer "In6.Cu")
		(net "M_H_CPU1_SA_DQS_DP<5>")
	)
	(segment
		(start 129.755646 -277.053548)
		(end 129.645156 -277.099522)
		(width 0.088646)
		(layer "In6.Cu")
		(net "M_H_CPU1_SA_DQS_DP<5>")
	)
	(segment
		(start 132.623306 -277.026878)
		(end 132.612892 -277.032974)
		(width 0.088646)
		(layer "In6.Cu")
		(net "M_H_CPU1_SA_DQS_DP<5>")
	)
	(segment
		(start 178.009804 -306.800758)
		(end 177.34026 -306.800758)
		(width 0.18288)
		(layer "In6.Cu")
		(net "M_H_CPU1_SA_DQS_DP<5>")
	)
	(segment
		(start 174.349664 -306.824888)
		(end 173.529498 -307.645054)
		(width 0.18288)
		(layer "In6.Cu")
		(net "M_H_CPU1_SA_DQS_DP<5>")
	)
	(segment
		(start 167.014398 -306.811426)
		(end 165.170358 -304.967386)
		(width 0.18288)
		(layer "In6.Cu")
		(net "M_H_CPU1_SA_DQS_DP<5>")
	)
	(segment
		(start 128.766316 -277.465282)
		(end 128.709166 -277.522432)
		(width 0.088646)
		(layer "In6.Cu")
		(net "M_H_CPU1_SA_DQS_DP<5>")
	)
	(segment
		(start 188.633608 -311.055512)
		(end 188.327538 -311.055512)
		(width 0.18288)
		(layer "In6.Cu")
		(net "M_H_CPU1_SA_DQS_DP<5>")
	)
	(segment
		(start 129.794762 -277.032466)
		(end 129.78892 -277.035768)
		(width 0.088646)
		(layer "In6.Cu")
		(net "M_H_CPU1_SA_DQS_DP<5>")
	)
	(segment
		(start 135.432292 -277.032974)
		(end 135.42391 -277.0378)
		(width 0.088646)
		(layer "In6.Cu")
		(net "M_H_CPU1_SA_DQS_DP<5>")
	)
	(segment
		(start 178.59375 -307.384704)
		(end 178.009804 -306.800758)
		(width 0.18288)
		(layer "In6.Cu")
		(net "M_H_CPU1_SA_DQS_DP<5>")
	)
	(segment
		(start 161.633916 -303.14265)
		(end 161.35096 -303.425606)
		(width 0.18288)
		(layer "In6.Cu")
		(net "M_H_CPU1_SA_DQS_DP<5>")
	)
	(segment
		(start 172.29836 -307.717952)
		(end 168.957752 -307.717952)
		(width 0.18288)
		(layer "In6.Cu")
		(net "M_H_CPU1_SA_DQS_DP<5>")
	)
	(segment
		(start 173.529498 -307.645054)
		(end 173.282102 -307.645054)
		(width 0.18288)
		(layer "In6.Cu")
		(net "M_H_CPU1_SA_DQS_DP<5>")
	)
	(segment
		(start 168.051226 -306.811426)
		(end 167.014398 -306.811426)
		(width 0.18288)
		(layer "In6.Cu")
		(net "M_H_CPU1_SA_DQS_DP<5>")
	)
	(segment
		(start 128.947672 -277.198836)
		(end 128.940306 -277.203154)
		(width 0.088646)
		(layer "In6.Cu")
		(net "M_H_CPU1_SA_DQS_DP<5>")
	)
	(segment
		(start 129.139442 -277.130256)
		(end 129.089658 -277.15083)
		(width 0.088646)
		(layer "In6.Cu")
		(net "M_H_CPU1_SA_DQS_DP<5>")
	)
	(segment
		(start 197.343014 -311.736994)
		(end 196.055234 -310.449214)
		(width 0.18288)
		(layer "In6.Cu")
		(net "M_H_CPU1_SA_DQS_DP<5>")
	)
	(segment
		(start 196.055234 -310.449214)
		(end 195.026026 -310.449214)
		(width 0.18288)
		(layer "In6.Cu")
		(net "M_H_CPU1_SA_DQS_DP<5>")
	)
	(segment
		(start 207.071214 -311.216802)
		(end 206.807562 -311.480454)
		(width 0.18288)
		(layer "In6.Cu")
		(net "M_H_CPU1_SA_DQS_DP<5>")
	)
	(segment
		(start 129.159254 -277.126192)
		(end 129.139442 -277.130256)
		(width 0.088646)
		(layer "In6.Cu")
		(net "M_H_CPU1_SA_DQS_DP<5>")
	)
	(segment
		(start 128.709166 -277.522432)
		(end 128.196594 -277.522432)
		(width 0.088646)
		(layer "In6.Cu")
		(net "M_H_CPU1_SA_DQS_DP<5>")
	)
	(segment
		(start 202.513438 -311.07126)
		(end 198.607426 -311.07126)
		(width 0.18288)
		(layer "In6.Cu")
		(net "M_H_CPU1_SA_DQS_DP<5>")
	)
	(segment
		(start 180.940456 -308.607206)
		(end 180.267356 -308.607206)
		(width 0.18288)
		(layer "In6.Cu")
		(net "M_H_CPU1_SA_DQS_DP<5>")
	)
	(segment
		(start 129.29362 -277.099522)
		(end 129.159254 -277.126446)
		(width 0.088646)
		(layer "In6.Cu")
		(net "M_H_CPU1_SA_DQS_DP<5>")
	)
	(segment
		(start 135.447024 -277.024338)
		(end 135.432292 -277.032974)
		(width 0.088646)
		(layer "In6.Cu")
		(net "M_H_CPU1_SA_DQS_DP<5>")
	)
	(segment
		(start 165.170358 -304.967386)
		(end 164.81933 -304.967386)
		(width 0.18288)
		(layer "In6.Cu")
		(net "M_H_CPU1_SA_DQS_DP<5>")
	)
	(segment
		(start 177.082958 -306.543456)
		(end 176.702974 -306.543456)
		(width 0.18288)
		(layer "In6.Cu")
		(net "M_H_CPU1_SA_DQS_DP<5>")
	)
	(segment
		(start 168.957752 -307.717952)
		(end 168.051226 -306.811426)
		(width 0.18288)
		(layer "In6.Cu")
		(net "M_H_CPU1_SA_DQS_DP<5>")
	)
	(segment
		(start 173.282102 -307.645054)
		(end 173.02988 -307.392832)
		(width 0.18288)
		(layer "In6.Cu")
		(net "M_H_CPU1_SA_DQS_DP<5>")
	)
	(segment
		(start 192.428368 -310.20893)
		(end 192.160398 -309.94096)
		(width 0.18288)
		(layer "In6.Cu")
		(net "M_H_CPU1_SA_DQS_DP<5>")
	)
	(segment
		(start 139.19454 -278.71166)
		(end 139.00404 -278.71166)
		(width 0.088646)
		(layer "In6.Cu")
		(net "M_H_CPU1_SA_DQS_DP<5>")
	)
	(segment
		(start 140.005054 -279.522174)
		(end 139.19454 -278.71166)
		(width 0.088646)
		(layer "In6.Cu")
		(net "M_H_CPU1_SA_DQS_DP<5>")
	)
	(segment
		(start 158.926022 -304.27676)
		(end 158.185358 -304.27676)
		(width 0.18288)
		(layer "In6.Cu")
		(net "M_H_CPU1_SA_DQS_DP<5>")
	)
	(segment
		(start 148.971762 -292.753542)
		(end 148.971762 -283.150056)
		(width 0.18288)
		(layer "In6.Cu")
		(net "M_H_CPU1_SA_DQS_DP<5>")
	)
	(segment
		(start 203.426314 -311.070752)
		(end 203.148184 -310.792622)
		(width 0.18288)
		(layer "In6.Cu")
		(net "M_H_CPU1_SA_DQS_DP<5>")
	)
	(segment
		(start 157.226508 -304.28184)
		(end 157.073092 -304.28184)
		(width 0.18288)
		(layer "In6.Cu")
		(net "M_H_CPU1_SA_DQS_DP<5>")
	)
	(arc
		(start 138.159744 -277.512526)
		(mid 138.081633 -277.235577)
		(end 137.877296 -277.032974)
		(width 0.088646)
		(layer "In6.Cu")
		(net "M_H_CPU1_SA_DQS_DP<5>")
	)
	(arc
		(start 131.673346 -277.032974)
		(mid 131.486148 -277.083117)
		(end 131.29895 -277.032974)
		(width 0.088646)
		(layer "In6.Cu")
		(net "M_H_CPU1_SA_DQS_DP<5>")
	)
	(arc
		(start 134.492746 -277.032974)
		(mid 134.305548 -277.083117)
		(end 134.11835 -277.032974)
		(width 0.088646)
		(layer "In6.Cu")
		(net "M_H_CPU1_SA_DQS_DP<5>")
	)
	(arc
		(start 136.372092 -277.032974)
		(mid 136.184894 -277.083117)
		(end 135.997696 -277.032974)
		(width 0.088646)
		(layer "In6.Cu")
		(net "M_H_CPU1_SA_DQS_DP<5>")
	)
	(arc
		(start 130.733546 -277.032974)
		(mid 130.546348 -277.083117)
		(end 130.35915 -277.032974)
		(width 0.088646)
		(layer "In6.Cu")
		(net "M_H_CPU1_SA_DQS_DP<5>")
	)
	(arc
		(start 138.629644 -278.31796)
		(mid 138.549482 -278.045771)
		(end 138.347196 -277.84679)
		(width 0.088646)
		(layer "In6.Cu")
		(net "M_H_CPU1_SA_DQS_DP<5>")
	)
	(arc
		(start 128.940306 -277.203154)
		(mid 128.824497 -277.315083)
		(end 128.766316 -277.465282)
		(width 0.088646)
		(layer "In6.Cu")
		(net "M_H_CPU1_SA_DQS_DP<5>")
	)
	(arc
		(start 139.00404 -278.71166)
		(mid 138.907013 -278.698828)
		(end 138.816588 -278.661368)
		(width 0.088646)
		(layer "In6.Cu")
		(net "M_H_CPU1_SA_DQS_DP<5>")
	)
	(arc
		(start 135.05815 -277.032974)
		(mid 134.783951 -276.957139)
		(end 134.507478 -277.024338)
		(width 0.088646)
		(layer "In6.Cu")
		(net "M_H_CPU1_SA_DQS_DP<5>")
	)
	(arc
		(start 137.877296 -277.032974)
		(mid 137.594594 -276.957198)
		(end 137.311892 -277.032974)
		(width 0.088646)
		(layer "In6.Cu")
		(net "M_H_CPU1_SA_DQS_DP<5>")
	)
	(arc
		(start 130.35915 -277.032974)
		(mid 130.334698 -277.019663)
		(end 130.30962 -277.007574)
		(width 0.088646)
		(layer "In6.Cu")
		(net "M_H_CPU1_SA_DQS_DP<5>")
	)
	(arc
		(start 133.17855 -277.032974)
		(mid 132.901737 -276.957104)
		(end 132.623306 -277.026878)
		(width 0.088646)
		(layer "In6.Cu")
		(net "M_H_CPU1_SA_DQS_DP<5>")
	)
	(arc
		(start 135.997696 -277.032974)
		(mid 135.723497 -276.957139)
		(end 135.447024 -277.024338)
		(width 0.088646)
		(layer "In6.Cu")
		(net "M_H_CPU1_SA_DQS_DP<5>")
	)
	(arc
		(start 133.552946 -277.032974)
		(mid 133.365748 -277.083117)
		(end 133.17855 -277.032974)
		(width 0.088646)
		(layer "In6.Cu")
		(net "M_H_CPU1_SA_DQS_DP<5>")
	)
	(arc
		(start 131.29895 -277.032974)
		(mid 131.016248 -276.957198)
		(end 130.733546 -277.032974)
		(width 0.088646)
		(layer "In6.Cu")
		(net "M_H_CPU1_SA_DQS_DP<5>")
	)
	(arc
		(start 138.816588 -278.661368)
		(mid 138.812379 -278.658601)
		(end 138.808206 -278.65578)
		(width 0.088646)
		(layer "In6.Cu")
		(net "M_H_CPU1_SA_DQS_DP<5>")
	)
	(arc
		(start 132.612892 -277.032974)
		(mid 132.425694 -277.083117)
		(end 132.238496 -277.032974)
		(width 0.088646)
		(layer "In6.Cu")
		(net "M_H_CPU1_SA_DQS_DP<5>")
	)
	(arc
		(start 134.11835 -277.032974)
		(mid 133.844151 -276.957139)
		(end 133.567678 -277.024338)
		(width 0.088646)
		(layer "In6.Cu")
		(net "M_H_CPU1_SA_DQS_DP<5>")
	)
	(arc
		(start 129.854198 -277.002748)
		(mid 129.824041 -277.01673)
		(end 129.794762 -277.032466)
		(width 0.088646)
		(layer "In6.Cu")
		(net "M_H_CPU1_SA_DQS_DP<5>")
	)
	(arc
		(start 137.311892 -277.032974)
		(mid 137.124694 -277.083117)
		(end 136.937496 -277.032974)
		(width 0.088646)
		(layer "In6.Cu")
		(net "M_H_CPU1_SA_DQS_DP<5>")
	)
	(arc
		(start 130.263646 -276.987)
		(mid 130.0823 -276.946865)
		(end 129.900172 -276.98319)
		(width 0.088646)
		(layer "In6.Cu")
		(net "M_H_CPU1_SA_DQS_DP<5>")
	)
	(arc
		(start 136.937496 -277.032974)
		(mid 136.654794 -276.957198)
		(end 136.372092 -277.032974)
		(width 0.088646)
		(layer "In6.Cu")
		(net "M_H_CPU1_SA_DQS_DP<5>")
	)
	(arc
		(start 138.808206 -278.65578)
		(mid 138.677292 -278.51942)
		(end 138.629644 -278.336502)
		(width 0.088646)
		(layer "In6.Cu")
		(net "M_H_CPU1_SA_DQS_DP<5>")
	)
	(arc
		(start 129.089658 -277.15083)
		(mid 129.017061 -277.167422)
		(end 128.949196 -277.198074)
		(width 0.088646)
		(layer "In6.Cu")
		(net "M_H_CPU1_SA_DQS_DP<5>")
	)
	(arc
		(start 138.338306 -277.84171)
		(mid 138.207392 -277.70535)
		(end 138.159744 -277.522432)
		(width 0.088646)
		(layer "In6.Cu")
		(net "M_H_CPU1_SA_DQS_DP<5>")
	)
	(arc
		(start 132.238496 -277.032974)
		(mid 131.961937 -276.957231)
		(end 131.68376 -277.026878)
		(width 0.088646)
		(layer "In6.Cu")
		(net "M_H_CPU1_SA_DQS_DP<5>")
	)
	(arc
		(start 135.42391 -277.0378)
		(mid 135.240402 -277.083078)
		(end 135.05815 -277.032974)
		(width 0.088646)
		(layer "In6.Cu")
		(net "M_H_CPU1_SA_DQS_DP<5>")
	)
	(segment
		(start 206.606648 -275.690584)
		(end 206.857854 -275.94179)
		(width 0.20066)
		(layer "F.Cu")
		(net "M_H_CPU1_SA_DQS_DP<4>")
	)
	(segment
		(start 209.812382 -275.645372)
		(end 210.182968 -275.645372)
		(width 0.20066)
		(layer "F.Cu")
		(net "M_H_CPU1_SA_DQS_DP<4>")
	)
	(segment
		(start 204.076046 -275.516594)
		(end 204.665326 -275.516594)
		(width 0.20066)
		(layer "F.Cu")
		(net "M_H_CPU1_SA_DQS_DP<4>")
	)
	(segment
		(start 206.9973 -275.94179)
		(end 207.023208 -275.94179)
		(width 0.101854)
		(layer "F.Cu")
		(net "M_H_CPU1_SA_DQS_DP<4>")
	)
	(segment
		(start 209.18043 -275.94179)
		(end 209.186526 -275.947886)
		(width 0.1016)
		(layer "F.Cu")
		(net "M_H_CPU1_SA_DQS_DP<4>")
	)
	(segment
		(start 205.50632 -275.276056)
		(end 205.920848 -275.690584)
		(width 0.20066)
		(layer "F.Cu")
		(net "M_H_CPU1_SA_DQS_DP<4>")
	)
	(segment
		(start 206.857854 -275.94179)
		(end 206.9973 -275.94179)
		(width 0.20066)
		(layer "F.Cu")
		(net "M_H_CPU1_SA_DQS_DP<4>")
	)
	(segment
		(start 210.182968 -275.645372)
		(end 210.593432 -275.234908)
		(width 0.20066)
		(layer "F.Cu")
		(net "M_H_CPU1_SA_DQS_DP<4>")
	)
	(segment
		(start 207.023208 -275.94179)
		(end 209.18043 -275.94179)
		(width 0.1016)
		(layer "F.Cu")
		(net "M_H_CPU1_SA_DQS_DP<4>")
	)
	(segment
		(start 202.971146 -275.516594)
		(end 204.076046 -275.516594)
		(width 0.20066)
		(layer "F.Cu")
		(net "M_H_CPU1_SA_DQS_DP<4>")
	)
	(segment
		(start 123.027694 -259.894832)
		(end 123.027694 -260.430518)
		(width 0.20066)
		(layer "F.Cu")
		(net "M_H_CPU1_SA_DQS_DP<4>")
	)
	(segment
		(start 123.027694 -260.430518)
		(end 123.027948 -260.430772)
		(width 0.20066)
		(layer "F.Cu")
		(net "M_H_CPU1_SA_DQS_DP<4>")
	)
	(segment
		(start 210.593432 -275.234908)
		(end 210.78952 -275.234908)
		(width 0.20066)
		(layer "F.Cu")
		(net "M_H_CPU1_SA_DQS_DP<4>")
	)
	(segment
		(start 209.509868 -275.947886)
		(end 209.812382 -275.645372)
		(width 0.20066)
		(layer "F.Cu")
		(net "M_H_CPU1_SA_DQS_DP<4>")
	)
	(segment
		(start 211.071206 -275.516594)
		(end 211.619846 -275.516594)
		(width 0.20066)
		(layer "F.Cu")
		(net "M_H_CPU1_SA_DQS_DP<4>")
	)
	(segment
		(start 205.920848 -275.690584)
		(end 206.606648 -275.690584)
		(width 0.20066)
		(layer "F.Cu")
		(net "M_H_CPU1_SA_DQS_DP<4>")
	)
	(segment
		(start 204.665326 -275.516594)
		(end 204.905864 -275.276056)
		(width 0.20066)
		(layer "F.Cu")
		(net "M_H_CPU1_SA_DQS_DP<4>")
	)
	(segment
		(start 209.186526 -275.947886)
		(end 209.509868 -275.947886)
		(width 0.20066)
		(layer "F.Cu")
		(net "M_H_CPU1_SA_DQS_DP<4>")
	)
	(segment
		(start 204.905864 -275.276056)
		(end 205.50632 -275.276056)
		(width 0.20066)
		(layer "F.Cu")
		(net "M_H_CPU1_SA_DQS_DP<4>")
	)
	(segment
		(start 210.78952 -275.234908)
		(end 211.071206 -275.516594)
		(width 0.20066)
		(layer "F.Cu")
		(net "M_H_CPU1_SA_DQS_DP<4>")
	)
	(segment
		(start 176.359566 -277.398226)
		(end 175.997616 -277.398226)
		(width 0.18288)
		(layer "In11.Cu")
		(net "M_H_CPU1_SA_DQS_DP<4>")
	)
	(segment
		(start 140.073126 -263.437878)
		(end 139.474448 -263.437878)
		(width 0.088646)
		(layer "In11.Cu")
		(net "M_H_CPU1_SA_DQS_DP<4>")
	)
	(segment
		(start 192.476882 -277.375366)
		(end 192.211452 -277.640796)
		(width 0.18288)
		(layer "In11.Cu")
		(net "M_H_CPU1_SA_DQS_DP<4>")
	)
	(segment
		(start 172.244004 -276.533102)
		(end 168.996868 -276.533102)
		(width 0.18288)
		(layer "In11.Cu")
		(net "M_H_CPU1_SA_DQS_DP<4>")
	)
	(segment
		(start 173.283118 -276.531832)
		(end 173.024038 -276.790912)
		(width 0.18288)
		(layer "In11.Cu")
		(net "M_H_CPU1_SA_DQS_DP<4>")
	)
	(segment
		(start 202.160632 -275.065998)
		(end 201.681334 -275.065998)
		(width 0.18288)
		(layer "In11.Cu")
		(net "M_H_CPU1_SA_DQS_DP<4>")
	)
	(segment
		(start 178.06797 -277.39594)
		(end 177.368708 -277.39594)
		(width 0.18288)
		(layer "In11.Cu")
		(net "M_H_CPU1_SA_DQS_DP<4>")
	)
	(segment
		(start 177.123852 -277.640796)
		(end 176.602136 -277.640796)
		(width 0.18288)
		(layer "In11.Cu")
		(net "M_H_CPU1_SA_DQS_DP<4>")
	)
	(segment
		(start 162.780218 -275.379942)
		(end 160.82264 -274.568666)
		(width 0.18288)
		(layer "In11.Cu")
		(net "M_H_CPU1_SA_DQS_DP<4>")
	)
	(segment
		(start 164.830506 -275.77161)
		(end 164.332666 -276.26945)
		(width 0.18288)
		(layer "In11.Cu")
		(net "M_H_CPU1_SA_DQS_DP<4>")
	)
	(segment
		(start 140.86586 -263.590786)
		(end 140.226034 -263.590786)
		(width 0.088646)
		(layer "In11.Cu")
		(net "M_H_CPU1_SA_DQS_DP<4>")
	)
	(segment
		(start 137.320782 -261.73938)
		(end 137.311892 -261.7343)
		(width 0.088646)
		(layer "In11.Cu")
		(net "M_H_CPU1_SA_DQS_DP<4>")
	)
	(segment
		(start 200.138792 -276.263354)
		(end 198.81469 -276.263354)
		(width 0.18288)
		(layer "In11.Cu")
		(net "M_H_CPU1_SA_DQS_DP<4>")
	)
	(segment
		(start 160.82264 -274.568666)
		(end 156.524452 -274.568666)
		(width 0.18288)
		(layer "In11.Cu")
		(net "M_H_CPU1_SA_DQS_DP<4>")
	)
	(segment
		(start 130.828796 -260.920484)
		(end 130.814064 -260.92912)
		(width 0.088646)
		(layer "In11.Cu")
		(net "M_H_CPU1_SA_DQS_DP<4>")
	)
	(segment
		(start 193.756788 -276.73935)
		(end 193.120772 -277.375366)
		(width 0.18288)
		(layer "In11.Cu")
		(net "M_H_CPU1_SA_DQS_DP<4>")
	)
	(segment
		(start 202.971146 -275.516594)
		(end 202.68184 -275.227288)
		(width 0.18288)
		(layer "In11.Cu")
		(net "M_H_CPU1_SA_DQS_DP<4>")
	)
	(segment
		(start 123.4059 -260.49605)
		(end 123.340622 -260.430772)
		(width 0.088646)
		(layer "In11.Cu")
		(net "M_H_CPU1_SA_DQS_DP<4>")
	)
	(segment
		(start 129.888996 -260.920484)
		(end 129.874264 -260.92912)
		(width 0.088646)
		(layer "In11.Cu")
		(net "M_H_CPU1_SA_DQS_DP<4>")
	)
	(segment
		(start 184.081166 -276.516338)
		(end 182.566564 -275.851366)
		(width 0.18288)
		(layer "In11.Cu")
		(net "M_H_CPU1_SA_DQS_DP<4>")
	)
	(segment
		(start 168.996868 -276.533102)
		(end 168.235376 -275.77161)
		(width 0.18288)
		(layer "In11.Cu")
		(net "M_H_CPU1_SA_DQS_DP<4>")
	)
	(segment
		(start 132.708396 -260.920484)
		(end 132.693664 -260.92912)
		(width 0.088646)
		(layer "In11.Cu")
		(net "M_H_CPU1_SA_DQS_DP<4>")
	)
	(segment
		(start 131.768596 -260.920484)
		(end 131.753864 -260.92912)
		(width 0.088646)
		(layer "In11.Cu")
		(net "M_H_CPU1_SA_DQS_DP<4>")
	)
	(segment
		(start 173.024038 -276.790912)
		(end 172.501814 -276.790912)
		(width 0.18288)
		(layer "In11.Cu")
		(net "M_H_CPU1_SA_DQS_DP<4>")
	)
	(segment
		(start 201.681334 -275.065998)
		(end 201.092562 -275.309838)
		(width 0.18288)
		(layer "In11.Cu")
		(net "M_H_CPU1_SA_DQS_DP<4>")
	)
	(segment
		(start 174.025052 -276.531832)
		(end 173.283118 -276.531832)
		(width 0.18288)
		(layer "In11.Cu")
		(net "M_H_CPU1_SA_DQS_DP<4>")
	)
	(segment
		(start 189.740032 -277.357586)
		(end 188.908436 -276.52599)
		(width 0.18288)
		(layer "In11.Cu")
		(net "M_H_CPU1_SA_DQS_DP<4>")
	)
	(segment
		(start 202.321922 -275.227288)
		(end 202.160632 -275.065998)
		(width 0.18288)
		(layer "In11.Cu")
		(net "M_H_CPU1_SA_DQS_DP<4>")
	)
	(segment
		(start 187.315094 -276.516338)
		(end 184.081166 -276.516338)
		(width 0.18288)
		(layer "In11.Cu")
		(net "M_H_CPU1_SA_DQS_DP<4>")
	)
	(segment
		(start 201.092562 -275.309838)
		(end 200.138792 -276.263354)
		(width 0.18288)
		(layer "In11.Cu")
		(net "M_H_CPU1_SA_DQS_DP<4>")
	)
	(segment
		(start 156.524452 -274.568666)
		(end 145.606516 -263.65073)
		(width 0.18288)
		(layer "In11.Cu")
		(net "M_H_CPU1_SA_DQS_DP<4>")
	)
	(segment
		(start 195.063618 -277.114)
		(end 194.688968 -276.73935)
		(width 0.18288)
		(layer "In11.Cu")
		(net "M_H_CPU1_SA_DQS_DP<4>")
	)
	(segment
		(start 179.262024 -276.664166)
		(end 178.799744 -276.664166)
		(width 0.18288)
		(layer "In11.Cu")
		(net "M_H_CPU1_SA_DQS_DP<4>")
	)
	(segment
		(start 191.689736 -277.640796)
		(end 191.406526 -277.357586)
		(width 0.18288)
		(layer "In11.Cu")
		(net "M_H_CPU1_SA_DQS_DP<4>")
	)
	(segment
		(start 138.909298 -262.891016)
		(end 138.909298 -262.872474)
		(width 0.088646)
		(layer "In11.Cu")
		(net "M_H_CPU1_SA_DQS_DP<4>")
	)
	(segment
		(start 178.799744 -276.664166)
		(end 178.06797 -277.39594)
		(width 0.18288)
		(layer "In11.Cu")
		(net "M_H_CPU1_SA_DQS_DP<4>")
	)
	(segment
		(start 177.368708 -277.39594)
		(end 177.123852 -277.640796)
		(width 0.18288)
		(layer "In11.Cu")
		(net "M_H_CPU1_SA_DQS_DP<4>")
	)
	(segment
		(start 191.406526 -277.357586)
		(end 189.740032 -277.357586)
		(width 0.18288)
		(layer "In11.Cu")
		(net "M_H_CPU1_SA_DQS_DP<4>")
	)
	(segment
		(start 137.499344 -262.068564)
		(end 137.499344 -262.058658)
		(width 0.088646)
		(layer "In11.Cu")
		(net "M_H_CPU1_SA_DQS_DP<4>")
	)
	(segment
		(start 138.34745 -262.548116)
		(end 138.337036 -262.554212)
		(width 0.088646)
		(layer "In11.Cu")
		(net "M_H_CPU1_SA_DQS_DP<4>")
	)
	(segment
		(start 188.376306 -276.52599)
		(end 188.111384 -276.790912)
		(width 0.18288)
		(layer "In11.Cu")
		(net "M_H_CPU1_SA_DQS_DP<4>")
	)
	(segment
		(start 188.111384 -276.790912)
		(end 187.589668 -276.790912)
		(width 0.18288)
		(layer "In11.Cu")
		(net "M_H_CPU1_SA_DQS_DP<4>")
	)
	(segment
		(start 163.669726 -276.26945)
		(end 162.780218 -275.379942)
		(width 0.18288)
		(layer "In11.Cu")
		(net "M_H_CPU1_SA_DQS_DP<4>")
	)
	(segment
		(start 123.340622 -260.430772)
		(end 123.027948 -260.430772)
		(width 0.088646)
		(layer "In11.Cu")
		(net "M_H_CPU1_SA_DQS_DP<4>")
	)
	(segment
		(start 198.81469 -276.263354)
		(end 197.964044 -277.114)
		(width 0.18288)
		(layer "In11.Cu")
		(net "M_H_CPU1_SA_DQS_DP<4>")
	)
	(segment
		(start 140.226034 -263.590786)
		(end 140.073126 -263.437878)
		(width 0.088646)
		(layer "In11.Cu")
		(net "M_H_CPU1_SA_DQS_DP<4>")
	)
	(segment
		(start 188.908436 -276.52599)
		(end 188.376306 -276.52599)
		(width 0.18288)
		(layer "In11.Cu")
		(net "M_H_CPU1_SA_DQS_DP<4>")
	)
	(segment
		(start 202.68184 -275.227288)
		(end 202.321922 -275.227288)
		(width 0.18288)
		(layer "In11.Cu")
		(net "M_H_CPU1_SA_DQS_DP<4>")
	)
	(segment
		(start 172.501814 -276.790912)
		(end 172.244004 -276.533102)
		(width 0.18288)
		(layer "In11.Cu")
		(net "M_H_CPU1_SA_DQS_DP<4>")
	)
	(segment
		(start 180.074824 -275.851366)
		(end 179.262024 -276.664166)
		(width 0.18288)
		(layer "In11.Cu")
		(net "M_H_CPU1_SA_DQS_DP<4>")
	)
	(segment
		(start 182.566564 -275.851366)
		(end 180.074824 -275.851366)
		(width 0.18288)
		(layer "In11.Cu")
		(net "M_H_CPU1_SA_DQS_DP<4>")
	)
	(segment
		(start 176.602136 -277.640796)
		(end 176.359566 -277.398226)
		(width 0.18288)
		(layer "In11.Cu")
		(net "M_H_CPU1_SA_DQS_DP<4>")
	)
	(segment
		(start 197.964044 -277.114)
		(end 195.063618 -277.114)
		(width 0.18288)
		(layer "In11.Cu")
		(net "M_H_CPU1_SA_DQS_DP<4>")
	)
	(segment
		(start 128.949196 -260.920484)
		(end 128.934464 -260.92912)
		(width 0.088646)
		(layer "In11.Cu")
		(net "M_H_CPU1_SA_DQS_DP<4>")
	)
	(segment
		(start 125.189996 -260.920484)
		(end 125.175264 -260.92912)
		(width 0.088646)
		(layer "In11.Cu")
		(net "M_H_CPU1_SA_DQS_DP<4>")
	)
	(segment
		(start 187.589668 -276.790912)
		(end 187.315094 -276.516338)
		(width 0.18288)
		(layer "In11.Cu")
		(net "M_H_CPU1_SA_DQS_DP<4>")
	)
	(segment
		(start 164.332666 -276.26945)
		(end 163.669726 -276.26945)
		(width 0.18288)
		(layer "In11.Cu")
		(net "M_H_CPU1_SA_DQS_DP<4>")
	)
	(segment
		(start 126.129796 -260.920484)
		(end 126.115064 -260.92912)
		(width 0.088646)
		(layer "In11.Cu")
		(net "M_H_CPU1_SA_DQS_DP<4>")
	)
	(segment
		(start 175.997616 -277.398226)
		(end 174.520352 -277.027386)
		(width 0.18288)
		(layer "In11.Cu")
		(net "M_H_CPU1_SA_DQS_DP<4>")
	)
	(segment
		(start 134.587996 -260.920484)
		(end 134.573264 -260.92912)
		(width 0.088646)
		(layer "In11.Cu")
		(net "M_H_CPU1_SA_DQS_DP<4>")
	)
	(segment
		(start 140.925804 -263.65073)
		(end 140.86586 -263.590786)
		(width 0.088646)
		(layer "In11.Cu")
		(net "M_H_CPU1_SA_DQS_DP<4>")
	)
	(segment
		(start 193.120772 -277.375366)
		(end 192.476882 -277.375366)
		(width 0.18288)
		(layer "In11.Cu")
		(net "M_H_CPU1_SA_DQS_DP<4>")
	)
	(segment
		(start 168.235376 -275.77161)
		(end 164.830506 -275.77161)
		(width 0.18288)
		(layer "In11.Cu")
		(net "M_H_CPU1_SA_DQS_DP<4>")
	)
	(segment
		(start 192.211452 -277.640796)
		(end 191.689736 -277.640796)
		(width 0.18288)
		(layer "In11.Cu")
		(net "M_H_CPU1_SA_DQS_DP<4>")
	)
	(segment
		(start 174.520352 -277.027386)
		(end 174.025052 -276.531832)
		(width 0.18288)
		(layer "In11.Cu")
		(net "M_H_CPU1_SA_DQS_DP<4>")
	)
	(segment
		(start 137.029444 -261.254748)
		(end 137.029444 -261.244842)
		(width 0.088646)
		(layer "In11.Cu")
		(net "M_H_CPU1_SA_DQS_DP<4>")
	)
	(segment
		(start 194.688968 -276.73935)
		(end 193.756788 -276.73935)
		(width 0.18288)
		(layer "In11.Cu")
		(net "M_H_CPU1_SA_DQS_DP<4>")
	)
	(segment
		(start 124.250196 -260.920484)
		(end 124.235464 -260.92912)
		(width 0.088646)
		(layer "In11.Cu")
		(net "M_H_CPU1_SA_DQS_DP<4>")
	)
	(segment
		(start 145.606516 -263.65073)
		(end 140.925804 -263.65073)
		(width 0.18288)
		(layer "In11.Cu")
		(net "M_H_CPU1_SA_DQS_DP<4>")
	)
	(segment
		(start 128.009396 -260.920484)
		(end 127.994664 -260.92912)
		(width 0.088646)
		(layer "In11.Cu")
		(net "M_H_CPU1_SA_DQS_DP<4>")
	)
	(arc
		(start 125.175264 -260.92912)
		(mid 124.898823 -260.996286)
		(end 124.624592 -260.920484)
		(width 0.088646)
		(layer "In11.Cu")
		(net "M_H_CPU1_SA_DQS_DP<4>")
	)
	(arc
		(start 136.467596 -260.920484)
		(mid 136.184894 -260.996226)
		(end 135.902192 -260.920484)
		(width 0.088646)
		(layer "In11.Cu")
		(net "M_H_CPU1_SA_DQS_DP<4>")
	)
	(arc
		(start 131.753864 -260.92912)
		(mid 131.477423 -260.996286)
		(end 131.203192 -260.920484)
		(width 0.088646)
		(layer "In11.Cu")
		(net "M_H_CPU1_SA_DQS_DP<4>")
	)
	(arc
		(start 132.693664 -260.92912)
		(mid 132.417223 -260.996286)
		(end 132.142992 -260.920484)
		(width 0.088646)
		(layer "In11.Cu")
		(net "M_H_CPU1_SA_DQS_DP<4>")
	)
	(arc
		(start 128.383792 -260.920484)
		(mid 128.196594 -260.870341)
		(end 128.009396 -260.920484)
		(width 0.088646)
		(layer "In11.Cu")
		(net "M_H_CPU1_SA_DQS_DP<4>")
	)
	(arc
		(start 129.874264 -260.92912)
		(mid 129.597823 -260.996286)
		(end 129.323592 -260.920484)
		(width 0.088646)
		(layer "In11.Cu")
		(net "M_H_CPU1_SA_DQS_DP<4>")
	)
	(arc
		(start 130.263392 -260.920484)
		(mid 130.076194 -260.870341)
		(end 129.888996 -260.920484)
		(width 0.088646)
		(layer "In11.Cu")
		(net "M_H_CPU1_SA_DQS_DP<4>")
	)
	(arc
		(start 130.814064 -260.92912)
		(mid 130.537623 -260.996286)
		(end 130.263392 -260.920484)
		(width 0.088646)
		(layer "In11.Cu")
		(net "M_H_CPU1_SA_DQS_DP<4>")
	)
	(arc
		(start 135.902192 -260.920484)
		(mid 135.714994 -260.870341)
		(end 135.527796 -260.920484)
		(width 0.088646)
		(layer "In11.Cu")
		(net "M_H_CPU1_SA_DQS_DP<4>")
	)
	(arc
		(start 128.934464 -260.92912)
		(mid 128.658023 -260.996286)
		(end 128.383792 -260.920484)
		(width 0.088646)
		(layer "In11.Cu")
		(net "M_H_CPU1_SA_DQS_DP<4>")
	)
	(arc
		(start 137.029444 -261.244842)
		(mid 136.842145 -260.920401)
		(end 136.467596 -260.920484)
		(width 0.088646)
		(layer "In11.Cu")
		(net "M_H_CPU1_SA_DQS_DP<4>")
	)
	(arc
		(start 135.527796 -260.920484)
		(mid 135.245094 -260.996226)
		(end 134.962392 -260.920484)
		(width 0.088646)
		(layer "In11.Cu")
		(net "M_H_CPU1_SA_DQS_DP<4>")
	)
	(arc
		(start 137.311892 -261.7343)
		(mid 137.107557 -261.531695)
		(end 137.029444 -261.254748)
		(width 0.088646)
		(layer "In11.Cu")
		(net "M_H_CPU1_SA_DQS_DP<4>")
	)
	(arc
		(start 126.115064 -260.92912)
		(mid 125.838623 -260.996286)
		(end 125.564392 -260.920484)
		(width 0.088646)
		(layer "In11.Cu")
		(net "M_H_CPU1_SA_DQS_DP<4>")
	)
	(arc
		(start 125.564392 -260.920484)
		(mid 125.377194 -260.870341)
		(end 125.189996 -260.920484)
		(width 0.088646)
		(layer "In11.Cu")
		(net "M_H_CPU1_SA_DQS_DP<4>")
	)
	(arc
		(start 127.443992 -260.920484)
		(mid 127.256794 -260.870341)
		(end 127.069596 -260.920484)
		(width 0.088646)
		(layer "In11.Cu")
		(net "M_H_CPU1_SA_DQS_DP<4>")
	)
	(arc
		(start 137.781792 -262.548116)
		(mid 137.577457 -262.345511)
		(end 137.499344 -262.068564)
		(width 0.088646)
		(layer "In11.Cu")
		(net "M_H_CPU1_SA_DQS_DP<4>")
	)
	(arc
		(start 127.069596 -260.920484)
		(mid 126.786894 -260.996226)
		(end 126.504192 -260.920484)
		(width 0.088646)
		(layer "In11.Cu")
		(net "M_H_CPU1_SA_DQS_DP<4>")
	)
	(arc
		(start 127.994664 -260.92912)
		(mid 127.718223 -260.996286)
		(end 127.443992 -260.920484)
		(width 0.088646)
		(layer "In11.Cu")
		(net "M_H_CPU1_SA_DQS_DP<4>")
	)
	(arc
		(start 139.474448 -263.437878)
		(mid 139.081257 -263.278777)
		(end 138.909298 -262.891016)
		(width 0.088646)
		(layer "In11.Cu")
		(net "M_H_CPU1_SA_DQS_DP<4>")
	)
	(arc
		(start 132.142992 -260.920484)
		(mid 131.955794 -260.870341)
		(end 131.768596 -260.920484)
		(width 0.088646)
		(layer "In11.Cu")
		(net "M_H_CPU1_SA_DQS_DP<4>")
	)
	(arc
		(start 123.408694 -260.517386)
		(mid 123.407196 -260.506731)
		(end 123.4059 -260.49605)
		(width 0.088646)
		(layer "In11.Cu")
		(net "M_H_CPU1_SA_DQS_DP<4>")
	)
	(arc
		(start 138.909044 -262.857742)
		(mid 138.715601 -262.54438)
		(end 138.34745 -262.548116)
		(width 0.088646)
		(layer "In11.Cu")
		(net "M_H_CPU1_SA_DQS_DP<4>")
	)
	(arc
		(start 129.323592 -260.920484)
		(mid 129.136394 -260.870341)
		(end 128.949196 -260.920484)
		(width 0.088646)
		(layer "In11.Cu")
		(net "M_H_CPU1_SA_DQS_DP<4>")
	)
	(arc
		(start 124.624592 -260.920484)
		(mid 124.437394 -260.870341)
		(end 124.250196 -260.920484)
		(width 0.088646)
		(layer "In11.Cu")
		(net "M_H_CPU1_SA_DQS_DP<4>")
	)
	(arc
		(start 133.648196 -260.920484)
		(mid 133.365494 -260.996226)
		(end 133.082792 -260.920484)
		(width 0.088646)
		(layer "In11.Cu")
		(net "M_H_CPU1_SA_DQS_DP<4>")
	)
	(arc
		(start 138.909298 -262.872474)
		(mid 138.909246 -262.865107)
		(end 138.909044 -262.857742)
		(width 0.088646)
		(layer "In11.Cu")
		(net "M_H_CPU1_SA_DQS_DP<4>")
	)
	(arc
		(start 134.022592 -260.920484)
		(mid 133.835394 -260.870341)
		(end 133.648196 -260.920484)
		(width 0.088646)
		(layer "In11.Cu")
		(net "M_H_CPU1_SA_DQS_DP<4>")
	)
	(arc
		(start 124.235464 -260.92912)
		(mid 123.71556 -260.937155)
		(end 123.408694 -260.517386)
		(width 0.088646)
		(layer "In11.Cu")
		(net "M_H_CPU1_SA_DQS_DP<4>")
	)
	(arc
		(start 126.504192 -260.920484)
		(mid 126.316994 -260.870341)
		(end 126.129796 -260.920484)
		(width 0.088646)
		(layer "In11.Cu")
		(net "M_H_CPU1_SA_DQS_DP<4>")
	)
	(arc
		(start 134.962392 -260.920484)
		(mid 134.775194 -260.870341)
		(end 134.587996 -260.920484)
		(width 0.088646)
		(layer "In11.Cu")
		(net "M_H_CPU1_SA_DQS_DP<4>")
	)
	(arc
		(start 131.203192 -260.920484)
		(mid 131.015994 -260.870341)
		(end 130.828796 -260.920484)
		(width 0.088646)
		(layer "In11.Cu")
		(net "M_H_CPU1_SA_DQS_DP<4>")
	)
	(arc
		(start 137.499344 -262.058658)
		(mid 137.451665 -261.875758)
		(end 137.320782 -261.73938)
		(width 0.088646)
		(layer "In11.Cu")
		(net "M_H_CPU1_SA_DQS_DP<4>")
	)
	(arc
		(start 133.082792 -260.920484)
		(mid 132.895594 -260.870341)
		(end 132.708396 -260.920484)
		(width 0.088646)
		(layer "In11.Cu")
		(net "M_H_CPU1_SA_DQS_DP<4>")
	)
	(arc
		(start 134.573264 -260.92912)
		(mid 134.296823 -260.996286)
		(end 134.022592 -260.920484)
		(width 0.088646)
		(layer "In11.Cu")
		(net "M_H_CPU1_SA_DQS_DP<4>")
	)
	(arc
		(start 138.337036 -262.554212)
		(mid 138.058604 -262.624026)
		(end 137.781792 -262.548116)
		(width 0.088646)
		(layer "In11.Cu")
		(net "M_H_CPU1_SA_DQS_DP<4>")
	)
	(segment
		(start 206.857854 -285.291784)
		(end 206.9973 -285.291784)
		(width 0.20066)
		(layer "F.Cu")
		(net "M_H_CPU1_SA_DQS_DP<3>")
	)
	(segment
		(start 202.971146 -284.866588)
		(end 204.076046 -284.866588)
		(width 0.20066)
		(layer "F.Cu")
		(net "M_H_CPU1_SA_DQS_DP<3>")
	)
	(segment
		(start 209.18043 -285.291784)
		(end 209.186526 -285.29788)
		(width 0.1016)
		(layer "F.Cu")
		(net "M_H_CPU1_SA_DQS_DP<3>")
	)
	(segment
		(start 205.920848 -285.040578)
		(end 206.606648 -285.040578)
		(width 0.20066)
		(layer "F.Cu")
		(net "M_H_CPU1_SA_DQS_DP<3>")
	)
	(segment
		(start 206.9973 -285.291784)
		(end 207.023208 -285.291784)
		(width 0.101854)
		(layer "F.Cu")
		(net "M_H_CPU1_SA_DQS_DP<3>")
	)
	(segment
		(start 206.606648 -285.040578)
		(end 206.857854 -285.291784)
		(width 0.20066)
		(layer "F.Cu")
		(net "M_H_CPU1_SA_DQS_DP<3>")
	)
	(segment
		(start 123.027694 -265.313922)
		(end 123.027948 -265.314176)
		(width 0.20066)
		(layer "F.Cu")
		(net "M_H_CPU1_SA_DQS_DP<3>")
	)
	(segment
		(start 204.905864 -284.62605)
		(end 205.50632 -284.62605)
		(width 0.20066)
		(layer "F.Cu")
		(net "M_H_CPU1_SA_DQS_DP<3>")
	)
	(segment
		(start 207.023208 -285.291784)
		(end 209.18043 -285.291784)
		(width 0.1016)
		(layer "F.Cu")
		(net "M_H_CPU1_SA_DQS_DP<3>")
	)
	(segment
		(start 210.182968 -284.995366)
		(end 210.593432 -284.584902)
		(width 0.20066)
		(layer "F.Cu")
		(net "M_H_CPU1_SA_DQS_DP<3>")
	)
	(segment
		(start 209.509868 -285.29788)
		(end 209.812382 -284.995366)
		(width 0.20066)
		(layer "F.Cu")
		(net "M_H_CPU1_SA_DQS_DP<3>")
	)
	(segment
		(start 205.50632 -284.62605)
		(end 205.920848 -285.040578)
		(width 0.20066)
		(layer "F.Cu")
		(net "M_H_CPU1_SA_DQS_DP<3>")
	)
	(segment
		(start 204.076046 -284.866588)
		(end 204.665326 -284.866588)
		(width 0.20066)
		(layer "F.Cu")
		(net "M_H_CPU1_SA_DQS_DP<3>")
	)
	(segment
		(start 209.186526 -285.29788)
		(end 209.509868 -285.29788)
		(width 0.20066)
		(layer "F.Cu")
		(net "M_H_CPU1_SA_DQS_DP<3>")
	)
	(segment
		(start 210.593432 -284.584902)
		(end 210.78952 -284.584902)
		(width 0.20066)
		(layer "F.Cu")
		(net "M_H_CPU1_SA_DQS_DP<3>")
	)
	(segment
		(start 209.812382 -284.995366)
		(end 210.182968 -284.995366)
		(width 0.20066)
		(layer "F.Cu")
		(net "M_H_CPU1_SA_DQS_DP<3>")
	)
	(segment
		(start 204.665326 -284.866588)
		(end 204.905864 -284.62605)
		(width 0.20066)
		(layer "F.Cu")
		(net "M_H_CPU1_SA_DQS_DP<3>")
	)
	(segment
		(start 211.071206 -284.866588)
		(end 211.619846 -284.866588)
		(width 0.20066)
		(layer "F.Cu")
		(net "M_H_CPU1_SA_DQS_DP<3>")
	)
	(segment
		(start 123.027694 -264.778236)
		(end 123.027694 -265.313922)
		(width 0.20066)
		(layer "F.Cu")
		(net "M_H_CPU1_SA_DQS_DP<3>")
	)
	(segment
		(start 210.78952 -284.584902)
		(end 211.071206 -284.866588)
		(width 0.20066)
		(layer "F.Cu")
		(net "M_H_CPU1_SA_DQS_DP<3>")
	)
	(segment
		(start 132.708396 -265.803888)
		(end 132.693664 -265.812524)
		(width 0.088646)
		(layer "In11.Cu")
		(net "M_H_CPU1_SA_DQS_DP<3>")
	)
	(segment
		(start 164.499798 -286.401002)
		(end 164.22624 -286.12592)
		(width 0.18288)
		(layer "In11.Cu")
		(net "M_H_CPU1_SA_DQS_DP<3>")
	)
	(segment
		(start 173.288706 -289.276028)
		(end 173.023784 -289.54095)
		(width 0.18288)
		(layer "In11.Cu")
		(net "M_H_CPU1_SA_DQS_DP<3>")
	)
	(segment
		(start 192.47231 -288.429954)
		(end 192.211452 -288.690812)
		(width 0.18288)
		(layer "In11.Cu")
		(net "M_H_CPU1_SA_DQS_DP<3>")
	)
	(segment
		(start 133.740144 -266.956032)
		(end 133.740144 -266.941808)
		(width 0.088646)
		(layer "In11.Cu")
		(net "M_H_CPU1_SA_DQS_DP<3>")
	)
	(segment
		(start 175.574198 -288.407602)
		(end 174.702724 -288.768536)
		(width 0.18288)
		(layer "In11.Cu")
		(net "M_H_CPU1_SA_DQS_DP<3>")
	)
	(segment
		(start 173.023784 -289.54095)
		(end 172.502068 -289.54095)
		(width 0.18288)
		(layer "In11.Cu")
		(net "M_H_CPU1_SA_DQS_DP<3>")
	)
	(segment
		(start 178.761644 -287.55975)
		(end 177.888138 -288.433256)
		(width 0.18288)
		(layer "In11.Cu")
		(net "M_H_CPU1_SA_DQS_DP<3>")
	)
	(segment
		(start 177.888138 -288.433256)
		(end 177.381408 -288.433256)
		(width 0.18288)
		(layer "In11.Cu")
		(net "M_H_CPU1_SA_DQS_DP<3>")
	)
	(segment
		(start 166.427912 -286.67964)
		(end 166.149274 -286.401002)
		(width 0.18288)
		(layer "In11.Cu")
		(net "M_H_CPU1_SA_DQS_DP<3>")
	)
	(segment
		(start 187.34532 -287.59658)
		(end 184.4294 -287.59658)
		(width 0.18288)
		(layer "In11.Cu")
		(net "M_H_CPU1_SA_DQS_DP<3>")
	)
	(segment
		(start 133.561582 -266.62253)
		(end 133.555994 -266.619482)
		(width 0.088646)
		(layer "In11.Cu")
		(net "M_H_CPU1_SA_DQS_DP<3>")
	)
	(segment
		(start 139.403074 -269.46733)
		(end 139.20724 -269.271496)
		(width 0.088646)
		(layer "In11.Cu")
		(net "M_H_CPU1_SA_DQS_DP<3>")
	)
	(segment
		(start 190.731902 -288.15919)
		(end 189.70117 -288.15919)
		(width 0.18288)
		(layer "In11.Cu")
		(net "M_H_CPU1_SA_DQS_DP<3>")
	)
	(segment
		(start 125.189996 -265.803888)
		(end 125.175264 -265.812524)
		(width 0.088646)
		(layer "In11.Cu")
		(net "M_H_CPU1_SA_DQS_DP<3>")
	)
	(segment
		(start 142.90167 -269.748)
		(end 140.696188 -269.748)
		(width 0.18288)
		(layer "In11.Cu")
		(net "M_H_CPU1_SA_DQS_DP<3>")
	)
	(segment
		(start 138.721338 -269.058898)
		(end 138.714988 -269.055088)
		(width 0.088646)
		(layer "In11.Cu")
		(net "M_H_CPU1_SA_DQS_DP<3>")
	)
	(segment
		(start 167.943276 -286.67964)
		(end 166.427912 -286.67964)
		(width 0.18288)
		(layer "In11.Cu")
		(net "M_H_CPU1_SA_DQS_DP<3>")
	)
	(segment
		(start 126.129796 -265.803888)
		(end 126.115064 -265.812524)
		(width 0.088646)
		(layer "In11.Cu")
		(net "M_H_CPU1_SA_DQS_DP<3>")
	)
	(segment
		(start 134.023608 -267.432028)
		(end 134.022592 -267.43152)
		(width 0.088646)
		(layer "In11.Cu")
		(net "M_H_CPU1_SA_DQS_DP<3>")
	)
	(segment
		(start 138.933936 -269.271496)
		(end 138.721338 -269.058898)
		(width 0.088646)
		(layer "In11.Cu")
		(net "M_H_CPU1_SA_DQS_DP<3>")
	)
	(segment
		(start 128.009396 -265.803888)
		(end 127.994664 -265.812524)
		(width 0.088646)
		(layer "In11.Cu")
		(net "M_H_CPU1_SA_DQS_DP<3>")
	)
	(segment
		(start 164.22624 -286.12592)
		(end 161.72053 -286.12592)
		(width 0.18288)
		(layer "In11.Cu")
		(net "M_H_CPU1_SA_DQS_DP<3>")
	)
	(segment
		(start 200.300336 -285.625032)
		(end 199.805036 -285.625032)
		(width 0.18288)
		(layer "In11.Cu")
		(net "M_H_CPU1_SA_DQS_DP<3>")
	)
	(segment
		(start 159.613346 -284.018736)
		(end 157.172406 -284.018736)
		(width 0.18288)
		(layer "In11.Cu")
		(net "M_H_CPU1_SA_DQS_DP<3>")
	)
	(segment
		(start 170.586654 -288.44621)
		(end 167.943276 -286.67964)
		(width 0.18288)
		(layer "In11.Cu")
		(net "M_H_CPU1_SA_DQS_DP<3>")
	)
	(segment
		(start 177.381408 -288.433256)
		(end 177.123852 -288.690812)
		(width 0.18288)
		(layer "In11.Cu")
		(net "M_H_CPU1_SA_DQS_DP<3>")
	)
	(segment
		(start 187.589668 -287.840928)
		(end 187.34532 -287.59658)
		(width 0.18288)
		(layer "In11.Cu")
		(net "M_H_CPU1_SA_DQS_DP<3>")
	)
	(segment
		(start 129.888996 -265.803888)
		(end 129.874264 -265.812524)
		(width 0.088646)
		(layer "In11.Cu")
		(net "M_H_CPU1_SA_DQS_DP<3>")
	)
	(segment
		(start 176.60874 -288.690812)
		(end 176.32553 -288.407602)
		(width 0.18288)
		(layer "In11.Cu")
		(net "M_H_CPU1_SA_DQS_DP<3>")
	)
	(segment
		(start 134.031482 -267.4366)
		(end 134.023608 -267.432028)
		(width 0.088646)
		(layer "In11.Cu")
		(net "M_H_CPU1_SA_DQS_DP<3>")
	)
	(segment
		(start 140.191744 -269.688056)
		(end 139.971018 -269.46733)
		(width 0.088646)
		(layer "In11.Cu")
		(net "M_H_CPU1_SA_DQS_DP<3>")
	)
	(segment
		(start 139.20724 -269.271496)
		(end 138.933936 -269.271496)
		(width 0.088646)
		(layer "In11.Cu")
		(net "M_H_CPU1_SA_DQS_DP<3>")
	)
	(segment
		(start 140.636244 -269.688056)
		(end 140.191744 -269.688056)
		(width 0.088646)
		(layer "In11.Cu")
		(net "M_H_CPU1_SA_DQS_DP<3>")
	)
	(segment
		(start 171.398184 -289.25774)
		(end 170.586654 -288.44621)
		(width 0.18288)
		(layer "In11.Cu")
		(net "M_H_CPU1_SA_DQS_DP<3>")
	)
	(segment
		(start 193.674492 -287.938464)
		(end 193.182748 -288.429954)
		(width 0.18288)
		(layer "In11.Cu")
		(net "M_H_CPU1_SA_DQS_DP<3>")
	)
	(segment
		(start 180.196236 -286.96539)
		(end 178.761644 -287.55975)
		(width 0.18288)
		(layer "In11.Cu")
		(net "M_H_CPU1_SA_DQS_DP<3>")
	)
	(segment
		(start 133.270498 -266.138152)
		(end 133.270244 -266.128246)
		(width 0.088646)
		(layer "In11.Cu")
		(net "M_H_CPU1_SA_DQS_DP<3>")
	)
	(segment
		(start 134.680198 -268.585188)
		(end 134.680198 -268.569694)
		(width 0.088646)
		(layer "In11.Cu")
		(net "M_H_CPU1_SA_DQS_DP<3>")
	)
	(segment
		(start 166.149274 -286.401002)
		(end 164.499798 -286.401002)
		(width 0.18288)
		(layer "In11.Cu")
		(net "M_H_CPU1_SA_DQS_DP<3>")
	)
	(segment
		(start 140.696188 -269.748)
		(end 140.636244 -269.688056)
		(width 0.088646)
		(layer "In11.Cu")
		(net "M_H_CPU1_SA_DQS_DP<3>")
	)
	(segment
		(start 202.12431 -284.61208)
		(end 201.937112 -284.424882)
		(width 0.18288)
		(layer "In11.Cu")
		(net "M_H_CPU1_SA_DQS_DP<3>")
	)
	(segment
		(start 131.768596 -265.803888)
		(end 131.753864 -265.812524)
		(width 0.088646)
		(layer "In11.Cu")
		(net "M_H_CPU1_SA_DQS_DP<3>")
	)
	(segment
		(start 182.9054 -286.96539)
		(end 180.196236 -286.96539)
		(width 0.18288)
		(layer "In11.Cu")
		(net "M_H_CPU1_SA_DQS_DP<3>")
	)
	(segment
		(start 189.109858 -287.567878)
		(end 188.384434 -287.567878)
		(width 0.18288)
		(layer "In11.Cu")
		(net "M_H_CPU1_SA_DQS_DP<3>")
	)
	(segment
		(start 161.72053 -286.12592)
		(end 159.613346 -284.018736)
		(width 0.18288)
		(layer "In11.Cu")
		(net "M_H_CPU1_SA_DQS_DP<3>")
	)
	(segment
		(start 124.250196 -265.803888)
		(end 124.235464 -265.812524)
		(width 0.088646)
		(layer "In11.Cu")
		(net "M_H_CPU1_SA_DQS_DP<3>")
	)
	(segment
		(start 172.502068 -289.54095)
		(end 172.218858 -289.25774)
		(width 0.18288)
		(layer "In11.Cu")
		(net "M_H_CPU1_SA_DQS_DP<3>")
	)
	(segment
		(start 174.404782 -289.066986)
		(end 173.89983 -289.276028)
		(width 0.18288)
		(layer "In11.Cu")
		(net "M_H_CPU1_SA_DQS_DP<3>")
	)
	(segment
		(start 189.70117 -288.15919)
		(end 189.109858 -287.567878)
		(width 0.18288)
		(layer "In11.Cu")
		(net "M_H_CPU1_SA_DQS_DP<3>")
	)
	(segment
		(start 172.218858 -289.25774)
		(end 171.398184 -289.25774)
		(width 0.18288)
		(layer "In11.Cu")
		(net "M_H_CPU1_SA_DQS_DP<3>")
	)
	(segment
		(start 201.500486 -284.424882)
		(end 200.300336 -285.625032)
		(width 0.18288)
		(layer "In11.Cu")
		(net "M_H_CPU1_SA_DQS_DP<3>")
	)
	(segment
		(start 184.4294 -287.59658)
		(end 182.9054 -286.96539)
		(width 0.18288)
		(layer "In11.Cu")
		(net "M_H_CPU1_SA_DQS_DP<3>")
	)
	(segment
		(start 191.689736 -288.690812)
		(end 191.443864 -288.44494)
		(width 0.18288)
		(layer "In11.Cu")
		(net "M_H_CPU1_SA_DQS_DP<3>")
	)
	(segment
		(start 197.28942 -286.667448)
		(end 196.097652 -286.667448)
		(width 0.18288)
		(layer "In11.Cu")
		(net "M_H_CPU1_SA_DQS_DP<3>")
	)
	(segment
		(start 176.32553 -288.407602)
		(end 175.574198 -288.407602)
		(width 0.18288)
		(layer "In11.Cu")
		(net "M_H_CPU1_SA_DQS_DP<3>")
	)
	(segment
		(start 123.340876 -265.314176)
		(end 123.027948 -265.314176)
		(width 0.088646)
		(layer "In11.Cu")
		(net "M_H_CPU1_SA_DQS_DP<3>")
	)
	(segment
		(start 138.714988 -269.055088)
		(end 138.7094 -269.052294)
		(width 0.088646)
		(layer "In11.Cu")
		(net "M_H_CPU1_SA_DQS_DP<3>")
	)
	(segment
		(start 130.828796 -265.803888)
		(end 130.814064 -265.812524)
		(width 0.088646)
		(layer "In11.Cu")
		(net "M_H_CPU1_SA_DQS_DP<3>")
	)
	(segment
		(start 201.937112 -284.424882)
		(end 201.500486 -284.424882)
		(width 0.18288)
		(layer "In11.Cu")
		(net "M_H_CPU1_SA_DQS_DP<3>")
	)
	(segment
		(start 128.949196 -265.803888)
		(end 128.934464 -265.812524)
		(width 0.088646)
		(layer "In11.Cu")
		(net "M_H_CPU1_SA_DQS_DP<3>")
	)
	(segment
		(start 133.553454 -266.617958)
		(end 133.552692 -266.61745)
		(width 0.088646)
		(layer "In11.Cu")
		(net "M_H_CPU1_SA_DQS_DP<3>")
	)
	(segment
		(start 199.805036 -285.625032)
		(end 197.28942 -286.667448)
		(width 0.18288)
		(layer "In11.Cu")
		(net "M_H_CPU1_SA_DQS_DP<3>")
	)
	(segment
		(start 139.971018 -269.46733)
		(end 139.403074 -269.46733)
		(width 0.088646)
		(layer "In11.Cu")
		(net "M_H_CPU1_SA_DQS_DP<3>")
	)
	(segment
		(start 173.89983 -289.276028)
		(end 173.288706 -289.276028)
		(width 0.18288)
		(layer "In11.Cu")
		(net "M_H_CPU1_SA_DQS_DP<3>")
	)
	(segment
		(start 191.443864 -288.44494)
		(end 191.017652 -288.44494)
		(width 0.18288)
		(layer "In11.Cu")
		(net "M_H_CPU1_SA_DQS_DP<3>")
	)
	(segment
		(start 191.017652 -288.44494)
		(end 190.731902 -288.15919)
		(width 0.18288)
		(layer "In11.Cu")
		(net "M_H_CPU1_SA_DQS_DP<3>")
	)
	(segment
		(start 202.971146 -284.866588)
		(end 202.716638 -284.61208)
		(width 0.18288)
		(layer "In11.Cu")
		(net "M_H_CPU1_SA_DQS_DP<3>")
	)
	(segment
		(start 193.182748 -288.429954)
		(end 192.47231 -288.429954)
		(width 0.18288)
		(layer "In11.Cu")
		(net "M_H_CPU1_SA_DQS_DP<3>")
	)
	(segment
		(start 135.527796 -269.059152)
		(end 135.513064 -269.067788)
		(width 0.088646)
		(layer "In11.Cu")
		(net "M_H_CPU1_SA_DQS_DP<3>")
	)
	(segment
		(start 196.097652 -286.667448)
		(end 194.952874 -287.141666)
		(width 0.18288)
		(layer "In11.Cu")
		(net "M_H_CPU1_SA_DQS_DP<3>")
	)
	(segment
		(start 188.384434 -287.567878)
		(end 188.111384 -287.840928)
		(width 0.18288)
		(layer "In11.Cu")
		(net "M_H_CPU1_SA_DQS_DP<3>")
	)
	(segment
		(start 194.496944 -287.597596)
		(end 193.674492 -287.938464)
		(width 0.18288)
		(layer "In11.Cu")
		(net "M_H_CPU1_SA_DQS_DP<3>")
	)
	(segment
		(start 134.501636 -268.250416)
		(end 134.48665 -268.24178)
		(width 0.088646)
		(layer "In11.Cu")
		(net "M_H_CPU1_SA_DQS_DP<3>")
	)
	(segment
		(start 137.79627 -269.067788)
		(end 137.773156 -269.054326)
		(width 0.088646)
		(layer "In11.Cu")
		(net "M_H_CPU1_SA_DQS_DP<3>")
	)
	(segment
		(start 188.111384 -287.840928)
		(end 187.589668 -287.840928)
		(width 0.18288)
		(layer "In11.Cu")
		(net "M_H_CPU1_SA_DQS_DP<3>")
	)
	(segment
		(start 192.211452 -288.690812)
		(end 191.689736 -288.690812)
		(width 0.18288)
		(layer "In11.Cu")
		(net "M_H_CPU1_SA_DQS_DP<3>")
	)
	(segment
		(start 202.716638 -284.61208)
		(end 202.12431 -284.61208)
		(width 0.18288)
		(layer "In11.Cu")
		(net "M_H_CPU1_SA_DQS_DP<3>")
	)
	(segment
		(start 194.952874 -287.141666)
		(end 194.496944 -287.597596)
		(width 0.18288)
		(layer "In11.Cu")
		(net "M_H_CPU1_SA_DQS_DP<3>")
	)
	(segment
		(start 133.555994 -266.619482)
		(end 133.553454 -266.617958)
		(width 0.088646)
		(layer "In11.Cu")
		(net "M_H_CPU1_SA_DQS_DP<3>")
	)
	(segment
		(start 123.4059 -265.3792)
		(end 123.340876 -265.314176)
		(width 0.088646)
		(layer "In11.Cu")
		(net "M_H_CPU1_SA_DQS_DP<3>")
	)
	(segment
		(start 174.702724 -288.768536)
		(end 174.404782 -289.066986)
		(width 0.18288)
		(layer "In11.Cu")
		(net "M_H_CPU1_SA_DQS_DP<3>")
	)
	(segment
		(start 177.123852 -288.690812)
		(end 176.60874 -288.690812)
		(width 0.18288)
		(layer "In11.Cu")
		(net "M_H_CPU1_SA_DQS_DP<3>")
	)
	(segment
		(start 157.172406 -284.018736)
		(end 142.90167 -269.748)
		(width 0.18288)
		(layer "In11.Cu")
		(net "M_H_CPU1_SA_DQS_DP<3>")
	)
	(arc
		(start 132.693664 -265.812524)
		(mid 132.417223 -265.87969)
		(end 132.142992 -265.803888)
		(width 0.088646)
		(layer "In11.Cu")
		(net "M_H_CPU1_SA_DQS_DP<3>")
	)
	(arc
		(start 134.680198 -268.569694)
		(mid 134.632519 -268.386794)
		(end 134.501636 -268.250416)
		(width 0.088646)
		(layer "In11.Cu")
		(net "M_H_CPU1_SA_DQS_DP<3>")
	)
	(arc
		(start 138.346942 -269.059152)
		(mid 138.072743 -269.134987)
		(end 137.79627 -269.067788)
		(width 0.088646)
		(layer "In11.Cu")
		(net "M_H_CPU1_SA_DQS_DP<3>")
	)
	(arc
		(start 127.069596 -265.803888)
		(mid 126.786894 -265.87963)
		(end 126.504192 -265.803888)
		(width 0.088646)
		(layer "In11.Cu")
		(net "M_H_CPU1_SA_DQS_DP<3>")
	)
	(arc
		(start 136.841992 -269.059152)
		(mid 136.654794 -269.009009)
		(end 136.467596 -269.059152)
		(width 0.088646)
		(layer "In11.Cu")
		(net "M_H_CPU1_SA_DQS_DP<3>")
	)
	(arc
		(start 130.814064 -265.812524)
		(mid 130.537623 -265.87969)
		(end 130.263392 -265.803888)
		(width 0.088646)
		(layer "In11.Cu")
		(net "M_H_CPU1_SA_DQS_DP<3>")
	)
	(arc
		(start 129.874264 -265.812524)
		(mid 129.597823 -265.87969)
		(end 129.323592 -265.803888)
		(width 0.088646)
		(layer "In11.Cu")
		(net "M_H_CPU1_SA_DQS_DP<3>")
	)
	(arc
		(start 128.383792 -265.803888)
		(mid 128.196594 -265.753745)
		(end 128.009396 -265.803888)
		(width 0.088646)
		(layer "In11.Cu")
		(net "M_H_CPU1_SA_DQS_DP<3>")
	)
	(arc
		(start 134.20979 -267.741146)
		(mid 134.158736 -267.566566)
		(end 134.031482 -267.4366)
		(width 0.088646)
		(layer "In11.Cu")
		(net "M_H_CPU1_SA_DQS_DP<3>")
	)
	(arc
		(start 129.323592 -265.803888)
		(mid 129.136394 -265.753745)
		(end 128.949196 -265.803888)
		(width 0.088646)
		(layer "In11.Cu")
		(net "M_H_CPU1_SA_DQS_DP<3>")
	)
	(arc
		(start 134.210044 -267.755878)
		(mid 134.209992 -267.748511)
		(end 134.20979 -267.741146)
		(width 0.088646)
		(layer "In11.Cu")
		(net "M_H_CPU1_SA_DQS_DP<3>")
	)
	(arc
		(start 133.552692 -266.61745)
		(mid 133.348603 -266.414903)
		(end 133.270498 -266.138152)
		(width 0.088646)
		(layer "In11.Cu")
		(net "M_H_CPU1_SA_DQS_DP<3>")
	)
	(arc
		(start 136.467596 -269.059152)
		(mid 136.184894 -269.134928)
		(end 135.902192 -269.059152)
		(width 0.088646)
		(layer "In11.Cu")
		(net "M_H_CPU1_SA_DQS_DP<3>")
	)
	(arc
		(start 134.022592 -267.43152)
		(mid 133.819287 -267.230654)
		(end 133.740144 -266.956032)
		(width 0.088646)
		(layer "In11.Cu")
		(net "M_H_CPU1_SA_DQS_DP<3>")
	)
	(arc
		(start 128.934464 -265.812524)
		(mid 128.658023 -265.87969)
		(end 128.383792 -265.803888)
		(width 0.088646)
		(layer "In11.Cu")
		(net "M_H_CPU1_SA_DQS_DP<3>")
	)
	(arc
		(start 127.443992 -265.803888)
		(mid 127.256794 -265.753745)
		(end 127.069596 -265.803888)
		(width 0.088646)
		(layer "In11.Cu")
		(net "M_H_CPU1_SA_DQS_DP<3>")
	)
	(arc
		(start 138.7094 -269.052294)
		(mid 138.527289 -269.008969)
		(end 138.346942 -269.059152)
		(width 0.088646)
		(layer "In11.Cu")
		(net "M_H_CPU1_SA_DQS_DP<3>")
	)
	(arc
		(start 126.115064 -265.812524)
		(mid 125.838623 -265.87969)
		(end 125.564392 -265.803888)
		(width 0.088646)
		(layer "In11.Cu")
		(net "M_H_CPU1_SA_DQS_DP<3>")
	)
	(arc
		(start 130.263392 -265.803888)
		(mid 130.076194 -265.753745)
		(end 129.888996 -265.803888)
		(width 0.088646)
		(layer "In11.Cu")
		(net "M_H_CPU1_SA_DQS_DP<3>")
	)
	(arc
		(start 126.504192 -265.803888)
		(mid 126.316994 -265.753745)
		(end 126.129796 -265.803888)
		(width 0.088646)
		(layer "In11.Cu")
		(net "M_H_CPU1_SA_DQS_DP<3>")
	)
	(arc
		(start 125.564392 -265.803888)
		(mid 125.377194 -265.753745)
		(end 125.189996 -265.803888)
		(width 0.088646)
		(layer "In11.Cu")
		(net "M_H_CPU1_SA_DQS_DP<3>")
	)
	(arc
		(start 133.270244 -266.128246)
		(mid 133.082945 -265.803805)
		(end 132.708396 -265.803888)
		(width 0.088646)
		(layer "In11.Cu")
		(net "M_H_CPU1_SA_DQS_DP<3>")
	)
	(arc
		(start 131.203192 -265.803888)
		(mid 131.015994 -265.753745)
		(end 130.828796 -265.803888)
		(width 0.088646)
		(layer "In11.Cu")
		(net "M_H_CPU1_SA_DQS_DP<3>")
	)
	(arc
		(start 137.773156 -269.054326)
		(mid 137.589648 -269.009048)
		(end 137.407396 -269.059152)
		(width 0.088646)
		(layer "In11.Cu")
		(net "M_H_CPU1_SA_DQS_DP<3>")
	)
	(arc
		(start 135.902192 -269.059152)
		(mid 135.714994 -269.009009)
		(end 135.527796 -269.059152)
		(width 0.088646)
		(layer "In11.Cu")
		(net "M_H_CPU1_SA_DQS_DP<3>")
	)
	(arc
		(start 137.407396 -269.059152)
		(mid 137.124694 -269.134928)
		(end 136.841992 -269.059152)
		(width 0.088646)
		(layer "In11.Cu")
		(net "M_H_CPU1_SA_DQS_DP<3>")
	)
	(arc
		(start 123.408694 -265.400536)
		(mid 123.407196 -265.389881)
		(end 123.4059 -265.3792)
		(width 0.088646)
		(layer "In11.Cu")
		(net "M_H_CPU1_SA_DQS_DP<3>")
	)
	(arc
		(start 132.142992 -265.803888)
		(mid 131.955794 -265.753745)
		(end 131.768596 -265.803888)
		(width 0.088646)
		(layer "In11.Cu")
		(net "M_H_CPU1_SA_DQS_DP<3>")
	)
	(arc
		(start 124.624592 -265.803888)
		(mid 124.437394 -265.753745)
		(end 124.250196 -265.803888)
		(width 0.088646)
		(layer "In11.Cu")
		(net "M_H_CPU1_SA_DQS_DP<3>")
	)
	(arc
		(start 133.740144 -266.941808)
		(mid 133.692465 -266.758908)
		(end 133.561582 -266.62253)
		(width 0.088646)
		(layer "In11.Cu")
		(net "M_H_CPU1_SA_DQS_DP<3>")
	)
	(arc
		(start 134.48665 -268.24178)
		(mid 134.284063 -268.035429)
		(end 134.210044 -267.755878)
		(width 0.088646)
		(layer "In11.Cu")
		(net "M_H_CPU1_SA_DQS_DP<3>")
	)
	(arc
		(start 127.994664 -265.812524)
		(mid 127.718223 -265.87969)
		(end 127.443992 -265.803888)
		(width 0.088646)
		(layer "In11.Cu")
		(net "M_H_CPU1_SA_DQS_DP<3>")
	)
	(arc
		(start 125.175264 -265.812524)
		(mid 124.898823 -265.87969)
		(end 124.624592 -265.803888)
		(width 0.088646)
		(layer "In11.Cu")
		(net "M_H_CPU1_SA_DQS_DP<3>")
	)
	(arc
		(start 124.235464 -265.812524)
		(mid 123.715448 -265.820503)
		(end 123.408694 -265.400536)
		(width 0.088646)
		(layer "In11.Cu")
		(net "M_H_CPU1_SA_DQS_DP<3>")
	)
	(arc
		(start 135.513064 -269.067788)
		(mid 134.961871 -269.05899)
		(end 134.680198 -268.585188)
		(width 0.088646)
		(layer "In11.Cu")
		(net "M_H_CPU1_SA_DQS_DP<3>")
	)
	(arc
		(start 131.753864 -265.812524)
		(mid 131.477423 -265.87969)
		(end 131.203192 -265.803888)
		(width 0.088646)
		(layer "In11.Cu")
		(net "M_H_CPU1_SA_DQS_DP<3>")
	)
	(segment
		(start 210.182968 -294.34536)
		(end 210.593432 -293.934896)
		(width 0.20066)
		(layer "F.Cu")
		(net "M_H_CPU1_SA_DQS_DP<2>")
	)
	(segment
		(start 206.606648 -294.390572)
		(end 206.857854 -294.641778)
		(width 0.20066)
		(layer "F.Cu")
		(net "M_H_CPU1_SA_DQS_DP<2>")
	)
	(segment
		(start 123.027694 -269.66164)
		(end 123.027948 -270.167862)
		(width 0.20066)
		(layer "F.Cu")
		(net "M_H_CPU1_SA_DQS_DP<2>")
	)
	(segment
		(start 211.071206 -294.216582)
		(end 211.619846 -294.216582)
		(width 0.20066)
		(layer "F.Cu")
		(net "M_H_CPU1_SA_DQS_DP<2>")
	)
	(segment
		(start 205.920848 -294.390572)
		(end 206.606648 -294.390572)
		(width 0.20066)
		(layer "F.Cu")
		(net "M_H_CPU1_SA_DQS_DP<2>")
	)
	(segment
		(start 209.18043 -294.641778)
		(end 209.186526 -294.647874)
		(width 0.1016)
		(layer "F.Cu")
		(net "M_H_CPU1_SA_DQS_DP<2>")
	)
	(segment
		(start 206.857854 -294.641778)
		(end 206.9973 -294.641778)
		(width 0.20066)
		(layer "F.Cu")
		(net "M_H_CPU1_SA_DQS_DP<2>")
	)
	(segment
		(start 204.076046 -294.216582)
		(end 204.665326 -294.216582)
		(width 0.20066)
		(layer "F.Cu")
		(net "M_H_CPU1_SA_DQS_DP<2>")
	)
	(segment
		(start 207.023208 -294.641778)
		(end 209.18043 -294.641778)
		(width 0.1016)
		(layer "F.Cu")
		(net "M_H_CPU1_SA_DQS_DP<2>")
	)
	(segment
		(start 206.9973 -294.641778)
		(end 207.023208 -294.641778)
		(width 0.101854)
		(layer "F.Cu")
		(net "M_H_CPU1_SA_DQS_DP<2>")
	)
	(segment
		(start 209.509868 -294.647874)
		(end 209.812382 -294.34536)
		(width 0.20066)
		(layer "F.Cu")
		(net "M_H_CPU1_SA_DQS_DP<2>")
	)
	(segment
		(start 210.78952 -293.934896)
		(end 211.071206 -294.216582)
		(width 0.20066)
		(layer "F.Cu")
		(net "M_H_CPU1_SA_DQS_DP<2>")
	)
	(segment
		(start 209.186526 -294.647874)
		(end 209.509868 -294.647874)
		(width 0.20066)
		(layer "F.Cu")
		(net "M_H_CPU1_SA_DQS_DP<2>")
	)
	(segment
		(start 209.812382 -294.34536)
		(end 210.182968 -294.34536)
		(width 0.20066)
		(layer "F.Cu")
		(net "M_H_CPU1_SA_DQS_DP<2>")
	)
	(segment
		(start 205.50632 -293.976044)
		(end 205.920848 -294.390572)
		(width 0.20066)
		(layer "F.Cu")
		(net "M_H_CPU1_SA_DQS_DP<2>")
	)
	(segment
		(start 210.593432 -293.934896)
		(end 210.78952 -293.934896)
		(width 0.20066)
		(layer "F.Cu")
		(net "M_H_CPU1_SA_DQS_DP<2>")
	)
	(segment
		(start 204.665326 -294.216582)
		(end 204.905864 -293.976044)
		(width 0.20066)
		(layer "F.Cu")
		(net "M_H_CPU1_SA_DQS_DP<2>")
	)
	(segment
		(start 202.971146 -294.216582)
		(end 204.076046 -294.216582)
		(width 0.20066)
		(layer "F.Cu")
		(net "M_H_CPU1_SA_DQS_DP<2>")
	)
	(segment
		(start 204.905864 -293.976044)
		(end 205.50632 -293.976044)
		(width 0.20066)
		(layer "F.Cu")
		(net "M_H_CPU1_SA_DQS_DP<2>")
	)
	(segment
		(start 123.027948 -270.167862)
		(end 123.027948 -270.19758)
		(width 0.20066)
		(layer "F.Cu")
		(net "M_H_CPU1_SA_DQS_DP<2>")
	)
	(segment
		(start 128.392682 -270.692118)
		(end 128.383792 -270.687038)
		(width 0.088646)
		(layer "In11.Cu")
		(net "M_H_CPU1_SA_DQS_DP<2>")
	)
	(segment
		(start 178.835812 -298.808648)
		(end 178.168554 -299.475906)
		(width 0.18288)
		(layer "In11.Cu")
		(net "M_H_CPU1_SA_DQS_DP<2>")
	)
	(segment
		(start 194.677792 -298.431966)
		(end 194.202558 -298.431966)
		(width 0.18288)
		(layer "In11.Cu")
		(net "M_H_CPU1_SA_DQS_DP<2>")
	)
	(segment
		(start 174.833534 -299.457618)
		(end 173.972982 -300.31817)
		(width 0.18288)
		(layer "In11.Cu")
		(net "M_H_CPU1_SA_DQS_DP<2>")
	)
	(segment
		(start 129.79527 -271.501616)
		(end 129.793746 -271.500854)
		(width 0.088646)
		(layer "In11.Cu")
		(net "M_H_CPU1_SA_DQS_DP<2>")
	)
	(segment
		(start 168.553384 -298.435268)
		(end 167.902128 -297.784012)
		(width 0.18288)
		(layer "In11.Cu")
		(net "M_H_CPU1_SA_DQS_DP<2>")
	)
	(segment
		(start 130.920998 -273.468592)
		(end 130.920998 -273.453098)
		(width 0.088646)
		(layer "In11.Cu")
		(net "M_H_CPU1_SA_DQS_DP<2>")
	)
	(segment
		(start 184.113932 -298.630848)
		(end 183.244998 -297.761914)
		(width 0.18288)
		(layer "In11.Cu")
		(net "M_H_CPU1_SA_DQS_DP<2>")
	)
	(segment
		(start 197.360032 -296.114216)
		(end 195.956682 -297.517566)
		(width 0.18288)
		(layer "In11.Cu")
		(net "M_H_CPU1_SA_DQS_DP<2>")
	)
	(segment
		(start 195.592192 -297.517566)
		(end 194.677792 -298.431966)
		(width 0.18288)
		(layer "In11.Cu")
		(net "M_H_CPU1_SA_DQS_DP<2>")
	)
	(segment
		(start 188.111384 -298.890944)
		(end 187.589668 -298.890944)
		(width 0.18288)
		(layer "In11.Cu")
		(net "M_H_CPU1_SA_DQS_DP<2>")
	)
	(segment
		(start 130.272282 -272.320004)
		(end 130.263392 -272.314924)
		(width 0.088646)
		(layer "In11.Cu")
		(net "M_H_CPU1_SA_DQS_DP<2>")
	)
	(segment
		(start 135.527796 -273.942556)
		(end 135.513064 -273.951192)
		(width 0.088646)
		(layer "In11.Cu")
		(net "M_H_CPU1_SA_DQS_DP<2>")
	)
	(segment
		(start 173.25975 -300.31817)
		(end 172.986446 -300.591474)
		(width 0.18288)
		(layer "In11.Cu")
		(net "M_H_CPU1_SA_DQS_DP<2>")
	)
	(segment
		(start 189.111128 -298.626022)
		(end 188.376306 -298.626022)
		(width 0.18288)
		(layer "In11.Cu")
		(net "M_H_CPU1_SA_DQS_DP<2>")
	)
	(segment
		(start 165.188392 -297.784012)
		(end 164.06622 -296.66184)
		(width 0.18288)
		(layer "In11.Cu")
		(net "M_H_CPU1_SA_DQS_DP<2>")
	)
	(segment
		(start 176.602136 -299.740828)
		(end 176.318926 -299.457618)
		(width 0.18288)
		(layer "In11.Cu")
		(net "M_H_CPU1_SA_DQS_DP<2>")
	)
	(segment
		(start 183.244998 -297.761914)
		(end 182.148226 -297.761914)
		(width 0.18288)
		(layer "In11.Cu")
		(net "M_H_CPU1_SA_DQS_DP<2>")
	)
	(segment
		(start 192.467484 -299.488352)
		(end 192.215008 -299.740828)
		(width 0.18288)
		(layer "In11.Cu")
		(net "M_H_CPU1_SA_DQS_DP<2>")
	)
	(segment
		(start 128.009396 -270.687038)
		(end 127.994664 -270.695674)
		(width 0.088646)
		(layer "In11.Cu")
		(net "M_H_CPU1_SA_DQS_DP<2>")
	)
	(segment
		(start 187.329572 -298.630848)
		(end 184.113932 -298.630848)
		(width 0.18288)
		(layer "In11.Cu")
		(net "M_H_CPU1_SA_DQS_DP<2>")
	)
	(segment
		(start 178.168554 -299.475906)
		(end 177.411126 -299.475906)
		(width 0.18288)
		(layer "In11.Cu")
		(net "M_H_CPU1_SA_DQS_DP<2>")
	)
	(segment
		(start 157.905196 -294.611552)
		(end 156.373576 -294.611552)
		(width 0.18288)
		(layer "In11.Cu")
		(net "M_H_CPU1_SA_DQS_DP<2>")
	)
	(segment
		(start 128.869186 -271.50949)
		(end 128.84785 -271.497298)
		(width 0.088646)
		(layer "In11.Cu")
		(net "M_H_CPU1_SA_DQS_DP<2>")
	)
	(segment
		(start 151.901144 -288.18967)
		(end 139.617704 -275.90623)
		(width 0.18288)
		(layer "In11.Cu")
		(net "M_H_CPU1_SA_DQS_DP<2>")
	)
	(segment
		(start 191.422782 -299.473874)
		(end 189.95898 -299.473874)
		(width 0.18288)
		(layer "In11.Cu")
		(net "M_H_CPU1_SA_DQS_DP<2>")
	)
	(segment
		(start 126.510288 -270.69034)
		(end 126.50597 -270.6878)
		(width 0.088646)
		(layer "In11.Cu")
		(net "M_H_CPU1_SA_DQS_DP<2>")
	)
	(segment
		(start 131.768596 -273.942556)
		(end 131.753864 -273.951192)
		(width 0.088646)
		(layer "In11.Cu")
		(net "M_H_CPU1_SA_DQS_DP<2>")
	)
	(segment
		(start 192.215008 -299.740828)
		(end 191.689736 -299.740828)
		(width 0.18288)
		(layer "In11.Cu")
		(net "M_H_CPU1_SA_DQS_DP<2>")
	)
	(segment
		(start 139.617704 -275.90623)
		(end 139.325858 -275.90623)
		(width 0.18288)
		(layer "In11.Cu")
		(net "M_H_CPU1_SA_DQS_DP<2>")
	)
	(segment
		(start 176.318926 -299.457618)
		(end 174.833534 -299.457618)
		(width 0.18288)
		(layer "In11.Cu")
		(net "M_H_CPU1_SA_DQS_DP<2>")
	)
	(segment
		(start 123.340622 -270.19758)
		(end 123.027948 -270.19758)
		(width 0.088646)
		(layer "In11.Cu")
		(net "M_H_CPU1_SA_DQS_DP<2>")
	)
	(segment
		(start 132.70865 -273.942556)
		(end 132.698236 -273.948652)
		(width 0.088646)
		(layer "In11.Cu")
		(net "M_H_CPU1_SA_DQS_DP<2>")
	)
	(segment
		(start 169.585132 -298.435268)
		(end 168.553384 -298.435268)
		(width 0.18288)
		(layer "In11.Cu")
		(net "M_H_CPU1_SA_DQS_DP<2>")
	)
	(segment
		(start 199.170036 -295.124632)
		(end 198.180452 -296.114216)
		(width 0.18288)
		(layer "In11.Cu")
		(net "M_H_CPU1_SA_DQS_DP<2>")
	)
	(segment
		(start 177.146204 -299.740828)
		(end 176.602136 -299.740828)
		(width 0.18288)
		(layer "In11.Cu")
		(net "M_H_CPU1_SA_DQS_DP<2>")
	)
	(segment
		(start 138.764264 -275.846286)
		(end 136.919462 -274.001484)
		(width 0.088646)
		(layer "In11.Cu")
		(net "M_H_CPU1_SA_DQS_DP<2>")
	)
	(segment
		(start 195.956682 -297.517566)
		(end 195.592192 -297.517566)
		(width 0.18288)
		(layer "In11.Cu")
		(net "M_H_CPU1_SA_DQS_DP<2>")
	)
	(segment
		(start 191.689736 -299.740828)
		(end 191.422782 -299.473874)
		(width 0.18288)
		(layer "In11.Cu")
		(net "M_H_CPU1_SA_DQS_DP<2>")
	)
	(segment
		(start 133.648196 -273.942556)
		(end 133.637782 -273.948652)
		(width 0.088646)
		(layer "In11.Cu")
		(net "M_H_CPU1_SA_DQS_DP<2>")
	)
	(segment
		(start 177.411126 -299.475906)
		(end 177.146204 -299.740828)
		(width 0.18288)
		(layer "In11.Cu")
		(net "M_H_CPU1_SA_DQS_DP<2>")
	)
	(segment
		(start 139.265914 -275.846286)
		(end 138.764264 -275.846286)
		(width 0.088646)
		(layer "In11.Cu")
		(net "M_H_CPU1_SA_DQS_DP<2>")
	)
	(segment
		(start 172.565822 -300.591474)
		(end 172.292518 -300.31817)
		(width 0.18288)
		(layer "In11.Cu")
		(net "M_H_CPU1_SA_DQS_DP<2>")
	)
	(segment
		(start 201.429112 -293.779956)
		(end 200.084436 -295.124632)
		(width 0.18288)
		(layer "In11.Cu")
		(net "M_H_CPU1_SA_DQS_DP<2>")
	)
	(segment
		(start 202.21829 -293.964106)
		(end 202.03414 -293.779956)
		(width 0.18288)
		(layer "In11.Cu")
		(net "M_H_CPU1_SA_DQS_DP<2>")
	)
	(segment
		(start 123.690888 -270.69034)
		(end 123.685046 -270.687038)
		(width 0.088646)
		(layer "In11.Cu")
		(net "M_H_CPU1_SA_DQS_DP<2>")
	)
	(segment
		(start 126.50597 -270.6878)
		(end 126.498604 -270.683736)
		(width 0.088646)
		(layer "In11.Cu")
		(net "M_H_CPU1_SA_DQS_DP<2>")
	)
	(segment
		(start 123.406154 -270.263112)
		(end 123.340622 -270.19758)
		(width 0.088646)
		(layer "In11.Cu")
		(net "M_H_CPU1_SA_DQS_DP<2>")
	)
	(segment
		(start 173.972982 -300.31817)
		(end 173.25975 -300.31817)
		(width 0.18288)
		(layer "In11.Cu")
		(net "M_H_CPU1_SA_DQS_DP<2>")
	)
	(segment
		(start 124.62637 -270.6878)
		(end 124.619004 -270.683736)
		(width 0.088646)
		(layer "In11.Cu")
		(net "M_H_CPU1_SA_DQS_DP<2>")
	)
	(segment
		(start 124.630688 -270.69034)
		(end 124.62637 -270.6878)
		(width 0.088646)
		(layer "In11.Cu")
		(net "M_H_CPU1_SA_DQS_DP<2>")
	)
	(segment
		(start 171.468034 -300.31817)
		(end 169.585132 -298.435268)
		(width 0.18288)
		(layer "In11.Cu")
		(net "M_H_CPU1_SA_DQS_DP<2>")
	)
	(segment
		(start 128.868678 -271.50949)
		(end 128.869186 -271.50949)
		(width 0.088646)
		(layer "In11.Cu")
		(net "M_H_CPU1_SA_DQS_DP<2>")
	)
	(segment
		(start 172.986446 -300.591474)
		(end 172.565822 -300.591474)
		(width 0.18288)
		(layer "In11.Cu")
		(net "M_H_CPU1_SA_DQS_DP<2>")
	)
	(segment
		(start 151.901144 -290.13912)
		(end 151.901144 -288.18967)
		(width 0.18288)
		(layer "In11.Cu")
		(net "M_H_CPU1_SA_DQS_DP<2>")
	)
	(segment
		(start 194.202558 -298.431966)
		(end 193.146172 -299.488352)
		(width 0.18288)
		(layer "In11.Cu")
		(net "M_H_CPU1_SA_DQS_DP<2>")
	)
	(segment
		(start 202.71867 -293.964106)
		(end 202.21829 -293.964106)
		(width 0.18288)
		(layer "In11.Cu")
		(net "M_H_CPU1_SA_DQS_DP<2>")
	)
	(segment
		(start 130.742436 -273.13382)
		(end 130.733546 -273.12874)
		(width 0.088646)
		(layer "In11.Cu")
		(net "M_H_CPU1_SA_DQS_DP<2>")
	)
	(segment
		(start 180.062124 -299.252386)
		(end 179.618386 -298.808648)
		(width 0.18288)
		(layer "In11.Cu")
		(net "M_H_CPU1_SA_DQS_DP<2>")
	)
	(segment
		(start 156.373576 -294.611552)
		(end 151.901144 -290.13912)
		(width 0.18288)
		(layer "In11.Cu")
		(net "M_H_CPU1_SA_DQS_DP<2>")
	)
	(segment
		(start 139.325858 -275.90623)
		(end 139.265914 -275.846286)
		(width 0.088646)
		(layer "In11.Cu")
		(net "M_H_CPU1_SA_DQS_DP<2>")
	)
	(segment
		(start 123.685046 -270.687038)
		(end 123.683014 -270.685768)
		(width 0.088646)
		(layer "In11.Cu")
		(net "M_H_CPU1_SA_DQS_DP<2>")
	)
	(segment
		(start 134.587996 -273.942556)
		(end 134.573264 -273.951192)
		(width 0.088646)
		(layer "In11.Cu")
		(net "M_H_CPU1_SA_DQS_DP<2>")
	)
	(segment
		(start 189.95898 -299.473874)
		(end 189.111128 -298.626022)
		(width 0.18288)
		(layer "In11.Cu")
		(net "M_H_CPU1_SA_DQS_DP<2>")
	)
	(segment
		(start 164.06622 -296.66184)
		(end 160.622234 -296.66184)
		(width 0.18288)
		(layer "In11.Cu")
		(net "M_H_CPU1_SA_DQS_DP<2>")
	)
	(segment
		(start 172.292518 -300.31817)
		(end 171.468034 -300.31817)
		(width 0.18288)
		(layer "In11.Cu")
		(net "M_H_CPU1_SA_DQS_DP<2>")
	)
	(segment
		(start 159.78378 -295.823386)
		(end 159.11703 -295.823386)
		(width 0.18288)
		(layer "In11.Cu")
		(net "M_H_CPU1_SA_DQS_DP<2>")
	)
	(segment
		(start 159.11703 -295.823386)
		(end 157.905196 -294.611552)
		(width 0.18288)
		(layer "In11.Cu")
		(net "M_H_CPU1_SA_DQS_DP<2>")
	)
	(segment
		(start 202.03414 -293.779956)
		(end 201.429112 -293.779956)
		(width 0.18288)
		(layer "In11.Cu")
		(net "M_H_CPU1_SA_DQS_DP<2>")
	)
	(segment
		(start 167.902128 -297.784012)
		(end 165.188392 -297.784012)
		(width 0.18288)
		(layer "In11.Cu")
		(net "M_H_CPU1_SA_DQS_DP<2>")
	)
	(segment
		(start 200.084436 -295.124632)
		(end 199.170036 -295.124632)
		(width 0.18288)
		(layer "In11.Cu")
		(net "M_H_CPU1_SA_DQS_DP<2>")
	)
	(segment
		(start 188.376306 -298.626022)
		(end 188.111384 -298.890944)
		(width 0.18288)
		(layer "In11.Cu")
		(net "M_H_CPU1_SA_DQS_DP<2>")
	)
	(segment
		(start 125.56617 -270.6878)
		(end 125.558804 -270.683736)
		(width 0.088646)
		(layer "In11.Cu")
		(net "M_H_CPU1_SA_DQS_DP<2>")
	)
	(segment
		(start 198.180452 -296.114216)
		(end 197.360032 -296.114216)
		(width 0.18288)
		(layer "In11.Cu")
		(net "M_H_CPU1_SA_DQS_DP<2>")
	)
	(segment
		(start 129.802636 -271.505934)
		(end 129.79527 -271.501616)
		(width 0.088646)
		(layer "In11.Cu")
		(net "M_H_CPU1_SA_DQS_DP<2>")
	)
	(segment
		(start 160.622234 -296.66184)
		(end 159.78378 -295.823386)
		(width 0.18288)
		(layer "In11.Cu")
		(net "M_H_CPU1_SA_DQS_DP<2>")
	)
	(segment
		(start 180.657754 -299.252386)
		(end 180.062124 -299.252386)
		(width 0.18288)
		(layer "In11.Cu")
		(net "M_H_CPU1_SA_DQS_DP<2>")
	)
	(segment
		(start 182.148226 -297.761914)
		(end 180.657754 -299.252386)
		(width 0.18288)
		(layer "In11.Cu")
		(net "M_H_CPU1_SA_DQS_DP<2>")
	)
	(segment
		(start 193.146172 -299.488352)
		(end 192.467484 -299.488352)
		(width 0.18288)
		(layer "In11.Cu")
		(net "M_H_CPU1_SA_DQS_DP<2>")
	)
	(segment
		(start 202.971146 -294.216582)
		(end 202.71867 -293.964106)
		(width 0.18288)
		(layer "In11.Cu")
		(net "M_H_CPU1_SA_DQS_DP<2>")
	)
	(segment
		(start 125.570488 -270.69034)
		(end 125.56617 -270.6878)
		(width 0.088646)
		(layer "In11.Cu")
		(net "M_H_CPU1_SA_DQS_DP<2>")
	)
	(segment
		(start 130.733546 -273.12874)
		(end 130.72745 -273.125184)
		(width 0.088646)
		(layer "In11.Cu")
		(net "M_H_CPU1_SA_DQS_DP<2>")
	)
	(segment
		(start 179.618386 -298.808648)
		(end 178.835812 -298.808648)
		(width 0.18288)
		(layer "In11.Cu")
		(net "M_H_CPU1_SA_DQS_DP<2>")
	)
	(segment
		(start 129.981198 -271.84731)
		(end 129.981198 -271.825212)
		(width 0.088646)
		(layer "In11.Cu")
		(net "M_H_CPU1_SA_DQS_DP<2>")
	)
	(segment
		(start 187.589668 -298.890944)
		(end 187.329572 -298.630848)
		(width 0.18288)
		(layer "In11.Cu")
		(net "M_H_CPU1_SA_DQS_DP<2>")
	)
	(arc
		(start 128.383792 -270.687038)
		(mid 128.196594 -270.636895)
		(end 128.009396 -270.687038)
		(width 0.088646)
		(layer "In11.Cu")
		(net "M_H_CPU1_SA_DQS_DP<2>")
	)
	(arc
		(start 135.902192 -273.942556)
		(mid 135.714994 -273.892413)
		(end 135.527796 -273.942556)
		(width 0.088646)
		(layer "In11.Cu")
		(net "M_H_CPU1_SA_DQS_DP<2>")
	)
	(arc
		(start 129.41935 -271.500854)
		(mid 129.145151 -271.576689)
		(end 128.868678 -271.50949)
		(width 0.088646)
		(layer "In11.Cu")
		(net "M_H_CPU1_SA_DQS_DP<2>")
	)
	(arc
		(start 136.919462 -274.001484)
		(mid 136.88265 -273.969491)
		(end 136.841992 -273.942556)
		(width 0.088646)
		(layer "In11.Cu")
		(net "M_H_CPU1_SA_DQS_DP<2>")
	)
	(arc
		(start 136.467596 -273.942556)
		(mid 136.184894 -274.018332)
		(end 135.902192 -273.942556)
		(width 0.088646)
		(layer "In11.Cu")
		(net "M_H_CPU1_SA_DQS_DP<2>")
	)
	(arc
		(start 128.571244 -271.011396)
		(mid 128.523565 -270.828496)
		(end 128.392682 -270.692118)
		(width 0.088646)
		(layer "In11.Cu")
		(net "M_H_CPU1_SA_DQS_DP<2>")
	)
	(arc
		(start 135.513064 -273.951192)
		(mid 135.236589 -274.018512)
		(end 134.962392 -273.942556)
		(width 0.088646)
		(layer "In11.Cu")
		(net "M_H_CPU1_SA_DQS_DP<2>")
	)
	(arc
		(start 130.450844 -272.639282)
		(mid 130.450792 -272.631915)
		(end 130.45059 -272.62455)
		(width 0.088646)
		(layer "In11.Cu")
		(net "M_H_CPU1_SA_DQS_DP<2>")
	)
	(arc
		(start 124.619004 -270.683736)
		(mid 124.434149 -270.636786)
		(end 124.250196 -270.687038)
		(width 0.088646)
		(layer "In11.Cu")
		(net "M_H_CPU1_SA_DQS_DP<2>")
	)
	(arc
		(start 131.203192 -273.942556)
		(mid 131.000369 -273.742325)
		(end 130.920998 -273.468592)
		(width 0.088646)
		(layer "In11.Cu")
		(net "M_H_CPU1_SA_DQS_DP<2>")
	)
	(arc
		(start 125.558804 -270.683736)
		(mid 125.373949 -270.636786)
		(end 125.189996 -270.687038)
		(width 0.088646)
		(layer "In11.Cu")
		(net "M_H_CPU1_SA_DQS_DP<2>")
	)
	(arc
		(start 129.793746 -271.500854)
		(mid 129.606548 -271.450711)
		(end 129.41935 -271.500854)
		(width 0.088646)
		(layer "In11.Cu")
		(net "M_H_CPU1_SA_DQS_DP<2>")
	)
	(arc
		(start 130.45059 -272.62455)
		(mid 130.399536 -272.44997)
		(end 130.272282 -272.320004)
		(width 0.088646)
		(layer "In11.Cu")
		(net "M_H_CPU1_SA_DQS_DP<2>")
	)
	(arc
		(start 130.72745 -273.125184)
		(mid 130.524863 -272.918833)
		(end 130.450844 -272.639282)
		(width 0.088646)
		(layer "In11.Cu")
		(net "M_H_CPU1_SA_DQS_DP<2>")
	)
	(arc
		(start 127.069596 -270.687038)
		(mid 126.790393 -270.762678)
		(end 126.510288 -270.69034)
		(width 0.088646)
		(layer "In11.Cu")
		(net "M_H_CPU1_SA_DQS_DP<2>")
	)
	(arc
		(start 124.250196 -270.687038)
		(mid 123.970993 -270.762678)
		(end 123.690888 -270.69034)
		(width 0.088646)
		(layer "In11.Cu")
		(net "M_H_CPU1_SA_DQS_DP<2>")
	)
	(arc
		(start 136.841992 -273.942556)
		(mid 136.654794 -273.892413)
		(end 136.467596 -273.942556)
		(width 0.088646)
		(layer "In11.Cu")
		(net "M_H_CPU1_SA_DQS_DP<2>")
	)
	(arc
		(start 131.753864 -273.951192)
		(mid 131.477389 -274.018512)
		(end 131.203192 -273.942556)
		(width 0.088646)
		(layer "In11.Cu")
		(net "M_H_CPU1_SA_DQS_DP<2>")
	)
	(arc
		(start 123.683014 -270.685768)
		(mid 123.53136 -270.556806)
		(end 123.43384 -270.383254)
		(width 0.088646)
		(layer "In11.Cu")
		(net "M_H_CPU1_SA_DQS_DP<2>")
	)
	(arc
		(start 132.142992 -273.942556)
		(mid 131.955794 -273.892413)
		(end 131.768596 -273.942556)
		(width 0.088646)
		(layer "In11.Cu")
		(net "M_H_CPU1_SA_DQS_DP<2>")
	)
	(arc
		(start 127.994664 -270.695674)
		(mid 127.718189 -270.762994)
		(end 127.443992 -270.687038)
		(width 0.088646)
		(layer "In11.Cu")
		(net "M_H_CPU1_SA_DQS_DP<2>")
	)
	(arc
		(start 123.409202 -270.284194)
		(mid 123.407578 -270.273667)
		(end 123.406154 -270.263112)
		(width 0.088646)
		(layer "In11.Cu")
		(net "M_H_CPU1_SA_DQS_DP<2>")
	)
	(arc
		(start 133.637782 -273.948652)
		(mid 133.359604 -274.018375)
		(end 133.083046 -273.942556)
		(width 0.088646)
		(layer "In11.Cu")
		(net "M_H_CPU1_SA_DQS_DP<2>")
	)
	(arc
		(start 133.083046 -273.942556)
		(mid 132.895848 -273.892413)
		(end 132.70865 -273.942556)
		(width 0.088646)
		(layer "In11.Cu")
		(net "M_H_CPU1_SA_DQS_DP<2>")
	)
	(arc
		(start 128.84785 -271.497298)
		(mid 128.645263 -271.290947)
		(end 128.571244 -271.011396)
		(width 0.088646)
		(layer "In11.Cu")
		(net "M_H_CPU1_SA_DQS_DP<2>")
	)
	(arc
		(start 126.498604 -270.683736)
		(mid 126.313749 -270.636786)
		(end 126.129796 -270.687038)
		(width 0.088646)
		(layer "In11.Cu")
		(net "M_H_CPU1_SA_DQS_DP<2>")
	)
	(arc
		(start 125.189996 -270.687038)
		(mid 124.910793 -270.762678)
		(end 124.630688 -270.69034)
		(width 0.088646)
		(layer "In11.Cu")
		(net "M_H_CPU1_SA_DQS_DP<2>")
	)
	(arc
		(start 134.573264 -273.951192)
		(mid 134.296789 -274.018512)
		(end 134.022592 -273.942556)
		(width 0.088646)
		(layer "In11.Cu")
		(net "M_H_CPU1_SA_DQS_DP<2>")
	)
	(arc
		(start 127.443992 -270.687038)
		(mid 127.256794 -270.636895)
		(end 127.069596 -270.687038)
		(width 0.088646)
		(layer "In11.Cu")
		(net "M_H_CPU1_SA_DQS_DP<2>")
	)
	(arc
		(start 126.129796 -270.687038)
		(mid 125.850593 -270.762678)
		(end 125.570488 -270.69034)
		(width 0.088646)
		(layer "In11.Cu")
		(net "M_H_CPU1_SA_DQS_DP<2>")
	)
	(arc
		(start 134.022592 -273.942556)
		(mid 133.835394 -273.892413)
		(end 133.648196 -273.942556)
		(width 0.088646)
		(layer "In11.Cu")
		(net "M_H_CPU1_SA_DQS_DP<2>")
	)
	(arc
		(start 132.698236 -273.948652)
		(mid 132.419804 -274.018498)
		(end 132.142992 -273.942556)
		(width 0.088646)
		(layer "In11.Cu")
		(net "M_H_CPU1_SA_DQS_DP<2>")
	)
	(arc
		(start 123.43384 -270.383254)
		(mid 123.419277 -270.334282)
		(end 123.409202 -270.284194)
		(width 0.088646)
		(layer "In11.Cu")
		(net "M_H_CPU1_SA_DQS_DP<2>")
	)
	(arc
		(start 134.962392 -273.942556)
		(mid 134.775194 -273.892413)
		(end 134.587996 -273.942556)
		(width 0.088646)
		(layer "In11.Cu")
		(net "M_H_CPU1_SA_DQS_DP<2>")
	)
	(arc
		(start 129.981198 -271.825212)
		(mid 129.933519 -271.642312)
		(end 129.802636 -271.505934)
		(width 0.088646)
		(layer "In11.Cu")
		(net "M_H_CPU1_SA_DQS_DP<2>")
	)
	(arc
		(start 130.263392 -272.314924)
		(mid 130.06211 -272.117437)
		(end 129.981198 -271.84731)
		(width 0.088646)
		(layer "In11.Cu")
		(net "M_H_CPU1_SA_DQS_DP<2>")
	)
	(arc
		(start 130.920998 -273.453098)
		(mid 130.873319 -273.270198)
		(end 130.742436 -273.13382)
		(width 0.088646)
		(layer "In11.Cu")
		(net "M_H_CPU1_SA_DQS_DP<2>")
	)
	(segment
		(start 206.9973 -303.991772)
		(end 207.023208 -303.991772)
		(width 0.101854)
		(layer "F.Cu")
		(net "M_H_CPU1_SA_DQS_DP<1>")
	)
	(segment
		(start 206.606648 -303.740566)
		(end 206.857854 -303.991772)
		(width 0.20066)
		(layer "F.Cu")
		(net "M_H_CPU1_SA_DQS_DP<1>")
	)
	(segment
		(start 205.50632 -303.326038)
		(end 205.920848 -303.740566)
		(width 0.20066)
		(layer "F.Cu")
		(net "M_H_CPU1_SA_DQS_DP<1>")
	)
	(segment
		(start 204.665326 -303.566576)
		(end 204.905864 -303.326038)
		(width 0.20066)
		(layer "F.Cu")
		(net "M_H_CPU1_SA_DQS_DP<1>")
	)
	(segment
		(start 209.812382 -303.695354)
		(end 210.182968 -303.695354)
		(width 0.20066)
		(layer "F.Cu")
		(net "M_H_CPU1_SA_DQS_DP<1>")
	)
	(segment
		(start 202.971146 -303.566576)
		(end 204.076046 -303.566576)
		(width 0.20066)
		(layer "F.Cu")
		(net "M_H_CPU1_SA_DQS_DP<1>")
	)
	(segment
		(start 210.78952 -303.28489)
		(end 211.071206 -303.566576)
		(width 0.20066)
		(layer "F.Cu")
		(net "M_H_CPU1_SA_DQS_DP<1>")
	)
	(segment
		(start 209.18043 -303.991772)
		(end 209.186526 -303.997868)
		(width 0.1016)
		(layer "F.Cu")
		(net "M_H_CPU1_SA_DQS_DP<1>")
	)
	(segment
		(start 210.182968 -303.695354)
		(end 210.593432 -303.28489)
		(width 0.20066)
		(layer "F.Cu")
		(net "M_H_CPU1_SA_DQS_DP<1>")
	)
	(segment
		(start 209.186526 -303.997868)
		(end 209.509868 -303.997868)
		(width 0.20066)
		(layer "F.Cu")
		(net "M_H_CPU1_SA_DQS_DP<1>")
	)
	(segment
		(start 123.967494 -274.54479)
		(end 123.967748 -274.545044)
		(width 0.20066)
		(layer "F.Cu")
		(net "M_H_CPU1_SA_DQS_DP<1>")
	)
	(segment
		(start 210.593432 -303.28489)
		(end 210.78952 -303.28489)
		(width 0.20066)
		(layer "F.Cu")
		(net "M_H_CPU1_SA_DQS_DP<1>")
	)
	(segment
		(start 123.967748 -274.545044)
		(end 123.967748 -275.08073)
		(width 0.20066)
		(layer "F.Cu")
		(net "M_H_CPU1_SA_DQS_DP<1>")
	)
	(segment
		(start 209.509868 -303.997868)
		(end 209.812382 -303.695354)
		(width 0.20066)
		(layer "F.Cu")
		(net "M_H_CPU1_SA_DQS_DP<1>")
	)
	(segment
		(start 204.905864 -303.326038)
		(end 205.50632 -303.326038)
		(width 0.20066)
		(layer "F.Cu")
		(net "M_H_CPU1_SA_DQS_DP<1>")
	)
	(segment
		(start 206.857854 -303.991772)
		(end 206.9973 -303.991772)
		(width 0.20066)
		(layer "F.Cu")
		(net "M_H_CPU1_SA_DQS_DP<1>")
	)
	(segment
		(start 204.076046 -303.566576)
		(end 204.665326 -303.566576)
		(width 0.20066)
		(layer "F.Cu")
		(net "M_H_CPU1_SA_DQS_DP<1>")
	)
	(segment
		(start 211.071206 -303.566576)
		(end 211.619846 -303.566576)
		(width 0.20066)
		(layer "F.Cu")
		(net "M_H_CPU1_SA_DQS_DP<1>")
	)
	(segment
		(start 205.920848 -303.740566)
		(end 206.606648 -303.740566)
		(width 0.20066)
		(layer "F.Cu")
		(net "M_H_CPU1_SA_DQS_DP<1>")
	)
	(segment
		(start 207.023208 -303.991772)
		(end 209.18043 -303.991772)
		(width 0.1016)
		(layer "F.Cu")
		(net "M_H_CPU1_SA_DQS_DP<1>")
	)
	(segment
		(start 153.709624 -304.869088)
		(end 153.709624 -300.689264)
		(width 0.18288)
		(layer "In11.Cu")
		(net "M_H_CPU1_SA_DQS_DP<1>")
	)
	(segment
		(start 201.23404 -304.292)
		(end 200.27011 -305.25593)
		(width 0.18288)
		(layer "In11.Cu")
		(net "M_H_CPU1_SA_DQS_DP<1>")
	)
	(segment
		(start 126.221998 -278.351996)
		(end 126.221998 -278.336502)
		(width 0.088646)
		(layer "In11.Cu")
		(net "M_H_CPU1_SA_DQS_DP<1>")
	)
	(segment
		(start 124.29236 -275.34997)
		(end 124.269246 -275.326856)
		(width 0.088646)
		(layer "In11.Cu")
		(net "M_H_CPU1_SA_DQS_DP<1>")
	)
	(segment
		(start 124.269246 -275.326856)
		(end 124.26188 -275.326856)
		(width 0.088646)
		(layer "In11.Cu")
		(net "M_H_CPU1_SA_DQS_DP<1>")
	)
	(segment
		(start 166.139622 -308.79034)
		(end 166.015162 -308.66588)
		(width 0.18288)
		(layer "In11.Cu")
		(net "M_H_CPU1_SA_DQS_DP<1>")
	)
	(segment
		(start 124.624592 -275.570442)
		(end 124.62256 -275.569172)
		(width 0.088646)
		(layer "In11.Cu")
		(net "M_H_CPU1_SA_DQS_DP<1>")
	)
	(segment
		(start 128.853946 -279.639776)
		(end 128.85166 -279.638506)
		(width 0.088646)
		(layer "In11.Cu")
		(net "M_H_CPU1_SA_DQS_DP<1>")
	)
	(segment
		(start 169.470324 -309.417212)
		(end 168.789096 -309.417212)
		(width 0.18288)
		(layer "In11.Cu")
		(net "M_H_CPU1_SA_DQS_DP<1>")
	)
	(segment
		(start 125.751844 -275.904706)
		(end 125.751844 -275.886418)
		(width 0.088646)
		(layer "In11.Cu")
		(net "M_H_CPU1_SA_DQS_DP<1>")
	)
	(segment
		(start 135.911082 -280.458926)
		(end 135.902192 -280.453846)
		(width 0.088646)
		(layer "In11.Cu")
		(net "M_H_CPU1_SA_DQS_DP<1>")
	)
	(segment
		(start 177.388774 -310.525922)
		(end 177.123852 -310.790844)
		(width 0.18288)
		(layer "In11.Cu")
		(net "M_H_CPU1_SA_DQS_DP<1>")
	)
	(segment
		(start 159.079184 -308.88686)
		(end 158.93288 -308.984396)
		(width 0.18288)
		(layer "In11.Cu")
		(net "M_H_CPU1_SA_DQS_DP<1>")
	)
	(segment
		(start 168.789096 -309.417212)
		(end 168.037764 -308.66588)
		(width 0.18288)
		(layer "In11.Cu")
		(net "M_H_CPU1_SA_DQS_DP<1>")
	)
	(segment
		(start 185.81243 -309.667656)
		(end 185.68797 -309.792116)
		(width 0.18288)
		(layer "In11.Cu")
		(net "M_H_CPU1_SA_DQS_DP<1>")
	)
	(segment
		(start 160.513776 -309.174134)
		(end 160.512252 -309.173372)
		(width 0.18288)
		(layer "In11.Cu")
		(net "M_H_CPU1_SA_DQS_DP<1>")
	)
	(segment
		(start 187.589668 -309.94096)
		(end 187.316364 -309.667656)
		(width 0.18288)
		(layer "In11.Cu")
		(net "M_H_CPU1_SA_DQS_DP<1>")
	)
	(segment
		(start 133.567678 -279.648412)
		(end 133.552946 -279.639776)
		(width 0.088646)
		(layer "In11.Cu")
		(net "M_H_CPU1_SA_DQS_DP<1>")
	)
	(segment
		(start 174.263812 -311.233312)
		(end 174.101252 -311.166002)
		(width 0.18288)
		(layer "In11.Cu")
		(net "M_H_CPU1_SA_DQS_DP<1>")
	)
	(segment
		(start 202.176634 -303.296574)
		(end 201.985626 -303.105566)
		(width 0.18288)
		(layer "In11.Cu")
		(net "M_H_CPU1_SA_DQS_DP<1>")
	)
	(segment
		(start 201.985626 -303.105566)
		(end 201.525124 -303.105566)
		(width 0.18288)
		(layer "In11.Cu")
		(net "M_H_CPU1_SA_DQS_DP<1>")
	)
	(segment
		(start 202.971146 -303.566576)
		(end 202.701144 -303.296574)
		(width 0.18288)
		(layer "In11.Cu")
		(net "M_H_CPU1_SA_DQS_DP<1>")
	)
	(segment
		(start 161.995612 -309.66537)
		(end 161.871152 -309.54091)
		(width 0.18288)
		(layer "In11.Cu")
		(net "M_H_CPU1_SA_DQS_DP<1>")
	)
	(segment
		(start 174.77105 -311.023508)
		(end 174.263812 -311.233312)
		(width 0.18288)
		(layer "In11.Cu")
		(net "M_H_CPU1_SA_DQS_DP<1>")
	)
	(segment
		(start 139.04595 -283.740352)
		(end 138.641074 -283.335476)
		(width 0.18288)
		(layer "In11.Cu")
		(net "M_H_CPU1_SA_DQS_DP<1>")
	)
	(segment
		(start 172.995336 -311.640982)
		(end 172.502068 -311.640982)
		(width 0.18288)
		(layer "In11.Cu")
		(net "M_H_CPU1_SA_DQS_DP<1>")
	)
	(segment
		(start 178.112928 -310.525922)
		(end 177.388774 -310.525922)
		(width 0.18288)
		(layer "In11.Cu")
		(net "M_H_CPU1_SA_DQS_DP<1>")
	)
	(segment
		(start 157.389068 -308.548532)
		(end 156.5656 -307.725064)
		(width 0.18288)
		(layer "In11.Cu")
		(net "M_H_CPU1_SA_DQS_DP<1>")
	)
	(segment
		(start 173.594776 -311.37606)
		(end 173.260258 -311.37606)
		(width 0.18288)
		(layer "In11.Cu")
		(net "M_H_CPU1_SA_DQS_DP<1>")
	)
	(segment
		(start 154.485594 -305.82108)
		(end 154.097482 -305.432968)
		(width 0.18288)
		(layer "In11.Cu")
		(net "M_H_CPU1_SA_DQS_DP<1>")
	)
	(segment
		(start 155.613608 -306.773072)
		(end 155.437586 -306.773072)
		(width 0.18288)
		(layer "In11.Cu")
		(net "M_H_CPU1_SA_DQS_DP<1>")
	)
	(segment
		(start 170.394376 -310.341264)
		(end 169.470324 -309.417212)
		(width 0.18288)
		(layer "In11.Cu")
		(net "M_H_CPU1_SA_DQS_DP<1>")
	)
	(segment
		(start 168.037764 -308.66588)
		(end 166.812722 -308.66588)
		(width 0.18288)
		(layer "In11.Cu")
		(net "M_H_CPU1_SA_DQS_DP<1>")
	)
	(segment
		(start 191.689736 -310.790844)
		(end 191.406526 -310.507634)
		(width 0.18288)
		(layer "In11.Cu")
		(net "M_H_CPU1_SA_DQS_DP<1>")
	)
	(segment
		(start 196.3547 -308.381908)
		(end 196.178678 -308.381908)
		(width 0.18288)
		(layer "In11.Cu")
		(net "M_H_CPU1_SA_DQS_DP<1>")
	)
	(segment
		(start 154.661616 -305.82108)
		(end 154.485594 -305.82108)
		(width 0.18288)
		(layer "In11.Cu")
		(net "M_H_CPU1_SA_DQS_DP<1>")
	)
	(segment
		(start 127.069596 -278.82596)
		(end 127.054864 -278.834596)
		(width 0.088646)
		(layer "In11.Cu")
		(net "M_H_CPU1_SA_DQS_DP<1>")
	)
	(segment
		(start 187.316364 -309.667656)
		(end 185.81243 -309.667656)
		(width 0.18288)
		(layer "In11.Cu")
		(net "M_H_CPU1_SA_DQS_DP<1>")
	)
	(segment
		(start 124.62256 -275.569172)
		(end 124.578872 -275.544026)
		(width 0.088646)
		(layer "In11.Cu")
		(net "M_H_CPU1_SA_DQS_DP<1>")
	)
	(segment
		(start 185.68797 -309.792116)
		(end 185.13933 -309.792116)
		(width 0.18288)
		(layer "In11.Cu")
		(net "M_H_CPU1_SA_DQS_DP<1>")
	)
	(segment
		(start 138.641074 -283.335476)
		(end 138.641074 -283.244036)
		(width 0.088646)
		(layer "In11.Cu")
		(net "M_H_CPU1_SA_DQS_DP<1>")
	)
	(segment
		(start 183.61279 -309.667656)
		(end 183.019446 -310.261)
		(width 0.18288)
		(layer "In11.Cu")
		(net "M_H_CPU1_SA_DQS_DP<1>")
	)
	(segment
		(start 128.009396 -278.82596)
		(end 127.994664 -278.834596)
		(width 0.088646)
		(layer "In11.Cu")
		(net "M_H_CPU1_SA_DQS_DP<1>")
	)
	(segment
		(start 154.097482 -305.432968)
		(end 154.097482 -305.256946)
		(width 0.18288)
		(layer "In11.Cu")
		(net "M_H_CPU1_SA_DQS_DP<1>")
	)
	(segment
		(start 172.502068 -311.640982)
		(end 172.203618 -311.342532)
		(width 0.18288)
		(layer "In11.Cu")
		(net "M_H_CPU1_SA_DQS_DP<1>")
	)
	(segment
		(start 198.930006 -306.362862)
		(end 198.153782 -307.139086)
		(width 0.18288)
		(layer "In11.Cu")
		(net "M_H_CPU1_SA_DQS_DP<1>")
	)
	(segment
		(start 125.573282 -275.575522)
		(end 125.564392 -275.570442)
		(width 0.088646)
		(layer "In11.Cu")
		(net "M_H_CPU1_SA_DQS_DP<1>")
	)
	(segment
		(start 154.097482 -305.256946)
		(end 153.709624 -304.869088)
		(width 0.18288)
		(layer "In11.Cu")
		(net "M_H_CPU1_SA_DQS_DP<1>")
	)
	(segment
		(start 128.85166 -279.638506)
		(end 128.849628 -279.637236)
		(width 0.088646)
		(layer "In11.Cu")
		(net "M_H_CPU1_SA_DQS_DP<1>")
	)
	(segment
		(start 130.748278 -279.648412)
		(end 130.733546 -279.639776)
		(width 0.088646)
		(layer "In11.Cu")
		(net "M_H_CPU1_SA_DQS_DP<1>")
	)
	(segment
		(start 135.433054 -279.640284)
		(end 135.432038 -279.639776)
		(width 0.088646)
		(layer "In11.Cu")
		(net "M_H_CPU1_SA_DQS_DP<1>")
	)
	(segment
		(start 126.04242 -276.38883)
		(end 126.037594 -276.38629)
		(width 0.088646)
		(layer "In11.Cu")
		(net "M_H_CPU1_SA_DQS_DP<1>")
	)
	(segment
		(start 181.090824 -310.38546)
		(end 180.542184 -310.38546)
		(width 0.18288)
		(layer "In11.Cu")
		(net "M_H_CPU1_SA_DQS_DP<1>")
	)
	(segment
		(start 161.198306 -309.54091)
		(end 160.513776 -309.174134)
		(width 0.18288)
		(layer "In11.Cu")
		(net "M_H_CPU1_SA_DQS_DP<1>")
	)
	(segment
		(start 125.189996 -275.570442)
		(end 125.175264 -275.579078)
		(width 0.088646)
		(layer "In11.Cu")
		(net "M_H_CPU1_SA_DQS_DP<1>")
	)
	(segment
		(start 191.406526 -310.507634)
		(end 189.869064 -310.507634)
		(width 0.18288)
		(layer "In11.Cu")
		(net "M_H_CPU1_SA_DQS_DP<1>")
	)
	(segment
		(start 193.044318 -310.557672)
		(end 192.444624 -310.557672)
		(width 0.18288)
		(layer "In11.Cu")
		(net "M_H_CPU1_SA_DQS_DP<1>")
	)
	(segment
		(start 189.037468 -309.676038)
		(end 188.376306 -309.676038)
		(width 0.18288)
		(layer "In11.Cu")
		(net "M_H_CPU1_SA_DQS_DP<1>")
	)
	(segment
		(start 166.015162 -308.66588)
		(end 165.466522 -308.66588)
		(width 0.18288)
		(layer "In11.Cu")
		(net "M_H_CPU1_SA_DQS_DP<1>")
	)
	(segment
		(start 153.709624 -300.689264)
		(end 145.311876 -292.291516)
		(width 0.18288)
		(layer "In11.Cu")
		(net "M_H_CPU1_SA_DQS_DP<1>")
	)
	(segment
		(start 125.751844 -275.886418)
		(end 125.75159 -275.880068)
		(width 0.088646)
		(layer "In11.Cu")
		(net "M_H_CPU1_SA_DQS_DP<1>")
	)
	(segment
		(start 174.101252 -311.166002)
		(end 173.594522 -311.375806)
		(width 0.18288)
		(layer "In11.Cu")
		(net "M_H_CPU1_SA_DQS_DP<1>")
	)
	(segment
		(start 133.17855 -279.639776)
		(end 133.168136 -279.645872)
		(width 0.088646)
		(layer "In11.Cu")
		(net "M_H_CPU1_SA_DQS_DP<1>")
	)
	(segment
		(start 173.594522 -311.375806)
		(end 173.594776 -311.37606)
		(width 0.18288)
		(layer "In11.Cu")
		(net "M_H_CPU1_SA_DQS_DP<1>")
	)
	(segment
		(start 178.839876 -309.798974)
		(end 178.112928 -310.525922)
		(width 0.18288)
		(layer "In11.Cu")
		(net "M_H_CPU1_SA_DQS_DP<1>")
	)
	(segment
		(start 156.389578 -307.725064)
		(end 156.001466 -307.336952)
		(width 0.18288)
		(layer "In11.Cu")
		(net "M_H_CPU1_SA_DQS_DP<1>")
	)
	(segment
		(start 197.4215 -307.139086)
		(end 196.742812 -307.817774)
		(width 0.18288)
		(layer "In11.Cu")
		(net "M_H_CPU1_SA_DQS_DP<1>")
	)
	(segment
		(start 137.790682 -282.086558)
		(end 137.781792 -282.081478)
		(width 0.088646)
		(layer "In11.Cu")
		(net "M_H_CPU1_SA_DQS_DP<1>")
	)
	(segment
		(start 137.499344 -281.601926)
		(end 137.499344 -281.59202)
		(width 0.088646)
		(layer "In11.Cu")
		(net "M_H_CPU1_SA_DQS_DP<1>")
	)
	(segment
		(start 174.83836 -310.860694)
		(end 174.77105 -311.023508)
		(width 0.18288)
		(layer "In11.Cu")
		(net "M_H_CPU1_SA_DQS_DP<1>")
	)
	(segment
		(start 124.259848 -275.323554)
		(end 124.106178 -275.21916)
		(width 0.088646)
		(layer "In11.Cu")
		(net "M_H_CPU1_SA_DQS_DP<1>")
	)
	(segment
		(start 166.812722 -308.66588)
		(end 166.688262 -308.79034)
		(width 0.18288)
		(layer "In11.Cu")
		(net "M_H_CPU1_SA_DQS_DP<1>")
	)
	(segment
		(start 201.525124 -303.105566)
		(end 201.23404 -303.39665)
		(width 0.18288)
		(layer "In11.Cu")
		(net "M_H_CPU1_SA_DQS_DP<1>")
	)
	(segment
		(start 138.641074 -283.244036)
		(end 138.576558 -283.17952)
		(width 0.088646)
		(layer "In11.Cu")
		(net "M_H_CPU1_SA_DQS_DP<1>")
	)
	(segment
		(start 176.351946 -310.540654)
		(end 175.611028 -310.540654)
		(width 0.18288)
		(layer "In11.Cu")
		(net "M_H_CPU1_SA_DQS_DP<1>")
	)
	(segment
		(start 126.034292 -277.032974)
		(end 126.043182 -277.027894)
		(width 0.088646)
		(layer "In11.Cu")
		(net "M_H_CPU1_SA_DQS_DP<1>")
	)
	(segment
		(start 196.178678 -308.381908)
		(end 195.79082 -308.769766)
		(width 0.18288)
		(layer "In11.Cu")
		(net "M_H_CPU1_SA_DQS_DP<1>")
	)
	(segment
		(start 161.871152 -309.54091)
		(end 161.198306 -309.54091)
		(width 0.18288)
		(layer "In11.Cu")
		(net "M_H_CPU1_SA_DQS_DP<1>")
	)
	(segment
		(start 164.591492 -309.54091)
		(end 164.014912 -309.54091)
		(width 0.18288)
		(layer "In11.Cu")
		(net "M_H_CPU1_SA_DQS_DP<1>")
	)
	(segment
		(start 163.217352 -309.54091)
		(end 162.668712 -309.54091)
		(width 0.18288)
		(layer "In11.Cu")
		(net "M_H_CPU1_SA_DQS_DP<1>")
	)
	(segment
		(start 166.688262 -308.79034)
		(end 166.139622 -308.79034)
		(width 0.18288)
		(layer "In11.Cu")
		(net "M_H_CPU1_SA_DQS_DP<1>")
	)
	(segment
		(start 194.568064 -309.607966)
		(end 193.994024 -309.607966)
		(width 0.18288)
		(layer "In11.Cu")
		(net "M_H_CPU1_SA_DQS_DP<1>")
	)
	(segment
		(start 188.111384 -309.94096)
		(end 187.589668 -309.94096)
		(width 0.18288)
		(layer "In11.Cu")
		(net "M_H_CPU1_SA_DQS_DP<1>")
	)
	(segment
		(start 156.5656 -307.725064)
		(end 156.389578 -307.725064)
		(width 0.18288)
		(layer "In11.Cu")
		(net "M_H_CPU1_SA_DQS_DP<1>")
	)
	(segment
		(start 176.602136 -310.790844)
		(end 176.351946 -310.540654)
		(width 0.18288)
		(layer "In11.Cu")
		(net "M_H_CPU1_SA_DQS_DP<1>")
	)
	(segment
		(start 180.542184 -310.38546)
		(end 180.417724 -310.261)
		(width 0.18288)
		(layer "In11.Cu")
		(net "M_H_CPU1_SA_DQS_DP<1>")
	)
	(segment
		(start 198.153782 -307.139086)
		(end 197.4215 -307.139086)
		(width 0.18288)
		(layer "In11.Cu")
		(net "M_H_CPU1_SA_DQS_DP<1>")
	)
	(segment
		(start 177.123852 -310.790844)
		(end 176.602136 -310.790844)
		(width 0.18288)
		(layer "In11.Cu")
		(net "M_H_CPU1_SA_DQS_DP<1>")
	)
	(segment
		(start 132.238496 -279.639776)
		(end 132.228082 -279.645872)
		(width 0.088646)
		(layer "In11.Cu")
		(net "M_H_CPU1_SA_DQS_DP<1>")
	)
	(segment
		(start 188.376306 -309.676038)
		(end 188.111384 -309.94096)
		(width 0.18288)
		(layer "In11.Cu")
		(net "M_H_CPU1_SA_DQS_DP<1>")
	)
	(segment
		(start 124.469906 -275.482812)
		(end 124.29236 -275.34997)
		(width 0.088646)
		(layer "In11.Cu")
		(net "M_H_CPU1_SA_DQS_DP<1>")
	)
	(segment
		(start 185.01487 -309.667656)
		(end 183.61279 -309.667656)
		(width 0.18288)
		(layer "In11.Cu")
		(net "M_H_CPU1_SA_DQS_DP<1>")
	)
	(segment
		(start 137.969244 -282.42006)
		(end 137.969244 -282.405836)
		(width 0.088646)
		(layer "In11.Cu")
		(net "M_H_CPU1_SA_DQS_DP<1>")
	)
	(segment
		(start 137.320782 -281.272742)
		(end 137.311892 -281.267662)
		(width 0.088646)
		(layer "In11.Cu")
		(net "M_H_CPU1_SA_DQS_DP<1>")
	)
	(segment
		(start 180.417724 -310.261)
		(end 179.869084 -310.261)
		(width 0.18288)
		(layer "In11.Cu")
		(net "M_H_CPU1_SA_DQS_DP<1>")
	)
	(segment
		(start 126.036832 -276.385782)
		(end 126.035054 -276.384766)
		(width 0.088646)
		(layer "In11.Cu")
		(net "M_H_CPU1_SA_DQS_DP<1>")
	)
	(segment
		(start 170.782488 -310.905398)
		(end 170.394376 -310.517286)
		(width 0.18288)
		(layer "In11.Cu")
		(net "M_H_CPU1_SA_DQS_DP<1>")
	)
	(segment
		(start 162.668712 -309.54091)
		(end 162.544252 -309.66537)
		(width 0.18288)
		(layer "In11.Cu")
		(net "M_H_CPU1_SA_DQS_DP<1>")
	)
	(segment
		(start 155.049474 -306.208938)
		(end 154.661616 -305.82108)
		(width 0.18288)
		(layer "In11.Cu")
		(net "M_H_CPU1_SA_DQS_DP<1>")
	)
	(segment
		(start 196.742812 -307.993796)
		(end 196.3547 -308.381908)
		(width 0.18288)
		(layer "In11.Cu")
		(net "M_H_CPU1_SA_DQS_DP<1>")
	)
	(segment
		(start 126.043436 -278.017224)
		(end 126.034546 -278.012144)
		(width 0.088646)
		(layer "In11.Cu")
		(net "M_H_CPU1_SA_DQS_DP<1>")
	)
	(segment
		(start 128.392682 -278.83104)
		(end 128.383792 -278.82596)
		(width 0.088646)
		(layer "In11.Cu")
		(net "M_H_CPU1_SA_DQS_DP<1>")
	)
	(segment
		(start 170.95851 -310.905398)
		(end 170.782488 -310.905398)
		(width 0.18288)
		(layer "In11.Cu")
		(net "M_H_CPU1_SA_DQS_DP<1>")
	)
	(segment
		(start 183.019446 -310.261)
		(end 181.215284 -310.261)
		(width 0.18288)
		(layer "In11.Cu")
		(net "M_H_CPU1_SA_DQS_DP<1>")
	)
	(segment
		(start 158.93288 -308.984396)
		(end 158.394654 -308.8767)
		(width 0.18288)
		(layer "In11.Cu")
		(net "M_H_CPU1_SA_DQS_DP<1>")
	)
	(segment
		(start 126.043182 -276.389338)
		(end 126.04242 -276.38883)
		(width 0.088646)
		(layer "In11.Cu")
		(net "M_H_CPU1_SA_DQS_DP<1>")
	)
	(segment
		(start 181.215284 -310.261)
		(end 181.090824 -310.38546)
		(width 0.18288)
		(layer "In11.Cu")
		(net "M_H_CPU1_SA_DQS_DP<1>")
	)
	(segment
		(start 155.049474 -306.38496)
		(end 155.049474 -306.208938)
		(width 0.18288)
		(layer "In11.Cu")
		(net "M_H_CPU1_SA_DQS_DP<1>")
	)
	(segment
		(start 202.701144 -303.296574)
		(end 202.176634 -303.296574)
		(width 0.18288)
		(layer "In11.Cu")
		(net "M_H_CPU1_SA_DQS_DP<1>")
	)
	(segment
		(start 173.260258 -311.37606)
		(end 172.995336 -311.640982)
		(width 0.18288)
		(layer "In11.Cu")
		(net "M_H_CPU1_SA_DQS_DP<1>")
	)
	(segment
		(start 172.203618 -311.342532)
		(end 171.395644 -311.342532)
		(width 0.18288)
		(layer "In11.Cu")
		(net "M_H_CPU1_SA_DQS_DP<1>")
	)
	(segment
		(start 195.406264 -308.769766)
		(end 194.568064 -309.607966)
		(width 0.18288)
		(layer "In11.Cu")
		(net "M_H_CPU1_SA_DQS_DP<1>")
	)
	(segment
		(start 126.037594 -276.38629)
		(end 126.036832 -276.385782)
		(width 0.088646)
		(layer "In11.Cu")
		(net "M_H_CPU1_SA_DQS_DP<1>")
	)
	(segment
		(start 135.440928 -279.644856)
		(end 135.433054 -279.640284)
		(width 0.088646)
		(layer "In11.Cu")
		(net "M_H_CPU1_SA_DQS_DP<1>")
	)
	(segment
		(start 124.106178 -275.21916)
		(end 123.967748 -275.08073)
		(width 0.088646)
		(layer "In11.Cu")
		(net "M_H_CPU1_SA_DQS_DP<1>")
	)
	(segment
		(start 124.26188 -275.326856)
		(end 124.259848 -275.323554)
		(width 0.088646)
		(layer "In11.Cu")
		(net "M_H_CPU1_SA_DQS_DP<1>")
	)
	(segment
		(start 156.001466 -307.16093)
		(end 155.613608 -306.773072)
		(width 0.18288)
		(layer "In11.Cu")
		(net "M_H_CPU1_SA_DQS_DP<1>")
	)
	(segment
		(start 201.23404 -303.39665)
		(end 201.23404 -304.292)
		(width 0.18288)
		(layer "In11.Cu")
		(net "M_H_CPU1_SA_DQS_DP<1>")
	)
	(segment
		(start 158.296864 -308.730142)
		(end 157.389068 -308.548532)
		(width 0.18288)
		(layer "In11.Cu")
		(net "M_H_CPU1_SA_DQS_DP<1>")
	)
	(segment
		(start 139.04595 -284.502352)
		(end 139.04595 -283.740352)
		(width 0.18288)
		(layer "In11.Cu")
		(net "M_H_CPU1_SA_DQS_DP<1>")
	)
	(segment
		(start 163.341812 -309.66537)
		(end 163.217352 -309.54091)
		(width 0.18288)
		(layer "In11.Cu")
		(net "M_H_CPU1_SA_DQS_DP<1>")
	)
	(segment
		(start 200.27011 -305.25593)
		(end 200.27011 -305.636676)
		(width 0.18288)
		(layer "In11.Cu")
		(net "M_H_CPU1_SA_DQS_DP<1>")
	)
	(segment
		(start 128.849628 -279.637236)
		(end 128.84785 -279.63622)
		(width 0.088646)
		(layer "In11.Cu")
		(net "M_H_CPU1_SA_DQS_DP<1>")
	)
	(segment
		(start 193.994024 -309.607966)
		(end 193.044318 -310.557672)
		(width 0.18288)
		(layer "In11.Cu")
		(net "M_H_CPU1_SA_DQS_DP<1>")
	)
	(segment
		(start 200.27011 -305.636676)
		(end 199.543924 -306.362862)
		(width 0.18288)
		(layer "In11.Cu")
		(net "M_H_CPU1_SA_DQS_DP<1>")
	)
	(segment
		(start 126.035054 -276.384766)
		(end 126.034292 -276.384258)
		(width 0.088646)
		(layer "In11.Cu")
		(net "M_H_CPU1_SA_DQS_DP<1>")
	)
	(segment
		(start 125.751844 -277.536656)
		(end 125.751844 -277.512526)
		(width 0.088646)
		(layer "In11.Cu")
		(net "M_H_CPU1_SA_DQS_DP<1>")
	)
	(segment
		(start 165.466522 -308.66588)
		(end 164.591492 -309.54091)
		(width 0.18288)
		(layer "In11.Cu")
		(net "M_H_CPU1_SA_DQS_DP<1>")
	)
	(segment
		(start 179.869084 -310.261)
		(end 179.407058 -309.798974)
		(width 0.18288)
		(layer "In11.Cu")
		(net "M_H_CPU1_SA_DQS_DP<1>")
	)
	(segment
		(start 195.79082 -308.769766)
		(end 195.406264 -308.769766)
		(width 0.18288)
		(layer "In11.Cu")
		(net "M_H_CPU1_SA_DQS_DP<1>")
	)
	(segment
		(start 189.869064 -310.507634)
		(end 189.037468 -309.676038)
		(width 0.18288)
		(layer "In11.Cu")
		(net "M_H_CPU1_SA_DQS_DP<1>")
	)
	(segment
		(start 163.890452 -309.66537)
		(end 163.341812 -309.66537)
		(width 0.18288)
		(layer "In11.Cu")
		(net "M_H_CPU1_SA_DQS_DP<1>")
	)
	(segment
		(start 179.407058 -309.798974)
		(end 178.839876 -309.798974)
		(width 0.18288)
		(layer "In11.Cu")
		(net "M_H_CPU1_SA_DQS_DP<1>")
	)
	(segment
		(start 162.544252 -309.66537)
		(end 161.995612 -309.66537)
		(width 0.18288)
		(layer "In11.Cu")
		(net "M_H_CPU1_SA_DQS_DP<1>")
	)
	(segment
		(start 175.611028 -310.540654)
		(end 174.83836 -310.860694)
		(width 0.18288)
		(layer "In11.Cu")
		(net "M_H_CPU1_SA_DQS_DP<1>")
	)
	(segment
		(start 128.868678 -279.648412)
		(end 128.853946 -279.639776)
		(width 0.088646)
		(layer "In11.Cu")
		(net "M_H_CPU1_SA_DQS_DP<1>")
	)
	(segment
		(start 145.311876 -292.291516)
		(end 145.311876 -290.768278)
		(width 0.18288)
		(layer "In11.Cu")
		(net "M_H_CPU1_SA_DQS_DP<1>")
	)
	(segment
		(start 196.742812 -307.817774)
		(end 196.742812 -307.993796)
		(width 0.18288)
		(layer "In11.Cu")
		(net "M_H_CPU1_SA_DQS_DP<1>")
	)
	(segment
		(start 135.61949 -279.971754)
		(end 135.61949 -279.964134)
		(width 0.088646)
		(layer "In11.Cu")
		(net "M_H_CPU1_SA_DQS_DP<1>")
	)
	(segment
		(start 136.089644 -280.78811)
		(end 136.089644 -280.778204)
		(width 0.088646)
		(layer "In11.Cu")
		(net "M_H_CPU1_SA_DQS_DP<1>")
	)
	(segment
		(start 185.13933 -309.792116)
		(end 185.01487 -309.667656)
		(width 0.18288)
		(layer "In11.Cu")
		(net "M_H_CPU1_SA_DQS_DP<1>")
	)
	(segment
		(start 192.444624 -310.557672)
		(end 192.211452 -310.790844)
		(width 0.18288)
		(layer "In11.Cu")
		(net "M_H_CPU1_SA_DQS_DP<1>")
	)
	(segment
		(start 192.211452 -310.790844)
		(end 191.689736 -310.790844)
		(width 0.18288)
		(layer "In11.Cu")
		(net "M_H_CPU1_SA_DQS_DP<1>")
	)
	(segment
		(start 158.394654 -308.8767)
		(end 158.296864 -308.730142)
		(width 0.18288)
		(layer "In11.Cu")
		(net "M_H_CPU1_SA_DQS_DP<1>")
	)
	(segment
		(start 164.014912 -309.54091)
		(end 163.890452 -309.66537)
		(width 0.18288)
		(layer "In11.Cu")
		(net "M_H_CPU1_SA_DQS_DP<1>")
	)
	(segment
		(start 124.578872 -275.544026)
		(end 124.469906 -275.482812)
		(width 0.088646)
		(layer "In11.Cu")
		(net "M_H_CPU1_SA_DQS_DP<1>")
	)
	(segment
		(start 156.001466 -307.336952)
		(end 156.001466 -307.16093)
		(width 0.18288)
		(layer "In11.Cu")
		(net "M_H_CPU1_SA_DQS_DP<1>")
	)
	(segment
		(start 171.395644 -311.342532)
		(end 170.95851 -310.905398)
		(width 0.18288)
		(layer "In11.Cu")
		(net "M_H_CPU1_SA_DQS_DP<1>")
	)
	(segment
		(start 160.512252 -309.173372)
		(end 159.079184 -308.88686)
		(width 0.18288)
		(layer "In11.Cu")
		(net "M_H_CPU1_SA_DQS_DP<1>")
	)
	(segment
		(start 170.394376 -310.517286)
		(end 170.394376 -310.341264)
		(width 0.18288)
		(layer "In11.Cu")
		(net "M_H_CPU1_SA_DQS_DP<1>")
	)
	(segment
		(start 145.311876 -290.768278)
		(end 139.04595 -284.502352)
		(width 0.18288)
		(layer "In11.Cu")
		(net "M_H_CPU1_SA_DQS_DP<1>")
	)
	(segment
		(start 155.437586 -306.773072)
		(end 155.049474 -306.38496)
		(width 0.18288)
		(layer "In11.Cu")
		(net "M_H_CPU1_SA_DQS_DP<1>")
	)
	(segment
		(start 199.543924 -306.362862)
		(end 198.930006 -306.362862)
		(width 0.18288)
		(layer "In11.Cu")
		(net "M_H_CPU1_SA_DQS_DP<1>")
	)
	(arc
		(start 126.504192 -278.82596)
		(mid 126.301369 -278.625729)
		(end 126.221998 -278.351996)
		(width 0.088646)
		(layer "In11.Cu")
		(net "M_H_CPU1_SA_DQS_DP<1>")
	)
	(arc
		(start 136.089644 -280.778204)
		(mid 136.041965 -280.595304)
		(end 135.911082 -280.458926)
		(width 0.088646)
		(layer "In11.Cu")
		(net "M_H_CPU1_SA_DQS_DP<1>")
	)
	(arc
		(start 126.221998 -278.336502)
		(mid 126.174319 -278.153602)
		(end 126.043436 -278.017224)
		(width 0.088646)
		(layer "In11.Cu")
		(net "M_H_CPU1_SA_DQS_DP<1>")
	)
	(arc
		(start 125.751844 -277.512526)
		(mid 125.829955 -277.235577)
		(end 126.034292 -277.032974)
		(width 0.088646)
		(layer "In11.Cu")
		(net "M_H_CPU1_SA_DQS_DP<1>")
	)
	(arc
		(start 138.305032 -282.932124)
		(mid 138.279278 -282.912691)
		(end 138.251946 -282.895548)
		(width 0.088646)
		(layer "In11.Cu")
		(net "M_H_CPU1_SA_DQS_DP<1>")
	)
	(arc
		(start 125.75159 -275.880068)
		(mid 125.700536 -275.705488)
		(end 125.573282 -275.575522)
		(width 0.088646)
		(layer "In11.Cu")
		(net "M_H_CPU1_SA_DQS_DP<1>")
	)
	(arc
		(start 125.564392 -275.570442)
		(mid 125.377194 -275.520299)
		(end 125.189996 -275.570442)
		(width 0.088646)
		(layer "In11.Cu")
		(net "M_H_CPU1_SA_DQS_DP<1>")
	)
	(arc
		(start 126.034292 -276.384258)
		(mid 125.829957 -276.181653)
		(end 125.751844 -275.904706)
		(width 0.088646)
		(layer "In11.Cu")
		(net "M_H_CPU1_SA_DQS_DP<1>")
	)
	(arc
		(start 126.034546 -278.012144)
		(mid 125.831065 -277.81134)
		(end 125.751844 -277.536656)
		(width 0.088646)
		(layer "In11.Cu")
		(net "M_H_CPU1_SA_DQS_DP<1>")
	)
	(arc
		(start 134.492746 -279.639776)
		(mid 134.305548 -279.589633)
		(end 134.11835 -279.639776)
		(width 0.088646)
		(layer "In11.Cu")
		(net "M_H_CPU1_SA_DQS_DP<1>")
	)
	(arc
		(start 137.499344 -281.59202)
		(mid 137.451665 -281.40912)
		(end 137.320782 -281.272742)
		(width 0.088646)
		(layer "In11.Cu")
		(net "M_H_CPU1_SA_DQS_DP<1>")
	)
	(arc
		(start 129.793746 -279.639776)
		(mid 129.606548 -279.589633)
		(end 129.41935 -279.639776)
		(width 0.088646)
		(layer "In11.Cu")
		(net "M_H_CPU1_SA_DQS_DP<1>")
	)
	(arc
		(start 134.11835 -279.639776)
		(mid 133.844151 -279.715611)
		(end 133.567678 -279.648412)
		(width 0.088646)
		(layer "In11.Cu")
		(net "M_H_CPU1_SA_DQS_DP<1>")
	)
	(arc
		(start 136.937496 -281.267662)
		(mid 136.654794 -281.343438)
		(end 136.372092 -281.267662)
		(width 0.088646)
		(layer "In11.Cu")
		(net "M_H_CPU1_SA_DQS_DP<1>")
	)
	(arc
		(start 135.61949 -279.964134)
		(mid 135.571811 -279.781234)
		(end 135.440928 -279.644856)
		(width 0.088646)
		(layer "In11.Cu")
		(net "M_H_CPU1_SA_DQS_DP<1>")
	)
	(arc
		(start 137.781792 -282.081478)
		(mid 137.577457 -281.878873)
		(end 137.499344 -281.601926)
		(width 0.088646)
		(layer "In11.Cu")
		(net "M_H_CPU1_SA_DQS_DP<1>")
	)
	(arc
		(start 135.902192 -280.453846)
		(mid 135.69712 -280.250167)
		(end 135.61949 -279.971754)
		(width 0.088646)
		(layer "In11.Cu")
		(net "M_H_CPU1_SA_DQS_DP<1>")
	)
	(arc
		(start 126.043182 -277.027894)
		(mid 126.221779 -276.708616)
		(end 126.043182 -276.389338)
		(width 0.088646)
		(layer "In11.Cu")
		(net "M_H_CPU1_SA_DQS_DP<1>")
	)
	(arc
		(start 136.372092 -281.267662)
		(mid 136.167757 -281.065057)
		(end 136.089644 -280.78811)
		(width 0.088646)
		(layer "In11.Cu")
		(net "M_H_CPU1_SA_DQS_DP<1>")
	)
	(arc
		(start 128.84785 -279.63622)
		(mid 128.645263 -279.429869)
		(end 128.571244 -279.150318)
		(width 0.088646)
		(layer "In11.Cu")
		(net "M_H_CPU1_SA_DQS_DP<1>")
	)
	(arc
		(start 128.571244 -279.150318)
		(mid 128.523565 -278.967418)
		(end 128.392682 -278.83104)
		(width 0.088646)
		(layer "In11.Cu")
		(net "M_H_CPU1_SA_DQS_DP<1>")
	)
	(arc
		(start 137.311892 -281.267662)
		(mid 137.124694 -281.217519)
		(end 136.937496 -281.267662)
		(width 0.088646)
		(layer "In11.Cu")
		(net "M_H_CPU1_SA_DQS_DP<1>")
	)
	(arc
		(start 127.054864 -278.834596)
		(mid 126.778389 -278.901916)
		(end 126.504192 -278.82596)
		(width 0.088646)
		(layer "In11.Cu")
		(net "M_H_CPU1_SA_DQS_DP<1>")
	)
	(arc
		(start 125.175264 -275.579078)
		(mid 124.898823 -275.646244)
		(end 124.624592 -275.570442)
		(width 0.088646)
		(layer "In11.Cu")
		(net "M_H_CPU1_SA_DQS_DP<1>")
	)
	(arc
		(start 133.168136 -279.645872)
		(mid 132.889704 -279.715718)
		(end 132.612892 -279.639776)
		(width 0.088646)
		(layer "In11.Cu")
		(net "M_H_CPU1_SA_DQS_DP<1>")
	)
	(arc
		(start 129.41935 -279.639776)
		(mid 129.145151 -279.715611)
		(end 128.868678 -279.648412)
		(width 0.088646)
		(layer "In11.Cu")
		(net "M_H_CPU1_SA_DQS_DP<1>")
	)
	(arc
		(start 135.057642 -279.639776)
		(mid 134.775194 -279.715425)
		(end 134.492746 -279.639776)
		(width 0.088646)
		(layer "In11.Cu")
		(net "M_H_CPU1_SA_DQS_DP<1>")
	)
	(arc
		(start 127.443992 -278.82596)
		(mid 127.256794 -278.775817)
		(end 127.069596 -278.82596)
		(width 0.088646)
		(layer "In11.Cu")
		(net "M_H_CPU1_SA_DQS_DP<1>")
	)
	(arc
		(start 132.228082 -279.645872)
		(mid 131.949904 -279.715595)
		(end 131.673346 -279.639776)
		(width 0.088646)
		(layer "In11.Cu")
		(net "M_H_CPU1_SA_DQS_DP<1>")
	)
	(arc
		(start 138.576558 -283.17952)
		(mid 138.443673 -283.052663)
		(end 138.305032 -282.932124)
		(width 0.088646)
		(layer "In11.Cu")
		(net "M_H_CPU1_SA_DQS_DP<1>")
	)
	(arc
		(start 131.673346 -279.639776)
		(mid 131.486148 -279.589633)
		(end 131.29895 -279.639776)
		(width 0.088646)
		(layer "In11.Cu")
		(net "M_H_CPU1_SA_DQS_DP<1>")
	)
	(arc
		(start 135.432038 -279.639776)
		(mid 135.24484 -279.589633)
		(end 135.057642 -279.639776)
		(width 0.088646)
		(layer "In11.Cu")
		(net "M_H_CPU1_SA_DQS_DP<1>")
	)
	(arc
		(start 130.733546 -279.639776)
		(mid 130.546348 -279.589633)
		(end 130.35915 -279.639776)
		(width 0.088646)
		(layer "In11.Cu")
		(net "M_H_CPU1_SA_DQS_DP<1>")
	)
	(arc
		(start 131.29895 -279.639776)
		(mid 131.024751 -279.715611)
		(end 130.748278 -279.648412)
		(width 0.088646)
		(layer "In11.Cu")
		(net "M_H_CPU1_SA_DQS_DP<1>")
	)
	(arc
		(start 137.969244 -282.405836)
		(mid 137.921565 -282.222936)
		(end 137.790682 -282.086558)
		(width 0.088646)
		(layer "In11.Cu")
		(net "M_H_CPU1_SA_DQS_DP<1>")
	)
	(arc
		(start 132.612892 -279.639776)
		(mid 132.425694 -279.589633)
		(end 132.238496 -279.639776)
		(width 0.088646)
		(layer "In11.Cu")
		(net "M_H_CPU1_SA_DQS_DP<1>")
	)
	(arc
		(start 133.552946 -279.639776)
		(mid 133.365748 -279.589633)
		(end 133.17855 -279.639776)
		(width 0.088646)
		(layer "In11.Cu")
		(net "M_H_CPU1_SA_DQS_DP<1>")
	)
	(arc
		(start 127.994664 -278.834596)
		(mid 127.718189 -278.901916)
		(end 127.443992 -278.82596)
		(width 0.088646)
		(layer "In11.Cu")
		(net "M_H_CPU1_SA_DQS_DP<1>")
	)
	(arc
		(start 130.35915 -279.639776)
		(mid 130.076448 -279.715552)
		(end 129.793746 -279.639776)
		(width 0.088646)
		(layer "In11.Cu")
		(net "M_H_CPU1_SA_DQS_DP<1>")
	)
	(arc
		(start 138.251946 -282.895548)
		(mid 138.048465 -282.694744)
		(end 137.969244 -282.42006)
		(width 0.088646)
		(layer "In11.Cu")
		(net "M_H_CPU1_SA_DQS_DP<1>")
	)
	(arc
		(start 128.383792 -278.82596)
		(mid 128.196594 -278.775817)
		(end 128.009396 -278.82596)
		(width 0.088646)
		(layer "In11.Cu")
		(net "M_H_CPU1_SA_DQS_DP<1>")
	)
	(segment
		(start 206.9973 -313.341766)
		(end 207.023208 -313.341766)
		(width 0.101854)
		(layer "F.Cu")
		(net "M_H_CPU1_SA_DQS_DP<0>")
	)
	(segment
		(start 209.812382 -313.045348)
		(end 210.182968 -313.045348)
		(width 0.20066)
		(layer "F.Cu")
		(net "M_H_CPU1_SA_DQS_DP<0>")
	)
	(segment
		(start 207.023208 -313.341766)
		(end 209.18043 -313.341766)
		(width 0.1016)
		(layer "F.Cu")
		(net "M_H_CPU1_SA_DQS_DP<0>")
	)
	(segment
		(start 210.78952 -312.634884)
		(end 211.071206 -312.91657)
		(width 0.20066)
		(layer "F.Cu")
		(net "M_H_CPU1_SA_DQS_DP<0>")
	)
	(segment
		(start 206.857854 -313.341766)
		(end 206.9973 -313.341766)
		(width 0.20066)
		(layer "F.Cu")
		(net "M_H_CPU1_SA_DQS_DP<0>")
	)
	(segment
		(start 206.606648 -313.09056)
		(end 206.857854 -313.341766)
		(width 0.20066)
		(layer "F.Cu")
		(net "M_H_CPU1_SA_DQS_DP<0>")
	)
	(segment
		(start 205.920848 -313.09056)
		(end 206.606648 -313.09056)
		(width 0.20066)
		(layer "F.Cu")
		(net "M_H_CPU1_SA_DQS_DP<0>")
	)
	(segment
		(start 209.509868 -313.347862)
		(end 209.812382 -313.045348)
		(width 0.20066)
		(layer "F.Cu")
		(net "M_H_CPU1_SA_DQS_DP<0>")
	)
	(segment
		(start 127.257048 -276.986492)
		(end 127.257048 -277.522178)
		(width 0.20066)
		(layer "F.Cu")
		(net "M_H_CPU1_SA_DQS_DP<0>")
	)
	(segment
		(start 204.905864 -312.676032)
		(end 205.50632 -312.676032)
		(width 0.20066)
		(layer "F.Cu")
		(net "M_H_CPU1_SA_DQS_DP<0>")
	)
	(segment
		(start 204.076046 -312.91657)
		(end 204.665326 -312.91657)
		(width 0.20066)
		(layer "F.Cu")
		(net "M_H_CPU1_SA_DQS_DP<0>")
	)
	(segment
		(start 209.186526 -313.347862)
		(end 209.509868 -313.347862)
		(width 0.20066)
		(layer "F.Cu")
		(net "M_H_CPU1_SA_DQS_DP<0>")
	)
	(segment
		(start 205.50632 -312.676032)
		(end 205.920848 -313.09056)
		(width 0.20066)
		(layer "F.Cu")
		(net "M_H_CPU1_SA_DQS_DP<0>")
	)
	(segment
		(start 202.971146 -312.91657)
		(end 204.076046 -312.91657)
		(width 0.20066)
		(layer "F.Cu")
		(net "M_H_CPU1_SA_DQS_DP<0>")
	)
	(segment
		(start 127.257048 -277.522178)
		(end 127.256794 -277.522432)
		(width 0.20066)
		(layer "F.Cu")
		(net "M_H_CPU1_SA_DQS_DP<0>")
	)
	(segment
		(start 210.182968 -313.045348)
		(end 210.593432 -312.634884)
		(width 0.20066)
		(layer "F.Cu")
		(net "M_H_CPU1_SA_DQS_DP<0>")
	)
	(segment
		(start 209.18043 -313.341766)
		(end 209.186526 -313.347862)
		(width 0.1016)
		(layer "F.Cu")
		(net "M_H_CPU1_SA_DQS_DP<0>")
	)
	(segment
		(start 204.665326 -312.91657)
		(end 204.905864 -312.676032)
		(width 0.20066)
		(layer "F.Cu")
		(net "M_H_CPU1_SA_DQS_DP<0>")
	)
	(segment
		(start 211.071206 -312.91657)
		(end 211.619846 -312.91657)
		(width 0.20066)
		(layer "F.Cu")
		(net "M_H_CPU1_SA_DQS_DP<0>")
	)
	(segment
		(start 210.593432 -312.634884)
		(end 210.78952 -312.634884)
		(width 0.20066)
		(layer "F.Cu")
		(net "M_H_CPU1_SA_DQS_DP<0>")
	)
	(segment
		(start 140.283946 -281.058874)
		(end 140.142468 -281.058874)
		(width 0.088646)
		(layer "In6.Cu")
		(net "M_H_CPU1_SA_DQS_DP<0>")
	)
	(segment
		(start 161.620708 -305.691032)
		(end 161.361374 -305.431698)
		(width 0.18288)
		(layer "In6.Cu")
		(net "M_H_CPU1_SA_DQS_DP<0>")
	)
	(segment
		(start 184.37606 -312.201306)
		(end 183.82996 -312.201306)
		(width 0.18288)
		(layer "In6.Cu")
		(net "M_H_CPU1_SA_DQS_DP<0>")
	)
	(segment
		(start 198.415148 -312.865008)
		(end 196.840602 -312.865008)
		(width 0.18288)
		(layer "In6.Cu")
		(net "M_H_CPU1_SA_DQS_DP<0>")
	)
	(segment
		(start 199.956166 -312.316114)
		(end 199.831706 -312.191654)
		(width 0.18288)
		(layer "In6.Cu")
		(net "M_H_CPU1_SA_DQS_DP<0>")
	)
	(segment
		(start 196.840602 -312.865008)
		(end 196.286628 -312.311034)
		(width 0.18288)
		(layer "In6.Cu")
		(net "M_H_CPU1_SA_DQS_DP<0>")
	)
	(segment
		(start 139.670536 -280.318718)
		(end 139.586462 -280.115772)
		(width 0.088646)
		(layer "In6.Cu")
		(net "M_H_CPU1_SA_DQS_DP<0>")
	)
	(segment
		(start 160.754314 -305.431698)
		(end 160.629854 -305.556158)
		(width 0.18288)
		(layer "In6.Cu")
		(net "M_H_CPU1_SA_DQS_DP<0>")
	)
	(segment
		(start 160.083754 -305.556158)
		(end 159.959294 -305.431698)
		(width 0.18288)
		(layer "In6.Cu")
		(net "M_H_CPU1_SA_DQS_DP<0>")
	)
	(segment
		(start 166.744142 -308.270402)
		(end 164.39896 -306.703222)
		(width 0.18288)
		(layer "In6.Cu")
		(net "M_H_CPU1_SA_DQS_DP<0>")
	)
	(segment
		(start 140.142468 -281.058874)
		(end 139.979908 -280.896314)
		(width 0.088646)
		(layer "In6.Cu")
		(net "M_H_CPU1_SA_DQS_DP<0>")
	)
	(segment
		(start 182.337456 -312.201306)
		(end 181.890162 -311.754012)
		(width 0.18288)
		(layer "In6.Cu")
		(net "M_H_CPU1_SA_DQS_DP<0>")
	)
	(segment
		(start 175.649636 -308.937914)
		(end 175.103536 -308.937914)
		(width 0.18288)
		(layer "In6.Cu")
		(net "M_H_CPU1_SA_DQS_DP<0>")
	)
	(segment
		(start 183.7055 -312.325766)
		(end 183.1594 -312.325766)
		(width 0.18288)
		(layer "In6.Cu")
		(net "M_H_CPU1_SA_DQS_DP<0>")
	)
	(segment
		(start 156.759148 -306.254404)
		(end 155.71851 -305.213766)
		(width 0.18288)
		(layer "In6.Cu")
		(net "M_H_CPU1_SA_DQS_DP<0>")
	)
	(segment
		(start 137.790682 -278.83104)
		(end 137.781792 -278.82596)
		(width 0.088646)
		(layer "In6.Cu")
		(net "M_H_CPU1_SA_DQS_DP<0>")
	)
	(segment
		(start 159.413194 -305.431698)
		(end 158.569152 -306.27574)
		(width 0.18288)
		(layer "In6.Cu")
		(net "M_H_CPU1_SA_DQS_DP<0>")
	)
	(segment
		(start 195.069968 -312.435494)
		(end 194.945508 -312.311034)
		(width 0.18288)
		(layer "In6.Cu")
		(net "M_H_CPU1_SA_DQS_DP<0>")
	)
	(segment
		(start 127.928878 -278.02078)
		(end 127.914146 -278.012144)
		(width 0.088646)
		(layer "In6.Cu")
		(net "M_H_CPU1_SA_DQS_DP<0>")
	)
	(segment
		(start 202.692254 -312.637678)
		(end 202.09891 -312.637678)
		(width 0.18288)
		(layer "In6.Cu")
		(net "M_H_CPU1_SA_DQS_DP<0>")
	)
	(segment
		(start 161.361374 -305.431698)
		(end 160.754314 -305.431698)
		(width 0.18288)
		(layer "In6.Cu")
		(net "M_H_CPU1_SA_DQS_DP<0>")
	)
	(segment
		(start 188.061092 -314.191142)
		(end 187.707016 -314.191142)
		(width 0.18288)
		(layer "In6.Cu")
		(net "M_H_CPU1_SA_DQS_DP<0>")
	)
	(segment
		(start 172.976286 -309.94096)
		(end 172.581316 -309.94096)
		(width 0.18288)
		(layer "In6.Cu")
		(net "M_H_CPU1_SA_DQS_DP<0>")
	)
	(segment
		(start 171.130722 -309.778654)
		(end 171.006262 -309.654194)
		(width 0.18288)
		(layer "In6.Cu")
		(net "M_H_CPU1_SA_DQS_DP<0>")
	)
	(segment
		(start 157.24759 -306.254404)
		(end 156.759148 -306.254404)
		(width 0.18288)
		(layer "In6.Cu")
		(net "M_H_CPU1_SA_DQS_DP<0>")
	)
	(segment
		(start 155.71851 -301.097188)
		(end 147.854162 -293.23284)
		(width 0.18288)
		(layer "In6.Cu")
		(net "M_H_CPU1_SA_DQS_DP<0>")
	)
	(segment
		(start 137.969244 -279.160224)
		(end 137.969244 -279.150318)
		(width 0.088646)
		(layer "In6.Cu")
		(net "M_H_CPU1_SA_DQS_DP<0>")
	)
	(segment
		(start 168.814496 -309.654194)
		(end 167.405304 -308.712616)
		(width 0.18288)
		(layer "In6.Cu")
		(net "M_H_CPU1_SA_DQS_DP<0>")
	)
	(segment
		(start 162.266122 -305.417728)
		(end 161.992818 -305.691032)
		(width 0.18288)
		(layer "In6.Cu")
		(net "M_H_CPU1_SA_DQS_DP<0>")
	)
	(segment
		(start 185.522108 -313.523376)
		(end 185.135774 -313.137042)
		(width 0.18288)
		(layer "In6.Cu")
		(net "M_H_CPU1_SA_DQS_DP<0>")
	)
	(segment
		(start 158.167578 -306.27574)
		(end 157.904942 -306.538376)
		(width 0.18288)
		(layer "In6.Cu")
		(net "M_H_CPU1_SA_DQS_DP<0>")
	)
	(segment
		(start 183.03494 -312.201306)
		(end 182.337456 -312.201306)
		(width 0.18288)
		(layer "In6.Cu")
		(net "M_H_CPU1_SA_DQS_DP<0>")
	)
	(segment
		(start 147.854162 -293.23284)
		(end 147.854162 -283.613606)
		(width 0.18288)
		(layer "In6.Cu")
		(net "M_H_CPU1_SA_DQS_DP<0>")
	)
	(segment
		(start 158.569152 -306.27574)
		(end 158.167578 -306.27574)
		(width 0.18288)
		(layer "In6.Cu")
		(net "M_H_CPU1_SA_DQS_DP<0>")
	)
	(segment
		(start 186.092846 -313.918092)
		(end 185.69813 -313.523376)
		(width 0.18288)
		(layer "In6.Cu")
		(net "M_H_CPU1_SA_DQS_DP<0>")
	)
	(segment
		(start 200.626726 -312.191654)
		(end 200.502266 -312.316114)
		(width 0.18288)
		(layer "In6.Cu")
		(net "M_H_CPU1_SA_DQS_DP<0>")
	)
	(segment
		(start 187.433966 -313.918092)
		(end 186.092846 -313.918092)
		(width 0.18288)
		(layer "In6.Cu")
		(net "M_H_CPU1_SA_DQS_DP<0>")
	)
	(segment
		(start 195.740528 -312.311034)
		(end 195.616068 -312.435494)
		(width 0.18288)
		(layer "In6.Cu")
		(net "M_H_CPU1_SA_DQS_DP<0>")
	)
	(segment
		(start 167.405304 -308.712616)
		(end 167.232838 -308.746906)
		(width 0.18288)
		(layer "In6.Cu")
		(net "M_H_CPU1_SA_DQS_DP<0>")
	)
	(segment
		(start 160.629854 -305.556158)
		(end 160.083754 -305.556158)
		(width 0.18288)
		(layer "In6.Cu")
		(net "M_H_CPU1_SA_DQS_DP<0>")
	)
	(segment
		(start 137.499344 -278.346408)
		(end 137.499344 -278.336502)
		(width 0.088646)
		(layer "In6.Cu")
		(net "M_H_CPU1_SA_DQS_DP<0>")
	)
	(segment
		(start 155.71851 -305.213766)
		(end 155.71851 -301.097188)
		(width 0.18288)
		(layer "In6.Cu")
		(net "M_H_CPU1_SA_DQS_DP<0>")
	)
	(segment
		(start 189.633352 -313.080654)
		(end 188.79439 -313.919616)
		(width 0.18288)
		(layer "In6.Cu")
		(net "M_H_CPU1_SA_DQS_DP<0>")
	)
	(segment
		(start 172.29455 -309.654194)
		(end 171.801282 -309.654194)
		(width 0.18288)
		(layer "In6.Cu")
		(net "M_H_CPU1_SA_DQS_DP<0>")
	)
	(segment
		(start 145.359374 -281.118818)
		(end 140.367258 -281.118818)
		(width 0.18288)
		(layer "In6.Cu")
		(net "M_H_CPU1_SA_DQS_DP<0>")
	)
	(segment
		(start 157.531562 -306.538376)
		(end 157.24759 -306.254404)
		(width 0.18288)
		(layer "In6.Cu")
		(net "M_H_CPU1_SA_DQS_DP<0>")
	)
	(segment
		(start 192.422018 -313.080654)
		(end 192.161668 -313.341004)
		(width 0.18288)
		(layer "In6.Cu")
		(net "M_H_CPU1_SA_DQS_DP<0>")
	)
	(segment
		(start 195.616068 -312.435494)
		(end 195.069968 -312.435494)
		(width 0.18288)
		(layer "In6.Cu")
		(net "M_H_CPU1_SA_DQS_DP<0>")
	)
	(segment
		(start 179.168298 -309.771796)
		(end 178.992276 -309.771796)
		(width 0.18288)
		(layer "In6.Cu")
		(net "M_H_CPU1_SA_DQS_DP<0>")
	)
	(segment
		(start 163.113466 -305.417728)
		(end 162.266122 -305.417728)
		(width 0.18288)
		(layer "In6.Cu")
		(net "M_H_CPU1_SA_DQS_DP<0>")
	)
	(segment
		(start 174.979076 -308.813454)
		(end 174.534576 -308.813454)
		(width 0.18288)
		(layer "In6.Cu")
		(net "M_H_CPU1_SA_DQS_DP<0>")
	)
	(segment
		(start 191.808608 -313.341004)
		(end 191.548258 -313.080654)
		(width 0.18288)
		(layer "In6.Cu")
		(net "M_H_CPU1_SA_DQS_DP<0>")
	)
	(segment
		(start 166.778432 -308.443122)
		(end 166.744142 -308.270402)
		(width 0.18288)
		(layer "In6.Cu")
		(net "M_H_CPU1_SA_DQS_DP<0>")
	)
	(segment
		(start 147.854162 -283.613606)
		(end 145.359374 -281.118818)
		(width 0.18288)
		(layer "In6.Cu")
		(net "M_H_CPU1_SA_DQS_DP<0>")
	)
	(segment
		(start 176.42586 -308.813454)
		(end 175.774096 -308.813454)
		(width 0.18288)
		(layer "In6.Cu")
		(net "M_H_CPU1_SA_DQS_DP<0>")
	)
	(segment
		(start 171.676822 -309.778654)
		(end 171.130722 -309.778654)
		(width 0.18288)
		(layer "In6.Cu")
		(net "M_H_CPU1_SA_DQS_DP<0>")
	)
	(segment
		(start 140.367258 -281.118818)
		(end 140.34389 -281.118818)
		(width 0.088646)
		(layer "In6.Cu")
		(net "M_H_CPU1_SA_DQS_DP<0>")
	)
	(segment
		(start 169.484294 -309.654194)
		(end 168.814496 -309.654194)
		(width 0.18288)
		(layer "In6.Cu")
		(net "M_H_CPU1_SA_DQS_DP<0>")
	)
	(segment
		(start 178.219862 -308.82336)
		(end 177.350928 -308.82336)
		(width 0.18288)
		(layer "In6.Cu")
		(net "M_H_CPU1_SA_DQS_DP<0>")
	)
	(segment
		(start 171.006262 -309.654194)
		(end 170.279314 -309.654194)
		(width 0.18288)
		(layer "In6.Cu")
		(net "M_H_CPU1_SA_DQS_DP<0>")
	)
	(segment
		(start 175.774096 -308.813454)
		(end 175.649636 -308.937914)
		(width 0.18288)
		(layer "In6.Cu")
		(net "M_H_CPU1_SA_DQS_DP<0>")
	)
	(segment
		(start 135.447024 -278.02078)
		(end 135.432292 -278.012144)
		(width 0.088646)
		(layer "In6.Cu")
		(net "M_H_CPU1_SA_DQS_DP<0>")
	)
	(segment
		(start 177.083466 -309.090822)
		(end 176.703228 -309.090822)
		(width 0.18288)
		(layer "In6.Cu")
		(net "M_H_CPU1_SA_DQS_DP<0>")
	)
	(segment
		(start 190.335662 -313.205114)
		(end 190.211202 -313.080654)
		(width 0.18288)
		(layer "In6.Cu")
		(net "M_H_CPU1_SA_DQS_DP<0>")
	)
	(segment
		(start 169.608754 -309.778654)
		(end 169.484294 -309.654194)
		(width 0.18288)
		(layer "In6.Cu")
		(net "M_H_CPU1_SA_DQS_DP<0>")
	)
	(segment
		(start 170.279314 -309.654194)
		(end 170.154854 -309.778654)
		(width 0.18288)
		(layer "In6.Cu")
		(net "M_H_CPU1_SA_DQS_DP<0>")
	)
	(segment
		(start 183.82996 -312.201306)
		(end 183.7055 -312.325766)
		(width 0.18288)
		(layer "In6.Cu")
		(net "M_H_CPU1_SA_DQS_DP<0>")
	)
	(segment
		(start 194.945508 -312.311034)
		(end 193.879216 -312.311034)
		(width 0.18288)
		(layer "In6.Cu")
		(net "M_H_CPU1_SA_DQS_DP<0>")
	)
	(segment
		(start 179.873148 -310.476646)
		(end 179.168298 -309.771796)
		(width 0.18288)
		(layer "In6.Cu")
		(net "M_H_CPU1_SA_DQS_DP<0>")
	)
	(segment
		(start 133.56336 -278.01824)
		(end 133.552946 -278.012144)
		(width 0.088646)
		(layer "In6.Cu")
		(net "M_H_CPU1_SA_DQS_DP<0>")
	)
	(segment
		(start 131.29895 -278.012144)
		(end 131.288536 -278.01824)
		(width 0.088646)
		(layer "In6.Cu")
		(net "M_H_CPU1_SA_DQS_DP<0>")
	)
	(segment
		(start 193.879216 -312.311034)
		(end 193.109596 -313.080654)
		(width 0.18288)
		(layer "In6.Cu")
		(net "M_H_CPU1_SA_DQS_DP<0>")
	)
	(segment
		(start 178.605942 -309.20944)
		(end 178.219862 -308.82336)
		(width 0.18288)
		(layer "In6.Cu")
		(net "M_H_CPU1_SA_DQS_DP<0>")
	)
	(segment
		(start 139.229592 -279.664668)
		(end 139.229084 -279.664668)
		(width 0.088646)
		(layer "In6.Cu")
		(net "M_H_CPU1_SA_DQS_DP<0>")
	)
	(segment
		(start 139.979908 -280.896314)
		(end 139.670536 -280.318718)
		(width 0.088646)
		(layer "In6.Cu")
		(net "M_H_CPU1_SA_DQS_DP<0>")
	)
	(segment
		(start 185.69813 -313.523376)
		(end 185.522108 -313.523376)
		(width 0.18288)
		(layer "In6.Cu")
		(net "M_H_CPU1_SA_DQS_DP<0>")
	)
	(segment
		(start 190.881762 -313.205114)
		(end 190.335662 -313.205114)
		(width 0.18288)
		(layer "In6.Cu")
		(net "M_H_CPU1_SA_DQS_DP<0>")
	)
	(segment
		(start 192.161668 -313.341004)
		(end 191.808608 -313.341004)
		(width 0.18288)
		(layer "In6.Cu")
		(net "M_H_CPU1_SA_DQS_DP<0>")
	)
	(segment
		(start 140.34389 -281.118818)
		(end 140.283946 -281.058874)
		(width 0.088646)
		(layer "In6.Cu")
		(net "M_H_CPU1_SA_DQS_DP<0>")
	)
	(segment
		(start 131.688078 -278.02078)
		(end 131.673346 -278.012144)
		(width 0.088646)
		(layer "In6.Cu")
		(net "M_H_CPU1_SA_DQS_DP<0>")
	)
	(segment
		(start 173.673262 -309.674768)
		(end 173.242478 -309.674768)
		(width 0.18288)
		(layer "In6.Cu")
		(net "M_H_CPU1_SA_DQS_DP<0>")
	)
	(segment
		(start 190.211202 -313.080654)
		(end 189.633352 -313.080654)
		(width 0.18288)
		(layer "In6.Cu")
		(net "M_H_CPU1_SA_DQS_DP<0>")
	)
	(segment
		(start 181.890162 -311.754012)
		(end 181.71414 -311.754012)
		(width 0.18288)
		(layer "In6.Cu")
		(net "M_H_CPU1_SA_DQS_DP<0>")
	)
	(segment
		(start 193.109596 -313.080654)
		(end 192.422018 -313.080654)
		(width 0.18288)
		(layer "In6.Cu")
		(net "M_H_CPU1_SA_DQS_DP<0>")
	)
	(segment
		(start 176.703228 -309.090822)
		(end 176.42586 -308.813454)
		(width 0.18288)
		(layer "In6.Cu")
		(net "M_H_CPU1_SA_DQS_DP<0>")
	)
	(segment
		(start 199.831706 -312.191654)
		(end 199.088502 -312.191654)
		(width 0.18288)
		(layer "In6.Cu")
		(net "M_H_CPU1_SA_DQS_DP<0>")
	)
	(segment
		(start 161.992818 -305.691032)
		(end 161.620708 -305.691032)
		(width 0.18288)
		(layer "In6.Cu")
		(net "M_H_CPU1_SA_DQS_DP<0>")
	)
	(segment
		(start 183.1594 -312.325766)
		(end 183.03494 -312.201306)
		(width 0.18288)
		(layer "In6.Cu")
		(net "M_H_CPU1_SA_DQS_DP<0>")
	)
	(segment
		(start 181.327552 -311.367424)
		(end 181.327552 -311.191402)
		(width 0.18288)
		(layer "In6.Cu")
		(net "M_H_CPU1_SA_DQS_DP<0>")
	)
	(segment
		(start 170.154854 -309.778654)
		(end 169.608754 -309.778654)
		(width 0.18288)
		(layer "In6.Cu")
		(net "M_H_CPU1_SA_DQS_DP<0>")
	)
	(segment
		(start 178.605942 -309.385462)
		(end 178.605942 -309.20944)
		(width 0.18288)
		(layer "In6.Cu")
		(net "M_H_CPU1_SA_DQS_DP<0>")
	)
	(segment
		(start 187.707016 -314.191142)
		(end 187.433966 -313.918092)
		(width 0.18288)
		(layer "In6.Cu")
		(net "M_H_CPU1_SA_DQS_DP<0>")
	)
	(segment
		(start 157.904942 -306.538376)
		(end 157.531562 -306.538376)
		(width 0.18288)
		(layer "In6.Cu")
		(net "M_H_CPU1_SA_DQS_DP<0>")
	)
	(segment
		(start 181.327552 -311.191402)
		(end 180.612796 -310.476646)
		(width 0.18288)
		(layer "In6.Cu")
		(net "M_H_CPU1_SA_DQS_DP<0>")
	)
	(segment
		(start 177.350928 -308.82336)
		(end 177.083466 -309.090822)
		(width 0.18288)
		(layer "In6.Cu")
		(net "M_H_CPU1_SA_DQS_DP<0>")
	)
	(segment
		(start 132.627878 -278.02078)
		(end 132.613146 -278.012144)
		(width 0.088646)
		(layer "In6.Cu")
		(net "M_H_CPU1_SA_DQS_DP<0>")
	)
	(segment
		(start 172.581316 -309.94096)
		(end 172.29455 -309.654194)
		(width 0.18288)
		(layer "In6.Cu")
		(net "M_H_CPU1_SA_DQS_DP<0>")
	)
	(segment
		(start 175.103536 -308.937914)
		(end 174.979076 -308.813454)
		(width 0.18288)
		(layer "In6.Cu")
		(net "M_H_CPU1_SA_DQS_DP<0>")
	)
	(segment
		(start 159.959294 -305.431698)
		(end 159.413194 -305.431698)
		(width 0.18288)
		(layer "In6.Cu")
		(net "M_H_CPU1_SA_DQS_DP<0>")
	)
	(segment
		(start 185.135774 -312.96102)
		(end 184.37606 -312.201306)
		(width 0.18288)
		(layer "In6.Cu")
		(net "M_H_CPU1_SA_DQS_DP<0>")
	)
	(segment
		(start 171.801282 -309.654194)
		(end 171.676822 -309.778654)
		(width 0.18288)
		(layer "In6.Cu")
		(net "M_H_CPU1_SA_DQS_DP<0>")
	)
	(segment
		(start 188.79439 -313.919616)
		(end 188.332618 -313.919616)
		(width 0.18288)
		(layer "In6.Cu")
		(net "M_H_CPU1_SA_DQS_DP<0>")
	)
	(segment
		(start 199.088502 -312.191654)
		(end 198.415148 -312.865008)
		(width 0.18288)
		(layer "In6.Cu")
		(net "M_H_CPU1_SA_DQS_DP<0>")
	)
	(segment
		(start 185.135774 -313.137042)
		(end 185.135774 -312.96102)
		(width 0.18288)
		(layer "In6.Cu")
		(net "M_H_CPU1_SA_DQS_DP<0>")
	)
	(segment
		(start 202.971146 -312.91657)
		(end 202.692254 -312.637678)
		(width 0.18288)
		(layer "In6.Cu")
		(net "M_H_CPU1_SA_DQS_DP<0>")
	)
	(segment
		(start 130.358896 -278.012144)
		(end 130.348482 -278.01824)
		(width 0.088646)
		(layer "In6.Cu")
		(net "M_H_CPU1_SA_DQS_DP<0>")
	)
	(segment
		(start 191.006222 -313.080654)
		(end 190.881762 -313.205114)
		(width 0.18288)
		(layer "In6.Cu")
		(net "M_H_CPU1_SA_DQS_DP<0>")
	)
	(segment
		(start 180.612796 -310.476646)
		(end 179.873148 -310.476646)
		(width 0.18288)
		(layer "In6.Cu")
		(net "M_H_CPU1_SA_DQS_DP<0>")
	)
	(segment
		(start 167.232838 -308.746906)
		(end 166.778432 -308.443122)
		(width 0.18288)
		(layer "In6.Cu")
		(net "M_H_CPU1_SA_DQS_DP<0>")
	)
	(segment
		(start 139.586462 -280.115772)
		(end 139.384278 -279.813766)
		(width 0.088646)
		(layer "In6.Cu")
		(net "M_H_CPU1_SA_DQS_DP<0>")
	)
	(segment
		(start 178.992276 -309.771796)
		(end 178.605942 -309.385462)
		(width 0.18288)
		(layer "In6.Cu")
		(net "M_H_CPU1_SA_DQS_DP<0>")
	)
	(segment
		(start 128.868678 -278.02078)
		(end 128.853946 -278.012144)
		(width 0.088646)
		(layer "In6.Cu")
		(net "M_H_CPU1_SA_DQS_DP<0>")
	)
	(segment
		(start 200.502266 -312.316114)
		(end 199.956166 -312.316114)
		(width 0.18288)
		(layer "In6.Cu")
		(net "M_H_CPU1_SA_DQS_DP<0>")
	)
	(segment
		(start 188.332618 -313.919616)
		(end 188.061092 -314.191142)
		(width 0.18288)
		(layer "In6.Cu")
		(net "M_H_CPU1_SA_DQS_DP<0>")
	)
	(segment
		(start 201.652886 -312.191654)
		(end 200.626726 -312.191654)
		(width 0.18288)
		(layer "In6.Cu")
		(net "M_H_CPU1_SA_DQS_DP<0>")
	)
	(segment
		(start 139.384278 -279.813766)
		(end 139.267692 -279.697434)
		(width 0.088646)
		(layer "In6.Cu")
		(net "M_H_CPU1_SA_DQS_DP<0>")
	)
	(segment
		(start 164.39896 -306.703222)
		(end 163.113466 -305.417728)
		(width 0.18288)
		(layer "In6.Cu")
		(net "M_H_CPU1_SA_DQS_DP<0>")
	)
	(segment
		(start 173.242478 -309.674768)
		(end 172.976286 -309.94096)
		(width 0.18288)
		(layer "In6.Cu")
		(net "M_H_CPU1_SA_DQS_DP<0>")
	)
	(segment
		(start 196.286628 -312.311034)
		(end 195.740528 -312.311034)
		(width 0.18288)
		(layer "In6.Cu")
		(net "M_H_CPU1_SA_DQS_DP<0>")
	)
	(segment
		(start 174.534576 -308.813454)
		(end 173.673262 -309.674768)
		(width 0.18288)
		(layer "In6.Cu")
		(net "M_H_CPU1_SA_DQS_DP<0>")
	)
	(segment
		(start 202.09891 -312.637678)
		(end 201.652886 -312.191654)
		(width 0.18288)
		(layer "In6.Cu")
		(net "M_H_CPU1_SA_DQS_DP<0>")
	)
	(segment
		(start 181.71414 -311.754012)
		(end 181.327552 -311.367424)
		(width 0.18288)
		(layer "In6.Cu")
		(net "M_H_CPU1_SA_DQS_DP<0>")
	)
	(segment
		(start 191.548258 -313.080654)
		(end 191.006222 -313.080654)
		(width 0.18288)
		(layer "In6.Cu")
		(net "M_H_CPU1_SA_DQS_DP<0>")
	)
	(arc
		(start 131.673346 -278.012144)
		(mid 131.486148 -277.962001)
		(end 131.29895 -278.012144)
		(width 0.088646)
		(layer "In6.Cu")
		(net "M_H_CPU1_SA_DQS_DP<0>")
	)
	(arc
		(start 139.267692 -279.697434)
		(mid 139.249189 -279.680415)
		(end 139.229592 -279.664668)
		(width 0.088646)
		(layer "In6.Cu")
		(net "M_H_CPU1_SA_DQS_DP<0>")
	)
	(arc
		(start 128.47955 -278.012144)
		(mid 128.205321 -278.088069)
		(end 127.928878 -278.02078)
		(width 0.088646)
		(layer "In6.Cu")
		(net "M_H_CPU1_SA_DQS_DP<0>")
	)
	(arc
		(start 138.817096 -279.639776)
		(mid 138.25612 -279.642307)
		(end 137.969244 -279.160224)
		(width 0.088646)
		(layer "In6.Cu")
		(net "M_H_CPU1_SA_DQS_DP<0>")
	)
	(arc
		(start 135.997696 -278.012144)
		(mid 135.723467 -278.088069)
		(end 135.447024 -278.02078)
		(width 0.088646)
		(layer "In6.Cu")
		(net "M_H_CPU1_SA_DQS_DP<0>")
	)
	(arc
		(start 136.372092 -278.012144)
		(mid 136.184894 -277.962001)
		(end 135.997696 -278.012144)
		(width 0.088646)
		(layer "In6.Cu")
		(net "M_H_CPU1_SA_DQS_DP<0>")
	)
	(arc
		(start 132.613146 -278.012144)
		(mid 132.425948 -277.962001)
		(end 132.23875 -278.012144)
		(width 0.088646)
		(layer "In6.Cu")
		(net "M_H_CPU1_SA_DQS_DP<0>")
	)
	(arc
		(start 133.552946 -278.012144)
		(mid 133.365748 -277.962001)
		(end 133.17855 -278.012144)
		(width 0.088646)
		(layer "In6.Cu")
		(net "M_H_CPU1_SA_DQS_DP<0>")
	)
	(arc
		(start 128.853946 -278.012144)
		(mid 128.666748 -277.962001)
		(end 128.47955 -278.012144)
		(width 0.088646)
		(layer "In6.Cu")
		(net "M_H_CPU1_SA_DQS_DP<0>")
	)
	(arc
		(start 137.969244 -279.150318)
		(mid 137.921565 -278.967418)
		(end 137.790682 -278.83104)
		(width 0.088646)
		(layer "In6.Cu")
		(net "M_H_CPU1_SA_DQS_DP<0>")
	)
	(arc
		(start 130.348482 -278.01824)
		(mid 130.070304 -278.087932)
		(end 129.793746 -278.012144)
		(width 0.088646)
		(layer "In6.Cu")
		(net "M_H_CPU1_SA_DQS_DP<0>")
	)
	(arc
		(start 135.432292 -278.012144)
		(mid 135.245094 -277.962001)
		(end 135.057896 -278.012144)
		(width 0.088646)
		(layer "In6.Cu")
		(net "M_H_CPU1_SA_DQS_DP<0>")
	)
	(arc
		(start 133.17855 -278.012144)
		(mid 132.904321 -278.088069)
		(end 132.627878 -278.02078)
		(width 0.088646)
		(layer "In6.Cu")
		(net "M_H_CPU1_SA_DQS_DP<0>")
	)
	(arc
		(start 134.118096 -278.012144)
		(mid 133.841537 -278.087853)
		(end 133.56336 -278.01824)
		(width 0.088646)
		(layer "In6.Cu")
		(net "M_H_CPU1_SA_DQS_DP<0>")
	)
	(arc
		(start 129.41935 -278.012144)
		(mid 129.145121 -278.088069)
		(end 128.868678 -278.02078)
		(width 0.088646)
		(layer "In6.Cu")
		(net "M_H_CPU1_SA_DQS_DP<0>")
	)
	(arc
		(start 131.288536 -278.01824)
		(mid 131.010104 -278.088054)
		(end 130.733292 -278.012144)
		(width 0.088646)
		(layer "In6.Cu")
		(net "M_H_CPU1_SA_DQS_DP<0>")
	)
	(arc
		(start 137.781792 -278.82596)
		(mid 137.577457 -278.623355)
		(end 137.499344 -278.346408)
		(width 0.088646)
		(layer "In6.Cu")
		(net "M_H_CPU1_SA_DQS_DP<0>")
	)
	(arc
		(start 130.733292 -278.012144)
		(mid 130.546094 -277.962001)
		(end 130.358896 -278.012144)
		(width 0.088646)
		(layer "In6.Cu")
		(net "M_H_CPU1_SA_DQS_DP<0>")
	)
	(arc
		(start 137.499344 -278.336502)
		(mid 137.312045 -278.012061)
		(end 136.937496 -278.012144)
		(width 0.088646)
		(layer "In6.Cu")
		(net "M_H_CPU1_SA_DQS_DP<0>")
	)
	(arc
		(start 129.793746 -278.012144)
		(mid 129.606548 -277.962001)
		(end 129.41935 -278.012144)
		(width 0.088646)
		(layer "In6.Cu")
		(net "M_H_CPU1_SA_DQS_DP<0>")
	)
	(arc
		(start 134.492492 -278.012144)
		(mid 134.305294 -277.962001)
		(end 134.118096 -278.012144)
		(width 0.088646)
		(layer "In6.Cu")
		(net "M_H_CPU1_SA_DQS_DP<0>")
	)
	(arc
		(start 132.23875 -278.012144)
		(mid 131.964521 -278.088069)
		(end 131.688078 -278.02078)
		(width 0.088646)
		(layer "In6.Cu")
		(net "M_H_CPU1_SA_DQS_DP<0>")
	)
	(arc
		(start 135.057896 -278.012144)
		(mid 134.775194 -278.087886)
		(end 134.492492 -278.012144)
		(width 0.088646)
		(layer "In6.Cu")
		(net "M_H_CPU1_SA_DQS_DP<0>")
	)
	(arc
		(start 127.914146 -278.012144)
		(mid 127.571982 -277.785393)
		(end 127.256794 -277.522432)
		(width 0.088646)
		(layer "In6.Cu")
		(net "M_H_CPU1_SA_DQS_DP<0>")
	)
	(arc
		(start 139.229084 -279.664668)
		(mid 139.026835 -279.590366)
		(end 138.817096 -279.639776)
		(width 0.088646)
		(layer "In6.Cu")
		(net "M_H_CPU1_SA_DQS_DP<0>")
	)
	(arc
		(start 136.937496 -278.012144)
		(mid 136.654794 -278.087886)
		(end 136.372092 -278.012144)
		(width 0.088646)
		(layer "In6.Cu")
		(net "M_H_CPU1_SA_DQS_DP<0>")
	)
	(segment
		(start 208.70672 -274.66671)
		(end 208.977992 -274.395438)
		(width 0.20066)
		(layer "F.Cu")
		(net "M_H_CPU1_SA_DQS_DN<9>")
	)
	(segment
		(start 212.619336 -274.241768)
		(end 212.630258 -274.25269)
		(width 0.1016)
		(layer "F.Cu")
		(net "M_H_CPU1_SA_DQS_DN<9>")
	)
	(segment
		(start 210.603084 -274.247864)
		(end 210.60918 -274.241768)
		(width 0.1016)
		(layer "F.Cu")
		(net "M_H_CPU1_SA_DQS_DN<9>")
	)
	(segment
		(start 213.234778 -273.96694)
		(end 213.724744 -273.96694)
		(width 0.20066)
		(layer "F.Cu")
		(net "M_H_CPU1_SA_DQS_DN<9>")
	)
	(segment
		(start 210.60918 -274.241768)
		(end 212.619336 -274.241768)
		(width 0.1016)
		(layer "F.Cu")
		(net "M_H_CPU1_SA_DQS_DN<9>")
	)
	(segment
		(start 208.176114 -274.66671)
		(end 208.70672 -274.66671)
		(width 0.20066)
		(layer "F.Cu")
		(net "M_H_CPU1_SA_DQS_DN<9>")
	)
	(segment
		(start 209.886296 -273.970496)
		(end 210.008724 -273.970496)
		(width 0.20066)
		(layer "F.Cu")
		(net "M_H_CPU1_SA_DQS_DN<9>")
	)
	(segment
		(start 210.008724 -273.970496)
		(end 210.286092 -274.247864)
		(width 0.20066)
		(layer "F.Cu")
		(net "M_H_CPU1_SA_DQS_DN<9>")
	)
	(segment
		(start 212.949028 -274.25269)
		(end 213.234778 -273.96694)
		(width 0.20066)
		(layer "F.Cu")
		(net "M_H_CPU1_SA_DQS_DN<9>")
	)
	(segment
		(start 215.216232 -274.66671)
		(end 215.719914 -274.66671)
		(width 0.20066)
		(layer "F.Cu")
		(net "M_H_CPU1_SA_DQS_DN<9>")
	)
	(segment
		(start 207.071214 -274.66671)
		(end 208.176114 -274.66671)
		(width 0.20066)
		(layer "F.Cu")
		(net "M_H_CPU1_SA_DQS_DN<9>")
	)
	(segment
		(start 210.598258 -274.247864)
		(end 210.603084 -274.247864)
		(width 0.101854)
		(layer "F.Cu")
		(net "M_H_CPU1_SA_DQS_DN<9>")
	)
	(segment
		(start 209.461354 -274.395438)
		(end 209.886296 -273.970496)
		(width 0.20066)
		(layer "F.Cu")
		(net "M_H_CPU1_SA_DQS_DN<9>")
	)
	(segment
		(start 214.961978 -274.412456)
		(end 215.216232 -274.66671)
		(width 0.20066)
		(layer "F.Cu")
		(net "M_H_CPU1_SA_DQS_DN<9>")
	)
	(segment
		(start 125.847094 -259.894832)
		(end 125.847094 -260.430518)
		(width 0.20066)
		(layer "F.Cu")
		(net "M_H_CPU1_SA_DQS_DN<9>")
	)
	(segment
		(start 212.630258 -274.25269)
		(end 212.949028 -274.25269)
		(width 0.20066)
		(layer "F.Cu")
		(net "M_H_CPU1_SA_DQS_DN<9>")
	)
	(segment
		(start 214.17026 -274.412456)
		(end 214.961978 -274.412456)
		(width 0.20066)
		(layer "F.Cu")
		(net "M_H_CPU1_SA_DQS_DN<9>")
	)
	(segment
		(start 213.724744 -273.96694)
		(end 214.17026 -274.412456)
		(width 0.20066)
		(layer "F.Cu")
		(net "M_H_CPU1_SA_DQS_DN<9>")
	)
	(segment
		(start 210.286092 -274.247864)
		(end 210.598258 -274.247864)
		(width 0.20066)
		(layer "F.Cu")
		(net "M_H_CPU1_SA_DQS_DN<9>")
	)
	(segment
		(start 125.847094 -260.430518)
		(end 125.847348 -260.430772)
		(width 0.20066)
		(layer "F.Cu")
		(net "M_H_CPU1_SA_DQS_DN<9>")
	)
	(segment
		(start 208.977992 -274.395438)
		(end 209.461354 -274.395438)
		(width 0.20066)
		(layer "F.Cu")
		(net "M_H_CPU1_SA_DQS_DN<9>")
	)
	(segment
		(start 135.447024 -260.11505)
		(end 135.432292 -260.106414)
		(width 0.088646)
		(layer "In11.Cu")
		(net "M_H_CPU1_SA_DQS_DN<9>")
	)
	(segment
		(start 163.948618 -274.240498)
		(end 163.786058 -274.307808)
		(width 0.18288)
		(layer "In11.Cu")
		(net "M_H_CPU1_SA_DQS_DN<9>")
	)
	(segment
		(start 166.073836 -274.63242)
		(end 164.895784 -274.63242)
		(width 0.18288)
		(layer "In11.Cu")
		(net "M_H_CPU1_SA_DQS_DN<9>")
	)
	(segment
		(start 129.808478 -260.11505)
		(end 129.793746 -260.106414)
		(width 0.088646)
		(layer "In11.Cu")
		(net "M_H_CPU1_SA_DQS_DN<9>")
	)
	(segment
		(start 200.150984 -274.56638)
		(end 200.083674 -274.729194)
		(width 0.18288)
		(layer "In11.Cu")
		(net "M_H_CPU1_SA_DQS_DN<9>")
	)
	(segment
		(start 171.072302 -273.988276)
		(end 169.762932 -274.248626)
		(width 0.18288)
		(layer "In11.Cu")
		(net "M_H_CPU1_SA_DQS_DN<9>")
	)
	(segment
		(start 192.877694 -275.704808)
		(end 192.447672 -275.704808)
		(width 0.18288)
		(layer "In11.Cu")
		(net "M_H_CPU1_SA_DQS_DN<9>")
	)
	(segment
		(start 200.083674 -274.729194)
		(end 199.576944 -274.93976)
		(width 0.18288)
		(layer "In11.Cu")
		(net "M_H_CPU1_SA_DQS_DN<9>")
	)
	(segment
		(start 139.379452 -262.069072)
		(end 139.379452 -262.06069)
		(width 0.088646)
		(layer "In11.Cu")
		(net "M_H_CPU1_SA_DQS_DN<9>")
	)
	(segment
		(start 167.836088 -274.632166)
		(end 167.836088 -274.63242)
		(width 0.18288)
		(layer "In11.Cu")
		(net "M_H_CPU1_SA_DQS_DN<9>")
	)
	(segment
		(start 189.527942 -274.513548)
		(end 189.01918 -274.004786)
		(width 0.18288)
		(layer "In11.Cu")
		(net "M_H_CPU1_SA_DQS_DN<9>")
	)
	(segment
		(start 163.21151 -273.93519)
		(end 162.70478 -273.725386)
		(width 0.18288)
		(layer "In11.Cu")
		(net "M_H_CPU1_SA_DQS_DN<9>")
	)
	(segment
		(start 180.914548 -274.585938)
		(end 180.186838 -274.585938)
		(width 0.18288)
		(layer "In11.Cu")
		(net "M_H_CPU1_SA_DQS_DN<9>")
	)
	(segment
		(start 192.211706 -275.940774)
		(end 191.689482 -275.940774)
		(width 0.18288)
		(layer "In11.Cu")
		(net "M_H_CPU1_SA_DQS_DN<9>")
	)
	(segment
		(start 206.800958 -274.396454)
		(end 206.405988 -274.396454)
		(width 0.18288)
		(layer "In11.Cu")
		(net "M_H_CPU1_SA_DQS_DN<9>")
	)
	(segment
		(start 137.313416 -260.107176)
		(end 137.311892 -260.106414)
		(width 0.088646)
		(layer "In11.Cu")
		(net "M_H_CPU1_SA_DQS_DN<9>")
	)
	(segment
		(start 174.642018 -274.961096)
		(end 174.253906 -274.572984)
		(width 0.18288)
		(layer "In11.Cu")
		(net "M_H_CPU1_SA_DQS_DN<9>")
	)
	(segment
		(start 203.204318 -274.23618)
		(end 203.021438 -274.23618)
		(width 0.18288)
		(layer "In11.Cu")
		(net "M_H_CPU1_SA_DQS_DN<9>")
	)
	(segment
		(start 138.817604 -261.734046)
		(end 138.817096 -261.7343)
		(width 0.088646)
		(layer "In11.Cu")
		(net "M_H_CPU1_SA_DQS_DN<9>")
	)
	(segment
		(start 125.95225 -260.200648)
		(end 125.930152 -260.210046)
		(width 0.088646)
		(layer "In11.Cu")
		(net "M_H_CPU1_SA_DQS_DN<9>")
	)
	(segment
		(start 183.863742 -274.585938)
		(end 183.058308 -274.585938)
		(width 0.18288)
		(layer "In11.Cu")
		(net "M_H_CPU1_SA_DQS_DN<9>")
	)
	(segment
		(start 198.1708 -275.389594)
		(end 197.664324 -275.599906)
		(width 0.18288)
		(layer "In11.Cu")
		(net "M_H_CPU1_SA_DQS_DN<9>")
	)
	(segment
		(start 139.379452 -262.06069)
		(end 139.379198 -262.049768)
		(width 0.088646)
		(layer "In11.Cu")
		(net "M_H_CPU1_SA_DQS_DN<9>")
	)
	(segment
		(start 175.536352 -275.679408)
		(end 174.81804 -274.961096)
		(width 0.18288)
		(layer "In11.Cu")
		(net "M_H_CPU1_SA_DQS_DN<9>")
	)
	(segment
		(start 158.837884 -273.508724)
		(end 158.289244 -273.508724)
		(width 0.18288)
		(layer "In11.Cu")
		(net "M_H_CPU1_SA_DQS_DN<9>")
	)
	(segment
		(start 158.164784 -273.384264)
		(end 156.57449 -273.384264)
		(width 0.18288)
		(layer "In11.Cu")
		(net "M_H_CPU1_SA_DQS_DN<9>")
	)
	(segment
		(start 131.688078 -260.11505)
		(end 131.673346 -260.106414)
		(width 0.088646)
		(layer "In11.Cu")
		(net "M_H_CPU1_SA_DQS_DN<9>")
	)
	(segment
		(start 169.665142 -274.395438)
		(end 169.126662 -274.502372)
		(width 0.18288)
		(layer "In11.Cu")
		(net "M_H_CPU1_SA_DQS_DN<9>")
	)
	(segment
		(start 126.51359 -260.15442)
		(end 126.374906 -260.19252)
		(width 0.088646)
		(layer "In11.Cu")
		(net "M_H_CPU1_SA_DQS_DN<9>")
	)
	(segment
		(start 193.087244 -275.495258)
		(end 192.877694 -275.704808)
		(width 0.18288)
		(layer "In11.Cu")
		(net "M_H_CPU1_SA_DQS_DN<9>")
	)
	(segment
		(start 204.259434 -274.558252)
		(end 203.677774 -273.976592)
		(width 0.18288)
		(layer "In11.Cu")
		(net "M_H_CPU1_SA_DQS_DN<9>")
	)
	(segment
		(start 205.605634 -274.558252)
		(end 205.481174 -274.682712)
		(width 0.18288)
		(layer "In11.Cu")
		(net "M_H_CPU1_SA_DQS_DN<9>")
	)
	(segment
		(start 190.512446 -275.498052)
		(end 190.09233 -275.077936)
		(width 0.18288)
		(layer "In11.Cu")
		(net "M_H_CPU1_SA_DQS_DN<9>")
	)
	(segment
		(start 177.124106 -275.940774)
		(end 176.601882 -275.940774)
		(width 0.18288)
		(layer "In11.Cu")
		(net "M_H_CPU1_SA_DQS_DN<9>")
	)
	(segment
		(start 206.015336 -274.558252)
		(end 205.605634 -274.558252)
		(width 0.18288)
		(layer "In11.Cu")
		(net "M_H_CPU1_SA_DQS_DN<9>")
	)
	(segment
		(start 160.263332 -273.384264)
		(end 158.962344 -273.384264)
		(width 0.18288)
		(layer "In11.Cu")
		(net "M_H_CPU1_SA_DQS_DN<9>")
	)
	(segment
		(start 140.188696 -262.623554)
		(end 139.944094 -262.623554)
		(width 0.088646)
		(layer "In11.Cu")
		(net "M_H_CPU1_SA_DQS_DN<9>")
	)
	(segment
		(start 126.984506 -260.11251)
		(end 126.974092 -260.106414)
		(width 0.088646)
		(layer "In11.Cu")
		(net "M_H_CPU1_SA_DQS_DN<9>")
	)
	(segment
		(start 178.863752 -275.134578)
		(end 178.633374 -275.365464)
		(width 0.18288)
		(layer "In11.Cu")
		(net "M_H_CPU1_SA_DQS_DN<9>")
	)
	(segment
		(start 137.969244 -261.254748)
		(end 137.969244 -261.244842)
		(width 0.088646)
		(layer "In11.Cu")
		(net "M_H_CPU1_SA_DQS_DN<9>")
	)
	(segment
		(start 189.01918 -274.004786)
		(end 188.347604 -274.004786)
		(width 0.18288)
		(layer "In11.Cu")
		(net "M_H_CPU1_SA_DQS_DN<9>")
	)
	(segment
		(start 183.058308 -274.585938)
		(end 182.933848 -274.710398)
		(width 0.18288)
		(layer "In11.Cu")
		(net "M_H_CPU1_SA_DQS_DN<9>")
	)
	(segment
		(start 190.93434 -275.672042)
		(end 190.512446 -275.498052)
		(width 0.18288)
		(layer "In11.Cu")
		(net "M_H_CPU1_SA_DQS_DN<9>")
	)
	(segment
		(start 156.57449 -273.384264)
		(end 145.99666 -262.806434)
		(width 0.18288)
		(layer "In11.Cu")
		(net "M_H_CPU1_SA_DQS_DN<9>")
	)
	(segment
		(start 181.587648 -274.710398)
		(end 181.039008 -274.710398)
		(width 0.18288)
		(layer "In11.Cu")
		(net "M_H_CPU1_SA_DQS_DN<9>")
	)
	(segment
		(start 168.980358 -274.404582)
		(end 167.836088 -274.632166)
		(width 0.18288)
		(layer "In11.Cu")
		(net "M_H_CPU1_SA_DQS_DN<9>")
	)
	(segment
		(start 130.748278 -260.11505)
		(end 130.733546 -260.106414)
		(width 0.088646)
		(layer "In11.Cu")
		(net "M_H_CPU1_SA_DQS_DN<9>")
	)
	(segment
		(start 194.275202 -275.078444)
		(end 194.092576 -275.078444)
		(width 0.18288)
		(layer "In11.Cu")
		(net "M_H_CPU1_SA_DQS_DN<9>")
	)
	(segment
		(start 198.333614 -275.45665)
		(end 198.1708 -275.389594)
		(width 0.18288)
		(layer "In11.Cu")
		(net "M_H_CPU1_SA_DQS_DN<9>")
	)
	(segment
		(start 172.501814 -274.240752)
		(end 172.249338 -273.988276)
		(width 0.18288)
		(layer "In11.Cu")
		(net "M_H_CPU1_SA_DQS_DN<9>")
	)
	(segment
		(start 177.838608 -275.69541)
		(end 177.36947 -275.69541)
		(width 0.18288)
		(layer "In11.Cu")
		(net "M_H_CPU1_SA_DQS_DN<9>")
	)
	(segment
		(start 199.41413 -274.872704)
		(end 198.907654 -275.083016)
		(width 0.18288)
		(layer "In11.Cu")
		(net "M_H_CPU1_SA_DQS_DN<9>")
	)
	(segment
		(start 187.343542 -273.99488)
		(end 186.637676 -273.99488)
		(width 0.18288)
		(layer "In11.Cu")
		(net "M_H_CPU1_SA_DQS_DN<9>")
	)
	(segment
		(start 200.945496 -274.23618)
		(end 200.150984 -274.56638)
		(width 0.18288)
		(layer "In11.Cu")
		(net "M_H_CPU1_SA_DQS_DN<9>")
	)
	(segment
		(start 140.842492 -262.74649)
		(end 140.311632 -262.74649)
		(width 0.088646)
		(layer "In11.Cu")
		(net "M_H_CPU1_SA_DQS_DN<9>")
	)
	(segment
		(start 140.311632 -262.74649)
		(end 140.188696 -262.623554)
		(width 0.088646)
		(layer "In11.Cu")
		(net "M_H_CPU1_SA_DQS_DN<9>")
	)
	(segment
		(start 174.253906 -274.396962)
		(end 173.866048 -274.009104)
		(width 0.18288)
		(layer "In11.Cu")
		(net "M_H_CPU1_SA_DQS_DN<9>")
	)
	(segment
		(start 181.039008 -274.710398)
		(end 180.914548 -274.585938)
		(width 0.18288)
		(layer "In11.Cu")
		(net "M_H_CPU1_SA_DQS_DN<9>")
	)
	(segment
		(start 162.70478 -273.725386)
		(end 161.087308 -273.725386)
		(width 0.18288)
		(layer "In11.Cu")
		(net "M_H_CPU1_SA_DQS_DN<9>")
	)
	(segment
		(start 127.928878 -260.11505)
		(end 127.914146 -260.106414)
		(width 0.088646)
		(layer "In11.Cu")
		(net "M_H_CPU1_SA_DQS_DN<9>")
	)
	(segment
		(start 163.279074 -274.098004)
		(end 163.21151 -273.93519)
		(width 0.18288)
		(layer "In11.Cu")
		(net "M_H_CPU1_SA_DQS_DN<9>")
	)
	(segment
		(start 185.964576 -274.11934)
		(end 185.840116 -273.99488)
		(width 0.18288)
		(layer "In11.Cu")
		(net "M_H_CPU1_SA_DQS_DN<9>")
	)
	(segment
		(start 185.291222 -273.99488)
		(end 183.863742 -274.585938)
		(width 0.18288)
		(layer "In11.Cu")
		(net "M_H_CPU1_SA_DQS_DN<9>")
	)
	(segment
		(start 180.186838 -274.585938)
		(end 178.863752 -275.134578)
		(width 0.18288)
		(layer "In11.Cu")
		(net "M_H_CPU1_SA_DQS_DN<9>")
	)
	(segment
		(start 203.021438 -274.23618)
		(end 202.795378 -274.23618)
		(width 0.16002)
		(layer "In11.Cu")
		(net "M_H_CPU1_SA_DQS_DN<9>")
	)
	(segment
		(start 198.907654 -275.083016)
		(end 198.840344 -275.246084)
		(width 0.18288)
		(layer "In11.Cu")
		(net "M_H_CPU1_SA_DQS_DN<9>")
	)
	(segment
		(start 173.31563 -274.009104)
		(end 173.083982 -274.240752)
		(width 0.18288)
		(layer "In11.Cu")
		(net "M_H_CPU1_SA_DQS_DN<9>")
	)
	(segment
		(start 181.712108 -274.585938)
		(end 181.587648 -274.710398)
		(width 0.18288)
		(layer "In11.Cu")
		(net "M_H_CPU1_SA_DQS_DN<9>")
	)
	(segment
		(start 186.513216 -274.11934)
		(end 185.964576 -274.11934)
		(width 0.18288)
		(layer "In11.Cu")
		(net "M_H_CPU1_SA_DQS_DN<9>")
	)
	(segment
		(start 191.689482 -275.940774)
		(end 191.42075 -275.672042)
		(width 0.18288)
		(layer "In11.Cu")
		(net "M_H_CPU1_SA_DQS_DN<9>")
	)
	(segment
		(start 204.808074 -274.558252)
		(end 204.259434 -274.558252)
		(width 0.18288)
		(layer "In11.Cu")
		(net "M_H_CPU1_SA_DQS_DN<9>")
	)
	(segment
		(start 195.53301 -275.60016)
		(end 194.275202 -275.078444)
		(width 0.18288)
		(layer "In11.Cu")
		(net "M_H_CPU1_SA_DQS_DN<9>")
	)
	(segment
		(start 169.762932 -274.248626)
		(end 169.665142 -274.395438)
		(width 0.18288)
		(layer "In11.Cu")
		(net "M_H_CPU1_SA_DQS_DN<9>")
	)
	(segment
		(start 133.563106 -260.11251)
		(end 133.552692 -260.106414)
		(width 0.088646)
		(layer "In11.Cu")
		(net "M_H_CPU1_SA_DQS_DN<9>")
	)
	(segment
		(start 137.320782 -260.111494)
		(end 137.313416 -260.107176)
		(width 0.088646)
		(layer "In11.Cu")
		(net "M_H_CPU1_SA_DQS_DN<9>")
	)
	(segment
		(start 194.092576 -275.078444)
		(end 193.087244 -275.495258)
		(width 0.18288)
		(layer "In11.Cu")
		(net "M_H_CPU1_SA_DQS_DN<9>")
	)
	(segment
		(start 136.386824 -260.11505)
		(end 136.372092 -260.106414)
		(width 0.088646)
		(layer "In11.Cu")
		(net "M_H_CPU1_SA_DQS_DN<9>")
	)
	(segment
		(start 126.597918 -260.10743)
		(end 126.51359 -260.15442)
		(width 0.088646)
		(layer "In11.Cu")
		(net "M_H_CPU1_SA_DQS_DN<9>")
	)
	(segment
		(start 207.071214 -274.66671)
		(end 206.800958 -274.396454)
		(width 0.18288)
		(layer "In11.Cu")
		(net "M_H_CPU1_SA_DQS_DN<9>")
	)
	(segment
		(start 163.786058 -274.307808)
		(end 163.279074 -274.098004)
		(width 0.18288)
		(layer "In11.Cu")
		(net "M_H_CPU1_SA_DQS_DN<9>")
	)
	(segment
		(start 167.836088 -274.63242)
		(end 166.871396 -274.63242)
		(width 0.18288)
		(layer "In11.Cu")
		(net "M_H_CPU1_SA_DQS_DN<9>")
	)
	(segment
		(start 176.340516 -275.679408)
		(end 175.536352 -275.679408)
		(width 0.18288)
		(layer "In11.Cu")
		(net "M_H_CPU1_SA_DQS_DN<9>")
	)
	(segment
		(start 189.527942 -274.68957)
		(end 189.527942 -274.513548)
		(width 0.18288)
		(layer "In11.Cu")
		(net "M_H_CPU1_SA_DQS_DN<9>")
	)
	(segment
		(start 176.601882 -275.940774)
		(end 176.340516 -275.679408)
		(width 0.18288)
		(layer "In11.Cu")
		(net "M_H_CPU1_SA_DQS_DN<9>")
	)
	(segment
		(start 186.637676 -273.99488)
		(end 186.513216 -274.11934)
		(width 0.18288)
		(layer "In11.Cu")
		(net "M_H_CPU1_SA_DQS_DN<9>")
	)
	(segment
		(start 125.847348 -260.305804)
		(end 125.847348 -260.430772)
		(width 0.088646)
		(layer "In11.Cu")
		(net "M_H_CPU1_SA_DQS_DN<9>")
	)
	(segment
		(start 190.09233 -275.077936)
		(end 189.916308 -275.077936)
		(width 0.18288)
		(layer "In11.Cu")
		(net "M_H_CPU1_SA_DQS_DN<9>")
	)
	(segment
		(start 166.746936 -274.75688)
		(end 166.198296 -274.75688)
		(width 0.18288)
		(layer "In11.Cu")
		(net "M_H_CPU1_SA_DQS_DN<9>")
	)
	(segment
		(start 166.871396 -274.63242)
		(end 166.746936 -274.75688)
		(width 0.18288)
		(layer "In11.Cu")
		(net "M_H_CPU1_SA_DQS_DN<9>")
	)
	(segment
		(start 191.42075 -275.672042)
		(end 190.93434 -275.672042)
		(width 0.18288)
		(layer "In11.Cu")
		(net "M_H_CPU1_SA_DQS_DN<9>")
	)
	(segment
		(start 182.385208 -274.710398)
		(end 182.260748 -274.585938)
		(width 0.18288)
		(layer "In11.Cu")
		(net "M_H_CPU1_SA_DQS_DN<9>")
	)
	(segment
		(start 177.36947 -275.69541)
		(end 177.124106 -275.940774)
		(width 0.18288)
		(layer "In11.Cu")
		(net "M_H_CPU1_SA_DQS_DN<9>")
	)
	(segment
		(start 126.599442 -260.106668)
		(end 126.597918 -260.10743)
		(width 0.088646)
		(layer "In11.Cu")
		(net "M_H_CPU1_SA_DQS_DN<9>")
	)
	(segment
		(start 137.790682 -260.925564)
		(end 137.781792 -260.920484)
		(width 0.088646)
		(layer "In11.Cu")
		(net "M_H_CPU1_SA_DQS_DN<9>")
	)
	(segment
		(start 137.499344 -260.449314)
		(end 137.499344 -260.430772)
		(width 0.088646)
		(layer "In11.Cu")
		(net "M_H_CPU1_SA_DQS_DN<9>")
	)
	(segment
		(start 174.253906 -274.572984)
		(end 174.253906 -274.396962)
		(width 0.18288)
		(layer "In11.Cu")
		(net "M_H_CPU1_SA_DQS_DN<9>")
	)
	(segment
		(start 158.962344 -273.384264)
		(end 158.837884 -273.508724)
		(width 0.18288)
		(layer "In11.Cu")
		(net "M_H_CPU1_SA_DQS_DN<9>")
	)
	(segment
		(start 198.840344 -275.246084)
		(end 198.333614 -275.45665)
		(width 0.18288)
		(layer "In11.Cu")
		(net "M_H_CPU1_SA_DQS_DN<9>")
	)
	(segment
		(start 173.866048 -274.009104)
		(end 173.31563 -274.009104)
		(width 0.18288)
		(layer "In11.Cu")
		(net "M_H_CPU1_SA_DQS_DN<9>")
	)
	(segment
		(start 158.289244 -273.508724)
		(end 158.164784 -273.384264)
		(width 0.18288)
		(layer "In11.Cu")
		(net "M_H_CPU1_SA_DQS_DN<9>")
	)
	(segment
		(start 164.895784 -274.63242)
		(end 163.948618 -274.240498)
		(width 0.18288)
		(layer "In11.Cu")
		(net "M_H_CPU1_SA_DQS_DN<9>")
	)
	(segment
		(start 204.932534 -274.682712)
		(end 204.808074 -274.558252)
		(width 0.18288)
		(layer "In11.Cu")
		(net "M_H_CPU1_SA_DQS_DN<9>")
	)
	(segment
		(start 145.99666 -262.806434)
		(end 140.902436 -262.806434)
		(width 0.18288)
		(layer "In11.Cu")
		(net "M_H_CPU1_SA_DQS_DN<9>")
	)
	(segment
		(start 161.087308 -273.725386)
		(end 160.263332 -273.384264)
		(width 0.18288)
		(layer "In11.Cu")
		(net "M_H_CPU1_SA_DQS_DN<9>")
	)
	(segment
		(start 196.173852 -275.60016)
		(end 195.53301 -275.60016)
		(width 0.18288)
		(layer "In11.Cu")
		(net "M_H_CPU1_SA_DQS_DN<9>")
	)
	(segment
		(start 197.664324 -275.599906)
		(end 197.664578 -275.60016)
		(width 0.18288)
		(layer "In11.Cu")
		(net "M_H_CPU1_SA_DQS_DN<9>")
	)
	(segment
		(start 187.589414 -274.240752)
		(end 187.343542 -273.99488)
		(width 0.18288)
		(layer "In11.Cu")
		(net "M_H_CPU1_SA_DQS_DN<9>")
	)
	(segment
		(start 196.298312 -275.72462)
		(end 196.173852 -275.60016)
		(width 0.18288)
		(layer "In11.Cu")
		(net "M_H_CPU1_SA_DQS_DN<9>")
	)
	(segment
		(start 185.840116 -273.99488)
		(end 185.291222 -273.99488)
		(width 0.18288)
		(layer "In11.Cu")
		(net "M_H_CPU1_SA_DQS_DN<9>")
	)
	(segment
		(start 189.916308 -275.077936)
		(end 189.527942 -274.68957)
		(width 0.18288)
		(layer "In11.Cu")
		(net "M_H_CPU1_SA_DQS_DN<9>")
	)
	(segment
		(start 169.126662 -274.502372)
		(end 168.980358 -274.404582)
		(width 0.18288)
		(layer "In11.Cu")
		(net "M_H_CPU1_SA_DQS_DN<9>")
	)
	(segment
		(start 174.81804 -274.961096)
		(end 174.642018 -274.961096)
		(width 0.18288)
		(layer "In11.Cu")
		(net "M_H_CPU1_SA_DQS_DN<9>")
	)
	(segment
		(start 126.374906 -260.19252)
		(end 125.95225 -260.200648)
		(width 0.088646)
		(layer "In11.Cu")
		(net "M_H_CPU1_SA_DQS_DN<9>")
	)
	(segment
		(start 125.930152 -260.210046)
		(end 125.856746 -260.283452)
		(width 0.088646)
		(layer "In11.Cu")
		(net "M_H_CPU1_SA_DQS_DN<9>")
	)
	(segment
		(start 197.664578 -275.60016)
		(end 196.971412 -275.60016)
		(width 0.18288)
		(layer "In11.Cu")
		(net "M_H_CPU1_SA_DQS_DN<9>")
	)
	(segment
		(start 192.447672 -275.704808)
		(end 192.211706 -275.940774)
		(width 0.18288)
		(layer "In11.Cu")
		(net "M_H_CPU1_SA_DQS_DN<9>")
	)
	(segment
		(start 196.846952 -275.72462)
		(end 196.298312 -275.72462)
		(width 0.18288)
		(layer "In11.Cu")
		(net "M_H_CPU1_SA_DQS_DN<9>")
	)
	(segment
		(start 196.971412 -275.60016)
		(end 196.846952 -275.72462)
		(width 0.18288)
		(layer "In11.Cu")
		(net "M_H_CPU1_SA_DQS_DN<9>")
	)
	(segment
		(start 203.677774 -273.976592)
		(end 203.463906 -273.976592)
		(width 0.18288)
		(layer "In11.Cu")
		(net "M_H_CPU1_SA_DQS_DN<9>")
	)
	(segment
		(start 182.260748 -274.585938)
		(end 181.712108 -274.585938)
		(width 0.18288)
		(layer "In11.Cu")
		(net "M_H_CPU1_SA_DQS_DN<9>")
	)
	(segment
		(start 178.633374 -275.365464)
		(end 177.838608 -275.69541)
		(width 0.18288)
		(layer "In11.Cu")
		(net "M_H_CPU1_SA_DQS_DN<9>")
	)
	(segment
		(start 134.50316 -260.11251)
		(end 134.492746 -260.106414)
		(width 0.088646)
		(layer "In11.Cu")
		(net "M_H_CPU1_SA_DQS_DN<9>")
	)
	(segment
		(start 125.856746 -260.283452)
		(end 125.847348 -260.305804)
		(width 0.088646)
		(layer "In11.Cu")
		(net "M_H_CPU1_SA_DQS_DN<9>")
	)
	(segment
		(start 182.933848 -274.710398)
		(end 182.385208 -274.710398)
		(width 0.18288)
		(layer "In11.Cu")
		(net "M_H_CPU1_SA_DQS_DN<9>")
	)
	(segment
		(start 199.576944 -274.93976)
		(end 199.41413 -274.872704)
		(width 0.18288)
		(layer "In11.Cu")
		(net "M_H_CPU1_SA_DQS_DN<9>")
	)
	(segment
		(start 173.083982 -274.240752)
		(end 172.501814 -274.240752)
		(width 0.18288)
		(layer "In11.Cu")
		(net "M_H_CPU1_SA_DQS_DN<9>")
	)
	(segment
		(start 202.795378 -274.23618)
		(end 200.945496 -274.23618)
		(width 0.18288)
		(layer "In11.Cu")
		(net "M_H_CPU1_SA_DQS_DN<9>")
	)
	(segment
		(start 166.198296 -274.75688)
		(end 166.073836 -274.63242)
		(width 0.18288)
		(layer "In11.Cu")
		(net "M_H_CPU1_SA_DQS_DN<9>")
	)
	(segment
		(start 132.62356 -260.11251)
		(end 132.613146 -260.106414)
		(width 0.088646)
		(layer "In11.Cu")
		(net "M_H_CPU1_SA_DQS_DN<9>")
	)
	(segment
		(start 203.463906 -273.976592)
		(end 203.204318 -274.23618)
		(width 0.18288)
		(layer "In11.Cu")
		(net "M_H_CPU1_SA_DQS_DN<9>")
	)
	(segment
		(start 188.347604 -274.004786)
		(end 188.111638 -274.240752)
		(width 0.18288)
		(layer "In11.Cu")
		(net "M_H_CPU1_SA_DQS_DN<9>")
	)
	(segment
		(start 205.481174 -274.682712)
		(end 204.932534 -274.682712)
		(width 0.18288)
		(layer "In11.Cu")
		(net "M_H_CPU1_SA_DQS_DN<9>")
	)
	(segment
		(start 128.868678 -260.11505)
		(end 128.853946 -260.106414)
		(width 0.088646)
		(layer "In11.Cu")
		(net "M_H_CPU1_SA_DQS_DN<9>")
	)
	(segment
		(start 206.405988 -274.396454)
		(end 206.015336 -274.558252)
		(width 0.18288)
		(layer "In11.Cu")
		(net "M_H_CPU1_SA_DQS_DN<9>")
	)
	(segment
		(start 140.902436 -262.806434)
		(end 140.842492 -262.74649)
		(width 0.088646)
		(layer "In11.Cu")
		(net "M_H_CPU1_SA_DQS_DN<9>")
	)
	(segment
		(start 188.111638 -274.240752)
		(end 187.589414 -274.240752)
		(width 0.18288)
		(layer "In11.Cu")
		(net "M_H_CPU1_SA_DQS_DN<9>")
	)
	(segment
		(start 172.249338 -273.988276)
		(end 171.072302 -273.988276)
		(width 0.18288)
		(layer "In11.Cu")
		(net "M_H_CPU1_SA_DQS_DN<9>")
	)
	(arc
		(start 137.969244 -261.244842)
		(mid 137.921565 -261.061942)
		(end 137.790682 -260.925564)
		(width 0.088646)
		(layer "In11.Cu")
		(net "M_H_CPU1_SA_DQS_DN<9>")
	)
	(arc
		(start 131.29895 -260.106414)
		(mid 131.024751 -260.182249)
		(end 130.748278 -260.11505)
		(width 0.088646)
		(layer "In11.Cu")
		(net "M_H_CPU1_SA_DQS_DN<9>")
	)
	(arc
		(start 130.733546 -260.106414)
		(mid 130.546348 -260.056271)
		(end 130.35915 -260.106414)
		(width 0.088646)
		(layer "In11.Cu")
		(net "M_H_CPU1_SA_DQS_DN<9>")
	)
	(arc
		(start 137.499344 -260.430772)
		(mid 137.451665 -260.247872)
		(end 137.320782 -260.111494)
		(width 0.088646)
		(layer "In11.Cu")
		(net "M_H_CPU1_SA_DQS_DN<9>")
	)
	(arc
		(start 128.47955 -260.106414)
		(mid 128.205351 -260.182249)
		(end 127.928878 -260.11505)
		(width 0.088646)
		(layer "In11.Cu")
		(net "M_H_CPU1_SA_DQS_DN<9>")
	)
	(arc
		(start 137.781792 -260.920484)
		(mid 137.579506 -260.721503)
		(end 137.499344 -260.449314)
		(width 0.088646)
		(layer "In11.Cu")
		(net "M_H_CPU1_SA_DQS_DN<9>")
	)
	(arc
		(start 126.974092 -260.106414)
		(mid 126.78672 -260.056271)
		(end 126.599442 -260.106668)
		(width 0.088646)
		(layer "In11.Cu")
		(net "M_H_CPU1_SA_DQS_DN<9>")
	)
	(arc
		(start 138.817096 -261.7343)
		(mid 138.25612 -261.736831)
		(end 137.969244 -261.254748)
		(width 0.088646)
		(layer "In11.Cu")
		(net "M_H_CPU1_SA_DQS_DN<9>")
	)
	(arc
		(start 132.613146 -260.106414)
		(mid 132.425948 -260.056271)
		(end 132.23875 -260.106414)
		(width 0.088646)
		(layer "In11.Cu")
		(net "M_H_CPU1_SA_DQS_DN<9>")
	)
	(arc
		(start 135.432292 -260.106414)
		(mid 135.245094 -260.056271)
		(end 135.057896 -260.106414)
		(width 0.088646)
		(layer "In11.Cu")
		(net "M_H_CPU1_SA_DQS_DN<9>")
	)
	(arc
		(start 134.11835 -260.106414)
		(mid 133.841537 -260.182284)
		(end 133.563106 -260.11251)
		(width 0.088646)
		(layer "In11.Cu")
		(net "M_H_CPU1_SA_DQS_DN<9>")
	)
	(arc
		(start 139.944094 -262.623554)
		(mid 139.548352 -262.461766)
		(end 139.379452 -262.069072)
		(width 0.088646)
		(layer "In11.Cu")
		(net "M_H_CPU1_SA_DQS_DN<9>")
	)
	(arc
		(start 127.914146 -260.106414)
		(mid 127.726948 -260.056271)
		(end 127.53975 -260.106414)
		(width 0.088646)
		(layer "In11.Cu")
		(net "M_H_CPU1_SA_DQS_DN<9>")
	)
	(arc
		(start 135.997696 -260.106414)
		(mid 135.723497 -260.182249)
		(end 135.447024 -260.11505)
		(width 0.088646)
		(layer "In11.Cu")
		(net "M_H_CPU1_SA_DQS_DN<9>")
	)
	(arc
		(start 135.057896 -260.106414)
		(mid 134.781337 -260.182157)
		(end 134.50316 -260.11251)
		(width 0.088646)
		(layer "In11.Cu")
		(net "M_H_CPU1_SA_DQS_DN<9>")
	)
	(arc
		(start 136.937496 -260.106414)
		(mid 136.663297 -260.182249)
		(end 136.386824 -260.11505)
		(width 0.088646)
		(layer "In11.Cu")
		(net "M_H_CPU1_SA_DQS_DN<9>")
	)
	(arc
		(start 139.379198 -262.049768)
		(mid 139.188324 -261.731959)
		(end 138.817604 -261.734046)
		(width 0.088646)
		(layer "In11.Cu")
		(net "M_H_CPU1_SA_DQS_DN<9>")
	)
	(arc
		(start 132.23875 -260.106414)
		(mid 131.964551 -260.182249)
		(end 131.688078 -260.11505)
		(width 0.088646)
		(layer "In11.Cu")
		(net "M_H_CPU1_SA_DQS_DN<9>")
	)
	(arc
		(start 137.311892 -260.106414)
		(mid 137.124694 -260.056271)
		(end 136.937496 -260.106414)
		(width 0.088646)
		(layer "In11.Cu")
		(net "M_H_CPU1_SA_DQS_DN<9>")
	)
	(arc
		(start 134.492746 -260.106414)
		(mid 134.305548 -260.056271)
		(end 134.11835 -260.106414)
		(width 0.088646)
		(layer "In11.Cu")
		(net "M_H_CPU1_SA_DQS_DN<9>")
	)
	(arc
		(start 133.552692 -260.106414)
		(mid 133.365494 -260.056271)
		(end 133.178296 -260.106414)
		(width 0.088646)
		(layer "In11.Cu")
		(net "M_H_CPU1_SA_DQS_DN<9>")
	)
	(arc
		(start 129.41935 -260.106414)
		(mid 129.145151 -260.182249)
		(end 128.868678 -260.11505)
		(width 0.088646)
		(layer "In11.Cu")
		(net "M_H_CPU1_SA_DQS_DN<9>")
	)
	(arc
		(start 129.793746 -260.106414)
		(mid 129.606548 -260.056271)
		(end 129.41935 -260.106414)
		(width 0.088646)
		(layer "In11.Cu")
		(net "M_H_CPU1_SA_DQS_DN<9>")
	)
	(arc
		(start 136.372092 -260.106414)
		(mid 136.184894 -260.056271)
		(end 135.997696 -260.106414)
		(width 0.088646)
		(layer "In11.Cu")
		(net "M_H_CPU1_SA_DQS_DN<9>")
	)
	(arc
		(start 131.673346 -260.106414)
		(mid 131.486148 -260.056271)
		(end 131.29895 -260.106414)
		(width 0.088646)
		(layer "In11.Cu")
		(net "M_H_CPU1_SA_DQS_DN<9>")
	)
	(arc
		(start 128.853946 -260.106414)
		(mid 128.666748 -260.056271)
		(end 128.47955 -260.106414)
		(width 0.088646)
		(layer "In11.Cu")
		(net "M_H_CPU1_SA_DQS_DN<9>")
	)
	(arc
		(start 130.35915 -260.106414)
		(mid 130.084951 -260.182249)
		(end 129.808478 -260.11505)
		(width 0.088646)
		(layer "In11.Cu")
		(net "M_H_CPU1_SA_DQS_DN<9>")
	)
	(arc
		(start 127.53975 -260.106414)
		(mid 127.262937 -260.182284)
		(end 126.984506 -260.11251)
		(width 0.088646)
		(layer "In11.Cu")
		(net "M_H_CPU1_SA_DQS_DN<9>")
	)
	(arc
		(start 133.178296 -260.106414)
		(mid 132.901737 -260.182157)
		(end 132.62356 -260.11251)
		(width 0.088646)
		(layer "In11.Cu")
		(net "M_H_CPU1_SA_DQS_DN<9>")
	)
	(segment
		(start 210.286092 -283.597858)
		(end 210.598258 -283.597858)
		(width 0.20066)
		(layer "F.Cu")
		(net "M_H_CPU1_SA_DQS_DN<8>")
	)
	(segment
		(start 210.60918 -283.591762)
		(end 212.619336 -283.591762)
		(width 0.1016)
		(layer "F.Cu")
		(net "M_H_CPU1_SA_DQS_DN<8>")
	)
	(segment
		(start 125.847094 -265.313922)
		(end 125.847348 -265.314176)
		(width 0.20066)
		(layer "F.Cu")
		(net "M_H_CPU1_SA_DQS_DN<8>")
	)
	(segment
		(start 208.176114 -284.016704)
		(end 208.70672 -284.016704)
		(width 0.20066)
		(layer "F.Cu")
		(net "M_H_CPU1_SA_DQS_DN<8>")
	)
	(segment
		(start 207.071214 -284.016704)
		(end 208.176114 -284.016704)
		(width 0.20066)
		(layer "F.Cu")
		(net "M_H_CPU1_SA_DQS_DN<8>")
	)
	(segment
		(start 212.630258 -283.602684)
		(end 212.949028 -283.602684)
		(width 0.20066)
		(layer "F.Cu")
		(net "M_H_CPU1_SA_DQS_DN<8>")
	)
	(segment
		(start 215.216232 -284.016704)
		(end 215.719914 -284.016704)
		(width 0.20066)
		(layer "F.Cu")
		(net "M_H_CPU1_SA_DQS_DN<8>")
	)
	(segment
		(start 212.949028 -283.602684)
		(end 213.234778 -283.316934)
		(width 0.20066)
		(layer "F.Cu")
		(net "M_H_CPU1_SA_DQS_DN<8>")
	)
	(segment
		(start 210.598258 -283.597858)
		(end 210.603084 -283.597858)
		(width 0.101854)
		(layer "F.Cu")
		(net "M_H_CPU1_SA_DQS_DN<8>")
	)
	(segment
		(start 213.724744 -283.316934)
		(end 214.17026 -283.76245)
		(width 0.20066)
		(layer "F.Cu")
		(net "M_H_CPU1_SA_DQS_DN<8>")
	)
	(segment
		(start 208.70672 -284.016704)
		(end 208.977992 -283.745432)
		(width 0.20066)
		(layer "F.Cu")
		(net "M_H_CPU1_SA_DQS_DN<8>")
	)
	(segment
		(start 214.17026 -283.76245)
		(end 214.961978 -283.76245)
		(width 0.20066)
		(layer "F.Cu")
		(net "M_H_CPU1_SA_DQS_DN<8>")
	)
	(segment
		(start 213.234778 -283.316934)
		(end 213.724744 -283.316934)
		(width 0.20066)
		(layer "F.Cu")
		(net "M_H_CPU1_SA_DQS_DN<8>")
	)
	(segment
		(start 209.886296 -283.32049)
		(end 210.008724 -283.32049)
		(width 0.20066)
		(layer "F.Cu")
		(net "M_H_CPU1_SA_DQS_DN<8>")
	)
	(segment
		(start 214.961978 -283.76245)
		(end 215.216232 -284.016704)
		(width 0.20066)
		(layer "F.Cu")
		(net "M_H_CPU1_SA_DQS_DN<8>")
	)
	(segment
		(start 210.008724 -283.32049)
		(end 210.286092 -283.597858)
		(width 0.20066)
		(layer "F.Cu")
		(net "M_H_CPU1_SA_DQS_DN<8>")
	)
	(segment
		(start 209.461354 -283.745432)
		(end 209.886296 -283.32049)
		(width 0.20066)
		(layer "F.Cu")
		(net "M_H_CPU1_SA_DQS_DN<8>")
	)
	(segment
		(start 208.977992 -283.745432)
		(end 209.461354 -283.745432)
		(width 0.20066)
		(layer "F.Cu")
		(net "M_H_CPU1_SA_DQS_DN<8>")
	)
	(segment
		(start 210.603084 -283.597858)
		(end 210.60918 -283.591762)
		(width 0.1016)
		(layer "F.Cu")
		(net "M_H_CPU1_SA_DQS_DN<8>")
	)
	(segment
		(start 125.847094 -264.778236)
		(end 125.847094 -265.313922)
		(width 0.20066)
		(layer "F.Cu")
		(net "M_H_CPU1_SA_DQS_DN<8>")
	)
	(segment
		(start 212.619336 -283.591762)
		(end 212.630258 -283.602684)
		(width 0.1016)
		(layer "F.Cu")
		(net "M_H_CPU1_SA_DQS_DN<8>")
	)
	(segment
		(start 178.91252 -285.796736)
		(end 177.983134 -286.726122)
		(width 0.18288)
		(layer "In11.Cu")
		(net "M_H_CPU1_SA_DQS_DN<8>")
	)
	(segment
		(start 135.149844 -266.128246)
		(end 135.149844 -266.119864)
		(width 0.088646)
		(layer "In11.Cu")
		(net "M_H_CPU1_SA_DQS_DN<8>")
	)
	(segment
		(start 161.475928 -283.813504)
		(end 161.299906 -283.813504)
		(width 0.18288)
		(layer "In11.Cu")
		(net "M_H_CPU1_SA_DQS_DN<8>")
	)
	(segment
		(start 192.211706 -286.99079)
		(end 191.689482 -286.99079)
		(width 0.18288)
		(layer "In11.Cu")
		(net "M_H_CPU1_SA_DQS_DN<8>")
	)
	(segment
		(start 174.100998 -287.442656)
		(end 173.778418 -287.57626)
		(width 0.18288)
		(layer "In11.Cu")
		(net "M_H_CPU1_SA_DQS_DN<8>")
	)
	(segment
		(start 156.378148 -281.943302)
		(end 156.378148 -281.76728)
		(width 0.18288)
		(layer "In11.Cu")
		(net "M_H_CPU1_SA_DQS_DN<8>")
	)
	(segment
		(start 140.684504 -268.900656)
		(end 140.62456 -268.840712)
		(width 0.088646)
		(layer "In11.Cu")
		(net "M_H_CPU1_SA_DQS_DN<8>")
	)
	(segment
		(start 185.91657 -286.021272)
		(end 185.36793 -286.021272)
		(width 0.18288)
		(layer "In11.Cu")
		(net "M_H_CPU1_SA_DQS_DN<8>")
	)
	(segment
		(start 188.376306 -285.876238)
		(end 188.111638 -286.140906)
		(width 0.18288)
		(layer "In11.Cu")
		(net "M_H_CPU1_SA_DQS_DN<8>")
	)
	(segment
		(start 177.124106 -286.99079)
		(end 176.601882 -286.99079)
		(width 0.18288)
		(layer "In11.Cu")
		(net "M_H_CPU1_SA_DQS_DN<8>")
	)
	(segment
		(start 171.836588 -287.602676)
		(end 170.608752 -286.988758)
		(width 0.18288)
		(layer "In11.Cu")
		(net "M_H_CPU1_SA_DQS_DN<8>")
	)
	(segment
		(start 166.098982 -285.259272)
		(end 165.424358 -285.259272)
		(width 0.18288)
		(layer "In11.Cu")
		(net "M_H_CPU1_SA_DQS_DN<8>")
	)
	(segment
		(start 140.62456 -268.840712)
		(end 139.76096 -268.840712)
		(width 0.088646)
		(layer "In11.Cu")
		(net "M_H_CPU1_SA_DQS_DN<8>")
	)
	(segment
		(start 134.971282 -265.808968)
		(end 134.962392 -265.803888)
		(width 0.088646)
		(layer "In11.Cu")
		(net "M_H_CPU1_SA_DQS_DN<8>")
	)
	(segment
		(start 187.589414 -286.140906)
		(end 187.34532 -285.896812)
		(width 0.18288)
		(layer "In11.Cu")
		(net "M_H_CPU1_SA_DQS_DN<8>")
	)
	(segment
		(start 200.275444 -284.380432)
		(end 198.93534 -284.380432)
		(width 0.18288)
		(layer "In11.Cu")
		(net "M_H_CPU1_SA_DQS_DN<8>")
	)
	(segment
		(start 155.814268 -281.379422)
		(end 155.426156 -280.99131)
		(width 0.18288)
		(layer "In11.Cu")
		(net "M_H_CPU1_SA_DQS_DN<8>")
	)
	(segment
		(start 174.50435 -287.039304)
		(end 174.100998 -287.442656)
		(width 0.18288)
		(layer "In11.Cu")
		(net "M_H_CPU1_SA_DQS_DN<8>")
	)
	(segment
		(start 170.608752 -286.988758)
		(end 169.654728 -286.034734)
		(width 0.18288)
		(layer "In11.Cu")
		(net "M_H_CPU1_SA_DQS_DN<8>")
	)
	(segment
		(start 129.808478 -264.998454)
		(end 129.793746 -264.989818)
		(width 0.088646)
		(layer "In11.Cu")
		(net "M_H_CPU1_SA_DQS_DN<8>")
	)
	(segment
		(start 125.847348 -265.189208)
		(end 125.847348 -265.314176)
		(width 0.088646)
		(layer "In11.Cu")
		(net "M_H_CPU1_SA_DQS_DN<8>")
	)
	(segment
		(start 188.111638 -286.140906)
		(end 187.589414 -286.140906)
		(width 0.18288)
		(layer "In11.Cu")
		(net "M_H_CPU1_SA_DQS_DN<8>")
	)
	(segment
		(start 155.426156 -280.99131)
		(end 155.426156 -280.815288)
		(width 0.18288)
		(layer "In11.Cu")
		(net "M_H_CPU1_SA_DQS_DN<8>")
	)
	(segment
		(start 160.91154 -283.425138)
		(end 160.91154 -283.249116)
		(width 0.18288)
		(layer "In11.Cu")
		(net "M_H_CPU1_SA_DQS_DN<8>")
	)
	(segment
		(start 125.930152 -265.09345)
		(end 125.856746 -265.166856)
		(width 0.088646)
		(layer "In11.Cu")
		(net "M_H_CPU1_SA_DQS_DN<8>")
	)
	(segment
		(start 202.358752 -283.324046)
		(end 202.097386 -283.585412)
		(width 0.18288)
		(layer "In11.Cu")
		(net "M_H_CPU1_SA_DQS_DN<8>")
	)
	(segment
		(start 134.49427 -264.99058)
		(end 134.492746 -264.989818)
		(width 0.088646)
		(layer "In11.Cu")
		(net "M_H_CPU1_SA_DQS_DN<8>")
	)
	(segment
		(start 127.539496 -264.989818)
		(end 127.53213 -264.994136)
		(width 0.088646)
		(layer "In11.Cu")
		(net "M_H_CPU1_SA_DQS_DN<8>")
	)
	(segment
		(start 177.388774 -286.726122)
		(end 177.124106 -286.99079)
		(width 0.18288)
		(layer "In11.Cu")
		(net "M_H_CPU1_SA_DQS_DN<8>")
	)
	(segment
		(start 196.069458 -285.241746)
		(end 195.944998 -285.117286)
		(width 0.18288)
		(layer "In11.Cu")
		(net "M_H_CPU1_SA_DQS_DN<8>")
	)
	(segment
		(start 181.216554 -285.335218)
		(end 181.092094 -285.210758)
		(width 0.18288)
		(layer "In11.Cu")
		(net "M_H_CPU1_SA_DQS_DN<8>")
	)
	(segment
		(start 173.778418 -287.57626)
		(end 173.288706 -287.57626)
		(width 0.18288)
		(layer "In11.Cu")
		(net "M_H_CPU1_SA_DQS_DN<8>")
	)
	(segment
		(start 176.601882 -286.99079)
		(end 176.329086 -286.717994)
		(width 0.18288)
		(layer "In11.Cu")
		(net "M_H_CPU1_SA_DQS_DN<8>")
	)
	(segment
		(start 134.501636 -264.994898)
		(end 134.49427 -264.99058)
		(width 0.088646)
		(layer "In11.Cu")
		(net "M_H_CPU1_SA_DQS_DN<8>")
	)
	(segment
		(start 164.834824 -285.015432)
		(end 164.250116 -284.43047)
		(width 0.18288)
		(layer "In11.Cu")
		(net "M_H_CPU1_SA_DQS_DN<8>")
	)
	(segment
		(start 139.02563 -268.33576)
		(end 138.589258 -268.33576)
		(width 0.088646)
		(layer "In11.Cu")
		(net "M_H_CPU1_SA_DQS_DN<8>")
	)
	(segment
		(start 161.299906 -283.813504)
		(end 160.91154 -283.425138)
		(width 0.18288)
		(layer "In11.Cu")
		(net "M_H_CPU1_SA_DQS_DN<8>")
	)
	(segment
		(start 202.848718 -283.578554)
		(end 202.776582 -283.578554)
		(width 0.18288)
		(layer "In11.Cu")
		(net "M_H_CPU1_SA_DQS_DN<8>")
	)
	(segment
		(start 203.471526 -283.306012)
		(end 203.198984 -283.578554)
		(width 0.18288)
		(layer "In11.Cu")
		(net "M_H_CPU1_SA_DQS_DN<8>")
	)
	(segment
		(start 193.460878 -286.387032)
		(end 193.121788 -286.726122)
		(width 0.18288)
		(layer "In11.Cu")
		(net "M_H_CPU1_SA_DQS_DN<8>")
	)
	(segment
		(start 190.56096 -286.723582)
		(end 189.591188 -286.321754)
		(width 0.18288)
		(layer "In11.Cu")
		(net "M_H_CPU1_SA_DQS_DN<8>")
	)
	(segment
		(start 135.44042 -266.622276)
		(end 135.42645 -266.614148)
		(width 0.088646)
		(layer "In11.Cu")
		(net "M_H_CPU1_SA_DQS_DN<8>")
	)
	(segment
		(start 155.99029 -281.379422)
		(end 155.814268 -281.379422)
		(width 0.18288)
		(layer "In11.Cu")
		(net "M_H_CPU1_SA_DQS_DN<8>")
	)
	(segment
		(start 187.34532 -285.896812)
		(end 186.04103 -285.896812)
		(width 0.18288)
		(layer "In11.Cu")
		(net "M_H_CPU1_SA_DQS_DN<8>")
	)
	(segment
		(start 157.33014 -282.719272)
		(end 156.942282 -282.331414)
		(width 0.18288)
		(layer "In11.Cu")
		(net "M_H_CPU1_SA_DQS_DN<8>")
	)
	(segment
		(start 191.689482 -286.99079)
		(end 191.422274 -286.723582)
		(width 0.18288)
		(layer "In11.Cu")
		(net "M_H_CPU1_SA_DQS_DN<8>")
	)
	(segment
		(start 204.342238 -283.650182)
		(end 203.998068 -283.306012)
		(width 0.18288)
		(layer "In11.Cu")
		(net "M_H_CPU1_SA_DQS_DN<8>")
	)
	(segment
		(start 158.93923 -282.843732)
		(end 158.39059 -282.843732)
		(width 0.18288)
		(layer "In11.Cu")
		(net "M_H_CPU1_SA_DQS_DN<8>")
	)
	(segment
		(start 205.751938 -283.755846)
		(end 205.364842 -283.91612)
		(width 0.18288)
		(layer "In11.Cu")
		(net "M_H_CPU1_SA_DQS_DN<8>")
	)
	(segment
		(start 155.038298 -280.42743)
		(end 154.862276 -280.42743)
		(width 0.18288)
		(layer "In11.Cu")
		(net "M_H_CPU1_SA_DQS_DN<8>")
	)
	(segment
		(start 164.250116 -284.43047)
		(end 163.439094 -284.43047)
		(width 0.18288)
		(layer "In11.Cu")
		(net "M_H_CPU1_SA_DQS_DN<8>")
	)
	(segment
		(start 193.121788 -286.726122)
		(end 192.476374 -286.726122)
		(width 0.18288)
		(layer "In11.Cu")
		(net "M_H_CPU1_SA_DQS_DN<8>")
	)
	(segment
		(start 165.424358 -285.259272)
		(end 164.834824 -285.015432)
		(width 0.18288)
		(layer "In11.Cu")
		(net "M_H_CPU1_SA_DQS_DN<8>")
	)
	(segment
		(start 196.618098 -285.241746)
		(end 196.069458 -285.241746)
		(width 0.18288)
		(layer "In11.Cu")
		(net "M_H_CPU1_SA_DQS_DN<8>")
	)
	(segment
		(start 135.619744 -266.96035)
		(end 135.619744 -266.941808)
		(width 0.088646)
		(layer "In11.Cu")
		(net "M_H_CPU1_SA_DQS_DN<8>")
	)
	(segment
		(start 203.198984 -283.578554)
		(end 203.082398 -283.578554)
		(width 0.18288)
		(layer "In11.Cu")
		(net "M_H_CPU1_SA_DQS_DN<8>")
	)
	(segment
		(start 154.474164 -280.039318)
		(end 154.474164 -279.863296)
		(width 0.18288)
		(layer "In11.Cu")
		(net "M_H_CPU1_SA_DQS_DN<8>")
	)
	(segment
		(start 169.654728 -286.034734)
		(end 167.781986 -285.259272)
		(width 0.18288)
		(layer "In11.Cu")
		(net "M_H_CPU1_SA_DQS_DN<8>")
	)
	(segment
		(start 135.911082 -267.4366)
		(end 135.902192 -267.43152)
		(width 0.088646)
		(layer "In11.Cu")
		(net "M_H_CPU1_SA_DQS_DN<8>")
	)
	(segment
		(start 155.426156 -280.815288)
		(end 155.038298 -280.42743)
		(width 0.18288)
		(layer "In11.Cu")
		(net "M_H_CPU1_SA_DQS_DN<8>")
	)
	(segment
		(start 128.479296 -264.989818)
		(end 128.47193 -264.994136)
		(width 0.088646)
		(layer "In11.Cu")
		(net "M_H_CPU1_SA_DQS_DN<8>")
	)
	(segment
		(start 175.278796 -286.717994)
		(end 174.50435 -287.039304)
		(width 0.18288)
		(layer "In11.Cu")
		(net "M_H_CPU1_SA_DQS_DN<8>")
	)
	(segment
		(start 206.810356 -283.755846)
		(end 205.751938 -283.755846)
		(width 0.18288)
		(layer "In11.Cu")
		(net "M_H_CPU1_SA_DQS_DN<8>")
	)
	(segment
		(start 166.896542 -285.259272)
		(end 166.772082 -285.383732)
		(width 0.18288)
		(layer "In11.Cu")
		(net "M_H_CPU1_SA_DQS_DN<8>")
	)
	(segment
		(start 163.314634 -284.55493)
		(end 162.765994 -284.55493)
		(width 0.18288)
		(layer "In11.Cu")
		(net "M_H_CPU1_SA_DQS_DN<8>")
	)
	(segment
		(start 158.26613 -282.719272)
		(end 157.33014 -282.719272)
		(width 0.18288)
		(layer "In11.Cu")
		(net "M_H_CPU1_SA_DQS_DN<8>")
	)
	(segment
		(start 131.688078 -264.998454)
		(end 131.673346 -264.989818)
		(width 0.088646)
		(layer "In11.Cu")
		(net "M_H_CPU1_SA_DQS_DN<8>")
	)
	(segment
		(start 176.329086 -286.717994)
		(end 175.278796 -286.717994)
		(width 0.18288)
		(layer "In11.Cu")
		(net "M_H_CPU1_SA_DQS_DN<8>")
	)
	(segment
		(start 194.597528 -285.916116)
		(end 193.460878 -286.387032)
		(width 0.18288)
		(layer "In11.Cu")
		(net "M_H_CPU1_SA_DQS_DN<8>")
	)
	(segment
		(start 195.396358 -285.117286)
		(end 194.597528 -285.916116)
		(width 0.18288)
		(layer "In11.Cu")
		(net "M_H_CPU1_SA_DQS_DN<8>")
	)
	(segment
		(start 127.544068 -264.987024)
		(end 127.539496 -264.989818)
		(width 0.088646)
		(layer "In11.Cu")
		(net "M_H_CPU1_SA_DQS_DN<8>")
	)
	(segment
		(start 205.364842 -283.91612)
		(end 204.98435 -283.91612)
		(width 0.18288)
		(layer "In11.Cu")
		(net "M_H_CPU1_SA_DQS_DN<8>")
	)
	(segment
		(start 201.070464 -283.585412)
		(end 200.275444 -284.380432)
		(width 0.18288)
		(layer "In11.Cu")
		(net "M_H_CPU1_SA_DQS_DN<8>")
	)
	(segment
		(start 143.511524 -268.900656)
		(end 140.684504 -268.900656)
		(width 0.18288)
		(layer "In11.Cu")
		(net "M_H_CPU1_SA_DQS_DN<8>")
	)
	(segment
		(start 126.604268 -264.987024)
		(end 126.59233 -264.994136)
		(width 0.088646)
		(layer "In11.Cu")
		(net "M_H_CPU1_SA_DQS_DN<8>")
	)
	(segment
		(start 198.198486 -285.117286)
		(end 196.742558 -285.117286)
		(width 0.18288)
		(layer "In11.Cu")
		(net "M_H_CPU1_SA_DQS_DN<8>")
	)
	(segment
		(start 133.178296 -264.989818)
		(end 133.167882 -264.995914)
		(width 0.088646)
		(layer "In11.Cu")
		(net "M_H_CPU1_SA_DQS_DN<8>")
	)
	(segment
		(start 191.422274 -286.723582)
		(end 190.56096 -286.723582)
		(width 0.18288)
		(layer "In11.Cu")
		(net "M_H_CPU1_SA_DQS_DN<8>")
	)
	(segment
		(start 128.483868 -264.987024)
		(end 128.479296 -264.989818)
		(width 0.088646)
		(layer "In11.Cu")
		(net "M_H_CPU1_SA_DQS_DN<8>")
	)
	(segment
		(start 162.092894 -284.43047)
		(end 161.475928 -283.813504)
		(width 0.18288)
		(layer "In11.Cu")
		(net "M_H_CPU1_SA_DQS_DN<8>")
	)
	(segment
		(start 177.983134 -286.726122)
		(end 177.388774 -286.726122)
		(width 0.18288)
		(layer "In11.Cu")
		(net "M_H_CPU1_SA_DQS_DN<8>")
	)
	(segment
		(start 181.765194 -285.335218)
		(end 181.216554 -285.335218)
		(width 0.18288)
		(layer "In11.Cu")
		(net "M_H_CPU1_SA_DQS_DN<8>")
	)
	(segment
		(start 130.748278 -264.998454)
		(end 130.733546 -264.989818)
		(width 0.088646)
		(layer "In11.Cu")
		(net "M_H_CPU1_SA_DQS_DN<8>")
	)
	(segment
		(start 136.089644 -267.765784)
		(end 136.089644 -267.755878)
		(width 0.088646)
		(layer "In11.Cu")
		(net "M_H_CPU1_SA_DQS_DN<8>")
	)
	(segment
		(start 139.76096 -268.840712)
		(end 139.485878 -268.56563)
		(width 0.088646)
		(layer "In11.Cu")
		(net "M_H_CPU1_SA_DQS_DN<8>")
	)
	(segment
		(start 203.998068 -283.306012)
		(end 203.471526 -283.306012)
		(width 0.18288)
		(layer "In11.Cu")
		(net "M_H_CPU1_SA_DQS_DN<8>")
	)
	(segment
		(start 163.439094 -284.43047)
		(end 163.314634 -284.55493)
		(width 0.18288)
		(layer "In11.Cu")
		(net "M_H_CPU1_SA_DQS_DN<8>")
	)
	(segment
		(start 125.856746 -265.166856)
		(end 125.847348 -265.189208)
		(width 0.088646)
		(layer "In11.Cu")
		(net "M_H_CPU1_SA_DQS_DN<8>")
	)
	(segment
		(start 135.149844 -266.119864)
		(end 135.14959 -266.113514)
		(width 0.088646)
		(layer "In11.Cu")
		(net "M_H_CPU1_SA_DQS_DN<8>")
	)
	(segment
		(start 160.381696 -282.719272)
		(end 159.06369 -282.719272)
		(width 0.18288)
		(layer "In11.Cu")
		(net "M_H_CPU1_SA_DQS_DN<8>")
	)
	(segment
		(start 192.476374 -286.726122)
		(end 192.211706 -286.99079)
		(width 0.18288)
		(layer "In11.Cu")
		(net "M_H_CPU1_SA_DQS_DN<8>")
	)
	(segment
		(start 195.944998 -285.117286)
		(end 195.396358 -285.117286)
		(width 0.18288)
		(layer "In11.Cu")
		(net "M_H_CPU1_SA_DQS_DN<8>")
	)
	(segment
		(start 139.485878 -268.56563)
		(end 139.255246 -268.56563)
		(width 0.088646)
		(layer "In11.Cu")
		(net "M_H_CPU1_SA_DQS_DN<8>")
	)
	(segment
		(start 162.765994 -284.55493)
		(end 162.641534 -284.43047)
		(width 0.18288)
		(layer "In11.Cu")
		(net "M_H_CPU1_SA_DQS_DN<8>")
	)
	(segment
		(start 133.563106 -264.995914)
		(end 133.552692 -264.989818)
		(width 0.088646)
		(layer "In11.Cu")
		(net "M_H_CPU1_SA_DQS_DN<8>")
	)
	(segment
		(start 156.378148 -281.76728)
		(end 155.99029 -281.379422)
		(width 0.18288)
		(layer "In11.Cu")
		(net "M_H_CPU1_SA_DQS_DN<8>")
	)
	(segment
		(start 160.91154 -283.249116)
		(end 160.381696 -282.719272)
		(width 0.18288)
		(layer "In11.Cu")
		(net "M_H_CPU1_SA_DQS_DN<8>")
	)
	(segment
		(start 185.36793 -286.021272)
		(end 185.24347 -285.896812)
		(width 0.18288)
		(layer "In11.Cu")
		(net "M_H_CPU1_SA_DQS_DN<8>")
	)
	(segment
		(start 172.263562 -287.602676)
		(end 171.836588 -287.602676)
		(width 0.18288)
		(layer "In11.Cu")
		(net "M_H_CPU1_SA_DQS_DN<8>")
	)
	(segment
		(start 156.942282 -282.331414)
		(end 156.76626 -282.331414)
		(width 0.18288)
		(layer "In11.Cu")
		(net "M_H_CPU1_SA_DQS_DN<8>")
	)
	(segment
		(start 154.862276 -280.42743)
		(end 154.474164 -280.039318)
		(width 0.18288)
		(layer "In11.Cu")
		(net "M_H_CPU1_SA_DQS_DN<8>")
	)
	(segment
		(start 185.24347 -285.896812)
		(end 184.307734 -285.896812)
		(width 0.18288)
		(layer "In11.Cu")
		(net "M_H_CPU1_SA_DQS_DN<8>")
	)
	(segment
		(start 159.06369 -282.719272)
		(end 158.93923 -282.843732)
		(width 0.18288)
		(layer "In11.Cu")
		(net "M_H_CPU1_SA_DQS_DN<8>")
	)
	(segment
		(start 186.04103 -285.896812)
		(end 185.91657 -286.021272)
		(width 0.18288)
		(layer "In11.Cu")
		(net "M_H_CPU1_SA_DQS_DN<8>")
	)
	(segment
		(start 202.776582 -283.578554)
		(end 202.522074 -283.324046)
		(width 0.18288)
		(layer "In11.Cu")
		(net "M_H_CPU1_SA_DQS_DN<8>")
	)
	(segment
		(start 203.082398 -283.578554)
		(end 202.848718 -283.578554)
		(width 0.16002)
		(layer "In11.Cu")
		(net "M_H_CPU1_SA_DQS_DN<8>")
	)
	(segment
		(start 182.6514 -285.210758)
		(end 181.889654 -285.210758)
		(width 0.18288)
		(layer "In11.Cu")
		(net "M_H_CPU1_SA_DQS_DN<8>")
	)
	(segment
		(start 204.98435 -283.91612)
		(end 204.342238 -283.650182)
		(width 0.18288)
		(layer "In11.Cu")
		(net "M_H_CPU1_SA_DQS_DN<8>")
	)
	(segment
		(start 158.39059 -282.843732)
		(end 158.26613 -282.719272)
		(width 0.18288)
		(layer "In11.Cu")
		(net "M_H_CPU1_SA_DQS_DN<8>")
	)
	(segment
		(start 198.93534 -284.380432)
		(end 198.198486 -285.117286)
		(width 0.18288)
		(layer "In11.Cu")
		(net "M_H_CPU1_SA_DQS_DN<8>")
	)
	(segment
		(start 167.781986 -285.259272)
		(end 166.896542 -285.259272)
		(width 0.18288)
		(layer "In11.Cu")
		(net "M_H_CPU1_SA_DQS_DN<8>")
	)
	(segment
		(start 202.097386 -283.585412)
		(end 201.070464 -283.585412)
		(width 0.18288)
		(layer "In11.Cu")
		(net "M_H_CPU1_SA_DQS_DN<8>")
	)
	(segment
		(start 166.772082 -285.383732)
		(end 166.223442 -285.383732)
		(width 0.18288)
		(layer "In11.Cu")
		(net "M_H_CPU1_SA_DQS_DN<8>")
	)
	(segment
		(start 173.288706 -287.57626)
		(end 173.024038 -287.840928)
		(width 0.18288)
		(layer "In11.Cu")
		(net "M_H_CPU1_SA_DQS_DN<8>")
	)
	(segment
		(start 189.145672 -285.876238)
		(end 188.376306 -285.876238)
		(width 0.18288)
		(layer "In11.Cu")
		(net "M_H_CPU1_SA_DQS_DN<8>")
	)
	(segment
		(start 166.223442 -285.383732)
		(end 166.098982 -285.259272)
		(width 0.18288)
		(layer "In11.Cu")
		(net "M_H_CPU1_SA_DQS_DN<8>")
	)
	(segment
		(start 196.742558 -285.117286)
		(end 196.618098 -285.241746)
		(width 0.18288)
		(layer "In11.Cu")
		(net "M_H_CPU1_SA_DQS_DN<8>")
	)
	(segment
		(start 207.071214 -284.016704)
		(end 206.810356 -283.755846)
		(width 0.18288)
		(layer "In11.Cu")
		(net "M_H_CPU1_SA_DQS_DN<8>")
	)
	(segment
		(start 139.255246 -268.56563)
		(end 139.02563 -268.33576)
		(width 0.088646)
		(layer "In11.Cu")
		(net "M_H_CPU1_SA_DQS_DN<8>")
	)
	(segment
		(start 156.76626 -282.331414)
		(end 156.378148 -281.943302)
		(width 0.18288)
		(layer "In11.Cu")
		(net "M_H_CPU1_SA_DQS_DN<8>")
	)
	(segment
		(start 173.024038 -287.840928)
		(end 172.501814 -287.840928)
		(width 0.18288)
		(layer "In11.Cu")
		(net "M_H_CPU1_SA_DQS_DN<8>")
	)
	(segment
		(start 129.423668 -264.987024)
		(end 129.419096 -264.989818)
		(width 0.088646)
		(layer "In11.Cu")
		(net "M_H_CPU1_SA_DQS_DN<8>")
	)
	(segment
		(start 134.680198 -265.336274)
		(end 134.680198 -265.314176)
		(width 0.088646)
		(layer "In11.Cu")
		(net "M_H_CPU1_SA_DQS_DN<8>")
	)
	(segment
		(start 189.591188 -286.321754)
		(end 189.145672 -285.876238)
		(width 0.18288)
		(layer "In11.Cu")
		(net "M_H_CPU1_SA_DQS_DN<8>")
	)
	(segment
		(start 180.327046 -285.210758)
		(end 178.91252 -285.796736)
		(width 0.18288)
		(layer "In11.Cu")
		(net "M_H_CPU1_SA_DQS_DN<8>")
	)
	(segment
		(start 181.092094 -285.210758)
		(end 180.327046 -285.210758)
		(width 0.18288)
		(layer "In11.Cu")
		(net "M_H_CPU1_SA_DQS_DN<8>")
	)
	(segment
		(start 181.889654 -285.210758)
		(end 181.765194 -285.335218)
		(width 0.18288)
		(layer "In11.Cu")
		(net "M_H_CPU1_SA_DQS_DN<8>")
	)
	(segment
		(start 202.522074 -283.324046)
		(end 202.358752 -283.324046)
		(width 0.18288)
		(layer "In11.Cu")
		(net "M_H_CPU1_SA_DQS_DN<8>")
	)
	(segment
		(start 129.419096 -264.989818)
		(end 129.41173 -264.994136)
		(width 0.088646)
		(layer "In11.Cu")
		(net "M_H_CPU1_SA_DQS_DN<8>")
	)
	(segment
		(start 172.501814 -287.840928)
		(end 172.263562 -287.602676)
		(width 0.18288)
		(layer "In11.Cu")
		(net "M_H_CPU1_SA_DQS_DN<8>")
	)
	(segment
		(start 184.307734 -285.896812)
		(end 182.6514 -285.210758)
		(width 0.18288)
		(layer "In11.Cu")
		(net "M_H_CPU1_SA_DQS_DN<8>")
	)
	(segment
		(start 162.641534 -284.43047)
		(end 162.092894 -284.43047)
		(width 0.18288)
		(layer "In11.Cu")
		(net "M_H_CPU1_SA_DQS_DN<8>")
	)
	(segment
		(start 126.281434 -265.077702)
		(end 125.95225 -265.084052)
		(width 0.088646)
		(layer "In11.Cu")
		(net "M_H_CPU1_SA_DQS_DN<8>")
	)
	(segment
		(start 154.474164 -279.863296)
		(end 143.511524 -268.900656)
		(width 0.18288)
		(layer "In11.Cu")
		(net "M_H_CPU1_SA_DQS_DN<8>")
	)
	(arc
		(start 134.962392 -265.803888)
		(mid 134.76111 -265.606401)
		(end 134.680198 -265.336274)
		(width 0.088646)
		(layer "In11.Cu")
		(net "M_H_CPU1_SA_DQS_DN<8>")
	)
	(arc
		(start 130.35915 -264.989818)
		(mid 130.084951 -265.065653)
		(end 129.808478 -264.998454)
		(width 0.088646)
		(layer "In11.Cu")
		(net "M_H_CPU1_SA_DQS_DN<8>")
	)
	(arc
		(start 132.23875 -264.989818)
		(mid 131.964551 -265.065653)
		(end 131.688078 -264.998454)
		(width 0.088646)
		(layer "In11.Cu")
		(net "M_H_CPU1_SA_DQS_DN<8>")
	)
	(arc
		(start 133.552692 -264.989818)
		(mid 133.365494 -264.939675)
		(end 133.178296 -264.989818)
		(width 0.088646)
		(layer "In11.Cu")
		(net "M_H_CPU1_SA_DQS_DN<8>")
	)
	(arc
		(start 137.877296 -268.245336)
		(mid 137.594594 -268.321112)
		(end 137.311892 -268.245336)
		(width 0.088646)
		(layer "In11.Cu")
		(net "M_H_CPU1_SA_DQS_DN<8>")
	)
	(arc
		(start 135.619744 -266.941808)
		(mid 135.571853 -266.758596)
		(end 135.44042 -266.622276)
		(width 0.088646)
		(layer "In11.Cu")
		(net "M_H_CPU1_SA_DQS_DN<8>")
	)
	(arc
		(start 127.914146 -264.989818)
		(mid 127.729482 -264.939558)
		(end 127.544068 -264.987024)
		(width 0.088646)
		(layer "In11.Cu")
		(net "M_H_CPU1_SA_DQS_DN<8>")
	)
	(arc
		(start 127.53213 -264.994136)
		(mid 127.252779 -265.065574)
		(end 126.9746 -264.989818)
		(width 0.088646)
		(layer "In11.Cu")
		(net "M_H_CPU1_SA_DQS_DN<8>")
	)
	(arc
		(start 134.492746 -264.989818)
		(mid 134.305548 -264.939675)
		(end 134.11835 -264.989818)
		(width 0.088646)
		(layer "In11.Cu")
		(net "M_H_CPU1_SA_DQS_DN<8>")
	)
	(arc
		(start 135.902192 -267.43152)
		(mid 135.699906 -267.232539)
		(end 135.619744 -266.96035)
		(width 0.088646)
		(layer "In11.Cu")
		(net "M_H_CPU1_SA_DQS_DN<8>")
	)
	(arc
		(start 135.42645 -266.614148)
		(mid 135.223863 -266.407797)
		(end 135.149844 -266.128246)
		(width 0.088646)
		(layer "In11.Cu")
		(net "M_H_CPU1_SA_DQS_DN<8>")
	)
	(arc
		(start 128.47193 -264.994136)
		(mid 128.192469 -265.065573)
		(end 127.914146 -264.989818)
		(width 0.088646)
		(layer "In11.Cu")
		(net "M_H_CPU1_SA_DQS_DN<8>")
	)
	(arc
		(start 132.613146 -264.989818)
		(mid 132.425948 -264.939675)
		(end 132.23875 -264.989818)
		(width 0.088646)
		(layer "In11.Cu")
		(net "M_H_CPU1_SA_DQS_DN<8>")
	)
	(arc
		(start 130.733546 -264.989818)
		(mid 130.546348 -264.939675)
		(end 130.35915 -264.989818)
		(width 0.088646)
		(layer "In11.Cu")
		(net "M_H_CPU1_SA_DQS_DN<8>")
	)
	(arc
		(start 126.589028 -264.995914)
		(mid 126.440181 -265.055424)
		(end 126.281434 -265.077702)
		(width 0.088646)
		(layer "In11.Cu")
		(net "M_H_CPU1_SA_DQS_DN<8>")
	)
	(arc
		(start 138.335258 -268.28623)
		(mid 138.292767 -268.267229)
		(end 138.251692 -268.245336)
		(width 0.088646)
		(layer "In11.Cu")
		(net "M_H_CPU1_SA_DQS_DN<8>")
	)
	(arc
		(start 131.29895 -264.989818)
		(mid 131.024751 -265.065653)
		(end 130.748278 -264.998454)
		(width 0.088646)
		(layer "In11.Cu")
		(net "M_H_CPU1_SA_DQS_DN<8>")
	)
	(arc
		(start 129.793746 -264.989818)
		(mid 129.609082 -264.939558)
		(end 129.423668 -264.987024)
		(width 0.088646)
		(layer "In11.Cu")
		(net "M_H_CPU1_SA_DQS_DN<8>")
	)
	(arc
		(start 136.089644 -267.755878)
		(mid 136.041965 -267.572978)
		(end 135.911082 -267.4366)
		(width 0.088646)
		(layer "In11.Cu")
		(net "M_H_CPU1_SA_DQS_DN<8>")
	)
	(arc
		(start 135.14959 -266.113514)
		(mid 135.098536 -265.938934)
		(end 134.971282 -265.808968)
		(width 0.088646)
		(layer "In11.Cu")
		(net "M_H_CPU1_SA_DQS_DN<8>")
	)
	(arc
		(start 134.11835 -264.989818)
		(mid 133.841537 -265.065688)
		(end 133.563106 -264.995914)
		(width 0.088646)
		(layer "In11.Cu")
		(net "M_H_CPU1_SA_DQS_DN<8>")
	)
	(arc
		(start 134.680198 -265.314176)
		(mid 134.632519 -265.131276)
		(end 134.501636 -264.994898)
		(width 0.088646)
		(layer "In11.Cu")
		(net "M_H_CPU1_SA_DQS_DN<8>")
	)
	(arc
		(start 131.673346 -264.989818)
		(mid 131.486148 -264.939675)
		(end 131.29895 -264.989818)
		(width 0.088646)
		(layer "In11.Cu")
		(net "M_H_CPU1_SA_DQS_DN<8>")
	)
	(arc
		(start 126.9746 -264.989818)
		(mid 126.789793 -264.939432)
		(end 126.604268 -264.987024)
		(width 0.088646)
		(layer "In11.Cu")
		(net "M_H_CPU1_SA_DQS_DN<8>")
	)
	(arc
		(start 136.937496 -268.245336)
		(mid 136.37652 -268.247867)
		(end 136.089644 -267.765784)
		(width 0.088646)
		(layer "In11.Cu")
		(net "M_H_CPU1_SA_DQS_DN<8>")
	)
	(arc
		(start 138.251692 -268.245336)
		(mid 138.064494 -268.195193)
		(end 137.877296 -268.245336)
		(width 0.088646)
		(layer "In11.Cu")
		(net "M_H_CPU1_SA_DQS_DN<8>")
	)
	(arc
		(start 129.41173 -264.994136)
		(mid 129.132269 -265.065573)
		(end 128.853946 -264.989818)
		(width 0.088646)
		(layer "In11.Cu")
		(net "M_H_CPU1_SA_DQS_DN<8>")
	)
	(arc
		(start 138.589258 -268.33576)
		(mid 138.459859 -268.323293)
		(end 138.335258 -268.28623)
		(width 0.088646)
		(layer "In11.Cu")
		(net "M_H_CPU1_SA_DQS_DN<8>")
	)
	(arc
		(start 128.853946 -264.989818)
		(mid 128.669282 -264.939558)
		(end 128.483868 -264.987024)
		(width 0.088646)
		(layer "In11.Cu")
		(net "M_H_CPU1_SA_DQS_DN<8>")
	)
	(arc
		(start 126.59233 -264.994136)
		(mid 126.590681 -264.995028)
		(end 126.589028 -264.995914)
		(width 0.088646)
		(layer "In11.Cu")
		(net "M_H_CPU1_SA_DQS_DN<8>")
	)
	(arc
		(start 133.167882 -264.995914)
		(mid 132.889704 -265.065637)
		(end 132.613146 -264.989818)
		(width 0.088646)
		(layer "In11.Cu")
		(net "M_H_CPU1_SA_DQS_DN<8>")
	)
	(arc
		(start 125.95225 -265.084052)
		(mid 125.940298 -265.086631)
		(end 125.930152 -265.09345)
		(width 0.088646)
		(layer "In11.Cu")
		(net "M_H_CPU1_SA_DQS_DN<8>")
	)
	(arc
		(start 137.311892 -268.245336)
		(mid 137.124694 -268.195193)
		(end 136.937496 -268.245336)
		(width 0.088646)
		(layer "In11.Cu")
		(net "M_H_CPU1_SA_DQS_DN<8>")
	)
	(segment
		(start 210.286092 -292.947852)
		(end 210.598258 -292.947852)
		(width 0.20066)
		(layer "F.Cu")
		(net "M_H_CPU1_SA_DQS_DN<7>")
	)
	(segment
		(start 214.961978 -293.112444)
		(end 215.216232 -293.366698)
		(width 0.20066)
		(layer "F.Cu")
		(net "M_H_CPU1_SA_DQS_DN<7>")
	)
	(segment
		(start 210.008724 -292.670484)
		(end 210.286092 -292.947852)
		(width 0.20066)
		(layer "F.Cu")
		(net "M_H_CPU1_SA_DQS_DN<7>")
	)
	(segment
		(start 209.886296 -292.670484)
		(end 210.008724 -292.670484)
		(width 0.20066)
		(layer "F.Cu")
		(net "M_H_CPU1_SA_DQS_DN<7>")
	)
	(segment
		(start 208.977992 -293.095426)
		(end 209.461354 -293.095426)
		(width 0.20066)
		(layer "F.Cu")
		(net "M_H_CPU1_SA_DQS_DN<7>")
	)
	(segment
		(start 213.234778 -292.666928)
		(end 213.724744 -292.666928)
		(width 0.20066)
		(layer "F.Cu")
		(net "M_H_CPU1_SA_DQS_DN<7>")
	)
	(segment
		(start 208.176114 -293.366698)
		(end 208.70672 -293.366698)
		(width 0.20066)
		(layer "F.Cu")
		(net "M_H_CPU1_SA_DQS_DN<7>")
	)
	(segment
		(start 209.461354 -293.095426)
		(end 209.886296 -292.670484)
		(width 0.20066)
		(layer "F.Cu")
		(net "M_H_CPU1_SA_DQS_DN<7>")
	)
	(segment
		(start 207.071214 -293.366698)
		(end 208.176114 -293.366698)
		(width 0.20066)
		(layer "F.Cu")
		(net "M_H_CPU1_SA_DQS_DN<7>")
	)
	(segment
		(start 213.724744 -292.666928)
		(end 214.17026 -293.112444)
		(width 0.20066)
		(layer "F.Cu")
		(net "M_H_CPU1_SA_DQS_DN<7>")
	)
	(segment
		(start 212.949028 -292.952678)
		(end 213.234778 -292.666928)
		(width 0.20066)
		(layer "F.Cu")
		(net "M_H_CPU1_SA_DQS_DN<7>")
	)
	(segment
		(start 208.70672 -293.366698)
		(end 208.977992 -293.095426)
		(width 0.20066)
		(layer "F.Cu")
		(net "M_H_CPU1_SA_DQS_DN<7>")
	)
	(segment
		(start 214.17026 -293.112444)
		(end 214.961978 -293.112444)
		(width 0.20066)
		(layer "F.Cu")
		(net "M_H_CPU1_SA_DQS_DN<7>")
	)
	(segment
		(start 212.619336 -292.941756)
		(end 212.630258 -292.952678)
		(width 0.1016)
		(layer "F.Cu")
		(net "M_H_CPU1_SA_DQS_DN<7>")
	)
	(segment
		(start 210.603084 -292.947852)
		(end 210.60918 -292.941756)
		(width 0.1016)
		(layer "F.Cu")
		(net "M_H_CPU1_SA_DQS_DN<7>")
	)
	(segment
		(start 215.216232 -293.366698)
		(end 215.719914 -293.366698)
		(width 0.20066)
		(layer "F.Cu")
		(net "M_H_CPU1_SA_DQS_DN<7>")
	)
	(segment
		(start 210.60918 -292.941756)
		(end 212.619336 -292.941756)
		(width 0.1016)
		(layer "F.Cu")
		(net "M_H_CPU1_SA_DQS_DN<7>")
	)
	(segment
		(start 125.847348 -270.167862)
		(end 125.847348 -270.19758)
		(width 0.20066)
		(layer "F.Cu")
		(net "M_H_CPU1_SA_DQS_DN<7>")
	)
	(segment
		(start 125.847094 -269.66164)
		(end 125.847348 -270.167862)
		(width 0.20066)
		(layer "F.Cu")
		(net "M_H_CPU1_SA_DQS_DN<7>")
	)
	(segment
		(start 212.630258 -292.952678)
		(end 212.949028 -292.952678)
		(width 0.20066)
		(layer "F.Cu")
		(net "M_H_CPU1_SA_DQS_DN<7>")
	)
	(segment
		(start 210.598258 -292.947852)
		(end 210.603084 -292.947852)
		(width 0.101854)
		(layer "F.Cu")
		(net "M_H_CPU1_SA_DQS_DN<7>")
	)
	(segment
		(start 155.07335 -291.96284)
		(end 154.685238 -291.574728)
		(width 0.18288)
		(layer "In11.Cu")
		(net "M_H_CPU1_SA_DQS_DN<7>")
	)
	(segment
		(start 183.503316 -296.937684)
		(end 182.888382 -296.32275)
		(width 0.18288)
		(layer "In11.Cu")
		(net "M_H_CPU1_SA_DQS_DN<7>")
	)
	(segment
		(start 160.55721 -295.003728)
		(end 159.734758 -294.18153)
		(width 0.18288)
		(layer "In11.Cu")
		(net "M_H_CPU1_SA_DQS_DN<7>")
	)
	(segment
		(start 206.371444 -293.273734)
		(end 205.76921 -293.273734)
		(width 0.18288)
		(layer "In11.Cu")
		(net "M_H_CPU1_SA_DQS_DN<7>")
	)
	(segment
		(start 153.733246 -290.446714)
		(end 152.786588 -289.500056)
		(width 0.18288)
		(layer "In11.Cu")
		(net "M_H_CPU1_SA_DQS_DN<7>")
	)
	(segment
		(start 166.579296 -296.330878)
		(end 166.454836 -296.455338)
		(width 0.18288)
		(layer "In11.Cu")
		(net "M_H_CPU1_SA_DQS_DN<7>")
	)
	(segment
		(start 203.200254 -292.940232)
		(end 203.076048 -292.940232)
		(width 0.18288)
		(layer "In11.Cu")
		(net "M_H_CPU1_SA_DQS_DN<7>")
	)
	(segment
		(start 130.920998 -271.84731)
		(end 130.920998 -271.825212)
		(width 0.088646)
		(layer "In11.Cu")
		(net "M_H_CPU1_SA_DQS_DN<7>")
	)
	(segment
		(start 177.355754 -297.809158)
		(end 177.124106 -298.040806)
		(width 0.18288)
		(layer "In11.Cu")
		(net "M_H_CPU1_SA_DQS_DN<7>")
	)
	(segment
		(start 156.589222 -293.30269)
		(end 156.201364 -292.914832)
		(width 0.18288)
		(layer "In11.Cu")
		(net "M_H_CPU1_SA_DQS_DN<7>")
	)
	(segment
		(start 193.6115 -297.089068)
		(end 192.92443 -297.776138)
		(width 0.18288)
		(layer "In11.Cu")
		(net "M_H_CPU1_SA_DQS_DN<7>")
	)
	(segment
		(start 161.285174 -295.128188)
		(end 161.160714 -295.003728)
		(width 0.18288)
		(layer "In11.Cu")
		(net "M_H_CPU1_SA_DQS_DN<7>")
	)
	(segment
		(start 201.798936 -292.940486)
		(end 201.0029 -292.940486)
		(width 0.18288)
		(layer "In11.Cu")
		(net "M_H_CPU1_SA_DQS_DN<7>")
	)
	(segment
		(start 182.888382 -296.32275)
		(end 181.871112 -296.32275)
		(width 0.18288)
		(layer "In11.Cu")
		(net "M_H_CPU1_SA_DQS_DN<7>")
	)
	(segment
		(start 184.91327 -296.937684)
		(end 183.503316 -296.937684)
		(width 0.18288)
		(layer "In11.Cu")
		(net "M_H_CPU1_SA_DQS_DN<7>")
	)
	(segment
		(start 179.719986 -297.513502)
		(end 179.3875 -297.181016)
		(width 0.18288)
		(layer "In11.Cu")
		(net "M_H_CPU1_SA_DQS_DN<7>")
	)
	(segment
		(start 203.076048 -292.940232)
		(end 202.912218 -292.940232)
		(width 0.16002)
		(layer "In11.Cu")
		(net "M_H_CPU1_SA_DQS_DN<7>")
	)
	(segment
		(start 170.966892 -298.100496)
		(end 170.79087 -298.100496)
		(width 0.18288)
		(layer "In11.Cu")
		(net "M_H_CPU1_SA_DQS_DN<7>")
	)
	(segment
		(start 203.474828 -292.665658)
		(end 203.200254 -292.940232)
		(width 0.18288)
		(layer "In11.Cu")
		(net "M_H_CPU1_SA_DQS_DN<7>")
	)
	(segment
		(start 179.3875 -297.181016)
		(end 178.864006 -297.181016)
		(width 0.18288)
		(layer "In11.Cu")
		(net "M_H_CPU1_SA_DQS_DN<7>")
	)
	(segment
		(start 202.912218 -292.940232)
		(end 202.780646 -292.940232)
		(width 0.18288)
		(layer "In11.Cu")
		(net "M_H_CPU1_SA_DQS_DN<7>")
	)
	(segment
		(start 204.392784 -293.273734)
		(end 203.784708 -292.665658)
		(width 0.18288)
		(layer "In11.Cu")
		(net "M_H_CPU1_SA_DQS_DN<7>")
	)
	(segment
		(start 172.986446 -298.891452)
		(end 172.565822 -298.891452)
		(width 0.18288)
		(layer "In11.Cu")
		(net "M_H_CPU1_SA_DQS_DN<7>")
	)
	(segment
		(start 139.538202 -274.648422)
		(end 139.325858 -274.648422)
		(width 0.18288)
		(layer "In11.Cu")
		(net "M_H_CPU1_SA_DQS_DN<7>")
	)
	(segment
		(start 202.780646 -292.940232)
		(end 202.470766 -292.630352)
		(width 0.18288)
		(layer "In11.Cu")
		(net "M_H_CPU1_SA_DQS_DN<7>")
	)
	(segment
		(start 201.0029 -292.940486)
		(end 200.168002 -293.775384)
		(width 0.18288)
		(layer "In11.Cu")
		(net "M_H_CPU1_SA_DQS_DN<7>")
	)
	(segment
		(start 172.565822 -298.891452)
		(end 172.325538 -298.651168)
		(width 0.18288)
		(layer "In11.Cu")
		(net "M_H_CPU1_SA_DQS_DN<7>")
	)
	(segment
		(start 131.663186 -273.122898)
		(end 131.661154 -273.121628)
		(width 0.088646)
		(layer "In11.Cu")
		(net "M_H_CPU1_SA_DQS_DN<7>")
	)
	(segment
		(start 131.673346 -273.12874)
		(end 131.672076 -273.127978)
		(width 0.088646)
		(layer "In11.Cu")
		(net "M_H_CPU1_SA_DQS_DN<7>")
	)
	(segment
		(start 185.03773 -297.062144)
		(end 184.91327 -296.937684)
		(width 0.18288)
		(layer "In11.Cu")
		(net "M_H_CPU1_SA_DQS_DN<7>")
	)
	(segment
		(start 190.06439 -297.79595)
		(end 189.227714 -296.959274)
		(width 0.18288)
		(layer "In11.Cu")
		(net "M_H_CPU1_SA_DQS_DN<7>")
	)
	(segment
		(start 161.958274 -295.003728)
		(end 161.833814 -295.128188)
		(width 0.18288)
		(layer "In11.Cu")
		(net "M_H_CPU1_SA_DQS_DN<7>")
	)
	(segment
		(start 155.249372 -291.96284)
		(end 155.07335 -291.96284)
		(width 0.18288)
		(layer "In11.Cu")
		(net "M_H_CPU1_SA_DQS_DN<7>")
	)
	(segment
		(start 188.111638 -297.190922)
		(end 187.589414 -297.190922)
		(width 0.18288)
		(layer "In11.Cu")
		(net "M_H_CPU1_SA_DQS_DN<7>")
	)
	(segment
		(start 152.786588 -289.500056)
		(end 152.786588 -287.896808)
		(width 0.18288)
		(layer "In11.Cu")
		(net "M_H_CPU1_SA_DQS_DN<7>")
	)
	(segment
		(start 202.470766 -292.630352)
		(end 202.10907 -292.630352)
		(width 0.18288)
		(layer "In11.Cu")
		(net "M_H_CPU1_SA_DQS_DN<7>")
	)
	(segment
		(start 177.124106 -298.040806)
		(end 176.601882 -298.040806)
		(width 0.18288)
		(layer "In11.Cu")
		(net "M_H_CPU1_SA_DQS_DN<7>")
	)
	(segment
		(start 137.38987 -273.187922)
		(end 137.38987 -273.188176)
		(width 0.088646)
		(layer "In11.Cu")
		(net "M_H_CPU1_SA_DQS_DN<7>")
	)
	(segment
		(start 207.071214 -293.366698)
		(end 206.81696 -293.112444)
		(width 0.18288)
		(layer "In11.Cu")
		(net "M_H_CPU1_SA_DQS_DN<7>")
	)
	(segment
		(start 125.847348 -270.059404)
		(end 125.847348 -270.19758)
		(width 0.088646)
		(layer "In11.Cu")
		(net "M_H_CPU1_SA_DQS_DN<7>")
	)
	(segment
		(start 159.734758 -294.18153)
		(end 157.613604 -293.30269)
		(width 0.18288)
		(layer "In11.Cu")
		(net "M_H_CPU1_SA_DQS_DN<7>")
	)
	(segment
		(start 189.227714 -296.959274)
		(end 188.343286 -296.959274)
		(width 0.18288)
		(layer "In11.Cu")
		(net "M_H_CPU1_SA_DQS_DN<7>")
	)
	(segment
		(start 195.105528 -296.179748)
		(end 194.196208 -297.089068)
		(width 0.18288)
		(layer "In11.Cu")
		(net "M_H_CPU1_SA_DQS_DN<7>")
	)
	(segment
		(start 204.97165 -293.273734)
		(end 204.392784 -293.273734)
		(width 0.18288)
		(layer "In11.Cu")
		(net "M_H_CPU1_SA_DQS_DN<7>")
	)
	(segment
		(start 176.33061 -297.769534)
		(end 175.517556 -297.769534)
		(width 0.18288)
		(layer "In11.Cu")
		(net "M_H_CPU1_SA_DQS_DN<7>")
	)
	(segment
		(start 163.429442 -295.478454)
		(end 162.954716 -295.003728)
		(width 0.18288)
		(layer "In11.Cu")
		(net "M_H_CPU1_SA_DQS_DN<7>")
	)
	(segment
		(start 126.9746 -269.873222)
		(end 126.9746 -269.872968)
		(width 0.088646)
		(layer "In11.Cu")
		(net "M_H_CPU1_SA_DQS_DN<7>")
	)
	(segment
		(start 170.402758 -297.536362)
		(end 169.875454 -297.009058)
		(width 0.18288)
		(layer "In11.Cu")
		(net "M_H_CPU1_SA_DQS_DN<7>")
	)
	(segment
		(start 125.94463 -269.962376)
		(end 125.847348 -270.059404)
		(width 0.088646)
		(layer "In11.Cu")
		(net "M_H_CPU1_SA_DQS_DN<7>")
	)
	(segment
		(start 152.786588 -287.896808)
		(end 139.538202 -274.648422)
		(width 0.18288)
		(layer "In11.Cu")
		(net "M_H_CPU1_SA_DQS_DN<7>")
	)
	(segment
		(start 200.168002 -293.775384)
		(end 199.152002 -293.775384)
		(width 0.18288)
		(layer "In11.Cu")
		(net "M_H_CPU1_SA_DQS_DN<7>")
	)
	(segment
		(start 127.928878 -269.881858)
		(end 127.914146 -269.873222)
		(width 0.088646)
		(layer "In11.Cu")
		(net "M_H_CPU1_SA_DQS_DN<7>")
	)
	(segment
		(start 196.768466 -295.3512)
		(end 196.380354 -295.739312)
		(width 0.18288)
		(layer "In11.Cu")
		(net "M_H_CPU1_SA_DQS_DN<7>")
	)
	(segment
		(start 161.833814 -295.128188)
		(end 161.285174 -295.128188)
		(width 0.18288)
		(layer "In11.Cu")
		(net "M_H_CPU1_SA_DQS_DN<7>")
	)
	(segment
		(start 173.28769 -298.590208)
		(end 172.986446 -298.891452)
		(width 0.18288)
		(layer "In11.Cu")
		(net "M_H_CPU1_SA_DQS_DN<7>")
	)
	(segment
		(start 192.476374 -297.776138)
		(end 192.211706 -298.040806)
		(width 0.18288)
		(layer "In11.Cu")
		(net "M_H_CPU1_SA_DQS_DN<7>")
	)
	(segment
		(start 170.402758 -297.712384)
		(end 170.402758 -297.536362)
		(width 0.18288)
		(layer "In11.Cu")
		(net "M_H_CPU1_SA_DQS_DN<7>")
	)
	(segment
		(start 194.196208 -297.089068)
		(end 193.6115 -297.089068)
		(width 0.18288)
		(layer "In11.Cu")
		(net "M_H_CPU1_SA_DQS_DN<7>")
	)
	(segment
		(start 202.10907 -292.630352)
		(end 201.798936 -292.940486)
		(width 0.18288)
		(layer "In11.Cu")
		(net "M_H_CPU1_SA_DQS_DN<7>")
	)
	(segment
		(start 155.63723 -292.350698)
		(end 155.249372 -291.96284)
		(width 0.18288)
		(layer "In11.Cu")
		(net "M_H_CPU1_SA_DQS_DN<7>")
	)
	(segment
		(start 130.742436 -271.505934)
		(end 130.733546 -271.500854)
		(width 0.088646)
		(layer "In11.Cu")
		(net "M_H_CPU1_SA_DQS_DN<7>")
	)
	(segment
		(start 131.672076 -273.127978)
		(end 131.663186 -273.122898)
		(width 0.088646)
		(layer "In11.Cu")
		(net "M_H_CPU1_SA_DQS_DN<7>")
	)
	(segment
		(start 199.152002 -293.775384)
		(end 198.38162 -294.545766)
		(width 0.18288)
		(layer "In11.Cu")
		(net "M_H_CPU1_SA_DQS_DN<7>")
	)
	(segment
		(start 131.212082 -272.320004)
		(end 131.203192 -272.314924)
		(width 0.088646)
		(layer "In11.Cu")
		(net "M_H_CPU1_SA_DQS_DN<7>")
	)
	(segment
		(start 180.68036 -297.513502)
		(end 179.719986 -297.513502)
		(width 0.18288)
		(layer "In11.Cu")
		(net "M_H_CPU1_SA_DQS_DN<7>")
	)
	(segment
		(start 129.041398 -270.213074)
		(end 129.041398 -270.19758)
		(width 0.088646)
		(layer "In11.Cu")
		(net "M_H_CPU1_SA_DQS_DN<7>")
	)
	(segment
		(start 173.536102 -298.590208)
		(end 173.28769 -298.590208)
		(width 0.18288)
		(layer "In11.Cu")
		(net "M_H_CPU1_SA_DQS_DN<7>")
	)
	(segment
		(start 130.733546 -271.500854)
		(end 130.72745 -271.497298)
		(width 0.088646)
		(layer "In11.Cu")
		(net "M_H_CPU1_SA_DQS_DN<7>")
	)
	(segment
		(start 130.272282 -270.692118)
		(end 130.263392 -270.687038)
		(width 0.088646)
		(layer "In11.Cu")
		(net "M_H_CPU1_SA_DQS_DN<7>")
	)
	(segment
		(start 196.204332 -295.739312)
		(end 195.763896 -296.179748)
		(width 0.18288)
		(layer "In11.Cu")
		(net "M_H_CPU1_SA_DQS_DN<7>")
	)
	(segment
		(start 187.589414 -297.190922)
		(end 187.336176 -296.937684)
		(width 0.18288)
		(layer "In11.Cu")
		(net "M_H_CPU1_SA_DQS_DN<7>")
	)
	(segment
		(start 166.454836 -296.455338)
		(end 165.906196 -296.455338)
		(width 0.18288)
		(layer "In11.Cu")
		(net "M_H_CPU1_SA_DQS_DN<7>")
	)
	(segment
		(start 192.211706 -298.040806)
		(end 191.689482 -298.040806)
		(width 0.18288)
		(layer "In11.Cu")
		(net "M_H_CPU1_SA_DQS_DN<7>")
	)
	(segment
		(start 191.444626 -297.79595)
		(end 190.06439 -297.79595)
		(width 0.18288)
		(layer "In11.Cu")
		(net "M_H_CPU1_SA_DQS_DN<7>")
	)
	(segment
		(start 165.781736 -296.330878)
		(end 165.100508 -296.330878)
		(width 0.18288)
		(layer "In11.Cu")
		(net "M_H_CPU1_SA_DQS_DN<7>")
	)
	(segment
		(start 196.768466 -295.175178)
		(end 196.768466 -295.3512)
		(width 0.18288)
		(layer "In11.Cu")
		(net "M_H_CPU1_SA_DQS_DN<7>")
	)
	(segment
		(start 203.784708 -292.665658)
		(end 203.474828 -292.665658)
		(width 0.18288)
		(layer "In11.Cu")
		(net "M_H_CPU1_SA_DQS_DN<7>")
	)
	(segment
		(start 205.64475 -293.398194)
		(end 205.09611 -293.398194)
		(width 0.18288)
		(layer "In11.Cu")
		(net "M_H_CPU1_SA_DQS_DN<7>")
	)
	(segment
		(start 154.685238 -291.398706)
		(end 154.29738 -291.010848)
		(width 0.18288)
		(layer "In11.Cu")
		(net "M_H_CPU1_SA_DQS_DN<7>")
	)
	(segment
		(start 157.613604 -293.30269)
		(end 156.589222 -293.30269)
		(width 0.18288)
		(layer "In11.Cu")
		(net "M_H_CPU1_SA_DQS_DN<7>")
	)
	(segment
		(start 197.397878 -294.545766)
		(end 196.768466 -295.175178)
		(width 0.18288)
		(layer "In11.Cu")
		(net "M_H_CPU1_SA_DQS_DN<7>")
	)
	(segment
		(start 206.532734 -293.112444)
		(end 206.371444 -293.273734)
		(width 0.18288)
		(layer "In11.Cu")
		(net "M_H_CPU1_SA_DQS_DN<7>")
	)
	(segment
		(start 195.763896 -296.179748)
		(end 195.105528 -296.179748)
		(width 0.18288)
		(layer "In11.Cu")
		(net "M_H_CPU1_SA_DQS_DN<7>")
	)
	(segment
		(start 185.58637 -297.062144)
		(end 185.03773 -297.062144)
		(width 0.18288)
		(layer "In11.Cu")
		(net "M_H_CPU1_SA_DQS_DN<7>")
	)
	(segment
		(start 156.201364 -292.914832)
		(end 156.025342 -292.914832)
		(width 0.18288)
		(layer "In11.Cu")
		(net "M_H_CPU1_SA_DQS_DN<7>")
	)
	(segment
		(start 185.71083 -296.937684)
		(end 185.58637 -297.062144)
		(width 0.18288)
		(layer "In11.Cu")
		(net "M_H_CPU1_SA_DQS_DN<7>")
	)
	(segment
		(start 169.875454 -297.009058)
		(end 169.230548 -297.009058)
		(width 0.18288)
		(layer "In11.Cu")
		(net "M_H_CPU1_SA_DQS_DN<7>")
	)
	(segment
		(start 171.517564 -298.651168)
		(end 170.966892 -298.100496)
		(width 0.18288)
		(layer "In11.Cu")
		(net "M_H_CPU1_SA_DQS_DN<7>")
	)
	(segment
		(start 133.567678 -273.137376)
		(end 133.552946 -273.12874)
		(width 0.088646)
		(layer "In11.Cu")
		(net "M_H_CPU1_SA_DQS_DN<7>")
	)
	(segment
		(start 138.790426 -274.588478)
		(end 137.38987 -273.187922)
		(width 0.088646)
		(layer "In11.Cu")
		(net "M_H_CPU1_SA_DQS_DN<7>")
	)
	(segment
		(start 192.92443 -297.776138)
		(end 192.476374 -297.776138)
		(width 0.18288)
		(layer "In11.Cu")
		(net "M_H_CPU1_SA_DQS_DN<7>")
	)
	(segment
		(start 154.685238 -291.574728)
		(end 154.685238 -291.398706)
		(width 0.18288)
		(layer "In11.Cu")
		(net "M_H_CPU1_SA_DQS_DN<7>")
	)
	(segment
		(start 172.325538 -298.651168)
		(end 171.517564 -298.651168)
		(width 0.18288)
		(layer "In11.Cu")
		(net "M_H_CPU1_SA_DQS_DN<7>")
	)
	(segment
		(start 205.09611 -293.398194)
		(end 204.97165 -293.273734)
		(width 0.18288)
		(layer "In11.Cu")
		(net "M_H_CPU1_SA_DQS_DN<7>")
	)
	(segment
		(start 126.000256 -269.948152)
		(end 125.94463 -269.962376)
		(width 0.088646)
		(layer "In11.Cu")
		(net "M_H_CPU1_SA_DQS_DN<7>")
	)
	(segment
		(start 176.601882 -298.040806)
		(end 176.33061 -297.769534)
		(width 0.18288)
		(layer "In11.Cu")
		(net "M_H_CPU1_SA_DQS_DN<7>")
	)
	(segment
		(start 167.593264 -296.330878)
		(end 166.579296 -296.330878)
		(width 0.18288)
		(layer "In11.Cu")
		(net "M_H_CPU1_SA_DQS_DN<7>")
	)
	(segment
		(start 164.248084 -295.478454)
		(end 163.429442 -295.478454)
		(width 0.18288)
		(layer "In11.Cu")
		(net "M_H_CPU1_SA_DQS_DN<7>")
	)
	(segment
		(start 175.517556 -297.769534)
		(end 173.536102 -298.590208)
		(width 0.18288)
		(layer "In11.Cu")
		(net "M_H_CPU1_SA_DQS_DN<7>")
	)
	(segment
		(start 169.230548 -297.009058)
		(end 167.593264 -296.330878)
		(width 0.18288)
		(layer "In11.Cu")
		(net "M_H_CPU1_SA_DQS_DN<7>")
	)
	(segment
		(start 153.733246 -290.622736)
		(end 153.733246 -290.446714)
		(width 0.18288)
		(layer "In11.Cu")
		(net "M_H_CPU1_SA_DQS_DN<7>")
	)
	(segment
		(start 161.160714 -295.003728)
		(end 160.55721 -295.003728)
		(width 0.18288)
		(layer "In11.Cu")
		(net "M_H_CPU1_SA_DQS_DN<7>")
	)
	(segment
		(start 126.320042 -269.948152)
		(end 126.000256 -269.948152)
		(width 0.088646)
		(layer "In11.Cu")
		(net "M_H_CPU1_SA_DQS_DN<7>")
	)
	(segment
		(start 139.265914 -274.588478)
		(end 138.790426 -274.588478)
		(width 0.088646)
		(layer "In11.Cu")
		(net "M_H_CPU1_SA_DQS_DN<7>")
	)
	(segment
		(start 170.79087 -298.100496)
		(end 170.402758 -297.712384)
		(width 0.18288)
		(layer "In11.Cu")
		(net "M_H_CPU1_SA_DQS_DN<7>")
	)
	(segment
		(start 134.507478 -273.137376)
		(end 134.492746 -273.12874)
		(width 0.088646)
		(layer "In11.Cu")
		(net "M_H_CPU1_SA_DQS_DN<7>")
	)
	(segment
		(start 187.336176 -296.937684)
		(end 185.71083 -296.937684)
		(width 0.18288)
		(layer "In11.Cu")
		(net "M_H_CPU1_SA_DQS_DN<7>")
	)
	(segment
		(start 196.380354 -295.739312)
		(end 196.204332 -295.739312)
		(width 0.18288)
		(layer "In11.Cu")
		(net "M_H_CPU1_SA_DQS_DN<7>")
	)
	(segment
		(start 154.29738 -291.010848)
		(end 154.121358 -291.010848)
		(width 0.18288)
		(layer "In11.Cu")
		(net "M_H_CPU1_SA_DQS_DN<7>")
	)
	(segment
		(start 198.38162 -294.545766)
		(end 197.397878 -294.545766)
		(width 0.18288)
		(layer "In11.Cu")
		(net "M_H_CPU1_SA_DQS_DN<7>")
	)
	(segment
		(start 165.100508 -296.330878)
		(end 164.248084 -295.478454)
		(width 0.18288)
		(layer "In11.Cu")
		(net "M_H_CPU1_SA_DQS_DN<7>")
	)
	(segment
		(start 139.325858 -274.648422)
		(end 139.265914 -274.588478)
		(width 0.088646)
		(layer "In11.Cu")
		(net "M_H_CPU1_SA_DQS_DN<7>")
	)
	(segment
		(start 135.44296 -273.134836)
		(end 135.432546 -273.12874)
		(width 0.088646)
		(layer "In11.Cu")
		(net "M_H_CPU1_SA_DQS_DN<7>")
	)
	(segment
		(start 155.63723 -292.52672)
		(end 155.63723 -292.350698)
		(width 0.18288)
		(layer "In11.Cu")
		(net "M_H_CPU1_SA_DQS_DN<7>")
	)
	(segment
		(start 178.864006 -297.181016)
		(end 178.235864 -297.809158)
		(width 0.18288)
		(layer "In11.Cu")
		(net "M_H_CPU1_SA_DQS_DN<7>")
	)
	(segment
		(start 156.025342 -292.914832)
		(end 155.63723 -292.52672)
		(width 0.18288)
		(layer "In11.Cu")
		(net "M_H_CPU1_SA_DQS_DN<7>")
	)
	(segment
		(start 162.954716 -295.003728)
		(end 161.958274 -295.003728)
		(width 0.18288)
		(layer "In11.Cu")
		(net "M_H_CPU1_SA_DQS_DN<7>")
	)
	(segment
		(start 132.627878 -273.137376)
		(end 132.613146 -273.12874)
		(width 0.088646)
		(layer "In11.Cu")
		(net "M_H_CPU1_SA_DQS_DN<7>")
	)
	(segment
		(start 165.906196 -296.455338)
		(end 165.781736 -296.330878)
		(width 0.18288)
		(layer "In11.Cu")
		(net "M_H_CPU1_SA_DQS_DN<7>")
	)
	(segment
		(start 129.888996 -270.687038)
		(end 129.874264 -270.695674)
		(width 0.088646)
		(layer "In11.Cu")
		(net "M_H_CPU1_SA_DQS_DN<7>")
	)
	(segment
		(start 181.871112 -296.32275)
		(end 180.68036 -297.513502)
		(width 0.18288)
		(layer "In11.Cu")
		(net "M_H_CPU1_SA_DQS_DN<7>")
	)
	(segment
		(start 126.989078 -269.881858)
		(end 126.9746 -269.873222)
		(width 0.088646)
		(layer "In11.Cu")
		(net "M_H_CPU1_SA_DQS_DN<7>")
	)
	(segment
		(start 128.862836 -269.878302)
		(end 128.853946 -269.873222)
		(width 0.088646)
		(layer "In11.Cu")
		(net "M_H_CPU1_SA_DQS_DN<7>")
	)
	(segment
		(start 191.689482 -298.040806)
		(end 191.444626 -297.79595)
		(width 0.18288)
		(layer "In11.Cu")
		(net "M_H_CPU1_SA_DQS_DN<7>")
	)
	(segment
		(start 206.81696 -293.112444)
		(end 206.532734 -293.112444)
		(width 0.18288)
		(layer "In11.Cu")
		(net "M_H_CPU1_SA_DQS_DN<7>")
	)
	(segment
		(start 188.343286 -296.959274)
		(end 188.111638 -297.190922)
		(width 0.18288)
		(layer "In11.Cu")
		(net "M_H_CPU1_SA_DQS_DN<7>")
	)
	(segment
		(start 178.235864 -297.809158)
		(end 177.355754 -297.809158)
		(width 0.18288)
		(layer "In11.Cu")
		(net "M_H_CPU1_SA_DQS_DN<7>")
	)
	(segment
		(start 205.76921 -293.273734)
		(end 205.64475 -293.398194)
		(width 0.18288)
		(layer "In11.Cu")
		(net "M_H_CPU1_SA_DQS_DN<7>")
	)
	(segment
		(start 154.121358 -291.010848)
		(end 153.733246 -290.622736)
		(width 0.18288)
		(layer "In11.Cu")
		(net "M_H_CPU1_SA_DQS_DN<7>")
	)
	(arc
		(start 129.874264 -270.695674)
		(mid 129.597789 -270.762994)
		(end 129.323592 -270.687038)
		(width 0.088646)
		(layer "In11.Cu")
		(net "M_H_CPU1_SA_DQS_DN<7>")
	)
	(arc
		(start 129.041398 -270.19758)
		(mid 128.993719 -270.01468)
		(end 128.862836 -269.878302)
		(width 0.088646)
		(layer "In11.Cu")
		(net "M_H_CPU1_SA_DQS_DN<7>")
	)
	(arc
		(start 131.203192 -272.314924)
		(mid 131.00191 -272.117437)
		(end 130.920998 -271.84731)
		(width 0.088646)
		(layer "In11.Cu")
		(net "M_H_CPU1_SA_DQS_DN<7>")
	)
	(arc
		(start 126.600204 -269.872968)
		(mid 126.465091 -269.92906)
		(end 126.320042 -269.948152)
		(width 0.088646)
		(layer "In11.Cu")
		(net "M_H_CPU1_SA_DQS_DN<7>")
	)
	(arc
		(start 130.263392 -270.687038)
		(mid 130.076194 -270.636895)
		(end 129.888996 -270.687038)
		(width 0.088646)
		(layer "In11.Cu")
		(net "M_H_CPU1_SA_DQS_DN<7>")
	)
	(arc
		(start 132.23875 -273.12874)
		(mid 131.956048 -273.204516)
		(end 131.673346 -273.12874)
		(width 0.088646)
		(layer "In11.Cu")
		(net "M_H_CPU1_SA_DQS_DN<7>")
	)
	(arc
		(start 128.853946 -269.873222)
		(mid 128.666748 -269.823079)
		(end 128.47955 -269.873222)
		(width 0.088646)
		(layer "In11.Cu")
		(net "M_H_CPU1_SA_DQS_DN<7>")
	)
	(arc
		(start 134.11835 -273.12874)
		(mid 133.844151 -273.204575)
		(end 133.567678 -273.137376)
		(width 0.088646)
		(layer "In11.Cu")
		(net "M_H_CPU1_SA_DQS_DN<7>")
	)
	(arc
		(start 131.661154 -273.121628)
		(mid 131.462926 -272.91578)
		(end 131.390644 -272.639282)
		(width 0.088646)
		(layer "In11.Cu")
		(net "M_H_CPU1_SA_DQS_DN<7>")
	)
	(arc
		(start 131.390644 -272.639282)
		(mid 131.342965 -272.456382)
		(end 131.212082 -272.320004)
		(width 0.088646)
		(layer "In11.Cu")
		(net "M_H_CPU1_SA_DQS_DN<7>")
	)
	(arc
		(start 135.05815 -273.12874)
		(mid 134.783951 -273.204575)
		(end 134.507478 -273.137376)
		(width 0.088646)
		(layer "In11.Cu")
		(net "M_H_CPU1_SA_DQS_DN<7>")
	)
	(arc
		(start 126.9746 -269.872968)
		(mid 126.787402 -269.822859)
		(end 126.600204 -269.872968)
		(width 0.088646)
		(layer "In11.Cu")
		(net "M_H_CPU1_SA_DQS_DN<7>")
	)
	(arc
		(start 135.432546 -273.12874)
		(mid 135.245348 -273.078597)
		(end 135.05815 -273.12874)
		(width 0.088646)
		(layer "In11.Cu")
		(net "M_H_CPU1_SA_DQS_DN<7>")
	)
	(arc
		(start 134.492746 -273.12874)
		(mid 134.305548 -273.078597)
		(end 134.11835 -273.12874)
		(width 0.088646)
		(layer "In11.Cu")
		(net "M_H_CPU1_SA_DQS_DN<7>")
	)
	(arc
		(start 127.53975 -269.873222)
		(mid 127.265521 -269.949147)
		(end 126.989078 -269.881858)
		(width 0.088646)
		(layer "In11.Cu")
		(net "M_H_CPU1_SA_DQS_DN<7>")
	)
	(arc
		(start 136.372092 -273.12874)
		(mid 136.184894 -273.078597)
		(end 135.997696 -273.12874)
		(width 0.088646)
		(layer "In11.Cu")
		(net "M_H_CPU1_SA_DQS_DN<7>")
	)
	(arc
		(start 137.311892 -273.12874)
		(mid 137.124694 -273.078597)
		(end 136.937496 -273.12874)
		(width 0.088646)
		(layer "In11.Cu")
		(net "M_H_CPU1_SA_DQS_DN<7>")
	)
	(arc
		(start 133.552946 -273.12874)
		(mid 133.365748 -273.078597)
		(end 133.17855 -273.12874)
		(width 0.088646)
		(layer "In11.Cu")
		(net "M_H_CPU1_SA_DQS_DN<7>")
	)
	(arc
		(start 130.920998 -271.825212)
		(mid 130.873319 -271.642312)
		(end 130.742436 -271.505934)
		(width 0.088646)
		(layer "In11.Cu")
		(net "M_H_CPU1_SA_DQS_DN<7>")
	)
	(arc
		(start 137.355072 -273.157442)
		(mid 137.333982 -273.142338)
		(end 137.311892 -273.12874)
		(width 0.088646)
		(layer "In11.Cu")
		(net "M_H_CPU1_SA_DQS_DN<7>")
	)
	(arc
		(start 130.72745 -271.497298)
		(mid 130.524863 -271.290947)
		(end 130.450844 -271.011396)
		(width 0.088646)
		(layer "In11.Cu")
		(net "M_H_CPU1_SA_DQS_DN<7>")
	)
	(arc
		(start 127.914146 -269.873222)
		(mid 127.726948 -269.823079)
		(end 127.53975 -269.873222)
		(width 0.088646)
		(layer "In11.Cu")
		(net "M_H_CPU1_SA_DQS_DN<7>")
	)
	(arc
		(start 137.38987 -273.188176)
		(mid 137.372947 -273.172271)
		(end 137.355072 -273.157442)
		(width 0.088646)
		(layer "In11.Cu")
		(net "M_H_CPU1_SA_DQS_DN<7>")
	)
	(arc
		(start 133.17855 -273.12874)
		(mid 132.904351 -273.204575)
		(end 132.627878 -273.137376)
		(width 0.088646)
		(layer "In11.Cu")
		(net "M_H_CPU1_SA_DQS_DN<7>")
	)
	(arc
		(start 135.997696 -273.12874)
		(mid 135.721137 -273.204483)
		(end 135.44296 -273.134836)
		(width 0.088646)
		(layer "In11.Cu")
		(net "M_H_CPU1_SA_DQS_DN<7>")
	)
	(arc
		(start 129.323592 -270.687038)
		(mid 129.120769 -270.486807)
		(end 129.041398 -270.213074)
		(width 0.088646)
		(layer "In11.Cu")
		(net "M_H_CPU1_SA_DQS_DN<7>")
	)
	(arc
		(start 130.450844 -271.011396)
		(mid 130.403165 -270.828496)
		(end 130.272282 -270.692118)
		(width 0.088646)
		(layer "In11.Cu")
		(net "M_H_CPU1_SA_DQS_DN<7>")
	)
	(arc
		(start 128.47955 -269.873222)
		(mid 128.205321 -269.949147)
		(end 127.928878 -269.881858)
		(width 0.088646)
		(layer "In11.Cu")
		(net "M_H_CPU1_SA_DQS_DN<7>")
	)
	(arc
		(start 132.613146 -273.12874)
		(mid 132.425948 -273.078597)
		(end 132.23875 -273.12874)
		(width 0.088646)
		(layer "In11.Cu")
		(net "M_H_CPU1_SA_DQS_DN<7>")
	)
	(arc
		(start 136.937496 -273.12874)
		(mid 136.654794 -273.204516)
		(end 136.372092 -273.12874)
		(width 0.088646)
		(layer "In11.Cu")
		(net "M_H_CPU1_SA_DQS_DN<7>")
	)
	(segment
		(start 214.961978 -302.462438)
		(end 215.216232 -302.716692)
		(width 0.20066)
		(layer "F.Cu")
		(net "M_H_CPU1_SA_DQS_DN<6>")
	)
	(segment
		(start 210.008724 -302.020478)
		(end 210.286092 -302.297846)
		(width 0.20066)
		(layer "F.Cu")
		(net "M_H_CPU1_SA_DQS_DN<6>")
	)
	(segment
		(start 208.977992 -302.44542)
		(end 209.461354 -302.44542)
		(width 0.20066)
		(layer "F.Cu")
		(net "M_H_CPU1_SA_DQS_DN<6>")
	)
	(segment
		(start 212.630258 -302.302672)
		(end 212.949028 -302.302672)
		(width 0.20066)
		(layer "F.Cu")
		(net "M_H_CPU1_SA_DQS_DN<6>")
	)
	(segment
		(start 213.234778 -302.016922)
		(end 213.724744 -302.016922)
		(width 0.20066)
		(layer "F.Cu")
		(net "M_H_CPU1_SA_DQS_DN<6>")
	)
	(segment
		(start 207.071214 -302.716692)
		(end 208.176114 -302.716692)
		(width 0.20066)
		(layer "F.Cu")
		(net "M_H_CPU1_SA_DQS_DN<6>")
	)
	(segment
		(start 208.70672 -302.716692)
		(end 208.977992 -302.44542)
		(width 0.20066)
		(layer "F.Cu")
		(net "M_H_CPU1_SA_DQS_DN<6>")
	)
	(segment
		(start 212.949028 -302.302672)
		(end 213.234778 -302.016922)
		(width 0.20066)
		(layer "F.Cu")
		(net "M_H_CPU1_SA_DQS_DN<6>")
	)
	(segment
		(start 210.286092 -302.297846)
		(end 210.598258 -302.297846)
		(width 0.20066)
		(layer "F.Cu")
		(net "M_H_CPU1_SA_DQS_DN<6>")
	)
	(segment
		(start 125.847094 -274.54479)
		(end 125.847348 -274.545044)
		(width 0.20066)
		(layer "F.Cu")
		(net "M_H_CPU1_SA_DQS_DN<6>")
	)
	(segment
		(start 210.603084 -302.297846)
		(end 210.60918 -302.29175)
		(width 0.1016)
		(layer "F.Cu")
		(net "M_H_CPU1_SA_DQS_DN<6>")
	)
	(segment
		(start 209.886296 -302.020478)
		(end 210.008724 -302.020478)
		(width 0.20066)
		(layer "F.Cu")
		(net "M_H_CPU1_SA_DQS_DN<6>")
	)
	(segment
		(start 214.17026 -302.462438)
		(end 214.961978 -302.462438)
		(width 0.20066)
		(layer "F.Cu")
		(net "M_H_CPU1_SA_DQS_DN<6>")
	)
	(segment
		(start 212.619336 -302.29175)
		(end 212.630258 -302.302672)
		(width 0.1016)
		(layer "F.Cu")
		(net "M_H_CPU1_SA_DQS_DN<6>")
	)
	(segment
		(start 215.216232 -302.716692)
		(end 215.719914 -302.716692)
		(width 0.20066)
		(layer "F.Cu")
		(net "M_H_CPU1_SA_DQS_DN<6>")
	)
	(segment
		(start 125.847348 -274.545044)
		(end 125.847348 -275.08073)
		(width 0.20066)
		(layer "F.Cu")
		(net "M_H_CPU1_SA_DQS_DN<6>")
	)
	(segment
		(start 209.461354 -302.44542)
		(end 209.886296 -302.020478)
		(width 0.20066)
		(layer "F.Cu")
		(net "M_H_CPU1_SA_DQS_DN<6>")
	)
	(segment
		(start 208.176114 -302.716692)
		(end 208.70672 -302.716692)
		(width 0.20066)
		(layer "F.Cu")
		(net "M_H_CPU1_SA_DQS_DN<6>")
	)
	(segment
		(start 213.724744 -302.016922)
		(end 214.17026 -302.462438)
		(width 0.20066)
		(layer "F.Cu")
		(net "M_H_CPU1_SA_DQS_DN<6>")
	)
	(segment
		(start 210.60918 -302.29175)
		(end 212.619336 -302.29175)
		(width 0.1016)
		(layer "F.Cu")
		(net "M_H_CPU1_SA_DQS_DN<6>")
	)
	(segment
		(start 210.598258 -302.297846)
		(end 210.603084 -302.297846)
		(width 0.101854)
		(layer "F.Cu")
		(net "M_H_CPU1_SA_DQS_DN<6>")
	)
	(segment
		(start 171.12107 -309.2958)
		(end 170.945048 -309.2958)
		(width 0.18288)
		(layer "In11.Cu")
		(net "M_H_CPU1_SA_DQS_DN<6>")
	)
	(segment
		(start 181.561994 -308.952646)
		(end 181.013354 -308.952646)
		(width 0.18288)
		(layer "In11.Cu")
		(net "M_H_CPU1_SA_DQS_DN<6>")
	)
	(segment
		(start 186.684158 -308.004464)
		(end 186.559698 -308.128924)
		(width 0.18288)
		(layer "In11.Cu")
		(net "M_H_CPU1_SA_DQS_DN<6>")
	)
	(segment
		(start 154.563064 -303.92243)
		(end 154.563064 -300.367954)
		(width 0.18288)
		(layer "In11.Cu")
		(net "M_H_CPU1_SA_DQS_DN<6>")
	)
	(segment
		(start 161.591752 -307.71846)
		(end 160.470596 -307.71846)
		(width 0.18288)
		(layer "In11.Cu")
		(net "M_H_CPU1_SA_DQS_DN<6>")
	)
	(segment
		(start 156.900118 -306.259484)
		(end 156.108908 -305.468274)
		(width 0.18288)
		(layer "In11.Cu")
		(net "M_H_CPU1_SA_DQS_DN<6>")
	)
	(segment
		(start 192.211706 -309.090822)
		(end 191.689482 -309.090822)
		(width 0.18288)
		(layer "In11.Cu")
		(net "M_H_CPU1_SA_DQS_DN<6>")
	)
	(segment
		(start 203.463906 -302.026574)
		(end 203.199238 -302.291242)
		(width 0.18288)
		(layer "In11.Cu")
		(net "M_H_CPU1_SA_DQS_DN<6>")
	)
	(segment
		(start 161.716212 -307.84292)
		(end 161.591752 -307.71846)
		(width 0.18288)
		(layer "In11.Cu")
		(net "M_H_CPU1_SA_DQS_DN<6>")
	)
	(segment
		(start 159.416242 -306.840128)
		(end 159.416242 -306.664106)
		(width 0.18288)
		(layer "In11.Cu")
		(net "M_H_CPU1_SA_DQS_DN<6>")
	)
	(segment
		(start 129.88925 -278.82596)
		(end 129.878836 -278.832056)
		(width 0.088646)
		(layer "In11.Cu")
		(net "M_H_CPU1_SA_DQS_DN<6>")
	)
	(segment
		(start 175.819562 -308.857142)
		(end 175.695102 -308.981602)
		(width 0.18288)
		(layer "In11.Cu")
		(net "M_H_CPU1_SA_DQS_DN<6>")
	)
	(segment
		(start 179.663344 -308.22265)
		(end 178.922934 -308.22265)
		(width 0.18288)
		(layer "In11.Cu")
		(net "M_H_CPU1_SA_DQS_DN<6>")
	)
	(segment
		(start 166.909242 -307.127402)
		(end 166.784782 -307.002942)
		(width 0.18288)
		(layer "In11.Cu")
		(net "M_H_CPU1_SA_DQS_DN<6>")
	)
	(segment
		(start 126.497842 -275.566124)
		(end 126.349506 -275.482812)
		(width 0.088646)
		(layer "In11.Cu")
		(net "M_H_CPU1_SA_DQS_DN<6>")
	)
	(segment
		(start 139.99972 -284.281372)
		(end 139.99972 -283.87167)
		(width 0.18288)
		(layer "In11.Cu")
		(net "M_H_CPU1_SA_DQS_DN<6>")
	)
	(segment
		(start 204.983334 -302.737774)
		(end 204.858874 -302.613314)
		(width 0.18288)
		(layer "In11.Cu")
		(net "M_H_CPU1_SA_DQS_DN<6>")
	)
	(segment
		(start 159.028384 -306.276248)
		(end 158.174944 -306.276248)
		(width 0.18288)
		(layer "In11.Cu")
		(net "M_H_CPU1_SA_DQS_DN<6>")
	)
	(segment
		(start 190.217552 -308.97703)
		(end 190.093092 -308.85257)
		(width 0.18288)
		(layer "In11.Cu")
		(net "M_H_CPU1_SA_DQS_DN<6>")
	)
	(segment
		(start 163.611052 -307.84292)
		(end 163.062412 -307.84292)
		(width 0.18288)
		(layer "In11.Cu")
		(net "M_H_CPU1_SA_DQS_DN<6>")
	)
	(segment
		(start 157.910784 -306.540408)
		(end 157.513528 -306.540408)
		(width 0.18288)
		(layer "In11.Cu")
		(net "M_H_CPU1_SA_DQS_DN<6>")
	)
	(segment
		(start 127.161798 -276.72411)
		(end 127.161798 -276.708616)
		(width 0.088646)
		(layer "In11.Cu")
		(net "M_H_CPU1_SA_DQS_DN<6>")
	)
	(segment
		(start 172.260768 -309.699914)
		(end 171.525438 -309.699914)
		(width 0.18288)
		(layer "In11.Cu")
		(net "M_H_CPU1_SA_DQS_DN<6>")
	)
	(segment
		(start 183.991758 -308.004464)
		(end 183.168036 -308.828186)
		(width 0.18288)
		(layer "In11.Cu")
		(net "M_H_CPU1_SA_DQS_DN<6>")
	)
	(segment
		(start 159.980376 -307.22824)
		(end 159.804354 -307.22824)
		(width 0.18288)
		(layer "In11.Cu")
		(net "M_H_CPU1_SA_DQS_DN<6>")
	)
	(segment
		(start 190.093092 -308.85257)
		(end 189.411356 -308.85257)
		(width 0.18288)
		(layer "In11.Cu")
		(net "M_H_CPU1_SA_DQS_DN<6>")
	)
	(segment
		(start 171.525438 -309.699914)
		(end 171.12107 -309.2958)
		(width 0.18288)
		(layer "In11.Cu")
		(net "M_H_CPU1_SA_DQS_DN<6>")
	)
	(segment
		(start 188.08065 -308.240938)
		(end 187.674758 -308.240938)
		(width 0.18288)
		(layer "In11.Cu")
		(net "M_H_CPU1_SA_DQS_DN<6>")
	)
	(segment
		(start 170.945048 -309.2958)
		(end 170.556936 -308.907688)
		(width 0.18288)
		(layer "In11.Cu")
		(net "M_H_CPU1_SA_DQS_DN<6>")
	)
	(segment
		(start 176.601882 -309.090822)
		(end 176.368202 -308.857142)
		(width 0.18288)
		(layer "In11.Cu")
		(net "M_H_CPU1_SA_DQS_DN<6>")
	)
	(segment
		(start 204.310234 -302.613314)
		(end 203.723494 -302.026574)
		(width 0.18288)
		(layer "In11.Cu")
		(net "M_H_CPU1_SA_DQS_DN<6>")
	)
	(segment
		(start 184.540398 -308.004464)
		(end 183.991758 -308.004464)
		(width 0.18288)
		(layer "In11.Cu")
		(net "M_H_CPU1_SA_DQS_DN<6>")
	)
	(segment
		(start 168.1988 -307.002942)
		(end 167.582342 -307.002942)
		(width 0.18288)
		(layer "In11.Cu")
		(net "M_H_CPU1_SA_DQS_DN<6>")
	)
	(segment
		(start 170.556936 -308.907688)
		(end 170.556682 -308.731666)
		(width 0.18288)
		(layer "In11.Cu")
		(net "M_H_CPU1_SA_DQS_DN<6>")
	)
	(segment
		(start 180.26888 -308.828186)
		(end 179.663344 -308.22265)
		(width 0.18288)
		(layer "In11.Cu")
		(net "M_H_CPU1_SA_DQS_DN<6>")
	)
	(segment
		(start 186.559698 -308.128924)
		(end 186.011058 -308.128924)
		(width 0.18288)
		(layer "In11.Cu")
		(net "M_H_CPU1_SA_DQS_DN<6>")
	)
	(segment
		(start 155.932886 -305.468274)
		(end 155.54452 -305.079908)
		(width 0.18288)
		(layer "In11.Cu")
		(net "M_H_CPU1_SA_DQS_DN<6>")
	)
	(segment
		(start 156.108908 -305.468274)
		(end 155.932886 -305.468274)
		(width 0.18288)
		(layer "In11.Cu")
		(net "M_H_CPU1_SA_DQS_DN<6>")
	)
	(segment
		(start 138.921998 -281.919172)
		(end 138.32967 -281.326844)
		(width 0.088646)
		(layer "In11.Cu")
		(net "M_H_CPU1_SA_DQS_DN<6>")
	)
	(segment
		(start 125.985778 -275.21916)
		(end 125.847348 -275.08073)
		(width 0.088646)
		(layer "In11.Cu")
		(net "M_H_CPU1_SA_DQS_DN<6>")
	)
	(segment
		(start 173.553882 -309.676292)
		(end 173.288706 -309.676292)
		(width 0.18288)
		(layer "In11.Cu")
		(net "M_H_CPU1_SA_DQS_DN<6>")
	)
	(segment
		(start 140.060172 -283.68244)
		(end 138.921998 -282.544266)
		(width 0.088646)
		(layer "In11.Cu")
		(net "M_H_CPU1_SA_DQS_DN<6>")
	)
	(segment
		(start 177.124106 -309.090822)
		(end 176.601882 -309.090822)
		(width 0.18288)
		(layer "In11.Cu")
		(net "M_H_CPU1_SA_DQS_DN<6>")
	)
	(segment
		(start 183.168036 -308.828186)
		(end 181.686454 -308.828186)
		(width 0.18288)
		(layer "In11.Cu")
		(net "M_H_CPU1_SA_DQS_DN<6>")
	)
	(segment
		(start 174.373032 -308.857142)
		(end 173.553882 -309.676292)
		(width 0.18288)
		(layer "In11.Cu")
		(net "M_H_CPU1_SA_DQS_DN<6>")
	)
	(segment
		(start 155.54452 -304.903886)
		(end 154.563064 -303.92243)
		(width 0.18288)
		(layer "In11.Cu")
		(net "M_H_CPU1_SA_DQS_DN<6>")
	)
	(segment
		(start 193.880994 -307.783992)
		(end 192.834768 -308.830218)
		(width 0.18288)
		(layer "In11.Cu")
		(net "M_H_CPU1_SA_DQS_DN<6>")
	)
	(segment
		(start 192.47231 -308.830218)
		(end 192.211706 -309.090822)
		(width 0.18288)
		(layer "In11.Cu")
		(net "M_H_CPU1_SA_DQS_DN<6>")
	)
	(segment
		(start 175.695102 -308.981602)
		(end 175.146462 -308.981602)
		(width 0.18288)
		(layer "In11.Cu")
		(net "M_H_CPU1_SA_DQS_DN<6>")
	)
	(segment
		(start 187.438284 -308.004464)
		(end 186.684158 -308.004464)
		(width 0.18288)
		(layer "In11.Cu")
		(net "M_H_CPU1_SA_DQS_DN<6>")
	)
	(segment
		(start 181.686454 -308.828186)
		(end 181.561994 -308.952646)
		(width 0.18288)
		(layer "In11.Cu")
		(net "M_H_CPU1_SA_DQS_DN<6>")
	)
	(segment
		(start 175.022002 -308.857142)
		(end 174.373032 -308.857142)
		(width 0.18288)
		(layer "In11.Cu")
		(net "M_H_CPU1_SA_DQS_DN<6>")
	)
	(segment
		(start 201.430636 -302.020986)
		(end 200.288144 -303.163478)
		(width 0.18288)
		(layer "In11.Cu")
		(net "M_H_CPU1_SA_DQS_DN<6>")
	)
	(segment
		(start 203.723494 -302.026574)
		(end 203.463906 -302.026574)
		(width 0.18288)
		(layer "In11.Cu")
		(net "M_H_CPU1_SA_DQS_DN<6>")
	)
	(segment
		(start 127.631444 -277.536656)
		(end 127.631444 -277.522432)
		(width 0.088646)
		(layer "In11.Cu")
		(net "M_H_CPU1_SA_DQS_DN<6>")
	)
	(segment
		(start 194.65925 -307.783992)
		(end 193.880994 -307.783992)
		(width 0.18288)
		(layer "In11.Cu")
		(net "M_H_CPU1_SA_DQS_DN<6>")
	)
	(segment
		(start 199.310244 -304.705766)
		(end 198.345044 -305.670966)
		(width 0.18288)
		(layer "In11.Cu")
		(net "M_H_CPU1_SA_DQS_DN<6>")
	)
	(segment
		(start 126.17196 -275.34997)
		(end 126.148846 -275.326856)
		(width 0.088646)
		(layer "In11.Cu")
		(net "M_H_CPU1_SA_DQS_DN<6>")
	)
	(segment
		(start 206.52232 -302.441102)
		(end 206.350108 -302.613314)
		(width 0.18288)
		(layer "In11.Cu")
		(net "M_H_CPU1_SA_DQS_DN<6>")
	)
	(segment
		(start 155.54452 -305.079908)
		(end 155.54452 -304.903886)
		(width 0.18288)
		(layer "In11.Cu")
		(net "M_H_CPU1_SA_DQS_DN<6>")
	)
	(segment
		(start 130.27406 -278.832056)
		(end 130.263646 -278.82596)
		(width 0.088646)
		(layer "In11.Cu")
		(net "M_H_CPU1_SA_DQS_DN<6>")
	)
	(segment
		(start 169.319194 -308.123336)
		(end 168.1988 -307.002942)
		(width 0.18288)
		(layer "In11.Cu")
		(net "M_H_CPU1_SA_DQS_DN<6>")
	)
	(segment
		(start 167.457882 -307.127402)
		(end 166.909242 -307.127402)
		(width 0.18288)
		(layer "In11.Cu")
		(net "M_H_CPU1_SA_DQS_DN<6>")
	)
	(segment
		(start 126.14148 -275.326856)
		(end 126.139448 -275.323554)
		(width 0.088646)
		(layer "In11.Cu")
		(net "M_H_CPU1_SA_DQS_DN<6>")
	)
	(segment
		(start 195.375276 -307.067966)
		(end 194.65925 -307.783992)
		(width 0.18288)
		(layer "In11.Cu")
		(net "M_H_CPU1_SA_DQS_DN<6>")
	)
	(segment
		(start 131.76885 -278.82596)
		(end 131.758436 -278.832056)
		(width 0.088646)
		(layer "In11.Cu")
		(net "M_H_CPU1_SA_DQS_DN<6>")
	)
	(segment
		(start 199.60082 -304.705766)
		(end 199.310244 -304.705766)
		(width 0.18288)
		(layer "In11.Cu")
		(net "M_H_CPU1_SA_DQS_DN<6>")
	)
	(segment
		(start 185.213498 -308.128924)
		(end 184.664858 -308.128924)
		(width 0.18288)
		(layer "In11.Cu")
		(net "M_H_CPU1_SA_DQS_DN<6>")
	)
	(segment
		(start 191.689482 -309.090822)
		(end 191.45123 -308.85257)
		(width 0.18288)
		(layer "In11.Cu")
		(net "M_H_CPU1_SA_DQS_DN<6>")
	)
	(segment
		(start 176.368202 -308.857142)
		(end 175.819562 -308.857142)
		(width 0.18288)
		(layer "In11.Cu")
		(net "M_H_CPU1_SA_DQS_DN<6>")
	)
	(segment
		(start 185.886598 -308.004464)
		(end 185.337958 -308.004464)
		(width 0.18288)
		(layer "In11.Cu")
		(net "M_H_CPU1_SA_DQS_DN<6>")
	)
	(segment
		(start 191.45123 -308.85257)
		(end 190.890652 -308.85257)
		(width 0.18288)
		(layer "In11.Cu")
		(net "M_H_CPU1_SA_DQS_DN<6>")
	)
	(segment
		(start 172.501814 -309.94096)
		(end 172.260768 -309.699914)
		(width 0.18288)
		(layer "In11.Cu")
		(net "M_H_CPU1_SA_DQS_DN<6>")
	)
	(segment
		(start 166.784782 -307.002942)
		(end 165.033706 -307.002942)
		(width 0.18288)
		(layer "In11.Cu")
		(net "M_H_CPU1_SA_DQS_DN<6>")
	)
	(segment
		(start 136.089644 -279.160224)
		(end 136.089644 -279.150318)
		(width 0.088646)
		(layer "In11.Cu")
		(net "M_H_CPU1_SA_DQS_DN<6>")
	)
	(segment
		(start 138.921998 -282.544266)
		(end 138.921998 -281.919172)
		(width 0.088646)
		(layer "In11.Cu")
		(net "M_H_CPU1_SA_DQS_DN<6>")
	)
	(segment
		(start 126.983236 -276.389338)
		(end 126.96825 -276.380702)
		(width 0.088646)
		(layer "In11.Cu")
		(net "M_H_CPU1_SA_DQS_DN<6>")
	)
	(segment
		(start 205.531974 -302.737774)
		(end 204.983334 -302.737774)
		(width 0.18288)
		(layer "In11.Cu")
		(net "M_H_CPU1_SA_DQS_DN<6>")
	)
	(segment
		(start 126.148846 -275.326856)
		(end 126.14148 -275.326856)
		(width 0.088646)
		(layer "In11.Cu")
		(net "M_H_CPU1_SA_DQS_DN<6>")
	)
	(segment
		(start 162.389312 -307.71846)
		(end 162.264852 -307.84292)
		(width 0.18288)
		(layer "In11.Cu")
		(net "M_H_CPU1_SA_DQS_DN<6>")
	)
	(segment
		(start 205.656434 -302.613314)
		(end 205.531974 -302.737774)
		(width 0.18288)
		(layer "In11.Cu")
		(net "M_H_CPU1_SA_DQS_DN<6>")
	)
	(segment
		(start 187.674758 -308.240938)
		(end 187.438284 -308.004464)
		(width 0.18288)
		(layer "In11.Cu")
		(net "M_H_CPU1_SA_DQS_DN<6>")
	)
	(segment
		(start 202.76185 -302.291242)
		(end 202.491594 -302.020986)
		(width 0.18288)
		(layer "In11.Cu")
		(net "M_H_CPU1_SA_DQS_DN<6>")
	)
	(segment
		(start 157.232604 -306.259484)
		(end 156.900118 -306.259484)
		(width 0.18288)
		(layer "In11.Cu")
		(net "M_H_CPU1_SA_DQS_DN<6>")
	)
	(segment
		(start 207.071214 -302.716692)
		(end 206.795624 -302.441102)
		(width 0.18288)
		(layer "In11.Cu")
		(net "M_H_CPU1_SA_DQS_DN<6>")
	)
	(segment
		(start 126.513082 -275.575522)
		(end 126.497842 -275.566124)
		(width 0.088646)
		(layer "In11.Cu")
		(net "M_H_CPU1_SA_DQS_DN<6>")
	)
	(segment
		(start 203.051664 -302.291242)
		(end 202.874118 -302.291242)
		(width 0.16002)
		(layer "In11.Cu")
		(net "M_H_CPU1_SA_DQS_DN<6>")
	)
	(segment
		(start 163.735512 -307.71846)
		(end 163.611052 -307.84292)
		(width 0.18288)
		(layer "In11.Cu")
		(net "M_H_CPU1_SA_DQS_DN<6>")
	)
	(segment
		(start 162.264852 -307.84292)
		(end 161.716212 -307.84292)
		(width 0.18288)
		(layer "In11.Cu")
		(net "M_H_CPU1_SA_DQS_DN<6>")
	)
	(segment
		(start 139.99972 -283.87167)
		(end 140.060172 -283.811218)
		(width 0.088646)
		(layer "In11.Cu")
		(net "M_H_CPU1_SA_DQS_DN<6>")
	)
	(segment
		(start 173.024038 -309.94096)
		(end 172.501814 -309.94096)
		(width 0.18288)
		(layer "In11.Cu")
		(net "M_H_CPU1_SA_DQS_DN<6>")
	)
	(segment
		(start 200.288144 -303.163478)
		(end 200.288144 -304.018442)
		(width 0.18288)
		(layer "In11.Cu")
		(net "M_H_CPU1_SA_DQS_DN<6>")
	)
	(segment
		(start 198.345044 -305.670966)
		(end 197.41642 -305.670966)
		(width 0.18288)
		(layer "In11.Cu")
		(net "M_H_CPU1_SA_DQS_DN<6>")
	)
	(segment
		(start 162.937952 -307.71846)
		(end 162.389312 -307.71846)
		(width 0.18288)
		(layer "In11.Cu")
		(net "M_H_CPU1_SA_DQS_DN<6>")
	)
	(segment
		(start 167.582342 -307.002942)
		(end 167.457882 -307.127402)
		(width 0.18288)
		(layer "In11.Cu")
		(net "M_H_CPU1_SA_DQS_DN<6>")
	)
	(segment
		(start 173.288706 -309.676292)
		(end 173.024038 -309.94096)
		(width 0.18288)
		(layer "In11.Cu")
		(net "M_H_CPU1_SA_DQS_DN<6>")
	)
	(segment
		(start 126.139448 -275.323554)
		(end 125.985778 -275.21916)
		(width 0.088646)
		(layer "In11.Cu")
		(net "M_H_CPU1_SA_DQS_DN<6>")
	)
	(segment
		(start 200.288144 -304.018442)
		(end 199.60082 -304.705766)
		(width 0.18288)
		(layer "In11.Cu")
		(net "M_H_CPU1_SA_DQS_DN<6>")
	)
	(segment
		(start 180.888894 -308.828186)
		(end 180.26888 -308.828186)
		(width 0.18288)
		(layer "In11.Cu")
		(net "M_H_CPU1_SA_DQS_DN<6>")
	)
	(segment
		(start 175.146462 -308.981602)
		(end 175.022002 -308.857142)
		(width 0.18288)
		(layer "In11.Cu")
		(net "M_H_CPU1_SA_DQS_DN<6>")
	)
	(segment
		(start 165.033706 -307.002942)
		(end 164.318188 -307.71846)
		(width 0.18288)
		(layer "In11.Cu")
		(net "M_H_CPU1_SA_DQS_DN<6>")
	)
	(segment
		(start 177.36312 -308.851808)
		(end 177.124106 -309.090822)
		(width 0.18288)
		(layer "In11.Cu")
		(net "M_H_CPU1_SA_DQS_DN<6>")
	)
	(segment
		(start 126.349506 -275.482812)
		(end 126.17196 -275.34997)
		(width 0.088646)
		(layer "In11.Cu")
		(net "M_H_CPU1_SA_DQS_DN<6>")
	)
	(segment
		(start 129.041398 -278.351996)
		(end 129.041398 -278.336502)
		(width 0.088646)
		(layer "In11.Cu")
		(net "M_H_CPU1_SA_DQS_DN<6>")
	)
	(segment
		(start 197.41642 -305.670966)
		(end 196.01942 -307.067966)
		(width 0.18288)
		(layer "In11.Cu")
		(net "M_H_CPU1_SA_DQS_DN<6>")
	)
	(segment
		(start 178.922934 -308.22265)
		(end 178.293776 -308.851808)
		(width 0.18288)
		(layer "In11.Cu")
		(net "M_H_CPU1_SA_DQS_DN<6>")
	)
	(segment
		(start 186.011058 -308.128924)
		(end 185.886598 -308.004464)
		(width 0.18288)
		(layer "In11.Cu")
		(net "M_H_CPU1_SA_DQS_DN<6>")
	)
	(segment
		(start 184.664858 -308.128924)
		(end 184.540398 -308.004464)
		(width 0.18288)
		(layer "In11.Cu")
		(net "M_H_CPU1_SA_DQS_DN<6>")
	)
	(segment
		(start 140.060172 -283.811218)
		(end 140.060172 -283.68244)
		(width 0.088646)
		(layer "In11.Cu")
		(net "M_H_CPU1_SA_DQS_DN<6>")
	)
	(segment
		(start 204.858874 -302.613314)
		(end 204.310234 -302.613314)
		(width 0.18288)
		(layer "In11.Cu")
		(net "M_H_CPU1_SA_DQS_DN<6>")
	)
	(segment
		(start 146.393662 -292.198552)
		(end 146.393662 -290.675314)
		(width 0.18288)
		(layer "In11.Cu")
		(net "M_H_CPU1_SA_DQS_DN<6>")
	)
	(segment
		(start 188.329062 -307.992526)
		(end 188.08065 -308.240938)
		(width 0.18288)
		(layer "In11.Cu")
		(net "M_H_CPU1_SA_DQS_DN<6>")
	)
	(segment
		(start 136.559544 -279.982676)
		(end 136.559544 -279.964134)
		(width 0.088646)
		(layer "In11.Cu")
		(net "M_H_CPU1_SA_DQS_DN<6>")
	)
	(segment
		(start 206.350108 -302.613314)
		(end 205.656434 -302.613314)
		(width 0.18288)
		(layer "In11.Cu")
		(net "M_H_CPU1_SA_DQS_DN<6>")
	)
	(segment
		(start 190.766192 -308.97703)
		(end 190.217552 -308.97703)
		(width 0.18288)
		(layer "In11.Cu")
		(net "M_H_CPU1_SA_DQS_DN<6>")
	)
	(segment
		(start 181.013354 -308.952646)
		(end 180.888894 -308.828186)
		(width 0.18288)
		(layer "In11.Cu")
		(net "M_H_CPU1_SA_DQS_DN<6>")
	)
	(segment
		(start 127.452882 -277.203154)
		(end 127.443992 -277.198074)
		(width 0.088646)
		(layer "In11.Cu")
		(net "M_H_CPU1_SA_DQS_DN<6>")
	)
	(segment
		(start 138.246104 -281.263852)
		(end 138.245596 -281.264106)
		(width 0.088646)
		(layer "In11.Cu")
		(net "M_H_CPU1_SA_DQS_DN<6>")
	)
	(segment
		(start 170.556682 -308.731666)
		(end 169.948098 -308.123336)
		(width 0.18288)
		(layer "In11.Cu")
		(net "M_H_CPU1_SA_DQS_DN<6>")
	)
	(segment
		(start 203.199238 -302.291242)
		(end 203.051664 -302.291242)
		(width 0.18288)
		(layer "In11.Cu")
		(net "M_H_CPU1_SA_DQS_DN<6>")
	)
	(segment
		(start 160.470596 -307.71846)
		(end 159.980376 -307.22824)
		(width 0.18288)
		(layer "In11.Cu")
		(net "M_H_CPU1_SA_DQS_DN<6>")
	)
	(segment
		(start 202.874118 -302.291242)
		(end 202.76185 -302.291242)
		(width 0.18288)
		(layer "In11.Cu")
		(net "M_H_CPU1_SA_DQS_DN<6>")
	)
	(segment
		(start 159.416242 -306.664106)
		(end 159.028384 -306.276248)
		(width 0.18288)
		(layer "In11.Cu")
		(net "M_H_CPU1_SA_DQS_DN<6>")
	)
	(segment
		(start 133.648196 -278.82596)
		(end 133.637782 -278.832056)
		(width 0.088646)
		(layer "In11.Cu")
		(net "M_H_CPU1_SA_DQS_DN<6>")
	)
	(segment
		(start 158.174944 -306.276248)
		(end 157.910784 -306.540408)
		(width 0.18288)
		(layer "In11.Cu")
		(net "M_H_CPU1_SA_DQS_DN<6>")
	)
	(segment
		(start 196.01942 -307.067966)
		(end 195.375276 -307.067966)
		(width 0.18288)
		(layer "In11.Cu")
		(net "M_H_CPU1_SA_DQS_DN<6>")
	)
	(segment
		(start 190.890652 -308.85257)
		(end 190.766192 -308.97703)
		(width 0.18288)
		(layer "In11.Cu")
		(net "M_H_CPU1_SA_DQS_DN<6>")
	)
	(segment
		(start 192.834768 -308.830218)
		(end 192.47231 -308.830218)
		(width 0.18288)
		(layer "In11.Cu")
		(net "M_H_CPU1_SA_DQS_DN<6>")
	)
	(segment
		(start 146.393662 -290.675314)
		(end 139.99972 -284.281372)
		(width 0.18288)
		(layer "In11.Cu")
		(net "M_H_CPU1_SA_DQS_DN<6>")
	)
	(segment
		(start 188.551312 -307.992526)
		(end 188.329062 -307.992526)
		(width 0.18288)
		(layer "In11.Cu")
		(net "M_H_CPU1_SA_DQS_DN<6>")
	)
	(segment
		(start 185.337958 -308.004464)
		(end 185.213498 -308.128924)
		(width 0.18288)
		(layer "In11.Cu")
		(net "M_H_CPU1_SA_DQS_DN<6>")
	)
	(segment
		(start 154.563064 -300.367954)
		(end 146.393662 -292.198552)
		(width 0.18288)
		(layer "In11.Cu")
		(net "M_H_CPU1_SA_DQS_DN<6>")
	)
	(segment
		(start 159.804354 -307.22824)
		(end 159.416242 -306.840128)
		(width 0.18288)
		(layer "In11.Cu")
		(net "M_H_CPU1_SA_DQS_DN<6>")
	)
	(segment
		(start 169.948098 -308.123336)
		(end 169.319194 -308.123336)
		(width 0.18288)
		(layer "In11.Cu")
		(net "M_H_CPU1_SA_DQS_DN<6>")
	)
	(segment
		(start 164.318188 -307.71846)
		(end 163.735512 -307.71846)
		(width 0.18288)
		(layer "In11.Cu")
		(net "M_H_CPU1_SA_DQS_DN<6>")
	)
	(segment
		(start 206.795624 -302.441102)
		(end 206.52232 -302.441102)
		(width 0.18288)
		(layer "In11.Cu")
		(net "M_H_CPU1_SA_DQS_DN<6>")
	)
	(segment
		(start 178.293776 -308.851808)
		(end 177.36312 -308.851808)
		(width 0.18288)
		(layer "In11.Cu")
		(net "M_H_CPU1_SA_DQS_DN<6>")
	)
	(segment
		(start 202.491594 -302.020986)
		(end 201.430636 -302.020986)
		(width 0.18288)
		(layer "In11.Cu")
		(net "M_H_CPU1_SA_DQS_DN<6>")
	)
	(segment
		(start 157.513528 -306.540408)
		(end 157.232604 -306.259484)
		(width 0.18288)
		(layer "In11.Cu")
		(net "M_H_CPU1_SA_DQS_DN<6>")
	)
	(segment
		(start 163.062412 -307.84292)
		(end 162.937952 -307.71846)
		(width 0.18288)
		(layer "In11.Cu")
		(net "M_H_CPU1_SA_DQS_DN<6>")
	)
	(segment
		(start 189.411356 -308.85257)
		(end 188.551312 -307.992526)
		(width 0.18288)
		(layer "In11.Cu")
		(net "M_H_CPU1_SA_DQS_DN<6>")
	)
	(segment
		(start 136.380982 -279.644856)
		(end 136.372092 -279.639776)
		(width 0.088646)
		(layer "In11.Cu")
		(net "M_H_CPU1_SA_DQS_DN<6>")
	)
	(arc
		(start 128.47955 -278.012144)
		(mid 127.920124 -278.015837)
		(end 127.631444 -277.536656)
		(width 0.088646)
		(layer "In11.Cu")
		(net "M_H_CPU1_SA_DQS_DN<6>")
	)
	(arc
		(start 134.022592 -278.82596)
		(mid 133.835394 -278.775817)
		(end 133.648196 -278.82596)
		(width 0.088646)
		(layer "In11.Cu")
		(net "M_H_CPU1_SA_DQS_DN<6>")
	)
	(arc
		(start 131.203192 -278.82596)
		(mid 131.015994 -278.775817)
		(end 130.828796 -278.82596)
		(width 0.088646)
		(layer "In11.Cu")
		(net "M_H_CPU1_SA_DQS_DN<6>")
	)
	(arc
		(start 127.161798 -276.708616)
		(mid 127.114119 -276.525716)
		(end 126.983236 -276.389338)
		(width 0.088646)
		(layer "In11.Cu")
		(net "M_H_CPU1_SA_DQS_DN<6>")
	)
	(arc
		(start 138.32967 -281.326844)
		(mid 138.290095 -281.292419)
		(end 138.246104 -281.263852)
		(width 0.088646)
		(layer "In11.Cu")
		(net "M_H_CPU1_SA_DQS_DN<6>")
	)
	(arc
		(start 136.559544 -279.964134)
		(mid 136.511865 -279.781234)
		(end 136.380982 -279.644856)
		(width 0.088646)
		(layer "In11.Cu")
		(net "M_H_CPU1_SA_DQS_DN<6>")
	)
	(arc
		(start 134.587996 -278.82596)
		(mid 134.305294 -278.901736)
		(end 134.022592 -278.82596)
		(width 0.088646)
		(layer "In11.Cu")
		(net "M_H_CPU1_SA_DQS_DN<6>")
	)
	(arc
		(start 132.70865 -278.82596)
		(mid 132.425948 -278.901736)
		(end 132.143246 -278.82596)
		(width 0.088646)
		(layer "In11.Cu")
		(net "M_H_CPU1_SA_DQS_DN<6>")
	)
	(arc
		(start 130.263646 -278.82596)
		(mid 130.076448 -278.775817)
		(end 129.88925 -278.82596)
		(width 0.088646)
		(layer "In11.Cu")
		(net "M_H_CPU1_SA_DQS_DN<6>")
	)
	(arc
		(start 133.083046 -278.82596)
		(mid 132.895848 -278.775817)
		(end 132.70865 -278.82596)
		(width 0.088646)
		(layer "In11.Cu")
		(net "M_H_CPU1_SA_DQS_DN<6>")
	)
	(arc
		(start 129.878836 -278.832056)
		(mid 129.325361 -278.827061)
		(end 129.041398 -278.351996)
		(width 0.088646)
		(layer "In11.Cu")
		(net "M_H_CPU1_SA_DQS_DN<6>")
	)
	(arc
		(start 137.407396 -280.453846)
		(mid 136.850022 -280.458395)
		(end 136.559544 -279.982676)
		(width 0.088646)
		(layer "In11.Cu")
		(net "M_H_CPU1_SA_DQS_DN<6>")
	)
	(arc
		(start 131.758436 -278.832056)
		(mid 131.480004 -278.901902)
		(end 131.203192 -278.82596)
		(width 0.088646)
		(layer "In11.Cu")
		(net "M_H_CPU1_SA_DQS_DN<6>")
	)
	(arc
		(start 135.527796 -278.82596)
		(mid 135.245094 -278.901736)
		(end 134.962392 -278.82596)
		(width 0.088646)
		(layer "In11.Cu")
		(net "M_H_CPU1_SA_DQS_DN<6>")
	)
	(arc
		(start 127.631444 -277.522432)
		(mid 127.583765 -277.339532)
		(end 127.452882 -277.203154)
		(width 0.088646)
		(layer "In11.Cu")
		(net "M_H_CPU1_SA_DQS_DN<6>")
	)
	(arc
		(start 127.443992 -277.198074)
		(mid 127.241169 -276.997843)
		(end 127.161798 -276.72411)
		(width 0.088646)
		(layer "In11.Cu")
		(net "M_H_CPU1_SA_DQS_DN<6>")
	)
	(arc
		(start 129.041398 -278.336502)
		(mid 128.854099 -278.012061)
		(end 128.47955 -278.012144)
		(width 0.088646)
		(layer "In11.Cu")
		(net "M_H_CPU1_SA_DQS_DN<6>")
	)
	(arc
		(start 138.245596 -281.264106)
		(mid 138.043183 -281.057693)
		(end 137.969244 -280.778204)
		(width 0.088646)
		(layer "In11.Cu")
		(net "M_H_CPU1_SA_DQS_DN<6>")
	)
	(arc
		(start 130.828796 -278.82596)
		(mid 130.552237 -278.901703)
		(end 130.27406 -278.832056)
		(width 0.088646)
		(layer "In11.Cu")
		(net "M_H_CPU1_SA_DQS_DN<6>")
	)
	(arc
		(start 126.96825 -276.380702)
		(mid 126.765663 -276.174351)
		(end 126.691644 -275.8948)
		(width 0.088646)
		(layer "In11.Cu")
		(net "M_H_CPU1_SA_DQS_DN<6>")
	)
	(arc
		(start 134.962392 -278.82596)
		(mid 134.775194 -278.775817)
		(end 134.587996 -278.82596)
		(width 0.088646)
		(layer "In11.Cu")
		(net "M_H_CPU1_SA_DQS_DN<6>")
	)
	(arc
		(start 136.089644 -279.150318)
		(mid 135.902345 -278.825877)
		(end 135.527796 -278.82596)
		(width 0.088646)
		(layer "In11.Cu")
		(net "M_H_CPU1_SA_DQS_DN<6>")
	)
	(arc
		(start 126.691644 -275.8948)
		(mid 126.643965 -275.7119)
		(end 126.513082 -275.575522)
		(width 0.088646)
		(layer "In11.Cu")
		(net "M_H_CPU1_SA_DQS_DN<6>")
	)
	(arc
		(start 132.143246 -278.82596)
		(mid 131.956048 -278.775817)
		(end 131.76885 -278.82596)
		(width 0.088646)
		(layer "In11.Cu")
		(net "M_H_CPU1_SA_DQS_DN<6>")
	)
	(arc
		(start 133.637782 -278.832056)
		(mid 133.359604 -278.901779)
		(end 133.083046 -278.82596)
		(width 0.088646)
		(layer "In11.Cu")
		(net "M_H_CPU1_SA_DQS_DN<6>")
	)
	(arc
		(start 136.372092 -279.639776)
		(mid 136.167757 -279.437171)
		(end 136.089644 -279.160224)
		(width 0.088646)
		(layer "In11.Cu")
		(net "M_H_CPU1_SA_DQS_DN<6>")
	)
	(arc
		(start 137.969244 -280.778204)
		(mid 137.781945 -280.453763)
		(end 137.407396 -280.453846)
		(width 0.088646)
		(layer "In11.Cu")
		(net "M_H_CPU1_SA_DQS_DN<6>")
	)
	(segment
		(start 213.234778 -311.366916)
		(end 213.724744 -311.366916)
		(width 0.20066)
		(layer "F.Cu")
		(net "M_H_CPU1_SA_DQS_DN<5>")
	)
	(segment
		(start 208.977992 -311.795414)
		(end 209.461354 -311.795414)
		(width 0.20066)
		(layer "F.Cu")
		(net "M_H_CPU1_SA_DQS_DN<5>")
	)
	(segment
		(start 214.17026 -311.812432)
		(end 214.961978 -311.812432)
		(width 0.20066)
		(layer "F.Cu")
		(net "M_H_CPU1_SA_DQS_DN<5>")
	)
	(segment
		(start 207.071214 -312.066686)
		(end 208.176114 -312.066686)
		(width 0.20066)
		(layer "F.Cu")
		(net "M_H_CPU1_SA_DQS_DN<5>")
	)
	(segment
		(start 215.216232 -312.066686)
		(end 215.719914 -312.066686)
		(width 0.20066)
		(layer "F.Cu")
		(net "M_H_CPU1_SA_DQS_DN<5>")
	)
	(segment
		(start 210.603084 -311.64784)
		(end 210.60918 -311.641744)
		(width 0.1016)
		(layer "F.Cu")
		(net "M_H_CPU1_SA_DQS_DN<5>")
	)
	(segment
		(start 212.619336 -311.641744)
		(end 212.630258 -311.652666)
		(width 0.1016)
		(layer "F.Cu")
		(net "M_H_CPU1_SA_DQS_DN<5>")
	)
	(segment
		(start 210.60918 -311.641744)
		(end 212.619336 -311.641744)
		(width 0.1016)
		(layer "F.Cu")
		(net "M_H_CPU1_SA_DQS_DN<5>")
	)
	(segment
		(start 129.136648 -277.522178)
		(end 129.136394 -277.522432)
		(width 0.20066)
		(layer "F.Cu")
		(net "M_H_CPU1_SA_DQS_DN<5>")
	)
	(segment
		(start 210.286092 -311.64784)
		(end 210.598258 -311.64784)
		(width 0.20066)
		(layer "F.Cu")
		(net "M_H_CPU1_SA_DQS_DN<5>")
	)
	(segment
		(start 209.461354 -311.795414)
		(end 209.886296 -311.370472)
		(width 0.20066)
		(layer "F.Cu")
		(net "M_H_CPU1_SA_DQS_DN<5>")
	)
	(segment
		(start 209.886296 -311.370472)
		(end 210.008724 -311.370472)
		(width 0.20066)
		(layer "F.Cu")
		(net "M_H_CPU1_SA_DQS_DN<5>")
	)
	(segment
		(start 213.724744 -311.366916)
		(end 214.17026 -311.812432)
		(width 0.20066)
		(layer "F.Cu")
		(net "M_H_CPU1_SA_DQS_DN<5>")
	)
	(segment
		(start 212.949028 -311.652666)
		(end 213.234778 -311.366916)
		(width 0.20066)
		(layer "F.Cu")
		(net "M_H_CPU1_SA_DQS_DN<5>")
	)
	(segment
		(start 214.961978 -311.812432)
		(end 215.216232 -312.066686)
		(width 0.20066)
		(layer "F.Cu")
		(net "M_H_CPU1_SA_DQS_DN<5>")
	)
	(segment
		(start 210.008724 -311.370472)
		(end 210.286092 -311.64784)
		(width 0.20066)
		(layer "F.Cu")
		(net "M_H_CPU1_SA_DQS_DN<5>")
	)
	(segment
		(start 210.598258 -311.64784)
		(end 210.603084 -311.64784)
		(width 0.101854)
		(layer "F.Cu")
		(net "M_H_CPU1_SA_DQS_DN<5>")
	)
	(segment
		(start 129.136648 -276.986492)
		(end 129.136648 -277.522178)
		(width 0.20066)
		(layer "F.Cu")
		(net "M_H_CPU1_SA_DQS_DN<5>")
	)
	(segment
		(start 208.176114 -312.066686)
		(end 208.70672 -312.066686)
		(width 0.20066)
		(layer "F.Cu")
		(net "M_H_CPU1_SA_DQS_DN<5>")
	)
	(segment
		(start 212.630258 -311.652666)
		(end 212.949028 -311.652666)
		(width 0.20066)
		(layer "F.Cu")
		(net "M_H_CPU1_SA_DQS_DN<5>")
	)
	(segment
		(start 208.70672 -312.066686)
		(end 208.977992 -311.795414)
		(width 0.20066)
		(layer "F.Cu")
		(net "M_H_CPU1_SA_DQS_DN<5>")
	)
	(segment
		(start 205.696566 -311.958736)
		(end 204.689202 -311.958736)
		(width 0.18288)
		(layer "In6.Cu")
		(net "M_H_CPU1_SA_DQS_DN<5>")
	)
	(segment
		(start 138.439144 -278.355044)
		(end 138.439144 -278.336502)
		(width 0.088646)
		(layer "In6.Cu")
		(net "M_H_CPU1_SA_DQS_DN<5>")
	)
	(segment
		(start 204.111098 -311.380632)
		(end 203.43241 -311.380632)
		(width 0.18288)
		(layer "In6.Cu")
		(net "M_H_CPU1_SA_DQS_DN<5>")
	)
	(segment
		(start 175.694848 -307.259228)
		(end 175.148748 -307.259228)
		(width 0.18288)
		(layer "In6.Cu")
		(net "M_H_CPU1_SA_DQS_DN<5>")
	)
	(segment
		(start 206.794862 -311.790334)
		(end 206.10322 -311.790334)
		(width 0.18288)
		(layer "In6.Cu")
		(net "M_H_CPU1_SA_DQS_DN<5>")
	)
	(segment
		(start 188.060076 -311.640982)
		(end 187.686696 -311.640982)
		(width 0.18288)
		(layer "In6.Cu")
		(net "M_H_CPU1_SA_DQS_DN<5>")
	)
	(segment
		(start 178.465226 -307.694584)
		(end 177.88128 -307.110638)
		(width 0.18288)
		(layer "In6.Cu")
		(net "M_H_CPU1_SA_DQS_DN<5>")
	)
	(segment
		(start 178.91633 -307.694584)
		(end 178.465226 -307.694584)
		(width 0.18288)
		(layer "In6.Cu")
		(net "M_H_CPU1_SA_DQS_DN<5>")
	)
	(segment
		(start 174.478188 -307.134768)
		(end 173.658022 -307.954934)
		(width 0.18288)
		(layer "In6.Cu")
		(net "M_H_CPU1_SA_DQS_DN<5>")
	)
	(segment
		(start 135.527796 -277.198074)
		(end 135.513064 -277.20671)
		(width 0.088646)
		(layer "In6.Cu")
		(net "M_H_CPU1_SA_DQS_DN<5>")
	)
	(segment
		(start 177.09007 -307.391054)
		(end 176.704244 -307.391054)
		(width 0.18288)
		(layer "In6.Cu")
		(net "M_H_CPU1_SA_DQS_DN<5>")
	)
	(segment
		(start 165.751002 -305.986434)
		(end 165.041834 -305.277266)
		(width 0.18288)
		(layer "In6.Cu")
		(net "M_H_CPU1_SA_DQS_DN<5>")
	)
	(segment
		(start 157.895798 -304.838862)
		(end 157.507686 -304.838862)
		(width 0.18288)
		(layer "In6.Cu")
		(net "M_H_CPU1_SA_DQS_DN<5>")
	)
	(segment
		(start 171.683172 -308.152292)
		(end 171.137072 -308.152292)
		(width 0.18288)
		(layer "In6.Cu")
		(net "M_H_CPU1_SA_DQS_DN<5>")
	)
	(segment
		(start 157.260544 -304.59172)
		(end 156.944568 -304.59172)
		(width 0.18288)
		(layer "In6.Cu")
		(net "M_H_CPU1_SA_DQS_DN<5>")
	)
	(segment
		(start 129.889504 -277.19782)
		(end 129.846832 -277.22068)
		(width 0.088646)
		(layer "In6.Cu")
		(net "M_H_CPU1_SA_DQS_DN<5>")
	)
	(segment
		(start 157.507686 -304.838862)
		(end 157.260544 -304.59172)
		(width 0.18288)
		(layer "In6.Cu")
		(net "M_H_CPU1_SA_DQS_DN<5>")
	)
	(segment
		(start 129.836418 -277.226268)
		(end 129.683002 -277.289768)
		(width 0.088646)
		(layer "In6.Cu")
		(net "M_H_CPU1_SA_DQS_DN<5>")
	)
	(segment
		(start 161.379408 -303.735486)
		(end 159.9057 -303.735486)
		(width 0.18288)
		(layer "In6.Cu")
		(net "M_H_CPU1_SA_DQS_DN<5>")
	)
	(segment
		(start 204.689202 -311.958736)
		(end 204.111098 -311.380632)
		(width 0.18288)
		(layer "In6.Cu")
		(net "M_H_CPU1_SA_DQS_DN<5>")
	)
	(segment
		(start 172.976286 -308.241192)
		(end 172.54728 -308.241192)
		(width 0.18288)
		(layer "In6.Cu")
		(net "M_H_CPU1_SA_DQS_DN<5>")
	)
	(segment
		(start 171.137072 -308.152292)
		(end 171.012612 -308.027832)
		(width 0.18288)
		(layer "In6.Cu")
		(net "M_H_CPU1_SA_DQS_DN<5>")
	)
	(segment
		(start 193.876676 -311.158636)
		(end 193.23685 -310.51881)
		(width 0.18288)
		(layer "In6.Cu")
		(net "M_H_CPU1_SA_DQS_DN<5>")
	)
	(segment
		(start 130.24358 -277.186898)
		(end 130.18516 -277.160482)
		(width 0.088646)
		(layer "In6.Cu")
		(net "M_H_CPU1_SA_DQS_DN<5>")
	)
	(segment
		(start 145.683478 -280.300176)
		(end 140.980668 -280.300176)
		(width 0.18288)
		(layer "In6.Cu")
		(net "M_H_CPU1_SA_DQS_DN<5>")
	)
	(segment
		(start 166.313358 -306.54879)
		(end 166.137336 -306.54879)
		(width 0.18288)
		(layer "In6.Cu")
		(net "M_H_CPU1_SA_DQS_DN<5>")
	)
	(segment
		(start 167.922702 -307.121306)
		(end 166.885874 -307.121306)
		(width 0.18288)
		(layer "In6.Cu")
		(net "M_H_CPU1_SA_DQS_DN<5>")
	)
	(segment
		(start 175.024288 -307.134768)
		(end 174.478188 -307.134768)
		(width 0.18288)
		(layer "In6.Cu")
		(net "M_H_CPU1_SA_DQS_DN<5>")
	)
	(segment
		(start 140.980668 -280.300176)
		(end 140.463016 -280.0858)
		(width 0.18288)
		(layer "In6.Cu")
		(net "M_H_CPU1_SA_DQS_DN<5>")
	)
	(segment
		(start 159.054546 -304.58664)
		(end 158.14802 -304.58664)
		(width 0.18288)
		(layer "In6.Cu")
		(net "M_H_CPU1_SA_DQS_DN<5>")
	)
	(segment
		(start 181.809644 -309.914798)
		(end 181.633622 -309.914798)
		(width 0.18288)
		(layer "In6.Cu")
		(net "M_H_CPU1_SA_DQS_DN<5>")
	)
	(segment
		(start 129.889758 -277.197312)
		(end 129.889504 -277.19782)
		(width 0.088646)
		(layer "In6.Cu")
		(net "M_H_CPU1_SA_DQS_DN<5>")
	)
	(segment
		(start 170.466512 -308.027832)
		(end 170.342052 -308.152292)
		(width 0.18288)
		(layer "In6.Cu")
		(net "M_H_CPU1_SA_DQS_DN<5>")
	)
	(segment
		(start 191.525906 -310.5404)
		(end 190.928244 -310.5404)
		(width 0.18288)
		(layer "In6.Cu")
		(net "M_H_CPU1_SA_DQS_DN<5>")
	)
	(segment
		(start 163.93922 -304.701702)
		(end 163.552886 -304.315368)
		(width 0.18288)
		(layer "In6.Cu")
		(net "M_H_CPU1_SA_DQS_DN<5>")
	)
	(segment
		(start 169.671492 -308.027832)
		(end 168.829228 -308.027832)
		(width 0.18288)
		(layer "In6.Cu")
		(net "M_H_CPU1_SA_DQS_DN<5>")
	)
	(segment
		(start 192.15862 -310.791098)
		(end 191.776604 -310.791098)
		(width 0.18288)
		(layer "In6.Cu")
		(net "M_H_CPU1_SA_DQS_DN<5>")
	)
	(segment
		(start 175.148748 -307.259228)
		(end 175.024288 -307.134768)
		(width 0.18288)
		(layer "In6.Cu")
		(net "M_H_CPU1_SA_DQS_DN<5>")
	)
	(segment
		(start 138.260582 -278.017224)
		(end 138.251692 -278.012144)
		(width 0.088646)
		(layer "In6.Cu")
		(net "M_H_CPU1_SA_DQS_DN<5>")
	)
	(segment
		(start 185.403236 -311.493662)
		(end 184.857136 -311.493662)
		(width 0.18288)
		(layer "In6.Cu")
		(net "M_H_CPU1_SA_DQS_DN<5>")
	)
	(segment
		(start 203.17206 -311.640982)
		(end 202.784964 -311.640982)
		(width 0.18288)
		(layer "In6.Cu")
		(net "M_H_CPU1_SA_DQS_DN<5>")
	)
	(segment
		(start 189.587124 -310.5404)
		(end 188.762132 -311.365392)
		(width 0.18288)
		(layer "In6.Cu")
		(net "M_H_CPU1_SA_DQS_DN<5>")
	)
	(segment
		(start 190.257684 -310.66486)
		(end 190.133224 -310.5404)
		(width 0.18288)
		(layer "In6.Cu")
		(net "M_H_CPU1_SA_DQS_DN<5>")
	)
	(segment
		(start 131.768596 -277.198074)
		(end 131.758182 -277.20417)
		(width 0.088646)
		(layer "In6.Cu")
		(net "M_H_CPU1_SA_DQS_DN<5>")
	)
	(segment
		(start 165.751002 -306.162456)
		(end 165.751002 -305.986434)
		(width 0.18288)
		(layer "In6.Cu")
		(net "M_H_CPU1_SA_DQS_DN<5>")
	)
	(segment
		(start 158.14802 -304.58664)
		(end 157.895798 -304.838862)
		(width 0.18288)
		(layer "In6.Cu")
		(net "M_H_CPU1_SA_DQS_DN<5>")
	)
	(segment
		(start 202.525122 -311.38114)
		(end 198.73595 -311.38114)
		(width 0.18288)
		(layer "In6.Cu")
		(net "M_H_CPU1_SA_DQS_DN<5>")
	)
	(segment
		(start 207.071214 -312.066686)
		(end 206.794862 -311.790334)
		(width 0.18288)
		(layer "In6.Cu")
		(net "M_H_CPU1_SA_DQS_DN<5>")
	)
	(segment
		(start 190.803784 -310.66486)
		(end 190.257684 -310.66486)
		(width 0.18288)
		(layer "In6.Cu")
		(net "M_H_CPU1_SA_DQS_DN<5>")
	)
	(segment
		(start 186.073796 -311.369202)
		(end 185.527696 -311.369202)
		(width 0.18288)
		(layer "In6.Cu")
		(net "M_H_CPU1_SA_DQS_DN<5>")
	)
	(segment
		(start 173.262544 -307.954934)
		(end 172.976286 -308.241192)
		(width 0.18288)
		(layer "In6.Cu")
		(net "M_H_CPU1_SA_DQS_DN<5>")
	)
	(segment
		(start 173.658022 -307.954934)
		(end 173.262544 -307.954934)
		(width 0.18288)
		(layer "In6.Cu")
		(net "M_H_CPU1_SA_DQS_DN<5>")
	)
	(segment
		(start 164.690806 -305.277266)
		(end 164.115242 -304.701702)
		(width 0.18288)
		(layer "In6.Cu")
		(net "M_H_CPU1_SA_DQS_DN<5>")
	)
	(segment
		(start 166.137336 -306.54879)
		(end 165.751002 -306.162456)
		(width 0.18288)
		(layer "In6.Cu")
		(net "M_H_CPU1_SA_DQS_DN<5>")
	)
	(segment
		(start 181.633622 -309.914798)
		(end 181.247034 -309.52821)
		(width 0.18288)
		(layer "In6.Cu")
		(net "M_H_CPU1_SA_DQS_DN<5>")
	)
	(segment
		(start 130.260598 -277.196042)
		(end 130.24358 -277.186898)
		(width 0.088646)
		(layer "In6.Cu")
		(net "M_H_CPU1_SA_DQS_DN<5>")
	)
	(segment
		(start 202.784964 -311.640982)
		(end 202.525122 -311.38114)
		(width 0.18288)
		(layer "In6.Cu")
		(net "M_H_CPU1_SA_DQS_DN<5>")
	)
	(segment
		(start 197.21449 -312.046874)
		(end 195.92671 -310.759094)
		(width 0.18288)
		(layer "In6.Cu")
		(net "M_H_CPU1_SA_DQS_DN<5>")
	)
	(segment
		(start 187.686696 -311.640982)
		(end 187.414916 -311.369202)
		(width 0.18288)
		(layer "In6.Cu")
		(net "M_H_CPU1_SA_DQS_DN<5>")
	)
	(segment
		(start 129.136394 -277.373334)
		(end 129.136394 -277.522432)
		(width 0.088646)
		(layer "In6.Cu")
		(net "M_H_CPU1_SA_DQS_DN<5>")
	)
	(segment
		(start 130.264154 -277.19782)
		(end 130.2639 -277.19782)
		(width 0.088646)
		(layer "In6.Cu")
		(net "M_H_CPU1_SA_DQS_DN<5>")
	)
	(segment
		(start 180.138832 -308.917086)
		(end 178.91633 -307.694584)
		(width 0.18288)
		(layer "In6.Cu")
		(net "M_H_CPU1_SA_DQS_DN<5>")
	)
	(segment
		(start 129.846832 -277.22068)
		(end 129.84607 -277.221188)
		(width 0.088646)
		(layer "In6.Cu")
		(net "M_H_CPU1_SA_DQS_DN<5>")
	)
	(segment
		(start 139.939268 -279.859486)
		(end 139.843764 -279.630124)
		(width 0.088646)
		(layer "In6.Cu")
		(net "M_H_CPU1_SA_DQS_DN<5>")
	)
	(segment
		(start 177.88128 -307.110638)
		(end 177.370486 -307.110638)
		(width 0.18288)
		(layer "In6.Cu")
		(net "M_H_CPU1_SA_DQS_DN<5>")
	)
	(segment
		(start 180.811932 -308.917086)
		(end 180.138832 -308.917086)
		(width 0.18288)
		(layer "In6.Cu")
		(net "M_H_CPU1_SA_DQS_DN<5>")
	)
	(segment
		(start 171.012612 -308.027832)
		(end 170.466512 -308.027832)
		(width 0.18288)
		(layer "In6.Cu")
		(net "M_H_CPU1_SA_DQS_DN<5>")
	)
	(segment
		(start 161.634932 -303.99101)
		(end 161.379408 -303.735486)
		(width 0.18288)
		(layer "In6.Cu")
		(net "M_H_CPU1_SA_DQS_DN<5>")
	)
	(segment
		(start 140.367258 -280.0858)
		(end 140.34389 -280.0858)
		(width 0.088646)
		(layer "In6.Cu")
		(net "M_H_CPU1_SA_DQS_DN<5>")
	)
	(segment
		(start 165.041834 -305.277266)
		(end 164.690806 -305.277266)
		(width 0.18288)
		(layer "In6.Cu")
		(net "M_H_CPU1_SA_DQS_DN<5>")
	)
	(segment
		(start 170.342052 -308.152292)
		(end 169.795952 -308.152292)
		(width 0.18288)
		(layer "In6.Cu")
		(net "M_H_CPU1_SA_DQS_DN<5>")
	)
	(segment
		(start 168.829228 -308.027832)
		(end 167.922702 -307.121306)
		(width 0.18288)
		(layer "In6.Cu")
		(net "M_H_CPU1_SA_DQS_DN<5>")
	)
	(segment
		(start 156.530548 -300.750732)
		(end 148.661882 -292.882066)
		(width 0.18288)
		(layer "In6.Cu")
		(net "M_H_CPU1_SA_DQS_DN<5>")
	)
	(segment
		(start 140.283946 -280.025856)
		(end 140.105638 -280.025856)
		(width 0.088646)
		(layer "In6.Cu")
		(net "M_H_CPU1_SA_DQS_DN<5>")
	)
	(segment
		(start 129.683002 -277.289768)
		(end 129.31267 -277.289768)
		(width 0.088646)
		(layer "In6.Cu")
		(net "M_H_CPU1_SA_DQS_DN<5>")
	)
	(segment
		(start 129.31267 -277.289768)
		(end 129.196592 -277.313136)
		(width 0.088646)
		(layer "In6.Cu")
		(net "M_H_CPU1_SA_DQS_DN<5>")
	)
	(segment
		(start 163.552886 -304.139346)
		(end 163.131246 -303.717706)
		(width 0.18288)
		(layer "In6.Cu")
		(net "M_H_CPU1_SA_DQS_DN<5>")
	)
	(segment
		(start 190.133224 -310.5404)
		(end 189.587124 -310.5404)
		(width 0.18288)
		(layer "In6.Cu")
		(net "M_H_CPU1_SA_DQS_DN<5>")
	)
	(segment
		(start 176.704244 -307.391054)
		(end 176.447958 -307.134768)
		(width 0.18288)
		(layer "In6.Cu")
		(net "M_H_CPU1_SA_DQS_DN<5>")
	)
	(segment
		(start 140.34389 -280.0858)
		(end 140.283946 -280.025856)
		(width 0.088646)
		(layer "In6.Cu")
		(net "M_H_CPU1_SA_DQS_DN<5>")
	)
	(segment
		(start 133.648196 -277.198074)
		(end 133.633464 -277.20671)
		(width 0.088646)
		(layer "In6.Cu")
		(net "M_H_CPU1_SA_DQS_DN<5>")
	)
	(segment
		(start 140.463016 -280.0858)
		(end 140.367258 -280.0858)
		(width 0.18288)
		(layer "In6.Cu")
		(net "M_H_CPU1_SA_DQS_DN<5>")
	)
	(segment
		(start 195.92671 -310.759094)
		(end 195.15455 -310.759094)
		(width 0.18288)
		(layer "In6.Cu")
		(net "M_H_CPU1_SA_DQS_DN<5>")
	)
	(segment
		(start 186.744356 -311.493662)
		(end 186.198256 -311.493662)
		(width 0.18288)
		(layer "In6.Cu")
		(net "M_H_CPU1_SA_DQS_DN<5>")
	)
	(segment
		(start 166.885874 -307.121306)
		(end 166.313358 -306.54879)
		(width 0.18288)
		(layer "In6.Cu")
		(net "M_H_CPU1_SA_DQS_DN<5>")
	)
	(segment
		(start 192.430908 -310.51881)
		(end 192.15862 -310.791098)
		(width 0.18288)
		(layer "In6.Cu")
		(net "M_H_CPU1_SA_DQS_DN<5>")
	)
	(segment
		(start 137.969244 -277.540974)
		(end 137.969244 -277.522432)
		(width 0.088646)
		(layer "In6.Cu")
		(net "M_H_CPU1_SA_DQS_DN<5>")
	)
	(segment
		(start 163.552886 -304.315368)
		(end 163.552886 -304.139346)
		(width 0.18288)
		(layer "In6.Cu")
		(net "M_H_CPU1_SA_DQS_DN<5>")
	)
	(segment
		(start 159.9057 -303.735486)
		(end 159.054546 -304.58664)
		(width 0.18288)
		(layer "In6.Cu")
		(net "M_H_CPU1_SA_DQS_DN<5>")
	)
	(segment
		(start 171.807632 -308.027832)
		(end 171.683172 -308.152292)
		(width 0.18288)
		(layer "In6.Cu")
		(net "M_H_CPU1_SA_DQS_DN<5>")
	)
	(segment
		(start 137.790682 -277.203154)
		(end 137.781792 -277.198074)
		(width 0.088646)
		(layer "In6.Cu")
		(net "M_H_CPU1_SA_DQS_DN<5>")
	)
	(segment
		(start 176.447958 -307.134768)
		(end 175.819308 -307.134768)
		(width 0.18288)
		(layer "In6.Cu")
		(net "M_H_CPU1_SA_DQS_DN<5>")
	)
	(segment
		(start 198.070216 -312.046874)
		(end 197.21449 -312.046874)
		(width 0.18288)
		(layer "In6.Cu")
		(net "M_H_CPU1_SA_DQS_DN<5>")
	)
	(segment
		(start 182.335932 -310.441086)
		(end 181.809644 -309.914798)
		(width 0.18288)
		(layer "In6.Cu")
		(net "M_H_CPU1_SA_DQS_DN<5>")
	)
	(segment
		(start 181.247034 -309.352188)
		(end 180.811932 -308.917086)
		(width 0.18288)
		(layer "In6.Cu")
		(net "M_H_CPU1_SA_DQS_DN<5>")
	)
	(segment
		(start 185.527696 -311.369202)
		(end 185.403236 -311.493662)
		(width 0.18288)
		(layer "In6.Cu")
		(net "M_H_CPU1_SA_DQS_DN<5>")
	)
	(segment
		(start 163.131246 -303.717706)
		(end 162.256978 -303.717706)
		(width 0.18288)
		(layer "In6.Cu")
		(net "M_H_CPU1_SA_DQS_DN<5>")
	)
	(segment
		(start 169.795952 -308.152292)
		(end 169.671492 -308.027832)
		(width 0.18288)
		(layer "In6.Cu")
		(net "M_H_CPU1_SA_DQS_DN<5>")
	)
	(segment
		(start 172.33392 -308.027832)
		(end 171.807632 -308.027832)
		(width 0.18288)
		(layer "In6.Cu")
		(net "M_H_CPU1_SA_DQS_DN<5>")
	)
	(segment
		(start 162.256978 -303.717706)
		(end 161.983674 -303.99101)
		(width 0.18288)
		(layer "In6.Cu")
		(net "M_H_CPU1_SA_DQS_DN<5>")
	)
	(segment
		(start 148.661882 -283.27858)
		(end 145.683478 -280.300176)
		(width 0.18288)
		(layer "In6.Cu")
		(net "M_H_CPU1_SA_DQS_DN<5>")
	)
	(segment
		(start 186.198256 -311.493662)
		(end 186.073796 -311.369202)
		(width 0.18288)
		(layer "In6.Cu")
		(net "M_H_CPU1_SA_DQS_DN<5>")
	)
	(segment
		(start 129.974848 -277.158196)
		(end 129.929128 -277.177754)
		(width 0.088646)
		(layer "In6.Cu")
		(net "M_H_CPU1_SA_DQS_DN<5>")
	)
	(segment
		(start 175.819308 -307.134768)
		(end 175.694848 -307.259228)
		(width 0.18288)
		(layer "In6.Cu")
		(net "M_H_CPU1_SA_DQS_DN<5>")
	)
	(segment
		(start 183.287924 -310.441086)
		(end 182.335932 -310.441086)
		(width 0.18288)
		(layer "In6.Cu")
		(net "M_H_CPU1_SA_DQS_DN<5>")
	)
	(segment
		(start 195.15455 -310.759094)
		(end 194.755008 -311.158636)
		(width 0.18288)
		(layer "In6.Cu")
		(net "M_H_CPU1_SA_DQS_DN<5>")
	)
	(segment
		(start 140.105638 -280.025856)
		(end 139.939268 -279.859486)
		(width 0.088646)
		(layer "In6.Cu")
		(net "M_H_CPU1_SA_DQS_DN<5>")
	)
	(segment
		(start 198.73595 -311.38114)
		(end 198.070216 -312.046874)
		(width 0.18288)
		(layer "In6.Cu")
		(net "M_H_CPU1_SA_DQS_DN<5>")
	)
	(segment
		(start 139.115546 -278.901906)
		(end 139.00404 -278.901906)
		(width 0.088646)
		(layer "In6.Cu")
		(net "M_H_CPU1_SA_DQS_DN<5>")
	)
	(segment
		(start 190.928244 -310.5404)
		(end 190.803784 -310.66486)
		(width 0.18288)
		(layer "In6.Cu")
		(net "M_H_CPU1_SA_DQS_DN<5>")
	)
	(segment
		(start 172.54728 -308.241192)
		(end 172.33392 -308.027832)
		(width 0.18288)
		(layer "In6.Cu")
		(net "M_H_CPU1_SA_DQS_DN<5>")
	)
	(segment
		(start 129.836672 -277.226268)
		(end 129.836418 -277.226268)
		(width 0.088646)
		(layer "In6.Cu")
		(net "M_H_CPU1_SA_DQS_DN<5>")
	)
	(segment
		(start 203.43241 -311.380632)
		(end 203.17206 -311.640982)
		(width 0.18288)
		(layer "In6.Cu")
		(net "M_H_CPU1_SA_DQS_DN<5>")
	)
	(segment
		(start 156.530548 -304.1777)
		(end 156.530548 -300.750732)
		(width 0.18288)
		(layer "In6.Cu")
		(net "M_H_CPU1_SA_DQS_DN<5>")
	)
	(segment
		(start 184.857136 -311.493662)
		(end 184.732676 -311.369202)
		(width 0.18288)
		(layer "In6.Cu")
		(net "M_H_CPU1_SA_DQS_DN<5>")
	)
	(segment
		(start 164.115242 -304.701702)
		(end 163.93922 -304.701702)
		(width 0.18288)
		(layer "In6.Cu")
		(net "M_H_CPU1_SA_DQS_DN<5>")
	)
	(segment
		(start 136.467596 -277.198074)
		(end 136.457182 -277.20417)
		(width 0.088646)
		(layer "In6.Cu")
		(net "M_H_CPU1_SA_DQS_DN<5>")
	)
	(segment
		(start 188.335666 -311.365392)
		(end 188.060076 -311.640982)
		(width 0.18288)
		(layer "In6.Cu")
		(net "M_H_CPU1_SA_DQS_DN<5>")
	)
	(segment
		(start 191.776604 -310.791098)
		(end 191.525906 -310.5404)
		(width 0.18288)
		(layer "In6.Cu")
		(net "M_H_CPU1_SA_DQS_DN<5>")
	)
	(segment
		(start 184.21604 -311.369202)
		(end 183.287924 -310.441086)
		(width 0.18288)
		(layer "In6.Cu")
		(net "M_H_CPU1_SA_DQS_DN<5>")
	)
	(segment
		(start 139.843764 -279.630124)
		(end 139.115546 -278.901906)
		(width 0.088646)
		(layer "In6.Cu")
		(net "M_H_CPU1_SA_DQS_DN<5>")
	)
	(segment
		(start 134.587996 -277.198074)
		(end 134.573264 -277.20671)
		(width 0.088646)
		(layer "In6.Cu")
		(net "M_H_CPU1_SA_DQS_DN<5>")
	)
	(segment
		(start 177.370486 -307.110638)
		(end 177.09007 -307.391054)
		(width 0.18288)
		(layer "In6.Cu")
		(net "M_H_CPU1_SA_DQS_DN<5>")
	)
	(segment
		(start 181.247034 -309.52821)
		(end 181.247034 -309.352188)
		(width 0.18288)
		(layer "In6.Cu")
		(net "M_H_CPU1_SA_DQS_DN<5>")
	)
	(segment
		(start 161.983674 -303.99101)
		(end 161.634932 -303.99101)
		(width 0.18288)
		(layer "In6.Cu")
		(net "M_H_CPU1_SA_DQS_DN<5>")
	)
	(segment
		(start 206.10322 -311.790334)
		(end 205.696566 -311.958736)
		(width 0.18288)
		(layer "In6.Cu")
		(net "M_H_CPU1_SA_DQS_DN<5>")
	)
	(segment
		(start 135.536178 -277.193248)
		(end 135.527796 -277.198074)
		(width 0.088646)
		(layer "In6.Cu")
		(net "M_H_CPU1_SA_DQS_DN<5>")
	)
	(segment
		(start 184.732676 -311.369202)
		(end 184.21604 -311.369202)
		(width 0.18288)
		(layer "In6.Cu")
		(net "M_H_CPU1_SA_DQS_DN<5>")
	)
	(segment
		(start 193.23685 -310.51881)
		(end 192.430908 -310.51881)
		(width 0.18288)
		(layer "In6.Cu")
		(net "M_H_CPU1_SA_DQS_DN<5>")
	)
	(segment
		(start 186.868816 -311.369202)
		(end 186.744356 -311.493662)
		(width 0.18288)
		(layer "In6.Cu")
		(net "M_H_CPU1_SA_DQS_DN<5>")
	)
	(segment
		(start 148.661882 -292.882066)
		(end 148.661882 -283.27858)
		(width 0.18288)
		(layer "In6.Cu")
		(net "M_H_CPU1_SA_DQS_DN<5>")
	)
	(segment
		(start 129.84607 -277.221188)
		(end 129.836672 -277.226268)
		(width 0.088646)
		(layer "In6.Cu")
		(net "M_H_CPU1_SA_DQS_DN<5>")
	)
	(segment
		(start 194.755008 -311.158636)
		(end 193.876676 -311.158636)
		(width 0.18288)
		(layer "In6.Cu")
		(net "M_H_CPU1_SA_DQS_DN<5>")
	)
	(segment
		(start 187.414916 -311.369202)
		(end 186.868816 -311.369202)
		(width 0.18288)
		(layer "In6.Cu")
		(net "M_H_CPU1_SA_DQS_DN<5>")
	)
	(segment
		(start 156.944568 -304.59172)
		(end 156.530548 -304.1777)
		(width 0.18288)
		(layer "In6.Cu")
		(net "M_H_CPU1_SA_DQS_DN<5>")
	)
	(segment
		(start 130.2639 -277.198328)
		(end 130.264154 -277.19782)
		(width 0.088646)
		(layer "In6.Cu")
		(net "M_H_CPU1_SA_DQS_DN<5>")
	)
	(segment
		(start 188.762132 -311.365392)
		(end 188.335666 -311.365392)
		(width 0.18288)
		(layer "In6.Cu")
		(net "M_H_CPU1_SA_DQS_DN<5>")
	)
	(segment
		(start 129.196592 -277.313136)
		(end 129.136394 -277.373334)
		(width 0.088646)
		(layer "In6.Cu")
		(net "M_H_CPU1_SA_DQS_DN<5>")
	)
	(arc
		(start 134.962392 -277.198074)
		(mid 134.775194 -277.147931)
		(end 134.587996 -277.198074)
		(width 0.088646)
		(layer "In6.Cu")
		(net "M_H_CPU1_SA_DQS_DN<5>")
	)
	(arc
		(start 131.203446 -277.198074)
		(mid 131.016248 -277.147931)
		(end 130.82905 -277.198074)
		(width 0.088646)
		(layer "In6.Cu")
		(net "M_H_CPU1_SA_DQS_DN<5>")
	)
	(arc
		(start 131.758182 -277.20417)
		(mid 131.480004 -277.273893)
		(end 131.203446 -277.198074)
		(width 0.088646)
		(layer "In6.Cu")
		(net "M_H_CPU1_SA_DQS_DN<5>")
	)
	(arc
		(start 129.929128 -277.177754)
		(mid 129.909156 -277.186955)
		(end 129.889758 -277.197312)
		(width 0.088646)
		(layer "In6.Cu")
		(net "M_H_CPU1_SA_DQS_DN<5>")
	)
	(arc
		(start 138.251692 -278.012144)
		(mid 138.049406 -277.813163)
		(end 137.969244 -277.540974)
		(width 0.088646)
		(layer "In6.Cu")
		(net "M_H_CPU1_SA_DQS_DN<5>")
	)
	(arc
		(start 134.022592 -277.198074)
		(mid 133.835394 -277.147931)
		(end 133.648196 -277.198074)
		(width 0.088646)
		(layer "In6.Cu")
		(net "M_H_CPU1_SA_DQS_DN<5>")
	)
	(arc
		(start 130.82905 -277.198074)
		(mid 130.546521 -277.27385)
		(end 130.2639 -277.198328)
		(width 0.088646)
		(layer "In6.Cu")
		(net "M_H_CPU1_SA_DQS_DN<5>")
	)
	(arc
		(start 134.573264 -277.20671)
		(mid 134.296789 -277.27403)
		(end 134.022592 -277.198074)
		(width 0.088646)
		(layer "In6.Cu")
		(net "M_H_CPU1_SA_DQS_DN<5>")
	)
	(arc
		(start 132.142992 -277.198074)
		(mid 131.955794 -277.147931)
		(end 131.768596 -277.198074)
		(width 0.088646)
		(layer "In6.Cu")
		(net "M_H_CPU1_SA_DQS_DN<5>")
	)
	(arc
		(start 135.513064 -277.20671)
		(mid 135.236589 -277.27403)
		(end 134.962392 -277.198074)
		(width 0.088646)
		(layer "In6.Cu")
		(net "M_H_CPU1_SA_DQS_DN<5>")
	)
	(arc
		(start 137.781792 -277.198074)
		(mid 137.594594 -277.147931)
		(end 137.407396 -277.198074)
		(width 0.088646)
		(layer "In6.Cu")
		(net "M_H_CPU1_SA_DQS_DN<5>")
	)
	(arc
		(start 130.2639 -277.19782)
		(mid 130.262251 -277.196927)
		(end 130.260598 -277.196042)
		(width 0.088646)
		(layer "In6.Cu")
		(net "M_H_CPU1_SA_DQS_DN<5>")
	)
	(arc
		(start 136.457182 -277.20417)
		(mid 136.17875 -277.274016)
		(end 135.901938 -277.198074)
		(width 0.088646)
		(layer "In6.Cu")
		(net "M_H_CPU1_SA_DQS_DN<5>")
	)
	(arc
		(start 137.407396 -277.198074)
		(mid 137.124694 -277.27385)
		(end 136.841992 -277.198074)
		(width 0.088646)
		(layer "In6.Cu")
		(net "M_H_CPU1_SA_DQS_DN<5>")
	)
	(arc
		(start 136.841992 -277.198074)
		(mid 136.654794 -277.147931)
		(end 136.467596 -277.198074)
		(width 0.088646)
		(layer "In6.Cu")
		(net "M_H_CPU1_SA_DQS_DN<5>")
	)
	(arc
		(start 135.901938 -277.198074)
		(mid 135.719687 -277.147963)
		(end 135.536178 -277.193248)
		(width 0.088646)
		(layer "In6.Cu")
		(net "M_H_CPU1_SA_DQS_DN<5>")
	)
	(arc
		(start 132.708396 -277.198074)
		(mid 132.425694 -277.27385)
		(end 132.142992 -277.198074)
		(width 0.088646)
		(layer "In6.Cu")
		(net "M_H_CPU1_SA_DQS_DN<5>")
	)
	(arc
		(start 138.439144 -278.336502)
		(mid 138.391465 -278.153602)
		(end 138.260582 -278.017224)
		(width 0.088646)
		(layer "In6.Cu")
		(net "M_H_CPU1_SA_DQS_DN<5>")
	)
	(arc
		(start 133.633464 -277.20671)
		(mid 133.356989 -277.27403)
		(end 133.082792 -277.198074)
		(width 0.088646)
		(layer "In6.Cu")
		(net "M_H_CPU1_SA_DQS_DN<5>")
	)
	(arc
		(start 139.00404 -278.901906)
		(mid 138.611011 -278.742717)
		(end 138.439144 -278.355044)
		(width 0.088646)
		(layer "In6.Cu")
		(net "M_H_CPU1_SA_DQS_DN<5>")
	)
	(arc
		(start 130.18516 -277.160482)
		(mid 130.080249 -277.137264)
		(end 129.974848 -277.158196)
		(width 0.088646)
		(layer "In6.Cu")
		(net "M_H_CPU1_SA_DQS_DN<5>")
	)
	(arc
		(start 133.082792 -277.198074)
		(mid 132.895594 -277.147931)
		(end 132.708396 -277.198074)
		(width 0.088646)
		(layer "In6.Cu")
		(net "M_H_CPU1_SA_DQS_DN<5>")
	)
	(arc
		(start 137.969244 -277.522432)
		(mid 137.921565 -277.339532)
		(end 137.790682 -277.203154)
		(width 0.088646)
		(layer "In6.Cu")
		(net "M_H_CPU1_SA_DQS_DN<5>")
	)
	(segment
		(start 206.849726 -275.091652)
		(end 206.9973 -275.091652)
		(width 0.20066)
		(layer "F.Cu")
		(net "M_H_CPU1_SA_DQS_DN<4>")
	)
	(segment
		(start 209.51063 -275.086318)
		(end 209.742024 -275.317712)
		(width 0.20066)
		(layer "F.Cu")
		(net "M_H_CPU1_SA_DQS_DN<4>")
	)
	(segment
		(start 209.181192 -275.091652)
		(end 209.186526 -275.086318)
		(width 0.1016)
		(layer "F.Cu")
		(net "M_H_CPU1_SA_DQS_DN<4>")
	)
	(segment
		(start 207.001618 -275.091652)
		(end 209.181192 -275.091652)
		(width 0.1016)
		(layer "F.Cu")
		(net "M_H_CPU1_SA_DQS_DN<4>")
	)
	(segment
		(start 202.971146 -274.66671)
		(end 204.076046 -274.66671)
		(width 0.20066)
		(layer "F.Cu")
		(net "M_H_CPU1_SA_DQS_DN<4>")
	)
	(segment
		(start 204.076046 -274.66671)
		(end 204.624686 -274.66671)
		(width 0.20066)
		(layer "F.Cu")
		(net "M_H_CPU1_SA_DQS_DN<4>")
	)
	(segment
		(start 204.906372 -274.948396)
		(end 205.64221 -274.948396)
		(width 0.20066)
		(layer "F.Cu")
		(net "M_H_CPU1_SA_DQS_DN<4>")
	)
	(segment
		(start 210.790028 -274.907248)
		(end 211.030566 -274.66671)
		(width 0.20066)
		(layer "F.Cu")
		(net "M_H_CPU1_SA_DQS_DN<4>")
	)
	(segment
		(start 210.457542 -274.907248)
		(end 210.790028 -274.907248)
		(width 0.20066)
		(layer "F.Cu")
		(net "M_H_CPU1_SA_DQS_DN<4>")
	)
	(segment
		(start 204.624686 -274.66671)
		(end 204.906372 -274.948396)
		(width 0.20066)
		(layer "F.Cu")
		(net "M_H_CPU1_SA_DQS_DN<4>")
	)
	(segment
		(start 209.742024 -275.317712)
		(end 210.047078 -275.317712)
		(width 0.20066)
		(layer "F.Cu")
		(net "M_H_CPU1_SA_DQS_DN<4>")
	)
	(segment
		(start 206.9973 -275.091652)
		(end 207.001618 -275.091652)
		(width 0.101854)
		(layer "F.Cu")
		(net "M_H_CPU1_SA_DQS_DN<4>")
	)
	(segment
		(start 210.047078 -275.317712)
		(end 210.457542 -274.907248)
		(width 0.20066)
		(layer "F.Cu")
		(net "M_H_CPU1_SA_DQS_DN<4>")
	)
	(segment
		(start 123.967494 -259.894832)
		(end 123.967494 -260.430518)
		(width 0.20066)
		(layer "F.Cu")
		(net "M_H_CPU1_SA_DQS_DN<4>")
	)
	(segment
		(start 205.64221 -274.948396)
		(end 206.056738 -275.362924)
		(width 0.20066)
		(layer "F.Cu")
		(net "M_H_CPU1_SA_DQS_DN<4>")
	)
	(segment
		(start 206.578454 -275.362924)
		(end 206.849726 -275.091652)
		(width 0.20066)
		(layer "F.Cu")
		(net "M_H_CPU1_SA_DQS_DN<4>")
	)
	(segment
		(start 209.186526 -275.086318)
		(end 209.51063 -275.086318)
		(width 0.20066)
		(layer "F.Cu")
		(net "M_H_CPU1_SA_DQS_DN<4>")
	)
	(segment
		(start 211.030566 -274.66671)
		(end 211.619846 -274.66671)
		(width 0.20066)
		(layer "F.Cu")
		(net "M_H_CPU1_SA_DQS_DN<4>")
	)
	(segment
		(start 123.967494 -260.430518)
		(end 123.967748 -260.430772)
		(width 0.20066)
		(layer "F.Cu")
		(net "M_H_CPU1_SA_DQS_DN<4>")
	)
	(segment
		(start 206.056738 -275.362924)
		(end 206.578454 -275.362924)
		(width 0.20066)
		(layer "F.Cu")
		(net "M_H_CPU1_SA_DQS_DN<4>")
	)
	(segment
		(start 177.939446 -277.08606)
		(end 177.386742 -277.08606)
		(width 0.18288)
		(layer "In11.Cu")
		(net "M_H_CPU1_SA_DQS_DN<4>")
	)
	(segment
		(start 194.817492 -276.42947)
		(end 193.628264 -276.42947)
		(width 0.18288)
		(layer "In11.Cu")
		(net "M_H_CPU1_SA_DQS_DN<4>")
	)
	(segment
		(start 137.219944 -261.244842)
		(end 137.219944 -261.2263)
		(width 0.088646)
		(layer "In11.Cu")
		(net "M_H_CPU1_SA_DQS_DN<4>")
	)
	(segment
		(start 172.254164 -276.214586)
		(end 172.236892 -276.214586)
		(width 0.18288)
		(layer "In11.Cu")
		(net "M_H_CPU1_SA_DQS_DN<4>")
	)
	(segment
		(start 202.450446 -274.917408)
		(end 202.289156 -274.756118)
		(width 0.18288)
		(layer "In11.Cu")
		(net "M_H_CPU1_SA_DQS_DN<4>")
	)
	(segment
		(start 137.407396 -261.5692)
		(end 137.398506 -261.56412)
		(width 0.088646)
		(layer "In11.Cu")
		(net "M_H_CPU1_SA_DQS_DN<4>")
	)
	(segment
		(start 197.83552 -276.80412)
		(end 196.895212 -276.80412)
		(width 0.18288)
		(layer "In11.Cu")
		(net "M_H_CPU1_SA_DQS_DN<4>")
	)
	(segment
		(start 177.386742 -277.08606)
		(end 177.093118 -276.792436)
		(width 0.18288)
		(layer "In11.Cu")
		(net "M_H_CPU1_SA_DQS_DN<4>")
	)
	(segment
		(start 196.770752 -276.67966)
		(end 196.222112 -276.67966)
		(width 0.18288)
		(layer "In11.Cu")
		(net "M_H_CPU1_SA_DQS_DN<4>")
	)
	(segment
		(start 140.925804 -263.34085)
		(end 140.866114 -263.40054)
		(width 0.088646)
		(layer "In11.Cu")
		(net "M_H_CPU1_SA_DQS_DN<4>")
	)
	(segment
		(start 125.109478 -260.746494)
		(end 125.094746 -260.75513)
		(width 0.088646)
		(layer "In11.Cu")
		(net "M_H_CPU1_SA_DQS_DN<4>")
	)
	(segment
		(start 131.688078 -260.746494)
		(end 131.673346 -260.75513)
		(width 0.088646)
		(layer "In11.Cu")
		(net "M_H_CPU1_SA_DQS_DN<4>")
	)
	(segment
		(start 174.153576 -276.221952)
		(end 173.25975 -276.221952)
		(width 0.18288)
		(layer "In11.Cu")
		(net "M_H_CPU1_SA_DQS_DN<4>")
	)
	(segment
		(start 201.618596 -274.756118)
		(end 200.917302 -275.04644)
		(width 0.18288)
		(layer "In11.Cu")
		(net "M_H_CPU1_SA_DQS_DN<4>")
	)
	(segment
		(start 140.15212 -263.247632)
		(end 139.474194 -263.247632)
		(width 0.088646)
		(layer "In11.Cu")
		(net "M_H_CPU1_SA_DQS_DN<4>")
	)
	(segment
		(start 196.222112 -276.67966)
		(end 196.097652 -276.80412)
		(width 0.18288)
		(layer "In11.Cu")
		(net "M_H_CPU1_SA_DQS_DN<4>")
	)
	(segment
		(start 188.087762 -275.940774)
		(end 187.615322 -275.940774)
		(width 0.18288)
		(layer "In11.Cu")
		(net "M_H_CPU1_SA_DQS_DN<4>")
	)
	(segment
		(start 189.03696 -276.21611)
		(end 188.363098 -276.21611)
		(width 0.18288)
		(layer "In11.Cu")
		(net "M_H_CPU1_SA_DQS_DN<4>")
	)
	(segment
		(start 130.748278 -260.746494)
		(end 130.733546 -260.75513)
		(width 0.088646)
		(layer "In11.Cu")
		(net "M_H_CPU1_SA_DQS_DN<4>")
	)
	(segment
		(start 145.73504 -263.34085)
		(end 140.925804 -263.34085)
		(width 0.18288)
		(layer "In11.Cu")
		(net "M_H_CPU1_SA_DQS_DN<4>")
	)
	(segment
		(start 169.125392 -276.223222)
		(end 168.3639 -275.46173)
		(width 0.18288)
		(layer "In11.Cu")
		(net "M_H_CPU1_SA_DQS_DN<4>")
	)
	(segment
		(start 185.711084 -276.206458)
		(end 185.586624 -276.081998)
		(width 0.18288)
		(layer "In11.Cu")
		(net "M_H_CPU1_SA_DQS_DN<4>")
	)
	(segment
		(start 123.655074 -260.430772)
		(end 123.967748 -260.430772)
		(width 0.088646)
		(layer "In11.Cu")
		(net "M_H_CPU1_SA_DQS_DN<4>")
	)
	(segment
		(start 188.363098 -276.21611)
		(end 188.087762 -275.940774)
		(width 0.18288)
		(layer "In11.Cu")
		(net "M_H_CPU1_SA_DQS_DN<4>")
	)
	(segment
		(start 185.037984 -276.081998)
		(end 184.913524 -276.206458)
		(width 0.18288)
		(layer "In11.Cu")
		(net "M_H_CPU1_SA_DQS_DN<4>")
	)
	(segment
		(start 139.099544 -262.88492)
		(end 139.099798 -262.884666)
		(width 0.088646)
		(layer "In11.Cu")
		(net "M_H_CPU1_SA_DQS_DN<4>")
	)
	(segment
		(start 140.305028 -263.40054)
		(end 140.15212 -263.247632)
		(width 0.088646)
		(layer "In11.Cu")
		(net "M_H_CPU1_SA_DQS_DN<4>")
	)
	(segment
		(start 196.097652 -276.80412)
		(end 195.192142 -276.80412)
		(width 0.18288)
		(layer "In11.Cu")
		(net "M_H_CPU1_SA_DQS_DN<4>")
	)
	(segment
		(start 200.010268 -275.953474)
		(end 198.686166 -275.953474)
		(width 0.18288)
		(layer "In11.Cu")
		(net "M_H_CPU1_SA_DQS_DN<4>")
	)
	(segment
		(start 129.808478 -260.746494)
		(end 129.793746 -260.75513)
		(width 0.088646)
		(layer "In11.Cu")
		(net "M_H_CPU1_SA_DQS_DN<4>")
	)
	(segment
		(start 191.71539 -276.790658)
		(end 191.458342 -277.047706)
		(width 0.18288)
		(layer "In11.Cu")
		(net "M_H_CPU1_SA_DQS_DN<4>")
	)
	(segment
		(start 126.04496 -260.749034)
		(end 126.034546 -260.75513)
		(width 0.088646)
		(layer "In11.Cu")
		(net "M_H_CPU1_SA_DQS_DN<4>")
	)
	(segment
		(start 172.978826 -275.941028)
		(end 172.527722 -275.941028)
		(width 0.18288)
		(layer "In11.Cu")
		(net "M_H_CPU1_SA_DQS_DN<4>")
	)
	(segment
		(start 178.67122 -276.354286)
		(end 177.939446 -277.08606)
		(width 0.18288)
		(layer "In11.Cu")
		(net "M_H_CPU1_SA_DQS_DN<4>")
	)
	(segment
		(start 127.928878 -260.746494)
		(end 127.914146 -260.75513)
		(width 0.088646)
		(layer "In11.Cu")
		(net "M_H_CPU1_SA_DQS_DN<4>")
	)
	(segment
		(start 172.228256 -276.223222)
		(end 169.125392 -276.223222)
		(width 0.18288)
		(layer "In11.Cu")
		(net "M_H_CPU1_SA_DQS_DN<4>")
	)
	(segment
		(start 164.701982 -275.46173)
		(end 164.204142 -275.95957)
		(width 0.18288)
		(layer "In11.Cu")
		(net "M_H_CPU1_SA_DQS_DN<4>")
	)
	(segment
		(start 179.9463 -275.541486)
		(end 179.1335 -276.354286)
		(width 0.18288)
		(layer "In11.Cu")
		(net "M_H_CPU1_SA_DQS_DN<4>")
	)
	(segment
		(start 132.62356 -260.749034)
		(end 132.613146 -260.75513)
		(width 0.088646)
		(layer "In11.Cu")
		(net "M_H_CPU1_SA_DQS_DN<4>")
	)
	(segment
		(start 192.450974 -277.065486)
		(end 192.176146 -276.790658)
		(width 0.18288)
		(layer "In11.Cu")
		(net "M_H_CPU1_SA_DQS_DN<4>")
	)
	(segment
		(start 187.615322 -275.940774)
		(end 187.349638 -276.206458)
		(width 0.18288)
		(layer "In11.Cu")
		(net "M_H_CPU1_SA_DQS_DN<4>")
	)
	(segment
		(start 139.099798 -262.872474)
		(end 139.099798 -262.850376)
		(width 0.088646)
		(layer "In11.Cu")
		(net "M_H_CPU1_SA_DQS_DN<4>")
	)
	(segment
		(start 187.349638 -276.206458)
		(end 185.711084 -276.206458)
		(width 0.18288)
		(layer "In11.Cu")
		(net "M_H_CPU1_SA_DQS_DN<4>")
	)
	(segment
		(start 123.59767 -260.488176)
		(end 123.655074 -260.430772)
		(width 0.088646)
		(layer "In11.Cu")
		(net "M_H_CPU1_SA_DQS_DN<4>")
	)
	(segment
		(start 124.169678 -260.746494)
		(end 124.154946 -260.75513)
		(width 0.088646)
		(layer "In11.Cu")
		(net "M_H_CPU1_SA_DQS_DN<4>")
	)
	(segment
		(start 182.63235 -275.541486)
		(end 179.9463 -275.541486)
		(width 0.18288)
		(layer "In11.Cu")
		(net "M_H_CPU1_SA_DQS_DN<4>")
	)
	(segment
		(start 191.458342 -277.047706)
		(end 189.868556 -277.047706)
		(width 0.18288)
		(layer "In11.Cu")
		(net "M_H_CPU1_SA_DQS_DN<4>")
	)
	(segment
		(start 133.563106 -260.749034)
		(end 133.552692 -260.75513)
		(width 0.088646)
		(layer "In11.Cu")
		(net "M_H_CPU1_SA_DQS_DN<4>")
	)
	(segment
		(start 202.971146 -274.66671)
		(end 202.720448 -274.917408)
		(width 0.18288)
		(layer "In11.Cu")
		(net "M_H_CPU1_SA_DQS_DN<4>")
	)
	(segment
		(start 174.679102 -276.747478)
		(end 174.153576 -276.221952)
		(width 0.18288)
		(layer "In11.Cu")
		(net "M_H_CPU1_SA_DQS_DN<4>")
	)
	(segment
		(start 134.50316 -260.749034)
		(end 134.492746 -260.75513)
		(width 0.088646)
		(layer "In11.Cu")
		(net "M_H_CPU1_SA_DQS_DN<4>")
	)
	(segment
		(start 184.913524 -276.206458)
		(end 184.146952 -276.206458)
		(width 0.18288)
		(layer "In11.Cu")
		(net "M_H_CPU1_SA_DQS_DN<4>")
	)
	(segment
		(start 192.176146 -276.790658)
		(end 191.71539 -276.790658)
		(width 0.18288)
		(layer "In11.Cu")
		(net "M_H_CPU1_SA_DQS_DN<4>")
	)
	(segment
		(start 189.868556 -277.047706)
		(end 189.03696 -276.21611)
		(width 0.18288)
		(layer "In11.Cu")
		(net "M_H_CPU1_SA_DQS_DN<4>")
	)
	(segment
		(start 177.093118 -276.792436)
		(end 176.611788 -276.792436)
		(width 0.18288)
		(layer "In11.Cu")
		(net "M_H_CPU1_SA_DQS_DN<4>")
	)
	(segment
		(start 184.146952 -276.206458)
		(end 182.63235 -275.541486)
		(width 0.18288)
		(layer "In11.Cu")
		(net "M_H_CPU1_SA_DQS_DN<4>")
	)
	(segment
		(start 179.1335 -276.354286)
		(end 178.67122 -276.354286)
		(width 0.18288)
		(layer "In11.Cu")
		(net "M_H_CPU1_SA_DQS_DN<4>")
	)
	(segment
		(start 195.192142 -276.80412)
		(end 194.817492 -276.42947)
		(width 0.18288)
		(layer "In11.Cu")
		(net "M_H_CPU1_SA_DQS_DN<4>")
	)
	(segment
		(start 164.204142 -275.95957)
		(end 163.79825 -275.95957)
		(width 0.18288)
		(layer "In11.Cu")
		(net "M_H_CPU1_SA_DQS_DN<4>")
	)
	(segment
		(start 162.955478 -275.116544)
		(end 160.885378 -274.258786)
		(width 0.18288)
		(layer "In11.Cu")
		(net "M_H_CPU1_SA_DQS_DN<4>")
	)
	(segment
		(start 173.25975 -276.221952)
		(end 172.978826 -275.941028)
		(width 0.18288)
		(layer "In11.Cu")
		(net "M_H_CPU1_SA_DQS_DN<4>")
	)
	(segment
		(start 176.611788 -276.792436)
		(end 176.315878 -277.088346)
		(width 0.18288)
		(layer "In11.Cu")
		(net "M_H_CPU1_SA_DQS_DN<4>")
	)
	(segment
		(start 200.917302 -275.04644)
		(end 200.010268 -275.953474)
		(width 0.18288)
		(layer "In11.Cu")
		(net "M_H_CPU1_SA_DQS_DN<4>")
	)
	(segment
		(start 193.628264 -276.42947)
		(end 192.992248 -277.065486)
		(width 0.18288)
		(layer "In11.Cu")
		(net "M_H_CPU1_SA_DQS_DN<4>")
	)
	(segment
		(start 198.686166 -275.953474)
		(end 197.83552 -276.80412)
		(width 0.18288)
		(layer "In11.Cu")
		(net "M_H_CPU1_SA_DQS_DN<4>")
	)
	(segment
		(start 140.866114 -263.40054)
		(end 140.305028 -263.40054)
		(width 0.088646)
		(layer "In11.Cu")
		(net "M_H_CPU1_SA_DQS_DN<4>")
	)
	(segment
		(start 192.992248 -277.065486)
		(end 192.450974 -277.065486)
		(width 0.18288)
		(layer "In11.Cu")
		(net "M_H_CPU1_SA_DQS_DN<4>")
	)
	(segment
		(start 172.527722 -275.941028)
		(end 172.254164 -276.214586)
		(width 0.18288)
		(layer "In11.Cu")
		(net "M_H_CPU1_SA_DQS_DN<4>")
	)
	(segment
		(start 126.984506 -260.749034)
		(end 126.9746 -260.75513)
		(width 0.088646)
		(layer "In11.Cu")
		(net "M_H_CPU1_SA_DQS_DN<4>")
	)
	(segment
		(start 168.3639 -275.46173)
		(end 164.701982 -275.46173)
		(width 0.18288)
		(layer "In11.Cu")
		(net "M_H_CPU1_SA_DQS_DN<4>")
	)
	(segment
		(start 172.236892 -276.214586)
		(end 172.228256 -276.223222)
		(width 0.18288)
		(layer "In11.Cu")
		(net "M_H_CPU1_SA_DQS_DN<4>")
	)
	(segment
		(start 128.868678 -260.746494)
		(end 128.853946 -260.75513)
		(width 0.088646)
		(layer "In11.Cu")
		(net "M_H_CPU1_SA_DQS_DN<4>")
	)
	(segment
		(start 202.720448 -274.917408)
		(end 202.450446 -274.917408)
		(width 0.18288)
		(layer "In11.Cu")
		(net "M_H_CPU1_SA_DQS_DN<4>")
	)
	(segment
		(start 138.26236 -262.376666)
		(end 138.251946 -262.382762)
		(width 0.088646)
		(layer "In11.Cu")
		(net "M_H_CPU1_SA_DQS_DN<4>")
	)
	(segment
		(start 176.315878 -277.088346)
		(end 176.03724 -277.088346)
		(width 0.18288)
		(layer "In11.Cu")
		(net "M_H_CPU1_SA_DQS_DN<4>")
	)
	(segment
		(start 160.885378 -274.258786)
		(end 156.652976 -274.258786)
		(width 0.18288)
		(layer "In11.Cu")
		(net "M_H_CPU1_SA_DQS_DN<4>")
	)
	(segment
		(start 156.652976 -274.258786)
		(end 145.73504 -263.34085)
		(width 0.18288)
		(layer "In11.Cu")
		(net "M_H_CPU1_SA_DQS_DN<4>")
	)
	(segment
		(start 137.689844 -262.058658)
		(end 137.689844 -262.048752)
		(width 0.088646)
		(layer "In11.Cu")
		(net "M_H_CPU1_SA_DQS_DN<4>")
	)
	(segment
		(start 185.586624 -276.081998)
		(end 185.037984 -276.081998)
		(width 0.18288)
		(layer "In11.Cu")
		(net "M_H_CPU1_SA_DQS_DN<4>")
	)
	(segment
		(start 163.79825 -275.95957)
		(end 162.955478 -275.116544)
		(width 0.18288)
		(layer "In11.Cu")
		(net "M_H_CPU1_SA_DQS_DN<4>")
	)
	(segment
		(start 202.289156 -274.756118)
		(end 201.618596 -274.756118)
		(width 0.18288)
		(layer "In11.Cu")
		(net "M_H_CPU1_SA_DQS_DN<4>")
	)
	(segment
		(start 176.03724 -277.088346)
		(end 174.679102 -276.747478)
		(width 0.18288)
		(layer "In11.Cu")
		(net "M_H_CPU1_SA_DQS_DN<4>")
	)
	(segment
		(start 196.895212 -276.80412)
		(end 196.770752 -276.67966)
		(width 0.18288)
		(layer "In11.Cu")
		(net "M_H_CPU1_SA_DQS_DN<4>")
	)
	(arc
		(start 139.474194 -263.247632)
		(mid 139.213518 -263.142027)
		(end 139.099544 -262.88492)
		(width 0.088646)
		(layer "In11.Cu")
		(net "M_H_CPU1_SA_DQS_DN<4>")
	)
	(arc
		(start 131.29895 -260.75513)
		(mid 131.024721 -260.679205)
		(end 130.748278 -260.746494)
		(width 0.088646)
		(layer "In11.Cu")
		(net "M_H_CPU1_SA_DQS_DN<4>")
	)
	(arc
		(start 130.733546 -260.75513)
		(mid 130.546348 -260.805273)
		(end 130.35915 -260.75513)
		(width 0.088646)
		(layer "In11.Cu")
		(net "M_H_CPU1_SA_DQS_DN<4>")
	)
	(arc
		(start 128.47955 -260.75513)
		(mid 128.205321 -260.679205)
		(end 127.928878 -260.746494)
		(width 0.088646)
		(layer "In11.Cu")
		(net "M_H_CPU1_SA_DQS_DN<4>")
	)
	(arc
		(start 124.154946 -260.75513)
		(mid 123.805954 -260.76852)
		(end 123.59767 -260.488176)
		(width 0.088646)
		(layer "In11.Cu")
		(net "M_H_CPU1_SA_DQS_DN<4>")
	)
	(arc
		(start 133.552692 -260.75513)
		(mid 133.365494 -260.805273)
		(end 133.178296 -260.75513)
		(width 0.088646)
		(layer "In11.Cu")
		(net "M_H_CPU1_SA_DQS_DN<4>")
	)
	(arc
		(start 134.11835 -260.75513)
		(mid 133.841537 -260.679294)
		(end 133.563106 -260.749034)
		(width 0.088646)
		(layer "In11.Cu")
		(net "M_H_CPU1_SA_DQS_DN<4>")
	)
	(arc
		(start 129.41935 -260.75513)
		(mid 129.145121 -260.679205)
		(end 128.868678 -260.746494)
		(width 0.088646)
		(layer "In11.Cu")
		(net "M_H_CPU1_SA_DQS_DN<4>")
	)
	(arc
		(start 125.66015 -260.75513)
		(mid 125.385921 -260.679205)
		(end 125.109478 -260.746494)
		(width 0.088646)
		(layer "In11.Cu")
		(net "M_H_CPU1_SA_DQS_DN<4>")
	)
	(arc
		(start 129.793746 -260.75513)
		(mid 129.606548 -260.805273)
		(end 129.41935 -260.75513)
		(width 0.088646)
		(layer "In11.Cu")
		(net "M_H_CPU1_SA_DQS_DN<4>")
	)
	(arc
		(start 127.914146 -260.75513)
		(mid 127.726948 -260.805273)
		(end 127.53975 -260.75513)
		(width 0.088646)
		(layer "In11.Cu")
		(net "M_H_CPU1_SA_DQS_DN<4>")
	)
	(arc
		(start 127.53975 -260.75513)
		(mid 127.262937 -260.679294)
		(end 126.984506 -260.749034)
		(width 0.088646)
		(layer "In11.Cu")
		(net "M_H_CPU1_SA_DQS_DN<4>")
	)
	(arc
		(start 138.251946 -262.382762)
		(mid 137.877191 -262.383142)
		(end 137.689844 -262.058658)
		(width 0.088646)
		(layer "In11.Cu")
		(net "M_H_CPU1_SA_DQS_DN<4>")
	)
	(arc
		(start 135.997696 -260.75513)
		(mid 135.714994 -260.679388)
		(end 135.432292 -260.75513)
		(width 0.088646)
		(layer "In11.Cu")
		(net "M_H_CPU1_SA_DQS_DN<4>")
	)
	(arc
		(start 131.673346 -260.75513)
		(mid 131.486148 -260.805273)
		(end 131.29895 -260.75513)
		(width 0.088646)
		(layer "In11.Cu")
		(net "M_H_CPU1_SA_DQS_DN<4>")
	)
	(arc
		(start 135.432292 -260.75513)
		(mid 135.245094 -260.805273)
		(end 135.057896 -260.75513)
		(width 0.088646)
		(layer "In11.Cu")
		(net "M_H_CPU1_SA_DQS_DN<4>")
	)
	(arc
		(start 137.219944 -261.2263)
		(mid 136.929466 -260.750581)
		(end 136.372092 -260.75513)
		(width 0.088646)
		(layer "In11.Cu")
		(net "M_H_CPU1_SA_DQS_DN<4>")
	)
	(arc
		(start 136.372092 -260.75513)
		(mid 136.184894 -260.805273)
		(end 135.997696 -260.75513)
		(width 0.088646)
		(layer "In11.Cu")
		(net "M_H_CPU1_SA_DQS_DN<4>")
	)
	(arc
		(start 125.094746 -260.75513)
		(mid 124.907548 -260.805273)
		(end 124.72035 -260.75513)
		(width 0.088646)
		(layer "In11.Cu")
		(net "M_H_CPU1_SA_DQS_DN<4>")
	)
	(arc
		(start 124.72035 -260.75513)
		(mid 124.446121 -260.679205)
		(end 124.169678 -260.746494)
		(width 0.088646)
		(layer "In11.Cu")
		(net "M_H_CPU1_SA_DQS_DN<4>")
	)
	(arc
		(start 132.23875 -260.75513)
		(mid 131.964521 -260.679205)
		(end 131.688078 -260.746494)
		(width 0.088646)
		(layer "In11.Cu")
		(net "M_H_CPU1_SA_DQS_DN<4>")
	)
	(arc
		(start 128.853946 -260.75513)
		(mid 128.666748 -260.805273)
		(end 128.47955 -260.75513)
		(width 0.088646)
		(layer "In11.Cu")
		(net "M_H_CPU1_SA_DQS_DN<4>")
	)
	(arc
		(start 126.034546 -260.75513)
		(mid 125.847348 -260.805273)
		(end 125.66015 -260.75513)
		(width 0.088646)
		(layer "In11.Cu")
		(net "M_H_CPU1_SA_DQS_DN<4>")
	)
	(arc
		(start 130.35915 -260.75513)
		(mid 130.084921 -260.679205)
		(end 129.808478 -260.746494)
		(width 0.088646)
		(layer "In11.Cu")
		(net "M_H_CPU1_SA_DQS_DN<4>")
	)
	(arc
		(start 133.178296 -260.75513)
		(mid 132.901737 -260.679421)
		(end 132.62356 -260.749034)
		(width 0.088646)
		(layer "In11.Cu")
		(net "M_H_CPU1_SA_DQS_DN<4>")
	)
	(arc
		(start 137.398506 -261.56412)
		(mid 137.267592 -261.42776)
		(end 137.219944 -261.244842)
		(width 0.088646)
		(layer "In11.Cu")
		(net "M_H_CPU1_SA_DQS_DN<4>")
	)
	(arc
		(start 139.099798 -262.850376)
		(mid 138.813094 -262.380183)
		(end 138.26236 -262.376666)
		(width 0.088646)
		(layer "In11.Cu")
		(net "M_H_CPU1_SA_DQS_DN<4>")
	)
	(arc
		(start 126.9746 -260.75513)
		(mid 126.787148 -260.8054)
		(end 126.599696 -260.75513)
		(width 0.088646)
		(layer "In11.Cu")
		(net "M_H_CPU1_SA_DQS_DN<4>")
	)
	(arc
		(start 137.689844 -262.048752)
		(mid 137.611733 -261.771803)
		(end 137.407396 -261.5692)
		(width 0.088646)
		(layer "In11.Cu")
		(net "M_H_CPU1_SA_DQS_DN<4>")
	)
	(arc
		(start 135.057896 -260.75513)
		(mid 134.781337 -260.679421)
		(end 134.50316 -260.749034)
		(width 0.088646)
		(layer "In11.Cu")
		(net "M_H_CPU1_SA_DQS_DN<4>")
	)
	(arc
		(start 139.099798 -262.884666)
		(mid 139.099748 -262.87857)
		(end 139.099798 -262.872474)
		(width 0.088646)
		(layer "In11.Cu")
		(net "M_H_CPU1_SA_DQS_DN<4>")
	)
	(arc
		(start 132.613146 -260.75513)
		(mid 132.425948 -260.805273)
		(end 132.23875 -260.75513)
		(width 0.088646)
		(layer "In11.Cu")
		(net "M_H_CPU1_SA_DQS_DN<4>")
	)
	(arc
		(start 134.492746 -260.75513)
		(mid 134.305548 -260.805273)
		(end 134.11835 -260.75513)
		(width 0.088646)
		(layer "In11.Cu")
		(net "M_H_CPU1_SA_DQS_DN<4>")
	)
	(arc
		(start 126.599696 -260.75513)
		(mid 126.323137 -260.679421)
		(end 126.04496 -260.749034)
		(width 0.088646)
		(layer "In11.Cu")
		(net "M_H_CPU1_SA_DQS_DN<4>")
	)
	(segment
		(start 123.967494 -265.313922)
		(end 123.967748 -265.314176)
		(width 0.20066)
		(layer "F.Cu")
		(net "M_H_CPU1_SA_DQS_DN<3>")
	)
	(segment
		(start 211.030566 -284.016704)
		(end 211.619846 -284.016704)
		(width 0.20066)
		(layer "F.Cu")
		(net "M_H_CPU1_SA_DQS_DN<3>")
	)
	(segment
		(start 209.186526 -284.436312)
		(end 209.51063 -284.436312)
		(width 0.20066)
		(layer "F.Cu")
		(net "M_H_CPU1_SA_DQS_DN<3>")
	)
	(segment
		(start 206.056738 -284.712918)
		(end 206.578454 -284.712918)
		(width 0.20066)
		(layer "F.Cu")
		(net "M_H_CPU1_SA_DQS_DN<3>")
	)
	(segment
		(start 123.967494 -264.778236)
		(end 123.967494 -265.313922)
		(width 0.20066)
		(layer "F.Cu")
		(net "M_H_CPU1_SA_DQS_DN<3>")
	)
	(segment
		(start 209.181192 -284.441646)
		(end 209.186526 -284.436312)
		(width 0.1016)
		(layer "F.Cu")
		(net "M_H_CPU1_SA_DQS_DN<3>")
	)
	(segment
		(start 206.9973 -284.441646)
		(end 207.001618 -284.441646)
		(width 0.101854)
		(layer "F.Cu")
		(net "M_H_CPU1_SA_DQS_DN<3>")
	)
	(segment
		(start 204.624686 -284.016704)
		(end 204.906372 -284.29839)
		(width 0.20066)
		(layer "F.Cu")
		(net "M_H_CPU1_SA_DQS_DN<3>")
	)
	(segment
		(start 210.047078 -284.667706)
		(end 210.457542 -284.257242)
		(width 0.20066)
		(layer "F.Cu")
		(net "M_H_CPU1_SA_DQS_DN<3>")
	)
	(segment
		(start 205.64221 -284.29839)
		(end 206.056738 -284.712918)
		(width 0.20066)
		(layer "F.Cu")
		(net "M_H_CPU1_SA_DQS_DN<3>")
	)
	(segment
		(start 206.849726 -284.441646)
		(end 206.9973 -284.441646)
		(width 0.20066)
		(layer "F.Cu")
		(net "M_H_CPU1_SA_DQS_DN<3>")
	)
	(segment
		(start 210.457542 -284.257242)
		(end 210.790028 -284.257242)
		(width 0.20066)
		(layer "F.Cu")
		(net "M_H_CPU1_SA_DQS_DN<3>")
	)
	(segment
		(start 207.001618 -284.441646)
		(end 209.181192 -284.441646)
		(width 0.1016)
		(layer "F.Cu")
		(net "M_H_CPU1_SA_DQS_DN<3>")
	)
	(segment
		(start 209.51063 -284.436312)
		(end 209.742024 -284.667706)
		(width 0.20066)
		(layer "F.Cu")
		(net "M_H_CPU1_SA_DQS_DN<3>")
	)
	(segment
		(start 206.578454 -284.712918)
		(end 206.849726 -284.441646)
		(width 0.20066)
		(layer "F.Cu")
		(net "M_H_CPU1_SA_DQS_DN<3>")
	)
	(segment
		(start 204.906372 -284.29839)
		(end 205.64221 -284.29839)
		(width 0.20066)
		(layer "F.Cu")
		(net "M_H_CPU1_SA_DQS_DN<3>")
	)
	(segment
		(start 210.790028 -284.257242)
		(end 211.030566 -284.016704)
		(width 0.20066)
		(layer "F.Cu")
		(net "M_H_CPU1_SA_DQS_DN<3>")
	)
	(segment
		(start 204.076046 -284.016704)
		(end 204.624686 -284.016704)
		(width 0.20066)
		(layer "F.Cu")
		(net "M_H_CPU1_SA_DQS_DN<3>")
	)
	(segment
		(start 202.971146 -284.016704)
		(end 204.076046 -284.016704)
		(width 0.20066)
		(layer "F.Cu")
		(net "M_H_CPU1_SA_DQS_DN<3>")
	)
	(segment
		(start 209.742024 -284.667706)
		(end 210.047078 -284.667706)
		(width 0.20066)
		(layer "F.Cu")
		(net "M_H_CPU1_SA_DQS_DN<3>")
	)
	(segment
		(start 196.03593 -286.357568)
		(end 194.777106 -286.878776)
		(width 0.18288)
		(layer "In11.Cu")
		(net "M_H_CPU1_SA_DQS_DN<3>")
	)
	(segment
		(start 140.050012 -269.277084)
		(end 139.482068 -269.277084)
		(width 0.088646)
		(layer "In11.Cu")
		(net "M_H_CPU1_SA_DQS_DN<3>")
	)
	(segment
		(start 180.133498 -286.65551)
		(end 178.586384 -287.296352)
		(width 0.18288)
		(layer "In11.Cu")
		(net "M_H_CPU1_SA_DQS_DN<3>")
	)
	(segment
		(start 172.525944 -288.69259)
		(end 172.270674 -288.94786)
		(width 0.18288)
		(layer "In11.Cu")
		(net "M_H_CPU1_SA_DQS_DN<3>")
	)
	(segment
		(start 202.971146 -284.016704)
		(end 202.68565 -284.3022)
		(width 0.18288)
		(layer "In11.Cu")
		(net "M_H_CPU1_SA_DQS_DN<3>")
	)
	(segment
		(start 171.526708 -288.94786)
		(end 170.783504 -288.204656)
		(width 0.18288)
		(layer "In11.Cu")
		(net "M_H_CPU1_SA_DQS_DN<3>")
	)
	(segment
		(start 188.355986 -287.257998)
		(end 188.090556 -286.992568)
		(width 0.18288)
		(layer "In11.Cu")
		(net "M_H_CPU1_SA_DQS_DN<3>")
	)
	(segment
		(start 132.62356 -265.632438)
		(end 132.613146 -265.638534)
		(width 0.088646)
		(layer "In11.Cu")
		(net "M_H_CPU1_SA_DQS_DN<3>")
	)
	(segment
		(start 134.128256 -267.27277)
		(end 134.11835 -267.266166)
		(width 0.088646)
		(layer "In11.Cu")
		(net "M_H_CPU1_SA_DQS_DN<3>")
	)
	(segment
		(start 135.44296 -268.887956)
		(end 135.432546 -268.894052)
		(width 0.088646)
		(layer "In11.Cu")
		(net "M_H_CPU1_SA_DQS_DN<3>")
	)
	(segment
		(start 191.71539 -287.840674)
		(end 191.421004 -288.13506)
		(width 0.18288)
		(layer "In11.Cu")
		(net "M_H_CPU1_SA_DQS_DN<3>")
	)
	(segment
		(start 160.268412 -284.235398)
		(end 159.74187 -283.708856)
		(width 0.18288)
		(layer "In11.Cu")
		(net "M_H_CPU1_SA_DQS_DN<3>")
	)
	(segment
		(start 176.592992 -287.842452)
		(end 176.337722 -288.097722)
		(width 0.18288)
		(layer "In11.Cu")
		(net "M_H_CPU1_SA_DQS_DN<3>")
	)
	(segment
		(start 159.74187 -283.708856)
		(end 157.30093 -283.708856)
		(width 0.18288)
		(layer "In11.Cu")
		(net "M_H_CPU1_SA_DQS_DN<3>")
	)
	(segment
		(start 162.658806 -285.81604)
		(end 161.849054 -285.81604)
		(width 0.18288)
		(layer "In11.Cu")
		(net "M_H_CPU1_SA_DQS_DN<3>")
	)
	(segment
		(start 176.337722 -288.097722)
		(end 175.512476 -288.097722)
		(width 0.18288)
		(layer "In11.Cu")
		(net "M_H_CPU1_SA_DQS_DN<3>")
	)
	(segment
		(start 143.030194 -269.43812)
		(end 140.696188 -269.43812)
		(width 0.18288)
		(layer "In11.Cu")
		(net "M_H_CPU1_SA_DQS_DN<3>")
	)
	(segment
		(start 177.759614 -288.123376)
		(end 177.430684 -288.123376)
		(width 0.18288)
		(layer "In11.Cu")
		(net "M_H_CPU1_SA_DQS_DN<3>")
	)
	(segment
		(start 177.430684 -288.123376)
		(end 177.14976 -287.842452)
		(width 0.18288)
		(layer "In11.Cu")
		(net "M_H_CPU1_SA_DQS_DN<3>")
	)
	(segment
		(start 189.238382 -287.257998)
		(end 188.355986 -287.257998)
		(width 0.18288)
		(layer "In11.Cu")
		(net "M_H_CPU1_SA_DQS_DN<3>")
	)
	(segment
		(start 160.832546 -284.62351)
		(end 160.444434 -284.235398)
		(width 0.18288)
		(layer "In11.Cu")
		(net "M_H_CPU1_SA_DQS_DN<3>")
	)
	(segment
		(start 134.11835 -267.266166)
		(end 134.10946 -267.261086)
		(width 0.088646)
		(layer "In11.Cu")
		(net "M_H_CPU1_SA_DQS_DN<3>")
	)
	(segment
		(start 174.229014 -288.804096)
		(end 173.837346 -288.966148)
		(width 0.18288)
		(layer "In11.Cu")
		(net "M_H_CPU1_SA_DQS_DN<3>")
	)
	(segment
		(start 139.482068 -269.277084)
		(end 139.286234 -269.08125)
		(width 0.088646)
		(layer "In11.Cu")
		(net "M_H_CPU1_SA_DQS_DN<3>")
	)
	(segment
		(start 191.421004 -288.13506)
		(end 191.146176 -288.13506)
		(width 0.18288)
		(layer "In11.Cu")
		(net "M_H_CPU1_SA_DQS_DN<3>")
	)
	(segment
		(start 128.868678 -265.629898)
		(end 128.853946 -265.638534)
		(width 0.088646)
		(layer "In11.Cu")
		(net "M_H_CPU1_SA_DQS_DN<3>")
	)
	(segment
		(start 134.400036 -267.734288)
		(end 134.400036 -267.73378)
		(width 0.088646)
		(layer "In11.Cu")
		(net "M_H_CPU1_SA_DQS_DN<3>")
	)
	(segment
		(start 177.14976 -287.842452)
		(end 176.592992 -287.842452)
		(width 0.18288)
		(layer "In11.Cu")
		(net "M_H_CPU1_SA_DQS_DN<3>")
	)
	(segment
		(start 123.59767 -265.371326)
		(end 123.65482 -265.314176)
		(width 0.088646)
		(layer "In11.Cu")
		(net "M_H_CPU1_SA_DQS_DN<3>")
	)
	(segment
		(start 190.860426 -287.84931)
		(end 189.829694 -287.84931)
		(width 0.18288)
		(layer "In11.Cu")
		(net "M_H_CPU1_SA_DQS_DN<3>")
	)
	(segment
		(start 168.038018 -286.36976)
		(end 166.556436 -286.36976)
		(width 0.18288)
		(layer "In11.Cu")
		(net "M_H_CPU1_SA_DQS_DN<3>")
	)
	(segment
		(start 187.330334 -287.275778)
		(end 187.325508 -287.275778)
		(width 0.18288)
		(layer "In11.Cu")
		(net "M_H_CPU1_SA_DQS_DN<3>")
	)
	(segment
		(start 163.331906 -285.69158)
		(end 162.783266 -285.69158)
		(width 0.18288)
		(layer "In11.Cu")
		(net "M_H_CPU1_SA_DQS_DN<3>")
	)
	(segment
		(start 174.526956 -288.505646)
		(end 174.229014 -288.804096)
		(width 0.18288)
		(layer "In11.Cu")
		(net "M_H_CPU1_SA_DQS_DN<3>")
	)
	(segment
		(start 138.838178 -268.906498)
		(end 138.798554 -268.883638)
		(width 0.088646)
		(layer "In11.Cu")
		(net "M_H_CPU1_SA_DQS_DN<3>")
	)
	(segment
		(start 163.456366 -285.81604)
		(end 163.331906 -285.69158)
		(width 0.18288)
		(layer "In11.Cu")
		(net "M_H_CPU1_SA_DQS_DN<3>")
	)
	(segment
		(start 127.928878 -265.629898)
		(end 127.914146 -265.638534)
		(width 0.088646)
		(layer "In11.Cu")
		(net "M_H_CPU1_SA_DQS_DN<3>")
	)
	(segment
		(start 187.325508 -287.275778)
		(end 187.314586 -287.2867)
		(width 0.18288)
		(layer "In11.Cu")
		(net "M_H_CPU1_SA_DQS_DN<3>")
	)
	(segment
		(start 193.054224 -288.120074)
		(end 192.474342 -288.120074)
		(width 0.18288)
		(layer "In11.Cu")
		(net "M_H_CPU1_SA_DQS_DN<3>")
	)
	(segment
		(start 182.968138 -286.65551)
		(end 180.133498 -286.65551)
		(width 0.18288)
		(layer "In11.Cu")
		(net "M_H_CPU1_SA_DQS_DN<3>")
	)
	(segment
		(start 131.688078 -265.629898)
		(end 131.673346 -265.638534)
		(width 0.088646)
		(layer "In11.Cu")
		(net "M_H_CPU1_SA_DQS_DN<3>")
	)
	(segment
		(start 173.260258 -288.966148)
		(end 172.9867 -288.69259)
		(width 0.18288)
		(layer "In11.Cu")
		(net "M_H_CPU1_SA_DQS_DN<3>")
	)
	(segment
		(start 134.870444 -268.58214)
		(end 134.870444 -268.569694)
		(width 0.088646)
		(layer "In11.Cu")
		(net "M_H_CPU1_SA_DQS_DN<3>")
	)
	(segment
		(start 194.321176 -287.334706)
		(end 193.49847 -287.675574)
		(width 0.18288)
		(layer "In11.Cu")
		(net "M_H_CPU1_SA_DQS_DN<3>")
	)
	(segment
		(start 126.04496 -265.632438)
		(end 126.034546 -265.638534)
		(width 0.088646)
		(layer "In11.Cu")
		(net "M_H_CPU1_SA_DQS_DN<3>")
	)
	(segment
		(start 164.355272 -285.81604)
		(end 163.456366 -285.81604)
		(width 0.18288)
		(layer "In11.Cu")
		(net "M_H_CPU1_SA_DQS_DN<3>")
	)
	(segment
		(start 140.270738 -269.49781)
		(end 140.050012 -269.277084)
		(width 0.088646)
		(layer "In11.Cu")
		(net "M_H_CPU1_SA_DQS_DN<3>")
	)
	(segment
		(start 187.613544 -286.992568)
		(end 187.330334 -287.275778)
		(width 0.18288)
		(layer "In11.Cu")
		(net "M_H_CPU1_SA_DQS_DN<3>")
	)
	(segment
		(start 194.777106 -286.878776)
		(end 194.321176 -287.334706)
		(width 0.18288)
		(layer "In11.Cu")
		(net "M_H_CPU1_SA_DQS_DN<3>")
	)
	(segment
		(start 129.808478 -265.629898)
		(end 129.793746 -265.638534)
		(width 0.088646)
		(layer "In11.Cu")
		(net "M_H_CPU1_SA_DQS_DN<3>")
	)
	(segment
		(start 173.837346 -288.966148)
		(end 173.260258 -288.966148)
		(width 0.18288)
		(layer "In11.Cu")
		(net "M_H_CPU1_SA_DQS_DN<3>")
	)
	(segment
		(start 130.748278 -265.629898)
		(end 130.733546 -265.638534)
		(width 0.088646)
		(layer "In11.Cu")
		(net "M_H_CPU1_SA_DQS_DN<3>")
	)
	(segment
		(start 197.227698 -286.357568)
		(end 196.03593 -286.357568)
		(width 0.18288)
		(layer "In11.Cu")
		(net "M_H_CPU1_SA_DQS_DN<3>")
	)
	(segment
		(start 137.88898 -268.90091)
		(end 137.866628 -268.887956)
		(width 0.088646)
		(layer "In11.Cu")
		(net "M_H_CPU1_SA_DQS_DN<3>")
	)
	(segment
		(start 140.696188 -269.43812)
		(end 140.636498 -269.49781)
		(width 0.088646)
		(layer "In11.Cu")
		(net "M_H_CPU1_SA_DQS_DN<3>")
	)
	(segment
		(start 192.194942 -287.840674)
		(end 191.71539 -287.840674)
		(width 0.18288)
		(layer "In11.Cu")
		(net "M_H_CPU1_SA_DQS_DN<3>")
	)
	(segment
		(start 178.586384 -287.296352)
		(end 177.759614 -288.123376)
		(width 0.18288)
		(layer "In11.Cu")
		(net "M_H_CPU1_SA_DQS_DN<3>")
	)
	(segment
		(start 160.832546 -284.799532)
		(end 160.832546 -284.62351)
		(width 0.18288)
		(layer "In11.Cu")
		(net "M_H_CPU1_SA_DQS_DN<3>")
	)
	(segment
		(start 189.829694 -287.84931)
		(end 189.238382 -287.257998)
		(width 0.18288)
		(layer "In11.Cu")
		(net "M_H_CPU1_SA_DQS_DN<3>")
	)
	(segment
		(start 201.371962 -284.115002)
		(end 200.171812 -285.315152)
		(width 0.18288)
		(layer "In11.Cu")
		(net "M_H_CPU1_SA_DQS_DN<3>")
	)
	(segment
		(start 199.743314 -285.315152)
		(end 197.227698 -286.357568)
		(width 0.18288)
		(layer "In11.Cu")
		(net "M_H_CPU1_SA_DQS_DN<3>")
	)
	(segment
		(start 184.492138 -287.2867)
		(end 182.968138 -286.65551)
		(width 0.18288)
		(layer "In11.Cu")
		(net "M_H_CPU1_SA_DQS_DN<3>")
	)
	(segment
		(start 175.512476 -288.097722)
		(end 174.526956 -288.505646)
		(width 0.18288)
		(layer "In11.Cu")
		(net "M_H_CPU1_SA_DQS_DN<3>")
	)
	(segment
		(start 162.783266 -285.69158)
		(end 162.658806 -285.81604)
		(width 0.18288)
		(layer "In11.Cu")
		(net "M_H_CPU1_SA_DQS_DN<3>")
	)
	(segment
		(start 170.783504 -288.204656)
		(end 168.038018 -286.36976)
		(width 0.18288)
		(layer "In11.Cu")
		(net "M_H_CPU1_SA_DQS_DN<3>")
	)
	(segment
		(start 187.314586 -287.2867)
		(end 184.492138 -287.2867)
		(width 0.18288)
		(layer "In11.Cu")
		(net "M_H_CPU1_SA_DQS_DN<3>")
	)
	(segment
		(start 202.065636 -284.115002)
		(end 201.371962 -284.115002)
		(width 0.18288)
		(layer "In11.Cu")
		(net "M_H_CPU1_SA_DQS_DN<3>")
	)
	(segment
		(start 188.090556 -286.992568)
		(end 187.613544 -286.992568)
		(width 0.18288)
		(layer "In11.Cu")
		(net "M_H_CPU1_SA_DQS_DN<3>")
	)
	(segment
		(start 202.68565 -284.3022)
		(end 202.252834 -284.3022)
		(width 0.18288)
		(layer "In11.Cu")
		(net "M_H_CPU1_SA_DQS_DN<3>")
	)
	(segment
		(start 166.556436 -286.36976)
		(end 166.277798 -286.091122)
		(width 0.18288)
		(layer "In11.Cu")
		(net "M_H_CPU1_SA_DQS_DN<3>")
	)
	(segment
		(start 191.146176 -288.13506)
		(end 190.860426 -287.84931)
		(width 0.18288)
		(layer "In11.Cu")
		(net "M_H_CPU1_SA_DQS_DN<3>")
	)
	(segment
		(start 202.252834 -284.3022)
		(end 202.065636 -284.115002)
		(width 0.18288)
		(layer "In11.Cu")
		(net "M_H_CPU1_SA_DQS_DN<3>")
	)
	(segment
		(start 124.169678 -265.629898)
		(end 124.154946 -265.638534)
		(width 0.088646)
		(layer "In11.Cu")
		(net "M_H_CPU1_SA_DQS_DN<3>")
	)
	(segment
		(start 192.474342 -288.120074)
		(end 192.194942 -287.840674)
		(width 0.18288)
		(layer "In11.Cu")
		(net "M_H_CPU1_SA_DQS_DN<3>")
	)
	(segment
		(start 123.65482 -265.314176)
		(end 123.967748 -265.314176)
		(width 0.088646)
		(layer "In11.Cu")
		(net "M_H_CPU1_SA_DQS_DN<3>")
	)
	(segment
		(start 172.270674 -288.94786)
		(end 171.526708 -288.94786)
		(width 0.18288)
		(layer "In11.Cu")
		(net "M_H_CPU1_SA_DQS_DN<3>")
	)
	(segment
		(start 157.30093 -283.708856)
		(end 143.030194 -269.43812)
		(width 0.18288)
		(layer "In11.Cu")
		(net "M_H_CPU1_SA_DQS_DN<3>")
	)
	(segment
		(start 126.984506 -265.632438)
		(end 126.974092 -265.638534)
		(width 0.088646)
		(layer "In11.Cu")
		(net "M_H_CPU1_SA_DQS_DN<3>")
	)
	(segment
		(start 166.277798 -286.091122)
		(end 164.62883 -286.091122)
		(width 0.18288)
		(layer "In11.Cu")
		(net "M_H_CPU1_SA_DQS_DN<3>")
	)
	(segment
		(start 140.636498 -269.49781)
		(end 140.270738 -269.49781)
		(width 0.088646)
		(layer "In11.Cu")
		(net "M_H_CPU1_SA_DQS_DN<3>")
	)
	(segment
		(start 161.849054 -285.81604)
		(end 160.832546 -284.799532)
		(width 0.18288)
		(layer "In11.Cu")
		(net "M_H_CPU1_SA_DQS_DN<3>")
	)
	(segment
		(start 172.9867 -288.69259)
		(end 172.525944 -288.69259)
		(width 0.18288)
		(layer "In11.Cu")
		(net "M_H_CPU1_SA_DQS_DN<3>")
	)
	(segment
		(start 200.171812 -285.315152)
		(end 199.743314 -285.315152)
		(width 0.18288)
		(layer "In11.Cu")
		(net "M_H_CPU1_SA_DQS_DN<3>")
	)
	(segment
		(start 139.286234 -269.08125)
		(end 139.01293 -269.08125)
		(width 0.088646)
		(layer "In11.Cu")
		(net "M_H_CPU1_SA_DQS_DN<3>")
	)
	(segment
		(start 193.49847 -287.675574)
		(end 193.054224 -288.120074)
		(width 0.18288)
		(layer "In11.Cu")
		(net "M_H_CPU1_SA_DQS_DN<3>")
	)
	(segment
		(start 135.05815 -268.894052)
		(end 135.057642 -268.894306)
		(width 0.088646)
		(layer "In11.Cu")
		(net "M_H_CPU1_SA_DQS_DN<3>")
	)
	(segment
		(start 133.660388 -266.459462)
		(end 133.639306 -266.44727)
		(width 0.088646)
		(layer "In11.Cu")
		(net "M_H_CPU1_SA_DQS_DN<3>")
	)
	(segment
		(start 133.460744 -266.127992)
		(end 133.46049 -266.10945)
		(width 0.088646)
		(layer "In11.Cu")
		(net "M_H_CPU1_SA_DQS_DN<3>")
	)
	(segment
		(start 160.444434 -284.235398)
		(end 160.268412 -284.235398)
		(width 0.18288)
		(layer "In11.Cu")
		(net "M_H_CPU1_SA_DQS_DN<3>")
	)
	(segment
		(start 164.62883 -286.091122)
		(end 164.355272 -285.81604)
		(width 0.18288)
		(layer "In11.Cu")
		(net "M_H_CPU1_SA_DQS_DN<3>")
	)
	(segment
		(start 134.59841 -268.086586)
		(end 134.582662 -268.077442)
		(width 0.088646)
		(layer "In11.Cu")
		(net "M_H_CPU1_SA_DQS_DN<3>")
	)
	(segment
		(start 125.109478 -265.629898)
		(end 125.094746 -265.638534)
		(width 0.088646)
		(layer "In11.Cu")
		(net "M_H_CPU1_SA_DQS_DN<3>")
	)
	(segment
		(start 139.01293 -269.08125)
		(end 138.838178 -268.906498)
		(width 0.088646)
		(layer "In11.Cu")
		(net "M_H_CPU1_SA_DQS_DN<3>")
	)
	(arc
		(start 133.46049 -266.10945)
		(mid 133.175356 -265.636983)
		(end 132.62356 -265.632438)
		(width 0.088646)
		(layer "In11.Cu")
		(net "M_H_CPU1_SA_DQS_DN<3>")
	)
	(arc
		(start 128.47955 -265.638534)
		(mid 128.205321 -265.562609)
		(end 127.928878 -265.629898)
		(width 0.088646)
		(layer "In11.Cu")
		(net "M_H_CPU1_SA_DQS_DN<3>")
	)
	(arc
		(start 126.974092 -265.638534)
		(mid 126.786894 -265.688677)
		(end 126.599696 -265.638534)
		(width 0.088646)
		(layer "In11.Cu")
		(net "M_H_CPU1_SA_DQS_DN<3>")
	)
	(arc
		(start 128.853946 -265.638534)
		(mid 128.666748 -265.688677)
		(end 128.47955 -265.638534)
		(width 0.088646)
		(layer "In11.Cu")
		(net "M_H_CPU1_SA_DQS_DN<3>")
	)
	(arc
		(start 131.673346 -265.638534)
		(mid 131.486148 -265.688677)
		(end 131.29895 -265.638534)
		(width 0.088646)
		(layer "In11.Cu")
		(net "M_H_CPU1_SA_DQS_DN<3>")
	)
	(arc
		(start 132.613146 -265.638534)
		(mid 132.425948 -265.688677)
		(end 132.23875 -265.638534)
		(width 0.088646)
		(layer "In11.Cu")
		(net "M_H_CPU1_SA_DQS_DN<3>")
	)
	(arc
		(start 137.311892 -268.894052)
		(mid 137.124694 -268.944195)
		(end 136.937496 -268.894052)
		(width 0.088646)
		(layer "In11.Cu")
		(net "M_H_CPU1_SA_DQS_DN<3>")
	)
	(arc
		(start 136.937496 -268.894052)
		(mid 136.654794 -268.818276)
		(end 136.372092 -268.894052)
		(width 0.088646)
		(layer "In11.Cu")
		(net "M_H_CPU1_SA_DQS_DN<3>")
	)
	(arc
		(start 135.057642 -268.894306)
		(mid 134.92361 -268.762458)
		(end 134.870444 -268.58214)
		(width 0.088646)
		(layer "In11.Cu")
		(net "M_H_CPU1_SA_DQS_DN<3>")
	)
	(arc
		(start 136.372092 -268.894052)
		(mid 136.184894 -268.944195)
		(end 135.997696 -268.894052)
		(width 0.088646)
		(layer "In11.Cu")
		(net "M_H_CPU1_SA_DQS_DN<3>")
	)
	(arc
		(start 130.35915 -265.638534)
		(mid 130.084921 -265.562609)
		(end 129.808478 -265.629898)
		(width 0.088646)
		(layer "In11.Cu")
		(net "M_H_CPU1_SA_DQS_DN<3>")
	)
	(arc
		(start 134.400544 -267.755878)
		(mid 134.400392 -267.745081)
		(end 134.400036 -267.734288)
		(width 0.088646)
		(layer "In11.Cu")
		(net "M_H_CPU1_SA_DQS_DN<3>")
	)
	(arc
		(start 129.41935 -265.638534)
		(mid 129.145121 -265.562609)
		(end 128.868678 -265.629898)
		(width 0.088646)
		(layer "In11.Cu")
		(net "M_H_CPU1_SA_DQS_DN<3>")
	)
	(arc
		(start 131.29895 -265.638534)
		(mid 131.024721 -265.562609)
		(end 130.748278 -265.629898)
		(width 0.088646)
		(layer "In11.Cu")
		(net "M_H_CPU1_SA_DQS_DN<3>")
	)
	(arc
		(start 126.034546 -265.638534)
		(mid 125.847348 -265.688677)
		(end 125.66015 -265.638534)
		(width 0.088646)
		(layer "In11.Cu")
		(net "M_H_CPU1_SA_DQS_DN<3>")
	)
	(arc
		(start 130.733546 -265.638534)
		(mid 130.546348 -265.688677)
		(end 130.35915 -265.638534)
		(width 0.088646)
		(layer "In11.Cu")
		(net "M_H_CPU1_SA_DQS_DN<3>")
	)
	(arc
		(start 138.251438 -268.894052)
		(mid 138.071091 -268.944255)
		(end 137.88898 -268.90091)
		(width 0.088646)
		(layer "In11.Cu")
		(net "M_H_CPU1_SA_DQS_DN<3>")
	)
	(arc
		(start 132.23875 -265.638534)
		(mid 131.964521 -265.562609)
		(end 131.688078 -265.629898)
		(width 0.088646)
		(layer "In11.Cu")
		(net "M_H_CPU1_SA_DQS_DN<3>")
	)
	(arc
		(start 127.914146 -265.638534)
		(mid 127.726948 -265.688677)
		(end 127.53975 -265.638534)
		(width 0.088646)
		(layer "In11.Cu")
		(net "M_H_CPU1_SA_DQS_DN<3>")
	)
	(arc
		(start 124.154946 -265.638534)
		(mid 123.805841 -265.65187)
		(end 123.59767 -265.371326)
		(width 0.088646)
		(layer "In11.Cu")
		(net "M_H_CPU1_SA_DQS_DN<3>")
	)
	(arc
		(start 125.094746 -265.638534)
		(mid 124.907548 -265.688677)
		(end 124.72035 -265.638534)
		(width 0.088646)
		(layer "In11.Cu")
		(net "M_H_CPU1_SA_DQS_DN<3>")
	)
	(arc
		(start 133.639306 -266.44727)
		(mid 133.508392 -266.31091)
		(end 133.460744 -266.127992)
		(width 0.088646)
		(layer "In11.Cu")
		(net "M_H_CPU1_SA_DQS_DN<3>")
	)
	(arc
		(start 125.66015 -265.638534)
		(mid 125.385921 -265.562609)
		(end 125.109478 -265.629898)
		(width 0.088646)
		(layer "In11.Cu")
		(net "M_H_CPU1_SA_DQS_DN<3>")
	)
	(arc
		(start 134.582662 -268.077442)
		(mid 134.449227 -267.94067)
		(end 134.400544 -267.755878)
		(width 0.088646)
		(layer "In11.Cu")
		(net "M_H_CPU1_SA_DQS_DN<3>")
	)
	(arc
		(start 124.72035 -265.638534)
		(mid 124.446121 -265.562609)
		(end 124.169678 -265.629898)
		(width 0.088646)
		(layer "In11.Cu")
		(net "M_H_CPU1_SA_DQS_DN<3>")
	)
	(arc
		(start 138.798554 -268.883638)
		(mid 138.52365 -268.818234)
		(end 138.251438 -268.894052)
		(width 0.088646)
		(layer "In11.Cu")
		(net "M_H_CPU1_SA_DQS_DN<3>")
	)
	(arc
		(start 135.432546 -268.894052)
		(mid 135.245348 -268.944195)
		(end 135.05815 -268.894052)
		(width 0.088646)
		(layer "In11.Cu")
		(net "M_H_CPU1_SA_DQS_DN<3>")
	)
	(arc
		(start 134.400036 -267.73378)
		(mid 134.322147 -267.469093)
		(end 134.128256 -267.27277)
		(width 0.088646)
		(layer "In11.Cu")
		(net "M_H_CPU1_SA_DQS_DN<3>")
	)
	(arc
		(start 134.870444 -268.569694)
		(mid 134.797752 -268.292489)
		(end 134.59841 -268.086586)
		(width 0.088646)
		(layer "In11.Cu")
		(net "M_H_CPU1_SA_DQS_DN<3>")
	)
	(arc
		(start 129.793746 -265.638534)
		(mid 129.606548 -265.688677)
		(end 129.41935 -265.638534)
		(width 0.088646)
		(layer "In11.Cu")
		(net "M_H_CPU1_SA_DQS_DN<3>")
	)
	(arc
		(start 135.997696 -268.894052)
		(mid 135.721137 -268.818309)
		(end 135.44296 -268.887956)
		(width 0.088646)
		(layer "In11.Cu")
		(net "M_H_CPU1_SA_DQS_DN<3>")
	)
	(arc
		(start 134.10946 -267.261086)
		(mid 133.978546 -267.124726)
		(end 133.930898 -266.941808)
		(width 0.088646)
		(layer "In11.Cu")
		(net "M_H_CPU1_SA_DQS_DN<3>")
	)
	(arc
		(start 127.53975 -265.638534)
		(mid 127.262937 -265.562698)
		(end 126.984506 -265.632438)
		(width 0.088646)
		(layer "In11.Cu")
		(net "M_H_CPU1_SA_DQS_DN<3>")
	)
	(arc
		(start 133.930898 -266.941808)
		(mid 133.858663 -266.665284)
		(end 133.660388 -266.459462)
		(width 0.088646)
		(layer "In11.Cu")
		(net "M_H_CPU1_SA_DQS_DN<3>")
	)
	(arc
		(start 126.599696 -265.638534)
		(mid 126.323137 -265.562825)
		(end 126.04496 -265.632438)
		(width 0.088646)
		(layer "In11.Cu")
		(net "M_H_CPU1_SA_DQS_DN<3>")
	)
	(arc
		(start 137.866628 -268.887956)
		(mid 137.58845 -268.818233)
		(end 137.311892 -268.894052)
		(width 0.088646)
		(layer "In11.Cu")
		(net "M_H_CPU1_SA_DQS_DN<3>")
	)
	(segment
		(start 210.790028 -293.607236)
		(end 211.030566 -293.366698)
		(width 0.20066)
		(layer "F.Cu")
		(net "M_H_CPU1_SA_DQS_DN<2>")
	)
	(segment
		(start 204.624686 -293.366698)
		(end 204.906372 -293.648384)
		(width 0.20066)
		(layer "F.Cu")
		(net "M_H_CPU1_SA_DQS_DN<2>")
	)
	(segment
		(start 207.001618 -293.79164)
		(end 209.181192 -293.79164)
		(width 0.1016)
		(layer "F.Cu")
		(net "M_H_CPU1_SA_DQS_DN<2>")
	)
	(segment
		(start 123.967748 -270.167862)
		(end 123.967748 -270.19758)
		(width 0.20066)
		(layer "F.Cu")
		(net "M_H_CPU1_SA_DQS_DN<2>")
	)
	(segment
		(start 209.181192 -293.79164)
		(end 209.186526 -293.786306)
		(width 0.1016)
		(layer "F.Cu")
		(net "M_H_CPU1_SA_DQS_DN<2>")
	)
	(segment
		(start 204.906372 -293.648384)
		(end 205.64221 -293.648384)
		(width 0.20066)
		(layer "F.Cu")
		(net "M_H_CPU1_SA_DQS_DN<2>")
	)
	(segment
		(start 210.457542 -293.607236)
		(end 210.790028 -293.607236)
		(width 0.20066)
		(layer "F.Cu")
		(net "M_H_CPU1_SA_DQS_DN<2>")
	)
	(segment
		(start 204.076046 -293.366698)
		(end 204.624686 -293.366698)
		(width 0.20066)
		(layer "F.Cu")
		(net "M_H_CPU1_SA_DQS_DN<2>")
	)
	(segment
		(start 210.047078 -294.0177)
		(end 210.457542 -293.607236)
		(width 0.20066)
		(layer "F.Cu")
		(net "M_H_CPU1_SA_DQS_DN<2>")
	)
	(segment
		(start 206.9973 -293.79164)
		(end 207.001618 -293.79164)
		(width 0.101854)
		(layer "F.Cu")
		(net "M_H_CPU1_SA_DQS_DN<2>")
	)
	(segment
		(start 206.056738 -294.062912)
		(end 206.578454 -294.062912)
		(width 0.20066)
		(layer "F.Cu")
		(net "M_H_CPU1_SA_DQS_DN<2>")
	)
	(segment
		(start 123.967494 -269.66164)
		(end 123.967748 -270.167862)
		(width 0.20066)
		(layer "F.Cu")
		(net "M_H_CPU1_SA_DQS_DN<2>")
	)
	(segment
		(start 209.186526 -293.786306)
		(end 209.51063 -293.786306)
		(width 0.20066)
		(layer "F.Cu")
		(net "M_H_CPU1_SA_DQS_DN<2>")
	)
	(segment
		(start 202.971146 -293.366698)
		(end 204.076046 -293.366698)
		(width 0.20066)
		(layer "F.Cu")
		(net "M_H_CPU1_SA_DQS_DN<2>")
	)
	(segment
		(start 206.849726 -293.79164)
		(end 206.9973 -293.79164)
		(width 0.20066)
		(layer "F.Cu")
		(net "M_H_CPU1_SA_DQS_DN<2>")
	)
	(segment
		(start 205.64221 -293.648384)
		(end 206.056738 -294.062912)
		(width 0.20066)
		(layer "F.Cu")
		(net "M_H_CPU1_SA_DQS_DN<2>")
	)
	(segment
		(start 211.030566 -293.366698)
		(end 211.619846 -293.366698)
		(width 0.20066)
		(layer "F.Cu")
		(net "M_H_CPU1_SA_DQS_DN<2>")
	)
	(segment
		(start 209.742024 -294.0177)
		(end 210.047078 -294.0177)
		(width 0.20066)
		(layer "F.Cu")
		(net "M_H_CPU1_SA_DQS_DN<2>")
	)
	(segment
		(start 209.51063 -293.786306)
		(end 209.742024 -294.0177)
		(width 0.20066)
		(layer "F.Cu")
		(net "M_H_CPU1_SA_DQS_DN<2>")
	)
	(segment
		(start 206.578454 -294.062912)
		(end 206.849726 -293.79164)
		(width 0.20066)
		(layer "F.Cu")
		(net "M_H_CPU1_SA_DQS_DN<2>")
	)
	(segment
		(start 177.418238 -299.166026)
		(end 177.14468 -298.892468)
		(width 0.18288)
		(layer "In11.Cu")
		(net "M_H_CPU1_SA_DQS_DN<2>")
	)
	(segment
		(start 169.713656 -298.125388)
		(end 168.681908 -298.125388)
		(width 0.18288)
		(layer "In11.Cu")
		(net "M_H_CPU1_SA_DQS_DN<2>")
	)
	(segment
		(start 185.76417 -298.196508)
		(end 185.21553 -298.196508)
		(width 0.18288)
		(layer "In11.Cu")
		(net "M_H_CPU1_SA_DQS_DN<2>")
	)
	(segment
		(start 183.373522 -297.452034)
		(end 182.019702 -297.452034)
		(width 0.18288)
		(layer "In11.Cu")
		(net "M_H_CPU1_SA_DQS_DN<2>")
	)
	(segment
		(start 128.947672 -271.334992)
		(end 128.940306 -271.330674)
		(width 0.088646)
		(layer "In11.Cu")
		(net "M_H_CPU1_SA_DQS_DN<2>")
	)
	(segment
		(start 184.242456 -298.320968)
		(end 183.373522 -297.452034)
		(width 0.18288)
		(layer "In11.Cu")
		(net "M_H_CPU1_SA_DQS_DN<2>")
	)
	(segment
		(start 202.162664 -293.470076)
		(end 201.300588 -293.470076)
		(width 0.18288)
		(layer "In11.Cu")
		(net "M_H_CPU1_SA_DQS_DN<2>")
	)
	(segment
		(start 193.017648 -299.178472)
		(end 192.46596 -299.178472)
		(width 0.18288)
		(layer "In11.Cu")
		(net "M_H_CPU1_SA_DQS_DN<2>")
	)
	(segment
		(start 126.599696 -270.521938)
		(end 126.592584 -270.517874)
		(width 0.088646)
		(layer "In11.Cu")
		(net "M_H_CPU1_SA_DQS_DN<2>")
	)
	(segment
		(start 180.190648 -298.942506)
		(end 179.74691 -298.498768)
		(width 0.18288)
		(layer "In11.Cu")
		(net "M_H_CPU1_SA_DQS_DN<2>")
	)
	(segment
		(start 168.030652 -297.474132)
		(end 166.731696 -297.474132)
		(width 0.18288)
		(layer "In11.Cu")
		(net "M_H_CPU1_SA_DQS_DN<2>")
	)
	(segment
		(start 152.211024 -290.010596)
		(end 152.211024 -288.061146)
		(width 0.18288)
		(layer "In11.Cu")
		(net "M_H_CPU1_SA_DQS_DN<2>")
	)
	(segment
		(start 156.5021 -294.301672)
		(end 152.211024 -290.010596)
		(width 0.18288)
		(layer "In11.Cu")
		(net "M_H_CPU1_SA_DQS_DN<2>")
	)
	(segment
		(start 127.928878 -270.513302)
		(end 127.914146 -270.521938)
		(width 0.088646)
		(layer "In11.Cu")
		(net "M_H_CPU1_SA_DQS_DN<2>")
	)
	(segment
		(start 182.019702 -297.452034)
		(end 180.52923 -298.942506)
		(width 0.18288)
		(layer "In11.Cu")
		(net "M_H_CPU1_SA_DQS_DN<2>")
	)
	(segment
		(start 166.607236 -297.349672)
		(end 166.058596 -297.349672)
		(width 0.18288)
		(layer "In11.Cu")
		(net "M_H_CPU1_SA_DQS_DN<2>")
	)
	(segment
		(start 199.041512 -294.814752)
		(end 198.051928 -295.804336)
		(width 0.18288)
		(layer "In11.Cu")
		(net "M_H_CPU1_SA_DQS_DN<2>")
	)
	(segment
		(start 187.615322 -298.040806)
		(end 187.33516 -298.320968)
		(width 0.18288)
		(layer "In11.Cu")
		(net "M_H_CPU1_SA_DQS_DN<2>")
	)
	(segment
		(start 165.316916 -297.474132)
		(end 164.194744 -296.35196)
		(width 0.18288)
		(layer "In11.Cu")
		(net "M_H_CPU1_SA_DQS_DN<2>")
	)
	(segment
		(start 192.46596 -299.178472)
		(end 192.182242 -298.894754)
		(width 0.18288)
		(layer "In11.Cu")
		(net "M_H_CPU1_SA_DQS_DN<2>")
	)
	(segment
		(start 202.683618 -293.654226)
		(end 202.346814 -293.654226)
		(width 0.18288)
		(layer "In11.Cu")
		(net "M_H_CPU1_SA_DQS_DN<2>")
	)
	(segment
		(start 190.087504 -299.163994)
		(end 189.239652 -298.316142)
		(width 0.18288)
		(layer "In11.Cu")
		(net "M_H_CPU1_SA_DQS_DN<2>")
	)
	(segment
		(start 130.35915 -272.14957)
		(end 130.35026 -272.14449)
		(width 0.088646)
		(layer "In11.Cu")
		(net "M_H_CPU1_SA_DQS_DN<2>")
	)
	(segment
		(start 168.681908 -298.125388)
		(end 168.030652 -297.474132)
		(width 0.18288)
		(layer "In11.Cu")
		(net "M_H_CPU1_SA_DQS_DN<2>")
	)
	(segment
		(start 124.724922 -270.524732)
		(end 124.720096 -270.521938)
		(width 0.088646)
		(layer "In11.Cu")
		(net "M_H_CPU1_SA_DQS_DN<2>")
	)
	(segment
		(start 195.463668 -297.207686)
		(end 194.549268 -298.122086)
		(width 0.18288)
		(layer "In11.Cu")
		(net "M_H_CPU1_SA_DQS_DN<2>")
	)
	(segment
		(start 192.182242 -298.894754)
		(end 191.711326 -298.894754)
		(width 0.18288)
		(layer "In11.Cu")
		(net "M_H_CPU1_SA_DQS_DN<2>")
	)
	(segment
		(start 197.231508 -295.804336)
		(end 195.828158 -297.207686)
		(width 0.18288)
		(layer "In11.Cu")
		(net "M_H_CPU1_SA_DQS_DN<2>")
	)
	(segment
		(start 166.731696 -297.474132)
		(end 166.607236 -297.349672)
		(width 0.18288)
		(layer "In11.Cu")
		(net "M_H_CPU1_SA_DQS_DN<2>")
	)
	(segment
		(start 131.688078 -273.76882)
		(end 131.673346 -273.777456)
		(width 0.088646)
		(layer "In11.Cu")
		(net "M_H_CPU1_SA_DQS_DN<2>")
	)
	(segment
		(start 135.44296 -273.77136)
		(end 135.432546 -273.777456)
		(width 0.088646)
		(layer "In11.Cu")
		(net "M_H_CPU1_SA_DQS_DN<2>")
	)
	(segment
		(start 185.88863 -298.320968)
		(end 185.76417 -298.196508)
		(width 0.18288)
		(layer "In11.Cu")
		(net "M_H_CPU1_SA_DQS_DN<2>")
	)
	(segment
		(start 139.746228 -275.59635)
		(end 139.325858 -275.59635)
		(width 0.18288)
		(layer "In11.Cu")
		(net "M_H_CPU1_SA_DQS_DN<2>")
	)
	(segment
		(start 131.29895 -273.777456)
		(end 131.29006 -273.772376)
		(width 0.088646)
		(layer "In11.Cu")
		(net "M_H_CPU1_SA_DQS_DN<2>")
	)
	(segment
		(start 178.707288 -298.498768)
		(end 178.04003 -299.166026)
		(width 0.18288)
		(layer "In11.Cu")
		(net "M_H_CPU1_SA_DQS_DN<2>")
	)
	(segment
		(start 189.239652 -298.316142)
		(end 188.35243 -298.316142)
		(width 0.18288)
		(layer "In11.Cu")
		(net "M_H_CPU1_SA_DQS_DN<2>")
	)
	(segment
		(start 133.567678 -273.76882)
		(end 133.552946 -273.777456)
		(width 0.088646)
		(layer "In11.Cu")
		(net "M_H_CPU1_SA_DQS_DN<2>")
	)
	(segment
		(start 180.52923 -298.942506)
		(end 180.190648 -298.942506)
		(width 0.18288)
		(layer "In11.Cu")
		(net "M_H_CPU1_SA_DQS_DN<2>")
	)
	(segment
		(start 125.659896 -270.521938)
		(end 125.652784 -270.517874)
		(width 0.088646)
		(layer "In11.Cu")
		(net "M_H_CPU1_SA_DQS_DN<2>")
	)
	(segment
		(start 185.21553 -298.196508)
		(end 185.09107 -298.320968)
		(width 0.18288)
		(layer "In11.Cu")
		(net "M_H_CPU1_SA_DQS_DN<2>")
	)
	(segment
		(start 179.74691 -298.498768)
		(end 178.707288 -298.498768)
		(width 0.18288)
		(layer "In11.Cu")
		(net "M_H_CPU1_SA_DQS_DN<2>")
	)
	(segment
		(start 130.828796 -272.96364)
		(end 130.819906 -272.95856)
		(width 0.088646)
		(layer "In11.Cu")
		(net "M_H_CPU1_SA_DQS_DN<2>")
	)
	(segment
		(start 194.074034 -298.122086)
		(end 193.017648 -299.178472)
		(width 0.18288)
		(layer "In11.Cu")
		(net "M_H_CPU1_SA_DQS_DN<2>")
	)
	(segment
		(start 128.949196 -271.335754)
		(end 128.947672 -271.334992)
		(width 0.088646)
		(layer "In11.Cu")
		(net "M_H_CPU1_SA_DQS_DN<2>")
	)
	(segment
		(start 152.211024 -288.061146)
		(end 139.746228 -275.59635)
		(width 0.18288)
		(layer "In11.Cu")
		(net "M_H_CPU1_SA_DQS_DN<2>")
	)
	(segment
		(start 199.955912 -294.814752)
		(end 199.041512 -294.814752)
		(width 0.18288)
		(layer "In11.Cu")
		(net "M_H_CPU1_SA_DQS_DN<2>")
	)
	(segment
		(start 128.761744 -271.011396)
		(end 128.761744 -270.995902)
		(width 0.088646)
		(layer "In11.Cu")
		(net "M_H_CPU1_SA_DQS_DN<2>")
	)
	(segment
		(start 159.245554 -295.513506)
		(end 158.03372 -294.301672)
		(width 0.18288)
		(layer "In11.Cu")
		(net "M_H_CPU1_SA_DQS_DN<2>")
	)
	(segment
		(start 173.844458 -300.00829)
		(end 173.26229 -300.00829)
		(width 0.18288)
		(layer "In11.Cu")
		(net "M_H_CPU1_SA_DQS_DN<2>")
	)
	(segment
		(start 123.597416 -270.254984)
		(end 123.65482 -270.19758)
		(width 0.088646)
		(layer "In11.Cu")
		(net "M_H_CPU1_SA_DQS_DN<2>")
	)
	(segment
		(start 195.828158 -297.207686)
		(end 195.463668 -297.207686)
		(width 0.18288)
		(layer "In11.Cu")
		(net "M_H_CPU1_SA_DQS_DN<2>")
	)
	(segment
		(start 201.300588 -293.470076)
		(end 199.955912 -294.814752)
		(width 0.18288)
		(layer "In11.Cu")
		(net "M_H_CPU1_SA_DQS_DN<2>")
	)
	(segment
		(start 139.325858 -275.59635)
		(end 139.266168 -275.65604)
		(width 0.088646)
		(layer "In11.Cu")
		(net "M_H_CPU1_SA_DQS_DN<2>")
	)
	(segment
		(start 191.711326 -298.894754)
		(end 191.442086 -299.163994)
		(width 0.18288)
		(layer "In11.Cu")
		(net "M_H_CPU1_SA_DQS_DN<2>")
	)
	(segment
		(start 123.65482 -270.19758)
		(end 123.967748 -270.19758)
		(width 0.088646)
		(layer "In11.Cu")
		(net "M_H_CPU1_SA_DQS_DN<2>")
	)
	(segment
		(start 191.442086 -299.163994)
		(end 190.087504 -299.163994)
		(width 0.18288)
		(layer "In11.Cu")
		(net "M_H_CPU1_SA_DQS_DN<2>")
	)
	(segment
		(start 160.750758 -296.35196)
		(end 159.912304 -295.513506)
		(width 0.18288)
		(layer "In11.Cu")
		(net "M_H_CPU1_SA_DQS_DN<2>")
	)
	(segment
		(start 138.843512 -275.65604)
		(end 137.053828 -273.866356)
		(width 0.088646)
		(layer "In11.Cu")
		(net "M_H_CPU1_SA_DQS_DN<2>")
	)
	(segment
		(start 172.995844 -299.741844)
		(end 172.550074 -299.741844)
		(width 0.18288)
		(layer "In11.Cu")
		(net "M_H_CPU1_SA_DQS_DN<2>")
	)
	(segment
		(start 123.785122 -270.524732)
		(end 123.780804 -270.522446)
		(width 0.088646)
		(layer "In11.Cu")
		(net "M_H_CPU1_SA_DQS_DN<2>")
	)
	(segment
		(start 174.70501 -299.147738)
		(end 173.844458 -300.00829)
		(width 0.18288)
		(layer "In11.Cu")
		(net "M_H_CPU1_SA_DQS_DN<2>")
	)
	(segment
		(start 134.507478 -273.76882)
		(end 134.492746 -273.777456)
		(width 0.088646)
		(layer "In11.Cu")
		(net "M_H_CPU1_SA_DQS_DN<2>")
	)
	(segment
		(start 202.346814 -293.654226)
		(end 202.162664 -293.470076)
		(width 0.18288)
		(layer "In11.Cu")
		(net "M_H_CPU1_SA_DQS_DN<2>")
	)
	(segment
		(start 202.971146 -293.366698)
		(end 202.683618 -293.654226)
		(width 0.18288)
		(layer "In11.Cu")
		(net "M_H_CPU1_SA_DQS_DN<2>")
	)
	(segment
		(start 166.058596 -297.349672)
		(end 165.934136 -297.474132)
		(width 0.18288)
		(layer "In11.Cu")
		(net "M_H_CPU1_SA_DQS_DN<2>")
	)
	(segment
		(start 164.194744 -296.35196)
		(end 160.750758 -296.35196)
		(width 0.18288)
		(layer "In11.Cu")
		(net "M_H_CPU1_SA_DQS_DN<2>")
	)
	(segment
		(start 123.780804 -270.522446)
		(end 123.77928 -270.52143)
		(width 0.088646)
		(layer "In11.Cu")
		(net "M_H_CPU1_SA_DQS_DN<2>")
	)
	(segment
		(start 124.720096 -270.521938)
		(end 124.712984 -270.517874)
		(width 0.088646)
		(layer "In11.Cu")
		(net "M_H_CPU1_SA_DQS_DN<2>")
	)
	(segment
		(start 188.35243 -298.316142)
		(end 188.077094 -298.040806)
		(width 0.18288)
		(layer "In11.Cu")
		(net "M_H_CPU1_SA_DQS_DN<2>")
	)
	(segment
		(start 177.14468 -298.892468)
		(end 176.57572 -298.892468)
		(width 0.18288)
		(layer "In11.Cu")
		(net "M_H_CPU1_SA_DQS_DN<2>")
	)
	(segment
		(start 126.989078 -270.513302)
		(end 126.9746 -270.521938)
		(width 0.088646)
		(layer "In11.Cu")
		(net "M_H_CPU1_SA_DQS_DN<2>")
	)
	(segment
		(start 173.26229 -300.00829)
		(end 172.995844 -299.741844)
		(width 0.18288)
		(layer "In11.Cu")
		(net "M_H_CPU1_SA_DQS_DN<2>")
	)
	(segment
		(start 185.09107 -298.320968)
		(end 184.242456 -298.320968)
		(width 0.18288)
		(layer "In11.Cu")
		(net "M_H_CPU1_SA_DQS_DN<2>")
	)
	(segment
		(start 198.051928 -295.804336)
		(end 197.231508 -295.804336)
		(width 0.18288)
		(layer "In11.Cu")
		(net "M_H_CPU1_SA_DQS_DN<2>")
	)
	(segment
		(start 129.895092 -271.33931)
		(end 129.874264 -271.327118)
		(width 0.088646)
		(layer "In11.Cu")
		(net "M_H_CPU1_SA_DQS_DN<2>")
	)
	(segment
		(start 130.641344 -272.639282)
		(end 130.641344 -272.617184)
		(width 0.088646)
		(layer "In11.Cu")
		(net "M_H_CPU1_SA_DQS_DN<2>")
	)
	(segment
		(start 188.077094 -298.040806)
		(end 187.615322 -298.040806)
		(width 0.18288)
		(layer "In11.Cu")
		(net "M_H_CPU1_SA_DQS_DN<2>")
	)
	(segment
		(start 172.550074 -299.741844)
		(end 172.283628 -300.00829)
		(width 0.18288)
		(layer "In11.Cu")
		(net "M_H_CPU1_SA_DQS_DN<2>")
	)
	(segment
		(start 194.549268 -298.122086)
		(end 194.074034 -298.122086)
		(width 0.18288)
		(layer "In11.Cu")
		(net "M_H_CPU1_SA_DQS_DN<2>")
	)
	(segment
		(start 126.604522 -270.524732)
		(end 126.599696 -270.521938)
		(width 0.088646)
		(layer "In11.Cu")
		(net "M_H_CPU1_SA_DQS_DN<2>")
	)
	(segment
		(start 139.266168 -275.65604)
		(end 138.843512 -275.65604)
		(width 0.088646)
		(layer "In11.Cu")
		(net "M_H_CPU1_SA_DQS_DN<2>")
	)
	(segment
		(start 125.664722 -270.524732)
		(end 125.659896 -270.521938)
		(width 0.088646)
		(layer "In11.Cu")
		(net "M_H_CPU1_SA_DQS_DN<2>")
	)
	(segment
		(start 187.33516 -298.320968)
		(end 185.88863 -298.320968)
		(width 0.18288)
		(layer "In11.Cu")
		(net "M_H_CPU1_SA_DQS_DN<2>")
	)
	(segment
		(start 172.283628 -300.00829)
		(end 171.596558 -300.00829)
		(width 0.18288)
		(layer "In11.Cu")
		(net "M_H_CPU1_SA_DQS_DN<2>")
	)
	(segment
		(start 176.57572 -298.892468)
		(end 176.32045 -299.147738)
		(width 0.18288)
		(layer "In11.Cu")
		(net "M_H_CPU1_SA_DQS_DN<2>")
	)
	(segment
		(start 165.934136 -297.474132)
		(end 165.316916 -297.474132)
		(width 0.18288)
		(layer "In11.Cu")
		(net "M_H_CPU1_SA_DQS_DN<2>")
	)
	(segment
		(start 178.04003 -299.166026)
		(end 177.418238 -299.166026)
		(width 0.18288)
		(layer "In11.Cu")
		(net "M_H_CPU1_SA_DQS_DN<2>")
	)
	(segment
		(start 159.912304 -295.513506)
		(end 159.245554 -295.513506)
		(width 0.18288)
		(layer "In11.Cu")
		(net "M_H_CPU1_SA_DQS_DN<2>")
	)
	(segment
		(start 130.834892 -272.967196)
		(end 130.828796 -272.96364)
		(width 0.088646)
		(layer "In11.Cu")
		(net "M_H_CPU1_SA_DQS_DN<2>")
	)
	(segment
		(start 176.32045 -299.147738)
		(end 174.70501 -299.147738)
		(width 0.18288)
		(layer "In11.Cu")
		(net "M_H_CPU1_SA_DQS_DN<2>")
	)
	(segment
		(start 158.03372 -294.301672)
		(end 156.5021 -294.301672)
		(width 0.18288)
		(layer "In11.Cu")
		(net "M_H_CPU1_SA_DQS_DN<2>")
	)
	(segment
		(start 123.77928 -270.52143)
		(end 123.779026 -270.521176)
		(width 0.088646)
		(layer "In11.Cu")
		(net "M_H_CPU1_SA_DQS_DN<2>")
	)
	(segment
		(start 171.596558 -300.00829)
		(end 169.713656 -298.125388)
		(width 0.18288)
		(layer "In11.Cu")
		(net "M_H_CPU1_SA_DQS_DN<2>")
	)
	(arc
		(start 130.171952 -271.839944)
		(mid 130.171755 -271.832579)
		(end 130.171698 -271.825212)
		(width 0.088646)
		(layer "In11.Cu")
		(net "M_H_CPU1_SA_DQS_DN<2>")
	)
	(arc
		(start 128.761744 -270.995902)
		(mid 128.682374 -270.722168)
		(end 128.47955 -270.521938)
		(width 0.088646)
		(layer "In11.Cu")
		(net "M_H_CPU1_SA_DQS_DN<2>")
	)
	(arc
		(start 125.094746 -270.521938)
		(mid 124.910193 -270.572197)
		(end 124.724922 -270.524732)
		(width 0.088646)
		(layer "In11.Cu")
		(net "M_H_CPU1_SA_DQS_DN<2>")
	)
	(arc
		(start 127.914146 -270.521938)
		(mid 127.726948 -270.572081)
		(end 127.53975 -270.521938)
		(width 0.088646)
		(layer "In11.Cu")
		(net "M_H_CPU1_SA_DQS_DN<2>")
	)
	(arc
		(start 123.613672 -270.32077)
		(mid 123.604051 -270.288246)
		(end 123.597416 -270.254984)
		(width 0.088646)
		(layer "In11.Cu")
		(net "M_H_CPU1_SA_DQS_DN<2>")
	)
	(arc
		(start 136.372092 -273.777456)
		(mid 136.184894 -273.827599)
		(end 135.997696 -273.777456)
		(width 0.088646)
		(layer "In11.Cu")
		(net "M_H_CPU1_SA_DQS_DN<2>")
	)
	(arc
		(start 130.641344 -272.617184)
		(mid 130.560433 -272.347056)
		(end 130.35915 -272.14957)
		(width 0.088646)
		(layer "In11.Cu")
		(net "M_H_CPU1_SA_DQS_DN<2>")
	)
	(arc
		(start 137.053828 -273.866356)
		(mid 136.997952 -273.81792)
		(end 136.936226 -273.777202)
		(width 0.088646)
		(layer "In11.Cu")
		(net "M_H_CPU1_SA_DQS_DN<2>")
	)
	(arc
		(start 131.29006 -273.772376)
		(mid 131.159146 -273.636016)
		(end 131.111498 -273.453098)
		(width 0.088646)
		(layer "In11.Cu")
		(net "M_H_CPU1_SA_DQS_DN<2>")
	)
	(arc
		(start 135.05815 -273.777456)
		(mid 134.783951 -273.701621)
		(end 134.507478 -273.76882)
		(width 0.088646)
		(layer "In11.Cu")
		(net "M_H_CPU1_SA_DQS_DN<2>")
	)
	(arc
		(start 130.819906 -272.95856)
		(mid 130.688992 -272.8222)
		(end 130.641344 -272.639282)
		(width 0.088646)
		(layer "In11.Cu")
		(net "M_H_CPU1_SA_DQS_DN<2>")
	)
	(arc
		(start 124.712984 -270.517874)
		(mid 124.433442 -270.44628)
		(end 124.154946 -270.521938)
		(width 0.088646)
		(layer "In11.Cu")
		(net "M_H_CPU1_SA_DQS_DN<2>")
	)
	(arc
		(start 133.552946 -273.777456)
		(mid 133.365748 -273.827599)
		(end 133.17855 -273.777456)
		(width 0.088646)
		(layer "In11.Cu")
		(net "M_H_CPU1_SA_DQS_DN<2>")
	)
	(arc
		(start 133.17855 -273.777456)
		(mid 132.895848 -273.70168)
		(end 132.613146 -273.777456)
		(width 0.088646)
		(layer "In11.Cu")
		(net "M_H_CPU1_SA_DQS_DN<2>")
	)
	(arc
		(start 130.171698 -271.825212)
		(mid 130.097707 -271.545646)
		(end 129.895092 -271.33931)
		(width 0.088646)
		(layer "In11.Cu")
		(net "M_H_CPU1_SA_DQS_DN<2>")
	)
	(arc
		(start 134.492746 -273.777456)
		(mid 134.305548 -273.827599)
		(end 134.11835 -273.777456)
		(width 0.088646)
		(layer "In11.Cu")
		(net "M_H_CPU1_SA_DQS_DN<2>")
	)
	(arc
		(start 126.034546 -270.521938)
		(mid 125.849993 -270.572197)
		(end 125.664722 -270.524732)
		(width 0.088646)
		(layer "In11.Cu")
		(net "M_H_CPU1_SA_DQS_DN<2>")
	)
	(arc
		(start 125.652784 -270.517874)
		(mid 125.373242 -270.44628)
		(end 125.094746 -270.521938)
		(width 0.088646)
		(layer "In11.Cu")
		(net "M_H_CPU1_SA_DQS_DN<2>")
	)
	(arc
		(start 128.47955 -270.521938)
		(mid 128.205351 -270.446103)
		(end 127.928878 -270.513302)
		(width 0.088646)
		(layer "In11.Cu")
		(net "M_H_CPU1_SA_DQS_DN<2>")
	)
	(arc
		(start 130.35026 -272.14449)
		(mid 130.223006 -272.014524)
		(end 130.171952 -271.839944)
		(width 0.088646)
		(layer "In11.Cu")
		(net "M_H_CPU1_SA_DQS_DN<2>")
	)
	(arc
		(start 128.940306 -271.330674)
		(mid 128.809392 -271.194314)
		(end 128.761744 -271.011396)
		(width 0.088646)
		(layer "In11.Cu")
		(net "M_H_CPU1_SA_DQS_DN<2>")
	)
	(arc
		(start 126.592584 -270.517874)
		(mid 126.313042 -270.44628)
		(end 126.034546 -270.521938)
		(width 0.088646)
		(layer "In11.Cu")
		(net "M_H_CPU1_SA_DQS_DN<2>")
	)
	(arc
		(start 131.111498 -273.453098)
		(mid 131.037507 -273.173532)
		(end 130.834892 -272.967196)
		(width 0.088646)
		(layer "In11.Cu")
		(net "M_H_CPU1_SA_DQS_DN<2>")
	)
	(arc
		(start 132.613146 -273.777456)
		(mid 132.425948 -273.827599)
		(end 132.23875 -273.777456)
		(width 0.088646)
		(layer "In11.Cu")
		(net "M_H_CPU1_SA_DQS_DN<2>")
	)
	(arc
		(start 136.936226 -273.777202)
		(mid 136.654113 -273.701841)
		(end 136.372092 -273.777456)
		(width 0.088646)
		(layer "In11.Cu")
		(net "M_H_CPU1_SA_DQS_DN<2>")
	)
	(arc
		(start 124.154946 -270.521938)
		(mid 123.970393 -270.572197)
		(end 123.785122 -270.524732)
		(width 0.088646)
		(layer "In11.Cu")
		(net "M_H_CPU1_SA_DQS_DN<2>")
	)
	(arc
		(start 123.779026 -270.521176)
		(mid 123.678441 -270.435753)
		(end 123.613672 -270.32077)
		(width 0.088646)
		(layer "In11.Cu")
		(net "M_H_CPU1_SA_DQS_DN<2>")
	)
	(arc
		(start 134.11835 -273.777456)
		(mid 133.844151 -273.701621)
		(end 133.567678 -273.76882)
		(width 0.088646)
		(layer "In11.Cu")
		(net "M_H_CPU1_SA_DQS_DN<2>")
	)
	(arc
		(start 135.432546 -273.777456)
		(mid 135.245348 -273.827599)
		(end 135.05815 -273.777456)
		(width 0.088646)
		(layer "In11.Cu")
		(net "M_H_CPU1_SA_DQS_DN<2>")
	)
	(arc
		(start 131.673346 -273.777456)
		(mid 131.486148 -273.827599)
		(end 131.29895 -273.777456)
		(width 0.088646)
		(layer "In11.Cu")
		(net "M_H_CPU1_SA_DQS_DN<2>")
	)
	(arc
		(start 129.323592 -271.335754)
		(mid 129.136394 -271.385897)
		(end 128.949196 -271.335754)
		(width 0.088646)
		(layer "In11.Cu")
		(net "M_H_CPU1_SA_DQS_DN<2>")
	)
	(arc
		(start 135.997696 -273.777456)
		(mid 135.721137 -273.701713)
		(end 135.44296 -273.77136)
		(width 0.088646)
		(layer "In11.Cu")
		(net "M_H_CPU1_SA_DQS_DN<2>")
	)
	(arc
		(start 129.874264 -271.327118)
		(mid 129.597789 -271.259798)
		(end 129.323592 -271.335754)
		(width 0.088646)
		(layer "In11.Cu")
		(net "M_H_CPU1_SA_DQS_DN<2>")
	)
	(arc
		(start 127.53975 -270.521938)
		(mid 127.265551 -270.446103)
		(end 126.989078 -270.513302)
		(width 0.088646)
		(layer "In11.Cu")
		(net "M_H_CPU1_SA_DQS_DN<2>")
	)
	(arc
		(start 132.23875 -273.777456)
		(mid 131.964551 -273.701621)
		(end 131.688078 -273.76882)
		(width 0.088646)
		(layer "In11.Cu")
		(net "M_H_CPU1_SA_DQS_DN<2>")
	)
	(arc
		(start 126.9746 -270.521938)
		(mid 126.789936 -270.572198)
		(end 126.604522 -270.524732)
		(width 0.088646)
		(layer "In11.Cu")
		(net "M_H_CPU1_SA_DQS_DN<2>")
	)
	(segment
		(start 206.056738 -303.412906)
		(end 206.578454 -303.412906)
		(width 0.20066)
		(layer "F.Cu")
		(net "M_H_CPU1_SA_DQS_DN<1>")
	)
	(segment
		(start 204.076046 -302.716692)
		(end 204.624686 -302.716692)
		(width 0.20066)
		(layer "F.Cu")
		(net "M_H_CPU1_SA_DQS_DN<1>")
	)
	(segment
		(start 209.51063 -303.1363)
		(end 209.742024 -303.367694)
		(width 0.20066)
		(layer "F.Cu")
		(net "M_H_CPU1_SA_DQS_DN<1>")
	)
	(segment
		(start 209.742024 -303.367694)
		(end 210.047078 -303.367694)
		(width 0.20066)
		(layer "F.Cu")
		(net "M_H_CPU1_SA_DQS_DN<1>")
	)
	(segment
		(start 209.181192 -303.141634)
		(end 209.186526 -303.1363)
		(width 0.1016)
		(layer "F.Cu")
		(net "M_H_CPU1_SA_DQS_DN<1>")
	)
	(segment
		(start 123.027948 -274.545044)
		(end 123.027948 -275.08073)
		(width 0.20066)
		(layer "F.Cu")
		(net "M_H_CPU1_SA_DQS_DN<1>")
	)
	(segment
		(start 207.001618 -303.141634)
		(end 209.181192 -303.141634)
		(width 0.1016)
		(layer "F.Cu")
		(net "M_H_CPU1_SA_DQS_DN<1>")
	)
	(segment
		(start 204.624686 -302.716692)
		(end 204.906372 -302.998378)
		(width 0.20066)
		(layer "F.Cu")
		(net "M_H_CPU1_SA_DQS_DN<1>")
	)
	(segment
		(start 205.64221 -302.998378)
		(end 206.056738 -303.412906)
		(width 0.20066)
		(layer "F.Cu")
		(net "M_H_CPU1_SA_DQS_DN<1>")
	)
	(segment
		(start 210.790028 -302.95723)
		(end 211.030566 -302.716692)
		(width 0.20066)
		(layer "F.Cu")
		(net "M_H_CPU1_SA_DQS_DN<1>")
	)
	(segment
		(start 206.849726 -303.141634)
		(end 206.9973 -303.141634)
		(width 0.20066)
		(layer "F.Cu")
		(net "M_H_CPU1_SA_DQS_DN<1>")
	)
	(segment
		(start 211.030566 -302.716692)
		(end 211.619846 -302.716692)
		(width 0.20066)
		(layer "F.Cu")
		(net "M_H_CPU1_SA_DQS_DN<1>")
	)
	(segment
		(start 210.457542 -302.95723)
		(end 210.790028 -302.95723)
		(width 0.20066)
		(layer "F.Cu")
		(net "M_H_CPU1_SA_DQS_DN<1>")
	)
	(segment
		(start 206.578454 -303.412906)
		(end 206.849726 -303.141634)
		(width 0.20066)
		(layer "F.Cu")
		(net "M_H_CPU1_SA_DQS_DN<1>")
	)
	(segment
		(start 206.9973 -303.141634)
		(end 207.001618 -303.141634)
		(width 0.101854)
		(layer "F.Cu")
		(net "M_H_CPU1_SA_DQS_DN<1>")
	)
	(segment
		(start 202.971146 -302.716692)
		(end 204.076046 -302.716692)
		(width 0.20066)
		(layer "F.Cu")
		(net "M_H_CPU1_SA_DQS_DN<1>")
	)
	(segment
		(start 209.186526 -303.1363)
		(end 209.51063 -303.1363)
		(width 0.20066)
		(layer "F.Cu")
		(net "M_H_CPU1_SA_DQS_DN<1>")
	)
	(segment
		(start 204.906372 -302.998378)
		(end 205.64221 -302.998378)
		(width 0.20066)
		(layer "F.Cu")
		(net "M_H_CPU1_SA_DQS_DN<1>")
	)
	(segment
		(start 210.047078 -303.367694)
		(end 210.457542 -302.95723)
		(width 0.20066)
		(layer "F.Cu")
		(net "M_H_CPU1_SA_DQS_DN<1>")
	)
	(segment
		(start 123.027694 -274.54479)
		(end 123.027948 -274.545044)
		(width 0.20066)
		(layer "F.Cu")
		(net "M_H_CPU1_SA_DQS_DN<1>")
	)
	(segment
		(start 123.59767 -275.02358)
		(end 123.54052 -275.08073)
		(width 0.088646)
		(layer "In11.Cu")
		(net "M_H_CPU1_SA_DQS_DN<1>")
	)
	(segment
		(start 126.129796 -277.198074)
		(end 126.141988 -277.190962)
		(width 0.088646)
		(layer "In11.Cu")
		(net "M_H_CPU1_SA_DQS_DN<1>")
	)
	(segment
		(start 157.541722 -308.262782)
		(end 154.019504 -304.740564)
		(width 0.18288)
		(layer "In11.Cu")
		(net "M_H_CPU1_SA_DQS_DN<1>")
	)
	(segment
		(start 138.860276 -283.116274)
		(end 138.782552 -283.116274)
		(width 0.088646)
		(layer "In11.Cu")
		(net "M_H_CPU1_SA_DQS_DN<1>")
	)
	(segment
		(start 154.019504 -300.56074)
		(end 145.621756 -292.162992)
		(width 0.18288)
		(layer "In11.Cu")
		(net "M_H_CPU1_SA_DQS_DN<1>")
	)
	(segment
		(start 128.947672 -279.473914)
		(end 128.940306 -279.469596)
		(width 0.088646)
		(layer "In11.Cu")
		(net "M_H_CPU1_SA_DQS_DN<1>")
	)
	(segment
		(start 179.535582 -309.489094)
		(end 178.711352 -309.489094)
		(width 0.18288)
		(layer "In11.Cu")
		(net "M_H_CPU1_SA_DQS_DN<1>")
	)
	(segment
		(start 202.11415 -302.795686)
		(end 201.3966 -302.795686)
		(width 0.18288)
		(layer "In11.Cu")
		(net "M_H_CPU1_SA_DQS_DN<1>")
	)
	(segment
		(start 175.548798 -310.230774)
		(end 173.532038 -311.06618)
		(width 0.18288)
		(layer "In11.Cu")
		(net "M_H_CPU1_SA_DQS_DN<1>")
	)
	(segment
		(start 202.305158 -302.986694)
		(end 202.11415 -302.795686)
		(width 0.18288)
		(layer "In11.Cu")
		(net "M_H_CPU1_SA_DQS_DN<1>")
	)
	(segment
		(start 133.648196 -279.474676)
		(end 133.637782 -279.46858)
		(width 0.088646)
		(layer "In11.Cu")
		(net "M_H_CPU1_SA_DQS_DN<1>")
	)
	(segment
		(start 195.662296 -308.459886)
		(end 195.27774 -308.459886)
		(width 0.18288)
		(layer "In11.Cu")
		(net "M_H_CPU1_SA_DQS_DN<1>")
	)
	(segment
		(start 191.71539 -309.940706)
		(end 191.458342 -310.197754)
		(width 0.18288)
		(layer "In11.Cu")
		(net "M_H_CPU1_SA_DQS_DN<1>")
	)
	(segment
		(start 168.91762 -309.107332)
		(end 168.166288 -308.356)
		(width 0.18288)
		(layer "In11.Cu")
		(net "M_H_CPU1_SA_DQS_DN<1>")
	)
	(segment
		(start 199.96023 -305.508152)
		(end 199.4154 -306.052982)
		(width 0.18288)
		(layer "In11.Cu")
		(net "M_H_CPU1_SA_DQS_DN<1>")
	)
	(segment
		(start 145.621756 -292.162992)
		(end 145.621756 -290.639754)
		(width 0.18288)
		(layer "In11.Cu")
		(net "M_H_CPU1_SA_DQS_DN<1>")
	)
	(segment
		(start 168.166288 -308.356)
		(end 165.337998 -308.356)
		(width 0.18288)
		(layer "In11.Cu")
		(net "M_H_CPU1_SA_DQS_DN<1>")
	)
	(segment
		(start 189.997588 -310.197754)
		(end 189.165992 -309.366158)
		(width 0.18288)
		(layer "In11.Cu")
		(net "M_H_CPU1_SA_DQS_DN<1>")
	)
	(segment
		(start 173.299882 -311.06618)
		(end 173.024546 -310.790844)
		(width 0.18288)
		(layer "In11.Cu")
		(net "M_H_CPU1_SA_DQS_DN<1>")
	)
	(segment
		(start 123.78055 -274.756372)
		(end 123.77166 -274.761452)
		(width 0.088646)
		(layer "In11.Cu")
		(net "M_H_CPU1_SA_DQS_DN<1>")
	)
	(segment
		(start 136.280144 -280.778204)
		(end 136.280144 -280.759662)
		(width 0.088646)
		(layer "In11.Cu")
		(net "M_H_CPU1_SA_DQS_DN<1>")
	)
	(segment
		(start 154.019504 -304.740564)
		(end 154.019504 -300.56074)
		(width 0.18288)
		(layer "In11.Cu")
		(net "M_H_CPU1_SA_DQS_DN<1>")
	)
	(segment
		(start 124.574046 -275.323046)
		(end 124.417582 -275.205698)
		(width 0.088646)
		(layer "In11.Cu")
		(net "M_H_CPU1_SA_DQS_DN<1>")
	)
	(segment
		(start 193.8655 -309.298086)
		(end 192.915794 -310.247792)
		(width 0.18288)
		(layer "In11.Cu")
		(net "M_H_CPU1_SA_DQS_DN<1>")
	)
	(segment
		(start 200.92416 -304.163476)
		(end 199.96023 -305.127406)
		(width 0.18288)
		(layer "In11.Cu")
		(net "M_H_CPU1_SA_DQS_DN<1>")
	)
	(segment
		(start 161.276792 -309.23103)
		(end 160.619694 -308.878732)
		(width 0.18288)
		(layer "In11.Cu")
		(net "M_H_CPU1_SA_DQS_DN<1>")
	)
	(segment
		(start 138.347196 -282.730194)
		(end 138.338306 -282.725114)
		(width 0.088646)
		(layer "In11.Cu")
		(net "M_H_CPU1_SA_DQS_DN<1>")
	)
	(segment
		(start 194.43954 -309.298086)
		(end 193.8655 -309.298086)
		(width 0.18288)
		(layer "In11.Cu")
		(net "M_H_CPU1_SA_DQS_DN<1>")
	)
	(segment
		(start 124.15647 -274.757134)
		(end 124.154946 -274.756372)
		(width 0.088646)
		(layer "In11.Cu")
		(net "M_H_CPU1_SA_DQS_DN<1>")
	)
	(segment
		(start 198.025258 -306.829206)
		(end 197.292976 -306.829206)
		(width 0.18288)
		(layer "In11.Cu")
		(net "M_H_CPU1_SA_DQS_DN<1>")
	)
	(segment
		(start 126.989078 -278.652224)
		(end 126.974346 -278.66086)
		(width 0.088646)
		(layer "In11.Cu")
		(net "M_H_CPU1_SA_DQS_DN<1>")
	)
	(segment
		(start 124.405898 -275.194014)
		(end 124.342398 -275.08073)
		(width 0.088646)
		(layer "In11.Cu")
		(net "M_H_CPU1_SA_DQS_DN<1>")
	)
	(segment
		(start 130.828796 -279.474676)
		(end 130.818382 -279.46858)
		(width 0.088646)
		(layer "In11.Cu")
		(net "M_H_CPU1_SA_DQS_DN<1>")
	)
	(segment
		(start 192.192402 -309.940706)
		(end 191.71539 -309.940706)
		(width 0.18288)
		(layer "In11.Cu")
		(net "M_H_CPU1_SA_DQS_DN<1>")
	)
	(segment
		(start 126.129796 -276.219158)
		(end 126.120906 -276.214078)
		(width 0.088646)
		(layer "In11.Cu")
		(net "M_H_CPU1_SA_DQS_DN<1>")
	)
	(segment
		(start 197.292976 -306.829206)
		(end 195.662296 -308.459886)
		(width 0.18288)
		(layer "In11.Cu")
		(net "M_H_CPU1_SA_DQS_DN<1>")
	)
	(segment
		(start 177.37201 -310.216042)
		(end 177.096674 -309.940706)
		(width 0.18288)
		(layer "In11.Cu")
		(net "M_H_CPU1_SA_DQS_DN<1>")
	)
	(segment
		(start 137.877296 -281.916378)
		(end 137.876534 -281.91587)
		(width 0.088646)
		(layer "In11.Cu")
		(net "M_H_CPU1_SA_DQS_DN<1>")
	)
	(segment
		(start 172.285914 -311.032652)
		(end 171.524168 -311.032652)
		(width 0.18288)
		(layer "In11.Cu")
		(net "M_H_CPU1_SA_DQS_DN<1>")
	)
	(segment
		(start 126.412498 -278.336502)
		(end 126.412498 -278.322278)
		(width 0.088646)
		(layer "In11.Cu")
		(net "M_H_CPU1_SA_DQS_DN<1>")
	)
	(segment
		(start 177.984404 -310.216042)
		(end 177.37201 -310.216042)
		(width 0.18288)
		(layer "In11.Cu")
		(net "M_H_CPU1_SA_DQS_DN<1>")
	)
	(segment
		(start 176.337722 -310.230774)
		(end 175.548798 -310.230774)
		(width 0.18288)
		(layer "In11.Cu")
		(net "M_H_CPU1_SA_DQS_DN<1>")
	)
	(segment
		(start 128.761744 -279.150318)
		(end 128.761744 -279.140412)
		(width 0.088646)
		(layer "In11.Cu")
		(net "M_H_CPU1_SA_DQS_DN<1>")
	)
	(segment
		(start 123.54052 -275.08073)
		(end 123.027948 -275.08073)
		(width 0.088646)
		(layer "In11.Cu")
		(net "M_H_CPU1_SA_DQS_DN<1>")
	)
	(segment
		(start 126.59995 -278.66086)
		(end 126.59106 -278.65578)
		(width 0.088646)
		(layer "In11.Cu")
		(net "M_H_CPU1_SA_DQS_DN<1>")
	)
	(segment
		(start 177.096674 -309.940706)
		(end 176.62779 -309.940706)
		(width 0.18288)
		(layer "In11.Cu")
		(net "M_H_CPU1_SA_DQS_DN<1>")
	)
	(segment
		(start 135.533892 -279.478232)
		(end 135.527796 -279.474676)
		(width 0.088646)
		(layer "In11.Cu")
		(net "M_H_CPU1_SA_DQS_DN<1>")
	)
	(segment
		(start 138.159744 -282.405836)
		(end 138.159744 -282.39593)
		(width 0.088646)
		(layer "In11.Cu")
		(net "M_H_CPU1_SA_DQS_DN<1>")
	)
	(segment
		(start 131.76885 -279.474676)
		(end 131.758436 -279.46858)
		(width 0.088646)
		(layer "In11.Cu")
		(net "M_H_CPU1_SA_DQS_DN<1>")
	)
	(segment
		(start 124.72035 -275.405088)
		(end 124.720096 -275.405088)
		(width 0.088646)
		(layer "In11.Cu")
		(net "M_H_CPU1_SA_DQS_DN<1>")
	)
	(segment
		(start 183.484266 -309.357776)
		(end 182.890922 -309.95112)
		(width 0.18288)
		(layer "In11.Cu")
		(net "M_H_CPU1_SA_DQS_DN<1>")
	)
	(segment
		(start 202.701144 -302.986694)
		(end 202.305158 -302.986694)
		(width 0.18288)
		(layer "In11.Cu")
		(net "M_H_CPU1_SA_DQS_DN<1>")
	)
	(segment
		(start 124.417582 -275.205698)
		(end 124.405898 -275.194014)
		(width 0.088646)
		(layer "In11.Cu")
		(net "M_H_CPU1_SA_DQS_DN<1>")
	)
	(segment
		(start 132.157978 -279.46604)
		(end 132.143246 -279.474676)
		(width 0.088646)
		(layer "In11.Cu")
		(net "M_H_CPU1_SA_DQS_DN<1>")
	)
	(segment
		(start 178.711352 -309.489094)
		(end 177.984404 -310.216042)
		(width 0.18288)
		(layer "In11.Cu")
		(net "M_H_CPU1_SA_DQS_DN<1>")
	)
	(segment
		(start 136.467596 -281.102562)
		(end 136.458706 -281.097482)
		(width 0.088646)
		(layer "In11.Cu")
		(net "M_H_CPU1_SA_DQS_DN<1>")
	)
	(segment
		(start 164.462968 -309.23103)
		(end 161.276792 -309.23103)
		(width 0.18288)
		(layer "In11.Cu")
		(net "M_H_CPU1_SA_DQS_DN<1>")
	)
	(segment
		(start 199.96023 -305.127406)
		(end 199.96023 -305.508152)
		(width 0.18288)
		(layer "In11.Cu")
		(net "M_H_CPU1_SA_DQS_DN<1>")
	)
	(segment
		(start 200.92416 -303.268126)
		(end 200.92416 -304.163476)
		(width 0.18288)
		(layer "In11.Cu")
		(net "M_H_CPU1_SA_DQS_DN<1>")
	)
	(segment
		(start 176.62779 -309.940706)
		(end 176.337722 -310.230774)
		(width 0.18288)
		(layer "In11.Cu")
		(net "M_H_CPU1_SA_DQS_DN<1>")
	)
	(segment
		(start 187.348368 -309.357776)
		(end 183.484266 -309.357776)
		(width 0.18288)
		(layer "In11.Cu")
		(net "M_H_CPU1_SA_DQS_DN<1>")
	)
	(segment
		(start 173.532038 -311.06618)
		(end 173.299882 -311.06618)
		(width 0.18288)
		(layer "In11.Cu")
		(net "M_H_CPU1_SA_DQS_DN<1>")
	)
	(segment
		(start 145.621756 -290.639754)
		(end 139.35583 -284.373828)
		(width 0.18288)
		(layer "In11.Cu")
		(net "M_H_CPU1_SA_DQS_DN<1>")
	)
	(segment
		(start 171.524168 -311.032652)
		(end 169.598848 -309.107332)
		(width 0.18288)
		(layer "In11.Cu")
		(net "M_H_CPU1_SA_DQS_DN<1>")
	)
	(segment
		(start 139.35583 -284.373828)
		(end 139.35583 -283.611828)
		(width 0.18288)
		(layer "In11.Cu")
		(net "M_H_CPU1_SA_DQS_DN<1>")
	)
	(segment
		(start 165.337998 -308.356)
		(end 164.462968 -309.23103)
		(width 0.18288)
		(layer "In11.Cu")
		(net "M_H_CPU1_SA_DQS_DN<1>")
	)
	(segment
		(start 124.719334 -275.40458)
		(end 124.574046 -275.323046)
		(width 0.088646)
		(layer "In11.Cu")
		(net "M_H_CPU1_SA_DQS_DN<1>")
	)
	(segment
		(start 191.458342 -310.197754)
		(end 189.997588 -310.197754)
		(width 0.18288)
		(layer "In11.Cu")
		(net "M_H_CPU1_SA_DQS_DN<1>")
	)
	(segment
		(start 139.35583 -283.611828)
		(end 138.860276 -283.116274)
		(width 0.18288)
		(layer "In11.Cu")
		(net "M_H_CPU1_SA_DQS_DN<1>")
	)
	(segment
		(start 169.598848 -309.107332)
		(end 168.91762 -309.107332)
		(width 0.18288)
		(layer "In11.Cu")
		(net "M_H_CPU1_SA_DQS_DN<1>")
	)
	(segment
		(start 124.720096 -275.405088)
		(end 124.719334 -275.40458)
		(width 0.088646)
		(layer "In11.Cu")
		(net "M_H_CPU1_SA_DQS_DN<1>")
	)
	(segment
		(start 138.782552 -283.116274)
		(end 138.706352 -283.040074)
		(width 0.088646)
		(layer "In11.Cu")
		(net "M_H_CPU1_SA_DQS_DN<1>")
	)
	(segment
		(start 173.024546 -310.790844)
		(end 172.527722 -310.790844)
		(width 0.18288)
		(layer "In11.Cu")
		(net "M_H_CPU1_SA_DQS_DN<1>")
	)
	(segment
		(start 134.977124 -279.46604)
		(end 134.962392 -279.474676)
		(width 0.088646)
		(layer "In11.Cu")
		(net "M_H_CPU1_SA_DQS_DN<1>")
	)
	(segment
		(start 192.915794 -310.247792)
		(end 192.499488 -310.247792)
		(width 0.18288)
		(layer "In11.Cu")
		(net "M_H_CPU1_SA_DQS_DN<1>")
	)
	(segment
		(start 198.801482 -306.052982)
		(end 198.025258 -306.829206)
		(width 0.18288)
		(layer "In11.Cu")
		(net "M_H_CPU1_SA_DQS_DN<1>")
	)
	(segment
		(start 125.942598 -277.531068)
		(end 125.942598 -277.513796)
		(width 0.088646)
		(layer "In11.Cu")
		(net "M_H_CPU1_SA_DQS_DN<1>")
	)
	(segment
		(start 137.689844 -281.59202)
		(end 137.689844 -281.582114)
		(width 0.088646)
		(layer "In11.Cu")
		(net "M_H_CPU1_SA_DQS_DN<1>")
	)
	(segment
		(start 135.997696 -280.288492)
		(end 135.988806 -280.283412)
		(width 0.088646)
		(layer "In11.Cu")
		(net "M_H_CPU1_SA_DQS_DN<1>")
	)
	(segment
		(start 128.949196 -279.474676)
		(end 128.947672 -279.473914)
		(width 0.088646)
		(layer "In11.Cu")
		(net "M_H_CPU1_SA_DQS_DN<1>")
	)
	(segment
		(start 127.92456 -278.654764)
		(end 127.914146 -278.66086)
		(width 0.088646)
		(layer "In11.Cu")
		(net "M_H_CPU1_SA_DQS_DN<1>")
	)
	(segment
		(start 182.890922 -309.95112)
		(end 179.997608 -309.95112)
		(width 0.18288)
		(layer "In11.Cu")
		(net "M_H_CPU1_SA_DQS_DN<1>")
	)
	(segment
		(start 160.619694 -308.878732)
		(end 157.541722 -308.262782)
		(width 0.18288)
		(layer "In11.Cu")
		(net "M_H_CPU1_SA_DQS_DN<1>")
	)
	(segment
		(start 134.587996 -279.474676)
		(end 134.573264 -279.46604)
		(width 0.088646)
		(layer "In11.Cu")
		(net "M_H_CPU1_SA_DQS_DN<1>")
	)
	(segment
		(start 187.613544 -309.0926)
		(end 187.348368 -309.357776)
		(width 0.18288)
		(layer "In11.Cu")
		(net "M_H_CPU1_SA_DQS_DN<1>")
	)
	(segment
		(start 126.141988 -276.22627)
		(end 126.13386 -276.221444)
		(width 0.088646)
		(layer "In11.Cu")
		(net "M_H_CPU1_SA_DQS_DN<1>")
	)
	(segment
		(start 125.942344 -275.8948)
		(end 125.942344 -275.872702)
		(width 0.088646)
		(layer "In11.Cu")
		(net "M_H_CPU1_SA_DQS_DN<1>")
	)
	(segment
		(start 172.527722 -310.790844)
		(end 172.285914 -311.032652)
		(width 0.18288)
		(layer "In11.Cu")
		(net "M_H_CPU1_SA_DQS_DN<1>")
	)
	(segment
		(start 187.972192 -309.090822)
		(end 187.970414 -309.0926)
		(width 0.18288)
		(layer "In11.Cu")
		(net "M_H_CPU1_SA_DQS_DN<1>")
	)
	(segment
		(start 129.88925 -279.474676)
		(end 129.878836 -279.46858)
		(width 0.088646)
		(layer "In11.Cu")
		(net "M_H_CPU1_SA_DQS_DN<1>")
	)
	(segment
		(start 179.997608 -309.95112)
		(end 179.535582 -309.489094)
		(width 0.18288)
		(layer "In11.Cu")
		(net "M_H_CPU1_SA_DQS_DN<1>")
	)
	(segment
		(start 202.971146 -302.716692)
		(end 202.701144 -302.986694)
		(width 0.18288)
		(layer "In11.Cu")
		(net "M_H_CPU1_SA_DQS_DN<1>")
	)
	(segment
		(start 188.08065 -309.090822)
		(end 187.972192 -309.090822)
		(width 0.18288)
		(layer "In11.Cu")
		(net "M_H_CPU1_SA_DQS_DN<1>")
	)
	(segment
		(start 189.165992 -309.366158)
		(end 188.355986 -309.366158)
		(width 0.18288)
		(layer "In11.Cu")
		(net "M_H_CPU1_SA_DQS_DN<1>")
	)
	(segment
		(start 201.3966 -302.795686)
		(end 200.92416 -303.268126)
		(width 0.18288)
		(layer "In11.Cu")
		(net "M_H_CPU1_SA_DQS_DN<1>")
	)
	(segment
		(start 188.355986 -309.366158)
		(end 188.08065 -309.090822)
		(width 0.18288)
		(layer "In11.Cu")
		(net "M_H_CPU1_SA_DQS_DN<1>")
	)
	(segment
		(start 126.13386 -276.221444)
		(end 126.129796 -276.219158)
		(width 0.088646)
		(layer "In11.Cu")
		(net "M_H_CPU1_SA_DQS_DN<1>")
	)
	(segment
		(start 192.499488 -310.247792)
		(end 192.192402 -309.940706)
		(width 0.18288)
		(layer "In11.Cu")
		(net "M_H_CPU1_SA_DQS_DN<1>")
	)
	(segment
		(start 187.970414 -309.0926)
		(end 187.613544 -309.0926)
		(width 0.18288)
		(layer "In11.Cu")
		(net "M_H_CPU1_SA_DQS_DN<1>")
	)
	(segment
		(start 125.109478 -275.396452)
		(end 125.094746 -275.405088)
		(width 0.088646)
		(layer "In11.Cu")
		(net "M_H_CPU1_SA_DQS_DN<1>")
	)
	(segment
		(start 137.876534 -281.91587)
		(end 137.868406 -281.911298)
		(width 0.088646)
		(layer "In11.Cu")
		(net "M_H_CPU1_SA_DQS_DN<1>")
	)
	(segment
		(start 138.426698 -282.78582)
		(end 138.426444 -282.785312)
		(width 0.088646)
		(layer "In11.Cu")
		(net "M_H_CPU1_SA_DQS_DN<1>")
	)
	(segment
		(start 195.27774 -308.459886)
		(end 194.43954 -309.298086)
		(width 0.18288)
		(layer "In11.Cu")
		(net "M_H_CPU1_SA_DQS_DN<1>")
	)
	(segment
		(start 199.4154 -306.052982)
		(end 198.801482 -306.052982)
		(width 0.18288)
		(layer "In11.Cu")
		(net "M_H_CPU1_SA_DQS_DN<1>")
	)
	(arc
		(start 136.841992 -281.102562)
		(mid 136.654794 -281.152705)
		(end 136.467596 -281.102562)
		(width 0.088646)
		(layer "In11.Cu")
		(net "M_H_CPU1_SA_DQS_DN<1>")
	)
	(arc
		(start 137.868406 -281.911298)
		(mid 137.737492 -281.774938)
		(end 137.689844 -281.59202)
		(width 0.088646)
		(layer "In11.Cu")
		(net "M_H_CPU1_SA_DQS_DN<1>")
	)
	(arc
		(start 135.988806 -280.283412)
		(mid 135.857892 -280.147052)
		(end 135.810244 -279.964134)
		(width 0.088646)
		(layer "In11.Cu")
		(net "M_H_CPU1_SA_DQS_DN<1>")
	)
	(arc
		(start 138.426444 -282.785312)
		(mid 138.387997 -282.756061)
		(end 138.347196 -282.730194)
		(width 0.088646)
		(layer "In11.Cu")
		(net "M_H_CPU1_SA_DQS_DN<1>")
	)
	(arc
		(start 128.479296 -278.66086)
		(mid 128.202737 -278.585117)
		(end 127.92456 -278.654764)
		(width 0.088646)
		(layer "In11.Cu")
		(net "M_H_CPU1_SA_DQS_DN<1>")
	)
	(arc
		(start 136.280144 -280.759662)
		(mid 136.199982 -280.487473)
		(end 135.997696 -280.288492)
		(width 0.088646)
		(layer "In11.Cu")
		(net "M_H_CPU1_SA_DQS_DN<1>")
	)
	(arc
		(start 123.77166 -274.761452)
		(mid 123.655851 -274.873381)
		(end 123.59767 -275.02358)
		(width 0.088646)
		(layer "In11.Cu")
		(net "M_H_CPU1_SA_DQS_DN<1>")
	)
	(arc
		(start 133.637782 -279.46858)
		(mid 133.359604 -279.398857)
		(end 133.083046 -279.474676)
		(width 0.088646)
		(layer "In11.Cu")
		(net "M_H_CPU1_SA_DQS_DN<1>")
	)
	(arc
		(start 128.761744 -279.140412)
		(mid 128.683633 -278.863463)
		(end 128.479296 -278.66086)
		(width 0.088646)
		(layer "In11.Cu")
		(net "M_H_CPU1_SA_DQS_DN<1>")
	)
	(arc
		(start 125.942344 -275.872702)
		(mid 125.861433 -275.602574)
		(end 125.66015 -275.405088)
		(width 0.088646)
		(layer "In11.Cu")
		(net "M_H_CPU1_SA_DQS_DN<1>")
	)
	(arc
		(start 134.022592 -279.474676)
		(mid 133.835394 -279.524819)
		(end 133.648196 -279.474676)
		(width 0.088646)
		(layer "In11.Cu")
		(net "M_H_CPU1_SA_DQS_DN<1>")
	)
	(arc
		(start 127.53975 -278.66086)
		(mid 127.265551 -278.585025)
		(end 126.989078 -278.652224)
		(width 0.088646)
		(layer "In11.Cu")
		(net "M_H_CPU1_SA_DQS_DN<1>")
	)
	(arc
		(start 138.706352 -283.040074)
		(mid 138.569543 -282.909627)
		(end 138.426698 -282.78582)
		(width 0.088646)
		(layer "In11.Cu")
		(net "M_H_CPU1_SA_DQS_DN<1>")
	)
	(arc
		(start 131.758436 -279.46858)
		(mid 131.480004 -279.398734)
		(end 131.203192 -279.474676)
		(width 0.088646)
		(layer "In11.Cu")
		(net "M_H_CPU1_SA_DQS_DN<1>")
	)
	(arc
		(start 126.59106 -278.65578)
		(mid 126.460146 -278.51942)
		(end 126.412498 -278.336502)
		(width 0.088646)
		(layer "In11.Cu")
		(net "M_H_CPU1_SA_DQS_DN<1>")
	)
	(arc
		(start 125.942598 -277.513796)
		(mid 125.994868 -277.331431)
		(end 126.129796 -277.198074)
		(width 0.088646)
		(layer "In11.Cu")
		(net "M_H_CPU1_SA_DQS_DN<1>")
	)
	(arc
		(start 129.323592 -279.474676)
		(mid 129.136394 -279.524819)
		(end 128.949196 -279.474676)
		(width 0.088646)
		(layer "In11.Cu")
		(net "M_H_CPU1_SA_DQS_DN<1>")
	)
	(arc
		(start 136.458706 -281.097482)
		(mid 136.327792 -280.961122)
		(end 136.280144 -280.778204)
		(width 0.088646)
		(layer "In11.Cu")
		(net "M_H_CPU1_SA_DQS_DN<1>")
	)
	(arc
		(start 125.094746 -275.405088)
		(mid 124.907548 -275.455231)
		(end 124.72035 -275.405088)
		(width 0.088646)
		(layer "In11.Cu")
		(net "M_H_CPU1_SA_DQS_DN<1>")
	)
	(arc
		(start 132.143246 -279.474676)
		(mid 131.956048 -279.524819)
		(end 131.76885 -279.474676)
		(width 0.088646)
		(layer "In11.Cu")
		(net "M_H_CPU1_SA_DQS_DN<1>")
	)
	(arc
		(start 129.878836 -279.46858)
		(mid 129.600404 -279.398734)
		(end 129.323592 -279.474676)
		(width 0.088646)
		(layer "In11.Cu")
		(net "M_H_CPU1_SA_DQS_DN<1>")
	)
	(arc
		(start 124.342398 -275.08073)
		(mid 124.292614 -274.894116)
		(end 124.15647 -274.757134)
		(width 0.088646)
		(layer "In11.Cu")
		(net "M_H_CPU1_SA_DQS_DN<1>")
	)
	(arc
		(start 135.810244 -279.964134)
		(mid 135.736328 -279.684632)
		(end 135.533892 -279.478232)
		(width 0.088646)
		(layer "In11.Cu")
		(net "M_H_CPU1_SA_DQS_DN<1>")
	)
	(arc
		(start 128.940306 -279.469596)
		(mid 128.809392 -279.333236)
		(end 128.761744 -279.150318)
		(width 0.088646)
		(layer "In11.Cu")
		(net "M_H_CPU1_SA_DQS_DN<1>")
	)
	(arc
		(start 126.141988 -277.190962)
		(mid 126.412444 -276.708616)
		(end 126.141988 -276.22627)
		(width 0.088646)
		(layer "In11.Cu")
		(net "M_H_CPU1_SA_DQS_DN<1>")
	)
	(arc
		(start 137.407396 -281.102562)
		(mid 137.124694 -281.026786)
		(end 136.841992 -281.102562)
		(width 0.088646)
		(layer "In11.Cu")
		(net "M_H_CPU1_SA_DQS_DN<1>")
	)
	(arc
		(start 134.573264 -279.46604)
		(mid 134.296789 -279.39872)
		(end 134.022592 -279.474676)
		(width 0.088646)
		(layer "In11.Cu")
		(net "M_H_CPU1_SA_DQS_DN<1>")
	)
	(arc
		(start 135.527796 -279.474676)
		(mid 135.253597 -279.398841)
		(end 134.977124 -279.46604)
		(width 0.088646)
		(layer "In11.Cu")
		(net "M_H_CPU1_SA_DQS_DN<1>")
	)
	(arc
		(start 126.974346 -278.66086)
		(mid 126.787148 -278.711003)
		(end 126.59995 -278.66086)
		(width 0.088646)
		(layer "In11.Cu")
		(net "M_H_CPU1_SA_DQS_DN<1>")
	)
	(arc
		(start 126.412498 -278.322278)
		(mid 126.333279 -278.047593)
		(end 126.129796 -277.84679)
		(width 0.088646)
		(layer "In11.Cu")
		(net "M_H_CPU1_SA_DQS_DN<1>")
	)
	(arc
		(start 124.154946 -274.756372)
		(mid 123.967748 -274.706229)
		(end 123.78055 -274.756372)
		(width 0.088646)
		(layer "In11.Cu")
		(net "M_H_CPU1_SA_DQS_DN<1>")
	)
	(arc
		(start 131.203192 -279.474676)
		(mid 131.015994 -279.524819)
		(end 130.828796 -279.474676)
		(width 0.088646)
		(layer "In11.Cu")
		(net "M_H_CPU1_SA_DQS_DN<1>")
	)
	(arc
		(start 138.159744 -282.39593)
		(mid 138.081633 -282.118981)
		(end 137.877296 -281.916378)
		(width 0.088646)
		(layer "In11.Cu")
		(net "M_H_CPU1_SA_DQS_DN<1>")
	)
	(arc
		(start 130.818382 -279.46858)
		(mid 130.540204 -279.398857)
		(end 130.263646 -279.474676)
		(width 0.088646)
		(layer "In11.Cu")
		(net "M_H_CPU1_SA_DQS_DN<1>")
	)
	(arc
		(start 132.70865 -279.474676)
		(mid 132.434451 -279.398841)
		(end 132.157978 -279.46604)
		(width 0.088646)
		(layer "In11.Cu")
		(net "M_H_CPU1_SA_DQS_DN<1>")
	)
	(arc
		(start 126.120906 -276.214078)
		(mid 125.989992 -276.077718)
		(end 125.942344 -275.8948)
		(width 0.088646)
		(layer "In11.Cu")
		(net "M_H_CPU1_SA_DQS_DN<1>")
	)
	(arc
		(start 138.338306 -282.725114)
		(mid 138.207392 -282.588754)
		(end 138.159744 -282.405836)
		(width 0.088646)
		(layer "In11.Cu")
		(net "M_H_CPU1_SA_DQS_DN<1>")
	)
	(arc
		(start 126.129796 -277.84679)
		(mid 125.994863 -277.713436)
		(end 125.942598 -277.531068)
		(width 0.088646)
		(layer "In11.Cu")
		(net "M_H_CPU1_SA_DQS_DN<1>")
	)
	(arc
		(start 127.914146 -278.66086)
		(mid 127.726948 -278.711003)
		(end 127.53975 -278.66086)
		(width 0.088646)
		(layer "In11.Cu")
		(net "M_H_CPU1_SA_DQS_DN<1>")
	)
	(arc
		(start 137.689844 -281.582114)
		(mid 137.611733 -281.305165)
		(end 137.407396 -281.102562)
		(width 0.088646)
		(layer "In11.Cu")
		(net "M_H_CPU1_SA_DQS_DN<1>")
	)
	(arc
		(start 134.962392 -279.474676)
		(mid 134.775194 -279.524819)
		(end 134.587996 -279.474676)
		(width 0.088646)
		(layer "In11.Cu")
		(net "M_H_CPU1_SA_DQS_DN<1>")
	)
	(arc
		(start 130.263646 -279.474676)
		(mid 130.076448 -279.524819)
		(end 129.88925 -279.474676)
		(width 0.088646)
		(layer "In11.Cu")
		(net "M_H_CPU1_SA_DQS_DN<1>")
	)
	(arc
		(start 125.66015 -275.405088)
		(mid 125.385921 -275.329163)
		(end 125.109478 -275.396452)
		(width 0.088646)
		(layer "In11.Cu")
		(net "M_H_CPU1_SA_DQS_DN<1>")
	)
	(arc
		(start 133.083046 -279.474676)
		(mid 132.895848 -279.524819)
		(end 132.70865 -279.474676)
		(width 0.088646)
		(layer "In11.Cu")
		(net "M_H_CPU1_SA_DQS_DN<1>")
	)
	(segment
		(start 209.186526 -312.486294)
		(end 209.51063 -312.486294)
		(width 0.20066)
		(layer "F.Cu")
		(net "M_H_CPU1_SA_DQS_DN<0>")
	)
	(segment
		(start 209.181192 -312.491628)
		(end 209.186526 -312.486294)
		(width 0.1016)
		(layer "F.Cu")
		(net "M_H_CPU1_SA_DQS_DN<0>")
	)
	(segment
		(start 206.849726 -312.491628)
		(end 206.9973 -312.491628)
		(width 0.20066)
		(layer "F.Cu")
		(net "M_H_CPU1_SA_DQS_DN<0>")
	)
	(segment
		(start 206.578454 -312.7629)
		(end 206.849726 -312.491628)
		(width 0.20066)
		(layer "F.Cu")
		(net "M_H_CPU1_SA_DQS_DN<0>")
	)
	(segment
		(start 211.030566 -312.066686)
		(end 211.619846 -312.066686)
		(width 0.20066)
		(layer "F.Cu")
		(net "M_H_CPU1_SA_DQS_DN<0>")
	)
	(segment
		(start 207.001618 -312.491628)
		(end 209.181192 -312.491628)
		(width 0.1016)
		(layer "F.Cu")
		(net "M_H_CPU1_SA_DQS_DN<0>")
	)
	(segment
		(start 206.9973 -312.491628)
		(end 207.001618 -312.491628)
		(width 0.101854)
		(layer "F.Cu")
		(net "M_H_CPU1_SA_DQS_DN<0>")
	)
	(segment
		(start 209.51063 -312.486294)
		(end 209.742024 -312.717688)
		(width 0.20066)
		(layer "F.Cu")
		(net "M_H_CPU1_SA_DQS_DN<0>")
	)
	(segment
		(start 210.790028 -312.307224)
		(end 211.030566 -312.066686)
		(width 0.20066)
		(layer "F.Cu")
		(net "M_H_CPU1_SA_DQS_DN<0>")
	)
	(segment
		(start 205.64221 -312.348372)
		(end 206.056738 -312.7629)
		(width 0.20066)
		(layer "F.Cu")
		(net "M_H_CPU1_SA_DQS_DN<0>")
	)
	(segment
		(start 210.047078 -312.717688)
		(end 210.457542 -312.307224)
		(width 0.20066)
		(layer "F.Cu")
		(net "M_H_CPU1_SA_DQS_DN<0>")
	)
	(segment
		(start 204.076046 -312.066686)
		(end 204.624686 -312.066686)
		(width 0.20066)
		(layer "F.Cu")
		(net "M_H_CPU1_SA_DQS_DN<0>")
	)
	(segment
		(start 202.971146 -312.066686)
		(end 204.076046 -312.066686)
		(width 0.20066)
		(layer "F.Cu")
		(net "M_H_CPU1_SA_DQS_DN<0>")
	)
	(segment
		(start 204.624686 -312.066686)
		(end 204.906372 -312.348372)
		(width 0.20066)
		(layer "F.Cu")
		(net "M_H_CPU1_SA_DQS_DN<0>")
	)
	(segment
		(start 126.317248 -276.986492)
		(end 126.317248 -277.522178)
		(width 0.20066)
		(layer "F.Cu")
		(net "M_H_CPU1_SA_DQS_DN<0>")
	)
	(segment
		(start 206.056738 -312.7629)
		(end 206.578454 -312.7629)
		(width 0.20066)
		(layer "F.Cu")
		(net "M_H_CPU1_SA_DQS_DN<0>")
	)
	(segment
		(start 210.457542 -312.307224)
		(end 210.790028 -312.307224)
		(width 0.20066)
		(layer "F.Cu")
		(net "M_H_CPU1_SA_DQS_DN<0>")
	)
	(segment
		(start 209.742024 -312.717688)
		(end 210.047078 -312.717688)
		(width 0.20066)
		(layer "F.Cu")
		(net "M_H_CPU1_SA_DQS_DN<0>")
	)
	(segment
		(start 204.906372 -312.348372)
		(end 205.64221 -312.348372)
		(width 0.20066)
		(layer "F.Cu")
		(net "M_H_CPU1_SA_DQS_DN<0>")
	)
	(segment
		(start 126.317248 -277.522178)
		(end 126.316994 -277.522432)
		(width 0.20066)
		(layer "F.Cu")
		(net "M_H_CPU1_SA_DQS_DN<0>")
	)
	(segment
		(start 173.253908 -309.364888)
		(end 172.98162 -309.0926)
		(width 0.18288)
		(layer "In6.Cu")
		(net "M_H_CPU1_SA_DQS_DN<0>")
	)
	(segment
		(start 162.267392 -305.107848)
		(end 162.002216 -304.842672)
		(width 0.18288)
		(layer "In6.Cu")
		(net "M_H_CPU1_SA_DQS_DN<0>")
	)
	(segment
		(start 140.34389 -280.808938)
		(end 140.2842 -280.868628)
		(width 0.088646)
		(layer "In6.Cu")
		(net "M_H_CPU1_SA_DQS_DN<0>")
	)
	(segment
		(start 129.88925 -277.84679)
		(end 129.878836 -277.840694)
		(width 0.088646)
		(layer "In6.Cu")
		(net "M_H_CPU1_SA_DQS_DN<0>")
	)
	(segment
		(start 128.949196 -277.84679)
		(end 128.934464 -277.838154)
		(width 0.088646)
		(layer "In6.Cu")
		(net "M_H_CPU1_SA_DQS_DN<0>")
	)
	(segment
		(start 192.438274 -312.770774)
		(end 192.160144 -312.492644)
		(width 0.18288)
		(layer "In6.Cu")
		(net "M_H_CPU1_SA_DQS_DN<0>")
	)
	(segment
		(start 161.62782 -304.842672)
		(end 161.348674 -305.121818)
		(width 0.18288)
		(layer "In6.Cu")
		(net "M_H_CPU1_SA_DQS_DN<0>")
	)
	(segment
		(start 187.696094 -313.34075)
		(end 187.428632 -313.608212)
		(width 0.18288)
		(layer "In6.Cu")
		(net "M_H_CPU1_SA_DQS_DN<0>")
	)
	(segment
		(start 202.710034 -312.327798)
		(end 202.227434 -312.327798)
		(width 0.18288)
		(layer "In6.Cu")
		(net "M_H_CPU1_SA_DQS_DN<0>")
	)
	(segment
		(start 182.46598 -311.891426)
		(end 180.74132 -310.166766)
		(width 0.18288)
		(layer "In6.Cu")
		(net "M_H_CPU1_SA_DQS_DN<0>")
	)
	(segment
		(start 159.28467 -305.121818)
		(end 158.440628 -305.96586)
		(width 0.18288)
		(layer "In6.Cu")
		(net "M_H_CPU1_SA_DQS_DN<0>")
	)
	(segment
		(start 201.78141 -311.881774)
		(end 198.959978 -311.881774)
		(width 0.18288)
		(layer "In6.Cu")
		(net "M_H_CPU1_SA_DQS_DN<0>")
	)
	(segment
		(start 158.440628 -305.96586)
		(end 158.181548 -305.96586)
		(width 0.18288)
		(layer "In6.Cu")
		(net "M_H_CPU1_SA_DQS_DN<0>")
	)
	(segment
		(start 180.001672 -310.166766)
		(end 178.348386 -308.51348)
		(width 0.18288)
		(layer "In6.Cu")
		(net "M_H_CPU1_SA_DQS_DN<0>")
	)
	(segment
		(start 164.596572 -306.46243)
		(end 163.24199 -305.107848)
		(width 0.18288)
		(layer "In6.Cu")
		(net "M_H_CPU1_SA_DQS_DN<0>")
	)
	(segment
		(start 127.768604 -277.469092)
		(end 127.663702 -277.36419)
		(width 0.088646)
		(layer "In6.Cu")
		(net "M_H_CPU1_SA_DQS_DN<0>")
	)
	(segment
		(start 202.227434 -312.327798)
		(end 201.78141 -311.881774)
		(width 0.18288)
		(layer "In6.Cu")
		(net "M_H_CPU1_SA_DQS_DN<0>")
	)
	(segment
		(start 158.181548 -305.96586)
		(end 157.910784 -305.695096)
		(width 0.18288)
		(layer "In6.Cu")
		(net "M_H_CPU1_SA_DQS_DN<0>")
	)
	(segment
		(start 177.07356 -308.242462)
		(end 176.71288 -308.242462)
		(width 0.18288)
		(layer "In6.Cu")
		(net "M_H_CPU1_SA_DQS_DN<0>")
	)
	(segment
		(start 157.50159 -305.695096)
		(end 157.252162 -305.944524)
		(width 0.18288)
		(layer "In6.Cu")
		(net "M_H_CPU1_SA_DQS_DN<0>")
	)
	(segment
		(start 168.90873 -309.344314)
		(end 164.596572 -306.46243)
		(width 0.18288)
		(layer "In6.Cu")
		(net "M_H_CPU1_SA_DQS_DN<0>")
	)
	(segment
		(start 192.160144 -312.492644)
		(end 191.809624 -312.492644)
		(width 0.18288)
		(layer "In6.Cu")
		(net "M_H_CPU1_SA_DQS_DN<0>")
	)
	(segment
		(start 145.487898 -280.808938)
		(end 140.367258 -280.808938)
		(width 0.18288)
		(layer "In6.Cu")
		(net "M_H_CPU1_SA_DQS_DN<0>")
	)
	(segment
		(start 126.829566 -277.522432)
		(end 126.316994 -277.522432)
		(width 0.088646)
		(layer "In6.Cu")
		(net "M_H_CPU1_SA_DQS_DN<0>")
	)
	(segment
		(start 136.467596 -277.84679)
		(end 136.457182 -277.840694)
		(width 0.088646)
		(layer "In6.Cu")
		(net "M_H_CPU1_SA_DQS_DN<0>")
	)
	(segment
		(start 177.344578 -308.51348)
		(end 177.07356 -308.242462)
		(width 0.18288)
		(layer "In6.Cu")
		(net "M_H_CPU1_SA_DQS_DN<0>")
	)
	(segment
		(start 192.981072 -312.770774)
		(end 192.438274 -312.770774)
		(width 0.18288)
		(layer "In6.Cu")
		(net "M_H_CPU1_SA_DQS_DN<0>")
	)
	(segment
		(start 140.221462 -280.868628)
		(end 140.134594 -280.781506)
		(width 0.088646)
		(layer "In6.Cu")
		(net "M_H_CPU1_SA_DQS_DN<0>")
	)
	(segment
		(start 133.648196 -277.84679)
		(end 133.633464 -277.838154)
		(width 0.088646)
		(layer "In6.Cu")
		(net "M_H_CPU1_SA_DQS_DN<0>")
	)
	(segment
		(start 148.164042 -283.485082)
		(end 145.487898 -280.808938)
		(width 0.18288)
		(layer "In6.Cu")
		(net "M_H_CPU1_SA_DQS_DN<0>")
	)
	(segment
		(start 189.504828 -312.770774)
		(end 188.665866 -313.609736)
		(width 0.18288)
		(layer "In6.Cu")
		(net "M_H_CPU1_SA_DQS_DN<0>")
	)
	(segment
		(start 156.887672 -305.944524)
		(end 156.02839 -305.085242)
		(width 0.18288)
		(layer "In6.Cu")
		(net "M_H_CPU1_SA_DQS_DN<0>")
	)
	(segment
		(start 196.415152 -312.001154)
		(end 193.750692 -312.001154)
		(width 0.18288)
		(layer "In6.Cu")
		(net "M_H_CPU1_SA_DQS_DN<0>")
	)
	(segment
		(start 140.367258 -280.808938)
		(end 140.34389 -280.808938)
		(width 0.088646)
		(layer "In6.Cu")
		(net "M_H_CPU1_SA_DQS_DN<0>")
	)
	(segment
		(start 140.134594 -280.781506)
		(end 139.842748 -280.237184)
		(width 0.088646)
		(layer "In6.Cu")
		(net "M_H_CPU1_SA_DQS_DN<0>")
	)
	(segment
		(start 176.71288 -308.242462)
		(end 176.451768 -308.503574)
		(width 0.18288)
		(layer "In6.Cu")
		(net "M_H_CPU1_SA_DQS_DN<0>")
	)
	(segment
		(start 172.357542 -309.344314)
		(end 168.90873 -309.344314)
		(width 0.18288)
		(layer "In6.Cu")
		(net "M_H_CPU1_SA_DQS_DN<0>")
	)
	(segment
		(start 139.532106 -279.6921)
		(end 139.40155 -279.562052)
		(width 0.088646)
		(layer "In6.Cu")
		(net "M_H_CPU1_SA_DQS_DN<0>")
	)
	(segment
		(start 196.969126 -312.555128)
		(end 196.415152 -312.001154)
		(width 0.18288)
		(layer "In6.Cu")
		(net "M_H_CPU1_SA_DQS_DN<0>")
	)
	(segment
		(start 130.278378 -277.838154)
		(end 130.263646 -277.84679)
		(width 0.088646)
		(layer "In6.Cu")
		(net "M_H_CPU1_SA_DQS_DN<0>")
	)
	(segment
		(start 138.721846 -279.47493)
		(end 138.721592 -279.474676)
		(width 0.088646)
		(layer "In6.Cu")
		(net "M_H_CPU1_SA_DQS_DN<0>")
	)
	(segment
		(start 148.164042 -293.104316)
		(end 148.164042 -283.485082)
		(width 0.18288)
		(layer "In6.Cu")
		(net "M_H_CPU1_SA_DQS_DN<0>")
	)
	(segment
		(start 187.428632 -313.608212)
		(end 186.22137 -313.608212)
		(width 0.18288)
		(layer "In6.Cu")
		(net "M_H_CPU1_SA_DQS_DN<0>")
	)
	(segment
		(start 193.750692 -312.001154)
		(end 192.981072 -312.770774)
		(width 0.18288)
		(layer "In6.Cu")
		(net "M_H_CPU1_SA_DQS_DN<0>")
	)
	(segment
		(start 135.527542 -277.84679)
		(end 135.517128 -277.840694)
		(width 0.088646)
		(layer "In6.Cu")
		(net "M_H_CPU1_SA_DQS_DN<0>")
	)
	(segment
		(start 137.877296 -278.66086)
		(end 137.868406 -278.65578)
		(width 0.088646)
		(layer "In6.Cu")
		(net "M_H_CPU1_SA_DQS_DN<0>")
	)
	(segment
		(start 178.348386 -308.51348)
		(end 177.344578 -308.51348)
		(width 0.18288)
		(layer "In6.Cu")
		(net "M_H_CPU1_SA_DQS_DN<0>")
	)
	(segment
		(start 191.531494 -312.770774)
		(end 189.504828 -312.770774)
		(width 0.18288)
		(layer "In6.Cu")
		(net "M_H_CPU1_SA_DQS_DN<0>")
	)
	(segment
		(start 163.24199 -305.107848)
		(end 162.267392 -305.107848)
		(width 0.18288)
		(layer "In6.Cu")
		(net "M_H_CPU1_SA_DQS_DN<0>")
	)
	(segment
		(start 132.708396 -277.84679)
		(end 132.693664 -277.838154)
		(width 0.088646)
		(layer "In6.Cu")
		(net "M_H_CPU1_SA_DQS_DN<0>")
	)
	(segment
		(start 127.452882 -277.203154)
		(end 127.443992 -277.198074)
		(width 0.088646)
		(layer "In6.Cu")
		(net "M_H_CPU1_SA_DQS_DN<0>")
	)
	(segment
		(start 138.159744 -279.150318)
		(end 138.159744 -279.140412)
		(width 0.088646)
		(layer "In6.Cu")
		(net "M_H_CPU1_SA_DQS_DN<0>")
	)
	(segment
		(start 139.842748 -280.237184)
		(end 139.755118 -280.025602)
		(width 0.088646)
		(layer "In6.Cu")
		(net "M_H_CPU1_SA_DQS_DN<0>")
	)
	(segment
		(start 140.2842 -280.868628)
		(end 140.221462 -280.868628)
		(width 0.088646)
		(layer "In6.Cu")
		(net "M_H_CPU1_SA_DQS_DN<0>")
	)
	(segment
		(start 188.333634 -313.609736)
		(end 188.064648 -313.34075)
		(width 0.18288)
		(layer "In6.Cu")
		(net "M_H_CPU1_SA_DQS_DN<0>")
	)
	(segment
		(start 191.809624 -312.492644)
		(end 191.531494 -312.770774)
		(width 0.18288)
		(layer "In6.Cu")
		(net "M_H_CPU1_SA_DQS_DN<0>")
	)
	(segment
		(start 198.286624 -312.555128)
		(end 196.969126 -312.555128)
		(width 0.18288)
		(layer "In6.Cu")
		(net "M_H_CPU1_SA_DQS_DN<0>")
	)
	(segment
		(start 161.348674 -305.121818)
		(end 159.28467 -305.121818)
		(width 0.18288)
		(layer "In6.Cu")
		(net "M_H_CPU1_SA_DQS_DN<0>")
	)
	(segment
		(start 174.406052 -308.503574)
		(end 173.544738 -309.364888)
		(width 0.18288)
		(layer "In6.Cu")
		(net "M_H_CPU1_SA_DQS_DN<0>")
	)
	(segment
		(start 173.544738 -309.364888)
		(end 173.253908 -309.364888)
		(width 0.18288)
		(layer "In6.Cu")
		(net "M_H_CPU1_SA_DQS_DN<0>")
	)
	(segment
		(start 188.665866 -313.609736)
		(end 188.333634 -313.609736)
		(width 0.18288)
		(layer "In6.Cu")
		(net "M_H_CPU1_SA_DQS_DN<0>")
	)
	(segment
		(start 198.959978 -311.881774)
		(end 198.286624 -312.555128)
		(width 0.18288)
		(layer "In6.Cu")
		(net "M_H_CPU1_SA_DQS_DN<0>")
	)
	(segment
		(start 186.22137 -313.608212)
		(end 184.504584 -311.891426)
		(width 0.18288)
		(layer "In6.Cu")
		(net "M_H_CPU1_SA_DQS_DN<0>")
	)
	(segment
		(start 172.98162 -309.0926)
		(end 172.609256 -309.0926)
		(width 0.18288)
		(layer "In6.Cu")
		(net "M_H_CPU1_SA_DQS_DN<0>")
	)
	(segment
		(start 156.02839 -300.968664)
		(end 148.164042 -293.104316)
		(width 0.18288)
		(layer "In6.Cu")
		(net "M_H_CPU1_SA_DQS_DN<0>")
	)
	(segment
		(start 139.755118 -280.025602)
		(end 139.532106 -279.6921)
		(width 0.088646)
		(layer "In6.Cu")
		(net "M_H_CPU1_SA_DQS_DN<0>")
	)
	(segment
		(start 180.74132 -310.166766)
		(end 180.001672 -310.166766)
		(width 0.18288)
		(layer "In6.Cu")
		(net "M_H_CPU1_SA_DQS_DN<0>")
	)
	(segment
		(start 157.252162 -305.944524)
		(end 156.887672 -305.944524)
		(width 0.18288)
		(layer "In6.Cu")
		(net "M_H_CPU1_SA_DQS_DN<0>")
	)
	(segment
		(start 138.7221 -279.47493)
		(end 138.721846 -279.47493)
		(width 0.088646)
		(layer "In6.Cu")
		(net "M_H_CPU1_SA_DQS_DN<0>")
	)
	(segment
		(start 162.002216 -304.842672)
		(end 161.62782 -304.842672)
		(width 0.18288)
		(layer "In6.Cu")
		(net "M_H_CPU1_SA_DQS_DN<0>")
	)
	(segment
		(start 137.689844 -278.336502)
		(end 137.689844 -278.31796)
		(width 0.088646)
		(layer "In6.Cu")
		(net "M_H_CPU1_SA_DQS_DN<0>")
	)
	(segment
		(start 184.504584 -311.891426)
		(end 182.46598 -311.891426)
		(width 0.18288)
		(layer "In6.Cu")
		(net "M_H_CPU1_SA_DQS_DN<0>")
	)
	(segment
		(start 188.064648 -313.34075)
		(end 187.696094 -313.34075)
		(width 0.18288)
		(layer "In6.Cu")
		(net "M_H_CPU1_SA_DQS_DN<0>")
	)
	(segment
		(start 157.910784 -305.695096)
		(end 157.50159 -305.695096)
		(width 0.18288)
		(layer "In6.Cu")
		(net "M_H_CPU1_SA_DQS_DN<0>")
	)
	(segment
		(start 131.768596 -277.84679)
		(end 131.758182 -277.840694)
		(width 0.088646)
		(layer "In6.Cu")
		(net "M_H_CPU1_SA_DQS_DN<0>")
	)
	(segment
		(start 172.609256 -309.0926)
		(end 172.357542 -309.344314)
		(width 0.18288)
		(layer "In6.Cu")
		(net "M_H_CPU1_SA_DQS_DN<0>")
	)
	(segment
		(start 126.886716 -277.465282)
		(end 126.829566 -277.522432)
		(width 0.088646)
		(layer "In6.Cu")
		(net "M_H_CPU1_SA_DQS_DN<0>")
	)
	(segment
		(start 176.451768 -308.503574)
		(end 174.406052 -308.503574)
		(width 0.18288)
		(layer "In6.Cu")
		(net "M_H_CPU1_SA_DQS_DN<0>")
	)
	(segment
		(start 156.02839 -305.085242)
		(end 156.02839 -300.968664)
		(width 0.18288)
		(layer "In6.Cu")
		(net "M_H_CPU1_SA_DQS_DN<0>")
	)
	(segment
		(start 202.971146 -312.066686)
		(end 202.710034 -312.327798)
		(width 0.18288)
		(layer "In6.Cu")
		(net "M_H_CPU1_SA_DQS_DN<0>")
	)
	(arc
		(start 132.142992 -277.84679)
		(mid 131.955794 -277.896933)
		(end 131.768596 -277.84679)
		(width 0.088646)
		(layer "In6.Cu")
		(net "M_H_CPU1_SA_DQS_DN<0>")
	)
	(arc
		(start 129.878836 -277.840694)
		(mid 129.600404 -277.77088)
		(end 129.323592 -277.84679)
		(width 0.088646)
		(layer "In6.Cu")
		(net "M_H_CPU1_SA_DQS_DN<0>")
	)
	(arc
		(start 136.457182 -277.840694)
		(mid 136.17875 -277.77088)
		(end 135.901938 -277.84679)
		(width 0.088646)
		(layer "In6.Cu")
		(net "M_H_CPU1_SA_DQS_DN<0>")
	)
	(arc
		(start 130.82905 -277.84679)
		(mid 130.554821 -277.770865)
		(end 130.278378 -277.838154)
		(width 0.088646)
		(layer "In6.Cu")
		(net "M_H_CPU1_SA_DQS_DN<0>")
	)
	(arc
		(start 130.263646 -277.84679)
		(mid 130.076448 -277.896933)
		(end 129.88925 -277.84679)
		(width 0.088646)
		(layer "In6.Cu")
		(net "M_H_CPU1_SA_DQS_DN<0>")
	)
	(arc
		(start 139.40155 -279.562052)
		(mid 139.373187 -279.536045)
		(end 139.34313 -279.512014)
		(width 0.088646)
		(layer "In6.Cu")
		(net "M_H_CPU1_SA_DQS_DN<0>")
	)
	(arc
		(start 137.868406 -278.65578)
		(mid 137.737492 -278.51942)
		(end 137.689844 -278.336502)
		(width 0.088646)
		(layer "In6.Cu")
		(net "M_H_CPU1_SA_DQS_DN<0>")
	)
	(arc
		(start 129.323592 -277.84679)
		(mid 129.136394 -277.896933)
		(end 128.949196 -277.84679)
		(width 0.088646)
		(layer "In6.Cu")
		(net "M_H_CPU1_SA_DQS_DN<0>")
	)
	(arc
		(start 137.689844 -278.31796)
		(mid 137.399366 -277.842241)
		(end 136.841992 -277.84679)
		(width 0.088646)
		(layer "In6.Cu")
		(net "M_H_CPU1_SA_DQS_DN<0>")
	)
	(arc
		(start 132.693664 -277.838154)
		(mid 132.417223 -277.770988)
		(end 132.142992 -277.84679)
		(width 0.088646)
		(layer "In6.Cu")
		(net "M_H_CPU1_SA_DQS_DN<0>")
	)
	(arc
		(start 134.962392 -277.84679)
		(mid 134.775194 -277.896933)
		(end 134.587996 -277.84679)
		(width 0.088646)
		(layer "In6.Cu")
		(net "M_H_CPU1_SA_DQS_DN<0>")
	)
	(arc
		(start 134.587996 -277.84679)
		(mid 134.305294 -277.771048)
		(end 134.022592 -277.84679)
		(width 0.088646)
		(layer "In6.Cu")
		(net "M_H_CPU1_SA_DQS_DN<0>")
	)
	(arc
		(start 127.82677 -277.58263)
		(mid 127.806638 -277.521272)
		(end 127.768604 -277.469092)
		(width 0.088646)
		(layer "In6.Cu")
		(net "M_H_CPU1_SA_DQS_DN<0>")
	)
	(arc
		(start 131.758182 -277.840694)
		(mid 131.480004 -277.771002)
		(end 131.203446 -277.84679)
		(width 0.088646)
		(layer "In6.Cu")
		(net "M_H_CPU1_SA_DQS_DN<0>")
	)
	(arc
		(start 135.517128 -277.840694)
		(mid 135.23895 -277.771002)
		(end 134.962392 -277.84679)
		(width 0.088646)
		(layer "In6.Cu")
		(net "M_H_CPU1_SA_DQS_DN<0>")
	)
	(arc
		(start 128.934464 -277.838154)
		(mid 128.658023 -277.770988)
		(end 128.383792 -277.84679)
		(width 0.088646)
		(layer "In6.Cu")
		(net "M_H_CPU1_SA_DQS_DN<0>")
	)
	(arc
		(start 138.721592 -279.474676)
		(mid 138.347117 -279.47463)
		(end 138.159744 -279.150318)
		(width 0.088646)
		(layer "In6.Cu")
		(net "M_H_CPU1_SA_DQS_DN<0>")
	)
	(arc
		(start 138.159744 -279.140412)
		(mid 138.081633 -278.863463)
		(end 137.877296 -278.66086)
		(width 0.088646)
		(layer "In6.Cu")
		(net "M_H_CPU1_SA_DQS_DN<0>")
	)
	(arc
		(start 127.443992 -277.198074)
		(mid 127.094887 -277.184738)
		(end 126.886716 -277.465282)
		(width 0.088646)
		(layer "In6.Cu")
		(net "M_H_CPU1_SA_DQS_DN<0>")
	)
	(arc
		(start 134.022592 -277.84679)
		(mid 133.835394 -277.896933)
		(end 133.648196 -277.84679)
		(width 0.088646)
		(layer "In6.Cu")
		(net "M_H_CPU1_SA_DQS_DN<0>")
	)
	(arc
		(start 136.841992 -277.84679)
		(mid 136.654794 -277.896933)
		(end 136.467596 -277.84679)
		(width 0.088646)
		(layer "In6.Cu")
		(net "M_H_CPU1_SA_DQS_DN<0>")
	)
	(arc
		(start 128.383792 -277.84679)
		(mid 128.036063 -277.860783)
		(end 127.82677 -277.58263)
		(width 0.088646)
		(layer "In6.Cu")
		(net "M_H_CPU1_SA_DQS_DN<0>")
	)
	(arc
		(start 127.663702 -277.36419)
		(mid 127.563655 -277.276652)
		(end 127.452882 -277.203154)
		(width 0.088646)
		(layer "In6.Cu")
		(net "M_H_CPU1_SA_DQS_DN<0>")
	)
	(arc
		(start 133.633464 -277.838154)
		(mid 133.357023 -277.770988)
		(end 133.082792 -277.84679)
		(width 0.088646)
		(layer "In6.Cu")
		(net "M_H_CPU1_SA_DQS_DN<0>")
	)
	(arc
		(start 131.203446 -277.84679)
		(mid 131.016248 -277.896933)
		(end 130.82905 -277.84679)
		(width 0.088646)
		(layer "In6.Cu")
		(net "M_H_CPU1_SA_DQS_DN<0>")
	)
	(arc
		(start 139.34313 -279.512014)
		(mid 139.038185 -279.400291)
		(end 138.7221 -279.47493)
		(width 0.088646)
		(layer "In6.Cu")
		(net "M_H_CPU1_SA_DQS_DN<0>")
	)
	(arc
		(start 135.901938 -277.84679)
		(mid 135.71474 -277.896933)
		(end 135.527542 -277.84679)
		(width 0.088646)
		(layer "In6.Cu")
		(net "M_H_CPU1_SA_DQS_DN<0>")
	)
	(arc
		(start 133.082792 -277.84679)
		(mid 132.895594 -277.896933)
		(end 132.708396 -277.84679)
		(width 0.088646)
		(layer "In6.Cu")
		(net "M_H_CPU1_SA_DQS_DN<0>")
	)
	(segment
		(start 206.626714 -304.841656)
		(end 206.508604 -304.959766)
		(width 0.20066)
		(layer "F.Cu")
		(net "M_H_CPU1_SA_DQ<9>")
	)
	(segment
		(start 206.991458 -304.841656)
		(end 206.971392 -304.841656)
		(width 0.101854)
		(layer "F.Cu")
		(net "M_H_CPU1_SA_DQ<9>")
	)
	(segment
		(start 211.619846 -305.266598)
		(end 211.619592 -305.266852)
		(width 0.20066)
		(layer "F.Cu")
		(net "M_H_CPU1_SA_DQ<9>")
	)
	(segment
		(start 206.320644 -305.515264)
		(end 205.84541 -305.515264)
		(width 0.20066)
		(layer "F.Cu")
		(net "M_H_CPU1_SA_DQ<9>")
	)
	(segment
		(start 210.028028 -305.266852)
		(end 209.596482 -304.835306)
		(width 0.20066)
		(layer "F.Cu")
		(net "M_H_CPU1_SA_DQ<9>")
	)
	(segment
		(start 211.619592 -305.266852)
		(end 210.028028 -305.266852)
		(width 0.20066)
		(layer "F.Cu")
		(net "M_H_CPU1_SA_DQ<9>")
	)
	(segment
		(start 206.508604 -304.959766)
		(end 206.508604 -305.327304)
		(width 0.20066)
		(layer "F.Cu")
		(net "M_H_CPU1_SA_DQ<9>")
	)
	(segment
		(start 206.971392 -304.841656)
		(end 206.626714 -304.841656)
		(width 0.20066)
		(layer "F.Cu")
		(net "M_H_CPU1_SA_DQ<9>")
	)
	(segment
		(start 205.596744 -305.266598)
		(end 204.076046 -305.266598)
		(width 0.20066)
		(layer "F.Cu")
		(net "M_H_CPU1_SA_DQ<9>")
	)
	(segment
		(start 209.180176 -304.841656)
		(end 206.991458 -304.841656)
		(width 0.1016)
		(layer "F.Cu")
		(net "M_H_CPU1_SA_DQ<9>")
	)
	(segment
		(start 123.497848 -275.894546)
		(end 123.497594 -275.8948)
		(width 0.20066)
		(layer "F.Cu")
		(net "M_H_CPU1_SA_DQ<9>")
	)
	(segment
		(start 204.076046 -305.266598)
		(end 202.971146 -305.266598)
		(width 0.20066)
		(layer "F.Cu")
		(net "M_H_CPU1_SA_DQ<9>")
	)
	(segment
		(start 205.84541 -305.515264)
		(end 205.596744 -305.266598)
		(width 0.20066)
		(layer "F.Cu")
		(net "M_H_CPU1_SA_DQ<9>")
	)
	(segment
		(start 206.508604 -305.327304)
		(end 206.320644 -305.515264)
		(width 0.20066)
		(layer "F.Cu")
		(net "M_H_CPU1_SA_DQ<9>")
	)
	(segment
		(start 209.596482 -304.835306)
		(end 209.186526 -304.835306)
		(width 0.20066)
		(layer "F.Cu")
		(net "M_H_CPU1_SA_DQ<9>")
	)
	(segment
		(start 123.497848 -275.35886)
		(end 123.497848 -275.894546)
		(width 0.20066)
		(layer "F.Cu")
		(net "M_H_CPU1_SA_DQ<9>")
	)
	(segment
		(start 209.186526 -304.835306)
		(end 209.180176 -304.841656)
		(width 0.1016)
		(layer "F.Cu")
		(net "M_H_CPU1_SA_DQ<9>")
	)
	(segment
		(start 171.415456 -314.18911)
		(end 169.182542 -311.956196)
		(width 0.18288)
		(layer "In11.Cu")
		(net "M_H_CPU1_SA_DQ<9>")
	)
	(segment
		(start 168.41216 -311.185814)
		(end 167.949372 -310.723026)
		(width 0.18288)
		(layer "In11.Cu")
		(net "M_H_CPU1_SA_DQ<9>")
	)
	(segment
		(start 157.579568 -310.71058)
		(end 152.688544 -305.819556)
		(width 0.18288)
		(layer "In11.Cu")
		(net "M_H_CPU1_SA_DQ<9>")
	)
	(segment
		(start 125.281944 -276.708616)
		(end 125.281944 -276.708362)
		(width 0.088646)
		(layer "In11.Cu")
		(net "M_H_CPU1_SA_DQ<9>")
	)
	(segment
		(start 137.029444 -282.42006)
		(end 137.029444 -282.405836)
		(width 0.088646)
		(layer "In11.Cu")
		(net "M_H_CPU1_SA_DQ<9>")
	)
	(segment
		(start 183.775858 -311.83072)
		(end 181.661562 -311.83072)
		(width 0.18288)
		(layer "In11.Cu")
		(net "M_H_CPU1_SA_DQ<9>")
	)
	(segment
		(start 138.439144 -284.863032)
		(end 138.439144 -284.838902)
		(width 0.088646)
		(layer "In11.Cu")
		(net "M_H_CPU1_SA_DQ<9>")
	)
	(segment
		(start 175.559466 -313.21121)
		(end 174.222918 -313.21121)
		(width 0.18288)
		(layer "In11.Cu")
		(net "M_H_CPU1_SA_DQ<9>")
	)
	(segment
		(start 158.786322 -310.71058)
		(end 157.579568 -310.71058)
		(width 0.18288)
		(layer "In11.Cu")
		(net "M_H_CPU1_SA_DQ<9>")
	)
	(segment
		(start 168.909492 -311.956196)
		(end 168.540176 -312.325512)
		(width 0.18288)
		(layer "In11.Cu")
		(net "M_H_CPU1_SA_DQ<9>")
	)
	(segment
		(start 202.045824 -306.001928)
		(end 199.940926 -308.106826)
		(width 0.18288)
		(layer "In11.Cu")
		(net "M_H_CPU1_SA_DQ<9>")
	)
	(segment
		(start 152.688544 -301.112682)
		(end 144.066514 -292.490652)
		(width 0.18288)
		(layer "In11.Cu")
		(net "M_H_CPU1_SA_DQ<9>")
	)
	(segment
		(start 189.678056 -312.491882)
		(end 188.827918 -311.641744)
		(width 0.18288)
		(layer "In11.Cu")
		(net "M_H_CPU1_SA_DQ<9>")
	)
	(segment
		(start 190.653416 -312.491882)
		(end 189.678056 -312.491882)
		(width 0.18288)
		(layer "In11.Cu")
		(net "M_H_CPU1_SA_DQ<9>")
	)
	(segment
		(start 174.222918 -313.21121)
		(end 173.245018 -314.18911)
		(width 0.18288)
		(layer "In11.Cu")
		(net "M_H_CPU1_SA_DQ<9>")
	)
	(segment
		(start 144.066514 -292.490652)
		(end 144.066514 -291.055552)
		(width 0.18288)
		(layer "In11.Cu")
		(net "M_H_CPU1_SA_DQ<9>")
	)
	(segment
		(start 144.066514 -291.055552)
		(end 139.365482 -286.35452)
		(width 0.18288)
		(layer "In11.Cu")
		(net "M_H_CPU1_SA_DQ<9>")
	)
	(segment
		(start 133.648196 -280.453846)
		(end 133.633464 -280.462482)
		(width 0.088646)
		(layer "In11.Cu")
		(net "M_H_CPU1_SA_DQ<9>")
	)
	(segment
		(start 196.196966 -311.266586)
		(end 195.546726 -311.916826)
		(width 0.18288)
		(layer "In11.Cu")
		(net "M_H_CPU1_SA_DQ<9>")
	)
	(segment
		(start 124.12472 -276.366986)
		(end 123.497594 -275.8948)
		(width 0.088646)
		(layer "In11.Cu")
		(net "M_H_CPU1_SA_DQ<9>")
	)
	(segment
		(start 167.949372 -310.723026)
		(end 167.036242 -310.723026)
		(width 0.18288)
		(layer "In11.Cu")
		(net "M_H_CPU1_SA_DQ<9>")
	)
	(segment
		(start 137.499598 -283.2354)
		(end 137.499598 -283.219906)
		(width 0.088646)
		(layer "In11.Cu")
		(net "M_H_CPU1_SA_DQ<9>")
	)
	(segment
		(start 195.546726 -311.916826)
		(end 194.486784 -311.916826)
		(width 0.18288)
		(layer "In11.Cu")
		(net "M_H_CPU1_SA_DQ<9>")
	)
	(segment
		(start 202.837034 -305.674014)
		(end 202.045824 -306.001928)
		(width 0.18288)
		(layer "In11.Cu")
		(net "M_H_CPU1_SA_DQ<9>")
	)
	(segment
		(start 159.9184 -311.842658)
		(end 158.786322 -310.71058)
		(width 0.18288)
		(layer "In11.Cu")
		(net "M_H_CPU1_SA_DQ<9>")
	)
	(segment
		(start 169.182542 -311.956196)
		(end 168.909492 -311.956196)
		(width 0.18288)
		(layer "In11.Cu")
		(net "M_H_CPU1_SA_DQ<9>")
	)
	(segment
		(start 135.441182 -281.272742)
		(end 135.432292 -281.267662)
		(width 0.088646)
		(layer "In11.Cu")
		(net "M_H_CPU1_SA_DQ<9>")
	)
	(segment
		(start 137.790682 -283.714444)
		(end 137.781792 -283.709364)
		(width 0.088646)
		(layer "In11.Cu")
		(net "M_H_CPU1_SA_DQ<9>")
	)
	(segment
		(start 168.04259 -312.100722)
		(end 168.04259 -311.827926)
		(width 0.18288)
		(layer "In11.Cu")
		(net "M_H_CPU1_SA_DQ<9>")
	)
	(segment
		(start 135.149844 -280.78811)
		(end 135.149844 -280.778204)
		(width 0.088646)
		(layer "In11.Cu")
		(net "M_H_CPU1_SA_DQ<9>")
	)
	(segment
		(start 166.567358 -311.842658)
		(end 159.9184 -311.842658)
		(width 0.18288)
		(layer "In11.Cu")
		(net "M_H_CPU1_SA_DQ<9>")
	)
	(segment
		(start 197.604126 -308.894226)
		(end 196.879718 -309.618634)
		(width 0.18288)
		(layer "In11.Cu")
		(net "M_H_CPU1_SA_DQ<9>")
	)
	(segment
		(start 139.055094 -285.65221)
		(end 138.799316 -285.396432)
		(width 0.088646)
		(layer "In11.Cu")
		(net "M_H_CPU1_SA_DQ<9>")
	)
	(segment
		(start 175.688498 -313.340242)
		(end 175.559466 -313.21121)
		(width 0.18288)
		(layer "In11.Cu")
		(net "M_H_CPU1_SA_DQ<9>")
	)
	(segment
		(start 126.984506 -279.645872)
		(end 126.974092 -279.639776)
		(width 0.088646)
		(layer "In11.Cu")
		(net "M_H_CPU1_SA_DQ<9>")
	)
	(segment
		(start 134.971282 -280.458926)
		(end 134.962392 -280.453846)
		(width 0.088646)
		(layer "In11.Cu")
		(net "M_H_CPU1_SA_DQ<9>")
	)
	(segment
		(start 129.888996 -280.453846)
		(end 129.874264 -280.462482)
		(width 0.088646)
		(layer "In11.Cu")
		(net "M_H_CPU1_SA_DQ<9>")
	)
	(segment
		(start 128.949196 -280.453846)
		(end 128.934464 -280.462482)
		(width 0.088646)
		(layer "In11.Cu")
		(net "M_H_CPU1_SA_DQ<9>")
	)
	(segment
		(start 166.727378 -311.03189)
		(end 166.727378 -311.682638)
		(width 0.18288)
		(layer "In11.Cu")
		(net "M_H_CPU1_SA_DQ<9>")
	)
	(segment
		(start 136.850882 -282.086558)
		(end 136.841992 -282.081478)
		(width 0.088646)
		(layer "In11.Cu")
		(net "M_H_CPU1_SA_DQ<9>")
	)
	(segment
		(start 125.282198 -278.351996)
		(end 125.282198 -278.336502)
		(width 0.088646)
		(layer "In11.Cu")
		(net "M_H_CPU1_SA_DQ<9>")
	)
	(segment
		(start 126.034546 -279.639776)
		(end 126.02845 -279.63622)
		(width 0.088646)
		(layer "In11.Cu")
		(net "M_H_CPU1_SA_DQ<9>")
	)
	(segment
		(start 188.827918 -311.641744)
		(end 183.964834 -311.641744)
		(width 0.18288)
		(layer "In11.Cu")
		(net "M_H_CPU1_SA_DQ<9>")
	)
	(segment
		(start 138.251946 -284.52318)
		(end 138.248136 -284.520894)
		(width 0.088646)
		(layer "In11.Cu")
		(net "M_H_CPU1_SA_DQ<9>")
	)
	(segment
		(start 168.540176 -312.325512)
		(end 168.26738 -312.325512)
		(width 0.18288)
		(layer "In11.Cu")
		(net "M_H_CPU1_SA_DQ<9>")
	)
	(segment
		(start 178.475894 -312.404252)
		(end 177.539904 -313.340242)
		(width 0.18288)
		(layer "In11.Cu")
		(net "M_H_CPU1_SA_DQ<9>")
	)
	(segment
		(start 168.41216 -311.458356)
		(end 168.41216 -311.185814)
		(width 0.18288)
		(layer "In11.Cu")
		(net "M_H_CPU1_SA_DQ<9>")
	)
	(segment
		(start 166.727378 -311.682638)
		(end 166.567358 -311.842658)
		(width 0.18288)
		(layer "In11.Cu")
		(net "M_H_CPU1_SA_DQ<9>")
	)
	(segment
		(start 202.971146 -305.539902)
		(end 202.837034 -305.674014)
		(width 0.18288)
		(layer "In11.Cu")
		(net "M_H_CPU1_SA_DQ<9>")
	)
	(segment
		(start 127.923036 -279.644856)
		(end 127.914146 -279.639776)
		(width 0.088646)
		(layer "In11.Cu")
		(net "M_H_CPU1_SA_DQ<9>")
	)
	(segment
		(start 128.101598 -279.986232)
		(end 128.101598 -279.964134)
		(width 0.088646)
		(layer "In11.Cu")
		(net "M_H_CPU1_SA_DQ<9>")
	)
	(segment
		(start 194.486784 -311.916826)
		(end 193.059812 -313.343798)
		(width 0.18288)
		(layer "In11.Cu")
		(net "M_H_CPU1_SA_DQ<9>")
	)
	(segment
		(start 177.539904 -313.340242)
		(end 175.688498 -313.340242)
		(width 0.18288)
		(layer "In11.Cu")
		(net "M_H_CPU1_SA_DQ<9>")
	)
	(segment
		(start 135.619744 -281.601926)
		(end 135.619744 -281.59202)
		(width 0.088646)
		(layer "In11.Cu")
		(net "M_H_CPU1_SA_DQ<9>")
	)
	(segment
		(start 125.094746 -278.012398)
		(end 125.094746 -278.012144)
		(width 0.088646)
		(layer "In11.Cu")
		(net "M_H_CPU1_SA_DQ<9>")
	)
	(segment
		(start 196.879718 -309.618634)
		(end 196.196966 -311.266586)
		(width 0.18288)
		(layer "In11.Cu")
		(net "M_H_CPU1_SA_DQ<9>")
	)
	(segment
		(start 138.248136 -284.520894)
		(end 138.24585 -284.519624)
		(width 0.088646)
		(layer "In11.Cu")
		(net "M_H_CPU1_SA_DQ<9>")
	)
	(segment
		(start 130.828796 -280.453846)
		(end 130.814064 -280.462482)
		(width 0.088646)
		(layer "In11.Cu")
		(net "M_H_CPU1_SA_DQ<9>")
	)
	(segment
		(start 181.661562 -311.83072)
		(end 181.08803 -312.404252)
		(width 0.18288)
		(layer "In11.Cu")
		(net "M_H_CPU1_SA_DQ<9>")
	)
	(segment
		(start 193.059812 -313.343798)
		(end 191.505332 -313.343798)
		(width 0.18288)
		(layer "In11.Cu")
		(net "M_H_CPU1_SA_DQ<9>")
	)
	(segment
		(start 167.036242 -310.723026)
		(end 166.727378 -311.03189)
		(width 0.18288)
		(layer "In11.Cu")
		(net "M_H_CPU1_SA_DQ<9>")
	)
	(segment
		(start 126.04496 -279.645872)
		(end 126.034546 -279.639776)
		(width 0.088646)
		(layer "In11.Cu")
		(net "M_H_CPU1_SA_DQ<9>")
	)
	(segment
		(start 124.1552 -276.384258)
		(end 124.12472 -276.366986)
		(width 0.088646)
		(layer "In11.Cu")
		(net "M_H_CPU1_SA_DQ<9>")
	)
	(segment
		(start 125.094746 -277.033228)
		(end 125.094746 -277.032974)
		(width 0.088646)
		(layer "In11.Cu")
		(net "M_H_CPU1_SA_DQ<9>")
	)
	(segment
		(start 131.768596 -280.453846)
		(end 131.753864 -280.462482)
		(width 0.088646)
		(layer "In11.Cu")
		(net "M_H_CPU1_SA_DQ<9>")
	)
	(segment
		(start 199.204326 -308.106826)
		(end 198.416926 -308.894226)
		(width 0.18288)
		(layer "In11.Cu")
		(net "M_H_CPU1_SA_DQ<9>")
	)
	(segment
		(start 181.08803 -312.404252)
		(end 178.475894 -312.404252)
		(width 0.18288)
		(layer "In11.Cu")
		(net "M_H_CPU1_SA_DQ<9>")
	)
	(segment
		(start 191.505332 -313.343798)
		(end 190.653416 -312.491882)
		(width 0.18288)
		(layer "In11.Cu")
		(net "M_H_CPU1_SA_DQ<9>")
	)
	(segment
		(start 183.964834 -311.641744)
		(end 183.775858 -311.83072)
		(width 0.18288)
		(layer "In11.Cu")
		(net "M_H_CPU1_SA_DQ<9>")
	)
	(segment
		(start 152.688544 -305.819556)
		(end 152.688544 -301.112682)
		(width 0.18288)
		(layer "In11.Cu")
		(net "M_H_CPU1_SA_DQ<9>")
	)
	(segment
		(start 139.055094 -286.044132)
		(end 139.055094 -285.65221)
		(width 0.088646)
		(layer "In11.Cu")
		(net "M_H_CPU1_SA_DQ<9>")
	)
	(segment
		(start 199.940926 -308.106826)
		(end 199.204326 -308.106826)
		(width 0.18288)
		(layer "In11.Cu")
		(net "M_H_CPU1_SA_DQ<9>")
	)
	(segment
		(start 125.573282 -278.83104)
		(end 125.564392 -278.82596)
		(width 0.088646)
		(layer "In11.Cu")
		(net "M_H_CPU1_SA_DQ<9>")
	)
	(segment
		(start 168.26738 -312.325512)
		(end 168.04259 -312.100722)
		(width 0.18288)
		(layer "In11.Cu")
		(net "M_H_CPU1_SA_DQ<9>")
	)
	(segment
		(start 198.416926 -308.894226)
		(end 197.604126 -308.894226)
		(width 0.18288)
		(layer "In11.Cu")
		(net "M_H_CPU1_SA_DQ<9>")
	)
	(segment
		(start 173.245018 -314.18911)
		(end 171.415456 -314.18911)
		(width 0.18288)
		(layer "In11.Cu")
		(net "M_H_CPU1_SA_DQ<9>")
	)
	(segment
		(start 202.971146 -305.266598)
		(end 202.971146 -305.539902)
		(width 0.18288)
		(layer "In11.Cu")
		(net "M_H_CPU1_SA_DQ<9>")
	)
	(segment
		(start 139.365482 -286.35452)
		(end 139.055094 -286.044132)
		(width 0.088646)
		(layer "In11.Cu")
		(net "M_H_CPU1_SA_DQ<9>")
	)
	(segment
		(start 137.321036 -282.900628)
		(end 137.312146 -282.895548)
		(width 0.088646)
		(layer "In11.Cu")
		(net "M_H_CPU1_SA_DQ<9>")
	)
	(segment
		(start 134.587996 -280.453846)
		(end 134.573264 -280.462482)
		(width 0.088646)
		(layer "In11.Cu")
		(net "M_H_CPU1_SA_DQ<9>")
	)
	(segment
		(start 168.04259 -311.827926)
		(end 168.41216 -311.458356)
		(width 0.18288)
		(layer "In11.Cu")
		(net "M_H_CPU1_SA_DQ<9>")
	)
	(arc
		(start 126.02845 -279.63622)
		(mid 125.825863 -279.429869)
		(end 125.751844 -279.150318)
		(width 0.088646)
		(layer "In11.Cu")
		(net "M_H_CPU1_SA_DQ<9>")
	)
	(arc
		(start 134.962392 -280.453846)
		(mid 134.775194 -280.403703)
		(end 134.587996 -280.453846)
		(width 0.088646)
		(layer "In11.Cu")
		(net "M_H_CPU1_SA_DQ<9>")
	)
	(arc
		(start 130.814064 -280.462482)
		(mid 130.537623 -280.529648)
		(end 130.263392 -280.453846)
		(width 0.088646)
		(layer "In11.Cu")
		(net "M_H_CPU1_SA_DQ<9>")
	)
	(arc
		(start 125.751844 -279.150318)
		(mid 125.704165 -278.967418)
		(end 125.573282 -278.83104)
		(width 0.088646)
		(layer "In11.Cu")
		(net "M_H_CPU1_SA_DQ<9>")
	)
	(arc
		(start 125.282198 -278.336502)
		(mid 125.231905 -278.149326)
		(end 125.094746 -278.012398)
		(width 0.088646)
		(layer "In11.Cu")
		(net "M_H_CPU1_SA_DQ<9>")
	)
	(arc
		(start 137.312146 -282.895548)
		(mid 137.108665 -282.694744)
		(end 137.029444 -282.42006)
		(width 0.088646)
		(layer "In11.Cu")
		(net "M_H_CPU1_SA_DQ<9>")
	)
	(arc
		(start 137.969244 -284.033722)
		(mid 137.921565 -283.850822)
		(end 137.790682 -283.714444)
		(width 0.088646)
		(layer "In11.Cu")
		(net "M_H_CPU1_SA_DQ<9>")
	)
	(arc
		(start 131.203192 -280.453846)
		(mid 131.015994 -280.403703)
		(end 130.828796 -280.453846)
		(width 0.088646)
		(layer "In11.Cu")
		(net "M_H_CPU1_SA_DQ<9>")
	)
	(arc
		(start 125.281944 -276.708362)
		(mid 125.23178 -276.521224)
		(end 125.094746 -276.384258)
		(width 0.088646)
		(layer "In11.Cu")
		(net "M_H_CPU1_SA_DQ<9>")
	)
	(arc
		(start 137.029444 -282.405836)
		(mid 136.981765 -282.222936)
		(end 136.850882 -282.086558)
		(width 0.088646)
		(layer "In11.Cu")
		(net "M_H_CPU1_SA_DQ<9>")
	)
	(arc
		(start 128.383792 -280.453846)
		(mid 128.18251 -280.256359)
		(end 128.101598 -279.986232)
		(width 0.088646)
		(layer "In11.Cu")
		(net "M_H_CPU1_SA_DQ<9>")
	)
	(arc
		(start 128.934464 -280.462482)
		(mid 128.658023 -280.529648)
		(end 128.383792 -280.453846)
		(width 0.088646)
		(layer "In11.Cu")
		(net "M_H_CPU1_SA_DQ<9>")
	)
	(arc
		(start 126.974092 -279.639776)
		(mid 126.786894 -279.589633)
		(end 126.599696 -279.639776)
		(width 0.088646)
		(layer "In11.Cu")
		(net "M_H_CPU1_SA_DQ<9>")
	)
	(arc
		(start 135.902192 -282.081478)
		(mid 135.697857 -281.878873)
		(end 135.619744 -281.601926)
		(width 0.088646)
		(layer "In11.Cu")
		(net "M_H_CPU1_SA_DQ<9>")
	)
	(arc
		(start 138.721592 -285.336996)
		(mid 138.518594 -285.136827)
		(end 138.439144 -284.863032)
		(width 0.088646)
		(layer "In11.Cu")
		(net "M_H_CPU1_SA_DQ<9>")
	)
	(arc
		(start 125.094746 -277.032974)
		(mid 125.231771 -276.895861)
		(end 125.281944 -276.708616)
		(width 0.088646)
		(layer "In11.Cu")
		(net "M_H_CPU1_SA_DQ<9>")
	)
	(arc
		(start 125.094746 -276.384258)
		(mid 124.907548 -276.334115)
		(end 124.72035 -276.384258)
		(width 0.088646)
		(layer "In11.Cu")
		(net "M_H_CPU1_SA_DQ<9>")
	)
	(arc
		(start 138.24585 -284.519624)
		(mid 138.043263 -284.313273)
		(end 137.969244 -284.033722)
		(width 0.088646)
		(layer "In11.Cu")
		(net "M_H_CPU1_SA_DQ<9>")
	)
	(arc
		(start 135.619744 -281.59202)
		(mid 135.572065 -281.40912)
		(end 135.441182 -281.272742)
		(width 0.088646)
		(layer "In11.Cu")
		(net "M_H_CPU1_SA_DQ<9>")
	)
	(arc
		(start 135.432292 -281.267662)
		(mid 135.227957 -281.065057)
		(end 135.149844 -280.78811)
		(width 0.088646)
		(layer "In11.Cu")
		(net "M_H_CPU1_SA_DQ<9>")
	)
	(arc
		(start 133.633464 -280.462482)
		(mid 133.357023 -280.529648)
		(end 133.082792 -280.453846)
		(width 0.088646)
		(layer "In11.Cu")
		(net "M_H_CPU1_SA_DQ<9>")
	)
	(arc
		(start 132.142992 -280.453846)
		(mid 131.955794 -280.403703)
		(end 131.768596 -280.453846)
		(width 0.088646)
		(layer "In11.Cu")
		(net "M_H_CPU1_SA_DQ<9>")
	)
	(arc
		(start 134.573264 -280.462482)
		(mid 134.296823 -280.529648)
		(end 134.022592 -280.453846)
		(width 0.088646)
		(layer "In11.Cu")
		(net "M_H_CPU1_SA_DQ<9>")
	)
	(arc
		(start 128.101598 -279.964134)
		(mid 128.053919 -279.781234)
		(end 127.923036 -279.644856)
		(width 0.088646)
		(layer "In11.Cu")
		(net "M_H_CPU1_SA_DQ<9>")
	)
	(arc
		(start 125.094746 -278.012144)
		(mid 124.887758 -277.805172)
		(end 124.812044 -277.522432)
		(width 0.088646)
		(layer "In11.Cu")
		(net "M_H_CPU1_SA_DQ<9>")
	)
	(arc
		(start 124.812044 -277.522432)
		(mid 124.887854 -277.239948)
		(end 125.094746 -277.033228)
		(width 0.088646)
		(layer "In11.Cu")
		(net "M_H_CPU1_SA_DQ<9>")
	)
	(arc
		(start 137.499598 -283.219906)
		(mid 137.451919 -283.037006)
		(end 137.321036 -282.900628)
		(width 0.088646)
		(layer "In11.Cu")
		(net "M_H_CPU1_SA_DQ<9>")
	)
	(arc
		(start 125.564392 -278.82596)
		(mid 125.361569 -278.625729)
		(end 125.282198 -278.351996)
		(width 0.088646)
		(layer "In11.Cu")
		(net "M_H_CPU1_SA_DQ<9>")
	)
	(arc
		(start 124.72035 -276.384258)
		(mid 124.437792 -276.459907)
		(end 124.1552 -276.384258)
		(width 0.088646)
		(layer "In11.Cu")
		(net "M_H_CPU1_SA_DQ<9>")
	)
	(arc
		(start 132.708396 -280.453846)
		(mid 132.425694 -280.529588)
		(end 132.142992 -280.453846)
		(width 0.088646)
		(layer "In11.Cu")
		(net "M_H_CPU1_SA_DQ<9>")
	)
	(arc
		(start 131.753864 -280.462482)
		(mid 131.477423 -280.529648)
		(end 131.203192 -280.453846)
		(width 0.088646)
		(layer "In11.Cu")
		(net "M_H_CPU1_SA_DQ<9>")
	)
	(arc
		(start 134.022592 -280.453846)
		(mid 133.835394 -280.403703)
		(end 133.648196 -280.453846)
		(width 0.088646)
		(layer "In11.Cu")
		(net "M_H_CPU1_SA_DQ<9>")
	)
	(arc
		(start 135.149844 -280.778204)
		(mid 135.102165 -280.595304)
		(end 134.971282 -280.458926)
		(width 0.088646)
		(layer "In11.Cu")
		(net "M_H_CPU1_SA_DQ<9>")
	)
	(arc
		(start 127.53975 -279.639776)
		(mid 127.262937 -279.715646)
		(end 126.984506 -279.645872)
		(width 0.088646)
		(layer "In11.Cu")
		(net "M_H_CPU1_SA_DQ<9>")
	)
	(arc
		(start 137.781792 -283.709364)
		(mid 137.578969 -283.509133)
		(end 137.499598 -283.2354)
		(width 0.088646)
		(layer "In11.Cu")
		(net "M_H_CPU1_SA_DQ<9>")
	)
	(arc
		(start 129.323592 -280.453846)
		(mid 129.136394 -280.403703)
		(end 128.949196 -280.453846)
		(width 0.088646)
		(layer "In11.Cu")
		(net "M_H_CPU1_SA_DQ<9>")
	)
	(arc
		(start 138.439144 -284.838902)
		(mid 138.386874 -284.656537)
		(end 138.251946 -284.52318)
		(width 0.088646)
		(layer "In11.Cu")
		(net "M_H_CPU1_SA_DQ<9>")
	)
	(arc
		(start 127.914146 -279.639776)
		(mid 127.726948 -279.589633)
		(end 127.53975 -279.639776)
		(width 0.088646)
		(layer "In11.Cu")
		(net "M_H_CPU1_SA_DQ<9>")
	)
	(arc
		(start 130.263392 -280.453846)
		(mid 130.076194 -280.403703)
		(end 129.888996 -280.453846)
		(width 0.088646)
		(layer "In11.Cu")
		(net "M_H_CPU1_SA_DQ<9>")
	)
	(arc
		(start 126.599696 -279.639776)
		(mid 126.323137 -279.715519)
		(end 126.04496 -279.645872)
		(width 0.088646)
		(layer "In11.Cu")
		(net "M_H_CPU1_SA_DQ<9>")
	)
	(arc
		(start 133.082792 -280.453846)
		(mid 132.895594 -280.403703)
		(end 132.708396 -280.453846)
		(width 0.088646)
		(layer "In11.Cu")
		(net "M_H_CPU1_SA_DQ<9>")
	)
	(arc
		(start 136.467596 -282.081478)
		(mid 136.184894 -282.157254)
		(end 135.902192 -282.081478)
		(width 0.088646)
		(layer "In11.Cu")
		(net "M_H_CPU1_SA_DQ<9>")
	)
	(arc
		(start 136.841992 -282.081478)
		(mid 136.654794 -282.031335)
		(end 136.467596 -282.081478)
		(width 0.088646)
		(layer "In11.Cu")
		(net "M_H_CPU1_SA_DQ<9>")
	)
	(arc
		(start 129.874264 -280.462482)
		(mid 129.597823 -280.529648)
		(end 129.323592 -280.453846)
		(width 0.088646)
		(layer "In11.Cu")
		(net "M_H_CPU1_SA_DQ<9>")
	)
	(arc
		(start 138.799316 -285.396432)
		(mid 138.762406 -285.364161)
		(end 138.721592 -285.336996)
		(width 0.088646)
		(layer "In11.Cu")
		(net "M_H_CPU1_SA_DQ<9>")
	)
	(segment
		(start 206.626714 -306.541678)
		(end 206.508604 -306.659788)
		(width 0.20066)
		(layer "F.Cu")
		(net "M_H_CPU1_SA_DQ<8>")
	)
	(segment
		(start 209.596482 -306.535328)
		(end 209.186526 -306.535328)
		(width 0.20066)
		(layer "F.Cu")
		(net "M_H_CPU1_SA_DQ<8>")
	)
	(segment
		(start 206.320644 -307.215286)
		(end 205.84541 -307.215286)
		(width 0.20066)
		(layer "F.Cu")
		(net "M_H_CPU1_SA_DQ<8>")
	)
	(segment
		(start 207.018382 -306.541678)
		(end 206.971392 -306.541678)
		(width 0.101854)
		(layer "F.Cu")
		(net "M_H_CPU1_SA_DQ<8>")
	)
	(segment
		(start 211.619592 -306.966874)
		(end 210.028028 -306.966874)
		(width 0.20066)
		(layer "F.Cu")
		(net "M_H_CPU1_SA_DQ<8>")
	)
	(segment
		(start 209.186526 -306.535328)
		(end 209.180176 -306.541678)
		(width 0.1016)
		(layer "F.Cu")
		(net "M_H_CPU1_SA_DQ<8>")
	)
	(segment
		(start 209.180176 -306.541678)
		(end 207.018382 -306.541678)
		(width 0.1016)
		(layer "F.Cu")
		(net "M_H_CPU1_SA_DQ<8>")
	)
	(segment
		(start 205.84541 -307.215286)
		(end 205.596744 -306.96662)
		(width 0.20066)
		(layer "F.Cu")
		(net "M_H_CPU1_SA_DQ<8>")
	)
	(segment
		(start 206.508604 -307.027326)
		(end 206.320644 -307.215286)
		(width 0.20066)
		(layer "F.Cu")
		(net "M_H_CPU1_SA_DQ<8>")
	)
	(segment
		(start 123.967494 -276.172676)
		(end 123.967748 -276.708616)
		(width 0.20066)
		(layer "F.Cu")
		(net "M_H_CPU1_SA_DQ<8>")
	)
	(segment
		(start 205.596744 -306.96662)
		(end 204.076046 -306.96662)
		(width 0.20066)
		(layer "F.Cu")
		(net "M_H_CPU1_SA_DQ<8>")
	)
	(segment
		(start 206.508604 -306.659788)
		(end 206.508604 -307.027326)
		(width 0.20066)
		(layer "F.Cu")
		(net "M_H_CPU1_SA_DQ<8>")
	)
	(segment
		(start 211.619846 -306.96662)
		(end 211.619592 -306.966874)
		(width 0.20066)
		(layer "F.Cu")
		(net "M_H_CPU1_SA_DQ<8>")
	)
	(segment
		(start 204.076046 -306.96662)
		(end 202.971146 -306.96662)
		(width 0.20066)
		(layer "F.Cu")
		(net "M_H_CPU1_SA_DQ<8>")
	)
	(segment
		(start 210.028028 -306.966874)
		(end 209.596482 -306.535328)
		(width 0.20066)
		(layer "F.Cu")
		(net "M_H_CPU1_SA_DQ<8>")
	)
	(segment
		(start 206.971392 -306.541678)
		(end 206.626714 -306.541678)
		(width 0.20066)
		(layer "F.Cu")
		(net "M_H_CPU1_SA_DQ<8>")
	)
	(segment
		(start 175.829722 -314.917328)
		(end 174.736252 -314.917328)
		(width 0.18288)
		(layer "In11.Cu")
		(net "M_H_CPU1_SA_DQ<8>")
	)
	(segment
		(start 126.51486 -280.459942)
		(end 126.504446 -280.453846)
		(width 0.088646)
		(layer "In11.Cu")
		(net "M_H_CPU1_SA_DQ<8>")
	)
	(segment
		(start 142.888716 -292.750494)
		(end 142.888716 -291.842444)
		(width 0.18288)
		(layer "In11.Cu")
		(net "M_H_CPU1_SA_DQ<8>")
	)
	(segment
		(start 192.372234 -315.04128)
		(end 190.5254 -315.04128)
		(width 0.18288)
		(layer "In11.Cu")
		(net "M_H_CPU1_SA_DQ<8>")
	)
	(segment
		(start 151.672544 -301.534322)
		(end 142.888716 -292.750494)
		(width 0.18288)
		(layer "In11.Cu")
		(net "M_H_CPU1_SA_DQ<8>")
	)
	(segment
		(start 142.888716 -291.842444)
		(end 138.469116 -287.422844)
		(width 0.18288)
		(layer "In11.Cu")
		(net "M_H_CPU1_SA_DQ<8>")
	)
	(segment
		(start 164.643816 -313.34329)
		(end 163.774628 -313.34329)
		(width 0.18288)
		(layer "In11.Cu")
		(net "M_H_CPU1_SA_DQ<8>")
	)
	(segment
		(start 182.332376 -313.331606)
		(end 181.372764 -314.291218)
		(width 0.18288)
		(layer "In11.Cu")
		(net "M_H_CPU1_SA_DQ<8>")
	)
	(segment
		(start 187.064142 -314.188348)
		(end 186.2074 -313.331606)
		(width 0.18288)
		(layer "In11.Cu")
		(net "M_H_CPU1_SA_DQ<8>")
	)
	(segment
		(start 202.971146 -307.124608)
		(end 202.908662 -307.275484)
		(width 0.18288)
		(layer "In11.Cu")
		(net "M_H_CPU1_SA_DQ<8>")
	)
	(segment
		(start 179.722018 -314.291218)
		(end 179.379626 -313.948826)
		(width 0.18288)
		(layer "In11.Cu")
		(net "M_H_CPU1_SA_DQ<8>")
	)
	(segment
		(start 125.094746 -279.639776)
		(end 125.091952 -279.638252)
		(width 0.088646)
		(layer "In11.Cu")
		(net "M_H_CPU1_SA_DQ<8>")
	)
	(segment
		(start 189.672468 -314.188348)
		(end 187.064142 -314.188348)
		(width 0.18288)
		(layer "In11.Cu")
		(net "M_H_CPU1_SA_DQ<8>")
	)
	(segment
		(start 137.321036 -284.52826)
		(end 137.312146 -284.52318)
		(width 0.088646)
		(layer "In11.Cu")
		(net "M_H_CPU1_SA_DQ<8>")
	)
	(segment
		(start 190.5254 -315.04128)
		(end 189.672468 -314.188348)
		(width 0.18288)
		(layer "In11.Cu")
		(net "M_H_CPU1_SA_DQ<8>")
	)
	(segment
		(start 196.969126 -313.186826)
		(end 194.941444 -315.214508)
		(width 0.18288)
		(layer "In11.Cu")
		(net "M_H_CPU1_SA_DQ<8>")
	)
	(segment
		(start 137.790682 -285.342076)
		(end 137.781792 -285.336996)
		(width 0.088646)
		(layer "In11.Cu")
		(net "M_H_CPU1_SA_DQ<8>")
	)
	(segment
		(start 158.291276 -313.122056)
		(end 151.672544 -306.503324)
		(width 0.18288)
		(layer "In11.Cu")
		(net "M_H_CPU1_SA_DQ<8>")
	)
	(segment
		(start 137.312146 -284.52318)
		(end 137.30605 -284.519624)
		(width 0.088646)
		(layer "In11.Cu")
		(net "M_H_CPU1_SA_DQ<8>")
	)
	(segment
		(start 138.466322 -286.346646)
		(end 138.329924 -286.210248)
		(width 0.088646)
		(layer "In11.Cu")
		(net "M_H_CPU1_SA_DQ<8>")
	)
	(segment
		(start 171.669456 -315.88964)
		(end 170.400472 -315.364114)
		(width 0.18288)
		(layer "In11.Cu")
		(net "M_H_CPU1_SA_DQ<8>")
	)
	(segment
		(start 123.872244 -277.536656)
		(end 123.872244 -277.522432)
		(width 0.088646)
		(layer "In11.Cu")
		(net "M_H_CPU1_SA_DQ<8>")
	)
	(segment
		(start 178.897026 -313.948826)
		(end 177.802794 -315.043058)
		(width 0.18288)
		(layer "In11.Cu")
		(net "M_H_CPU1_SA_DQ<8>")
	)
	(segment
		(start 138.469116 -287.422844)
		(end 138.469116 -286.895794)
		(width 0.18288)
		(layer "In11.Cu")
		(net "M_H_CPU1_SA_DQ<8>")
	)
	(segment
		(start 197.825614 -313.186826)
		(end 196.969126 -313.186826)
		(width 0.18288)
		(layer "In11.Cu")
		(net "M_H_CPU1_SA_DQ<8>")
	)
	(segment
		(start 138.469116 -286.895794)
		(end 138.466322 -286.893)
		(width 0.088646)
		(layer "In11.Cu")
		(net "M_H_CPU1_SA_DQ<8>")
	)
	(segment
		(start 126.13005 -280.453846)
		(end 126.119636 -280.459942)
		(width 0.088646)
		(layer "In11.Cu")
		(net "M_H_CPU1_SA_DQ<8>")
	)
	(segment
		(start 177.802794 -315.043058)
		(end 175.955452 -315.043058)
		(width 0.18288)
		(layer "In11.Cu")
		(net "M_H_CPU1_SA_DQ<8>")
	)
	(segment
		(start 192.545462 -315.214508)
		(end 192.372234 -315.04128)
		(width 0.18288)
		(layer "In11.Cu")
		(net "M_H_CPU1_SA_DQ<8>")
	)
	(segment
		(start 162.878008 -314.168028)
		(end 162.878008 -313.53633)
		(width 0.18288)
		(layer "In11.Cu")
		(net "M_H_CPU1_SA_DQ<8>")
	)
	(segment
		(start 125.282198 -279.986232)
		(end 125.282198 -279.964134)
		(width 0.088646)
		(layer "In11.Cu")
		(net "M_H_CPU1_SA_DQ<8>")
	)
	(segment
		(start 165.258496 -313.081162)
		(end 164.905944 -313.081162)
		(width 0.18288)
		(layer "In11.Cu")
		(net "M_H_CPU1_SA_DQ<8>")
	)
	(segment
		(start 183.697118 -313.331606)
		(end 182.332376 -313.331606)
		(width 0.18288)
		(layer "In11.Cu")
		(net "M_H_CPU1_SA_DQ<8>")
	)
	(segment
		(start 194.941444 -315.214508)
		(end 192.545462 -315.214508)
		(width 0.18288)
		(layer "In11.Cu")
		(net "M_H_CPU1_SA_DQ<8>")
	)
	(segment
		(start 163.581588 -314.168028)
		(end 163.388548 -314.361068)
		(width 0.18288)
		(layer "In11.Cu")
		(net "M_H_CPU1_SA_DQ<8>")
	)
	(segment
		(start 134.679944 -281.59202)
		(end 134.679944 -281.583384)
		(width 0.088646)
		(layer "In11.Cu")
		(net "M_H_CPU1_SA_DQ<8>")
	)
	(segment
		(start 202.379326 -308.034436)
		(end 202.379326 -308.343808)
		(width 0.18288)
		(layer "In11.Cu")
		(net "M_H_CPU1_SA_DQ<8>")
	)
	(segment
		(start 202.908662 -307.275484)
		(end 202.541886 -307.64226)
		(width 0.18288)
		(layer "In11.Cu")
		(net "M_H_CPU1_SA_DQ<8>")
	)
	(segment
		(start 134.962646 -282.081478)
		(end 134.95655 -282.077922)
		(width 0.088646)
		(layer "In11.Cu")
		(net "M_H_CPU1_SA_DQ<8>")
	)
	(segment
		(start 202.174602 -308.837838)
		(end 197.825614 -313.186826)
		(width 0.18288)
		(layer "In11.Cu")
		(net "M_H_CPU1_SA_DQ<8>")
	)
	(segment
		(start 168.849802 -315.364114)
		(end 167.951658 -314.46597)
		(width 0.18288)
		(layer "In11.Cu")
		(net "M_H_CPU1_SA_DQ<8>")
	)
	(segment
		(start 137.969244 -285.675578)
		(end 137.969244 -285.661354)
		(width 0.088646)
		(layer "In11.Cu")
		(net "M_H_CPU1_SA_DQ<8>")
	)
	(segment
		(start 162.878008 -313.53633)
		(end 162.684968 -313.34329)
		(width 0.18288)
		(layer "In11.Cu")
		(net "M_H_CPU1_SA_DQ<8>")
	)
	(segment
		(start 160.565084 -313.122056)
		(end 158.291276 -313.122056)
		(width 0.18288)
		(layer "In11.Cu")
		(net "M_H_CPU1_SA_DQ<8>")
	)
	(segment
		(start 124.337826 -276.765766)
		(end 124.280676 -276.708616)
		(width 0.088646)
		(layer "In11.Cu")
		(net "M_H_CPU1_SA_DQ<8>")
	)
	(segment
		(start 124.280676 -276.708616)
		(end 123.967748 -276.708616)
		(width 0.088646)
		(layer "In11.Cu")
		(net "M_H_CPU1_SA_DQ<8>")
	)
	(segment
		(start 175.955452 -315.043058)
		(end 175.829722 -314.917328)
		(width 0.18288)
		(layer "In11.Cu")
		(net "M_H_CPU1_SA_DQ<8>")
	)
	(segment
		(start 127.914146 -281.267662)
		(end 127.90805 -281.264106)
		(width 0.088646)
		(layer "In11.Cu")
		(net "M_H_CPU1_SA_DQ<8>")
	)
	(segment
		(start 132.627878 -281.276298)
		(end 132.613146 -281.267662)
		(width 0.088646)
		(layer "In11.Cu")
		(net "M_H_CPU1_SA_DQ<8>")
	)
	(segment
		(start 163.581588 -313.53633)
		(end 163.581588 -314.168028)
		(width 0.18288)
		(layer "In11.Cu")
		(net "M_H_CPU1_SA_DQ<8>")
	)
	(segment
		(start 185.171842 -313.331606)
		(end 185.045858 -313.45759)
		(width 0.18288)
		(layer "In11.Cu")
		(net "M_H_CPU1_SA_DQ<8>")
	)
	(segment
		(start 186.2074 -313.331606)
		(end 185.171842 -313.331606)
		(width 0.18288)
		(layer "In11.Cu")
		(net "M_H_CPU1_SA_DQ<8>")
	)
	(segment
		(start 128.868678 -281.276298)
		(end 128.853946 -281.267662)
		(width 0.088646)
		(layer "In11.Cu")
		(net "M_H_CPU1_SA_DQ<8>")
	)
	(segment
		(start 127.928878 -281.276298)
		(end 127.914146 -281.267662)
		(width 0.088646)
		(layer "In11.Cu")
		(net "M_H_CPU1_SA_DQ<8>")
	)
	(segment
		(start 151.672544 -306.503324)
		(end 151.672544 -301.534322)
		(width 0.18288)
		(layer "In11.Cu")
		(net "M_H_CPU1_SA_DQ<8>")
	)
	(segment
		(start 129.808478 -281.276298)
		(end 129.793746 -281.267662)
		(width 0.088646)
		(layer "In11.Cu")
		(net "M_H_CPU1_SA_DQ<8>")
	)
	(segment
		(start 125.091952 -279.638252)
		(end 125.08865 -279.63622)
		(width 0.088646)
		(layer "In11.Cu")
		(net "M_H_CPU1_SA_DQ<8>")
	)
	(segment
		(start 131.688078 -281.276298)
		(end 131.673346 -281.267662)
		(width 0.088646)
		(layer "In11.Cu")
		(net "M_H_CPU1_SA_DQ<8>")
	)
	(segment
		(start 164.905944 -313.081162)
		(end 164.643816 -313.34329)
		(width 0.18288)
		(layer "In11.Cu")
		(net "M_H_CPU1_SA_DQ<8>")
	)
	(segment
		(start 202.971146 -306.96662)
		(end 202.971146 -307.124608)
		(width 0.18288)
		(layer "In11.Cu")
		(net "M_H_CPU1_SA_DQ<8>")
	)
	(segment
		(start 163.774628 -313.34329)
		(end 163.581588 -313.53633)
		(width 0.18288)
		(layer "In11.Cu")
		(net "M_H_CPU1_SA_DQ<8>")
	)
	(segment
		(start 163.071048 -314.361068)
		(end 162.878008 -314.168028)
		(width 0.18288)
		(layer "In11.Cu")
		(net "M_H_CPU1_SA_DQ<8>")
	)
	(segment
		(start 127.452882 -280.458926)
		(end 127.443992 -280.453846)
		(width 0.088646)
		(layer "In11.Cu")
		(net "M_H_CPU1_SA_DQ<8>")
	)
	(segment
		(start 135.149844 -282.424378)
		(end 135.149844 -282.3972)
		(width 0.088646)
		(layer "In11.Cu")
		(net "M_H_CPU1_SA_DQ<8>")
	)
	(segment
		(start 167.951658 -314.46597)
		(end 166.643304 -314.46597)
		(width 0.18288)
		(layer "In11.Cu")
		(net "M_H_CPU1_SA_DQ<8>")
	)
	(segment
		(start 185.045858 -313.45759)
		(end 183.823102 -313.45759)
		(width 0.18288)
		(layer "In11.Cu")
		(net "M_H_CPU1_SA_DQ<8>")
	)
	(segment
		(start 170.400472 -315.364114)
		(end 168.849802 -315.364114)
		(width 0.18288)
		(layer "In11.Cu")
		(net "M_H_CPU1_SA_DQ<8>")
	)
	(segment
		(start 133.567678 -281.276298)
		(end 133.552946 -281.267662)
		(width 0.088646)
		(layer "In11.Cu")
		(net "M_H_CPU1_SA_DQ<8>")
	)
	(segment
		(start 130.748278 -281.276298)
		(end 130.733546 -281.267662)
		(width 0.088646)
		(layer "In11.Cu")
		(net "M_H_CPU1_SA_DQ<8>")
	)
	(segment
		(start 162.684968 -313.34329)
		(end 160.786318 -313.34329)
		(width 0.18288)
		(layer "In11.Cu")
		(net "M_H_CPU1_SA_DQ<8>")
	)
	(segment
		(start 136.380982 -282.900628)
		(end 136.372092 -282.895548)
		(width 0.088646)
		(layer "In11.Cu")
		(net "M_H_CPU1_SA_DQ<8>")
	)
	(segment
		(start 124.342398 -278.351996)
		(end 124.342398 -278.336502)
		(width 0.088646)
		(layer "In11.Cu")
		(net "M_H_CPU1_SA_DQ<8>")
	)
	(segment
		(start 174.736252 -314.917328)
		(end 173.76394 -315.88964)
		(width 0.18288)
		(layer "In11.Cu")
		(net "M_H_CPU1_SA_DQ<8>")
	)
	(segment
		(start 124.154946 -277.032974)
		(end 124.163836 -277.027894)
		(width 0.088646)
		(layer "In11.Cu")
		(net "M_H_CPU1_SA_DQ<8>")
	)
	(segment
		(start 163.388548 -314.361068)
		(end 163.071048 -314.361068)
		(width 0.18288)
		(layer "In11.Cu")
		(net "M_H_CPU1_SA_DQ<8>")
	)
	(segment
		(start 124.163836 -278.017224)
		(end 124.154946 -278.012144)
		(width 0.088646)
		(layer "In11.Cu")
		(net "M_H_CPU1_SA_DQ<8>")
	)
	(segment
		(start 173.76394 -315.88964)
		(end 171.669456 -315.88964)
		(width 0.18288)
		(layer "In11.Cu")
		(net "M_H_CPU1_SA_DQ<8>")
	)
	(segment
		(start 136.850882 -283.714444)
		(end 136.841992 -283.709364)
		(width 0.088646)
		(layer "In11.Cu")
		(net "M_H_CPU1_SA_DQ<8>")
	)
	(segment
		(start 125.103636 -279.644856)
		(end 125.094746 -279.639776)
		(width 0.088646)
		(layer "In11.Cu")
		(net "M_H_CPU1_SA_DQ<8>")
	)
	(segment
		(start 160.786318 -313.34329)
		(end 160.565084 -313.122056)
		(width 0.18288)
		(layer "In11.Cu")
		(net "M_H_CPU1_SA_DQ<8>")
	)
	(segment
		(start 136.841992 -283.709364)
		(end 136.835896 -283.705808)
		(width 0.088646)
		(layer "In11.Cu")
		(net "M_H_CPU1_SA_DQ<8>")
	)
	(segment
		(start 137.499598 -284.863032)
		(end 137.499598 -284.847538)
		(width 0.088646)
		(layer "In11.Cu")
		(net "M_H_CPU1_SA_DQ<8>")
	)
	(segment
		(start 124.633482 -278.83104)
		(end 124.624592 -278.82596)
		(width 0.088646)
		(layer "In11.Cu")
		(net "M_H_CPU1_SA_DQ<8>")
	)
	(segment
		(start 202.379326 -308.343808)
		(end 202.174602 -308.837838)
		(width 0.18288)
		(layer "In11.Cu")
		(net "M_H_CPU1_SA_DQ<8>")
	)
	(segment
		(start 181.372764 -314.291218)
		(end 179.722018 -314.291218)
		(width 0.18288)
		(layer "In11.Cu")
		(net "M_H_CPU1_SA_DQ<8>")
	)
	(segment
		(start 166.643304 -314.46597)
		(end 165.258496 -313.081162)
		(width 0.18288)
		(layer "In11.Cu")
		(net "M_H_CPU1_SA_DQ<8>")
	)
	(segment
		(start 179.379626 -313.948826)
		(end 178.897026 -313.948826)
		(width 0.18288)
		(layer "In11.Cu")
		(net "M_H_CPU1_SA_DQ<8>")
	)
	(segment
		(start 124.14885 -277.03653)
		(end 124.154946 -277.032974)
		(width 0.088646)
		(layer "In11.Cu")
		(net "M_H_CPU1_SA_DQ<8>")
	)
	(segment
		(start 138.466322 -286.893)
		(end 138.466322 -286.346646)
		(width 0.088646)
		(layer "In11.Cu")
		(net "M_H_CPU1_SA_DQ<8>")
	)
	(segment
		(start 183.823102 -313.45759)
		(end 183.697118 -313.331606)
		(width 0.18288)
		(layer "In11.Cu")
		(net "M_H_CPU1_SA_DQ<8>")
	)
	(segment
		(start 202.541886 -307.64226)
		(end 202.379326 -308.034436)
		(width 0.18288)
		(layer "In11.Cu")
		(net "M_H_CPU1_SA_DQ<8>")
	)
	(arc
		(start 128.853946 -281.267662)
		(mid 128.666748 -281.217519)
		(end 128.47955 -281.267662)
		(width 0.088646)
		(layer "In11.Cu")
		(net "M_H_CPU1_SA_DQ<8>")
	)
	(arc
		(start 135.432292 -282.895548)
		(mid 135.230006 -282.696567)
		(end 135.149844 -282.424378)
		(width 0.088646)
		(layer "In11.Cu")
		(net "M_H_CPU1_SA_DQ<8>")
	)
	(arc
		(start 137.969244 -285.661354)
		(mid 137.921565 -285.478454)
		(end 137.790682 -285.342076)
		(width 0.088646)
		(layer "In11.Cu")
		(net "M_H_CPU1_SA_DQ<8>")
	)
	(arc
		(start 126.504446 -280.453846)
		(mid 126.317248 -280.403703)
		(end 126.13005 -280.453846)
		(width 0.088646)
		(layer "In11.Cu")
		(net "M_H_CPU1_SA_DQ<8>")
	)
	(arc
		(start 129.41935 -281.267662)
		(mid 129.145151 -281.343497)
		(end 128.868678 -281.276298)
		(width 0.088646)
		(layer "In11.Cu")
		(net "M_H_CPU1_SA_DQ<8>")
	)
	(arc
		(start 137.029444 -284.033722)
		(mid 136.981765 -283.850822)
		(end 136.850882 -283.714444)
		(width 0.088646)
		(layer "In11.Cu")
		(net "M_H_CPU1_SA_DQ<8>")
	)
	(arc
		(start 136.372092 -282.895548)
		(mid 136.184894 -282.845405)
		(end 135.997696 -282.895548)
		(width 0.088646)
		(layer "In11.Cu")
		(net "M_H_CPU1_SA_DQ<8>")
	)
	(arc
		(start 134.95655 -282.077922)
		(mid 134.753963 -281.871571)
		(end 134.679944 -281.59202)
		(width 0.088646)
		(layer "In11.Cu")
		(net "M_H_CPU1_SA_DQ<8>")
	)
	(arc
		(start 132.23875 -281.267662)
		(mid 131.964551 -281.343497)
		(end 131.688078 -281.276298)
		(width 0.088646)
		(layer "In11.Cu")
		(net "M_H_CPU1_SA_DQ<8>")
	)
	(arc
		(start 124.163836 -277.027894)
		(mid 124.279645 -276.915965)
		(end 124.337826 -276.765766)
		(width 0.088646)
		(layer "In11.Cu")
		(net "M_H_CPU1_SA_DQ<8>")
	)
	(arc
		(start 130.35915 -281.267662)
		(mid 130.084951 -281.343497)
		(end 129.808478 -281.276298)
		(width 0.088646)
		(layer "In11.Cu")
		(net "M_H_CPU1_SA_DQ<8>")
	)
	(arc
		(start 138.251946 -286.151066)
		(mid 138.048465 -285.950262)
		(end 137.969244 -285.675578)
		(width 0.088646)
		(layer "In11.Cu")
		(net "M_H_CPU1_SA_DQ<8>")
	)
	(arc
		(start 128.47955 -281.267662)
		(mid 128.205351 -281.343497)
		(end 127.928878 -281.276298)
		(width 0.088646)
		(layer "In11.Cu")
		(net "M_H_CPU1_SA_DQ<8>")
	)
	(arc
		(start 130.733546 -281.267662)
		(mid 130.546348 -281.217519)
		(end 130.35915 -281.267662)
		(width 0.088646)
		(layer "In11.Cu")
		(net "M_H_CPU1_SA_DQ<8>")
	)
	(arc
		(start 137.30605 -284.519624)
		(mid 137.103463 -284.313273)
		(end 137.029444 -284.033722)
		(width 0.088646)
		(layer "In11.Cu")
		(net "M_H_CPU1_SA_DQ<8>")
	)
	(arc
		(start 132.613146 -281.267662)
		(mid 132.425948 -281.217519)
		(end 132.23875 -281.267662)
		(width 0.088646)
		(layer "In11.Cu")
		(net "M_H_CPU1_SA_DQ<8>")
	)
	(arc
		(start 123.872244 -277.522432)
		(mid 123.946235 -277.242866)
		(end 124.14885 -277.03653)
		(width 0.088646)
		(layer "In11.Cu")
		(net "M_H_CPU1_SA_DQ<8>")
	)
	(arc
		(start 137.781792 -285.336996)
		(mid 137.578969 -285.136765)
		(end 137.499598 -284.863032)
		(width 0.088646)
		(layer "In11.Cu")
		(net "M_H_CPU1_SA_DQ<8>")
	)
	(arc
		(start 135.149844 -282.3972)
		(mid 135.097574 -282.214835)
		(end 134.962646 -282.081478)
		(width 0.088646)
		(layer "In11.Cu")
		(net "M_H_CPU1_SA_DQ<8>")
	)
	(arc
		(start 137.499598 -284.847538)
		(mid 137.451919 -284.664638)
		(end 137.321036 -284.52826)
		(width 0.088646)
		(layer "In11.Cu")
		(net "M_H_CPU1_SA_DQ<8>")
	)
	(arc
		(start 127.90805 -281.264106)
		(mid 127.705463 -281.057755)
		(end 127.631444 -280.778204)
		(width 0.088646)
		(layer "In11.Cu")
		(net "M_H_CPU1_SA_DQ<8>")
	)
	(arc
		(start 125.564392 -280.453846)
		(mid 125.36311 -280.256359)
		(end 125.282198 -279.986232)
		(width 0.088646)
		(layer "In11.Cu")
		(net "M_H_CPU1_SA_DQ<8>")
	)
	(arc
		(start 125.08865 -279.63622)
		(mid 124.886063 -279.429869)
		(end 124.812044 -279.150318)
		(width 0.088646)
		(layer "In11.Cu")
		(net "M_H_CPU1_SA_DQ<8>")
	)
	(arc
		(start 134.679944 -281.583384)
		(mid 134.627674 -281.401019)
		(end 134.492746 -281.267662)
		(width 0.088646)
		(layer "In11.Cu")
		(net "M_H_CPU1_SA_DQ<8>")
	)
	(arc
		(start 124.624592 -278.82596)
		(mid 124.421769 -278.625729)
		(end 124.342398 -278.351996)
		(width 0.088646)
		(layer "In11.Cu")
		(net "M_H_CPU1_SA_DQ<8>")
	)
	(arc
		(start 135.997696 -282.895548)
		(mid 135.714994 -282.97129)
		(end 135.432292 -282.895548)
		(width 0.088646)
		(layer "In11.Cu")
		(net "M_H_CPU1_SA_DQ<8>")
	)
	(arc
		(start 131.673346 -281.267662)
		(mid 131.486148 -281.217519)
		(end 131.29895 -281.267662)
		(width 0.088646)
		(layer "In11.Cu")
		(net "M_H_CPU1_SA_DQ<8>")
	)
	(arc
		(start 136.559544 -283.219906)
		(mid 136.511865 -283.037006)
		(end 136.380982 -282.900628)
		(width 0.088646)
		(layer "In11.Cu")
		(net "M_H_CPU1_SA_DQ<8>")
	)
	(arc
		(start 131.29895 -281.267662)
		(mid 131.024751 -281.343497)
		(end 130.748278 -281.276298)
		(width 0.088646)
		(layer "In11.Cu")
		(net "M_H_CPU1_SA_DQ<8>")
	)
	(arc
		(start 126.119636 -280.459942)
		(mid 125.841204 -280.529756)
		(end 125.564392 -280.453846)
		(width 0.088646)
		(layer "In11.Cu")
		(net "M_H_CPU1_SA_DQ<8>")
	)
	(arc
		(start 129.793746 -281.267662)
		(mid 129.606548 -281.217519)
		(end 129.41935 -281.267662)
		(width 0.088646)
		(layer "In11.Cu")
		(net "M_H_CPU1_SA_DQ<8>")
	)
	(arc
		(start 127.069596 -280.453846)
		(mid 126.793037 -280.529555)
		(end 126.51486 -280.459942)
		(width 0.088646)
		(layer "In11.Cu")
		(net "M_H_CPU1_SA_DQ<8>")
	)
	(arc
		(start 125.282198 -279.964134)
		(mid 125.234519 -279.781234)
		(end 125.103636 -279.644856)
		(width 0.088646)
		(layer "In11.Cu")
		(net "M_H_CPU1_SA_DQ<8>")
	)
	(arc
		(start 124.154946 -278.012144)
		(mid 123.951465 -277.81134)
		(end 123.872244 -277.536656)
		(width 0.088646)
		(layer "In11.Cu")
		(net "M_H_CPU1_SA_DQ<8>")
	)
	(arc
		(start 124.342398 -278.336502)
		(mid 124.294719 -278.153602)
		(end 124.163836 -278.017224)
		(width 0.088646)
		(layer "In11.Cu")
		(net "M_H_CPU1_SA_DQ<8>")
	)
	(arc
		(start 138.329924 -286.210248)
		(mid 138.292874 -286.178102)
		(end 138.251946 -286.151066)
		(width 0.088646)
		(layer "In11.Cu")
		(net "M_H_CPU1_SA_DQ<8>")
	)
	(arc
		(start 127.631444 -280.778204)
		(mid 127.583765 -280.595304)
		(end 127.452882 -280.458926)
		(width 0.088646)
		(layer "In11.Cu")
		(net "M_H_CPU1_SA_DQ<8>")
	)
	(arc
		(start 133.552946 -281.267662)
		(mid 133.365748 -281.217519)
		(end 133.17855 -281.267662)
		(width 0.088646)
		(layer "In11.Cu")
		(net "M_H_CPU1_SA_DQ<8>")
	)
	(arc
		(start 134.11835 -281.267662)
		(mid 133.844151 -281.343497)
		(end 133.567678 -281.276298)
		(width 0.088646)
		(layer "In11.Cu")
		(net "M_H_CPU1_SA_DQ<8>")
	)
	(arc
		(start 124.812044 -279.150318)
		(mid 124.764365 -278.967418)
		(end 124.633482 -278.83104)
		(width 0.088646)
		(layer "In11.Cu")
		(net "M_H_CPU1_SA_DQ<8>")
	)
	(arc
		(start 134.492746 -281.267662)
		(mid 134.305548 -281.217519)
		(end 134.11835 -281.267662)
		(width 0.088646)
		(layer "In11.Cu")
		(net "M_H_CPU1_SA_DQ<8>")
	)
	(arc
		(start 127.443992 -280.453846)
		(mid 127.256794 -280.403703)
		(end 127.069596 -280.453846)
		(width 0.088646)
		(layer "In11.Cu")
		(net "M_H_CPU1_SA_DQ<8>")
	)
	(arc
		(start 136.835896 -283.705808)
		(mid 136.633483 -283.499395)
		(end 136.559544 -283.219906)
		(width 0.088646)
		(layer "In11.Cu")
		(net "M_H_CPU1_SA_DQ<8>")
	)
	(arc
		(start 133.17855 -281.267662)
		(mid 132.904351 -281.343497)
		(end 132.627878 -281.276298)
		(width 0.088646)
		(layer "In11.Cu")
		(net "M_H_CPU1_SA_DQ<8>")
	)
	(segment
		(start 213.311486 -308.253892)
		(end 213.515448 -308.04993)
		(width 0.20066)
		(layer "F.Cu")
		(net "M_H_CPU1_SA_DQ<7>")
	)
	(segment
		(start 208.176114 -307.816758)
		(end 209.874358 -307.816758)
		(width 0.20066)
		(layer "F.Cu")
		(net "M_H_CPU1_SA_DQ<7>")
	)
	(segment
		(start 210.610196 -308.2417)
		(end 212.618066 -308.2417)
		(width 0.1016)
		(layer "F.Cu")
		(net "M_H_CPU1_SA_DQ<7>")
	)
	(segment
		(start 213.515448 -307.798978)
		(end 213.749636 -307.56479)
		(width 0.20066)
		(layer "F.Cu")
		(net "M_H_CPU1_SA_DQ<7>")
	)
	(segment
		(start 128.196848 -275.35886)
		(end 128.196848 -275.894546)
		(width 0.20066)
		(layer "F.Cu")
		(net "M_H_CPU1_SA_DQ<7>")
	)
	(segment
		(start 210.306412 -308.248812)
		(end 210.598258 -308.248812)
		(width 0.20066)
		(layer "F.Cu")
		(net "M_H_CPU1_SA_DQ<7>")
	)
	(segment
		(start 128.196848 -275.894546)
		(end 128.196594 -275.8948)
		(width 0.20066)
		(layer "F.Cu")
		(net "M_H_CPU1_SA_DQ<7>")
	)
	(segment
		(start 212.630258 -308.253892)
		(end 213.311486 -308.253892)
		(width 0.20066)
		(layer "F.Cu")
		(net "M_H_CPU1_SA_DQ<7>")
	)
	(segment
		(start 212.618066 -308.2417)
		(end 212.630258 -308.253892)
		(width 0.1016)
		(layer "F.Cu")
		(net "M_H_CPU1_SA_DQ<7>")
	)
	(segment
		(start 207.071214 -307.816758)
		(end 208.176114 -307.816758)
		(width 0.20066)
		(layer "F.Cu")
		(net "M_H_CPU1_SA_DQ<7>")
	)
	(segment
		(start 210.598258 -308.248812)
		(end 210.603084 -308.248812)
		(width 0.101854)
		(layer "F.Cu")
		(net "M_H_CPU1_SA_DQ<7>")
	)
	(segment
		(start 210.603084 -308.248812)
		(end 210.610196 -308.2417)
		(width 0.1016)
		(layer "F.Cu")
		(net "M_H_CPU1_SA_DQ<7>")
	)
	(segment
		(start 213.749636 -307.56479)
		(end 214.133684 -307.56479)
		(width 0.20066)
		(layer "F.Cu")
		(net "M_H_CPU1_SA_DQ<7>")
	)
	(segment
		(start 213.515448 -308.04993)
		(end 213.515448 -307.798978)
		(width 0.20066)
		(layer "F.Cu")
		(net "M_H_CPU1_SA_DQ<7>")
	)
	(segment
		(start 214.385652 -307.816758)
		(end 215.719914 -307.816758)
		(width 0.20066)
		(layer "F.Cu")
		(net "M_H_CPU1_SA_DQ<7>")
	)
	(segment
		(start 209.874358 -307.816758)
		(end 210.306412 -308.248812)
		(width 0.20066)
		(layer "F.Cu")
		(net "M_H_CPU1_SA_DQ<7>")
	)
	(segment
		(start 214.133684 -307.56479)
		(end 214.385652 -307.816758)
		(width 0.20066)
		(layer "F.Cu")
		(net "M_H_CPU1_SA_DQ<7>")
	)
	(segment
		(start 175.621188 -303.454054)
		(end 175.30953 -303.142396)
		(width 0.18288)
		(layer "In6.Cu")
		(net "M_H_CPU1_SA_DQ<7>")
	)
	(segment
		(start 168.834054 -302.857154)
		(end 168.834054 -302.631094)
		(width 0.18288)
		(layer "In6.Cu")
		(net "M_H_CPU1_SA_DQ<7>")
	)
	(segment
		(start 134.498334 -275.401786)
		(end 134.492746 -275.405088)
		(width 0.088646)
		(layer "In6.Cu")
		(net "M_H_CPU1_SA_DQ<7>")
	)
	(segment
		(start 164.51326 -299.742352)
		(end 163.778692 -299.742352)
		(width 0.18288)
		(layer "In6.Cu")
		(net "M_H_CPU1_SA_DQ<7>")
	)
	(segment
		(start 170.082972 -303.134776)
		(end 169.810176 -302.86198)
		(width 0.18288)
		(layer "In6.Cu")
		(net "M_H_CPU1_SA_DQ<7>")
	)
	(segment
		(start 170.297602 -304.159666)
		(end 170.03903 -304.159666)
		(width 0.18288)
		(layer "In6.Cu")
		(net "M_H_CPU1_SA_DQ<7>")
	)
	(segment
		(start 168.112694 -301.390558)
		(end 168.112694 -301.164498)
		(width 0.18288)
		(layer "In6.Cu")
		(net "M_H_CPU1_SA_DQ<7>")
	)
	(segment
		(start 160.469834 -299.232828)
		(end 160.237932 -299.000926)
		(width 0.18288)
		(layer "In6.Cu")
		(net "M_H_CPU1_SA_DQ<7>")
	)
	(segment
		(start 133.563106 -275.398992)
		(end 133.552692 -275.405088)
		(width 0.088646)
		(layer "In6.Cu")
		(net "M_H_CPU1_SA_DQ<7>")
	)
	(segment
		(start 183.888126 -307.392578)
		(end 183.230774 -306.735226)
		(width 0.18288)
		(layer "In6.Cu")
		(net "M_H_CPU1_SA_DQ<7>")
	)
	(segment
		(start 176.314608 -303.142396)
		(end 176.00295 -303.454054)
		(width 0.18288)
		(layer "In6.Cu")
		(net "M_H_CPU1_SA_DQ<7>")
	)
	(segment
		(start 167.892222 -300.944026)
		(end 166.920926 -300.944026)
		(width 0.18288)
		(layer "In6.Cu")
		(net "M_H_CPU1_SA_DQ<7>")
	)
	(segment
		(start 161.422842 -298.796964)
		(end 161.16427 -298.796964)
		(width 0.18288)
		(layer "In6.Cu")
		(net "M_H_CPU1_SA_DQ<7>")
	)
	(segment
		(start 169.810176 -302.86198)
		(end 169.584116 -302.86198)
		(width 0.18288)
		(layer "In6.Cu")
		(net "M_H_CPU1_SA_DQ<7>")
	)
	(segment
		(start 159.112204 -298.123356)
		(end 158.784544 -298.123356)
		(width 0.18288)
		(layer "In6.Cu")
		(net "M_H_CPU1_SA_DQ<7>")
	)
	(segment
		(start 169.807128 -303.927764)
		(end 169.807128 -303.669192)
		(width 0.18288)
		(layer "In6.Cu")
		(net "M_H_CPU1_SA_DQ<7>")
	)
	(segment
		(start 170.573446 -303.883822)
		(end 170.297602 -304.159666)
		(width 0.18288)
		(layer "In6.Cu")
		(net "M_H_CPU1_SA_DQ<7>")
	)
	(segment
		(start 173.334426 -303.992026)
		(end 170.940222 -303.992026)
		(width 0.18288)
		(layer "In6.Cu")
		(net "M_H_CPU1_SA_DQ<7>")
	)
	(segment
		(start 170.082972 -303.393348)
		(end 170.082972 -303.134776)
		(width 0.18288)
		(layer "In6.Cu")
		(net "M_H_CPU1_SA_DQ<7>")
	)
	(segment
		(start 188.809122 -307.392578)
		(end 183.888126 -307.392578)
		(width 0.18288)
		(layer "In6.Cu")
		(net "M_H_CPU1_SA_DQ<7>")
	)
	(segment
		(start 165.468046 -299.491146)
		(end 164.764466 -299.491146)
		(width 0.18288)
		(layer "In6.Cu")
		(net "M_H_CPU1_SA_DQ<7>")
	)
	(segment
		(start 159.295084 -297.940476)
		(end 159.112204 -298.123356)
		(width 0.18288)
		(layer "In6.Cu")
		(net "M_H_CPU1_SA_DQ<7>")
	)
	(segment
		(start 177.323496 -303.142396)
		(end 176.314608 -303.142396)
		(width 0.18288)
		(layer "In6.Cu")
		(net "M_H_CPU1_SA_DQ<7>")
	)
	(segment
		(start 168.112694 -301.164498)
		(end 167.892222 -300.944026)
		(width 0.18288)
		(layer "In6.Cu")
		(net "M_H_CPU1_SA_DQ<7>")
	)
	(segment
		(start 130.748278 -275.396452)
		(end 130.733546 -275.405088)
		(width 0.088646)
		(layer "In6.Cu")
		(net "M_H_CPU1_SA_DQ<7>")
	)
	(segment
		(start 202.769724 -308.242716)
		(end 201.948288 -307.42128)
		(width 0.18288)
		(layer "In6.Cu")
		(net "M_H_CPU1_SA_DQ<7>")
	)
	(segment
		(start 169.324528 -303.121568)
		(end 169.098468 -303.121568)
		(width 0.18288)
		(layer "In6.Cu")
		(net "M_H_CPU1_SA_DQ<7>")
	)
	(segment
		(start 131.688078 -275.396452)
		(end 131.673346 -275.405088)
		(width 0.088646)
		(layer "In6.Cu")
		(net "M_H_CPU1_SA_DQ<7>")
	)
	(segment
		(start 170.03903 -304.159666)
		(end 169.807128 -303.927764)
		(width 0.18288)
		(layer "In6.Cu")
		(net "M_H_CPU1_SA_DQ<7>")
	)
	(segment
		(start 136.387078 -275.396706)
		(end 136.372346 -275.405342)
		(width 0.088646)
		(layer "In6.Cu")
		(net "M_H_CPU1_SA_DQ<7>")
	)
	(segment
		(start 168.829228 -301.881032)
		(end 168.603168 -301.881032)
		(width 0.18288)
		(layer "In6.Cu")
		(net "M_H_CPU1_SA_DQ<7>")
	)
	(segment
		(start 132.62356 -275.398992)
		(end 132.613146 -275.405088)
		(width 0.088646)
		(layer "In6.Cu")
		(net "M_H_CPU1_SA_DQ<7>")
	)
	(segment
		(start 170.940222 -303.992026)
		(end 170.832018 -303.883822)
		(width 0.18288)
		(layer "In6.Cu")
		(net "M_H_CPU1_SA_DQ<7>")
	)
	(segment
		(start 169.093642 -302.371506)
		(end 169.093642 -302.145446)
		(width 0.18288)
		(layer "In6.Cu")
		(net "M_H_CPU1_SA_DQ<7>")
	)
	(segment
		(start 206.645256 -308.242716)
		(end 202.769724 -308.242716)
		(width 0.18288)
		(layer "In6.Cu")
		(net "M_H_CPU1_SA_DQ<7>")
	)
	(segment
		(start 138.266678 -275.396706)
		(end 138.251946 -275.405342)
		(width 0.088646)
		(layer "In6.Cu")
		(net "M_H_CPU1_SA_DQ<7>")
	)
	(segment
		(start 174.184056 -303.142396)
		(end 173.334426 -303.992026)
		(width 0.18288)
		(layer "In6.Cu")
		(net "M_H_CPU1_SA_DQ<7>")
	)
	(segment
		(start 160.673796 -298.30649)
		(end 160.673796 -298.047918)
		(width 0.18288)
		(layer "In6.Cu")
		(net "M_H_CPU1_SA_DQ<7>")
	)
	(segment
		(start 168.834054 -302.631094)
		(end 169.093642 -302.371506)
		(width 0.18288)
		(layer "In6.Cu")
		(net "M_H_CPU1_SA_DQ<7>")
	)
	(segment
		(start 180.563774 -304.906426)
		(end 180.134514 -304.906426)
		(width 0.18288)
		(layer "In6.Cu")
		(net "M_H_CPU1_SA_DQ<7>")
	)
	(segment
		(start 158.601664 -297.40606)
		(end 158.418784 -297.22318)
		(width 0.18288)
		(layer "In6.Cu")
		(net "M_H_CPU1_SA_DQ<7>")
	)
	(segment
		(start 140.193522 -277.76043)
		(end 139.569444 -277.136352)
		(width 0.088646)
		(layer "In6.Cu")
		(net "M_H_CPU1_SA_DQ<7>")
	)
	(segment
		(start 167.912542 -301.59071)
		(end 168.112694 -301.390558)
		(width 0.18288)
		(layer "In6.Cu")
		(net "M_H_CPU1_SA_DQ<7>")
	)
	(segment
		(start 159.849058 -297.22318)
		(end 159.477964 -297.22318)
		(width 0.18288)
		(layer "In6.Cu")
		(net "M_H_CPU1_SA_DQ<7>")
	)
	(segment
		(start 169.098468 -303.121568)
		(end 168.834054 -302.857154)
		(width 0.18288)
		(layer "In6.Cu")
		(net "M_H_CPU1_SA_DQ<7>")
	)
	(segment
		(start 189.435486 -306.766214)
		(end 188.809122 -307.392578)
		(width 0.18288)
		(layer "In6.Cu")
		(net "M_H_CPU1_SA_DQ<7>")
	)
	(segment
		(start 158.601664 -297.940476)
		(end 158.601664 -297.40606)
		(width 0.18288)
		(layer "In6.Cu")
		(net "M_H_CPU1_SA_DQ<7>")
	)
	(segment
		(start 127.826516 -275.952204)
		(end 127.88392 -275.8948)
		(width 0.088646)
		(layer "In6.Cu")
		(net "M_H_CPU1_SA_DQ<7>")
	)
	(segment
		(start 179.372514 -304.144426)
		(end 178.325526 -304.144426)
		(width 0.18288)
		(layer "In6.Cu")
		(net "M_H_CPU1_SA_DQ<7>")
	)
	(segment
		(start 150.963122 -282.325064)
		(end 146.636994 -277.998936)
		(width 0.18288)
		(layer "In6.Cu")
		(net "M_H_CPU1_SA_DQ<7>")
	)
	(segment
		(start 164.764466 -299.491146)
		(end 164.51326 -299.742352)
		(width 0.18288)
		(layer "In6.Cu")
		(net "M_H_CPU1_SA_DQ<7>")
	)
	(segment
		(start 191.27851 -306.766214)
		(end 189.435486 -306.766214)
		(width 0.18288)
		(layer "In6.Cu")
		(net "M_H_CPU1_SA_DQ<7>")
	)
	(segment
		(start 139.286996 -276.219158)
		(end 139.278106 -276.214078)
		(width 0.088646)
		(layer "In6.Cu")
		(net "M_H_CPU1_SA_DQ<7>")
	)
	(segment
		(start 158.418784 -297.22318)
		(end 157.036008 -297.22318)
		(width 0.18288)
		(layer "In6.Cu")
		(net "M_H_CPU1_SA_DQ<7>")
	)
	(segment
		(start 182.392574 -306.735226)
		(end 180.563774 -304.906426)
		(width 0.18288)
		(layer "In6.Cu")
		(net "M_H_CPU1_SA_DQ<7>")
	)
	(segment
		(start 161.518092 -298.892214)
		(end 161.422842 -298.796964)
		(width 0.18288)
		(layer "In6.Cu")
		(net "M_H_CPU1_SA_DQ<7>")
	)
	(segment
		(start 146.636994 -277.998936)
		(end 141.451076 -277.998936)
		(width 0.18288)
		(layer "In6.Cu")
		(net "M_H_CPU1_SA_DQ<7>")
	)
	(segment
		(start 169.584116 -302.86198)
		(end 169.324528 -303.121568)
		(width 0.18288)
		(layer "In6.Cu")
		(net "M_H_CPU1_SA_DQ<7>")
	)
	(segment
		(start 196.403722 -306.542694)
		(end 191.81826 -306.542694)
		(width 0.18288)
		(layer "In6.Cu")
		(net "M_H_CPU1_SA_DQ<7>")
	)
	(segment
		(start 135.447278 -275.396706)
		(end 135.432546 -275.405342)
		(width 0.088646)
		(layer "In6.Cu")
		(net "M_H_CPU1_SA_DQ<7>")
	)
	(segment
		(start 159.295084 -297.40606)
		(end 159.295084 -297.940476)
		(width 0.18288)
		(layer "In6.Cu")
		(net "M_H_CPU1_SA_DQ<7>")
	)
	(segment
		(start 159.477964 -297.22318)
		(end 159.295084 -297.40606)
		(width 0.18288)
		(layer "In6.Cu")
		(net "M_H_CPU1_SA_DQ<7>")
	)
	(segment
		(start 141.451076 -277.998936)
		(end 140.875258 -277.76043)
		(width 0.18288)
		(layer "In6.Cu")
		(net "M_H_CPU1_SA_DQ<7>")
	)
	(segment
		(start 137.326878 -275.396706)
		(end 137.312146 -275.405342)
		(width 0.088646)
		(layer "In6.Cu")
		(net "M_H_CPU1_SA_DQ<7>")
	)
	(segment
		(start 158.784544 -298.123356)
		(end 158.601664 -297.940476)
		(width 0.18288)
		(layer "In6.Cu")
		(net "M_H_CPU1_SA_DQ<7>")
	)
	(segment
		(start 160.237932 -299.000926)
		(end 160.237932 -298.742354)
		(width 0.18288)
		(layer "In6.Cu")
		(net "M_H_CPU1_SA_DQ<7>")
	)
	(segment
		(start 175.30953 -303.142396)
		(end 174.184056 -303.142396)
		(width 0.18288)
		(layer "In6.Cu")
		(net "M_H_CPU1_SA_DQ<7>")
	)
	(segment
		(start 168.603168 -301.881032)
		(end 168.403016 -302.081184)
		(width 0.18288)
		(layer "In6.Cu")
		(net "M_H_CPU1_SA_DQ<7>")
	)
	(segment
		(start 161.16427 -298.796964)
		(end 160.728406 -299.232828)
		(width 0.18288)
		(layer "In6.Cu")
		(net "M_H_CPU1_SA_DQ<7>")
	)
	(segment
		(start 160.728406 -299.232828)
		(end 160.469834 -299.232828)
		(width 0.18288)
		(layer "In6.Cu")
		(net "M_H_CPU1_SA_DQ<7>")
	)
	(segment
		(start 128.392682 -276.214078)
		(end 128.383792 -276.219158)
		(width 0.088646)
		(layer "In6.Cu")
		(net "M_H_CPU1_SA_DQ<7>")
	)
	(segment
		(start 139.569444 -277.136352)
		(end 139.569444 -276.69871)
		(width 0.088646)
		(layer "In6.Cu")
		(net "M_H_CPU1_SA_DQ<7>")
	)
	(segment
		(start 127.88392 -275.8948)
		(end 128.196594 -275.8948)
		(width 0.088646)
		(layer "In6.Cu")
		(net "M_H_CPU1_SA_DQ<7>")
	)
	(segment
		(start 160.237932 -298.742354)
		(end 160.673796 -298.30649)
		(width 0.18288)
		(layer "In6.Cu")
		(net "M_H_CPU1_SA_DQ<7>")
	)
	(segment
		(start 168.403016 -302.081184)
		(end 168.176956 -302.081184)
		(width 0.18288)
		(layer "In6.Cu")
		(net "M_H_CPU1_SA_DQ<7>")
	)
	(segment
		(start 169.807128 -303.669192)
		(end 170.082972 -303.393348)
		(width 0.18288)
		(layer "In6.Cu")
		(net "M_H_CPU1_SA_DQ<7>")
	)
	(segment
		(start 176.00295 -303.454054)
		(end 175.621188 -303.454054)
		(width 0.18288)
		(layer "In6.Cu")
		(net "M_H_CPU1_SA_DQ<7>")
	)
	(segment
		(start 207.071214 -307.816758)
		(end 206.645256 -308.242716)
		(width 0.18288)
		(layer "In6.Cu")
		(net "M_H_CPU1_SA_DQ<7>")
	)
	(segment
		(start 129.808478 -275.396452)
		(end 129.793746 -275.405088)
		(width 0.088646)
		(layer "In6.Cu")
		(net "M_H_CPU1_SA_DQ<7>")
	)
	(segment
		(start 201.948288 -307.42128)
		(end 198.607426 -307.42128)
		(width 0.18288)
		(layer "In6.Cu")
		(net "M_H_CPU1_SA_DQ<7>")
	)
	(segment
		(start 168.176956 -302.081184)
		(end 167.912542 -301.81677)
		(width 0.18288)
		(layer "In6.Cu")
		(net "M_H_CPU1_SA_DQ<7>")
	)
	(segment
		(start 160.673796 -298.047918)
		(end 159.849058 -297.22318)
		(width 0.18288)
		(layer "In6.Cu")
		(net "M_H_CPU1_SA_DQ<7>")
	)
	(segment
		(start 180.134514 -304.906426)
		(end 179.372514 -304.144426)
		(width 0.18288)
		(layer "In6.Cu")
		(net "M_H_CPU1_SA_DQ<7>")
	)
	(segment
		(start 140.367258 -277.76043)
		(end 140.193522 -277.76043)
		(width 0.088646)
		(layer "In6.Cu")
		(net "M_H_CPU1_SA_DQ<7>")
	)
	(segment
		(start 169.093642 -302.145446)
		(end 168.829228 -301.881032)
		(width 0.18288)
		(layer "In6.Cu")
		(net "M_H_CPU1_SA_DQ<7>")
	)
	(segment
		(start 198.607426 -307.42128)
		(end 196.403722 -306.542694)
		(width 0.18288)
		(layer "In6.Cu")
		(net "M_H_CPU1_SA_DQ<7>")
	)
	(segment
		(start 162.928554 -298.892214)
		(end 161.518092 -298.892214)
		(width 0.18288)
		(layer "In6.Cu")
		(net "M_H_CPU1_SA_DQ<7>")
	)
	(segment
		(start 178.325526 -304.144426)
		(end 177.323496 -303.142396)
		(width 0.18288)
		(layer "In6.Cu")
		(net "M_H_CPU1_SA_DQ<7>")
	)
	(segment
		(start 183.230774 -306.735226)
		(end 182.392574 -306.735226)
		(width 0.18288)
		(layer "In6.Cu")
		(net "M_H_CPU1_SA_DQ<7>")
	)
	(segment
		(start 191.727582 -306.580286)
		(end 191.27851 -306.766214)
		(width 0.18288)
		(layer "In6.Cu")
		(net "M_H_CPU1_SA_DQ<7>")
	)
	(segment
		(start 167.912542 -301.81677)
		(end 167.912542 -301.59071)
		(width 0.18288)
		(layer "In6.Cu")
		(net "M_H_CPU1_SA_DQ<7>")
	)
	(segment
		(start 170.832018 -303.883822)
		(end 170.573446 -303.883822)
		(width 0.18288)
		(layer "In6.Cu")
		(net "M_H_CPU1_SA_DQ<7>")
	)
	(segment
		(start 128.571244 -275.88718)
		(end 128.571244 -275.8948)
		(width 0.088646)
		(layer "In6.Cu")
		(net "M_H_CPU1_SA_DQ<7>")
	)
	(segment
		(start 157.036008 -297.22318)
		(end 150.963122 -291.150294)
		(width 0.18288)
		(layer "In6.Cu")
		(net "M_H_CPU1_SA_DQ<7>")
	)
	(segment
		(start 128.009396 -276.219158)
		(end 128.000506 -276.214078)
		(width 0.088646)
		(layer "In6.Cu")
		(net "M_H_CPU1_SA_DQ<7>")
	)
	(segment
		(start 191.81826 -306.542694)
		(end 191.727582 -306.580286)
		(width 0.18288)
		(layer "In6.Cu")
		(net "M_H_CPU1_SA_DQ<7>")
	)
	(segment
		(start 166.920926 -300.944026)
		(end 165.468046 -299.491146)
		(width 0.18288)
		(layer "In6.Cu")
		(net "M_H_CPU1_SA_DQ<7>")
	)
	(segment
		(start 150.963122 -291.150294)
		(end 150.963122 -282.325064)
		(width 0.18288)
		(layer "In6.Cu")
		(net "M_H_CPU1_SA_DQ<7>")
	)
	(segment
		(start 163.778692 -299.742352)
		(end 162.928554 -298.892214)
		(width 0.18288)
		(layer "In6.Cu")
		(net "M_H_CPU1_SA_DQ<7>")
	)
	(segment
		(start 139.099544 -275.8948)
		(end 139.099544 -275.879306)
		(width 0.088646)
		(layer "In6.Cu")
		(net "M_H_CPU1_SA_DQ<7>")
	)
	(segment
		(start 140.875258 -277.76043)
		(end 140.367258 -277.76043)
		(width 0.18288)
		(layer "In6.Cu")
		(net "M_H_CPU1_SA_DQ<7>")
	)
	(arc
		(start 131.29895 -275.405088)
		(mid 131.024721 -275.329163)
		(end 130.748278 -275.396452)
		(width 0.088646)
		(layer "In6.Cu")
		(net "M_H_CPU1_SA_DQ<7>")
	)
	(arc
		(start 137.87755 -275.405342)
		(mid 137.603351 -275.329507)
		(end 137.326878 -275.396706)
		(width 0.088646)
		(layer "In6.Cu")
		(net "M_H_CPU1_SA_DQ<7>")
	)
	(arc
		(start 137.312146 -275.405342)
		(mid 137.124948 -275.455485)
		(end 136.93775 -275.405342)
		(width 0.088646)
		(layer "In6.Cu")
		(net "M_H_CPU1_SA_DQ<7>")
	)
	(arc
		(start 136.93775 -275.405342)
		(mid 136.663551 -275.329507)
		(end 136.387078 -275.396706)
		(width 0.088646)
		(layer "In6.Cu")
		(net "M_H_CPU1_SA_DQ<7>")
	)
	(arc
		(start 139.099544 -275.879306)
		(mid 139.020174 -275.605572)
		(end 138.81735 -275.405342)
		(width 0.088646)
		(layer "In6.Cu")
		(net "M_H_CPU1_SA_DQ<7>")
	)
	(arc
		(start 138.81735 -275.405342)
		(mid 138.543151 -275.329507)
		(end 138.266678 -275.396706)
		(width 0.088646)
		(layer "In6.Cu")
		(net "M_H_CPU1_SA_DQ<7>")
	)
	(arc
		(start 128.571244 -275.8948)
		(mid 128.523565 -276.0777)
		(end 128.392682 -276.214078)
		(width 0.088646)
		(layer "In6.Cu")
		(net "M_H_CPU1_SA_DQ<7>")
	)
	(arc
		(start 134.11835 -275.405088)
		(mid 133.841537 -275.329252)
		(end 133.563106 -275.398992)
		(width 0.088646)
		(layer "In6.Cu")
		(net "M_H_CPU1_SA_DQ<7>")
	)
	(arc
		(start 128.000506 -276.214078)
		(mid 127.884767 -276.102254)
		(end 127.826516 -275.952204)
		(width 0.088646)
		(layer "In6.Cu")
		(net "M_H_CPU1_SA_DQ<7>")
	)
	(arc
		(start 129.793746 -275.405088)
		(mid 129.606548 -275.455231)
		(end 129.41935 -275.405088)
		(width 0.088646)
		(layer "In6.Cu")
		(net "M_H_CPU1_SA_DQ<7>")
	)
	(arc
		(start 139.569444 -276.69871)
		(mid 139.491333 -276.421761)
		(end 139.286996 -276.219158)
		(width 0.088646)
		(layer "In6.Cu")
		(net "M_H_CPU1_SA_DQ<7>")
	)
	(arc
		(start 130.35915 -275.405088)
		(mid 130.084921 -275.329163)
		(end 129.808478 -275.396452)
		(width 0.088646)
		(layer "In6.Cu")
		(net "M_H_CPU1_SA_DQ<7>")
	)
	(arc
		(start 138.251946 -275.405342)
		(mid 138.064748 -275.455485)
		(end 137.87755 -275.405342)
		(width 0.088646)
		(layer "In6.Cu")
		(net "M_H_CPU1_SA_DQ<7>")
	)
	(arc
		(start 135.99795 -275.405342)
		(mid 135.723751 -275.329507)
		(end 135.447278 -275.396706)
		(width 0.088646)
		(layer "In6.Cu")
		(net "M_H_CPU1_SA_DQ<7>")
	)
	(arc
		(start 136.372346 -275.405342)
		(mid 136.185148 -275.455485)
		(end 135.99795 -275.405342)
		(width 0.088646)
		(layer "In6.Cu")
		(net "M_H_CPU1_SA_DQ<7>")
	)
	(arc
		(start 139.278106 -276.214078)
		(mid 139.147192 -276.077718)
		(end 139.099544 -275.8948)
		(width 0.088646)
		(layer "In6.Cu")
		(net "M_H_CPU1_SA_DQ<7>")
	)
	(arc
		(start 129.41935 -275.405088)
		(mid 129.136648 -275.329346)
		(end 128.853946 -275.405088)
		(width 0.088646)
		(layer "In6.Cu")
		(net "M_H_CPU1_SA_DQ<7>")
	)
	(arc
		(start 132.613146 -275.405088)
		(mid 132.425948 -275.455231)
		(end 132.23875 -275.405088)
		(width 0.088646)
		(layer "In6.Cu")
		(net "M_H_CPU1_SA_DQ<7>")
	)
	(arc
		(start 131.673346 -275.405088)
		(mid 131.486148 -275.455231)
		(end 131.29895 -275.405088)
		(width 0.088646)
		(layer "In6.Cu")
		(net "M_H_CPU1_SA_DQ<7>")
	)
	(arc
		(start 135.432546 -275.405342)
		(mid 135.245348 -275.455485)
		(end 135.05815 -275.405342)
		(width 0.088646)
		(layer "In6.Cu")
		(net "M_H_CPU1_SA_DQ<7>")
	)
	(arc
		(start 130.733546 -275.405088)
		(mid 130.546348 -275.455231)
		(end 130.35915 -275.405088)
		(width 0.088646)
		(layer "In6.Cu")
		(net "M_H_CPU1_SA_DQ<7>")
	)
	(arc
		(start 132.23875 -275.405088)
		(mid 131.964521 -275.329163)
		(end 131.688078 -275.396452)
		(width 0.088646)
		(layer "In6.Cu")
		(net "M_H_CPU1_SA_DQ<7>")
	)
	(arc
		(start 133.552692 -275.405088)
		(mid 133.365494 -275.455231)
		(end 133.178296 -275.405088)
		(width 0.088646)
		(layer "In6.Cu")
		(net "M_H_CPU1_SA_DQ<7>")
	)
	(arc
		(start 134.492746 -275.405088)
		(mid 134.305548 -275.455231)
		(end 134.11835 -275.405088)
		(width 0.088646)
		(layer "In6.Cu")
		(net "M_H_CPU1_SA_DQ<7>")
	)
	(arc
		(start 133.178296 -275.405088)
		(mid 132.901737 -275.329379)
		(end 132.62356 -275.398992)
		(width 0.088646)
		(layer "In6.Cu")
		(net "M_H_CPU1_SA_DQ<7>")
	)
	(arc
		(start 135.05815 -275.405342)
		(mid 134.778722 -275.32945)
		(end 134.498334 -275.401786)
		(width 0.088646)
		(layer "In6.Cu")
		(net "M_H_CPU1_SA_DQ<7>")
	)
	(arc
		(start 128.853946 -275.405088)
		(mid 128.648874 -275.608767)
		(end 128.571244 -275.88718)
		(width 0.088646)
		(layer "In6.Cu")
		(net "M_H_CPU1_SA_DQ<7>")
	)
	(arc
		(start 128.383792 -276.219158)
		(mid 128.196594 -276.269301)
		(end 128.009396 -276.219158)
		(width 0.088646)
		(layer "In6.Cu")
		(net "M_H_CPU1_SA_DQ<7>")
	)
	(segment
		(start 210.306412 -309.948834)
		(end 210.598258 -309.948834)
		(width 0.20066)
		(layer "F.Cu")
		(net "M_H_CPU1_SA_DQ<6>")
	)
	(segment
		(start 213.515448 -309.499)
		(end 213.749636 -309.264812)
		(width 0.20066)
		(layer "F.Cu")
		(net "M_H_CPU1_SA_DQ<6>")
	)
	(segment
		(start 207.071214 -309.51678)
		(end 208.176114 -309.51678)
		(width 0.20066)
		(layer "F.Cu")
		(net "M_H_CPU1_SA_DQ<6>")
	)
	(segment
		(start 210.603084 -309.948834)
		(end 210.610196 -309.941722)
		(width 0.1016)
		(layer "F.Cu")
		(net "M_H_CPU1_SA_DQ<6>")
	)
	(segment
		(start 210.610196 -309.941722)
		(end 212.618066 -309.941722)
		(width 0.1016)
		(layer "F.Cu")
		(net "M_H_CPU1_SA_DQ<6>")
	)
	(segment
		(start 128.666494 -276.172676)
		(end 128.666748 -276.708616)
		(width 0.20066)
		(layer "F.Cu")
		(net "M_H_CPU1_SA_DQ<6>")
	)
	(segment
		(start 209.874358 -309.51678)
		(end 210.306412 -309.948834)
		(width 0.20066)
		(layer "F.Cu")
		(net "M_H_CPU1_SA_DQ<6>")
	)
	(segment
		(start 212.630258 -309.953914)
		(end 213.311486 -309.953914)
		(width 0.20066)
		(layer "F.Cu")
		(net "M_H_CPU1_SA_DQ<6>")
	)
	(segment
		(start 210.598258 -309.948834)
		(end 210.603084 -309.948834)
		(width 0.101854)
		(layer "F.Cu")
		(net "M_H_CPU1_SA_DQ<6>")
	)
	(segment
		(start 212.618066 -309.941722)
		(end 212.630258 -309.953914)
		(width 0.1016)
		(layer "F.Cu")
		(net "M_H_CPU1_SA_DQ<6>")
	)
	(segment
		(start 213.515448 -309.749952)
		(end 213.515448 -309.499)
		(width 0.20066)
		(layer "F.Cu")
		(net "M_H_CPU1_SA_DQ<6>")
	)
	(segment
		(start 208.176114 -309.51678)
		(end 209.874358 -309.51678)
		(width 0.20066)
		(layer "F.Cu")
		(net "M_H_CPU1_SA_DQ<6>")
	)
	(segment
		(start 214.133684 -309.264812)
		(end 214.385652 -309.51678)
		(width 0.20066)
		(layer "F.Cu")
		(net "M_H_CPU1_SA_DQ<6>")
	)
	(segment
		(start 214.385652 -309.51678)
		(end 215.719914 -309.51678)
		(width 0.20066)
		(layer "F.Cu")
		(net "M_H_CPU1_SA_DQ<6>")
	)
	(segment
		(start 213.749636 -309.264812)
		(end 214.133684 -309.264812)
		(width 0.20066)
		(layer "F.Cu")
		(net "M_H_CPU1_SA_DQ<6>")
	)
	(segment
		(start 213.311486 -309.953914)
		(end 213.515448 -309.749952)
		(width 0.20066)
		(layer "F.Cu")
		(net "M_H_CPU1_SA_DQ<6>")
	)
	(segment
		(start 168.991026 -305.846226)
		(end 168.087802 -304.943002)
		(width 0.18288)
		(layer "In6.Cu")
		(net "M_H_CPU1_SA_DQ<6>")
	)
	(segment
		(start 190.784226 -308.442614)
		(end 189.74308 -308.442614)
		(width 0.18288)
		(layer "In6.Cu")
		(net "M_H_CPU1_SA_DQ<6>")
	)
	(segment
		(start 140.517118 -278.771604)
		(end 140.336524 -278.771604)
		(width 0.088646)
		(layer "In6.Cu")
		(net "M_H_CPU1_SA_DQ<6>")
	)
	(segment
		(start 161.085276 -301.166784)
		(end 160.806384 -301.166784)
		(width 0.18288)
		(layer "In6.Cu")
		(net "M_H_CPU1_SA_DQ<6>")
	)
	(segment
		(start 201.332084 -309.335424)
		(end 201.149204 -309.152544)
		(width 0.18288)
		(layer "In6.Cu")
		(net "M_H_CPU1_SA_DQ<6>")
	)
	(segment
		(start 205.698852 -310.534558)
		(end 205.37805 -310.534558)
		(width 0.18288)
		(layer "In6.Cu")
		(net "M_H_CPU1_SA_DQ<6>")
	)
	(segment
		(start 205.859126 -310.374284)
		(end 205.698852 -310.534558)
		(width 0.18288)
		(layer "In6.Cu")
		(net "M_H_CPU1_SA_DQ<6>")
	)
	(segment
		(start 193.22415 -308.061614)
		(end 193.043048 -308.242716)
		(width 0.18288)
		(layer "In6.Cu")
		(net "M_H_CPU1_SA_DQ<6>")
	)
	(segment
		(start 161.339784 -300.912276)
		(end 161.085276 -301.166784)
		(width 0.18288)
		(layer "In6.Cu")
		(net "M_H_CPU1_SA_DQ<6>")
	)
	(segment
		(start 149.967442 -282.73756)
		(end 146.224498 -278.994616)
		(width 0.18288)
		(layer "In6.Cu")
		(net "M_H_CPU1_SA_DQ<6>")
	)
	(segment
		(start 159.792924 -301.635922)
		(end 159.419544 -301.635922)
		(width 0.18288)
		(layer "In6.Cu")
		(net "M_H_CPU1_SA_DQ<6>")
	)
	(segment
		(start 139.500864 -278.03348)
		(end 139.40409 -277.936706)
		(width 0.088646)
		(layer "In6.Cu")
		(net "M_H_CPU1_SA_DQ<6>")
	)
	(segment
		(start 189.74308 -308.442614)
		(end 189.08268 -309.103014)
		(width 0.18288)
		(layer "In6.Cu")
		(net "M_H_CPU1_SA_DQ<6>")
	)
	(segment
		(start 160.806384 -301.166784)
		(end 160.646364 -301.006764)
		(width 0.18288)
		(layer "In6.Cu")
		(net "M_H_CPU1_SA_DQ<6>")
	)
	(segment
		(start 161.339784 -300.752256)
		(end 161.339784 -300.912276)
		(width 0.18288)
		(layer "In6.Cu")
		(net "M_H_CPU1_SA_DQ<6>")
	)
	(segment
		(start 202.78852 -309.0926)
		(end 202.545696 -309.335424)
		(width 0.18288)
		(layer "In6.Cu")
		(net "M_H_CPU1_SA_DQ<6>")
	)
	(segment
		(start 206.39151 -308.837076)
		(end 206.091536 -308.837076)
		(width 0.18288)
		(layer "In6.Cu")
		(net "M_H_CPU1_SA_DQ<6>")
	)
	(segment
		(start 188.356494 -309.092346)
		(end 183.915812 -309.092346)
		(width 0.18288)
		(layer "In6.Cu")
		(net "M_H_CPU1_SA_DQ<6>")
	)
	(segment
		(start 200.638664 -308.56047)
		(end 200.455784 -308.74335)
		(width 0.18288)
		(layer "In6.Cu")
		(net "M_H_CPU1_SA_DQ<6>")
	)
	(segment
		(start 167.36314 -304.943002)
		(end 164.360606 -301.940468)
		(width 0.18288)
		(layer "In6.Cu")
		(net "M_H_CPU1_SA_DQ<6>")
	)
	(segment
		(start 202.545696 -309.335424)
		(end 201.332084 -309.335424)
		(width 0.18288)
		(layer "In6.Cu")
		(net "M_H_CPU1_SA_DQ<6>")
	)
	(segment
		(start 163.37026 -301.940468)
		(end 162.022028 -300.592236)
		(width 0.18288)
		(layer "In6.Cu")
		(net "M_H_CPU1_SA_DQ<6>")
	)
	(segment
		(start 133.648196 -276.219158)
		(end 133.633464 -276.210522)
		(width 0.088646)
		(layer "In6.Cu")
		(net "M_H_CPU1_SA_DQ<6>")
	)
	(segment
		(start 160.486344 -300.592236)
		(end 160.112964 -300.592236)
		(width 0.18288)
		(layer "In6.Cu")
		(net "M_H_CPU1_SA_DQ<6>")
	)
	(segment
		(start 205.859126 -309.069486)
		(end 205.859126 -310.374284)
		(width 0.18288)
		(layer "In6.Cu")
		(net "M_H_CPU1_SA_DQ<6>")
	)
	(segment
		(start 180.187092 -306.633626)
		(end 179.425092 -305.871626)
		(width 0.18288)
		(layer "In6.Cu")
		(net "M_H_CPU1_SA_DQ<6>")
	)
	(segment
		(start 164.360606 -301.940468)
		(end 163.37026 -301.940468)
		(width 0.18288)
		(layer "In6.Cu")
		(net "M_H_CPU1_SA_DQ<6>")
	)
	(segment
		(start 171.861226 -305.846226)
		(end 168.991026 -305.846226)
		(width 0.18288)
		(layer "In6.Cu")
		(net "M_H_CPU1_SA_DQ<6>")
	)
	(segment
		(start 204.544676 -309.25262)
		(end 204.384656 -309.0926)
		(width 0.18288)
		(layer "In6.Cu")
		(net "M_H_CPU1_SA_DQ<6>")
	)
	(segment
		(start 193.043048 -308.242716)
		(end 190.984124 -308.242716)
		(width 0.18288)
		(layer "In6.Cu")
		(net "M_H_CPU1_SA_DQ<6>")
	)
	(segment
		(start 200.272904 -309.335424)
		(end 198.669656 -309.335424)
		(width 0.18288)
		(layer "In6.Cu")
		(net "M_H_CPU1_SA_DQ<6>")
	)
	(segment
		(start 149.967442 -292.197536)
		(end 149.967442 -282.73756)
		(width 0.18288)
		(layer "In6.Cu")
		(net "M_H_CPU1_SA_DQ<6>")
	)
	(segment
		(start 146.224498 -278.994616)
		(end 141.252194 -278.994616)
		(width 0.18288)
		(layer "In6.Cu")
		(net "M_H_CPU1_SA_DQ<6>")
	)
	(segment
		(start 139.099544 -277.522432)
		(end 139.099544 -277.512526)
		(width 0.088646)
		(layer "In6.Cu")
		(net "M_H_CPU1_SA_DQ<6>")
	)
	(segment
		(start 173.359826 -305.692302)
		(end 172.01515 -305.692302)
		(width 0.18288)
		(layer "In6.Cu")
		(net "M_H_CPU1_SA_DQ<6>")
	)
	(segment
		(start 160.646364 -301.006764)
		(end 160.646364 -300.752256)
		(width 0.18288)
		(layer "In6.Cu")
		(net "M_H_CPU1_SA_DQ<6>")
	)
	(segment
		(start 159.952944 -301.475902)
		(end 159.792924 -301.635922)
		(width 0.18288)
		(layer "In6.Cu")
		(net "M_H_CPU1_SA_DQ<6>")
	)
	(segment
		(start 139.5984 -278.03348)
		(end 139.500864 -278.03348)
		(width 0.088646)
		(layer "In6.Cu")
		(net "M_H_CPU1_SA_DQ<6>")
	)
	(segment
		(start 196.82841 -308.417214)
		(end 195.280026 -308.417214)
		(width 0.18288)
		(layer "In6.Cu")
		(net "M_H_CPU1_SA_DQ<6>")
	)
	(segment
		(start 201.149204 -308.74335)
		(end 200.966324 -308.56047)
		(width 0.18288)
		(layer "In6.Cu")
		(net "M_H_CPU1_SA_DQ<6>")
	)
	(segment
		(start 141.252194 -278.994616)
		(end 140.713968 -278.771604)
		(width 0.18288)
		(layer "In6.Cu")
		(net "M_H_CPU1_SA_DQ<6>")
	)
	(segment
		(start 179.425092 -305.871626)
		(end 178.50612 -305.871626)
		(width 0.18288)
		(layer "In6.Cu")
		(net "M_H_CPU1_SA_DQ<6>")
	)
	(segment
		(start 161.499804 -300.592236)
		(end 161.339784 -300.752256)
		(width 0.18288)
		(layer "In6.Cu")
		(net "M_H_CPU1_SA_DQ<6>")
	)
	(segment
		(start 200.455784 -309.152544)
		(end 200.272904 -309.335424)
		(width 0.18288)
		(layer "In6.Cu")
		(net "M_H_CPU1_SA_DQ<6>")
	)
	(segment
		(start 168.087802 -304.943002)
		(end 167.36314 -304.943002)
		(width 0.18288)
		(layer "In6.Cu")
		(net "M_H_CPU1_SA_DQ<6>")
	)
	(segment
		(start 129.888996 -276.219158)
		(end 129.878582 -276.213062)
		(width 0.088646)
		(layer "In6.Cu")
		(net "M_H_CPU1_SA_DQ<6>")
	)
	(segment
		(start 160.646364 -300.752256)
		(end 160.486344 -300.592236)
		(width 0.18288)
		(layer "In6.Cu")
		(net "M_H_CPU1_SA_DQ<6>")
	)
	(segment
		(start 194.924426 -308.061614)
		(end 193.22415 -308.061614)
		(width 0.18288)
		(layer "In6.Cu")
		(net "M_H_CPU1_SA_DQ<6>")
	)
	(segment
		(start 177.476658 -304.842164)
		(end 174.209964 -304.842164)
		(width 0.18288)
		(layer "In6.Cu")
		(net "M_H_CPU1_SA_DQ<6>")
	)
	(segment
		(start 206.091536 -308.837076)
		(end 205.859126 -309.069486)
		(width 0.18288)
		(layer "In6.Cu")
		(net "M_H_CPU1_SA_DQ<6>")
	)
	(segment
		(start 159.099504 -300.592236)
		(end 158.734506 -300.592236)
		(width 0.18288)
		(layer "In6.Cu")
		(net "M_H_CPU1_SA_DQ<6>")
	)
	(segment
		(start 157.883606 -299.741336)
		(end 157.511242 -299.741336)
		(width 0.18288)
		(layer "In6.Cu")
		(net "M_H_CPU1_SA_DQ<6>")
	)
	(segment
		(start 204.72781 -310.535574)
		(end 204.544676 -310.352948)
		(width 0.18288)
		(layer "In6.Cu")
		(net "M_H_CPU1_SA_DQ<6>")
	)
	(segment
		(start 198.669656 -309.335424)
		(end 198.208646 -308.874414)
		(width 0.18288)
		(layer "In6.Cu")
		(net "M_H_CPU1_SA_DQ<6>")
	)
	(segment
		(start 188.367162 -309.103014)
		(end 188.356494 -309.092346)
		(width 0.18288)
		(layer "In6.Cu")
		(net "M_H_CPU1_SA_DQ<6>")
	)
	(segment
		(start 204.544676 -310.352948)
		(end 204.544676 -309.25262)
		(width 0.18288)
		(layer "In6.Cu")
		(net "M_H_CPU1_SA_DQ<6>")
	)
	(segment
		(start 182.447692 -308.386226)
		(end 180.695092 -306.633626)
		(width 0.18288)
		(layer "In6.Cu")
		(net "M_H_CPU1_SA_DQ<6>")
	)
	(segment
		(start 159.419544 -301.635922)
		(end 159.259524 -301.475902)
		(width 0.18288)
		(layer "In6.Cu")
		(net "M_H_CPU1_SA_DQ<6>")
	)
	(segment
		(start 178.50612 -305.871626)
		(end 177.476658 -304.842164)
		(width 0.18288)
		(layer "In6.Cu")
		(net "M_H_CPU1_SA_DQ<6>")
	)
	(segment
		(start 138.629644 -276.708616)
		(end 138.629644 -276.69871)
		(width 0.088646)
		(layer "In6.Cu")
		(net "M_H_CPU1_SA_DQ<6>")
	)
	(segment
		(start 183.209692 -308.386226)
		(end 182.447692 -308.386226)
		(width 0.18288)
		(layer "In6.Cu")
		(net "M_H_CPU1_SA_DQ<6>")
	)
	(segment
		(start 135.527796 -276.219158)
		(end 135.513064 -276.210522)
		(width 0.088646)
		(layer "In6.Cu")
		(net "M_H_CPU1_SA_DQ<6>")
	)
	(segment
		(start 140.713968 -278.771604)
		(end 140.517118 -278.771604)
		(width 0.18288)
		(layer "In6.Cu")
		(net "M_H_CPU1_SA_DQ<6>")
	)
	(segment
		(start 190.984124 -308.242716)
		(end 190.784226 -308.442614)
		(width 0.18288)
		(layer "In6.Cu")
		(net "M_H_CPU1_SA_DQ<6>")
	)
	(segment
		(start 207.071214 -309.51678)
		(end 206.39151 -308.837076)
		(width 0.18288)
		(layer "In6.Cu")
		(net "M_H_CPU1_SA_DQ<6>")
	)
	(segment
		(start 174.209964 -304.842164)
		(end 173.359826 -305.692302)
		(width 0.18288)
		(layer "In6.Cu")
		(net "M_H_CPU1_SA_DQ<6>")
	)
	(segment
		(start 159.952944 -300.752256)
		(end 159.952944 -301.475902)
		(width 0.18288)
		(layer "In6.Cu")
		(net "M_H_CPU1_SA_DQ<6>")
	)
	(segment
		(start 159.259524 -300.752256)
		(end 159.099504 -300.592236)
		(width 0.18288)
		(layer "In6.Cu")
		(net "M_H_CPU1_SA_DQ<6>")
	)
	(segment
		(start 140.336524 -278.771604)
		(end 139.5984 -278.03348)
		(width 0.088646)
		(layer "In6.Cu")
		(net "M_H_CPU1_SA_DQ<6>")
	)
	(segment
		(start 198.208646 -308.874414)
		(end 197.28561 -308.874414)
		(width 0.18288)
		(layer "In6.Cu")
		(net "M_H_CPU1_SA_DQ<6>")
	)
	(segment
		(start 205.37805 -310.534558)
		(end 204.72781 -310.535574)
		(width 0.18288)
		(layer "In6.Cu")
		(net "M_H_CPU1_SA_DQ<6>")
	)
	(segment
		(start 183.915812 -309.092346)
		(end 183.209692 -308.386226)
		(width 0.18288)
		(layer "In6.Cu")
		(net "M_H_CPU1_SA_DQ<6>")
	)
	(segment
		(start 158.734506 -300.592236)
		(end 157.883606 -299.741336)
		(width 0.18288)
		(layer "In6.Cu")
		(net "M_H_CPU1_SA_DQ<6>")
	)
	(segment
		(start 201.149204 -309.152544)
		(end 201.149204 -308.74335)
		(width 0.18288)
		(layer "In6.Cu")
		(net "M_H_CPU1_SA_DQ<6>")
	)
	(segment
		(start 134.587996 -276.219158)
		(end 134.573264 -276.210522)
		(width 0.088646)
		(layer "In6.Cu")
		(net "M_H_CPU1_SA_DQ<6>")
	)
	(segment
		(start 129.247392 -276.27199)
		(end 128.666748 -276.708616)
		(width 0.088646)
		(layer "In6.Cu")
		(net "M_H_CPU1_SA_DQ<6>")
	)
	(segment
		(start 200.455784 -308.74335)
		(end 200.455784 -309.152544)
		(width 0.18288)
		(layer "In6.Cu")
		(net "M_H_CPU1_SA_DQ<6>")
	)
	(segment
		(start 160.112964 -300.592236)
		(end 159.952944 -300.752256)
		(width 0.18288)
		(layer "In6.Cu")
		(net "M_H_CPU1_SA_DQ<6>")
	)
	(segment
		(start 172.01515 -305.692302)
		(end 171.861226 -305.846226)
		(width 0.18288)
		(layer "In6.Cu")
		(net "M_H_CPU1_SA_DQ<6>")
	)
	(segment
		(start 197.28561 -308.874414)
		(end 196.82841 -308.417214)
		(width 0.18288)
		(layer "In6.Cu")
		(net "M_H_CPU1_SA_DQ<6>")
	)
	(segment
		(start 162.022028 -300.592236)
		(end 161.499804 -300.592236)
		(width 0.18288)
		(layer "In6.Cu")
		(net "M_H_CPU1_SA_DQ<6>")
	)
	(segment
		(start 130.828796 -276.219158)
		(end 130.814064 -276.210522)
		(width 0.088646)
		(layer "In6.Cu")
		(net "M_H_CPU1_SA_DQ<6>")
	)
	(segment
		(start 159.259524 -301.475902)
		(end 159.259524 -300.752256)
		(width 0.18288)
		(layer "In6.Cu")
		(net "M_H_CPU1_SA_DQ<6>")
	)
	(segment
		(start 195.280026 -308.417214)
		(end 194.924426 -308.061614)
		(width 0.18288)
		(layer "In6.Cu")
		(net "M_H_CPU1_SA_DQ<6>")
	)
	(segment
		(start 138.817096 -277.032974)
		(end 138.808206 -277.027894)
		(width 0.088646)
		(layer "In6.Cu")
		(net "M_H_CPU1_SA_DQ<6>")
	)
	(segment
		(start 200.966324 -308.56047)
		(end 200.638664 -308.56047)
		(width 0.18288)
		(layer "In6.Cu")
		(net "M_H_CPU1_SA_DQ<6>")
	)
	(segment
		(start 157.511242 -299.741336)
		(end 149.967442 -292.197536)
		(width 0.18288)
		(layer "In6.Cu")
		(net "M_H_CPU1_SA_DQ<6>")
	)
	(segment
		(start 180.695092 -306.633626)
		(end 180.187092 -306.633626)
		(width 0.18288)
		(layer "In6.Cu")
		(net "M_H_CPU1_SA_DQ<6>")
	)
	(segment
		(start 204.384656 -309.0926)
		(end 202.78852 -309.0926)
		(width 0.18288)
		(layer "In6.Cu")
		(net "M_H_CPU1_SA_DQ<6>")
	)
	(segment
		(start 189.08268 -309.103014)
		(end 188.367162 -309.103014)
		(width 0.18288)
		(layer "In6.Cu")
		(net "M_H_CPU1_SA_DQ<6>")
	)
	(segment
		(start 131.768596 -276.219158)
		(end 131.753864 -276.210522)
		(width 0.088646)
		(layer "In6.Cu")
		(net "M_H_CPU1_SA_DQ<6>")
	)
	(arc
		(start 136.841992 -276.219158)
		(mid 136.654794 -276.269301)
		(end 136.467596 -276.219158)
		(width 0.088646)
		(layer "In6.Cu")
		(net "M_H_CPU1_SA_DQ<6>")
	)
	(arc
		(start 134.573264 -276.210522)
		(mid 134.296789 -276.143202)
		(end 134.022592 -276.219158)
		(width 0.088646)
		(layer "In6.Cu")
		(net "M_H_CPU1_SA_DQ<6>")
	)
	(arc
		(start 133.633464 -276.210522)
		(mid 133.356989 -276.143202)
		(end 133.082792 -276.219158)
		(width 0.088646)
		(layer "In6.Cu")
		(net "M_H_CPU1_SA_DQ<6>")
	)
	(arc
		(start 130.263392 -276.219158)
		(mid 130.076194 -276.269301)
		(end 129.888996 -276.219158)
		(width 0.088646)
		(layer "In6.Cu")
		(net "M_H_CPU1_SA_DQ<6>")
	)
	(arc
		(start 139.099544 -277.512526)
		(mid 139.021433 -277.235577)
		(end 138.817096 -277.032974)
		(width 0.088646)
		(layer "In6.Cu")
		(net "M_H_CPU1_SA_DQ<6>")
	)
	(arc
		(start 138.629644 -276.69871)
		(mid 138.551533 -276.421761)
		(end 138.347196 -276.219158)
		(width 0.088646)
		(layer "In6.Cu")
		(net "M_H_CPU1_SA_DQ<6>")
	)
	(arc
		(start 129.323846 -276.219158)
		(mid 129.284525 -276.243992)
		(end 129.247392 -276.27199)
		(width 0.088646)
		(layer "In6.Cu")
		(net "M_H_CPU1_SA_DQ<6>")
	)
	(arc
		(start 136.467596 -276.219158)
		(mid 136.184894 -276.143382)
		(end 135.902192 -276.219158)
		(width 0.088646)
		(layer "In6.Cu")
		(net "M_H_CPU1_SA_DQ<6>")
	)
	(arc
		(start 135.902192 -276.219158)
		(mid 135.714994 -276.269301)
		(end 135.527796 -276.219158)
		(width 0.088646)
		(layer "In6.Cu")
		(net "M_H_CPU1_SA_DQ<6>")
	)
	(arc
		(start 131.203192 -276.219158)
		(mid 131.015994 -276.269301)
		(end 130.828796 -276.219158)
		(width 0.088646)
		(layer "In6.Cu")
		(net "M_H_CPU1_SA_DQ<6>")
	)
	(arc
		(start 130.814064 -276.210522)
		(mid 130.537589 -276.143202)
		(end 130.263392 -276.219158)
		(width 0.088646)
		(layer "In6.Cu")
		(net "M_H_CPU1_SA_DQ<6>")
	)
	(arc
		(start 133.082792 -276.219158)
		(mid 132.895594 -276.269301)
		(end 132.708396 -276.219158)
		(width 0.088646)
		(layer "In6.Cu")
		(net "M_H_CPU1_SA_DQ<6>")
	)
	(arc
		(start 135.513064 -276.210522)
		(mid 135.236589 -276.143202)
		(end 134.962392 -276.219158)
		(width 0.088646)
		(layer "In6.Cu")
		(net "M_H_CPU1_SA_DQ<6>")
	)
	(arc
		(start 138.347196 -276.219158)
		(mid 138.064494 -276.143382)
		(end 137.781792 -276.219158)
		(width 0.088646)
		(layer "In6.Cu")
		(net "M_H_CPU1_SA_DQ<6>")
	)
	(arc
		(start 132.708396 -276.219158)
		(mid 132.425694 -276.143382)
		(end 132.142992 -276.219158)
		(width 0.088646)
		(layer "In6.Cu")
		(net "M_H_CPU1_SA_DQ<6>")
	)
	(arc
		(start 134.962392 -276.219158)
		(mid 134.775194 -276.269301)
		(end 134.587996 -276.219158)
		(width 0.088646)
		(layer "In6.Cu")
		(net "M_H_CPU1_SA_DQ<6>")
	)
	(arc
		(start 129.878582 -276.213062)
		(mid 129.600404 -276.143339)
		(end 129.323846 -276.219158)
		(width 0.088646)
		(layer "In6.Cu")
		(net "M_H_CPU1_SA_DQ<6>")
	)
	(arc
		(start 134.022592 -276.219158)
		(mid 133.835394 -276.269301)
		(end 133.648196 -276.219158)
		(width 0.088646)
		(layer "In6.Cu")
		(net "M_H_CPU1_SA_DQ<6>")
	)
	(arc
		(start 139.278106 -277.84171)
		(mid 139.147192 -277.70535)
		(end 139.099544 -277.522432)
		(width 0.088646)
		(layer "In6.Cu")
		(net "M_H_CPU1_SA_DQ<6>")
	)
	(arc
		(start 137.781792 -276.219158)
		(mid 137.594594 -276.269301)
		(end 137.407396 -276.219158)
		(width 0.088646)
		(layer "In6.Cu")
		(net "M_H_CPU1_SA_DQ<6>")
	)
	(arc
		(start 131.753864 -276.210522)
		(mid 131.477389 -276.143202)
		(end 131.203192 -276.219158)
		(width 0.088646)
		(layer "In6.Cu")
		(net "M_H_CPU1_SA_DQ<6>")
	)
	(arc
		(start 138.808206 -277.027894)
		(mid 138.677292 -276.891534)
		(end 138.629644 -276.708616)
		(width 0.088646)
		(layer "In6.Cu")
		(net "M_H_CPU1_SA_DQ<6>")
	)
	(arc
		(start 132.142992 -276.219158)
		(mid 131.955794 -276.269301)
		(end 131.768596 -276.219158)
		(width 0.088646)
		(layer "In6.Cu")
		(net "M_H_CPU1_SA_DQ<6>")
	)
	(arc
		(start 139.40409 -277.936706)
		(mid 139.344427 -277.884794)
		(end 139.278106 -277.84171)
		(width 0.088646)
		(layer "In6.Cu")
		(net "M_H_CPU1_SA_DQ<6>")
	)
	(arc
		(start 137.407396 -276.219158)
		(mid 137.124694 -276.143382)
		(end 136.841992 -276.219158)
		(width 0.088646)
		(layer "In6.Cu")
		(net "M_H_CPU1_SA_DQ<6>")
	)
	(segment
		(start 209.186526 -308.23535)
		(end 209.180176 -308.2417)
		(width 0.1016)
		(layer "F.Cu")
		(net "M_H_CPU1_SA_DQ<5>")
	)
	(segment
		(start 206.508604 -308.35981)
		(end 206.508604 -308.727348)
		(width 0.20066)
		(layer "F.Cu")
		(net "M_H_CPU1_SA_DQ<5>")
	)
	(segment
		(start 127.257048 -275.894546)
		(end 127.256794 -275.8948)
		(width 0.20066)
		(layer "F.Cu")
		(net "M_H_CPU1_SA_DQ<5>")
	)
	(segment
		(start 205.596744 -308.666642)
		(end 204.076046 -308.666642)
		(width 0.20066)
		(layer "F.Cu")
		(net "M_H_CPU1_SA_DQ<5>")
	)
	(segment
		(start 204.076046 -308.666642)
		(end 202.971146 -308.666642)
		(width 0.20066)
		(layer "F.Cu")
		(net "M_H_CPU1_SA_DQ<5>")
	)
	(segment
		(start 205.84541 -308.915308)
		(end 205.596744 -308.666642)
		(width 0.20066)
		(layer "F.Cu")
		(net "M_H_CPU1_SA_DQ<5>")
	)
	(segment
		(start 209.596482 -308.23535)
		(end 209.186526 -308.23535)
		(width 0.20066)
		(layer "F.Cu")
		(net "M_H_CPU1_SA_DQ<5>")
	)
	(segment
		(start 127.257048 -275.35886)
		(end 127.257048 -275.894546)
		(width 0.20066)
		(layer "F.Cu")
		(net "M_H_CPU1_SA_DQ<5>")
	)
	(segment
		(start 206.991458 -308.2417)
		(end 206.971392 -308.2417)
		(width 0.101854)
		(layer "F.Cu")
		(net "M_H_CPU1_SA_DQ<5>")
	)
	(segment
		(start 211.619846 -308.666642)
		(end 211.619592 -308.666896)
		(width 0.20066)
		(layer "F.Cu")
		(net "M_H_CPU1_SA_DQ<5>")
	)
	(segment
		(start 210.028028 -308.666896)
		(end 209.596482 -308.23535)
		(width 0.20066)
		(layer "F.Cu")
		(net "M_H_CPU1_SA_DQ<5>")
	)
	(segment
		(start 209.180176 -308.2417)
		(end 206.991458 -308.2417)
		(width 0.1016)
		(layer "F.Cu")
		(net "M_H_CPU1_SA_DQ<5>")
	)
	(segment
		(start 206.626714 -308.2417)
		(end 206.508604 -308.35981)
		(width 0.20066)
		(layer "F.Cu")
		(net "M_H_CPU1_SA_DQ<5>")
	)
	(segment
		(start 206.320644 -308.915308)
		(end 205.84541 -308.915308)
		(width 0.20066)
		(layer "F.Cu")
		(net "M_H_CPU1_SA_DQ<5>")
	)
	(segment
		(start 206.971392 -308.2417)
		(end 206.626714 -308.2417)
		(width 0.20066)
		(layer "F.Cu")
		(net "M_H_CPU1_SA_DQ<5>")
	)
	(segment
		(start 206.508604 -308.727348)
		(end 206.320644 -308.915308)
		(width 0.20066)
		(layer "F.Cu")
		(net "M_H_CPU1_SA_DQ<5>")
	)
	(segment
		(start 211.619592 -308.666896)
		(end 210.028028 -308.666896)
		(width 0.20066)
		(layer "F.Cu")
		(net "M_H_CPU1_SA_DQ<5>")
	)
	(segment
		(start 158.879032 -299.790866)
		(end 158.652972 -299.790866)
		(width 0.18288)
		(layer "In6.Cu")
		(net "M_H_CPU1_SA_DQ<5>")
	)
	(segment
		(start 176.357788 -303.992026)
		(end 176.05629 -304.293524)
		(width 0.18288)
		(layer "In6.Cu")
		(net "M_H_CPU1_SA_DQ<5>")
	)
	(segment
		(start 166.085774 -301.497746)
		(end 166.085774 -301.239174)
		(width 0.18288)
		(layer "In6.Cu")
		(net "M_H_CPU1_SA_DQ<5>")
	)
	(segment
		(start 194.11315 -307.528214)
		(end 193.64706 -307.062124)
		(width 0.18288)
		(layer "In6.Cu")
		(net "M_H_CPU1_SA_DQ<5>")
	)
	(segment
		(start 171.007786 -304.677318)
		(end 170.824906 -304.860198)
		(width 0.18288)
		(layer "In6.Cu")
		(net "M_H_CPU1_SA_DQ<5>")
	)
	(segment
		(start 161.487104 -299.742606)
		(end 161.195512 -300.034198)
		(width 0.18288)
		(layer "In6.Cu")
		(net "M_H_CPU1_SA_DQ<5>")
	)
	(segment
		(start 159.192214 -299.477684)
		(end 158.879032 -299.790866)
		(width 0.18288)
		(layer "In6.Cu")
		(net "M_H_CPU1_SA_DQ<5>")
	)
	(segment
		(start 160.765236 -300.034198)
		(end 160.473644 -299.742606)
		(width 0.18288)
		(layer "In6.Cu")
		(net "M_H_CPU1_SA_DQ<5>")
	)
	(segment
		(start 198.172832 -308.344824)
		(end 197.517004 -308.344824)
		(width 0.18288)
		(layer "In6.Cu")
		(net "M_H_CPU1_SA_DQ<5>")
	)
	(segment
		(start 175.664368 -304.293524)
		(end 175.36287 -303.992026)
		(width 0.18288)
		(layer "In6.Cu")
		(net "M_H_CPU1_SA_DQ<5>")
	)
	(segment
		(start 192.658492 -307.232558)
		(end 192.498472 -307.392578)
		(width 0.18288)
		(layer "In6.Cu")
		(net "M_H_CPU1_SA_DQ<5>")
	)
	(segment
		(start 165.976046 -302.32985)
		(end 165.744144 -302.097948)
		(width 0.18288)
		(layer "In6.Cu")
		(net "M_H_CPU1_SA_DQ<5>")
	)
	(segment
		(start 134.587996 -275.570442)
		(end 134.573264 -275.579078)
		(width 0.088646)
		(layer "In6.Cu")
		(net "M_H_CPU1_SA_DQ<5>")
	)
	(segment
		(start 139.378944 -277.461726)
		(end 139.378944 -276.708616)
		(width 0.088646)
		(layer "In6.Cu")
		(net "M_H_CPU1_SA_DQ<5>")
	)
	(segment
		(start 171.797218 -304.677318)
		(end 171.007786 -304.677318)
		(width 0.18288)
		(layer "In6.Cu")
		(net "M_H_CPU1_SA_DQ<5>")
	)
	(segment
		(start 141.351762 -278.496776)
		(end 140.798042 -278.267414)
		(width 0.18288)
		(layer "In6.Cu")
		(net "M_H_CPU1_SA_DQ<5>")
	)
	(segment
		(start 131.768596 -275.570442)
		(end 131.753864 -275.579078)
		(width 0.088646)
		(layer "In6.Cu")
		(net "M_H_CPU1_SA_DQ<5>")
	)
	(segment
		(start 184.925716 -308.242208)
		(end 183.947308 -308.242208)
		(width 0.18288)
		(layer "In6.Cu")
		(net "M_H_CPU1_SA_DQ<5>")
	)
	(segment
		(start 179.214526 -304.703226)
		(end 178.128422 -304.703226)
		(width 0.18288)
		(layer "In6.Cu")
		(net "M_H_CPU1_SA_DQ<5>")
	)
	(segment
		(start 157.078426 -297.97121)
		(end 150.465282 -291.358066)
		(width 0.18288)
		(layer "In6.Cu")
		(net "M_H_CPU1_SA_DQ<5>")
	)
	(segment
		(start 135.527796 -275.570442)
		(end 135.513064 -275.579078)
		(width 0.088646)
		(layer "In6.Cu")
		(net "M_H_CPU1_SA_DQ<5>")
	)
	(segment
		(start 140.367258 -278.267414)
		(end 140.184632 -278.267414)
		(width 0.088646)
		(layer "In6.Cu")
		(net "M_H_CPU1_SA_DQ<5>")
	)
	(segment
		(start 197.517004 -308.344824)
		(end 196.370194 -307.198014)
		(width 0.18288)
		(layer "In6.Cu")
		(net "M_H_CPU1_SA_DQ<5>")
	)
	(segment
		(start 179.976526 -305.465226)
		(end 179.214526 -304.703226)
		(width 0.18288)
		(layer "In6.Cu")
		(net "M_H_CPU1_SA_DQ<5>")
	)
	(segment
		(start 167.557196 -302.969168)
		(end 167.215566 -303.310798)
		(width 0.18288)
		(layer "In6.Cu")
		(net "M_H_CPU1_SA_DQ<5>")
	)
	(segment
		(start 167.066722 -302.478694)
		(end 167.066722 -302.220122)
		(width 0.18288)
		(layer "In6.Cu")
		(net "M_H_CPU1_SA_DQ<5>")
	)
	(segment
		(start 138.730482 -275.575522)
		(end 138.721592 -275.570442)
		(width 0.088646)
		(layer "In6.Cu")
		(net "M_H_CPU1_SA_DQ<5>")
	)
	(segment
		(start 202.971146 -308.666642)
		(end 202.412854 -308.666642)
		(width 0.18288)
		(layer "In6.Cu")
		(net "M_H_CPU1_SA_DQ<5>")
	)
	(segment
		(start 190.533528 -307.392578)
		(end 189.706758 -307.392578)
		(width 0.18288)
		(layer "In6.Cu")
		(net "M_H_CPU1_SA_DQ<5>")
	)
	(segment
		(start 167.70604 -303.801272)
		(end 168.04767 -303.459642)
		(width 0.18288)
		(layer "In6.Cu")
		(net "M_H_CPU1_SA_DQ<5>")
	)
	(segment
		(start 166.576248 -301.98822)
		(end 166.234618 -302.32985)
		(width 0.18288)
		(layer "In6.Cu")
		(net "M_H_CPU1_SA_DQ<5>")
	)
	(segment
		(start 163.432236 -300.773846)
		(end 163.19373 -300.872906)
		(width 0.18288)
		(layer "In6.Cu")
		(net "M_H_CPU1_SA_DQ<5>")
	)
	(segment
		(start 191.539876 -307.392578)
		(end 191.226948 -307.705506)
		(width 0.18288)
		(layer "In6.Cu")
		(net "M_H_CPU1_SA_DQ<5>")
	)
	(segment
		(start 158.388558 -299.526452)
		(end 158.388558 -299.300392)
		(width 0.18288)
		(layer "In6.Cu")
		(net "M_H_CPU1_SA_DQ<5>")
	)
	(segment
		(start 138.909044 -275.904706)
		(end 138.909044 -275.8948)
		(width 0.088646)
		(layer "In6.Cu")
		(net "M_H_CPU1_SA_DQ<5>")
	)
	(segment
		(start 164.848286 -301.025306)
		(end 164.337746 -300.514766)
		(width 0.18288)
		(layer "In6.Cu")
		(net "M_H_CPU1_SA_DQ<5>")
	)
	(segment
		(start 185.60796 -307.89499)
		(end 185.272934 -307.89499)
		(width 0.18288)
		(layer "In6.Cu")
		(net "M_H_CPU1_SA_DQ<5>")
	)
	(segment
		(start 166.83482 -301.98822)
		(end 166.576248 -301.98822)
		(width 0.18288)
		(layer "In6.Cu")
		(net "M_H_CPU1_SA_DQ<5>")
	)
	(segment
		(start 201.68108 -307.934868)
		(end 198.582788 -307.934868)
		(width 0.18288)
		(layer "In6.Cu")
		(net "M_H_CPU1_SA_DQ<5>")
	)
	(segment
		(start 166.725092 -303.078896)
		(end 166.725092 -302.820324)
		(width 0.18288)
		(layer "In6.Cu")
		(net "M_H_CPU1_SA_DQ<5>")
	)
	(segment
		(start 167.215566 -303.310798)
		(end 166.956994 -303.310798)
		(width 0.18288)
		(layer "In6.Cu")
		(net "M_H_CPU1_SA_DQ<5>")
	)
	(segment
		(start 163.825174 -300.302422)
		(end 163.586414 -300.401482)
		(width 0.18288)
		(layer "In6.Cu")
		(net "M_H_CPU1_SA_DQ<5>")
	)
	(segment
		(start 128.94945 -275.570442)
		(end 128.94056 -275.575522)
		(width 0.088646)
		(layer "In6.Cu")
		(net "M_H_CPU1_SA_DQ<5>")
	)
	(segment
		(start 130.828796 -275.570442)
		(end 130.814064 -275.579078)
		(width 0.088646)
		(layer "In6.Cu")
		(net "M_H_CPU1_SA_DQ<5>")
	)
	(segment
		(start 165.871906 -301.025306)
		(end 164.848286 -301.025306)
		(width 0.18288)
		(layer "In6.Cu")
		(net "M_H_CPU1_SA_DQ<5>")
	)
	(segment
		(start 185.955178 -308.242208)
		(end 185.60796 -307.89499)
		(width 0.18288)
		(layer "In6.Cu")
		(net "M_H_CPU1_SA_DQ<5>")
	)
	(segment
		(start 167.066722 -302.220122)
		(end 166.83482 -301.98822)
		(width 0.18288)
		(layer "In6.Cu")
		(net "M_H_CPU1_SA_DQ<5>")
	)
	(segment
		(start 165.744144 -301.839376)
		(end 166.085774 -301.497746)
		(width 0.18288)
		(layer "In6.Cu")
		(net "M_H_CPU1_SA_DQ<5>")
	)
	(segment
		(start 166.085774 -301.239174)
		(end 165.871906 -301.025306)
		(width 0.18288)
		(layer "In6.Cu")
		(net "M_H_CPU1_SA_DQ<5>")
	)
	(segment
		(start 129.888996 -275.570442)
		(end 129.878582 -275.576538)
		(width 0.088646)
		(layer "In6.Cu")
		(net "M_H_CPU1_SA_DQ<5>")
	)
	(segment
		(start 162.473386 -299.742606)
		(end 161.487104 -299.742606)
		(width 0.18288)
		(layer "In6.Cu")
		(net "M_H_CPU1_SA_DQ<5>")
	)
	(segment
		(start 170.824906 -304.860198)
		(end 170.824906 -305.159156)
		(width 0.18288)
		(layer "In6.Cu")
		(net "M_H_CPU1_SA_DQ<5>")
	)
	(segment
		(start 162.890454 -300.747176)
		(end 162.791394 -300.508416)
		(width 0.18288)
		(layer "In6.Cu")
		(net "M_H_CPU1_SA_DQ<5>")
	)
	(segment
		(start 191.226948 -307.705506)
		(end 190.846456 -307.705506)
		(width 0.18288)
		(layer "In6.Cu")
		(net "M_H_CPU1_SA_DQ<5>")
	)
	(segment
		(start 167.815768 -302.969168)
		(end 167.557196 -302.969168)
		(width 0.18288)
		(layer "In6.Cu")
		(net "M_H_CPU1_SA_DQ<5>")
	)
	(segment
		(start 185.272934 -307.89499)
		(end 184.925716 -308.242208)
		(width 0.18288)
		(layer "In6.Cu")
		(net "M_H_CPU1_SA_DQ<5>")
	)
	(segment
		(start 139.200382 -276.389338)
		(end 139.191492 -276.384258)
		(width 0.088646)
		(layer "In6.Cu")
		(net "M_H_CPU1_SA_DQ<5>")
	)
	(segment
		(start 158.652972 -299.790866)
		(end 158.388558 -299.526452)
		(width 0.18288)
		(layer "In6.Cu")
		(net "M_H_CPU1_SA_DQ<5>")
	)
	(segment
		(start 182.999126 -307.294026)
		(end 182.160926 -307.294026)
		(width 0.18288)
		(layer "In6.Cu")
		(net "M_H_CPU1_SA_DQ<5>")
	)
	(segment
		(start 198.582788 -307.934868)
		(end 198.172832 -308.344824)
		(width 0.18288)
		(layer "In6.Cu")
		(net "M_H_CPU1_SA_DQ<5>")
	)
	(segment
		(start 189.311026 -307.78831)
		(end 189.311026 -308.059582)
		(width 0.18288)
		(layer "In6.Cu")
		(net "M_H_CPU1_SA_DQ<5>")
	)
	(segment
		(start 166.234618 -302.32985)
		(end 165.976046 -302.32985)
		(width 0.18288)
		(layer "In6.Cu")
		(net "M_H_CPU1_SA_DQ<5>")
	)
	(segment
		(start 173.246288 -304.842164)
		(end 171.962064 -304.842164)
		(width 0.18288)
		(layer "In6.Cu")
		(net "M_H_CPU1_SA_DQ<5>")
	)
	(segment
		(start 158.70174 -298.98721)
		(end 158.70174 -298.76115)
		(width 0.18288)
		(layer "In6.Cu")
		(net "M_H_CPU1_SA_DQ<5>")
	)
	(segment
		(start 189.706758 -307.392578)
		(end 189.311026 -307.78831)
		(width 0.18288)
		(layer "In6.Cu")
		(net "M_H_CPU1_SA_DQ<5>")
	)
	(segment
		(start 170.131486 -304.860198)
		(end 169.948606 -304.677318)
		(width 0.18288)
		(layer "In6.Cu")
		(net "M_H_CPU1_SA_DQ<5>")
	)
	(segment
		(start 162.791394 -300.508416)
		(end 162.945572 -300.136052)
		(width 0.18288)
		(layer "In6.Cu")
		(net "M_H_CPU1_SA_DQ<5>")
	)
	(segment
		(start 178.128422 -304.703226)
		(end 177.417222 -303.992026)
		(width 0.18288)
		(layer "In6.Cu")
		(net "M_H_CPU1_SA_DQ<5>")
	)
	(segment
		(start 128.485646 -276.380702)
		(end 128.47955 -276.384258)
		(width 0.088646)
		(layer "In6.Cu")
		(net "M_H_CPU1_SA_DQ<5>")
	)
	(segment
		(start 160.473644 -299.742606)
		(end 159.683196 -299.742606)
		(width 0.18288)
		(layer "In6.Cu")
		(net "M_H_CPU1_SA_DQ<5>")
	)
	(segment
		(start 171.962064 -304.842164)
		(end 171.797218 -304.677318)
		(width 0.18288)
		(layer "In6.Cu")
		(net "M_H_CPU1_SA_DQ<5>")
	)
	(segment
		(start 168.796716 -303.950116)
		(end 168.538144 -303.950116)
		(width 0.18288)
		(layer "In6.Cu")
		(net "M_H_CPU1_SA_DQ<5>")
	)
	(segment
		(start 166.956994 -303.310798)
		(end 166.725092 -303.078896)
		(width 0.18288)
		(layer "In6.Cu")
		(net "M_H_CPU1_SA_DQ<5>")
	)
	(segment
		(start 157.9118 -297.97121)
		(end 157.078426 -297.97121)
		(width 0.18288)
		(layer "In6.Cu")
		(net "M_H_CPU1_SA_DQ<5>")
	)
	(segment
		(start 175.36287 -303.992026)
		(end 174.096426 -303.992026)
		(width 0.18288)
		(layer "In6.Cu")
		(net "M_H_CPU1_SA_DQ<5>")
	)
	(segment
		(start 150.465282 -291.358066)
		(end 150.465282 -282.531312)
		(width 0.18288)
		(layer "In6.Cu")
		(net "M_H_CPU1_SA_DQ<5>")
	)
	(segment
		(start 196.370194 -307.198014)
		(end 195.203826 -307.198014)
		(width 0.18288)
		(layer "In6.Cu")
		(net "M_H_CPU1_SA_DQ<5>")
	)
	(segment
		(start 170.131486 -305.159156)
		(end 170.131486 -304.860198)
		(width 0.18288)
		(layer "In6.Cu")
		(net "M_H_CPU1_SA_DQ<5>")
	)
	(segment
		(start 140.184632 -278.267414)
		(end 139.378944 -277.461726)
		(width 0.088646)
		(layer "In6.Cu")
		(net "M_H_CPU1_SA_DQ<5>")
	)
	(segment
		(start 127.928878 -276.392894)
		(end 127.914146 -276.384258)
		(width 0.088646)
		(layer "In6.Cu")
		(net "M_H_CPU1_SA_DQ<5>")
	)
	(segment
		(start 189.1284 -308.242208)
		(end 185.955178 -308.242208)
		(width 0.18288)
		(layer "In6.Cu")
		(net "M_H_CPU1_SA_DQ<5>")
	)
	(segment
		(start 176.05629 -304.293524)
		(end 175.664368 -304.293524)
		(width 0.18288)
		(layer "In6.Cu")
		(net "M_H_CPU1_SA_DQ<5>")
	)
	(segment
		(start 180.332126 -305.465226)
		(end 179.976526 -305.465226)
		(width 0.18288)
		(layer "In6.Cu")
		(net "M_H_CPU1_SA_DQ<5>")
	)
	(segment
		(start 170.642026 -305.342036)
		(end 170.314366 -305.342036)
		(width 0.18288)
		(layer "In6.Cu")
		(net "M_H_CPU1_SA_DQ<5>")
	)
	(segment
		(start 140.798042 -278.267414)
		(end 140.367258 -278.267414)
		(width 0.18288)
		(layer "In6.Cu")
		(net "M_H_CPU1_SA_DQ<5>")
	)
	(segment
		(start 127.569468 -275.8948)
		(end 127.256794 -275.8948)
		(width 0.088646)
		(layer "In6.Cu")
		(net "M_H_CPU1_SA_DQ<5>")
	)
	(segment
		(start 161.195512 -300.034198)
		(end 160.765236 -300.034198)
		(width 0.18288)
		(layer "In6.Cu")
		(net "M_H_CPU1_SA_DQ<5>")
	)
	(segment
		(start 168.538144 -303.950116)
		(end 168.196514 -304.291746)
		(width 0.18288)
		(layer "In6.Cu")
		(net "M_H_CPU1_SA_DQ<5>")
	)
	(segment
		(start 132.708396 -275.570442)
		(end 132.693664 -275.579078)
		(width 0.088646)
		(layer "In6.Cu")
		(net "M_H_CPU1_SA_DQ<5>")
	)
	(segment
		(start 170.314366 -305.342036)
		(end 170.131486 -305.159156)
		(width 0.18288)
		(layer "In6.Cu")
		(net "M_H_CPU1_SA_DQ<5>")
	)
	(segment
		(start 164.337746 -300.514766)
		(end 163.825174 -300.302422)
		(width 0.18288)
		(layer "In6.Cu")
		(net "M_H_CPU1_SA_DQ<5>")
	)
	(segment
		(start 190.846456 -307.705506)
		(end 190.533528 -307.392578)
		(width 0.18288)
		(layer "In6.Cu")
		(net "M_H_CPU1_SA_DQ<5>")
	)
	(segment
		(start 182.160926 -307.294026)
		(end 180.332126 -305.465226)
		(width 0.18288)
		(layer "In6.Cu")
		(net "M_H_CPU1_SA_DQ<5>")
	)
	(segment
		(start 168.196514 -304.291746)
		(end 167.937942 -304.291746)
		(width 0.18288)
		(layer "In6.Cu")
		(net "M_H_CPU1_SA_DQ<5>")
	)
	(segment
		(start 163.19373 -300.872906)
		(end 162.890454 -300.747176)
		(width 0.18288)
		(layer "In6.Cu")
		(net "M_H_CPU1_SA_DQ<5>")
	)
	(segment
		(start 158.388558 -299.300392)
		(end 158.70174 -298.98721)
		(width 0.18288)
		(layer "In6.Cu")
		(net "M_H_CPU1_SA_DQ<5>")
	)
	(segment
		(start 136.467596 -275.570442)
		(end 136.452864 -275.579078)
		(width 0.088646)
		(layer "In6.Cu")
		(net "M_H_CPU1_SA_DQ<5>")
	)
	(segment
		(start 192.818512 -307.062124)
		(end 192.658492 -307.222144)
		(width 0.18288)
		(layer "In6.Cu")
		(net "M_H_CPU1_SA_DQ<5>")
	)
	(segment
		(start 177.417222 -303.992026)
		(end 176.357788 -303.992026)
		(width 0.18288)
		(layer "In6.Cu")
		(net "M_H_CPU1_SA_DQ<5>")
	)
	(segment
		(start 174.096426 -303.992026)
		(end 173.246288 -304.842164)
		(width 0.18288)
		(layer "In6.Cu")
		(net "M_H_CPU1_SA_DQ<5>")
	)
	(segment
		(start 162.945572 -300.136052)
		(end 162.846512 -299.897292)
		(width 0.18288)
		(layer "In6.Cu")
		(net "M_H_CPU1_SA_DQ<5>")
	)
	(segment
		(start 168.04767 -303.459642)
		(end 168.04767 -303.20107)
		(width 0.18288)
		(layer "In6.Cu")
		(net "M_H_CPU1_SA_DQ<5>")
	)
	(segment
		(start 137.407396 -275.570442)
		(end 137.392664 -275.579078)
		(width 0.088646)
		(layer "In6.Cu")
		(net "M_H_CPU1_SA_DQ<5>")
	)
	(segment
		(start 162.846512 -299.897292)
		(end 162.473386 -299.742606)
		(width 0.18288)
		(layer "In6.Cu")
		(net "M_H_CPU1_SA_DQ<5>")
	)
	(segment
		(start 159.683196 -299.742606)
		(end 159.418274 -299.477684)
		(width 0.18288)
		(layer "In6.Cu")
		(net "M_H_CPU1_SA_DQ<5>")
	)
	(segment
		(start 127.635254 -275.960586)
		(end 127.569468 -275.8948)
		(width 0.088646)
		(layer "In6.Cu")
		(net "M_H_CPU1_SA_DQ<5>")
	)
	(segment
		(start 192.658492 -307.222144)
		(end 192.658492 -307.232558)
		(width 0.18288)
		(layer "In6.Cu")
		(net "M_H_CPU1_SA_DQ<5>")
	)
	(segment
		(start 194.873626 -307.528214)
		(end 194.11315 -307.528214)
		(width 0.18288)
		(layer "In6.Cu")
		(net "M_H_CPU1_SA_DQ<5>")
	)
	(segment
		(start 150.465282 -282.531312)
		(end 146.430746 -278.496776)
		(width 0.18288)
		(layer "In6.Cu")
		(net "M_H_CPU1_SA_DQ<5>")
	)
	(segment
		(start 127.914146 -276.384258)
		(end 127.90805 -276.380702)
		(width 0.088646)
		(layer "In6.Cu")
		(net "M_H_CPU1_SA_DQ<5>")
	)
	(segment
		(start 202.412854 -308.666642)
		(end 201.68108 -307.934868)
		(width 0.18288)
		(layer "In6.Cu")
		(net "M_H_CPU1_SA_DQ<5>")
	)
	(segment
		(start 169.523918 -304.677318)
		(end 168.796716 -303.950116)
		(width 0.18288)
		(layer "In6.Cu")
		(net "M_H_CPU1_SA_DQ<5>")
	)
	(segment
		(start 192.498472 -307.392578)
		(end 191.539876 -307.392578)
		(width 0.18288)
		(layer "In6.Cu")
		(net "M_H_CPU1_SA_DQ<5>")
	)
	(segment
		(start 158.70174 -298.76115)
		(end 157.9118 -297.97121)
		(width 0.18288)
		(layer "In6.Cu")
		(net "M_H_CPU1_SA_DQ<5>")
	)
	(segment
		(start 167.70604 -304.059844)
		(end 167.70604 -303.801272)
		(width 0.18288)
		(layer "In6.Cu")
		(net "M_H_CPU1_SA_DQ<5>")
	)
	(segment
		(start 170.824906 -305.159156)
		(end 170.642026 -305.342036)
		(width 0.18288)
		(layer "In6.Cu")
		(net "M_H_CPU1_SA_DQ<5>")
	)
	(segment
		(start 168.04767 -303.20107)
		(end 167.815768 -302.969168)
		(width 0.18288)
		(layer "In6.Cu")
		(net "M_H_CPU1_SA_DQ<5>")
	)
	(segment
		(start 169.948606 -304.677318)
		(end 169.523918 -304.677318)
		(width 0.18288)
		(layer "In6.Cu")
		(net "M_H_CPU1_SA_DQ<5>")
	)
	(segment
		(start 167.937942 -304.291746)
		(end 167.70604 -304.059844)
		(width 0.18288)
		(layer "In6.Cu")
		(net "M_H_CPU1_SA_DQ<5>")
	)
	(segment
		(start 138.347196 -275.570442)
		(end 138.332464 -275.579078)
		(width 0.088646)
		(layer "In6.Cu")
		(net "M_H_CPU1_SA_DQ<5>")
	)
	(segment
		(start 166.725092 -302.820324)
		(end 167.066722 -302.478694)
		(width 0.18288)
		(layer "In6.Cu")
		(net "M_H_CPU1_SA_DQ<5>")
	)
	(segment
		(start 159.418274 -299.477684)
		(end 159.192214 -299.477684)
		(width 0.18288)
		(layer "In6.Cu")
		(net "M_H_CPU1_SA_DQ<5>")
	)
	(segment
		(start 163.586414 -300.401482)
		(end 163.432236 -300.773846)
		(width 0.18288)
		(layer "In6.Cu")
		(net "M_H_CPU1_SA_DQ<5>")
	)
	(segment
		(start 195.203826 -307.198014)
		(end 194.873626 -307.528214)
		(width 0.18288)
		(layer "In6.Cu")
		(net "M_H_CPU1_SA_DQ<5>")
	)
	(segment
		(start 146.430746 -278.496776)
		(end 141.351762 -278.496776)
		(width 0.18288)
		(layer "In6.Cu")
		(net "M_H_CPU1_SA_DQ<5>")
	)
	(segment
		(start 189.311026 -308.059582)
		(end 189.1284 -308.242208)
		(width 0.18288)
		(layer "In6.Cu")
		(net "M_H_CPU1_SA_DQ<5>")
	)
	(segment
		(start 193.64706 -307.062124)
		(end 192.818512 -307.062124)
		(width 0.18288)
		(layer "In6.Cu")
		(net "M_H_CPU1_SA_DQ<5>")
	)
	(segment
		(start 183.947308 -308.242208)
		(end 182.999126 -307.294026)
		(width 0.18288)
		(layer "In6.Cu")
		(net "M_H_CPU1_SA_DQ<5>")
	)
	(segment
		(start 165.744144 -302.097948)
		(end 165.744144 -301.839376)
		(width 0.18288)
		(layer "In6.Cu")
		(net "M_H_CPU1_SA_DQ<5>")
	)
	(arc
		(start 138.909044 -275.8948)
		(mid 138.861365 -275.7119)
		(end 138.730482 -275.575522)
		(width 0.088646)
		(layer "In6.Cu")
		(net "M_H_CPU1_SA_DQ<5>")
	)
	(arc
		(start 138.721592 -275.570442)
		(mid 138.534394 -275.520299)
		(end 138.347196 -275.570442)
		(width 0.088646)
		(layer "In6.Cu")
		(net "M_H_CPU1_SA_DQ<5>")
	)
	(arc
		(start 137.392664 -275.579078)
		(mid 137.116189 -275.646398)
		(end 136.841992 -275.570442)
		(width 0.088646)
		(layer "In6.Cu")
		(net "M_H_CPU1_SA_DQ<5>")
	)
	(arc
		(start 139.191492 -276.384258)
		(mid 138.987157 -276.181653)
		(end 138.909044 -275.904706)
		(width 0.088646)
		(layer "In6.Cu")
		(net "M_H_CPU1_SA_DQ<5>")
	)
	(arc
		(start 135.902192 -275.570442)
		(mid 135.714994 -275.520299)
		(end 135.527796 -275.570442)
		(width 0.088646)
		(layer "In6.Cu")
		(net "M_H_CPU1_SA_DQ<5>")
	)
	(arc
		(start 128.47955 -276.384258)
		(mid 128.205351 -276.460093)
		(end 127.928878 -276.392894)
		(width 0.088646)
		(layer "In6.Cu")
		(net "M_H_CPU1_SA_DQ<5>")
	)
	(arc
		(start 132.142992 -275.570442)
		(mid 131.955794 -275.520299)
		(end 131.768596 -275.570442)
		(width 0.088646)
		(layer "In6.Cu")
		(net "M_H_CPU1_SA_DQ<5>")
	)
	(arc
		(start 139.378944 -276.708616)
		(mid 139.331265 -276.525716)
		(end 139.200382 -276.389338)
		(width 0.088646)
		(layer "In6.Cu")
		(net "M_H_CPU1_SA_DQ<5>")
	)
	(arc
		(start 138.332464 -275.579078)
		(mid 138.055989 -275.646398)
		(end 137.781792 -275.570442)
		(width 0.088646)
		(layer "In6.Cu")
		(net "M_H_CPU1_SA_DQ<5>")
	)
	(arc
		(start 134.962392 -275.570442)
		(mid 134.775194 -275.520299)
		(end 134.587996 -275.570442)
		(width 0.088646)
		(layer "In6.Cu")
		(net "M_H_CPU1_SA_DQ<5>")
	)
	(arc
		(start 136.841992 -275.570442)
		(mid 136.654794 -275.520299)
		(end 136.467596 -275.570442)
		(width 0.088646)
		(layer "In6.Cu")
		(net "M_H_CPU1_SA_DQ<5>")
	)
	(arc
		(start 131.203192 -275.570442)
		(mid 131.015994 -275.520299)
		(end 130.828796 -275.570442)
		(width 0.088646)
		(layer "In6.Cu")
		(net "M_H_CPU1_SA_DQ<5>")
	)
	(arc
		(start 129.323846 -275.570442)
		(mid 129.136648 -275.520299)
		(end 128.94945 -275.570442)
		(width 0.088646)
		(layer "In6.Cu")
		(net "M_H_CPU1_SA_DQ<5>")
	)
	(arc
		(start 135.513064 -275.579078)
		(mid 135.236589 -275.646398)
		(end 134.962392 -275.570442)
		(width 0.088646)
		(layer "In6.Cu")
		(net "M_H_CPU1_SA_DQ<5>")
	)
	(arc
		(start 127.90805 -276.380702)
		(mid 127.722595 -276.202507)
		(end 127.635254 -275.960586)
		(width 0.088646)
		(layer "In6.Cu")
		(net "M_H_CPU1_SA_DQ<5>")
	)
	(arc
		(start 133.648196 -275.570442)
		(mid 133.365494 -275.646184)
		(end 133.082792 -275.570442)
		(width 0.088646)
		(layer "In6.Cu")
		(net "M_H_CPU1_SA_DQ<5>")
	)
	(arc
		(start 134.573264 -275.579078)
		(mid 134.296823 -275.646244)
		(end 134.022592 -275.570442)
		(width 0.088646)
		(layer "In6.Cu")
		(net "M_H_CPU1_SA_DQ<5>")
	)
	(arc
		(start 137.781792 -275.570442)
		(mid 137.594594 -275.520299)
		(end 137.407396 -275.570442)
		(width 0.088646)
		(layer "In6.Cu")
		(net "M_H_CPU1_SA_DQ<5>")
	)
	(arc
		(start 128.761998 -275.8948)
		(mid 128.688082 -276.174302)
		(end 128.485646 -276.380702)
		(width 0.088646)
		(layer "In6.Cu")
		(net "M_H_CPU1_SA_DQ<5>")
	)
	(arc
		(start 130.263392 -275.570442)
		(mid 130.076194 -275.520299)
		(end 129.888996 -275.570442)
		(width 0.088646)
		(layer "In6.Cu")
		(net "M_H_CPU1_SA_DQ<5>")
	)
	(arc
		(start 136.452864 -275.579078)
		(mid 136.176389 -275.646398)
		(end 135.902192 -275.570442)
		(width 0.088646)
		(layer "In6.Cu")
		(net "M_H_CPU1_SA_DQ<5>")
	)
	(arc
		(start 134.022592 -275.570442)
		(mid 133.835394 -275.520299)
		(end 133.648196 -275.570442)
		(width 0.088646)
		(layer "In6.Cu")
		(net "M_H_CPU1_SA_DQ<5>")
	)
	(arc
		(start 128.94056 -275.575522)
		(mid 128.809646 -275.711882)
		(end 128.761998 -275.8948)
		(width 0.088646)
		(layer "In6.Cu")
		(net "M_H_CPU1_SA_DQ<5>")
	)
	(arc
		(start 129.878582 -275.576538)
		(mid 129.600404 -275.64623)
		(end 129.323846 -275.570442)
		(width 0.088646)
		(layer "In6.Cu")
		(net "M_H_CPU1_SA_DQ<5>")
	)
	(arc
		(start 131.753864 -275.579078)
		(mid 131.477423 -275.646244)
		(end 131.203192 -275.570442)
		(width 0.088646)
		(layer "In6.Cu")
		(net "M_H_CPU1_SA_DQ<5>")
	)
	(arc
		(start 130.814064 -275.579078)
		(mid 130.537623 -275.646244)
		(end 130.263392 -275.570442)
		(width 0.088646)
		(layer "In6.Cu")
		(net "M_H_CPU1_SA_DQ<5>")
	)
	(arc
		(start 132.693664 -275.579078)
		(mid 132.417223 -275.646244)
		(end 132.142992 -275.570442)
		(width 0.088646)
		(layer "In6.Cu")
		(net "M_H_CPU1_SA_DQ<5>")
	)
	(arc
		(start 133.082792 -275.570442)
		(mid 132.895594 -275.520299)
		(end 132.708396 -275.570442)
		(width 0.088646)
		(layer "In6.Cu")
		(net "M_H_CPU1_SA_DQ<5>")
	)
	(segment
		(start 209.186526 -309.935372)
		(end 209.180176 -309.941722)
		(width 0.1016)
		(layer "F.Cu")
		(net "M_H_CPU1_SA_DQ<4>")
	)
	(segment
		(start 209.180176 -309.941722)
		(end 207.018382 -309.941722)
		(width 0.1016)
		(layer "F.Cu")
		(net "M_H_CPU1_SA_DQ<4>")
	)
	(segment
		(start 211.619592 -310.366918)
		(end 210.028028 -310.366918)
		(width 0.20066)
		(layer "F.Cu")
		(net "M_H_CPU1_SA_DQ<4>")
	)
	(segment
		(start 206.508604 -310.059832)
		(end 206.508604 -310.42737)
		(width 0.20066)
		(layer "F.Cu")
		(net "M_H_CPU1_SA_DQ<4>")
	)
	(segment
		(start 204.076046 -310.366664)
		(end 202.971146 -310.366664)
		(width 0.20066)
		(layer "F.Cu")
		(net "M_H_CPU1_SA_DQ<4>")
	)
	(segment
		(start 209.596482 -309.935372)
		(end 209.186526 -309.935372)
		(width 0.20066)
		(layer "F.Cu")
		(net "M_H_CPU1_SA_DQ<4>")
	)
	(segment
		(start 205.84541 -310.61533)
		(end 205.596744 -310.366664)
		(width 0.20066)
		(layer "F.Cu")
		(net "M_H_CPU1_SA_DQ<4>")
	)
	(segment
		(start 211.619846 -310.366664)
		(end 211.619592 -310.366918)
		(width 0.20066)
		(layer "F.Cu")
		(net "M_H_CPU1_SA_DQ<4>")
	)
	(segment
		(start 207.018382 -309.941722)
		(end 206.971392 -309.941722)
		(width 0.101854)
		(layer "F.Cu")
		(net "M_H_CPU1_SA_DQ<4>")
	)
	(segment
		(start 210.028028 -310.366918)
		(end 209.596482 -309.935372)
		(width 0.20066)
		(layer "F.Cu")
		(net "M_H_CPU1_SA_DQ<4>")
	)
	(segment
		(start 206.626714 -309.941722)
		(end 206.508604 -310.059832)
		(width 0.20066)
		(layer "F.Cu")
		(net "M_H_CPU1_SA_DQ<4>")
	)
	(segment
		(start 206.320644 -310.61533)
		(end 205.84541 -310.61533)
		(width 0.20066)
		(layer "F.Cu")
		(net "M_H_CPU1_SA_DQ<4>")
	)
	(segment
		(start 206.971392 -309.941722)
		(end 206.626714 -309.941722)
		(width 0.20066)
		(layer "F.Cu")
		(net "M_H_CPU1_SA_DQ<4>")
	)
	(segment
		(start 205.596744 -310.366664)
		(end 204.076046 -310.366664)
		(width 0.20066)
		(layer "F.Cu")
		(net "M_H_CPU1_SA_DQ<4>")
	)
	(segment
		(start 126.786894 -276.172676)
		(end 126.787148 -276.708616)
		(width 0.20066)
		(layer "F.Cu")
		(net "M_H_CPU1_SA_DQ<4>")
	)
	(segment
		(start 206.508604 -310.42737)
		(end 206.320644 -310.61533)
		(width 0.20066)
		(layer "F.Cu")
		(net "M_H_CPU1_SA_DQ<4>")
	)
	(segment
		(start 166.238174 -304.938938)
		(end 166.326058 -304.851054)
		(width 0.18288)
		(layer "In6.Cu")
		(net "M_H_CPU1_SA_DQ<4>")
	)
	(segment
		(start 167.042592 -305.341528)
		(end 166.816532 -305.341528)
		(width 0.18288)
		(layer "In6.Cu")
		(net "M_H_CPU1_SA_DQ<4>")
	)
	(segment
		(start 180.484526 -307.141626)
		(end 179.976526 -307.141626)
		(width 0.18288)
		(layer "In6.Cu")
		(net "M_H_CPU1_SA_DQ<4>")
	)
	(segment
		(start 166.728648 -305.429412)
		(end 166.502588 -305.429412)
		(width 0.18288)
		(layer "In6.Cu")
		(net "M_H_CPU1_SA_DQ<4>")
	)
	(segment
		(start 165.17112 -303.696116)
		(end 165.02126 -303.845976)
		(width 0.18288)
		(layer "In6.Cu")
		(net "M_H_CPU1_SA_DQ<4>")
	)
	(segment
		(start 170.257216 -307.139594)
		(end 170.084496 -306.966874)
		(width 0.18288)
		(layer "In6.Cu")
		(net "M_H_CPU1_SA_DQ<4>")
	)
	(segment
		(start 130.748278 -276.392894)
		(end 130.733546 -276.384258)
		(width 0.088646)
		(layer "In6.Cu")
		(net "M_H_CPU1_SA_DQ<4>")
	)
	(segment
		(start 193.483992 -309.25262)
		(end 193.483992 -309.494428)
		(width 0.18288)
		(layer "In6.Cu")
		(net "M_H_CPU1_SA_DQ<4>")
	)
	(segment
		(start 200.54189 -310.565038)
		(end 200.35901 -310.382158)
		(width 0.18288)
		(layer "In6.Cu")
		(net "M_H_CPU1_SA_DQ<4>")
	)
	(segment
		(start 162.491674 -301.769526)
		(end 162.164268 -301.44212)
		(width 0.18288)
		(layer "In6.Cu")
		(net "M_H_CPU1_SA_DQ<4>")
	)
	(segment
		(start 161.576258 -301.44212)
		(end 161.185098 -301.83328)
		(width 0.18288)
		(layer "In6.Cu")
		(net "M_H_CPU1_SA_DQ<4>")
	)
	(segment
		(start 128.868678 -277.024338)
		(end 128.853946 -277.032974)
		(width 0.088646)
		(layer "In6.Cu")
		(net "M_H_CPU1_SA_DQ<4>")
	)
	(segment
		(start 167.891714 -305.559714)
		(end 167.260778 -305.559714)
		(width 0.18288)
		(layer "In6.Cu")
		(net "M_H_CPU1_SA_DQ<4>")
	)
	(segment
		(start 138.439144 -276.718522)
		(end 138.439144 -276.708616)
		(width 0.088646)
		(layer "In6.Cu")
		(net "M_H_CPU1_SA_DQ<4>")
	)
	(segment
		(start 179.976526 -307.141626)
		(end 179.214526 -306.379626)
		(width 0.18288)
		(layer "In6.Cu")
		(net "M_H_CPU1_SA_DQ<4>")
	)
	(segment
		(start 162.728402 -302.739806)
		(end 162.502342 -302.739806)
		(width 0.18288)
		(layer "In6.Cu")
		(net "M_H_CPU1_SA_DQ<4>")
	)
	(segment
		(start 171.835826 -306.354226)
		(end 171.046394 -306.354226)
		(width 0.18288)
		(layer "In6.Cu")
		(net "M_H_CPU1_SA_DQ<4>")
	)
	(segment
		(start 200.86955 -310.565038)
		(end 200.54189 -310.565038)
		(width 0.18288)
		(layer "In6.Cu")
		(net "M_H_CPU1_SA_DQ<4>")
	)
	(segment
		(start 166.326058 -304.851054)
		(end 166.326058 -304.624994)
		(width 0.18288)
		(layer "In6.Cu")
		(net "M_H_CPU1_SA_DQ<4>")
	)
	(segment
		(start 138.909044 -277.540974)
		(end 138.909044 -277.522432)
		(width 0.088646)
		(layer "In6.Cu")
		(net "M_H_CPU1_SA_DQ<4>")
	)
	(segment
		(start 182.237126 -308.894226)
		(end 180.484526 -307.141626)
		(width 0.18288)
		(layer "In6.Cu")
		(net "M_H_CPU1_SA_DQ<4>")
	)
	(segment
		(start 164.680646 -302.979582)
		(end 164.187124 -302.48606)
		(width 0.18288)
		(layer "In6.Cu")
		(net "M_H_CPU1_SA_DQ<4>")
	)
	(segment
		(start 157.525466 -300.590712)
		(end 149.469602 -292.534848)
		(width 0.18288)
		(layer "In6.Cu")
		(net "M_H_CPU1_SA_DQ<4>")
	)
	(segment
		(start 164.187124 -302.48606)
		(end 162.982148 -302.48606)
		(width 0.18288)
		(layer "In6.Cu")
		(net "M_H_CPU1_SA_DQ<4>")
	)
	(segment
		(start 199.069198 -309.948072)
		(end 197.468744 -309.948072)
		(width 0.18288)
		(layer "In6.Cu")
		(net "M_H_CPU1_SA_DQ<4>")
	)
	(segment
		(start 170.873166 -306.527454)
		(end 170.873166 -306.985416)
		(width 0.18288)
		(layer "In6.Cu")
		(net "M_H_CPU1_SA_DQ<4>")
	)
	(segment
		(start 164.530786 -303.581562)
		(end 164.530786 -303.355502)
		(width 0.18288)
		(layer "In6.Cu")
		(net "M_H_CPU1_SA_DQ<4>")
	)
	(segment
		(start 138.730482 -277.203154)
		(end 138.721592 -277.198074)
		(width 0.088646)
		(layer "In6.Cu")
		(net "M_H_CPU1_SA_DQ<4>")
	)
	(segment
		(start 193.644012 -309.0926)
		(end 193.483992 -309.25262)
		(width 0.18288)
		(layer "In6.Cu")
		(net "M_H_CPU1_SA_DQ<4>")
	)
	(segment
		(start 166.816532 -305.341528)
		(end 166.728648 -305.429412)
		(width 0.18288)
		(layer "In6.Cu")
		(net "M_H_CPU1_SA_DQ<4>")
	)
	(segment
		(start 192.630552 -309.0926)
		(end 189.85484 -309.0926)
		(width 0.18288)
		(layer "In6.Cu")
		(net "M_H_CPU1_SA_DQ<4>")
	)
	(segment
		(start 162.164268 -301.44212)
		(end 161.576258 -301.44212)
		(width 0.18288)
		(layer "In6.Cu")
		(net "M_H_CPU1_SA_DQ<4>")
	)
	(segment
		(start 194.962272 -309.25262)
		(end 194.962272 -309.670958)
		(width 0.18288)
		(layer "In6.Cu")
		(net "M_H_CPU1_SA_DQ<4>")
	)
	(segment
		(start 139.422124 -278.22398)
		(end 139.26947 -278.071326)
		(width 0.088646)
		(layer "In6.Cu")
		(net "M_H_CPU1_SA_DQ<4>")
	)
	(segment
		(start 194.108832 -309.0926)
		(end 193.644012 -309.0926)
		(width 0.18288)
		(layer "In6.Cu")
		(net "M_H_CPU1_SA_DQ<4>")
	)
	(segment
		(start 158.672784 -301.30115)
		(end 157.962346 -300.590712)
		(width 0.18288)
		(layer "In6.Cu")
		(net "M_H_CPU1_SA_DQ<4>")
	)
	(segment
		(start 202.971146 -310.366664)
		(end 202.445366 -309.840884)
		(width 0.18288)
		(layer "In6.Cu")
		(net "M_H_CPU1_SA_DQ<4>")
	)
	(segment
		(start 201.05243 -310.382158)
		(end 200.86955 -310.565038)
		(width 0.18288)
		(layer "In6.Cu")
		(net "M_H_CPU1_SA_DQ<4>")
	)
	(segment
		(start 169.85615 -306.354226)
		(end 168.686226 -306.354226)
		(width 0.18288)
		(layer "In6.Cu")
		(net "M_H_CPU1_SA_DQ<4>")
	)
	(segment
		(start 134.507478 -276.392894)
		(end 134.492746 -276.384258)
		(width 0.088646)
		(layer "In6.Cu")
		(net "M_H_CPU1_SA_DQ<4>")
	)
	(segment
		(start 149.469602 -282.943808)
		(end 146.01825 -279.492456)
		(width 0.18288)
		(layer "In6.Cu")
		(net "M_H_CPU1_SA_DQ<4>")
	)
	(segment
		(start 178.30165 -306.379626)
		(end 177.614326 -305.692302)
		(width 0.18288)
		(layer "In6.Cu")
		(net "M_H_CPU1_SA_DQ<4>")
	)
	(segment
		(start 200.35901 -310.023764)
		(end 200.17613 -309.840884)
		(width 0.18288)
		(layer "In6.Cu")
		(net "M_H_CPU1_SA_DQ<4>")
	)
	(segment
		(start 182.999126 -308.894226)
		(end 182.237126 -308.894226)
		(width 0.18288)
		(layer "In6.Cu")
		(net "M_H_CPU1_SA_DQ<4>")
	)
	(segment
		(start 199.176386 -309.840884)
		(end 199.069198 -309.948072)
		(width 0.18288)
		(layer "In6.Cu")
		(net "M_H_CPU1_SA_DQ<4>")
	)
	(segment
		(start 184.047384 -309.942484)
		(end 182.999126 -308.894226)
		(width 0.18288)
		(layer "In6.Cu")
		(net "M_H_CPU1_SA_DQ<4>")
	)
	(segment
		(start 165.02126 -303.845976)
		(end 164.7952 -303.845976)
		(width 0.18288)
		(layer "In6.Cu")
		(net "M_H_CPU1_SA_DQ<4>")
	)
	(segment
		(start 161.358072 -302.458628)
		(end 161.093658 -302.723042)
		(width 0.18288)
		(layer "In6.Cu")
		(net "M_H_CPU1_SA_DQ<4>")
	)
	(segment
		(start 162.982148 -302.48606)
		(end 162.728402 -302.739806)
		(width 0.18288)
		(layer "In6.Cu")
		(net "M_H_CPU1_SA_DQ<4>")
	)
	(segment
		(start 138.260582 -276.389338)
		(end 138.251692 -276.384258)
		(width 0.088646)
		(layer "In6.Cu")
		(net "M_H_CPU1_SA_DQ<4>")
	)
	(segment
		(start 170.718988 -307.139594)
		(end 170.257216 -307.139594)
		(width 0.18288)
		(layer "In6.Cu")
		(net "M_H_CPU1_SA_DQ<4>")
	)
	(segment
		(start 158.939484 -302.903128)
		(end 158.672784 -302.636428)
		(width 0.18288)
		(layer "In6.Cu")
		(net "M_H_CPU1_SA_DQ<4>")
	)
	(segment
		(start 162.491674 -301.995586)
		(end 162.491674 -301.769526)
		(width 0.18288)
		(layer "In6.Cu")
		(net "M_H_CPU1_SA_DQ<4>")
	)
	(segment
		(start 129.808478 -276.392894)
		(end 129.793746 -276.384258)
		(width 0.088646)
		(layer "In6.Cu")
		(net "M_H_CPU1_SA_DQ<4>")
	)
	(segment
		(start 162.502342 -302.739806)
		(end 162.237928 -302.475392)
		(width 0.18288)
		(layer "In6.Cu")
		(net "M_H_CPU1_SA_DQ<4>")
	)
	(segment
		(start 170.873166 -306.985416)
		(end 170.718988 -307.139594)
		(width 0.18288)
		(layer "In6.Cu")
		(net "M_H_CPU1_SA_DQ<4>")
	)
	(segment
		(start 192.950592 -309.654448)
		(end 192.790572 -309.494428)
		(width 0.18288)
		(layer "In6.Cu")
		(net "M_H_CPU1_SA_DQ<4>")
	)
	(segment
		(start 140.62837 -279.275032)
		(end 140.517118 -279.275032)
		(width 0.18288)
		(layer "In6.Cu")
		(net "M_H_CPU1_SA_DQ<4>")
	)
	(segment
		(start 162.237928 -302.249332)
		(end 162.491674 -301.995586)
		(width 0.18288)
		(layer "In6.Cu")
		(net "M_H_CPU1_SA_DQ<4>")
	)
	(segment
		(start 139.422124 -278.354536)
		(end 139.422124 -278.22398)
		(width 0.088646)
		(layer "In6.Cu")
		(net "M_H_CPU1_SA_DQ<4>")
	)
	(segment
		(start 160.867598 -302.723042)
		(end 160.694624 -302.549814)
		(width 0.18288)
		(layer "In6.Cu")
		(net "M_H_CPU1_SA_DQ<4>")
	)
	(segment
		(start 201.05243 -310.023764)
		(end 201.05243 -310.382158)
		(width 0.18288)
		(layer "In6.Cu")
		(net "M_H_CPU1_SA_DQ<4>")
	)
	(segment
		(start 164.680646 -303.205642)
		(end 164.680646 -302.979582)
		(width 0.18288)
		(layer "In6.Cu")
		(net "M_H_CPU1_SA_DQ<4>")
	)
	(segment
		(start 165.39718 -303.696116)
		(end 165.17112 -303.696116)
		(width 0.18288)
		(layer "In6.Cu")
		(net "M_H_CPU1_SA_DQ<4>")
	)
	(segment
		(start 149.469602 -292.534848)
		(end 149.469602 -282.943808)
		(width 0.18288)
		(layer "In6.Cu")
		(net "M_H_CPU1_SA_DQ<4>")
	)
	(segment
		(start 160.468564 -302.549814)
		(end 160.11525 -302.903128)
		(width 0.18288)
		(layer "In6.Cu")
		(net "M_H_CPU1_SA_DQ<4>")
	)
	(segment
		(start 195.122292 -309.0926)
		(end 194.962272 -309.25262)
		(width 0.18288)
		(layer "In6.Cu")
		(net "M_H_CPU1_SA_DQ<4>")
	)
	(segment
		(start 140.34262 -279.275032)
		(end 139.422124 -278.354536)
		(width 0.088646)
		(layer "In6.Cu")
		(net "M_H_CPU1_SA_DQ<4>")
	)
	(segment
		(start 166.502588 -305.429412)
		(end 166.238174 -305.164998)
		(width 0.18288)
		(layer "In6.Cu")
		(net "M_H_CPU1_SA_DQ<4>")
	)
	(segment
		(start 202.445366 -309.840884)
		(end 201.23531 -309.840884)
		(width 0.18288)
		(layer "In6.Cu")
		(net "M_H_CPU1_SA_DQ<4>")
	)
	(segment
		(start 167.260778 -305.559714)
		(end 167.042592 -305.341528)
		(width 0.18288)
		(layer "In6.Cu")
		(net "M_H_CPU1_SA_DQ<4>")
	)
	(segment
		(start 194.802252 -309.830978)
		(end 194.428872 -309.830978)
		(width 0.18288)
		(layer "In6.Cu")
		(net "M_H_CPU1_SA_DQ<4>")
	)
	(segment
		(start 158.672784 -302.636428)
		(end 158.672784 -301.30115)
		(width 0.18288)
		(layer "In6.Cu")
		(net "M_H_CPU1_SA_DQ<4>")
	)
	(segment
		(start 131.68376 -276.390354)
		(end 131.673346 -276.384258)
		(width 0.088646)
		(layer "In6.Cu")
		(net "M_H_CPU1_SA_DQ<4>")
	)
	(segment
		(start 168.686226 -306.354226)
		(end 167.891714 -305.559714)
		(width 0.18288)
		(layer "In6.Cu")
		(net "M_H_CPU1_SA_DQ<4>")
	)
	(segment
		(start 160.694624 -302.549814)
		(end 160.468564 -302.549814)
		(width 0.18288)
		(layer "In6.Cu")
		(net "M_H_CPU1_SA_DQ<4>")
	)
	(segment
		(start 197.468744 -309.948072)
		(end 196.613272 -309.0926)
		(width 0.18288)
		(layer "In6.Cu")
		(net "M_H_CPU1_SA_DQ<4>")
	)
	(segment
		(start 160.11525 -302.903128)
		(end 158.939484 -302.903128)
		(width 0.18288)
		(layer "In6.Cu")
		(net "M_H_CPU1_SA_DQ<4>")
	)
	(segment
		(start 166.326058 -304.624994)
		(end 165.39718 -303.696116)
		(width 0.18288)
		(layer "In6.Cu")
		(net "M_H_CPU1_SA_DQ<4>")
	)
	(segment
		(start 161.358072 -302.232568)
		(end 161.358072 -302.458628)
		(width 0.18288)
		(layer "In6.Cu")
		(net "M_H_CPU1_SA_DQ<4>")
	)
	(segment
		(start 174.209964 -305.692302)
		(end 173.359826 -306.54244)
		(width 0.18288)
		(layer "In6.Cu")
		(net "M_H_CPU1_SA_DQ<4>")
	)
	(segment
		(start 166.238174 -305.164998)
		(end 166.238174 -304.938938)
		(width 0.18288)
		(layer "In6.Cu")
		(net "M_H_CPU1_SA_DQ<4>")
	)
	(segment
		(start 194.428872 -309.830978)
		(end 194.268852 -309.670958)
		(width 0.18288)
		(layer "In6.Cu")
		(net "M_H_CPU1_SA_DQ<4>")
	)
	(segment
		(start 189.004956 -309.942484)
		(end 184.047384 -309.942484)
		(width 0.18288)
		(layer "In6.Cu")
		(net "M_H_CPU1_SA_DQ<4>")
	)
	(segment
		(start 133.567678 -276.392894)
		(end 133.552946 -276.384258)
		(width 0.088646)
		(layer "In6.Cu")
		(net "M_H_CPU1_SA_DQ<4>")
	)
	(segment
		(start 170.084496 -306.582572)
		(end 169.85615 -306.354226)
		(width 0.18288)
		(layer "In6.Cu")
		(net "M_H_CPU1_SA_DQ<4>")
	)
	(segment
		(start 193.483992 -309.494428)
		(end 193.323972 -309.654448)
		(width 0.18288)
		(layer "In6.Cu")
		(net "M_H_CPU1_SA_DQ<4>")
	)
	(segment
		(start 132.623306 -276.390354)
		(end 132.612892 -276.384258)
		(width 0.088646)
		(layer "In6.Cu")
		(net "M_H_CPU1_SA_DQ<4>")
	)
	(segment
		(start 192.790572 -309.494428)
		(end 192.790572 -309.25262)
		(width 0.18288)
		(layer "In6.Cu")
		(net "M_H_CPU1_SA_DQ<4>")
	)
	(segment
		(start 127.279146 -276.891242)
		(end 126.787148 -276.708616)
		(width 0.088646)
		(layer "In6.Cu")
		(net "M_H_CPU1_SA_DQ<4>")
	)
	(segment
		(start 170.084496 -306.966874)
		(end 170.084496 -306.582572)
		(width 0.18288)
		(layer "In6.Cu")
		(net "M_H_CPU1_SA_DQ<4>")
	)
	(segment
		(start 194.268852 -309.670958)
		(end 194.268852 -309.25262)
		(width 0.18288)
		(layer "In6.Cu")
		(net "M_H_CPU1_SA_DQ<4>")
	)
	(segment
		(start 161.185098 -301.83328)
		(end 161.185098 -302.05934)
		(width 0.18288)
		(layer "In6.Cu")
		(net "M_H_CPU1_SA_DQ<4>")
	)
	(segment
		(start 201.23531 -309.840884)
		(end 201.05243 -310.023764)
		(width 0.18288)
		(layer "In6.Cu")
		(net "M_H_CPU1_SA_DQ<4>")
	)
	(segment
		(start 164.7952 -303.845976)
		(end 164.530786 -303.581562)
		(width 0.18288)
		(layer "In6.Cu")
		(net "M_H_CPU1_SA_DQ<4>")
	)
	(segment
		(start 157.962346 -300.590712)
		(end 157.525466 -300.590712)
		(width 0.18288)
		(layer "In6.Cu")
		(net "M_H_CPU1_SA_DQ<4>")
	)
	(segment
		(start 141.15288 -279.492456)
		(end 140.62837 -279.275032)
		(width 0.18288)
		(layer "In6.Cu")
		(net "M_H_CPU1_SA_DQ<4>")
	)
	(segment
		(start 140.517118 -279.275032)
		(end 140.34262 -279.275032)
		(width 0.088646)
		(layer "In6.Cu")
		(net "M_H_CPU1_SA_DQ<4>")
	)
	(segment
		(start 189.85484 -309.0926)
		(end 189.004956 -309.942484)
		(width 0.18288)
		(layer "In6.Cu")
		(net "M_H_CPU1_SA_DQ<4>")
	)
	(segment
		(start 192.790572 -309.25262)
		(end 192.630552 -309.0926)
		(width 0.18288)
		(layer "In6.Cu")
		(net "M_H_CPU1_SA_DQ<4>")
	)
	(segment
		(start 179.214526 -306.379626)
		(end 178.30165 -306.379626)
		(width 0.18288)
		(layer "In6.Cu")
		(net "M_H_CPU1_SA_DQ<4>")
	)
	(segment
		(start 162.237928 -302.475392)
		(end 162.237928 -302.249332)
		(width 0.18288)
		(layer "In6.Cu")
		(net "M_H_CPU1_SA_DQ<4>")
	)
	(segment
		(start 171.046394 -306.354226)
		(end 170.873166 -306.527454)
		(width 0.18288)
		(layer "In6.Cu")
		(net "M_H_CPU1_SA_DQ<4>")
	)
	(segment
		(start 200.35901 -310.382158)
		(end 200.35901 -310.023764)
		(width 0.18288)
		(layer "In6.Cu")
		(net "M_H_CPU1_SA_DQ<4>")
	)
	(segment
		(start 127.53975 -277.032974)
		(end 127.35941 -276.928834)
		(width 0.088646)
		(layer "In6.Cu")
		(net "M_H_CPU1_SA_DQ<4>")
	)
	(segment
		(start 194.962272 -309.670958)
		(end 194.802252 -309.830978)
		(width 0.18288)
		(layer "In6.Cu")
		(net "M_H_CPU1_SA_DQ<4>")
	)
	(segment
		(start 161.093658 -302.723042)
		(end 160.867598 -302.723042)
		(width 0.18288)
		(layer "In6.Cu")
		(net "M_H_CPU1_SA_DQ<4>")
	)
	(segment
		(start 127.928878 -277.024338)
		(end 127.914146 -277.032974)
		(width 0.088646)
		(layer "In6.Cu")
		(net "M_H_CPU1_SA_DQ<4>")
	)
	(segment
		(start 161.185098 -302.05934)
		(end 161.358072 -302.232568)
		(width 0.18288)
		(layer "In6.Cu")
		(net "M_H_CPU1_SA_DQ<4>")
	)
	(segment
		(start 200.17613 -309.840884)
		(end 199.176386 -309.840884)
		(width 0.18288)
		(layer "In6.Cu")
		(net "M_H_CPU1_SA_DQ<4>")
	)
	(segment
		(start 177.614326 -305.692302)
		(end 174.209964 -305.692302)
		(width 0.18288)
		(layer "In6.Cu")
		(net "M_H_CPU1_SA_DQ<4>")
	)
	(segment
		(start 135.44296 -276.390354)
		(end 135.432546 -276.384258)
		(width 0.088646)
		(layer "In6.Cu")
		(net "M_H_CPU1_SA_DQ<4>")
	)
	(segment
		(start 196.613272 -309.0926)
		(end 195.122292 -309.0926)
		(width 0.18288)
		(layer "In6.Cu")
		(net "M_H_CPU1_SA_DQ<4>")
	)
	(segment
		(start 173.359826 -306.54244)
		(end 172.02404 -306.54244)
		(width 0.18288)
		(layer "In6.Cu")
		(net "M_H_CPU1_SA_DQ<4>")
	)
	(segment
		(start 164.530786 -303.355502)
		(end 164.680646 -303.205642)
		(width 0.18288)
		(layer "In6.Cu")
		(net "M_H_CPU1_SA_DQ<4>")
	)
	(segment
		(start 194.268852 -309.25262)
		(end 194.108832 -309.0926)
		(width 0.18288)
		(layer "In6.Cu")
		(net "M_H_CPU1_SA_DQ<4>")
	)
	(segment
		(start 193.323972 -309.654448)
		(end 192.950592 -309.654448)
		(width 0.18288)
		(layer "In6.Cu")
		(net "M_H_CPU1_SA_DQ<4>")
	)
	(segment
		(start 172.02404 -306.54244)
		(end 171.835826 -306.354226)
		(width 0.18288)
		(layer "In6.Cu")
		(net "M_H_CPU1_SA_DQ<4>")
	)
	(segment
		(start 146.01825 -279.492456)
		(end 141.15288 -279.492456)
		(width 0.18288)
		(layer "In6.Cu")
		(net "M_H_CPU1_SA_DQ<4>")
	)
	(arc
		(start 135.997696 -276.384258)
		(mid 135.721137 -276.460001)
		(end 135.44296 -276.390354)
		(width 0.088646)
		(layer "In6.Cu")
		(net "M_H_CPU1_SA_DQ<4>")
	)
	(arc
		(start 139.191492 -278.012144)
		(mid 138.989206 -277.813163)
		(end 138.909044 -277.540974)
		(width 0.088646)
		(layer "In6.Cu")
		(net "M_H_CPU1_SA_DQ<4>")
	)
	(arc
		(start 129.250186 -276.593554)
		(mid 129.093722 -276.839315)
		(end 128.868678 -277.024338)
		(width 0.088646)
		(layer "In6.Cu")
		(net "M_H_CPU1_SA_DQ<4>")
	)
	(arc
		(start 127.914146 -277.032974)
		(mid 127.726948 -277.083151)
		(end 127.53975 -277.032974)
		(width 0.088646)
		(layer "In6.Cu")
		(net "M_H_CPU1_SA_DQ<4>")
	)
	(arc
		(start 134.492746 -276.384258)
		(mid 134.305548 -276.334115)
		(end 134.11835 -276.384258)
		(width 0.088646)
		(layer "In6.Cu")
		(net "M_H_CPU1_SA_DQ<4>")
	)
	(arc
		(start 129.793746 -276.384258)
		(mid 129.471988 -276.359124)
		(end 129.250186 -276.593554)
		(width 0.088646)
		(layer "In6.Cu")
		(net "M_H_CPU1_SA_DQ<4>")
	)
	(arc
		(start 128.853946 -277.032974)
		(mid 128.666748 -277.083117)
		(end 128.47955 -277.032974)
		(width 0.088646)
		(layer "In6.Cu")
		(net "M_H_CPU1_SA_DQ<4>")
	)
	(arc
		(start 137.311892 -276.384258)
		(mid 137.124694 -276.334115)
		(end 136.937496 -276.384258)
		(width 0.088646)
		(layer "In6.Cu")
		(net "M_H_CPU1_SA_DQ<4>")
	)
	(arc
		(start 134.11835 -276.384258)
		(mid 133.844151 -276.460093)
		(end 133.567678 -276.392894)
		(width 0.088646)
		(layer "In6.Cu")
		(net "M_H_CPU1_SA_DQ<4>")
	)
	(arc
		(start 130.733546 -276.384258)
		(mid 130.546348 -276.334115)
		(end 130.35915 -276.384258)
		(width 0.088646)
		(layer "In6.Cu")
		(net "M_H_CPU1_SA_DQ<4>")
	)
	(arc
		(start 137.877296 -276.384258)
		(mid 137.594594 -276.460034)
		(end 137.311892 -276.384258)
		(width 0.088646)
		(layer "In6.Cu")
		(net "M_H_CPU1_SA_DQ<4>")
	)
	(arc
		(start 133.17855 -276.384258)
		(mid 132.901737 -276.460128)
		(end 132.623306 -276.390354)
		(width 0.088646)
		(layer "In6.Cu")
		(net "M_H_CPU1_SA_DQ<4>")
	)
	(arc
		(start 130.35915 -276.384258)
		(mid 130.084951 -276.460093)
		(end 129.808478 -276.392894)
		(width 0.088646)
		(layer "In6.Cu")
		(net "M_H_CPU1_SA_DQ<4>")
	)
	(arc
		(start 132.238496 -276.384258)
		(mid 131.961937 -276.460001)
		(end 131.68376 -276.390354)
		(width 0.088646)
		(layer "In6.Cu")
		(net "M_H_CPU1_SA_DQ<4>")
	)
	(arc
		(start 128.47955 -277.032974)
		(mid 128.205351 -276.957139)
		(end 127.928878 -277.024338)
		(width 0.088646)
		(layer "In6.Cu")
		(net "M_H_CPU1_SA_DQ<4>")
	)
	(arc
		(start 133.552946 -276.384258)
		(mid 133.365748 -276.334115)
		(end 133.17855 -276.384258)
		(width 0.088646)
		(layer "In6.Cu")
		(net "M_H_CPU1_SA_DQ<4>")
	)
	(arc
		(start 136.372092 -276.384258)
		(mid 136.184894 -276.334115)
		(end 135.997696 -276.384258)
		(width 0.088646)
		(layer "In6.Cu")
		(net "M_H_CPU1_SA_DQ<4>")
	)
	(arc
		(start 135.05815 -276.384258)
		(mid 134.783951 -276.460093)
		(end 134.507478 -276.392894)
		(width 0.088646)
		(layer "In6.Cu")
		(net "M_H_CPU1_SA_DQ<4>")
	)
	(arc
		(start 127.35941 -276.928834)
		(mid 127.32007 -276.908347)
		(end 127.279146 -276.891242)
		(width 0.088646)
		(layer "In6.Cu")
		(net "M_H_CPU1_SA_DQ<4>")
	)
	(arc
		(start 138.909044 -277.522432)
		(mid 138.861365 -277.339532)
		(end 138.730482 -277.203154)
		(width 0.088646)
		(layer "In6.Cu")
		(net "M_H_CPU1_SA_DQ<4>")
	)
	(arc
		(start 131.29895 -276.384258)
		(mid 131.024751 -276.460093)
		(end 130.748278 -276.392894)
		(width 0.088646)
		(layer "In6.Cu")
		(net "M_H_CPU1_SA_DQ<4>")
	)
	(arc
		(start 138.721592 -277.198074)
		(mid 138.517257 -276.995469)
		(end 138.439144 -276.718522)
		(width 0.088646)
		(layer "In6.Cu")
		(net "M_H_CPU1_SA_DQ<4>")
	)
	(arc
		(start 139.26947 -278.071326)
		(mid 139.23242 -278.03918)
		(end 139.191492 -278.012144)
		(width 0.088646)
		(layer "In6.Cu")
		(net "M_H_CPU1_SA_DQ<4>")
	)
	(arc
		(start 138.251692 -276.384258)
		(mid 138.064494 -276.334115)
		(end 137.877296 -276.384258)
		(width 0.088646)
		(layer "In6.Cu")
		(net "M_H_CPU1_SA_DQ<4>")
	)
	(arc
		(start 132.612892 -276.384258)
		(mid 132.425694 -276.334115)
		(end 132.238496 -276.384258)
		(width 0.088646)
		(layer "In6.Cu")
		(net "M_H_CPU1_SA_DQ<4>")
	)
	(arc
		(start 135.432546 -276.384258)
		(mid 135.245348 -276.334115)
		(end 135.05815 -276.384258)
		(width 0.088646)
		(layer "In6.Cu")
		(net "M_H_CPU1_SA_DQ<4>")
	)
	(arc
		(start 136.937496 -276.384258)
		(mid 136.654794 -276.460034)
		(end 136.372092 -276.384258)
		(width 0.088646)
		(layer "In6.Cu")
		(net "M_H_CPU1_SA_DQ<4>")
	)
	(arc
		(start 131.673346 -276.384258)
		(mid 131.486148 -276.334115)
		(end 131.29895 -276.384258)
		(width 0.088646)
		(layer "In6.Cu")
		(net "M_H_CPU1_SA_DQ<4>")
	)
	(arc
		(start 138.439144 -276.708616)
		(mid 138.391465 -276.525716)
		(end 138.260582 -276.389338)
		(width 0.088646)
		(layer "In6.Cu")
		(net "M_H_CPU1_SA_DQ<4>")
	)
	(segment
		(start 212.618066 -314.19165)
		(end 212.630258 -314.203842)
		(width 0.1016)
		(layer "F.Cu")
		(net "M_H_CPU1_SA_DQ<3>")
	)
	(segment
		(start 210.603084 -314.198762)
		(end 210.610196 -314.19165)
		(width 0.1016)
		(layer "F.Cu")
		(net "M_H_CPU1_SA_DQ<3>")
	)
	(segment
		(start 213.515448 -313.99988)
		(end 213.515448 -313.748928)
		(width 0.20066)
		(layer "F.Cu")
		(net "M_H_CPU1_SA_DQ<3>")
	)
	(segment
		(start 207.071214 -313.766708)
		(end 208.176114 -313.766708)
		(width 0.20066)
		(layer "F.Cu")
		(net "M_H_CPU1_SA_DQ<3>")
	)
	(segment
		(start 214.133684 -313.51474)
		(end 214.385652 -313.766708)
		(width 0.20066)
		(layer "F.Cu")
		(net "M_H_CPU1_SA_DQ<3>")
	)
	(segment
		(start 210.598258 -314.198762)
		(end 210.603084 -314.198762)
		(width 0.101854)
		(layer "F.Cu")
		(net "M_H_CPU1_SA_DQ<3>")
	)
	(segment
		(start 210.306412 -314.198762)
		(end 210.598258 -314.198762)
		(width 0.20066)
		(layer "F.Cu")
		(net "M_H_CPU1_SA_DQ<3>")
	)
	(segment
		(start 208.176114 -313.766708)
		(end 209.874358 -313.766708)
		(width 0.20066)
		(layer "F.Cu")
		(net "M_H_CPU1_SA_DQ<3>")
	)
	(segment
		(start 212.630258 -314.203842)
		(end 213.311486 -314.203842)
		(width 0.20066)
		(layer "F.Cu")
		(net "M_H_CPU1_SA_DQ<3>")
	)
	(segment
		(start 213.311486 -314.203842)
		(end 213.515448 -313.99988)
		(width 0.20066)
		(layer "F.Cu")
		(net "M_H_CPU1_SA_DQ<3>")
	)
	(segment
		(start 210.610196 -314.19165)
		(end 212.618066 -314.19165)
		(width 0.1016)
		(layer "F.Cu")
		(net "M_H_CPU1_SA_DQ<3>")
	)
	(segment
		(start 128.666494 -277.800562)
		(end 128.666494 -278.336502)
		(width 0.20066)
		(layer "F.Cu")
		(net "M_H_CPU1_SA_DQ<3>")
	)
	(segment
		(start 213.749636 -313.51474)
		(end 214.133684 -313.51474)
		(width 0.20066)
		(layer "F.Cu")
		(net "M_H_CPU1_SA_DQ<3>")
	)
	(segment
		(start 213.515448 -313.748928)
		(end 213.749636 -313.51474)
		(width 0.20066)
		(layer "F.Cu")
		(net "M_H_CPU1_SA_DQ<3>")
	)
	(segment
		(start 214.385652 -313.766708)
		(end 215.719914 -313.766708)
		(width 0.20066)
		(layer "F.Cu")
		(net "M_H_CPU1_SA_DQ<3>")
	)
	(segment
		(start 209.874358 -313.766708)
		(end 210.306412 -314.198762)
		(width 0.20066)
		(layer "F.Cu")
		(net "M_H_CPU1_SA_DQ<3>")
	)
	(segment
		(start 161.440114 -309.26532)
		(end 160.62833 -308.453536)
		(width 0.18288)
		(layer "In6.Cu")
		(net "M_H_CPU1_SA_DQ<3>")
	)
	(segment
		(start 201.288396 -315.042296)
		(end 200.398126 -314.152026)
		(width 0.18288)
		(layer "In6.Cu")
		(net "M_H_CPU1_SA_DQ<3>")
	)
	(segment
		(start 166.77132 -310.182768)
		(end 166.44366 -310.182768)
		(width 0.18288)
		(layer "In6.Cu")
		(net "M_H_CPU1_SA_DQ<3>")
	)
	(segment
		(start 205.937104 -313.766708)
		(end 205.79334 -313.910472)
		(width 0.18288)
		(layer "In6.Cu")
		(net "M_H_CPU1_SA_DQ<3>")
	)
	(segment
		(start 158.617412 -308.245256)
		(end 158.409132 -308.453536)
		(width 0.18288)
		(layer "In6.Cu")
		(net "M_H_CPU1_SA_DQ<3>")
	)
	(segment
		(start 131.76885 -278.82596)
		(end 131.758436 -278.832056)
		(width 0.088646)
		(layer "In6.Cu")
		(net "M_H_CPU1_SA_DQ<3>")
	)
	(segment
		(start 137.029444 -279.160224)
		(end 137.029444 -279.150318)
		(width 0.088646)
		(layer "In6.Cu")
		(net "M_H_CPU1_SA_DQ<3>")
	)
	(segment
		(start 183.811926 -314.101226)
		(end 183.052974 -313.342274)
		(width 0.18288)
		(layer "In6.Cu")
		(net "M_H_CPU1_SA_DQ<3>")
	)
	(segment
		(start 206.165196 -314.799472)
		(end 205.933294 -315.031374)
		(width 0.18288)
		(layer "In6.Cu")
		(net "M_H_CPU1_SA_DQ<3>")
	)
	(segment
		(start 139.920218 -281.975814)
		(end 139.920218 -281.970226)
		(width 0.088646)
		(layer "In6.Cu")
		(net "M_H_CPU1_SA_DQ<3>")
	)
	(segment
		(start 137.499344 -279.982676)
		(end 137.499344 -279.964134)
		(width 0.088646)
		(layer "In6.Cu")
		(net "M_H_CPU1_SA_DQ<3>")
	)
	(segment
		(start 186.36488 -315.89218)
		(end 184.573926 -314.101226)
		(width 0.18288)
		(layer "In6.Cu")
		(net "M_H_CPU1_SA_DQ<3>")
	)
	(segment
		(start 198.50608 -314.799472)
		(end 194.993514 -314.799472)
		(width 0.18288)
		(layer "In6.Cu")
		(net "M_H_CPU1_SA_DQ<3>")
	)
	(segment
		(start 165.460426 -310.773826)
		(end 164.419026 -309.732426)
		(width 0.18288)
		(layer "In6.Cu")
		(net "M_H_CPU1_SA_DQ<3>")
	)
	(segment
		(start 179.542948 -312.28284)
		(end 178.052222 -310.792114)
		(width 0.18288)
		(layer "In6.Cu")
		(net "M_H_CPU1_SA_DQ<3>")
	)
	(segment
		(start 171.191682 -311.825132)
		(end 171.008802 -311.642252)
		(width 0.18288)
		(layer "In6.Cu")
		(net "M_H_CPU1_SA_DQ<3>")
	)
	(segment
		(start 171.374562 -312.214006)
		(end 171.191682 -312.031126)
		(width 0.18288)
		(layer "In6.Cu")
		(net "M_H_CPU1_SA_DQ<3>")
	)
	(segment
		(start 139.427966 -280.780744)
		(end 139.227814 -280.580592)
		(width 0.088646)
		(layer "In6.Cu")
		(net "M_H_CPU1_SA_DQ<3>")
	)
	(segment
		(start 183.052974 -313.342274)
		(end 181.839108 -313.342274)
		(width 0.18288)
		(layer "In6.Cu")
		(net "M_H_CPU1_SA_DQ<3>")
	)
	(segment
		(start 154.694382 -301.514256)
		(end 146.858482 -293.678356)
		(width 0.18288)
		(layer "In6.Cu")
		(net "M_H_CPU1_SA_DQ<3>")
	)
	(segment
		(start 139.227814 -280.580592)
		(end 139.194286 -280.580592)
		(width 0.088646)
		(layer "In6.Cu")
		(net "M_H_CPU1_SA_DQ<3>")
	)
	(segment
		(start 146.858482 -293.678356)
		(end 146.858482 -284.166818)
		(width 0.18288)
		(layer "In6.Cu")
		(net "M_H_CPU1_SA_DQ<3>")
	)
	(segment
		(start 139.920218 -281.970226)
		(end 139.427966 -280.780744)
		(width 0.088646)
		(layer "In6.Cu")
		(net "M_H_CPU1_SA_DQ<3>")
	)
	(segment
		(start 206.165196 -314.5409)
		(end 206.165196 -314.799472)
		(width 0.18288)
		(layer "In6.Cu")
		(net "M_H_CPU1_SA_DQ<3>")
	)
	(segment
		(start 158.409132 -308.453536)
		(end 157.238954 -308.453536)
		(width 0.18288)
		(layer "In6.Cu")
		(net "M_H_CPU1_SA_DQ<3>")
	)
	(segment
		(start 163.733226 -309.732426)
		(end 163.26612 -309.26532)
		(width 0.18288)
		(layer "In6.Cu")
		(net "M_H_CPU1_SA_DQ<3>")
	)
	(segment
		(start 166.9542 -310.365648)
		(end 166.77132 -310.182768)
		(width 0.18288)
		(layer "In6.Cu")
		(net "M_H_CPU1_SA_DQ<3>")
	)
	(segment
		(start 205.674722 -315.031374)
		(end 205.302866 -314.659518)
		(width 0.18288)
		(layer "In6.Cu")
		(net "M_H_CPU1_SA_DQ<3>")
	)
	(segment
		(start 144.824704 -282.13304)
		(end 140.339064 -282.13304)
		(width 0.18288)
		(layer "In6.Cu")
		(net "M_H_CPU1_SA_DQ<3>")
	)
	(segment
		(start 190.830708 -315.042296)
		(end 190.708026 -314.919614)
		(width 0.18288)
		(layer "In6.Cu")
		(net "M_H_CPU1_SA_DQ<3>")
	)
	(segment
		(start 205.044294 -314.659518)
		(end 204.661516 -315.042296)
		(width 0.18288)
		(layer "In6.Cu")
		(net "M_H_CPU1_SA_DQ<3>")
	)
	(segment
		(start 188.592206 -315.89218)
		(end 186.36488 -315.89218)
		(width 0.18288)
		(layer "In6.Cu")
		(net "M_H_CPU1_SA_DQ<3>")
	)
	(segment
		(start 159.285432 -308.453536)
		(end 159.077152 -308.245256)
		(width 0.18288)
		(layer "In6.Cu")
		(net "M_H_CPU1_SA_DQ<3>")
	)
	(segment
		(start 168.894252 -311.642252)
		(end 168.025826 -310.773826)
		(width 0.18288)
		(layer "In6.Cu")
		(net "M_H_CPU1_SA_DQ<3>")
	)
	(segment
		(start 159.077152 -308.245256)
		(end 158.617412 -308.245256)
		(width 0.18288)
		(layer "In6.Cu")
		(net "M_H_CPU1_SA_DQ<3>")
	)
	(segment
		(start 171.885102 -312.031126)
		(end 171.702222 -312.214006)
		(width 0.18288)
		(layer "In6.Cu")
		(net "M_H_CPU1_SA_DQ<3>")
	)
	(segment
		(start 205.302866 -314.659518)
		(end 205.044294 -314.659518)
		(width 0.18288)
		(layer "In6.Cu")
		(net "M_H_CPU1_SA_DQ<3>")
	)
	(segment
		(start 129.966974 -278.781002)
		(end 129.88925 -278.82596)
		(width 0.088646)
		(layer "In6.Cu")
		(net "M_H_CPU1_SA_DQ<3>")
	)
	(segment
		(start 164.419026 -309.732426)
		(end 163.733226 -309.732426)
		(width 0.18288)
		(layer "In6.Cu")
		(net "M_H_CPU1_SA_DQ<3>")
	)
	(segment
		(start 167.13708 -310.773826)
		(end 166.9542 -310.590946)
		(width 0.18288)
		(layer "In6.Cu")
		(net "M_H_CPU1_SA_DQ<3>")
	)
	(segment
		(start 175.005492 -310.792114)
		(end 174.155354 -311.642252)
		(width 0.18288)
		(layer "In6.Cu")
		(net "M_H_CPU1_SA_DQ<3>")
	)
	(segment
		(start 171.885102 -311.825132)
		(end 171.885102 -312.031126)
		(width 0.18288)
		(layer "In6.Cu")
		(net "M_H_CPU1_SA_DQ<3>")
	)
	(segment
		(start 205.933294 -315.031374)
		(end 205.674722 -315.031374)
		(width 0.18288)
		(layer "In6.Cu")
		(net "M_H_CPU1_SA_DQ<3>")
	)
	(segment
		(start 166.44366 -310.182768)
		(end 166.26078 -310.365648)
		(width 0.18288)
		(layer "In6.Cu")
		(net "M_H_CPU1_SA_DQ<3>")
	)
	(segment
		(start 130.189986 -278.783034)
		(end 130.0988 -278.747728)
		(width 0.088646)
		(layer "In6.Cu")
		(net "M_H_CPU1_SA_DQ<3>")
	)
	(segment
		(start 180.779674 -312.28284)
		(end 179.542948 -312.28284)
		(width 0.18288)
		(layer "In6.Cu")
		(net "M_H_CPU1_SA_DQ<3>")
	)
	(segment
		(start 163.26612 -309.26532)
		(end 161.440114 -309.26532)
		(width 0.18288)
		(layer "In6.Cu")
		(net "M_H_CPU1_SA_DQ<3>")
	)
	(segment
		(start 138.34745 -280.453846)
		(end 138.337036 -280.459942)
		(width 0.088646)
		(layer "In6.Cu")
		(net "M_H_CPU1_SA_DQ<3>")
	)
	(segment
		(start 194.993514 -314.799472)
		(end 194.75069 -315.042296)
		(width 0.18288)
		(layer "In6.Cu")
		(net "M_H_CPU1_SA_DQ<3>")
	)
	(segment
		(start 190.708026 -314.919614)
		(end 189.564772 -314.919614)
		(width 0.18288)
		(layer "In6.Cu")
		(net "M_H_CPU1_SA_DQ<3>")
	)
	(segment
		(start 166.0779 -310.773826)
		(end 165.460426 -310.773826)
		(width 0.18288)
		(layer "In6.Cu")
		(net "M_H_CPU1_SA_DQ<3>")
	)
	(segment
		(start 157.238954 -308.453536)
		(end 154.694382 -305.908964)
		(width 0.18288)
		(layer "In6.Cu")
		(net "M_H_CPU1_SA_DQ<3>")
	)
	(segment
		(start 189.564772 -314.919614)
		(end 188.592206 -315.89218)
		(width 0.18288)
		(layer "In6.Cu")
		(net "M_H_CPU1_SA_DQ<3>")
	)
	(segment
		(start 184.573926 -314.101226)
		(end 183.811926 -314.101226)
		(width 0.18288)
		(layer "In6.Cu")
		(net "M_H_CPU1_SA_DQ<3>")
	)
	(segment
		(start 181.839108 -313.342274)
		(end 180.779674 -312.28284)
		(width 0.18288)
		(layer "In6.Cu")
		(net "M_H_CPU1_SA_DQ<3>")
	)
	(segment
		(start 205.79334 -313.910472)
		(end 205.79334 -314.169044)
		(width 0.18288)
		(layer "In6.Cu")
		(net "M_H_CPU1_SA_DQ<3>")
	)
	(segment
		(start 174.155354 -311.642252)
		(end 172.067982 -311.642252)
		(width 0.18288)
		(layer "In6.Cu")
		(net "M_H_CPU1_SA_DQ<3>")
	)
	(segment
		(start 160.62833 -308.453536)
		(end 159.285432 -308.453536)
		(width 0.18288)
		(layer "In6.Cu")
		(net "M_H_CPU1_SA_DQ<3>")
	)
	(segment
		(start 154.694382 -305.908964)
		(end 154.694382 -301.514256)
		(width 0.18288)
		(layer "In6.Cu")
		(net "M_H_CPU1_SA_DQ<3>")
	)
	(segment
		(start 171.191682 -312.031126)
		(end 171.191682 -311.825132)
		(width 0.18288)
		(layer "In6.Cu")
		(net "M_H_CPU1_SA_DQ<3>")
	)
	(segment
		(start 137.320782 -279.644856)
		(end 137.311892 -279.639776)
		(width 0.088646)
		(layer "In6.Cu")
		(net "M_H_CPU1_SA_DQ<3>")
	)
	(segment
		(start 199.153526 -314.152026)
		(end 198.50608 -314.799472)
		(width 0.18288)
		(layer "In6.Cu")
		(net "M_H_CPU1_SA_DQ<3>")
	)
	(segment
		(start 204.661516 -315.042296)
		(end 201.288396 -315.042296)
		(width 0.18288)
		(layer "In6.Cu")
		(net "M_H_CPU1_SA_DQ<3>")
	)
	(segment
		(start 146.858482 -284.166818)
		(end 144.824704 -282.13304)
		(width 0.18288)
		(layer "In6.Cu")
		(net "M_H_CPU1_SA_DQ<3>")
	)
	(segment
		(start 140.077444 -282.13304)
		(end 139.920218 -281.975814)
		(width 0.088646)
		(layer "In6.Cu")
		(net "M_H_CPU1_SA_DQ<3>")
	)
	(segment
		(start 166.26078 -310.590946)
		(end 166.0779 -310.773826)
		(width 0.18288)
		(layer "In6.Cu")
		(net "M_H_CPU1_SA_DQ<3>")
	)
	(segment
		(start 136.850882 -278.83104)
		(end 136.841992 -278.82596)
		(width 0.088646)
		(layer "In6.Cu")
		(net "M_H_CPU1_SA_DQ<3>")
	)
	(segment
		(start 172.067982 -311.642252)
		(end 171.885102 -311.825132)
		(width 0.18288)
		(layer "In6.Cu")
		(net "M_H_CPU1_SA_DQ<3>")
	)
	(segment
		(start 200.398126 -314.152026)
		(end 199.153526 -314.152026)
		(width 0.18288)
		(layer "In6.Cu")
		(net "M_H_CPU1_SA_DQ<3>")
	)
	(segment
		(start 168.025826 -310.773826)
		(end 167.13708 -310.773826)
		(width 0.18288)
		(layer "In6.Cu")
		(net "M_H_CPU1_SA_DQ<3>")
	)
	(segment
		(start 194.75069 -315.042296)
		(end 190.830708 -315.042296)
		(width 0.18288)
		(layer "In6.Cu")
		(net "M_H_CPU1_SA_DQ<3>")
	)
	(segment
		(start 133.648196 -278.82596)
		(end 133.637782 -278.832056)
		(width 0.088646)
		(layer "In6.Cu")
		(net "M_H_CPU1_SA_DQ<3>")
	)
	(segment
		(start 166.9542 -310.590946)
		(end 166.9542 -310.365648)
		(width 0.18288)
		(layer "In6.Cu")
		(net "M_H_CPU1_SA_DQ<3>")
	)
	(segment
		(start 130.0988 -278.747728)
		(end 129.997454 -278.769826)
		(width 0.088646)
		(layer "In6.Cu")
		(net "M_H_CPU1_SA_DQ<3>")
	)
	(segment
		(start 166.26078 -310.365648)
		(end 166.26078 -310.590946)
		(width 0.18288)
		(layer "In6.Cu")
		(net "M_H_CPU1_SA_DQ<3>")
	)
	(segment
		(start 207.071214 -313.766708)
		(end 205.937104 -313.766708)
		(width 0.18288)
		(layer "In6.Cu")
		(net "M_H_CPU1_SA_DQ<3>")
	)
	(segment
		(start 171.702222 -312.214006)
		(end 171.374562 -312.214006)
		(width 0.18288)
		(layer "In6.Cu")
		(net "M_H_CPU1_SA_DQ<3>")
	)
	(segment
		(start 171.008802 -311.642252)
		(end 168.894252 -311.642252)
		(width 0.18288)
		(layer "In6.Cu")
		(net "M_H_CPU1_SA_DQ<3>")
	)
	(segment
		(start 129.338578 -278.834596)
		(end 129.23139 -278.772112)
		(width 0.088646)
		(layer "In6.Cu")
		(net "M_H_CPU1_SA_DQ<3>")
	)
	(segment
		(start 178.052222 -310.792114)
		(end 175.005492 -310.792114)
		(width 0.18288)
		(layer "In6.Cu")
		(net "M_H_CPU1_SA_DQ<3>")
	)
	(segment
		(start 130.27406 -278.832056)
		(end 130.189986 -278.783034)
		(width 0.088646)
		(layer "In6.Cu")
		(net "M_H_CPU1_SA_DQ<3>")
	)
	(segment
		(start 205.79334 -314.169044)
		(end 206.165196 -314.5409)
		(width 0.18288)
		(layer "In6.Cu")
		(net "M_H_CPU1_SA_DQ<3>")
	)
	(segment
		(start 140.339064 -282.13304)
		(end 140.077444 -282.13304)
		(width 0.088646)
		(layer "In6.Cu")
		(net "M_H_CPU1_SA_DQ<3>")
	)
	(arc
		(start 135.527796 -278.82596)
		(mid 135.245094 -278.901736)
		(end 134.962392 -278.82596)
		(width 0.088646)
		(layer "In6.Cu")
		(net "M_H_CPU1_SA_DQ<3>")
	)
	(arc
		(start 129.997454 -278.769826)
		(mid 129.981715 -278.774056)
		(end 129.966974 -278.781002)
		(width 0.088646)
		(layer "In6.Cu")
		(net "M_H_CPU1_SA_DQ<3>")
	)
	(arc
		(start 137.781792 -280.453846)
		(mid 137.579506 -280.254865)
		(end 137.499344 -279.982676)
		(width 0.088646)
		(layer "In6.Cu")
		(net "M_H_CPU1_SA_DQ<3>")
	)
	(arc
		(start 137.029444 -279.150318)
		(mid 136.981765 -278.967418)
		(end 136.850882 -278.83104)
		(width 0.088646)
		(layer "In6.Cu")
		(net "M_H_CPU1_SA_DQ<3>")
	)
	(arc
		(start 136.467596 -278.82596)
		(mid 136.184894 -278.901736)
		(end 135.902192 -278.82596)
		(width 0.088646)
		(layer "In6.Cu")
		(net "M_H_CPU1_SA_DQ<3>")
	)
	(arc
		(start 133.083046 -278.82596)
		(mid 132.895848 -278.775817)
		(end 132.70865 -278.82596)
		(width 0.088646)
		(layer "In6.Cu")
		(net "M_H_CPU1_SA_DQ<3>")
	)
	(arc
		(start 138.337036 -280.459942)
		(mid 138.058604 -280.529756)
		(end 137.781792 -280.453846)
		(width 0.088646)
		(layer "In6.Cu")
		(net "M_H_CPU1_SA_DQ<3>")
	)
	(arc
		(start 130.828796 -278.82596)
		(mid 130.552237 -278.901703)
		(end 130.27406 -278.832056)
		(width 0.088646)
		(layer "In6.Cu")
		(net "M_H_CPU1_SA_DQ<3>")
	)
	(arc
		(start 132.70865 -278.82596)
		(mid 132.425948 -278.901736)
		(end 132.143246 -278.82596)
		(width 0.088646)
		(layer "In6.Cu")
		(net "M_H_CPU1_SA_DQ<3>")
	)
	(arc
		(start 134.962392 -278.82596)
		(mid 134.775194 -278.775817)
		(end 134.587996 -278.82596)
		(width 0.088646)
		(layer "In6.Cu")
		(net "M_H_CPU1_SA_DQ<3>")
	)
	(arc
		(start 139.194286 -280.580592)
		(mid 138.949709 -280.548363)
		(end 138.721846 -280.453846)
		(width 0.088646)
		(layer "In6.Cu")
		(net "M_H_CPU1_SA_DQ<3>")
	)
	(arc
		(start 134.587996 -278.82596)
		(mid 134.305294 -278.901736)
		(end 134.022592 -278.82596)
		(width 0.088646)
		(layer "In6.Cu")
		(net "M_H_CPU1_SA_DQ<3>")
	)
	(arc
		(start 134.022592 -278.82596)
		(mid 133.835394 -278.775817)
		(end 133.648196 -278.82596)
		(width 0.088646)
		(layer "In6.Cu")
		(net "M_H_CPU1_SA_DQ<3>")
	)
	(arc
		(start 137.311892 -279.639776)
		(mid 137.107557 -279.437171)
		(end 137.029444 -279.160224)
		(width 0.088646)
		(layer "In6.Cu")
		(net "M_H_CPU1_SA_DQ<3>")
	)
	(arc
		(start 129.23139 -278.772112)
		(mid 128.934793 -278.572656)
		(end 128.666494 -278.336502)
		(width 0.088646)
		(layer "In6.Cu")
		(net "M_H_CPU1_SA_DQ<3>")
	)
	(arc
		(start 132.143246 -278.82596)
		(mid 131.956048 -278.775817)
		(end 131.76885 -278.82596)
		(width 0.088646)
		(layer "In6.Cu")
		(net "M_H_CPU1_SA_DQ<3>")
	)
	(arc
		(start 137.499344 -279.964134)
		(mid 137.451665 -279.781234)
		(end 137.320782 -279.644856)
		(width 0.088646)
		(layer "In6.Cu")
		(net "M_H_CPU1_SA_DQ<3>")
	)
	(arc
		(start 131.758436 -278.832056)
		(mid 131.480004 -278.901902)
		(end 131.203192 -278.82596)
		(width 0.088646)
		(layer "In6.Cu")
		(net "M_H_CPU1_SA_DQ<3>")
	)
	(arc
		(start 136.841992 -278.82596)
		(mid 136.654794 -278.775817)
		(end 136.467596 -278.82596)
		(width 0.088646)
		(layer "In6.Cu")
		(net "M_H_CPU1_SA_DQ<3>")
	)
	(arc
		(start 131.203192 -278.82596)
		(mid 131.015994 -278.775817)
		(end 130.828796 -278.82596)
		(width 0.088646)
		(layer "In6.Cu")
		(net "M_H_CPU1_SA_DQ<3>")
	)
	(arc
		(start 133.637782 -278.832056)
		(mid 133.359604 -278.901779)
		(end 133.083046 -278.82596)
		(width 0.088646)
		(layer "In6.Cu")
		(net "M_H_CPU1_SA_DQ<3>")
	)
	(arc
		(start 135.902192 -278.82596)
		(mid 135.714994 -278.775817)
		(end 135.527796 -278.82596)
		(width 0.088646)
		(layer "In6.Cu")
		(net "M_H_CPU1_SA_DQ<3>")
	)
	(arc
		(start 138.721846 -280.453846)
		(mid 138.534648 -280.403703)
		(end 138.34745 -280.453846)
		(width 0.088646)
		(layer "In6.Cu")
		(net "M_H_CPU1_SA_DQ<3>")
	)
	(arc
		(start 129.88925 -278.82596)
		(mid 129.615051 -278.901795)
		(end 129.338578 -278.834596)
		(width 0.088646)
		(layer "In6.Cu")
		(net "M_H_CPU1_SA_DQ<3>")
	)
	(segment
		(start 124.907294 -263.68629)
		(end 124.907548 -263.686544)
		(width 0.20066)
		(layer "F.Cu")
		(net "M_H_CPU1_SA_DQ<31>")
	)
	(segment
		(start 210.598258 -280.19883)
		(end 210.603084 -280.19883)
		(width 0.101854)
		(layer "F.Cu")
		(net "M_H_CPU1_SA_DQ<31>")
	)
	(segment
		(start 214.133684 -279.514808)
		(end 214.385652 -279.766776)
		(width 0.20066)
		(layer "F.Cu")
		(net "M_H_CPU1_SA_DQ<31>")
	)
	(segment
		(start 207.071214 -279.766776)
		(end 208.176114 -279.766776)
		(width 0.20066)
		(layer "F.Cu")
		(net "M_H_CPU1_SA_DQ<31>")
	)
	(segment
		(start 213.311486 -280.20391)
		(end 213.515448 -279.999948)
		(width 0.20066)
		(layer "F.Cu")
		(net "M_H_CPU1_SA_DQ<31>")
	)
	(segment
		(start 210.603084 -280.19883)
		(end 210.610196 -280.191718)
		(width 0.1016)
		(layer "F.Cu")
		(net "M_H_CPU1_SA_DQ<31>")
	)
	(segment
		(start 213.515448 -279.748996)
		(end 213.749636 -279.514808)
		(width 0.20066)
		(layer "F.Cu")
		(net "M_H_CPU1_SA_DQ<31>")
	)
	(segment
		(start 210.306412 -280.19883)
		(end 210.598258 -280.19883)
		(width 0.20066)
		(layer "F.Cu")
		(net "M_H_CPU1_SA_DQ<31>")
	)
	(segment
		(start 212.618066 -280.191718)
		(end 212.630258 -280.20391)
		(width 0.1016)
		(layer "F.Cu")
		(net "M_H_CPU1_SA_DQ<31>")
	)
	(segment
		(start 213.515448 -279.999948)
		(end 213.515448 -279.748996)
		(width 0.20066)
		(layer "F.Cu")
		(net "M_H_CPU1_SA_DQ<31>")
	)
	(segment
		(start 213.749636 -279.514808)
		(end 214.133684 -279.514808)
		(width 0.20066)
		(layer "F.Cu")
		(net "M_H_CPU1_SA_DQ<31>")
	)
	(segment
		(start 214.385652 -279.766776)
		(end 215.719914 -279.766776)
		(width 0.20066)
		(layer "F.Cu")
		(net "M_H_CPU1_SA_DQ<31>")
	)
	(segment
		(start 124.907294 -263.150604)
		(end 124.907294 -263.68629)
		(width 0.20066)
		(layer "F.Cu")
		(net "M_H_CPU1_SA_DQ<31>")
	)
	(segment
		(start 210.610196 -280.191718)
		(end 212.618066 -280.191718)
		(width 0.1016)
		(layer "F.Cu")
		(net "M_H_CPU1_SA_DQ<31>")
	)
	(segment
		(start 209.874358 -279.766776)
		(end 210.306412 -280.19883)
		(width 0.20066)
		(layer "F.Cu")
		(net "M_H_CPU1_SA_DQ<31>")
	)
	(segment
		(start 208.176114 -279.766776)
		(end 209.874358 -279.766776)
		(width 0.20066)
		(layer "F.Cu")
		(net "M_H_CPU1_SA_DQ<31>")
	)
	(segment
		(start 212.630258 -280.20391)
		(end 213.311486 -280.20391)
		(width 0.20066)
		(layer "F.Cu")
		(net "M_H_CPU1_SA_DQ<31>")
	)
	(segment
		(start 128.009396 -263.196832)
		(end 127.994664 -263.188196)
		(width 0.088646)
		(layer "In11.Cu")
		(net "M_H_CPU1_SA_DQ<31>")
	)
	(segment
		(start 140.087604 -266.531852)
		(end 139.923012 -266.531852)
		(width 0.088646)
		(layer "In11.Cu")
		(net "M_H_CPU1_SA_DQ<31>")
	)
	(segment
		(start 174.720504 -282.742894)
		(end 172.107098 -282.742894)
		(width 0.18288)
		(layer "In11.Cu")
		(net "M_H_CPU1_SA_DQ<31>")
	)
	(segment
		(start 175.571912 -281.891486)
		(end 174.720504 -282.742894)
		(width 0.18288)
		(layer "In11.Cu")
		(net "M_H_CPU1_SA_DQ<31>")
	)
	(segment
		(start 139.612878 -266.221718)
		(end 139.427458 -266.221718)
		(width 0.088646)
		(layer "In11.Cu")
		(net "M_H_CPU1_SA_DQ<31>")
	)
	(segment
		(start 196.72046 -281.19578)
		(end 196.40296 -281.19578)
		(width 0.18288)
		(layer "In11.Cu")
		(net "M_H_CPU1_SA_DQ<31>")
	)
	(segment
		(start 124.59462 -263.686544)
		(end 124.907548 -263.686544)
		(width 0.088646)
		(layer "In11.Cu")
		(net "M_H_CPU1_SA_DQ<31>")
	)
	(segment
		(start 133.648196 -263.196832)
		(end 133.633464 -263.188196)
		(width 0.088646)
		(layer "In11.Cu")
		(net "M_H_CPU1_SA_DQ<31>")
	)
	(segment
		(start 170.15587 -282.225242)
		(end 168.601136 -280.670508)
		(width 0.18288)
		(layer "In11.Cu")
		(net "M_H_CPU1_SA_DQ<31>")
	)
	(segment
		(start 160.383728 -278.696928)
		(end 157.434026 -278.696928)
		(width 0.18288)
		(layer "In11.Cu")
		(net "M_H_CPU1_SA_DQ<31>")
	)
	(segment
		(start 135.997696 -264.010902)
		(end 135.988806 -264.005822)
		(width 0.088646)
		(layer "In11.Cu")
		(net "M_H_CPU1_SA_DQ<31>")
	)
	(segment
		(start 181.735222 -281.427936)
		(end 181.542182 -281.234896)
		(width 0.18288)
		(layer "In11.Cu")
		(net "M_H_CPU1_SA_DQ<31>")
	)
	(segment
		(start 137.877296 -265.638788)
		(end 137.868406 -265.633454)
		(width 0.088646)
		(layer "In11.Cu")
		(net "M_H_CPU1_SA_DQ<31>")
	)
	(segment
		(start 203.931774 -280.19121)
		(end 202.330812 -280.19121)
		(width 0.18288)
		(layer "In11.Cu")
		(net "M_H_CPU1_SA_DQ<31>")
	)
	(segment
		(start 196.9135 -281.726386)
		(end 196.9135 -281.38882)
		(width 0.18288)
		(layer "In11.Cu")
		(net "M_H_CPU1_SA_DQ<31>")
	)
	(segment
		(start 178.9938 -281.71394)
		(end 178.816254 -281.891486)
		(width 0.18288)
		(layer "In11.Cu")
		(net "M_H_CPU1_SA_DQ<31>")
	)
	(segment
		(start 196.01688 -281.919426)
		(end 194.822826 -281.919426)
		(width 0.18288)
		(layer "In11.Cu")
		(net "M_H_CPU1_SA_DQ<31>")
	)
	(segment
		(start 179.52974 -281.71394)
		(end 178.9938 -281.71394)
		(width 0.18288)
		(layer "In11.Cu")
		(net "M_H_CPU1_SA_DQ<31>")
	)
	(segment
		(start 171.582334 -282.961334)
		(end 170.846242 -282.225242)
		(width 0.18288)
		(layer "In11.Cu")
		(net "M_H_CPU1_SA_DQ<31>")
	)
	(segment
		(start 171.888658 -282.961334)
		(end 171.582334 -282.961334)
		(width 0.18288)
		(layer "In11.Cu")
		(net "M_H_CPU1_SA_DQ<31>")
	)
	(segment
		(start 139.427458 -266.221718)
		(end 138.93419 -265.72845)
		(width 0.088646)
		(layer "In11.Cu")
		(net "M_H_CPU1_SA_DQ<31>")
	)
	(segment
		(start 183.337962 -281.97429)
		(end 181.928262 -281.97429)
		(width 0.18288)
		(layer "In11.Cu")
		(net "M_H_CPU1_SA_DQ<31>")
	)
	(segment
		(start 126.129796 -263.196832)
		(end 126.119382 -263.190736)
		(width 0.088646)
		(layer "In11.Cu")
		(net "M_H_CPU1_SA_DQ<31>")
	)
	(segment
		(start 181.031642 -281.78125)
		(end 180.838602 -281.97429)
		(width 0.18288)
		(layer "In11.Cu")
		(net "M_H_CPU1_SA_DQ<31>")
	)
	(segment
		(start 178.816254 -281.891486)
		(end 175.571912 -281.891486)
		(width 0.18288)
		(layer "In11.Cu")
		(net "M_H_CPU1_SA_DQ<31>")
	)
	(segment
		(start 130.828796 -263.196832)
		(end 130.814064 -263.188196)
		(width 0.088646)
		(layer "In11.Cu")
		(net "M_H_CPU1_SA_DQ<31>")
	)
	(segment
		(start 181.542182 -281.234896)
		(end 181.224682 -281.234896)
		(width 0.18288)
		(layer "In11.Cu")
		(net "M_H_CPU1_SA_DQ<31>")
	)
	(segment
		(start 194.670426 -281.767026)
		(end 192.947544 -281.767026)
		(width 0.18288)
		(layer "In11.Cu")
		(net "M_H_CPU1_SA_DQ<31>")
	)
	(segment
		(start 156.476192 -278.53767)
		(end 144.470374 -266.531852)
		(width 0.18288)
		(layer "In11.Cu")
		(net "M_H_CPU1_SA_DQ<31>")
	)
	(segment
		(start 144.470374 -266.531852)
		(end 140.087604 -266.531852)
		(width 0.18288)
		(layer "In11.Cu")
		(net "M_H_CPU1_SA_DQ<31>")
	)
	(segment
		(start 197.10654 -281.919426)
		(end 196.9135 -281.726386)
		(width 0.18288)
		(layer "In11.Cu")
		(net "M_H_CPU1_SA_DQ<31>")
	)
	(segment
		(start 164.762942 -281.06751)
		(end 163.760658 -281.06751)
		(width 0.18288)
		(layer "In11.Cu")
		(net "M_H_CPU1_SA_DQ<31>")
	)
	(segment
		(start 136.93775 -265.638534)
		(end 136.92886 -265.633454)
		(width 0.088646)
		(layer "In11.Cu")
		(net "M_H_CPU1_SA_DQ<31>")
	)
	(segment
		(start 161.269426 -279.582626)
		(end 160.383728 -278.696928)
		(width 0.18288)
		(layer "In11.Cu")
		(net "M_H_CPU1_SA_DQ<31>")
	)
	(segment
		(start 136.473692 -264.828274)
		(end 136.458706 -264.819638)
		(width 0.088646)
		(layer "In11.Cu")
		(net "M_H_CPU1_SA_DQ<31>")
	)
	(segment
		(start 181.928262 -281.97429)
		(end 181.735222 -281.78125)
		(width 0.18288)
		(layer "In11.Cu")
		(net "M_H_CPU1_SA_DQ<31>")
	)
	(segment
		(start 184.01919 -281.293062)
		(end 183.337962 -281.97429)
		(width 0.18288)
		(layer "In11.Cu")
		(net "M_H_CPU1_SA_DQ<31>")
	)
	(segment
		(start 189.187836 -281.89428)
		(end 188.331856 -281.0383)
		(width 0.18288)
		(layer "In11.Cu")
		(net "M_H_CPU1_SA_DQ<31>")
	)
	(segment
		(start 200.72223 -280.5811)
		(end 200.186036 -280.5811)
		(width 0.18288)
		(layer "In11.Cu")
		(net "M_H_CPU1_SA_DQ<31>")
	)
	(segment
		(start 161.269426 -279.815798)
		(end 161.269426 -279.582626)
		(width 0.18288)
		(layer "In11.Cu")
		(net "M_H_CPU1_SA_DQ<31>")
	)
	(segment
		(start 196.20992 -281.38882)
		(end 196.20992 -281.726386)
		(width 0.18288)
		(layer "In11.Cu")
		(net "M_H_CPU1_SA_DQ<31>")
	)
	(segment
		(start 199.665844 -281.101292)
		(end 198.71436 -281.101292)
		(width 0.18288)
		(layer "In11.Cu")
		(net "M_H_CPU1_SA_DQ<31>")
	)
	(segment
		(start 206.489808 -280.348182)
		(end 204.088746 -280.348182)
		(width 0.18288)
		(layer "In11.Cu")
		(net "M_H_CPU1_SA_DQ<31>")
	)
	(segment
		(start 157.434026 -278.696928)
		(end 157.274768 -278.53767)
		(width 0.18288)
		(layer "In11.Cu")
		(net "M_H_CPU1_SA_DQ<31>")
	)
	(segment
		(start 125.103636 -264.005822)
		(end 125.094746 -264.010902)
		(width 0.088646)
		(layer "In11.Cu")
		(net "M_H_CPU1_SA_DQ<31>")
	)
	(segment
		(start 134.587996 -263.196832)
		(end 134.573264 -263.188196)
		(width 0.088646)
		(layer "In11.Cu")
		(net "M_H_CPU1_SA_DQ<31>")
	)
	(segment
		(start 207.071214 -279.766776)
		(end 206.489808 -280.348182)
		(width 0.18288)
		(layer "In11.Cu")
		(net "M_H_CPU1_SA_DQ<31>")
	)
	(segment
		(start 202.330812 -280.19121)
		(end 202.201272 -280.06167)
		(width 0.18288)
		(layer "In11.Cu")
		(net "M_H_CPU1_SA_DQ<31>")
	)
	(segment
		(start 192.82029 -281.89428)
		(end 189.187836 -281.89428)
		(width 0.18288)
		(layer "In11.Cu")
		(net "M_H_CPU1_SA_DQ<31>")
	)
	(segment
		(start 188.331856 -281.0383)
		(end 187.009278 -281.0383)
		(width 0.18288)
		(layer "In11.Cu")
		(net "M_H_CPU1_SA_DQ<31>")
	)
	(segment
		(start 124.53747 -263.743694)
		(end 124.59462 -263.686544)
		(width 0.088646)
		(layer "In11.Cu")
		(net "M_H_CPU1_SA_DQ<31>")
	)
	(segment
		(start 135.810244 -263.686544)
		(end 135.810244 -263.668002)
		(width 0.088646)
		(layer "In11.Cu")
		(net "M_H_CPU1_SA_DQ<31>")
	)
	(segment
		(start 139.923012 -266.531852)
		(end 139.612878 -266.221718)
		(width 0.088646)
		(layer "In11.Cu")
		(net "M_H_CPU1_SA_DQ<31>")
	)
	(segment
		(start 196.9135 -281.38882)
		(end 196.72046 -281.19578)
		(width 0.18288)
		(layer "In11.Cu")
		(net "M_H_CPU1_SA_DQ<31>")
	)
	(segment
		(start 179.79009 -281.97429)
		(end 179.52974 -281.71394)
		(width 0.18288)
		(layer "In11.Cu")
		(net "M_H_CPU1_SA_DQ<31>")
	)
	(segment
		(start 132.708396 -263.196832)
		(end 132.697982 -263.190736)
		(width 0.088646)
		(layer "In11.Cu")
		(net "M_H_CPU1_SA_DQ<31>")
	)
	(segment
		(start 181.224682 -281.234896)
		(end 181.031642 -281.427936)
		(width 0.18288)
		(layer "In11.Cu")
		(net "M_H_CPU1_SA_DQ<31>")
	)
	(segment
		(start 168.601136 -280.670508)
		(end 165.159944 -280.670508)
		(width 0.18288)
		(layer "In11.Cu")
		(net "M_H_CPU1_SA_DQ<31>")
	)
	(segment
		(start 125.282198 -263.66978)
		(end 125.282198 -263.686544)
		(width 0.088646)
		(layer "In11.Cu")
		(net "M_H_CPU1_SA_DQ<31>")
	)
	(segment
		(start 170.846242 -282.225242)
		(end 170.15587 -282.225242)
		(width 0.18288)
		(layer "In11.Cu")
		(net "M_H_CPU1_SA_DQ<31>")
	)
	(segment
		(start 136.280144 -264.50036)
		(end 136.280144 -264.490454)
		(width 0.088646)
		(layer "In11.Cu")
		(net "M_H_CPU1_SA_DQ<31>")
	)
	(segment
		(start 186.754516 -281.293062)
		(end 184.01919 -281.293062)
		(width 0.18288)
		(layer "In11.Cu")
		(net "M_H_CPU1_SA_DQ<31>")
	)
	(segment
		(start 131.76885 -263.196832)
		(end 131.758436 -263.190736)
		(width 0.088646)
		(layer "In11.Cu")
		(net "M_H_CPU1_SA_DQ<31>")
	)
	(segment
		(start 198.71436 -281.101292)
		(end 197.896226 -281.919426)
		(width 0.18288)
		(layer "In11.Cu")
		(net "M_H_CPU1_SA_DQ<31>")
	)
	(segment
		(start 124.72035 -264.010902)
		(end 124.71146 -264.005822)
		(width 0.088646)
		(layer "In11.Cu")
		(net "M_H_CPU1_SA_DQ<31>")
	)
	(segment
		(start 200.186036 -280.5811)
		(end 199.665844 -281.101292)
		(width 0.18288)
		(layer "In11.Cu")
		(net "M_H_CPU1_SA_DQ<31>")
	)
	(segment
		(start 163.760658 -281.06751)
		(end 162.834574 -280.141426)
		(width 0.18288)
		(layer "In11.Cu")
		(net "M_H_CPU1_SA_DQ<31>")
	)
	(segment
		(start 194.822826 -281.919426)
		(end 194.670426 -281.767026)
		(width 0.18288)
		(layer "In11.Cu")
		(net "M_H_CPU1_SA_DQ<31>")
	)
	(segment
		(start 161.595054 -280.141426)
		(end 161.269426 -279.815798)
		(width 0.18288)
		(layer "In11.Cu")
		(net "M_H_CPU1_SA_DQ<31>")
	)
	(segment
		(start 204.088746 -280.348182)
		(end 203.931774 -280.19121)
		(width 0.18288)
		(layer "In11.Cu")
		(net "M_H_CPU1_SA_DQ<31>")
	)
	(segment
		(start 181.735222 -281.78125)
		(end 181.735222 -281.427936)
		(width 0.18288)
		(layer "In11.Cu")
		(net "M_H_CPU1_SA_DQ<31>")
	)
	(segment
		(start 165.159944 -280.670508)
		(end 164.762942 -281.06751)
		(width 0.18288)
		(layer "In11.Cu")
		(net "M_H_CPU1_SA_DQ<31>")
	)
	(segment
		(start 202.201272 -280.06167)
		(end 201.24166 -280.06167)
		(width 0.18288)
		(layer "In11.Cu")
		(net "M_H_CPU1_SA_DQ<31>")
	)
	(segment
		(start 187.009278 -281.0383)
		(end 186.754516 -281.293062)
		(width 0.18288)
		(layer "In11.Cu")
		(net "M_H_CPU1_SA_DQ<31>")
	)
	(segment
		(start 181.031642 -281.427936)
		(end 181.031642 -281.78125)
		(width 0.18288)
		(layer "In11.Cu")
		(net "M_H_CPU1_SA_DQ<31>")
	)
	(segment
		(start 162.834574 -280.141426)
		(end 161.595054 -280.141426)
		(width 0.18288)
		(layer "In11.Cu")
		(net "M_H_CPU1_SA_DQ<31>")
	)
	(segment
		(start 196.40296 -281.19578)
		(end 196.20992 -281.38882)
		(width 0.18288)
		(layer "In11.Cu")
		(net "M_H_CPU1_SA_DQ<31>")
	)
	(segment
		(start 192.947544 -281.767026)
		(end 192.82029 -281.89428)
		(width 0.18288)
		(layer "In11.Cu")
		(net "M_H_CPU1_SA_DQ<31>")
	)
	(segment
		(start 180.838602 -281.97429)
		(end 179.79009 -281.97429)
		(width 0.18288)
		(layer "In11.Cu")
		(net "M_H_CPU1_SA_DQ<31>")
	)
	(segment
		(start 172.107098 -282.742894)
		(end 171.888658 -282.961334)
		(width 0.18288)
		(layer "In11.Cu")
		(net "M_H_CPU1_SA_DQ<31>")
	)
	(segment
		(start 127.069596 -263.196832)
		(end 127.054864 -263.188196)
		(width 0.088646)
		(layer "In11.Cu")
		(net "M_H_CPU1_SA_DQ<31>")
	)
	(segment
		(start 197.896226 -281.919426)
		(end 197.10654 -281.919426)
		(width 0.18288)
		(layer "In11.Cu")
		(net "M_H_CPU1_SA_DQ<31>")
	)
	(segment
		(start 201.24166 -280.06167)
		(end 200.72223 -280.5811)
		(width 0.18288)
		(layer "In11.Cu")
		(net "M_H_CPU1_SA_DQ<31>")
	)
	(segment
		(start 196.20992 -281.726386)
		(end 196.01688 -281.919426)
		(width 0.18288)
		(layer "In11.Cu")
		(net "M_H_CPU1_SA_DQ<31>")
	)
	(segment
		(start 157.274768 -278.53767)
		(end 156.476192 -278.53767)
		(width 0.18288)
		(layer "In11.Cu")
		(net "M_H_CPU1_SA_DQ<31>")
	)
	(segment
		(start 128.949196 -263.196832)
		(end 128.934464 -263.188196)
		(width 0.088646)
		(layer "In11.Cu")
		(net "M_H_CPU1_SA_DQ<31>")
	)
	(arc
		(start 132.697982 -263.190736)
		(mid 132.419804 -263.121044)
		(end 132.143246 -263.196832)
		(width 0.088646)
		(layer "In11.Cu")
		(net "M_H_CPU1_SA_DQ<31>")
	)
	(arc
		(start 127.054864 -263.188196)
		(mid 126.778423 -263.12103)
		(end 126.504192 -263.196832)
		(width 0.088646)
		(layer "In11.Cu")
		(net "M_H_CPU1_SA_DQ<31>")
	)
	(arc
		(start 127.994664 -263.188196)
		(mid 127.718223 -263.12103)
		(end 127.443992 -263.196832)
		(width 0.088646)
		(layer "In11.Cu")
		(net "M_H_CPU1_SA_DQ<31>")
	)
	(arc
		(start 134.022592 -263.196832)
		(mid 133.835394 -263.246975)
		(end 133.648196 -263.196832)
		(width 0.088646)
		(layer "In11.Cu")
		(net "M_H_CPU1_SA_DQ<31>")
	)
	(arc
		(start 124.71146 -264.005822)
		(mid 124.595651 -263.893893)
		(end 124.53747 -263.743694)
		(width 0.088646)
		(layer "In11.Cu")
		(net "M_H_CPU1_SA_DQ<31>")
	)
	(arc
		(start 133.633464 -263.188196)
		(mid 133.357023 -263.12103)
		(end 133.082792 -263.196832)
		(width 0.088646)
		(layer "In11.Cu")
		(net "M_H_CPU1_SA_DQ<31>")
	)
	(arc
		(start 134.573264 -263.188196)
		(mid 134.296823 -263.12103)
		(end 134.022592 -263.196832)
		(width 0.088646)
		(layer "In11.Cu")
		(net "M_H_CPU1_SA_DQ<31>")
	)
	(arc
		(start 129.323592 -263.196832)
		(mid 129.136394 -263.246975)
		(end 128.949196 -263.196832)
		(width 0.088646)
		(layer "In11.Cu")
		(net "M_H_CPU1_SA_DQ<31>")
	)
	(arc
		(start 126.119382 -263.190736)
		(mid 125.841204 -263.121044)
		(end 125.564646 -263.196832)
		(width 0.088646)
		(layer "In11.Cu")
		(net "M_H_CPU1_SA_DQ<31>")
	)
	(arc
		(start 136.458706 -264.819638)
		(mid 136.327792 -264.683278)
		(end 136.280144 -264.50036)
		(width 0.088646)
		(layer "In11.Cu")
		(net "M_H_CPU1_SA_DQ<31>")
	)
	(arc
		(start 138.251692 -265.638788)
		(mid 138.064494 -265.688965)
		(end 137.877296 -265.638788)
		(width 0.088646)
		(layer "In11.Cu")
		(net "M_H_CPU1_SA_DQ<31>")
	)
	(arc
		(start 137.868406 -265.633454)
		(mid 137.589618 -265.562891)
		(end 137.312146 -265.638534)
		(width 0.088646)
		(layer "In11.Cu")
		(net "M_H_CPU1_SA_DQ<31>")
	)
	(arc
		(start 125.282198 -263.686544)
		(mid 125.234519 -263.869444)
		(end 125.103636 -264.005822)
		(width 0.088646)
		(layer "In11.Cu")
		(net "M_H_CPU1_SA_DQ<31>")
	)
	(arc
		(start 130.814064 -263.188196)
		(mid 130.537623 -263.12103)
		(end 130.263392 -263.196832)
		(width 0.088646)
		(layer "In11.Cu")
		(net "M_H_CPU1_SA_DQ<31>")
	)
	(arc
		(start 130.263392 -263.196832)
		(mid 130.076194 -263.246975)
		(end 129.888996 -263.196832)
		(width 0.088646)
		(layer "In11.Cu")
		(net "M_H_CPU1_SA_DQ<31>")
	)
	(arc
		(start 136.750298 -265.314176)
		(mid 136.676307 -265.03461)
		(end 136.473692 -264.828274)
		(width 0.088646)
		(layer "In11.Cu")
		(net "M_H_CPU1_SA_DQ<31>")
	)
	(arc
		(start 129.888996 -263.196832)
		(mid 129.606294 -263.12109)
		(end 129.323592 -263.196832)
		(width 0.088646)
		(layer "In11.Cu")
		(net "M_H_CPU1_SA_DQ<31>")
	)
	(arc
		(start 138.93419 -265.72845)
		(mid 138.878585 -265.679776)
		(end 138.817096 -265.638788)
		(width 0.088646)
		(layer "In11.Cu")
		(net "M_H_CPU1_SA_DQ<31>")
	)
	(arc
		(start 135.810244 -263.668002)
		(mid 135.730082 -263.395813)
		(end 135.527796 -263.196832)
		(width 0.088646)
		(layer "In11.Cu")
		(net "M_H_CPU1_SA_DQ<31>")
	)
	(arc
		(start 135.988806 -264.005822)
		(mid 135.857892 -263.869462)
		(end 135.810244 -263.686544)
		(width 0.088646)
		(layer "In11.Cu")
		(net "M_H_CPU1_SA_DQ<31>")
	)
	(arc
		(start 125.564646 -263.196832)
		(mid 125.361904 -263.396575)
		(end 125.282198 -263.66978)
		(width 0.088646)
		(layer "In11.Cu")
		(net "M_H_CPU1_SA_DQ<31>")
	)
	(arc
		(start 138.817096 -265.638788)
		(mid 138.534394 -265.563012)
		(end 138.251692 -265.638788)
		(width 0.088646)
		(layer "In11.Cu")
		(net "M_H_CPU1_SA_DQ<31>")
	)
	(arc
		(start 136.280144 -264.490454)
		(mid 136.202033 -264.213505)
		(end 135.997696 -264.010902)
		(width 0.088646)
		(layer "In11.Cu")
		(net "M_H_CPU1_SA_DQ<31>")
	)
	(arc
		(start 125.094746 -264.010902)
		(mid 124.907548 -264.061045)
		(end 124.72035 -264.010902)
		(width 0.088646)
		(layer "In11.Cu")
		(net "M_H_CPU1_SA_DQ<31>")
	)
	(arc
		(start 134.962392 -263.196832)
		(mid 134.775194 -263.246975)
		(end 134.587996 -263.196832)
		(width 0.088646)
		(layer "In11.Cu")
		(net "M_H_CPU1_SA_DQ<31>")
	)
	(arc
		(start 131.203192 -263.196832)
		(mid 131.015994 -263.246975)
		(end 130.828796 -263.196832)
		(width 0.088646)
		(layer "In11.Cu")
		(net "M_H_CPU1_SA_DQ<31>")
	)
	(arc
		(start 128.383792 -263.196832)
		(mid 128.196594 -263.246975)
		(end 128.009396 -263.196832)
		(width 0.088646)
		(layer "In11.Cu")
		(net "M_H_CPU1_SA_DQ<31>")
	)
	(arc
		(start 127.443992 -263.196832)
		(mid 127.256794 -263.246975)
		(end 127.069596 -263.196832)
		(width 0.088646)
		(layer "In11.Cu")
		(net "M_H_CPU1_SA_DQ<31>")
	)
	(arc
		(start 133.082792 -263.196832)
		(mid 132.895594 -263.246975)
		(end 132.708396 -263.196832)
		(width 0.088646)
		(layer "In11.Cu")
		(net "M_H_CPU1_SA_DQ<31>")
	)
	(arc
		(start 136.92886 -265.633454)
		(mid 136.797946 -265.497094)
		(end 136.750298 -265.314176)
		(width 0.088646)
		(layer "In11.Cu")
		(net "M_H_CPU1_SA_DQ<31>")
	)
	(arc
		(start 137.312146 -265.638534)
		(mid 137.124948 -265.688677)
		(end 136.93775 -265.638534)
		(width 0.088646)
		(layer "In11.Cu")
		(net "M_H_CPU1_SA_DQ<31>")
	)
	(arc
		(start 128.934464 -263.188196)
		(mid 128.658023 -263.12103)
		(end 128.383792 -263.196832)
		(width 0.088646)
		(layer "In11.Cu")
		(net "M_H_CPU1_SA_DQ<31>")
	)
	(arc
		(start 131.758436 -263.190736)
		(mid 131.480004 -263.120922)
		(end 131.203192 -263.196832)
		(width 0.088646)
		(layer "In11.Cu")
		(net "M_H_CPU1_SA_DQ<31>")
	)
	(arc
		(start 135.527796 -263.196832)
		(mid 135.245094 -263.12109)
		(end 134.962392 -263.196832)
		(width 0.088646)
		(layer "In11.Cu")
		(net "M_H_CPU1_SA_DQ<31>")
	)
	(arc
		(start 132.143246 -263.196832)
		(mid 131.956048 -263.246975)
		(end 131.76885 -263.196832)
		(width 0.088646)
		(layer "In11.Cu")
		(net "M_H_CPU1_SA_DQ<31>")
	)
	(arc
		(start 126.504192 -263.196832)
		(mid 126.316994 -263.246975)
		(end 126.129796 -263.196832)
		(width 0.088646)
		(layer "In11.Cu")
		(net "M_H_CPU1_SA_DQ<31>")
	)
	(segment
		(start 125.377448 -264.500106)
		(end 125.377194 -264.50036)
		(width 0.20066)
		(layer "F.Cu")
		(net "M_H_CPU1_SA_DQ<30>")
	)
	(segment
		(start 210.598258 -281.898852)
		(end 210.603084 -281.898852)
		(width 0.101854)
		(layer "F.Cu")
		(net "M_H_CPU1_SA_DQ<30>")
	)
	(segment
		(start 213.515448 -281.69997)
		(end 213.515448 -281.449018)
		(width 0.20066)
		(layer "F.Cu")
		(net "M_H_CPU1_SA_DQ<30>")
	)
	(segment
		(start 209.874358 -281.466798)
		(end 210.306412 -281.898852)
		(width 0.20066)
		(layer "F.Cu")
		(net "M_H_CPU1_SA_DQ<30>")
	)
	(segment
		(start 207.071468 -281.466798)
		(end 208.176114 -281.466798)
		(width 0.20066)
		(layer "F.Cu")
		(net "M_H_CPU1_SA_DQ<30>")
	)
	(segment
		(start 125.377448 -263.96442)
		(end 125.377448 -264.500106)
		(width 0.20066)
		(layer "F.Cu")
		(net "M_H_CPU1_SA_DQ<30>")
	)
	(segment
		(start 208.176114 -281.466798)
		(end 209.874358 -281.466798)
		(width 0.20066)
		(layer "F.Cu")
		(net "M_H_CPU1_SA_DQ<30>")
	)
	(segment
		(start 213.515448 -281.449018)
		(end 213.749636 -281.21483)
		(width 0.20066)
		(layer "F.Cu")
		(net "M_H_CPU1_SA_DQ<30>")
	)
	(segment
		(start 213.749636 -281.21483)
		(end 214.133684 -281.21483)
		(width 0.20066)
		(layer "F.Cu")
		(net "M_H_CPU1_SA_DQ<30>")
	)
	(segment
		(start 214.385652 -281.466798)
		(end 215.719914 -281.466798)
		(width 0.20066)
		(layer "F.Cu")
		(net "M_H_CPU1_SA_DQ<30>")
	)
	(segment
		(start 207.071214 -281.466544)
		(end 207.071468 -281.466798)
		(width 0.20066)
		(layer "F.Cu")
		(net "M_H_CPU1_SA_DQ<30>")
	)
	(segment
		(start 212.630258 -281.903932)
		(end 213.311486 -281.903932)
		(width 0.20066)
		(layer "F.Cu")
		(net "M_H_CPU1_SA_DQ<30>")
	)
	(segment
		(start 213.311486 -281.903932)
		(end 213.515448 -281.69997)
		(width 0.20066)
		(layer "F.Cu")
		(net "M_H_CPU1_SA_DQ<30>")
	)
	(segment
		(start 214.133684 -281.21483)
		(end 214.385652 -281.466798)
		(width 0.20066)
		(layer "F.Cu")
		(net "M_H_CPU1_SA_DQ<30>")
	)
	(segment
		(start 212.618066 -281.89174)
		(end 212.630258 -281.903932)
		(width 0.1016)
		(layer "F.Cu")
		(net "M_H_CPU1_SA_DQ<30>")
	)
	(segment
		(start 210.603084 -281.898852)
		(end 210.610196 -281.89174)
		(width 0.1016)
		(layer "F.Cu")
		(net "M_H_CPU1_SA_DQ<30>")
	)
	(segment
		(start 210.610196 -281.89174)
		(end 212.618066 -281.89174)
		(width 0.1016)
		(layer "F.Cu")
		(net "M_H_CPU1_SA_DQ<30>")
	)
	(segment
		(start 210.306412 -281.898852)
		(end 210.598258 -281.898852)
		(width 0.20066)
		(layer "F.Cu")
		(net "M_H_CPU1_SA_DQ<30>")
	)
	(segment
		(start 170.502072 -283.63164)
		(end 170.231308 -283.902658)
		(width 0.18288)
		(layer "In11.Cu")
		(net "M_H_CPU1_SA_DQ<30>")
	)
	(segment
		(start 129.803906 -264.004806)
		(end 129.793492 -264.010902)
		(width 0.088646)
		(layer "In11.Cu")
		(net "M_H_CPU1_SA_DQ<30>")
	)
	(segment
		(start 204.568806 -282.071826)
		(end 204.04582 -282.071826)
		(width 0.18288)
		(layer "In11.Cu")
		(net "M_H_CPU1_SA_DQ<30>")
	)
	(segment
		(start 172.039026 -285.323026)
		(end 171.412916 -285.323026)
		(width 0.18288)
		(layer "In11.Cu")
		(net "M_H_CPU1_SA_DQ<30>")
	)
	(segment
		(start 128.86436 -264.004806)
		(end 128.853946 -264.010902)
		(width 0.088646)
		(layer "In11.Cu")
		(net "M_H_CPU1_SA_DQ<30>")
	)
	(segment
		(start 202.719686 -281.891232)
		(end 202.49388 -281.665426)
		(width 0.18288)
		(layer "In11.Cu")
		(net "M_H_CPU1_SA_DQ<30>")
	)
	(segment
		(start 203.865226 -281.891232)
		(end 202.719686 -281.891232)
		(width 0.18288)
		(layer "In11.Cu")
		(net "M_H_CPU1_SA_DQ<30>")
	)
	(segment
		(start 173.449996 -285.291784)
		(end 172.070268 -285.291784)
		(width 0.18288)
		(layer "In11.Cu")
		(net "M_H_CPU1_SA_DQ<30>")
	)
	(segment
		(start 170.974512 -283.87802)
		(end 170.728132 -283.63164)
		(width 0.18288)
		(layer "In11.Cu")
		(net "M_H_CPU1_SA_DQ<30>")
	)
	(segment
		(start 127.928878 -264.002266)
		(end 127.914146 -264.010902)
		(width 0.088646)
		(layer "In11.Cu")
		(net "M_H_CPU1_SA_DQ<30>")
	)
	(segment
		(start 187.621926 -282.740862)
		(end 186.614562 -283.748226)
		(width 0.18288)
		(layer "In11.Cu")
		(net "M_H_CPU1_SA_DQ<30>")
	)
	(segment
		(start 136.467596 -266.45235)
		(end 136.453372 -266.444222)
		(width 0.088646)
		(layer "In11.Cu")
		(net "M_H_CPU1_SA_DQ<30>")
	)
	(segment
		(start 156.466794 -279.965658)
		(end 144.048988 -267.547852)
		(width 0.18288)
		(layer "In11.Cu")
		(net "M_H_CPU1_SA_DQ<30>")
	)
	(segment
		(start 205.770226 -281.911806)
		(end 205.770226 -281.258264)
		(width 0.18288)
		(layer "In11.Cu")
		(net "M_H_CPU1_SA_DQ<30>")
	)
	(segment
		(start 193.67754 -283.658818)
		(end 192.89522 -284.441138)
		(width 0.18288)
		(layer "In11.Cu")
		(net "M_H_CPU1_SA_DQ<30>")
	)
	(segment
		(start 140.087604 -267.547852)
		(end 139.235434 -267.547852)
		(width 0.088646)
		(layer "In11.Cu")
		(net "M_H_CPU1_SA_DQ<30>")
	)
	(segment
		(start 125.958346 -264.056114)
		(end 125.377194 -264.50036)
		(width 0.088646)
		(layer "In11.Cu")
		(net "M_H_CPU1_SA_DQ<30>")
	)
	(segment
		(start 130.748278 -264.002266)
		(end 130.733546 -264.010902)
		(width 0.088646)
		(layer "In11.Cu")
		(net "M_H_CPU1_SA_DQ<30>")
	)
	(segment
		(start 202.49388 -281.665426)
		(end 200.95591 -281.665426)
		(width 0.18288)
		(layer "In11.Cu")
		(net "M_H_CPU1_SA_DQ<30>")
	)
	(segment
		(start 204.728826 -281.1145)
		(end 204.728826 -281.911806)
		(width 0.18288)
		(layer "In11.Cu")
		(net "M_H_CPU1_SA_DQ<30>")
	)
	(segment
		(start 172.070268 -285.291784)
		(end 172.039026 -285.323026)
		(width 0.18288)
		(layer "In11.Cu")
		(net "M_H_CPU1_SA_DQ<30>")
	)
	(segment
		(start 126.034546 -264.010902)
		(end 125.958346 -264.056114)
		(width 0.088646)
		(layer "In11.Cu")
		(net "M_H_CPU1_SA_DQ<30>")
	)
	(segment
		(start 135.527796 -264.824718)
		(end 135.518906 -264.819638)
		(width 0.088646)
		(layer "In11.Cu")
		(net "M_H_CPU1_SA_DQ<30>")
	)
	(segment
		(start 131.688078 -264.002266)
		(end 131.673346 -264.010902)
		(width 0.088646)
		(layer "In11.Cu")
		(net "M_H_CPU1_SA_DQ<30>")
	)
	(segment
		(start 207.071214 -281.466544)
		(end 206.465932 -282.071826)
		(width 0.18288)
		(layer "In11.Cu")
		(net "M_H_CPU1_SA_DQ<30>")
	)
	(segment
		(start 170.231308 -283.902658)
		(end 170.005248 -283.902658)
		(width 0.18288)
		(layer "In11.Cu")
		(net "M_H_CPU1_SA_DQ<30>")
	)
	(segment
		(start 168.012618 -282.630626)
		(end 164.800026 -282.630626)
		(width 0.18288)
		(layer "In11.Cu")
		(net "M_H_CPU1_SA_DQ<30>")
	)
	(segment
		(start 161.40303 -281.747976)
		(end 159.9819 -280.326846)
		(width 0.18288)
		(layer "In11.Cu")
		(net "M_H_CPU1_SA_DQ<30>")
	)
	(segment
		(start 135.340344 -264.50036)
		(end 135.340344 -264.490454)
		(width 0.088646)
		(layer "In11.Cu")
		(net "M_H_CPU1_SA_DQ<30>")
	)
	(segment
		(start 135.99795 -265.638534)
		(end 135.98906 -265.633454)
		(width 0.088646)
		(layer "In11.Cu")
		(net "M_H_CPU1_SA_DQ<30>")
	)
	(segment
		(start 164.800026 -282.630626)
		(end 164.393626 -283.037026)
		(width 0.18288)
		(layer "In11.Cu")
		(net "M_H_CPU1_SA_DQ<30>")
	)
	(segment
		(start 192.89522 -284.441138)
		(end 190.057532 -284.441138)
		(width 0.18288)
		(layer "In11.Cu")
		(net "M_H_CPU1_SA_DQ<30>")
	)
	(segment
		(start 162.698176 -281.747976)
		(end 161.40303 -281.747976)
		(width 0.18288)
		(layer "In11.Cu")
		(net "M_H_CPU1_SA_DQ<30>")
	)
	(segment
		(start 188.357256 -282.740862)
		(end 187.621926 -282.740862)
		(width 0.18288)
		(layer "In11.Cu")
		(net "M_H_CPU1_SA_DQ<30>")
	)
	(segment
		(start 126.989078 -264.002266)
		(end 126.974346 -264.010902)
		(width 0.088646)
		(layer "In11.Cu")
		(net "M_H_CPU1_SA_DQ<30>")
	)
	(segment
		(start 171.412916 -285.323026)
		(end 170.712638 -284.622748)
		(width 0.18288)
		(layer "In11.Cu")
		(net "M_H_CPU1_SA_DQ<30>")
	)
	(segment
		(start 170.005248 -283.902658)
		(end 169.794682 -283.692092)
		(width 0.18288)
		(layer "In11.Cu")
		(net "M_H_CPU1_SA_DQ<30>")
	)
	(segment
		(start 205.466188 -280.954226)
		(end 204.8891 -280.954226)
		(width 0.18288)
		(layer "In11.Cu")
		(net "M_H_CPU1_SA_DQ<30>")
	)
	(segment
		(start 205.770226 -281.258264)
		(end 205.466188 -280.954226)
		(width 0.18288)
		(layer "In11.Cu")
		(net "M_H_CPU1_SA_DQ<30>")
	)
	(segment
		(start 170.712638 -284.366208)
		(end 170.974512 -284.10408)
		(width 0.18288)
		(layer "In11.Cu")
		(net "M_H_CPU1_SA_DQ<30>")
	)
	(segment
		(start 177.45202 -284.441138)
		(end 174.300642 -284.441138)
		(width 0.18288)
		(layer "In11.Cu")
		(net "M_H_CPU1_SA_DQ<30>")
	)
	(segment
		(start 204.728826 -281.911806)
		(end 204.568806 -282.071826)
		(width 0.18288)
		(layer "In11.Cu")
		(net "M_H_CPU1_SA_DQ<30>")
	)
	(segment
		(start 198.515224 -282.904692)
		(end 197.761098 -283.658818)
		(width 0.18288)
		(layer "In11.Cu")
		(net "M_H_CPU1_SA_DQ<30>")
	)
	(segment
		(start 157.504638 -280.326846)
		(end 157.14345 -279.965658)
		(width 0.18288)
		(layer "In11.Cu")
		(net "M_H_CPU1_SA_DQ<30>")
	)
	(segment
		(start 190.057532 -284.441138)
		(end 188.357256 -282.740862)
		(width 0.18288)
		(layer "In11.Cu")
		(net "M_H_CPU1_SA_DQ<30>")
	)
	(segment
		(start 169.074084 -283.692092)
		(end 168.012618 -282.630626)
		(width 0.18288)
		(layer "In11.Cu")
		(net "M_H_CPU1_SA_DQ<30>")
	)
	(segment
		(start 197.761098 -283.658818)
		(end 193.67754 -283.658818)
		(width 0.18288)
		(layer "In11.Cu")
		(net "M_H_CPU1_SA_DQ<30>")
	)
	(segment
		(start 135.533892 -264.828274)
		(end 135.527796 -264.824718)
		(width 0.088646)
		(layer "In11.Cu")
		(net "M_H_CPU1_SA_DQ<30>")
	)
	(segment
		(start 204.8891 -280.954226)
		(end 204.728826 -281.1145)
		(width 0.18288)
		(layer "In11.Cu")
		(net "M_H_CPU1_SA_DQ<30>")
	)
	(segment
		(start 170.712638 -284.622748)
		(end 170.712638 -284.366208)
		(width 0.18288)
		(layer "In11.Cu")
		(net "M_H_CPU1_SA_DQ<30>")
	)
	(segment
		(start 199.716644 -282.904692)
		(end 198.515224 -282.904692)
		(width 0.18288)
		(layer "In11.Cu")
		(net "M_H_CPU1_SA_DQ<30>")
	)
	(segment
		(start 206.465932 -282.071826)
		(end 205.930246 -282.071826)
		(width 0.18288)
		(layer "In11.Cu")
		(net "M_H_CPU1_SA_DQ<30>")
	)
	(segment
		(start 164.393626 -283.037026)
		(end 163.987226 -283.037026)
		(width 0.18288)
		(layer "In11.Cu")
		(net "M_H_CPU1_SA_DQ<30>")
	)
	(segment
		(start 170.974512 -284.10408)
		(end 170.974512 -283.87802)
		(width 0.18288)
		(layer "In11.Cu")
		(net "M_H_CPU1_SA_DQ<30>")
	)
	(segment
		(start 136.280144 -266.128246)
		(end 136.280144 -266.106148)
		(width 0.088646)
		(layer "In11.Cu")
		(net "M_H_CPU1_SA_DQ<30>")
	)
	(segment
		(start 178.144932 -283.748226)
		(end 177.45202 -284.441138)
		(width 0.18288)
		(layer "In11.Cu")
		(net "M_H_CPU1_SA_DQ<30>")
	)
	(segment
		(start 144.048988 -267.547852)
		(end 140.087604 -267.547852)
		(width 0.18288)
		(layer "In11.Cu")
		(net "M_H_CPU1_SA_DQ<30>")
	)
	(segment
		(start 133.567678 -264.002266)
		(end 133.552946 -264.010902)
		(width 0.088646)
		(layer "In11.Cu")
		(net "M_H_CPU1_SA_DQ<30>")
	)
	(segment
		(start 205.930246 -282.071826)
		(end 205.770226 -281.911806)
		(width 0.18288)
		(layer "In11.Cu")
		(net "M_H_CPU1_SA_DQ<30>")
	)
	(segment
		(start 186.614562 -283.748226)
		(end 178.144932 -283.748226)
		(width 0.18288)
		(layer "In11.Cu")
		(net "M_H_CPU1_SA_DQ<30>")
	)
	(segment
		(start 163.987226 -283.037026)
		(end 162.698176 -281.747976)
		(width 0.18288)
		(layer "In11.Cu")
		(net "M_H_CPU1_SA_DQ<30>")
	)
	(segment
		(start 157.14345 -279.965658)
		(end 156.466794 -279.965658)
		(width 0.18288)
		(layer "In11.Cu")
		(net "M_H_CPU1_SA_DQ<30>")
	)
	(segment
		(start 139.235434 -267.547852)
		(end 138.62939 -266.941808)
		(width 0.088646)
		(layer "In11.Cu")
		(net "M_H_CPU1_SA_DQ<30>")
	)
	(segment
		(start 170.728132 -283.63164)
		(end 170.502072 -283.63164)
		(width 0.18288)
		(layer "In11.Cu")
		(net "M_H_CPU1_SA_DQ<30>")
	)
	(segment
		(start 159.9819 -280.326846)
		(end 157.504638 -280.326846)
		(width 0.18288)
		(layer "In11.Cu")
		(net "M_H_CPU1_SA_DQ<30>")
	)
	(segment
		(start 169.794682 -283.692092)
		(end 169.074084 -283.692092)
		(width 0.18288)
		(layer "In11.Cu")
		(net "M_H_CPU1_SA_DQ<30>")
	)
	(segment
		(start 200.95591 -281.665426)
		(end 199.716644 -282.904692)
		(width 0.18288)
		(layer "In11.Cu")
		(net "M_H_CPU1_SA_DQ<30>")
	)
	(segment
		(start 174.300642 -284.441138)
		(end 173.449996 -285.291784)
		(width 0.18288)
		(layer "In11.Cu")
		(net "M_H_CPU1_SA_DQ<30>")
	)
	(segment
		(start 204.04582 -282.071826)
		(end 203.865226 -281.891232)
		(width 0.18288)
		(layer "In11.Cu")
		(net "M_H_CPU1_SA_DQ<30>")
	)
	(segment
		(start 134.50316 -264.004806)
		(end 134.492746 -264.010902)
		(width 0.088646)
		(layer "In11.Cu")
		(net "M_H_CPU1_SA_DQ<30>")
	)
	(arc
		(start 136.453372 -266.444222)
		(mid 136.326329 -266.308406)
		(end 136.280144 -266.128246)
		(width 0.088646)
		(layer "In11.Cu")
		(net "M_H_CPU1_SA_DQ<30>")
	)
	(arc
		(start 130.733546 -264.010902)
		(mid 130.546348 -264.061045)
		(end 130.35915 -264.010902)
		(width 0.088646)
		(layer "In11.Cu")
		(net "M_H_CPU1_SA_DQ<30>")
	)
	(arc
		(start 127.914146 -264.010902)
		(mid 127.726948 -264.061045)
		(end 127.53975 -264.010902)
		(width 0.088646)
		(layer "In11.Cu")
		(net "M_H_CPU1_SA_DQ<30>")
	)
	(arc
		(start 133.552946 -264.010902)
		(mid 133.365748 -264.061045)
		(end 133.17855 -264.010902)
		(width 0.088646)
		(layer "In11.Cu")
		(net "M_H_CPU1_SA_DQ<30>")
	)
	(arc
		(start 126.974346 -264.010902)
		(mid 126.787148 -264.061045)
		(end 126.59995 -264.010902)
		(width 0.088646)
		(layer "In11.Cu")
		(net "M_H_CPU1_SA_DQ<30>")
	)
	(arc
		(start 134.492746 -264.010902)
		(mid 134.305548 -264.061045)
		(end 134.11835 -264.010902)
		(width 0.088646)
		(layer "In11.Cu")
		(net "M_H_CPU1_SA_DQ<30>")
	)
	(arc
		(start 137.781792 -266.45235)
		(mid 137.594594 -266.502527)
		(end 137.407396 -266.45235)
		(width 0.088646)
		(layer "In11.Cu")
		(net "M_H_CPU1_SA_DQ<30>")
	)
	(arc
		(start 138.46429 -266.542012)
		(mid 138.408685 -266.493338)
		(end 138.347196 -266.45235)
		(width 0.088646)
		(layer "In11.Cu")
		(net "M_H_CPU1_SA_DQ<30>")
	)
	(arc
		(start 129.793492 -264.010902)
		(mid 129.606294 -264.061045)
		(end 129.419096 -264.010902)
		(width 0.088646)
		(layer "In11.Cu")
		(net "M_H_CPU1_SA_DQ<30>")
	)
	(arc
		(start 130.35915 -264.010902)
		(mid 130.082337 -263.935032)
		(end 129.803906 -264.004806)
		(width 0.088646)
		(layer "In11.Cu")
		(net "M_H_CPU1_SA_DQ<30>")
	)
	(arc
		(start 134.11835 -264.010902)
		(mid 133.844151 -263.935067)
		(end 133.567678 -264.002266)
		(width 0.088646)
		(layer "In11.Cu")
		(net "M_H_CPU1_SA_DQ<30>")
	)
	(arc
		(start 135.98906 -265.633454)
		(mid 135.858146 -265.497094)
		(end 135.810498 -265.314176)
		(width 0.088646)
		(layer "In11.Cu")
		(net "M_H_CPU1_SA_DQ<30>")
	)
	(arc
		(start 138.62939 -266.941808)
		(mid 138.586731 -266.725434)
		(end 138.46429 -266.542012)
		(width 0.088646)
		(layer "In11.Cu")
		(net "M_H_CPU1_SA_DQ<30>")
	)
	(arc
		(start 132.23875 -264.010902)
		(mid 131.964551 -263.935067)
		(end 131.688078 -264.002266)
		(width 0.088646)
		(layer "In11.Cu")
		(net "M_H_CPU1_SA_DQ<30>")
	)
	(arc
		(start 129.419096 -264.010902)
		(mid 129.142537 -263.935159)
		(end 128.86436 -264.004806)
		(width 0.088646)
		(layer "In11.Cu")
		(net "M_H_CPU1_SA_DQ<30>")
	)
	(arc
		(start 128.47955 -264.010902)
		(mid 128.205351 -263.935067)
		(end 127.928878 -264.002266)
		(width 0.088646)
		(layer "In11.Cu")
		(net "M_H_CPU1_SA_DQ<30>")
	)
	(arc
		(start 136.841992 -266.45235)
		(mid 136.654794 -266.502527)
		(end 136.467596 -266.45235)
		(width 0.088646)
		(layer "In11.Cu")
		(net "M_H_CPU1_SA_DQ<30>")
	)
	(arc
		(start 131.673346 -264.010902)
		(mid 131.486148 -264.061045)
		(end 131.29895 -264.010902)
		(width 0.088646)
		(layer "In11.Cu")
		(net "M_H_CPU1_SA_DQ<30>")
	)
	(arc
		(start 133.17855 -264.010902)
		(mid 132.895848 -263.935126)
		(end 132.613146 -264.010902)
		(width 0.088646)
		(layer "In11.Cu")
		(net "M_H_CPU1_SA_DQ<30>")
	)
	(arc
		(start 128.853946 -264.010902)
		(mid 128.666748 -264.061045)
		(end 128.47955 -264.010902)
		(width 0.088646)
		(layer "In11.Cu")
		(net "M_H_CPU1_SA_DQ<30>")
	)
	(arc
		(start 135.518906 -264.819638)
		(mid 135.387992 -264.683278)
		(end 135.340344 -264.50036)
		(width 0.088646)
		(layer "In11.Cu")
		(net "M_H_CPU1_SA_DQ<30>")
	)
	(arc
		(start 135.340344 -264.490454)
		(mid 135.262233 -264.213505)
		(end 135.057896 -264.010902)
		(width 0.088646)
		(layer "In11.Cu")
		(net "M_H_CPU1_SA_DQ<30>")
	)
	(arc
		(start 138.347196 -266.45235)
		(mid 138.064494 -266.376574)
		(end 137.781792 -266.45235)
		(width 0.088646)
		(layer "In11.Cu")
		(net "M_H_CPU1_SA_DQ<30>")
	)
	(arc
		(start 131.29895 -264.010902)
		(mid 131.024751 -263.935067)
		(end 130.748278 -264.002266)
		(width 0.088646)
		(layer "In11.Cu")
		(net "M_H_CPU1_SA_DQ<30>")
	)
	(arc
		(start 132.613146 -264.010902)
		(mid 132.425948 -264.061045)
		(end 132.23875 -264.010902)
		(width 0.088646)
		(layer "In11.Cu")
		(net "M_H_CPU1_SA_DQ<30>")
	)
	(arc
		(start 126.59995 -264.010902)
		(mid 126.317248 -263.935126)
		(end 126.034546 -264.010902)
		(width 0.088646)
		(layer "In11.Cu")
		(net "M_H_CPU1_SA_DQ<30>")
	)
	(arc
		(start 136.280144 -266.106148)
		(mid 136.199233 -265.83602)
		(end 135.99795 -265.638534)
		(width 0.088646)
		(layer "In11.Cu")
		(net "M_H_CPU1_SA_DQ<30>")
	)
	(arc
		(start 135.057896 -264.010902)
		(mid 134.781337 -263.935159)
		(end 134.50316 -264.004806)
		(width 0.088646)
		(layer "In11.Cu")
		(net "M_H_CPU1_SA_DQ<30>")
	)
	(arc
		(start 135.810498 -265.314176)
		(mid 135.736507 -265.03461)
		(end 135.533892 -264.828274)
		(width 0.088646)
		(layer "In11.Cu")
		(net "M_H_CPU1_SA_DQ<30>")
	)
	(arc
		(start 127.53975 -264.010902)
		(mid 127.265551 -263.935067)
		(end 126.989078 -264.002266)
		(width 0.088646)
		(layer "In11.Cu")
		(net "M_H_CPU1_SA_DQ<30>")
	)
	(arc
		(start 137.407396 -266.45235)
		(mid 137.124694 -266.376574)
		(end 136.841992 -266.45235)
		(width 0.088646)
		(layer "In11.Cu")
		(net "M_H_CPU1_SA_DQ<30>")
	)
	(segment
		(start 214.385652 -315.46673)
		(end 215.719914 -315.46673)
		(width 0.20066)
		(layer "F.Cu")
		(net "M_H_CPU1_SA_DQ<2>")
	)
	(segment
		(start 210.603084 -315.898784)
		(end 210.610196 -315.891672)
		(width 0.1016)
		(layer "F.Cu")
		(net "M_H_CPU1_SA_DQ<2>")
	)
	(segment
		(start 213.515448 -315.699902)
		(end 213.515448 -315.44895)
		(width 0.20066)
		(layer "F.Cu")
		(net "M_H_CPU1_SA_DQ<2>")
	)
	(segment
		(start 209.874358 -315.46673)
		(end 210.306412 -315.898784)
		(width 0.20066)
		(layer "F.Cu")
		(net "M_H_CPU1_SA_DQ<2>")
	)
	(segment
		(start 210.306412 -315.898784)
		(end 210.598258 -315.898784)
		(width 0.20066)
		(layer "F.Cu")
		(net "M_H_CPU1_SA_DQ<2>")
	)
	(segment
		(start 208.176114 -315.46673)
		(end 209.874358 -315.46673)
		(width 0.20066)
		(layer "F.Cu")
		(net "M_H_CPU1_SA_DQ<2>")
	)
	(segment
		(start 213.311486 -315.903864)
		(end 213.515448 -315.699902)
		(width 0.20066)
		(layer "F.Cu")
		(net "M_H_CPU1_SA_DQ<2>")
	)
	(segment
		(start 207.071214 -315.46673)
		(end 208.176114 -315.46673)
		(width 0.20066)
		(layer "F.Cu")
		(net "M_H_CPU1_SA_DQ<2>")
	)
	(segment
		(start 212.630258 -315.903864)
		(end 213.311486 -315.903864)
		(width 0.20066)
		(layer "F.Cu")
		(net "M_H_CPU1_SA_DQ<2>")
	)
	(segment
		(start 131.016248 -279.150064)
		(end 131.015994 -279.150318)
		(width 0.20066)
		(layer "F.Cu")
		(net "M_H_CPU1_SA_DQ<2>")
	)
	(segment
		(start 213.749636 -315.214762)
		(end 214.133684 -315.214762)
		(width 0.20066)
		(layer "F.Cu")
		(net "M_H_CPU1_SA_DQ<2>")
	)
	(segment
		(start 210.610196 -315.891672)
		(end 212.618066 -315.891672)
		(width 0.1016)
		(layer "F.Cu")
		(net "M_H_CPU1_SA_DQ<2>")
	)
	(segment
		(start 210.598258 -315.898784)
		(end 210.603084 -315.898784)
		(width 0.101854)
		(layer "F.Cu")
		(net "M_H_CPU1_SA_DQ<2>")
	)
	(segment
		(start 131.016248 -278.614378)
		(end 131.016248 -279.150064)
		(width 0.20066)
		(layer "F.Cu")
		(net "M_H_CPU1_SA_DQ<2>")
	)
	(segment
		(start 213.515448 -315.44895)
		(end 213.749636 -315.214762)
		(width 0.20066)
		(layer "F.Cu")
		(net "M_H_CPU1_SA_DQ<2>")
	)
	(segment
		(start 212.618066 -315.891672)
		(end 212.630258 -315.903864)
		(width 0.1016)
		(layer "F.Cu")
		(net "M_H_CPU1_SA_DQ<2>")
	)
	(segment
		(start 214.133684 -315.214762)
		(end 214.385652 -315.46673)
		(width 0.20066)
		(layer "F.Cu")
		(net "M_H_CPU1_SA_DQ<2>")
	)
	(segment
		(start 185.184796 -315.550296)
		(end 184.505346 -315.295026)
		(width 0.18288)
		(layer "In6.Cu")
		(net "M_H_CPU1_SA_DQ<2>")
	)
	(segment
		(start 167.191436 -311.83326)
		(end 167.234362 -311.56402)
		(width 0.18288)
		(layer "In6.Cu")
		(net "M_H_CPU1_SA_DQ<2>")
	)
	(segment
		(start 181.613302 -313.786012)
		(end 181.285642 -313.786012)
		(width 0.18288)
		(layer "In6.Cu")
		(net "M_H_CPU1_SA_DQ<2>")
	)
	(segment
		(start 196.338698 -315.706252)
		(end 196.155818 -315.889132)
		(width 0.18288)
		(layer "In6.Cu")
		(net "M_H_CPU1_SA_DQ<2>")
	)
	(segment
		(start 174.440596 -312.76417)
		(end 173.115478 -313.315858)
		(width 0.18288)
		(layer "In6.Cu")
		(net "M_H_CPU1_SA_DQ<2>")
	)
	(segment
		(start 186.376818 -316.742318)
		(end 185.184796 -315.550296)
		(width 0.18288)
		(layer "In6.Cu")
		(net "M_H_CPU1_SA_DQ<2>")
	)
	(segment
		(start 146.360642 -284.451044)
		(end 144.54378 -282.634182)
		(width 0.18288)
		(layer "In6.Cu")
		(net "M_H_CPU1_SA_DQ<2>")
	)
	(segment
		(start 204.08646 -316.79388)
		(end 203.90358 -316.611)
		(width 0.18288)
		(layer "In6.Cu")
		(net "M_H_CPU1_SA_DQ<2>")
	)
	(segment
		(start 132.157978 -279.46604)
		(end 132.143246 -279.474676)
		(width 0.088646)
		(layer "In6.Cu")
		(net "M_H_CPU1_SA_DQ<2>")
	)
	(segment
		(start 134.587996 -279.474676)
		(end 134.573264 -279.46604)
		(width 0.088646)
		(layer "In6.Cu")
		(net "M_H_CPU1_SA_DQ<2>")
	)
	(segment
		(start 160.48609 -309.029354)
		(end 159.519874 -309.029354)
		(width 0.18288)
		(layer "In6.Cu")
		(net "M_H_CPU1_SA_DQ<2>")
	)
	(segment
		(start 180.16474 -314.265056)
		(end 179.68087 -313.781186)
		(width 0.18288)
		(layer "In6.Cu")
		(net "M_H_CPU1_SA_DQ<2>")
	)
	(segment
		(start 131.261612 -279.445212)
		(end 131.172458 -279.421336)
		(width 0.088646)
		(layer "In6.Cu")
		(net "M_H_CPU1_SA_DQ<2>")
	)
	(segment
		(start 174.944024 -312.695844)
		(end 174.440596 -312.76417)
		(width 0.18288)
		(layer "In6.Cu")
		(net "M_H_CPU1_SA_DQ<2>")
	)
	(segment
		(start 161.357056 -309.90032)
		(end 160.48609 -309.029354)
		(width 0.18288)
		(layer "In6.Cu")
		(net "M_H_CPU1_SA_DQ<2>")
	)
	(segment
		(start 166.297356 -311.876694)
		(end 164.72281 -311.627266)
		(width 0.18288)
		(layer "In6.Cu")
		(net "M_H_CPU1_SA_DQ<2>")
	)
	(segment
		(start 167.082216 -311.354978)
		(end 166.758366 -311.303416)
		(width 0.18288)
		(layer "In6.Cu")
		(net "M_H_CPU1_SA_DQ<2>")
	)
	(segment
		(start 131.172458 -279.421336)
		(end 131.015994 -279.150318)
		(width 0.088646)
		(layer "In6.Cu")
		(net "M_H_CPU1_SA_DQ<2>")
	)
	(segment
		(start 175.486822 -311.722516)
		(end 175.141636 -311.769506)
		(width 0.18288)
		(layer "In6.Cu")
		(net "M_H_CPU1_SA_DQ<2>")
	)
	(segment
		(start 170.31081 -312.706258)
		(end 170.401996 -312.506106)
		(width 0.18288)
		(layer "In6.Cu")
		(net "M_H_CPU1_SA_DQ<2>")
	)
	(segment
		(start 139.661138 -282.29179)
		(end 139.661138 -281.892248)
		(width 0.088646)
		(layer "In6.Cu")
		(net "M_H_CPU1_SA_DQ<2>")
	)
	(segment
		(start 170.390312 -312.91784)
		(end 170.31081 -312.706258)
		(width 0.18288)
		(layer "In6.Cu")
		(net "M_H_CPU1_SA_DQ<2>")
	)
	(segment
		(start 170.005248 -312.149998)
		(end 169.793666 -312.2295)
		(width 0.18288)
		(layer "In6.Cu")
		(net "M_H_CPU1_SA_DQ<2>")
	)
	(segment
		(start 176.260506 -312.518044)
		(end 175.923194 -312.56351)
		(width 0.18288)
		(layer "In6.Cu")
		(net "M_H_CPU1_SA_DQ<2>")
	)
	(segment
		(start 204.597 -316.611)
		(end 204.41412 -316.79388)
		(width 0.18288)
		(layer "In6.Cu")
		(net "M_H_CPU1_SA_DQ<2>")
	)
	(segment
		(start 183.176926 -314.380626)
		(end 181.979062 -314.380626)
		(width 0.18288)
		(layer "In6.Cu")
		(net "M_H_CPU1_SA_DQ<2>")
	)
	(segment
		(start 166.549324 -311.455562)
		(end 166.506398 -311.724548)
		(width 0.18288)
		(layer "In6.Cu")
		(net "M_H_CPU1_SA_DQ<2>")
	)
	(segment
		(start 170.322494 -312.294524)
		(end 170.005248 -312.149998)
		(width 0.18288)
		(layer "In6.Cu")
		(net "M_H_CPU1_SA_DQ<2>")
	)
	(segment
		(start 204.77988 -315.892942)
		(end 204.597 -316.075822)
		(width 0.18288)
		(layer "In6.Cu")
		(net "M_H_CPU1_SA_DQ<2>")
	)
	(segment
		(start 196.338698 -315.480192)
		(end 196.338698 -315.706252)
		(width 0.18288)
		(layer "In6.Cu")
		(net "M_H_CPU1_SA_DQ<2>")
	)
	(segment
		(start 180.720746 -314.380626)
		(end 180.16474 -314.265056)
		(width 0.18288)
		(layer "In6.Cu")
		(net "M_H_CPU1_SA_DQ<2>")
	)
	(segment
		(start 170.401996 -312.506106)
		(end 170.322494 -312.294524)
		(width 0.18288)
		(layer "In6.Cu")
		(net "M_H_CPU1_SA_DQ<2>")
	)
	(segment
		(start 199.925686 -315.295026)
		(end 198.97217 -315.295026)
		(width 0.18288)
		(layer "In6.Cu")
		(net "M_H_CPU1_SA_DQ<2>")
	)
	(segment
		(start 181.285642 -313.786012)
		(end 181.102762 -313.968892)
		(width 0.18288)
		(layer "In6.Cu")
		(net "M_H_CPU1_SA_DQ<2>")
	)
	(segment
		(start 139.920726 -282.551378)
		(end 139.661138 -282.29179)
		(width 0.088646)
		(layer "In6.Cu")
		(net "M_H_CPU1_SA_DQ<2>")
	)
	(segment
		(start 175.743362 -312.42635)
		(end 175.666654 -311.859676)
		(width 0.18288)
		(layer "In6.Cu")
		(net "M_H_CPU1_SA_DQ<2>")
	)
	(segment
		(start 139.661138 -281.892248)
		(end 139.367006 -281.182064)
		(width 0.088646)
		(layer "In6.Cu")
		(net "M_H_CPU1_SA_DQ<2>")
	)
	(segment
		(start 204.41412 -316.79388)
		(end 204.08646 -316.79388)
		(width 0.18288)
		(layer "In6.Cu")
		(net "M_H_CPU1_SA_DQ<2>")
	)
	(segment
		(start 169.0624 -312.314082)
		(end 167.343328 -312.042048)
		(width 0.18288)
		(layer "In6.Cu")
		(net "M_H_CPU1_SA_DQ<2>")
	)
	(segment
		(start 140.00353 -282.634182)
		(end 139.920726 -282.551378)
		(width 0.18288)
		(layer "In6.Cu")
		(net "M_H_CPU1_SA_DQ<2>")
	)
	(segment
		(start 134.977124 -279.46604)
		(end 134.962392 -279.474676)
		(width 0.088646)
		(layer "In6.Cu")
		(net "M_H_CPU1_SA_DQ<2>")
	)
	(segment
		(start 196.849238 -315.297312)
		(end 196.521578 -315.297312)
		(width 0.18288)
		(layer "In6.Cu")
		(net "M_H_CPU1_SA_DQ<2>")
	)
	(segment
		(start 166.758366 -311.303416)
		(end 166.549324 -311.455562)
		(width 0.18288)
		(layer "In6.Cu")
		(net "M_H_CPU1_SA_DQ<2>")
	)
	(segment
		(start 136.750044 -279.964134)
		(end 136.750044 -279.954228)
		(width 0.088646)
		(layer "In6.Cu")
		(net "M_H_CPU1_SA_DQ<2>")
	)
	(segment
		(start 169.70248 -312.429652)
		(end 169.490898 -312.509154)
		(width 0.18288)
		(layer "In6.Cu")
		(net "M_H_CPU1_SA_DQ<2>")
	)
	(segment
		(start 158.643574 -309.212234)
		(end 158.460694 -309.029354)
		(width 0.18288)
		(layer "In6.Cu")
		(net "M_H_CPU1_SA_DQ<2>")
	)
	(segment
		(start 198.97217 -315.295026)
		(end 197.84695 -315.889132)
		(width 0.18288)
		(layer "In6.Cu")
		(net "M_H_CPU1_SA_DQ<2>")
	)
	(segment
		(start 169.793666 -312.2295)
		(end 169.70248 -312.429652)
		(width 0.18288)
		(layer "In6.Cu")
		(net "M_H_CPU1_SA_DQ<2>")
	)
	(segment
		(start 180.919882 -314.380626)
		(end 180.720746 -314.380626)
		(width 0.18288)
		(layer "In6.Cu")
		(net "M_H_CPU1_SA_DQ<2>")
	)
	(segment
		(start 203.90358 -316.611)
		(end 203.90358 -316.075822)
		(width 0.18288)
		(layer "In6.Cu")
		(net "M_H_CPU1_SA_DQ<2>")
	)
	(segment
		(start 171.32427 -313.342274)
		(end 170.390312 -312.91784)
		(width 0.18288)
		(layer "In6.Cu")
		(net "M_H_CPU1_SA_DQ<2>")
	)
	(segment
		(start 207.071214 -315.46673)
		(end 206.645002 -315.892942)
		(width 0.18288)
		(layer "In6.Cu")
		(net "M_H_CPU1_SA_DQ<2>")
	)
	(segment
		(start 144.54378 -282.634182)
		(end 140.00353 -282.634182)
		(width 0.18288)
		(layer "In6.Cu")
		(net "M_H_CPU1_SA_DQ<2>")
	)
	(segment
		(start 156.818076 -309.029354)
		(end 154.195018 -306.406296)
		(width 0.18288)
		(layer "In6.Cu")
		(net "M_H_CPU1_SA_DQ<2>")
	)
	(segment
		(start 176.724056 -312.49239)
		(end 176.260506 -312.518044)
		(width 0.18288)
		(layer "In6.Cu")
		(net "M_H_CPU1_SA_DQ<2>")
	)
	(segment
		(start 159.154114 -309.865268)
		(end 158.826454 -309.865268)
		(width 0.18288)
		(layer "In6.Cu")
		(net "M_H_CPU1_SA_DQ<2>")
	)
	(segment
		(start 164.533834 -311.523634)
		(end 162.91052 -309.90032)
		(width 0.18288)
		(layer "In6.Cu")
		(net "M_H_CPU1_SA_DQ<2>")
	)
	(segment
		(start 204.597 -316.075822)
		(end 204.597 -316.611)
		(width 0.18288)
		(layer "In6.Cu")
		(net "M_H_CPU1_SA_DQ<2>")
	)
	(segment
		(start 206.645002 -315.892942)
		(end 204.77988 -315.892942)
		(width 0.18288)
		(layer "In6.Cu")
		(net "M_H_CPU1_SA_DQ<2>")
	)
	(segment
		(start 181.102762 -313.968892)
		(end 181.102762 -314.197746)
		(width 0.18288)
		(layer "In6.Cu")
		(net "M_H_CPU1_SA_DQ<2>")
	)
	(segment
		(start 166.506398 -311.724548)
		(end 166.297356 -311.876694)
		(width 0.18288)
		(layer "In6.Cu")
		(net "M_H_CPU1_SA_DQ<2>")
	)
	(segment
		(start 197.84695 -315.889132)
		(end 197.214998 -315.889132)
		(width 0.18288)
		(layer "In6.Cu")
		(net "M_H_CPU1_SA_DQ<2>")
	)
	(segment
		(start 181.979062 -314.380626)
		(end 181.796182 -314.197746)
		(width 0.18288)
		(layer "In6.Cu")
		(net "M_H_CPU1_SA_DQ<2>")
	)
	(segment
		(start 183.923686 -315.127386)
		(end 183.176926 -314.380626)
		(width 0.18288)
		(layer "In6.Cu")
		(net "M_H_CPU1_SA_DQ<2>")
	)
	(segment
		(start 190.175896 -315.889132)
		(end 188.116718 -316.742318)
		(width 0.18288)
		(layer "In6.Cu")
		(net "M_H_CPU1_SA_DQ<2>")
	)
	(segment
		(start 175.923194 -312.56351)
		(end 175.743362 -312.42635)
		(width 0.18288)
		(layer "In6.Cu")
		(net "M_H_CPU1_SA_DQ<2>")
	)
	(segment
		(start 162.91052 -309.90032)
		(end 161.357056 -309.90032)
		(width 0.18288)
		(layer "In6.Cu")
		(net "M_H_CPU1_SA_DQ<2>")
	)
	(segment
		(start 175.666654 -311.859676)
		(end 175.486822 -311.722516)
		(width 0.18288)
		(layer "In6.Cu")
		(net "M_H_CPU1_SA_DQ<2>")
	)
	(segment
		(start 137.219944 -280.778204)
		(end 137.219944 -280.759662)
		(width 0.088646)
		(layer "In6.Cu")
		(net "M_H_CPU1_SA_DQ<2>")
	)
	(segment
		(start 197.032118 -315.480192)
		(end 196.849238 -315.297312)
		(width 0.18288)
		(layer "In6.Cu")
		(net "M_H_CPU1_SA_DQ<2>")
	)
	(segment
		(start 164.72281 -311.627266)
		(end 164.533834 -311.523634)
		(width 0.18288)
		(layer "In6.Cu")
		(net "M_H_CPU1_SA_DQ<2>")
	)
	(segment
		(start 173.115478 -313.315858)
		(end 173.051978 -313.342274)
		(width 0.18288)
		(layer "In6.Cu")
		(net "M_H_CPU1_SA_DQ<2>")
	)
	(segment
		(start 159.336994 -309.212234)
		(end 159.336994 -309.682388)
		(width 0.18288)
		(layer "In6.Cu")
		(net "M_H_CPU1_SA_DQ<2>")
	)
	(segment
		(start 167.234362 -311.56402)
		(end 167.082216 -311.354978)
		(width 0.18288)
		(layer "In6.Cu")
		(net "M_H_CPU1_SA_DQ<2>")
	)
	(segment
		(start 203.90358 -316.075822)
		(end 203.7207 -315.892942)
		(width 0.18288)
		(layer "In6.Cu")
		(net "M_H_CPU1_SA_DQ<2>")
	)
	(segment
		(start 184.505346 -315.295026)
		(end 183.923686 -315.127386)
		(width 0.18288)
		(layer "In6.Cu")
		(net "M_H_CPU1_SA_DQ<2>")
	)
	(segment
		(start 133.648196 -279.474676)
		(end 133.637782 -279.46858)
		(width 0.088646)
		(layer "In6.Cu")
		(net "M_H_CPU1_SA_DQ<2>")
	)
	(segment
		(start 175.004476 -311.949338)
		(end 175.081184 -312.516012)
		(width 0.18288)
		(layer "In6.Cu")
		(net "M_H_CPU1_SA_DQ<2>")
	)
	(segment
		(start 169.490898 -312.509154)
		(end 169.0624 -312.314082)
		(width 0.18288)
		(layer "In6.Cu")
		(net "M_H_CPU1_SA_DQ<2>")
	)
	(segment
		(start 137.792206 -281.096466)
		(end 137.781792 -281.102562)
		(width 0.088646)
		(layer "In6.Cu")
		(net "M_H_CPU1_SA_DQ<2>")
	)
	(segment
		(start 131.76885 -279.474676)
		(end 131.758436 -279.46858)
		(width 0.088646)
		(layer "In6.Cu")
		(net "M_H_CPU1_SA_DQ<2>")
	)
	(segment
		(start 175.081184 -312.516012)
		(end 174.944024 -312.695844)
		(width 0.18288)
		(layer "In6.Cu")
		(net "M_H_CPU1_SA_DQ<2>")
	)
	(segment
		(start 203.7207 -315.892942)
		(end 201.404728 -315.892942)
		(width 0.18288)
		(layer "In6.Cu")
		(net "M_H_CPU1_SA_DQ<2>")
	)
	(segment
		(start 138.73226 -281.096466)
		(end 138.721846 -281.102562)
		(width 0.088646)
		(layer "In6.Cu")
		(net "M_H_CPU1_SA_DQ<2>")
	)
	(segment
		(start 181.796182 -313.968892)
		(end 181.613302 -313.786012)
		(width 0.18288)
		(layer "In6.Cu")
		(net "M_H_CPU1_SA_DQ<2>")
	)
	(segment
		(start 201.404728 -315.892942)
		(end 199.925686 -315.295026)
		(width 0.18288)
		(layer "In6.Cu")
		(net "M_H_CPU1_SA_DQ<2>")
	)
	(segment
		(start 159.519874 -309.029354)
		(end 159.336994 -309.212234)
		(width 0.18288)
		(layer "In6.Cu")
		(net "M_H_CPU1_SA_DQ<2>")
	)
	(segment
		(start 139.367006 -281.182064)
		(end 139.287504 -281.102562)
		(width 0.088646)
		(layer "In6.Cu")
		(net "M_H_CPU1_SA_DQ<2>")
	)
	(segment
		(start 167.343328 -312.042048)
		(end 167.191436 -311.83326)
		(width 0.18288)
		(layer "In6.Cu")
		(net "M_H_CPU1_SA_DQ<2>")
	)
	(segment
		(start 173.051978 -313.342274)
		(end 171.32427 -313.342274)
		(width 0.18288)
		(layer "In6.Cu")
		(net "M_H_CPU1_SA_DQ<2>")
	)
	(segment
		(start 158.643574 -309.682388)
		(end 158.643574 -309.212234)
		(width 0.18288)
		(layer "In6.Cu")
		(net "M_H_CPU1_SA_DQ<2>")
	)
	(segment
		(start 158.460694 -309.029354)
		(end 156.818076 -309.029354)
		(width 0.18288)
		(layer "In6.Cu")
		(net "M_H_CPU1_SA_DQ<2>")
	)
	(segment
		(start 188.116718 -316.742318)
		(end 186.376818 -316.742318)
		(width 0.18288)
		(layer "In6.Cu")
		(net "M_H_CPU1_SA_DQ<2>")
	)
	(segment
		(start 181.102762 -314.197746)
		(end 180.919882 -314.380626)
		(width 0.18288)
		(layer "In6.Cu")
		(net "M_H_CPU1_SA_DQ<2>")
	)
	(segment
		(start 158.826454 -309.865268)
		(end 158.643574 -309.682388)
		(width 0.18288)
		(layer "In6.Cu")
		(net "M_H_CPU1_SA_DQ<2>")
	)
	(segment
		(start 197.032118 -315.706252)
		(end 197.032118 -315.480192)
		(width 0.18288)
		(layer "In6.Cu")
		(net "M_H_CPU1_SA_DQ<2>")
	)
	(segment
		(start 177.403506 -312.49239)
		(end 176.724056 -312.49239)
		(width 0.18288)
		(layer "In6.Cu")
		(net "M_H_CPU1_SA_DQ<2>")
	)
	(segment
		(start 196.521578 -315.297312)
		(end 196.338698 -315.480192)
		(width 0.18288)
		(layer "In6.Cu")
		(net "M_H_CPU1_SA_DQ<2>")
	)
	(segment
		(start 179.68087 -313.781186)
		(end 177.403506 -312.49239)
		(width 0.18288)
		(layer "In6.Cu")
		(net "M_H_CPU1_SA_DQ<2>")
	)
	(segment
		(start 196.155818 -315.889132)
		(end 190.175896 -315.889132)
		(width 0.18288)
		(layer "In6.Cu")
		(net "M_H_CPU1_SA_DQ<2>")
	)
	(segment
		(start 159.336994 -309.682388)
		(end 159.154114 -309.865268)
		(width 0.18288)
		(layer "In6.Cu")
		(net "M_H_CPU1_SA_DQ<2>")
	)
	(segment
		(start 181.796182 -314.197746)
		(end 181.796182 -313.968892)
		(width 0.18288)
		(layer "In6.Cu")
		(net "M_H_CPU1_SA_DQ<2>")
	)
	(segment
		(start 154.195018 -306.406296)
		(end 154.195018 -301.735744)
		(width 0.18288)
		(layer "In6.Cu")
		(net "M_H_CPU1_SA_DQ<2>")
	)
	(segment
		(start 197.214998 -315.889132)
		(end 197.032118 -315.706252)
		(width 0.18288)
		(layer "In6.Cu")
		(net "M_H_CPU1_SA_DQ<2>")
	)
	(segment
		(start 146.360642 -293.901368)
		(end 146.360642 -284.451044)
		(width 0.18288)
		(layer "In6.Cu")
		(net "M_H_CPU1_SA_DQ<2>")
	)
	(segment
		(start 175.141636 -311.769506)
		(end 175.004476 -311.949338)
		(width 0.18288)
		(layer "In6.Cu")
		(net "M_H_CPU1_SA_DQ<2>")
	)
	(segment
		(start 154.195018 -301.735744)
		(end 146.360642 -293.901368)
		(width 0.18288)
		(layer "In6.Cu")
		(net "M_H_CPU1_SA_DQ<2>")
	)
	(segment
		(start 137.407396 -281.102562)
		(end 137.398506 -281.097482)
		(width 0.088646)
		(layer "In6.Cu")
		(net "M_H_CPU1_SA_DQ<2>")
	)
	(segment
		(start 136.937496 -280.288492)
		(end 136.928606 -280.283412)
		(width 0.088646)
		(layer "In6.Cu")
		(net "M_H_CPU1_SA_DQ<2>")
	)
	(arc
		(start 131.758436 -279.46858)
		(mid 131.51273 -279.399326)
		(end 131.261612 -279.445212)
		(width 0.088646)
		(layer "In6.Cu")
		(net "M_H_CPU1_SA_DQ<2>")
	)
	(arc
		(start 136.750044 -279.954228)
		(mid 136.671933 -279.677279)
		(end 136.467596 -279.474676)
		(width 0.088646)
		(layer "In6.Cu")
		(net "M_H_CPU1_SA_DQ<2>")
	)
	(arc
		(start 134.573264 -279.46604)
		(mid 134.296789 -279.39872)
		(end 134.022592 -279.474676)
		(width 0.088646)
		(layer "In6.Cu")
		(net "M_H_CPU1_SA_DQ<2>")
	)
	(arc
		(start 136.467596 -279.474676)
		(mid 136.184894 -279.3989)
		(end 135.902192 -279.474676)
		(width 0.088646)
		(layer "In6.Cu")
		(net "M_H_CPU1_SA_DQ<2>")
	)
	(arc
		(start 132.70865 -279.474676)
		(mid 132.434451 -279.398841)
		(end 132.157978 -279.46604)
		(width 0.088646)
		(layer "In6.Cu")
		(net "M_H_CPU1_SA_DQ<2>")
	)
	(arc
		(start 137.398506 -281.097482)
		(mid 137.267592 -280.961122)
		(end 137.219944 -280.778204)
		(width 0.088646)
		(layer "In6.Cu")
		(net "M_H_CPU1_SA_DQ<2>")
	)
	(arc
		(start 133.637782 -279.46858)
		(mid 133.359604 -279.398857)
		(end 133.083046 -279.474676)
		(width 0.088646)
		(layer "In6.Cu")
		(net "M_H_CPU1_SA_DQ<2>")
	)
	(arc
		(start 138.34745 -281.102562)
		(mid 138.070637 -281.026692)
		(end 137.792206 -281.096466)
		(width 0.088646)
		(layer "In6.Cu")
		(net "M_H_CPU1_SA_DQ<2>")
	)
	(arc
		(start 133.083046 -279.474676)
		(mid 132.895848 -279.524819)
		(end 132.70865 -279.474676)
		(width 0.088646)
		(layer "In6.Cu")
		(net "M_H_CPU1_SA_DQ<2>")
	)
	(arc
		(start 135.902192 -279.474676)
		(mid 135.714994 -279.524819)
		(end 135.527796 -279.474676)
		(width 0.088646)
		(layer "In6.Cu")
		(net "M_H_CPU1_SA_DQ<2>")
	)
	(arc
		(start 132.143246 -279.474676)
		(mid 131.956048 -279.524819)
		(end 131.76885 -279.474676)
		(width 0.088646)
		(layer "In6.Cu")
		(net "M_H_CPU1_SA_DQ<2>")
	)
	(arc
		(start 138.721846 -281.102562)
		(mid 138.534648 -281.152705)
		(end 138.34745 -281.102562)
		(width 0.088646)
		(layer "In6.Cu")
		(net "M_H_CPU1_SA_DQ<2>")
	)
	(arc
		(start 134.962392 -279.474676)
		(mid 134.775194 -279.524819)
		(end 134.587996 -279.474676)
		(width 0.088646)
		(layer "In6.Cu")
		(net "M_H_CPU1_SA_DQ<2>")
	)
	(arc
		(start 139.287504 -281.102562)
		(mid 139.010691 -281.026692)
		(end 138.73226 -281.096466)
		(width 0.088646)
		(layer "In6.Cu")
		(net "M_H_CPU1_SA_DQ<2>")
	)
	(arc
		(start 135.527796 -279.474676)
		(mid 135.253597 -279.398841)
		(end 134.977124 -279.46604)
		(width 0.088646)
		(layer "In6.Cu")
		(net "M_H_CPU1_SA_DQ<2>")
	)
	(arc
		(start 137.781792 -281.102562)
		(mid 137.594594 -281.152705)
		(end 137.407396 -281.102562)
		(width 0.088646)
		(layer "In6.Cu")
		(net "M_H_CPU1_SA_DQ<2>")
	)
	(arc
		(start 136.928606 -280.283412)
		(mid 136.797692 -280.147052)
		(end 136.750044 -279.964134)
		(width 0.088646)
		(layer "In6.Cu")
		(net "M_H_CPU1_SA_DQ<2>")
	)
	(arc
		(start 134.022592 -279.474676)
		(mid 133.835394 -279.524819)
		(end 133.648196 -279.474676)
		(width 0.088646)
		(layer "In6.Cu")
		(net "M_H_CPU1_SA_DQ<2>")
	)
	(arc
		(start 137.219944 -280.759662)
		(mid 137.139782 -280.487473)
		(end 136.937496 -280.288492)
		(width 0.088646)
		(layer "In6.Cu")
		(net "M_H_CPU1_SA_DQ<2>")
	)
	(segment
		(start 209.596482 -280.185368)
		(end 209.186526 -280.185368)
		(width 0.20066)
		(layer "F.Cu")
		(net "M_H_CPU1_SA_DQ<29>")
	)
	(segment
		(start 209.180176 -280.191718)
		(end 206.991458 -280.191718)
		(width 0.1016)
		(layer "F.Cu")
		(net "M_H_CPU1_SA_DQ<29>")
	)
	(segment
		(start 206.320644 -280.865326)
		(end 205.84541 -280.865326)
		(width 0.20066)
		(layer "F.Cu")
		(net "M_H_CPU1_SA_DQ<29>")
	)
	(segment
		(start 210.028028 -280.616914)
		(end 209.596482 -280.185368)
		(width 0.20066)
		(layer "F.Cu")
		(net "M_H_CPU1_SA_DQ<29>")
	)
	(segment
		(start 123.967494 -263.68629)
		(end 123.967748 -263.686544)
		(width 0.20066)
		(layer "F.Cu")
		(net "M_H_CPU1_SA_DQ<29>")
	)
	(segment
		(start 123.967494 -263.150604)
		(end 123.967494 -263.68629)
		(width 0.20066)
		(layer "F.Cu")
		(net "M_H_CPU1_SA_DQ<29>")
	)
	(segment
		(start 205.596744 -280.61666)
		(end 204.076046 -280.61666)
		(width 0.20066)
		(layer "F.Cu")
		(net "M_H_CPU1_SA_DQ<29>")
	)
	(segment
		(start 206.626714 -280.191718)
		(end 206.508604 -280.309828)
		(width 0.20066)
		(layer "F.Cu")
		(net "M_H_CPU1_SA_DQ<29>")
	)
	(segment
		(start 206.971392 -280.191718)
		(end 206.626714 -280.191718)
		(width 0.20066)
		(layer "F.Cu")
		(net "M_H_CPU1_SA_DQ<29>")
	)
	(segment
		(start 206.508604 -280.677366)
		(end 206.320644 -280.865326)
		(width 0.20066)
		(layer "F.Cu")
		(net "M_H_CPU1_SA_DQ<29>")
	)
	(segment
		(start 204.076046 -280.61666)
		(end 202.971146 -280.61666)
		(width 0.20066)
		(layer "F.Cu")
		(net "M_H_CPU1_SA_DQ<29>")
	)
	(segment
		(start 209.186526 -280.185368)
		(end 209.180176 -280.191718)
		(width 0.1016)
		(layer "F.Cu")
		(net "M_H_CPU1_SA_DQ<29>")
	)
	(segment
		(start 211.619846 -280.61666)
		(end 211.619592 -280.616914)
		(width 0.20066)
		(layer "F.Cu")
		(net "M_H_CPU1_SA_DQ<29>")
	)
	(segment
		(start 206.508604 -280.309828)
		(end 206.508604 -280.677366)
		(width 0.20066)
		(layer "F.Cu")
		(net "M_H_CPU1_SA_DQ<29>")
	)
	(segment
		(start 211.619592 -280.616914)
		(end 210.028028 -280.616914)
		(width 0.20066)
		(layer "F.Cu")
		(net "M_H_CPU1_SA_DQ<29>")
	)
	(segment
		(start 206.991458 -280.191718)
		(end 206.971392 -280.191718)
		(width 0.101854)
		(layer "F.Cu")
		(net "M_H_CPU1_SA_DQ<29>")
	)
	(segment
		(start 205.84541 -280.865326)
		(end 205.596744 -280.61666)
		(width 0.20066)
		(layer "F.Cu")
		(net "M_H_CPU1_SA_DQ<29>")
	)
	(segment
		(start 185.858404 -282.05303)
		(end 185.665364 -281.85999)
		(width 0.18288)
		(layer "In11.Cu")
		(net "M_H_CPU1_SA_DQ<29>")
	)
	(segment
		(start 126.049278 -263.370822)
		(end 126.034546 -263.362186)
		(width 0.088646)
		(layer "In11.Cu")
		(net "M_H_CPU1_SA_DQ<29>")
	)
	(segment
		(start 160.761426 -279.836626)
		(end 160.245552 -279.320752)
		(width 0.18288)
		(layer "In11.Cu")
		(net "M_H_CPU1_SA_DQ<29>")
	)
	(segment
		(start 136.372346 -264.989818)
		(end 136.36625 -264.986262)
		(width 0.088646)
		(layer "In11.Cu")
		(net "M_H_CPU1_SA_DQ<29>")
	)
	(segment
		(start 196.97065 -282.951936)
		(end 196.77761 -283.144976)
		(width 0.18288)
		(layer "In11.Cu")
		(net "M_H_CPU1_SA_DQ<29>")
	)
	(segment
		(start 165.895782 -281.944826)
		(end 164.723826 -281.944826)
		(width 0.18288)
		(layer "In11.Cu")
		(net "M_H_CPU1_SA_DQ<29>")
	)
	(segment
		(start 144.259808 -267.039852)
		(end 140.087604 -267.039852)
		(width 0.18288)
		(layer "In11.Cu")
		(net "M_H_CPU1_SA_DQ<29>")
	)
	(segment
		(start 175.320706 -283.829252)
		(end 174.497746 -283.829252)
		(width 0.18288)
		(layer "In11.Cu")
		(net "M_H_CPU1_SA_DQ<29>")
	)
	(segment
		(start 197.16369 -282.478226)
		(end 196.97065 -282.671266)
		(width 0.18288)
		(layer "In11.Cu")
		(net "M_H_CPU1_SA_DQ<29>")
	)
	(segment
		(start 185.154824 -282.793186)
		(end 184.961784 -282.986226)
		(width 0.18288)
		(layer "In11.Cu")
		(net "M_H_CPU1_SA_DQ<29>")
	)
	(segment
		(start 191.185038 -283.88691)
		(end 190.867538 -283.88691)
		(width 0.18288)
		(layer "In11.Cu")
		(net "M_H_CPU1_SA_DQ<29>")
	)
	(segment
		(start 163.017708 -281.174444)
		(end 161.71799 -281.174444)
		(width 0.18288)
		(layer "In11.Cu")
		(net "M_H_CPU1_SA_DQ<29>")
	)
	(segment
		(start 128.86436 -263.368282)
		(end 128.853946 -263.362186)
		(width 0.088646)
		(layer "In11.Cu")
		(net "M_H_CPU1_SA_DQ<29>")
	)
	(segment
		(start 140.087604 -267.039852)
		(end 139.976352 -267.039852)
		(width 0.088646)
		(layer "In11.Cu")
		(net "M_H_CPU1_SA_DQ<29>")
	)
	(segment
		(start 183.477916 -282.563316)
		(end 180.234082 -282.563316)
		(width 0.18288)
		(layer "In11.Cu")
		(net "M_H_CPU1_SA_DQ<29>")
	)
	(segment
		(start 186.655202 -282.986226)
		(end 186.051444 -282.986226)
		(width 0.18288)
		(layer "In11.Cu")
		(net "M_H_CPU1_SA_DQ<29>")
	)
	(segment
		(start 136.559798 -265.336274)
		(end 136.559798 -265.314176)
		(width 0.088646)
		(layer "In11.Cu")
		(net "M_H_CPU1_SA_DQ<29>")
	)
	(segment
		(start 190.867538 -283.88691)
		(end 190.674498 -283.69387)
		(width 0.18288)
		(layer "In11.Cu")
		(net "M_H_CPU1_SA_DQ<29>")
	)
	(segment
		(start 137.781792 -265.804142)
		(end 137.77087 -265.797792)
		(width 0.088646)
		(layer "In11.Cu")
		(net "M_H_CPU1_SA_DQ<29>")
	)
	(segment
		(start 189.237366 -282.734766)
		(end 188.391546 -281.888946)
		(width 0.18288)
		(layer "In11.Cu")
		(net "M_H_CPU1_SA_DQ<29>")
	)
	(segment
		(start 202.971146 -280.61666)
		(end 202.451208 -281.136598)
		(width 0.18288)
		(layer "In11.Cu")
		(net "M_H_CPU1_SA_DQ<29>")
	)
	(segment
		(start 176.40681 -282.743148)
		(end 175.320706 -283.829252)
		(width 0.18288)
		(layer "In11.Cu")
		(net "M_H_CPU1_SA_DQ<29>")
	)
	(segment
		(start 132.627878 -263.370822)
		(end 132.613146 -263.362186)
		(width 0.088646)
		(layer "In11.Cu")
		(net "M_H_CPU1_SA_DQ<29>")
	)
	(segment
		(start 186.051444 -282.986226)
		(end 185.858404 -282.793186)
		(width 0.18288)
		(layer "In11.Cu")
		(net "M_H_CPU1_SA_DQ<29>")
	)
	(segment
		(start 196.77761 -283.144976)
		(end 196.46011 -283.144976)
		(width 0.18288)
		(layer "In11.Cu")
		(net "M_H_CPU1_SA_DQ<29>")
	)
	(segment
		(start 192.916556 -282.739846)
		(end 191.571118 -282.739846)
		(width 0.18288)
		(layer "In11.Cu")
		(net "M_H_CPU1_SA_DQ<29>")
	)
	(segment
		(start 196.07403 -282.478226)
		(end 194.864228 -282.478226)
		(width 0.18288)
		(layer "In11.Cu")
		(net "M_H_CPU1_SA_DQ<29>")
	)
	(segment
		(start 185.858404 -282.793186)
		(end 185.858404 -282.05303)
		(width 0.18288)
		(layer "In11.Cu")
		(net "M_H_CPU1_SA_DQ<29>")
	)
	(segment
		(start 166.985442 -281.944826)
		(end 166.792402 -281.751786)
		(width 0.18288)
		(layer "In11.Cu")
		(net "M_H_CPU1_SA_DQ<29>")
	)
	(segment
		(start 125.189996 -264.176002)
		(end 125.175264 -264.184638)
		(width 0.088646)
		(layer "In11.Cu")
		(net "M_H_CPU1_SA_DQ<29>")
	)
	(segment
		(start 183.900826 -282.986226)
		(end 183.477916 -282.563316)
		(width 0.18288)
		(layer "In11.Cu")
		(net "M_H_CPU1_SA_DQ<29>")
	)
	(segment
		(start 196.97065 -282.671266)
		(end 196.97065 -282.951936)
		(width 0.18288)
		(layer "In11.Cu")
		(net "M_H_CPU1_SA_DQ<29>")
	)
	(segment
		(start 185.154824 -282.05303)
		(end 185.154824 -282.793186)
		(width 0.18288)
		(layer "In11.Cu")
		(net "M_H_CPU1_SA_DQ<29>")
	)
	(segment
		(start 161.71799 -281.174444)
		(end 160.761426 -280.21788)
		(width 0.18288)
		(layer "In11.Cu")
		(net "M_H_CPU1_SA_DQ<29>")
	)
	(segment
		(start 135.441182 -263.367266)
		(end 135.432292 -263.362186)
		(width 0.088646)
		(layer "In11.Cu")
		(net "M_H_CPU1_SA_DQ<29>")
	)
	(segment
		(start 125.196092 -264.172446)
		(end 125.189996 -264.176002)
		(width 0.088646)
		(layer "In11.Cu")
		(net "M_H_CPU1_SA_DQ<29>")
	)
	(segment
		(start 166.792402 -281.379676)
		(end 166.599362 -281.186636)
		(width 0.18288)
		(layer "In11.Cu")
		(net "M_H_CPU1_SA_DQ<29>")
	)
	(segment
		(start 136.381236 -264.994898)
		(end 136.372346 -264.989818)
		(width 0.088646)
		(layer "In11.Cu")
		(net "M_H_CPU1_SA_DQ<29>")
	)
	(segment
		(start 174.260256 -283.591762)
		(end 171.467018 -283.591762)
		(width 0.18288)
		(layer "In11.Cu")
		(net "M_H_CPU1_SA_DQ<29>")
	)
	(segment
		(start 170.738546 -282.86329)
		(end 168.99509 -282.86329)
		(width 0.18288)
		(layer "In11.Cu")
		(net "M_H_CPU1_SA_DQ<29>")
	)
	(segment
		(start 198.099426 -282.478226)
		(end 197.16369 -282.478226)
		(width 0.18288)
		(layer "In11.Cu")
		(net "M_H_CPU1_SA_DQ<29>")
	)
	(segment
		(start 196.46011 -283.144976)
		(end 196.26707 -282.951936)
		(width 0.18288)
		(layer "In11.Cu")
		(net "M_H_CPU1_SA_DQ<29>")
	)
	(segment
		(start 202.451208 -281.136598)
		(end 200.595738 -281.136598)
		(width 0.18288)
		(layer "In11.Cu")
		(net "M_H_CPU1_SA_DQ<29>")
	)
	(segment
		(start 190.674498 -283.69387)
		(end 190.674498 -282.927806)
		(width 0.18288)
		(layer "In11.Cu")
		(net "M_H_CPU1_SA_DQ<29>")
	)
	(segment
		(start 127.928878 -263.370822)
		(end 127.914146 -263.362186)
		(width 0.088646)
		(layer "In11.Cu")
		(net "M_H_CPU1_SA_DQ<29>")
	)
	(segment
		(start 194.864228 -282.478226)
		(end 194.212718 -283.129736)
		(width 0.18288)
		(layer "In11.Cu")
		(net "M_H_CPU1_SA_DQ<29>")
	)
	(segment
		(start 199.970644 -281.761692)
		(end 198.81596 -281.761692)
		(width 0.18288)
		(layer "In11.Cu")
		(net "M_H_CPU1_SA_DQ<29>")
	)
	(segment
		(start 185.347864 -281.85999)
		(end 185.154824 -282.05303)
		(width 0.18288)
		(layer "In11.Cu")
		(net "M_H_CPU1_SA_DQ<29>")
	)
	(segment
		(start 160.245552 -279.320752)
		(end 156.540708 -279.320752)
		(width 0.18288)
		(layer "In11.Cu")
		(net "M_H_CPU1_SA_DQ<29>")
	)
	(segment
		(start 166.792402 -281.751786)
		(end 166.792402 -281.379676)
		(width 0.18288)
		(layer "In11.Cu")
		(net "M_H_CPU1_SA_DQ<29>")
	)
	(segment
		(start 178.499516 -282.743148)
		(end 176.40681 -282.743148)
		(width 0.18288)
		(layer "In11.Cu")
		(net "M_H_CPU1_SA_DQ<29>")
	)
	(segment
		(start 184.961784 -282.986226)
		(end 183.900826 -282.986226)
		(width 0.18288)
		(layer "In11.Cu")
		(net "M_H_CPU1_SA_DQ<29>")
	)
	(segment
		(start 190.481458 -282.734766)
		(end 189.237366 -282.734766)
		(width 0.18288)
		(layer "In11.Cu")
		(net "M_H_CPU1_SA_DQ<29>")
	)
	(segment
		(start 137.407396 -265.803888)
		(end 137.392664 -265.812524)
		(width 0.088646)
		(layer "In11.Cu")
		(net "M_H_CPU1_SA_DQ<29>")
	)
	(segment
		(start 166.281862 -281.186636)
		(end 166.088822 -281.379676)
		(width 0.18288)
		(layer "In11.Cu")
		(net "M_H_CPU1_SA_DQ<29>")
	)
	(segment
		(start 194.212718 -283.129736)
		(end 193.306446 -283.129736)
		(width 0.18288)
		(layer "In11.Cu")
		(net "M_H_CPU1_SA_DQ<29>")
	)
	(segment
		(start 191.571118 -282.739846)
		(end 191.378078 -282.932886)
		(width 0.18288)
		(layer "In11.Cu")
		(net "M_H_CPU1_SA_DQ<29>")
	)
	(segment
		(start 196.26707 -282.951936)
		(end 196.26707 -282.671266)
		(width 0.18288)
		(layer "In11.Cu")
		(net "M_H_CPU1_SA_DQ<29>")
	)
	(segment
		(start 188.391546 -281.888946)
		(end 187.34278 -281.888946)
		(width 0.18288)
		(layer "In11.Cu")
		(net "M_H_CPU1_SA_DQ<29>")
	)
	(segment
		(start 156.540708 -279.320752)
		(end 144.259808 -267.039852)
		(width 0.18288)
		(layer "In11.Cu")
		(net "M_H_CPU1_SA_DQ<29>")
	)
	(segment
		(start 200.595738 -281.136598)
		(end 199.970644 -281.761692)
		(width 0.18288)
		(layer "In11.Cu")
		(net "M_H_CPU1_SA_DQ<29>")
	)
	(segment
		(start 166.088822 -281.751786)
		(end 165.895782 -281.944826)
		(width 0.18288)
		(layer "In11.Cu")
		(net "M_H_CPU1_SA_DQ<29>")
	)
	(segment
		(start 135.619744 -263.69645)
		(end 135.619744 -263.686544)
		(width 0.088646)
		(layer "In11.Cu")
		(net "M_H_CPU1_SA_DQ<29>")
	)
	(segment
		(start 135.911082 -264.181082)
		(end 135.902192 -264.176002)
		(width 0.088646)
		(layer "In11.Cu")
		(net "M_H_CPU1_SA_DQ<29>")
	)
	(segment
		(start 125.66015 -263.362186)
		(end 125.65126 -263.367266)
		(width 0.088646)
		(layer "In11.Cu")
		(net "M_H_CPU1_SA_DQ<29>")
	)
	(segment
		(start 198.81596 -281.761692)
		(end 198.099426 -282.478226)
		(width 0.18288)
		(layer "In11.Cu")
		(net "M_H_CPU1_SA_DQ<29>")
	)
	(segment
		(start 191.378078 -283.69387)
		(end 191.185038 -283.88691)
		(width 0.18288)
		(layer "In11.Cu")
		(net "M_H_CPU1_SA_DQ<29>")
	)
	(segment
		(start 171.467018 -283.591762)
		(end 170.738546 -282.86329)
		(width 0.18288)
		(layer "In11.Cu")
		(net "M_H_CPU1_SA_DQ<29>")
	)
	(segment
		(start 124.280676 -263.686544)
		(end 123.967748 -263.686544)
		(width 0.088646)
		(layer "In11.Cu")
		(net "M_H_CPU1_SA_DQ<29>")
	)
	(segment
		(start 193.306446 -283.129736)
		(end 192.916556 -282.739846)
		(width 0.18288)
		(layer "In11.Cu")
		(net "M_H_CPU1_SA_DQ<29>")
	)
	(segment
		(start 191.378078 -282.932886)
		(end 191.378078 -283.69387)
		(width 0.18288)
		(layer "In11.Cu")
		(net "M_H_CPU1_SA_DQ<29>")
	)
	(segment
		(start 196.26707 -282.671266)
		(end 196.07403 -282.478226)
		(width 0.18288)
		(layer "In11.Cu")
		(net "M_H_CPU1_SA_DQ<29>")
	)
	(segment
		(start 124.345954 -263.751822)
		(end 124.280676 -263.686544)
		(width 0.088646)
		(layer "In11.Cu")
		(net "M_H_CPU1_SA_DQ<29>")
	)
	(segment
		(start 190.674498 -282.927806)
		(end 190.481458 -282.734766)
		(width 0.18288)
		(layer "In11.Cu")
		(net "M_H_CPU1_SA_DQ<29>")
	)
	(segment
		(start 164.723826 -281.944826)
		(end 164.419026 -281.640026)
		(width 0.18288)
		(layer "In11.Cu")
		(net "M_H_CPU1_SA_DQ<29>")
	)
	(segment
		(start 187.34278 -281.888946)
		(end 187.21959 -282.012136)
		(width 0.18288)
		(layer "In11.Cu")
		(net "M_H_CPU1_SA_DQ<29>")
	)
	(segment
		(start 166.088822 -281.379676)
		(end 166.088822 -281.751786)
		(width 0.18288)
		(layer "In11.Cu")
		(net "M_H_CPU1_SA_DQ<29>")
	)
	(segment
		(start 160.761426 -280.21788)
		(end 160.761426 -279.836626)
		(width 0.18288)
		(layer "In11.Cu")
		(net "M_H_CPU1_SA_DQ<29>")
	)
	(segment
		(start 129.803906 -263.368282)
		(end 129.793492 -263.362186)
		(width 0.088646)
		(layer "In11.Cu")
		(net "M_H_CPU1_SA_DQ<29>")
	)
	(segment
		(start 179.633372 -283.164026)
		(end 178.920394 -283.164026)
		(width 0.18288)
		(layer "In11.Cu")
		(net "M_H_CPU1_SA_DQ<29>")
	)
	(segment
		(start 168.076626 -281.944826)
		(end 166.985442 -281.944826)
		(width 0.18288)
		(layer "In11.Cu")
		(net "M_H_CPU1_SA_DQ<29>")
	)
	(segment
		(start 134.50316 -263.368282)
		(end 134.492746 -263.362186)
		(width 0.088646)
		(layer "In11.Cu")
		(net "M_H_CPU1_SA_DQ<29>")
	)
	(segment
		(start 185.665364 -281.85999)
		(end 185.347864 -281.85999)
		(width 0.18288)
		(layer "In11.Cu")
		(net "M_H_CPU1_SA_DQ<29>")
	)
	(segment
		(start 126.989078 -263.370822)
		(end 126.9746 -263.362186)
		(width 0.088646)
		(layer "In11.Cu")
		(net "M_H_CPU1_SA_DQ<29>")
	)
	(segment
		(start 174.497746 -283.829252)
		(end 174.260256 -283.591762)
		(width 0.18288)
		(layer "In11.Cu")
		(net "M_H_CPU1_SA_DQ<29>")
	)
	(segment
		(start 166.599362 -281.186636)
		(end 166.281862 -281.186636)
		(width 0.18288)
		(layer "In11.Cu")
		(net "M_H_CPU1_SA_DQ<29>")
	)
	(segment
		(start 163.48329 -281.640026)
		(end 163.017708 -281.174444)
		(width 0.18288)
		(layer "In11.Cu")
		(net "M_H_CPU1_SA_DQ<29>")
	)
	(segment
		(start 133.567678 -263.370822)
		(end 133.552946 -263.362186)
		(width 0.088646)
		(layer "In11.Cu")
		(net "M_H_CPU1_SA_DQ<29>")
	)
	(segment
		(start 187.21959 -282.012136)
		(end 187.21959 -282.421838)
		(width 0.18288)
		(layer "In11.Cu")
		(net "M_H_CPU1_SA_DQ<29>")
	)
	(segment
		(start 164.419026 -281.640026)
		(end 163.48329 -281.640026)
		(width 0.18288)
		(layer "In11.Cu")
		(net "M_H_CPU1_SA_DQ<29>")
	)
	(segment
		(start 139.976352 -267.039852)
		(end 138.79957 -265.86307)
		(width 0.088646)
		(layer "In11.Cu")
		(net "M_H_CPU1_SA_DQ<29>")
	)
	(segment
		(start 130.748278 -263.370822)
		(end 130.733546 -263.362186)
		(width 0.088646)
		(layer "In11.Cu")
		(net "M_H_CPU1_SA_DQ<29>")
	)
	(segment
		(start 168.99509 -282.86329)
		(end 168.076626 -281.944826)
		(width 0.18288)
		(layer "In11.Cu")
		(net "M_H_CPU1_SA_DQ<29>")
	)
	(segment
		(start 187.21959 -282.421838)
		(end 186.655202 -282.986226)
		(width 0.18288)
		(layer "In11.Cu")
		(net "M_H_CPU1_SA_DQ<29>")
	)
	(segment
		(start 178.920394 -283.164026)
		(end 178.499516 -282.743148)
		(width 0.18288)
		(layer "In11.Cu")
		(net "M_H_CPU1_SA_DQ<29>")
	)
	(segment
		(start 180.234082 -282.563316)
		(end 179.633372 -283.164026)
		(width 0.18288)
		(layer "In11.Cu")
		(net "M_H_CPU1_SA_DQ<29>")
	)
	(arc
		(start 134.492746 -263.362186)
		(mid 134.305548 -263.312043)
		(end 134.11835 -263.362186)
		(width 0.088646)
		(layer "In11.Cu")
		(net "M_H_CPU1_SA_DQ<29>")
	)
	(arc
		(start 125.472698 -263.686544)
		(mid 125.398707 -263.96611)
		(end 125.196092 -264.172446)
		(width 0.088646)
		(layer "In11.Cu")
		(net "M_H_CPU1_SA_DQ<29>")
	)
	(arc
		(start 136.089644 -264.50036)
		(mid 136.041965 -264.31746)
		(end 135.911082 -264.181082)
		(width 0.088646)
		(layer "In11.Cu")
		(net "M_H_CPU1_SA_DQ<29>")
	)
	(arc
		(start 135.057896 -263.362186)
		(mid 134.781337 -263.437895)
		(end 134.50316 -263.368282)
		(width 0.088646)
		(layer "In11.Cu")
		(net "M_H_CPU1_SA_DQ<29>")
	)
	(arc
		(start 129.793492 -263.362186)
		(mid 129.606294 -263.312043)
		(end 129.419096 -263.362186)
		(width 0.088646)
		(layer "In11.Cu")
		(net "M_H_CPU1_SA_DQ<29>")
	)
	(arc
		(start 125.175264 -264.184638)
		(mid 124.898789 -264.251958)
		(end 124.624592 -264.176002)
		(width 0.088646)
		(layer "In11.Cu")
		(net "M_H_CPU1_SA_DQ<29>")
	)
	(arc
		(start 131.29895 -263.362186)
		(mid 131.024721 -263.438111)
		(end 130.748278 -263.370822)
		(width 0.088646)
		(layer "In11.Cu")
		(net "M_H_CPU1_SA_DQ<29>")
	)
	(arc
		(start 136.559798 -265.314176)
		(mid 136.512119 -265.131276)
		(end 136.381236 -264.994898)
		(width 0.088646)
		(layer "In11.Cu")
		(net "M_H_CPU1_SA_DQ<29>")
	)
	(arc
		(start 133.17855 -263.362186)
		(mid 132.904321 -263.438111)
		(end 132.627878 -263.370822)
		(width 0.088646)
		(layer "In11.Cu")
		(net "M_H_CPU1_SA_DQ<29>")
	)
	(arc
		(start 138.347196 -265.804142)
		(mid 138.064494 -265.879918)
		(end 137.781792 -265.804142)
		(width 0.088646)
		(layer "In11.Cu")
		(net "M_H_CPU1_SA_DQ<29>")
	)
	(arc
		(start 127.914146 -263.362186)
		(mid 127.726948 -263.312043)
		(end 127.53975 -263.362186)
		(width 0.088646)
		(layer "In11.Cu")
		(net "M_H_CPU1_SA_DQ<29>")
	)
	(arc
		(start 137.77087 -265.797792)
		(mid 137.58834 -265.753768)
		(end 137.407396 -265.803888)
		(width 0.088646)
		(layer "In11.Cu")
		(net "M_H_CPU1_SA_DQ<29>")
	)
	(arc
		(start 127.53975 -263.362186)
		(mid 127.265521 -263.438111)
		(end 126.989078 -263.370822)
		(width 0.088646)
		(layer "In11.Cu")
		(net "M_H_CPU1_SA_DQ<29>")
	)
	(arc
		(start 133.552946 -263.362186)
		(mid 133.365748 -263.312043)
		(end 133.17855 -263.362186)
		(width 0.088646)
		(layer "In11.Cu")
		(net "M_H_CPU1_SA_DQ<29>")
	)
	(arc
		(start 129.419096 -263.362186)
		(mid 129.142537 -263.437895)
		(end 128.86436 -263.368282)
		(width 0.088646)
		(layer "In11.Cu")
		(net "M_H_CPU1_SA_DQ<29>")
	)
	(arc
		(start 134.11835 -263.362186)
		(mid 133.844121 -263.438111)
		(end 133.567678 -263.370822)
		(width 0.088646)
		(layer "In11.Cu")
		(net "M_H_CPU1_SA_DQ<29>")
	)
	(arc
		(start 132.23875 -263.362186)
		(mid 131.956048 -263.437928)
		(end 131.673346 -263.362186)
		(width 0.088646)
		(layer "In11.Cu")
		(net "M_H_CPU1_SA_DQ<29>")
	)
	(arc
		(start 126.9746 -263.362186)
		(mid 126.787292 -263.312043)
		(end 126.59995 -263.362186)
		(width 0.088646)
		(layer "In11.Cu")
		(net "M_H_CPU1_SA_DQ<29>")
	)
	(arc
		(start 135.619744 -263.686544)
		(mid 135.572065 -263.503644)
		(end 135.441182 -263.367266)
		(width 0.088646)
		(layer "In11.Cu")
		(net "M_H_CPU1_SA_DQ<29>")
	)
	(arc
		(start 126.034546 -263.362186)
		(mid 125.847348 -263.312043)
		(end 125.66015 -263.362186)
		(width 0.088646)
		(layer "In11.Cu")
		(net "M_H_CPU1_SA_DQ<29>")
	)
	(arc
		(start 138.721592 -265.804142)
		(mid 138.534394 -265.753965)
		(end 138.347196 -265.804142)
		(width 0.088646)
		(layer "In11.Cu")
		(net "M_H_CPU1_SA_DQ<29>")
	)
	(arc
		(start 135.432292 -263.362186)
		(mid 135.245094 -263.312043)
		(end 135.057896 -263.362186)
		(width 0.088646)
		(layer "In11.Cu")
		(net "M_H_CPU1_SA_DQ<29>")
	)
	(arc
		(start 128.853946 -263.362186)
		(mid 128.666748 -263.312043)
		(end 128.47955 -263.362186)
		(width 0.088646)
		(layer "In11.Cu")
		(net "M_H_CPU1_SA_DQ<29>")
	)
	(arc
		(start 124.624592 -264.176002)
		(mid 124.435009 -263.996932)
		(end 124.345954 -263.751822)
		(width 0.088646)
		(layer "In11.Cu")
		(net "M_H_CPU1_SA_DQ<29>")
	)
	(arc
		(start 136.36625 -264.986262)
		(mid 136.163663 -264.779911)
		(end 136.089644 -264.50036)
		(width 0.088646)
		(layer "In11.Cu")
		(net "M_H_CPU1_SA_DQ<29>")
	)
	(arc
		(start 138.79957 -265.86307)
		(mid 138.762505 -265.831061)
		(end 138.721592 -265.804142)
		(width 0.088646)
		(layer "In11.Cu")
		(net "M_H_CPU1_SA_DQ<29>")
	)
	(arc
		(start 128.47955 -263.362186)
		(mid 128.205321 -263.438111)
		(end 127.928878 -263.370822)
		(width 0.088646)
		(layer "In11.Cu")
		(net "M_H_CPU1_SA_DQ<29>")
	)
	(arc
		(start 131.673346 -263.362186)
		(mid 131.486148 -263.312043)
		(end 131.29895 -263.362186)
		(width 0.088646)
		(layer "In11.Cu")
		(net "M_H_CPU1_SA_DQ<29>")
	)
	(arc
		(start 130.733546 -263.362186)
		(mid 130.546348 -263.312043)
		(end 130.35915 -263.362186)
		(width 0.088646)
		(layer "In11.Cu")
		(net "M_H_CPU1_SA_DQ<29>")
	)
	(arc
		(start 135.902192 -264.176002)
		(mid 135.697857 -263.973397)
		(end 135.619744 -263.69645)
		(width 0.088646)
		(layer "In11.Cu")
		(net "M_H_CPU1_SA_DQ<29>")
	)
	(arc
		(start 125.65126 -263.367266)
		(mid 125.520346 -263.503626)
		(end 125.472698 -263.686544)
		(width 0.088646)
		(layer "In11.Cu")
		(net "M_H_CPU1_SA_DQ<29>")
	)
	(arc
		(start 126.59995 -263.362186)
		(mid 126.325721 -263.438111)
		(end 126.049278 -263.370822)
		(width 0.088646)
		(layer "In11.Cu")
		(net "M_H_CPU1_SA_DQ<29>")
	)
	(arc
		(start 137.392664 -265.812524)
		(mid 137.116223 -265.87969)
		(end 136.841992 -265.803888)
		(width 0.088646)
		(layer "In11.Cu")
		(net "M_H_CPU1_SA_DQ<29>")
	)
	(arc
		(start 132.613146 -263.362186)
		(mid 132.425948 -263.312043)
		(end 132.23875 -263.362186)
		(width 0.088646)
		(layer "In11.Cu")
		(net "M_H_CPU1_SA_DQ<29>")
	)
	(arc
		(start 136.841992 -265.803888)
		(mid 136.64071 -265.606401)
		(end 136.559798 -265.336274)
		(width 0.088646)
		(layer "In11.Cu")
		(net "M_H_CPU1_SA_DQ<29>")
	)
	(arc
		(start 130.35915 -263.362186)
		(mid 130.082337 -263.438022)
		(end 129.803906 -263.368282)
		(width 0.088646)
		(layer "In11.Cu")
		(net "M_H_CPU1_SA_DQ<29>")
	)
	(segment
		(start 211.619592 -282.316936)
		(end 210.028028 -282.316936)
		(width 0.20066)
		(layer "F.Cu")
		(net "M_H_CPU1_SA_DQ<28>")
	)
	(segment
		(start 205.84541 -282.565348)
		(end 205.596744 -282.316682)
		(width 0.20066)
		(layer "F.Cu")
		(net "M_H_CPU1_SA_DQ<28>")
	)
	(segment
		(start 211.619846 -282.316682)
		(end 211.619592 -282.316936)
		(width 0.20066)
		(layer "F.Cu")
		(net "M_H_CPU1_SA_DQ<28>")
	)
	(segment
		(start 206.626714 -281.89174)
		(end 206.508604 -282.00985)
		(width 0.20066)
		(layer "F.Cu")
		(net "M_H_CPU1_SA_DQ<28>")
	)
	(segment
		(start 204.076046 -282.316682)
		(end 202.971146 -282.316682)
		(width 0.20066)
		(layer "F.Cu")
		(net "M_H_CPU1_SA_DQ<28>")
	)
	(segment
		(start 209.596482 -281.88539)
		(end 209.186526 -281.88539)
		(width 0.20066)
		(layer "F.Cu")
		(net "M_H_CPU1_SA_DQ<28>")
	)
	(segment
		(start 123.497848 -264.500106)
		(end 123.497594 -264.50036)
		(width 0.20066)
		(layer "F.Cu")
		(net "M_H_CPU1_SA_DQ<28>")
	)
	(segment
		(start 205.596744 -282.316682)
		(end 204.076046 -282.316682)
		(width 0.20066)
		(layer "F.Cu")
		(net "M_H_CPU1_SA_DQ<28>")
	)
	(segment
		(start 209.186526 -281.88539)
		(end 209.180176 -281.89174)
		(width 0.1016)
		(layer "F.Cu")
		(net "M_H_CPU1_SA_DQ<28>")
	)
	(segment
		(start 206.971392 -281.89174)
		(end 206.626714 -281.89174)
		(width 0.20066)
		(layer "F.Cu")
		(net "M_H_CPU1_SA_DQ<28>")
	)
	(segment
		(start 210.028028 -282.316936)
		(end 209.596482 -281.88539)
		(width 0.20066)
		(layer "F.Cu")
		(net "M_H_CPU1_SA_DQ<28>")
	)
	(segment
		(start 209.180176 -281.89174)
		(end 207.018382 -281.89174)
		(width 0.1016)
		(layer "F.Cu")
		(net "M_H_CPU1_SA_DQ<28>")
	)
	(segment
		(start 207.018382 -281.89174)
		(end 206.971392 -281.89174)
		(width 0.101854)
		(layer "F.Cu")
		(net "M_H_CPU1_SA_DQ<28>")
	)
	(segment
		(start 206.508604 -282.00985)
		(end 206.508604 -282.377388)
		(width 0.20066)
		(layer "F.Cu")
		(net "M_H_CPU1_SA_DQ<28>")
	)
	(segment
		(start 123.497848 -263.96442)
		(end 123.497848 -264.500106)
		(width 0.20066)
		(layer "F.Cu")
		(net "M_H_CPU1_SA_DQ<28>")
	)
	(segment
		(start 206.320644 -282.565348)
		(end 205.84541 -282.565348)
		(width 0.20066)
		(layer "F.Cu")
		(net "M_H_CPU1_SA_DQ<28>")
	)
	(segment
		(start 206.508604 -282.377388)
		(end 206.320644 -282.565348)
		(width 0.20066)
		(layer "F.Cu")
		(net "M_H_CPU1_SA_DQ<28>")
	)
	(segment
		(start 189.614302 -284.994604)
		(end 188.209428 -283.58973)
		(width 0.18288)
		(layer "In11.Cu")
		(net "M_H_CPU1_SA_DQ<28>")
	)
	(segment
		(start 131.768596 -264.176002)
		(end 131.753864 -264.184638)
		(width 0.088646)
		(layer "In11.Cu")
		(net "M_H_CPU1_SA_DQ<28>")
	)
	(segment
		(start 167.303958 -284.250892)
		(end 166.93261 -284.250892)
		(width 0.18288)
		(layer "In11.Cu")
		(net "M_H_CPU1_SA_DQ<28>")
	)
	(segment
		(start 132.70865 -264.176002)
		(end 132.698236 -264.182098)
		(width 0.088646)
		(layer "In11.Cu")
		(net "M_H_CPU1_SA_DQ<28>")
	)
	(segment
		(start 192.898776 -285.291022)
		(end 191.495426 -285.291022)
		(width 0.18288)
		(layer "In11.Cu")
		(net "M_H_CPU1_SA_DQ<28>")
	)
	(segment
		(start 198.651876 -283.488892)
		(end 197.867778 -284.27299)
		(width 0.18288)
		(layer "In11.Cu")
		(net "M_H_CPU1_SA_DQ<28>")
	)
	(segment
		(start 187.530232 -283.58973)
		(end 186.856624 -284.263338)
		(width 0.18288)
		(layer "In11.Cu")
		(net "M_H_CPU1_SA_DQ<28>")
	)
	(segment
		(start 185.241438 -284.456378)
		(end 185.048398 -284.263338)
		(width 0.18288)
		(layer "In11.Cu")
		(net "M_H_CPU1_SA_DQ<28>")
	)
	(segment
		(start 176.179226 -285.043626)
		(end 174.940468 -285.043626)
		(width 0.18288)
		(layer "In11.Cu")
		(net "M_H_CPU1_SA_DQ<28>")
	)
	(segment
		(start 125.76302 -264.679938)
		(end 125.753368 -264.679938)
		(width 0.088646)
		(layer "In11.Cu")
		(net "M_H_CPU1_SA_DQ<28>")
	)
	(segment
		(start 168.200578 -284.057852)
		(end 168.200578 -283.732732)
		(width 0.18288)
		(layer "In11.Cu")
		(net "M_H_CPU1_SA_DQ<28>")
	)
	(segment
		(start 156.366718 -280.584402)
		(end 143.838168 -268.055852)
		(width 0.18288)
		(layer "In11.Cu")
		(net "M_H_CPU1_SA_DQ<28>")
	)
	(segment
		(start 167.496998 -284.057852)
		(end 167.303958 -284.250892)
		(width 0.18288)
		(layer "In11.Cu")
		(net "M_H_CPU1_SA_DQ<28>")
	)
	(segment
		(start 140.087604 -268.055852)
		(end 139.831826 -268.055852)
		(width 0.088646)
		(layer "In11.Cu")
		(net "M_H_CPU1_SA_DQ<28>")
	)
	(segment
		(start 191.495426 -285.291022)
		(end 191.199008 -284.994604)
		(width 0.18288)
		(layer "In11.Cu")
		(net "M_H_CPU1_SA_DQ<28>")
	)
	(segment
		(start 185.945018 -284.456378)
		(end 185.945018 -284.856936)
		(width 0.18288)
		(layer "In11.Cu")
		(net "M_H_CPU1_SA_DQ<28>")
	)
	(segment
		(start 197.867778 -284.27299)
		(end 193.916808 -284.27299)
		(width 0.18288)
		(layer "In11.Cu")
		(net "M_H_CPU1_SA_DQ<28>")
	)
	(segment
		(start 127.069596 -264.176002)
		(end 127.059182 -264.182098)
		(width 0.088646)
		(layer "In11.Cu")
		(net "M_H_CPU1_SA_DQ<28>")
	)
	(segment
		(start 185.048398 -284.263338)
		(end 178.51882 -284.263338)
		(width 0.18288)
		(layer "In11.Cu")
		(net "M_H_CPU1_SA_DQ<28>")
	)
	(segment
		(start 158.972758 -281.547062)
		(end 158.971996 -281.350212)
		(width 0.18288)
		(layer "In11.Cu")
		(net "M_H_CPU1_SA_DQ<28>")
	)
	(segment
		(start 176.426876 -285.291276)
		(end 176.179226 -285.043626)
		(width 0.18288)
		(layer "In11.Cu")
		(net "M_H_CPU1_SA_DQ<28>")
	)
	(segment
		(start 167.690038 -283.539692)
		(end 167.496998 -283.732732)
		(width 0.18288)
		(layer "In11.Cu")
		(net "M_H_CPU1_SA_DQ<28>")
	)
	(segment
		(start 135.441436 -264.994898)
		(end 135.432546 -264.989818)
		(width 0.088646)
		(layer "In11.Cu")
		(net "M_H_CPU1_SA_DQ<28>")
	)
	(segment
		(start 166.93261 -284.250892)
		(end 166.73957 -284.057852)
		(width 0.18288)
		(layer "In11.Cu")
		(net "M_H_CPU1_SA_DQ<28>")
	)
	(segment
		(start 166.54653 -283.144214)
		(end 166.22903 -283.144214)
		(width 0.18288)
		(layer "In11.Cu")
		(net "M_H_CPU1_SA_DQ<28>")
	)
	(segment
		(start 124.048774 -264.728452)
		(end 123.497594 -264.50036)
		(width 0.088646)
		(layer "In11.Cu")
		(net "M_H_CPU1_SA_DQ<28>")
	)
	(segment
		(start 124.168154 -264.847832)
		(end 124.048774 -264.728452)
		(width 0.088646)
		(layer "In11.Cu")
		(net "M_H_CPU1_SA_DQ<28>")
	)
	(segment
		(start 171.748196 -285.893256)
		(end 171.25315 -285.893256)
		(width 0.18288)
		(layer "In11.Cu")
		(net "M_H_CPU1_SA_DQ<28>")
	)
	(segment
		(start 174.940468 -285.043626)
		(end 173.842426 -286.141668)
		(width 0.18288)
		(layer "In11.Cu")
		(net "M_H_CPU1_SA_DQ<28>")
	)
	(segment
		(start 185.241438 -284.856936)
		(end 185.241438 -284.456378)
		(width 0.18288)
		(layer "In11.Cu")
		(net "M_H_CPU1_SA_DQ<28>")
	)
	(segment
		(start 201.918824 -282.746196)
		(end 200.73874 -282.746196)
		(width 0.18288)
		(layer "In11.Cu")
		(net "M_H_CPU1_SA_DQ<28>")
	)
	(segment
		(start 157.368748 -280.947114)
		(end 157.006036 -280.584402)
		(width 0.18288)
		(layer "In11.Cu")
		(net "M_H_CPU1_SA_DQ<28>")
	)
	(segment
		(start 165.349174 -284.250892)
		(end 164.665406 -283.567124)
		(width 0.18288)
		(layer "In11.Cu")
		(net "M_H_CPU1_SA_DQ<28>")
	)
	(segment
		(start 128.009396 -264.176002)
		(end 127.994664 -264.184638)
		(width 0.088646)
		(layer "In11.Cu")
		(net "M_H_CPU1_SA_DQ<28>")
	)
	(segment
		(start 126.13005 -264.176002)
		(end 126.129796 -264.176256)
		(width 0.088646)
		(layer "In11.Cu")
		(net "M_H_CPU1_SA_DQ<28>")
	)
	(segment
		(start 139.596114 -267.82014)
		(end 139.151868 -267.82014)
		(width 0.088646)
		(layer "In11.Cu")
		(net "M_H_CPU1_SA_DQ<28>")
	)
	(segment
		(start 125.564646 -264.824718)
		(end 125.552962 -264.831322)
		(width 0.088646)
		(layer "In11.Cu")
		(net "M_H_CPU1_SA_DQ<28>")
	)
	(segment
		(start 133.648196 -264.176002)
		(end 133.637782 -264.182098)
		(width 0.088646)
		(layer "In11.Cu")
		(net "M_H_CPU1_SA_DQ<28>")
	)
	(segment
		(start 168.200578 -283.732732)
		(end 168.007538 -283.539692)
		(width 0.18288)
		(layer "In11.Cu")
		(net "M_H_CPU1_SA_DQ<28>")
	)
	(segment
		(start 135.911082 -265.808968)
		(end 135.902192 -265.803888)
		(width 0.088646)
		(layer "In11.Cu")
		(net "M_H_CPU1_SA_DQ<28>")
	)
	(segment
		(start 173.842426 -286.141668)
		(end 171.996608 -286.141668)
		(width 0.18288)
		(layer "In11.Cu")
		(net "M_H_CPU1_SA_DQ<28>")
	)
	(segment
		(start 135.432546 -264.989818)
		(end 135.429752 -264.988294)
		(width 0.088646)
		(layer "In11.Cu")
		(net "M_H_CPU1_SA_DQ<28>")
	)
	(segment
		(start 200.73874 -282.746196)
		(end 199.996044 -283.488892)
		(width 0.18288)
		(layer "In11.Cu")
		(net "M_H_CPU1_SA_DQ<28>")
	)
	(segment
		(start 138.439144 -267.107416)
		(end 138.439144 -266.941554)
		(width 0.088646)
		(layer "In11.Cu")
		(net "M_H_CPU1_SA_DQ<28>")
	)
	(segment
		(start 134.587996 -264.176002)
		(end 134.573264 -264.184638)
		(width 0.088646)
		(layer "In11.Cu")
		(net "M_H_CPU1_SA_DQ<28>")
	)
	(segment
		(start 125.177296 -264.83056)
		(end 125.115828 -264.794746)
		(width 0.088646)
		(layer "In11.Cu")
		(net "M_H_CPU1_SA_DQ<28>")
	)
	(segment
		(start 166.73957 -283.337254)
		(end 166.54653 -283.144214)
		(width 0.18288)
		(layer "In11.Cu")
		(net "M_H_CPU1_SA_DQ<28>")
	)
	(segment
		(start 185.751978 -285.049976)
		(end 185.434478 -285.049976)
		(width 0.18288)
		(layer "In11.Cu")
		(net "M_H_CPU1_SA_DQ<28>")
	)
	(segment
		(start 186.856624 -284.263338)
		(end 186.138058 -284.263338)
		(width 0.18288)
		(layer "In11.Cu")
		(net "M_H_CPU1_SA_DQ<28>")
	)
	(segment
		(start 166.03599 -283.337254)
		(end 166.03599 -284.057852)
		(width 0.18288)
		(layer "In11.Cu")
		(net "M_H_CPU1_SA_DQ<28>")
	)
	(segment
		(start 185.945018 -284.856936)
		(end 185.751978 -285.049976)
		(width 0.18288)
		(layer "In11.Cu")
		(net "M_H_CPU1_SA_DQ<28>")
	)
	(segment
		(start 166.03599 -284.057852)
		(end 165.84295 -284.250892)
		(width 0.18288)
		(layer "In11.Cu")
		(net "M_H_CPU1_SA_DQ<28>")
	)
	(segment
		(start 202.971146 -282.316682)
		(end 202.348338 -282.316682)
		(width 0.18288)
		(layer "In11.Cu")
		(net "M_H_CPU1_SA_DQ<28>")
	)
	(segment
		(start 164.665406 -283.567124)
		(end 163.608258 -283.567124)
		(width 0.18288)
		(layer "In11.Cu")
		(net "M_H_CPU1_SA_DQ<28>")
	)
	(segment
		(start 139.151868 -267.82014)
		(end 138.439144 -267.107416)
		(width 0.088646)
		(layer "In11.Cu")
		(net "M_H_CPU1_SA_DQ<28>")
	)
	(segment
		(start 168.007538 -283.539692)
		(end 167.690038 -283.539692)
		(width 0.18288)
		(layer "In11.Cu")
		(net "M_H_CPU1_SA_DQ<28>")
	)
	(segment
		(start 202.348338 -282.316682)
		(end 201.918824 -282.746196)
		(width 0.18288)
		(layer "In11.Cu")
		(net "M_H_CPU1_SA_DQ<28>")
	)
	(segment
		(start 166.22903 -283.144214)
		(end 166.03599 -283.337254)
		(width 0.18288)
		(layer "In11.Cu")
		(net "M_H_CPU1_SA_DQ<28>")
	)
	(segment
		(start 177.490882 -285.291276)
		(end 176.426876 -285.291276)
		(width 0.18288)
		(layer "In11.Cu")
		(net "M_H_CPU1_SA_DQ<28>")
	)
	(segment
		(start 161.6837 -282.818586)
		(end 160.75914 -281.894026)
		(width 0.18288)
		(layer "In11.Cu")
		(net "M_H_CPU1_SA_DQ<28>")
	)
	(segment
		(start 160.75914 -281.894026)
		(end 159.319722 -281.894026)
		(width 0.18288)
		(layer "In11.Cu")
		(net "M_H_CPU1_SA_DQ<28>")
	)
	(segment
		(start 128.949196 -264.176002)
		(end 128.934464 -264.184638)
		(width 0.088646)
		(layer "In11.Cu")
		(net "M_H_CPU1_SA_DQ<28>")
	)
	(segment
		(start 130.828796 -264.176002)
		(end 130.814064 -264.184638)
		(width 0.088646)
		(layer "In11.Cu")
		(net "M_H_CPU1_SA_DQ<28>")
	)
	(segment
		(start 157.006036 -280.584402)
		(end 156.366718 -280.584402)
		(width 0.18288)
		(layer "In11.Cu")
		(net "M_H_CPU1_SA_DQ<28>")
	)
	(segment
		(start 167.496998 -283.732732)
		(end 167.496998 -284.057852)
		(width 0.18288)
		(layer "In11.Cu")
		(net "M_H_CPU1_SA_DQ<28>")
	)
	(segment
		(start 143.838168 -268.055852)
		(end 140.087604 -268.055852)
		(width 0.18288)
		(layer "In11.Cu")
		(net "M_H_CPU1_SA_DQ<28>")
	)
	(segment
		(start 193.916808 -284.27299)
		(end 192.898776 -285.291022)
		(width 0.18288)
		(layer "In11.Cu")
		(net "M_H_CPU1_SA_DQ<28>")
	)
	(segment
		(start 134.971282 -264.181082)
		(end 134.962392 -264.176002)
		(width 0.088646)
		(layer "In11.Cu")
		(net "M_H_CPU1_SA_DQ<28>")
	)
	(segment
		(start 178.51882 -284.263338)
		(end 177.490882 -285.291276)
		(width 0.18288)
		(layer "In11.Cu")
		(net "M_H_CPU1_SA_DQ<28>")
	)
	(segment
		(start 158.971996 -281.133804)
		(end 158.785306 -280.947114)
		(width 0.18288)
		(layer "In11.Cu")
		(net "M_H_CPU1_SA_DQ<28>")
	)
	(segment
		(start 162.85972 -282.818586)
		(end 161.6837 -282.818586)
		(width 0.18288)
		(layer "In11.Cu")
		(net "M_H_CPU1_SA_DQ<28>")
	)
	(segment
		(start 188.209428 -283.58973)
		(end 187.530232 -283.58973)
		(width 0.18288)
		(layer "In11.Cu")
		(net "M_H_CPU1_SA_DQ<28>")
	)
	(segment
		(start 135.429752 -264.988294)
		(end 135.42645 -264.986262)
		(width 0.088646)
		(layer "In11.Cu")
		(net "M_H_CPU1_SA_DQ<28>")
	)
	(segment
		(start 165.84295 -284.250892)
		(end 165.349174 -284.250892)
		(width 0.18288)
		(layer "In11.Cu")
		(net "M_H_CPU1_SA_DQ<28>")
	)
	(segment
		(start 135.619998 -265.336274)
		(end 135.619998 -265.314176)
		(width 0.088646)
		(layer "In11.Cu")
		(net "M_H_CPU1_SA_DQ<28>")
	)
	(segment
		(start 136.089644 -266.138152)
		(end 136.089644 -266.128246)
		(width 0.088646)
		(layer "In11.Cu")
		(net "M_H_CPU1_SA_DQ<28>")
	)
	(segment
		(start 158.971996 -281.350212)
		(end 158.971996 -281.133804)
		(width 0.18288)
		(layer "In11.Cu")
		(net "M_H_CPU1_SA_DQ<28>")
	)
	(segment
		(start 186.138058 -284.263338)
		(end 185.945018 -284.456378)
		(width 0.18288)
		(layer "In11.Cu")
		(net "M_H_CPU1_SA_DQ<28>")
	)
	(segment
		(start 139.831826 -268.055852)
		(end 139.596114 -267.82014)
		(width 0.088646)
		(layer "In11.Cu")
		(net "M_H_CPU1_SA_DQ<28>")
	)
	(segment
		(start 163.608258 -283.567124)
		(end 162.85972 -282.818586)
		(width 0.18288)
		(layer "In11.Cu")
		(net "M_H_CPU1_SA_DQ<28>")
	)
	(segment
		(start 166.73957 -284.057852)
		(end 166.73957 -283.337254)
		(width 0.18288)
		(layer "In11.Cu")
		(net "M_H_CPU1_SA_DQ<28>")
	)
	(segment
		(start 159.319722 -281.894026)
		(end 158.972758 -281.547062)
		(width 0.18288)
		(layer "In11.Cu")
		(net "M_H_CPU1_SA_DQ<28>")
	)
	(segment
		(start 168.393618 -284.250892)
		(end 168.200578 -284.057852)
		(width 0.18288)
		(layer "In11.Cu")
		(net "M_H_CPU1_SA_DQ<28>")
	)
	(segment
		(start 199.996044 -283.488892)
		(end 198.651876 -283.488892)
		(width 0.18288)
		(layer "In11.Cu")
		(net "M_H_CPU1_SA_DQ<28>")
	)
	(segment
		(start 158.785306 -280.947114)
		(end 157.368748 -280.947114)
		(width 0.18288)
		(layer "In11.Cu")
		(net "M_H_CPU1_SA_DQ<28>")
	)
	(segment
		(start 125.942598 -264.50036)
		(end 125.76302 -264.679938)
		(width 0.088646)
		(layer "In11.Cu")
		(net "M_H_CPU1_SA_DQ<28>")
	)
	(segment
		(start 185.434478 -285.049976)
		(end 185.241438 -284.856936)
		(width 0.18288)
		(layer "In11.Cu")
		(net "M_H_CPU1_SA_DQ<28>")
	)
	(segment
		(start 171.25315 -285.893256)
		(end 169.610786 -284.250892)
		(width 0.18288)
		(layer "In11.Cu")
		(net "M_H_CPU1_SA_DQ<28>")
	)
	(segment
		(start 171.996608 -286.141668)
		(end 171.748196 -285.893256)
		(width 0.18288)
		(layer "In11.Cu")
		(net "M_H_CPU1_SA_DQ<28>")
	)
	(segment
		(start 191.199008 -284.994604)
		(end 189.614302 -284.994604)
		(width 0.18288)
		(layer "In11.Cu")
		(net "M_H_CPU1_SA_DQ<28>")
	)
	(segment
		(start 169.610786 -284.250892)
		(end 168.393618 -284.250892)
		(width 0.18288)
		(layer "In11.Cu")
		(net "M_H_CPU1_SA_DQ<28>")
	)
	(arc
		(start 126.504446 -264.176002)
		(mid 126.317248 -264.125859)
		(end 126.13005 -264.176002)
		(width 0.088646)
		(layer "In11.Cu")
		(net "M_H_CPU1_SA_DQ<28>")
	)
	(arc
		(start 125.753368 -264.679938)
		(mid 125.663758 -264.758522)
		(end 125.564646 -264.824718)
		(width 0.088646)
		(layer "In11.Cu")
		(net "M_H_CPU1_SA_DQ<28>")
	)
	(arc
		(start 138.32967 -266.676632)
		(mid 138.292605 -266.644623)
		(end 138.251692 -266.617704)
		(width 0.088646)
		(layer "In11.Cu")
		(net "M_H_CPU1_SA_DQ<28>")
	)
	(arc
		(start 129.888996 -264.176002)
		(mid 129.606294 -264.251778)
		(end 129.323592 -264.176002)
		(width 0.088646)
		(layer "In11.Cu")
		(net "M_H_CPU1_SA_DQ<28>")
	)
	(arc
		(start 132.142992 -264.176002)
		(mid 131.955794 -264.125859)
		(end 131.768596 -264.176002)
		(width 0.088646)
		(layer "In11.Cu")
		(net "M_H_CPU1_SA_DQ<28>")
	)
	(arc
		(start 137.877296 -266.617704)
		(mid 137.594594 -266.69348)
		(end 137.311892 -266.617704)
		(width 0.088646)
		(layer "In11.Cu")
		(net "M_H_CPU1_SA_DQ<28>")
	)
	(arc
		(start 138.251692 -266.617704)
		(mid 138.064494 -266.567527)
		(end 137.877296 -266.617704)
		(width 0.088646)
		(layer "In11.Cu")
		(net "M_H_CPU1_SA_DQ<28>")
	)
	(arc
		(start 134.962392 -264.176002)
		(mid 134.775194 -264.125859)
		(end 134.587996 -264.176002)
		(width 0.088646)
		(layer "In11.Cu")
		(net "M_H_CPU1_SA_DQ<28>")
	)
	(arc
		(start 138.439144 -266.941554)
		(mid 138.410834 -266.798174)
		(end 138.32967 -266.676632)
		(width 0.088646)
		(layer "In11.Cu")
		(net "M_H_CPU1_SA_DQ<28>")
	)
	(arc
		(start 131.753864 -264.184638)
		(mid 131.477389 -264.251958)
		(end 131.203192 -264.176002)
		(width 0.088646)
		(layer "In11.Cu")
		(net "M_H_CPU1_SA_DQ<28>")
	)
	(arc
		(start 129.323592 -264.176002)
		(mid 129.136394 -264.125859)
		(end 128.949196 -264.176002)
		(width 0.088646)
		(layer "In11.Cu")
		(net "M_H_CPU1_SA_DQ<28>")
	)
	(arc
		(start 136.937496 -266.617704)
		(mid 136.654794 -266.69348)
		(end 136.372092 -266.617704)
		(width 0.088646)
		(layer "In11.Cu")
		(net "M_H_CPU1_SA_DQ<28>")
	)
	(arc
		(start 124.712984 -264.847832)
		(mid 124.440532 -264.960797)
		(end 124.168154 -264.847832)
		(width 0.088646)
		(layer "In11.Cu")
		(net "M_H_CPU1_SA_DQ<28>")
	)
	(arc
		(start 134.573264 -264.184638)
		(mid 134.296789 -264.251958)
		(end 134.022592 -264.176002)
		(width 0.088646)
		(layer "In11.Cu")
		(net "M_H_CPU1_SA_DQ<28>")
	)
	(arc
		(start 127.059182 -264.182098)
		(mid 126.781004 -264.251821)
		(end 126.504446 -264.176002)
		(width 0.088646)
		(layer "In11.Cu")
		(net "M_H_CPU1_SA_DQ<28>")
	)
	(arc
		(start 135.42645 -264.986262)
		(mid 135.223863 -264.779911)
		(end 135.149844 -264.50036)
		(width 0.088646)
		(layer "In11.Cu")
		(net "M_H_CPU1_SA_DQ<28>")
	)
	(arc
		(start 131.203192 -264.176002)
		(mid 131.015994 -264.125859)
		(end 130.828796 -264.176002)
		(width 0.088646)
		(layer "In11.Cu")
		(net "M_H_CPU1_SA_DQ<28>")
	)
	(arc
		(start 133.083046 -264.176002)
		(mid 132.895848 -264.125859)
		(end 132.70865 -264.176002)
		(width 0.088646)
		(layer "In11.Cu")
		(net "M_H_CPU1_SA_DQ<28>")
	)
	(arc
		(start 128.934464 -264.184638)
		(mid 128.657989 -264.251958)
		(end 128.383792 -264.176002)
		(width 0.088646)
		(layer "In11.Cu")
		(net "M_H_CPU1_SA_DQ<28>")
	)
	(arc
		(start 127.443992 -264.176002)
		(mid 127.256794 -264.125859)
		(end 127.069596 -264.176002)
		(width 0.088646)
		(layer "In11.Cu")
		(net "M_H_CPU1_SA_DQ<28>")
	)
	(arc
		(start 136.372092 -266.617704)
		(mid 136.167757 -266.415099)
		(end 136.089644 -266.138152)
		(width 0.088646)
		(layer "In11.Cu")
		(net "M_H_CPU1_SA_DQ<28>")
	)
	(arc
		(start 135.149844 -264.50036)
		(mid 135.102165 -264.31746)
		(end 134.971282 -264.181082)
		(width 0.088646)
		(layer "In11.Cu")
		(net "M_H_CPU1_SA_DQ<28>")
	)
	(arc
		(start 133.637782 -264.182098)
		(mid 133.359604 -264.251821)
		(end 133.083046 -264.176002)
		(width 0.088646)
		(layer "In11.Cu")
		(net "M_H_CPU1_SA_DQ<28>")
	)
	(arc
		(start 128.383792 -264.176002)
		(mid 128.196594 -264.125859)
		(end 128.009396 -264.176002)
		(width 0.088646)
		(layer "In11.Cu")
		(net "M_H_CPU1_SA_DQ<28>")
	)
	(arc
		(start 137.311892 -266.617704)
		(mid 137.124694 -266.567527)
		(end 136.937496 -266.617704)
		(width 0.088646)
		(layer "In11.Cu")
		(net "M_H_CPU1_SA_DQ<28>")
	)
	(arc
		(start 132.698236 -264.182098)
		(mid 132.419804 -264.251944)
		(end 132.142992 -264.176002)
		(width 0.088646)
		(layer "In11.Cu")
		(net "M_H_CPU1_SA_DQ<28>")
	)
	(arc
		(start 125.552962 -264.831322)
		(mid 125.365024 -264.881499)
		(end 125.177296 -264.83056)
		(width 0.088646)
		(layer "In11.Cu")
		(net "M_H_CPU1_SA_DQ<28>")
	)
	(arc
		(start 130.814064 -264.184638)
		(mid 130.537589 -264.251958)
		(end 130.263392 -264.176002)
		(width 0.088646)
		(layer "In11.Cu")
		(net "M_H_CPU1_SA_DQ<28>")
	)
	(arc
		(start 126.129796 -264.176256)
		(mid 125.992751 -264.313216)
		(end 125.942598 -264.50036)
		(width 0.088646)
		(layer "In11.Cu")
		(net "M_H_CPU1_SA_DQ<28>")
	)
	(arc
		(start 135.619998 -265.314176)
		(mid 135.572319 -265.131276)
		(end 135.441436 -264.994898)
		(width 0.088646)
		(layer "In11.Cu")
		(net "M_H_CPU1_SA_DQ<28>")
	)
	(arc
		(start 134.022592 -264.176002)
		(mid 133.835394 -264.125859)
		(end 133.648196 -264.176002)
		(width 0.088646)
		(layer "In11.Cu")
		(net "M_H_CPU1_SA_DQ<28>")
	)
	(arc
		(start 127.994664 -264.184638)
		(mid 127.718189 -264.251958)
		(end 127.443992 -264.176002)
		(width 0.088646)
		(layer "In11.Cu")
		(net "M_H_CPU1_SA_DQ<28>")
	)
	(arc
		(start 136.089644 -266.128246)
		(mid 136.041965 -265.945346)
		(end 135.911082 -265.808968)
		(width 0.088646)
		(layer "In11.Cu")
		(net "M_H_CPU1_SA_DQ<28>")
	)
	(arc
		(start 125.115828 -264.794746)
		(mid 124.905382 -264.752888)
		(end 124.712984 -264.847832)
		(width 0.088646)
		(layer "In11.Cu")
		(net "M_H_CPU1_SA_DQ<28>")
	)
	(arc
		(start 130.263392 -264.176002)
		(mid 130.076194 -264.125859)
		(end 129.888996 -264.176002)
		(width 0.088646)
		(layer "In11.Cu")
		(net "M_H_CPU1_SA_DQ<28>")
	)
	(arc
		(start 135.902192 -265.803888)
		(mid 135.70091 -265.606401)
		(end 135.619998 -265.336274)
		(width 0.088646)
		(layer "In11.Cu")
		(net "M_H_CPU1_SA_DQ<28>")
	)
	(segment
		(start 209.874358 -285.716726)
		(end 210.306412 -286.14878)
		(width 0.20066)
		(layer "F.Cu")
		(net "M_H_CPU1_SA_DQ<27>")
	)
	(segment
		(start 213.311486 -286.15386)
		(end 213.515448 -285.949898)
		(width 0.20066)
		(layer "F.Cu")
		(net "M_H_CPU1_SA_DQ<27>")
	)
	(segment
		(start 210.306412 -286.14878)
		(end 210.598258 -286.14878)
		(width 0.20066)
		(layer "F.Cu")
		(net "M_H_CPU1_SA_DQ<27>")
	)
	(segment
		(start 214.133684 -285.464758)
		(end 214.385652 -285.716726)
		(width 0.20066)
		(layer "F.Cu")
		(net "M_H_CPU1_SA_DQ<27>")
	)
	(segment
		(start 125.377448 -266.127992)
		(end 125.377194 -266.128246)
		(width 0.20066)
		(layer "F.Cu")
		(net "M_H_CPU1_SA_DQ<27>")
	)
	(segment
		(start 214.385652 -285.716726)
		(end 215.719914 -285.716726)
		(width 0.20066)
		(layer "F.Cu")
		(net "M_H_CPU1_SA_DQ<27>")
	)
	(segment
		(start 207.071214 -285.716726)
		(end 208.176114 -285.716726)
		(width 0.20066)
		(layer "F.Cu")
		(net "M_H_CPU1_SA_DQ<27>")
	)
	(segment
		(start 212.618066 -286.141668)
		(end 212.630258 -286.15386)
		(width 0.1016)
		(layer "F.Cu")
		(net "M_H_CPU1_SA_DQ<27>")
	)
	(segment
		(start 210.610196 -286.141668)
		(end 212.618066 -286.141668)
		(width 0.1016)
		(layer "F.Cu")
		(net "M_H_CPU1_SA_DQ<27>")
	)
	(segment
		(start 213.515448 -285.949898)
		(end 213.515448 -285.698946)
		(width 0.20066)
		(layer "F.Cu")
		(net "M_H_CPU1_SA_DQ<27>")
	)
	(segment
		(start 213.515448 -285.698946)
		(end 213.749636 -285.464758)
		(width 0.20066)
		(layer "F.Cu")
		(net "M_H_CPU1_SA_DQ<27>")
	)
	(segment
		(start 210.598258 -286.14878)
		(end 210.603084 -286.14878)
		(width 0.101854)
		(layer "F.Cu")
		(net "M_H_CPU1_SA_DQ<27>")
	)
	(segment
		(start 212.630258 -286.15386)
		(end 213.311486 -286.15386)
		(width 0.20066)
		(layer "F.Cu")
		(net "M_H_CPU1_SA_DQ<27>")
	)
	(segment
		(start 125.377448 -265.592306)
		(end 125.377448 -266.127992)
		(width 0.20066)
		(layer "F.Cu")
		(net "M_H_CPU1_SA_DQ<27>")
	)
	(segment
		(start 210.603084 -286.14878)
		(end 210.610196 -286.141668)
		(width 0.1016)
		(layer "F.Cu")
		(net "M_H_CPU1_SA_DQ<27>")
	)
	(segment
		(start 208.176114 -285.716726)
		(end 209.874358 -285.716726)
		(width 0.20066)
		(layer "F.Cu")
		(net "M_H_CPU1_SA_DQ<27>")
	)
	(segment
		(start 213.749636 -285.464758)
		(end 214.133684 -285.464758)
		(width 0.20066)
		(layer "F.Cu")
		(net "M_H_CPU1_SA_DQ<27>")
	)
	(segment
		(start 128.009396 -266.45235)
		(end 127.994664 -266.443714)
		(width 0.088646)
		(layer "In11.Cu")
		(net "M_H_CPU1_SA_DQ<27>")
	)
	(segment
		(start 169.68089 -288.75609)
		(end 169.07129 -288.75609)
		(width 0.18288)
		(layer "In11.Cu")
		(net "M_H_CPU1_SA_DQ<27>")
	)
	(segment
		(start 131.774692 -266.455906)
		(end 131.768596 -266.45235)
		(width 0.088646)
		(layer "In11.Cu")
		(net "M_H_CPU1_SA_DQ<27>")
	)
	(segment
		(start 196.515228 -287.310068)
		(end 196.197728 -287.310068)
		(width 0.18288)
		(layer "In11.Cu")
		(net "M_H_CPU1_SA_DQ<27>")
	)
	(segment
		(start 132.051298 -266.950444)
		(end 132.051298 -266.941808)
		(width 0.088646)
		(layer "In11.Cu")
		(net "M_H_CPU1_SA_DQ<27>")
	)
	(segment
		(start 134.11835 -268.894052)
		(end 134.10946 -268.888972)
		(width 0.088646)
		(layer "In11.Cu")
		(net "M_H_CPU1_SA_DQ<27>")
	)
	(segment
		(start 184.320434 -288.866834)
		(end 183.39689 -287.94329)
		(width 0.18288)
		(layer "In11.Cu")
		(net "M_H_CPU1_SA_DQ<27>")
	)
	(segment
		(start 125.379226 -266.128754)
		(end 125.377194 -266.128246)
		(width 0.088646)
		(layer "In11.Cu")
		(net "M_H_CPU1_SA_DQ<27>")
	)
	(segment
		(start 159.447484 -285.388812)
		(end 158.609538 -284.550866)
		(width 0.18288)
		(layer "In11.Cu")
		(net "M_H_CPU1_SA_DQ<27>")
	)
	(segment
		(start 193.584068 -288.834068)
		(end 192.877186 -289.54095)
		(width 0.18288)
		(layer "In11.Cu")
		(net "M_H_CPU1_SA_DQ<27>")
	)
	(segment
		(start 171.478956 -290.554156)
		(end 169.68089 -288.75609)
		(width 0.18288)
		(layer "In11.Cu")
		(net "M_H_CPU1_SA_DQ<27>")
	)
	(segment
		(start 135.527796 -269.707868)
		(end 135.513064 -269.699232)
		(width 0.088646)
		(layer "In11.Cu")
		(net "M_H_CPU1_SA_DQ<27>")
	)
	(segment
		(start 140.262102 -270.263874)
		(end 139.881356 -269.883128)
		(width 0.088646)
		(layer "In11.Cu")
		(net "M_H_CPU1_SA_DQ<27>")
	)
	(segment
		(start 207.071214 -285.716726)
		(end 207.045814 -285.716726)
		(width 0.18288)
		(layer "In11.Cu")
		(net "M_H_CPU1_SA_DQ<27>")
	)
	(segment
		(start 196.708268 -287.815274)
		(end 196.708268 -287.503108)
		(width 0.18288)
		(layer "In11.Cu")
		(net "M_H_CPU1_SA_DQ<27>")
	)
	(segment
		(start 191.26835 -289.54095)
		(end 190.41618 -288.68878)
		(width 0.18288)
		(layer "In11.Cu")
		(net "M_H_CPU1_SA_DQ<27>")
	)
	(segment
		(start 186.951874 -288.866834)
		(end 184.320434 -288.866834)
		(width 0.18288)
		(layer "In11.Cu")
		(net "M_H_CPU1_SA_DQ<27>")
	)
	(segment
		(start 196.901308 -288.008314)
		(end 196.708268 -287.815274)
		(width 0.18288)
		(layer "In11.Cu")
		(net "M_H_CPU1_SA_DQ<27>")
	)
	(segment
		(start 139.881356 -269.883128)
		(end 138.646154 -269.883128)
		(width 0.088646)
		(layer "In11.Cu")
		(net "M_H_CPU1_SA_DQ<27>")
	)
	(segment
		(start 172.46854 -290.391596)
		(end 172.30598 -290.554156)
		(width 0.18288)
		(layer "In11.Cu")
		(net "M_H_CPU1_SA_DQ<27>")
	)
	(segment
		(start 207.045814 -285.716726)
		(end 206.752444 -285.424118)
		(width 0.18288)
		(layer "In11.Cu")
		(net "M_H_CPU1_SA_DQ<27>")
	)
	(segment
		(start 167.441626 -288.040826)
		(end 166.730426 -287.329626)
		(width 0.18288)
		(layer "In11.Cu")
		(net "M_H_CPU1_SA_DQ<27>")
	)
	(segment
		(start 194.276472 -288.834068)
		(end 193.584068 -288.834068)
		(width 0.18288)
		(layer "In11.Cu")
		(net "M_H_CPU1_SA_DQ<27>")
	)
	(segment
		(start 127.069596 -266.45235)
		(end 127.054864 -266.443714)
		(width 0.088646)
		(layer "In11.Cu")
		(net "M_H_CPU1_SA_DQ<27>")
	)
	(segment
		(start 137.407396 -269.707868)
		(end 137.392664 -269.699232)
		(width 0.088646)
		(layer "In11.Cu")
		(net "M_H_CPU1_SA_DQ<27>")
	)
	(segment
		(start 202.502516 -285.475426)
		(end 201.23531 -285.475426)
		(width 0.18288)
		(layer "In11.Cu")
		(net "M_H_CPU1_SA_DQ<27>")
	)
	(segment
		(start 192.134236 -289.539426)
		(end 192.132712 -289.54095)
		(width 0.18288)
		(layer "In11.Cu")
		(net "M_H_CPU1_SA_DQ<27>")
	)
	(segment
		(start 203.947776 -285.291022)
		(end 202.68692 -285.291022)
		(width 0.18288)
		(layer "In11.Cu")
		(net "M_H_CPU1_SA_DQ<27>")
	)
	(segment
		(start 166.18458 -287.329626)
		(end 165.852602 -287.661604)
		(width 0.18288)
		(layer "In11.Cu")
		(net "M_H_CPU1_SA_DQ<27>")
	)
	(segment
		(start 178.71186 -288.74466)
		(end 177.91557 -289.54095)
		(width 0.18288)
		(layer "In11.Cu")
		(net "M_H_CPU1_SA_DQ<27>")
	)
	(segment
		(start 202.68692 -285.291022)
		(end 202.502516 -285.475426)
		(width 0.18288)
		(layer "In11.Cu")
		(net "M_H_CPU1_SA_DQ<27>")
	)
	(segment
		(start 138.646154 -269.883128)
		(end 138.332464 -269.699232)
		(width 0.088646)
		(layer "In11.Cu")
		(net "M_H_CPU1_SA_DQ<27>")
	)
	(segment
		(start 196.197728 -287.310068)
		(end 196.004688 -287.503108)
		(width 0.18288)
		(layer "In11.Cu")
		(net "M_H_CPU1_SA_DQ<27>")
	)
	(segment
		(start 169.07129 -288.75609)
		(end 168.356026 -288.040826)
		(width 0.18288)
		(layer "In11.Cu")
		(net "M_H_CPU1_SA_DQ<27>")
	)
	(segment
		(start 192.877186 -289.54095)
		(end 192.134236 -289.539426)
		(width 0.18288)
		(layer "In11.Cu")
		(net "M_H_CPU1_SA_DQ<27>")
	)
	(segment
		(start 134.400544 -269.38351)
		(end 134.400544 -269.368016)
		(width 0.088646)
		(layer "In11.Cu")
		(net "M_H_CPU1_SA_DQ<27>")
	)
	(segment
		(start 203.966572 -285.272226)
		(end 203.947776 -285.291022)
		(width 0.18288)
		(layer "In11.Cu")
		(net "M_H_CPU1_SA_DQ<27>")
	)
	(segment
		(start 206.752444 -285.424118)
		(end 206.600044 -285.272226)
		(width 0.18288)
		(layer "In11.Cu")
		(net "M_H_CPU1_SA_DQ<27>")
	)
	(segment
		(start 132.521198 -267.764514)
		(end 132.521198 -267.741654)
		(width 0.088646)
		(layer "In11.Cu")
		(net "M_H_CPU1_SA_DQ<27>")
	)
	(segment
		(start 179.285392 -288.74466)
		(end 178.71186 -288.74466)
		(width 0.18288)
		(layer "In11.Cu")
		(net "M_H_CPU1_SA_DQ<27>")
	)
	(segment
		(start 177.91557 -289.54095)
		(end 176.382426 -289.54095)
		(width 0.18288)
		(layer "In11.Cu")
		(net "M_H_CPU1_SA_DQ<27>")
	)
	(segment
		(start 196.004688 -287.815274)
		(end 195.811648 -288.008314)
		(width 0.18288)
		(layer "In11.Cu")
		(net "M_H_CPU1_SA_DQ<27>")
	)
	(segment
		(start 136.467596 -269.707868)
		(end 136.452864 -269.699232)
		(width 0.088646)
		(layer "In11.Cu")
		(net "M_H_CPU1_SA_DQ<27>")
	)
	(segment
		(start 128.949196 -266.45235)
		(end 128.934464 -266.443714)
		(width 0.088646)
		(layer "In11.Cu")
		(net "M_H_CPU1_SA_DQ<27>")
	)
	(segment
		(start 198.608442 -287.121092)
		(end 197.72122 -288.008314)
		(width 0.18288)
		(layer "In11.Cu")
		(net "M_H_CPU1_SA_DQ<27>")
	)
	(segment
		(start 183.39689 -287.94329)
		(end 180.086762 -287.94329)
		(width 0.18288)
		(layer "In11.Cu")
		(net "M_H_CPU1_SA_DQ<27>")
	)
	(segment
		(start 140.651738 -270.263874)
		(end 140.262102 -270.263874)
		(width 0.088646)
		(layer "In11.Cu")
		(net "M_H_CPU1_SA_DQ<27>")
	)
	(segment
		(start 160.457134 -286.281114)
		(end 159.764476 -286.281114)
		(width 0.18288)
		(layer "In11.Cu")
		(net "M_H_CPU1_SA_DQ<27>")
	)
	(segment
		(start 176.212246 -289.71113)
		(end 174.268384 -289.71113)
		(width 0.18288)
		(layer "In11.Cu")
		(net "M_H_CPU1_SA_DQ<27>")
	)
	(segment
		(start 206.600044 -285.272226)
		(end 203.966572 -285.272226)
		(width 0.18288)
		(layer "In11.Cu")
		(net "M_H_CPU1_SA_DQ<27>")
	)
	(segment
		(start 197.72122 -288.008314)
		(end 196.901308 -288.008314)
		(width 0.18288)
		(layer "In11.Cu")
		(net "M_H_CPU1_SA_DQ<27>")
	)
	(segment
		(start 142.691866 -270.263874)
		(end 140.651738 -270.263874)
		(width 0.18288)
		(layer "In11.Cu")
		(net "M_H_CPU1_SA_DQ<27>")
	)
	(segment
		(start 190.41618 -288.68878)
		(end 187.129928 -288.68878)
		(width 0.18288)
		(layer "In11.Cu")
		(net "M_H_CPU1_SA_DQ<27>")
	)
	(segment
		(start 199.589644 -287.121092)
		(end 198.608442 -287.121092)
		(width 0.18288)
		(layer "In11.Cu")
		(net "M_H_CPU1_SA_DQ<27>")
	)
	(segment
		(start 168.356026 -288.040826)
		(end 167.441626 -288.040826)
		(width 0.18288)
		(layer "In11.Cu")
		(net "M_H_CPU1_SA_DQ<27>")
	)
	(segment
		(start 156.978858 -284.550866)
		(end 142.691866 -270.263874)
		(width 0.18288)
		(layer "In11.Cu")
		(net "M_H_CPU1_SA_DQ<27>")
	)
	(segment
		(start 133.654292 -268.083792)
		(end 133.648196 -268.080236)
		(width 0.088646)
		(layer "In11.Cu")
		(net "M_H_CPU1_SA_DQ<27>")
	)
	(segment
		(start 195.102226 -288.008314)
		(end 194.276472 -288.834068)
		(width 0.18288)
		(layer "In11.Cu")
		(net "M_H_CPU1_SA_DQ<27>")
	)
	(segment
		(start 174.268384 -289.71113)
		(end 173.587918 -290.391596)
		(width 0.18288)
		(layer "In11.Cu")
		(net "M_H_CPU1_SA_DQ<27>")
	)
	(segment
		(start 165.852602 -287.661604)
		(end 165.04539 -287.661604)
		(width 0.18288)
		(layer "In11.Cu")
		(net "M_H_CPU1_SA_DQ<27>")
	)
	(segment
		(start 201.23531 -285.475426)
		(end 199.589644 -287.121092)
		(width 0.18288)
		(layer "In11.Cu")
		(net "M_H_CPU1_SA_DQ<27>")
	)
	(segment
		(start 131.768596 -266.45235)
		(end 131.753864 -266.443714)
		(width 0.088646)
		(layer "In11.Cu")
		(net "M_H_CPU1_SA_DQ<27>")
	)
	(segment
		(start 180.086762 -287.94329)
		(end 179.285392 -288.74466)
		(width 0.18288)
		(layer "In11.Cu")
		(net "M_H_CPU1_SA_DQ<27>")
	)
	(segment
		(start 176.382426 -289.54095)
		(end 176.212246 -289.71113)
		(width 0.18288)
		(layer "In11.Cu")
		(net "M_H_CPU1_SA_DQ<27>")
	)
	(segment
		(start 129.888996 -266.45235)
		(end 129.874264 -266.443714)
		(width 0.088646)
		(layer "In11.Cu")
		(net "M_H_CPU1_SA_DQ<27>")
	)
	(segment
		(start 187.129928 -288.68878)
		(end 186.951874 -288.866834)
		(width 0.18288)
		(layer "In11.Cu")
		(net "M_H_CPU1_SA_DQ<27>")
	)
	(segment
		(start 133.648196 -268.080236)
		(end 133.633464 -268.0716)
		(width 0.088646)
		(layer "In11.Cu")
		(net "M_H_CPU1_SA_DQ<27>")
	)
	(segment
		(start 166.730426 -287.329626)
		(end 166.18458 -287.329626)
		(width 0.18288)
		(layer "In11.Cu")
		(net "M_H_CPU1_SA_DQ<27>")
	)
	(segment
		(start 165.04539 -287.661604)
		(end 164.587428 -287.203642)
		(width 0.18288)
		(layer "In11.Cu")
		(net "M_H_CPU1_SA_DQ<27>")
	)
	(segment
		(start 130.828796 -266.45235)
		(end 130.814064 -266.443714)
		(width 0.088646)
		(layer "In11.Cu")
		(net "M_H_CPU1_SA_DQ<27>")
	)
	(segment
		(start 161.379662 -287.203642)
		(end 160.457134 -286.281114)
		(width 0.18288)
		(layer "In11.Cu")
		(net "M_H_CPU1_SA_DQ<27>")
	)
	(segment
		(start 159.764476 -286.281114)
		(end 159.447484 -285.964122)
		(width 0.18288)
		(layer "In11.Cu")
		(net "M_H_CPU1_SA_DQ<27>")
	)
	(segment
		(start 196.004688 -287.503108)
		(end 196.004688 -287.815274)
		(width 0.18288)
		(layer "In11.Cu")
		(net "M_H_CPU1_SA_DQ<27>")
	)
	(segment
		(start 159.447484 -285.964122)
		(end 159.447484 -285.388812)
		(width 0.18288)
		(layer "In11.Cu")
		(net "M_H_CPU1_SA_DQ<27>")
	)
	(segment
		(start 173.587918 -290.391596)
		(end 172.46854 -290.391596)
		(width 0.18288)
		(layer "In11.Cu")
		(net "M_H_CPU1_SA_DQ<27>")
	)
	(segment
		(start 196.708268 -287.503108)
		(end 196.515228 -287.310068)
		(width 0.18288)
		(layer "In11.Cu")
		(net "M_H_CPU1_SA_DQ<27>")
	)
	(segment
		(start 158.609538 -284.550866)
		(end 156.978858 -284.550866)
		(width 0.18288)
		(layer "In11.Cu")
		(net "M_H_CPU1_SA_DQ<27>")
	)
	(segment
		(start 192.132712 -289.54095)
		(end 191.26835 -289.54095)
		(width 0.18288)
		(layer "In11.Cu")
		(net "M_H_CPU1_SA_DQ<27>")
	)
	(segment
		(start 164.587428 -287.203642)
		(end 161.379662 -287.203642)
		(width 0.18288)
		(layer "In11.Cu")
		(net "M_H_CPU1_SA_DQ<27>")
	)
	(segment
		(start 134.587996 -269.707868)
		(end 134.579106 -269.702788)
		(width 0.088646)
		(layer "In11.Cu")
		(net "M_H_CPU1_SA_DQ<27>")
	)
	(segment
		(start 195.811648 -288.008314)
		(end 195.102226 -288.008314)
		(width 0.18288)
		(layer "In11.Cu")
		(net "M_H_CPU1_SA_DQ<27>")
	)
	(segment
		(start 172.30598 -290.554156)
		(end 171.478956 -290.554156)
		(width 0.18288)
		(layer "In11.Cu")
		(net "M_H_CPU1_SA_DQ<27>")
	)
	(arc
		(start 127.054864 -266.443714)
		(mid 126.778389 -266.376394)
		(end 126.504192 -266.45235)
		(width 0.088646)
		(layer "In11.Cu")
		(net "M_H_CPU1_SA_DQ<27>")
	)
	(arc
		(start 132.521198 -267.741654)
		(mid 132.441979 -267.466969)
		(end 132.238496 -267.266166)
		(width 0.088646)
		(layer "In11.Cu")
		(net "M_H_CPU1_SA_DQ<27>")
	)
	(arc
		(start 133.633464 -268.0716)
		(mid 133.356989 -268.00428)
		(end 133.082792 -268.080236)
		(width 0.088646)
		(layer "In11.Cu")
		(net "M_H_CPU1_SA_DQ<27>")
	)
	(arc
		(start 134.10946 -268.888972)
		(mid 133.978546 -268.752612)
		(end 133.930898 -268.569694)
		(width 0.088646)
		(layer "In11.Cu")
		(net "M_H_CPU1_SA_DQ<27>")
	)
	(arc
		(start 135.513064 -269.699232)
		(mid 135.236623 -269.632066)
		(end 134.962392 -269.707868)
		(width 0.088646)
		(layer "In11.Cu")
		(net "M_H_CPU1_SA_DQ<27>")
	)
	(arc
		(start 126.504192 -266.45235)
		(mid 126.316994 -266.502527)
		(end 126.129796 -266.45235)
		(width 0.088646)
		(layer "In11.Cu")
		(net "M_H_CPU1_SA_DQ<27>")
	)
	(arc
		(start 133.930898 -268.569694)
		(mid 133.856907 -268.290128)
		(end 133.654292 -268.083792)
		(width 0.088646)
		(layer "In11.Cu")
		(net "M_H_CPU1_SA_DQ<27>")
	)
	(arc
		(start 127.994664 -266.443714)
		(mid 127.718189 -266.376394)
		(end 127.443992 -266.45235)
		(width 0.088646)
		(layer "In11.Cu")
		(net "M_H_CPU1_SA_DQ<27>")
	)
	(arc
		(start 128.934464 -266.443714)
		(mid 128.657989 -266.376394)
		(end 128.383792 -266.45235)
		(width 0.088646)
		(layer "In11.Cu")
		(net "M_H_CPU1_SA_DQ<27>")
	)
	(arc
		(start 134.579106 -269.702788)
		(mid 134.448192 -269.566428)
		(end 134.400544 -269.38351)
		(width 0.088646)
		(layer "In11.Cu")
		(net "M_H_CPU1_SA_DQ<27>")
	)
	(arc
		(start 134.400544 -269.368016)
		(mid 134.321174 -269.094282)
		(end 134.11835 -268.894052)
		(width 0.088646)
		(layer "In11.Cu")
		(net "M_H_CPU1_SA_DQ<27>")
	)
	(arc
		(start 134.962392 -269.707868)
		(mid 134.775194 -269.758011)
		(end 134.587996 -269.707868)
		(width 0.088646)
		(layer "In11.Cu")
		(net "M_H_CPU1_SA_DQ<27>")
	)
	(arc
		(start 131.753864 -266.443714)
		(mid 131.477389 -266.376394)
		(end 131.203192 -266.45235)
		(width 0.088646)
		(layer "In11.Cu")
		(net "M_H_CPU1_SA_DQ<27>")
	)
	(arc
		(start 130.263392 -266.45235)
		(mid 130.076194 -266.502527)
		(end 129.888996 -266.45235)
		(width 0.088646)
		(layer "In11.Cu")
		(net "M_H_CPU1_SA_DQ<27>")
	)
	(arc
		(start 127.443992 -266.45235)
		(mid 127.256794 -266.502527)
		(end 127.069596 -266.45235)
		(width 0.088646)
		(layer "In11.Cu")
		(net "M_H_CPU1_SA_DQ<27>")
	)
	(arc
		(start 130.814064 -266.443714)
		(mid 130.537589 -266.376394)
		(end 130.263392 -266.45235)
		(width 0.088646)
		(layer "In11.Cu")
		(net "M_H_CPU1_SA_DQ<27>")
	)
	(arc
		(start 137.781792 -269.707868)
		(mid 137.594594 -269.758011)
		(end 137.407396 -269.707868)
		(width 0.088646)
		(layer "In11.Cu")
		(net "M_H_CPU1_SA_DQ<27>")
	)
	(arc
		(start 129.874264 -266.443714)
		(mid 129.597789 -266.376394)
		(end 129.323592 -266.45235)
		(width 0.088646)
		(layer "In11.Cu")
		(net "M_H_CPU1_SA_DQ<27>")
	)
	(arc
		(start 132.708396 -268.080236)
		(mid 132.573463 -267.946882)
		(end 132.521198 -267.764514)
		(width 0.088646)
		(layer "In11.Cu")
		(net "M_H_CPU1_SA_DQ<27>")
	)
	(arc
		(start 128.383792 -266.45235)
		(mid 128.196594 -266.502527)
		(end 128.009396 -266.45235)
		(width 0.088646)
		(layer "In11.Cu")
		(net "M_H_CPU1_SA_DQ<27>")
	)
	(arc
		(start 135.902192 -269.707868)
		(mid 135.714994 -269.758011)
		(end 135.527796 -269.707868)
		(width 0.088646)
		(layer "In11.Cu")
		(net "M_H_CPU1_SA_DQ<27>")
	)
	(arc
		(start 136.452864 -269.699232)
		(mid 136.176423 -269.632066)
		(end 135.902192 -269.707868)
		(width 0.088646)
		(layer "In11.Cu")
		(net "M_H_CPU1_SA_DQ<27>")
	)
	(arc
		(start 132.238496 -267.266166)
		(mid 132.103563 -267.132812)
		(end 132.051298 -266.950444)
		(width 0.088646)
		(layer "In11.Cu")
		(net "M_H_CPU1_SA_DQ<27>")
	)
	(arc
		(start 138.332464 -269.699232)
		(mid 138.056023 -269.632066)
		(end 137.781792 -269.707868)
		(width 0.088646)
		(layer "In11.Cu")
		(net "M_H_CPU1_SA_DQ<27>")
	)
	(arc
		(start 133.082792 -268.080236)
		(mid 132.895594 -268.130379)
		(end 132.708396 -268.080236)
		(width 0.088646)
		(layer "In11.Cu")
		(net "M_H_CPU1_SA_DQ<27>")
	)
	(arc
		(start 131.203192 -266.45235)
		(mid 131.015994 -266.502527)
		(end 130.828796 -266.45235)
		(width 0.088646)
		(layer "In11.Cu")
		(net "M_H_CPU1_SA_DQ<27>")
	)
	(arc
		(start 137.392664 -269.699232)
		(mid 137.116223 -269.632066)
		(end 136.841992 -269.707868)
		(width 0.088646)
		(layer "In11.Cu")
		(net "M_H_CPU1_SA_DQ<27>")
	)
	(arc
		(start 126.129796 -266.45235)
		(mid 125.76394 -266.268681)
		(end 125.379226 -266.128754)
		(width 0.088646)
		(layer "In11.Cu")
		(net "M_H_CPU1_SA_DQ<27>")
	)
	(arc
		(start 129.323592 -266.45235)
		(mid 129.136394 -266.502527)
		(end 128.949196 -266.45235)
		(width 0.088646)
		(layer "In11.Cu")
		(net "M_H_CPU1_SA_DQ<27>")
	)
	(arc
		(start 132.051298 -266.941808)
		(mid 131.977307 -266.662242)
		(end 131.774692 -266.455906)
		(width 0.088646)
		(layer "In11.Cu")
		(net "M_H_CPU1_SA_DQ<27>")
	)
	(arc
		(start 136.841992 -269.707868)
		(mid 136.654794 -269.758011)
		(end 136.467596 -269.707868)
		(width 0.088646)
		(layer "In11.Cu")
		(net "M_H_CPU1_SA_DQ<27>")
	)
	(segment
		(start 208.176114 -287.416748)
		(end 209.874358 -287.416748)
		(width 0.20066)
		(layer "F.Cu")
		(net "M_H_CPU1_SA_DQ<26>")
	)
	(segment
		(start 210.610196 -287.84169)
		(end 212.618066 -287.84169)
		(width 0.1016)
		(layer "F.Cu")
		(net "M_H_CPU1_SA_DQ<26>")
	)
	(segment
		(start 209.874358 -287.416748)
		(end 210.306412 -287.848802)
		(width 0.20066)
		(layer "F.Cu")
		(net "M_H_CPU1_SA_DQ<26>")
	)
	(segment
		(start 213.515448 -287.64992)
		(end 213.515448 -287.398968)
		(width 0.20066)
		(layer "F.Cu")
		(net "M_H_CPU1_SA_DQ<26>")
	)
	(segment
		(start 212.630258 -287.853882)
		(end 213.311486 -287.853882)
		(width 0.20066)
		(layer "F.Cu")
		(net "M_H_CPU1_SA_DQ<26>")
	)
	(segment
		(start 213.515448 -287.398968)
		(end 213.749636 -287.16478)
		(width 0.20066)
		(layer "F.Cu")
		(net "M_H_CPU1_SA_DQ<26>")
	)
	(segment
		(start 207.071214 -287.416748)
		(end 208.176114 -287.416748)
		(width 0.20066)
		(layer "F.Cu")
		(net "M_H_CPU1_SA_DQ<26>")
	)
	(segment
		(start 124.907294 -266.405868)
		(end 124.907294 -266.941554)
		(width 0.20066)
		(layer "F.Cu")
		(net "M_H_CPU1_SA_DQ<26>")
	)
	(segment
		(start 213.749636 -287.16478)
		(end 214.133684 -287.16478)
		(width 0.20066)
		(layer "F.Cu")
		(net "M_H_CPU1_SA_DQ<26>")
	)
	(segment
		(start 213.311486 -287.853882)
		(end 213.515448 -287.64992)
		(width 0.20066)
		(layer "F.Cu")
		(net "M_H_CPU1_SA_DQ<26>")
	)
	(segment
		(start 214.385652 -287.416748)
		(end 215.719914 -287.416748)
		(width 0.20066)
		(layer "F.Cu")
		(net "M_H_CPU1_SA_DQ<26>")
	)
	(segment
		(start 124.907294 -266.941554)
		(end 124.907548 -266.941808)
		(width 0.20066)
		(layer "F.Cu")
		(net "M_H_CPU1_SA_DQ<26>")
	)
	(segment
		(start 210.306412 -287.848802)
		(end 210.598258 -287.848802)
		(width 0.20066)
		(layer "F.Cu")
		(net "M_H_CPU1_SA_DQ<26>")
	)
	(segment
		(start 212.618066 -287.84169)
		(end 212.630258 -287.853882)
		(width 0.1016)
		(layer "F.Cu")
		(net "M_H_CPU1_SA_DQ<26>")
	)
	(segment
		(start 210.598258 -287.848802)
		(end 210.603084 -287.848802)
		(width 0.101854)
		(layer "F.Cu")
		(net "M_H_CPU1_SA_DQ<26>")
	)
	(segment
		(start 210.603084 -287.848802)
		(end 210.610196 -287.84169)
		(width 0.1016)
		(layer "F.Cu")
		(net "M_H_CPU1_SA_DQ<26>")
	)
	(segment
		(start 214.133684 -287.16478)
		(end 214.385652 -287.416748)
		(width 0.20066)
		(layer "F.Cu")
		(net "M_H_CPU1_SA_DQ<26>")
	)
	(segment
		(start 197.212966 -289.564826)
		(end 196.98208 -289.795712)
		(width 0.18288)
		(layer "In11.Cu")
		(net "M_H_CPU1_SA_DQ<26>")
	)
	(segment
		(start 181.142386 -289.59429)
		(end 180.101494 -289.769296)
		(width 0.18288)
		(layer "In11.Cu")
		(net "M_H_CPU1_SA_DQ<26>")
	)
	(segment
		(start 139.280392 -270.957802)
		(end 138.93419 -270.6116)
		(width 0.088646)
		(layer "In11.Cu")
		(net "M_H_CPU1_SA_DQ<26>")
	)
	(segment
		(start 124.594874 -266.941808)
		(end 124.907548 -266.941808)
		(width 0.088646)
		(layer "In11.Cu")
		(net "M_H_CPU1_SA_DQ<26>")
	)
	(segment
		(start 159.186372 -287.862772)
		(end 158.64459 -287.47085)
		(width 0.18288)
		(layer "In11.Cu")
		(net "M_H_CPU1_SA_DQ<26>")
	)
	(segment
		(start 187.938918 -290.392612)
		(end 187.092336 -290.392612)
		(width 0.18288)
		(layer "In11.Cu")
		(net "M_H_CPU1_SA_DQ<26>")
	)
	(segment
		(start 134.11835 -270.521938)
		(end 134.10946 -270.516858)
		(width 0.088646)
		(layer "In11.Cu")
		(net "M_H_CPU1_SA_DQ<26>")
	)
	(segment
		(start 190.202566 -290.276026)
		(end 189.742826 -290.276026)
		(width 0.18288)
		(layer "In11.Cu")
		(net "M_H_CPU1_SA_DQ<26>")
	)
	(segment
		(start 180.101494 -289.769296)
		(end 179.829206 -289.903662)
		(width 0.18288)
		(layer "In11.Cu")
		(net "M_H_CPU1_SA_DQ<26>")
	)
	(segment
		(start 134.507478 -270.513302)
		(end 134.492746 -270.521938)
		(width 0.088646)
		(layer "In11.Cu")
		(net "M_H_CPU1_SA_DQ<26>")
	)
	(segment
		(start 207.071214 -287.416748)
		(end 207.061308 -287.421828)
		(width 0.18288)
		(layer "In11.Cu")
		(net "M_H_CPU1_SA_DQ<26>")
	)
	(segment
		(start 203.408026 -286.991044)
		(end 202.468226 -286.991044)
		(width 0.18288)
		(layer "In11.Cu")
		(net "M_H_CPU1_SA_DQ<26>")
	)
	(segment
		(start 207.061308 -287.421828)
		(end 205.528418 -286.918146)
		(width 0.18288)
		(layer "In11.Cu")
		(net "M_H_CPU1_SA_DQ<26>")
	)
	(segment
		(start 160.655 -288.879026)
		(end 160.425892 -288.650426)
		(width 0.18288)
		(layer "In11.Cu")
		(net "M_H_CPU1_SA_DQ<26>")
	)
	(segment
		(start 196.98208 -289.795712)
		(end 194.992752 -289.795712)
		(width 0.18288)
		(layer "In11.Cu")
		(net "M_H_CPU1_SA_DQ<26>")
	)
	(segment
		(start 203.718668 -286.918146)
		(end 203.408026 -286.991044)
		(width 0.18288)
		(layer "In11.Cu")
		(net "M_H_CPU1_SA_DQ<26>")
	)
	(segment
		(start 137.326878 -270.513302)
		(end 137.312146 -270.521938)
		(width 0.088646)
		(layer "In11.Cu")
		(net "M_H_CPU1_SA_DQ<26>")
	)
	(segment
		(start 182.706264 -289.59429)
		(end 181.142386 -289.59429)
		(width 0.18288)
		(layer "In11.Cu")
		(net "M_H_CPU1_SA_DQ<26>")
	)
	(segment
		(start 192.982596 -291.241988)
		(end 192.030858 -291.240972)
		(width 0.18288)
		(layer "In11.Cu")
		(net "M_H_CPU1_SA_DQ<26>")
	)
	(segment
		(start 187.092336 -290.392612)
		(end 186.953144 -290.531804)
		(width 0.18288)
		(layer "In11.Cu")
		(net "M_H_CPU1_SA_DQ<26>")
	)
	(segment
		(start 171.64177 -292.265862)
		(end 171.641008 -292.265608)
		(width 0.18288)
		(layer "In11.Cu")
		(net "M_H_CPU1_SA_DQ<26>")
	)
	(segment
		(start 131.581398 -267.755878)
		(end 131.581398 -267.741654)
		(width 0.088646)
		(layer "In11.Cu")
		(net "M_H_CPU1_SA_DQ<26>")
	)
	(segment
		(start 169.060876 -290.434268)
		(end 167.987726 -289.784282)
		(width 0.18288)
		(layer "In11.Cu")
		(net "M_H_CPU1_SA_DQ<26>")
	)
	(segment
		(start 139.97305 -271.284192)
		(end 139.64666 -270.957802)
		(width 0.088646)
		(layer "In11.Cu")
		(net "M_H_CPU1_SA_DQ<26>")
	)
	(segment
		(start 126.044706 -267.26007)
		(end 126.034292 -267.266166)
		(width 0.088646)
		(layer "In11.Cu")
		(net "M_H_CPU1_SA_DQ<26>")
	)
	(segment
		(start 172.49775 -292.092126)
		(end 172.324014 -292.265862)
		(width 0.18288)
		(layer "In11.Cu")
		(net "M_H_CPU1_SA_DQ<26>")
	)
	(segment
		(start 188.315346 -290.390834)
		(end 187.940696 -290.390834)
		(width 0.18288)
		(layer "In11.Cu")
		(net "M_H_CPU1_SA_DQ<26>")
	)
	(segment
		(start 183.56834 -289.998658)
		(end 182.706264 -289.59429)
		(width 0.18288)
		(layer "In11.Cu")
		(net "M_H_CPU1_SA_DQ<26>")
	)
	(segment
		(start 205.528418 -286.918146)
		(end 203.718668 -286.918146)
		(width 0.18288)
		(layer "In11.Cu")
		(net "M_H_CPU1_SA_DQ<26>")
	)
	(segment
		(start 166.590726 -289.784282)
		(end 165.496494 -288.69005)
		(width 0.18288)
		(layer "In11.Cu")
		(net "M_H_CPU1_SA_DQ<26>")
	)
	(segment
		(start 167.987726 -289.784282)
		(end 166.590726 -289.784282)
		(width 0.18288)
		(layer "In11.Cu")
		(net "M_H_CPU1_SA_DQ<26>")
	)
	(segment
		(start 139.995148 -271.30629)
		(end 139.97305 -271.284192)
		(width 0.18288)
		(layer "In11.Cu")
		(net "M_H_CPU1_SA_DQ<26>")
	)
	(segment
		(start 193.699892 -290.523168)
		(end 192.982596 -291.241988)
		(width 0.18288)
		(layer "In11.Cu")
		(net "M_H_CPU1_SA_DQ<26>")
	)
	(segment
		(start 187.940696 -290.390834)
		(end 187.938918 -290.392612)
		(width 0.18288)
		(layer "In11.Cu")
		(net "M_H_CPU1_SA_DQ<26>")
	)
	(segment
		(start 177.206402 -291.240972)
		(end 176.382426 -291.240972)
		(width 0.18288)
		(layer "In11.Cu")
		(net "M_H_CPU1_SA_DQ<26>")
	)
	(segment
		(start 184.48401 -290.531804)
		(end 183.56834 -289.998658)
		(width 0.18288)
		(layer "In11.Cu")
		(net "M_H_CPU1_SA_DQ<26>")
	)
	(segment
		(start 136.387078 -270.513302)
		(end 136.372346 -270.521938)
		(width 0.088646)
		(layer "In11.Cu")
		(net "M_H_CPU1_SA_DQ<26>")
	)
	(segment
		(start 171.641008 -292.265608)
		(end 170.145456 -290.770056)
		(width 0.18288)
		(layer "In11.Cu")
		(net "M_H_CPU1_SA_DQ<26>")
	)
	(segment
		(start 131.76885 -268.080236)
		(end 131.75996 -268.075156)
		(width 0.088646)
		(layer "In11.Cu")
		(net "M_H_CPU1_SA_DQ<26>")
	)
	(segment
		(start 133.930898 -270.19758)
		(end 133.930898 -270.18996)
		(width 0.088646)
		(layer "In11.Cu")
		(net "M_H_CPU1_SA_DQ<26>")
	)
	(segment
		(start 164.609526 -288.879026)
		(end 160.655 -288.879026)
		(width 0.18288)
		(layer "In11.Cu")
		(net "M_H_CPU1_SA_DQ<26>")
	)
	(segment
		(start 132.23875 -268.894052)
		(end 132.22986 -268.888972)
		(width 0.088646)
		(layer "In11.Cu")
		(net "M_H_CPU1_SA_DQ<26>")
	)
	(segment
		(start 126.989078 -267.25753)
		(end 126.9746 -267.266166)
		(width 0.088646)
		(layer "In11.Cu")
		(net "M_H_CPU1_SA_DQ<26>")
	)
	(segment
		(start 197.852792 -289.564826)
		(end 197.212966 -289.564826)
		(width 0.18288)
		(layer "In11.Cu")
		(net "M_H_CPU1_SA_DQ<26>")
	)
	(segment
		(start 194.264788 -290.523168)
		(end 193.699892 -290.523168)
		(width 0.18288)
		(layer "In11.Cu")
		(net "M_H_CPU1_SA_DQ<26>")
	)
	(segment
		(start 142.191486 -271.30629)
		(end 139.995148 -271.30629)
		(width 0.18288)
		(layer "In11.Cu")
		(net "M_H_CPU1_SA_DQ<26>")
	)
	(segment
		(start 130.748278 -267.25753)
		(end 130.733546 -267.266166)
		(width 0.088646)
		(layer "In11.Cu")
		(net "M_H_CPU1_SA_DQ<26>")
	)
	(segment
		(start 124.72035 -267.266166)
		(end 124.71146 -267.261086)
		(width 0.088646)
		(layer "In11.Cu")
		(net "M_H_CPU1_SA_DQ<26>")
	)
	(segment
		(start 199.686164 -288.746692)
		(end 199.135746 -288.746692)
		(width 0.18288)
		(layer "In11.Cu")
		(net "M_H_CPU1_SA_DQ<26>")
	)
	(segment
		(start 179.829206 -289.903662)
		(end 179.288948 -290.44392)
		(width 0.18288)
		(layer "In11.Cu")
		(net "M_H_CPU1_SA_DQ<26>")
	)
	(segment
		(start 139.64666 -270.957802)
		(end 139.280392 -270.957802)
		(width 0.088646)
		(layer "In11.Cu")
		(net "M_H_CPU1_SA_DQ<26>")
	)
	(segment
		(start 179.288948 -290.44392)
		(end 178.690016 -290.6268)
		(width 0.18288)
		(layer "In11.Cu")
		(net "M_H_CPU1_SA_DQ<26>")
	)
	(segment
		(start 133.460998 -269.392146)
		(end 133.460998 -269.373604)
		(width 0.088646)
		(layer "In11.Cu")
		(net "M_H_CPU1_SA_DQ<26>")
	)
	(segment
		(start 192.030858 -291.240972)
		(end 191.418972 -291.240972)
		(width 0.18288)
		(layer "In11.Cu")
		(net "M_H_CPU1_SA_DQ<26>")
	)
	(segment
		(start 160.425892 -288.650426)
		(end 159.974026 -288.650426)
		(width 0.18288)
		(layer "In11.Cu")
		(net "M_H_CPU1_SA_DQ<26>")
	)
	(segment
		(start 176.382426 -291.240972)
		(end 174.7901 -291.431726)
		(width 0.18288)
		(layer "In11.Cu")
		(net "M_H_CPU1_SA_DQ<26>")
	)
	(segment
		(start 138.266678 -270.513302)
		(end 138.251946 -270.521938)
		(width 0.088646)
		(layer "In11.Cu")
		(net "M_H_CPU1_SA_DQ<26>")
	)
	(segment
		(start 164.798502 -288.69005)
		(end 164.609526 -288.879026)
		(width 0.18288)
		(layer "In11.Cu")
		(net "M_H_CPU1_SA_DQ<26>")
	)
	(segment
		(start 159.974026 -288.650426)
		(end 159.186372 -287.862772)
		(width 0.18288)
		(layer "In11.Cu")
		(net "M_H_CPU1_SA_DQ<26>")
	)
	(segment
		(start 189.742826 -290.276026)
		(end 188.315346 -290.390834)
		(width 0.18288)
		(layer "In11.Cu")
		(net "M_H_CPU1_SA_DQ<26>")
	)
	(segment
		(start 128.868678 -267.25753)
		(end 128.853946 -267.266166)
		(width 0.088646)
		(layer "In11.Cu")
		(net "M_H_CPU1_SA_DQ<26>")
	)
	(segment
		(start 172.324014 -292.265862)
		(end 171.64177 -292.265862)
		(width 0.18288)
		(layer "In11.Cu")
		(net "M_H_CPU1_SA_DQ<26>")
	)
	(segment
		(start 190.822326 -290.644326)
		(end 190.202566 -290.276026)
		(width 0.18288)
		(layer "In11.Cu")
		(net "M_H_CPU1_SA_DQ<26>")
	)
	(segment
		(start 158.64459 -287.47085)
		(end 156.994352 -285.820612)
		(width 0.18288)
		(layer "In11.Cu")
		(net "M_H_CPU1_SA_DQ<26>")
	)
	(segment
		(start 170.145456 -290.770056)
		(end 169.706036 -290.595812)
		(width 0.18288)
		(layer "In11.Cu")
		(net "M_H_CPU1_SA_DQ<26>")
	)
	(segment
		(start 169.706036 -290.595812)
		(end 169.060876 -290.434268)
		(width 0.18288)
		(layer "In11.Cu")
		(net "M_H_CPU1_SA_DQ<26>")
	)
	(segment
		(start 191.418972 -291.240972)
		(end 190.822326 -290.644326)
		(width 0.18288)
		(layer "In11.Cu")
		(net "M_H_CPU1_SA_DQ<26>")
	)
	(segment
		(start 135.447278 -270.513302)
		(end 135.432546 -270.521938)
		(width 0.088646)
		(layer "In11.Cu")
		(net "M_H_CPU1_SA_DQ<26>")
	)
	(segment
		(start 177.604674 -291.180266)
		(end 177.206402 -291.240972)
		(width 0.18288)
		(layer "In11.Cu")
		(net "M_H_CPU1_SA_DQ<26>")
	)
	(segment
		(start 124.53747 -266.999212)
		(end 124.594874 -266.941808)
		(width 0.088646)
		(layer "In11.Cu")
		(net "M_H_CPU1_SA_DQ<26>")
	)
	(segment
		(start 132.051298 -268.569694)
		(end 132.051298 -268.559788)
		(width 0.088646)
		(layer "In11.Cu")
		(net "M_H_CPU1_SA_DQ<26>")
	)
	(segment
		(start 165.496494 -288.69005)
		(end 164.798502 -288.69005)
		(width 0.18288)
		(layer "In11.Cu")
		(net "M_H_CPU1_SA_DQ<26>")
	)
	(segment
		(start 173.293786 -292.092126)
		(end 172.49775 -292.092126)
		(width 0.18288)
		(layer "In11.Cu")
		(net "M_H_CPU1_SA_DQ<26>")
	)
	(segment
		(start 178.690016 -290.6268)
		(end 177.604674 -291.180266)
		(width 0.18288)
		(layer "In11.Cu")
		(net "M_H_CPU1_SA_DQ<26>")
	)
	(segment
		(start 156.994352 -285.820612)
		(end 156.705808 -285.820612)
		(width 0.18288)
		(layer "In11.Cu")
		(net "M_H_CPU1_SA_DQ<26>")
	)
	(segment
		(start 194.992752 -289.795712)
		(end 194.264788 -290.523168)
		(width 0.18288)
		(layer "In11.Cu")
		(net "M_H_CPU1_SA_DQ<26>")
	)
	(segment
		(start 186.953144 -290.531804)
		(end 184.48401 -290.531804)
		(width 0.18288)
		(layer "In11.Cu")
		(net "M_H_CPU1_SA_DQ<26>")
	)
	(segment
		(start 199.135746 -288.746692)
		(end 198.536306 -288.881312)
		(width 0.18288)
		(layer "In11.Cu")
		(net "M_H_CPU1_SA_DQ<26>")
	)
	(segment
		(start 201.189844 -287.243012)
		(end 199.686164 -288.746692)
		(width 0.18288)
		(layer "In11.Cu")
		(net "M_H_CPU1_SA_DQ<26>")
	)
	(segment
		(start 127.928878 -267.25753)
		(end 127.914146 -267.266166)
		(width 0.088646)
		(layer "In11.Cu")
		(net "M_H_CPU1_SA_DQ<26>")
	)
	(segment
		(start 174.7901 -291.431726)
		(end 173.293786 -292.092126)
		(width 0.18288)
		(layer "In11.Cu")
		(net "M_H_CPU1_SA_DQ<26>")
	)
	(segment
		(start 202.468226 -286.991044)
		(end 201.189844 -287.243012)
		(width 0.18288)
		(layer "In11.Cu")
		(net "M_H_CPU1_SA_DQ<26>")
	)
	(segment
		(start 125.10516 -267.26007)
		(end 125.094746 -267.266166)
		(width 0.088646)
		(layer "In11.Cu")
		(net "M_H_CPU1_SA_DQ<26>")
	)
	(segment
		(start 198.536306 -288.881312)
		(end 197.852792 -289.564826)
		(width 0.18288)
		(layer "In11.Cu")
		(net "M_H_CPU1_SA_DQ<26>")
	)
	(segment
		(start 156.705808 -285.820612)
		(end 142.191486 -271.30629)
		(width 0.18288)
		(layer "In11.Cu")
		(net "M_H_CPU1_SA_DQ<26>")
	)
	(segment
		(start 129.808478 -267.25753)
		(end 129.793746 -267.266166)
		(width 0.088646)
		(layer "In11.Cu")
		(net "M_H_CPU1_SA_DQ<26>")
	)
	(arc
		(start 124.71146 -267.261086)
		(mid 124.595721 -267.149262)
		(end 124.53747 -266.999212)
		(width 0.088646)
		(layer "In11.Cu")
		(net "M_H_CPU1_SA_DQ<26>")
	)
	(arc
		(start 128.853946 -267.266166)
		(mid 128.666748 -267.316309)
		(end 128.47955 -267.266166)
		(width 0.088646)
		(layer "In11.Cu")
		(net "M_H_CPU1_SA_DQ<26>")
	)
	(arc
		(start 127.914146 -267.266166)
		(mid 127.726948 -267.316309)
		(end 127.53975 -267.266166)
		(width 0.088646)
		(layer "In11.Cu")
		(net "M_H_CPU1_SA_DQ<26>")
	)
	(arc
		(start 132.22986 -268.888972)
		(mid 132.098946 -268.752612)
		(end 132.051298 -268.569694)
		(width 0.088646)
		(layer "In11.Cu")
		(net "M_H_CPU1_SA_DQ<26>")
	)
	(arc
		(start 126.034292 -267.266166)
		(mid 125.847094 -267.316309)
		(end 125.659896 -267.266166)
		(width 0.088646)
		(layer "In11.Cu")
		(net "M_H_CPU1_SA_DQ<26>")
	)
	(arc
		(start 137.87755 -270.521938)
		(mid 137.603351 -270.446103)
		(end 137.326878 -270.513302)
		(width 0.088646)
		(layer "In11.Cu")
		(net "M_H_CPU1_SA_DQ<26>")
	)
	(arc
		(start 135.05815 -270.521938)
		(mid 134.783951 -270.446103)
		(end 134.507478 -270.513302)
		(width 0.088646)
		(layer "In11.Cu")
		(net "M_H_CPU1_SA_DQ<26>")
	)
	(arc
		(start 136.372346 -270.521938)
		(mid 136.185148 -270.572081)
		(end 135.99795 -270.521938)
		(width 0.088646)
		(layer "In11.Cu")
		(net "M_H_CPU1_SA_DQ<26>")
	)
	(arc
		(start 125.094746 -267.266166)
		(mid 124.907548 -267.316309)
		(end 124.72035 -267.266166)
		(width 0.088646)
		(layer "In11.Cu")
		(net "M_H_CPU1_SA_DQ<26>")
	)
	(arc
		(start 126.9746 -267.266166)
		(mid 126.787292 -267.316309)
		(end 126.59995 -267.266166)
		(width 0.088646)
		(layer "In11.Cu")
		(net "M_H_CPU1_SA_DQ<26>")
	)
	(arc
		(start 131.29895 -267.266166)
		(mid 131.024721 -267.190241)
		(end 130.748278 -267.25753)
		(width 0.088646)
		(layer "In11.Cu")
		(net "M_H_CPU1_SA_DQ<26>")
	)
	(arc
		(start 127.53975 -267.266166)
		(mid 127.265521 -267.190241)
		(end 126.989078 -267.25753)
		(width 0.088646)
		(layer "In11.Cu")
		(net "M_H_CPU1_SA_DQ<26>")
	)
	(arc
		(start 125.659896 -267.266166)
		(mid 125.383337 -267.190457)
		(end 125.10516 -267.26007)
		(width 0.088646)
		(layer "In11.Cu")
		(net "M_H_CPU1_SA_DQ<26>")
	)
	(arc
		(start 135.99795 -270.521938)
		(mid 135.723751 -270.446103)
		(end 135.447278 -270.513302)
		(width 0.088646)
		(layer "In11.Cu")
		(net "M_H_CPU1_SA_DQ<26>")
	)
	(arc
		(start 132.051298 -268.559788)
		(mid 131.973187 -268.282839)
		(end 131.76885 -268.080236)
		(width 0.088646)
		(layer "In11.Cu")
		(net "M_H_CPU1_SA_DQ<26>")
	)
	(arc
		(start 129.793746 -267.266166)
		(mid 129.606548 -267.316309)
		(end 129.41935 -267.266166)
		(width 0.088646)
		(layer "In11.Cu")
		(net "M_H_CPU1_SA_DQ<26>")
	)
	(arc
		(start 137.312146 -270.521938)
		(mid 137.124948 -270.572081)
		(end 136.93775 -270.521938)
		(width 0.088646)
		(layer "In11.Cu")
		(net "M_H_CPU1_SA_DQ<26>")
	)
	(arc
		(start 130.35915 -267.266166)
		(mid 130.084921 -267.190241)
		(end 129.808478 -267.25753)
		(width 0.088646)
		(layer "In11.Cu")
		(net "M_H_CPU1_SA_DQ<26>")
	)
	(arc
		(start 138.251946 -270.521938)
		(mid 138.064748 -270.572081)
		(end 137.87755 -270.521938)
		(width 0.088646)
		(layer "In11.Cu")
		(net "M_H_CPU1_SA_DQ<26>")
	)
	(arc
		(start 131.581398 -267.741654)
		(mid 131.502257 -267.467031)
		(end 131.29895 -267.266166)
		(width 0.088646)
		(layer "In11.Cu")
		(net "M_H_CPU1_SA_DQ<26>")
	)
	(arc
		(start 131.75996 -268.075156)
		(mid 131.629046 -267.938796)
		(end 131.581398 -267.755878)
		(width 0.088646)
		(layer "In11.Cu")
		(net "M_H_CPU1_SA_DQ<26>")
	)
	(arc
		(start 134.492746 -270.521938)
		(mid 134.305548 -270.572081)
		(end 134.11835 -270.521938)
		(width 0.088646)
		(layer "In11.Cu")
		(net "M_H_CPU1_SA_DQ<26>")
	)
	(arc
		(start 132.613146 -268.894052)
		(mid 132.425948 -268.944195)
		(end 132.23875 -268.894052)
		(width 0.088646)
		(layer "In11.Cu")
		(net "M_H_CPU1_SA_DQ<26>")
	)
	(arc
		(start 135.432546 -270.521938)
		(mid 135.245348 -270.572081)
		(end 135.05815 -270.521938)
		(width 0.088646)
		(layer "In11.Cu")
		(net "M_H_CPU1_SA_DQ<26>")
	)
	(arc
		(start 126.59995 -267.266166)
		(mid 126.323137 -267.19033)
		(end 126.044706 -267.26007)
		(width 0.088646)
		(layer "In11.Cu")
		(net "M_H_CPU1_SA_DQ<26>")
	)
	(arc
		(start 129.41935 -267.266166)
		(mid 129.145121 -267.190241)
		(end 128.868678 -267.25753)
		(width 0.088646)
		(layer "In11.Cu")
		(net "M_H_CPU1_SA_DQ<26>")
	)
	(arc
		(start 133.930898 -270.18996)
		(mid 133.853269 -269.911547)
		(end 133.648196 -269.707868)
		(width 0.088646)
		(layer "In11.Cu")
		(net "M_H_CPU1_SA_DQ<26>")
	)
	(arc
		(start 133.17855 -268.894052)
		(mid 132.895848 -268.818276)
		(end 132.613146 -268.894052)
		(width 0.088646)
		(layer "In11.Cu")
		(net "M_H_CPU1_SA_DQ<26>")
	)
	(arc
		(start 136.93775 -270.521938)
		(mid 136.663551 -270.446103)
		(end 136.387078 -270.513302)
		(width 0.088646)
		(layer "In11.Cu")
		(net "M_H_CPU1_SA_DQ<26>")
	)
	(arc
		(start 138.93419 -270.6116)
		(mid 138.61671 -270.452023)
		(end 138.266678 -270.513302)
		(width 0.088646)
		(layer "In11.Cu")
		(net "M_H_CPU1_SA_DQ<26>")
	)
	(arc
		(start 134.10946 -270.516858)
		(mid 133.978546 -270.380498)
		(end 133.930898 -270.19758)
		(width 0.088646)
		(layer "In11.Cu")
		(net "M_H_CPU1_SA_DQ<26>")
	)
	(arc
		(start 130.733546 -267.266166)
		(mid 130.546348 -267.316309)
		(end 130.35915 -267.266166)
		(width 0.088646)
		(layer "In11.Cu")
		(net "M_H_CPU1_SA_DQ<26>")
	)
	(arc
		(start 133.460998 -269.373604)
		(mid 133.382887 -269.096655)
		(end 133.17855 -268.894052)
		(width 0.088646)
		(layer "In11.Cu")
		(net "M_H_CPU1_SA_DQ<26>")
	)
	(arc
		(start 128.47955 -267.266166)
		(mid 128.205321 -267.190241)
		(end 127.928878 -267.25753)
		(width 0.088646)
		(layer "In11.Cu")
		(net "M_H_CPU1_SA_DQ<26>")
	)
	(arc
		(start 133.648196 -269.707868)
		(mid 133.513263 -269.574514)
		(end 133.460998 -269.392146)
		(width 0.088646)
		(layer "In11.Cu")
		(net "M_H_CPU1_SA_DQ<26>")
	)
	(segment
		(start 206.508604 -286.259778)
		(end 206.508604 -286.627316)
		(width 0.20066)
		(layer "F.Cu")
		(net "M_H_CPU1_SA_DQ<25>")
	)
	(segment
		(start 209.180176 -286.141668)
		(end 206.991458 -286.141668)
		(width 0.1016)
		(layer "F.Cu")
		(net "M_H_CPU1_SA_DQ<25>")
	)
	(segment
		(start 123.497848 -265.592306)
		(end 123.497848 -266.127992)
		(width 0.20066)
		(layer "F.Cu")
		(net "M_H_CPU1_SA_DQ<25>")
	)
	(segment
		(start 206.626714 -286.141668)
		(end 206.508604 -286.259778)
		(width 0.20066)
		(layer "F.Cu")
		(net "M_H_CPU1_SA_DQ<25>")
	)
	(segment
		(start 209.186526 -286.135318)
		(end 209.180176 -286.141668)
		(width 0.1016)
		(layer "F.Cu")
		(net "M_H_CPU1_SA_DQ<25>")
	)
	(segment
		(start 210.028028 -286.566864)
		(end 209.596482 -286.135318)
		(width 0.20066)
		(layer "F.Cu")
		(net "M_H_CPU1_SA_DQ<25>")
	)
	(segment
		(start 205.596744 -286.56661)
		(end 204.076046 -286.56661)
		(width 0.20066)
		(layer "F.Cu")
		(net "M_H_CPU1_SA_DQ<25>")
	)
	(segment
		(start 206.991458 -286.141668)
		(end 206.971392 -286.141668)
		(width 0.101854)
		(layer "F.Cu")
		(net "M_H_CPU1_SA_DQ<25>")
	)
	(segment
		(start 206.320644 -286.815276)
		(end 205.84541 -286.815276)
		(width 0.20066)
		(layer "F.Cu")
		(net "M_H_CPU1_SA_DQ<25>")
	)
	(segment
		(start 205.84541 -286.815276)
		(end 205.596744 -286.56661)
		(width 0.20066)
		(layer "F.Cu")
		(net "M_H_CPU1_SA_DQ<25>")
	)
	(segment
		(start 123.497848 -266.127992)
		(end 123.497594 -266.128246)
		(width 0.20066)
		(layer "F.Cu")
		(net "M_H_CPU1_SA_DQ<25>")
	)
	(segment
		(start 206.508604 -286.627316)
		(end 206.320644 -286.815276)
		(width 0.20066)
		(layer "F.Cu")
		(net "M_H_CPU1_SA_DQ<25>")
	)
	(segment
		(start 204.076046 -286.56661)
		(end 202.971146 -286.56661)
		(width 0.20066)
		(layer "F.Cu")
		(net "M_H_CPU1_SA_DQ<25>")
	)
	(segment
		(start 211.619592 -286.566864)
		(end 210.028028 -286.566864)
		(width 0.20066)
		(layer "F.Cu")
		(net "M_H_CPU1_SA_DQ<25>")
	)
	(segment
		(start 211.619846 -286.56661)
		(end 211.619592 -286.566864)
		(width 0.20066)
		(layer "F.Cu")
		(net "M_H_CPU1_SA_DQ<25>")
	)
	(segment
		(start 209.596482 -286.135318)
		(end 209.186526 -286.135318)
		(width 0.20066)
		(layer "F.Cu")
		(net "M_H_CPU1_SA_DQ<25>")
	)
	(segment
		(start 206.971392 -286.141668)
		(end 206.626714 -286.141668)
		(width 0.20066)
		(layer "F.Cu")
		(net "M_H_CPU1_SA_DQ<25>")
	)
	(segment
		(start 196.84746 -289.02533)
		(end 196.65442 -289.21837)
		(width 0.18288)
		(layer "In11.Cu")
		(net "M_H_CPU1_SA_DQ<25>")
	)
	(segment
		(start 127.928878 -266.62634)
		(end 127.914146 -266.617704)
		(width 0.088646)
		(layer "In11.Cu")
		(net "M_H_CPU1_SA_DQ<25>")
	)
	(segment
		(start 194.46113 -289.392868)
		(end 193.863468 -289.392868)
		(width 0.18288)
		(layer "In11.Cu")
		(net "M_H_CPU1_SA_DQ<25>")
	)
	(segment
		(start 195.95084 -288.594292)
		(end 195.259706 -288.594292)
		(width 0.18288)
		(layer "In11.Cu")
		(net "M_H_CPU1_SA_DQ<25>")
	)
	(segment
		(start 176.125124 -290.390834)
		(end 175.993552 -290.259262)
		(width 0.18288)
		(layer "In11.Cu")
		(net "M_H_CPU1_SA_DQ<25>")
	)
	(segment
		(start 138.478768 -270.093948)
		(end 138.266678 -269.881858)
		(width 0.088646)
		(layer "In11.Cu")
		(net "M_H_CPU1_SA_DQ<25>")
	)
	(segment
		(start 192.865502 -290.390834)
		(end 191.305688 -290.390834)
		(width 0.18288)
		(layer "In11.Cu")
		(net "M_H_CPU1_SA_DQ<25>")
	)
	(segment
		(start 187.13196 -289.541966)
		(end 186.972956 -289.382962)
		(width 0.18288)
		(layer "In11.Cu")
		(net "M_H_CPU1_SA_DQ<25>")
	)
	(segment
		(start 179.544472 -289.26536)
		(end 178.97856 -289.26536)
		(width 0.18288)
		(layer "In11.Cu")
		(net "M_H_CPU1_SA_DQ<25>")
	)
	(segment
		(start 140.047218 -270.40967)
		(end 139.731496 -270.093948)
		(width 0.088646)
		(layer "In11.Cu")
		(net "M_H_CPU1_SA_DQ<25>")
	)
	(segment
		(start 181.800246 -288.886646)
		(end 181.607206 -289.079686)
		(width 0.18288)
		(layer "In11.Cu")
		(net "M_H_CPU1_SA_DQ<25>")
	)
	(segment
		(start 181.800246 -288.74593)
		(end 181.800246 -288.886646)
		(width 0.18288)
		(layer "In11.Cu")
		(net "M_H_CPU1_SA_DQ<25>")
	)
	(segment
		(start 162.458146 -288.18713)
		(end 162.007042 -287.736026)
		(width 0.18288)
		(layer "In11.Cu")
		(net "M_H_CPU1_SA_DQ<25>")
	)
	(segment
		(start 156.813758 -285.104332)
		(end 142.48384 -270.774414)
		(width 0.18288)
		(layer "In11.Cu")
		(net "M_H_CPU1_SA_DQ<25>")
	)
	(segment
		(start 167.98925 -288.567114)
		(end 166.355268 -288.567114)
		(width 0.18288)
		(layer "In11.Cu")
		(net "M_H_CPU1_SA_DQ<25>")
	)
	(segment
		(start 191.305688 -290.390834)
		(end 190.644526 -289.729672)
		(width 0.18288)
		(layer "In11.Cu")
		(net "M_H_CPU1_SA_DQ<25>")
	)
	(segment
		(start 164.330126 -287.736026)
		(end 163.779454 -287.736026)
		(width 0.18288)
		(layer "In11.Cu")
		(net "M_H_CPU1_SA_DQ<25>")
	)
	(segment
		(start 202.971146 -286.56661)
		(end 202.971146 -286.417004)
		(width 0.18288)
		(layer "In11.Cu")
		(net "M_H_CPU1_SA_DQ<25>")
	)
	(segment
		(start 197.0405 -288.594292)
		(end 196.84746 -288.787332)
		(width 0.18288)
		(layer "In11.Cu")
		(net "M_H_CPU1_SA_DQ<25>")
	)
	(segment
		(start 134.031482 -269.064232)
		(end 134.022592 -269.059152)
		(width 0.088646)
		(layer "In11.Cu")
		(net "M_H_CPU1_SA_DQ<25>")
	)
	(segment
		(start 196.84746 -288.787332)
		(end 196.84746 -289.02533)
		(width 0.18288)
		(layer "In11.Cu")
		(net "M_H_CPU1_SA_DQ<25>")
	)
	(segment
		(start 171.211494 -291.074094)
		(end 169.52849 -289.39109)
		(width 0.18288)
		(layer "In11.Cu")
		(net "M_H_CPU1_SA_DQ<25>")
	)
	(segment
		(start 158.375096 -285.64967)
		(end 157.829758 -285.104332)
		(width 0.18288)
		(layer "In11.Cu")
		(net "M_H_CPU1_SA_DQ<25>")
	)
	(segment
		(start 172.308774 -291.241734)
		(end 172.141134 -291.074094)
		(width 0.18288)
		(layer "In11.Cu")
		(net "M_H_CPU1_SA_DQ<25>")
	)
	(segment
		(start 180.256942 -288.55289)
		(end 179.544472 -289.26536)
		(width 0.18288)
		(layer "In11.Cu")
		(net "M_H_CPU1_SA_DQ<25>")
	)
	(segment
		(start 193.863468 -289.392868)
		(end 192.865502 -290.390834)
		(width 0.18288)
		(layer "In11.Cu")
		(net "M_H_CPU1_SA_DQ<25>")
	)
	(segment
		(start 186.972956 -289.382962)
		(end 184.082182 -289.382962)
		(width 0.18288)
		(layer "In11.Cu")
		(net "M_H_CPU1_SA_DQ<25>")
	)
	(segment
		(start 131.860544 -266.956032)
		(end 131.860544 -266.941808)
		(width 0.088646)
		(layer "In11.Cu")
		(net "M_H_CPU1_SA_DQ<25>")
	)
	(segment
		(start 196.14388 -289.02533)
		(end 196.14388 -288.787332)
		(width 0.18288)
		(layer "In11.Cu")
		(net "M_H_CPU1_SA_DQ<25>")
	)
	(segment
		(start 158.193232 -286.057848)
		(end 158.375096 -285.87573)
		(width 0.18288)
		(layer "In11.Cu")
		(net "M_H_CPU1_SA_DQ<25>")
	)
	(segment
		(start 175.993552 -290.259262)
		(end 174.442374 -290.259262)
		(width 0.18288)
		(layer "In11.Cu")
		(net "M_H_CPU1_SA_DQ<25>")
	)
	(segment
		(start 131.68122 -266.622276)
		(end 131.673346 -266.617704)
		(width 0.088646)
		(layer "In11.Cu")
		(net "M_H_CPU1_SA_DQ<25>")
	)
	(segment
		(start 132.330444 -267.755878)
		(end 132.330444 -267.747242)
		(width 0.088646)
		(layer "In11.Cu")
		(net "M_H_CPU1_SA_DQ<25>")
	)
	(segment
		(start 181.096666 -288.74593)
		(end 180.903626 -288.55289)
		(width 0.18288)
		(layer "In11.Cu")
		(net "M_H_CPU1_SA_DQ<25>")
	)
	(segment
		(start 181.607206 -289.079686)
		(end 181.289706 -289.079686)
		(width 0.18288)
		(layer "In11.Cu")
		(net "M_H_CPU1_SA_DQ<25>")
	)
	(segment
		(start 166.355268 -288.567114)
		(end 165.958266 -288.170112)
		(width 0.18288)
		(layer "In11.Cu")
		(net "M_H_CPU1_SA_DQ<25>")
	)
	(segment
		(start 132.627878 -268.253972)
		(end 132.613146 -268.245336)
		(width 0.088646)
		(layer "In11.Cu")
		(net "M_H_CPU1_SA_DQ<25>")
	)
	(segment
		(start 129.808478 -266.62634)
		(end 129.793746 -266.617704)
		(width 0.088646)
		(layer "In11.Cu")
		(net "M_H_CPU1_SA_DQ<25>")
	)
	(segment
		(start 137.326878 -269.881858)
		(end 137.312146 -269.873222)
		(width 0.088646)
		(layer "In11.Cu")
		(net "M_H_CPU1_SA_DQ<25>")
	)
	(segment
		(start 184.082182 -289.382962)
		(end 183.25211 -288.55289)
		(width 0.18288)
		(layer "In11.Cu")
		(net "M_H_CPU1_SA_DQ<25>")
	)
	(segment
		(start 195.259706 -288.594292)
		(end 194.46113 -289.392868)
		(width 0.18288)
		(layer "In11.Cu")
		(net "M_H_CPU1_SA_DQ<25>")
	)
	(segment
		(start 181.289706 -289.079686)
		(end 181.096666 -288.886646)
		(width 0.18288)
		(layer "In11.Cu")
		(net "M_H_CPU1_SA_DQ<25>")
	)
	(segment
		(start 159.644334 -286.918908)
		(end 159.073596 -286.34817)
		(width 0.18288)
		(layer "In11.Cu")
		(net "M_H_CPU1_SA_DQ<25>")
	)
	(segment
		(start 201.46391 -286.034226)
		(end 199.716644 -287.781492)
		(width 0.18288)
		(layer "In11.Cu")
		(net "M_H_CPU1_SA_DQ<25>")
	)
	(segment
		(start 202.971146 -286.417004)
		(end 202.910186 -286.269684)
		(width 0.18288)
		(layer "In11.Cu")
		(net "M_H_CPU1_SA_DQ<25>")
	)
	(segment
		(start 174.442374 -290.259262)
		(end 173.459902 -291.241734)
		(width 0.18288)
		(layer "In11.Cu")
		(net "M_H_CPU1_SA_DQ<25>")
	)
	(segment
		(start 188.457332 -289.541966)
		(end 187.13196 -289.541966)
		(width 0.18288)
		(layer "In11.Cu")
		(net "M_H_CPU1_SA_DQ<25>")
	)
	(segment
		(start 142.48384 -270.774414)
		(end 140.651738 -270.774414)
		(width 0.18288)
		(layer "In11.Cu")
		(net "M_H_CPU1_SA_DQ<25>")
	)
	(segment
		(start 140.047218 -270.51127)
		(end 140.047218 -270.40967)
		(width 0.088646)
		(layer "In11.Cu")
		(net "M_H_CPU1_SA_DQ<25>")
	)
	(segment
		(start 173.459902 -291.241734)
		(end 172.308774 -291.241734)
		(width 0.18288)
		(layer "In11.Cu")
		(net "M_H_CPU1_SA_DQ<25>")
	)
	(segment
		(start 138.266678 -269.881858)
		(end 138.251946 -269.873222)
		(width 0.088646)
		(layer "In11.Cu")
		(net "M_H_CPU1_SA_DQ<25>")
	)
	(segment
		(start 124.2822 -266.502134)
		(end 123.497594 -266.128246)
		(width 0.088646)
		(layer "In11.Cu")
		(net "M_H_CPU1_SA_DQ<25>")
	)
	(segment
		(start 158.847536 -286.34817)
		(end 158.665672 -286.530288)
		(width 0.18288)
		(layer "In11.Cu")
		(net "M_H_CPU1_SA_DQ<25>")
	)
	(segment
		(start 160.295336 -286.918908)
		(end 159.644334 -286.918908)
		(width 0.18288)
		(layer "In11.Cu")
		(net "M_H_CPU1_SA_DQ<25>")
	)
	(segment
		(start 190.644526 -289.729672)
		(end 188.645038 -289.729672)
		(width 0.18288)
		(layer "In11.Cu")
		(net "M_H_CPU1_SA_DQ<25>")
	)
	(segment
		(start 196.14388 -288.787332)
		(end 195.95084 -288.594292)
		(width 0.18288)
		(layer "In11.Cu")
		(net "M_H_CPU1_SA_DQ<25>")
	)
	(segment
		(start 158.193232 -286.283908)
		(end 158.193232 -286.057848)
		(width 0.18288)
		(layer "In11.Cu")
		(net "M_H_CPU1_SA_DQ<25>")
	)
	(segment
		(start 136.387078 -269.881858)
		(end 136.372346 -269.873222)
		(width 0.088646)
		(layer "In11.Cu")
		(net "M_H_CPU1_SA_DQ<25>")
	)
	(segment
		(start 168.813226 -289.39109)
		(end 167.98925 -288.567114)
		(width 0.18288)
		(layer "In11.Cu")
		(net "M_H_CPU1_SA_DQ<25>")
	)
	(segment
		(start 159.073596 -286.34817)
		(end 158.847536 -286.34817)
		(width 0.18288)
		(layer "In11.Cu")
		(net "M_H_CPU1_SA_DQ<25>")
	)
	(segment
		(start 135.447278 -269.881858)
		(end 135.432546 -269.873222)
		(width 0.088646)
		(layer "In11.Cu")
		(net "M_H_CPU1_SA_DQ<25>")
	)
	(segment
		(start 198.68896 -287.781492)
		(end 197.87616 -288.594292)
		(width 0.18288)
		(layer "In11.Cu")
		(net "M_H_CPU1_SA_DQ<25>")
	)
	(segment
		(start 157.829758 -285.104332)
		(end 156.813758 -285.104332)
		(width 0.18288)
		(layer "In11.Cu")
		(net "M_H_CPU1_SA_DQ<25>")
	)
	(segment
		(start 202.674728 -286.034226)
		(end 201.46391 -286.034226)
		(width 0.18288)
		(layer "In11.Cu")
		(net "M_H_CPU1_SA_DQ<25>")
	)
	(segment
		(start 124.42825 -266.502642)
		(end 124.2822 -266.502134)
		(width 0.088646)
		(layer "In11.Cu")
		(net "M_H_CPU1_SA_DQ<25>")
	)
	(segment
		(start 126.989078 -266.62634)
		(end 126.974346 -266.617704)
		(width 0.088646)
		(layer "In11.Cu")
		(net "M_H_CPU1_SA_DQ<25>")
	)
	(segment
		(start 128.868678 -266.62634)
		(end 128.853946 -266.617704)
		(width 0.088646)
		(layer "In11.Cu")
		(net "M_H_CPU1_SA_DQ<25>")
	)
	(segment
		(start 134.210044 -269.397734)
		(end 134.210044 -269.38351)
		(width 0.088646)
		(layer "In11.Cu")
		(net "M_H_CPU1_SA_DQ<25>")
	)
	(segment
		(start 199.716644 -287.781492)
		(end 198.68896 -287.781492)
		(width 0.18288)
		(layer "In11.Cu")
		(net "M_H_CPU1_SA_DQ<25>")
	)
	(segment
		(start 178.97856 -289.26536)
		(end 177.853086 -290.390834)
		(width 0.18288)
		(layer "In11.Cu")
		(net "M_H_CPU1_SA_DQ<25>")
	)
	(segment
		(start 163.779454 -287.736026)
		(end 163.32835 -288.18713)
		(width 0.18288)
		(layer "In11.Cu")
		(net "M_H_CPU1_SA_DQ<25>")
	)
	(segment
		(start 181.993286 -288.55289)
		(end 181.800246 -288.74593)
		(width 0.18288)
		(layer "In11.Cu")
		(net "M_H_CPU1_SA_DQ<25>")
	)
	(segment
		(start 134.507478 -269.881858)
		(end 134.492746 -269.873222)
		(width 0.088646)
		(layer "In11.Cu")
		(net "M_H_CPU1_SA_DQ<25>")
	)
	(segment
		(start 158.439612 -286.530288)
		(end 158.193232 -286.283908)
		(width 0.18288)
		(layer "In11.Cu")
		(net "M_H_CPU1_SA_DQ<25>")
	)
	(segment
		(start 140.310362 -270.774414)
		(end 140.047218 -270.51127)
		(width 0.088646)
		(layer "In11.Cu")
		(net "M_H_CPU1_SA_DQ<25>")
	)
	(segment
		(start 139.731496 -270.093948)
		(end 138.478768 -270.093948)
		(width 0.088646)
		(layer "In11.Cu")
		(net "M_H_CPU1_SA_DQ<25>")
	)
	(segment
		(start 140.651738 -270.774414)
		(end 140.310362 -270.774414)
		(width 0.088646)
		(layer "In11.Cu")
		(net "M_H_CPU1_SA_DQ<25>")
	)
	(segment
		(start 133.561836 -268.250416)
		(end 133.552946 -268.245336)
		(width 0.088646)
		(layer "In11.Cu")
		(net "M_H_CPU1_SA_DQ<25>")
	)
	(segment
		(start 181.096666 -288.886646)
		(end 181.096666 -288.74593)
		(width 0.18288)
		(layer "In11.Cu")
		(net "M_H_CPU1_SA_DQ<25>")
	)
	(segment
		(start 165.958266 -288.170112)
		(end 164.764212 -288.170112)
		(width 0.18288)
		(layer "In11.Cu")
		(net "M_H_CPU1_SA_DQ<25>")
	)
	(segment
		(start 158.375096 -285.87573)
		(end 158.375096 -285.64967)
		(width 0.18288)
		(layer "In11.Cu")
		(net "M_H_CPU1_SA_DQ<25>")
	)
	(segment
		(start 161.112454 -287.736026)
		(end 160.295336 -286.918908)
		(width 0.18288)
		(layer "In11.Cu")
		(net "M_H_CPU1_SA_DQ<25>")
	)
	(segment
		(start 196.65442 -289.21837)
		(end 196.33692 -289.21837)
		(width 0.18288)
		(layer "In11.Cu")
		(net "M_H_CPU1_SA_DQ<25>")
	)
	(segment
		(start 125.610874 -266.502642)
		(end 124.42825 -266.502642)
		(width 0.088646)
		(layer "In11.Cu")
		(net "M_H_CPU1_SA_DQ<25>")
	)
	(segment
		(start 164.764212 -288.170112)
		(end 164.330126 -287.736026)
		(width 0.18288)
		(layer "In11.Cu")
		(net "M_H_CPU1_SA_DQ<25>")
	)
	(segment
		(start 177.853086 -290.390834)
		(end 176.125124 -290.390834)
		(width 0.18288)
		(layer "In11.Cu")
		(net "M_H_CPU1_SA_DQ<25>")
	)
	(segment
		(start 132.613146 -268.245336)
		(end 132.60705 -268.24178)
		(width 0.088646)
		(layer "In11.Cu")
		(net "M_H_CPU1_SA_DQ<25>")
	)
	(segment
		(start 126.035054 -266.617704)
		(end 126.034292 -266.61745)
		(width 0.088646)
		(layer "In11.Cu")
		(net "M_H_CPU1_SA_DQ<25>")
	)
	(segment
		(start 196.33692 -289.21837)
		(end 196.14388 -289.02533)
		(width 0.18288)
		(layer "In11.Cu")
		(net "M_H_CPU1_SA_DQ<25>")
	)
	(segment
		(start 197.87616 -288.594292)
		(end 197.0405 -288.594292)
		(width 0.18288)
		(layer "In11.Cu")
		(net "M_H_CPU1_SA_DQ<25>")
	)
	(segment
		(start 188.645038 -289.729672)
		(end 188.457332 -289.541966)
		(width 0.18288)
		(layer "In11.Cu")
		(net "M_H_CPU1_SA_DQ<25>")
	)
	(segment
		(start 158.665672 -286.530288)
		(end 158.439612 -286.530288)
		(width 0.18288)
		(layer "In11.Cu")
		(net "M_H_CPU1_SA_DQ<25>")
	)
	(segment
		(start 130.748278 -266.62634)
		(end 130.733546 -266.617704)
		(width 0.088646)
		(layer "In11.Cu")
		(net "M_H_CPU1_SA_DQ<25>")
	)
	(segment
		(start 162.007042 -287.736026)
		(end 161.112454 -287.736026)
		(width 0.18288)
		(layer "In11.Cu")
		(net "M_H_CPU1_SA_DQ<25>")
	)
	(segment
		(start 133.740398 -268.585188)
		(end 133.740398 -268.569694)
		(width 0.088646)
		(layer "In11.Cu")
		(net "M_H_CPU1_SA_DQ<25>")
	)
	(segment
		(start 202.910186 -286.269684)
		(end 202.674728 -286.034226)
		(width 0.18288)
		(layer "In11.Cu")
		(net "M_H_CPU1_SA_DQ<25>")
	)
	(segment
		(start 163.32835 -288.18713)
		(end 162.458146 -288.18713)
		(width 0.18288)
		(layer "In11.Cu")
		(net "M_H_CPU1_SA_DQ<25>")
	)
	(segment
		(start 183.25211 -288.55289)
		(end 181.993286 -288.55289)
		(width 0.18288)
		(layer "In11.Cu")
		(net "M_H_CPU1_SA_DQ<25>")
	)
	(segment
		(start 180.903626 -288.55289)
		(end 180.256942 -288.55289)
		(width 0.18288)
		(layer "In11.Cu")
		(net "M_H_CPU1_SA_DQ<25>")
	)
	(segment
		(start 172.141134 -291.074094)
		(end 171.211494 -291.074094)
		(width 0.18288)
		(layer "In11.Cu")
		(net "M_H_CPU1_SA_DQ<25>")
	)
	(segment
		(start 169.52849 -289.39109)
		(end 168.813226 -289.39109)
		(width 0.18288)
		(layer "In11.Cu")
		(net "M_H_CPU1_SA_DQ<25>")
	)
	(arc
		(start 134.492746 -269.873222)
		(mid 134.289265 -269.672418)
		(end 134.210044 -269.397734)
		(width 0.088646)
		(layer "In11.Cu")
		(net "M_H_CPU1_SA_DQ<25>")
	)
	(arc
		(start 138.251946 -269.873222)
		(mid 138.064748 -269.823079)
		(end 137.87755 -269.873222)
		(width 0.088646)
		(layer "In11.Cu")
		(net "M_H_CPU1_SA_DQ<25>")
	)
	(arc
		(start 127.53975 -266.617704)
		(mid 127.265551 -266.693539)
		(end 126.989078 -266.62634)
		(width 0.088646)
		(layer "In11.Cu")
		(net "M_H_CPU1_SA_DQ<25>")
	)
	(arc
		(start 132.143246 -267.43152)
		(mid 131.939765 -267.230716)
		(end 131.860544 -266.956032)
		(width 0.088646)
		(layer "In11.Cu")
		(net "M_H_CPU1_SA_DQ<25>")
	)
	(arc
		(start 128.853946 -266.617704)
		(mid 128.666748 -266.567527)
		(end 128.47955 -266.617704)
		(width 0.088646)
		(layer "In11.Cu")
		(net "M_H_CPU1_SA_DQ<25>")
	)
	(arc
		(start 126.59995 -266.617704)
		(mid 126.317502 -266.693421)
		(end 126.035054 -266.617704)
		(width 0.088646)
		(layer "In11.Cu")
		(net "M_H_CPU1_SA_DQ<25>")
	)
	(arc
		(start 131.860544 -266.941808)
		(mid 131.812653 -266.758596)
		(end 131.68122 -266.622276)
		(width 0.088646)
		(layer "In11.Cu")
		(net "M_H_CPU1_SA_DQ<25>")
	)
	(arc
		(start 130.733546 -266.617704)
		(mid 130.546348 -266.567527)
		(end 130.35915 -266.617704)
		(width 0.088646)
		(layer "In11.Cu")
		(net "M_H_CPU1_SA_DQ<25>")
	)
	(arc
		(start 131.673346 -266.617704)
		(mid 131.486148 -266.567527)
		(end 131.29895 -266.617704)
		(width 0.088646)
		(layer "In11.Cu")
		(net "M_H_CPU1_SA_DQ<25>")
	)
	(arc
		(start 135.432546 -269.873222)
		(mid 135.245348 -269.823079)
		(end 135.05815 -269.873222)
		(width 0.088646)
		(layer "In11.Cu")
		(net "M_H_CPU1_SA_DQ<25>")
	)
	(arc
		(start 134.022592 -269.059152)
		(mid 133.819769 -268.858921)
		(end 133.740398 -268.585188)
		(width 0.088646)
		(layer "In11.Cu")
		(net "M_H_CPU1_SA_DQ<25>")
	)
	(arc
		(start 135.99795 -269.873222)
		(mid 135.723721 -269.949147)
		(end 135.447278 -269.881858)
		(width 0.088646)
		(layer "In11.Cu")
		(net "M_H_CPU1_SA_DQ<25>")
	)
	(arc
		(start 134.210044 -269.38351)
		(mid 134.162365 -269.20061)
		(end 134.031482 -269.064232)
		(width 0.088646)
		(layer "In11.Cu")
		(net "M_H_CPU1_SA_DQ<25>")
	)
	(arc
		(start 132.330444 -267.747242)
		(mid 132.278174 -267.564877)
		(end 132.143246 -267.43152)
		(width 0.088646)
		(layer "In11.Cu")
		(net "M_H_CPU1_SA_DQ<25>")
	)
	(arc
		(start 130.35915 -266.617704)
		(mid 130.084951 -266.693539)
		(end 129.808478 -266.62634)
		(width 0.088646)
		(layer "In11.Cu")
		(net "M_H_CPU1_SA_DQ<25>")
	)
	(arc
		(start 133.552946 -268.245336)
		(mid 133.365748 -268.195193)
		(end 133.17855 -268.245336)
		(width 0.088646)
		(layer "In11.Cu")
		(net "M_H_CPU1_SA_DQ<25>")
	)
	(arc
		(start 135.05815 -269.873222)
		(mid 134.783921 -269.949147)
		(end 134.507478 -269.881858)
		(width 0.088646)
		(layer "In11.Cu")
		(net "M_H_CPU1_SA_DQ<25>")
	)
	(arc
		(start 133.740398 -268.569694)
		(mid 133.692719 -268.386794)
		(end 133.561836 -268.250416)
		(width 0.088646)
		(layer "In11.Cu")
		(net "M_H_CPU1_SA_DQ<25>")
	)
	(arc
		(start 129.41935 -266.617704)
		(mid 129.145151 -266.693539)
		(end 128.868678 -266.62634)
		(width 0.088646)
		(layer "In11.Cu")
		(net "M_H_CPU1_SA_DQ<25>")
	)
	(arc
		(start 131.29895 -266.617704)
		(mid 131.024751 -266.693539)
		(end 130.748278 -266.62634)
		(width 0.088646)
		(layer "In11.Cu")
		(net "M_H_CPU1_SA_DQ<25>")
	)
	(arc
		(start 126.974346 -266.617704)
		(mid 126.787148 -266.567527)
		(end 126.59995 -266.617704)
		(width 0.088646)
		(layer "In11.Cu")
		(net "M_H_CPU1_SA_DQ<25>")
	)
	(arc
		(start 128.47955 -266.617704)
		(mid 128.205351 -266.693539)
		(end 127.928878 -266.62634)
		(width 0.088646)
		(layer "In11.Cu")
		(net "M_H_CPU1_SA_DQ<25>")
	)
	(arc
		(start 127.914146 -266.617704)
		(mid 127.726948 -266.567527)
		(end 127.53975 -266.617704)
		(width 0.088646)
		(layer "In11.Cu")
		(net "M_H_CPU1_SA_DQ<25>")
	)
	(arc
		(start 129.793746 -266.617704)
		(mid 129.606548 -266.567527)
		(end 129.41935 -266.617704)
		(width 0.088646)
		(layer "In11.Cu")
		(net "M_H_CPU1_SA_DQ<25>")
	)
	(arc
		(start 126.034292 -266.61745)
		(mid 125.830227 -266.531853)
		(end 125.610874 -266.502642)
		(width 0.088646)
		(layer "In11.Cu")
		(net "M_H_CPU1_SA_DQ<25>")
	)
	(arc
		(start 136.93775 -269.873222)
		(mid 136.663521 -269.949147)
		(end 136.387078 -269.881858)
		(width 0.088646)
		(layer "In11.Cu")
		(net "M_H_CPU1_SA_DQ<25>")
	)
	(arc
		(start 137.312146 -269.873222)
		(mid 137.124948 -269.823079)
		(end 136.93775 -269.873222)
		(width 0.088646)
		(layer "In11.Cu")
		(net "M_H_CPU1_SA_DQ<25>")
	)
	(arc
		(start 136.372346 -269.873222)
		(mid 136.185148 -269.823079)
		(end 135.99795 -269.873222)
		(width 0.088646)
		(layer "In11.Cu")
		(net "M_H_CPU1_SA_DQ<25>")
	)
	(arc
		(start 137.87755 -269.873222)
		(mid 137.603321 -269.949147)
		(end 137.326878 -269.881858)
		(width 0.088646)
		(layer "In11.Cu")
		(net "M_H_CPU1_SA_DQ<25>")
	)
	(arc
		(start 133.17855 -268.245336)
		(mid 132.904351 -268.321171)
		(end 132.627878 -268.253972)
		(width 0.088646)
		(layer "In11.Cu")
		(net "M_H_CPU1_SA_DQ<25>")
	)
	(arc
		(start 132.60705 -268.24178)
		(mid 132.404463 -268.035429)
		(end 132.330444 -267.755878)
		(width 0.088646)
		(layer "In11.Cu")
		(net "M_H_CPU1_SA_DQ<25>")
	)
	(segment
		(start 210.028028 -288.266886)
		(end 209.596482 -287.83534)
		(width 0.20066)
		(layer "F.Cu")
		(net "M_H_CPU1_SA_DQ<24>")
	)
	(segment
		(start 123.967494 -266.405868)
		(end 123.967494 -266.941554)
		(width 0.20066)
		(layer "F.Cu")
		(net "M_H_CPU1_SA_DQ<24>")
	)
	(segment
		(start 209.180176 -287.84169)
		(end 207.018382 -287.84169)
		(width 0.1016)
		(layer "F.Cu")
		(net "M_H_CPU1_SA_DQ<24>")
	)
	(segment
		(start 207.018382 -287.84169)
		(end 206.971392 -287.84169)
		(width 0.101854)
		(layer "F.Cu")
		(net "M_H_CPU1_SA_DQ<24>")
	)
	(segment
		(start 206.508604 -288.327338)
		(end 206.320644 -288.515298)
		(width 0.20066)
		(layer "F.Cu")
		(net "M_H_CPU1_SA_DQ<24>")
	)
	(segment
		(start 206.508604 -287.9598)
		(end 206.508604 -288.327338)
		(width 0.20066)
		(layer "F.Cu")
		(net "M_H_CPU1_SA_DQ<24>")
	)
	(segment
		(start 211.619846 -288.266632)
		(end 211.619592 -288.266886)
		(width 0.20066)
		(layer "F.Cu")
		(net "M_H_CPU1_SA_DQ<24>")
	)
	(segment
		(start 211.619592 -288.266886)
		(end 210.028028 -288.266886)
		(width 0.20066)
		(layer "F.Cu")
		(net "M_H_CPU1_SA_DQ<24>")
	)
	(segment
		(start 206.320644 -288.515298)
		(end 205.84541 -288.515298)
		(width 0.20066)
		(layer "F.Cu")
		(net "M_H_CPU1_SA_DQ<24>")
	)
	(segment
		(start 206.626714 -287.84169)
		(end 206.508604 -287.9598)
		(width 0.20066)
		(layer "F.Cu")
		(net "M_H_CPU1_SA_DQ<24>")
	)
	(segment
		(start 206.971392 -287.84169)
		(end 206.626714 -287.84169)
		(width 0.20066)
		(layer "F.Cu")
		(net "M_H_CPU1_SA_DQ<24>")
	)
	(segment
		(start 204.076046 -288.266632)
		(end 202.971146 -288.266632)
		(width 0.20066)
		(layer "F.Cu")
		(net "M_H_CPU1_SA_DQ<24>")
	)
	(segment
		(start 209.186526 -287.83534)
		(end 209.180176 -287.84169)
		(width 0.1016)
		(layer "F.Cu")
		(net "M_H_CPU1_SA_DQ<24>")
	)
	(segment
		(start 205.84541 -288.515298)
		(end 205.596744 -288.266632)
		(width 0.20066)
		(layer "F.Cu")
		(net "M_H_CPU1_SA_DQ<24>")
	)
	(segment
		(start 123.967494 -266.941554)
		(end 123.967748 -266.941808)
		(width 0.20066)
		(layer "F.Cu")
		(net "M_H_CPU1_SA_DQ<24>")
	)
	(segment
		(start 205.596744 -288.266632)
		(end 204.076046 -288.266632)
		(width 0.20066)
		(layer "F.Cu")
		(net "M_H_CPU1_SA_DQ<24>")
	)
	(segment
		(start 209.596482 -287.83534)
		(end 209.186526 -287.83534)
		(width 0.20066)
		(layer "F.Cu")
		(net "M_H_CPU1_SA_DQ<24>")
	)
	(segment
		(start 183.79821 -291.11321)
		(end 182.96509 -290.28009)
		(width 0.18288)
		(layer "In11.Cu")
		(net "M_H_CPU1_SA_DQ<24>")
	)
	(segment
		(start 132.70865 -269.059152)
		(end 132.698236 -269.065248)
		(width 0.088646)
		(layer "In11.Cu")
		(net "M_H_CPU1_SA_DQ<24>")
	)
	(segment
		(start 168.69537 -291.14369)
		(end 167.896794 -290.345114)
		(width 0.18288)
		(layer "In11.Cu")
		(net "M_H_CPU1_SA_DQ<24>")
	)
	(segment
		(start 141.97076 -271.81937)
		(end 139.759944 -271.81937)
		(width 0.18288)
		(layer "In11.Cu")
		(net "M_H_CPU1_SA_DQ<24>")
	)
	(segment
		(start 131.212082 -267.4366)
		(end 131.203192 -267.43152)
		(width 0.088646)
		(layer "In11.Cu")
		(net "M_H_CPU1_SA_DQ<24>")
	)
	(segment
		(start 167.896794 -290.345114)
		(end 165.574726 -290.345114)
		(width 0.18288)
		(layer "In11.Cu")
		(net "M_H_CPU1_SA_DQ<24>")
	)
	(segment
		(start 139.177522 -271.124172)
		(end 138.79957 -270.74622)
		(width 0.088646)
		(layer "In11.Cu")
		(net "M_H_CPU1_SA_DQ<24>")
	)
	(segment
		(start 178.780694 -291.165026)
		(end 177.854864 -292.090856)
		(width 0.18288)
		(layer "In11.Cu")
		(net "M_H_CPU1_SA_DQ<24>")
	)
	(segment
		(start 194.098926 -291.04082)
		(end 193.04889 -292.090856)
		(width 0.18288)
		(layer "In11.Cu")
		(net "M_H_CPU1_SA_DQ<24>")
	)
	(segment
		(start 182.96509 -290.28009)
		(end 182.170832 -290.28009)
		(width 0.18288)
		(layer "In11.Cu")
		(net "M_H_CPU1_SA_DQ<24>")
	)
	(segment
		(start 159.633158 -289.564064)
		(end 158.592012 -288.522918)
		(width 0.18288)
		(layer "In11.Cu")
		(net "M_H_CPU1_SA_DQ<24>")
	)
	(segment
		(start 160.977326 -289.463226)
		(end 160.876488 -289.564064)
		(width 0.18288)
		(layer "In11.Cu")
		(net "M_H_CPU1_SA_DQ<24>")
	)
	(segment
		(start 163.510976 -289.463226)
		(end 163.317936 -289.656266)
		(width 0.18288)
		(layer "In11.Cu")
		(net "M_H_CPU1_SA_DQ<24>")
	)
	(segment
		(start 162.614356 -289.656266)
		(end 162.421316 -289.463226)
		(width 0.18288)
		(layer "In11.Cu")
		(net "M_H_CPU1_SA_DQ<24>")
	)
	(segment
		(start 157.269434 -287.118044)
		(end 141.97076 -271.81937)
		(width 0.18288)
		(layer "In11.Cu")
		(net "M_H_CPU1_SA_DQ<24>")
	)
	(segment
		(start 128.949196 -267.43152)
		(end 128.934464 -267.440156)
		(width 0.088646)
		(layer "In11.Cu")
		(net "M_H_CPU1_SA_DQ<24>")
	)
	(segment
		(start 176.152048 -291.925248)
		(end 174.999904 -291.925248)
		(width 0.18288)
		(layer "In11.Cu")
		(net "M_H_CPU1_SA_DQ<24>")
	)
	(segment
		(start 187.128404 -291.11321)
		(end 183.79821 -291.11321)
		(width 0.18288)
		(layer "In11.Cu")
		(net "M_H_CPU1_SA_DQ<24>")
	)
	(segment
		(start 191.270636 -292.090856)
		(end 190.780416 -291.600636)
		(width 0.18288)
		(layer "In11.Cu")
		(net "M_H_CPU1_SA_DQ<24>")
	)
	(segment
		(start 139.598654 -271.65808)
		(end 139.177522 -271.236948)
		(width 0.088646)
		(layer "In11.Cu")
		(net "M_H_CPU1_SA_DQ<24>")
	)
	(segment
		(start 158.592012 -288.522918)
		(end 158.166054 -288.522918)
		(width 0.18288)
		(layer "In11.Cu")
		(net "M_H_CPU1_SA_DQ<24>")
	)
	(segment
		(start 182.170832 -290.28009)
		(end 181.977792 -290.47313)
		(width 0.18288)
		(layer "In11.Cu")
		(net "M_H_CPU1_SA_DQ<24>")
	)
	(segment
		(start 202.697588 -288.355024)
		(end 202.652376 -288.309812)
		(width 0.18288)
		(layer "In11.Cu")
		(net "M_H_CPU1_SA_DQ<24>")
	)
	(segment
		(start 181.784752 -291.006784)
		(end 181.467252 -291.006784)
		(width 0.18288)
		(layer "In11.Cu")
		(net "M_H_CPU1_SA_DQ<24>")
	)
	(segment
		(start 195.228464 -290.352734)
		(end 194.540378 -291.04082)
		(width 0.18288)
		(layer "In11.Cu")
		(net "M_H_CPU1_SA_DQ<24>")
	)
	(segment
		(start 181.274212 -290.47313)
		(end 181.081172 -290.28009)
		(width 0.18288)
		(layer "In11.Cu")
		(net "M_H_CPU1_SA_DQ<24>")
	)
	(segment
		(start 165.574726 -290.345114)
		(end 164.692838 -289.463226)
		(width 0.18288)
		(layer "In11.Cu")
		(net "M_H_CPU1_SA_DQ<24>")
	)
	(segment
		(start 139.759944 -271.81937)
		(end 139.598654 -271.65808)
		(width 0.18288)
		(layer "In11.Cu")
		(net "M_H_CPU1_SA_DQ<24>")
	)
	(segment
		(start 181.081172 -290.28009)
		(end 180.25491 -290.28009)
		(width 0.18288)
		(layer "In11.Cu")
		(net "M_H_CPU1_SA_DQ<24>")
	)
	(segment
		(start 134.587996 -270.687038)
		(end 134.573264 -270.695674)
		(width 0.088646)
		(layer "In11.Cu")
		(net "M_H_CPU1_SA_DQ<24>")
	)
	(segment
		(start 163.317936 -289.656266)
		(end 163.317936 -290.035742)
		(width 0.18288)
		(layer "In11.Cu")
		(net "M_H_CPU1_SA_DQ<24>")
	)
	(segment
		(start 197.822058 -290.352734)
		(end 195.228464 -290.352734)
		(width 0.18288)
		(layer "In11.Cu")
		(net "M_H_CPU1_SA_DQ<24>")
	)
	(segment
		(start 131.860798 -268.585188)
		(end 131.860798 -268.569694)
		(width 0.088646)
		(layer "In11.Cu")
		(net "M_H_CPU1_SA_DQ<24>")
	)
	(segment
		(start 189.001908 -291.240972)
		(end 187.256166 -291.240972)
		(width 0.18288)
		(layer "In11.Cu")
		(net "M_H_CPU1_SA_DQ<24>")
	)
	(segment
		(start 181.467252 -291.006784)
		(end 181.274212 -290.813744)
		(width 0.18288)
		(layer "In11.Cu")
		(net "M_H_CPU1_SA_DQ<24>")
	)
	(segment
		(start 139.177522 -271.236948)
		(end 139.177522 -271.124172)
		(width 0.088646)
		(layer "In11.Cu")
		(net "M_H_CPU1_SA_DQ<24>")
	)
	(segment
		(start 171.24299 -292.94201)
		(end 169.44467 -291.14369)
		(width 0.18288)
		(layer "In11.Cu")
		(net "M_H_CPU1_SA_DQ<24>")
	)
	(segment
		(start 169.44467 -291.14369)
		(end 168.69537 -291.14369)
		(width 0.18288)
		(layer "In11.Cu")
		(net "M_H_CPU1_SA_DQ<24>")
	)
	(segment
		(start 137.407396 -270.687038)
		(end 137.392664 -270.695674)
		(width 0.088646)
		(layer "In11.Cu")
		(net "M_H_CPU1_SA_DQ<24>")
	)
	(segment
		(start 181.274212 -290.813744)
		(end 181.274212 -290.47313)
		(width 0.18288)
		(layer "In11.Cu")
		(net "M_H_CPU1_SA_DQ<24>")
	)
	(segment
		(start 163.124896 -290.228782)
		(end 162.807396 -290.228782)
		(width 0.18288)
		(layer "In11.Cu")
		(net "M_H_CPU1_SA_DQ<24>")
	)
	(segment
		(start 187.256166 -291.240972)
		(end 187.128404 -291.11321)
		(width 0.18288)
		(layer "In11.Cu")
		(net "M_H_CPU1_SA_DQ<24>")
	)
	(segment
		(start 177.854864 -292.090856)
		(end 176.317656 -292.090856)
		(width 0.18288)
		(layer "In11.Cu")
		(net "M_H_CPU1_SA_DQ<24>")
	)
	(segment
		(start 125.189996 -267.43152)
		(end 125.175264 -267.440156)
		(width 0.088646)
		(layer "In11.Cu")
		(net "M_H_CPU1_SA_DQ<24>")
	)
	(segment
		(start 202.652376 -288.309812)
		(end 202.15352 -287.812226)
		(width 0.18288)
		(layer "In11.Cu")
		(net "M_H_CPU1_SA_DQ<24>")
	)
	(segment
		(start 124.3457 -267.007086)
		(end 124.280422 -266.941808)
		(width 0.088646)
		(layer "In11.Cu")
		(net "M_H_CPU1_SA_DQ<24>")
	)
	(segment
		(start 201.340974 -287.812226)
		(end 199.789288 -289.363912)
		(width 0.18288)
		(layer "In11.Cu")
		(net "M_H_CPU1_SA_DQ<24>")
	)
	(segment
		(start 199.789288 -289.363912)
		(end 198.81088 -289.363912)
		(width 0.18288)
		(layer "In11.Cu")
		(net "M_H_CPU1_SA_DQ<24>")
	)
	(segment
		(start 157.269434 -287.626298)
		(end 157.269434 -287.118044)
		(width 0.18288)
		(layer "In11.Cu")
		(net "M_H_CPU1_SA_DQ<24>")
	)
	(segment
		(start 189.361572 -291.600636)
		(end 189.001908 -291.240972)
		(width 0.18288)
		(layer "In11.Cu")
		(net "M_H_CPU1_SA_DQ<24>")
	)
	(segment
		(start 194.540378 -291.04082)
		(end 194.098926 -291.04082)
		(width 0.18288)
		(layer "In11.Cu")
		(net "M_H_CPU1_SA_DQ<24>")
	)
	(segment
		(start 180.25491 -290.28009)
		(end 179.369974 -291.165026)
		(width 0.18288)
		(layer "In11.Cu")
		(net "M_H_CPU1_SA_DQ<24>")
	)
	(segment
		(start 131.682236 -268.250416)
		(end 131.673346 -268.245336)
		(width 0.088646)
		(layer "In11.Cu")
		(net "M_H_CPU1_SA_DQ<24>")
	)
	(segment
		(start 129.888996 -267.43152)
		(end 129.874264 -267.440156)
		(width 0.088646)
		(layer "In11.Cu")
		(net "M_H_CPU1_SA_DQ<24>")
	)
	(segment
		(start 124.280422 -266.941808)
		(end 123.967748 -266.941808)
		(width 0.088646)
		(layer "In11.Cu")
		(net "M_H_CPU1_SA_DQ<24>")
	)
	(segment
		(start 134.022592 -270.687038)
		(end 134.018274 -270.684498)
		(width 0.088646)
		(layer "In11.Cu")
		(net "M_H_CPU1_SA_DQ<24>")
	)
	(segment
		(start 162.807396 -290.228782)
		(end 162.614356 -290.035742)
		(width 0.18288)
		(layer "In11.Cu")
		(net "M_H_CPU1_SA_DQ<24>")
	)
	(segment
		(start 160.876488 -289.564064)
		(end 159.633158 -289.564064)
		(width 0.18288)
		(layer "In11.Cu")
		(net "M_H_CPU1_SA_DQ<24>")
	)
	(segment
		(start 133.270244 -269.402052)
		(end 133.270244 -269.374874)
		(width 0.088646)
		(layer "In11.Cu")
		(net "M_H_CPU1_SA_DQ<24>")
	)
	(segment
		(start 193.04889 -292.090856)
		(end 191.270636 -292.090856)
		(width 0.18288)
		(layer "In11.Cu")
		(net "M_H_CPU1_SA_DQ<24>")
	)
	(segment
		(start 136.467596 -270.687038)
		(end 136.452864 -270.695674)
		(width 0.088646)
		(layer "In11.Cu")
		(net "M_H_CPU1_SA_DQ<24>")
	)
	(segment
		(start 164.692838 -289.463226)
		(end 163.510976 -289.463226)
		(width 0.18288)
		(layer "In11.Cu")
		(net "M_H_CPU1_SA_DQ<24>")
	)
	(segment
		(start 173.983142 -292.94201)
		(end 171.24299 -292.94201)
		(width 0.18288)
		(layer "In11.Cu")
		(net "M_H_CPU1_SA_DQ<24>")
	)
	(segment
		(start 127.069596 -267.43152)
		(end 127.054864 -267.440156)
		(width 0.088646)
		(layer "In11.Cu")
		(net "M_H_CPU1_SA_DQ<24>")
	)
	(segment
		(start 130.828796 -267.43152)
		(end 130.814064 -267.440156)
		(width 0.088646)
		(layer "In11.Cu")
		(net "M_H_CPU1_SA_DQ<24>")
	)
	(segment
		(start 181.977792 -290.813744)
		(end 181.784752 -291.006784)
		(width 0.18288)
		(layer "In11.Cu")
		(net "M_H_CPU1_SA_DQ<24>")
	)
	(segment
		(start 162.421316 -289.463226)
		(end 160.977326 -289.463226)
		(width 0.18288)
		(layer "In11.Cu")
		(net "M_H_CPU1_SA_DQ<24>")
	)
	(segment
		(start 162.614356 -290.035742)
		(end 162.614356 -289.656266)
		(width 0.18288)
		(layer "In11.Cu")
		(net "M_H_CPU1_SA_DQ<24>")
	)
	(segment
		(start 134.018274 -270.684498)
		(end 134.016496 -270.683482)
		(width 0.088646)
		(layer "In11.Cu")
		(net "M_H_CPU1_SA_DQ<24>")
	)
	(segment
		(start 135.527796 -270.687038)
		(end 135.513064 -270.695674)
		(width 0.088646)
		(layer "In11.Cu")
		(net "M_H_CPU1_SA_DQ<24>")
	)
	(segment
		(start 202.971146 -288.266632)
		(end 202.882754 -288.355024)
		(width 0.18288)
		(layer "In11.Cu")
		(net "M_H_CPU1_SA_DQ<24>")
	)
	(segment
		(start 202.882754 -288.355024)
		(end 202.697588 -288.355024)
		(width 0.18288)
		(layer "In11.Cu")
		(net "M_H_CPU1_SA_DQ<24>")
	)
	(segment
		(start 128.009396 -267.43152)
		(end 127.994664 -267.440156)
		(width 0.088646)
		(layer "In11.Cu")
		(net "M_H_CPU1_SA_DQ<24>")
	)
	(segment
		(start 174.999904 -291.925248)
		(end 173.983142 -292.94201)
		(width 0.18288)
		(layer "In11.Cu")
		(net "M_H_CPU1_SA_DQ<24>")
	)
	(segment
		(start 158.166054 -288.522918)
		(end 157.269434 -287.626298)
		(width 0.18288)
		(layer "In11.Cu")
		(net "M_H_CPU1_SA_DQ<24>")
	)
	(segment
		(start 181.977792 -290.47313)
		(end 181.977792 -290.813744)
		(width 0.18288)
		(layer "In11.Cu")
		(net "M_H_CPU1_SA_DQ<24>")
	)
	(segment
		(start 190.780416 -291.600636)
		(end 189.361572 -291.600636)
		(width 0.18288)
		(layer "In11.Cu")
		(net "M_H_CPU1_SA_DQ<24>")
	)
	(segment
		(start 138.347196 -270.687038)
		(end 138.332464 -270.695674)
		(width 0.088646)
		(layer "In11.Cu")
		(net "M_H_CPU1_SA_DQ<24>")
	)
	(segment
		(start 133.561582 -269.878302)
		(end 133.552692 -269.873222)
		(width 0.088646)
		(layer "In11.Cu")
		(net "M_H_CPU1_SA_DQ<24>")
	)
	(segment
		(start 198.81088 -289.363912)
		(end 197.822058 -290.352734)
		(width 0.18288)
		(layer "In11.Cu")
		(net "M_H_CPU1_SA_DQ<24>")
	)
	(segment
		(start 176.317656 -292.090856)
		(end 176.152048 -291.925248)
		(width 0.18288)
		(layer "In11.Cu")
		(net "M_H_CPU1_SA_DQ<24>")
	)
	(segment
		(start 179.369974 -291.165026)
		(end 178.780694 -291.165026)
		(width 0.18288)
		(layer "In11.Cu")
		(net "M_H_CPU1_SA_DQ<24>")
	)
	(segment
		(start 202.15352 -287.812226)
		(end 201.340974 -287.812226)
		(width 0.18288)
		(layer "In11.Cu")
		(net "M_H_CPU1_SA_DQ<24>")
	)
	(segment
		(start 131.673346 -268.245336)
		(end 131.661154 -268.238224)
		(width 0.088646)
		(layer "In11.Cu")
		(net "M_H_CPU1_SA_DQ<24>")
	)
	(segment
		(start 163.317936 -290.035742)
		(end 163.124896 -290.228782)
		(width 0.18288)
		(layer "In11.Cu")
		(net "M_H_CPU1_SA_DQ<24>")
	)
	(arc
		(start 134.016496 -270.683482)
		(mid 133.814083 -270.477069)
		(end 133.740144 -270.19758)
		(width 0.088646)
		(layer "In11.Cu")
		(net "M_H_CPU1_SA_DQ<24>")
	)
	(arc
		(start 128.934464 -267.440156)
		(mid 128.658023 -267.507322)
		(end 128.383792 -267.43152)
		(width 0.088646)
		(layer "In11.Cu")
		(net "M_H_CPU1_SA_DQ<24>")
	)
	(arc
		(start 129.323592 -267.43152)
		(mid 129.136394 -267.381377)
		(end 128.949196 -267.43152)
		(width 0.088646)
		(layer "In11.Cu")
		(net "M_H_CPU1_SA_DQ<24>")
	)
	(arc
		(start 133.552692 -269.873222)
		(mid 133.350406 -269.674241)
		(end 133.270244 -269.402052)
		(width 0.088646)
		(layer "In11.Cu")
		(net "M_H_CPU1_SA_DQ<24>")
	)
	(arc
		(start 136.841992 -270.687038)
		(mid 136.654794 -270.636895)
		(end 136.467596 -270.687038)
		(width 0.088646)
		(layer "In11.Cu")
		(net "M_H_CPU1_SA_DQ<24>")
	)
	(arc
		(start 127.054864 -267.440156)
		(mid 126.778423 -267.507322)
		(end 126.504192 -267.43152)
		(width 0.088646)
		(layer "In11.Cu")
		(net "M_H_CPU1_SA_DQ<24>")
	)
	(arc
		(start 128.383792 -267.43152)
		(mid 128.196594 -267.381377)
		(end 128.009396 -267.43152)
		(width 0.088646)
		(layer "In11.Cu")
		(net "M_H_CPU1_SA_DQ<24>")
	)
	(arc
		(start 133.270244 -269.374874)
		(mid 133.217974 -269.192509)
		(end 133.083046 -269.059152)
		(width 0.088646)
		(layer "In11.Cu")
		(net "M_H_CPU1_SA_DQ<24>")
	)
	(arc
		(start 130.263392 -267.43152)
		(mid 130.076194 -267.381377)
		(end 129.888996 -267.43152)
		(width 0.088646)
		(layer "In11.Cu")
		(net "M_H_CPU1_SA_DQ<24>")
	)
	(arc
		(start 127.443992 -267.43152)
		(mid 127.256794 -267.381377)
		(end 127.069596 -267.43152)
		(width 0.088646)
		(layer "In11.Cu")
		(net "M_H_CPU1_SA_DQ<24>")
	)
	(arc
		(start 125.175264 -267.440156)
		(mid 124.898823 -267.507322)
		(end 124.624592 -267.43152)
		(width 0.088646)
		(layer "In11.Cu")
		(net "M_H_CPU1_SA_DQ<24>")
	)
	(arc
		(start 124.624592 -267.43152)
		(mid 124.434852 -267.252357)
		(end 124.3457 -267.007086)
		(width 0.088646)
		(layer "In11.Cu")
		(net "M_H_CPU1_SA_DQ<24>")
	)
	(arc
		(start 135.513064 -270.695674)
		(mid 135.236589 -270.762994)
		(end 134.962392 -270.687038)
		(width 0.088646)
		(layer "In11.Cu")
		(net "M_H_CPU1_SA_DQ<24>")
	)
	(arc
		(start 130.814064 -267.440156)
		(mid 130.537623 -267.507322)
		(end 130.263392 -267.43152)
		(width 0.088646)
		(layer "In11.Cu")
		(net "M_H_CPU1_SA_DQ<24>")
	)
	(arc
		(start 133.083046 -269.059152)
		(mid 132.895848 -269.009009)
		(end 132.70865 -269.059152)
		(width 0.088646)
		(layer "In11.Cu")
		(net "M_H_CPU1_SA_DQ<24>")
	)
	(arc
		(start 136.452864 -270.695674)
		(mid 136.176389 -270.762994)
		(end 135.902192 -270.687038)
		(width 0.088646)
		(layer "In11.Cu")
		(net "M_H_CPU1_SA_DQ<24>")
	)
	(arc
		(start 132.142992 -269.059152)
		(mid 131.940169 -268.858921)
		(end 131.860798 -268.585188)
		(width 0.088646)
		(layer "In11.Cu")
		(net "M_H_CPU1_SA_DQ<24>")
	)
	(arc
		(start 132.698236 -269.065248)
		(mid 132.419804 -269.135094)
		(end 132.142992 -269.059152)
		(width 0.088646)
		(layer "In11.Cu")
		(net "M_H_CPU1_SA_DQ<24>")
	)
	(arc
		(start 125.564392 -267.43152)
		(mid 125.377194 -267.381377)
		(end 125.189996 -267.43152)
		(width 0.088646)
		(layer "In11.Cu")
		(net "M_H_CPU1_SA_DQ<24>")
	)
	(arc
		(start 137.781792 -270.687038)
		(mid 137.594594 -270.636895)
		(end 137.407396 -270.687038)
		(width 0.088646)
		(layer "In11.Cu")
		(net "M_H_CPU1_SA_DQ<24>")
	)
	(arc
		(start 126.504192 -267.43152)
		(mid 126.316994 -267.381377)
		(end 126.129796 -267.43152)
		(width 0.088646)
		(layer "In11.Cu")
		(net "M_H_CPU1_SA_DQ<24>")
	)
	(arc
		(start 138.332464 -270.695674)
		(mid 138.055989 -270.762994)
		(end 137.781792 -270.687038)
		(width 0.088646)
		(layer "In11.Cu")
		(net "M_H_CPU1_SA_DQ<24>")
	)
	(arc
		(start 131.390644 -267.755878)
		(mid 131.342965 -267.572978)
		(end 131.212082 -267.4366)
		(width 0.088646)
		(layer "In11.Cu")
		(net "M_H_CPU1_SA_DQ<24>")
	)
	(arc
		(start 133.740144 -270.19758)
		(mid 133.692465 -270.01468)
		(end 133.561582 -269.878302)
		(width 0.088646)
		(layer "In11.Cu")
		(net "M_H_CPU1_SA_DQ<24>")
	)
	(arc
		(start 134.573264 -270.695674)
		(mid 134.296789 -270.762994)
		(end 134.022592 -270.687038)
		(width 0.088646)
		(layer "In11.Cu")
		(net "M_H_CPU1_SA_DQ<24>")
	)
	(arc
		(start 131.860798 -268.569694)
		(mid 131.813119 -268.386794)
		(end 131.682236 -268.250416)
		(width 0.088646)
		(layer "In11.Cu")
		(net "M_H_CPU1_SA_DQ<24>")
	)
	(arc
		(start 138.721592 -270.687038)
		(mid 138.534394 -270.636895)
		(end 138.347196 -270.687038)
		(width 0.088646)
		(layer "In11.Cu")
		(net "M_H_CPU1_SA_DQ<24>")
	)
	(arc
		(start 131.203192 -267.43152)
		(mid 131.015994 -267.381377)
		(end 130.828796 -267.43152)
		(width 0.088646)
		(layer "In11.Cu")
		(net "M_H_CPU1_SA_DQ<24>")
	)
	(arc
		(start 126.129796 -267.43152)
		(mid 125.847094 -267.507262)
		(end 125.564392 -267.43152)
		(width 0.088646)
		(layer "In11.Cu")
		(net "M_H_CPU1_SA_DQ<24>")
	)
	(arc
		(start 137.392664 -270.695674)
		(mid 137.116189 -270.762994)
		(end 136.841992 -270.687038)
		(width 0.088646)
		(layer "In11.Cu")
		(net "M_H_CPU1_SA_DQ<24>")
	)
	(arc
		(start 138.79957 -270.74622)
		(mid 138.76252 -270.714074)
		(end 138.721592 -270.687038)
		(width 0.088646)
		(layer "In11.Cu")
		(net "M_H_CPU1_SA_DQ<24>")
	)
	(arc
		(start 127.994664 -267.440156)
		(mid 127.718223 -267.507322)
		(end 127.443992 -267.43152)
		(width 0.088646)
		(layer "In11.Cu")
		(net "M_H_CPU1_SA_DQ<24>")
	)
	(arc
		(start 135.902192 -270.687038)
		(mid 135.714994 -270.636895)
		(end 135.527796 -270.687038)
		(width 0.088646)
		(layer "In11.Cu")
		(net "M_H_CPU1_SA_DQ<24>")
	)
	(arc
		(start 134.962392 -270.687038)
		(mid 134.775194 -270.636895)
		(end 134.587996 -270.687038)
		(width 0.088646)
		(layer "In11.Cu")
		(net "M_H_CPU1_SA_DQ<24>")
	)
	(arc
		(start 131.661154 -268.238224)
		(mid 131.462926 -268.032376)
		(end 131.390644 -267.755878)
		(width 0.088646)
		(layer "In11.Cu")
		(net "M_H_CPU1_SA_DQ<24>")
	)
	(arc
		(start 129.874264 -267.440156)
		(mid 129.597823 -267.507322)
		(end 129.323592 -267.43152)
		(width 0.088646)
		(layer "In11.Cu")
		(net "M_H_CPU1_SA_DQ<24>")
	)
	(segment
		(start 213.515448 -289.09899)
		(end 213.749636 -288.864802)
		(width 0.20066)
		(layer "F.Cu")
		(net "M_H_CPU1_SA_DQ<23>")
	)
	(segment
		(start 210.603084 -289.548824)
		(end 210.610196 -289.541712)
		(width 0.1016)
		(layer "F.Cu")
		(net "M_H_CPU1_SA_DQ<23>")
	)
	(segment
		(start 210.306412 -289.548824)
		(end 210.598258 -289.548824)
		(width 0.20066)
		(layer "F.Cu")
		(net "M_H_CPU1_SA_DQ<23>")
	)
	(segment
		(start 212.618066 -289.541712)
		(end 212.630258 -289.553904)
		(width 0.1016)
		(layer "F.Cu")
		(net "M_H_CPU1_SA_DQ<23>")
	)
	(segment
		(start 214.385652 -289.11677)
		(end 215.719914 -289.11677)
		(width 0.20066)
		(layer "F.Cu")
		(net "M_H_CPU1_SA_DQ<23>")
	)
	(segment
		(start 213.749636 -288.864802)
		(end 214.133684 -288.864802)
		(width 0.20066)
		(layer "F.Cu")
		(net "M_H_CPU1_SA_DQ<23>")
	)
	(segment
		(start 210.610196 -289.541712)
		(end 212.618066 -289.541712)
		(width 0.1016)
		(layer "F.Cu")
		(net "M_H_CPU1_SA_DQ<23>")
	)
	(segment
		(start 212.630258 -289.553904)
		(end 213.311486 -289.553904)
		(width 0.20066)
		(layer "F.Cu")
		(net "M_H_CPU1_SA_DQ<23>")
	)
	(segment
		(start 207.071214 -289.11677)
		(end 208.176114 -289.11677)
		(width 0.20066)
		(layer "F.Cu")
		(net "M_H_CPU1_SA_DQ<23>")
	)
	(segment
		(start 209.874358 -289.11677)
		(end 210.306412 -289.548824)
		(width 0.20066)
		(layer "F.Cu")
		(net "M_H_CPU1_SA_DQ<23>")
	)
	(segment
		(start 214.133684 -288.864802)
		(end 214.385652 -289.11677)
		(width 0.20066)
		(layer "F.Cu")
		(net "M_H_CPU1_SA_DQ<23>")
	)
	(segment
		(start 124.907294 -268.56944)
		(end 124.907548 -268.569694)
		(width 0.20066)
		(layer "F.Cu")
		(net "M_H_CPU1_SA_DQ<23>")
	)
	(segment
		(start 208.176114 -289.11677)
		(end 209.874358 -289.11677)
		(width 0.20066)
		(layer "F.Cu")
		(net "M_H_CPU1_SA_DQ<23>")
	)
	(segment
		(start 213.311486 -289.553904)
		(end 213.515448 -289.349942)
		(width 0.20066)
		(layer "F.Cu")
		(net "M_H_CPU1_SA_DQ<23>")
	)
	(segment
		(start 210.598258 -289.548824)
		(end 210.603084 -289.548824)
		(width 0.101854)
		(layer "F.Cu")
		(net "M_H_CPU1_SA_DQ<23>")
	)
	(segment
		(start 213.515448 -289.349942)
		(end 213.515448 -289.09899)
		(width 0.20066)
		(layer "F.Cu")
		(net "M_H_CPU1_SA_DQ<23>")
	)
	(segment
		(start 124.907294 -268.033754)
		(end 124.907294 -268.56944)
		(width 0.20066)
		(layer "F.Cu")
		(net "M_H_CPU1_SA_DQ<23>")
	)
	(segment
		(start 156.979874 -288.521902)
		(end 141.287754 -272.829782)
		(width 0.18288)
		(layer "In11.Cu")
		(net "M_H_CPU1_SA_DQ<23>")
	)
	(segment
		(start 207.045814 -289.11677)
		(end 206.367888 -289.793426)
		(width 0.18288)
		(layer "In11.Cu")
		(net "M_H_CPU1_SA_DQ<23>")
	)
	(segment
		(start 169.592498 -293.046658)
		(end 169.397426 -293.046658)
		(width 0.18288)
		(layer "In11.Cu")
		(net "M_H_CPU1_SA_DQ<23>")
	)
	(segment
		(start 201.32167 -289.016186)
		(end 199.85863 -290.479226)
		(width 0.18288)
		(layer "In11.Cu")
		(net "M_H_CPU1_SA_DQ<23>")
	)
	(segment
		(start 172.165518 -294.772334)
		(end 171.319698 -294.772334)
		(width 0.18288)
		(layer "In11.Cu")
		(net "M_H_CPU1_SA_DQ<23>")
	)
	(segment
		(start 207.071214 -289.11677)
		(end 207.045814 -289.11677)
		(width 0.18288)
		(layer "In11.Cu")
		(net "M_H_CPU1_SA_DQ<23>")
	)
	(segment
		(start 162.073844 -290.63315)
		(end 161.756344 -290.63315)
		(width 0.18288)
		(layer "In11.Cu")
		(net "M_H_CPU1_SA_DQ<23>")
	)
	(segment
		(start 202.196446 -289.016186)
		(end 201.32167 -289.016186)
		(width 0.18288)
		(layer "In11.Cu")
		(net "M_H_CPU1_SA_DQ<23>")
	)
	(segment
		(start 132.991098 -270.206216)
		(end 132.991098 -270.179038)
		(width 0.088646)
		(layer "In11.Cu")
		(net "M_H_CPU1_SA_DQ<23>")
	)
	(segment
		(start 167.853614 -293.046658)
		(end 167.831262 -293.06901)
		(width 0.18288)
		(layer "In11.Cu")
		(net "M_H_CPU1_SA_DQ<23>")
	)
	(segment
		(start 138.613642 -272.351754)
		(end 138.613642 -271.59331)
		(width 0.088646)
		(layer "In11.Cu")
		(net "M_H_CPU1_SA_DQ<23>")
	)
	(segment
		(start 138.368278 -271.347946)
		(end 138.332464 -271.327118)
		(width 0.088646)
		(layer "In11.Cu")
		(net "M_H_CPU1_SA_DQ<23>")
	)
	(segment
		(start 133.460744 -271.011396)
		(end 133.460744 -271.00149)
		(width 0.088646)
		(layer "In11.Cu")
		(net "M_H_CPU1_SA_DQ<23>")
	)
	(segment
		(start 141.287754 -272.829782)
		(end 139.325604 -272.829782)
		(width 0.18288)
		(layer "In11.Cu")
		(net "M_H_CPU1_SA_DQ<23>")
	)
	(segment
		(start 167.831262 -293.06901)
		(end 167.41013 -293.06901)
		(width 0.18288)
		(layer "In11.Cu")
		(net "M_H_CPU1_SA_DQ<23>")
	)
	(segment
		(start 164.608256 -292.093396)
		(end 163.780216 -292.093396)
		(width 0.18288)
		(layer "In11.Cu")
		(net "M_H_CPU1_SA_DQ<23>")
	)
	(segment
		(start 165.707568 -291.624258)
		(end 165.514528 -291.431218)
		(width 0.18288)
		(layer "In11.Cu")
		(net "M_H_CPU1_SA_DQ<23>")
	)
	(segment
		(start 171.319698 -294.772334)
		(end 169.592498 -293.046658)
		(width 0.18288)
		(layer "In11.Cu")
		(net "M_H_CPU1_SA_DQ<23>")
	)
	(segment
		(start 131.581144 -269.38351)
		(end 131.581144 -269.368016)
		(width 0.088646)
		(layer "In11.Cu")
		(net "M_H_CPU1_SA_DQ<23>")
	)
	(segment
		(start 162.266884 -291.022786)
		(end 162.266884 -290.82619)
		(width 0.18288)
		(layer "In11.Cu")
		(net "M_H_CPU1_SA_DQ<23>")
	)
	(segment
		(start 139.09167 -272.829782)
		(end 138.613642 -272.351754)
		(width 0.088646)
		(layer "In11.Cu")
		(net "M_H_CPU1_SA_DQ<23>")
	)
	(segment
		(start 159.316674 -290.382706)
		(end 158.549086 -289.615118)
		(width 0.18288)
		(layer "In11.Cu")
		(net "M_H_CPU1_SA_DQ<23>")
	)
	(segment
		(start 168.500806 -292.853618)
		(end 168.307766 -293.046658)
		(width 0.18288)
		(layer "In11.Cu")
		(net "M_H_CPU1_SA_DQ<23>")
	)
	(segment
		(start 165.900608 -292.090094)
		(end 165.707568 -291.897054)
		(width 0.18288)
		(layer "In11.Cu")
		(net "M_H_CPU1_SA_DQ<23>")
	)
	(segment
		(start 160.998662 -291.215826)
		(end 160.165542 -290.382706)
		(width 0.18288)
		(layer "In11.Cu")
		(net "M_H_CPU1_SA_DQ<23>")
	)
	(segment
		(start 190.82258 -293.082726)
		(end 189.314582 -293.082726)
		(width 0.18288)
		(layer "In11.Cu")
		(net "M_H_CPU1_SA_DQ<23>")
	)
	(segment
		(start 130.828796 -268.080236)
		(end 130.814064 -268.0716)
		(width 0.088646)
		(layer "In11.Cu")
		(net "M_H_CPU1_SA_DQ<23>")
	)
	(segment
		(start 169.397426 -293.046658)
		(end 169.204386 -292.853618)
		(width 0.18288)
		(layer "In11.Cu")
		(net "M_H_CPU1_SA_DQ<23>")
	)
	(segment
		(start 191.532256 -293.792402)
		(end 190.82258 -293.082726)
		(width 0.18288)
		(layer "In11.Cu")
		(net "M_H_CPU1_SA_DQ<23>")
	)
	(segment
		(start 127.069596 -268.080236)
		(end 127.054864 -268.0716)
		(width 0.088646)
		(layer "In11.Cu")
		(net "M_H_CPU1_SA_DQ<23>")
	)
	(segment
		(start 161.563304 -290.82619)
		(end 161.563304 -291.022786)
		(width 0.18288)
		(layer "In11.Cu")
		(net "M_H_CPU1_SA_DQ<23>")
	)
	(segment
		(start 204.79258 -289.793426)
		(end 204.541374 -289.54222)
		(width 0.18288)
		(layer "In11.Cu")
		(net "M_H_CPU1_SA_DQ<23>")
	)
	(segment
		(start 169.011346 -292.386512)
		(end 168.693846 -292.386512)
		(width 0.18288)
		(layer "In11.Cu")
		(net "M_H_CPU1_SA_DQ<23>")
	)
	(segment
		(start 128.009396 -268.080236)
		(end 127.994664 -268.0716)
		(width 0.088646)
		(layer "In11.Cu")
		(net "M_H_CPU1_SA_DQ<23>")
	)
	(segment
		(start 164.810948 -292.090094)
		(end 164.611558 -292.090094)
		(width 0.18288)
		(layer "In11.Cu")
		(net "M_H_CPU1_SA_DQ<23>")
	)
	(segment
		(start 165.197028 -291.431218)
		(end 165.003988 -291.624258)
		(width 0.18288)
		(layer "In11.Cu")
		(net "M_H_CPU1_SA_DQ<23>")
	)
	(segment
		(start 165.514528 -291.431218)
		(end 165.197028 -291.431218)
		(width 0.18288)
		(layer "In11.Cu")
		(net "M_H_CPU1_SA_DQ<23>")
	)
	(segment
		(start 188.32703 -292.095174)
		(end 184.951878 -292.095174)
		(width 0.18288)
		(layer "In11.Cu")
		(net "M_H_CPU1_SA_DQ<23>")
	)
	(segment
		(start 161.756344 -290.63315)
		(end 161.563304 -290.82619)
		(width 0.18288)
		(layer "In11.Cu")
		(net "M_H_CPU1_SA_DQ<23>")
	)
	(segment
		(start 199.85863 -290.479226)
		(end 199.051926 -290.479226)
		(width 0.18288)
		(layer "In11.Cu")
		(net "M_H_CPU1_SA_DQ<23>")
	)
	(segment
		(start 158.549086 -289.615118)
		(end 157.456886 -289.615118)
		(width 0.18288)
		(layer "In11.Cu")
		(net "M_H_CPU1_SA_DQ<23>")
	)
	(segment
		(start 168.307766 -293.046658)
		(end 167.853614 -293.046658)
		(width 0.18288)
		(layer "In11.Cu")
		(net "M_H_CPU1_SA_DQ<23>")
	)
	(segment
		(start 137.407396 -271.335754)
		(end 137.392664 -271.327118)
		(width 0.088646)
		(layer "In11.Cu")
		(net "M_H_CPU1_SA_DQ<23>")
	)
	(segment
		(start 167.41013 -293.06901)
		(end 166.431214 -292.090094)
		(width 0.18288)
		(layer "In11.Cu")
		(net "M_H_CPU1_SA_DQ<23>")
	)
	(segment
		(start 138.613642 -271.59331)
		(end 138.368278 -271.347946)
		(width 0.088646)
		(layer "In11.Cu")
		(net "M_H_CPU1_SA_DQ<23>")
	)
	(segment
		(start 133.648196 -271.335754)
		(end 133.639306 -271.330674)
		(width 0.088646)
		(layer "In11.Cu")
		(net "M_H_CPU1_SA_DQ<23>")
	)
	(segment
		(start 162.902646 -291.215826)
		(end 162.459924 -291.215826)
		(width 0.18288)
		(layer "In11.Cu")
		(net "M_H_CPU1_SA_DQ<23>")
	)
	(segment
		(start 166.431214 -292.090094)
		(end 165.900608 -292.090094)
		(width 0.18288)
		(layer "In11.Cu")
		(net "M_H_CPU1_SA_DQ<23>")
	)
	(segment
		(start 199.051926 -290.479226)
		(end 198.162926 -291.368226)
		(width 0.18288)
		(layer "In11.Cu")
		(net "M_H_CPU1_SA_DQ<23>")
	)
	(segment
		(start 192.94221 -293.792402)
		(end 191.532256 -293.792402)
		(width 0.18288)
		(layer "In11.Cu")
		(net "M_H_CPU1_SA_DQ<23>")
	)
	(segment
		(start 177.268378 -293.792402)
		(end 174.437802 -293.792402)
		(width 0.18288)
		(layer "In11.Cu")
		(net "M_H_CPU1_SA_DQ<23>")
	)
	(segment
		(start 204.541374 -289.54222)
		(end 202.72248 -289.54222)
		(width 0.18288)
		(layer "In11.Cu")
		(net "M_H_CPU1_SA_DQ<23>")
	)
	(segment
		(start 162.266884 -290.82619)
		(end 162.073844 -290.63315)
		(width 0.18288)
		(layer "In11.Cu")
		(net "M_H_CPU1_SA_DQ<23>")
	)
	(segment
		(start 130.834892 -268.083792)
		(end 130.828796 -268.080236)
		(width 0.088646)
		(layer "In11.Cu")
		(net "M_H_CPU1_SA_DQ<23>")
	)
	(segment
		(start 136.467596 -271.335754)
		(end 136.452864 -271.327118)
		(width 0.088646)
		(layer "In11.Cu")
		(net "M_H_CPU1_SA_DQ<23>")
	)
	(segment
		(start 162.459924 -291.215826)
		(end 162.266884 -291.022786)
		(width 0.18288)
		(layer "In11.Cu")
		(net "M_H_CPU1_SA_DQ<23>")
	)
	(segment
		(start 168.500806 -292.579552)
		(end 168.500806 -292.853618)
		(width 0.18288)
		(layer "In11.Cu")
		(net "M_H_CPU1_SA_DQ<23>")
	)
	(segment
		(start 160.165542 -290.382706)
		(end 159.316674 -290.382706)
		(width 0.18288)
		(layer "In11.Cu")
		(net "M_H_CPU1_SA_DQ<23>")
	)
	(segment
		(start 206.367888 -289.793426)
		(end 204.79258 -289.793426)
		(width 0.18288)
		(layer "In11.Cu")
		(net "M_H_CPU1_SA_DQ<23>")
	)
	(segment
		(start 134.587996 -271.335754)
		(end 134.573264 -271.327118)
		(width 0.088646)
		(layer "In11.Cu")
		(net "M_H_CPU1_SA_DQ<23>")
	)
	(segment
		(start 126.129796 -268.080236)
		(end 126.115064 -268.0716)
		(width 0.088646)
		(layer "In11.Cu")
		(net "M_H_CPU1_SA_DQ<23>")
	)
	(segment
		(start 195.366386 -291.368226)
		(end 192.94221 -293.792402)
		(width 0.18288)
		(layer "In11.Cu")
		(net "M_H_CPU1_SA_DQ<23>")
	)
	(segment
		(start 202.72248 -289.54222)
		(end 202.196446 -289.016186)
		(width 0.18288)
		(layer "In11.Cu")
		(net "M_H_CPU1_SA_DQ<23>")
	)
	(segment
		(start 174.437802 -293.792402)
		(end 173.587918 -294.642286)
		(width 0.18288)
		(layer "In11.Cu")
		(net "M_H_CPU1_SA_DQ<23>")
	)
	(segment
		(start 169.204386 -292.579552)
		(end 169.011346 -292.386512)
		(width 0.18288)
		(layer "In11.Cu")
		(net "M_H_CPU1_SA_DQ<23>")
	)
	(segment
		(start 172.295566 -294.642286)
		(end 172.165518 -294.772334)
		(width 0.18288)
		(layer "In11.Cu")
		(net "M_H_CPU1_SA_DQ<23>")
	)
	(segment
		(start 129.888996 -268.080236)
		(end 129.888742 -268.080236)
		(width 0.088646)
		(layer "In11.Cu")
		(net "M_H_CPU1_SA_DQ<23>")
	)
	(segment
		(start 161.563304 -291.022786)
		(end 161.370264 -291.215826)
		(width 0.18288)
		(layer "In11.Cu")
		(net "M_H_CPU1_SA_DQ<23>")
	)
	(segment
		(start 165.003988 -291.624258)
		(end 165.003988 -291.897054)
		(width 0.18288)
		(layer "In11.Cu")
		(net "M_H_CPU1_SA_DQ<23>")
	)
	(segment
		(start 165.003988 -291.897054)
		(end 164.810948 -292.090094)
		(width 0.18288)
		(layer "In11.Cu")
		(net "M_H_CPU1_SA_DQ<23>")
	)
	(segment
		(start 184.951878 -292.095174)
		(end 183.977026 -293.070026)
		(width 0.18288)
		(layer "In11.Cu")
		(net "M_H_CPU1_SA_DQ<23>")
	)
	(segment
		(start 131.768596 -269.707868)
		(end 131.759706 -269.702788)
		(width 0.088646)
		(layer "In11.Cu")
		(net "M_H_CPU1_SA_DQ<23>")
	)
	(segment
		(start 168.693846 -292.386512)
		(end 168.500806 -292.579552)
		(width 0.18288)
		(layer "In11.Cu")
		(net "M_H_CPU1_SA_DQ<23>")
	)
	(segment
		(start 135.527796 -271.335754)
		(end 135.513064 -271.327118)
		(width 0.088646)
		(layer "In11.Cu")
		(net "M_H_CPU1_SA_DQ<23>")
	)
	(segment
		(start 125.564392 -268.080236)
		(end 125.48616 -268.125448)
		(width 0.088646)
		(layer "In11.Cu")
		(net "M_H_CPU1_SA_DQ<23>")
	)
	(segment
		(start 132.70865 -269.707868)
		(end 132.698236 -269.701772)
		(width 0.088646)
		(layer "In11.Cu")
		(net "M_H_CPU1_SA_DQ<23>")
	)
	(segment
		(start 177.990754 -293.070026)
		(end 177.268378 -293.792402)
		(width 0.18288)
		(layer "In11.Cu")
		(net "M_H_CPU1_SA_DQ<23>")
	)
	(segment
		(start 169.204386 -292.853618)
		(end 169.204386 -292.579552)
		(width 0.18288)
		(layer "In11.Cu")
		(net "M_H_CPU1_SA_DQ<23>")
	)
	(segment
		(start 157.456886 -289.615118)
		(end 156.979874 -289.138106)
		(width 0.18288)
		(layer "In11.Cu")
		(net "M_H_CPU1_SA_DQ<23>")
	)
	(segment
		(start 139.325604 -272.829782)
		(end 139.09167 -272.829782)
		(width 0.088646)
		(layer "In11.Cu")
		(net "M_H_CPU1_SA_DQ<23>")
	)
	(segment
		(start 165.707568 -291.897054)
		(end 165.707568 -291.624258)
		(width 0.18288)
		(layer "In11.Cu")
		(net "M_H_CPU1_SA_DQ<23>")
	)
	(segment
		(start 173.587918 -294.642286)
		(end 172.295566 -294.642286)
		(width 0.18288)
		(layer "In11.Cu")
		(net "M_H_CPU1_SA_DQ<23>")
	)
	(segment
		(start 163.780216 -292.093396)
		(end 162.902646 -291.215826)
		(width 0.18288)
		(layer "In11.Cu")
		(net "M_H_CPU1_SA_DQ<23>")
	)
	(segment
		(start 128.949196 -268.080236)
		(end 128.934464 -268.0716)
		(width 0.088646)
		(layer "In11.Cu")
		(net "M_H_CPU1_SA_DQ<23>")
	)
	(segment
		(start 164.611558 -292.090094)
		(end 164.608256 -292.093396)
		(width 0.18288)
		(layer "In11.Cu")
		(net "M_H_CPU1_SA_DQ<23>")
	)
	(segment
		(start 131.29895 -268.894052)
		(end 131.29006 -268.888972)
		(width 0.088646)
		(layer "In11.Cu")
		(net "M_H_CPU1_SA_DQ<23>")
	)
	(segment
		(start 161.370264 -291.215826)
		(end 160.998662 -291.215826)
		(width 0.18288)
		(layer "In11.Cu")
		(net "M_H_CPU1_SA_DQ<23>")
	)
	(segment
		(start 183.977026 -293.070026)
		(end 177.990754 -293.070026)
		(width 0.18288)
		(layer "In11.Cu")
		(net "M_H_CPU1_SA_DQ<23>")
	)
	(segment
		(start 156.979874 -289.138106)
		(end 156.979874 -288.521902)
		(width 0.18288)
		(layer "In11.Cu")
		(net "M_H_CPU1_SA_DQ<23>")
	)
	(segment
		(start 189.314582 -293.082726)
		(end 188.32703 -292.095174)
		(width 0.18288)
		(layer "In11.Cu")
		(net "M_H_CPU1_SA_DQ<23>")
	)
	(segment
		(start 198.162926 -291.368226)
		(end 195.366386 -291.368226)
		(width 0.18288)
		(layer "In11.Cu")
		(net "M_H_CPU1_SA_DQ<23>")
	)
	(arc
		(start 133.178296 -270.521938)
		(mid 133.043363 -270.388584)
		(end 132.991098 -270.206216)
		(width 0.088646)
		(layer "In11.Cu")
		(net "M_H_CPU1_SA_DQ<23>")
	)
	(arc
		(start 136.452864 -271.327118)
		(mid 136.176389 -271.259798)
		(end 135.902192 -271.335754)
		(width 0.088646)
		(layer "In11.Cu")
		(net "M_H_CPU1_SA_DQ<23>")
	)
	(arc
		(start 127.443992 -268.080236)
		(mid 127.256794 -268.130379)
		(end 127.069596 -268.080236)
		(width 0.088646)
		(layer "In11.Cu")
		(net "M_H_CPU1_SA_DQ<23>")
	)
	(arc
		(start 126.115064 -268.0716)
		(mid 125.838589 -268.00428)
		(end 125.564392 -268.080236)
		(width 0.088646)
		(layer "In11.Cu")
		(net "M_H_CPU1_SA_DQ<23>")
	)
	(arc
		(start 135.513064 -271.327118)
		(mid 135.236589 -271.259798)
		(end 134.962392 -271.335754)
		(width 0.088646)
		(layer "In11.Cu")
		(net "M_H_CPU1_SA_DQ<23>")
	)
	(arc
		(start 137.781792 -271.335754)
		(mid 137.594594 -271.385897)
		(end 137.407396 -271.335754)
		(width 0.088646)
		(layer "In11.Cu")
		(net "M_H_CPU1_SA_DQ<23>")
	)
	(arc
		(start 127.054864 -268.0716)
		(mid 126.778389 -268.00428)
		(end 126.504192 -268.080236)
		(width 0.088646)
		(layer "In11.Cu")
		(net "M_H_CPU1_SA_DQ<23>")
	)
	(arc
		(start 134.962392 -271.335754)
		(mid 134.775194 -271.385897)
		(end 134.587996 -271.335754)
		(width 0.088646)
		(layer "In11.Cu")
		(net "M_H_CPU1_SA_DQ<23>")
	)
	(arc
		(start 127.994664 -268.0716)
		(mid 127.718189 -268.00428)
		(end 127.443992 -268.080236)
		(width 0.088646)
		(layer "In11.Cu")
		(net "M_H_CPU1_SA_DQ<23>")
	)
	(arc
		(start 133.460744 -271.00149)
		(mid 133.382633 -270.724541)
		(end 133.178296 -270.521938)
		(width 0.088646)
		(layer "In11.Cu")
		(net "M_H_CPU1_SA_DQ<23>")
	)
	(arc
		(start 131.29006 -268.888972)
		(mid 131.159146 -268.752612)
		(end 131.111498 -268.569694)
		(width 0.088646)
		(layer "In11.Cu")
		(net "M_H_CPU1_SA_DQ<23>")
	)
	(arc
		(start 134.573264 -271.327118)
		(mid 134.296789 -271.259798)
		(end 134.022592 -271.335754)
		(width 0.088646)
		(layer "In11.Cu")
		(net "M_H_CPU1_SA_DQ<23>")
	)
	(arc
		(start 132.142992 -269.707868)
		(mid 131.955794 -269.758011)
		(end 131.768596 -269.707868)
		(width 0.088646)
		(layer "In11.Cu")
		(net "M_H_CPU1_SA_DQ<23>")
	)
	(arc
		(start 131.581144 -269.368016)
		(mid 131.501774 -269.094282)
		(end 131.29895 -268.894052)
		(width 0.088646)
		(layer "In11.Cu")
		(net "M_H_CPU1_SA_DQ<23>")
	)
	(arc
		(start 130.263392 -268.080236)
		(mid 130.076194 -268.130379)
		(end 129.888996 -268.080236)
		(width 0.088646)
		(layer "In11.Cu")
		(net "M_H_CPU1_SA_DQ<23>")
	)
	(arc
		(start 128.383792 -268.080236)
		(mid 128.196594 -268.130379)
		(end 128.009396 -268.080236)
		(width 0.088646)
		(layer "In11.Cu")
		(net "M_H_CPU1_SA_DQ<23>")
	)
	(arc
		(start 131.759706 -269.702788)
		(mid 131.628792 -269.566428)
		(end 131.581144 -269.38351)
		(width 0.088646)
		(layer "In11.Cu")
		(net "M_H_CPU1_SA_DQ<23>")
	)
	(arc
		(start 136.841992 -271.335754)
		(mid 136.654794 -271.385897)
		(end 136.467596 -271.335754)
		(width 0.088646)
		(layer "In11.Cu")
		(net "M_H_CPU1_SA_DQ<23>")
	)
	(arc
		(start 132.698236 -269.701772)
		(mid 132.419804 -269.631958)
		(end 132.142992 -269.707868)
		(width 0.088646)
		(layer "In11.Cu")
		(net "M_H_CPU1_SA_DQ<23>")
	)
	(arc
		(start 138.332464 -271.327118)
		(mid 138.055989 -271.259798)
		(end 137.781792 -271.335754)
		(width 0.088646)
		(layer "In11.Cu")
		(net "M_H_CPU1_SA_DQ<23>")
	)
	(arc
		(start 134.022592 -271.335754)
		(mid 133.835394 -271.385897)
		(end 133.648196 -271.335754)
		(width 0.088646)
		(layer "In11.Cu")
		(net "M_H_CPU1_SA_DQ<23>")
	)
	(arc
		(start 135.902192 -271.335754)
		(mid 135.714994 -271.385897)
		(end 135.527796 -271.335754)
		(width 0.088646)
		(layer "In11.Cu")
		(net "M_H_CPU1_SA_DQ<23>")
	)
	(arc
		(start 129.323592 -268.080236)
		(mid 129.136394 -268.130379)
		(end 128.949196 -268.080236)
		(width 0.088646)
		(layer "In11.Cu")
		(net "M_H_CPU1_SA_DQ<23>")
	)
	(arc
		(start 133.639306 -271.330674)
		(mid 133.508392 -271.194314)
		(end 133.460744 -271.011396)
		(width 0.088646)
		(layer "In11.Cu")
		(net "M_H_CPU1_SA_DQ<23>")
	)
	(arc
		(start 129.888742 -268.080236)
		(mid 129.60615 -268.00446)
		(end 129.323592 -268.080236)
		(width 0.088646)
		(layer "In11.Cu")
		(net "M_H_CPU1_SA_DQ<23>")
	)
	(arc
		(start 126.504192 -268.080236)
		(mid 126.316994 -268.130379)
		(end 126.129796 -268.080236)
		(width 0.088646)
		(layer "In11.Cu")
		(net "M_H_CPU1_SA_DQ<23>")
	)
	(arc
		(start 132.991098 -270.179038)
		(mid 132.910936 -269.906849)
		(end 132.70865 -269.707868)
		(width 0.088646)
		(layer "In11.Cu")
		(net "M_H_CPU1_SA_DQ<23>")
	)
	(arc
		(start 131.111498 -268.569694)
		(mid 131.037507 -268.290128)
		(end 130.834892 -268.083792)
		(width 0.088646)
		(layer "In11.Cu")
		(net "M_H_CPU1_SA_DQ<23>")
	)
	(arc
		(start 130.814064 -268.0716)
		(mid 130.537589 -268.00428)
		(end 130.263392 -268.080236)
		(width 0.088646)
		(layer "In11.Cu")
		(net "M_H_CPU1_SA_DQ<23>")
	)
	(arc
		(start 137.392664 -271.327118)
		(mid 137.116189 -271.259798)
		(end 136.841992 -271.335754)
		(width 0.088646)
		(layer "In11.Cu")
		(net "M_H_CPU1_SA_DQ<23>")
	)
	(arc
		(start 125.48616 -268.125448)
		(mid 125.18232 -268.328642)
		(end 124.907548 -268.569694)
		(width 0.088646)
		(layer "In11.Cu")
		(net "M_H_CPU1_SA_DQ<23>")
	)
	(arc
		(start 128.934464 -268.0716)
		(mid 128.657989 -268.00428)
		(end 128.383792 -268.080236)
		(width 0.088646)
		(layer "In11.Cu")
		(net "M_H_CPU1_SA_DQ<23>")
	)
	(segment
		(start 209.874358 -290.816792)
		(end 210.306412 -291.248846)
		(width 0.20066)
		(layer "F.Cu")
		(net "M_H_CPU1_SA_DQ<22>")
	)
	(segment
		(start 210.306412 -291.248846)
		(end 210.598258 -291.248846)
		(width 0.20066)
		(layer "F.Cu")
		(net "M_H_CPU1_SA_DQ<22>")
	)
	(segment
		(start 212.630258 -291.253926)
		(end 213.311486 -291.253926)
		(width 0.20066)
		(layer "F.Cu")
		(net "M_H_CPU1_SA_DQ<22>")
	)
	(segment
		(start 214.133684 -290.564824)
		(end 214.385652 -290.816792)
		(width 0.20066)
		(layer "F.Cu")
		(net "M_H_CPU1_SA_DQ<22>")
	)
	(segment
		(start 213.515448 -290.799012)
		(end 213.749636 -290.564824)
		(width 0.20066)
		(layer "F.Cu")
		(net "M_H_CPU1_SA_DQ<22>")
	)
	(segment
		(start 210.610196 -291.241734)
		(end 212.618066 -291.241734)
		(width 0.1016)
		(layer "F.Cu")
		(net "M_H_CPU1_SA_DQ<22>")
	)
	(segment
		(start 125.377448 -268.84757)
		(end 125.377448 -269.383256)
		(width 0.20066)
		(layer "F.Cu")
		(net "M_H_CPU1_SA_DQ<22>")
	)
	(segment
		(start 213.749636 -290.564824)
		(end 214.133684 -290.564824)
		(width 0.20066)
		(layer "F.Cu")
		(net "M_H_CPU1_SA_DQ<22>")
	)
	(segment
		(start 213.311486 -291.253926)
		(end 213.515448 -291.049964)
		(width 0.20066)
		(layer "F.Cu")
		(net "M_H_CPU1_SA_DQ<22>")
	)
	(segment
		(start 212.618066 -291.241734)
		(end 212.630258 -291.253926)
		(width 0.1016)
		(layer "F.Cu")
		(net "M_H_CPU1_SA_DQ<22>")
	)
	(segment
		(start 210.603084 -291.248846)
		(end 210.610196 -291.241734)
		(width 0.1016)
		(layer "F.Cu")
		(net "M_H_CPU1_SA_DQ<22>")
	)
	(segment
		(start 210.598258 -291.248846)
		(end 210.603084 -291.248846)
		(width 0.101854)
		(layer "F.Cu")
		(net "M_H_CPU1_SA_DQ<22>")
	)
	(segment
		(start 207.071468 -290.816792)
		(end 208.176114 -290.816792)
		(width 0.20066)
		(layer "F.Cu")
		(net "M_H_CPU1_SA_DQ<22>")
	)
	(segment
		(start 125.377448 -269.383256)
		(end 125.377194 -269.38351)
		(width 0.20066)
		(layer "F.Cu")
		(net "M_H_CPU1_SA_DQ<22>")
	)
	(segment
		(start 213.515448 -291.049964)
		(end 213.515448 -290.799012)
		(width 0.20066)
		(layer "F.Cu")
		(net "M_H_CPU1_SA_DQ<22>")
	)
	(segment
		(start 208.176114 -290.816792)
		(end 209.874358 -290.816792)
		(width 0.20066)
		(layer "F.Cu")
		(net "M_H_CPU1_SA_DQ<22>")
	)
	(segment
		(start 214.385652 -290.816792)
		(end 215.719914 -290.816792)
		(width 0.20066)
		(layer "F.Cu")
		(net "M_H_CPU1_SA_DQ<22>")
	)
	(segment
		(start 207.071214 -290.816538)
		(end 207.071468 -290.816792)
		(width 0.20066)
		(layer "F.Cu")
		(net "M_H_CPU1_SA_DQ<22>")
	)
	(segment
		(start 136.387078 -272.140934)
		(end 136.372346 -272.14957)
		(width 0.088646)
		(layer "In11.Cu")
		(net "M_H_CPU1_SA_DQ<22>")
	)
	(segment
		(start 166.39032 -293.636192)
		(end 165.883844 -293.636192)
		(width 0.18288)
		(layer "In11.Cu")
		(net "M_H_CPU1_SA_DQ<22>")
	)
	(segment
		(start 155.780994 -288.942526)
		(end 140.377418 -273.53895)
		(width 0.18288)
		(layer "In11.Cu")
		(net "M_H_CPU1_SA_DQ<22>")
	)
	(segment
		(start 178.757834 -295.432226)
		(end 178.424078 -295.765982)
		(width 0.18288)
		(layer "In11.Cu")
		(net "M_H_CPU1_SA_DQ<22>")
	)
	(segment
		(start 178.424078 -295.765982)
		(end 177.591466 -295.765982)
		(width 0.18288)
		(layer "In11.Cu")
		(net "M_H_CPU1_SA_DQ<22>")
	)
	(segment
		(start 183.80202 -294.678608)
		(end 183.80202 -294.304466)
		(width 0.18288)
		(layer "In11.Cu")
		(net "M_H_CPU1_SA_DQ<22>")
	)
	(segment
		(start 132.051298 -271.833848)
		(end 132.051298 -271.825212)
		(width 0.088646)
		(layer "In11.Cu")
		(net "M_H_CPU1_SA_DQ<22>")
	)
	(segment
		(start 164.940488 -294.006524)
		(end 164.13099 -293.197026)
		(width 0.18288)
		(layer "In11.Cu")
		(net "M_H_CPU1_SA_DQ<22>")
	)
	(segment
		(start 195.283074 -293.750492)
		(end 194.331082 -294.702484)
		(width 0.18288)
		(layer "In11.Cu")
		(net "M_H_CPU1_SA_DQ<22>")
	)
	(segment
		(start 182.929276 -294.548814)
		(end 182.655972 -294.548814)
		(width 0.18288)
		(layer "In11.Cu")
		(net "M_H_CPU1_SA_DQ<22>")
	)
	(segment
		(start 183.80202 -294.304466)
		(end 183.696102 -294.198548)
		(width 0.18288)
		(layer "In11.Cu")
		(net "M_H_CPU1_SA_DQ<22>")
	)
	(segment
		(start 130.641344 -269.38351)
		(end 130.641344 -269.368016)
		(width 0.088646)
		(layer "In11.Cu")
		(net "M_H_CPU1_SA_DQ<22>")
	)
	(segment
		(start 159.869632 -291.821616)
		(end 158.667704 -291.821616)
		(width 0.18288)
		(layer "In11.Cu")
		(net "M_H_CPU1_SA_DQ<22>")
	)
	(segment
		(start 205.555088 -291.668708)
		(end 205.128876 -291.242496)
		(width 0.18288)
		(layer "In11.Cu")
		(net "M_H_CPU1_SA_DQ<22>")
	)
	(segment
		(start 182.655972 -294.548814)
		(end 182.281322 -294.174164)
		(width 0.18288)
		(layer "In11.Cu")
		(net "M_H_CPU1_SA_DQ<22>")
	)
	(segment
		(start 203.851002 -291.049456)
		(end 203.657962 -291.242496)
		(width 0.18288)
		(layer "In11.Cu")
		(net "M_H_CPU1_SA_DQ<22>")
	)
	(segment
		(start 207.071214 -290.816538)
		(end 207.045814 -290.816538)
		(width 0.18288)
		(layer "In11.Cu")
		(net "M_H_CPU1_SA_DQ<22>")
	)
	(segment
		(start 126.034546 -268.894052)
		(end 125.958346 -268.93901)
		(width 0.088646)
		(layer "In11.Cu")
		(net "M_H_CPU1_SA_DQ<22>")
	)
	(segment
		(start 138.218418 -272.63217)
		(end 138.218418 -272.463006)
		(width 0.088646)
		(layer "In11.Cu")
		(net "M_H_CPU1_SA_DQ<22>")
	)
	(segment
		(start 204.044042 -290.458398)
		(end 203.851002 -290.651438)
		(width 0.18288)
		(layer "In11.Cu")
		(net "M_H_CPU1_SA_DQ<22>")
	)
	(segment
		(start 131.768596 -271.335754)
		(end 131.759706 -271.330674)
		(width 0.088646)
		(layer "In11.Cu")
		(net "M_H_CPU1_SA_DQ<22>")
	)
	(segment
		(start 177.317908 -295.492424)
		(end 176.28997 -295.492424)
		(width 0.18288)
		(layer "In11.Cu")
		(net "M_H_CPU1_SA_DQ<22>")
	)
	(segment
		(start 202.757532 -291.242496)
		(end 202.156822 -290.641786)
		(width 0.18288)
		(layer "In11.Cu")
		(net "M_H_CPU1_SA_DQ<22>")
	)
	(segment
		(start 179.917852 -295.640252)
		(end 179.709826 -295.432226)
		(width 0.18288)
		(layer "In11.Cu")
		(net "M_H_CPU1_SA_DQ<22>")
	)
	(segment
		(start 198.016622 -292.993826)
		(end 196.633592 -292.993826)
		(width 0.18288)
		(layer "In11.Cu")
		(net "M_H_CPU1_SA_DQ<22>")
	)
	(segment
		(start 207.045814 -290.816538)
		(end 206.752444 -291.109146)
		(width 0.18288)
		(layer "In11.Cu")
		(net "M_H_CPU1_SA_DQ<22>")
	)
	(segment
		(start 128.868678 -268.885416)
		(end 128.853946 -268.894052)
		(width 0.088646)
		(layer "In11.Cu")
		(net "M_H_CPU1_SA_DQ<22>")
	)
	(segment
		(start 190.758318 -295.492424)
		(end 190.653162 -295.59758)
		(width 0.18288)
		(layer "In11.Cu")
		(net "M_H_CPU1_SA_DQ<22>")
	)
	(segment
		(start 198.702422 -292.308026)
		(end 198.016622 -292.993826)
		(width 0.18288)
		(layer "In11.Cu")
		(net "M_H_CPU1_SA_DQ<22>")
	)
	(segment
		(start 133.567678 -272.140934)
		(end 133.552946 -272.14957)
		(width 0.088646)
		(layer "In11.Cu")
		(net "M_H_CPU1_SA_DQ<22>")
	)
	(segment
		(start 172.246036 -296.401236)
		(end 171.330366 -296.401236)
		(width 0.18288)
		(layer "In11.Cu")
		(net "M_H_CPU1_SA_DQ<22>")
	)
	(segment
		(start 176.28997 -295.492424)
		(end 176.112678 -295.669716)
		(width 0.18288)
		(layer "In11.Cu")
		(net "M_H_CPU1_SA_DQ<22>")
	)
	(segment
		(start 169.610786 -294.680132)
		(end 168.997376 -294.680132)
		(width 0.18288)
		(layer "In11.Cu")
		(net "M_H_CPU1_SA_DQ<22>")
	)
	(segment
		(start 174.133764 -295.669716)
		(end 173.461172 -296.342308)
		(width 0.18288)
		(layer "In11.Cu")
		(net "M_H_CPU1_SA_DQ<22>")
	)
	(segment
		(start 126.605538 -268.897608)
		(end 126.599696 -268.894052)
		(width 0.088646)
		(layer "In11.Cu")
		(net "M_H_CPU1_SA_DQ<22>")
	)
	(segment
		(start 137.326878 -272.140934)
		(end 137.312146 -272.14957)
		(width 0.088646)
		(layer "In11.Cu")
		(net "M_H_CPU1_SA_DQ<22>")
	)
	(segment
		(start 131.581144 -271.011396)
		(end 131.581144 -270.995902)
		(width 0.088646)
		(layer "In11.Cu")
		(net "M_H_CPU1_SA_DQ<22>")
	)
	(segment
		(start 183.902604 -294.779192)
		(end 183.80202 -294.678608)
		(width 0.18288)
		(layer "In11.Cu")
		(net "M_H_CPU1_SA_DQ<22>")
	)
	(segment
		(start 157.580076 -291.308028)
		(end 155.780994 -289.508946)
		(width 0.18288)
		(layer "In11.Cu")
		(net "M_H_CPU1_SA_DQ<22>")
	)
	(segment
		(start 168.997376 -294.680132)
		(end 168.583864 -294.26662)
		(width 0.18288)
		(layer "In11.Cu")
		(net "M_H_CPU1_SA_DQ<22>")
	)
	(segment
		(start 206.752444 -291.109146)
		(end 206.752444 -291.242496)
		(width 0.18288)
		(layer "In11.Cu")
		(net "M_H_CPU1_SA_DQ<22>")
	)
	(segment
		(start 164.13099 -293.197026)
		(end 161.245042 -293.197026)
		(width 0.18288)
		(layer "In11.Cu")
		(net "M_H_CPU1_SA_DQ<22>")
	)
	(segment
		(start 173.461172 -296.342308)
		(end 172.304964 -296.342308)
		(width 0.18288)
		(layer "In11.Cu")
		(net "M_H_CPU1_SA_DQ<22>")
	)
	(segment
		(start 202.156822 -290.641786)
		(end 201.252582 -290.641786)
		(width 0.18288)
		(layer "In11.Cu")
		(net "M_H_CPU1_SA_DQ<22>")
	)
	(segment
		(start 206.326232 -291.668708)
		(end 205.555088 -291.668708)
		(width 0.18288)
		(layer "In11.Cu")
		(net "M_H_CPU1_SA_DQ<22>")
	)
	(segment
		(start 135.447278 -272.140934)
		(end 135.432546 -272.14957)
		(width 0.088646)
		(layer "In11.Cu")
		(net "M_H_CPU1_SA_DQ<22>")
	)
	(segment
		(start 168.583864 -294.26662)
		(end 167.020748 -294.26662)
		(width 0.18288)
		(layer "In11.Cu")
		(net "M_H_CPU1_SA_DQ<22>")
	)
	(segment
		(start 158.154116 -291.308028)
		(end 157.580076 -291.308028)
		(width 0.18288)
		(layer "In11.Cu")
		(net "M_H_CPU1_SA_DQ<22>")
	)
	(segment
		(start 180.395372 -295.640252)
		(end 179.917852 -295.640252)
		(width 0.18288)
		(layer "In11.Cu")
		(net "M_H_CPU1_SA_DQ<22>")
	)
	(segment
		(start 165.513512 -294.006524)
		(end 164.940488 -294.006524)
		(width 0.18288)
		(layer "In11.Cu")
		(net "M_H_CPU1_SA_DQ<22>")
	)
	(segment
		(start 193.172588 -295.492424)
		(end 190.758318 -295.492424)
		(width 0.18288)
		(layer "In11.Cu")
		(net "M_H_CPU1_SA_DQ<22>")
	)
	(segment
		(start 165.883844 -293.636192)
		(end 165.513512 -294.006524)
		(width 0.18288)
		(layer "In11.Cu")
		(net "M_H_CPU1_SA_DQ<22>")
	)
	(segment
		(start 155.780994 -289.508946)
		(end 155.780994 -288.942526)
		(width 0.18288)
		(layer "In11.Cu")
		(net "M_H_CPU1_SA_DQ<22>")
	)
	(segment
		(start 188.953902 -294.64254)
		(end 187.154312 -294.64254)
		(width 0.18288)
		(layer "In11.Cu")
		(net "M_H_CPU1_SA_DQ<22>")
	)
	(segment
		(start 126.599696 -268.894052)
		(end 126.593854 -268.89075)
		(width 0.088646)
		(layer "In11.Cu")
		(net "M_H_CPU1_SA_DQ<22>")
	)
	(segment
		(start 203.851002 -290.651438)
		(end 203.851002 -291.049456)
		(width 0.18288)
		(layer "In11.Cu")
		(net "M_H_CPU1_SA_DQ<22>")
	)
	(segment
		(start 172.304964 -296.342308)
		(end 172.246036 -296.401236)
		(width 0.18288)
		(layer "In11.Cu")
		(net "M_H_CPU1_SA_DQ<22>")
	)
	(segment
		(start 161.245042 -293.197026)
		(end 159.869632 -291.821616)
		(width 0.18288)
		(layer "In11.Cu")
		(net "M_H_CPU1_SA_DQ<22>")
	)
	(segment
		(start 140.377418 -273.53895)
		(end 139.349226 -273.53895)
		(width 0.18288)
		(layer "In11.Cu")
		(net "M_H_CPU1_SA_DQ<22>")
	)
	(segment
		(start 183.696102 -294.198548)
		(end 183.279542 -294.198548)
		(width 0.18288)
		(layer "In11.Cu")
		(net "M_H_CPU1_SA_DQ<22>")
	)
	(segment
		(start 182.281322 -294.174164)
		(end 181.86146 -294.174164)
		(width 0.18288)
		(layer "In11.Cu")
		(net "M_H_CPU1_SA_DQ<22>")
	)
	(segment
		(start 176.112678 -295.669716)
		(end 174.133764 -295.669716)
		(width 0.18288)
		(layer "In11.Cu")
		(net "M_H_CPU1_SA_DQ<22>")
	)
	(segment
		(start 179.709826 -295.432226)
		(end 178.757834 -295.432226)
		(width 0.18288)
		(layer "In11.Cu")
		(net "M_H_CPU1_SA_DQ<22>")
	)
	(segment
		(start 204.554582 -291.049456)
		(end 204.554582 -290.651438)
		(width 0.18288)
		(layer "In11.Cu")
		(net "M_H_CPU1_SA_DQ<22>")
	)
	(segment
		(start 195.876926 -293.750492)
		(end 195.283074 -293.750492)
		(width 0.18288)
		(layer "In11.Cu")
		(net "M_H_CPU1_SA_DQ<22>")
	)
	(segment
		(start 203.657962 -291.242496)
		(end 202.757532 -291.242496)
		(width 0.18288)
		(layer "In11.Cu")
		(net "M_H_CPU1_SA_DQ<22>")
	)
	(segment
		(start 131.29895 -270.521938)
		(end 131.29006 -270.516858)
		(width 0.088646)
		(layer "In11.Cu")
		(net "M_H_CPU1_SA_DQ<22>")
	)
	(segment
		(start 196.633592 -292.993826)
		(end 195.876926 -293.750492)
		(width 0.18288)
		(layer "In11.Cu")
		(net "M_H_CPU1_SA_DQ<22>")
	)
	(segment
		(start 204.554582 -290.651438)
		(end 204.361542 -290.458398)
		(width 0.18288)
		(layer "In11.Cu")
		(net "M_H_CPU1_SA_DQ<22>")
	)
	(segment
		(start 127.545338 -268.897608)
		(end 127.539496 -268.894052)
		(width 0.088646)
		(layer "In11.Cu")
		(net "M_H_CPU1_SA_DQ<22>")
	)
	(segment
		(start 139.125198 -273.53895)
		(end 138.218418 -272.63217)
		(width 0.088646)
		(layer "In11.Cu")
		(net "M_H_CPU1_SA_DQ<22>")
	)
	(segment
		(start 183.279542 -294.198548)
		(end 182.929276 -294.548814)
		(width 0.18288)
		(layer "In11.Cu")
		(net "M_H_CPU1_SA_DQ<22>")
	)
	(segment
		(start 194.331082 -294.702484)
		(end 193.962528 -294.702484)
		(width 0.18288)
		(layer "In11.Cu")
		(net "M_H_CPU1_SA_DQ<22>")
	)
	(segment
		(start 125.955298 -268.940026)
		(end 125.951488 -268.942058)
		(width 0.088646)
		(layer "In11.Cu")
		(net "M_H_CPU1_SA_DQ<22>")
	)
	(segment
		(start 131.111498 -270.19758)
		(end 131.111498 -270.183356)
		(width 0.088646)
		(layer "In11.Cu")
		(net "M_H_CPU1_SA_DQ<22>")
	)
	(segment
		(start 128.479296 -268.894052)
		(end 128.473454 -268.89075)
		(width 0.088646)
		(layer "In11.Cu")
		(net "M_H_CPU1_SA_DQ<22>")
	)
	(segment
		(start 134.507478 -272.140934)
		(end 134.492746 -272.14957)
		(width 0.088646)
		(layer "In11.Cu")
		(net "M_H_CPU1_SA_DQ<22>")
	)
	(segment
		(start 132.623306 -272.143474)
		(end 132.612892 -272.14957)
		(width 0.088646)
		(layer "In11.Cu")
		(net "M_H_CPU1_SA_DQ<22>")
	)
	(segment
		(start 187.154312 -294.64254)
		(end 187.01766 -294.779192)
		(width 0.18288)
		(layer "In11.Cu")
		(net "M_H_CPU1_SA_DQ<22>")
	)
	(segment
		(start 181.86146 -294.174164)
		(end 180.395372 -295.640252)
		(width 0.18288)
		(layer "In11.Cu")
		(net "M_H_CPU1_SA_DQ<22>")
	)
	(segment
		(start 199.586342 -292.308026)
		(end 198.702422 -292.308026)
		(width 0.18288)
		(layer "In11.Cu")
		(net "M_H_CPU1_SA_DQ<22>")
	)
	(segment
		(start 206.752444 -291.242496)
		(end 206.326232 -291.668708)
		(width 0.18288)
		(layer "In11.Cu")
		(net "M_H_CPU1_SA_DQ<22>")
	)
	(segment
		(start 190.653162 -295.59758)
		(end 189.908942 -295.59758)
		(width 0.18288)
		(layer "In11.Cu")
		(net "M_H_CPU1_SA_DQ<22>")
	)
	(segment
		(start 189.908942 -295.59758)
		(end 188.953902 -294.64254)
		(width 0.18288)
		(layer "In11.Cu")
		(net "M_H_CPU1_SA_DQ<22>")
	)
	(segment
		(start 128.485138 -268.897608)
		(end 128.479296 -268.894052)
		(width 0.088646)
		(layer "In11.Cu")
		(net "M_H_CPU1_SA_DQ<22>")
	)
	(segment
		(start 131.774692 -271.33931)
		(end 131.768596 -271.335754)
		(width 0.088646)
		(layer "In11.Cu")
		(net "M_H_CPU1_SA_DQ<22>")
	)
	(segment
		(start 127.539496 -268.894052)
		(end 127.533654 -268.89075)
		(width 0.088646)
		(layer "In11.Cu")
		(net "M_H_CPU1_SA_DQ<22>")
	)
	(segment
		(start 139.349226 -273.53895)
		(end 139.125198 -273.53895)
		(width 0.088646)
		(layer "In11.Cu")
		(net "M_H_CPU1_SA_DQ<22>")
	)
	(segment
		(start 204.361542 -290.458398)
		(end 204.044042 -290.458398)
		(width 0.18288)
		(layer "In11.Cu")
		(net "M_H_CPU1_SA_DQ<22>")
	)
	(segment
		(start 187.01766 -294.779192)
		(end 183.902604 -294.779192)
		(width 0.18288)
		(layer "In11.Cu")
		(net "M_H_CPU1_SA_DQ<22>")
	)
	(segment
		(start 171.330366 -296.401236)
		(end 169.610786 -294.680132)
		(width 0.18288)
		(layer "In11.Cu")
		(net "M_H_CPU1_SA_DQ<22>")
	)
	(segment
		(start 204.747622 -291.242496)
		(end 204.554582 -291.049456)
		(width 0.18288)
		(layer "In11.Cu")
		(net "M_H_CPU1_SA_DQ<22>")
	)
	(segment
		(start 130.828796 -269.707868)
		(end 130.819906 -269.702788)
		(width 0.088646)
		(layer "In11.Cu")
		(net "M_H_CPU1_SA_DQ<22>")
	)
	(segment
		(start 205.128876 -291.242496)
		(end 204.747622 -291.242496)
		(width 0.18288)
		(layer "In11.Cu")
		(net "M_H_CPU1_SA_DQ<22>")
	)
	(segment
		(start 177.591466 -295.765982)
		(end 177.317908 -295.492424)
		(width 0.18288)
		(layer "In11.Cu")
		(net "M_H_CPU1_SA_DQ<22>")
	)
	(segment
		(start 129.808478 -268.885416)
		(end 129.793746 -268.894052)
		(width 0.088646)
		(layer "In11.Cu")
		(net "M_H_CPU1_SA_DQ<22>")
	)
	(segment
		(start 138.218418 -272.463006)
		(end 137.994644 -272.239232)
		(width 0.088646)
		(layer "In11.Cu")
		(net "M_H_CPU1_SA_DQ<22>")
	)
	(segment
		(start 193.962528 -294.702484)
		(end 193.172588 -295.492424)
		(width 0.18288)
		(layer "In11.Cu")
		(net "M_H_CPU1_SA_DQ<22>")
	)
	(segment
		(start 158.667704 -291.821616)
		(end 158.154116 -291.308028)
		(width 0.18288)
		(layer "In11.Cu")
		(net "M_H_CPU1_SA_DQ<22>")
	)
	(segment
		(start 167.020748 -294.26662)
		(end 166.39032 -293.636192)
		(width 0.18288)
		(layer "In11.Cu")
		(net "M_H_CPU1_SA_DQ<22>")
	)
	(segment
		(start 201.252582 -290.641786)
		(end 199.586342 -292.308026)
		(width 0.18288)
		(layer "In11.Cu")
		(net "M_H_CPU1_SA_DQ<22>")
	)
	(arc
		(start 136.372346 -272.14957)
		(mid 136.185148 -272.199713)
		(end 135.99795 -272.14957)
		(width 0.088646)
		(layer "In11.Cu")
		(net "M_H_CPU1_SA_DQ<22>")
	)
	(arc
		(start 132.612892 -272.14957)
		(mid 132.425694 -272.199713)
		(end 132.238496 -272.14957)
		(width 0.088646)
		(layer "In11.Cu")
		(net "M_H_CPU1_SA_DQ<22>")
	)
	(arc
		(start 137.312146 -272.14957)
		(mid 137.124948 -272.199713)
		(end 136.93775 -272.14957)
		(width 0.088646)
		(layer "In11.Cu")
		(net "M_H_CPU1_SA_DQ<22>")
	)
	(arc
		(start 131.29006 -270.516858)
		(mid 131.159146 -270.380498)
		(end 131.111498 -270.19758)
		(width 0.088646)
		(layer "In11.Cu")
		(net "M_H_CPU1_SA_DQ<22>")
	)
	(arc
		(start 130.819906 -269.702788)
		(mid 130.688992 -269.566428)
		(end 130.641344 -269.38351)
		(width 0.088646)
		(layer "In11.Cu")
		(net "M_H_CPU1_SA_DQ<22>")
	)
	(arc
		(start 127.533654 -268.89075)
		(mid 127.253693 -268.818433)
		(end 126.9746 -268.894052)
		(width 0.088646)
		(layer "In11.Cu")
		(net "M_H_CPU1_SA_DQ<22>")
	)
	(arc
		(start 130.641344 -269.368016)
		(mid 130.561974 -269.094282)
		(end 130.35915 -268.894052)
		(width 0.088646)
		(layer "In11.Cu")
		(net "M_H_CPU1_SA_DQ<22>")
	)
	(arc
		(start 127.914146 -268.894052)
		(mid 127.730222 -268.944306)
		(end 127.545338 -268.897608)
		(width 0.088646)
		(layer "In11.Cu")
		(net "M_H_CPU1_SA_DQ<22>")
	)
	(arc
		(start 126.9746 -268.894052)
		(mid 126.790533 -268.944432)
		(end 126.605538 -268.897608)
		(width 0.088646)
		(layer "In11.Cu")
		(net "M_H_CPU1_SA_DQ<22>")
	)
	(arc
		(start 128.853946 -268.894052)
		(mid 128.670022 -268.944306)
		(end 128.485138 -268.897608)
		(width 0.088646)
		(layer "In11.Cu")
		(net "M_H_CPU1_SA_DQ<22>")
	)
	(arc
		(start 129.793746 -268.894052)
		(mid 129.606548 -268.944195)
		(end 129.41935 -268.894052)
		(width 0.088646)
		(layer "In11.Cu")
		(net "M_H_CPU1_SA_DQ<22>")
	)
	(arc
		(start 126.593854 -268.89075)
		(mid 126.313749 -268.818308)
		(end 126.034546 -268.894052)
		(width 0.088646)
		(layer "In11.Cu")
		(net "M_H_CPU1_SA_DQ<22>")
	)
	(arc
		(start 129.41935 -268.894052)
		(mid 129.145151 -268.818217)
		(end 128.868678 -268.885416)
		(width 0.088646)
		(layer "In11.Cu")
		(net "M_H_CPU1_SA_DQ<22>")
	)
	(arc
		(start 134.492746 -272.14957)
		(mid 134.305548 -272.199713)
		(end 134.11835 -272.14957)
		(width 0.088646)
		(layer "In11.Cu")
		(net "M_H_CPU1_SA_DQ<22>")
	)
	(arc
		(start 135.432546 -272.14957)
		(mid 135.245348 -272.199713)
		(end 135.05815 -272.14957)
		(width 0.088646)
		(layer "In11.Cu")
		(net "M_H_CPU1_SA_DQ<22>")
	)
	(arc
		(start 135.99795 -272.14957)
		(mid 135.723721 -272.073645)
		(end 135.447278 -272.140934)
		(width 0.088646)
		(layer "In11.Cu")
		(net "M_H_CPU1_SA_DQ<22>")
	)
	(arc
		(start 125.951488 -268.942058)
		(mid 125.649957 -269.144072)
		(end 125.377194 -269.38351)
		(width 0.088646)
		(layer "In11.Cu")
		(net "M_H_CPU1_SA_DQ<22>")
	)
	(arc
		(start 136.93775 -272.14957)
		(mid 136.663521 -272.073645)
		(end 136.387078 -272.140934)
		(width 0.088646)
		(layer "In11.Cu")
		(net "M_H_CPU1_SA_DQ<22>")
	)
	(arc
		(start 130.35915 -268.894052)
		(mid 130.084951 -268.818217)
		(end 129.808478 -268.885416)
		(width 0.088646)
		(layer "In11.Cu")
		(net "M_H_CPU1_SA_DQ<22>")
	)
	(arc
		(start 132.051298 -271.825212)
		(mid 131.977307 -271.545646)
		(end 131.774692 -271.33931)
		(width 0.088646)
		(layer "In11.Cu")
		(net "M_H_CPU1_SA_DQ<22>")
	)
	(arc
		(start 131.111498 -270.183356)
		(mid 131.032279 -269.908671)
		(end 130.828796 -269.707868)
		(width 0.088646)
		(layer "In11.Cu")
		(net "M_H_CPU1_SA_DQ<22>")
	)
	(arc
		(start 125.958346 -268.93901)
		(mid 125.956827 -268.939534)
		(end 125.955298 -268.940026)
		(width 0.088646)
		(layer "In11.Cu")
		(net "M_H_CPU1_SA_DQ<22>")
	)
	(arc
		(start 137.994644 -272.239232)
		(mid 137.939028 -272.190574)
		(end 137.87755 -272.14957)
		(width 0.088646)
		(layer "In11.Cu")
		(net "M_H_CPU1_SA_DQ<22>")
	)
	(arc
		(start 128.473454 -268.89075)
		(mid 128.193349 -268.818308)
		(end 127.914146 -268.894052)
		(width 0.088646)
		(layer "In11.Cu")
		(net "M_H_CPU1_SA_DQ<22>")
	)
	(arc
		(start 133.17855 -272.14957)
		(mid 132.901737 -272.073734)
		(end 132.623306 -272.143474)
		(width 0.088646)
		(layer "In11.Cu")
		(net "M_H_CPU1_SA_DQ<22>")
	)
	(arc
		(start 131.581144 -270.995902)
		(mid 131.501774 -270.722168)
		(end 131.29895 -270.521938)
		(width 0.088646)
		(layer "In11.Cu")
		(net "M_H_CPU1_SA_DQ<22>")
	)
	(arc
		(start 132.238496 -272.14957)
		(mid 132.103563 -272.016216)
		(end 132.051298 -271.833848)
		(width 0.088646)
		(layer "In11.Cu")
		(net "M_H_CPU1_SA_DQ<22>")
	)
	(arc
		(start 133.552946 -272.14957)
		(mid 133.365748 -272.199713)
		(end 133.17855 -272.14957)
		(width 0.088646)
		(layer "In11.Cu")
		(net "M_H_CPU1_SA_DQ<22>")
	)
	(arc
		(start 137.87755 -272.14957)
		(mid 137.603321 -272.073645)
		(end 137.326878 -272.140934)
		(width 0.088646)
		(layer "In11.Cu")
		(net "M_H_CPU1_SA_DQ<22>")
	)
	(arc
		(start 134.11835 -272.14957)
		(mid 133.844121 -272.073645)
		(end 133.567678 -272.140934)
		(width 0.088646)
		(layer "In11.Cu")
		(net "M_H_CPU1_SA_DQ<22>")
	)
	(arc
		(start 135.05815 -272.14957)
		(mid 134.783921 -272.073645)
		(end 134.507478 -272.140934)
		(width 0.088646)
		(layer "In11.Cu")
		(net "M_H_CPU1_SA_DQ<22>")
	)
	(arc
		(start 131.759706 -271.330674)
		(mid 131.628792 -271.194314)
		(end 131.581144 -271.011396)
		(width 0.088646)
		(layer "In11.Cu")
		(net "M_H_CPU1_SA_DQ<22>")
	)
	(segment
		(start 211.619846 -289.966654)
		(end 211.619592 -289.966908)
		(width 0.20066)
		(layer "F.Cu")
		(net "M_H_CPU1_SA_DQ<21>")
	)
	(segment
		(start 206.626714 -289.541712)
		(end 206.508604 -289.659822)
		(width 0.20066)
		(layer "F.Cu")
		(net "M_H_CPU1_SA_DQ<21>")
	)
	(segment
		(start 209.596482 -289.535362)
		(end 209.186526 -289.535362)
		(width 0.20066)
		(layer "F.Cu")
		(net "M_H_CPU1_SA_DQ<21>")
	)
	(segment
		(start 205.596744 -289.966654)
		(end 204.076046 -289.966654)
		(width 0.20066)
		(layer "F.Cu")
		(net "M_H_CPU1_SA_DQ<21>")
	)
	(segment
		(start 206.320644 -290.21532)
		(end 205.84541 -290.21532)
		(width 0.20066)
		(layer "F.Cu")
		(net "M_H_CPU1_SA_DQ<21>")
	)
	(segment
		(start 123.967494 -268.56944)
		(end 123.967748 -268.569694)
		(width 0.20066)
		(layer "F.Cu")
		(net "M_H_CPU1_SA_DQ<21>")
	)
	(segment
		(start 205.84541 -290.21532)
		(end 205.596744 -289.966654)
		(width 0.20066)
		(layer "F.Cu")
		(net "M_H_CPU1_SA_DQ<21>")
	)
	(segment
		(start 204.076046 -289.966654)
		(end 202.971146 -289.966654)
		(width 0.20066)
		(layer "F.Cu")
		(net "M_H_CPU1_SA_DQ<21>")
	)
	(segment
		(start 123.967494 -268.033754)
		(end 123.967494 -268.56944)
		(width 0.20066)
		(layer "F.Cu")
		(net "M_H_CPU1_SA_DQ<21>")
	)
	(segment
		(start 210.028028 -289.966908)
		(end 209.596482 -289.535362)
		(width 0.20066)
		(layer "F.Cu")
		(net "M_H_CPU1_SA_DQ<21>")
	)
	(segment
		(start 206.508604 -289.659822)
		(end 206.508604 -290.02736)
		(width 0.20066)
		(layer "F.Cu")
		(net "M_H_CPU1_SA_DQ<21>")
	)
	(segment
		(start 209.180176 -289.541712)
		(end 206.991458 -289.541712)
		(width 0.1016)
		(layer "F.Cu")
		(net "M_H_CPU1_SA_DQ<21>")
	)
	(segment
		(start 209.186526 -289.535362)
		(end 209.180176 -289.541712)
		(width 0.1016)
		(layer "F.Cu")
		(net "M_H_CPU1_SA_DQ<21>")
	)
	(segment
		(start 206.991458 -289.541712)
		(end 206.971392 -289.541712)
		(width 0.101854)
		(layer "F.Cu")
		(net "M_H_CPU1_SA_DQ<21>")
	)
	(segment
		(start 206.971392 -289.541712)
		(end 206.626714 -289.541712)
		(width 0.20066)
		(layer "F.Cu")
		(net "M_H_CPU1_SA_DQ<21>")
	)
	(segment
		(start 211.619592 -289.966908)
		(end 210.028028 -289.966908)
		(width 0.20066)
		(layer "F.Cu")
		(net "M_H_CPU1_SA_DQ<21>")
	)
	(segment
		(start 206.508604 -290.02736)
		(end 206.320644 -290.21532)
		(width 0.20066)
		(layer "F.Cu")
		(net "M_H_CPU1_SA_DQ<21>")
	)
	(segment
		(start 133.567678 -271.50949)
		(end 133.552946 -271.500854)
		(width 0.088646)
		(layer "In11.Cu")
		(net "M_H_CPU1_SA_DQ<21>")
	)
	(segment
		(start 177.726848 -294.641524)
		(end 176.392332 -294.641524)
		(width 0.18288)
		(layer "In11.Cu")
		(net "M_H_CPU1_SA_DQ<21>")
	)
	(segment
		(start 156.358336 -289.255962)
		(end 156.358336 -288.694114)
		(width 0.18288)
		(layer "In11.Cu")
		(net "M_H_CPU1_SA_DQ<21>")
	)
	(segment
		(start 125.189996 -269.059152)
		(end 125.187202 -269.060676)
		(width 0.088646)
		(layer "In11.Cu")
		(net "M_H_CPU1_SA_DQ<21>")
	)
	(segment
		(start 177.919888 -293.951914)
		(end 177.919888 -294.448484)
		(width 0.18288)
		(layer "In11.Cu")
		(net "M_H_CPU1_SA_DQ<21>")
	)
	(segment
		(start 185.76925 -292.641274)
		(end 185.45175 -292.641274)
		(width 0.18288)
		(layer "In11.Cu")
		(net "M_H_CPU1_SA_DQ<21>")
	)
	(segment
		(start 186.979052 -293.41191)
		(end 186.15533 -293.41191)
		(width 0.18288)
		(layer "In11.Cu")
		(net "M_H_CPU1_SA_DQ<21>")
	)
	(segment
		(start 190.913512 -294.415718)
		(end 190.720472 -294.222678)
		(width 0.18288)
		(layer "In11.Cu")
		(net "M_H_CPU1_SA_DQ<21>")
	)
	(segment
		(start 130.733546 -268.245336)
		(end 130.733292 -268.245336)
		(width 0.088646)
		(layer "In11.Cu")
		(net "M_H_CPU1_SA_DQ<21>")
	)
	(segment
		(start 157.343856 -290.241482)
		(end 156.358336 -289.255962)
		(width 0.18288)
		(layer "In11.Cu")
		(net "M_H_CPU1_SA_DQ<21>")
	)
	(segment
		(start 200.023984 -291.032692)
		(end 199.26046 -291.032692)
		(width 0.18288)
		(layer "In11.Cu")
		(net "M_H_CPU1_SA_DQ<21>")
	)
	(segment
		(start 157.972506 -290.241482)
		(end 157.343856 -290.241482)
		(width 0.18288)
		(layer "In11.Cu")
		(net "M_H_CPU1_SA_DQ<21>")
	)
	(segment
		(start 156.358336 -288.694114)
		(end 140.85189 -273.187668)
		(width 0.18288)
		(layer "In11.Cu")
		(net "M_H_CPU1_SA_DQ<21>")
	)
	(segment
		(start 190.016892 -294.222678)
		(end 189.823852 -294.415718)
		(width 0.18288)
		(layer "In11.Cu")
		(net "M_H_CPU1_SA_DQ<21>")
	)
	(segment
		(start 176.067974 -294.317166)
		(end 174.762922 -294.317166)
		(width 0.18288)
		(layer "In11.Cu")
		(net "M_H_CPU1_SA_DQ<21>")
	)
	(segment
		(start 178.623468 -293.951914)
		(end 178.430428 -293.758874)
		(width 0.18288)
		(layer "In11.Cu")
		(net "M_H_CPU1_SA_DQ<21>")
	)
	(segment
		(start 201.53249 -289.524186)
		(end 200.023984 -291.032692)
		(width 0.18288)
		(layer "In11.Cu")
		(net "M_H_CPU1_SA_DQ<21>")
	)
	(segment
		(start 185.96229 -292.834314)
		(end 185.76925 -292.641274)
		(width 0.18288)
		(layer "In11.Cu")
		(net "M_H_CPU1_SA_DQ<21>")
	)
	(segment
		(start 191.700404 -294.642286)
		(end 191.473836 -294.415718)
		(width 0.18288)
		(layer "In11.Cu")
		(net "M_H_CPU1_SA_DQ<21>")
	)
	(segment
		(start 163.027614 -292.074854)
		(end 162.834574 -291.881814)
		(width 0.18288)
		(layer "In11.Cu")
		(net "M_H_CPU1_SA_DQ<21>")
	)
	(segment
		(start 134.507478 -271.50949)
		(end 134.492746 -271.500854)
		(width 0.088646)
		(layer "In11.Cu")
		(net "M_H_CPU1_SA_DQ<21>")
	)
	(segment
		(start 202.895962 -290.041838)
		(end 202.49261 -290.041838)
		(width 0.18288)
		(layer "In11.Cu")
		(net "M_H_CPU1_SA_DQ<21>")
	)
	(segment
		(start 166.273226 -292.668706)
		(end 165.762686 -292.668706)
		(width 0.18288)
		(layer "In11.Cu")
		(net "M_H_CPU1_SA_DQ<21>")
	)
	(segment
		(start 188.412882 -292.938708)
		(end 187.452254 -292.938708)
		(width 0.18288)
		(layer "In11.Cu")
		(net "M_H_CPU1_SA_DQ<21>")
	)
	(segment
		(start 124.624846 -269.059152)
		(end 124.61875 -269.055596)
		(width 0.088646)
		(layer "In11.Cu")
		(net "M_H_CPU1_SA_DQ<21>")
	)
	(segment
		(start 179.81295 -294.662606)
		(end 178.816508 -294.662606)
		(width 0.18288)
		(layer "In11.Cu")
		(net "M_H_CPU1_SA_DQ<21>")
	)
	(segment
		(start 139.12977 -273.187668)
		(end 138.423396 -272.481294)
		(width 0.088646)
		(layer "In11.Cu")
		(net "M_H_CPU1_SA_DQ<21>")
	)
	(segment
		(start 168.48836 -293.554658)
		(end 168.021508 -293.554658)
		(width 0.18288)
		(layer "In11.Cu")
		(net "M_H_CPU1_SA_DQ<21>")
	)
	(segment
		(start 164.346128 -292.641274)
		(end 163.220654 -292.641274)
		(width 0.18288)
		(layer "In11.Cu")
		(net "M_H_CPU1_SA_DQ<21>")
	)
	(segment
		(start 202.971146 -289.966654)
		(end 202.895962 -290.041838)
		(width 0.18288)
		(layer "In11.Cu")
		(net "M_H_CPU1_SA_DQ<21>")
	)
	(segment
		(start 188.926724 -293.45255)
		(end 188.412882 -292.938708)
		(width 0.18288)
		(layer "In11.Cu")
		(net "M_H_CPU1_SA_DQ<21>")
	)
	(segment
		(start 191.473836 -294.415718)
		(end 190.913512 -294.415718)
		(width 0.18288)
		(layer "In11.Cu")
		(net "M_H_CPU1_SA_DQ<21>")
	)
	(segment
		(start 168.021508 -293.554658)
		(end 167.82034 -293.755826)
		(width 0.18288)
		(layer "In11.Cu")
		(net "M_H_CPU1_SA_DQ<21>")
	)
	(segment
		(start 176.392332 -294.641524)
		(end 176.067974 -294.317166)
		(width 0.18288)
		(layer "In11.Cu")
		(net "M_H_CPU1_SA_DQ<21>")
	)
	(segment
		(start 128.868678 -268.253972)
		(end 128.853946 -268.245336)
		(width 0.088646)
		(layer "In11.Cu")
		(net "M_H_CPU1_SA_DQ<21>")
	)
	(segment
		(start 178.112928 -293.758874)
		(end 177.919888 -293.951914)
		(width 0.18288)
		(layer "In11.Cu")
		(net "M_H_CPU1_SA_DQ<21>")
	)
	(segment
		(start 139.325604 -273.187668)
		(end 139.12977 -273.187668)
		(width 0.088646)
		(layer "In11.Cu")
		(net "M_H_CPU1_SA_DQ<21>")
	)
	(segment
		(start 162.324034 -292.448234)
		(end 162.130994 -292.641274)
		(width 0.18288)
		(layer "In11.Cu")
		(net "M_H_CPU1_SA_DQ<21>")
	)
	(segment
		(start 188.926724 -293.852854)
		(end 188.926724 -293.45255)
		(width 0.18288)
		(layer "In11.Cu")
		(net "M_H_CPU1_SA_DQ<21>")
	)
	(segment
		(start 184.163462 -293.656512)
		(end 181.30774 -293.656512)
		(width 0.18288)
		(layer "In11.Cu")
		(net "M_H_CPU1_SA_DQ<21>")
	)
	(segment
		(start 159.018986 -291.287962)
		(end 157.972506 -290.241482)
		(width 0.18288)
		(layer "In11.Cu")
		(net "M_H_CPU1_SA_DQ<21>")
	)
	(segment
		(start 133.552946 -271.500854)
		(end 133.54685 -271.497298)
		(width 0.088646)
		(layer "In11.Cu")
		(net "M_H_CPU1_SA_DQ<21>")
	)
	(segment
		(start 137.326878 -271.50949)
		(end 137.312146 -271.500854)
		(width 0.088646)
		(layer "In11.Cu")
		(net "M_H_CPU1_SA_DQ<21>")
	)
	(segment
		(start 198.391526 -291.901626)
		(end 196.715126 -291.901626)
		(width 0.18288)
		(layer "In11.Cu")
		(net "M_H_CPU1_SA_DQ<21>")
	)
	(segment
		(start 185.25871 -293.21887)
		(end 185.06567 -293.41191)
		(width 0.18288)
		(layer "In11.Cu")
		(net "M_H_CPU1_SA_DQ<21>")
	)
	(segment
		(start 185.25871 -292.834314)
		(end 185.25871 -293.21887)
		(width 0.18288)
		(layer "In11.Cu")
		(net "M_H_CPU1_SA_DQ<21>")
	)
	(segment
		(start 174.762922 -294.317166)
		(end 173.587918 -295.49217)
		(width 0.18288)
		(layer "In11.Cu")
		(net "M_H_CPU1_SA_DQ<21>")
	)
	(segment
		(start 132.800344 -270.207486)
		(end 132.800344 -270.188944)
		(width 0.088646)
		(layer "In11.Cu")
		(net "M_H_CPU1_SA_DQ<21>")
	)
	(segment
		(start 189.489588 -294.415718)
		(end 188.926724 -293.852854)
		(width 0.18288)
		(layer "In11.Cu")
		(net "M_H_CPU1_SA_DQ<21>")
	)
	(segment
		(start 140.85189 -273.187668)
		(end 139.325604 -273.187668)
		(width 0.18288)
		(layer "In11.Cu")
		(net "M_H_CPU1_SA_DQ<21>")
	)
	(segment
		(start 165.762686 -292.668706)
		(end 165.435026 -292.996366)
		(width 0.18288)
		(layer "In11.Cu")
		(net "M_H_CPU1_SA_DQ<21>")
	)
	(segment
		(start 169.552112 -293.755826)
		(end 168.689528 -293.755826)
		(width 0.18288)
		(layer "In11.Cu")
		(net "M_H_CPU1_SA_DQ<21>")
	)
	(segment
		(start 129.808478 -268.253972)
		(end 129.793746 -268.245336)
		(width 0.088646)
		(layer "In11.Cu")
		(net "M_H_CPU1_SA_DQ<21>")
	)
	(segment
		(start 190.720472 -293.79672)
		(end 190.527432 -293.60368)
		(width 0.18288)
		(layer "In11.Cu")
		(net "M_H_CPU1_SA_DQ<21>")
	)
	(segment
		(start 135.447278 -271.50949)
		(end 135.432546 -271.500854)
		(width 0.088646)
		(layer "In11.Cu")
		(net "M_H_CPU1_SA_DQ<21>")
	)
	(segment
		(start 171.976288 -295.49217)
		(end 171.769786 -295.285668)
		(width 0.18288)
		(layer "In11.Cu")
		(net "M_H_CPU1_SA_DQ<21>")
	)
	(segment
		(start 178.816508 -294.662606)
		(end 178.623468 -294.469566)
		(width 0.18288)
		(layer "In11.Cu")
		(net "M_H_CPU1_SA_DQ<21>")
	)
	(segment
		(start 161.696654 -292.641274)
		(end 160.343342 -291.287962)
		(width 0.18288)
		(layer "In11.Cu")
		(net "M_H_CPU1_SA_DQ<21>")
	)
	(segment
		(start 173.587918 -295.49217)
		(end 171.976288 -295.49217)
		(width 0.18288)
		(layer "In11.Cu")
		(net "M_H_CPU1_SA_DQ<21>")
	)
	(segment
		(start 178.430428 -293.758874)
		(end 178.112928 -293.758874)
		(width 0.18288)
		(layer "In11.Cu")
		(net "M_H_CPU1_SA_DQ<21>")
	)
	(segment
		(start 162.130994 -292.641274)
		(end 161.696654 -292.641274)
		(width 0.18288)
		(layer "In11.Cu")
		(net "M_H_CPU1_SA_DQ<21>")
	)
	(segment
		(start 196.715126 -291.901626)
		(end 195.622926 -292.993826)
		(width 0.18288)
		(layer "In11.Cu")
		(net "M_H_CPU1_SA_DQ<21>")
	)
	(segment
		(start 162.517074 -291.881814)
		(end 162.324034 -292.074854)
		(width 0.18288)
		(layer "In11.Cu")
		(net "M_H_CPU1_SA_DQ<21>")
	)
	(segment
		(start 124.549662 -269.007336)
		(end 123.967748 -268.569694)
		(width 0.088646)
		(layer "In11.Cu")
		(net "M_H_CPU1_SA_DQ<21>")
	)
	(segment
		(start 184.639966 -293.41191)
		(end 184.408572 -293.411656)
		(width 0.18288)
		(layer "In11.Cu")
		(net "M_H_CPU1_SA_DQ<21>")
	)
	(segment
		(start 187.452254 -292.938708)
		(end 186.979052 -293.41191)
		(width 0.18288)
		(layer "In11.Cu")
		(net "M_H_CPU1_SA_DQ<21>")
	)
	(segment
		(start 162.834574 -291.881814)
		(end 162.517074 -291.881814)
		(width 0.18288)
		(layer "In11.Cu")
		(net "M_H_CPU1_SA_DQ<21>")
	)
	(segment
		(start 202.49261 -290.041838)
		(end 201.974958 -289.524186)
		(width 0.18288)
		(layer "In11.Cu")
		(net "M_H_CPU1_SA_DQ<21>")
	)
	(segment
		(start 180.097176 -294.377872)
		(end 179.81295 -294.662606)
		(width 0.18288)
		(layer "In11.Cu")
		(net "M_H_CPU1_SA_DQ<21>")
	)
	(segment
		(start 189.823852 -294.415718)
		(end 189.489588 -294.415718)
		(width 0.18288)
		(layer "In11.Cu")
		(net "M_H_CPU1_SA_DQ<21>")
	)
	(segment
		(start 184.408572 -293.411656)
		(end 184.163462 -293.656512)
		(width 0.18288)
		(layer "In11.Cu")
		(net "M_H_CPU1_SA_DQ<21>")
	)
	(segment
		(start 201.974958 -289.524186)
		(end 201.53249 -289.524186)
		(width 0.18288)
		(layer "In11.Cu")
		(net "M_H_CPU1_SA_DQ<21>")
	)
	(segment
		(start 190.016892 -293.79672)
		(end 190.016892 -294.222678)
		(width 0.18288)
		(layer "In11.Cu")
		(net "M_H_CPU1_SA_DQ<21>")
	)
	(segment
		(start 136.387078 -271.50949)
		(end 136.372346 -271.500854)
		(width 0.088646)
		(layer "In11.Cu")
		(net "M_H_CPU1_SA_DQ<21>")
	)
	(segment
		(start 185.96229 -293.21887)
		(end 185.96229 -292.834314)
		(width 0.18288)
		(layer "In11.Cu")
		(net "M_H_CPU1_SA_DQ<21>")
	)
	(segment
		(start 177.919888 -294.448484)
		(end 177.726848 -294.641524)
		(width 0.18288)
		(layer "In11.Cu")
		(net "M_H_CPU1_SA_DQ<21>")
	)
	(segment
		(start 133.091682 -270.692118)
		(end 133.082792 -270.687038)
		(width 0.088646)
		(layer "In11.Cu")
		(net "M_H_CPU1_SA_DQ<21>")
	)
	(segment
		(start 130.742436 -268.250416)
		(end 130.733546 -268.245336)
		(width 0.088646)
		(layer "In11.Cu")
		(net "M_H_CPU1_SA_DQ<21>")
	)
	(segment
		(start 194.721226 -292.993826)
		(end 193.072766 -294.642286)
		(width 0.18288)
		(layer "In11.Cu")
		(net "M_H_CPU1_SA_DQ<21>")
	)
	(segment
		(start 130.920998 -268.585188)
		(end 130.920998 -268.569694)
		(width 0.088646)
		(layer "In11.Cu")
		(net "M_H_CPU1_SA_DQ<21>")
	)
	(segment
		(start 127.928878 -268.253972)
		(end 127.914146 -268.245336)
		(width 0.088646)
		(layer "In11.Cu")
		(net "M_H_CPU1_SA_DQ<21>")
	)
	(segment
		(start 126.0348 -268.245336)
		(end 126.034546 -268.245336)
		(width 0.088646)
		(layer "In11.Cu")
		(net "M_H_CPU1_SA_DQ<21>")
	)
	(segment
		(start 163.027614 -292.448234)
		(end 163.027614 -292.074854)
		(width 0.18288)
		(layer "In11.Cu")
		(net "M_H_CPU1_SA_DQ<21>")
	)
	(segment
		(start 138.423396 -272.481294)
		(end 138.423396 -271.672304)
		(width 0.088646)
		(layer "In11.Cu")
		(net "M_H_CPU1_SA_DQ<21>")
	)
	(segment
		(start 162.324034 -292.074854)
		(end 162.324034 -292.448234)
		(width 0.18288)
		(layer "In11.Cu")
		(net "M_H_CPU1_SA_DQ<21>")
	)
	(segment
		(start 171.081954 -295.285668)
		(end 169.552112 -293.755826)
		(width 0.18288)
		(layer "In11.Cu")
		(net "M_H_CPU1_SA_DQ<21>")
	)
	(segment
		(start 190.720472 -294.222678)
		(end 190.720472 -293.79672)
		(width 0.18288)
		(layer "In11.Cu")
		(net "M_H_CPU1_SA_DQ<21>")
	)
	(segment
		(start 190.527432 -293.60368)
		(end 190.209932 -293.60368)
		(width 0.18288)
		(layer "In11.Cu")
		(net "M_H_CPU1_SA_DQ<21>")
	)
	(segment
		(start 131.390644 -269.397734)
		(end 131.390644 -269.38351)
		(width 0.088646)
		(layer "In11.Cu")
		(net "M_H_CPU1_SA_DQ<21>")
	)
	(segment
		(start 168.689528 -293.755826)
		(end 168.48836 -293.554658)
		(width 0.18288)
		(layer "In11.Cu")
		(net "M_H_CPU1_SA_DQ<21>")
	)
	(segment
		(start 131.688078 -269.881858)
		(end 131.673346 -269.873222)
		(width 0.088646)
		(layer "In11.Cu")
		(net "M_H_CPU1_SA_DQ<21>")
	)
	(segment
		(start 126.989078 -268.253972)
		(end 126.974346 -268.245336)
		(width 0.088646)
		(layer "In11.Cu")
		(net "M_H_CPU1_SA_DQ<21>")
	)
	(segment
		(start 199.26046 -291.032692)
		(end 198.391526 -291.901626)
		(width 0.18288)
		(layer "In11.Cu")
		(net "M_H_CPU1_SA_DQ<21>")
	)
	(segment
		(start 195.622926 -292.993826)
		(end 194.721226 -292.993826)
		(width 0.18288)
		(layer "In11.Cu")
		(net "M_H_CPU1_SA_DQ<21>")
	)
	(segment
		(start 165.435026 -292.996366)
		(end 164.70122 -292.996366)
		(width 0.18288)
		(layer "In11.Cu")
		(net "M_H_CPU1_SA_DQ<21>")
	)
	(segment
		(start 167.82034 -293.755826)
		(end 167.360346 -293.755826)
		(width 0.18288)
		(layer "In11.Cu")
		(net "M_H_CPU1_SA_DQ<21>")
	)
	(segment
		(start 190.209932 -293.60368)
		(end 190.016892 -293.79672)
		(width 0.18288)
		(layer "In11.Cu")
		(net "M_H_CPU1_SA_DQ<21>")
	)
	(segment
		(start 164.70122 -292.996366)
		(end 164.346128 -292.641274)
		(width 0.18288)
		(layer "In11.Cu")
		(net "M_H_CPU1_SA_DQ<21>")
	)
	(segment
		(start 186.15533 -293.41191)
		(end 185.96229 -293.21887)
		(width 0.18288)
		(layer "In11.Cu")
		(net "M_H_CPU1_SA_DQ<21>")
	)
	(segment
		(start 131.212082 -269.064232)
		(end 131.203192 -269.059152)
		(width 0.088646)
		(layer "In11.Cu")
		(net "M_H_CPU1_SA_DQ<21>")
	)
	(segment
		(start 185.06567 -293.41191)
		(end 184.639966 -293.41191)
		(width 0.18288)
		(layer "In11.Cu")
		(net "M_H_CPU1_SA_DQ<21>")
	)
	(segment
		(start 181.30774 -293.656512)
		(end 180.58638 -294.377872)
		(width 0.18288)
		(layer "In11.Cu")
		(net "M_H_CPU1_SA_DQ<21>")
	)
	(segment
		(start 193.072766 -294.642286)
		(end 191.700404 -294.642286)
		(width 0.18288)
		(layer "In11.Cu")
		(net "M_H_CPU1_SA_DQ<21>")
	)
	(segment
		(start 185.45175 -292.641274)
		(end 185.25871 -292.834314)
		(width 0.18288)
		(layer "In11.Cu")
		(net "M_H_CPU1_SA_DQ<21>")
	)
	(segment
		(start 163.220654 -292.641274)
		(end 163.027614 -292.448234)
		(width 0.18288)
		(layer "In11.Cu")
		(net "M_H_CPU1_SA_DQ<21>")
	)
	(segment
		(start 180.58638 -294.377872)
		(end 180.097176 -294.377872)
		(width 0.18288)
		(layer "In11.Cu")
		(net "M_H_CPU1_SA_DQ<21>")
	)
	(segment
		(start 171.769786 -295.285668)
		(end 171.081954 -295.285668)
		(width 0.18288)
		(layer "In11.Cu")
		(net "M_H_CPU1_SA_DQ<21>")
	)
	(segment
		(start 160.343342 -291.287962)
		(end 159.018986 -291.287962)
		(width 0.18288)
		(layer "In11.Cu")
		(net "M_H_CPU1_SA_DQ<21>")
	)
	(segment
		(start 167.360346 -293.755826)
		(end 166.273226 -292.668706)
		(width 0.18288)
		(layer "In11.Cu")
		(net "M_H_CPU1_SA_DQ<21>")
	)
	(segment
		(start 125.66015 -268.245336)
		(end 125.659642 -268.245844)
		(width 0.088646)
		(layer "In11.Cu")
		(net "M_H_CPU1_SA_DQ<21>")
	)
	(segment
		(start 138.423396 -271.672304)
		(end 138.251946 -271.500854)
		(width 0.088646)
		(layer "In11.Cu")
		(net "M_H_CPU1_SA_DQ<21>")
	)
	(segment
		(start 178.623468 -294.469566)
		(end 178.623468 -293.951914)
		(width 0.18288)
		(layer "In11.Cu")
		(net "M_H_CPU1_SA_DQ<21>")
	)
	(arc
		(start 130.35915 -268.245336)
		(mid 130.084951 -268.321171)
		(end 129.808478 -268.253972)
		(width 0.088646)
		(layer "In11.Cu")
		(net "M_H_CPU1_SA_DQ<21>")
	)
	(arc
		(start 135.05815 -271.500854)
		(mid 134.783951 -271.576689)
		(end 134.507478 -271.50949)
		(width 0.088646)
		(layer "In11.Cu")
		(net "M_H_CPU1_SA_DQ<21>")
	)
	(arc
		(start 137.312146 -271.500854)
		(mid 137.124948 -271.450711)
		(end 136.93775 -271.500854)
		(width 0.088646)
		(layer "In11.Cu")
		(net "M_H_CPU1_SA_DQ<21>")
	)
	(arc
		(start 129.41935 -268.245336)
		(mid 129.145151 -268.321171)
		(end 128.868678 -268.253972)
		(width 0.088646)
		(layer "In11.Cu")
		(net "M_H_CPU1_SA_DQ<21>")
	)
	(arc
		(start 126.974346 -268.245336)
		(mid 126.787148 -268.195193)
		(end 126.59995 -268.245336)
		(width 0.088646)
		(layer "In11.Cu")
		(net "M_H_CPU1_SA_DQ<21>")
	)
	(arc
		(start 136.372346 -271.500854)
		(mid 136.185148 -271.450711)
		(end 135.99795 -271.500854)
		(width 0.088646)
		(layer "In11.Cu")
		(net "M_H_CPU1_SA_DQ<21>")
	)
	(arc
		(start 126.59995 -268.245336)
		(mid 126.317392 -268.320985)
		(end 126.0348 -268.245336)
		(width 0.088646)
		(layer "In11.Cu")
		(net "M_H_CPU1_SA_DQ<21>")
	)
	(arc
		(start 135.432546 -271.500854)
		(mid 135.245348 -271.450711)
		(end 135.05815 -271.500854)
		(width 0.088646)
		(layer "In11.Cu")
		(net "M_H_CPU1_SA_DQ<21>")
	)
	(arc
		(start 131.390644 -269.38351)
		(mid 131.342965 -269.20061)
		(end 131.212082 -269.064232)
		(width 0.088646)
		(layer "In11.Cu")
		(net "M_H_CPU1_SA_DQ<21>")
	)
	(arc
		(start 131.673346 -269.873222)
		(mid 131.469865 -269.672418)
		(end 131.390644 -269.397734)
		(width 0.088646)
		(layer "In11.Cu")
		(net "M_H_CPU1_SA_DQ<21>")
	)
	(arc
		(start 137.87755 -271.500854)
		(mid 137.603351 -271.576689)
		(end 137.326878 -271.50949)
		(width 0.088646)
		(layer "In11.Cu")
		(net "M_H_CPU1_SA_DQ<21>")
	)
	(arc
		(start 125.187202 -269.060676)
		(mid 124.905813 -269.13587)
		(end 124.624846 -269.059152)
		(width 0.088646)
		(layer "In11.Cu")
		(net "M_H_CPU1_SA_DQ<21>")
	)
	(arc
		(start 138.251946 -271.500854)
		(mid 138.064748 -271.450711)
		(end 137.87755 -271.500854)
		(width 0.088646)
		(layer "In11.Cu")
		(net "M_H_CPU1_SA_DQ<21>")
	)
	(arc
		(start 131.203192 -269.059152)
		(mid 131.000369 -268.858921)
		(end 130.920998 -268.585188)
		(width 0.088646)
		(layer "In11.Cu")
		(net "M_H_CPU1_SA_DQ<21>")
	)
	(arc
		(start 133.54685 -271.497298)
		(mid 133.344263 -271.290947)
		(end 133.270244 -271.011396)
		(width 0.088646)
		(layer "In11.Cu")
		(net "M_H_CPU1_SA_DQ<21>")
	)
	(arc
		(start 132.613146 -269.873222)
		(mid 132.425948 -269.823079)
		(end 132.23875 -269.873222)
		(width 0.088646)
		(layer "In11.Cu")
		(net "M_H_CPU1_SA_DQ<21>")
	)
	(arc
		(start 127.914146 -268.245336)
		(mid 127.726948 -268.195193)
		(end 127.53975 -268.245336)
		(width 0.088646)
		(layer "In11.Cu")
		(net "M_H_CPU1_SA_DQ<21>")
	)
	(arc
		(start 126.034546 -268.245336)
		(mid 125.847348 -268.195193)
		(end 125.66015 -268.245336)
		(width 0.088646)
		(layer "In11.Cu")
		(net "M_H_CPU1_SA_DQ<21>")
	)
	(arc
		(start 132.23875 -269.873222)
		(mid 131.964521 -269.949147)
		(end 131.688078 -269.881858)
		(width 0.088646)
		(layer "In11.Cu")
		(net "M_H_CPU1_SA_DQ<21>")
	)
	(arc
		(start 136.93775 -271.500854)
		(mid 136.663551 -271.576689)
		(end 136.387078 -271.50949)
		(width 0.088646)
		(layer "In11.Cu")
		(net "M_H_CPU1_SA_DQ<21>")
	)
	(arc
		(start 132.800344 -270.188944)
		(mid 132.748074 -270.006579)
		(end 132.613146 -269.873222)
		(width 0.088646)
		(layer "In11.Cu")
		(net "M_H_CPU1_SA_DQ<21>")
	)
	(arc
		(start 133.270244 -271.011396)
		(mid 133.222565 -270.828496)
		(end 133.091682 -270.692118)
		(width 0.088646)
		(layer "In11.Cu")
		(net "M_H_CPU1_SA_DQ<21>")
	)
	(arc
		(start 133.082792 -270.687038)
		(mid 132.878457 -270.484433)
		(end 132.800344 -270.207486)
		(width 0.088646)
		(layer "In11.Cu")
		(net "M_H_CPU1_SA_DQ<21>")
	)
	(arc
		(start 134.11835 -271.500854)
		(mid 133.844151 -271.576689)
		(end 133.567678 -271.50949)
		(width 0.088646)
		(layer "In11.Cu")
		(net "M_H_CPU1_SA_DQ<21>")
	)
	(arc
		(start 125.472444 -268.569694)
		(mid 125.396774 -268.852258)
		(end 125.189996 -269.059152)
		(width 0.088646)
		(layer "In11.Cu")
		(net "M_H_CPU1_SA_DQ<21>")
	)
	(arc
		(start 130.920998 -268.569694)
		(mid 130.873319 -268.386794)
		(end 130.742436 -268.250416)
		(width 0.088646)
		(layer "In11.Cu")
		(net "M_H_CPU1_SA_DQ<21>")
	)
	(arc
		(start 134.492746 -271.500854)
		(mid 134.305548 -271.450711)
		(end 134.11835 -271.500854)
		(width 0.088646)
		(layer "In11.Cu")
		(net "M_H_CPU1_SA_DQ<21>")
	)
	(arc
		(start 128.853946 -268.245336)
		(mid 128.666748 -268.195193)
		(end 128.47955 -268.245336)
		(width 0.088646)
		(layer "In11.Cu")
		(net "M_H_CPU1_SA_DQ<21>")
	)
	(arc
		(start 128.47955 -268.245336)
		(mid 128.205351 -268.321171)
		(end 127.928878 -268.253972)
		(width 0.088646)
		(layer "In11.Cu")
		(net "M_H_CPU1_SA_DQ<21>")
	)
	(arc
		(start 124.61875 -269.055596)
		(mid 124.583309 -269.032751)
		(end 124.549662 -269.007336)
		(width 0.088646)
		(layer "In11.Cu")
		(net "M_H_CPU1_SA_DQ<21>")
	)
	(arc
		(start 130.733292 -268.245336)
		(mid 130.546238 -268.195286)
		(end 130.35915 -268.245336)
		(width 0.088646)
		(layer "In11.Cu")
		(net "M_H_CPU1_SA_DQ<21>")
	)
	(arc
		(start 127.53975 -268.245336)
		(mid 127.265551 -268.321171)
		(end 126.989078 -268.253972)
		(width 0.088646)
		(layer "In11.Cu")
		(net "M_H_CPU1_SA_DQ<21>")
	)
	(arc
		(start 129.793746 -268.245336)
		(mid 129.606548 -268.195193)
		(end 129.41935 -268.245336)
		(width 0.088646)
		(layer "In11.Cu")
		(net "M_H_CPU1_SA_DQ<21>")
	)
	(arc
		(start 135.99795 -271.500854)
		(mid 135.723751 -271.576689)
		(end 135.447278 -271.50949)
		(width 0.088646)
		(layer "In11.Cu")
		(net "M_H_CPU1_SA_DQ<21>")
	)
	(arc
		(start 125.659642 -268.245844)
		(mid 125.522661 -268.382694)
		(end 125.472444 -268.569694)
		(width 0.088646)
		(layer "In11.Cu")
		(net "M_H_CPU1_SA_DQ<21>")
	)
	(segment
		(start 205.596744 -291.666676)
		(end 204.076046 -291.666676)
		(width 0.20066)
		(layer "F.Cu")
		(net "M_H_CPU1_SA_DQ<20>")
	)
	(segment
		(start 206.971392 -291.241734)
		(end 206.626714 -291.241734)
		(width 0.20066)
		(layer "F.Cu")
		(net "M_H_CPU1_SA_DQ<20>")
	)
	(segment
		(start 204.076046 -291.666676)
		(end 202.971146 -291.666676)
		(width 0.20066)
		(layer "F.Cu")
		(net "M_H_CPU1_SA_DQ<20>")
	)
	(segment
		(start 209.180176 -291.241734)
		(end 207.018382 -291.241734)
		(width 0.1016)
		(layer "F.Cu")
		(net "M_H_CPU1_SA_DQ<20>")
	)
	(segment
		(start 123.497848 -269.383256)
		(end 123.497594 -269.38351)
		(width 0.20066)
		(layer "F.Cu")
		(net "M_H_CPU1_SA_DQ<20>")
	)
	(segment
		(start 205.84541 -291.915342)
		(end 205.596744 -291.666676)
		(width 0.20066)
		(layer "F.Cu")
		(net "M_H_CPU1_SA_DQ<20>")
	)
	(segment
		(start 210.028028 -291.66693)
		(end 209.596482 -291.235384)
		(width 0.20066)
		(layer "F.Cu")
		(net "M_H_CPU1_SA_DQ<20>")
	)
	(segment
		(start 209.596482 -291.235384)
		(end 209.186526 -291.235384)
		(width 0.20066)
		(layer "F.Cu")
		(net "M_H_CPU1_SA_DQ<20>")
	)
	(segment
		(start 211.619592 -291.66693)
		(end 210.028028 -291.66693)
		(width 0.20066)
		(layer "F.Cu")
		(net "M_H_CPU1_SA_DQ<20>")
	)
	(segment
		(start 206.508604 -291.359844)
		(end 206.508604 -291.727382)
		(width 0.20066)
		(layer "F.Cu")
		(net "M_H_CPU1_SA_DQ<20>")
	)
	(segment
		(start 211.619846 -291.666676)
		(end 211.619592 -291.66693)
		(width 0.20066)
		(layer "F.Cu")
		(net "M_H_CPU1_SA_DQ<20>")
	)
	(segment
		(start 123.497848 -268.84757)
		(end 123.497848 -269.383256)
		(width 0.20066)
		(layer "F.Cu")
		(net "M_H_CPU1_SA_DQ<20>")
	)
	(segment
		(start 207.018382 -291.241734)
		(end 206.971392 -291.241734)
		(width 0.101854)
		(layer "F.Cu")
		(net "M_H_CPU1_SA_DQ<20>")
	)
	(segment
		(start 209.186526 -291.235384)
		(end 209.180176 -291.241734)
		(width 0.1016)
		(layer "F.Cu")
		(net "M_H_CPU1_SA_DQ<20>")
	)
	(segment
		(start 206.320644 -291.915342)
		(end 205.84541 -291.915342)
		(width 0.20066)
		(layer "F.Cu")
		(net "M_H_CPU1_SA_DQ<20>")
	)
	(segment
		(start 206.508604 -291.727382)
		(end 206.320644 -291.915342)
		(width 0.20066)
		(layer "F.Cu")
		(net "M_H_CPU1_SA_DQ<20>")
	)
	(segment
		(start 206.626714 -291.241734)
		(end 206.508604 -291.359844)
		(width 0.20066)
		(layer "F.Cu")
		(net "M_H_CPU1_SA_DQ<20>")
	)
	(segment
		(start 175.123348 -296.181526)
		(end 174.515018 -296.181526)
		(width 0.18288)
		(layer "In11.Cu")
		(net "M_H_CPU1_SA_DQ<20>")
	)
	(segment
		(start 128.009396 -269.059152)
		(end 128.009142 -269.059152)
		(width 0.088646)
		(layer "In11.Cu")
		(net "M_H_CPU1_SA_DQ<20>")
	)
	(segment
		(start 185.290714 -295.585896)
		(end 185.097674 -295.392856)
		(width 0.18288)
		(layer "In11.Cu")
		(net "M_H_CPU1_SA_DQ<20>")
	)
	(segment
		(start 165.944042 -294.675814)
		(end 165.692074 -294.780462)
		(width 0.18288)
		(layer "In11.Cu")
		(net "M_H_CPU1_SA_DQ<20>")
	)
	(segment
		(start 188.212984 -295.492424)
		(end 187.59932 -295.492424)
		(width 0.18288)
		(layer "In11.Cu")
		(net "M_H_CPU1_SA_DQ<20>")
	)
	(segment
		(start 137.407396 -272.314924)
		(end 137.392664 -272.32356)
		(width 0.088646)
		(layer "In11.Cu")
		(net "M_H_CPU1_SA_DQ<20>")
	)
	(segment
		(start 164.771324 -294.648128)
		(end 163.77412 -294.648128)
		(width 0.18288)
		(layer "In11.Cu")
		(net "M_H_CPU1_SA_DQ<20>")
	)
	(segment
		(start 164.904674 -294.514778)
		(end 164.771324 -294.648128)
		(width 0.18288)
		(layer "In11.Cu")
		(net "M_H_CPU1_SA_DQ<20>")
	)
	(segment
		(start 155.225242 -289.686492)
		(end 155.225242 -289.16376)
		(width 0.18288)
		(layer "In11.Cu")
		(net "M_H_CPU1_SA_DQ<20>")
	)
	(segment
		(start 201.207116 -291.91585)
		(end 201.014076 -292.10889)
		(width 0.18288)
		(layer "In11.Cu")
		(net "M_H_CPU1_SA_DQ<20>")
	)
	(segment
		(start 157.449012 -291.909754)
		(end 157.188154 -291.649404)
		(width 0.18288)
		(layer "In11.Cu")
		(net "M_H_CPU1_SA_DQ<20>")
	)
	(segment
		(start 155.657804 -290.916614)
		(end 155.385008 -290.916614)
		(width 0.18288)
		(layer "In11.Cu")
		(net "M_H_CPU1_SA_DQ<20>")
	)
	(segment
		(start 125.189996 -269.707868)
		(end 125.175264 -269.699232)
		(width 0.088646)
		(layer "In11.Cu")
		(net "M_H_CPU1_SA_DQ<20>")
	)
	(segment
		(start 201.510646 -291.215826)
		(end 201.207116 -291.519356)
		(width 0.18288)
		(layer "In11.Cu")
		(net "M_H_CPU1_SA_DQ<20>")
	)
	(segment
		(start 177.331624 -296.342308)
		(end 176.105058 -296.342308)
		(width 0.18288)
		(layer "In11.Cu")
		(net "M_H_CPU1_SA_DQ<20>")
	)
	(segment
		(start 178.021742 -296.759376)
		(end 177.748692 -296.759376)
		(width 0.18288)
		(layer "In11.Cu")
		(net "M_H_CPU1_SA_DQ<20>")
	)
	(segment
		(start 131.212082 -270.692118)
		(end 131.203192 -270.687038)
		(width 0.088646)
		(layer "In11.Cu")
		(net "M_H_CPU1_SA_DQ<20>")
	)
	(segment
		(start 184.036462 -295.49979)
		(end 182.216552 -295.49979)
		(width 0.18288)
		(layer "In11.Cu")
		(net "M_H_CPU1_SA_DQ<20>")
	)
	(segment
		(start 166.557198 -294.531034)
		(end 166.26332 -294.409114)
		(width 0.18288)
		(layer "In11.Cu")
		(net "M_H_CPU1_SA_DQ<20>")
	)
	(segment
		(start 166.011606 -294.513254)
		(end 165.944042 -294.675814)
		(width 0.18288)
		(layer "In11.Cu")
		(net "M_H_CPU1_SA_DQ<20>")
	)
	(segment
		(start 168.52265 -295.316402)
		(end 168.331642 -295.50741)
		(width 0.18288)
		(layer "In11.Cu")
		(net "M_H_CPU1_SA_DQ<20>")
	)
	(segment
		(start 139.325604 -273.907504)
		(end 139.107672 -273.907504)
		(width 0.088646)
		(layer "In11.Cu")
		(net "M_H_CPU1_SA_DQ<20>")
	)
	(segment
		(start 162.873944 -293.747952)
		(end 160.989772 -293.747952)
		(width 0.18288)
		(layer "In11.Cu")
		(net "M_H_CPU1_SA_DQ<20>")
	)
	(segment
		(start 185.290714 -295.875456)
		(end 185.290714 -295.585896)
		(width 0.18288)
		(layer "In11.Cu")
		(net "M_H_CPU1_SA_DQ<20>")
	)
	(segment
		(start 179.834032 -296.152062)
		(end 179.635912 -296.350182)
		(width 0.18288)
		(layer "In11.Cu")
		(net "M_H_CPU1_SA_DQ<20>")
	)
	(segment
		(start 181.9656 -295.248838)
		(end 181.508908 -295.248838)
		(width 0.18288)
		(layer "In11.Cu")
		(net "M_H_CPU1_SA_DQ<20>")
	)
	(segment
		(start 130.742436 -269.878302)
		(end 130.733546 -269.873222)
		(width 0.088646)
		(layer "In11.Cu")
		(net "M_H_CPU1_SA_DQ<20>")
	)
	(segment
		(start 127.06985 -269.059152)
		(end 127.069342 -269.059152)
		(width 0.088646)
		(layer "In11.Cu")
		(net "M_H_CPU1_SA_DQ<20>")
	)
	(segment
		(start 123.743212 -269.678404)
		(end 123.654058 -269.654528)
		(width 0.088646)
		(layer "In11.Cu")
		(net "M_H_CPU1_SA_DQ<20>")
	)
	(segment
		(start 177.748692 -296.759376)
		(end 177.331624 -296.342308)
		(width 0.18288)
		(layer "In11.Cu")
		(net "M_H_CPU1_SA_DQ<20>")
	)
	(segment
		(start 185.097674 -295.392856)
		(end 184.143396 -295.392856)
		(width 0.18288)
		(layer "In11.Cu")
		(net "M_H_CPU1_SA_DQ<20>")
	)
	(segment
		(start 196.71538 -294.062404)
		(end 196.183758 -294.594026)
		(width 0.18288)
		(layer "In11.Cu")
		(net "M_H_CPU1_SA_DQ<20>")
	)
	(segment
		(start 191.61252 -296.342308)
		(end 191.41948 -296.535348)
		(width 0.18288)
		(layer "In11.Cu")
		(net "M_H_CPU1_SA_DQ<20>")
	)
	(segment
		(start 189.691264 -296.121582)
		(end 188.802518 -295.232836)
		(width 0.18288)
		(layer "In11.Cu")
		(net "M_H_CPU1_SA_DQ<20>")
	)
	(segment
		(start 155.160218 -290.691824)
		(end 155.160218 -290.419028)
		(width 0.18288)
		(layer "In11.Cu")
		(net "M_H_CPU1_SA_DQ<20>")
	)
	(segment
		(start 166.69893 -295.197276)
		(end 166.594282 -294.945308)
		(width 0.18288)
		(layer "In11.Cu")
		(net "M_H_CPU1_SA_DQ<20>")
	)
	(segment
		(start 156.15539 -291.686996)
		(end 156.15539 -291.4142)
		(width 0.18288)
		(layer "In11.Cu")
		(net "M_H_CPU1_SA_DQ<20>")
	)
	(segment
		(start 156.15539 -291.4142)
		(end 156.417772 -291.151818)
		(width 0.18288)
		(layer "In11.Cu")
		(net "M_H_CPU1_SA_DQ<20>")
	)
	(segment
		(start 139.968986 -273.907504)
		(end 139.325604 -273.907504)
		(width 0.18288)
		(layer "In11.Cu")
		(net "M_H_CPU1_SA_DQ<20>")
	)
	(segment
		(start 174.354998 -296.341546)
		(end 174.354998 -296.68343)
		(width 0.18288)
		(layer "In11.Cu")
		(net "M_H_CPU1_SA_DQ<20>")
	)
	(segment
		(start 190.383922 -296.342308)
		(end 190.163196 -296.121582)
		(width 0.18288)
		(layer "In11.Cu")
		(net "M_H_CPU1_SA_DQ<20>")
	)
	(segment
		(start 184.143396 -295.392856)
		(end 184.036462 -295.49979)
		(width 0.18288)
		(layer "In11.Cu")
		(net "M_H_CPU1_SA_DQ<20>")
	)
	(segment
		(start 179.635912 -296.350182)
		(end 178.430936 -296.350182)
		(width 0.18288)
		(layer "In11.Cu")
		(net "M_H_CPU1_SA_DQ<20>")
	)
	(segment
		(start 180.605684 -296.152062)
		(end 179.834032 -296.152062)
		(width 0.18288)
		(layer "In11.Cu")
		(net "M_H_CPU1_SA_DQ<20>")
	)
	(segment
		(start 156.38018 -291.911786)
		(end 156.15539 -291.686996)
		(width 0.18288)
		(layer "In11.Cu")
		(net "M_H_CPU1_SA_DQ<20>")
	)
	(segment
		(start 139.107672 -273.907504)
		(end 137.997438 -272.79727)
		(width 0.088646)
		(layer "In11.Cu")
		(net "M_H_CPU1_SA_DQ<20>")
	)
	(segment
		(start 130.272282 -269.064232)
		(end 130.263392 -269.059152)
		(width 0.088646)
		(layer "In11.Cu")
		(net "M_H_CPU1_SA_DQ<20>")
	)
	(segment
		(start 155.4226 -289.88385)
		(end 155.225242 -289.686492)
		(width 0.18288)
		(layer "In11.Cu")
		(net "M_H_CPU1_SA_DQ<20>")
	)
	(segment
		(start 191.41948 -296.535348)
		(end 191.41948 -296.759884)
		(width 0.18288)
		(layer "In11.Cu")
		(net "M_H_CPU1_SA_DQ<20>")
	)
	(segment
		(start 185.779156 -296.090594)
		(end 185.505852 -296.090594)
		(width 0.18288)
		(layer "In11.Cu")
		(net "M_H_CPU1_SA_DQ<20>")
	)
	(segment
		(start 178.430936 -296.350182)
		(end 178.021742 -296.759376)
		(width 0.18288)
		(layer "In11.Cu")
		(net "M_H_CPU1_SA_DQ<20>")
	)
	(segment
		(start 173.845982 -297.192446)
		(end 172.259244 -297.192446)
		(width 0.18288)
		(layer "In11.Cu")
		(net "M_H_CPU1_SA_DQ<20>")
	)
	(segment
		(start 194.425824 -295.372028)
		(end 194.070224 -295.372028)
		(width 0.18288)
		(layer "In11.Cu")
		(net "M_H_CPU1_SA_DQ<20>")
	)
	(segment
		(start 196.71538 -293.704772)
		(end 196.71538 -294.062404)
		(width 0.18288)
		(layer "In11.Cu")
		(net "M_H_CPU1_SA_DQ<20>")
	)
	(segment
		(start 188.472572 -295.232836)
		(end 188.212984 -295.492424)
		(width 0.18288)
		(layer "In11.Cu")
		(net "M_H_CPU1_SA_DQ<20>")
	)
	(segment
		(start 155.920186 -290.654232)
		(end 155.657804 -290.916614)
		(width 0.18288)
		(layer "In11.Cu")
		(net "M_H_CPU1_SA_DQ<20>")
	)
	(segment
		(start 130.450844 -269.397734)
		(end 130.450844 -269.38351)
		(width 0.088646)
		(layer "In11.Cu")
		(net "M_H_CPU1_SA_DQ<20>")
	)
	(segment
		(start 188.802518 -295.232836)
		(end 188.472572 -295.232836)
		(width 0.18288)
		(layer "In11.Cu")
		(net "M_H_CPU1_SA_DQ<20>")
	)
	(segment
		(start 155.160218 -290.419028)
		(end 155.4226 -290.156646)
		(width 0.18288)
		(layer "In11.Cu")
		(net "M_H_CPU1_SA_DQ<20>")
	)
	(segment
		(start 186.187334 -295.392856)
		(end 185.994294 -295.585896)
		(width 0.18288)
		(layer "In11.Cu")
		(net "M_H_CPU1_SA_DQ<20>")
	)
	(segment
		(start 201.014076 -292.10889)
		(end 200.504298 -292.10889)
		(width 0.18288)
		(layer "In11.Cu")
		(net "M_H_CPU1_SA_DQ<20>")
	)
	(segment
		(start 155.385008 -290.916614)
		(end 155.160218 -290.691824)
		(width 0.18288)
		(layer "In11.Cu")
		(net "M_H_CPU1_SA_DQ<20>")
	)
	(segment
		(start 163.77412 -294.648128)
		(end 162.873944 -293.747952)
		(width 0.18288)
		(layer "In11.Cu")
		(net "M_H_CPU1_SA_DQ<20>")
	)
	(segment
		(start 196.183758 -294.594026)
		(end 195.203826 -294.594026)
		(width 0.18288)
		(layer "In11.Cu")
		(net "M_H_CPU1_SA_DQ<20>")
	)
	(segment
		(start 190.90894 -296.952924)
		(end 190.7159 -296.759884)
		(width 0.18288)
		(layer "In11.Cu")
		(net "M_H_CPU1_SA_DQ<20>")
	)
	(segment
		(start 198.874126 -292.866826)
		(end 198.213726 -293.527226)
		(width 0.18288)
		(layer "In11.Cu")
		(net "M_H_CPU1_SA_DQ<20>")
	)
	(segment
		(start 198.213726 -293.527226)
		(end 196.892926 -293.527226)
		(width 0.18288)
		(layer "In11.Cu")
		(net "M_H_CPU1_SA_DQ<20>")
	)
	(segment
		(start 202.386692 -291.666676)
		(end 201.935842 -291.215826)
		(width 0.18288)
		(layer "In11.Cu")
		(net "M_H_CPU1_SA_DQ<20>")
	)
	(segment
		(start 128.389888 -269.062708)
		(end 128.383792 -269.059152)
		(width 0.088646)
		(layer "In11.Cu")
		(net "M_H_CPU1_SA_DQ<20>")
	)
	(segment
		(start 191.22644 -296.952924)
		(end 190.90894 -296.952924)
		(width 0.18288)
		(layer "In11.Cu")
		(net "M_H_CPU1_SA_DQ<20>")
	)
	(segment
		(start 199.746362 -292.866826)
		(end 198.874126 -292.866826)
		(width 0.18288)
		(layer "In11.Cu")
		(net "M_H_CPU1_SA_DQ<20>")
	)
	(segment
		(start 185.994294 -295.585896)
		(end 185.994294 -295.875456)
		(width 0.18288)
		(layer "In11.Cu")
		(net "M_H_CPU1_SA_DQ<20>")
	)
	(segment
		(start 185.505852 -296.090594)
		(end 185.290714 -295.875456)
		(width 0.18288)
		(layer "In11.Cu")
		(net "M_H_CPU1_SA_DQ<20>")
	)
	(segment
		(start 134.587996 -272.314924)
		(end 134.573264 -272.32356)
		(width 0.088646)
		(layer "In11.Cu")
		(net "M_H_CPU1_SA_DQ<20>")
	)
	(segment
		(start 191.41948 -296.759884)
		(end 191.22644 -296.952924)
		(width 0.18288)
		(layer "In11.Cu")
		(net "M_H_CPU1_SA_DQ<20>")
	)
	(segment
		(start 187.499752 -295.392856)
		(end 186.187334 -295.392856)
		(width 0.18288)
		(layer "In11.Cu")
		(net "M_H_CPU1_SA_DQ<20>")
	)
	(segment
		(start 187.59932 -295.492424)
		(end 187.499752 -295.392856)
		(width 0.18288)
		(layer "In11.Cu")
		(net "M_H_CPU1_SA_DQ<20>")
	)
	(segment
		(start 156.417772 -291.151818)
		(end 156.417772 -290.879022)
		(width 0.18288)
		(layer "In11.Cu")
		(net "M_H_CPU1_SA_DQ<20>")
	)
	(segment
		(start 171.07154 -296.924476)
		(end 169.463466 -295.316402)
		(width 0.18288)
		(layer "In11.Cu")
		(net "M_H_CPU1_SA_DQ<20>")
	)
	(segment
		(start 201.935842 -291.215826)
		(end 201.510646 -291.215826)
		(width 0.18288)
		(layer "In11.Cu")
		(net "M_H_CPU1_SA_DQ<20>")
	)
	(segment
		(start 169.463466 -295.316402)
		(end 168.52265 -295.316402)
		(width 0.18288)
		(layer "In11.Cu")
		(net "M_H_CPU1_SA_DQ<20>")
	)
	(segment
		(start 190.7159 -296.535348)
		(end 190.52286 -296.342308)
		(width 0.18288)
		(layer "In11.Cu")
		(net "M_H_CPU1_SA_DQ<20>")
	)
	(segment
		(start 171.991274 -296.924476)
		(end 171.07154 -296.924476)
		(width 0.18288)
		(layer "In11.Cu")
		(net "M_H_CPU1_SA_DQ<20>")
	)
	(segment
		(start 185.994294 -295.875456)
		(end 185.779156 -296.090594)
		(width 0.18288)
		(layer "In11.Cu")
		(net "M_H_CPU1_SA_DQ<20>")
	)
	(segment
		(start 202.971146 -291.666676)
		(end 202.386692 -291.666676)
		(width 0.18288)
		(layer "In11.Cu")
		(net "M_H_CPU1_SA_DQ<20>")
	)
	(segment
		(start 160.989772 -293.747952)
		(end 160.20161 -292.95979)
		(width 0.18288)
		(layer "In11.Cu")
		(net "M_H_CPU1_SA_DQ<20>")
	)
	(segment
		(start 166.26332 -294.409114)
		(end 166.011606 -294.513254)
		(width 0.18288)
		(layer "In11.Cu")
		(net "M_H_CPU1_SA_DQ<20>")
	)
	(segment
		(start 131.673346 -271.500854)
		(end 131.66725 -271.497298)
		(width 0.088646)
		(layer "In11.Cu")
		(net "M_H_CPU1_SA_DQ<20>")
	)
	(segment
		(start 125.922532 -269.218156)
		(end 125.781562 -269.35938)
		(width 0.088646)
		(layer "In11.Cu")
		(net "M_H_CPU1_SA_DQ<20>")
	)
	(segment
		(start 123.654058 -269.654528)
		(end 123.497594 -269.38351)
		(width 0.088646)
		(layer "In11.Cu")
		(net "M_H_CPU1_SA_DQ<20>")
	)
	(segment
		(start 190.7159 -296.759884)
		(end 190.7159 -296.535348)
		(width 0.18288)
		(layer "In11.Cu")
		(net "M_H_CPU1_SA_DQ<20>")
	)
	(segment
		(start 167.045386 -295.340786)
		(end 166.69893 -295.197276)
		(width 0.18288)
		(layer "In11.Cu")
		(net "M_H_CPU1_SA_DQ<20>")
	)
	(segment
		(start 130.920998 -270.213074)
		(end 130.920998 -270.19758)
		(width 0.088646)
		(layer "In11.Cu")
		(net "M_H_CPU1_SA_DQ<20>")
	)
	(segment
		(start 190.163196 -296.121582)
		(end 189.691264 -296.121582)
		(width 0.18288)
		(layer "In11.Cu")
		(net "M_H_CPU1_SA_DQ<20>")
	)
	(segment
		(start 156.652976 -291.911786)
		(end 156.38018 -291.911786)
		(width 0.18288)
		(layer "In11.Cu")
		(net "M_H_CPU1_SA_DQ<20>")
	)
	(segment
		(start 172.259244 -297.192446)
		(end 171.991274 -296.924476)
		(width 0.18288)
		(layer "In11.Cu")
		(net "M_H_CPU1_SA_DQ<20>")
	)
	(segment
		(start 133.648196 -272.314924)
		(end 133.633464 -272.32356)
		(width 0.088646)
		(layer "In11.Cu")
		(net "M_H_CPU1_SA_DQ<20>")
	)
	(segment
		(start 137.997438 -272.511266)
		(end 137.860024 -272.373852)
		(width 0.088646)
		(layer "In11.Cu")
		(net "M_H_CPU1_SA_DQ<20>")
	)
	(segment
		(start 159.075374 -292.95979)
		(end 158.025338 -291.909754)
		(width 0.18288)
		(layer "In11.Cu")
		(net "M_H_CPU1_SA_DQ<20>")
	)
	(segment
		(start 201.207116 -291.519356)
		(end 201.207116 -291.91585)
		(width 0.18288)
		(layer "In11.Cu")
		(net "M_H_CPU1_SA_DQ<20>")
	)
	(segment
		(start 165.051232 -294.514778)
		(end 164.904674 -294.514778)
		(width 0.18288)
		(layer "In11.Cu")
		(net "M_H_CPU1_SA_DQ<20>")
	)
	(segment
		(start 166.594282 -294.945308)
		(end 166.661592 -294.782748)
		(width 0.18288)
		(layer "In11.Cu")
		(net "M_H_CPU1_SA_DQ<20>")
	)
	(segment
		(start 135.527796 -272.314924)
		(end 135.513064 -272.32356)
		(width 0.088646)
		(layer "In11.Cu")
		(net "M_H_CPU1_SA_DQ<20>")
	)
	(segment
		(start 176.105058 -296.342308)
		(end 175.945038 -296.502328)
		(width 0.18288)
		(layer "In11.Cu")
		(net "M_H_CPU1_SA_DQ<20>")
	)
	(segment
		(start 156.192982 -290.654232)
		(end 155.920186 -290.654232)
		(width 0.18288)
		(layer "In11.Cu")
		(net "M_H_CPU1_SA_DQ<20>")
	)
	(segment
		(start 165.692074 -294.780462)
		(end 165.051232 -294.514778)
		(width 0.18288)
		(layer "In11.Cu")
		(net "M_H_CPU1_SA_DQ<20>")
	)
	(segment
		(start 132.15366 -272.32102)
		(end 132.143246 -272.314924)
		(width 0.088646)
		(layer "In11.Cu")
		(net "M_H_CPU1_SA_DQ<20>")
	)
	(segment
		(start 166.661592 -294.782748)
		(end 166.557198 -294.531034)
		(width 0.18288)
		(layer "In11.Cu")
		(net "M_H_CPU1_SA_DQ<20>")
	)
	(segment
		(start 193.099944 -296.342308)
		(end 191.61252 -296.342308)
		(width 0.18288)
		(layer "In11.Cu")
		(net "M_H_CPU1_SA_DQ<20>")
	)
	(segment
		(start 174.354998 -296.68343)
		(end 173.845982 -297.192446)
		(width 0.18288)
		(layer "In11.Cu")
		(net "M_H_CPU1_SA_DQ<20>")
	)
	(segment
		(start 175.44415 -296.502328)
		(end 175.123348 -296.181526)
		(width 0.18288)
		(layer "In11.Cu")
		(net "M_H_CPU1_SA_DQ<20>")
	)
	(segment
		(start 156.417772 -290.879022)
		(end 156.192982 -290.654232)
		(width 0.18288)
		(layer "In11.Cu")
		(net "M_H_CPU1_SA_DQ<20>")
	)
	(segment
		(start 156.915358 -291.649404)
		(end 156.652976 -291.911786)
		(width 0.18288)
		(layer "In11.Cu")
		(net "M_H_CPU1_SA_DQ<20>")
	)
	(segment
		(start 196.892926 -293.527226)
		(end 196.71538 -293.704772)
		(width 0.18288)
		(layer "In11.Cu")
		(net "M_H_CPU1_SA_DQ<20>")
	)
	(segment
		(start 182.216552 -295.49979)
		(end 181.9656 -295.248838)
		(width 0.18288)
		(layer "In11.Cu")
		(net "M_H_CPU1_SA_DQ<20>")
	)
	(segment
		(start 125.573282 -269.702788)
		(end 125.564392 -269.707868)
		(width 0.088646)
		(layer "In11.Cu")
		(net "M_H_CPU1_SA_DQ<20>")
	)
	(segment
		(start 124.250196 -269.707868)
		(end 124.235464 -269.699232)
		(width 0.088646)
		(layer "In11.Cu")
		(net "M_H_CPU1_SA_DQ<20>")
	)
	(segment
		(start 200.504298 -292.10889)
		(end 199.746362 -292.866826)
		(width 0.18288)
		(layer "In11.Cu")
		(net "M_H_CPU1_SA_DQ<20>")
	)
	(segment
		(start 168.331642 -295.50741)
		(end 167.21201 -295.50741)
		(width 0.18288)
		(layer "In11.Cu")
		(net "M_H_CPU1_SA_DQ<20>")
	)
	(segment
		(start 155.4226 -290.156646)
		(end 155.4226 -289.88385)
		(width 0.18288)
		(layer "In11.Cu")
		(net "M_H_CPU1_SA_DQ<20>")
	)
	(segment
		(start 128.94945 -269.059152)
		(end 128.949196 -269.059152)
		(width 0.088646)
		(layer "In11.Cu")
		(net "M_H_CPU1_SA_DQ<20>")
	)
	(segment
		(start 195.203826 -294.594026)
		(end 194.425824 -295.372028)
		(width 0.18288)
		(layer "In11.Cu")
		(net "M_H_CPU1_SA_DQ<20>")
	)
	(segment
		(start 158.025338 -291.909754)
		(end 157.449012 -291.909754)
		(width 0.18288)
		(layer "In11.Cu")
		(net "M_H_CPU1_SA_DQ<20>")
	)
	(segment
		(start 175.945038 -296.502328)
		(end 175.44415 -296.502328)
		(width 0.18288)
		(layer "In11.Cu")
		(net "M_H_CPU1_SA_DQ<20>")
	)
	(segment
		(start 137.997438 -272.79727)
		(end 137.997438 -272.511266)
		(width 0.088646)
		(layer "In11.Cu")
		(net "M_H_CPU1_SA_DQ<20>")
	)
	(segment
		(start 131.860544 -271.839436)
		(end 131.860544 -271.816576)
		(width 0.088646)
		(layer "In11.Cu")
		(net "M_H_CPU1_SA_DQ<20>")
	)
	(segment
		(start 190.52286 -296.342308)
		(end 190.383922 -296.342308)
		(width 0.18288)
		(layer "In11.Cu")
		(net "M_H_CPU1_SA_DQ<20>")
	)
	(segment
		(start 160.20161 -292.95979)
		(end 159.075374 -292.95979)
		(width 0.18288)
		(layer "In11.Cu")
		(net "M_H_CPU1_SA_DQ<20>")
	)
	(segment
		(start 129.888996 -269.059152)
		(end 129.874264 -269.067788)
		(width 0.088646)
		(layer "In11.Cu")
		(net "M_H_CPU1_SA_DQ<20>")
	)
	(segment
		(start 194.070224 -295.372028)
		(end 193.099944 -296.342308)
		(width 0.18288)
		(layer "In11.Cu")
		(net "M_H_CPU1_SA_DQ<20>")
	)
	(segment
		(start 167.21201 -295.50741)
		(end 167.045386 -295.340786)
		(width 0.18288)
		(layer "In11.Cu")
		(net "M_H_CPU1_SA_DQ<20>")
	)
	(segment
		(start 155.225242 -289.16376)
		(end 139.968986 -273.907504)
		(width 0.18288)
		(layer "In11.Cu")
		(net "M_H_CPU1_SA_DQ<20>")
	)
	(segment
		(start 136.467596 -272.314924)
		(end 136.452864 -272.32356)
		(width 0.088646)
		(layer "In11.Cu")
		(net "M_H_CPU1_SA_DQ<20>")
	)
	(segment
		(start 157.188154 -291.649404)
		(end 156.915358 -291.649404)
		(width 0.18288)
		(layer "In11.Cu")
		(net "M_H_CPU1_SA_DQ<20>")
	)
	(segment
		(start 174.515018 -296.181526)
		(end 174.354998 -296.341546)
		(width 0.18288)
		(layer "In11.Cu")
		(net "M_H_CPU1_SA_DQ<20>")
	)
	(segment
		(start 181.508908 -295.248838)
		(end 180.605684 -296.152062)
		(width 0.18288)
		(layer "In11.Cu")
		(net "M_H_CPU1_SA_DQ<20>")
	)
	(arc
		(start 125.564392 -269.707868)
		(mid 125.377194 -269.758011)
		(end 125.189996 -269.707868)
		(width 0.088646)
		(layer "In11.Cu")
		(net "M_H_CPU1_SA_DQ<20>")
	)
	(arc
		(start 129.323592 -269.059152)
		(mid 129.136538 -269.009102)
		(end 128.94945 -269.059152)
		(width 0.088646)
		(layer "In11.Cu")
		(net "M_H_CPU1_SA_DQ<20>")
	)
	(arc
		(start 132.143246 -272.314924)
		(mid 131.939765 -272.11412)
		(end 131.860544 -271.839436)
		(width 0.088646)
		(layer "In11.Cu")
		(net "M_H_CPU1_SA_DQ<20>")
	)
	(arc
		(start 134.022592 -272.314924)
		(mid 133.835394 -272.264781)
		(end 133.648196 -272.314924)
		(width 0.088646)
		(layer "In11.Cu")
		(net "M_H_CPU1_SA_DQ<20>")
	)
	(arc
		(start 128.949196 -269.059152)
		(mid 128.670022 -269.134917)
		(end 128.389888 -269.062708)
		(width 0.088646)
		(layer "In11.Cu")
		(net "M_H_CPU1_SA_DQ<20>")
	)
	(arc
		(start 135.902192 -272.314924)
		(mid 135.714994 -272.264781)
		(end 135.527796 -272.314924)
		(width 0.088646)
		(layer "In11.Cu")
		(net "M_H_CPU1_SA_DQ<20>")
	)
	(arc
		(start 137.781792 -272.314924)
		(mid 137.594594 -272.264781)
		(end 137.407396 -272.314924)
		(width 0.088646)
		(layer "In11.Cu")
		(net "M_H_CPU1_SA_DQ<20>")
	)
	(arc
		(start 131.390644 -271.011396)
		(mid 131.342965 -270.828496)
		(end 131.212082 -270.692118)
		(width 0.088646)
		(layer "In11.Cu")
		(net "M_H_CPU1_SA_DQ<20>")
	)
	(arc
		(start 126.504192 -269.059152)
		(mid 126.316994 -269.009009)
		(end 126.129796 -269.059152)
		(width 0.088646)
		(layer "In11.Cu")
		(net "M_H_CPU1_SA_DQ<20>")
	)
	(arc
		(start 131.203192 -270.687038)
		(mid 131.000369 -270.486807)
		(end 130.920998 -270.213074)
		(width 0.088646)
		(layer "In11.Cu")
		(net "M_H_CPU1_SA_DQ<20>")
	)
	(arc
		(start 132.708396 -272.314924)
		(mid 132.431837 -272.390633)
		(end 132.15366 -272.32102)
		(width 0.088646)
		(layer "In11.Cu")
		(net "M_H_CPU1_SA_DQ<20>")
	)
	(arc
		(start 134.962392 -272.314924)
		(mid 134.775194 -272.264781)
		(end 134.587996 -272.314924)
		(width 0.088646)
		(layer "In11.Cu")
		(net "M_H_CPU1_SA_DQ<20>")
	)
	(arc
		(start 130.450844 -269.38351)
		(mid 130.403165 -269.20061)
		(end 130.272282 -269.064232)
		(width 0.088646)
		(layer "In11.Cu")
		(net "M_H_CPU1_SA_DQ<20>")
	)
	(arc
		(start 129.874264 -269.067788)
		(mid 129.597789 -269.135108)
		(end 129.323592 -269.059152)
		(width 0.088646)
		(layer "In11.Cu")
		(net "M_H_CPU1_SA_DQ<20>")
	)
	(arc
		(start 131.66725 -271.497298)
		(mid 131.464663 -271.290947)
		(end 131.390644 -271.011396)
		(width 0.088646)
		(layer "In11.Cu")
		(net "M_H_CPU1_SA_DQ<20>")
	)
	(arc
		(start 125.68047 -269.60322)
		(mid 125.632633 -269.659202)
		(end 125.573282 -269.702788)
		(width 0.088646)
		(layer "In11.Cu")
		(net "M_H_CPU1_SA_DQ<20>")
	)
	(arc
		(start 136.452864 -272.32356)
		(mid 136.176423 -272.390726)
		(end 135.902192 -272.314924)
		(width 0.088646)
		(layer "In11.Cu")
		(net "M_H_CPU1_SA_DQ<20>")
	)
	(arc
		(start 125.175264 -269.699232)
		(mid 124.898823 -269.632066)
		(end 124.624592 -269.707868)
		(width 0.088646)
		(layer "In11.Cu")
		(net "M_H_CPU1_SA_DQ<20>")
	)
	(arc
		(start 131.860544 -271.816576)
		(mid 131.808274 -271.634211)
		(end 131.673346 -271.500854)
		(width 0.088646)
		(layer "In11.Cu")
		(net "M_H_CPU1_SA_DQ<20>")
	)
	(arc
		(start 127.069342 -269.059152)
		(mid 126.78675 -269.134928)
		(end 126.504192 -269.059152)
		(width 0.088646)
		(layer "In11.Cu")
		(net "M_H_CPU1_SA_DQ<20>")
	)
	(arc
		(start 134.573264 -272.32356)
		(mid 134.296823 -272.390726)
		(end 134.022592 -272.314924)
		(width 0.088646)
		(layer "In11.Cu")
		(net "M_H_CPU1_SA_DQ<20>")
	)
	(arc
		(start 130.263392 -269.059152)
		(mid 130.076194 -269.009009)
		(end 129.888996 -269.059152)
		(width 0.088646)
		(layer "In11.Cu")
		(net "M_H_CPU1_SA_DQ<20>")
	)
	(arc
		(start 128.383792 -269.059152)
		(mid 128.196594 -269.009009)
		(end 128.009396 -269.059152)
		(width 0.088646)
		(layer "In11.Cu")
		(net "M_H_CPU1_SA_DQ<20>")
	)
	(arc
		(start 125.749304 -269.425928)
		(mid 125.726338 -269.519022)
		(end 125.68047 -269.60322)
		(width 0.088646)
		(layer "In11.Cu")
		(net "M_H_CPU1_SA_DQ<20>")
	)
	(arc
		(start 125.781562 -269.35938)
		(mid 125.759797 -269.389922)
		(end 125.749304 -269.425928)
		(width 0.088646)
		(layer "In11.Cu")
		(net "M_H_CPU1_SA_DQ<20>")
	)
	(arc
		(start 127.443992 -269.059152)
		(mid 127.256938 -269.009102)
		(end 127.06985 -269.059152)
		(width 0.088646)
		(layer "In11.Cu")
		(net "M_H_CPU1_SA_DQ<20>")
	)
	(arc
		(start 130.733546 -269.873222)
		(mid 130.530065 -269.672418)
		(end 130.450844 -269.397734)
		(width 0.088646)
		(layer "In11.Cu")
		(net "M_H_CPU1_SA_DQ<20>")
	)
	(arc
		(start 137.860024 -272.373852)
		(mid 137.822833 -272.341834)
		(end 137.781792 -272.314924)
		(width 0.088646)
		(layer "In11.Cu")
		(net "M_H_CPU1_SA_DQ<20>")
	)
	(arc
		(start 124.624592 -269.707868)
		(mid 124.437394 -269.758011)
		(end 124.250196 -269.707868)
		(width 0.088646)
		(layer "In11.Cu")
		(net "M_H_CPU1_SA_DQ<20>")
	)
	(arc
		(start 135.513064 -272.32356)
		(mid 135.236623 -272.390726)
		(end 134.962392 -272.314924)
		(width 0.088646)
		(layer "In11.Cu")
		(net "M_H_CPU1_SA_DQ<20>")
	)
	(arc
		(start 133.082792 -272.314924)
		(mid 132.895594 -272.264781)
		(end 132.708396 -272.314924)
		(width 0.088646)
		(layer "In11.Cu")
		(net "M_H_CPU1_SA_DQ<20>")
	)
	(arc
		(start 128.009142 -269.059152)
		(mid 127.72655 -269.134928)
		(end 127.443992 -269.059152)
		(width 0.088646)
		(layer "In11.Cu")
		(net "M_H_CPU1_SA_DQ<20>")
	)
	(arc
		(start 133.633464 -272.32356)
		(mid 133.357023 -272.390726)
		(end 133.082792 -272.314924)
		(width 0.088646)
		(layer "In11.Cu")
		(net "M_H_CPU1_SA_DQ<20>")
	)
	(arc
		(start 126.129796 -269.059152)
		(mid 126.02094 -269.131846)
		(end 125.922532 -269.218156)
		(width 0.088646)
		(layer "In11.Cu")
		(net "M_H_CPU1_SA_DQ<20>")
	)
	(arc
		(start 130.920998 -270.19758)
		(mid 130.873319 -270.01468)
		(end 130.742436 -269.878302)
		(width 0.088646)
		(layer "In11.Cu")
		(net "M_H_CPU1_SA_DQ<20>")
	)
	(arc
		(start 137.392664 -272.32356)
		(mid 137.116223 -272.390726)
		(end 136.841992 -272.314924)
		(width 0.088646)
		(layer "In11.Cu")
		(net "M_H_CPU1_SA_DQ<20>")
	)
	(arc
		(start 124.235464 -269.699232)
		(mid 123.99172 -269.632383)
		(end 123.743212 -269.678404)
		(width 0.088646)
		(layer "In11.Cu")
		(net "M_H_CPU1_SA_DQ<20>")
	)
	(arc
		(start 136.841992 -272.314924)
		(mid 136.654794 -272.264781)
		(end 136.467596 -272.314924)
		(width 0.088646)
		(layer "In11.Cu")
		(net "M_H_CPU1_SA_DQ<20>")
	)
	(segment
		(start 205.596744 -314.616592)
		(end 204.076046 -314.616592)
		(width 0.20066)
		(layer "F.Cu")
		(net "M_H_CPU1_SA_DQ<1>")
	)
	(segment
		(start 206.991458 -314.19165)
		(end 206.971392 -314.19165)
		(width 0.101854)
		(layer "F.Cu")
		(net "M_H_CPU1_SA_DQ<1>")
	)
	(segment
		(start 129.606294 -278.336248)
		(end 129.606548 -278.336502)
		(width 0.20066)
		(layer "F.Cu")
		(net "M_H_CPU1_SA_DQ<1>")
	)
	(segment
		(start 129.606294 -277.800562)
		(end 129.606294 -278.336248)
		(width 0.20066)
		(layer "F.Cu")
		(net "M_H_CPU1_SA_DQ<1>")
	)
	(segment
		(start 206.626714 -314.19165)
		(end 206.508604 -314.30976)
		(width 0.20066)
		(layer "F.Cu")
		(net "M_H_CPU1_SA_DQ<1>")
	)
	(segment
		(start 205.84541 -314.865258)
		(end 205.596744 -314.616592)
		(width 0.20066)
		(layer "F.Cu")
		(net "M_H_CPU1_SA_DQ<1>")
	)
	(segment
		(start 209.180176 -314.19165)
		(end 206.991458 -314.19165)
		(width 0.1016)
		(layer "F.Cu")
		(net "M_H_CPU1_SA_DQ<1>")
	)
	(segment
		(start 210.028028 -314.616846)
		(end 209.596482 -314.1853)
		(width 0.20066)
		(layer "F.Cu")
		(net "M_H_CPU1_SA_DQ<1>")
	)
	(segment
		(start 204.076046 -314.616592)
		(end 202.971146 -314.616592)
		(width 0.20066)
		(layer "F.Cu")
		(net "M_H_CPU1_SA_DQ<1>")
	)
	(segment
		(start 206.508604 -314.30976)
		(end 206.508604 -314.677298)
		(width 0.20066)
		(layer "F.Cu")
		(net "M_H_CPU1_SA_DQ<1>")
	)
	(segment
		(start 211.619846 -314.616592)
		(end 211.619592 -314.616846)
		(width 0.20066)
		(layer "F.Cu")
		(net "M_H_CPU1_SA_DQ<1>")
	)
	(segment
		(start 209.186526 -314.1853)
		(end 209.180176 -314.19165)
		(width 0.1016)
		(layer "F.Cu")
		(net "M_H_CPU1_SA_DQ<1>")
	)
	(segment
		(start 209.596482 -314.1853)
		(end 209.186526 -314.1853)
		(width 0.20066)
		(layer "F.Cu")
		(net "M_H_CPU1_SA_DQ<1>")
	)
	(segment
		(start 206.320644 -314.865258)
		(end 205.84541 -314.865258)
		(width 0.20066)
		(layer "F.Cu")
		(net "M_H_CPU1_SA_DQ<1>")
	)
	(segment
		(start 211.619592 -314.616846)
		(end 210.028028 -314.616846)
		(width 0.20066)
		(layer "F.Cu")
		(net "M_H_CPU1_SA_DQ<1>")
	)
	(segment
		(start 206.971392 -314.19165)
		(end 206.626714 -314.19165)
		(width 0.20066)
		(layer "F.Cu")
		(net "M_H_CPU1_SA_DQ<1>")
	)
	(segment
		(start 206.508604 -314.677298)
		(end 206.320644 -314.865258)
		(width 0.20066)
		(layer "F.Cu")
		(net "M_H_CPU1_SA_DQ<1>")
	)
	(segment
		(start 162.631628 -307.26126)
		(end 162.113214 -307.779674)
		(width 0.18288)
		(layer "In6.Cu")
		(net "M_H_CPU1_SA_DQ<1>")
	)
	(segment
		(start 165.69182 -309.125112)
		(end 165.946582 -308.87035)
		(width 0.18288)
		(layer "In6.Cu")
		(net "M_H_CPU1_SA_DQ<1>")
	)
	(segment
		(start 155.21051 -305.504088)
		(end 155.21051 -301.301912)
		(width 0.18288)
		(layer "In6.Cu")
		(net "M_H_CPU1_SA_DQ<1>")
	)
	(segment
		(start 169.186098 -310.792622)
		(end 168.806622 -310.792622)
		(width 0.18288)
		(layer "In6.Cu")
		(net "M_H_CPU1_SA_DQ<1>")
	)
	(segment
		(start 163.122102 -307.751734)
		(end 163.122102 -307.525674)
		(width 0.18288)
		(layer "In6.Cu")
		(net "M_H_CPU1_SA_DQ<1>")
	)
	(segment
		(start 170.841162 -311.060846)
		(end 170.572938 -310.792622)
		(width 0.18288)
		(layer "In6.Cu")
		(net "M_H_CPU1_SA_DQ<1>")
	)
	(segment
		(start 158.171642 -307.393594)
		(end 157.100016 -307.393594)
		(width 0.18288)
		(layer "In6.Cu")
		(net "M_H_CPU1_SA_DQ<1>")
	)
	(segment
		(start 137.87755 -280.288492)
		(end 137.868406 -280.283412)
		(width 0.088646)
		(layer "In6.Cu")
		(net "M_H_CPU1_SA_DQ<1>")
	)
	(segment
		(start 186.46648 -315.275214)
		(end 184.784492 -313.593226)
		(width 0.18288)
		(layer "In6.Cu")
		(net "M_H_CPU1_SA_DQ<1>")
	)
	(segment
		(start 162.603688 -308.496208)
		(end 162.603688 -308.270148)
		(width 0.18288)
		(layer "In6.Cu")
		(net "M_H_CPU1_SA_DQ<1>")
	)
	(segment
		(start 197.234048 -314.298838)
		(end 197.0659 -314.13069)
		(width 0.18288)
		(layer "In6.Cu")
		(net "M_H_CPU1_SA_DQ<1>")
	)
	(segment
		(start 174.14113 -310.792622)
		(end 171.534582 -310.792622)
		(width 0.18288)
		(layer "In6.Cu")
		(net "M_H_CPU1_SA_DQ<1>")
	)
	(segment
		(start 163.122102 -307.525674)
		(end 162.857688 -307.26126)
		(width 0.18288)
		(layer "In6.Cu")
		(net "M_H_CPU1_SA_DQ<1>")
	)
	(segment
		(start 130.743706 -278.654764)
		(end 130.733292 -278.66086)
		(width 0.088646)
		(layer "In6.Cu")
		(net "M_H_CPU1_SA_DQ<1>")
	)
	(segment
		(start 166.437056 -309.360824)
		(end 166.182294 -309.615586)
		(width 0.18288)
		(layer "In6.Cu")
		(net "M_H_CPU1_SA_DQ<1>")
	)
	(segment
		(start 182.059326 -312.83783)
		(end 180.972968 -311.751472)
		(width 0.18288)
		(layer "In6.Cu")
		(net "M_H_CPU1_SA_DQ<1>")
	)
	(segment
		(start 189.285626 -314.411614)
		(end 188.65469 -315.04255)
		(width 0.18288)
		(layer "In6.Cu")
		(net "M_H_CPU1_SA_DQ<1>")
	)
	(segment
		(start 167.364918 -310.062626)
		(end 166.663116 -309.360824)
		(width 0.18288)
		(layer "In6.Cu")
		(net "M_H_CPU1_SA_DQ<1>")
	)
	(segment
		(start 179.742338 -311.751472)
		(end 177.93081 -309.939944)
		(width 0.18288)
		(layer "In6.Cu")
		(net "M_H_CPU1_SA_DQ<1>")
	)
	(segment
		(start 188.65469 -315.04255)
		(end 187.23229 -315.04255)
		(width 0.18288)
		(layer "In6.Cu")
		(net "M_H_CPU1_SA_DQ<1>")
	)
	(segment
		(start 165.946582 -308.64429)
		(end 165.866318 -308.564026)
		(width 0.18288)
		(layer "In6.Cu")
		(net "M_H_CPU1_SA_DQ<1>")
	)
	(segment
		(start 187.23229 -315.04255)
		(end 186.999626 -315.275214)
		(width 0.18288)
		(layer "In6.Cu")
		(net "M_H_CPU1_SA_DQ<1>")
	)
	(segment
		(start 200.945242 -312.80862)
		(end 200.617582 -312.80862)
		(width 0.18288)
		(layer "In6.Cu")
		(net "M_H_CPU1_SA_DQ<1>")
	)
	(segment
		(start 200.251822 -313.643264)
		(end 198.722488 -313.643264)
		(width 0.18288)
		(layer "In6.Cu")
		(net "M_H_CPU1_SA_DQ<1>")
	)
	(segment
		(start 133.56336 -278.654764)
		(end 133.552946 -278.66086)
		(width 0.088646)
		(layer "In6.Cu")
		(net "M_H_CPU1_SA_DQ<1>")
	)
	(segment
		(start 193.778378 -313.630818)
		(end 193.218308 -314.190888)
		(width 0.18288)
		(layer "In6.Cu")
		(net "M_H_CPU1_SA_DQ<1>")
	)
	(segment
		(start 190.725552 -314.190888)
		(end 190.504826 -314.411614)
		(width 0.18288)
		(layer "In6.Cu")
		(net "M_H_CPU1_SA_DQ<1>")
	)
	(segment
		(start 162.603688 -308.270148)
		(end 163.122102 -307.751734)
		(width 0.18288)
		(layer "In6.Cu")
		(net "M_H_CPU1_SA_DQ<1>")
	)
	(segment
		(start 186.999626 -315.275214)
		(end 186.46648 -315.275214)
		(width 0.18288)
		(layer "In6.Cu")
		(net "M_H_CPU1_SA_DQ<1>")
	)
	(segment
		(start 157.100016 -307.393594)
		(end 155.21051 -305.504088)
		(width 0.18288)
		(layer "In6.Cu")
		(net "M_H_CPU1_SA_DQ<1>")
	)
	(segment
		(start 140.367258 -281.63266)
		(end 140.063982 -281.63266)
		(width 0.088646)
		(layer "In6.Cu")
		(net "M_H_CPU1_SA_DQ<1>")
	)
	(segment
		(start 165.946582 -308.87035)
		(end 165.946582 -308.64429)
		(width 0.18288)
		(layer "In6.Cu")
		(net "M_H_CPU1_SA_DQ<1>")
	)
	(segment
		(start 201.997818 -313.643264)
		(end 201.311002 -313.643264)
		(width 0.18288)
		(layer "In6.Cu")
		(net "M_H_CPU1_SA_DQ<1>")
	)
	(segment
		(start 202.971146 -314.616592)
		(end 201.997818 -313.643264)
		(width 0.18288)
		(layer "In6.Cu")
		(net "M_H_CPU1_SA_DQ<1>")
	)
	(segment
		(start 130.267456 -278.607266)
		(end 129.977388 -278.437086)
		(width 0.088646)
		(layer "In6.Cu")
		(net "M_H_CPU1_SA_DQ<1>")
	)
	(segment
		(start 140.063982 -281.63266)
		(end 139.94384 -281.512518)
		(width 0.088646)
		(layer "In6.Cu")
		(net "M_H_CPU1_SA_DQ<1>")
	)
	(segment
		(start 184.022492 -313.593226)
		(end 183.267096 -312.83783)
		(width 0.18288)
		(layer "In6.Cu")
		(net "M_H_CPU1_SA_DQ<1>")
	)
	(segment
		(start 195.146168 -314.294774)
		(end 194.482212 -313.630818)
		(width 0.18288)
		(layer "In6.Cu")
		(net "M_H_CPU1_SA_DQ<1>")
	)
	(segment
		(start 184.784492 -313.593226)
		(end 184.022492 -313.593226)
		(width 0.18288)
		(layer "In6.Cu")
		(net "M_H_CPU1_SA_DQ<1>")
	)
	(segment
		(start 147.356322 -283.891228)
		(end 145.097754 -281.63266)
		(width 0.18288)
		(layer "In6.Cu")
		(net "M_H_CPU1_SA_DQ<1>")
	)
	(segment
		(start 196.497956 -313.398662)
		(end 196.30009 -313.596528)
		(width 0.18288)
		(layer "In6.Cu")
		(net "M_H_CPU1_SA_DQ<1>")
	)
	(segment
		(start 183.267096 -312.83783)
		(end 182.059326 -312.83783)
		(width 0.18288)
		(layer "In6.Cu")
		(net "M_H_CPU1_SA_DQ<1>")
	)
	(segment
		(start 162.113214 -307.779674)
		(end 161.887154 -307.779674)
		(width 0.18288)
		(layer "In6.Cu")
		(net "M_H_CPU1_SA_DQ<1>")
	)
	(segment
		(start 163.934394 -309.199026)
		(end 163.38804 -308.652672)
		(width 0.18288)
		(layer "In6.Cu")
		(net "M_H_CPU1_SA_DQ<1>")
	)
	(segment
		(start 198.722488 -313.643264)
		(end 198.066914 -314.298838)
		(width 0.18288)
		(layer "In6.Cu")
		(net "M_H_CPU1_SA_DQ<1>")
	)
	(segment
		(start 194.482212 -313.630818)
		(end 193.778378 -313.630818)
		(width 0.18288)
		(layer "In6.Cu")
		(net "M_H_CPU1_SA_DQ<1>")
	)
	(segment
		(start 180.972968 -311.751472)
		(end 179.742338 -311.751472)
		(width 0.18288)
		(layer "In6.Cu")
		(net "M_H_CPU1_SA_DQ<1>")
	)
	(segment
		(start 162.760152 -308.652672)
		(end 162.603688 -308.496208)
		(width 0.18288)
		(layer "In6.Cu")
		(net "M_H_CPU1_SA_DQ<1>")
	)
	(segment
		(start 160.034224 -307.368702)
		(end 159.660844 -307.368702)
		(width 0.18288)
		(layer "In6.Cu")
		(net "M_H_CPU1_SA_DQ<1>")
	)
	(segment
		(start 196.30009 -314.134754)
		(end 196.14007 -314.294774)
		(width 0.18288)
		(layer "In6.Cu")
		(net "M_H_CPU1_SA_DQ<1>")
	)
	(segment
		(start 137.689844 -279.964134)
		(end 137.689844 -279.954228)
		(width 0.088646)
		(layer "In6.Cu")
		(net "M_H_CPU1_SA_DQ<1>")
	)
	(segment
		(start 164.443918 -309.199026)
		(end 163.934394 -309.199026)
		(width 0.18288)
		(layer "In6.Cu")
		(net "M_H_CPU1_SA_DQ<1>")
	)
	(segment
		(start 137.407396 -279.474676)
		(end 137.398506 -279.469596)
		(width 0.088646)
		(layer "In6.Cu")
		(net "M_H_CPU1_SA_DQ<1>")
	)
	(segment
		(start 161.887154 -307.779674)
		(end 160.828736 -306.721256)
		(width 0.18288)
		(layer "In6.Cu")
		(net "M_H_CPU1_SA_DQ<1>")
	)
	(segment
		(start 201.128122 -312.9915)
		(end 200.945242 -312.80862)
		(width 0.18288)
		(layer "In6.Cu")
		(net "M_H_CPU1_SA_DQ<1>")
	)
	(segment
		(start 155.21051 -301.301912)
		(end 147.356322 -293.447724)
		(width 0.18288)
		(layer "In6.Cu")
		(net "M_H_CPU1_SA_DQ<1>")
	)
	(segment
		(start 139.94384 -281.512518)
		(end 139.584684 -280.645616)
		(width 0.088646)
		(layer "In6.Cu")
		(net "M_H_CPU1_SA_DQ<1>")
	)
	(segment
		(start 165.866318 -308.564026)
		(end 165.078918 -308.564026)
		(width 0.18288)
		(layer "In6.Cu")
		(net "M_H_CPU1_SA_DQ<1>")
	)
	(segment
		(start 166.182294 -309.615586)
		(end 165.956234 -309.615586)
		(width 0.18288)
		(layer "In6.Cu")
		(net "M_H_CPU1_SA_DQ<1>")
	)
	(segment
		(start 200.617582 -312.80862)
		(end 200.434702 -312.9915)
		(width 0.18288)
		(layer "In6.Cu")
		(net "M_H_CPU1_SA_DQ<1>")
	)
	(segment
		(start 197.0659 -313.618626)
		(end 196.845936 -313.398662)
		(width 0.18288)
		(layer "In6.Cu")
		(net "M_H_CPU1_SA_DQ<1>")
	)
	(segment
		(start 145.097754 -281.63266)
		(end 140.367258 -281.63266)
		(width 0.18288)
		(layer "In6.Cu")
		(net "M_H_CPU1_SA_DQ<1>")
	)
	(segment
		(start 193.218308 -314.190888)
		(end 190.725552 -314.190888)
		(width 0.18288)
		(layer "In6.Cu")
		(net "M_H_CPU1_SA_DQ<1>")
	)
	(segment
		(start 169.454322 -311.060846)
		(end 169.186098 -310.792622)
		(width 0.18288)
		(layer "In6.Cu")
		(net "M_H_CPU1_SA_DQ<1>")
	)
	(segment
		(start 159.660844 -307.368702)
		(end 159.500824 -307.208682)
		(width 0.18288)
		(layer "In6.Cu")
		(net "M_H_CPU1_SA_DQ<1>")
	)
	(segment
		(start 196.14007 -314.294774)
		(end 195.146168 -314.294774)
		(width 0.18288)
		(layer "In6.Cu")
		(net "M_H_CPU1_SA_DQ<1>")
	)
	(segment
		(start 190.504826 -314.411614)
		(end 189.285626 -314.411614)
		(width 0.18288)
		(layer "In6.Cu")
		(net "M_H_CPU1_SA_DQ<1>")
	)
	(segment
		(start 168.806622 -310.792622)
		(end 168.076626 -310.062626)
		(width 0.18288)
		(layer "In6.Cu")
		(net "M_H_CPU1_SA_DQ<1>")
	)
	(segment
		(start 138.26236 -280.282396)
		(end 138.251946 -280.288492)
		(width 0.088646)
		(layer "In6.Cu")
		(net "M_H_CPU1_SA_DQ<1>")
	)
	(segment
		(start 169.879518 -311.060846)
		(end 169.454322 -311.060846)
		(width 0.18288)
		(layer "In6.Cu")
		(net "M_H_CPU1_SA_DQ<1>")
	)
	(segment
		(start 159.500824 -307.208682)
		(end 159.500824 -306.881276)
		(width 0.18288)
		(layer "In6.Cu")
		(net "M_H_CPU1_SA_DQ<1>")
	)
	(segment
		(start 197.0659 -314.13069)
		(end 197.0659 -313.618626)
		(width 0.18288)
		(layer "In6.Cu")
		(net "M_H_CPU1_SA_DQ<1>")
	)
	(segment
		(start 198.066914 -314.298838)
		(end 197.234048 -314.298838)
		(width 0.18288)
		(layer "In6.Cu")
		(net "M_H_CPU1_SA_DQ<1>")
	)
	(segment
		(start 159.500824 -306.881276)
		(end 159.340804 -306.721256)
		(width 0.18288)
		(layer "In6.Cu")
		(net "M_H_CPU1_SA_DQ<1>")
	)
	(segment
		(start 139.324334 -280.385266)
		(end 139.175744 -280.385266)
		(width 0.088646)
		(layer "In6.Cu")
		(net "M_H_CPU1_SA_DQ<1>")
	)
	(segment
		(start 171.266358 -311.060846)
		(end 170.841162 -311.060846)
		(width 0.18288)
		(layer "In6.Cu")
		(net "M_H_CPU1_SA_DQ<1>")
	)
	(segment
		(start 201.128122 -313.460384)
		(end 201.128122 -312.9915)
		(width 0.18288)
		(layer "In6.Cu")
		(net "M_H_CPU1_SA_DQ<1>")
	)
	(segment
		(start 177.93081 -309.939944)
		(end 174.993808 -309.939944)
		(width 0.18288)
		(layer "In6.Cu")
		(net "M_H_CPU1_SA_DQ<1>")
	)
	(segment
		(start 160.194244 -306.881276)
		(end 160.194244 -307.208682)
		(width 0.18288)
		(layer "In6.Cu")
		(net "M_H_CPU1_SA_DQ<1>")
	)
	(segment
		(start 162.857688 -307.26126)
		(end 162.631628 -307.26126)
		(width 0.18288)
		(layer "In6.Cu")
		(net "M_H_CPU1_SA_DQ<1>")
	)
	(segment
		(start 200.434702 -312.9915)
		(end 200.434702 -313.460384)
		(width 0.18288)
		(layer "In6.Cu")
		(net "M_H_CPU1_SA_DQ<1>")
	)
	(segment
		(start 171.534582 -310.792622)
		(end 171.266358 -311.060846)
		(width 0.18288)
		(layer "In6.Cu")
		(net "M_H_CPU1_SA_DQ<1>")
	)
	(segment
		(start 165.078918 -308.564026)
		(end 164.443918 -309.199026)
		(width 0.18288)
		(layer "In6.Cu")
		(net "M_H_CPU1_SA_DQ<1>")
	)
	(segment
		(start 158.84398 -306.721256)
		(end 158.171642 -307.393594)
		(width 0.18288)
		(layer "In6.Cu")
		(net "M_H_CPU1_SA_DQ<1>")
	)
	(segment
		(start 130.358896 -278.66086)
		(end 130.267456 -278.607266)
		(width 0.088646)
		(layer "In6.Cu")
		(net "M_H_CPU1_SA_DQ<1>")
	)
	(segment
		(start 139.584684 -280.645616)
		(end 139.324334 -280.385266)
		(width 0.088646)
		(layer "In6.Cu")
		(net "M_H_CPU1_SA_DQ<1>")
	)
	(segment
		(start 196.30009 -313.596528)
		(end 196.30009 -314.134754)
		(width 0.18288)
		(layer "In6.Cu")
		(net "M_H_CPU1_SA_DQ<1>")
	)
	(segment
		(start 200.434702 -313.460384)
		(end 200.251822 -313.643264)
		(width 0.18288)
		(layer "In6.Cu")
		(net "M_H_CPU1_SA_DQ<1>")
	)
	(segment
		(start 170.147742 -310.792622)
		(end 169.879518 -311.060846)
		(width 0.18288)
		(layer "In6.Cu")
		(net "M_H_CPU1_SA_DQ<1>")
	)
	(segment
		(start 201.311002 -313.643264)
		(end 201.128122 -313.460384)
		(width 0.18288)
		(layer "In6.Cu")
		(net "M_H_CPU1_SA_DQ<1>")
	)
	(segment
		(start 160.194244 -307.208682)
		(end 160.034224 -307.368702)
		(width 0.18288)
		(layer "In6.Cu")
		(net "M_H_CPU1_SA_DQ<1>")
	)
	(segment
		(start 168.076626 -310.062626)
		(end 167.364918 -310.062626)
		(width 0.18288)
		(layer "In6.Cu")
		(net "M_H_CPU1_SA_DQ<1>")
	)
	(segment
		(start 170.572938 -310.792622)
		(end 170.147742 -310.792622)
		(width 0.18288)
		(layer "In6.Cu")
		(net "M_H_CPU1_SA_DQ<1>")
	)
	(segment
		(start 196.845936 -313.398662)
		(end 196.497956 -313.398662)
		(width 0.18288)
		(layer "In6.Cu")
		(net "M_H_CPU1_SA_DQ<1>")
	)
	(segment
		(start 165.956234 -309.615586)
		(end 165.69182 -309.351172)
		(width 0.18288)
		(layer "In6.Cu")
		(net "M_H_CPU1_SA_DQ<1>")
	)
	(segment
		(start 174.993808 -309.939944)
		(end 174.14113 -310.792622)
		(width 0.18288)
		(layer "In6.Cu")
		(net "M_H_CPU1_SA_DQ<1>")
	)
	(segment
		(start 165.69182 -309.351172)
		(end 165.69182 -309.125112)
		(width 0.18288)
		(layer "In6.Cu")
		(net "M_H_CPU1_SA_DQ<1>")
	)
	(segment
		(start 147.356322 -293.447724)
		(end 147.356322 -283.891228)
		(width 0.18288)
		(layer "In6.Cu")
		(net "M_H_CPU1_SA_DQ<1>")
	)
	(segment
		(start 137.219944 -279.150318)
		(end 137.219944 -279.140412)
		(width 0.088646)
		(layer "In6.Cu")
		(net "M_H_CPU1_SA_DQ<1>")
	)
	(segment
		(start 166.663116 -309.360824)
		(end 166.437056 -309.360824)
		(width 0.18288)
		(layer "In6.Cu")
		(net "M_H_CPU1_SA_DQ<1>")
	)
	(segment
		(start 159.340804 -306.721256)
		(end 158.84398 -306.721256)
		(width 0.18288)
		(layer "In6.Cu")
		(net "M_H_CPU1_SA_DQ<1>")
	)
	(segment
		(start 160.354264 -306.721256)
		(end 160.194244 -306.881276)
		(width 0.18288)
		(layer "In6.Cu")
		(net "M_H_CPU1_SA_DQ<1>")
	)
	(segment
		(start 163.38804 -308.652672)
		(end 162.760152 -308.652672)
		(width 0.18288)
		(layer "In6.Cu")
		(net "M_H_CPU1_SA_DQ<1>")
	)
	(segment
		(start 160.828736 -306.721256)
		(end 160.354264 -306.721256)
		(width 0.18288)
		(layer "In6.Cu")
		(net "M_H_CPU1_SA_DQ<1>")
	)
	(arc
		(start 137.398506 -279.469596)
		(mid 137.267592 -279.333236)
		(end 137.219944 -279.150318)
		(width 0.088646)
		(layer "In6.Cu")
		(net "M_H_CPU1_SA_DQ<1>")
	)
	(arc
		(start 132.23875 -278.66086)
		(mid 131.956048 -278.585084)
		(end 131.673346 -278.66086)
		(width 0.088646)
		(layer "In6.Cu")
		(net "M_H_CPU1_SA_DQ<1>")
	)
	(arc
		(start 131.29895 -278.66086)
		(mid 131.022137 -278.58499)
		(end 130.743706 -278.654764)
		(width 0.088646)
		(layer "In6.Cu")
		(net "M_H_CPU1_SA_DQ<1>")
	)
	(arc
		(start 137.868406 -280.283412)
		(mid 137.737492 -280.147052)
		(end 137.689844 -279.964134)
		(width 0.088646)
		(layer "In6.Cu")
		(net "M_H_CPU1_SA_DQ<1>")
	)
	(arc
		(start 136.372092 -278.66086)
		(mid 136.184894 -278.711003)
		(end 135.997696 -278.66086)
		(width 0.088646)
		(layer "In6.Cu")
		(net "M_H_CPU1_SA_DQ<1>")
	)
	(arc
		(start 135.432292 -278.66086)
		(mid 135.245094 -278.711003)
		(end 135.057896 -278.66086)
		(width 0.088646)
		(layer "In6.Cu")
		(net "M_H_CPU1_SA_DQ<1>")
	)
	(arc
		(start 135.997696 -278.66086)
		(mid 135.714994 -278.585084)
		(end 135.432292 -278.66086)
		(width 0.088646)
		(layer "In6.Cu")
		(net "M_H_CPU1_SA_DQ<1>")
	)
	(arc
		(start 132.613146 -278.66086)
		(mid 132.425948 -278.711003)
		(end 132.23875 -278.66086)
		(width 0.088646)
		(layer "In6.Cu")
		(net "M_H_CPU1_SA_DQ<1>")
	)
	(arc
		(start 134.492492 -278.66086)
		(mid 134.305294 -278.711003)
		(end 134.118096 -278.66086)
		(width 0.088646)
		(layer "In6.Cu")
		(net "M_H_CPU1_SA_DQ<1>")
	)
	(arc
		(start 137.689844 -279.954228)
		(mid 137.611733 -279.677279)
		(end 137.407396 -279.474676)
		(width 0.088646)
		(layer "In6.Cu")
		(net "M_H_CPU1_SA_DQ<1>")
	)
	(arc
		(start 137.219944 -279.140412)
		(mid 137.141833 -278.863463)
		(end 136.937496 -278.66086)
		(width 0.088646)
		(layer "In6.Cu")
		(net "M_H_CPU1_SA_DQ<1>")
	)
	(arc
		(start 129.977388 -278.437086)
		(mid 129.798675 -278.362069)
		(end 129.606548 -278.336502)
		(width 0.088646)
		(layer "In6.Cu")
		(net "M_H_CPU1_SA_DQ<1>")
	)
	(arc
		(start 138.817604 -280.288492)
		(mid 138.540791 -280.212656)
		(end 138.26236 -280.282396)
		(width 0.088646)
		(layer "In6.Cu")
		(net "M_H_CPU1_SA_DQ<1>")
	)
	(arc
		(start 138.251946 -280.288492)
		(mid 138.064748 -280.338635)
		(end 137.87755 -280.288492)
		(width 0.088646)
		(layer "In6.Cu")
		(net "M_H_CPU1_SA_DQ<1>")
	)
	(arc
		(start 134.118096 -278.66086)
		(mid 133.841537 -278.585117)
		(end 133.56336 -278.654764)
		(width 0.088646)
		(layer "In6.Cu")
		(net "M_H_CPU1_SA_DQ<1>")
	)
	(arc
		(start 130.733292 -278.66086)
		(mid 130.546094 -278.711003)
		(end 130.358896 -278.66086)
		(width 0.088646)
		(layer "In6.Cu")
		(net "M_H_CPU1_SA_DQ<1>")
	)
	(arc
		(start 136.937496 -278.66086)
		(mid 136.654794 -278.585084)
		(end 136.372092 -278.66086)
		(width 0.088646)
		(layer "In6.Cu")
		(net "M_H_CPU1_SA_DQ<1>")
	)
	(arc
		(start 133.17855 -278.66086)
		(mid 132.895848 -278.585084)
		(end 132.613146 -278.66086)
		(width 0.088646)
		(layer "In6.Cu")
		(net "M_H_CPU1_SA_DQ<1>")
	)
	(arc
		(start 139.175744 -280.385266)
		(mid 138.990259 -280.360634)
		(end 138.817604 -280.288492)
		(width 0.088646)
		(layer "In6.Cu")
		(net "M_H_CPU1_SA_DQ<1>")
	)
	(arc
		(start 135.057896 -278.66086)
		(mid 134.775194 -278.585084)
		(end 134.492492 -278.66086)
		(width 0.088646)
		(layer "In6.Cu")
		(net "M_H_CPU1_SA_DQ<1>")
	)
	(arc
		(start 133.552946 -278.66086)
		(mid 133.365748 -278.711003)
		(end 133.17855 -278.66086)
		(width 0.088646)
		(layer "In6.Cu")
		(net "M_H_CPU1_SA_DQ<1>")
	)
	(arc
		(start 131.673346 -278.66086)
		(mid 131.486148 -278.711003)
		(end 131.29895 -278.66086)
		(width 0.088646)
		(layer "In6.Cu")
		(net "M_H_CPU1_SA_DQ<1>")
	)
	(segment
		(start 212.618066 -295.491662)
		(end 212.630258 -295.503854)
		(width 0.1016)
		(layer "F.Cu")
		(net "M_H_CPU1_SA_DQ<19>")
	)
	(segment
		(start 210.598258 -295.498774)
		(end 210.603084 -295.498774)
		(width 0.101854)
		(layer "F.Cu")
		(net "M_H_CPU1_SA_DQ<19>")
	)
	(segment
		(start 213.311486 -295.503854)
		(end 213.515448 -295.299892)
		(width 0.20066)
		(layer "F.Cu")
		(net "M_H_CPU1_SA_DQ<19>")
	)
	(segment
		(start 214.133684 -294.814752)
		(end 214.385652 -295.06672)
		(width 0.20066)
		(layer "F.Cu")
		(net "M_H_CPU1_SA_DQ<19>")
	)
	(segment
		(start 207.071214 -295.06672)
		(end 208.176114 -295.06672)
		(width 0.20066)
		(layer "F.Cu")
		(net "M_H_CPU1_SA_DQ<19>")
	)
	(segment
		(start 210.610196 -295.491662)
		(end 212.618066 -295.491662)
		(width 0.1016)
		(layer "F.Cu")
		(net "M_H_CPU1_SA_DQ<19>")
	)
	(segment
		(start 208.176114 -295.06672)
		(end 209.874358 -295.06672)
		(width 0.20066)
		(layer "F.Cu")
		(net "M_H_CPU1_SA_DQ<19>")
	)
	(segment
		(start 210.306412 -295.498774)
		(end 210.598258 -295.498774)
		(width 0.20066)
		(layer "F.Cu")
		(net "M_H_CPU1_SA_DQ<19>")
	)
	(segment
		(start 212.630258 -295.503854)
		(end 213.311486 -295.503854)
		(width 0.20066)
		(layer "F.Cu")
		(net "M_H_CPU1_SA_DQ<19>")
	)
	(segment
		(start 213.515448 -295.04894)
		(end 213.749636 -294.814752)
		(width 0.20066)
		(layer "F.Cu")
		(net "M_H_CPU1_SA_DQ<19>")
	)
	(segment
		(start 213.749636 -294.814752)
		(end 214.133684 -294.814752)
		(width 0.20066)
		(layer "F.Cu")
		(net "M_H_CPU1_SA_DQ<19>")
	)
	(segment
		(start 125.377448 -270.475456)
		(end 125.377448 -271.011142)
		(width 0.20066)
		(layer "F.Cu")
		(net "M_H_CPU1_SA_DQ<19>")
	)
	(segment
		(start 213.515448 -295.299892)
		(end 213.515448 -295.04894)
		(width 0.20066)
		(layer "F.Cu")
		(net "M_H_CPU1_SA_DQ<19>")
	)
	(segment
		(start 214.385652 -295.06672)
		(end 215.719914 -295.06672)
		(width 0.20066)
		(layer "F.Cu")
		(net "M_H_CPU1_SA_DQ<19>")
	)
	(segment
		(start 209.874358 -295.06672)
		(end 210.306412 -295.498774)
		(width 0.20066)
		(layer "F.Cu")
		(net "M_H_CPU1_SA_DQ<19>")
	)
	(segment
		(start 125.377448 -271.011142)
		(end 125.377194 -271.011396)
		(width 0.20066)
		(layer "F.Cu")
		(net "M_H_CPU1_SA_DQ<19>")
	)
	(segment
		(start 210.603084 -295.498774)
		(end 210.610196 -295.491662)
		(width 0.1016)
		(layer "F.Cu")
		(net "M_H_CPU1_SA_DQ<19>")
	)
	(segment
		(start 176.099216 -300.592236)
		(end 175.925226 -300.766226)
		(width 0.18288)
		(layer "In11.Cu")
		(net "M_H_CPU1_SA_DQ<19>")
	)
	(segment
		(start 179.14874 -300.226222)
		(end 178.619404 -300.226222)
		(width 0.18288)
		(layer "In11.Cu")
		(net "M_H_CPU1_SA_DQ<19>")
	)
	(segment
		(start 129.888996 -272.96364)
		(end 129.880106 -272.95856)
		(width 0.088646)
		(layer "In11.Cu")
		(net "M_H_CPU1_SA_DQ<19>")
	)
	(segment
		(start 138.123168 -276.219412)
		(end 136.584944 -274.681188)
		(width 0.088646)
		(layer "In11.Cu")
		(net "M_H_CPU1_SA_DQ<19>")
	)
	(segment
		(start 143.054832 -280.133044)
		(end 143.055086 -280.064718)
		(width 0.18288)
		(layer "In11.Cu")
		(net "M_H_CPU1_SA_DQ<19>")
	)
	(segment
		(start 159.810704 -297.272964)
		(end 158.137352 -295.599612)
		(width 0.18288)
		(layer "In11.Cu")
		(net "M_H_CPU1_SA_DQ<19>")
	)
	(segment
		(start 206.262732 -295.06672)
		(end 205.567026 -295.762426)
		(width 0.18288)
		(layer "In11.Cu")
		(net "M_H_CPU1_SA_DQ<19>")
	)
	(segment
		(start 172.089826 -301.655226)
		(end 171.512484 -301.655226)
		(width 0.18288)
		(layer "In11.Cu")
		(net "M_H_CPU1_SA_DQ<19>")
	)
	(segment
		(start 126.101856 -271.319498)
		(end 125.377194 -271.011396)
		(width 0.088646)
		(layer "In11.Cu")
		(net "M_H_CPU1_SA_DQ<19>")
	)
	(segment
		(start 189.87897 -300.77537)
		(end 188.845952 -299.742352)
		(width 0.18288)
		(layer "In11.Cu")
		(net "M_H_CPU1_SA_DQ<19>")
	)
	(segment
		(start 139.164568 -276.48662)
		(end 138.89736 -276.219412)
		(width 0.088646)
		(layer "In11.Cu")
		(net "M_H_CPU1_SA_DQ<19>")
	)
	(segment
		(start 205.567026 -295.762426)
		(end 204.186028 -295.762426)
		(width 0.18288)
		(layer "In11.Cu")
		(net "M_H_CPU1_SA_DQ<19>")
	)
	(segment
		(start 188.845952 -299.742352)
		(end 187.290456 -299.742352)
		(width 0.18288)
		(layer "In11.Cu")
		(net "M_H_CPU1_SA_DQ<19>")
	)
	(segment
		(start 173.588172 -301.442374)
		(end 172.302678 -301.442374)
		(width 0.18288)
		(layer "In11.Cu")
		(net "M_H_CPU1_SA_DQ<19>")
	)
	(segment
		(start 204.186028 -295.762426)
		(end 203.916026 -295.492424)
		(width 0.18288)
		(layer "In11.Cu")
		(net "M_H_CPU1_SA_DQ<19>")
	)
	(segment
		(start 190.96101 -300.77537)
		(end 189.87897 -300.77537)
		(width 0.18288)
		(layer "In11.Cu")
		(net "M_H_CPU1_SA_DQ<19>")
	)
	(segment
		(start 130.828796 -274.591272)
		(end 130.819906 -274.586192)
		(width 0.088646)
		(layer "In11.Cu")
		(net "M_H_CPU1_SA_DQ<19>")
	)
	(segment
		(start 128.868678 -272.140934)
		(end 128.853946 -272.14957)
		(width 0.088646)
		(layer "In11.Cu")
		(net "M_H_CPU1_SA_DQ<19>")
	)
	(segment
		(start 128.015492 -271.33931)
		(end 128.009396 -271.335754)
		(width 0.088646)
		(layer "In11.Cu")
		(net "M_H_CPU1_SA_DQ<19>")
	)
	(segment
		(start 187.131198 -299.90161)
		(end 183.874918 -299.90161)
		(width 0.18288)
		(layer "In11.Cu")
		(net "M_H_CPU1_SA_DQ<19>")
	)
	(segment
		(start 172.302678 -301.442374)
		(end 172.089826 -301.655226)
		(width 0.18288)
		(layer "In11.Cu")
		(net "M_H_CPU1_SA_DQ<19>")
	)
	(segment
		(start 192.871598 -300.055026)
		(end 192.334642 -300.591982)
		(width 0.18288)
		(layer "In11.Cu")
		(net "M_H_CPU1_SA_DQ<19>")
	)
	(segment
		(start 175.925226 -300.766226)
		(end 174.26432 -300.766226)
		(width 0.18288)
		(layer "In11.Cu")
		(net "M_H_CPU1_SA_DQ<19>")
	)
	(segment
		(start 203.916026 -295.492424)
		(end 202.718924 -295.492424)
		(width 0.18288)
		(layer "In11.Cu")
		(net "M_H_CPU1_SA_DQ<19>")
	)
	(segment
		(start 195.217542 -298.912026)
		(end 194.074542 -300.055026)
		(width 0.18288)
		(layer "In11.Cu")
		(net "M_H_CPU1_SA_DQ<19>")
	)
	(segment
		(start 167.221154 -299.557948)
		(end 167.028114 -299.750988)
		(width 0.18288)
		(layer "In11.Cu")
		(net "M_H_CPU1_SA_DQ<19>")
	)
	(segment
		(start 178.619404 -300.226222)
		(end 178.25339 -300.592236)
		(width 0.18288)
		(layer "In11.Cu")
		(net "M_H_CPU1_SA_DQ<19>")
	)
	(segment
		(start 207.071214 -295.06672)
		(end 206.262732 -295.06672)
		(width 0.18288)
		(layer "In11.Cu")
		(net "M_H_CPU1_SA_DQ<19>")
	)
	(segment
		(start 191.144398 -300.591982)
		(end 190.96101 -300.77537)
		(width 0.18288)
		(layer "In11.Cu")
		(net "M_H_CPU1_SA_DQ<19>")
	)
	(segment
		(start 202.11796 -294.89146)
		(end 201.294492 -294.89146)
		(width 0.18288)
		(layer "In11.Cu")
		(net "M_H_CPU1_SA_DQ<19>")
	)
	(segment
		(start 151.343106 -290.339018)
		(end 151.343106 -288.459418)
		(width 0.18288)
		(layer "In11.Cu")
		(net "M_H_CPU1_SA_DQ<19>")
	)
	(segment
		(start 168.121838 -299.064426)
		(end 167.414194 -299.064426)
		(width 0.18288)
		(layer "In11.Cu")
		(net "M_H_CPU1_SA_DQ<19>")
	)
	(segment
		(start 151.343106 -288.459418)
		(end 143.153638 -280.232358)
		(width 0.18288)
		(layer "In11.Cu")
		(net "M_H_CPU1_SA_DQ<19>")
	)
	(segment
		(start 168.82618 -299.768768)
		(end 168.121838 -299.064426)
		(width 0.18288)
		(layer "In11.Cu")
		(net "M_H_CPU1_SA_DQ<19>")
	)
	(segment
		(start 156.601922 -295.599612)
		(end 151.343106 -290.339018)
		(width 0.18288)
		(layer "In11.Cu")
		(net "M_H_CPU1_SA_DQ<19>")
	)
	(segment
		(start 143.153638 -280.232358)
		(end 143.054832 -280.133044)
		(width 0.18288)
		(layer "In11.Cu")
		(net "M_H_CPU1_SA_DQ<19>")
	)
	(segment
		(start 199.737726 -296.448226)
		(end 198.747126 -296.448226)
		(width 0.18288)
		(layer "In11.Cu")
		(net "M_H_CPU1_SA_DQ<19>")
	)
	(segment
		(start 178.25339 -300.592236)
		(end 176.099216 -300.592236)
		(width 0.18288)
		(layer "In11.Cu")
		(net "M_H_CPU1_SA_DQ<19>")
	)
	(segment
		(start 169.626026 -299.768768)
		(end 168.82618 -299.768768)
		(width 0.18288)
		(layer "In11.Cu")
		(net "M_H_CPU1_SA_DQ<19>")
	)
	(segment
		(start 127.069596 -271.335754)
		(end 127.054864 -271.327118)
		(width 0.088646)
		(layer "In11.Cu")
		(net "M_H_CPU1_SA_DQ<19>")
	)
	(segment
		(start 197.858126 -297.337226)
		(end 197.344538 -297.337226)
		(width 0.18288)
		(layer "In11.Cu")
		(net "M_H_CPU1_SA_DQ<19>")
	)
	(segment
		(start 202.718924 -295.492424)
		(end 202.11796 -294.89146)
		(width 0.18288)
		(layer "In11.Cu")
		(net "M_H_CPU1_SA_DQ<19>")
	)
	(segment
		(start 195.769738 -298.912026)
		(end 195.217542 -298.912026)
		(width 0.18288)
		(layer "In11.Cu")
		(net "M_H_CPU1_SA_DQ<19>")
	)
	(segment
		(start 158.137352 -295.599612)
		(end 156.601922 -295.599612)
		(width 0.18288)
		(layer "In11.Cu")
		(net "M_H_CPU1_SA_DQ<19>")
	)
	(segment
		(start 129.895092 -272.967196)
		(end 129.888996 -272.96364)
		(width 0.088646)
		(layer "In11.Cu")
		(net "M_H_CPU1_SA_DQ<19>")
	)
	(segment
		(start 143.055086 -280.064718)
		(end 139.495022 -276.48789)
		(width 0.18288)
		(layer "In11.Cu")
		(net "M_H_CPU1_SA_DQ<19>")
	)
	(segment
		(start 166.710614 -299.750988)
		(end 166.517574 -299.557948)
		(width 0.18288)
		(layer "In11.Cu")
		(net "M_H_CPU1_SA_DQ<19>")
	)
	(segment
		(start 179.532534 -300.610016)
		(end 179.14874 -300.226222)
		(width 0.18288)
		(layer "In11.Cu")
		(net "M_H_CPU1_SA_DQ<19>")
	)
	(segment
		(start 187.290456 -299.742352)
		(end 187.131198 -299.90161)
		(width 0.18288)
		(layer "In11.Cu")
		(net "M_H_CPU1_SA_DQ<19>")
	)
	(segment
		(start 166.324534 -299.064426)
		(end 164.723826 -299.064426)
		(width 0.18288)
		(layer "In11.Cu")
		(net "M_H_CPU1_SA_DQ<19>")
	)
	(segment
		(start 171.512484 -301.655226)
		(end 169.626026 -299.768768)
		(width 0.18288)
		(layer "In11.Cu")
		(net "M_H_CPU1_SA_DQ<19>")
	)
	(segment
		(start 198.747126 -296.448226)
		(end 197.858126 -297.337226)
		(width 0.18288)
		(layer "In11.Cu")
		(net "M_H_CPU1_SA_DQ<19>")
	)
	(segment
		(start 136.467596 -274.591272)
		(end 136.452864 -274.582636)
		(width 0.088646)
		(layer "In11.Cu")
		(net "M_H_CPU1_SA_DQ<19>")
	)
	(segment
		(start 194.074542 -300.055026)
		(end 192.871598 -300.055026)
		(width 0.18288)
		(layer "In11.Cu")
		(net "M_H_CPU1_SA_DQ<19>")
	)
	(segment
		(start 127.06985 -271.335754)
		(end 127.069596 -271.335754)
		(width 0.088646)
		(layer "In11.Cu")
		(net "M_H_CPU1_SA_DQ<19>")
	)
	(segment
		(start 180.841904 -300.610016)
		(end 179.532534 -300.610016)
		(width 0.18288)
		(layer "In11.Cu")
		(net "M_H_CPU1_SA_DQ<19>")
	)
	(segment
		(start 166.517574 -299.257466)
		(end 166.324534 -299.064426)
		(width 0.18288)
		(layer "In11.Cu")
		(net "M_H_CPU1_SA_DQ<19>")
	)
	(segment
		(start 164.723826 -299.064426)
		(end 162.842956 -297.180508)
		(width 0.18288)
		(layer "In11.Cu")
		(net "M_H_CPU1_SA_DQ<19>")
	)
	(segment
		(start 167.414194 -299.064426)
		(end 167.221154 -299.257466)
		(width 0.18288)
		(layer "In11.Cu")
		(net "M_H_CPU1_SA_DQ<19>")
	)
	(segment
		(start 130.641344 -274.266914)
		(end 130.641344 -274.25142)
		(width 0.088646)
		(layer "In11.Cu")
		(net "M_H_CPU1_SA_DQ<19>")
	)
	(segment
		(start 133.09346 -274.585176)
		(end 133.083046 -274.591272)
		(width 0.088646)
		(layer "In11.Cu")
		(net "M_H_CPU1_SA_DQ<19>")
	)
	(segment
		(start 130.35915 -273.777456)
		(end 130.35026 -273.772376)
		(width 0.088646)
		(layer "In11.Cu")
		(net "M_H_CPU1_SA_DQ<19>")
	)
	(segment
		(start 134.587996 -274.591272)
		(end 134.573264 -274.582636)
		(width 0.088646)
		(layer "In11.Cu")
		(net "M_H_CPU1_SA_DQ<19>")
	)
	(segment
		(start 138.89736 -276.219412)
		(end 138.123168 -276.219412)
		(width 0.088646)
		(layer "In11.Cu")
		(net "M_H_CPU1_SA_DQ<19>")
	)
	(segment
		(start 139.495022 -276.48789)
		(end 139.316714 -276.487382)
		(width 0.18288)
		(layer "In11.Cu")
		(net "M_H_CPU1_SA_DQ<19>")
	)
	(segment
		(start 181.755034 -299.696886)
		(end 180.841904 -300.610016)
		(width 0.18288)
		(layer "In11.Cu")
		(net "M_H_CPU1_SA_DQ<19>")
	)
	(segment
		(start 166.517574 -299.557948)
		(end 166.517574 -299.257466)
		(width 0.18288)
		(layer "In11.Cu")
		(net "M_H_CPU1_SA_DQ<19>")
	)
	(segment
		(start 139.316714 -276.487382)
		(end 139.164568 -276.48662)
		(width 0.088646)
		(layer "In11.Cu")
		(net "M_H_CPU1_SA_DQ<19>")
	)
	(segment
		(start 183.874918 -299.90161)
		(end 183.670194 -299.696886)
		(width 0.18288)
		(layer "In11.Cu")
		(net "M_H_CPU1_SA_DQ<19>")
	)
	(segment
		(start 162.107118 -297.179746)
		(end 160.880298 -297.179746)
		(width 0.18288)
		(layer "In11.Cu")
		(net "M_H_CPU1_SA_DQ<19>")
	)
	(segment
		(start 162.842956 -297.180508)
		(end 162.107118 -297.179746)
		(width 0.18288)
		(layer "In11.Cu")
		(net "M_H_CPU1_SA_DQ<19>")
	)
	(segment
		(start 160.880298 -297.179746)
		(end 160.78708 -297.272964)
		(width 0.18288)
		(layer "In11.Cu")
		(net "M_H_CPU1_SA_DQ<19>")
	)
	(segment
		(start 174.26432 -300.766226)
		(end 173.588172 -301.442374)
		(width 0.18288)
		(layer "In11.Cu")
		(net "M_H_CPU1_SA_DQ<19>")
	)
	(segment
		(start 126.129796 -271.335754)
		(end 126.101856 -271.319498)
		(width 0.088646)
		(layer "In11.Cu")
		(net "M_H_CPU1_SA_DQ<19>")
	)
	(segment
		(start 132.70865 -274.591272)
		(end 132.698236 -274.585176)
		(width 0.088646)
		(layer "In11.Cu")
		(net "M_H_CPU1_SA_DQ<19>")
	)
	(segment
		(start 128.47955 -272.14957)
		(end 128.47066 -272.14449)
		(width 0.088646)
		(layer "In11.Cu")
		(net "M_H_CPU1_SA_DQ<19>")
	)
	(segment
		(start 183.670194 -299.696886)
		(end 181.755034 -299.696886)
		(width 0.18288)
		(layer "In11.Cu")
		(net "M_H_CPU1_SA_DQ<19>")
	)
	(segment
		(start 167.028114 -299.750988)
		(end 166.710614 -299.750988)
		(width 0.18288)
		(layer "In11.Cu")
		(net "M_H_CPU1_SA_DQ<19>")
	)
	(segment
		(start 131.768596 -274.591272)
		(end 131.753864 -274.582636)
		(width 0.088646)
		(layer "In11.Cu")
		(net "M_H_CPU1_SA_DQ<19>")
	)
	(segment
		(start 129.701544 -272.639282)
		(end 129.701544 -272.63852)
		(width 0.088646)
		(layer "In11.Cu")
		(net "M_H_CPU1_SA_DQ<19>")
	)
	(segment
		(start 201.294492 -294.89146)
		(end 199.737726 -296.448226)
		(width 0.18288)
		(layer "In11.Cu")
		(net "M_H_CPU1_SA_DQ<19>")
	)
	(segment
		(start 135.527796 -274.591272)
		(end 135.513064 -274.582636)
		(width 0.088646)
		(layer "In11.Cu")
		(net "M_H_CPU1_SA_DQ<19>")
	)
	(segment
		(start 197.344538 -297.337226)
		(end 195.769738 -298.912026)
		(width 0.18288)
		(layer "In11.Cu")
		(net "M_H_CPU1_SA_DQ<19>")
	)
	(segment
		(start 128.009396 -271.335754)
		(end 127.994664 -271.327118)
		(width 0.088646)
		(layer "In11.Cu")
		(net "M_H_CPU1_SA_DQ<19>")
	)
	(segment
		(start 192.334642 -300.591982)
		(end 191.144398 -300.591982)
		(width 0.18288)
		(layer "In11.Cu")
		(net "M_H_CPU1_SA_DQ<19>")
	)
	(segment
		(start 160.78708 -297.272964)
		(end 159.810704 -297.272964)
		(width 0.18288)
		(layer "In11.Cu")
		(net "M_H_CPU1_SA_DQ<19>")
	)
	(segment
		(start 167.221154 -299.257466)
		(end 167.221154 -299.557948)
		(width 0.18288)
		(layer "In11.Cu")
		(net "M_H_CPU1_SA_DQ<19>")
	)
	(arc
		(start 132.698236 -274.585176)
		(mid 132.419804 -274.51533)
		(end 132.142992 -274.591272)
		(width 0.088646)
		(layer "In11.Cu")
		(net "M_H_CPU1_SA_DQ<19>")
	)
	(arc
		(start 130.171698 -273.453098)
		(mid 130.097707 -273.173532)
		(end 129.895092 -272.967196)
		(width 0.088646)
		(layer "In11.Cu")
		(net "M_H_CPU1_SA_DQ<19>")
	)
	(arc
		(start 128.853946 -272.14957)
		(mid 128.666748 -272.199713)
		(end 128.47955 -272.14957)
		(width 0.088646)
		(layer "In11.Cu")
		(net "M_H_CPU1_SA_DQ<19>")
	)
	(arc
		(start 133.648196 -274.591272)
		(mid 133.371637 -274.515529)
		(end 133.09346 -274.585176)
		(width 0.088646)
		(layer "In11.Cu")
		(net "M_H_CPU1_SA_DQ<19>")
	)
	(arc
		(start 131.753864 -274.582636)
		(mid 131.477389 -274.515316)
		(end 131.203192 -274.591272)
		(width 0.088646)
		(layer "In11.Cu")
		(net "M_H_CPU1_SA_DQ<19>")
	)
	(arc
		(start 130.641344 -274.25142)
		(mid 130.561974 -273.977686)
		(end 130.35915 -273.777456)
		(width 0.088646)
		(layer "In11.Cu")
		(net "M_H_CPU1_SA_DQ<19>")
	)
	(arc
		(start 134.962392 -274.591272)
		(mid 134.775194 -274.641415)
		(end 134.587996 -274.591272)
		(width 0.088646)
		(layer "In11.Cu")
		(net "M_H_CPU1_SA_DQ<19>")
	)
	(arc
		(start 127.054864 -271.327118)
		(mid 126.778389 -271.259798)
		(end 126.504192 -271.335754)
		(width 0.088646)
		(layer "In11.Cu")
		(net "M_H_CPU1_SA_DQ<19>")
	)
	(arc
		(start 130.35026 -273.772376)
		(mid 130.219346 -273.636016)
		(end 130.171698 -273.453098)
		(width 0.088646)
		(layer "In11.Cu")
		(net "M_H_CPU1_SA_DQ<19>")
	)
	(arc
		(start 136.452864 -274.582636)
		(mid 136.176423 -274.51547)
		(end 135.902192 -274.591272)
		(width 0.088646)
		(layer "In11.Cu")
		(net "M_H_CPU1_SA_DQ<19>")
	)
	(arc
		(start 128.47066 -272.14449)
		(mid 128.339746 -272.00813)
		(end 128.292098 -271.825212)
		(width 0.088646)
		(layer "In11.Cu")
		(net "M_H_CPU1_SA_DQ<19>")
	)
	(arc
		(start 136.584944 -274.681188)
		(mid 136.529215 -274.632388)
		(end 136.467596 -274.591272)
		(width 0.088646)
		(layer "In11.Cu")
		(net "M_H_CPU1_SA_DQ<19>")
	)
	(arc
		(start 135.513064 -274.582636)
		(mid 135.236623 -274.51547)
		(end 134.962392 -274.591272)
		(width 0.088646)
		(layer "In11.Cu")
		(net "M_H_CPU1_SA_DQ<19>")
	)
	(arc
		(start 129.880106 -272.95856)
		(mid 129.749192 -272.8222)
		(end 129.701544 -272.639282)
		(width 0.088646)
		(layer "In11.Cu")
		(net "M_H_CPU1_SA_DQ<19>")
	)
	(arc
		(start 132.142992 -274.591272)
		(mid 131.955794 -274.641415)
		(end 131.768596 -274.591272)
		(width 0.088646)
		(layer "In11.Cu")
		(net "M_H_CPU1_SA_DQ<19>")
	)
	(arc
		(start 126.504192 -271.335754)
		(mid 126.316994 -271.385897)
		(end 126.129796 -271.335754)
		(width 0.088646)
		(layer "In11.Cu")
		(net "M_H_CPU1_SA_DQ<19>")
	)
	(arc
		(start 127.994664 -271.327118)
		(mid 127.718189 -271.259798)
		(end 127.443992 -271.335754)
		(width 0.088646)
		(layer "In11.Cu")
		(net "M_H_CPU1_SA_DQ<19>")
	)
	(arc
		(start 135.902192 -274.591272)
		(mid 135.714994 -274.641415)
		(end 135.527796 -274.591272)
		(width 0.088646)
		(layer "In11.Cu")
		(net "M_H_CPU1_SA_DQ<19>")
	)
	(arc
		(start 128.292098 -271.825212)
		(mid 128.218107 -271.545646)
		(end 128.015492 -271.33931)
		(width 0.088646)
		(layer "In11.Cu")
		(net "M_H_CPU1_SA_DQ<19>")
	)
	(arc
		(start 134.573264 -274.582636)
		(mid 134.296789 -274.515316)
		(end 134.022592 -274.591272)
		(width 0.088646)
		(layer "In11.Cu")
		(net "M_H_CPU1_SA_DQ<19>")
	)
	(arc
		(start 131.203192 -274.591272)
		(mid 131.015994 -274.641415)
		(end 130.828796 -274.591272)
		(width 0.088646)
		(layer "In11.Cu")
		(net "M_H_CPU1_SA_DQ<19>")
	)
	(arc
		(start 133.083046 -274.591272)
		(mid 132.895848 -274.641415)
		(end 132.70865 -274.591272)
		(width 0.088646)
		(layer "In11.Cu")
		(net "M_H_CPU1_SA_DQ<19>")
	)
	(arc
		(start 127.443992 -271.335754)
		(mid 127.256938 -271.385804)
		(end 127.06985 -271.335754)
		(width 0.088646)
		(layer "In11.Cu")
		(net "M_H_CPU1_SA_DQ<19>")
	)
	(arc
		(start 129.701544 -272.63852)
		(mid 129.625929 -272.356256)
		(end 129.41935 -272.14957)
		(width 0.088646)
		(layer "In11.Cu")
		(net "M_H_CPU1_SA_DQ<19>")
	)
	(arc
		(start 129.41935 -272.14957)
		(mid 129.145121 -272.073645)
		(end 128.868678 -272.140934)
		(width 0.088646)
		(layer "In11.Cu")
		(net "M_H_CPU1_SA_DQ<19>")
	)
	(arc
		(start 134.022592 -274.591272)
		(mid 133.835394 -274.641415)
		(end 133.648196 -274.591272)
		(width 0.088646)
		(layer "In11.Cu")
		(net "M_H_CPU1_SA_DQ<19>")
	)
	(arc
		(start 130.819906 -274.586192)
		(mid 130.688992 -274.449832)
		(end 130.641344 -274.266914)
		(width 0.088646)
		(layer "In11.Cu")
		(net "M_H_CPU1_SA_DQ<19>")
	)
	(segment
		(start 214.133684 -296.514774)
		(end 214.385652 -296.766742)
		(width 0.20066)
		(layer "F.Cu")
		(net "M_H_CPU1_SA_DQ<18>")
	)
	(segment
		(start 210.610196 -297.191684)
		(end 212.618066 -297.191684)
		(width 0.1016)
		(layer "F.Cu")
		(net "M_H_CPU1_SA_DQ<18>")
	)
	(segment
		(start 212.630258 -297.203876)
		(end 213.311486 -297.203876)
		(width 0.20066)
		(layer "F.Cu")
		(net "M_H_CPU1_SA_DQ<18>")
	)
	(segment
		(start 213.515448 -296.748962)
		(end 213.749636 -296.514774)
		(width 0.20066)
		(layer "F.Cu")
		(net "M_H_CPU1_SA_DQ<18>")
	)
	(segment
		(start 213.749636 -296.514774)
		(end 214.133684 -296.514774)
		(width 0.20066)
		(layer "F.Cu")
		(net "M_H_CPU1_SA_DQ<18>")
	)
	(segment
		(start 210.598258 -297.198796)
		(end 210.603084 -297.198796)
		(width 0.101854)
		(layer "F.Cu")
		(net "M_H_CPU1_SA_DQ<18>")
	)
	(segment
		(start 207.071214 -296.766742)
		(end 208.176114 -296.766742)
		(width 0.20066)
		(layer "F.Cu")
		(net "M_H_CPU1_SA_DQ<18>")
	)
	(segment
		(start 208.176114 -296.766742)
		(end 209.874358 -296.766742)
		(width 0.20066)
		(layer "F.Cu")
		(net "M_H_CPU1_SA_DQ<18>")
	)
	(segment
		(start 213.311486 -297.203876)
		(end 213.515448 -296.999914)
		(width 0.20066)
		(layer "F.Cu")
		(net "M_H_CPU1_SA_DQ<18>")
	)
	(segment
		(start 210.603084 -297.198796)
		(end 210.610196 -297.191684)
		(width 0.1016)
		(layer "F.Cu")
		(net "M_H_CPU1_SA_DQ<18>")
	)
	(segment
		(start 213.515448 -296.999914)
		(end 213.515448 -296.748962)
		(width 0.20066)
		(layer "F.Cu")
		(net "M_H_CPU1_SA_DQ<18>")
	)
	(segment
		(start 214.385652 -296.766742)
		(end 215.719914 -296.766742)
		(width 0.20066)
		(layer "F.Cu")
		(net "M_H_CPU1_SA_DQ<18>")
	)
	(segment
		(start 212.618066 -297.191684)
		(end 212.630258 -297.203876)
		(width 0.1016)
		(layer "F.Cu")
		(net "M_H_CPU1_SA_DQ<18>")
	)
	(segment
		(start 209.874358 -296.766742)
		(end 210.306412 -297.198796)
		(width 0.20066)
		(layer "F.Cu")
		(net "M_H_CPU1_SA_DQ<18>")
	)
	(segment
		(start 124.907294 -271.289272)
		(end 124.907548 -271.825212)
		(width 0.20066)
		(layer "F.Cu")
		(net "M_H_CPU1_SA_DQ<18>")
	)
	(segment
		(start 210.306412 -297.198796)
		(end 210.598258 -297.198796)
		(width 0.20066)
		(layer "F.Cu")
		(net "M_H_CPU1_SA_DQ<18>")
	)
	(segment
		(start 142.150338 -280.731976)
		(end 142.150338 -280.48458)
		(width 0.18288)
		(layer "In11.Cu")
		(net "M_H_CPU1_SA_DQ<18>")
	)
	(segment
		(start 124.59462 -271.825212)
		(end 124.907548 -271.825212)
		(width 0.088646)
		(layer "In11.Cu")
		(net "M_H_CPU1_SA_DQ<18>")
	)
	(segment
		(start 133.563106 -275.398992)
		(end 133.552692 -275.405088)
		(width 0.088646)
		(layer "In11.Cu")
		(net "M_H_CPU1_SA_DQ<18>")
	)
	(segment
		(start 182.40248 -301.375826)
		(end 181.884828 -301.68596)
		(width 0.18288)
		(layer "In11.Cu")
		(net "M_H_CPU1_SA_DQ<18>")
	)
	(segment
		(start 126.044706 -272.143474)
		(end 126.034292 -272.14957)
		(width 0.088646)
		(layer "In11.Cu")
		(net "M_H_CPU1_SA_DQ<18>")
	)
	(segment
		(start 132.62356 -275.398992)
		(end 132.613146 -275.405088)
		(width 0.088646)
		(layer "In11.Cu")
		(net "M_H_CPU1_SA_DQ<18>")
	)
	(segment
		(start 159.013906 -298.224194)
		(end 158.062168 -297.272456)
		(width 0.18288)
		(layer "In11.Cu")
		(net "M_H_CPU1_SA_DQ<18>")
	)
	(segment
		(start 124.72035 -272.14957)
		(end 124.71146 -272.14449)
		(width 0.088646)
		(layer "In11.Cu")
		(net "M_H_CPU1_SA_DQ<18>")
	)
	(segment
		(start 125.659896 -272.14957)
		(end 125.649482 -272.143474)
		(width 0.088646)
		(layer "In11.Cu")
		(net "M_H_CPU1_SA_DQ<18>")
	)
	(segment
		(start 177.43805 -303.143412)
		(end 173.996096 -303.143412)
		(width 0.18288)
		(layer "In11.Cu")
		(net "M_H_CPU1_SA_DQ<18>")
	)
	(segment
		(start 128.015492 -272.967196)
		(end 128.009396 -272.96364)
		(width 0.088646)
		(layer "In11.Cu")
		(net "M_H_CPU1_SA_DQ<18>")
	)
	(segment
		(start 125.66015 -272.14957)
		(end 125.659896 -272.14957)
		(width 0.088646)
		(layer "In11.Cu")
		(net "M_H_CPU1_SA_DQ<18>")
	)
	(segment
		(start 202.65771 -297.192192)
		(end 202.039728 -296.57421)
		(width 0.18288)
		(layer "In11.Cu")
		(net "M_H_CPU1_SA_DQ<18>")
	)
	(segment
		(start 128.949196 -274.591272)
		(end 128.940306 -274.586192)
		(width 0.088646)
		(layer "In11.Cu")
		(net "M_H_CPU1_SA_DQ<18>")
	)
	(segment
		(start 183.7309 -301.375826)
		(end 182.40248 -301.375826)
		(width 0.18288)
		(layer "In11.Cu")
		(net "M_H_CPU1_SA_DQ<18>")
	)
	(segment
		(start 206.380842 -297.431714)
		(end 204.73797 -297.431714)
		(width 0.18288)
		(layer "In11.Cu")
		(net "M_H_CPU1_SA_DQ<18>")
	)
	(segment
		(start 129.808478 -275.396452)
		(end 129.793746 -275.405088)
		(width 0.088646)
		(layer "In11.Cu")
		(net "M_H_CPU1_SA_DQ<18>")
	)
	(segment
		(start 130.748278 -275.396452)
		(end 130.733546 -275.405088)
		(width 0.088646)
		(layer "In11.Cu")
		(net "M_H_CPU1_SA_DQ<18>")
	)
	(segment
		(start 127.821944 -272.639282)
		(end 127.821944 -272.63852)
		(width 0.088646)
		(layer "In11.Cu")
		(net "M_H_CPU1_SA_DQ<18>")
	)
	(segment
		(start 202.039728 -296.57421)
		(end 201.193654 -296.57421)
		(width 0.18288)
		(layer "In11.Cu")
		(net "M_H_CPU1_SA_DQ<18>")
	)
	(segment
		(start 139.252198 -277.303484)
		(end 138.75004 -276.801326)
		(width 0.088646)
		(layer "In11.Cu")
		(net "M_H_CPU1_SA_DQ<18>")
	)
	(segment
		(start 201.193654 -296.57421)
		(end 199.668638 -298.099226)
		(width 0.18288)
		(layer "In11.Cu")
		(net "M_H_CPU1_SA_DQ<18>")
	)
	(segment
		(start 187.161678 -301.442374)
		(end 186.031378 -301.702724)
		(width 0.18288)
		(layer "In11.Cu")
		(net "M_H_CPU1_SA_DQ<18>")
	)
	(segment
		(start 137.839196 -276.801326)
		(end 136.532874 -275.495004)
		(width 0.088646)
		(layer "In11.Cu")
		(net "M_H_CPU1_SA_DQ<18>")
	)
	(segment
		(start 139.630658 -277.9649)
		(end 139.252198 -277.58644)
		(width 0.088646)
		(layer "In11.Cu")
		(net "M_H_CPU1_SA_DQ<18>")
	)
	(segment
		(start 189.1665 -301.855378)
		(end 188.430916 -301.442374)
		(width 0.18288)
		(layer "In11.Cu")
		(net "M_H_CPU1_SA_DQ<18>")
	)
	(segment
		(start 167.954706 -301.350426)
		(end 166.784274 -301.350426)
		(width 0.18288)
		(layer "In11.Cu")
		(net "M_H_CPU1_SA_DQ<18>")
	)
	(segment
		(start 173.14545 -303.994058)
		(end 172.294804 -303.994058)
		(width 0.18288)
		(layer "In11.Cu")
		(net "M_H_CPU1_SA_DQ<18>")
	)
	(segment
		(start 181.884828 -301.68596)
		(end 180.08854 -302.444404)
		(width 0.18288)
		(layer "In11.Cu")
		(net "M_H_CPU1_SA_DQ<18>")
	)
	(segment
		(start 192.415414 -302.941736)
		(end 192.214754 -303.142396)
		(width 0.18288)
		(layer "In11.Cu")
		(net "M_H_CPU1_SA_DQ<18>")
	)
	(segment
		(start 150.290784 -288.872422)
		(end 142.150338 -280.731976)
		(width 0.18288)
		(layer "In11.Cu")
		(net "M_H_CPU1_SA_DQ<18>")
	)
	(segment
		(start 135.447278 -275.396706)
		(end 135.432546 -275.405342)
		(width 0.088646)
		(layer "In11.Cu")
		(net "M_H_CPU1_SA_DQ<18>")
	)
	(segment
		(start 142.150338 -280.48458)
		(end 139.630658 -277.9649)
		(width 0.18288)
		(layer "In11.Cu")
		(net "M_H_CPU1_SA_DQ<18>")
	)
	(segment
		(start 190.453518 -303.142396)
		(end 189.1665 -301.855378)
		(width 0.18288)
		(layer "In11.Cu")
		(net "M_H_CPU1_SA_DQ<18>")
	)
	(segment
		(start 128.009396 -272.96364)
		(end 128.000506 -272.95856)
		(width 0.088646)
		(layer "In11.Cu")
		(net "M_H_CPU1_SA_DQ<18>")
	)
	(segment
		(start 161.33064 -299.742352)
		(end 160.59404 -299.005752)
		(width 0.18288)
		(layer "In11.Cu")
		(net "M_H_CPU1_SA_DQ<18>")
	)
	(segment
		(start 198.670926 -298.099226)
		(end 197.756526 -299.013626)
		(width 0.18288)
		(layer "In11.Cu")
		(net "M_H_CPU1_SA_DQ<18>")
	)
	(segment
		(start 159.013906 -298.584366)
		(end 159.013906 -298.224194)
		(width 0.18288)
		(layer "In11.Cu")
		(net "M_H_CPU1_SA_DQ<18>")
	)
	(segment
		(start 165.842696 -301.159926)
		(end 162.911536 -300.072298)
		(width 0.18288)
		(layer "In11.Cu")
		(net "M_H_CPU1_SA_DQ<18>")
	)
	(segment
		(start 162.911536 -300.072298)
		(end 162.58159 -299.742352)
		(width 0.18288)
		(layer "In11.Cu")
		(net "M_H_CPU1_SA_DQ<18>")
	)
	(segment
		(start 158.062168 -297.272456)
		(end 156.818584 -297.272456)
		(width 0.18288)
		(layer "In11.Cu")
		(net "M_H_CPU1_SA_DQ<18>")
	)
	(segment
		(start 195.562474 -300.68012)
		(end 195.137278 -300.68012)
		(width 0.18288)
		(layer "In11.Cu")
		(net "M_H_CPU1_SA_DQ<18>")
	)
	(segment
		(start 171.160186 -302.887126)
		(end 169.874946 -301.601886)
		(width 0.18288)
		(layer "In11.Cu")
		(net "M_H_CPU1_SA_DQ<18>")
	)
	(segment
		(start 169.874946 -301.601886)
		(end 168.206166 -301.601886)
		(width 0.18288)
		(layer "In11.Cu")
		(net "M_H_CPU1_SA_DQ<18>")
	)
	(segment
		(start 126.989078 -272.140934)
		(end 126.974346 -272.14957)
		(width 0.088646)
		(layer "In11.Cu")
		(net "M_H_CPU1_SA_DQ<18>")
	)
	(segment
		(start 128.47955 -273.777456)
		(end 128.47066 -273.772376)
		(width 0.088646)
		(layer "In11.Cu")
		(net "M_H_CPU1_SA_DQ<18>")
	)
	(segment
		(start 172.294804 -303.994058)
		(end 172.098716 -303.79797)
		(width 0.18288)
		(layer "In11.Cu")
		(net "M_H_CPU1_SA_DQ<18>")
	)
	(segment
		(start 194.314572 -301.502826)
		(end 193.20764 -301.502826)
		(width 0.18288)
		(layer "In11.Cu")
		(net "M_H_CPU1_SA_DQ<18>")
	)
	(segment
		(start 195.137278 -300.68012)
		(end 194.314572 -301.502826)
		(width 0.18288)
		(layer "In11.Cu")
		(net "M_H_CPU1_SA_DQ<18>")
	)
	(segment
		(start 199.668638 -298.099226)
		(end 198.670926 -298.099226)
		(width 0.18288)
		(layer "In11.Cu")
		(net "M_H_CPU1_SA_DQ<18>")
	)
	(segment
		(start 150.290784 -290.744656)
		(end 150.290784 -288.872422)
		(width 0.18288)
		(layer "In11.Cu")
		(net "M_H_CPU1_SA_DQ<18>")
	)
	(segment
		(start 184.732168 -301.702724)
		(end 183.7309 -301.375826)
		(width 0.18288)
		(layer "In11.Cu")
		(net "M_H_CPU1_SA_DQ<18>")
	)
	(segment
		(start 166.784274 -301.350426)
		(end 165.842696 -301.159926)
		(width 0.18288)
		(layer "In11.Cu")
		(net "M_H_CPU1_SA_DQ<18>")
	)
	(segment
		(start 204.73797 -297.431714)
		(end 204.498448 -297.192192)
		(width 0.18288)
		(layer "In11.Cu")
		(net "M_H_CPU1_SA_DQ<18>")
	)
	(segment
		(start 192.415414 -302.295052)
		(end 192.415414 -302.941736)
		(width 0.18288)
		(layer "In11.Cu")
		(net "M_H_CPU1_SA_DQ<18>")
	)
	(segment
		(start 128.955292 -274.594828)
		(end 128.949196 -274.591272)
		(width 0.088646)
		(layer "In11.Cu")
		(net "M_H_CPU1_SA_DQ<18>")
	)
	(segment
		(start 138.75004 -276.801326)
		(end 137.839196 -276.801326)
		(width 0.088646)
		(layer "In11.Cu")
		(net "M_H_CPU1_SA_DQ<18>")
	)
	(segment
		(start 172.098716 -303.208182)
		(end 171.77766 -302.887126)
		(width 0.18288)
		(layer "In11.Cu")
		(net "M_H_CPU1_SA_DQ<18>")
	)
	(segment
		(start 139.252198 -277.58644)
		(end 139.252198 -277.303484)
		(width 0.088646)
		(layer "In11.Cu")
		(net "M_H_CPU1_SA_DQ<18>")
	)
	(segment
		(start 162.58159 -299.742352)
		(end 161.33064 -299.742352)
		(width 0.18288)
		(layer "In11.Cu")
		(net "M_H_CPU1_SA_DQ<18>")
	)
	(segment
		(start 156.818584 -297.272456)
		(end 150.290784 -290.744656)
		(width 0.18288)
		(layer "In11.Cu")
		(net "M_H_CPU1_SA_DQ<18>")
	)
	(segment
		(start 124.53747 -271.882362)
		(end 124.59462 -271.825212)
		(width 0.088646)
		(layer "In11.Cu")
		(net "M_H_CPU1_SA_DQ<18>")
	)
	(segment
		(start 159.435292 -299.005752)
		(end 159.013906 -298.584366)
		(width 0.18288)
		(layer "In11.Cu")
		(net "M_H_CPU1_SA_DQ<18>")
	)
	(segment
		(start 172.098716 -303.79797)
		(end 172.098716 -303.208182)
		(width 0.18288)
		(layer "In11.Cu")
		(net "M_H_CPU1_SA_DQ<18>")
	)
	(segment
		(start 160.59404 -299.005752)
		(end 159.435292 -299.005752)
		(width 0.18288)
		(layer "In11.Cu")
		(net "M_H_CPU1_SA_DQ<18>")
	)
	(segment
		(start 207.045814 -296.766742)
		(end 206.380842 -297.431714)
		(width 0.18288)
		(layer "In11.Cu")
		(net "M_H_CPU1_SA_DQ<18>")
	)
	(segment
		(start 188.430916 -301.442374)
		(end 187.161678 -301.442374)
		(width 0.18288)
		(layer "In11.Cu")
		(net "M_H_CPU1_SA_DQ<18>")
	)
	(segment
		(start 193.20764 -301.502826)
		(end 192.415414 -302.295052)
		(width 0.18288)
		(layer "In11.Cu")
		(net "M_H_CPU1_SA_DQ<18>")
	)
	(segment
		(start 129.41935 -275.405088)
		(end 129.41046 -275.400008)
		(width 0.088646)
		(layer "In11.Cu")
		(net "M_H_CPU1_SA_DQ<18>")
	)
	(segment
		(start 186.031378 -301.702724)
		(end 184.732168 -301.702724)
		(width 0.18288)
		(layer "In11.Cu")
		(net "M_H_CPU1_SA_DQ<18>")
	)
	(segment
		(start 173.996096 -303.143412)
		(end 173.14545 -303.994058)
		(width 0.18288)
		(layer "In11.Cu")
		(net "M_H_CPU1_SA_DQ<18>")
	)
	(segment
		(start 134.498334 -275.401786)
		(end 134.492746 -275.405088)
		(width 0.088646)
		(layer "In11.Cu")
		(net "M_H_CPU1_SA_DQ<18>")
	)
	(segment
		(start 128.761744 -274.266914)
		(end 128.761744 -274.25142)
		(width 0.088646)
		(layer "In11.Cu")
		(net "M_H_CPU1_SA_DQ<18>")
	)
	(segment
		(start 168.206166 -301.601886)
		(end 167.954706 -301.350426)
		(width 0.18288)
		(layer "In11.Cu")
		(net "M_H_CPU1_SA_DQ<18>")
	)
	(segment
		(start 197.756526 -299.013626)
		(end 197.228968 -299.013626)
		(width 0.18288)
		(layer "In11.Cu")
		(net "M_H_CPU1_SA_DQ<18>")
	)
	(segment
		(start 197.228968 -299.013626)
		(end 195.562474 -300.68012)
		(width 0.18288)
		(layer "In11.Cu")
		(net "M_H_CPU1_SA_DQ<18>")
	)
	(segment
		(start 136.532874 -275.495004)
		(end 136.11479 -275.495004)
		(width 0.088646)
		(layer "In11.Cu")
		(net "M_H_CPU1_SA_DQ<18>")
	)
	(segment
		(start 204.498448 -297.192192)
		(end 202.65771 -297.192192)
		(width 0.18288)
		(layer "In11.Cu")
		(net "M_H_CPU1_SA_DQ<18>")
	)
	(segment
		(start 192.214754 -303.142396)
		(end 190.453518 -303.142396)
		(width 0.18288)
		(layer "In11.Cu")
		(net "M_H_CPU1_SA_DQ<18>")
	)
	(segment
		(start 179.125626 -302.444404)
		(end 177.43805 -303.143412)
		(width 0.18288)
		(layer "In11.Cu")
		(net "M_H_CPU1_SA_DQ<18>")
	)
	(segment
		(start 180.08854 -302.444404)
		(end 179.125626 -302.444404)
		(width 0.18288)
		(layer "In11.Cu")
		(net "M_H_CPU1_SA_DQ<18>")
	)
	(segment
		(start 171.77766 -302.887126)
		(end 171.160186 -302.887126)
		(width 0.18288)
		(layer "In11.Cu")
		(net "M_H_CPU1_SA_DQ<18>")
	)
	(segment
		(start 131.688078 -275.396452)
		(end 131.673346 -275.405088)
		(width 0.088646)
		(layer "In11.Cu")
		(net "M_H_CPU1_SA_DQ<18>")
	)
	(segment
		(start 207.071214 -296.766742)
		(end 207.045814 -296.766742)
		(width 0.18288)
		(layer "In11.Cu")
		(net "M_H_CPU1_SA_DQ<18>")
	)
	(arc
		(start 128.292098 -273.453098)
		(mid 128.218107 -273.173532)
		(end 128.015492 -272.967196)
		(width 0.088646)
		(layer "In11.Cu")
		(net "M_H_CPU1_SA_DQ<18>")
	)
	(arc
		(start 125.649482 -272.143474)
		(mid 125.371304 -272.073782)
		(end 125.094746 -272.14957)
		(width 0.088646)
		(layer "In11.Cu")
		(net "M_H_CPU1_SA_DQ<18>")
	)
	(arc
		(start 128.47066 -273.772376)
		(mid 128.339746 -273.636016)
		(end 128.292098 -273.453098)
		(width 0.088646)
		(layer "In11.Cu")
		(net "M_H_CPU1_SA_DQ<18>")
	)
	(arc
		(start 131.673346 -275.405088)
		(mid 131.486148 -275.455231)
		(end 131.29895 -275.405088)
		(width 0.088646)
		(layer "In11.Cu")
		(net "M_H_CPU1_SA_DQ<18>")
	)
	(arc
		(start 135.05815 -275.405342)
		(mid 134.778722 -275.32945)
		(end 134.498334 -275.401786)
		(width 0.088646)
		(layer "In11.Cu")
		(net "M_H_CPU1_SA_DQ<18>")
	)
	(arc
		(start 130.35915 -275.405088)
		(mid 130.084921 -275.329163)
		(end 129.808478 -275.396452)
		(width 0.088646)
		(layer "In11.Cu")
		(net "M_H_CPU1_SA_DQ<18>")
	)
	(arc
		(start 127.821944 -272.63852)
		(mid 127.746329 -272.356256)
		(end 127.53975 -272.14957)
		(width 0.088646)
		(layer "In11.Cu")
		(net "M_H_CPU1_SA_DQ<18>")
	)
	(arc
		(start 128.761744 -274.25142)
		(mid 128.682374 -273.977686)
		(end 128.47955 -273.777456)
		(width 0.088646)
		(layer "In11.Cu")
		(net "M_H_CPU1_SA_DQ<18>")
	)
	(arc
		(start 134.11835 -275.405088)
		(mid 133.841537 -275.329252)
		(end 133.563106 -275.398992)
		(width 0.088646)
		(layer "In11.Cu")
		(net "M_H_CPU1_SA_DQ<18>")
	)
	(arc
		(start 124.71146 -272.14449)
		(mid 124.595651 -272.032561)
		(end 124.53747 -271.882362)
		(width 0.088646)
		(layer "In11.Cu")
		(net "M_H_CPU1_SA_DQ<18>")
	)
	(arc
		(start 126.59995 -272.14957)
		(mid 126.323137 -272.073734)
		(end 126.044706 -272.143474)
		(width 0.088646)
		(layer "In11.Cu")
		(net "M_H_CPU1_SA_DQ<18>")
	)
	(arc
		(start 129.793746 -275.405088)
		(mid 129.606548 -275.455231)
		(end 129.41935 -275.405088)
		(width 0.088646)
		(layer "In11.Cu")
		(net "M_H_CPU1_SA_DQ<18>")
	)
	(arc
		(start 129.41046 -275.400008)
		(mid 129.279546 -275.263648)
		(end 129.231898 -275.08073)
		(width 0.088646)
		(layer "In11.Cu")
		(net "M_H_CPU1_SA_DQ<18>")
	)
	(arc
		(start 135.432546 -275.405342)
		(mid 135.245348 -275.455485)
		(end 135.05815 -275.405342)
		(width 0.088646)
		(layer "In11.Cu")
		(net "M_H_CPU1_SA_DQ<18>")
	)
	(arc
		(start 125.094746 -272.14957)
		(mid 124.907548 -272.199713)
		(end 124.72035 -272.14957)
		(width 0.088646)
		(layer "In11.Cu")
		(net "M_H_CPU1_SA_DQ<18>")
	)
	(arc
		(start 134.492746 -275.405088)
		(mid 134.305548 -275.455231)
		(end 134.11835 -275.405088)
		(width 0.088646)
		(layer "In11.Cu")
		(net "M_H_CPU1_SA_DQ<18>")
	)
	(arc
		(start 133.178296 -275.405088)
		(mid 132.901737 -275.329379)
		(end 132.62356 -275.398992)
		(width 0.088646)
		(layer "In11.Cu")
		(net "M_H_CPU1_SA_DQ<18>")
	)
	(arc
		(start 129.231898 -275.08073)
		(mid 129.157907 -274.801164)
		(end 128.955292 -274.594828)
		(width 0.088646)
		(layer "In11.Cu")
		(net "M_H_CPU1_SA_DQ<18>")
	)
	(arc
		(start 127.53975 -272.14957)
		(mid 127.265521 -272.073645)
		(end 126.989078 -272.140934)
		(width 0.088646)
		(layer "In11.Cu")
		(net "M_H_CPU1_SA_DQ<18>")
	)
	(arc
		(start 128.940306 -274.586192)
		(mid 128.809392 -274.449832)
		(end 128.761744 -274.266914)
		(width 0.088646)
		(layer "In11.Cu")
		(net "M_H_CPU1_SA_DQ<18>")
	)
	(arc
		(start 132.23875 -275.405088)
		(mid 131.964521 -275.329163)
		(end 131.688078 -275.396452)
		(width 0.088646)
		(layer "In11.Cu")
		(net "M_H_CPU1_SA_DQ<18>")
	)
	(arc
		(start 130.733546 -275.405088)
		(mid 130.546348 -275.455231)
		(end 130.35915 -275.405088)
		(width 0.088646)
		(layer "In11.Cu")
		(net "M_H_CPU1_SA_DQ<18>")
	)
	(arc
		(start 128.000506 -272.95856)
		(mid 127.869592 -272.8222)
		(end 127.821944 -272.639282)
		(width 0.088646)
		(layer "In11.Cu")
		(net "M_H_CPU1_SA_DQ<18>")
	)
	(arc
		(start 126.034292 -272.14957)
		(mid 125.847238 -272.19962)
		(end 125.66015 -272.14957)
		(width 0.088646)
		(layer "In11.Cu")
		(net "M_H_CPU1_SA_DQ<18>")
	)
	(arc
		(start 133.552692 -275.405088)
		(mid 133.365494 -275.455231)
		(end 133.178296 -275.405088)
		(width 0.088646)
		(layer "In11.Cu")
		(net "M_H_CPU1_SA_DQ<18>")
	)
	(arc
		(start 126.974346 -272.14957)
		(mid 126.787148 -272.199713)
		(end 126.59995 -272.14957)
		(width 0.088646)
		(layer "In11.Cu")
		(net "M_H_CPU1_SA_DQ<18>")
	)
	(arc
		(start 136.11479 -275.495004)
		(mid 135.79731 -275.335427)
		(end 135.447278 -275.396706)
		(width 0.088646)
		(layer "In11.Cu")
		(net "M_H_CPU1_SA_DQ<18>")
	)
	(arc
		(start 131.29895 -275.405088)
		(mid 131.024721 -275.329163)
		(end 130.748278 -275.396452)
		(width 0.088646)
		(layer "In11.Cu")
		(net "M_H_CPU1_SA_DQ<18>")
	)
	(arc
		(start 132.613146 -275.405088)
		(mid 132.425948 -275.455231)
		(end 132.23875 -275.405088)
		(width 0.088646)
		(layer "In11.Cu")
		(net "M_H_CPU1_SA_DQ<18>")
	)
	(segment
		(start 206.971392 -295.491662)
		(end 206.626714 -295.491662)
		(width 0.20066)
		(layer "F.Cu")
		(net "M_H_CPU1_SA_DQ<17>")
	)
	(segment
		(start 210.028028 -295.916858)
		(end 209.596482 -295.485312)
		(width 0.20066)
		(layer "F.Cu")
		(net "M_H_CPU1_SA_DQ<17>")
	)
	(segment
		(start 209.596482 -295.485312)
		(end 209.186526 -295.485312)
		(width 0.20066)
		(layer "F.Cu")
		(net "M_H_CPU1_SA_DQ<17>")
	)
	(segment
		(start 123.497848 -271.011142)
		(end 123.497594 -271.011396)
		(width 0.20066)
		(layer "F.Cu")
		(net "M_H_CPU1_SA_DQ<17>")
	)
	(segment
		(start 209.180176 -295.491662)
		(end 206.991458 -295.491662)
		(width 0.1016)
		(layer "F.Cu")
		(net "M_H_CPU1_SA_DQ<17>")
	)
	(segment
		(start 211.619592 -295.916858)
		(end 210.028028 -295.916858)
		(width 0.20066)
		(layer "F.Cu")
		(net "M_H_CPU1_SA_DQ<17>")
	)
	(segment
		(start 206.320644 -296.16527)
		(end 205.84541 -296.16527)
		(width 0.20066)
		(layer "F.Cu")
		(net "M_H_CPU1_SA_DQ<17>")
	)
	(segment
		(start 209.186526 -295.485312)
		(end 209.180176 -295.491662)
		(width 0.1016)
		(layer "F.Cu")
		(net "M_H_CPU1_SA_DQ<17>")
	)
	(segment
		(start 206.626714 -295.491662)
		(end 206.508604 -295.609772)
		(width 0.20066)
		(layer "F.Cu")
		(net "M_H_CPU1_SA_DQ<17>")
	)
	(segment
		(start 206.991458 -295.491662)
		(end 206.971392 -295.491662)
		(width 0.101854)
		(layer "F.Cu")
		(net "M_H_CPU1_SA_DQ<17>")
	)
	(segment
		(start 123.497848 -270.475456)
		(end 123.497848 -271.011142)
		(width 0.20066)
		(layer "F.Cu")
		(net "M_H_CPU1_SA_DQ<17>")
	)
	(segment
		(start 205.84541 -296.16527)
		(end 205.596744 -295.916604)
		(width 0.20066)
		(layer "F.Cu")
		(net "M_H_CPU1_SA_DQ<17>")
	)
	(segment
		(start 206.508604 -295.609772)
		(end 206.508604 -295.97731)
		(width 0.20066)
		(layer "F.Cu")
		(net "M_H_CPU1_SA_DQ<17>")
	)
	(segment
		(start 204.076046 -295.916604)
		(end 202.971146 -295.916604)
		(width 0.20066)
		(layer "F.Cu")
		(net "M_H_CPU1_SA_DQ<17>")
	)
	(segment
		(start 211.619846 -295.916604)
		(end 211.619592 -295.916858)
		(width 0.20066)
		(layer "F.Cu")
		(net "M_H_CPU1_SA_DQ<17>")
	)
	(segment
		(start 206.508604 -295.97731)
		(end 206.320644 -296.16527)
		(width 0.20066)
		(layer "F.Cu")
		(net "M_H_CPU1_SA_DQ<17>")
	)
	(segment
		(start 205.596744 -295.916604)
		(end 204.076046 -295.916604)
		(width 0.20066)
		(layer "F.Cu")
		(net "M_H_CPU1_SA_DQ<17>")
	)
	(segment
		(start 128.949196 -272.314924)
		(end 128.934464 -272.32356)
		(width 0.088646)
		(layer "In11.Cu")
		(net "M_H_CPU1_SA_DQ<17>")
	)
	(segment
		(start 126.989078 -271.50949)
		(end 126.9746 -271.500854)
		(width 0.088646)
		(layer "In11.Cu")
		(net "M_H_CPU1_SA_DQ<17>")
	)
	(segment
		(start 167.088566 -300.447964)
		(end 166.726108 -300.297596)
		(width 0.18288)
		(layer "In11.Cu")
		(net "M_H_CPU1_SA_DQ<17>")
	)
	(segment
		(start 130.733546 -274.756372)
		(end 130.72745 -274.752816)
		(width 0.088646)
		(layer "In11.Cu")
		(net "M_H_CPU1_SA_DQ<17>")
	)
	(segment
		(start 125.665738 -271.497552)
		(end 125.659896 -271.500854)
		(width 0.088646)
		(layer "In11.Cu")
		(net "M_H_CPU1_SA_DQ<17>")
	)
	(segment
		(start 131.688078 -274.765008)
		(end 131.673346 -274.756372)
		(width 0.088646)
		(layer "In11.Cu")
		(net "M_H_CPU1_SA_DQ<17>")
	)
	(segment
		(start 173.587918 -302.292004)
		(end 171.405804 -302.292004)
		(width 0.18288)
		(layer "In11.Cu")
		(net "M_H_CPU1_SA_DQ<17>")
	)
	(segment
		(start 165.918134 -300.359318)
		(end 165.719252 -299.880782)
		(width 0.18288)
		(layer "In11.Cu")
		(net "M_H_CPU1_SA_DQ<17>")
	)
	(segment
		(start 177.738532 -301.655226)
		(end 177.525426 -301.44212)
		(width 0.18288)
		(layer "In11.Cu")
		(net "M_H_CPU1_SA_DQ<17>")
	)
	(segment
		(start 150.81504 -288.677858)
		(end 142.615158 -280.477976)
		(width 0.18288)
		(layer "In11.Cu")
		(net "M_H_CPU1_SA_DQ<17>")
	)
	(segment
		(start 165.220142 -299.674026)
		(end 164.571426 -299.674026)
		(width 0.18288)
		(layer "In11.Cu")
		(net "M_H_CPU1_SA_DQ<17>")
	)
	(segment
		(start 179.729892 -301.35449)
		(end 179.430426 -301.655226)
		(width 0.18288)
		(layer "In11.Cu")
		(net "M_H_CPU1_SA_DQ<17>")
	)
	(segment
		(start 165.719252 -299.880782)
		(end 165.220142 -299.674026)
		(width 0.18288)
		(layer "In11.Cu")
		(net "M_H_CPU1_SA_DQ<17>")
	)
	(segment
		(start 185.304684 -300.603666)
		(end 185.111644 -300.410626)
		(width 0.18288)
		(layer "In11.Cu")
		(net "M_H_CPU1_SA_DQ<17>")
	)
	(segment
		(start 174.597822 -301.2821)
		(end 173.587918 -302.292004)
		(width 0.18288)
		(layer "In11.Cu")
		(net "M_H_CPU1_SA_DQ<17>")
	)
	(segment
		(start 176.206404 -301.44212)
		(end 176.046384 -301.2821)
		(width 0.18288)
		(layer "In11.Cu")
		(net "M_H_CPU1_SA_DQ<17>")
	)
	(segment
		(start 199.026526 -297.007026)
		(end 198.137526 -297.896026)
		(width 0.18288)
		(layer "In11.Cu")
		(net "M_H_CPU1_SA_DQ<17>")
	)
	(segment
		(start 133.178296 -274.756372)
		(end 133.167882 -274.762468)
		(width 0.088646)
		(layer "In11.Cu")
		(net "M_H_CPU1_SA_DQ<17>")
	)
	(segment
		(start 163.89477 -299.828458)
		(end 162.108642 -298.04233)
		(width 0.18288)
		(layer "In11.Cu")
		(net "M_H_CPU1_SA_DQ<17>")
	)
	(segment
		(start 135.447278 -274.765262)
		(end 135.432546 -274.756626)
		(width 0.088646)
		(layer "In11.Cu")
		(net "M_H_CPU1_SA_DQ<17>")
	)
	(segment
		(start 164.571426 -299.674026)
		(end 164.416994 -299.828458)
		(width 0.18288)
		(layer "In11.Cu")
		(net "M_H_CPU1_SA_DQ<17>")
	)
	(segment
		(start 160.85693 -298.04233)
		(end 160.620202 -297.805602)
		(width 0.18288)
		(layer "In11.Cu")
		(net "M_H_CPU1_SA_DQ<17>")
	)
	(segment
		(start 129.332482 -272.320004)
		(end 129.323592 -272.314924)
		(width 0.088646)
		(layer "In11.Cu")
		(net "M_H_CPU1_SA_DQ<17>")
	)
	(segment
		(start 127.923036 -271.505934)
		(end 127.914146 -271.500854)
		(width 0.088646)
		(layer "In11.Cu")
		(net "M_H_CPU1_SA_DQ<17>")
	)
	(segment
		(start 194.302126 -300.563026)
		(end 193.256408 -300.563026)
		(width 0.18288)
		(layer "In11.Cu")
		(net "M_H_CPU1_SA_DQ<17>")
	)
	(segment
		(start 126.034292 -271.500854)
		(end 126.033784 -271.5006)
		(width 0.088646)
		(layer "In11.Cu")
		(net "M_H_CPU1_SA_DQ<17>")
	)
	(segment
		(start 181.803294 -300.639226)
		(end 181.08803 -301.35449)
		(width 0.18288)
		(layer "In11.Cu")
		(net "M_H_CPU1_SA_DQ<17>")
	)
	(segment
		(start 183.875426 -300.410626)
		(end 183.646826 -300.639226)
		(width 0.18288)
		(layer "In11.Cu")
		(net "M_H_CPU1_SA_DQ<17>")
	)
	(segment
		(start 130.748278 -274.765008)
		(end 130.733546 -274.756372)
		(width 0.088646)
		(layer "In11.Cu")
		(net "M_H_CPU1_SA_DQ<17>")
	)
	(segment
		(start 129.802636 -273.13382)
		(end 129.793746 -273.12874)
		(width 0.088646)
		(layer "In11.Cu")
		(net "M_H_CPU1_SA_DQ<17>")
	)
	(segment
		(start 142.615158 -280.282396)
		(end 139.645898 -277.313136)
		(width 0.18288)
		(layer "In11.Cu")
		(net "M_H_CPU1_SA_DQ<17>")
	)
	(segment
		(start 201.489818 -295.483534)
		(end 199.966326 -297.007026)
		(width 0.18288)
		(layer "In11.Cu")
		(net "M_H_CPU1_SA_DQ<17>")
	)
	(segment
		(start 125.659896 -271.500854)
		(end 125.654054 -271.50441)
		(width 0.088646)
		(layer "In11.Cu")
		(net "M_H_CPU1_SA_DQ<17>")
	)
	(segment
		(start 167.975026 -300.715426)
		(end 167.356028 -300.715426)
		(width 0.18288)
		(layer "In11.Cu")
		(net "M_H_CPU1_SA_DQ<17>")
	)
	(segment
		(start 191.370966 -301.63516)
		(end 191.370966 -301.95139)
		(width 0.18288)
		(layer "In11.Cu")
		(net "M_H_CPU1_SA_DQ<17>")
	)
	(segment
		(start 189.620906 -301.38497)
		(end 188.827918 -300.591982)
		(width 0.18288)
		(layer "In11.Cu")
		(net "M_H_CPU1_SA_DQ<17>")
	)
	(segment
		(start 190.474092 -301.38497)
		(end 189.620906 -301.38497)
		(width 0.18288)
		(layer "In11.Cu")
		(net "M_H_CPU1_SA_DQ<17>")
	)
	(segment
		(start 183.646826 -300.639226)
		(end 181.803294 -300.639226)
		(width 0.18288)
		(layer "In11.Cu")
		(net "M_H_CPU1_SA_DQ<17>")
	)
	(segment
		(start 123.533154 -271.011396)
		(end 123.497594 -271.011396)
		(width 0.088646)
		(layer "In11.Cu")
		(net "M_H_CPU1_SA_DQ<17>")
	)
	(segment
		(start 123.780296 -271.258538)
		(end 123.533154 -271.011396)
		(width 0.088646)
		(layer "In11.Cu")
		(net "M_H_CPU1_SA_DQ<17>")
	)
	(segment
		(start 129.981198 -273.468592)
		(end 129.981198 -273.453098)
		(width 0.088646)
		(layer "In11.Cu")
		(net "M_H_CPU1_SA_DQ<17>")
	)
	(segment
		(start 185.304684 -300.985682)
		(end 185.304684 -300.603666)
		(width 0.18288)
		(layer "In11.Cu")
		(net "M_H_CPU1_SA_DQ<17>")
	)
	(segment
		(start 150.81504 -290.536884)
		(end 150.81504 -288.677858)
		(width 0.18288)
		(layer "In11.Cu")
		(net "M_H_CPU1_SA_DQ<17>")
	)
	(segment
		(start 179.430426 -301.655226)
		(end 177.738532 -301.655226)
		(width 0.18288)
		(layer "In11.Cu")
		(net "M_H_CPU1_SA_DQ<17>")
	)
	(segment
		(start 186.008264 -300.603666)
		(end 186.008264 -300.985682)
		(width 0.18288)
		(layer "In11.Cu")
		(net "M_H_CPU1_SA_DQ<17>")
	)
	(segment
		(start 201.948034 -295.483534)
		(end 201.489818 -295.483534)
		(width 0.18288)
		(layer "In11.Cu")
		(net "M_H_CPU1_SA_DQ<17>")
	)
	(segment
		(start 138.854688 -276.521926)
		(end 138.156442 -276.521926)
		(width 0.088646)
		(layer "In11.Cu")
		(net "M_H_CPU1_SA_DQ<17>")
	)
	(segment
		(start 133.563106 -274.762468)
		(end 133.552692 -274.756372)
		(width 0.088646)
		(layer "In11.Cu")
		(net "M_H_CPU1_SA_DQ<17>")
	)
	(segment
		(start 186.008264 -300.985682)
		(end 185.815224 -301.178722)
		(width 0.18288)
		(layer "In11.Cu")
		(net "M_H_CPU1_SA_DQ<17>")
	)
	(segment
		(start 128.101598 -271.84731)
		(end 128.101598 -271.825212)
		(width 0.088646)
		(layer "In11.Cu")
		(net "M_H_CPU1_SA_DQ<17>")
	)
	(segment
		(start 191.564006 -301.44212)
		(end 191.370966 -301.63516)
		(width 0.18288)
		(layer "In11.Cu")
		(net "M_H_CPU1_SA_DQ<17>")
	)
	(segment
		(start 187.460382 -300.591982)
		(end 187.279026 -300.410626)
		(width 0.18288)
		(layer "In11.Cu")
		(net "M_H_CPU1_SA_DQ<17>")
	)
	(segment
		(start 191.177926 -302.14443)
		(end 190.860426 -302.14443)
		(width 0.18288)
		(layer "In11.Cu")
		(net "M_H_CPU1_SA_DQ<17>")
	)
	(segment
		(start 188.827918 -300.591982)
		(end 187.460382 -300.591982)
		(width 0.18288)
		(layer "In11.Cu")
		(net "M_H_CPU1_SA_DQ<17>")
	)
	(segment
		(start 142.615158 -280.477976)
		(end 142.615158 -280.282396)
		(width 0.18288)
		(layer "In11.Cu")
		(net "M_H_CPU1_SA_DQ<17>")
	)
	(segment
		(start 185.815224 -301.178722)
		(end 185.497724 -301.178722)
		(width 0.18288)
		(layer "In11.Cu")
		(net "M_H_CPU1_SA_DQ<17>")
	)
	(segment
		(start 186.201304 -300.410626)
		(end 186.008264 -300.603666)
		(width 0.18288)
		(layer "In11.Cu")
		(net "M_H_CPU1_SA_DQ<17>")
	)
	(segment
		(start 169.56532 -300.45152)
		(end 168.238932 -300.45152)
		(width 0.18288)
		(layer "In11.Cu")
		(net "M_H_CPU1_SA_DQ<17>")
	)
	(segment
		(start 181.08803 -301.35449)
		(end 179.729892 -301.35449)
		(width 0.18288)
		(layer "In11.Cu")
		(net "M_H_CPU1_SA_DQ<17>")
	)
	(segment
		(start 139.645898 -277.313136)
		(end 138.854688 -276.521926)
		(width 0.088646)
		(layer "In11.Cu")
		(net "M_H_CPU1_SA_DQ<17>")
	)
	(segment
		(start 130.272282 -273.947636)
		(end 130.263392 -273.942556)
		(width 0.088646)
		(layer "In11.Cu")
		(net "M_H_CPU1_SA_DQ<17>")
	)
	(segment
		(start 167.356028 -300.715426)
		(end 167.088566 -300.447964)
		(width 0.18288)
		(layer "In11.Cu")
		(net "M_H_CPU1_SA_DQ<17>")
	)
	(segment
		(start 138.156442 -276.521926)
		(end 136.450324 -274.815808)
		(width 0.088646)
		(layer "In11.Cu")
		(net "M_H_CPU1_SA_DQ<17>")
	)
	(segment
		(start 199.966326 -297.007026)
		(end 199.026526 -297.007026)
		(width 0.18288)
		(layer "In11.Cu")
		(net "M_H_CPU1_SA_DQ<17>")
	)
	(segment
		(start 195.851526 -299.572426)
		(end 195.292726 -299.572426)
		(width 0.18288)
		(layer "In11.Cu")
		(net "M_H_CPU1_SA_DQ<17>")
	)
	(segment
		(start 168.238932 -300.45152)
		(end 167.975026 -300.715426)
		(width 0.18288)
		(layer "In11.Cu")
		(net "M_H_CPU1_SA_DQ<17>")
	)
	(segment
		(start 191.370966 -301.95139)
		(end 191.177926 -302.14443)
		(width 0.18288)
		(layer "In11.Cu")
		(net "M_H_CPU1_SA_DQ<17>")
	)
	(segment
		(start 159.53105 -297.805602)
		(end 158.024576 -296.299128)
		(width 0.18288)
		(layer "In11.Cu")
		(net "M_H_CPU1_SA_DQ<17>")
	)
	(segment
		(start 193.256408 -300.563026)
		(end 192.377314 -301.44212)
		(width 0.18288)
		(layer "In11.Cu")
		(net "M_H_CPU1_SA_DQ<17>")
	)
	(segment
		(start 158.024576 -296.299128)
		(end 156.577284 -296.299128)
		(width 0.18288)
		(layer "In11.Cu")
		(net "M_H_CPU1_SA_DQ<17>")
	)
	(segment
		(start 202.971146 -295.916604)
		(end 202.87996 -296.00779)
		(width 0.18288)
		(layer "In11.Cu")
		(net "M_H_CPU1_SA_DQ<17>")
	)
	(segment
		(start 197.527926 -297.896026)
		(end 195.851526 -299.572426)
		(width 0.18288)
		(layer "In11.Cu")
		(net "M_H_CPU1_SA_DQ<17>")
	)
	(segment
		(start 160.620202 -297.805602)
		(end 159.53105 -297.805602)
		(width 0.18288)
		(layer "In11.Cu")
		(net "M_H_CPU1_SA_DQ<17>")
	)
	(segment
		(start 166.247826 -300.496224)
		(end 165.918134 -300.359318)
		(width 0.18288)
		(layer "In11.Cu")
		(net "M_H_CPU1_SA_DQ<17>")
	)
	(segment
		(start 198.137526 -297.896026)
		(end 197.527926 -297.896026)
		(width 0.18288)
		(layer "In11.Cu")
		(net "M_H_CPU1_SA_DQ<17>")
	)
	(segment
		(start 177.525426 -301.44212)
		(end 176.206404 -301.44212)
		(width 0.18288)
		(layer "In11.Cu")
		(net "M_H_CPU1_SA_DQ<17>")
	)
	(segment
		(start 190.667386 -301.95139)
		(end 190.667386 -301.578264)
		(width 0.18288)
		(layer "In11.Cu")
		(net "M_H_CPU1_SA_DQ<17>")
	)
	(segment
		(start 202.47229 -296.00779)
		(end 201.948034 -295.483534)
		(width 0.18288)
		(layer "In11.Cu")
		(net "M_H_CPU1_SA_DQ<17>")
	)
	(segment
		(start 156.577284 -296.299128)
		(end 150.81504 -290.536884)
		(width 0.18288)
		(layer "In11.Cu")
		(net "M_H_CPU1_SA_DQ<17>")
	)
	(segment
		(start 176.046384 -301.2821)
		(end 174.597822 -301.2821)
		(width 0.18288)
		(layer "In11.Cu")
		(net "M_H_CPU1_SA_DQ<17>")
	)
	(segment
		(start 190.667386 -301.578264)
		(end 190.474092 -301.38497)
		(width 0.18288)
		(layer "In11.Cu")
		(net "M_H_CPU1_SA_DQ<17>")
	)
	(segment
		(start 190.860426 -302.14443)
		(end 190.667386 -301.95139)
		(width 0.18288)
		(layer "In11.Cu")
		(net "M_H_CPU1_SA_DQ<17>")
	)
	(segment
		(start 124.807472 -271.423892)
		(end 124.292614 -271.423892)
		(width 0.088646)
		(layer "In11.Cu")
		(net "M_H_CPU1_SA_DQ<17>")
	)
	(segment
		(start 126.044706 -271.50695)
		(end 126.034292 -271.500854)
		(width 0.088646)
		(layer "In11.Cu")
		(net "M_H_CPU1_SA_DQ<17>")
	)
	(segment
		(start 185.497724 -301.178722)
		(end 185.304684 -300.985682)
		(width 0.18288)
		(layer "In11.Cu")
		(net "M_H_CPU1_SA_DQ<17>")
	)
	(segment
		(start 166.726108 -300.297596)
		(end 166.247826 -300.496224)
		(width 0.18288)
		(layer "In11.Cu")
		(net "M_H_CPU1_SA_DQ<17>")
	)
	(segment
		(start 185.111644 -300.410626)
		(end 183.875426 -300.410626)
		(width 0.18288)
		(layer "In11.Cu")
		(net "M_H_CPU1_SA_DQ<17>")
	)
	(segment
		(start 192.377314 -301.44212)
		(end 191.564006 -301.44212)
		(width 0.18288)
		(layer "In11.Cu")
		(net "M_H_CPU1_SA_DQ<17>")
	)
	(segment
		(start 164.416994 -299.828458)
		(end 163.89477 -299.828458)
		(width 0.18288)
		(layer "In11.Cu")
		(net "M_H_CPU1_SA_DQ<17>")
	)
	(segment
		(start 134.512812 -274.768056)
		(end 134.492746 -274.756372)
		(width 0.088646)
		(layer "In11.Cu")
		(net "M_H_CPU1_SA_DQ<17>")
	)
	(segment
		(start 195.292726 -299.572426)
		(end 194.302126 -300.563026)
		(width 0.18288)
		(layer "In11.Cu")
		(net "M_H_CPU1_SA_DQ<17>")
	)
	(segment
		(start 202.87996 -296.00779)
		(end 202.47229 -296.00779)
		(width 0.18288)
		(layer "In11.Cu")
		(net "M_H_CPU1_SA_DQ<17>")
	)
	(segment
		(start 162.108642 -298.04233)
		(end 160.85693 -298.04233)
		(width 0.18288)
		(layer "In11.Cu")
		(net "M_H_CPU1_SA_DQ<17>")
	)
	(segment
		(start 187.279026 -300.410626)
		(end 186.201304 -300.410626)
		(width 0.18288)
		(layer "In11.Cu")
		(net "M_H_CPU1_SA_DQ<17>")
	)
	(segment
		(start 129.793746 -273.12874)
		(end 129.78765 -273.125184)
		(width 0.088646)
		(layer "In11.Cu")
		(net "M_H_CPU1_SA_DQ<17>")
	)
	(segment
		(start 171.405804 -302.292004)
		(end 169.56532 -300.45152)
		(width 0.18288)
		(layer "In11.Cu")
		(net "M_H_CPU1_SA_DQ<17>")
	)
	(arc
		(start 132.613146 -274.756372)
		(mid 132.425948 -274.706229)
		(end 132.23875 -274.756372)
		(width 0.088646)
		(layer "In11.Cu")
		(net "M_H_CPU1_SA_DQ<17>")
	)
	(arc
		(start 133.167882 -274.762468)
		(mid 132.889704 -274.832191)
		(end 132.613146 -274.756372)
		(width 0.088646)
		(layer "In11.Cu")
		(net "M_H_CPU1_SA_DQ<17>")
	)
	(arc
		(start 130.72745 -274.752816)
		(mid 130.524863 -274.546465)
		(end 130.450844 -274.266914)
		(width 0.088646)
		(layer "In11.Cu")
		(net "M_H_CPU1_SA_DQ<17>")
	)
	(arc
		(start 126.033784 -271.5006)
		(mid 125.850166 -271.450757)
		(end 125.665738 -271.497552)
		(width 0.088646)
		(layer "In11.Cu")
		(net "M_H_CPU1_SA_DQ<17>")
	)
	(arc
		(start 129.78765 -273.125184)
		(mid 129.585063 -272.918833)
		(end 129.511044 -272.639282)
		(width 0.088646)
		(layer "In11.Cu")
		(net "M_H_CPU1_SA_DQ<17>")
	)
	(arc
		(start 134.492746 -274.756372)
		(mid 134.305548 -274.706229)
		(end 134.11835 -274.756372)
		(width 0.088646)
		(layer "In11.Cu")
		(net "M_H_CPU1_SA_DQ<17>")
	)
	(arc
		(start 123.851162 -271.311878)
		(mid 123.813807 -271.287761)
		(end 123.780296 -271.258538)
		(width 0.088646)
		(layer "In11.Cu")
		(net "M_H_CPU1_SA_DQ<17>")
	)
	(arc
		(start 127.53975 -271.500854)
		(mid 127.265551 -271.576689)
		(end 126.989078 -271.50949)
		(width 0.088646)
		(layer "In11.Cu")
		(net "M_H_CPU1_SA_DQ<17>")
	)
	(arc
		(start 124.292614 -271.423892)
		(mid 124.064864 -271.395555)
		(end 123.851162 -271.311878)
		(width 0.088646)
		(layer "In11.Cu")
		(net "M_H_CPU1_SA_DQ<17>")
	)
	(arc
		(start 136.372346 -274.756626)
		(mid 136.185148 -274.706483)
		(end 135.99795 -274.756626)
		(width 0.088646)
		(layer "In11.Cu")
		(net "M_H_CPU1_SA_DQ<17>")
	)
	(arc
		(start 126.9746 -271.500854)
		(mid 126.787292 -271.450711)
		(end 126.59995 -271.500854)
		(width 0.088646)
		(layer "In11.Cu")
		(net "M_H_CPU1_SA_DQ<17>")
	)
	(arc
		(start 136.450324 -274.815808)
		(mid 136.413274 -274.783662)
		(end 136.372346 -274.756626)
		(width 0.088646)
		(layer "In11.Cu")
		(net "M_H_CPU1_SA_DQ<17>")
	)
	(arc
		(start 131.29895 -274.756372)
		(mid 131.024751 -274.832207)
		(end 130.748278 -274.765008)
		(width 0.088646)
		(layer "In11.Cu")
		(net "M_H_CPU1_SA_DQ<17>")
	)
	(arc
		(start 129.981198 -273.453098)
		(mid 129.933519 -273.270198)
		(end 129.802636 -273.13382)
		(width 0.088646)
		(layer "In11.Cu")
		(net "M_H_CPU1_SA_DQ<17>")
	)
	(arc
		(start 128.101598 -271.825212)
		(mid 128.053919 -271.642312)
		(end 127.923036 -271.505934)
		(width 0.088646)
		(layer "In11.Cu")
		(net "M_H_CPU1_SA_DQ<17>")
	)
	(arc
		(start 133.552692 -274.756372)
		(mid 133.365494 -274.706229)
		(end 133.178296 -274.756372)
		(width 0.088646)
		(layer "In11.Cu")
		(net "M_H_CPU1_SA_DQ<17>")
	)
	(arc
		(start 135.05815 -274.756626)
		(mid 134.786961 -274.832373)
		(end 134.512812 -274.768056)
		(width 0.088646)
		(layer "In11.Cu")
		(net "M_H_CPU1_SA_DQ<17>")
	)
	(arc
		(start 127.914146 -271.500854)
		(mid 127.726948 -271.450711)
		(end 127.53975 -271.500854)
		(width 0.088646)
		(layer "In11.Cu")
		(net "M_H_CPU1_SA_DQ<17>")
	)
	(arc
		(start 128.383792 -272.314924)
		(mid 128.18251 -272.117437)
		(end 128.101598 -271.84731)
		(width 0.088646)
		(layer "In11.Cu")
		(net "M_H_CPU1_SA_DQ<17>")
	)
	(arc
		(start 129.511044 -272.639282)
		(mid 129.463365 -272.456382)
		(end 129.332482 -272.320004)
		(width 0.088646)
		(layer "In11.Cu")
		(net "M_H_CPU1_SA_DQ<17>")
	)
	(arc
		(start 128.934464 -272.32356)
		(mid 128.658023 -272.390726)
		(end 128.383792 -272.314924)
		(width 0.088646)
		(layer "In11.Cu")
		(net "M_H_CPU1_SA_DQ<17>")
	)
	(arc
		(start 126.59995 -271.500854)
		(mid 126.323137 -271.576724)
		(end 126.044706 -271.50695)
		(width 0.088646)
		(layer "In11.Cu")
		(net "M_H_CPU1_SA_DQ<17>")
	)
	(arc
		(start 130.263392 -273.942556)
		(mid 130.060569 -273.742325)
		(end 129.981198 -273.468592)
		(width 0.088646)
		(layer "In11.Cu")
		(net "M_H_CPU1_SA_DQ<17>")
	)
	(arc
		(start 129.323592 -272.314924)
		(mid 129.136394 -272.264781)
		(end 128.949196 -272.314924)
		(width 0.088646)
		(layer "In11.Cu")
		(net "M_H_CPU1_SA_DQ<17>")
	)
	(arc
		(start 135.432546 -274.756626)
		(mid 135.245348 -274.706483)
		(end 135.05815 -274.756626)
		(width 0.088646)
		(layer "In11.Cu")
		(net "M_H_CPU1_SA_DQ<17>")
	)
	(arc
		(start 125.654054 -271.50441)
		(mid 125.373919 -271.576693)
		(end 125.094746 -271.500854)
		(width 0.088646)
		(layer "In11.Cu")
		(net "M_H_CPU1_SA_DQ<17>")
	)
	(arc
		(start 125.094746 -271.500854)
		(mid 124.95618 -271.443433)
		(end 124.807472 -271.423892)
		(width 0.088646)
		(layer "In11.Cu")
		(net "M_H_CPU1_SA_DQ<17>")
	)
	(arc
		(start 134.11835 -274.756372)
		(mid 133.841537 -274.832242)
		(end 133.563106 -274.762468)
		(width 0.088646)
		(layer "In11.Cu")
		(net "M_H_CPU1_SA_DQ<17>")
	)
	(arc
		(start 135.99795 -274.756626)
		(mid 135.723721 -274.832551)
		(end 135.447278 -274.765262)
		(width 0.088646)
		(layer "In11.Cu")
		(net "M_H_CPU1_SA_DQ<17>")
	)
	(arc
		(start 132.23875 -274.756372)
		(mid 131.964551 -274.832207)
		(end 131.688078 -274.765008)
		(width 0.088646)
		(layer "In11.Cu")
		(net "M_H_CPU1_SA_DQ<17>")
	)
	(arc
		(start 130.450844 -274.266914)
		(mid 130.403165 -274.084014)
		(end 130.272282 -273.947636)
		(width 0.088646)
		(layer "In11.Cu")
		(net "M_H_CPU1_SA_DQ<17>")
	)
	(arc
		(start 131.673346 -274.756372)
		(mid 131.486148 -274.706229)
		(end 131.29895 -274.756372)
		(width 0.088646)
		(layer "In11.Cu")
		(net "M_H_CPU1_SA_DQ<17>")
	)
	(segment
		(start 205.596744 -297.616626)
		(end 204.076046 -297.616626)
		(width 0.20066)
		(layer "F.Cu")
		(net "M_H_CPU1_SA_DQ<16>")
	)
	(segment
		(start 206.320644 -297.865292)
		(end 205.84541 -297.865292)
		(width 0.20066)
		(layer "F.Cu")
		(net "M_H_CPU1_SA_DQ<16>")
	)
	(segment
		(start 209.186526 -297.185334)
		(end 209.180176 -297.191684)
		(width 0.1016)
		(layer "F.Cu")
		(net "M_H_CPU1_SA_DQ<16>")
	)
	(segment
		(start 204.076046 -297.616626)
		(end 202.971146 -297.616626)
		(width 0.20066)
		(layer "F.Cu")
		(net "M_H_CPU1_SA_DQ<16>")
	)
	(segment
		(start 211.619846 -297.616626)
		(end 211.619592 -297.61688)
		(width 0.20066)
		(layer "F.Cu")
		(net "M_H_CPU1_SA_DQ<16>")
	)
	(segment
		(start 206.508604 -297.309794)
		(end 206.508604 -297.677332)
		(width 0.20066)
		(layer "F.Cu")
		(net "M_H_CPU1_SA_DQ<16>")
	)
	(segment
		(start 123.967494 -271.289272)
		(end 123.967748 -271.825212)
		(width 0.20066)
		(layer "F.Cu")
		(net "M_H_CPU1_SA_DQ<16>")
	)
	(segment
		(start 206.971392 -297.191684)
		(end 206.626714 -297.191684)
		(width 0.20066)
		(layer "F.Cu")
		(net "M_H_CPU1_SA_DQ<16>")
	)
	(segment
		(start 209.596482 -297.185334)
		(end 209.186526 -297.185334)
		(width 0.20066)
		(layer "F.Cu")
		(net "M_H_CPU1_SA_DQ<16>")
	)
	(segment
		(start 205.84541 -297.865292)
		(end 205.596744 -297.616626)
		(width 0.20066)
		(layer "F.Cu")
		(net "M_H_CPU1_SA_DQ<16>")
	)
	(segment
		(start 209.180176 -297.191684)
		(end 207.018382 -297.191684)
		(width 0.1016)
		(layer "F.Cu")
		(net "M_H_CPU1_SA_DQ<16>")
	)
	(segment
		(start 206.508604 -297.677332)
		(end 206.320644 -297.865292)
		(width 0.20066)
		(layer "F.Cu")
		(net "M_H_CPU1_SA_DQ<16>")
	)
	(segment
		(start 207.018382 -297.191684)
		(end 206.971392 -297.191684)
		(width 0.101854)
		(layer "F.Cu")
		(net "M_H_CPU1_SA_DQ<16>")
	)
	(segment
		(start 206.626714 -297.191684)
		(end 206.508604 -297.309794)
		(width 0.20066)
		(layer "F.Cu")
		(net "M_H_CPU1_SA_DQ<16>")
	)
	(segment
		(start 211.619592 -297.61688)
		(end 210.028028 -297.61688)
		(width 0.20066)
		(layer "F.Cu")
		(net "M_H_CPU1_SA_DQ<16>")
	)
	(segment
		(start 210.028028 -297.61688)
		(end 209.596482 -297.185334)
		(width 0.20066)
		(layer "F.Cu")
		(net "M_H_CPU1_SA_DQ<16>")
	)
	(segment
		(start 166.675562 -301.93107)
		(end 166.121334 -301.93107)
		(width 0.18288)
		(layer "In11.Cu")
		(net "M_H_CPU1_SA_DQ<16>")
	)
	(segment
		(start 171.873164 -304.841148)
		(end 171.450762 -304.418746)
		(width 0.18288)
		(layer "In11.Cu")
		(net "M_H_CPU1_SA_DQ<16>")
	)
	(segment
		(start 159.12465 -299.546264)
		(end 158.444946 -298.86656)
		(width 0.18288)
		(layer "In11.Cu")
		(net "M_H_CPU1_SA_DQ<16>")
	)
	(segment
		(start 184.075324 -302.674528)
		(end 181.198012 -302.674528)
		(width 0.18288)
		(layer "In11.Cu")
		(net "M_H_CPU1_SA_DQ<16>")
	)
	(segment
		(start 188.705998 -302.292004)
		(end 184.457848 -302.292004)
		(width 0.18288)
		(layer "In11.Cu")
		(net "M_H_CPU1_SA_DQ<16>")
	)
	(segment
		(start 139.460478 -278.25954)
		(end 138.952478 -277.75154)
		(width 0.088646)
		(layer "In11.Cu")
		(net "M_H_CPU1_SA_DQ<16>")
	)
	(segment
		(start 201.363072 -297.162728)
		(end 199.886316 -298.639484)
		(width 0.18288)
		(layer "In11.Cu")
		(net "M_H_CPU1_SA_DQ<16>")
	)
	(segment
		(start 202.971146 -297.77309)
		(end 202.911202 -297.91787)
		(width 0.18288)
		(layer "In11.Cu")
		(net "M_H_CPU1_SA_DQ<16>")
	)
	(segment
		(start 202.480418 -297.928284)
		(end 202.191366 -297.639232)
		(width 0.18288)
		(layer "In11.Cu")
		(net "M_H_CPU1_SA_DQ<16>")
	)
	(segment
		(start 178.719734 -303.239678)
		(end 177.966878 -303.992534)
		(width 0.18288)
		(layer "In11.Cu")
		(net "M_H_CPU1_SA_DQ<16>")
	)
	(segment
		(start 158.444946 -298.432982)
		(end 157.942788 -297.930824)
		(width 0.18288)
		(layer "In11.Cu")
		(net "M_H_CPU1_SA_DQ<16>")
	)
	(segment
		(start 202.827128 -298.001944)
		(end 202.658218 -298.001944)
		(width 0.18288)
		(layer "In11.Cu")
		(net "M_H_CPU1_SA_DQ<16>")
	)
	(segment
		(start 135.527796 -275.570442)
		(end 135.513064 -275.579078)
		(width 0.088646)
		(layer "In11.Cu")
		(net "M_H_CPU1_SA_DQ<16>")
	)
	(segment
		(start 202.191366 -297.462194)
		(end 201.8919 -297.162728)
		(width 0.18288)
		(layer "In11.Cu")
		(net "M_H_CPU1_SA_DQ<16>")
	)
	(segment
		(start 149.762718 -290.957254)
		(end 149.762718 -289.117024)
		(width 0.18288)
		(layer "In11.Cu")
		(net "M_H_CPU1_SA_DQ<16>")
	)
	(segment
		(start 134.587996 -275.570442)
		(end 134.573264 -275.579078)
		(width 0.088646)
		(layer "In11.Cu")
		(net "M_H_CPU1_SA_DQ<16>")
	)
	(segment
		(start 202.191366 -297.639232)
		(end 202.191366 -297.462194)
		(width 0.18288)
		(layer "In11.Cu")
		(net "M_H_CPU1_SA_DQ<16>")
	)
	(segment
		(start 161.289492 -300.592236)
		(end 160.24352 -299.546264)
		(width 0.18288)
		(layer "In11.Cu")
		(net "M_H_CPU1_SA_DQ<16>")
	)
	(segment
		(start 192.937638 -303.238662)
		(end 192.184274 -303.992026)
		(width 0.18288)
		(layer "In11.Cu")
		(net "M_H_CPU1_SA_DQ<16>")
	)
	(segment
		(start 164.221668 -301.985426)
		(end 162.828478 -300.592236)
		(width 0.18288)
		(layer "In11.Cu")
		(net "M_H_CPU1_SA_DQ<16>")
	)
	(segment
		(start 158.444946 -298.86656)
		(end 158.444946 -298.432982)
		(width 0.18288)
		(layer "In11.Cu")
		(net "M_H_CPU1_SA_DQ<16>")
	)
	(segment
		(start 198.968868 -298.639484)
		(end 198.010526 -299.597826)
		(width 0.18288)
		(layer "In11.Cu")
		(net "M_H_CPU1_SA_DQ<16>")
	)
	(segment
		(start 131.768596 -275.570442)
		(end 131.753864 -275.579078)
		(width 0.088646)
		(layer "In11.Cu")
		(net "M_H_CPU1_SA_DQ<16>")
	)
	(segment
		(start 136.419336 -275.686266)
		(end 136.036812 -275.686266)
		(width 0.088646)
		(layer "In11.Cu")
		(net "M_H_CPU1_SA_DQ<16>")
	)
	(segment
		(start 192.937638 -302.818038)
		(end 192.937638 -303.238662)
		(width 0.18288)
		(layer "In11.Cu")
		(net "M_H_CPU1_SA_DQ<16>")
	)
	(segment
		(start 162.828478 -300.592236)
		(end 161.289492 -300.592236)
		(width 0.18288)
		(layer "In11.Cu")
		(net "M_H_CPU1_SA_DQ<16>")
	)
	(segment
		(start 167.110918 -302.366426)
		(end 166.675562 -301.93107)
		(width 0.18288)
		(layer "In11.Cu")
		(net "M_H_CPU1_SA_DQ<16>")
	)
	(segment
		(start 189.287912 -303.317656)
		(end 189.287912 -302.873918)
		(width 0.18288)
		(layer "In11.Cu")
		(net "M_H_CPU1_SA_DQ<16>")
	)
	(segment
		(start 177.966878 -303.992534)
		(end 175.890174 -303.992534)
		(width 0.18288)
		(layer "In11.Cu")
		(net "M_H_CPU1_SA_DQ<16>")
	)
	(segment
		(start 171.450762 -304.418746)
		(end 171.450762 -304.119026)
		(width 0.18288)
		(layer "In11.Cu")
		(net "M_H_CPU1_SA_DQ<16>")
	)
	(segment
		(start 201.8919 -297.162728)
		(end 201.363072 -297.162728)
		(width 0.18288)
		(layer "In11.Cu")
		(net "M_H_CPU1_SA_DQ<16>")
	)
	(segment
		(start 128.853946 -274.756372)
		(end 128.851152 -274.754848)
		(width 0.088646)
		(layer "In11.Cu")
		(net "M_H_CPU1_SA_DQ<16>")
	)
	(segment
		(start 128.851152 -274.754848)
		(end 128.84785 -274.752816)
		(width 0.088646)
		(layer "In11.Cu")
		(net "M_H_CPU1_SA_DQ<16>")
	)
	(segment
		(start 174.182024 -303.886108)
		(end 173.226984 -304.841148)
		(width 0.18288)
		(layer "In11.Cu")
		(net "M_H_CPU1_SA_DQ<16>")
	)
	(segment
		(start 125.19025 -272.314924)
		(end 125.189996 -272.314924)
		(width 0.088646)
		(layer "In11.Cu")
		(net "M_H_CPU1_SA_DQ<16>")
	)
	(segment
		(start 197.451726 -299.597826)
		(end 195.724526 -301.325026)
		(width 0.18288)
		(layer "In11.Cu")
		(net "M_H_CPU1_SA_DQ<16>")
	)
	(segment
		(start 194.581526 -302.036226)
		(end 193.71945 -302.036226)
		(width 0.18288)
		(layer "In11.Cu")
		(net "M_H_CPU1_SA_DQ<16>")
	)
	(segment
		(start 124.3457 -271.890236)
		(end 124.280676 -271.825212)
		(width 0.088646)
		(layer "In11.Cu")
		(net "M_H_CPU1_SA_DQ<16>")
	)
	(segment
		(start 138.952478 -277.397464)
		(end 138.58494 -277.029926)
		(width 0.088646)
		(layer "In11.Cu")
		(net "M_H_CPU1_SA_DQ<16>")
	)
	(segment
		(start 129.888996 -275.570442)
		(end 129.878582 -275.576538)
		(width 0.088646)
		(layer "In11.Cu")
		(net "M_H_CPU1_SA_DQ<16>")
	)
	(segment
		(start 127.914146 -273.12874)
		(end 127.911352 -273.127216)
		(width 0.088646)
		(layer "In11.Cu")
		(net "M_H_CPU1_SA_DQ<16>")
	)
	(segment
		(start 138.58494 -277.029926)
		(end 137.762996 -277.029926)
		(width 0.088646)
		(layer "In11.Cu")
		(net "M_H_CPU1_SA_DQ<16>")
	)
	(segment
		(start 127.911352 -273.127216)
		(end 127.90805 -273.125184)
		(width 0.088646)
		(layer "In11.Cu")
		(net "M_H_CPU1_SA_DQ<16>")
	)
	(segment
		(start 139.630658 -278.66975)
		(end 139.460478 -278.49957)
		(width 0.088646)
		(layer "In11.Cu")
		(net "M_H_CPU1_SA_DQ<16>")
	)
	(segment
		(start 192.184274 -303.992026)
		(end 190.40602 -303.992026)
		(width 0.18288)
		(layer "In11.Cu")
		(net "M_H_CPU1_SA_DQ<16>")
	)
	(segment
		(start 190.00724 -303.593246)
		(end 189.563502 -303.593246)
		(width 0.18288)
		(layer "In11.Cu")
		(net "M_H_CPU1_SA_DQ<16>")
	)
	(segment
		(start 149.762718 -289.117024)
		(end 141.627098 -280.981404)
		(width 0.18288)
		(layer "In11.Cu")
		(net "M_H_CPU1_SA_DQ<16>")
	)
	(segment
		(start 179.380388 -302.96612)
		(end 178.719734 -303.239678)
		(width 0.18288)
		(layer "In11.Cu")
		(net "M_H_CPU1_SA_DQ<16>")
	)
	(segment
		(start 189.287912 -302.873918)
		(end 188.705998 -302.292004)
		(width 0.18288)
		(layer "In11.Cu")
		(net "M_H_CPU1_SA_DQ<16>")
	)
	(segment
		(start 166.121334 -301.93107)
		(end 165.685978 -302.366426)
		(width 0.18288)
		(layer "In11.Cu")
		(net "M_H_CPU1_SA_DQ<16>")
	)
	(segment
		(start 165.685978 -302.366426)
		(end 165.104826 -302.366426)
		(width 0.18288)
		(layer "In11.Cu")
		(net "M_H_CPU1_SA_DQ<16>")
	)
	(segment
		(start 124.3457 -272.078704)
		(end 124.3457 -271.890236)
		(width 0.088646)
		(layer "In11.Cu")
		(net "M_H_CPU1_SA_DQ<16>")
	)
	(segment
		(start 195.724526 -301.325026)
		(end 195.292726 -301.325026)
		(width 0.18288)
		(layer "In11.Cu")
		(net "M_H_CPU1_SA_DQ<16>")
	)
	(segment
		(start 175.783748 -303.886108)
		(end 174.182024 -303.886108)
		(width 0.18288)
		(layer "In11.Cu")
		(net "M_H_CPU1_SA_DQ<16>")
	)
	(segment
		(start 175.890174 -303.992534)
		(end 175.783748 -303.886108)
		(width 0.18288)
		(layer "In11.Cu")
		(net "M_H_CPU1_SA_DQ<16>")
	)
	(segment
		(start 127.452882 -272.320004)
		(end 127.443992 -272.314924)
		(width 0.088646)
		(layer "In11.Cu")
		(net "M_H_CPU1_SA_DQ<16>")
	)
	(segment
		(start 129.041398 -275.100034)
		(end 129.041398 -275.08073)
		(width 0.088646)
		(layer "In11.Cu")
		(net "M_H_CPU1_SA_DQ<16>")
	)
	(segment
		(start 171.450762 -304.119026)
		(end 169.698162 -302.366426)
		(width 0.18288)
		(layer "In11.Cu")
		(net "M_H_CPU1_SA_DQ<16>")
	)
	(segment
		(start 124.280676 -271.825212)
		(end 123.967748 -271.825212)
		(width 0.088646)
		(layer "In11.Cu")
		(net "M_H_CPU1_SA_DQ<16>")
	)
	(segment
		(start 128.862836 -274.761452)
		(end 128.853946 -274.756372)
		(width 0.088646)
		(layer "In11.Cu")
		(net "M_H_CPU1_SA_DQ<16>")
	)
	(segment
		(start 173.226984 -304.841148)
		(end 171.873164 -304.841148)
		(width 0.18288)
		(layer "In11.Cu")
		(net "M_H_CPU1_SA_DQ<16>")
	)
	(segment
		(start 136.036812 -275.686266)
		(end 135.98017 -275.629624)
		(width 0.088646)
		(layer "In11.Cu")
		(net "M_H_CPU1_SA_DQ<16>")
	)
	(segment
		(start 193.71945 -302.036226)
		(end 192.937638 -302.818038)
		(width 0.18288)
		(layer "In11.Cu")
		(net "M_H_CPU1_SA_DQ<16>")
	)
	(segment
		(start 127.923036 -273.13382)
		(end 127.914146 -273.12874)
		(width 0.088646)
		(layer "In11.Cu")
		(net "M_H_CPU1_SA_DQ<16>")
	)
	(segment
		(start 165.104826 -302.366426)
		(end 164.723826 -301.985426)
		(width 0.18288)
		(layer "In11.Cu")
		(net "M_H_CPU1_SA_DQ<16>")
	)
	(segment
		(start 198.010526 -299.597826)
		(end 197.451726 -299.597826)
		(width 0.18288)
		(layer "In11.Cu")
		(net "M_H_CPU1_SA_DQ<16>")
	)
	(segment
		(start 124.460254 -272.214086)
		(end 124.3457 -272.078704)
		(width 0.088646)
		(layer "In11.Cu")
		(net "M_H_CPU1_SA_DQ<16>")
	)
	(segment
		(start 139.460478 -278.49957)
		(end 139.460478 -278.25954)
		(width 0.088646)
		(layer "In11.Cu")
		(net "M_H_CPU1_SA_DQ<16>")
	)
	(segment
		(start 202.971146 -297.616626)
		(end 202.971146 -297.77309)
		(width 0.18288)
		(layer "In11.Cu")
		(net "M_H_CPU1_SA_DQ<16>")
	)
	(segment
		(start 128.392682 -273.947636)
		(end 128.383792 -273.942556)
		(width 0.088646)
		(layer "In11.Cu")
		(net "M_H_CPU1_SA_DQ<16>")
	)
	(segment
		(start 137.762996 -277.029926)
		(end 136.419336 -275.686266)
		(width 0.088646)
		(layer "In11.Cu")
		(net "M_H_CPU1_SA_DQ<16>")
	)
	(segment
		(start 181.198012 -302.674528)
		(end 180.90642 -302.96612)
		(width 0.18288)
		(layer "In11.Cu")
		(net "M_H_CPU1_SA_DQ<16>")
	)
	(segment
		(start 141.627098 -280.66619)
		(end 139.630658 -278.66975)
		(width 0.18288)
		(layer "In11.Cu")
		(net "M_H_CPU1_SA_DQ<16>")
	)
	(segment
		(start 132.708396 -275.570442)
		(end 132.693664 -275.579078)
		(width 0.088646)
		(layer "In11.Cu")
		(net "M_H_CPU1_SA_DQ<16>")
	)
	(segment
		(start 202.658218 -298.001944)
		(end 202.480418 -297.928284)
		(width 0.18288)
		(layer "In11.Cu")
		(net "M_H_CPU1_SA_DQ<16>")
	)
	(segment
		(start 157.942788 -297.930824)
		(end 156.736288 -297.930824)
		(width 0.18288)
		(layer "In11.Cu")
		(net "M_H_CPU1_SA_DQ<16>")
	)
	(segment
		(start 195.292726 -301.325026)
		(end 194.581526 -302.036226)
		(width 0.18288)
		(layer "In11.Cu")
		(net "M_H_CPU1_SA_DQ<16>")
	)
	(segment
		(start 128.101598 -273.468592)
		(end 128.101598 -273.453098)
		(width 0.088646)
		(layer "In11.Cu")
		(net "M_H_CPU1_SA_DQ<16>")
	)
	(segment
		(start 184.457848 -302.292004)
		(end 184.075324 -302.674528)
		(width 0.18288)
		(layer "In11.Cu")
		(net "M_H_CPU1_SA_DQ<16>")
	)
	(segment
		(start 164.723826 -301.985426)
		(end 164.221668 -301.985426)
		(width 0.18288)
		(layer "In11.Cu")
		(net "M_H_CPU1_SA_DQ<16>")
	)
	(segment
		(start 180.90642 -302.96612)
		(end 179.380388 -302.96612)
		(width 0.18288)
		(layer "In11.Cu")
		(net "M_H_CPU1_SA_DQ<16>")
	)
	(segment
		(start 190.40602 -303.992026)
		(end 190.00724 -303.593246)
		(width 0.18288)
		(layer "In11.Cu")
		(net "M_H_CPU1_SA_DQ<16>")
	)
	(segment
		(start 125.57506 -272.32102)
		(end 125.564646 -272.314924)
		(width 0.088646)
		(layer "In11.Cu")
		(net "M_H_CPU1_SA_DQ<16>")
	)
	(segment
		(start 160.24352 -299.546264)
		(end 159.12465 -299.546264)
		(width 0.18288)
		(layer "In11.Cu")
		(net "M_H_CPU1_SA_DQ<16>")
	)
	(segment
		(start 127.069596 -272.314924)
		(end 127.054864 -272.32356)
		(width 0.088646)
		(layer "In11.Cu")
		(net "M_H_CPU1_SA_DQ<16>")
	)
	(segment
		(start 156.736288 -297.930824)
		(end 149.762718 -290.957254)
		(width 0.18288)
		(layer "In11.Cu")
		(net "M_H_CPU1_SA_DQ<16>")
	)
	(segment
		(start 202.911202 -297.91787)
		(end 202.827128 -298.001944)
		(width 0.18288)
		(layer "In11.Cu")
		(net "M_H_CPU1_SA_DQ<16>")
	)
	(segment
		(start 141.627098 -280.981404)
		(end 141.627098 -280.66619)
		(width 0.18288)
		(layer "In11.Cu")
		(net "M_H_CPU1_SA_DQ<16>")
	)
	(segment
		(start 189.563502 -303.593246)
		(end 189.287912 -303.317656)
		(width 0.18288)
		(layer "In11.Cu")
		(net "M_H_CPU1_SA_DQ<16>")
	)
	(segment
		(start 124.624592 -272.314924)
		(end 124.460254 -272.214086)
		(width 0.088646)
		(layer "In11.Cu")
		(net "M_H_CPU1_SA_DQ<16>")
	)
	(segment
		(start 199.886316 -298.639484)
		(end 198.968868 -298.639484)
		(width 0.18288)
		(layer "In11.Cu")
		(net "M_H_CPU1_SA_DQ<16>")
	)
	(segment
		(start 169.698162 -302.366426)
		(end 167.110918 -302.366426)
		(width 0.18288)
		(layer "In11.Cu")
		(net "M_H_CPU1_SA_DQ<16>")
	)
	(segment
		(start 138.952478 -277.75154)
		(end 138.952478 -277.397464)
		(width 0.088646)
		(layer "In11.Cu")
		(net "M_H_CPU1_SA_DQ<16>")
	)
	(segment
		(start 130.828796 -275.570442)
		(end 130.814064 -275.579078)
		(width 0.088646)
		(layer "In11.Cu")
		(net "M_H_CPU1_SA_DQ<16>")
	)
	(arc
		(start 132.693664 -275.579078)
		(mid 132.417223 -275.646244)
		(end 132.142992 -275.570442)
		(width 0.088646)
		(layer "In11.Cu")
		(net "M_H_CPU1_SA_DQ<16>")
	)
	(arc
		(start 130.814064 -275.579078)
		(mid 130.537623 -275.646244)
		(end 130.263392 -275.570442)
		(width 0.088646)
		(layer "In11.Cu")
		(net "M_H_CPU1_SA_DQ<16>")
	)
	(arc
		(start 125.564646 -272.314924)
		(mid 125.377448 -272.264781)
		(end 125.19025 -272.314924)
		(width 0.088646)
		(layer "In11.Cu")
		(net "M_H_CPU1_SA_DQ<16>")
	)
	(arc
		(start 134.573264 -275.579078)
		(mid 134.296823 -275.646244)
		(end 134.022592 -275.570442)
		(width 0.088646)
		(layer "In11.Cu")
		(net "M_H_CPU1_SA_DQ<16>")
	)
	(arc
		(start 135.513064 -275.579078)
		(mid 135.236589 -275.646398)
		(end 134.962392 -275.570442)
		(width 0.088646)
		(layer "In11.Cu")
		(net "M_H_CPU1_SA_DQ<16>")
	)
	(arc
		(start 128.101598 -273.453098)
		(mid 128.053919 -273.270198)
		(end 127.923036 -273.13382)
		(width 0.088646)
		(layer "In11.Cu")
		(net "M_H_CPU1_SA_DQ<16>")
	)
	(arc
		(start 134.962392 -275.570442)
		(mid 134.775194 -275.520299)
		(end 134.587996 -275.570442)
		(width 0.088646)
		(layer "In11.Cu")
		(net "M_H_CPU1_SA_DQ<16>")
	)
	(arc
		(start 128.84785 -274.752816)
		(mid 128.645263 -274.546465)
		(end 128.571244 -274.266914)
		(width 0.088646)
		(layer "In11.Cu")
		(net "M_H_CPU1_SA_DQ<16>")
	)
	(arc
		(start 133.648196 -275.570442)
		(mid 133.365494 -275.646184)
		(end 133.082792 -275.570442)
		(width 0.088646)
		(layer "In11.Cu")
		(net "M_H_CPU1_SA_DQ<16>")
	)
	(arc
		(start 127.054864 -272.32356)
		(mid 126.778423 -272.390726)
		(end 126.504192 -272.314924)
		(width 0.088646)
		(layer "In11.Cu")
		(net "M_H_CPU1_SA_DQ<16>")
	)
	(arc
		(start 131.203192 -275.570442)
		(mid 131.015994 -275.520299)
		(end 130.828796 -275.570442)
		(width 0.088646)
		(layer "In11.Cu")
		(net "M_H_CPU1_SA_DQ<16>")
	)
	(arc
		(start 131.753864 -275.579078)
		(mid 131.477423 -275.646244)
		(end 131.203192 -275.570442)
		(width 0.088646)
		(layer "In11.Cu")
		(net "M_H_CPU1_SA_DQ<16>")
	)
	(arc
		(start 129.323846 -275.570442)
		(mid 129.121756 -275.371788)
		(end 129.041398 -275.100034)
		(width 0.088646)
		(layer "In11.Cu")
		(net "M_H_CPU1_SA_DQ<16>")
	)
	(arc
		(start 129.041398 -275.08073)
		(mid 128.993719 -274.89783)
		(end 128.862836 -274.761452)
		(width 0.088646)
		(layer "In11.Cu")
		(net "M_H_CPU1_SA_DQ<16>")
	)
	(arc
		(start 135.902192 -275.570442)
		(mid 135.714994 -275.520299)
		(end 135.527796 -275.570442)
		(width 0.088646)
		(layer "In11.Cu")
		(net "M_H_CPU1_SA_DQ<16>")
	)
	(arc
		(start 130.263392 -275.570442)
		(mid 130.076194 -275.520299)
		(end 129.888996 -275.570442)
		(width 0.088646)
		(layer "In11.Cu")
		(net "M_H_CPU1_SA_DQ<16>")
	)
	(arc
		(start 132.142992 -275.570442)
		(mid 131.955794 -275.520299)
		(end 131.768596 -275.570442)
		(width 0.088646)
		(layer "In11.Cu")
		(net "M_H_CPU1_SA_DQ<16>")
	)
	(arc
		(start 134.022592 -275.570442)
		(mid 133.835394 -275.520299)
		(end 133.648196 -275.570442)
		(width 0.088646)
		(layer "In11.Cu")
		(net "M_H_CPU1_SA_DQ<16>")
	)
	(arc
		(start 133.082792 -275.570442)
		(mid 132.895594 -275.520299)
		(end 132.708396 -275.570442)
		(width 0.088646)
		(layer "In11.Cu")
		(net "M_H_CPU1_SA_DQ<16>")
	)
	(arc
		(start 128.571244 -274.266914)
		(mid 128.523565 -274.084014)
		(end 128.392682 -273.947636)
		(width 0.088646)
		(layer "In11.Cu")
		(net "M_H_CPU1_SA_DQ<16>")
	)
	(arc
		(start 127.443992 -272.314924)
		(mid 127.256794 -272.264781)
		(end 127.069596 -272.314924)
		(width 0.088646)
		(layer "In11.Cu")
		(net "M_H_CPU1_SA_DQ<16>")
	)
	(arc
		(start 127.90805 -273.125184)
		(mid 127.705463 -272.918833)
		(end 127.631444 -272.639282)
		(width 0.088646)
		(layer "In11.Cu")
		(net "M_H_CPU1_SA_DQ<16>")
	)
	(arc
		(start 135.98017 -275.629624)
		(mid 135.94312 -275.597478)
		(end 135.902192 -275.570442)
		(width 0.088646)
		(layer "In11.Cu")
		(net "M_H_CPU1_SA_DQ<16>")
	)
	(arc
		(start 127.631444 -272.639282)
		(mid 127.583765 -272.456382)
		(end 127.452882 -272.320004)
		(width 0.088646)
		(layer "In11.Cu")
		(net "M_H_CPU1_SA_DQ<16>")
	)
	(arc
		(start 125.189996 -272.314924)
		(mid 124.907294 -272.390666)
		(end 124.624592 -272.314924)
		(width 0.088646)
		(layer "In11.Cu")
		(net "M_H_CPU1_SA_DQ<16>")
	)
	(arc
		(start 129.878582 -275.576538)
		(mid 129.600404 -275.64623)
		(end 129.323846 -275.570442)
		(width 0.088646)
		(layer "In11.Cu")
		(net "M_H_CPU1_SA_DQ<16>")
	)
	(arc
		(start 128.383792 -273.942556)
		(mid 128.180969 -273.742325)
		(end 128.101598 -273.468592)
		(width 0.088646)
		(layer "In11.Cu")
		(net "M_H_CPU1_SA_DQ<16>")
	)
	(arc
		(start 126.504192 -272.314924)
		(mid 126.316994 -272.264781)
		(end 126.129796 -272.314924)
		(width 0.088646)
		(layer "In11.Cu")
		(net "M_H_CPU1_SA_DQ<16>")
	)
	(arc
		(start 126.129796 -272.314924)
		(mid 125.853237 -272.390633)
		(end 125.57506 -272.32102)
		(width 0.088646)
		(layer "In11.Cu")
		(net "M_H_CPU1_SA_DQ<16>")
	)
	(segment
		(start 210.598258 -298.898818)
		(end 210.603084 -298.898818)
		(width 0.101854)
		(layer "F.Cu")
		(net "M_H_CPU1_SA_DQ<15>")
	)
	(segment
		(start 124.907294 -273.452844)
		(end 124.907548 -273.453098)
		(width 0.20066)
		(layer "F.Cu")
		(net "M_H_CPU1_SA_DQ<15>")
	)
	(segment
		(start 210.603084 -298.898818)
		(end 210.610196 -298.891706)
		(width 0.1016)
		(layer "F.Cu")
		(net "M_H_CPU1_SA_DQ<15>")
	)
	(segment
		(start 214.385652 -298.466764)
		(end 215.719914 -298.466764)
		(width 0.20066)
		(layer "F.Cu")
		(net "M_H_CPU1_SA_DQ<15>")
	)
	(segment
		(start 212.630258 -298.903898)
		(end 213.311486 -298.903898)
		(width 0.20066)
		(layer "F.Cu")
		(net "M_H_CPU1_SA_DQ<15>")
	)
	(segment
		(start 124.907294 -272.917158)
		(end 124.907294 -273.452844)
		(width 0.20066)
		(layer "F.Cu")
		(net "M_H_CPU1_SA_DQ<15>")
	)
	(segment
		(start 210.610196 -298.891706)
		(end 212.618066 -298.891706)
		(width 0.1016)
		(layer "F.Cu")
		(net "M_H_CPU1_SA_DQ<15>")
	)
	(segment
		(start 210.306412 -298.898818)
		(end 210.598258 -298.898818)
		(width 0.20066)
		(layer "F.Cu")
		(net "M_H_CPU1_SA_DQ<15>")
	)
	(segment
		(start 207.071214 -298.466764)
		(end 208.176114 -298.466764)
		(width 0.20066)
		(layer "F.Cu")
		(net "M_H_CPU1_SA_DQ<15>")
	)
	(segment
		(start 208.176114 -298.466764)
		(end 209.874358 -298.466764)
		(width 0.20066)
		(layer "F.Cu")
		(net "M_H_CPU1_SA_DQ<15>")
	)
	(segment
		(start 213.515448 -298.699936)
		(end 213.515448 -298.448984)
		(width 0.20066)
		(layer "F.Cu")
		(net "M_H_CPU1_SA_DQ<15>")
	)
	(segment
		(start 212.618066 -298.891706)
		(end 212.630258 -298.903898)
		(width 0.1016)
		(layer "F.Cu")
		(net "M_H_CPU1_SA_DQ<15>")
	)
	(segment
		(start 209.874358 -298.466764)
		(end 210.306412 -298.898818)
		(width 0.20066)
		(layer "F.Cu")
		(net "M_H_CPU1_SA_DQ<15>")
	)
	(segment
		(start 214.133684 -298.214796)
		(end 214.385652 -298.466764)
		(width 0.20066)
		(layer "F.Cu")
		(net "M_H_CPU1_SA_DQ<15>")
	)
	(segment
		(start 213.515448 -298.448984)
		(end 213.749636 -298.214796)
		(width 0.20066)
		(layer "F.Cu")
		(net "M_H_CPU1_SA_DQ<15>")
	)
	(segment
		(start 213.311486 -298.903898)
		(end 213.515448 -298.699936)
		(width 0.20066)
		(layer "F.Cu")
		(net "M_H_CPU1_SA_DQ<15>")
	)
	(segment
		(start 213.749636 -298.214796)
		(end 214.133684 -298.214796)
		(width 0.20066)
		(layer "F.Cu")
		(net "M_H_CPU1_SA_DQ<15>")
	)
	(segment
		(start 129.895092 -276.222714)
		(end 129.888996 -276.219158)
		(width 0.088646)
		(layer "In11.Cu")
		(net "M_H_CPU1_SA_DQ<15>")
	)
	(segment
		(start 201.318368 -298.376848)
		(end 199.821038 -299.874178)
		(width 0.18288)
		(layer "In11.Cu")
		(net "M_H_CPU1_SA_DQ<15>")
	)
	(segment
		(start 205.3717 -298.896024)
		(end 204.52969 -298.896024)
		(width 0.18288)
		(layer "In11.Cu")
		(net "M_H_CPU1_SA_DQ<15>")
	)
	(segment
		(start 132.623306 -277.026878)
		(end 132.612892 -277.032974)
		(width 0.088646)
		(layer "In11.Cu")
		(net "M_H_CPU1_SA_DQ<15>")
	)
	(segment
		(start 140.800074 -281.513026)
		(end 140.670534 -281.200606)
		(width 0.18288)
		(layer "In11.Cu")
		(net "M_H_CPU1_SA_DQ<15>")
	)
	(segment
		(start 190.881254 -304.94097)
		(end 189.751716 -304.94097)
		(width 0.18288)
		(layer "In11.Cu")
		(net "M_H_CPU1_SA_DQ<15>")
	)
	(segment
		(start 164.506656 -303.012856)
		(end 162.229038 -303.012856)
		(width 0.18288)
		(layer "In11.Cu")
		(net "M_H_CPU1_SA_DQ<15>")
	)
	(segment
		(start 190.981838 -304.840386)
		(end 190.881254 -304.94097)
		(width 0.18288)
		(layer "In11.Cu")
		(net "M_H_CPU1_SA_DQ<15>")
	)
	(segment
		(start 131.68376 -277.026878)
		(end 131.673346 -277.032974)
		(width 0.088646)
		(layer "In11.Cu")
		(net "M_H_CPU1_SA_DQ<15>")
	)
	(segment
		(start 158.735522 -300.89475)
		(end 158.18612 -301.444152)
		(width 0.18288)
		(layer "In11.Cu")
		(net "M_H_CPU1_SA_DQ<15>")
	)
	(segment
		(start 169.21861 -304.056034)
		(end 168.368726 -303.20488)
		(width 0.18288)
		(layer "In11.Cu")
		(net "M_H_CPU1_SA_DQ<15>")
	)
	(segment
		(start 199.207374 -299.874178)
		(end 198.391526 -300.690026)
		(width 0.18288)
		(layer "In11.Cu")
		(net "M_H_CPU1_SA_DQ<15>")
	)
	(segment
		(start 202.65136 -298.893484)
		(end 202.347576 -298.5897)
		(width 0.18288)
		(layer "In11.Cu")
		(net "M_H_CPU1_SA_DQ<15>")
	)
	(segment
		(start 127.53975 -273.777456)
		(end 127.53086 -273.772376)
		(width 0.088646)
		(layer "In11.Cu")
		(net "M_H_CPU1_SA_DQ<15>")
	)
	(segment
		(start 185.193432 -303.817782)
		(end 185.000392 -304.010822)
		(width 0.18288)
		(layer "In11.Cu")
		(net "M_H_CPU1_SA_DQ<15>")
	)
	(segment
		(start 206.07528 -300.069504)
		(end 205.75778 -300.069504)
		(width 0.18288)
		(layer "In11.Cu")
		(net "M_H_CPU1_SA_DQ<15>")
	)
	(segment
		(start 157.50032 -301.444152)
		(end 157.046168 -300.99)
		(width 0.18288)
		(layer "In11.Cu")
		(net "M_H_CPU1_SA_DQ<15>")
	)
	(segment
		(start 206.26832 -299.876464)
		(end 206.07528 -300.069504)
		(width 0.18288)
		(layer "In11.Cu")
		(net "M_H_CPU1_SA_DQ<15>")
	)
	(segment
		(start 162.100006 -303.141888)
		(end 161.526982 -303.141888)
		(width 0.18288)
		(layer "In11.Cu")
		(net "M_H_CPU1_SA_DQ<15>")
	)
	(segment
		(start 193.751708 -303.27092)
		(end 193.751708 -303.56048)
		(width 0.18288)
		(layer "In11.Cu")
		(net "M_H_CPU1_SA_DQ<15>")
	)
	(segment
		(start 205.56474 -299.876464)
		(end 205.56474 -299.089064)
		(width 0.18288)
		(layer "In11.Cu")
		(net "M_H_CPU1_SA_DQ<15>")
	)
	(segment
		(start 193.751708 -303.56048)
		(end 192.471802 -304.840386)
		(width 0.18288)
		(layer "In11.Cu")
		(net "M_H_CPU1_SA_DQ<15>")
	)
	(segment
		(start 203.63307 -299.895006)
		(end 203.63307 -299.089064)
		(width 0.18288)
		(layer "In11.Cu")
		(net "M_H_CPU1_SA_DQ<15>")
	)
	(segment
		(start 178.53279 -304.601626)
		(end 178.291744 -304.842672)
		(width 0.18288)
		(layer "In11.Cu")
		(net "M_H_CPU1_SA_DQ<15>")
	)
	(segment
		(start 206.46136 -298.896024)
		(end 206.26832 -299.089064)
		(width 0.18288)
		(layer "In11.Cu")
		(net "M_H_CPU1_SA_DQ<15>")
	)
	(segment
		(start 206.26832 -299.089064)
		(end 206.26832 -299.876464)
		(width 0.18288)
		(layer "In11.Cu")
		(net "M_H_CPU1_SA_DQ<15>")
	)
	(segment
		(start 180.849524 -304.916078)
		(end 179.821078 -304.916078)
		(width 0.18288)
		(layer "In11.Cu")
		(net "M_H_CPU1_SA_DQ<15>")
	)
	(segment
		(start 185.897012 -303.801272)
		(end 185.897012 -303.321212)
		(width 0.18288)
		(layer "In11.Cu")
		(net "M_H_CPU1_SA_DQ<15>")
	)
	(segment
		(start 185.386472 -303.128172)
		(end 185.193432 -303.321212)
		(width 0.18288)
		(layer "In11.Cu")
		(net "M_H_CPU1_SA_DQ<15>")
	)
	(segment
		(start 192.471802 -304.840386)
		(end 190.981838 -304.840386)
		(width 0.18288)
		(layer "In11.Cu")
		(net "M_H_CPU1_SA_DQ<15>")
	)
	(segment
		(start 160.952688 -302.567594)
		(end 160.952688 -301.401988)
		(width 0.18288)
		(layer "In11.Cu")
		(net "M_H_CPU1_SA_DQ<15>")
	)
	(segment
		(start 136.937496 -277.032974)
		(end 136.93775 -277.032974)
		(width 0.088646)
		(layer "In11.Cu")
		(net "M_H_CPU1_SA_DQ<15>")
	)
	(segment
		(start 157.046168 -299.396658)
		(end 148.956014 -291.306504)
		(width 0.18288)
		(layer "In11.Cu")
		(net "M_H_CPU1_SA_DQ<15>")
	)
	(segment
		(start 135.447024 -277.024338)
		(end 135.432292 -277.032974)
		(width 0.088646)
		(layer "In11.Cu")
		(net "M_H_CPU1_SA_DQ<15>")
	)
	(segment
		(start 160.952688 -301.401988)
		(end 160.44545 -300.89475)
		(width 0.18288)
		(layer "In11.Cu")
		(net "M_H_CPU1_SA_DQ<15>")
	)
	(segment
		(start 133.567678 -277.024338)
		(end 133.552946 -277.032974)
		(width 0.088646)
		(layer "In11.Cu")
		(net "M_H_CPU1_SA_DQ<15>")
	)
	(segment
		(start 181.746144 -304.242724)
		(end 181.553104 -304.049684)
		(width 0.18288)
		(layer "In11.Cu")
		(net "M_H_CPU1_SA_DQ<15>")
	)
	(segment
		(start 206.64043 -298.896024)
		(end 206.46136 -298.896024)
		(width 0.18288)
		(layer "In11.Cu")
		(net "M_H_CPU1_SA_DQ<15>")
	)
	(segment
		(start 197.751446 -300.690026)
		(end 195.52539 -302.916082)
		(width 0.18288)
		(layer "In11.Cu")
		(net "M_H_CPU1_SA_DQ<15>")
	)
	(segment
		(start 138.701018 -279.056846)
		(end 138.701018 -278.678894)
		(width 0.088646)
		(layer "In11.Cu")
		(net "M_H_CPU1_SA_DQ<15>")
	)
	(segment
		(start 174.254922 -305.02479)
		(end 173.586394 -305.693318)
		(width 0.18288)
		(layer "In11.Cu")
		(net "M_H_CPU1_SA_DQ<15>")
	)
	(segment
		(start 173.586394 -305.693318)
		(end 171.340526 -305.693318)
		(width 0.18288)
		(layer "In11.Cu")
		(net "M_H_CPU1_SA_DQ<15>")
	)
	(segment
		(start 203.43749 -298.893484)
		(end 202.65136 -298.893484)
		(width 0.18288)
		(layer "In11.Cu")
		(net "M_H_CPU1_SA_DQ<15>")
	)
	(segment
		(start 204.33665 -299.895006)
		(end 204.14361 -300.088046)
		(width 0.18288)
		(layer "In11.Cu")
		(net "M_H_CPU1_SA_DQ<15>")
	)
	(segment
		(start 160.44545 -300.89475)
		(end 158.735522 -300.89475)
		(width 0.18288)
		(layer "In11.Cu")
		(net "M_H_CPU1_SA_DQ<15>")
	)
	(segment
		(start 185.703972 -303.128172)
		(end 185.386472 -303.128172)
		(width 0.18288)
		(layer "In11.Cu")
		(net "M_H_CPU1_SA_DQ<15>")
	)
	(segment
		(start 125.143768 -273.453098)
		(end 124.907548 -273.453098)
		(width 0.088646)
		(layer "In11.Cu")
		(net "M_H_CPU1_SA_DQ<15>")
	)
	(segment
		(start 128.761998 -275.8948)
		(end 128.761998 -275.880576)
		(width 0.088646)
		(layer "In11.Cu")
		(net "M_H_CPU1_SA_DQ<15>")
	)
	(segment
		(start 168.368726 -303.20488)
		(end 164.69868 -303.20488)
		(width 0.18288)
		(layer "In11.Cu")
		(net "M_H_CPU1_SA_DQ<15>")
	)
	(segment
		(start 139.975844 -280.505916)
		(end 139.739116 -280.269188)
		(width 0.088646)
		(layer "In11.Cu")
		(net "M_H_CPU1_SA_DQ<15>")
	)
	(segment
		(start 176.084738 -304.842672)
		(end 175.90262 -305.02479)
		(width 0.18288)
		(layer "In11.Cu")
		(net "M_H_CPU1_SA_DQ<15>")
	)
	(segment
		(start 189.751716 -304.94097)
		(end 188.805058 -303.994312)
		(width 0.18288)
		(layer "In11.Cu")
		(net "M_H_CPU1_SA_DQ<15>")
	)
	(segment
		(start 127.821944 -274.266914)
		(end 127.821944 -274.25142)
		(width 0.088646)
		(layer "In11.Cu")
		(net "M_H_CPU1_SA_DQ<15>")
	)
	(segment
		(start 185.193432 -303.321212)
		(end 185.193432 -303.817782)
		(width 0.18288)
		(layer "In11.Cu")
		(net "M_H_CPU1_SA_DQ<15>")
	)
	(segment
		(start 204.14361 -300.088046)
		(end 203.82611 -300.088046)
		(width 0.18288)
		(layer "In11.Cu")
		(net "M_H_CPU1_SA_DQ<15>")
	)
	(segment
		(start 203.82611 -300.088046)
		(end 203.63307 -299.895006)
		(width 0.18288)
		(layer "In11.Cu")
		(net "M_H_CPU1_SA_DQ<15>")
	)
	(segment
		(start 126.129796 -272.96364)
		(end 126.119382 -272.957544)
		(width 0.088646)
		(layer "In11.Cu")
		(net "M_H_CPU1_SA_DQ<15>")
	)
	(segment
		(start 204.33665 -299.089064)
		(end 204.33665 -299.895006)
		(width 0.18288)
		(layer "In11.Cu")
		(net "M_H_CPU1_SA_DQ<15>")
	)
	(segment
		(start 162.229038 -303.012856)
		(end 162.100006 -303.141888)
		(width 0.18288)
		(layer "In11.Cu")
		(net "M_H_CPU1_SA_DQ<15>")
	)
	(segment
		(start 128.94945 -276.219158)
		(end 128.94056 -276.214078)
		(width 0.088646)
		(layer "In11.Cu")
		(net "M_H_CPU1_SA_DQ<15>")
	)
	(segment
		(start 138.629644 -278.60752)
		(end 138.629644 -278.31796)
		(width 0.088646)
		(layer "In11.Cu")
		(net "M_H_CPU1_SA_DQ<15>")
	)
	(segment
		(start 140.670534 -281.200606)
		(end 139.975844 -280.505916)
		(width 0.18288)
		(layer "In11.Cu")
		(net "M_H_CPU1_SA_DQ<15>")
	)
	(segment
		(start 186.090052 -303.994312)
		(end 185.897012 -303.801272)
		(width 0.18288)
		(layer "In11.Cu")
		(net "M_H_CPU1_SA_DQ<15>")
	)
	(segment
		(start 181.235604 -304.049684)
		(end 181.042564 -304.242724)
		(width 0.18288)
		(layer "In11.Cu")
		(net "M_H_CPU1_SA_DQ<15>")
	)
	(segment
		(start 158.18612 -301.444152)
		(end 157.50032 -301.444152)
		(width 0.18288)
		(layer "In11.Cu")
		(net "M_H_CPU1_SA_DQ<15>")
	)
	(segment
		(start 148.956014 -291.306504)
		(end 148.956014 -289.668966)
		(width 0.18288)
		(layer "In11.Cu")
		(net "M_H_CPU1_SA_DQ<15>")
	)
	(segment
		(start 135.432292 -277.032974)
		(end 135.42391 -277.0378)
		(width 0.088646)
		(layer "In11.Cu")
		(net "M_H_CPU1_SA_DQ<15>")
	)
	(segment
		(start 139.739116 -280.269188)
		(end 139.739116 -280.094944)
		(width 0.088646)
		(layer "In11.Cu")
		(net "M_H_CPU1_SA_DQ<15>")
	)
	(segment
		(start 157.046168 -300.99)
		(end 157.046168 -299.396658)
		(width 0.18288)
		(layer "In11.Cu")
		(net "M_H_CPU1_SA_DQ<15>")
	)
	(segment
		(start 137.407396 -277.84679)
		(end 137.398506 -277.84171)
		(width 0.088646)
		(layer "In11.Cu")
		(net "M_H_CPU1_SA_DQ<15>")
	)
	(segment
		(start 136.382506 -277.026878)
		(end 136.372092 -277.032974)
		(width 0.088646)
		(layer "In11.Cu")
		(net "M_H_CPU1_SA_DQ<15>")
	)
	(segment
		(start 205.56474 -299.089064)
		(end 205.3717 -298.896024)
		(width 0.18288)
		(layer "In11.Cu")
		(net "M_H_CPU1_SA_DQ<15>")
	)
	(segment
		(start 205.75778 -300.069504)
		(end 205.56474 -299.876464)
		(width 0.18288)
		(layer "In11.Cu")
		(net "M_H_CPU1_SA_DQ<15>")
	)
	(segment
		(start 182.875428 -304.916078)
		(end 181.939184 -304.916078)
		(width 0.18288)
		(layer "In11.Cu")
		(net "M_H_CPU1_SA_DQ<15>")
	)
	(segment
		(start 161.526982 -303.141888)
		(end 160.952688 -302.567594)
		(width 0.18288)
		(layer "In11.Cu")
		(net "M_H_CPU1_SA_DQ<15>")
	)
	(segment
		(start 178.291744 -304.842672)
		(end 176.084738 -304.842672)
		(width 0.18288)
		(layer "In11.Cu")
		(net "M_H_CPU1_SA_DQ<15>")
	)
	(segment
		(start 204.52969 -298.896024)
		(end 204.33665 -299.089064)
		(width 0.18288)
		(layer "In11.Cu")
		(net "M_H_CPU1_SA_DQ<15>")
	)
	(segment
		(start 199.821038 -299.874178)
		(end 199.207374 -299.874178)
		(width 0.18288)
		(layer "In11.Cu")
		(net "M_H_CPU1_SA_DQ<15>")
	)
	(segment
		(start 127.075692 -272.967196)
		(end 127.069596 -272.96364)
		(width 0.088646)
		(layer "In11.Cu")
		(net "M_H_CPU1_SA_DQ<15>")
	)
	(segment
		(start 195.52539 -302.916082)
		(end 194.106546 -302.916082)
		(width 0.18288)
		(layer "In11.Cu")
		(net "M_H_CPU1_SA_DQ<15>")
	)
	(segment
		(start 128.47955 -275.405088)
		(end 128.47066 -275.400008)
		(width 0.088646)
		(layer "In11.Cu")
		(net "M_H_CPU1_SA_DQ<15>")
	)
	(segment
		(start 185.000392 -304.010822)
		(end 183.780684 -304.010822)
		(width 0.18288)
		(layer "In11.Cu")
		(net "M_H_CPU1_SA_DQ<15>")
	)
	(segment
		(start 185.897012 -303.321212)
		(end 185.703972 -303.128172)
		(width 0.18288)
		(layer "In11.Cu")
		(net "M_H_CPU1_SA_DQ<15>")
	)
	(segment
		(start 181.746144 -304.723038)
		(end 181.746144 -304.242724)
		(width 0.18288)
		(layer "In11.Cu")
		(net "M_H_CPU1_SA_DQ<15>")
	)
	(segment
		(start 125.564646 -272.96364)
		(end 125.55855 -272.967196)
		(width 0.088646)
		(layer "In11.Cu")
		(net "M_H_CPU1_SA_DQ<15>")
	)
	(segment
		(start 179.821078 -304.916078)
		(end 179.506626 -304.601626)
		(width 0.18288)
		(layer "In11.Cu")
		(net "M_H_CPU1_SA_DQ<15>")
	)
	(segment
		(start 128.009396 -274.591272)
		(end 128.000506 -274.586192)
		(width 0.088646)
		(layer "In11.Cu")
		(net "M_H_CPU1_SA_DQ<15>")
	)
	(segment
		(start 139.739116 -280.094944)
		(end 138.701018 -279.056846)
		(width 0.088646)
		(layer "In11.Cu")
		(net "M_H_CPU1_SA_DQ<15>")
	)
	(segment
		(start 194.106546 -302.916082)
		(end 193.751708 -303.27092)
		(width 0.18288)
		(layer "In11.Cu")
		(net "M_H_CPU1_SA_DQ<15>")
	)
	(segment
		(start 130.35915 -277.032974)
		(end 130.35026 -277.027894)
		(width 0.088646)
		(layer "In11.Cu")
		(net "M_H_CPU1_SA_DQ<15>")
	)
	(segment
		(start 129.888996 -276.219158)
		(end 129.878582 -276.213062)
		(width 0.088646)
		(layer "In11.Cu")
		(net "M_H_CPU1_SA_DQ<15>")
	)
	(segment
		(start 171.340526 -305.693318)
		(end 169.702226 -304.056034)
		(width 0.18288)
		(layer "In11.Cu")
		(net "M_H_CPU1_SA_DQ<15>")
	)
	(segment
		(start 128.015492 -274.594828)
		(end 128.009396 -274.591272)
		(width 0.088646)
		(layer "In11.Cu")
		(net "M_H_CPU1_SA_DQ<15>")
	)
	(segment
		(start 203.63307 -299.089064)
		(end 203.43749 -298.893484)
		(width 0.18288)
		(layer "In11.Cu")
		(net "M_H_CPU1_SA_DQ<15>")
	)
	(segment
		(start 188.805058 -303.994312)
		(end 186.090052 -303.994312)
		(width 0.18288)
		(layer "In11.Cu")
		(net "M_H_CPU1_SA_DQ<15>")
	)
	(segment
		(start 164.69868 -303.20488)
		(end 164.506656 -303.012856)
		(width 0.18288)
		(layer "In11.Cu")
		(net "M_H_CPU1_SA_DQ<15>")
	)
	(segment
		(start 148.956014 -289.668966)
		(end 140.800074 -281.513026)
		(width 0.18288)
		(layer "In11.Cu")
		(net "M_H_CPU1_SA_DQ<15>")
	)
	(segment
		(start 198.391526 -300.690026)
		(end 197.751446 -300.690026)
		(width 0.18288)
		(layer "In11.Cu")
		(net "M_H_CPU1_SA_DQ<15>")
	)
	(segment
		(start 181.939184 -304.916078)
		(end 181.746144 -304.723038)
		(width 0.18288)
		(layer "In11.Cu")
		(net "M_H_CPU1_SA_DQ<15>")
	)
	(segment
		(start 169.702226 -304.056034)
		(end 169.21861 -304.056034)
		(width 0.18288)
		(layer "In11.Cu")
		(net "M_H_CPU1_SA_DQ<15>")
	)
	(segment
		(start 134.507478 -277.024338)
		(end 134.492746 -277.032974)
		(width 0.088646)
		(layer "In11.Cu")
		(net "M_H_CPU1_SA_DQ<15>")
	)
	(segment
		(start 207.071214 -298.466764)
		(end 206.64043 -298.896024)
		(width 0.18288)
		(layer "In11.Cu")
		(net "M_H_CPU1_SA_DQ<15>")
	)
	(segment
		(start 125.409706 -273.095212)
		(end 125.355858 -273.161252)
		(width 0.088646)
		(layer "In11.Cu")
		(net "M_H_CPU1_SA_DQ<15>")
	)
	(segment
		(start 201.833734 -298.376848)
		(end 201.318368 -298.376848)
		(width 0.18288)
		(layer "In11.Cu")
		(net "M_H_CPU1_SA_DQ<15>")
	)
	(segment
		(start 181.553104 -304.049684)
		(end 181.235604 -304.049684)
		(width 0.18288)
		(layer "In11.Cu")
		(net "M_H_CPU1_SA_DQ<15>")
	)
	(segment
		(start 137.219944 -277.522432)
		(end 137.219944 -277.512526)
		(width 0.088646)
		(layer "In11.Cu")
		(net "M_H_CPU1_SA_DQ<15>")
	)
	(segment
		(start 127.069596 -272.96364)
		(end 127.054864 -272.955004)
		(width 0.088646)
		(layer "In11.Cu")
		(net "M_H_CPU1_SA_DQ<15>")
	)
	(segment
		(start 179.506626 -304.601626)
		(end 178.53279 -304.601626)
		(width 0.18288)
		(layer "In11.Cu")
		(net "M_H_CPU1_SA_DQ<15>")
	)
	(segment
		(start 181.042564 -304.242724)
		(end 181.042564 -304.723038)
		(width 0.18288)
		(layer "In11.Cu")
		(net "M_H_CPU1_SA_DQ<15>")
	)
	(segment
		(start 175.90262 -305.02479)
		(end 174.254922 -305.02479)
		(width 0.18288)
		(layer "In11.Cu")
		(net "M_H_CPU1_SA_DQ<15>")
	)
	(segment
		(start 138.701018 -278.678894)
		(end 138.629644 -278.60752)
		(width 0.088646)
		(layer "In11.Cu")
		(net "M_H_CPU1_SA_DQ<15>")
	)
	(segment
		(start 181.042564 -304.723038)
		(end 180.849524 -304.916078)
		(width 0.18288)
		(layer "In11.Cu")
		(net "M_H_CPU1_SA_DQ<15>")
	)
	(segment
		(start 183.780684 -304.010822)
		(end 182.875428 -304.916078)
		(width 0.18288)
		(layer "In11.Cu")
		(net "M_H_CPU1_SA_DQ<15>")
	)
	(segment
		(start 202.347576 -298.5897)
		(end 201.833734 -298.376848)
		(width 0.18288)
		(layer "In11.Cu")
		(net "M_H_CPU1_SA_DQ<15>")
	)
	(arc
		(start 132.238496 -277.032974)
		(mid 131.961937 -276.957231)
		(end 131.68376 -277.026878)
		(width 0.088646)
		(layer "In11.Cu")
		(net "M_H_CPU1_SA_DQ<15>")
	)
	(arc
		(start 135.997696 -277.032974)
		(mid 135.723497 -276.957139)
		(end 135.447024 -277.024338)
		(width 0.088646)
		(layer "In11.Cu")
		(net "M_H_CPU1_SA_DQ<15>")
	)
	(arc
		(start 128.47066 -275.400008)
		(mid 128.339746 -275.263648)
		(end 128.292098 -275.08073)
		(width 0.088646)
		(layer "In11.Cu")
		(net "M_H_CPU1_SA_DQ<15>")
	)
	(arc
		(start 133.552946 -277.032974)
		(mid 133.365748 -277.083117)
		(end 133.17855 -277.032974)
		(width 0.088646)
		(layer "In11.Cu")
		(net "M_H_CPU1_SA_DQ<15>")
	)
	(arc
		(start 127.53086 -273.772376)
		(mid 127.399946 -273.636016)
		(end 127.352298 -273.453098)
		(width 0.088646)
		(layer "In11.Cu")
		(net "M_H_CPU1_SA_DQ<15>")
	)
	(arc
		(start 125.281944 -273.373596)
		(mid 125.223525 -273.431908)
		(end 125.143768 -273.453098)
		(width 0.088646)
		(layer "In11.Cu")
		(net "M_H_CPU1_SA_DQ<15>")
	)
	(arc
		(start 125.302772 -273.300952)
		(mid 125.296852 -273.323319)
		(end 125.29185 -273.34591)
		(width 0.088646)
		(layer "In11.Cu")
		(net "M_H_CPU1_SA_DQ<15>")
	)
	(arc
		(start 127.352298 -273.453098)
		(mid 127.278307 -273.173532)
		(end 127.075692 -272.967196)
		(width 0.088646)
		(layer "In11.Cu")
		(net "M_H_CPU1_SA_DQ<15>")
	)
	(arc
		(start 135.42391 -277.0378)
		(mid 135.240402 -277.083078)
		(end 135.05815 -277.032974)
		(width 0.088646)
		(layer "In11.Cu")
		(net "M_H_CPU1_SA_DQ<15>")
	)
	(arc
		(start 136.372092 -277.032974)
		(mid 136.184894 -277.083117)
		(end 135.997696 -277.032974)
		(width 0.088646)
		(layer "In11.Cu")
		(net "M_H_CPU1_SA_DQ<15>")
	)
	(arc
		(start 125.355858 -273.161252)
		(mid 125.318045 -273.226392)
		(end 125.303026 -273.30019)
		(width 0.088646)
		(layer "In11.Cu")
		(net "M_H_CPU1_SA_DQ<15>")
	)
	(arc
		(start 128.761998 -275.880576)
		(mid 128.682857 -275.605953)
		(end 128.47955 -275.405088)
		(width 0.088646)
		(layer "In11.Cu")
		(net "M_H_CPU1_SA_DQ<15>")
	)
	(arc
		(start 130.171698 -276.708616)
		(mid 130.097707 -276.42905)
		(end 129.895092 -276.222714)
		(width 0.088646)
		(layer "In11.Cu")
		(net "M_H_CPU1_SA_DQ<15>")
	)
	(arc
		(start 131.29895 -277.032974)
		(mid 131.016248 -276.957198)
		(end 130.733546 -277.032974)
		(width 0.088646)
		(layer "In11.Cu")
		(net "M_H_CPU1_SA_DQ<15>")
	)
	(arc
		(start 128.94056 -276.214078)
		(mid 128.809646 -276.077718)
		(end 128.761998 -275.8948)
		(width 0.088646)
		(layer "In11.Cu")
		(net "M_H_CPU1_SA_DQ<15>")
	)
	(arc
		(start 132.612892 -277.032974)
		(mid 132.425694 -277.083117)
		(end 132.238496 -277.032974)
		(width 0.088646)
		(layer "In11.Cu")
		(net "M_H_CPU1_SA_DQ<15>")
	)
	(arc
		(start 129.323846 -276.219158)
		(mid 129.136648 -276.269301)
		(end 128.94945 -276.219158)
		(width 0.088646)
		(layer "In11.Cu")
		(net "M_H_CPU1_SA_DQ<15>")
	)
	(arc
		(start 134.492746 -277.032974)
		(mid 134.305548 -277.083117)
		(end 134.11835 -277.032974)
		(width 0.088646)
		(layer "In11.Cu")
		(net "M_H_CPU1_SA_DQ<15>")
	)
	(arc
		(start 134.11835 -277.032974)
		(mid 133.844151 -276.957139)
		(end 133.567678 -277.024338)
		(width 0.088646)
		(layer "In11.Cu")
		(net "M_H_CPU1_SA_DQ<15>")
	)
	(arc
		(start 130.733546 -277.032974)
		(mid 130.546348 -277.083117)
		(end 130.35915 -277.032974)
		(width 0.088646)
		(layer "In11.Cu")
		(net "M_H_CPU1_SA_DQ<15>")
	)
	(arc
		(start 130.35026 -277.027894)
		(mid 130.219346 -276.891534)
		(end 130.171698 -276.708616)
		(width 0.088646)
		(layer "In11.Cu")
		(net "M_H_CPU1_SA_DQ<15>")
	)
	(arc
		(start 125.29185 -273.34591)
		(mid 125.288037 -273.360159)
		(end 125.281944 -273.373596)
		(width 0.088646)
		(layer "In11.Cu")
		(net "M_H_CPU1_SA_DQ<15>")
	)
	(arc
		(start 137.398506 -277.84171)
		(mid 137.267592 -277.70535)
		(end 137.219944 -277.522432)
		(width 0.088646)
		(layer "In11.Cu")
		(net "M_H_CPU1_SA_DQ<15>")
	)
	(arc
		(start 126.119382 -272.957544)
		(mid 125.841204 -272.887821)
		(end 125.564646 -272.96364)
		(width 0.088646)
		(layer "In11.Cu")
		(net "M_H_CPU1_SA_DQ<15>")
	)
	(arc
		(start 131.673346 -277.032974)
		(mid 131.486148 -277.083117)
		(end 131.29895 -277.032974)
		(width 0.088646)
		(layer "In11.Cu")
		(net "M_H_CPU1_SA_DQ<15>")
	)
	(arc
		(start 137.219944 -277.512526)
		(mid 137.141833 -277.235577)
		(end 136.937496 -277.032974)
		(width 0.088646)
		(layer "In11.Cu")
		(net "M_H_CPU1_SA_DQ<15>")
	)
	(arc
		(start 137.781792 -277.84679)
		(mid 137.594594 -277.896933)
		(end 137.407396 -277.84679)
		(width 0.088646)
		(layer "In11.Cu")
		(net "M_H_CPU1_SA_DQ<15>")
	)
	(arc
		(start 127.821944 -274.25142)
		(mid 127.742574 -273.977686)
		(end 127.53975 -273.777456)
		(width 0.088646)
		(layer "In11.Cu")
		(net "M_H_CPU1_SA_DQ<15>")
	)
	(arc
		(start 125.303026 -273.30019)
		(mid 125.302899 -273.300571)
		(end 125.302772 -273.300952)
		(width 0.088646)
		(layer "In11.Cu")
		(net "M_H_CPU1_SA_DQ<15>")
	)
	(arc
		(start 136.93775 -277.032974)
		(mid 136.660937 -276.957104)
		(end 136.382506 -277.026878)
		(width 0.088646)
		(layer "In11.Cu")
		(net "M_H_CPU1_SA_DQ<15>")
	)
	(arc
		(start 135.05815 -277.032974)
		(mid 134.783951 -276.957139)
		(end 134.507478 -277.024338)
		(width 0.088646)
		(layer "In11.Cu")
		(net "M_H_CPU1_SA_DQ<15>")
	)
	(arc
		(start 138.629644 -278.31796)
		(mid 138.339166 -277.842241)
		(end 137.781792 -277.84679)
		(width 0.088646)
		(layer "In11.Cu")
		(net "M_H_CPU1_SA_DQ<15>")
	)
	(arc
		(start 127.054864 -272.955004)
		(mid 126.778389 -272.887684)
		(end 126.504192 -272.96364)
		(width 0.088646)
		(layer "In11.Cu")
		(net "M_H_CPU1_SA_DQ<15>")
	)
	(arc
		(start 126.504192 -272.96364)
		(mid 126.316994 -273.013783)
		(end 126.129796 -272.96364)
		(width 0.088646)
		(layer "In11.Cu")
		(net "M_H_CPU1_SA_DQ<15>")
	)
	(arc
		(start 129.878582 -276.213062)
		(mid 129.600404 -276.143339)
		(end 129.323846 -276.219158)
		(width 0.088646)
		(layer "In11.Cu")
		(net "M_H_CPU1_SA_DQ<15>")
	)
	(arc
		(start 125.55855 -272.967196)
		(mid 125.478537 -273.024701)
		(end 125.409706 -273.095212)
		(width 0.088646)
		(layer "In11.Cu")
		(net "M_H_CPU1_SA_DQ<15>")
	)
	(arc
		(start 133.17855 -277.032974)
		(mid 132.901737 -276.957104)
		(end 132.623306 -277.026878)
		(width 0.088646)
		(layer "In11.Cu")
		(net "M_H_CPU1_SA_DQ<15>")
	)
	(arc
		(start 128.292098 -275.08073)
		(mid 128.218107 -274.801164)
		(end 128.015492 -274.594828)
		(width 0.088646)
		(layer "In11.Cu")
		(net "M_H_CPU1_SA_DQ<15>")
	)
	(arc
		(start 128.000506 -274.586192)
		(mid 127.869592 -274.449832)
		(end 127.821944 -274.266914)
		(width 0.088646)
		(layer "In11.Cu")
		(net "M_H_CPU1_SA_DQ<15>")
	)
	(segment
		(start 212.630258 -300.60392)
		(end 213.311486 -300.60392)
		(width 0.20066)
		(layer "F.Cu")
		(net "M_H_CPU1_SA_DQ<14>")
	)
	(segment
		(start 214.385652 -300.166786)
		(end 215.719914 -300.166786)
		(width 0.20066)
		(layer "F.Cu")
		(net "M_H_CPU1_SA_DQ<14>")
	)
	(segment
		(start 210.306412 -300.59884)
		(end 210.598258 -300.59884)
		(width 0.20066)
		(layer "F.Cu")
		(net "M_H_CPU1_SA_DQ<14>")
	)
	(segment
		(start 208.176114 -300.166786)
		(end 209.874358 -300.166786)
		(width 0.20066)
		(layer "F.Cu")
		(net "M_H_CPU1_SA_DQ<14>")
	)
	(segment
		(start 207.071214 -300.166532)
		(end 208.17586 -300.166532)
		(width 0.20066)
		(layer "F.Cu")
		(net "M_H_CPU1_SA_DQ<14>")
	)
	(segment
		(start 209.874358 -300.166786)
		(end 210.306412 -300.59884)
		(width 0.20066)
		(layer "F.Cu")
		(net "M_H_CPU1_SA_DQ<14>")
	)
	(segment
		(start 213.311486 -300.60392)
		(end 213.515448 -300.399958)
		(width 0.20066)
		(layer "F.Cu")
		(net "M_H_CPU1_SA_DQ<14>")
	)
	(segment
		(start 125.377448 -274.26666)
		(end 125.377194 -274.266914)
		(width 0.20066)
		(layer "F.Cu")
		(net "M_H_CPU1_SA_DQ<14>")
	)
	(segment
		(start 210.603084 -300.59884)
		(end 210.610196 -300.591728)
		(width 0.1016)
		(layer "F.Cu")
		(net "M_H_CPU1_SA_DQ<14>")
	)
	(segment
		(start 213.749636 -299.914818)
		(end 214.133684 -299.914818)
		(width 0.20066)
		(layer "F.Cu")
		(net "M_H_CPU1_SA_DQ<14>")
	)
	(segment
		(start 208.17586 -300.166532)
		(end 208.176114 -300.166786)
		(width 0.20066)
		(layer "F.Cu")
		(net "M_H_CPU1_SA_DQ<14>")
	)
	(segment
		(start 210.610196 -300.591728)
		(end 212.618066 -300.591728)
		(width 0.1016)
		(layer "F.Cu")
		(net "M_H_CPU1_SA_DQ<14>")
	)
	(segment
		(start 213.515448 -300.149006)
		(end 213.749636 -299.914818)
		(width 0.20066)
		(layer "F.Cu")
		(net "M_H_CPU1_SA_DQ<14>")
	)
	(segment
		(start 125.377448 -273.730974)
		(end 125.377448 -274.26666)
		(width 0.20066)
		(layer "F.Cu")
		(net "M_H_CPU1_SA_DQ<14>")
	)
	(segment
		(start 213.515448 -300.399958)
		(end 213.515448 -300.149006)
		(width 0.20066)
		(layer "F.Cu")
		(net "M_H_CPU1_SA_DQ<14>")
	)
	(segment
		(start 212.618066 -300.591728)
		(end 212.630258 -300.60392)
		(width 0.1016)
		(layer "F.Cu")
		(net "M_H_CPU1_SA_DQ<14>")
	)
	(segment
		(start 214.133684 -299.914818)
		(end 214.385652 -300.166786)
		(width 0.20066)
		(layer "F.Cu")
		(net "M_H_CPU1_SA_DQ<14>")
	)
	(segment
		(start 210.598258 -300.59884)
		(end 210.603084 -300.59884)
		(width 0.101854)
		(layer "F.Cu")
		(net "M_H_CPU1_SA_DQ<14>")
	)
	(segment
		(start 138.159744 -279.150318)
		(end 138.159744 -279.140412)
		(width 0.088646)
		(layer "In11.Cu")
		(net "M_H_CPU1_SA_DQ<14>")
	)
	(segment
		(start 194.683126 -304.779426)
		(end 194.044062 -304.779426)
		(width 0.18288)
		(layer "In11.Cu")
		(net "M_H_CPU1_SA_DQ<14>")
	)
	(segment
		(start 156.872432 -303.394364)
		(end 156.872432 -303.121568)
		(width 0.18288)
		(layer "In11.Cu")
		(net "M_H_CPU1_SA_DQ<14>")
	)
	(segment
		(start 158.116016 -303.990502)
		(end 157.46857 -303.990502)
		(width 0.18288)
		(layer "In11.Cu")
		(net "M_H_CPU1_SA_DQ<14>")
	)
	(segment
		(start 198.731632 -302.78832)
		(end 198.345044 -302.78832)
		(width 0.18288)
		(layer "In11.Cu")
		(net "M_H_CPU1_SA_DQ<14>")
	)
	(segment
		(start 138.347196 -279.474676)
		(end 138.338306 -279.469596)
		(width 0.088646)
		(layer "In11.Cu")
		(net "M_H_CPU1_SA_DQ<14>")
	)
	(segment
		(start 160.355788 -304.93843)
		(end 159.063944 -304.93843)
		(width 0.18288)
		(layer "In11.Cu")
		(net "M_H_CPU1_SA_DQ<14>")
	)
	(segment
		(start 194.985894 -305.082194)
		(end 194.683126 -304.779426)
		(width 0.18288)
		(layer "In11.Cu")
		(net "M_H_CPU1_SA_DQ<14>")
	)
	(segment
		(start 196.337936 -303.784762)
		(end 196.337936 -304.057558)
		(width 0.18288)
		(layer "In11.Cu")
		(net "M_H_CPU1_SA_DQ<14>")
	)
	(segment
		(start 207.071214 -300.166532)
		(end 206.613252 -300.623478)
		(width 0.18288)
		(layer "In11.Cu")
		(net "M_H_CPU1_SA_DQ<14>")
	)
	(segment
		(start 179.633626 -306.405026)
		(end 178.93665 -306.405026)
		(width 0.18288)
		(layer "In11.Cu")
		(net "M_H_CPU1_SA_DQ<14>")
	)
	(segment
		(start 196.835522 -303.559972)
		(end 196.562726 -303.559972)
		(width 0.18288)
		(layer "In11.Cu")
		(net "M_H_CPU1_SA_DQ<14>")
	)
	(segment
		(start 156.879036 -302.392588)
		(end 156.60624 -302.392588)
		(width 0.18288)
		(layer "In11.Cu")
		(net "M_H_CPU1_SA_DQ<14>")
	)
	(segment
		(start 204.004418 -301.195994)
		(end 203.811378 -301.002954)
		(width 0.18288)
		(layer "In11.Cu")
		(net "M_H_CPU1_SA_DQ<14>")
	)
	(segment
		(start 139.196572 -280.455624)
		(end 138.61669 -279.875742)
		(width 0.088646)
		(layer "In11.Cu")
		(net "M_H_CPU1_SA_DQ<14>")
	)
	(segment
		(start 156.60624 -302.392588)
		(end 156.374846 -302.623982)
		(width 0.18288)
		(layer "In11.Cu")
		(net "M_H_CPU1_SA_DQ<14>")
	)
	(segment
		(start 202.061064 -300.014386)
		(end 201.391266 -300.014386)
		(width 0.18288)
		(layer "In11.Cu")
		(net "M_H_CPU1_SA_DQ<14>")
	)
	(segment
		(start 199.242172 -302.27778)
		(end 198.731632 -302.78832)
		(width 0.18288)
		(layer "In11.Cu")
		(net "M_H_CPU1_SA_DQ<14>")
	)
	(segment
		(start 203.585318 -300.590458)
		(end 202.637136 -300.590458)
		(width 0.18288)
		(layer "In11.Cu")
		(net "M_H_CPU1_SA_DQ<14>")
	)
	(segment
		(start 127.081788 -274.598384)
		(end 127.069596 -274.591272)
		(width 0.088646)
		(layer "In11.Cu")
		(net "M_H_CPU1_SA_DQ<14>")
	)
	(segment
		(start 157.46857 -303.990502)
		(end 156.872432 -303.394364)
		(width 0.18288)
		(layer "In11.Cu")
		(net "M_H_CPU1_SA_DQ<14>")
	)
	(segment
		(start 171.333414 -307.393848)
		(end 169.702226 -305.76266)
		(width 0.18288)
		(layer "In11.Cu")
		(net "M_H_CPU1_SA_DQ<14>")
	)
	(segment
		(start 205.567026 -301.643034)
		(end 205.373986 -301.449994)
		(width 0.18288)
		(layer "In11.Cu")
		(net "M_H_CPU1_SA_DQ<14>")
	)
	(segment
		(start 204.707998 -300.623478)
		(end 204.514958 -300.816518)
		(width 0.18288)
		(layer "In11.Cu")
		(net "M_H_CPU1_SA_DQ<14>")
	)
	(segment
		(start 196.5706 -304.290222)
		(end 196.5706 -304.563018)
		(width 0.18288)
		(layer "In11.Cu")
		(net "M_H_CPU1_SA_DQ<14>")
	)
	(segment
		(start 169.702226 -305.76266)
		(end 168.889426 -305.76266)
		(width 0.18288)
		(layer "In11.Cu")
		(net "M_H_CPU1_SA_DQ<14>")
	)
	(segment
		(start 191.263016 -306.02682)
		(end 190.80861 -306.02682)
		(width 0.18288)
		(layer "In11.Cu")
		(net "M_H_CPU1_SA_DQ<14>")
	)
	(segment
		(start 129.425446 -277.03653)
		(end 129.41935 -277.032974)
		(width 0.088646)
		(layer "In11.Cu")
		(net "M_H_CPU1_SA_DQ<14>")
	)
	(segment
		(start 162.794696 -304.14087)
		(end 162.601656 -304.33391)
		(width 0.18288)
		(layer "In11.Cu")
		(net "M_H_CPU1_SA_DQ<14>")
	)
	(segment
		(start 199.710294 -301.574962)
		(end 199.484234 -301.574962)
		(width 0.18288)
		(layer "In11.Cu")
		(net "M_H_CPU1_SA_DQ<14>")
	)
	(segment
		(start 206.613252 -300.623478)
		(end 206.270606 -300.623478)
		(width 0.18288)
		(layer "In11.Cu")
		(net "M_H_CPU1_SA_DQ<14>")
	)
	(segment
		(start 163.112196 -304.14087)
		(end 162.794696 -304.14087)
		(width 0.18288)
		(layer "In11.Cu")
		(net "M_H_CPU1_SA_DQ<14>")
	)
	(segment
		(start 163.305236 -304.6349)
		(end 163.305236 -304.33391)
		(width 0.18288)
		(layer "In11.Cu")
		(net "M_H_CPU1_SA_DQ<14>")
	)
	(segment
		(start 162.601656 -304.6349)
		(end 162.393376 -304.84318)
		(width 0.18288)
		(layer "In11.Cu")
		(net "M_H_CPU1_SA_DQ<14>")
	)
	(segment
		(start 202.637136 -300.590458)
		(end 202.061064 -300.014386)
		(width 0.18288)
		(layer "In11.Cu")
		(net "M_H_CPU1_SA_DQ<14>")
	)
	(segment
		(start 161.094674 -304.51679)
		(end 160.777428 -304.51679)
		(width 0.18288)
		(layer "In11.Cu")
		(net "M_H_CPU1_SA_DQ<14>")
	)
	(segment
		(start 136.750044 -278.336502)
		(end 136.750044 -278.31796)
		(width 0.088646)
		(layer "In11.Cu")
		(net "M_H_CPU1_SA_DQ<14>")
	)
	(segment
		(start 162.393376 -304.84318)
		(end 161.421064 -304.84318)
		(width 0.18288)
		(layer "In11.Cu")
		(net "M_H_CPU1_SA_DQ<14>")
	)
	(segment
		(start 206.077566 -300.816518)
		(end 206.077566 -301.449994)
		(width 0.18288)
		(layer "In11.Cu")
		(net "M_H_CPU1_SA_DQ<14>")
	)
	(segment
		(start 127.821944 -275.8948)
		(end 127.821944 -275.872702)
		(width 0.088646)
		(layer "In11.Cu")
		(net "M_H_CPU1_SA_DQ<14>")
	)
	(segment
		(start 205.180946 -300.623478)
		(end 204.707998 -300.623478)
		(width 0.18288)
		(layer "In11.Cu")
		(net "M_H_CPU1_SA_DQ<14>")
	)
	(segment
		(start 157.103826 -302.617378)
		(end 156.879036 -302.392588)
		(width 0.18288)
		(layer "In11.Cu")
		(net "M_H_CPU1_SA_DQ<14>")
	)
	(segment
		(start 128.009396 -276.219158)
		(end 128.000506 -276.214078)
		(width 0.088646)
		(layer "In11.Cu")
		(net "M_H_CPU1_SA_DQ<14>")
	)
	(segment
		(start 128.015492 -276.222714)
		(end 128.009396 -276.219158)
		(width 0.088646)
		(layer "In11.Cu")
		(net "M_H_CPU1_SA_DQ<14>")
	)
	(segment
		(start 201.391266 -300.014386)
		(end 199.826372 -301.57928)
		(width 0.18288)
		(layer "In11.Cu")
		(net "M_H_CPU1_SA_DQ<14>")
	)
	(segment
		(start 147.898358 -290.06419)
		(end 141.136878 -283.302964)
		(width 0.18288)
		(layer "In11.Cu")
		(net "M_H_CPU1_SA_DQ<14>")
	)
	(segment
		(start 136.467596 -277.84679)
		(end 136.457182 -277.840694)
		(width 0.088646)
		(layer "In11.Cu")
		(net "M_H_CPU1_SA_DQ<14>")
	)
	(segment
		(start 205.373986 -301.449994)
		(end 205.373986 -300.816518)
		(width 0.18288)
		(layer "In11.Cu")
		(net "M_H_CPU1_SA_DQ<14>")
	)
	(segment
		(start 135.527542 -277.84679)
		(end 135.517128 -277.840694)
		(width 0.088646)
		(layer "In11.Cu")
		(net "M_H_CPU1_SA_DQ<14>")
	)
	(segment
		(start 196.337936 -304.057558)
		(end 196.5706 -304.290222)
		(width 0.18288)
		(layer "In11.Cu")
		(net "M_H_CPU1_SA_DQ<14>")
	)
	(segment
		(start 131.768596 -277.84679)
		(end 131.758182 -277.840694)
		(width 0.088646)
		(layer "In11.Cu")
		(net "M_H_CPU1_SA_DQ<14>")
	)
	(segment
		(start 204.321918 -301.195994)
		(end 204.004418 -301.195994)
		(width 0.18288)
		(layer "In11.Cu")
		(net "M_H_CPU1_SA_DQ<14>")
	)
	(segment
		(start 189.196218 -306.724812)
		(end 188.163454 -305.692048)
		(width 0.18288)
		(layer "In11.Cu")
		(net "M_H_CPU1_SA_DQ<14>")
	)
	(segment
		(start 206.270606 -300.623478)
		(end 206.077566 -300.816518)
		(width 0.18288)
		(layer "In11.Cu")
		(net "M_H_CPU1_SA_DQ<14>")
	)
	(segment
		(start 156.374846 -302.623982)
		(end 156.10205 -302.623982)
		(width 0.18288)
		(layer "In11.Cu")
		(net "M_H_CPU1_SA_DQ<14>")
	)
	(segment
		(start 128.868678 -277.024338)
		(end 128.853946 -277.032974)
		(width 0.088646)
		(layer "In11.Cu")
		(net "M_H_CPU1_SA_DQ<14>")
	)
	(segment
		(start 199.484234 -301.574962)
		(end 199.242172 -301.817024)
		(width 0.18288)
		(layer "In11.Cu")
		(net "M_H_CPU1_SA_DQ<14>")
	)
	(segment
		(start 187.357004 -305.692048)
		(end 187.177426 -305.871626)
		(width 0.18288)
		(layer "In11.Cu")
		(net "M_H_CPU1_SA_DQ<14>")
	)
	(segment
		(start 177.22088 -306.541678)
		(end 176.478438 -306.541678)
		(width 0.18288)
		(layer "In11.Cu")
		(net "M_H_CPU1_SA_DQ<14>")
	)
	(segment
		(start 130.278378 -277.838154)
		(end 130.263646 -277.84679)
		(width 0.088646)
		(layer "In11.Cu")
		(net "M_H_CPU1_SA_DQ<14>")
	)
	(segment
		(start 198.345044 -302.78832)
		(end 197.340982 -303.792636)
		(width 0.18288)
		(layer "In11.Cu")
		(net "M_H_CPU1_SA_DQ<14>")
	)
	(segment
		(start 128.47955 -277.032974)
		(end 128.47066 -277.027894)
		(width 0.088646)
		(layer "In11.Cu")
		(net "M_H_CPU1_SA_DQ<14>")
	)
	(segment
		(start 160.777428 -304.51679)
		(end 160.355788 -304.93843)
		(width 0.18288)
		(layer "In11.Cu")
		(net "M_H_CPU1_SA_DQ<14>")
	)
	(segment
		(start 179.879498 -306.650898)
		(end 179.633626 -306.405026)
		(width 0.18288)
		(layer "In11.Cu")
		(net "M_H_CPU1_SA_DQ<14>")
	)
	(segment
		(start 138.61669 -279.716738)
		(end 138.46429 -279.564338)
		(width 0.088646)
		(layer "In11.Cu")
		(net "M_H_CPU1_SA_DQ<14>")
	)
	(segment
		(start 199.714612 -301.57928)
		(end 199.710294 -301.574962)
		(width 0.18288)
		(layer "In11.Cu")
		(net "M_H_CPU1_SA_DQ<14>")
	)
	(segment
		(start 205.373986 -300.816518)
		(end 205.180946 -300.623478)
		(width 0.18288)
		(layer "In11.Cu")
		(net "M_H_CPU1_SA_DQ<14>")
	)
	(segment
		(start 176.11979 -306.18303)
		(end 175.747426 -306.18303)
		(width 0.18288)
		(layer "In11.Cu")
		(net "M_H_CPU1_SA_DQ<14>")
	)
	(segment
		(start 162.601656 -304.33391)
		(end 162.601656 -304.6349)
		(width 0.18288)
		(layer "In11.Cu")
		(net "M_H_CPU1_SA_DQ<14>")
	)
	(segment
		(start 197.340982 -303.792636)
		(end 197.068186 -303.792636)
		(width 0.18288)
		(layer "In11.Cu")
		(net "M_H_CPU1_SA_DQ<14>")
	)
	(segment
		(start 126.882398 -274.27555)
		(end 126.882398 -274.257008)
		(width 0.088646)
		(layer "In11.Cu")
		(net "M_H_CPU1_SA_DQ<14>")
	)
	(segment
		(start 205.884526 -301.643034)
		(end 205.567026 -301.643034)
		(width 0.18288)
		(layer "In11.Cu")
		(net "M_H_CPU1_SA_DQ<14>")
	)
	(segment
		(start 127.53975 -275.405088)
		(end 127.53086 -275.400008)
		(width 0.088646)
		(layer "In11.Cu")
		(net "M_H_CPU1_SA_DQ<14>")
	)
	(segment
		(start 159.063944 -304.93843)
		(end 158.116016 -303.990502)
		(width 0.18288)
		(layer "In11.Cu")
		(net "M_H_CPU1_SA_DQ<14>")
	)
	(segment
		(start 164.79774 -305.008026)
		(end 164.617654 -304.82794)
		(width 0.18288)
		(layer "In11.Cu")
		(net "M_H_CPU1_SA_DQ<14>")
	)
	(segment
		(start 197.068186 -303.792636)
		(end 196.835522 -303.559972)
		(width 0.18288)
		(layer "In11.Cu")
		(net "M_H_CPU1_SA_DQ<14>")
	)
	(segment
		(start 176.478438 -306.541678)
		(end 176.11979 -306.18303)
		(width 0.18288)
		(layer "In11.Cu")
		(net "M_H_CPU1_SA_DQ<14>")
	)
	(segment
		(start 196.5706 -304.563018)
		(end 196.315838 -304.818034)
		(width 0.18288)
		(layer "In11.Cu")
		(net "M_H_CPU1_SA_DQ<14>")
	)
	(segment
		(start 141.136878 -283.302964)
		(end 140.289788 -282.455874)
		(width 0.18288)
		(layer "In11.Cu")
		(net "M_H_CPU1_SA_DQ<14>")
	)
	(segment
		(start 168.889426 -305.76266)
		(end 168.134792 -305.008026)
		(width 0.18288)
		(layer "In11.Cu")
		(net "M_H_CPU1_SA_DQ<14>")
	)
	(segment
		(start 163.498276 -304.82794)
		(end 163.305236 -304.6349)
		(width 0.18288)
		(layer "In11.Cu")
		(net "M_H_CPU1_SA_DQ<14>")
	)
	(segment
		(start 204.514958 -300.816518)
		(end 204.514958 -301.002954)
		(width 0.18288)
		(layer "In11.Cu")
		(net "M_H_CPU1_SA_DQ<14>")
	)
	(segment
		(start 190.110618 -306.724812)
		(end 189.196218 -306.724812)
		(width 0.18288)
		(layer "In11.Cu")
		(net "M_H_CPU1_SA_DQ<14>")
	)
	(segment
		(start 188.163454 -305.692048)
		(end 187.357004 -305.692048)
		(width 0.18288)
		(layer "In11.Cu")
		(net "M_H_CPU1_SA_DQ<14>")
	)
	(segment
		(start 178.93665 -306.405026)
		(end 178.466496 -306.87518)
		(width 0.18288)
		(layer "In11.Cu")
		(net "M_H_CPU1_SA_DQ<14>")
	)
	(segment
		(start 178.466496 -306.87518)
		(end 177.554382 -306.87518)
		(width 0.18288)
		(layer "In11.Cu")
		(net "M_H_CPU1_SA_DQ<14>")
	)
	(segment
		(start 139.70254 -281.357324)
		(end 139.196572 -280.851356)
		(width 0.088646)
		(layer "In11.Cu")
		(net "M_H_CPU1_SA_DQ<14>")
	)
	(segment
		(start 132.708396 -277.84679)
		(end 132.693664 -277.838154)
		(width 0.088646)
		(layer "In11.Cu")
		(net "M_H_CPU1_SA_DQ<14>")
	)
	(segment
		(start 195.446904 -305.082194)
		(end 194.985894 -305.082194)
		(width 0.18288)
		(layer "In11.Cu")
		(net "M_H_CPU1_SA_DQ<14>")
	)
	(segment
		(start 192.714118 -306.542186)
		(end 191.778382 -306.542186)
		(width 0.18288)
		(layer "In11.Cu")
		(net "M_H_CPU1_SA_DQ<14>")
	)
	(segment
		(start 126.034546 -273.777456)
		(end 125.958346 -273.822922)
		(width 0.088646)
		(layer "In11.Cu")
		(net "M_H_CPU1_SA_DQ<14>")
	)
	(segment
		(start 156.10205 -302.623982)
		(end 155.894024 -302.415956)
		(width 0.18288)
		(layer "In11.Cu")
		(net "M_H_CPU1_SA_DQ<14>")
	)
	(segment
		(start 203.811378 -301.002954)
		(end 203.811378 -300.816518)
		(width 0.18288)
		(layer "In11.Cu")
		(net "M_H_CPU1_SA_DQ<14>")
	)
	(segment
		(start 164.617654 -304.82794)
		(end 163.498276 -304.82794)
		(width 0.18288)
		(layer "In11.Cu")
		(net "M_H_CPU1_SA_DQ<14>")
	)
	(segment
		(start 196.315838 -304.818034)
		(end 195.711826 -304.818034)
		(width 0.18288)
		(layer "In11.Cu")
		(net "M_H_CPU1_SA_DQ<14>")
	)
	(segment
		(start 136.937496 -278.66086)
		(end 136.928606 -278.65578)
		(width 0.088646)
		(layer "In11.Cu")
		(net "M_H_CPU1_SA_DQ<14>")
	)
	(segment
		(start 187.177426 -305.871626)
		(end 183.672226 -305.871626)
		(width 0.18288)
		(layer "In11.Cu")
		(net "M_H_CPU1_SA_DQ<14>")
	)
	(segment
		(start 156.872432 -303.121568)
		(end 157.103826 -302.890174)
		(width 0.18288)
		(layer "In11.Cu")
		(net "M_H_CPU1_SA_DQ<14>")
	)
	(segment
		(start 173.58614 -307.393848)
		(end 171.333414 -307.393848)
		(width 0.18288)
		(layer "In11.Cu")
		(net "M_H_CPU1_SA_DQ<14>")
	)
	(segment
		(start 195.711826 -304.818034)
		(end 195.446904 -305.082194)
		(width 0.18288)
		(layer "In11.Cu")
		(net "M_H_CPU1_SA_DQ<14>")
	)
	(segment
		(start 157.103826 -302.890174)
		(end 157.103826 -302.617378)
		(width 0.18288)
		(layer "In11.Cu")
		(net "M_H_CPU1_SA_DQ<14>")
	)
	(segment
		(start 182.892954 -306.650898)
		(end 179.879498 -306.650898)
		(width 0.18288)
		(layer "In11.Cu")
		(net "M_H_CPU1_SA_DQ<14>")
	)
	(segment
		(start 133.648196 -277.84679)
		(end 133.633464 -277.838154)
		(width 0.088646)
		(layer "In11.Cu")
		(net "M_H_CPU1_SA_DQ<14>")
	)
	(segment
		(start 161.421064 -304.84318)
		(end 161.094674 -304.51679)
		(width 0.18288)
		(layer "In11.Cu")
		(net "M_H_CPU1_SA_DQ<14>")
	)
	(segment
		(start 175.310546 -306.61991)
		(end 174.360078 -306.61991)
		(width 0.18288)
		(layer "In11.Cu")
		(net "M_H_CPU1_SA_DQ<14>")
	)
	(segment
		(start 194.044062 -304.779426)
		(end 193.616326 -305.207162)
		(width 0.18288)
		(layer "In11.Cu")
		(net "M_H_CPU1_SA_DQ<14>")
	)
	(segment
		(start 193.616326 -305.207162)
		(end 193.616326 -305.639978)
		(width 0.18288)
		(layer "In11.Cu")
		(net "M_H_CPU1_SA_DQ<14>")
	)
	(segment
		(start 204.514958 -301.002954)
		(end 204.321918 -301.195994)
		(width 0.18288)
		(layer "In11.Cu")
		(net "M_H_CPU1_SA_DQ<14>")
	)
	(segment
		(start 174.360078 -306.61991)
		(end 173.58614 -307.393848)
		(width 0.18288)
		(layer "In11.Cu")
		(net "M_H_CPU1_SA_DQ<14>")
	)
	(segment
		(start 206.077566 -301.449994)
		(end 205.884526 -301.643034)
		(width 0.18288)
		(layer "In11.Cu")
		(net "M_H_CPU1_SA_DQ<14>")
	)
	(segment
		(start 190.80861 -306.02682)
		(end 190.110618 -306.724812)
		(width 0.18288)
		(layer "In11.Cu")
		(net "M_H_CPU1_SA_DQ<14>")
	)
	(segment
		(start 191.778382 -306.542186)
		(end 191.263016 -306.02682)
		(width 0.18288)
		(layer "In11.Cu")
		(net "M_H_CPU1_SA_DQ<14>")
	)
	(segment
		(start 168.134792 -305.008026)
		(end 164.79774 -305.008026)
		(width 0.18288)
		(layer "In11.Cu")
		(net "M_H_CPU1_SA_DQ<14>")
	)
	(segment
		(start 203.811378 -300.816518)
		(end 203.585318 -300.590458)
		(width 0.18288)
		(layer "In11.Cu")
		(net "M_H_CPU1_SA_DQ<14>")
	)
	(segment
		(start 196.562726 -303.559972)
		(end 196.337936 -303.784762)
		(width 0.18288)
		(layer "In11.Cu")
		(net "M_H_CPU1_SA_DQ<14>")
	)
	(segment
		(start 140.289788 -282.455874)
		(end 139.927838 -281.582622)
		(width 0.18288)
		(layer "In11.Cu")
		(net "M_H_CPU1_SA_DQ<14>")
	)
	(segment
		(start 147.898358 -291.797486)
		(end 147.898358 -290.06419)
		(width 0.18288)
		(layer "In11.Cu")
		(net "M_H_CPU1_SA_DQ<14>")
	)
	(segment
		(start 183.672226 -305.871626)
		(end 182.892954 -306.650898)
		(width 0.18288)
		(layer "In11.Cu")
		(net "M_H_CPU1_SA_DQ<14>")
	)
	(segment
		(start 175.747426 -306.18303)
		(end 175.310546 -306.61991)
		(width 0.18288)
		(layer "In11.Cu")
		(net "M_H_CPU1_SA_DQ<14>")
	)
	(segment
		(start 139.927838 -281.582622)
		(end 139.70254 -281.357324)
		(width 0.18288)
		(layer "In11.Cu")
		(net "M_H_CPU1_SA_DQ<14>")
	)
	(segment
		(start 199.826372 -301.57928)
		(end 199.714612 -301.57928)
		(width 0.18288)
		(layer "In11.Cu")
		(net "M_H_CPU1_SA_DQ<14>")
	)
	(segment
		(start 139.196572 -280.851356)
		(end 139.196572 -280.455624)
		(width 0.088646)
		(layer "In11.Cu")
		(net "M_H_CPU1_SA_DQ<14>")
	)
	(segment
		(start 163.305236 -304.33391)
		(end 163.112196 -304.14087)
		(width 0.18288)
		(layer "In11.Cu")
		(net "M_H_CPU1_SA_DQ<14>")
	)
	(segment
		(start 138.61669 -279.875742)
		(end 138.61669 -279.716738)
		(width 0.088646)
		(layer "In11.Cu")
		(net "M_H_CPU1_SA_DQ<14>")
	)
	(segment
		(start 177.554382 -306.87518)
		(end 177.22088 -306.541678)
		(width 0.18288)
		(layer "In11.Cu")
		(net "M_H_CPU1_SA_DQ<14>")
	)
	(segment
		(start 199.242172 -301.817024)
		(end 199.242172 -302.27778)
		(width 0.18288)
		(layer "In11.Cu")
		(net "M_H_CPU1_SA_DQ<14>")
	)
	(segment
		(start 155.894024 -302.415956)
		(end 155.894024 -299.793152)
		(width 0.18288)
		(layer "In11.Cu")
		(net "M_H_CPU1_SA_DQ<14>")
	)
	(segment
		(start 155.894024 -299.793152)
		(end 147.898358 -291.797486)
		(width 0.18288)
		(layer "In11.Cu")
		(net "M_H_CPU1_SA_DQ<14>")
	)
	(segment
		(start 125.958346 -273.822922)
		(end 125.377194 -274.266914)
		(width 0.088646)
		(layer "In11.Cu")
		(net "M_H_CPU1_SA_DQ<14>")
	)
	(segment
		(start 129.88925 -277.84679)
		(end 129.88036 -277.84171)
		(width 0.088646)
		(layer "In11.Cu")
		(net "M_H_CPU1_SA_DQ<14>")
	)
	(segment
		(start 193.616326 -305.639978)
		(end 192.714118 -306.542186)
		(width 0.18288)
		(layer "In11.Cu")
		(net "M_H_CPU1_SA_DQ<14>")
	)
	(arc
		(start 126.882398 -274.257008)
		(mid 126.804287 -273.980059)
		(end 126.59995 -273.777456)
		(width 0.088646)
		(layer "In11.Cu")
		(net "M_H_CPU1_SA_DQ<14>")
	)
	(arc
		(start 127.352298 -275.08073)
		(mid 127.280063 -274.804206)
		(end 127.081788 -274.598384)
		(width 0.088646)
		(layer "In11.Cu")
		(net "M_H_CPU1_SA_DQ<14>")
	)
	(arc
		(start 126.59995 -273.777456)
		(mid 126.317248 -273.70168)
		(end 126.034546 -273.777456)
		(width 0.088646)
		(layer "In11.Cu")
		(net "M_H_CPU1_SA_DQ<14>")
	)
	(arc
		(start 138.338306 -279.469596)
		(mid 138.207392 -279.333236)
		(end 138.159744 -279.150318)
		(width 0.088646)
		(layer "In11.Cu")
		(net "M_H_CPU1_SA_DQ<14>")
	)
	(arc
		(start 127.069596 -274.591272)
		(mid 126.934663 -274.457918)
		(end 126.882398 -274.27555)
		(width 0.088646)
		(layer "In11.Cu")
		(net "M_H_CPU1_SA_DQ<14>")
	)
	(arc
		(start 130.263646 -277.84679)
		(mid 130.076448 -277.896933)
		(end 129.88925 -277.84679)
		(width 0.088646)
		(layer "In11.Cu")
		(net "M_H_CPU1_SA_DQ<14>")
	)
	(arc
		(start 132.693664 -277.838154)
		(mid 132.417223 -277.770988)
		(end 132.142992 -277.84679)
		(width 0.088646)
		(layer "In11.Cu")
		(net "M_H_CPU1_SA_DQ<14>")
	)
	(arc
		(start 129.41935 -277.032974)
		(mid 129.145151 -276.957139)
		(end 128.868678 -277.024338)
		(width 0.088646)
		(layer "In11.Cu")
		(net "M_H_CPU1_SA_DQ<14>")
	)
	(arc
		(start 134.022592 -277.84679)
		(mid 133.835394 -277.896933)
		(end 133.648196 -277.84679)
		(width 0.088646)
		(layer "In11.Cu")
		(net "M_H_CPU1_SA_DQ<14>")
	)
	(arc
		(start 131.203446 -277.84679)
		(mid 131.016248 -277.896933)
		(end 130.82905 -277.84679)
		(width 0.088646)
		(layer "In11.Cu")
		(net "M_H_CPU1_SA_DQ<14>")
	)
	(arc
		(start 136.457182 -277.840694)
		(mid 136.17875 -277.77088)
		(end 135.901938 -277.84679)
		(width 0.088646)
		(layer "In11.Cu")
		(net "M_H_CPU1_SA_DQ<14>")
	)
	(arc
		(start 135.901938 -277.84679)
		(mid 135.71474 -277.896933)
		(end 135.527542 -277.84679)
		(width 0.088646)
		(layer "In11.Cu")
		(net "M_H_CPU1_SA_DQ<14>")
	)
	(arc
		(start 138.159744 -279.140412)
		(mid 138.081633 -278.863463)
		(end 137.877296 -278.66086)
		(width 0.088646)
		(layer "In11.Cu")
		(net "M_H_CPU1_SA_DQ<14>")
	)
	(arc
		(start 136.750044 -278.31796)
		(mid 136.669882 -278.045771)
		(end 136.467596 -277.84679)
		(width 0.088646)
		(layer "In11.Cu")
		(net "M_H_CPU1_SA_DQ<14>")
	)
	(arc
		(start 134.962392 -277.84679)
		(mid 134.775194 -277.896933)
		(end 134.587996 -277.84679)
		(width 0.088646)
		(layer "In11.Cu")
		(net "M_H_CPU1_SA_DQ<14>")
	)
	(arc
		(start 128.292098 -276.708616)
		(mid 128.218107 -276.42905)
		(end 128.015492 -276.222714)
		(width 0.088646)
		(layer "In11.Cu")
		(net "M_H_CPU1_SA_DQ<14>")
	)
	(arc
		(start 128.47066 -277.027894)
		(mid 128.339746 -276.891534)
		(end 128.292098 -276.708616)
		(width 0.088646)
		(layer "In11.Cu")
		(net "M_H_CPU1_SA_DQ<14>")
	)
	(arc
		(start 134.587996 -277.84679)
		(mid 134.305294 -277.771048)
		(end 134.022592 -277.84679)
		(width 0.088646)
		(layer "In11.Cu")
		(net "M_H_CPU1_SA_DQ<14>")
	)
	(arc
		(start 135.517128 -277.840694)
		(mid 135.23895 -277.771002)
		(end 134.962392 -277.84679)
		(width 0.088646)
		(layer "In11.Cu")
		(net "M_H_CPU1_SA_DQ<14>")
	)
	(arc
		(start 133.633464 -277.838154)
		(mid 133.357023 -277.770988)
		(end 133.082792 -277.84679)
		(width 0.088646)
		(layer "In11.Cu")
		(net "M_H_CPU1_SA_DQ<14>")
	)
	(arc
		(start 131.758182 -277.840694)
		(mid 131.480004 -277.771002)
		(end 131.203446 -277.84679)
		(width 0.088646)
		(layer "In11.Cu")
		(net "M_H_CPU1_SA_DQ<14>")
	)
	(arc
		(start 138.441938 -279.543256)
		(mid 138.396343 -279.506512)
		(end 138.347196 -279.474676)
		(width 0.088646)
		(layer "In11.Cu")
		(net "M_H_CPU1_SA_DQ<14>")
	)
	(arc
		(start 129.88036 -277.84171)
		(mid 129.749446 -277.70535)
		(end 129.701798 -277.522432)
		(width 0.088646)
		(layer "In11.Cu")
		(net "M_H_CPU1_SA_DQ<14>")
	)
	(arc
		(start 130.82905 -277.84679)
		(mid 130.554821 -277.770865)
		(end 130.278378 -277.838154)
		(width 0.088646)
		(layer "In11.Cu")
		(net "M_H_CPU1_SA_DQ<14>")
	)
	(arc
		(start 133.082792 -277.84679)
		(mid 132.895594 -277.896933)
		(end 132.708396 -277.84679)
		(width 0.088646)
		(layer "In11.Cu")
		(net "M_H_CPU1_SA_DQ<14>")
	)
	(arc
		(start 127.821944 -275.872702)
		(mid 127.741033 -275.602574)
		(end 127.53975 -275.405088)
		(width 0.088646)
		(layer "In11.Cu")
		(net "M_H_CPU1_SA_DQ<14>")
	)
	(arc
		(start 137.311892 -278.66086)
		(mid 137.124694 -278.711003)
		(end 136.937496 -278.66086)
		(width 0.088646)
		(layer "In11.Cu")
		(net "M_H_CPU1_SA_DQ<14>")
	)
	(arc
		(start 136.928606 -278.65578)
		(mid 136.797692 -278.51942)
		(end 136.750044 -278.336502)
		(width 0.088646)
		(layer "In11.Cu")
		(net "M_H_CPU1_SA_DQ<14>")
	)
	(arc
		(start 129.701798 -277.522432)
		(mid 129.627882 -277.24293)
		(end 129.425446 -277.03653)
		(width 0.088646)
		(layer "In11.Cu")
		(net "M_H_CPU1_SA_DQ<14>")
	)
	(arc
		(start 128.853946 -277.032974)
		(mid 128.666748 -277.083117)
		(end 128.47955 -277.032974)
		(width 0.088646)
		(layer "In11.Cu")
		(net "M_H_CPU1_SA_DQ<14>")
	)
	(arc
		(start 127.53086 -275.400008)
		(mid 127.399946 -275.263648)
		(end 127.352298 -275.08073)
		(width 0.088646)
		(layer "In11.Cu")
		(net "M_H_CPU1_SA_DQ<14>")
	)
	(arc
		(start 128.000506 -276.214078)
		(mid 127.869592 -276.077718)
		(end 127.821944 -275.8948)
		(width 0.088646)
		(layer "In11.Cu")
		(net "M_H_CPU1_SA_DQ<14>")
	)
	(arc
		(start 132.142992 -277.84679)
		(mid 131.955794 -277.896933)
		(end 131.768596 -277.84679)
		(width 0.088646)
		(layer "In11.Cu")
		(net "M_H_CPU1_SA_DQ<14>")
	)
	(arc
		(start 138.46429 -279.564338)
		(mid 138.453255 -279.553647)
		(end 138.441938 -279.543256)
		(width 0.088646)
		(layer "In11.Cu")
		(net "M_H_CPU1_SA_DQ<14>")
	)
	(arc
		(start 137.877296 -278.66086)
		(mid 137.594594 -278.585084)
		(end 137.311892 -278.66086)
		(width 0.088646)
		(layer "In11.Cu")
		(net "M_H_CPU1_SA_DQ<14>")
	)
	(segment
		(start 211.619592 -299.316902)
		(end 210.028028 -299.316902)
		(width 0.20066)
		(layer "F.Cu")
		(net "M_H_CPU1_SA_DQ<13>")
	)
	(segment
		(start 209.186526 -298.885356)
		(end 209.180176 -298.891706)
		(width 0.1016)
		(layer "F.Cu")
		(net "M_H_CPU1_SA_DQ<13>")
	)
	(segment
		(start 206.320644 -299.565314)
		(end 205.84541 -299.565314)
		(width 0.20066)
		(layer "F.Cu")
		(net "M_H_CPU1_SA_DQ<13>")
	)
	(segment
		(start 206.991458 -298.891706)
		(end 206.971392 -298.891706)
		(width 0.101854)
		(layer "F.Cu")
		(net "M_H_CPU1_SA_DQ<13>")
	)
	(segment
		(start 209.180176 -298.891706)
		(end 206.991458 -298.891706)
		(width 0.1016)
		(layer "F.Cu")
		(net "M_H_CPU1_SA_DQ<13>")
	)
	(segment
		(start 206.508604 -299.009816)
		(end 206.508604 -299.377354)
		(width 0.20066)
		(layer "F.Cu")
		(net "M_H_CPU1_SA_DQ<13>")
	)
	(segment
		(start 123.967494 -272.917158)
		(end 123.967494 -273.452844)
		(width 0.20066)
		(layer "F.Cu")
		(net "M_H_CPU1_SA_DQ<13>")
	)
	(segment
		(start 206.626714 -298.891706)
		(end 206.508604 -299.009816)
		(width 0.20066)
		(layer "F.Cu")
		(net "M_H_CPU1_SA_DQ<13>")
	)
	(segment
		(start 206.971392 -298.891706)
		(end 206.626714 -298.891706)
		(width 0.20066)
		(layer "F.Cu")
		(net "M_H_CPU1_SA_DQ<13>")
	)
	(segment
		(start 211.619846 -299.316648)
		(end 211.619592 -299.316902)
		(width 0.20066)
		(layer "F.Cu")
		(net "M_H_CPU1_SA_DQ<13>")
	)
	(segment
		(start 204.076046 -299.316648)
		(end 202.971146 -299.316648)
		(width 0.20066)
		(layer "F.Cu")
		(net "M_H_CPU1_SA_DQ<13>")
	)
	(segment
		(start 123.967494 -273.452844)
		(end 123.967748 -273.453098)
		(width 0.20066)
		(layer "F.Cu")
		(net "M_H_CPU1_SA_DQ<13>")
	)
	(segment
		(start 206.508604 -299.377354)
		(end 206.320644 -299.565314)
		(width 0.20066)
		(layer "F.Cu")
		(net "M_H_CPU1_SA_DQ<13>")
	)
	(segment
		(start 210.028028 -299.316902)
		(end 209.596482 -298.885356)
		(width 0.20066)
		(layer "F.Cu")
		(net "M_H_CPU1_SA_DQ<13>")
	)
	(segment
		(start 205.596744 -299.316648)
		(end 204.076046 -299.316648)
		(width 0.20066)
		(layer "F.Cu")
		(net "M_H_CPU1_SA_DQ<13>")
	)
	(segment
		(start 209.596482 -298.885356)
		(end 209.186526 -298.885356)
		(width 0.20066)
		(layer "F.Cu")
		(net "M_H_CPU1_SA_DQ<13>")
	)
	(segment
		(start 205.84541 -299.565314)
		(end 205.596744 -299.316648)
		(width 0.20066)
		(layer "F.Cu")
		(net "M_H_CPU1_SA_DQ<13>")
	)
	(segment
		(start 156.5148 -299.695108)
		(end 148.427694 -291.608002)
		(width 0.18288)
		(layer "In11.Cu")
		(net "M_H_CPU1_SA_DQ<13>")
	)
	(segment
		(start 127.911352 -274.754848)
		(end 127.90805 -274.752816)
		(width 0.088646)
		(layer "In11.Cu")
		(net "M_H_CPU1_SA_DQ<13>")
	)
	(segment
		(start 148.427694 -291.608002)
		(end 148.427694 -289.861752)
		(width 0.18288)
		(layer "In11.Cu")
		(net "M_H_CPU1_SA_DQ<13>")
	)
	(segment
		(start 134.587996 -277.198074)
		(end 134.573264 -277.20671)
		(width 0.088646)
		(layer "In11.Cu")
		(net "M_H_CPU1_SA_DQ<13>")
	)
	(segment
		(start 199.382126 -300.461426)
		(end 198.881746 -300.961806)
		(width 0.18288)
		(layer "In11.Cu")
		(net "M_H_CPU1_SA_DQ<13>")
	)
	(segment
		(start 166.286942 -304.49774)
		(end 166.093902 -304.3047)
		(width 0.18288)
		(layer "In11.Cu")
		(net "M_H_CPU1_SA_DQ<13>")
	)
	(segment
		(start 185.948574 -304.735738)
		(end 185.948574 -305.169824)
		(width 0.18288)
		(layer "In11.Cu")
		(net "M_H_CPU1_SA_DQ<13>")
	)
	(segment
		(start 183.265826 -305.465226)
		(end 181.983634 -305.465226)
		(width 0.18288)
		(layer "In11.Cu")
		(net "M_H_CPU1_SA_DQ<13>")
	)
	(segment
		(start 166.797482 -303.915064)
		(end 166.797482 -304.3047)
		(width 0.18288)
		(layer "In11.Cu")
		(net "M_H_CPU1_SA_DQ<13>")
	)
	(segment
		(start 158.573216 -302.483266)
		(end 158.380176 -302.290226)
		(width 0.18288)
		(layer "In11.Cu")
		(net "M_H_CPU1_SA_DQ<13>")
	)
	(segment
		(start 173.587918 -306.541678)
		(end 172.372528 -306.541678)
		(width 0.18288)
		(layer "In11.Cu")
		(net "M_H_CPU1_SA_DQ<13>")
	)
	(segment
		(start 202.814428 -299.714666)
		(end 202.541378 -299.714666)
		(width 0.18288)
		(layer "In11.Cu")
		(net "M_H_CPU1_SA_DQ<13>")
	)
	(segment
		(start 158.766256 -303.869852)
		(end 158.573216 -303.676812)
		(width 0.18288)
		(layer "In11.Cu")
		(net "M_H_CPU1_SA_DQ<13>")
	)
	(segment
		(start 137.029444 -277.540974)
		(end 137.029444 -277.522432)
		(width 0.088646)
		(layer "In11.Cu")
		(net "M_H_CPU1_SA_DQ<13>")
	)
	(segment
		(start 197.814946 -302.384206)
		(end 196.781674 -302.384206)
		(width 0.18288)
		(layer "In11.Cu")
		(net "M_H_CPU1_SA_DQ<13>")
	)
	(segment
		(start 185.948574 -305.169824)
		(end 185.755534 -305.362864)
		(width 0.18288)
		(layer "In11.Cu")
		(net "M_H_CPU1_SA_DQ<13>")
	)
	(segment
		(start 181.790594 -305.939952)
		(end 181.597554 -306.132992)
		(width 0.18288)
		(layer "In11.Cu")
		(net "M_H_CPU1_SA_DQ<13>")
	)
	(segment
		(start 166.093902 -303.915064)
		(end 165.900862 -303.722024)
		(width 0.18288)
		(layer "In11.Cu")
		(net "M_H_CPU1_SA_DQ<13>")
	)
	(segment
		(start 188.670438 -304.842418)
		(end 187.46089 -304.842418)
		(width 0.18288)
		(layer "In11.Cu")
		(net "M_H_CPU1_SA_DQ<13>")
	)
	(segment
		(start 181.790594 -305.658266)
		(end 181.790594 -305.939952)
		(width 0.18288)
		(layer "In11.Cu")
		(net "M_H_CPU1_SA_DQ<13>")
	)
	(segment
		(start 189.582806 -305.808126)
		(end 189.013846 -305.808126)
		(width 0.18288)
		(layer "In11.Cu")
		(net "M_H_CPU1_SA_DQ<13>")
	)
	(segment
		(start 127.923036 -274.761452)
		(end 127.914146 -274.756372)
		(width 0.088646)
		(layer "In11.Cu")
		(net "M_H_CPU1_SA_DQ<13>")
	)
	(segment
		(start 138.260582 -278.017224)
		(end 138.251692 -278.012144)
		(width 0.088646)
		(layer "In11.Cu")
		(net "M_H_CPU1_SA_DQ<13>")
	)
	(segment
		(start 202.971146 -299.316648)
		(end 202.971146 -299.473112)
		(width 0.18288)
		(layer "In11.Cu")
		(net "M_H_CPU1_SA_DQ<13>")
	)
	(segment
		(start 201.978006 -298.953936)
		(end 201.816208 -298.88688)
		(width 0.18288)
		(layer "In11.Cu")
		(net "M_H_CPU1_SA_DQ<13>")
	)
	(segment
		(start 185.244994 -305.169824)
		(end 185.244994 -304.735738)
		(width 0.18288)
		(layer "In11.Cu")
		(net "M_H_CPU1_SA_DQ<13>")
	)
	(segment
		(start 159.469836 -302.285146)
		(end 159.276796 -302.478186)
		(width 0.18288)
		(layer "In11.Cu")
		(net "M_H_CPU1_SA_DQ<13>")
	)
	(segment
		(start 194.008502 -304.042826)
		(end 192.359534 -305.691794)
		(width 0.18288)
		(layer "In11.Cu")
		(net "M_H_CPU1_SA_DQ<13>")
	)
	(segment
		(start 135.527796 -277.198074)
		(end 135.513064 -277.20671)
		(width 0.088646)
		(layer "In11.Cu")
		(net "M_H_CPU1_SA_DQ<13>")
	)
	(segment
		(start 172.235876 -306.405026)
		(end 171.150026 -306.405026)
		(width 0.18288)
		(layer "In11.Cu")
		(net "M_H_CPU1_SA_DQ<13>")
	)
	(segment
		(start 179.885086 -305.721766)
		(end 178.73345 -305.721766)
		(width 0.18288)
		(layer "In11.Cu")
		(net "M_H_CPU1_SA_DQ<13>")
	)
	(segment
		(start 163.266374 -303.575466)
		(end 162.52063 -303.575466)
		(width 0.18288)
		(layer "In11.Cu")
		(net "M_H_CPU1_SA_DQ<13>")
	)
	(segment
		(start 201.816208 -298.88688)
		(end 201.529696 -298.88688)
		(width 0.18288)
		(layer "In11.Cu")
		(net "M_H_CPU1_SA_DQ<13>")
	)
	(segment
		(start 160.350454 -302.909224)
		(end 160.350454 -302.618648)
		(width 0.18288)
		(layer "In11.Cu")
		(net "M_H_CPU1_SA_DQ<13>")
	)
	(segment
		(start 165.019228 -303.722024)
		(end 164.531294 -304.209958)
		(width 0.18288)
		(layer "In11.Cu")
		(net "M_H_CPU1_SA_DQ<13>")
	)
	(segment
		(start 172.372528 -306.541678)
		(end 172.235876 -306.405026)
		(width 0.18288)
		(layer "In11.Cu")
		(net "M_H_CPU1_SA_DQ<13>")
	)
	(segment
		(start 168.146476 -303.722024)
		(end 166.990522 -303.722024)
		(width 0.18288)
		(layer "In11.Cu")
		(net "M_H_CPU1_SA_DQ<13>")
	)
	(segment
		(start 201.529696 -298.88688)
		(end 199.95515 -300.461426)
		(width 0.18288)
		(layer "In11.Cu")
		(net "M_H_CPU1_SA_DQ<13>")
	)
	(segment
		(start 166.990522 -303.722024)
		(end 166.797482 -303.915064)
		(width 0.18288)
		(layer "In11.Cu")
		(net "M_H_CPU1_SA_DQ<13>")
	)
	(segment
		(start 138.507978 -278.758142)
		(end 138.439144 -278.689308)
		(width 0.088646)
		(layer "In11.Cu")
		(net "M_H_CPU1_SA_DQ<13>")
	)
	(segment
		(start 126.049278 -273.137376)
		(end 126.034546 -273.12874)
		(width 0.088646)
		(layer "In11.Cu")
		(net "M_H_CPU1_SA_DQ<13>")
	)
	(segment
		(start 169.09669 -304.672238)
		(end 168.146476 -303.722024)
		(width 0.18288)
		(layer "In11.Cu")
		(net "M_H_CPU1_SA_DQ<13>")
	)
	(segment
		(start 138.507978 -279.216866)
		(end 138.507978 -278.758142)
		(width 0.088646)
		(layer "In11.Cu")
		(net "M_H_CPU1_SA_DQ<13>")
	)
	(segment
		(start 202.971146 -299.473112)
		(end 202.911202 -299.617892)
		(width 0.18288)
		(layer "In11.Cu")
		(net "M_H_CPU1_SA_DQ<13>")
	)
	(segment
		(start 159.98317 -303.79416)
		(end 159.98317 -303.276508)
		(width 0.18288)
		(layer "In11.Cu")
		(net "M_H_CPU1_SA_DQ<13>")
	)
	(segment
		(start 185.755534 -305.362864)
		(end 185.438034 -305.362864)
		(width 0.18288)
		(layer "In11.Cu")
		(net "M_H_CPU1_SA_DQ<13>")
	)
	(segment
		(start 202.191366 -299.167296)
		(end 201.978006 -298.953936)
		(width 0.18288)
		(layer "In11.Cu")
		(net "M_H_CPU1_SA_DQ<13>")
	)
	(segment
		(start 163.900866 -304.209958)
		(end 163.266374 -303.575466)
		(width 0.18288)
		(layer "In11.Cu")
		(net "M_H_CPU1_SA_DQ<13>")
	)
	(segment
		(start 198.881746 -301.317406)
		(end 197.814946 -302.384206)
		(width 0.18288)
		(layer "In11.Cu")
		(net "M_H_CPU1_SA_DQ<13>")
	)
	(segment
		(start 125.66015 -273.12874)
		(end 125.659642 -273.128994)
		(width 0.088646)
		(layer "In11.Cu")
		(net "M_H_CPU1_SA_DQ<13>")
	)
	(segment
		(start 124.347478 -273.44116)
		(end 123.979686 -273.44116)
		(width 0.088646)
		(layer "In11.Cu")
		(net "M_H_CPU1_SA_DQ<13>")
	)
	(segment
		(start 181.280054 -306.132992)
		(end 181.087014 -305.939952)
		(width 0.18288)
		(layer "In11.Cu")
		(net "M_H_CPU1_SA_DQ<13>")
	)
	(segment
		(start 159.98317 -303.276508)
		(end 160.350454 -302.909224)
		(width 0.18288)
		(layer "In11.Cu")
		(net "M_H_CPU1_SA_DQ<13>")
	)
	(segment
		(start 196.781674 -302.384206)
		(end 195.688204 -303.477676)
		(width 0.18288)
		(layer "In11.Cu")
		(net "M_H_CPU1_SA_DQ<13>")
	)
	(segment
		(start 181.087014 -305.939952)
		(end 181.087014 -305.658266)
		(width 0.18288)
		(layer "In11.Cu")
		(net "M_H_CPU1_SA_DQ<13>")
	)
	(segment
		(start 140.302742 -281.39898)
		(end 139.692634 -280.788872)
		(width 0.18288)
		(layer "In11.Cu")
		(net "M_H_CPU1_SA_DQ<13>")
	)
	(segment
		(start 131.768596 -277.198074)
		(end 131.758182 -277.20417)
		(width 0.088646)
		(layer "In11.Cu")
		(net "M_H_CPU1_SA_DQ<13>")
	)
	(segment
		(start 199.95515 -300.461426)
		(end 199.382126 -300.461426)
		(width 0.18288)
		(layer "In11.Cu")
		(net "M_H_CPU1_SA_DQ<13>")
	)
	(segment
		(start 136.850882 -277.203154)
		(end 136.841992 -277.198074)
		(width 0.088646)
		(layer "In11.Cu")
		(net "M_H_CPU1_SA_DQ<13>")
	)
	(segment
		(start 140.541756 -281.975814)
		(end 140.302742 -281.39898)
		(width 0.18288)
		(layer "In11.Cu")
		(net "M_H_CPU1_SA_DQ<13>")
	)
	(segment
		(start 178.289712 -306.165504)
		(end 177.67808 -306.165504)
		(width 0.18288)
		(layer "In11.Cu")
		(net "M_H_CPU1_SA_DQ<13>")
	)
	(segment
		(start 174.584106 -305.54549)
		(end 173.587918 -306.541678)
		(width 0.18288)
		(layer "In11.Cu")
		(net "M_H_CPU1_SA_DQ<13>")
	)
	(segment
		(start 158.380176 -302.290226)
		(end 157.518862 -302.290226)
		(width 0.18288)
		(layer "In11.Cu")
		(net "M_H_CPU1_SA_DQ<13>")
	)
	(segment
		(start 166.797482 -304.3047)
		(end 166.604442 -304.49774)
		(width 0.18288)
		(layer "In11.Cu")
		(net "M_H_CPU1_SA_DQ<13>")
	)
	(segment
		(start 159.083756 -303.869852)
		(end 158.766256 -303.869852)
		(width 0.18288)
		(layer "In11.Cu")
		(net "M_H_CPU1_SA_DQ<13>")
	)
	(segment
		(start 129.981198 -276.718522)
		(end 129.981198 -276.708616)
		(width 0.088646)
		(layer "In11.Cu")
		(net "M_H_CPU1_SA_DQ<13>")
	)
	(segment
		(start 125.189996 -273.942556)
		(end 125.182376 -273.946874)
		(width 0.088646)
		(layer "In11.Cu")
		(net "M_H_CPU1_SA_DQ<13>")
	)
	(segment
		(start 127.161798 -273.468592)
		(end 127.161798 -273.453098)
		(width 0.088646)
		(layer "In11.Cu")
		(net "M_H_CPU1_SA_DQ<13>")
	)
	(segment
		(start 185.438034 -305.362864)
		(end 185.244994 -305.169824)
		(width 0.18288)
		(layer "In11.Cu")
		(net "M_H_CPU1_SA_DQ<13>")
	)
	(segment
		(start 136.467596 -277.198074)
		(end 136.457182 -277.20417)
		(width 0.088646)
		(layer "In11.Cu")
		(net "M_H_CPU1_SA_DQ<13>")
	)
	(segment
		(start 189.873382 -305.51755)
		(end 189.582806 -305.808126)
		(width 0.18288)
		(layer "In11.Cu")
		(net "M_H_CPU1_SA_DQ<13>")
	)
	(segment
		(start 185.244994 -304.735738)
		(end 185.051954 -304.542698)
		(width 0.18288)
		(layer "In11.Cu")
		(net "M_H_CPU1_SA_DQ<13>")
	)
	(segment
		(start 191.69253 -305.691794)
		(end 191.518286 -305.51755)
		(width 0.18288)
		(layer "In11.Cu")
		(net "M_H_CPU1_SA_DQ<13>")
	)
	(segment
		(start 171.150026 -306.405026)
		(end 169.417238 -304.672238)
		(width 0.18288)
		(layer "In11.Cu")
		(net "M_H_CPU1_SA_DQ<13>")
	)
	(segment
		(start 191.518286 -305.51755)
		(end 189.873382 -305.51755)
		(width 0.18288)
		(layer "In11.Cu")
		(net "M_H_CPU1_SA_DQ<13>")
	)
	(segment
		(start 202.911202 -299.617892)
		(end 202.814428 -299.714666)
		(width 0.18288)
		(layer "In11.Cu")
		(net "M_H_CPU1_SA_DQ<13>")
	)
	(segment
		(start 198.881746 -300.961806)
		(end 198.881746 -301.317406)
		(width 0.18288)
		(layer "In11.Cu")
		(net "M_H_CPU1_SA_DQ<13>")
	)
	(segment
		(start 162.52063 -303.575466)
		(end 162.104324 -303.991772)
		(width 0.18288)
		(layer "In11.Cu")
		(net "M_H_CPU1_SA_DQ<13>")
	)
	(segment
		(start 181.597554 -306.132992)
		(end 181.280054 -306.132992)
		(width 0.18288)
		(layer "In11.Cu")
		(net "M_H_CPU1_SA_DQ<13>")
	)
	(segment
		(start 127.452882 -273.947636)
		(end 127.443992 -273.942556)
		(width 0.088646)
		(layer "In11.Cu")
		(net "M_H_CPU1_SA_DQ<13>")
	)
	(segment
		(start 188.853826 -305.025806)
		(end 188.670438 -304.842418)
		(width 0.18288)
		(layer "In11.Cu")
		(net "M_H_CPU1_SA_DQ<13>")
	)
	(segment
		(start 148.427694 -289.861752)
		(end 140.541756 -281.975814)
		(width 0.18288)
		(layer "In11.Cu")
		(net "M_H_CPU1_SA_DQ<13>")
	)
	(segment
		(start 123.979686 -273.44116)
		(end 123.967748 -273.453098)
		(width 0.088646)
		(layer "In11.Cu")
		(net "M_H_CPU1_SA_DQ<13>")
	)
	(segment
		(start 128.853946 -276.384258)
		(end 128.841754 -276.377146)
		(width 0.088646)
		(layer "In11.Cu")
		(net "M_H_CPU1_SA_DQ<13>")
	)
	(segment
		(start 160.350454 -302.618648)
		(end 160.017714 -302.285146)
		(width 0.18288)
		(layer "In11.Cu")
		(net "M_H_CPU1_SA_DQ<13>")
	)
	(segment
		(start 126.983236 -273.13382)
		(end 126.9746 -273.12874)
		(width 0.088646)
		(layer "In11.Cu")
		(net "M_H_CPU1_SA_DQ<13>")
	)
	(segment
		(start 176.488598 -305.54549)
		(end 174.584106 -305.54549)
		(width 0.18288)
		(layer "In11.Cu")
		(net "M_H_CPU1_SA_DQ<13>")
	)
	(segment
		(start 192.359534 -305.691794)
		(end 191.69253 -305.691794)
		(width 0.18288)
		(layer "In11.Cu")
		(net "M_H_CPU1_SA_DQ<13>")
	)
	(segment
		(start 128.101598 -275.102828)
		(end 128.101598 -275.08073)
		(width 0.088646)
		(layer "In11.Cu")
		(net "M_H_CPU1_SA_DQ<13>")
	)
	(segment
		(start 189.013846 -305.808126)
		(end 188.853826 -305.648106)
		(width 0.18288)
		(layer "In11.Cu")
		(net "M_H_CPU1_SA_DQ<13>")
	)
	(segment
		(start 129.802636 -276.389338)
		(end 129.793746 -276.384258)
		(width 0.088646)
		(layer "In11.Cu")
		(net "M_H_CPU1_SA_DQ<13>")
	)
	(segment
		(start 133.648196 -277.198074)
		(end 133.633464 -277.20671)
		(width 0.088646)
		(layer "In11.Cu")
		(net "M_H_CPU1_SA_DQ<13>")
	)
	(segment
		(start 186.141614 -304.542698)
		(end 185.948574 -304.735738)
		(width 0.18288)
		(layer "In11.Cu")
		(net "M_H_CPU1_SA_DQ<13>")
	)
	(segment
		(start 166.604442 -304.49774)
		(end 166.286942 -304.49774)
		(width 0.18288)
		(layer "In11.Cu")
		(net "M_H_CPU1_SA_DQ<13>")
	)
	(segment
		(start 180.893974 -305.465226)
		(end 180.141626 -305.465226)
		(width 0.18288)
		(layer "In11.Cu")
		(net "M_H_CPU1_SA_DQ<13>")
	)
	(segment
		(start 159.276796 -303.676812)
		(end 159.083756 -303.869852)
		(width 0.18288)
		(layer "In11.Cu")
		(net "M_H_CPU1_SA_DQ<13>")
	)
	(segment
		(start 139.692634 -280.788872)
		(end 139.461494 -280.557732)
		(width 0.088646)
		(layer "In11.Cu")
		(net "M_H_CPU1_SA_DQ<13>")
	)
	(segment
		(start 195.688204 -303.477676)
		(end 195.045076 -303.477676)
		(width 0.18288)
		(layer "In11.Cu")
		(net "M_H_CPU1_SA_DQ<13>")
	)
	(segment
		(start 160.017714 -302.285146)
		(end 159.469836 -302.285146)
		(width 0.18288)
		(layer "In11.Cu")
		(net "M_H_CPU1_SA_DQ<13>")
	)
	(segment
		(start 128.392682 -275.575522)
		(end 128.383792 -275.570442)
		(width 0.088646)
		(layer "In11.Cu")
		(net "M_H_CPU1_SA_DQ<13>")
	)
	(segment
		(start 181.087014 -305.658266)
		(end 180.893974 -305.465226)
		(width 0.18288)
		(layer "In11.Cu")
		(net "M_H_CPU1_SA_DQ<13>")
	)
	(segment
		(start 202.191366 -299.364654)
		(end 202.191366 -299.167296)
		(width 0.18288)
		(layer "In11.Cu")
		(net "M_H_CPU1_SA_DQ<13>")
	)
	(segment
		(start 138.439144 -278.689308)
		(end 138.439144 -278.336502)
		(width 0.088646)
		(layer "In11.Cu")
		(net "M_H_CPU1_SA_DQ<13>")
	)
	(segment
		(start 180.141626 -305.465226)
		(end 179.885086 -305.721766)
		(width 0.18288)
		(layer "In11.Cu")
		(net "M_H_CPU1_SA_DQ<13>")
	)
	(segment
		(start 177.20437 -305.691794)
		(end 176.634902 -305.691794)
		(width 0.18288)
		(layer "In11.Cu")
		(net "M_H_CPU1_SA_DQ<13>")
	)
	(segment
		(start 177.67808 -306.165504)
		(end 177.20437 -305.691794)
		(width 0.18288)
		(layer "In11.Cu")
		(net "M_H_CPU1_SA_DQ<13>")
	)
	(segment
		(start 159.276796 -302.478186)
		(end 159.276796 -303.676812)
		(width 0.18288)
		(layer "In11.Cu")
		(net "M_H_CPU1_SA_DQ<13>")
	)
	(segment
		(start 157.518862 -302.290226)
		(end 156.5148 -301.286164)
		(width 0.18288)
		(layer "In11.Cu")
		(net "M_H_CPU1_SA_DQ<13>")
	)
	(segment
		(start 184.188354 -304.542698)
		(end 183.265826 -305.465226)
		(width 0.18288)
		(layer "In11.Cu")
		(net "M_H_CPU1_SA_DQ<13>")
	)
	(segment
		(start 185.051954 -304.542698)
		(end 184.188354 -304.542698)
		(width 0.18288)
		(layer "In11.Cu")
		(net "M_H_CPU1_SA_DQ<13>")
	)
	(segment
		(start 165.900862 -303.722024)
		(end 165.019228 -303.722024)
		(width 0.18288)
		(layer "In11.Cu")
		(net "M_H_CPU1_SA_DQ<13>")
	)
	(segment
		(start 139.461494 -280.557732)
		(end 139.461494 -280.170382)
		(width 0.088646)
		(layer "In11.Cu")
		(net "M_H_CPU1_SA_DQ<13>")
	)
	(segment
		(start 188.853826 -305.648106)
		(end 188.853826 -305.025806)
		(width 0.18288)
		(layer "In11.Cu")
		(net "M_H_CPU1_SA_DQ<13>")
	)
	(segment
		(start 156.5148 -301.286164)
		(end 156.5148 -299.695108)
		(width 0.18288)
		(layer "In11.Cu")
		(net "M_H_CPU1_SA_DQ<13>")
	)
	(segment
		(start 160.180782 -303.991772)
		(end 159.98317 -303.79416)
		(width 0.18288)
		(layer "In11.Cu")
		(net "M_H_CPU1_SA_DQ<13>")
	)
	(segment
		(start 194.479926 -304.042826)
		(end 194.008502 -304.042826)
		(width 0.18288)
		(layer "In11.Cu")
		(net "M_H_CPU1_SA_DQ<13>")
	)
	(segment
		(start 139.461494 -280.170382)
		(end 138.507978 -279.216866)
		(width 0.088646)
		(layer "In11.Cu")
		(net "M_H_CPU1_SA_DQ<13>")
	)
	(segment
		(start 169.417238 -304.672238)
		(end 169.09669 -304.672238)
		(width 0.18288)
		(layer "In11.Cu")
		(net "M_H_CPU1_SA_DQ<13>")
	)
	(segment
		(start 178.73345 -305.721766)
		(end 178.289712 -306.165504)
		(width 0.18288)
		(layer "In11.Cu")
		(net "M_H_CPU1_SA_DQ<13>")
	)
	(segment
		(start 166.093902 -304.3047)
		(end 166.093902 -303.915064)
		(width 0.18288)
		(layer "In11.Cu")
		(net "M_H_CPU1_SA_DQ<13>")
	)
	(segment
		(start 181.983634 -305.465226)
		(end 181.790594 -305.658266)
		(width 0.18288)
		(layer "In11.Cu")
		(net "M_H_CPU1_SA_DQ<13>")
	)
	(segment
		(start 127.914146 -274.756372)
		(end 127.911352 -274.754848)
		(width 0.088646)
		(layer "In11.Cu")
		(net "M_H_CPU1_SA_DQ<13>")
	)
	(segment
		(start 164.531294 -304.209958)
		(end 163.900866 -304.209958)
		(width 0.18288)
		(layer "In11.Cu")
		(net "M_H_CPU1_SA_DQ<13>")
	)
	(segment
		(start 176.634902 -305.691794)
		(end 176.488598 -305.54549)
		(width 0.18288)
		(layer "In11.Cu")
		(net "M_H_CPU1_SA_DQ<13>")
	)
	(segment
		(start 158.573216 -303.676812)
		(end 158.573216 -302.483266)
		(width 0.18288)
		(layer "In11.Cu")
		(net "M_H_CPU1_SA_DQ<13>")
	)
	(segment
		(start 187.16117 -304.542698)
		(end 186.141614 -304.542698)
		(width 0.18288)
		(layer "In11.Cu")
		(net "M_H_CPU1_SA_DQ<13>")
	)
	(segment
		(start 162.104324 -303.991772)
		(end 160.180782 -303.991772)
		(width 0.18288)
		(layer "In11.Cu")
		(net "M_H_CPU1_SA_DQ<13>")
	)
	(segment
		(start 195.045076 -303.477676)
		(end 194.479926 -304.042826)
		(width 0.18288)
		(layer "In11.Cu")
		(net "M_H_CPU1_SA_DQ<13>")
	)
	(segment
		(start 187.46089 -304.842418)
		(end 187.16117 -304.542698)
		(width 0.18288)
		(layer "In11.Cu")
		(net "M_H_CPU1_SA_DQ<13>")
	)
	(segment
		(start 202.541378 -299.714666)
		(end 202.191366 -299.364654)
		(width 0.18288)
		(layer "In11.Cu")
		(net "M_H_CPU1_SA_DQ<13>")
	)
	(segment
		(start 135.536178 -277.193248)
		(end 135.527796 -277.198074)
		(width 0.088646)
		(layer "In11.Cu")
		(net "M_H_CPU1_SA_DQ<13>")
	)
	(arc
		(start 126.59995 -273.12874)
		(mid 126.325751 -273.204575)
		(end 126.049278 -273.137376)
		(width 0.088646)
		(layer "In11.Cu")
		(net "M_H_CPU1_SA_DQ<13>")
	)
	(arc
		(start 127.161798 -273.453098)
		(mid 127.114119 -273.270198)
		(end 126.983236 -273.13382)
		(width 0.088646)
		(layer "In11.Cu")
		(net "M_H_CPU1_SA_DQ<13>")
	)
	(arc
		(start 131.758182 -277.20417)
		(mid 131.480004 -277.273893)
		(end 131.203446 -277.198074)
		(width 0.088646)
		(layer "In11.Cu")
		(net "M_H_CPU1_SA_DQ<13>")
	)
	(arc
		(start 126.034546 -273.12874)
		(mid 125.847348 -273.078597)
		(end 125.66015 -273.12874)
		(width 0.088646)
		(layer "In11.Cu")
		(net "M_H_CPU1_SA_DQ<13>")
	)
	(arc
		(start 137.029444 -277.522432)
		(mid 136.981765 -277.339532)
		(end 136.850882 -277.203154)
		(width 0.088646)
		(layer "In11.Cu")
		(net "M_H_CPU1_SA_DQ<13>")
	)
	(arc
		(start 132.142992 -277.198074)
		(mid 131.955794 -277.147931)
		(end 131.768596 -277.198074)
		(width 0.088646)
		(layer "In11.Cu")
		(net "M_H_CPU1_SA_DQ<13>")
	)
	(arc
		(start 132.708396 -277.198074)
		(mid 132.425694 -277.27385)
		(end 132.142992 -277.198074)
		(width 0.088646)
		(layer "In11.Cu")
		(net "M_H_CPU1_SA_DQ<13>")
	)
	(arc
		(start 129.41935 -276.384258)
		(mid 129.136648 -276.460034)
		(end 128.853946 -276.384258)
		(width 0.088646)
		(layer "In11.Cu")
		(net "M_H_CPU1_SA_DQ<13>")
	)
	(arc
		(start 125.659642 -273.128994)
		(mid 125.522597 -273.265954)
		(end 125.472444 -273.453098)
		(width 0.088646)
		(layer "In11.Cu")
		(net "M_H_CPU1_SA_DQ<13>")
	)
	(arc
		(start 131.203446 -277.198074)
		(mid 131.016248 -277.147931)
		(end 130.82905 -277.198074)
		(width 0.088646)
		(layer "In11.Cu")
		(net "M_H_CPU1_SA_DQ<13>")
	)
	(arc
		(start 134.573264 -277.20671)
		(mid 134.296789 -277.27403)
		(end 134.022592 -277.198074)
		(width 0.088646)
		(layer "In11.Cu")
		(net "M_H_CPU1_SA_DQ<13>")
	)
	(arc
		(start 133.633464 -277.20671)
		(mid 133.356989 -277.27403)
		(end 133.082792 -277.198074)
		(width 0.088646)
		(layer "In11.Cu")
		(net "M_H_CPU1_SA_DQ<13>")
	)
	(arc
		(start 126.9746 -273.12874)
		(mid 126.787292 -273.078597)
		(end 126.59995 -273.12874)
		(width 0.088646)
		(layer "In11.Cu")
		(net "M_H_CPU1_SA_DQ<13>")
	)
	(arc
		(start 130.82905 -277.198074)
		(mid 130.546348 -277.27385)
		(end 130.263646 -277.198074)
		(width 0.088646)
		(layer "In11.Cu")
		(net "M_H_CPU1_SA_DQ<13>")
	)
	(arc
		(start 136.841992 -277.198074)
		(mid 136.654794 -277.147931)
		(end 136.467596 -277.198074)
		(width 0.088646)
		(layer "In11.Cu")
		(net "M_H_CPU1_SA_DQ<13>")
	)
	(arc
		(start 124.507752 -273.590004)
		(mid 124.456821 -273.484152)
		(end 124.347478 -273.44116)
		(width 0.088646)
		(layer "In11.Cu")
		(net "M_H_CPU1_SA_DQ<13>")
	)
	(arc
		(start 125.472444 -273.453098)
		(mid 125.396774 -273.735662)
		(end 125.189996 -273.942556)
		(width 0.088646)
		(layer "In11.Cu")
		(net "M_H_CPU1_SA_DQ<13>")
	)
	(arc
		(start 138.251692 -278.012144)
		(mid 138.064494 -277.962001)
		(end 137.877296 -278.012144)
		(width 0.088646)
		(layer "In11.Cu")
		(net "M_H_CPU1_SA_DQ<13>")
	)
	(arc
		(start 128.571244 -275.8948)
		(mid 128.523565 -275.7119)
		(end 128.392682 -275.575522)
		(width 0.088646)
		(layer "In11.Cu")
		(net "M_H_CPU1_SA_DQ<13>")
	)
	(arc
		(start 135.901938 -277.198074)
		(mid 135.719687 -277.147963)
		(end 135.536178 -277.193248)
		(width 0.088646)
		(layer "In11.Cu")
		(net "M_H_CPU1_SA_DQ<13>")
	)
	(arc
		(start 128.383792 -275.570442)
		(mid 128.18251 -275.372955)
		(end 128.101598 -275.102828)
		(width 0.088646)
		(layer "In11.Cu")
		(net "M_H_CPU1_SA_DQ<13>")
	)
	(arc
		(start 134.022592 -277.198074)
		(mid 133.835394 -277.147931)
		(end 133.648196 -277.198074)
		(width 0.088646)
		(layer "In11.Cu")
		(net "M_H_CPU1_SA_DQ<13>")
	)
	(arc
		(start 136.457182 -277.20417)
		(mid 136.17875 -277.274016)
		(end 135.901938 -277.198074)
		(width 0.088646)
		(layer "In11.Cu")
		(net "M_H_CPU1_SA_DQ<13>")
	)
	(arc
		(start 127.90805 -274.752816)
		(mid 127.705463 -274.546465)
		(end 127.631444 -274.266914)
		(width 0.088646)
		(layer "In11.Cu")
		(net "M_H_CPU1_SA_DQ<13>")
	)
	(arc
		(start 127.631444 -274.266914)
		(mid 127.583765 -274.084014)
		(end 127.452882 -273.947636)
		(width 0.088646)
		(layer "In11.Cu")
		(net "M_H_CPU1_SA_DQ<13>")
	)
	(arc
		(start 133.082792 -277.198074)
		(mid 132.895594 -277.147931)
		(end 132.708396 -277.198074)
		(width 0.088646)
		(layer "In11.Cu")
		(net "M_H_CPU1_SA_DQ<13>")
	)
	(arc
		(start 129.981198 -276.708616)
		(mid 129.933519 -276.525716)
		(end 129.802636 -276.389338)
		(width 0.088646)
		(layer "In11.Cu")
		(net "M_H_CPU1_SA_DQ<13>")
	)
	(arc
		(start 137.311892 -278.012144)
		(mid 137.109606 -277.813163)
		(end 137.029444 -277.540974)
		(width 0.088646)
		(layer "In11.Cu")
		(net "M_H_CPU1_SA_DQ<13>")
	)
	(arc
		(start 128.101598 -275.08073)
		(mid 128.053919 -274.89783)
		(end 127.923036 -274.761452)
		(width 0.088646)
		(layer "In11.Cu")
		(net "M_H_CPU1_SA_DQ<13>")
	)
	(arc
		(start 137.877296 -278.012144)
		(mid 137.594594 -278.087886)
		(end 137.311892 -278.012144)
		(width 0.088646)
		(layer "In11.Cu")
		(net "M_H_CPU1_SA_DQ<13>")
	)
	(arc
		(start 125.182376 -273.946874)
		(mid 124.746405 -273.954962)
		(end 124.507752 -273.590004)
		(width 0.088646)
		(layer "In11.Cu")
		(net "M_H_CPU1_SA_DQ<13>")
	)
	(arc
		(start 128.841754 -276.377146)
		(mid 128.643526 -276.171298)
		(end 128.571244 -275.8948)
		(width 0.088646)
		(layer "In11.Cu")
		(net "M_H_CPU1_SA_DQ<13>")
	)
	(arc
		(start 134.962392 -277.198074)
		(mid 134.775194 -277.147931)
		(end 134.587996 -277.198074)
		(width 0.088646)
		(layer "In11.Cu")
		(net "M_H_CPU1_SA_DQ<13>")
	)
	(arc
		(start 129.793746 -276.384258)
		(mid 129.606548 -276.334115)
		(end 129.41935 -276.384258)
		(width 0.088646)
		(layer "In11.Cu")
		(net "M_H_CPU1_SA_DQ<13>")
	)
	(arc
		(start 135.513064 -277.20671)
		(mid 135.236589 -277.27403)
		(end 134.962392 -277.198074)
		(width 0.088646)
		(layer "In11.Cu")
		(net "M_H_CPU1_SA_DQ<13>")
	)
	(arc
		(start 127.443992 -273.942556)
		(mid 127.241169 -273.742325)
		(end 127.161798 -273.468592)
		(width 0.088646)
		(layer "In11.Cu")
		(net "M_H_CPU1_SA_DQ<13>")
	)
	(arc
		(start 138.439144 -278.336502)
		(mid 138.391465 -278.153602)
		(end 138.260582 -278.017224)
		(width 0.088646)
		(layer "In11.Cu")
		(net "M_H_CPU1_SA_DQ<13>")
	)
	(arc
		(start 130.263646 -277.198074)
		(mid 130.059311 -276.995469)
		(end 129.981198 -276.718522)
		(width 0.088646)
		(layer "In11.Cu")
		(net "M_H_CPU1_SA_DQ<13>")
	)
	(segment
		(start 123.497848 -274.26666)
		(end 123.497594 -274.266914)
		(width 0.20066)
		(layer "F.Cu")
		(net "M_H_CPU1_SA_DQ<12>")
	)
	(segment
		(start 209.180176 -300.591728)
		(end 207.018382 -300.591728)
		(width 0.1016)
		(layer "F.Cu")
		(net "M_H_CPU1_SA_DQ<12>")
	)
	(segment
		(start 207.018382 -300.591728)
		(end 206.971392 -300.591728)
		(width 0.101854)
		(layer "F.Cu")
		(net "M_H_CPU1_SA_DQ<12>")
	)
	(segment
		(start 206.626714 -300.591728)
		(end 206.508604 -300.709838)
		(width 0.20066)
		(layer "F.Cu")
		(net "M_H_CPU1_SA_DQ<12>")
	)
	(segment
		(start 205.596744 -301.01667)
		(end 204.076046 -301.01667)
		(width 0.20066)
		(layer "F.Cu")
		(net "M_H_CPU1_SA_DQ<12>")
	)
	(segment
		(start 211.619846 -301.01667)
		(end 211.619592 -301.016924)
		(width 0.20066)
		(layer "F.Cu")
		(net "M_H_CPU1_SA_DQ<12>")
	)
	(segment
		(start 209.186526 -300.585378)
		(end 209.180176 -300.591728)
		(width 0.1016)
		(layer "F.Cu")
		(net "M_H_CPU1_SA_DQ<12>")
	)
	(segment
		(start 211.619592 -301.016924)
		(end 210.028028 -301.016924)
		(width 0.20066)
		(layer "F.Cu")
		(net "M_H_CPU1_SA_DQ<12>")
	)
	(segment
		(start 204.076046 -301.01667)
		(end 202.971146 -301.01667)
		(width 0.20066)
		(layer "F.Cu")
		(net "M_H_CPU1_SA_DQ<12>")
	)
	(segment
		(start 206.320644 -301.265336)
		(end 205.84541 -301.265336)
		(width 0.20066)
		(layer "F.Cu")
		(net "M_H_CPU1_SA_DQ<12>")
	)
	(segment
		(start 206.508604 -300.709838)
		(end 206.508604 -301.077376)
		(width 0.20066)
		(layer "F.Cu")
		(net "M_H_CPU1_SA_DQ<12>")
	)
	(segment
		(start 206.508604 -301.077376)
		(end 206.320644 -301.265336)
		(width 0.20066)
		(layer "F.Cu")
		(net "M_H_CPU1_SA_DQ<12>")
	)
	(segment
		(start 205.84541 -301.265336)
		(end 205.596744 -301.01667)
		(width 0.20066)
		(layer "F.Cu")
		(net "M_H_CPU1_SA_DQ<12>")
	)
	(segment
		(start 209.596482 -300.585378)
		(end 209.186526 -300.585378)
		(width 0.20066)
		(layer "F.Cu")
		(net "M_H_CPU1_SA_DQ<12>")
	)
	(segment
		(start 123.497848 -273.730974)
		(end 123.497848 -274.26666)
		(width 0.20066)
		(layer "F.Cu")
		(net "M_H_CPU1_SA_DQ<12>")
	)
	(segment
		(start 206.971392 -300.591728)
		(end 206.626714 -300.591728)
		(width 0.20066)
		(layer "F.Cu")
		(net "M_H_CPU1_SA_DQ<12>")
	)
	(segment
		(start 210.028028 -301.016924)
		(end 209.596482 -300.585378)
		(width 0.20066)
		(layer "F.Cu")
		(net "M_H_CPU1_SA_DQ<12>")
	)
	(segment
		(start 163.85921 -305.691794)
		(end 163.337494 -305.691794)
		(width 0.18288)
		(layer "In11.Cu")
		(net "M_H_CPU1_SA_DQ<12>")
	)
	(segment
		(start 147.290282 -290.180268)
		(end 140.738098 -283.628084)
		(width 0.18288)
		(layer "In11.Cu")
		(net "M_H_CPU1_SA_DQ<12>")
	)
	(segment
		(start 138.251692 -279.839674)
		(end 138.251692 -279.692354)
		(width 0.088646)
		(layer "In11.Cu")
		(net "M_H_CPU1_SA_DQ<12>")
	)
	(segment
		(start 163.144454 -306.640484)
		(end 162.951414 -306.833524)
		(width 0.18288)
		(layer "In11.Cu")
		(net "M_H_CPU1_SA_DQ<12>")
	)
	(segment
		(start 175.430688 -307.58384)
		(end 175.064674 -307.217826)
		(width 0.18288)
		(layer "In11.Cu")
		(net "M_H_CPU1_SA_DQ<12>")
	)
	(segment
		(start 126.13005 -273.942556)
		(end 126.12116 -273.947636)
		(width 0.088646)
		(layer "In11.Cu")
		(net "M_H_CPU1_SA_DQ<12>")
	)
	(segment
		(start 178.175412 -307.803296)
		(end 177.982372 -307.996336)
		(width 0.18288)
		(layer "In11.Cu")
		(net "M_H_CPU1_SA_DQ<12>")
	)
	(segment
		(start 181.434994 -307.98008)
		(end 181.241954 -307.78704)
		(width 0.18288)
		(layer "In11.Cu")
		(net "M_H_CPU1_SA_DQ<12>")
	)
	(segment
		(start 124.250196 -274.591272)
		(end 124.235464 -274.582636)
		(width 0.088646)
		(layer "In11.Cu")
		(net "M_H_CPU1_SA_DQ<12>")
	)
	(segment
		(start 191.25819 -307.785516)
		(end 191.06515 -307.978556)
		(width 0.18288)
		(layer "In11.Cu")
		(net "M_H_CPU1_SA_DQ<12>")
	)
	(segment
		(start 126.691644 -274.27682)
		(end 126.691644 -274.258278)
		(width 0.088646)
		(layer "In11.Cu")
		(net "M_H_CPU1_SA_DQ<12>")
	)
	(segment
		(start 182.138574 -307.208682)
		(end 181.945534 -307.401722)
		(width 0.18288)
		(layer "In11.Cu")
		(net "M_H_CPU1_SA_DQ<12>")
	)
	(segment
		(start 172.293026 -308.241954)
		(end 172.136308 -308.085236)
		(width 0.18288)
		(layer "In11.Cu")
		(net "M_H_CPU1_SA_DQ<12>")
	)
	(segment
		(start 202.372722 -301.01667)
		(end 201.920856 -300.564804)
		(width 0.18288)
		(layer "In11.Cu")
		(net "M_H_CPU1_SA_DQ<12>")
	)
	(segment
		(start 172.136308 -308.085236)
		(end 171.237402 -308.085236)
		(width 0.18288)
		(layer "In11.Cu")
		(net "M_H_CPU1_SA_DQ<12>")
	)
	(segment
		(start 127.452882 -275.575522)
		(end 127.443992 -275.570442)
		(width 0.088646)
		(layer "In11.Cu")
		(net "M_H_CPU1_SA_DQ<12>")
	)
	(segment
		(start 181.945534 -307.401722)
		(end 181.945534 -307.78704)
		(width 0.18288)
		(layer "In11.Cu")
		(net "M_H_CPU1_SA_DQ<12>")
	)
	(segment
		(start 163.337494 -305.691794)
		(end 163.144454 -305.884834)
		(width 0.18288)
		(layer "In11.Cu")
		(net "M_H_CPU1_SA_DQ<12>")
	)
	(segment
		(start 162.247834 -305.691794)
		(end 161.417254 -305.691794)
		(width 0.18288)
		(layer "In11.Cu")
		(net "M_H_CPU1_SA_DQ<12>")
	)
	(segment
		(start 123.34113 -274.537932)
		(end 123.497594 -274.266914)
		(width 0.088646)
		(layer "In11.Cu")
		(net "M_H_CPU1_SA_DQ<12>")
	)
	(segment
		(start 162.633914 -306.833524)
		(end 162.440874 -306.640484)
		(width 0.18288)
		(layer "In11.Cu")
		(net "M_H_CPU1_SA_DQ<12>")
	)
	(segment
		(start 191.45123 -307.237638)
		(end 191.25819 -307.430678)
		(width 0.18288)
		(layer "In11.Cu")
		(net "M_H_CPU1_SA_DQ<12>")
	)
	(segment
		(start 197.0278 -304.847752)
		(end 196.283326 -305.592226)
		(width 0.18288)
		(layer "In11.Cu")
		(net "M_H_CPU1_SA_DQ<12>")
	)
	(segment
		(start 140.738098 -283.628084)
		(end 140.738098 -283.525722)
		(width 0.18288)
		(layer "In11.Cu")
		(net "M_H_CPU1_SA_DQ<12>")
	)
	(segment
		(start 175.78832 -307.58384)
		(end 175.430688 -307.58384)
		(width 0.18288)
		(layer "In11.Cu")
		(net "M_H_CPU1_SA_DQ<12>")
	)
	(segment
		(start 160.520634 -306.474368)
		(end 160.520634 -305.884834)
		(width 0.18288)
		(layer "In11.Cu")
		(net "M_H_CPU1_SA_DQ<12>")
	)
	(segment
		(start 201.920856 -300.564804)
		(end 201.569828 -300.564804)
		(width 0.18288)
		(layer "In11.Cu")
		(net "M_H_CPU1_SA_DQ<12>")
	)
	(segment
		(start 128.949196 -277.198074)
		(end 128.934464 -277.20671)
		(width 0.088646)
		(layer "In11.Cu")
		(net "M_H_CPU1_SA_DQ<12>")
	)
	(segment
		(start 165.853618 -305.97856)
		(end 165.853618 -305.7144)
		(width 0.18288)
		(layer "In11.Cu")
		(net "M_H_CPU1_SA_DQ<12>")
	)
	(segment
		(start 168.686226 -306.32146)
		(end 167.886126 -305.52136)
		(width 0.18288)
		(layer "In11.Cu")
		(net "M_H_CPU1_SA_DQ<12>")
	)
	(segment
		(start 190.36157 -307.237638)
		(end 188.990224 -307.237638)
		(width 0.18288)
		(layer "In11.Cu")
		(net "M_H_CPU1_SA_DQ<12>")
	)
	(segment
		(start 194.733926 -305.592226)
		(end 194.378326 -305.947826)
		(width 0.18288)
		(layer "In11.Cu")
		(net "M_H_CPU1_SA_DQ<12>")
	)
	(segment
		(start 176.67605 -307.389022)
		(end 176.504854 -307.217826)
		(width 0.18288)
		(layer "In11.Cu")
		(net "M_H_CPU1_SA_DQ<12>")
	)
	(segment
		(start 181.752494 -307.98008)
		(end 181.434994 -307.98008)
		(width 0.18288)
		(layer "In11.Cu")
		(net "M_H_CPU1_SA_DQ<12>")
	)
	(segment
		(start 165.853618 -305.7144)
		(end 165.660578 -305.52136)
		(width 0.18288)
		(layer "In11.Cu")
		(net "M_H_CPU1_SA_DQ<12>")
	)
	(segment
		(start 166.557198 -305.7144)
		(end 166.557198 -305.97856)
		(width 0.18288)
		(layer "In11.Cu")
		(net "M_H_CPU1_SA_DQ<12>")
	)
	(segment
		(start 123.362212 -274.61591)
		(end 123.34113 -274.537932)
		(width 0.088646)
		(layer "In11.Cu")
		(net "M_H_CPU1_SA_DQ<12>")
	)
	(segment
		(start 173.587664 -308.241954)
		(end 172.293026 -308.241954)
		(width 0.18288)
		(layer "In11.Cu")
		(net "M_H_CPU1_SA_DQ<12>")
	)
	(segment
		(start 188.290962 -306.538376)
		(end 186.042046 -306.538376)
		(width 0.18288)
		(layer "In11.Cu")
		(net "M_H_CPU1_SA_DQ<12>")
	)
	(segment
		(start 161.417254 -305.691794)
		(end 161.224214 -305.884834)
		(width 0.18288)
		(layer "In11.Cu")
		(net "M_H_CPU1_SA_DQ<12>")
	)
	(segment
		(start 127.161544 -275.094954)
		(end 127.161544 -275.08073)
		(width 0.088646)
		(layer "In11.Cu")
		(net "M_H_CPU1_SA_DQ<12>")
	)
	(segment
		(start 129.332482 -277.203154)
		(end 129.323592 -277.198074)
		(width 0.088646)
		(layer "In11.Cu")
		(net "M_H_CPU1_SA_DQ<12>")
	)
	(segment
		(start 165.660578 -305.52136)
		(end 165.232588 -305.52136)
		(width 0.18288)
		(layer "In11.Cu")
		(net "M_H_CPU1_SA_DQ<12>")
	)
	(segment
		(start 159.96539 -305.691794)
		(end 159.723836 -305.45024)
		(width 0.18288)
		(layer "In11.Cu")
		(net "M_H_CPU1_SA_DQ<12>")
	)
	(segment
		(start 129.511044 -277.530052)
		(end 129.511044 -277.522432)
		(width 0.088646)
		(layer "In11.Cu")
		(net "M_H_CPU1_SA_DQ<12>")
	)
	(segment
		(start 181.945534 -307.78704)
		(end 181.752494 -307.98008)
		(width 0.18288)
		(layer "In11.Cu")
		(net "M_H_CPU1_SA_DQ<12>")
	)
	(segment
		(start 181.048914 -307.208682)
		(end 179.97297 -307.208682)
		(width 0.18288)
		(layer "In11.Cu")
		(net "M_H_CPU1_SA_DQ<12>")
	)
	(segment
		(start 186.042046 -306.538376)
		(end 185.849006 -306.731416)
		(width 0.18288)
		(layer "In11.Cu")
		(net "M_H_CPU1_SA_DQ<12>")
	)
	(segment
		(start 190.55461 -307.430678)
		(end 190.36157 -307.237638)
		(width 0.18288)
		(layer "In11.Cu")
		(net "M_H_CPU1_SA_DQ<12>")
	)
	(segment
		(start 190.74765 -307.978556)
		(end 190.55461 -307.785516)
		(width 0.18288)
		(layer "In11.Cu")
		(net "M_H_CPU1_SA_DQ<12>")
	)
	(segment
		(start 166.750238 -305.52136)
		(end 166.557198 -305.7144)
		(width 0.18288)
		(layer "In11.Cu")
		(net "M_H_CPU1_SA_DQ<12>")
	)
	(segment
		(start 178.368452 -307.396642)
		(end 178.175412 -307.589682)
		(width 0.18288)
		(layer "In11.Cu")
		(net "M_H_CPU1_SA_DQ<12>")
	)
	(segment
		(start 125.189996 -274.591272)
		(end 125.175264 -274.582636)
		(width 0.088646)
		(layer "In11.Cu")
		(net "M_H_CPU1_SA_DQ<12>")
	)
	(segment
		(start 161.031174 -306.667408)
		(end 160.713674 -306.667408)
		(width 0.18288)
		(layer "In11.Cu")
		(net "M_H_CPU1_SA_DQ<12>")
	)
	(segment
		(start 162.951414 -306.833524)
		(end 162.633914 -306.833524)
		(width 0.18288)
		(layer "In11.Cu")
		(net "M_H_CPU1_SA_DQ<12>")
	)
	(segment
		(start 196.283326 -305.592226)
		(end 194.733926 -305.592226)
		(width 0.18288)
		(layer "In11.Cu")
		(net "M_H_CPU1_SA_DQ<12>")
	)
	(segment
		(start 162.440874 -305.884834)
		(end 162.247834 -305.691794)
		(width 0.18288)
		(layer "In11.Cu")
		(net "M_H_CPU1_SA_DQ<12>")
	)
	(segment
		(start 130.358896 -278.012144)
		(end 130.348482 -278.01824)
		(width 0.088646)
		(layer "In11.Cu")
		(net "M_H_CPU1_SA_DQ<12>")
	)
	(segment
		(start 166.364158 -306.1716)
		(end 166.046658 -306.1716)
		(width 0.18288)
		(layer "In11.Cu")
		(net "M_H_CPU1_SA_DQ<12>")
	)
	(segment
		(start 158.72587 -305.45024)
		(end 158.115254 -304.839624)
		(width 0.18288)
		(layer "In11.Cu")
		(net "M_H_CPU1_SA_DQ<12>")
	)
	(segment
		(start 176.154334 -307.217826)
		(end 175.78832 -307.58384)
		(width 0.18288)
		(layer "In11.Cu")
		(net "M_H_CPU1_SA_DQ<12>")
	)
	(segment
		(start 185.849006 -306.731416)
		(end 185.849006 -306.981606)
		(width 0.18288)
		(layer "In11.Cu")
		(net "M_H_CPU1_SA_DQ<12>")
	)
	(segment
		(start 139.505436 -281.803348)
		(end 138.909298 -281.20721)
		(width 0.088646)
		(layer "In11.Cu")
		(net "M_H_CPU1_SA_DQ<12>")
	)
	(segment
		(start 171.237402 -308.085236)
		(end 169.473626 -306.32146)
		(width 0.18288)
		(layer "In11.Cu")
		(net "M_H_CPU1_SA_DQ<12>")
	)
	(segment
		(start 177.664872 -307.996336)
		(end 177.471832 -307.803296)
		(width 0.18288)
		(layer "In11.Cu")
		(net "M_H_CPU1_SA_DQ<12>")
	)
	(segment
		(start 165.232588 -305.52136)
		(end 164.796978 -305.95697)
		(width 0.18288)
		(layer "In11.Cu")
		(net "M_H_CPU1_SA_DQ<12>")
	)
	(segment
		(start 131.29895 -278.012144)
		(end 131.288536 -278.01824)
		(width 0.088646)
		(layer "In11.Cu")
		(net "M_H_CPU1_SA_DQ<12>")
	)
	(segment
		(start 190.55461 -307.785516)
		(end 190.55461 -307.430678)
		(width 0.18288)
		(layer "In11.Cu")
		(net "M_H_CPU1_SA_DQ<12>")
	)
	(segment
		(start 131.688078 -278.02078)
		(end 131.673346 -278.012144)
		(width 0.088646)
		(layer "In11.Cu")
		(net "M_H_CPU1_SA_DQ<12>")
	)
	(segment
		(start 133.56336 -278.01824)
		(end 133.552946 -278.012144)
		(width 0.088646)
		(layer "In11.Cu")
		(net "M_H_CPU1_SA_DQ<12>")
	)
	(segment
		(start 125.942598 -274.352258)
		(end 125.774958 -274.519898)
		(width 0.088646)
		(layer "In11.Cu")
		(net "M_H_CPU1_SA_DQ<12>")
	)
	(segment
		(start 161.224214 -306.474368)
		(end 161.031174 -306.667408)
		(width 0.18288)
		(layer "In11.Cu")
		(net "M_H_CPU1_SA_DQ<12>")
	)
	(segment
		(start 160.520634 -305.884834)
		(end 160.327594 -305.691794)
		(width 0.18288)
		(layer "In11.Cu")
		(net "M_H_CPU1_SA_DQ<12>")
	)
	(segment
		(start 158.115254 -304.839624)
		(end 157.50159 -304.839624)
		(width 0.18288)
		(layer "In11.Cu")
		(net "M_H_CPU1_SA_DQ<12>")
	)
	(segment
		(start 155.386024 -302.724058)
		(end 155.386024 -300.003718)
		(width 0.18288)
		(layer "In11.Cu")
		(net "M_H_CPU1_SA_DQ<12>")
	)
	(segment
		(start 191.643 -307.237638)
		(end 191.45123 -307.237638)
		(width 0.18288)
		(layer "In11.Cu")
		(net "M_H_CPU1_SA_DQ<12>")
	)
	(segment
		(start 175.064674 -307.217826)
		(end 174.611792 -307.217826)
		(width 0.18288)
		(layer "In11.Cu")
		(net "M_H_CPU1_SA_DQ<12>")
	)
	(segment
		(start 167.886126 -305.52136)
		(end 166.750238 -305.52136)
		(width 0.18288)
		(layer "In11.Cu")
		(net "M_H_CPU1_SA_DQ<12>")
	)
	(segment
		(start 183.96077 -306.472082)
		(end 183.22417 -307.208682)
		(width 0.18288)
		(layer "In11.Cu")
		(net "M_H_CPU1_SA_DQ<12>")
	)
	(segment
		(start 201.035666 -301.227998)
		(end 198.213726 -304.049938)
		(width 0.18288)
		(layer "In11.Cu")
		(net "M_H_CPU1_SA_DQ<12>")
	)
	(segment
		(start 194.378326 -305.947826)
		(end 194.044316 -305.947826)
		(width 0.18288)
		(layer "In11.Cu")
		(net "M_H_CPU1_SA_DQ<12>")
	)
	(segment
		(start 185.145426 -306.665122)
		(end 184.952386 -306.472082)
		(width 0.18288)
		(layer "In11.Cu")
		(net "M_H_CPU1_SA_DQ<12>")
	)
	(segment
		(start 181.241954 -307.78704)
		(end 181.241954 -307.401722)
		(width 0.18288)
		(layer "In11.Cu")
		(net "M_H_CPU1_SA_DQ<12>")
	)
	(segment
		(start 185.145426 -306.981606)
		(end 185.145426 -306.665122)
		(width 0.18288)
		(layer "In11.Cu")
		(net "M_H_CPU1_SA_DQ<12>")
	)
	(segment
		(start 201.035666 -301.098966)
		(end 201.035666 -301.227998)
		(width 0.18288)
		(layer "In11.Cu")
		(net "M_H_CPU1_SA_DQ<12>")
	)
	(segment
		(start 178.175412 -307.589682)
		(end 178.175412 -307.803296)
		(width 0.18288)
		(layer "In11.Cu")
		(net "M_H_CPU1_SA_DQ<12>")
	)
	(segment
		(start 160.327594 -305.691794)
		(end 159.96539 -305.691794)
		(width 0.18288)
		(layer "In11.Cu")
		(net "M_H_CPU1_SA_DQ<12>")
	)
	(segment
		(start 161.224214 -305.884834)
		(end 161.224214 -306.474368)
		(width 0.18288)
		(layer "In11.Cu")
		(net "M_H_CPU1_SA_DQ<12>")
	)
	(segment
		(start 191.06515 -307.978556)
		(end 190.74765 -307.978556)
		(width 0.18288)
		(layer "In11.Cu")
		(net "M_H_CPU1_SA_DQ<12>")
	)
	(segment
		(start 166.046658 -306.1716)
		(end 165.853618 -305.97856)
		(width 0.18288)
		(layer "In11.Cu")
		(net "M_H_CPU1_SA_DQ<12>")
	)
	(segment
		(start 128.101598 -276.72411)
		(end 128.101598 -276.708616)
		(width 0.088646)
		(layer "In11.Cu")
		(net "M_H_CPU1_SA_DQ<12>")
	)
	(segment
		(start 126.982982 -274.761452)
		(end 126.974092 -274.756372)
		(width 0.088646)
		(layer "In11.Cu")
		(net "M_H_CPU1_SA_DQ<12>")
	)
	(segment
		(start 159.723836 -305.45024)
		(end 158.72587 -305.45024)
		(width 0.18288)
		(layer "In11.Cu")
		(net "M_H_CPU1_SA_DQ<12>")
	)
	(segment
		(start 179.78501 -307.396642)
		(end 178.368452 -307.396642)
		(width 0.18288)
		(layer "In11.Cu")
		(net "M_H_CPU1_SA_DQ<12>")
	)
	(segment
		(start 191.25819 -307.430678)
		(end 191.25819 -307.785516)
		(width 0.18288)
		(layer "In11.Cu")
		(net "M_H_CPU1_SA_DQ<12>")
	)
	(segment
		(start 164.124386 -305.95697)
		(end 163.85921 -305.691794)
		(width 0.18288)
		(layer "In11.Cu")
		(net "M_H_CPU1_SA_DQ<12>")
	)
	(segment
		(start 198.213726 -304.049938)
		(end 198.213726 -304.601626)
		(width 0.18288)
		(layer "In11.Cu")
		(net "M_H_CPU1_SA_DQ<12>")
	)
	(segment
		(start 197.9676 -304.847752)
		(end 197.0278 -304.847752)
		(width 0.18288)
		(layer "In11.Cu")
		(net "M_H_CPU1_SA_DQ<12>")
	)
	(segment
		(start 127.923036 -276.389338)
		(end 127.914146 -276.384258)
		(width 0.088646)
		(layer "In11.Cu")
		(net "M_H_CPU1_SA_DQ<12>")
	)
	(segment
		(start 139.555728 -281.85364)
		(end 139.505436 -281.803348)
		(width 0.18288)
		(layer "In11.Cu")
		(net "M_H_CPU1_SA_DQ<12>")
	)
	(segment
		(start 194.044316 -305.947826)
		(end 192.600326 -307.391816)
		(width 0.18288)
		(layer "In11.Cu")
		(net "M_H_CPU1_SA_DQ<12>")
	)
	(segment
		(start 177.982372 -307.996336)
		(end 177.664872 -307.996336)
		(width 0.18288)
		(layer "In11.Cu")
		(net "M_H_CPU1_SA_DQ<12>")
	)
	(segment
		(start 191.797178 -307.391816)
		(end 191.643 -307.237638)
		(width 0.18288)
		(layer "In11.Cu")
		(net "M_H_CPU1_SA_DQ<12>")
	)
	(segment
		(start 140.738098 -283.525722)
		(end 139.902184 -282.689808)
		(width 0.18288)
		(layer "In11.Cu")
		(net "M_H_CPU1_SA_DQ<12>")
	)
	(segment
		(start 202.971146 -301.01667)
		(end 202.372722 -301.01667)
		(width 0.18288)
		(layer "In11.Cu")
		(net "M_H_CPU1_SA_DQ<12>")
	)
	(segment
		(start 160.713674 -306.667408)
		(end 160.520634 -306.474368)
		(width 0.18288)
		(layer "In11.Cu")
		(net "M_H_CPU1_SA_DQ<12>")
	)
	(segment
		(start 127.914146 -276.384258)
		(end 127.90805 -276.380702)
		(width 0.088646)
		(layer "In11.Cu")
		(net "M_H_CPU1_SA_DQ<12>")
	)
	(segment
		(start 138.876278 -280.510996)
		(end 138.284712 -279.91943)
		(width 0.088646)
		(layer "In11.Cu")
		(net "M_H_CPU1_SA_DQ<12>")
	)
	(segment
		(start 185.849006 -306.981606)
		(end 185.655966 -307.174646)
		(width 0.18288)
		(layer "In11.Cu")
		(net "M_H_CPU1_SA_DQ<12>")
	)
	(segment
		(start 132.627878 -278.02078)
		(end 132.613146 -278.012144)
		(width 0.088646)
		(layer "In11.Cu")
		(net "M_H_CPU1_SA_DQ<12>")
	)
	(segment
		(start 183.22417 -307.208682)
		(end 182.138574 -307.208682)
		(width 0.18288)
		(layer "In11.Cu")
		(net "M_H_CPU1_SA_DQ<12>")
	)
	(segment
		(start 155.386024 -300.003718)
		(end 147.290282 -291.907976)
		(width 0.18288)
		(layer "In11.Cu")
		(net "M_H_CPU1_SA_DQ<12>")
	)
	(segment
		(start 192.600326 -307.391816)
		(end 191.797178 -307.391816)
		(width 0.18288)
		(layer "In11.Cu")
		(net "M_H_CPU1_SA_DQ<12>")
	)
	(segment
		(start 137.969244 -279.160224)
		(end 137.969244 -279.150318)
		(width 0.088646)
		(layer "In11.Cu")
		(net "M_H_CPU1_SA_DQ<12>")
	)
	(segment
		(start 139.902184 -282.689808)
		(end 139.555728 -281.85364)
		(width 0.18288)
		(layer "In11.Cu")
		(net "M_H_CPU1_SA_DQ<12>")
	)
	(segment
		(start 177.471832 -307.803296)
		(end 177.471832 -307.589682)
		(width 0.18288)
		(layer "In11.Cu")
		(net "M_H_CPU1_SA_DQ<12>")
	)
	(segment
		(start 176.504854 -307.217826)
		(end 176.154334 -307.217826)
		(width 0.18288)
		(layer "In11.Cu")
		(net "M_H_CPU1_SA_DQ<12>")
	)
	(segment
		(start 164.796978 -305.95697)
		(end 164.124386 -305.95697)
		(width 0.18288)
		(layer "In11.Cu")
		(net "M_H_CPU1_SA_DQ<12>")
	)
	(segment
		(start 181.241954 -307.401722)
		(end 181.048914 -307.208682)
		(width 0.18288)
		(layer "In11.Cu")
		(net "M_H_CPU1_SA_DQ<12>")
	)
	(segment
		(start 147.290282 -291.907976)
		(end 147.290282 -290.180268)
		(width 0.18288)
		(layer "In11.Cu")
		(net "M_H_CPU1_SA_DQ<12>")
	)
	(segment
		(start 179.97297 -307.208682)
		(end 179.78501 -307.396642)
		(width 0.18288)
		(layer "In11.Cu")
		(net "M_H_CPU1_SA_DQ<12>")
	)
	(segment
		(start 185.655966 -307.174646)
		(end 185.338466 -307.174646)
		(width 0.18288)
		(layer "In11.Cu")
		(net "M_H_CPU1_SA_DQ<12>")
	)
	(segment
		(start 174.611792 -307.217826)
		(end 173.587664 -308.241954)
		(width 0.18288)
		(layer "In11.Cu")
		(net "M_H_CPU1_SA_DQ<12>")
	)
	(segment
		(start 135.447024 -278.02078)
		(end 135.432292 -278.012144)
		(width 0.088646)
		(layer "In11.Cu")
		(net "M_H_CPU1_SA_DQ<12>")
	)
	(segment
		(start 125.942598 -274.266914)
		(end 125.942598 -274.352258)
		(width 0.088646)
		(layer "In11.Cu")
		(net "M_H_CPU1_SA_DQ<12>")
	)
	(segment
		(start 166.557198 -305.97856)
		(end 166.364158 -306.1716)
		(width 0.18288)
		(layer "In11.Cu")
		(net "M_H_CPU1_SA_DQ<12>")
	)
	(segment
		(start 201.569828 -300.564804)
		(end 201.035666 -301.098966)
		(width 0.18288)
		(layer "In11.Cu")
		(net "M_H_CPU1_SA_DQ<12>")
	)
	(segment
		(start 136.380982 -278.017224)
		(end 136.372092 -278.012144)
		(width 0.088646)
		(layer "In11.Cu")
		(net "M_H_CPU1_SA_DQ<12>")
	)
	(segment
		(start 163.144454 -305.884834)
		(end 163.144454 -306.640484)
		(width 0.18288)
		(layer "In11.Cu")
		(net "M_H_CPU1_SA_DQ<12>")
	)
	(segment
		(start 188.990224 -307.237638)
		(end 188.290962 -306.538376)
		(width 0.18288)
		(layer "In11.Cu")
		(net "M_H_CPU1_SA_DQ<12>")
	)
	(segment
		(start 137.790682 -278.83104)
		(end 137.781792 -278.82596)
		(width 0.088646)
		(layer "In11.Cu")
		(net "M_H_CPU1_SA_DQ<12>")
	)
	(segment
		(start 177.471832 -307.589682)
		(end 177.271172 -307.389022)
		(width 0.18288)
		(layer "In11.Cu")
		(net "M_H_CPU1_SA_DQ<12>")
	)
	(segment
		(start 198.213726 -304.601626)
		(end 197.9676 -304.847752)
		(width 0.18288)
		(layer "In11.Cu")
		(net "M_H_CPU1_SA_DQ<12>")
	)
	(segment
		(start 138.909298 -281.20721)
		(end 138.909298 -280.590752)
		(width 0.088646)
		(layer "In11.Cu")
		(net "M_H_CPU1_SA_DQ<12>")
	)
	(segment
		(start 169.473626 -306.32146)
		(end 168.686226 -306.32146)
		(width 0.18288)
		(layer "In11.Cu")
		(net "M_H_CPU1_SA_DQ<12>")
	)
	(segment
		(start 177.271172 -307.389022)
		(end 176.67605 -307.389022)
		(width 0.18288)
		(layer "In11.Cu")
		(net "M_H_CPU1_SA_DQ<12>")
	)
	(segment
		(start 157.50159 -304.839624)
		(end 155.386024 -302.724058)
		(width 0.18288)
		(layer "In11.Cu")
		(net "M_H_CPU1_SA_DQ<12>")
	)
	(segment
		(start 185.338466 -307.174646)
		(end 185.145426 -306.981606)
		(width 0.18288)
		(layer "In11.Cu")
		(net "M_H_CPU1_SA_DQ<12>")
	)
	(segment
		(start 184.952386 -306.472082)
		(end 183.96077 -306.472082)
		(width 0.18288)
		(layer "In11.Cu")
		(net "M_H_CPU1_SA_DQ<12>")
	)
	(segment
		(start 136.559544 -278.346408)
		(end 136.559544 -278.336502)
		(width 0.088646)
		(layer "In11.Cu")
		(net "M_H_CPU1_SA_DQ<12>")
	)
	(segment
		(start 162.440874 -306.640484)
		(end 162.440874 -305.884834)
		(width 0.18288)
		(layer "In11.Cu")
		(net "M_H_CPU1_SA_DQ<12>")
	)
	(arc
		(start 129.793746 -278.012144)
		(mid 129.588674 -277.808465)
		(end 129.511044 -277.530052)
		(width 0.088646)
		(layer "In11.Cu")
		(net "M_H_CPU1_SA_DQ<12>")
	)
	(arc
		(start 125.774958 -274.519898)
		(mid 125.666127 -274.545122)
		(end 125.564392 -274.591272)
		(width 0.088646)
		(layer "In11.Cu")
		(net "M_H_CPU1_SA_DQ<12>")
	)
	(arc
		(start 126.12116 -273.947636)
		(mid 125.990246 -274.083996)
		(end 125.942598 -274.266914)
		(width 0.088646)
		(layer "In11.Cu")
		(net "M_H_CPU1_SA_DQ<12>")
	)
	(arc
		(start 129.511044 -277.522432)
		(mid 129.463365 -277.339532)
		(end 129.332482 -277.203154)
		(width 0.088646)
		(layer "In11.Cu")
		(net "M_H_CPU1_SA_DQ<12>")
	)
	(arc
		(start 133.17855 -278.012144)
		(mid 132.904321 -278.088069)
		(end 132.627878 -278.02078)
		(width 0.088646)
		(layer "In11.Cu")
		(net "M_H_CPU1_SA_DQ<12>")
	)
	(arc
		(start 127.443992 -275.570442)
		(mid 127.240687 -275.369576)
		(end 127.161544 -275.094954)
		(width 0.088646)
		(layer "In11.Cu")
		(net "M_H_CPU1_SA_DQ<12>")
	)
	(arc
		(start 135.432292 -278.012144)
		(mid 135.245094 -277.962001)
		(end 135.057896 -278.012144)
		(width 0.088646)
		(layer "In11.Cu")
		(net "M_H_CPU1_SA_DQ<12>")
	)
	(arc
		(start 130.733292 -278.012144)
		(mid 130.546094 -277.962001)
		(end 130.358896 -278.012144)
		(width 0.088646)
		(layer "In11.Cu")
		(net "M_H_CPU1_SA_DQ<12>")
	)
	(arc
		(start 138.251692 -279.692354)
		(mid 138.240714 -279.648089)
		(end 138.210544 -279.613868)
		(width 0.088646)
		(layer "In11.Cu")
		(net "M_H_CPU1_SA_DQ<12>")
	)
	(arc
		(start 134.492492 -278.012144)
		(mid 134.305294 -277.962001)
		(end 134.118096 -278.012144)
		(width 0.088646)
		(layer "In11.Cu")
		(net "M_H_CPU1_SA_DQ<12>")
	)
	(arc
		(start 135.057896 -278.012144)
		(mid 134.775194 -278.087886)
		(end 134.492492 -278.012144)
		(width 0.088646)
		(layer "In11.Cu")
		(net "M_H_CPU1_SA_DQ<12>")
	)
	(arc
		(start 136.841992 -278.82596)
		(mid 136.637657 -278.623355)
		(end 136.559544 -278.346408)
		(width 0.088646)
		(layer "In11.Cu")
		(net "M_H_CPU1_SA_DQ<12>")
	)
	(arc
		(start 132.23875 -278.012144)
		(mid 131.964521 -278.088069)
		(end 131.688078 -278.02078)
		(width 0.088646)
		(layer "In11.Cu")
		(net "M_H_CPU1_SA_DQ<12>")
	)
	(arc
		(start 127.631444 -275.8948)
		(mid 127.583765 -275.7119)
		(end 127.452882 -275.575522)
		(width 0.088646)
		(layer "In11.Cu")
		(net "M_H_CPU1_SA_DQ<12>")
	)
	(arc
		(start 138.284712 -279.91943)
		(mid 138.260262 -279.882838)
		(end 138.251692 -279.839674)
		(width 0.088646)
		(layer "In11.Cu")
		(net "M_H_CPU1_SA_DQ<12>")
	)
	(arc
		(start 124.235464 -274.582636)
		(mid 123.958989 -274.515316)
		(end 123.684792 -274.591272)
		(width 0.088646)
		(layer "In11.Cu")
		(net "M_H_CPU1_SA_DQ<12>")
	)
	(arc
		(start 132.613146 -278.012144)
		(mid 132.425948 -277.962001)
		(end 132.23875 -278.012144)
		(width 0.088646)
		(layer "In11.Cu")
		(net "M_H_CPU1_SA_DQ<12>")
	)
	(arc
		(start 124.624592 -274.591272)
		(mid 124.437394 -274.641415)
		(end 124.250196 -274.591272)
		(width 0.088646)
		(layer "In11.Cu")
		(net "M_H_CPU1_SA_DQ<12>")
	)
	(arc
		(start 125.175264 -274.582636)
		(mid 124.898789 -274.515316)
		(end 124.624592 -274.591272)
		(width 0.088646)
		(layer "In11.Cu")
		(net "M_H_CPU1_SA_DQ<12>")
	)
	(arc
		(start 136.559544 -278.336502)
		(mid 136.511865 -278.153602)
		(end 136.380982 -278.017224)
		(width 0.088646)
		(layer "In11.Cu")
		(net "M_H_CPU1_SA_DQ<12>")
	)
	(arc
		(start 134.118096 -278.012144)
		(mid 133.841537 -278.087853)
		(end 133.56336 -278.01824)
		(width 0.088646)
		(layer "In11.Cu")
		(net "M_H_CPU1_SA_DQ<12>")
	)
	(arc
		(start 126.974092 -274.756372)
		(mid 126.769757 -274.553767)
		(end 126.691644 -274.27682)
		(width 0.088646)
		(layer "In11.Cu")
		(net "M_H_CPU1_SA_DQ<12>")
	)
	(arc
		(start 131.673346 -278.012144)
		(mid 131.486148 -277.962001)
		(end 131.29895 -278.012144)
		(width 0.088646)
		(layer "In11.Cu")
		(net "M_H_CPU1_SA_DQ<12>")
	)
	(arc
		(start 128.934464 -277.20671)
		(mid 128.657989 -277.27403)
		(end 128.383792 -277.198074)
		(width 0.088646)
		(layer "In11.Cu")
		(net "M_H_CPU1_SA_DQ<12>")
	)
	(arc
		(start 127.90805 -276.380702)
		(mid 127.705463 -276.174351)
		(end 127.631444 -275.8948)
		(width 0.088646)
		(layer "In11.Cu")
		(net "M_H_CPU1_SA_DQ<12>")
	)
	(arc
		(start 133.552946 -278.012144)
		(mid 133.365748 -277.962001)
		(end 133.17855 -278.012144)
		(width 0.088646)
		(layer "In11.Cu")
		(net "M_H_CPU1_SA_DQ<12>")
	)
	(arc
		(start 138.909298 -280.590752)
		(mid 138.900713 -280.547594)
		(end 138.876278 -280.510996)
		(width 0.088646)
		(layer "In11.Cu")
		(net "M_H_CPU1_SA_DQ<12>")
	)
	(arc
		(start 123.684792 -274.591272)
		(mid 123.526304 -274.640205)
		(end 123.362212 -274.61591)
		(width 0.088646)
		(layer "In11.Cu")
		(net "M_H_CPU1_SA_DQ<12>")
	)
	(arc
		(start 137.407396 -278.82596)
		(mid 137.124694 -278.901736)
		(end 136.841992 -278.82596)
		(width 0.088646)
		(layer "In11.Cu")
		(net "M_H_CPU1_SA_DQ<12>")
	)
	(arc
		(start 127.161544 -275.08073)
		(mid 127.113865 -274.89783)
		(end 126.982982 -274.761452)
		(width 0.088646)
		(layer "In11.Cu")
		(net "M_H_CPU1_SA_DQ<12>")
	)
	(arc
		(start 137.969244 -279.150318)
		(mid 137.921565 -278.967418)
		(end 137.790682 -278.83104)
		(width 0.088646)
		(layer "In11.Cu")
		(net "M_H_CPU1_SA_DQ<12>")
	)
	(arc
		(start 128.383792 -277.198074)
		(mid 128.180969 -276.997843)
		(end 128.101598 -276.72411)
		(width 0.088646)
		(layer "In11.Cu")
		(net "M_H_CPU1_SA_DQ<12>")
	)
	(arc
		(start 135.997696 -278.012144)
		(mid 135.723467 -278.088069)
		(end 135.447024 -278.02078)
		(width 0.088646)
		(layer "In11.Cu")
		(net "M_H_CPU1_SA_DQ<12>")
	)
	(arc
		(start 136.372092 -278.012144)
		(mid 136.184894 -277.962001)
		(end 135.997696 -278.012144)
		(width 0.088646)
		(layer "In11.Cu")
		(net "M_H_CPU1_SA_DQ<12>")
	)
	(arc
		(start 126.691644 -274.258278)
		(mid 126.639374 -274.075913)
		(end 126.504446 -273.942556)
		(width 0.088646)
		(layer "In11.Cu")
		(net "M_H_CPU1_SA_DQ<12>")
	)
	(arc
		(start 138.210544 -279.613868)
		(mid 138.035353 -279.416053)
		(end 137.969244 -279.160224)
		(width 0.088646)
		(layer "In11.Cu")
		(net "M_H_CPU1_SA_DQ<12>")
	)
	(arc
		(start 137.781792 -278.82596)
		(mid 137.594594 -278.775817)
		(end 137.407396 -278.82596)
		(width 0.088646)
		(layer "In11.Cu")
		(net "M_H_CPU1_SA_DQ<12>")
	)
	(arc
		(start 128.101598 -276.708616)
		(mid 128.053919 -276.525716)
		(end 127.923036 -276.389338)
		(width 0.088646)
		(layer "In11.Cu")
		(net "M_H_CPU1_SA_DQ<12>")
	)
	(arc
		(start 126.504446 -273.942556)
		(mid 126.317248 -273.892413)
		(end 126.13005 -273.942556)
		(width 0.088646)
		(layer "In11.Cu")
		(net "M_H_CPU1_SA_DQ<12>")
	)
	(arc
		(start 125.564392 -274.591272)
		(mid 125.377194 -274.641415)
		(end 125.189996 -274.591272)
		(width 0.088646)
		(layer "In11.Cu")
		(net "M_H_CPU1_SA_DQ<12>")
	)
	(arc
		(start 130.348482 -278.01824)
		(mid 130.070304 -278.087932)
		(end 129.793746 -278.012144)
		(width 0.088646)
		(layer "In11.Cu")
		(net "M_H_CPU1_SA_DQ<12>")
	)
	(arc
		(start 129.323592 -277.198074)
		(mid 129.136394 -277.147931)
		(end 128.949196 -277.198074)
		(width 0.088646)
		(layer "In11.Cu")
		(net "M_H_CPU1_SA_DQ<12>")
	)
	(arc
		(start 131.288536 -278.01824)
		(mid 131.010104 -278.088054)
		(end 130.733292 -278.012144)
		(width 0.088646)
		(layer "In11.Cu")
		(net "M_H_CPU1_SA_DQ<12>")
	)
	(segment
		(start 210.598258 -304.848768)
		(end 210.603084 -304.848768)
		(width 0.101854)
		(layer "F.Cu")
		(net "M_H_CPU1_SA_DQ<11>")
	)
	(segment
		(start 125.377448 -275.35886)
		(end 125.377448 -275.894546)
		(width 0.20066)
		(layer "F.Cu")
		(net "M_H_CPU1_SA_DQ<11>")
	)
	(segment
		(start 213.515448 -304.649886)
		(end 213.515448 -304.398934)
		(width 0.20066)
		(layer "F.Cu")
		(net "M_H_CPU1_SA_DQ<11>")
	)
	(segment
		(start 212.618066 -304.841656)
		(end 212.630258 -304.853848)
		(width 0.1016)
		(layer "F.Cu")
		(net "M_H_CPU1_SA_DQ<11>")
	)
	(segment
		(start 214.133684 -304.164746)
		(end 214.385652 -304.416714)
		(width 0.20066)
		(layer "F.Cu")
		(net "M_H_CPU1_SA_DQ<11>")
	)
	(segment
		(start 213.515448 -304.398934)
		(end 213.749636 -304.164746)
		(width 0.20066)
		(layer "F.Cu")
		(net "M_H_CPU1_SA_DQ<11>")
	)
	(segment
		(start 214.385652 -304.416714)
		(end 215.719914 -304.416714)
		(width 0.20066)
		(layer "F.Cu")
		(net "M_H_CPU1_SA_DQ<11>")
	)
	(segment
		(start 209.874358 -304.416714)
		(end 210.306412 -304.848768)
		(width 0.20066)
		(layer "F.Cu")
		(net "M_H_CPU1_SA_DQ<11>")
	)
	(segment
		(start 210.610196 -304.841656)
		(end 212.618066 -304.841656)
		(width 0.1016)
		(layer "F.Cu")
		(net "M_H_CPU1_SA_DQ<11>")
	)
	(segment
		(start 210.603084 -304.848768)
		(end 210.610196 -304.841656)
		(width 0.1016)
		(layer "F.Cu")
		(net "M_H_CPU1_SA_DQ<11>")
	)
	(segment
		(start 207.071214 -304.416714)
		(end 208.176114 -304.416714)
		(width 0.20066)
		(layer "F.Cu")
		(net "M_H_CPU1_SA_DQ<11>")
	)
	(segment
		(start 210.306412 -304.848768)
		(end 210.598258 -304.848768)
		(width 0.20066)
		(layer "F.Cu")
		(net "M_H_CPU1_SA_DQ<11>")
	)
	(segment
		(start 213.311486 -304.853848)
		(end 213.515448 -304.649886)
		(width 0.20066)
		(layer "F.Cu")
		(net "M_H_CPU1_SA_DQ<11>")
	)
	(segment
		(start 212.630258 -304.853848)
		(end 213.311486 -304.853848)
		(width 0.20066)
		(layer "F.Cu")
		(net "M_H_CPU1_SA_DQ<11>")
	)
	(segment
		(start 213.749636 -304.164746)
		(end 214.133684 -304.164746)
		(width 0.20066)
		(layer "F.Cu")
		(net "M_H_CPU1_SA_DQ<11>")
	)
	(segment
		(start 208.176114 -304.416714)
		(end 209.874358 -304.416714)
		(width 0.20066)
		(layer "F.Cu")
		(net "M_H_CPU1_SA_DQ<11>")
	)
	(segment
		(start 125.377448 -275.894546)
		(end 125.377194 -275.8948)
		(width 0.20066)
		(layer "F.Cu")
		(net "M_H_CPU1_SA_DQ<11>")
	)
	(segment
		(start 139.408916 -285.736792)
		(end 138.933936 -285.261812)
		(width 0.088646)
		(layer "In11.Cu")
		(net "M_H_CPU1_SA_DQ<11>")
	)
	(segment
		(start 189.825884 -311.789826)
		(end 188.827918 -310.79186)
		(width 0.18288)
		(layer "In11.Cu")
		(net "M_H_CPU1_SA_DQ<11>")
	)
	(segment
		(start 135.810244 -281.59202)
		(end 135.810244 -281.582114)
		(width 0.088646)
		(layer "In11.Cu")
		(net "M_H_CPU1_SA_DQ<11>")
	)
	(segment
		(start 135.997696 -281.916378)
		(end 135.988806 -281.911298)
		(width 0.088646)
		(layer "In11.Cu")
		(net "M_H_CPU1_SA_DQ<11>")
	)
	(segment
		(start 125.18136 -277.203154)
		(end 125.19025 -277.198074)
		(width 0.088646)
		(layer "In11.Cu")
		(net "M_H_CPU1_SA_DQ<11>")
	)
	(segment
		(start 202.571858 -304.65903)
		(end 201.636122 -304.65903)
		(width 0.18288)
		(layer "In11.Cu")
		(net "M_H_CPU1_SA_DQ<11>")
	)
	(segment
		(start 198.958708 -307.514244)
		(end 198.171308 -308.301644)
		(width 0.18288)
		(layer "In11.Cu")
		(net "M_H_CPU1_SA_DQ<11>")
	)
	(segment
		(start 180.75783 -311.743852)
		(end 178.058826 -311.743852)
		(width 0.18288)
		(layer "In11.Cu")
		(net "M_H_CPU1_SA_DQ<11>")
	)
	(segment
		(start 138.159744 -284.033722)
		(end 138.159744 -284.018228)
		(width 0.088646)
		(layer "In11.Cu")
		(net "M_H_CPU1_SA_DQ<11>")
	)
	(segment
		(start 137.690098 -283.219906)
		(end 137.690098 -283.205682)
		(width 0.088646)
		(layer "In11.Cu")
		(net "M_H_CPU1_SA_DQ<11>")
	)
	(segment
		(start 178.058826 -311.743852)
		(end 177.30978 -312.492898)
		(width 0.18288)
		(layer "In11.Cu")
		(net "M_H_CPU1_SA_DQ<11>")
	)
	(segment
		(start 160.62833 -311.029604)
		(end 159.686752 -310.088026)
		(width 0.18288)
		(layer "In11.Cu")
		(net "M_H_CPU1_SA_DQ<11>")
	)
	(segment
		(start 183.411368 -310.781446)
		(end 181.720236 -310.781446)
		(width 0.18288)
		(layer "In11.Cu")
		(net "M_H_CPU1_SA_DQ<11>")
	)
	(segment
		(start 133.567678 -280.279856)
		(end 133.552946 -280.288492)
		(width 0.088646)
		(layer "In11.Cu")
		(net "M_H_CPU1_SA_DQ<11>")
	)
	(segment
		(start 125.462284 -276.246336)
		(end 125.377194 -276.161246)
		(width 0.088646)
		(layer "In11.Cu")
		(net "M_H_CPU1_SA_DQ<11>")
	)
	(segment
		(start 173.587156 -312.492898)
		(end 173.270672 -312.809382)
		(width 0.18288)
		(layer "In11.Cu")
		(net "M_H_CPU1_SA_DQ<11>")
	)
	(segment
		(start 135.340344 -280.778204)
		(end 135.340344 -280.76398)
		(width 0.088646)
		(layer "In11.Cu")
		(net "M_H_CPU1_SA_DQ<11>")
	)
	(segment
		(start 173.270672 -312.809382)
		(end 173.270672 -313.149488)
		(width 0.18288)
		(layer "In11.Cu")
		(net "M_H_CPU1_SA_DQ<11>")
	)
	(segment
		(start 192.339214 -312.49493)
		(end 191.399922 -312.49493)
		(width 0.18288)
		(layer "In11.Cu")
		(net "M_H_CPU1_SA_DQ<11>")
	)
	(segment
		(start 201.636122 -304.65903)
		(end 200.84288 -305.452272)
		(width 0.18288)
		(layer "In11.Cu")
		(net "M_H_CPU1_SA_DQ<11>")
	)
	(segment
		(start 125.942344 -279.150318)
		(end 125.942344 -279.134824)
		(width 0.088646)
		(layer "In11.Cu")
		(net "M_H_CPU1_SA_DQ<11>")
	)
	(segment
		(start 200.84288 -306.366672)
		(end 199.695308 -307.514244)
		(width 0.18288)
		(layer "In11.Cu")
		(net "M_H_CPU1_SA_DQ<11>")
	)
	(segment
		(start 183.756554 -311.126632)
		(end 183.411368 -310.781446)
		(width 0.18288)
		(layer "In11.Cu")
		(net "M_H_CPU1_SA_DQ<11>")
	)
	(segment
		(start 138.629644 -284.856174)
		(end 138.629644 -284.832044)
		(width 0.088646)
		(layer "In11.Cu")
		(net "M_H_CPU1_SA_DQ<11>")
	)
	(segment
		(start 153.196544 -300.902116)
		(end 144.651476 -292.357048)
		(width 0.18288)
		(layer "In11.Cu")
		(net "M_H_CPU1_SA_DQ<11>")
	)
	(segment
		(start 177.30978 -312.492898)
		(end 173.587156 -312.492898)
		(width 0.18288)
		(layer "In11.Cu")
		(net "M_H_CPU1_SA_DQ<11>")
	)
	(segment
		(start 195.136262 -310.21909)
		(end 193.228976 -312.126376)
		(width 0.18288)
		(layer "In11.Cu")
		(net "M_H_CPU1_SA_DQ<11>")
	)
	(segment
		(start 137.87755 -283.544264)
		(end 137.86866 -283.539184)
		(width 0.088646)
		(layer "In11.Cu")
		(net "M_H_CPU1_SA_DQ<11>")
	)
	(segment
		(start 207.071214 -304.416714)
		(end 206.262732 -304.416714)
		(width 0.18288)
		(layer "In11.Cu")
		(net "M_H_CPU1_SA_DQ<11>")
	)
	(segment
		(start 125.66015 -278.66086)
		(end 125.65126 -278.65578)
		(width 0.088646)
		(layer "In11.Cu")
		(net "M_H_CPU1_SA_DQ<11>")
	)
	(segment
		(start 187.396374 -310.79186)
		(end 187.061602 -311.126632)
		(width 0.18288)
		(layer "In11.Cu")
		(net "M_H_CPU1_SA_DQ<11>")
	)
	(segment
		(start 125.472698 -278.336502)
		(end 125.472698 -278.31796)
		(width 0.088646)
		(layer "In11.Cu")
		(net "M_H_CPU1_SA_DQ<11>")
	)
	(segment
		(start 137.219944 -282.405836)
		(end 137.219944 -282.39593)
		(width 0.088646)
		(layer "In11.Cu")
		(net "M_H_CPU1_SA_DQ<11>")
	)
	(segment
		(start 197.358508 -308.301644)
		(end 195.656708 -310.003444)
		(width 0.18288)
		(layer "In11.Cu")
		(net "M_H_CPU1_SA_DQ<11>")
	)
	(segment
		(start 137.407396 -282.730194)
		(end 137.398506 -282.725114)
		(width 0.088646)
		(layer "In11.Cu")
		(net "M_H_CPU1_SA_DQ<11>")
	)
	(segment
		(start 138.347196 -284.35808)
		(end 138.338306 -284.353)
		(width 0.088646)
		(layer "In11.Cu")
		(net "M_H_CPU1_SA_DQ<11>")
	)
	(segment
		(start 153.196544 -305.608736)
		(end 153.196544 -300.902116)
		(width 0.18288)
		(layer "In11.Cu")
		(net "M_H_CPU1_SA_DQ<11>")
	)
	(segment
		(start 157.675834 -310.088026)
		(end 153.196544 -305.608736)
		(width 0.18288)
		(layer "In11.Cu")
		(net "M_H_CPU1_SA_DQ<11>")
	)
	(segment
		(start 129.808478 -280.279856)
		(end 129.793746 -280.288492)
		(width 0.088646)
		(layer "In11.Cu")
		(net "M_H_CPU1_SA_DQ<11>")
	)
	(segment
		(start 135.527796 -281.102562)
		(end 135.518906 -281.097482)
		(width 0.088646)
		(layer "In11.Cu")
		(net "M_H_CPU1_SA_DQ<11>")
	)
	(segment
		(start 125.19025 -277.84679)
		(end 125.18136 -277.84171)
		(width 0.088646)
		(layer "In11.Cu")
		(net "M_H_CPU1_SA_DQ<11>")
	)
	(segment
		(start 139.516866 -285.736792)
		(end 139.408916 -285.736792)
		(width 0.088646)
		(layer "In11.Cu")
		(net "M_H_CPU1_SA_DQ<11>")
	)
	(segment
		(start 188.827918 -310.79186)
		(end 187.396374 -310.79186)
		(width 0.18288)
		(layer "In11.Cu")
		(net "M_H_CPU1_SA_DQ<11>")
	)
	(segment
		(start 173.270672 -313.149488)
		(end 173.076616 -313.343544)
		(width 0.18288)
		(layer "In11.Cu")
		(net "M_H_CPU1_SA_DQ<11>")
	)
	(segment
		(start 165.28796 -310.099964)
		(end 164.35832 -311.029604)
		(width 0.18288)
		(layer "In11.Cu")
		(net "M_H_CPU1_SA_DQ<11>")
	)
	(segment
		(start 173.076616 -313.343544)
		(end 171.320714 -313.343544)
		(width 0.18288)
		(layer "In11.Cu")
		(net "M_H_CPU1_SA_DQ<11>")
	)
	(segment
		(start 202.752706 -304.839878)
		(end 202.571858 -304.65903)
		(width 0.18288)
		(layer "In11.Cu")
		(net "M_H_CPU1_SA_DQ<11>")
	)
	(segment
		(start 125.377194 -276.161246)
		(end 125.377194 -275.8948)
		(width 0.088646)
		(layer "In11.Cu")
		(net "M_H_CPU1_SA_DQ<11>")
	)
	(segment
		(start 191.399922 -312.49493)
		(end 190.694818 -311.789826)
		(width 0.18288)
		(layer "In11.Cu")
		(net "M_H_CPU1_SA_DQ<11>")
	)
	(segment
		(start 144.651476 -292.357048)
		(end 144.651476 -290.871402)
		(width 0.18288)
		(layer "In11.Cu")
		(net "M_H_CPU1_SA_DQ<11>")
	)
	(segment
		(start 190.694818 -311.789826)
		(end 189.825884 -311.789826)
		(width 0.18288)
		(layer "In11.Cu")
		(net "M_H_CPU1_SA_DQ<11>")
	)
	(segment
		(start 198.171308 -308.301644)
		(end 197.358508 -308.301644)
		(width 0.18288)
		(layer "In11.Cu")
		(net "M_H_CPU1_SA_DQ<11>")
	)
	(segment
		(start 195.656708 -310.003444)
		(end 195.136262 -310.21909)
		(width 0.18288)
		(layer "In11.Cu")
		(net "M_H_CPU1_SA_DQ<11>")
	)
	(segment
		(start 128.009396 -279.474676)
		(end 127.994664 -279.46604)
		(width 0.088646)
		(layer "In11.Cu")
		(net "M_H_CPU1_SA_DQ<11>")
	)
	(segment
		(start 199.695308 -307.514244)
		(end 198.958708 -307.514244)
		(width 0.18288)
		(layer "In11.Cu")
		(net "M_H_CPU1_SA_DQ<11>")
	)
	(segment
		(start 126.129796 -279.474676)
		(end 126.120906 -279.469596)
		(width 0.088646)
		(layer "In11.Cu")
		(net "M_H_CPU1_SA_DQ<11>")
	)
	(segment
		(start 128.868678 -280.279856)
		(end 128.853946 -280.288492)
		(width 0.088646)
		(layer "In11.Cu")
		(net "M_H_CPU1_SA_DQ<11>")
	)
	(segment
		(start 203.913486 -304.839878)
		(end 202.752706 -304.839878)
		(width 0.18288)
		(layer "In11.Cu")
		(net "M_H_CPU1_SA_DQ<11>")
	)
	(segment
		(start 131.68376 -280.282396)
		(end 131.673346 -280.288492)
		(width 0.088646)
		(layer "In11.Cu")
		(net "M_H_CPU1_SA_DQ<11>")
	)
	(segment
		(start 132.623306 -280.282396)
		(end 132.612892 -280.288492)
		(width 0.088646)
		(layer "In11.Cu")
		(net "M_H_CPU1_SA_DQ<11>")
	)
	(segment
		(start 125.462284 -276.537166)
		(end 125.462284 -276.246336)
		(width 0.088646)
		(layer "In11.Cu")
		(net "M_H_CPU1_SA_DQ<11>")
	)
	(segment
		(start 171.320714 -313.343544)
		(end 168.07561 -310.099964)
		(width 0.18288)
		(layer "In11.Cu")
		(net "M_H_CPU1_SA_DQ<11>")
	)
	(segment
		(start 164.35832 -311.029604)
		(end 160.62833 -311.029604)
		(width 0.18288)
		(layer "In11.Cu")
		(net "M_H_CPU1_SA_DQ<11>")
	)
	(segment
		(start 187.061602 -311.126632)
		(end 183.756554 -311.126632)
		(width 0.18288)
		(layer "In11.Cu")
		(net "M_H_CPU1_SA_DQ<11>")
	)
	(segment
		(start 144.651476 -290.871402)
		(end 139.750038 -285.969964)
		(width 0.18288)
		(layer "In11.Cu")
		(net "M_H_CPU1_SA_DQ<11>")
	)
	(segment
		(start 205.253844 -305.425602)
		(end 204.49921 -305.425602)
		(width 0.18288)
		(layer "In11.Cu")
		(net "M_H_CPU1_SA_DQ<11>")
	)
	(segment
		(start 128.47955 -280.288492)
		(end 128.47066 -280.283412)
		(width 0.088646)
		(layer "In11.Cu")
		(net "M_H_CPU1_SA_DQ<11>")
	)
	(segment
		(start 168.07561 -310.099964)
		(end 165.28796 -310.099964)
		(width 0.18288)
		(layer "In11.Cu")
		(net "M_H_CPU1_SA_DQ<11>")
	)
	(segment
		(start 193.228976 -312.126376)
		(end 192.339214 -312.49493)
		(width 0.18288)
		(layer "In11.Cu")
		(net "M_H_CPU1_SA_DQ<11>")
	)
	(segment
		(start 206.262732 -304.416714)
		(end 205.253844 -305.425602)
		(width 0.18288)
		(layer "In11.Cu")
		(net "M_H_CPU1_SA_DQ<11>")
	)
	(segment
		(start 139.750038 -285.969964)
		(end 139.516866 -285.736792)
		(width 0.088646)
		(layer "In11.Cu")
		(net "M_H_CPU1_SA_DQ<11>")
	)
	(segment
		(start 204.49921 -305.425602)
		(end 203.913486 -304.839878)
		(width 0.18288)
		(layer "In11.Cu")
		(net "M_H_CPU1_SA_DQ<11>")
	)
	(segment
		(start 181.720236 -310.781446)
		(end 180.75783 -311.743852)
		(width 0.18288)
		(layer "In11.Cu")
		(net "M_H_CPU1_SA_DQ<11>")
	)
	(segment
		(start 128.015492 -279.478232)
		(end 128.009396 -279.474676)
		(width 0.088646)
		(layer "In11.Cu")
		(net "M_H_CPU1_SA_DQ<11>")
	)
	(segment
		(start 200.84288 -305.452272)
		(end 200.84288 -306.366672)
		(width 0.18288)
		(layer "In11.Cu")
		(net "M_H_CPU1_SA_DQ<11>")
	)
	(segment
		(start 130.748278 -280.279856)
		(end 130.733546 -280.288492)
		(width 0.088646)
		(layer "In11.Cu")
		(net "M_H_CPU1_SA_DQ<11>")
	)
	(segment
		(start 125.449838 -276.549612)
		(end 125.462284 -276.537166)
		(width 0.088646)
		(layer "In11.Cu")
		(net "M_H_CPU1_SA_DQ<11>")
	)
	(segment
		(start 159.686752 -310.088026)
		(end 157.675834 -310.088026)
		(width 0.18288)
		(layer "In11.Cu")
		(net "M_H_CPU1_SA_DQ<11>")
	)
	(arc
		(start 131.29895 -280.288492)
		(mid 131.024721 -280.212567)
		(end 130.748278 -280.279856)
		(width 0.088646)
		(layer "In11.Cu")
		(net "M_H_CPU1_SA_DQ<11>")
	)
	(arc
		(start 125.18136 -277.84171)
		(mid 125.002763 -277.522432)
		(end 125.18136 -277.203154)
		(width 0.088646)
		(layer "In11.Cu")
		(net "M_H_CPU1_SA_DQ<11>")
	)
	(arc
		(start 125.19025 -277.198074)
		(mid 125.432136 -276.918748)
		(end 125.449838 -276.549612)
		(width 0.088646)
		(layer "In11.Cu")
		(net "M_H_CPU1_SA_DQ<11>")
	)
	(arc
		(start 133.17855 -280.288492)
		(mid 132.901737 -280.212656)
		(end 132.623306 -280.282396)
		(width 0.088646)
		(layer "In11.Cu")
		(net "M_H_CPU1_SA_DQ<11>")
	)
	(arc
		(start 129.41935 -280.288492)
		(mid 129.145121 -280.212567)
		(end 128.868678 -280.279856)
		(width 0.088646)
		(layer "In11.Cu")
		(net "M_H_CPU1_SA_DQ<11>")
	)
	(arc
		(start 131.673346 -280.288492)
		(mid 131.486148 -280.338635)
		(end 131.29895 -280.288492)
		(width 0.088646)
		(layer "In11.Cu")
		(net "M_H_CPU1_SA_DQ<11>")
	)
	(arc
		(start 137.219944 -282.39593)
		(mid 137.141833 -282.118981)
		(end 136.937496 -281.916378)
		(width 0.088646)
		(layer "In11.Cu")
		(net "M_H_CPU1_SA_DQ<11>")
	)
	(arc
		(start 127.994664 -279.46604)
		(mid 127.718189 -279.39872)
		(end 127.443992 -279.474676)
		(width 0.088646)
		(layer "In11.Cu")
		(net "M_H_CPU1_SA_DQ<11>")
	)
	(arc
		(start 128.47066 -280.283412)
		(mid 128.339746 -280.147052)
		(end 128.292098 -279.964134)
		(width 0.088646)
		(layer "In11.Cu")
		(net "M_H_CPU1_SA_DQ<11>")
	)
	(arc
		(start 134.492746 -280.288492)
		(mid 134.305548 -280.338635)
		(end 134.11835 -280.288492)
		(width 0.088646)
		(layer "In11.Cu")
		(net "M_H_CPU1_SA_DQ<11>")
	)
	(arc
		(start 126.504192 -279.474676)
		(mid 126.316994 -279.524819)
		(end 126.129796 -279.474676)
		(width 0.088646)
		(layer "In11.Cu")
		(net "M_H_CPU1_SA_DQ<11>")
	)
	(arc
		(start 126.120906 -279.469596)
		(mid 125.989992 -279.333236)
		(end 125.942344 -279.150318)
		(width 0.088646)
		(layer "In11.Cu")
		(net "M_H_CPU1_SA_DQ<11>")
	)
	(arc
		(start 132.238496 -280.288492)
		(mid 131.961937 -280.212783)
		(end 131.68376 -280.282396)
		(width 0.088646)
		(layer "In11.Cu")
		(net "M_H_CPU1_SA_DQ<11>")
	)
	(arc
		(start 134.11835 -280.288492)
		(mid 133.844121 -280.212567)
		(end 133.567678 -280.279856)
		(width 0.088646)
		(layer "In11.Cu")
		(net "M_H_CPU1_SA_DQ<11>")
	)
	(arc
		(start 138.159744 -284.018228)
		(mid 138.080374 -283.744494)
		(end 137.87755 -283.544264)
		(width 0.088646)
		(layer "In11.Cu")
		(net "M_H_CPU1_SA_DQ<11>")
	)
	(arc
		(start 135.810244 -281.582114)
		(mid 135.732133 -281.305165)
		(end 135.527796 -281.102562)
		(width 0.088646)
		(layer "In11.Cu")
		(net "M_H_CPU1_SA_DQ<11>")
	)
	(arc
		(start 135.340344 -280.76398)
		(mid 135.261125 -280.489295)
		(end 135.057642 -280.288492)
		(width 0.088646)
		(layer "In11.Cu")
		(net "M_H_CPU1_SA_DQ<11>")
	)
	(arc
		(start 138.629644 -284.832044)
		(mid 138.550195 -284.558248)
		(end 138.347196 -284.35808)
		(width 0.088646)
		(layer "In11.Cu")
		(net "M_H_CPU1_SA_DQ<11>")
	)
	(arc
		(start 129.793746 -280.288492)
		(mid 129.606548 -280.338635)
		(end 129.41935 -280.288492)
		(width 0.088646)
		(layer "In11.Cu")
		(net "M_H_CPU1_SA_DQ<11>")
	)
	(arc
		(start 130.35915 -280.288492)
		(mid 130.084921 -280.212567)
		(end 129.808478 -280.279856)
		(width 0.088646)
		(layer "In11.Cu")
		(net "M_H_CPU1_SA_DQ<11>")
	)
	(arc
		(start 137.86866 -283.539184)
		(mid 137.737746 -283.402824)
		(end 137.690098 -283.219906)
		(width 0.088646)
		(layer "In11.Cu")
		(net "M_H_CPU1_SA_DQ<11>")
	)
	(arc
		(start 125.472698 -278.31796)
		(mid 125.392536 -278.045771)
		(end 125.19025 -277.84679)
		(width 0.088646)
		(layer "In11.Cu")
		(net "M_H_CPU1_SA_DQ<11>")
	)
	(arc
		(start 125.65126 -278.65578)
		(mid 125.520346 -278.51942)
		(end 125.472698 -278.336502)
		(width 0.088646)
		(layer "In11.Cu")
		(net "M_H_CPU1_SA_DQ<11>")
	)
	(arc
		(start 137.398506 -282.725114)
		(mid 137.267592 -282.588754)
		(end 137.219944 -282.405836)
		(width 0.088646)
		(layer "In11.Cu")
		(net "M_H_CPU1_SA_DQ<11>")
	)
	(arc
		(start 127.069596 -279.474676)
		(mid 126.786894 -279.3989)
		(end 126.504192 -279.474676)
		(width 0.088646)
		(layer "In11.Cu")
		(net "M_H_CPU1_SA_DQ<11>")
	)
	(arc
		(start 135.988806 -281.911298)
		(mid 135.857892 -281.774938)
		(end 135.810244 -281.59202)
		(width 0.088646)
		(layer "In11.Cu")
		(net "M_H_CPU1_SA_DQ<11>")
	)
	(arc
		(start 135.057642 -280.288492)
		(mid 134.775194 -280.212877)
		(end 134.492746 -280.288492)
		(width 0.088646)
		(layer "In11.Cu")
		(net "M_H_CPU1_SA_DQ<11>")
	)
	(arc
		(start 130.733546 -280.288492)
		(mid 130.546348 -280.338635)
		(end 130.35915 -280.288492)
		(width 0.088646)
		(layer "In11.Cu")
		(net "M_H_CPU1_SA_DQ<11>")
	)
	(arc
		(start 132.612892 -280.288492)
		(mid 132.425694 -280.338635)
		(end 132.238496 -280.288492)
		(width 0.088646)
		(layer "In11.Cu")
		(net "M_H_CPU1_SA_DQ<11>")
	)
	(arc
		(start 133.552946 -280.288492)
		(mid 133.365748 -280.338635)
		(end 133.17855 -280.288492)
		(width 0.088646)
		(layer "In11.Cu")
		(net "M_H_CPU1_SA_DQ<11>")
	)
	(arc
		(start 136.937496 -281.916378)
		(mid 136.654794 -281.840602)
		(end 136.372092 -281.916378)
		(width 0.088646)
		(layer "In11.Cu")
		(net "M_H_CPU1_SA_DQ<11>")
	)
	(arc
		(start 137.690098 -283.205682)
		(mid 137.610879 -282.930997)
		(end 137.407396 -282.730194)
		(width 0.088646)
		(layer "In11.Cu")
		(net "M_H_CPU1_SA_DQ<11>")
	)
	(arc
		(start 128.292098 -279.964134)
		(mid 128.218107 -279.684568)
		(end 128.015492 -279.478232)
		(width 0.088646)
		(layer "In11.Cu")
		(net "M_H_CPU1_SA_DQ<11>")
	)
	(arc
		(start 138.338306 -284.353)
		(mid 138.207392 -284.21664)
		(end 138.159744 -284.033722)
		(width 0.088646)
		(layer "In11.Cu")
		(net "M_H_CPU1_SA_DQ<11>")
	)
	(arc
		(start 138.933936 -285.261812)
		(mid 138.878345 -285.213003)
		(end 138.816842 -285.171896)
		(width 0.088646)
		(layer "In11.Cu")
		(net "M_H_CPU1_SA_DQ<11>")
	)
	(arc
		(start 138.816842 -285.171896)
		(mid 138.681909 -285.038542)
		(end 138.629644 -284.856174)
		(width 0.088646)
		(layer "In11.Cu")
		(net "M_H_CPU1_SA_DQ<11>")
	)
	(arc
		(start 128.853946 -280.288492)
		(mid 128.666748 -280.338635)
		(end 128.47955 -280.288492)
		(width 0.088646)
		(layer "In11.Cu")
		(net "M_H_CPU1_SA_DQ<11>")
	)
	(arc
		(start 127.443992 -279.474676)
		(mid 127.256794 -279.524819)
		(end 127.069596 -279.474676)
		(width 0.088646)
		(layer "In11.Cu")
		(net "M_H_CPU1_SA_DQ<11>")
	)
	(arc
		(start 125.942344 -279.134824)
		(mid 125.862974 -278.86109)
		(end 125.66015 -278.66086)
		(width 0.088646)
		(layer "In11.Cu")
		(net "M_H_CPU1_SA_DQ<11>")
	)
	(arc
		(start 136.372092 -281.916378)
		(mid 136.184894 -281.966521)
		(end 135.997696 -281.916378)
		(width 0.088646)
		(layer "In11.Cu")
		(net "M_H_CPU1_SA_DQ<11>")
	)
	(arc
		(start 135.518906 -281.097482)
		(mid 135.387992 -280.961122)
		(end 135.340344 -280.778204)
		(width 0.088646)
		(layer "In11.Cu")
		(net "M_H_CPU1_SA_DQ<11>")
	)
	(segment
		(start 212.630258 -306.55387)
		(end 213.311486 -306.55387)
		(width 0.20066)
		(layer "F.Cu")
		(net "M_H_CPU1_SA_DQ<10>")
	)
	(segment
		(start 213.515448 -306.349908)
		(end 213.515448 -306.098956)
		(width 0.20066)
		(layer "F.Cu")
		(net "M_H_CPU1_SA_DQ<10>")
	)
	(segment
		(start 213.311486 -306.55387)
		(end 213.515448 -306.349908)
		(width 0.20066)
		(layer "F.Cu")
		(net "M_H_CPU1_SA_DQ<10>")
	)
	(segment
		(start 124.907294 -276.172676)
		(end 124.907548 -276.708616)
		(width 0.20066)
		(layer "F.Cu")
		(net "M_H_CPU1_SA_DQ<10>")
	)
	(segment
		(start 210.610196 -306.541678)
		(end 212.618066 -306.541678)
		(width 0.1016)
		(layer "F.Cu")
		(net "M_H_CPU1_SA_DQ<10>")
	)
	(segment
		(start 214.133684 -305.864768)
		(end 214.385652 -306.116736)
		(width 0.20066)
		(layer "F.Cu")
		(net "M_H_CPU1_SA_DQ<10>")
	)
	(segment
		(start 213.515448 -306.098956)
		(end 213.749636 -305.864768)
		(width 0.20066)
		(layer "F.Cu")
		(net "M_H_CPU1_SA_DQ<10>")
	)
	(segment
		(start 210.598258 -306.54879)
		(end 210.603084 -306.54879)
		(width 0.101854)
		(layer "F.Cu")
		(net "M_H_CPU1_SA_DQ<10>")
	)
	(segment
		(start 207.071214 -306.116736)
		(end 208.176114 -306.116736)
		(width 0.20066)
		(layer "F.Cu")
		(net "M_H_CPU1_SA_DQ<10>")
	)
	(segment
		(start 212.618066 -306.541678)
		(end 212.630258 -306.55387)
		(width 0.1016)
		(layer "F.Cu")
		(net "M_H_CPU1_SA_DQ<10>")
	)
	(segment
		(start 208.176114 -306.116736)
		(end 209.874358 -306.116736)
		(width 0.20066)
		(layer "F.Cu")
		(net "M_H_CPU1_SA_DQ<10>")
	)
	(segment
		(start 210.306412 -306.54879)
		(end 210.598258 -306.54879)
		(width 0.20066)
		(layer "F.Cu")
		(net "M_H_CPU1_SA_DQ<10>")
	)
	(segment
		(start 209.874358 -306.116736)
		(end 210.306412 -306.54879)
		(width 0.20066)
		(layer "F.Cu")
		(net "M_H_CPU1_SA_DQ<10>")
	)
	(segment
		(start 210.603084 -306.54879)
		(end 210.610196 -306.541678)
		(width 0.1016)
		(layer "F.Cu")
		(net "M_H_CPU1_SA_DQ<10>")
	)
	(segment
		(start 213.749636 -305.864768)
		(end 214.133684 -305.864768)
		(width 0.20066)
		(layer "F.Cu")
		(net "M_H_CPU1_SA_DQ<10>")
	)
	(segment
		(start 214.385652 -306.116736)
		(end 215.719914 -306.116736)
		(width 0.20066)
		(layer "F.Cu")
		(net "M_H_CPU1_SA_DQ<10>")
	)
	(segment
		(start 199.68083 -309.757826)
		(end 199.514206 -309.757826)
		(width 0.18288)
		(layer "In11.Cu")
		(net "M_H_CPU1_SA_DQ<10>")
	)
	(segment
		(start 206.752444 -306.25669)
		(end 206.224378 -306.508404)
		(width 0.18288)
		(layer "In11.Cu")
		(net "M_H_CPU1_SA_DQ<10>")
	)
	(segment
		(start 127.821944 -280.778204)
		(end 127.821944 -280.756106)
		(width 0.088646)
		(layer "In11.Cu")
		(net "M_H_CPU1_SA_DQ<10>")
	)
	(segment
		(start 124.250196 -277.198074)
		(end 124.25299 -277.19655)
		(width 0.088646)
		(layer "In11.Cu")
		(net "M_H_CPU1_SA_DQ<10>")
	)
	(segment
		(start 184.358026 -312.297318)
		(end 183.559958 -312.549794)
		(width 0.18288)
		(layer "In11.Cu")
		(net "M_H_CPU1_SA_DQ<10>")
	)
	(segment
		(start 186.862212 -312.297572)
		(end 186.860942 -312.297318)
		(width 0.18288)
		(layer "In11.Cu")
		(net "M_H_CPU1_SA_DQ<10>")
	)
	(segment
		(start 139.003024 -286.71647)
		(end 138.656568 -286.370014)
		(width 0.088646)
		(layer "In11.Cu")
		(net "M_H_CPU1_SA_DQ<10>")
	)
	(segment
		(start 202.198732 -307.239924)
		(end 199.68083 -309.757826)
		(width 0.18288)
		(layer "In11.Cu")
		(net "M_H_CPU1_SA_DQ<10>")
	)
	(segment
		(start 183.559958 -312.549794)
		(end 182.263796 -312.549794)
		(width 0.18288)
		(layer "In11.Cu")
		(net "M_H_CPU1_SA_DQ<10>")
	)
	(segment
		(start 143.499332 -291.212778)
		(end 139.003024 -286.71647)
		(width 0.18288)
		(layer "In11.Cu")
		(net "M_H_CPU1_SA_DQ<10>")
	)
	(segment
		(start 198.035418 -311.573926)
		(end 197.861936 -311.747408)
		(width 0.18288)
		(layer "In11.Cu")
		(net "M_H_CPU1_SA_DQ<10>")
	)
	(segment
		(start 152.180544 -306.292504)
		(end 152.180544 -301.323502)
		(width 0.18288)
		(layer "In11.Cu")
		(net "M_H_CPU1_SA_DQ<10>")
	)
	(segment
		(start 206.224378 -306.508404)
		(end 205.09484 -306.705254)
		(width 0.18288)
		(layer "In11.Cu")
		(net "M_H_CPU1_SA_DQ<10>")
	)
	(segment
		(start 124.532898 -278.336502)
		(end 124.532898 -278.322278)
		(width 0.088646)
		(layer "In11.Cu")
		(net "M_H_CPU1_SA_DQ<10>")
	)
	(segment
		(start 178.338226 -313.440826)
		(end 177.586386 -314.192666)
		(width 0.18288)
		(layer "In11.Cu")
		(net "M_H_CPU1_SA_DQ<10>")
	)
	(segment
		(start 126.984506 -280.282396)
		(end 126.974092 -280.288492)
		(width 0.088646)
		(layer "In11.Cu")
		(net "M_H_CPU1_SA_DQ<10>")
	)
	(segment
		(start 172.280326 -315.042804)
		(end 172.100494 -315.222636)
		(width 0.18288)
		(layer "In11.Cu")
		(net "M_H_CPU1_SA_DQ<10>")
	)
	(segment
		(start 173.267116 -315.042804)
		(end 172.280326 -315.042804)
		(width 0.18288)
		(layer "In11.Cu")
		(net "M_H_CPU1_SA_DQ<10>")
	)
	(segment
		(start 177.586386 -314.192666)
		(end 175.706278 -314.192666)
		(width 0.18288)
		(layer "In11.Cu")
		(net "M_H_CPU1_SA_DQ<10>")
	)
	(segment
		(start 134.594092 -281.106118)
		(end 134.587996 -281.102562)
		(width 0.088646)
		(layer "In11.Cu")
		(net "M_H_CPU1_SA_DQ<10>")
	)
	(segment
		(start 152.180544 -301.323502)
		(end 143.499332 -292.64229)
		(width 0.18288)
		(layer "In11.Cu")
		(net "M_H_CPU1_SA_DQ<10>")
	)
	(segment
		(start 173.93285 -314.37707)
		(end 173.267116 -315.042804)
		(width 0.18288)
		(layer "In11.Cu")
		(net "M_H_CPU1_SA_DQ<10>")
	)
	(segment
		(start 134.587996 -281.102562)
		(end 134.573264 -281.093926)
		(width 0.088646)
		(layer "In11.Cu")
		(net "M_H_CPU1_SA_DQ<10>")
	)
	(segment
		(start 166.76243 -312.793634)
		(end 165.591744 -312.360056)
		(width 0.18288)
		(layer "In11.Cu")
		(net "M_H_CPU1_SA_DQ<10>")
	)
	(segment
		(start 138.656568 -286.370014)
		(end 138.656568 -286.267652)
		(width 0.088646)
		(layer "In11.Cu")
		(net "M_H_CPU1_SA_DQ<10>")
	)
	(segment
		(start 143.499332 -292.64229)
		(end 143.499332 -291.212778)
		(width 0.18288)
		(layer "In11.Cu")
		(net "M_H_CPU1_SA_DQ<10>")
	)
	(segment
		(start 207.071214 -306.116736)
		(end 207.056736 -306.111656)
		(width 0.18288)
		(layer "In11.Cu")
		(net "M_H_CPU1_SA_DQ<10>")
	)
	(segment
		(start 135.340598 -282.414472)
		(end 135.340598 -282.405836)
		(width 0.088646)
		(layer "In11.Cu")
		(net "M_H_CPU1_SA_DQ<10>")
	)
	(segment
		(start 205.09484 -306.705254)
		(end 203.916026 -306.54244)
		(width 0.18288)
		(layer "In11.Cu")
		(net "M_H_CPU1_SA_DQ<10>")
	)
	(segment
		(start 158.248096 -312.360056)
		(end 152.180544 -306.292504)
		(width 0.18288)
		(layer "In11.Cu")
		(net "M_H_CPU1_SA_DQ<10>")
	)
	(segment
		(start 203.916026 -306.54244)
		(end 202.500484 -306.54244)
		(width 0.18288)
		(layer "In11.Cu")
		(net "M_H_CPU1_SA_DQ<10>")
	)
	(segment
		(start 128.949196 -281.102562)
		(end 128.934464 -281.093926)
		(width 0.088646)
		(layer "In11.Cu")
		(net "M_H_CPU1_SA_DQ<10>")
	)
	(segment
		(start 132.708396 -281.102562)
		(end 132.693664 -281.093926)
		(width 0.088646)
		(layer "In11.Cu")
		(net "M_H_CPU1_SA_DQ<10>")
	)
	(segment
		(start 187.30214 -313.165998)
		(end 187.30214 -312.7375)
		(width 0.18288)
		(layer "In11.Cu")
		(net "M_H_CPU1_SA_DQ<10>")
	)
	(segment
		(start 138.159744 -285.661354)
		(end 138.159744 -285.64586)
		(width 0.088646)
		(layer "In11.Cu")
		(net "M_H_CPU1_SA_DQ<10>")
	)
	(segment
		(start 124.72035 -278.66086)
		(end 124.71146 -278.65578)
		(width 0.088646)
		(layer "In11.Cu")
		(net "M_H_CPU1_SA_DQ<10>")
	)
	(segment
		(start 182.263796 -312.549794)
		(end 181.870604 -312.942986)
		(width 0.18288)
		(layer "In11.Cu")
		(net "M_H_CPU1_SA_DQ<10>")
	)
	(segment
		(start 194.597782 -313.529472)
		(end 192.997328 -314.192412)
		(width 0.18288)
		(layer "In11.Cu")
		(net "M_H_CPU1_SA_DQ<10>")
	)
	(segment
		(start 137.219944 -284.033722)
		(end 137.219944 -284.018228)
		(width 0.088646)
		(layer "In11.Cu")
		(net "M_H_CPU1_SA_DQ<10>")
	)
	(segment
		(start 126.599696 -280.288492)
		(end 126.589282 -280.282396)
		(width 0.088646)
		(layer "In11.Cu")
		(net "M_H_CPU1_SA_DQ<10>")
	)
	(segment
		(start 137.407396 -284.35808)
		(end 137.398506 -284.353)
		(width 0.088646)
		(layer "In11.Cu")
		(net "M_H_CPU1_SA_DQ<10>")
	)
	(segment
		(start 187.479686 -313.343544)
		(end 187.30214 -313.165998)
		(width 0.18288)
		(layer "In11.Cu")
		(net "M_H_CPU1_SA_DQ<10>")
	)
	(segment
		(start 138.347196 -285.985712)
		(end 138.338306 -285.980632)
		(width 0.088646)
		(layer "In11.Cu")
		(net "M_H_CPU1_SA_DQ<10>")
	)
	(segment
		(start 181.870604 -312.942986)
		(end 179.262278 -313.440826)
		(width 0.18288)
		(layer "In11.Cu")
		(net "M_H_CPU1_SA_DQ<10>")
	)
	(segment
		(start 189.564772 -313.10199)
		(end 189.323218 -313.343544)
		(width 0.18288)
		(layer "In11.Cu")
		(net "M_H_CPU1_SA_DQ<10>")
	)
	(segment
		(start 191.553846 -314.192412)
		(end 190.463424 -313.10199)
		(width 0.18288)
		(layer "In11.Cu")
		(net "M_H_CPU1_SA_DQ<10>")
	)
	(segment
		(start 202.500484 -306.54244)
		(end 202.198732 -306.844192)
		(width 0.18288)
		(layer "In11.Cu")
		(net "M_H_CPU1_SA_DQ<10>")
	)
	(segment
		(start 128.009396 -281.102562)
		(end 128.000506 -281.097482)
		(width 0.088646)
		(layer "In11.Cu")
		(net "M_H_CPU1_SA_DQ<10>")
	)
	(segment
		(start 165.591744 -312.360056)
		(end 158.248096 -312.360056)
		(width 0.18288)
		(layer "In11.Cu")
		(net "M_H_CPU1_SA_DQ<10>")
	)
	(segment
		(start 172.100494 -315.222636)
		(end 171.3992 -315.222636)
		(width 0.18288)
		(layer "In11.Cu")
		(net "M_H_CPU1_SA_DQ<10>")
	)
	(segment
		(start 131.768596 -281.102562)
		(end 131.753864 -281.093926)
		(width 0.088646)
		(layer "In11.Cu")
		(net "M_H_CPU1_SA_DQ<10>")
	)
	(segment
		(start 124.59462 -276.708616)
		(end 124.907548 -276.708616)
		(width 0.088646)
		(layer "In11.Cu")
		(net "M_H_CPU1_SA_DQ<10>")
	)
	(segment
		(start 124.250196 -277.84679)
		(end 124.241306 -277.84171)
		(width 0.088646)
		(layer "In11.Cu")
		(net "M_H_CPU1_SA_DQ<10>")
	)
	(segment
		(start 179.262278 -313.440826)
		(end 178.338226 -313.440826)
		(width 0.18288)
		(layer "In11.Cu")
		(net "M_H_CPU1_SA_DQ<10>")
	)
	(segment
		(start 207.056736 -306.111656)
		(end 206.752444 -306.25669)
		(width 0.18288)
		(layer "In11.Cu")
		(net "M_H_CPU1_SA_DQ<10>")
	)
	(segment
		(start 125.66015 -280.288492)
		(end 125.65126 -280.283412)
		(width 0.088646)
		(layer "In11.Cu")
		(net "M_H_CPU1_SA_DQ<10>")
	)
	(segment
		(start 169.552366 -313.826398)
		(end 166.763192 -312.79338)
		(width 0.18288)
		(layer "In11.Cu")
		(net "M_H_CPU1_SA_DQ<10>")
	)
	(segment
		(start 194.878198 -313.342274)
		(end 194.597782 -313.529472)
		(width 0.18288)
		(layer "In11.Cu")
		(net "M_H_CPU1_SA_DQ<10>")
	)
	(segment
		(start 133.648196 -281.102562)
		(end 133.633464 -281.093926)
		(width 0.088646)
		(layer "In11.Cu")
		(net "M_H_CPU1_SA_DQ<10>")
	)
	(segment
		(start 125.196092 -279.478232)
		(end 125.189996 -279.474676)
		(width 0.088646)
		(layer "In11.Cu")
		(net "M_H_CPU1_SA_DQ<10>")
	)
	(segment
		(start 136.93775 -283.544264)
		(end 136.92886 -283.539184)
		(width 0.088646)
		(layer "In11.Cu")
		(net "M_H_CPU1_SA_DQ<10>")
	)
	(segment
		(start 189.323218 -313.343544)
		(end 187.479686 -313.343544)
		(width 0.18288)
		(layer "In11.Cu")
		(net "M_H_CPU1_SA_DQ<10>")
	)
	(segment
		(start 124.241306 -277.203154)
		(end 124.250196 -277.198074)
		(width 0.088646)
		(layer "In11.Cu")
		(net "M_H_CPU1_SA_DQ<10>")
	)
	(segment
		(start 186.860942 -312.297318)
		(end 184.358026 -312.297318)
		(width 0.18288)
		(layer "In11.Cu")
		(net "M_H_CPU1_SA_DQ<10>")
	)
	(segment
		(start 129.888996 -281.102562)
		(end 129.874264 -281.093926)
		(width 0.088646)
		(layer "In11.Cu")
		(net "M_H_CPU1_SA_DQ<10>")
	)
	(segment
		(start 125.002544 -279.150318)
		(end 125.002544 -279.134824)
		(width 0.088646)
		(layer "In11.Cu")
		(net "M_H_CPU1_SA_DQ<10>")
	)
	(segment
		(start 166.763192 -312.79338)
		(end 166.76243 -312.793634)
		(width 0.18288)
		(layer "In11.Cu")
		(net "M_H_CPU1_SA_DQ<10>")
	)
	(segment
		(start 137.413492 -284.361636)
		(end 137.407396 -284.35808)
		(width 0.088646)
		(layer "In11.Cu")
		(net "M_H_CPU1_SA_DQ<10>")
	)
	(segment
		(start 136.750298 -283.219906)
		(end 136.750298 -283.212286)
		(width 0.088646)
		(layer "In11.Cu")
		(net "M_H_CPU1_SA_DQ<10>")
	)
	(segment
		(start 130.828796 -281.102562)
		(end 130.814064 -281.093926)
		(width 0.088646)
		(layer "In11.Cu")
		(net "M_H_CPU1_SA_DQ<10>")
	)
	(segment
		(start 134.870698 -281.600656)
		(end 134.870698 -281.59202)
		(width 0.088646)
		(layer "In11.Cu")
		(net "M_H_CPU1_SA_DQ<10>")
	)
	(segment
		(start 175.521874 -314.37707)
		(end 173.93285 -314.37707)
		(width 0.18288)
		(layer "In11.Cu")
		(net "M_H_CPU1_SA_DQ<10>")
	)
	(segment
		(start 137.87755 -285.171896)
		(end 137.86866 -285.166816)
		(width 0.088646)
		(layer "In11.Cu")
		(net "M_H_CPU1_SA_DQ<10>")
	)
	(segment
		(start 171.3992 -315.222636)
		(end 169.552366 -313.826398)
		(width 0.18288)
		(layer "In11.Cu")
		(net "M_H_CPU1_SA_DQ<10>")
	)
	(segment
		(start 202.198732 -306.844192)
		(end 202.198732 -307.239924)
		(width 0.18288)
		(layer "In11.Cu")
		(net "M_H_CPU1_SA_DQ<10>")
	)
	(segment
		(start 135.063992 -281.919934)
		(end 135.057896 -281.916378)
		(width 0.088646)
		(layer "In11.Cu")
		(net "M_H_CPU1_SA_DQ<10>")
	)
	(segment
		(start 198.273924 -310.998108)
		(end 198.035418 -311.573926)
		(width 0.18288)
		(layer "In11.Cu")
		(net "M_H_CPU1_SA_DQ<10>")
	)
	(segment
		(start 192.997328 -314.192412)
		(end 191.553846 -314.192412)
		(width 0.18288)
		(layer "In11.Cu")
		(net "M_H_CPU1_SA_DQ<10>")
	)
	(segment
		(start 199.514206 -309.757826)
		(end 198.273924 -310.998108)
		(width 0.18288)
		(layer "In11.Cu")
		(net "M_H_CPU1_SA_DQ<10>")
	)
	(segment
		(start 190.463424 -313.10199)
		(end 189.564772 -313.10199)
		(width 0.18288)
		(layer "In11.Cu")
		(net "M_H_CPU1_SA_DQ<10>")
	)
	(segment
		(start 125.189996 -279.474676)
		(end 125.181106 -279.469596)
		(width 0.088646)
		(layer "In11.Cu")
		(net "M_H_CPU1_SA_DQ<10>")
	)
	(segment
		(start 124.25299 -277.19655)
		(end 124.256292 -277.194518)
		(width 0.088646)
		(layer "In11.Cu")
		(net "M_H_CPU1_SA_DQ<10>")
	)
	(segment
		(start 138.656568 -286.267652)
		(end 138.464544 -286.075628)
		(width 0.088646)
		(layer "In11.Cu")
		(net "M_H_CPU1_SA_DQ<10>")
	)
	(segment
		(start 124.529088 -276.774148)
		(end 124.59462 -276.708616)
		(width 0.088646)
		(layer "In11.Cu")
		(net "M_H_CPU1_SA_DQ<10>")
	)
	(segment
		(start 187.30214 -312.7375)
		(end 186.862212 -312.297572)
		(width 0.18288)
		(layer "In11.Cu")
		(net "M_H_CPU1_SA_DQ<10>")
	)
	(segment
		(start 175.706278 -314.192666)
		(end 175.521874 -314.37707)
		(width 0.18288)
		(layer "In11.Cu")
		(net "M_H_CPU1_SA_DQ<10>")
	)
	(segment
		(start 197.861936 -311.747408)
		(end 194.878198 -313.342274)
		(width 0.18288)
		(layer "In11.Cu")
		(net "M_H_CPU1_SA_DQ<10>")
	)
	(arc
		(start 137.398506 -284.353)
		(mid 137.267592 -284.21664)
		(end 137.219944 -284.033722)
		(width 0.088646)
		(layer "In11.Cu")
		(net "M_H_CPU1_SA_DQ<10>")
	)
	(arc
		(start 131.203192 -281.102562)
		(mid 131.015994 -281.152705)
		(end 130.828796 -281.102562)
		(width 0.088646)
		(layer "In11.Cu")
		(net "M_H_CPU1_SA_DQ<10>")
	)
	(arc
		(start 136.750298 -283.212286)
		(mid 136.672669 -282.933873)
		(end 136.467596 -282.730194)
		(width 0.088646)
		(layer "In11.Cu")
		(net "M_H_CPU1_SA_DQ<10>")
	)
	(arc
		(start 133.633464 -281.093926)
		(mid 133.356989 -281.026606)
		(end 133.082792 -281.102562)
		(width 0.088646)
		(layer "In11.Cu")
		(net "M_H_CPU1_SA_DQ<10>")
	)
	(arc
		(start 130.814064 -281.093926)
		(mid 130.537589 -281.026606)
		(end 130.263392 -281.102562)
		(width 0.088646)
		(layer "In11.Cu")
		(net "M_H_CPU1_SA_DQ<10>")
	)
	(arc
		(start 138.159744 -285.64586)
		(mid 138.080374 -285.372126)
		(end 137.87755 -285.171896)
		(width 0.088646)
		(layer "In11.Cu")
		(net "M_H_CPU1_SA_DQ<10>")
	)
	(arc
		(start 133.082792 -281.102562)
		(mid 132.895594 -281.152705)
		(end 132.708396 -281.102562)
		(width 0.088646)
		(layer "In11.Cu")
		(net "M_H_CPU1_SA_DQ<10>")
	)
	(arc
		(start 134.870698 -281.59202)
		(mid 134.796707 -281.312454)
		(end 134.594092 -281.106118)
		(width 0.088646)
		(layer "In11.Cu")
		(net "M_H_CPU1_SA_DQ<10>")
	)
	(arc
		(start 125.472698 -279.964134)
		(mid 125.398707 -279.684568)
		(end 125.196092 -279.478232)
		(width 0.088646)
		(layer "In11.Cu")
		(net "M_H_CPU1_SA_DQ<10>")
	)
	(arc
		(start 134.573264 -281.093926)
		(mid 134.296789 -281.026606)
		(end 134.022592 -281.102562)
		(width 0.088646)
		(layer "In11.Cu")
		(net "M_H_CPU1_SA_DQ<10>")
	)
	(arc
		(start 138.464544 -286.075628)
		(mid 138.408815 -286.026828)
		(end 138.347196 -285.985712)
		(width 0.088646)
		(layer "In11.Cu")
		(net "M_H_CPU1_SA_DQ<10>")
	)
	(arc
		(start 124.241306 -277.84171)
		(mid 124.062709 -277.522432)
		(end 124.241306 -277.203154)
		(width 0.088646)
		(layer "In11.Cu")
		(net "M_H_CPU1_SA_DQ<10>")
	)
	(arc
		(start 134.022592 -281.102562)
		(mid 133.835394 -281.152705)
		(end 133.648196 -281.102562)
		(width 0.088646)
		(layer "In11.Cu")
		(net "M_H_CPU1_SA_DQ<10>")
	)
	(arc
		(start 137.690098 -284.847538)
		(mid 137.616107 -284.567972)
		(end 137.413492 -284.361636)
		(width 0.088646)
		(layer "In11.Cu")
		(net "M_H_CPU1_SA_DQ<10>")
	)
	(arc
		(start 124.256292 -277.194518)
		(mid 124.441815 -277.016217)
		(end 124.529088 -276.774148)
		(width 0.088646)
		(layer "In11.Cu")
		(net "M_H_CPU1_SA_DQ<10>")
	)
	(arc
		(start 131.753864 -281.093926)
		(mid 131.477389 -281.026606)
		(end 131.203192 -281.102562)
		(width 0.088646)
		(layer "In11.Cu")
		(net "M_H_CPU1_SA_DQ<10>")
	)
	(arc
		(start 126.974092 -280.288492)
		(mid 126.786894 -280.338635)
		(end 126.599696 -280.288492)
		(width 0.088646)
		(layer "In11.Cu")
		(net "M_H_CPU1_SA_DQ<10>")
	)
	(arc
		(start 132.693664 -281.093926)
		(mid 132.417189 -281.026606)
		(end 132.142992 -281.102562)
		(width 0.088646)
		(layer "In11.Cu")
		(net "M_H_CPU1_SA_DQ<10>")
	)
	(arc
		(start 132.142992 -281.102562)
		(mid 131.955794 -281.152705)
		(end 131.768596 -281.102562)
		(width 0.088646)
		(layer "In11.Cu")
		(net "M_H_CPU1_SA_DQ<10>")
	)
	(arc
		(start 127.53975 -280.288492)
		(mid 127.262937 -280.212656)
		(end 126.984506 -280.282396)
		(width 0.088646)
		(layer "In11.Cu")
		(net "M_H_CPU1_SA_DQ<10>")
	)
	(arc
		(start 135.902192 -282.730194)
		(mid 135.714994 -282.780337)
		(end 135.527796 -282.730194)
		(width 0.088646)
		(layer "In11.Cu")
		(net "M_H_CPU1_SA_DQ<10>")
	)
	(arc
		(start 125.002544 -279.134824)
		(mid 124.923174 -278.86109)
		(end 124.72035 -278.66086)
		(width 0.088646)
		(layer "In11.Cu")
		(net "M_H_CPU1_SA_DQ<10>")
	)
	(arc
		(start 135.057896 -281.916378)
		(mid 134.922963 -281.783024)
		(end 134.870698 -281.600656)
		(width 0.088646)
		(layer "In11.Cu")
		(net "M_H_CPU1_SA_DQ<10>")
	)
	(arc
		(start 130.263392 -281.102562)
		(mid 130.076194 -281.152705)
		(end 129.888996 -281.102562)
		(width 0.088646)
		(layer "In11.Cu")
		(net "M_H_CPU1_SA_DQ<10>")
	)
	(arc
		(start 135.527796 -282.730194)
		(mid 135.392863 -282.59684)
		(end 135.340598 -282.414472)
		(width 0.088646)
		(layer "In11.Cu")
		(net "M_H_CPU1_SA_DQ<10>")
	)
	(arc
		(start 129.874264 -281.093926)
		(mid 129.597789 -281.026606)
		(end 129.323592 -281.102562)
		(width 0.088646)
		(layer "In11.Cu")
		(net "M_H_CPU1_SA_DQ<10>")
	)
	(arc
		(start 137.86866 -285.166816)
		(mid 137.737746 -285.030456)
		(end 137.690098 -284.847538)
		(width 0.088646)
		(layer "In11.Cu")
		(net "M_H_CPU1_SA_DQ<10>")
	)
	(arc
		(start 126.589282 -280.282396)
		(mid 126.311104 -280.212704)
		(end 126.034546 -280.288492)
		(width 0.088646)
		(layer "In11.Cu")
		(net "M_H_CPU1_SA_DQ<10>")
	)
	(arc
		(start 137.219944 -284.018228)
		(mid 137.140574 -283.744494)
		(end 136.93775 -283.544264)
		(width 0.088646)
		(layer "In11.Cu")
		(net "M_H_CPU1_SA_DQ<10>")
	)
	(arc
		(start 136.92886 -283.539184)
		(mid 136.797946 -283.402824)
		(end 136.750298 -283.219906)
		(width 0.088646)
		(layer "In11.Cu")
		(net "M_H_CPU1_SA_DQ<10>")
	)
	(arc
		(start 138.338306 -285.980632)
		(mid 138.207392 -285.844272)
		(end 138.159744 -285.661354)
		(width 0.088646)
		(layer "In11.Cu")
		(net "M_H_CPU1_SA_DQ<10>")
	)
	(arc
		(start 125.65126 -280.283412)
		(mid 125.520346 -280.147052)
		(end 125.472698 -279.964134)
		(width 0.088646)
		(layer "In11.Cu")
		(net "M_H_CPU1_SA_DQ<10>")
	)
	(arc
		(start 128.000506 -281.097482)
		(mid 127.869592 -280.961122)
		(end 127.821944 -280.778204)
		(width 0.088646)
		(layer "In11.Cu")
		(net "M_H_CPU1_SA_DQ<10>")
	)
	(arc
		(start 127.821944 -280.756106)
		(mid 127.741033 -280.485978)
		(end 127.53975 -280.288492)
		(width 0.088646)
		(layer "In11.Cu")
		(net "M_H_CPU1_SA_DQ<10>")
	)
	(arc
		(start 135.340598 -282.405836)
		(mid 135.266607 -282.12627)
		(end 135.063992 -281.919934)
		(width 0.088646)
		(layer "In11.Cu")
		(net "M_H_CPU1_SA_DQ<10>")
	)
	(arc
		(start 126.034546 -280.288492)
		(mid 125.847348 -280.338635)
		(end 125.66015 -280.288492)
		(width 0.088646)
		(layer "In11.Cu")
		(net "M_H_CPU1_SA_DQ<10>")
	)
	(arc
		(start 124.532898 -278.322278)
		(mid 124.453679 -278.047593)
		(end 124.250196 -277.84679)
		(width 0.088646)
		(layer "In11.Cu")
		(net "M_H_CPU1_SA_DQ<10>")
	)
	(arc
		(start 125.181106 -279.469596)
		(mid 125.050192 -279.333236)
		(end 125.002544 -279.150318)
		(width 0.088646)
		(layer "In11.Cu")
		(net "M_H_CPU1_SA_DQ<10>")
	)
	(arc
		(start 128.934464 -281.093926)
		(mid 128.657989 -281.026606)
		(end 128.383792 -281.102562)
		(width 0.088646)
		(layer "In11.Cu")
		(net "M_H_CPU1_SA_DQ<10>")
	)
	(arc
		(start 136.467596 -282.730194)
		(mid 136.184894 -282.654452)
		(end 135.902192 -282.730194)
		(width 0.088646)
		(layer "In11.Cu")
		(net "M_H_CPU1_SA_DQ<10>")
	)
	(arc
		(start 128.383792 -281.102562)
		(mid 128.196594 -281.152705)
		(end 128.009396 -281.102562)
		(width 0.088646)
		(layer "In11.Cu")
		(net "M_H_CPU1_SA_DQ<10>")
	)
	(arc
		(start 124.71146 -278.65578)
		(mid 124.580546 -278.51942)
		(end 124.532898 -278.336502)
		(width 0.088646)
		(layer "In11.Cu")
		(net "M_H_CPU1_SA_DQ<10>")
	)
	(arc
		(start 129.323592 -281.102562)
		(mid 129.136394 -281.152705)
		(end 128.949196 -281.102562)
		(width 0.088646)
		(layer "In11.Cu")
		(net "M_H_CPU1_SA_DQ<10>")
	)
	(segment
		(start 207.018382 -315.891672)
		(end 206.971392 -315.891672)
		(width 0.101854)
		(layer "F.Cu")
		(net "M_H_CPU1_SA_DQ<0>")
	)
	(segment
		(start 206.508604 -316.009782)
		(end 206.508604 -316.37732)
		(width 0.20066)
		(layer "F.Cu")
		(net "M_H_CPU1_SA_DQ<0>")
	)
	(segment
		(start 209.596482 -315.885322)
		(end 209.186526 -315.885322)
		(width 0.20066)
		(layer "F.Cu")
		(net "M_H_CPU1_SA_DQ<0>")
	)
	(segment
		(start 209.186526 -315.885322)
		(end 209.180176 -315.891672)
		(width 0.1016)
		(layer "F.Cu")
		(net "M_H_CPU1_SA_DQ<0>")
	)
	(segment
		(start 205.84541 -316.56528)
		(end 205.596744 -316.316614)
		(width 0.20066)
		(layer "F.Cu")
		(net "M_H_CPU1_SA_DQ<0>")
	)
	(segment
		(start 211.619592 -316.316868)
		(end 210.028028 -316.316868)
		(width 0.20066)
		(layer "F.Cu")
		(net "M_H_CPU1_SA_DQ<0>")
	)
	(segment
		(start 210.028028 -316.316868)
		(end 209.596482 -315.885322)
		(width 0.20066)
		(layer "F.Cu")
		(net "M_H_CPU1_SA_DQ<0>")
	)
	(segment
		(start 206.320644 -316.56528)
		(end 205.84541 -316.56528)
		(width 0.20066)
		(layer "F.Cu")
		(net "M_H_CPU1_SA_DQ<0>")
	)
	(segment
		(start 206.626714 -315.891672)
		(end 206.508604 -316.009782)
		(width 0.20066)
		(layer "F.Cu")
		(net "M_H_CPU1_SA_DQ<0>")
	)
	(segment
		(start 205.596744 -316.316614)
		(end 204.076046 -316.316614)
		(width 0.20066)
		(layer "F.Cu")
		(net "M_H_CPU1_SA_DQ<0>")
	)
	(segment
		(start 206.508604 -316.37732)
		(end 206.320644 -316.56528)
		(width 0.20066)
		(layer "F.Cu")
		(net "M_H_CPU1_SA_DQ<0>")
	)
	(segment
		(start 131.485894 -279.428194)
		(end 131.485894 -279.96388)
		(width 0.20066)
		(layer "F.Cu")
		(net "M_H_CPU1_SA_DQ<0>")
	)
	(segment
		(start 204.076046 -316.316614)
		(end 202.971146 -316.316614)
		(width 0.20066)
		(layer "F.Cu")
		(net "M_H_CPU1_SA_DQ<0>")
	)
	(segment
		(start 209.180176 -315.891672)
		(end 207.018382 -315.891672)
		(width 0.1016)
		(layer "F.Cu")
		(net "M_H_CPU1_SA_DQ<0>")
	)
	(segment
		(start 206.971392 -315.891672)
		(end 206.626714 -315.891672)
		(width 0.20066)
		(layer "F.Cu")
		(net "M_H_CPU1_SA_DQ<0>")
	)
	(segment
		(start 131.485894 -279.96388)
		(end 131.486148 -279.964134)
		(width 0.20066)
		(layer "F.Cu")
		(net "M_H_CPU1_SA_DQ<0>")
	)
	(segment
		(start 211.619846 -316.316614)
		(end 211.619592 -316.316868)
		(width 0.20066)
		(layer "F.Cu")
		(net "M_H_CPU1_SA_DQ<0>")
	)
	(segment
		(start 166.159942 -313.84494)
		(end 165.977062 -313.66206)
		(width 0.18288)
		(layer "In6.Cu")
		(net "M_H_CPU1_SA_DQ<0>")
	)
	(segment
		(start 196.928486 -317.925958)
		(end 196.600826 -317.925958)
		(width 0.18288)
		(layer "In6.Cu")
		(net "M_H_CPU1_SA_DQ<0>")
	)
	(segment
		(start 192.98539 -317.45555)
		(end 192.98539 -316.95136)
		(width 0.18288)
		(layer "In6.Cu")
		(net "M_H_CPU1_SA_DQ<0>")
	)
	(segment
		(start 166.853362 -312.662824)
		(end 166.670482 -312.845704)
		(width 0.18288)
		(layer "In6.Cu")
		(net "M_H_CPU1_SA_DQ<0>")
	)
	(segment
		(start 166.670482 -312.845704)
		(end 166.670482 -313.66206)
		(width 0.18288)
		(layer "In6.Cu")
		(net "M_H_CPU1_SA_DQ<0>")
	)
	(segment
		(start 163.01593 -310.86933)
		(end 160.635188 -310.86933)
		(width 0.18288)
		(layer "In6.Cu")
		(net "M_H_CPU1_SA_DQ<0>")
	)
	(segment
		(start 153.6954 -301.957232)
		(end 145.862802 -294.124634)
		(width 0.18288)
		(layer "In6.Cu")
		(net "M_H_CPU1_SA_DQ<0>")
	)
	(segment
		(start 136.380982 -279.644856)
		(end 136.372092 -279.639776)
		(width 0.088646)
		(layer "In6.Cu")
		(net "M_H_CPU1_SA_DQ<0>")
	)
	(segment
		(start 183.671972 -315.820552)
		(end 182.765446 -314.914026)
		(width 0.18288)
		(layer "In6.Cu")
		(net "M_H_CPU1_SA_DQ<0>")
	)
	(segment
		(start 139.498832 -283.132022)
		(end 139.41933 -283.05252)
		(width 0.18288)
		(layer "In6.Cu")
		(net "M_H_CPU1_SA_DQ<0>")
	)
	(segment
		(start 169.90949 -314.192412)
		(end 169.514012 -314.192412)
		(width 0.18288)
		(layer "In6.Cu")
		(net "M_H_CPU1_SA_DQ<0>")
	)
	(segment
		(start 187.187078 -317.24219)
		(end 186.12231 -317.24219)
		(width 0.18288)
		(layer "In6.Cu")
		(net "M_H_CPU1_SA_DQ<0>")
	)
	(segment
		(start 191.609218 -316.742318)
		(end 191.312038 -316.445138)
		(width 0.18288)
		(layer "In6.Cu")
		(net "M_H_CPU1_SA_DQ<0>")
	)
	(segment
		(start 170.78579 -314.375292)
		(end 170.78579 -314.936632)
		(width 0.18288)
		(layer "In6.Cu")
		(net "M_H_CPU1_SA_DQ<0>")
	)
	(segment
		(start 157.353508 -310.383936)
		(end 153.6954 -306.725828)
		(width 0.18288)
		(layer "In6.Cu")
		(net "M_H_CPU1_SA_DQ<0>")
	)
	(segment
		(start 193.213736 -317.683896)
		(end 192.98539 -317.45555)
		(width 0.18288)
		(layer "In6.Cu")
		(net "M_H_CPU1_SA_DQ<0>")
	)
	(segment
		(start 153.6954 -306.725828)
		(end 153.6954 -301.957232)
		(width 0.18288)
		(layer "In6.Cu")
		(net "M_H_CPU1_SA_DQ<0>")
	)
	(segment
		(start 200.773538 -316.742318)
		(end 199.834246 -315.803026)
		(width 0.18288)
		(layer "In6.Cu")
		(net "M_H_CPU1_SA_DQ<0>")
	)
	(segment
		(start 186.12231 -317.24219)
		(end 184.881266 -316.001146)
		(width 0.18288)
		(layer "In6.Cu")
		(net "M_H_CPU1_SA_DQ<0>")
	)
	(segment
		(start 202.971146 -316.316614)
		(end 202.545442 -316.742318)
		(width 0.18288)
		(layer "In6.Cu")
		(net "M_H_CPU1_SA_DQ<0>")
	)
	(segment
		(start 177.903886 -314.047886)
		(end 177.194718 -313.338718)
		(width 0.18288)
		(layer "In6.Cu")
		(net "M_H_CPU1_SA_DQ<0>")
	)
	(segment
		(start 197.111366 -316.590426)
		(end 197.111366 -317.743078)
		(width 0.18288)
		(layer "In6.Cu")
		(net "M_H_CPU1_SA_DQ<0>")
	)
	(segment
		(start 160.635188 -310.86933)
		(end 160.149794 -310.383936)
		(width 0.18288)
		(layer "In6.Cu")
		(net "M_H_CPU1_SA_DQ<0>")
	)
	(segment
		(start 194.192144 -316.742318)
		(end 193.93408 -317.000382)
		(width 0.18288)
		(layer "In6.Cu")
		(net "M_H_CPU1_SA_DQ<0>")
	)
	(segment
		(start 193.93408 -317.485268)
		(end 193.735452 -317.683896)
		(width 0.18288)
		(layer "In6.Cu")
		(net "M_H_CPU1_SA_DQ<0>")
	)
	(segment
		(start 136.559544 -279.982676)
		(end 136.559544 -279.964134)
		(width 0.088646)
		(layer "In6.Cu")
		(net "M_H_CPU1_SA_DQ<0>")
	)
	(segment
		(start 196.235066 -316.407546)
		(end 194.980052 -316.407546)
		(width 0.18288)
		(layer "In6.Cu")
		(net "M_H_CPU1_SA_DQ<0>")
	)
	(segment
		(start 180.078126 -314.914026)
		(end 179.388516 -314.224416)
		(width 0.18288)
		(layer "In6.Cu")
		(net "M_H_CPU1_SA_DQ<0>")
	)
	(segment
		(start 187.569602 -317.624714)
		(end 187.187078 -317.24219)
		(width 0.18288)
		(layer "In6.Cu")
		(net "M_H_CPU1_SA_DQ<0>")
	)
	(segment
		(start 131.350766 -279.615138)
		(end 131.329684 -279.693116)
		(width 0.088646)
		(layer "In6.Cu")
		(net "M_H_CPU1_SA_DQ<0>")
	)
	(segment
		(start 177.194718 -313.338718)
		(end 174.693072 -313.338718)
		(width 0.18288)
		(layer "In6.Cu")
		(net "M_H_CPU1_SA_DQ<0>")
	)
	(segment
		(start 196.417946 -316.590426)
		(end 196.235066 -316.407546)
		(width 0.18288)
		(layer "In6.Cu")
		(net "M_H_CPU1_SA_DQ<0>")
	)
	(segment
		(start 193.93408 -317.000382)
		(end 193.93408 -317.485268)
		(width 0.18288)
		(layer "In6.Cu")
		(net "M_H_CPU1_SA_DQ<0>")
	)
	(segment
		(start 165.977062 -312.845704)
		(end 165.794182 -312.662824)
		(width 0.18288)
		(layer "In6.Cu")
		(net "M_H_CPU1_SA_DQ<0>")
	)
	(segment
		(start 192.776348 -316.742318)
		(end 191.609218 -316.742318)
		(width 0.18288)
		(layer "In6.Cu")
		(net "M_H_CPU1_SA_DQ<0>")
	)
	(segment
		(start 188.972698 -317.624714)
		(end 187.569602 -317.624714)
		(width 0.18288)
		(layer "In6.Cu")
		(net "M_H_CPU1_SA_DQ<0>")
	)
	(segment
		(start 170.96867 -314.192412)
		(end 170.78579 -314.375292)
		(width 0.18288)
		(layer "In6.Cu")
		(net "M_H_CPU1_SA_DQ<0>")
	)
	(segment
		(start 131.329684 -279.693116)
		(end 131.486148 -279.964134)
		(width 0.088646)
		(layer "In6.Cu")
		(net "M_H_CPU1_SA_DQ<0>")
	)
	(segment
		(start 192.98539 -316.95136)
		(end 192.776348 -316.742318)
		(width 0.18288)
		(layer "In6.Cu")
		(net "M_H_CPU1_SA_DQ<0>")
	)
	(segment
		(start 197.111366 -317.743078)
		(end 196.928486 -317.925958)
		(width 0.18288)
		(layer "In6.Cu")
		(net "M_H_CPU1_SA_DQ<0>")
	)
	(segment
		(start 199.834246 -315.803026)
		(end 199.173084 -315.803026)
		(width 0.18288)
		(layer "In6.Cu")
		(net "M_H_CPU1_SA_DQ<0>")
	)
	(segment
		(start 164.809424 -312.662824)
		(end 163.01593 -310.86933)
		(width 0.18288)
		(layer "In6.Cu")
		(net "M_H_CPU1_SA_DQ<0>")
	)
	(segment
		(start 197.294246 -316.407546)
		(end 197.111366 -316.590426)
		(width 0.18288)
		(layer "In6.Cu")
		(net "M_H_CPU1_SA_DQ<0>")
	)
	(segment
		(start 139.199112 -282.832302)
		(end 139.199112 -281.904694)
		(width 0.088646)
		(layer "In6.Cu")
		(net "M_H_CPU1_SA_DQ<0>")
	)
	(segment
		(start 136.850882 -280.458926)
		(end 136.841992 -280.453846)
		(width 0.088646)
		(layer "In6.Cu")
		(net "M_H_CPU1_SA_DQ<0>")
	)
	(segment
		(start 184.881266 -316.001146)
		(end 184.482994 -315.820552)
		(width 0.18288)
		(layer "In6.Cu")
		(net "M_H_CPU1_SA_DQ<0>")
	)
	(segment
		(start 170.09237 -314.936632)
		(end 170.09237 -314.375292)
		(width 0.18288)
		(layer "In6.Cu")
		(net "M_H_CPU1_SA_DQ<0>")
	)
	(segment
		(start 132.238496 -279.639776)
		(end 132.228082 -279.645872)
		(width 0.088646)
		(layer "In6.Cu")
		(net "M_H_CPU1_SA_DQ<0>")
	)
	(segment
		(start 179.388516 -314.224416)
		(end 179.021486 -314.047886)
		(width 0.18288)
		(layer "In6.Cu")
		(net "M_H_CPU1_SA_DQ<0>")
	)
	(segment
		(start 166.670482 -313.66206)
		(end 166.487602 -313.84494)
		(width 0.18288)
		(layer "In6.Cu")
		(net "M_H_CPU1_SA_DQ<0>")
	)
	(segment
		(start 135.997696 -279.639776)
		(end 135.987282 -279.645872)
		(width 0.088646)
		(layer "In6.Cu")
		(net "M_H_CPU1_SA_DQ<0>")
	)
	(segment
		(start 196.600826 -317.925958)
		(end 196.417946 -317.743078)
		(width 0.18288)
		(layer "In6.Cu")
		(net "M_H_CPU1_SA_DQ<0>")
	)
	(segment
		(start 190.152274 -316.445138)
		(end 188.972698 -317.624714)
		(width 0.18288)
		(layer "In6.Cu")
		(net "M_H_CPU1_SA_DQ<0>")
	)
	(segment
		(start 179.021486 -314.047886)
		(end 177.903886 -314.047886)
		(width 0.18288)
		(layer "In6.Cu")
		(net "M_H_CPU1_SA_DQ<0>")
	)
	(segment
		(start 133.17855 -279.639776)
		(end 133.168136 -279.645872)
		(width 0.088646)
		(layer "In6.Cu")
		(net "M_H_CPU1_SA_DQ<0>")
	)
	(segment
		(start 166.487602 -313.84494)
		(end 166.159942 -313.84494)
		(width 0.18288)
		(layer "In6.Cu")
		(net "M_H_CPU1_SA_DQ<0>")
	)
	(segment
		(start 137.029444 -280.78811)
		(end 137.029444 -280.778204)
		(width 0.088646)
		(layer "In6.Cu")
		(net "M_H_CPU1_SA_DQ<0>")
	)
	(segment
		(start 169.514012 -314.192412)
		(end 167.984424 -312.662824)
		(width 0.18288)
		(layer "In6.Cu")
		(net "M_H_CPU1_SA_DQ<0>")
	)
	(segment
		(start 165.794182 -312.662824)
		(end 164.809424 -312.662824)
		(width 0.18288)
		(layer "In6.Cu")
		(net "M_H_CPU1_SA_DQ<0>")
	)
	(segment
		(start 196.417946 -317.743078)
		(end 196.417946 -316.590426)
		(width 0.18288)
		(layer "In6.Cu")
		(net "M_H_CPU1_SA_DQ<0>")
	)
	(segment
		(start 174.693072 -313.338718)
		(end 173.839378 -314.192412)
		(width 0.18288)
		(layer "In6.Cu")
		(net "M_H_CPU1_SA_DQ<0>")
	)
	(segment
		(start 173.839378 -314.192412)
		(end 170.96867 -314.192412)
		(width 0.18288)
		(layer "In6.Cu")
		(net "M_H_CPU1_SA_DQ<0>")
	)
	(segment
		(start 184.482994 -315.820552)
		(end 183.671972 -315.820552)
		(width 0.18288)
		(layer "In6.Cu")
		(net "M_H_CPU1_SA_DQ<0>")
	)
	(segment
		(start 191.312038 -316.445138)
		(end 190.152274 -316.445138)
		(width 0.18288)
		(layer "In6.Cu")
		(net "M_H_CPU1_SA_DQ<0>")
	)
	(segment
		(start 194.980052 -316.407546)
		(end 194.64528 -316.742318)
		(width 0.18288)
		(layer "In6.Cu")
		(net "M_H_CPU1_SA_DQ<0>")
	)
	(segment
		(start 202.545442 -316.742318)
		(end 200.773538 -316.742318)
		(width 0.18288)
		(layer "In6.Cu")
		(net "M_H_CPU1_SA_DQ<0>")
	)
	(segment
		(start 167.984424 -312.662824)
		(end 166.853362 -312.662824)
		(width 0.18288)
		(layer "In6.Cu")
		(net "M_H_CPU1_SA_DQ<0>")
	)
	(segment
		(start 145.862802 -284.727396)
		(end 144.267428 -283.132022)
		(width 0.18288)
		(layer "In6.Cu")
		(net "M_H_CPU1_SA_DQ<0>")
	)
	(segment
		(start 194.64528 -316.742318)
		(end 194.192144 -316.742318)
		(width 0.18288)
		(layer "In6.Cu")
		(net "M_H_CPU1_SA_DQ<0>")
	)
	(segment
		(start 139.41933 -283.05252)
		(end 139.199112 -282.832302)
		(width 0.088646)
		(layer "In6.Cu")
		(net "M_H_CPU1_SA_DQ<0>")
	)
	(segment
		(start 145.862802 -294.124634)
		(end 145.862802 -284.727396)
		(width 0.18288)
		(layer "In6.Cu")
		(net "M_H_CPU1_SA_DQ<0>")
	)
	(segment
		(start 144.267428 -283.132022)
		(end 139.498832 -283.132022)
		(width 0.18288)
		(layer "In6.Cu")
		(net "M_H_CPU1_SA_DQ<0>")
	)
	(segment
		(start 182.765446 -314.914026)
		(end 180.078126 -314.914026)
		(width 0.18288)
		(layer "In6.Cu")
		(net "M_H_CPU1_SA_DQ<0>")
	)
	(segment
		(start 165.977062 -313.66206)
		(end 165.977062 -312.845704)
		(width 0.18288)
		(layer "In6.Cu")
		(net "M_H_CPU1_SA_DQ<0>")
	)
	(segment
		(start 160.149794 -310.383936)
		(end 157.353508 -310.383936)
		(width 0.18288)
		(layer "In6.Cu")
		(net "M_H_CPU1_SA_DQ<0>")
	)
	(segment
		(start 170.27525 -315.119512)
		(end 170.09237 -314.936632)
		(width 0.18288)
		(layer "In6.Cu")
		(net "M_H_CPU1_SA_DQ<0>")
	)
	(segment
		(start 170.60291 -315.119512)
		(end 170.27525 -315.119512)
		(width 0.18288)
		(layer "In6.Cu")
		(net "M_H_CPU1_SA_DQ<0>")
	)
	(segment
		(start 133.567678 -279.648412)
		(end 133.552946 -279.639776)
		(width 0.088646)
		(layer "In6.Cu")
		(net "M_H_CPU1_SA_DQ<0>")
	)
	(segment
		(start 170.78579 -314.936632)
		(end 170.60291 -315.119512)
		(width 0.18288)
		(layer "In6.Cu")
		(net "M_H_CPU1_SA_DQ<0>")
	)
	(segment
		(start 199.173084 -315.803026)
		(end 198.568564 -316.407546)
		(width 0.18288)
		(layer "In6.Cu")
		(net "M_H_CPU1_SA_DQ<0>")
	)
	(segment
		(start 193.735452 -317.683896)
		(end 193.213736 -317.683896)
		(width 0.18288)
		(layer "In6.Cu")
		(net "M_H_CPU1_SA_DQ<0>")
	)
	(segment
		(start 198.568564 -316.407546)
		(end 197.294246 -316.407546)
		(width 0.18288)
		(layer "In6.Cu")
		(net "M_H_CPU1_SA_DQ<0>")
	)
	(segment
		(start 170.09237 -314.375292)
		(end 169.90949 -314.192412)
		(width 0.18288)
		(layer "In6.Cu")
		(net "M_H_CPU1_SA_DQ<0>")
	)
	(arc
		(start 132.612892 -279.639776)
		(mid 132.425694 -279.589633)
		(end 132.238496 -279.639776)
		(width 0.088646)
		(layer "In6.Cu")
		(net "M_H_CPU1_SA_DQ<0>")
	)
	(arc
		(start 138.584432 -281.341576)
		(mid 138.41235 -281.330311)
		(end 138.251692 -281.267662)
		(width 0.088646)
		(layer "In6.Cu")
		(net "M_H_CPU1_SA_DQ<0>")
	)
	(arc
		(start 136.559544 -279.964134)
		(mid 136.511865 -279.781234)
		(end 136.380982 -279.644856)
		(width 0.088646)
		(layer "In6.Cu")
		(net "M_H_CPU1_SA_DQ<0>")
	)
	(arc
		(start 133.168136 -279.645872)
		(mid 132.889704 -279.715718)
		(end 132.612892 -279.639776)
		(width 0.088646)
		(layer "In6.Cu")
		(net "M_H_CPU1_SA_DQ<0>")
	)
	(arc
		(start 132.228082 -279.645872)
		(mid 131.949904 -279.715595)
		(end 131.673346 -279.639776)
		(width 0.088646)
		(layer "In6.Cu")
		(net "M_H_CPU1_SA_DQ<0>")
	)
	(arc
		(start 136.841992 -280.453846)
		(mid 136.639706 -280.254865)
		(end 136.559544 -279.982676)
		(width 0.088646)
		(layer "In6.Cu")
		(net "M_H_CPU1_SA_DQ<0>")
	)
	(arc
		(start 134.11835 -279.639776)
		(mid 133.844151 -279.715611)
		(end 133.567678 -279.648412)
		(width 0.088646)
		(layer "In6.Cu")
		(net "M_H_CPU1_SA_DQ<0>")
	)
	(arc
		(start 131.673346 -279.639776)
		(mid 131.514858 -279.590843)
		(end 131.350766 -279.615138)
		(width 0.088646)
		(layer "In6.Cu")
		(net "M_H_CPU1_SA_DQ<0>")
	)
	(arc
		(start 136.372092 -279.639776)
		(mid 136.184894 -279.589633)
		(end 135.997696 -279.639776)
		(width 0.088646)
		(layer "In6.Cu")
		(net "M_H_CPU1_SA_DQ<0>")
	)
	(arc
		(start 133.552946 -279.639776)
		(mid 133.365748 -279.589633)
		(end 133.17855 -279.639776)
		(width 0.088646)
		(layer "In6.Cu")
		(net "M_H_CPU1_SA_DQ<0>")
	)
	(arc
		(start 137.029444 -280.778204)
		(mid 136.981765 -280.595304)
		(end 136.850882 -280.458926)
		(width 0.088646)
		(layer "In6.Cu")
		(net "M_H_CPU1_SA_DQ<0>")
	)
	(arc
		(start 138.251692 -281.267662)
		(mid 138.064494 -281.217519)
		(end 137.877296 -281.267662)
		(width 0.088646)
		(layer "In6.Cu")
		(net "M_H_CPU1_SA_DQ<0>")
	)
	(arc
		(start 135.057642 -279.639776)
		(mid 134.775194 -279.715425)
		(end 134.492746 -279.639776)
		(width 0.088646)
		(layer "In6.Cu")
		(net "M_H_CPU1_SA_DQ<0>")
	)
	(arc
		(start 135.987282 -279.645872)
		(mid 135.70885 -279.715718)
		(end 135.432038 -279.639776)
		(width 0.088646)
		(layer "In6.Cu")
		(net "M_H_CPU1_SA_DQ<0>")
	)
	(arc
		(start 139.199112 -281.904694)
		(mid 139.015686 -281.487831)
		(end 138.584432 -281.341576)
		(width 0.088646)
		(layer "In6.Cu")
		(net "M_H_CPU1_SA_DQ<0>")
	)
	(arc
		(start 134.492746 -279.639776)
		(mid 134.305548 -279.589633)
		(end 134.11835 -279.639776)
		(width 0.088646)
		(layer "In6.Cu")
		(net "M_H_CPU1_SA_DQ<0>")
	)
	(arc
		(start 137.877296 -281.267662)
		(mid 137.594594 -281.343438)
		(end 137.311892 -281.267662)
		(width 0.088646)
		(layer "In6.Cu")
		(net "M_H_CPU1_SA_DQ<0>")
	)
	(arc
		(start 135.432038 -279.639776)
		(mid 135.24484 -279.589633)
		(end 135.057642 -279.639776)
		(width 0.088646)
		(layer "In6.Cu")
		(net "M_H_CPU1_SA_DQ<0>")
	)
	(arc
		(start 137.311892 -281.267662)
		(mid 137.107557 -281.065057)
		(end 137.029444 -280.78811)
		(width 0.088646)
		(layer "In6.Cu")
		(net "M_H_CPU1_SA_DQ<0>")
	)
	(segment
		(start 123.497848 -256.361184)
		(end 123.497594 -256.361438)
		(width 0.20066)
		(layer "F.Cu")
		(net "M_H_CPU1_SA_CS_N<3>")
	)
	(segment
		(start 208.176114 -267.016738)
		(end 206.995014 -267.016738)
		(width 0.20066)
		(layer "F.Cu")
		(net "M_H_CPU1_SA_CS_N<3>")
	)
	(segment
		(start 123.497848 -255.825498)
		(end 123.497848 -256.361184)
		(width 0.20066)
		(layer "F.Cu")
		(net "M_H_CPU1_SA_CS_N<3>")
	)
	(segment
		(start 168.12768 -263.898888)
		(end 167.90924 -264.117328)
		(width 0.18288)
		(layer "In11.Cu")
		(net "M_H_CPU1_SA_CS_N<3>")
	)
	(segment
		(start 136.389364 -255.86182)
		(end 136.372092 -255.87198)
		(width 0.088646)
		(layer "In11.Cu")
		(net "M_H_CPU1_SA_CS_N<3>")
	)
	(segment
		(start 123.654058 -256.632456)
		(end 123.497594 -256.361438)
		(width 0.088646)
		(layer "In11.Cu")
		(net "M_H_CPU1_SA_CS_N<3>")
	)
	(segment
		(start 125.104906 -255.865884)
		(end 125.094492 -255.87198)
		(width 0.088646)
		(layer "In11.Cu")
		(net "M_H_CPU1_SA_CS_N<3>")
	)
	(segment
		(start 150.179532 -258.25323)
		(end 149.644608 -257.718306)
		(width 0.18288)
		(layer "In11.Cu")
		(net "M_H_CPU1_SA_CS_N<3>")
	)
	(segment
		(start 131.68376 -255.865884)
		(end 131.673346 -255.87198)
		(width 0.088646)
		(layer "In11.Cu")
		(net "M_H_CPU1_SA_CS_N<3>")
	)
	(segment
		(start 130.748278 -255.863344)
		(end 130.733546 -255.87198)
		(width 0.088646)
		(layer "In11.Cu")
		(net "M_H_CPU1_SA_CS_N<3>")
	)
	(segment
		(start 129.808478 -255.863344)
		(end 129.793746 -255.87198)
		(width 0.088646)
		(layer "In11.Cu")
		(net "M_H_CPU1_SA_CS_N<3>")
	)
	(segment
		(start 183.041036 -264.96772)
		(end 182.693056 -264.61974)
		(width 0.18288)
		(layer "In11.Cu")
		(net "M_H_CPU1_SA_CS_N<3>")
	)
	(segment
		(start 127.928878 -255.863344)
		(end 127.914146 -255.87198)
		(width 0.088646)
		(layer "In11.Cu")
		(net "M_H_CPU1_SA_CS_N<3>")
	)
	(segment
		(start 126.04496 -255.865884)
		(end 126.034546 -255.87198)
		(width 0.088646)
		(layer "In11.Cu")
		(net "M_H_CPU1_SA_CS_N<3>")
	)
	(segment
		(start 124.154946 -255.87198)
		(end 124.14885 -255.875536)
		(width 0.088646)
		(layer "In11.Cu")
		(net "M_H_CPU1_SA_CS_N<3>")
	)
	(segment
		(start 185.309002 -264.96772)
		(end 183.041036 -264.96772)
		(width 0.18288)
		(layer "In11.Cu")
		(net "M_H_CPU1_SA_CS_N<3>")
	)
	(segment
		(start 187.190126 -263.844024)
		(end 186.432698 -263.844024)
		(width 0.18288)
		(layer "In11.Cu")
		(net "M_H_CPU1_SA_CS_N<3>")
	)
	(segment
		(start 189.466982 -264.040874)
		(end 187.386976 -264.040874)
		(width 0.18288)
		(layer "In11.Cu")
		(net "M_H_CPU1_SA_CS_N<3>")
	)
	(segment
		(start 206.65567 -266.380722)
		(end 204.349604 -266.380722)
		(width 0.18288)
		(layer "In11.Cu")
		(net "M_H_CPU1_SA_CS_N<3>")
	)
	(segment
		(start 174.006002 -264.193528)
		(end 173.853348 -264.040874)
		(width 0.18288)
		(layer "In11.Cu")
		(net "M_H_CPU1_SA_CS_N<3>")
	)
	(segment
		(start 175.738028 -264.193528)
		(end 174.006002 -264.193528)
		(width 0.18288)
		(layer "In11.Cu")
		(net "M_H_CPU1_SA_CS_N<3>")
	)
	(segment
		(start 167.90924 -264.117328)
		(end 164.688012 -264.117328)
		(width 0.18288)
		(layer "In11.Cu")
		(net "M_H_CPU1_SA_CS_N<3>")
	)
	(segment
		(start 137.94613 -255.978406)
		(end 137.80389 -255.836166)
		(width 0.088646)
		(layer "In11.Cu")
		(net "M_H_CPU1_SA_CS_N<3>")
	)
	(segment
		(start 200.503536 -265.658092)
		(end 199.015096 -265.658092)
		(width 0.18288)
		(layer "In11.Cu")
		(net "M_H_CPU1_SA_CS_N<3>")
	)
	(segment
		(start 190.472568 -264.157968)
		(end 189.584076 -264.157968)
		(width 0.18288)
		(layer "In11.Cu")
		(net "M_H_CPU1_SA_CS_N<3>")
	)
	(segment
		(start 164.688012 -264.117328)
		(end 164.4777 -263.907016)
		(width 0.18288)
		(layer "In11.Cu")
		(net "M_H_CPU1_SA_CS_N<3>")
	)
	(segment
		(start 157.287468 -263.172194)
		(end 157.088332 -263.172194)
		(width 0.18288)
		(layer "In11.Cu")
		(net "M_H_CPU1_SA_CS_N<3>")
	)
	(segment
		(start 173.853348 -264.040874)
		(end 171.89196 -264.040874)
		(width 0.18288)
		(layer "In11.Cu")
		(net "M_H_CPU1_SA_CS_N<3>")
	)
	(segment
		(start 206.995014 -266.720066)
		(end 206.65567 -266.380722)
		(width 0.18288)
		(layer "In11.Cu")
		(net "M_H_CPU1_SA_CS_N<3>")
	)
	(segment
		(start 157.088332 -263.172194)
		(end 152.169368 -258.25323)
		(width 0.18288)
		(layer "In11.Cu")
		(net "M_H_CPU1_SA_CS_N<3>")
	)
	(segment
		(start 189.584076 -264.157968)
		(end 189.466982 -264.040874)
		(width 0.18288)
		(layer "In11.Cu")
		(net "M_H_CPU1_SA_CS_N<3>")
	)
	(segment
		(start 176.435512 -264.891012)
		(end 175.738028 -264.193528)
		(width 0.18288)
		(layer "In11.Cu")
		(net "M_H_CPU1_SA_CS_N<3>")
	)
	(segment
		(start 161.28111 -263.907016)
		(end 161.11728 -264.070846)
		(width 0.18288)
		(layer "In11.Cu")
		(net "M_H_CPU1_SA_CS_N<3>")
	)
	(segment
		(start 187.386976 -264.040874)
		(end 187.190126 -263.844024)
		(width 0.18288)
		(layer "In11.Cu")
		(net "M_H_CPU1_SA_CS_N<3>")
	)
	(segment
		(start 198.069962 -264.712958)
		(end 195.286884 -264.712958)
		(width 0.18288)
		(layer "In11.Cu")
		(net "M_H_CPU1_SA_CS_N<3>")
	)
	(segment
		(start 202.726036 -267.443204)
		(end 202.014582 -266.73175)
		(width 0.18288)
		(layer "In11.Cu")
		(net "M_H_CPU1_SA_CS_N<3>")
	)
	(segment
		(start 126.984506 -255.865884)
		(end 126.9746 -255.87198)
		(width 0.088646)
		(layer "In11.Cu")
		(net "M_H_CPU1_SA_CS_N<3>")
	)
	(segment
		(start 171.749974 -263.898888)
		(end 168.12768 -263.898888)
		(width 0.18288)
		(layer "In11.Cu")
		(net "M_H_CPU1_SA_CS_N<3>")
	)
	(segment
		(start 191.205612 -264.891012)
		(end 190.472568 -264.157968)
		(width 0.18288)
		(layer "In11.Cu")
		(net "M_H_CPU1_SA_CS_N<3>")
	)
	(segment
		(start 124.16536 -255.865884)
		(end 124.154946 -255.87198)
		(width 0.088646)
		(layer "In11.Cu")
		(net "M_H_CPU1_SA_CS_N<3>")
	)
	(segment
		(start 171.89196 -264.040874)
		(end 171.749974 -263.898888)
		(width 0.18288)
		(layer "In11.Cu")
		(net "M_H_CPU1_SA_CS_N<3>")
	)
	(segment
		(start 161.11728 -264.070846)
		(end 159.676846 -264.070846)
		(width 0.18288)
		(layer "In11.Cu")
		(net "M_H_CPU1_SA_CS_N<3>")
	)
	(segment
		(start 157.287722 -263.172448)
		(end 157.287468 -263.172194)
		(width 0.18288)
		(layer "In11.Cu")
		(net "M_H_CPU1_SA_CS_N<3>")
	)
	(segment
		(start 199.015096 -265.658092)
		(end 198.069962 -264.712958)
		(width 0.18288)
		(layer "In11.Cu")
		(net "M_H_CPU1_SA_CS_N<3>")
	)
	(segment
		(start 178.214274 -264.891012)
		(end 176.435512 -264.891012)
		(width 0.18288)
		(layer "In11.Cu")
		(net "M_H_CPU1_SA_CS_N<3>")
	)
	(segment
		(start 186.432698 -263.844024)
		(end 185.309002 -264.96772)
		(width 0.18288)
		(layer "In11.Cu")
		(net "M_H_CPU1_SA_CS_N<3>")
	)
	(segment
		(start 202.014582 -266.73175)
		(end 201.577194 -266.73175)
		(width 0.18288)
		(layer "In11.Cu")
		(net "M_H_CPU1_SA_CS_N<3>")
	)
	(segment
		(start 178.409854 -265.086592)
		(end 178.214274 -264.891012)
		(width 0.18288)
		(layer "In11.Cu")
		(net "M_H_CPU1_SA_CS_N<3>")
	)
	(segment
		(start 201.577194 -266.73175)
		(end 200.503536 -265.658092)
		(width 0.18288)
		(layer "In11.Cu")
		(net "M_H_CPU1_SA_CS_N<3>")
	)
	(segment
		(start 194.962018 -265.037824)
		(end 193.316098 -265.037824)
		(width 0.18288)
		(layer "In11.Cu")
		(net "M_H_CPU1_SA_CS_N<3>")
	)
	(segment
		(start 133.563106 -255.865884)
		(end 133.552692 -255.87198)
		(width 0.088646)
		(layer "In11.Cu")
		(net "M_H_CPU1_SA_CS_N<3>")
	)
	(segment
		(start 193.169286 -264.891012)
		(end 191.205612 -264.891012)
		(width 0.18288)
		(layer "In11.Cu")
		(net "M_H_CPU1_SA_CS_N<3>")
	)
	(segment
		(start 195.286884 -264.712958)
		(end 194.962018 -265.037824)
		(width 0.18288)
		(layer "In11.Cu")
		(net "M_H_CPU1_SA_CS_N<3>")
	)
	(segment
		(start 179.460144 -265.086592)
		(end 178.409854 -265.086592)
		(width 0.18288)
		(layer "In11.Cu")
		(net "M_H_CPU1_SA_CS_N<3>")
	)
	(segment
		(start 164.4777 -263.907016)
		(end 161.28111 -263.907016)
		(width 0.18288)
		(layer "In11.Cu")
		(net "M_H_CPU1_SA_CS_N<3>")
	)
	(segment
		(start 158.778448 -263.172448)
		(end 157.287722 -263.172448)
		(width 0.18288)
		(layer "In11.Cu")
		(net "M_H_CPU1_SA_CS_N<3>")
	)
	(segment
		(start 152.169368 -258.25323)
		(end 150.179532 -258.25323)
		(width 0.18288)
		(layer "In11.Cu")
		(net "M_H_CPU1_SA_CS_N<3>")
	)
	(segment
		(start 206.995014 -267.016738)
		(end 206.995014 -266.720066)
		(width 0.18288)
		(layer "In11.Cu")
		(net "M_H_CPU1_SA_CS_N<3>")
	)
	(segment
		(start 149.644608 -257.718306)
		(end 143.47952 -257.718306)
		(width 0.18288)
		(layer "In11.Cu")
		(net "M_H_CPU1_SA_CS_N<3>")
	)
	(segment
		(start 182.693056 -264.61974)
		(end 179.926996 -264.61974)
		(width 0.18288)
		(layer "In11.Cu")
		(net "M_H_CPU1_SA_CS_N<3>")
	)
	(segment
		(start 193.316098 -265.037824)
		(end 193.169286 -264.891012)
		(width 0.18288)
		(layer "In11.Cu")
		(net "M_H_CPU1_SA_CS_N<3>")
	)
	(segment
		(start 134.50316 -255.865884)
		(end 134.492746 -255.87198)
		(width 0.088646)
		(layer "In11.Cu")
		(net "M_H_CPU1_SA_CS_N<3>")
	)
	(segment
		(start 179.926996 -264.61974)
		(end 179.460144 -265.086592)
		(width 0.18288)
		(layer "In11.Cu")
		(net "M_H_CPU1_SA_CS_N<3>")
	)
	(segment
		(start 141.73962 -255.978406)
		(end 140.18895 -255.978406)
		(width 0.18288)
		(layer "In11.Cu")
		(net "M_H_CPU1_SA_CS_N<3>")
	)
	(segment
		(start 159.676846 -264.070846)
		(end 158.778448 -263.172448)
		(width 0.18288)
		(layer "In11.Cu")
		(net "M_H_CPU1_SA_CS_N<3>")
	)
	(segment
		(start 123.73229 -256.653284)
		(end 123.654058 -256.632456)
		(width 0.088646)
		(layer "In11.Cu")
		(net "M_H_CPU1_SA_CS_N<3>")
	)
	(segment
		(start 143.47952 -257.718306)
		(end 141.73962 -255.978406)
		(width 0.18288)
		(layer "In11.Cu")
		(net "M_H_CPU1_SA_CS_N<3>")
	)
	(segment
		(start 204.349604 -266.380722)
		(end 203.287122 -267.443204)
		(width 0.18288)
		(layer "In11.Cu")
		(net "M_H_CPU1_SA_CS_N<3>")
	)
	(segment
		(start 140.18895 -255.978406)
		(end 137.94613 -255.978406)
		(width 0.088646)
		(layer "In11.Cu")
		(net "M_H_CPU1_SA_CS_N<3>")
	)
	(segment
		(start 203.287122 -267.443204)
		(end 202.726036 -267.443204)
		(width 0.18288)
		(layer "In11.Cu")
		(net "M_H_CPU1_SA_CS_N<3>")
	)
	(arc
		(start 137.312146 -255.871726)
		(mid 137.124948 -255.921869)
		(end 136.93775 -255.871726)
		(width 0.088646)
		(layer "In11.Cu")
		(net "M_H_CPU1_SA_CS_N<3>")
	)
	(arc
		(start 129.793746 -255.87198)
		(mid 129.606548 -255.922123)
		(end 129.41935 -255.87198)
		(width 0.088646)
		(layer "In11.Cu")
		(net "M_H_CPU1_SA_CS_N<3>")
	)
	(arc
		(start 135.997696 -255.87198)
		(mid 135.714994 -255.796204)
		(end 135.432292 -255.87198)
		(width 0.088646)
		(layer "In11.Cu")
		(net "M_H_CPU1_SA_CS_N<3>")
	)
	(arc
		(start 127.914146 -255.87198)
		(mid 127.726948 -255.922123)
		(end 127.53975 -255.87198)
		(width 0.088646)
		(layer "In11.Cu")
		(net "M_H_CPU1_SA_CS_N<3>")
	)
	(arc
		(start 124.14885 -255.875536)
		(mid 123.946263 -256.081887)
		(end 123.872244 -256.361438)
		(width 0.088646)
		(layer "In11.Cu")
		(net "M_H_CPU1_SA_CS_N<3>")
	)
	(arc
		(start 126.599696 -255.87198)
		(mid 126.323137 -255.796237)
		(end 126.04496 -255.865884)
		(width 0.088646)
		(layer "In11.Cu")
		(net "M_H_CPU1_SA_CS_N<3>")
	)
	(arc
		(start 133.552692 -255.87198)
		(mid 133.365494 -255.922123)
		(end 133.178296 -255.87198)
		(width 0.088646)
		(layer "In11.Cu")
		(net "M_H_CPU1_SA_CS_N<3>")
	)
	(arc
		(start 131.29895 -255.87198)
		(mid 131.024751 -255.796145)
		(end 130.748278 -255.863344)
		(width 0.088646)
		(layer "In11.Cu")
		(net "M_H_CPU1_SA_CS_N<3>")
	)
	(arc
		(start 134.492746 -255.87198)
		(mid 134.305548 -255.922123)
		(end 134.11835 -255.87198)
		(width 0.088646)
		(layer "In11.Cu")
		(net "M_H_CPU1_SA_CS_N<3>")
	)
	(arc
		(start 133.178296 -255.87198)
		(mid 132.895594 -255.796204)
		(end 132.612892 -255.87198)
		(width 0.088646)
		(layer "In11.Cu")
		(net "M_H_CPU1_SA_CS_N<3>")
	)
	(arc
		(start 125.66015 -255.87198)
		(mid 125.383337 -255.79611)
		(end 125.104906 -255.865884)
		(width 0.088646)
		(layer "In11.Cu")
		(net "M_H_CPU1_SA_CS_N<3>")
	)
	(arc
		(start 125.094492 -255.87198)
		(mid 124.907294 -255.922123)
		(end 124.720096 -255.87198)
		(width 0.088646)
		(layer "In11.Cu")
		(net "M_H_CPU1_SA_CS_N<3>")
	)
	(arc
		(start 132.238496 -255.87198)
		(mid 131.961937 -255.796237)
		(end 131.68376 -255.865884)
		(width 0.088646)
		(layer "In11.Cu")
		(net "M_H_CPU1_SA_CS_N<3>")
	)
	(arc
		(start 129.41935 -255.87198)
		(mid 129.136648 -255.796204)
		(end 128.853946 -255.87198)
		(width 0.088646)
		(layer "In11.Cu")
		(net "M_H_CPU1_SA_CS_N<3>")
	)
	(arc
		(start 136.93775 -255.871726)
		(mid 136.664828 -255.795823)
		(end 136.389364 -255.86182)
		(width 0.088646)
		(layer "In11.Cu")
		(net "M_H_CPU1_SA_CS_N<3>")
	)
	(arc
		(start 127.53975 -255.87198)
		(mid 127.262937 -255.79611)
		(end 126.984506 -255.865884)
		(width 0.088646)
		(layer "In11.Cu")
		(net "M_H_CPU1_SA_CS_N<3>")
	)
	(arc
		(start 136.372092 -255.87198)
		(mid 136.184894 -255.922123)
		(end 135.997696 -255.87198)
		(width 0.088646)
		(layer "In11.Cu")
		(net "M_H_CPU1_SA_CS_N<3>")
	)
	(arc
		(start 132.612892 -255.87198)
		(mid 132.425694 -255.922123)
		(end 132.238496 -255.87198)
		(width 0.088646)
		(layer "In11.Cu")
		(net "M_H_CPU1_SA_CS_N<3>")
	)
	(arc
		(start 124.720096 -255.87198)
		(mid 124.443537 -255.796237)
		(end 124.16536 -255.865884)
		(width 0.088646)
		(layer "In11.Cu")
		(net "M_H_CPU1_SA_CS_N<3>")
	)
	(arc
		(start 134.11835 -255.87198)
		(mid 133.841537 -255.79611)
		(end 133.563106 -255.865884)
		(width 0.088646)
		(layer "In11.Cu")
		(net "M_H_CPU1_SA_CS_N<3>")
	)
	(arc
		(start 128.47955 -255.87198)
		(mid 128.205351 -255.796145)
		(end 127.928878 -255.863344)
		(width 0.088646)
		(layer "In11.Cu")
		(net "M_H_CPU1_SA_CS_N<3>")
	)
	(arc
		(start 123.872244 -256.361438)
		(mid 123.835384 -256.523235)
		(end 123.73229 -256.653284)
		(width 0.088646)
		(layer "In11.Cu")
		(net "M_H_CPU1_SA_CS_N<3>")
	)
	(arc
		(start 130.35915 -255.87198)
		(mid 130.084951 -255.796145)
		(end 129.808478 -255.863344)
		(width 0.088646)
		(layer "In11.Cu")
		(net "M_H_CPU1_SA_CS_N<3>")
	)
	(arc
		(start 135.432292 -255.87198)
		(mid 135.245094 -255.922123)
		(end 135.057896 -255.87198)
		(width 0.088646)
		(layer "In11.Cu")
		(net "M_H_CPU1_SA_CS_N<3>")
	)
	(arc
		(start 126.9746 -255.87198)
		(mid 126.787148 -255.92225)
		(end 126.599696 -255.87198)
		(width 0.088646)
		(layer "In11.Cu")
		(net "M_H_CPU1_SA_CS_N<3>")
	)
	(arc
		(start 137.80389 -255.836166)
		(mid 137.553922 -255.797469)
		(end 137.312146 -255.871726)
		(width 0.088646)
		(layer "In11.Cu")
		(net "M_H_CPU1_SA_CS_N<3>")
	)
	(arc
		(start 135.057896 -255.87198)
		(mid 134.781337 -255.796237)
		(end 134.50316 -255.865884)
		(width 0.088646)
		(layer "In11.Cu")
		(net "M_H_CPU1_SA_CS_N<3>")
	)
	(arc
		(start 128.853946 -255.87198)
		(mid 128.666748 -255.922123)
		(end 128.47955 -255.87198)
		(width 0.088646)
		(layer "In11.Cu")
		(net "M_H_CPU1_SA_CS_N<3>")
	)
	(arc
		(start 131.673346 -255.87198)
		(mid 131.486148 -255.922123)
		(end 131.29895 -255.87198)
		(width 0.088646)
		(layer "In11.Cu")
		(net "M_H_CPU1_SA_CS_N<3>")
	)
	(arc
		(start 130.733546 -255.87198)
		(mid 130.546348 -255.922123)
		(end 130.35915 -255.87198)
		(width 0.088646)
		(layer "In11.Cu")
		(net "M_H_CPU1_SA_CS_N<3>")
	)
	(arc
		(start 126.034546 -255.87198)
		(mid 125.847348 -255.922123)
		(end 125.66015 -255.87198)
		(width 0.088646)
		(layer "In11.Cu")
		(net "M_H_CPU1_SA_CS_N<3>")
	)
	(segment
		(start 123.967494 -257.175)
		(end 123.967748 -257.175254)
		(width 0.20066)
		(layer "F.Cu")
		(net "M_H_CPU1_SA_CS_N<2>")
	)
	(segment
		(start 123.967494 -256.639314)
		(end 123.967494 -257.175)
		(width 0.20066)
		(layer "F.Cu")
		(net "M_H_CPU1_SA_CS_N<2>")
	)
	(segment
		(start 202.971146 -267.866622)
		(end 204.076046 -267.866622)
		(width 0.20066)
		(layer "F.Cu")
		(net "M_H_CPU1_SA_CS_N<2>")
	)
	(segment
		(start 159.479996 -264.635996)
		(end 158.898082 -264.054082)
		(width 0.18288)
		(layer "In11.Cu")
		(net "M_H_CPU1_SA_CS_N<2>")
	)
	(segment
		(start 193.398648 -265.740896)
		(end 191.295528 -265.740896)
		(width 0.18288)
		(layer "In11.Cu")
		(net "M_H_CPU1_SA_CS_N<2>")
	)
	(segment
		(start 191.295528 -265.740896)
		(end 190.302134 -264.747502)
		(width 0.18288)
		(layer "In11.Cu")
		(net "M_H_CPU1_SA_CS_N<2>")
	)
	(segment
		(start 168.500552 -264.99439)
		(end 168.139364 -264.633202)
		(width 0.18288)
		(layer "In11.Cu")
		(net "M_H_CPU1_SA_CS_N<2>")
	)
	(segment
		(start 134.587996 -256.03708)
		(end 134.573264 -256.045716)
		(width 0.088646)
		(layer "In11.Cu")
		(net "M_H_CPU1_SA_CS_N<2>")
	)
	(segment
		(start 172.053758 -264.893044)
		(end 171.952412 -264.99439)
		(width 0.18288)
		(layer "In11.Cu")
		(net "M_H_CPU1_SA_CS_N<2>")
	)
	(segment
		(start 157.287468 -264.053828)
		(end 156.995622 -264.053828)
		(width 0.18288)
		(layer "In11.Cu")
		(net "M_H_CPU1_SA_CS_N<2>")
	)
	(segment
		(start 124.062744 -256.361438)
		(end 124.062744 -256.376932)
		(width 0.088646)
		(layer "In11.Cu")
		(net "M_H_CPU1_SA_CS_N<2>")
	)
	(segment
		(start 198.311262 -265.807698)
		(end 195.021454 -265.807698)
		(width 0.18288)
		(layer "In11.Cu")
		(net "M_H_CPU1_SA_CS_N<2>")
	)
	(segment
		(start 128.009396 -256.03708)
		(end 127.994664 -256.045716)
		(width 0.088646)
		(layer "In11.Cu")
		(net "M_H_CPU1_SA_CS_N<2>")
	)
	(segment
		(start 151.741632 -258.799838)
		(end 150.159212 -258.799838)
		(width 0.18288)
		(layer "In11.Cu")
		(net "M_H_CPU1_SA_CS_N<2>")
	)
	(segment
		(start 139.445492 -256.370074)
		(end 139.253214 -256.177796)
		(width 0.088646)
		(layer "In11.Cu")
		(net "M_H_CPU1_SA_CS_N<2>")
	)
	(segment
		(start 161.106358 -264.905744)
		(end 160.83661 -264.635996)
		(width 0.18288)
		(layer "In11.Cu")
		(net "M_H_CPU1_SA_CS_N<2>")
	)
	(segment
		(start 202.420728 -267.866622)
		(end 202.031346 -267.47724)
		(width 0.18288)
		(layer "In11.Cu")
		(net "M_H_CPU1_SA_CS_N<2>")
	)
	(segment
		(start 140.18895 -256.370074)
		(end 139.445492 -256.370074)
		(width 0.088646)
		(layer "In11.Cu")
		(net "M_H_CPU1_SA_CS_N<2>")
	)
	(segment
		(start 173.825408 -264.893044)
		(end 172.053758 -264.893044)
		(width 0.18288)
		(layer "In11.Cu")
		(net "M_H_CPU1_SA_CS_N<2>")
	)
	(segment
		(start 176.44491 -265.73861)
		(end 175.448468 -264.742168)
		(width 0.18288)
		(layer "In11.Cu")
		(net "M_H_CPU1_SA_CS_N<2>")
	)
	(segment
		(start 179.714906 -265.73861)
		(end 176.44491 -265.73861)
		(width 0.18288)
		(layer "In11.Cu")
		(net "M_H_CPU1_SA_CS_N<2>")
	)
	(segment
		(start 139.253214 -256.177796)
		(end 137.802366 -256.177796)
		(width 0.088646)
		(layer "In11.Cu")
		(net "M_H_CPU1_SA_CS_N<2>")
	)
	(segment
		(start 168.139364 -264.633202)
		(end 164.597842 -264.633202)
		(width 0.18288)
		(layer "In11.Cu")
		(net "M_H_CPU1_SA_CS_N<2>")
	)
	(segment
		(start 150.159212 -258.799838)
		(end 149.42312 -258.063746)
		(width 0.18288)
		(layer "In11.Cu")
		(net "M_H_CPU1_SA_CS_N<2>")
	)
	(segment
		(start 202.971146 -267.866622)
		(end 202.420728 -267.866622)
		(width 0.18288)
		(layer "In11.Cu")
		(net "M_H_CPU1_SA_CS_N<2>")
	)
	(segment
		(start 173.976284 -264.742168)
		(end 173.825408 -264.893044)
		(width 0.18288)
		(layer "In11.Cu")
		(net "M_H_CPU1_SA_CS_N<2>")
	)
	(segment
		(start 193.577464 -265.56208)
		(end 193.398648 -265.740896)
		(width 0.18288)
		(layer "In11.Cu")
		(net "M_H_CPU1_SA_CS_N<2>")
	)
	(segment
		(start 149.42312 -258.063746)
		(end 143.33601 -258.063746)
		(width 0.18288)
		(layer "In11.Cu")
		(net "M_H_CPU1_SA_CS_N<2>")
	)
	(segment
		(start 157.287722 -264.054082)
		(end 157.287468 -264.053828)
		(width 0.18288)
		(layer "In11.Cu")
		(net "M_H_CPU1_SA_CS_N<2>")
	)
	(segment
		(start 187.24372 -264.891012)
		(end 187.0964 -265.038332)
		(width 0.18288)
		(layer "In11.Cu")
		(net "M_H_CPU1_SA_CS_N<2>")
	)
	(segment
		(start 201.280522 -267.166344)
		(end 200.70445 -266.590272)
		(width 0.18288)
		(layer "In11.Cu")
		(net "M_H_CPU1_SA_CS_N<2>")
	)
	(segment
		(start 171.952412 -264.99439)
		(end 168.500552 -264.99439)
		(width 0.18288)
		(layer "In11.Cu")
		(net "M_H_CPU1_SA_CS_N<2>")
	)
	(segment
		(start 143.33601 -258.063746)
		(end 141.642338 -256.370074)
		(width 0.18288)
		(layer "In11.Cu")
		(net "M_H_CPU1_SA_CS_N<2>")
	)
	(segment
		(start 195.021454 -265.807698)
		(end 194.775836 -265.56208)
		(width 0.18288)
		(layer "In11.Cu")
		(net "M_H_CPU1_SA_CS_N<2>")
	)
	(segment
		(start 185.619644 -265.536934)
		(end 183.242204 -265.536934)
		(width 0.18288)
		(layer "In11.Cu")
		(net "M_H_CPU1_SA_CS_N<2>")
	)
	(segment
		(start 199.093836 -266.590272)
		(end 198.311262 -265.807698)
		(width 0.18288)
		(layer "In11.Cu")
		(net "M_H_CPU1_SA_CS_N<2>")
	)
	(segment
		(start 200.70445 -266.590272)
		(end 199.093836 -266.590272)
		(width 0.18288)
		(layer "In11.Cu")
		(net "M_H_CPU1_SA_CS_N<2>")
	)
	(segment
		(start 123.835414 -256.815082)
		(end 123.811284 -256.904236)
		(width 0.088646)
		(layer "In11.Cu")
		(net "M_H_CPU1_SA_CS_N<2>")
	)
	(segment
		(start 179.84978 -265.873484)
		(end 179.714906 -265.73861)
		(width 0.18288)
		(layer "In11.Cu")
		(net "M_H_CPU1_SA_CS_N<2>")
	)
	(segment
		(start 128.94945 -256.03708)
		(end 128.939036 -256.043176)
		(width 0.088646)
		(layer "In11.Cu")
		(net "M_H_CPU1_SA_CS_N<2>")
	)
	(segment
		(start 182.905654 -265.873484)
		(end 179.84978 -265.873484)
		(width 0.18288)
		(layer "In11.Cu")
		(net "M_H_CPU1_SA_CS_N<2>")
	)
	(segment
		(start 131.768596 -256.03708)
		(end 131.753864 -256.045716)
		(width 0.088646)
		(layer "In11.Cu")
		(net "M_H_CPU1_SA_CS_N<2>")
	)
	(segment
		(start 141.642338 -256.370074)
		(end 140.18895 -256.370074)
		(width 0.18288)
		(layer "In11.Cu")
		(net "M_H_CPU1_SA_CS_N<2>")
	)
	(segment
		(start 175.448468 -264.742168)
		(end 173.976284 -264.742168)
		(width 0.18288)
		(layer "In11.Cu")
		(net "M_H_CPU1_SA_CS_N<2>")
	)
	(segment
		(start 164.3253 -264.905744)
		(end 161.106358 -264.905744)
		(width 0.18288)
		(layer "In11.Cu")
		(net "M_H_CPU1_SA_CS_N<2>")
	)
	(segment
		(start 137.407396 -256.03708)
		(end 137.392664 -256.045716)
		(width 0.088646)
		(layer "In11.Cu")
		(net "M_H_CPU1_SA_CS_N<2>")
	)
	(segment
		(start 194.775836 -265.56208)
		(end 193.577464 -265.56208)
		(width 0.18288)
		(layer "In11.Cu")
		(net "M_H_CPU1_SA_CS_N<2>")
	)
	(segment
		(start 164.597842 -264.633202)
		(end 164.3253 -264.905744)
		(width 0.18288)
		(layer "In11.Cu")
		(net "M_H_CPU1_SA_CS_N<2>")
	)
	(segment
		(start 156.995622 -264.053828)
		(end 151.741632 -258.799838)
		(width 0.18288)
		(layer "In11.Cu")
		(net "M_H_CPU1_SA_CS_N<2>")
	)
	(segment
		(start 126.129796 -256.03708)
		(end 126.115064 -256.045716)
		(width 0.088646)
		(layer "In11.Cu")
		(net "M_H_CPU1_SA_CS_N<2>")
	)
	(segment
		(start 189.700662 -264.747502)
		(end 189.557152 -264.891012)
		(width 0.18288)
		(layer "In11.Cu")
		(net "M_H_CPU1_SA_CS_N<2>")
	)
	(segment
		(start 202.031346 -267.47724)
		(end 201.280522 -267.166344)
		(width 0.18288)
		(layer "In11.Cu")
		(net "M_H_CPU1_SA_CS_N<2>")
	)
	(segment
		(start 190.302134 -264.747502)
		(end 189.700662 -264.747502)
		(width 0.18288)
		(layer "In11.Cu")
		(net "M_H_CPU1_SA_CS_N<2>")
	)
	(segment
		(start 130.828796 -256.03708)
		(end 130.814064 -256.045716)
		(width 0.088646)
		(layer "In11.Cu")
		(net "M_H_CPU1_SA_CS_N<2>")
	)
	(segment
		(start 187.0964 -265.038332)
		(end 186.118246 -265.038332)
		(width 0.18288)
		(layer "In11.Cu")
		(net "M_H_CPU1_SA_CS_N<2>")
	)
	(segment
		(start 158.898082 -264.054082)
		(end 157.287722 -264.054082)
		(width 0.18288)
		(layer "In11.Cu")
		(net "M_H_CPU1_SA_CS_N<2>")
	)
	(segment
		(start 123.811284 -256.904236)
		(end 123.967748 -257.175254)
		(width 0.088646)
		(layer "In11.Cu")
		(net "M_H_CPU1_SA_CS_N<2>")
	)
	(segment
		(start 137.802366 -256.177796)
		(end 137.611866 -255.987296)
		(width 0.088646)
		(layer "In11.Cu")
		(net "M_H_CPU1_SA_CS_N<2>")
	)
	(segment
		(start 124.250196 -256.03708)
		(end 124.241306 -256.04216)
		(width 0.088646)
		(layer "In11.Cu")
		(net "M_H_CPU1_SA_CS_N<2>")
	)
	(segment
		(start 183.242204 -265.536934)
		(end 182.905654 -265.873484)
		(width 0.18288)
		(layer "In11.Cu")
		(net "M_H_CPU1_SA_CS_N<2>")
	)
	(segment
		(start 186.118246 -265.038332)
		(end 185.619644 -265.536934)
		(width 0.18288)
		(layer "In11.Cu")
		(net "M_H_CPU1_SA_CS_N<2>")
	)
	(segment
		(start 189.557152 -264.891012)
		(end 187.24372 -264.891012)
		(width 0.18288)
		(layer "In11.Cu")
		(net "M_H_CPU1_SA_CS_N<2>")
	)
	(segment
		(start 160.83661 -264.635996)
		(end 159.479996 -264.635996)
		(width 0.18288)
		(layer "In11.Cu")
		(net "M_H_CPU1_SA_CS_N<2>")
	)
	(segment
		(start 129.888996 -256.03708)
		(end 129.878582 -256.043176)
		(width 0.088646)
		(layer "In11.Cu")
		(net "M_H_CPU1_SA_CS_N<2>")
	)
	(arc
		(start 137.611866 -255.987296)
		(mid 137.506055 -255.997513)
		(end 137.407396 -256.03708)
		(width 0.088646)
		(layer "In11.Cu")
		(net "M_H_CPU1_SA_CS_N<2>")
	)
	(arc
		(start 133.082792 -256.03708)
		(mid 132.895594 -255.986937)
		(end 132.708396 -256.03708)
		(width 0.088646)
		(layer "In11.Cu")
		(net "M_H_CPU1_SA_CS_N<2>")
	)
	(arc
		(start 127.443992 -256.03708)
		(mid 127.256794 -255.986937)
		(end 127.069596 -256.03708)
		(width 0.088646)
		(layer "In11.Cu")
		(net "M_H_CPU1_SA_CS_N<2>")
	)
	(arc
		(start 131.203192 -256.03708)
		(mid 131.015994 -255.986937)
		(end 130.828796 -256.03708)
		(width 0.088646)
		(layer "In11.Cu")
		(net "M_H_CPU1_SA_CS_N<2>")
	)
	(arc
		(start 127.994664 -256.045716)
		(mid 127.718189 -256.113036)
		(end 127.443992 -256.03708)
		(width 0.088646)
		(layer "In11.Cu")
		(net "M_H_CPU1_SA_CS_N<2>")
	)
	(arc
		(start 136.467596 -256.03708)
		(mid 136.184894 -256.112856)
		(end 135.902192 -256.03708)
		(width 0.088646)
		(layer "In11.Cu")
		(net "M_H_CPU1_SA_CS_N<2>")
	)
	(arc
		(start 132.142992 -256.03708)
		(mid 131.955794 -255.986937)
		(end 131.768596 -256.03708)
		(width 0.088646)
		(layer "In11.Cu")
		(net "M_H_CPU1_SA_CS_N<2>")
	)
	(arc
		(start 132.708396 -256.03708)
		(mid 132.425694 -256.112856)
		(end 132.142992 -256.03708)
		(width 0.088646)
		(layer "In11.Cu")
		(net "M_H_CPU1_SA_CS_N<2>")
	)
	(arc
		(start 137.392664 -256.045716)
		(mid 137.116223 -256.112882)
		(end 136.841992 -256.03708)
		(width 0.088646)
		(layer "In11.Cu")
		(net "M_H_CPU1_SA_CS_N<2>")
	)
	(arc
		(start 133.648196 -256.03708)
		(mid 133.365494 -256.112856)
		(end 133.082792 -256.03708)
		(width 0.088646)
		(layer "In11.Cu")
		(net "M_H_CPU1_SA_CS_N<2>")
	)
	(arc
		(start 128.939036 -256.043176)
		(mid 128.660604 -256.113022)
		(end 128.383792 -256.03708)
		(width 0.088646)
		(layer "In11.Cu")
		(net "M_H_CPU1_SA_CS_N<2>")
	)
	(arc
		(start 130.263392 -256.03708)
		(mid 130.076194 -255.986937)
		(end 129.888996 -256.03708)
		(width 0.088646)
		(layer "In11.Cu")
		(net "M_H_CPU1_SA_CS_N<2>")
	)
	(arc
		(start 127.069596 -256.03708)
		(mid 126.786894 -256.112856)
		(end 126.504192 -256.03708)
		(width 0.088646)
		(layer "In11.Cu")
		(net "M_H_CPU1_SA_CS_N<2>")
	)
	(arc
		(start 136.841992 -256.03708)
		(mid 136.654794 -255.986937)
		(end 136.467596 -256.03708)
		(width 0.088646)
		(layer "In11.Cu")
		(net "M_H_CPU1_SA_CS_N<2>")
	)
	(arc
		(start 125.564392 -256.03708)
		(mid 125.377194 -255.986937)
		(end 125.189996 -256.03708)
		(width 0.088646)
		(layer "In11.Cu")
		(net "M_H_CPU1_SA_CS_N<2>")
	)
	(arc
		(start 129.323846 -256.03708)
		(mid 129.136648 -255.986937)
		(end 128.94945 -256.03708)
		(width 0.088646)
		(layer "In11.Cu")
		(net "M_H_CPU1_SA_CS_N<2>")
	)
	(arc
		(start 124.062744 -256.376932)
		(mid 123.9994 -256.622109)
		(end 123.835414 -256.815082)
		(width 0.088646)
		(layer "In11.Cu")
		(net "M_H_CPU1_SA_CS_N<2>")
	)
	(arc
		(start 124.241306 -256.04216)
		(mid 124.110392 -256.17852)
		(end 124.062744 -256.361438)
		(width 0.088646)
		(layer "In11.Cu")
		(net "M_H_CPU1_SA_CS_N<2>")
	)
	(arc
		(start 124.624592 -256.03708)
		(mid 124.437394 -255.986937)
		(end 124.250196 -256.03708)
		(width 0.088646)
		(layer "In11.Cu")
		(net "M_H_CPU1_SA_CS_N<2>")
	)
	(arc
		(start 135.902192 -256.03708)
		(mid 135.714994 -255.986937)
		(end 135.527796 -256.03708)
		(width 0.088646)
		(layer "In11.Cu")
		(net "M_H_CPU1_SA_CS_N<2>")
	)
	(arc
		(start 134.573264 -256.045716)
		(mid 134.296789 -256.113036)
		(end 134.022592 -256.03708)
		(width 0.088646)
		(layer "In11.Cu")
		(net "M_H_CPU1_SA_CS_N<2>")
	)
	(arc
		(start 134.962392 -256.03708)
		(mid 134.775194 -255.986937)
		(end 134.587996 -256.03708)
		(width 0.088646)
		(layer "In11.Cu")
		(net "M_H_CPU1_SA_CS_N<2>")
	)
	(arc
		(start 130.814064 -256.045716)
		(mid 130.537589 -256.113036)
		(end 130.263392 -256.03708)
		(width 0.088646)
		(layer "In11.Cu")
		(net "M_H_CPU1_SA_CS_N<2>")
	)
	(arc
		(start 128.383792 -256.03708)
		(mid 128.196594 -255.986937)
		(end 128.009396 -256.03708)
		(width 0.088646)
		(layer "In11.Cu")
		(net "M_H_CPU1_SA_CS_N<2>")
	)
	(arc
		(start 126.115064 -256.045716)
		(mid 125.838589 -256.113036)
		(end 125.564392 -256.03708)
		(width 0.088646)
		(layer "In11.Cu")
		(net "M_H_CPU1_SA_CS_N<2>")
	)
	(arc
		(start 131.753864 -256.045716)
		(mid 131.477389 -256.113036)
		(end 131.203192 -256.03708)
		(width 0.088646)
		(layer "In11.Cu")
		(net "M_H_CPU1_SA_CS_N<2>")
	)
	(arc
		(start 135.527796 -256.03708)
		(mid 135.245094 -256.112856)
		(end 134.962392 -256.03708)
		(width 0.088646)
		(layer "In11.Cu")
		(net "M_H_CPU1_SA_CS_N<2>")
	)
	(arc
		(start 126.504192 -256.03708)
		(mid 126.316994 -255.986937)
		(end 126.129796 -256.03708)
		(width 0.088646)
		(layer "In11.Cu")
		(net "M_H_CPU1_SA_CS_N<2>")
	)
	(arc
		(start 129.878582 -256.043176)
		(mid 129.600404 -256.112899)
		(end 129.323846 -256.03708)
		(width 0.088646)
		(layer "In11.Cu")
		(net "M_H_CPU1_SA_CS_N<2>")
	)
	(arc
		(start 125.189996 -256.03708)
		(mid 124.907294 -256.112856)
		(end 124.624592 -256.03708)
		(width 0.088646)
		(layer "In11.Cu")
		(net "M_H_CPU1_SA_CS_N<2>")
	)
	(arc
		(start 134.022592 -256.03708)
		(mid 133.835394 -255.986937)
		(end 133.648196 -256.03708)
		(width 0.088646)
		(layer "In11.Cu")
		(net "M_H_CPU1_SA_CS_N<2>")
	)
	(segment
		(start 125.377194 -255.825752)
		(end 125.377194 -256.361438)
		(width 0.20066)
		(layer "F.Cu")
		(net "M_H_CPU1_SA_CS_N<1>")
	)
	(segment
		(start 125.377448 -255.825498)
		(end 125.377194 -255.825752)
		(width 0.20066)
		(layer "F.Cu")
		(net "M_H_CPU1_SA_CS_N<1>")
	)
	(segment
		(start 215.719914 -267.016738)
		(end 214.615014 -267.016738)
		(width 0.20066)
		(layer "F.Cu")
		(net "M_H_CPU1_SA_CS_N<1>")
	)
	(segment
		(start 182.795418 -266.385294)
		(end 180.135784 -266.385294)
		(width 0.18288)
		(layer "In11.Cu")
		(net "M_H_CPU1_SA_CS_N<1>")
	)
	(segment
		(start 192.89903 -266.591034)
		(end 191.393826 -266.591034)
		(width 0.18288)
		(layer "In11.Cu")
		(net "M_H_CPU1_SA_CS_N<1>")
	)
	(segment
		(start 125.804676 -256.611628)
		(end 125.516894 -256.41935)
		(width 0.088646)
		(layer "In11.Cu")
		(net "M_H_CPU1_SA_CS_N<1>")
	)
	(segment
		(start 133.648196 -256.685796)
		(end 133.633464 -256.67716)
		(width 0.088646)
		(layer "In11.Cu")
		(net "M_H_CPU1_SA_CS_N<1>")
	)
	(segment
		(start 186.355228 -265.562334)
		(end 185.327036 -266.590526)
		(width 0.18288)
		(layer "In11.Cu")
		(net "M_H_CPU1_SA_CS_N<1>")
	)
	(segment
		(start 175.459898 -265.744706)
		(end 171.996354 -265.744706)
		(width 0.18288)
		(layer "In11.Cu")
		(net "M_H_CPU1_SA_CS_N<1>")
	)
	(segment
		(start 180.135784 -266.385294)
		(end 179.92598 -266.595098)
		(width 0.18288)
		(layer "In11.Cu")
		(net "M_H_CPU1_SA_CS_N<1>")
	)
	(segment
		(start 158.42869 -264.66419)
		(end 156.840428 -264.66419)
		(width 0.18288)
		(layer "In11.Cu")
		(net "M_H_CPU1_SA_CS_N<1>")
	)
	(segment
		(start 164.380926 -265.575288)
		(end 161.583624 -265.575288)
		(width 0.18288)
		(layer "In11.Cu")
		(net "M_H_CPU1_SA_CS_N<1>")
	)
	(segment
		(start 161.190432 -265.96848)
		(end 159.73298 -265.96848)
		(width 0.18288)
		(layer "In11.Cu")
		(net "M_H_CPU1_SA_CS_N<1>")
	)
	(segment
		(start 201.530458 -268.44117)
		(end 201.158348 -268.06906)
		(width 0.18288)
		(layer "In11.Cu")
		(net "M_H_CPU1_SA_CS_N<1>")
	)
	(segment
		(start 190.684404 -265.881612)
		(end 189.365636 -265.881612)
		(width 0.18288)
		(layer "In11.Cu")
		(net "M_H_CPU1_SA_CS_N<1>")
	)
	(segment
		(start 189.365636 -265.881612)
		(end 189.22492 -265.740896)
		(width 0.18288)
		(layer "In11.Cu")
		(net "M_H_CPU1_SA_CS_N<1>")
	)
	(segment
		(start 189.22492 -265.740896)
		(end 187.438538 -265.740896)
		(width 0.18288)
		(layer "In11.Cu")
		(net "M_H_CPU1_SA_CS_N<1>")
	)
	(segment
		(start 183.00065 -266.590526)
		(end 182.795418 -266.385294)
		(width 0.18288)
		(layer "In11.Cu")
		(net "M_H_CPU1_SA_CS_N<1>")
	)
	(segment
		(start 201.158348 -267.802868)
		(end 200.800462 -267.444982)
		(width 0.18288)
		(layer "In11.Cu")
		(net "M_H_CPU1_SA_CS_N<1>")
	)
	(segment
		(start 168.184068 -265.864086)
		(end 164.669724 -265.864086)
		(width 0.18288)
		(layer "In11.Cu")
		(net "M_H_CPU1_SA_CS_N<1>")
	)
	(segment
		(start 149.24532 -258.409186)
		(end 143.1925 -258.409186)
		(width 0.18288)
		(layer "In11.Cu")
		(net "M_H_CPU1_SA_CS_N<1>")
	)
	(segment
		(start 143.1925 -258.409186)
		(end 141.518386 -256.735072)
		(width 0.18288)
		(layer "In11.Cu")
		(net "M_H_CPU1_SA_CS_N<1>")
	)
	(segment
		(start 164.669724 -265.864086)
		(end 164.380926 -265.575288)
		(width 0.18288)
		(layer "In11.Cu")
		(net "M_H_CPU1_SA_CS_N<1>")
	)
	(segment
		(start 202.664822 -268.293596)
		(end 202.517248 -268.44117)
		(width 0.18288)
		(layer "In11.Cu")
		(net "M_H_CPU1_SA_CS_N<1>")
	)
	(segment
		(start 214.05088 -267.580872)
		(end 211.684108 -267.580872)
		(width 0.18288)
		(layer "In11.Cu")
		(net "M_H_CPU1_SA_CS_N<1>")
	)
	(segment
		(start 156.840428 -264.66419)
		(end 151.4856 -259.309362)
		(width 0.18288)
		(layer "In11.Cu")
		(net "M_H_CPU1_SA_CS_N<1>")
	)
	(segment
		(start 129.888996 -256.685796)
		(end 129.878582 -256.6797)
		(width 0.088646)
		(layer "In11.Cu")
		(net "M_H_CPU1_SA_CS_N<1>")
	)
	(segment
		(start 150.145496 -259.309362)
		(end 149.24532 -258.409186)
		(width 0.18288)
		(layer "In11.Cu")
		(net "M_H_CPU1_SA_CS_N<1>")
	)
	(segment
		(start 139.405868 -256.735072)
		(end 139.286996 -256.685796)
		(width 0.088646)
		(layer "In11.Cu")
		(net "M_H_CPU1_SA_CS_N<1>")
	)
	(segment
		(start 131.768596 -256.685796)
		(end 131.753864 -256.67716)
		(width 0.088646)
		(layer "In11.Cu")
		(net "M_H_CPU1_SA_CS_N<1>")
	)
	(segment
		(start 171.996354 -265.744706)
		(end 171.832778 -265.58113)
		(width 0.18288)
		(layer "In11.Cu")
		(net "M_H_CPU1_SA_CS_N<1>")
	)
	(segment
		(start 171.832778 -265.58113)
		(end 168.467024 -265.58113)
		(width 0.18288)
		(layer "In11.Cu")
		(net "M_H_CPU1_SA_CS_N<1>")
	)
	(segment
		(start 159.73298 -265.96848)
		(end 158.42869 -264.66419)
		(width 0.18288)
		(layer "In11.Cu")
		(net "M_H_CPU1_SA_CS_N<1>")
	)
	(segment
		(start 200.800462 -267.444982)
		(end 199.01027 -267.444982)
		(width 0.18288)
		(layer "In11.Cu")
		(net "M_H_CPU1_SA_CS_N<1>")
	)
	(segment
		(start 193.073782 -266.765786)
		(end 192.89903 -266.591034)
		(width 0.18288)
		(layer "In11.Cu")
		(net "M_H_CPU1_SA_CS_N<1>")
	)
	(segment
		(start 201.158348 -268.06906)
		(end 201.158348 -267.802868)
		(width 0.18288)
		(layer "In11.Cu")
		(net "M_H_CPU1_SA_CS_N<1>")
	)
	(segment
		(start 187.259976 -265.562334)
		(end 186.355228 -265.562334)
		(width 0.18288)
		(layer "In11.Cu")
		(net "M_H_CPU1_SA_CS_N<1>")
	)
	(segment
		(start 204.048106 -267.625068)
		(end 203.379578 -268.293596)
		(width 0.18288)
		(layer "In11.Cu")
		(net "M_H_CPU1_SA_CS_N<1>")
	)
	(segment
		(start 198.019924 -266.454636)
		(end 195.123816 -266.454636)
		(width 0.18288)
		(layer "In11.Cu")
		(net "M_H_CPU1_SA_CS_N<1>")
	)
	(segment
		(start 130.828796 -256.685796)
		(end 130.814064 -256.67716)
		(width 0.088646)
		(layer "In11.Cu")
		(net "M_H_CPU1_SA_CS_N<1>")
	)
	(segment
		(start 161.583624 -265.575288)
		(end 161.190432 -265.96848)
		(width 0.18288)
		(layer "In11.Cu")
		(net "M_H_CPU1_SA_CS_N<1>")
	)
	(segment
		(start 199.01027 -267.444982)
		(end 198.019924 -266.454636)
		(width 0.18288)
		(layer "In11.Cu")
		(net "M_H_CPU1_SA_CS_N<1>")
	)
	(segment
		(start 127.069596 -256.685796)
		(end 127.054864 -256.67716)
		(width 0.088646)
		(layer "In11.Cu")
		(net "M_H_CPU1_SA_CS_N<1>")
	)
	(segment
		(start 202.517248 -268.44117)
		(end 201.530458 -268.44117)
		(width 0.18288)
		(layer "In11.Cu")
		(net "M_H_CPU1_SA_CS_N<1>")
	)
	(segment
		(start 211.684108 -267.580872)
		(end 211.542376 -267.43914)
		(width 0.18288)
		(layer "In11.Cu")
		(net "M_H_CPU1_SA_CS_N<1>")
	)
	(segment
		(start 206.753968 -267.43914)
		(end 206.56804 -267.625068)
		(width 0.18288)
		(layer "In11.Cu")
		(net "M_H_CPU1_SA_CS_N<1>")
	)
	(segment
		(start 206.56804 -267.625068)
		(end 204.048106 -267.625068)
		(width 0.18288)
		(layer "In11.Cu")
		(net "M_H_CPU1_SA_CS_N<1>")
	)
	(segment
		(start 185.327036 -266.590526)
		(end 183.00065 -266.590526)
		(width 0.18288)
		(layer "In11.Cu")
		(net "M_H_CPU1_SA_CS_N<1>")
	)
	(segment
		(start 128.94945 -256.685796)
		(end 128.939036 -256.6797)
		(width 0.088646)
		(layer "In11.Cu")
		(net "M_H_CPU1_SA_CS_N<1>")
	)
	(segment
		(start 141.518386 -256.735072)
		(end 140.18895 -256.735072)
		(width 0.18288)
		(layer "In11.Cu")
		(net "M_H_CPU1_SA_CS_N<1>")
	)
	(segment
		(start 125.516894 -256.41935)
		(end 125.377194 -256.361438)
		(width 0.088646)
		(layer "In11.Cu")
		(net "M_H_CPU1_SA_CS_N<1>")
	)
	(segment
		(start 194.812666 -266.765786)
		(end 193.073782 -266.765786)
		(width 0.18288)
		(layer "In11.Cu")
		(net "M_H_CPU1_SA_CS_N<1>")
	)
	(segment
		(start 140.18895 -256.735072)
		(end 139.405868 -256.735072)
		(width 0.088646)
		(layer "In11.Cu")
		(net "M_H_CPU1_SA_CS_N<1>")
	)
	(segment
		(start 214.615014 -267.016738)
		(end 214.05088 -267.580872)
		(width 0.18288)
		(layer "In11.Cu")
		(net "M_H_CPU1_SA_CS_N<1>")
	)
	(segment
		(start 203.379578 -268.293596)
		(end 202.664822 -268.293596)
		(width 0.18288)
		(layer "In11.Cu")
		(net "M_H_CPU1_SA_CS_N<1>")
	)
	(segment
		(start 179.92598 -266.595098)
		(end 176.31029 -266.595098)
		(width 0.18288)
		(layer "In11.Cu")
		(net "M_H_CPU1_SA_CS_N<1>")
	)
	(segment
		(start 168.467024 -265.58113)
		(end 168.184068 -265.864086)
		(width 0.18288)
		(layer "In11.Cu")
		(net "M_H_CPU1_SA_CS_N<1>")
	)
	(segment
		(start 211.542376 -267.43914)
		(end 206.753968 -267.43914)
		(width 0.18288)
		(layer "In11.Cu")
		(net "M_H_CPU1_SA_CS_N<1>")
	)
	(segment
		(start 191.393826 -266.591034)
		(end 190.684404 -265.881612)
		(width 0.18288)
		(layer "In11.Cu")
		(net "M_H_CPU1_SA_CS_N<1>")
	)
	(segment
		(start 176.31029 -266.595098)
		(end 175.459898 -265.744706)
		(width 0.18288)
		(layer "In11.Cu")
		(net "M_H_CPU1_SA_CS_N<1>")
	)
	(segment
		(start 195.123816 -266.454636)
		(end 194.812666 -266.765786)
		(width 0.18288)
		(layer "In11.Cu")
		(net "M_H_CPU1_SA_CS_N<1>")
	)
	(segment
		(start 151.4856 -259.309362)
		(end 150.145496 -259.309362)
		(width 0.18288)
		(layer "In11.Cu")
		(net "M_H_CPU1_SA_CS_N<1>")
	)
	(segment
		(start 187.438538 -265.740896)
		(end 187.259976 -265.562334)
		(width 0.18288)
		(layer "In11.Cu")
		(net "M_H_CPU1_SA_CS_N<1>")
	)
	(arc
		(start 131.753864 -256.67716)
		(mid 131.477389 -256.60984)
		(end 131.203192 -256.685796)
		(width 0.088646)
		(layer "In11.Cu")
		(net "M_H_CPU1_SA_CS_N<1>")
	)
	(arc
		(start 133.082792 -256.685796)
		(mid 132.895594 -256.735939)
		(end 132.708396 -256.685796)
		(width 0.088646)
		(layer "In11.Cu")
		(net "M_H_CPU1_SA_CS_N<1>")
	)
	(arc
		(start 128.939036 -256.6797)
		(mid 128.660604 -256.609854)
		(end 128.383792 -256.685796)
		(width 0.088646)
		(layer "In11.Cu")
		(net "M_H_CPU1_SA_CS_N<1>")
	)
	(arc
		(start 136.841992 -256.685796)
		(mid 136.654794 -256.735939)
		(end 136.467596 -256.685796)
		(width 0.088646)
		(layer "In11.Cu")
		(net "M_H_CPU1_SA_CS_N<1>")
	)
	(arc
		(start 134.962392 -256.685796)
		(mid 134.775194 -256.735939)
		(end 134.587996 -256.685796)
		(width 0.088646)
		(layer "In11.Cu")
		(net "M_H_CPU1_SA_CS_N<1>")
	)
	(arc
		(start 126.129796 -256.685796)
		(mid 125.972831 -256.624182)
		(end 125.804676 -256.611628)
		(width 0.088646)
		(layer "In11.Cu")
		(net "M_H_CPU1_SA_CS_N<1>")
	)
	(arc
		(start 137.781792 -256.685796)
		(mid 137.594594 -256.735939)
		(end 137.407396 -256.685796)
		(width 0.088646)
		(layer "In11.Cu")
		(net "M_H_CPU1_SA_CS_N<1>")
	)
	(arc
		(start 136.467596 -256.685796)
		(mid 136.184894 -256.61002)
		(end 135.902192 -256.685796)
		(width 0.088646)
		(layer "In11.Cu")
		(net "M_H_CPU1_SA_CS_N<1>")
	)
	(arc
		(start 138.347196 -256.685796)
		(mid 138.064494 -256.61002)
		(end 137.781792 -256.685796)
		(width 0.088646)
		(layer "In11.Cu")
		(net "M_H_CPU1_SA_CS_N<1>")
	)
	(arc
		(start 129.323846 -256.685796)
		(mid 129.136648 -256.735939)
		(end 128.94945 -256.685796)
		(width 0.088646)
		(layer "In11.Cu")
		(net "M_H_CPU1_SA_CS_N<1>")
	)
	(arc
		(start 135.527796 -256.685796)
		(mid 135.245094 -256.61002)
		(end 134.962392 -256.685796)
		(width 0.088646)
		(layer "In11.Cu")
		(net "M_H_CPU1_SA_CS_N<1>")
	)
	(arc
		(start 131.203192 -256.685796)
		(mid 131.015994 -256.735939)
		(end 130.828796 -256.685796)
		(width 0.088646)
		(layer "In11.Cu")
		(net "M_H_CPU1_SA_CS_N<1>")
	)
	(arc
		(start 129.878582 -256.6797)
		(mid 129.600404 -256.609977)
		(end 129.323846 -256.685796)
		(width 0.088646)
		(layer "In11.Cu")
		(net "M_H_CPU1_SA_CS_N<1>")
	)
	(arc
		(start 139.286996 -256.685796)
		(mid 139.004294 -256.61002)
		(end 138.721592 -256.685796)
		(width 0.088646)
		(layer "In11.Cu")
		(net "M_H_CPU1_SA_CS_N<1>")
	)
	(arc
		(start 135.902192 -256.685796)
		(mid 135.714994 -256.735939)
		(end 135.527796 -256.685796)
		(width 0.088646)
		(layer "In11.Cu")
		(net "M_H_CPU1_SA_CS_N<1>")
	)
	(arc
		(start 134.022592 -256.685796)
		(mid 133.835394 -256.735939)
		(end 133.648196 -256.685796)
		(width 0.088646)
		(layer "In11.Cu")
		(net "M_H_CPU1_SA_CS_N<1>")
	)
	(arc
		(start 132.142992 -256.685796)
		(mid 131.955794 -256.735939)
		(end 131.768596 -256.685796)
		(width 0.088646)
		(layer "In11.Cu")
		(net "M_H_CPU1_SA_CS_N<1>")
	)
	(arc
		(start 138.721592 -256.685796)
		(mid 138.534394 -256.735939)
		(end 138.347196 -256.685796)
		(width 0.088646)
		(layer "In11.Cu")
		(net "M_H_CPU1_SA_CS_N<1>")
	)
	(arc
		(start 133.633464 -256.67716)
		(mid 133.356989 -256.60984)
		(end 133.082792 -256.685796)
		(width 0.088646)
		(layer "In11.Cu")
		(net "M_H_CPU1_SA_CS_N<1>")
	)
	(arc
		(start 127.443992 -256.685796)
		(mid 127.256794 -256.735939)
		(end 127.069596 -256.685796)
		(width 0.088646)
		(layer "In11.Cu")
		(net "M_H_CPU1_SA_CS_N<1>")
	)
	(arc
		(start 130.814064 -256.67716)
		(mid 130.537589 -256.60984)
		(end 130.263392 -256.685796)
		(width 0.088646)
		(layer "In11.Cu")
		(net "M_H_CPU1_SA_CS_N<1>")
	)
	(arc
		(start 127.054864 -256.67716)
		(mid 126.778389 -256.60984)
		(end 126.504192 -256.685796)
		(width 0.088646)
		(layer "In11.Cu")
		(net "M_H_CPU1_SA_CS_N<1>")
	)
	(arc
		(start 128.383792 -256.685796)
		(mid 128.196594 -256.735939)
		(end 128.009396 -256.685796)
		(width 0.088646)
		(layer "In11.Cu")
		(net "M_H_CPU1_SA_CS_N<1>")
	)
	(arc
		(start 130.263392 -256.685796)
		(mid 130.076194 -256.735939)
		(end 129.888996 -256.685796)
		(width 0.088646)
		(layer "In11.Cu")
		(net "M_H_CPU1_SA_CS_N<1>")
	)
	(arc
		(start 132.708396 -256.685796)
		(mid 132.425694 -256.61002)
		(end 132.142992 -256.685796)
		(width 0.088646)
		(layer "In11.Cu")
		(net "M_H_CPU1_SA_CS_N<1>")
	)
	(arc
		(start 128.009396 -256.685796)
		(mid 127.726694 -256.61002)
		(end 127.443992 -256.685796)
		(width 0.088646)
		(layer "In11.Cu")
		(net "M_H_CPU1_SA_CS_N<1>")
	)
	(arc
		(start 126.504192 -256.685796)
		(mid 126.316994 -256.735939)
		(end 126.129796 -256.685796)
		(width 0.088646)
		(layer "In11.Cu")
		(net "M_H_CPU1_SA_CS_N<1>")
	)
	(arc
		(start 137.407396 -256.685796)
		(mid 137.124694 -256.61002)
		(end 136.841992 -256.685796)
		(width 0.088646)
		(layer "In11.Cu")
		(net "M_H_CPU1_SA_CS_N<1>")
	)
	(arc
		(start 134.587996 -256.685796)
		(mid 134.305294 -256.61002)
		(end 134.022592 -256.685796)
		(width 0.088646)
		(layer "In11.Cu")
		(net "M_H_CPU1_SA_CS_N<1>")
	)
	(segment
		(start 124.907294 -256.639314)
		(end 124.907294 -257.175254)
		(width 0.20066)
		(layer "F.Cu")
		(net "M_H_CPU1_SA_CS_N<0>")
	)
	(segment
		(start 211.619846 -267.866622)
		(end 210.514946 -267.866622)
		(width 0.20066)
		(layer "F.Cu")
		(net "M_H_CPU1_SA_CS_N<0>")
	)
	(segment
		(start 141.375384 -257.08102)
		(end 140.18895 -257.08102)
		(width 0.18288)
		(layer "In11.Cu")
		(net "M_H_CPU1_SA_CS_N<0>")
	)
	(segment
		(start 176.33188 -267.44168)
		(end 175.31969 -266.42949)
		(width 0.18288)
		(layer "In11.Cu")
		(net "M_H_CPU1_SA_CS_N<0>")
	)
	(segment
		(start 157.20695 -265.757152)
		(end 151.327104 -259.877306)
		(width 0.18288)
		(layer "In11.Cu")
		(net "M_H_CPU1_SA_CS_N<0>")
	)
	(segment
		(start 198.921878 -268.28369)
		(end 196.944234 -268.28369)
		(width 0.18288)
		(layer "In11.Cu")
		(net "M_H_CPU1_SA_CS_N<0>")
	)
	(segment
		(start 179.177442 -267.27023)
		(end 178.366928 -267.27023)
		(width 0.18288)
		(layer "In11.Cu")
		(net "M_H_CPU1_SA_CS_N<0>")
	)
	(segment
		(start 124.53747 -257.118104)
		(end 124.59462 -257.175254)
		(width 0.088646)
		(layer "In11.Cu")
		(net "M_H_CPU1_SA_CS_N<0>")
	)
	(segment
		(start 200.713594 -268.435836)
		(end 199.074024 -268.435836)
		(width 0.18288)
		(layer "In11.Cu")
		(net "M_H_CPU1_SA_CS_N<0>")
	)
	(segment
		(start 139.421616 -257.08102)
		(end 139.191492 -256.850896)
		(width 0.088646)
		(layer "In11.Cu")
		(net "M_H_CPU1_SA_CS_N<0>")
	)
	(segment
		(start 178.195478 -267.44168)
		(end 176.33188 -267.44168)
		(width 0.18288)
		(layer "In11.Cu")
		(net "M_H_CPU1_SA_CS_N<0>")
	)
	(segment
		(start 124.59462 -257.175254)
		(end 124.907294 -257.175254)
		(width 0.088646)
		(layer "In11.Cu")
		(net "M_H_CPU1_SA_CS_N<0>")
	)
	(segment
		(start 186.979814 -266.591034)
		(end 186.126628 -267.44422)
		(width 0.18288)
		(layer "In11.Cu")
		(net "M_H_CPU1_SA_CS_N<0>")
	)
	(segment
		(start 178.366928 -267.27023)
		(end 178.195478 -267.44168)
		(width 0.18288)
		(layer "In11.Cu")
		(net "M_H_CPU1_SA_CS_N<0>")
	)
	(segment
		(start 196.751194 -267.305536)
		(end 196.558154 -267.112496)
		(width 0.18288)
		(layer "In11.Cu")
		(net "M_H_CPU1_SA_CS_N<0>")
	)
	(segment
		(start 202.328018 -269.142972)
		(end 202.154536 -268.96949)
		(width 0.18288)
		(layer "In11.Cu")
		(net "M_H_CPU1_SA_CS_N<0>")
	)
	(segment
		(start 126.044706 -256.856992)
		(end 126.034292 -256.850896)
		(width 0.088646)
		(layer "In11.Cu")
		(net "M_H_CPU1_SA_CS_N<0>")
	)
	(segment
		(start 196.944234 -268.28369)
		(end 196.751194 -268.09065)
		(width 0.18288)
		(layer "In11.Cu")
		(net "M_H_CPU1_SA_CS_N<0>")
	)
	(segment
		(start 202.154536 -268.96949)
		(end 201.247248 -268.96949)
		(width 0.18288)
		(layer "In11.Cu")
		(net "M_H_CPU1_SA_CS_N<0>")
	)
	(segment
		(start 193.044318 -267.442696)
		(end 191.420496 -267.442696)
		(width 0.18288)
		(layer "In11.Cu")
		(net "M_H_CPU1_SA_CS_N<0>")
	)
	(segment
		(start 133.56336 -256.856992)
		(end 133.552946 -256.850896)
		(width 0.088646)
		(layer "In11.Cu")
		(net "M_H_CPU1_SA_CS_N<0>")
	)
	(segment
		(start 161.14903 -266.577826)
		(end 159.605726 -266.577826)
		(width 0.18288)
		(layer "In11.Cu")
		(net "M_H_CPU1_SA_CS_N<0>")
	)
	(segment
		(start 129.808478 -256.859532)
		(end 129.793746 -256.850896)
		(width 0.088646)
		(layer "In11.Cu")
		(net "M_H_CPU1_SA_CS_N<0>")
	)
	(segment
		(start 132.623306 -256.856992)
		(end 132.612892 -256.850896)
		(width 0.088646)
		(layer "In11.Cu")
		(net "M_H_CPU1_SA_CS_N<0>")
	)
	(segment
		(start 149.019514 -258.75488)
		(end 143.049244 -258.75488)
		(width 0.18288)
		(layer "In11.Cu")
		(net "M_H_CPU1_SA_CS_N<0>")
	)
	(segment
		(start 190.424054 -266.446254)
		(end 189.461394 -266.446254)
		(width 0.18288)
		(layer "In11.Cu")
		(net "M_H_CPU1_SA_CS_N<0>")
	)
	(segment
		(start 204.479398 -268.14145)
		(end 203.477876 -269.142972)
		(width 0.18288)
		(layer "In11.Cu")
		(net "M_H_CPU1_SA_CS_N<0>")
	)
	(segment
		(start 199.074024 -268.435836)
		(end 198.921878 -268.28369)
		(width 0.18288)
		(layer "In11.Cu")
		(net "M_H_CPU1_SA_CS_N<0>")
	)
	(segment
		(start 159.605726 -266.577826)
		(end 158.785052 -265.757152)
		(width 0.18288)
		(layer "In11.Cu")
		(net "M_H_CPU1_SA_CS_N<0>")
	)
	(segment
		(start 186.126628 -267.44422)
		(end 179.351432 -267.44422)
		(width 0.18288)
		(layer "In11.Cu")
		(net "M_H_CPU1_SA_CS_N<0>")
	)
	(segment
		(start 194.291204 -267.35151)
		(end 193.135504 -267.35151)
		(width 0.18288)
		(layer "In11.Cu")
		(net "M_H_CPU1_SA_CS_N<0>")
	)
	(segment
		(start 196.047614 -267.305536)
		(end 196.047614 -268.09065)
		(width 0.18288)
		(layer "In11.Cu")
		(net "M_H_CPU1_SA_CS_N<0>")
	)
	(segment
		(start 158.785052 -265.757152)
		(end 157.20695 -265.757152)
		(width 0.18288)
		(layer "In11.Cu")
		(net "M_H_CPU1_SA_CS_N<0>")
	)
	(segment
		(start 164.025834 -266.7381)
		(end 161.309304 -266.7381)
		(width 0.18288)
		(layer "In11.Cu")
		(net "M_H_CPU1_SA_CS_N<0>")
	)
	(segment
		(start 172.041058 -266.799568)
		(end 169.192448 -266.799568)
		(width 0.18288)
		(layer "In11.Cu")
		(net "M_H_CPU1_SA_CS_N<0>")
	)
	(segment
		(start 174.060358 -266.590526)
		(end 172.2501 -266.590526)
		(width 0.18288)
		(layer "In11.Cu")
		(net "M_H_CPU1_SA_CS_N<0>")
	)
	(segment
		(start 143.049244 -258.75488)
		(end 141.375384 -257.08102)
		(width 0.18288)
		(layer "In11.Cu")
		(net "M_H_CPU1_SA_CS_N<0>")
	)
	(segment
		(start 175.31969 -266.42949)
		(end 174.221394 -266.42949)
		(width 0.18288)
		(layer "In11.Cu")
		(net "M_H_CPU1_SA_CS_N<0>")
	)
	(segment
		(start 127.924306 -256.856992)
		(end 127.913892 -256.850896)
		(width 0.088646)
		(layer "In11.Cu")
		(net "M_H_CPU1_SA_CS_N<0>")
	)
	(segment
		(start 189.461394 -266.446254)
		(end 189.316614 -266.591034)
		(width 0.18288)
		(layer "In11.Cu")
		(net "M_H_CPU1_SA_CS_N<0>")
	)
	(segment
		(start 205.974442 -268.14145)
		(end 204.479398 -268.14145)
		(width 0.18288)
		(layer "In11.Cu")
		(net "M_H_CPU1_SA_CS_N<0>")
	)
	(segment
		(start 196.751194 -268.09065)
		(end 196.751194 -267.305536)
		(width 0.18288)
		(layer "In11.Cu")
		(net "M_H_CPU1_SA_CS_N<0>")
	)
	(segment
		(start 196.558154 -267.112496)
		(end 196.240654 -267.112496)
		(width 0.18288)
		(layer "In11.Cu")
		(net "M_H_CPU1_SA_CS_N<0>")
	)
	(segment
		(start 206.129128 -268.296136)
		(end 205.974442 -268.14145)
		(width 0.18288)
		(layer "In11.Cu")
		(net "M_H_CPU1_SA_CS_N<0>")
	)
	(segment
		(start 203.477876 -269.142972)
		(end 202.328018 -269.142972)
		(width 0.18288)
		(layer "In11.Cu")
		(net "M_H_CPU1_SA_CS_N<0>")
	)
	(segment
		(start 191.420496 -267.442696)
		(end 190.424054 -266.446254)
		(width 0.18288)
		(layer "In11.Cu")
		(net "M_H_CPU1_SA_CS_N<0>")
	)
	(segment
		(start 189.316614 -266.591034)
		(end 186.979814 -266.591034)
		(width 0.18288)
		(layer "In11.Cu")
		(net "M_H_CPU1_SA_CS_N<0>")
	)
	(segment
		(start 161.309304 -266.7381)
		(end 161.14903 -266.577826)
		(width 0.18288)
		(layer "In11.Cu")
		(net "M_H_CPU1_SA_CS_N<0>")
	)
	(segment
		(start 130.748278 -256.859532)
		(end 130.733546 -256.850896)
		(width 0.088646)
		(layer "In11.Cu")
		(net "M_H_CPU1_SA_CS_N<0>")
	)
	(segment
		(start 179.351432 -267.44422)
		(end 179.177442 -267.27023)
		(width 0.18288)
		(layer "In11.Cu")
		(net "M_H_CPU1_SA_CS_N<0>")
	)
	(segment
		(start 169.192448 -266.799568)
		(end 168.970706 -266.577826)
		(width 0.18288)
		(layer "In11.Cu")
		(net "M_H_CPU1_SA_CS_N<0>")
	)
	(segment
		(start 193.135504 -267.35151)
		(end 193.044318 -267.442696)
		(width 0.18288)
		(layer "In11.Cu")
		(net "M_H_CPU1_SA_CS_N<0>")
	)
	(segment
		(start 168.970706 -266.577826)
		(end 164.186108 -266.577826)
		(width 0.18288)
		(layer "In11.Cu")
		(net "M_H_CPU1_SA_CS_N<0>")
	)
	(segment
		(start 210.514946 -268.007084)
		(end 210.447128 -268.17066)
		(width 0.18288)
		(layer "In11.Cu")
		(net "M_H_CPU1_SA_CS_N<0>")
	)
	(segment
		(start 174.221394 -266.42949)
		(end 174.060358 -266.590526)
		(width 0.18288)
		(layer "In11.Cu")
		(net "M_H_CPU1_SA_CS_N<0>")
	)
	(segment
		(start 196.240654 -267.112496)
		(end 196.047614 -267.305536)
		(width 0.18288)
		(layer "In11.Cu")
		(net "M_H_CPU1_SA_CS_N<0>")
	)
	(segment
		(start 196.047614 -268.09065)
		(end 195.846954 -268.29131)
		(width 0.18288)
		(layer "In11.Cu")
		(net "M_H_CPU1_SA_CS_N<0>")
	)
	(segment
		(start 151.327104 -259.877306)
		(end 150.14194 -259.877306)
		(width 0.18288)
		(layer "In11.Cu")
		(net "M_H_CPU1_SA_CS_N<0>")
	)
	(segment
		(start 126.98476 -256.856992)
		(end 126.9746 -256.850896)
		(width 0.088646)
		(layer "In11.Cu")
		(net "M_H_CPU1_SA_CS_N<0>")
	)
	(segment
		(start 210.447128 -268.17066)
		(end 210.321652 -268.296136)
		(width 0.18288)
		(layer "In11.Cu")
		(net "M_H_CPU1_SA_CS_N<0>")
	)
	(segment
		(start 164.186108 -266.577826)
		(end 164.025834 -266.7381)
		(width 0.18288)
		(layer "In11.Cu")
		(net "M_H_CPU1_SA_CS_N<0>")
	)
	(segment
		(start 195.846954 -268.29131)
		(end 195.231004 -268.29131)
		(width 0.18288)
		(layer "In11.Cu")
		(net "M_H_CPU1_SA_CS_N<0>")
	)
	(segment
		(start 195.231004 -268.29131)
		(end 194.291204 -267.35151)
		(width 0.18288)
		(layer "In11.Cu")
		(net "M_H_CPU1_SA_CS_N<0>")
	)
	(segment
		(start 172.2501 -266.590526)
		(end 172.041058 -266.799568)
		(width 0.18288)
		(layer "In11.Cu")
		(net "M_H_CPU1_SA_CS_N<0>")
	)
	(segment
		(start 131.68376 -256.856992)
		(end 131.673346 -256.850896)
		(width 0.088646)
		(layer "In11.Cu")
		(net "M_H_CPU1_SA_CS_N<0>")
	)
	(segment
		(start 140.18895 -257.08102)
		(end 139.421616 -257.08102)
		(width 0.088646)
		(layer "In11.Cu")
		(net "M_H_CPU1_SA_CS_N<0>")
	)
	(segment
		(start 201.247248 -268.96949)
		(end 200.713594 -268.435836)
		(width 0.18288)
		(layer "In11.Cu")
		(net "M_H_CPU1_SA_CS_N<0>")
	)
	(segment
		(start 210.321652 -268.296136)
		(end 206.129128 -268.296136)
		(width 0.18288)
		(layer "In11.Cu")
		(net "M_H_CPU1_SA_CS_N<0>")
	)
	(segment
		(start 210.514946 -267.866622)
		(end 210.514946 -268.007084)
		(width 0.18288)
		(layer "In11.Cu")
		(net "M_H_CPU1_SA_CS_N<0>")
	)
	(segment
		(start 150.14194 -259.877306)
		(end 149.019514 -258.75488)
		(width 0.18288)
		(layer "In11.Cu")
		(net "M_H_CPU1_SA_CS_N<0>")
	)
	(arc
		(start 131.673346 -256.850896)
		(mid 131.486148 -256.800753)
		(end 131.29895 -256.850896)
		(width 0.088646)
		(layer "In11.Cu")
		(net "M_H_CPU1_SA_CS_N<0>")
	)
	(arc
		(start 127.539496 -256.850896)
		(mid 127.262937 -256.926639)
		(end 126.98476 -256.856992)
		(width 0.088646)
		(layer "In11.Cu")
		(net "M_H_CPU1_SA_CS_N<0>")
	)
	(arc
		(start 128.853946 -256.850896)
		(mid 128.666748 -256.800753)
		(end 128.47955 -256.850896)
		(width 0.088646)
		(layer "In11.Cu")
		(net "M_H_CPU1_SA_CS_N<0>")
	)
	(arc
		(start 129.793746 -256.850896)
		(mid 129.606548 -256.800753)
		(end 129.41935 -256.850896)
		(width 0.088646)
		(layer "In11.Cu")
		(net "M_H_CPU1_SA_CS_N<0>")
	)
	(arc
		(start 138.251692 -256.850896)
		(mid 138.064494 -256.800753)
		(end 137.877296 -256.850896)
		(width 0.088646)
		(layer "In11.Cu")
		(net "M_H_CPU1_SA_CS_N<0>")
	)
	(arc
		(start 131.29895 -256.850896)
		(mid 131.024751 -256.926731)
		(end 130.748278 -256.859532)
		(width 0.088646)
		(layer "In11.Cu")
		(net "M_H_CPU1_SA_CS_N<0>")
	)
	(arc
		(start 137.311892 -256.850896)
		(mid 137.124694 -256.800753)
		(end 136.937496 -256.850896)
		(width 0.088646)
		(layer "In11.Cu")
		(net "M_H_CPU1_SA_CS_N<0>")
	)
	(arc
		(start 125.659896 -256.850896)
		(mid 125.377194 -256.926672)
		(end 125.094492 -256.850896)
		(width 0.088646)
		(layer "In11.Cu")
		(net "M_H_CPU1_SA_CS_N<0>")
	)
	(arc
		(start 136.372092 -256.850896)
		(mid 136.184894 -256.800753)
		(end 135.997696 -256.850896)
		(width 0.088646)
		(layer "In11.Cu")
		(net "M_H_CPU1_SA_CS_N<0>")
	)
	(arc
		(start 128.47955 -256.850896)
		(mid 128.202737 -256.926766)
		(end 127.924306 -256.856992)
		(width 0.088646)
		(layer "In11.Cu")
		(net "M_H_CPU1_SA_CS_N<0>")
	)
	(arc
		(start 134.118096 -256.850896)
		(mid 133.841537 -256.926639)
		(end 133.56336 -256.856992)
		(width 0.088646)
		(layer "In11.Cu")
		(net "M_H_CPU1_SA_CS_N<0>")
	)
	(arc
		(start 135.997696 -256.850896)
		(mid 135.714994 -256.926672)
		(end 135.432292 -256.850896)
		(width 0.088646)
		(layer "In11.Cu")
		(net "M_H_CPU1_SA_CS_N<0>")
	)
	(arc
		(start 130.35915 -256.850896)
		(mid 130.084951 -256.926731)
		(end 129.808478 -256.859532)
		(width 0.088646)
		(layer "In11.Cu")
		(net "M_H_CPU1_SA_CS_N<0>")
	)
	(arc
		(start 126.59995 -256.850896)
		(mid 126.323137 -256.926766)
		(end 126.044706 -256.856992)
		(width 0.088646)
		(layer "In11.Cu")
		(net "M_H_CPU1_SA_CS_N<0>")
	)
	(arc
		(start 135.057896 -256.850896)
		(mid 134.775194 -256.926672)
		(end 134.492492 -256.850896)
		(width 0.088646)
		(layer "In11.Cu")
		(net "M_H_CPU1_SA_CS_N<0>")
	)
	(arc
		(start 125.094492 -256.850896)
		(mid 124.907294 -256.800753)
		(end 124.720096 -256.850896)
		(width 0.088646)
		(layer "In11.Cu")
		(net "M_H_CPU1_SA_CS_N<0>")
	)
	(arc
		(start 136.937496 -256.850896)
		(mid 136.654794 -256.926672)
		(end 136.372092 -256.850896)
		(width 0.088646)
		(layer "In11.Cu")
		(net "M_H_CPU1_SA_CS_N<0>")
	)
	(arc
		(start 126.034292 -256.850896)
		(mid 125.847094 -256.800753)
		(end 125.659896 -256.850896)
		(width 0.088646)
		(layer "In11.Cu")
		(net "M_H_CPU1_SA_CS_N<0>")
	)
	(arc
		(start 138.817096 -256.850896)
		(mid 138.534394 -256.926672)
		(end 138.251692 -256.850896)
		(width 0.088646)
		(layer "In11.Cu")
		(net "M_H_CPU1_SA_CS_N<0>")
	)
	(arc
		(start 132.612892 -256.850896)
		(mid 132.425694 -256.800753)
		(end 132.238496 -256.850896)
		(width 0.088646)
		(layer "In11.Cu")
		(net "M_H_CPU1_SA_CS_N<0>")
	)
	(arc
		(start 129.41935 -256.850896)
		(mid 129.136648 -256.926672)
		(end 128.853946 -256.850896)
		(width 0.088646)
		(layer "In11.Cu")
		(net "M_H_CPU1_SA_CS_N<0>")
	)
	(arc
		(start 124.720096 -256.850896)
		(mid 124.598428 -256.963751)
		(end 124.53747 -257.118104)
		(width 0.088646)
		(layer "In11.Cu")
		(net "M_H_CPU1_SA_CS_N<0>")
	)
	(arc
		(start 132.238496 -256.850896)
		(mid 131.961937 -256.926639)
		(end 131.68376 -256.856992)
		(width 0.088646)
		(layer "In11.Cu")
		(net "M_H_CPU1_SA_CS_N<0>")
	)
	(arc
		(start 133.17855 -256.850896)
		(mid 132.901737 -256.926766)
		(end 132.623306 -256.856992)
		(width 0.088646)
		(layer "In11.Cu")
		(net "M_H_CPU1_SA_CS_N<0>")
	)
	(arc
		(start 139.191492 -256.850896)
		(mid 139.004294 -256.800753)
		(end 138.817096 -256.850896)
		(width 0.088646)
		(layer "In11.Cu")
		(net "M_H_CPU1_SA_CS_N<0>")
	)
	(arc
		(start 137.877296 -256.850896)
		(mid 137.594594 -256.926672)
		(end 137.311892 -256.850896)
		(width 0.088646)
		(layer "In11.Cu")
		(net "M_H_CPU1_SA_CS_N<0>")
	)
	(arc
		(start 133.552946 -256.850896)
		(mid 133.365748 -256.800753)
		(end 133.17855 -256.850896)
		(width 0.088646)
		(layer "In11.Cu")
		(net "M_H_CPU1_SA_CS_N<0>")
	)
	(arc
		(start 130.733546 -256.850896)
		(mid 130.546348 -256.800753)
		(end 130.35915 -256.850896)
		(width 0.088646)
		(layer "In11.Cu")
		(net "M_H_CPU1_SA_CS_N<0>")
	)
	(arc
		(start 126.9746 -256.850896)
		(mid 126.787292 -256.800753)
		(end 126.59995 -256.850896)
		(width 0.088646)
		(layer "In11.Cu")
		(net "M_H_CPU1_SA_CS_N<0>")
	)
	(arc
		(start 134.492492 -256.850896)
		(mid 134.305294 -256.800753)
		(end 134.118096 -256.850896)
		(width 0.088646)
		(layer "In11.Cu")
		(net "M_H_CPU1_SA_CS_N<0>")
	)
	(arc
		(start 135.432292 -256.850896)
		(mid 135.245094 -256.800753)
		(end 135.057896 -256.850896)
		(width 0.088646)
		(layer "In11.Cu")
		(net "M_H_CPU1_SA_CS_N<0>")
	)
	(arc
		(start 127.913892 -256.850896)
		(mid 127.726694 -256.800753)
		(end 127.539496 -256.850896)
		(width 0.088646)
		(layer "In11.Cu")
		(net "M_H_CPU1_SA_CS_N<0>")
	)
	(segment
		(start 212.618066 -270.841724)
		(end 212.630258 -270.853916)
		(width 0.1016)
		(layer "F.Cu")
		(net "M_H_CPU1_SA_CB<7>")
	)
	(segment
		(start 214.133684 -270.164814)
		(end 214.385652 -270.416782)
		(width 0.20066)
		(layer "F.Cu")
		(net "M_H_CPU1_SA_CB<7>")
	)
	(segment
		(start 213.749636 -270.164814)
		(end 214.133684 -270.164814)
		(width 0.20066)
		(layer "F.Cu")
		(net "M_H_CPU1_SA_CB<7>")
	)
	(segment
		(start 208.176114 -270.416782)
		(end 209.874358 -270.416782)
		(width 0.20066)
		(layer "F.Cu")
		(net "M_H_CPU1_SA_CB<7>")
	)
	(segment
		(start 210.598258 -270.848836)
		(end 210.603084 -270.848836)
		(width 0.101854)
		(layer "F.Cu")
		(net "M_H_CPU1_SA_CB<7>")
	)
	(segment
		(start 213.515448 -270.399002)
		(end 213.749636 -270.164814)
		(width 0.20066)
		(layer "F.Cu")
		(net "M_H_CPU1_SA_CB<7>")
	)
	(segment
		(start 210.610196 -270.841724)
		(end 212.618066 -270.841724)
		(width 0.1016)
		(layer "F.Cu")
		(net "M_H_CPU1_SA_CB<7>")
	)
	(segment
		(start 209.874358 -270.416782)
		(end 210.306412 -270.848836)
		(width 0.20066)
		(layer "F.Cu")
		(net "M_H_CPU1_SA_CB<7>")
	)
	(segment
		(start 213.311486 -270.853916)
		(end 213.515448 -270.649954)
		(width 0.20066)
		(layer "F.Cu")
		(net "M_H_CPU1_SA_CB<7>")
	)
	(segment
		(start 210.306412 -270.848836)
		(end 210.598258 -270.848836)
		(width 0.20066)
		(layer "F.Cu")
		(net "M_H_CPU1_SA_CB<7>")
	)
	(segment
		(start 124.907548 -258.267454)
		(end 124.907548 -258.80314)
		(width 0.20066)
		(layer "F.Cu")
		(net "M_H_CPU1_SA_CB<7>")
	)
	(segment
		(start 214.385652 -270.416782)
		(end 215.719914 -270.416782)
		(width 0.20066)
		(layer "F.Cu")
		(net "M_H_CPU1_SA_CB<7>")
	)
	(segment
		(start 210.603084 -270.848836)
		(end 210.610196 -270.841724)
		(width 0.1016)
		(layer "F.Cu")
		(net "M_H_CPU1_SA_CB<7>")
	)
	(segment
		(start 212.630258 -270.853916)
		(end 213.311486 -270.853916)
		(width 0.20066)
		(layer "F.Cu")
		(net "M_H_CPU1_SA_CB<7>")
	)
	(segment
		(start 124.907294 -258.2672)
		(end 124.907548 -258.267454)
		(width 0.20066)
		(layer "F.Cu")
		(net "M_H_CPU1_SA_CB<7>")
	)
	(segment
		(start 213.515448 -270.649954)
		(end 213.515448 -270.399002)
		(width 0.20066)
		(layer "F.Cu")
		(net "M_H_CPU1_SA_CB<7>")
	)
	(segment
		(start 207.071214 -270.416782)
		(end 208.176114 -270.416782)
		(width 0.20066)
		(layer "F.Cu")
		(net "M_H_CPU1_SA_CB<7>")
	)
	(segment
		(start 187.84062 -269.990824)
		(end 187.839858 -269.991586)
		(width 0.18288)
		(layer "In11.Cu")
		(net "M_H_CPU1_SA_CB<7>")
	)
	(segment
		(start 128.009396 -258.313428)
		(end 127.998982 -258.307332)
		(width 0.088646)
		(layer "In11.Cu")
		(net "M_H_CPU1_SA_CB<7>")
	)
	(segment
		(start 206.25054 -271.236186)
		(end 205.131162 -271.236186)
		(width 0.18288)
		(layer "In11.Cu")
		(net "M_H_CPU1_SA_CB<7>")
	)
	(segment
		(start 160.32099 -269.80769)
		(end 158.288228 -269.80769)
		(width 0.18288)
		(layer "In11.Cu")
		(net "M_H_CPU1_SA_CB<7>")
	)
	(segment
		(start 133.64845 -258.313428)
		(end 133.638036 -258.307332)
		(width 0.088646)
		(layer "In11.Cu")
		(net "M_H_CPU1_SA_CB<7>")
	)
	(segment
		(start 196.843142 -271.460468)
		(end 196.843142 -270.826992)
		(width 0.18288)
		(layer "In11.Cu")
		(net "M_H_CPU1_SA_CB<7>")
	)
	(segment
		(start 205.131162 -271.236186)
		(end 204.73543 -270.840454)
		(width 0.18288)
		(layer "In11.Cu")
		(net "M_H_CPU1_SA_CB<7>")
	)
	(segment
		(start 172.235368 -270.102838)
		(end 168.48836 -270.102838)
		(width 0.18288)
		(layer "In11.Cu")
		(net "M_H_CPU1_SA_CB<7>")
	)
	(segment
		(start 164.56533 -270.114522)
		(end 163.491672 -270.114522)
		(width 0.18288)
		(layer "In11.Cu")
		(net "M_H_CPU1_SA_CB<7>")
	)
	(segment
		(start 165.599872 -269.90802)
		(end 164.771832 -269.90802)
		(width 0.18288)
		(layer "In11.Cu")
		(net "M_H_CPU1_SA_CB<7>")
	)
	(segment
		(start 176.823116 -270.844518)
		(end 176.25822 -270.844518)
		(width 0.18288)
		(layer "In11.Cu")
		(net "M_H_CPU1_SA_CB<7>")
	)
	(segment
		(start 193.6877 -271.841976)
		(end 192.688464 -270.84274)
		(width 0.18288)
		(layer "In11.Cu")
		(net "M_H_CPU1_SA_CB<7>")
	)
	(segment
		(start 135.912606 -258.307332)
		(end 135.902192 -258.313428)
		(width 0.088646)
		(layer "In11.Cu")
		(net "M_H_CPU1_SA_CB<7>")
	)
	(segment
		(start 173.529498 -269.990824)
		(end 172.75048 -269.990824)
		(width 0.18288)
		(layer "In11.Cu")
		(net "M_H_CPU1_SA_CB<7>")
	)
	(segment
		(start 207.071214 -270.416782)
		(end 206.25054 -271.236186)
		(width 0.18288)
		(layer "In11.Cu")
		(net "M_H_CPU1_SA_CB<7>")
	)
	(segment
		(start 131.76885 -258.313428)
		(end 131.758436 -258.307332)
		(width 0.088646)
		(layer "In11.Cu")
		(net "M_H_CPU1_SA_CB<7>")
	)
	(segment
		(start 163.298632 -269.275814)
		(end 163.105592 -269.082774)
		(width 0.18288)
		(layer "In11.Cu")
		(net "M_H_CPU1_SA_CB<7>")
	)
	(segment
		(start 179.532026 -270.667226)
		(end 178.445414 -270.667226)
		(width 0.18288)
		(layer "In11.Cu")
		(net "M_H_CPU1_SA_CB<7>")
	)
	(segment
		(start 139.98575 -259.411216)
		(end 139.100814 -259.411216)
		(width 0.088646)
		(layer "In11.Cu")
		(net "M_H_CPU1_SA_CB<7>")
	)
	(segment
		(start 198.390764 -271.653508)
		(end 197.036182 -271.653508)
		(width 0.18288)
		(layer "In11.Cu")
		(net "M_H_CPU1_SA_CB<7>")
	)
	(segment
		(start 191.584834 -270.84274)
		(end 191.464946 -270.962628)
		(width 0.18288)
		(layer "In11.Cu")
		(net "M_H_CPU1_SA_CB<7>")
	)
	(segment
		(start 130.828796 -258.313428)
		(end 130.814064 -258.304792)
		(width 0.088646)
		(layer "In11.Cu")
		(net "M_H_CPU1_SA_CB<7>")
	)
	(segment
		(start 178.445414 -270.667226)
		(end 178.268884 -270.843756)
		(width 0.18288)
		(layer "In11.Cu")
		(net "M_H_CPU1_SA_CB<7>")
	)
	(segment
		(start 172.749718 -269.991586)
		(end 172.34662 -269.991586)
		(width 0.18288)
		(layer "In11.Cu")
		(net "M_H_CPU1_SA_CB<7>")
	)
	(segment
		(start 196.843142 -270.826992)
		(end 196.650102 -270.633952)
		(width 0.18288)
		(layer "In11.Cu")
		(net "M_H_CPU1_SA_CB<7>")
	)
	(segment
		(start 188.342524 -269.990824)
		(end 187.84062 -269.990824)
		(width 0.18288)
		(layer "In11.Cu")
		(net "M_H_CPU1_SA_CB<7>")
	)
	(segment
		(start 162.788092 -269.082774)
		(end 162.595052 -269.275814)
		(width 0.18288)
		(layer "In11.Cu")
		(net "M_H_CPU1_SA_CB<7>")
	)
	(segment
		(start 176.823878 -270.843756)
		(end 176.823116 -270.844518)
		(width 0.18288)
		(layer "In11.Cu")
		(net "M_H_CPU1_SA_CB<7>")
	)
	(segment
		(start 158.288228 -269.80769)
		(end 158.105094 -269.990824)
		(width 0.18288)
		(layer "In11.Cu")
		(net "M_H_CPU1_SA_CB<7>")
	)
	(segment
		(start 196.650102 -270.633952)
		(end 196.332602 -270.633952)
		(width 0.18288)
		(layer "In11.Cu")
		(net "M_H_CPU1_SA_CB<7>")
	)
	(segment
		(start 162.402012 -270.114522)
		(end 160.627822 -270.114522)
		(width 0.18288)
		(layer "In11.Cu")
		(net "M_H_CPU1_SA_CB<7>")
	)
	(segment
		(start 158.105094 -269.990824)
		(end 156.550868 -269.990824)
		(width 0.18288)
		(layer "In11.Cu")
		(net "M_H_CPU1_SA_CB<7>")
	)
	(segment
		(start 196.332602 -270.633952)
		(end 196.139562 -270.826992)
		(width 0.18288)
		(layer "In11.Cu")
		(net "M_H_CPU1_SA_CB<7>")
	)
	(segment
		(start 166.689532 -269.90802)
		(end 166.496492 -269.71498)
		(width 0.18288)
		(layer "In11.Cu")
		(net "M_H_CPU1_SA_CB<7>")
	)
	(segment
		(start 196.139562 -270.826992)
		(end 196.139562 -271.460468)
		(width 0.18288)
		(layer "In11.Cu")
		(net "M_H_CPU1_SA_CB<7>")
	)
	(segment
		(start 196.139562 -271.460468)
		(end 195.946522 -271.653508)
		(width 0.18288)
		(layer "In11.Cu")
		(net "M_H_CPU1_SA_CB<7>")
	)
	(segment
		(start 195.946522 -271.653508)
		(end 195.032884 -271.653508)
		(width 0.18288)
		(layer "In11.Cu")
		(net "M_H_CPU1_SA_CB<7>")
	)
	(segment
		(start 202.202542 -270.840454)
		(end 202.16495 -270.802862)
		(width 0.18288)
		(layer "In11.Cu")
		(net "M_H_CPU1_SA_CB<7>")
	)
	(segment
		(start 168.293542 -269.90802)
		(end 166.689532 -269.90802)
		(width 0.18288)
		(layer "In11.Cu")
		(net "M_H_CPU1_SA_CB<7>")
	)
	(segment
		(start 160.627822 -270.114522)
		(end 160.32099 -269.80769)
		(width 0.18288)
		(layer "In11.Cu")
		(net "M_H_CPU1_SA_CB<7>")
	)
	(segment
		(start 182.887366 -270.895826)
		(end 179.760626 -270.895826)
		(width 0.18288)
		(layer "In11.Cu")
		(net "M_H_CPU1_SA_CB<7>")
	)
	(segment
		(start 126.129796 -258.313428)
		(end 126.119382 -258.307332)
		(width 0.088646)
		(layer "In11.Cu")
		(net "M_H_CPU1_SA_CB<7>")
	)
	(segment
		(start 204.73543 -270.840454)
		(end 202.202542 -270.840454)
		(width 0.18288)
		(layer "In11.Cu")
		(net "M_H_CPU1_SA_CB<7>")
	)
	(segment
		(start 162.595052 -269.275814)
		(end 162.595052 -269.921482)
		(width 0.18288)
		(layer "In11.Cu")
		(net "M_H_CPU1_SA_CB<7>")
	)
	(segment
		(start 194.844416 -271.841976)
		(end 193.6877 -271.841976)
		(width 0.18288)
		(layer "In11.Cu")
		(net "M_H_CPU1_SA_CB<7>")
	)
	(segment
		(start 176.25822 -270.844518)
		(end 175.299116 -269.885414)
		(width 0.18288)
		(layer "In11.Cu")
		(net "M_H_CPU1_SA_CB<7>")
	)
	(segment
		(start 197.036182 -271.653508)
		(end 196.843142 -271.460468)
		(width 0.18288)
		(layer "In11.Cu")
		(net "M_H_CPU1_SA_CB<7>")
	)
	(segment
		(start 191.464946 -270.962628)
		(end 189.314328 -270.962628)
		(width 0.18288)
		(layer "In11.Cu")
		(net "M_H_CPU1_SA_CB<7>")
	)
	(segment
		(start 163.298632 -269.921482)
		(end 163.298632 -269.275814)
		(width 0.18288)
		(layer "In11.Cu")
		(net "M_H_CPU1_SA_CB<7>")
	)
	(segment
		(start 166.496492 -269.246858)
		(end 166.303452 -269.053818)
		(width 0.18288)
		(layer "In11.Cu")
		(net "M_H_CPU1_SA_CB<7>")
	)
	(segment
		(start 156.550868 -269.990824)
		(end 147.609814 -261.04977)
		(width 0.18288)
		(layer "In11.Cu")
		(net "M_H_CPU1_SA_CB<7>")
	)
	(segment
		(start 139.100814 -259.411216)
		(end 138.05408 -258.364482)
		(width 0.088646)
		(layer "In11.Cu")
		(net "M_H_CPU1_SA_CB<7>")
	)
	(segment
		(start 187.167266 -269.991586)
		(end 187.038996 -270.119856)
		(width 0.18288)
		(layer "In11.Cu")
		(net "M_H_CPU1_SA_CB<7>")
	)
	(segment
		(start 187.839858 -269.991586)
		(end 187.167266 -269.991586)
		(width 0.18288)
		(layer "In11.Cu")
		(net "M_H_CPU1_SA_CB<7>")
	)
	(segment
		(start 179.760626 -270.895826)
		(end 179.532026 -270.667226)
		(width 0.18288)
		(layer "In11.Cu")
		(net "M_H_CPU1_SA_CB<7>")
	)
	(segment
		(start 163.491672 -270.114522)
		(end 163.298632 -269.921482)
		(width 0.18288)
		(layer "In11.Cu")
		(net "M_H_CPU1_SA_CB<7>")
	)
	(segment
		(start 163.105592 -269.082774)
		(end 162.788092 -269.082774)
		(width 0.18288)
		(layer "In11.Cu")
		(net "M_H_CPU1_SA_CB<7>")
	)
	(segment
		(start 165.792912 -269.246858)
		(end 165.792912 -269.71498)
		(width 0.18288)
		(layer "In11.Cu")
		(net "M_H_CPU1_SA_CB<7>")
	)
	(segment
		(start 138.05408 -258.364482)
		(end 137.594848 -258.364482)
		(width 0.088646)
		(layer "In11.Cu")
		(net "M_H_CPU1_SA_CB<7>")
	)
	(segment
		(start 202.16495 -270.802862)
		(end 199.24141 -270.802862)
		(width 0.18288)
		(layer "In11.Cu")
		(net "M_H_CPU1_SA_CB<7>")
	)
	(segment
		(start 164.771832 -269.90802)
		(end 164.56533 -270.114522)
		(width 0.18288)
		(layer "In11.Cu")
		(net "M_H_CPU1_SA_CB<7>")
	)
	(segment
		(start 199.24141 -270.802862)
		(end 198.390764 -271.653508)
		(width 0.18288)
		(layer "In11.Cu")
		(net "M_H_CPU1_SA_CB<7>")
	)
	(segment
		(start 173.634908 -269.885414)
		(end 173.529498 -269.990824)
		(width 0.18288)
		(layer "In11.Cu")
		(net "M_H_CPU1_SA_CB<7>")
	)
	(segment
		(start 178.268884 -270.843756)
		(end 176.823878 -270.843756)
		(width 0.18288)
		(layer "In11.Cu")
		(net "M_H_CPU1_SA_CB<7>")
	)
	(segment
		(start 187.038996 -270.119856)
		(end 183.663336 -270.119856)
		(width 0.18288)
		(layer "In11.Cu")
		(net "M_H_CPU1_SA_CB<7>")
	)
	(segment
		(start 166.496492 -269.71498)
		(end 166.496492 -269.246858)
		(width 0.18288)
		(layer "In11.Cu")
		(net "M_H_CPU1_SA_CB<7>")
	)
	(segment
		(start 165.792912 -269.71498)
		(end 165.599872 -269.90802)
		(width 0.18288)
		(layer "In11.Cu")
		(net "M_H_CPU1_SA_CB<7>")
	)
	(segment
		(start 132.708396 -258.313428)
		(end 132.697982 -258.307332)
		(width 0.088646)
		(layer "In11.Cu")
		(net "M_H_CPU1_SA_CB<7>")
	)
	(segment
		(start 175.299116 -269.885414)
		(end 173.634908 -269.885414)
		(width 0.18288)
		(layer "In11.Cu")
		(net "M_H_CPU1_SA_CB<7>")
	)
	(segment
		(start 134.587996 -258.313428)
		(end 134.577582 -258.307332)
		(width 0.088646)
		(layer "In11.Cu")
		(net "M_H_CPU1_SA_CB<7>")
	)
	(segment
		(start 142.07744 -261.04977)
		(end 140.438886 -259.411216)
		(width 0.18288)
		(layer "In11.Cu")
		(net "M_H_CPU1_SA_CB<7>")
	)
	(segment
		(start 162.595052 -269.921482)
		(end 162.402012 -270.114522)
		(width 0.18288)
		(layer "In11.Cu")
		(net "M_H_CPU1_SA_CB<7>")
	)
	(segment
		(start 125.564646 -258.313428)
		(end 125.488446 -258.35737)
		(width 0.088646)
		(layer "In11.Cu")
		(net "M_H_CPU1_SA_CB<7>")
	)
	(segment
		(start 195.032884 -271.653508)
		(end 194.844416 -271.841976)
		(width 0.18288)
		(layer "In11.Cu")
		(net "M_H_CPU1_SA_CB<7>")
	)
	(segment
		(start 168.48836 -270.102838)
		(end 168.293542 -269.90802)
		(width 0.18288)
		(layer "In11.Cu")
		(net "M_H_CPU1_SA_CB<7>")
	)
	(segment
		(start 166.303452 -269.053818)
		(end 165.985952 -269.053818)
		(width 0.18288)
		(layer "In11.Cu")
		(net "M_H_CPU1_SA_CB<7>")
	)
	(segment
		(start 128.949196 -258.313428)
		(end 128.934464 -258.304792)
		(width 0.088646)
		(layer "In11.Cu")
		(net "M_H_CPU1_SA_CB<7>")
	)
	(segment
		(start 172.75048 -269.990824)
		(end 172.749718 -269.991586)
		(width 0.18288)
		(layer "In11.Cu")
		(net "M_H_CPU1_SA_CB<7>")
	)
	(segment
		(start 136.856978 -258.304792)
		(end 136.842246 -258.313428)
		(width 0.088646)
		(layer "In11.Cu")
		(net "M_H_CPU1_SA_CB<7>")
	)
	(segment
		(start 183.663336 -270.119856)
		(end 182.887366 -270.895826)
		(width 0.18288)
		(layer "In11.Cu")
		(net "M_H_CPU1_SA_CB<7>")
	)
	(segment
		(start 189.314328 -270.962628)
		(end 188.342524 -269.990824)
		(width 0.18288)
		(layer "In11.Cu")
		(net "M_H_CPU1_SA_CB<7>")
	)
	(segment
		(start 140.438886 -259.411216)
		(end 139.98575 -259.411216)
		(width 0.18288)
		(layer "In11.Cu")
		(net "M_H_CPU1_SA_CB<7>")
	)
	(segment
		(start 172.34662 -269.991586)
		(end 172.235368 -270.102838)
		(width 0.18288)
		(layer "In11.Cu")
		(net "M_H_CPU1_SA_CB<7>")
	)
	(segment
		(start 165.985952 -269.053818)
		(end 165.792912 -269.246858)
		(width 0.18288)
		(layer "In11.Cu")
		(net "M_H_CPU1_SA_CB<7>")
	)
	(segment
		(start 127.06985 -258.313428)
		(end 127.059436 -258.307332)
		(width 0.088646)
		(layer "In11.Cu")
		(net "M_H_CPU1_SA_CB<7>")
	)
	(segment
		(start 147.609814 -261.04977)
		(end 142.07744 -261.04977)
		(width 0.18288)
		(layer "In11.Cu")
		(net "M_H_CPU1_SA_CB<7>")
	)
	(segment
		(start 192.688464 -270.84274)
		(end 191.584834 -270.84274)
		(width 0.18288)
		(layer "In11.Cu")
		(net "M_H_CPU1_SA_CB<7>")
	)
	(arc
		(start 129.888996 -258.313428)
		(mid 129.606294 -258.237686)
		(end 129.323592 -258.313428)
		(width 0.088646)
		(layer "In11.Cu")
		(net "M_H_CPU1_SA_CB<7>")
	)
	(arc
		(start 126.119382 -258.307332)
		(mid 125.841204 -258.23764)
		(end 125.564646 -258.313428)
		(width 0.088646)
		(layer "In11.Cu")
		(net "M_H_CPU1_SA_CB<7>")
	)
	(arc
		(start 137.594848 -258.364482)
		(mid 137.497898 -258.351253)
		(end 137.40765 -258.313428)
		(width 0.088646)
		(layer "In11.Cu")
		(net "M_H_CPU1_SA_CB<7>")
	)
	(arc
		(start 128.934464 -258.304792)
		(mid 128.658023 -258.237626)
		(end 128.383792 -258.313428)
		(width 0.088646)
		(layer "In11.Cu")
		(net "M_H_CPU1_SA_CB<7>")
	)
	(arc
		(start 127.059436 -258.307332)
		(mid 126.781004 -258.237518)
		(end 126.504192 -258.313428)
		(width 0.088646)
		(layer "In11.Cu")
		(net "M_H_CPU1_SA_CB<7>")
	)
	(arc
		(start 135.902192 -258.313428)
		(mid 135.714994 -258.363571)
		(end 135.527796 -258.313428)
		(width 0.088646)
		(layer "In11.Cu")
		(net "M_H_CPU1_SA_CB<7>")
	)
	(arc
		(start 128.383792 -258.313428)
		(mid 128.196594 -258.363571)
		(end 128.009396 -258.313428)
		(width 0.088646)
		(layer "In11.Cu")
		(net "M_H_CPU1_SA_CB<7>")
	)
	(arc
		(start 131.203192 -258.313428)
		(mid 131.015994 -258.363571)
		(end 130.828796 -258.313428)
		(width 0.088646)
		(layer "In11.Cu")
		(net "M_H_CPU1_SA_CB<7>")
	)
	(arc
		(start 126.504192 -258.313428)
		(mid 126.316994 -258.363571)
		(end 126.129796 -258.313428)
		(width 0.088646)
		(layer "In11.Cu")
		(net "M_H_CPU1_SA_CB<7>")
	)
	(arc
		(start 137.40765 -258.313428)
		(mid 137.133421 -258.237503)
		(end 136.856978 -258.304792)
		(width 0.088646)
		(layer "In11.Cu")
		(net "M_H_CPU1_SA_CB<7>")
	)
	(arc
		(start 133.082792 -258.313428)
		(mid 132.895594 -258.363571)
		(end 132.708396 -258.313428)
		(width 0.088646)
		(layer "In11.Cu")
		(net "M_H_CPU1_SA_CB<7>")
	)
	(arc
		(start 132.143246 -258.313428)
		(mid 131.956048 -258.363571)
		(end 131.76885 -258.313428)
		(width 0.088646)
		(layer "In11.Cu")
		(net "M_H_CPU1_SA_CB<7>")
	)
	(arc
		(start 136.46785 -258.313428)
		(mid 136.191037 -258.237592)
		(end 135.912606 -258.307332)
		(width 0.088646)
		(layer "In11.Cu")
		(net "M_H_CPU1_SA_CB<7>")
	)
	(arc
		(start 130.814064 -258.304792)
		(mid 130.537623 -258.237626)
		(end 130.263392 -258.313428)
		(width 0.088646)
		(layer "In11.Cu")
		(net "M_H_CPU1_SA_CB<7>")
	)
	(arc
		(start 136.842246 -258.313428)
		(mid 136.655048 -258.363571)
		(end 136.46785 -258.313428)
		(width 0.088646)
		(layer "In11.Cu")
		(net "M_H_CPU1_SA_CB<7>")
	)
	(arc
		(start 127.444246 -258.313428)
		(mid 127.257048 -258.363571)
		(end 127.06985 -258.313428)
		(width 0.088646)
		(layer "In11.Cu")
		(net "M_H_CPU1_SA_CB<7>")
	)
	(arc
		(start 125.488446 -258.35737)
		(mid 125.18339 -258.561219)
		(end 124.907548 -258.80314)
		(width 0.088646)
		(layer "In11.Cu")
		(net "M_H_CPU1_SA_CB<7>")
	)
	(arc
		(start 133.638036 -258.307332)
		(mid 133.359604 -258.237518)
		(end 133.082792 -258.313428)
		(width 0.088646)
		(layer "In11.Cu")
		(net "M_H_CPU1_SA_CB<7>")
	)
	(arc
		(start 130.263392 -258.313428)
		(mid 130.076194 -258.363571)
		(end 129.888996 -258.313428)
		(width 0.088646)
		(layer "In11.Cu")
		(net "M_H_CPU1_SA_CB<7>")
	)
	(arc
		(start 127.998982 -258.307332)
		(mid 127.720804 -258.23764)
		(end 127.444246 -258.313428)
		(width 0.088646)
		(layer "In11.Cu")
		(net "M_H_CPU1_SA_CB<7>")
	)
	(arc
		(start 132.697982 -258.307332)
		(mid 132.419804 -258.23764)
		(end 132.143246 -258.313428)
		(width 0.088646)
		(layer "In11.Cu")
		(net "M_H_CPU1_SA_CB<7>")
	)
	(arc
		(start 134.577582 -258.307332)
		(mid 134.299404 -258.23764)
		(end 134.022846 -258.313428)
		(width 0.088646)
		(layer "In11.Cu")
		(net "M_H_CPU1_SA_CB<7>")
	)
	(arc
		(start 131.758436 -258.307332)
		(mid 131.480004 -258.237518)
		(end 131.203192 -258.313428)
		(width 0.088646)
		(layer "In11.Cu")
		(net "M_H_CPU1_SA_CB<7>")
	)
	(arc
		(start 129.323592 -258.313428)
		(mid 129.136394 -258.363571)
		(end 128.949196 -258.313428)
		(width 0.088646)
		(layer "In11.Cu")
		(net "M_H_CPU1_SA_CB<7>")
	)
	(arc
		(start 134.022846 -258.313428)
		(mid 133.835648 -258.363571)
		(end 133.64845 -258.313428)
		(width 0.088646)
		(layer "In11.Cu")
		(net "M_H_CPU1_SA_CB<7>")
	)
	(arc
		(start 134.962392 -258.313428)
		(mid 134.775194 -258.363571)
		(end 134.587996 -258.313428)
		(width 0.088646)
		(layer "In11.Cu")
		(net "M_H_CPU1_SA_CB<7>")
	)
	(arc
		(start 135.527796 -258.313428)
		(mid 135.245094 -258.237686)
		(end 134.962392 -258.313428)
		(width 0.088646)
		(layer "In11.Cu")
		(net "M_H_CPU1_SA_CB<7>")
	)
	(segment
		(start 213.515448 -272.099024)
		(end 213.749636 -271.864836)
		(width 0.20066)
		(layer "F.Cu")
		(net "M_H_CPU1_SA_CB<6>")
	)
	(segment
		(start 125.377448 -259.081016)
		(end 125.377448 -259.093462)
		(width 0.20066)
		(layer "F.Cu")
		(net "M_H_CPU1_SA_CB<6>")
	)
	(segment
		(start 207.071468 -272.116804)
		(end 208.176114 -272.116804)
		(width 0.20066)
		(layer "F.Cu")
		(net "M_H_CPU1_SA_CB<6>")
	)
	(segment
		(start 125.377448 -259.093462)
		(end 125.377194 -259.616956)
		(width 0.20066)
		(layer "F.Cu")
		(net "M_H_CPU1_SA_CB<6>")
	)
	(segment
		(start 210.598258 -272.548858)
		(end 210.603084 -272.548858)
		(width 0.101854)
		(layer "F.Cu")
		(net "M_H_CPU1_SA_CB<6>")
	)
	(segment
		(start 214.133684 -271.864836)
		(end 214.385652 -272.116804)
		(width 0.20066)
		(layer "F.Cu")
		(net "M_H_CPU1_SA_CB<6>")
	)
	(segment
		(start 213.311486 -272.553938)
		(end 213.515448 -272.349976)
		(width 0.20066)
		(layer "F.Cu")
		(net "M_H_CPU1_SA_CB<6>")
	)
	(segment
		(start 213.749636 -271.864836)
		(end 214.133684 -271.864836)
		(width 0.20066)
		(layer "F.Cu")
		(net "M_H_CPU1_SA_CB<6>")
	)
	(segment
		(start 213.515448 -272.349976)
		(end 213.515448 -272.099024)
		(width 0.20066)
		(layer "F.Cu")
		(net "M_H_CPU1_SA_CB<6>")
	)
	(segment
		(start 212.630258 -272.553938)
		(end 213.311486 -272.553938)
		(width 0.20066)
		(layer "F.Cu")
		(net "M_H_CPU1_SA_CB<6>")
	)
	(segment
		(start 210.610196 -272.541746)
		(end 212.618066 -272.541746)
		(width 0.1016)
		(layer "F.Cu")
		(net "M_H_CPU1_SA_CB<6>")
	)
	(segment
		(start 208.176114 -272.116804)
		(end 209.874358 -272.116804)
		(width 0.20066)
		(layer "F.Cu")
		(net "M_H_CPU1_SA_CB<6>")
	)
	(segment
		(start 210.306412 -272.548858)
		(end 210.598258 -272.548858)
		(width 0.20066)
		(layer "F.Cu")
		(net "M_H_CPU1_SA_CB<6>")
	)
	(segment
		(start 209.874358 -272.116804)
		(end 210.306412 -272.548858)
		(width 0.20066)
		(layer "F.Cu")
		(net "M_H_CPU1_SA_CB<6>")
	)
	(segment
		(start 212.618066 -272.541746)
		(end 212.630258 -272.553938)
		(width 0.1016)
		(layer "F.Cu")
		(net "M_H_CPU1_SA_CB<6>")
	)
	(segment
		(start 214.385652 -272.116804)
		(end 215.719914 -272.116804)
		(width 0.20066)
		(layer "F.Cu")
		(net "M_H_CPU1_SA_CB<6>")
	)
	(segment
		(start 210.603084 -272.548858)
		(end 210.610196 -272.541746)
		(width 0.1016)
		(layer "F.Cu")
		(net "M_H_CPU1_SA_CB<6>")
	)
	(segment
		(start 207.071214 -272.11655)
		(end 207.071468 -272.116804)
		(width 0.20066)
		(layer "F.Cu")
		(net "M_H_CPU1_SA_CB<6>")
	)
	(segment
		(start 132.627878 -259.118862)
		(end 132.613146 -259.127498)
		(width 0.088646)
		(layer "In11.Cu")
		(net "M_H_CPU1_SA_CB<6>")
	)
	(segment
		(start 138.373866 -259.95884)
		(end 138.35253 -259.94487)
		(width 0.088646)
		(layer "In11.Cu")
		(net "M_H_CPU1_SA_CB<6>")
	)
	(segment
		(start 134.50316 -259.121402)
		(end 134.492746 -259.127498)
		(width 0.088646)
		(layer "In11.Cu")
		(net "M_H_CPU1_SA_CB<6>")
	)
	(segment
		(start 179.786026 -272.572226)
		(end 179.633626 -272.419826)
		(width 0.18288)
		(layer "In11.Cu")
		(net "M_H_CPU1_SA_CB<6>")
	)
	(segment
		(start 129.803906 -259.121402)
		(end 129.793492 -259.127498)
		(width 0.088646)
		(layer "In11.Cu")
		(net "M_H_CPU1_SA_CB<6>")
	)
	(segment
		(start 204.505052 -272.349214)
		(end 204.505052 -271.602962)
		(width 0.18288)
		(layer "In11.Cu")
		(net "M_H_CPU1_SA_CB<6>")
	)
	(segment
		(start 138.15949 -259.616956)
		(end 138.15949 -259.601462)
		(width 0.088646)
		(layer "In11.Cu")
		(net "M_H_CPU1_SA_CB<6>")
	)
	(segment
		(start 187.068206 -271.690846)
		(end 186.95924 -271.799812)
		(width 0.18288)
		(layer "In11.Cu")
		(net "M_H_CPU1_SA_CB<6>")
	)
	(segment
		(start 163.246562 -271.327118)
		(end 162.406838 -271.327118)
		(width 0.18288)
		(layer "In11.Cu")
		(net "M_H_CPU1_SA_CB<6>")
	)
	(segment
		(start 188.264292 -271.690846)
		(end 187.068206 -271.690846)
		(width 0.18288)
		(layer "In11.Cu")
		(net "M_H_CPU1_SA_CB<6>")
	)
	(segment
		(start 146.876262 -261.75335)
		(end 141.115796 -261.75335)
		(width 0.18288)
		(layer "In11.Cu")
		(net "M_H_CPU1_SA_CB<6>")
	)
	(segment
		(start 141.115796 -261.75335)
		(end 139.986004 -260.623558)
		(width 0.18288)
		(layer "In11.Cu")
		(net "M_H_CPU1_SA_CB<6>")
	)
	(segment
		(start 166.407084 -272.133822)
		(end 166.089584 -272.133822)
		(width 0.18288)
		(layer "In11.Cu")
		(net "M_H_CPU1_SA_CB<6>")
	)
	(segment
		(start 186.95924 -271.799812)
		(end 183.83504 -271.799812)
		(width 0.18288)
		(layer "In11.Cu")
		(net "M_H_CPU1_SA_CB<6>")
	)
	(segment
		(start 194.856608 -273.27987)
		(end 194.676522 -273.459956)
		(width 0.18288)
		(layer "In11.Cu")
		(net "M_H_CPU1_SA_CB<6>")
	)
	(segment
		(start 139.723622 -260.361176)
		(end 138.776202 -260.361176)
		(width 0.088646)
		(layer "In11.Cu")
		(net "M_H_CPU1_SA_CB<6>")
	)
	(segment
		(start 156.777182 -271.65427)
		(end 146.876262 -261.75335)
		(width 0.18288)
		(layer "In11.Cu")
		(net "M_H_CPU1_SA_CB<6>")
	)
	(segment
		(start 166.600124 -271.651222)
		(end 166.600124 -271.940782)
		(width 0.18288)
		(layer "In11.Cu")
		(net "M_H_CPU1_SA_CB<6>")
	)
	(segment
		(start 135.447024 -259.118862)
		(end 135.432292 -259.127498)
		(width 0.088646)
		(layer "In11.Cu")
		(net "M_H_CPU1_SA_CB<6>")
	)
	(segment
		(start 126.989078 -259.118862)
		(end 126.9746 -259.127498)
		(width 0.088646)
		(layer "In11.Cu")
		(net "M_H_CPU1_SA_CB<6>")
	)
	(segment
		(start 166.793164 -271.458182)
		(end 166.600124 -271.651222)
		(width 0.18288)
		(layer "In11.Cu")
		(net "M_H_CPU1_SA_CB<6>")
	)
	(segment
		(start 162.03168 -271.702276)
		(end 161.125408 -271.702276)
		(width 0.18288)
		(layer "In11.Cu")
		(net "M_H_CPU1_SA_CB<6>")
	)
	(segment
		(start 128.86436 -259.121402)
		(end 128.853946 -259.127498)
		(width 0.088646)
		(layer "In11.Cu")
		(net "M_H_CPU1_SA_CB<6>")
	)
	(segment
		(start 199.182482 -272.440908)
		(end 198.34352 -273.27987)
		(width 0.18288)
		(layer "In11.Cu")
		(net "M_H_CPU1_SA_CB<6>")
	)
	(segment
		(start 138.776202 -260.361176)
		(end 138.373866 -259.95884)
		(width 0.088646)
		(layer "In11.Cu")
		(net "M_H_CPU1_SA_CB<6>")
	)
	(segment
		(start 203.801472 -271.602962)
		(end 203.801472 -272.349214)
		(width 0.18288)
		(layer "In11.Cu")
		(net "M_H_CPU1_SA_CB<6>")
	)
	(segment
		(start 130.748278 -259.118862)
		(end 130.733546 -259.127498)
		(width 0.088646)
		(layer "In11.Cu")
		(net "M_H_CPU1_SA_CB<6>")
	)
	(segment
		(start 206.718154 -272.44294)
		(end 206.360268 -272.800826)
		(width 0.18288)
		(layer "In11.Cu")
		(net "M_H_CPU1_SA_CB<6>")
	)
	(segment
		(start 203.801472 -272.349214)
		(end 203.608432 -272.542254)
		(width 0.18288)
		(layer "In11.Cu")
		(net "M_H_CPU1_SA_CB<6>")
	)
	(segment
		(start 174.327312 -271.556734)
		(end 174.1932 -271.690846)
		(width 0.18288)
		(layer "In11.Cu")
		(net "M_H_CPU1_SA_CB<6>")
	)
	(segment
		(start 202.65644 -272.542254)
		(end 202.411584 -272.440908)
		(width 0.18288)
		(layer "In11.Cu")
		(net "M_H_CPU1_SA_CB<6>")
	)
	(segment
		(start 127.928878 -259.118862)
		(end 127.914146 -259.127498)
		(width 0.088646)
		(layer "In11.Cu")
		(net "M_H_CPU1_SA_CB<6>")
	)
	(segment
		(start 177.923444 -272.419826)
		(end 177.802286 -272.540984)
		(width 0.18288)
		(layer "In11.Cu")
		(net "M_H_CPU1_SA_CB<6>")
	)
	(segment
		(start 205.095348 -272.542254)
		(end 204.698092 -272.542254)
		(width 0.18288)
		(layer "In11.Cu")
		(net "M_H_CPU1_SA_CB<6>")
	)
	(segment
		(start 194.676522 -273.459956)
		(end 193.614294 -273.459956)
		(width 0.18288)
		(layer "In11.Cu")
		(net "M_H_CPU1_SA_CB<6>")
	)
	(segment
		(start 189.243462 -272.670016)
		(end 188.264292 -271.690846)
		(width 0.18288)
		(layer "In11.Cu")
		(net "M_H_CPU1_SA_CB<6>")
	)
	(segment
		(start 183.83504 -271.799812)
		(end 183.062626 -272.572226)
		(width 0.18288)
		(layer "In11.Cu")
		(net "M_H_CPU1_SA_CB<6>")
	)
	(segment
		(start 161.125408 -271.702276)
		(end 161.077402 -271.65427)
		(width 0.18288)
		(layer "In11.Cu")
		(net "M_H_CPU1_SA_CB<6>")
	)
	(segment
		(start 202.411584 -272.440908)
		(end 199.182482 -272.440908)
		(width 0.18288)
		(layer "In11.Cu")
		(net "M_H_CPU1_SA_CB<6>")
	)
	(segment
		(start 163.62172 -271.702276)
		(end 163.246562 -271.327118)
		(width 0.18288)
		(layer "In11.Cu")
		(net "M_H_CPU1_SA_CB<6>")
	)
	(segment
		(start 205.35392 -272.800826)
		(end 205.095348 -272.542254)
		(width 0.18288)
		(layer "In11.Cu")
		(net "M_H_CPU1_SA_CB<6>")
	)
	(segment
		(start 190.751206 -272.670016)
		(end 189.243462 -272.670016)
		(width 0.18288)
		(layer "In11.Cu")
		(net "M_H_CPU1_SA_CB<6>")
	)
	(segment
		(start 139.986004 -260.623558)
		(end 139.723622 -260.361176)
		(width 0.088646)
		(layer "In11.Cu")
		(net "M_H_CPU1_SA_CB<6>")
	)
	(segment
		(start 176.376584 -272.540984)
		(end 175.392334 -271.556734)
		(width 0.18288)
		(layer "In11.Cu")
		(net "M_H_CPU1_SA_CB<6>")
	)
	(segment
		(start 183.062626 -272.572226)
		(end 179.786026 -272.572226)
		(width 0.18288)
		(layer "In11.Cu")
		(net "M_H_CPU1_SA_CB<6>")
	)
	(segment
		(start 166.600124 -271.940782)
		(end 166.407084 -272.133822)
		(width 0.18288)
		(layer "In11.Cu")
		(net "M_H_CPU1_SA_CB<6>")
	)
	(segment
		(start 204.505052 -271.602962)
		(end 204.312012 -271.409922)
		(width 0.18288)
		(layer "In11.Cu")
		(net "M_H_CPU1_SA_CB<6>")
	)
	(segment
		(start 175.392334 -271.556734)
		(end 174.327312 -271.556734)
		(width 0.18288)
		(layer "In11.Cu")
		(net "M_H_CPU1_SA_CB<6>")
	)
	(segment
		(start 166.089584 -272.133822)
		(end 165.896544 -271.940782)
		(width 0.18288)
		(layer "In11.Cu")
		(net "M_H_CPU1_SA_CB<6>")
	)
	(segment
		(start 203.994512 -271.409922)
		(end 203.801472 -271.602962)
		(width 0.18288)
		(layer "In11.Cu")
		(net "M_H_CPU1_SA_CB<6>")
	)
	(segment
		(start 165.896544 -271.651222)
		(end 165.703504 -271.458182)
		(width 0.18288)
		(layer "In11.Cu")
		(net "M_H_CPU1_SA_CB<6>")
	)
	(segment
		(start 198.34352 -273.27987)
		(end 194.856608 -273.27987)
		(width 0.18288)
		(layer "In11.Cu")
		(net "M_H_CPU1_SA_CB<6>")
	)
	(segment
		(start 168.46931 -271.458182)
		(end 166.793164 -271.458182)
		(width 0.18288)
		(layer "In11.Cu")
		(net "M_H_CPU1_SA_CB<6>")
	)
	(segment
		(start 161.077402 -271.65427)
		(end 156.777182 -271.65427)
		(width 0.18288)
		(layer "In11.Cu")
		(net "M_H_CPU1_SA_CB<6>")
	)
	(segment
		(start 126.049278 -259.118862)
		(end 125.93574 -259.18541)
		(width 0.088646)
		(layer "In11.Cu")
		(net "M_H_CPU1_SA_CB<6>")
	)
	(segment
		(start 131.688078 -259.118862)
		(end 131.673346 -259.127498)
		(width 0.088646)
		(layer "In11.Cu")
		(net "M_H_CPU1_SA_CB<6>")
	)
	(segment
		(start 206.719424 -272.44294)
		(end 206.718154 -272.44294)
		(width 0.18288)
		(layer "In11.Cu")
		(net "M_H_CPU1_SA_CB<6>")
	)
	(segment
		(start 171.726606 -271.690846)
		(end 171.581826 -271.835626)
		(width 0.18288)
		(layer "In11.Cu")
		(net "M_H_CPU1_SA_CB<6>")
	)
	(segment
		(start 190.87846 -272.542762)
		(end 190.751206 -272.670016)
		(width 0.18288)
		(layer "In11.Cu")
		(net "M_H_CPU1_SA_CB<6>")
	)
	(segment
		(start 162.406838 -271.327118)
		(end 162.03168 -271.702276)
		(width 0.18288)
		(layer "In11.Cu")
		(net "M_H_CPU1_SA_CB<6>")
	)
	(segment
		(start 179.633626 -272.419826)
		(end 177.923444 -272.419826)
		(width 0.18288)
		(layer "In11.Cu")
		(net "M_H_CPU1_SA_CB<6>")
	)
	(segment
		(start 207.071214 -272.11655)
		(end 207.045814 -272.11655)
		(width 0.18288)
		(layer "In11.Cu")
		(net "M_H_CPU1_SA_CB<6>")
	)
	(segment
		(start 177.802286 -272.540984)
		(end 176.376584 -272.540984)
		(width 0.18288)
		(layer "In11.Cu")
		(net "M_H_CPU1_SA_CB<6>")
	)
	(segment
		(start 203.608432 -272.542254)
		(end 202.65644 -272.542254)
		(width 0.18288)
		(layer "In11.Cu")
		(net "M_H_CPU1_SA_CB<6>")
	)
	(segment
		(start 164.721032 -271.458182)
		(end 164.476938 -271.702276)
		(width 0.18288)
		(layer "In11.Cu")
		(net "M_H_CPU1_SA_CB<6>")
	)
	(segment
		(start 164.476938 -271.702276)
		(end 163.62172 -271.702276)
		(width 0.18288)
		(layer "In11.Cu")
		(net "M_H_CPU1_SA_CB<6>")
	)
	(segment
		(start 137.326624 -259.118862)
		(end 137.311892 -259.127498)
		(width 0.088646)
		(layer "In11.Cu")
		(net "M_H_CPU1_SA_CB<6>")
	)
	(segment
		(start 133.567678 -259.118862)
		(end 133.552946 -259.127498)
		(width 0.088646)
		(layer "In11.Cu")
		(net "M_H_CPU1_SA_CB<6>")
	)
	(segment
		(start 192.6971 -272.542762)
		(end 190.87846 -272.542762)
		(width 0.18288)
		(layer "In11.Cu")
		(net "M_H_CPU1_SA_CB<6>")
	)
	(segment
		(start 206.360268 -272.800826)
		(end 205.35392 -272.800826)
		(width 0.18288)
		(layer "In11.Cu")
		(net "M_H_CPU1_SA_CB<6>")
	)
	(segment
		(start 171.581826 -271.835626)
		(end 168.846754 -271.835626)
		(width 0.18288)
		(layer "In11.Cu")
		(net "M_H_CPU1_SA_CB<6>")
	)
	(segment
		(start 165.703504 -271.458182)
		(end 164.721032 -271.458182)
		(width 0.18288)
		(layer "In11.Cu")
		(net "M_H_CPU1_SA_CB<6>")
	)
	(segment
		(start 204.698092 -272.542254)
		(end 204.505052 -272.349214)
		(width 0.18288)
		(layer "In11.Cu")
		(net "M_H_CPU1_SA_CB<6>")
	)
	(segment
		(start 138.35253 -259.94487)
		(end 138.338052 -259.936234)
		(width 0.088646)
		(layer "In11.Cu")
		(net "M_H_CPU1_SA_CB<6>")
	)
	(segment
		(start 207.045814 -272.11655)
		(end 206.719424 -272.44294)
		(width 0.18288)
		(layer "In11.Cu")
		(net "M_H_CPU1_SA_CB<6>")
	)
	(segment
		(start 165.896544 -271.940782)
		(end 165.896544 -271.651222)
		(width 0.18288)
		(layer "In11.Cu")
		(net "M_H_CPU1_SA_CB<6>")
	)
	(segment
		(start 193.614294 -273.459956)
		(end 192.6971 -272.542762)
		(width 0.18288)
		(layer "In11.Cu")
		(net "M_H_CPU1_SA_CB<6>")
	)
	(segment
		(start 168.846754 -271.835626)
		(end 168.46931 -271.458182)
		(width 0.18288)
		(layer "In11.Cu")
		(net "M_H_CPU1_SA_CB<6>")
	)
	(segment
		(start 136.386824 -259.118862)
		(end 136.372092 -259.127498)
		(width 0.088646)
		(layer "In11.Cu")
		(net "M_H_CPU1_SA_CB<6>")
	)
	(segment
		(start 204.312012 -271.409922)
		(end 203.994512 -271.409922)
		(width 0.18288)
		(layer "In11.Cu")
		(net "M_H_CPU1_SA_CB<6>")
	)
	(segment
		(start 174.1932 -271.690846)
		(end 171.726606 -271.690846)
		(width 0.18288)
		(layer "In11.Cu")
		(net "M_H_CPU1_SA_CB<6>")
	)
	(arc
		(start 132.613146 -259.127498)
		(mid 132.425948 -259.177641)
		(end 132.23875 -259.127498)
		(width 0.088646)
		(layer "In11.Cu")
		(net "M_H_CPU1_SA_CB<6>")
	)
	(arc
		(start 129.419096 -259.127498)
		(mid 129.142537 -259.051755)
		(end 128.86436 -259.121402)
		(width 0.088646)
		(layer "In11.Cu")
		(net "M_H_CPU1_SA_CB<6>")
	)
	(arc
		(start 132.23875 -259.127498)
		(mid 131.964551 -259.051663)
		(end 131.688078 -259.118862)
		(width 0.088646)
		(layer "In11.Cu")
		(net "M_H_CPU1_SA_CB<6>")
	)
	(arc
		(start 129.793492 -259.127498)
		(mid 129.606294 -259.177641)
		(end 129.419096 -259.127498)
		(width 0.088646)
		(layer "In11.Cu")
		(net "M_H_CPU1_SA_CB<6>")
	)
	(arc
		(start 134.11835 -259.127498)
		(mid 133.844151 -259.051663)
		(end 133.567678 -259.118862)
		(width 0.088646)
		(layer "In11.Cu")
		(net "M_H_CPU1_SA_CB<6>")
	)
	(arc
		(start 136.372092 -259.127498)
		(mid 136.184894 -259.177641)
		(end 135.997696 -259.127498)
		(width 0.088646)
		(layer "In11.Cu")
		(net "M_H_CPU1_SA_CB<6>")
	)
	(arc
		(start 133.17855 -259.127498)
		(mid 132.904351 -259.051663)
		(end 132.627878 -259.118862)
		(width 0.088646)
		(layer "In11.Cu")
		(net "M_H_CPU1_SA_CB<6>")
	)
	(arc
		(start 125.93574 -259.18541)
		(mid 125.642684 -259.383343)
		(end 125.377194 -259.616956)
		(width 0.088646)
		(layer "In11.Cu")
		(net "M_H_CPU1_SA_CB<6>")
	)
	(arc
		(start 135.057896 -259.127498)
		(mid 134.781337 -259.051755)
		(end 134.50316 -259.121402)
		(width 0.088646)
		(layer "In11.Cu")
		(net "M_H_CPU1_SA_CB<6>")
	)
	(arc
		(start 131.29895 -259.127498)
		(mid 131.024751 -259.051663)
		(end 130.748278 -259.118862)
		(width 0.088646)
		(layer "In11.Cu")
		(net "M_H_CPU1_SA_CB<6>")
	)
	(arc
		(start 134.492746 -259.127498)
		(mid 134.305548 -259.177641)
		(end 134.11835 -259.127498)
		(width 0.088646)
		(layer "In11.Cu")
		(net "M_H_CPU1_SA_CB<6>")
	)
	(arc
		(start 138.338052 -259.936234)
		(mid 138.207138 -259.799874)
		(end 138.15949 -259.616956)
		(width 0.088646)
		(layer "In11.Cu")
		(net "M_H_CPU1_SA_CB<6>")
	)
	(arc
		(start 137.311892 -259.127498)
		(mid 137.124694 -259.177641)
		(end 136.937496 -259.127498)
		(width 0.088646)
		(layer "In11.Cu")
		(net "M_H_CPU1_SA_CB<6>")
	)
	(arc
		(start 128.853946 -259.127498)
		(mid 128.666748 -259.177641)
		(end 128.47955 -259.127498)
		(width 0.088646)
		(layer "In11.Cu")
		(net "M_H_CPU1_SA_CB<6>")
	)
	(arc
		(start 138.15949 -259.601462)
		(mid 138.08012 -259.327728)
		(end 137.877296 -259.127498)
		(width 0.088646)
		(layer "In11.Cu")
		(net "M_H_CPU1_SA_CB<6>")
	)
	(arc
		(start 136.937496 -259.127498)
		(mid 136.663297 -259.051663)
		(end 136.386824 -259.118862)
		(width 0.088646)
		(layer "In11.Cu")
		(net "M_H_CPU1_SA_CB<6>")
	)
	(arc
		(start 131.673346 -259.127498)
		(mid 131.486148 -259.177641)
		(end 131.29895 -259.127498)
		(width 0.088646)
		(layer "In11.Cu")
		(net "M_H_CPU1_SA_CB<6>")
	)
	(arc
		(start 130.733546 -259.127498)
		(mid 130.546348 -259.177641)
		(end 130.35915 -259.127498)
		(width 0.088646)
		(layer "In11.Cu")
		(net "M_H_CPU1_SA_CB<6>")
	)
	(arc
		(start 135.432292 -259.127498)
		(mid 135.245094 -259.177641)
		(end 135.057896 -259.127498)
		(width 0.088646)
		(layer "In11.Cu")
		(net "M_H_CPU1_SA_CB<6>")
	)
	(arc
		(start 133.552946 -259.127498)
		(mid 133.365748 -259.177641)
		(end 133.17855 -259.127498)
		(width 0.088646)
		(layer "In11.Cu")
		(net "M_H_CPU1_SA_CB<6>")
	)
	(arc
		(start 137.877296 -259.127498)
		(mid 137.603097 -259.051663)
		(end 137.326624 -259.118862)
		(width 0.088646)
		(layer "In11.Cu")
		(net "M_H_CPU1_SA_CB<6>")
	)
	(arc
		(start 127.53975 -259.127498)
		(mid 127.265551 -259.051663)
		(end 126.989078 -259.118862)
		(width 0.088646)
		(layer "In11.Cu")
		(net "M_H_CPU1_SA_CB<6>")
	)
	(arc
		(start 130.35915 -259.127498)
		(mid 130.082337 -259.051628)
		(end 129.803906 -259.121402)
		(width 0.088646)
		(layer "In11.Cu")
		(net "M_H_CPU1_SA_CB<6>")
	)
	(arc
		(start 128.47955 -259.127498)
		(mid 128.205351 -259.051663)
		(end 127.928878 -259.118862)
		(width 0.088646)
		(layer "In11.Cu")
		(net "M_H_CPU1_SA_CB<6>")
	)
	(arc
		(start 127.914146 -259.127498)
		(mid 127.726948 -259.177641)
		(end 127.53975 -259.127498)
		(width 0.088646)
		(layer "In11.Cu")
		(net "M_H_CPU1_SA_CB<6>")
	)
	(arc
		(start 135.997696 -259.127498)
		(mid 135.723497 -259.051663)
		(end 135.447024 -259.118862)
		(width 0.088646)
		(layer "In11.Cu")
		(net "M_H_CPU1_SA_CB<6>")
	)
	(arc
		(start 126.9746 -259.127498)
		(mid 126.787292 -259.177641)
		(end 126.59995 -259.127498)
		(width 0.088646)
		(layer "In11.Cu")
		(net "M_H_CPU1_SA_CB<6>")
	)
	(arc
		(start 126.59995 -259.127498)
		(mid 126.325751 -259.051663)
		(end 126.049278 -259.118862)
		(width 0.088646)
		(layer "In11.Cu")
		(net "M_H_CPU1_SA_CB<6>")
	)
	(segment
		(start 206.508604 -271.327372)
		(end 206.320644 -271.515332)
		(width 0.20066)
		(layer "F.Cu")
		(net "M_H_CPU1_SA_CB<5>")
	)
	(segment
		(start 210.028028 -271.26692)
		(end 209.596482 -270.835374)
		(width 0.20066)
		(layer "F.Cu")
		(net "M_H_CPU1_SA_CB<5>")
	)
	(segment
		(start 206.508604 -270.959834)
		(end 206.508604 -271.327372)
		(width 0.20066)
		(layer "F.Cu")
		(net "M_H_CPU1_SA_CB<5>")
	)
	(segment
		(start 123.967748 -258.267454)
		(end 123.967748 -258.80314)
		(width 0.20066)
		(layer "F.Cu")
		(net "M_H_CPU1_SA_CB<5>")
	)
	(segment
		(start 204.076046 -271.266666)
		(end 202.971146 -271.266666)
		(width 0.20066)
		(layer "F.Cu")
		(net "M_H_CPU1_SA_CB<5>")
	)
	(segment
		(start 123.967494 -258.2672)
		(end 123.967748 -258.267454)
		(width 0.20066)
		(layer "F.Cu")
		(net "M_H_CPU1_SA_CB<5>")
	)
	(segment
		(start 205.596744 -271.266666)
		(end 204.076046 -271.266666)
		(width 0.20066)
		(layer "F.Cu")
		(net "M_H_CPU1_SA_CB<5>")
	)
	(segment
		(start 206.320644 -271.515332)
		(end 205.84541 -271.515332)
		(width 0.20066)
		(layer "F.Cu")
		(net "M_H_CPU1_SA_CB<5>")
	)
	(segment
		(start 205.84541 -271.515332)
		(end 205.596744 -271.266666)
		(width 0.20066)
		(layer "F.Cu")
		(net "M_H_CPU1_SA_CB<5>")
	)
	(segment
		(start 211.619846 -271.266666)
		(end 211.619592 -271.26692)
		(width 0.20066)
		(layer "F.Cu")
		(net "M_H_CPU1_SA_CB<5>")
	)
	(segment
		(start 209.186526 -270.835374)
		(end 209.180176 -270.841724)
		(width 0.1016)
		(layer "F.Cu")
		(net "M_H_CPU1_SA_CB<5>")
	)
	(segment
		(start 209.180176 -270.841724)
		(end 206.991458 -270.841724)
		(width 0.1016)
		(layer "F.Cu")
		(net "M_H_CPU1_SA_CB<5>")
	)
	(segment
		(start 206.626714 -270.841724)
		(end 206.508604 -270.959834)
		(width 0.20066)
		(layer "F.Cu")
		(net "M_H_CPU1_SA_CB<5>")
	)
	(segment
		(start 206.971392 -270.841724)
		(end 206.626714 -270.841724)
		(width 0.20066)
		(layer "F.Cu")
		(net "M_H_CPU1_SA_CB<5>")
	)
	(segment
		(start 209.596482 -270.835374)
		(end 209.186526 -270.835374)
		(width 0.20066)
		(layer "F.Cu")
		(net "M_H_CPU1_SA_CB<5>")
	)
	(segment
		(start 206.991458 -270.841724)
		(end 206.971392 -270.841724)
		(width 0.101854)
		(layer "F.Cu")
		(net "M_H_CPU1_SA_CB<5>")
	)
	(segment
		(start 211.619592 -271.26692)
		(end 210.028028 -271.26692)
		(width 0.20066)
		(layer "F.Cu")
		(net "M_H_CPU1_SA_CB<5>")
	)
	(segment
		(start 202.312778 -271.925034)
		(end 201.207116 -271.925034)
		(width 0.18288)
		(layer "In11.Cu")
		(net "M_H_CPU1_SA_CB<5>")
	)
	(segment
		(start 196.113146 -272.562828)
		(end 195.920106 -272.755868)
		(width 0.18288)
		(layer "In11.Cu")
		(net "M_H_CPU1_SA_CB<5>")
	)
	(segment
		(start 201.207116 -271.925034)
		(end 201.014076 -271.731994)
		(width 0.18288)
		(layer "In11.Cu")
		(net "M_H_CPU1_SA_CB<5>")
	)
	(segment
		(start 173.977554 -271.136872)
		(end 173.580044 -271.136872)
		(width 0.18288)
		(layer "In11.Cu")
		(net "M_H_CPU1_SA_CB<5>")
	)
	(segment
		(start 186.240166 -270.62938)
		(end 186.047126 -270.82242)
		(width 0.18288)
		(layer "In11.Cu")
		(net "M_H_CPU1_SA_CB<5>")
	)
	(segment
		(start 187.500768 -270.840962)
		(end 187.289186 -270.62938)
		(width 0.18288)
		(layer "In11.Cu")
		(net "M_H_CPU1_SA_CB<5>")
	)
	(segment
		(start 198.945246 -271.925034)
		(end 198.114412 -272.755868)
		(width 0.18288)
		(layer "In11.Cu")
		(net "M_H_CPU1_SA_CB<5>")
	)
	(segment
		(start 180.829966 -271.403826)
		(end 180.090826 -271.403826)
		(width 0.18288)
		(layer "In11.Cu")
		(net "M_H_CPU1_SA_CB<5>")
	)
	(segment
		(start 188.258958 -270.840962)
		(end 187.500768 -270.840962)
		(width 0.18288)
		(layer "In11.Cu")
		(net "M_H_CPU1_SA_CB<5>")
	)
	(segment
		(start 186.047126 -271.095978)
		(end 185.854086 -271.289018)
		(width 0.18288)
		(layer "In11.Cu")
		(net "M_H_CPU1_SA_CB<5>")
	)
	(segment
		(start 170.666918 -271.324324)
		(end 170.349418 -271.324324)
		(width 0.18288)
		(layer "In11.Cu")
		(net "M_H_CPU1_SA_CB<5>")
	)
	(segment
		(start 193.299334 -272.363184)
		(end 192.630552 -271.694402)
		(width 0.18288)
		(layer "In11.Cu")
		(net "M_H_CPU1_SA_CB<5>")
	)
	(segment
		(start 164.648642 -270.922242)
		(end 164.520626 -270.794226)
		(width 0.18288)
		(layer "In11.Cu")
		(net "M_H_CPU1_SA_CB<5>")
	)
	(segment
		(start 200.821036 -271.362678)
		(end 200.503536 -271.362678)
		(width 0.18288)
		(layer "In11.Cu")
		(net "M_H_CPU1_SA_CB<5>")
	)
	(segment
		(start 139.328144 -259.92455)
		(end 137.958322 -258.554728)
		(width 0.088646)
		(layer "In11.Cu")
		(net "M_H_CPU1_SA_CB<5>")
	)
	(segment
		(start 171.052998 -270.631158)
		(end 170.859958 -270.824198)
		(width 0.18288)
		(layer "In11.Cu")
		(net "M_H_CPU1_SA_CB<5>")
	)
	(segment
		(start 196.306186 -272.02257)
		(end 196.113146 -272.21561)
		(width 0.18288)
		(layer "In11.Cu")
		(net "M_H_CPU1_SA_CB<5>")
	)
	(segment
		(start 156.82849 -270.946372)
		(end 156.78785 -270.946372)
		(width 0.18288)
		(layer "In11.Cu")
		(net "M_H_CPU1_SA_CB<5>")
	)
	(segment
		(start 200.503536 -271.362678)
		(end 200.310496 -271.555718)
		(width 0.18288)
		(layer "In11.Cu")
		(net "M_H_CPU1_SA_CB<5>")
	)
	(segment
		(start 198.114412 -272.755868)
		(end 197.009766 -272.755868)
		(width 0.18288)
		(layer "In11.Cu")
		(net "M_H_CPU1_SA_CB<5>")
	)
	(segment
		(start 200.310496 -271.555718)
		(end 200.310496 -271.731994)
		(width 0.18288)
		(layer "In11.Cu")
		(net "M_H_CPU1_SA_CB<5>")
	)
	(segment
		(start 141.622018 -261.40791)
		(end 140.138658 -259.92455)
		(width 0.18288)
		(layer "In11.Cu")
		(net "M_H_CPU1_SA_CB<5>")
	)
	(segment
		(start 187.289186 -270.62938)
		(end 186.240166 -270.62938)
		(width 0.18288)
		(layer "In11.Cu")
		(net "M_H_CPU1_SA_CB<5>")
	)
	(segment
		(start 188.952632 -271.534636)
		(end 188.258958 -270.840962)
		(width 0.18288)
		(layer "In11.Cu")
		(net "M_H_CPU1_SA_CB<5>")
	)
	(segment
		(start 160.901126 -270.794226)
		(end 160.748726 -270.946626)
		(width 0.18288)
		(layer "In11.Cu")
		(net "M_H_CPU1_SA_CB<5>")
	)
	(segment
		(start 126.049278 -258.487418)
		(end 126.034546 -258.478782)
		(width 0.088646)
		(layer "In11.Cu")
		(net "M_H_CPU1_SA_CB<5>")
	)
	(segment
		(start 137.958322 -258.554728)
		(end 137.594848 -258.554728)
		(width 0.088646)
		(layer "In11.Cu")
		(net "M_H_CPU1_SA_CB<5>")
	)
	(segment
		(start 180.090826 -271.403826)
		(end 179.582826 -271.911826)
		(width 0.18288)
		(layer "In11.Cu")
		(net "M_H_CPU1_SA_CB<5>")
	)
	(segment
		(start 196.623686 -272.02257)
		(end 196.306186 -272.02257)
		(width 0.18288)
		(layer "In11.Cu")
		(net "M_H_CPU1_SA_CB<5>")
	)
	(segment
		(start 186.047126 -270.82242)
		(end 186.047126 -271.095978)
		(width 0.18288)
		(layer "In11.Cu")
		(net "M_H_CPU1_SA_CB<5>")
	)
	(segment
		(start 156.78785 -270.946372)
		(end 147.249388 -261.40791)
		(width 0.18288)
		(layer "In11.Cu")
		(net "M_H_CPU1_SA_CB<5>")
	)
	(segment
		(start 164.520626 -270.794226)
		(end 160.901126 -270.794226)
		(width 0.18288)
		(layer "In11.Cu")
		(net "M_H_CPU1_SA_CB<5>")
	)
	(segment
		(start 174.90821 -271.022826)
		(end 174.726346 -270.840962)
		(width 0.18288)
		(layer "In11.Cu")
		(net "M_H_CPU1_SA_CB<5>")
	)
	(segment
		(start 170.156378 -270.824198)
		(end 169.963338 -270.631158)
		(width 0.18288)
		(layer "In11.Cu")
		(net "M_H_CPU1_SA_CB<5>")
	)
	(segment
		(start 185.854086 -271.289018)
		(end 185.536586 -271.289018)
		(width 0.18288)
		(layer "In11.Cu")
		(net "M_H_CPU1_SA_CB<5>")
	)
	(segment
		(start 194.381628 -272.363184)
		(end 193.299334 -272.363184)
		(width 0.18288)
		(layer "In11.Cu")
		(net "M_H_CPU1_SA_CB<5>")
	)
	(segment
		(start 197.009766 -272.755868)
		(end 196.816726 -272.562828)
		(width 0.18288)
		(layer "In11.Cu")
		(net "M_H_CPU1_SA_CB<5>")
	)
	(segment
		(start 178.84267 -271.911826)
		(end 178.33467 -271.403826)
		(width 0.18288)
		(layer "In11.Cu")
		(net "M_H_CPU1_SA_CB<5>")
	)
	(segment
		(start 124.18822 -259.023612)
		(end 123.967748 -258.80314)
		(width 0.088646)
		(layer "In11.Cu")
		(net "M_H_CPU1_SA_CB<5>")
	)
	(segment
		(start 160.748726 -270.946626)
		(end 156.828744 -270.946626)
		(width 0.18288)
		(layer "In11.Cu")
		(net "M_H_CPU1_SA_CB<5>")
	)
	(segment
		(start 156.828744 -270.946626)
		(end 156.82849 -270.946372)
		(width 0.18288)
		(layer "In11.Cu")
		(net "M_H_CPU1_SA_CB<5>")
	)
	(segment
		(start 147.249388 -261.40791)
		(end 141.622018 -261.40791)
		(width 0.18288)
		(layer "In11.Cu")
		(net "M_H_CPU1_SA_CB<5>")
	)
	(segment
		(start 172.021246 -270.840962)
		(end 171.811442 -270.631158)
		(width 0.18288)
		(layer "In11.Cu")
		(net "M_H_CPU1_SA_CB<5>")
	)
	(segment
		(start 177.981864 -271.403826)
		(end 177.69459 -271.6911)
		(width 0.18288)
		(layer "In11.Cu")
		(net "M_H_CPU1_SA_CB<5>")
	)
	(segment
		(start 169.204894 -270.631158)
		(end 168.91381 -270.922242)
		(width 0.18288)
		(layer "In11.Cu")
		(net "M_H_CPU1_SA_CB<5>")
	)
	(segment
		(start 134.493 -258.478782)
		(end 134.492746 -258.478782)
		(width 0.088646)
		(layer "In11.Cu")
		(net "M_H_CPU1_SA_CB<5>")
	)
	(segment
		(start 196.816726 -272.21561)
		(end 196.623686 -272.02257)
		(width 0.18288)
		(layer "In11.Cu")
		(net "M_H_CPU1_SA_CB<5>")
	)
	(segment
		(start 125.472444 -258.80314)
		(end 125.472444 -258.922012)
		(width 0.088646)
		(layer "In11.Cu")
		(net "M_H_CPU1_SA_CB<5>")
	)
	(segment
		(start 136.937496 -258.478782)
		(end 136.922764 -258.487418)
		(width 0.088646)
		(layer "In11.Cu")
		(net "M_H_CPU1_SA_CB<5>")
	)
	(segment
		(start 201.014076 -271.555718)
		(end 200.821036 -271.362678)
		(width 0.18288)
		(layer "In11.Cu")
		(net "M_H_CPU1_SA_CB<5>")
	)
	(segment
		(start 181.533546 -272.036032)
		(end 181.216046 -272.036032)
		(width 0.18288)
		(layer "In11.Cu")
		(net "M_H_CPU1_SA_CB<5>")
	)
	(segment
		(start 196.816726 -272.562828)
		(end 196.816726 -272.21561)
		(width 0.18288)
		(layer "In11.Cu")
		(net "M_H_CPU1_SA_CB<5>")
	)
	(segment
		(start 129.803906 -258.484878)
		(end 129.793492 -258.478782)
		(width 0.088646)
		(layer "In11.Cu")
		(net "M_H_CPU1_SA_CB<5>")
	)
	(segment
		(start 173.284134 -270.840962)
		(end 172.021246 -270.840962)
		(width 0.18288)
		(layer "In11.Cu")
		(net "M_H_CPU1_SA_CB<5>")
	)
	(segment
		(start 166.547038 -270.484092)
		(end 166.353998 -270.291052)
		(width 0.18288)
		(layer "In11.Cu")
		(net "M_H_CPU1_SA_CB<5>")
	)
	(segment
		(start 166.036498 -270.291052)
		(end 165.843458 -270.484092)
		(width 0.18288)
		(layer "In11.Cu")
		(net "M_H_CPU1_SA_CB<5>")
	)
	(segment
		(start 139.98575 -259.92455)
		(end 139.328144 -259.92455)
		(width 0.088646)
		(layer "In11.Cu")
		(net "M_H_CPU1_SA_CB<5>")
	)
	(segment
		(start 181.726586 -271.842992)
		(end 181.533546 -272.036032)
		(width 0.18288)
		(layer "In11.Cu")
		(net "M_H_CPU1_SA_CB<5>")
	)
	(segment
		(start 195.920106 -272.755868)
		(end 194.774312 -272.755868)
		(width 0.18288)
		(layer "In11.Cu")
		(net "M_H_CPU1_SA_CB<5>")
	)
	(segment
		(start 165.650418 -270.922242)
		(end 164.648642 -270.922242)
		(width 0.18288)
		(layer "In11.Cu")
		(net "M_H_CPU1_SA_CB<5>")
	)
	(segment
		(start 176.3141 -271.6911)
		(end 175.645826 -271.022826)
		(width 0.18288)
		(layer "In11.Cu")
		(net "M_H_CPU1_SA_CB<5>")
	)
	(segment
		(start 171.811442 -270.631158)
		(end 171.052998 -270.631158)
		(width 0.18288)
		(layer "In11.Cu")
		(net "M_H_CPU1_SA_CB<5>")
	)
	(segment
		(start 169.963338 -270.631158)
		(end 169.204894 -270.631158)
		(width 0.18288)
		(layer "In11.Cu")
		(net "M_H_CPU1_SA_CB<5>")
	)
	(segment
		(start 165.843458 -270.484092)
		(end 165.843458 -270.729202)
		(width 0.18288)
		(layer "In11.Cu")
		(net "M_H_CPU1_SA_CB<5>")
	)
	(segment
		(start 170.859958 -271.131284)
		(end 170.666918 -271.324324)
		(width 0.18288)
		(layer "In11.Cu")
		(net "M_H_CPU1_SA_CB<5>")
	)
	(segment
		(start 185.343546 -271.095978)
		(end 185.343546 -270.82242)
		(width 0.18288)
		(layer "In11.Cu")
		(net "M_H_CPU1_SA_CB<5>")
	)
	(segment
		(start 173.580044 -271.136872)
		(end 173.284134 -270.840962)
		(width 0.18288)
		(layer "In11.Cu")
		(net "M_H_CPU1_SA_CB<5>")
	)
	(segment
		(start 166.547038 -270.729202)
		(end 166.547038 -270.484092)
		(width 0.18288)
		(layer "In11.Cu")
		(net "M_H_CPU1_SA_CB<5>")
	)
	(segment
		(start 192.630552 -271.694402)
		(end 191.478408 -271.694402)
		(width 0.18288)
		(layer "In11.Cu")
		(net "M_H_CPU1_SA_CB<5>")
	)
	(segment
		(start 135.432292 -258.478782)
		(end 135.432038 -258.478782)
		(width 0.088646)
		(layer "In11.Cu")
		(net "M_H_CPU1_SA_CB<5>")
	)
	(segment
		(start 168.91381 -270.922242)
		(end 166.740078 -270.922242)
		(width 0.18288)
		(layer "In11.Cu")
		(net "M_H_CPU1_SA_CB<5>")
	)
	(segment
		(start 194.774312 -272.755868)
		(end 194.381628 -272.363184)
		(width 0.18288)
		(layer "In11.Cu")
		(net "M_H_CPU1_SA_CB<5>")
	)
	(segment
		(start 201.014076 -271.731994)
		(end 201.014076 -271.555718)
		(width 0.18288)
		(layer "In11.Cu")
		(net "M_H_CPU1_SA_CB<5>")
	)
	(segment
		(start 174.726346 -270.840962)
		(end 174.273464 -270.840962)
		(width 0.18288)
		(layer "In11.Cu")
		(net "M_H_CPU1_SA_CB<5>")
	)
	(segment
		(start 166.353998 -270.291052)
		(end 166.036498 -270.291052)
		(width 0.18288)
		(layer "In11.Cu")
		(net "M_H_CPU1_SA_CB<5>")
	)
	(segment
		(start 177.69459 -271.6911)
		(end 176.3141 -271.6911)
		(width 0.18288)
		(layer "In11.Cu")
		(net "M_H_CPU1_SA_CB<5>")
	)
	(segment
		(start 184.095898 -270.62938)
		(end 183.321452 -271.403826)
		(width 0.18288)
		(layer "In11.Cu")
		(net "M_H_CPU1_SA_CB<5>")
	)
	(segment
		(start 191.478408 -271.694402)
		(end 191.318642 -271.534636)
		(width 0.18288)
		(layer "In11.Cu")
		(net "M_H_CPU1_SA_CB<5>")
	)
	(segment
		(start 170.156378 -271.131284)
		(end 170.156378 -270.824198)
		(width 0.18288)
		(layer "In11.Cu")
		(net "M_H_CPU1_SA_CB<5>")
	)
	(segment
		(start 185.343546 -270.82242)
		(end 185.150506 -270.62938)
		(width 0.18288)
		(layer "In11.Cu")
		(net "M_H_CPU1_SA_CB<5>")
	)
	(segment
		(start 128.86436 -258.484878)
		(end 128.853946 -258.478782)
		(width 0.088646)
		(layer "In11.Cu")
		(net "M_H_CPU1_SA_CB<5>")
	)
	(segment
		(start 130.748278 -258.487418)
		(end 130.733546 -258.478782)
		(width 0.088646)
		(layer "In11.Cu")
		(net "M_H_CPU1_SA_CB<5>")
	)
	(segment
		(start 181.023006 -271.596866)
		(end 180.829966 -271.403826)
		(width 0.18288)
		(layer "In11.Cu")
		(net "M_H_CPU1_SA_CB<5>")
	)
	(segment
		(start 196.113146 -272.21561)
		(end 196.113146 -272.562828)
		(width 0.18288)
		(layer "In11.Cu")
		(net "M_H_CPU1_SA_CB<5>")
	)
	(segment
		(start 181.726586 -271.596866)
		(end 181.726586 -271.842992)
		(width 0.18288)
		(layer "In11.Cu")
		(net "M_H_CPU1_SA_CB<5>")
	)
	(segment
		(start 181.023006 -271.842992)
		(end 181.023006 -271.596866)
		(width 0.18288)
		(layer "In11.Cu")
		(net "M_H_CPU1_SA_CB<5>")
	)
	(segment
		(start 125.66015 -258.478782)
		(end 125.659642 -258.479036)
		(width 0.088646)
		(layer "In11.Cu")
		(net "M_H_CPU1_SA_CB<5>")
	)
	(segment
		(start 200.310496 -271.731994)
		(end 200.117456 -271.925034)
		(width 0.18288)
		(layer "In11.Cu")
		(net "M_H_CPU1_SA_CB<5>")
	)
	(segment
		(start 181.216046 -272.036032)
		(end 181.023006 -271.842992)
		(width 0.18288)
		(layer "In11.Cu")
		(net "M_H_CPU1_SA_CB<5>")
	)
	(segment
		(start 185.536586 -271.289018)
		(end 185.343546 -271.095978)
		(width 0.18288)
		(layer "In11.Cu")
		(net "M_H_CPU1_SA_CB<5>")
	)
	(segment
		(start 135.99795 -258.478782)
		(end 135.997696 -258.478782)
		(width 0.088646)
		(layer "In11.Cu")
		(net "M_H_CPU1_SA_CB<5>")
	)
	(segment
		(start 200.117456 -271.925034)
		(end 198.945246 -271.925034)
		(width 0.18288)
		(layer "In11.Cu")
		(net "M_H_CPU1_SA_CB<5>")
	)
	(segment
		(start 181.919626 -271.403826)
		(end 181.726586 -271.596866)
		(width 0.18288)
		(layer "In11.Cu")
		(net "M_H_CPU1_SA_CB<5>")
	)
	(segment
		(start 166.740078 -270.922242)
		(end 166.547038 -270.729202)
		(width 0.18288)
		(layer "In11.Cu")
		(net "M_H_CPU1_SA_CB<5>")
	)
	(segment
		(start 140.138658 -259.92455)
		(end 139.98575 -259.92455)
		(width 0.18288)
		(layer "In11.Cu")
		(net "M_H_CPU1_SA_CB<5>")
	)
	(segment
		(start 174.273464 -270.840962)
		(end 173.977554 -271.136872)
		(width 0.18288)
		(layer "In11.Cu")
		(net "M_H_CPU1_SA_CB<5>")
	)
	(segment
		(start 183.321452 -271.403826)
		(end 181.919626 -271.403826)
		(width 0.18288)
		(layer "In11.Cu")
		(net "M_H_CPU1_SA_CB<5>")
	)
	(segment
		(start 178.33467 -271.403826)
		(end 177.981864 -271.403826)
		(width 0.18288)
		(layer "In11.Cu")
		(net "M_H_CPU1_SA_CB<5>")
	)
	(segment
		(start 127.928878 -258.487418)
		(end 127.914146 -258.478782)
		(width 0.088646)
		(layer "In11.Cu")
		(net "M_H_CPU1_SA_CB<5>")
	)
	(segment
		(start 165.843458 -270.729202)
		(end 165.650418 -270.922242)
		(width 0.18288)
		(layer "In11.Cu")
		(net "M_H_CPU1_SA_CB<5>")
	)
	(segment
		(start 185.150506 -270.62938)
		(end 184.095898 -270.62938)
		(width 0.18288)
		(layer "In11.Cu")
		(net "M_H_CPU1_SA_CB<5>")
	)
	(segment
		(start 170.859958 -270.824198)
		(end 170.859958 -271.131284)
		(width 0.18288)
		(layer "In11.Cu")
		(net "M_H_CPU1_SA_CB<5>")
	)
	(segment
		(start 125.10643 -259.288026)
		(end 124.826522 -259.288026)
		(width 0.088646)
		(layer "In11.Cu")
		(net "M_H_CPU1_SA_CB<5>")
	)
	(segment
		(start 132.627878 -258.487418)
		(end 132.613146 -258.478782)
		(width 0.088646)
		(layer "In11.Cu")
		(net "M_H_CPU1_SA_CB<5>")
	)
	(segment
		(start 175.645826 -271.022826)
		(end 174.90821 -271.022826)
		(width 0.18288)
		(layer "In11.Cu")
		(net "M_H_CPU1_SA_CB<5>")
	)
	(segment
		(start 179.582826 -271.911826)
		(end 178.84267 -271.911826)
		(width 0.18288)
		(layer "In11.Cu")
		(net "M_H_CPU1_SA_CB<5>")
	)
	(segment
		(start 191.318642 -271.534636)
		(end 188.952632 -271.534636)
		(width 0.18288)
		(layer "In11.Cu")
		(net "M_H_CPU1_SA_CB<5>")
	)
	(segment
		(start 202.971146 -271.266666)
		(end 202.312778 -271.925034)
		(width 0.18288)
		(layer "In11.Cu")
		(net "M_H_CPU1_SA_CB<5>")
	)
	(segment
		(start 170.349418 -271.324324)
		(end 170.156378 -271.131284)
		(width 0.18288)
		(layer "In11.Cu")
		(net "M_H_CPU1_SA_CB<5>")
	)
	(arc
		(start 134.11835 -258.478782)
		(mid 133.835648 -258.554524)
		(end 133.552946 -258.478782)
		(width 0.088646)
		(layer "In11.Cu")
		(net "M_H_CPU1_SA_CB<5>")
	)
	(arc
		(start 135.997696 -258.478782)
		(mid 135.714994 -258.554524)
		(end 135.432292 -258.478782)
		(width 0.088646)
		(layer "In11.Cu")
		(net "M_H_CPU1_SA_CB<5>")
	)
	(arc
		(start 124.826522 -259.288026)
		(mid 124.481068 -259.219311)
		(end 124.18822 -259.023612)
		(width 0.088646)
		(layer "In11.Cu")
		(net "M_H_CPU1_SA_CB<5>")
	)
	(arc
		(start 132.23875 -258.478782)
		(mid 131.956048 -258.554524)
		(end 131.673346 -258.478782)
		(width 0.088646)
		(layer "In11.Cu")
		(net "M_H_CPU1_SA_CB<5>")
	)
	(arc
		(start 126.59995 -258.478782)
		(mid 126.325721 -258.554707)
		(end 126.049278 -258.487418)
		(width 0.088646)
		(layer "In11.Cu")
		(net "M_H_CPU1_SA_CB<5>")
	)
	(arc
		(start 125.472444 -258.922012)
		(mid 125.365241 -259.180823)
		(end 125.10643 -259.288026)
		(width 0.088646)
		(layer "In11.Cu")
		(net "M_H_CPU1_SA_CB<5>")
	)
	(arc
		(start 128.853946 -258.478782)
		(mid 128.666748 -258.428639)
		(end 128.47955 -258.478782)
		(width 0.088646)
		(layer "In11.Cu")
		(net "M_H_CPU1_SA_CB<5>")
	)
	(arc
		(start 135.057896 -258.478782)
		(mid 134.775448 -258.554431)
		(end 134.493 -258.478782)
		(width 0.088646)
		(layer "In11.Cu")
		(net "M_H_CPU1_SA_CB<5>")
	)
	(arc
		(start 126.9746 -258.478782)
		(mid 126.787292 -258.428639)
		(end 126.59995 -258.478782)
		(width 0.088646)
		(layer "In11.Cu")
		(net "M_H_CPU1_SA_CB<5>")
	)
	(arc
		(start 129.419096 -258.478782)
		(mid 129.142537 -258.554491)
		(end 128.86436 -258.484878)
		(width 0.088646)
		(layer "In11.Cu")
		(net "M_H_CPU1_SA_CB<5>")
	)
	(arc
		(start 136.372092 -258.478782)
		(mid 136.185038 -258.428732)
		(end 135.99795 -258.478782)
		(width 0.088646)
		(layer "In11.Cu")
		(net "M_H_CPU1_SA_CB<5>")
	)
	(arc
		(start 130.733546 -258.478782)
		(mid 130.546348 -258.428639)
		(end 130.35915 -258.478782)
		(width 0.088646)
		(layer "In11.Cu")
		(net "M_H_CPU1_SA_CB<5>")
	)
	(arc
		(start 131.29895 -258.478782)
		(mid 131.024721 -258.554707)
		(end 130.748278 -258.487418)
		(width 0.088646)
		(layer "In11.Cu")
		(net "M_H_CPU1_SA_CB<5>")
	)
	(arc
		(start 132.613146 -258.478782)
		(mid 132.425948 -258.428639)
		(end 132.23875 -258.478782)
		(width 0.088646)
		(layer "In11.Cu")
		(net "M_H_CPU1_SA_CB<5>")
	)
	(arc
		(start 127.914146 -258.478782)
		(mid 127.726948 -258.428639)
		(end 127.53975 -258.478782)
		(width 0.088646)
		(layer "In11.Cu")
		(net "M_H_CPU1_SA_CB<5>")
	)
	(arc
		(start 133.17855 -258.478782)
		(mid 132.904321 -258.554707)
		(end 132.627878 -258.487418)
		(width 0.088646)
		(layer "In11.Cu")
		(net "M_H_CPU1_SA_CB<5>")
	)
	(arc
		(start 125.659642 -258.479036)
		(mid 125.522597 -258.615996)
		(end 125.472444 -258.80314)
		(width 0.088646)
		(layer "In11.Cu")
		(net "M_H_CPU1_SA_CB<5>")
	)
	(arc
		(start 129.793492 -258.478782)
		(mid 129.606294 -258.428639)
		(end 129.419096 -258.478782)
		(width 0.088646)
		(layer "In11.Cu")
		(net "M_H_CPU1_SA_CB<5>")
	)
	(arc
		(start 137.594848 -258.554728)
		(mid 137.448378 -258.535368)
		(end 137.311892 -258.478782)
		(width 0.088646)
		(layer "In11.Cu")
		(net "M_H_CPU1_SA_CB<5>")
	)
	(arc
		(start 135.432038 -258.478782)
		(mid 135.244984 -258.428732)
		(end 135.057896 -258.478782)
		(width 0.088646)
		(layer "In11.Cu")
		(net "M_H_CPU1_SA_CB<5>")
	)
	(arc
		(start 134.492746 -258.478782)
		(mid 134.305548 -258.428639)
		(end 134.11835 -258.478782)
		(width 0.088646)
		(layer "In11.Cu")
		(net "M_H_CPU1_SA_CB<5>")
	)
	(arc
		(start 137.311892 -258.478782)
		(mid 137.124694 -258.428639)
		(end 136.937496 -258.478782)
		(width 0.088646)
		(layer "In11.Cu")
		(net "M_H_CPU1_SA_CB<5>")
	)
	(arc
		(start 126.034546 -258.478782)
		(mid 125.847348 -258.428639)
		(end 125.66015 -258.478782)
		(width 0.088646)
		(layer "In11.Cu")
		(net "M_H_CPU1_SA_CB<5>")
	)
	(arc
		(start 128.47955 -258.478782)
		(mid 128.205321 -258.554707)
		(end 127.928878 -258.487418)
		(width 0.088646)
		(layer "In11.Cu")
		(net "M_H_CPU1_SA_CB<5>")
	)
	(arc
		(start 130.35915 -258.478782)
		(mid 130.082337 -258.554618)
		(end 129.803906 -258.484878)
		(width 0.088646)
		(layer "In11.Cu")
		(net "M_H_CPU1_SA_CB<5>")
	)
	(arc
		(start 127.53975 -258.478782)
		(mid 127.257192 -258.554397)
		(end 126.9746 -258.478782)
		(width 0.088646)
		(layer "In11.Cu")
		(net "M_H_CPU1_SA_CB<5>")
	)
	(arc
		(start 131.673346 -258.478782)
		(mid 131.486148 -258.428639)
		(end 131.29895 -258.478782)
		(width 0.088646)
		(layer "In11.Cu")
		(net "M_H_CPU1_SA_CB<5>")
	)
	(arc
		(start 136.922764 -258.487418)
		(mid 136.646323 -258.554584)
		(end 136.372092 -258.478782)
		(width 0.088646)
		(layer "In11.Cu")
		(net "M_H_CPU1_SA_CB<5>")
	)
	(arc
		(start 133.552946 -258.478782)
		(mid 133.365748 -258.428639)
		(end 133.17855 -258.478782)
		(width 0.088646)
		(layer "In11.Cu")
		(net "M_H_CPU1_SA_CB<5>")
	)
	(segment
		(start 206.508604 -273.027394)
		(end 206.320644 -273.215354)
		(width 0.20066)
		(layer "F.Cu")
		(net "M_H_CPU1_SA_CB<4>")
	)
	(segment
		(start 209.180176 -272.541746)
		(end 207.018382 -272.541746)
		(width 0.1016)
		(layer "F.Cu")
		(net "M_H_CPU1_SA_CB<4>")
	)
	(segment
		(start 209.596482 -272.535396)
		(end 209.186526 -272.535396)
		(width 0.20066)
		(layer "F.Cu")
		(net "M_H_CPU1_SA_CB<4>")
	)
	(segment
		(start 205.596744 -272.966688)
		(end 204.076046 -272.966688)
		(width 0.20066)
		(layer "F.Cu")
		(net "M_H_CPU1_SA_CB<4>")
	)
	(segment
		(start 206.971392 -272.541746)
		(end 206.626714 -272.541746)
		(width 0.20066)
		(layer "F.Cu")
		(net "M_H_CPU1_SA_CB<4>")
	)
	(segment
		(start 206.626714 -272.541746)
		(end 206.508604 -272.659856)
		(width 0.20066)
		(layer "F.Cu")
		(net "M_H_CPU1_SA_CB<4>")
	)
	(segment
		(start 123.497848 -259.081016)
		(end 123.497848 -259.093462)
		(width 0.20066)
		(layer "F.Cu")
		(net "M_H_CPU1_SA_CB<4>")
	)
	(segment
		(start 123.497848 -259.093462)
		(end 123.497594 -259.616956)
		(width 0.20066)
		(layer "F.Cu")
		(net "M_H_CPU1_SA_CB<4>")
	)
	(segment
		(start 205.84541 -273.215354)
		(end 205.596744 -272.966688)
		(width 0.20066)
		(layer "F.Cu")
		(net "M_H_CPU1_SA_CB<4>")
	)
	(segment
		(start 207.018382 -272.541746)
		(end 206.971392 -272.541746)
		(width 0.101854)
		(layer "F.Cu")
		(net "M_H_CPU1_SA_CB<4>")
	)
	(segment
		(start 209.186526 -272.535396)
		(end 209.180176 -272.541746)
		(width 0.1016)
		(layer "F.Cu")
		(net "M_H_CPU1_SA_CB<4>")
	)
	(segment
		(start 211.619846 -272.966688)
		(end 211.619592 -272.966942)
		(width 0.20066)
		(layer "F.Cu")
		(net "M_H_CPU1_SA_CB<4>")
	)
	(segment
		(start 206.320644 -273.215354)
		(end 205.84541 -273.215354)
		(width 0.20066)
		(layer "F.Cu")
		(net "M_H_CPU1_SA_CB<4>")
	)
	(segment
		(start 210.028028 -272.966942)
		(end 209.596482 -272.535396)
		(width 0.20066)
		(layer "F.Cu")
		(net "M_H_CPU1_SA_CB<4>")
	)
	(segment
		(start 211.619592 -272.966942)
		(end 210.028028 -272.966942)
		(width 0.20066)
		(layer "F.Cu")
		(net "M_H_CPU1_SA_CB<4>")
	)
	(segment
		(start 206.508604 -272.659856)
		(end 206.508604 -273.027394)
		(width 0.20066)
		(layer "F.Cu")
		(net "M_H_CPU1_SA_CB<4>")
	)
	(segment
		(start 204.076046 -272.966688)
		(end 202.971146 -272.966688)
		(width 0.20066)
		(layer "F.Cu")
		(net "M_H_CPU1_SA_CB<4>")
	)
	(segment
		(start 196.069204 -273.982434)
		(end 196.069204 -274.508214)
		(width 0.18288)
		(layer "In11.Cu")
		(net "M_H_CPU1_SA_CB<4>")
	)
	(segment
		(start 202.971146 -272.966688)
		(end 202.652376 -272.966942)
		(width 0.18288)
		(layer "In11.Cu")
		(net "M_H_CPU1_SA_CB<4>")
	)
	(segment
		(start 137.790428 -259.297678)
		(end 137.781538 -259.292598)
		(width 0.088646)
		(layer "In11.Cu")
		(net "M_H_CPU1_SA_CB<4>")
	)
	(segment
		(start 125.793246 -259.63499)
		(end 125.70714 -259.794756)
		(width 0.088646)
		(layer "In11.Cu")
		(net "M_H_CPU1_SA_CB<4>")
	)
	(segment
		(start 170.257724 -273.29257)
		(end 169.940224 -273.29257)
		(width 0.18288)
		(layer "In11.Cu")
		(net "M_H_CPU1_SA_CB<4>")
	)
	(segment
		(start 140.747242 -262.11403)
		(end 139.986004 -261.352792)
		(width 0.18288)
		(layer "In11.Cu")
		(net "M_H_CPU1_SA_CB<4>")
	)
	(segment
		(start 166.364158 -273.65325)
		(end 166.046658 -273.65325)
		(width 0.18288)
		(layer "In11.Cu")
		(net "M_H_CPU1_SA_CB<4>")
	)
	(segment
		(start 146.518376 -262.11403)
		(end 140.747242 -262.11403)
		(width 0.18288)
		(layer "In11.Cu")
		(net "M_H_CPU1_SA_CB<4>")
	)
	(segment
		(start 178.870102 -273.51355)
		(end 178.749198 -273.392646)
		(width 0.18288)
		(layer "In11.Cu")
		(net "M_H_CPU1_SA_CB<4>")
	)
	(segment
		(start 175.916844 -272.970244)
		(end 173.801786 -272.970244)
		(width 0.18288)
		(layer "In11.Cu")
		(net "M_H_CPU1_SA_CB<4>")
	)
	(segment
		(start 188.838078 -273.179794)
		(end 188.199268 -272.540984)
		(width 0.18288)
		(layer "In11.Cu")
		(net "M_H_CPU1_SA_CB<4>")
	)
	(segment
		(start 196.069204 -274.508214)
		(end 195.876164 -274.701254)
		(width 0.18288)
		(layer "In11.Cu")
		(net "M_H_CPU1_SA_CB<4>")
	)
	(segment
		(start 196.965824 -274.769326)
		(end 196.772784 -274.576286)
		(width 0.18288)
		(layer "In11.Cu")
		(net "M_H_CPU1_SA_CB<4>")
	)
	(segment
		(start 138.817858 -260.672326)
		(end 138.252454 -260.106922)
		(width 0.088646)
		(layer "In11.Cu")
		(net "M_H_CPU1_SA_CB<4>")
	)
	(segment
		(start 186.159648 -272.386806)
		(end 185.966608 -272.579846)
		(width 0.18288)
		(layer "In11.Cu")
		(net "M_H_CPU1_SA_CB<4>")
	)
	(segment
		(start 192.947036 -274.004532)
		(end 192.33388 -273.391376)
		(width 0.18288)
		(layer "In11.Cu")
		(net "M_H_CPU1_SA_CB<4>")
	)
	(segment
		(start 132.708396 -259.292598)
		(end 132.693664 -259.301234)
		(width 0.088646)
		(layer "In11.Cu")
		(net "M_H_CPU1_SA_CB<4>")
	)
	(segment
		(start 169.940224 -273.29257)
		(end 169.747184 -273.09953)
		(width 0.18288)
		(layer "In11.Cu")
		(net "M_H_CPU1_SA_CB<4>")
	)
	(segment
		(start 165.853618 -273.46021)
		(end 165.853618 -272.900394)
		(width 0.18288)
		(layer "In11.Cu")
		(net "M_H_CPU1_SA_CB<4>")
	)
	(segment
		(start 172.280326 -272.540476)
		(end 172.094906 -272.355056)
		(width 0.18288)
		(layer "In11.Cu")
		(net "M_H_CPU1_SA_CB<4>")
	)
	(segment
		(start 185.069988 -272.386806)
		(end 184.060846 -272.386806)
		(width 0.18288)
		(layer "In11.Cu")
		(net "M_H_CPU1_SA_CB<4>")
	)
	(segment
		(start 199.055482 -273.39798)
		(end 198.619618 -273.833844)
		(width 0.18288)
		(layer "In11.Cu")
		(net "M_H_CPU1_SA_CB<4>")
	)
	(segment
		(start 198.43496 -273.833844)
		(end 197.499478 -274.769326)
		(width 0.18288)
		(layer "In11.Cu")
		(net "M_H_CPU1_SA_CB<4>")
	)
	(segment
		(start 139.305538 -260.672326)
		(end 138.817858 -260.672326)
		(width 0.088646)
		(layer "In11.Cu")
		(net "M_H_CPU1_SA_CB<4>")
	)
	(segment
		(start 185.966608 -272.932906)
		(end 185.773568 -273.125946)
		(width 0.18288)
		(layer "In11.Cu")
		(net "M_H_CPU1_SA_CB<4>")
	)
	(segment
		(start 179.73167 -273.51355)
		(end 178.870102 -273.51355)
		(width 0.18288)
		(layer "In11.Cu")
		(net "M_H_CPU1_SA_CB<4>")
	)
	(segment
		(start 196.772784 -274.576286)
		(end 196.772784 -273.982434)
		(width 0.18288)
		(layer "In11.Cu")
		(net "M_H_CPU1_SA_CB<4>")
	)
	(segment
		(start 133.648196 -259.292598)
		(end 133.633464 -259.301234)
		(width 0.088646)
		(layer "In11.Cu")
		(net "M_H_CPU1_SA_CB<4>")
	)
	(segment
		(start 185.456068 -273.125946)
		(end 185.263028 -272.932906)
		(width 0.18288)
		(layer "In11.Cu")
		(net "M_H_CPU1_SA_CB<4>")
	)
	(segment
		(start 130.828796 -259.292598)
		(end 130.814064 -259.301234)
		(width 0.088646)
		(layer "In11.Cu")
		(net "M_H_CPU1_SA_CB<4>")
	)
	(segment
		(start 195.142866 -274.24126)
		(end 193.825622 -274.24126)
		(width 0.18288)
		(layer "In11.Cu")
		(net "M_H_CPU1_SA_CB<4>")
	)
	(segment
		(start 125.573536 -259.936234)
		(end 125.572012 -259.936742)
		(width 0.088646)
		(layer "In11.Cu")
		(net "M_H_CPU1_SA_CB<4>")
	)
	(segment
		(start 138.252454 -260.106922)
		(end 138.251692 -260.106414)
		(width 0.088646)
		(layer "In11.Cu")
		(net "M_H_CPU1_SA_CB<4>")
	)
	(segment
		(start 165.853618 -272.900394)
		(end 165.660578 -272.707354)
		(width 0.18288)
		(layer "In11.Cu")
		(net "M_H_CPU1_SA_CB<4>")
	)
	(segment
		(start 166.750238 -272.707354)
		(end 166.557198 -272.900394)
		(width 0.18288)
		(layer "In11.Cu")
		(net "M_H_CPU1_SA_CB<4>")
	)
	(segment
		(start 125.189996 -259.941314)
		(end 125.175264 -259.932678)
		(width 0.088646)
		(layer "In11.Cu")
		(net "M_H_CPU1_SA_CB<4>")
	)
	(segment
		(start 173.372018 -272.540476)
		(end 172.280326 -272.540476)
		(width 0.18288)
		(layer "In11.Cu")
		(net "M_H_CPU1_SA_CB<4>")
	)
	(segment
		(start 170.450764 -273.09953)
		(end 170.257724 -273.29257)
		(width 0.18288)
		(layer "In11.Cu")
		(net "M_H_CPU1_SA_CB<4>")
	)
	(segment
		(start 197.499478 -274.769326)
		(end 196.965824 -274.769326)
		(width 0.18288)
		(layer "In11.Cu")
		(net "M_H_CPU1_SA_CB<4>")
	)
	(segment
		(start 136.467342 -259.292598)
		(end 136.45261 -259.301234)
		(width 0.088646)
		(layer "In11.Cu")
		(net "M_H_CPU1_SA_CB<4>")
	)
	(segment
		(start 125.941074 -259.437378)
		(end 125.938026 -259.440426)
		(width 0.088646)
		(layer "In11.Cu")
		(net "M_H_CPU1_SA_CB<4>")
	)
	(segment
		(start 169.554144 -272.355056)
		(end 168.307004 -272.355056)
		(width 0.18288)
		(layer "In11.Cu")
		(net "M_H_CPU1_SA_CB<4>")
	)
	(segment
		(start 161.563812 -272.536412)
		(end 161.390076 -272.362676)
		(width 0.18288)
		(layer "In11.Cu")
		(net "M_H_CPU1_SA_CB<4>")
	)
	(segment
		(start 134.587996 -259.292598)
		(end 134.573264 -259.301234)
		(width 0.088646)
		(layer "In11.Cu")
		(net "M_H_CPU1_SA_CB<4>")
	)
	(segment
		(start 196.772784 -273.982434)
		(end 196.579744 -273.789394)
		(width 0.18288)
		(layer "In11.Cu")
		(net "M_H_CPU1_SA_CB<4>")
	)
	(segment
		(start 168.307004 -272.355056)
		(end 167.954706 -272.707354)
		(width 0.18288)
		(layer "In11.Cu")
		(net "M_H_CPU1_SA_CB<4>")
	)
	(segment
		(start 186.814206 -272.386806)
		(end 186.159648 -272.386806)
		(width 0.18288)
		(layer "In11.Cu")
		(net "M_H_CPU1_SA_CB<4>")
	)
	(segment
		(start 167.954706 -272.707354)
		(end 166.750238 -272.707354)
		(width 0.18288)
		(layer "In11.Cu")
		(net "M_H_CPU1_SA_CB<4>")
	)
	(segment
		(start 185.263028 -272.579846)
		(end 185.069988 -272.386806)
		(width 0.18288)
		(layer "In11.Cu")
		(net "M_H_CPU1_SA_CB<4>")
	)
	(segment
		(start 170.643804 -272.355056)
		(end 170.450764 -272.548096)
		(width 0.18288)
		(layer "In11.Cu")
		(net "M_H_CPU1_SA_CB<4>")
	)
	(segment
		(start 156.951426 -272.54708)
		(end 146.518376 -262.11403)
		(width 0.18288)
		(layer "In11.Cu")
		(net "M_H_CPU1_SA_CB<4>")
	)
	(segment
		(start 193.825622 -274.24126)
		(end 193.588894 -274.004532)
		(width 0.18288)
		(layer "In11.Cu")
		(net "M_H_CPU1_SA_CB<4>")
	)
	(segment
		(start 176.339246 -273.392646)
		(end 175.916844 -272.970244)
		(width 0.18288)
		(layer "In11.Cu")
		(net "M_H_CPU1_SA_CB<4>")
	)
	(segment
		(start 165.660578 -272.707354)
		(end 164.84473 -272.707354)
		(width 0.18288)
		(layer "In11.Cu")
		(net "M_H_CPU1_SA_CB<4>")
	)
	(segment
		(start 185.966608 -272.579846)
		(end 185.966608 -272.932906)
		(width 0.18288)
		(layer "In11.Cu")
		(net "M_H_CPU1_SA_CB<4>")
	)
	(segment
		(start 124.250196 -259.941314)
		(end 123.853194 -259.712206)
		(width 0.088646)
		(layer "In11.Cu")
		(net "M_H_CPU1_SA_CB<4>")
	)
	(segment
		(start 184.060846 -272.386806)
		(end 183.357774 -273.089878)
		(width 0.18288)
		(layer "In11.Cu")
		(net "M_H_CPU1_SA_CB<4>")
	)
	(segment
		(start 202.652376 -272.966942)
		(end 202.350878 -272.966942)
		(width 0.18288)
		(layer "In11.Cu")
		(net "M_H_CPU1_SA_CB<4>")
	)
	(segment
		(start 172.094906 -272.355056)
		(end 170.643804 -272.355056)
		(width 0.18288)
		(layer "In11.Cu")
		(net "M_H_CPU1_SA_CB<4>")
	)
	(segment
		(start 192.33388 -273.391376)
		(end 190.406782 -273.391376)
		(width 0.18288)
		(layer "In11.Cu")
		(net "M_H_CPU1_SA_CB<4>")
	)
	(segment
		(start 193.588894 -274.004532)
		(end 192.947036 -274.004532)
		(width 0.18288)
		(layer "In11.Cu")
		(net "M_H_CPU1_SA_CB<4>")
	)
	(segment
		(start 164.84473 -272.707354)
		(end 164.673788 -272.536412)
		(width 0.18288)
		(layer "In11.Cu")
		(net "M_H_CPU1_SA_CB<4>")
	)
	(segment
		(start 188.199268 -272.540984)
		(end 186.968384 -272.540984)
		(width 0.18288)
		(layer "In11.Cu")
		(net "M_H_CPU1_SA_CB<4>")
	)
	(segment
		(start 139.986004 -261.352792)
		(end 139.305538 -260.672326)
		(width 0.088646)
		(layer "In11.Cu")
		(net "M_H_CPU1_SA_CB<4>")
	)
	(segment
		(start 185.263028 -272.932906)
		(end 185.263028 -272.579846)
		(width 0.18288)
		(layer "In11.Cu")
		(net "M_H_CPU1_SA_CB<4>")
	)
	(segment
		(start 186.968384 -272.540984)
		(end 186.814206 -272.386806)
		(width 0.18288)
		(layer "In11.Cu")
		(net "M_H_CPU1_SA_CB<4>")
	)
	(segment
		(start 196.579744 -273.789394)
		(end 196.262244 -273.789394)
		(width 0.18288)
		(layer "In11.Cu")
		(net "M_H_CPU1_SA_CB<4>")
	)
	(segment
		(start 173.801786 -272.970244)
		(end 173.372018 -272.540476)
		(width 0.18288)
		(layer "In11.Cu")
		(net "M_H_CPU1_SA_CB<4>")
	)
	(segment
		(start 128.009396 -259.292598)
		(end 127.994664 -259.301234)
		(width 0.088646)
		(layer "In11.Cu")
		(net "M_H_CPU1_SA_CB<4>")
	)
	(segment
		(start 135.527542 -259.292598)
		(end 135.517128 -259.298694)
		(width 0.088646)
		(layer "In11.Cu")
		(net "M_H_CPU1_SA_CB<4>")
	)
	(segment
		(start 183.357774 -273.089878)
		(end 180.155342 -273.089878)
		(width 0.18288)
		(layer "In11.Cu")
		(net "M_H_CPU1_SA_CB<4>")
	)
	(segment
		(start 138.251692 -260.106414)
		(end 138.245596 -260.102858)
		(width 0.088646)
		(layer "In11.Cu")
		(net "M_H_CPU1_SA_CB<4>")
	)
	(segment
		(start 160.392872 -272.54708)
		(end 156.951426 -272.54708)
		(width 0.18288)
		(layer "In11.Cu")
		(net "M_H_CPU1_SA_CB<4>")
	)
	(segment
		(start 180.155342 -273.089878)
		(end 179.73167 -273.51355)
		(width 0.18288)
		(layer "In11.Cu")
		(net "M_H_CPU1_SA_CB<4>")
	)
	(segment
		(start 166.557198 -272.900394)
		(end 166.557198 -273.46021)
		(width 0.18288)
		(layer "In11.Cu")
		(net "M_H_CPU1_SA_CB<4>")
	)
	(segment
		(start 178.749198 -273.392646)
		(end 176.339246 -273.392646)
		(width 0.18288)
		(layer "In11.Cu")
		(net "M_H_CPU1_SA_CB<4>")
	)
	(segment
		(start 169.747184 -273.09953)
		(end 169.747184 -272.548096)
		(width 0.18288)
		(layer "In11.Cu")
		(net "M_H_CPU1_SA_CB<4>")
	)
	(segment
		(start 190.406782 -273.391376)
		(end 190.1952 -273.179794)
		(width 0.18288)
		(layer "In11.Cu")
		(net "M_H_CPU1_SA_CB<4>")
	)
	(segment
		(start 160.577276 -272.362676)
		(end 160.392872 -272.54708)
		(width 0.18288)
		(layer "In11.Cu")
		(net "M_H_CPU1_SA_CB<4>")
	)
	(segment
		(start 198.619618 -273.833844)
		(end 198.43496 -273.833844)
		(width 0.18288)
		(layer "In11.Cu")
		(net "M_H_CPU1_SA_CB<4>")
	)
	(segment
		(start 166.046658 -273.65325)
		(end 165.853618 -273.46021)
		(width 0.18288)
		(layer "In11.Cu")
		(net "M_H_CPU1_SA_CB<4>")
	)
	(segment
		(start 169.747184 -272.548096)
		(end 169.554144 -272.355056)
		(width 0.18288)
		(layer "In11.Cu")
		(net "M_H_CPU1_SA_CB<4>")
	)
	(segment
		(start 201.91984 -273.39798)
		(end 199.055482 -273.39798)
		(width 0.18288)
		(layer "In11.Cu")
		(net "M_H_CPU1_SA_CB<4>")
	)
	(segment
		(start 195.60286 -274.701254)
		(end 195.142866 -274.24126)
		(width 0.18288)
		(layer "In11.Cu")
		(net "M_H_CPU1_SA_CB<4>")
	)
	(segment
		(start 128.949196 -259.292598)
		(end 128.934464 -259.301234)
		(width 0.088646)
		(layer "In11.Cu")
		(net "M_H_CPU1_SA_CB<4>")
	)
	(segment
		(start 190.1952 -273.179794)
		(end 188.838078 -273.179794)
		(width 0.18288)
		(layer "In11.Cu")
		(net "M_H_CPU1_SA_CB<4>")
	)
	(segment
		(start 137.407142 -259.292598)
		(end 137.39241 -259.301234)
		(width 0.088646)
		(layer "In11.Cu")
		(net "M_H_CPU1_SA_CB<4>")
	)
	(segment
		(start 131.768596 -259.292598)
		(end 131.753864 -259.301234)
		(width 0.088646)
		(layer "In11.Cu")
		(net "M_H_CPU1_SA_CB<4>")
	)
	(segment
		(start 164.673788 -272.536412)
		(end 161.563812 -272.536412)
		(width 0.18288)
		(layer "In11.Cu")
		(net "M_H_CPU1_SA_CB<4>")
	)
	(segment
		(start 170.450764 -272.548096)
		(end 170.450764 -273.09953)
		(width 0.18288)
		(layer "In11.Cu")
		(net "M_H_CPU1_SA_CB<4>")
	)
	(segment
		(start 185.773568 -273.125946)
		(end 185.456068 -273.125946)
		(width 0.18288)
		(layer "In11.Cu")
		(net "M_H_CPU1_SA_CB<4>")
	)
	(segment
		(start 127.069596 -259.292598)
		(end 127.054864 -259.301234)
		(width 0.088646)
		(layer "In11.Cu")
		(net "M_H_CPU1_SA_CB<4>")
	)
	(segment
		(start 202.350878 -272.966942)
		(end 201.91984 -273.39798)
		(width 0.18288)
		(layer "In11.Cu")
		(net "M_H_CPU1_SA_CB<4>")
	)
	(segment
		(start 195.876164 -274.701254)
		(end 195.60286 -274.701254)
		(width 0.18288)
		(layer "In11.Cu")
		(net "M_H_CPU1_SA_CB<4>")
	)
	(segment
		(start 166.557198 -273.46021)
		(end 166.364158 -273.65325)
		(width 0.18288)
		(layer "In11.Cu")
		(net "M_H_CPU1_SA_CB<4>")
	)
	(segment
		(start 196.262244 -273.789394)
		(end 196.069204 -273.982434)
		(width 0.18288)
		(layer "In11.Cu")
		(net "M_H_CPU1_SA_CB<4>")
	)
	(segment
		(start 161.390076 -272.362676)
		(end 160.577276 -272.362676)
		(width 0.18288)
		(layer "In11.Cu")
		(net "M_H_CPU1_SA_CB<4>")
	)
	(arc
		(start 135.517128 -259.298694)
		(mid 135.23895 -259.368417)
		(end 134.962392 -259.292598)
		(width 0.088646)
		(layer "In11.Cu")
		(net "M_H_CPU1_SA_CB<4>")
	)
	(arc
		(start 125.938026 -259.440426)
		(mid 125.858537 -259.532426)
		(end 125.793246 -259.63499)
		(width 0.088646)
		(layer "In11.Cu")
		(net "M_H_CPU1_SA_CB<4>")
	)
	(arc
		(start 135.901938 -259.292598)
		(mid 135.71474 -259.242455)
		(end 135.527542 -259.292598)
		(width 0.088646)
		(layer "In11.Cu")
		(net "M_H_CPU1_SA_CB<4>")
	)
	(arc
		(start 137.39241 -259.301234)
		(mid 137.115935 -259.368554)
		(end 136.841738 -259.292598)
		(width 0.088646)
		(layer "In11.Cu")
		(net "M_H_CPU1_SA_CB<4>")
	)
	(arc
		(start 136.841738 -259.292598)
		(mid 136.65454 -259.242455)
		(end 136.467342 -259.292598)
		(width 0.088646)
		(layer "In11.Cu")
		(net "M_H_CPU1_SA_CB<4>")
	)
	(arc
		(start 132.142992 -259.292598)
		(mid 131.955794 -259.242455)
		(end 131.768596 -259.292598)
		(width 0.088646)
		(layer "In11.Cu")
		(net "M_H_CPU1_SA_CB<4>")
	)
	(arc
		(start 125.175264 -259.932678)
		(mid 124.898789 -259.865358)
		(end 124.624592 -259.941314)
		(width 0.088646)
		(layer "In11.Cu")
		(net "M_H_CPU1_SA_CB<4>")
	)
	(arc
		(start 136.45261 -259.301234)
		(mid 136.176135 -259.368554)
		(end 135.901938 -259.292598)
		(width 0.088646)
		(layer "In11.Cu")
		(net "M_H_CPU1_SA_CB<4>")
	)
	(arc
		(start 134.573264 -259.301234)
		(mid 134.296789 -259.368554)
		(end 134.022592 -259.292598)
		(width 0.088646)
		(layer "In11.Cu")
		(net "M_H_CPU1_SA_CB<4>")
	)
	(arc
		(start 127.443992 -259.292598)
		(mid 127.256794 -259.242455)
		(end 127.069596 -259.292598)
		(width 0.088646)
		(layer "In11.Cu")
		(net "M_H_CPU1_SA_CB<4>")
	)
	(arc
		(start 137.96899 -259.616956)
		(mid 137.921311 -259.434056)
		(end 137.790428 -259.297678)
		(width 0.088646)
		(layer "In11.Cu")
		(net "M_H_CPU1_SA_CB<4>")
	)
	(arc
		(start 126.129796 -259.292598)
		(mid 126.030695 -259.358809)
		(end 125.941074 -259.437378)
		(width 0.088646)
		(layer "In11.Cu")
		(net "M_H_CPU1_SA_CB<4>")
	)
	(arc
		(start 137.781538 -259.292598)
		(mid 137.59434 -259.242455)
		(end 137.407142 -259.292598)
		(width 0.088646)
		(layer "In11.Cu")
		(net "M_H_CPU1_SA_CB<4>")
	)
	(arc
		(start 131.203192 -259.292598)
		(mid 131.015994 -259.242455)
		(end 130.828796 -259.292598)
		(width 0.088646)
		(layer "In11.Cu")
		(net "M_H_CPU1_SA_CB<4>")
	)
	(arc
		(start 125.70714 -259.794756)
		(mid 125.649675 -259.874311)
		(end 125.573536 -259.936234)
		(width 0.088646)
		(layer "In11.Cu")
		(net "M_H_CPU1_SA_CB<4>")
	)
	(arc
		(start 130.814064 -259.301234)
		(mid 130.537589 -259.368554)
		(end 130.263392 -259.292598)
		(width 0.088646)
		(layer "In11.Cu")
		(net "M_H_CPU1_SA_CB<4>")
	)
	(arc
		(start 133.633464 -259.301234)
		(mid 133.356989 -259.368554)
		(end 133.082792 -259.292598)
		(width 0.088646)
		(layer "In11.Cu")
		(net "M_H_CPU1_SA_CB<4>")
	)
	(arc
		(start 130.263392 -259.292598)
		(mid 130.076194 -259.242455)
		(end 129.888996 -259.292598)
		(width 0.088646)
		(layer "In11.Cu")
		(net "M_H_CPU1_SA_CB<4>")
	)
	(arc
		(start 134.962392 -259.292598)
		(mid 134.775194 -259.242455)
		(end 134.587996 -259.292598)
		(width 0.088646)
		(layer "In11.Cu")
		(net "M_H_CPU1_SA_CB<4>")
	)
	(arc
		(start 128.383792 -259.292598)
		(mid 128.196594 -259.242455)
		(end 128.009396 -259.292598)
		(width 0.088646)
		(layer "In11.Cu")
		(net "M_H_CPU1_SA_CB<4>")
	)
	(arc
		(start 125.572012 -259.936742)
		(mid 125.381637 -259.991385)
		(end 125.189996 -259.941314)
		(width 0.088646)
		(layer "In11.Cu")
		(net "M_H_CPU1_SA_CB<4>")
	)
	(arc
		(start 133.082792 -259.292598)
		(mid 132.895594 -259.242455)
		(end 132.708396 -259.292598)
		(width 0.088646)
		(layer "In11.Cu")
		(net "M_H_CPU1_SA_CB<4>")
	)
	(arc
		(start 129.888996 -259.292598)
		(mid 129.606294 -259.368374)
		(end 129.323592 -259.292598)
		(width 0.088646)
		(layer "In11.Cu")
		(net "M_H_CPU1_SA_CB<4>")
	)
	(arc
		(start 124.624592 -259.941314)
		(mid 124.437394 -259.991457)
		(end 124.250196 -259.941314)
		(width 0.088646)
		(layer "In11.Cu")
		(net "M_H_CPU1_SA_CB<4>")
	)
	(arc
		(start 127.994664 -259.301234)
		(mid 127.718189 -259.368554)
		(end 127.443992 -259.292598)
		(width 0.088646)
		(layer "In11.Cu")
		(net "M_H_CPU1_SA_CB<4>")
	)
	(arc
		(start 128.934464 -259.301234)
		(mid 128.657989 -259.368554)
		(end 128.383792 -259.292598)
		(width 0.088646)
		(layer "In11.Cu")
		(net "M_H_CPU1_SA_CB<4>")
	)
	(arc
		(start 138.245596 -260.102858)
		(mid 138.043009 -259.896507)
		(end 137.96899 -259.616956)
		(width 0.088646)
		(layer "In11.Cu")
		(net "M_H_CPU1_SA_CB<4>")
	)
	(arc
		(start 129.323592 -259.292598)
		(mid 129.136394 -259.242455)
		(end 128.949196 -259.292598)
		(width 0.088646)
		(layer "In11.Cu")
		(net "M_H_CPU1_SA_CB<4>")
	)
	(arc
		(start 127.054864 -259.301234)
		(mid 126.778389 -259.368554)
		(end 126.504192 -259.292598)
		(width 0.088646)
		(layer "In11.Cu")
		(net "M_H_CPU1_SA_CB<4>")
	)
	(arc
		(start 134.022592 -259.292598)
		(mid 133.835394 -259.242455)
		(end 133.648196 -259.292598)
		(width 0.088646)
		(layer "In11.Cu")
		(net "M_H_CPU1_SA_CB<4>")
	)
	(arc
		(start 126.504192 -259.292598)
		(mid 126.316994 -259.242455)
		(end 126.129796 -259.292598)
		(width 0.088646)
		(layer "In11.Cu")
		(net "M_H_CPU1_SA_CB<4>")
	)
	(arc
		(start 123.853194 -259.712206)
		(mid 123.681661 -259.641185)
		(end 123.497594 -259.616956)
		(width 0.088646)
		(layer "In11.Cu")
		(net "M_H_CPU1_SA_CB<4>")
	)
	(arc
		(start 132.693664 -259.301234)
		(mid 132.417189 -259.368554)
		(end 132.142992 -259.292598)
		(width 0.088646)
		(layer "In11.Cu")
		(net "M_H_CPU1_SA_CB<4>")
	)
	(arc
		(start 131.753864 -259.301234)
		(mid 131.477389 -259.368554)
		(end 131.203192 -259.292598)
		(width 0.088646)
		(layer "In11.Cu")
		(net "M_H_CPU1_SA_CB<4>")
	)
	(segment
		(start 210.610196 -276.791674)
		(end 212.618066 -276.791674)
		(width 0.1016)
		(layer "F.Cu")
		(net "M_H_CPU1_SA_CB<3>")
	)
	(segment
		(start 125.377448 -260.708902)
		(end 125.377448 -261.244334)
		(width 0.20066)
		(layer "F.Cu")
		(net "M_H_CPU1_SA_CB<3>")
	)
	(segment
		(start 214.133684 -276.114764)
		(end 214.385652 -276.366732)
		(width 0.20066)
		(layer "F.Cu")
		(net "M_H_CPU1_SA_CB<3>")
	)
	(segment
		(start 208.176114 -276.366732)
		(end 209.874358 -276.366732)
		(width 0.20066)
		(layer "F.Cu")
		(net "M_H_CPU1_SA_CB<3>")
	)
	(segment
		(start 207.071214 -276.366732)
		(end 208.176114 -276.366732)
		(width 0.20066)
		(layer "F.Cu")
		(net "M_H_CPU1_SA_CB<3>")
	)
	(segment
		(start 209.874358 -276.366732)
		(end 210.306412 -276.798786)
		(width 0.20066)
		(layer "F.Cu")
		(net "M_H_CPU1_SA_CB<3>")
	)
	(segment
		(start 213.515448 -276.348952)
		(end 213.749636 -276.114764)
		(width 0.20066)
		(layer "F.Cu")
		(net "M_H_CPU1_SA_CB<3>")
	)
	(segment
		(start 213.749636 -276.114764)
		(end 214.133684 -276.114764)
		(width 0.20066)
		(layer "F.Cu")
		(net "M_H_CPU1_SA_CB<3>")
	)
	(segment
		(start 125.377448 -261.244334)
		(end 125.377194 -261.244588)
		(width 0.20066)
		(layer "F.Cu")
		(net "M_H_CPU1_SA_CB<3>")
	)
	(segment
		(start 125.377194 -261.244588)
		(end 125.377194 -261.244842)
		(width 0.20066)
		(layer "F.Cu")
		(net "M_H_CPU1_SA_CB<3>")
	)
	(segment
		(start 212.618066 -276.791674)
		(end 212.630258 -276.803866)
		(width 0.1016)
		(layer "F.Cu")
		(net "M_H_CPU1_SA_CB<3>")
	)
	(segment
		(start 213.515448 -276.599904)
		(end 213.515448 -276.348952)
		(width 0.20066)
		(layer "F.Cu")
		(net "M_H_CPU1_SA_CB<3>")
	)
	(segment
		(start 213.311486 -276.803866)
		(end 213.515448 -276.599904)
		(width 0.20066)
		(layer "F.Cu")
		(net "M_H_CPU1_SA_CB<3>")
	)
	(segment
		(start 210.306412 -276.798786)
		(end 210.598258 -276.798786)
		(width 0.20066)
		(layer "F.Cu")
		(net "M_H_CPU1_SA_CB<3>")
	)
	(segment
		(start 212.630258 -276.803866)
		(end 213.311486 -276.803866)
		(width 0.20066)
		(layer "F.Cu")
		(net "M_H_CPU1_SA_CB<3>")
	)
	(segment
		(start 210.603084 -276.798786)
		(end 210.610196 -276.791674)
		(width 0.1016)
		(layer "F.Cu")
		(net "M_H_CPU1_SA_CB<3>")
	)
	(segment
		(start 214.385652 -276.366732)
		(end 215.719914 -276.366732)
		(width 0.20066)
		(layer "F.Cu")
		(net "M_H_CPU1_SA_CB<3>")
	)
	(segment
		(start 210.598258 -276.798786)
		(end 210.603084 -276.798786)
		(width 0.101854)
		(layer "F.Cu")
		(net "M_H_CPU1_SA_CB<3>")
	)
	(segment
		(start 137.407396 -263.196832)
		(end 137.398506 -263.191752)
		(width 0.088646)
		(layer "In11.Cu")
		(net "M_H_CPU1_SA_CB<3>")
	)
	(segment
		(start 206.09052 -277.064978)
		(end 203.890118 -277.064978)
		(width 0.18288)
		(layer "In11.Cu")
		(net "M_H_CPU1_SA_CB<3>")
	)
	(segment
		(start 185.389266 -277.03018)
		(end 185.196226 -277.22322)
		(width 0.18288)
		(layer "In11.Cu")
		(net "M_H_CPU1_SA_CB<3>")
	)
	(segment
		(start 131.768596 -261.5692)
		(end 131.753864 -261.560564)
		(width 0.088646)
		(layer "In11.Cu")
		(net "M_H_CPU1_SA_CB<3>")
	)
	(segment
		(start 176.76495 -278.490934)
		(end 176.764188 -278.491696)
		(width 0.18288)
		(layer "In11.Cu")
		(net "M_H_CPU1_SA_CB<3>")
	)
	(segment
		(start 185.706766 -277.03018)
		(end 185.389266 -277.03018)
		(width 0.18288)
		(layer "In11.Cu")
		(net "M_H_CPU1_SA_CB<3>")
	)
	(segment
		(start 190.264034 -278.631396)
		(end 189.744858 -278.416258)
		(width 0.18288)
		(layer "In11.Cu")
		(net "M_H_CPU1_SA_CB<3>")
	)
	(segment
		(start 185.196226 -277.636986)
		(end 185.003186 -277.830026)
		(width 0.18288)
		(layer "In11.Cu")
		(net "M_H_CPU1_SA_CB<3>")
	)
	(segment
		(start 128.949196 -261.5692)
		(end 128.934464 -261.560564)
		(width 0.088646)
		(layer "In11.Cu")
		(net "M_H_CPU1_SA_CB<3>")
	)
	(segment
		(start 158.36138 -275.345398)
		(end 156.575506 -275.345398)
		(width 0.18288)
		(layer "In11.Cu")
		(net "M_H_CPU1_SA_CB<3>")
	)
	(segment
		(start 156.575506 -275.345398)
		(end 145.43278 -264.202672)
		(width 0.18288)
		(layer "In11.Cu")
		(net "M_H_CPU1_SA_CB<3>")
	)
	(segment
		(start 171.861226 -277.742142)
		(end 169.143426 -277.742142)
		(width 0.18288)
		(layer "In11.Cu")
		(net "M_H_CPU1_SA_CB<3>")
	)
	(segment
		(start 177.855118 -278.490934)
		(end 176.76495 -278.490934)
		(width 0.18288)
		(layer "In11.Cu")
		(net "M_H_CPU1_SA_CB<3>")
	)
	(segment
		(start 161.441892 -276.077426)
		(end 160.710118 -275.345652)
		(width 0.18288)
		(layer "In11.Cu")
		(net "M_H_CPU1_SA_CB<3>")
	)
	(segment
		(start 162.487356 -276.077426)
		(end 161.441892 -276.077426)
		(width 0.18288)
		(layer "In11.Cu")
		(net "M_H_CPU1_SA_CB<3>")
	)
	(segment
		(start 189.744858 -278.416258)
		(end 188.969396 -277.640796)
		(width 0.18288)
		(layer "In11.Cu")
		(net "M_H_CPU1_SA_CB<3>")
	)
	(segment
		(start 185.899806 -277.636986)
		(end 185.899806 -277.22322)
		(width 0.18288)
		(layer "In11.Cu")
		(net "M_H_CPU1_SA_CB<3>")
	)
	(segment
		(start 160.710118 -275.345652)
		(end 158.361634 -275.345652)
		(width 0.18288)
		(layer "In11.Cu")
		(net "M_H_CPU1_SA_CB<3>")
	)
	(segment
		(start 186.593226 -277.830026)
		(end 186.092846 -277.830026)
		(width 0.18288)
		(layer "In11.Cu")
		(net "M_H_CPU1_SA_CB<3>")
	)
	(segment
		(start 130.828796 -261.5692)
		(end 130.814064 -261.560564)
		(width 0.088646)
		(layer "In11.Cu")
		(net "M_H_CPU1_SA_CB<3>")
	)
	(segment
		(start 136.937496 -262.383016)
		(end 136.928606 -262.377936)
		(width 0.088646)
		(layer "In11.Cu")
		(net "M_H_CPU1_SA_CB<3>")
	)
	(segment
		(start 140.180822 -264.019792)
		(end 139.605004 -264.019792)
		(width 0.18288)
		(layer "In11.Cu")
		(net "M_H_CPU1_SA_CB<3>")
	)
	(segment
		(start 168.34231 -276.941026)
		(end 164.462714 -276.941026)
		(width 0.18288)
		(layer "In11.Cu")
		(net "M_H_CPU1_SA_CB<3>")
	)
	(segment
		(start 202.746102 -276.792182)
		(end 201.94397 -275.99005)
		(width 0.18288)
		(layer "In11.Cu")
		(net "M_H_CPU1_SA_CB<3>")
	)
	(segment
		(start 207.071214 -276.366732)
		(end 206.788766 -276.366732)
		(width 0.18288)
		(layer "In11.Cu")
		(net "M_H_CPU1_SA_CB<3>")
	)
	(segment
		(start 136.750044 -262.058658)
		(end 136.750044 -262.048752)
		(width 0.088646)
		(layer "In11.Cu")
		(net "M_H_CPU1_SA_CB<3>")
	)
	(segment
		(start 191.475614 -278.490426)
		(end 191.334644 -278.631396)
		(width 0.18288)
		(layer "In11.Cu")
		(net "M_H_CPU1_SA_CB<3>")
	)
	(segment
		(start 129.888996 -261.5692)
		(end 129.874264 -261.560564)
		(width 0.088646)
		(layer "In11.Cu")
		(net "M_H_CPU1_SA_CB<3>")
	)
	(segment
		(start 173.881796 -277.640796)
		(end 172.75302 -277.640796)
		(width 0.18288)
		(layer "In11.Cu")
		(net "M_H_CPU1_SA_CB<3>")
	)
	(segment
		(start 188.969396 -277.640796)
		(end 186.782456 -277.640796)
		(width 0.18288)
		(layer "In11.Cu")
		(net "M_H_CPU1_SA_CB<3>")
	)
	(segment
		(start 199.280018 -276.780498)
		(end 198.427594 -277.632922)
		(width 0.18288)
		(layer "In11.Cu")
		(net "M_H_CPU1_SA_CB<3>")
	)
	(segment
		(start 184.027826 -277.830026)
		(end 182.995824 -276.798024)
		(width 0.18288)
		(layer "In11.Cu")
		(net "M_H_CPU1_SA_CB<3>")
	)
	(segment
		(start 202.88377 -276.793706)
		(end 202.882246 -276.792182)
		(width 0.18288)
		(layer "In11.Cu")
		(net "M_H_CPU1_SA_CB<3>")
	)
	(segment
		(start 158.361634 -275.345652)
		(end 158.36138 -275.345398)
		(width 0.18288)
		(layer "In11.Cu")
		(net "M_H_CPU1_SA_CB<3>")
	)
	(segment
		(start 180.792628 -276.798024)
		(end 179.760626 -277.830026)
		(width 0.18288)
		(layer "In11.Cu")
		(net "M_H_CPU1_SA_CB<3>")
	)
	(segment
		(start 126.129796 -261.5692)
		(end 125.732794 -261.340092)
		(width 0.088646)
		(layer "In11.Cu")
		(net "M_H_CPU1_SA_CB<3>")
	)
	(segment
		(start 138.97737 -264.019792)
		(end 138.629898 -263.67232)
		(width 0.088646)
		(layer "In11.Cu")
		(net "M_H_CPU1_SA_CB<3>")
	)
	(segment
		(start 186.092846 -277.830026)
		(end 185.899806 -277.636986)
		(width 0.18288)
		(layer "In11.Cu")
		(net "M_H_CPU1_SA_CB<3>")
	)
	(segment
		(start 194.21348 -277.847552)
		(end 193.974212 -277.847552)
		(width 0.18288)
		(layer "In11.Cu")
		(net "M_H_CPU1_SA_CB<3>")
	)
	(segment
		(start 172.75302 -277.640796)
		(end 172.752258 -277.641558)
		(width 0.18288)
		(layer "In11.Cu")
		(net "M_H_CPU1_SA_CB<3>")
	)
	(segment
		(start 128.009396 -261.5692)
		(end 127.994664 -261.560564)
		(width 0.088646)
		(layer "In11.Cu")
		(net "M_H_CPU1_SA_CB<3>")
	)
	(segment
		(start 191.334644 -278.631396)
		(end 190.264034 -278.631396)
		(width 0.18288)
		(layer "In11.Cu")
		(net "M_H_CPU1_SA_CB<3>")
	)
	(segment
		(start 185.899806 -277.22322)
		(end 185.706766 -277.03018)
		(width 0.18288)
		(layer "In11.Cu")
		(net "M_H_CPU1_SA_CB<3>")
	)
	(segment
		(start 182.995824 -276.798024)
		(end 180.792628 -276.798024)
		(width 0.18288)
		(layer "In11.Cu")
		(net "M_H_CPU1_SA_CB<3>")
	)
	(segment
		(start 163.196778 -276.786848)
		(end 162.487356 -276.077426)
		(width 0.18288)
		(layer "In11.Cu")
		(net "M_H_CPU1_SA_CB<3>")
	)
	(segment
		(start 174.883826 -278.642826)
		(end 173.881796 -277.640796)
		(width 0.18288)
		(layer "In11.Cu")
		(net "M_H_CPU1_SA_CB<3>")
	)
	(segment
		(start 185.003186 -277.830026)
		(end 184.027826 -277.830026)
		(width 0.18288)
		(layer "In11.Cu")
		(net "M_H_CPU1_SA_CB<3>")
	)
	(segment
		(start 198.427594 -277.632922)
		(end 194.42811 -277.632922)
		(width 0.18288)
		(layer "In11.Cu")
		(net "M_H_CPU1_SA_CB<3>")
	)
	(segment
		(start 200.506838 -276.780498)
		(end 199.280018 -276.780498)
		(width 0.18288)
		(layer "In11.Cu")
		(net "M_H_CPU1_SA_CB<3>")
	)
	(segment
		(start 133.648196 -261.5692)
		(end 133.633464 -261.560564)
		(width 0.088646)
		(layer "In11.Cu")
		(net "M_H_CPU1_SA_CB<3>")
	)
	(segment
		(start 201.94397 -275.99005)
		(end 201.297286 -275.99005)
		(width 0.18288)
		(layer "In11.Cu")
		(net "M_H_CPU1_SA_CB<3>")
	)
	(segment
		(start 175.949356 -278.491696)
		(end 175.798226 -278.642826)
		(width 0.18288)
		(layer "In11.Cu")
		(net "M_H_CPU1_SA_CB<3>")
	)
	(segment
		(start 192.422018 -278.490426)
		(end 191.475614 -278.490426)
		(width 0.18288)
		(layer "In11.Cu")
		(net "M_H_CPU1_SA_CB<3>")
	)
	(segment
		(start 134.587996 -261.5692)
		(end 134.573264 -261.560564)
		(width 0.088646)
		(layer "In11.Cu")
		(net "M_H_CPU1_SA_CB<3>")
	)
	(segment
		(start 178.516026 -277.830026)
		(end 177.855118 -278.490934)
		(width 0.18288)
		(layer "In11.Cu")
		(net "M_H_CPU1_SA_CB<3>")
	)
	(segment
		(start 193.974212 -277.847552)
		(end 192.422018 -278.490426)
		(width 0.18288)
		(layer "In11.Cu")
		(net "M_H_CPU1_SA_CB<3>")
	)
	(segment
		(start 140.363702 -264.202672)
		(end 140.180822 -264.019792)
		(width 0.18288)
		(layer "In11.Cu")
		(net "M_H_CPU1_SA_CB<3>")
	)
	(segment
		(start 203.618846 -276.793706)
		(end 202.88377 -276.793706)
		(width 0.18288)
		(layer "In11.Cu")
		(net "M_H_CPU1_SA_CB<3>")
	)
	(segment
		(start 127.069596 -261.5692)
		(end 127.054864 -261.560564)
		(width 0.088646)
		(layer "In11.Cu")
		(net "M_H_CPU1_SA_CB<3>")
	)
	(segment
		(start 164.308536 -276.786848)
		(end 163.196778 -276.786848)
		(width 0.18288)
		(layer "In11.Cu")
		(net "M_H_CPU1_SA_CB<3>")
	)
	(segment
		(start 176.764188 -278.491696)
		(end 175.949356 -278.491696)
		(width 0.18288)
		(layer "In11.Cu")
		(net "M_H_CPU1_SA_CB<3>")
	)
	(segment
		(start 145.43278 -264.202672)
		(end 140.363702 -264.202672)
		(width 0.18288)
		(layer "In11.Cu")
		(net "M_H_CPU1_SA_CB<3>")
	)
	(segment
		(start 169.143426 -277.742142)
		(end 168.34231 -276.941026)
		(width 0.18288)
		(layer "In11.Cu")
		(net "M_H_CPU1_SA_CB<3>")
	)
	(segment
		(start 137.219944 -262.872474)
		(end 137.219944 -262.862568)
		(width 0.088646)
		(layer "In11.Cu")
		(net "M_H_CPU1_SA_CB<3>")
	)
	(segment
		(start 175.798226 -278.642826)
		(end 174.883826 -278.642826)
		(width 0.18288)
		(layer "In11.Cu")
		(net "M_H_CPU1_SA_CB<3>")
	)
	(segment
		(start 203.890118 -277.064978)
		(end 203.618846 -276.793706)
		(width 0.18288)
		(layer "In11.Cu")
		(net "M_H_CPU1_SA_CB<3>")
	)
	(segment
		(start 186.782456 -277.640796)
		(end 186.593226 -277.830026)
		(width 0.18288)
		(layer "In11.Cu")
		(net "M_H_CPU1_SA_CB<3>")
	)
	(segment
		(start 185.196226 -277.22322)
		(end 185.196226 -277.636986)
		(width 0.18288)
		(layer "In11.Cu")
		(net "M_H_CPU1_SA_CB<3>")
	)
	(segment
		(start 206.788766 -276.366732)
		(end 206.09052 -277.064978)
		(width 0.18288)
		(layer "In11.Cu")
		(net "M_H_CPU1_SA_CB<3>")
	)
	(segment
		(start 171.96181 -277.641558)
		(end 171.861226 -277.742142)
		(width 0.18288)
		(layer "In11.Cu")
		(net "M_H_CPU1_SA_CB<3>")
	)
	(segment
		(start 201.297286 -275.99005)
		(end 200.506838 -276.780498)
		(width 0.18288)
		(layer "In11.Cu")
		(net "M_H_CPU1_SA_CB<3>")
	)
	(segment
		(start 172.752258 -277.641558)
		(end 171.96181 -277.641558)
		(width 0.18288)
		(layer "In11.Cu")
		(net "M_H_CPU1_SA_CB<3>")
	)
	(segment
		(start 202.882246 -276.792182)
		(end 202.746102 -276.792182)
		(width 0.18288)
		(layer "In11.Cu")
		(net "M_H_CPU1_SA_CB<3>")
	)
	(segment
		(start 179.760626 -277.830026)
		(end 178.516026 -277.830026)
		(width 0.18288)
		(layer "In11.Cu")
		(net "M_H_CPU1_SA_CB<3>")
	)
	(segment
		(start 164.462714 -276.941026)
		(end 164.308536 -276.786848)
		(width 0.18288)
		(layer "In11.Cu")
		(net "M_H_CPU1_SA_CB<3>")
	)
	(segment
		(start 139.605004 -264.019792)
		(end 138.97737 -264.019792)
		(width 0.088646)
		(layer "In11.Cu")
		(net "M_H_CPU1_SA_CB<3>")
	)
	(segment
		(start 194.42811 -277.632922)
		(end 194.21348 -277.847552)
		(width 0.18288)
		(layer "In11.Cu")
		(net "M_H_CPU1_SA_CB<3>")
	)
	(segment
		(start 137.792206 -263.190736)
		(end 137.781792 -263.196832)
		(width 0.088646)
		(layer "In11.Cu")
		(net "M_H_CPU1_SA_CB<3>")
	)
	(arc
		(start 131.203192 -261.5692)
		(mid 131.015994 -261.619343)
		(end 130.828796 -261.5692)
		(width 0.088646)
		(layer "In11.Cu")
		(net "M_H_CPU1_SA_CB<3>")
	)
	(arc
		(start 137.781792 -263.196832)
		(mid 137.594594 -263.246975)
		(end 137.407396 -263.196832)
		(width 0.088646)
		(layer "In11.Cu")
		(net "M_H_CPU1_SA_CB<3>")
	)
	(arc
		(start 127.443992 -261.5692)
		(mid 127.256794 -261.619343)
		(end 127.069596 -261.5692)
		(width 0.088646)
		(layer "In11.Cu")
		(net "M_H_CPU1_SA_CB<3>")
	)
	(arc
		(start 131.753864 -261.560564)
		(mid 131.477389 -261.493244)
		(end 131.203192 -261.5692)
		(width 0.088646)
		(layer "In11.Cu")
		(net "M_H_CPU1_SA_CB<3>")
	)
	(arc
		(start 137.398506 -263.191752)
		(mid 137.267592 -263.055392)
		(end 137.219944 -262.872474)
		(width 0.088646)
		(layer "In11.Cu")
		(net "M_H_CPU1_SA_CB<3>")
	)
	(arc
		(start 130.814064 -261.560564)
		(mid 130.537589 -261.493244)
		(end 130.263392 -261.5692)
		(width 0.088646)
		(layer "In11.Cu")
		(net "M_H_CPU1_SA_CB<3>")
	)
	(arc
		(start 137.219944 -262.862568)
		(mid 137.141833 -262.585619)
		(end 136.937496 -262.383016)
		(width 0.088646)
		(layer "In11.Cu")
		(net "M_H_CPU1_SA_CB<3>")
	)
	(arc
		(start 128.934464 -261.560564)
		(mid 128.657989 -261.493244)
		(end 128.383792 -261.5692)
		(width 0.088646)
		(layer "In11.Cu")
		(net "M_H_CPU1_SA_CB<3>")
	)
	(arc
		(start 136.467596 -261.5692)
		(mid 136.184894 -261.493424)
		(end 135.902192 -261.5692)
		(width 0.088646)
		(layer "In11.Cu")
		(net "M_H_CPU1_SA_CB<3>")
	)
	(arc
		(start 136.750044 -262.048752)
		(mid 136.671933 -261.771803)
		(end 136.467596 -261.5692)
		(width 0.088646)
		(layer "In11.Cu")
		(net "M_H_CPU1_SA_CB<3>")
	)
	(arc
		(start 129.323592 -261.5692)
		(mid 129.136394 -261.619343)
		(end 128.949196 -261.5692)
		(width 0.088646)
		(layer "In11.Cu")
		(net "M_H_CPU1_SA_CB<3>")
	)
	(arc
		(start 134.962392 -261.5692)
		(mid 134.775194 -261.619343)
		(end 134.587996 -261.5692)
		(width 0.088646)
		(layer "In11.Cu")
		(net "M_H_CPU1_SA_CB<3>")
	)
	(arc
		(start 133.082792 -261.5692)
		(mid 132.895594 -261.619343)
		(end 132.708396 -261.5692)
		(width 0.088646)
		(layer "In11.Cu")
		(net "M_H_CPU1_SA_CB<3>")
	)
	(arc
		(start 135.527796 -261.5692)
		(mid 135.245094 -261.493424)
		(end 134.962392 -261.5692)
		(width 0.088646)
		(layer "In11.Cu")
		(net "M_H_CPU1_SA_CB<3>")
	)
	(arc
		(start 125.732794 -261.340092)
		(mid 125.561261 -261.269071)
		(end 125.377194 -261.244842)
		(width 0.088646)
		(layer "In11.Cu")
		(net "M_H_CPU1_SA_CB<3>")
	)
	(arc
		(start 136.928606 -262.377936)
		(mid 136.797692 -262.241576)
		(end 136.750044 -262.058658)
		(width 0.088646)
		(layer "In11.Cu")
		(net "M_H_CPU1_SA_CB<3>")
	)
	(arc
		(start 138.629898 -263.67232)
		(mid 138.346362 -263.196203)
		(end 137.792206 -263.190736)
		(width 0.088646)
		(layer "In11.Cu")
		(net "M_H_CPU1_SA_CB<3>")
	)
	(arc
		(start 127.994664 -261.560564)
		(mid 127.718189 -261.493244)
		(end 127.443992 -261.5692)
		(width 0.088646)
		(layer "In11.Cu")
		(net "M_H_CPU1_SA_CB<3>")
	)
	(arc
		(start 134.573264 -261.560564)
		(mid 134.296789 -261.493244)
		(end 134.022592 -261.5692)
		(width 0.088646)
		(layer "In11.Cu")
		(net "M_H_CPU1_SA_CB<3>")
	)
	(arc
		(start 129.874264 -261.560564)
		(mid 129.597789 -261.493244)
		(end 129.323592 -261.5692)
		(width 0.088646)
		(layer "In11.Cu")
		(net "M_H_CPU1_SA_CB<3>")
	)
	(arc
		(start 127.054864 -261.560564)
		(mid 126.778389 -261.493244)
		(end 126.504192 -261.5692)
		(width 0.088646)
		(layer "In11.Cu")
		(net "M_H_CPU1_SA_CB<3>")
	)
	(arc
		(start 126.504192 -261.5692)
		(mid 126.316994 -261.619343)
		(end 126.129796 -261.5692)
		(width 0.088646)
		(layer "In11.Cu")
		(net "M_H_CPU1_SA_CB<3>")
	)
	(arc
		(start 132.142992 -261.5692)
		(mid 131.955794 -261.619343)
		(end 131.768596 -261.5692)
		(width 0.088646)
		(layer "In11.Cu")
		(net "M_H_CPU1_SA_CB<3>")
	)
	(arc
		(start 133.633464 -261.560564)
		(mid 133.356989 -261.493244)
		(end 133.082792 -261.5692)
		(width 0.088646)
		(layer "In11.Cu")
		(net "M_H_CPU1_SA_CB<3>")
	)
	(arc
		(start 134.022592 -261.5692)
		(mid 133.835394 -261.619343)
		(end 133.648196 -261.5692)
		(width 0.088646)
		(layer "In11.Cu")
		(net "M_H_CPU1_SA_CB<3>")
	)
	(arc
		(start 130.263392 -261.5692)
		(mid 130.076194 -261.619343)
		(end 129.888996 -261.5692)
		(width 0.088646)
		(layer "In11.Cu")
		(net "M_H_CPU1_SA_CB<3>")
	)
	(arc
		(start 135.902192 -261.5692)
		(mid 135.714994 -261.619343)
		(end 135.527796 -261.5692)
		(width 0.088646)
		(layer "In11.Cu")
		(net "M_H_CPU1_SA_CB<3>")
	)
	(arc
		(start 128.383792 -261.5692)
		(mid 128.196594 -261.619343)
		(end 128.009396 -261.5692)
		(width 0.088646)
		(layer "In11.Cu")
		(net "M_H_CPU1_SA_CB<3>")
	)
	(arc
		(start 132.708396 -261.5692)
		(mid 132.425694 -261.493424)
		(end 132.142992 -261.5692)
		(width 0.088646)
		(layer "In11.Cu")
		(net "M_H_CPU1_SA_CB<3>")
	)
	(segment
		(start 213.311486 -278.503888)
		(end 213.515448 -278.299926)
		(width 0.20066)
		(layer "F.Cu")
		(net "M_H_CPU1_SA_CB<2>")
	)
	(segment
		(start 212.630258 -278.503888)
		(end 213.311486 -278.503888)
		(width 0.20066)
		(layer "F.Cu")
		(net "M_H_CPU1_SA_CB<2>")
	)
	(segment
		(start 210.603084 -278.498808)
		(end 210.610196 -278.491696)
		(width 0.1016)
		(layer "F.Cu")
		(net "M_H_CPU1_SA_CB<2>")
	)
	(segment
		(start 212.618066 -278.491696)
		(end 212.630258 -278.503888)
		(width 0.1016)
		(layer "F.Cu")
		(net "M_H_CPU1_SA_CB<2>")
	)
	(segment
		(start 124.907548 -261.522972)
		(end 124.907548 -262.058658)
		(width 0.20066)
		(layer "F.Cu")
		(net "M_H_CPU1_SA_CB<2>")
	)
	(segment
		(start 208.176114 -278.066754)
		(end 209.874358 -278.066754)
		(width 0.20066)
		(layer "F.Cu")
		(net "M_H_CPU1_SA_CB<2>")
	)
	(segment
		(start 124.907294 -261.522718)
		(end 124.907548 -261.522972)
		(width 0.20066)
		(layer "F.Cu")
		(net "M_H_CPU1_SA_CB<2>")
	)
	(segment
		(start 214.133684 -277.814786)
		(end 214.385652 -278.066754)
		(width 0.20066)
		(layer "F.Cu")
		(net "M_H_CPU1_SA_CB<2>")
	)
	(segment
		(start 207.071214 -278.066754)
		(end 208.176114 -278.066754)
		(width 0.20066)
		(layer "F.Cu")
		(net "M_H_CPU1_SA_CB<2>")
	)
	(segment
		(start 213.515448 -278.299926)
		(end 213.515448 -278.048974)
		(width 0.20066)
		(layer "F.Cu")
		(net "M_H_CPU1_SA_CB<2>")
	)
	(segment
		(start 210.610196 -278.491696)
		(end 212.618066 -278.491696)
		(width 0.1016)
		(layer "F.Cu")
		(net "M_H_CPU1_SA_CB<2>")
	)
	(segment
		(start 213.749636 -277.814786)
		(end 214.133684 -277.814786)
		(width 0.20066)
		(layer "F.Cu")
		(net "M_H_CPU1_SA_CB<2>")
	)
	(segment
		(start 209.874358 -278.066754)
		(end 210.306412 -278.498808)
		(width 0.20066)
		(layer "F.Cu")
		(net "M_H_CPU1_SA_CB<2>")
	)
	(segment
		(start 210.306412 -278.498808)
		(end 210.598258 -278.498808)
		(width 0.20066)
		(layer "F.Cu")
		(net "M_H_CPU1_SA_CB<2>")
	)
	(segment
		(start 214.385652 -278.066754)
		(end 215.719914 -278.066754)
		(width 0.20066)
		(layer "F.Cu")
		(net "M_H_CPU1_SA_CB<2>")
	)
	(segment
		(start 213.515448 -278.048974)
		(end 213.749636 -277.814786)
		(width 0.20066)
		(layer "F.Cu")
		(net "M_H_CPU1_SA_CB<2>")
	)
	(segment
		(start 210.598258 -278.498808)
		(end 210.603084 -278.498808)
		(width 0.101854)
		(layer "F.Cu")
		(net "M_H_CPU1_SA_CB<2>")
	)
	(segment
		(start 202.680062 -278.491442)
		(end 202.099926 -277.911306)
		(width 0.18288)
		(layer "In11.Cu")
		(net "M_H_CPU1_SA_CB<2>")
	)
	(segment
		(start 198.487538 -279.090374)
		(end 194.697858 -279.090374)
		(width 0.18288)
		(layer "In11.Cu")
		(net "M_H_CPU1_SA_CB<2>")
	)
	(segment
		(start 129.808478 -262.37438)
		(end 129.793746 -262.383016)
		(width 0.088646)
		(layer "In11.Cu")
		(net "M_H_CPU1_SA_CB<2>")
	)
	(segment
		(start 139.605004 -265.218672)
		(end 139.206478 -265.218672)
		(width 0.088646)
		(layer "In11.Cu")
		(net "M_H_CPU1_SA_CB<2>")
	)
	(segment
		(start 179.938426 -279.227026)
		(end 179.532026 -279.633426)
		(width 0.18288)
		(layer "In11.Cu")
		(net "M_H_CPU1_SA_CB<2>")
	)
	(segment
		(start 130.748278 -262.37438)
		(end 130.733546 -262.383016)
		(width 0.088646)
		(layer "In11.Cu")
		(net "M_H_CPU1_SA_CB<2>")
	)
	(segment
		(start 191.10706 -280.190956)
		(end 190.967106 -280.33091)
		(width 0.18288)
		(layer "In11.Cu")
		(net "M_H_CPU1_SA_CB<2>")
	)
	(segment
		(start 176.220882 -280.191718)
		(end 176.086262 -280.326338)
		(width 0.18288)
		(layer "In11.Cu")
		(net "M_H_CPU1_SA_CB<2>")
	)
	(segment
		(start 134.50316 -262.37692)
		(end 134.492746 -262.383016)
		(width 0.088646)
		(layer "In11.Cu")
		(net "M_H_CPU1_SA_CB<2>")
	)
	(segment
		(start 169.099484 -279.411684)
		(end 168.330626 -278.642826)
		(width 0.18288)
		(layer "In11.Cu")
		(net "M_H_CPU1_SA_CB<2>")
	)
	(segment
		(start 192.90792 -279.879552)
		(end 192.596516 -280.190956)
		(width 0.18288)
		(layer "In11.Cu")
		(net "M_H_CPU1_SA_CB<2>")
	)
	(segment
		(start 207.045814 -278.066754)
		(end 205.82001 -279.292558)
		(width 0.18288)
		(layer "In11.Cu")
		(net "M_H_CPU1_SA_CB<2>")
	)
	(segment
		(start 173.882558 -279.340818)
		(end 172.128434 -279.340818)
		(width 0.18288)
		(layer "In11.Cu")
		(net "M_H_CPU1_SA_CB<2>")
	)
	(segment
		(start 156.903166 -277.110698)
		(end 145.01114 -265.218672)
		(width 0.18288)
		(layer "In11.Cu")
		(net "M_H_CPU1_SA_CB<2>")
	)
	(segment
		(start 188.976254 -279.340818)
		(end 186.865768 -279.340818)
		(width 0.18288)
		(layer "In11.Cu")
		(net "M_H_CPU1_SA_CB<2>")
	)
	(segment
		(start 193.808858 -279.506426)
		(end 192.90792 -279.879552)
		(width 0.18288)
		(layer "In11.Cu")
		(net "M_H_CPU1_SA_CB<2>")
	)
	(segment
		(start 194.697858 -279.090374)
		(end 194.281806 -279.506426)
		(width 0.18288)
		(layer "In11.Cu")
		(net "M_H_CPU1_SA_CB<2>")
	)
	(segment
		(start 162.780726 -277.906226)
		(end 162.180016 -277.906226)
		(width 0.18288)
		(layer "In11.Cu")
		(net "M_H_CPU1_SA_CB<2>")
	)
	(segment
		(start 127.928878 -262.37438)
		(end 127.914146 -262.383016)
		(width 0.088646)
		(layer "In11.Cu")
		(net "M_H_CPU1_SA_CB<2>")
	)
	(segment
		(start 183.61152 -279.44572)
		(end 183.392826 -279.227026)
		(width 0.18288)
		(layer "In11.Cu")
		(net "M_H_CPU1_SA_CB<2>")
	)
	(segment
		(start 202.099926 -277.911306)
		(end 201.086212 -277.911306)
		(width 0.18288)
		(layer "In11.Cu")
		(net "M_H_CPU1_SA_CB<2>")
	)
	(segment
		(start 136.750044 -263.686544)
		(end 136.750044 -263.668002)
		(width 0.088646)
		(layer "In11.Cu")
		(net "M_H_CPU1_SA_CB<2>")
	)
	(segment
		(start 136.937496 -264.010902)
		(end 136.928606 -264.005822)
		(width 0.088646)
		(layer "In11.Cu")
		(net "M_H_CPU1_SA_CB<2>")
	)
	(segment
		(start 178.081686 -279.633426)
		(end 177.524156 -280.190956)
		(width 0.18288)
		(layer "In11.Cu")
		(net "M_H_CPU1_SA_CB<2>")
	)
	(segment
		(start 176.854358 -280.191718)
		(end 176.220882 -280.191718)
		(width 0.18288)
		(layer "In11.Cu")
		(net "M_H_CPU1_SA_CB<2>")
	)
	(segment
		(start 124.594874 -262.058658)
		(end 124.907548 -262.058658)
		(width 0.088646)
		(layer "In11.Cu")
		(net "M_H_CPU1_SA_CB<2>")
	)
	(segment
		(start 126.044706 -262.37692)
		(end 126.034292 -262.383016)
		(width 0.088646)
		(layer "In11.Cu")
		(net "M_H_CPU1_SA_CB<2>")
	)
	(segment
		(start 126.989078 -262.37438)
		(end 126.9746 -262.383016)
		(width 0.088646)
		(layer "In11.Cu")
		(net "M_H_CPU1_SA_CB<2>")
	)
	(segment
		(start 124.53747 -262.116062)
		(end 124.594874 -262.058658)
		(width 0.088646)
		(layer "In11.Cu")
		(net "M_H_CPU1_SA_CB<2>")
	)
	(segment
		(start 177.524156 -280.190956)
		(end 176.85512 -280.190956)
		(width 0.18288)
		(layer "In11.Cu")
		(net "M_H_CPU1_SA_CB<2>")
	)
	(segment
		(start 190.967106 -280.33091)
		(end 189.966346 -280.33091)
		(width 0.18288)
		(layer "In11.Cu")
		(net "M_H_CPU1_SA_CB<2>")
	)
	(segment
		(start 162.180016 -277.906226)
		(end 161.423858 -277.552658)
		(width 0.18288)
		(layer "In11.Cu")
		(net "M_H_CPU1_SA_CB<2>")
	)
	(segment
		(start 164.876226 -278.642826)
		(end 164.539676 -278.306276)
		(width 0.18288)
		(layer "In11.Cu")
		(net "M_H_CPU1_SA_CB<2>")
	)
	(segment
		(start 139.206478 -265.218672)
		(end 138.957558 -264.969752)
		(width 0.088646)
		(layer "In11.Cu")
		(net "M_H_CPU1_SA_CB<2>")
	)
	(segment
		(start 136.280144 -262.872474)
		(end 136.280144 -262.862568)
		(width 0.088646)
		(layer "In11.Cu")
		(net "M_H_CPU1_SA_CB<2>")
	)
	(segment
		(start 186.865768 -279.340818)
		(end 186.760866 -279.44572)
		(width 0.18288)
		(layer "In11.Cu")
		(net "M_H_CPU1_SA_CB<2>")
	)
	(segment
		(start 199.122538 -278.455374)
		(end 198.487538 -279.090374)
		(width 0.18288)
		(layer "In11.Cu")
		(net "M_H_CPU1_SA_CB<2>")
	)
	(segment
		(start 204.414882 -278.491442)
		(end 202.680062 -278.491442)
		(width 0.18288)
		(layer "In11.Cu")
		(net "M_H_CPU1_SA_CB<2>")
	)
	(segment
		(start 183.392826 -279.227026)
		(end 179.938426 -279.227026)
		(width 0.18288)
		(layer "In11.Cu")
		(net "M_H_CPU1_SA_CB<2>")
	)
	(segment
		(start 132.623306 -262.37692)
		(end 132.612892 -262.383016)
		(width 0.088646)
		(layer "In11.Cu")
		(net "M_H_CPU1_SA_CB<2>")
	)
	(segment
		(start 174.868078 -280.326338)
		(end 173.882558 -279.340818)
		(width 0.18288)
		(layer "In11.Cu")
		(net "M_H_CPU1_SA_CB<2>")
	)
	(segment
		(start 189.966346 -280.33091)
		(end 188.976254 -279.340818)
		(width 0.18288)
		(layer "In11.Cu")
		(net "M_H_CPU1_SA_CB<2>")
	)
	(segment
		(start 124.72035 -262.383016)
		(end 124.71146 -262.377936)
		(width 0.088646)
		(layer "In11.Cu")
		(net "M_H_CPU1_SA_CB<2>")
	)
	(segment
		(start 145.01114 -265.218672)
		(end 139.605004 -265.218672)
		(width 0.18288)
		(layer "In11.Cu")
		(net "M_H_CPU1_SA_CB<2>")
	)
	(segment
		(start 200.542144 -278.455374)
		(end 199.122538 -278.455374)
		(width 0.18288)
		(layer "In11.Cu")
		(net "M_H_CPU1_SA_CB<2>")
	)
	(segment
		(start 176.85512 -280.190956)
		(end 176.854358 -280.191718)
		(width 0.18288)
		(layer "In11.Cu")
		(net "M_H_CPU1_SA_CB<2>")
	)
	(segment
		(start 136.467596 -263.196832)
		(end 136.458706 -263.191752)
		(width 0.088646)
		(layer "In11.Cu")
		(net "M_H_CPU1_SA_CB<2>")
	)
	(segment
		(start 163.180776 -278.306276)
		(end 162.780726 -277.906226)
		(width 0.18288)
		(layer "In11.Cu")
		(net "M_H_CPU1_SA_CB<2>")
	)
	(segment
		(start 205.82001 -279.292558)
		(end 205.215998 -279.292558)
		(width 0.18288)
		(layer "In11.Cu")
		(net "M_H_CPU1_SA_CB<2>")
	)
	(segment
		(start 172.057568 -279.411684)
		(end 169.099484 -279.411684)
		(width 0.18288)
		(layer "In11.Cu")
		(net "M_H_CPU1_SA_CB<2>")
	)
	(segment
		(start 172.128434 -279.340818)
		(end 172.057568 -279.411684)
		(width 0.18288)
		(layer "In11.Cu")
		(net "M_H_CPU1_SA_CB<2>")
	)
	(segment
		(start 128.868678 -262.37438)
		(end 128.853946 -262.383016)
		(width 0.088646)
		(layer "In11.Cu")
		(net "M_H_CPU1_SA_CB<2>")
	)
	(segment
		(start 138.877802 -264.936732)
		(end 138.049 -264.10793)
		(width 0.088646)
		(layer "In11.Cu")
		(net "M_H_CPU1_SA_CB<2>")
	)
	(segment
		(start 161.423858 -277.552658)
		(end 160.981898 -277.110698)
		(width 0.18288)
		(layer "In11.Cu")
		(net "M_H_CPU1_SA_CB<2>")
	)
	(segment
		(start 168.330626 -278.642826)
		(end 164.876226 -278.642826)
		(width 0.18288)
		(layer "In11.Cu")
		(net "M_H_CPU1_SA_CB<2>")
	)
	(segment
		(start 164.539676 -278.306276)
		(end 163.180776 -278.306276)
		(width 0.18288)
		(layer "In11.Cu")
		(net "M_H_CPU1_SA_CB<2>")
	)
	(segment
		(start 132.238496 -262.383016)
		(end 132.228082 -262.37692)
		(width 0.088646)
		(layer "In11.Cu")
		(net "M_H_CPU1_SA_CB<2>")
	)
	(segment
		(start 201.086212 -277.911306)
		(end 200.542144 -278.455374)
		(width 0.18288)
		(layer "In11.Cu")
		(net "M_H_CPU1_SA_CB<2>")
	)
	(segment
		(start 205.215998 -279.292558)
		(end 204.414882 -278.491442)
		(width 0.18288)
		(layer "In11.Cu")
		(net "M_H_CPU1_SA_CB<2>")
	)
	(segment
		(start 125.659896 -262.383016)
		(end 125.649482 -262.37692)
		(width 0.088646)
		(layer "In11.Cu")
		(net "M_H_CPU1_SA_CB<2>")
	)
	(segment
		(start 186.760866 -279.44572)
		(end 183.61152 -279.44572)
		(width 0.18288)
		(layer "In11.Cu")
		(net "M_H_CPU1_SA_CB<2>")
	)
	(segment
		(start 194.281806 -279.506426)
		(end 193.808858 -279.506426)
		(width 0.18288)
		(layer "In11.Cu")
		(net "M_H_CPU1_SA_CB<2>")
	)
	(segment
		(start 179.532026 -279.633426)
		(end 178.081686 -279.633426)
		(width 0.18288)
		(layer "In11.Cu")
		(net "M_H_CPU1_SA_CB<2>")
	)
	(segment
		(start 160.981898 -277.110698)
		(end 156.903166 -277.110698)
		(width 0.18288)
		(layer "In11.Cu")
		(net "M_H_CPU1_SA_CB<2>")
	)
	(segment
		(start 176.086262 -280.326338)
		(end 174.868078 -280.326338)
		(width 0.18288)
		(layer "In11.Cu")
		(net "M_H_CPU1_SA_CB<2>")
	)
	(segment
		(start 192.596516 -280.190956)
		(end 191.10706 -280.190956)
		(width 0.18288)
		(layer "In11.Cu")
		(net "M_H_CPU1_SA_CB<2>")
	)
	(segment
		(start 207.071214 -278.066754)
		(end 207.045814 -278.066754)
		(width 0.18288)
		(layer "In11.Cu")
		(net "M_H_CPU1_SA_CB<2>")
	)
	(segment
		(start 133.567678 -262.37438)
		(end 133.552946 -262.383016)
		(width 0.088646)
		(layer "In11.Cu")
		(net "M_H_CPU1_SA_CB<2>")
	)
	(arc
		(start 126.034292 -262.383016)
		(mid 125.847094 -262.433159)
		(end 125.659896 -262.383016)
		(width 0.088646)
		(layer "In11.Cu")
		(net "M_H_CPU1_SA_CB<2>")
	)
	(arc
		(start 132.228082 -262.37692)
		(mid 131.949904 -262.307197)
		(end 131.673346 -262.383016)
		(width 0.088646)
		(layer "In11.Cu")
		(net "M_H_CPU1_SA_CB<2>")
	)
	(arc
		(start 130.733546 -262.383016)
		(mid 130.546348 -262.433159)
		(end 130.35915 -262.383016)
		(width 0.088646)
		(layer "In11.Cu")
		(net "M_H_CPU1_SA_CB<2>")
	)
	(arc
		(start 131.29895 -262.383016)
		(mid 131.024751 -262.307181)
		(end 130.748278 -262.37438)
		(width 0.088646)
		(layer "In11.Cu")
		(net "M_H_CPU1_SA_CB<2>")
	)
	(arc
		(start 128.47955 -262.383016)
		(mid 128.205351 -262.307181)
		(end 127.928878 -262.37438)
		(width 0.088646)
		(layer "In11.Cu")
		(net "M_H_CPU1_SA_CB<2>")
	)
	(arc
		(start 125.094746 -262.383016)
		(mid 124.907548 -262.433159)
		(end 124.72035 -262.383016)
		(width 0.088646)
		(layer "In11.Cu")
		(net "M_H_CPU1_SA_CB<2>")
	)
	(arc
		(start 137.311892 -264.010902)
		(mid 137.124694 -264.061045)
		(end 136.937496 -264.010902)
		(width 0.088646)
		(layer "In11.Cu")
		(net "M_H_CPU1_SA_CB<2>")
	)
	(arc
		(start 136.750044 -263.668002)
		(mid 136.669882 -263.395813)
		(end 136.467596 -263.196832)
		(width 0.088646)
		(layer "In11.Cu")
		(net "M_H_CPU1_SA_CB<2>")
	)
	(arc
		(start 138.957558 -264.969752)
		(mid 138.9144 -264.961167)
		(end 138.877802 -264.936732)
		(width 0.088646)
		(layer "In11.Cu")
		(net "M_H_CPU1_SA_CB<2>")
	)
	(arc
		(start 125.649482 -262.37692)
		(mid 125.371304 -262.307197)
		(end 125.094746 -262.383016)
		(width 0.088646)
		(layer "In11.Cu")
		(net "M_H_CPU1_SA_CB<2>")
	)
	(arc
		(start 136.458706 -263.191752)
		(mid 136.327792 -263.055392)
		(end 136.280144 -262.872474)
		(width 0.088646)
		(layer "In11.Cu")
		(net "M_H_CPU1_SA_CB<2>")
	)
	(arc
		(start 124.71146 -262.377936)
		(mid 124.595721 -262.266112)
		(end 124.53747 -262.116062)
		(width 0.088646)
		(layer "In11.Cu")
		(net "M_H_CPU1_SA_CB<2>")
	)
	(arc
		(start 129.41935 -262.383016)
		(mid 129.145151 -262.307181)
		(end 128.868678 -262.37438)
		(width 0.088646)
		(layer "In11.Cu")
		(net "M_H_CPU1_SA_CB<2>")
	)
	(arc
		(start 135.432292 -262.383016)
		(mid 135.245094 -262.433159)
		(end 135.057896 -262.383016)
		(width 0.088646)
		(layer "In11.Cu")
		(net "M_H_CPU1_SA_CB<2>")
	)
	(arc
		(start 133.17855 -262.383016)
		(mid 132.901737 -262.307146)
		(end 132.623306 -262.37692)
		(width 0.088646)
		(layer "In11.Cu")
		(net "M_H_CPU1_SA_CB<2>")
	)
	(arc
		(start 135.997696 -262.383016)
		(mid 135.714994 -262.30724)
		(end 135.432292 -262.383016)
		(width 0.088646)
		(layer "In11.Cu")
		(net "M_H_CPU1_SA_CB<2>")
	)
	(arc
		(start 130.35915 -262.383016)
		(mid 130.084951 -262.307181)
		(end 129.808478 -262.37438)
		(width 0.088646)
		(layer "In11.Cu")
		(net "M_H_CPU1_SA_CB<2>")
	)
	(arc
		(start 127.914146 -262.383016)
		(mid 127.726948 -262.433159)
		(end 127.53975 -262.383016)
		(width 0.088646)
		(layer "In11.Cu")
		(net "M_H_CPU1_SA_CB<2>")
	)
	(arc
		(start 136.928606 -264.005822)
		(mid 136.797692 -263.869462)
		(end 136.750044 -263.686544)
		(width 0.088646)
		(layer "In11.Cu")
		(net "M_H_CPU1_SA_CB<2>")
	)
	(arc
		(start 129.793746 -262.383016)
		(mid 129.606548 -262.433159)
		(end 129.41935 -262.383016)
		(width 0.088646)
		(layer "In11.Cu")
		(net "M_H_CPU1_SA_CB<2>")
	)
	(arc
		(start 134.11835 -262.383016)
		(mid 133.844151 -262.307181)
		(end 133.567678 -262.37438)
		(width 0.088646)
		(layer "In11.Cu")
		(net "M_H_CPU1_SA_CB<2>")
	)
	(arc
		(start 136.280144 -262.862568)
		(mid 136.202033 -262.585619)
		(end 135.997696 -262.383016)
		(width 0.088646)
		(layer "In11.Cu")
		(net "M_H_CPU1_SA_CB<2>")
	)
	(arc
		(start 127.53975 -262.383016)
		(mid 127.265551 -262.307181)
		(end 126.989078 -262.37438)
		(width 0.088646)
		(layer "In11.Cu")
		(net "M_H_CPU1_SA_CB<2>")
	)
	(arc
		(start 126.59995 -262.383016)
		(mid 126.323137 -262.307146)
		(end 126.044706 -262.37692)
		(width 0.088646)
		(layer "In11.Cu")
		(net "M_H_CPU1_SA_CB<2>")
	)
	(arc
		(start 128.853946 -262.383016)
		(mid 128.666748 -262.433159)
		(end 128.47955 -262.383016)
		(width 0.088646)
		(layer "In11.Cu")
		(net "M_H_CPU1_SA_CB<2>")
	)
	(arc
		(start 133.552946 -262.383016)
		(mid 133.365748 -262.433159)
		(end 133.17855 -262.383016)
		(width 0.088646)
		(layer "In11.Cu")
		(net "M_H_CPU1_SA_CB<2>")
	)
	(arc
		(start 126.9746 -262.383016)
		(mid 126.787292 -262.433159)
		(end 126.59995 -262.383016)
		(width 0.088646)
		(layer "In11.Cu")
		(net "M_H_CPU1_SA_CB<2>")
	)
	(arc
		(start 132.612892 -262.383016)
		(mid 132.425694 -262.433159)
		(end 132.238496 -262.383016)
		(width 0.088646)
		(layer "In11.Cu")
		(net "M_H_CPU1_SA_CB<2>")
	)
	(arc
		(start 138.049 -264.10793)
		(mid 137.696912 -263.934297)
		(end 137.311892 -264.010902)
		(width 0.088646)
		(layer "In11.Cu")
		(net "M_H_CPU1_SA_CB<2>")
	)
	(arc
		(start 134.492746 -262.383016)
		(mid 134.305548 -262.433159)
		(end 134.11835 -262.383016)
		(width 0.088646)
		(layer "In11.Cu")
		(net "M_H_CPU1_SA_CB<2>")
	)
	(arc
		(start 131.673346 -262.383016)
		(mid 131.486148 -262.433159)
		(end 131.29895 -262.383016)
		(width 0.088646)
		(layer "In11.Cu")
		(net "M_H_CPU1_SA_CB<2>")
	)
	(arc
		(start 135.057896 -262.383016)
		(mid 134.781337 -262.307273)
		(end 134.50316 -262.37692)
		(width 0.088646)
		(layer "In11.Cu")
		(net "M_H_CPU1_SA_CB<2>")
	)
	(segment
		(start 123.497594 -261.244588)
		(end 123.497594 -261.244842)
		(width 0.20066)
		(layer "F.Cu")
		(net "M_H_CPU1_SA_CB<1>")
	)
	(segment
		(start 123.497848 -261.244334)
		(end 123.497594 -261.244588)
		(width 0.20066)
		(layer "F.Cu")
		(net "M_H_CPU1_SA_CB<1>")
	)
	(segment
		(start 204.076046 -277.216616)
		(end 202.971146 -277.216616)
		(width 0.20066)
		(layer "F.Cu")
		(net "M_H_CPU1_SA_CB<1>")
	)
	(segment
		(start 206.991458 -276.791674)
		(end 206.971392 -276.791674)
		(width 0.101854)
		(layer "F.Cu")
		(net "M_H_CPU1_SA_CB<1>")
	)
	(segment
		(start 206.508604 -277.277322)
		(end 206.320644 -277.465282)
		(width 0.20066)
		(layer "F.Cu")
		(net "M_H_CPU1_SA_CB<1>")
	)
	(segment
		(start 123.497848 -260.708902)
		(end 123.497848 -261.244334)
		(width 0.20066)
		(layer "F.Cu")
		(net "M_H_CPU1_SA_CB<1>")
	)
	(segment
		(start 209.596482 -276.785324)
		(end 209.186526 -276.785324)
		(width 0.20066)
		(layer "F.Cu")
		(net "M_H_CPU1_SA_CB<1>")
	)
	(segment
		(start 209.180176 -276.791674)
		(end 206.991458 -276.791674)
		(width 0.1016)
		(layer "F.Cu")
		(net "M_H_CPU1_SA_CB<1>")
	)
	(segment
		(start 209.186526 -276.785324)
		(end 209.180176 -276.791674)
		(width 0.1016)
		(layer "F.Cu")
		(net "M_H_CPU1_SA_CB<1>")
	)
	(segment
		(start 205.84541 -277.465282)
		(end 205.596744 -277.216616)
		(width 0.20066)
		(layer "F.Cu")
		(net "M_H_CPU1_SA_CB<1>")
	)
	(segment
		(start 210.028028 -277.21687)
		(end 209.596482 -276.785324)
		(width 0.20066)
		(layer "F.Cu")
		(net "M_H_CPU1_SA_CB<1>")
	)
	(segment
		(start 206.971392 -276.791674)
		(end 206.626714 -276.791674)
		(width 0.20066)
		(layer "F.Cu")
		(net "M_H_CPU1_SA_CB<1>")
	)
	(segment
		(start 206.508604 -276.909784)
		(end 206.508604 -277.277322)
		(width 0.20066)
		(layer "F.Cu")
		(net "M_H_CPU1_SA_CB<1>")
	)
	(segment
		(start 211.619846 -277.216616)
		(end 211.619592 -277.21687)
		(width 0.20066)
		(layer "F.Cu")
		(net "M_H_CPU1_SA_CB<1>")
	)
	(segment
		(start 205.596744 -277.216616)
		(end 204.076046 -277.216616)
		(width 0.20066)
		(layer "F.Cu")
		(net "M_H_CPU1_SA_CB<1>")
	)
	(segment
		(start 206.320644 -277.465282)
		(end 205.84541 -277.465282)
		(width 0.20066)
		(layer "F.Cu")
		(net "M_H_CPU1_SA_CB<1>")
	)
	(segment
		(start 206.626714 -276.791674)
		(end 206.508604 -276.909784)
		(width 0.20066)
		(layer "F.Cu")
		(net "M_H_CPU1_SA_CB<1>")
	)
	(segment
		(start 211.619592 -277.21687)
		(end 210.028028 -277.21687)
		(width 0.20066)
		(layer "F.Cu")
		(net "M_H_CPU1_SA_CB<1>")
	)
	(segment
		(start 166.057072 -278.063706)
		(end 165.44544 -277.452074)
		(width 0.18288)
		(layer "In11.Cu")
		(net "M_H_CPU1_SA_CB<1>")
	)
	(segment
		(start 195.069714 -278.537162)
		(end 194.895978 -278.363426)
		(width 0.18288)
		(layer "In11.Cu")
		(net "M_H_CPU1_SA_CB<1>")
	)
	(segment
		(start 202.971146 -277.216616)
		(end 202.971146 -277.37308)
		(width 0.18288)
		(layer "In11.Cu")
		(net "M_H_CPU1_SA_CB<1>")
	)
	(segment
		(start 181.044596 -277.504906)
		(end 181.044596 -278.52243)
		(width 0.18288)
		(layer "In11.Cu")
		(net "M_H_CPU1_SA_CB<1>")
	)
	(segment
		(start 170.821858 -278.45512)
		(end 170.821858 -278.683212)
		(width 0.18288)
		(layer "In11.Cu")
		(net "M_H_CPU1_SA_CB<1>")
	)
	(segment
		(start 173.131226 -278.490934)
		(end 172.470826 -278.490934)
		(width 0.18288)
		(layer "In11.Cu")
		(net "M_H_CPU1_SA_CB<1>")
	)
	(segment
		(start 181.555136 -277.311866)
		(end 181.237636 -277.311866)
		(width 0.18288)
		(layer "In11.Cu")
		(net "M_H_CPU1_SA_CB<1>")
	)
	(segment
		(start 126.989078 -261.742936)
		(end 126.9746 -261.7343)
		(width 0.088646)
		(layer "In11.Cu")
		(net "M_H_CPU1_SA_CB<1>")
	)
	(segment
		(start 131.68376 -261.740396)
		(end 131.673346 -261.7343)
		(width 0.088646)
		(layer "In11.Cu")
		(net "M_H_CPU1_SA_CB<1>")
	)
	(segment
		(start 193.832226 -278.566626)
		(end 193.57086 -278.827992)
		(width 0.18288)
		(layer "In11.Cu")
		(net "M_H_CPU1_SA_CB<1>")
	)
	(segment
		(start 145.22196 -264.710672)
		(end 139.605004 -264.710672)
		(width 0.18288)
		(layer "In11.Cu")
		(net "M_H_CPU1_SA_CB<1>")
	)
	(segment
		(start 169.035984 -278.26208)
		(end 168.468294 -278.031194)
		(width 0.18288)
		(layer "In11.Cu")
		(net "M_H_CPU1_SA_CB<1>")
	)
	(segment
		(start 188.904118 -278.673814)
		(end 188.295026 -278.490934)
		(width 0.18288)
		(layer "In11.Cu")
		(net "M_H_CPU1_SA_CB<1>")
	)
	(segment
		(start 181.941216 -278.71547)
		(end 181.748176 -278.52243)
		(width 0.18288)
		(layer "In11.Cu")
		(net "M_H_CPU1_SA_CB<1>")
	)
	(segment
		(start 139.605004 -264.710672)
		(end 139.398248 -264.710672)
		(width 0.088646)
		(layer "In11.Cu")
		(net "M_H_CPU1_SA_CB<1>")
	)
	(segment
		(start 178.896772 -278.388826)
		(end 178.376326 -278.910034)
		(width 0.18288)
		(layer "In11.Cu")
		(net "M_H_CPU1_SA_CB<1>")
	)
	(segment
		(start 202.971146 -277.37308)
		(end 202.911202 -277.51786)
		(width 0.18288)
		(layer "In11.Cu")
		(net "M_H_CPU1_SA_CB<1>")
	)
	(segment
		(start 137.029444 -262.891016)
		(end 137.029444 -262.872474)
		(width 0.088646)
		(layer "In11.Cu")
		(net "M_H_CPU1_SA_CB<1>")
	)
	(segment
		(start 202.814428 -277.614634)
		(end 202.541378 -277.614634)
		(width 0.18288)
		(layer "In11.Cu")
		(net "M_H_CPU1_SA_CB<1>")
	)
	(segment
		(start 187.329572 -278.490934)
		(end 187.188348 -278.34971)
		(width 0.18288)
		(layer "In11.Cu")
		(net "M_H_CPU1_SA_CB<1>")
	)
	(segment
		(start 128.868678 -261.742936)
		(end 128.853946 -261.7343)
		(width 0.088646)
		(layer "In11.Cu")
		(net "M_H_CPU1_SA_CB<1>")
	)
	(segment
		(start 170.311318 -278.876252)
		(end 170.118278 -278.683212)
		(width 0.18288)
		(layer "In11.Cu")
		(net "M_H_CPU1_SA_CB<1>")
	)
	(segment
		(start 124.250196 -261.5692)
		(end 123.868688 -261.34568)
		(width 0.088646)
		(layer "In11.Cu")
		(net "M_H_CPU1_SA_CB<1>")
	)
	(segment
		(start 158.36138 -275.912834)
		(end 156.424122 -275.912834)
		(width 0.18288)
		(layer "In11.Cu")
		(net "M_H_CPU1_SA_CB<1>")
	)
	(segment
		(start 194.895978 -278.363426)
		(end 194.391026 -278.363426)
		(width 0.18288)
		(layer "In11.Cu")
		(net "M_H_CPU1_SA_CB<1>")
	)
	(segment
		(start 179.668932 -278.388826)
		(end 178.896772 -278.388826)
		(width 0.18288)
		(layer "In11.Cu")
		(net "M_H_CPU1_SA_CB<1>")
	)
	(segment
		(start 184.454038 -278.34971)
		(end 182.734966 -278.71547)
		(width 0.18288)
		(layer "In11.Cu")
		(net "M_H_CPU1_SA_CB<1>")
	)
	(segment
		(start 133.567678 -261.742936)
		(end 133.552946 -261.7343)
		(width 0.088646)
		(layer "In11.Cu")
		(net "M_H_CPU1_SA_CB<1>")
	)
	(segment
		(start 138.439144 -263.751568)
		(end 138.439144 -263.686544)
		(width 0.088646)
		(layer "In11.Cu")
		(net "M_H_CPU1_SA_CB<1>")
	)
	(segment
		(start 134.50316 -261.740396)
		(end 134.492746 -261.7343)
		(width 0.088646)
		(layer "In11.Cu")
		(net "M_H_CPU1_SA_CB<1>")
	)
	(segment
		(start 177.398426 -279.341072)
		(end 176.357026 -279.341072)
		(width 0.18288)
		(layer "In11.Cu")
		(net "M_H_CPU1_SA_CB<1>")
	)
	(segment
		(start 167.142668 -277.576026)
		(end 166.654988 -278.063706)
		(width 0.18288)
		(layer "In11.Cu")
		(net "M_H_CPU1_SA_CB<1>")
	)
	(segment
		(start 164.682678 -277.452074)
		(end 164.482526 -277.652226)
		(width 0.18288)
		(layer "In11.Cu")
		(net "M_H_CPU1_SA_CB<1>")
	)
	(segment
		(start 182.734966 -278.71547)
		(end 181.941216 -278.71547)
		(width 0.18288)
		(layer "In11.Cu")
		(net "M_H_CPU1_SA_CB<1>")
	)
	(segment
		(start 188.295026 -278.490934)
		(end 187.329572 -278.490934)
		(width 0.18288)
		(layer "In11.Cu")
		(net "M_H_CPU1_SA_CB<1>")
	)
	(segment
		(start 171.014898 -278.26208)
		(end 170.821858 -278.45512)
		(width 0.18288)
		(layer "In11.Cu")
		(net "M_H_CPU1_SA_CB<1>")
	)
	(segment
		(start 136.559544 -262.068564)
		(end 136.559544 -262.058658)
		(width 0.088646)
		(layer "In11.Cu")
		(net "M_H_CPU1_SA_CB<1>")
	)
	(segment
		(start 136.380982 -261.73938)
		(end 136.372092 -261.7343)
		(width 0.088646)
		(layer "In11.Cu")
		(net "M_H_CPU1_SA_CB<1>")
	)
	(segment
		(start 175.341026 -279.227026)
		(end 174.902368 -279.227026)
		(width 0.18288)
		(layer "In11.Cu")
		(net "M_H_CPU1_SA_CB<1>")
	)
	(segment
		(start 132.623306 -261.740396)
		(end 132.612892 -261.7343)
		(width 0.088646)
		(layer "In11.Cu")
		(net "M_H_CPU1_SA_CB<1>")
	)
	(segment
		(start 190.128906 -279.341072)
		(end 188.904118 -278.673814)
		(width 0.18288)
		(layer "In11.Cu")
		(net "M_H_CPU1_SA_CB<1>")
	)
	(segment
		(start 202.911202 -277.51786)
		(end 202.814428 -277.614634)
		(width 0.18288)
		(layer "In11.Cu")
		(net "M_H_CPU1_SA_CB<1>")
	)
	(segment
		(start 164.482526 -277.652226)
		(end 163.314126 -277.652226)
		(width 0.18288)
		(layer "In11.Cu")
		(net "M_H_CPU1_SA_CB<1>")
	)
	(segment
		(start 170.118278 -278.45512)
		(end 169.925238 -278.26208)
		(width 0.18288)
		(layer "In11.Cu")
		(net "M_H_CPU1_SA_CB<1>")
	)
	(segment
		(start 127.928878 -261.742936)
		(end 127.914146 -261.7343)
		(width 0.088646)
		(layer "In11.Cu")
		(net "M_H_CPU1_SA_CB<1>")
	)
	(segment
		(start 169.925238 -278.26208)
		(end 169.035984 -278.26208)
		(width 0.18288)
		(layer "In11.Cu")
		(net "M_H_CPU1_SA_CB<1>")
	)
	(segment
		(start 167.467026 -277.576026)
		(end 167.142668 -277.576026)
		(width 0.18288)
		(layer "In11.Cu")
		(net "M_H_CPU1_SA_CB<1>")
	)
	(segment
		(start 179.995576 -278.71547)
		(end 179.668932 -278.388826)
		(width 0.18288)
		(layer "In11.Cu")
		(net "M_H_CPU1_SA_CB<1>")
	)
	(segment
		(start 170.821858 -278.683212)
		(end 170.628818 -278.876252)
		(width 0.18288)
		(layer "In11.Cu")
		(net "M_H_CPU1_SA_CB<1>")
	)
	(segment
		(start 160.523428 -275.913088)
		(end 158.361634 -275.913088)
		(width 0.18288)
		(layer "In11.Cu")
		(net "M_H_CPU1_SA_CB<1>")
	)
	(segment
		(start 192.3415 -279.341072)
		(end 190.128906 -279.341072)
		(width 0.18288)
		(layer "In11.Cu")
		(net "M_H_CPU1_SA_CB<1>")
	)
	(segment
		(start 163.314126 -277.652226)
		(end 162.323526 -276.661626)
		(width 0.18288)
		(layer "In11.Cu")
		(net "M_H_CPU1_SA_CB<1>")
	)
	(segment
		(start 136.850882 -262.553196)
		(end 136.841992 -262.548116)
		(width 0.088646)
		(layer "In11.Cu")
		(net "M_H_CPU1_SA_CB<1>")
	)
	(segment
		(start 198.898764 -277.942802)
		(end 198.304404 -278.537162)
		(width 0.18288)
		(layer "In11.Cu")
		(net "M_H_CPU1_SA_CB<1>")
	)
	(segment
		(start 201.411332 -276.737826)
		(end 200.206356 -277.942802)
		(width 0.18288)
		(layer "In11.Cu")
		(net "M_H_CPU1_SA_CB<1>")
	)
	(segment
		(start 126.044706 -261.740396)
		(end 126.034292 -261.7343)
		(width 0.088646)
		(layer "In11.Cu")
		(net "M_H_CPU1_SA_CB<1>")
	)
	(segment
		(start 130.748278 -261.742936)
		(end 130.733546 -261.7343)
		(width 0.088646)
		(layer "In11.Cu")
		(net "M_H_CPU1_SA_CB<1>")
	)
	(segment
		(start 202.541378 -277.614634)
		(end 202.191366 -277.264622)
		(width 0.18288)
		(layer "In11.Cu")
		(net "M_H_CPU1_SA_CB<1>")
	)
	(segment
		(start 161.271966 -276.661626)
		(end 160.523428 -275.913088)
		(width 0.18288)
		(layer "In11.Cu")
		(net "M_H_CPU1_SA_CB<1>")
	)
	(segment
		(start 187.188348 -278.34971)
		(end 184.454038 -278.34971)
		(width 0.18288)
		(layer "In11.Cu")
		(net "M_H_CPU1_SA_CB<1>")
	)
	(segment
		(start 178.376326 -278.910034)
		(end 177.398426 -279.341072)
		(width 0.18288)
		(layer "In11.Cu")
		(net "M_H_CPU1_SA_CB<1>")
	)
	(segment
		(start 156.424122 -275.912834)
		(end 145.22196 -264.710672)
		(width 0.18288)
		(layer "In11.Cu")
		(net "M_H_CPU1_SA_CB<1>")
	)
	(segment
		(start 166.654988 -278.063706)
		(end 166.057072 -278.063706)
		(width 0.18288)
		(layer "In11.Cu")
		(net "M_H_CPU1_SA_CB<1>")
	)
	(segment
		(start 181.748176 -278.52243)
		(end 181.748176 -277.504906)
		(width 0.18288)
		(layer "In11.Cu")
		(net "M_H_CPU1_SA_CB<1>")
	)
	(segment
		(start 198.304404 -278.537162)
		(end 195.069714 -278.537162)
		(width 0.18288)
		(layer "In11.Cu")
		(net "M_H_CPU1_SA_CB<1>")
	)
	(segment
		(start 202.191366 -276.988524)
		(end 201.940668 -276.737826)
		(width 0.18288)
		(layer "In11.Cu")
		(net "M_H_CPU1_SA_CB<1>")
	)
	(segment
		(start 158.361634 -275.913088)
		(end 158.36138 -275.912834)
		(width 0.18288)
		(layer "In11.Cu")
		(net "M_H_CPU1_SA_CB<1>")
	)
	(segment
		(start 181.748176 -277.504906)
		(end 181.555136 -277.311866)
		(width 0.18288)
		(layer "In11.Cu")
		(net "M_H_CPU1_SA_CB<1>")
	)
	(segment
		(start 129.808478 -261.742936)
		(end 129.793746 -261.7343)
		(width 0.088646)
		(layer "In11.Cu")
		(net "M_H_CPU1_SA_CB<1>")
	)
	(segment
		(start 194.391026 -278.363426)
		(end 193.832226 -278.566626)
		(width 0.18288)
		(layer "In11.Cu")
		(net "M_H_CPU1_SA_CB<1>")
	)
	(segment
		(start 139.398248 -264.710672)
		(end 138.439144 -263.751568)
		(width 0.088646)
		(layer "In11.Cu")
		(net "M_H_CPU1_SA_CB<1>")
	)
	(segment
		(start 138.260582 -263.367266)
		(end 138.251692 -263.362186)
		(width 0.088646)
		(layer "In11.Cu")
		(net "M_H_CPU1_SA_CB<1>")
	)
	(segment
		(start 170.118278 -278.683212)
		(end 170.118278 -278.45512)
		(width 0.18288)
		(layer "In11.Cu")
		(net "M_H_CPU1_SA_CB<1>")
	)
	(segment
		(start 162.323526 -276.661626)
		(end 161.271966 -276.661626)
		(width 0.18288)
		(layer "In11.Cu")
		(net "M_H_CPU1_SA_CB<1>")
	)
	(segment
		(start 202.191366 -277.264622)
		(end 202.191366 -276.988524)
		(width 0.18288)
		(layer "In11.Cu")
		(net "M_H_CPU1_SA_CB<1>")
	)
	(segment
		(start 201.940668 -276.737826)
		(end 201.411332 -276.737826)
		(width 0.18288)
		(layer "In11.Cu")
		(net "M_H_CPU1_SA_CB<1>")
	)
	(segment
		(start 170.628818 -278.876252)
		(end 170.311318 -278.876252)
		(width 0.18288)
		(layer "In11.Cu")
		(net "M_H_CPU1_SA_CB<1>")
	)
	(segment
		(start 193.57086 -278.827992)
		(end 192.3415 -279.341072)
		(width 0.18288)
		(layer "In11.Cu")
		(net "M_H_CPU1_SA_CB<1>")
	)
	(segment
		(start 181.044596 -278.52243)
		(end 180.851556 -278.71547)
		(width 0.18288)
		(layer "In11.Cu")
		(net "M_H_CPU1_SA_CB<1>")
	)
	(segment
		(start 165.44544 -277.452074)
		(end 164.682678 -277.452074)
		(width 0.18288)
		(layer "In11.Cu")
		(net "M_H_CPU1_SA_CB<1>")
	)
	(segment
		(start 176.357026 -279.341072)
		(end 175.341026 -279.227026)
		(width 0.18288)
		(layer "In11.Cu")
		(net "M_H_CPU1_SA_CB<1>")
	)
	(segment
		(start 180.851556 -278.71547)
		(end 179.995576 -278.71547)
		(width 0.18288)
		(layer "In11.Cu")
		(net "M_H_CPU1_SA_CB<1>")
	)
	(segment
		(start 168.468294 -278.031194)
		(end 167.467026 -277.576026)
		(width 0.18288)
		(layer "In11.Cu")
		(net "M_H_CPU1_SA_CB<1>")
	)
	(segment
		(start 181.237636 -277.311866)
		(end 181.044596 -277.504906)
		(width 0.18288)
		(layer "In11.Cu")
		(net "M_H_CPU1_SA_CB<1>")
	)
	(segment
		(start 174.902368 -279.227026)
		(end 173.698916 -278.668988)
		(width 0.18288)
		(layer "In11.Cu")
		(net "M_H_CPU1_SA_CB<1>")
	)
	(segment
		(start 172.470826 -278.490934)
		(end 172.241972 -278.26208)
		(width 0.18288)
		(layer "In11.Cu")
		(net "M_H_CPU1_SA_CB<1>")
	)
	(segment
		(start 125.309122 -261.63905)
		(end 125.175264 -261.560564)
		(width 0.088646)
		(layer "In11.Cu")
		(net "M_H_CPU1_SA_CB<1>")
	)
	(segment
		(start 172.241972 -278.26208)
		(end 171.014898 -278.26208)
		(width 0.18288)
		(layer "In11.Cu")
		(net "M_H_CPU1_SA_CB<1>")
	)
	(segment
		(start 200.206356 -277.942802)
		(end 198.898764 -277.942802)
		(width 0.18288)
		(layer "In11.Cu")
		(net "M_H_CPU1_SA_CB<1>")
	)
	(segment
		(start 173.698916 -278.668988)
		(end 173.131226 -278.490934)
		(width 0.18288)
		(layer "In11.Cu")
		(net "M_H_CPU1_SA_CB<1>")
	)
	(arc
		(start 128.47955 -261.7343)
		(mid 128.205351 -261.810135)
		(end 127.928878 -261.742936)
		(width 0.088646)
		(layer "In11.Cu")
		(net "M_H_CPU1_SA_CB<1>")
	)
	(arc
		(start 133.552946 -261.7343)
		(mid 133.365748 -261.684157)
		(end 133.17855 -261.7343)
		(width 0.088646)
		(layer "In11.Cu")
		(net "M_H_CPU1_SA_CB<1>")
	)
	(arc
		(start 123.868688 -261.34568)
		(mid 123.689867 -261.270495)
		(end 123.497594 -261.244842)
		(width 0.088646)
		(layer "In11.Cu")
		(net "M_H_CPU1_SA_CB<1>")
	)
	(arc
		(start 133.17855 -261.7343)
		(mid 132.901737 -261.81017)
		(end 132.623306 -261.740396)
		(width 0.088646)
		(layer "In11.Cu")
		(net "M_H_CPU1_SA_CB<1>")
	)
	(arc
		(start 128.853946 -261.7343)
		(mid 128.666748 -261.684157)
		(end 128.47955 -261.7343)
		(width 0.088646)
		(layer "In11.Cu")
		(net "M_H_CPU1_SA_CB<1>")
	)
	(arc
		(start 130.35915 -261.7343)
		(mid 130.084951 -261.810135)
		(end 129.808478 -261.742936)
		(width 0.088646)
		(layer "In11.Cu")
		(net "M_H_CPU1_SA_CB<1>")
	)
	(arc
		(start 129.793746 -261.7343)
		(mid 129.606548 -261.684157)
		(end 129.41935 -261.7343)
		(width 0.088646)
		(layer "In11.Cu")
		(net "M_H_CPU1_SA_CB<1>")
	)
	(arc
		(start 131.29895 -261.7343)
		(mid 131.024751 -261.810135)
		(end 130.748278 -261.742936)
		(width 0.088646)
		(layer "In11.Cu")
		(net "M_H_CPU1_SA_CB<1>")
	)
	(arc
		(start 135.057896 -261.7343)
		(mid 134.781337 -261.810043)
		(end 134.50316 -261.740396)
		(width 0.088646)
		(layer "In11.Cu")
		(net "M_H_CPU1_SA_CB<1>")
	)
	(arc
		(start 137.877296 -263.362186)
		(mid 137.594594 -263.437928)
		(end 137.311892 -263.362186)
		(width 0.088646)
		(layer "In11.Cu")
		(net "M_H_CPU1_SA_CB<1>")
	)
	(arc
		(start 137.029444 -262.872474)
		(mid 136.981765 -262.689574)
		(end 136.850882 -262.553196)
		(width 0.088646)
		(layer "In11.Cu")
		(net "M_H_CPU1_SA_CB<1>")
	)
	(arc
		(start 132.612892 -261.7343)
		(mid 132.425694 -261.684157)
		(end 132.238496 -261.7343)
		(width 0.088646)
		(layer "In11.Cu")
		(net "M_H_CPU1_SA_CB<1>")
	)
	(arc
		(start 136.841992 -262.548116)
		(mid 136.637657 -262.345511)
		(end 136.559544 -262.068564)
		(width 0.088646)
		(layer "In11.Cu")
		(net "M_H_CPU1_SA_CB<1>")
	)
	(arc
		(start 136.559544 -262.058658)
		(mid 136.511865 -261.875758)
		(end 136.380982 -261.73938)
		(width 0.088646)
		(layer "In11.Cu")
		(net "M_H_CPU1_SA_CB<1>")
	)
	(arc
		(start 134.492746 -261.7343)
		(mid 134.305548 -261.684157)
		(end 134.11835 -261.7343)
		(width 0.088646)
		(layer "In11.Cu")
		(net "M_H_CPU1_SA_CB<1>")
	)
	(arc
		(start 125.659896 -261.7343)
		(mid 125.47816 -261.710061)
		(end 125.309122 -261.63905)
		(width 0.088646)
		(layer "In11.Cu")
		(net "M_H_CPU1_SA_CB<1>")
	)
	(arc
		(start 131.673346 -261.7343)
		(mid 131.486148 -261.684157)
		(end 131.29895 -261.7343)
		(width 0.088646)
		(layer "In11.Cu")
		(net "M_H_CPU1_SA_CB<1>")
	)
	(arc
		(start 126.034292 -261.7343)
		(mid 125.847094 -261.684157)
		(end 125.659896 -261.7343)
		(width 0.088646)
		(layer "In11.Cu")
		(net "M_H_CPU1_SA_CB<1>")
	)
	(arc
		(start 126.9746 -261.7343)
		(mid 126.787292 -261.684157)
		(end 126.59995 -261.7343)
		(width 0.088646)
		(layer "In11.Cu")
		(net "M_H_CPU1_SA_CB<1>")
	)
	(arc
		(start 135.997696 -261.7343)
		(mid 135.714994 -261.810076)
		(end 135.432292 -261.7343)
		(width 0.088646)
		(layer "In11.Cu")
		(net "M_H_CPU1_SA_CB<1>")
	)
	(arc
		(start 132.238496 -261.7343)
		(mid 131.961937 -261.810043)
		(end 131.68376 -261.740396)
		(width 0.088646)
		(layer "In11.Cu")
		(net "M_H_CPU1_SA_CB<1>")
	)
	(arc
		(start 138.439144 -263.686544)
		(mid 138.391465 -263.503644)
		(end 138.260582 -263.367266)
		(width 0.088646)
		(layer "In11.Cu")
		(net "M_H_CPU1_SA_CB<1>")
	)
	(arc
		(start 137.311892 -263.362186)
		(mid 137.109606 -263.163205)
		(end 137.029444 -262.891016)
		(width 0.088646)
		(layer "In11.Cu")
		(net "M_H_CPU1_SA_CB<1>")
	)
	(arc
		(start 127.914146 -261.7343)
		(mid 127.726948 -261.684157)
		(end 127.53975 -261.7343)
		(width 0.088646)
		(layer "In11.Cu")
		(net "M_H_CPU1_SA_CB<1>")
	)
	(arc
		(start 125.175264 -261.560564)
		(mid 124.898789 -261.493244)
		(end 124.624592 -261.5692)
		(width 0.088646)
		(layer "In11.Cu")
		(net "M_H_CPU1_SA_CB<1>")
	)
	(arc
		(start 129.41935 -261.7343)
		(mid 129.145151 -261.810135)
		(end 128.868678 -261.742936)
		(width 0.088646)
		(layer "In11.Cu")
		(net "M_H_CPU1_SA_CB<1>")
	)
	(arc
		(start 130.733546 -261.7343)
		(mid 130.546348 -261.684157)
		(end 130.35915 -261.7343)
		(width 0.088646)
		(layer "In11.Cu")
		(net "M_H_CPU1_SA_CB<1>")
	)
	(arc
		(start 136.372092 -261.7343)
		(mid 136.184894 -261.684157)
		(end 135.997696 -261.7343)
		(width 0.088646)
		(layer "In11.Cu")
		(net "M_H_CPU1_SA_CB<1>")
	)
	(arc
		(start 124.624592 -261.5692)
		(mid 124.437394 -261.619343)
		(end 124.250196 -261.5692)
		(width 0.088646)
		(layer "In11.Cu")
		(net "M_H_CPU1_SA_CB<1>")
	)
	(arc
		(start 134.11835 -261.7343)
		(mid 133.844151 -261.810135)
		(end 133.567678 -261.742936)
		(width 0.088646)
		(layer "In11.Cu")
		(net "M_H_CPU1_SA_CB<1>")
	)
	(arc
		(start 127.53975 -261.7343)
		(mid 127.265551 -261.810135)
		(end 126.989078 -261.742936)
		(width 0.088646)
		(layer "In11.Cu")
		(net "M_H_CPU1_SA_CB<1>")
	)
	(arc
		(start 135.432292 -261.7343)
		(mid 135.245094 -261.684157)
		(end 135.057896 -261.7343)
		(width 0.088646)
		(layer "In11.Cu")
		(net "M_H_CPU1_SA_CB<1>")
	)
	(arc
		(start 138.251692 -263.362186)
		(mid 138.064494 -263.312043)
		(end 137.877296 -263.362186)
		(width 0.088646)
		(layer "In11.Cu")
		(net "M_H_CPU1_SA_CB<1>")
	)
	(arc
		(start 126.59995 -261.7343)
		(mid 126.323137 -261.81017)
		(end 126.044706 -261.740396)
		(width 0.088646)
		(layer "In11.Cu")
		(net "M_H_CPU1_SA_CB<1>")
	)
	(segment
		(start 209.180176 -278.491696)
		(end 207.018382 -278.491696)
		(width 0.1016)
		(layer "F.Cu")
		(net "M_H_CPU1_SA_CB<0>")
	)
	(segment
		(start 211.619592 -278.916892)
		(end 210.028028 -278.916892)
		(width 0.20066)
		(layer "F.Cu")
		(net "M_H_CPU1_SA_CB<0>")
	)
	(segment
		(start 206.320644 -279.165304)
		(end 205.84541 -279.165304)
		(width 0.20066)
		(layer "F.Cu")
		(net "M_H_CPU1_SA_CB<0>")
	)
	(segment
		(start 210.028028 -278.916892)
		(end 209.596482 -278.485346)
		(width 0.20066)
		(layer "F.Cu")
		(net "M_H_CPU1_SA_CB<0>")
	)
	(segment
		(start 206.508604 -278.977344)
		(end 206.320644 -279.165304)
		(width 0.20066)
		(layer "F.Cu")
		(net "M_H_CPU1_SA_CB<0>")
	)
	(segment
		(start 205.596744 -278.916638)
		(end 204.076046 -278.916638)
		(width 0.20066)
		(layer "F.Cu")
		(net "M_H_CPU1_SA_CB<0>")
	)
	(segment
		(start 204.076046 -278.916638)
		(end 202.971146 -278.916638)
		(width 0.20066)
		(layer "F.Cu")
		(net "M_H_CPU1_SA_CB<0>")
	)
	(segment
		(start 205.84541 -279.165304)
		(end 205.596744 -278.916638)
		(width 0.20066)
		(layer "F.Cu")
		(net "M_H_CPU1_SA_CB<0>")
	)
	(segment
		(start 207.018382 -278.491696)
		(end 206.971392 -278.491696)
		(width 0.101854)
		(layer "F.Cu")
		(net "M_H_CPU1_SA_CB<0>")
	)
	(segment
		(start 206.508604 -278.609806)
		(end 206.508604 -278.977344)
		(width 0.20066)
		(layer "F.Cu")
		(net "M_H_CPU1_SA_CB<0>")
	)
	(segment
		(start 206.971392 -278.491696)
		(end 206.626714 -278.491696)
		(width 0.20066)
		(layer "F.Cu")
		(net "M_H_CPU1_SA_CB<0>")
	)
	(segment
		(start 209.596482 -278.485346)
		(end 209.186526 -278.485346)
		(width 0.20066)
		(layer "F.Cu")
		(net "M_H_CPU1_SA_CB<0>")
	)
	(segment
		(start 211.619846 -278.916638)
		(end 211.619592 -278.916892)
		(width 0.20066)
		(layer "F.Cu")
		(net "M_H_CPU1_SA_CB<0>")
	)
	(segment
		(start 123.967494 -261.522718)
		(end 123.967748 -261.522972)
		(width 0.20066)
		(layer "F.Cu")
		(net "M_H_CPU1_SA_CB<0>")
	)
	(segment
		(start 209.186526 -278.485346)
		(end 209.180176 -278.491696)
		(width 0.1016)
		(layer "F.Cu")
		(net "M_H_CPU1_SA_CB<0>")
	)
	(segment
		(start 206.626714 -278.491696)
		(end 206.508604 -278.609806)
		(width 0.20066)
		(layer "F.Cu")
		(net "M_H_CPU1_SA_CB<0>")
	)
	(segment
		(start 123.967748 -261.522972)
		(end 123.967748 -262.058658)
		(width 0.20066)
		(layer "F.Cu")
		(net "M_H_CPU1_SA_CB<0>")
	)
	(segment
		(start 125.57506 -262.554212)
		(end 125.564646 -262.548116)
		(width 0.088646)
		(layer "In11.Cu")
		(net "M_H_CPU1_SA_CB<0>")
	)
	(segment
		(start 178.730656 -280.256742)
		(end 177.6857 -280.896314)
		(width 0.18288)
		(layer "In11.Cu")
		(net "M_H_CPU1_SA_CB<0>")
	)
	(segment
		(start 170.182794 -280.309066)
		(end 169.989754 -280.116026)
		(width 0.18288)
		(layer "In11.Cu")
		(net "M_H_CPU1_SA_CB<0>")
	)
	(segment
		(start 136.089644 -262.891016)
		(end 136.089644 -262.872474)
		(width 0.088646)
		(layer "In11.Cu")
		(net "M_H_CPU1_SA_CB<0>")
	)
	(segment
		(start 173.224698 -280.653236)
		(end 173.224698 -280.289)
		(width 0.18288)
		(layer "In11.Cu")
		(net "M_H_CPU1_SA_CB<0>")
	)
	(segment
		(start 164.736526 -279.331166)
		(end 164.500306 -279.421082)
		(width 0.18288)
		(layer "In11.Cu")
		(net "M_H_CPU1_SA_CB<0>")
	)
	(segment
		(start 196.250814 -279.804114)
		(end 196.250814 -280.269696)
		(width 0.18288)
		(layer "In11.Cu")
		(net "M_H_CPU1_SA_CB<0>")
	)
	(segment
		(start 135.911082 -262.553196)
		(end 135.902192 -262.548116)
		(width 0.088646)
		(layer "In11.Cu")
		(net "M_H_CPU1_SA_CB<0>")
	)
	(segment
		(start 187.279026 -280.141426)
		(end 184.116726 -280.141426)
		(width 0.18288)
		(layer "In11.Cu")
		(net "M_H_CPU1_SA_CB<0>")
	)
	(segment
		(start 194.44843 -280.033222)
		(end 193.301366 -280.301446)
		(width 0.18288)
		(layer "In11.Cu")
		(net "M_H_CPU1_SA_CB<0>")
	)
	(segment
		(start 173.66234 -280.846276)
		(end 173.417738 -280.846276)
		(width 0.18288)
		(layer "In11.Cu")
		(net "M_H_CPU1_SA_CB<0>")
	)
	(segment
		(start 139.336018 -265.726672)
		(end 137.790682 -264.181336)
		(width 0.088646)
		(layer "In11.Cu")
		(net "M_H_CPU1_SA_CB<0>")
	)
	(segment
		(start 179.239926 -280.141426)
		(end 178.845972 -280.141426)
		(width 0.18288)
		(layer "In11.Cu")
		(net "M_H_CPU1_SA_CB<0>")
	)
	(segment
		(start 196.954394 -279.804114)
		(end 196.761354 -279.611074)
		(width 0.18288)
		(layer "In11.Cu")
		(net "M_H_CPU1_SA_CB<0>")
	)
	(segment
		(start 195.098924 -280.462736)
		(end 194.66941 -280.033222)
		(width 0.18288)
		(layer "In11.Cu")
		(net "M_H_CPU1_SA_CB<0>")
	)
	(segment
		(start 197.147434 -280.462736)
		(end 196.954394 -280.269696)
		(width 0.18288)
		(layer "In11.Cu")
		(net "M_H_CPU1_SA_CB<0>")
	)
	(segment
		(start 134.587996 -262.548116)
		(end 134.573264 -262.556752)
		(width 0.088646)
		(layer "In11.Cu")
		(net "M_H_CPU1_SA_CB<0>")
	)
	(segment
		(start 202.971146 -278.916638)
		(end 202.971146 -279.073102)
		(width 0.18288)
		(layer "In11.Cu")
		(net "M_H_CPU1_SA_CB<0>")
	)
	(segment
		(start 167.854122 -279.331166)
		(end 164.736526 -279.331166)
		(width 0.18288)
		(layer "In11.Cu")
		(net "M_H_CPU1_SA_CB<0>")
	)
	(segment
		(start 174.04842 -281.886406)
		(end 173.85538 -281.693366)
		(width 0.18288)
		(layer "In11.Cu")
		(net "M_H_CPU1_SA_CB<0>")
	)
	(segment
		(start 173.224698 -280.289)
		(end 173.126654 -280.190956)
		(width 0.18288)
		(layer "In11.Cu")
		(net "M_H_CPU1_SA_CB<0>")
	)
	(segment
		(start 201.562462 -278.435308)
		(end 200.596754 -279.401016)
		(width 0.18288)
		(layer "In11.Cu")
		(net "M_H_CPU1_SA_CB<0>")
	)
	(segment
		(start 162.500564 -278.759666)
		(end 160.441894 -277.62454)
		(width 0.18288)
		(layer "In11.Cu")
		(net "M_H_CPU1_SA_CB<0>")
	)
	(segment
		(start 173.126654 -280.190956)
		(end 172.305726 -280.190956)
		(width 0.18288)
		(layer "In11.Cu")
		(net "M_H_CPU1_SA_CB<0>")
	)
	(segment
		(start 174.55896 -281.039316)
		(end 174.55896 -281.693366)
		(width 0.18288)
		(layer "In11.Cu")
		(net "M_H_CPU1_SA_CB<0>")
	)
	(segment
		(start 170.182794 -280.852372)
		(end 170.182794 -280.309066)
		(width 0.18288)
		(layer "In11.Cu")
		(net "M_H_CPU1_SA_CB<0>")
	)
	(segment
		(start 125.19025 -262.548116)
		(end 125.179836 -262.554212)
		(width 0.088646)
		(layer "In11.Cu")
		(net "M_H_CPU1_SA_CB<0>")
	)
	(segment
		(start 163.965128 -279.389586)
		(end 162.500564 -278.759666)
		(width 0.18288)
		(layer "In11.Cu")
		(net "M_H_CPU1_SA_CB<0>")
	)
	(segment
		(start 173.417738 -280.846276)
		(end 173.224698 -280.653236)
		(width 0.18288)
		(layer "In11.Cu")
		(net "M_H_CPU1_SA_CB<0>")
	)
	(segment
		(start 197.982078 -280.462736)
		(end 197.147434 -280.462736)
		(width 0.18288)
		(layer "In11.Cu")
		(net "M_H_CPU1_SA_CB<0>")
	)
	(segment
		(start 173.85538 -281.693366)
		(end 173.85538 -281.039316)
		(width 0.18288)
		(layer "In11.Cu")
		(net "M_H_CPU1_SA_CB<0>")
	)
	(segment
		(start 189.556644 -280.879804)
		(end 189.116208 -280.439368)
		(width 0.18288)
		(layer "In11.Cu")
		(net "M_H_CPU1_SA_CB<0>")
	)
	(segment
		(start 160.441894 -277.62454)
		(end 156.698188 -277.62454)
		(width 0.18288)
		(layer "In11.Cu")
		(net "M_H_CPU1_SA_CB<0>")
	)
	(segment
		(start 178.845972 -280.141426)
		(end 178.730656 -280.256742)
		(width 0.18288)
		(layer "In11.Cu")
		(net "M_H_CPU1_SA_CB<0>")
	)
	(segment
		(start 176.301908 -280.846276)
		(end 174.752 -280.846276)
		(width 0.18288)
		(layer "In11.Cu")
		(net "M_H_CPU1_SA_CB<0>")
	)
	(segment
		(start 128.949196 -262.548116)
		(end 128.934464 -262.556752)
		(width 0.088646)
		(layer "In11.Cu")
		(net "M_H_CPU1_SA_CB<0>")
	)
	(segment
		(start 129.888996 -262.548116)
		(end 129.874264 -262.556752)
		(width 0.088646)
		(layer "In11.Cu")
		(net "M_H_CPU1_SA_CB<0>")
	)
	(segment
		(start 170.693334 -281.045412)
		(end 170.375834 -281.045412)
		(width 0.18288)
		(layer "In11.Cu")
		(net "M_H_CPU1_SA_CB<0>")
	)
	(segment
		(start 192.56248 -281.040332)
		(end 190.984378 -281.040332)
		(width 0.18288)
		(layer "In11.Cu")
		(net "M_H_CPU1_SA_CB<0>")
	)
	(segment
		(start 202.541378 -279.314656)
		(end 202.191366 -278.964644)
		(width 0.18288)
		(layer "In11.Cu")
		(net "M_H_CPU1_SA_CB<0>")
	)
	(segment
		(start 196.954394 -280.269696)
		(end 196.954394 -279.804114)
		(width 0.18288)
		(layer "In11.Cu")
		(net "M_H_CPU1_SA_CB<0>")
	)
	(segment
		(start 184.116726 -280.141426)
		(end 183.175656 -280.323036)
		(width 0.18288)
		(layer "In11.Cu")
		(net "M_H_CPU1_SA_CB<0>")
	)
	(segment
		(start 196.761354 -279.611074)
		(end 196.443854 -279.611074)
		(width 0.18288)
		(layer "In11.Cu")
		(net "M_H_CPU1_SA_CB<0>")
	)
	(segment
		(start 202.911202 -279.217882)
		(end 202.814428 -279.314656)
		(width 0.18288)
		(layer "In11.Cu")
		(net "M_H_CPU1_SA_CB<0>")
	)
	(segment
		(start 183.175656 -280.323036)
		(end 181.124352 -280.401268)
		(width 0.18288)
		(layer "In11.Cu")
		(net "M_H_CPU1_SA_CB<0>")
	)
	(segment
		(start 137.790682 -264.181336)
		(end 137.781792 -264.176256)
		(width 0.088646)
		(layer "In11.Cu")
		(net "M_H_CPU1_SA_CB<0>")
	)
	(segment
		(start 156.698188 -277.62454)
		(end 144.80032 -265.726672)
		(width 0.18288)
		(layer "In11.Cu")
		(net "M_H_CPU1_SA_CB<0>")
	)
	(segment
		(start 127.069596 -262.548116)
		(end 127.054864 -262.556752)
		(width 0.088646)
		(layer "In11.Cu")
		(net "M_H_CPU1_SA_CB<0>")
	)
	(segment
		(start 169.989754 -280.116026)
		(end 169.704766 -280.116026)
		(width 0.18288)
		(layer "In11.Cu")
		(net "M_H_CPU1_SA_CB<0>")
	)
	(segment
		(start 131.76885 -262.548116)
		(end 131.758436 -262.554212)
		(width 0.088646)
		(layer "In11.Cu")
		(net "M_H_CPU1_SA_CB<0>")
	)
	(segment
		(start 176.496726 -281.041094)
		(end 176.301908 -280.846276)
		(width 0.18288)
		(layer "In11.Cu")
		(net "M_H_CPU1_SA_CB<0>")
	)
	(segment
		(start 170.886374 -280.309066)
		(end 170.886374 -280.852372)
		(width 0.18288)
		(layer "In11.Cu")
		(net "M_H_CPU1_SA_CB<0>")
	)
	(segment
		(start 174.55896 -281.693366)
		(end 174.36592 -281.886406)
		(width 0.18288)
		(layer "In11.Cu")
		(net "M_H_CPU1_SA_CB<0>")
	)
	(segment
		(start 196.250814 -280.269696)
		(end 196.057774 -280.462736)
		(width 0.18288)
		(layer "In11.Cu")
		(net "M_H_CPU1_SA_CB<0>")
	)
	(segment
		(start 181.124352 -280.401268)
		(end 179.788566 -280.267156)
		(width 0.18288)
		(layer "In11.Cu")
		(net "M_H_CPU1_SA_CB<0>")
	)
	(segment
		(start 202.191366 -278.964644)
		(end 202.191366 -278.725122)
		(width 0.18288)
		(layer "In11.Cu")
		(net "M_H_CPU1_SA_CB<0>")
	)
	(segment
		(start 139.605004 -265.726672)
		(end 139.336018 -265.726672)
		(width 0.088646)
		(layer "In11.Cu")
		(net "M_H_CPU1_SA_CB<0>")
	)
	(segment
		(start 179.788566 -280.267156)
		(end 179.239926 -280.141426)
		(width 0.18288)
		(layer "In11.Cu")
		(net "M_H_CPU1_SA_CB<0>")
	)
	(segment
		(start 187.328556 -280.190956)
		(end 187.279026 -280.141426)
		(width 0.18288)
		(layer "In11.Cu")
		(net "M_H_CPU1_SA_CB<0>")
	)
	(segment
		(start 171.696126 -280.116026)
		(end 171.079414 -280.116026)
		(width 0.18288)
		(layer "In11.Cu")
		(net "M_H_CPU1_SA_CB<0>")
	)
	(segment
		(start 173.85538 -281.039316)
		(end 173.66234 -280.846276)
		(width 0.18288)
		(layer "In11.Cu")
		(net "M_H_CPU1_SA_CB<0>")
	)
	(segment
		(start 132.15366 -262.554212)
		(end 132.143246 -262.548116)
		(width 0.088646)
		(layer "In11.Cu")
		(net "M_H_CPU1_SA_CB<0>")
	)
	(segment
		(start 199.043798 -279.401016)
		(end 197.982078 -280.462736)
		(width 0.18288)
		(layer "In11.Cu")
		(net "M_H_CPU1_SA_CB<0>")
	)
	(segment
		(start 190.82385 -280.879804)
		(end 189.556644 -280.879804)
		(width 0.18288)
		(layer "In11.Cu")
		(net "M_H_CPU1_SA_CB<0>")
	)
	(segment
		(start 193.301366 -280.301446)
		(end 192.56248 -281.040332)
		(width 0.18288)
		(layer "In11.Cu")
		(net "M_H_CPU1_SA_CB<0>")
	)
	(segment
		(start 133.648196 -262.548116)
		(end 133.633464 -262.556752)
		(width 0.088646)
		(layer "In11.Cu")
		(net "M_H_CPU1_SA_CB<0>")
	)
	(segment
		(start 174.36592 -281.886406)
		(end 174.04842 -281.886406)
		(width 0.18288)
		(layer "In11.Cu")
		(net "M_H_CPU1_SA_CB<0>")
	)
	(segment
		(start 177.309526 -281.041094)
		(end 176.496726 -281.041094)
		(width 0.18288)
		(layer "In11.Cu")
		(net "M_H_CPU1_SA_CB<0>")
	)
	(segment
		(start 177.6857 -280.896314)
		(end 177.309526 -281.041094)
		(width 0.18288)
		(layer "In11.Cu")
		(net "M_H_CPU1_SA_CB<0>")
	)
	(segment
		(start 124.280422 -262.058658)
		(end 123.967748 -262.058658)
		(width 0.088646)
		(layer "In11.Cu")
		(net "M_H_CPU1_SA_CB<0>")
	)
	(segment
		(start 202.814428 -279.314656)
		(end 202.541378 -279.314656)
		(width 0.18288)
		(layer "In11.Cu")
		(net "M_H_CPU1_SA_CB<0>")
	)
	(segment
		(start 168.948608 -279.92451)
		(end 167.854122 -279.331166)
		(width 0.18288)
		(layer "In11.Cu")
		(net "M_H_CPU1_SA_CB<0>")
	)
	(segment
		(start 128.009396 -262.548116)
		(end 127.994664 -262.556752)
		(width 0.088646)
		(layer "In11.Cu")
		(net "M_H_CPU1_SA_CB<0>")
	)
	(segment
		(start 170.886374 -280.852372)
		(end 170.693334 -281.045412)
		(width 0.18288)
		(layer "In11.Cu")
		(net "M_H_CPU1_SA_CB<0>")
	)
	(segment
		(start 124.345954 -262.12419)
		(end 124.280422 -262.058658)
		(width 0.088646)
		(layer "In11.Cu")
		(net "M_H_CPU1_SA_CB<0>")
	)
	(segment
		(start 201.901552 -278.435308)
		(end 201.562462 -278.435308)
		(width 0.18288)
		(layer "In11.Cu")
		(net "M_H_CPU1_SA_CB<0>")
	)
	(segment
		(start 171.079414 -280.116026)
		(end 170.886374 -280.309066)
		(width 0.18288)
		(layer "In11.Cu")
		(net "M_H_CPU1_SA_CB<0>")
	)
	(segment
		(start 188.374782 -280.190956)
		(end 187.328556 -280.190956)
		(width 0.18288)
		(layer "In11.Cu")
		(net "M_H_CPU1_SA_CB<0>")
	)
	(segment
		(start 172.305726 -280.190956)
		(end 171.696126 -280.116026)
		(width 0.18288)
		(layer "In11.Cu")
		(net "M_H_CPU1_SA_CB<0>")
	)
	(segment
		(start 136.559544 -263.705086)
		(end 136.559544 -263.686544)
		(width 0.088646)
		(layer "In11.Cu")
		(net "M_H_CPU1_SA_CB<0>")
	)
	(segment
		(start 189.116208 -280.439368)
		(end 188.374782 -280.190956)
		(width 0.18288)
		(layer "In11.Cu")
		(net "M_H_CPU1_SA_CB<0>")
	)
	(segment
		(start 130.828796 -262.548116)
		(end 130.814064 -262.556752)
		(width 0.088646)
		(layer "In11.Cu")
		(net "M_H_CPU1_SA_CB<0>")
	)
	(segment
		(start 136.380982 -263.367266)
		(end 136.372092 -263.362186)
		(width 0.088646)
		(layer "In11.Cu")
		(net "M_H_CPU1_SA_CB<0>")
	)
	(segment
		(start 169.704766 -280.116026)
		(end 168.948608 -279.92451)
		(width 0.18288)
		(layer "In11.Cu")
		(net "M_H_CPU1_SA_CB<0>")
	)
	(segment
		(start 174.752 -280.846276)
		(end 174.55896 -281.039316)
		(width 0.18288)
		(layer "In11.Cu")
		(net "M_H_CPU1_SA_CB<0>")
	)
	(segment
		(start 196.057774 -280.462736)
		(end 195.098924 -280.462736)
		(width 0.18288)
		(layer "In11.Cu")
		(net "M_H_CPU1_SA_CB<0>")
	)
	(segment
		(start 170.375834 -281.045412)
		(end 170.182794 -280.852372)
		(width 0.18288)
		(layer "In11.Cu")
		(net "M_H_CPU1_SA_CB<0>")
	)
	(segment
		(start 202.971146 -279.073102)
		(end 202.911202 -279.217882)
		(width 0.18288)
		(layer "In11.Cu")
		(net "M_H_CPU1_SA_CB<0>")
	)
	(segment
		(start 202.191366 -278.725122)
		(end 201.901552 -278.435308)
		(width 0.18288)
		(layer "In11.Cu")
		(net "M_H_CPU1_SA_CB<0>")
	)
	(segment
		(start 190.984378 -281.040332)
		(end 190.82385 -280.879804)
		(width 0.18288)
		(layer "In11.Cu")
		(net "M_H_CPU1_SA_CB<0>")
	)
	(segment
		(start 164.500306 -279.421082)
		(end 163.965128 -279.389586)
		(width 0.18288)
		(layer "In11.Cu")
		(net "M_H_CPU1_SA_CB<0>")
	)
	(segment
		(start 144.80032 -265.726672)
		(end 139.605004 -265.726672)
		(width 0.18288)
		(layer "In11.Cu")
		(net "M_H_CPU1_SA_CB<0>")
	)
	(segment
		(start 196.443854 -279.611074)
		(end 196.250814 -279.804114)
		(width 0.18288)
		(layer "In11.Cu")
		(net "M_H_CPU1_SA_CB<0>")
	)
	(segment
		(start 194.66941 -280.033222)
		(end 194.44843 -280.033222)
		(width 0.18288)
		(layer "In11.Cu")
		(net "M_H_CPU1_SA_CB<0>")
	)
	(segment
		(start 200.596754 -279.401016)
		(end 199.043798 -279.401016)
		(width 0.18288)
		(layer "In11.Cu")
		(net "M_H_CPU1_SA_CB<0>")
	)
	(arc
		(start 136.372092 -263.362186)
		(mid 136.169806 -263.163205)
		(end 136.089644 -262.891016)
		(width 0.088646)
		(layer "In11.Cu")
		(net "M_H_CPU1_SA_CB<0>")
	)
	(arc
		(start 131.203192 -262.548116)
		(mid 131.015994 -262.497973)
		(end 130.828796 -262.548116)
		(width 0.088646)
		(layer "In11.Cu")
		(net "M_H_CPU1_SA_CB<0>")
	)
	(arc
		(start 127.994664 -262.556752)
		(mid 127.718189 -262.624072)
		(end 127.443992 -262.548116)
		(width 0.088646)
		(layer "In11.Cu")
		(net "M_H_CPU1_SA_CB<0>")
	)
	(arc
		(start 128.383792 -262.548116)
		(mid 128.196594 -262.497973)
		(end 128.009396 -262.548116)
		(width 0.088646)
		(layer "In11.Cu")
		(net "M_H_CPU1_SA_CB<0>")
	)
	(arc
		(start 136.559544 -263.686544)
		(mid 136.511865 -263.503644)
		(end 136.380982 -263.367266)
		(width 0.088646)
		(layer "In11.Cu")
		(net "M_H_CPU1_SA_CB<0>")
	)
	(arc
		(start 129.874264 -262.556752)
		(mid 129.597789 -262.624072)
		(end 129.323592 -262.548116)
		(width 0.088646)
		(layer "In11.Cu")
		(net "M_H_CPU1_SA_CB<0>")
	)
	(arc
		(start 129.323592 -262.548116)
		(mid 129.136394 -262.497973)
		(end 128.949196 -262.548116)
		(width 0.088646)
		(layer "In11.Cu")
		(net "M_H_CPU1_SA_CB<0>")
	)
	(arc
		(start 133.633464 -262.556752)
		(mid 133.356989 -262.624072)
		(end 133.082792 -262.548116)
		(width 0.088646)
		(layer "In11.Cu")
		(net "M_H_CPU1_SA_CB<0>")
	)
	(arc
		(start 128.934464 -262.556752)
		(mid 128.657989 -262.624072)
		(end 128.383792 -262.548116)
		(width 0.088646)
		(layer "In11.Cu")
		(net "M_H_CPU1_SA_CB<0>")
	)
	(arc
		(start 133.082792 -262.548116)
		(mid 132.895594 -262.497973)
		(end 132.708396 -262.548116)
		(width 0.088646)
		(layer "In11.Cu")
		(net "M_H_CPU1_SA_CB<0>")
	)
	(arc
		(start 126.129796 -262.548116)
		(mid 125.853237 -262.623859)
		(end 125.57506 -262.554212)
		(width 0.088646)
		(layer "In11.Cu")
		(net "M_H_CPU1_SA_CB<0>")
	)
	(arc
		(start 134.962392 -262.548116)
		(mid 134.775194 -262.497973)
		(end 134.587996 -262.548116)
		(width 0.088646)
		(layer "In11.Cu")
		(net "M_H_CPU1_SA_CB<0>")
	)
	(arc
		(start 135.902192 -262.548116)
		(mid 135.714994 -262.497973)
		(end 135.527796 -262.548116)
		(width 0.088646)
		(layer "In11.Cu")
		(net "M_H_CPU1_SA_CB<0>")
	)
	(arc
		(start 132.708396 -262.548116)
		(mid 132.431837 -262.623859)
		(end 132.15366 -262.554212)
		(width 0.088646)
		(layer "In11.Cu")
		(net "M_H_CPU1_SA_CB<0>")
	)
	(arc
		(start 137.407396 -264.176256)
		(mid 137.124694 -264.251998)
		(end 136.841992 -264.176256)
		(width 0.088646)
		(layer "In11.Cu")
		(net "M_H_CPU1_SA_CB<0>")
	)
	(arc
		(start 134.573264 -262.556752)
		(mid 134.296789 -262.624072)
		(end 134.022592 -262.548116)
		(width 0.088646)
		(layer "In11.Cu")
		(net "M_H_CPU1_SA_CB<0>")
	)
	(arc
		(start 131.758436 -262.554212)
		(mid 131.480004 -262.624058)
		(end 131.203192 -262.548116)
		(width 0.088646)
		(layer "In11.Cu")
		(net "M_H_CPU1_SA_CB<0>")
	)
	(arc
		(start 124.624592 -262.548116)
		(mid 124.435079 -262.369151)
		(end 124.345954 -262.12419)
		(width 0.088646)
		(layer "In11.Cu")
		(net "M_H_CPU1_SA_CB<0>")
	)
	(arc
		(start 134.022592 -262.548116)
		(mid 133.835394 -262.497973)
		(end 133.648196 -262.548116)
		(width 0.088646)
		(layer "In11.Cu")
		(net "M_H_CPU1_SA_CB<0>")
	)
	(arc
		(start 135.527796 -262.548116)
		(mid 135.245094 -262.623892)
		(end 134.962392 -262.548116)
		(width 0.088646)
		(layer "In11.Cu")
		(net "M_H_CPU1_SA_CB<0>")
	)
	(arc
		(start 127.443992 -262.548116)
		(mid 127.256794 -262.497973)
		(end 127.069596 -262.548116)
		(width 0.088646)
		(layer "In11.Cu")
		(net "M_H_CPU1_SA_CB<0>")
	)
	(arc
		(start 125.564646 -262.548116)
		(mid 125.377448 -262.497973)
		(end 125.19025 -262.548116)
		(width 0.088646)
		(layer "In11.Cu")
		(net "M_H_CPU1_SA_CB<0>")
	)
	(arc
		(start 137.781792 -264.176256)
		(mid 137.594594 -264.126113)
		(end 137.407396 -264.176256)
		(width 0.088646)
		(layer "In11.Cu")
		(net "M_H_CPU1_SA_CB<0>")
	)
	(arc
		(start 132.143246 -262.548116)
		(mid 131.956048 -262.497973)
		(end 131.76885 -262.548116)
		(width 0.088646)
		(layer "In11.Cu")
		(net "M_H_CPU1_SA_CB<0>")
	)
	(arc
		(start 127.054864 -262.556752)
		(mid 126.778389 -262.624072)
		(end 126.504192 -262.548116)
		(width 0.088646)
		(layer "In11.Cu")
		(net "M_H_CPU1_SA_CB<0>")
	)
	(arc
		(start 125.179836 -262.554212)
		(mid 124.901404 -262.624058)
		(end 124.624592 -262.548116)
		(width 0.088646)
		(layer "In11.Cu")
		(net "M_H_CPU1_SA_CB<0>")
	)
	(arc
		(start 126.504192 -262.548116)
		(mid 126.316994 -262.497973)
		(end 126.129796 -262.548116)
		(width 0.088646)
		(layer "In11.Cu")
		(net "M_H_CPU1_SA_CB<0>")
	)
	(arc
		(start 136.841992 -264.176256)
		(mid 136.639706 -263.977275)
		(end 136.559544 -263.705086)
		(width 0.088646)
		(layer "In11.Cu")
		(net "M_H_CPU1_SA_CB<0>")
	)
	(arc
		(start 130.814064 -262.556752)
		(mid 130.537589 -262.624072)
		(end 130.263392 -262.548116)
		(width 0.088646)
		(layer "In11.Cu")
		(net "M_H_CPU1_SA_CB<0>")
	)
	(arc
		(start 136.089644 -262.872474)
		(mid 136.041965 -262.689574)
		(end 135.911082 -262.553196)
		(width 0.088646)
		(layer "In11.Cu")
		(net "M_H_CPU1_SA_CB<0>")
	)
	(arc
		(start 130.263392 -262.548116)
		(mid 130.076194 -262.497973)
		(end 129.888996 -262.548116)
		(width 0.088646)
		(layer "In11.Cu")
		(net "M_H_CPU1_SA_CB<0>")
	)
	(segment
		(start 206.987902 -261.49173)
		(end 207.001618 -261.49173)
		(width 0.101854)
		(layer "F.Cu")
		(net "M_H_CPU1_SA_CA<6>")
	)
	(segment
		(start 209.17408 -261.49173)
		(end 209.186526 -261.504176)
		(width 0.1016)
		(layer "F.Cu")
		(net "M_H_CPU1_SA_CA<6>")
	)
	(segment
		(start 209.186526 -261.504176)
		(end 209.602578 -261.504176)
		(width 0.20066)
		(layer "F.Cu")
		(net "M_H_CPU1_SA_CA<6>")
	)
	(segment
		(start 123.387612 -246.900192)
		(end 123.387612 -246.364506)
		(width 0.20066)
		(layer "F.Cu")
		(net "M_H_CPU1_SA_CA<6>")
	)
	(segment
		(start 210.04022 -261.066534)
		(end 211.619592 -261.066534)
		(width 0.20066)
		(layer "F.Cu")
		(net "M_H_CPU1_SA_CA<6>")
	)
	(segment
		(start 205.961234 -260.572504)
		(end 206.88046 -261.49173)
		(width 0.20066)
		(layer "F.Cu")
		(net "M_H_CPU1_SA_CA<6>")
	)
	(segment
		(start 211.619592 -261.066534)
		(end 211.619846 -261.066788)
		(width 0.20066)
		(layer "F.Cu")
		(net "M_H_CPU1_SA_CA<6>")
	)
	(segment
		(start 123.387866 -246.900446)
		(end 123.387612 -246.900192)
		(width 0.20066)
		(layer "F.Cu")
		(net "M_H_CPU1_SA_CA<6>")
	)
	(segment
		(start 209.602578 -261.504176)
		(end 210.04022 -261.066534)
		(width 0.20066)
		(layer "F.Cu")
		(net "M_H_CPU1_SA_CA<6>")
	)
	(segment
		(start 205.63586 -260.572504)
		(end 205.961234 -260.572504)
		(width 0.20066)
		(layer "F.Cu")
		(net "M_H_CPU1_SA_CA<6>")
	)
	(segment
		(start 207.001618 -261.49173)
		(end 209.17408 -261.49173)
		(width 0.1016)
		(layer "F.Cu")
		(net "M_H_CPU1_SA_CA<6>")
	)
	(segment
		(start 202.971146 -261.066788)
		(end 204.076046 -261.066788)
		(width 0.20066)
		(layer "F.Cu")
		(net "M_H_CPU1_SA_CA<6>")
	)
	(segment
		(start 205.141576 -261.066788)
		(end 205.63586 -260.572504)
		(width 0.20066)
		(layer "F.Cu")
		(net "M_H_CPU1_SA_CA<6>")
	)
	(segment
		(start 206.88046 -261.49173)
		(end 206.987902 -261.49173)
		(width 0.20066)
		(layer "F.Cu")
		(net "M_H_CPU1_SA_CA<6>")
	)
	(segment
		(start 204.076046 -261.066788)
		(end 205.141576 -261.066788)
		(width 0.20066)
		(layer "F.Cu")
		(net "M_H_CPU1_SA_CA<6>")
	)
	(segment
		(start 123.19 -246.682768)
		(end 123.200414 -246.688864)
		(width 0.088646)
		(layer "In11.Cu")
		(net "M_H_CPU1_SA_CA<6>")
	)
	(segment
		(start 198.6153 -259.067554)
		(end 194.03441 -259.067554)
		(width 0.18288)
		(layer "In11.Cu")
		(net "M_H_CPU1_SA_CA<6>")
	)
	(segment
		(start 193.258948 -258.292092)
		(end 192.760854 -258.085844)
		(width 0.18288)
		(layer "In11.Cu")
		(net "M_H_CPU1_SA_CA<6>")
	)
	(segment
		(start 158.332932 -257.323844)
		(end 156.835602 -257.323844)
		(width 0.18288)
		(layer "In11.Cu")
		(net "M_H_CPU1_SA_CA<6>")
	)
	(segment
		(start 123.622308 -246.07266)
		(end 123.544076 -246.093488)
		(width 0.088646)
		(layer "In11.Cu")
		(net "M_H_CPU1_SA_CA<6>")
	)
	(segment
		(start 154.758898 -255.24714)
		(end 152.696418 -254.392176)
		(width 0.18288)
		(layer "In11.Cu")
		(net "M_H_CPU1_SA_CA<6>")
	)
	(segment
		(start 202.971146 -260.94944)
		(end 202.880214 -260.729984)
		(width 0.18288)
		(layer "In11.Cu")
		(net "M_H_CPU1_SA_CA<6>")
	)
	(segment
		(start 156.835602 -257.323844)
		(end 154.758898 -255.24714)
		(width 0.18288)
		(layer "In11.Cu")
		(net "M_H_CPU1_SA_CA<6>")
	)
	(segment
		(start 123.544076 -246.093488)
		(end 123.387612 -246.364506)
		(width 0.088646)
		(layer "In11.Cu")
		(net "M_H_CPU1_SA_CA<6>")
	)
	(segment
		(start 142.013432 -252.786388)
		(end 124.568458 -252.786388)
		(width 0.18288)
		(layer "In11.Cu")
		(net "M_H_CPU1_SA_CA<6>")
	)
	(segment
		(start 124.255276 -252.786388)
		(end 123.762262 -252.293374)
		(width 0.088646)
		(layer "In11.Cu")
		(net "M_H_CPU1_SA_CA<6>")
	)
	(segment
		(start 200.02246 -258.940808)
		(end 198.742046 -258.940808)
		(width 0.18288)
		(layer "In11.Cu")
		(net "M_H_CPU1_SA_CA<6>")
	)
	(segment
		(start 123.762262 -252.293374)
		(end 123.762262 -249.620024)
		(width 0.088646)
		(layer "In11.Cu")
		(net "M_H_CPU1_SA_CA<6>")
	)
	(segment
		(start 202.880214 -260.729984)
		(end 201.846688 -259.696458)
		(width 0.18288)
		(layer "In11.Cu")
		(net "M_H_CPU1_SA_CA<6>")
	)
	(segment
		(start 192.760854 -258.085844)
		(end 160.54197 -258.085844)
		(width 0.18288)
		(layer "In11.Cu")
		(net "M_H_CPU1_SA_CA<6>")
	)
	(segment
		(start 123.57481 -246.688864)
		(end 123.5837 -246.683784)
		(width 0.088646)
		(layer "In11.Cu")
		(net "M_H_CPU1_SA_CA<6>")
	)
	(segment
		(start 124.568458 -252.786388)
		(end 124.255276 -252.786388)
		(width 0.088646)
		(layer "In11.Cu")
		(net "M_H_CPU1_SA_CA<6>")
	)
	(segment
		(start 122.822462 -248.01068)
		(end 122.822462 -247.992138)
		(width 0.088646)
		(layer "In11.Cu")
		(net "M_H_CPU1_SA_CA<6>")
	)
	(segment
		(start 122.352816 -247.193816)
		(end 122.352816 -247.168416)
		(width 0.088646)
		(layer "In11.Cu")
		(net "M_H_CPU1_SA_CA<6>")
	)
	(segment
		(start 160.54197 -258.085844)
		(end 158.332932 -257.323844)
		(width 0.18288)
		(layer "In11.Cu")
		(net "M_H_CPU1_SA_CA<6>")
	)
	(segment
		(start 148.730716 -254.392176)
		(end 147.859496 -255.263396)
		(width 0.18288)
		(layer "In11.Cu")
		(net "M_H_CPU1_SA_CA<6>")
	)
	(segment
		(start 194.03441 -259.067554)
		(end 193.258948 -258.292092)
		(width 0.18288)
		(layer "In11.Cu")
		(net "M_H_CPU1_SA_CA<6>")
	)
	(segment
		(start 122.6439 -247.67286)
		(end 122.63501 -247.66778)
		(width 0.088646)
		(layer "In11.Cu")
		(net "M_H_CPU1_SA_CA<6>")
	)
	(segment
		(start 123.1138 -248.48693)
		(end 123.10491 -248.48185)
		(width 0.088646)
		(layer "In11.Cu")
		(net "M_H_CPU1_SA_CA<6>")
	)
	(segment
		(start 123.57481 -249.295666)
		(end 123.568714 -249.29211)
		(width 0.088646)
		(layer "In11.Cu")
		(net "M_H_CPU1_SA_CA<6>")
	)
	(segment
		(start 147.859496 -255.263396)
		(end 144.49044 -255.263396)
		(width 0.18288)
		(layer "In11.Cu")
		(net "M_H_CPU1_SA_CA<6>")
	)
	(segment
		(start 144.49044 -255.263396)
		(end 142.013432 -252.786388)
		(width 0.18288)
		(layer "In11.Cu")
		(net "M_H_CPU1_SA_CA<6>")
	)
	(segment
		(start 201.846688 -259.696458)
		(end 200.02246 -258.940808)
		(width 0.18288)
		(layer "In11.Cu")
		(net "M_H_CPU1_SA_CA<6>")
	)
	(segment
		(start 123.5837 -249.300746)
		(end 123.57481 -249.295666)
		(width 0.088646)
		(layer "In11.Cu")
		(net "M_H_CPU1_SA_CA<6>")
	)
	(segment
		(start 152.696418 -254.392176)
		(end 148.730716 -254.392176)
		(width 0.18288)
		(layer "In11.Cu")
		(net "M_H_CPU1_SA_CA<6>")
	)
	(segment
		(start 202.971146 -261.066788)
		(end 202.971146 -260.94944)
		(width 0.18288)
		(layer "In11.Cu")
		(net "M_H_CPU1_SA_CA<6>")
	)
	(segment
		(start 198.742046 -258.940808)
		(end 198.6153 -259.067554)
		(width 0.18288)
		(layer "In11.Cu")
		(net "M_H_CPU1_SA_CA<6>")
	)
	(arc
		(start 123.5837 -246.683784)
		(mid 123.714614 -246.547424)
		(end 123.762262 -246.364506)
		(width 0.088646)
		(layer "In11.Cu")
		(net "M_H_CPU1_SA_CA<6>")
	)
	(arc
		(start 123.10491 -248.48185)
		(mid 122.902624 -248.282869)
		(end 122.822462 -248.01068)
		(width 0.088646)
		(layer "In11.Cu")
		(net "M_H_CPU1_SA_CA<6>")
	)
	(arc
		(start 123.200414 -246.688864)
		(mid 123.387612 -246.739007)
		(end 123.57481 -246.688864)
		(width 0.088646)
		(layer "In11.Cu")
		(net "M_H_CPU1_SA_CA<6>")
	)
	(arc
		(start 123.762262 -246.364506)
		(mid 123.725402 -246.202709)
		(end 123.622308 -246.07266)
		(width 0.088646)
		(layer "In11.Cu")
		(net "M_H_CPU1_SA_CA<6>")
	)
	(arc
		(start 122.63501 -247.66778)
		(mid 122.432187 -247.467549)
		(end 122.352816 -247.193816)
		(width 0.088646)
		(layer "In11.Cu")
		(net "M_H_CPU1_SA_CA<6>")
	)
	(arc
		(start 122.635264 -246.688864)
		(mid 122.911823 -246.613121)
		(end 123.19 -246.682768)
		(width 0.088646)
		(layer "In11.Cu")
		(net "M_H_CPU1_SA_CA<6>")
	)
	(arc
		(start 122.352816 -247.168416)
		(mid 122.430927 -246.891467)
		(end 122.635264 -246.688864)
		(width 0.088646)
		(layer "In11.Cu")
		(net "M_H_CPU1_SA_CA<6>")
	)
	(arc
		(start 123.292362 -248.806208)
		(mid 123.244683 -248.623308)
		(end 123.1138 -248.48693)
		(width 0.088646)
		(layer "In11.Cu")
		(net "M_H_CPU1_SA_CA<6>")
	)
	(arc
		(start 123.762262 -249.620024)
		(mid 123.714583 -249.437124)
		(end 123.5837 -249.300746)
		(width 0.088646)
		(layer "In11.Cu")
		(net "M_H_CPU1_SA_CA<6>")
	)
	(arc
		(start 123.568714 -249.29211)
		(mid 123.366301 -249.085697)
		(end 123.292362 -248.806208)
		(width 0.088646)
		(layer "In11.Cu")
		(net "M_H_CPU1_SA_CA<6>")
	)
	(arc
		(start 122.822462 -247.992138)
		(mid 122.774783 -247.809238)
		(end 122.6439 -247.67286)
		(width 0.088646)
		(layer "In11.Cu")
		(net "M_H_CPU1_SA_CA<6>")
	)
	(segment
		(start 210.603084 -262.352282)
		(end 210.613752 -262.341614)
		(width 0.1016)
		(layer "F.Cu")
		(net "M_H_CPU1_SA_CA<5>")
	)
	(segment
		(start 214.1728 -261.48411)
		(end 214.605362 -261.916672)
		(width 0.20066)
		(layer "F.Cu")
		(net "M_H_CPU1_SA_CA<5>")
	)
	(segment
		(start 210.613752 -262.341614)
		(end 212.622892 -262.341614)
		(width 0.1016)
		(layer "F.Cu")
		(net "M_H_CPU1_SA_CA<5>")
	)
	(segment
		(start 212.630258 -262.34898)
		(end 212.904324 -262.34898)
		(width 0.20066)
		(layer "F.Cu")
		(net "M_H_CPU1_SA_CA<5>")
	)
	(segment
		(start 210.598258 -262.352282)
		(end 210.603084 -262.352282)
		(width 0.101854)
		(layer "F.Cu")
		(net "M_H_CPU1_SA_CA<5>")
	)
	(segment
		(start 124.907294 -253.383796)
		(end 124.907294 -253.919482)
		(width 0.20066)
		(layer "F.Cu")
		(net "M_H_CPU1_SA_CA<5>")
	)
	(segment
		(start 210.247484 -262.352282)
		(end 210.598258 -262.352282)
		(width 0.20066)
		(layer "F.Cu")
		(net "M_H_CPU1_SA_CA<5>")
	)
	(segment
		(start 207.071214 -261.916672)
		(end 208.176114 -261.916672)
		(width 0.20066)
		(layer "F.Cu")
		(net "M_H_CPU1_SA_CA<5>")
	)
	(segment
		(start 208.176114 -261.916672)
		(end 209.811874 -261.916672)
		(width 0.20066)
		(layer "F.Cu")
		(net "M_H_CPU1_SA_CA<5>")
	)
	(segment
		(start 124.907294 -253.919482)
		(end 124.907548 -253.919736)
		(width 0.20066)
		(layer "F.Cu")
		(net "M_H_CPU1_SA_CA<5>")
	)
	(segment
		(start 212.904324 -262.34898)
		(end 213.769194 -261.48411)
		(width 0.20066)
		(layer "F.Cu")
		(net "M_H_CPU1_SA_CA<5>")
	)
	(segment
		(start 213.769194 -261.48411)
		(end 214.1728 -261.48411)
		(width 0.20066)
		(layer "F.Cu")
		(net "M_H_CPU1_SA_CA<5>")
	)
	(segment
		(start 212.622892 -262.341614)
		(end 212.630258 -262.34898)
		(width 0.1016)
		(layer "F.Cu")
		(net "M_H_CPU1_SA_CA<5>")
	)
	(segment
		(start 214.605362 -261.916672)
		(end 215.719914 -261.916672)
		(width 0.20066)
		(layer "F.Cu")
		(net "M_H_CPU1_SA_CA<5>")
	)
	(segment
		(start 209.811874 -261.916672)
		(end 210.247484 -262.352282)
		(width 0.20066)
		(layer "F.Cu")
		(net "M_H_CPU1_SA_CA<5>")
	)
	(segment
		(start 148.996908 -254.914146)
		(end 148.29409 -255.616964)
		(width 0.18288)
		(layer "In11.Cu")
		(net "M_H_CPU1_SA_CA<5>")
	)
	(segment
		(start 158.742888 -258.158488)
		(end 158.361634 -257.950462)
		(width 0.18288)
		(layer "In11.Cu")
		(net "M_H_CPU1_SA_CA<5>")
	)
	(segment
		(start 183.510682 -259.166106)
		(end 178.510946 -259.166106)
		(width 0.18288)
		(layer "In11.Cu")
		(net "M_H_CPU1_SA_CA<5>")
	)
	(segment
		(start 175.573182 -259.076698)
		(end 173.745144 -259.076698)
		(width 0.18288)
		(layer "In11.Cu")
		(net "M_H_CPU1_SA_CA<5>")
	)
	(segment
		(start 202.889358 -261.492492)
		(end 202.887834 -261.490968)
		(width 0.18288)
		(layer "In11.Cu")
		(net "M_H_CPU1_SA_CA<5>")
	)
	(segment
		(start 202.286616 -260.946392)
		(end 201.979022 -260.638798)
		(width 0.18288)
		(layer "In11.Cu")
		(net "M_H_CPU1_SA_CA<5>")
	)
	(segment
		(start 125.382528 -253.138686)
		(end 124.907548 -253.614174)
		(width 0.18288)
		(layer "In11.Cu")
		(net "M_H_CPU1_SA_CA<5>")
	)
	(segment
		(start 176.851818 -258.94157)
		(end 175.70831 -258.94157)
		(width 0.18288)
		(layer "In11.Cu")
		(net "M_H_CPU1_SA_CA<5>")
	)
	(segment
		(start 198.920354 -260.638798)
		(end 198.020686 -259.73913)
		(width 0.18288)
		(layer "In11.Cu")
		(net "M_H_CPU1_SA_CA<5>")
	)
	(segment
		(start 156.663644 -257.950462)
		(end 154.358086 -255.663954)
		(width 0.18288)
		(layer "In11.Cu")
		(net "M_H_CPU1_SA_CA<5>")
	)
	(segment
		(start 188.628782 -258.941062)
		(end 187.347098 -258.941062)
		(width 0.18288)
		(layer "In11.Cu")
		(net "M_H_CPU1_SA_CA<5>")
	)
	(segment
		(start 192.748154 -258.941062)
		(end 191.48679 -258.941062)
		(width 0.18288)
		(layer "In11.Cu")
		(net "M_H_CPU1_SA_CA<5>")
	)
	(segment
		(start 193.546222 -259.73913)
		(end 192.748154 -258.941062)
		(width 0.18288)
		(layer "In11.Cu")
		(net "M_H_CPU1_SA_CA<5>")
	)
	(segment
		(start 188.807598 -259.119878)
		(end 188.628782 -258.941062)
		(width 0.18288)
		(layer "In11.Cu")
		(net "M_H_CPU1_SA_CA<5>")
	)
	(segment
		(start 172.188632 -258.94157)
		(end 172.04182 -259.088382)
		(width 0.18288)
		(layer "In11.Cu")
		(net "M_H_CPU1_SA_CA<5>")
	)
	(segment
		(start 141.87043 -253.138686)
		(end 125.382528 -253.138686)
		(width 0.18288)
		(layer "In11.Cu")
		(net "M_H_CPU1_SA_CA<5>")
	)
	(segment
		(start 201.979022 -260.638798)
		(end 198.920354 -260.638798)
		(width 0.18288)
		(layer "In11.Cu")
		(net "M_H_CPU1_SA_CA<5>")
	)
	(segment
		(start 176.85258 -258.940808)
		(end 176.851818 -258.94157)
		(width 0.18288)
		(layer "In11.Cu")
		(net "M_H_CPU1_SA_CA<5>")
	)
	(segment
		(start 206.295752 -261.142226)
		(end 203.618592 -261.142226)
		(width 0.18288)
		(layer "In11.Cu")
		(net "M_H_CPU1_SA_CA<5>")
	)
	(segment
		(start 144.348708 -255.616964)
		(end 141.87043 -253.138686)
		(width 0.18288)
		(layer "In11.Cu")
		(net "M_H_CPU1_SA_CA<5>")
	)
	(segment
		(start 202.887834 -261.490968)
		(end 202.615292 -261.490968)
		(width 0.18288)
		(layer "In11.Cu")
		(net "M_H_CPU1_SA_CA<5>")
	)
	(segment
		(start 172.746416 -258.94157)
		(end 172.188632 -258.94157)
		(width 0.18288)
		(layer "In11.Cu")
		(net "M_H_CPU1_SA_CA<5>")
	)
	(segment
		(start 173.609254 -258.940808)
		(end 172.747178 -258.940808)
		(width 0.18288)
		(layer "In11.Cu")
		(net "M_H_CPU1_SA_CA<5>")
	)
	(segment
		(start 191.48679 -258.941062)
		(end 191.307974 -259.119878)
		(width 0.18288)
		(layer "In11.Cu")
		(net "M_H_CPU1_SA_CA<5>")
	)
	(segment
		(start 172.04182 -259.088382)
		(end 159.672782 -259.088382)
		(width 0.18288)
		(layer "In11.Cu")
		(net "M_H_CPU1_SA_CA<5>")
	)
	(segment
		(start 148.29409 -255.616964)
		(end 144.348708 -255.616964)
		(width 0.18288)
		(layer "In11.Cu")
		(net "M_H_CPU1_SA_CA<5>")
	)
	(segment
		(start 173.745144 -259.076698)
		(end 173.609254 -258.940808)
		(width 0.18288)
		(layer "In11.Cu")
		(net "M_H_CPU1_SA_CA<5>")
	)
	(segment
		(start 183.735726 -258.941062)
		(end 183.510682 -259.166106)
		(width 0.18288)
		(layer "In11.Cu")
		(net "M_H_CPU1_SA_CA<5>")
	)
	(segment
		(start 191.307974 -259.119878)
		(end 188.807598 -259.119878)
		(width 0.18288)
		(layer "In11.Cu")
		(net "M_H_CPU1_SA_CA<5>")
	)
	(segment
		(start 202.615292 -261.490968)
		(end 202.286616 -261.162292)
		(width 0.18288)
		(layer "In11.Cu")
		(net "M_H_CPU1_SA_CA<5>")
	)
	(segment
		(start 187.175394 -259.112766)
		(end 185.287158 -259.112766)
		(width 0.18288)
		(layer "In11.Cu")
		(net "M_H_CPU1_SA_CA<5>")
	)
	(segment
		(start 124.907548 -253.614174)
		(end 124.907548 -253.919736)
		(width 0.18288)
		(layer "In11.Cu")
		(net "M_H_CPU1_SA_CA<5>")
	)
	(segment
		(start 172.747178 -258.940808)
		(end 172.746416 -258.94157)
		(width 0.18288)
		(layer "In11.Cu")
		(net "M_H_CPU1_SA_CA<5>")
	)
	(segment
		(start 178.510946 -259.166106)
		(end 178.285648 -258.940808)
		(width 0.18288)
		(layer "In11.Cu")
		(net "M_H_CPU1_SA_CA<5>")
	)
	(segment
		(start 185.287158 -259.112766)
		(end 185.115454 -258.941062)
		(width 0.18288)
		(layer "In11.Cu")
		(net "M_H_CPU1_SA_CA<5>")
	)
	(segment
		(start 175.70831 -258.94157)
		(end 175.573182 -259.076698)
		(width 0.18288)
		(layer "In11.Cu")
		(net "M_H_CPU1_SA_CA<5>")
	)
	(segment
		(start 187.347098 -258.941062)
		(end 187.175394 -259.112766)
		(width 0.18288)
		(layer "In11.Cu")
		(net "M_H_CPU1_SA_CA<5>")
	)
	(segment
		(start 178.285648 -258.940808)
		(end 176.85258 -258.940808)
		(width 0.18288)
		(layer "In11.Cu")
		(net "M_H_CPU1_SA_CA<5>")
	)
	(segment
		(start 159.672782 -259.088382)
		(end 158.742888 -258.158488)
		(width 0.18288)
		(layer "In11.Cu")
		(net "M_H_CPU1_SA_CA<5>")
	)
	(segment
		(start 158.361634 -257.950462)
		(end 156.663644 -257.950462)
		(width 0.18288)
		(layer "In11.Cu")
		(net "M_H_CPU1_SA_CA<5>")
	)
	(segment
		(start 203.618592 -261.142226)
		(end 203.268326 -261.492492)
		(width 0.18288)
		(layer "In11.Cu")
		(net "M_H_CPU1_SA_CA<5>")
	)
	(segment
		(start 154.358086 -255.663954)
		(end 152.539954 -254.914146)
		(width 0.18288)
		(layer "In11.Cu")
		(net "M_H_CPU1_SA_CA<5>")
	)
	(segment
		(start 207.071214 -261.916672)
		(end 206.295752 -261.142226)
		(width 0.18288)
		(layer "In11.Cu")
		(net "M_H_CPU1_SA_CA<5>")
	)
	(segment
		(start 203.268326 -261.492492)
		(end 202.889358 -261.492492)
		(width 0.18288)
		(layer "In11.Cu")
		(net "M_H_CPU1_SA_CA<5>")
	)
	(segment
		(start 198.020686 -259.73913)
		(end 193.546222 -259.73913)
		(width 0.18288)
		(layer "In11.Cu")
		(net "M_H_CPU1_SA_CA<5>")
	)
	(segment
		(start 185.115454 -258.941062)
		(end 183.735726 -258.941062)
		(width 0.18288)
		(layer "In11.Cu")
		(net "M_H_CPU1_SA_CA<5>")
	)
	(segment
		(start 152.539954 -254.914146)
		(end 148.996908 -254.914146)
		(width 0.18288)
		(layer "In11.Cu")
		(net "M_H_CPU1_SA_CA<5>")
	)
	(segment
		(start 202.286616 -261.162292)
		(end 202.286616 -260.946392)
		(width 0.18288)
		(layer "In11.Cu")
		(net "M_H_CPU1_SA_CA<5>")
	)
	(segment
		(start 204.076046 -262.76681)
		(end 205.141576 -262.76681)
		(width 0.20066)
		(layer "F.Cu")
		(net "M_H_CPU1_SA_CA<4>")
	)
	(segment
		(start 123.967494 -253.919482)
		(end 123.967748 -253.919736)
		(width 0.20066)
		(layer "F.Cu")
		(net "M_H_CPU1_SA_CA<4>")
	)
	(segment
		(start 205.141576 -262.76681)
		(end 205.63586 -262.272526)
		(width 0.20066)
		(layer "F.Cu")
		(net "M_H_CPU1_SA_CA<4>")
	)
	(segment
		(start 211.619592 -262.766556)
		(end 211.619846 -262.76681)
		(width 0.20066)
		(layer "F.Cu")
		(net "M_H_CPU1_SA_CA<4>")
	)
	(segment
		(start 202.971146 -262.76681)
		(end 204.076046 -262.76681)
		(width 0.20066)
		(layer "F.Cu")
		(net "M_H_CPU1_SA_CA<4>")
	)
	(segment
		(start 123.967494 -253.383796)
		(end 123.967494 -253.919482)
		(width 0.20066)
		(layer "F.Cu")
		(net "M_H_CPU1_SA_CA<4>")
	)
	(segment
		(start 209.602578 -263.204198)
		(end 210.04022 -262.766556)
		(width 0.20066)
		(layer "F.Cu")
		(net "M_H_CPU1_SA_CA<4>")
	)
	(segment
		(start 210.04022 -262.766556)
		(end 211.619592 -262.766556)
		(width 0.20066)
		(layer "F.Cu")
		(net "M_H_CPU1_SA_CA<4>")
	)
	(segment
		(start 207.001618 -263.191752)
		(end 209.17408 -263.191752)
		(width 0.1016)
		(layer "F.Cu")
		(net "M_H_CPU1_SA_CA<4>")
	)
	(segment
		(start 209.186526 -263.204198)
		(end 209.602578 -263.204198)
		(width 0.20066)
		(layer "F.Cu")
		(net "M_H_CPU1_SA_CA<4>")
	)
	(segment
		(start 205.961234 -262.272526)
		(end 206.88046 -263.191752)
		(width 0.20066)
		(layer "F.Cu")
		(net "M_H_CPU1_SA_CA<4>")
	)
	(segment
		(start 206.987902 -263.191752)
		(end 207.001618 -263.191752)
		(width 0.101854)
		(layer "F.Cu")
		(net "M_H_CPU1_SA_CA<4>")
	)
	(segment
		(start 205.63586 -262.272526)
		(end 205.961234 -262.272526)
		(width 0.20066)
		(layer "F.Cu")
		(net "M_H_CPU1_SA_CA<4>")
	)
	(segment
		(start 209.17408 -263.191752)
		(end 209.186526 -263.204198)
		(width 0.1016)
		(layer "F.Cu")
		(net "M_H_CPU1_SA_CA<4>")
	)
	(segment
		(start 206.88046 -263.191752)
		(end 206.987902 -263.191752)
		(width 0.20066)
		(layer "F.Cu")
		(net "M_H_CPU1_SA_CA<4>")
	)
	(segment
		(start 181.146196 -260.679946)
		(end 180.953156 -260.872986)
		(width 0.18288)
		(layer "In11.Cu")
		(net "M_H_CPU1_SA_CA<4>")
	)
	(segment
		(start 177.796444 -259.864352)
		(end 177.796444 -260.338062)
		(width 0.18288)
		(layer "In11.Cu")
		(net "M_H_CPU1_SA_CA<4>")
	)
	(segment
		(start 194.64274 -260.440932)
		(end 192.860168 -260.440932)
		(width 0.18288)
		(layer "In11.Cu")
		(net "M_H_CPU1_SA_CA<4>")
	)
	(segment
		(start 200.584054 -261.517892)
		(end 199.020938 -261.517892)
		(width 0.18288)
		(layer "In11.Cu")
		(net "M_H_CPU1_SA_CA<4>")
	)
	(segment
		(start 149.342602 -255.432306)
		(end 148.81225 -255.962658)
		(width 0.18288)
		(layer "In11.Cu")
		(net "M_H_CPU1_SA_CA<4>")
	)
	(segment
		(start 156.946346 -258.99999)
		(end 154.050238 -256.103882)
		(width 0.18288)
		(layer "In11.Cu")
		(net "M_H_CPU1_SA_CA<4>")
	)
	(segment
		(start 178.500024 -259.864352)
		(end 178.306984 -259.671312)
		(width 0.18288)
		(layer "In11.Cu")
		(net "M_H_CPU1_SA_CA<4>")
	)
	(segment
		(start 181.849776 -260.679946)
		(end 181.849776 -259.970524)
		(width 0.18288)
		(layer "In11.Cu")
		(net "M_H_CPU1_SA_CA<4>")
	)
	(segment
		(start 178.500024 -260.338062)
		(end 178.500024 -259.864352)
		(width 0.18288)
		(layer "In11.Cu")
		(net "M_H_CPU1_SA_CA<4>")
	)
	(segment
		(start 152.428956 -255.432306)
		(end 149.342602 -255.432306)
		(width 0.18288)
		(layer "In11.Cu")
		(net "M_H_CPU1_SA_CA<4>")
	)
	(segment
		(start 183.925464 -260.641084)
		(end 183.693562 -260.872986)
		(width 0.18288)
		(layer "In11.Cu")
		(net "M_H_CPU1_SA_CA<4>")
	)
	(segment
		(start 125.426724 -253.68377)
		(end 125.426724 -253.83363)
		(width 0.18288)
		(layer "In11.Cu")
		(net "M_H_CPU1_SA_CA<4>")
	)
	(segment
		(start 195.011294 -260.809486)
		(end 194.64274 -260.440932)
		(width 0.18288)
		(layer "In11.Cu")
		(net "M_H_CPU1_SA_CA<4>")
	)
	(segment
		(start 183.693562 -260.872986)
		(end 182.042816 -260.872986)
		(width 0.18288)
		(layer "In11.Cu")
		(net "M_H_CPU1_SA_CA<4>")
	)
	(segment
		(start 125.619764 -253.49073)
		(end 125.426724 -253.68377)
		(width 0.18288)
		(layer "In11.Cu")
		(net "M_H_CPU1_SA_CA<4>")
	)
	(segment
		(start 125.314964 -254.313436)
		(end 124.420884 -254.313436)
		(width 0.088646)
		(layer "In11.Cu")
		(net "M_H_CPU1_SA_CA<4>")
	)
	(segment
		(start 181.339236 -259.777484)
		(end 181.146196 -259.970524)
		(width 0.18288)
		(layer "In11.Cu")
		(net "M_H_CPU1_SA_CA<4>")
	)
	(segment
		(start 202.971146 -262.76681)
		(end 202.971146 -262.63219)
		(width 0.18288)
		(layer "In11.Cu")
		(net "M_H_CPU1_SA_CA<4>")
	)
	(segment
		(start 177.118772 -260.64083)
		(end 176.489614 -260.64083)
		(width 0.18288)
		(layer "In11.Cu")
		(net "M_H_CPU1_SA_CA<4>")
	)
	(segment
		(start 181.849776 -259.970524)
		(end 181.656736 -259.777484)
		(width 0.18288)
		(layer "In11.Cu")
		(net "M_H_CPU1_SA_CA<4>")
	)
	(segment
		(start 173.801024 -259.61594)
		(end 173.626018 -259.790946)
		(width 0.18288)
		(layer "In11.Cu")
		(net "M_H_CPU1_SA_CA<4>")
	)
	(segment
		(start 188.788802 -259.635752)
		(end 188.633608 -259.790946)
		(width 0.18288)
		(layer "In11.Cu")
		(net "M_H_CPU1_SA_CA<4>")
	)
	(segment
		(start 177.603404 -260.531102)
		(end 177.2285 -260.531102)
		(width 0.18288)
		(layer "In11.Cu")
		(net "M_H_CPU1_SA_CA<4>")
	)
	(segment
		(start 144.195038 -255.962658)
		(end 141.72311 -253.49073)
		(width 0.18288)
		(layer "In11.Cu")
		(net "M_H_CPU1_SA_CA<4>")
	)
	(segment
		(start 202.494388 -262.089138)
		(end 201.1553 -262.089138)
		(width 0.18288)
		(layer "In11.Cu")
		(net "M_H_CPU1_SA_CA<4>")
	)
	(segment
		(start 175.464724 -259.61594)
		(end 173.801024 -259.61594)
		(width 0.18288)
		(layer "In11.Cu")
		(net "M_H_CPU1_SA_CA<4>")
	)
	(segment
		(start 125.426724 -254.201676)
		(end 125.314964 -254.313436)
		(width 0.088646)
		(layer "In11.Cu")
		(net "M_H_CPU1_SA_CA<4>")
	)
	(segment
		(start 192.66027 -260.64083)
		(end 191.718438 -260.64083)
		(width 0.18288)
		(layer "In11.Cu")
		(net "M_H_CPU1_SA_CA<4>")
	)
	(segment
		(start 159.46755 -259.64515)
		(end 158.82239 -258.99999)
		(width 0.18288)
		(layer "In11.Cu")
		(net "M_H_CPU1_SA_CA<4>")
	)
	(segment
		(start 182.042816 -260.872986)
		(end 181.849776 -260.679946)
		(width 0.18288)
		(layer "In11.Cu")
		(net "M_H_CPU1_SA_CA<4>")
	)
	(segment
		(start 172.288962 -259.790946)
		(end 172.143166 -259.64515)
		(width 0.18288)
		(layer "In11.Cu")
		(net "M_H_CPU1_SA_CA<4>")
	)
	(segment
		(start 202.924156 -262.518906)
		(end 202.494388 -262.089138)
		(width 0.18288)
		(layer "In11.Cu")
		(net "M_H_CPU1_SA_CA<4>")
	)
	(segment
		(start 202.971146 -262.63219)
		(end 202.924156 -262.518906)
		(width 0.18288)
		(layer "In11.Cu")
		(net "M_H_CPU1_SA_CA<4>")
	)
	(segment
		(start 177.989484 -259.671312)
		(end 177.796444 -259.864352)
		(width 0.18288)
		(layer "In11.Cu")
		(net "M_H_CPU1_SA_CA<4>")
	)
	(segment
		(start 201.1553 -262.089138)
		(end 200.584054 -261.517892)
		(width 0.18288)
		(layer "In11.Cu")
		(net "M_H_CPU1_SA_CA<4>")
	)
	(segment
		(start 176.489614 -260.64083)
		(end 175.464724 -259.61594)
		(width 0.18288)
		(layer "In11.Cu")
		(net "M_H_CPU1_SA_CA<4>")
	)
	(segment
		(start 199.020938 -261.517892)
		(end 198.312532 -260.809486)
		(width 0.18288)
		(layer "In11.Cu")
		(net "M_H_CPU1_SA_CA<4>")
	)
	(segment
		(start 154.050238 -256.103882)
		(end 152.428956 -255.432306)
		(width 0.18288)
		(layer "In11.Cu")
		(net "M_H_CPU1_SA_CA<4>")
	)
	(segment
		(start 141.72311 -253.49073)
		(end 125.619764 -253.49073)
		(width 0.18288)
		(layer "In11.Cu")
		(net "M_H_CPU1_SA_CA<4>")
	)
	(segment
		(start 177.796444 -260.338062)
		(end 177.603404 -260.531102)
		(width 0.18288)
		(layer "In11.Cu")
		(net "M_H_CPU1_SA_CA<4>")
	)
	(segment
		(start 186.12231 -259.790946)
		(end 185.272172 -260.641084)
		(width 0.18288)
		(layer "In11.Cu")
		(net "M_H_CPU1_SA_CA<4>")
	)
	(segment
		(start 173.626018 -259.790946)
		(end 172.288962 -259.790946)
		(width 0.18288)
		(layer "In11.Cu")
		(net "M_H_CPU1_SA_CA<4>")
	)
	(segment
		(start 172.143166 -259.64515)
		(end 159.46755 -259.64515)
		(width 0.18288)
		(layer "In11.Cu")
		(net "M_H_CPU1_SA_CA<4>")
	)
	(segment
		(start 198.312532 -260.809486)
		(end 195.011294 -260.809486)
		(width 0.18288)
		(layer "In11.Cu")
		(net "M_H_CPU1_SA_CA<4>")
	)
	(segment
		(start 179.687982 -260.531102)
		(end 178.693064 -260.531102)
		(width 0.18288)
		(layer "In11.Cu")
		(net "M_H_CPU1_SA_CA<4>")
	)
	(segment
		(start 181.656736 -259.777484)
		(end 181.339236 -259.777484)
		(width 0.18288)
		(layer "In11.Cu")
		(net "M_H_CPU1_SA_CA<4>")
	)
	(segment
		(start 148.81225 -255.962658)
		(end 144.195038 -255.962658)
		(width 0.18288)
		(layer "In11.Cu")
		(net "M_H_CPU1_SA_CA<4>")
	)
	(segment
		(start 125.426724 -253.83363)
		(end 125.426724 -254.201676)
		(width 0.088646)
		(layer "In11.Cu")
		(net "M_H_CPU1_SA_CA<4>")
	)
	(segment
		(start 191.718438 -260.64083)
		(end 190.71336 -259.635752)
		(width 0.18288)
		(layer "In11.Cu")
		(net "M_H_CPU1_SA_CA<4>")
	)
	(segment
		(start 178.693064 -260.531102)
		(end 178.500024 -260.338062)
		(width 0.18288)
		(layer "In11.Cu")
		(net "M_H_CPU1_SA_CA<4>")
	)
	(segment
		(start 180.029866 -260.872986)
		(end 179.687982 -260.531102)
		(width 0.18288)
		(layer "In11.Cu")
		(net "M_H_CPU1_SA_CA<4>")
	)
	(segment
		(start 192.860168 -260.440932)
		(end 192.66027 -260.64083)
		(width 0.18288)
		(layer "In11.Cu")
		(net "M_H_CPU1_SA_CA<4>")
	)
	(segment
		(start 158.82239 -258.99999)
		(end 156.946346 -258.99999)
		(width 0.18288)
		(layer "In11.Cu")
		(net "M_H_CPU1_SA_CA<4>")
	)
	(segment
		(start 185.272172 -260.641084)
		(end 183.925464 -260.641084)
		(width 0.18288)
		(layer "In11.Cu")
		(net "M_H_CPU1_SA_CA<4>")
	)
	(segment
		(start 124.420884 -254.313436)
		(end 124.027184 -253.919736)
		(width 0.088646)
		(layer "In11.Cu")
		(net "M_H_CPU1_SA_CA<4>")
	)
	(segment
		(start 180.953156 -260.872986)
		(end 180.029866 -260.872986)
		(width 0.18288)
		(layer "In11.Cu")
		(net "M_H_CPU1_SA_CA<4>")
	)
	(segment
		(start 177.2285 -260.531102)
		(end 177.118772 -260.64083)
		(width 0.18288)
		(layer "In11.Cu")
		(net "M_H_CPU1_SA_CA<4>")
	)
	(segment
		(start 188.633608 -259.790946)
		(end 186.12231 -259.790946)
		(width 0.18288)
		(layer "In11.Cu")
		(net "M_H_CPU1_SA_CA<4>")
	)
	(segment
		(start 178.306984 -259.671312)
		(end 177.989484 -259.671312)
		(width 0.18288)
		(layer "In11.Cu")
		(net "M_H_CPU1_SA_CA<4>")
	)
	(segment
		(start 181.146196 -259.970524)
		(end 181.146196 -260.679946)
		(width 0.18288)
		(layer "In11.Cu")
		(net "M_H_CPU1_SA_CA<4>")
	)
	(segment
		(start 124.027184 -253.919736)
		(end 123.967748 -253.919736)
		(width 0.088646)
		(layer "In11.Cu")
		(net "M_H_CPU1_SA_CA<4>")
	)
	(segment
		(start 190.71336 -259.635752)
		(end 188.788802 -259.635752)
		(width 0.18288)
		(layer "In11.Cu")
		(net "M_H_CPU1_SA_CA<4>")
	)
	(segment
		(start 208.176114 -263.616694)
		(end 209.811874 -263.616694)
		(width 0.20066)
		(layer "F.Cu")
		(net "M_H_CPU1_SA_CA<3>")
	)
	(segment
		(start 212.904324 -264.049002)
		(end 213.769194 -263.184132)
		(width 0.20066)
		(layer "F.Cu")
		(net "M_H_CPU1_SA_CA<3>")
	)
	(segment
		(start 125.377448 -254.733298)
		(end 125.377194 -254.733552)
		(width 0.20066)
		(layer "F.Cu")
		(net "M_H_CPU1_SA_CA<3>")
	)
	(segment
		(start 210.603084 -264.052304)
		(end 210.613752 -264.041636)
		(width 0.1016)
		(layer "F.Cu")
		(net "M_H_CPU1_SA_CA<3>")
	)
	(segment
		(start 212.630258 -264.049002)
		(end 212.904324 -264.049002)
		(width 0.20066)
		(layer "F.Cu")
		(net "M_H_CPU1_SA_CA<3>")
	)
	(segment
		(start 210.247484 -264.052304)
		(end 210.598258 -264.052304)
		(width 0.20066)
		(layer "F.Cu")
		(net "M_H_CPU1_SA_CA<3>")
	)
	(segment
		(start 214.605362 -263.616694)
		(end 215.719914 -263.616694)
		(width 0.20066)
		(layer "F.Cu")
		(net "M_H_CPU1_SA_CA<3>")
	)
	(segment
		(start 213.769194 -263.184132)
		(end 214.1728 -263.184132)
		(width 0.20066)
		(layer "F.Cu")
		(net "M_H_CPU1_SA_CA<3>")
	)
	(segment
		(start 210.598258 -264.052304)
		(end 210.603084 -264.052304)
		(width 0.101854)
		(layer "F.Cu")
		(net "M_H_CPU1_SA_CA<3>")
	)
	(segment
		(start 209.811874 -263.616694)
		(end 210.247484 -264.052304)
		(width 0.20066)
		(layer "F.Cu")
		(net "M_H_CPU1_SA_CA<3>")
	)
	(segment
		(start 125.377448 -254.197612)
		(end 125.377448 -254.733298)
		(width 0.20066)
		(layer "F.Cu")
		(net "M_H_CPU1_SA_CA<3>")
	)
	(segment
		(start 214.1728 -263.184132)
		(end 214.605362 -263.616694)
		(width 0.20066)
		(layer "F.Cu")
		(net "M_H_CPU1_SA_CA<3>")
	)
	(segment
		(start 212.622892 -264.041636)
		(end 212.630258 -264.049002)
		(width 0.1016)
		(layer "F.Cu")
		(net "M_H_CPU1_SA_CA<3>")
	)
	(segment
		(start 210.613752 -264.041636)
		(end 212.622892 -264.041636)
		(width 0.1016)
		(layer "F.Cu")
		(net "M_H_CPU1_SA_CA<3>")
	)
	(segment
		(start 207.071214 -263.616694)
		(end 208.176114 -263.616694)
		(width 0.20066)
		(layer "F.Cu")
		(net "M_H_CPU1_SA_CA<3>")
	)
	(segment
		(start 179.608734 -261.681976)
		(end 178.025298 -261.681976)
		(width 0.18288)
		(layer "In11.Cu")
		(net "M_H_CPU1_SA_CA<3>")
	)
	(segment
		(start 132.247132 -254.24892)
		(end 132.23875 -254.244094)
		(width 0.088646)
		(layer "In11.Cu")
		(net "M_H_CPU1_SA_CA<3>")
	)
	(segment
		(start 187.277248 -260.64083)
		(end 187.152026 -260.515608)
		(width 0.18288)
		(layer "In11.Cu")
		(net "M_H_CPU1_SA_CA<3>")
	)
	(segment
		(start 153.698448 -256.53365)
		(end 152.289002 -255.950212)
		(width 0.18288)
		(layer "In11.Cu")
		(net "M_H_CPU1_SA_CA<3>")
	)
	(segment
		(start 202.527408 -263.322816)
		(end 201.269346 -263.322816)
		(width 0.18288)
		(layer "In11.Cu")
		(net "M_H_CPU1_SA_CA<3>")
	)
	(segment
		(start 198.828406 -262.21182)
		(end 197.940422 -261.323836)
		(width 0.18288)
		(layer "In11.Cu")
		(net "M_H_CPU1_SA_CA<3>")
	)
	(segment
		(start 176.502568 -261.490968)
		(end 175.81626 -260.80466)
		(width 0.18288)
		(layer "In11.Cu")
		(net "M_H_CPU1_SA_CA<3>")
	)
	(segment
		(start 132.23875 -254.244094)
		(end 132.224018 -254.235458)
		(width 0.088646)
		(layer "In11.Cu")
		(net "M_H_CPU1_SA_CA<3>")
	)
	(segment
		(start 125.418088 -254.733552)
		(end 125.377194 -254.733552)
		(width 0.088646)
		(layer "In11.Cu")
		(net "M_H_CPU1_SA_CA<3>")
	)
	(segment
		(start 185.123836 -261.522718)
		(end 183.320436 -261.522718)
		(width 0.18288)
		(layer "In11.Cu")
		(net "M_H_CPU1_SA_CA<3>")
	)
	(segment
		(start 168.959784 -260.727444)
		(end 164.751512 -260.727444)
		(width 0.18288)
		(layer "In11.Cu")
		(net "M_H_CPU1_SA_CA<3>")
	)
	(segment
		(start 129.803906 -254.237998)
		(end 129.793492 -254.244094)
		(width 0.088646)
		(layer "In11.Cu")
		(net "M_H_CPU1_SA_CA<3>")
	)
	(segment
		(start 173.777656 -260.80466)
		(end 173.613826 -260.64083)
		(width 0.18288)
		(layer "In11.Cu")
		(net "M_H_CPU1_SA_CA<3>")
	)
	(segment
		(start 191.590168 -261.490968)
		(end 190.869062 -260.769862)
		(width 0.18288)
		(layer "In11.Cu")
		(net "M_H_CPU1_SA_CA<3>")
	)
	(segment
		(start 204.144118 -262.847074)
		(end 203.798932 -263.19226)
		(width 0.18288)
		(layer "In11.Cu")
		(net "M_H_CPU1_SA_CA<3>")
	)
	(segment
		(start 175.81626 -260.80466)
		(end 173.777656 -260.80466)
		(width 0.18288)
		(layer "In11.Cu")
		(net "M_H_CPU1_SA_CA<3>")
	)
	(segment
		(start 133.567678 -254.235458)
		(end 133.552946 -254.244094)
		(width 0.088646)
		(layer "In11.Cu")
		(net "M_H_CPU1_SA_CA<3>")
	)
	(segment
		(start 193.72072 -261.677658)
		(end 193.53403 -261.490968)
		(width 0.18288)
		(layer "In11.Cu")
		(net "M_H_CPU1_SA_CA<3>")
	)
	(segment
		(start 188.778642 -260.64083)
		(end 187.277248 -260.64083)
		(width 0.18288)
		(layer "In11.Cu")
		(net "M_H_CPU1_SA_CA<3>")
	)
	(segment
		(start 144.048734 -256.32029)
		(end 142.144242 -254.415798)
		(width 0.18288)
		(layer "In11.Cu")
		(net "M_H_CPU1_SA_CA<3>")
	)
	(segment
		(start 171.85894 -260.234684)
		(end 169.452544 -260.234684)
		(width 0.18288)
		(layer "In11.Cu")
		(net "M_H_CPU1_SA_CA<3>")
	)
	(segment
		(start 200.15835 -262.21182)
		(end 198.828406 -262.21182)
		(width 0.18288)
		(layer "In11.Cu")
		(net "M_H_CPU1_SA_CA<3>")
	)
	(segment
		(start 126.989078 -254.235458)
		(end 126.9746 -254.244094)
		(width 0.088646)
		(layer "In11.Cu")
		(net "M_H_CPU1_SA_CA<3>")
	)
	(segment
		(start 149.568916 -255.950212)
		(end 149.198838 -256.32029)
		(width 0.18288)
		(layer "In11.Cu")
		(net "M_H_CPU1_SA_CA<3>")
	)
	(segment
		(start 149.198838 -256.32029)
		(end 144.048734 -256.32029)
		(width 0.18288)
		(layer "In11.Cu")
		(net "M_H_CPU1_SA_CA<3>")
	)
	(segment
		(start 183.320436 -261.522718)
		(end 183.189372 -261.391654)
		(width 0.18288)
		(layer "In11.Cu")
		(net "M_H_CPU1_SA_CA<3>")
	)
	(segment
		(start 139.804648 -254.415798)
		(end 139.663424 -254.557022)
		(width 0.088646)
		(layer "In11.Cu")
		(net "M_H_CPU1_SA_CA<3>")
	)
	(segment
		(start 131.307078 -254.24892)
		(end 131.298696 -254.244094)
		(width 0.088646)
		(layer "In11.Cu")
		(net "M_H_CPU1_SA_CA<3>")
	)
	(segment
		(start 186.130946 -260.515608)
		(end 185.123836 -261.522718)
		(width 0.18288)
		(layer "In11.Cu")
		(net "M_H_CPU1_SA_CA<3>")
	)
	(segment
		(start 197.940422 -261.323836)
		(end 195.050918 -261.323836)
		(width 0.18288)
		(layer "In11.Cu")
		(net "M_H_CPU1_SA_CA<3>")
	)
	(segment
		(start 193.53403 -261.490968)
		(end 191.590168 -261.490968)
		(width 0.18288)
		(layer "In11.Cu")
		(net "M_H_CPU1_SA_CA<3>")
	)
	(segment
		(start 156.71292 -259.548122)
		(end 153.698448 -256.53365)
		(width 0.18288)
		(layer "In11.Cu")
		(net "M_H_CPU1_SA_CA<3>")
	)
	(segment
		(start 179.899056 -261.391654)
		(end 179.608734 -261.681976)
		(width 0.18288)
		(layer "In11.Cu")
		(net "M_H_CPU1_SA_CA<3>")
	)
	(segment
		(start 172.265086 -260.64083)
		(end 171.85894 -260.234684)
		(width 0.18288)
		(layer "In11.Cu")
		(net "M_H_CPU1_SA_CA<3>")
	)
	(segment
		(start 207.071214 -263.616694)
		(end 206.301594 -262.847074)
		(width 0.18288)
		(layer "In11.Cu")
		(net "M_H_CPU1_SA_CA<3>")
	)
	(segment
		(start 190.869062 -260.769862)
		(end 188.907674 -260.769862)
		(width 0.18288)
		(layer "In11.Cu")
		(net "M_H_CPU1_SA_CA<3>")
	)
	(segment
		(start 127.92456 -254.237998)
		(end 127.914146 -254.244094)
		(width 0.088646)
		(layer "In11.Cu")
		(net "M_H_CPU1_SA_CA<3>")
	)
	(segment
		(start 201.269346 -263.322816)
		(end 200.15835 -262.21182)
		(width 0.18288)
		(layer "In11.Cu")
		(net "M_H_CPU1_SA_CA<3>")
	)
	(segment
		(start 140.18895 -254.415798)
		(end 139.804648 -254.415798)
		(width 0.088646)
		(layer "In11.Cu")
		(net "M_H_CPU1_SA_CA<3>")
	)
	(segment
		(start 134.50316 -254.237998)
		(end 134.492746 -254.244094)
		(width 0.088646)
		(layer "In11.Cu")
		(net "M_H_CPU1_SA_CA<3>")
	)
	(segment
		(start 158.557722 -259.548122)
		(end 156.71292 -259.548122)
		(width 0.18288)
		(layer "In11.Cu")
		(net "M_H_CPU1_SA_CA<3>")
	)
	(segment
		(start 159.860234 -260.850634)
		(end 158.557722 -259.548122)
		(width 0.18288)
		(layer "In11.Cu")
		(net "M_H_CPU1_SA_CA<3>")
	)
	(segment
		(start 152.289002 -255.950212)
		(end 149.568916 -255.950212)
		(width 0.18288)
		(layer "In11.Cu")
		(net "M_H_CPU1_SA_CA<3>")
	)
	(segment
		(start 132.613146 -254.244094)
		(end 132.612892 -254.244094)
		(width 0.088646)
		(layer "In11.Cu")
		(net "M_H_CPU1_SA_CA<3>")
	)
	(segment
		(start 142.144242 -254.415798)
		(end 140.18895 -254.415798)
		(width 0.18288)
		(layer "In11.Cu")
		(net "M_H_CPU1_SA_CA<3>")
	)
	(segment
		(start 173.613826 -260.64083)
		(end 172.265086 -260.64083)
		(width 0.18288)
		(layer "In11.Cu")
		(net "M_H_CPU1_SA_CA<3>")
	)
	(segment
		(start 177.83429 -261.490968)
		(end 176.502568 -261.490968)
		(width 0.18288)
		(layer "In11.Cu")
		(net "M_H_CPU1_SA_CA<3>")
	)
	(segment
		(start 139.157456 -254.557022)
		(end 138.93419 -254.333756)
		(width 0.088646)
		(layer "In11.Cu")
		(net "M_H_CPU1_SA_CA<3>")
	)
	(segment
		(start 188.907674 -260.769862)
		(end 188.778642 -260.64083)
		(width 0.18288)
		(layer "In11.Cu")
		(net "M_H_CPU1_SA_CA<3>")
	)
	(segment
		(start 203.798932 -263.19226)
		(end 202.657964 -263.19226)
		(width 0.18288)
		(layer "In11.Cu")
		(net "M_H_CPU1_SA_CA<3>")
	)
	(segment
		(start 194.697096 -261.677658)
		(end 193.72072 -261.677658)
		(width 0.18288)
		(layer "In11.Cu")
		(net "M_H_CPU1_SA_CA<3>")
	)
	(segment
		(start 125.857508 -254.294132)
		(end 125.418088 -254.733552)
		(width 0.088646)
		(layer "In11.Cu")
		(net "M_H_CPU1_SA_CA<3>")
	)
	(segment
		(start 164.751512 -260.727444)
		(end 164.346636 -260.322568)
		(width 0.18288)
		(layer "In11.Cu")
		(net "M_H_CPU1_SA_CA<3>")
	)
	(segment
		(start 139.663424 -254.557022)
		(end 139.157456 -254.557022)
		(width 0.088646)
		(layer "In11.Cu")
		(net "M_H_CPU1_SA_CA<3>")
	)
	(segment
		(start 202.657964 -263.19226)
		(end 202.527408 -263.322816)
		(width 0.18288)
		(layer "In11.Cu")
		(net "M_H_CPU1_SA_CA<3>")
	)
	(segment
		(start 130.74396 -254.237998)
		(end 130.733546 -254.244094)
		(width 0.088646)
		(layer "In11.Cu")
		(net "M_H_CPU1_SA_CA<3>")
	)
	(segment
		(start 183.189372 -261.391654)
		(end 179.899056 -261.391654)
		(width 0.18288)
		(layer "In11.Cu")
		(net "M_H_CPU1_SA_CA<3>")
	)
	(segment
		(start 164.346636 -260.322568)
		(end 161.66211 -260.322568)
		(width 0.18288)
		(layer "In11.Cu")
		(net "M_H_CPU1_SA_CA<3>")
	)
	(segment
		(start 195.050918 -261.323836)
		(end 194.697096 -261.677658)
		(width 0.18288)
		(layer "In11.Cu")
		(net "M_H_CPU1_SA_CA<3>")
	)
	(segment
		(start 206.301594 -262.847074)
		(end 204.144118 -262.847074)
		(width 0.18288)
		(layer "In11.Cu")
		(net "M_H_CPU1_SA_CA<3>")
	)
	(segment
		(start 161.134044 -260.850634)
		(end 159.860234 -260.850634)
		(width 0.18288)
		(layer "In11.Cu")
		(net "M_H_CPU1_SA_CA<3>")
	)
	(segment
		(start 169.452544 -260.234684)
		(end 168.959784 -260.727444)
		(width 0.18288)
		(layer "In11.Cu")
		(net "M_H_CPU1_SA_CA<3>")
	)
	(segment
		(start 161.66211 -260.322568)
		(end 161.134044 -260.850634)
		(width 0.18288)
		(layer "In11.Cu")
		(net "M_H_CPU1_SA_CA<3>")
	)
	(segment
		(start 187.152026 -260.515608)
		(end 186.130946 -260.515608)
		(width 0.18288)
		(layer "In11.Cu")
		(net "M_H_CPU1_SA_CA<3>")
	)
	(segment
		(start 178.025298 -261.681976)
		(end 177.83429 -261.490968)
		(width 0.18288)
		(layer "In11.Cu")
		(net "M_H_CPU1_SA_CA<3>")
	)
	(arc
		(start 128.853692 -254.244094)
		(mid 128.666494 -254.294237)
		(end 128.479296 -254.244094)
		(width 0.088646)
		(layer "In11.Cu")
		(net "M_H_CPU1_SA_CA<3>")
	)
	(arc
		(start 138.251692 -254.244094)
		(mid 138.064494 -254.294237)
		(end 137.877296 -254.244094)
		(width 0.088646)
		(layer "In11.Cu")
		(net "M_H_CPU1_SA_CA<3>")
	)
	(arc
		(start 134.11835 -254.244094)
		(mid 133.844151 -254.168259)
		(end 133.567678 -254.235458)
		(width 0.088646)
		(layer "In11.Cu")
		(net "M_H_CPU1_SA_CA<3>")
	)
	(arc
		(start 132.612892 -254.244094)
		(mid 132.430641 -254.294205)
		(end 132.247132 -254.24892)
		(width 0.088646)
		(layer "In11.Cu")
		(net "M_H_CPU1_SA_CA<3>")
	)
	(arc
		(start 130.35915 -254.244094)
		(mid 130.082337 -254.168224)
		(end 129.803906 -254.237998)
		(width 0.088646)
		(layer "In11.Cu")
		(net "M_H_CPU1_SA_CA<3>")
	)
	(arc
		(start 135.432292 -254.244094)
		(mid 135.245094 -254.294237)
		(end 135.057896 -254.244094)
		(width 0.088646)
		(layer "In11.Cu")
		(net "M_H_CPU1_SA_CA<3>")
	)
	(arc
		(start 132.224018 -254.235458)
		(mid 131.947543 -254.168138)
		(end 131.673346 -254.244094)
		(width 0.088646)
		(layer "In11.Cu")
		(net "M_H_CPU1_SA_CA<3>")
	)
	(arc
		(start 137.311892 -254.244094)
		(mid 137.124694 -254.294237)
		(end 136.937496 -254.244094)
		(width 0.088646)
		(layer "In11.Cu")
		(net "M_H_CPU1_SA_CA<3>")
	)
	(arc
		(start 137.877296 -254.244094)
		(mid 137.594594 -254.168318)
		(end 137.311892 -254.244094)
		(width 0.088646)
		(layer "In11.Cu")
		(net "M_H_CPU1_SA_CA<3>")
	)
	(arc
		(start 126.9746 -254.244094)
		(mid 126.787292 -254.294237)
		(end 126.59995 -254.244094)
		(width 0.088646)
		(layer "In11.Cu")
		(net "M_H_CPU1_SA_CA<3>")
	)
	(arc
		(start 133.17855 -254.244094)
		(mid 132.895848 -254.168318)
		(end 132.613146 -254.244094)
		(width 0.088646)
		(layer "In11.Cu")
		(net "M_H_CPU1_SA_CA<3>")
	)
	(arc
		(start 138.93419 -254.333756)
		(mid 138.878585 -254.285082)
		(end 138.817096 -254.244094)
		(width 0.088646)
		(layer "In11.Cu")
		(net "M_H_CPU1_SA_CA<3>")
	)
	(arc
		(start 130.733546 -254.244094)
		(mid 130.546348 -254.294237)
		(end 130.35915 -254.244094)
		(width 0.088646)
		(layer "In11.Cu")
		(net "M_H_CPU1_SA_CA<3>")
	)
	(arc
		(start 134.492746 -254.244094)
		(mid 134.305548 -254.294237)
		(end 134.11835 -254.244094)
		(width 0.088646)
		(layer "In11.Cu")
		(net "M_H_CPU1_SA_CA<3>")
	)
	(arc
		(start 127.53975 -254.244094)
		(mid 127.265551 -254.168259)
		(end 126.989078 -254.235458)
		(width 0.088646)
		(layer "In11.Cu")
		(net "M_H_CPU1_SA_CA<3>")
	)
	(arc
		(start 126.59995 -254.244094)
		(mid 126.317248 -254.168318)
		(end 126.034546 -254.244094)
		(width 0.088646)
		(layer "In11.Cu")
		(net "M_H_CPU1_SA_CA<3>")
	)
	(arc
		(start 136.372092 -254.244094)
		(mid 136.184894 -254.294237)
		(end 135.997696 -254.244094)
		(width 0.088646)
		(layer "In11.Cu")
		(net "M_H_CPU1_SA_CA<3>")
	)
	(arc
		(start 138.817096 -254.244094)
		(mid 138.534394 -254.168318)
		(end 138.251692 -254.244094)
		(width 0.088646)
		(layer "In11.Cu")
		(net "M_H_CPU1_SA_CA<3>")
	)
	(arc
		(start 136.937496 -254.244094)
		(mid 136.654794 -254.168318)
		(end 136.372092 -254.244094)
		(width 0.088646)
		(layer "In11.Cu")
		(net "M_H_CPU1_SA_CA<3>")
	)
	(arc
		(start 129.419096 -254.244094)
		(mid 129.136394 -254.168318)
		(end 128.853692 -254.244094)
		(width 0.088646)
		(layer "In11.Cu")
		(net "M_H_CPU1_SA_CA<3>")
	)
	(arc
		(start 129.793492 -254.244094)
		(mid 129.606294 -254.294237)
		(end 129.419096 -254.244094)
		(width 0.088646)
		(layer "In11.Cu")
		(net "M_H_CPU1_SA_CA<3>")
	)
	(arc
		(start 126.034546 -254.244094)
		(mid 125.949145 -254.280137)
		(end 125.857508 -254.294132)
		(width 0.088646)
		(layer "In11.Cu")
		(net "M_H_CPU1_SA_CA<3>")
	)
	(arc
		(start 131.673346 -254.244094)
		(mid 131.490841 -254.294332)
		(end 131.307078 -254.24892)
		(width 0.088646)
		(layer "In11.Cu")
		(net "M_H_CPU1_SA_CA<3>")
	)
	(arc
		(start 135.997696 -254.244094)
		(mid 135.714994 -254.168318)
		(end 135.432292 -254.244094)
		(width 0.088646)
		(layer "In11.Cu")
		(net "M_H_CPU1_SA_CA<3>")
	)
	(arc
		(start 131.298696 -254.244094)
		(mid 131.022137 -254.168351)
		(end 130.74396 -254.237998)
		(width 0.088646)
		(layer "In11.Cu")
		(net "M_H_CPU1_SA_CA<3>")
	)
	(arc
		(start 128.479296 -254.244094)
		(mid 128.202737 -254.168351)
		(end 127.92456 -254.237998)
		(width 0.088646)
		(layer "In11.Cu")
		(net "M_H_CPU1_SA_CA<3>")
	)
	(arc
		(start 133.552946 -254.244094)
		(mid 133.365748 -254.294237)
		(end 133.17855 -254.244094)
		(width 0.088646)
		(layer "In11.Cu")
		(net "M_H_CPU1_SA_CA<3>")
	)
	(arc
		(start 135.057896 -254.244094)
		(mid 134.781337 -254.168351)
		(end 134.50316 -254.237998)
		(width 0.088646)
		(layer "In11.Cu")
		(net "M_H_CPU1_SA_CA<3>")
	)
	(arc
		(start 127.914146 -254.244094)
		(mid 127.726948 -254.294237)
		(end 127.53975 -254.244094)
		(width 0.088646)
		(layer "In11.Cu")
		(net "M_H_CPU1_SA_CA<3>")
	)
	(segment
		(start 209.602578 -264.903966)
		(end 210.04022 -264.466324)
		(width 0.20066)
		(layer "F.Cu")
		(net "M_H_CPU1_SA_CA<2>")
	)
	(segment
		(start 206.987902 -264.89152)
		(end 207.001618 -264.89152)
		(width 0.101854)
		(layer "F.Cu")
		(net "M_H_CPU1_SA_CA<2>")
	)
	(segment
		(start 207.001618 -264.89152)
		(end 209.17408 -264.89152)
		(width 0.1016)
		(layer "F.Cu")
		(net "M_H_CPU1_SA_CA<2>")
	)
	(segment
		(start 205.63586 -263.972294)
		(end 205.961234 -263.972294)
		(width 0.20066)
		(layer "F.Cu")
		(net "M_H_CPU1_SA_CA<2>")
	)
	(segment
		(start 205.141576 -264.466578)
		(end 205.63586 -263.972294)
		(width 0.20066)
		(layer "F.Cu")
		(net "M_H_CPU1_SA_CA<2>")
	)
	(segment
		(start 209.17408 -264.89152)
		(end 209.186526 -264.903966)
		(width 0.1016)
		(layer "F.Cu")
		(net "M_H_CPU1_SA_CA<2>")
	)
	(segment
		(start 205.961234 -263.972294)
		(end 206.88046 -264.89152)
		(width 0.20066)
		(layer "F.Cu")
		(net "M_H_CPU1_SA_CA<2>")
	)
	(segment
		(start 209.186526 -264.903966)
		(end 209.602578 -264.903966)
		(width 0.20066)
		(layer "F.Cu")
		(net "M_H_CPU1_SA_CA<2>")
	)
	(segment
		(start 202.971146 -264.466578)
		(end 204.076046 -264.466578)
		(width 0.20066)
		(layer "F.Cu")
		(net "M_H_CPU1_SA_CA<2>")
	)
	(segment
		(start 211.619592 -264.466324)
		(end 211.619846 -264.466578)
		(width 0.20066)
		(layer "F.Cu")
		(net "M_H_CPU1_SA_CA<2>")
	)
	(segment
		(start 123.497594 -254.197866)
		(end 123.497594 -254.733552)
		(width 0.20066)
		(layer "F.Cu")
		(net "M_H_CPU1_SA_CA<2>")
	)
	(segment
		(start 204.076046 -264.466578)
		(end 205.141576 -264.466578)
		(width 0.20066)
		(layer "F.Cu")
		(net "M_H_CPU1_SA_CA<2>")
	)
	(segment
		(start 206.88046 -264.89152)
		(end 206.987902 -264.89152)
		(width 0.20066)
		(layer "F.Cu")
		(net "M_H_CPU1_SA_CA<2>")
	)
	(segment
		(start 123.497848 -254.197612)
		(end 123.497594 -254.197866)
		(width 0.20066)
		(layer "F.Cu")
		(net "M_H_CPU1_SA_CA<2>")
	)
	(segment
		(start 210.04022 -264.466324)
		(end 211.619592 -264.466324)
		(width 0.20066)
		(layer "F.Cu")
		(net "M_H_CPU1_SA_CA<2>")
	)
	(segment
		(start 198.322184 -262.46582)
		(end 194.943222 -262.46582)
		(width 0.18288)
		(layer "In11.Cu")
		(net "M_H_CPU1_SA_CA<2>")
	)
	(segment
		(start 192.795398 -262.20166)
		(end 192.656206 -262.340852)
		(width 0.18288)
		(layer "In11.Cu")
		(net "M_H_CPU1_SA_CA<2>")
	)
	(segment
		(start 200.520808 -263.405112)
		(end 199.261476 -263.405112)
		(width 0.18288)
		(layer "In11.Cu")
		(net "M_H_CPU1_SA_CA<2>")
	)
	(segment
		(start 149.467316 -256.669286)
		(end 143.898366 -256.669286)
		(width 0.18288)
		(layer "In11.Cu")
		(net "M_H_CPU1_SA_CA<2>")
	)
	(segment
		(start 194.943222 -262.46582)
		(end 194.679062 -262.20166)
		(width 0.18288)
		(layer "In11.Cu")
		(net "M_H_CPU1_SA_CA<2>")
	)
	(segment
		(start 187.823094 -261.492492)
		(end 187.232544 -261.492492)
		(width 0.18288)
		(layer "In11.Cu")
		(net "M_H_CPU1_SA_CA<2>")
	)
	(segment
		(start 172.080936 -261.490968)
		(end 171.910756 -261.661148)
		(width 0.18288)
		(layer "In11.Cu")
		(net "M_H_CPU1_SA_CA<2>")
	)
	(segment
		(start 178.063144 -262.198104)
		(end 177.920396 -262.340852)
		(width 0.18288)
		(layer "In11.Cu")
		(net "M_H_CPU1_SA_CA<2>")
	)
	(segment
		(start 128.009396 -254.409194)
		(end 127.994664 -254.41783)
		(width 0.088646)
		(layer "In11.Cu")
		(net "M_H_CPU1_SA_CA<2>")
	)
	(segment
		(start 168.590214 -261.284212)
		(end 164.550598 -261.284212)
		(width 0.18288)
		(layer "In11.Cu")
		(net "M_H_CPU1_SA_CA<2>")
	)
	(segment
		(start 187.132468 -261.592568)
		(end 185.774838 -261.592568)
		(width 0.18288)
		(layer "In11.Cu")
		(net "M_H_CPU1_SA_CA<2>")
	)
	(segment
		(start 188.720476 -261.490968)
		(end 187.824618 -261.490968)
		(width 0.18288)
		(layer "In11.Cu")
		(net "M_H_CPU1_SA_CA<2>")
	)
	(segment
		(start 183.099456 -262.37438)
		(end 179.91455 -262.37438)
		(width 0.18288)
		(layer "In11.Cu")
		(net "M_H_CPU1_SA_CA<2>")
	)
	(segment
		(start 202.971146 -264.466578)
		(end 202.39609 -264.466578)
		(width 0.18288)
		(layer "In11.Cu")
		(net "M_H_CPU1_SA_CA<2>")
	)
	(segment
		(start 157.117288 -260.708902)
		(end 153.389076 -256.98069)
		(width 0.18288)
		(layer "In11.Cu")
		(net "M_H_CPU1_SA_CA<2>")
	)
	(segment
		(start 191.699134 -262.340852)
		(end 190.65748 -261.299198)
		(width 0.18288)
		(layer "In11.Cu")
		(net "M_H_CPU1_SA_CA<2>")
	)
	(segment
		(start 187.824618 -261.490968)
		(end 187.823094 -261.492492)
		(width 0.18288)
		(layer "In11.Cu")
		(net "M_H_CPU1_SA_CA<2>")
	)
	(segment
		(start 170.427904 -260.754876)
		(end 170.234864 -260.947916)
		(width 0.18288)
		(layer "In11.Cu")
		(net "M_H_CPU1_SA_CA<2>")
	)
	(segment
		(start 185.774838 -261.592568)
		(end 185.304176 -262.06323)
		(width 0.18288)
		(layer "In11.Cu")
		(net "M_H_CPU1_SA_CA<2>")
	)
	(segment
		(start 183.410606 -262.06323)
		(end 183.099456 -262.37438)
		(width 0.18288)
		(layer "In11.Cu")
		(net "M_H_CPU1_SA_CA<2>")
	)
	(segment
		(start 141.990826 -254.761746)
		(end 140.192506 -254.761746)
		(width 0.18288)
		(layer "In11.Cu")
		(net "M_H_CPU1_SA_CA<2>")
	)
	(segment
		(start 134.587996 -254.409194)
		(end 134.573264 -254.41783)
		(width 0.088646)
		(layer "In11.Cu")
		(net "M_H_CPU1_SA_CA<2>")
	)
	(segment
		(start 152.137618 -256.462276)
		(end 149.674326 -256.462276)
		(width 0.18288)
		(layer "In11.Cu")
		(net "M_H_CPU1_SA_CA<2>")
	)
	(segment
		(start 140.192506 -254.761746)
		(end 139.09294 -254.761746)
		(width 0.088646)
		(layer "In11.Cu")
		(net "M_H_CPU1_SA_CA<2>")
	)
	(segment
		(start 192.656206 -262.340852)
		(end 191.699134 -262.340852)
		(width 0.18288)
		(layer "In11.Cu")
		(net "M_H_CPU1_SA_CA<2>")
	)
	(segment
		(start 149.674326 -256.462276)
		(end 149.467316 -256.669286)
		(width 0.18288)
		(layer "In11.Cu")
		(net "M_H_CPU1_SA_CA<2>")
	)
	(segment
		(start 170.938444 -261.468108)
		(end 170.938444 -260.947916)
		(width 0.18288)
		(layer "In11.Cu")
		(net "M_H_CPU1_SA_CA<2>")
	)
	(segment
		(start 173.89602 -261.324598)
		(end 173.72965 -261.490968)
		(width 0.18288)
		(layer "In11.Cu")
		(net "M_H_CPU1_SA_CA<2>")
	)
	(segment
		(start 139.09294 -254.761746)
		(end 138.79957 -254.46863)
		(width 0.088646)
		(layer "In11.Cu")
		(net "M_H_CPU1_SA_CA<2>")
	)
	(segment
		(start 179.91455 -262.37438)
		(end 179.738274 -262.198104)
		(width 0.18288)
		(layer "In11.Cu")
		(net "M_H_CPU1_SA_CA<2>")
	)
	(segment
		(start 138.79957 -254.46863)
		(end 138.79957 -254.468376)
		(width 0.088646)
		(layer "In11.Cu")
		(net "M_H_CPU1_SA_CA<2>")
	)
	(segment
		(start 187.232544 -261.492492)
		(end 187.132468 -261.592568)
		(width 0.18288)
		(layer "In11.Cu")
		(net "M_H_CPU1_SA_CA<2>")
	)
	(segment
		(start 176.41697 -262.340852)
		(end 175.400716 -261.324598)
		(width 0.18288)
		(layer "In11.Cu")
		(net "M_H_CPU1_SA_CA<2>")
	)
	(segment
		(start 201.860658 -263.931146)
		(end 201.046842 -263.931146)
		(width 0.18288)
		(layer "In11.Cu")
		(net "M_H_CPU1_SA_CA<2>")
	)
	(segment
		(start 127.069596 -254.409194)
		(end 127.059182 -254.41529)
		(width 0.088646)
		(layer "In11.Cu")
		(net "M_H_CPU1_SA_CA<2>")
	)
	(segment
		(start 158.981902 -260.708902)
		(end 157.117288 -260.708902)
		(width 0.18288)
		(layer "In11.Cu")
		(net "M_H_CPU1_SA_CA<2>")
	)
	(segment
		(start 128.949196 -254.409194)
		(end 128.934464 -254.41783)
		(width 0.088646)
		(layer "In11.Cu")
		(net "M_H_CPU1_SA_CA<2>")
	)
	(segment
		(start 201.046842 -263.931146)
		(end 200.520808 -263.405112)
		(width 0.18288)
		(layer "In11.Cu")
		(net "M_H_CPU1_SA_CA<2>")
	)
	(segment
		(start 125.942598 -254.733552)
		(end 125.691138 -254.985012)
		(width 0.088646)
		(layer "In11.Cu")
		(net "M_H_CPU1_SA_CA<2>")
	)
	(segment
		(start 131.213606 -254.41529)
		(end 131.203192 -254.409194)
		(width 0.088646)
		(layer "In11.Cu")
		(net "M_H_CPU1_SA_CA<2>")
	)
	(segment
		(start 159.639508 -261.366508)
		(end 158.981902 -260.708902)
		(width 0.18288)
		(layer "In11.Cu")
		(net "M_H_CPU1_SA_CA<2>")
	)
	(segment
		(start 185.304176 -262.06323)
		(end 183.410606 -262.06323)
		(width 0.18288)
		(layer "In11.Cu")
		(net "M_H_CPU1_SA_CA<2>")
	)
	(segment
		(start 177.920396 -262.340852)
		(end 176.41697 -262.340852)
		(width 0.18288)
		(layer "In11.Cu")
		(net "M_H_CPU1_SA_CA<2>")
	)
	(segment
		(start 171.131484 -261.661148)
		(end 170.938444 -261.468108)
		(width 0.18288)
		(layer "In11.Cu")
		(net "M_H_CPU1_SA_CA<2>")
	)
	(segment
		(start 133.648196 -254.409194)
		(end 133.637782 -254.41529)
		(width 0.088646)
		(layer "In11.Cu")
		(net "M_H_CPU1_SA_CA<2>")
	)
	(segment
		(start 125.691138 -254.985012)
		(end 125.564392 -255.05791)
		(width 0.088646)
		(layer "In11.Cu")
		(net "M_H_CPU1_SA_CA<2>")
	)
	(segment
		(start 124.25045 -255.05791)
		(end 124.240036 -255.051814)
		(width 0.088646)
		(layer "In11.Cu")
		(net "M_H_CPU1_SA_CA<2>")
	)
	(segment
		(start 173.72965 -261.490968)
		(end 172.080936 -261.490968)
		(width 0.18288)
		(layer "In11.Cu")
		(net "M_H_CPU1_SA_CA<2>")
	)
	(segment
		(start 123.34113 -255.00457)
		(end 123.497594 -254.733552)
		(width 0.088646)
		(layer "In11.Cu")
		(net "M_H_CPU1_SA_CA<2>")
	)
	(segment
		(start 153.389076 -256.98069)
		(end 152.137618 -256.462276)
		(width 0.18288)
		(layer "In11.Cu")
		(net "M_H_CPU1_SA_CA<2>")
	)
	(segment
		(start 161.359342 -261.366508)
		(end 159.639508 -261.366508)
		(width 0.18288)
		(layer "In11.Cu")
		(net "M_H_CPU1_SA_CA<2>")
	)
	(segment
		(start 132.157978 -254.41783)
		(end 132.143246 -254.409194)
		(width 0.088646)
		(layer "In11.Cu")
		(net "M_H_CPU1_SA_CA<2>")
	)
	(segment
		(start 124.63526 -255.051814)
		(end 124.624846 -255.05791)
		(width 0.088646)
		(layer "In11.Cu")
		(net "M_H_CPU1_SA_CA<2>")
	)
	(segment
		(start 188.912246 -261.299198)
		(end 188.720476 -261.490968)
		(width 0.18288)
		(layer "In11.Cu")
		(net "M_H_CPU1_SA_CA<2>")
	)
	(segment
		(start 170.041824 -261.661148)
		(end 168.96715 -261.661148)
		(width 0.18288)
		(layer "In11.Cu")
		(net "M_H_CPU1_SA_CA<2>")
	)
	(segment
		(start 170.938444 -260.947916)
		(end 170.745404 -260.754876)
		(width 0.18288)
		(layer "In11.Cu")
		(net "M_H_CPU1_SA_CA<2>")
	)
	(segment
		(start 170.234864 -261.468108)
		(end 170.041824 -261.661148)
		(width 0.18288)
		(layer "In11.Cu")
		(net "M_H_CPU1_SA_CA<2>")
	)
	(segment
		(start 168.96715 -261.661148)
		(end 168.590214 -261.284212)
		(width 0.18288)
		(layer "In11.Cu")
		(net "M_H_CPU1_SA_CA<2>")
	)
	(segment
		(start 143.898366 -256.669286)
		(end 141.990826 -254.761746)
		(width 0.18288)
		(layer "In11.Cu")
		(net "M_H_CPU1_SA_CA<2>")
	)
	(segment
		(start 190.65748 -261.299198)
		(end 188.912246 -261.299198)
		(width 0.18288)
		(layer "In11.Cu")
		(net "M_H_CPU1_SA_CA<2>")
	)
	(segment
		(start 161.647886 -261.655052)
		(end 161.359342 -261.366508)
		(width 0.18288)
		(layer "In11.Cu")
		(net "M_H_CPU1_SA_CA<2>")
	)
	(segment
		(start 126.13005 -254.409194)
		(end 126.12116 -254.414274)
		(width 0.088646)
		(layer "In11.Cu")
		(net "M_H_CPU1_SA_CA<2>")
	)
	(segment
		(start 132.143246 -254.409194)
		(end 132.131308 -254.402336)
		(width 0.088646)
		(layer "In11.Cu")
		(net "M_H_CPU1_SA_CA<2>")
	)
	(segment
		(start 123.362212 -255.082548)
		(end 123.34113 -255.00457)
		(width 0.088646)
		(layer "In11.Cu")
		(net "M_H_CPU1_SA_CA<2>")
	)
	(segment
		(start 170.234864 -260.947916)
		(end 170.234864 -261.468108)
		(width 0.18288)
		(layer "In11.Cu")
		(net "M_H_CPU1_SA_CA<2>")
	)
	(segment
		(start 171.910756 -261.661148)
		(end 171.131484 -261.661148)
		(width 0.18288)
		(layer "In11.Cu")
		(net "M_H_CPU1_SA_CA<2>")
	)
	(segment
		(start 164.550598 -261.284212)
		(end 164.179758 -261.655052)
		(width 0.18288)
		(layer "In11.Cu")
		(net "M_H_CPU1_SA_CA<2>")
	)
	(segment
		(start 130.828796 -254.409194)
		(end 130.814064 -254.41783)
		(width 0.088646)
		(layer "In11.Cu")
		(net "M_H_CPU1_SA_CA<2>")
	)
	(segment
		(start 164.179758 -261.655052)
		(end 161.647886 -261.655052)
		(width 0.18288)
		(layer "In11.Cu")
		(net "M_H_CPU1_SA_CA<2>")
	)
	(segment
		(start 194.679062 -262.20166)
		(end 192.795398 -262.20166)
		(width 0.18288)
		(layer "In11.Cu")
		(net "M_H_CPU1_SA_CA<2>")
	)
	(segment
		(start 175.400716 -261.324598)
		(end 173.89602 -261.324598)
		(width 0.18288)
		(layer "In11.Cu")
		(net "M_H_CPU1_SA_CA<2>")
	)
	(segment
		(start 179.738274 -262.198104)
		(end 178.063144 -262.198104)
		(width 0.18288)
		(layer "In11.Cu")
		(net "M_H_CPU1_SA_CA<2>")
	)
	(segment
		(start 170.745404 -260.754876)
		(end 170.427904 -260.754876)
		(width 0.18288)
		(layer "In11.Cu")
		(net "M_H_CPU1_SA_CA<2>")
	)
	(segment
		(start 199.261476 -263.405112)
		(end 198.322184 -262.46582)
		(width 0.18288)
		(layer "In11.Cu")
		(net "M_H_CPU1_SA_CA<2>")
	)
	(segment
		(start 202.39609 -264.466578)
		(end 201.860658 -263.931146)
		(width 0.18288)
		(layer "In11.Cu")
		(net "M_H_CPU1_SA_CA<2>")
	)
	(arc
		(start 135.527796 -254.409194)
		(mid 135.245094 -254.48497)
		(end 134.962392 -254.409194)
		(width 0.088646)
		(layer "In11.Cu")
		(net "M_H_CPU1_SA_CA<2>")
	)
	(arc
		(start 127.443992 -254.409194)
		(mid 127.256794 -254.359051)
		(end 127.069596 -254.409194)
		(width 0.088646)
		(layer "In11.Cu")
		(net "M_H_CPU1_SA_CA<2>")
	)
	(arc
		(start 137.781792 -254.409194)
		(mid 137.594594 -254.359051)
		(end 137.407396 -254.409194)
		(width 0.088646)
		(layer "In11.Cu")
		(net "M_H_CPU1_SA_CA<2>")
	)
	(arc
		(start 136.841992 -254.409194)
		(mid 136.654794 -254.359051)
		(end 136.467596 -254.409194)
		(width 0.088646)
		(layer "In11.Cu")
		(net "M_H_CPU1_SA_CA<2>")
	)
	(arc
		(start 134.962392 -254.409194)
		(mid 134.775194 -254.359051)
		(end 134.587996 -254.409194)
		(width 0.088646)
		(layer "In11.Cu")
		(net "M_H_CPU1_SA_CA<2>")
	)
	(arc
		(start 128.934464 -254.41783)
		(mid 128.657989 -254.48515)
		(end 128.383792 -254.409194)
		(width 0.088646)
		(layer "In11.Cu")
		(net "M_H_CPU1_SA_CA<2>")
	)
	(arc
		(start 131.203192 -254.409194)
		(mid 131.015994 -254.359051)
		(end 130.828796 -254.409194)
		(width 0.088646)
		(layer "In11.Cu")
		(net "M_H_CPU1_SA_CA<2>")
	)
	(arc
		(start 133.083046 -254.409194)
		(mid 132.895848 -254.359051)
		(end 132.70865 -254.409194)
		(width 0.088646)
		(layer "In11.Cu")
		(net "M_H_CPU1_SA_CA<2>")
	)
	(arc
		(start 133.637782 -254.41529)
		(mid 133.359604 -254.485013)
		(end 133.083046 -254.409194)
		(width 0.088646)
		(layer "In11.Cu")
		(net "M_H_CPU1_SA_CA<2>")
	)
	(arc
		(start 124.240036 -255.051814)
		(mid 123.961604 -254.982)
		(end 123.684792 -255.05791)
		(width 0.088646)
		(layer "In11.Cu")
		(net "M_H_CPU1_SA_CA<2>")
	)
	(arc
		(start 131.76885 -254.409194)
		(mid 131.492037 -254.485064)
		(end 131.213606 -254.41529)
		(width 0.088646)
		(layer "In11.Cu")
		(net "M_H_CPU1_SA_CA<2>")
	)
	(arc
		(start 126.504446 -254.409194)
		(mid 126.317248 -254.359051)
		(end 126.13005 -254.409194)
		(width 0.088646)
		(layer "In11.Cu")
		(net "M_H_CPU1_SA_CA<2>")
	)
	(arc
		(start 135.902192 -254.409194)
		(mid 135.714994 -254.359051)
		(end 135.527796 -254.409194)
		(width 0.088646)
		(layer "In11.Cu")
		(net "M_H_CPU1_SA_CA<2>")
	)
	(arc
		(start 126.12116 -254.414274)
		(mid 125.990246 -254.550634)
		(end 125.942598 -254.733552)
		(width 0.088646)
		(layer "In11.Cu")
		(net "M_H_CPU1_SA_CA<2>")
	)
	(arc
		(start 125.189996 -255.05791)
		(mid 124.913437 -254.982201)
		(end 124.63526 -255.051814)
		(width 0.088646)
		(layer "In11.Cu")
		(net "M_H_CPU1_SA_CA<2>")
	)
	(arc
		(start 124.624846 -255.05791)
		(mid 124.437648 -255.108053)
		(end 124.25045 -255.05791)
		(width 0.088646)
		(layer "In11.Cu")
		(net "M_H_CPU1_SA_CA<2>")
	)
	(arc
		(start 129.888996 -254.409194)
		(mid 129.606294 -254.48497)
		(end 129.323592 -254.409194)
		(width 0.088646)
		(layer "In11.Cu")
		(net "M_H_CPU1_SA_CA<2>")
	)
	(arc
		(start 132.70865 -254.409194)
		(mid 132.434451 -254.485029)
		(end 132.157978 -254.41783)
		(width 0.088646)
		(layer "In11.Cu")
		(net "M_H_CPU1_SA_CA<2>")
	)
	(arc
		(start 136.467596 -254.409194)
		(mid 136.184894 -254.48497)
		(end 135.902192 -254.409194)
		(width 0.088646)
		(layer "In11.Cu")
		(net "M_H_CPU1_SA_CA<2>")
	)
	(arc
		(start 127.059182 -254.41529)
		(mid 126.781004 -254.485013)
		(end 126.504446 -254.409194)
		(width 0.088646)
		(layer "In11.Cu")
		(net "M_H_CPU1_SA_CA<2>")
	)
	(arc
		(start 130.814064 -254.41783)
		(mid 130.537589 -254.48515)
		(end 130.263392 -254.409194)
		(width 0.088646)
		(layer "In11.Cu")
		(net "M_H_CPU1_SA_CA<2>")
	)
	(arc
		(start 134.022592 -254.409194)
		(mid 133.835394 -254.359051)
		(end 133.648196 -254.409194)
		(width 0.088646)
		(layer "In11.Cu")
		(net "M_H_CPU1_SA_CA<2>")
	)
	(arc
		(start 130.263392 -254.409194)
		(mid 130.076194 -254.359051)
		(end 129.888996 -254.409194)
		(width 0.088646)
		(layer "In11.Cu")
		(net "M_H_CPU1_SA_CA<2>")
	)
	(arc
		(start 128.383792 -254.409194)
		(mid 128.196594 -254.359051)
		(end 128.009396 -254.409194)
		(width 0.088646)
		(layer "In11.Cu")
		(net "M_H_CPU1_SA_CA<2>")
	)
	(arc
		(start 137.407396 -254.409194)
		(mid 137.124694 -254.48497)
		(end 136.841992 -254.409194)
		(width 0.088646)
		(layer "In11.Cu")
		(net "M_H_CPU1_SA_CA<2>")
	)
	(arc
		(start 129.323592 -254.409194)
		(mid 129.136394 -254.359051)
		(end 128.949196 -254.409194)
		(width 0.088646)
		(layer "In11.Cu")
		(net "M_H_CPU1_SA_CA<2>")
	)
	(arc
		(start 123.684792 -255.05791)
		(mid 123.526304 -255.106843)
		(end 123.362212 -255.082548)
		(width 0.088646)
		(layer "In11.Cu")
		(net "M_H_CPU1_SA_CA<2>")
	)
	(arc
		(start 138.347196 -254.409194)
		(mid 138.064494 -254.48497)
		(end 137.781792 -254.409194)
		(width 0.088646)
		(layer "In11.Cu")
		(net "M_H_CPU1_SA_CA<2>")
	)
	(arc
		(start 134.573264 -254.41783)
		(mid 134.296789 -254.48515)
		(end 134.022592 -254.409194)
		(width 0.088646)
		(layer "In11.Cu")
		(net "M_H_CPU1_SA_CA<2>")
	)
	(arc
		(start 125.564392 -255.05791)
		(mid 125.377194 -255.108053)
		(end 125.189996 -255.05791)
		(width 0.088646)
		(layer "In11.Cu")
		(net "M_H_CPU1_SA_CA<2>")
	)
	(arc
		(start 138.721592 -254.409194)
		(mid 138.534394 -254.359051)
		(end 138.347196 -254.409194)
		(width 0.088646)
		(layer "In11.Cu")
		(net "M_H_CPU1_SA_CA<2>")
	)
	(arc
		(start 138.79957 -254.468376)
		(mid 138.76252 -254.43623)
		(end 138.721592 -254.409194)
		(width 0.088646)
		(layer "In11.Cu")
		(net "M_H_CPU1_SA_CA<2>")
	)
	(arc
		(start 127.994664 -254.41783)
		(mid 127.718189 -254.48515)
		(end 127.443992 -254.409194)
		(width 0.088646)
		(layer "In11.Cu")
		(net "M_H_CPU1_SA_CA<2>")
	)
	(arc
		(start 132.131308 -254.402336)
		(mid 131.949197 -254.359011)
		(end 131.76885 -254.409194)
		(width 0.088646)
		(layer "In11.Cu")
		(net "M_H_CPU1_SA_CA<2>")
	)
	(segment
		(start 212.622892 -265.741658)
		(end 212.630258 -265.749024)
		(width 0.1016)
		(layer "F.Cu")
		(net "M_H_CPU1_SA_CA<1>")
	)
	(segment
		(start 210.613752 -265.741658)
		(end 212.622892 -265.741658)
		(width 0.1016)
		(layer "F.Cu")
		(net "M_H_CPU1_SA_CA<1>")
	)
	(segment
		(start 208.176114 -265.316716)
		(end 209.811874 -265.316716)
		(width 0.20066)
		(layer "F.Cu")
		(net "M_H_CPU1_SA_CA<1>")
	)
	(segment
		(start 209.811874 -265.316716)
		(end 210.247484 -265.752326)
		(width 0.20066)
		(layer "F.Cu")
		(net "M_H_CPU1_SA_CA<1>")
	)
	(segment
		(start 213.769194 -264.884154)
		(end 214.1728 -264.884154)
		(width 0.20066)
		(layer "F.Cu")
		(net "M_H_CPU1_SA_CA<1>")
	)
	(segment
		(start 210.247484 -265.752326)
		(end 210.598258 -265.752326)
		(width 0.20066)
		(layer "F.Cu")
		(net "M_H_CPU1_SA_CA<1>")
	)
	(segment
		(start 207.071214 -265.316716)
		(end 208.176114 -265.316716)
		(width 0.20066)
		(layer "F.Cu")
		(net "M_H_CPU1_SA_CA<1>")
	)
	(segment
		(start 214.1728 -264.884154)
		(end 214.605362 -265.316716)
		(width 0.20066)
		(layer "F.Cu")
		(net "M_H_CPU1_SA_CA<1>")
	)
	(segment
		(start 212.630258 -265.749024)
		(end 212.904324 -265.749024)
		(width 0.20066)
		(layer "F.Cu")
		(net "M_H_CPU1_SA_CA<1>")
	)
	(segment
		(start 125.847094 -255.011682)
		(end 125.847348 -255.011936)
		(width 0.20066)
		(layer "F.Cu")
		(net "M_H_CPU1_SA_CA<1>")
	)
	(segment
		(start 214.605362 -265.316716)
		(end 215.719914 -265.316716)
		(width 0.20066)
		(layer "F.Cu")
		(net "M_H_CPU1_SA_CA<1>")
	)
	(segment
		(start 210.603084 -265.752326)
		(end 210.613752 -265.741658)
		(width 0.1016)
		(layer "F.Cu")
		(net "M_H_CPU1_SA_CA<1>")
	)
	(segment
		(start 125.847348 -255.011936)
		(end 125.847348 -255.547622)
		(width 0.20066)
		(layer "F.Cu")
		(net "M_H_CPU1_SA_CA<1>")
	)
	(segment
		(start 212.904324 -265.749024)
		(end 213.769194 -264.884154)
		(width 0.20066)
		(layer "F.Cu")
		(net "M_H_CPU1_SA_CA<1>")
	)
	(segment
		(start 210.598258 -265.752326)
		(end 210.603084 -265.752326)
		(width 0.101854)
		(layer "F.Cu")
		(net "M_H_CPU1_SA_CA<1>")
	)
	(segment
		(start 127.928878 -255.2319)
		(end 127.914146 -255.223264)
		(width 0.088646)
		(layer "In11.Cu")
		(net "M_H_CPU1_SA_CA<1>")
	)
	(segment
		(start 178.08194 -264.040874)
		(end 176.773078 -264.040874)
		(width 0.18288)
		(layer "In11.Cu")
		(net "M_H_CPU1_SA_CA<1>")
	)
	(segment
		(start 125.93828 -255.45669)
		(end 125.847348 -255.547622)
		(width 0.088646)
		(layer "In11.Cu")
		(net "M_H_CPU1_SA_CA<1>")
	)
	(segment
		(start 188.970412 -263.19099)
		(end 187.35421 -263.19099)
		(width 0.18288)
		(layer "In11.Cu")
		(net "M_H_CPU1_SA_CA<1>")
	)
	(segment
		(start 192.676526 -264.040874)
		(end 191.855598 -264.040874)
		(width 0.18288)
		(layer "In11.Cu")
		(net "M_H_CPU1_SA_CA<1>")
	)
	(segment
		(start 191.855598 -264.040874)
		(end 191.855344 -264.041128)
		(width 0.18288)
		(layer "In11.Cu")
		(net "M_H_CPU1_SA_CA<1>")
	)
	(segment
		(start 176.772824 -264.041128)
		(end 176.334928 -264.041128)
		(width 0.18288)
		(layer "In11.Cu")
		(net "M_H_CPU1_SA_CA<1>")
	)
	(segment
		(start 164.77234 -263.19099)
		(end 164.203126 -263.19099)
		(width 0.18288)
		(layer "In11.Cu")
		(net "M_H_CPU1_SA_CA<1>")
	)
	(segment
		(start 191.855344 -264.041128)
		(end 191.422528 -264.041128)
		(width 0.18288)
		(layer "In11.Cu")
		(net "M_H_CPU1_SA_CA<1>")
	)
	(segment
		(start 152.380442 -257.727704)
		(end 150.234142 -257.727704)
		(width 0.18288)
		(layer "In11.Cu")
		(net "M_H_CPU1_SA_CA<1>")
	)
	(segment
		(start 206.56296 -265.82497)
		(end 204.174852 -265.82497)
		(width 0.18288)
		(layer "In11.Cu")
		(net "M_H_CPU1_SA_CA<1>")
	)
	(segment
		(start 195.276724 -264.197084)
		(end 194.990466 -263.910826)
		(width 0.18288)
		(layer "In11.Cu")
		(net "M_H_CPU1_SA_CA<1>")
	)
	(segment
		(start 187.23356 -263.31164)
		(end 186.22264 -263.31164)
		(width 0.18288)
		(layer "In11.Cu")
		(net "M_H_CPU1_SA_CA<1>")
	)
	(segment
		(start 175.32223 -263.02843)
		(end 173.868842 -263.02843)
		(width 0.18288)
		(layer "In11.Cu")
		(net "M_H_CPU1_SA_CA<1>")
	)
	(segment
		(start 136.93775 -255.22301)
		(end 136.92886 -255.228344)
		(width 0.088646)
		(layer "In11.Cu")
		(net "M_H_CPU1_SA_CA<1>")
	)
	(segment
		(start 138.266678 -255.231646)
		(end 138.251946 -255.22301)
		(width 0.088646)
		(layer "In11.Cu")
		(net "M_H_CPU1_SA_CA<1>")
	)
	(segment
		(start 126.599696 -255.223264)
		(end 126.589282 -255.22936)
		(width 0.088646)
		(layer "In11.Cu")
		(net "M_H_CPU1_SA_CA<1>")
	)
	(segment
		(start 183.407812 -264.064242)
		(end 179.687474 -264.064242)
		(width 0.18288)
		(layer "In11.Cu")
		(net "M_H_CPU1_SA_CA<1>")
	)
	(segment
		(start 141.760194 -255.510284)
		(end 140.18895 -255.510284)
		(width 0.18288)
		(layer "In11.Cu")
		(net "M_H_CPU1_SA_CA<1>")
	)
	(segment
		(start 168.640506 -263.037828)
		(end 164.925502 -263.037828)
		(width 0.18288)
		(layer "In11.Cu")
		(net "M_H_CPU1_SA_CA<1>")
	)
	(segment
		(start 201.886312 -265.661648)
		(end 201.233278 -265.661648)
		(width 0.18288)
		(layer "In11.Cu")
		(net "M_H_CPU1_SA_CA<1>")
	)
	(segment
		(start 133.178296 -255.223264)
		(end 133.167882 -255.22936)
		(width 0.088646)
		(layer "In11.Cu")
		(net "M_H_CPU1_SA_CA<1>")
	)
	(segment
		(start 194.990466 -263.910826)
		(end 192.806574 -263.910826)
		(width 0.18288)
		(layer "In11.Cu")
		(net "M_H_CPU1_SA_CA<1>")
	)
	(segment
		(start 164.01923 -263.374886)
		(end 161.368994 -263.374886)
		(width 0.18288)
		(layer "In11.Cu")
		(net "M_H_CPU1_SA_CA<1>")
	)
	(segment
		(start 189.129924 -263.031478)
		(end 188.970412 -263.19099)
		(width 0.18288)
		(layer "In11.Cu")
		(net "M_H_CPU1_SA_CA<1>")
	)
	(segment
		(start 173.706282 -263.19099)
		(end 172.29455 -263.19099)
		(width 0.18288)
		(layer "In11.Cu")
		(net "M_H_CPU1_SA_CA<1>")
	)
	(segment
		(start 157.290516 -262.637778)
		(end 152.380442 -257.727704)
		(width 0.18288)
		(layer "In11.Cu")
		(net "M_H_CPU1_SA_CA<1>")
	)
	(segment
		(start 164.203126 -263.19099)
		(end 164.01923 -263.374886)
		(width 0.18288)
		(layer "In11.Cu")
		(net "M_H_CPU1_SA_CA<1>")
	)
	(segment
		(start 137.326878 -255.231646)
		(end 137.312146 -255.22301)
		(width 0.088646)
		(layer "In11.Cu")
		(net "M_H_CPU1_SA_CA<1>")
	)
	(segment
		(start 198.461884 -264.197084)
		(end 195.276724 -264.197084)
		(width 0.18288)
		(layer "In11.Cu")
		(net "M_H_CPU1_SA_CA<1>")
	)
	(segment
		(start 128.868678 -255.2319)
		(end 128.853946 -255.223264)
		(width 0.088646)
		(layer "In11.Cu")
		(net "M_H_CPU1_SA_CA<1>")
	)
	(segment
		(start 139.497308 -255.510284)
		(end 139.26947 -255.282446)
		(width 0.088646)
		(layer "In11.Cu")
		(net "M_H_CPU1_SA_CA<1>")
	)
	(segment
		(start 192.806574 -263.910826)
		(end 192.676526 -264.040874)
		(width 0.18288)
		(layer "In11.Cu")
		(net "M_H_CPU1_SA_CA<1>")
	)
	(segment
		(start 199.363076 -265.098276)
		(end 198.461884 -264.197084)
		(width 0.18288)
		(layer "In11.Cu")
		(net "M_H_CPU1_SA_CA<1>")
	)
	(segment
		(start 207.071214 -265.316716)
		(end 206.56296 -265.82497)
		(width 0.18288)
		(layer "In11.Cu")
		(net "M_H_CPU1_SA_CA<1>")
	)
	(segment
		(start 183.600852 -263.871202)
		(end 183.407812 -264.064242)
		(width 0.18288)
		(layer "In11.Cu")
		(net "M_H_CPU1_SA_CA<1>")
	)
	(segment
		(start 176.334928 -264.041128)
		(end 175.32223 -263.02843)
		(width 0.18288)
		(layer "In11.Cu")
		(net "M_H_CPU1_SA_CA<1>")
	)
	(segment
		(start 164.925502 -263.037828)
		(end 164.77234 -263.19099)
		(width 0.18288)
		(layer "In11.Cu")
		(net "M_H_CPU1_SA_CA<1>")
	)
	(segment
		(start 161.368994 -263.374886)
		(end 160.957768 -262.96366)
		(width 0.18288)
		(layer "In11.Cu")
		(net "M_H_CPU1_SA_CA<1>")
	)
	(segment
		(start 178.279806 -263.843008)
		(end 178.08194 -264.040874)
		(width 0.18288)
		(layer "In11.Cu")
		(net "M_H_CPU1_SA_CA<1>")
	)
	(segment
		(start 203.404978 -266.594844)
		(end 202.569318 -266.594844)
		(width 0.18288)
		(layer "In11.Cu")
		(net "M_H_CPU1_SA_CA<1>")
	)
	(segment
		(start 160.957768 -262.96366)
		(end 159.45866 -262.96366)
		(width 0.18288)
		(layer "In11.Cu")
		(net "M_H_CPU1_SA_CA<1>")
	)
	(segment
		(start 204.174852 -265.82497)
		(end 203.404978 -266.594844)
		(width 0.18288)
		(layer "In11.Cu")
		(net "M_H_CPU1_SA_CA<1>")
	)
	(segment
		(start 187.35421 -263.19099)
		(end 187.23356 -263.31164)
		(width 0.18288)
		(layer "In11.Cu")
		(net "M_H_CPU1_SA_CA<1>")
	)
	(segment
		(start 143.614902 -257.364992)
		(end 141.760194 -255.510284)
		(width 0.18288)
		(layer "In11.Cu")
		(net "M_H_CPU1_SA_CA<1>")
	)
	(segment
		(start 176.773078 -264.040874)
		(end 176.772824 -264.041128)
		(width 0.18288)
		(layer "In11.Cu")
		(net "M_H_CPU1_SA_CA<1>")
	)
	(segment
		(start 172.10786 -263.37768)
		(end 168.980358 -263.37768)
		(width 0.18288)
		(layer "In11.Cu")
		(net "M_H_CPU1_SA_CA<1>")
	)
	(segment
		(start 202.569318 -266.594844)
		(end 202.230228 -266.255754)
		(width 0.18288)
		(layer "In11.Cu")
		(net "M_H_CPU1_SA_CA<1>")
	)
	(segment
		(start 172.29455 -263.19099)
		(end 172.10786 -263.37768)
		(width 0.18288)
		(layer "In11.Cu")
		(net "M_H_CPU1_SA_CA<1>")
	)
	(segment
		(start 150.234142 -257.727704)
		(end 149.87143 -257.364992)
		(width 0.18288)
		(layer "In11.Cu")
		(net "M_H_CPU1_SA_CA<1>")
	)
	(segment
		(start 173.868842 -263.02843)
		(end 173.706282 -263.19099)
		(width 0.18288)
		(layer "In11.Cu")
		(net "M_H_CPU1_SA_CA<1>")
	)
	(segment
		(start 191.422528 -264.041128)
		(end 190.412878 -263.031478)
		(width 0.18288)
		(layer "In11.Cu")
		(net "M_H_CPU1_SA_CA<1>")
	)
	(segment
		(start 179.687474 -264.064242)
		(end 179.46624 -263.843008)
		(width 0.18288)
		(layer "In11.Cu")
		(net "M_H_CPU1_SA_CA<1>")
	)
	(segment
		(start 186.22264 -263.31164)
		(end 185.663078 -263.871202)
		(width 0.18288)
		(layer "In11.Cu")
		(net "M_H_CPU1_SA_CA<1>")
	)
	(segment
		(start 185.663078 -263.871202)
		(end 183.600852 -263.871202)
		(width 0.18288)
		(layer "In11.Cu")
		(net "M_H_CPU1_SA_CA<1>")
	)
	(segment
		(start 200.669906 -265.098276)
		(end 199.363076 -265.098276)
		(width 0.18288)
		(layer "In11.Cu")
		(net "M_H_CPU1_SA_CA<1>")
	)
	(segment
		(start 126.984506 -255.22936)
		(end 126.9746 -255.223264)
		(width 0.088646)
		(layer "In11.Cu")
		(net "M_H_CPU1_SA_CA<1>")
	)
	(segment
		(start 133.563106 -255.22936)
		(end 133.552692 -255.223264)
		(width 0.088646)
		(layer "In11.Cu")
		(net "M_H_CPU1_SA_CA<1>")
	)
	(segment
		(start 202.230228 -266.005564)
		(end 201.886312 -265.661648)
		(width 0.18288)
		(layer "In11.Cu")
		(net "M_H_CPU1_SA_CA<1>")
	)
	(segment
		(start 168.980358 -263.37768)
		(end 168.640506 -263.037828)
		(width 0.18288)
		(layer "In11.Cu")
		(net "M_H_CPU1_SA_CA<1>")
	)
	(segment
		(start 159.132778 -262.637778)
		(end 157.290516 -262.637778)
		(width 0.18288)
		(layer "In11.Cu")
		(net "M_H_CPU1_SA_CA<1>")
	)
	(segment
		(start 130.748278 -255.2319)
		(end 130.733546 -255.223264)
		(width 0.088646)
		(layer "In11.Cu")
		(net "M_H_CPU1_SA_CA<1>")
	)
	(segment
		(start 201.233278 -265.661648)
		(end 200.669906 -265.098276)
		(width 0.18288)
		(layer "In11.Cu")
		(net "M_H_CPU1_SA_CA<1>")
	)
	(segment
		(start 129.808478 -255.2319)
		(end 129.793746 -255.223264)
		(width 0.088646)
		(layer "In11.Cu")
		(net "M_H_CPU1_SA_CA<1>")
	)
	(segment
		(start 179.46624 -263.843008)
		(end 178.279806 -263.843008)
		(width 0.18288)
		(layer "In11.Cu")
		(net "M_H_CPU1_SA_CA<1>")
	)
	(segment
		(start 132.23875 -255.223264)
		(end 132.224018 -255.2319)
		(width 0.088646)
		(layer "In11.Cu")
		(net "M_H_CPU1_SA_CA<1>")
	)
	(segment
		(start 140.18895 -255.510284)
		(end 139.497308 -255.510284)
		(width 0.088646)
		(layer "In11.Cu")
		(net "M_H_CPU1_SA_CA<1>")
	)
	(segment
		(start 134.50316 -255.22936)
		(end 134.492746 -255.223264)
		(width 0.088646)
		(layer "In11.Cu")
		(net "M_H_CPU1_SA_CA<1>")
	)
	(segment
		(start 149.87143 -257.364992)
		(end 143.614902 -257.364992)
		(width 0.18288)
		(layer "In11.Cu")
		(net "M_H_CPU1_SA_CA<1>")
	)
	(segment
		(start 159.45866 -262.96366)
		(end 159.132778 -262.637778)
		(width 0.18288)
		(layer "In11.Cu")
		(net "M_H_CPU1_SA_CA<1>")
	)
	(segment
		(start 190.412878 -263.031478)
		(end 189.129924 -263.031478)
		(width 0.18288)
		(layer "In11.Cu")
		(net "M_H_CPU1_SA_CA<1>")
	)
	(segment
		(start 202.230228 -266.255754)
		(end 202.230228 -266.005564)
		(width 0.18288)
		(layer "In11.Cu")
		(net "M_H_CPU1_SA_CA<1>")
	)
	(arc
		(start 129.41935 -255.223264)
		(mid 129.145121 -255.299189)
		(end 128.868678 -255.2319)
		(width 0.088646)
		(layer "In11.Cu")
		(net "M_H_CPU1_SA_CA<1>")
	)
	(arc
		(start 138.251946 -255.22301)
		(mid 138.064748 -255.172867)
		(end 137.87755 -255.22301)
		(width 0.088646)
		(layer "In11.Cu")
		(net "M_H_CPU1_SA_CA<1>")
	)
	(arc
		(start 126.319026 -255.298956)
		(mid 126.112959 -255.339945)
		(end 125.93828 -255.45669)
		(width 0.088646)
		(layer "In11.Cu")
		(net "M_H_CPU1_SA_CA<1>")
	)
	(arc
		(start 133.552692 -255.223264)
		(mid 133.365494 -255.173121)
		(end 133.178296 -255.223264)
		(width 0.088646)
		(layer "In11.Cu")
		(net "M_H_CPU1_SA_CA<1>")
	)
	(arc
		(start 126.589282 -255.22936)
		(mid 126.458516 -255.281097)
		(end 126.319026 -255.298956)
		(width 0.088646)
		(layer "In11.Cu")
		(net "M_H_CPU1_SA_CA<1>")
	)
	(arc
		(start 133.167882 -255.22936)
		(mid 132.889704 -255.299052)
		(end 132.613146 -255.223264)
		(width 0.088646)
		(layer "In11.Cu")
		(net "M_H_CPU1_SA_CA<1>")
	)
	(arc
		(start 131.673346 -255.223264)
		(mid 131.486148 -255.173121)
		(end 131.29895 -255.223264)
		(width 0.088646)
		(layer "In11.Cu")
		(net "M_H_CPU1_SA_CA<1>")
	)
	(arc
		(start 135.997696 -255.223264)
		(mid 135.714994 -255.299006)
		(end 135.432292 -255.223264)
		(width 0.088646)
		(layer "In11.Cu")
		(net "M_H_CPU1_SA_CA<1>")
	)
	(arc
		(start 139.26947 -255.282446)
		(mid 139.23256 -255.250175)
		(end 139.191746 -255.22301)
		(width 0.088646)
		(layer "In11.Cu")
		(net "M_H_CPU1_SA_CA<1>")
	)
	(arc
		(start 128.853946 -255.223264)
		(mid 128.666748 -255.173121)
		(end 128.47955 -255.223264)
		(width 0.088646)
		(layer "In11.Cu")
		(net "M_H_CPU1_SA_CA<1>")
	)
	(arc
		(start 139.191746 -255.22301)
		(mid 139.004548 -255.172867)
		(end 138.81735 -255.22301)
		(width 0.088646)
		(layer "In11.Cu")
		(net "M_H_CPU1_SA_CA<1>")
	)
	(arc
		(start 136.372092 -255.223264)
		(mid 136.184894 -255.173121)
		(end 135.997696 -255.223264)
		(width 0.088646)
		(layer "In11.Cu")
		(net "M_H_CPU1_SA_CA<1>")
	)
	(arc
		(start 130.733546 -255.223264)
		(mid 130.546348 -255.173121)
		(end 130.35915 -255.223264)
		(width 0.088646)
		(layer "In11.Cu")
		(net "M_H_CPU1_SA_CA<1>")
	)
	(arc
		(start 134.492746 -255.223264)
		(mid 134.305548 -255.173121)
		(end 134.11835 -255.223264)
		(width 0.088646)
		(layer "In11.Cu")
		(net "M_H_CPU1_SA_CA<1>")
	)
	(arc
		(start 136.92886 -255.228344)
		(mid 136.649818 -255.299029)
		(end 136.372092 -255.223264)
		(width 0.088646)
		(layer "In11.Cu")
		(net "M_H_CPU1_SA_CA<1>")
	)
	(arc
		(start 126.9746 -255.223264)
		(mid 126.787148 -255.172994)
		(end 126.599696 -255.223264)
		(width 0.088646)
		(layer "In11.Cu")
		(net "M_H_CPU1_SA_CA<1>")
	)
	(arc
		(start 130.35915 -255.223264)
		(mid 130.084921 -255.299189)
		(end 129.808478 -255.2319)
		(width 0.088646)
		(layer "In11.Cu")
		(net "M_H_CPU1_SA_CA<1>")
	)
	(arc
		(start 127.53975 -255.223264)
		(mid 127.262937 -255.2991)
		(end 126.984506 -255.22936)
		(width 0.088646)
		(layer "In11.Cu")
		(net "M_H_CPU1_SA_CA<1>")
	)
	(arc
		(start 135.057896 -255.223264)
		(mid 134.781337 -255.298973)
		(end 134.50316 -255.22936)
		(width 0.088646)
		(layer "In11.Cu")
		(net "M_H_CPU1_SA_CA<1>")
	)
	(arc
		(start 131.29895 -255.223264)
		(mid 131.024721 -255.299189)
		(end 130.748278 -255.2319)
		(width 0.088646)
		(layer "In11.Cu")
		(net "M_H_CPU1_SA_CA<1>")
	)
	(arc
		(start 134.11835 -255.223264)
		(mid 133.841537 -255.2991)
		(end 133.563106 -255.22936)
		(width 0.088646)
		(layer "In11.Cu")
		(net "M_H_CPU1_SA_CA<1>")
	)
	(arc
		(start 137.312146 -255.22301)
		(mid 137.124948 -255.172867)
		(end 136.93775 -255.22301)
		(width 0.088646)
		(layer "In11.Cu")
		(net "M_H_CPU1_SA_CA<1>")
	)
	(arc
		(start 132.224018 -255.2319)
		(mid 131.947577 -255.299066)
		(end 131.673346 -255.223264)
		(width 0.088646)
		(layer "In11.Cu")
		(net "M_H_CPU1_SA_CA<1>")
	)
	(arc
		(start 138.81735 -255.22301)
		(mid 138.543151 -255.298845)
		(end 138.266678 -255.231646)
		(width 0.088646)
		(layer "In11.Cu")
		(net "M_H_CPU1_SA_CA<1>")
	)
	(arc
		(start 137.87755 -255.22301)
		(mid 137.603351 -255.298845)
		(end 137.326878 -255.231646)
		(width 0.088646)
		(layer "In11.Cu")
		(net "M_H_CPU1_SA_CA<1>")
	)
	(arc
		(start 127.914146 -255.223264)
		(mid 127.726948 -255.173121)
		(end 127.53975 -255.223264)
		(width 0.088646)
		(layer "In11.Cu")
		(net "M_H_CPU1_SA_CA<1>")
	)
	(arc
		(start 129.793746 -255.223264)
		(mid 129.606548 -255.173121)
		(end 129.41935 -255.223264)
		(width 0.088646)
		(layer "In11.Cu")
		(net "M_H_CPU1_SA_CA<1>")
	)
	(arc
		(start 132.613146 -255.223264)
		(mid 132.425948 -255.173121)
		(end 132.23875 -255.223264)
		(width 0.088646)
		(layer "In11.Cu")
		(net "M_H_CPU1_SA_CA<1>")
	)
	(arc
		(start 128.47955 -255.223264)
		(mid 128.205321 -255.299189)
		(end 127.928878 -255.2319)
		(width 0.088646)
		(layer "In11.Cu")
		(net "M_H_CPU1_SA_CA<1>")
	)
	(arc
		(start 135.432292 -255.223264)
		(mid 135.245094 -255.173121)
		(end 135.057896 -255.223264)
		(width 0.088646)
		(layer "In11.Cu")
		(net "M_H_CPU1_SA_CA<1>")
	)
	(segment
		(start 209.17408 -266.591542)
		(end 209.186526 -266.603988)
		(width 0.1016)
		(layer "F.Cu")
		(net "M_H_CPU1_SA_CA<0>")
	)
	(segment
		(start 209.602578 -266.603988)
		(end 210.04022 -266.166346)
		(width 0.20066)
		(layer "F.Cu")
		(net "M_H_CPU1_SA_CA<0>")
	)
	(segment
		(start 205.818994 -265.672316)
		(end 206.73822 -266.591542)
		(width 0.20066)
		(layer "F.Cu")
		(net "M_H_CPU1_SA_CA<0>")
	)
	(segment
		(start 123.027694 -255.547368)
		(end 123.027948 -255.547622)
		(width 0.20066)
		(layer "F.Cu")
		(net "M_H_CPU1_SA_CA<0>")
	)
	(segment
		(start 206.893668 -266.591542)
		(end 206.91475 -266.591542)
		(width 0.101854)
		(layer "F.Cu")
		(net "M_H_CPU1_SA_CA<0>")
	)
	(segment
		(start 206.91475 -266.591542)
		(end 209.17408 -266.591542)
		(width 0.1016)
		(layer "F.Cu")
		(net "M_H_CPU1_SA_CA<0>")
	)
	(segment
		(start 210.04022 -266.166346)
		(end 211.619592 -266.166346)
		(width 0.20066)
		(layer "F.Cu")
		(net "M_H_CPU1_SA_CA<0>")
	)
	(segment
		(start 123.027694 -255.011682)
		(end 123.027694 -255.547368)
		(width 0.20066)
		(layer "F.Cu")
		(net "M_H_CPU1_SA_CA<0>")
	)
	(segment
		(start 209.186526 -266.603988)
		(end 209.602578 -266.603988)
		(width 0.20066)
		(layer "F.Cu")
		(net "M_H_CPU1_SA_CA<0>")
	)
	(segment
		(start 202.971146 -266.1666)
		(end 204.076046 -266.1666)
		(width 0.20066)
		(layer "F.Cu")
		(net "M_H_CPU1_SA_CA<0>")
	)
	(segment
		(start 206.73822 -266.591542)
		(end 206.893668 -266.591542)
		(width 0.20066)
		(layer "F.Cu")
		(net "M_H_CPU1_SA_CA<0>")
	)
	(segment
		(start 204.076046 -266.1666)
		(end 205.002892 -266.1666)
		(width 0.20066)
		(layer "F.Cu")
		(net "M_H_CPU1_SA_CA<0>")
	)
	(segment
		(start 205.497176 -265.672316)
		(end 205.818994 -265.672316)
		(width 0.20066)
		(layer "F.Cu")
		(net "M_H_CPU1_SA_CA<0>")
	)
	(segment
		(start 205.002892 -266.1666)
		(end 205.497176 -265.672316)
		(width 0.20066)
		(layer "F.Cu")
		(net "M_H_CPU1_SA_CA<0>")
	)
	(segment
		(start 211.619592 -266.166346)
		(end 211.619846 -266.1666)
		(width 0.20066)
		(layer "F.Cu")
		(net "M_H_CPU1_SA_CA<0>")
	)
	(segment
		(start 131.769104 -255.05791)
		(end 131.757928 -255.051306)
		(width 0.088646)
		(layer "In11.Cu")
		(net "M_H_CPU1_SA_CA<0>")
	)
	(segment
		(start 172.334682 -262.340852)
		(end 172.17898 -262.18515)
		(width 0.18288)
		(layer "In11.Cu")
		(net "M_H_CPU1_SA_CA<0>")
	)
	(segment
		(start 161.348166 -262.36168)
		(end 159.66948 -262.36168)
		(width 0.18288)
		(layer "In11.Cu")
		(net "M_H_CPU1_SA_CA<0>")
	)
	(segment
		(start 125.104906 -255.22936)
		(end 125.094492 -255.223264)
		(width 0.088646)
		(layer "In11.Cu")
		(net "M_H_CPU1_SA_CA<0>")
	)
	(segment
		(start 150.46071 -257.217672)
		(end 150.257764 -257.014726)
		(width 0.18288)
		(layer "In11.Cu")
		(net "M_H_CPU1_SA_CA<0>")
	)
	(segment
		(start 156.76499 -261.375652)
		(end 152.60701 -257.217672)
		(width 0.18288)
		(layer "In11.Cu")
		(net "M_H_CPU1_SA_CA<0>")
	)
	(segment
		(start 183.668924 -262.970518)
		(end 180.007514 -262.970518)
		(width 0.18288)
		(layer "In11.Cu")
		(net "M_H_CPU1_SA_CA<0>")
	)
	(segment
		(start 199.04837 -263.938258)
		(end 198.130668 -263.020556)
		(width 0.18288)
		(layer "In11.Cu")
		(net "M_H_CPU1_SA_CA<0>")
	)
	(segment
		(start 124.720096 -255.223264)
		(end 124.709682 -255.22936)
		(width 0.088646)
		(layer "In11.Cu")
		(net "M_H_CPU1_SA_CA<0>")
	)
	(segment
		(start 202.971146 -266.018772)
		(end 202.908154 -265.866626)
		(width 0.18288)
		(layer "In11.Cu")
		(net "M_H_CPU1_SA_CA<0>")
	)
	(segment
		(start 192.795652 -263.38911)
		(end 192.597532 -263.19099)
		(width 0.18288)
		(layer "In11.Cu")
		(net "M_H_CPU1_SA_CA<0>")
	)
	(segment
		(start 202.971146 -266.1666)
		(end 202.971146 -266.018772)
		(width 0.18288)
		(layer "In11.Cu")
		(net "M_H_CPU1_SA_CA<0>")
	)
	(segment
		(start 202.17765 -265.136122)
		(end 201.46391 -265.136122)
		(width 0.18288)
		(layer "In11.Cu")
		(net "M_H_CPU1_SA_CA<0>")
	)
	(segment
		(start 198.130668 -263.020556)
		(end 195.21805 -263.020556)
		(width 0.18288)
		(layer "In11.Cu")
		(net "M_H_CPU1_SA_CA<0>")
	)
	(segment
		(start 128.949196 -255.05791)
		(end 128.934464 -255.049274)
		(width 0.088646)
		(layer "In11.Cu")
		(net "M_H_CPU1_SA_CA<0>")
	)
	(segment
		(start 168.94429 -262.18515)
		(end 168.608502 -262.520938)
		(width 0.18288)
		(layer "In11.Cu")
		(net "M_H_CPU1_SA_CA<0>")
	)
	(segment
		(start 184.045606 -263.3472)
		(end 183.668924 -262.970518)
		(width 0.18288)
		(layer "In11.Cu")
		(net "M_H_CPU1_SA_CA<0>")
	)
	(segment
		(start 191.35979 -263.19099)
		(end 190.68415 -262.51535)
		(width 0.18288)
		(layer "In11.Cu")
		(net "M_H_CPU1_SA_CA<0>")
	)
	(segment
		(start 195.21805 -263.020556)
		(end 194.849496 -263.38911)
		(width 0.18288)
		(layer "In11.Cu")
		(net "M_H_CPU1_SA_CA<0>")
	)
	(segment
		(start 194.849496 -263.38911)
		(end 192.795652 -263.38911)
		(width 0.18288)
		(layer "In11.Cu")
		(net "M_H_CPU1_SA_CA<0>")
	)
	(segment
		(start 159.66948 -262.36168)
		(end 158.683452 -261.375652)
		(width 0.18288)
		(layer "In11.Cu")
		(net "M_H_CPU1_SA_CA<0>")
	)
	(segment
		(start 129.888996 -255.05791)
		(end 129.874264 -255.049274)
		(width 0.088646)
		(layer "In11.Cu")
		(net "M_H_CPU1_SA_CA<0>")
	)
	(segment
		(start 190.68415 -262.51535)
		(end 189.042548 -262.51535)
		(width 0.18288)
		(layer "In11.Cu")
		(net "M_H_CPU1_SA_CA<0>")
	)
	(segment
		(start 143.754602 -257.014726)
		(end 141.887448 -255.147572)
		(width 0.18288)
		(layer "In11.Cu")
		(net "M_H_CPU1_SA_CA<0>")
	)
	(segment
		(start 130.828796 -255.05791)
		(end 130.814064 -255.049274)
		(width 0.088646)
		(layer "In11.Cu")
		(net "M_H_CPU1_SA_CA<0>")
	)
	(segment
		(start 187.559696 -262.340852)
		(end 187.349638 -262.130794)
		(width 0.18288)
		(layer "In11.Cu")
		(net "M_H_CPU1_SA_CA<0>")
	)
	(segment
		(start 184.770522 -263.3472)
		(end 184.045606 -263.3472)
		(width 0.18288)
		(layer "In11.Cu")
		(net "M_H_CPU1_SA_CA<0>")
	)
	(segment
		(start 164.2618 -262.187182)
		(end 161.522664 -262.187182)
		(width 0.18288)
		(layer "In11.Cu")
		(net "M_H_CPU1_SA_CA<0>")
	)
	(segment
		(start 152.60701 -257.217672)
		(end 150.46071 -257.217672)
		(width 0.18288)
		(layer "In11.Cu")
		(net "M_H_CPU1_SA_CA<0>")
	)
	(segment
		(start 172.17898 -262.18515)
		(end 168.94429 -262.18515)
		(width 0.18288)
		(layer "In11.Cu")
		(net "M_H_CPU1_SA_CA<0>")
	)
	(segment
		(start 175.593502 -262.512302)
		(end 173.750732 -262.512302)
		(width 0.18288)
		(layer "In11.Cu")
		(net "M_H_CPU1_SA_CA<0>")
	)
	(segment
		(start 200.266046 -263.938258)
		(end 199.04837 -263.938258)
		(width 0.18288)
		(layer "In11.Cu")
		(net "M_H_CPU1_SA_CA<0>")
	)
	(segment
		(start 173.579282 -262.340852)
		(end 172.334682 -262.340852)
		(width 0.18288)
		(layer "In11.Cu")
		(net "M_H_CPU1_SA_CA<0>")
	)
	(segment
		(start 187.349638 -262.130794)
		(end 185.986928 -262.130794)
		(width 0.18288)
		(layer "In11.Cu")
		(net "M_H_CPU1_SA_CA<0>")
	)
	(segment
		(start 150.257764 -257.014726)
		(end 143.754602 -257.014726)
		(width 0.18288)
		(layer "In11.Cu")
		(net "M_H_CPU1_SA_CA<0>")
	)
	(segment
		(start 126.51486 -255.051814)
		(end 126.504446 -255.05791)
		(width 0.088646)
		(layer "In11.Cu")
		(net "M_H_CPU1_SA_CA<0>")
	)
	(segment
		(start 179.655216 -263.322816)
		(end 178.047396 -263.322816)
		(width 0.18288)
		(layer "In11.Cu")
		(net "M_H_CPU1_SA_CA<0>")
	)
	(segment
		(start 123.273312 -255.252982)
		(end 123.184412 -255.276604)
		(width 0.088646)
		(layer "In11.Cu")
		(net "M_H_CPU1_SA_CA<0>")
	)
	(segment
		(start 178.047396 -263.322816)
		(end 177.91557 -263.19099)
		(width 0.18288)
		(layer "In11.Cu")
		(net "M_H_CPU1_SA_CA<0>")
	)
	(segment
		(start 128.009396 -255.05791)
		(end 127.994664 -255.049274)
		(width 0.088646)
		(layer "In11.Cu")
		(net "M_H_CPU1_SA_CA<0>")
	)
	(segment
		(start 173.750732 -262.512302)
		(end 173.579282 -262.340852)
		(width 0.18288)
		(layer "In11.Cu")
		(net "M_H_CPU1_SA_CA<0>")
	)
	(segment
		(start 192.597532 -263.19099)
		(end 191.35979 -263.19099)
		(width 0.18288)
		(layer "In11.Cu")
		(net "M_H_CPU1_SA_CA<0>")
	)
	(segment
		(start 139.286996 -255.05791)
		(end 139.272264 -255.049274)
		(width 0.088646)
		(layer "In11.Cu")
		(net "M_H_CPU1_SA_CA<0>")
	)
	(segment
		(start 134.587996 -255.05791)
		(end 134.573264 -255.049274)
		(width 0.088646)
		(layer "In11.Cu")
		(net "M_H_CPU1_SA_CA<0>")
	)
	(segment
		(start 123.184412 -255.276604)
		(end 123.027948 -255.547622)
		(width 0.088646)
		(layer "In11.Cu")
		(net "M_H_CPU1_SA_CA<0>")
	)
	(segment
		(start 133.09346 -255.051814)
		(end 133.083046 -255.05791)
		(width 0.088646)
		(layer "In11.Cu")
		(net "M_H_CPU1_SA_CA<0>")
	)
	(segment
		(start 125.945392 -255.05791)
		(end 125.66015 -255.223264)
		(width 0.088646)
		(layer "In11.Cu")
		(net "M_H_CPU1_SA_CA<0>")
	)
	(segment
		(start 164.595556 -262.520938)
		(end 164.2618 -262.187182)
		(width 0.18288)
		(layer "In11.Cu")
		(net "M_H_CPU1_SA_CA<0>")
	)
	(segment
		(start 126.13005 -255.05791)
		(end 125.945392 -255.05791)
		(width 0.088646)
		(layer "In11.Cu")
		(net "M_H_CPU1_SA_CA<0>")
	)
	(segment
		(start 180.007514 -262.970518)
		(end 179.655216 -263.322816)
		(width 0.18288)
		(layer "In11.Cu")
		(net "M_H_CPU1_SA_CA<0>")
	)
	(segment
		(start 131.757928 -255.051306)
		(end 131.753864 -255.049274)
		(width 0.088646)
		(layer "In11.Cu")
		(net "M_H_CPU1_SA_CA<0>")
	)
	(segment
		(start 188.86805 -262.340852)
		(end 187.559696 -262.340852)
		(width 0.18288)
		(layer "In11.Cu")
		(net "M_H_CPU1_SA_CA<0>")
	)
	(segment
		(start 201.46391 -265.136122)
		(end 200.266046 -263.938258)
		(width 0.18288)
		(layer "In11.Cu")
		(net "M_H_CPU1_SA_CA<0>")
	)
	(segment
		(start 138.347196 -255.05791)
		(end 138.332464 -255.049274)
		(width 0.088646)
		(layer "In11.Cu")
		(net "M_H_CPU1_SA_CA<0>")
	)
	(segment
		(start 132.153914 -255.051814)
		(end 132.1435 -255.05791)
		(width 0.088646)
		(layer "In11.Cu")
		(net "M_H_CPU1_SA_CA<0>")
	)
	(segment
		(start 189.042548 -262.51535)
		(end 188.86805 -262.340852)
		(width 0.18288)
		(layer "In11.Cu")
		(net "M_H_CPU1_SA_CA<0>")
	)
	(segment
		(start 202.908154 -265.866626)
		(end 202.17765 -265.136122)
		(width 0.18288)
		(layer "In11.Cu")
		(net "M_H_CPU1_SA_CA<0>")
	)
	(segment
		(start 161.522664 -262.187182)
		(end 161.348166 -262.36168)
		(width 0.18288)
		(layer "In11.Cu")
		(net "M_H_CPU1_SA_CA<0>")
	)
	(segment
		(start 176.27219 -263.19099)
		(end 175.593502 -262.512302)
		(width 0.18288)
		(layer "In11.Cu")
		(net "M_H_CPU1_SA_CA<0>")
	)
	(segment
		(start 137.407396 -255.05791)
		(end 137.392664 -255.049274)
		(width 0.088646)
		(layer "In11.Cu")
		(net "M_H_CPU1_SA_CA<0>")
	)
	(segment
		(start 158.683452 -261.375652)
		(end 156.76499 -261.375652)
		(width 0.18288)
		(layer "In11.Cu")
		(net "M_H_CPU1_SA_CA<0>")
	)
	(segment
		(start 141.887448 -255.147572)
		(end 140.18895 -255.147572)
		(width 0.18288)
		(layer "In11.Cu")
		(net "M_H_CPU1_SA_CA<0>")
	)
	(segment
		(start 168.608502 -262.520938)
		(end 164.595556 -262.520938)
		(width 0.18288)
		(layer "In11.Cu")
		(net "M_H_CPU1_SA_CA<0>")
	)
	(segment
		(start 185.986928 -262.130794)
		(end 184.770522 -263.3472)
		(width 0.18288)
		(layer "In11.Cu")
		(net "M_H_CPU1_SA_CA<0>")
	)
	(segment
		(start 177.91557 -263.19099)
		(end 176.27219 -263.19099)
		(width 0.18288)
		(layer "In11.Cu")
		(net "M_H_CPU1_SA_CA<0>")
	)
	(segment
		(start 140.18895 -255.147572)
		(end 139.40409 -255.147572)
		(width 0.088646)
		(layer "In11.Cu")
		(net "M_H_CPU1_SA_CA<0>")
	)
	(arc
		(start 128.934464 -255.049274)
		(mid 128.658023 -254.982108)
		(end 128.383792 -255.05791)
		(width 0.088646)
		(layer "In11.Cu")
		(net "M_H_CPU1_SA_CA<0>")
	)
	(arc
		(start 125.094492 -255.223264)
		(mid 124.907294 -255.173121)
		(end 124.720096 -255.223264)
		(width 0.088646)
		(layer "In11.Cu")
		(net "M_H_CPU1_SA_CA<0>")
	)
	(arc
		(start 127.994664 -255.049274)
		(mid 127.718223 -254.982108)
		(end 127.443992 -255.05791)
		(width 0.088646)
		(layer "In11.Cu")
		(net "M_H_CPU1_SA_CA<0>")
	)
	(arc
		(start 134.022592 -255.05791)
		(mid 133.835394 -255.108053)
		(end 133.648196 -255.05791)
		(width 0.088646)
		(layer "In11.Cu")
		(net "M_H_CPU1_SA_CA<0>")
	)
	(arc
		(start 128.383792 -255.05791)
		(mid 128.196594 -255.108053)
		(end 128.009396 -255.05791)
		(width 0.088646)
		(layer "In11.Cu")
		(net "M_H_CPU1_SA_CA<0>")
	)
	(arc
		(start 131.753864 -255.049274)
		(mid 131.477423 -254.982108)
		(end 131.203192 -255.05791)
		(width 0.088646)
		(layer "In11.Cu")
		(net "M_H_CPU1_SA_CA<0>")
	)
	(arc
		(start 133.083046 -255.05791)
		(mid 132.895848 -255.108053)
		(end 132.70865 -255.05791)
		(width 0.088646)
		(layer "In11.Cu")
		(net "M_H_CPU1_SA_CA<0>")
	)
	(arc
		(start 138.332464 -255.049274)
		(mid 138.055989 -254.981954)
		(end 137.781792 -255.05791)
		(width 0.088646)
		(layer "In11.Cu")
		(net "M_H_CPU1_SA_CA<0>")
	)
	(arc
		(start 138.721592 -255.05791)
		(mid 138.534394 -255.108053)
		(end 138.347196 -255.05791)
		(width 0.088646)
		(layer "In11.Cu")
		(net "M_H_CPU1_SA_CA<0>")
	)
	(arc
		(start 132.1435 -255.05791)
		(mid 131.956302 -255.108053)
		(end 131.769104 -255.05791)
		(width 0.088646)
		(layer "In11.Cu")
		(net "M_H_CPU1_SA_CA<0>")
	)
	(arc
		(start 131.203192 -255.05791)
		(mid 131.015994 -255.108053)
		(end 130.828796 -255.05791)
		(width 0.088646)
		(layer "In11.Cu")
		(net "M_H_CPU1_SA_CA<0>")
	)
	(arc
		(start 130.263392 -255.05791)
		(mid 130.076194 -255.108053)
		(end 129.888996 -255.05791)
		(width 0.088646)
		(layer "In11.Cu")
		(net "M_H_CPU1_SA_CA<0>")
	)
	(arc
		(start 135.902192 -255.05791)
		(mid 135.714994 -255.108053)
		(end 135.527796 -255.05791)
		(width 0.088646)
		(layer "In11.Cu")
		(net "M_H_CPU1_SA_CA<0>")
	)
	(arc
		(start 137.781792 -255.05791)
		(mid 137.594594 -255.108053)
		(end 137.407396 -255.05791)
		(width 0.088646)
		(layer "In11.Cu")
		(net "M_H_CPU1_SA_CA<0>")
	)
	(arc
		(start 139.40409 -255.147572)
		(mid 139.348485 -255.098898)
		(end 139.286996 -255.05791)
		(width 0.088646)
		(layer "In11.Cu")
		(net "M_H_CPU1_SA_CA<0>")
	)
	(arc
		(start 136.467596 -255.05791)
		(mid 136.184894 -254.982168)
		(end 135.902192 -255.05791)
		(width 0.088646)
		(layer "In11.Cu")
		(net "M_H_CPU1_SA_CA<0>")
	)
	(arc
		(start 125.66015 -255.223264)
		(mid 125.383337 -255.2991)
		(end 125.104906 -255.22936)
		(width 0.088646)
		(layer "In11.Cu")
		(net "M_H_CPU1_SA_CA<0>")
	)
	(arc
		(start 127.443992 -255.05791)
		(mid 127.256794 -255.108053)
		(end 127.069596 -255.05791)
		(width 0.088646)
		(layer "In11.Cu")
		(net "M_H_CPU1_SA_CA<0>")
	)
	(arc
		(start 129.874264 -255.049274)
		(mid 129.597823 -254.982108)
		(end 129.323592 -255.05791)
		(width 0.088646)
		(layer "In11.Cu")
		(net "M_H_CPU1_SA_CA<0>")
	)
	(arc
		(start 127.069596 -255.05791)
		(mid 126.793037 -254.982201)
		(end 126.51486 -255.051814)
		(width 0.088646)
		(layer "In11.Cu")
		(net "M_H_CPU1_SA_CA<0>")
	)
	(arc
		(start 124.154946 -255.223264)
		(mid 123.967748 -255.173121)
		(end 123.78055 -255.223264)
		(width 0.088646)
		(layer "In11.Cu")
		(net "M_H_CPU1_SA_CA<0>")
	)
	(arc
		(start 126.504446 -255.05791)
		(mid 126.317248 -255.108053)
		(end 126.13005 -255.05791)
		(width 0.088646)
		(layer "In11.Cu")
		(net "M_H_CPU1_SA_CA<0>")
	)
	(arc
		(start 135.527796 -255.05791)
		(mid 135.245094 -254.982168)
		(end 134.962392 -255.05791)
		(width 0.088646)
		(layer "In11.Cu")
		(net "M_H_CPU1_SA_CA<0>")
	)
	(arc
		(start 132.70865 -255.05791)
		(mid 132.432091 -254.982201)
		(end 132.153914 -255.051814)
		(width 0.088646)
		(layer "In11.Cu")
		(net "M_H_CPU1_SA_CA<0>")
	)
	(arc
		(start 134.573264 -255.049274)
		(mid 134.296823 -254.982108)
		(end 134.022592 -255.05791)
		(width 0.088646)
		(layer "In11.Cu")
		(net "M_H_CPU1_SA_CA<0>")
	)
	(arc
		(start 133.648196 -255.05791)
		(mid 133.371637 -254.982201)
		(end 133.09346 -255.051814)
		(width 0.088646)
		(layer "In11.Cu")
		(net "M_H_CPU1_SA_CA<0>")
	)
	(arc
		(start 124.709682 -255.22936)
		(mid 124.431504 -255.299052)
		(end 124.154946 -255.223264)
		(width 0.088646)
		(layer "In11.Cu")
		(net "M_H_CPU1_SA_CA<0>")
	)
	(arc
		(start 136.841992 -255.05791)
		(mid 136.654794 -255.108053)
		(end 136.467596 -255.05791)
		(width 0.088646)
		(layer "In11.Cu")
		(net "M_H_CPU1_SA_CA<0>")
	)
	(arc
		(start 137.392664 -255.049274)
		(mid 137.116189 -254.981954)
		(end 136.841992 -255.05791)
		(width 0.088646)
		(layer "In11.Cu")
		(net "M_H_CPU1_SA_CA<0>")
	)
	(arc
		(start 129.323592 -255.05791)
		(mid 129.136394 -255.108053)
		(end 128.949196 -255.05791)
		(width 0.088646)
		(layer "In11.Cu")
		(net "M_H_CPU1_SA_CA<0>")
	)
	(arc
		(start 139.272264 -255.049274)
		(mid 138.995789 -254.981954)
		(end 138.721592 -255.05791)
		(width 0.088646)
		(layer "In11.Cu")
		(net "M_H_CPU1_SA_CA<0>")
	)
	(arc
		(start 134.962392 -255.05791)
		(mid 134.775194 -255.108053)
		(end 134.587996 -255.05791)
		(width 0.088646)
		(layer "In11.Cu")
		(net "M_H_CPU1_SA_CA<0>")
	)
	(arc
		(start 130.814064 -255.049274)
		(mid 130.537623 -254.982108)
		(end 130.263392 -255.05791)
		(width 0.088646)
		(layer "In11.Cu")
		(net "M_H_CPU1_SA_CA<0>")
	)
	(arc
		(start 123.78055 -255.223264)
		(mid 123.530453 -255.29829)
		(end 123.273312 -255.252982)
		(width 0.088646)
		(layer "In11.Cu")
		(net "M_H_CPU1_SA_CA<0>")
	)
	(segment
		(start 122.917712 -247.714262)
		(end 122.917966 -247.714008)
		(width 0.20066)
		(layer "F.Cu")
		(net "M_H_CPU1_CLK_DP<1>")
	)
	(segment
		(start 208.176114 -260.21665)
		(end 207.071214 -260.21665)
		(width 0.20066)
		(layer "F.Cu")
		(net "M_H_CPU1_CLK_DP<1>")
	)
	(segment
		(start 122.917966 -247.714008)
		(end 122.917966 -247.178322)
		(width 0.20066)
		(layer "F.Cu")
		(net "M_H_CPU1_CLK_DP<1>")
	)
	(segment
		(start 152.945846 -253.352046)
		(end 148.31695 -253.352046)
		(width 0.18288)
		(layer "In11.Cu")
		(net "M_H_CPU1_CLK_DP<1>")
	)
	(segment
		(start 158.491682 -256.011934)
		(end 157.325314 -256.011934)
		(width 0.18288)
		(layer "In11.Cu")
		(net "M_H_CPU1_CLK_DP<1>")
	)
	(segment
		(start 124.70257 -250.693428)
		(end 124.70257 -249.620024)
		(width 0.088646)
		(layer "In11.Cu")
		(net "M_H_CPU1_CLK_DP<1>")
	)
	(segment
		(start 206.453486 -259.950458)
		(end 204.669136 -259.438394)
		(width 0.18288)
		(layer "In11.Cu")
		(net "M_H_CPU1_CLK_DP<1>")
	)
	(segment
		(start 161.028634 -257.062732)
		(end 158.491682 -256.011934)
		(width 0.18288)
		(layer "In11.Cu")
		(net "M_H_CPU1_CLK_DP<1>")
	)
	(segment
		(start 125.095254 -251.75083)
		(end 124.64288 -251.298456)
		(width 0.18288)
		(layer "In11.Cu")
		(net "M_H_CPU1_CLK_DP<1>")
	)
	(segment
		(start 124.5235 -249.300746)
		(end 124.515626 -249.296174)
		(width 0.088646)
		(layer "In11.Cu")
		(net "M_H_CPU1_CLK_DP<1>")
	)
	(segment
		(start 123.230894 -247.178322)
		(end 122.917966 -247.178322)
		(width 0.088646)
		(layer "In11.Cu")
		(net "M_H_CPU1_CLK_DP<1>")
	)
	(segment
		(start 155.882086 -254.568452)
		(end 152.945846 -253.352046)
		(width 0.18288)
		(layer "In11.Cu")
		(net "M_H_CPU1_CLK_DP<1>")
	)
	(segment
		(start 206.805022 -259.950458)
		(end 206.453486 -259.950458)
		(width 0.18288)
		(layer "In11.Cu")
		(net "M_H_CPU1_CLK_DP<1>")
	)
	(segment
		(start 134.449058 -252.068076)
		(end 134.131812 -251.75083)
		(width 0.18288)
		(layer "In11.Cu")
		(net "M_H_CPU1_CLK_DP<1>")
	)
	(segment
		(start 123.296172 -247.2436)
		(end 123.230894 -247.178322)
		(width 0.088646)
		(layer "In11.Cu")
		(net "M_H_CPU1_CLK_DP<1>")
	)
	(segment
		(start 124.515626 -249.296174)
		(end 124.51461 -249.295666)
		(width 0.088646)
		(layer "In11.Cu")
		(net "M_H_CPU1_CLK_DP<1>")
	)
	(segment
		(start 124.64288 -251.298456)
		(end 124.64288 -250.753118)
		(width 0.18288)
		(layer "In11.Cu")
		(net "M_H_CPU1_CLK_DP<1>")
	)
	(segment
		(start 123.5837 -247.67286)
		(end 123.57481 -247.66778)
		(width 0.088646)
		(layer "In11.Cu")
		(net "M_H_CPU1_CLK_DP<1>")
	)
	(segment
		(start 142.282418 -252.068076)
		(end 134.449058 -252.068076)
		(width 0.18288)
		(layer "In11.Cu")
		(net "M_H_CPU1_CLK_DP<1>")
	)
	(segment
		(start 195.612512 -257.062732)
		(end 161.028634 -257.062732)
		(width 0.18288)
		(layer "In11.Cu")
		(net "M_H_CPU1_CLK_DP<1>")
	)
	(segment
		(start 144.76857 -254.554228)
		(end 142.282418 -252.068076)
		(width 0.18288)
		(layer "In11.Cu")
		(net "M_H_CPU1_CLK_DP<1>")
	)
	(segment
		(start 157.325314 -256.011934)
		(end 155.882086 -254.568452)
		(width 0.18288)
		(layer "In11.Cu")
		(net "M_H_CPU1_CLK_DP<1>")
	)
	(segment
		(start 147.114768 -254.554228)
		(end 144.76857 -254.554228)
		(width 0.183134)
		(layer "In11.Cu")
		(net "M_H_CPU1_CLK_DP<1>")
	)
	(segment
		(start 124.523754 -249.300492)
		(end 124.5235 -249.300746)
		(width 0.088646)
		(layer "In11.Cu")
		(net "M_H_CPU1_CLK_DP<1>")
	)
	(segment
		(start 204.669136 -259.438394)
		(end 203.166218 -257.935476)
		(width 0.18288)
		(layer "In11.Cu")
		(net "M_H_CPU1_CLK_DP<1>")
	)
	(segment
		(start 148.31695 -253.352046)
		(end 147.114768 -254.554228)
		(width 0.18288)
		(layer "In11.Cu")
		(net "M_H_CPU1_CLK_DP<1>")
	)
	(segment
		(start 123.762262 -248.006362)
		(end 123.762262 -247.992138)
		(width 0.088646)
		(layer "In11.Cu")
		(net "M_H_CPU1_CLK_DP<1>")
	)
	(segment
		(start 124.64288 -250.753118)
		(end 124.70257 -250.693428)
		(width 0.088646)
		(layer "In11.Cu")
		(net "M_H_CPU1_CLK_DP<1>")
	)
	(segment
		(start 203.166218 -257.935476)
		(end 195.612512 -257.062732)
		(width 0.18288)
		(layer "In11.Cu")
		(net "M_H_CPU1_CLK_DP<1>")
	)
	(segment
		(start 124.053854 -248.48693)
		(end 124.044964 -248.48185)
		(width 0.088646)
		(layer "In11.Cu")
		(net "M_H_CPU1_CLK_DP<1>")
	)
	(segment
		(start 207.071214 -260.21665)
		(end 206.805022 -259.950458)
		(width 0.18288)
		(layer "In11.Cu")
		(net "M_H_CPU1_CLK_DP<1>")
	)
	(segment
		(start 134.131812 -251.75083)
		(end 125.095254 -251.75083)
		(width 0.18288)
		(layer "In11.Cu")
		(net "M_H_CPU1_CLK_DP<1>")
	)
	(segment
		(start 124.232416 -248.821702)
		(end 124.232416 -248.806208)
		(width 0.088646)
		(layer "In11.Cu")
		(net "M_H_CPU1_CLK_DP<1>")
	)
	(arc
		(start 123.762262 -247.992138)
		(mid 123.714583 -247.809238)
		(end 123.5837 -247.67286)
		(width 0.088646)
		(layer "In11.Cu")
		(net "M_H_CPU1_CLK_DP<1>")
	)
	(arc
		(start 123.298966 -247.264682)
		(mid 123.29747 -247.254154)
		(end 123.296172 -247.2436)
		(width 0.088646)
		(layer "In11.Cu")
		(net "M_H_CPU1_CLK_DP<1>")
	)
	(arc
		(start 123.57481 -247.66778)
		(mid 123.391148 -247.497541)
		(end 123.298966 -247.264682)
		(width 0.088646)
		(layer "In11.Cu")
		(net "M_H_CPU1_CLK_DP<1>")
	)
	(arc
		(start 124.232416 -248.806208)
		(mid 124.184737 -248.623308)
		(end 124.053854 -248.48693)
		(width 0.088646)
		(layer "In11.Cu")
		(net "M_H_CPU1_CLK_DP<1>")
	)
	(arc
		(start 124.70257 -249.620024)
		(mid 124.654826 -249.436942)
		(end 124.523754 -249.300492)
		(width 0.088646)
		(layer "In11.Cu")
		(net "M_H_CPU1_CLK_DP<1>")
	)
	(arc
		(start 124.044964 -248.48185)
		(mid 123.841483 -248.281046)
		(end 123.762262 -248.006362)
		(width 0.088646)
		(layer "In11.Cu")
		(net "M_H_CPU1_CLK_DP<1>")
	)
	(arc
		(start 124.51461 -249.295666)
		(mid 124.311787 -249.095435)
		(end 124.232416 -248.821702)
		(width 0.088646)
		(layer "In11.Cu")
		(net "M_H_CPU1_CLK_DP<1>")
	)
	(segment
		(start 124.797312 -247.714262)
		(end 124.797566 -247.714008)
		(width 0.20066)
		(layer "F.Cu")
		(net "M_H_CPU1_CLK_DP<0>")
	)
	(segment
		(start 124.797566 -247.714008)
		(end 124.797566 -247.178322)
		(width 0.20066)
		(layer "F.Cu")
		(net "M_H_CPU1_CLK_DP<0>")
	)
	(segment
		(start 215.719914 -260.21665)
		(end 214.615014 -260.21665)
		(width 0.20066)
		(layer "F.Cu")
		(net "M_H_CPU1_CLK_DP<0>")
	)
	(segment
		(start 158.356554 -255.060704)
		(end 157.56763 -255.060704)
		(width 0.18288)
		(layer "In11.Cu")
		(net "M_H_CPU1_CLK_DP<0>")
	)
	(segment
		(start 156.015436 -253.50851)
		(end 152.922986 -252.462538)
		(width 0.18288)
		(layer "In11.Cu")
		(net "M_H_CPU1_CLK_DP<0>")
	)
	(segment
		(start 150.129494 -252.462538)
		(end 146.966686 -249.29973)
		(width 0.18288)
		(layer "In11.Cu")
		(net "M_H_CPU1_CLK_DP<0>")
	)
	(segment
		(start 126.398782 -249.298206)
		(end 126.39421 -249.295666)
		(width 0.088646)
		(layer "In11.Cu")
		(net "M_H_CPU1_CLK_DP<0>")
	)
	(segment
		(start 125.933454 -248.48693)
		(end 125.924564 -248.48185)
		(width 0.088646)
		(layer "In11.Cu")
		(net "M_H_CPU1_CLK_DP<0>")
	)
	(segment
		(start 125.4633 -247.67286)
		(end 125.455426 -247.668288)
		(width 0.088646)
		(layer "In11.Cu")
		(net "M_H_CPU1_CLK_DP<0>")
	)
	(segment
		(start 207.885284 -258.373118)
		(end 204.998828 -257.17754)
		(width 0.18288)
		(layer "In11.Cu")
		(net "M_H_CPU1_CLK_DP<0>")
	)
	(segment
		(start 204.998828 -257.17754)
		(end 194.584574 -256.076196)
		(width 0.18288)
		(layer "In11.Cu")
		(net "M_H_CPU1_CLK_DP<0>")
	)
	(segment
		(start 209.266282 -259.754116)
		(end 207.885284 -258.373118)
		(width 0.18288)
		(layer "In11.Cu")
		(net "M_H_CPU1_CLK_DP<0>")
	)
	(segment
		(start 135.388858 -251.380498)
		(end 134.84733 -250.83897)
		(width 0.18288)
		(layer "In11.Cu")
		(net "M_H_CPU1_CLK_DP<0>")
	)
	(segment
		(start 140.39342 -251.380498)
		(end 135.388858 -251.380498)
		(width 0.18288)
		(layer "In11.Cu")
		(net "M_H_CPU1_CLK_DP<0>")
	)
	(segment
		(start 125.455426 -247.668288)
		(end 125.45441 -247.66778)
		(width 0.088646)
		(layer "In11.Cu")
		(net "M_H_CPU1_CLK_DP<0>")
	)
	(segment
		(start 213.20887 -259.754116)
		(end 209.266282 -259.754116)
		(width 0.18288)
		(layer "In11.Cu")
		(net "M_H_CPU1_CLK_DP<0>")
	)
	(segment
		(start 145.043398 -249.453146)
		(end 140.39342 -251.380498)
		(width 0.18288)
		(layer "In11.Cu")
		(net "M_H_CPU1_CLK_DP<0>")
	)
	(segment
		(start 134.84733 -250.83897)
		(end 127.119126 -250.83897)
		(width 0.18288)
		(layer "In11.Cu")
		(net "M_H_CPU1_CLK_DP<0>")
	)
	(segment
		(start 126.112016 -248.821702)
		(end 126.112016 -248.806208)
		(width 0.088646)
		(layer "In11.Cu")
		(net "M_H_CPU1_CLK_DP<0>")
	)
	(segment
		(start 126.581916 -250.216924)
		(end 126.581916 -249.61977)
		(width 0.088646)
		(layer "In11.Cu")
		(net "M_H_CPU1_CLK_DP<0>")
	)
	(segment
		(start 146.966686 -249.29973)
		(end 145.809716 -249.29973)
		(width 0.18288)
		(layer "In11.Cu")
		(net "M_H_CPU1_CLK_DP<0>")
	)
	(segment
		(start 152.922986 -252.462538)
		(end 150.129494 -252.462538)
		(width 0.18288)
		(layer "In11.Cu")
		(net "M_H_CPU1_CLK_DP<0>")
	)
	(segment
		(start 125.11024 -247.178322)
		(end 124.797566 -247.178322)
		(width 0.088646)
		(layer "In11.Cu")
		(net "M_H_CPU1_CLK_DP<0>")
	)
	(segment
		(start 126.894082 -250.613926)
		(end 126.894082 -250.52909)
		(width 0.088646)
		(layer "In11.Cu")
		(net "M_H_CPU1_CLK_DP<0>")
	)
	(segment
		(start 126.894082 -250.52909)
		(end 126.581916 -250.216924)
		(width 0.088646)
		(layer "In11.Cu")
		(net "M_H_CPU1_CLK_DP<0>")
	)
	(segment
		(start 126.400814 -249.299476)
		(end 126.398782 -249.298206)
		(width 0.088646)
		(layer "In11.Cu")
		(net "M_H_CPU1_CLK_DP<0>")
	)
	(segment
		(start 214.615014 -260.21665)
		(end 214.339678 -259.941314)
		(width 0.18288)
		(layer "In11.Cu")
		(net "M_H_CPU1_CLK_DP<0>")
	)
	(segment
		(start 145.809716 -249.29973)
		(end 145.043398 -249.453146)
		(width 0.18288)
		(layer "In11.Cu")
		(net "M_H_CPU1_CLK_DP<0>")
	)
	(segment
		(start 214.339678 -259.941314)
		(end 213.396068 -259.941314)
		(width 0.18288)
		(layer "In11.Cu")
		(net "M_H_CPU1_CLK_DP<0>")
	)
	(segment
		(start 157.56763 -255.060704)
		(end 156.015436 -253.50851)
		(width 0.18288)
		(layer "In11.Cu")
		(net "M_H_CPU1_CLK_DP<0>")
	)
	(segment
		(start 125.641862 -247.999758)
		(end 125.641862 -247.992138)
		(width 0.088646)
		(layer "In11.Cu")
		(net "M_H_CPU1_CLK_DP<0>")
	)
	(segment
		(start 125.175772 -247.243854)
		(end 125.11024 -247.178322)
		(width 0.088646)
		(layer "In11.Cu")
		(net "M_H_CPU1_CLK_DP<0>")
	)
	(segment
		(start 126.581916 -249.61977)
		(end 126.581662 -249.620024)
		(width 0.088646)
		(layer "In11.Cu")
		(net "M_H_CPU1_CLK_DP<0>")
	)
	(segment
		(start 161.62782 -256.076196)
		(end 158.356554 -255.060704)
		(width 0.18288)
		(layer "In11.Cu")
		(net "M_H_CPU1_CLK_DP<0>")
	)
	(segment
		(start 213.396068 -259.941314)
		(end 213.20887 -259.754116)
		(width 0.18288)
		(layer "In11.Cu")
		(net "M_H_CPU1_CLK_DP<0>")
	)
	(segment
		(start 127.119126 -250.83897)
		(end 126.894082 -250.613926)
		(width 0.18288)
		(layer "In11.Cu")
		(net "M_H_CPU1_CLK_DP<0>")
	)
	(segment
		(start 126.4031 -249.300746)
		(end 126.400814 -249.299476)
		(width 0.088646)
		(layer "In11.Cu")
		(net "M_H_CPU1_CLK_DP<0>")
	)
	(segment
		(start 194.584574 -256.076196)
		(end 161.62782 -256.076196)
		(width 0.18288)
		(layer "In11.Cu")
		(net "M_H_CPU1_CLK_DP<0>")
	)
	(arc
		(start 126.112016 -248.806208)
		(mid 126.064337 -248.623308)
		(end 125.933454 -248.48693)
		(width 0.088646)
		(layer "In11.Cu")
		(net "M_H_CPU1_CLK_DP<0>")
	)
	(arc
		(start 125.924564 -248.48185)
		(mid 125.719492 -248.278171)
		(end 125.641862 -247.999758)
		(width 0.088646)
		(layer "In11.Cu")
		(net "M_H_CPU1_CLK_DP<0>")
	)
	(arc
		(start 125.178566 -247.264936)
		(mid 125.17707 -247.254408)
		(end 125.175772 -247.243854)
		(width 0.088646)
		(layer "In11.Cu")
		(net "M_H_CPU1_CLK_DP<0>")
	)
	(arc
		(start 125.45441 -247.66778)
		(mid 125.270819 -247.497645)
		(end 125.178566 -247.264936)
		(width 0.088646)
		(layer "In11.Cu")
		(net "M_H_CPU1_CLK_DP<0>")
	)
	(arc
		(start 126.581662 -249.620024)
		(mid 126.533983 -249.437124)
		(end 126.4031 -249.300746)
		(width 0.088646)
		(layer "In11.Cu")
		(net "M_H_CPU1_CLK_DP<0>")
	)
	(arc
		(start 126.39421 -249.295666)
		(mid 126.191387 -249.095435)
		(end 126.112016 -248.821702)
		(width 0.088646)
		(layer "In11.Cu")
		(net "M_H_CPU1_CLK_DP<0>")
	)
	(arc
		(start 125.641862 -247.992138)
		(mid 125.594183 -247.809238)
		(end 125.4633 -247.67286)
		(width 0.088646)
		(layer "In11.Cu")
		(net "M_H_CPU1_CLK_DP<0>")
	)
	(segment
		(start 123.857512 -247.714262)
		(end 123.857766 -247.714008)
		(width 0.20066)
		(layer "F.Cu")
		(net "M_H_CPU1_CLK_DN<1>")
	)
	(segment
		(start 207.071214 -259.366766)
		(end 208.176114 -259.366766)
		(width 0.20066)
		(layer "F.Cu")
		(net "M_H_CPU1_CLK_DN<1>")
	)
	(segment
		(start 123.857766 -247.714008)
		(end 123.857766 -247.178322)
		(width 0.20066)
		(layer "F.Cu")
		(net "M_H_CPU1_CLK_DN<1>")
	)
	(segment
		(start 123.487688 -247.235472)
		(end 123.544838 -247.178322)
		(width 0.088646)
		(layer "In11.Cu")
		(net "M_H_CPU1_CLK_DN<1>")
	)
	(segment
		(start 203.30922 -257.63982)
		(end 195.630546 -256.752852)
		(width 0.18288)
		(layer "In11.Cu")
		(net "M_H_CPU1_CLK_DN<1>")
	)
	(segment
		(start 124.616464 -249.134122)
		(end 124.61494 -249.13336)
		(width 0.088646)
		(layer "In11.Cu")
		(net "M_H_CPU1_CLK_DN<1>")
	)
	(segment
		(start 203.986384 -258.144518)
		(end 203.813918 -258.144518)
		(width 0.18288)
		(layer "In11.Cu")
		(net "M_H_CPU1_CLK_DN<1>")
	)
	(segment
		(start 204.831696 -259.16255)
		(end 204.363828 -258.694428)
		(width 0.18288)
		(layer "In11.Cu")
		(net "M_H_CPU1_CLK_DN<1>")
	)
	(segment
		(start 189.898528 -256.752852)
		(end 189.776608 -256.630932)
		(width 0.18288)
		(layer "In11.Cu")
		(net "M_H_CPU1_CLK_DN<1>")
	)
	(segment
		(start 134.577582 -251.758196)
		(end 134.260336 -251.44095)
		(width 0.18288)
		(layer "In11.Cu")
		(net "M_H_CPU1_CLK_DN<1>")
	)
	(segment
		(start 191.742568 -256.752852)
		(end 191.209168 -256.752852)
		(width 0.18288)
		(layer "In11.Cu")
		(net "M_H_CPU1_CLK_DN<1>")
	)
	(segment
		(start 124.95276 -250.753118)
		(end 124.892816 -250.693174)
		(width 0.088646)
		(layer "In11.Cu")
		(net "M_H_CPU1_CLK_DN<1>")
	)
	(segment
		(start 192.397888 -256.630932)
		(end 191.864488 -256.630932)
		(width 0.18288)
		(layer "In11.Cu")
		(net "M_H_CPU1_CLK_DN<1>")
	)
	(segment
		(start 190.431928 -256.752852)
		(end 189.898528 -256.752852)
		(width 0.18288)
		(layer "In11.Cu")
		(net "M_H_CPU1_CLK_DN<1>")
	)
	(segment
		(start 142.410942 -251.758196)
		(end 134.577582 -251.758196)
		(width 0.18288)
		(layer "In11.Cu")
		(net "M_H_CPU1_CLK_DN<1>")
	)
	(segment
		(start 124.61494 -249.13336)
		(end 124.610368 -249.130566)
		(width 0.088646)
		(layer "In11.Cu")
		(net "M_H_CPU1_CLK_DN<1>")
	)
	(segment
		(start 189.121288 -256.752852)
		(end 161.090356 -256.752852)
		(width 0.18288)
		(layer "In11.Cu")
		(net "M_H_CPU1_CLK_DN<1>")
	)
	(segment
		(start 191.087248 -256.630932)
		(end 190.553848 -256.630932)
		(width 0.18288)
		(layer "In11.Cu")
		(net "M_H_CPU1_CLK_DN<1>")
	)
	(segment
		(start 191.864488 -256.630932)
		(end 191.742568 -256.752852)
		(width 0.18288)
		(layer "In11.Cu")
		(net "M_H_CPU1_CLK_DN<1>")
	)
	(segment
		(start 125.223778 -251.44095)
		(end 124.95276 -251.169932)
		(width 0.18288)
		(layer "In11.Cu")
		(net "M_H_CPU1_CLK_DN<1>")
	)
	(segment
		(start 123.544838 -247.178322)
		(end 123.857766 -247.178322)
		(width 0.088646)
		(layer "In11.Cu")
		(net "M_H_CPU1_CLK_DN<1>")
	)
	(segment
		(start 123.670568 -247.50268)
		(end 123.661678 -247.4976)
		(width 0.088646)
		(layer "In11.Cu")
		(net "M_H_CPU1_CLK_DN<1>")
	)
	(segment
		(start 191.209168 -256.752852)
		(end 191.087248 -256.630932)
		(width 0.18288)
		(layer "In11.Cu")
		(net "M_H_CPU1_CLK_DN<1>")
	)
	(segment
		(start 190.553848 -256.630932)
		(end 190.431928 -256.752852)
		(width 0.18288)
		(layer "In11.Cu")
		(net "M_H_CPU1_CLK_DN<1>")
	)
	(segment
		(start 124.892816 -250.693174)
		(end 124.892816 -249.620024)
		(width 0.088646)
		(layer "In11.Cu")
		(net "M_H_CPU1_CLK_DN<1>")
	)
	(segment
		(start 153.007568 -253.042166)
		(end 148.188426 -253.042166)
		(width 0.18288)
		(layer "In11.Cu")
		(net "M_H_CPU1_CLK_DN<1>")
	)
	(segment
		(start 207.071214 -259.366766)
		(end 207.060292 -259.366766)
		(width 0.18288)
		(layer "In11.Cu")
		(net "M_H_CPU1_CLK_DN<1>")
	)
	(segment
		(start 144.89684 -254.244094)
		(end 142.410942 -251.758196)
		(width 0.18288)
		(layer "In11.Cu")
		(net "M_H_CPU1_CLK_DN<1>")
	)
	(segment
		(start 192.519808 -256.752852)
		(end 192.397888 -256.630932)
		(width 0.18288)
		(layer "In11.Cu")
		(net "M_H_CPU1_CLK_DN<1>")
	)
	(segment
		(start 123.952762 -247.992138)
		(end 123.952762 -247.976644)
		(width 0.088646)
		(layer "In11.Cu")
		(net "M_H_CPU1_CLK_DN<1>")
	)
	(segment
		(start 124.95276 -251.169932)
		(end 124.95276 -250.753118)
		(width 0.18288)
		(layer "In11.Cu")
		(net "M_H_CPU1_CLK_DN<1>")
	)
	(segment
		(start 195.630546 -256.752852)
		(end 193.830448 -256.752852)
		(width 0.18288)
		(layer "In11.Cu")
		(net "M_H_CPU1_CLK_DN<1>")
	)
	(segment
		(start 193.175128 -256.630932)
		(end 193.053208 -256.752852)
		(width 0.18288)
		(layer "In11.Cu")
		(net "M_H_CPU1_CLK_DN<1>")
	)
	(segment
		(start 204.363828 -258.521962)
		(end 203.986384 -258.144518)
		(width 0.18288)
		(layer "In11.Cu")
		(net "M_H_CPU1_CLK_DN<1>")
	)
	(segment
		(start 206.497174 -259.640578)
		(end 204.831696 -259.16255)
		(width 0.18288)
		(layer "In11.Cu")
		(net "M_H_CPU1_CLK_DN<1>")
	)
	(segment
		(start 207.060292 -259.366766)
		(end 206.78648 -259.640578)
		(width 0.18288)
		(layer "In11.Cu")
		(net "M_H_CPU1_CLK_DN<1>")
	)
	(segment
		(start 189.776608 -256.630932)
		(end 189.243208 -256.630932)
		(width 0.18288)
		(layer "In11.Cu")
		(net "M_H_CPU1_CLK_DN<1>")
	)
	(segment
		(start 124.140214 -248.316496)
		(end 124.131324 -248.311416)
		(width 0.088646)
		(layer "In11.Cu")
		(net "M_H_CPU1_CLK_DN<1>")
	)
	(segment
		(start 203.813918 -258.144518)
		(end 203.30922 -257.63982)
		(width 0.18288)
		(layer "In11.Cu")
		(net "M_H_CPU1_CLK_DN<1>")
	)
	(segment
		(start 161.090356 -256.752852)
		(end 158.553404 -255.702054)
		(width 0.18288)
		(layer "In11.Cu")
		(net "M_H_CPU1_CLK_DN<1>")
	)
	(segment
		(start 146.986498 -254.244094)
		(end 144.89684 -254.244094)
		(width 0.18288)
		(layer "In11.Cu")
		(net "M_H_CPU1_CLK_DN<1>")
	)
	(segment
		(start 134.260336 -251.44095)
		(end 125.223778 -251.44095)
		(width 0.18288)
		(layer "In11.Cu")
		(net "M_H_CPU1_CLK_DN<1>")
	)
	(segment
		(start 124.610368 -249.130566)
		(end 124.601478 -249.125486)
		(width 0.088646)
		(layer "In11.Cu")
		(net "M_H_CPU1_CLK_DN<1>")
	)
	(segment
		(start 124.422916 -248.806208)
		(end 124.422916 -248.791984)
		(width 0.088646)
		(layer "In11.Cu")
		(net "M_H_CPU1_CLK_DN<1>")
	)
	(segment
		(start 193.830448 -256.752852)
		(end 193.708528 -256.630932)
		(width 0.18288)
		(layer "In11.Cu")
		(net "M_H_CPU1_CLK_DN<1>")
	)
	(segment
		(start 157.453838 -255.702054)
		(end 156.057854 -254.305562)
		(width 0.18288)
		(layer "In11.Cu")
		(net "M_H_CPU1_CLK_DN<1>")
	)
	(segment
		(start 193.053208 -256.752852)
		(end 192.519808 -256.752852)
		(width 0.18288)
		(layer "In11.Cu")
		(net "M_H_CPU1_CLK_DN<1>")
	)
	(segment
		(start 148.188426 -253.042166)
		(end 146.986498 -254.244094)
		(width 0.18288)
		(layer "In11.Cu")
		(net "M_H_CPU1_CLK_DN<1>")
	)
	(segment
		(start 158.553404 -255.702054)
		(end 157.453838 -255.702054)
		(width 0.18288)
		(layer "In11.Cu")
		(net "M_H_CPU1_CLK_DN<1>")
	)
	(segment
		(start 204.363828 -258.694428)
		(end 204.363828 -258.521962)
		(width 0.18288)
		(layer "In11.Cu")
		(net "M_H_CPU1_CLK_DN<1>")
	)
	(segment
		(start 156.057854 -254.305562)
		(end 153.007568 -253.042166)
		(width 0.18288)
		(layer "In11.Cu")
		(net "M_H_CPU1_CLK_DN<1>")
	)
	(segment
		(start 206.78648 -259.640578)
		(end 206.497174 -259.640578)
		(width 0.18288)
		(layer "In11.Cu")
		(net "M_H_CPU1_CLK_DN<1>")
	)
	(segment
		(start 189.243208 -256.630932)
		(end 189.121288 -256.752852)
		(width 0.18288)
		(layer "In11.Cu")
		(net "M_H_CPU1_CLK_DN<1>")
	)
	(segment
		(start 193.708528 -256.630932)
		(end 193.175128 -256.630932)
		(width 0.18288)
		(layer "In11.Cu")
		(net "M_H_CPU1_CLK_DN<1>")
	)
	(arc
		(start 123.952762 -247.976644)
		(mid 123.873392 -247.70291)
		(end 123.670568 -247.50268)
		(width 0.088646)
		(layer "In11.Cu")
		(net "M_H_CPU1_CLK_DN<1>")
	)
	(arc
		(start 124.892816 -249.620024)
		(mid 124.8189 -249.340522)
		(end 124.616464 -249.134122)
		(width 0.088646)
		(layer "In11.Cu")
		(net "M_H_CPU1_CLK_DN<1>")
	)
	(arc
		(start 123.661678 -247.4976)
		(mid 123.545869 -247.385671)
		(end 123.487688 -247.235472)
		(width 0.088646)
		(layer "In11.Cu")
		(net "M_H_CPU1_CLK_DN<1>")
	)
	(arc
		(start 124.131324 -248.311416)
		(mid 124.00041 -248.175056)
		(end 123.952762 -247.992138)
		(width 0.088646)
		(layer "In11.Cu")
		(net "M_H_CPU1_CLK_DN<1>")
	)
	(arc
		(start 124.601478 -249.125486)
		(mid 124.470564 -248.989126)
		(end 124.422916 -248.806208)
		(width 0.088646)
		(layer "In11.Cu")
		(net "M_H_CPU1_CLK_DN<1>")
	)
	(arc
		(start 124.422916 -248.791984)
		(mid 124.343697 -248.517299)
		(end 124.140214 -248.316496)
		(width 0.088646)
		(layer "In11.Cu")
		(net "M_H_CPU1_CLK_DN<1>")
	)
	(segment
		(start 214.615014 -259.366766)
		(end 215.719914 -259.366766)
		(width 0.20066)
		(layer "F.Cu")
		(net "M_H_CPU1_CLK_DN<0>")
	)
	(segment
		(start 125.737112 -247.714262)
		(end 125.737366 -247.714008)
		(width 0.20066)
		(layer "F.Cu")
		(net "M_H_CPU1_CLK_DN<0>")
	)
	(segment
		(start 125.737366 -247.714008)
		(end 125.737366 -247.178322)
		(width 0.20066)
		(layer "F.Cu")
		(net "M_H_CPU1_CLK_DN<0>")
	)
	(segment
		(start 125.424692 -247.178322)
		(end 125.737366 -247.178322)
		(width 0.088646)
		(layer "In11.Cu")
		(net "M_H_CPU1_CLK_DN<0>")
	)
	(segment
		(start 158.403798 -254.750824)
		(end 157.696154 -254.750824)
		(width 0.18288)
		(layer "In11.Cu")
		(net "M_H_CPU1_CLK_DN<0>")
	)
	(segment
		(start 209.394806 -259.444236)
		(end 208.061052 -258.110228)
		(width 0.18288)
		(layer "In11.Cu")
		(net "M_H_CPU1_CLK_DN<0>")
	)
	(segment
		(start 211.946236 -259.322316)
		(end 211.824316 -259.444236)
		(width 0.18288)
		(layer "In11.Cu")
		(net "M_H_CPU1_CLK_DN<0>")
	)
	(segment
		(start 152.97404 -252.152658)
		(end 150.258018 -252.152658)
		(width 0.18288)
		(layer "In11.Cu")
		(net "M_H_CPU1_CLK_DN<0>")
	)
	(segment
		(start 202.774042 -256.507996)
		(end 202.640184 -256.6162)
		(width 0.18288)
		(layer "In11.Cu")
		(net "M_H_CPU1_CLK_DN<0>")
	)
	(segment
		(start 126.772162 -250.13793)
		(end 126.772162 -249.492262)
		(width 0.088646)
		(layer "In11.Cu")
		(net "M_H_CPU1_CLK_DN<0>")
	)
	(segment
		(start 144.95272 -249.155204)
		(end 144.829276 -249.206258)
		(width 0.18288)
		(layer "In11.Cu")
		(net "M_H_CPU1_CLK_DN<0>")
	)
	(segment
		(start 212.601556 -259.444236)
		(end 212.479636 -259.322316)
		(width 0.18288)
		(layer "In11.Cu")
		(net "M_H_CPU1_CLK_DN<0>")
	)
	(segment
		(start 125.552454 -247.50395)
		(end 125.550676 -247.502934)
		(width 0.088646)
		(layer "In11.Cu")
		(net "M_H_CPU1_CLK_DN<0>")
	)
	(segment
		(start 211.168996 -259.322316)
		(end 210.635596 -259.322316)
		(width 0.18288)
		(layer "In11.Cu")
		(net "M_H_CPU1_CLK_DN<0>")
	)
	(segment
		(start 211.290916 -259.444236)
		(end 211.168996 -259.322316)
		(width 0.18288)
		(layer "In11.Cu")
		(net "M_H_CPU1_CLK_DN<0>")
	)
	(segment
		(start 127.24765 -250.52909)
		(end 127.113284 -250.394724)
		(width 0.18288)
		(layer "In11.Cu")
		(net "M_H_CPU1_CLK_DN<0>")
	)
	(segment
		(start 125.550676 -247.502934)
		(end 125.541278 -247.4976)
		(width 0.088646)
		(layer "In11.Cu")
		(net "M_H_CPU1_CLK_DN<0>")
	)
	(segment
		(start 213.524592 -259.631434)
		(end 213.337394 -259.444236)
		(width 0.18288)
		(layer "In11.Cu")
		(net "M_H_CPU1_CLK_DN<0>")
	)
	(segment
		(start 126.77267 -250.13793)
		(end 126.772162 -250.13793)
		(width 0.088646)
		(layer "In11.Cu")
		(net "M_H_CPU1_CLK_DN<0>")
	)
	(segment
		(start 125.556264 -247.506236)
		(end 125.552454 -247.50395)
		(width 0.088646)
		(layer "In11.Cu")
		(net "M_H_CPU1_CLK_DN<0>")
	)
	(segment
		(start 126.302516 -248.806208)
		(end 126.302516 -248.787666)
		(width 0.088646)
		(layer "In11.Cu")
		(net "M_H_CPU1_CLK_DN<0>")
	)
	(segment
		(start 147.09521 -248.98985)
		(end 145.745962 -248.98985)
		(width 0.18288)
		(layer "In11.Cu")
		(net "M_H_CPU1_CLK_DN<0>")
	)
	(segment
		(start 210.635596 -259.322316)
		(end 210.513676 -259.444236)
		(width 0.18288)
		(layer "In11.Cu")
		(net "M_H_CPU1_CLK_DN<0>")
	)
	(segment
		(start 206.770732 -257.443732)
		(end 206.611474 -257.509772)
		(width 0.18288)
		(layer "In11.Cu")
		(net "M_H_CPU1_CLK_DN<0>")
	)
	(segment
		(start 210.513676 -259.444236)
		(end 209.394806 -259.444236)
		(width 0.18288)
		(layer "In11.Cu")
		(net "M_H_CPU1_CLK_DN<0>")
	)
	(segment
		(start 157.696154 -254.750824)
		(end 156.183584 -253.238)
		(width 0.18288)
		(layer "In11.Cu")
		(net "M_H_CPU1_CLK_DN<0>")
	)
	(segment
		(start 206.611474 -257.509772)
		(end 205.076044 -256.87401)
		(width 0.18288)
		(layer "In11.Cu")
		(net "M_H_CPU1_CLK_DN<0>")
	)
	(segment
		(start 205.076044 -256.87401)
		(end 203.41336 -256.698242)
		(width 0.18288)
		(layer "In11.Cu")
		(net "M_H_CPU1_CLK_DN<0>")
	)
	(segment
		(start 161.675064 -255.766316)
		(end 158.403798 -254.750824)
		(width 0.18288)
		(layer "In11.Cu")
		(net "M_H_CPU1_CLK_DN<0>")
	)
	(segment
		(start 145.737834 -248.997978)
		(end 144.95272 -249.155204)
		(width 0.18288)
		(layer "In11.Cu")
		(net "M_H_CPU1_CLK_DN<0>")
	)
	(segment
		(start 134.975854 -250.52909)
		(end 127.24765 -250.52909)
		(width 0.18288)
		(layer "In11.Cu")
		(net "M_H_CPU1_CLK_DN<0>")
	)
	(segment
		(start 194.601084 -255.766316)
		(end 161.675064 -255.766316)
		(width 0.18288)
		(layer "In11.Cu")
		(net "M_H_CPU1_CLK_DN<0>")
	)
	(segment
		(start 126.493778 -249.132852)
		(end 126.481078 -249.125486)
		(width 0.088646)
		(layer "In11.Cu")
		(net "M_H_CPU1_CLK_DN<0>")
	)
	(segment
		(start 211.824316 -259.444236)
		(end 211.290916 -259.444236)
		(width 0.18288)
		(layer "In11.Cu")
		(net "M_H_CPU1_CLK_DN<0>")
	)
	(segment
		(start 207.329786 -257.80746)
		(end 207.263746 -257.647948)
		(width 0.18288)
		(layer "In11.Cu")
		(net "M_H_CPU1_CLK_DN<0>")
	)
	(segment
		(start 127.113284 -250.394724)
		(end 127.029464 -250.394724)
		(width 0.088646)
		(layer "In11.Cu")
		(net "M_H_CPU1_CLK_DN<0>")
	)
	(segment
		(start 212.479636 -259.322316)
		(end 211.946236 -259.322316)
		(width 0.18288)
		(layer "In11.Cu")
		(net "M_H_CPU1_CLK_DN<0>")
	)
	(segment
		(start 140.331698 -251.070618)
		(end 135.517382 -251.070618)
		(width 0.18288)
		(layer "In11.Cu")
		(net "M_H_CPU1_CLK_DN<0>")
	)
	(segment
		(start 213.337394 -259.444236)
		(end 212.601556 -259.444236)
		(width 0.18288)
		(layer "In11.Cu")
		(net "M_H_CPU1_CLK_DN<0>")
	)
	(segment
		(start 126.501144 -249.137424)
		(end 126.497588 -249.135138)
		(width 0.088646)
		(layer "In11.Cu")
		(net "M_H_CPU1_CLK_DN<0>")
	)
	(segment
		(start 156.183584 -253.238)
		(end 152.97404 -252.152658)
		(width 0.18288)
		(layer "In11.Cu")
		(net "M_H_CPU1_CLK_DN<0>")
	)
	(segment
		(start 144.829276 -249.206258)
		(end 140.331698 -251.070618)
		(width 0.18288)
		(layer "In11.Cu")
		(net "M_H_CPU1_CLK_DN<0>")
	)
	(segment
		(start 126.020068 -248.316496)
		(end 126.011178 -248.311416)
		(width 0.088646)
		(layer "In11.Cu")
		(net "M_H_CPU1_CLK_DN<0>")
	)
	(segment
		(start 125.367288 -247.235726)
		(end 125.424692 -247.178322)
		(width 0.088646)
		(layer "In11.Cu")
		(net "M_H_CPU1_CLK_DN<0>")
	)
	(segment
		(start 203.41336 -256.698242)
		(end 203.304902 -256.563876)
		(width 0.18288)
		(layer "In11.Cu")
		(net "M_H_CPU1_CLK_DN<0>")
	)
	(segment
		(start 208.061052 -258.110228)
		(end 207.329786 -257.80746)
		(width 0.18288)
		(layer "In11.Cu")
		(net "M_H_CPU1_CLK_DN<0>")
	)
	(segment
		(start 126.497588 -249.135138)
		(end 126.494032 -249.133106)
		(width 0.088646)
		(layer "In11.Cu")
		(net "M_H_CPU1_CLK_DN<0>")
	)
	(segment
		(start 203.304902 -256.563876)
		(end 202.774042 -256.507996)
		(width 0.18288)
		(layer "In11.Cu")
		(net "M_H_CPU1_CLK_DN<0>")
	)
	(segment
		(start 150.258018 -252.152658)
		(end 147.09521 -248.98985)
		(width 0.18288)
		(layer "In11.Cu")
		(net "M_H_CPU1_CLK_DN<0>")
	)
	(segment
		(start 127.029464 -250.394724)
		(end 126.77267 -250.13793)
		(width 0.088646)
		(layer "In11.Cu")
		(net "M_H_CPU1_CLK_DN<0>")
	)
	(segment
		(start 202.640184 -256.6162)
		(end 194.601084 -255.766316)
		(width 0.18288)
		(layer "In11.Cu")
		(net "M_H_CPU1_CLK_DN<0>")
	)
	(segment
		(start 214.615014 -259.366766)
		(end 214.350346 -259.631434)
		(width 0.18288)
		(layer "In11.Cu")
		(net "M_H_CPU1_CLK_DN<0>")
	)
	(segment
		(start 214.350346 -259.631434)
		(end 213.524592 -259.631434)
		(width 0.18288)
		(layer "In11.Cu")
		(net "M_H_CPU1_CLK_DN<0>")
	)
	(segment
		(start 126.772162 -249.492262)
		(end 126.752604 -249.47245)
		(width 0.088646)
		(layer "In11.Cu")
		(net "M_H_CPU1_CLK_DN<0>")
	)
	(segment
		(start 135.517382 -251.070618)
		(end 134.975854 -250.52909)
		(width 0.18288)
		(layer "In11.Cu")
		(net "M_H_CPU1_CLK_DN<0>")
	)
	(segment
		(start 126.494032 -249.133106)
		(end 126.493778 -249.132852)
		(width 0.088646)
		(layer "In11.Cu")
		(net "M_H_CPU1_CLK_DN<0>")
	)
	(segment
		(start 145.745962 -248.98985)
		(end 145.737834 -248.997978)
		(width 0.18288)
		(layer "In11.Cu")
		(net "M_H_CPU1_CLK_DN<0>")
	)
	(segment
		(start 207.263746 -257.647948)
		(end 206.770732 -257.443732)
		(width 0.18288)
		(layer "In11.Cu")
		(net "M_H_CPU1_CLK_DN<0>")
	)
	(arc
		(start 126.481078 -249.125486)
		(mid 126.350164 -248.989126)
		(end 126.302516 -248.806208)
		(width 0.088646)
		(layer "In11.Cu")
		(net "M_H_CPU1_CLK_DN<0>")
	)
	(arc
		(start 126.302516 -248.787666)
		(mid 126.222354 -248.515477)
		(end 126.020068 -248.316496)
		(width 0.088646)
		(layer "In11.Cu")
		(net "M_H_CPU1_CLK_DN<0>")
	)
	(arc
		(start 126.011178 -248.311416)
		(mid 125.880264 -248.175056)
		(end 125.832616 -247.992138)
		(width 0.088646)
		(layer "In11.Cu")
		(net "M_H_CPU1_CLK_DN<0>")
	)
	(arc
		(start 125.832616 -247.992138)
		(mid 125.7587 -247.712636)
		(end 125.556264 -247.506236)
		(width 0.088646)
		(layer "In11.Cu")
		(net "M_H_CPU1_CLK_DN<0>")
	)
	(arc
		(start 126.752604 -249.47245)
		(mid 126.659068 -249.280769)
		(end 126.501144 -249.137424)
		(width 0.088646)
		(layer "In11.Cu")
		(net "M_H_CPU1_CLK_DN<0>")
	)
	(arc
		(start 125.541278 -247.4976)
		(mid 125.425539 -247.385776)
		(end 125.367288 -247.235726)
		(width 0.088646)
		(layer "In11.Cu")
		(net "M_H_CPU1_CLK_DN<0>")
	)
	(segment
		(start 209.171794 -269.1003)
		(end 209.035142 -269.141702)
		(width 0.1016)
		(layer "F.Cu")
		(net "M_H_CPU1_ALERT_N")
	)
	(segment
		(start 205.650084 -269.916656)
		(end 204.956664 -269.916656)
		(width 0.20066)
		(layer "F.Cu")
		(net "M_H_CPU1_ALERT_N")
	)
	(segment
		(start 206.95031 -269.141702)
		(end 206.831184 -269.141702)
		(width 0.20066)
		(layer "F.Cu")
		(net "M_H_CPU1_ALERT_N")
	)
	(segment
		(start 206.539084 -269.611856)
		(end 206.361284 -269.789656)
		(width 0.20066)
		(layer "F.Cu")
		(net "M_H_CPU1_ALERT_N")
	)
	(segment
		(start 122.087894 -256.639314)
		(end 122.087894 -257.175)
		(width 0.20066)
		(layer "F.Cu")
		(net "M_H_CPU1_ALERT_N")
	)
	(segment
		(start 209.035142 -269.141702)
		(end 207.159352 -269.141702)
		(width 0.1016)
		(layer "F.Cu")
		(net "M_H_CPU1_ALERT_N")
	)
	(segment
		(start 207.159352 -269.141702)
		(end 206.95031 -269.141702)
		(width 0.101854)
		(layer "F.Cu")
		(net "M_H_CPU1_ALERT_N")
	)
	(segment
		(start 122.087894 -257.175)
		(end 122.088148 -257.175254)
		(width 0.20066)
		(layer "F.Cu")
		(net "M_H_CPU1_ALERT_N")
	)
	(segment
		(start 204.076046 -269.566644)
		(end 202.971146 -269.566644)
		(width 0.20066)
		(layer "F.Cu")
		(net "M_H_CPU1_ALERT_N")
	)
	(segment
		(start 210.659218 -269.65275)
		(end 210.316064 -269.65275)
		(width 0.20066)
		(layer "F.Cu")
		(net "M_H_CPU1_ALERT_N")
	)
	(segment
		(start 209.763614 -269.1003)
		(end 209.186526 -269.1003)
		(width 0.20066)
		(layer "F.Cu")
		(net "M_H_CPU1_ALERT_N")
	)
	(segment
		(start 204.606652 -269.566644)
		(end 204.076046 -269.566644)
		(width 0.20066)
		(layer "F.Cu")
		(net "M_H_CPU1_ALERT_N")
	)
	(segment
		(start 205.777084 -269.789656)
		(end 205.650084 -269.916656)
		(width 0.20066)
		(layer "F.Cu")
		(net "M_H_CPU1_ALERT_N")
	)
	(segment
		(start 209.186526 -269.1003)
		(end 209.171794 -269.1003)
		(width 0.1016)
		(layer "F.Cu")
		(net "M_H_CPU1_ALERT_N")
	)
	(segment
		(start 210.316064 -269.65275)
		(end 209.763614 -269.1003)
		(width 0.20066)
		(layer "F.Cu")
		(net "M_H_CPU1_ALERT_N")
	)
	(segment
		(start 211.619846 -269.566644)
		(end 211.619592 -269.566898)
		(width 0.20066)
		(layer "F.Cu")
		(net "M_H_CPU1_ALERT_N")
	)
	(segment
		(start 206.361284 -269.789656)
		(end 205.777084 -269.789656)
		(width 0.20066)
		(layer "F.Cu")
		(net "M_H_CPU1_ALERT_N")
	)
	(segment
		(start 211.619592 -269.566898)
		(end 210.74507 -269.566898)
		(width 0.20066)
		(layer "F.Cu")
		(net "M_H_CPU1_ALERT_N")
	)
	(segment
		(start 210.74507 -269.566898)
		(end 210.659218 -269.65275)
		(width 0.20066)
		(layer "F.Cu")
		(net "M_H_CPU1_ALERT_N")
	)
	(segment
		(start 206.831184 -269.141702)
		(end 206.539084 -269.433802)
		(width 0.20066)
		(layer "F.Cu")
		(net "M_H_CPU1_ALERT_N")
	)
	(segment
		(start 206.539084 -269.433802)
		(end 206.539084 -269.611856)
		(width 0.20066)
		(layer "F.Cu")
		(net "M_H_CPU1_ALERT_N")
	)
	(segment
		(start 204.956664 -269.916656)
		(end 204.606652 -269.566644)
		(width 0.20066)
		(layer "F.Cu")
		(net "M_H_CPU1_ALERT_N")
	)
	(via
		(at 202.971146 -269.566644)
		(size 0.4572)
		(drill 0.2032)
		(layers "F.Cu" "B.Cu")
		(net "M_H_CPU1_ALERT_N")
	)
	(via
		(at 122.088148 -257.175254)
		(size 0.4572)
		(drill 0.2032)
		(layers "F.Cu" "B.Cu")
		(net "M_H_CPU1_ALERT_N")
	)
	(segment
		(start 164.34181 -267.443712)
		(end 164.150294 -267.252196)
		(width 0.18288)
		(layer "In11.Cu")
		(net "M_H_CPU1_ALERT_N")
	)
	(segment
		(start 169.025316 -267.315442)
		(end 168.897046 -267.443712)
		(width 0.18288)
		(layer "In11.Cu")
		(net "M_H_CPU1_ALERT_N")
	)
	(segment
		(start 150.123906 -260.415278)
		(end 148.808948 -259.10032)
		(width 0.18288)
		(layer "In11.Cu")
		(net "M_H_CPU1_ALERT_N")
	)
	(segment
		(start 190.358268 -267.707364)
		(end 189.353698 -267.707364)
		(width 0.18288)
		(layer "In11.Cu")
		(net "M_H_CPU1_ALERT_N")
	)
	(segment
		(start 132.238496 -257.499612)
		(end 132.228082 -257.493516)
		(width 0.088646)
		(layer "In11.Cu")
		(net "M_H_CPU1_ALERT_N")
	)
	(segment
		(start 132.623306 -257.493516)
		(end 132.612892 -257.499612)
		(width 0.088646)
		(layer "In11.Cu")
		(net "M_H_CPU1_ALERT_N")
	)
	(segment
		(start 186.36488 -268.614906)
		(end 186.040014 -268.29004)
		(width 0.18288)
		(layer "In11.Cu")
		(net "M_H_CPU1_ALERT_N")
	)
	(segment
		(start 201.41311 -270.02867)
		(end 200.405746 -269.021306)
		(width 0.18288)
		(layer "In11.Cu")
		(net "M_H_CPU1_ALERT_N")
	)
	(segment
		(start 189.353698 -267.707364)
		(end 189.087252 -267.440918)
		(width 0.18288)
		(layer "In11.Cu")
		(net "M_H_CPU1_ALERT_N")
	)
	(segment
		(start 195.004944 -269.244826)
		(end 194.051174 -268.291056)
		(width 0.18288)
		(layer "In11.Cu")
		(net "M_H_CPU1_ALERT_N")
	)
	(segment
		(start 148.808948 -259.10032)
		(end 142.903702 -259.10032)
		(width 0.18288)
		(layer "In11.Cu")
		(net "M_H_CPU1_ALERT_N")
	)
	(segment
		(start 168.897046 -267.443712)
		(end 164.34181 -267.443712)
		(width 0.18288)
		(layer "In11.Cu")
		(net "M_H_CPU1_ALERT_N")
	)
	(segment
		(start 124.16536 -257.493516)
		(end 124.154946 -257.499612)
		(width 0.088646)
		(layer "In11.Cu")
		(net "M_H_CPU1_ALERT_N")
	)
	(segment
		(start 136.937496 -257.499612)
		(end 136.922764 -257.490976)
		(width 0.088646)
		(layer "In11.Cu")
		(net "M_H_CPU1_ALERT_N")
	)
	(segment
		(start 187.240926 -268.260576)
		(end 186.886596 -268.614906)
		(width 0.18288)
		(layer "In11.Cu")
		(net "M_H_CPU1_ALERT_N")
	)
	(segment
		(start 125.659896 -257.499612)
		(end 125.645164 -257.490976)
		(width 0.088646)
		(layer "In11.Cu")
		(net "M_H_CPU1_ALERT_N")
	)
	(segment
		(start 202.68184 -269.85595)
		(end 202.404218 -269.94866)
		(width 0.18288)
		(layer "In11.Cu")
		(net "M_H_CPU1_ALERT_N")
	)
	(segment
		(start 159.145224 -267.443712)
		(end 158.155132 -266.45362)
		(width 0.18288)
		(layer "In11.Cu")
		(net "M_H_CPU1_ALERT_N")
	)
	(segment
		(start 189.087252 -267.440918)
		(end 187.939426 -267.440918)
		(width 0.18288)
		(layer "In11.Cu")
		(net "M_H_CPU1_ALERT_N")
	)
	(segment
		(start 187.938918 -267.441426)
		(end 187.829698 -267.441426)
		(width 0.18288)
		(layer "In11.Cu")
		(net "M_H_CPU1_ALERT_N")
	)
	(segment
		(start 202.163934 -270.02867)
		(end 201.41311 -270.02867)
		(width 0.18288)
		(layer "In11.Cu")
		(net "M_H_CPU1_ALERT_N")
	)
	(segment
		(start 199.162416 -269.021306)
		(end 198.938896 -269.244826)
		(width 0.18288)
		(layer "In11.Cu")
		(net "M_H_CPU1_ALERT_N")
	)
	(segment
		(start 157.029912 -266.45362)
		(end 150.99157 -260.415278)
		(width 0.18288)
		(layer "In11.Cu")
		(net "M_H_CPU1_ALERT_N")
	)
	(segment
		(start 175.378872 -267.441172)
		(end 171.975272 -267.441172)
		(width 0.18288)
		(layer "In11.Cu")
		(net "M_H_CPU1_ALERT_N")
	)
	(segment
		(start 164.150294 -267.252196)
		(end 161.32302 -267.252196)
		(width 0.18288)
		(layer "In11.Cu")
		(net "M_H_CPU1_ALERT_N")
	)
	(segment
		(start 161.32302 -267.252196)
		(end 161.131504 -267.443712)
		(width 0.18288)
		(layer "In11.Cu")
		(net "M_H_CPU1_ALERT_N")
	)
	(segment
		(start 179.685696 -268.29004)
		(end 179.49545 -268.480286)
		(width 0.18288)
		(layer "In11.Cu")
		(net "M_H_CPU1_ALERT_N")
	)
	(segment
		(start 139.475972 -257.52171)
		(end 138.924538 -257.52171)
		(width 0.088646)
		(layer "In11.Cu")
		(net "M_H_CPU1_ALERT_N")
	)
	(segment
		(start 187.829698 -267.441426)
		(end 187.829444 -267.441172)
		(width 0.18288)
		(layer "In11.Cu")
		(net "M_H_CPU1_ALERT_N")
	)
	(segment
		(start 140.18895 -257.466338)
		(end 139.609576 -257.466338)
		(width 0.088646)
		(layer "In11.Cu")
		(net "M_H_CPU1_ALERT_N")
	)
	(segment
		(start 137.877296 -257.499612)
		(end 137.862564 -257.490976)
		(width 0.088646)
		(layer "In11.Cu")
		(net "M_H_CPU1_ALERT_N")
	)
	(segment
		(start 134.118096 -257.499612)
		(end 134.107682 -257.493516)
		(width 0.088646)
		(layer "In11.Cu")
		(net "M_H_CPU1_ALERT_N")
	)
	(segment
		(start 187.829444 -267.441172)
		(end 187.44438 -267.441172)
		(width 0.18288)
		(layer "In11.Cu")
		(net "M_H_CPU1_ALERT_N")
	)
	(segment
		(start 194.051174 -268.291056)
		(end 190.94196 -268.291056)
		(width 0.18288)
		(layer "In11.Cu")
		(net "M_H_CPU1_ALERT_N")
	)
	(segment
		(start 130.748278 -257.490976)
		(end 130.733546 -257.499612)
		(width 0.088646)
		(layer "In11.Cu")
		(net "M_H_CPU1_ALERT_N")
	)
	(segment
		(start 176.417986 -268.480286)
		(end 175.378872 -267.441172)
		(width 0.18288)
		(layer "In11.Cu")
		(net "M_H_CPU1_ALERT_N")
	)
	(segment
		(start 186.040014 -268.29004)
		(end 179.685696 -268.29004)
		(width 0.18288)
		(layer "In11.Cu")
		(net "M_H_CPU1_ALERT_N")
	)
	(segment
		(start 187.939426 -267.440918)
		(end 187.938918 -267.441426)
		(width 0.18288)
		(layer "In11.Cu")
		(net "M_H_CPU1_ALERT_N")
	)
	(segment
		(start 200.405746 -269.021306)
		(end 199.162416 -269.021306)
		(width 0.18288)
		(layer "In11.Cu")
		(net "M_H_CPU1_ALERT_N")
	)
	(segment
		(start 142.903702 -259.10032)
		(end 141.26972 -257.466338)
		(width 0.18288)
		(layer "In11.Cu")
		(net "M_H_CPU1_ALERT_N")
	)
	(segment
		(start 171.975272 -267.441172)
		(end 171.849542 -267.315442)
		(width 0.18288)
		(layer "In11.Cu")
		(net "M_H_CPU1_ALERT_N")
	)
	(segment
		(start 127.539496 -257.499612)
		(end 127.529082 -257.493516)
		(width 0.088646)
		(layer "In11.Cu")
		(net "M_H_CPU1_ALERT_N")
	)
	(segment
		(start 187.44438 -267.441172)
		(end 187.240926 -267.644626)
		(width 0.18288)
		(layer "In11.Cu")
		(net "M_H_CPU1_ALERT_N")
	)
	(segment
		(start 127.924306 -257.493516)
		(end 127.913892 -257.499612)
		(width 0.088646)
		(layer "In11.Cu")
		(net "M_H_CPU1_ALERT_N")
	)
	(segment
		(start 123.229878 -257.490976)
		(end 123.215146 -257.499612)
		(width 0.088646)
		(layer "In11.Cu")
		(net "M_H_CPU1_ALERT_N")
	)
	(segment
		(start 202.404218 -269.94866)
		(end 202.163934 -270.02867)
		(width 0.18288)
		(layer "In11.Cu")
		(net "M_H_CPU1_ALERT_N")
	)
	(segment
		(start 202.971146 -269.566644)
		(end 202.68184 -269.85595)
		(width 0.18288)
		(layer "In11.Cu")
		(net "M_H_CPU1_ALERT_N")
	)
	(segment
		(start 122.812048 -257.482848)
		(end 122.088148 -257.175254)
		(width 0.088646)
		(layer "In11.Cu")
		(net "M_H_CPU1_ALERT_N")
	)
	(segment
		(start 198.938896 -269.244826)
		(end 195.004944 -269.244826)
		(width 0.18288)
		(layer "In11.Cu")
		(net "M_H_CPU1_ALERT_N")
	)
	(segment
		(start 129.808478 -257.490976)
		(end 129.793746 -257.499612)
		(width 0.088646)
		(layer "In11.Cu")
		(net "M_H_CPU1_ALERT_N")
	)
	(segment
		(start 161.131504 -267.443712)
		(end 159.145224 -267.443712)
		(width 0.18288)
		(layer "In11.Cu")
		(net "M_H_CPU1_ALERT_N")
	)
	(segment
		(start 141.26972 -257.466338)
		(end 140.18895 -257.466338)
		(width 0.18288)
		(layer "In11.Cu")
		(net "M_H_CPU1_ALERT_N")
	)
	(segment
		(start 150.99157 -260.415278)
		(end 150.123906 -260.415278)
		(width 0.18288)
		(layer "In11.Cu")
		(net "M_H_CPU1_ALERT_N")
	)
	(segment
		(start 187.240926 -267.644626)
		(end 187.240926 -268.260576)
		(width 0.18288)
		(layer "In11.Cu")
		(net "M_H_CPU1_ALERT_N")
	)
	(segment
		(start 158.155132 -266.45362)
		(end 157.029912 -266.45362)
		(width 0.18288)
		(layer "In11.Cu")
		(net "M_H_CPU1_ALERT_N")
	)
	(segment
		(start 190.94196 -268.291056)
		(end 190.358268 -267.707364)
		(width 0.18288)
		(layer "In11.Cu")
		(net "M_H_CPU1_ALERT_N")
	)
	(segment
		(start 122.84075 -257.499612)
		(end 122.812048 -257.482848)
		(width 0.088646)
		(layer "In11.Cu")
		(net "M_H_CPU1_ALERT_N")
	)
	(segment
		(start 126.044706 -257.493516)
		(end 126.034292 -257.499612)
		(width 0.088646)
		(layer "In11.Cu")
		(net "M_H_CPU1_ALERT_N")
	)
	(segment
		(start 128.868678 -257.490976)
		(end 128.853946 -257.499612)
		(width 0.088646)
		(layer "In11.Cu")
		(net "M_H_CPU1_ALERT_N")
	)
	(segment
		(start 171.849542 -267.315442)
		(end 169.025316 -267.315442)
		(width 0.18288)
		(layer "In11.Cu")
		(net "M_H_CPU1_ALERT_N")
	)
	(segment
		(start 179.49545 -268.480286)
		(end 176.417986 -268.480286)
		(width 0.18288)
		(layer "In11.Cu")
		(net "M_H_CPU1_ALERT_N")
	)
	(segment
		(start 186.886596 -268.614906)
		(end 186.36488 -268.614906)
		(width 0.18288)
		(layer "In11.Cu")
		(net "M_H_CPU1_ALERT_N")
	)
	(arc
		(start 130.733546 -257.499612)
		(mid 130.546348 -257.549755)
		(end 130.35915 -257.499612)
		(width 0.088646)
		(layer "In11.Cu")
		(net "M_H_CPU1_ALERT_N")
	)
	(arc
		(start 129.793746 -257.499612)
		(mid 129.606548 -257.549755)
		(end 129.41935 -257.499612)
		(width 0.088646)
		(layer "In11.Cu")
		(net "M_H_CPU1_ALERT_N")
	)
	(arc
		(start 136.922764 -257.490976)
		(mid 136.646289 -257.423656)
		(end 136.372092 -257.499612)
		(width 0.088646)
		(layer "In11.Cu")
		(net "M_H_CPU1_ALERT_N")
	)
	(arc
		(start 131.29895 -257.499612)
		(mid 131.024751 -257.423777)
		(end 130.748278 -257.490976)
		(width 0.088646)
		(layer "In11.Cu")
		(net "M_H_CPU1_ALERT_N")
	)
	(arc
		(start 137.311892 -257.499612)
		(mid 137.124694 -257.549755)
		(end 136.937496 -257.499612)
		(width 0.088646)
		(layer "In11.Cu")
		(net "M_H_CPU1_ALERT_N")
	)
	(arc
		(start 132.228082 -257.493516)
		(mid 131.949904 -257.423793)
		(end 131.673346 -257.499612)
		(width 0.088646)
		(layer "In11.Cu")
		(net "M_H_CPU1_ALERT_N")
	)
	(arc
		(start 131.673346 -257.499612)
		(mid 131.486148 -257.549755)
		(end 131.29895 -257.499612)
		(width 0.088646)
		(layer "In11.Cu")
		(net "M_H_CPU1_ALERT_N")
	)
	(arc
		(start 135.997696 -257.499612)
		(mid 135.714994 -257.423836)
		(end 135.432292 -257.499612)
		(width 0.088646)
		(layer "In11.Cu")
		(net "M_H_CPU1_ALERT_N")
	)
	(arc
		(start 137.862564 -257.490976)
		(mid 137.586089 -257.423656)
		(end 137.311892 -257.499612)
		(width 0.088646)
		(layer "In11.Cu")
		(net "M_H_CPU1_ALERT_N")
	)
	(arc
		(start 127.913892 -257.499612)
		(mid 127.726694 -257.549755)
		(end 127.539496 -257.499612)
		(width 0.088646)
		(layer "In11.Cu")
		(net "M_H_CPU1_ALERT_N")
	)
	(arc
		(start 123.215146 -257.499612)
		(mid 123.027948 -257.549755)
		(end 122.84075 -257.499612)
		(width 0.088646)
		(layer "In11.Cu")
		(net "M_H_CPU1_ALERT_N")
	)
	(arc
		(start 126.034292 -257.499612)
		(mid 125.847094 -257.549755)
		(end 125.659896 -257.499612)
		(width 0.088646)
		(layer "In11.Cu")
		(net "M_H_CPU1_ALERT_N")
	)
	(arc
		(start 130.35915 -257.499612)
		(mid 130.084951 -257.423777)
		(end 129.808478 -257.490976)
		(width 0.088646)
		(layer "In11.Cu")
		(net "M_H_CPU1_ALERT_N")
	)
	(arc
		(start 138.802364 -257.490976)
		(mid 138.525889 -257.423656)
		(end 138.251692 -257.499612)
		(width 0.088646)
		(layer "In11.Cu")
		(net "M_H_CPU1_ALERT_N")
	)
	(arc
		(start 139.609576 -257.466338)
		(mid 139.560489 -257.476102)
		(end 139.518898 -257.50393)
		(width 0.088646)
		(layer "In11.Cu")
		(net "M_H_CPU1_ALERT_N")
	)
	(arc
		(start 124.154946 -257.499612)
		(mid 123.967748 -257.549755)
		(end 123.78055 -257.499612)
		(width 0.088646)
		(layer "In11.Cu")
		(net "M_H_CPU1_ALERT_N")
	)
	(arc
		(start 123.78055 -257.499612)
		(mid 123.506351 -257.423777)
		(end 123.229878 -257.490976)
		(width 0.088646)
		(layer "In11.Cu")
		(net "M_H_CPU1_ALERT_N")
	)
	(arc
		(start 132.612892 -257.499612)
		(mid 132.425694 -257.549755)
		(end 132.238496 -257.499612)
		(width 0.088646)
		(layer "In11.Cu")
		(net "M_H_CPU1_ALERT_N")
	)
	(arc
		(start 138.924538 -257.52171)
		(mid 138.861553 -257.513898)
		(end 138.802364 -257.490976)
		(width 0.088646)
		(layer "In11.Cu")
		(net "M_H_CPU1_ALERT_N")
	)
	(arc
		(start 129.41935 -257.499612)
		(mid 129.145151 -257.423777)
		(end 128.868678 -257.490976)
		(width 0.088646)
		(layer "In11.Cu")
		(net "M_H_CPU1_ALERT_N")
	)
	(arc
		(start 128.47955 -257.499612)
		(mid 128.202737 -257.423742)
		(end 127.924306 -257.493516)
		(width 0.088646)
		(layer "In11.Cu")
		(net "M_H_CPU1_ALERT_N")
	)
	(arc
		(start 135.432292 -257.499612)
		(mid 135.245094 -257.549755)
		(end 135.057896 -257.499612)
		(width 0.088646)
		(layer "In11.Cu")
		(net "M_H_CPU1_ALERT_N")
	)
	(arc
		(start 126.9746 -257.499612)
		(mid 126.787292 -257.549755)
		(end 126.59995 -257.499612)
		(width 0.088646)
		(layer "In11.Cu")
		(net "M_H_CPU1_ALERT_N")
	)
	(arc
		(start 125.645164 -257.490976)
		(mid 125.368689 -257.423656)
		(end 125.094492 -257.499612)
		(width 0.088646)
		(layer "In11.Cu")
		(net "M_H_CPU1_ALERT_N")
	)
	(arc
		(start 139.518898 -257.50393)
		(mid 139.499203 -257.51709)
		(end 139.475972 -257.52171)
		(width 0.088646)
		(layer "In11.Cu")
		(net "M_H_CPU1_ALERT_N")
	)
	(arc
		(start 136.372092 -257.499612)
		(mid 136.184894 -257.549755)
		(end 135.997696 -257.499612)
		(width 0.088646)
		(layer "In11.Cu")
		(net "M_H_CPU1_ALERT_N")
	)
	(arc
		(start 134.107682 -257.493516)
		(mid 133.829504 -257.423793)
		(end 133.552946 -257.499612)
		(width 0.088646)
		(layer "In11.Cu")
		(net "M_H_CPU1_ALERT_N")
	)
	(arc
		(start 126.59995 -257.499612)
		(mid 126.323137 -257.423742)
		(end 126.044706 -257.493516)
		(width 0.088646)
		(layer "In11.Cu")
		(net "M_H_CPU1_ALERT_N")
	)
	(arc
		(start 134.492492 -257.499612)
		(mid 134.305294 -257.549755)
		(end 134.118096 -257.499612)
		(width 0.088646)
		(layer "In11.Cu")
		(net "M_H_CPU1_ALERT_N")
	)
	(arc
		(start 135.057896 -257.499612)
		(mid 134.775194 -257.423836)
		(end 134.492492 -257.499612)
		(width 0.088646)
		(layer "In11.Cu")
		(net "M_H_CPU1_ALERT_N")
	)
	(arc
		(start 125.094492 -257.499612)
		(mid 124.907294 -257.549755)
		(end 124.720096 -257.499612)
		(width 0.088646)
		(layer "In11.Cu")
		(net "M_H_CPU1_ALERT_N")
	)
	(arc
		(start 128.853946 -257.499612)
		(mid 128.666748 -257.549755)
		(end 128.47955 -257.499612)
		(width 0.088646)
		(layer "In11.Cu")
		(net "M_H_CPU1_ALERT_N")
	)
	(arc
		(start 124.720096 -257.499612)
		(mid 124.443537 -257.423869)
		(end 124.16536 -257.493516)
		(width 0.088646)
		(layer "In11.Cu")
		(net "M_H_CPU1_ALERT_N")
	)
	(arc
		(start 133.552946 -257.499612)
		(mid 133.365748 -257.549755)
		(end 133.17855 -257.499612)
		(width 0.088646)
		(layer "In11.Cu")
		(net "M_H_CPU1_ALERT_N")
	)
	(arc
		(start 138.251692 -257.499612)
		(mid 138.064494 -257.549755)
		(end 137.877296 -257.499612)
		(width 0.088646)
		(layer "In11.Cu")
		(net "M_H_CPU1_ALERT_N")
	)
	(arc
		(start 133.17855 -257.499612)
		(mid 132.901737 -257.423742)
		(end 132.623306 -257.493516)
		(width 0.088646)
		(layer "In11.Cu")
		(net "M_H_CPU1_ALERT_N")
	)
	(arc
		(start 127.529082 -257.493516)
		(mid 127.251048 -257.423916)
		(end 126.9746 -257.499612)
		(width 0.088646)
		(layer "In11.Cu")
		(net "M_H_CPU1_ALERT_N")
	)
	(segment
		(start 381.305816 -253.38405)
		(end 381.305816 -253.919736)
		(width 0.20066)
		(layer "F.Cu")
		(net "M_H_CPU0_SB_RSP<1>")
	)
	(segment
		(start 381.305562 -253.383796)
		(end 381.305816 -253.38405)
		(width 0.20066)
		(layer "F.Cu")
		(net "M_H_CPU0_SB_RSP<1>")
	)
	(segment
		(start 450.911214 -243.216684)
		(end 452.016114 -243.216684)
		(width 0.20066)
		(layer "F.Cu")
		(net "M_H_CPU0_SB_RSP<1>")
	)
	(segment
		(start 440.857894 -251.92101)
		(end 440.857894 -251.47524)
		(width 0.18288)
		(layer "In6.Cu")
		(net "M_H_CPU0_SB_RSP<1>")
	)
	(segment
		(start 396.99692 -257.097276)
		(end 393.63777 -257.097276)
		(width 0.18288)
		(layer "In6.Cu")
		(net "M_H_CPU0_SB_RSP<1>")
	)
	(segment
		(start 435.013354 -255.59512)
		(end 434.716428 -255.892046)
		(width 0.18288)
		(layer "In6.Cu")
		(net "M_H_CPU0_SB_RSP<1>")
	)
	(segment
		(start 450.911214 -243.242084)
		(end 451.386194 -243.717064)
		(width 0.18288)
		(layer "In6.Cu")
		(net "M_H_CPU0_SB_RSP<1>")
	)
	(segment
		(start 435.994302 -254.614172)
		(end 435.7624 -254.846074)
		(width 0.18288)
		(layer "In6.Cu")
		(net "M_H_CPU0_SB_RSP<1>")
	)
	(segment
		(start 451.157594 -244.490748)
		(end 450.711062 -244.490748)
		(width 0.18288)
		(layer "In6.Cu")
		(net "M_H_CPU0_SB_RSP<1>")
	)
	(segment
		(start 390.160256 -255.998726)
		(end 389.33374 -255.17221)
		(width 0.18288)
		(layer "In6.Cu")
		(net "M_H_CPU0_SB_RSP<1>")
	)
	(segment
		(start 436.055262 -255.397508)
		(end 436.055262 -255.65608)
		(width 0.18288)
		(layer "In6.Cu")
		(net "M_H_CPU0_SB_RSP<1>")
	)
	(segment
		(start 439.316114 -251.29236)
		(end 436.743348 -253.865126)
		(width 0.18288)
		(layer "In6.Cu")
		(net "M_H_CPU0_SB_RSP<1>")
	)
	(segment
		(start 449.876926 -246.722646)
		(end 448.836542 -246.722646)
		(width 0.18288)
		(layer "In6.Cu")
		(net "M_H_CPU0_SB_RSP<1>")
	)
	(segment
		(start 441.551314 -251.47524)
		(end 441.551314 -251.92101)
		(width 0.18288)
		(layer "In6.Cu")
		(net "M_H_CPU0_SB_RSP<1>")
	)
	(segment
		(start 451.386194 -243.717064)
		(end 451.386194 -244.262148)
		(width 0.18288)
		(layer "In6.Cu")
		(net "M_H_CPU0_SB_RSP<1>")
	)
	(segment
		(start 436.252874 -254.614172)
		(end 435.994302 -254.614172)
		(width 0.18288)
		(layer "In6.Cu")
		(net "M_H_CPU0_SB_RSP<1>")
	)
	(segment
		(start 451.386194 -244.262148)
		(end 451.157594 -244.490748)
		(width 0.18288)
		(layer "In6.Cu")
		(net "M_H_CPU0_SB_RSP<1>")
	)
	(segment
		(start 448.836542 -246.722646)
		(end 447.266822 -248.292366)
		(width 0.18288)
		(layer "In6.Cu")
		(net "M_H_CPU0_SB_RSP<1>")
	)
	(segment
		(start 436.804308 -254.907034)
		(end 436.545736 -254.907034)
		(width 0.18288)
		(layer "In6.Cu")
		(net "M_H_CPU0_SB_RSP<1>")
	)
	(segment
		(start 450.911214 -243.216684)
		(end 450.911214 -243.242084)
		(width 0.18288)
		(layer "In6.Cu")
		(net "M_H_CPU0_SB_RSP<1>")
	)
	(segment
		(start 382.01473 -254.329184)
		(end 381.305816 -253.919736)
		(width 0.088646)
		(layer "In6.Cu")
		(net "M_H_CPU0_SB_RSP<1>")
	)
	(segment
		(start 385.266946 -255.231646)
		(end 385.252214 -255.22301)
		(width 0.088646)
		(layer "In6.Cu")
		(net "M_H_CPU0_SB_RSP<1>")
	)
	(segment
		(start 435.82336 -255.887982)
		(end 435.564788 -255.887982)
		(width 0.18288)
		(layer "In6.Cu")
		(net "M_H_CPU0_SB_RSP<1>")
	)
	(segment
		(start 437.03621 -254.675132)
		(end 436.804308 -254.907034)
		(width 0.18288)
		(layer "In6.Cu")
		(net "M_H_CPU0_SB_RSP<1>")
	)
	(segment
		(start 398.20215 -255.892046)
		(end 396.99692 -257.097276)
		(width 0.18288)
		(layer "In6.Cu")
		(net "M_H_CPU0_SB_RSP<1>")
	)
	(segment
		(start 436.545736 -254.907034)
		(end 436.252874 -254.614172)
		(width 0.18288)
		(layer "In6.Cu")
		(net "M_H_CPU0_SB_RSP<1>")
	)
	(segment
		(start 441.734194 -251.29236)
		(end 441.551314 -251.47524)
		(width 0.18288)
		(layer "In6.Cu")
		(net "M_H_CPU0_SB_RSP<1>")
	)
	(segment
		(start 436.055262 -255.65608)
		(end 435.82336 -255.887982)
		(width 0.18288)
		(layer "In6.Cu")
		(net "M_H_CPU0_SB_RSP<1>")
	)
	(segment
		(start 382.91135 -254.414274)
		(end 382.762252 -254.329184)
		(width 0.088646)
		(layer "In6.Cu")
		(net "M_H_CPU0_SB_RSP<1>")
	)
	(segment
		(start 441.551314 -251.92101)
		(end 441.368434 -252.10389)
		(width 0.18288)
		(layer "In6.Cu")
		(net "M_H_CPU0_SB_RSP<1>")
	)
	(segment
		(start 434.716428 -255.892046)
		(end 398.20215 -255.892046)
		(width 0.18288)
		(layer "In6.Cu")
		(net "M_H_CPU0_SB_RSP<1>")
	)
	(segment
		(start 389.33374 -255.17221)
		(end 387.875018 -255.17221)
		(width 0.18288)
		(layer "In6.Cu")
		(net "M_H_CPU0_SB_RSP<1>")
	)
	(segment
		(start 436.743348 -254.123698)
		(end 437.03621 -254.41656)
		(width 0.18288)
		(layer "In6.Cu")
		(net "M_H_CPU0_SB_RSP<1>")
	)
	(segment
		(start 393.63777 -257.097276)
		(end 392.05027 -256.781554)
		(width 0.18288)
		(layer "In6.Cu")
		(net "M_H_CPU0_SB_RSP<1>")
	)
	(segment
		(start 445.937894 -249.155966)
		(end 445.107314 -249.155966)
		(width 0.18288)
		(layer "In6.Cu")
		(net "M_H_CPU0_SB_RSP<1>")
	)
	(segment
		(start 392.05027 -256.781554)
		(end 390.160256 -255.998726)
		(width 0.18288)
		(layer "In6.Cu")
		(net "M_H_CPU0_SB_RSP<1>")
	)
	(segment
		(start 435.7624 -255.104646)
		(end 436.055262 -255.397508)
		(width 0.18288)
		(layer "In6.Cu")
		(net "M_H_CPU0_SB_RSP<1>")
	)
	(segment
		(start 450.230494 -246.369078)
		(end 449.876926 -246.722646)
		(width 0.18288)
		(layer "In6.Cu")
		(net "M_H_CPU0_SB_RSP<1>")
	)
	(segment
		(start 440.675014 -251.29236)
		(end 439.316114 -251.29236)
		(width 0.18288)
		(layer "In6.Cu")
		(net "M_H_CPU0_SB_RSP<1>")
	)
	(segment
		(start 450.230494 -244.971316)
		(end 450.230494 -246.369078)
		(width 0.18288)
		(layer "In6.Cu")
		(net "M_H_CPU0_SB_RSP<1>")
	)
	(segment
		(start 435.7624 -254.846074)
		(end 435.7624 -255.104646)
		(width 0.18288)
		(layer "In6.Cu")
		(net "M_H_CPU0_SB_RSP<1>")
	)
	(segment
		(start 435.271926 -255.59512)
		(end 435.013354 -255.59512)
		(width 0.18288)
		(layer "In6.Cu")
		(net "M_H_CPU0_SB_RSP<1>")
	)
	(segment
		(start 382.762252 -254.329184)
		(end 382.01473 -254.329184)
		(width 0.088646)
		(layer "In6.Cu")
		(net "M_H_CPU0_SB_RSP<1>")
	)
	(segment
		(start 447.266822 -248.292366)
		(end 446.801494 -248.292366)
		(width 0.18288)
		(layer "In6.Cu")
		(net "M_H_CPU0_SB_RSP<1>")
	)
	(segment
		(start 387.875018 -255.17221)
		(end 386.944616 -255.17221)
		(width 0.088646)
		(layer "In6.Cu")
		(net "M_H_CPU0_SB_RSP<1>")
	)
	(segment
		(start 440.857894 -251.47524)
		(end 440.675014 -251.29236)
		(width 0.18288)
		(layer "In6.Cu")
		(net "M_H_CPU0_SB_RSP<1>")
	)
	(segment
		(start 383.089912 -254.752094)
		(end 383.089912 -254.733552)
		(width 0.088646)
		(layer "In6.Cu")
		(net "M_H_CPU0_SB_RSP<1>")
	)
	(segment
		(start 436.743348 -253.865126)
		(end 436.743348 -254.123698)
		(width 0.18288)
		(layer "In6.Cu")
		(net "M_H_CPU0_SB_RSP<1>")
	)
	(segment
		(start 441.368434 -252.10389)
		(end 441.040774 -252.10389)
		(width 0.18288)
		(layer "In6.Cu")
		(net "M_H_CPU0_SB_RSP<1>")
	)
	(segment
		(start 441.040774 -252.10389)
		(end 440.857894 -251.92101)
		(width 0.18288)
		(layer "In6.Cu")
		(net "M_H_CPU0_SB_RSP<1>")
	)
	(segment
		(start 384.877818 -255.22301)
		(end 384.868928 -255.228344)
		(width 0.088646)
		(layer "In6.Cu")
		(net "M_H_CPU0_SB_RSP<1>")
	)
	(segment
		(start 450.711062 -244.490748)
		(end 450.230494 -244.971316)
		(width 0.18288)
		(layer "In6.Cu")
		(net "M_H_CPU0_SB_RSP<1>")
	)
	(segment
		(start 442.97092 -251.29236)
		(end 441.734194 -251.29236)
		(width 0.18288)
		(layer "In6.Cu")
		(net "M_H_CPU0_SB_RSP<1>")
	)
	(segment
		(start 446.801494 -248.292366)
		(end 445.937894 -249.155966)
		(width 0.18288)
		(layer "In6.Cu")
		(net "M_H_CPU0_SB_RSP<1>")
	)
	(segment
		(start 437.03621 -254.41656)
		(end 437.03621 -254.675132)
		(width 0.18288)
		(layer "In6.Cu")
		(net "M_H_CPU0_SB_RSP<1>")
	)
	(segment
		(start 386.206746 -255.231646)
		(end 386.192014 -255.22301)
		(width 0.088646)
		(layer "In6.Cu")
		(net "M_H_CPU0_SB_RSP<1>")
	)
	(segment
		(start 435.564788 -255.887982)
		(end 435.271926 -255.59512)
		(width 0.18288)
		(layer "In6.Cu")
		(net "M_H_CPU0_SB_RSP<1>")
	)
	(segment
		(start 445.107314 -249.155966)
		(end 442.97092 -251.29236)
		(width 0.18288)
		(layer "In6.Cu")
		(net "M_H_CPU0_SB_RSP<1>")
	)
	(arc
		(start 385.252214 -255.22301)
		(mid 385.065016 -255.172867)
		(end 384.877818 -255.22301)
		(width 0.088646)
		(layer "In6.Cu")
		(net "M_H_CPU0_SB_RSP<1>")
	)
	(arc
		(start 383.37236 -255.223264)
		(mid 383.170074 -255.024283)
		(end 383.089912 -254.752094)
		(width 0.088646)
		(layer "In6.Cu")
		(net "M_H_CPU0_SB_RSP<1>")
	)
	(arc
		(start 383.937764 -255.223264)
		(mid 383.655062 -255.299006)
		(end 383.37236 -255.223264)
		(width 0.088646)
		(layer "In6.Cu")
		(net "M_H_CPU0_SB_RSP<1>")
	)
	(arc
		(start 386.944616 -255.17221)
		(mid 386.847677 -255.1853)
		(end 386.757418 -255.22301)
		(width 0.088646)
		(layer "In6.Cu")
		(net "M_H_CPU0_SB_RSP<1>")
	)
	(arc
		(start 383.089912 -254.733552)
		(mid 383.042233 -254.550652)
		(end 382.91135 -254.414274)
		(width 0.088646)
		(layer "In6.Cu")
		(net "M_H_CPU0_SB_RSP<1>")
	)
	(arc
		(start 386.757418 -255.22301)
		(mid 386.483219 -255.298845)
		(end 386.206746 -255.231646)
		(width 0.088646)
		(layer "In6.Cu")
		(net "M_H_CPU0_SB_RSP<1>")
	)
	(arc
		(start 384.31216 -255.223264)
		(mid 384.124962 -255.173121)
		(end 383.937764 -255.223264)
		(width 0.088646)
		(layer "In6.Cu")
		(net "M_H_CPU0_SB_RSP<1>")
	)
	(arc
		(start 386.192014 -255.22301)
		(mid 386.004816 -255.172867)
		(end 385.817618 -255.22301)
		(width 0.088646)
		(layer "In6.Cu")
		(net "M_H_CPU0_SB_RSP<1>")
	)
	(arc
		(start 385.817618 -255.22301)
		(mid 385.543419 -255.298845)
		(end 385.266946 -255.231646)
		(width 0.088646)
		(layer "In6.Cu")
		(net "M_H_CPU0_SB_RSP<1>")
	)
	(arc
		(start 384.868928 -255.228344)
		(mid 384.589886 -255.299029)
		(end 384.31216 -255.223264)
		(width 0.088646)
		(layer "In6.Cu")
		(net "M_H_CPU0_SB_RSP<1>")
	)
	(segment
		(start 381.775716 -254.733298)
		(end 381.775462 -254.733552)
		(width 0.20066)
		(layer "F.Cu")
		(net "M_H_CPU0_SB_RSP<0>")
	)
	(segment
		(start 458.455014 -243.216684)
		(end 459.559914 -243.216684)
		(width 0.20066)
		(layer "F.Cu")
		(net "M_H_CPU0_SB_RSP<0>")
	)
	(segment
		(start 381.775716 -254.197612)
		(end 381.775716 -254.733298)
		(width 0.20066)
		(layer "F.Cu")
		(net "M_H_CPU0_SB_RSP<0>")
	)
	(segment
		(start 451.126606 -249.592338)
		(end 449.875402 -249.592338)
		(width 0.18288)
		(layer "In6.Cu")
		(net "M_H_CPU0_SB_RSP<0>")
	)
	(segment
		(start 399.537936 -256.891282)
		(end 398.336262 -258.092956)
		(width 0.18288)
		(layer "In6.Cu")
		(net "M_H_CPU0_SB_RSP<0>")
	)
	(segment
		(start 458.455014 -243.242084)
		(end 459.016354 -243.803424)
		(width 0.18288)
		(layer "In6.Cu")
		(net "M_H_CPU0_SB_RSP<0>")
	)
	(segment
		(start 447.604134 -251.863606)
		(end 446.059814 -251.863606)
		(width 0.18288)
		(layer "In6.Cu")
		(net "M_H_CPU0_SB_RSP<0>")
	)
	(segment
		(start 382.08839 -254.733552)
		(end 381.775462 -254.733552)
		(width 0.088646)
		(layer "In6.Cu")
		(net "M_H_CPU0_SB_RSP<0>")
	)
	(segment
		(start 457.825348 -244.492272)
		(end 456.707494 -245.610126)
		(width 0.18288)
		(layer "In6.Cu")
		(net "M_H_CPU0_SB_RSP<0>")
	)
	(segment
		(start 459.016354 -243.803424)
		(end 459.016354 -244.218206)
		(width 0.18288)
		(layer "In6.Cu")
		(net "M_H_CPU0_SB_RSP<0>")
	)
	(segment
		(start 387.875018 -256.242312)
		(end 386.885942 -256.242312)
		(width 0.088646)
		(layer "In6.Cu")
		(net "M_H_CPU0_SB_RSP<0>")
	)
	(segment
		(start 440.23026 -256.891282)
		(end 399.537936 -256.891282)
		(width 0.18288)
		(layer "In6.Cu")
		(net "M_H_CPU0_SB_RSP<0>")
	)
	(segment
		(start 444.234316 -252.887226)
		(end 440.23026 -256.891282)
		(width 0.18288)
		(layer "In6.Cu")
		(net "M_H_CPU0_SB_RSP<0>")
	)
	(segment
		(start 382.620012 -255.557528)
		(end 382.620012 -255.538986)
		(width 0.088646)
		(layer "In6.Cu")
		(net "M_H_CPU0_SB_RSP<0>")
	)
	(segment
		(start 445.036194 -252.887226)
		(end 444.234316 -252.887226)
		(width 0.18288)
		(layer "In6.Cu")
		(net "M_H_CPU0_SB_RSP<0>")
	)
	(segment
		(start 386.287518 -256.03708)
		(end 386.272786 -256.045716)
		(width 0.088646)
		(layer "In6.Cu")
		(net "M_H_CPU0_SB_RSP<0>")
	)
	(segment
		(start 393.538456 -258.092956)
		(end 391.559288 -257.699256)
		(width 0.18288)
		(layer "In6.Cu")
		(net "M_H_CPU0_SB_RSP<0>")
	)
	(segment
		(start 458.742288 -244.492272)
		(end 457.825348 -244.492272)
		(width 0.18288)
		(layer "In6.Cu")
		(net "M_H_CPU0_SB_RSP<0>")
	)
	(segment
		(start 456.707494 -245.610126)
		(end 456.707494 -246.626888)
		(width 0.18288)
		(layer "In6.Cu")
		(net "M_H_CPU0_SB_RSP<0>")
	)
	(segment
		(start 446.059814 -251.863606)
		(end 445.036194 -252.887226)
		(width 0.18288)
		(layer "In6.Cu")
		(net "M_H_CPU0_SB_RSP<0>")
	)
	(segment
		(start 386.299456 -256.030222)
		(end 386.287518 -256.03708)
		(width 0.088646)
		(layer "In6.Cu")
		(net "M_H_CPU0_SB_RSP<0>")
	)
	(segment
		(start 452.826628 -247.892316)
		(end 451.126606 -249.592338)
		(width 0.18288)
		(layer "In6.Cu")
		(net "M_H_CPU0_SB_RSP<0>")
	)
	(segment
		(start 386.885942 -256.242312)
		(end 386.739638 -256.096008)
		(width 0.088646)
		(layer "In6.Cu")
		(net "M_H_CPU0_SB_RSP<0>")
	)
	(segment
		(start 398.336262 -258.092956)
		(end 393.538456 -258.092956)
		(width 0.18288)
		(layer "In6.Cu")
		(net "M_H_CPU0_SB_RSP<0>")
	)
	(segment
		(start 385.347464 -256.03708)
		(end 385.332732 -256.045716)
		(width 0.088646)
		(layer "In6.Cu")
		(net "M_H_CPU0_SB_RSP<0>")
	)
	(segment
		(start 385.355846 -256.032254)
		(end 385.347464 -256.03708)
		(width 0.088646)
		(layer "In6.Cu")
		(net "M_H_CPU0_SB_RSP<0>")
	)
	(segment
		(start 389.09117 -256.676906)
		(end 388.656576 -256.242312)
		(width 0.18288)
		(layer "In6.Cu")
		(net "M_H_CPU0_SB_RSP<0>")
	)
	(segment
		(start 458.455014 -243.216684)
		(end 458.455014 -243.242084)
		(width 0.18288)
		(layer "In6.Cu")
		(net "M_H_CPU0_SB_RSP<0>")
	)
	(segment
		(start 459.016354 -244.218206)
		(end 458.742288 -244.492272)
		(width 0.18288)
		(layer "In6.Cu")
		(net "M_H_CPU0_SB_RSP<0>")
	)
	(segment
		(start 449.875402 -249.592338)
		(end 447.604134 -251.863606)
		(width 0.18288)
		(layer "In6.Cu")
		(net "M_H_CPU0_SB_RSP<0>")
	)
	(segment
		(start 382.153668 -254.79883)
		(end 382.08839 -254.733552)
		(width 0.088646)
		(layer "In6.Cu")
		(net "M_H_CPU0_SB_RSP<0>")
	)
	(segment
		(start 455.442066 -247.892316)
		(end 452.826628 -247.892316)
		(width 0.18288)
		(layer "In6.Cu")
		(net "M_H_CPU0_SB_RSP<0>")
	)
	(segment
		(start 391.559288 -257.699256)
		(end 389.09117 -256.676906)
		(width 0.18288)
		(layer "In6.Cu")
		(net "M_H_CPU0_SB_RSP<0>")
	)
	(segment
		(start 456.707494 -246.626888)
		(end 455.442066 -247.892316)
		(width 0.18288)
		(layer "In6.Cu")
		(net "M_H_CPU0_SB_RSP<0>")
	)
	(segment
		(start 388.656576 -256.242312)
		(end 387.875018 -256.242312)
		(width 0.18288)
		(layer "In6.Cu")
		(net "M_H_CPU0_SB_RSP<0>")
	)
	(arc
		(start 382.432814 -255.223264)
		(mid 382.242907 -255.044158)
		(end 382.153668 -254.79883)
		(width 0.088646)
		(layer "In6.Cu")
		(net "M_H_CPU0_SB_RSP<0>")
	)
	(arc
		(start 383.84226 -256.03708)
		(mid 383.655062 -255.986937)
		(end 383.467864 -256.03708)
		(width 0.088646)
		(layer "In6.Cu")
		(net "M_H_CPU0_SB_RSP<0>")
	)
	(arc
		(start 385.722114 -256.03708)
		(mid 385.539609 -255.986842)
		(end 385.355846 -256.032254)
		(width 0.088646)
		(layer "In6.Cu")
		(net "M_H_CPU0_SB_RSP<0>")
	)
	(arc
		(start 386.272786 -256.045716)
		(mid 385.996345 -256.112882)
		(end 385.722114 -256.03708)
		(width 0.088646)
		(layer "In6.Cu")
		(net "M_H_CPU0_SB_RSP<0>")
	)
	(arc
		(start 382.620012 -255.538986)
		(mid 382.567742 -255.356621)
		(end 382.432814 -255.223264)
		(width 0.088646)
		(layer "In6.Cu")
		(net "M_H_CPU0_SB_RSP<0>")
	)
	(arc
		(start 382.90246 -256.03708)
		(mid 382.698125 -255.834475)
		(end 382.620012 -255.557528)
		(width 0.088646)
		(layer "In6.Cu")
		(net "M_H_CPU0_SB_RSP<0>")
	)
	(arc
		(start 385.332732 -256.045716)
		(mid 385.056291 -256.112882)
		(end 384.78206 -256.03708)
		(width 0.088646)
		(layer "In6.Cu")
		(net "M_H_CPU0_SB_RSP<0>")
	)
	(arc
		(start 384.407664 -256.03708)
		(mid 384.124962 -256.112856)
		(end 383.84226 -256.03708)
		(width 0.088646)
		(layer "In6.Cu")
		(net "M_H_CPU0_SB_RSP<0>")
	)
	(arc
		(start 386.661914 -256.03708)
		(mid 386.481567 -255.986877)
		(end 386.299456 -256.030222)
		(width 0.088646)
		(layer "In6.Cu")
		(net "M_H_CPU0_SB_RSP<0>")
	)
	(arc
		(start 383.467864 -256.03708)
		(mid 383.185162 -256.112856)
		(end 382.90246 -256.03708)
		(width 0.088646)
		(layer "In6.Cu")
		(net "M_H_CPU0_SB_RSP<0>")
	)
	(arc
		(start 384.78206 -256.03708)
		(mid 384.594862 -255.986937)
		(end 384.407664 -256.03708)
		(width 0.088646)
		(layer "In6.Cu")
		(net "M_H_CPU0_SB_RSP<0>")
	)
	(arc
		(start 386.739638 -256.096008)
		(mid 386.702702 -256.064003)
		(end 386.661914 -256.03708)
		(width 0.088646)
		(layer "In6.Cu")
		(net "M_H_CPU0_SB_RSP<0>")
	)
	(segment
		(start 458.55382 -247.04167)
		(end 460.56296 -247.04167)
		(width 0.1016)
		(layer "F.Cu")
		(net "M_H_CPU0_SB_PAR")
	)
	(segment
		(start 457.751942 -246.616728)
		(end 458.187552 -247.052338)
		(width 0.20066)
		(layer "F.Cu")
		(net "M_H_CPU0_SB_PAR")
	)
	(segment
		(start 456.116182 -246.616728)
		(end 457.751942 -246.616728)
		(width 0.20066)
		(layer "F.Cu")
		(net "M_H_CPU0_SB_PAR")
	)
	(segment
		(start 455.011282 -246.616728)
		(end 456.116182 -246.616728)
		(width 0.20066)
		(layer "F.Cu")
		(net "M_H_CPU0_SB_PAR")
	)
	(segment
		(start 458.538326 -247.052338)
		(end 458.543152 -247.052338)
		(width 0.101854)
		(layer "F.Cu")
		(net "M_H_CPU0_SB_PAR")
	)
	(segment
		(start 460.844392 -247.049036)
		(end 461.709262 -246.184166)
		(width 0.20066)
		(layer "F.Cu")
		(net "M_H_CPU0_SB_PAR")
	)
	(segment
		(start 460.56296 -247.04167)
		(end 460.570326 -247.049036)
		(width 0.1016)
		(layer "F.Cu")
		(net "M_H_CPU0_SB_PAR")
	)
	(segment
		(start 460.570326 -247.049036)
		(end 460.844392 -247.049036)
		(width 0.20066)
		(layer "F.Cu")
		(net "M_H_CPU0_SB_PAR")
	)
	(segment
		(start 462.54543 -246.616728)
		(end 463.659982 -246.616728)
		(width 0.20066)
		(layer "F.Cu")
		(net "M_H_CPU0_SB_PAR")
	)
	(segment
		(start 461.709262 -246.184166)
		(end 462.112868 -246.184166)
		(width 0.20066)
		(layer "F.Cu")
		(net "M_H_CPU0_SB_PAR")
	)
	(segment
		(start 458.187552 -247.052338)
		(end 458.538326 -247.052338)
		(width 0.20066)
		(layer "F.Cu")
		(net "M_H_CPU0_SB_PAR")
	)
	(segment
		(start 458.543152 -247.052338)
		(end 458.55382 -247.04167)
		(width 0.1016)
		(layer "F.Cu")
		(net "M_H_CPU0_SB_PAR")
	)
	(segment
		(start 376.966734 -245.27256)
		(end 376.96648 -245.272306)
		(width 0.20066)
		(layer "F.Cu")
		(net "M_H_CPU0_SB_PAR")
	)
	(segment
		(start 376.96648 -245.272306)
		(end 376.96648 -244.73662)
		(width 0.20066)
		(layer "F.Cu")
		(net "M_H_CPU0_SB_PAR")
	)
	(segment
		(start 462.112868 -246.184166)
		(end 462.54543 -246.616728)
		(width 0.20066)
		(layer "F.Cu")
		(net "M_H_CPU0_SB_PAR")
	)
	(segment
		(start 402.49983 -247.06072)
		(end 402.30679 -246.86768)
		(width 0.18288)
		(layer "In11.Cu")
		(net "M_H_CPU0_SB_PAR")
	)
	(segment
		(start 404.41753 -246.86768)
		(end 404.22449 -247.06072)
		(width 0.18288)
		(layer "In11.Cu")
		(net "M_H_CPU0_SB_PAR")
	)
	(segment
		(start 427.225968 -246.36476)
		(end 426.504354 -246.36476)
		(width 0.18288)
		(layer "In11.Cu")
		(net "M_H_CPU0_SB_PAR")
	)
	(segment
		(start 403.52091 -246.430292)
		(end 403.20341 -246.430292)
		(width 0.18288)
		(layer "In11.Cu")
		(net "M_H_CPU0_SB_PAR")
	)
	(segment
		(start 451.654672 -247.040654)
		(end 450.251322 -247.040654)
		(width 0.18288)
		(layer "In11.Cu")
		(net "M_H_CPU0_SB_PAR")
	)
	(segment
		(start 404.41753 -246.623332)
		(end 404.41753 -246.86768)
		(width 0.18288)
		(layer "In11.Cu")
		(net "M_H_CPU0_SB_PAR")
	)
	(segment
		(start 435.769512 -247.8913)
		(end 435.297834 -247.8913)
		(width 0.18288)
		(layer "In11.Cu")
		(net "M_H_CPU0_SB_PAR")
	)
	(segment
		(start 435.769766 -247.891046)
		(end 435.769512 -247.8913)
		(width 0.18288)
		(layer "In11.Cu")
		(net "M_H_CPU0_SB_PAR")
	)
	(segment
		(start 405.12111 -246.86768)
		(end 405.12111 -246.623332)
		(width 0.18288)
		(layer "In11.Cu")
		(net "M_H_CPU0_SB_PAR")
	)
	(segment
		(start 440.809126 -247.891046)
		(end 439.792618 -247.891046)
		(width 0.18288)
		(layer "In11.Cu")
		(net "M_H_CPU0_SB_PAR")
	)
	(segment
		(start 404.22449 -247.06072)
		(end 403.90699 -247.06072)
		(width 0.18288)
		(layer "In11.Cu")
		(net "M_H_CPU0_SB_PAR")
	)
	(segment
		(start 447.003678 -246.766842)
		(end 446.242694 -247.527826)
		(width 0.18288)
		(layer "In11.Cu")
		(net "M_H_CPU0_SB_PAR")
	)
	(segment
		(start 401.60321 -246.86768)
		(end 401.41017 -247.06072)
		(width 0.18288)
		(layer "In11.Cu")
		(net "M_H_CPU0_SB_PAR")
	)
	(segment
		(start 450.251322 -247.040654)
		(end 449.97751 -246.766842)
		(width 0.18288)
		(layer "In11.Cu")
		(net "M_H_CPU0_SB_PAR")
	)
	(segment
		(start 405.31415 -247.06072)
		(end 405.12111 -246.86768)
		(width 0.18288)
		(layer "In11.Cu")
		(net "M_H_CPU0_SB_PAR")
	)
	(segment
		(start 442.35497 -248.03735)
		(end 440.95543 -248.03735)
		(width 0.18288)
		(layer "In11.Cu")
		(net "M_H_CPU0_SB_PAR")
	)
	(segment
		(start 435.17439 -248.014744)
		(end 434.46319 -248.014744)
		(width 0.18288)
		(layer "In11.Cu")
		(net "M_H_CPU0_SB_PAR")
	)
	(segment
		(start 410.489146 -247.314466)
		(end 410.489146 -246.628666)
		(width 0.18288)
		(layer "In11.Cu")
		(net "M_H_CPU0_SB_PAR")
	)
	(segment
		(start 402.81733 -247.06072)
		(end 402.49983 -247.06072)
		(width 0.18288)
		(layer "In11.Cu")
		(net "M_H_CPU0_SB_PAR")
	)
	(segment
		(start 377.061984 -245.55069)
		(end 377.061984 -245.536466)
		(width 0.088646)
		(layer "In11.Cu")
		(net "M_H_CPU0_SB_PAR")
	)
	(segment
		(start 435.881526 -247.891046)
		(end 435.769766 -247.891046)
		(width 0.18288)
		(layer "In11.Cu")
		(net "M_H_CPU0_SB_PAR")
	)
	(segment
		(start 402.30679 -246.623332)
		(end 402.11375 -246.430292)
		(width 0.18288)
		(layer "In11.Cu")
		(net "M_H_CPU0_SB_PAR")
	)
	(segment
		(start 403.01037 -246.623332)
		(end 403.01037 -246.86768)
		(width 0.18288)
		(layer "In11.Cu")
		(net "M_H_CPU0_SB_PAR")
	)
	(segment
		(start 401.60321 -246.623332)
		(end 401.60321 -246.86768)
		(width 0.18288)
		(layer "In11.Cu")
		(net "M_H_CPU0_SB_PAR")
	)
	(segment
		(start 404.92807 -246.430292)
		(end 404.61057 -246.430292)
		(width 0.18288)
		(layer "In11.Cu")
		(net "M_H_CPU0_SB_PAR")
	)
	(segment
		(start 446.242694 -247.527826)
		(end 442.864494 -247.527826)
		(width 0.18288)
		(layer "In11.Cu")
		(net "M_H_CPU0_SB_PAR")
	)
	(segment
		(start 434.46319 -248.014744)
		(end 433.442872 -246.994426)
		(width 0.18288)
		(layer "In11.Cu")
		(net "M_H_CPU0_SB_PAR")
	)
	(segment
		(start 386.249672 -246.55907)
		(end 385.772406 -246.55907)
		(width 0.088646)
		(layer "In11.Cu")
		(net "M_H_CPU0_SB_PAR")
	)
	(segment
		(start 411.192726 -247.314466)
		(end 410.999686 -247.507506)
		(width 0.18288)
		(layer "In11.Cu")
		(net "M_H_CPU0_SB_PAR")
	)
	(segment
		(start 377.638564 -245.866412)
		(end 377.623832 -245.875048)
		(width 0.088646)
		(layer "In11.Cu")
		(net "M_H_CPU0_SB_PAR")
	)
	(segment
		(start 411.192726 -246.628666)
		(end 411.192726 -247.314466)
		(width 0.18288)
		(layer "In11.Cu")
		(net "M_H_CPU0_SB_PAR")
	)
	(segment
		(start 401.79625 -246.430292)
		(end 401.60321 -246.623332)
		(width 0.18288)
		(layer "In11.Cu")
		(net "M_H_CPU0_SB_PAR")
	)
	(segment
		(start 430.997868 -246.994426)
		(end 430.837594 -247.1547)
		(width 0.18288)
		(layer "In11.Cu")
		(net "M_H_CPU0_SB_PAR")
	)
	(segment
		(start 404.61057 -246.430292)
		(end 404.41753 -246.623332)
		(width 0.18288)
		(layer "In11.Cu")
		(net "M_H_CPU0_SB_PAR")
	)
	(segment
		(start 438.48909 -247.67921)
		(end 437.14416 -247.67921)
		(width 0.18288)
		(layer "In11.Cu")
		(net "M_H_CPU0_SB_PAR")
	)
	(segment
		(start 402.30679 -246.86768)
		(end 402.30679 -246.623332)
		(width 0.18288)
		(layer "In11.Cu")
		(net "M_H_CPU0_SB_PAR")
	)
	(segment
		(start 442.864494 -247.527826)
		(end 442.35497 -248.03735)
		(width 0.18288)
		(layer "In11.Cu")
		(net "M_H_CPU0_SB_PAR")
	)
	(segment
		(start 403.90699 -247.06072)
		(end 403.71395 -246.86768)
		(width 0.18288)
		(layer "In11.Cu")
		(net "M_H_CPU0_SB_PAR")
	)
	(segment
		(start 398.953228 -247.06072)
		(end 398.088358 -246.19585)
		(width 0.18288)
		(layer "In11.Cu")
		(net "M_H_CPU0_SB_PAR")
	)
	(segment
		(start 378.578364 -245.866412)
		(end 378.563632 -245.875048)
		(width 0.088646)
		(layer "In11.Cu")
		(net "M_H_CPU0_SB_PAR")
	)
	(segment
		(start 403.71395 -246.86768)
		(end 403.71395 -246.623332)
		(width 0.18288)
		(layer "In11.Cu")
		(net "M_H_CPU0_SB_PAR")
	)
	(segment
		(start 439.792618 -247.891046)
		(end 439.792364 -247.8913)
		(width 0.18288)
		(layer "In11.Cu")
		(net "M_H_CPU0_SB_PAR")
	)
	(segment
		(start 426.504354 -246.36476)
		(end 426.330364 -246.19077)
		(width 0.18288)
		(layer "In11.Cu")
		(net "M_H_CPU0_SB_PAR")
	)
	(segment
		(start 403.71395 -246.623332)
		(end 403.52091 -246.430292)
		(width 0.18288)
		(layer "In11.Cu")
		(net "M_H_CPU0_SB_PAR")
	)
	(segment
		(start 420.21887 -247.041162)
		(end 419.437058 -246.25935)
		(width 0.18288)
		(layer "In11.Cu")
		(net "M_H_CPU0_SB_PAR")
	)
	(segment
		(start 435.88178 -247.8913)
		(end 435.881526 -247.891046)
		(width 0.18288)
		(layer "In11.Cu")
		(net "M_H_CPU0_SB_PAR")
	)
	(segment
		(start 422.294304 -247.208548)
		(end 422.126918 -247.041162)
		(width 0.18288)
		(layer "In11.Cu")
		(net "M_H_CPU0_SB_PAR")
	)
	(segment
		(start 408.576272 -247.06072)
		(end 405.31415 -247.06072)
		(width 0.18288)
		(layer "In11.Cu")
		(net "M_H_CPU0_SB_PAR")
	)
	(segment
		(start 439.792364 -247.8913)
		(end 438.70118 -247.8913)
		(width 0.18288)
		(layer "In11.Cu")
		(net "M_H_CPU0_SB_PAR")
	)
	(segment
		(start 416.762438 -246.25935)
		(end 416.430714 -245.927626)
		(width 0.18288)
		(layer "In11.Cu")
		(net "M_H_CPU0_SB_PAR")
	)
	(segment
		(start 409.201366 -246.435626)
		(end 408.576272 -247.06072)
		(width 0.18288)
		(layer "In11.Cu")
		(net "M_H_CPU0_SB_PAR")
	)
	(segment
		(start 376.96648 -245.153434)
		(end 376.96648 -244.73662)
		(width 0.088646)
		(layer "In11.Cu")
		(net "M_H_CPU0_SB_PAR")
	)
	(segment
		(start 391.128504 -246.55907)
		(end 386.249672 -246.55907)
		(width 0.18288)
		(layer "In11.Cu")
		(net "M_H_CPU0_SB_PAR")
	)
	(segment
		(start 410.489146 -246.628666)
		(end 410.296106 -246.435626)
		(width 0.18288)
		(layer "In11.Cu")
		(net "M_H_CPU0_SB_PAR")
	)
	(segment
		(start 419.437058 -246.25935)
		(end 416.762438 -246.25935)
		(width 0.18288)
		(layer "In11.Cu")
		(net "M_H_CPU0_SB_PAR")
	)
	(segment
		(start 398.088358 -246.19585)
		(end 392.954256 -246.19585)
		(width 0.18288)
		(layer "In11.Cu")
		(net "M_H_CPU0_SB_PAR")
	)
	(segment
		(start 384.297936 -246.688864)
		(end 384.289046 -246.683784)
		(width 0.088646)
		(layer "In11.Cu")
		(net "M_H_CPU0_SB_PAR")
	)
	(segment
		(start 437.14416 -247.67921)
		(end 436.93207 -247.8913)
		(width 0.18288)
		(layer "In11.Cu")
		(net "M_H_CPU0_SB_PAR")
	)
	(segment
		(start 403.20341 -246.430292)
		(end 403.01037 -246.623332)
		(width 0.18288)
		(layer "In11.Cu")
		(net "M_H_CPU0_SB_PAR")
	)
	(segment
		(start 454.36028 -247.26773)
		(end 451.881748 -247.26773)
		(width 0.18288)
		(layer "In11.Cu")
		(net "M_H_CPU0_SB_PAR")
	)
	(segment
		(start 424.245786 -246.19077)
		(end 423.228008 -247.208548)
		(width 0.18288)
		(layer "In11.Cu")
		(net "M_H_CPU0_SB_PAR")
	)
	(segment
		(start 429.674274 -246.19331)
		(end 427.397418 -246.19331)
		(width 0.18288)
		(layer "In11.Cu")
		(net "M_H_CPU0_SB_PAR")
	)
	(segment
		(start 438.70118 -247.8913)
		(end 438.48909 -247.67921)
		(width 0.18288)
		(layer "In11.Cu")
		(net "M_H_CPU0_SB_PAR")
	)
	(segment
		(start 413.057594 -245.927626)
		(end 412.549594 -246.435626)
		(width 0.18288)
		(layer "In11.Cu")
		(net "M_H_CPU0_SB_PAR")
	)
	(segment
		(start 405.12111 -246.623332)
		(end 404.92807 -246.430292)
		(width 0.18288)
		(layer "In11.Cu")
		(net "M_H_CPU0_SB_PAR")
	)
	(segment
		(start 412.549594 -246.435626)
		(end 411.385766 -246.435626)
		(width 0.18288)
		(layer "In11.Cu")
		(net "M_H_CPU0_SB_PAR")
	)
	(segment
		(start 410.682186 -247.507506)
		(end 410.489146 -247.314466)
		(width 0.18288)
		(layer "In11.Cu")
		(net "M_H_CPU0_SB_PAR")
	)
	(segment
		(start 410.999686 -247.507506)
		(end 410.682186 -247.507506)
		(width 0.18288)
		(layer "In11.Cu")
		(net "M_H_CPU0_SB_PAR")
	)
	(segment
		(start 401.41017 -247.06072)
		(end 398.953228 -247.06072)
		(width 0.18288)
		(layer "In11.Cu")
		(net "M_H_CPU0_SB_PAR")
	)
	(segment
		(start 380.453392 -245.868952)
		(end 380.442978 -245.875048)
		(width 0.088646)
		(layer "In11.Cu")
		(net "M_H_CPU0_SB_PAR")
	)
	(segment
		(start 423.228008 -247.208548)
		(end 422.294304 -247.208548)
		(width 0.18288)
		(layer "In11.Cu")
		(net "M_H_CPU0_SB_PAR")
	)
	(segment
		(start 435.297834 -247.8913)
		(end 435.17439 -248.014744)
		(width 0.18288)
		(layer "In11.Cu")
		(net "M_H_CPU0_SB_PAR")
	)
	(segment
		(start 433.442872 -246.994426)
		(end 430.997868 -246.994426)
		(width 0.18288)
		(layer "In11.Cu")
		(net "M_H_CPU0_SB_PAR")
	)
	(segment
		(start 410.296106 -246.435626)
		(end 409.201366 -246.435626)
		(width 0.18288)
		(layer "In11.Cu")
		(net "M_H_CPU0_SB_PAR")
	)
	(segment
		(start 385.772406 -246.55907)
		(end 385.592574 -246.738902)
		(width 0.088646)
		(layer "In11.Cu")
		(net "M_H_CPU0_SB_PAR")
	)
	(segment
		(start 451.881748 -247.26773)
		(end 451.654672 -247.040654)
		(width 0.18288)
		(layer "In11.Cu")
		(net "M_H_CPU0_SB_PAR")
	)
	(segment
		(start 426.330364 -246.19077)
		(end 424.245786 -246.19077)
		(width 0.18288)
		(layer "In11.Cu")
		(net "M_H_CPU0_SB_PAR")
	)
	(segment
		(start 403.01037 -246.86768)
		(end 402.81733 -247.06072)
		(width 0.18288)
		(layer "In11.Cu")
		(net "M_H_CPU0_SB_PAR")
	)
	(segment
		(start 411.385766 -246.435626)
		(end 411.192726 -246.628666)
		(width 0.18288)
		(layer "In11.Cu")
		(net "M_H_CPU0_SB_PAR")
	)
	(segment
		(start 384.110484 -246.364506)
		(end 384.110484 -246.3546)
		(width 0.088646)
		(layer "In11.Cu")
		(net "M_H_CPU0_SB_PAR")
	)
	(segment
		(start 379.513846 -245.868952)
		(end 379.503432 -245.875048)
		(width 0.088646)
		(layer "In11.Cu")
		(net "M_H_CPU0_SB_PAR")
	)
	(segment
		(start 430.184814 -247.1547)
		(end 430.024794 -246.99468)
		(width 0.18288)
		(layer "In11.Cu")
		(net "M_H_CPU0_SB_PAR")
	)
	(segment
		(start 430.024794 -246.99468)
		(end 430.024794 -246.54383)
		(width 0.18288)
		(layer "In11.Cu")
		(net "M_H_CPU0_SB_PAR")
	)
	(segment
		(start 455.011282 -246.616728)
		(end 454.36028 -247.26773)
		(width 0.18288)
		(layer "In11.Cu")
		(net "M_H_CPU0_SB_PAR")
	)
	(segment
		(start 422.126918 -247.041162)
		(end 420.21887 -247.041162)
		(width 0.18288)
		(layer "In11.Cu")
		(net "M_H_CPU0_SB_PAR")
	)
	(segment
		(start 402.11375 -246.430292)
		(end 401.79625 -246.430292)
		(width 0.18288)
		(layer "In11.Cu")
		(net "M_H_CPU0_SB_PAR")
	)
	(segment
		(start 430.024794 -246.54383)
		(end 429.674274 -246.19331)
		(width 0.18288)
		(layer "In11.Cu")
		(net "M_H_CPU0_SB_PAR")
	)
	(segment
		(start 436.93207 -247.8913)
		(end 435.88178 -247.8913)
		(width 0.18288)
		(layer "In11.Cu")
		(net "M_H_CPU0_SB_PAR")
	)
	(segment
		(start 449.97751 -246.766842)
		(end 447.003678 -246.766842)
		(width 0.18288)
		(layer "In11.Cu")
		(net "M_H_CPU0_SB_PAR")
	)
	(segment
		(start 392.954256 -246.19585)
		(end 391.128504 -246.55907)
		(width 0.18288)
		(layer "In11.Cu")
		(net "M_H_CPU0_SB_PAR")
	)
	(segment
		(start 385.592574 -246.738902)
		(end 385.426966 -246.738902)
		(width 0.088646)
		(layer "In11.Cu")
		(net "M_H_CPU0_SB_PAR")
	)
	(segment
		(start 430.837594 -247.1547)
		(end 430.184814 -247.1547)
		(width 0.18288)
		(layer "In11.Cu")
		(net "M_H_CPU0_SB_PAR")
	)
	(segment
		(start 427.397418 -246.19331)
		(end 427.225968 -246.36476)
		(width 0.18288)
		(layer "In11.Cu")
		(net "M_H_CPU0_SB_PAR")
	)
	(segment
		(start 440.95543 -248.03735)
		(end 440.809126 -247.891046)
		(width 0.18288)
		(layer "In11.Cu")
		(net "M_H_CPU0_SB_PAR")
	)
	(segment
		(start 416.430714 -245.927626)
		(end 413.057594 -245.927626)
		(width 0.18288)
		(layer "In11.Cu")
		(net "M_H_CPU0_SB_PAR")
	)
	(arc
		(start 381.383032 -245.875048)
		(mid 381.195834 -245.925191)
		(end 381.008636 -245.875048)
		(width 0.088646)
		(layer "In11.Cu")
		(net "M_H_CPU0_SB_PAR")
	)
	(arc
		(start 377.439682 -245.925086)
		(mid 377.240078 -245.869355)
		(end 377.100592 -245.716044)
		(width 0.088646)
		(layer "In11.Cu")
		(net "M_H_CPU0_SB_PAR")
	)
	(arc
		(start 377.000262 -245.293642)
		(mid 376.975086 -245.225538)
		(end 376.96648 -245.153434)
		(width 0.088646)
		(layer "In11.Cu")
		(net "M_H_CPU0_SB_PAR")
	)
	(arc
		(start 384.672332 -246.688864)
		(mid 384.485134 -246.739007)
		(end 384.297936 -246.688864)
		(width 0.088646)
		(layer "In11.Cu")
		(net "M_H_CPU0_SB_PAR")
	)
	(arc
		(start 377.623832 -245.875048)
		(mid 377.534996 -245.911981)
		(end 377.439682 -245.925086)
		(width 0.088646)
		(layer "In11.Cu")
		(net "M_H_CPU0_SB_PAR")
	)
	(arc
		(start 379.503432 -245.875048)
		(mid 379.316234 -245.925191)
		(end 379.129036 -245.875048)
		(width 0.088646)
		(layer "In11.Cu")
		(net "M_H_CPU0_SB_PAR")
	)
	(arc
		(start 380.442978 -245.875048)
		(mid 380.25578 -245.925191)
		(end 380.068582 -245.875048)
		(width 0.088646)
		(layer "In11.Cu")
		(net "M_H_CPU0_SB_PAR")
	)
	(arc
		(start 385.237736 -246.688864)
		(mid 384.955034 -246.613088)
		(end 384.672332 -246.688864)
		(width 0.088646)
		(layer "In11.Cu")
		(net "M_H_CPU0_SB_PAR")
	)
	(arc
		(start 383.262632 -245.875048)
		(mid 383.075434 -245.925191)
		(end 382.888236 -245.875048)
		(width 0.088646)
		(layer "In11.Cu")
		(net "M_H_CPU0_SB_PAR")
	)
	(arc
		(start 380.068582 -245.875048)
		(mid 379.792023 -245.799305)
		(end 379.513846 -245.868952)
		(width 0.088646)
		(layer "In11.Cu")
		(net "M_H_CPU0_SB_PAR")
	)
	(arc
		(start 377.100592 -245.716044)
		(mid 377.071789 -245.635582)
		(end 377.061984 -245.55069)
		(width 0.088646)
		(layer "In11.Cu")
		(net "M_H_CPU0_SB_PAR")
	)
	(arc
		(start 378.189236 -245.875048)
		(mid 377.915037 -245.799213)
		(end 377.638564 -245.866412)
		(width 0.088646)
		(layer "In11.Cu")
		(net "M_H_CPU0_SB_PAR")
	)
	(arc
		(start 377.061984 -245.536466)
		(mid 377.044727 -245.411598)
		(end 377.000262 -245.293642)
		(width 0.088646)
		(layer "In11.Cu")
		(net "M_H_CPU0_SB_PAR")
	)
	(arc
		(start 381.008636 -245.875048)
		(mid 380.731823 -245.799178)
		(end 380.453392 -245.868952)
		(width 0.088646)
		(layer "In11.Cu")
		(net "M_H_CPU0_SB_PAR")
	)
	(arc
		(start 382.888236 -245.875048)
		(mid 382.605534 -245.799272)
		(end 382.322832 -245.875048)
		(width 0.088646)
		(layer "In11.Cu")
		(net "M_H_CPU0_SB_PAR")
	)
	(arc
		(start 384.289046 -246.683784)
		(mid 384.158132 -246.547424)
		(end 384.110484 -246.364506)
		(width 0.088646)
		(layer "In11.Cu")
		(net "M_H_CPU0_SB_PAR")
	)
	(arc
		(start 378.563632 -245.875048)
		(mid 378.376434 -245.925191)
		(end 378.189236 -245.875048)
		(width 0.088646)
		(layer "In11.Cu")
		(net "M_H_CPU0_SB_PAR")
	)
	(arc
		(start 379.129036 -245.875048)
		(mid 378.854837 -245.799213)
		(end 378.578364 -245.866412)
		(width 0.088646)
		(layer "In11.Cu")
		(net "M_H_CPU0_SB_PAR")
	)
	(arc
		(start 385.426966 -246.738902)
		(mid 385.329018 -246.726482)
		(end 385.237736 -246.688864)
		(width 0.088646)
		(layer "In11.Cu")
		(net "M_H_CPU0_SB_PAR")
	)
	(arc
		(start 381.948436 -245.875048)
		(mid 381.665734 -245.799272)
		(end 381.383032 -245.875048)
		(width 0.088646)
		(layer "In11.Cu")
		(net "M_H_CPU0_SB_PAR")
	)
	(arc
		(start 382.322832 -245.875048)
		(mid 382.135634 -245.925191)
		(end 381.948436 -245.875048)
		(width 0.088646)
		(layer "In11.Cu")
		(net "M_H_CPU0_SB_PAR")
	)
	(arc
		(start 383.828036 -245.875048)
		(mid 383.545334 -245.799272)
		(end 383.262632 -245.875048)
		(width 0.088646)
		(layer "In11.Cu")
		(net "M_H_CPU0_SB_PAR")
	)
	(arc
		(start 384.110484 -246.3546)
		(mid 384.032373 -246.077651)
		(end 383.828036 -245.875048)
		(width 0.088646)
		(layer "In11.Cu")
		(net "M_H_CPU0_SB_PAR")
	)
	(segment
		(start 450.911214 -238.116618)
		(end 452.016114 -238.116618)
		(width 0.20066)
		(layer "F.Cu")
		(net "M_H_CPU0_SB_DQS_DP<9>")
	)
	(segment
		(start 453.860916 -238.290608)
		(end 453.446388 -237.87608)
		(width 0.20066)
		(layer "F.Cu")
		(net "M_H_CPU0_SB_DQS_DP<9>")
	)
	(segment
		(start 452.605394 -238.116618)
		(end 452.016114 -238.116618)
		(width 0.20066)
		(layer "F.Cu")
		(net "M_H_CPU0_SB_DQS_DP<9>")
	)
	(segment
		(start 458.729588 -237.834932)
		(end 458.5335 -237.834932)
		(width 0.20066)
		(layer "F.Cu")
		(net "M_H_CPU0_SB_DQS_DP<9>")
	)
	(segment
		(start 457.75245 -238.245396)
		(end 457.449936 -238.54791)
		(width 0.20066)
		(layer "F.Cu")
		(net "M_H_CPU0_SB_DQS_DP<9>")
	)
	(segment
		(start 457.126594 -238.54791)
		(end 457.120498 -238.541814)
		(width 0.1016)
		(layer "F.Cu")
		(net "M_H_CPU0_SB_DQS_DP<9>")
	)
	(segment
		(start 370.858034 -242.830604)
		(end 370.858034 -242.294918)
		(width 0.20066)
		(layer "F.Cu")
		(net "M_H_CPU0_SB_DQS_DP<9>")
	)
	(segment
		(start 457.449936 -238.54791)
		(end 457.126594 -238.54791)
		(width 0.20066)
		(layer "F.Cu")
		(net "M_H_CPU0_SB_DQS_DP<9>")
	)
	(segment
		(start 370.85778 -242.830858)
		(end 370.858034 -242.830604)
		(width 0.20066)
		(layer "F.Cu")
		(net "M_H_CPU0_SB_DQS_DP<9>")
	)
	(segment
		(start 458.123036 -238.245396)
		(end 457.75245 -238.245396)
		(width 0.20066)
		(layer "F.Cu")
		(net "M_H_CPU0_SB_DQS_DP<9>")
	)
	(segment
		(start 454.963276 -238.541814)
		(end 454.937368 -238.541814)
		(width 0.101854)
		(layer "F.Cu")
		(net "M_H_CPU0_SB_DQS_DP<9>")
	)
	(segment
		(start 454.546716 -238.290608)
		(end 453.860916 -238.290608)
		(width 0.20066)
		(layer "F.Cu")
		(net "M_H_CPU0_SB_DQS_DP<9>")
	)
	(segment
		(start 454.797922 -238.541814)
		(end 454.546716 -238.290608)
		(width 0.20066)
		(layer "F.Cu")
		(net "M_H_CPU0_SB_DQS_DP<9>")
	)
	(segment
		(start 459.011274 -238.116618)
		(end 458.729588 -237.834932)
		(width 0.20066)
		(layer "F.Cu")
		(net "M_H_CPU0_SB_DQS_DP<9>")
	)
	(segment
		(start 454.937368 -238.541814)
		(end 454.797922 -238.541814)
		(width 0.20066)
		(layer "F.Cu")
		(net "M_H_CPU0_SB_DQS_DP<9>")
	)
	(segment
		(start 452.845932 -237.87608)
		(end 452.605394 -238.116618)
		(width 0.20066)
		(layer "F.Cu")
		(net "M_H_CPU0_SB_DQS_DP<9>")
	)
	(segment
		(start 453.446388 -237.87608)
		(end 452.845932 -237.87608)
		(width 0.20066)
		(layer "F.Cu")
		(net "M_H_CPU0_SB_DQS_DP<9>")
	)
	(segment
		(start 458.5335 -237.834932)
		(end 458.123036 -238.245396)
		(width 0.20066)
		(layer "F.Cu")
		(net "M_H_CPU0_SB_DQS_DP<9>")
	)
	(segment
		(start 457.120498 -238.541814)
		(end 454.963276 -238.541814)
		(width 0.1016)
		(layer "F.Cu")
		(net "M_H_CPU0_SB_DQS_DP<9>")
	)
	(segment
		(start 459.559914 -238.116618)
		(end 459.011274 -238.116618)
		(width 0.20066)
		(layer "F.Cu")
		(net "M_H_CPU0_SB_DQS_DP<9>")
	)
	(segment
		(start 374.344946 -242.790726)
		(end 374.334532 -242.78463)
		(width 0.088646)
		(layer "In11.Cu")
		(net "M_H_CPU0_SB_DQS_DP<9>")
	)
	(segment
		(start 431.564542 -235.875576)
		(end 427.806866 -235.875576)
		(width 0.18288)
		(layer "In11.Cu")
		(net "M_H_CPU0_SB_DQS_DP<9>")
	)
	(segment
		(start 439.385202 -238.233966)
		(end 438.382664 -238.233966)
		(width 0.18288)
		(layer "In11.Cu")
		(net "M_H_CPU0_SB_DQS_DP<9>")
	)
	(segment
		(start 436.316374 -236.575854)
		(end 436.051452 -236.840776)
		(width 0.18288)
		(layer "In11.Cu")
		(net "M_H_CPU0_SB_DQS_DP<9>")
	)
	(segment
		(start 436.724552 -236.575854)
		(end 436.316374 -236.575854)
		(width 0.18288)
		(layer "In11.Cu")
		(net "M_H_CPU0_SB_DQS_DP<9>")
	)
	(segment
		(start 420.440866 -236.84103)
		(end 420.191946 -236.59211)
		(width 0.18288)
		(layer "In11.Cu")
		(net "M_H_CPU0_SB_DQS_DP<9>")
	)
	(segment
		(start 372.080282 -242.78463)
		(end 372.06555 -242.793266)
		(width 0.088646)
		(layer "In11.Cu")
		(net "M_H_CPU0_SB_DQS_DP<9>")
	)
	(segment
		(start 424.34383 -235.699554)
		(end 423.139616 -235.699554)
		(width 0.18288)
		(layer "In11.Cu")
		(net "M_H_CPU0_SB_DQS_DP<9>")
	)
	(segment
		(start 378.658882 -242.78463)
		(end 378.64415 -242.793266)
		(width 0.088646)
		(layer "In11.Cu")
		(net "M_H_CPU0_SB_DQS_DP<9>")
	)
	(segment
		(start 447.105532 -237.388146)
		(end 442.17971 -237.388146)
		(width 0.18288)
		(layer "In11.Cu")
		(net "M_H_CPU0_SB_DQS_DP<9>")
	)
	(segment
		(start 396.006574 -243.460524)
		(end 389.019796 -243.460524)
		(width 0.18288)
		(layer "In11.Cu")
		(net "M_H_CPU0_SB_DQS_DP<9>")
	)
	(segment
		(start 450.183504 -237.85957)
		(end 450.001894 -237.67796)
		(width 0.18288)
		(layer "In11.Cu")
		(net "M_H_CPU0_SB_DQS_DP<9>")
	)
	(segment
		(start 371.235986 -242.360196)
		(end 371.170708 -242.294918)
		(width 0.088646)
		(layer "In11.Cu")
		(net "M_H_CPU0_SB_DQS_DP<9>")
	)
	(segment
		(start 388.959852 -243.40058)
		(end 385.307078 -243.40058)
		(width 0.088646)
		(layer "In11.Cu")
		(net "M_H_CPU0_SB_DQS_DP<9>")
	)
	(segment
		(start 371.170708 -242.294918)
		(end 370.858034 -242.294918)
		(width 0.088646)
		(layer "In11.Cu")
		(net "M_H_CPU0_SB_DQS_DP<9>")
	)
	(segment
		(start 423.139616 -235.699554)
		(end 422.262808 -236.576362)
		(width 0.18288)
		(layer "In11.Cu")
		(net "M_H_CPU0_SB_DQS_DP<9>")
	)
	(segment
		(start 439.693558 -238.542322)
		(end 439.385202 -238.233966)
		(width 0.18288)
		(layer "In11.Cu")
		(net "M_H_CPU0_SB_DQS_DP<9>")
	)
	(segment
		(start 420.191946 -236.59211)
		(end 416.51428 -236.59211)
		(width 0.18288)
		(layer "In11.Cu")
		(net "M_H_CPU0_SB_DQS_DP<9>")
	)
	(segment
		(start 383.358136 -242.78463)
		(end 383.347722 -242.790726)
		(width 0.088646)
		(layer "In11.Cu")
		(net "M_H_CPU0_SB_DQS_DP<9>")
	)
	(segment
		(start 442.17971 -237.388146)
		(end 441.291472 -238.276384)
		(width 0.18288)
		(layer "In11.Cu")
		(net "M_H_CPU0_SB_DQS_DP<9>")
	)
	(segment
		(start 427.328584 -236.353858)
		(end 426.634148 -236.353858)
		(width 0.18288)
		(layer "In11.Cu")
		(net "M_H_CPU0_SB_DQS_DP<9>")
	)
	(segment
		(start 400.960844 -238.506254)
		(end 396.006574 -243.460524)
		(width 0.18288)
		(layer "In11.Cu")
		(net "M_H_CPU0_SB_DQS_DP<9>")
	)
	(segment
		(start 373.020082 -242.78463)
		(end 373.00535 -242.793266)
		(width 0.088646)
		(layer "In11.Cu")
		(net "M_H_CPU0_SB_DQS_DP<9>")
	)
	(segment
		(start 425.064174 -235.991146)
		(end 424.635422 -235.991146)
		(width 0.18288)
		(layer "In11.Cu")
		(net "M_H_CPU0_SB_DQS_DP<9>")
	)
	(segment
		(start 426.634148 -236.353858)
		(end 426.006768 -235.726478)
		(width 0.18288)
		(layer "In11.Cu")
		(net "M_H_CPU0_SB_DQS_DP<9>")
	)
	(segment
		(start 420.964106 -236.84103)
		(end 420.440866 -236.84103)
		(width 0.18288)
		(layer "In11.Cu")
		(net "M_H_CPU0_SB_DQS_DP<9>")
	)
	(segment
		(start 432.269392 -236.580426)
		(end 431.564542 -235.875576)
		(width 0.18288)
		(layer "In11.Cu")
		(net "M_H_CPU0_SB_DQS_DP<9>")
	)
	(segment
		(start 447.806572 -237.67796)
		(end 447.105532 -237.388146)
		(width 0.18288)
		(layer "In11.Cu")
		(net "M_H_CPU0_SB_DQS_DP<9>")
	)
	(segment
		(start 380.538736 -242.78463)
		(end 380.528322 -242.790726)
		(width 0.088646)
		(layer "In11.Cu")
		(net "M_H_CPU0_SB_DQS_DP<9>")
	)
	(segment
		(start 424.635422 -235.991146)
		(end 424.34383 -235.699554)
		(width 0.18288)
		(layer "In11.Cu")
		(net "M_H_CPU0_SB_DQS_DP<9>")
	)
	(segment
		(start 406.926034 -238.506254)
		(end 400.960844 -238.506254)
		(width 0.18288)
		(layer "In11.Cu")
		(net "M_H_CPU0_SB_DQS_DP<9>")
	)
	(segment
		(start 415.814256 -237.292134)
		(end 408.140154 -237.292134)
		(width 0.18288)
		(layer "In11.Cu")
		(net "M_H_CPU0_SB_DQS_DP<9>")
	)
	(segment
		(start 389.019796 -243.460524)
		(end 388.959852 -243.40058)
		(width 0.088646)
		(layer "In11.Cu")
		(net "M_H_CPU0_SB_DQS_DP<9>")
	)
	(segment
		(start 422.262808 -236.576362)
		(end 421.228774 -236.576362)
		(width 0.18288)
		(layer "In11.Cu")
		(net "M_H_CPU0_SB_DQS_DP<9>")
	)
	(segment
		(start 425.328842 -235.726478)
		(end 425.064174 -235.991146)
		(width 0.18288)
		(layer "In11.Cu")
		(net "M_H_CPU0_SB_DQS_DP<9>")
	)
	(segment
		(start 441.291472 -238.276384)
		(end 440.404504 -238.276384)
		(width 0.18288)
		(layer "In11.Cu")
		(net "M_H_CPU0_SB_DQS_DP<9>")
	)
	(segment
		(start 375.839482 -242.78463)
		(end 375.82475 -242.793266)
		(width 0.088646)
		(layer "In11.Cu")
		(net "M_H_CPU0_SB_DQS_DP<9>")
	)
	(segment
		(start 435.269386 -236.580426)
		(end 432.269392 -236.580426)
		(width 0.18288)
		(layer "In11.Cu")
		(net "M_H_CPU0_SB_DQS_DP<9>")
	)
	(segment
		(start 408.140154 -237.292134)
		(end 406.926034 -238.506254)
		(width 0.18288)
		(layer "In11.Cu")
		(net "M_H_CPU0_SB_DQS_DP<9>")
	)
	(segment
		(start 373.960136 -242.78463)
		(end 373.949722 -242.790726)
		(width 0.088646)
		(layer "In11.Cu")
		(net "M_H_CPU0_SB_DQS_DP<9>")
	)
	(segment
		(start 426.006768 -235.726478)
		(end 425.328842 -235.726478)
		(width 0.18288)
		(layer "In11.Cu")
		(net "M_H_CPU0_SB_DQS_DP<9>")
	)
	(segment
		(start 427.806866 -235.875576)
		(end 427.328584 -236.353858)
		(width 0.18288)
		(layer "In11.Cu")
		(net "M_H_CPU0_SB_DQS_DP<9>")
	)
	(segment
		(start 440.138566 -238.542322)
		(end 439.693558 -238.542322)
		(width 0.18288)
		(layer "In11.Cu")
		(net "M_H_CPU0_SB_DQS_DP<9>")
	)
	(segment
		(start 438.382664 -238.233966)
		(end 436.724552 -236.575854)
		(width 0.18288)
		(layer "In11.Cu")
		(net "M_H_CPU0_SB_DQS_DP<9>")
	)
	(segment
		(start 416.51428 -236.59211)
		(end 415.814256 -237.292134)
		(width 0.18288)
		(layer "In11.Cu")
		(net "M_H_CPU0_SB_DQS_DP<9>")
	)
	(segment
		(start 376.779282 -242.78463)
		(end 376.76455 -242.793266)
		(width 0.088646)
		(layer "In11.Cu")
		(net "M_H_CPU0_SB_DQS_DP<9>")
	)
	(segment
		(start 450.001894 -237.67796)
		(end 447.806572 -237.67796)
		(width 0.18288)
		(layer "In11.Cu")
		(net "M_H_CPU0_SB_DQS_DP<9>")
	)
	(segment
		(start 450.911214 -238.116618)
		(end 450.654166 -237.85957)
		(width 0.18288)
		(layer "In11.Cu")
		(net "M_H_CPU0_SB_DQS_DP<9>")
	)
	(segment
		(start 379.598682 -242.78463)
		(end 379.58395 -242.793266)
		(width 0.088646)
		(layer "In11.Cu")
		(net "M_H_CPU0_SB_DQS_DP<9>")
	)
	(segment
		(start 450.654166 -237.85957)
		(end 450.183504 -237.85957)
		(width 0.18288)
		(layer "In11.Cu")
		(net "M_H_CPU0_SB_DQS_DP<9>")
	)
	(segment
		(start 382.418082 -242.78463)
		(end 382.407668 -242.790726)
		(width 0.088646)
		(layer "In11.Cu")
		(net "M_H_CPU0_SB_DQS_DP<9>")
	)
	(segment
		(start 435.529736 -236.840776)
		(end 435.269386 -236.580426)
		(width 0.18288)
		(layer "In11.Cu")
		(net "M_H_CPU0_SB_DQS_DP<9>")
	)
	(segment
		(start 385.307078 -243.40058)
		(end 384.75031 -242.843812)
		(width 0.088646)
		(layer "In11.Cu")
		(net "M_H_CPU0_SB_DQS_DP<9>")
	)
	(segment
		(start 421.228774 -236.576362)
		(end 420.964106 -236.84103)
		(width 0.18288)
		(layer "In11.Cu")
		(net "M_H_CPU0_SB_DQS_DP<9>")
	)
	(segment
		(start 440.404504 -238.276384)
		(end 440.138566 -238.542322)
		(width 0.18288)
		(layer "In11.Cu")
		(net "M_H_CPU0_SB_DQS_DP<9>")
	)
	(segment
		(start 377.719082 -242.78463)
		(end 377.70435 -242.793266)
		(width 0.088646)
		(layer "In11.Cu")
		(net "M_H_CPU0_SB_DQS_DP<9>")
	)
	(segment
		(start 436.051452 -236.840776)
		(end 435.529736 -236.840776)
		(width 0.18288)
		(layer "In11.Cu")
		(net "M_H_CPU0_SB_DQS_DP<9>")
	)
	(arc
		(start 378.64415 -242.793266)
		(mid 378.367709 -242.860432)
		(end 378.093478 -242.78463)
		(width 0.088646)
		(layer "In11.Cu")
		(net "M_H_CPU0_SB_DQS_DP<9>")
	)
	(arc
		(start 376.213878 -242.78463)
		(mid 376.02668 -242.734487)
		(end 375.839482 -242.78463)
		(width 0.088646)
		(layer "In11.Cu")
		(net "M_H_CPU0_SB_DQS_DP<9>")
	)
	(arc
		(start 378.093478 -242.78463)
		(mid 377.90628 -242.734487)
		(end 377.719082 -242.78463)
		(width 0.088646)
		(layer "In11.Cu")
		(net "M_H_CPU0_SB_DQS_DP<9>")
	)
	(arc
		(start 381.478536 -242.78463)
		(mid 381.195834 -242.860372)
		(end 380.913132 -242.78463)
		(width 0.088646)
		(layer "In11.Cu")
		(net "M_H_CPU0_SB_DQS_DP<9>")
	)
	(arc
		(start 374.899682 -242.78463)
		(mid 374.623123 -242.860373)
		(end 374.344946 -242.790726)
		(width 0.088646)
		(layer "In11.Cu")
		(net "M_H_CPU0_SB_DQS_DP<9>")
	)
	(arc
		(start 377.70435 -242.793266)
		(mid 377.427909 -242.860432)
		(end 377.153678 -242.78463)
		(width 0.088646)
		(layer "In11.Cu")
		(net "M_H_CPU0_SB_DQS_DP<9>")
	)
	(arc
		(start 372.454678 -242.78463)
		(mid 372.26748 -242.734487)
		(end 372.080282 -242.78463)
		(width 0.088646)
		(layer "In11.Cu")
		(net "M_H_CPU0_SB_DQS_DP<9>")
	)
	(arc
		(start 379.58395 -242.793266)
		(mid 379.307509 -242.860432)
		(end 379.033278 -242.78463)
		(width 0.088646)
		(layer "In11.Cu")
		(net "M_H_CPU0_SB_DQS_DP<9>")
	)
	(arc
		(start 373.00535 -242.793266)
		(mid 372.728875 -242.860586)
		(end 372.454678 -242.78463)
		(width 0.088646)
		(layer "In11.Cu")
		(net "M_H_CPU0_SB_DQS_DP<9>")
	)
	(arc
		(start 380.528322 -242.790726)
		(mid 380.24989 -242.86054)
		(end 379.973078 -242.78463)
		(width 0.088646)
		(layer "In11.Cu")
		(net "M_H_CPU0_SB_DQS_DP<9>")
	)
	(arc
		(start 373.394478 -242.78463)
		(mid 373.20728 -242.734487)
		(end 373.020082 -242.78463)
		(width 0.088646)
		(layer "In11.Cu")
		(net "M_H_CPU0_SB_DQS_DP<9>")
	)
	(arc
		(start 380.913132 -242.78463)
		(mid 380.725934 -242.734487)
		(end 380.538736 -242.78463)
		(width 0.088646)
		(layer "In11.Cu")
		(net "M_H_CPU0_SB_DQS_DP<9>")
	)
	(arc
		(start 382.792478 -242.78463)
		(mid 382.60528 -242.734487)
		(end 382.418082 -242.78463)
		(width 0.088646)
		(layer "In11.Cu")
		(net "M_H_CPU0_SB_DQS_DP<9>")
	)
	(arc
		(start 371.23878 -242.381532)
		(mid 371.237282 -242.370877)
		(end 371.235986 -242.360196)
		(width 0.088646)
		(layer "In11.Cu")
		(net "M_H_CPU0_SB_DQS_DP<9>")
	)
	(arc
		(start 377.153678 -242.78463)
		(mid 376.96648 -242.734487)
		(end 376.779282 -242.78463)
		(width 0.088646)
		(layer "In11.Cu")
		(net "M_H_CPU0_SB_DQS_DP<9>")
	)
	(arc
		(start 375.82475 -242.793266)
		(mid 375.548309 -242.860432)
		(end 375.274078 -242.78463)
		(width 0.088646)
		(layer "In11.Cu")
		(net "M_H_CPU0_SB_DQS_DP<9>")
	)
	(arc
		(start 382.407668 -242.790726)
		(mid 382.12949 -242.860418)
		(end 381.852932 -242.78463)
		(width 0.088646)
		(layer "In11.Cu")
		(net "M_H_CPU0_SB_DQS_DP<9>")
	)
	(arc
		(start 383.347722 -242.790726)
		(mid 383.06929 -242.86054)
		(end 382.792478 -242.78463)
		(width 0.088646)
		(layer "In11.Cu")
		(net "M_H_CPU0_SB_DQS_DP<9>")
	)
	(arc
		(start 371.514878 -242.78463)
		(mid 371.331054 -242.614436)
		(end 371.23878 -242.381532)
		(width 0.088646)
		(layer "In11.Cu")
		(net "M_H_CPU0_SB_DQS_DP<9>")
	)
	(arc
		(start 384.297936 -242.78463)
		(mid 384.015234 -242.860372)
		(end 383.732532 -242.78463)
		(width 0.088646)
		(layer "In11.Cu")
		(net "M_H_CPU0_SB_DQS_DP<9>")
	)
	(arc
		(start 374.334532 -242.78463)
		(mid 374.147334 -242.734487)
		(end 373.960136 -242.78463)
		(width 0.088646)
		(layer "In11.Cu")
		(net "M_H_CPU0_SB_DQS_DP<9>")
	)
	(arc
		(start 383.732532 -242.78463)
		(mid 383.545334 -242.734487)
		(end 383.358136 -242.78463)
		(width 0.088646)
		(layer "In11.Cu")
		(net "M_H_CPU0_SB_DQS_DP<9>")
	)
	(arc
		(start 379.973078 -242.78463)
		(mid 379.78588 -242.734487)
		(end 379.598682 -242.78463)
		(width 0.088646)
		(layer "In11.Cu")
		(net "M_H_CPU0_SB_DQS_DP<9>")
	)
	(arc
		(start 372.06555 -242.793266)
		(mid 371.789075 -242.860556)
		(end 371.514878 -242.78463)
		(width 0.088646)
		(layer "In11.Cu")
		(net "M_H_CPU0_SB_DQS_DP<9>")
	)
	(arc
		(start 373.949722 -242.790726)
		(mid 373.67129 -242.860572)
		(end 373.394478 -242.78463)
		(width 0.088646)
		(layer "In11.Cu")
		(net "M_H_CPU0_SB_DQS_DP<9>")
	)
	(arc
		(start 384.75031 -242.843812)
		(mid 384.71326 -242.811666)
		(end 384.672332 -242.78463)
		(width 0.088646)
		(layer "In11.Cu")
		(net "M_H_CPU0_SB_DQS_DP<9>")
	)
	(arc
		(start 376.76455 -242.793266)
		(mid 376.488109 -242.860432)
		(end 376.213878 -242.78463)
		(width 0.088646)
		(layer "In11.Cu")
		(net "M_H_CPU0_SB_DQS_DP<9>")
	)
	(arc
		(start 375.274078 -242.78463)
		(mid 375.08688 -242.734487)
		(end 374.899682 -242.78463)
		(width 0.088646)
		(layer "In11.Cu")
		(net "M_H_CPU0_SB_DQS_DP<9>")
	)
	(arc
		(start 384.672332 -242.78463)
		(mid 384.485134 -242.734487)
		(end 384.297936 -242.78463)
		(width 0.088646)
		(layer "In11.Cu")
		(net "M_H_CPU0_SB_DQS_DP<9>")
	)
	(arc
		(start 381.852932 -242.78463)
		(mid 381.665734 -242.734487)
		(end 381.478536 -242.78463)
		(width 0.088646)
		(layer "In11.Cu")
		(net "M_H_CPU0_SB_DQS_DP<9>")
	)
	(arc
		(start 379.033278 -242.78463)
		(mid 378.84608 -242.734487)
		(end 378.658882 -242.78463)
		(width 0.088646)
		(layer "In11.Cu")
		(net "M_H_CPU0_SB_DQS_DP<9>")
	)
	(segment
		(start 457.265532 -199.267826)
		(end 456.960732 -199.267826)
		(width 0.20066)
		(layer "F.Cu")
		(net "M_H_CPU0_SB_DQS_DP<8>")
	)
	(segment
		(start 461.14716 -198.839328)
		(end 460.892144 -198.584312)
		(width 0.20066)
		(layer "F.Cu")
		(net "M_H_CPU0_SB_DQS_DP<8>")
	)
	(segment
		(start 463.092038 -199.01662)
		(end 462.823814 -199.284844)
		(width 0.20066)
		(layer "F.Cu")
		(net "M_H_CPU0_SB_DQS_DP<8>")
	)
	(segment
		(start 463.659982 -199.01662)
		(end 463.092038 -199.01662)
		(width 0.20066)
		(layer "F.Cu")
		(net "M_H_CPU0_SB_DQS_DP<8>")
	)
	(segment
		(start 456.709526 -199.01662)
		(end 456.116182 -199.01662)
		(width 0.20066)
		(layer "F.Cu")
		(net "M_H_CPU0_SB_DQS_DP<8>")
	)
	(segment
		(start 457.690474 -198.842884)
		(end 457.265532 -199.267826)
		(width 0.20066)
		(layer "F.Cu")
		(net "M_H_CPU0_SB_DQS_DP<8>")
	)
	(segment
		(start 455.011282 -199.01662)
		(end 456.116182 -199.01662)
		(width 0.20066)
		(layer "F.Cu")
		(net "M_H_CPU0_SB_DQS_DP<8>")
	)
	(segment
		(start 460.56296 -198.591678)
		(end 458.550264 -198.591678)
		(width 0.1016)
		(layer "F.Cu")
		(net "M_H_CPU0_SB_DQS_DP<8>")
	)
	(segment
		(start 458.227176 -198.584566)
		(end 457.968858 -198.842884)
		(width 0.20066)
		(layer "F.Cu")
		(net "M_H_CPU0_SB_DQS_DP<8>")
	)
	(segment
		(start 458.538326 -198.584566)
		(end 458.227176 -198.584566)
		(width 0.20066)
		(layer "F.Cu")
		(net "M_H_CPU0_SB_DQS_DP<8>")
	)
	(segment
		(start 373.677434 -228.180646)
		(end 373.677434 -227.64496)
		(width 0.20066)
		(layer "F.Cu")
		(net "M_H_CPU0_SB_DQS_DP<8>")
	)
	(segment
		(start 460.570326 -198.584312)
		(end 460.56296 -198.591678)
		(width 0.1016)
		(layer "F.Cu")
		(net "M_H_CPU0_SB_DQS_DP<8>")
	)
	(segment
		(start 373.67718 -228.1809)
		(end 373.677434 -228.180646)
		(width 0.20066)
		(layer "F.Cu")
		(net "M_H_CPU0_SB_DQS_DP<8>")
	)
	(segment
		(start 460.892144 -198.584312)
		(end 460.570326 -198.584312)
		(width 0.20066)
		(layer "F.Cu")
		(net "M_H_CPU0_SB_DQS_DP<8>")
	)
	(segment
		(start 458.543152 -198.584566)
		(end 458.538326 -198.584566)
		(width 0.101854)
		(layer "F.Cu")
		(net "M_H_CPU0_SB_DQS_DP<8>")
	)
	(segment
		(start 462.246218 -199.284844)
		(end 461.800702 -198.839328)
		(width 0.20066)
		(layer "F.Cu")
		(net "M_H_CPU0_SB_DQS_DP<8>")
	)
	(segment
		(start 462.823814 -199.284844)
		(end 462.246218 -199.284844)
		(width 0.20066)
		(layer "F.Cu")
		(net "M_H_CPU0_SB_DQS_DP<8>")
	)
	(segment
		(start 458.550264 -198.591678)
		(end 458.543152 -198.584566)
		(width 0.1016)
		(layer "F.Cu")
		(net "M_H_CPU0_SB_DQS_DP<8>")
	)
	(segment
		(start 461.800702 -198.839328)
		(end 461.14716 -198.839328)
		(width 0.20066)
		(layer "F.Cu")
		(net "M_H_CPU0_SB_DQS_DP<8>")
	)
	(segment
		(start 456.960732 -199.267826)
		(end 456.709526 -199.01662)
		(width 0.20066)
		(layer "F.Cu")
		(net "M_H_CPU0_SB_DQS_DP<8>")
	)
	(segment
		(start 457.968858 -198.842884)
		(end 457.690474 -198.842884)
		(width 0.20066)
		(layer "F.Cu")
		(net "M_H_CPU0_SB_DQS_DP<8>")
	)
	(segment
		(start 378.578364 -227.960682)
		(end 378.563632 -227.969318)
		(width 0.088646)
		(layer "In11.Cu")
		(net "M_H_CPU0_SB_DQS_DP<8>")
	)
	(segment
		(start 406.790398 -201.874374)
		(end 406.241758 -201.874374)
		(width 0.18288)
		(layer "In11.Cu")
		(net "M_H_CPU0_SB_DQS_DP<8>")
	)
	(segment
		(start 403.92096 -204.844142)
		(end 395.67993 -213.085172)
		(width 0.18288)
		(layer "In11.Cu")
		(net "M_H_CPU0_SB_DQS_DP<8>")
	)
	(segment
		(start 405.36876 -201.998834)
		(end 403.92096 -203.446634)
		(width 0.18288)
		(layer "In11.Cu")
		(net "M_H_CPU0_SB_DQS_DP<8>")
	)
	(segment
		(start 429.776128 -202.000612)
		(end 429.651668 -201.876152)
		(width 0.18288)
		(layer "In11.Cu")
		(net "M_H_CPU0_SB_DQS_DP<8>")
	)
	(segment
		(start 454.058528 -199.28459)
		(end 451.910958 -201.43216)
		(width 0.18288)
		(layer "In11.Cu")
		(net "M_H_CPU0_SB_DQS_DP<8>")
	)
	(segment
		(start 450.682106 -201.14133)
		(end 450.40804 -201.415396)
		(width 0.18288)
		(layer "In11.Cu")
		(net "M_H_CPU0_SB_DQS_DP<8>")
	)
	(segment
		(start 440.127898 -200.291192)
		(end 439.655458 -200.291192)
		(width 0.18288)
		(layer "In11.Cu")
		(net "M_H_CPU0_SB_DQS_DP<8>")
	)
	(segment
		(start 428.196248 -202.000612)
		(end 427.199806 -201.587608)
		(width 0.18288)
		(layer "In11.Cu")
		(net "M_H_CPU0_SB_DQS_DP<8>")
	)
	(segment
		(start 455.011282 -199.01662)
		(end 454.743312 -199.28459)
		(width 0.18288)
		(layer "In11.Cu")
		(net "M_H_CPU0_SB_DQS_DP<8>")
	)
	(segment
		(start 418.315902 -201.429874)
		(end 417.041838 -201.683112)
		(width 0.18288)
		(layer "In11.Cu")
		(net "M_H_CPU0_SB_DQS_DP<8>")
	)
	(segment
		(start 423.303446 -200.560432)
		(end 421.552116 -201.285602)
		(width 0.18288)
		(layer "In11.Cu")
		(net "M_H_CPU0_SB_DQS_DP<8>")
	)
	(segment
		(start 414.544764 -202.003914)
		(end 414.420304 -201.879454)
		(width 0.18288)
		(layer "In11.Cu")
		(net "M_H_CPU0_SB_DQS_DP<8>")
	)
	(segment
		(start 388.046976 -224.550478)
		(end 388.046976 -224.634806)
		(width 0.088646)
		(layer "In11.Cu")
		(net "M_H_CPU0_SB_DQS_DP<8>")
	)
	(segment
		(start 406.117298 -201.998834)
		(end 405.36876 -201.998834)
		(width 0.18288)
		(layer "In11.Cu")
		(net "M_H_CPU0_SB_DQS_DP<8>")
	)
	(segment
		(start 451.394576 -201.43216)
		(end 451.103746 -201.14133)
		(width 0.18288)
		(layer "In11.Cu")
		(net "M_H_CPU0_SB_DQS_DP<8>")
	)
	(segment
		(start 416.259264 -201.839068)
		(end 415.430208 -202.003914)
		(width 0.18288)
		(layer "In11.Cu")
		(net "M_H_CPU0_SB_DQS_DP<8>")
	)
	(segment
		(start 451.910958 -201.43216)
		(end 451.394576 -201.43216)
		(width 0.18288)
		(layer "In11.Cu")
		(net "M_H_CPU0_SB_DQS_DP<8>")
	)
	(segment
		(start 414.420304 -201.879454)
		(end 413.871664 -201.879454)
		(width 0.18288)
		(layer "In11.Cu")
		(net "M_H_CPU0_SB_DQS_DP<8>")
	)
	(segment
		(start 421.552116 -201.285602)
		(end 421.421306 -201.416666)
		(width 0.18288)
		(layer "In11.Cu")
		(net "M_H_CPU0_SB_DQS_DP<8>")
	)
	(segment
		(start 413.871664 -201.879454)
		(end 413.747204 -202.003914)
		(width 0.18288)
		(layer "In11.Cu")
		(net "M_H_CPU0_SB_DQS_DP<8>")
	)
	(segment
		(start 449.380102 -201.415396)
		(end 449.255642 -201.290936)
		(width 0.18288)
		(layer "In11.Cu")
		(net "M_H_CPU0_SB_DQS_DP<8>")
	)
	(segment
		(start 433.089304 -201.276966)
		(end 432.964844 -201.401426)
		(width 0.18288)
		(layer "In11.Cu")
		(net "M_H_CPU0_SB_DQS_DP<8>")
	)
	(segment
		(start 374.814846 -227.963222)
		(end 374.804432 -227.969318)
		(width 0.088646)
		(layer "In11.Cu")
		(net "M_H_CPU0_SB_DQS_DP<8>")
	)
	(segment
		(start 424.567858 -200.291192)
		(end 424.298618 -200.560432)
		(width 0.18288)
		(layer "In11.Cu")
		(net "M_H_CPU0_SB_DQS_DP<8>")
	)
	(segment
		(start 373.677434 -227.769928)
		(end 373.677434 -227.64496)
		(width 0.088646)
		(layer "In11.Cu")
		(net "M_H_CPU0_SB_DQS_DP<8>")
	)
	(segment
		(start 451.103746 -201.14133)
		(end 450.682106 -201.14133)
		(width 0.18288)
		(layer "In11.Cu")
		(net "M_H_CPU0_SB_DQS_DP<8>")
	)
	(segment
		(start 388.046976 -224.634806)
		(end 386.947918 -225.733864)
		(width 0.088646)
		(layer "In11.Cu")
		(net "M_H_CPU0_SB_DQS_DP<8>")
	)
	(segment
		(start 450.40804 -201.415396)
		(end 449.380102 -201.415396)
		(width 0.18288)
		(layer "In11.Cu")
		(net "M_H_CPU0_SB_DQS_DP<8>")
	)
	(segment
		(start 410.414724 -201.467466)
		(end 409.462986 -201.467466)
		(width 0.18288)
		(layer "In11.Cu")
		(net "M_H_CPU0_SB_DQS_DP<8>")
	)
	(segment
		(start 429.103028 -201.876152)
		(end 428.978568 -202.000612)
		(width 0.18288)
		(layer "In11.Cu")
		(net "M_H_CPU0_SB_DQS_DP<8>")
	)
	(segment
		(start 432.28133 -201.401426)
		(end 430.8348 -202.000612)
		(width 0.18288)
		(layer "In11.Cu")
		(net "M_H_CPU0_SB_DQS_DP<8>")
	)
	(segment
		(start 395.67993 -215.885522)
		(end 389.124952 -222.4405)
		(width 0.18288)
		(layer "In11.Cu")
		(net "M_H_CPU0_SB_DQS_DP<8>")
	)
	(segment
		(start 373.760238 -227.865686)
		(end 373.686832 -227.79228)
		(width 0.088646)
		(layer "In11.Cu")
		(net "M_H_CPU0_SB_DQS_DP<8>")
	)
	(segment
		(start 395.67993 -213.085172)
		(end 395.67993 -215.885522)
		(width 0.18288)
		(layer "In11.Cu")
		(net "M_H_CPU0_SB_DQS_DP<8>")
	)
	(segment
		(start 437.846216 -200.578466)
		(end 436.992522 -201.43216)
		(width 0.18288)
		(layer "In11.Cu")
		(net "M_H_CPU0_SB_DQS_DP<8>")
	)
	(segment
		(start 420.179246 -201.429874)
		(end 418.315902 -201.429874)
		(width 0.18288)
		(layer "In11.Cu")
		(net "M_H_CPU0_SB_DQS_DP<8>")
	)
	(segment
		(start 433.762404 -201.401426)
		(end 433.637944 -201.276966)
		(width 0.18288)
		(layer "In11.Cu")
		(net "M_H_CPU0_SB_DQS_DP<8>")
	)
	(segment
		(start 386.947918 -225.733864)
		(end 386.947918 -226.409504)
		(width 0.088646)
		(layer "In11.Cu")
		(net "M_H_CPU0_SB_DQS_DP<8>")
	)
	(segment
		(start 374.27281 -227.884482)
		(end 373.782336 -227.875084)
		(width 0.088646)
		(layer "In11.Cu")
		(net "M_H_CPU0_SB_DQS_DP<8>")
	)
	(segment
		(start 448.582542 -201.415396)
		(end 447.60388 -201.415396)
		(width 0.18288)
		(layer "In11.Cu")
		(net "M_H_CPU0_SB_DQS_DP<8>")
	)
	(segment
		(start 416.357054 -201.69251)
		(end 416.259264 -201.839068)
		(width 0.18288)
		(layer "In11.Cu")
		(net "M_H_CPU0_SB_DQS_DP<8>")
	)
	(segment
		(start 389.124952 -223.472502)
		(end 388.046976 -224.550478)
		(width 0.18288)
		(layer "In11.Cu")
		(net "M_H_CPU0_SB_DQS_DP<8>")
	)
	(segment
		(start 413.097472 -202.003914)
		(end 411.803596 -201.467466)
		(width 0.18288)
		(layer "In11.Cu")
		(net "M_H_CPU0_SB_DQS_DP<8>")
	)
	(segment
		(start 430.8348 -202.000612)
		(end 429.776128 -202.000612)
		(width 0.18288)
		(layer "In11.Cu")
		(net "M_H_CPU0_SB_DQS_DP<8>")
	)
	(segment
		(start 416.895534 -201.585322)
		(end 416.357054 -201.69251)
		(width 0.18288)
		(layer "In11.Cu")
		(net "M_H_CPU0_SB_DQS_DP<8>")
	)
	(segment
		(start 425.036234 -200.291192)
		(end 424.567858 -200.291192)
		(width 0.18288)
		(layer "In11.Cu")
		(net "M_H_CPU0_SB_DQS_DP<8>")
	)
	(segment
		(start 406.914858 -201.998834)
		(end 406.790398 -201.874374)
		(width 0.18288)
		(layer "In11.Cu")
		(net "M_H_CPU0_SB_DQS_DP<8>")
	)
	(segment
		(start 427.199806 -201.587608)
		(end 426.178472 -200.566528)
		(width 0.18288)
		(layer "In11.Cu")
		(net "M_H_CPU0_SB_DQS_DP<8>")
	)
	(segment
		(start 411.803596 -201.467466)
		(end 411.212284 -201.467466)
		(width 0.18288)
		(layer "In11.Cu")
		(net "M_H_CPU0_SB_DQS_DP<8>")
	)
	(segment
		(start 417.041838 -201.683112)
		(end 416.895534 -201.585322)
		(width 0.18288)
		(layer "In11.Cu")
		(net "M_H_CPU0_SB_DQS_DP<8>")
	)
	(segment
		(start 413.747204 -202.003914)
		(end 413.097472 -202.003914)
		(width 0.18288)
		(layer "In11.Cu")
		(net "M_H_CPU0_SB_DQS_DP<8>")
	)
	(segment
		(start 442.806582 -200.810622)
		(end 442.403738 -201.213466)
		(width 0.18288)
		(layer "In11.Cu")
		(net "M_H_CPU0_SB_DQS_DP<8>")
	)
	(segment
		(start 406.241758 -201.874374)
		(end 406.117298 -201.998834)
		(width 0.18288)
		(layer "In11.Cu")
		(net "M_H_CPU0_SB_DQS_DP<8>")
	)
	(segment
		(start 403.92096 -203.446634)
		(end 403.92096 -204.844142)
		(width 0.18288)
		(layer "In11.Cu")
		(net "M_H_CPU0_SB_DQS_DP<8>")
	)
	(segment
		(start 389.124952 -222.4405)
		(end 389.124952 -223.472502)
		(width 0.18288)
		(layer "In11.Cu")
		(net "M_H_CPU0_SB_DQS_DP<8>")
	)
	(segment
		(start 420.941246 -201.14133)
		(end 420.46779 -201.14133)
		(width 0.18288)
		(layer "In11.Cu")
		(net "M_H_CPU0_SB_DQS_DP<8>")
	)
	(segment
		(start 440.407806 -200.5711)
		(end 440.127898 -200.291192)
		(width 0.18288)
		(layer "In11.Cu")
		(net "M_H_CPU0_SB_DQS_DP<8>")
	)
	(segment
		(start 436.992522 -201.43216)
		(end 436.295292 -201.43216)
		(width 0.18288)
		(layer "In11.Cu")
		(net "M_H_CPU0_SB_DQS_DP<8>")
	)
	(segment
		(start 421.216582 -201.416666)
		(end 420.941246 -201.14133)
		(width 0.18288)
		(layer "In11.Cu")
		(net "M_H_CPU0_SB_DQS_DP<8>")
	)
	(segment
		(start 408.931618 -201.998834)
		(end 406.914858 -201.998834)
		(width 0.18288)
		(layer "In11.Cu")
		(net "M_H_CPU0_SB_DQS_DP<8>")
	)
	(segment
		(start 436.004462 -201.14133)
		(end 435.55539 -201.14133)
		(width 0.18288)
		(layer "In11.Cu")
		(net "M_H_CPU0_SB_DQS_DP<8>")
	)
	(segment
		(start 425.31157 -200.566528)
		(end 425.036234 -200.291192)
		(width 0.18288)
		(layer "In11.Cu")
		(net "M_H_CPU0_SB_DQS_DP<8>")
	)
	(segment
		(start 384.389884 -227.635054)
		(end 384.389884 -227.64496)
		(width 0.088646)
		(layer "In11.Cu")
		(net "M_H_CPU0_SB_DQS_DP<8>")
	)
	(segment
		(start 421.421306 -201.416666)
		(end 421.216582 -201.416666)
		(width 0.18288)
		(layer "In11.Cu")
		(net "M_H_CPU0_SB_DQS_DP<8>")
	)
	(segment
		(start 415.430208 -202.003914)
		(end 414.544764 -202.003914)
		(width 0.18288)
		(layer "In11.Cu")
		(net "M_H_CPU0_SB_DQS_DP<8>")
	)
	(segment
		(start 410.539184 -201.343006)
		(end 410.414724 -201.467466)
		(width 0.18288)
		(layer "In11.Cu")
		(net "M_H_CPU0_SB_DQS_DP<8>")
	)
	(segment
		(start 429.651668 -201.876152)
		(end 429.103028 -201.876152)
		(width 0.18288)
		(layer "In11.Cu")
		(net "M_H_CPU0_SB_DQS_DP<8>")
	)
	(segment
		(start 379.518164 -227.960682)
		(end 379.503432 -227.969318)
		(width 0.088646)
		(layer "In11.Cu")
		(net "M_H_CPU0_SB_DQS_DP<8>")
	)
	(segment
		(start 441.260484 -200.5711)
		(end 440.407806 -200.5711)
		(width 0.18288)
		(layer "In11.Cu")
		(net "M_H_CPU0_SB_DQS_DP<8>")
	)
	(segment
		(start 374.430036 -227.969318)
		(end 374.27281 -227.884482)
		(width 0.088646)
		(layer "In11.Cu")
		(net "M_H_CPU0_SB_DQS_DP<8>")
	)
	(segment
		(start 420.46779 -201.14133)
		(end 420.179246 -201.429874)
		(width 0.18288)
		(layer "In11.Cu")
		(net "M_H_CPU0_SB_DQS_DP<8>")
	)
	(segment
		(start 435.295294 -201.401426)
		(end 433.762404 -201.401426)
		(width 0.18288)
		(layer "In11.Cu")
		(net "M_H_CPU0_SB_DQS_DP<8>")
	)
	(segment
		(start 435.55539 -201.14133)
		(end 435.295294 -201.401426)
		(width 0.18288)
		(layer "In11.Cu")
		(net "M_H_CPU0_SB_DQS_DP<8>")
	)
	(segment
		(start 424.298618 -200.560432)
		(end 423.303446 -200.560432)
		(width 0.18288)
		(layer "In11.Cu")
		(net "M_H_CPU0_SB_DQS_DP<8>")
	)
	(segment
		(start 382.337564 -227.960682)
		(end 382.322832 -227.969318)
		(width 0.088646)
		(layer "In11.Cu")
		(net "M_H_CPU0_SB_DQS_DP<8>")
	)
	(segment
		(start 448.707002 -201.290936)
		(end 448.582542 -201.415396)
		(width 0.18288)
		(layer "In11.Cu")
		(net "M_H_CPU0_SB_DQS_DP<8>")
	)
	(segment
		(start 432.964844 -201.401426)
		(end 432.28133 -201.401426)
		(width 0.18288)
		(layer "In11.Cu")
		(net "M_H_CPU0_SB_DQS_DP<8>")
	)
	(segment
		(start 386.739638 -226.617784)
		(end 386.739638 -226.839018)
		(width 0.088646)
		(layer "In11.Cu")
		(net "M_H_CPU0_SB_DQS_DP<8>")
	)
	(segment
		(start 386.947918 -226.409504)
		(end 386.739638 -226.617784)
		(width 0.088646)
		(layer "In11.Cu")
		(net "M_H_CPU0_SB_DQS_DP<8>")
	)
	(segment
		(start 446.143888 -200.810622)
		(end 442.806582 -200.810622)
		(width 0.18288)
		(layer "In11.Cu")
		(net "M_H_CPU0_SB_DQS_DP<8>")
	)
	(segment
		(start 439.655458 -200.291192)
		(end 439.368184 -200.578466)
		(width 0.18288)
		(layer "In11.Cu")
		(net "M_H_CPU0_SB_DQS_DP<8>")
	)
	(segment
		(start 428.978568 -202.000612)
		(end 428.196248 -202.000612)
		(width 0.18288)
		(layer "In11.Cu")
		(net "M_H_CPU0_SB_DQS_DP<8>")
	)
	(segment
		(start 411.212284 -201.467466)
		(end 411.087824 -201.343006)
		(width 0.18288)
		(layer "In11.Cu")
		(net "M_H_CPU0_SB_DQS_DP<8>")
	)
	(segment
		(start 373.782336 -227.875084)
		(end 373.760238 -227.865686)
		(width 0.088646)
		(layer "In11.Cu")
		(net "M_H_CPU0_SB_DQS_DP<8>")
	)
	(segment
		(start 376.694192 -227.963222)
		(end 376.683778 -227.969318)
		(width 0.088646)
		(layer "In11.Cu")
		(net "M_H_CPU0_SB_DQS_DP<8>")
	)
	(segment
		(start 411.087824 -201.343006)
		(end 410.539184 -201.343006)
		(width 0.18288)
		(layer "In11.Cu")
		(net "M_H_CPU0_SB_DQS_DP<8>")
	)
	(segment
		(start 447.60388 -201.415396)
		(end 446.143888 -200.810622)
		(width 0.18288)
		(layer "In11.Cu")
		(net "M_H_CPU0_SB_DQS_DP<8>")
	)
	(segment
		(start 409.462986 -201.467466)
		(end 408.931618 -201.998834)
		(width 0.18288)
		(layer "In11.Cu")
		(net "M_H_CPU0_SB_DQS_DP<8>")
	)
	(segment
		(start 436.295292 -201.43216)
		(end 436.004462 -201.14133)
		(width 0.18288)
		(layer "In11.Cu")
		(net "M_H_CPU0_SB_DQS_DP<8>")
	)
	(segment
		(start 433.637944 -201.276966)
		(end 433.089304 -201.276966)
		(width 0.18288)
		(layer "In11.Cu")
		(net "M_H_CPU0_SB_DQS_DP<8>")
	)
	(segment
		(start 426.178472 -200.566528)
		(end 425.31157 -200.566528)
		(width 0.18288)
		(layer "In11.Cu")
		(net "M_H_CPU0_SB_DQS_DP<8>")
	)
	(segment
		(start 449.255642 -201.290936)
		(end 448.707002 -201.290936)
		(width 0.18288)
		(layer "In11.Cu")
		(net "M_H_CPU0_SB_DQS_DP<8>")
	)
	(segment
		(start 441.90285 -201.213466)
		(end 441.260484 -200.5711)
		(width 0.18288)
		(layer "In11.Cu")
		(net "M_H_CPU0_SB_DQS_DP<8>")
	)
	(segment
		(start 442.403738 -201.213466)
		(end 441.90285 -201.213466)
		(width 0.18288)
		(layer "In11.Cu")
		(net "M_H_CPU0_SB_DQS_DP<8>")
	)
	(segment
		(start 373.686832 -227.79228)
		(end 373.677434 -227.769928)
		(width 0.088646)
		(layer "In11.Cu")
		(net "M_H_CPU0_SB_DQS_DP<8>")
	)
	(segment
		(start 439.368184 -200.578466)
		(end 437.846216 -200.578466)
		(width 0.18288)
		(layer "In11.Cu")
		(net "M_H_CPU0_SB_DQS_DP<8>")
	)
	(segment
		(start 454.743312 -199.28459)
		(end 454.058528 -199.28459)
		(width 0.18288)
		(layer "In11.Cu")
		(net "M_H_CPU0_SB_DQS_DP<8>")
	)
	(segment
		(start 377.638564 -227.960682)
		(end 377.623832 -227.969318)
		(width 0.088646)
		(layer "In11.Cu")
		(net "M_H_CPU0_SB_DQS_DP<8>")
	)
	(arc
		(start 374.804432 -227.969318)
		(mid 374.617234 -228.019461)
		(end 374.430036 -227.969318)
		(width 0.088646)
		(layer "In11.Cu")
		(net "M_H_CPU0_SB_DQS_DP<8>")
	)
	(arc
		(start 380.068836 -227.969318)
		(mid 379.794607 -227.893393)
		(end 379.518164 -227.960682)
		(width 0.088646)
		(layer "In11.Cu")
		(net "M_H_CPU0_SB_DQS_DP<8>")
	)
	(arc
		(start 378.189236 -227.969318)
		(mid 377.915007 -227.893393)
		(end 377.638564 -227.960682)
		(width 0.088646)
		(layer "In11.Cu")
		(net "M_H_CPU0_SB_DQS_DP<8>")
	)
	(arc
		(start 383.262632 -227.969318)
		(mid 383.075434 -228.019461)
		(end 382.888236 -227.969318)
		(width 0.088646)
		(layer "In11.Cu")
		(net "M_H_CPU0_SB_DQS_DP<8>")
	)
	(arc
		(start 386.177536 -227.155502)
		(mid 385.894834 -227.079726)
		(end 385.612132 -227.155502)
		(width 0.088646)
		(layer "In11.Cu")
		(net "M_H_CPU0_SB_DQS_DP<8>")
	)
	(arc
		(start 380.443232 -227.969318)
		(mid 380.256034 -228.019461)
		(end 380.068836 -227.969318)
		(width 0.088646)
		(layer "In11.Cu")
		(net "M_H_CPU0_SB_DQS_DP<8>")
	)
	(arc
		(start 386.739638 -226.839018)
		(mid 386.548865 -227.157662)
		(end 386.177536 -227.155502)
		(width 0.088646)
		(layer "In11.Cu")
		(net "M_H_CPU0_SB_DQS_DP<8>")
	)
	(arc
		(start 385.612132 -227.155502)
		(mid 385.424934 -227.205645)
		(end 385.237736 -227.155502)
		(width 0.088646)
		(layer "In11.Cu")
		(net "M_H_CPU0_SB_DQS_DP<8>")
	)
	(arc
		(start 379.503432 -227.969318)
		(mid 379.316234 -228.019461)
		(end 379.129036 -227.969318)
		(width 0.088646)
		(layer "In11.Cu")
		(net "M_H_CPU0_SB_DQS_DP<8>")
	)
	(arc
		(start 377.249436 -227.969318)
		(mid 376.972623 -227.893482)
		(end 376.694192 -227.963222)
		(width 0.088646)
		(layer "In11.Cu")
		(net "M_H_CPU0_SB_DQS_DP<8>")
	)
	(arc
		(start 381.383032 -227.969318)
		(mid 381.195834 -228.019461)
		(end 381.008636 -227.969318)
		(width 0.088646)
		(layer "In11.Cu")
		(net "M_H_CPU0_SB_DQS_DP<8>")
	)
	(arc
		(start 379.129036 -227.969318)
		(mid 378.854807 -227.893393)
		(end 378.578364 -227.960682)
		(width 0.088646)
		(layer "In11.Cu")
		(net "M_H_CPU0_SB_DQS_DP<8>")
	)
	(arc
		(start 381.948436 -227.969318)
		(mid 381.665734 -227.893576)
		(end 381.383032 -227.969318)
		(width 0.088646)
		(layer "In11.Cu")
		(net "M_H_CPU0_SB_DQS_DP<8>")
	)
	(arc
		(start 385.237736 -227.155502)
		(mid 384.67676 -227.152971)
		(end 384.389884 -227.635054)
		(width 0.088646)
		(layer "In11.Cu")
		(net "M_H_CPU0_SB_DQS_DP<8>")
	)
	(arc
		(start 375.743978 -227.969318)
		(mid 375.55678 -228.019461)
		(end 375.369582 -227.969318)
		(width 0.088646)
		(layer "In11.Cu")
		(net "M_H_CPU0_SB_DQS_DP<8>")
	)
	(arc
		(start 383.828036 -227.969318)
		(mid 383.545334 -227.893576)
		(end 383.262632 -227.969318)
		(width 0.088646)
		(layer "In11.Cu")
		(net "M_H_CPU0_SB_DQS_DP<8>")
	)
	(arc
		(start 382.888236 -227.969318)
		(mid 382.614007 -227.893393)
		(end 382.337564 -227.960682)
		(width 0.088646)
		(layer "In11.Cu")
		(net "M_H_CPU0_SB_DQS_DP<8>")
	)
	(arc
		(start 375.369582 -227.969318)
		(mid 375.093023 -227.893609)
		(end 374.814846 -227.963222)
		(width 0.088646)
		(layer "In11.Cu")
		(net "M_H_CPU0_SB_DQS_DP<8>")
	)
	(arc
		(start 378.563632 -227.969318)
		(mid 378.376434 -228.019461)
		(end 378.189236 -227.969318)
		(width 0.088646)
		(layer "In11.Cu")
		(net "M_H_CPU0_SB_DQS_DP<8>")
	)
	(arc
		(start 381.008636 -227.969318)
		(mid 380.725934 -227.893576)
		(end 380.443232 -227.969318)
		(width 0.088646)
		(layer "In11.Cu")
		(net "M_H_CPU0_SB_DQS_DP<8>")
	)
	(arc
		(start 382.322832 -227.969318)
		(mid 382.135634 -228.019461)
		(end 381.948436 -227.969318)
		(width 0.088646)
		(layer "In11.Cu")
		(net "M_H_CPU0_SB_DQS_DP<8>")
	)
	(arc
		(start 384.389884 -227.64496)
		(mid 384.20253 -227.969179)
		(end 383.828036 -227.969318)
		(width 0.088646)
		(layer "In11.Cu")
		(net "M_H_CPU0_SB_DQS_DP<8>")
	)
	(arc
		(start 376.309382 -227.969318)
		(mid 376.02668 -227.893576)
		(end 375.743978 -227.969318)
		(width 0.088646)
		(layer "In11.Cu")
		(net "M_H_CPU0_SB_DQS_DP<8>")
	)
	(arc
		(start 377.623832 -227.969318)
		(mid 377.436634 -228.019461)
		(end 377.249436 -227.969318)
		(width 0.088646)
		(layer "In11.Cu")
		(net "M_H_CPU0_SB_DQS_DP<8>")
	)
	(arc
		(start 376.683778 -227.969318)
		(mid 376.49658 -228.019461)
		(end 376.309382 -227.969318)
		(width 0.088646)
		(layer "In11.Cu")
		(net "M_H_CPU0_SB_DQS_DP<8>")
	)
	(segment
		(start 456.709526 -208.366614)
		(end 456.960732 -208.61782)
		(width 0.20066)
		(layer "F.Cu")
		(net "M_H_CPU0_SB_DQS_DP<7>")
	)
	(segment
		(start 463.092038 -208.366614)
		(end 463.659982 -208.366614)
		(width 0.20066)
		(layer "F.Cu")
		(net "M_H_CPU0_SB_DQS_DP<7>")
	)
	(segment
		(start 457.690474 -208.192878)
		(end 457.968858 -208.192878)
		(width 0.20066)
		(layer "F.Cu")
		(net "M_H_CPU0_SB_DQS_DP<7>")
	)
	(segment
		(start 462.823814 -208.634838)
		(end 463.092038 -208.366614)
		(width 0.20066)
		(layer "F.Cu")
		(net "M_H_CPU0_SB_DQS_DP<7>")
	)
	(segment
		(start 456.960732 -208.61782)
		(end 457.265532 -208.61782)
		(width 0.20066)
		(layer "F.Cu")
		(net "M_H_CPU0_SB_DQS_DP<7>")
	)
	(segment
		(start 456.116182 -208.366614)
		(end 456.709526 -208.366614)
		(width 0.20066)
		(layer "F.Cu")
		(net "M_H_CPU0_SB_DQS_DP<7>")
	)
	(segment
		(start 461.14716 -208.189322)
		(end 461.800702 -208.189322)
		(width 0.20066)
		(layer "F.Cu")
		(net "M_H_CPU0_SB_DQS_DP<7>")
	)
	(segment
		(start 462.246218 -208.634838)
		(end 462.823814 -208.634838)
		(width 0.20066)
		(layer "F.Cu")
		(net "M_H_CPU0_SB_DQS_DP<7>")
	)
	(segment
		(start 458.227176 -207.93456)
		(end 458.538326 -207.93456)
		(width 0.20066)
		(layer "F.Cu")
		(net "M_H_CPU0_SB_DQS_DP<7>")
	)
	(segment
		(start 458.538326 -207.93456)
		(end 458.543152 -207.93456)
		(width 0.101854)
		(layer "F.Cu")
		(net "M_H_CPU0_SB_DQS_DP<7>")
	)
	(segment
		(start 460.56296 -207.941672)
		(end 460.570326 -207.934306)
		(width 0.1016)
		(layer "F.Cu")
		(net "M_H_CPU0_SB_DQS_DP<7>")
	)
	(segment
		(start 376.02668 -230.622348)
		(end 376.02668 -230.086662)
		(width 0.20066)
		(layer "F.Cu")
		(net "M_H_CPU0_SB_DQS_DP<7>")
	)
	(segment
		(start 460.570326 -207.934306)
		(end 460.892144 -207.934306)
		(width 0.20066)
		(layer "F.Cu")
		(net "M_H_CPU0_SB_DQS_DP<7>")
	)
	(segment
		(start 457.968858 -208.192878)
		(end 458.227176 -207.93456)
		(width 0.20066)
		(layer "F.Cu")
		(net "M_H_CPU0_SB_DQS_DP<7>")
	)
	(segment
		(start 457.265532 -208.61782)
		(end 457.690474 -208.192878)
		(width 0.20066)
		(layer "F.Cu")
		(net "M_H_CPU0_SB_DQS_DP<7>")
	)
	(segment
		(start 458.550264 -207.941672)
		(end 460.56296 -207.941672)
		(width 0.1016)
		(layer "F.Cu")
		(net "M_H_CPU0_SB_DQS_DP<7>")
	)
	(segment
		(start 376.026934 -230.622602)
		(end 376.02668 -230.622348)
		(width 0.20066)
		(layer "F.Cu")
		(net "M_H_CPU0_SB_DQS_DP<7>")
	)
	(segment
		(start 461.800702 -208.189322)
		(end 462.246218 -208.634838)
		(width 0.20066)
		(layer "F.Cu")
		(net "M_H_CPU0_SB_DQS_DP<7>")
	)
	(segment
		(start 460.892144 -207.934306)
		(end 461.14716 -208.189322)
		(width 0.20066)
		(layer "F.Cu")
		(net "M_H_CPU0_SB_DQS_DP<7>")
	)
	(segment
		(start 458.543152 -207.93456)
		(end 458.550264 -207.941672)
		(width 0.1016)
		(layer "F.Cu")
		(net "M_H_CPU0_SB_DQS_DP<7>")
	)
	(segment
		(start 455.011282 -208.366614)
		(end 456.116182 -208.366614)
		(width 0.20066)
		(layer "F.Cu")
		(net "M_H_CPU0_SB_DQS_DP<7>")
	)
	(segment
		(start 377.633992 -229.591616)
		(end 377.632468 -229.592378)
		(width 0.088646)
		(layer "In6.Cu")
		(net "M_H_CPU0_SB_DQS_DP<7>")
	)
	(segment
		(start 376.779282 -229.762304)
		(end 376.777758 -229.763066)
		(width 0.088646)
		(layer "In6.Cu")
		(net "M_H_CPU0_SB_DQS_DP<7>")
	)
	(segment
		(start 421.193214 -210.770978)
		(end 420.915084 -210.492848)
		(width 0.18288)
		(layer "In6.Cu")
		(net "M_H_CPU0_SB_DQS_DP<7>")
	)
	(segment
		(start 454.73239 -208.645506)
		(end 454.155556 -208.645506)
		(width 0.18288)
		(layer "In6.Cu")
		(net "M_H_CPU0_SB_DQS_DP<7>")
	)
	(segment
		(start 440.385962 -207.37068)
		(end 440.107832 -207.09255)
		(width 0.18288)
		(layer "In6.Cu")
		(net "M_H_CPU0_SB_DQS_DP<7>")
	)
	(segment
		(start 386.776468 -226.860608)
		(end 386.65785 -227.146866)
		(width 0.088646)
		(layer "In6.Cu")
		(net "M_H_CPU0_SB_DQS_DP<7>")
	)
	(segment
		(start 443.321694 -207.576166)
		(end 442.447172 -207.93837)
		(width 0.18288)
		(layer "In6.Cu")
		(net "M_H_CPU0_SB_DQS_DP<7>")
	)
	(segment
		(start 386.65785 -227.146866)
		(end 385.62026 -228.184456)
		(width 0.088646)
		(layer "In6.Cu")
		(net "M_H_CPU0_SB_DQS_DP<7>")
	)
	(segment
		(start 383.358136 -228.783388)
		(end 383.347722 -228.777292)
		(width 0.088646)
		(layer "In6.Cu")
		(net "M_H_CPU0_SB_DQS_DP<7>")
	)
	(segment
		(start 439.469784 -207.372458)
		(end 437.724804 -207.372458)
		(width 0.18288)
		(layer "In6.Cu")
		(net "M_H_CPU0_SB_DQS_DP<7>")
	)
	(segment
		(start 385.62026 -228.55809)
		(end 385.41833 -228.76002)
		(width 0.088646)
		(layer "In6.Cu")
		(net "M_H_CPU0_SB_DQS_DP<7>")
	)
	(segment
		(start 405.456644 -208.871566)
		(end 403.032214 -211.295996)
		(width 0.18288)
		(layer "In6.Cu")
		(net "M_H_CPU0_SB_DQS_DP<7>")
	)
	(segment
		(start 378.093478 -228.783388)
		(end 378.087382 -228.786944)
		(width 0.088646)
		(layer "In6.Cu")
		(net "M_H_CPU0_SB_DQS_DP<7>")
	)
	(segment
		(start 434.782214 -208.21269)
		(end 433.047394 -208.931256)
		(width 0.18288)
		(layer "In6.Cu")
		(net "M_H_CPU0_SB_DQS_DP<7>")
	)
	(segment
		(start 455.011282 -208.366614)
		(end 454.73239 -208.645506)
		(width 0.18288)
		(layer "In6.Cu")
		(net "M_H_CPU0_SB_DQS_DP<7>")
	)
	(segment
		(start 387.190742 -226.653344)
		(end 387.131052 -226.713034)
		(width 0.088646)
		(layer "In6.Cu")
		(net "M_H_CPU0_SB_DQS_DP<7>")
	)
	(segment
		(start 380.538736 -228.783388)
		(end 380.528322 -228.777292)
		(width 0.088646)
		(layer "In6.Cu")
		(net "M_H_CPU0_SB_DQS_DP<7>")
	)
	(segment
		(start 386.924042 -226.713034)
		(end 386.776468 -226.860608)
		(width 0.088646)
		(layer "In6.Cu")
		(net "M_H_CPU0_SB_DQS_DP<7>")
	)
	(segment
		(start 437.724804 -207.372458)
		(end 436.876698 -208.220564)
		(width 0.18288)
		(layer "In6.Cu")
		(net "M_H_CPU0_SB_DQS_DP<7>")
	)
	(segment
		(start 443.91326 -207.576166)
		(end 443.321694 -207.576166)
		(width 0.18288)
		(layer "In6.Cu")
		(net "M_H_CPU0_SB_DQS_DP<7>")
	)
	(segment
		(start 378.08027 -228.791008)
		(end 378.080524 -228.791516)
		(width 0.088646)
		(layer "In6.Cu")
		(net "M_H_CPU0_SB_DQS_DP<7>")
	)
	(segment
		(start 450.699632 -207.942434)
		(end 450.42074 -208.221326)
		(width 0.18288)
		(layer "In6.Cu")
		(net "M_H_CPU0_SB_DQS_DP<7>")
	)
	(segment
		(start 451.099428 -207.942434)
		(end 450.699632 -207.942434)
		(width 0.18288)
		(layer "In6.Cu")
		(net "M_H_CPU0_SB_DQS_DP<7>")
	)
	(segment
		(start 452.978774 -209.019648)
		(end 452.17969 -208.220564)
		(width 0.18288)
		(layer "In6.Cu")
		(net "M_H_CPU0_SB_DQS_DP<7>")
	)
	(segment
		(start 387.88086 -226.653344)
		(end 387.190742 -226.653344)
		(width 0.18288)
		(layer "In6.Cu")
		(net "M_H_CPU0_SB_DQS_DP<7>")
	)
	(segment
		(start 426.600112 -208.931256)
		(end 425.610274 -209.921094)
		(width 0.18288)
		(layer "In6.Cu")
		(net "M_H_CPU0_SB_DQS_DP<7>")
	)
	(segment
		(start 376.539252 -230.086662)
		(end 376.02668 -230.086662)
		(width 0.088646)
		(layer "In6.Cu")
		(net "M_H_CPU0_SB_DQS_DP<7>")
	)
	(segment
		(start 450.42074 -208.221326)
		(end 447.331084 -208.221326)
		(width 0.18288)
		(layer "In6.Cu")
		(net "M_H_CPU0_SB_DQS_DP<7>")
	)
	(segment
		(start 447.331084 -208.221326)
		(end 445.779652 -208.863946)
		(width 0.18288)
		(layer "In6.Cu")
		(net "M_H_CPU0_SB_DQS_DP<7>")
	)
	(segment
		(start 387.131052 -226.713034)
		(end 386.924042 -226.713034)
		(width 0.088646)
		(layer "In6.Cu")
		(net "M_H_CPU0_SB_DQS_DP<7>")
	)
	(segment
		(start 384.297428 -228.783642)
		(end 384.297682 -228.783134)
		(width 0.088646)
		(layer "In6.Cu")
		(net "M_H_CPU0_SB_DQS_DP<7>")
	)
	(segment
		(start 436.876698 -208.220564)
		(end 436.277258 -208.220564)
		(width 0.18288)
		(layer "In6.Cu")
		(net "M_H_CPU0_SB_DQS_DP<7>")
	)
	(segment
		(start 425.296584 -209.921094)
		(end 425.0182 -209.64271)
		(width 0.18288)
		(layer "In6.Cu")
		(net "M_H_CPU0_SB_DQS_DP<7>")
	)
	(segment
		(start 379.598682 -228.783388)
		(end 379.58395 -228.774752)
		(width 0.088646)
		(layer "In6.Cu")
		(net "M_H_CPU0_SB_DQS_DP<7>")
	)
	(segment
		(start 376.777758 -229.763066)
		(end 376.770392 -229.767384)
		(width 0.088646)
		(layer "In6.Cu")
		(net "M_H_CPU0_SB_DQS_DP<7>")
	)
	(segment
		(start 435.999128 -207.942434)
		(end 435.631336 -207.942434)
		(width 0.18288)
		(layer "In6.Cu")
		(net "M_H_CPU0_SB_DQS_DP<7>")
	)
	(segment
		(start 454.155556 -208.645506)
		(end 453.781414 -209.019648)
		(width 0.18288)
		(layer "In6.Cu")
		(net "M_H_CPU0_SB_DQS_DP<7>")
	)
	(segment
		(start 419.477698 -210.763866)
		(end 417.585398 -208.871566)
		(width 0.18288)
		(layer "In6.Cu")
		(net "M_H_CPU0_SB_DQS_DP<7>")
	)
	(segment
		(start 445.20104 -208.863946)
		(end 443.91326 -207.576166)
		(width 0.18288)
		(layer "In6.Cu")
		(net "M_H_CPU0_SB_DQS_DP<7>")
	)
	(segment
		(start 425.610274 -209.921094)
		(end 425.296584 -209.921094)
		(width 0.18288)
		(layer "In6.Cu")
		(net "M_H_CPU0_SB_DQS_DP<7>")
	)
	(segment
		(start 377.123452 -229.663752)
		(end 376.969528 -229.694486)
		(width 0.088646)
		(layer "In6.Cu")
		(net "M_H_CPU0_SB_DQS_DP<7>")
	)
	(segment
		(start 385.62026 -228.184456)
		(end 385.62026 -228.55809)
		(width 0.088646)
		(layer "In6.Cu")
		(net "M_H_CPU0_SB_DQS_DP<7>")
	)
	(segment
		(start 424.651424 -209.64271)
		(end 424.394376 -209.899758)
		(width 0.18288)
		(layer "In6.Cu")
		(net "M_H_CPU0_SB_DQS_DP<7>")
	)
	(segment
		(start 424.394376 -209.899758)
		(end 422.63441 -209.899758)
		(width 0.18288)
		(layer "In6.Cu")
		(net "M_H_CPU0_SB_DQS_DP<7>")
	)
	(segment
		(start 425.0182 -209.64271)
		(end 424.651424 -209.64271)
		(width 0.18288)
		(layer "In6.Cu")
		(net "M_H_CPU0_SB_DQS_DP<7>")
	)
	(segment
		(start 435.631336 -207.942434)
		(end 435.36108 -208.21269)
		(width 0.18288)
		(layer "In6.Cu")
		(net "M_H_CPU0_SB_DQS_DP<7>")
	)
	(segment
		(start 422.63441 -209.899758)
		(end 421.76319 -210.770978)
		(width 0.18288)
		(layer "In6.Cu")
		(net "M_H_CPU0_SB_DQS_DP<7>")
	)
	(segment
		(start 452.17969 -208.220564)
		(end 451.377558 -208.220564)
		(width 0.18288)
		(layer "In6.Cu")
		(net "M_H_CPU0_SB_DQS_DP<7>")
	)
	(segment
		(start 378.658882 -228.783388)
		(end 378.64415 -228.774752)
		(width 0.088646)
		(layer "In6.Cu")
		(net "M_H_CPU0_SB_DQS_DP<7>")
	)
	(segment
		(start 440.107832 -207.09255)
		(end 439.749692 -207.09255)
		(width 0.18288)
		(layer "In6.Cu")
		(net "M_H_CPU0_SB_DQS_DP<7>")
	)
	(segment
		(start 420.284402 -210.763866)
		(end 419.477698 -210.763866)
		(width 0.18288)
		(layer "In6.Cu")
		(net "M_H_CPU0_SB_DQS_DP<7>")
	)
	(segment
		(start 376.596402 -230.029512)
		(end 376.539252 -230.086662)
		(width 0.088646)
		(layer "In6.Cu")
		(net "M_H_CPU0_SB_DQS_DP<7>")
	)
	(segment
		(start 421.76319 -210.770978)
		(end 421.193214 -210.770978)
		(width 0.18288)
		(layer "In6.Cu")
		(net "M_H_CPU0_SB_DQS_DP<7>")
	)
	(segment
		(start 420.915084 -210.492848)
		(end 420.55542 -210.492848)
		(width 0.18288)
		(layer "In6.Cu")
		(net "M_H_CPU0_SB_DQS_DP<7>")
	)
	(segment
		(start 435.36108 -208.21269)
		(end 434.782214 -208.21269)
		(width 0.18288)
		(layer "In6.Cu")
		(net "M_H_CPU0_SB_DQS_DP<7>")
	)
	(segment
		(start 376.969528 -229.694486)
		(end 376.919744 -229.71506)
		(width 0.088646)
		(layer "In6.Cu")
		(net "M_H_CPU0_SB_DQS_DP<7>")
	)
	(segment
		(start 445.779652 -208.863946)
		(end 445.20104 -208.863946)
		(width 0.18288)
		(layer "In6.Cu")
		(net "M_H_CPU0_SB_DQS_DP<7>")
	)
	(segment
		(start 377.632468 -229.592378)
		(end 377.60783 -229.606348)
		(width 0.088646)
		(layer "In6.Cu")
		(net "M_H_CPU0_SB_DQS_DP<7>")
	)
	(segment
		(start 417.585398 -208.871566)
		(end 405.456644 -208.871566)
		(width 0.18288)
		(layer "In6.Cu")
		(net "M_H_CPU0_SB_DQS_DP<7>")
	)
	(segment
		(start 433.047394 -208.931256)
		(end 426.600112 -208.931256)
		(width 0.18288)
		(layer "In6.Cu")
		(net "M_H_CPU0_SB_DQS_DP<7>")
	)
	(segment
		(start 403.032214 -211.295996)
		(end 403.032214 -211.50199)
		(width 0.18288)
		(layer "In6.Cu")
		(net "M_H_CPU0_SB_DQS_DP<7>")
	)
	(segment
		(start 439.749692 -207.09255)
		(end 439.469784 -207.372458)
		(width 0.18288)
		(layer "In6.Cu")
		(net "M_H_CPU0_SB_DQS_DP<7>")
	)
	(segment
		(start 377.478544 -229.663752)
		(end 377.123452 -229.663752)
		(width 0.088646)
		(layer "In6.Cu")
		(net "M_H_CPU0_SB_DQS_DP<7>")
	)
	(segment
		(start 453.781414 -209.019648)
		(end 452.978774 -209.019648)
		(width 0.18288)
		(layer "In6.Cu")
		(net "M_H_CPU0_SB_DQS_DP<7>")
	)
	(segment
		(start 382.418082 -228.783388)
		(end 382.407668 -228.777292)
		(width 0.088646)
		(layer "In6.Cu")
		(net "M_H_CPU0_SB_DQS_DP<7>")
	)
	(segment
		(start 441.017406 -207.37068)
		(end 440.385962 -207.37068)
		(width 0.18288)
		(layer "In6.Cu")
		(net "M_H_CPU0_SB_DQS_DP<7>")
	)
	(segment
		(start 420.55542 -210.492848)
		(end 420.284402 -210.763866)
		(width 0.18288)
		(layer "In6.Cu")
		(net "M_H_CPU0_SB_DQS_DP<7>")
	)
	(segment
		(start 441.585096 -207.93837)
		(end 441.017406 -207.37068)
		(width 0.18288)
		(layer "In6.Cu")
		(net "M_H_CPU0_SB_DQS_DP<7>")
	)
	(segment
		(start 442.447172 -207.93837)
		(end 441.585096 -207.93837)
		(width 0.18288)
		(layer "In6.Cu")
		(net "M_H_CPU0_SB_DQS_DP<7>")
	)
	(segment
		(start 403.032214 -211.50199)
		(end 387.88086 -226.653344)
		(width 0.18288)
		(layer "In6.Cu")
		(net "M_H_CPU0_SB_DQS_DP<7>")
	)
	(segment
		(start 385.237736 -228.783896)
		(end 385.237482 -228.783642)
		(width 0.088646)
		(layer "In6.Cu")
		(net "M_H_CPU0_SB_DQS_DP<7>")
	)
	(segment
		(start 451.377558 -208.220564)
		(end 451.099428 -207.942434)
		(width 0.18288)
		(layer "In6.Cu")
		(net "M_H_CPU0_SB_DQS_DP<7>")
	)
	(segment
		(start 377.60783 -229.606348)
		(end 377.478544 -229.663752)
		(width 0.088646)
		(layer "In6.Cu")
		(net "M_H_CPU0_SB_DQS_DP<7>")
	)
	(segment
		(start 436.277258 -208.220564)
		(end 435.999128 -207.942434)
		(width 0.18288)
		(layer "In6.Cu")
		(net "M_H_CPU0_SB_DQS_DP<7>")
	)
	(arc
		(start 380.913132 -228.783388)
		(mid 380.725934 -228.833531)
		(end 380.538736 -228.783388)
		(width 0.088646)
		(layer "In6.Cu")
		(net "M_H_CPU0_SB_DQS_DP<7>")
	)
	(arc
		(start 383.347722 -228.777292)
		(mid 383.06929 -228.707446)
		(end 382.792478 -228.783388)
		(width 0.088646)
		(layer "In6.Cu")
		(net "M_H_CPU0_SB_DQS_DP<7>")
	)
	(arc
		(start 383.732532 -228.783388)
		(mid 383.545334 -228.833531)
		(end 383.358136 -228.783388)
		(width 0.088646)
		(layer "In6.Cu")
		(net "M_H_CPU0_SB_DQS_DP<7>")
	)
	(arc
		(start 381.852932 -228.783388)
		(mid 381.665734 -228.833531)
		(end 381.478536 -228.783388)
		(width 0.088646)
		(layer "In6.Cu")
		(net "M_H_CPU0_SB_DQS_DP<7>")
	)
	(arc
		(start 384.672586 -228.783642)
		(mid 384.485024 -228.833878)
		(end 384.297428 -228.783642)
		(width 0.088646)
		(layer "In6.Cu")
		(net "M_H_CPU0_SB_DQS_DP<7>")
	)
	(arc
		(start 378.080524 -228.791516)
		(mid 377.883348 -228.997151)
		(end 377.811538 -229.272846)
		(width 0.088646)
		(layer "In6.Cu")
		(net "M_H_CPU0_SB_DQS_DP<7>")
	)
	(arc
		(start 384.297682 -228.783134)
		(mid 384.015061 -228.707519)
		(end 383.732532 -228.783388)
		(width 0.088646)
		(layer "In6.Cu")
		(net "M_H_CPU0_SB_DQS_DP<7>")
	)
	(arc
		(start 376.919744 -229.71506)
		(mid 376.847147 -229.731652)
		(end 376.779282 -229.762304)
		(width 0.088646)
		(layer "In6.Cu")
		(net "M_H_CPU0_SB_DQS_DP<7>")
	)
	(arc
		(start 378.087382 -228.786944)
		(mid 378.083818 -228.788962)
		(end 378.08027 -228.791008)
		(width 0.088646)
		(layer "In6.Cu")
		(net "M_H_CPU0_SB_DQS_DP<7>")
	)
	(arc
		(start 379.973078 -228.783388)
		(mid 379.78588 -228.833531)
		(end 379.598682 -228.783388)
		(width 0.088646)
		(layer "In6.Cu")
		(net "M_H_CPU0_SB_DQS_DP<7>")
	)
	(arc
		(start 385.41833 -228.76002)
		(mid 385.332076 -228.802596)
		(end 385.237736 -228.783896)
		(width 0.088646)
		(layer "In6.Cu")
		(net "M_H_CPU0_SB_DQS_DP<7>")
	)
	(arc
		(start 380.528322 -228.777292)
		(mid 380.24989 -228.707446)
		(end 379.973078 -228.783388)
		(width 0.088646)
		(layer "In6.Cu")
		(net "M_H_CPU0_SB_DQS_DP<7>")
	)
	(arc
		(start 376.770392 -229.767384)
		(mid 376.654583 -229.879313)
		(end 376.596402 -230.029512)
		(width 0.088646)
		(layer "In6.Cu")
		(net "M_H_CPU0_SB_DQS_DP<7>")
	)
	(arc
		(start 382.792478 -228.783388)
		(mid 382.60528 -228.833531)
		(end 382.418082 -228.783388)
		(width 0.088646)
		(layer "In6.Cu")
		(net "M_H_CPU0_SB_DQS_DP<7>")
	)
	(arc
		(start 385.237482 -228.783642)
		(mid 384.955034 -228.707959)
		(end 384.672586 -228.783642)
		(width 0.088646)
		(layer "In6.Cu")
		(net "M_H_CPU0_SB_DQS_DP<7>")
	)
	(arc
		(start 379.033278 -228.783388)
		(mid 378.84608 -228.833531)
		(end 378.658882 -228.783388)
		(width 0.088646)
		(layer "In6.Cu")
		(net "M_H_CPU0_SB_DQS_DP<7>")
	)
	(arc
		(start 377.811538 -229.272846)
		(mid 377.764155 -229.455282)
		(end 377.633992 -229.591616)
		(width 0.088646)
		(layer "In6.Cu")
		(net "M_H_CPU0_SB_DQS_DP<7>")
	)
	(arc
		(start 379.58395 -228.774752)
		(mid 379.307475 -228.707432)
		(end 379.033278 -228.783388)
		(width 0.088646)
		(layer "In6.Cu")
		(net "M_H_CPU0_SB_DQS_DP<7>")
	)
	(arc
		(start 382.407668 -228.777292)
		(mid 382.12949 -228.707569)
		(end 381.852932 -228.783388)
		(width 0.088646)
		(layer "In6.Cu")
		(net "M_H_CPU0_SB_DQS_DP<7>")
	)
	(arc
		(start 381.478536 -228.783388)
		(mid 381.195834 -228.707612)
		(end 380.913132 -228.783388)
		(width 0.088646)
		(layer "In6.Cu")
		(net "M_H_CPU0_SB_DQS_DP<7>")
	)
	(arc
		(start 378.64415 -228.774752)
		(mid 378.367675 -228.707432)
		(end 378.093478 -228.783388)
		(width 0.088646)
		(layer "In6.Cu")
		(net "M_H_CPU0_SB_DQS_DP<7>")
	)
	(segment
		(start 458.227176 -217.284554)
		(end 457.968858 -217.542872)
		(width 0.20066)
		(layer "F.Cu")
		(net "M_H_CPU0_SB_DQS_DP<6>")
	)
	(segment
		(start 460.570326 -217.2843)
		(end 460.56296 -217.291666)
		(width 0.1016)
		(layer "F.Cu")
		(net "M_H_CPU0_SB_DQS_DP<6>")
	)
	(segment
		(start 461.14716 -217.539316)
		(end 460.892144 -217.2843)
		(width 0.20066)
		(layer "F.Cu")
		(net "M_H_CPU0_SB_DQS_DP<6>")
	)
	(segment
		(start 458.543152 -217.284554)
		(end 458.538326 -217.284554)
		(width 0.101854)
		(layer "F.Cu")
		(net "M_H_CPU0_SB_DQS_DP<6>")
	)
	(segment
		(start 455.011282 -217.716608)
		(end 456.116182 -217.716608)
		(width 0.20066)
		(layer "F.Cu")
		(net "M_H_CPU0_SB_DQS_DP<6>")
	)
	(segment
		(start 463.092038 -217.716608)
		(end 462.823814 -217.984832)
		(width 0.20066)
		(layer "F.Cu")
		(net "M_H_CPU0_SB_DQS_DP<6>")
	)
	(segment
		(start 460.892144 -217.2843)
		(end 460.570326 -217.2843)
		(width 0.20066)
		(layer "F.Cu")
		(net "M_H_CPU0_SB_DQS_DP<6>")
	)
	(segment
		(start 457.265532 -217.967814)
		(end 456.960732 -217.967814)
		(width 0.20066)
		(layer "F.Cu")
		(net "M_H_CPU0_SB_DQS_DP<6>")
	)
	(segment
		(start 457.968858 -217.542872)
		(end 457.690474 -217.542872)
		(width 0.20066)
		(layer "F.Cu")
		(net "M_H_CPU0_SB_DQS_DP<6>")
	)
	(segment
		(start 457.690474 -217.542872)
		(end 457.265532 -217.967814)
		(width 0.20066)
		(layer "F.Cu")
		(net "M_H_CPU0_SB_DQS_DP<6>")
	)
	(segment
		(start 460.56296 -217.291666)
		(end 458.550264 -217.291666)
		(width 0.1016)
		(layer "F.Cu")
		(net "M_H_CPU0_SB_DQS_DP<6>")
	)
	(segment
		(start 458.550264 -217.291666)
		(end 458.543152 -217.284554)
		(width 0.1016)
		(layer "F.Cu")
		(net "M_H_CPU0_SB_DQS_DP<6>")
	)
	(segment
		(start 462.246218 -217.984832)
		(end 461.800702 -217.539316)
		(width 0.20066)
		(layer "F.Cu")
		(net "M_H_CPU0_SB_DQS_DP<6>")
	)
	(segment
		(start 456.960732 -217.967814)
		(end 456.709526 -217.716608)
		(width 0.20066)
		(layer "F.Cu")
		(net "M_H_CPU0_SB_DQS_DP<6>")
	)
	(segment
		(start 372.73738 -233.064304)
		(end 372.73738 -232.528618)
		(width 0.20066)
		(layer "F.Cu")
		(net "M_H_CPU0_SB_DQS_DP<6>")
	)
	(segment
		(start 462.823814 -217.984832)
		(end 462.246218 -217.984832)
		(width 0.20066)
		(layer "F.Cu")
		(net "M_H_CPU0_SB_DQS_DP<6>")
	)
	(segment
		(start 461.800702 -217.539316)
		(end 461.14716 -217.539316)
		(width 0.20066)
		(layer "F.Cu")
		(net "M_H_CPU0_SB_DQS_DP<6>")
	)
	(segment
		(start 458.538326 -217.284554)
		(end 458.227176 -217.284554)
		(width 0.20066)
		(layer "F.Cu")
		(net "M_H_CPU0_SB_DQS_DP<6>")
	)
	(segment
		(start 372.73738 -232.528618)
		(end 372.737634 -232.528364)
		(width 0.20066)
		(layer "F.Cu")
		(net "M_H_CPU0_SB_DQS_DP<6>")
	)
	(segment
		(start 463.659982 -217.716608)
		(end 463.092038 -217.716608)
		(width 0.20066)
		(layer "F.Cu")
		(net "M_H_CPU0_SB_DQS_DP<6>")
	)
	(segment
		(start 456.709526 -217.716608)
		(end 456.116182 -217.716608)
		(width 0.20066)
		(layer "F.Cu")
		(net "M_H_CPU0_SB_DQS_DP<6>")
	)
	(segment
		(start 373.714264 -232.111804)
		(end 373.616982 -232.136188)
		(width 0.088646)
		(layer "In11.Cu")
		(net "M_H_CPU0_SB_DQS_DP<6>")
	)
	(segment
		(start 373.616982 -232.136188)
		(end 373.490236 -232.204006)
		(width 0.088646)
		(layer "In11.Cu")
		(net "M_H_CPU0_SB_DQS_DP<6>")
	)
	(segment
		(start 388.020306 -230.269034)
		(end 387.716268 -230.269034)
		(width 0.088646)
		(layer "In11.Cu")
		(net "M_H_CPU0_SB_DQS_DP<6>")
	)
	(segment
		(start 439.655458 -211.341208)
		(end 439.374534 -211.622132)
		(width 0.18288)
		(layer "In11.Cu")
		(net "M_H_CPU0_SB_DQS_DP<6>")
	)
	(segment
		(start 441.482226 -211.021422)
		(end 440.968384 -211.535264)
		(width 0.18288)
		(layer "In11.Cu")
		(net "M_H_CPU0_SB_DQS_DP<6>")
	)
	(segment
		(start 401.871688 -217.276172)
		(end 394.50899 -224.63887)
		(width 0.18288)
		(layer "In11.Cu")
		(net "M_H_CPU0_SB_DQS_DP<6>")
	)
	(segment
		(start 437.206644 -210.766406)
		(end 436.310278 -210.766406)
		(width 0.18288)
		(layer "In11.Cu")
		(net "M_H_CPU0_SB_DQS_DP<6>")
	)
	(segment
		(start 388.079996 -230.209344)
		(end 388.020306 -230.269034)
		(width 0.088646)
		(layer "In11.Cu")
		(net "M_H_CPU0_SB_DQS_DP<6>")
	)
	(segment
		(start 382.792732 -232.038906)
		(end 382.792478 -232.038906)
		(width 0.088646)
		(layer "In11.Cu")
		(net "M_H_CPU0_SB_DQS_DP<6>")
	)
	(segment
		(start 386.739384 -231.4575)
		(end 386.739384 -231.714548)
		(width 0.088646)
		(layer "In11.Cu")
		(net "M_H_CPU0_SB_DQS_DP<6>")
	)
	(segment
		(start 446.284858 -213.954614)
		(end 445.604646 -213.274402)
		(width 0.18288)
		(layer "In11.Cu")
		(net "M_H_CPU0_SB_DQS_DP<6>")
	)
	(segment
		(start 452.20128 -217.842338)
		(end 451.915784 -217.556842)
		(width 0.18288)
		(layer "In11.Cu")
		(net "M_H_CPU0_SB_DQS_DP<6>")
	)
	(segment
		(start 449.27012 -217.198956)
		(end 447.911474 -215.84031)
		(width 0.18288)
		(layer "In11.Cu")
		(net "M_H_CPU0_SB_DQS_DP<6>")
	)
	(segment
		(start 422.72966 -211.631276)
		(end 421.894508 -212.466428)
		(width 0.18288)
		(layer "In11.Cu")
		(net "M_H_CPU0_SB_DQS_DP<6>")
	)
	(segment
		(start 450.137022 -217.558112)
		(end 449.27012 -217.198956)
		(width 0.18288)
		(layer "In11.Cu")
		(net "M_H_CPU0_SB_DQS_DP<6>")
	)
	(segment
		(start 454.067672 -217.9701)
		(end 453.417178 -218.239086)
		(width 0.18288)
		(layer "In11.Cu")
		(net "M_H_CPU0_SB_DQS_DP<6>")
	)
	(segment
		(start 387.427216 -230.558086)
		(end 387.427216 -230.769414)
		(width 0.088646)
		(layer "In11.Cu")
		(net "M_H_CPU0_SB_DQS_DP<6>")
	)
	(segment
		(start 432.150012 -210.767422)
		(end 431.28438 -209.90179)
		(width 0.18288)
		(layer "In11.Cu")
		(net "M_H_CPU0_SB_DQS_DP<6>")
	)
	(segment
		(start 451.410578 -217.556842)
		(end 451.144894 -217.291158)
		(width 0.18288)
		(layer "In11.Cu")
		(net "M_H_CPU0_SB_DQS_DP<6>")
	)
	(segment
		(start 447.036698 -215.477852)
		(end 446.82918 -215.270334)
		(width 0.18288)
		(layer "In11.Cu")
		(net "M_H_CPU0_SB_DQS_DP<6>")
	)
	(segment
		(start 373.490236 -232.204006)
		(end 373.481346 -232.209086)
		(width 0.088646)
		(layer "In11.Cu")
		(net "M_H_CPU0_SB_DQS_DP<6>")
	)
	(segment
		(start 374.225058 -232.099104)
		(end 373.738902 -232.108502)
		(width 0.088646)
		(layer "In11.Cu")
		(net "M_H_CPU0_SB_DQS_DP<6>")
	)
	(segment
		(start 377.731528 -232.046526)
		(end 377.71959 -232.039414)
		(width 0.088646)
		(layer "In11.Cu")
		(net "M_H_CPU0_SB_DQS_DP<6>")
	)
	(segment
		(start 374.333516 -232.039414)
		(end 374.24868 -232.089452)
		(width 0.088646)
		(layer "In11.Cu")
		(net "M_H_CPU0_SB_DQS_DP<6>")
	)
	(segment
		(start 374.899682 -232.038906)
		(end 374.899428 -232.038906)
		(width 0.088646)
		(layer "In11.Cu")
		(net "M_H_CPU0_SB_DQS_DP<6>")
	)
	(segment
		(start 389.85698 -230.209344)
		(end 388.079996 -230.209344)
		(width 0.18288)
		(layer "In11.Cu")
		(net "M_H_CPU0_SB_DQS_DP<6>")
	)
	(segment
		(start 442.522102 -211.021422)
		(end 441.482226 -211.021422)
		(width 0.18288)
		(layer "In11.Cu")
		(net "M_H_CPU0_SB_DQS_DP<6>")
	)
	(segment
		(start 450.376036 -217.558112)
		(end 450.137022 -217.558112)
		(width 0.18288)
		(layer "In11.Cu")
		(net "M_H_CPU0_SB_DQS_DP<6>")
	)
	(segment
		(start 420.18585 -212.473032)
		(end 416.519106 -212.473032)
		(width 0.18288)
		(layer "In11.Cu")
		(net "M_H_CPU0_SB_DQS_DP<6>")
	)
	(segment
		(start 426.8597 -210.652106)
		(end 425.895262 -211.616544)
		(width 0.18288)
		(layer "In11.Cu")
		(net "M_H_CPU0_SB_DQS_DP<6>")
	)
	(segment
		(start 408.869642 -212.201252)
		(end 408.056588 -211.864448)
		(width 0.18288)
		(layer "In11.Cu")
		(net "M_H_CPU0_SB_DQS_DP<6>")
	)
	(segment
		(start 379.611128 -232.046526)
		(end 379.59919 -232.039414)
		(width 0.088646)
		(layer "In11.Cu")
		(net "M_H_CPU0_SB_DQS_DP<6>")
	)
	(segment
		(start 424.567858 -211.341208)
		(end 424.27779 -211.631276)
		(width 0.18288)
		(layer "In11.Cu")
		(net "M_H_CPU0_SB_DQS_DP<6>")
	)
	(segment
		(start 381.852678 -232.039414)
		(end 381.844296 -232.044494)
		(width 0.088646)
		(layer "In11.Cu")
		(net "M_H_CPU0_SB_DQS_DP<6>")
	)
	(segment
		(start 440.13501 -211.341208)
		(end 439.655458 -211.341208)
		(width 0.18288)
		(layer "In11.Cu")
		(net "M_H_CPU0_SB_DQS_DP<6>")
	)
	(segment
		(start 425.045378 -211.341208)
		(end 424.567858 -211.341208)
		(width 0.18288)
		(layer "In11.Cu")
		(net "M_H_CPU0_SB_DQS_DP<6>")
	)
	(segment
		(start 425.320714 -211.616544)
		(end 425.045378 -211.341208)
		(width 0.18288)
		(layer "In11.Cu")
		(net "M_H_CPU0_SB_DQS_DP<6>")
	)
	(segment
		(start 420.952422 -212.191092)
		(end 420.46779 -212.191092)
		(width 0.18288)
		(layer "In11.Cu")
		(net "M_H_CPU0_SB_DQS_DP<6>")
	)
	(segment
		(start 373.31015 -232.454196)
		(end 373.235982 -232.528364)
		(width 0.088646)
		(layer "In11.Cu")
		(net "M_H_CPU0_SB_DQS_DP<6>")
	)
	(segment
		(start 451.144894 -217.291158)
		(end 450.64299 -217.291158)
		(width 0.18288)
		(layer "In11.Cu")
		(net "M_H_CPU0_SB_DQS_DP<6>")
	)
	(segment
		(start 424.27779 -211.631276)
		(end 422.72966 -211.631276)
		(width 0.18288)
		(layer "In11.Cu")
		(net "M_H_CPU0_SB_DQS_DP<6>")
	)
	(segment
		(start 374.24868 -232.089452)
		(end 374.227344 -232.098088)
		(width 0.088646)
		(layer "In11.Cu")
		(net "M_H_CPU0_SB_DQS_DP<6>")
	)
	(segment
		(start 453.417178 -218.239086)
		(end 452.994776 -218.239086)
		(width 0.18288)
		(layer "In11.Cu")
		(net "M_H_CPU0_SB_DQS_DP<6>")
	)
	(segment
		(start 452.994776 -218.239086)
		(end 452.20128 -217.842338)
		(width 0.18288)
		(layer "In11.Cu")
		(net "M_H_CPU0_SB_DQS_DP<6>")
	)
	(segment
		(start 445.604646 -213.274402)
		(end 444.708026 -212.902038)
		(width 0.18288)
		(layer "In11.Cu")
		(net "M_H_CPU0_SB_DQS_DP<6>")
	)
	(segment
		(start 416.519106 -212.473032)
		(end 415.913062 -211.866988)
		(width 0.18288)
		(layer "In11.Cu")
		(net "M_H_CPU0_SB_DQS_DP<6>")
	)
	(segment
		(start 438.06237 -211.622132)
		(end 437.206644 -210.766406)
		(width 0.18288)
		(layer "In11.Cu")
		(net "M_H_CPU0_SB_DQS_DP<6>")
	)
	(segment
		(start 415.913062 -211.866988)
		(end 412.766764 -211.866988)
		(width 0.18288)
		(layer "In11.Cu")
		(net "M_H_CPU0_SB_DQS_DP<6>")
	)
	(segment
		(start 427.919896 -209.90179)
		(end 427.16958 -210.652106)
		(width 0.18288)
		(layer "In11.Cu")
		(net "M_H_CPU0_SB_DQS_DP<6>")
	)
	(segment
		(start 440.968384 -211.535264)
		(end 440.77255 -211.616544)
		(width 0.18288)
		(layer "In11.Cu")
		(net "M_H_CPU0_SB_DQS_DP<6>")
	)
	(segment
		(start 408.056588 -211.864448)
		(end 405.254206 -211.864448)
		(width 0.18288)
		(layer "In11.Cu")
		(net "M_H_CPU0_SB_DQS_DP<6>")
	)
	(segment
		(start 446.82918 -215.270334)
		(end 446.284858 -213.954614)
		(width 0.18288)
		(layer "In11.Cu")
		(net "M_H_CPU0_SB_DQS_DP<6>")
	)
	(segment
		(start 373.235982 -232.528364)
		(end 372.737634 -232.528364)
		(width 0.088646)
		(layer "In11.Cu")
		(net "M_H_CPU0_SB_DQS_DP<6>")
	)
	(segment
		(start 440.77255 -211.616544)
		(end 440.410346 -211.616544)
		(width 0.18288)
		(layer "In11.Cu")
		(net "M_H_CPU0_SB_DQS_DP<6>")
	)
	(segment
		(start 440.410346 -211.616544)
		(end 440.13501 -211.341208)
		(width 0.18288)
		(layer "In11.Cu")
		(net "M_H_CPU0_SB_DQS_DP<6>")
	)
	(segment
		(start 378.671328 -232.046526)
		(end 378.65939 -232.039414)
		(width 0.088646)
		(layer "In11.Cu")
		(net "M_H_CPU0_SB_DQS_DP<6>")
	)
	(segment
		(start 427.16958 -210.652106)
		(end 426.8597 -210.652106)
		(width 0.18288)
		(layer "In11.Cu")
		(net "M_H_CPU0_SB_DQS_DP<6>")
	)
	(segment
		(start 394.50899 -224.63887)
		(end 394.50899 -225.557334)
		(width 0.18288)
		(layer "In11.Cu")
		(net "M_H_CPU0_SB_DQS_DP<6>")
	)
	(segment
		(start 375.839482 -232.038906)
		(end 375.82475 -232.03027)
		(width 0.088646)
		(layer "In11.Cu")
		(net "M_H_CPU0_SB_DQS_DP<6>")
	)
	(segment
		(start 435.279038 -210.767422)
		(end 432.150012 -210.767422)
		(width 0.18288)
		(layer "In11.Cu")
		(net "M_H_CPU0_SB_DQS_DP<6>")
	)
	(segment
		(start 421.894508 -212.466428)
		(end 421.227758 -212.466428)
		(width 0.18288)
		(layer "In11.Cu")
		(net "M_H_CPU0_SB_DQS_DP<6>")
	)
	(segment
		(start 387.427216 -230.769414)
		(end 386.739384 -231.4575)
		(width 0.088646)
		(layer "In11.Cu")
		(net "M_H_CPU0_SB_DQS_DP<6>")
	)
	(segment
		(start 374.227344 -232.098088)
		(end 374.225058 -232.099104)
		(width 0.088646)
		(layer "In11.Cu")
		(net "M_H_CPU0_SB_DQS_DP<6>")
	)
	(segment
		(start 375.851928 -232.046526)
		(end 375.839482 -232.038906)
		(width 0.088646)
		(layer "In11.Cu")
		(net "M_H_CPU0_SB_DQS_DP<6>")
	)
	(segment
		(start 436.034942 -210.49107)
		(end 435.55539 -210.49107)
		(width 0.18288)
		(layer "In11.Cu")
		(net "M_H_CPU0_SB_DQS_DP<6>")
	)
	(segment
		(start 425.895262 -211.616544)
		(end 425.320714 -211.616544)
		(width 0.18288)
		(layer "In11.Cu")
		(net "M_H_CPU0_SB_DQS_DP<6>")
	)
	(segment
		(start 420.46779 -212.191092)
		(end 420.18585 -212.473032)
		(width 0.18288)
		(layer "In11.Cu")
		(net "M_H_CPU0_SB_DQS_DP<6>")
	)
	(segment
		(start 447.911474 -215.84031)
		(end 447.036698 -215.477852)
		(width 0.18288)
		(layer "In11.Cu")
		(net "M_H_CPU0_SB_DQS_DP<6>")
	)
	(segment
		(start 394.50899 -225.557334)
		(end 389.85698 -230.209344)
		(width 0.18288)
		(layer "In11.Cu")
		(net "M_H_CPU0_SB_DQS_DP<6>")
	)
	(segment
		(start 401.871688 -215.246966)
		(end 401.871688 -217.276172)
		(width 0.18288)
		(layer "In11.Cu")
		(net "M_H_CPU0_SB_DQS_DP<6>")
	)
	(segment
		(start 431.28438 -209.90179)
		(end 427.919896 -209.90179)
		(width 0.18288)
		(layer "In11.Cu")
		(net "M_H_CPU0_SB_DQS_DP<6>")
	)
	(segment
		(start 412.4325 -212.201252)
		(end 408.869642 -212.201252)
		(width 0.18288)
		(layer "In11.Cu")
		(net "M_H_CPU0_SB_DQS_DP<6>")
	)
	(segment
		(start 443.042294 -211.236306)
		(end 442.522102 -211.021422)
		(width 0.18288)
		(layer "In11.Cu")
		(net "M_H_CPU0_SB_DQS_DP<6>")
	)
	(segment
		(start 439.374534 -211.622132)
		(end 438.06237 -211.622132)
		(width 0.18288)
		(layer "In11.Cu")
		(net "M_H_CPU0_SB_DQS_DP<6>")
	)
	(segment
		(start 451.915784 -217.556842)
		(end 451.410578 -217.556842)
		(width 0.18288)
		(layer "In11.Cu")
		(net "M_H_CPU0_SB_DQS_DP<6>")
	)
	(segment
		(start 421.227758 -212.466428)
		(end 420.952422 -212.191092)
		(width 0.18288)
		(layer "In11.Cu")
		(net "M_H_CPU0_SB_DQS_DP<6>")
	)
	(segment
		(start 444.708026 -212.902038)
		(end 443.042294 -211.236306)
		(width 0.18288)
		(layer "In11.Cu")
		(net "M_H_CPU0_SB_DQS_DP<6>")
	)
	(segment
		(start 455.011282 -217.716608)
		(end 454.756774 -217.9701)
		(width 0.18288)
		(layer "In11.Cu")
		(net "M_H_CPU0_SB_DQS_DP<6>")
	)
	(segment
		(start 412.766764 -211.866988)
		(end 412.4325 -212.201252)
		(width 0.18288)
		(layer "In11.Cu")
		(net "M_H_CPU0_SB_DQS_DP<6>")
	)
	(segment
		(start 405.254206 -211.864448)
		(end 401.871688 -215.246966)
		(width 0.18288)
		(layer "In11.Cu")
		(net "M_H_CPU0_SB_DQS_DP<6>")
	)
	(segment
		(start 387.716268 -230.269034)
		(end 387.427216 -230.558086)
		(width 0.088646)
		(layer "In11.Cu")
		(net "M_H_CPU0_SB_DQS_DP<6>")
	)
	(segment
		(start 450.64299 -217.291158)
		(end 450.376036 -217.558112)
		(width 0.18288)
		(layer "In11.Cu")
		(net "M_H_CPU0_SB_DQS_DP<6>")
	)
	(segment
		(start 380.547372 -232.04424)
		(end 380.53899 -232.039414)
		(width 0.088646)
		(layer "In11.Cu")
		(net "M_H_CPU0_SB_DQS_DP<6>")
	)
	(segment
		(start 435.55539 -210.49107)
		(end 435.279038 -210.767422)
		(width 0.18288)
		(layer "In11.Cu")
		(net "M_H_CPU0_SB_DQS_DP<6>")
	)
	(segment
		(start 454.756774 -217.9701)
		(end 454.067672 -217.9701)
		(width 0.18288)
		(layer "In11.Cu")
		(net "M_H_CPU0_SB_DQS_DP<6>")
	)
	(segment
		(start 436.310278 -210.766406)
		(end 436.034942 -210.49107)
		(width 0.18288)
		(layer "In11.Cu")
		(net "M_H_CPU0_SB_DQS_DP<6>")
	)
	(arc
		(start 379.973586 -232.03916)
		(mid 379.793299 -232.089572)
		(end 379.611128 -232.046526)
		(width 0.088646)
		(layer "In11.Cu")
		(net "M_H_CPU0_SB_DQS_DP<6>")
	)
	(arc
		(start 380.53899 -232.039414)
		(mid 380.256317 -231.963443)
		(end 379.973586 -232.03916)
		(width 0.088646)
		(layer "In11.Cu")
		(net "M_H_CPU0_SB_DQS_DP<6>")
	)
	(arc
		(start 374.899428 -232.038906)
		(mid 374.616413 -231.963257)
		(end 374.333516 -232.039414)
		(width 0.088646)
		(layer "In11.Cu")
		(net "M_H_CPU0_SB_DQS_DP<6>")
	)
	(arc
		(start 377.71959 -232.039414)
		(mid 377.436917 -231.963443)
		(end 377.154186 -232.03916)
		(width 0.088646)
		(layer "In11.Cu")
		(net "M_H_CPU0_SB_DQS_DP<6>")
	)
	(arc
		(start 381.844296 -232.044494)
		(mid 381.660475 -232.089552)
		(end 381.478028 -232.03916)
		(width 0.088646)
		(layer "In11.Cu")
		(net "M_H_CPU0_SB_DQS_DP<6>")
	)
	(arc
		(start 379.033786 -232.03916)
		(mid 378.853499 -232.089572)
		(end 378.671328 -232.046526)
		(width 0.088646)
		(layer "In11.Cu")
		(net "M_H_CPU0_SB_DQS_DP<6>")
	)
	(arc
		(start 384.297936 -232.038906)
		(mid 384.015234 -231.96313)
		(end 383.732532 -232.038906)
		(width 0.088646)
		(layer "In11.Cu")
		(net "M_H_CPU0_SB_DQS_DP<6>")
	)
	(arc
		(start 373.481346 -232.209086)
		(mid 373.370248 -232.313829)
		(end 373.31015 -232.454196)
		(width 0.088646)
		(layer "In11.Cu")
		(net "M_H_CPU0_SB_DQS_DP<6>")
	)
	(arc
		(start 376.214386 -232.03916)
		(mid 376.034099 -232.089572)
		(end 375.851928 -232.046526)
		(width 0.088646)
		(layer "In11.Cu")
		(net "M_H_CPU0_SB_DQS_DP<6>")
	)
	(arc
		(start 385.237736 -232.038906)
		(mid 384.955034 -231.96313)
		(end 384.672332 -232.038906)
		(width 0.088646)
		(layer "In11.Cu")
		(net "M_H_CPU0_SB_DQS_DP<6>")
	)
	(arc
		(start 382.417828 -232.03916)
		(mid 382.135206 -231.963477)
		(end 381.852678 -232.039414)
		(width 0.088646)
		(layer "In11.Cu")
		(net "M_H_CPU0_SB_DQS_DP<6>")
	)
	(arc
		(start 378.65939 -232.039414)
		(mid 378.376717 -231.963443)
		(end 378.093986 -232.03916)
		(width 0.088646)
		(layer "In11.Cu")
		(net "M_H_CPU0_SB_DQS_DP<6>")
	)
	(arc
		(start 380.913132 -232.03916)
		(mid 380.73091 -232.08936)
		(end 380.547372 -232.04424)
		(width 0.088646)
		(layer "In11.Cu")
		(net "M_H_CPU0_SB_DQS_DP<6>")
	)
	(arc
		(start 381.478028 -232.03916)
		(mid 381.19558 -231.963477)
		(end 380.913132 -232.03916)
		(width 0.088646)
		(layer "In11.Cu")
		(net "M_H_CPU0_SB_DQS_DP<6>")
	)
	(arc
		(start 383.358136 -232.038906)
		(mid 383.075434 -231.96313)
		(end 382.792732 -232.038906)
		(width 0.088646)
		(layer "In11.Cu")
		(net "M_H_CPU0_SB_DQS_DP<6>")
	)
	(arc
		(start 379.59919 -232.039414)
		(mid 379.316517 -231.963443)
		(end 379.033786 -232.03916)
		(width 0.088646)
		(layer "In11.Cu")
		(net "M_H_CPU0_SB_DQS_DP<6>")
	)
	(arc
		(start 375.82475 -232.03027)
		(mid 375.548275 -231.96295)
		(end 375.274078 -232.038906)
		(width 0.088646)
		(layer "In11.Cu")
		(net "M_H_CPU0_SB_DQS_DP<6>")
	)
	(arc
		(start 383.732532 -232.038906)
		(mid 383.545334 -232.089049)
		(end 383.358136 -232.038906)
		(width 0.088646)
		(layer "In11.Cu")
		(net "M_H_CPU0_SB_DQS_DP<6>")
	)
	(arc
		(start 376.779282 -232.03916)
		(mid 376.496834 -231.963477)
		(end 376.214386 -232.03916)
		(width 0.088646)
		(layer "In11.Cu")
		(net "M_H_CPU0_SB_DQS_DP<6>")
	)
	(arc
		(start 384.672332 -232.038906)
		(mid 384.485134 -232.089049)
		(end 384.297936 -232.038906)
		(width 0.088646)
		(layer "In11.Cu")
		(net "M_H_CPU0_SB_DQS_DP<6>")
	)
	(arc
		(start 378.093986 -232.03916)
		(mid 377.913699 -232.089572)
		(end 377.731528 -232.046526)
		(width 0.088646)
		(layer "In11.Cu")
		(net "M_H_CPU0_SB_DQS_DP<6>")
	)
	(arc
		(start 375.274078 -232.038906)
		(mid 375.08688 -232.089049)
		(end 374.899682 -232.038906)
		(width 0.088646)
		(layer "In11.Cu")
		(net "M_H_CPU0_SB_DQS_DP<6>")
	)
	(arc
		(start 373.738902 -232.108502)
		(mid 373.726487 -232.10944)
		(end 373.714264 -232.111804)
		(width 0.088646)
		(layer "In11.Cu")
		(net "M_H_CPU0_SB_DQS_DP<6>")
	)
	(arc
		(start 386.177536 -232.038906)
		(mid 385.894834 -231.96313)
		(end 385.612132 -232.038906)
		(width 0.088646)
		(layer "In11.Cu")
		(net "M_H_CPU0_SB_DQS_DP<6>")
	)
	(arc
		(start 377.154186 -232.03916)
		(mid 376.966734 -232.089396)
		(end 376.779282 -232.03916)
		(width 0.088646)
		(layer "In11.Cu")
		(net "M_H_CPU0_SB_DQS_DP<6>")
	)
	(arc
		(start 385.612132 -232.038906)
		(mid 385.424934 -232.089049)
		(end 385.237736 -232.038906)
		(width 0.088646)
		(layer "In11.Cu")
		(net "M_H_CPU0_SB_DQS_DP<6>")
	)
	(arc
		(start 386.739384 -231.714548)
		(mid 386.552085 -232.038989)
		(end 386.177536 -232.038906)
		(width 0.088646)
		(layer "In11.Cu")
		(net "M_H_CPU0_SB_DQS_DP<6>")
	)
	(arc
		(start 382.792478 -232.038906)
		(mid 382.605199 -232.089176)
		(end 382.417828 -232.03916)
		(width 0.088646)
		(layer "In11.Cu")
		(net "M_H_CPU0_SB_DQS_DP<6>")
	)
	(segment
		(start 461.14716 -226.88931)
		(end 460.892144 -226.634294)
		(width 0.20066)
		(layer "F.Cu")
		(net "M_H_CPU0_SB_DQS_DP<5>")
	)
	(segment
		(start 372.73738 -237.947454)
		(end 372.73738 -237.411768)
		(width 0.20066)
		(layer "F.Cu")
		(net "M_H_CPU0_SB_DQS_DP<5>")
	)
	(segment
		(start 461.800702 -226.88931)
		(end 461.14716 -226.88931)
		(width 0.20066)
		(layer "F.Cu")
		(net "M_H_CPU0_SB_DQS_DP<5>")
	)
	(segment
		(start 460.570326 -226.634294)
		(end 460.56296 -226.64166)
		(width 0.1016)
		(layer "F.Cu")
		(net "M_H_CPU0_SB_DQS_DP<5>")
	)
	(segment
		(start 462.823814 -227.334826)
		(end 462.246218 -227.334826)
		(width 0.20066)
		(layer "F.Cu")
		(net "M_H_CPU0_SB_DQS_DP<5>")
	)
	(segment
		(start 455.011282 -227.066602)
		(end 456.116182 -227.066602)
		(width 0.20066)
		(layer "F.Cu")
		(net "M_H_CPU0_SB_DQS_DP<5>")
	)
	(segment
		(start 457.265532 -227.317808)
		(end 456.960732 -227.317808)
		(width 0.20066)
		(layer "F.Cu")
		(net "M_H_CPU0_SB_DQS_DP<5>")
	)
	(segment
		(start 457.968858 -226.892866)
		(end 457.690474 -226.892866)
		(width 0.20066)
		(layer "F.Cu")
		(net "M_H_CPU0_SB_DQS_DP<5>")
	)
	(segment
		(start 462.246218 -227.334826)
		(end 461.800702 -226.88931)
		(width 0.20066)
		(layer "F.Cu")
		(net "M_H_CPU0_SB_DQS_DP<5>")
	)
	(segment
		(start 458.550264 -226.64166)
		(end 458.543152 -226.634548)
		(width 0.1016)
		(layer "F.Cu")
		(net "M_H_CPU0_SB_DQS_DP<5>")
	)
	(segment
		(start 463.659982 -227.066602)
		(end 463.092038 -227.066602)
		(width 0.20066)
		(layer "F.Cu")
		(net "M_H_CPU0_SB_DQS_DP<5>")
	)
	(segment
		(start 457.690474 -226.892866)
		(end 457.265532 -227.317808)
		(width 0.20066)
		(layer "F.Cu")
		(net "M_H_CPU0_SB_DQS_DP<5>")
	)
	(segment
		(start 463.092038 -227.066602)
		(end 462.823814 -227.334826)
		(width 0.20066)
		(layer "F.Cu")
		(net "M_H_CPU0_SB_DQS_DP<5>")
	)
	(segment
		(start 456.709526 -227.066602)
		(end 456.116182 -227.066602)
		(width 0.20066)
		(layer "F.Cu")
		(net "M_H_CPU0_SB_DQS_DP<5>")
	)
	(segment
		(start 458.538326 -226.634548)
		(end 458.227176 -226.634548)
		(width 0.20066)
		(layer "F.Cu")
		(net "M_H_CPU0_SB_DQS_DP<5>")
	)
	(segment
		(start 372.73738 -237.411768)
		(end 372.737634 -237.411514)
		(width 0.20066)
		(layer "F.Cu")
		(net "M_H_CPU0_SB_DQS_DP<5>")
	)
	(segment
		(start 458.543152 -226.634548)
		(end 458.538326 -226.634548)
		(width 0.101854)
		(layer "F.Cu")
		(net "M_H_CPU0_SB_DQS_DP<5>")
	)
	(segment
		(start 460.56296 -226.64166)
		(end 458.550264 -226.64166)
		(width 0.1016)
		(layer "F.Cu")
		(net "M_H_CPU0_SB_DQS_DP<5>")
	)
	(segment
		(start 456.960732 -227.317808)
		(end 456.709526 -227.066602)
		(width 0.20066)
		(layer "F.Cu")
		(net "M_H_CPU0_SB_DQS_DP<5>")
	)
	(segment
		(start 460.892144 -226.634294)
		(end 460.570326 -226.634294)
		(width 0.20066)
		(layer "F.Cu")
		(net "M_H_CPU0_SB_DQS_DP<5>")
	)
	(segment
		(start 458.227176 -226.634548)
		(end 457.968858 -226.892866)
		(width 0.20066)
		(layer "F.Cu")
		(net "M_H_CPU0_SB_DQS_DP<5>")
	)
	(segment
		(start 374.324372 -236.927898)
		(end 374.213374 -236.982508)
		(width 0.088646)
		(layer "In11.Cu")
		(net "M_H_CPU0_SB_DQS_DP<5>")
	)
	(segment
		(start 415.286444 -224.413318)
		(end 413.137096 -224.413318)
		(width 0.18288)
		(layer "In11.Cu")
		(net "M_H_CPU0_SB_DQS_DP<5>")
	)
	(segment
		(start 427.53788 -222.023178)
		(end 426.669708 -222.023178)
		(width 0.18288)
		(layer "In11.Cu")
		(net "M_H_CPU0_SB_DQS_DP<5>")
	)
	(segment
		(start 431.155602 -222.440246)
		(end 427.954948 -222.440246)
		(width 0.18288)
		(layer "In11.Cu")
		(net "M_H_CPU0_SB_DQS_DP<5>")
	)
	(segment
		(start 380.547372 -236.927644)
		(end 380.53899 -236.922818)
		(width 0.088646)
		(layer "In11.Cu")
		(net "M_H_CPU0_SB_DQS_DP<5>")
	)
	(segment
		(start 392.610594 -236.307884)
		(end 389.019796 -236.307884)
		(width 0.18288)
		(layer "In11.Cu")
		(net "M_H_CPU0_SB_DQS_DP<5>")
	)
	(segment
		(start 378.671328 -236.92993)
		(end 378.65939 -236.922818)
		(width 0.088646)
		(layer "In11.Cu")
		(net "M_H_CPU0_SB_DQS_DP<5>")
	)
	(segment
		(start 454.06183 -227.499672)
		(end 452.462138 -227.499672)
		(width 0.18288)
		(layer "In11.Cu")
		(net "M_H_CPU0_SB_DQS_DP<5>")
	)
	(segment
		(start 451.873112 -226.910646)
		(end 451.429628 -226.910646)
		(width 0.18288)
		(layer "In11.Cu")
		(net "M_H_CPU0_SB_DQS_DP<5>")
	)
	(segment
		(start 384.297682 -236.922056)
		(end 384.28295 -236.91342)
		(width 0.088646)
		(layer "In11.Cu")
		(net "M_H_CPU0_SB_DQS_DP<5>")
	)
	(segment
		(start 450.68617 -226.641152)
		(end 450.4055 -226.921822)
		(width 0.18288)
		(layer "In11.Cu")
		(net "M_H_CPU0_SB_DQS_DP<5>")
	)
	(segment
		(start 411.61335 -223.522286)
		(end 410.769308 -224.366328)
		(width 0.18288)
		(layer "In11.Cu")
		(net "M_H_CPU0_SB_DQS_DP<5>")
	)
	(segment
		(start 374.334278 -236.922056)
		(end 374.324372 -236.927898)
		(width 0.088646)
		(layer "In11.Cu")
		(net "M_H_CPU0_SB_DQS_DP<5>")
	)
	(segment
		(start 436.307484 -221.818708)
		(end 436.029862 -221.541086)
		(width 0.18288)
		(layer "In11.Cu")
		(net "M_H_CPU0_SB_DQS_DP<5>")
	)
	(segment
		(start 387.665214 -237.048294)
		(end 387.150102 -237.048294)
		(width 0.088646)
		(layer "In11.Cu")
		(net "M_H_CPU0_SB_DQS_DP<5>")
	)
	(segment
		(start 445.074294 -225.712274)
		(end 443.88913 -224.527364)
		(width 0.18288)
		(layer "In11.Cu")
		(net "M_H_CPU0_SB_DQS_DP<5>")
	)
	(segment
		(start 409.956254 -224.090992)
		(end 409.542234 -224.090992)
		(width 0.18288)
		(layer "In11.Cu")
		(net "M_H_CPU0_SB_DQS_DP<5>")
	)
	(segment
		(start 406.599644 -225.216212)
		(end 406.121108 -225.216212)
		(width 0.18288)
		(layer "In11.Cu")
		(net "M_H_CPU0_SB_DQS_DP<5>")
	)
	(segment
		(start 405.421338 -224.942908)
		(end 405.127714 -225.236532)
		(width 0.18288)
		(layer "In11.Cu")
		(net "M_H_CPU0_SB_DQS_DP<5>")
	)
	(segment
		(start 440.439302 -222.666306)
		(end 440.163966 -222.39097)
		(width 0.18288)
		(layer "In11.Cu")
		(net "M_H_CPU0_SB_DQS_DP<5>")
	)
	(segment
		(start 375.851166 -236.929422)
		(end 375.849388 -236.928406)
		(width 0.088646)
		(layer "In11.Cu")
		(net "M_H_CPU0_SB_DQS_DP<5>")
	)
	(segment
		(start 381.852678 -236.922818)
		(end 381.844296 -236.927898)
		(width 0.088646)
		(layer "In11.Cu")
		(net "M_H_CPU0_SB_DQS_DP<5>")
	)
	(segment
		(start 373.616982 -237.019338)
		(end 373.490236 -237.087156)
		(width 0.088646)
		(layer "In11.Cu")
		(net "M_H_CPU0_SB_DQS_DP<5>")
	)
	(segment
		(start 426.049948 -222.642938)
		(end 425.300394 -222.642938)
		(width 0.18288)
		(layer "In11.Cu")
		(net "M_H_CPU0_SB_DQS_DP<5>")
	)
	(segment
		(start 375.851928 -236.92993)
		(end 375.851166 -236.929422)
		(width 0.088646)
		(layer "In11.Cu")
		(net "M_H_CPU0_SB_DQS_DP<5>")
	)
	(segment
		(start 420.526718 -223.241108)
		(end 420.238936 -223.52889)
		(width 0.18288)
		(layer "In11.Cu")
		(net "M_H_CPU0_SB_DQS_DP<5>")
	)
	(segment
		(start 438.568084 -222.660972)
		(end 436.53456 -221.818708)
		(width 0.18288)
		(layer "In11.Cu")
		(net "M_H_CPU0_SB_DQS_DP<5>")
	)
	(segment
		(start 388.960106 -236.367574)
		(end 388.346442 -236.367574)
		(width 0.088646)
		(layer "In11.Cu")
		(net "M_H_CPU0_SB_DQS_DP<5>")
	)
	(segment
		(start 422.269158 -222.677736)
		(end 421.41521 -223.531684)
		(width 0.18288)
		(layer "In11.Cu")
		(net "M_H_CPU0_SB_DQS_DP<5>")
	)
	(segment
		(start 439.428128 -222.660972)
		(end 438.568084 -222.660972)
		(width 0.18288)
		(layer "In11.Cu")
		(net "M_H_CPU0_SB_DQS_DP<5>")
	)
	(segment
		(start 447.99377 -226.921822)
		(end 445.074294 -225.712274)
		(width 0.18288)
		(layer "In11.Cu")
		(net "M_H_CPU0_SB_DQS_DP<5>")
	)
	(segment
		(start 409.542234 -224.090992)
		(end 409.272994 -224.360232)
		(width 0.18288)
		(layer "In11.Cu")
		(net "M_H_CPU0_SB_DQS_DP<5>")
	)
	(segment
		(start 383.357882 -236.922056)
		(end 383.357882 -236.922564)
		(width 0.088646)
		(layer "In11.Cu")
		(net "M_H_CPU0_SB_DQS_DP<5>")
	)
	(segment
		(start 425.300394 -222.642938)
		(end 425.048426 -222.39097)
		(width 0.18288)
		(layer "In11.Cu")
		(net "M_H_CPU0_SB_DQS_DP<5>")
	)
	(segment
		(start 407.455624 -224.360232)
		(end 406.599644 -225.216212)
		(width 0.18288)
		(layer "In11.Cu")
		(net "M_H_CPU0_SB_DQS_DP<5>")
	)
	(segment
		(start 406.121108 -225.216212)
		(end 405.847804 -224.942908)
		(width 0.18288)
		(layer "In11.Cu")
		(net "M_H_CPU0_SB_DQS_DP<5>")
	)
	(segment
		(start 424.63085 -222.39097)
		(end 424.344084 -222.677736)
		(width 0.18288)
		(layer "In11.Cu")
		(net "M_H_CPU0_SB_DQS_DP<5>")
	)
	(segment
		(start 416.170872 -223.52889)
		(end 415.286444 -224.413318)
		(width 0.18288)
		(layer "In11.Cu")
		(net "M_H_CPU0_SB_DQS_DP<5>")
	)
	(segment
		(start 425.048426 -222.39097)
		(end 424.63085 -222.39097)
		(width 0.18288)
		(layer "In11.Cu")
		(net "M_H_CPU0_SB_DQS_DP<5>")
	)
	(segment
		(start 421.41521 -223.531684)
		(end 421.235886 -223.531684)
		(width 0.18288)
		(layer "In11.Cu")
		(net "M_H_CPU0_SB_DQS_DP<5>")
	)
	(segment
		(start 409.272994 -224.360232)
		(end 407.455624 -224.360232)
		(width 0.18288)
		(layer "In11.Cu")
		(net "M_H_CPU0_SB_DQS_DP<5>")
	)
	(segment
		(start 375.822718 -236.912404)
		(end 375.82475 -236.91342)
		(width 0.088646)
		(layer "In11.Cu")
		(net "M_H_CPU0_SB_DQS_DP<5>")
	)
	(segment
		(start 389.019796 -236.307884)
		(end 388.960106 -236.367574)
		(width 0.088646)
		(layer "In11.Cu")
		(net "M_H_CPU0_SB_DQS_DP<5>")
	)
	(segment
		(start 424.344084 -222.677736)
		(end 422.269158 -222.677736)
		(width 0.18288)
		(layer "In11.Cu")
		(net "M_H_CPU0_SB_DQS_DP<5>")
	)
	(segment
		(start 373.31015 -237.337346)
		(end 373.235982 -237.411514)
		(width 0.088646)
		(layer "In11.Cu")
		(net "M_H_CPU0_SB_DQS_DP<5>")
	)
	(segment
		(start 403.681946 -225.236532)
		(end 392.610594 -236.307884)
		(width 0.18288)
		(layer "In11.Cu")
		(net "M_H_CPU0_SB_DQS_DP<5>")
	)
	(segment
		(start 375.849388 -236.928406)
		(end 375.848626 -236.927898)
		(width 0.088646)
		(layer "In11.Cu")
		(net "M_H_CPU0_SB_DQS_DP<5>")
	)
	(segment
		(start 373.235982 -237.411514)
		(end 372.737634 -237.411514)
		(width 0.088646)
		(layer "In11.Cu")
		(net "M_H_CPU0_SB_DQS_DP<5>")
	)
	(segment
		(start 435.338982 -221.809818)
		(end 432.677824 -221.809818)
		(width 0.18288)
		(layer "In11.Cu")
		(net "M_H_CPU0_SB_DQS_DP<5>")
	)
	(segment
		(start 441.05068 -222.666306)
		(end 440.439302 -222.666306)
		(width 0.18288)
		(layer "In11.Cu")
		(net "M_H_CPU0_SB_DQS_DP<5>")
	)
	(segment
		(start 388.346442 -236.367574)
		(end 387.665468 -237.048548)
		(width 0.088646)
		(layer "In11.Cu")
		(net "M_H_CPU0_SB_DQS_DP<5>")
	)
	(segment
		(start 387.150102 -237.048294)
		(end 386.935218 -236.959394)
		(width 0.088646)
		(layer "In11.Cu")
		(net "M_H_CPU0_SB_DQS_DP<5>")
	)
	(segment
		(start 454.45553 -227.336604)
		(end 454.06183 -227.499672)
		(width 0.18288)
		(layer "In11.Cu")
		(net "M_H_CPU0_SB_DQS_DP<5>")
	)
	(segment
		(start 426.669708 -222.023178)
		(end 426.049948 -222.642938)
		(width 0.18288)
		(layer "In11.Cu")
		(net "M_H_CPU0_SB_DQS_DP<5>")
	)
	(segment
		(start 386.935218 -236.959394)
		(end 386.340096 -236.959394)
		(width 0.088646)
		(layer "In11.Cu")
		(net "M_H_CPU0_SB_DQS_DP<5>")
	)
	(segment
		(start 436.029862 -221.541086)
		(end 435.607714 -221.541086)
		(width 0.18288)
		(layer "In11.Cu")
		(net "M_H_CPU0_SB_DQS_DP<5>")
	)
	(segment
		(start 440.163966 -222.39097)
		(end 439.69813 -222.39097)
		(width 0.18288)
		(layer "In11.Cu")
		(net "M_H_CPU0_SB_DQS_DP<5>")
	)
	(segment
		(start 427.954948 -222.440246)
		(end 427.53788 -222.023178)
		(width 0.18288)
		(layer "In11.Cu")
		(net "M_H_CPU0_SB_DQS_DP<5>")
	)
	(segment
		(start 377.731528 -236.92993)
		(end 377.71959 -236.922818)
		(width 0.088646)
		(layer "In11.Cu")
		(net "M_H_CPU0_SB_DQS_DP<5>")
	)
	(segment
		(start 375.84761 -236.92739)
		(end 375.846086 -236.926374)
		(width 0.088646)
		(layer "In11.Cu")
		(net "M_H_CPU0_SB_DQS_DP<5>")
	)
	(segment
		(start 454.74128 -227.336604)
		(end 454.45553 -227.336604)
		(width 0.18288)
		(layer "In11.Cu")
		(net "M_H_CPU0_SB_DQS_DP<5>")
	)
	(segment
		(start 375.84126 -236.923326)
		(end 375.822718 -236.912404)
		(width 0.088646)
		(layer "In11.Cu")
		(net "M_H_CPU0_SB_DQS_DP<5>")
	)
	(segment
		(start 412.246064 -223.522286)
		(end 411.61335 -223.522286)
		(width 0.18288)
		(layer "In11.Cu")
		(net "M_H_CPU0_SB_DQS_DP<5>")
	)
	(segment
		(start 420.238936 -223.52889)
		(end 416.170872 -223.52889)
		(width 0.18288)
		(layer "In11.Cu")
		(net "M_H_CPU0_SB_DQS_DP<5>")
	)
	(segment
		(start 379.611128 -236.92993)
		(end 379.59919 -236.922818)
		(width 0.088646)
		(layer "In11.Cu")
		(net "M_H_CPU0_SB_DQS_DP<5>")
	)
	(segment
		(start 413.137096 -224.413318)
		(end 412.246064 -223.522286)
		(width 0.18288)
		(layer "In11.Cu")
		(net "M_H_CPU0_SB_DQS_DP<5>")
	)
	(segment
		(start 443.746636 -224.467928)
		(end 441.05068 -222.666306)
		(width 0.18288)
		(layer "In11.Cu")
		(net "M_H_CPU0_SB_DQS_DP<5>")
	)
	(segment
		(start 385.237482 -236.922056)
		(end 385.22275 -236.91342)
		(width 0.088646)
		(layer "In11.Cu")
		(net "M_H_CPU0_SB_DQS_DP<5>")
	)
	(segment
		(start 420.94531 -223.241108)
		(end 420.526718 -223.241108)
		(width 0.18288)
		(layer "In11.Cu")
		(net "M_H_CPU0_SB_DQS_DP<5>")
	)
	(segment
		(start 375.843546 -236.92485)
		(end 375.84126 -236.923326)
		(width 0.088646)
		(layer "In11.Cu")
		(net "M_H_CPU0_SB_DQS_DP<5>")
	)
	(segment
		(start 451.429628 -226.910646)
		(end 451.160134 -226.641152)
		(width 0.18288)
		(layer "In11.Cu")
		(net "M_H_CPU0_SB_DQS_DP<5>")
	)
	(segment
		(start 439.69813 -222.39097)
		(end 439.428128 -222.660972)
		(width 0.18288)
		(layer "In11.Cu")
		(net "M_H_CPU0_SB_DQS_DP<5>")
	)
	(segment
		(start 451.160134 -226.641152)
		(end 450.68617 -226.641152)
		(width 0.18288)
		(layer "In11.Cu")
		(net "M_H_CPU0_SB_DQS_DP<5>")
	)
	(segment
		(start 452.462138 -227.499672)
		(end 451.873112 -226.910646)
		(width 0.18288)
		(layer "In11.Cu")
		(net "M_H_CPU0_SB_DQS_DP<5>")
	)
	(segment
		(start 410.769308 -224.366328)
		(end 410.23159 -224.366328)
		(width 0.18288)
		(layer "In11.Cu")
		(net "M_H_CPU0_SB_DQS_DP<5>")
	)
	(segment
		(start 374.213374 -236.982508)
		(end 373.738902 -236.991652)
		(width 0.088646)
		(layer "In11.Cu")
		(net "M_H_CPU0_SB_DQS_DP<5>")
	)
	(segment
		(start 436.53456 -221.818708)
		(end 436.307484 -221.818708)
		(width 0.18288)
		(layer "In11.Cu")
		(net "M_H_CPU0_SB_DQS_DP<5>")
	)
	(segment
		(start 387.665468 -237.048548)
		(end 387.665214 -237.048294)
		(width 0.088646)
		(layer "In11.Cu")
		(net "M_H_CPU0_SB_DQS_DP<5>")
	)
	(segment
		(start 375.848626 -236.927898)
		(end 375.84761 -236.92739)
		(width 0.088646)
		(layer "In11.Cu")
		(net "M_H_CPU0_SB_DQS_DP<5>")
	)
	(segment
		(start 435.607714 -221.541086)
		(end 435.338982 -221.809818)
		(width 0.18288)
		(layer "In11.Cu")
		(net "M_H_CPU0_SB_DQS_DP<5>")
	)
	(segment
		(start 432.677824 -221.809818)
		(end 431.155602 -222.440246)
		(width 0.18288)
		(layer "In11.Cu")
		(net "M_H_CPU0_SB_DQS_DP<5>")
	)
	(segment
		(start 375.846086 -236.926374)
		(end 375.843546 -236.92485)
		(width 0.088646)
		(layer "In11.Cu")
		(net "M_H_CPU0_SB_DQS_DP<5>")
	)
	(segment
		(start 405.127714 -225.236532)
		(end 403.681946 -225.236532)
		(width 0.18288)
		(layer "In11.Cu")
		(net "M_H_CPU0_SB_DQS_DP<5>")
	)
	(segment
		(start 373.490236 -237.087156)
		(end 373.481346 -237.092236)
		(width 0.088646)
		(layer "In11.Cu")
		(net "M_H_CPU0_SB_DQS_DP<5>")
	)
	(segment
		(start 450.4055 -226.921822)
		(end 447.99377 -226.921822)
		(width 0.18288)
		(layer "In11.Cu")
		(net "M_H_CPU0_SB_DQS_DP<5>")
	)
	(segment
		(start 405.847804 -224.942908)
		(end 405.421338 -224.942908)
		(width 0.18288)
		(layer "In11.Cu")
		(net "M_H_CPU0_SB_DQS_DP<5>")
	)
	(segment
		(start 373.714264 -236.994954)
		(end 373.616982 -237.019338)
		(width 0.088646)
		(layer "In11.Cu")
		(net "M_H_CPU0_SB_DQS_DP<5>")
	)
	(segment
		(start 455.011282 -227.066602)
		(end 454.74128 -227.336604)
		(width 0.18288)
		(layer "In11.Cu")
		(net "M_H_CPU0_SB_DQS_DP<5>")
	)
	(segment
		(start 443.88913 -224.527364)
		(end 443.746636 -224.467928)
		(width 0.18288)
		(layer "In11.Cu")
		(net "M_H_CPU0_SB_DQS_DP<5>")
	)
	(segment
		(start 374.899682 -236.922056)
		(end 374.88495 -236.91342)
		(width 0.088646)
		(layer "In11.Cu")
		(net "M_H_CPU0_SB_DQS_DP<5>")
	)
	(segment
		(start 421.235886 -223.531684)
		(end 420.94531 -223.241108)
		(width 0.18288)
		(layer "In11.Cu")
		(net "M_H_CPU0_SB_DQS_DP<5>")
	)
	(segment
		(start 410.23159 -224.366328)
		(end 409.956254 -224.090992)
		(width 0.18288)
		(layer "In11.Cu")
		(net "M_H_CPU0_SB_DQS_DP<5>")
	)
	(arc
		(start 386.16255 -236.91342)
		(mid 385.886075 -236.8461)
		(end 385.611878 -236.922056)
		(width 0.088646)
		(layer "In11.Cu")
		(net "M_H_CPU0_SB_DQS_DP<5>")
	)
	(arc
		(start 383.732278 -236.922056)
		(mid 383.54508 -236.972233)
		(end 383.357882 -236.922056)
		(width 0.088646)
		(layer "In11.Cu")
		(net "M_H_CPU0_SB_DQS_DP<5>")
	)
	(arc
		(start 382.792986 -236.922564)
		(mid 382.605534 -236.9728)
		(end 382.418082 -236.922564)
		(width 0.088646)
		(layer "In11.Cu")
		(net "M_H_CPU0_SB_DQS_DP<5>")
	)
	(arc
		(start 378.093986 -236.922564)
		(mid 377.913699 -236.972976)
		(end 377.731528 -236.92993)
		(width 0.088646)
		(layer "In11.Cu")
		(net "M_H_CPU0_SB_DQS_DP<5>")
	)
	(arc
		(start 379.59919 -236.922818)
		(mid 379.316517 -236.846812)
		(end 379.033786 -236.922564)
		(width 0.088646)
		(layer "In11.Cu")
		(net "M_H_CPU0_SB_DQS_DP<5>")
	)
	(arc
		(start 381.844296 -236.927898)
		(mid 381.660475 -236.972956)
		(end 381.478028 -236.922564)
		(width 0.088646)
		(layer "In11.Cu")
		(net "M_H_CPU0_SB_DQS_DP<5>")
	)
	(arc
		(start 380.53899 -236.922818)
		(mid 380.256317 -236.846812)
		(end 379.973586 -236.922564)
		(width 0.088646)
		(layer "In11.Cu")
		(net "M_H_CPU0_SB_DQS_DP<5>")
	)
	(arc
		(start 383.357882 -236.922564)
		(mid 383.075434 -236.846847)
		(end 382.792986 -236.922564)
		(width 0.088646)
		(layer "In11.Cu")
		(net "M_H_CPU0_SB_DQS_DP<5>")
	)
	(arc
		(start 384.672078 -236.922056)
		(mid 384.48488 -236.972233)
		(end 384.297682 -236.922056)
		(width 0.088646)
		(layer "In11.Cu")
		(net "M_H_CPU0_SB_DQS_DP<5>")
	)
	(arc
		(start 376.214386 -236.922564)
		(mid 376.034099 -236.972976)
		(end 375.851928 -236.92993)
		(width 0.088646)
		(layer "In11.Cu")
		(net "M_H_CPU0_SB_DQS_DP<5>")
	)
	(arc
		(start 374.88495 -236.91342)
		(mid 374.608475 -236.8461)
		(end 374.334278 -236.922056)
		(width 0.088646)
		(layer "In11.Cu")
		(net "M_H_CPU0_SB_DQS_DP<5>")
	)
	(arc
		(start 375.82475 -236.91342)
		(mid 375.548275 -236.8461)
		(end 375.274078 -236.922056)
		(width 0.088646)
		(layer "In11.Cu")
		(net "M_H_CPU0_SB_DQS_DP<5>")
	)
	(arc
		(start 382.418082 -236.922564)
		(mid 382.135351 -236.846847)
		(end 381.852678 -236.922818)
		(width 0.088646)
		(layer "In11.Cu")
		(net "M_H_CPU0_SB_DQS_DP<5>")
	)
	(arc
		(start 384.28295 -236.91342)
		(mid 384.006475 -236.8461)
		(end 383.732278 -236.922056)
		(width 0.088646)
		(layer "In11.Cu")
		(net "M_H_CPU0_SB_DQS_DP<5>")
	)
	(arc
		(start 378.65939 -236.922818)
		(mid 378.376717 -236.846812)
		(end 378.093986 -236.922564)
		(width 0.088646)
		(layer "In11.Cu")
		(net "M_H_CPU0_SB_DQS_DP<5>")
	)
	(arc
		(start 380.913132 -236.922564)
		(mid 380.73091 -236.972764)
		(end 380.547372 -236.927644)
		(width 0.088646)
		(layer "In11.Cu")
		(net "M_H_CPU0_SB_DQS_DP<5>")
	)
	(arc
		(start 379.973586 -236.922564)
		(mid 379.793299 -236.972976)
		(end 379.611128 -236.92993)
		(width 0.088646)
		(layer "In11.Cu")
		(net "M_H_CPU0_SB_DQS_DP<5>")
	)
	(arc
		(start 385.22275 -236.91342)
		(mid 384.946275 -236.8461)
		(end 384.672078 -236.922056)
		(width 0.088646)
		(layer "In11.Cu")
		(net "M_H_CPU0_SB_DQS_DP<5>")
	)
	(arc
		(start 385.611878 -236.922056)
		(mid 385.42468 -236.972233)
		(end 385.237482 -236.922056)
		(width 0.088646)
		(layer "In11.Cu")
		(net "M_H_CPU0_SB_DQS_DP<5>")
	)
	(arc
		(start 379.033786 -236.922564)
		(mid 378.853499 -236.972976)
		(end 378.671328 -236.92993)
		(width 0.088646)
		(layer "In11.Cu")
		(net "M_H_CPU0_SB_DQS_DP<5>")
	)
	(arc
		(start 376.779282 -236.922564)
		(mid 376.496834 -236.846847)
		(end 376.214386 -236.922564)
		(width 0.088646)
		(layer "In11.Cu")
		(net "M_H_CPU0_SB_DQS_DP<5>")
	)
	(arc
		(start 381.478028 -236.922564)
		(mid 381.19558 -236.846847)
		(end 380.913132 -236.922564)
		(width 0.088646)
		(layer "In11.Cu")
		(net "M_H_CPU0_SB_DQS_DP<5>")
	)
	(arc
		(start 373.481346 -237.092236)
		(mid 373.370248 -237.196979)
		(end 373.31015 -237.337346)
		(width 0.088646)
		(layer "In11.Cu")
		(net "M_H_CPU0_SB_DQS_DP<5>")
	)
	(arc
		(start 377.71959 -236.922818)
		(mid 377.436917 -236.846812)
		(end 377.154186 -236.922564)
		(width 0.088646)
		(layer "In11.Cu")
		(net "M_H_CPU0_SB_DQS_DP<5>")
	)
	(arc
		(start 377.154186 -236.922564)
		(mid 376.966734 -236.9728)
		(end 376.779282 -236.922564)
		(width 0.088646)
		(layer "In11.Cu")
		(net "M_H_CPU0_SB_DQS_DP<5>")
	)
	(arc
		(start 375.274078 -236.922056)
		(mid 375.08688 -236.972233)
		(end 374.899682 -236.922056)
		(width 0.088646)
		(layer "In11.Cu")
		(net "M_H_CPU0_SB_DQS_DP<5>")
	)
	(arc
		(start 386.340096 -236.959394)
		(mid 386.248462 -236.947446)
		(end 386.16255 -236.91342)
		(width 0.088646)
		(layer "In11.Cu")
		(net "M_H_CPU0_SB_DQS_DP<5>")
	)
	(arc
		(start 373.738902 -236.991652)
		(mid 373.726487 -236.99259)
		(end 373.714264 -236.994954)
		(width 0.088646)
		(layer "In11.Cu")
		(net "M_H_CPU0_SB_DQS_DP<5>")
	)
	(segment
		(start 461.14716 -236.239304)
		(end 460.892144 -235.984288)
		(width 0.20066)
		(layer "F.Cu")
		(net "M_H_CPU0_SB_DQS_DP<4>")
	)
	(segment
		(start 458.550264 -235.991654)
		(end 458.543152 -235.984542)
		(width 0.1016)
		(layer "F.Cu")
		(net "M_H_CPU0_SB_DQS_DP<4>")
	)
	(segment
		(start 463.092038 -236.416596)
		(end 462.823814 -236.68482)
		(width 0.20066)
		(layer "F.Cu")
		(net "M_H_CPU0_SB_DQS_DP<4>")
	)
	(segment
		(start 458.543152 -235.984542)
		(end 458.538326 -235.984542)
		(width 0.101854)
		(layer "F.Cu")
		(net "M_H_CPU0_SB_DQS_DP<4>")
	)
	(segment
		(start 458.538326 -235.984542)
		(end 458.227176 -235.984542)
		(width 0.20066)
		(layer "F.Cu")
		(net "M_H_CPU0_SB_DQS_DP<4>")
	)
	(segment
		(start 456.709526 -236.416596)
		(end 456.116182 -236.416596)
		(width 0.20066)
		(layer "F.Cu")
		(net "M_H_CPU0_SB_DQS_DP<4>")
	)
	(segment
		(start 372.737634 -242.830604)
		(end 372.737634 -242.294918)
		(width 0.20066)
		(layer "F.Cu")
		(net "M_H_CPU0_SB_DQS_DP<4>")
	)
	(segment
		(start 460.570326 -235.984288)
		(end 460.56296 -235.991654)
		(width 0.1016)
		(layer "F.Cu")
		(net "M_H_CPU0_SB_DQS_DP<4>")
	)
	(segment
		(start 455.011282 -236.416596)
		(end 456.116182 -236.416596)
		(width 0.20066)
		(layer "F.Cu")
		(net "M_H_CPU0_SB_DQS_DP<4>")
	)
	(segment
		(start 462.823814 -236.68482)
		(end 462.246218 -236.68482)
		(width 0.20066)
		(layer "F.Cu")
		(net "M_H_CPU0_SB_DQS_DP<4>")
	)
	(segment
		(start 457.265532 -236.667802)
		(end 456.960732 -236.667802)
		(width 0.20066)
		(layer "F.Cu")
		(net "M_H_CPU0_SB_DQS_DP<4>")
	)
	(segment
		(start 462.246218 -236.68482)
		(end 461.800702 -236.239304)
		(width 0.20066)
		(layer "F.Cu")
		(net "M_H_CPU0_SB_DQS_DP<4>")
	)
	(segment
		(start 460.56296 -235.991654)
		(end 458.550264 -235.991654)
		(width 0.1016)
		(layer "F.Cu")
		(net "M_H_CPU0_SB_DQS_DP<4>")
	)
	(segment
		(start 457.968858 -236.24286)
		(end 457.690474 -236.24286)
		(width 0.20066)
		(layer "F.Cu")
		(net "M_H_CPU0_SB_DQS_DP<4>")
	)
	(segment
		(start 456.960732 -236.667802)
		(end 456.709526 -236.416596)
		(width 0.20066)
		(layer "F.Cu")
		(net "M_H_CPU0_SB_DQS_DP<4>")
	)
	(segment
		(start 372.73738 -242.830858)
		(end 372.737634 -242.830604)
		(width 0.20066)
		(layer "F.Cu")
		(net "M_H_CPU0_SB_DQS_DP<4>")
	)
	(segment
		(start 460.892144 -235.984288)
		(end 460.570326 -235.984288)
		(width 0.20066)
		(layer "F.Cu")
		(net "M_H_CPU0_SB_DQS_DP<4>")
	)
	(segment
		(start 461.800702 -236.239304)
		(end 461.14716 -236.239304)
		(width 0.20066)
		(layer "F.Cu")
		(net "M_H_CPU0_SB_DQS_DP<4>")
	)
	(segment
		(start 463.659982 -236.416596)
		(end 463.092038 -236.416596)
		(width 0.20066)
		(layer "F.Cu")
		(net "M_H_CPU0_SB_DQS_DP<4>")
	)
	(segment
		(start 457.690474 -236.24286)
		(end 457.265532 -236.667802)
		(width 0.20066)
		(layer "F.Cu")
		(net "M_H_CPU0_SB_DQS_DP<4>")
	)
	(segment
		(start 458.227176 -235.984542)
		(end 457.968858 -236.24286)
		(width 0.20066)
		(layer "F.Cu")
		(net "M_H_CPU0_SB_DQS_DP<4>")
	)
	(segment
		(start 452.06539 -236.287818)
		(end 451.454774 -236.287818)
		(width 0.18288)
		(layer "In11.Cu")
		(net "M_H_CPU0_SB_DQS_DP<4>")
	)
	(segment
		(start 440.424824 -235.443268)
		(end 440.122818 -235.141262)
		(width 0.18288)
		(layer "In11.Cu")
		(net "M_H_CPU0_SB_DQS_DP<4>")
	)
	(segment
		(start 374.324372 -241.811302)
		(end 374.213374 -241.865912)
		(width 0.088646)
		(layer "In11.Cu")
		(net "M_H_CPU0_SB_DQS_DP<4>")
	)
	(segment
		(start 407.905712 -235.65231)
		(end 406.694386 -236.15396)
		(width 0.18288)
		(layer "In11.Cu")
		(net "M_H_CPU0_SB_DQS_DP<4>")
	)
	(segment
		(start 374.213374 -241.865912)
		(end 373.738902 -241.875056)
		(width 0.088646)
		(layer "In11.Cu")
		(net "M_H_CPU0_SB_DQS_DP<4>")
	)
	(segment
		(start 425.314618 -233.716576)
		(end 425.039282 -233.44124)
		(width 0.18288)
		(layer "In11.Cu")
		(net "M_H_CPU0_SB_DQS_DP<4>")
	)
	(segment
		(start 413.851344 -235.472732)
		(end 412.332424 -234.843574)
		(width 0.18288)
		(layer "In11.Cu")
		(net "M_H_CPU0_SB_DQS_DP<4>")
	)
	(segment
		(start 417.18611 -234.599734)
		(end 415.07664 -235.472732)
		(width 0.18288)
		(layer "In11.Cu")
		(net "M_H_CPU0_SB_DQS_DP<4>")
	)
	(segment
		(start 430.644554 -233.967528)
		(end 428.064422 -233.967528)
		(width 0.18288)
		(layer "In11.Cu")
		(net "M_H_CPU0_SB_DQS_DP<4>")
	)
	(segment
		(start 435.234588 -234.586272)
		(end 433.755292 -234.586272)
		(width 0.18288)
		(layer "In11.Cu")
		(net "M_H_CPU0_SB_DQS_DP<4>")
	)
	(segment
		(start 375.851928 -241.81308)
		(end 375.83999 -241.805968)
		(width 0.088646)
		(layer "In11.Cu")
		(net "M_H_CPU0_SB_DQS_DP<4>")
	)
	(segment
		(start 377.731528 -241.81308)
		(end 377.71959 -241.805968)
		(width 0.088646)
		(layer "In11.Cu")
		(net "M_H_CPU0_SB_DQS_DP<4>")
	)
	(segment
		(start 428.064422 -233.967528)
		(end 427.21022 -234.321096)
		(width 0.18288)
		(layer "In11.Cu")
		(net "M_H_CPU0_SB_DQS_DP<4>")
	)
	(segment
		(start 424.34383 -233.703876)
		(end 423.430446 -233.703876)
		(width 0.18288)
		(layer "In11.Cu")
		(net "M_H_CPU0_SB_DQS_DP<4>")
	)
	(segment
		(start 448.656964 -236.257338)
		(end 445.70904 -235.67136)
		(width 0.18288)
		(layer "In11.Cu")
		(net "M_H_CPU0_SB_DQS_DP<4>")
	)
	(segment
		(start 442.010038 -236.102906)
		(end 441.774326 -236.005116)
		(width 0.18288)
		(layer "In11.Cu")
		(net "M_H_CPU0_SB_DQS_DP<4>")
	)
	(segment
		(start 420.2049 -234.599734)
		(end 417.18611 -234.599734)
		(width 0.18288)
		(layer "In11.Cu")
		(net "M_H_CPU0_SB_DQS_DP<4>")
	)
	(segment
		(start 375.274586 -241.805714)
		(end 375.274078 -241.80546)
		(width 0.088646)
		(layer "In11.Cu")
		(net "M_H_CPU0_SB_DQS_DP<4>")
	)
	(segment
		(start 421.241474 -234.573064)
		(end 420.959534 -234.291124)
		(width 0.18288)
		(layer "In11.Cu")
		(net "M_H_CPU0_SB_DQS_DP<4>")
	)
	(segment
		(start 424.606466 -233.44124)
		(end 424.34383 -233.703876)
		(width 0.18288)
		(layer "In11.Cu")
		(net "M_H_CPU0_SB_DQS_DP<4>")
	)
	(segment
		(start 373.714264 -241.878358)
		(end 373.616982 -241.902742)
		(width 0.088646)
		(layer "In11.Cu")
		(net "M_H_CPU0_SB_DQS_DP<4>")
	)
	(segment
		(start 435.528212 -234.292648)
		(end 435.234588 -234.586272)
		(width 0.18288)
		(layer "In11.Cu")
		(net "M_H_CPU0_SB_DQS_DP<4>")
	)
	(segment
		(start 374.899682 -241.80546)
		(end 374.88495 -241.796824)
		(width 0.088646)
		(layer "In11.Cu")
		(net "M_H_CPU0_SB_DQS_DP<4>")
	)
	(segment
		(start 395.516608 -242.322604)
		(end 389.019796 -242.322604)
		(width 0.18288)
		(layer "In11.Cu")
		(net "M_H_CPU0_SB_DQS_DP<4>")
	)
	(segment
		(start 427.011592 -234.321096)
		(end 425.552362 -233.716576)
		(width 0.18288)
		(layer "In11.Cu")
		(net "M_H_CPU0_SB_DQS_DP<4>")
	)
	(segment
		(start 443.225682 -235.67136)
		(end 442.183774 -236.102906)
		(width 0.18288)
		(layer "In11.Cu")
		(net "M_H_CPU0_SB_DQS_DP<4>")
	)
	(segment
		(start 378.671328 -241.81308)
		(end 378.65939 -241.805968)
		(width 0.088646)
		(layer "In11.Cu")
		(net "M_H_CPU0_SB_DQS_DP<4>")
	)
	(segment
		(start 451.158102 -235.991146)
		(end 450.70649 -235.991146)
		(width 0.18288)
		(layer "In11.Cu")
		(net "M_H_CPU0_SB_DQS_DP<4>")
	)
	(segment
		(start 423.430446 -233.703876)
		(end 421.331898 -234.573064)
		(width 0.18288)
		(layer "In11.Cu")
		(net "M_H_CPU0_SB_DQS_DP<4>")
	)
	(segment
		(start 379.611128 -241.81308)
		(end 379.59919 -241.805968)
		(width 0.088646)
		(layer "In11.Cu")
		(net "M_H_CPU0_SB_DQS_DP<4>")
	)
	(segment
		(start 373.616982 -241.902742)
		(end 373.490236 -241.97056)
		(width 0.088646)
		(layer "In11.Cu")
		(net "M_H_CPU0_SB_DQS_DP<4>")
	)
	(segment
		(start 374.334278 -241.80546)
		(end 374.324372 -241.811302)
		(width 0.088646)
		(layer "In11.Cu")
		(net "M_H_CPU0_SB_DQS_DP<4>")
	)
	(segment
		(start 409.353512 -236.013244)
		(end 408.481784 -235.65231)
		(width 0.18288)
		(layer "In11.Cu")
		(net "M_H_CPU0_SB_DQS_DP<4>")
	)
	(segment
		(start 454.117202 -236.68101)
		(end 453.587358 -236.900466)
		(width 0.18288)
		(layer "In11.Cu")
		(net "M_H_CPU0_SB_DQS_DP<4>")
	)
	(segment
		(start 382.418082 -241.80546)
		(end 382.407668 -241.799364)
		(width 0.088646)
		(layer "In11.Cu")
		(net "M_H_CPU0_SB_DQS_DP<4>")
	)
	(segment
		(start 441.538614 -235.769404)
		(end 440.75096 -235.443268)
		(width 0.18288)
		(layer "In11.Cu")
		(net "M_H_CPU0_SB_DQS_DP<4>")
	)
	(segment
		(start 452.439786 -236.66196)
		(end 452.06539 -236.287818)
		(width 0.18288)
		(layer "In11.Cu")
		(net "M_H_CPU0_SB_DQS_DP<4>")
	)
	(segment
		(start 425.552362 -233.716576)
		(end 425.314618 -233.716576)
		(width 0.18288)
		(layer "In11.Cu")
		(net "M_H_CPU0_SB_DQS_DP<4>")
	)
	(segment
		(start 437.727852 -235.412788)
		(end 436.908956 -234.593892)
		(width 0.18288)
		(layer "In11.Cu")
		(net "M_H_CPU0_SB_DQS_DP<4>")
	)
	(segment
		(start 388.960106 -242.382294)
		(end 388.171182 -242.382294)
		(width 0.088646)
		(layer "In11.Cu")
		(net "M_H_CPU0_SB_DQS_DP<4>")
	)
	(segment
		(start 421.331898 -234.573064)
		(end 421.241474 -234.573064)
		(width 0.18288)
		(layer "In11.Cu")
		(net "M_H_CPU0_SB_DQS_DP<4>")
	)
	(segment
		(start 408.481784 -235.65231)
		(end 407.905712 -235.65231)
		(width 0.18288)
		(layer "In11.Cu")
		(net "M_H_CPU0_SB_DQS_DP<4>")
	)
	(segment
		(start 453.587358 -236.900466)
		(end 453.015096 -236.900466)
		(width 0.18288)
		(layer "In11.Cu")
		(net "M_H_CPU0_SB_DQS_DP<4>")
	)
	(segment
		(start 440.122818 -235.141262)
		(end 439.655458 -235.141262)
		(width 0.18288)
		(layer "In11.Cu")
		(net "M_H_CPU0_SB_DQS_DP<4>")
	)
	(segment
		(start 427.21022 -234.321096)
		(end 427.011592 -234.321096)
		(width 0.18288)
		(layer "In11.Cu")
		(net "M_H_CPU0_SB_DQS_DP<4>")
	)
	(segment
		(start 420.51351 -234.291124)
		(end 420.2049 -234.599734)
		(width 0.18288)
		(layer "In11.Cu")
		(net "M_H_CPU0_SB_DQS_DP<4>")
	)
	(segment
		(start 454.746868 -236.68101)
		(end 454.117202 -236.68101)
		(width 0.18288)
		(layer "In11.Cu")
		(net "M_H_CPU0_SB_DQS_DP<4>")
	)
	(segment
		(start 455.011282 -236.416596)
		(end 454.746868 -236.68101)
		(width 0.18288)
		(layer "In11.Cu")
		(net "M_H_CPU0_SB_DQS_DP<4>")
	)
	(segment
		(start 400.928586 -236.910626)
		(end 395.516608 -242.322604)
		(width 0.18288)
		(layer "In11.Cu")
		(net "M_H_CPU0_SB_DQS_DP<4>")
	)
	(segment
		(start 425.039282 -233.44124)
		(end 424.606466 -233.44124)
		(width 0.18288)
		(layer "In11.Cu")
		(net "M_H_CPU0_SB_DQS_DP<4>")
	)
	(segment
		(start 415.07664 -235.472732)
		(end 413.851344 -235.472732)
		(width 0.18288)
		(layer "In11.Cu")
		(net "M_H_CPU0_SB_DQS_DP<4>")
	)
	(segment
		(start 388.171182 -242.382294)
		(end 387.956298 -242.597178)
		(width 0.088646)
		(layer "In11.Cu")
		(net "M_H_CPU0_SB_DQS_DP<4>")
	)
	(segment
		(start 389.019796 -242.322604)
		(end 388.960106 -242.382294)
		(width 0.088646)
		(layer "In11.Cu")
		(net "M_H_CPU0_SB_DQS_DP<4>")
	)
	(segment
		(start 381.852932 -241.80546)
		(end 381.853186 -241.805714)
		(width 0.088646)
		(layer "In11.Cu")
		(net "M_H_CPU0_SB_DQS_DP<4>")
	)
	(segment
		(start 409.685744 -236.013244)
		(end 409.353512 -236.013244)
		(width 0.18288)
		(layer "In11.Cu")
		(net "M_H_CPU0_SB_DQS_DP<4>")
	)
	(segment
		(start 450.70649 -235.991146)
		(end 450.440298 -236.257338)
		(width 0.18288)
		(layer "In11.Cu")
		(net "M_H_CPU0_SB_DQS_DP<4>")
	)
	(segment
		(start 405.937974 -236.910626)
		(end 400.928586 -236.910626)
		(width 0.18288)
		(layer "In11.Cu")
		(net "M_H_CPU0_SB_DQS_DP<4>")
	)
	(segment
		(start 436.09514 -234.292648)
		(end 435.528212 -234.292648)
		(width 0.18288)
		(layer "In11.Cu")
		(net "M_H_CPU0_SB_DQS_DP<4>")
	)
	(segment
		(start 420.959534 -234.291124)
		(end 420.51351 -234.291124)
		(width 0.18288)
		(layer "In11.Cu")
		(net "M_H_CPU0_SB_DQS_DP<4>")
	)
	(segment
		(start 380.550928 -241.81308)
		(end 380.53899 -241.805968)
		(width 0.088646)
		(layer "In11.Cu")
		(net "M_H_CPU0_SB_DQS_DP<4>")
	)
	(segment
		(start 451.454774 -236.287818)
		(end 451.158102 -235.991146)
		(width 0.18288)
		(layer "In11.Cu")
		(net "M_H_CPU0_SB_DQS_DP<4>")
	)
	(segment
		(start 450.440298 -236.257338)
		(end 448.656964 -236.257338)
		(width 0.18288)
		(layer "In11.Cu")
		(net "M_H_CPU0_SB_DQS_DP<4>")
	)
	(segment
		(start 439.383932 -235.412788)
		(end 437.727852 -235.412788)
		(width 0.18288)
		(layer "In11.Cu")
		(net "M_H_CPU0_SB_DQS_DP<4>")
	)
	(segment
		(start 411.436058 -234.843574)
		(end 409.685744 -236.013244)
		(width 0.18288)
		(layer "In11.Cu")
		(net "M_H_CPU0_SB_DQS_DP<4>")
	)
	(segment
		(start 442.183774 -236.102906)
		(end 442.010038 -236.102906)
		(width 0.18288)
		(layer "In11.Cu")
		(net "M_H_CPU0_SB_DQS_DP<4>")
	)
	(segment
		(start 436.908956 -234.593892)
		(end 436.396384 -234.593892)
		(width 0.18288)
		(layer "In11.Cu")
		(net "M_H_CPU0_SB_DQS_DP<4>")
	)
	(segment
		(start 406.694386 -236.15396)
		(end 405.937974 -236.910626)
		(width 0.18288)
		(layer "In11.Cu")
		(net "M_H_CPU0_SB_DQS_DP<4>")
	)
	(segment
		(start 383.358136 -241.80546)
		(end 383.347722 -241.799364)
		(width 0.088646)
		(layer "In11.Cu")
		(net "M_H_CPU0_SB_DQS_DP<4>")
	)
	(segment
		(start 439.655458 -235.141262)
		(end 439.383932 -235.412788)
		(width 0.18288)
		(layer "In11.Cu")
		(net "M_H_CPU0_SB_DQS_DP<4>")
	)
	(segment
		(start 436.396384 -234.593892)
		(end 436.09514 -234.292648)
		(width 0.18288)
		(layer "In11.Cu")
		(net "M_H_CPU0_SB_DQS_DP<4>")
	)
	(segment
		(start 433.755292 -234.586272)
		(end 430.644554 -233.967528)
		(width 0.18288)
		(layer "In11.Cu")
		(net "M_H_CPU0_SB_DQS_DP<4>")
	)
	(segment
		(start 412.332424 -234.843574)
		(end 411.436058 -234.843574)
		(width 0.18288)
		(layer "In11.Cu")
		(net "M_H_CPU0_SB_DQS_DP<4>")
	)
	(segment
		(start 445.70904 -235.67136)
		(end 443.225682 -235.67136)
		(width 0.18288)
		(layer "In11.Cu")
		(net "M_H_CPU0_SB_DQS_DP<4>")
	)
	(segment
		(start 387.956298 -242.597178)
		(end 386.166106 -242.597178)
		(width 0.088646)
		(layer "In11.Cu")
		(net "M_H_CPU0_SB_DQS_DP<4>")
	)
	(segment
		(start 440.75096 -235.443268)
		(end 440.424824 -235.443268)
		(width 0.18288)
		(layer "In11.Cu")
		(net "M_H_CPU0_SB_DQS_DP<4>")
	)
	(segment
		(start 441.774326 -236.005116)
		(end 441.538614 -235.769404)
		(width 0.18288)
		(layer "In11.Cu")
		(net "M_H_CPU0_SB_DQS_DP<4>")
	)
	(segment
		(start 386.166106 -242.597178)
		(end 385.425188 -241.85626)
		(width 0.088646)
		(layer "In11.Cu")
		(net "M_H_CPU0_SB_DQS_DP<4>")
	)
	(segment
		(start 453.015096 -236.900466)
		(end 452.439786 -236.66196)
		(width 0.18288)
		(layer "In11.Cu")
		(net "M_H_CPU0_SB_DQS_DP<4>")
	)
	(arc
		(start 381.853186 -241.805714)
		(mid 381.665734 -241.85595)
		(end 381.478282 -241.805714)
		(width 0.088646)
		(layer "In11.Cu")
		(net "M_H_CPU0_SB_DQS_DP<4>")
	)
	(arc
		(start 375.83999 -241.805968)
		(mid 375.557317 -241.729997)
		(end 375.274586 -241.805714)
		(width 0.088646)
		(layer "In11.Cu")
		(net "M_H_CPU0_SB_DQS_DP<4>")
	)
	(arc
		(start 379.59919 -241.805968)
		(mid 379.316517 -241.729997)
		(end 379.033786 -241.805714)
		(width 0.088646)
		(layer "In11.Cu")
		(net "M_H_CPU0_SB_DQS_DP<4>")
	)
	(arc
		(start 377.154186 -241.805714)
		(mid 376.966734 -241.85595)
		(end 376.779282 -241.805714)
		(width 0.088646)
		(layer "In11.Cu")
		(net "M_H_CPU0_SB_DQS_DP<4>")
	)
	(arc
		(start 384.672332 -241.80546)
		(mid 384.485134 -241.855603)
		(end 384.297936 -241.80546)
		(width 0.088646)
		(layer "In11.Cu")
		(net "M_H_CPU0_SB_DQS_DP<4>")
	)
	(arc
		(start 377.71959 -241.805968)
		(mid 377.436917 -241.729997)
		(end 377.154186 -241.805714)
		(width 0.088646)
		(layer "In11.Cu")
		(net "M_H_CPU0_SB_DQS_DP<4>")
	)
	(arc
		(start 383.347722 -241.799364)
		(mid 383.06929 -241.729518)
		(end 382.792478 -241.80546)
		(width 0.088646)
		(layer "In11.Cu")
		(net "M_H_CPU0_SB_DQS_DP<4>")
	)
	(arc
		(start 378.093986 -241.805714)
		(mid 377.913699 -241.856126)
		(end 377.731528 -241.81308)
		(width 0.088646)
		(layer "In11.Cu")
		(net "M_H_CPU0_SB_DQS_DP<4>")
	)
	(arc
		(start 381.478282 -241.805714)
		(mid 381.195834 -241.730031)
		(end 380.913386 -241.805714)
		(width 0.088646)
		(layer "In11.Cu")
		(net "M_H_CPU0_SB_DQS_DP<4>")
	)
	(arc
		(start 379.033786 -241.805714)
		(mid 378.853499 -241.856126)
		(end 378.671328 -241.81308)
		(width 0.088646)
		(layer "In11.Cu")
		(net "M_H_CPU0_SB_DQS_DP<4>")
	)
	(arc
		(start 385.237736 -241.80546)
		(mid 384.955034 -241.729684)
		(end 384.672332 -241.80546)
		(width 0.088646)
		(layer "In11.Cu")
		(net "M_H_CPU0_SB_DQS_DP<4>")
	)
	(arc
		(start 376.214386 -241.805714)
		(mid 376.034099 -241.856126)
		(end 375.851928 -241.81308)
		(width 0.088646)
		(layer "In11.Cu")
		(net "M_H_CPU0_SB_DQS_DP<4>")
	)
	(arc
		(start 380.913386 -241.805714)
		(mid 380.733099 -241.856126)
		(end 380.550928 -241.81308)
		(width 0.088646)
		(layer "In11.Cu")
		(net "M_H_CPU0_SB_DQS_DP<4>")
	)
	(arc
		(start 375.274078 -241.80546)
		(mid 375.08688 -241.855637)
		(end 374.899682 -241.80546)
		(width 0.088646)
		(layer "In11.Cu")
		(net "M_H_CPU0_SB_DQS_DP<4>")
	)
	(arc
		(start 385.3688 -241.851942)
		(mid 385.301095 -241.834828)
		(end 385.237736 -241.80546)
		(width 0.088646)
		(layer "In11.Cu")
		(net "M_H_CPU0_SB_DQS_DP<4>")
	)
	(arc
		(start 385.425188 -241.85626)
		(mid 385.396912 -241.855173)
		(end 385.3688 -241.851942)
		(width 0.088646)
		(layer "In11.Cu")
		(net "M_H_CPU0_SB_DQS_DP<4>")
	)
	(arc
		(start 379.973586 -241.805714)
		(mid 379.793299 -241.856126)
		(end 379.611128 -241.81308)
		(width 0.088646)
		(layer "In11.Cu")
		(net "M_H_CPU0_SB_DQS_DP<4>")
	)
	(arc
		(start 384.297936 -241.80546)
		(mid 384.015234 -241.729684)
		(end 383.732532 -241.80546)
		(width 0.088646)
		(layer "In11.Cu")
		(net "M_H_CPU0_SB_DQS_DP<4>")
	)
	(arc
		(start 383.732532 -241.80546)
		(mid 383.545334 -241.855603)
		(end 383.358136 -241.80546)
		(width 0.088646)
		(layer "In11.Cu")
		(net "M_H_CPU0_SB_DQS_DP<4>")
	)
	(arc
		(start 373.490236 -241.97056)
		(mid 373.120779 -242.148618)
		(end 372.737634 -242.294918)
		(width 0.088646)
		(layer "In11.Cu")
		(net "M_H_CPU0_SB_DQS_DP<4>")
	)
	(arc
		(start 376.779282 -241.805714)
		(mid 376.496834 -241.730031)
		(end 376.214386 -241.805714)
		(width 0.088646)
		(layer "In11.Cu")
		(net "M_H_CPU0_SB_DQS_DP<4>")
	)
	(arc
		(start 373.738902 -241.875056)
		(mid 373.726487 -241.875994)
		(end 373.714264 -241.878358)
		(width 0.088646)
		(layer "In11.Cu")
		(net "M_H_CPU0_SB_DQS_DP<4>")
	)
	(arc
		(start 382.792478 -241.80546)
		(mid 382.60528 -241.855603)
		(end 382.418082 -241.80546)
		(width 0.088646)
		(layer "In11.Cu")
		(net "M_H_CPU0_SB_DQS_DP<4>")
	)
	(arc
		(start 380.53899 -241.805968)
		(mid 380.256317 -241.729997)
		(end 379.973586 -241.805714)
		(width 0.088646)
		(layer "In11.Cu")
		(net "M_H_CPU0_SB_DQS_DP<4>")
	)
	(arc
		(start 382.407668 -241.799364)
		(mid 382.12949 -241.729641)
		(end 381.852932 -241.80546)
		(width 0.088646)
		(layer "In11.Cu")
		(net "M_H_CPU0_SB_DQS_DP<4>")
	)
	(arc
		(start 374.88495 -241.796824)
		(mid 374.608475 -241.729504)
		(end 374.334278 -241.80546)
		(width 0.088646)
		(layer "In11.Cu")
		(net "M_H_CPU0_SB_DQS_DP<4>")
	)
	(arc
		(start 378.65939 -241.805968)
		(mid 378.376717 -241.729997)
		(end 378.093986 -241.805714)
		(width 0.088646)
		(layer "In11.Cu")
		(net "M_H_CPU0_SB_DQS_DP<4>")
	)
	(segment
		(start 450.911214 -200.716642)
		(end 452.016114 -200.716642)
		(width 0.20066)
		(layer "F.Cu")
		(net "M_H_CPU0_SB_DQS_DP<3>")
	)
	(segment
		(start 457.120498 -201.141838)
		(end 454.963276 -201.141838)
		(width 0.1016)
		(layer "F.Cu")
		(net "M_H_CPU0_SB_DQS_DP<3>")
	)
	(segment
		(start 459.559914 -200.716642)
		(end 459.011274 -200.716642)
		(width 0.20066)
		(layer "F.Cu")
		(net "M_H_CPU0_SB_DQS_DP<3>")
	)
	(segment
		(start 454.797922 -201.141838)
		(end 454.546716 -200.890632)
		(width 0.20066)
		(layer "F.Cu")
		(net "M_H_CPU0_SB_DQS_DP<3>")
	)
	(segment
		(start 452.605394 -200.716642)
		(end 452.016114 -200.716642)
		(width 0.20066)
		(layer "F.Cu")
		(net "M_H_CPU0_SB_DQS_DP<3>")
	)
	(segment
		(start 458.123036 -200.84542)
		(end 457.75245 -200.84542)
		(width 0.20066)
		(layer "F.Cu")
		(net "M_H_CPU0_SB_DQS_DP<3>")
	)
	(segment
		(start 371.79758 -228.1809)
		(end 371.797834 -228.180646)
		(width 0.20066)
		(layer "F.Cu")
		(net "M_H_CPU0_SB_DQS_DP<3>")
	)
	(segment
		(start 457.126594 -201.147934)
		(end 457.120498 -201.141838)
		(width 0.1016)
		(layer "F.Cu")
		(net "M_H_CPU0_SB_DQS_DP<3>")
	)
	(segment
		(start 452.845932 -200.476104)
		(end 452.605394 -200.716642)
		(width 0.20066)
		(layer "F.Cu")
		(net "M_H_CPU0_SB_DQS_DP<3>")
	)
	(segment
		(start 454.963276 -201.141838)
		(end 454.937368 -201.141838)
		(width 0.101854)
		(layer "F.Cu")
		(net "M_H_CPU0_SB_DQS_DP<3>")
	)
	(segment
		(start 457.449936 -201.147934)
		(end 457.126594 -201.147934)
		(width 0.20066)
		(layer "F.Cu")
		(net "M_H_CPU0_SB_DQS_DP<3>")
	)
	(segment
		(start 371.797834 -228.180646)
		(end 371.797834 -227.64496)
		(width 0.20066)
		(layer "F.Cu")
		(net "M_H_CPU0_SB_DQS_DP<3>")
	)
	(segment
		(start 454.546716 -200.890632)
		(end 453.860916 -200.890632)
		(width 0.20066)
		(layer "F.Cu")
		(net "M_H_CPU0_SB_DQS_DP<3>")
	)
	(segment
		(start 458.5335 -200.434956)
		(end 458.123036 -200.84542)
		(width 0.20066)
		(layer "F.Cu")
		(net "M_H_CPU0_SB_DQS_DP<3>")
	)
	(segment
		(start 453.446388 -200.476104)
		(end 452.845932 -200.476104)
		(width 0.20066)
		(layer "F.Cu")
		(net "M_H_CPU0_SB_DQS_DP<3>")
	)
	(segment
		(start 459.011274 -200.716642)
		(end 458.729588 -200.434956)
		(width 0.20066)
		(layer "F.Cu")
		(net "M_H_CPU0_SB_DQS_DP<3>")
	)
	(segment
		(start 458.729588 -200.434956)
		(end 458.5335 -200.434956)
		(width 0.20066)
		(layer "F.Cu")
		(net "M_H_CPU0_SB_DQS_DP<3>")
	)
	(segment
		(start 453.860916 -200.890632)
		(end 453.446388 -200.476104)
		(width 0.20066)
		(layer "F.Cu")
		(net "M_H_CPU0_SB_DQS_DP<3>")
	)
	(segment
		(start 457.75245 -200.84542)
		(end 457.449936 -201.147934)
		(width 0.20066)
		(layer "F.Cu")
		(net "M_H_CPU0_SB_DQS_DP<3>")
	)
	(segment
		(start 454.937368 -201.141838)
		(end 454.797922 -201.141838)
		(width 0.20066)
		(layer "F.Cu")
		(net "M_H_CPU0_SB_DQS_DP<3>")
	)
	(segment
		(start 395.127226 -215.656922)
		(end 388.826502 -221.957646)
		(width 0.18288)
		(layer "In11.Cu")
		(net "M_H_CPU0_SB_DQS_DP<3>")
	)
	(segment
		(start 410.332174 -200.28281)
		(end 409.457398 -200.28281)
		(width 0.18288)
		(layer "In11.Cu")
		(net "M_H_CPU0_SB_DQS_DP<3>")
	)
	(segment
		(start 371.610636 -227.320602)
		(end 371.601746 -227.325682)
		(width 0.088646)
		(layer "In11.Cu")
		(net "M_H_CPU0_SB_DQS_DP<3>")
	)
	(segment
		(start 424.54195 -198.59117)
		(end 424.270932 -198.320152)
		(width 0.18288)
		(layer "In11.Cu")
		(net "M_H_CPU0_SB_DQS_DP<3>")
	)
	(segment
		(start 417.031678 -200.28281)
		(end 411.129734 -200.28281)
		(width 0.18288)
		(layer "In11.Cu")
		(net "M_H_CPU0_SB_DQS_DP<3>")
	)
	(segment
		(start 380.457964 -227.329238)
		(end 380.443232 -227.320602)
		(width 0.088646)
		(layer "In11.Cu")
		(net "M_H_CPU0_SB_DQS_DP<3>")
	)
	(segment
		(start 430.84242 -199.781668)
		(end 429.636682 -199.781668)
		(width 0.18288)
		(layer "In11.Cu")
		(net "M_H_CPU0_SB_DQS_DP<3>")
	)
	(segment
		(start 379.518164 -227.329238)
		(end 379.503432 -227.320602)
		(width 0.088646)
		(layer "In11.Cu")
		(net "M_H_CPU0_SB_DQS_DP<3>")
	)
	(segment
		(start 438.091326 -198.339964)
		(end 437.254904 -199.176386)
		(width 0.18288)
		(layer "In11.Cu")
		(net "M_H_CPU0_SB_DQS_DP<3>")
	)
	(segment
		(start 388.826502 -221.957646)
		(end 388.741666 -221.957646)
		(width 0.088646)
		(layer "In11.Cu")
		(net "M_H_CPU0_SB_DQS_DP<3>")
	)
	(segment
		(start 377.638564 -227.329238)
		(end 377.623832 -227.320602)
		(width 0.088646)
		(layer "In11.Cu")
		(net "M_H_CPU0_SB_DQS_DP<3>")
	)
	(segment
		(start 440.151774 -198.59117)
		(end 439.62955 -198.59117)
		(width 0.18288)
		(layer "In11.Cu")
		(net "M_H_CPU0_SB_DQS_DP<3>")
	)
	(segment
		(start 429.636682 -199.781668)
		(end 429.512222 -199.906128)
		(width 0.18288)
		(layer "In11.Cu")
		(net "M_H_CPU0_SB_DQS_DP<3>")
	)
	(segment
		(start 375.369582 -227.320602)
		(end 375.359168 -227.326698)
		(width 0.088646)
		(layer "In11.Cu")
		(net "M_H_CPU0_SB_DQS_DP<3>")
	)
	(segment
		(start 420.166038 -199.16521)
		(end 419.495478 -199.16521)
		(width 0.18288)
		(layer "In11.Cu")
		(net "M_H_CPU0_SB_DQS_DP<3>")
	)
	(segment
		(start 376.309382 -227.320602)
		(end 376.29465 -227.329238)
		(width 0.088646)
		(layer "In11.Cu")
		(net "M_H_CPU0_SB_DQS_DP<3>")
	)
	(segment
		(start 435.529736 -199.441308)
		(end 435.277006 -199.188578)
		(width 0.18288)
		(layer "In11.Cu")
		(net "M_H_CPU0_SB_DQS_DP<3>")
	)
	(segment
		(start 384.297936 -226.506786)
		(end 384.289046 -226.511866)
		(width 0.088646)
		(layer "In11.Cu")
		(net "M_H_CPU0_SB_DQS_DP<3>")
	)
	(segment
		(start 426.10786 -198.32828)
		(end 425.327064 -198.32828)
		(width 0.18288)
		(layer "In11.Cu")
		(net "M_H_CPU0_SB_DQS_DP<3>")
	)
	(segment
		(start 432.918362 -200.498456)
		(end 432.540918 -200.121012)
		(width 0.18288)
		(layer "In11.Cu")
		(net "M_H_CPU0_SB_DQS_DP<3>")
	)
	(segment
		(start 431.43551 -199.188578)
		(end 430.84242 -199.781668)
		(width 0.18288)
		(layer "In11.Cu")
		(net "M_H_CPU0_SB_DQS_DP<3>")
	)
	(segment
		(start 433.496974 -200.498456)
		(end 432.918362 -200.498456)
		(width 0.18288)
		(layer "In11.Cu")
		(net "M_H_CPU0_SB_DQS_DP<3>")
	)
	(segment
		(start 376.694192 -227.326698)
		(end 376.683778 -227.320602)
		(width 0.088646)
		(layer "In11.Cu")
		(net "M_H_CPU0_SB_DQS_DP<3>")
	)
	(segment
		(start 426.88383 -199.280272)
		(end 426.495718 -198.89216)
		(width 0.18288)
		(layer "In11.Cu")
		(net "M_H_CPU0_SB_DQS_DP<3>")
	)
	(segment
		(start 388.594854 -223.389952)
		(end 387.438138 -224.546668)
		(width 0.088646)
		(layer "In11.Cu")
		(net "M_H_CPU0_SB_DQS_DP<3>")
	)
	(segment
		(start 388.594854 -222.104458)
		(end 388.594854 -223.389952)
		(width 0.088646)
		(layer "In11.Cu")
		(net "M_H_CPU0_SB_DQS_DP<3>")
	)
	(segment
		(start 433.874418 -199.384666)
		(end 433.874418 -200.121012)
		(width 0.18288)
		(layer "In11.Cu")
		(net "M_H_CPU0_SB_DQS_DP<3>")
	)
	(segment
		(start 388.741666 -221.957646)
		(end 388.594854 -222.104458)
		(width 0.088646)
		(layer "In11.Cu")
		(net "M_H_CPU0_SB_DQS_DP<3>")
	)
	(segment
		(start 386.459984 -226.017328)
		(end 386.459984 -226.027234)
		(width 0.088646)
		(layer "In11.Cu")
		(net "M_H_CPU0_SB_DQS_DP<3>")
	)
	(segment
		(start 450.635878 -200.441306)
		(end 450.145404 -200.441306)
		(width 0.18288)
		(layer "In11.Cu")
		(net "M_H_CPU0_SB_DQS_DP<3>")
	)
	(segment
		(start 386.647436 -225.69297)
		(end 386.638546 -225.69805)
		(width 0.088646)
		(layer "In11.Cu")
		(net "M_H_CPU0_SB_DQS_DP<3>")
	)
	(segment
		(start 371.48516 -227.64496)
		(end 371.797834 -227.64496)
		(width 0.088646)
		(layer "In11.Cu")
		(net "M_H_CPU0_SB_DQS_DP<3>")
	)
	(segment
		(start 382.337564 -227.329238)
		(end 382.322832 -227.320602)
		(width 0.088646)
		(layer "In11.Cu")
		(net "M_H_CPU0_SB_DQS_DP<3>")
	)
	(segment
		(start 420.442136 -199.441308)
		(end 420.166038 -199.16521)
		(width 0.18288)
		(layer "In11.Cu")
		(net "M_H_CPU0_SB_DQS_DP<3>")
	)
	(segment
		(start 403.354794 -204.565504)
		(end 395.127226 -212.793072)
		(width 0.18288)
		(layer "In11.Cu")
		(net "M_H_CPU0_SB_DQS_DP<3>")
	)
	(segment
		(start 450.911214 -200.716642)
		(end 450.635878 -200.441306)
		(width 0.18288)
		(layer "In11.Cu")
		(net "M_H_CPU0_SB_DQS_DP<3>")
	)
	(segment
		(start 449.781168 -200.07707)
		(end 442.741812 -200.07707)
		(width 0.18288)
		(layer "In11.Cu")
		(net "M_H_CPU0_SB_DQS_DP<3>")
	)
	(segment
		(start 425.327064 -198.32828)
		(end 425.064174 -198.59117)
		(width 0.18288)
		(layer "In11.Cu")
		(net "M_H_CPU0_SB_DQS_DP<3>")
	)
	(segment
		(start 422.466516 -198.320152)
		(end 421.610282 -199.176386)
		(width 0.18288)
		(layer "In11.Cu")
		(net "M_H_CPU0_SB_DQS_DP<3>")
	)
	(segment
		(start 421.228774 -199.176386)
		(end 420.963852 -199.441308)
		(width 0.18288)
		(layer "In11.Cu")
		(net "M_H_CPU0_SB_DQS_DP<3>")
	)
	(segment
		(start 428.839122 -199.781668)
		(end 427.561248 -199.781668)
		(width 0.18288)
		(layer "In11.Cu")
		(net "M_H_CPU0_SB_DQS_DP<3>")
	)
	(segment
		(start 408.650948 -201.08926)
		(end 405.196548 -201.08926)
		(width 0.18288)
		(layer "In11.Cu")
		(net "M_H_CPU0_SB_DQS_DP<3>")
	)
	(segment
		(start 436.051452 -199.441308)
		(end 435.529736 -199.441308)
		(width 0.18288)
		(layer "In11.Cu")
		(net "M_H_CPU0_SB_DQS_DP<3>")
	)
	(segment
		(start 433.874418 -200.121012)
		(end 433.496974 -200.498456)
		(width 0.18288)
		(layer "In11.Cu")
		(net "M_H_CPU0_SB_DQS_DP<3>")
	)
	(segment
		(start 427.561248 -199.781668)
		(end 427.059852 -199.280272)
		(width 0.18288)
		(layer "In11.Cu")
		(net "M_H_CPU0_SB_DQS_DP<3>")
	)
	(segment
		(start 432.540918 -199.384666)
		(end 432.34483 -199.188578)
		(width 0.18288)
		(layer "In11.Cu")
		(net "M_H_CPU0_SB_DQS_DP<3>")
	)
	(segment
		(start 439.378344 -198.339964)
		(end 438.091326 -198.339964)
		(width 0.18288)
		(layer "In11.Cu")
		(net "M_H_CPU0_SB_DQS_DP<3>")
	)
	(segment
		(start 439.62955 -198.59117)
		(end 439.378344 -198.339964)
		(width 0.18288)
		(layer "In11.Cu")
		(net "M_H_CPU0_SB_DQS_DP<3>")
	)
	(segment
		(start 437.254904 -199.176386)
		(end 436.316374 -199.176386)
		(width 0.18288)
		(layer "In11.Cu")
		(net "M_H_CPU0_SB_DQS_DP<3>")
	)
	(segment
		(start 395.127226 -212.793072)
		(end 395.127226 -215.656922)
		(width 0.18288)
		(layer "In11.Cu")
		(net "M_H_CPU0_SB_DQS_DP<3>")
	)
	(segment
		(start 419.495478 -199.16521)
		(end 419.371018 -199.28967)
		(width 0.18288)
		(layer "In11.Cu")
		(net "M_H_CPU0_SB_DQS_DP<3>")
	)
	(segment
		(start 418.149278 -199.16521)
		(end 417.031678 -200.28281)
		(width 0.18288)
		(layer "In11.Cu")
		(net "M_H_CPU0_SB_DQS_DP<3>")
	)
	(segment
		(start 372.939564 -227.329238)
		(end 372.924832 -227.320602)
		(width 0.088646)
		(layer "In11.Cu")
		(net "M_H_CPU0_SB_DQS_DP<3>")
	)
	(segment
		(start 387.438138 -224.546668)
		(end 387.438138 -224.929446)
		(width 0.088646)
		(layer "In11.Cu")
		(net "M_H_CPU0_SB_DQS_DP<3>")
	)
	(segment
		(start 420.963852 -199.441308)
		(end 420.442136 -199.441308)
		(width 0.18288)
		(layer "In11.Cu")
		(net "M_H_CPU0_SB_DQS_DP<3>")
	)
	(segment
		(start 426.495718 -198.716138)
		(end 426.10786 -198.32828)
		(width 0.18288)
		(layer "In11.Cu")
		(net "M_H_CPU0_SB_DQS_DP<3>")
	)
	(segment
		(start 409.457398 -200.28281)
		(end 408.650948 -201.08926)
		(width 0.18288)
		(layer "In11.Cu")
		(net "M_H_CPU0_SB_DQS_DP<3>")
	)
	(segment
		(start 403.354794 -202.931014)
		(end 403.354794 -204.565504)
		(width 0.18288)
		(layer "In11.Cu")
		(net "M_H_CPU0_SB_DQS_DP<3>")
	)
	(segment
		(start 387.438138 -224.929446)
		(end 386.764276 -225.603308)
		(width 0.088646)
		(layer "In11.Cu")
		(net "M_H_CPU0_SB_DQS_DP<3>")
	)
	(segment
		(start 440.416442 -198.326502)
		(end 440.151774 -198.59117)
		(width 0.18288)
		(layer "In11.Cu")
		(net "M_H_CPU0_SB_DQS_DP<3>")
	)
	(segment
		(start 419.371018 -199.28967)
		(end 418.822378 -199.28967)
		(width 0.18288)
		(layer "In11.Cu")
		(net "M_H_CPU0_SB_DQS_DP<3>")
	)
	(segment
		(start 421.610282 -199.176386)
		(end 421.228774 -199.176386)
		(width 0.18288)
		(layer "In11.Cu")
		(net "M_H_CPU0_SB_DQS_DP<3>")
	)
	(segment
		(start 435.277006 -199.188578)
		(end 434.070506 -199.188578)
		(width 0.18288)
		(layer "In11.Cu")
		(net "M_H_CPU0_SB_DQS_DP<3>")
	)
	(segment
		(start 428.963582 -199.906128)
		(end 428.839122 -199.781668)
		(width 0.18288)
		(layer "In11.Cu")
		(net "M_H_CPU0_SB_DQS_DP<3>")
	)
	(segment
		(start 424.270932 -198.320152)
		(end 422.466516 -198.320152)
		(width 0.18288)
		(layer "In11.Cu")
		(net "M_H_CPU0_SB_DQS_DP<3>")
	)
	(segment
		(start 373.879364 -227.329238)
		(end 373.864632 -227.320602)
		(width 0.088646)
		(layer "In11.Cu")
		(net "M_H_CPU0_SB_DQS_DP<3>")
	)
	(segment
		(start 425.064174 -198.59117)
		(end 424.54195 -198.59117)
		(width 0.18288)
		(layer "In11.Cu")
		(net "M_H_CPU0_SB_DQS_DP<3>")
	)
	(segment
		(start 426.495718 -198.89216)
		(end 426.495718 -198.716138)
		(width 0.18288)
		(layer "In11.Cu")
		(net "M_H_CPU0_SB_DQS_DP<3>")
	)
	(segment
		(start 411.129734 -200.28281)
		(end 411.005274 -200.40727)
		(width 0.18288)
		(layer "In11.Cu")
		(net "M_H_CPU0_SB_DQS_DP<3>")
	)
	(segment
		(start 440.991244 -198.326502)
		(end 440.416442 -198.326502)
		(width 0.18288)
		(layer "In11.Cu")
		(net "M_H_CPU0_SB_DQS_DP<3>")
	)
	(segment
		(start 436.316374 -199.176386)
		(end 436.051452 -199.441308)
		(width 0.18288)
		(layer "In11.Cu")
		(net "M_H_CPU0_SB_DQS_DP<3>")
	)
	(segment
		(start 434.070506 -199.188578)
		(end 433.874418 -199.384666)
		(width 0.18288)
		(layer "In11.Cu")
		(net "M_H_CPU0_SB_DQS_DP<3>")
	)
	(segment
		(start 405.196548 -201.08926)
		(end 403.354794 -202.931014)
		(width 0.18288)
		(layer "In11.Cu")
		(net "M_H_CPU0_SB_DQS_DP<3>")
	)
	(segment
		(start 410.456634 -200.40727)
		(end 410.332174 -200.28281)
		(width 0.18288)
		(layer "In11.Cu")
		(net "M_H_CPU0_SB_DQS_DP<3>")
	)
	(segment
		(start 411.005274 -200.40727)
		(end 410.456634 -200.40727)
		(width 0.18288)
		(layer "In11.Cu")
		(net "M_H_CPU0_SB_DQS_DP<3>")
	)
	(segment
		(start 432.34483 -199.188578)
		(end 431.43551 -199.188578)
		(width 0.18288)
		(layer "In11.Cu")
		(net "M_H_CPU0_SB_DQS_DP<3>")
	)
	(segment
		(start 371.427756 -227.587556)
		(end 371.48516 -227.64496)
		(width 0.088646)
		(layer "In11.Cu")
		(net "M_H_CPU0_SB_DQS_DP<3>")
	)
	(segment
		(start 418.822378 -199.28967)
		(end 418.697918 -199.16521)
		(width 0.18288)
		(layer "In11.Cu")
		(net "M_H_CPU0_SB_DQS_DP<3>")
	)
	(segment
		(start 450.145404 -200.441306)
		(end 449.781168 -200.07707)
		(width 0.18288)
		(layer "In11.Cu")
		(net "M_H_CPU0_SB_DQS_DP<3>")
	)
	(segment
		(start 418.697918 -199.16521)
		(end 418.149278 -199.16521)
		(width 0.18288)
		(layer "In11.Cu")
		(net "M_H_CPU0_SB_DQS_DP<3>")
	)
	(segment
		(start 442.741812 -200.07707)
		(end 440.991244 -198.326502)
		(width 0.18288)
		(layer "In11.Cu")
		(net "M_H_CPU0_SB_DQS_DP<3>")
	)
	(segment
		(start 429.512222 -199.906128)
		(end 428.963582 -199.906128)
		(width 0.18288)
		(layer "In11.Cu")
		(net "M_H_CPU0_SB_DQS_DP<3>")
	)
	(segment
		(start 432.540918 -200.121012)
		(end 432.540918 -199.384666)
		(width 0.18288)
		(layer "In11.Cu")
		(net "M_H_CPU0_SB_DQS_DP<3>")
	)
	(segment
		(start 427.059852 -199.280272)
		(end 426.88383 -199.280272)
		(width 0.18288)
		(layer "In11.Cu")
		(net "M_H_CPU0_SB_DQS_DP<3>")
	)
	(segment
		(start 384.110484 -226.831144)
		(end 384.110484 -226.84105)
		(width 0.088646)
		(layer "In11.Cu")
		(net "M_H_CPU0_SB_DQS_DP<3>")
	)
	(arc
		(start 376.683778 -227.320602)
		(mid 376.49658 -227.270459)
		(end 376.309382 -227.320602)
		(width 0.088646)
		(layer "In11.Cu")
		(net "M_H_CPU0_SB_DQS_DP<3>")
	)
	(arc
		(start 375.743978 -227.320602)
		(mid 375.55678 -227.270459)
		(end 375.369582 -227.320602)
		(width 0.088646)
		(layer "In11.Cu")
		(net "M_H_CPU0_SB_DQS_DP<3>")
	)
	(arc
		(start 371.985032 -227.320602)
		(mid 371.797834 -227.270459)
		(end 371.610636 -227.320602)
		(width 0.088646)
		(layer "In11.Cu")
		(net "M_H_CPU0_SB_DQS_DP<3>")
	)
	(arc
		(start 376.29465 -227.329238)
		(mid 376.018175 -227.396558)
		(end 375.743978 -227.320602)
		(width 0.088646)
		(layer "In11.Cu")
		(net "M_H_CPU0_SB_DQS_DP<3>")
	)
	(arc
		(start 386.638546 -225.69805)
		(mid 386.507632 -225.83441)
		(end 386.459984 -226.017328)
		(width 0.088646)
		(layer "In11.Cu")
		(net "M_H_CPU0_SB_DQS_DP<3>")
	)
	(arc
		(start 378.189236 -227.320602)
		(mid 377.915037 -227.396437)
		(end 377.638564 -227.329238)
		(width 0.088646)
		(layer "In11.Cu")
		(net "M_H_CPU0_SB_DQS_DP<3>")
	)
	(arc
		(start 374.430036 -227.320602)
		(mid 374.155837 -227.396437)
		(end 373.879364 -227.329238)
		(width 0.088646)
		(layer "In11.Cu")
		(net "M_H_CPU0_SB_DQS_DP<3>")
	)
	(arc
		(start 386.177536 -226.506786)
		(mid 385.894834 -226.582562)
		(end 385.612132 -226.506786)
		(width 0.088646)
		(layer "In11.Cu")
		(net "M_H_CPU0_SB_DQS_DP<3>")
	)
	(arc
		(start 373.490236 -227.320602)
		(mid 373.216037 -227.396437)
		(end 372.939564 -227.329238)
		(width 0.088646)
		(layer "In11.Cu")
		(net "M_H_CPU0_SB_DQS_DP<3>")
	)
	(arc
		(start 383.262632 -227.320602)
		(mid 383.075434 -227.270459)
		(end 382.888236 -227.320602)
		(width 0.088646)
		(layer "In11.Cu")
		(net "M_H_CPU0_SB_DQS_DP<3>")
	)
	(arc
		(start 374.804432 -227.320602)
		(mid 374.617234 -227.270459)
		(end 374.430036 -227.320602)
		(width 0.088646)
		(layer "In11.Cu")
		(net "M_H_CPU0_SB_DQS_DP<3>")
	)
	(arc
		(start 385.612132 -226.506786)
		(mid 385.424934 -226.456643)
		(end 385.237736 -226.506786)
		(width 0.088646)
		(layer "In11.Cu")
		(net "M_H_CPU0_SB_DQS_DP<3>")
	)
	(arc
		(start 386.764276 -225.603308)
		(mid 386.708786 -225.651957)
		(end 386.647436 -225.69297)
		(width 0.088646)
		(layer "In11.Cu")
		(net "M_H_CPU0_SB_DQS_DP<3>")
	)
	(arc
		(start 382.322832 -227.320602)
		(mid 382.135634 -227.270459)
		(end 381.948436 -227.320602)
		(width 0.088646)
		(layer "In11.Cu")
		(net "M_H_CPU0_SB_DQS_DP<3>")
	)
	(arc
		(start 379.503432 -227.320602)
		(mid 379.316234 -227.270459)
		(end 379.129036 -227.320602)
		(width 0.088646)
		(layer "In11.Cu")
		(net "M_H_CPU0_SB_DQS_DP<3>")
	)
	(arc
		(start 386.459984 -226.027234)
		(mid 386.381873 -226.304183)
		(end 386.177536 -226.506786)
		(width 0.088646)
		(layer "In11.Cu")
		(net "M_H_CPU0_SB_DQS_DP<3>")
	)
	(arc
		(start 380.443232 -227.320602)
		(mid 380.256034 -227.270459)
		(end 380.068836 -227.320602)
		(width 0.088646)
		(layer "In11.Cu")
		(net "M_H_CPU0_SB_DQS_DP<3>")
	)
	(arc
		(start 384.672332 -226.506786)
		(mid 384.485134 -226.456643)
		(end 384.297936 -226.506786)
		(width 0.088646)
		(layer "In11.Cu")
		(net "M_H_CPU0_SB_DQS_DP<3>")
	)
	(arc
		(start 385.237736 -226.506786)
		(mid 384.955034 -226.582562)
		(end 384.672332 -226.506786)
		(width 0.088646)
		(layer "In11.Cu")
		(net "M_H_CPU0_SB_DQS_DP<3>")
	)
	(arc
		(start 377.249436 -227.320602)
		(mid 376.972623 -227.396472)
		(end 376.694192 -227.326698)
		(width 0.088646)
		(layer "In11.Cu")
		(net "M_H_CPU0_SB_DQS_DP<3>")
	)
	(arc
		(start 375.359168 -227.326698)
		(mid 375.08099 -227.396421)
		(end 374.804432 -227.320602)
		(width 0.088646)
		(layer "In11.Cu")
		(net "M_H_CPU0_SB_DQS_DP<3>")
	)
	(arc
		(start 383.828036 -227.320602)
		(mid 383.545334 -227.396378)
		(end 383.262632 -227.320602)
		(width 0.088646)
		(layer "In11.Cu")
		(net "M_H_CPU0_SB_DQS_DP<3>")
	)
	(arc
		(start 378.563632 -227.320602)
		(mid 378.376434 -227.270459)
		(end 378.189236 -227.320602)
		(width 0.088646)
		(layer "In11.Cu")
		(net "M_H_CPU0_SB_DQS_DP<3>")
	)
	(arc
		(start 372.924832 -227.320602)
		(mid 372.737634 -227.270459)
		(end 372.550436 -227.320602)
		(width 0.088646)
		(layer "In11.Cu")
		(net "M_H_CPU0_SB_DQS_DP<3>")
	)
	(arc
		(start 381.948436 -227.320602)
		(mid 381.665734 -227.396378)
		(end 381.383032 -227.320602)
		(width 0.088646)
		(layer "In11.Cu")
		(net "M_H_CPU0_SB_DQS_DP<3>")
	)
	(arc
		(start 380.068836 -227.320602)
		(mid 379.794637 -227.396437)
		(end 379.518164 -227.329238)
		(width 0.088646)
		(layer "In11.Cu")
		(net "M_H_CPU0_SB_DQS_DP<3>")
	)
	(arc
		(start 371.601746 -227.325682)
		(mid 371.486007 -227.437506)
		(end 371.427756 -227.587556)
		(width 0.088646)
		(layer "In11.Cu")
		(net "M_H_CPU0_SB_DQS_DP<3>")
	)
	(arc
		(start 382.888236 -227.320602)
		(mid 382.614037 -227.396437)
		(end 382.337564 -227.329238)
		(width 0.088646)
		(layer "In11.Cu")
		(net "M_H_CPU0_SB_DQS_DP<3>")
	)
	(arc
		(start 373.864632 -227.320602)
		(mid 373.677434 -227.270459)
		(end 373.490236 -227.320602)
		(width 0.088646)
		(layer "In11.Cu")
		(net "M_H_CPU0_SB_DQS_DP<3>")
	)
	(arc
		(start 384.289046 -226.511866)
		(mid 384.158132 -226.648226)
		(end 384.110484 -226.831144)
		(width 0.088646)
		(layer "In11.Cu")
		(net "M_H_CPU0_SB_DQS_DP<3>")
	)
	(arc
		(start 381.383032 -227.320602)
		(mid 381.195834 -227.270459)
		(end 381.008636 -227.320602)
		(width 0.088646)
		(layer "In11.Cu")
		(net "M_H_CPU0_SB_DQS_DP<3>")
	)
	(arc
		(start 372.550436 -227.320602)
		(mid 372.267734 -227.396378)
		(end 371.985032 -227.320602)
		(width 0.088646)
		(layer "In11.Cu")
		(net "M_H_CPU0_SB_DQS_DP<3>")
	)
	(arc
		(start 381.008636 -227.320602)
		(mid 380.734437 -227.396437)
		(end 380.457964 -227.329238)
		(width 0.088646)
		(layer "In11.Cu")
		(net "M_H_CPU0_SB_DQS_DP<3>")
	)
	(arc
		(start 377.623832 -227.320602)
		(mid 377.436634 -227.270459)
		(end 377.249436 -227.320602)
		(width 0.088646)
		(layer "In11.Cu")
		(net "M_H_CPU0_SB_DQS_DP<3>")
	)
	(arc
		(start 379.129036 -227.320602)
		(mid 378.846334 -227.396378)
		(end 378.563632 -227.320602)
		(width 0.088646)
		(layer "In11.Cu")
		(net "M_H_CPU0_SB_DQS_DP<3>")
	)
	(arc
		(start 384.110484 -226.84105)
		(mid 384.032373 -227.117999)
		(end 383.828036 -227.320602)
		(width 0.088646)
		(layer "In11.Cu")
		(net "M_H_CPU0_SB_DQS_DP<3>")
	)
	(segment
		(start 450.911214 -210.066636)
		(end 452.016114 -210.066636)
		(width 0.20066)
		(layer "F.Cu")
		(net "M_H_CPU0_SB_DQS_DP<2>")
	)
	(segment
		(start 452.845932 -209.826098)
		(end 453.446388 -209.826098)
		(width 0.20066)
		(layer "F.Cu")
		(net "M_H_CPU0_SB_DQS_DP<2>")
	)
	(segment
		(start 458.5335 -209.78495)
		(end 458.729588 -209.78495)
		(width 0.20066)
		(layer "F.Cu")
		(net "M_H_CPU0_SB_DQS_DP<2>")
	)
	(segment
		(start 374.14708 -230.622348)
		(end 374.14708 -230.086662)
		(width 0.20066)
		(layer "F.Cu")
		(net "M_H_CPU0_SB_DQS_DP<2>")
	)
	(segment
		(start 452.605394 -210.066636)
		(end 452.845932 -209.826098)
		(width 0.20066)
		(layer "F.Cu")
		(net "M_H_CPU0_SB_DQS_DP<2>")
	)
	(segment
		(start 374.147334 -230.622602)
		(end 374.14708 -230.622348)
		(width 0.20066)
		(layer "F.Cu")
		(net "M_H_CPU0_SB_DQS_DP<2>")
	)
	(segment
		(start 453.860916 -210.240626)
		(end 454.546716 -210.240626)
		(width 0.20066)
		(layer "F.Cu")
		(net "M_H_CPU0_SB_DQS_DP<2>")
	)
	(segment
		(start 458.123036 -210.195414)
		(end 458.5335 -209.78495)
		(width 0.20066)
		(layer "F.Cu")
		(net "M_H_CPU0_SB_DQS_DP<2>")
	)
	(segment
		(start 453.446388 -209.826098)
		(end 453.860916 -210.240626)
		(width 0.20066)
		(layer "F.Cu")
		(net "M_H_CPU0_SB_DQS_DP<2>")
	)
	(segment
		(start 454.963276 -210.491832)
		(end 457.120498 -210.491832)
		(width 0.1016)
		(layer "F.Cu")
		(net "M_H_CPU0_SB_DQS_DP<2>")
	)
	(segment
		(start 454.797922 -210.491832)
		(end 454.937368 -210.491832)
		(width 0.20066)
		(layer "F.Cu")
		(net "M_H_CPU0_SB_DQS_DP<2>")
	)
	(segment
		(start 452.016114 -210.066636)
		(end 452.605394 -210.066636)
		(width 0.20066)
		(layer "F.Cu")
		(net "M_H_CPU0_SB_DQS_DP<2>")
	)
	(segment
		(start 458.729588 -209.78495)
		(end 459.011274 -210.066636)
		(width 0.20066)
		(layer "F.Cu")
		(net "M_H_CPU0_SB_DQS_DP<2>")
	)
	(segment
		(start 457.126594 -210.497928)
		(end 457.449936 -210.497928)
		(width 0.20066)
		(layer "F.Cu")
		(net "M_H_CPU0_SB_DQS_DP<2>")
	)
	(segment
		(start 454.937368 -210.491832)
		(end 454.963276 -210.491832)
		(width 0.101854)
		(layer "F.Cu")
		(net "M_H_CPU0_SB_DQS_DP<2>")
	)
	(segment
		(start 457.120498 -210.491832)
		(end 457.126594 -210.497928)
		(width 0.1016)
		(layer "F.Cu")
		(net "M_H_CPU0_SB_DQS_DP<2>")
	)
	(segment
		(start 454.546716 -210.240626)
		(end 454.797922 -210.491832)
		(width 0.20066)
		(layer "F.Cu")
		(net "M_H_CPU0_SB_DQS_DP<2>")
	)
	(segment
		(start 457.75245 -210.195414)
		(end 458.123036 -210.195414)
		(width 0.20066)
		(layer "F.Cu")
		(net "M_H_CPU0_SB_DQS_DP<2>")
	)
	(segment
		(start 457.449936 -210.497928)
		(end 457.75245 -210.195414)
		(width 0.20066)
		(layer "F.Cu")
		(net "M_H_CPU0_SB_DQS_DP<2>")
	)
	(segment
		(start 459.011274 -210.066636)
		(end 459.559914 -210.066636)
		(width 0.20066)
		(layer "F.Cu")
		(net "M_H_CPU0_SB_DQS_DP<2>")
	)
	(segment
		(start 379.598936 -229.762304)
		(end 379.588522 -229.7684)
		(width 0.088646)
		(layer "In6.Cu")
		(net "M_H_CPU0_SB_DQS_DP<2>")
	)
	(segment
		(start 404.219156 -212.024976)
		(end 388.46125 -227.782882)
		(width 0.18288)
		(layer "In6.Cu")
		(net "M_H_CPU0_SB_DQS_DP<2>")
	)
	(segment
		(start 449.793614 -209.447892)
		(end 447.322448 -209.447892)
		(width 0.18288)
		(layer "In6.Cu")
		(net "M_H_CPU0_SB_DQS_DP<2>")
	)
	(segment
		(start 386.302758 -229.111302)
		(end 385.702556 -229.711504)
		(width 0.088646)
		(layer "In6.Cu")
		(net "M_H_CPU0_SB_DQS_DP<2>")
	)
	(segment
		(start 376.698764 -230.584756)
		(end 376.684032 -230.57612)
		(width 0.088646)
		(layer "In6.Cu")
		(net "M_H_CPU0_SB_DQS_DP<2>")
	)
	(segment
		(start 427.826678 -210.393788)
		(end 427.38802 -210.832446)
		(width 0.18288)
		(layer "In6.Cu")
		(net "M_H_CPU0_SB_DQS_DP<2>")
	)
	(segment
		(start 412.915354 -210.192112)
		(end 412.279084 -210.828382)
		(width 0.18288)
		(layer "In6.Cu")
		(net "M_H_CPU0_SB_DQS_DP<2>")
	)
	(segment
		(start 381.478536 -229.762304)
		(end 381.468122 -229.7684)
		(width 0.088646)
		(layer "In6.Cu")
		(net "M_H_CPU0_SB_DQS_DP<2>")
	)
	(segment
		(start 378.657358 -229.763066)
		(end 378.649992 -229.767384)
		(width 0.088646)
		(layer "In6.Cu")
		(net "M_H_CPU0_SB_DQS_DP<2>")
	)
	(segment
		(start 427.38802 -210.832446)
		(end 426.692568 -210.832446)
		(width 0.18288)
		(layer "In6.Cu")
		(net "M_H_CPU0_SB_DQS_DP<2>")
	)
	(segment
		(start 435.998112 -211.340954)
		(end 435.641496 -211.340954)
		(width 0.18288)
		(layer "In6.Cu")
		(net "M_H_CPU0_SB_DQS_DP<2>")
	)
	(segment
		(start 387.130798 -227.722938)
		(end 387.003036 -227.722938)
		(width 0.088646)
		(layer "In6.Cu")
		(net "M_H_CPU0_SB_DQS_DP<2>")
	)
	(segment
		(start 424.38193 -211.92109)
		(end 422.598088 -211.92109)
		(width 0.18288)
		(layer "In6.Cu")
		(net "M_H_CPU0_SB_DQS_DP<2>")
	)
	(segment
		(start 437.67502 -210.230466)
		(end 436.824882 -211.080604)
		(width 0.18288)
		(layer "In6.Cu")
		(net "M_H_CPU0_SB_DQS_DP<2>")
	)
	(segment
		(start 417.63569 -210.956906)
		(end 416.273742 -210.956906)
		(width 0.18288)
		(layer "In6.Cu")
		(net "M_H_CPU0_SB_DQS_DP<2>")
	)
	(segment
		(start 432.470306 -211.071968)
		(end 430.832768 -210.393788)
		(width 0.18288)
		(layer "In6.Cu")
		(net "M_H_CPU0_SB_DQS_DP<2>")
	)
	(segment
		(start 443.672468 -210.151726)
		(end 442.00445 -209.460846)
		(width 0.18288)
		(layer "In6.Cu")
		(net "M_H_CPU0_SB_DQS_DP<2>")
	)
	(segment
		(start 404.219156 -211.743036)
		(end 404.219156 -212.024976)
		(width 0.18288)
		(layer "In6.Cu")
		(net "M_H_CPU0_SB_DQS_DP<2>")
	)
	(segment
		(start 436.258462 -211.080604)
		(end 435.998112 -211.340954)
		(width 0.18288)
		(layer "In6.Cu")
		(net "M_H_CPU0_SB_DQS_DP<2>")
	)
	(segment
		(start 450.628004 -209.783426)
		(end 450.129148 -209.783426)
		(width 0.18288)
		(layer "In6.Cu")
		(net "M_H_CPU0_SB_DQS_DP<2>")
	)
	(segment
		(start 430.832768 -210.393788)
		(end 427.826678 -210.393788)
		(width 0.18288)
		(layer "In6.Cu")
		(net "M_H_CPU0_SB_DQS_DP<2>")
	)
	(segment
		(start 445.623188 -210.151726)
		(end 443.672468 -210.151726)
		(width 0.18288)
		(layer "In6.Cu")
		(net "M_H_CPU0_SB_DQS_DP<2>")
	)
	(segment
		(start 439.490866 -210.230466)
		(end 437.67502 -210.230466)
		(width 0.18288)
		(layer "In6.Cu")
		(net "M_H_CPU0_SB_DQS_DP<2>")
	)
	(segment
		(start 377.638564 -230.584756)
		(end 377.623832 -230.57612)
		(width 0.088646)
		(layer "In6.Cu")
		(net "M_H_CPU0_SB_DQS_DP<2>")
	)
	(segment
		(start 440.09818 -210.490816)
		(end 439.751216 -210.490816)
		(width 0.18288)
		(layer "In6.Cu")
		(net "M_H_CPU0_SB_DQS_DP<2>")
	)
	(segment
		(start 380.538482 -229.762304)
		(end 380.528068 -229.7684)
		(width 0.088646)
		(layer "In6.Cu")
		(net "M_H_CPU0_SB_DQS_DP<2>")
	)
	(segment
		(start 439.751216 -210.490816)
		(end 439.490866 -210.230466)
		(width 0.18288)
		(layer "In6.Cu")
		(net "M_H_CPU0_SB_DQS_DP<2>")
	)
	(segment
		(start 450.129148 -209.783426)
		(end 449.793614 -209.447892)
		(width 0.18288)
		(layer "In6.Cu")
		(net "M_H_CPU0_SB_DQS_DP<2>")
	)
	(segment
		(start 415.508948 -210.192112)
		(end 412.915354 -210.192112)
		(width 0.18288)
		(layer "In6.Cu")
		(net "M_H_CPU0_SB_DQS_DP<2>")
	)
	(segment
		(start 419.457886 -212.779102)
		(end 417.63569 -210.956906)
		(width 0.18288)
		(layer "In6.Cu")
		(net "M_H_CPU0_SB_DQS_DP<2>")
	)
	(segment
		(start 387.190742 -227.782882)
		(end 387.130798 -227.722938)
		(width 0.088646)
		(layer "In6.Cu")
		(net "M_H_CPU0_SB_DQS_DP<2>")
	)
	(segment
		(start 385.702556 -229.711504)
		(end 385.424934 -229.711504)
		(width 0.088646)
		(layer "In6.Cu")
		(net "M_H_CPU0_SB_DQS_DP<2>")
	)
	(segment
		(start 421.174926 -212.78088)
		(end 420.914576 -213.04123)
		(width 0.18288)
		(layer "In6.Cu")
		(net "M_H_CPU0_SB_DQS_DP<2>")
	)
	(segment
		(start 408.63266 -210.828382)
		(end 408.103324 -210.299046)
		(width 0.18288)
		(layer "In6.Cu")
		(net "M_H_CPU0_SB_DQS_DP<2>")
	)
	(segment
		(start 435.641496 -211.340954)
		(end 435.37251 -211.071968)
		(width 0.18288)
		(layer "In6.Cu")
		(net "M_H_CPU0_SB_DQS_DP<2>")
	)
	(segment
		(start 421.738298 -212.78088)
		(end 421.174926 -212.78088)
		(width 0.18288)
		(layer "In6.Cu")
		(net "M_H_CPU0_SB_DQS_DP<2>")
	)
	(segment
		(start 374.460008 -230.086662)
		(end 374.14708 -230.086662)
		(width 0.088646)
		(layer "In6.Cu")
		(net "M_H_CPU0_SB_DQS_DP<2>")
	)
	(segment
		(start 441.588652 -209.460846)
		(end 440.819032 -210.230466)
		(width 0.18288)
		(layer "In6.Cu")
		(net "M_H_CPU0_SB_DQS_DP<2>")
	)
	(segment
		(start 387.003036 -227.722938)
		(end 386.302758 -228.423216)
		(width 0.088646)
		(layer "In6.Cu")
		(net "M_H_CPU0_SB_DQS_DP<2>")
	)
	(segment
		(start 442.00445 -209.460846)
		(end 441.588652 -209.460846)
		(width 0.18288)
		(layer "In6.Cu")
		(net "M_H_CPU0_SB_DQS_DP<2>")
	)
	(segment
		(start 425.02328 -212.191092)
		(end 424.651932 -212.191092)
		(width 0.18288)
		(layer "In6.Cu")
		(net "M_H_CPU0_SB_DQS_DP<2>")
	)
	(segment
		(start 436.824882 -211.080604)
		(end 436.258462 -211.080604)
		(width 0.18288)
		(layer "In6.Cu")
		(net "M_H_CPU0_SB_DQS_DP<2>")
	)
	(segment
		(start 374.819164 -230.584756)
		(end 374.804432 -230.57612)
		(width 0.088646)
		(layer "In6.Cu")
		(net "M_H_CPU0_SB_DQS_DP<2>")
	)
	(segment
		(start 378.47143 -230.086662)
		(end 378.47143 -230.102156)
		(width 0.088646)
		(layer "In6.Cu")
		(net "M_H_CPU0_SB_DQS_DP<2>")
	)
	(segment
		(start 426.692568 -210.832446)
		(end 425.61002 -211.914994)
		(width 0.18288)
		(layer "In6.Cu")
		(net "M_H_CPU0_SB_DQS_DP<2>")
	)
	(segment
		(start 440.35853 -210.230466)
		(end 440.09818 -210.490816)
		(width 0.18288)
		(layer "In6.Cu")
		(net "M_H_CPU0_SB_DQS_DP<2>")
	)
	(segment
		(start 388.46125 -227.782882)
		(end 387.190742 -227.782882)
		(width 0.18288)
		(layer "In6.Cu")
		(net "M_H_CPU0_SB_DQS_DP<2>")
	)
	(segment
		(start 435.37251 -211.071968)
		(end 432.470306 -211.071968)
		(width 0.18288)
		(layer "In6.Cu")
		(net "M_H_CPU0_SB_DQS_DP<2>")
	)
	(segment
		(start 425.299378 -211.914994)
		(end 425.02328 -212.191092)
		(width 0.18288)
		(layer "In6.Cu")
		(net "M_H_CPU0_SB_DQS_DP<2>")
	)
	(segment
		(start 386.302758 -228.423216)
		(end 386.302758 -229.111302)
		(width 0.088646)
		(layer "In6.Cu")
		(net "M_H_CPU0_SB_DQS_DP<2>")
	)
	(segment
		(start 420.914576 -213.04123)
		(end 420.552372 -213.04123)
		(width 0.18288)
		(layer "In6.Cu")
		(net "M_H_CPU0_SB_DQS_DP<2>")
	)
	(segment
		(start 412.279084 -210.828382)
		(end 408.63266 -210.828382)
		(width 0.18288)
		(layer "In6.Cu")
		(net "M_H_CPU0_SB_DQS_DP<2>")
	)
	(segment
		(start 374.52554 -230.152194)
		(end 374.460008 -230.086662)
		(width 0.088646)
		(layer "In6.Cu")
		(net "M_H_CPU0_SB_DQS_DP<2>")
	)
	(segment
		(start 450.911214 -210.066636)
		(end 450.628004 -209.783426)
		(width 0.18288)
		(layer "In6.Cu")
		(net "M_H_CPU0_SB_DQS_DP<2>")
	)
	(segment
		(start 374.804432 -230.57612)
		(end 374.80367 -230.575612)
		(width 0.088646)
		(layer "In6.Cu")
		(net "M_H_CPU0_SB_DQS_DP<2>")
	)
	(segment
		(start 405.663146 -210.299046)
		(end 404.219156 -211.743036)
		(width 0.18288)
		(layer "In6.Cu")
		(net "M_H_CPU0_SB_DQS_DP<2>")
	)
	(segment
		(start 424.651932 -212.191092)
		(end 424.38193 -211.92109)
		(width 0.18288)
		(layer "In6.Cu")
		(net "M_H_CPU0_SB_DQS_DP<2>")
	)
	(segment
		(start 416.273742 -210.956906)
		(end 415.508948 -210.192112)
		(width 0.18288)
		(layer "In6.Cu")
		(net "M_H_CPU0_SB_DQS_DP<2>")
	)
	(segment
		(start 422.598088 -211.92109)
		(end 421.738298 -212.78088)
		(width 0.18288)
		(layer "In6.Cu")
		(net "M_H_CPU0_SB_DQS_DP<2>")
	)
	(segment
		(start 378.658882 -229.762304)
		(end 378.657358 -229.763066)
		(width 0.088646)
		(layer "In6.Cu")
		(net "M_H_CPU0_SB_DQS_DP<2>")
	)
	(segment
		(start 420.552372 -213.04123)
		(end 420.290244 -212.779102)
		(width 0.18288)
		(layer "In6.Cu")
		(net "M_H_CPU0_SB_DQS_DP<2>")
	)
	(segment
		(start 374.80367 -230.575612)
		(end 374.798336 -230.572564)
		(width 0.088646)
		(layer "In6.Cu")
		(net "M_H_CPU0_SB_DQS_DP<2>")
	)
	(segment
		(start 408.103324 -210.299046)
		(end 405.663146 -210.299046)
		(width 0.18288)
		(layer "In6.Cu")
		(net "M_H_CPU0_SB_DQS_DP<2>")
	)
	(segment
		(start 447.322448 -209.447892)
		(end 445.623188 -210.151726)
		(width 0.18288)
		(layer "In6.Cu")
		(net "M_H_CPU0_SB_DQS_DP<2>")
	)
	(segment
		(start 420.290244 -212.779102)
		(end 419.457886 -212.779102)
		(width 0.18288)
		(layer "In6.Cu")
		(net "M_H_CPU0_SB_DQS_DP<2>")
	)
	(segment
		(start 440.819032 -210.230466)
		(end 440.35853 -210.230466)
		(width 0.18288)
		(layer "In6.Cu")
		(net "M_H_CPU0_SB_DQS_DP<2>")
	)
	(segment
		(start 375.758964 -230.584756)
		(end 375.744232 -230.57612)
		(width 0.088646)
		(layer "In6.Cu")
		(net "M_H_CPU0_SB_DQS_DP<2>")
	)
	(segment
		(start 425.61002 -211.914994)
		(end 425.299378 -211.914994)
		(width 0.18288)
		(layer "In6.Cu")
		(net "M_H_CPU0_SB_DQS_DP<2>")
	)
	(arc
		(start 383.732532 -229.762304)
		(mid 383.545334 -229.712161)
		(end 383.358136 -229.762304)
		(width 0.088646)
		(layer "In6.Cu")
		(net "M_H_CPU0_SB_DQS_DP<2>")
	)
	(arc
		(start 376.684032 -230.57612)
		(mid 376.496834 -230.525977)
		(end 376.309636 -230.57612)
		(width 0.088646)
		(layer "In6.Cu")
		(net "M_H_CPU0_SB_DQS_DP<2>")
	)
	(arc
		(start 380.528068 -229.7684)
		(mid 380.24989 -229.838123)
		(end 379.973332 -229.762304)
		(width 0.088646)
		(layer "In6.Cu")
		(net "M_H_CPU0_SB_DQS_DP<2>")
	)
	(arc
		(start 379.033278 -229.762304)
		(mid 378.84608 -229.712161)
		(end 378.658882 -229.762304)
		(width 0.088646)
		(layer "In6.Cu")
		(net "M_H_CPU0_SB_DQS_DP<2>")
	)
	(arc
		(start 381.852932 -229.762304)
		(mid 381.665734 -229.712161)
		(end 381.478536 -229.762304)
		(width 0.088646)
		(layer "In6.Cu")
		(net "M_H_CPU0_SB_DQS_DP<2>")
	)
	(arc
		(start 382.418336 -229.762304)
		(mid 382.135634 -229.83808)
		(end 381.852932 -229.762304)
		(width 0.088646)
		(layer "In6.Cu")
		(net "M_H_CPU0_SB_DQS_DP<2>")
	)
	(arc
		(start 383.358136 -229.762304)
		(mid 383.075434 -229.83808)
		(end 382.792732 -229.762304)
		(width 0.088646)
		(layer "In6.Cu")
		(net "M_H_CPU0_SB_DQS_DP<2>")
	)
	(arc
		(start 378.649992 -229.767384)
		(mid 378.519078 -229.903744)
		(end 378.47143 -230.086662)
		(width 0.088646)
		(layer "In6.Cu")
		(net "M_H_CPU0_SB_DQS_DP<2>")
	)
	(arc
		(start 385.39293 -229.713028)
		(mid 385.312615 -229.729115)
		(end 385.237736 -229.762304)
		(width 0.088646)
		(layer "In6.Cu")
		(net "M_H_CPU0_SB_DQS_DP<2>")
	)
	(arc
		(start 381.468122 -229.7684)
		(mid 381.18969 -229.838246)
		(end 380.912878 -229.762304)
		(width 0.088646)
		(layer "In6.Cu")
		(net "M_H_CPU0_SB_DQS_DP<2>")
	)
	(arc
		(start 385.237736 -229.762304)
		(mid 384.955034 -229.83808)
		(end 384.672332 -229.762304)
		(width 0.088646)
		(layer "In6.Cu")
		(net "M_H_CPU0_SB_DQS_DP<2>")
	)
	(arc
		(start 375.369836 -230.57612)
		(mid 375.095637 -230.651955)
		(end 374.819164 -230.584756)
		(width 0.088646)
		(layer "In6.Cu")
		(net "M_H_CPU0_SB_DQS_DP<2>")
	)
	(arc
		(start 374.798336 -230.572564)
		(mid 374.612813 -230.394263)
		(end 374.52554 -230.152194)
		(width 0.088646)
		(layer "In6.Cu")
		(net "M_H_CPU0_SB_DQS_DP<2>")
	)
	(arc
		(start 379.973332 -229.762304)
		(mid 379.786134 -229.712161)
		(end 379.598936 -229.762304)
		(width 0.088646)
		(layer "In6.Cu")
		(net "M_H_CPU0_SB_DQS_DP<2>")
	)
	(arc
		(start 380.912878 -229.762304)
		(mid 380.72568 -229.712161)
		(end 380.538482 -229.762304)
		(width 0.088646)
		(layer "In6.Cu")
		(net "M_H_CPU0_SB_DQS_DP<2>")
	)
	(arc
		(start 378.189236 -230.57612)
		(mid 377.915037 -230.651955)
		(end 377.638564 -230.584756)
		(width 0.088646)
		(layer "In6.Cu")
		(net "M_H_CPU0_SB_DQS_DP<2>")
	)
	(arc
		(start 375.744232 -230.57612)
		(mid 375.557034 -230.525977)
		(end 375.369836 -230.57612)
		(width 0.088646)
		(layer "In6.Cu")
		(net "M_H_CPU0_SB_DQS_DP<2>")
	)
	(arc
		(start 382.792732 -229.762304)
		(mid 382.605534 -229.712161)
		(end 382.418336 -229.762304)
		(width 0.088646)
		(layer "In6.Cu")
		(net "M_H_CPU0_SB_DQS_DP<2>")
	)
	(arc
		(start 378.47143 -230.102156)
		(mid 378.39206 -230.37589)
		(end 378.189236 -230.57612)
		(width 0.088646)
		(layer "In6.Cu")
		(net "M_H_CPU0_SB_DQS_DP<2>")
	)
	(arc
		(start 384.672332 -229.762304)
		(mid 384.485134 -229.712161)
		(end 384.297936 -229.762304)
		(width 0.088646)
		(layer "In6.Cu")
		(net "M_H_CPU0_SB_DQS_DP<2>")
	)
	(arc
		(start 384.297936 -229.762304)
		(mid 384.015234 -229.83808)
		(end 383.732532 -229.762304)
		(width 0.088646)
		(layer "In6.Cu")
		(net "M_H_CPU0_SB_DQS_DP<2>")
	)
	(arc
		(start 379.588522 -229.7684)
		(mid 379.31009 -229.838246)
		(end 379.033278 -229.762304)
		(width 0.088646)
		(layer "In6.Cu")
		(net "M_H_CPU0_SB_DQS_DP<2>")
	)
	(arc
		(start 377.249436 -230.57612)
		(mid 376.975237 -230.651955)
		(end 376.698764 -230.584756)
		(width 0.088646)
		(layer "In6.Cu")
		(net "M_H_CPU0_SB_DQS_DP<2>")
	)
	(arc
		(start 385.424934 -229.711504)
		(mid 385.408916 -229.711922)
		(end 385.39293 -229.713028)
		(width 0.088646)
		(layer "In6.Cu")
		(net "M_H_CPU0_SB_DQS_DP<2>")
	)
	(arc
		(start 376.309636 -230.57612)
		(mid 376.035437 -230.651955)
		(end 375.758964 -230.584756)
		(width 0.088646)
		(layer "In6.Cu")
		(net "M_H_CPU0_SB_DQS_DP<2>")
	)
	(arc
		(start 377.623832 -230.57612)
		(mid 377.436634 -230.525977)
		(end 377.249436 -230.57612)
		(width 0.088646)
		(layer "In6.Cu")
		(net "M_H_CPU0_SB_DQS_DP<2>")
	)
	(segment
		(start 458.5335 -219.134944)
		(end 458.123036 -219.545408)
		(width 0.20066)
		(layer "F.Cu")
		(net "M_H_CPU0_SB_DQS_DP<1>")
	)
	(segment
		(start 452.605394 -219.41663)
		(end 452.016114 -219.41663)
		(width 0.20066)
		(layer "F.Cu")
		(net "M_H_CPU0_SB_DQS_DP<1>")
	)
	(segment
		(start 459.011274 -219.41663)
		(end 458.729588 -219.134944)
		(width 0.20066)
		(layer "F.Cu")
		(net "M_H_CPU0_SB_DQS_DP<1>")
	)
	(segment
		(start 454.937368 -219.841826)
		(end 454.797922 -219.841826)
		(width 0.20066)
		(layer "F.Cu")
		(net "M_H_CPU0_SB_DQS_DP<1>")
	)
	(segment
		(start 370.85778 -233.064304)
		(end 370.85778 -232.528618)
		(width 0.20066)
		(layer "F.Cu")
		(net "M_H_CPU0_SB_DQS_DP<1>")
	)
	(segment
		(start 454.797922 -219.841826)
		(end 454.546716 -219.59062)
		(width 0.20066)
		(layer "F.Cu")
		(net "M_H_CPU0_SB_DQS_DP<1>")
	)
	(segment
		(start 458.123036 -219.545408)
		(end 457.75245 -219.545408)
		(width 0.20066)
		(layer "F.Cu")
		(net "M_H_CPU0_SB_DQS_DP<1>")
	)
	(segment
		(start 453.446388 -219.176092)
		(end 452.845932 -219.176092)
		(width 0.20066)
		(layer "F.Cu")
		(net "M_H_CPU0_SB_DQS_DP<1>")
	)
	(segment
		(start 454.546716 -219.59062)
		(end 453.860916 -219.59062)
		(width 0.20066)
		(layer "F.Cu")
		(net "M_H_CPU0_SB_DQS_DP<1>")
	)
	(segment
		(start 458.729588 -219.134944)
		(end 458.5335 -219.134944)
		(width 0.20066)
		(layer "F.Cu")
		(net "M_H_CPU0_SB_DQS_DP<1>")
	)
	(segment
		(start 454.963276 -219.841826)
		(end 454.937368 -219.841826)
		(width 0.101854)
		(layer "F.Cu")
		(net "M_H_CPU0_SB_DQS_DP<1>")
	)
	(segment
		(start 453.860916 -219.59062)
		(end 453.446388 -219.176092)
		(width 0.20066)
		(layer "F.Cu")
		(net "M_H_CPU0_SB_DQS_DP<1>")
	)
	(segment
		(start 459.559914 -219.41663)
		(end 459.011274 -219.41663)
		(width 0.20066)
		(layer "F.Cu")
		(net "M_H_CPU0_SB_DQS_DP<1>")
	)
	(segment
		(start 457.126594 -219.847922)
		(end 457.120498 -219.841826)
		(width 0.1016)
		(layer "F.Cu")
		(net "M_H_CPU0_SB_DQS_DP<1>")
	)
	(segment
		(start 457.449936 -219.847922)
		(end 457.126594 -219.847922)
		(width 0.20066)
		(layer "F.Cu")
		(net "M_H_CPU0_SB_DQS_DP<1>")
	)
	(segment
		(start 370.85778 -232.528618)
		(end 370.858034 -232.528364)
		(width 0.20066)
		(layer "F.Cu")
		(net "M_H_CPU0_SB_DQS_DP<1>")
	)
	(segment
		(start 452.845932 -219.176092)
		(end 452.605394 -219.41663)
		(width 0.20066)
		(layer "F.Cu")
		(net "M_H_CPU0_SB_DQS_DP<1>")
	)
	(segment
		(start 457.75245 -219.545408)
		(end 457.449936 -219.847922)
		(width 0.20066)
		(layer "F.Cu")
		(net "M_H_CPU0_SB_DQS_DP<1>")
	)
	(segment
		(start 450.911214 -219.41663)
		(end 452.016114 -219.41663)
		(width 0.20066)
		(layer "F.Cu")
		(net "M_H_CPU0_SB_DQS_DP<1>")
	)
	(segment
		(start 457.120498 -219.841826)
		(end 454.963276 -219.841826)
		(width 0.1016)
		(layer "F.Cu")
		(net "M_H_CPU0_SB_DQS_DP<1>")
	)
	(segment
		(start 395.769846 -225.914204)
		(end 390.313418 -231.370632)
		(width 0.18288)
		(layer "In11.Cu")
		(net "M_H_CPU0_SB_DQS_DP<1>")
	)
	(segment
		(start 390.313418 -231.370632)
		(end 388.079996 -231.370632)
		(width 0.18288)
		(layer "In11.Cu")
		(net "M_H_CPU0_SB_DQS_DP<1>")
	)
	(segment
		(start 378.658882 -233.017822)
		(end 378.64415 -233.026458)
		(width 0.088646)
		(layer "In11.Cu")
		(net "M_H_CPU0_SB_DQS_DP<1>")
	)
	(segment
		(start 373.400574 -233.021124)
		(end 373.38889 -233.01452)
		(width 0.088646)
		(layer "In11.Cu")
		(net "M_H_CPU0_SB_DQS_DP<1>")
	)
	(segment
		(start 435.529482 -213.040976)
		(end 435.281832 -212.793326)
		(width 0.18288)
		(layer "In11.Cu")
		(net "M_H_CPU0_SB_DQS_DP<1>")
	)
	(segment
		(start 420.441882 -214.740998)
		(end 420.18966 -214.488776)
		(width 0.18288)
		(layer "In11.Cu")
		(net "M_H_CPU0_SB_DQS_DP<1>")
	)
	(segment
		(start 437.844184 -213.623652)
		(end 436.99684 -212.776308)
		(width 0.18288)
		(layer "In11.Cu")
		(net "M_H_CPU0_SB_DQS_DP<1>")
	)
	(segment
		(start 421.219884 -214.48522)
		(end 420.964106 -214.740998)
		(width 0.18288)
		(layer "In11.Cu")
		(net "M_H_CPU0_SB_DQS_DP<1>")
	)
	(segment
		(start 385.612386 -233.017568)
		(end 385.612132 -233.017822)
		(width 0.088646)
		(layer "In11.Cu")
		(net "M_H_CPU0_SB_DQS_DP<1>")
	)
	(segment
		(start 387.959092 -231.310688)
		(end 387.870446 -231.399334)
		(width 0.088646)
		(layer "In11.Cu")
		(net "M_H_CPU0_SB_DQS_DP<1>")
	)
	(segment
		(start 386.423408 -233.093768)
		(end 385.894834 -233.093768)
		(width 0.088646)
		(layer "In11.Cu")
		(net "M_H_CPU0_SB_DQS_DP<1>")
	)
	(segment
		(start 450.18579 -219.18168)
		(end 449.689474 -218.685364)
		(width 0.18288)
		(layer "In11.Cu")
		(net "M_H_CPU0_SB_DQS_DP<1>")
	)
	(segment
		(start 442.354462 -214.426546)
		(end 441.726066 -214.426546)
		(width 0.18288)
		(layer "In11.Cu")
		(net "M_H_CPU0_SB_DQS_DP<1>")
	)
	(segment
		(start 380.538736 -233.017822)
		(end 380.528322 -233.023918)
		(width 0.088646)
		(layer "In11.Cu")
		(net "M_H_CPU0_SB_DQS_DP<1>")
	)
	(segment
		(start 424.54195 -213.891114)
		(end 424.285664 -213.634828)
		(width 0.18288)
		(layer "In11.Cu")
		(net "M_H_CPU0_SB_DQS_DP<1>")
	)
	(segment
		(start 416.001708 -213.799166)
		(end 412.933388 -213.799166)
		(width 0.18288)
		(layer "In11.Cu")
		(net "M_H_CPU0_SB_DQS_DP<1>")
	)
	(segment
		(start 375.839482 -233.017822)
		(end 375.82475 -233.026458)
		(width 0.088646)
		(layer "In11.Cu")
		(net "M_H_CPU0_SB_DQS_DP<1>")
	)
	(segment
		(start 387.625844 -232.198672)
		(end 387.10108 -232.416096)
		(width 0.088646)
		(layer "In11.Cu")
		(net "M_H_CPU0_SB_DQS_DP<1>")
	)
	(segment
		(start 436.051706 -213.040976)
		(end 435.529482 -213.040976)
		(width 0.18288)
		(layer "In11.Cu")
		(net "M_H_CPU0_SB_DQS_DP<1>")
	)
	(segment
		(start 425.900596 -213.61019)
		(end 425.345098 -213.61019)
		(width 0.18288)
		(layer "In11.Cu")
		(net "M_H_CPU0_SB_DQS_DP<1>")
	)
	(segment
		(start 432.144678 -212.793326)
		(end 431.332386 -211.981034)
		(width 0.18288)
		(layer "In11.Cu")
		(net "M_H_CPU0_SB_DQS_DP<1>")
	)
	(segment
		(start 439.62955 -213.891114)
		(end 439.362088 -213.623652)
		(width 0.18288)
		(layer "In11.Cu")
		(net "M_H_CPU0_SB_DQS_DP<1>")
	)
	(segment
		(start 439.362088 -213.623652)
		(end 437.844184 -213.623652)
		(width 0.18288)
		(layer "In11.Cu")
		(net "M_H_CPU0_SB_DQS_DP<1>")
	)
	(segment
		(start 450.911214 -219.41663)
		(end 450.676264 -219.18168)
		(width 0.18288)
		(layer "In11.Cu")
		(net "M_H_CPU0_SB_DQS_DP<1>")
	)
	(segment
		(start 420.964106 -214.740998)
		(end 420.441882 -214.740998)
		(width 0.18288)
		(layer "In11.Cu")
		(net "M_H_CPU0_SB_DQS_DP<1>")
	)
	(segment
		(start 448.227196 -218.685364)
		(end 446.375536 -216.833704)
		(width 0.18288)
		(layer "In11.Cu")
		(net "M_H_CPU0_SB_DQS_DP<1>")
	)
	(segment
		(start 425.064174 -213.891114)
		(end 424.54195 -213.891114)
		(width 0.18288)
		(layer "In11.Cu")
		(net "M_H_CPU0_SB_DQS_DP<1>")
	)
	(segment
		(start 440.416442 -213.626446)
		(end 440.151774 -213.891114)
		(width 0.18288)
		(layer "In11.Cu")
		(net "M_H_CPU0_SB_DQS_DP<1>")
	)
	(segment
		(start 445.222884 -216.833704)
		(end 443.732666 -215.343486)
		(width 0.18288)
		(layer "In11.Cu")
		(net "M_H_CPU0_SB_DQS_DP<1>")
	)
	(segment
		(start 446.375536 -216.833704)
		(end 445.222884 -216.833704)
		(width 0.18288)
		(layer "In11.Cu")
		(net "M_H_CPU0_SB_DQS_DP<1>")
	)
	(segment
		(start 380.927864 -233.026458)
		(end 380.913132 -233.017822)
		(width 0.088646)
		(layer "In11.Cu")
		(net "M_H_CPU0_SB_DQS_DP<1>")
	)
	(segment
		(start 436.99684 -212.776308)
		(end 436.316374 -212.776308)
		(width 0.18288)
		(layer "In11.Cu")
		(net "M_H_CPU0_SB_DQS_DP<1>")
	)
	(segment
		(start 403.127718 -216.083388)
		(end 403.127718 -217.636852)
		(width 0.18288)
		(layer "In11.Cu")
		(net "M_H_CPU0_SB_DQS_DP<1>")
	)
	(segment
		(start 424.285664 -213.634828)
		(end 422.638982 -213.634828)
		(width 0.18288)
		(layer "In11.Cu")
		(net "M_H_CPU0_SB_DQS_DP<1>")
	)
	(segment
		(start 372.460774 -233.021124)
		(end 372.44909 -233.01452)
		(width 0.088646)
		(layer "In11.Cu")
		(net "M_H_CPU0_SB_DQS_DP<1>")
	)
	(segment
		(start 387.10108 -232.416096)
		(end 386.423408 -233.093768)
		(width 0.088646)
		(layer "In11.Cu")
		(net "M_H_CPU0_SB_DQS_DP<1>")
	)
	(segment
		(start 406.448006 -213.20633)
		(end 406.448006 -213.409022)
		(width 0.18288)
		(layer "In11.Cu")
		(net "M_H_CPU0_SB_DQS_DP<1>")
	)
	(segment
		(start 387.782816 -232.0417)
		(end 387.625844 -232.198672)
		(width 0.088646)
		(layer "In11.Cu")
		(net "M_H_CPU0_SB_DQS_DP<1>")
	)
	(segment
		(start 449.689474 -218.685364)
		(end 448.227196 -218.685364)
		(width 0.18288)
		(layer "In11.Cu")
		(net "M_H_CPU0_SB_DQS_DP<1>")
	)
	(segment
		(start 427.176946 -212.836252)
		(end 426.674534 -212.836252)
		(width 0.18288)
		(layer "In11.Cu")
		(net "M_H_CPU0_SB_DQS_DP<1>")
	)
	(segment
		(start 440.151774 -213.891114)
		(end 439.62955 -213.891114)
		(width 0.18288)
		(layer "In11.Cu")
		(net "M_H_CPU0_SB_DQS_DP<1>")
	)
	(segment
		(start 441.726066 -214.426546)
		(end 440.925966 -213.626446)
		(width 0.18288)
		(layer "In11.Cu")
		(net "M_H_CPU0_SB_DQS_DP<1>")
	)
	(segment
		(start 443.732666 -215.343486)
		(end 443.271402 -215.343486)
		(width 0.18288)
		(layer "In11.Cu")
		(net "M_H_CPU0_SB_DQS_DP<1>")
	)
	(segment
		(start 403.127718 -217.636852)
		(end 395.769846 -224.994724)
		(width 0.18288)
		(layer "In11.Cu")
		(net "M_H_CPU0_SB_DQS_DP<1>")
	)
	(segment
		(start 388.020052 -231.310688)
		(end 387.959092 -231.310688)
		(width 0.088646)
		(layer "In11.Cu")
		(net "M_H_CPU0_SB_DQS_DP<1>")
	)
	(segment
		(start 417.666678 -214.488776)
		(end 416.001708 -213.799166)
		(width 0.18288)
		(layer "In11.Cu")
		(net "M_H_CPU0_SB_DQS_DP<1>")
	)
	(segment
		(start 407.161746 -213.20633)
		(end 406.964388 -213.008972)
		(width 0.18288)
		(layer "In11.Cu")
		(net "M_H_CPU0_SB_DQS_DP<1>")
	)
	(segment
		(start 440.925966 -213.626446)
		(end 440.416442 -213.626446)
		(width 0.18288)
		(layer "In11.Cu")
		(net "M_H_CPU0_SB_DQS_DP<1>")
	)
	(segment
		(start 431.332386 -211.981034)
		(end 428.032164 -211.981034)
		(width 0.18288)
		(layer "In11.Cu")
		(net "M_H_CPU0_SB_DQS_DP<1>")
	)
	(segment
		(start 377.719082 -233.017822)
		(end 377.70435 -233.026458)
		(width 0.088646)
		(layer "In11.Cu")
		(net "M_H_CPU0_SB_DQS_DP<1>")
	)
	(segment
		(start 443.271402 -215.343486)
		(end 442.354462 -214.426546)
		(width 0.18288)
		(layer "In11.Cu")
		(net "M_H_CPU0_SB_DQS_DP<1>")
	)
	(segment
		(start 436.316374 -212.776308)
		(end 436.051706 -213.040976)
		(width 0.18288)
		(layer "In11.Cu")
		(net "M_H_CPU0_SB_DQS_DP<1>")
	)
	(segment
		(start 406.964388 -213.008972)
		(end 406.645364 -213.008972)
		(width 0.18288)
		(layer "In11.Cu")
		(net "M_H_CPU0_SB_DQS_DP<1>")
	)
	(segment
		(start 421.78859 -214.48522)
		(end 421.219884 -214.48522)
		(width 0.18288)
		(layer "In11.Cu")
		(net "M_H_CPU0_SB_DQS_DP<1>")
	)
	(segment
		(start 407.161746 -213.409022)
		(end 407.161746 -213.20633)
		(width 0.18288)
		(layer "In11.Cu")
		(net "M_H_CPU0_SB_DQS_DP<1>")
	)
	(segment
		(start 420.18966 -214.488776)
		(end 417.666678 -214.488776)
		(width 0.18288)
		(layer "In11.Cu")
		(net "M_H_CPU0_SB_DQS_DP<1>")
	)
	(segment
		(start 425.345098 -213.61019)
		(end 425.064174 -213.891114)
		(width 0.18288)
		(layer "In11.Cu")
		(net "M_H_CPU0_SB_DQS_DP<1>")
	)
	(segment
		(start 388.079996 -231.370632)
		(end 388.020052 -231.310688)
		(width 0.088646)
		(layer "In11.Cu")
		(net "M_H_CPU0_SB_DQS_DP<1>")
	)
	(segment
		(start 408.6479 -213.786466)
		(end 407.53919 -213.786466)
		(width 0.18288)
		(layer "In11.Cu")
		(net "M_H_CPU0_SB_DQS_DP<1>")
	)
	(segment
		(start 379.598682 -233.017822)
		(end 379.58395 -233.026458)
		(width 0.088646)
		(layer "In11.Cu")
		(net "M_H_CPU0_SB_DQS_DP<1>")
	)
	(segment
		(start 371.23624 -232.593896)
		(end 371.170708 -232.528364)
		(width 0.088646)
		(layer "In11.Cu")
		(net "M_H_CPU0_SB_DQS_DP<1>")
	)
	(segment
		(start 395.769846 -224.994724)
		(end 395.769846 -225.914204)
		(width 0.18288)
		(layer "In11.Cu")
		(net "M_H_CPU0_SB_DQS_DP<1>")
	)
	(segment
		(start 406.448006 -213.409022)
		(end 406.070562 -213.786466)
		(width 0.18288)
		(layer "In11.Cu")
		(net "M_H_CPU0_SB_DQS_DP<1>")
	)
	(segment
		(start 371.170708 -232.528364)
		(end 370.858034 -232.528364)
		(width 0.088646)
		(layer "In11.Cu")
		(net "M_H_CPU0_SB_DQS_DP<1>")
	)
	(segment
		(start 376.779282 -233.017822)
		(end 376.76455 -233.026458)
		(width 0.088646)
		(layer "In11.Cu")
		(net "M_H_CPU0_SB_DQS_DP<1>")
	)
	(segment
		(start 450.676264 -219.18168)
		(end 450.18579 -219.18168)
		(width 0.18288)
		(layer "In11.Cu")
		(net "M_H_CPU0_SB_DQS_DP<1>")
	)
	(segment
		(start 428.032164 -211.981034)
		(end 427.176946 -212.836252)
		(width 0.18288)
		(layer "In11.Cu")
		(net "M_H_CPU0_SB_DQS_DP<1>")
	)
	(segment
		(start 406.070562 -213.786466)
		(end 405.42464 -213.786466)
		(width 0.18288)
		(layer "In11.Cu")
		(net "M_H_CPU0_SB_DQS_DP<1>")
	)
	(segment
		(start 412.933388 -213.799166)
		(end 412.521146 -214.211408)
		(width 0.18288)
		(layer "In11.Cu")
		(net "M_H_CPU0_SB_DQS_DP<1>")
	)
	(segment
		(start 409.072842 -214.211408)
		(end 408.6479 -213.786466)
		(width 0.18288)
		(layer "In11.Cu")
		(net "M_H_CPU0_SB_DQS_DP<1>")
	)
	(segment
		(start 405.42464 -213.786466)
		(end 403.127718 -216.083388)
		(width 0.18288)
		(layer "In11.Cu")
		(net "M_H_CPU0_SB_DQS_DP<1>")
	)
	(segment
		(start 387.870446 -231.399334)
		(end 387.870446 -231.831134)
		(width 0.088646)
		(layer "In11.Cu")
		(net "M_H_CPU0_SB_DQS_DP<1>")
	)
	(segment
		(start 387.870446 -231.831134)
		(end 387.782816 -232.0417)
		(width 0.088646)
		(layer "In11.Cu")
		(net "M_H_CPU0_SB_DQS_DP<1>")
	)
	(segment
		(start 426.674534 -212.836252)
		(end 425.900596 -213.61019)
		(width 0.18288)
		(layer "In11.Cu")
		(net "M_H_CPU0_SB_DQS_DP<1>")
	)
	(segment
		(start 412.521146 -214.211408)
		(end 409.072842 -214.211408)
		(width 0.18288)
		(layer "In11.Cu")
		(net "M_H_CPU0_SB_DQS_DP<1>")
	)
	(segment
		(start 407.53919 -213.786466)
		(end 407.161746 -213.409022)
		(width 0.18288)
		(layer "In11.Cu")
		(net "M_H_CPU0_SB_DQS_DP<1>")
	)
	(segment
		(start 406.645364 -213.008972)
		(end 406.448006 -213.20633)
		(width 0.18288)
		(layer "In11.Cu")
		(net "M_H_CPU0_SB_DQS_DP<1>")
	)
	(segment
		(start 435.281832 -212.793326)
		(end 432.144678 -212.793326)
		(width 0.18288)
		(layer "In11.Cu")
		(net "M_H_CPU0_SB_DQS_DP<1>")
	)
	(segment
		(start 422.638982 -213.634828)
		(end 421.78859 -214.48522)
		(width 0.18288)
		(layer "In11.Cu")
		(net "M_H_CPU0_SB_DQS_DP<1>")
	)
	(arc
		(start 374.32869 -233.01452)
		(mid 374.143869 -232.967727)
		(end 373.959882 -233.017822)
		(width 0.088646)
		(layer "In11.Cu")
		(net "M_H_CPU0_SB_DQS_DP<1>")
	)
	(arc
		(start 373.38889 -233.01452)
		(mid 373.204035 -232.96757)
		(end 373.020082 -233.017822)
		(width 0.088646)
		(layer "In11.Cu")
		(net "M_H_CPU0_SB_DQS_DP<1>")
	)
	(arc
		(start 374.899682 -233.017822)
		(mid 374.897906 -233.018841)
		(end 374.896126 -233.019854)
		(width 0.088646)
		(layer "In11.Cu")
		(net "M_H_CPU0_SB_DQS_DP<1>")
	)
	(arc
		(start 373.959882 -233.017822)
		(mid 373.680679 -233.093462)
		(end 373.400574 -233.021124)
		(width 0.088646)
		(layer "In11.Cu")
		(net "M_H_CPU0_SB_DQS_DP<1>")
	)
	(arc
		(start 374.331738 -233.016298)
		(mid 374.330213 -233.015411)
		(end 374.32869 -233.01452)
		(width 0.088646)
		(layer "In11.Cu")
		(net "M_H_CPU0_SB_DQS_DP<1>")
	)
	(arc
		(start 377.70435 -233.026458)
		(mid 377.427875 -233.093778)
		(end 377.153678 -233.017822)
		(width 0.088646)
		(layer "In11.Cu")
		(net "M_H_CPU0_SB_DQS_DP<1>")
	)
	(arc
		(start 380.913132 -233.017822)
		(mid 380.725934 -232.967679)
		(end 380.538736 -233.017822)
		(width 0.088646)
		(layer "In11.Cu")
		(net "M_H_CPU0_SB_DQS_DP<1>")
	)
	(arc
		(start 380.528322 -233.023918)
		(mid 380.24989 -233.093764)
		(end 379.973078 -233.017822)
		(width 0.088646)
		(layer "In11.Cu")
		(net "M_H_CPU0_SB_DQS_DP<1>")
	)
	(arc
		(start 384.672332 -233.017822)
		(mid 384.485134 -232.967679)
		(end 384.297936 -233.017822)
		(width 0.088646)
		(layer "In11.Cu")
		(net "M_H_CPU0_SB_DQS_DP<1>")
	)
	(arc
		(start 372.44909 -233.01452)
		(mid 372.264235 -232.96757)
		(end 372.080282 -233.017822)
		(width 0.088646)
		(layer "In11.Cu")
		(net "M_H_CPU0_SB_DQS_DP<1>")
	)
	(arc
		(start 382.792732 -233.017822)
		(mid 382.605534 -232.967679)
		(end 382.418336 -233.017822)
		(width 0.088646)
		(layer "In11.Cu")
		(net "M_H_CPU0_SB_DQS_DP<1>")
	)
	(arc
		(start 382.418336 -233.017822)
		(mid 382.135634 -233.093598)
		(end 381.852932 -233.017822)
		(width 0.088646)
		(layer "In11.Cu")
		(net "M_H_CPU0_SB_DQS_DP<1>")
	)
	(arc
		(start 373.020082 -233.017822)
		(mid 372.740879 -233.093462)
		(end 372.460774 -233.021124)
		(width 0.088646)
		(layer "In11.Cu")
		(net "M_H_CPU0_SB_DQS_DP<1>")
	)
	(arc
		(start 378.093478 -233.017822)
		(mid 377.90628 -232.967679)
		(end 377.719082 -233.017822)
		(width 0.088646)
		(layer "In11.Cu")
		(net "M_H_CPU0_SB_DQS_DP<1>")
	)
	(arc
		(start 381.478536 -233.017822)
		(mid 381.204337 -233.093657)
		(end 380.927864 -233.026458)
		(width 0.088646)
		(layer "In11.Cu")
		(net "M_H_CPU0_SB_DQS_DP<1>")
	)
	(arc
		(start 372.080282 -233.017822)
		(mid 371.55346 -233.038163)
		(end 371.239034 -232.614978)
		(width 0.088646)
		(layer "In11.Cu")
		(net "M_H_CPU0_SB_DQS_DP<1>")
	)
	(arc
		(start 378.64415 -233.026458)
		(mid 378.367675 -233.093778)
		(end 378.093478 -233.017822)
		(width 0.088646)
		(layer "In11.Cu")
		(net "M_H_CPU0_SB_DQS_DP<1>")
	)
	(arc
		(start 379.033278 -233.017822)
		(mid 378.84608 -232.967679)
		(end 378.658882 -233.017822)
		(width 0.088646)
		(layer "In11.Cu")
		(net "M_H_CPU0_SB_DQS_DP<1>")
	)
	(arc
		(start 377.153678 -233.017822)
		(mid 376.96648 -232.967679)
		(end 376.779282 -233.017822)
		(width 0.088646)
		(layer "In11.Cu")
		(net "M_H_CPU0_SB_DQS_DP<1>")
	)
	(arc
		(start 385.612132 -233.017822)
		(mid 385.424934 -232.967679)
		(end 385.237736 -233.017822)
		(width 0.088646)
		(layer "In11.Cu")
		(net "M_H_CPU0_SB_DQS_DP<1>")
	)
	(arc
		(start 384.297936 -233.017822)
		(mid 384.015234 -233.093598)
		(end 383.732532 -233.017822)
		(width 0.088646)
		(layer "In11.Cu")
		(net "M_H_CPU0_SB_DQS_DP<1>")
	)
	(arc
		(start 375.82475 -233.026458)
		(mid 375.548275 -233.093778)
		(end 375.274078 -233.017822)
		(width 0.088646)
		(layer "In11.Cu")
		(net "M_H_CPU0_SB_DQS_DP<1>")
	)
	(arc
		(start 374.896126 -233.019854)
		(mid 374.615042 -233.093591)
		(end 374.334532 -233.017822)
		(width 0.088646)
		(layer "In11.Cu")
		(net "M_H_CPU0_SB_DQS_DP<1>")
	)
	(arc
		(start 385.237736 -233.017822)
		(mid 384.955034 -233.093598)
		(end 384.672332 -233.017822)
		(width 0.088646)
		(layer "In11.Cu")
		(net "M_H_CPU0_SB_DQS_DP<1>")
	)
	(arc
		(start 381.852932 -233.017822)
		(mid 381.665734 -232.967679)
		(end 381.478536 -233.017822)
		(width 0.088646)
		(layer "In11.Cu")
		(net "M_H_CPU0_SB_DQS_DP<1>")
	)
	(arc
		(start 383.732532 -233.017822)
		(mid 383.545334 -232.967679)
		(end 383.358136 -233.017822)
		(width 0.088646)
		(layer "In11.Cu")
		(net "M_H_CPU0_SB_DQS_DP<1>")
	)
	(arc
		(start 376.213878 -233.017822)
		(mid 376.02668 -232.967679)
		(end 375.839482 -233.017822)
		(width 0.088646)
		(layer "In11.Cu")
		(net "M_H_CPU0_SB_DQS_DP<1>")
	)
	(arc
		(start 376.76455 -233.026458)
		(mid 376.488075 -233.093778)
		(end 376.213878 -233.017822)
		(width 0.088646)
		(layer "In11.Cu")
		(net "M_H_CPU0_SB_DQS_DP<1>")
	)
	(arc
		(start 379.973078 -233.017822)
		(mid 379.78588 -232.967679)
		(end 379.598682 -233.017822)
		(width 0.088646)
		(layer "In11.Cu")
		(net "M_H_CPU0_SB_DQS_DP<1>")
	)
	(arc
		(start 374.334532 -233.017822)
		(mid 374.333132 -233.017066)
		(end 374.331738 -233.016298)
		(width 0.088646)
		(layer "In11.Cu")
		(net "M_H_CPU0_SB_DQS_DP<1>")
	)
	(arc
		(start 383.358136 -233.017822)
		(mid 383.075434 -233.093598)
		(end 382.792732 -233.017822)
		(width 0.088646)
		(layer "In11.Cu")
		(net "M_H_CPU0_SB_DQS_DP<1>")
	)
	(arc
		(start 379.58395 -233.026458)
		(mid 379.307475 -233.093778)
		(end 379.033278 -233.017822)
		(width 0.088646)
		(layer "In11.Cu")
		(net "M_H_CPU0_SB_DQS_DP<1>")
	)
	(arc
		(start 385.894834 -233.093768)
		(mid 385.748599 -233.074249)
		(end 385.612386 -233.017568)
		(width 0.088646)
		(layer "In11.Cu")
		(net "M_H_CPU0_SB_DQS_DP<1>")
	)
	(arc
		(start 371.239034 -232.614978)
		(mid 371.237537 -232.60445)
		(end 371.23624 -232.593896)
		(width 0.088646)
		(layer "In11.Cu")
		(net "M_H_CPU0_SB_DQS_DP<1>")
	)
	(arc
		(start 375.274078 -233.017822)
		(mid 375.08688 -232.967679)
		(end 374.899682 -233.017822)
		(width 0.088646)
		(layer "In11.Cu")
		(net "M_H_CPU0_SB_DQS_DP<1>")
	)
	(segment
		(start 459.011274 -228.766624)
		(end 458.729588 -228.484938)
		(width 0.20066)
		(layer "F.Cu")
		(net "M_H_CPU0_SB_DQS_DP<0>")
	)
	(segment
		(start 457.75245 -228.895402)
		(end 457.449936 -229.197916)
		(width 0.20066)
		(layer "F.Cu")
		(net "M_H_CPU0_SB_DQS_DP<0>")
	)
	(segment
		(start 458.5335 -228.484938)
		(end 458.123036 -228.895402)
		(width 0.20066)
		(layer "F.Cu")
		(net "M_H_CPU0_SB_DQS_DP<0>")
	)
	(segment
		(start 452.845932 -228.526086)
		(end 452.605394 -228.766624)
		(width 0.20066)
		(layer "F.Cu")
		(net "M_H_CPU0_SB_DQS_DP<0>")
	)
	(segment
		(start 452.605394 -228.766624)
		(end 452.016114 -228.766624)
		(width 0.20066)
		(layer "F.Cu")
		(net "M_H_CPU0_SB_DQS_DP<0>")
	)
	(segment
		(start 454.937368 -229.19182)
		(end 454.797922 -229.19182)
		(width 0.20066)
		(layer "F.Cu")
		(net "M_H_CPU0_SB_DQS_DP<0>")
	)
	(segment
		(start 370.85778 -237.947454)
		(end 370.85778 -237.411768)
		(width 0.20066)
		(layer "F.Cu")
		(net "M_H_CPU0_SB_DQS_DP<0>")
	)
	(segment
		(start 370.85778 -237.411768)
		(end 370.858034 -237.411514)
		(width 0.20066)
		(layer "F.Cu")
		(net "M_H_CPU0_SB_DQS_DP<0>")
	)
	(segment
		(start 457.126594 -229.197916)
		(end 457.120498 -229.19182)
		(width 0.1016)
		(layer "F.Cu")
		(net "M_H_CPU0_SB_DQS_DP<0>")
	)
	(segment
		(start 458.123036 -228.895402)
		(end 457.75245 -228.895402)
		(width 0.20066)
		(layer "F.Cu")
		(net "M_H_CPU0_SB_DQS_DP<0>")
	)
	(segment
		(start 453.860916 -228.940614)
		(end 453.446388 -228.526086)
		(width 0.20066)
		(layer "F.Cu")
		(net "M_H_CPU0_SB_DQS_DP<0>")
	)
	(segment
		(start 454.546716 -228.940614)
		(end 453.860916 -228.940614)
		(width 0.20066)
		(layer "F.Cu")
		(net "M_H_CPU0_SB_DQS_DP<0>")
	)
	(segment
		(start 457.449936 -229.197916)
		(end 457.126594 -229.197916)
		(width 0.20066)
		(layer "F.Cu")
		(net "M_H_CPU0_SB_DQS_DP<0>")
	)
	(segment
		(start 453.446388 -228.526086)
		(end 452.845932 -228.526086)
		(width 0.20066)
		(layer "F.Cu")
		(net "M_H_CPU0_SB_DQS_DP<0>")
	)
	(segment
		(start 457.120498 -229.19182)
		(end 454.963276 -229.19182)
		(width 0.1016)
		(layer "F.Cu")
		(net "M_H_CPU0_SB_DQS_DP<0>")
	)
	(segment
		(start 458.729588 -228.484938)
		(end 458.5335 -228.484938)
		(width 0.20066)
		(layer "F.Cu")
		(net "M_H_CPU0_SB_DQS_DP<0>")
	)
	(segment
		(start 450.911214 -228.766624)
		(end 452.016114 -228.766624)
		(width 0.20066)
		(layer "F.Cu")
		(net "M_H_CPU0_SB_DQS_DP<0>")
	)
	(segment
		(start 454.963276 -229.19182)
		(end 454.937368 -229.19182)
		(width 0.101854)
		(layer "F.Cu")
		(net "M_H_CPU0_SB_DQS_DP<0>")
	)
	(segment
		(start 454.797922 -229.19182)
		(end 454.546716 -228.940614)
		(width 0.20066)
		(layer "F.Cu")
		(net "M_H_CPU0_SB_DQS_DP<0>")
	)
	(segment
		(start 459.559914 -228.766624)
		(end 459.011274 -228.766624)
		(width 0.20066)
		(layer "F.Cu")
		(net "M_H_CPU0_SB_DQS_DP<0>")
	)
	(segment
		(start 435.350666 -223.810576)
		(end 431.773838 -223.810576)
		(width 0.18288)
		(layer "In11.Cu")
		(net "M_H_CPU0_SB_DQS_DP<0>")
	)
	(segment
		(start 420.240714 -225.528378)
		(end 416.80003 -225.528378)
		(width 0.18288)
		(layer "In11.Cu")
		(net "M_H_CPU0_SB_DQS_DP<0>")
	)
	(segment
		(start 443.113668 -226.332034)
		(end 442.20638 -225.424746)
		(width 0.18288)
		(layer "In11.Cu")
		(net "M_H_CPU0_SB_DQS_DP<0>")
	)
	(segment
		(start 421.228774 -225.526346)
		(end 420.964106 -225.791014)
		(width 0.18288)
		(layer "In11.Cu")
		(net "M_H_CPU0_SB_DQS_DP<0>")
	)
	(segment
		(start 411.753558 -225.704146)
		(end 411.081474 -226.37623)
		(width 0.18288)
		(layer "In11.Cu")
		(net "M_H_CPU0_SB_DQS_DP<0>")
	)
	(segment
		(start 440.151774 -224.940876)
		(end 439.671206 -224.940876)
		(width 0.18288)
		(layer "In11.Cu")
		(net "M_H_CPU0_SB_DQS_DP<0>")
	)
	(segment
		(start 426.498766 -224.053146)
		(end 425.875704 -224.676208)
		(width 0.18288)
		(layer "In11.Cu")
		(net "M_H_CPU0_SB_DQS_DP<0>")
	)
	(segment
		(start 409.532582 -226.640898)
		(end 409.255976 -226.364292)
		(width 0.18288)
		(layer "In11.Cu")
		(net "M_H_CPU0_SB_DQS_DP<0>")
	)
	(segment
		(start 438.868312 -224.702624)
		(end 438.574688 -224.409)
		(width 0.18288)
		(layer "In11.Cu")
		(net "M_H_CPU0_SB_DQS_DP<0>")
	)
	(segment
		(start 442.20638 -225.424746)
		(end 441.904882 -225.424746)
		(width 0.18288)
		(layer "In11.Cu")
		(net "M_H_CPU0_SB_DQS_DP<0>")
	)
	(segment
		(start 393.097258 -237.445804)
		(end 389.019796 -237.445804)
		(width 0.18288)
		(layer "In11.Cu")
		(net "M_H_CPU0_SB_DQS_DP<0>")
	)
	(segment
		(start 424.365166 -224.715324)
		(end 422.845484 -224.715324)
		(width 0.18288)
		(layer "In11.Cu")
		(net "M_H_CPU0_SB_DQS_DP<0>")
	)
	(segment
		(start 439.671206 -224.940876)
		(end 439.432954 -224.702624)
		(width 0.18288)
		(layer "In11.Cu")
		(net "M_H_CPU0_SB_DQS_DP<0>")
	)
	(segment
		(start 383.358136 -237.901226)
		(end 383.357882 -237.901226)
		(width 0.088646)
		(layer "In11.Cu")
		(net "M_H_CPU0_SB_DQS_DP<0>")
	)
	(segment
		(start 422.845484 -224.715324)
		(end 422.034462 -225.526346)
		(width 0.18288)
		(layer "In11.Cu")
		(net "M_H_CPU0_SB_DQS_DP<0>")
	)
	(segment
		(start 437.677814 -224.409)
		(end 437.095138 -223.826324)
		(width 0.18288)
		(layer "In11.Cu")
		(net "M_H_CPU0_SB_DQS_DP<0>")
	)
	(segment
		(start 406.849326 -227.226114)
		(end 406.103328 -227.226114)
		(width 0.18288)
		(layer "In11.Cu")
		(net "M_H_CPU0_SB_DQS_DP<0>")
	)
	(segment
		(start 388.450074 -237.38586)
		(end 387.985762 -237.850172)
		(width 0.088646)
		(layer "In11.Cu")
		(net "M_H_CPU0_SB_DQS_DP<0>")
	)
	(segment
		(start 370.858288 -237.411768)
		(end 370.858034 -237.411514)
		(width 0.088646)
		(layer "In11.Cu")
		(net "M_H_CPU0_SB_DQS_DP<0>")
	)
	(segment
		(start 443.596268 -226.332034)
		(end 443.113668 -226.332034)
		(width 0.18288)
		(layer "In11.Cu")
		(net "M_H_CPU0_SB_DQS_DP<0>")
	)
	(segment
		(start 371.515386 -237.901226)
		(end 371.391688 -237.83036)
		(width 0.088646)
		(layer "In11.Cu")
		(net "M_H_CPU0_SB_DQS_DP<0>")
	)
	(segment
		(start 431.099468 -224.484946)
		(end 427.654974 -224.484946)
		(width 0.18288)
		(layer "In11.Cu")
		(net "M_H_CPU0_SB_DQS_DP<0>")
	)
	(segment
		(start 412.437326 -225.704146)
		(end 411.753558 -225.704146)
		(width 0.18288)
		(layer "In11.Cu")
		(net "M_H_CPU0_SB_DQS_DP<0>")
	)
	(segment
		(start 427.223174 -224.053146)
		(end 426.498766 -224.053146)
		(width 0.18288)
		(layer "In11.Cu")
		(net "M_H_CPU0_SB_DQS_DP<0>")
	)
	(segment
		(start 425.875704 -224.676208)
		(end 425.328842 -224.676208)
		(width 0.18288)
		(layer "In11.Cu")
		(net "M_H_CPU0_SB_DQS_DP<0>")
	)
	(segment
		(start 420.964106 -225.791014)
		(end 420.50335 -225.791014)
		(width 0.18288)
		(layer "In11.Cu")
		(net "M_H_CPU0_SB_DQS_DP<0>")
	)
	(segment
		(start 422.034462 -225.526346)
		(end 421.228774 -225.526346)
		(width 0.18288)
		(layer "In11.Cu")
		(net "M_H_CPU0_SB_DQS_DP<0>")
	)
	(segment
		(start 380.927864 -237.909862)
		(end 380.913132 -237.901226)
		(width 0.088646)
		(layer "In11.Cu")
		(net "M_H_CPU0_SB_DQS_DP<0>")
	)
	(segment
		(start 388.959852 -237.38586)
		(end 388.450074 -237.38586)
		(width 0.088646)
		(layer "In11.Cu")
		(net "M_H_CPU0_SB_DQS_DP<0>")
	)
	(segment
		(start 371.163088 -237.498128)
		(end 371.16004 -237.49508)
		(width 0.088646)
		(layer "In11.Cu")
		(net "M_H_CPU0_SB_DQS_DP<0>")
	)
	(segment
		(start 425.064174 -224.940876)
		(end 424.590718 -224.940876)
		(width 0.18288)
		(layer "In11.Cu")
		(net "M_H_CPU0_SB_DQS_DP<0>")
	)
	(segment
		(start 441.904882 -225.424746)
		(end 441.156344 -224.676208)
		(width 0.18288)
		(layer "In11.Cu")
		(net "M_H_CPU0_SB_DQS_DP<0>")
	)
	(segment
		(start 411.081474 -226.37623)
		(end 410.249878 -226.37623)
		(width 0.18288)
		(layer "In11.Cu")
		(net "M_H_CPU0_SB_DQS_DP<0>")
	)
	(segment
		(start 410.249878 -226.37623)
		(end 409.98521 -226.640898)
		(width 0.18288)
		(layer "In11.Cu")
		(net "M_H_CPU0_SB_DQS_DP<0>")
	)
	(segment
		(start 435.631082 -224.090992)
		(end 435.350666 -223.810576)
		(width 0.18288)
		(layer "In11.Cu")
		(net "M_H_CPU0_SB_DQS_DP<0>")
	)
	(segment
		(start 450.645276 -228.500686)
		(end 450.201284 -228.500686)
		(width 0.18288)
		(layer "In11.Cu")
		(net "M_H_CPU0_SB_DQS_DP<0>")
	)
	(segment
		(start 436.051706 -224.090992)
		(end 435.631082 -224.090992)
		(width 0.18288)
		(layer "In11.Cu")
		(net "M_H_CPU0_SB_DQS_DP<0>")
	)
	(segment
		(start 445.343534 -228.0793)
		(end 443.596268 -226.332034)
		(width 0.18288)
		(layer "In11.Cu")
		(net "M_H_CPU0_SB_DQS_DP<0>")
	)
	(segment
		(start 416.80003 -225.528378)
		(end 416.16376 -226.164648)
		(width 0.18288)
		(layer "In11.Cu")
		(net "M_H_CPU0_SB_DQS_DP<0>")
	)
	(segment
		(start 438.574688 -224.409)
		(end 437.677814 -224.409)
		(width 0.18288)
		(layer "In11.Cu")
		(net "M_H_CPU0_SB_DQS_DP<0>")
	)
	(segment
		(start 412.897828 -226.164648)
		(end 412.437326 -225.704146)
		(width 0.18288)
		(layer "In11.Cu")
		(net "M_H_CPU0_SB_DQS_DP<0>")
	)
	(segment
		(start 382.792986 -237.901226)
		(end 382.792732 -237.901226)
		(width 0.088646)
		(layer "In11.Cu")
		(net "M_H_CPU0_SB_DQS_DP<0>")
	)
	(segment
		(start 441.156344 -224.676208)
		(end 440.416442 -224.676208)
		(width 0.18288)
		(layer "In11.Cu")
		(net "M_H_CPU0_SB_DQS_DP<0>")
	)
	(segment
		(start 389.019796 -237.445804)
		(end 388.959852 -237.38586)
		(width 0.088646)
		(layer "In11.Cu")
		(net "M_H_CPU0_SB_DQS_DP<0>")
	)
	(segment
		(start 406.103328 -227.226114)
		(end 405.840438 -227.489004)
		(width 0.18288)
		(layer "In11.Cu")
		(net "M_H_CPU0_SB_DQS_DP<0>")
	)
	(segment
		(start 440.416442 -224.676208)
		(end 440.151774 -224.940876)
		(width 0.18288)
		(layer "In11.Cu")
		(net "M_H_CPU0_SB_DQS_DP<0>")
	)
	(segment
		(start 449.779898 -228.0793)
		(end 445.343534 -228.0793)
		(width 0.18288)
		(layer "In11.Cu")
		(net "M_H_CPU0_SB_DQS_DP<0>")
	)
	(segment
		(start 416.16376 -226.164648)
		(end 412.897828 -226.164648)
		(width 0.18288)
		(layer "In11.Cu")
		(net "M_H_CPU0_SB_DQS_DP<0>")
	)
	(segment
		(start 409.255976 -226.364292)
		(end 407.711148 -226.364292)
		(width 0.18288)
		(layer "In11.Cu")
		(net "M_H_CPU0_SB_DQS_DP<0>")
	)
	(segment
		(start 424.590718 -224.940876)
		(end 424.365166 -224.715324)
		(width 0.18288)
		(layer "In11.Cu")
		(net "M_H_CPU0_SB_DQS_DP<0>")
	)
	(segment
		(start 373.020082 -237.901226)
		(end 373.00535 -237.909862)
		(width 0.088646)
		(layer "In11.Cu")
		(net "M_H_CPU0_SB_DQS_DP<0>")
	)
	(segment
		(start 450.201284 -228.500686)
		(end 449.779898 -228.0793)
		(width 0.18288)
		(layer "In11.Cu")
		(net "M_H_CPU0_SB_DQS_DP<0>")
	)
	(segment
		(start 436.316374 -223.826324)
		(end 436.051706 -224.090992)
		(width 0.18288)
		(layer "In11.Cu")
		(net "M_H_CPU0_SB_DQS_DP<0>")
	)
	(segment
		(start 387.985762 -237.850172)
		(end 386.364988 -237.850172)
		(width 0.088646)
		(layer "In11.Cu")
		(net "M_H_CPU0_SB_DQS_DP<0>")
	)
	(segment
		(start 403.328124 -227.214938)
		(end 393.097258 -237.445804)
		(width 0.18288)
		(layer "In11.Cu")
		(net "M_H_CPU0_SB_DQS_DP<0>")
	)
	(segment
		(start 380.538736 -237.901226)
		(end 380.528322 -237.907322)
		(width 0.088646)
		(layer "In11.Cu")
		(net "M_H_CPU0_SB_DQS_DP<0>")
	)
	(segment
		(start 371.16004 -237.4773)
		(end 371.094508 -237.411768)
		(width 0.088646)
		(layer "In11.Cu")
		(net "M_H_CPU0_SB_DQS_DP<0>")
	)
	(segment
		(start 374.899682 -237.901226)
		(end 374.889268 -237.907322)
		(width 0.088646)
		(layer "In11.Cu")
		(net "M_H_CPU0_SB_DQS_DP<0>")
	)
	(segment
		(start 405.840438 -227.489004)
		(end 405.43861 -227.489004)
		(width 0.18288)
		(layer "In11.Cu")
		(net "M_H_CPU0_SB_DQS_DP<0>")
	)
	(segment
		(start 437.095138 -223.826324)
		(end 436.316374 -223.826324)
		(width 0.18288)
		(layer "In11.Cu")
		(net "M_H_CPU0_SB_DQS_DP<0>")
	)
	(segment
		(start 427.654974 -224.484946)
		(end 427.223174 -224.053146)
		(width 0.18288)
		(layer "In11.Cu")
		(net "M_H_CPU0_SB_DQS_DP<0>")
	)
	(segment
		(start 371.16004 -237.49508)
		(end 371.16004 -237.4773)
		(width 0.088646)
		(layer "In11.Cu")
		(net "M_H_CPU0_SB_DQS_DP<0>")
	)
	(segment
		(start 409.98521 -226.640898)
		(end 409.532582 -226.640898)
		(width 0.18288)
		(layer "In11.Cu")
		(net "M_H_CPU0_SB_DQS_DP<0>")
	)
	(segment
		(start 375.839482 -237.901226)
		(end 375.82475 -237.909862)
		(width 0.088646)
		(layer "In11.Cu")
		(net "M_H_CPU0_SB_DQS_DP<0>")
	)
	(segment
		(start 431.773838 -223.810576)
		(end 431.099468 -224.484946)
		(width 0.18288)
		(layer "In11.Cu")
		(net "M_H_CPU0_SB_DQS_DP<0>")
	)
	(segment
		(start 371.094508 -237.411768)
		(end 370.858288 -237.411768)
		(width 0.088646)
		(layer "In11.Cu")
		(net "M_H_CPU0_SB_DQS_DP<0>")
	)
	(segment
		(start 405.164544 -227.214938)
		(end 403.328124 -227.214938)
		(width 0.18288)
		(layer "In11.Cu")
		(net "M_H_CPU0_SB_DQS_DP<0>")
	)
	(segment
		(start 377.719082 -237.901226)
		(end 377.70435 -237.909862)
		(width 0.088646)
		(layer "In11.Cu")
		(net "M_H_CPU0_SB_DQS_DP<0>")
	)
	(segment
		(start 373.960136 -237.901226)
		(end 373.949722 -237.907322)
		(width 0.088646)
		(layer "In11.Cu")
		(net "M_H_CPU0_SB_DQS_DP<0>")
	)
	(segment
		(start 407.711148 -226.364292)
		(end 406.849326 -227.226114)
		(width 0.18288)
		(layer "In11.Cu")
		(net "M_H_CPU0_SB_DQS_DP<0>")
	)
	(segment
		(start 379.598682 -237.901226)
		(end 379.58395 -237.909862)
		(width 0.088646)
		(layer "In11.Cu")
		(net "M_H_CPU0_SB_DQS_DP<0>")
	)
	(segment
		(start 405.43861 -227.489004)
		(end 405.164544 -227.214938)
		(width 0.18288)
		(layer "In11.Cu")
		(net "M_H_CPU0_SB_DQS_DP<0>")
	)
	(segment
		(start 450.911214 -228.766624)
		(end 450.645276 -228.500686)
		(width 0.18288)
		(layer "In11.Cu")
		(net "M_H_CPU0_SB_DQS_DP<0>")
	)
	(segment
		(start 420.50335 -225.791014)
		(end 420.240714 -225.528378)
		(width 0.18288)
		(layer "In11.Cu")
		(net "M_H_CPU0_SB_DQS_DP<0>")
	)
	(segment
		(start 425.328842 -224.676208)
		(end 425.064174 -224.940876)
		(width 0.18288)
		(layer "In11.Cu")
		(net "M_H_CPU0_SB_DQS_DP<0>")
	)
	(segment
		(start 439.432954 -224.702624)
		(end 438.868312 -224.702624)
		(width 0.18288)
		(layer "In11.Cu")
		(net "M_H_CPU0_SB_DQS_DP<0>")
	)
	(segment
		(start 378.658882 -237.901226)
		(end 378.64415 -237.909862)
		(width 0.088646)
		(layer "In11.Cu")
		(net "M_H_CPU0_SB_DQS_DP<0>")
	)
	(segment
		(start 376.779282 -237.901226)
		(end 376.76455 -237.909862)
		(width 0.088646)
		(layer "In11.Cu")
		(net "M_H_CPU0_SB_DQS_DP<0>")
	)
	(arc
		(start 373.00535 -237.909862)
		(mid 372.728875 -237.977182)
		(end 372.454678 -237.901226)
		(width 0.088646)
		(layer "In11.Cu")
		(net "M_H_CPU0_SB_DQS_DP<0>")
	)
	(arc
		(start 381.478536 -237.901226)
		(mid 381.204337 -237.977061)
		(end 380.927864 -237.909862)
		(width 0.088646)
		(layer "In11.Cu")
		(net "M_H_CPU0_SB_DQS_DP<0>")
	)
	(arc
		(start 373.394478 -237.901226)
		(mid 373.20728 -237.851083)
		(end 373.020082 -237.901226)
		(width 0.088646)
		(layer "In11.Cu")
		(net "M_H_CPU0_SB_DQS_DP<0>")
	)
	(arc
		(start 382.418336 -237.901226)
		(mid 382.135634 -237.977002)
		(end 381.852932 -237.901226)
		(width 0.088646)
		(layer "In11.Cu")
		(net "M_H_CPU0_SB_DQS_DP<0>")
	)
	(arc
		(start 386.177536 -237.901226)
		(mid 385.894834 -237.976968)
		(end 385.612132 -237.901226)
		(width 0.088646)
		(layer "In11.Cu")
		(net "M_H_CPU0_SB_DQS_DP<0>")
	)
	(arc
		(start 383.357882 -237.901226)
		(mid 383.075434 -237.976875)
		(end 382.792986 -237.901226)
		(width 0.088646)
		(layer "In11.Cu")
		(net "M_H_CPU0_SB_DQS_DP<0>")
	)
	(arc
		(start 376.213878 -237.901226)
		(mid 376.02668 -237.851083)
		(end 375.839482 -237.901226)
		(width 0.088646)
		(layer "In11.Cu")
		(net "M_H_CPU0_SB_DQS_DP<0>")
	)
	(arc
		(start 378.64415 -237.909862)
		(mid 378.367675 -237.977182)
		(end 378.093478 -237.901226)
		(width 0.088646)
		(layer "In11.Cu")
		(net "M_H_CPU0_SB_DQS_DP<0>")
	)
	(arc
		(start 380.913132 -237.901226)
		(mid 380.725934 -237.851083)
		(end 380.538736 -237.901226)
		(width 0.088646)
		(layer "In11.Cu")
		(net "M_H_CPU0_SB_DQS_DP<0>")
	)
	(arc
		(start 375.274078 -237.901226)
		(mid 375.08688 -237.851083)
		(end 374.899682 -237.901226)
		(width 0.088646)
		(layer "In11.Cu")
		(net "M_H_CPU0_SB_DQS_DP<0>")
	)
	(arc
		(start 377.153678 -237.901226)
		(mid 376.96648 -237.851083)
		(end 376.779282 -237.901226)
		(width 0.088646)
		(layer "In11.Cu")
		(net "M_H_CPU0_SB_DQS_DP<0>")
	)
	(arc
		(start 379.033278 -237.901226)
		(mid 378.84608 -237.851083)
		(end 378.658882 -237.901226)
		(width 0.088646)
		(layer "In11.Cu")
		(net "M_H_CPU0_SB_DQS_DP<0>")
	)
	(arc
		(start 376.76455 -237.909862)
		(mid 376.488075 -237.977182)
		(end 376.213878 -237.901226)
		(width 0.088646)
		(layer "In11.Cu")
		(net "M_H_CPU0_SB_DQS_DP<0>")
	)
	(arc
		(start 374.889268 -237.907322)
		(mid 374.61109 -237.977014)
		(end 374.334532 -237.901226)
		(width 0.088646)
		(layer "In11.Cu")
		(net "M_H_CPU0_SB_DQS_DP<0>")
	)
	(arc
		(start 383.732532 -237.901226)
		(mid 383.545334 -237.851083)
		(end 383.358136 -237.901226)
		(width 0.088646)
		(layer "In11.Cu")
		(net "M_H_CPU0_SB_DQS_DP<0>")
	)
	(arc
		(start 372.454678 -237.901226)
		(mid 372.26748 -237.851083)
		(end 372.080282 -237.901226)
		(width 0.088646)
		(layer "In11.Cu")
		(net "M_H_CPU0_SB_DQS_DP<0>")
	)
	(arc
		(start 377.70435 -237.909862)
		(mid 377.427875 -237.977182)
		(end 377.153678 -237.901226)
		(width 0.088646)
		(layer "In11.Cu")
		(net "M_H_CPU0_SB_DQS_DP<0>")
	)
	(arc
		(start 384.297936 -237.901226)
		(mid 384.015234 -237.976968)
		(end 383.732532 -237.901226)
		(width 0.088646)
		(layer "In11.Cu")
		(net "M_H_CPU0_SB_DQS_DP<0>")
	)
	(arc
		(start 381.852932 -237.901226)
		(mid 381.665734 -237.851083)
		(end 381.478536 -237.901226)
		(width 0.088646)
		(layer "In11.Cu")
		(net "M_H_CPU0_SB_DQS_DP<0>")
	)
	(arc
		(start 382.792732 -237.901226)
		(mid 382.605534 -237.851083)
		(end 382.418336 -237.901226)
		(width 0.088646)
		(layer "In11.Cu")
		(net "M_H_CPU0_SB_DQS_DP<0>")
	)
	(arc
		(start 378.093478 -237.901226)
		(mid 377.90628 -237.851083)
		(end 377.719082 -237.901226)
		(width 0.088646)
		(layer "In11.Cu")
		(net "M_H_CPU0_SB_DQS_DP<0>")
	)
	(arc
		(start 373.949722 -237.907322)
		(mid 373.67129 -237.977168)
		(end 373.394478 -237.901226)
		(width 0.088646)
		(layer "In11.Cu")
		(net "M_H_CPU0_SB_DQS_DP<0>")
	)
	(arc
		(start 385.612132 -237.901226)
		(mid 385.424934 -237.851083)
		(end 385.237736 -237.901226)
		(width 0.088646)
		(layer "In11.Cu")
		(net "M_H_CPU0_SB_DQS_DP<0>")
	)
	(arc
		(start 372.080282 -237.901226)
		(mid 371.797834 -237.976875)
		(end 371.515386 -237.901226)
		(width 0.088646)
		(layer "In11.Cu")
		(net "M_H_CPU0_SB_DQS_DP<0>")
	)
	(arc
		(start 384.672332 -237.901226)
		(mid 384.485134 -237.851083)
		(end 384.297936 -237.901226)
		(width 0.088646)
		(layer "In11.Cu")
		(net "M_H_CPU0_SB_DQS_DP<0>")
	)
	(arc
		(start 374.334532 -237.901226)
		(mid 374.147334 -237.851083)
		(end 373.960136 -237.901226)
		(width 0.088646)
		(layer "In11.Cu")
		(net "M_H_CPU0_SB_DQS_DP<0>")
	)
	(arc
		(start 385.237736 -237.901226)
		(mid 384.955034 -237.976968)
		(end 384.672332 -237.901226)
		(width 0.088646)
		(layer "In11.Cu")
		(net "M_H_CPU0_SB_DQS_DP<0>")
	)
	(arc
		(start 386.364988 -237.850172)
		(mid 386.267907 -237.863368)
		(end 386.177536 -237.901226)
		(width 0.088646)
		(layer "In11.Cu")
		(net "M_H_CPU0_SB_DQS_DP<0>")
	)
	(arc
		(start 379.58395 -237.909862)
		(mid 379.307475 -237.977182)
		(end 379.033278 -237.901226)
		(width 0.088646)
		(layer "In11.Cu")
		(net "M_H_CPU0_SB_DQS_DP<0>")
	)
	(arc
		(start 371.391688 -237.83036)
		(mid 371.239424 -237.690367)
		(end 371.163088 -237.498128)
		(width 0.088646)
		(layer "In11.Cu")
		(net "M_H_CPU0_SB_DQS_DP<0>")
	)
	(arc
		(start 379.973078 -237.901226)
		(mid 379.78588 -237.851083)
		(end 379.598682 -237.901226)
		(width 0.088646)
		(layer "In11.Cu")
		(net "M_H_CPU0_SB_DQS_DP<0>")
	)
	(arc
		(start 380.528322 -237.907322)
		(mid 380.24989 -237.977168)
		(end 379.973078 -237.901226)
		(width 0.088646)
		(layer "In11.Cu")
		(net "M_H_CPU0_SB_DQS_DP<0>")
	)
	(arc
		(start 375.82475 -237.909862)
		(mid 375.548275 -237.977182)
		(end 375.274078 -237.901226)
		(width 0.088646)
		(layer "In11.Cu")
		(net "M_H_CPU0_SB_DQS_DP<0>")
	)
	(segment
		(start 458.970634 -237.266734)
		(end 458.730096 -237.507272)
		(width 0.20066)
		(layer "F.Cu")
		(net "M_H_CPU0_SB_DQS_DN<9>")
	)
	(segment
		(start 457.12126 -237.691676)
		(end 454.941686 -237.691676)
		(width 0.1016)
		(layer "F.Cu")
		(net "M_H_CPU0_SB_DQS_DN<9>")
	)
	(segment
		(start 457.987146 -237.917736)
		(end 457.682092 -237.917736)
		(width 0.20066)
		(layer "F.Cu")
		(net "M_H_CPU0_SB_DQS_DN<9>")
	)
	(segment
		(start 454.941686 -237.691676)
		(end 454.937368 -237.691676)
		(width 0.101854)
		(layer "F.Cu")
		(net "M_H_CPU0_SB_DQS_DN<9>")
	)
	(segment
		(start 457.682092 -237.917736)
		(end 457.450698 -237.686342)
		(width 0.20066)
		(layer "F.Cu")
		(net "M_H_CPU0_SB_DQS_DN<9>")
	)
	(segment
		(start 450.911214 -237.266734)
		(end 452.016114 -237.266734)
		(width 0.20066)
		(layer "F.Cu")
		(net "M_H_CPU0_SB_DQS_DN<9>")
	)
	(segment
		(start 454.789794 -237.691676)
		(end 454.518522 -237.962948)
		(width 0.20066)
		(layer "F.Cu")
		(net "M_H_CPU0_SB_DQS_DN<9>")
	)
	(segment
		(start 453.582278 -237.54842)
		(end 452.84644 -237.54842)
		(width 0.20066)
		(layer "F.Cu")
		(net "M_H_CPU0_SB_DQS_DN<9>")
	)
	(segment
		(start 371.797834 -242.830604)
		(end 371.797834 -242.294918)
		(width 0.20066)
		(layer "F.Cu")
		(net "M_H_CPU0_SB_DQS_DN<9>")
	)
	(segment
		(start 454.518522 -237.962948)
		(end 453.996806 -237.962948)
		(width 0.20066)
		(layer "F.Cu")
		(net "M_H_CPU0_SB_DQS_DN<9>")
	)
	(segment
		(start 452.564754 -237.266734)
		(end 452.016114 -237.266734)
		(width 0.20066)
		(layer "F.Cu")
		(net "M_H_CPU0_SB_DQS_DN<9>")
	)
	(segment
		(start 454.937368 -237.691676)
		(end 454.789794 -237.691676)
		(width 0.20066)
		(layer "F.Cu")
		(net "M_H_CPU0_SB_DQS_DN<9>")
	)
	(segment
		(start 459.559914 -237.266734)
		(end 458.970634 -237.266734)
		(width 0.20066)
		(layer "F.Cu")
		(net "M_H_CPU0_SB_DQS_DN<9>")
	)
	(segment
		(start 457.126594 -237.686342)
		(end 457.12126 -237.691676)
		(width 0.1016)
		(layer "F.Cu")
		(net "M_H_CPU0_SB_DQS_DN<9>")
	)
	(segment
		(start 371.79758 -242.830858)
		(end 371.797834 -242.830604)
		(width 0.20066)
		(layer "F.Cu")
		(net "M_H_CPU0_SB_DQS_DN<9>")
	)
	(segment
		(start 452.84644 -237.54842)
		(end 452.564754 -237.266734)
		(width 0.20066)
		(layer "F.Cu")
		(net "M_H_CPU0_SB_DQS_DN<9>")
	)
	(segment
		(start 458.39761 -237.507272)
		(end 457.987146 -237.917736)
		(width 0.20066)
		(layer "F.Cu")
		(net "M_H_CPU0_SB_DQS_DN<9>")
	)
	(segment
		(start 458.730096 -237.507272)
		(end 458.39761 -237.507272)
		(width 0.20066)
		(layer "F.Cu")
		(net "M_H_CPU0_SB_DQS_DN<9>")
	)
	(segment
		(start 457.450698 -237.686342)
		(end 457.126594 -237.686342)
		(width 0.20066)
		(layer "F.Cu")
		(net "M_H_CPU0_SB_DQS_DN<9>")
	)
	(segment
		(start 453.996806 -237.962948)
		(end 453.582278 -237.54842)
		(width 0.20066)
		(layer "F.Cu")
		(net "M_H_CPU0_SB_DQS_DN<9>")
	)
	(segment
		(start 420.934642 -235.991146)
		(end 420.492174 -235.991146)
		(width 0.18288)
		(layer "In11.Cu")
		(net "M_H_CPU0_SB_DQS_DN<9>")
	)
	(segment
		(start 435.55539 -235.990638)
		(end 435.275482 -236.270546)
		(width 0.18288)
		(layer "In11.Cu")
		(net "M_H_CPU0_SB_DQS_DN<9>")
	)
	(segment
		(start 420.20109 -236.28223)
		(end 416.385756 -236.28223)
		(width 0.18288)
		(layer "In11.Cu")
		(net "M_H_CPU0_SB_DQS_DN<9>")
	)
	(segment
		(start 441.162948 -237.966504)
		(end 440.408314 -237.966504)
		(width 0.18288)
		(layer "In11.Cu")
		(net "M_H_CPU0_SB_DQS_DN<9>")
	)
	(segment
		(start 421.209978 -236.266482)
		(end 420.934642 -235.991146)
		(width 0.18288)
		(layer "In11.Cu")
		(net "M_H_CPU0_SB_DQS_DN<9>")
	)
	(segment
		(start 439.42254 -237.924086)
		(end 438.511188 -237.924086)
		(width 0.18288)
		(layer "In11.Cu")
		(net "M_H_CPU0_SB_DQS_DN<9>")
	)
	(segment
		(start 447.868802 -237.36808)
		(end 447.167762 -237.078266)
		(width 0.18288)
		(layer "In11.Cu")
		(net "M_H_CPU0_SB_DQS_DN<9>")
	)
	(segment
		(start 413.632904 -236.982254)
		(end 411.89148 -236.982254)
		(width 0.18288)
		(layer "In11.Cu")
		(net "M_H_CPU0_SB_DQS_DN<9>")
	)
	(segment
		(start 414.430464 -236.982254)
		(end 414.306004 -236.857794)
		(width 0.18288)
		(layer "In11.Cu")
		(net "M_H_CPU0_SB_DQS_DN<9>")
	)
	(segment
		(start 438.511188 -237.924086)
		(end 436.853076 -236.265974)
		(width 0.18288)
		(layer "In11.Cu")
		(net "M_H_CPU0_SB_DQS_DN<9>")
	)
	(segment
		(start 425.328334 -235.416598)
		(end 425.052998 -235.141262)
		(width 0.18288)
		(layer "In11.Cu")
		(net "M_H_CPU0_SB_DQS_DN<9>")
	)
	(segment
		(start 378.578364 -242.61064)
		(end 378.563632 -242.619276)
		(width 0.088646)
		(layer "In11.Cu")
		(net "M_H_CPU0_SB_DQS_DN<9>")
	)
	(segment
		(start 372.939564 -242.610894)
		(end 372.924832 -242.61953)
		(width 0.088646)
		(layer "In11.Cu")
		(net "M_H_CPU0_SB_DQS_DN<9>")
	)
	(segment
		(start 416.385756 -236.28223)
		(end 415.685732 -236.982254)
		(width 0.18288)
		(layer "In11.Cu")
		(net "M_H_CPU0_SB_DQS_DN<9>")
	)
	(segment
		(start 400.83232 -238.196374)
		(end 395.87805 -243.150644)
		(width 0.18288)
		(layer "In11.Cu")
		(net "M_H_CPU0_SB_DQS_DN<9>")
	)
	(segment
		(start 431.693066 -235.565696)
		(end 427.678342 -235.565696)
		(width 0.18288)
		(layer "In11.Cu")
		(net "M_H_CPU0_SB_DQS_DN<9>")
	)
	(segment
		(start 450.312028 -237.54969)
		(end 450.130418 -237.36808)
		(width 0.18288)
		(layer "In11.Cu")
		(net "M_H_CPU0_SB_DQS_DN<9>")
	)
	(segment
		(start 436.853076 -236.265974)
		(end 436.29199 -236.265974)
		(width 0.18288)
		(layer "In11.Cu")
		(net "M_H_CPU0_SB_DQS_DN<9>")
	)
	(segment
		(start 385.386072 -243.210334)
		(end 384.884676 -242.708684)
		(width 0.088646)
		(layer "In11.Cu")
		(net "M_H_CPU0_SB_DQS_DN<9>")
	)
	(segment
		(start 376.698764 -242.61064)
		(end 376.684032 -242.619276)
		(width 0.088646)
		(layer "In11.Cu")
		(net "M_H_CPU0_SB_DQS_DN<9>")
	)
	(segment
		(start 411.76702 -236.857794)
		(end 411.21838 -236.857794)
		(width 0.18288)
		(layer "In11.Cu")
		(net "M_H_CPU0_SB_DQS_DN<9>")
	)
	(segment
		(start 388.960106 -243.210334)
		(end 385.386072 -243.210334)
		(width 0.088646)
		(layer "In11.Cu")
		(net "M_H_CPU0_SB_DQS_DN<9>")
	)
	(segment
		(start 425.052998 -235.141262)
		(end 424.623738 -235.141262)
		(width 0.18288)
		(layer "In11.Cu")
		(net "M_H_CPU0_SB_DQS_DN<9>")
	)
	(segment
		(start 371.427756 -242.352322)
		(end 371.48516 -242.294918)
		(width 0.088646)
		(layer "In11.Cu")
		(net "M_H_CPU0_SB_DQS_DN<9>")
	)
	(segment
		(start 408.01163 -236.982254)
		(end 406.79751 -238.196374)
		(width 0.18288)
		(layer "In11.Cu")
		(net "M_H_CPU0_SB_DQS_DN<9>")
	)
	(segment
		(start 422.134284 -236.266482)
		(end 421.209978 -236.266482)
		(width 0.18288)
		(layer "In11.Cu")
		(net "M_H_CPU0_SB_DQS_DN<9>")
	)
	(segment
		(start 374.814592 -242.613434)
		(end 374.804178 -242.61953)
		(width 0.088646)
		(layer "In11.Cu")
		(net "M_H_CPU0_SB_DQS_DN<9>")
	)
	(segment
		(start 423.011092 -235.389674)
		(end 422.134284 -236.266482)
		(width 0.18288)
		(layer "In11.Cu")
		(net "M_H_CPU0_SB_DQS_DN<9>")
	)
	(segment
		(start 436.29199 -236.265974)
		(end 436.016654 -235.990638)
		(width 0.18288)
		(layer "In11.Cu")
		(net "M_H_CPU0_SB_DQS_DN<9>")
	)
	(segment
		(start 415.685732 -236.982254)
		(end 414.430464 -236.982254)
		(width 0.18288)
		(layer "In11.Cu")
		(net "M_H_CPU0_SB_DQS_DN<9>")
	)
	(segment
		(start 377.638564 -242.61064)
		(end 377.623832 -242.619276)
		(width 0.088646)
		(layer "In11.Cu")
		(net "M_H_CPU0_SB_DQS_DN<9>")
	)
	(segment
		(start 371.610636 -242.619276)
		(end 371.601746 -242.614196)
		(width 0.088646)
		(layer "In11.Cu")
		(net "M_H_CPU0_SB_DQS_DN<9>")
	)
	(segment
		(start 436.016654 -235.990638)
		(end 435.55539 -235.990638)
		(width 0.18288)
		(layer "In11.Cu")
		(net "M_H_CPU0_SB_DQS_DN<9>")
	)
	(segment
		(start 426.762672 -236.043978)
		(end 426.135292 -235.416598)
		(width 0.18288)
		(layer "In11.Cu")
		(net "M_H_CPU0_SB_DQS_DN<9>")
	)
	(segment
		(start 395.87805 -243.150644)
		(end 389.019796 -243.150644)
		(width 0.18288)
		(layer "In11.Cu")
		(net "M_H_CPU0_SB_DQS_DN<9>")
	)
	(segment
		(start 450.628258 -237.54969)
		(end 450.312028 -237.54969)
		(width 0.18288)
		(layer "In11.Cu")
		(net "M_H_CPU0_SB_DQS_DN<9>")
	)
	(segment
		(start 411.21838 -236.857794)
		(end 411.09392 -236.982254)
		(width 0.18288)
		(layer "In11.Cu")
		(net "M_H_CPU0_SB_DQS_DN<9>")
	)
	(segment
		(start 442.051186 -237.078266)
		(end 441.162948 -237.966504)
		(width 0.18288)
		(layer "In11.Cu")
		(net "M_H_CPU0_SB_DQS_DN<9>")
	)
	(segment
		(start 382.337564 -242.61064)
		(end 382.322832 -242.619276)
		(width 0.088646)
		(layer "In11.Cu")
		(net "M_H_CPU0_SB_DQS_DN<9>")
	)
	(segment
		(start 424.375326 -235.389674)
		(end 423.011092 -235.389674)
		(width 0.18288)
		(layer "In11.Cu")
		(net "M_H_CPU0_SB_DQS_DN<9>")
	)
	(segment
		(start 447.167762 -237.078266)
		(end 442.051186 -237.078266)
		(width 0.18288)
		(layer "In11.Cu")
		(net "M_H_CPU0_SB_DQS_DN<9>")
	)
	(segment
		(start 432.397916 -236.270546)
		(end 431.693066 -235.565696)
		(width 0.18288)
		(layer "In11.Cu")
		(net "M_H_CPU0_SB_DQS_DN<9>")
	)
	(segment
		(start 427.678342 -235.565696)
		(end 427.20006 -236.043978)
		(width 0.18288)
		(layer "In11.Cu")
		(net "M_H_CPU0_SB_DQS_DN<9>")
	)
	(segment
		(start 426.135292 -235.416598)
		(end 425.328334 -235.416598)
		(width 0.18288)
		(layer "In11.Cu")
		(net "M_H_CPU0_SB_DQS_DN<9>")
	)
	(segment
		(start 424.623738 -235.141262)
		(end 424.375326 -235.389674)
		(width 0.18288)
		(layer "In11.Cu")
		(net "M_H_CPU0_SB_DQS_DN<9>")
	)
	(segment
		(start 414.306004 -236.857794)
		(end 413.757364 -236.857794)
		(width 0.18288)
		(layer "In11.Cu")
		(net "M_H_CPU0_SB_DQS_DN<9>")
	)
	(segment
		(start 440.408314 -237.966504)
		(end 440.132978 -237.691168)
		(width 0.18288)
		(layer "In11.Cu")
		(net "M_H_CPU0_SB_DQS_DN<9>")
	)
	(segment
		(start 374.429782 -242.61953)
		(end 374.419368 -242.613434)
		(width 0.088646)
		(layer "In11.Cu")
		(net "M_H_CPU0_SB_DQS_DN<9>")
	)
	(segment
		(start 440.132978 -237.691168)
		(end 439.655458 -237.691168)
		(width 0.18288)
		(layer "In11.Cu")
		(net "M_H_CPU0_SB_DQS_DN<9>")
	)
	(segment
		(start 435.275482 -236.270546)
		(end 432.397916 -236.270546)
		(width 0.18288)
		(layer "In11.Cu")
		(net "M_H_CPU0_SB_DQS_DN<9>")
	)
	(segment
		(start 406.79751 -238.196374)
		(end 400.83232 -238.196374)
		(width 0.18288)
		(layer "In11.Cu")
		(net "M_H_CPU0_SB_DQS_DN<9>")
	)
	(segment
		(start 411.09392 -236.982254)
		(end 408.01163 -236.982254)
		(width 0.18288)
		(layer "In11.Cu")
		(net "M_H_CPU0_SB_DQS_DN<9>")
	)
	(segment
		(start 411.89148 -236.982254)
		(end 411.76702 -236.857794)
		(width 0.18288)
		(layer "In11.Cu")
		(net "M_H_CPU0_SB_DQS_DN<9>")
	)
	(segment
		(start 450.911214 -237.266734)
		(end 450.628258 -237.54969)
		(width 0.18288)
		(layer "In11.Cu")
		(net "M_H_CPU0_SB_DQS_DN<9>")
	)
	(segment
		(start 427.20006 -236.043978)
		(end 426.762672 -236.043978)
		(width 0.18288)
		(layer "In11.Cu")
		(net "M_H_CPU0_SB_DQS_DN<9>")
	)
	(segment
		(start 375.758964 -242.61064)
		(end 375.744232 -242.619276)
		(width 0.088646)
		(layer "In11.Cu")
		(net "M_H_CPU0_SB_DQS_DN<9>")
	)
	(segment
		(start 439.655458 -237.691168)
		(end 439.42254 -237.924086)
		(width 0.18288)
		(layer "In11.Cu")
		(net "M_H_CPU0_SB_DQS_DN<9>")
	)
	(segment
		(start 379.518164 -242.61064)
		(end 379.503432 -242.619276)
		(width 0.088646)
		(layer "In11.Cu")
		(net "M_H_CPU0_SB_DQS_DN<9>")
	)
	(segment
		(start 450.130418 -237.36808)
		(end 447.868802 -237.36808)
		(width 0.18288)
		(layer "In11.Cu")
		(net "M_H_CPU0_SB_DQS_DN<9>")
	)
	(segment
		(start 420.492174 -235.991146)
		(end 420.20109 -236.28223)
		(width 0.18288)
		(layer "In11.Cu")
		(net "M_H_CPU0_SB_DQS_DN<9>")
	)
	(segment
		(start 371.48516 -242.294918)
		(end 371.797834 -242.294918)
		(width 0.088646)
		(layer "In11.Cu")
		(net "M_H_CPU0_SB_DQS_DN<9>")
	)
	(segment
		(start 413.757364 -236.857794)
		(end 413.632904 -236.982254)
		(width 0.18288)
		(layer "In11.Cu")
		(net "M_H_CPU0_SB_DQS_DN<9>")
	)
	(segment
		(start 389.019796 -243.150644)
		(end 388.960106 -243.210334)
		(width 0.088646)
		(layer "In11.Cu")
		(net "M_H_CPU0_SB_DQS_DN<9>")
	)
	(arc
		(start 373.490236 -242.61953)
		(mid 373.216037 -242.543695)
		(end 372.939564 -242.610894)
		(width 0.088646)
		(layer "In11.Cu")
		(net "M_H_CPU0_SB_DQS_DN<9>")
	)
	(arc
		(start 375.369836 -242.61953)
		(mid 375.093023 -242.54366)
		(end 374.814592 -242.613434)
		(width 0.088646)
		(layer "In11.Cu")
		(net "M_H_CPU0_SB_DQS_DN<9>")
	)
	(arc
		(start 378.189236 -242.619276)
		(mid 377.915007 -242.543351)
		(end 377.638564 -242.61064)
		(width 0.088646)
		(layer "In11.Cu")
		(net "M_H_CPU0_SB_DQS_DN<9>")
	)
	(arc
		(start 380.068836 -242.619276)
		(mid 379.794607 -242.543351)
		(end 379.518164 -242.61064)
		(width 0.088646)
		(layer "In11.Cu")
		(net "M_H_CPU0_SB_DQS_DN<9>")
	)
	(arc
		(start 381.383032 -242.619276)
		(mid 381.195834 -242.669419)
		(end 381.008636 -242.619276)
		(width 0.088646)
		(layer "In11.Cu")
		(net "M_H_CPU0_SB_DQS_DN<9>")
	)
	(arc
		(start 377.249436 -242.619276)
		(mid 376.975207 -242.543351)
		(end 376.698764 -242.61064)
		(width 0.088646)
		(layer "In11.Cu")
		(net "M_H_CPU0_SB_DQS_DN<9>")
	)
	(arc
		(start 374.804178 -242.61953)
		(mid 374.61698 -242.669673)
		(end 374.429782 -242.61953)
		(width 0.088646)
		(layer "In11.Cu")
		(net "M_H_CPU0_SB_DQS_DN<9>")
	)
	(arc
		(start 376.684032 -242.619276)
		(mid 376.496834 -242.669419)
		(end 376.309636 -242.619276)
		(width 0.088646)
		(layer "In11.Cu")
		(net "M_H_CPU0_SB_DQS_DN<9>")
	)
	(arc
		(start 373.864632 -242.61953)
		(mid 373.677434 -242.669673)
		(end 373.490236 -242.61953)
		(width 0.088646)
		(layer "In11.Cu")
		(net "M_H_CPU0_SB_DQS_DN<9>")
	)
	(arc
		(start 383.262632 -242.619276)
		(mid 383.075434 -242.669419)
		(end 382.888236 -242.619276)
		(width 0.088646)
		(layer "In11.Cu")
		(net "M_H_CPU0_SB_DQS_DN<9>")
	)
	(arc
		(start 384.884676 -242.708684)
		(mid 384.872775 -242.697206)
		(end 384.860546 -242.686078)
		(width 0.088646)
		(layer "In11.Cu")
		(net "M_H_CPU0_SB_DQS_DN<9>")
	)
	(arc
		(start 381.008636 -242.619276)
		(mid 380.725934 -242.543534)
		(end 380.443232 -242.619276)
		(width 0.088646)
		(layer "In11.Cu")
		(net "M_H_CPU0_SB_DQS_DN<9>")
	)
	(arc
		(start 379.503432 -242.619276)
		(mid 379.316234 -242.669419)
		(end 379.129036 -242.619276)
		(width 0.088646)
		(layer "In11.Cu")
		(net "M_H_CPU0_SB_DQS_DN<9>")
	)
	(arc
		(start 384.202432 -242.619276)
		(mid 384.015234 -242.669419)
		(end 383.828036 -242.619276)
		(width 0.088646)
		(layer "In11.Cu")
		(net "M_H_CPU0_SB_DQS_DN<9>")
	)
	(arc
		(start 371.975126 -242.624864)
		(mid 371.889237 -242.658097)
		(end 371.797834 -242.669314)
		(width 0.088646)
		(layer "In11.Cu")
		(net "M_H_CPU0_SB_DQS_DN<9>")
	)
	(arc
		(start 372.924832 -242.61953)
		(mid 372.737634 -242.669673)
		(end 372.550436 -242.61953)
		(width 0.088646)
		(layer "In11.Cu")
		(net "M_H_CPU0_SB_DQS_DN<9>")
	)
	(arc
		(start 375.744232 -242.619276)
		(mid 375.557063 -242.670167)
		(end 375.369836 -242.61953)
		(width 0.088646)
		(layer "In11.Cu")
		(net "M_H_CPU0_SB_DQS_DN<9>")
	)
	(arc
		(start 371.999764 -242.610894)
		(mid 371.996217 -242.612815)
		(end 371.992652 -242.614704)
		(width 0.088646)
		(layer "In11.Cu")
		(net "M_H_CPU0_SB_DQS_DN<9>")
	)
	(arc
		(start 378.563632 -242.619276)
		(mid 378.376434 -242.669419)
		(end 378.189236 -242.619276)
		(width 0.088646)
		(layer "In11.Cu")
		(net "M_H_CPU0_SB_DQS_DN<9>")
	)
	(arc
		(start 376.309636 -242.619276)
		(mid 376.035407 -242.543351)
		(end 375.758964 -242.61064)
		(width 0.088646)
		(layer "In11.Cu")
		(net "M_H_CPU0_SB_DQS_DN<9>")
	)
	(arc
		(start 374.419368 -242.613434)
		(mid 374.14119 -242.543711)
		(end 373.864632 -242.61953)
		(width 0.088646)
		(layer "In11.Cu")
		(net "M_H_CPU0_SB_DQS_DN<9>")
	)
	(arc
		(start 371.601746 -242.614196)
		(mid 371.486007 -242.502372)
		(end 371.427756 -242.352322)
		(width 0.088646)
		(layer "In11.Cu")
		(net "M_H_CPU0_SB_DQS_DN<9>")
	)
	(arc
		(start 383.828036 -242.619276)
		(mid 383.545334 -242.543534)
		(end 383.262632 -242.619276)
		(width 0.088646)
		(layer "In11.Cu")
		(net "M_H_CPU0_SB_DQS_DN<9>")
	)
	(arc
		(start 379.129036 -242.619276)
		(mid 378.854807 -242.543351)
		(end 378.578364 -242.61064)
		(width 0.088646)
		(layer "In11.Cu")
		(net "M_H_CPU0_SB_DQS_DN<9>")
	)
	(arc
		(start 382.888236 -242.619276)
		(mid 382.614007 -242.543351)
		(end 382.337564 -242.61064)
		(width 0.088646)
		(layer "In11.Cu")
		(net "M_H_CPU0_SB_DQS_DN<9>")
	)
	(arc
		(start 371.992652 -242.614704)
		(mid 371.983959 -242.619904)
		(end 371.975126 -242.624864)
		(width 0.088646)
		(layer "In11.Cu")
		(net "M_H_CPU0_SB_DQS_DN<9>")
	)
	(arc
		(start 381.948436 -242.619276)
		(mid 381.665734 -242.543534)
		(end 381.383032 -242.619276)
		(width 0.088646)
		(layer "In11.Cu")
		(net "M_H_CPU0_SB_DQS_DN<9>")
	)
	(arc
		(start 380.443232 -242.619276)
		(mid 380.256034 -242.669419)
		(end 380.068836 -242.619276)
		(width 0.088646)
		(layer "In11.Cu")
		(net "M_H_CPU0_SB_DQS_DN<9>")
	)
	(arc
		(start 382.322832 -242.619276)
		(mid 382.135634 -242.669419)
		(end 381.948436 -242.619276)
		(width 0.088646)
		(layer "In11.Cu")
		(net "M_H_CPU0_SB_DQS_DN<9>")
	)
	(arc
		(start 384.860546 -242.686078)
		(mid 384.542271 -242.546385)
		(end 384.202432 -242.619276)
		(width 0.088646)
		(layer "In11.Cu")
		(net "M_H_CPU0_SB_DQS_DN<9>")
	)
	(arc
		(start 377.623832 -242.619276)
		(mid 377.436634 -242.669419)
		(end 377.249436 -242.619276)
		(width 0.088646)
		(layer "In11.Cu")
		(net "M_H_CPU0_SB_DQS_DN<9>")
	)
	(arc
		(start 371.611906 -242.620038)
		(mid 371.611271 -242.619657)
		(end 371.610636 -242.619276)
		(width 0.088646)
		(layer "In11.Cu")
		(net "M_H_CPU0_SB_DQS_DN<9>")
	)
	(arc
		(start 372.550436 -242.61953)
		(mid 372.276237 -242.543695)
		(end 371.999764 -242.610894)
		(width 0.088646)
		(layer "In11.Cu")
		(net "M_H_CPU0_SB_DQS_DN<9>")
	)
	(arc
		(start 371.797834 -242.669314)
		(mid 371.701653 -242.656816)
		(end 371.611906 -242.620038)
		(width 0.088646)
		(layer "In11.Cu")
		(net "M_H_CPU0_SB_DQS_DN<9>")
	)
	(segment
		(start 458.549248 -199.441816)
		(end 458.543152 -199.447912)
		(width 0.1016)
		(layer "F.Cu")
		(net "M_H_CPU0_SB_DQS_DN<8>")
	)
	(segment
		(start 461.174846 -199.166988)
		(end 460.889096 -199.452738)
		(width 0.20066)
		(layer "F.Cu")
		(net "M_H_CPU0_SB_DQS_DN<8>")
	)
	(segment
		(start 456.646788 -199.866758)
		(end 456.116182 -199.866758)
		(width 0.20066)
		(layer "F.Cu")
		(net "M_H_CPU0_SB_DQS_DN<8>")
	)
	(segment
		(start 462.902046 -199.612504)
		(end 462.110328 -199.612504)
		(width 0.20066)
		(layer "F.Cu")
		(net "M_H_CPU0_SB_DQS_DN<8>")
	)
	(segment
		(start 463.1563 -199.866758)
		(end 462.902046 -199.612504)
		(width 0.20066)
		(layer "F.Cu")
		(net "M_H_CPU0_SB_DQS_DN<8>")
	)
	(segment
		(start 460.889096 -199.452738)
		(end 460.570326 -199.452738)
		(width 0.20066)
		(layer "F.Cu")
		(net "M_H_CPU0_SB_DQS_DN<8>")
	)
	(segment
		(start 372.73738 -228.1809)
		(end 372.737634 -228.180646)
		(width 0.20066)
		(layer "F.Cu")
		(net "M_H_CPU0_SB_DQS_DN<8>")
	)
	(segment
		(start 460.559404 -199.441816)
		(end 458.549248 -199.441816)
		(width 0.1016)
		(layer "F.Cu")
		(net "M_H_CPU0_SB_DQS_DN<8>")
	)
	(segment
		(start 458.543152 -199.447912)
		(end 458.538326 -199.447912)
		(width 0.101854)
		(layer "F.Cu")
		(net "M_H_CPU0_SB_DQS_DN<8>")
	)
	(segment
		(start 372.737634 -228.180646)
		(end 372.737634 -227.64496)
		(width 0.20066)
		(layer "F.Cu")
		(net "M_H_CPU0_SB_DQS_DN<8>")
	)
	(segment
		(start 457.948792 -199.170544)
		(end 457.826364 -199.170544)
		(width 0.20066)
		(layer "F.Cu")
		(net "M_H_CPU0_SB_DQS_DN<8>")
	)
	(segment
		(start 461.664812 -199.166988)
		(end 461.174846 -199.166988)
		(width 0.20066)
		(layer "F.Cu")
		(net "M_H_CPU0_SB_DQS_DN<8>")
	)
	(segment
		(start 463.659982 -199.866758)
		(end 463.1563 -199.866758)
		(width 0.20066)
		(layer "F.Cu")
		(net "M_H_CPU0_SB_DQS_DN<8>")
	)
	(segment
		(start 460.570326 -199.452738)
		(end 460.559404 -199.441816)
		(width 0.1016)
		(layer "F.Cu")
		(net "M_H_CPU0_SB_DQS_DN<8>")
	)
	(segment
		(start 458.22616 -199.447912)
		(end 457.948792 -199.170544)
		(width 0.20066)
		(layer "F.Cu")
		(net "M_H_CPU0_SB_DQS_DN<8>")
	)
	(segment
		(start 462.110328 -199.612504)
		(end 461.664812 -199.166988)
		(width 0.20066)
		(layer "F.Cu")
		(net "M_H_CPU0_SB_DQS_DN<8>")
	)
	(segment
		(start 458.538326 -199.447912)
		(end 458.22616 -199.447912)
		(width 0.20066)
		(layer "F.Cu")
		(net "M_H_CPU0_SB_DQS_DN<8>")
	)
	(segment
		(start 457.826364 -199.170544)
		(end 457.401422 -199.595486)
		(width 0.20066)
		(layer "F.Cu")
		(net "M_H_CPU0_SB_DQS_DN<8>")
	)
	(segment
		(start 457.401422 -199.595486)
		(end 456.91806 -199.595486)
		(width 0.20066)
		(layer "F.Cu")
		(net "M_H_CPU0_SB_DQS_DN<8>")
	)
	(segment
		(start 455.011282 -199.866758)
		(end 456.116182 -199.866758)
		(width 0.20066)
		(layer "F.Cu")
		(net "M_H_CPU0_SB_DQS_DN<8>")
	)
	(segment
		(start 456.91806 -199.595486)
		(end 456.646788 -199.866758)
		(width 0.20066)
		(layer "F.Cu")
		(net "M_H_CPU0_SB_DQS_DN<8>")
	)
	(segment
		(start 378.658882 -228.134672)
		(end 378.64415 -228.143308)
		(width 0.088646)
		(layer "In11.Cu")
		(net "M_H_CPU0_SB_DQS_DN<8>")
	)
	(segment
		(start 389.434832 -222.569024)
		(end 389.434832 -223.601026)
		(width 0.18288)
		(layer "In11.Cu")
		(net "M_H_CPU0_SB_DQS_DN<8>")
	)
	(segment
		(start 451.38848 -201.74204)
		(end 451.139306 -201.991214)
		(width 0.18288)
		(layer "In11.Cu")
		(net "M_H_CPU0_SB_DQS_DN<8>")
	)
	(segment
		(start 415.460942 -202.313794)
		(end 413.03575 -202.313794)
		(width 0.18288)
		(layer "In11.Cu")
		(net "M_H_CPU0_SB_DQS_DN<8>")
	)
	(segment
		(start 440.152282 -201.140568)
		(end 439.629042 -201.140568)
		(width 0.18288)
		(layer "In11.Cu")
		(net "M_H_CPU0_SB_DQS_DN<8>")
	)
	(segment
		(start 446.08115 -201.120502)
		(end 442.935106 -201.120502)
		(width 0.18288)
		(layer "In11.Cu")
		(net "M_H_CPU0_SB_DQS_DN<8>")
	)
	(segment
		(start 374.223026 -228.073966)
		(end 373.738902 -228.064822)
		(width 0.088646)
		(layer "In11.Cu")
		(net "M_H_CPU0_SB_DQS_DN<8>")
	)
	(segment
		(start 423.366184 -200.870312)
		(end 421.728392 -201.548492)
		(width 0.18288)
		(layer "In11.Cu")
		(net "M_H_CPU0_SB_DQS_DN<8>")
	)
	(segment
		(start 450.71157 -201.991214)
		(end 450.445632 -201.725276)
		(width 0.18288)
		(layer "In11.Cu")
		(net "M_H_CPU0_SB_DQS_DN<8>")
	)
	(segment
		(start 420.441882 -201.991214)
		(end 420.190422 -201.739754)
		(width 0.18288)
		(layer "In11.Cu")
		(net "M_H_CPU0_SB_DQS_DN<8>")
	)
	(segment
		(start 388.266178 -224.76968)
		(end 388.181342 -224.76968)
		(width 0.088646)
		(layer "In11.Cu")
		(net "M_H_CPU0_SB_DQS_DN<8>")
	)
	(segment
		(start 451.139306 -201.991214)
		(end 450.71157 -201.991214)
		(width 0.18288)
		(layer "In11.Cu")
		(net "M_H_CPU0_SB_DQS_DN<8>")
	)
	(segment
		(start 395.98981 -213.213696)
		(end 395.98981 -216.014046)
		(width 0.18288)
		(layer "In11.Cu")
		(net "M_H_CPU0_SB_DQS_DN<8>")
	)
	(segment
		(start 440.41187 -200.88098)
		(end 440.152282 -201.140568)
		(width 0.18288)
		(layer "In11.Cu")
		(net "M_H_CPU0_SB_DQS_DN<8>")
	)
	(segment
		(start 425.062142 -201.143108)
		(end 424.543982 -201.143108)
		(width 0.18288)
		(layer "In11.Cu")
		(net "M_H_CPU0_SB_DQS_DN<8>")
	)
	(segment
		(start 427.024546 -201.851006)
		(end 426.049948 -200.876408)
		(width 0.18288)
		(layer "In11.Cu")
		(net "M_H_CPU0_SB_DQS_DN<8>")
	)
	(segment
		(start 454.738994 -199.59447)
		(end 454.187052 -199.59447)
		(width 0.18288)
		(layer "In11.Cu")
		(net "M_H_CPU0_SB_DQS_DN<8>")
	)
	(segment
		(start 430.897538 -202.310492)
		(end 428.13351 -202.310492)
		(width 0.18288)
		(layer "In11.Cu")
		(net "M_H_CPU0_SB_DQS_DN<8>")
	)
	(segment
		(start 385.707128 -227.320348)
		(end 385.707382 -227.320856)
		(width 0.088646)
		(layer "In11.Cu")
		(net "M_H_CPU0_SB_DQS_DN<8>")
	)
	(segment
		(start 439.629042 -201.140568)
		(end 439.37682 -200.888346)
		(width 0.18288)
		(layer "In11.Cu")
		(net "M_H_CPU0_SB_DQS_DN<8>")
	)
	(segment
		(start 442.532262 -201.523346)
		(end 441.774326 -201.523346)
		(width 0.18288)
		(layer "In11.Cu")
		(net "M_H_CPU0_SB_DQS_DN<8>")
	)
	(segment
		(start 382.418082 -228.134672)
		(end 382.407668 -228.140768)
		(width 0.088646)
		(layer "In11.Cu")
		(net "M_H_CPU0_SB_DQS_DN<8>")
	)
	(segment
		(start 409.59151 -201.777346)
		(end 409.060142 -202.308714)
		(width 0.18288)
		(layer "In11.Cu")
		(net "M_H_CPU0_SB_DQS_DN<8>")
	)
	(segment
		(start 421.728392 -201.548492)
		(end 421.550338 -201.726546)
		(width 0.18288)
		(layer "In11.Cu")
		(net "M_H_CPU0_SB_DQS_DN<8>")
	)
	(segment
		(start 384.580384 -227.64496)
		(end 384.580384 -227.663502)
		(width 0.088646)
		(layer "In11.Cu")
		(net "M_H_CPU0_SB_DQS_DN<8>")
	)
	(segment
		(start 426.049948 -200.876408)
		(end 425.328842 -200.876408)
		(width 0.18288)
		(layer "In11.Cu")
		(net "M_H_CPU0_SB_DQS_DN<8>")
	)
	(segment
		(start 424.543982 -201.143108)
		(end 424.271186 -200.870312)
		(width 0.18288)
		(layer "In11.Cu")
		(net "M_H_CPU0_SB_DQS_DN<8>")
	)
	(segment
		(start 447.541142 -201.725276)
		(end 446.08115 -201.120502)
		(width 0.18288)
		(layer "In11.Cu")
		(net "M_H_CPU0_SB_DQS_DN<8>")
	)
	(segment
		(start 424.271186 -200.870312)
		(end 423.366184 -200.870312)
		(width 0.18288)
		(layer "In11.Cu")
		(net "M_H_CPU0_SB_DQS_DN<8>")
	)
	(segment
		(start 439.37682 -200.888346)
		(end 437.97474 -200.888346)
		(width 0.18288)
		(layer "In11.Cu")
		(net "M_H_CPU0_SB_DQS_DN<8>")
	)
	(segment
		(start 374.899682 -228.134672)
		(end 374.889268 -228.140768)
		(width 0.088646)
		(layer "In11.Cu")
		(net "M_H_CPU0_SB_DQS_DN<8>")
	)
	(segment
		(start 405.497284 -202.308714)
		(end 404.23084 -203.575158)
		(width 0.18288)
		(layer "In11.Cu")
		(net "M_H_CPU0_SB_DQS_DN<8>")
	)
	(segment
		(start 441.13196 -200.88098)
		(end 440.41187 -200.88098)
		(width 0.18288)
		(layer "In11.Cu")
		(net "M_H_CPU0_SB_DQS_DN<8>")
	)
	(segment
		(start 432.344068 -201.711306)
		(end 430.897538 -202.310492)
		(width 0.18288)
		(layer "In11.Cu")
		(net "M_H_CPU0_SB_DQS_DN<8>")
	)
	(segment
		(start 383.358136 -228.134672)
		(end 383.347722 -228.140768)
		(width 0.088646)
		(layer "In11.Cu")
		(net "M_H_CPU0_SB_DQS_DN<8>")
	)
	(segment
		(start 413.03575 -202.313794)
		(end 411.741874 -201.777346)
		(width 0.18288)
		(layer "In11.Cu")
		(net "M_H_CPU0_SB_DQS_DN<8>")
	)
	(segment
		(start 452.039482 -201.74204)
		(end 451.38848 -201.74204)
		(width 0.18288)
		(layer "In11.Cu")
		(net "M_H_CPU0_SB_DQS_DN<8>")
	)
	(segment
		(start 404.23084 -203.575158)
		(end 404.23084 -204.972666)
		(width 0.18288)
		(layer "In11.Cu")
		(net "M_H_CPU0_SB_DQS_DN<8>")
	)
	(segment
		(start 373.490236 -227.969318)
		(end 373.481346 -227.964238)
		(width 0.088646)
		(layer "In11.Cu")
		(net "M_H_CPU0_SB_DQS_DN<8>")
	)
	(segment
		(start 436.30088 -201.74204)
		(end 436.051706 -201.991214)
		(width 0.18288)
		(layer "In11.Cu")
		(net "M_H_CPU0_SB_DQS_DN<8>")
	)
	(segment
		(start 379.598682 -228.134672)
		(end 379.58395 -228.143308)
		(width 0.088646)
		(layer "In11.Cu")
		(net "M_H_CPU0_SB_DQS_DN<8>")
	)
	(segment
		(start 373.616982 -228.037136)
		(end 373.490236 -227.969318)
		(width 0.088646)
		(layer "In11.Cu")
		(net "M_H_CPU0_SB_DQS_DN<8>")
	)
	(segment
		(start 437.121046 -201.74204)
		(end 436.30088 -201.74204)
		(width 0.18288)
		(layer "In11.Cu")
		(net "M_H_CPU0_SB_DQS_DN<8>")
	)
	(segment
		(start 389.434832 -223.601026)
		(end 388.266178 -224.76968)
		(width 0.18288)
		(layer "In11.Cu")
		(net "M_H_CPU0_SB_DQS_DN<8>")
	)
	(segment
		(start 409.060142 -202.308714)
		(end 405.497284 -202.308714)
		(width 0.18288)
		(layer "In11.Cu")
		(net "M_H_CPU0_SB_DQS_DN<8>")
	)
	(segment
		(start 387.138164 -226.488498)
		(end 386.929884 -226.696778)
		(width 0.088646)
		(layer "In11.Cu")
		(net "M_H_CPU0_SB_DQS_DN<8>")
	)
	(segment
		(start 411.741874 -201.777346)
		(end 409.59151 -201.777346)
		(width 0.18288)
		(layer "In11.Cu")
		(net "M_H_CPU0_SB_DQS_DN<8>")
	)
	(segment
		(start 386.929884 -226.696778)
		(end 386.929884 -226.84105)
		(width 0.088646)
		(layer "In11.Cu")
		(net "M_H_CPU0_SB_DQS_DN<8>")
	)
	(segment
		(start 435.529482 -201.991214)
		(end 435.249574 -201.711306)
		(width 0.18288)
		(layer "In11.Cu")
		(net "M_H_CPU0_SB_DQS_DN<8>")
	)
	(segment
		(start 421.228774 -201.726546)
		(end 420.964106 -201.991214)
		(width 0.18288)
		(layer "In11.Cu")
		(net "M_H_CPU0_SB_DQS_DN<8>")
	)
	(segment
		(start 435.249574 -201.711306)
		(end 432.344068 -201.711306)
		(width 0.18288)
		(layer "In11.Cu")
		(net "M_H_CPU0_SB_DQS_DN<8>")
	)
	(segment
		(start 418.347398 -201.739754)
		(end 415.460942 -202.313794)
		(width 0.18288)
		(layer "In11.Cu")
		(net "M_H_CPU0_SB_DQS_DN<8>")
	)
	(segment
		(start 380.538736 -228.134672)
		(end 380.528322 -228.140768)
		(width 0.088646)
		(layer "In11.Cu")
		(net "M_H_CPU0_SB_DQS_DN<8>")
	)
	(segment
		(start 428.13351 -202.310492)
		(end 427.024546 -201.851006)
		(width 0.18288)
		(layer "In11.Cu")
		(net "M_H_CPU0_SB_DQS_DN<8>")
	)
	(segment
		(start 421.550338 -201.726546)
		(end 421.228774 -201.726546)
		(width 0.18288)
		(layer "In11.Cu")
		(net "M_H_CPU0_SB_DQS_DN<8>")
	)
	(segment
		(start 395.98981 -216.014046)
		(end 389.434832 -222.569024)
		(width 0.18288)
		(layer "In11.Cu")
		(net "M_H_CPU0_SB_DQS_DN<8>")
	)
	(segment
		(start 420.190422 -201.739754)
		(end 418.347398 -201.739754)
		(width 0.18288)
		(layer "In11.Cu")
		(net "M_H_CPU0_SB_DQS_DN<8>")
	)
	(segment
		(start 425.328842 -200.876408)
		(end 425.062142 -201.143108)
		(width 0.18288)
		(layer "In11.Cu")
		(net "M_H_CPU0_SB_DQS_DN<8>")
	)
	(segment
		(start 450.445632 -201.725276)
		(end 447.541142 -201.725276)
		(width 0.18288)
		(layer "In11.Cu")
		(net "M_H_CPU0_SB_DQS_DN<8>")
	)
	(segment
		(start 455.011282 -199.866758)
		(end 454.738994 -199.59447)
		(width 0.18288)
		(layer "In11.Cu")
		(net "M_H_CPU0_SB_DQS_DN<8>")
	)
	(segment
		(start 404.23084 -204.972666)
		(end 395.98981 -213.213696)
		(width 0.18288)
		(layer "In11.Cu")
		(net "M_H_CPU0_SB_DQS_DN<8>")
	)
	(segment
		(start 437.97474 -200.888346)
		(end 437.121046 -201.74204)
		(width 0.18288)
		(layer "In11.Cu")
		(net "M_H_CPU0_SB_DQS_DN<8>")
	)
	(segment
		(start 436.051706 -201.991214)
		(end 435.529482 -201.991214)
		(width 0.18288)
		(layer "In11.Cu")
		(net "M_H_CPU0_SB_DQS_DN<8>")
	)
	(segment
		(start 373.235982 -227.64496)
		(end 372.737634 -227.64496)
		(width 0.088646)
		(layer "In11.Cu")
		(net "M_H_CPU0_SB_DQS_DN<8>")
	)
	(segment
		(start 387.138164 -225.812858)
		(end 387.138164 -226.488498)
		(width 0.088646)
		(layer "In11.Cu")
		(net "M_H_CPU0_SB_DQS_DN<8>")
	)
	(segment
		(start 374.329198 -228.13137)
		(end 374.223026 -228.073966)
		(width 0.088646)
		(layer "In11.Cu")
		(net "M_H_CPU0_SB_DQS_DN<8>")
	)
	(segment
		(start 373.31015 -227.719128)
		(end 373.235982 -227.64496)
		(width 0.088646)
		(layer "In11.Cu")
		(net "M_H_CPU0_SB_DQS_DN<8>")
	)
	(segment
		(start 442.935106 -201.120502)
		(end 442.532262 -201.523346)
		(width 0.18288)
		(layer "In11.Cu")
		(net "M_H_CPU0_SB_DQS_DN<8>")
	)
	(segment
		(start 373.714264 -228.06152)
		(end 373.616982 -228.037136)
		(width 0.088646)
		(layer "In11.Cu")
		(net "M_H_CPU0_SB_DQS_DN<8>")
	)
	(segment
		(start 384.767836 -227.320602)
		(end 384.758946 -227.325682)
		(width 0.088646)
		(layer "In11.Cu")
		(net "M_H_CPU0_SB_DQS_DN<8>")
	)
	(segment
		(start 388.181342 -224.76968)
		(end 387.138164 -225.812858)
		(width 0.088646)
		(layer "In11.Cu")
		(net "M_H_CPU0_SB_DQS_DN<8>")
	)
	(segment
		(start 377.719082 -228.134672)
		(end 377.70435 -228.143308)
		(width 0.088646)
		(layer "In11.Cu")
		(net "M_H_CPU0_SB_DQS_DN<8>")
	)
	(segment
		(start 441.774326 -201.523346)
		(end 441.13196 -200.88098)
		(width 0.18288)
		(layer "In11.Cu")
		(net "M_H_CPU0_SB_DQS_DN<8>")
	)
	(segment
		(start 420.964106 -201.991214)
		(end 420.441882 -201.991214)
		(width 0.18288)
		(layer "In11.Cu")
		(net "M_H_CPU0_SB_DQS_DN<8>")
	)
	(segment
		(start 454.187052 -199.59447)
		(end 452.039482 -201.74204)
		(width 0.18288)
		(layer "In11.Cu")
		(net "M_H_CPU0_SB_DQS_DN<8>")
	)
	(arc
		(start 382.792478 -228.134672)
		(mid 382.60528 -228.084529)
		(end 382.418082 -228.134672)
		(width 0.088646)
		(layer "In11.Cu")
		(net "M_H_CPU0_SB_DQS_DN<8>")
	)
	(arc
		(start 384.580384 -227.663502)
		(mid 384.500222 -227.935691)
		(end 384.297936 -228.134672)
		(width 0.088646)
		(layer "In11.Cu")
		(net "M_H_CPU0_SB_DQS_DN<8>")
	)
	(arc
		(start 374.333262 -228.133656)
		(mid 374.331224 -228.132524)
		(end 374.329198 -228.13137)
		(width 0.088646)
		(layer "In11.Cu")
		(net "M_H_CPU0_SB_DQS_DN<8>")
	)
	(arc
		(start 380.913132 -228.134672)
		(mid 380.725934 -228.084529)
		(end 380.538736 -228.134672)
		(width 0.088646)
		(layer "In11.Cu")
		(net "M_H_CPU0_SB_DQS_DN<8>")
	)
	(arc
		(start 376.779282 -228.134672)
		(mid 376.49658 -228.210414)
		(end 376.213878 -228.134672)
		(width 0.088646)
		(layer "In11.Cu")
		(net "M_H_CPU0_SB_DQS_DN<8>")
	)
	(arc
		(start 383.732532 -228.134672)
		(mid 383.545334 -228.084529)
		(end 383.358136 -228.134672)
		(width 0.088646)
		(layer "In11.Cu")
		(net "M_H_CPU0_SB_DQS_DN<8>")
	)
	(arc
		(start 373.738902 -228.064822)
		(mid 373.726487 -228.063884)
		(end 373.714264 -228.06152)
		(width 0.088646)
		(layer "In11.Cu")
		(net "M_H_CPU0_SB_DQS_DN<8>")
	)
	(arc
		(start 378.093478 -228.134672)
		(mid 377.90628 -228.084529)
		(end 377.719082 -228.134672)
		(width 0.088646)
		(layer "In11.Cu")
		(net "M_H_CPU0_SB_DQS_DN<8>")
	)
	(arc
		(start 377.70435 -228.143308)
		(mid 377.427909 -228.210474)
		(end 377.153678 -228.134672)
		(width 0.088646)
		(layer "In11.Cu")
		(net "M_H_CPU0_SB_DQS_DN<8>")
	)
	(arc
		(start 380.528322 -228.140768)
		(mid 380.24989 -228.210582)
		(end 379.973078 -228.134672)
		(width 0.088646)
		(layer "In11.Cu")
		(net "M_H_CPU0_SB_DQS_DN<8>")
	)
	(arc
		(start 386.082286 -227.320348)
		(mid 385.894724 -227.270112)
		(end 385.707128 -227.320348)
		(width 0.088646)
		(layer "In11.Cu")
		(net "M_H_CPU0_SB_DQS_DN<8>")
	)
	(arc
		(start 385.707382 -227.320856)
		(mid 385.424761 -227.396471)
		(end 385.142232 -227.320602)
		(width 0.088646)
		(layer "In11.Cu")
		(net "M_H_CPU0_SB_DQS_DN<8>")
	)
	(arc
		(start 373.481346 -227.964238)
		(mid 373.370248 -227.859495)
		(end 373.31015 -227.719128)
		(width 0.088646)
		(layer "In11.Cu")
		(net "M_H_CPU0_SB_DQS_DN<8>")
	)
	(arc
		(start 375.274078 -228.134672)
		(mid 375.08688 -228.084529)
		(end 374.899682 -228.134672)
		(width 0.088646)
		(layer "In11.Cu")
		(net "M_H_CPU0_SB_DQS_DN<8>")
	)
	(arc
		(start 377.153678 -228.134672)
		(mid 376.96648 -228.084529)
		(end 376.779282 -228.134672)
		(width 0.088646)
		(layer "In11.Cu")
		(net "M_H_CPU0_SB_DQS_DN<8>")
	)
	(arc
		(start 375.839482 -228.134672)
		(mid 375.55678 -228.210414)
		(end 375.274078 -228.134672)
		(width 0.088646)
		(layer "In11.Cu")
		(net "M_H_CPU0_SB_DQS_DN<8>")
	)
	(arc
		(start 382.407668 -228.140768)
		(mid 382.12949 -228.21046)
		(end 381.852932 -228.134672)
		(width 0.088646)
		(layer "In11.Cu")
		(net "M_H_CPU0_SB_DQS_DN<8>")
	)
	(arc
		(start 384.758946 -227.325682)
		(mid 384.628032 -227.462042)
		(end 384.580384 -227.64496)
		(width 0.088646)
		(layer "In11.Cu")
		(net "M_H_CPU0_SB_DQS_DN<8>")
	)
	(arc
		(start 381.852932 -228.134672)
		(mid 381.665734 -228.084529)
		(end 381.478536 -228.134672)
		(width 0.088646)
		(layer "In11.Cu")
		(net "M_H_CPU0_SB_DQS_DN<8>")
	)
	(arc
		(start 379.033278 -228.134672)
		(mid 378.84608 -228.084529)
		(end 378.658882 -228.134672)
		(width 0.088646)
		(layer "In11.Cu")
		(net "M_H_CPU0_SB_DQS_DN<8>")
	)
	(arc
		(start 378.64415 -228.143308)
		(mid 378.367709 -228.210474)
		(end 378.093478 -228.134672)
		(width 0.088646)
		(layer "In11.Cu")
		(net "M_H_CPU0_SB_DQS_DN<8>")
	)
	(arc
		(start 374.334532 -228.134672)
		(mid 374.333897 -228.134163)
		(end 374.333262 -228.133656)
		(width 0.088646)
		(layer "In11.Cu")
		(net "M_H_CPU0_SB_DQS_DN<8>")
	)
	(arc
		(start 374.889268 -228.140768)
		(mid 374.61109 -228.21046)
		(end 374.334532 -228.134672)
		(width 0.088646)
		(layer "In11.Cu")
		(net "M_H_CPU0_SB_DQS_DN<8>")
	)
	(arc
		(start 383.347722 -228.140768)
		(mid 383.06929 -228.210582)
		(end 382.792478 -228.134672)
		(width 0.088646)
		(layer "In11.Cu")
		(net "M_H_CPU0_SB_DQS_DN<8>")
	)
	(arc
		(start 379.973078 -228.134672)
		(mid 379.78588 -228.084529)
		(end 379.598682 -228.134672)
		(width 0.088646)
		(layer "In11.Cu")
		(net "M_H_CPU0_SB_DQS_DN<8>")
	)
	(arc
		(start 379.58395 -228.143308)
		(mid 379.307509 -228.210474)
		(end 379.033278 -228.134672)
		(width 0.088646)
		(layer "In11.Cu")
		(net "M_H_CPU0_SB_DQS_DN<8>")
	)
	(arc
		(start 381.478536 -228.134672)
		(mid 381.195834 -228.210414)
		(end 380.913132 -228.134672)
		(width 0.088646)
		(layer "In11.Cu")
		(net "M_H_CPU0_SB_DQS_DN<8>")
	)
	(arc
		(start 386.929884 -226.84105)
		(mid 386.643081 -227.322947)
		(end 386.082286 -227.320348)
		(width 0.088646)
		(layer "In11.Cu")
		(net "M_H_CPU0_SB_DQS_DN<8>")
	)
	(arc
		(start 376.213878 -228.134672)
		(mid 376.02668 -228.084529)
		(end 375.839482 -228.134672)
		(width 0.088646)
		(layer "In11.Cu")
		(net "M_H_CPU0_SB_DQS_DN<8>")
	)
	(arc
		(start 385.142232 -227.320602)
		(mid 384.955034 -227.270459)
		(end 384.767836 -227.320602)
		(width 0.088646)
		(layer "In11.Cu")
		(net "M_H_CPU0_SB_DQS_DN<8>")
	)
	(arc
		(start 384.297936 -228.134672)
		(mid 384.015234 -228.210414)
		(end 383.732532 -228.134672)
		(width 0.088646)
		(layer "In11.Cu")
		(net "M_H_CPU0_SB_DQS_DN<8>")
	)
	(segment
		(start 456.116182 -209.216752)
		(end 456.646788 -209.216752)
		(width 0.20066)
		(layer "F.Cu")
		(net "M_H_CPU0_SB_DQS_DN<7>")
	)
	(segment
		(start 457.401422 -208.94548)
		(end 457.826364 -208.520538)
		(width 0.20066)
		(layer "F.Cu")
		(net "M_H_CPU0_SB_DQS_DN<7>")
	)
	(segment
		(start 458.549248 -208.79181)
		(end 460.559404 -208.79181)
		(width 0.1016)
		(layer "F.Cu")
		(net "M_H_CPU0_SB_DQS_DN<7>")
	)
	(segment
		(start 456.91806 -208.94548)
		(end 457.401422 -208.94548)
		(width 0.20066)
		(layer "F.Cu")
		(net "M_H_CPU0_SB_DQS_DN<7>")
	)
	(segment
		(start 376.96648 -230.622348)
		(end 376.96648 -230.086662)
		(width 0.20066)
		(layer "F.Cu")
		(net "M_H_CPU0_SB_DQS_DN<7>")
	)
	(segment
		(start 460.889096 -208.802732)
		(end 461.174846 -208.516982)
		(width 0.20066)
		(layer "F.Cu")
		(net "M_H_CPU0_SB_DQS_DN<7>")
	)
	(segment
		(start 463.1563 -209.216752)
		(end 463.659982 -209.216752)
		(width 0.20066)
		(layer "F.Cu")
		(net "M_H_CPU0_SB_DQS_DN<7>")
	)
	(segment
		(start 461.174846 -208.516982)
		(end 461.664812 -208.516982)
		(width 0.20066)
		(layer "F.Cu")
		(net "M_H_CPU0_SB_DQS_DN<7>")
	)
	(segment
		(start 458.543152 -208.797906)
		(end 458.549248 -208.79181)
		(width 0.1016)
		(layer "F.Cu")
		(net "M_H_CPU0_SB_DQS_DN<7>")
	)
	(segment
		(start 461.664812 -208.516982)
		(end 462.110328 -208.962498)
		(width 0.20066)
		(layer "F.Cu")
		(net "M_H_CPU0_SB_DQS_DN<7>")
	)
	(segment
		(start 455.011282 -209.216752)
		(end 456.116182 -209.216752)
		(width 0.20066)
		(layer "F.Cu")
		(net "M_H_CPU0_SB_DQS_DN<7>")
	)
	(segment
		(start 457.826364 -208.520538)
		(end 457.948792 -208.520538)
		(width 0.20066)
		(layer "F.Cu")
		(net "M_H_CPU0_SB_DQS_DN<7>")
	)
	(segment
		(start 458.538326 -208.797906)
		(end 458.543152 -208.797906)
		(width 0.101854)
		(layer "F.Cu")
		(net "M_H_CPU0_SB_DQS_DN<7>")
	)
	(segment
		(start 460.570326 -208.802732)
		(end 460.889096 -208.802732)
		(width 0.20066)
		(layer "F.Cu")
		(net "M_H_CPU0_SB_DQS_DN<7>")
	)
	(segment
		(start 458.22616 -208.797906)
		(end 458.538326 -208.797906)
		(width 0.20066)
		(layer "F.Cu")
		(net "M_H_CPU0_SB_DQS_DN<7>")
	)
	(segment
		(start 462.902046 -208.962498)
		(end 463.1563 -209.216752)
		(width 0.20066)
		(layer "F.Cu")
		(net "M_H_CPU0_SB_DQS_DN<7>")
	)
	(segment
		(start 457.948792 -208.520538)
		(end 458.22616 -208.797906)
		(width 0.20066)
		(layer "F.Cu")
		(net "M_H_CPU0_SB_DQS_DN<7>")
	)
	(segment
		(start 376.966734 -230.622602)
		(end 376.96648 -230.622348)
		(width 0.20066)
		(layer "F.Cu")
		(net "M_H_CPU0_SB_DQS_DN<7>")
	)
	(segment
		(start 462.110328 -208.962498)
		(end 462.902046 -208.962498)
		(width 0.20066)
		(layer "F.Cu")
		(net "M_H_CPU0_SB_DQS_DN<7>")
	)
	(segment
		(start 456.646788 -209.216752)
		(end 456.91806 -208.94548)
		(width 0.20066)
		(layer "F.Cu")
		(net "M_H_CPU0_SB_DQS_DN<7>")
	)
	(segment
		(start 460.559404 -208.79181)
		(end 460.570326 -208.802732)
		(width 0.1016)
		(layer "F.Cu")
		(net "M_H_CPU0_SB_DQS_DN<7>")
	)
	(segment
		(start 425.738798 -210.230974)
		(end 425.276772 -210.230974)
		(width 0.18288)
		(layer "In6.Cu")
		(net "M_H_CPU0_SB_DQS_DN<7>")
	)
	(segment
		(start 409.245816 -209.305906)
		(end 409.121356 -209.181446)
		(width 0.18288)
		(layer "In6.Cu")
		(net "M_H_CPU0_SB_DQS_DN<7>")
	)
	(segment
		(start 379.518164 -228.957124)
		(end 379.503432 -228.948488)
		(width 0.088646)
		(layer "In6.Cu")
		(net "M_H_CPU0_SB_DQS_DN<7>")
	)
	(segment
		(start 377.142502 -229.853998)
		(end 377.026932 -229.877112)
		(width 0.088646)
		(layer "In6.Cu")
		(net "M_H_CPU0_SB_DQS_DN<7>")
	)
	(segment
		(start 442.508894 -208.24825)
		(end 441.456572 -208.24825)
		(width 0.18288)
		(layer "In6.Cu")
		(net "M_H_CPU0_SB_DQS_DN<7>")
	)
	(segment
		(start 410.586936 -209.305906)
		(end 410.462476 -209.181446)
		(width 0.18288)
		(layer "In6.Cu")
		(net "M_H_CPU0_SB_DQS_DN<7>")
	)
	(segment
		(start 420.296594 -211.073746)
		(end 419.349174 -211.073746)
		(width 0.18288)
		(layer "In6.Cu")
		(net "M_H_CPU0_SB_DQS_DN<7>")
	)
	(segment
		(start 436.262526 -208.530444)
		(end 436.002176 -208.790794)
		(width 0.18288)
		(layer "In6.Cu")
		(net "M_H_CPU0_SB_DQS_DN<7>")
	)
	(segment
		(start 424.657012 -210.49107)
		(end 424.37558 -210.209638)
		(width 0.18288)
		(layer "In6.Cu")
		(net "M_H_CPU0_SB_DQS_DN<7>")
	)
	(segment
		(start 405.585168 -209.181446)
		(end 403.342094 -211.42452)
		(width 0.18288)
		(layer "In6.Cu")
		(net "M_H_CPU0_SB_DQS_DN<7>")
	)
	(segment
		(start 413.815276 -209.305906)
		(end 413.269176 -209.305906)
		(width 0.18288)
		(layer "In6.Cu")
		(net "M_H_CPU0_SB_DQS_DN<7>")
	)
	(segment
		(start 425.276772 -210.230974)
		(end 425.016676 -210.49107)
		(width 0.18288)
		(layer "In6.Cu")
		(net "M_H_CPU0_SB_DQS_DN<7>")
	)
	(segment
		(start 416.497516 -209.305906)
		(end 415.951416 -209.305906)
		(width 0.18288)
		(layer "In6.Cu")
		(net "M_H_CPU0_SB_DQS_DN<7>")
	)
	(segment
		(start 378.189236 -228.948488)
		(end 378.180346 -228.953568)
		(width 0.088646)
		(layer "In6.Cu")
		(net "M_H_CPU0_SB_DQS_DN<7>")
	)
	(segment
		(start 417.456874 -209.181446)
		(end 416.621976 -209.181446)
		(width 0.18288)
		(layer "In6.Cu")
		(net "M_H_CPU0_SB_DQS_DN<7>")
	)
	(segment
		(start 414.610296 -209.305906)
		(end 414.485836 -209.181446)
		(width 0.18288)
		(layer "In6.Cu")
		(net "M_H_CPU0_SB_DQS_DN<7>")
	)
	(segment
		(start 411.133036 -209.305906)
		(end 410.586936 -209.305906)
		(width 0.18288)
		(layer "In6.Cu")
		(net "M_H_CPU0_SB_DQS_DN<7>")
	)
	(segment
		(start 387.130798 -226.90328)
		(end 387.003036 -226.90328)
		(width 0.088646)
		(layer "In6.Cu")
		(net "M_H_CPU0_SB_DQS_DN<7>")
	)
	(segment
		(start 377.727464 -229.757478)
		(end 377.69419 -229.776528)
		(width 0.088646)
		(layer "In6.Cu")
		(net "M_H_CPU0_SB_DQS_DN<7>")
	)
	(segment
		(start 433.109116 -209.241136)
		(end 428.069756 -209.241136)
		(width 0.18288)
		(layer "In6.Cu")
		(net "M_H_CPU0_SB_DQS_DN<7>")
	)
	(segment
		(start 427.274736 -209.241136)
		(end 426.728636 -209.241136)
		(width 0.18288)
		(layer "In6.Cu")
		(net "M_H_CPU0_SB_DQS_DN<7>")
	)
	(segment
		(start 434.843936 -208.52257)
		(end 433.109116 -209.241136)
		(width 0.18288)
		(layer "In6.Cu")
		(net "M_H_CPU0_SB_DQS_DN<7>")
	)
	(segment
		(start 455.011282 -209.216752)
		(end 454.749916 -208.955386)
		(width 0.18288)
		(layer "In6.Cu")
		(net "M_H_CPU0_SB_DQS_DN<7>")
	)
	(segment
		(start 435.364128 -208.52257)
		(end 434.843936 -208.52257)
		(width 0.18288)
		(layer "In6.Cu")
		(net "M_H_CPU0_SB_DQS_DN<7>")
	)
	(segment
		(start 386.938012 -226.968558)
		(end 386.819394 -227.254816)
		(width 0.088646)
		(layer "In6.Cu")
		(net "M_H_CPU0_SB_DQS_DN<7>")
	)
	(segment
		(start 418.063172 -209.963766)
		(end 418.063172 -209.787744)
		(width 0.18288)
		(layer "In6.Cu")
		(net "M_H_CPU0_SB_DQS_DN<7>")
	)
	(segment
		(start 415.156396 -209.305906)
		(end 414.610296 -209.305906)
		(width 0.18288)
		(layer "In6.Cu")
		(net "M_H_CPU0_SB_DQS_DN<7>")
	)
	(segment
		(start 409.916376 -209.181446)
		(end 409.791916 -209.305906)
		(width 0.18288)
		(layer "In6.Cu")
		(net "M_H_CPU0_SB_DQS_DN<7>")
	)
	(segment
		(start 415.280856 -209.181446)
		(end 415.156396 -209.305906)
		(width 0.18288)
		(layer "In6.Cu")
		(net "M_H_CPU0_SB_DQS_DN<7>")
	)
	(segment
		(start 421.169338 -211.080858)
		(end 420.908988 -211.341208)
		(width 0.18288)
		(layer "In6.Cu")
		(net "M_H_CPU0_SB_DQS_DN<7>")
	)
	(segment
		(start 420.908988 -211.341208)
		(end 420.564056 -211.341208)
		(width 0.18288)
		(layer "In6.Cu")
		(net "M_H_CPU0_SB_DQS_DN<7>")
	)
	(segment
		(start 414.485836 -209.181446)
		(end 413.939736 -209.181446)
		(width 0.18288)
		(layer "In6.Cu")
		(net "M_H_CPU0_SB_DQS_DN<7>")
	)
	(segment
		(start 419.349174 -211.073746)
		(end 418.625782 -210.350354)
		(width 0.18288)
		(layer "In6.Cu")
		(net "M_H_CPU0_SB_DQS_DN<7>")
	)
	(segment
		(start 418.063172 -209.787744)
		(end 417.456874 -209.181446)
		(width 0.18288)
		(layer "In6.Cu")
		(net "M_H_CPU0_SB_DQS_DN<7>")
	)
	(segment
		(start 450.434456 -208.531206)
		(end 447.392806 -208.531206)
		(width 0.18288)
		(layer "In6.Cu")
		(net "M_H_CPU0_SB_DQS_DN<7>")
	)
	(segment
		(start 407.780236 -209.181446)
		(end 406.926288 -209.181446)
		(width 0.18288)
		(layer "In6.Cu")
		(net "M_H_CPU0_SB_DQS_DN<7>")
	)
	(segment
		(start 418.625782 -210.350354)
		(end 418.44976 -210.350354)
		(width 0.18288)
		(layer "In6.Cu")
		(net "M_H_CPU0_SB_DQS_DN<7>")
	)
	(segment
		(start 427.399196 -209.365596)
		(end 427.274736 -209.241136)
		(width 0.18288)
		(layer "In6.Cu")
		(net "M_H_CPU0_SB_DQS_DN<7>")
	)
	(segment
		(start 406.131268 -209.181446)
		(end 405.585168 -209.181446)
		(width 0.18288)
		(layer "In6.Cu")
		(net "M_H_CPU0_SB_DQS_DN<7>")
	)
	(segment
		(start 426.728636 -209.241136)
		(end 425.738798 -210.230974)
		(width 0.18288)
		(layer "In6.Cu")
		(net "M_H_CPU0_SB_DQS_DN<7>")
	)
	(segment
		(start 385.810506 -228.26345)
		(end 385.810506 -228.637084)
		(width 0.088646)
		(layer "In6.Cu")
		(net "M_H_CPU0_SB_DQS_DN<7>")
	)
	(segment
		(start 382.337564 -228.957124)
		(end 382.322832 -228.948488)
		(width 0.088646)
		(layer "In6.Cu")
		(net "M_H_CPU0_SB_DQS_DN<7>")
	)
	(segment
		(start 443.383416 -207.886046)
		(end 442.508894 -208.24825)
		(width 0.18288)
		(layer "In6.Cu")
		(net "M_H_CPU0_SB_DQS_DN<7>")
	)
	(segment
		(start 439.7375 -207.94091)
		(end 439.478928 -207.682338)
		(width 0.18288)
		(layer "In6.Cu")
		(net "M_H_CPU0_SB_DQS_DN<7>")
	)
	(segment
		(start 415.951416 -209.305906)
		(end 415.826956 -209.181446)
		(width 0.18288)
		(layer "In6.Cu")
		(net "M_H_CPU0_SB_DQS_DN<7>")
	)
	(segment
		(start 411.928056 -209.305906)
		(end 411.803596 -209.181446)
		(width 0.18288)
		(layer "In6.Cu")
		(net "M_H_CPU0_SB_DQS_DN<7>")
	)
	(segment
		(start 437.005222 -208.530444)
		(end 436.262526 -208.530444)
		(width 0.18288)
		(layer "In6.Cu")
		(net "M_H_CPU0_SB_DQS_DN<7>")
	)
	(segment
		(start 439.478928 -207.682338)
		(end 437.853328 -207.682338)
		(width 0.18288)
		(layer "In6.Cu")
		(net "M_H_CPU0_SB_DQS_DN<7>")
	)
	(segment
		(start 409.121356 -209.181446)
		(end 408.575256 -209.181446)
		(width 0.18288)
		(layer "In6.Cu")
		(net "M_H_CPU0_SB_DQS_DN<7>")
	)
	(segment
		(start 403.342094 -211.630514)
		(end 388.009384 -226.963224)
		(width 0.18288)
		(layer "In6.Cu")
		(net "M_H_CPU0_SB_DQS_DN<7>")
	)
	(segment
		(start 420.564056 -211.341208)
		(end 420.296594 -211.073746)
		(width 0.18288)
		(layer "In6.Cu")
		(net "M_H_CPU0_SB_DQS_DN<7>")
	)
	(segment
		(start 428.069756 -209.241136)
		(end 427.945296 -209.365596)
		(width 0.18288)
		(layer "In6.Cu")
		(net "M_H_CPU0_SB_DQS_DN<7>")
	)
	(segment
		(start 451.35927 -208.530444)
		(end 451.09892 -208.790794)
		(width 0.18288)
		(layer "In6.Cu")
		(net "M_H_CPU0_SB_DQS_DN<7>")
	)
	(segment
		(start 443.784736 -207.886046)
		(end 443.383416 -207.886046)
		(width 0.18288)
		(layer "In6.Cu")
		(net "M_H_CPU0_SB_DQS_DN<7>")
	)
	(segment
		(start 425.016676 -210.49107)
		(end 424.657012 -210.49107)
		(width 0.18288)
		(layer "In6.Cu")
		(net "M_H_CPU0_SB_DQS_DN<7>")
	)
	(segment
		(start 376.96648 -229.937564)
		(end 376.96648 -230.086662)
		(width 0.088646)
		(layer "In6.Cu")
		(net "M_H_CPU0_SB_DQS_DN<7>")
	)
	(segment
		(start 377.51893 -229.853998)
		(end 377.142502 -229.853998)
		(width 0.088646)
		(layer "In6.Cu")
		(net "M_H_CPU0_SB_DQS_DN<7>")
	)
	(segment
		(start 412.598616 -209.181446)
		(end 412.474156 -209.305906)
		(width 0.18288)
		(layer "In6.Cu")
		(net "M_H_CPU0_SB_DQS_DN<7>")
	)
	(segment
		(start 447.392806 -208.531206)
		(end 445.841374 -209.173826)
		(width 0.18288)
		(layer "In6.Cu")
		(net "M_H_CPU0_SB_DQS_DN<7>")
	)
	(segment
		(start 440.110372 -207.94091)
		(end 439.7375 -207.94091)
		(width 0.18288)
		(layer "In6.Cu")
		(net "M_H_CPU0_SB_DQS_DN<7>")
	)
	(segment
		(start 436.002176 -208.790794)
		(end 435.632352 -208.790794)
		(width 0.18288)
		(layer "In6.Cu")
		(net "M_H_CPU0_SB_DQS_DN<7>")
	)
	(segment
		(start 386.819394 -227.254816)
		(end 385.810506 -228.26345)
		(width 0.088646)
		(layer "In6.Cu")
		(net "M_H_CPU0_SB_DQS_DN<7>")
	)
	(segment
		(start 445.072516 -209.173826)
		(end 443.784736 -207.886046)
		(width 0.18288)
		(layer "In6.Cu")
		(net "M_H_CPU0_SB_DQS_DN<7>")
	)
	(segment
		(start 403.342094 -211.42452)
		(end 403.342094 -211.630514)
		(width 0.18288)
		(layer "In6.Cu")
		(net "M_H_CPU0_SB_DQS_DN<7>")
	)
	(segment
		(start 377.026932 -229.877112)
		(end 376.96648 -229.937564)
		(width 0.088646)
		(layer "In6.Cu")
		(net "M_H_CPU0_SB_DQS_DN<7>")
	)
	(segment
		(start 440.888882 -207.68056)
		(end 440.370722 -207.68056)
		(width 0.18288)
		(layer "In6.Cu")
		(net "M_H_CPU0_SB_DQS_DN<7>")
	)
	(segment
		(start 427.945296 -209.365596)
		(end 427.399196 -209.365596)
		(width 0.18288)
		(layer "In6.Cu")
		(net "M_H_CPU0_SB_DQS_DN<7>")
	)
	(segment
		(start 441.456572 -208.24825)
		(end 440.888882 -207.68056)
		(width 0.18288)
		(layer "In6.Cu")
		(net "M_H_CPU0_SB_DQS_DN<7>")
	)
	(segment
		(start 409.791916 -209.305906)
		(end 409.245816 -209.305906)
		(width 0.18288)
		(layer "In6.Cu")
		(net "M_H_CPU0_SB_DQS_DN<7>")
	)
	(segment
		(start 406.926288 -209.181446)
		(end 406.801828 -209.305906)
		(width 0.18288)
		(layer "In6.Cu")
		(net "M_H_CPU0_SB_DQS_DN<7>")
	)
	(segment
		(start 408.450796 -209.305906)
		(end 407.904696 -209.305906)
		(width 0.18288)
		(layer "In6.Cu")
		(net "M_H_CPU0_SB_DQS_DN<7>")
	)
	(segment
		(start 415.826956 -209.181446)
		(end 415.280856 -209.181446)
		(width 0.18288)
		(layer "In6.Cu")
		(net "M_H_CPU0_SB_DQS_DN<7>")
	)
	(segment
		(start 421.891714 -211.080858)
		(end 421.169338 -211.080858)
		(width 0.18288)
		(layer "In6.Cu")
		(net "M_H_CPU0_SB_DQS_DN<7>")
	)
	(segment
		(start 452.85025 -209.329528)
		(end 452.051166 -208.530444)
		(width 0.18288)
		(layer "In6.Cu")
		(net "M_H_CPU0_SB_DQS_DN<7>")
	)
	(segment
		(start 424.37558 -210.209638)
		(end 422.762934 -210.209638)
		(width 0.18288)
		(layer "In6.Cu")
		(net "M_H_CPU0_SB_DQS_DN<7>")
	)
	(segment
		(start 453.909938 -209.329528)
		(end 452.85025 -209.329528)
		(width 0.18288)
		(layer "In6.Cu")
		(net "M_H_CPU0_SB_DQS_DN<7>")
	)
	(segment
		(start 416.621976 -209.181446)
		(end 416.497516 -209.305906)
		(width 0.18288)
		(layer "In6.Cu")
		(net "M_H_CPU0_SB_DQS_DN<7>")
	)
	(segment
		(start 422.762934 -210.209638)
		(end 421.891714 -211.080858)
		(width 0.18288)
		(layer "In6.Cu")
		(net "M_H_CPU0_SB_DQS_DN<7>")
	)
	(segment
		(start 412.474156 -209.305906)
		(end 411.928056 -209.305906)
		(width 0.18288)
		(layer "In6.Cu")
		(net "M_H_CPU0_SB_DQS_DN<7>")
	)
	(segment
		(start 408.575256 -209.181446)
		(end 408.450796 -209.305906)
		(width 0.18288)
		(layer "In6.Cu")
		(net "M_H_CPU0_SB_DQS_DN<7>")
	)
	(segment
		(start 413.269176 -209.305906)
		(end 413.144716 -209.181446)
		(width 0.18288)
		(layer "In6.Cu")
		(net "M_H_CPU0_SB_DQS_DN<7>")
	)
	(segment
		(start 413.144716 -209.181446)
		(end 412.598616 -209.181446)
		(width 0.18288)
		(layer "In6.Cu")
		(net "M_H_CPU0_SB_DQS_DN<7>")
	)
	(segment
		(start 387.003036 -226.90328)
		(end 386.938012 -226.968558)
		(width 0.088646)
		(layer "In6.Cu")
		(net "M_H_CPU0_SB_DQS_DN<7>")
	)
	(segment
		(start 437.853328 -207.682338)
		(end 437.005222 -208.530444)
		(width 0.18288)
		(layer "In6.Cu")
		(net "M_H_CPU0_SB_DQS_DN<7>")
	)
	(segment
		(start 388.009384 -226.963224)
		(end 387.190742 -226.963224)
		(width 0.18288)
		(layer "In6.Cu")
		(net "M_H_CPU0_SB_DQS_DN<7>")
	)
	(segment
		(start 407.904696 -209.305906)
		(end 407.780236 -209.181446)
		(width 0.18288)
		(layer "In6.Cu")
		(net "M_H_CPU0_SB_DQS_DN<7>")
	)
	(segment
		(start 418.44976 -210.350354)
		(end 418.063172 -209.963766)
		(width 0.18288)
		(layer "In6.Cu")
		(net "M_H_CPU0_SB_DQS_DN<7>")
	)
	(segment
		(start 445.841374 -209.173826)
		(end 445.072516 -209.173826)
		(width 0.18288)
		(layer "In6.Cu")
		(net "M_H_CPU0_SB_DQS_DN<7>")
	)
	(segment
		(start 411.803596 -209.181446)
		(end 411.257496 -209.181446)
		(width 0.18288)
		(layer "In6.Cu")
		(net "M_H_CPU0_SB_DQS_DN<7>")
	)
	(segment
		(start 387.190742 -226.963224)
		(end 387.130798 -226.90328)
		(width 0.088646)
		(layer "In6.Cu")
		(net "M_H_CPU0_SB_DQS_DN<7>")
	)
	(segment
		(start 385.810506 -228.637084)
		(end 385.55295 -228.89464)
		(width 0.088646)
		(layer "In6.Cu")
		(net "M_H_CPU0_SB_DQS_DN<7>")
	)
	(segment
		(start 454.28408 -208.955386)
		(end 453.909938 -209.329528)
		(width 0.18288)
		(layer "In6.Cu")
		(net "M_H_CPU0_SB_DQS_DN<7>")
	)
	(segment
		(start 451.09892 -208.790794)
		(end 450.694044 -208.790794)
		(width 0.18288)
		(layer "In6.Cu")
		(net "M_H_CPU0_SB_DQS_DN<7>")
	)
	(segment
		(start 378.578364 -228.957124)
		(end 378.563632 -228.948488)
		(width 0.088646)
		(layer "In6.Cu")
		(net "M_H_CPU0_SB_DQS_DN<7>")
	)
	(segment
		(start 413.939736 -209.181446)
		(end 413.815276 -209.305906)
		(width 0.18288)
		(layer "In6.Cu")
		(net "M_H_CPU0_SB_DQS_DN<7>")
	)
	(segment
		(start 385.14274 -228.948742)
		(end 385.142232 -228.948488)
		(width 0.088646)
		(layer "In6.Cu")
		(net "M_H_CPU0_SB_DQS_DN<7>")
	)
	(segment
		(start 452.051166 -208.530444)
		(end 451.35927 -208.530444)
		(width 0.18288)
		(layer "In6.Cu")
		(net "M_H_CPU0_SB_DQS_DN<7>")
	)
	(segment
		(start 411.257496 -209.181446)
		(end 411.133036 -209.305906)
		(width 0.18288)
		(layer "In6.Cu")
		(net "M_H_CPU0_SB_DQS_DN<7>")
	)
	(segment
		(start 377.69419 -229.776528)
		(end 377.51893 -229.853998)
		(width 0.088646)
		(layer "In6.Cu")
		(net "M_H_CPU0_SB_DQS_DN<7>")
	)
	(segment
		(start 450.694044 -208.790794)
		(end 450.434456 -208.531206)
		(width 0.18288)
		(layer "In6.Cu")
		(net "M_H_CPU0_SB_DQS_DN<7>")
	)
	(segment
		(start 406.801828 -209.305906)
		(end 406.255728 -209.305906)
		(width 0.18288)
		(layer "In6.Cu")
		(net "M_H_CPU0_SB_DQS_DN<7>")
	)
	(segment
		(start 454.749916 -208.955386)
		(end 454.28408 -208.955386)
		(width 0.18288)
		(layer "In6.Cu")
		(net "M_H_CPU0_SB_DQS_DN<7>")
	)
	(segment
		(start 410.462476 -209.181446)
		(end 409.916376 -209.181446)
		(width 0.18288)
		(layer "In6.Cu")
		(net "M_H_CPU0_SB_DQS_DN<7>")
	)
	(segment
		(start 435.632352 -208.790794)
		(end 435.364128 -208.52257)
		(width 0.18288)
		(layer "In6.Cu")
		(net "M_H_CPU0_SB_DQS_DN<7>")
	)
	(segment
		(start 377.731274 -229.755192)
		(end 377.727464 -229.757478)
		(width 0.088646)
		(layer "In6.Cu")
		(net "M_H_CPU0_SB_DQS_DN<7>")
	)
	(segment
		(start 440.370722 -207.68056)
		(end 440.110372 -207.94091)
		(width 0.18288)
		(layer "In6.Cu")
		(net "M_H_CPU0_SB_DQS_DN<7>")
	)
	(segment
		(start 406.255728 -209.305906)
		(end 406.131268 -209.181446)
		(width 0.18288)
		(layer "In6.Cu")
		(net "M_H_CPU0_SB_DQS_DN<7>")
	)
	(arc
		(start 385.142232 -228.948488)
		(mid 384.955034 -228.898345)
		(end 384.767836 -228.948488)
		(width 0.088646)
		(layer "In6.Cu")
		(net "M_H_CPU0_SB_DQS_DN<7>")
	)
	(arc
		(start 382.888236 -228.948488)
		(mid 382.614037 -229.024323)
		(end 382.337564 -228.957124)
		(width 0.088646)
		(layer "In6.Cu")
		(net "M_H_CPU0_SB_DQS_DN<7>")
	)
	(arc
		(start 380.443232 -228.948488)
		(mid 380.256034 -228.898345)
		(end 380.068836 -228.948488)
		(width 0.088646)
		(layer "In6.Cu")
		(net "M_H_CPU0_SB_DQS_DN<7>")
	)
	(arc
		(start 379.503432 -228.948488)
		(mid 379.316234 -228.898345)
		(end 379.129036 -228.948488)
		(width 0.088646)
		(layer "In6.Cu")
		(net "M_H_CPU0_SB_DQS_DN<7>")
	)
	(arc
		(start 381.008636 -228.948488)
		(mid 380.725934 -229.024264)
		(end 380.443232 -228.948488)
		(width 0.088646)
		(layer "In6.Cu")
		(net "M_H_CPU0_SB_DQS_DN<7>")
	)
	(arc
		(start 383.828036 -228.948488)
		(mid 383.545334 -229.024264)
		(end 383.262632 -228.948488)
		(width 0.088646)
		(layer "In6.Cu")
		(net "M_H_CPU0_SB_DQS_DN<7>")
	)
	(arc
		(start 380.068836 -228.948488)
		(mid 379.794637 -229.024323)
		(end 379.518164 -228.957124)
		(width 0.088646)
		(layer "In6.Cu")
		(net "M_H_CPU0_SB_DQS_DN<7>")
	)
	(arc
		(start 384.767836 -228.948488)
		(mid 384.485134 -229.024264)
		(end 384.202432 -228.948488)
		(width 0.088646)
		(layer "In6.Cu")
		(net "M_H_CPU0_SB_DQS_DN<7>")
	)
	(arc
		(start 384.202432 -228.948488)
		(mid 384.015234 -228.898345)
		(end 383.828036 -228.948488)
		(width 0.088646)
		(layer "In6.Cu")
		(net "M_H_CPU0_SB_DQS_DN<7>")
	)
	(arc
		(start 378.001784 -229.272846)
		(mid 377.929549 -229.54937)
		(end 377.731274 -229.755192)
		(width 0.088646)
		(layer "In6.Cu")
		(net "M_H_CPU0_SB_DQS_DN<7>")
	)
	(arc
		(start 385.55295 -228.89464)
		(mid 385.357034 -228.991187)
		(end 385.14274 -228.948742)
		(width 0.088646)
		(layer "In6.Cu")
		(net "M_H_CPU0_SB_DQS_DN<7>")
	)
	(arc
		(start 381.948436 -228.948488)
		(mid 381.665734 -229.024264)
		(end 381.383032 -228.948488)
		(width 0.088646)
		(layer "In6.Cu")
		(net "M_H_CPU0_SB_DQS_DN<7>")
	)
	(arc
		(start 379.129036 -228.948488)
		(mid 378.854837 -229.024323)
		(end 378.578364 -228.957124)
		(width 0.088646)
		(layer "In6.Cu")
		(net "M_H_CPU0_SB_DQS_DN<7>")
	)
	(arc
		(start 378.180346 -228.953568)
		(mid 378.049432 -229.089928)
		(end 378.001784 -229.272846)
		(width 0.088646)
		(layer "In6.Cu")
		(net "M_H_CPU0_SB_DQS_DN<7>")
	)
	(arc
		(start 382.322832 -228.948488)
		(mid 382.135634 -228.898345)
		(end 381.948436 -228.948488)
		(width 0.088646)
		(layer "In6.Cu")
		(net "M_H_CPU0_SB_DQS_DN<7>")
	)
	(arc
		(start 381.383032 -228.948488)
		(mid 381.195834 -228.898345)
		(end 381.008636 -228.948488)
		(width 0.088646)
		(layer "In6.Cu")
		(net "M_H_CPU0_SB_DQS_DN<7>")
	)
	(arc
		(start 378.563632 -228.948488)
		(mid 378.376434 -228.898345)
		(end 378.189236 -228.948488)
		(width 0.088646)
		(layer "In6.Cu")
		(net "M_H_CPU0_SB_DQS_DN<7>")
	)
	(arc
		(start 383.262632 -228.948488)
		(mid 383.075434 -228.898345)
		(end 382.888236 -228.948488)
		(width 0.088646)
		(layer "In6.Cu")
		(net "M_H_CPU0_SB_DQS_DN<7>")
	)
	(segment
		(start 461.174846 -217.866976)
		(end 460.889096 -218.152726)
		(width 0.20066)
		(layer "F.Cu")
		(net "M_H_CPU0_SB_DQS_DN<6>")
	)
	(segment
		(start 458.549248 -218.141804)
		(end 458.543152 -218.1479)
		(width 0.1016)
		(layer "F.Cu")
		(net "M_H_CPU0_SB_DQS_DN<6>")
	)
	(segment
		(start 457.401422 -218.295474)
		(end 456.91806 -218.295474)
		(width 0.20066)
		(layer "F.Cu")
		(net "M_H_CPU0_SB_DQS_DN<6>")
	)
	(segment
		(start 460.559404 -218.141804)
		(end 458.549248 -218.141804)
		(width 0.1016)
		(layer "F.Cu")
		(net "M_H_CPU0_SB_DQS_DN<6>")
	)
	(segment
		(start 373.67718 -232.528618)
		(end 373.677434 -232.528364)
		(width 0.20066)
		(layer "F.Cu")
		(net "M_H_CPU0_SB_DQS_DN<6>")
	)
	(segment
		(start 458.22616 -218.1479)
		(end 457.948792 -217.870532)
		(width 0.20066)
		(layer "F.Cu")
		(net "M_H_CPU0_SB_DQS_DN<6>")
	)
	(segment
		(start 463.1563 -218.566746)
		(end 462.902046 -218.312492)
		(width 0.20066)
		(layer "F.Cu")
		(net "M_H_CPU0_SB_DQS_DN<6>")
	)
	(segment
		(start 455.011282 -218.566746)
		(end 456.116182 -218.566746)
		(width 0.20066)
		(layer "F.Cu")
		(net "M_H_CPU0_SB_DQS_DN<6>")
	)
	(segment
		(start 461.664812 -217.866976)
		(end 461.174846 -217.866976)
		(width 0.20066)
		(layer "F.Cu")
		(net "M_H_CPU0_SB_DQS_DN<6>")
	)
	(segment
		(start 457.948792 -217.870532)
		(end 457.826364 -217.870532)
		(width 0.20066)
		(layer "F.Cu")
		(net "M_H_CPU0_SB_DQS_DN<6>")
	)
	(segment
		(start 460.889096 -218.152726)
		(end 460.570326 -218.152726)
		(width 0.20066)
		(layer "F.Cu")
		(net "M_H_CPU0_SB_DQS_DN<6>")
	)
	(segment
		(start 456.91806 -218.295474)
		(end 456.646788 -218.566746)
		(width 0.20066)
		(layer "F.Cu")
		(net "M_H_CPU0_SB_DQS_DN<6>")
	)
	(segment
		(start 458.538326 -218.1479)
		(end 458.22616 -218.1479)
		(width 0.20066)
		(layer "F.Cu")
		(net "M_H_CPU0_SB_DQS_DN<6>")
	)
	(segment
		(start 458.543152 -218.1479)
		(end 458.538326 -218.1479)
		(width 0.101854)
		(layer "F.Cu")
		(net "M_H_CPU0_SB_DQS_DN<6>")
	)
	(segment
		(start 460.570326 -218.152726)
		(end 460.559404 -218.141804)
		(width 0.1016)
		(layer "F.Cu")
		(net "M_H_CPU0_SB_DQS_DN<6>")
	)
	(segment
		(start 457.826364 -217.870532)
		(end 457.401422 -218.295474)
		(width 0.20066)
		(layer "F.Cu")
		(net "M_H_CPU0_SB_DQS_DN<6>")
	)
	(segment
		(start 462.902046 -218.312492)
		(end 462.110328 -218.312492)
		(width 0.20066)
		(layer "F.Cu")
		(net "M_H_CPU0_SB_DQS_DN<6>")
	)
	(segment
		(start 373.67718 -233.064304)
		(end 373.67718 -232.528618)
		(width 0.20066)
		(layer "F.Cu")
		(net "M_H_CPU0_SB_DQS_DN<6>")
	)
	(segment
		(start 462.110328 -218.312492)
		(end 461.664812 -217.866976)
		(width 0.20066)
		(layer "F.Cu")
		(net "M_H_CPU0_SB_DQS_DN<6>")
	)
	(segment
		(start 456.646788 -218.566746)
		(end 456.116182 -218.566746)
		(width 0.20066)
		(layer "F.Cu")
		(net "M_H_CPU0_SB_DQS_DN<6>")
	)
	(segment
		(start 463.659982 -218.566746)
		(end 463.1563 -218.566746)
		(width 0.20066)
		(layer "F.Cu")
		(net "M_H_CPU0_SB_DQS_DN<6>")
	)
	(segment
		(start 427.298104 -210.961986)
		(end 426.988224 -210.961986)
		(width 0.18288)
		(layer "In11.Cu")
		(net "M_H_CPU0_SB_DQS_DN<6>")
	)
	(segment
		(start 441.61075 -211.331302)
		(end 441.143644 -211.798408)
		(width 0.18288)
		(layer "In11.Cu")
		(net "M_H_CPU0_SB_DQS_DN<6>")
	)
	(segment
		(start 441.143644 -211.798408)
		(end 440.835542 -211.926424)
		(width 0.18288)
		(layer "In11.Cu")
		(net "M_H_CPU0_SB_DQS_DN<6>")
	)
	(segment
		(start 410.701744 -212.511132)
		(end 410.153104 -212.511132)
		(width 0.18288)
		(layer "In11.Cu")
		(net "M_H_CPU0_SB_DQS_DN<6>")
	)
	(segment
		(start 388.079996 -230.519224)
		(end 388.020052 -230.45928)
		(width 0.088646)
		(layer "In11.Cu")
		(net "M_H_CPU0_SB_DQS_DN<6>")
	)
	(segment
		(start 410.028644 -212.635592)
		(end 409.480004 -212.635592)
		(width 0.18288)
		(layer "In11.Cu")
		(net "M_H_CPU0_SB_DQS_DN<6>")
	)
	(segment
		(start 436.051706 -211.340954)
		(end 435.529482 -211.340954)
		(width 0.18288)
		(layer "In11.Cu")
		(net "M_H_CPU0_SB_DQS_DN<6>")
	)
	(segment
		(start 439.37047 -211.932012)
		(end 437.933846 -211.932012)
		(width 0.18288)
		(layer "In11.Cu")
		(net "M_H_CPU0_SB_DQS_DN<6>")
	)
	(segment
		(start 429.489362 -210.33613)
		(end 428.940722 -210.33613)
		(width 0.18288)
		(layer "In11.Cu")
		(net "M_H_CPU0_SB_DQS_DN<6>")
	)
	(segment
		(start 402.917152 -214.815928)
		(end 402.74113 -214.815928)
		(width 0.18288)
		(layer "In11.Cu")
		(net "M_H_CPU0_SB_DQS_DN<6>")
	)
	(segment
		(start 411.499304 -212.511132)
		(end 411.374844 -212.635592)
		(width 0.18288)
		(layer "In11.Cu")
		(net "M_H_CPU0_SB_DQS_DN<6>")
	)
	(segment
		(start 405.38273 -212.174328)
		(end 404.384256 -213.172802)
		(width 0.18288)
		(layer "In11.Cu")
		(net "M_H_CPU0_SB_DQS_DN<6>")
	)
	(segment
		(start 375.758964 -232.212642)
		(end 375.744232 -232.204006)
		(width 0.088646)
		(layer "In11.Cu")
		(net "M_H_CPU0_SB_DQS_DN<6>")
	)
	(segment
		(start 415.784538 -212.176868)
		(end 414.84931 -212.176868)
		(width 0.18288)
		(layer "In11.Cu")
		(net "M_H_CPU0_SB_DQS_DN<6>")
	)
	(segment
		(start 374.429528 -232.203752)
		(end 374.330214 -232.262426)
		(width 0.088646)
		(layer "In11.Cu")
		(net "M_H_CPU0_SB_DQS_DN<6>")
	)
	(segment
		(start 433.602638 -211.201762)
		(end 433.053998 -211.201762)
		(width 0.18288)
		(layer "In11.Cu")
		(net "M_H_CPU0_SB_DQS_DN<6>")
	)
	(segment
		(start 451.78726 -217.866722)
		(end 451.413626 -217.866722)
		(width 0.18288)
		(layer "In11.Cu")
		(net "M_H_CPU0_SB_DQS_DN<6>")
	)
	(segment
		(start 381.948436 -232.204006)
		(end 381.938022 -232.210102)
		(width 0.088646)
		(layer "In11.Cu")
		(net "M_H_CPU0_SB_DQS_DN<6>")
	)
	(segment
		(start 377.638564 -232.212642)
		(end 377.623832 -232.204006)
		(width 0.088646)
		(layer "In11.Cu")
		(net "M_H_CPU0_SB_DQS_DN<6>")
	)
	(segment
		(start 386.92963 -231.536494)
		(end 386.92963 -231.714548)
		(width 0.088646)
		(layer "In11.Cu")
		(net "M_H_CPU0_SB_DQS_DN<6>")
	)
	(segment
		(start 402.181568 -217.404696)
		(end 394.81887 -224.767394)
		(width 0.18288)
		(layer "In11.Cu")
		(net "M_H_CPU0_SB_DQS_DN<6>")
	)
	(segment
		(start 414.17621 -212.301328)
		(end 414.05175 -212.176868)
		(width 0.18288)
		(layer "In11.Cu")
		(net "M_H_CPU0_SB_DQS_DN<6>")
	)
	(segment
		(start 382.888236 -232.204006)
		(end 382.887728 -232.203752)
		(width 0.088646)
		(layer "In11.Cu")
		(net "M_H_CPU0_SB_DQS_DN<6>")
	)
	(segment
		(start 414.84931 -212.176868)
		(end 414.72485 -212.301328)
		(width 0.18288)
		(layer "In11.Cu")
		(net "M_H_CPU0_SB_DQS_DN<6>")
	)
	(segment
		(start 403.305264 -214.427816)
		(end 402.917152 -214.815928)
		(width 0.18288)
		(layer "In11.Cu")
		(net "M_H_CPU0_SB_DQS_DN<6>")
	)
	(segment
		(start 432.929538 -211.077302)
		(end 432.021488 -211.077302)
		(width 0.18288)
		(layer "In11.Cu")
		(net "M_H_CPU0_SB_DQS_DN<6>")
	)
	(segment
		(start 439.62955 -212.191092)
		(end 439.37047 -211.932012)
		(width 0.18288)
		(layer "In11.Cu")
		(net "M_H_CPU0_SB_DQS_DN<6>")
	)
	(segment
		(start 424.54195 -212.191092)
		(end 424.292014 -211.941156)
		(width 0.18288)
		(layer "In11.Cu")
		(net "M_H_CPU0_SB_DQS_DN<6>")
	)
	(segment
		(start 450.074284 -217.867992)
		(end 449.09486 -217.462354)
		(width 0.18288)
		(layer "In11.Cu")
		(net "M_H_CPU0_SB_DQS_DN<6>")
	)
	(segment
		(start 403.305264 -214.251794)
		(end 403.305264 -214.427816)
		(width 0.18288)
		(layer "In11.Cu")
		(net "M_H_CPU0_SB_DQS_DN<6>")
	)
	(segment
		(start 433.727098 -211.077302)
		(end 433.602638 -211.201762)
		(width 0.18288)
		(layer "In11.Cu")
		(net "M_H_CPU0_SB_DQS_DN<6>")
	)
	(segment
		(start 420.964106 -213.040976)
		(end 420.441882 -213.040976)
		(width 0.18288)
		(layer "In11.Cu")
		(net "M_H_CPU0_SB_DQS_DN<6>")
	)
	(segment
		(start 444.532766 -213.165182)
		(end 442.867288 -211.499704)
		(width 0.18288)
		(layer "In11.Cu")
		(net "M_H_CPU0_SB_DQS_DN<6>")
	)
	(segment
		(start 442.867288 -211.499704)
		(end 442.459872 -211.331302)
		(width 0.18288)
		(layer "In11.Cu")
		(net "M_H_CPU0_SB_DQS_DN<6>")
	)
	(segment
		(start 433.053998 -211.201762)
		(end 432.929538 -211.077302)
		(width 0.18288)
		(layer "In11.Cu")
		(net "M_H_CPU0_SB_DQS_DN<6>")
	)
	(segment
		(start 374.330214 -232.262426)
		(end 374.262396 -232.288842)
		(width 0.088646)
		(layer "In11.Cu")
		(net "M_H_CPU0_SB_DQS_DN<6>")
	)
	(segment
		(start 374.814592 -232.210102)
		(end 374.804178 -232.204006)
		(width 0.088646)
		(layer "In11.Cu")
		(net "M_H_CPU0_SB_DQS_DN<6>")
	)
	(segment
		(start 435.529482 -211.340954)
		(end 435.26583 -211.077302)
		(width 0.18288)
		(layer "In11.Cu")
		(net "M_H_CPU0_SB_DQS_DN<6>")
	)
	(segment
		(start 417.832794 -212.782912)
		(end 417.708334 -212.907372)
		(width 0.18288)
		(layer "In11.Cu")
		(net "M_H_CPU0_SB_DQS_DN<6>")
	)
	(segment
		(start 411.374844 -212.635592)
		(end 410.826204 -212.635592)
		(width 0.18288)
		(layer "In11.Cu")
		(net "M_H_CPU0_SB_DQS_DN<6>")
	)
	(segment
		(start 373.686832 -232.381044)
		(end 373.677434 -232.403396)
		(width 0.088646)
		(layer "In11.Cu")
		(net "M_H_CPU0_SB_DQS_DN<6>")
	)
	(segment
		(start 419.457886 -212.782912)
		(end 419.333426 -212.907372)
		(width 0.18288)
		(layer "In11.Cu")
		(net "M_H_CPU0_SB_DQS_DN<6>")
	)
	(segment
		(start 387.795262 -230.45928)
		(end 387.617462 -230.63708)
		(width 0.088646)
		(layer "In11.Cu")
		(net "M_H_CPU0_SB_DQS_DN<6>")
	)
	(segment
		(start 428.940722 -210.33613)
		(end 428.816262 -210.21167)
		(width 0.18288)
		(layer "In11.Cu")
		(net "M_H_CPU0_SB_DQS_DN<6>")
	)
	(segment
		(start 428.816262 -210.21167)
		(end 428.04842 -210.21167)
		(width 0.18288)
		(layer "In11.Cu")
		(net "M_H_CPU0_SB_DQS_DN<6>")
	)
	(segment
		(start 440.835542 -211.926424)
		(end 440.416442 -211.926424)
		(width 0.18288)
		(layer "In11.Cu")
		(net "M_H_CPU0_SB_DQS_DN<6>")
	)
	(segment
		(start 421.228774 -212.776308)
		(end 420.964106 -213.040976)
		(width 0.18288)
		(layer "In11.Cu")
		(net "M_H_CPU0_SB_DQS_DN<6>")
	)
	(segment
		(start 447.736214 -216.103708)
		(end 446.861438 -215.74125)
		(width 0.18288)
		(layer "In11.Cu")
		(net "M_H_CPU0_SB_DQS_DN<6>")
	)
	(segment
		(start 440.416442 -211.926424)
		(end 440.151774 -212.191092)
		(width 0.18288)
		(layer "In11.Cu")
		(net "M_H_CPU0_SB_DQS_DN<6>")
	)
	(segment
		(start 420.183818 -212.782912)
		(end 419.457886 -212.782912)
		(width 0.18288)
		(layer "In11.Cu")
		(net "M_H_CPU0_SB_DQS_DN<6>")
	)
	(segment
		(start 453.479408 -218.548966)
		(end 452.9201 -218.548966)
		(width 0.18288)
		(layer "In11.Cu")
		(net "M_H_CPU0_SB_DQS_DN<6>")
	)
	(segment
		(start 409.480004 -212.635592)
		(end 409.355544 -212.511132)
		(width 0.18288)
		(layer "In11.Cu")
		(net "M_H_CPU0_SB_DQS_DN<6>")
	)
	(segment
		(start 410.153104 -212.511132)
		(end 410.028644 -212.635592)
		(width 0.18288)
		(layer "In11.Cu")
		(net "M_H_CPU0_SB_DQS_DN<6>")
	)
	(segment
		(start 410.826204 -212.635592)
		(end 410.701744 -212.511132)
		(width 0.18288)
		(layer "In11.Cu")
		(net "M_H_CPU0_SB_DQS_DN<6>")
	)
	(segment
		(start 455.011282 -218.566746)
		(end 454.723246 -218.27998)
		(width 0.18288)
		(layer "In11.Cu")
		(net "M_H_CPU0_SB_DQS_DN<6>")
	)
	(segment
		(start 432.021488 -211.077302)
		(end 431.155856 -210.21167)
		(width 0.18288)
		(layer "In11.Cu")
		(net "M_H_CPU0_SB_DQS_DN<6>")
	)
	(segment
		(start 451.139306 -218.141042)
		(end 450.617082 -218.141042)
		(width 0.18288)
		(layer "In11.Cu")
		(net "M_H_CPU0_SB_DQS_DN<6>")
	)
	(segment
		(start 437.933846 -211.932012)
		(end 437.07812 -211.076286)
		(width 0.18288)
		(layer "In11.Cu")
		(net "M_H_CPU0_SB_DQS_DN<6>")
	)
	(segment
		(start 420.441882 -213.040976)
		(end 420.183818 -212.782912)
		(width 0.18288)
		(layer "In11.Cu")
		(net "M_H_CPU0_SB_DQS_DN<6>")
	)
	(segment
		(start 418.784786 -212.907372)
		(end 418.660326 -212.782912)
		(width 0.18288)
		(layer "In11.Cu")
		(net "M_H_CPU0_SB_DQS_DN<6>")
	)
	(segment
		(start 380.453646 -232.210102)
		(end 380.443232 -232.204006)
		(width 0.088646)
		(layer "In11.Cu")
		(net "M_H_CPU0_SB_DQS_DN<6>")
	)
	(segment
		(start 425.328842 -211.926424)
		(end 425.064174 -212.191092)
		(width 0.18288)
		(layer "In11.Cu")
		(net "M_H_CPU0_SB_DQS_DN<6>")
	)
	(segment
		(start 403.996144 -213.736936)
		(end 403.820122 -213.736936)
		(width 0.18288)
		(layer "In11.Cu")
		(net "M_H_CPU0_SB_DQS_DN<6>")
	)
	(segment
		(start 402.181568 -215.37549)
		(end 402.181568 -217.404696)
		(width 0.18288)
		(layer "In11.Cu")
		(net "M_H_CPU0_SB_DQS_DN<6>")
	)
	(segment
		(start 426.023786 -211.926424)
		(end 425.328842 -211.926424)
		(width 0.18288)
		(layer "In11.Cu")
		(net "M_H_CPU0_SB_DQS_DN<6>")
	)
	(segment
		(start 416.390582 -212.782912)
		(end 415.784538 -212.176868)
		(width 0.18288)
		(layer "In11.Cu")
		(net "M_H_CPU0_SB_DQS_DN<6>")
	)
	(segment
		(start 414.05175 -212.176868)
		(end 412.895288 -212.176868)
		(width 0.18288)
		(layer "In11.Cu")
		(net "M_H_CPU0_SB_DQS_DN<6>")
	)
	(segment
		(start 389.985504 -230.519224)
		(end 388.079996 -230.519224)
		(width 0.18288)
		(layer "In11.Cu")
		(net "M_H_CPU0_SB_DQS_DN<6>")
	)
	(segment
		(start 451.413626 -217.866722)
		(end 451.139306 -218.141042)
		(width 0.18288)
		(layer "In11.Cu")
		(net "M_H_CPU0_SB_DQS_DN<6>")
	)
	(segment
		(start 394.81887 -225.685858)
		(end 389.985504 -230.519224)
		(width 0.18288)
		(layer "In11.Cu")
		(net "M_H_CPU0_SB_DQS_DN<6>")
	)
	(segment
		(start 426.988224 -210.961986)
		(end 426.023786 -211.926424)
		(width 0.18288)
		(layer "In11.Cu")
		(net "M_H_CPU0_SB_DQS_DN<6>")
	)
	(segment
		(start 387.617462 -230.848408)
		(end 386.92963 -231.536494)
		(width 0.088646)
		(layer "In11.Cu")
		(net "M_H_CPU0_SB_DQS_DN<6>")
	)
	(segment
		(start 424.292014 -211.941156)
		(end 422.858184 -211.941156)
		(width 0.18288)
		(layer "In11.Cu")
		(net "M_H_CPU0_SB_DQS_DN<6>")
	)
	(segment
		(start 450.344032 -217.867992)
		(end 450.074284 -217.867992)
		(width 0.18288)
		(layer "In11.Cu")
		(net "M_H_CPU0_SB_DQS_DN<6>")
	)
	(segment
		(start 446.02146 -214.129874)
		(end 445.429386 -213.537546)
		(width 0.18288)
		(layer "In11.Cu")
		(net "M_H_CPU0_SB_DQS_DN<6>")
	)
	(segment
		(start 404.384256 -213.172802)
		(end 404.384256 -213.348824)
		(width 0.18288)
		(layer "In11.Cu")
		(net "M_H_CPU0_SB_DQS_DN<6>")
	)
	(segment
		(start 445.429386 -213.537546)
		(end 444.532766 -213.165182)
		(width 0.18288)
		(layer "In11.Cu")
		(net "M_H_CPU0_SB_DQS_DN<6>")
	)
	(segment
		(start 407.99385 -212.174328)
		(end 405.38273 -212.174328)
		(width 0.18288)
		(layer "In11.Cu")
		(net "M_H_CPU0_SB_DQS_DN<6>")
	)
	(segment
		(start 454.723246 -218.27998)
		(end 454.129902 -218.27998)
		(width 0.18288)
		(layer "In11.Cu")
		(net "M_H_CPU0_SB_DQS_DN<6>")
	)
	(segment
		(start 373.782336 -232.29824)
		(end 373.760238 -232.307638)
		(width 0.088646)
		(layer "In11.Cu")
		(net "M_H_CPU0_SB_DQS_DN<6>")
	)
	(segment
		(start 428.04842 -210.21167)
		(end 427.298104 -210.961986)
		(width 0.18288)
		(layer "In11.Cu")
		(net "M_H_CPU0_SB_DQS_DN<6>")
	)
	(segment
		(start 387.617462 -230.63708)
		(end 387.617462 -230.848408)
		(width 0.088646)
		(layer "In11.Cu")
		(net "M_H_CPU0_SB_DQS_DN<6>")
	)
	(segment
		(start 417.035234 -212.782912)
		(end 416.390582 -212.782912)
		(width 0.18288)
		(layer "In11.Cu")
		(net "M_H_CPU0_SB_DQS_DN<6>")
	)
	(segment
		(start 404.384256 -213.348824)
		(end 403.996144 -213.736936)
		(width 0.18288)
		(layer "In11.Cu")
		(net "M_H_CPU0_SB_DQS_DN<6>")
	)
	(segment
		(start 374.262396 -232.288842)
		(end 373.782336 -232.29824)
		(width 0.088646)
		(layer "In11.Cu")
		(net "M_H_CPU0_SB_DQS_DN<6>")
	)
	(segment
		(start 379.518164 -232.212642)
		(end 379.503432 -232.204006)
		(width 0.088646)
		(layer "In11.Cu")
		(net "M_H_CPU0_SB_DQS_DN<6>")
	)
	(segment
		(start 437.07812 -211.076286)
		(end 436.316374 -211.076286)
		(width 0.18288)
		(layer "In11.Cu")
		(net "M_H_CPU0_SB_DQS_DN<6>")
	)
	(segment
		(start 450.617082 -218.141042)
		(end 450.344032 -217.867992)
		(width 0.18288)
		(layer "In11.Cu")
		(net "M_H_CPU0_SB_DQS_DN<6>")
	)
	(segment
		(start 429.613822 -210.21167)
		(end 429.489362 -210.33613)
		(width 0.18288)
		(layer "In11.Cu")
		(net "M_H_CPU0_SB_DQS_DN<6>")
	)
	(segment
		(start 446.565782 -215.445594)
		(end 446.02146 -214.129874)
		(width 0.18288)
		(layer "In11.Cu")
		(net "M_H_CPU0_SB_DQS_DN<6>")
	)
	(segment
		(start 419.333426 -212.907372)
		(end 418.784786 -212.907372)
		(width 0.18288)
		(layer "In11.Cu")
		(net "M_H_CPU0_SB_DQS_DN<6>")
	)
	(segment
		(start 373.677434 -232.403396)
		(end 373.677434 -232.528364)
		(width 0.088646)
		(layer "In11.Cu")
		(net "M_H_CPU0_SB_DQS_DN<6>")
	)
	(segment
		(start 440.151774 -212.191092)
		(end 439.62955 -212.191092)
		(width 0.18288)
		(layer "In11.Cu")
		(net "M_H_CPU0_SB_DQS_DN<6>")
	)
	(segment
		(start 378.578364 -232.212642)
		(end 378.563632 -232.204006)
		(width 0.088646)
		(layer "In11.Cu")
		(net "M_H_CPU0_SB_DQS_DN<6>")
	)
	(segment
		(start 409.355544 -212.511132)
		(end 408.806904 -212.511132)
		(width 0.18288)
		(layer "In11.Cu")
		(net "M_H_CPU0_SB_DQS_DN<6>")
	)
	(segment
		(start 422.858184 -211.941156)
		(end 422.023032 -212.776308)
		(width 0.18288)
		(layer "In11.Cu")
		(net "M_H_CPU0_SB_DQS_DN<6>")
	)
	(segment
		(start 422.023032 -212.776308)
		(end 421.228774 -212.776308)
		(width 0.18288)
		(layer "In11.Cu")
		(net "M_H_CPU0_SB_DQS_DN<6>")
	)
	(segment
		(start 452.018908 -218.09837)
		(end 451.78726 -217.866722)
		(width 0.18288)
		(layer "In11.Cu")
		(net "M_H_CPU0_SB_DQS_DN<6>")
	)
	(segment
		(start 417.159694 -212.907372)
		(end 417.035234 -212.782912)
		(width 0.18288)
		(layer "In11.Cu")
		(net "M_H_CPU0_SB_DQS_DN<6>")
	)
	(segment
		(start 454.129902 -218.27998)
		(end 453.479408 -218.548966)
		(width 0.18288)
		(layer "In11.Cu")
		(net "M_H_CPU0_SB_DQS_DN<6>")
	)
	(segment
		(start 374.804178 -232.204006)
		(end 374.804432 -232.203752)
		(width 0.088646)
		(layer "In11.Cu")
		(net "M_H_CPU0_SB_DQS_DN<6>")
	)
	(segment
		(start 436.316374 -211.076286)
		(end 436.051706 -211.340954)
		(width 0.18288)
		(layer "In11.Cu")
		(net "M_H_CPU0_SB_DQS_DN<6>")
	)
	(segment
		(start 412.895288 -212.176868)
		(end 412.561024 -212.511132)
		(width 0.18288)
		(layer "In11.Cu")
		(net "M_H_CPU0_SB_DQS_DN<6>")
	)
	(segment
		(start 435.26583 -211.077302)
		(end 433.727098 -211.077302)
		(width 0.18288)
		(layer "In11.Cu")
		(net "M_H_CPU0_SB_DQS_DN<6>")
	)
	(segment
		(start 431.155856 -210.21167)
		(end 429.613822 -210.21167)
		(width 0.18288)
		(layer "In11.Cu")
		(net "M_H_CPU0_SB_DQS_DN<6>")
	)
	(segment
		(start 388.020052 -230.45928)
		(end 387.795262 -230.45928)
		(width 0.088646)
		(layer "In11.Cu")
		(net "M_H_CPU0_SB_DQS_DN<6>")
	)
	(segment
		(start 425.064174 -212.191092)
		(end 424.54195 -212.191092)
		(width 0.18288)
		(layer "In11.Cu")
		(net "M_H_CPU0_SB_DQS_DN<6>")
	)
	(segment
		(start 418.660326 -212.782912)
		(end 417.832794 -212.782912)
		(width 0.18288)
		(layer "In11.Cu")
		(net "M_H_CPU0_SB_DQS_DN<6>")
	)
	(segment
		(start 449.09486 -217.462354)
		(end 447.736214 -216.103708)
		(width 0.18288)
		(layer "In11.Cu")
		(net "M_H_CPU0_SB_DQS_DN<6>")
	)
	(segment
		(start 373.760238 -232.307638)
		(end 373.686832 -232.381044)
		(width 0.088646)
		(layer "In11.Cu")
		(net "M_H_CPU0_SB_DQS_DN<6>")
	)
	(segment
		(start 412.561024 -212.511132)
		(end 411.499304 -212.511132)
		(width 0.18288)
		(layer "In11.Cu")
		(net "M_H_CPU0_SB_DQS_DN<6>")
	)
	(segment
		(start 452.9201 -218.548966)
		(end 452.018908 -218.09837)
		(width 0.18288)
		(layer "In11.Cu")
		(net "M_H_CPU0_SB_DQS_DN<6>")
	)
	(segment
		(start 402.74113 -214.815928)
		(end 402.181568 -215.37549)
		(width 0.18288)
		(layer "In11.Cu")
		(net "M_H_CPU0_SB_DQS_DN<6>")
	)
	(segment
		(start 414.72485 -212.301328)
		(end 414.17621 -212.301328)
		(width 0.18288)
		(layer "In11.Cu")
		(net "M_H_CPU0_SB_DQS_DN<6>")
	)
	(segment
		(start 394.81887 -224.767394)
		(end 394.81887 -225.685858)
		(width 0.18288)
		(layer "In11.Cu")
		(net "M_H_CPU0_SB_DQS_DN<6>")
	)
	(segment
		(start 442.459872 -211.331302)
		(end 441.61075 -211.331302)
		(width 0.18288)
		(layer "In11.Cu")
		(net "M_H_CPU0_SB_DQS_DN<6>")
	)
	(segment
		(start 446.861438 -215.74125)
		(end 446.565782 -215.445594)
		(width 0.18288)
		(layer "In11.Cu")
		(net "M_H_CPU0_SB_DQS_DN<6>")
	)
	(segment
		(start 408.806904 -212.511132)
		(end 407.99385 -212.174328)
		(width 0.18288)
		(layer "In11.Cu")
		(net "M_H_CPU0_SB_DQS_DN<6>")
	)
	(segment
		(start 386.08254 -232.203752)
		(end 386.082032 -232.204006)
		(width 0.088646)
		(layer "In11.Cu")
		(net "M_H_CPU0_SB_DQS_DN<6>")
	)
	(segment
		(start 403.820122 -213.736936)
		(end 403.305264 -214.251794)
		(width 0.18288)
		(layer "In11.Cu")
		(net "M_H_CPU0_SB_DQS_DN<6>")
	)
	(segment
		(start 417.708334 -212.907372)
		(end 417.159694 -212.907372)
		(width 0.18288)
		(layer "In11.Cu")
		(net "M_H_CPU0_SB_DQS_DN<6>")
	)
	(arc
		(start 385.142232 -232.204006)
		(mid 384.955034 -232.153863)
		(end 384.767836 -232.204006)
		(width 0.088646)
		(layer "In11.Cu")
		(net "M_H_CPU0_SB_DQS_DN<6>")
	)
	(arc
		(start 382.887728 -232.203752)
		(mid 382.605309 -232.279562)
		(end 382.322832 -232.204006)
		(width 0.088646)
		(layer "In11.Cu")
		(net "M_H_CPU0_SB_DQS_DN<6>")
	)
	(arc
		(start 379.503432 -232.204006)
		(mid 379.316234 -232.153863)
		(end 379.129036 -232.204006)
		(width 0.088646)
		(layer "In11.Cu")
		(net "M_H_CPU0_SB_DQS_DN<6>")
	)
	(arc
		(start 381.382778 -232.204006)
		(mid 381.19558 -232.153863)
		(end 381.008382 -232.204006)
		(width 0.088646)
		(layer "In11.Cu")
		(net "M_H_CPU0_SB_DQS_DN<6>")
	)
	(arc
		(start 386.92963 -231.714548)
		(mid 386.647275 -232.203709)
		(end 386.08254 -232.203752)
		(width 0.088646)
		(layer "In11.Cu")
		(net "M_H_CPU0_SB_DQS_DN<6>")
	)
	(arc
		(start 381.008382 -232.204006)
		(mid 380.731823 -232.279749)
		(end 380.453646 -232.210102)
		(width 0.088646)
		(layer "In11.Cu")
		(net "M_H_CPU0_SB_DQS_DN<6>")
	)
	(arc
		(start 380.068836 -232.204006)
		(mid 379.794637 -232.279841)
		(end 379.518164 -232.212642)
		(width 0.088646)
		(layer "In11.Cu")
		(net "M_H_CPU0_SB_DQS_DN<6>")
	)
	(arc
		(start 384.767836 -232.204006)
		(mid 384.485134 -232.279782)
		(end 384.202432 -232.204006)
		(width 0.088646)
		(layer "In11.Cu")
		(net "M_H_CPU0_SB_DQS_DN<6>")
	)
	(arc
		(start 376.309636 -232.204006)
		(mid 376.035437 -232.279841)
		(end 375.758964 -232.212642)
		(width 0.088646)
		(layer "In11.Cu")
		(net "M_H_CPU0_SB_DQS_DN<6>")
	)
	(arc
		(start 381.938022 -232.210102)
		(mid 381.65959 -232.279948)
		(end 381.382778 -232.204006)
		(width 0.088646)
		(layer "In11.Cu")
		(net "M_H_CPU0_SB_DQS_DN<6>")
	)
	(arc
		(start 383.262632 -232.204006)
		(mid 383.075434 -232.153863)
		(end 382.888236 -232.204006)
		(width 0.088646)
		(layer "In11.Cu")
		(net "M_H_CPU0_SB_DQS_DN<6>")
	)
	(arc
		(start 375.744232 -232.204006)
		(mid 375.557034 -232.153863)
		(end 375.369836 -232.204006)
		(width 0.088646)
		(layer "In11.Cu")
		(net "M_H_CPU0_SB_DQS_DN<6>")
	)
	(arc
		(start 378.189236 -232.204006)
		(mid 377.915037 -232.279841)
		(end 377.638564 -232.212642)
		(width 0.088646)
		(layer "In11.Cu")
		(net "M_H_CPU0_SB_DQS_DN<6>")
	)
	(arc
		(start 374.804432 -232.203752)
		(mid 374.61698 -232.153516)
		(end 374.429528 -232.203752)
		(width 0.088646)
		(layer "In11.Cu")
		(net "M_H_CPU0_SB_DQS_DN<6>")
	)
	(arc
		(start 377.249436 -232.204006)
		(mid 376.966734 -232.279782)
		(end 376.684032 -232.204006)
		(width 0.088646)
		(layer "In11.Cu")
		(net "M_H_CPU0_SB_DQS_DN<6>")
	)
	(arc
		(start 376.684032 -232.204006)
		(mid 376.496834 -232.153863)
		(end 376.309636 -232.204006)
		(width 0.088646)
		(layer "In11.Cu")
		(net "M_H_CPU0_SB_DQS_DN<6>")
	)
	(arc
		(start 386.082032 -232.204006)
		(mid 385.894834 -232.153863)
		(end 385.707636 -232.204006)
		(width 0.088646)
		(layer "In11.Cu")
		(net "M_H_CPU0_SB_DQS_DN<6>")
	)
	(arc
		(start 377.623832 -232.204006)
		(mid 377.436634 -232.153863)
		(end 377.249436 -232.204006)
		(width 0.088646)
		(layer "In11.Cu")
		(net "M_H_CPU0_SB_DQS_DN<6>")
	)
	(arc
		(start 383.828036 -232.204006)
		(mid 383.545334 -232.279782)
		(end 383.262632 -232.204006)
		(width 0.088646)
		(layer "In11.Cu")
		(net "M_H_CPU0_SB_DQS_DN<6>")
	)
	(arc
		(start 385.707636 -232.204006)
		(mid 385.424934 -232.279782)
		(end 385.142232 -232.204006)
		(width 0.088646)
		(layer "In11.Cu")
		(net "M_H_CPU0_SB_DQS_DN<6>")
	)
	(arc
		(start 384.202432 -232.204006)
		(mid 384.015234 -232.153863)
		(end 383.828036 -232.204006)
		(width 0.088646)
		(layer "In11.Cu")
		(net "M_H_CPU0_SB_DQS_DN<6>")
	)
	(arc
		(start 378.563632 -232.204006)
		(mid 378.376434 -232.153863)
		(end 378.189236 -232.204006)
		(width 0.088646)
		(layer "In11.Cu")
		(net "M_H_CPU0_SB_DQS_DN<6>")
	)
	(arc
		(start 375.369836 -232.204006)
		(mid 375.093023 -232.279876)
		(end 374.814592 -232.210102)
		(width 0.088646)
		(layer "In11.Cu")
		(net "M_H_CPU0_SB_DQS_DN<6>")
	)
	(arc
		(start 379.129036 -232.204006)
		(mid 378.854837 -232.279841)
		(end 378.578364 -232.212642)
		(width 0.088646)
		(layer "In11.Cu")
		(net "M_H_CPU0_SB_DQS_DN<6>")
	)
	(arc
		(start 382.322832 -232.204006)
		(mid 382.135634 -232.153863)
		(end 381.948436 -232.204006)
		(width 0.088646)
		(layer "In11.Cu")
		(net "M_H_CPU0_SB_DQS_DN<6>")
	)
	(arc
		(start 380.443232 -232.204006)
		(mid 380.256034 -232.153863)
		(end 380.068836 -232.204006)
		(width 0.088646)
		(layer "In11.Cu")
		(net "M_H_CPU0_SB_DQS_DN<6>")
	)
	(segment
		(start 460.889096 -227.50272)
		(end 460.570326 -227.50272)
		(width 0.20066)
		(layer "F.Cu")
		(net "M_H_CPU0_SB_DQS_DN<5>")
	)
	(segment
		(start 458.22616 -227.497894)
		(end 457.948792 -227.220526)
		(width 0.20066)
		(layer "F.Cu")
		(net "M_H_CPU0_SB_DQS_DN<5>")
	)
	(segment
		(start 456.91806 -227.645468)
		(end 456.646788 -227.91674)
		(width 0.20066)
		(layer "F.Cu")
		(net "M_H_CPU0_SB_DQS_DN<5>")
	)
	(segment
		(start 457.401422 -227.645468)
		(end 456.91806 -227.645468)
		(width 0.20066)
		(layer "F.Cu")
		(net "M_H_CPU0_SB_DQS_DN<5>")
	)
	(segment
		(start 457.826364 -227.220526)
		(end 457.401422 -227.645468)
		(width 0.20066)
		(layer "F.Cu")
		(net "M_H_CPU0_SB_DQS_DN<5>")
	)
	(segment
		(start 461.174846 -227.21697)
		(end 460.889096 -227.50272)
		(width 0.20066)
		(layer "F.Cu")
		(net "M_H_CPU0_SB_DQS_DN<5>")
	)
	(segment
		(start 460.570326 -227.50272)
		(end 460.559404 -227.491798)
		(width 0.1016)
		(layer "F.Cu")
		(net "M_H_CPU0_SB_DQS_DN<5>")
	)
	(segment
		(start 373.67718 -237.947454)
		(end 373.67718 -237.411768)
		(width 0.20066)
		(layer "F.Cu")
		(net "M_H_CPU0_SB_DQS_DN<5>")
	)
	(segment
		(start 457.948792 -227.220526)
		(end 457.826364 -227.220526)
		(width 0.20066)
		(layer "F.Cu")
		(net "M_H_CPU0_SB_DQS_DN<5>")
	)
	(segment
		(start 463.1563 -227.91674)
		(end 462.902046 -227.662486)
		(width 0.20066)
		(layer "F.Cu")
		(net "M_H_CPU0_SB_DQS_DN<5>")
	)
	(segment
		(start 373.67718 -237.411768)
		(end 373.677434 -237.411514)
		(width 0.20066)
		(layer "F.Cu")
		(net "M_H_CPU0_SB_DQS_DN<5>")
	)
	(segment
		(start 455.011282 -227.91674)
		(end 456.116182 -227.91674)
		(width 0.20066)
		(layer "F.Cu")
		(net "M_H_CPU0_SB_DQS_DN<5>")
	)
	(segment
		(start 463.659982 -227.91674)
		(end 463.1563 -227.91674)
		(width 0.20066)
		(layer "F.Cu")
		(net "M_H_CPU0_SB_DQS_DN<5>")
	)
	(segment
		(start 458.549248 -227.491798)
		(end 458.543152 -227.497894)
		(width 0.1016)
		(layer "F.Cu")
		(net "M_H_CPU0_SB_DQS_DN<5>")
	)
	(segment
		(start 456.646788 -227.91674)
		(end 456.116182 -227.91674)
		(width 0.20066)
		(layer "F.Cu")
		(net "M_H_CPU0_SB_DQS_DN<5>")
	)
	(segment
		(start 462.902046 -227.662486)
		(end 462.110328 -227.662486)
		(width 0.20066)
		(layer "F.Cu")
		(net "M_H_CPU0_SB_DQS_DN<5>")
	)
	(segment
		(start 458.538326 -227.497894)
		(end 458.22616 -227.497894)
		(width 0.20066)
		(layer "F.Cu")
		(net "M_H_CPU0_SB_DQS_DN<5>")
	)
	(segment
		(start 461.664812 -227.21697)
		(end 461.174846 -227.21697)
		(width 0.20066)
		(layer "F.Cu")
		(net "M_H_CPU0_SB_DQS_DN<5>")
	)
	(segment
		(start 462.110328 -227.662486)
		(end 461.664812 -227.21697)
		(width 0.20066)
		(layer "F.Cu")
		(net "M_H_CPU0_SB_DQS_DN<5>")
	)
	(segment
		(start 458.543152 -227.497894)
		(end 458.538326 -227.497894)
		(width 0.101854)
		(layer "F.Cu")
		(net "M_H_CPU0_SB_DQS_DN<5>")
	)
	(segment
		(start 460.559404 -227.491798)
		(end 458.549248 -227.491798)
		(width 0.1016)
		(layer "F.Cu")
		(net "M_H_CPU0_SB_DQS_DN<5>")
	)
	(segment
		(start 436.05323 -222.39097)
		(end 435.579266 -222.39097)
		(width 0.18288)
		(layer "In11.Cu")
		(net "M_H_CPU0_SB_DQS_DN<5>")
	)
	(segment
		(start 403.81047 -225.546412)
		(end 392.739118 -236.617764)
		(width 0.18288)
		(layer "In11.Cu")
		(net "M_H_CPU0_SB_DQS_DN<5>")
	)
	(segment
		(start 436.471822 -222.128588)
		(end 436.315612 -222.128588)
		(width 0.18288)
		(layer "In11.Cu")
		(net "M_H_CPU0_SB_DQS_DN<5>")
	)
	(segment
		(start 406.11933 -225.526092)
		(end 405.856694 -225.788728)
		(width 0.18288)
		(layer "In11.Cu")
		(net "M_H_CPU0_SB_DQS_DN<5>")
	)
	(segment
		(start 450.666866 -227.491036)
		(end 450.407532 -227.231702)
		(width 0.18288)
		(layer "In11.Cu")
		(net "M_H_CPU0_SB_DQS_DN<5>")
	)
	(segment
		(start 453.575166 -227.809552)
		(end 453.450706 -227.934012)
		(width 0.18288)
		(layer "In11.Cu")
		(net "M_H_CPU0_SB_DQS_DN<5>")
	)
	(segment
		(start 451.744588 -227.220526)
		(end 451.436232 -227.220526)
		(width 0.18288)
		(layer "In11.Cu")
		(net "M_H_CPU0_SB_DQS_DN<5>")
	)
	(segment
		(start 410.897832 -224.676208)
		(end 410.219906 -224.676208)
		(width 0.18288)
		(layer "In11.Cu")
		(net "M_H_CPU0_SB_DQS_DN<5>")
	)
	(segment
		(start 439.64479 -223.240854)
		(end 439.374788 -222.970852)
		(width 0.18288)
		(layer "In11.Cu")
		(net "M_H_CPU0_SB_DQS_DN<5>")
	)
	(segment
		(start 408.049222 -224.799652)
		(end 407.919682 -224.670112)
		(width 0.18288)
		(layer "In11.Cu")
		(net "M_H_CPU0_SB_DQS_DN<5>")
	)
	(segment
		(start 425.35221 -222.952818)
		(end 425.064174 -223.240854)
		(width 0.18288)
		(layer "In11.Cu")
		(net "M_H_CPU0_SB_DQS_DN<5>")
	)
	(segment
		(start 408.755342 -224.670112)
		(end 408.625802 -224.799652)
		(width 0.18288)
		(layer "In11.Cu")
		(net "M_H_CPU0_SB_DQS_DN<5>")
	)
	(segment
		(start 375.754392 -237.093252)
		(end 375.753376 -237.092744)
		(width 0.088646)
		(layer "In11.Cu")
		(net "M_H_CPU0_SB_DQS_DN<5>")
	)
	(segment
		(start 452.902066 -227.934012)
		(end 452.777606 -227.809552)
		(width 0.18288)
		(layer "In11.Cu")
		(net "M_H_CPU0_SB_DQS_DN<5>")
	)
	(segment
		(start 410.219906 -224.676208)
		(end 409.955238 -224.940876)
		(width 0.18288)
		(layer "In11.Cu")
		(net "M_H_CPU0_SB_DQS_DN<5>")
	)
	(segment
		(start 405.167846 -225.546412)
		(end 403.81047 -225.546412)
		(width 0.18288)
		(layer "In11.Cu")
		(net "M_H_CPU0_SB_DQS_DN<5>")
	)
	(segment
		(start 436.315612 -222.128588)
		(end 436.05323 -222.39097)
		(width 0.18288)
		(layer "In11.Cu")
		(net "M_H_CPU0_SB_DQS_DN<5>")
	)
	(segment
		(start 414.534604 -224.847658)
		(end 413.985964 -224.847658)
		(width 0.18288)
		(layer "In11.Cu")
		(net "M_H_CPU0_SB_DQS_DN<5>")
	)
	(segment
		(start 413.861504 -224.723198)
		(end 413.008572 -224.723198)
		(width 0.18288)
		(layer "In11.Cu")
		(net "M_H_CPU0_SB_DQS_DN<5>")
	)
	(segment
		(start 424.334432 -222.987616)
		(end 422.397682 -222.987616)
		(width 0.18288)
		(layer "In11.Cu")
		(net "M_H_CPU0_SB_DQS_DN<5>")
	)
	(segment
		(start 419.372034 -223.96323)
		(end 418.823394 -223.96323)
		(width 0.18288)
		(layer "In11.Cu")
		(net "M_H_CPU0_SB_DQS_DN<5>")
	)
	(segment
		(start 387.744462 -237.238794)
		(end 387.112764 -237.238794)
		(width 0.088646)
		(layer "In11.Cu")
		(net "M_H_CPU0_SB_DQS_DN<5>")
	)
	(segment
		(start 416.299396 -223.83877)
		(end 415.414968 -224.723198)
		(width 0.18288)
		(layer "In11.Cu")
		(net "M_H_CPU0_SB_DQS_DN<5>")
	)
	(segment
		(start 375.751344 -237.091474)
		(end 375.744232 -237.08741)
		(width 0.088646)
		(layer "In11.Cu")
		(net "M_H_CPU0_SB_DQS_DN<5>")
	)
	(segment
		(start 392.739118 -236.617764)
		(end 389.019796 -236.617764)
		(width 0.18288)
		(layer "In11.Cu")
		(net "M_H_CPU0_SB_DQS_DN<5>")
	)
	(segment
		(start 387.112764 -237.238794)
		(end 386.897372 -237.14964)
		(width 0.088646)
		(layer "In11.Cu")
		(net "M_H_CPU0_SB_DQS_DN<5>")
	)
	(segment
		(start 405.410162 -225.788728)
		(end 405.167846 -225.546412)
		(width 0.18288)
		(layer "In11.Cu")
		(net "M_H_CPU0_SB_DQS_DN<5>")
	)
	(segment
		(start 428.511716 -222.750126)
		(end 427.826424 -222.750126)
		(width 0.18288)
		(layer "In11.Cu")
		(net "M_H_CPU0_SB_DQS_DN<5>")
	)
	(segment
		(start 429.982376 -222.874586)
		(end 429.857916 -222.750126)
		(width 0.18288)
		(layer "In11.Cu")
		(net "M_H_CPU0_SB_DQS_DN<5>")
	)
	(segment
		(start 452.333614 -227.809552)
		(end 451.744588 -227.220526)
		(width 0.18288)
		(layer "In11.Cu")
		(net "M_H_CPU0_SB_DQS_DN<5>")
	)
	(segment
		(start 418.698934 -223.83877)
		(end 418.150294 -223.83877)
		(width 0.18288)
		(layer "In11.Cu")
		(net "M_H_CPU0_SB_DQS_DN<5>")
	)
	(segment
		(start 385.156964 -237.096046)
		(end 385.142232 -237.08741)
		(width 0.088646)
		(layer "In11.Cu")
		(net "M_H_CPU0_SB_DQS_DN<5>")
	)
	(segment
		(start 389.019796 -236.617764)
		(end 388.959852 -236.55782)
		(width 0.088646)
		(layer "In11.Cu")
		(net "M_H_CPU0_SB_DQS_DN<5>")
	)
	(segment
		(start 446.341246 -226.707954)
		(end 446.273936 -226.54514)
		(width 0.18288)
		(layer "In11.Cu")
		(net "M_H_CPU0_SB_DQS_DN<5>")
	)
	(segment
		(start 386.897372 -237.14964)
		(end 386.339842 -237.14964)
		(width 0.088646)
		(layer "In11.Cu")
		(net "M_H_CPU0_SB_DQS_DN<5>")
	)
	(segment
		(start 426.798232 -222.333058)
		(end 426.178472 -222.952818)
		(width 0.18288)
		(layer "In11.Cu")
		(net "M_H_CPU0_SB_DQS_DN<5>")
	)
	(segment
		(start 443.59957 -224.74301)
		(end 440.955938 -222.976186)
		(width 0.18288)
		(layer "In11.Cu")
		(net "M_H_CPU0_SB_DQS_DN<5>")
	)
	(segment
		(start 433.289202 -222.119698)
		(end 432.740562 -222.119698)
		(width 0.18288)
		(layer "In11.Cu")
		(net "M_H_CPU0_SB_DQS_DN<5>")
	)
	(segment
		(start 415.414968 -224.723198)
		(end 414.659064 -224.723198)
		(width 0.18288)
		(layer "In11.Cu")
		(net "M_H_CPU0_SB_DQS_DN<5>")
	)
	(segment
		(start 373.760238 -237.190788)
		(end 373.686832 -237.264194)
		(width 0.088646)
		(layer "In11.Cu")
		(net "M_H_CPU0_SB_DQS_DN<5>")
	)
	(segment
		(start 375.758964 -237.096046)
		(end 375.754392 -237.093252)
		(width 0.088646)
		(layer "In11.Cu")
		(net "M_H_CPU0_SB_DQS_DN<5>")
	)
	(segment
		(start 413.008572 -224.723198)
		(end 412.11754 -223.832166)
		(width 0.18288)
		(layer "In11.Cu")
		(net "M_H_CPU0_SB_DQS_DN<5>")
	)
	(segment
		(start 375.753376 -237.092744)
		(end 375.751344 -237.091474)
		(width 0.088646)
		(layer "In11.Cu")
		(net "M_H_CPU0_SB_DQS_DN<5>")
	)
	(segment
		(start 438.505346 -222.970852)
		(end 436.471822 -222.128588)
		(width 0.18288)
		(layer "In11.Cu")
		(net "M_H_CPU0_SB_DQS_DN<5>")
	)
	(segment
		(start 454.279 -227.74529)
		(end 454.123806 -227.809552)
		(width 0.18288)
		(layer "In11.Cu")
		(net "M_H_CPU0_SB_DQS_DN<5>")
	)
	(segment
		(start 378.578364 -237.096046)
		(end 378.563632 -237.08741)
		(width 0.088646)
		(layer "In11.Cu")
		(net "M_H_CPU0_SB_DQS_DN<5>")
	)
	(segment
		(start 424.58767 -223.240854)
		(end 424.334432 -222.987616)
		(width 0.18288)
		(layer "In11.Cu")
		(net "M_H_CPU0_SB_DQS_DN<5>")
	)
	(segment
		(start 440.416442 -222.976186)
		(end 440.151774 -223.240854)
		(width 0.18288)
		(layer "In11.Cu")
		(net "M_H_CPU0_SB_DQS_DN<5>")
	)
	(segment
		(start 433.413662 -222.244158)
		(end 433.289202 -222.119698)
		(width 0.18288)
		(layer "In11.Cu")
		(net "M_H_CPU0_SB_DQS_DN<5>")
	)
	(segment
		(start 426.178472 -222.952818)
		(end 425.35221 -222.952818)
		(width 0.18288)
		(layer "In11.Cu")
		(net "M_H_CPU0_SB_DQS_DN<5>")
	)
	(segment
		(start 440.151774 -223.240854)
		(end 439.64479 -223.240854)
		(width 0.18288)
		(layer "In11.Cu")
		(net "M_H_CPU0_SB_DQS_DN<5>")
	)
	(segment
		(start 443.713616 -224.790254)
		(end 443.59957 -224.74301)
		(width 0.18288)
		(layer "In11.Cu")
		(net "M_H_CPU0_SB_DQS_DN<5>")
	)
	(segment
		(start 421.543734 -223.841564)
		(end 421.213534 -223.841564)
		(width 0.18288)
		(layer "In11.Cu")
		(net "M_H_CPU0_SB_DQS_DN<5>")
	)
	(segment
		(start 440.955938 -222.976186)
		(end 440.416442 -222.976186)
		(width 0.18288)
		(layer "In11.Cu")
		(net "M_H_CPU0_SB_DQS_DN<5>")
	)
	(segment
		(start 374.408446 -237.098586)
		(end 374.259348 -237.171992)
		(width 0.088646)
		(layer "In11.Cu")
		(net "M_H_CPU0_SB_DQS_DN<5>")
	)
	(segment
		(start 435.579266 -222.39097)
		(end 435.307994 -222.119698)
		(width 0.18288)
		(layer "In11.Cu")
		(net "M_H_CPU0_SB_DQS_DN<5>")
	)
	(segment
		(start 374.259348 -237.171992)
		(end 373.782844 -237.181136)
		(width 0.088646)
		(layer "In11.Cu")
		(net "M_H_CPU0_SB_DQS_DN<5>")
	)
	(segment
		(start 383.277364 -237.096046)
		(end 383.262632 -237.08741)
		(width 0.088646)
		(layer "In11.Cu")
		(net "M_H_CPU0_SB_DQS_DN<5>")
	)
	(segment
		(start 429.309276 -222.750126)
		(end 429.184816 -222.874586)
		(width 0.18288)
		(layer "In11.Cu")
		(net "M_H_CPU0_SB_DQS_DN<5>")
	)
	(segment
		(start 417.352734 -223.83877)
		(end 416.299396 -223.83877)
		(width 0.18288)
		(layer "In11.Cu")
		(net "M_H_CPU0_SB_DQS_DN<5>")
	)
	(segment
		(start 377.638564 -237.096046)
		(end 377.623832 -237.08741)
		(width 0.088646)
		(layer "In11.Cu")
		(net "M_H_CPU0_SB_DQS_DN<5>")
	)
	(segment
		(start 373.686832 -237.264194)
		(end 373.677434 -237.286546)
		(width 0.088646)
		(layer "In11.Cu")
		(net "M_H_CPU0_SB_DQS_DN<5>")
	)
	(segment
		(start 413.985964 -224.847658)
		(end 413.861504 -224.723198)
		(width 0.18288)
		(layer "In11.Cu")
		(net "M_H_CPU0_SB_DQS_DN<5>")
	)
	(segment
		(start 434.086762 -222.119698)
		(end 433.962302 -222.244158)
		(width 0.18288)
		(layer "In11.Cu")
		(net "M_H_CPU0_SB_DQS_DN<5>")
	)
	(segment
		(start 427.409356 -222.333058)
		(end 426.798232 -222.333058)
		(width 0.18288)
		(layer "In11.Cu")
		(net "M_H_CPU0_SB_DQS_DN<5>")
	)
	(segment
		(start 373.677434 -237.286546)
		(end 373.677434 -237.411514)
		(width 0.088646)
		(layer "In11.Cu")
		(net "M_H_CPU0_SB_DQS_DN<5>")
	)
	(segment
		(start 446.273936 -226.54514)
		(end 444.899034 -225.975418)
		(width 0.18288)
		(layer "In11.Cu")
		(net "M_H_CPU0_SB_DQS_DN<5>")
	)
	(segment
		(start 444.899034 -225.975418)
		(end 444.899034 -225.975672)
		(width 0.18288)
		(layer "In11.Cu")
		(net "M_H_CPU0_SB_DQS_DN<5>")
	)
	(segment
		(start 381.948436 -237.08741)
		(end 381.938022 -237.093506)
		(width 0.088646)
		(layer "In11.Cu")
		(net "M_H_CPU0_SB_DQS_DN<5>")
	)
	(segment
		(start 435.307994 -222.119698)
		(end 434.086762 -222.119698)
		(width 0.18288)
		(layer "In11.Cu")
		(net "M_H_CPU0_SB_DQS_DN<5>")
	)
	(segment
		(start 418.150294 -223.83877)
		(end 418.025834 -223.96323)
		(width 0.18288)
		(layer "In11.Cu")
		(net "M_H_CPU0_SB_DQS_DN<5>")
	)
	(segment
		(start 412.11754 -223.832166)
		(end 411.741874 -223.832166)
		(width 0.18288)
		(layer "In11.Cu")
		(net "M_H_CPU0_SB_DQS_DN<5>")
	)
	(segment
		(start 430.531016 -222.874586)
		(end 429.982376 -222.874586)
		(width 0.18288)
		(layer "In11.Cu")
		(net "M_H_CPU0_SB_DQS_DN<5>")
	)
	(segment
		(start 388.425436 -236.55782)
		(end 387.744462 -237.238794)
		(width 0.088646)
		(layer "In11.Cu")
		(net "M_H_CPU0_SB_DQS_DN<5>")
	)
	(segment
		(start 418.823394 -223.96323)
		(end 418.698934 -223.83877)
		(width 0.18288)
		(layer "In11.Cu")
		(net "M_H_CPU0_SB_DQS_DN<5>")
	)
	(segment
		(start 447.011044 -226.850448)
		(end 446.848484 -226.918012)
		(width 0.18288)
		(layer "In11.Cu")
		(net "M_H_CPU0_SB_DQS_DN<5>")
	)
	(segment
		(start 420.242492 -223.83877)
		(end 419.496494 -223.83877)
		(width 0.18288)
		(layer "In11.Cu")
		(net "M_H_CPU0_SB_DQS_DN<5>")
	)
	(segment
		(start 429.184816 -222.874586)
		(end 428.636176 -222.874586)
		(width 0.18288)
		(layer "In11.Cu")
		(net "M_H_CPU0_SB_DQS_DN<5>")
	)
	(segment
		(start 454.741026 -227.646484)
		(end 454.518268 -227.646484)
		(width 0.18288)
		(layer "In11.Cu")
		(net "M_H_CPU0_SB_DQS_DN<5>")
	)
	(segment
		(start 421.213534 -223.841564)
		(end 420.964106 -224.090992)
		(width 0.18288)
		(layer "In11.Cu")
		(net "M_H_CPU0_SB_DQS_DN<5>")
	)
	(segment
		(start 418.025834 -223.96323)
		(end 417.477194 -223.96323)
		(width 0.18288)
		(layer "In11.Cu")
		(net "M_H_CPU0_SB_DQS_DN<5>")
	)
	(segment
		(start 454.123806 -227.809552)
		(end 453.575166 -227.809552)
		(width 0.18288)
		(layer "In11.Cu")
		(net "M_H_CPU0_SB_DQS_DN<5>")
	)
	(segment
		(start 444.899034 -225.975672)
		(end 443.713616 -224.790254)
		(width 0.18288)
		(layer "In11.Cu")
		(net "M_H_CPU0_SB_DQS_DN<5>")
	)
	(segment
		(start 409.543758 -224.940876)
		(end 409.272994 -224.670112)
		(width 0.18288)
		(layer "In11.Cu")
		(net "M_H_CPU0_SB_DQS_DN<5>")
	)
	(segment
		(start 409.272994 -224.670112)
		(end 408.755342 -224.670112)
		(width 0.18288)
		(layer "In11.Cu")
		(net "M_H_CPU0_SB_DQS_DN<5>")
	)
	(segment
		(start 451.436232 -227.220526)
		(end 451.165722 -227.491036)
		(width 0.18288)
		(layer "In11.Cu")
		(net "M_H_CPU0_SB_DQS_DN<5>")
	)
	(segment
		(start 388.959852 -236.55782)
		(end 388.425436 -236.55782)
		(width 0.088646)
		(layer "In11.Cu")
		(net "M_H_CPU0_SB_DQS_DN<5>")
	)
	(segment
		(start 373.782844 -237.181136)
		(end 373.782336 -237.18139)
		(width 0.088646)
		(layer "In11.Cu")
		(net "M_H_CPU0_SB_DQS_DN<5>")
	)
	(segment
		(start 414.659064 -224.723198)
		(end 414.534604 -224.847658)
		(width 0.18288)
		(layer "In11.Cu")
		(net "M_H_CPU0_SB_DQS_DN<5>")
	)
	(segment
		(start 447.931032 -227.231702)
		(end 447.011044 -226.850448)
		(width 0.18288)
		(layer "In11.Cu")
		(net "M_H_CPU0_SB_DQS_DN<5>")
	)
	(segment
		(start 411.741874 -223.832166)
		(end 410.897832 -224.676208)
		(width 0.18288)
		(layer "In11.Cu")
		(net "M_H_CPU0_SB_DQS_DN<5>")
	)
	(segment
		(start 439.374788 -222.970852)
		(end 438.505346 -222.970852)
		(width 0.18288)
		(layer "In11.Cu")
		(net "M_H_CPU0_SB_DQS_DN<5>")
	)
	(segment
		(start 373.782336 -237.18139)
		(end 373.760238 -237.190788)
		(width 0.088646)
		(layer "In11.Cu")
		(net "M_H_CPU0_SB_DQS_DN<5>")
	)
	(segment
		(start 452.777606 -227.809552)
		(end 452.333614 -227.809552)
		(width 0.18288)
		(layer "In11.Cu")
		(net "M_H_CPU0_SB_DQS_DN<5>")
	)
	(segment
		(start 374.819164 -237.096046)
		(end 374.804432 -237.08741)
		(width 0.088646)
		(layer "In11.Cu")
		(net "M_H_CPU0_SB_DQS_DN<5>")
	)
	(segment
		(start 380.453646 -237.093506)
		(end 380.443232 -237.08741)
		(width 0.088646)
		(layer "In11.Cu")
		(net "M_H_CPU0_SB_DQS_DN<5>")
	)
	(segment
		(start 409.955238 -224.940876)
		(end 409.543758 -224.940876)
		(width 0.18288)
		(layer "In11.Cu")
		(net "M_H_CPU0_SB_DQS_DN<5>")
	)
	(segment
		(start 384.217164 -237.096046)
		(end 384.202432 -237.08741)
		(width 0.088646)
		(layer "In11.Cu")
		(net "M_H_CPU0_SB_DQS_DN<5>")
	)
	(segment
		(start 422.397682 -222.987616)
		(end 421.543734 -223.841564)
		(width 0.18288)
		(layer "In11.Cu")
		(net "M_H_CPU0_SB_DQS_DN<5>")
	)
	(segment
		(start 420.494714 -224.090992)
		(end 420.242492 -223.83877)
		(width 0.18288)
		(layer "In11.Cu")
		(net "M_H_CPU0_SB_DQS_DN<5>")
	)
	(segment
		(start 428.636176 -222.874586)
		(end 428.511716 -222.750126)
		(width 0.18288)
		(layer "In11.Cu")
		(net "M_H_CPU0_SB_DQS_DN<5>")
	)
	(segment
		(start 419.496494 -223.83877)
		(end 419.372034 -223.96323)
		(width 0.18288)
		(layer "In11.Cu")
		(net "M_H_CPU0_SB_DQS_DN<5>")
	)
	(segment
		(start 455.011282 -227.91674)
		(end 454.741026 -227.646484)
		(width 0.18288)
		(layer "In11.Cu")
		(net "M_H_CPU0_SB_DQS_DN<5>")
	)
	(segment
		(start 446.848484 -226.918012)
		(end 446.341246 -226.707954)
		(width 0.18288)
		(layer "In11.Cu")
		(net "M_H_CPU0_SB_DQS_DN<5>")
	)
	(segment
		(start 451.165722 -227.491036)
		(end 450.666866 -227.491036)
		(width 0.18288)
		(layer "In11.Cu")
		(net "M_H_CPU0_SB_DQS_DN<5>")
	)
	(segment
		(start 405.856694 -225.788728)
		(end 405.410162 -225.788728)
		(width 0.18288)
		(layer "In11.Cu")
		(net "M_H_CPU0_SB_DQS_DN<5>")
	)
	(segment
		(start 454.518268 -227.646484)
		(end 454.279 -227.74529)
		(width 0.18288)
		(layer "In11.Cu")
		(net "M_H_CPU0_SB_DQS_DN<5>")
	)
	(segment
		(start 450.407532 -227.231702)
		(end 447.931032 -227.231702)
		(width 0.18288)
		(layer "In11.Cu")
		(net "M_H_CPU0_SB_DQS_DN<5>")
	)
	(segment
		(start 425.064174 -223.240854)
		(end 424.58767 -223.240854)
		(width 0.18288)
		(layer "In11.Cu")
		(net "M_H_CPU0_SB_DQS_DN<5>")
	)
	(segment
		(start 453.450706 -227.934012)
		(end 452.902066 -227.934012)
		(width 0.18288)
		(layer "In11.Cu")
		(net "M_H_CPU0_SB_DQS_DN<5>")
	)
	(segment
		(start 433.962302 -222.244158)
		(end 433.413662 -222.244158)
		(width 0.18288)
		(layer "In11.Cu")
		(net "M_H_CPU0_SB_DQS_DN<5>")
	)
	(segment
		(start 420.964106 -224.090992)
		(end 420.494714 -224.090992)
		(width 0.18288)
		(layer "In11.Cu")
		(net "M_H_CPU0_SB_DQS_DN<5>")
	)
	(segment
		(start 417.477194 -223.96323)
		(end 417.352734 -223.83877)
		(width 0.18288)
		(layer "In11.Cu")
		(net "M_H_CPU0_SB_DQS_DN<5>")
	)
	(segment
		(start 406.728168 -225.526092)
		(end 406.11933 -225.526092)
		(width 0.18288)
		(layer "In11.Cu")
		(net "M_H_CPU0_SB_DQS_DN<5>")
	)
	(segment
		(start 374.430036 -237.08741)
		(end 374.408446 -237.098586)
		(width 0.088646)
		(layer "In11.Cu")
		(net "M_H_CPU0_SB_DQS_DN<5>")
	)
	(segment
		(start 429.857916 -222.750126)
		(end 429.309276 -222.750126)
		(width 0.18288)
		(layer "In11.Cu")
		(net "M_H_CPU0_SB_DQS_DN<5>")
	)
	(segment
		(start 379.518164 -237.096046)
		(end 379.503432 -237.08741)
		(width 0.088646)
		(layer "In11.Cu")
		(net "M_H_CPU0_SB_DQS_DN<5>")
	)
	(segment
		(start 432.740562 -222.119698)
		(end 431.21834 -222.750126)
		(width 0.18288)
		(layer "In11.Cu")
		(net "M_H_CPU0_SB_DQS_DN<5>")
	)
	(segment
		(start 408.625802 -224.799652)
		(end 408.049222 -224.799652)
		(width 0.18288)
		(layer "In11.Cu")
		(net "M_H_CPU0_SB_DQS_DN<5>")
	)
	(segment
		(start 407.919682 -224.670112)
		(end 407.584148 -224.670112)
		(width 0.18288)
		(layer "In11.Cu")
		(net "M_H_CPU0_SB_DQS_DN<5>")
	)
	(segment
		(start 431.21834 -222.750126)
		(end 430.655476 -222.750126)
		(width 0.18288)
		(layer "In11.Cu")
		(net "M_H_CPU0_SB_DQS_DN<5>")
	)
	(segment
		(start 427.826424 -222.750126)
		(end 427.409356 -222.333058)
		(width 0.18288)
		(layer "In11.Cu")
		(net "M_H_CPU0_SB_DQS_DN<5>")
	)
	(segment
		(start 407.584148 -224.670112)
		(end 406.728168 -225.526092)
		(width 0.18288)
		(layer "In11.Cu")
		(net "M_H_CPU0_SB_DQS_DN<5>")
	)
	(segment
		(start 430.655476 -222.750126)
		(end 430.531016 -222.874586)
		(width 0.18288)
		(layer "In11.Cu")
		(net "M_H_CPU0_SB_DQS_DN<5>")
	)
	(arc
		(start 374.804432 -237.08741)
		(mid 374.617234 -237.037233)
		(end 374.430036 -237.08741)
		(width 0.088646)
		(layer "In11.Cu")
		(net "M_H_CPU0_SB_DQS_DN<5>")
	)
	(arc
		(start 378.189236 -237.08741)
		(mid 377.915037 -237.163245)
		(end 377.638564 -237.096046)
		(width 0.088646)
		(layer "In11.Cu")
		(net "M_H_CPU0_SB_DQS_DN<5>")
	)
	(arc
		(start 383.262632 -237.08741)
		(mid 383.075434 -237.037233)
		(end 382.888236 -237.08741)
		(width 0.088646)
		(layer "In11.Cu")
		(net "M_H_CPU0_SB_DQS_DN<5>")
	)
	(arc
		(start 378.563632 -237.08741)
		(mid 378.376434 -237.037233)
		(end 378.189236 -237.08741)
		(width 0.088646)
		(layer "In11.Cu")
		(net "M_H_CPU0_SB_DQS_DN<5>")
	)
	(arc
		(start 380.443232 -237.08741)
		(mid 380.256034 -237.037233)
		(end 380.068836 -237.08741)
		(width 0.088646)
		(layer "In11.Cu")
		(net "M_H_CPU0_SB_DQS_DN<5>")
	)
	(arc
		(start 384.202432 -237.08741)
		(mid 384.015234 -237.037233)
		(end 383.828036 -237.08741)
		(width 0.088646)
		(layer "In11.Cu")
		(net "M_H_CPU0_SB_DQS_DN<5>")
	)
	(arc
		(start 376.309636 -237.08741)
		(mid 376.035437 -237.163245)
		(end 375.758964 -237.096046)
		(width 0.088646)
		(layer "In11.Cu")
		(net "M_H_CPU0_SB_DQS_DN<5>")
	)
	(arc
		(start 376.684032 -237.08741)
		(mid 376.496834 -237.037233)
		(end 376.309636 -237.08741)
		(width 0.088646)
		(layer "In11.Cu")
		(net "M_H_CPU0_SB_DQS_DN<5>")
	)
	(arc
		(start 380.068836 -237.08741)
		(mid 379.794637 -237.163245)
		(end 379.518164 -237.096046)
		(width 0.088646)
		(layer "In11.Cu")
		(net "M_H_CPU0_SB_DQS_DN<5>")
	)
	(arc
		(start 377.623832 -237.08741)
		(mid 377.436634 -237.037233)
		(end 377.249436 -237.08741)
		(width 0.088646)
		(layer "In11.Cu")
		(net "M_H_CPU0_SB_DQS_DN<5>")
	)
	(arc
		(start 375.369836 -237.08741)
		(mid 375.095637 -237.163245)
		(end 374.819164 -237.096046)
		(width 0.088646)
		(layer "In11.Cu")
		(net "M_H_CPU0_SB_DQS_DN<5>")
	)
	(arc
		(start 381.382778 -237.08741)
		(mid 381.19558 -237.037233)
		(end 381.008382 -237.08741)
		(width 0.088646)
		(layer "In11.Cu")
		(net "M_H_CPU0_SB_DQS_DN<5>")
	)
	(arc
		(start 381.938022 -237.093506)
		(mid 381.65959 -237.163352)
		(end 381.382778 -237.08741)
		(width 0.088646)
		(layer "In11.Cu")
		(net "M_H_CPU0_SB_DQS_DN<5>")
	)
	(arc
		(start 385.142232 -237.08741)
		(mid 384.955034 -237.037233)
		(end 384.767836 -237.08741)
		(width 0.088646)
		(layer "In11.Cu")
		(net "M_H_CPU0_SB_DQS_DN<5>")
	)
	(arc
		(start 382.888236 -237.08741)
		(mid 382.605534 -237.163186)
		(end 382.322832 -237.08741)
		(width 0.088646)
		(layer "In11.Cu")
		(net "M_H_CPU0_SB_DQS_DN<5>")
	)
	(arc
		(start 385.707636 -237.08741)
		(mid 385.433437 -237.163245)
		(end 385.156964 -237.096046)
		(width 0.088646)
		(layer "In11.Cu")
		(net "M_H_CPU0_SB_DQS_DN<5>")
	)
	(arc
		(start 377.249436 -237.08741)
		(mid 376.966734 -237.163186)
		(end 376.684032 -237.08741)
		(width 0.088646)
		(layer "In11.Cu")
		(net "M_H_CPU0_SB_DQS_DN<5>")
	)
	(arc
		(start 379.503432 -237.08741)
		(mid 379.316234 -237.037233)
		(end 379.129036 -237.08741)
		(width 0.088646)
		(layer "In11.Cu")
		(net "M_H_CPU0_SB_DQS_DN<5>")
	)
	(arc
		(start 375.744232 -237.08741)
		(mid 375.557034 -237.037233)
		(end 375.369836 -237.08741)
		(width 0.088646)
		(layer "In11.Cu")
		(net "M_H_CPU0_SB_DQS_DN<5>")
	)
	(arc
		(start 381.008382 -237.08741)
		(mid 380.731823 -237.163153)
		(end 380.453646 -237.093506)
		(width 0.088646)
		(layer "In11.Cu")
		(net "M_H_CPU0_SB_DQS_DN<5>")
	)
	(arc
		(start 383.828036 -237.08741)
		(mid 383.553837 -237.163245)
		(end 383.277364 -237.096046)
		(width 0.088646)
		(layer "In11.Cu")
		(net "M_H_CPU0_SB_DQS_DN<5>")
	)
	(arc
		(start 386.082032 -237.08741)
		(mid 385.894834 -237.037233)
		(end 385.707636 -237.08741)
		(width 0.088646)
		(layer "In11.Cu")
		(net "M_H_CPU0_SB_DQS_DN<5>")
	)
	(arc
		(start 384.767836 -237.08741)
		(mid 384.493637 -237.163245)
		(end 384.217164 -237.096046)
		(width 0.088646)
		(layer "In11.Cu")
		(net "M_H_CPU0_SB_DQS_DN<5>")
	)
	(arc
		(start 379.129036 -237.08741)
		(mid 378.854837 -237.163245)
		(end 378.578364 -237.096046)
		(width 0.088646)
		(layer "In11.Cu")
		(net "M_H_CPU0_SB_DQS_DN<5>")
	)
	(arc
		(start 382.322832 -237.08741)
		(mid 382.135634 -237.037233)
		(end 381.948436 -237.08741)
		(width 0.088646)
		(layer "In11.Cu")
		(net "M_H_CPU0_SB_DQS_DN<5>")
	)
	(arc
		(start 386.339842 -237.14964)
		(mid 386.207246 -237.133826)
		(end 386.082032 -237.08741)
		(width 0.088646)
		(layer "In11.Cu")
		(net "M_H_CPU0_SB_DQS_DN<5>")
	)
	(segment
		(start 462.110328 -237.01248)
		(end 461.664812 -236.566964)
		(width 0.20066)
		(layer "F.Cu")
		(net "M_H_CPU0_SB_DQS_DN<4>")
	)
	(segment
		(start 461.664812 -236.566964)
		(end 461.174846 -236.566964)
		(width 0.20066)
		(layer "F.Cu")
		(net "M_H_CPU0_SB_DQS_DN<4>")
	)
	(segment
		(start 373.67718 -242.830858)
		(end 373.677434 -242.830604)
		(width 0.20066)
		(layer "F.Cu")
		(net "M_H_CPU0_SB_DQS_DN<4>")
	)
	(segment
		(start 460.559404 -236.841792)
		(end 458.549248 -236.841792)
		(width 0.1016)
		(layer "F.Cu")
		(net "M_H_CPU0_SB_DQS_DN<4>")
	)
	(segment
		(start 458.538326 -236.847888)
		(end 458.22616 -236.847888)
		(width 0.20066)
		(layer "F.Cu")
		(net "M_H_CPU0_SB_DQS_DN<4>")
	)
	(segment
		(start 461.174846 -236.566964)
		(end 460.889096 -236.852714)
		(width 0.20066)
		(layer "F.Cu")
		(net "M_H_CPU0_SB_DQS_DN<4>")
	)
	(segment
		(start 455.011282 -237.266734)
		(end 456.116182 -237.266734)
		(width 0.20066)
		(layer "F.Cu")
		(net "M_H_CPU0_SB_DQS_DN<4>")
	)
	(segment
		(start 457.948792 -236.57052)
		(end 457.826364 -236.57052)
		(width 0.20066)
		(layer "F.Cu")
		(net "M_H_CPU0_SB_DQS_DN<4>")
	)
	(segment
		(start 458.22616 -236.847888)
		(end 457.948792 -236.57052)
		(width 0.20066)
		(layer "F.Cu")
		(net "M_H_CPU0_SB_DQS_DN<4>")
	)
	(segment
		(start 457.401422 -236.995462)
		(end 456.91806 -236.995462)
		(width 0.20066)
		(layer "F.Cu")
		(net "M_H_CPU0_SB_DQS_DN<4>")
	)
	(segment
		(start 373.677434 -242.830604)
		(end 373.677434 -242.294918)
		(width 0.20066)
		(layer "F.Cu")
		(net "M_H_CPU0_SB_DQS_DN<4>")
	)
	(segment
		(start 456.646788 -237.266734)
		(end 456.116182 -237.266734)
		(width 0.20066)
		(layer "F.Cu")
		(net "M_H_CPU0_SB_DQS_DN<4>")
	)
	(segment
		(start 462.902046 -237.01248)
		(end 462.110328 -237.01248)
		(width 0.20066)
		(layer "F.Cu")
		(net "M_H_CPU0_SB_DQS_DN<4>")
	)
	(segment
		(start 460.570326 -236.852714)
		(end 460.559404 -236.841792)
		(width 0.1016)
		(layer "F.Cu")
		(net "M_H_CPU0_SB_DQS_DN<4>")
	)
	(segment
		(start 458.543152 -236.847888)
		(end 458.538326 -236.847888)
		(width 0.101854)
		(layer "F.Cu")
		(net "M_H_CPU0_SB_DQS_DN<4>")
	)
	(segment
		(start 463.659982 -237.266734)
		(end 463.1563 -237.266734)
		(width 0.20066)
		(layer "F.Cu")
		(net "M_H_CPU0_SB_DQS_DN<4>")
	)
	(segment
		(start 458.549248 -236.841792)
		(end 458.543152 -236.847888)
		(width 0.1016)
		(layer "F.Cu")
		(net "M_H_CPU0_SB_DQS_DN<4>")
	)
	(segment
		(start 460.889096 -236.852714)
		(end 460.570326 -236.852714)
		(width 0.20066)
		(layer "F.Cu")
		(net "M_H_CPU0_SB_DQS_DN<4>")
	)
	(segment
		(start 456.91806 -236.995462)
		(end 456.646788 -237.266734)
		(width 0.20066)
		(layer "F.Cu")
		(net "M_H_CPU0_SB_DQS_DN<4>")
	)
	(segment
		(start 463.1563 -237.266734)
		(end 462.902046 -237.01248)
		(width 0.20066)
		(layer "F.Cu")
		(net "M_H_CPU0_SB_DQS_DN<4>")
	)
	(segment
		(start 457.826364 -236.57052)
		(end 457.401422 -236.995462)
		(width 0.20066)
		(layer "F.Cu")
		(net "M_H_CPU0_SB_DQS_DN<4>")
	)
	(segment
		(start 444.07328 -236.1057)
		(end 443.94882 -235.98124)
		(width 0.18288)
		(layer "In11.Cu")
		(net "M_H_CPU0_SB_DQS_DN<4>")
	)
	(segment
		(start 403.74951 -237.220506)
		(end 403.62505 -237.344966)
		(width 0.18288)
		(layer "In11.Cu")
		(net "M_H_CPU0_SB_DQS_DN<4>")
	)
	(segment
		(start 445.678306 -235.98124)
		(end 444.74638 -235.98124)
		(width 0.18288)
		(layer "In11.Cu")
		(net "M_H_CPU0_SB_DQS_DN<4>")
	)
	(segment
		(start 443.94882 -235.98124)
		(end 443.28842 -235.98124)
		(width 0.18288)
		(layer "In11.Cu")
		(net "M_H_CPU0_SB_DQS_DN<4>")
	)
	(segment
		(start 433.723796 -234.896152)
		(end 433.039266 -234.760008)
		(width 0.18288)
		(layer "In11.Cu")
		(net "M_H_CPU0_SB_DQS_DN<4>")
	)
	(segment
		(start 401.60575 -237.220506)
		(end 401.05711 -237.220506)
		(width 0.18288)
		(layer "In11.Cu")
		(net "M_H_CPU0_SB_DQS_DN<4>")
	)
	(segment
		(start 419.320726 -235.034074)
		(end 418.772086 -235.034074)
		(width 0.18288)
		(layer "In11.Cu")
		(net "M_H_CPU0_SB_DQS_DN<4>")
	)
	(segment
		(start 404.29815 -237.220506)
		(end 403.74951 -237.220506)
		(width 0.18288)
		(layer "In11.Cu")
		(net "M_H_CPU0_SB_DQS_DN<4>")
	)
	(segment
		(start 455.011282 -237.266734)
		(end 454.735438 -236.99089)
		(width 0.18288)
		(layer "In11.Cu")
		(net "M_H_CPU0_SB_DQS_DN<4>")
	)
	(segment
		(start 374.430036 -241.970814)
		(end 374.421654 -241.975132)
		(width 0.088646)
		(layer "In11.Cu")
		(net "M_H_CPU0_SB_DQS_DN<4>")
	)
	(segment
		(start 382.337564 -241.979196)
		(end 382.322832 -241.97056)
		(width 0.088646)
		(layer "In11.Cu")
		(net "M_H_CPU0_SB_DQS_DN<4>")
	)
	(segment
		(start 374.421654 -241.975132)
		(end 374.414796 -241.978942)
		(width 0.088646)
		(layer "In11.Cu")
		(net "M_H_CPU0_SB_DQS_DN<4>")
	)
	(segment
		(start 379.518164 -241.979196)
		(end 379.503432 -241.97056)
		(width 0.088646)
		(layer "In11.Cu")
		(net "M_H_CPU0_SB_DQS_DN<4>")
	)
	(segment
		(start 427.272958 -234.630976)
		(end 426.948854 -234.630976)
		(width 0.18288)
		(layer "In11.Cu")
		(net "M_H_CPU0_SB_DQS_DN<4>")
	)
	(segment
		(start 418.647626 -234.909614)
		(end 417.247832 -234.909614)
		(width 0.18288)
		(layer "In11.Cu")
		(net "M_H_CPU0_SB_DQS_DN<4>")
	)
	(segment
		(start 425.321222 -234.026456)
		(end 425.056554 -234.291124)
		(width 0.18288)
		(layer "In11.Cu")
		(net "M_H_CPU0_SB_DQS_DN<4>")
	)
	(segment
		(start 436.780432 -234.903772)
		(end 436.303928 -234.903772)
		(width 0.18288)
		(layer "In11.Cu")
		(net "M_H_CPU0_SB_DQS_DN<4>")
	)
	(segment
		(start 451.427596 -236.597698)
		(end 451.182994 -236.8423)
		(width 0.18288)
		(layer "In11.Cu")
		(net "M_H_CPU0_SB_DQS_DN<4>")
	)
	(segment
		(start 374.819164 -241.97945)
		(end 374.804432 -241.970814)
		(width 0.088646)
		(layer "In11.Cu")
		(net "M_H_CPU0_SB_DQS_DN<4>")
	)
	(segment
		(start 377.638564 -241.979196)
		(end 377.623832 -241.97056)
		(width 0.088646)
		(layer "In11.Cu")
		(net "M_H_CPU0_SB_DQS_DN<4>")
	)
	(segment
		(start 401.05711 -237.220506)
		(end 395.645132 -242.632484)
		(width 0.18288)
		(layer "In11.Cu")
		(net "M_H_CPU0_SB_DQS_DN<4>")
	)
	(segment
		(start 386.087112 -242.787424)
		(end 385.339844 -242.040156)
		(width 0.088646)
		(layer "In11.Cu")
		(net "M_H_CPU0_SB_DQS_DN<4>")
	)
	(segment
		(start 452.264526 -236.925358)
		(end 451.936866 -236.597698)
		(width 0.18288)
		(layer "In11.Cu")
		(net "M_H_CPU0_SB_DQS_DN<4>")
	)
	(segment
		(start 405.09571 -237.220506)
		(end 404.97125 -237.344966)
		(width 0.18288)
		(layer "In11.Cu")
		(net "M_H_CPU0_SB_DQS_DN<4>")
	)
	(segment
		(start 443.28842 -235.98124)
		(end 442.246512 -236.412786)
		(width 0.18288)
		(layer "In11.Cu")
		(net "M_H_CPU0_SB_DQS_DN<4>")
	)
	(segment
		(start 424.588686 -234.291124)
		(end 424.311318 -234.013756)
		(width 0.18288)
		(layer "In11.Cu")
		(net "M_H_CPU0_SB_DQS_DN<4>")
	)
	(segment
		(start 428.854362 -234.277408)
		(end 428.12716 -234.277408)
		(width 0.18288)
		(layer "In11.Cu")
		(net "M_H_CPU0_SB_DQS_DN<4>")
	)
	(segment
		(start 421.242744 -234.882944)
		(end 420.98468 -235.141008)
		(width 0.18288)
		(layer "In11.Cu")
		(net "M_H_CPU0_SB_DQS_DN<4>")
	)
	(segment
		(start 385.339844 -242.040156)
		(end 385.33959 -242.040156)
		(width 0.088646)
		(layer "In11.Cu")
		(net "M_H_CPU0_SB_DQS_DN<4>")
	)
	(segment
		(start 450.70395 -236.8423)
		(end 450.428868 -236.567218)
		(width 0.18288)
		(layer "In11.Cu")
		(net "M_H_CPU0_SB_DQS_DN<4>")
	)
	(segment
		(start 450.428868 -236.567218)
		(end 448.624198 -236.567218)
		(width 0.18288)
		(layer "In11.Cu")
		(net "M_H_CPU0_SB_DQS_DN<4>")
	)
	(segment
		(start 415.13887 -235.782612)
		(end 413.788606 -235.782612)
		(width 0.18288)
		(layer "In11.Cu")
		(net "M_H_CPU0_SB_DQS_DN<4>")
	)
	(segment
		(start 425.489624 -234.026456)
		(end 425.321222 -234.026456)
		(width 0.18288)
		(layer "In11.Cu")
		(net "M_H_CPU0_SB_DQS_DN<4>")
	)
	(segment
		(start 441.599066 -236.268514)
		(end 441.363354 -236.032802)
		(width 0.18288)
		(layer "In11.Cu")
		(net "M_H_CPU0_SB_DQS_DN<4>")
	)
	(segment
		(start 385.142486 -241.970306)
		(end 385.142232 -241.97056)
		(width 0.088646)
		(layer "In11.Cu")
		(net "M_H_CPU0_SB_DQS_DN<4>")
	)
	(segment
		(start 454.735438 -236.99089)
		(end 454.17994 -236.99089)
		(width 0.18288)
		(layer "In11.Cu")
		(net "M_H_CPU0_SB_DQS_DN<4>")
	)
	(segment
		(start 389.019796 -242.632484)
		(end 388.959852 -242.57254)
		(width 0.088646)
		(layer "In11.Cu")
		(net "M_H_CPU0_SB_DQS_DN<4>")
	)
	(segment
		(start 425.056554 -234.291124)
		(end 424.588686 -234.291124)
		(width 0.18288)
		(layer "In11.Cu")
		(net "M_H_CPU0_SB_DQS_DN<4>")
	)
	(segment
		(start 448.624198 -236.567218)
		(end 448.624198 -236.566964)
		(width 0.18288)
		(layer "In11.Cu")
		(net "M_H_CPU0_SB_DQS_DN<4>")
	)
	(segment
		(start 375.758964 -241.979196)
		(end 375.744232 -241.97056)
		(width 0.088646)
		(layer "In11.Cu")
		(net "M_H_CPU0_SB_DQS_DN<4>")
	)
	(segment
		(start 403.07641 -237.344966)
		(end 402.95195 -237.220506)
		(width 0.18288)
		(layer "In11.Cu")
		(net "M_H_CPU0_SB_DQS_DN<4>")
	)
	(segment
		(start 406.869646 -236.417358)
		(end 406.066498 -237.220506)
		(width 0.18288)
		(layer "In11.Cu")
		(net "M_H_CPU0_SB_DQS_DN<4>")
	)
	(segment
		(start 378.578364 -241.979196)
		(end 378.563632 -241.97056)
		(width 0.088646)
		(layer "In11.Cu")
		(net "M_H_CPU0_SB_DQS_DN<4>")
	)
	(segment
		(start 444.74638 -235.98124)
		(end 444.62192 -236.1057)
		(width 0.18288)
		(layer "In11.Cu")
		(net "M_H_CPU0_SB_DQS_DN<4>")
	)
	(segment
		(start 411.5308 -235.153454)
		(end 409.780486 -236.323124)
		(width 0.18288)
		(layer "In11.Cu")
		(net "M_H_CPU0_SB_DQS_DN<4>")
	)
	(segment
		(start 412.269686 -235.153454)
		(end 411.5308 -235.153454)
		(width 0.18288)
		(layer "In11.Cu")
		(net "M_H_CPU0_SB_DQS_DN<4>")
	)
	(segment
		(start 418.772086 -235.034074)
		(end 418.647626 -234.909614)
		(width 0.18288)
		(layer "In11.Cu")
		(net "M_H_CPU0_SB_DQS_DN<4>")
	)
	(segment
		(start 408.419046 -235.96219)
		(end 407.96845 -235.96219)
		(width 0.18288)
		(layer "In11.Cu")
		(net "M_H_CPU0_SB_DQS_DN<4>")
	)
	(segment
		(start 428.12716 -234.277408)
		(end 427.272958 -234.630976)
		(width 0.18288)
		(layer "In11.Cu")
		(net "M_H_CPU0_SB_DQS_DN<4>")
	)
	(segment
		(start 373.782336 -242.064794)
		(end 373.760238 -242.074192)
		(width 0.088646)
		(layer "In11.Cu")
		(net "M_H_CPU0_SB_DQS_DN<4>")
	)
	(segment
		(start 447.263012 -236.296454)
		(end 447.116708 -236.394244)
		(width 0.18288)
		(layer "In11.Cu")
		(net "M_H_CPU0_SB_DQS_DN<4>")
	)
	(segment
		(start 448.624198 -236.566964)
		(end 447.263012 -236.296454)
		(width 0.18288)
		(layer "In11.Cu")
		(net "M_H_CPU0_SB_DQS_DN<4>")
	)
	(segment
		(start 388.250176 -242.57254)
		(end 388.035292 -242.787424)
		(width 0.088646)
		(layer "In11.Cu")
		(net "M_H_CPU0_SB_DQS_DN<4>")
	)
	(segment
		(start 435.28488 -234.896152)
		(end 433.723796 -234.896152)
		(width 0.18288)
		(layer "In11.Cu")
		(net "M_H_CPU0_SB_DQS_DN<4>")
	)
	(segment
		(start 388.959852 -242.57254)
		(end 388.250176 -242.57254)
		(width 0.088646)
		(layer "In11.Cu")
		(net "M_H_CPU0_SB_DQS_DN<4>")
	)
	(segment
		(start 440.144154 -235.991146)
		(end 439.62955 -235.991146)
		(width 0.18288)
		(layer "In11.Cu")
		(net "M_H_CPU0_SB_DQS_DN<4>")
	)
	(segment
		(start 415.80816 -235.640372)
		(end 415.6456 -235.572808)
		(width 0.18288)
		(layer "In11.Cu")
		(net "M_H_CPU0_SB_DQS_DN<4>")
	)
	(segment
		(start 402.95195 -237.220506)
		(end 402.40331 -237.220506)
		(width 0.18288)
		(layer "In11.Cu")
		(net "M_H_CPU0_SB_DQS_DN<4>")
	)
	(segment
		(start 421.394636 -234.882944)
		(end 421.242744 -234.882944)
		(width 0.18288)
		(layer "In11.Cu")
		(net "M_H_CPU0_SB_DQS_DN<4>")
	)
	(segment
		(start 452.952358 -237.210346)
		(end 452.264526 -236.925358)
		(width 0.18288)
		(layer "In11.Cu")
		(net "M_H_CPU0_SB_DQS_DN<4>")
	)
	(segment
		(start 417.247832 -234.909614)
		(end 416.382962 -235.2675)
		(width 0.18288)
		(layer "In11.Cu")
		(net "M_H_CPU0_SB_DQS_DN<4>")
	)
	(segment
		(start 374.259348 -242.055396)
		(end 373.782844 -242.06454)
		(width 0.088646)
		(layer "In11.Cu")
		(net "M_H_CPU0_SB_DQS_DN<4>")
	)
	(segment
		(start 428.978822 -234.401868)
		(end 428.854362 -234.277408)
		(width 0.18288)
		(layer "In11.Cu")
		(net "M_H_CPU0_SB_DQS_DN<4>")
	)
	(segment
		(start 454.17994 -236.99089)
		(end 453.650096 -237.210346)
		(width 0.18288)
		(layer "In11.Cu")
		(net "M_H_CPU0_SB_DQS_DN<4>")
	)
	(segment
		(start 415.6456 -235.572808)
		(end 415.13887 -235.782612)
		(width 0.18288)
		(layer "In11.Cu")
		(net "M_H_CPU0_SB_DQS_DN<4>")
	)
	(segment
		(start 388.035292 -242.787424)
		(end 386.087112 -242.787424)
		(width 0.088646)
		(layer "In11.Cu")
		(net "M_H_CPU0_SB_DQS_DN<4>")
	)
	(segment
		(start 446.578482 -236.28731)
		(end 446.480692 -236.140752)
		(width 0.18288)
		(layer "In11.Cu")
		(net "M_H_CPU0_SB_DQS_DN<4>")
	)
	(segment
		(start 420.216584 -234.909614)
		(end 419.445186 -234.909614)
		(width 0.18288)
		(layer "In11.Cu")
		(net "M_H_CPU0_SB_DQS_DN<4>")
	)
	(segment
		(start 423.493184 -234.013756)
		(end 421.394636 -234.882944)
		(width 0.18288)
		(layer "In11.Cu")
		(net "M_H_CPU0_SB_DQS_DN<4>")
	)
	(segment
		(start 439.361072 -235.722668)
		(end 438.812432 -235.722668)
		(width 0.18288)
		(layer "In11.Cu")
		(net "M_H_CPU0_SB_DQS_DN<4>")
	)
	(segment
		(start 451.936866 -236.597698)
		(end 451.427596 -236.597698)
		(width 0.18288)
		(layer "In11.Cu")
		(net "M_H_CPU0_SB_DQS_DN<4>")
	)
	(segment
		(start 373.760238 -242.074192)
		(end 373.686832 -242.147598)
		(width 0.088646)
		(layer "In11.Cu")
		(net "M_H_CPU0_SB_DQS_DN<4>")
	)
	(segment
		(start 429.527462 -234.401868)
		(end 428.978822 -234.401868)
		(width 0.18288)
		(layer "In11.Cu")
		(net "M_H_CPU0_SB_DQS_DN<4>")
	)
	(segment
		(start 401.73021 -237.344966)
		(end 401.60575 -237.220506)
		(width 0.18288)
		(layer "In11.Cu")
		(net "M_H_CPU0_SB_DQS_DN<4>")
	)
	(segment
		(start 438.139332 -235.847128)
		(end 438.014872 -235.722668)
		(width 0.18288)
		(layer "In11.Cu")
		(net "M_H_CPU0_SB_DQS_DN<4>")
	)
	(segment
		(start 432.354482 -234.750864)
		(end 432.256692 -234.604306)
		(width 0.18288)
		(layer "In11.Cu")
		(net "M_H_CPU0_SB_DQS_DN<4>")
	)
	(segment
		(start 440.382152 -235.753148)
		(end 440.144154 -235.991146)
		(width 0.18288)
		(layer "In11.Cu")
		(net "M_H_CPU0_SB_DQS_DN<4>")
	)
	(segment
		(start 402.40331 -237.220506)
		(end 402.27885 -237.344966)
		(width 0.18288)
		(layer "In11.Cu")
		(net "M_H_CPU0_SB_DQS_DN<4>")
	)
	(segment
		(start 407.96845 -235.96219)
		(end 406.869646 -236.417358)
		(width 0.18288)
		(layer "In11.Cu")
		(net "M_H_CPU0_SB_DQS_DN<4>")
	)
	(segment
		(start 406.066498 -237.220506)
		(end 405.09571 -237.220506)
		(width 0.18288)
		(layer "In11.Cu")
		(net "M_H_CPU0_SB_DQS_DN<4>")
	)
	(segment
		(start 436.303928 -234.903772)
		(end 436.064152 -235.143548)
		(width 0.18288)
		(layer "In11.Cu")
		(net "M_H_CPU0_SB_DQS_DN<4>")
	)
	(segment
		(start 416.382962 -235.2675)
		(end 416.315398 -235.430568)
		(width 0.18288)
		(layer "In11.Cu")
		(net "M_H_CPU0_SB_DQS_DN<4>")
	)
	(segment
		(start 435.532276 -235.143548)
		(end 435.28488 -234.896152)
		(width 0.18288)
		(layer "In11.Cu")
		(net "M_H_CPU0_SB_DQS_DN<4>")
	)
	(segment
		(start 432.892962 -234.857798)
		(end 432.354482 -234.750864)
		(width 0.18288)
		(layer "In11.Cu")
		(net "M_H_CPU0_SB_DQS_DN<4>")
	)
	(segment
		(start 433.039266 -234.760008)
		(end 432.892962 -234.857798)
		(width 0.18288)
		(layer "In11.Cu")
		(net "M_H_CPU0_SB_DQS_DN<4>")
	)
	(segment
		(start 437.599328 -235.722668)
		(end 436.780432 -234.903772)
		(width 0.18288)
		(layer "In11.Cu")
		(net "M_H_CPU0_SB_DQS_DN<4>")
	)
	(segment
		(start 403.62505 -237.344966)
		(end 403.07641 -237.344966)
		(width 0.18288)
		(layer "In11.Cu")
		(net "M_H_CPU0_SB_DQS_DN<4>")
	)
	(segment
		(start 447.116708 -236.394244)
		(end 446.578482 -236.28731)
		(width 0.18288)
		(layer "In11.Cu")
		(net "M_H_CPU0_SB_DQS_DN<4>")
	)
	(segment
		(start 436.064152 -235.143548)
		(end 435.532276 -235.143548)
		(width 0.18288)
		(layer "In11.Cu")
		(net "M_H_CPU0_SB_DQS_DN<4>")
	)
	(segment
		(start 373.782844 -242.06454)
		(end 373.782336 -242.064794)
		(width 0.088646)
		(layer "In11.Cu")
		(net "M_H_CPU0_SB_DQS_DN<4>")
	)
	(segment
		(start 413.788606 -235.782612)
		(end 412.269686 -235.153454)
		(width 0.18288)
		(layer "In11.Cu")
		(net "M_H_CPU0_SB_DQS_DN<4>")
	)
	(segment
		(start 420.447978 -235.141008)
		(end 420.216584 -234.909614)
		(width 0.18288)
		(layer "In11.Cu")
		(net "M_H_CPU0_SB_DQS_DN<4>")
	)
	(segment
		(start 402.27885 -237.344966)
		(end 401.73021 -237.344966)
		(width 0.18288)
		(layer "In11.Cu")
		(net "M_H_CPU0_SB_DQS_DN<4>")
	)
	(segment
		(start 451.182994 -236.8423)
		(end 450.70395 -236.8423)
		(width 0.18288)
		(layer "In11.Cu")
		(net "M_H_CPU0_SB_DQS_DN<4>")
	)
	(segment
		(start 420.98468 -235.141008)
		(end 420.447978 -235.141008)
		(width 0.18288)
		(layer "In11.Cu")
		(net "M_H_CPU0_SB_DQS_DN<4>")
	)
	(segment
		(start 380.457964 -241.979196)
		(end 380.443232 -241.97056)
		(width 0.088646)
		(layer "In11.Cu")
		(net "M_H_CPU0_SB_DQS_DN<4>")
	)
	(segment
		(start 440.688222 -235.753148)
		(end 440.382152 -235.753148)
		(width 0.18288)
		(layer "In11.Cu")
		(net "M_H_CPU0_SB_DQS_DN<4>")
	)
	(segment
		(start 426.948854 -234.630976)
		(end 425.489624 -234.026456)
		(width 0.18288)
		(layer "In11.Cu")
		(net "M_H_CPU0_SB_DQS_DN<4>")
	)
	(segment
		(start 424.311318 -234.013756)
		(end 423.493184 -234.013756)
		(width 0.18288)
		(layer "In11.Cu")
		(net "M_H_CPU0_SB_DQS_DN<4>")
	)
	(segment
		(start 409.780486 -236.323124)
		(end 409.290774 -236.323124)
		(width 0.18288)
		(layer "In11.Cu")
		(net "M_H_CPU0_SB_DQS_DN<4>")
	)
	(segment
		(start 373.677434 -242.16995)
		(end 373.677434 -242.294918)
		(width 0.088646)
		(layer "In11.Cu")
		(net "M_H_CPU0_SB_DQS_DN<4>")
	)
	(segment
		(start 404.97125 -237.344966)
		(end 404.42261 -237.344966)
		(width 0.18288)
		(layer "In11.Cu")
		(net "M_H_CPU0_SB_DQS_DN<4>")
	)
	(segment
		(start 416.315398 -235.430568)
		(end 415.80816 -235.640372)
		(width 0.18288)
		(layer "In11.Cu")
		(net "M_H_CPU0_SB_DQS_DN<4>")
	)
	(segment
		(start 441.363354 -236.032802)
		(end 440.688222 -235.753148)
		(width 0.18288)
		(layer "In11.Cu")
		(net "M_H_CPU0_SB_DQS_DN<4>")
	)
	(segment
		(start 409.290774 -236.323124)
		(end 408.419046 -235.96219)
		(width 0.18288)
		(layer "In11.Cu")
		(net "M_H_CPU0_SB_DQS_DN<4>")
	)
	(segment
		(start 453.650096 -237.210346)
		(end 452.952358 -237.210346)
		(width 0.18288)
		(layer "In11.Cu")
		(net "M_H_CPU0_SB_DQS_DN<4>")
	)
	(segment
		(start 432.256692 -234.604306)
		(end 430.61382 -234.277408)
		(width 0.18288)
		(layer "In11.Cu")
		(net "M_H_CPU0_SB_DQS_DN<4>")
	)
	(segment
		(start 441.9473 -236.412786)
		(end 441.599066 -236.268514)
		(width 0.18288)
		(layer "In11.Cu")
		(net "M_H_CPU0_SB_DQS_DN<4>")
	)
	(segment
		(start 375.369836 -241.97056)
		(end 375.369836 -241.970814)
		(width 0.088646)
		(layer "In11.Cu")
		(net "M_H_CPU0_SB_DQS_DN<4>")
	)
	(segment
		(start 429.651922 -234.277408)
		(end 429.527462 -234.401868)
		(width 0.18288)
		(layer "In11.Cu")
		(net "M_H_CPU0_SB_DQS_DN<4>")
	)
	(segment
		(start 395.645132 -242.632484)
		(end 389.019796 -242.632484)
		(width 0.18288)
		(layer "In11.Cu")
		(net "M_H_CPU0_SB_DQS_DN<4>")
	)
	(segment
		(start 438.014872 -235.722668)
		(end 437.599328 -235.722668)
		(width 0.18288)
		(layer "In11.Cu")
		(net "M_H_CPU0_SB_DQS_DN<4>")
	)
	(segment
		(start 438.687972 -235.847128)
		(end 438.139332 -235.847128)
		(width 0.18288)
		(layer "In11.Cu")
		(net "M_H_CPU0_SB_DQS_DN<4>")
	)
	(segment
		(start 446.480692 -236.140752)
		(end 445.678306 -235.98124)
		(width 0.18288)
		(layer "In11.Cu")
		(net "M_H_CPU0_SB_DQS_DN<4>")
	)
	(segment
		(start 419.445186 -234.909614)
		(end 419.320726 -235.034074)
		(width 0.18288)
		(layer "In11.Cu")
		(net "M_H_CPU0_SB_DQS_DN<4>")
	)
	(segment
		(start 439.62955 -235.991146)
		(end 439.361072 -235.722668)
		(width 0.18288)
		(layer "In11.Cu")
		(net "M_H_CPU0_SB_DQS_DN<4>")
	)
	(segment
		(start 373.686832 -242.147598)
		(end 373.677434 -242.16995)
		(width 0.088646)
		(layer "In11.Cu")
		(net "M_H_CPU0_SB_DQS_DN<4>")
	)
	(segment
		(start 444.62192 -236.1057)
		(end 444.07328 -236.1057)
		(width 0.18288)
		(layer "In11.Cu")
		(net "M_H_CPU0_SB_DQS_DN<4>")
	)
	(segment
		(start 438.812432 -235.722668)
		(end 438.687972 -235.847128)
		(width 0.18288)
		(layer "In11.Cu")
		(net "M_H_CPU0_SB_DQS_DN<4>")
	)
	(segment
		(start 374.414796 -241.978942)
		(end 374.259348 -242.055396)
		(width 0.088646)
		(layer "In11.Cu")
		(net "M_H_CPU0_SB_DQS_DN<4>")
	)
	(segment
		(start 430.61382 -234.277408)
		(end 429.651922 -234.277408)
		(width 0.18288)
		(layer "In11.Cu")
		(net "M_H_CPU0_SB_DQS_DN<4>")
	)
	(segment
		(start 442.246512 -236.412786)
		(end 441.9473 -236.412786)
		(width 0.18288)
		(layer "In11.Cu")
		(net "M_H_CPU0_SB_DQS_DN<4>")
	)
	(segment
		(start 404.42261 -237.344966)
		(end 404.29815 -237.220506)
		(width 0.18288)
		(layer "In11.Cu")
		(net "M_H_CPU0_SB_DQS_DN<4>")
	)
	(arc
		(start 383.262632 -241.97056)
		(mid 383.075434 -241.920417)
		(end 382.888236 -241.97056)
		(width 0.088646)
		(layer "In11.Cu")
		(net "M_H_CPU0_SB_DQS_DN<4>")
	)
	(arc
		(start 383.828036 -241.97056)
		(mid 383.545334 -242.046336)
		(end 383.262632 -241.97056)
		(width 0.088646)
		(layer "In11.Cu")
		(net "M_H_CPU0_SB_DQS_DN<4>")
	)
	(arc
		(start 379.129036 -241.97056)
		(mid 378.854837 -242.046395)
		(end 378.578364 -241.979196)
		(width 0.088646)
		(layer "In11.Cu")
		(net "M_H_CPU0_SB_DQS_DN<4>")
	)
	(arc
		(start 375.369836 -241.970814)
		(mid 375.095637 -242.046649)
		(end 374.819164 -241.97945)
		(width 0.088646)
		(layer "In11.Cu")
		(net "M_H_CPU0_SB_DQS_DN<4>")
	)
	(arc
		(start 384.767836 -241.97056)
		(mid 384.485134 -242.046336)
		(end 384.202432 -241.97056)
		(width 0.088646)
		(layer "In11.Cu")
		(net "M_H_CPU0_SB_DQS_DN<4>")
	)
	(arc
		(start 379.503432 -241.97056)
		(mid 379.316234 -241.920417)
		(end 379.129036 -241.97056)
		(width 0.088646)
		(layer "In11.Cu")
		(net "M_H_CPU0_SB_DQS_DN<4>")
	)
	(arc
		(start 380.443232 -241.97056)
		(mid 380.256034 -241.920417)
		(end 380.068836 -241.97056)
		(width 0.088646)
		(layer "In11.Cu")
		(net "M_H_CPU0_SB_DQS_DN<4>")
	)
	(arc
		(start 376.684032 -241.97056)
		(mid 376.496834 -241.920417)
		(end 376.309636 -241.97056)
		(width 0.088646)
		(layer "In11.Cu")
		(net "M_H_CPU0_SB_DQS_DN<4>")
	)
	(arc
		(start 381.008636 -241.97056)
		(mid 380.734437 -242.046395)
		(end 380.457964 -241.979196)
		(width 0.088646)
		(layer "In11.Cu")
		(net "M_H_CPU0_SB_DQS_DN<4>")
	)
	(arc
		(start 378.563632 -241.97056)
		(mid 378.376434 -241.920417)
		(end 378.189236 -241.97056)
		(width 0.088646)
		(layer "In11.Cu")
		(net "M_H_CPU0_SB_DQS_DN<4>")
	)
	(arc
		(start 374.804432 -241.970814)
		(mid 374.617234 -241.920637)
		(end 374.430036 -241.970814)
		(width 0.088646)
		(layer "In11.Cu")
		(net "M_H_CPU0_SB_DQS_DN<4>")
	)
	(arc
		(start 380.068836 -241.97056)
		(mid 379.794637 -242.046395)
		(end 379.518164 -241.979196)
		(width 0.088646)
		(layer "In11.Cu")
		(net "M_H_CPU0_SB_DQS_DN<4>")
	)
	(arc
		(start 384.202432 -241.97056)
		(mid 384.015234 -241.920417)
		(end 383.828036 -241.97056)
		(width 0.088646)
		(layer "In11.Cu")
		(net "M_H_CPU0_SB_DQS_DN<4>")
	)
	(arc
		(start 377.249436 -241.97056)
		(mid 376.966734 -242.046336)
		(end 376.684032 -241.97056)
		(width 0.088646)
		(layer "In11.Cu")
		(net "M_H_CPU0_SB_DQS_DN<4>")
	)
	(arc
		(start 376.309636 -241.97056)
		(mid 376.035437 -242.046395)
		(end 375.758964 -241.979196)
		(width 0.088646)
		(layer "In11.Cu")
		(net "M_H_CPU0_SB_DQS_DN<4>")
	)
	(arc
		(start 377.623832 -241.97056)
		(mid 377.436634 -241.920417)
		(end 377.249436 -241.97056)
		(width 0.088646)
		(layer "In11.Cu")
		(net "M_H_CPU0_SB_DQS_DN<4>")
	)
	(arc
		(start 382.888236 -241.97056)
		(mid 382.614037 -242.046395)
		(end 382.337564 -241.979196)
		(width 0.088646)
		(layer "In11.Cu")
		(net "M_H_CPU0_SB_DQS_DN<4>")
	)
	(arc
		(start 381.383032 -241.97056)
		(mid 381.195834 -241.920417)
		(end 381.008636 -241.97056)
		(width 0.088646)
		(layer "In11.Cu")
		(net "M_H_CPU0_SB_DQS_DN<4>")
	)
	(arc
		(start 381.948436 -241.97056)
		(mid 381.665734 -242.046336)
		(end 381.383032 -241.97056)
		(width 0.088646)
		(layer "In11.Cu")
		(net "M_H_CPU0_SB_DQS_DN<4>")
	)
	(arc
		(start 375.744232 -241.97056)
		(mid 375.557034 -241.920417)
		(end 375.369836 -241.97056)
		(width 0.088646)
		(layer "In11.Cu")
		(net "M_H_CPU0_SB_DQS_DN<4>")
	)
	(arc
		(start 382.322832 -241.97056)
		(mid 382.135634 -241.920417)
		(end 381.948436 -241.97056)
		(width 0.088646)
		(layer "In11.Cu")
		(net "M_H_CPU0_SB_DQS_DN<4>")
	)
	(arc
		(start 385.142232 -241.97056)
		(mid 384.955034 -241.920417)
		(end 384.767836 -241.97056)
		(width 0.088646)
		(layer "In11.Cu")
		(net "M_H_CPU0_SB_DQS_DN<4>")
	)
	(arc
		(start 385.33959 -242.040156)
		(mid 385.237788 -242.014406)
		(end 385.142486 -241.970306)
		(width 0.088646)
		(layer "In11.Cu")
		(net "M_H_CPU0_SB_DQS_DN<4>")
	)
	(arc
		(start 378.189236 -241.97056)
		(mid 377.915037 -242.046395)
		(end 377.638564 -241.979196)
		(width 0.088646)
		(layer "In11.Cu")
		(net "M_H_CPU0_SB_DQS_DN<4>")
	)
	(segment
		(start 458.970634 -199.866758)
		(end 458.730096 -200.107296)
		(width 0.20066)
		(layer "F.Cu")
		(net "M_H_CPU0_SB_DQS_DN<3>")
	)
	(segment
		(start 457.987146 -200.51776)
		(end 457.682092 -200.51776)
		(width 0.20066)
		(layer "F.Cu")
		(net "M_H_CPU0_SB_DQS_DN<3>")
	)
	(segment
		(start 454.789794 -200.2917)
		(end 454.518522 -200.562972)
		(width 0.20066)
		(layer "F.Cu")
		(net "M_H_CPU0_SB_DQS_DN<3>")
	)
	(segment
		(start 457.450698 -200.286366)
		(end 457.126594 -200.286366)
		(width 0.20066)
		(layer "F.Cu")
		(net "M_H_CPU0_SB_DQS_DN<3>")
	)
	(segment
		(start 452.564754 -199.866758)
		(end 452.016114 -199.866758)
		(width 0.20066)
		(layer "F.Cu")
		(net "M_H_CPU0_SB_DQS_DN<3>")
	)
	(segment
		(start 459.559914 -199.866758)
		(end 458.970634 -199.866758)
		(width 0.20066)
		(layer "F.Cu")
		(net "M_H_CPU0_SB_DQS_DN<3>")
	)
	(segment
		(start 454.518522 -200.562972)
		(end 453.996806 -200.562972)
		(width 0.20066)
		(layer "F.Cu")
		(net "M_H_CPU0_SB_DQS_DN<3>")
	)
	(segment
		(start 453.996806 -200.562972)
		(end 453.582278 -200.148444)
		(width 0.20066)
		(layer "F.Cu")
		(net "M_H_CPU0_SB_DQS_DN<3>")
	)
	(segment
		(start 370.858034 -228.180646)
		(end 370.858034 -227.64496)
		(width 0.20066)
		(layer "F.Cu")
		(net "M_H_CPU0_SB_DQS_DN<3>")
	)
	(segment
		(start 458.730096 -200.107296)
		(end 458.39761 -200.107296)
		(width 0.20066)
		(layer "F.Cu")
		(net "M_H_CPU0_SB_DQS_DN<3>")
	)
	(segment
		(start 457.682092 -200.51776)
		(end 457.450698 -200.286366)
		(width 0.20066)
		(layer "F.Cu")
		(net "M_H_CPU0_SB_DQS_DN<3>")
	)
	(segment
		(start 457.126594 -200.286366)
		(end 457.12126 -200.2917)
		(width 0.1016)
		(layer "F.Cu")
		(net "M_H_CPU0_SB_DQS_DN<3>")
	)
	(segment
		(start 370.85778 -228.1809)
		(end 370.858034 -228.180646)
		(width 0.20066)
		(layer "F.Cu")
		(net "M_H_CPU0_SB_DQS_DN<3>")
	)
	(segment
		(start 450.911214 -199.866758)
		(end 452.016114 -199.866758)
		(width 0.20066)
		(layer "F.Cu")
		(net "M_H_CPU0_SB_DQS_DN<3>")
	)
	(segment
		(start 452.84644 -200.148444)
		(end 452.564754 -199.866758)
		(width 0.20066)
		(layer "F.Cu")
		(net "M_H_CPU0_SB_DQS_DN<3>")
	)
	(segment
		(start 454.941686 -200.2917)
		(end 454.937368 -200.2917)
		(width 0.101854)
		(layer "F.Cu")
		(net "M_H_CPU0_SB_DQS_DN<3>")
	)
	(segment
		(start 454.937368 -200.2917)
		(end 454.789794 -200.2917)
		(width 0.20066)
		(layer "F.Cu")
		(net "M_H_CPU0_SB_DQS_DN<3>")
	)
	(segment
		(start 457.12126 -200.2917)
		(end 454.941686 -200.2917)
		(width 0.1016)
		(layer "F.Cu")
		(net "M_H_CPU0_SB_DQS_DN<3>")
	)
	(segment
		(start 453.582278 -200.148444)
		(end 452.84644 -200.148444)
		(width 0.20066)
		(layer "F.Cu")
		(net "M_H_CPU0_SB_DQS_DN<3>")
	)
	(segment
		(start 458.39761 -200.107296)
		(end 457.987146 -200.51776)
		(width 0.20066)
		(layer "F.Cu")
		(net "M_H_CPU0_SB_DQS_DN<3>")
	)
	(segment
		(start 437.12638 -198.866506)
		(end 436.306722 -198.866506)
		(width 0.18288)
		(layer "In11.Cu")
		(net "M_H_CPU0_SB_DQS_DN<3>")
	)
	(segment
		(start 386.269484 -225.998786)
		(end 386.269484 -226.017328)
		(width 0.088646)
		(layer "In11.Cu")
		(net "M_H_CPU0_SB_DQS_DN<3>")
	)
	(segment
		(start 374.899936 -227.155502)
		(end 374.889522 -227.149406)
		(width 0.088646)
		(layer "In11.Cu")
		(net "M_H_CPU0_SB_DQS_DN<3>")
	)
	(segment
		(start 436.031386 -198.59117)
		(end 435.55539 -198.59117)
		(width 0.18288)
		(layer "In11.Cu")
		(net "M_H_CPU0_SB_DQS_DN<3>")
	)
	(segment
		(start 373.959882 -227.155502)
		(end 373.94515 -227.146866)
		(width 0.088646)
		(layer "In11.Cu")
		(net "M_H_CPU0_SB_DQS_DN<3>")
	)
	(segment
		(start 450.911214 -199.866758)
		(end 450.646546 -200.131426)
		(width 0.18288)
		(layer "In11.Cu")
		(net "M_H_CPU0_SB_DQS_DN<3>")
	)
	(segment
		(start 378.659136 -227.155502)
		(end 378.648722 -227.149406)
		(width 0.088646)
		(layer "In11.Cu")
		(net "M_H_CPU0_SB_DQS_DN<3>")
	)
	(segment
		(start 437.962802 -198.030084)
		(end 437.12638 -198.866506)
		(width 0.18288)
		(layer "In11.Cu")
		(net "M_H_CPU0_SB_DQS_DN<3>")
	)
	(segment
		(start 440.417458 -198.016622)
		(end 440.142122 -197.741286)
		(width 0.18288)
		(layer "In11.Cu")
		(net "M_H_CPU0_SB_DQS_DN<3>")
	)
	(segment
		(start 433.564538 -199.256142)
		(end 433.564538 -199.992488)
		(width 0.18288)
		(layer "In11.Cu")
		(net "M_H_CPU0_SB_DQS_DN<3>")
	)
	(segment
		(start 382.418082 -227.155502)
		(end 382.407668 -227.149406)
		(width 0.088646)
		(layer "In11.Cu")
		(net "M_H_CPU0_SB_DQS_DN<3>")
	)
	(segment
		(start 420.20363 -198.85533)
		(end 418.020754 -198.85533)
		(width 0.18288)
		(layer "In11.Cu")
		(net "M_H_CPU0_SB_DQS_DN<3>")
	)
	(segment
		(start 421.481758 -198.866506)
		(end 421.216582 -198.866506)
		(width 0.18288)
		(layer "In11.Cu")
		(net "M_H_CPU0_SB_DQS_DN<3>")
	)
	(segment
		(start 388.6073 -221.822772)
		(end 388.404608 -222.025464)
		(width 0.088646)
		(layer "In11.Cu")
		(net "M_H_CPU0_SB_DQS_DN<3>")
	)
	(segment
		(start 450.273928 -200.131426)
		(end 449.909692 -199.76719)
		(width 0.18288)
		(layer "In11.Cu")
		(net "M_H_CPU0_SB_DQS_DN<3>")
	)
	(segment
		(start 403.044914 -204.43698)
		(end 394.817346 -212.664548)
		(width 0.18288)
		(layer "In11.Cu")
		(net "M_H_CPU0_SB_DQS_DN<3>")
	)
	(segment
		(start 425.044362 -197.741286)
		(end 424.567858 -197.741286)
		(width 0.18288)
		(layer "In11.Cu")
		(net "M_H_CPU0_SB_DQS_DN<3>")
	)
	(segment
		(start 449.909692 -199.76719)
		(end 442.870336 -199.76719)
		(width 0.18288)
		(layer "In11.Cu")
		(net "M_H_CPU0_SB_DQS_DN<3>")
	)
	(segment
		(start 450.646546 -200.131426)
		(end 450.273928 -200.131426)
		(width 0.18288)
		(layer "In11.Cu")
		(net "M_H_CPU0_SB_DQS_DN<3>")
	)
	(segment
		(start 416.903154 -199.97293)
		(end 409.328874 -199.97293)
		(width 0.18288)
		(layer "In11.Cu")
		(net "M_H_CPU0_SB_DQS_DN<3>")
	)
	(segment
		(start 425.321476 -198.0184)
		(end 425.044362 -197.741286)
		(width 0.18288)
		(layer "In11.Cu")
		(net "M_H_CPU0_SB_DQS_DN<3>")
	)
	(segment
		(start 424.567858 -197.741286)
		(end 424.298872 -198.010272)
		(width 0.18288)
		(layer "In11.Cu")
		(net "M_H_CPU0_SB_DQS_DN<3>")
	)
	(segment
		(start 418.020754 -198.85533)
		(end 416.903154 -199.97293)
		(width 0.18288)
		(layer "In11.Cu")
		(net "M_H_CPU0_SB_DQS_DN<3>")
	)
	(segment
		(start 387.247892 -224.467674)
		(end 387.247892 -224.850452)
		(width 0.088646)
		(layer "In11.Cu")
		(net "M_H_CPU0_SB_DQS_DN<3>")
	)
	(segment
		(start 421.216582 -198.866506)
		(end 420.941246 -198.59117)
		(width 0.18288)
		(layer "In11.Cu")
		(net "M_H_CPU0_SB_DQS_DN<3>")
	)
	(segment
		(start 373.020082 -227.155502)
		(end 373.009668 -227.149406)
		(width 0.088646)
		(layer "In11.Cu")
		(net "M_H_CPU0_SB_DQS_DN<3>")
	)
	(segment
		(start 420.46779 -198.59117)
		(end 420.20363 -198.85533)
		(width 0.18288)
		(layer "In11.Cu")
		(net "M_H_CPU0_SB_DQS_DN<3>")
	)
	(segment
		(start 371.170708 -227.64496)
		(end 370.858034 -227.64496)
		(width 0.088646)
		(layer "In11.Cu")
		(net "M_H_CPU0_SB_DQS_DN<3>")
	)
	(segment
		(start 409.328874 -199.97293)
		(end 408.522424 -200.77938)
		(width 0.18288)
		(layer "In11.Cu")
		(net "M_H_CPU0_SB_DQS_DN<3>")
	)
	(segment
		(start 433.046886 -200.188576)
		(end 432.850798 -199.992488)
		(width 0.18288)
		(layer "In11.Cu")
		(net "M_H_CPU0_SB_DQS_DN<3>")
	)
	(segment
		(start 433.564538 -199.992488)
		(end 433.36845 -200.188576)
		(width 0.18288)
		(layer "In11.Cu")
		(net "M_H_CPU0_SB_DQS_DN<3>")
	)
	(segment
		(start 388.6073 -221.738444)
		(end 388.6073 -221.822772)
		(width 0.088646)
		(layer "In11.Cu")
		(net "M_H_CPU0_SB_DQS_DN<3>")
	)
	(segment
		(start 424.298872 -198.010272)
		(end 422.337992 -198.010272)
		(width 0.18288)
		(layer "In11.Cu")
		(net "M_H_CPU0_SB_DQS_DN<3>")
	)
	(segment
		(start 439.655458 -197.741286)
		(end 439.36666 -198.030084)
		(width 0.18288)
		(layer "In11.Cu")
		(net "M_H_CPU0_SB_DQS_DN<3>")
	)
	(segment
		(start 430.713896 -199.471788)
		(end 427.689772 -199.471788)
		(width 0.18288)
		(layer "In11.Cu")
		(net "M_H_CPU0_SB_DQS_DN<3>")
	)
	(segment
		(start 403.044914 -202.80249)
		(end 403.044914 -204.43698)
		(width 0.18288)
		(layer "In11.Cu")
		(net "M_H_CPU0_SB_DQS_DN<3>")
	)
	(segment
		(start 439.36666 -198.030084)
		(end 437.962802 -198.030084)
		(width 0.18288)
		(layer "In11.Cu")
		(net "M_H_CPU0_SB_DQS_DN<3>")
	)
	(segment
		(start 394.817346 -212.664548)
		(end 394.817346 -215.528398)
		(width 0.18288)
		(layer "In11.Cu")
		(net "M_H_CPU0_SB_DQS_DN<3>")
	)
	(segment
		(start 432.473354 -198.878698)
		(end 431.306986 -198.878698)
		(width 0.18288)
		(layer "In11.Cu")
		(net "M_H_CPU0_SB_DQS_DN<3>")
	)
	(segment
		(start 380.538482 -227.155502)
		(end 380.52375 -227.146866)
		(width 0.088646)
		(layer "In11.Cu")
		(net "M_H_CPU0_SB_DQS_DN<3>")
	)
	(segment
		(start 440.142122 -197.741286)
		(end 439.655458 -197.741286)
		(width 0.18288)
		(layer "In11.Cu")
		(net "M_H_CPU0_SB_DQS_DN<3>")
	)
	(segment
		(start 394.817346 -215.528398)
		(end 388.6073 -221.738444)
		(width 0.18288)
		(layer "In11.Cu")
		(net "M_H_CPU0_SB_DQS_DN<3>")
	)
	(segment
		(start 427.689772 -199.471788)
		(end 426.236384 -198.0184)
		(width 0.18288)
		(layer "In11.Cu")
		(net "M_H_CPU0_SB_DQS_DN<3>")
	)
	(segment
		(start 405.068024 -200.77938)
		(end 403.044914 -202.80249)
		(width 0.18288)
		(layer "In11.Cu")
		(net "M_H_CPU0_SB_DQS_DN<3>")
	)
	(segment
		(start 375.289064 -227.146866)
		(end 375.274332 -227.155502)
		(width 0.088646)
		(layer "In11.Cu")
		(net "M_H_CPU0_SB_DQS_DN<3>")
	)
	(segment
		(start 435.267862 -198.878698)
		(end 433.941982 -198.878698)
		(width 0.18288)
		(layer "In11.Cu")
		(net "M_H_CPU0_SB_DQS_DN<3>")
	)
	(segment
		(start 422.337992 -198.010272)
		(end 421.481758 -198.866506)
		(width 0.18288)
		(layer "In11.Cu")
		(net "M_H_CPU0_SB_DQS_DN<3>")
	)
	(segment
		(start 383.358136 -227.155502)
		(end 383.347722 -227.149406)
		(width 0.088646)
		(layer "In11.Cu")
		(net "M_H_CPU0_SB_DQS_DN<3>")
	)
	(segment
		(start 432.850798 -199.992488)
		(end 432.850798 -199.256142)
		(width 0.18288)
		(layer "In11.Cu")
		(net "M_H_CPU0_SB_DQS_DN<3>")
	)
	(segment
		(start 433.36845 -200.188576)
		(end 433.046886 -200.188576)
		(width 0.18288)
		(layer "In11.Cu")
		(net "M_H_CPU0_SB_DQS_DN<3>")
	)
	(segment
		(start 436.306722 -198.866506)
		(end 436.031386 -198.59117)
		(width 0.18288)
		(layer "In11.Cu")
		(net "M_H_CPU0_SB_DQS_DN<3>")
	)
	(segment
		(start 420.941246 -198.59117)
		(end 420.46779 -198.59117)
		(width 0.18288)
		(layer "In11.Cu")
		(net "M_H_CPU0_SB_DQS_DN<3>")
	)
	(segment
		(start 432.850798 -199.256142)
		(end 432.473354 -198.878698)
		(width 0.18288)
		(layer "In11.Cu")
		(net "M_H_CPU0_SB_DQS_DN<3>")
	)
	(segment
		(start 442.870336 -199.76719)
		(end 441.119768 -198.016622)
		(width 0.18288)
		(layer "In11.Cu")
		(net "M_H_CPU0_SB_DQS_DN<3>")
	)
	(segment
		(start 383.919984 -226.821238)
		(end 383.919984 -226.831144)
		(width 0.088646)
		(layer "In11.Cu")
		(net "M_H_CPU0_SB_DQS_DN<3>")
	)
	(segment
		(start 408.522424 -200.77938)
		(end 405.068024 -200.77938)
		(width 0.18288)
		(layer "In11.Cu")
		(net "M_H_CPU0_SB_DQS_DN<3>")
	)
	(segment
		(start 426.236384 -198.0184)
		(end 425.321476 -198.0184)
		(width 0.18288)
		(layer "In11.Cu")
		(net "M_H_CPU0_SB_DQS_DN<3>")
	)
	(segment
		(start 376.224546 -227.149406)
		(end 376.214132 -227.155502)
		(width 0.088646)
		(layer "In11.Cu")
		(net "M_H_CPU0_SB_DQS_DN<3>")
	)
	(segment
		(start 371.23624 -227.579428)
		(end 371.170708 -227.64496)
		(width 0.088646)
		(layer "In11.Cu")
		(net "M_H_CPU0_SB_DQS_DN<3>")
	)
	(segment
		(start 388.404608 -223.310958)
		(end 387.247892 -224.467674)
		(width 0.088646)
		(layer "In11.Cu")
		(net "M_H_CPU0_SB_DQS_DN<3>")
	)
	(segment
		(start 372.080536 -227.155502)
		(end 372.070122 -227.149406)
		(width 0.088646)
		(layer "In11.Cu")
		(net "M_H_CPU0_SB_DQS_DN<3>")
	)
	(segment
		(start 441.119768 -198.016622)
		(end 440.417458 -198.016622)
		(width 0.18288)
		(layer "In11.Cu")
		(net "M_H_CPU0_SB_DQS_DN<3>")
	)
	(segment
		(start 379.598682 -227.155502)
		(end 379.588268 -227.149406)
		(width 0.088646)
		(layer "In11.Cu")
		(net "M_H_CPU0_SB_DQS_DN<3>")
	)
	(segment
		(start 433.941982 -198.878698)
		(end 433.564538 -199.256142)
		(width 0.18288)
		(layer "In11.Cu")
		(net "M_H_CPU0_SB_DQS_DN<3>")
	)
	(segment
		(start 435.55539 -198.59117)
		(end 435.267862 -198.878698)
		(width 0.18288)
		(layer "In11.Cu")
		(net "M_H_CPU0_SB_DQS_DN<3>")
	)
	(segment
		(start 431.306986 -198.878698)
		(end 430.713896 -199.471788)
		(width 0.18288)
		(layer "In11.Cu")
		(net "M_H_CPU0_SB_DQS_DN<3>")
	)
	(segment
		(start 381.478536 -227.155502)
		(end 381.468122 -227.149406)
		(width 0.088646)
		(layer "In11.Cu")
		(net "M_H_CPU0_SB_DQS_DN<3>")
	)
	(segment
		(start 387.247892 -224.850452)
		(end 386.629656 -225.468688)
		(width 0.088646)
		(layer "In11.Cu")
		(net "M_H_CPU0_SB_DQS_DN<3>")
	)
	(segment
		(start 388.404608 -222.025464)
		(end 388.404608 -223.310958)
		(width 0.088646)
		(layer "In11.Cu")
		(net "M_H_CPU0_SB_DQS_DN<3>")
	)
	(segment
		(start 377.719082 -227.155502)
		(end 377.70435 -227.146866)
		(width 0.088646)
		(layer "In11.Cu")
		(net "M_H_CPU0_SB_DQS_DN<3>")
	)
	(arc
		(start 374.889522 -227.149406)
		(mid 374.61109 -227.07956)
		(end 374.334278 -227.155502)
		(width 0.088646)
		(layer "In11.Cu")
		(net "M_H_CPU0_SB_DQS_DN<3>")
	)
	(arc
		(start 377.70435 -227.146866)
		(mid 377.427875 -227.079546)
		(end 377.153678 -227.155502)
		(width 0.088646)
		(layer "In11.Cu")
		(net "M_H_CPU0_SB_DQS_DN<3>")
	)
	(arc
		(start 373.009668 -227.149406)
		(mid 372.73149 -227.079683)
		(end 372.454932 -227.155502)
		(width 0.088646)
		(layer "In11.Cu")
		(net "M_H_CPU0_SB_DQS_DN<3>")
	)
	(arc
		(start 377.153678 -227.155502)
		(mid 376.96648 -227.205645)
		(end 376.779282 -227.155502)
		(width 0.088646)
		(layer "In11.Cu")
		(net "M_H_CPU0_SB_DQS_DN<3>")
	)
	(arc
		(start 380.52375 -227.146866)
		(mid 380.247275 -227.079546)
		(end 379.973078 -227.155502)
		(width 0.088646)
		(layer "In11.Cu")
		(net "M_H_CPU0_SB_DQS_DN<3>")
	)
	(arc
		(start 380.912878 -227.155502)
		(mid 380.72568 -227.205645)
		(end 380.538482 -227.155502)
		(width 0.088646)
		(layer "In11.Cu")
		(net "M_H_CPU0_SB_DQS_DN<3>")
	)
	(arc
		(start 379.973078 -227.155502)
		(mid 379.78588 -227.205645)
		(end 379.598682 -227.155502)
		(width 0.088646)
		(layer "In11.Cu")
		(net "M_H_CPU0_SB_DQS_DN<3>")
	)
	(arc
		(start 386.551932 -225.527616)
		(mid 386.349646 -225.726597)
		(end 386.269484 -225.998786)
		(width 0.088646)
		(layer "In11.Cu")
		(net "M_H_CPU0_SB_DQS_DN<3>")
	)
	(arc
		(start 378.648722 -227.149406)
		(mid 378.37029 -227.07956)
		(end 378.093478 -227.155502)
		(width 0.088646)
		(layer "In11.Cu")
		(net "M_H_CPU0_SB_DQS_DN<3>")
	)
	(arc
		(start 376.779282 -227.155502)
		(mid 376.502723 -227.079759)
		(end 376.224546 -227.149406)
		(width 0.088646)
		(layer "In11.Cu")
		(net "M_H_CPU0_SB_DQS_DN<3>")
	)
	(arc
		(start 376.214132 -227.155502)
		(mid 376.026934 -227.205645)
		(end 375.839736 -227.155502)
		(width 0.088646)
		(layer "In11.Cu")
		(net "M_H_CPU0_SB_DQS_DN<3>")
	)
	(arc
		(start 383.919984 -226.831144)
		(mid 383.732685 -227.155585)
		(end 383.358136 -227.155502)
		(width 0.088646)
		(layer "In11.Cu")
		(net "M_H_CPU0_SB_DQS_DN<3>")
	)
	(arc
		(start 372.070122 -227.149406)
		(mid 371.548182 -227.137625)
		(end 371.239034 -227.558346)
		(width 0.088646)
		(layer "In11.Cu")
		(net "M_H_CPU0_SB_DQS_DN<3>")
	)
	(arc
		(start 375.839736 -227.155502)
		(mid 375.565537 -227.079667)
		(end 375.289064 -227.146866)
		(width 0.088646)
		(layer "In11.Cu")
		(net "M_H_CPU0_SB_DQS_DN<3>")
	)
	(arc
		(start 378.093478 -227.155502)
		(mid 377.90628 -227.205645)
		(end 377.719082 -227.155502)
		(width 0.088646)
		(layer "In11.Cu")
		(net "M_H_CPU0_SB_DQS_DN<3>")
	)
	(arc
		(start 379.588268 -227.149406)
		(mid 379.31009 -227.079683)
		(end 379.033532 -227.155502)
		(width 0.088646)
		(layer "In11.Cu")
		(net "M_H_CPU0_SB_DQS_DN<3>")
	)
	(arc
		(start 371.239034 -227.558346)
		(mid 371.237538 -227.568874)
		(end 371.23624 -227.579428)
		(width 0.088646)
		(layer "In11.Cu")
		(net "M_H_CPU0_SB_DQS_DN<3>")
	)
	(arc
		(start 381.852932 -227.155502)
		(mid 381.665734 -227.205645)
		(end 381.478536 -227.155502)
		(width 0.088646)
		(layer "In11.Cu")
		(net "M_H_CPU0_SB_DQS_DN<3>")
	)
	(arc
		(start 385.142232 -226.341686)
		(mid 384.955034 -226.391829)
		(end 384.767836 -226.341686)
		(width 0.088646)
		(layer "In11.Cu")
		(net "M_H_CPU0_SB_DQS_DN<3>")
	)
	(arc
		(start 373.94515 -227.146866)
		(mid 373.668675 -227.079546)
		(end 373.394478 -227.155502)
		(width 0.088646)
		(layer "In11.Cu")
		(net "M_H_CPU0_SB_DQS_DN<3>")
	)
	(arc
		(start 375.274332 -227.155502)
		(mid 375.087134 -227.205645)
		(end 374.899936 -227.155502)
		(width 0.088646)
		(layer "In11.Cu")
		(net "M_H_CPU0_SB_DQS_DN<3>")
	)
	(arc
		(start 382.407668 -227.149406)
		(mid 382.12949 -227.079683)
		(end 381.852932 -227.155502)
		(width 0.088646)
		(layer "In11.Cu")
		(net "M_H_CPU0_SB_DQS_DN<3>")
	)
	(arc
		(start 386.269484 -226.017328)
		(mid 386.082185 -226.341769)
		(end 385.707636 -226.341686)
		(width 0.088646)
		(layer "In11.Cu")
		(net "M_H_CPU0_SB_DQS_DN<3>")
	)
	(arc
		(start 381.468122 -227.149406)
		(mid 381.18969 -227.07956)
		(end 380.912878 -227.155502)
		(width 0.088646)
		(layer "In11.Cu")
		(net "M_H_CPU0_SB_DQS_DN<3>")
	)
	(arc
		(start 374.334278 -227.155502)
		(mid 374.14708 -227.205645)
		(end 373.959882 -227.155502)
		(width 0.088646)
		(layer "In11.Cu")
		(net "M_H_CPU0_SB_DQS_DN<3>")
	)
	(arc
		(start 384.767836 -226.341686)
		(mid 384.20686 -226.339155)
		(end 383.919984 -226.821238)
		(width 0.088646)
		(layer "In11.Cu")
		(net "M_H_CPU0_SB_DQS_DN<3>")
	)
	(arc
		(start 383.347722 -227.149406)
		(mid 383.06929 -227.07956)
		(end 382.792478 -227.155502)
		(width 0.088646)
		(layer "In11.Cu")
		(net "M_H_CPU0_SB_DQS_DN<3>")
	)
	(arc
		(start 372.454932 -227.155502)
		(mid 372.267734 -227.205645)
		(end 372.080536 -227.155502)
		(width 0.088646)
		(layer "In11.Cu")
		(net "M_H_CPU0_SB_DQS_DN<3>")
	)
	(arc
		(start 386.629656 -225.468688)
		(mid 386.592718 -225.50069)
		(end 386.551932 -225.527616)
		(width 0.088646)
		(layer "In11.Cu")
		(net "M_H_CPU0_SB_DQS_DN<3>")
	)
	(arc
		(start 382.792478 -227.155502)
		(mid 382.60528 -227.205645)
		(end 382.418082 -227.155502)
		(width 0.088646)
		(layer "In11.Cu")
		(net "M_H_CPU0_SB_DQS_DN<3>")
	)
	(arc
		(start 385.707636 -226.341686)
		(mid 385.424934 -226.26591)
		(end 385.142232 -226.341686)
		(width 0.088646)
		(layer "In11.Cu")
		(net "M_H_CPU0_SB_DQS_DN<3>")
	)
	(arc
		(start 379.033532 -227.155502)
		(mid 378.846334 -227.205645)
		(end 378.659136 -227.155502)
		(width 0.088646)
		(layer "In11.Cu")
		(net "M_H_CPU0_SB_DQS_DN<3>")
	)
	(arc
		(start 373.394478 -227.155502)
		(mid 373.20728 -227.205645)
		(end 373.020082 -227.155502)
		(width 0.088646)
		(layer "In11.Cu")
		(net "M_H_CPU0_SB_DQS_DN<3>")
	)
	(segment
		(start 454.789794 -209.641694)
		(end 454.937368 -209.641694)
		(width 0.20066)
		(layer "F.Cu")
		(net "M_H_CPU0_SB_DQS_DN<2>")
	)
	(segment
		(start 452.84644 -209.498438)
		(end 453.582278 -209.498438)
		(width 0.20066)
		(layer "F.Cu")
		(net "M_H_CPU0_SB_DQS_DN<2>")
	)
	(segment
		(start 454.518522 -209.912966)
		(end 454.789794 -209.641694)
		(width 0.20066)
		(layer "F.Cu")
		(net "M_H_CPU0_SB_DQS_DN<2>")
	)
	(segment
		(start 457.126594 -209.63636)
		(end 457.450698 -209.63636)
		(width 0.20066)
		(layer "F.Cu")
		(net "M_H_CPU0_SB_DQS_DN<2>")
	)
	(segment
		(start 452.016114 -209.216752)
		(end 452.564754 -209.216752)
		(width 0.20066)
		(layer "F.Cu")
		(net "M_H_CPU0_SB_DQS_DN<2>")
	)
	(segment
		(start 457.682092 -209.867754)
		(end 457.987146 -209.867754)
		(width 0.20066)
		(layer "F.Cu")
		(net "M_H_CPU0_SB_DQS_DN<2>")
	)
	(segment
		(start 454.937368 -209.641694)
		(end 454.941686 -209.641694)
		(width 0.101854)
		(layer "F.Cu")
		(net "M_H_CPU0_SB_DQS_DN<2>")
	)
	(segment
		(start 452.564754 -209.216752)
		(end 452.84644 -209.498438)
		(width 0.20066)
		(layer "F.Cu")
		(net "M_H_CPU0_SB_DQS_DN<2>")
	)
	(segment
		(start 457.987146 -209.867754)
		(end 458.39761 -209.45729)
		(width 0.20066)
		(layer "F.Cu")
		(net "M_H_CPU0_SB_DQS_DN<2>")
	)
	(segment
		(start 450.911214 -209.216752)
		(end 452.016114 -209.216752)
		(width 0.20066)
		(layer "F.Cu")
		(net "M_H_CPU0_SB_DQS_DN<2>")
	)
	(segment
		(start 453.996806 -209.912966)
		(end 454.518522 -209.912966)
		(width 0.20066)
		(layer "F.Cu")
		(net "M_H_CPU0_SB_DQS_DN<2>")
	)
	(segment
		(start 457.12126 -209.641694)
		(end 457.126594 -209.63636)
		(width 0.1016)
		(layer "F.Cu")
		(net "M_H_CPU0_SB_DQS_DN<2>")
	)
	(segment
		(start 453.582278 -209.498438)
		(end 453.996806 -209.912966)
		(width 0.20066)
		(layer "F.Cu")
		(net "M_H_CPU0_SB_DQS_DN<2>")
	)
	(segment
		(start 375.087134 -230.622602)
		(end 375.08688 -230.622348)
		(width 0.20066)
		(layer "F.Cu")
		(net "M_H_CPU0_SB_DQS_DN<2>")
	)
	(segment
		(start 457.450698 -209.63636)
		(end 457.682092 -209.867754)
		(width 0.20066)
		(layer "F.Cu")
		(net "M_H_CPU0_SB_DQS_DN<2>")
	)
	(segment
		(start 458.970634 -209.216752)
		(end 459.559914 -209.216752)
		(width 0.20066)
		(layer "F.Cu")
		(net "M_H_CPU0_SB_DQS_DN<2>")
	)
	(segment
		(start 454.941686 -209.641694)
		(end 457.12126 -209.641694)
		(width 0.1016)
		(layer "F.Cu")
		(net "M_H_CPU0_SB_DQS_DN<2>")
	)
	(segment
		(start 458.730096 -209.45729)
		(end 458.970634 -209.216752)
		(width 0.20066)
		(layer "F.Cu")
		(net "M_H_CPU0_SB_DQS_DN<2>")
	)
	(segment
		(start 458.39761 -209.45729)
		(end 458.730096 -209.45729)
		(width 0.20066)
		(layer "F.Cu")
		(net "M_H_CPU0_SB_DQS_DN<2>")
	)
	(segment
		(start 375.08688 -230.622348)
		(end 375.08688 -230.086662)
		(width 0.20066)
		(layer "F.Cu")
		(net "M_H_CPU0_SB_DQS_DN<2>")
	)
	(segment
		(start 421.188134 -212.471)
		(end 420.910004 -212.19287)
		(width 0.18288)
		(layer "In6.Cu")
		(net "M_H_CPU0_SB_DQS_DN<2>")
	)
	(segment
		(start 408.761184 -210.518502)
		(end 408.231848 -209.989166)
		(width 0.18288)
		(layer "In6.Cu")
		(net "M_H_CPU0_SB_DQS_DN<2>")
	)
	(segment
		(start 432.532028 -210.762088)
		(end 430.89449 -210.083908)
		(width 0.18288)
		(layer "In6.Cu")
		(net "M_H_CPU0_SB_DQS_DN<2>")
	)
	(segment
		(start 425.481496 -211.605114)
		(end 425.271946 -211.605114)
		(width 0.18288)
		(layer "In6.Cu")
		(net "M_H_CPU0_SB_DQS_DN<2>")
	)
	(segment
		(start 410.294836 -210.518502)
		(end 408.761184 -210.518502)
		(width 0.18288)
		(layer "In6.Cu")
		(net "M_H_CPU0_SB_DQS_DN<2>")
	)
	(segment
		(start 450.65442 -209.473546)
		(end 450.257672 -209.473546)
		(width 0.18288)
		(layer "In6.Cu")
		(net "M_H_CPU0_SB_DQS_DN<2>")
	)
	(segment
		(start 378.56287 -229.597712)
		(end 378.557536 -229.60076)
		(width 0.088646)
		(layer "In6.Cu")
		(net "M_H_CPU0_SB_DQS_DN<2>")
	)
	(segment
		(start 420.910004 -212.19287)
		(end 420.562024 -212.19287)
		(width 0.18288)
		(layer "In6.Cu")
		(net "M_H_CPU0_SB_DQS_DN<2>")
	)
	(segment
		(start 424.391582 -211.61121)
		(end 422.469564 -211.61121)
		(width 0.18288)
		(layer "In6.Cu")
		(net "M_H_CPU0_SB_DQS_DN<2>")
	)
	(segment
		(start 420.285672 -212.469222)
		(end 419.58641 -212.469222)
		(width 0.18288)
		(layer "In6.Cu")
		(net "M_H_CPU0_SB_DQS_DN<2>")
	)
	(segment
		(start 406.655778 -209.864706)
		(end 406.531318 -209.989166)
		(width 0.18288)
		(layer "In6.Cu")
		(net "M_H_CPU0_SB_DQS_DN<2>")
	)
	(segment
		(start 412.15056 -210.518502)
		(end 411.089856 -210.518502)
		(width 0.18288)
		(layer "In6.Cu")
		(net "M_H_CPU0_SB_DQS_DN<2>")
	)
	(segment
		(start 430.89449 -210.083908)
		(end 427.698154 -210.083908)
		(width 0.18288)
		(layer "In6.Cu")
		(net "M_H_CPU0_SB_DQS_DN<2>")
	)
	(segment
		(start 387.190742 -227.473002)
		(end 387.131052 -227.532692)
		(width 0.088646)
		(layer "In6.Cu")
		(net "M_H_CPU0_SB_DQS_DN<2>")
	)
	(segment
		(start 419.58641 -212.469222)
		(end 417.764214 -210.647026)
		(width 0.18288)
		(layer "In6.Cu")
		(net "M_H_CPU0_SB_DQS_DN<2>")
	)
	(segment
		(start 450.911214 -209.216752)
		(end 450.65442 -209.473546)
		(width 0.18288)
		(layer "In6.Cu")
		(net "M_H_CPU0_SB_DQS_DN<2>")
	)
	(segment
		(start 449.922138 -209.138012)
		(end 447.260726 -209.138012)
		(width 0.18288)
		(layer "In6.Cu")
		(net "M_H_CPU0_SB_DQS_DN<2>")
	)
	(segment
		(start 388.332726 -227.473002)
		(end 387.190742 -227.473002)
		(width 0.18288)
		(layer "In6.Cu")
		(net "M_H_CPU0_SB_DQS_DN<2>")
	)
	(segment
		(start 374.898158 -230.410258)
		(end 374.890792 -230.40594)
		(width 0.088646)
		(layer "In6.Cu")
		(net "M_H_CPU0_SB_DQS_DN<2>")
	)
	(segment
		(start 374.899682 -230.41102)
		(end 374.898158 -230.410258)
		(width 0.088646)
		(layer "In6.Cu")
		(net "M_H_CPU0_SB_DQS_DN<2>")
	)
	(segment
		(start 436.001668 -210.492594)
		(end 435.644544 -210.492594)
		(width 0.18288)
		(layer "In6.Cu")
		(net "M_H_CPU0_SB_DQS_DN<2>")
	)
	(segment
		(start 424.66006 -211.342732)
		(end 424.391582 -211.61121)
		(width 0.18288)
		(layer "In6.Cu")
		(net "M_H_CPU0_SB_DQS_DN<2>")
	)
	(segment
		(start 375.839482 -230.41102)
		(end 375.82475 -230.402384)
		(width 0.088646)
		(layer "In6.Cu")
		(net "M_H_CPU0_SB_DQS_DN<2>")
	)
	(segment
		(start 415.637472 -209.882232)
		(end 412.78683 -209.882232)
		(width 0.18288)
		(layer "In6.Cu")
		(net "M_H_CPU0_SB_DQS_DN<2>")
	)
	(segment
		(start 425.009564 -211.342732)
		(end 424.66006 -211.342732)
		(width 0.18288)
		(layer "In6.Cu")
		(net "M_H_CPU0_SB_DQS_DN<2>")
	)
	(segment
		(start 450.257672 -209.473546)
		(end 449.922138 -209.138012)
		(width 0.18288)
		(layer "In6.Cu")
		(net "M_H_CPU0_SB_DQS_DN<2>")
	)
	(segment
		(start 420.562024 -212.19287)
		(end 420.285672 -212.469222)
		(width 0.18288)
		(layer "In6.Cu")
		(net "M_H_CPU0_SB_DQS_DN<2>")
	)
	(segment
		(start 410.965396 -210.394042)
		(end 410.419296 -210.394042)
		(width 0.18288)
		(layer "In6.Cu")
		(net "M_H_CPU0_SB_DQS_DN<2>")
	)
	(segment
		(start 385.623562 -229.521258)
		(end 385.424934 -229.521258)
		(width 0.088646)
		(layer "In6.Cu")
		(net "M_H_CPU0_SB_DQS_DN<2>")
	)
	(segment
		(start 377.719082 -230.41102)
		(end 377.70435 -230.402384)
		(width 0.088646)
		(layer "In6.Cu")
		(net "M_H_CPU0_SB_DQS_DN<2>")
	)
	(segment
		(start 407.201878 -209.864706)
		(end 406.655778 -209.864706)
		(width 0.18288)
		(layer "In6.Cu")
		(net "M_H_CPU0_SB_DQS_DN<2>")
	)
	(segment
		(start 410.419296 -210.394042)
		(end 410.294836 -210.518502)
		(width 0.18288)
		(layer "In6.Cu")
		(net "M_H_CPU0_SB_DQS_DN<2>")
	)
	(segment
		(start 386.112512 -229.032308)
		(end 385.623562 -229.521258)
		(width 0.088646)
		(layer "In6.Cu")
		(net "M_H_CPU0_SB_DQS_DN<2>")
	)
	(segment
		(start 441.460128 -209.150966)
		(end 440.690508 -209.920586)
		(width 0.18288)
		(layer "In6.Cu")
		(net "M_H_CPU0_SB_DQS_DN<2>")
	)
	(segment
		(start 378.102368 -230.40594)
		(end 378.093478 -230.41102)
		(width 0.088646)
		(layer "In6.Cu")
		(net "M_H_CPU0_SB_DQS_DN<2>")
	)
	(segment
		(start 406.531318 -209.989166)
		(end 405.534622 -209.989166)
		(width 0.18288)
		(layer "In6.Cu")
		(net "M_H_CPU0_SB_DQS_DN<2>")
	)
	(segment
		(start 427.259496 -210.522566)
		(end 426.564044 -210.522566)
		(width 0.18288)
		(layer "In6.Cu")
		(net "M_H_CPU0_SB_DQS_DN<2>")
	)
	(segment
		(start 440.09818 -209.642456)
		(end 439.750708 -209.642456)
		(width 0.18288)
		(layer "In6.Cu")
		(net "M_H_CPU0_SB_DQS_DN<2>")
	)
	(segment
		(start 421.609774 -212.471)
		(end 421.188134 -212.471)
		(width 0.18288)
		(layer "In6.Cu")
		(net "M_H_CPU0_SB_DQS_DN<2>")
	)
	(segment
		(start 447.260726 -209.138012)
		(end 445.561466 -209.841846)
		(width 0.18288)
		(layer "In6.Cu")
		(net "M_H_CPU0_SB_DQS_DN<2>")
	)
	(segment
		(start 435.644544 -210.492594)
		(end 435.37505 -210.762088)
		(width 0.18288)
		(layer "In6.Cu")
		(net "M_H_CPU0_SB_DQS_DN<2>")
	)
	(segment
		(start 387.131052 -227.532692)
		(end 386.924042 -227.532692)
		(width 0.088646)
		(layer "In6.Cu")
		(net "M_H_CPU0_SB_DQS_DN<2>")
	)
	(segment
		(start 374.773952 -230.086662)
		(end 375.08688 -230.086662)
		(width 0.088646)
		(layer "In6.Cu")
		(net "M_H_CPU0_SB_DQS_DN<2>")
	)
	(segment
		(start 445.561466 -209.841846)
		(end 443.73419 -209.841846)
		(width 0.18288)
		(layer "In6.Cu")
		(net "M_H_CPU0_SB_DQS_DN<2>")
	)
	(segment
		(start 386.112512 -228.344222)
		(end 386.112512 -229.032308)
		(width 0.088646)
		(layer "In6.Cu")
		(net "M_H_CPU0_SB_DQS_DN<2>")
	)
	(segment
		(start 439.750708 -209.642456)
		(end 439.472578 -209.920586)
		(width 0.18288)
		(layer "In6.Cu")
		(net "M_H_CPU0_SB_DQS_DN<2>")
	)
	(segment
		(start 436.696358 -210.770724)
		(end 436.279798 -210.770724)
		(width 0.18288)
		(layer "In6.Cu")
		(net "M_H_CPU0_SB_DQS_DN<2>")
	)
	(segment
		(start 443.73419 -209.841846)
		(end 442.066172 -209.150966)
		(width 0.18288)
		(layer "In6.Cu")
		(net "M_H_CPU0_SB_DQS_DN<2>")
	)
	(segment
		(start 405.534622 -209.989166)
		(end 403.909276 -211.614512)
		(width 0.18288)
		(layer "In6.Cu")
		(net "M_H_CPU0_SB_DQS_DN<2>")
	)
	(segment
		(start 386.924042 -227.532692)
		(end 386.112512 -228.344222)
		(width 0.088646)
		(layer "In6.Cu")
		(net "M_H_CPU0_SB_DQS_DN<2>")
	)
	(segment
		(start 422.469564 -211.61121)
		(end 421.609774 -212.471)
		(width 0.18288)
		(layer "In6.Cu")
		(net "M_H_CPU0_SB_DQS_DN<2>")
	)
	(segment
		(start 412.78683 -209.882232)
		(end 412.15056 -210.518502)
		(width 0.18288)
		(layer "In6.Cu")
		(net "M_H_CPU0_SB_DQS_DN<2>")
	)
	(segment
		(start 408.231848 -209.989166)
		(end 407.326338 -209.989166)
		(width 0.18288)
		(layer "In6.Cu")
		(net "M_H_CPU0_SB_DQS_DN<2>")
	)
	(segment
		(start 439.472578 -209.920586)
		(end 437.546496 -209.920586)
		(width 0.18288)
		(layer "In6.Cu")
		(net "M_H_CPU0_SB_DQS_DN<2>")
	)
	(segment
		(start 403.909276 -211.896452)
		(end 388.332726 -227.473002)
		(width 0.18288)
		(layer "In6.Cu")
		(net "M_H_CPU0_SB_DQS_DN<2>")
	)
	(segment
		(start 427.698154 -210.083908)
		(end 427.259496 -210.522566)
		(width 0.18288)
		(layer "In6.Cu")
		(net "M_H_CPU0_SB_DQS_DN<2>")
	)
	(segment
		(start 440.37631 -209.920586)
		(end 440.09818 -209.642456)
		(width 0.18288)
		(layer "In6.Cu")
		(net "M_H_CPU0_SB_DQS_DN<2>")
	)
	(segment
		(start 417.764214 -210.647026)
		(end 416.402266 -210.647026)
		(width 0.18288)
		(layer "In6.Cu")
		(net "M_H_CPU0_SB_DQS_DN<2>")
	)
	(segment
		(start 378.563632 -229.597204)
		(end 378.56287 -229.597712)
		(width 0.088646)
		(layer "In6.Cu")
		(net "M_H_CPU0_SB_DQS_DN<2>")
	)
	(segment
		(start 380.457964 -229.588568)
		(end 380.443232 -229.597204)
		(width 0.088646)
		(layer "In6.Cu")
		(net "M_H_CPU0_SB_DQS_DN<2>")
	)
	(segment
		(start 376.779282 -230.41102)
		(end 376.76455 -230.402384)
		(width 0.088646)
		(layer "In6.Cu")
		(net "M_H_CPU0_SB_DQS_DN<2>")
	)
	(segment
		(start 437.546496 -209.920586)
		(end 436.696358 -210.770724)
		(width 0.18288)
		(layer "In6.Cu")
		(net "M_H_CPU0_SB_DQS_DN<2>")
	)
	(segment
		(start 411.089856 -210.518502)
		(end 410.965396 -210.394042)
		(width 0.18288)
		(layer "In6.Cu")
		(net "M_H_CPU0_SB_DQS_DN<2>")
	)
	(segment
		(start 425.271946 -211.605114)
		(end 425.009564 -211.342732)
		(width 0.18288)
		(layer "In6.Cu")
		(net "M_H_CPU0_SB_DQS_DN<2>")
	)
	(segment
		(start 435.37505 -210.762088)
		(end 432.532028 -210.762088)
		(width 0.18288)
		(layer "In6.Cu")
		(net "M_H_CPU0_SB_DQS_DN<2>")
	)
	(segment
		(start 442.066172 -209.150966)
		(end 441.460128 -209.150966)
		(width 0.18288)
		(layer "In6.Cu")
		(net "M_H_CPU0_SB_DQS_DN<2>")
	)
	(segment
		(start 416.402266 -210.647026)
		(end 415.637472 -209.882232)
		(width 0.18288)
		(layer "In6.Cu")
		(net "M_H_CPU0_SB_DQS_DN<2>")
	)
	(segment
		(start 440.690508 -209.920586)
		(end 440.37631 -209.920586)
		(width 0.18288)
		(layer "In6.Cu")
		(net "M_H_CPU0_SB_DQS_DN<2>")
	)
	(segment
		(start 403.909276 -211.614512)
		(end 403.909276 -211.896452)
		(width 0.18288)
		(layer "In6.Cu")
		(net "M_H_CPU0_SB_DQS_DN<2>")
	)
	(segment
		(start 436.279798 -210.770724)
		(end 436.001668 -210.492594)
		(width 0.18288)
		(layer "In6.Cu")
		(net "M_H_CPU0_SB_DQS_DN<2>")
	)
	(segment
		(start 407.326338 -209.989166)
		(end 407.201878 -209.864706)
		(width 0.18288)
		(layer "In6.Cu")
		(net "M_H_CPU0_SB_DQS_DN<2>")
	)
	(segment
		(start 378.578364 -229.588568)
		(end 378.563632 -229.597204)
		(width 0.088646)
		(layer "In6.Cu")
		(net "M_H_CPU0_SB_DQS_DN<2>")
	)
	(segment
		(start 426.564044 -210.522566)
		(end 425.481496 -211.605114)
		(width 0.18288)
		(layer "In6.Cu")
		(net "M_H_CPU0_SB_DQS_DN<2>")
	)
	(segment
		(start 374.716802 -230.143812)
		(end 374.773952 -230.086662)
		(width 0.088646)
		(layer "In6.Cu")
		(net "M_H_CPU0_SB_DQS_DN<2>")
	)
	(arc
		(start 385.424934 -229.521258)
		(mid 385.400401 -229.521746)
		(end 385.375912 -229.52329)
		(width 0.088646)
		(layer "In6.Cu")
		(net "M_H_CPU0_SB_DQS_DN<2>")
	)
	(arc
		(start 380.068836 -229.597204)
		(mid 379.786134 -229.521428)
		(end 379.503432 -229.597204)
		(width 0.088646)
		(layer "In6.Cu")
		(net "M_H_CPU0_SB_DQS_DN<2>")
	)
	(arc
		(start 375.82475 -230.402384)
		(mid 375.548275 -230.335064)
		(end 375.274078 -230.41102)
		(width 0.088646)
		(layer "In6.Cu")
		(net "M_H_CPU0_SB_DQS_DN<2>")
	)
	(arc
		(start 381.948436 -229.597204)
		(mid 381.665734 -229.521428)
		(end 381.383032 -229.597204)
		(width 0.088646)
		(layer "In6.Cu")
		(net "M_H_CPU0_SB_DQS_DN<2>")
	)
	(arc
		(start 381.008636 -229.597204)
		(mid 380.734437 -229.521369)
		(end 380.457964 -229.588568)
		(width 0.088646)
		(layer "In6.Cu")
		(net "M_H_CPU0_SB_DQS_DN<2>")
	)
	(arc
		(start 382.322832 -229.597204)
		(mid 382.135634 -229.647347)
		(end 381.948436 -229.597204)
		(width 0.088646)
		(layer "In6.Cu")
		(net "M_H_CPU0_SB_DQS_DN<2>")
	)
	(arc
		(start 379.503432 -229.597204)
		(mid 379.316234 -229.647347)
		(end 379.129036 -229.597204)
		(width 0.088646)
		(layer "In6.Cu")
		(net "M_H_CPU0_SB_DQS_DN<2>")
	)
	(arc
		(start 385.142232 -229.597204)
		(mid 384.955034 -229.647347)
		(end 384.767836 -229.597204)
		(width 0.088646)
		(layer "In6.Cu")
		(net "M_H_CPU0_SB_DQS_DN<2>")
	)
	(arc
		(start 375.274078 -230.41102)
		(mid 375.08688 -230.461163)
		(end 374.899682 -230.41102)
		(width 0.088646)
		(layer "In6.Cu")
		(net "M_H_CPU0_SB_DQS_DN<2>")
	)
	(arc
		(start 378.28093 -230.086662)
		(mid 378.233251 -230.269562)
		(end 378.102368 -230.40594)
		(width 0.088646)
		(layer "In6.Cu")
		(net "M_H_CPU0_SB_DQS_DN<2>")
	)
	(arc
		(start 376.76455 -230.402384)
		(mid 376.488075 -230.335064)
		(end 376.213878 -230.41102)
		(width 0.088646)
		(layer "In6.Cu")
		(net "M_H_CPU0_SB_DQS_DN<2>")
	)
	(arc
		(start 384.202432 -229.597204)
		(mid 384.015234 -229.647347)
		(end 383.828036 -229.597204)
		(width 0.088646)
		(layer "In6.Cu")
		(net "M_H_CPU0_SB_DQS_DN<2>")
	)
	(arc
		(start 380.443232 -229.597204)
		(mid 380.256034 -229.647347)
		(end 380.068836 -229.597204)
		(width 0.088646)
		(layer "In6.Cu")
		(net "M_H_CPU0_SB_DQS_DN<2>")
	)
	(arc
		(start 385.375912 -229.52329)
		(mid 385.255008 -229.547409)
		(end 385.142232 -229.597204)
		(width 0.088646)
		(layer "In6.Cu")
		(net "M_H_CPU0_SB_DQS_DN<2>")
	)
	(arc
		(start 377.153678 -230.41102)
		(mid 376.96648 -230.461163)
		(end 376.779282 -230.41102)
		(width 0.088646)
		(layer "In6.Cu")
		(net "M_H_CPU0_SB_DQS_DN<2>")
	)
	(arc
		(start 378.557536 -229.60076)
		(mid 378.354949 -229.807111)
		(end 378.28093 -230.086662)
		(width 0.088646)
		(layer "In6.Cu")
		(net "M_H_CPU0_SB_DQS_DN<2>")
	)
	(arc
		(start 383.262632 -229.597204)
		(mid 383.075434 -229.647347)
		(end 382.888236 -229.597204)
		(width 0.088646)
		(layer "In6.Cu")
		(net "M_H_CPU0_SB_DQS_DN<2>")
	)
	(arc
		(start 379.129036 -229.597204)
		(mid 378.854837 -229.521369)
		(end 378.578364 -229.588568)
		(width 0.088646)
		(layer "In6.Cu")
		(net "M_H_CPU0_SB_DQS_DN<2>")
	)
	(arc
		(start 384.767836 -229.597204)
		(mid 384.485134 -229.521428)
		(end 384.202432 -229.597204)
		(width 0.088646)
		(layer "In6.Cu")
		(net "M_H_CPU0_SB_DQS_DN<2>")
	)
	(arc
		(start 383.828036 -229.597204)
		(mid 383.545334 -229.521428)
		(end 383.262632 -229.597204)
		(width 0.088646)
		(layer "In6.Cu")
		(net "M_H_CPU0_SB_DQS_DN<2>")
	)
	(arc
		(start 381.383032 -229.597204)
		(mid 381.195834 -229.647347)
		(end 381.008636 -229.597204)
		(width 0.088646)
		(layer "In6.Cu")
		(net "M_H_CPU0_SB_DQS_DN<2>")
	)
	(arc
		(start 378.093478 -230.41102)
		(mid 377.90628 -230.461163)
		(end 377.719082 -230.41102)
		(width 0.088646)
		(layer "In6.Cu")
		(net "M_H_CPU0_SB_DQS_DN<2>")
	)
	(arc
		(start 374.890792 -230.40594)
		(mid 374.774983 -230.294011)
		(end 374.716802 -230.143812)
		(width 0.088646)
		(layer "In6.Cu")
		(net "M_H_CPU0_SB_DQS_DN<2>")
	)
	(arc
		(start 382.888236 -229.597204)
		(mid 382.605534 -229.521428)
		(end 382.322832 -229.597204)
		(width 0.088646)
		(layer "In6.Cu")
		(net "M_H_CPU0_SB_DQS_DN<2>")
	)
	(arc
		(start 377.70435 -230.402384)
		(mid 377.427875 -230.335064)
		(end 377.153678 -230.41102)
		(width 0.088646)
		(layer "In6.Cu")
		(net "M_H_CPU0_SB_DQS_DN<2>")
	)
	(arc
		(start 376.213878 -230.41102)
		(mid 376.02668 -230.461163)
		(end 375.839482 -230.41102)
		(width 0.088646)
		(layer "In6.Cu")
		(net "M_H_CPU0_SB_DQS_DN<2>")
	)
	(segment
		(start 452.564754 -218.566746)
		(end 452.016114 -218.566746)
		(width 0.20066)
		(layer "F.Cu")
		(net "M_H_CPU0_SB_DQS_DN<1>")
	)
	(segment
		(start 458.39761 -218.807284)
		(end 457.987146 -219.217748)
		(width 0.20066)
		(layer "F.Cu")
		(net "M_H_CPU0_SB_DQS_DN<1>")
	)
	(segment
		(start 453.996806 -219.26296)
		(end 453.582278 -218.848432)
		(width 0.20066)
		(layer "F.Cu")
		(net "M_H_CPU0_SB_DQS_DN<1>")
	)
	(segment
		(start 457.12126 -218.991688)
		(end 454.941686 -218.991688)
		(width 0.1016)
		(layer "F.Cu")
		(net "M_H_CPU0_SB_DQS_DN<1>")
	)
	(segment
		(start 454.789794 -218.991688)
		(end 454.518522 -219.26296)
		(width 0.20066)
		(layer "F.Cu")
		(net "M_H_CPU0_SB_DQS_DN<1>")
	)
	(segment
		(start 454.941686 -218.991688)
		(end 454.937368 -218.991688)
		(width 0.101854)
		(layer "F.Cu")
		(net "M_H_CPU0_SB_DQS_DN<1>")
	)
	(segment
		(start 458.970634 -218.566746)
		(end 458.730096 -218.807284)
		(width 0.20066)
		(layer "F.Cu")
		(net "M_H_CPU0_SB_DQS_DN<1>")
	)
	(segment
		(start 450.911214 -218.566746)
		(end 452.016114 -218.566746)
		(width 0.20066)
		(layer "F.Cu")
		(net "M_H_CPU0_SB_DQS_DN<1>")
	)
	(segment
		(start 453.582278 -218.848432)
		(end 452.84644 -218.848432)
		(width 0.20066)
		(layer "F.Cu")
		(net "M_H_CPU0_SB_DQS_DN<1>")
	)
	(segment
		(start 452.84644 -218.848432)
		(end 452.564754 -218.566746)
		(width 0.20066)
		(layer "F.Cu")
		(net "M_H_CPU0_SB_DQS_DN<1>")
	)
	(segment
		(start 457.450698 -218.986354)
		(end 457.126594 -218.986354)
		(width 0.20066)
		(layer "F.Cu")
		(net "M_H_CPU0_SB_DQS_DN<1>")
	)
	(segment
		(start 454.518522 -219.26296)
		(end 453.996806 -219.26296)
		(width 0.20066)
		(layer "F.Cu")
		(net "M_H_CPU0_SB_DQS_DN<1>")
	)
	(segment
		(start 371.79758 -233.064304)
		(end 371.79758 -232.528618)
		(width 0.20066)
		(layer "F.Cu")
		(net "M_H_CPU0_SB_DQS_DN<1>")
	)
	(segment
		(start 459.559914 -218.566746)
		(end 458.970634 -218.566746)
		(width 0.20066)
		(layer "F.Cu")
		(net "M_H_CPU0_SB_DQS_DN<1>")
	)
	(segment
		(start 457.126594 -218.986354)
		(end 457.12126 -218.991688)
		(width 0.1016)
		(layer "F.Cu")
		(net "M_H_CPU0_SB_DQS_DN<1>")
	)
	(segment
		(start 457.682092 -219.217748)
		(end 457.450698 -218.986354)
		(width 0.20066)
		(layer "F.Cu")
		(net "M_H_CPU0_SB_DQS_DN<1>")
	)
	(segment
		(start 371.79758 -232.528618)
		(end 371.797834 -232.528364)
		(width 0.20066)
		(layer "F.Cu")
		(net "M_H_CPU0_SB_DQS_DN<1>")
	)
	(segment
		(start 454.937368 -218.991688)
		(end 454.789794 -218.991688)
		(width 0.20066)
		(layer "F.Cu")
		(net "M_H_CPU0_SB_DQS_DN<1>")
	)
	(segment
		(start 457.987146 -219.217748)
		(end 457.682092 -219.217748)
		(width 0.20066)
		(layer "F.Cu")
		(net "M_H_CPU0_SB_DQS_DN<1>")
	)
	(segment
		(start 458.730096 -218.807284)
		(end 458.39761 -218.807284)
		(width 0.20066)
		(layer "F.Cu")
		(net "M_H_CPU0_SB_DQS_DN<1>")
	)
	(segment
		(start 437.972708 -213.313772)
		(end 437.125364 -212.466428)
		(width 0.18288)
		(layer "In11.Cu")
		(net "M_H_CPU0_SB_DQS_DN<1>")
	)
	(segment
		(start 445.351408 -216.523824)
		(end 443.86119 -215.033606)
		(width 0.18288)
		(layer "In11.Cu")
		(net "M_H_CPU0_SB_DQS_DN<1>")
	)
	(segment
		(start 375.758964 -232.844086)
		(end 375.744232 -232.852722)
		(width 0.088646)
		(layer "In11.Cu")
		(net "M_H_CPU0_SB_DQS_DN<1>")
	)
	(segment
		(start 406.138126 -213.280498)
		(end 405.942038 -213.476586)
		(width 0.18288)
		(layer "In11.Cu")
		(net "M_H_CPU0_SB_DQS_DN<1>")
	)
	(segment
		(start 372.556024 -232.856024)
		(end 372.54434 -232.84942)
		(width 0.088646)
		(layer "In11.Cu")
		(net "M_H_CPU0_SB_DQS_DN<1>")
	)
	(segment
		(start 405.296116 -213.476586)
		(end 402.817838 -215.954864)
		(width 0.18288)
		(layer "In11.Cu")
		(net "M_H_CPU0_SB_DQS_DN<1>")
	)
	(segment
		(start 435.263036 -212.483446)
		(end 432.273202 -212.483446)
		(width 0.18288)
		(layer "In11.Cu")
		(net "M_H_CPU0_SB_DQS_DN<1>")
	)
	(segment
		(start 381.948436 -232.852722)
		(end 381.938022 -232.846626)
		(width 0.088646)
		(layer "In11.Cu")
		(net "M_H_CPU0_SB_DQS_DN<1>")
	)
	(segment
		(start 374.429782 -232.852722)
		(end 374.435624 -232.856024)
		(width 0.088646)
		(layer "In11.Cu")
		(net "M_H_CPU0_SB_DQS_DN<1>")
	)
	(segment
		(start 407.471626 -213.077806)
		(end 407.092912 -212.699092)
		(width 0.18288)
		(layer "In11.Cu")
		(net "M_H_CPU0_SB_DQS_DN<1>")
	)
	(segment
		(start 409.201366 -213.901528)
		(end 408.776424 -213.476586)
		(width 0.18288)
		(layer "In11.Cu")
		(net "M_H_CPU0_SB_DQS_DN<1>")
	)
	(segment
		(start 407.471626 -213.280498)
		(end 407.471626 -213.077806)
		(width 0.18288)
		(layer "In11.Cu")
		(net "M_H_CPU0_SB_DQS_DN<1>")
	)
	(segment
		(start 374.814592 -232.846626)
		(end 374.804178 -232.852722)
		(width 0.088646)
		(layer "In11.Cu")
		(net "M_H_CPU0_SB_DQS_DN<1>")
	)
	(segment
		(start 385.70789 -232.852976)
		(end 385.707636 -232.852722)
		(width 0.088646)
		(layer "In11.Cu")
		(net "M_H_CPU0_SB_DQS_DN<1>")
	)
	(segment
		(start 420.180008 -214.178896)
		(end 419.075616 -214.178896)
		(width 0.18288)
		(layer "In11.Cu")
		(net "M_H_CPU0_SB_DQS_DN<1>")
	)
	(segment
		(start 418.278056 -214.178896)
		(end 417.729416 -214.178896)
		(width 0.18288)
		(layer "In11.Cu")
		(net "M_H_CPU0_SB_DQS_DN<1>")
	)
	(segment
		(start 437.125364 -212.466428)
		(end 436.295038 -212.466428)
		(width 0.18288)
		(layer "In11.Cu")
		(net "M_H_CPU0_SB_DQS_DN<1>")
	)
	(segment
		(start 425.772072 -213.30031)
		(end 425.307506 -213.30031)
		(width 0.18288)
		(layer "In11.Cu")
		(net "M_H_CPU0_SB_DQS_DN<1>")
	)
	(segment
		(start 420.92753 -213.891114)
		(end 420.46779 -213.891114)
		(width 0.18288)
		(layer "In11.Cu")
		(net "M_H_CPU0_SB_DQS_DN<1>")
	)
	(segment
		(start 435.55539 -212.191092)
		(end 435.263036 -212.483446)
		(width 0.18288)
		(layer "In11.Cu")
		(net "M_H_CPU0_SB_DQS_DN<1>")
	)
	(segment
		(start 407.092912 -212.699092)
		(end 406.51684 -212.699092)
		(width 0.18288)
		(layer "In11.Cu")
		(net "M_H_CPU0_SB_DQS_DN<1>")
	)
	(segment
		(start 388.020306 -231.120442)
		(end 387.880098 -231.120442)
		(width 0.088646)
		(layer "In11.Cu")
		(net "M_H_CPU0_SB_DQS_DN<1>")
	)
	(segment
		(start 448.35572 -218.375484)
		(end 446.50406 -216.523824)
		(width 0.18288)
		(layer "In11.Cu")
		(net "M_H_CPU0_SB_DQS_DN<1>")
	)
	(segment
		(start 378.578364 -232.844086)
		(end 378.563632 -232.852722)
		(width 0.088646)
		(layer "In11.Cu")
		(net "M_H_CPU0_SB_DQS_DN<1>")
	)
	(segment
		(start 449.817998 -218.375484)
		(end 448.35572 -218.375484)
		(width 0.18288)
		(layer "In11.Cu")
		(net "M_H_CPU0_SB_DQS_DN<1>")
	)
	(segment
		(start 439.641234 -213.04123)
		(end 439.368692 -213.313772)
		(width 0.18288)
		(layer "In11.Cu")
		(net "M_H_CPU0_SB_DQS_DN<1>")
	)
	(segment
		(start 408.776424 -213.476586)
		(end 407.667714 -213.476586)
		(width 0.18288)
		(layer "In11.Cu")
		(net "M_H_CPU0_SB_DQS_DN<1>")
	)
	(segment
		(start 406.51684 -212.699092)
		(end 406.138126 -213.077806)
		(width 0.18288)
		(layer "In11.Cu")
		(net "M_H_CPU0_SB_DQS_DN<1>")
	)
	(segment
		(start 450.60616 -218.8718)
		(end 450.314314 -218.8718)
		(width 0.18288)
		(layer "In11.Cu")
		(net "M_H_CPU0_SB_DQS_DN<1>")
	)
	(segment
		(start 424.28414 -213.324948)
		(end 422.510458 -213.324948)
		(width 0.18288)
		(layer "In11.Cu")
		(net "M_H_CPU0_SB_DQS_DN<1>")
	)
	(segment
		(start 371.792246 -232.522776)
		(end 371.797834 -232.528364)
		(width 0.088646)
		(layer "In11.Cu")
		(net "M_H_CPU0_SB_DQS_DN<1>")
	)
	(segment
		(start 388.079996 -231.060752)
		(end 388.020306 -231.120442)
		(width 0.088646)
		(layer "In11.Cu")
		(net "M_H_CPU0_SB_DQS_DN<1>")
	)
	(segment
		(start 419.075616 -214.178896)
		(end 418.951156 -214.054436)
		(width 0.18288)
		(layer "In11.Cu")
		(net "M_H_CPU0_SB_DQS_DN<1>")
	)
	(segment
		(start 446.50406 -216.523824)
		(end 445.351408 -216.523824)
		(width 0.18288)
		(layer "In11.Cu")
		(net "M_H_CPU0_SB_DQS_DN<1>")
	)
	(segment
		(start 441.85459 -214.116666)
		(end 441.05449 -213.316566)
		(width 0.18288)
		(layer "In11.Cu")
		(net "M_H_CPU0_SB_DQS_DN<1>")
	)
	(segment
		(start 420.46779 -213.891114)
		(end 420.180008 -214.178896)
		(width 0.18288)
		(layer "In11.Cu")
		(net "M_H_CPU0_SB_DQS_DN<1>")
	)
	(segment
		(start 412.392622 -213.901528)
		(end 409.201366 -213.901528)
		(width 0.18288)
		(layer "In11.Cu")
		(net "M_H_CPU0_SB_DQS_DN<1>")
	)
	(segment
		(start 412.804864 -213.489286)
		(end 412.392622 -213.901528)
		(width 0.18288)
		(layer "In11.Cu")
		(net "M_H_CPU0_SB_DQS_DN<1>")
	)
	(segment
		(start 371.490494 -232.522776)
		(end 371.792246 -232.522776)
		(width 0.088646)
		(layer "In11.Cu")
		(net "M_H_CPU0_SB_DQS_DN<1>")
	)
	(segment
		(start 387.6802 -231.793034)
		(end 387.62178 -231.933242)
		(width 0.088646)
		(layer "In11.Cu")
		(net "M_H_CPU0_SB_DQS_DN<1>")
	)
	(segment
		(start 424.567858 -213.04123)
		(end 424.28414 -213.324948)
		(width 0.18288)
		(layer "In11.Cu")
		(net "M_H_CPU0_SB_DQS_DN<1>")
	)
	(segment
		(start 395.459966 -224.8662)
		(end 395.459966 -225.78568)
		(width 0.18288)
		(layer "In11.Cu")
		(net "M_H_CPU0_SB_DQS_DN<1>")
	)
	(segment
		(start 422.510458 -213.324948)
		(end 421.660066 -214.17534)
		(width 0.18288)
		(layer "In11.Cu")
		(net "M_H_CPU0_SB_DQS_DN<1>")
	)
	(segment
		(start 387.6802 -231.32034)
		(end 387.6802 -231.793034)
		(width 0.088646)
		(layer "In11.Cu")
		(net "M_H_CPU0_SB_DQS_DN<1>")
	)
	(segment
		(start 395.459966 -225.78568)
		(end 390.184894 -231.060752)
		(width 0.18288)
		(layer "In11.Cu")
		(net "M_H_CPU0_SB_DQS_DN<1>")
	)
	(segment
		(start 387.62178 -231.933242)
		(end 387.517894 -232.037128)
		(width 0.088646)
		(layer "In11.Cu")
		(net "M_H_CPU0_SB_DQS_DN<1>")
	)
	(segment
		(start 441.05449 -213.316566)
		(end 440.406282 -213.316566)
		(width 0.18288)
		(layer "In11.Cu")
		(net "M_H_CPU0_SB_DQS_DN<1>")
	)
	(segment
		(start 421.660066 -214.17534)
		(end 421.211756 -214.17534)
		(width 0.18288)
		(layer "In11.Cu")
		(net "M_H_CPU0_SB_DQS_DN<1>")
	)
	(segment
		(start 427.90364 -211.671154)
		(end 427.048422 -212.526372)
		(width 0.18288)
		(layer "In11.Cu")
		(net "M_H_CPU0_SB_DQS_DN<1>")
	)
	(segment
		(start 427.048422 -212.526372)
		(end 426.54601 -212.526372)
		(width 0.18288)
		(layer "In11.Cu")
		(net "M_H_CPU0_SB_DQS_DN<1>")
	)
	(segment
		(start 426.54601 -212.526372)
		(end 425.772072 -213.30031)
		(width 0.18288)
		(layer "In11.Cu")
		(net "M_H_CPU0_SB_DQS_DN<1>")
	)
	(segment
		(start 376.698764 -232.844086)
		(end 376.684032 -232.852722)
		(width 0.088646)
		(layer "In11.Cu")
		(net "M_H_CPU0_SB_DQS_DN<1>")
	)
	(segment
		(start 450.911214 -218.566746)
		(end 450.60616 -218.8718)
		(width 0.18288)
		(layer "In11.Cu")
		(net "M_H_CPU0_SB_DQS_DN<1>")
	)
	(segment
		(start 387.517894 -232.037128)
		(end 386.99313 -232.254552)
		(width 0.088646)
		(layer "In11.Cu")
		(net "M_H_CPU0_SB_DQS_DN<1>")
	)
	(segment
		(start 425.307506 -213.30031)
		(end 425.048426 -213.04123)
		(width 0.18288)
		(layer "In11.Cu")
		(net "M_H_CPU0_SB_DQS_DN<1>")
	)
	(segment
		(start 440.406282 -213.316566)
		(end 440.130946 -213.04123)
		(width 0.18288)
		(layer "In11.Cu")
		(net "M_H_CPU0_SB_DQS_DN<1>")
	)
	(segment
		(start 406.138126 -213.077806)
		(end 406.138126 -213.280498)
		(width 0.18288)
		(layer "In11.Cu")
		(net "M_H_CPU0_SB_DQS_DN<1>")
	)
	(segment
		(start 417.729416 -214.178896)
		(end 416.064446 -213.489286)
		(width 0.18288)
		(layer "In11.Cu")
		(net "M_H_CPU0_SB_DQS_DN<1>")
	)
	(segment
		(start 431.46091 -211.671154)
		(end 427.90364 -211.671154)
		(width 0.18288)
		(layer "In11.Cu")
		(net "M_H_CPU0_SB_DQS_DN<1>")
	)
	(segment
		(start 373.495824 -232.856024)
		(end 373.48414 -232.84942)
		(width 0.088646)
		(layer "In11.Cu")
		(net "M_H_CPU0_SB_DQS_DN<1>")
	)
	(segment
		(start 387.880098 -231.120442)
		(end 387.6802 -231.32034)
		(width 0.088646)
		(layer "In11.Cu")
		(net "M_H_CPU0_SB_DQS_DN<1>")
	)
	(segment
		(start 405.942038 -213.476586)
		(end 405.296116 -213.476586)
		(width 0.18288)
		(layer "In11.Cu")
		(net "M_H_CPU0_SB_DQS_DN<1>")
	)
	(segment
		(start 418.951156 -214.054436)
		(end 418.402516 -214.054436)
		(width 0.18288)
		(layer "In11.Cu")
		(net "M_H_CPU0_SB_DQS_DN<1>")
	)
	(segment
		(start 379.518164 -232.844086)
		(end 379.503432 -232.852722)
		(width 0.088646)
		(layer "In11.Cu")
		(net "M_H_CPU0_SB_DQS_DN<1>")
	)
	(segment
		(start 440.130946 -213.04123)
		(end 439.641234 -213.04123)
		(width 0.18288)
		(layer "In11.Cu")
		(net "M_H_CPU0_SB_DQS_DN<1>")
	)
	(segment
		(start 371.427502 -232.585768)
		(end 371.490494 -232.522776)
		(width 0.088646)
		(layer "In11.Cu")
		(net "M_H_CPU0_SB_DQS_DN<1>")
	)
	(segment
		(start 425.048426 -213.04123)
		(end 424.567858 -213.04123)
		(width 0.18288)
		(layer "In11.Cu")
		(net "M_H_CPU0_SB_DQS_DN<1>")
	)
	(segment
		(start 432.273202 -212.483446)
		(end 431.46091 -211.671154)
		(width 0.18288)
		(layer "In11.Cu")
		(net "M_H_CPU0_SB_DQS_DN<1>")
	)
	(segment
		(start 443.86119 -215.033606)
		(end 443.399926 -215.033606)
		(width 0.18288)
		(layer "In11.Cu")
		(net "M_H_CPU0_SB_DQS_DN<1>")
	)
	(segment
		(start 377.638564 -232.844086)
		(end 377.623832 -232.852722)
		(width 0.088646)
		(layer "In11.Cu")
		(net "M_H_CPU0_SB_DQS_DN<1>")
	)
	(segment
		(start 381.008382 -232.852722)
		(end 380.997968 -232.846626)
		(width 0.088646)
		(layer "In11.Cu")
		(net "M_H_CPU0_SB_DQS_DN<1>")
	)
	(segment
		(start 436.295038 -212.466428)
		(end 436.019702 -212.191092)
		(width 0.18288)
		(layer "In11.Cu")
		(net "M_H_CPU0_SB_DQS_DN<1>")
	)
	(segment
		(start 421.211756 -214.17534)
		(end 420.92753 -213.891114)
		(width 0.18288)
		(layer "In11.Cu")
		(net "M_H_CPU0_SB_DQS_DN<1>")
	)
	(segment
		(start 443.399926 -215.033606)
		(end 442.482986 -214.116666)
		(width 0.18288)
		(layer "In11.Cu")
		(net "M_H_CPU0_SB_DQS_DN<1>")
	)
	(segment
		(start 386.99313 -232.254552)
		(end 386.344414 -232.903522)
		(width 0.088646)
		(layer "In11.Cu")
		(net "M_H_CPU0_SB_DQS_DN<1>")
	)
	(segment
		(start 450.314314 -218.8718)
		(end 449.817998 -218.375484)
		(width 0.18288)
		(layer "In11.Cu")
		(net "M_H_CPU0_SB_DQS_DN<1>")
	)
	(segment
		(start 416.064446 -213.489286)
		(end 412.804864 -213.489286)
		(width 0.18288)
		(layer "In11.Cu")
		(net "M_H_CPU0_SB_DQS_DN<1>")
	)
	(segment
		(start 390.184894 -231.060752)
		(end 388.079996 -231.060752)
		(width 0.18288)
		(layer "In11.Cu")
		(net "M_H_CPU0_SB_DQS_DN<1>")
	)
	(segment
		(start 386.344414 -232.903522)
		(end 385.895088 -232.903522)
		(width 0.088646)
		(layer "In11.Cu")
		(net "M_H_CPU0_SB_DQS_DN<1>")
	)
	(segment
		(start 439.368692 -213.313772)
		(end 437.972708 -213.313772)
		(width 0.18288)
		(layer "In11.Cu")
		(net "M_H_CPU0_SB_DQS_DN<1>")
	)
	(segment
		(start 402.817838 -215.954864)
		(end 402.817838 -217.508328)
		(width 0.18288)
		(layer "In11.Cu")
		(net "M_H_CPU0_SB_DQS_DN<1>")
	)
	(segment
		(start 436.019702 -212.191092)
		(end 435.55539 -212.191092)
		(width 0.18288)
		(layer "In11.Cu")
		(net "M_H_CPU0_SB_DQS_DN<1>")
	)
	(segment
		(start 407.667714 -213.476586)
		(end 407.471626 -213.280498)
		(width 0.18288)
		(layer "In11.Cu")
		(net "M_H_CPU0_SB_DQS_DN<1>")
	)
	(segment
		(start 442.482986 -214.116666)
		(end 441.85459 -214.116666)
		(width 0.18288)
		(layer "In11.Cu")
		(net "M_H_CPU0_SB_DQS_DN<1>")
	)
	(segment
		(start 418.402516 -214.054436)
		(end 418.278056 -214.178896)
		(width 0.18288)
		(layer "In11.Cu")
		(net "M_H_CPU0_SB_DQS_DN<1>")
	)
	(segment
		(start 402.817838 -217.508328)
		(end 395.459966 -224.8662)
		(width 0.18288)
		(layer "In11.Cu")
		(net "M_H_CPU0_SB_DQS_DN<1>")
	)
	(arc
		(start 373.864632 -232.852722)
		(mid 373.680678 -232.902851)
		(end 373.495824 -232.856024)
		(width 0.088646)
		(layer "In11.Cu")
		(net "M_H_CPU0_SB_DQS_DN<1>")
	)
	(arc
		(start 374.435624 -232.856024)
		(mid 374.150579 -232.777018)
		(end 373.864632 -232.852722)
		(width 0.088646)
		(layer "In11.Cu")
		(net "M_H_CPU0_SB_DQS_DN<1>")
	)
	(arc
		(start 375.744232 -232.852722)
		(mid 375.557034 -232.902865)
		(end 375.369836 -232.852722)
		(width 0.088646)
		(layer "In11.Cu")
		(net "M_H_CPU0_SB_DQS_DN<1>")
	)
	(arc
		(start 382.888236 -232.852722)
		(mid 382.605534 -232.776946)
		(end 382.322832 -232.852722)
		(width 0.088646)
		(layer "In11.Cu")
		(net "M_H_CPU0_SB_DQS_DN<1>")
	)
	(arc
		(start 373.48414 -232.84942)
		(mid 373.204035 -232.776978)
		(end 372.924832 -232.852722)
		(width 0.088646)
		(layer "In11.Cu")
		(net "M_H_CPU0_SB_DQS_DN<1>")
	)
	(arc
		(start 378.563632 -232.852722)
		(mid 378.376434 -232.902865)
		(end 378.189236 -232.852722)
		(width 0.088646)
		(layer "In11.Cu")
		(net "M_H_CPU0_SB_DQS_DN<1>")
	)
	(arc
		(start 377.249436 -232.852722)
		(mid 376.975237 -232.776887)
		(end 376.698764 -232.844086)
		(width 0.088646)
		(layer "In11.Cu")
		(net "M_H_CPU0_SB_DQS_DN<1>")
	)
	(arc
		(start 371.985032 -232.852722)
		(mid 371.635831 -232.866274)
		(end 371.427502 -232.585768)
		(width 0.088646)
		(layer "In11.Cu")
		(net "M_H_CPU0_SB_DQS_DN<1>")
	)
	(arc
		(start 385.895088 -232.903522)
		(mid 385.79816 -232.890571)
		(end 385.70789 -232.852976)
		(width 0.088646)
		(layer "In11.Cu")
		(net "M_H_CPU0_SB_DQS_DN<1>")
	)
	(arc
		(start 385.142232 -232.852722)
		(mid 384.955034 -232.902865)
		(end 384.767836 -232.852722)
		(width 0.088646)
		(layer "In11.Cu")
		(net "M_H_CPU0_SB_DQS_DN<1>")
	)
	(arc
		(start 381.938022 -232.846626)
		(mid 381.65959 -232.77678)
		(end 381.382778 -232.852722)
		(width 0.088646)
		(layer "In11.Cu")
		(net "M_H_CPU0_SB_DQS_DN<1>")
	)
	(arc
		(start 384.202432 -232.852722)
		(mid 384.015234 -232.902865)
		(end 383.828036 -232.852722)
		(width 0.088646)
		(layer "In11.Cu")
		(net "M_H_CPU0_SB_DQS_DN<1>")
	)
	(arc
		(start 381.382778 -232.852722)
		(mid 381.19558 -232.902865)
		(end 381.008382 -232.852722)
		(width 0.088646)
		(layer "In11.Cu")
		(net "M_H_CPU0_SB_DQS_DN<1>")
	)
	(arc
		(start 372.924832 -232.852722)
		(mid 372.740878 -232.902851)
		(end 372.556024 -232.856024)
		(width 0.088646)
		(layer "In11.Cu")
		(net "M_H_CPU0_SB_DQS_DN<1>")
	)
	(arc
		(start 372.54434 -232.84942)
		(mid 372.264235 -232.776978)
		(end 371.985032 -232.852722)
		(width 0.088646)
		(layer "In11.Cu")
		(net "M_H_CPU0_SB_DQS_DN<1>")
	)
	(arc
		(start 375.369836 -232.852722)
		(mid 375.093023 -232.776852)
		(end 374.814592 -232.846626)
		(width 0.088646)
		(layer "In11.Cu")
		(net "M_H_CPU0_SB_DQS_DN<1>")
	)
	(arc
		(start 384.767836 -232.852722)
		(mid 384.485134 -232.776946)
		(end 384.202432 -232.852722)
		(width 0.088646)
		(layer "In11.Cu")
		(net "M_H_CPU0_SB_DQS_DN<1>")
	)
	(arc
		(start 374.804178 -232.852722)
		(mid 374.61698 -232.902865)
		(end 374.429782 -232.852722)
		(width 0.088646)
		(layer "In11.Cu")
		(net "M_H_CPU0_SB_DQS_DN<1>")
	)
	(arc
		(start 376.309636 -232.852722)
		(mid 376.035437 -232.776887)
		(end 375.758964 -232.844086)
		(width 0.088646)
		(layer "In11.Cu")
		(net "M_H_CPU0_SB_DQS_DN<1>")
	)
	(arc
		(start 379.503432 -232.852722)
		(mid 379.316234 -232.902865)
		(end 379.129036 -232.852722)
		(width 0.088646)
		(layer "In11.Cu")
		(net "M_H_CPU0_SB_DQS_DN<1>")
	)
	(arc
		(start 383.828036 -232.852722)
		(mid 383.545334 -232.776946)
		(end 383.262632 -232.852722)
		(width 0.088646)
		(layer "In11.Cu")
		(net "M_H_CPU0_SB_DQS_DN<1>")
	)
	(arc
		(start 377.623832 -232.852722)
		(mid 377.436634 -232.902865)
		(end 377.249436 -232.852722)
		(width 0.088646)
		(layer "In11.Cu")
		(net "M_H_CPU0_SB_DQS_DN<1>")
	)
	(arc
		(start 379.129036 -232.852722)
		(mid 378.854837 -232.776887)
		(end 378.578364 -232.844086)
		(width 0.088646)
		(layer "In11.Cu")
		(net "M_H_CPU0_SB_DQS_DN<1>")
	)
	(arc
		(start 380.443232 -232.852722)
		(mid 380.256034 -232.902865)
		(end 380.068836 -232.852722)
		(width 0.088646)
		(layer "In11.Cu")
		(net "M_H_CPU0_SB_DQS_DN<1>")
	)
	(arc
		(start 383.262632 -232.852722)
		(mid 383.075434 -232.902865)
		(end 382.888236 -232.852722)
		(width 0.088646)
		(layer "In11.Cu")
		(net "M_H_CPU0_SB_DQS_DN<1>")
	)
	(arc
		(start 376.684032 -232.852722)
		(mid 376.496834 -232.902865)
		(end 376.309636 -232.852722)
		(width 0.088646)
		(layer "In11.Cu")
		(net "M_H_CPU0_SB_DQS_DN<1>")
	)
	(arc
		(start 382.322832 -232.852722)
		(mid 382.135634 -232.902865)
		(end 381.948436 -232.852722)
		(width 0.088646)
		(layer "In11.Cu")
		(net "M_H_CPU0_SB_DQS_DN<1>")
	)
	(arc
		(start 378.189236 -232.852722)
		(mid 377.915037 -232.776887)
		(end 377.638564 -232.844086)
		(width 0.088646)
		(layer "In11.Cu")
		(net "M_H_CPU0_SB_DQS_DN<1>")
	)
	(arc
		(start 385.707636 -232.852722)
		(mid 385.424934 -232.776946)
		(end 385.142232 -232.852722)
		(width 0.088646)
		(layer "In11.Cu")
		(net "M_H_CPU0_SB_DQS_DN<1>")
	)
	(arc
		(start 380.068836 -232.852722)
		(mid 379.794637 -232.776887)
		(end 379.518164 -232.844086)
		(width 0.088646)
		(layer "In11.Cu")
		(net "M_H_CPU0_SB_DQS_DN<1>")
	)
	(arc
		(start 380.997968 -232.846626)
		(mid 380.71979 -232.776903)
		(end 380.443232 -232.852722)
		(width 0.088646)
		(layer "In11.Cu")
		(net "M_H_CPU0_SB_DQS_DN<1>")
	)
	(segment
		(start 458.39761 -228.157278)
		(end 457.987146 -228.567742)
		(width 0.20066)
		(layer "F.Cu")
		(net "M_H_CPU0_SB_DQS_DN<0>")
	)
	(segment
		(start 453.996806 -228.612954)
		(end 453.582278 -228.198426)
		(width 0.20066)
		(layer "F.Cu")
		(net "M_H_CPU0_SB_DQS_DN<0>")
	)
	(segment
		(start 371.79758 -237.947454)
		(end 371.79758 -237.411768)
		(width 0.20066)
		(layer "F.Cu")
		(net "M_H_CPU0_SB_DQS_DN<0>")
	)
	(segment
		(start 458.730096 -228.157278)
		(end 458.39761 -228.157278)
		(width 0.20066)
		(layer "F.Cu")
		(net "M_H_CPU0_SB_DQS_DN<0>")
	)
	(segment
		(start 458.970634 -227.91674)
		(end 458.730096 -228.157278)
		(width 0.20066)
		(layer "F.Cu")
		(net "M_H_CPU0_SB_DQS_DN<0>")
	)
	(segment
		(start 459.559914 -227.91674)
		(end 458.970634 -227.91674)
		(width 0.20066)
		(layer "F.Cu")
		(net "M_H_CPU0_SB_DQS_DN<0>")
	)
	(segment
		(start 371.79758 -237.411768)
		(end 371.797834 -237.411514)
		(width 0.20066)
		(layer "F.Cu")
		(net "M_H_CPU0_SB_DQS_DN<0>")
	)
	(segment
		(start 454.518522 -228.612954)
		(end 453.996806 -228.612954)
		(width 0.20066)
		(layer "F.Cu")
		(net "M_H_CPU0_SB_DQS_DN<0>")
	)
	(segment
		(start 454.789794 -228.341682)
		(end 454.518522 -228.612954)
		(width 0.20066)
		(layer "F.Cu")
		(net "M_H_CPU0_SB_DQS_DN<0>")
	)
	(segment
		(start 452.564754 -227.91674)
		(end 452.016114 -227.91674)
		(width 0.20066)
		(layer "F.Cu")
		(net "M_H_CPU0_SB_DQS_DN<0>")
	)
	(segment
		(start 457.126594 -228.336348)
		(end 457.12126 -228.341682)
		(width 0.1016)
		(layer "F.Cu")
		(net "M_H_CPU0_SB_DQS_DN<0>")
	)
	(segment
		(start 454.937368 -228.341682)
		(end 454.789794 -228.341682)
		(width 0.20066)
		(layer "F.Cu")
		(net "M_H_CPU0_SB_DQS_DN<0>")
	)
	(segment
		(start 457.12126 -228.341682)
		(end 454.941686 -228.341682)
		(width 0.1016)
		(layer "F.Cu")
		(net "M_H_CPU0_SB_DQS_DN<0>")
	)
	(segment
		(start 452.84644 -228.198426)
		(end 452.564754 -227.91674)
		(width 0.20066)
		(layer "F.Cu")
		(net "M_H_CPU0_SB_DQS_DN<0>")
	)
	(segment
		(start 454.941686 -228.341682)
		(end 454.937368 -228.341682)
		(width 0.101854)
		(layer "F.Cu")
		(net "M_H_CPU0_SB_DQS_DN<0>")
	)
	(segment
		(start 453.582278 -228.198426)
		(end 452.84644 -228.198426)
		(width 0.20066)
		(layer "F.Cu")
		(net "M_H_CPU0_SB_DQS_DN<0>")
	)
	(segment
		(start 457.682092 -228.567742)
		(end 457.450698 -228.336348)
		(width 0.20066)
		(layer "F.Cu")
		(net "M_H_CPU0_SB_DQS_DN<0>")
	)
	(segment
		(start 457.450698 -228.336348)
		(end 457.126594 -228.336348)
		(width 0.20066)
		(layer "F.Cu")
		(net "M_H_CPU0_SB_DQS_DN<0>")
	)
	(segment
		(start 450.911214 -227.91674)
		(end 452.016114 -227.91674)
		(width 0.20066)
		(layer "F.Cu")
		(net "M_H_CPU0_SB_DQS_DN<0>")
	)
	(segment
		(start 457.987146 -228.567742)
		(end 457.682092 -228.567742)
		(width 0.20066)
		(layer "F.Cu")
		(net "M_H_CPU0_SB_DQS_DN<0>")
	)
	(segment
		(start 409.51785 -225.791014)
		(end 409.254452 -226.054412)
		(width 0.18288)
		(layer "In11.Cu")
		(net "M_H_CPU0_SB_DQS_DN<0>")
	)
	(segment
		(start 386.082286 -237.73638)
		(end 386.082032 -237.735872)
		(width 0.088646)
		(layer "In11.Cu")
		(net "M_H_CPU0_SB_DQS_DN<0>")
	)
	(segment
		(start 388.960106 -237.195614)
		(end 388.37108 -237.195614)
		(width 0.088646)
		(layer "In11.Cu")
		(net "M_H_CPU0_SB_DQS_DN<0>")
	)
	(segment
		(start 409.981654 -225.791014)
		(end 409.51785 -225.791014)
		(width 0.18288)
		(layer "In11.Cu")
		(net "M_H_CPU0_SB_DQS_DN<0>")
	)
	(segment
		(start 441.284868 -224.366328)
		(end 440.407298 -224.366328)
		(width 0.18288)
		(layer "In11.Cu")
		(net "M_H_CPU0_SB_DQS_DN<0>")
	)
	(segment
		(start 381.008382 -237.736126)
		(end 380.997968 -237.73003)
		(width 0.088646)
		(layer "In11.Cu")
		(net "M_H_CPU0_SB_DQS_DN<0>")
	)
	(segment
		(start 388.37108 -237.195614)
		(end 387.906768 -237.659926)
		(width 0.088646)
		(layer "In11.Cu")
		(net "M_H_CPU0_SB_DQS_DN<0>")
	)
	(segment
		(start 437.806338 -224.09912)
		(end 437.223662 -223.516444)
		(width 0.18288)
		(layer "In11.Cu")
		(net "M_H_CPU0_SB_DQS_DN<0>")
	)
	(segment
		(start 439.725562 -224.090992)
		(end 439.42381 -224.392744)
		(width 0.18288)
		(layer "In11.Cu")
		(net "M_H_CPU0_SB_DQS_DN<0>")
	)
	(segment
		(start 435.629558 -223.241108)
		(end 435.36997 -223.500696)
		(width 0.18288)
		(layer "In11.Cu")
		(net "M_H_CPU0_SB_DQS_DN<0>")
	)
	(segment
		(start 375.369836 -237.736126)
		(end 375.369836 -237.735872)
		(width 0.088646)
		(layer "In11.Cu")
		(net "M_H_CPU0_SB_DQS_DN<0>")
	)
	(segment
		(start 371.610636 -237.736126)
		(end 371.48643 -237.665006)
		(width 0.088646)
		(layer "In11.Cu")
		(net "M_H_CPU0_SB_DQS_DN<0>")
	)
	(segment
		(start 445.472058 -227.76942)
		(end 443.714124 -226.011486)
		(width 0.18288)
		(layer "In11.Cu")
		(net "M_H_CPU0_SB_DQS_DN<0>")
	)
	(segment
		(start 413.026352 -225.854768)
		(end 412.56585 -225.394266)
		(width 0.18288)
		(layer "In11.Cu")
		(net "M_H_CPU0_SB_DQS_DN<0>")
	)
	(segment
		(start 424.607482 -224.090992)
		(end 424.29303 -224.405444)
		(width 0.18288)
		(layer "In11.Cu")
		(net "M_H_CPU0_SB_DQS_DN<0>")
	)
	(segment
		(start 406.10282 -226.916234)
		(end 405.8285 -226.641914)
		(width 0.18288)
		(layer "In11.Cu")
		(net "M_H_CPU0_SB_DQS_DN<0>")
	)
	(segment
		(start 371.999764 -237.72749)
		(end 371.985032 -237.736126)
		(width 0.088646)
		(layer "In11.Cu")
		(net "M_H_CPU0_SB_DQS_DN<0>")
	)
	(segment
		(start 372.939564 -237.72749)
		(end 372.924832 -237.736126)
		(width 0.088646)
		(layer "In11.Cu")
		(net "M_H_CPU0_SB_DQS_DN<0>")
	)
	(segment
		(start 387.906768 -237.659926)
		(end 386.36448 -237.659926)
		(width 0.088646)
		(layer "In11.Cu")
		(net "M_H_CPU0_SB_DQS_DN<0>")
	)
	(segment
		(start 416.035236 -225.854768)
		(end 413.026352 -225.854768)
		(width 0.18288)
		(layer "In11.Cu")
		(net "M_H_CPU0_SB_DQS_DN<0>")
	)
	(segment
		(start 421.905938 -225.216466)
		(end 421.208962 -225.216466)
		(width 0.18288)
		(layer "In11.Cu")
		(net "M_H_CPU0_SB_DQS_DN<0>")
	)
	(segment
		(start 412.56585 -225.394266)
		(end 411.625034 -225.394266)
		(width 0.18288)
		(layer "In11.Cu")
		(net "M_H_CPU0_SB_DQS_DN<0>")
	)
	(segment
		(start 411.625034 -225.394266)
		(end 410.95295 -226.06635)
		(width 0.18288)
		(layer "In11.Cu")
		(net "M_H_CPU0_SB_DQS_DN<0>")
	)
	(segment
		(start 377.638564 -237.72749)
		(end 377.623832 -237.736126)
		(width 0.088646)
		(layer "In11.Cu")
		(net "M_H_CPU0_SB_DQS_DN<0>")
	)
	(segment
		(start 440.131962 -224.090992)
		(end 439.725562 -224.090992)
		(width 0.18288)
		(layer "In11.Cu")
		(net "M_H_CPU0_SB_DQS_DN<0>")
	)
	(segment
		(start 371.351556 -237.469172)
		(end 371.40896 -237.411768)
		(width 0.088646)
		(layer "In11.Cu")
		(net "M_H_CPU0_SB_DQS_DN<0>")
	)
	(segment
		(start 420.243762 -225.218498)
		(end 416.671506 -225.218498)
		(width 0.18288)
		(layer "In11.Cu")
		(net "M_H_CPU0_SB_DQS_DN<0>")
	)
	(segment
		(start 392.968734 -237.135924)
		(end 389.019796 -237.135924)
		(width 0.18288)
		(layer "In11.Cu")
		(net "M_H_CPU0_SB_DQS_DN<0>")
	)
	(segment
		(start 374.430036 -237.735872)
		(end 374.419368 -237.73003)
		(width 0.088646)
		(layer "In11.Cu")
		(net "M_H_CPU0_SB_DQS_DN<0>")
	)
	(segment
		(start 438.703212 -224.09912)
		(end 437.806338 -224.09912)
		(width 0.18288)
		(layer "In11.Cu")
		(net "M_H_CPU0_SB_DQS_DN<0>")
	)
	(segment
		(start 438.996836 -224.392744)
		(end 438.703212 -224.09912)
		(width 0.18288)
		(layer "In11.Cu")
		(net "M_H_CPU0_SB_DQS_DN<0>")
	)
	(segment
		(start 440.407298 -224.366328)
		(end 440.131962 -224.090992)
		(width 0.18288)
		(layer "In11.Cu")
		(net "M_H_CPU0_SB_DQS_DN<0>")
	)
	(segment
		(start 416.671506 -225.218498)
		(end 416.035236 -225.854768)
		(width 0.18288)
		(layer "In11.Cu")
		(net "M_H_CPU0_SB_DQS_DN<0>")
	)
	(segment
		(start 374.819164 -237.727236)
		(end 374.804432 -237.735872)
		(width 0.088646)
		(layer "In11.Cu")
		(net "M_H_CPU0_SB_DQS_DN<0>")
	)
	(segment
		(start 379.518164 -237.72749)
		(end 379.503432 -237.736126)
		(width 0.088646)
		(layer "In11.Cu")
		(net "M_H_CPU0_SB_DQS_DN<0>")
	)
	(segment
		(start 431.645314 -223.500696)
		(end 430.970944 -224.175066)
		(width 0.18288)
		(layer "In11.Cu")
		(net "M_H_CPU0_SB_DQS_DN<0>")
	)
	(segment
		(start 439.42381 -224.392744)
		(end 438.996836 -224.392744)
		(width 0.18288)
		(layer "In11.Cu")
		(net "M_H_CPU0_SB_DQS_DN<0>")
	)
	(segment
		(start 405.43988 -226.641914)
		(end 405.176736 -226.905058)
		(width 0.18288)
		(layer "In11.Cu")
		(net "M_H_CPU0_SB_DQS_DN<0>")
	)
	(segment
		(start 436.01767 -223.241108)
		(end 435.629558 -223.241108)
		(width 0.18288)
		(layer "In11.Cu")
		(net "M_H_CPU0_SB_DQS_DN<0>")
	)
	(segment
		(start 443.231524 -226.011486)
		(end 442.334904 -225.114866)
		(width 0.18288)
		(layer "In11.Cu")
		(net "M_H_CPU0_SB_DQS_DN<0>")
	)
	(segment
		(start 421.208962 -225.216466)
		(end 420.933626 -224.94113)
		(width 0.18288)
		(layer "In11.Cu")
		(net "M_H_CPU0_SB_DQS_DN<0>")
	)
	(segment
		(start 425.74718 -224.366328)
		(end 425.32173 -224.366328)
		(width 0.18288)
		(layer "In11.Cu")
		(net "M_H_CPU0_SB_DQS_DN<0>")
	)
	(segment
		(start 383.262632 -237.735872)
		(end 383.262632 -237.736126)
		(width 0.088646)
		(layer "In11.Cu")
		(net "M_H_CPU0_SB_DQS_DN<0>")
	)
	(segment
		(start 375.758964 -237.72749)
		(end 375.744232 -237.736126)
		(width 0.088646)
		(layer "In11.Cu")
		(net "M_H_CPU0_SB_DQS_DN<0>")
	)
	(segment
		(start 381.948436 -237.736126)
		(end 381.938022 -237.73003)
		(width 0.088646)
		(layer "In11.Cu")
		(net "M_H_CPU0_SB_DQS_DN<0>")
	)
	(segment
		(start 389.019796 -237.135924)
		(end 388.960106 -237.195614)
		(width 0.088646)
		(layer "In11.Cu")
		(net "M_H_CPU0_SB_DQS_DN<0>")
	)
	(segment
		(start 405.176736 -226.905058)
		(end 403.1996 -226.905058)
		(width 0.18288)
		(layer "In11.Cu")
		(net "M_H_CPU0_SB_DQS_DN<0>")
	)
	(segment
		(start 449.908422 -227.76942)
		(end 445.472058 -227.76942)
		(width 0.18288)
		(layer "In11.Cu")
		(net "M_H_CPU0_SB_DQS_DN<0>")
	)
	(segment
		(start 405.8285 -226.641914)
		(end 405.43988 -226.641914)
		(width 0.18288)
		(layer "In11.Cu")
		(net "M_H_CPU0_SB_DQS_DN<0>")
	)
	(segment
		(start 410.95295 -226.06635)
		(end 410.25699 -226.06635)
		(width 0.18288)
		(layer "In11.Cu")
		(net "M_H_CPU0_SB_DQS_DN<0>")
	)
	(segment
		(start 407.582624 -226.054412)
		(end 406.720802 -226.916234)
		(width 0.18288)
		(layer "In11.Cu")
		(net "M_H_CPU0_SB_DQS_DN<0>")
	)
	(segment
		(start 442.033406 -225.114866)
		(end 441.284868 -224.366328)
		(width 0.18288)
		(layer "In11.Cu")
		(net "M_H_CPU0_SB_DQS_DN<0>")
	)
	(segment
		(start 450.637148 -228.190806)
		(end 450.329808 -228.190806)
		(width 0.18288)
		(layer "In11.Cu")
		(net "M_H_CPU0_SB_DQS_DN<0>")
	)
	(segment
		(start 403.1996 -226.905058)
		(end 392.968734 -237.135924)
		(width 0.18288)
		(layer "In11.Cu")
		(net "M_H_CPU0_SB_DQS_DN<0>")
	)
	(segment
		(start 435.36997 -223.500696)
		(end 431.645314 -223.500696)
		(width 0.18288)
		(layer "In11.Cu")
		(net "M_H_CPU0_SB_DQS_DN<0>")
	)
	(segment
		(start 425.046394 -224.090992)
		(end 424.607482 -224.090992)
		(width 0.18288)
		(layer "In11.Cu")
		(net "M_H_CPU0_SB_DQS_DN<0>")
	)
	(segment
		(start 427.783498 -224.175066)
		(end 427.351698 -223.743266)
		(width 0.18288)
		(layer "In11.Cu")
		(net "M_H_CPU0_SB_DQS_DN<0>")
	)
	(segment
		(start 420.52113 -224.94113)
		(end 420.243762 -225.218498)
		(width 0.18288)
		(layer "In11.Cu")
		(net "M_H_CPU0_SB_DQS_DN<0>")
	)
	(segment
		(start 425.32173 -224.366328)
		(end 425.046394 -224.090992)
		(width 0.18288)
		(layer "In11.Cu")
		(net "M_H_CPU0_SB_DQS_DN<0>")
	)
	(segment
		(start 443.714124 -226.011486)
		(end 443.231524 -226.011486)
		(width 0.18288)
		(layer "In11.Cu")
		(net "M_H_CPU0_SB_DQS_DN<0>")
	)
	(segment
		(start 371.40896 -237.411768)
		(end 371.79758 -237.411768)
		(width 0.088646)
		(layer "In11.Cu")
		(net "M_H_CPU0_SB_DQS_DN<0>")
	)
	(segment
		(start 430.970944 -224.175066)
		(end 427.783498 -224.175066)
		(width 0.18288)
		(layer "In11.Cu")
		(net "M_H_CPU0_SB_DQS_DN<0>")
	)
	(segment
		(start 422.71696 -224.405444)
		(end 421.905938 -225.216466)
		(width 0.18288)
		(layer "In11.Cu")
		(net "M_H_CPU0_SB_DQS_DN<0>")
	)
	(segment
		(start 410.25699 -226.06635)
		(end 409.981654 -225.791014)
		(width 0.18288)
		(layer "In11.Cu")
		(net "M_H_CPU0_SB_DQS_DN<0>")
	)
	(segment
		(start 409.254452 -226.054412)
		(end 407.582624 -226.054412)
		(width 0.18288)
		(layer "In11.Cu")
		(net "M_H_CPU0_SB_DQS_DN<0>")
	)
	(segment
		(start 450.911214 -227.91674)
		(end 450.637148 -228.190806)
		(width 0.18288)
		(layer "In11.Cu")
		(net "M_H_CPU0_SB_DQS_DN<0>")
	)
	(segment
		(start 427.351698 -223.743266)
		(end 426.370242 -223.743266)
		(width 0.18288)
		(layer "In11.Cu")
		(net "M_H_CPU0_SB_DQS_DN<0>")
	)
	(segment
		(start 426.370242 -223.743266)
		(end 425.74718 -224.366328)
		(width 0.18288)
		(layer "In11.Cu")
		(net "M_H_CPU0_SB_DQS_DN<0>")
	)
	(segment
		(start 437.223662 -223.516444)
		(end 436.293006 -223.516444)
		(width 0.18288)
		(layer "In11.Cu")
		(net "M_H_CPU0_SB_DQS_DN<0>")
	)
	(segment
		(start 406.720802 -226.916234)
		(end 406.10282 -226.916234)
		(width 0.18288)
		(layer "In11.Cu")
		(net "M_H_CPU0_SB_DQS_DN<0>")
	)
	(segment
		(start 378.578364 -237.72749)
		(end 378.563632 -237.736126)
		(width 0.088646)
		(layer "In11.Cu")
		(net "M_H_CPU0_SB_DQS_DN<0>")
	)
	(segment
		(start 442.334904 -225.114866)
		(end 442.033406 -225.114866)
		(width 0.18288)
		(layer "In11.Cu")
		(net "M_H_CPU0_SB_DQS_DN<0>")
	)
	(segment
		(start 424.29303 -224.405444)
		(end 422.71696 -224.405444)
		(width 0.18288)
		(layer "In11.Cu")
		(net "M_H_CPU0_SB_DQS_DN<0>")
	)
	(segment
		(start 436.293006 -223.516444)
		(end 436.01767 -223.241108)
		(width 0.18288)
		(layer "In11.Cu")
		(net "M_H_CPU0_SB_DQS_DN<0>")
	)
	(segment
		(start 371.79758 -237.411768)
		(end 371.797834 -237.411514)
		(width 0.088646)
		(layer "In11.Cu")
		(net "M_H_CPU0_SB_DQS_DN<0>")
	)
	(segment
		(start 420.933626 -224.94113)
		(end 420.52113 -224.94113)
		(width 0.18288)
		(layer "In11.Cu")
		(net "M_H_CPU0_SB_DQS_DN<0>")
	)
	(segment
		(start 376.698764 -237.72749)
		(end 376.684032 -237.736126)
		(width 0.088646)
		(layer "In11.Cu")
		(net "M_H_CPU0_SB_DQS_DN<0>")
	)
	(segment
		(start 450.329808 -228.190806)
		(end 449.908422 -227.76942)
		(width 0.18288)
		(layer "In11.Cu")
		(net "M_H_CPU0_SB_DQS_DN<0>")
	)
	(arc
		(start 371.985032 -237.736126)
		(mid 371.797834 -237.786269)
		(end 371.610636 -237.736126)
		(width 0.088646)
		(layer "In11.Cu")
		(net "M_H_CPU0_SB_DQS_DN<0>")
	)
	(arc
		(start 385.707636 -237.735872)
		(mid 385.424934 -237.66013)
		(end 385.142232 -237.735872)
		(width 0.088646)
		(layer "In11.Cu")
		(net "M_H_CPU0_SB_DQS_DN<0>")
	)
	(arc
		(start 374.804432 -237.735872)
		(mid 374.617234 -237.786015)
		(end 374.430036 -237.735872)
		(width 0.088646)
		(layer "In11.Cu")
		(net "M_H_CPU0_SB_DQS_DN<0>")
	)
	(arc
		(start 382.322832 -237.736126)
		(mid 382.135634 -237.786269)
		(end 381.948436 -237.736126)
		(width 0.088646)
		(layer "In11.Cu")
		(net "M_H_CPU0_SB_DQS_DN<0>")
	)
	(arc
		(start 382.888236 -237.736126)
		(mid 382.605534 -237.66035)
		(end 382.322832 -237.736126)
		(width 0.088646)
		(layer "In11.Cu")
		(net "M_H_CPU0_SB_DQS_DN<0>")
	)
	(arc
		(start 380.068836 -237.736126)
		(mid 379.794637 -237.660291)
		(end 379.518164 -237.72749)
		(width 0.088646)
		(layer "In11.Cu")
		(net "M_H_CPU0_SB_DQS_DN<0>")
	)
	(arc
		(start 380.443232 -237.736126)
		(mid 380.256034 -237.786269)
		(end 380.068836 -237.736126)
		(width 0.088646)
		(layer "In11.Cu")
		(net "M_H_CPU0_SB_DQS_DN<0>")
	)
	(arc
		(start 379.503432 -237.736126)
		(mid 379.316234 -237.786269)
		(end 379.129036 -237.736126)
		(width 0.088646)
		(layer "In11.Cu")
		(net "M_H_CPU0_SB_DQS_DN<0>")
	)
	(arc
		(start 376.309636 -237.736126)
		(mid 376.035437 -237.660291)
		(end 375.758964 -237.72749)
		(width 0.088646)
		(layer "In11.Cu")
		(net "M_H_CPU0_SB_DQS_DN<0>")
	)
	(arc
		(start 384.202432 -237.735872)
		(mid 384.015234 -237.786015)
		(end 383.828036 -237.735872)
		(width 0.088646)
		(layer "In11.Cu")
		(net "M_H_CPU0_SB_DQS_DN<0>")
	)
	(arc
		(start 378.563632 -237.736126)
		(mid 378.376434 -237.786269)
		(end 378.189236 -237.736126)
		(width 0.088646)
		(layer "In11.Cu")
		(net "M_H_CPU0_SB_DQS_DN<0>")
	)
	(arc
		(start 376.684032 -237.736126)
		(mid 376.496834 -237.786269)
		(end 376.309636 -237.736126)
		(width 0.088646)
		(layer "In11.Cu")
		(net "M_H_CPU0_SB_DQS_DN<0>")
	)
	(arc
		(start 383.262632 -237.736126)
		(mid 383.075434 -237.786269)
		(end 382.888236 -237.736126)
		(width 0.088646)
		(layer "In11.Cu")
		(net "M_H_CPU0_SB_DQS_DN<0>")
	)
	(arc
		(start 380.997968 -237.73003)
		(mid 380.71979 -237.660307)
		(end 380.443232 -237.736126)
		(width 0.088646)
		(layer "In11.Cu")
		(net "M_H_CPU0_SB_DQS_DN<0>")
	)
	(arc
		(start 385.142232 -237.735872)
		(mid 384.955034 -237.786015)
		(end 384.767836 -237.735872)
		(width 0.088646)
		(layer "In11.Cu")
		(net "M_H_CPU0_SB_DQS_DN<0>")
	)
	(arc
		(start 384.767836 -237.735872)
		(mid 384.485134 -237.66013)
		(end 384.202432 -237.735872)
		(width 0.088646)
		(layer "In11.Cu")
		(net "M_H_CPU0_SB_DQS_DN<0>")
	)
	(arc
		(start 377.249436 -237.736126)
		(mid 376.975237 -237.660291)
		(end 376.698764 -237.72749)
		(width 0.088646)
		(layer "In11.Cu")
		(net "M_H_CPU0_SB_DQS_DN<0>")
	)
	(arc
		(start 372.924832 -237.736126)
		(mid 372.737634 -237.786269)
		(end 372.550436 -237.736126)
		(width 0.088646)
		(layer "In11.Cu")
		(net "M_H_CPU0_SB_DQS_DN<0>")
	)
	(arc
		(start 375.744232 -237.736126)
		(mid 375.557034 -237.786269)
		(end 375.369836 -237.736126)
		(width 0.088646)
		(layer "In11.Cu")
		(net "M_H_CPU0_SB_DQS_DN<0>")
	)
	(arc
		(start 374.419368 -237.73003)
		(mid 374.14119 -237.660307)
		(end 373.864632 -237.736126)
		(width 0.088646)
		(layer "In11.Cu")
		(net "M_H_CPU0_SB_DQS_DN<0>")
	)
	(arc
		(start 386.36448 -237.659926)
		(mid 386.218361 -237.679609)
		(end 386.082286 -237.73638)
		(width 0.088646)
		(layer "In11.Cu")
		(net "M_H_CPU0_SB_DQS_DN<0>")
	)
	(arc
		(start 378.189236 -237.736126)
		(mid 377.915037 -237.660291)
		(end 377.638564 -237.72749)
		(width 0.088646)
		(layer "In11.Cu")
		(net "M_H_CPU0_SB_DQS_DN<0>")
	)
	(arc
		(start 381.938022 -237.73003)
		(mid 381.65959 -237.660184)
		(end 381.382778 -237.736126)
		(width 0.088646)
		(layer "In11.Cu")
		(net "M_H_CPU0_SB_DQS_DN<0>")
	)
	(arc
		(start 381.382778 -237.736126)
		(mid 381.19558 -237.786269)
		(end 381.008382 -237.736126)
		(width 0.088646)
		(layer "In11.Cu")
		(net "M_H_CPU0_SB_DQS_DN<0>")
	)
	(arc
		(start 379.129036 -237.736126)
		(mid 378.854837 -237.660291)
		(end 378.578364 -237.72749)
		(width 0.088646)
		(layer "In11.Cu")
		(net "M_H_CPU0_SB_DQS_DN<0>")
	)
	(arc
		(start 386.082032 -237.735872)
		(mid 385.894834 -237.786015)
		(end 385.707636 -237.735872)
		(width 0.088646)
		(layer "In11.Cu")
		(net "M_H_CPU0_SB_DQS_DN<0>")
	)
	(arc
		(start 373.490236 -237.736126)
		(mid 373.216037 -237.660291)
		(end 372.939564 -237.72749)
		(width 0.088646)
		(layer "In11.Cu")
		(net "M_H_CPU0_SB_DQS_DN<0>")
	)
	(arc
		(start 375.369836 -237.735872)
		(mid 375.095607 -237.659947)
		(end 374.819164 -237.727236)
		(width 0.088646)
		(layer "In11.Cu")
		(net "M_H_CPU0_SB_DQS_DN<0>")
	)
	(arc
		(start 373.864632 -237.736126)
		(mid 373.677434 -237.786269)
		(end 373.490236 -237.736126)
		(width 0.088646)
		(layer "In11.Cu")
		(net "M_H_CPU0_SB_DQS_DN<0>")
	)
	(arc
		(start 383.828036 -237.735872)
		(mid 383.545334 -237.66013)
		(end 383.262632 -237.735872)
		(width 0.088646)
		(layer "In11.Cu")
		(net "M_H_CPU0_SB_DQS_DN<0>")
	)
	(arc
		(start 372.550436 -237.736126)
		(mid 372.276237 -237.660291)
		(end 371.999764 -237.72749)
		(width 0.088646)
		(layer "In11.Cu")
		(net "M_H_CPU0_SB_DQS_DN<0>")
	)
	(arc
		(start 377.623832 -237.736126)
		(mid 377.436634 -237.786269)
		(end 377.249436 -237.736126)
		(width 0.088646)
		(layer "In11.Cu")
		(net "M_H_CPU0_SB_DQS_DN<0>")
	)
	(arc
		(start 371.48643 -237.665006)
		(mid 371.396552 -237.582531)
		(end 371.351556 -237.469172)
		(width 0.088646)
		(layer "In11.Cu")
		(net "M_H_CPU0_SB_DQS_DN<0>")
	)
	(segment
		(start 457.126594 -220.68536)
		(end 457.120244 -220.69171)
		(width 0.1016)
		(layer "F.Cu")
		(net "M_H_CPU0_SB_DQ<9>")
	)
	(segment
		(start 457.53655 -220.68536)
		(end 457.126594 -220.68536)
		(width 0.20066)
		(layer "F.Cu")
		(net "M_H_CPU0_SB_DQ<9>")
	)
	(segment
		(start 454.260712 -221.365318)
		(end 453.785478 -221.365318)
		(width 0.20066)
		(layer "F.Cu")
		(net "M_H_CPU0_SB_DQ<9>")
	)
	(segment
		(start 454.566782 -220.69171)
		(end 454.448672 -220.80982)
		(width 0.20066)
		(layer "F.Cu")
		(net "M_H_CPU0_SB_DQ<9>")
	)
	(segment
		(start 453.785478 -221.365318)
		(end 453.536812 -221.116652)
		(width 0.20066)
		(layer "F.Cu")
		(net "M_H_CPU0_SB_DQ<9>")
	)
	(segment
		(start 452.016114 -221.116652)
		(end 450.911214 -221.116652)
		(width 0.20066)
		(layer "F.Cu")
		(net "M_H_CPU0_SB_DQ<9>")
	)
	(segment
		(start 457.120244 -220.69171)
		(end 454.931526 -220.69171)
		(width 0.1016)
		(layer "F.Cu")
		(net "M_H_CPU0_SB_DQ<9>")
	)
	(segment
		(start 454.931526 -220.69171)
		(end 454.91146 -220.69171)
		(width 0.101854)
		(layer "F.Cu")
		(net "M_H_CPU0_SB_DQ<9>")
	)
	(segment
		(start 459.55966 -221.116906)
		(end 457.968096 -221.116906)
		(width 0.20066)
		(layer "F.Cu")
		(net "M_H_CPU0_SB_DQ<9>")
	)
	(segment
		(start 459.559914 -221.116652)
		(end 459.55966 -221.116906)
		(width 0.20066)
		(layer "F.Cu")
		(net "M_H_CPU0_SB_DQ<9>")
	)
	(segment
		(start 453.536812 -221.116652)
		(end 452.016114 -221.116652)
		(width 0.20066)
		(layer "F.Cu")
		(net "M_H_CPU0_SB_DQ<9>")
	)
	(segment
		(start 454.448672 -221.177358)
		(end 454.260712 -221.365318)
		(width 0.20066)
		(layer "F.Cu")
		(net "M_H_CPU0_SB_DQ<9>")
	)
	(segment
		(start 371.32768 -233.877866)
		(end 371.32768 -233.34218)
		(width 0.20066)
		(layer "F.Cu")
		(net "M_H_CPU0_SB_DQ<9>")
	)
	(segment
		(start 371.327934 -233.87812)
		(end 371.32768 -233.877866)
		(width 0.20066)
		(layer "F.Cu")
		(net "M_H_CPU0_SB_DQ<9>")
	)
	(segment
		(start 454.91146 -220.69171)
		(end 454.566782 -220.69171)
		(width 0.20066)
		(layer "F.Cu")
		(net "M_H_CPU0_SB_DQ<9>")
	)
	(segment
		(start 457.968096 -221.116906)
		(end 457.53655 -220.68536)
		(width 0.20066)
		(layer "F.Cu")
		(net "M_H_CPU0_SB_DQ<9>")
	)
	(segment
		(start 454.448672 -220.80982)
		(end 454.448672 -221.177358)
		(width 0.20066)
		(layer "F.Cu")
		(net "M_H_CPU0_SB_DQ<9>")
	)
	(segment
		(start 407.588212 -215.742266)
		(end 407.588212 -215.964516)
		(width 0.18288)
		(layer "In11.Cu")
		(net "M_H_CPU0_SB_DQ<9>")
	)
	(segment
		(start 403.587712 -218.957398)
		(end 403.799294 -219.16898)
		(width 0.18288)
		(layer "In11.Cu")
		(net "M_H_CPU0_SB_DQ<9>")
	)
	(segment
		(start 411.20568 -215.684608)
		(end 411.20568 -215.440006)
		(width 0.18288)
		(layer "In11.Cu")
		(net "M_H_CPU0_SB_DQ<9>")
	)
	(segment
		(start 429.674528 -213.990428)
		(end 429.481488 -213.797388)
		(width 0.18288)
		(layer "In11.Cu")
		(net "M_H_CPU0_SB_DQ<9>")
	)
	(segment
		(start 414.08731 -215.837008)
		(end 414.08731 -215.666066)
		(width 0.18288)
		(layer "In11.Cu")
		(net "M_H_CPU0_SB_DQ<9>")
	)
	(segment
		(start 403.574504 -219.666566)
		(end 403.301708 -219.666566)
		(width 0.18288)
		(layer "In11.Cu")
		(net "M_H_CPU0_SB_DQ<9>")
	)
	(segment
		(start 443.093094 -217.174826)
		(end 442.254894 -216.336626)
		(width 0.18288)
		(layer "In11.Cu")
		(net "M_H_CPU0_SB_DQ<9>")
	)
	(segment
		(start 390.755124 -232.450386)
		(end 388.103364 -232.450386)
		(width 0.18288)
		(layer "In11.Cu")
		(net "M_H_CPU0_SB_DQ<9>")
	)
	(segment
		(start 447.334894 -219.968826)
		(end 446.191894 -218.825826)
		(width 0.18288)
		(layer "In11.Cu")
		(net "M_H_CPU0_SB_DQ<9>")
	)
	(segment
		(start 406.270714 -216.707466)
		(end 406.270714 -216.980262)
		(width 0.18288)
		(layer "In11.Cu")
		(net "M_H_CPU0_SB_DQ<9>")
	)
	(segment
		(start 450.911214 -221.116652)
		(end 450.296788 -220.502226)
		(width 0.18288)
		(layer "In11.Cu")
		(net "M_H_CPU0_SB_DQ<9>")
	)
	(segment
		(start 432.96205 -214.605362)
		(end 431.336958 -214.605362)
		(width 0.18288)
		(layer "In11.Cu")
		(net "M_H_CPU0_SB_DQ<9>")
	)
	(segment
		(start 404.794466 -218.173808)
		(end 404.794466 -218.446604)
		(width 0.18288)
		(layer "In11.Cu")
		(net "M_H_CPU0_SB_DQ<9>")
	)
	(segment
		(start 376.694446 -233.837988)
		(end 376.684032 -233.831892)
		(width 0.088646)
		(layer "In11.Cu")
		(net "M_H_CPU0_SB_DQ<9>")
	)
	(segment
		(start 414.08731 -215.666066)
		(end 413.89427 -215.473026)
		(width 0.18288)
		(layer "In11.Cu")
		(net "M_H_CPU0_SB_DQ<9>")
	)
	(segment
		(start 441.797694 -216.336626)
		(end 441.053474 -215.592406)
		(width 0.18288)
		(layer "In11.Cu")
		(net "M_H_CPU0_SB_DQ<9>")
	)
	(segment
		(start 437.505094 -215.422226)
		(end 436.823866 -214.740998)
		(width 0.18288)
		(layer "In11.Cu")
		(net "M_H_CPU0_SB_DQ<9>")
	)
	(segment
		(start 414.79089 -215.666066)
		(end 414.79089 -215.837008)
		(width 0.18288)
		(layer "In11.Cu")
		(net "M_H_CPU0_SB_DQ<9>")
	)
	(segment
		(start 447.893694 -219.968826)
		(end 447.334894 -219.968826)
		(width 0.18288)
		(layer "In11.Cu")
		(net "M_H_CPU0_SB_DQ<9>")
	)
	(segment
		(start 406.270714 -216.980262)
		(end 406.045924 -217.205052)
		(width 0.18288)
		(layer "In11.Cu")
		(net "M_H_CPU0_SB_DQ<9>")
	)
	(segment
		(start 433.85867 -215.025224)
		(end 433.66563 -215.218264)
		(width 0.18288)
		(layer "In11.Cu")
		(net "M_H_CPU0_SB_DQ<9>")
	)
	(segment
		(start 414.28035 -216.030048)
		(end 414.08731 -215.837008)
		(width 0.18288)
		(layer "In11.Cu")
		(net "M_H_CPU0_SB_DQ<9>")
	)
	(segment
		(start 426.910754 -214.685626)
		(end 426.005498 -215.590882)
		(width 0.18288)
		(layer "In11.Cu")
		(net "M_H_CPU0_SB_DQ<9>")
	)
	(segment
		(start 416.64763 -216.285826)
		(end 415.83483 -215.473026)
		(width 0.18288)
		(layer "In11.Cu")
		(net "M_H_CPU0_SB_DQ<9>")
	)
	(segment
		(start 433.85867 -214.798402)
		(end 433.85867 -215.025224)
		(width 0.18288)
		(layer "In11.Cu")
		(net "M_H_CPU0_SB_DQ<9>")
	)
	(segment
		(start 439.199274 -215.592406)
		(end 439.029094 -215.422226)
		(width 0.18288)
		(layer "In11.Cu")
		(net "M_H_CPU0_SB_DQ<9>")
	)
	(segment
		(start 404.085298 -218.459812)
		(end 403.812502 -218.459812)
		(width 0.18288)
		(layer "In11.Cu")
		(net "M_H_CPU0_SB_DQ<9>")
	)
	(segment
		(start 387.926834 -232.450386)
		(end 386.469382 -233.907838)
		(width 0.088646)
		(layer "In11.Cu")
		(net "M_H_CPU0_SB_DQ<9>")
	)
	(segment
		(start 406.334722 -215.549226)
		(end 406.141682 -215.742266)
		(width 0.18288)
		(layer "In11.Cu")
		(net "M_H_CPU0_SB_DQ<9>")
	)
	(segment
		(start 408.371294 -215.549226)
		(end 407.781252 -215.549226)
		(width 0.18288)
		(layer "In11.Cu")
		(net "M_H_CPU0_SB_DQ<9>")
	)
	(segment
		(start 372.939564 -233.840528)
		(end 372.924832 -233.831892)
		(width 0.088646)
		(layer "In11.Cu")
		(net "M_H_CPU0_SB_DQ<9>")
	)
	(segment
		(start 431.336958 -214.605362)
		(end 431.053494 -214.888826)
		(width 0.18288)
		(layer "In11.Cu")
		(net "M_H_CPU0_SB_DQ<9>")
	)
	(segment
		(start 428.777908 -214.888826)
		(end 427.878494 -214.888826)
		(width 0.18288)
		(layer "In11.Cu")
		(net "M_H_CPU0_SB_DQ<9>")
	)
	(segment
		(start 388.103364 -232.450386)
		(end 387.926834 -232.450386)
		(width 0.088646)
		(layer "In11.Cu")
		(net "M_H_CPU0_SB_DQ<9>")
	)
	(segment
		(start 429.867568 -214.888826)
		(end 429.674528 -214.695786)
		(width 0.18288)
		(layer "In11.Cu")
		(net "M_H_CPU0_SB_DQ<9>")
	)
	(segment
		(start 433.34813 -215.218264)
		(end 433.15509 -215.025224)
		(width 0.18288)
		(layer "In11.Cu")
		(net "M_H_CPU0_SB_DQ<9>")
	)
	(segment
		(start 405.773128 -217.205052)
		(end 405.644096 -217.07602)
		(width 0.18288)
		(layer "In11.Cu")
		(net "M_H_CPU0_SB_DQ<9>")
	)
	(segment
		(start 403.799294 -219.16898)
		(end 403.799294 -219.441776)
		(width 0.18288)
		(layer "In11.Cu")
		(net "M_H_CPU0_SB_DQ<9>")
	)
	(segment
		(start 405.644096 -217.07602)
		(end 405.196294 -217.07602)
		(width 0.18288)
		(layer "In11.Cu")
		(net "M_H_CPU0_SB_DQ<9>")
	)
	(segment
		(start 374.819164 -233.840528)
		(end 374.804432 -233.831892)
		(width 0.088646)
		(layer "In11.Cu")
		(net "M_H_CPU0_SB_DQ<9>")
	)
	(segment
		(start 402.81733 -219.454984)
		(end 397.031464 -225.242628)
		(width 0.18288)
		(layer "In11.Cu")
		(net "M_H_CPU0_SB_DQ<9>")
	)
	(segment
		(start 422.581578 -215.435942)
		(end 421.577262 -216.440258)
		(width 0.18288)
		(layer "In11.Cu")
		(net "M_H_CPU0_SB_DQ<9>")
	)
	(segment
		(start 434.05171 -214.605362)
		(end 433.85867 -214.798402)
		(width 0.18288)
		(layer "In11.Cu")
		(net "M_H_CPU0_SB_DQ<9>")
	)
	(segment
		(start 413.89427 -215.473026)
		(end 413.070294 -215.473026)
		(width 0.18288)
		(layer "In11.Cu")
		(net "M_H_CPU0_SB_DQ<9>")
	)
	(segment
		(start 424.166792 -215.435942)
		(end 422.581578 -215.435942)
		(width 0.18288)
		(layer "In11.Cu")
		(net "M_H_CPU0_SB_DQ<9>")
	)
	(segment
		(start 433.15509 -214.798402)
		(end 432.96205 -214.605362)
		(width 0.18288)
		(layer "In11.Cu")
		(net "M_H_CPU0_SB_DQ<9>")
	)
	(segment
		(start 414.98393 -215.473026)
		(end 414.79089 -215.666066)
		(width 0.18288)
		(layer "In11.Cu")
		(net "M_H_CPU0_SB_DQ<9>")
	)
	(segment
		(start 431.053494 -214.888826)
		(end 429.867568 -214.888826)
		(width 0.18288)
		(layer "In11.Cu")
		(net "M_H_CPU0_SB_DQ<9>")
	)
	(segment
		(start 406.045924 -217.205052)
		(end 405.773128 -217.205052)
		(width 0.18288)
		(layer "In11.Cu")
		(net "M_H_CPU0_SB_DQ<9>")
	)
	(segment
		(start 375.758964 -233.840528)
		(end 375.744232 -233.831892)
		(width 0.088646)
		(layer "In11.Cu")
		(net "M_H_CPU0_SB_DQ<9>")
	)
	(segment
		(start 410.30906 -215.877648)
		(end 408.699716 -215.877648)
		(width 0.18288)
		(layer "In11.Cu")
		(net "M_H_CPU0_SB_DQ<9>")
	)
	(segment
		(start 404.582884 -217.68943)
		(end 404.582884 -217.962226)
		(width 0.18288)
		(layer "In11.Cu")
		(net "M_H_CPU0_SB_DQ<9>")
	)
	(segment
		(start 411.20568 -215.440006)
		(end 411.01264 -215.246966)
		(width 0.18288)
		(layer "In11.Cu")
		(net "M_H_CPU0_SB_DQ<9>")
	)
	(segment
		(start 450.296788 -220.502226)
		(end 448.427094 -220.502226)
		(width 0.18288)
		(layer "In11.Cu")
		(net "M_H_CPU0_SB_DQ<9>")
	)
	(segment
		(start 406.141682 -215.742266)
		(end 406.141682 -216.578434)
		(width 0.18288)
		(layer "In11.Cu")
		(net "M_H_CPU0_SB_DQ<9>")
	)
	(segment
		(start 410.5021 -215.440006)
		(end 410.5021 -215.684608)
		(width 0.18288)
		(layer "In11.Cu")
		(net "M_H_CPU0_SB_DQ<9>")
	)
	(segment
		(start 446.191894 -218.825826)
		(end 445.125094 -218.825826)
		(width 0.18288)
		(layer "In11.Cu")
		(net "M_H_CPU0_SB_DQ<9>")
	)
	(segment
		(start 406.884632 -215.964516)
		(end 406.884632 -215.742266)
		(width 0.18288)
		(layer "In11.Cu")
		(net "M_H_CPU0_SB_DQ<9>")
	)
	(segment
		(start 424.321732 -215.590882)
		(end 424.166792 -215.435942)
		(width 0.18288)
		(layer "In11.Cu")
		(net "M_H_CPU0_SB_DQ<9>")
	)
	(segment
		(start 427.878494 -214.888826)
		(end 427.675294 -214.685626)
		(width 0.18288)
		(layer "In11.Cu")
		(net "M_H_CPU0_SB_DQ<9>")
	)
	(segment
		(start 441.053474 -215.592406)
		(end 439.199274 -215.592406)
		(width 0.18288)
		(layer "In11.Cu")
		(net "M_H_CPU0_SB_DQ<9>")
	)
	(segment
		(start 415.83483 -215.473026)
		(end 414.98393 -215.473026)
		(width 0.18288)
		(layer "In11.Cu")
		(net "M_H_CPU0_SB_DQ<9>")
	)
	(segment
		(start 404.794466 -218.446604)
		(end 404.569676 -218.671394)
		(width 0.18288)
		(layer "In11.Cu")
		(net "M_H_CPU0_SB_DQ<9>")
	)
	(segment
		(start 433.15509 -215.025224)
		(end 433.15509 -214.798402)
		(width 0.18288)
		(layer "In11.Cu")
		(net "M_H_CPU0_SB_DQ<9>")
	)
	(segment
		(start 405.196294 -217.07602)
		(end 404.582884 -217.68943)
		(width 0.18288)
		(layer "In11.Cu")
		(net "M_H_CPU0_SB_DQ<9>")
	)
	(segment
		(start 448.427094 -220.502226)
		(end 447.893694 -219.968826)
		(width 0.18288)
		(layer "In11.Cu")
		(net "M_H_CPU0_SB_DQ<9>")
	)
	(segment
		(start 427.675294 -214.685626)
		(end 426.910754 -214.685626)
		(width 0.18288)
		(layer "In11.Cu")
		(net "M_H_CPU0_SB_DQ<9>")
	)
	(segment
		(start 404.29688 -218.671394)
		(end 404.085298 -218.459812)
		(width 0.18288)
		(layer "In11.Cu")
		(net "M_H_CPU0_SB_DQ<9>")
	)
	(segment
		(start 407.077672 -216.157556)
		(end 406.884632 -215.964516)
		(width 0.18288)
		(layer "In11.Cu")
		(net "M_H_CPU0_SB_DQ<9>")
	)
	(segment
		(start 442.254894 -216.336626)
		(end 441.797694 -216.336626)
		(width 0.18288)
		(layer "In11.Cu")
		(net "M_H_CPU0_SB_DQ<9>")
	)
	(segment
		(start 421.576246 -216.439242)
		(end 420.08171 -216.439242)
		(width 0.18288)
		(layer "In11.Cu")
		(net "M_H_CPU0_SB_DQ<9>")
	)
	(segment
		(start 421.577262 -216.440258)
		(end 421.576246 -216.439242)
		(width 0.18288)
		(layer "In11.Cu")
		(net "M_H_CPU0_SB_DQ<9>")
	)
	(segment
		(start 411.01264 -215.246966)
		(end 410.69514 -215.246966)
		(width 0.18288)
		(layer "In11.Cu")
		(net "M_H_CPU0_SB_DQ<9>")
	)
	(segment
		(start 411.39872 -215.877648)
		(end 411.20568 -215.684608)
		(width 0.18288)
		(layer "In11.Cu")
		(net "M_H_CPU0_SB_DQ<9>")
	)
	(segment
		(start 439.029094 -215.422226)
		(end 437.505094 -215.422226)
		(width 0.18288)
		(layer "In11.Cu")
		(net "M_H_CPU0_SB_DQ<9>")
	)
	(segment
		(start 419.928294 -216.285826)
		(end 416.64763 -216.285826)
		(width 0.18288)
		(layer "In11.Cu")
		(net "M_H_CPU0_SB_DQ<9>")
	)
	(segment
		(start 443.474094 -217.174826)
		(end 443.093094 -217.174826)
		(width 0.18288)
		(layer "In11.Cu")
		(net "M_H_CPU0_SB_DQ<9>")
	)
	(segment
		(start 428.970948 -213.990428)
		(end 428.970948 -214.695786)
		(width 0.18288)
		(layer "In11.Cu")
		(net "M_H_CPU0_SB_DQ<9>")
	)
	(segment
		(start 408.699716 -215.877648)
		(end 408.371294 -215.549226)
		(width 0.18288)
		(layer "In11.Cu")
		(net "M_H_CPU0_SB_DQ<9>")
	)
	(segment
		(start 377.633992 -233.837988)
		(end 377.623578 -233.831892)
		(width 0.088646)
		(layer "In11.Cu")
		(net "M_H_CPU0_SB_DQ<9>")
	)
	(segment
		(start 429.481488 -213.797388)
		(end 429.163988 -213.797388)
		(width 0.18288)
		(layer "In11.Cu")
		(net "M_H_CPU0_SB_DQ<9>")
	)
	(segment
		(start 414.79089 -215.837008)
		(end 414.59785 -216.030048)
		(width 0.18288)
		(layer "In11.Cu")
		(net "M_H_CPU0_SB_DQ<9>")
	)
	(segment
		(start 403.587712 -218.684602)
		(end 403.587712 -218.957398)
		(width 0.18288)
		(layer "In11.Cu")
		(net "M_H_CPU0_SB_DQ<9>")
	)
	(segment
		(start 428.970948 -214.695786)
		(end 428.777908 -214.888826)
		(width 0.18288)
		(layer "In11.Cu")
		(net "M_H_CPU0_SB_DQ<9>")
	)
	(segment
		(start 378.578364 -233.840528)
		(end 378.563632 -233.831892)
		(width 0.088646)
		(layer "In11.Cu")
		(net "M_H_CPU0_SB_DQ<9>")
	)
	(segment
		(start 403.301708 -219.666566)
		(end 403.090126 -219.454984)
		(width 0.18288)
		(layer "In11.Cu")
		(net "M_H_CPU0_SB_DQ<9>")
	)
	(segment
		(start 436.823866 -214.740998)
		(end 435.071266 -214.740998)
		(width 0.18288)
		(layer "In11.Cu")
		(net "M_H_CPU0_SB_DQ<9>")
	)
	(segment
		(start 435.071266 -214.740998)
		(end 434.93563 -214.605362)
		(width 0.18288)
		(layer "In11.Cu")
		(net "M_H_CPU0_SB_DQ<9>")
	)
	(segment
		(start 433.66563 -215.218264)
		(end 433.34813 -215.218264)
		(width 0.18288)
		(layer "In11.Cu")
		(net "M_H_CPU0_SB_DQ<9>")
	)
	(segment
		(start 434.93563 -214.605362)
		(end 434.05171 -214.605362)
		(width 0.18288)
		(layer "In11.Cu")
		(net "M_H_CPU0_SB_DQ<9>")
	)
	(segment
		(start 403.799294 -219.441776)
		(end 403.574504 -219.666566)
		(width 0.18288)
		(layer "In11.Cu")
		(net "M_H_CPU0_SB_DQ<9>")
	)
	(segment
		(start 403.812502 -218.459812)
		(end 403.587712 -218.684602)
		(width 0.18288)
		(layer "In11.Cu")
		(net "M_H_CPU0_SB_DQ<9>")
	)
	(segment
		(start 410.5021 -215.684608)
		(end 410.30906 -215.877648)
		(width 0.18288)
		(layer "In11.Cu")
		(net "M_H_CPU0_SB_DQ<9>")
	)
	(segment
		(start 386.469382 -233.907838)
		(end 386.364988 -233.907838)
		(width 0.088646)
		(layer "In11.Cu")
		(net "M_H_CPU0_SB_DQ<9>")
	)
	(segment
		(start 379.518164 -233.840528)
		(end 379.503432 -233.831892)
		(width 0.088646)
		(layer "In11.Cu")
		(net "M_H_CPU0_SB_DQ<9>")
	)
	(segment
		(start 429.163988 -213.797388)
		(end 428.970948 -213.990428)
		(width 0.18288)
		(layer "In11.Cu")
		(net "M_H_CPU0_SB_DQ<9>")
	)
	(segment
		(start 426.005498 -215.590882)
		(end 424.321732 -215.590882)
		(width 0.18288)
		(layer "In11.Cu")
		(net "M_H_CPU0_SB_DQ<9>")
	)
	(segment
		(start 371.999764 -233.840528)
		(end 371.88775 -233.774742)
		(width 0.088646)
		(layer "In11.Cu")
		(net "M_H_CPU0_SB_DQ<9>")
	)
	(segment
		(start 407.588212 -215.964516)
		(end 407.395172 -216.157556)
		(width 0.18288)
		(layer "In11.Cu")
		(net "M_H_CPU0_SB_DQ<9>")
	)
	(segment
		(start 445.125094 -218.825826)
		(end 443.474094 -217.174826)
		(width 0.18288)
		(layer "In11.Cu")
		(net "M_H_CPU0_SB_DQ<9>")
	)
	(segment
		(start 429.674528 -214.695786)
		(end 429.674528 -213.990428)
		(width 0.18288)
		(layer "In11.Cu")
		(net "M_H_CPU0_SB_DQ<9>")
	)
	(segment
		(start 407.395172 -216.157556)
		(end 407.077672 -216.157556)
		(width 0.18288)
		(layer "In11.Cu")
		(net "M_H_CPU0_SB_DQ<9>")
	)
	(segment
		(start 406.691592 -215.549226)
		(end 406.334722 -215.549226)
		(width 0.18288)
		(layer "In11.Cu")
		(net "M_H_CPU0_SB_DQ<9>")
	)
	(segment
		(start 404.569676 -218.671394)
		(end 404.29688 -218.671394)
		(width 0.18288)
		(layer "In11.Cu")
		(net "M_H_CPU0_SB_DQ<9>")
	)
	(segment
		(start 403.090126 -219.454984)
		(end 402.81733 -219.454984)
		(width 0.18288)
		(layer "In11.Cu")
		(net "M_H_CPU0_SB_DQ<9>")
	)
	(segment
		(start 406.884632 -215.742266)
		(end 406.691592 -215.549226)
		(width 0.18288)
		(layer "In11.Cu")
		(net "M_H_CPU0_SB_DQ<9>")
	)
	(segment
		(start 407.781252 -215.549226)
		(end 407.588212 -215.742266)
		(width 0.18288)
		(layer "In11.Cu")
		(net "M_H_CPU0_SB_DQ<9>")
	)
	(segment
		(start 410.69514 -215.246966)
		(end 410.5021 -215.440006)
		(width 0.18288)
		(layer "In11.Cu")
		(net "M_H_CPU0_SB_DQ<9>")
	)
	(segment
		(start 397.031464 -226.172268)
		(end 390.755124 -232.450386)
		(width 0.18288)
		(layer "In11.Cu")
		(net "M_H_CPU0_SB_DQ<9>")
	)
	(segment
		(start 420.08171 -216.439242)
		(end 419.928294 -216.285826)
		(width 0.18288)
		(layer "In11.Cu")
		(net "M_H_CPU0_SB_DQ<9>")
	)
	(segment
		(start 413.070294 -215.473026)
		(end 412.665672 -215.877648)
		(width 0.18288)
		(layer "In11.Cu")
		(net "M_H_CPU0_SB_DQ<9>")
	)
	(segment
		(start 406.141682 -216.578434)
		(end 406.270714 -216.707466)
		(width 0.18288)
		(layer "In11.Cu")
		(net "M_H_CPU0_SB_DQ<9>")
	)
	(segment
		(start 414.59785 -216.030048)
		(end 414.28035 -216.030048)
		(width 0.18288)
		(layer "In11.Cu")
		(net "M_H_CPU0_SB_DQ<9>")
	)
	(segment
		(start 404.582884 -217.962226)
		(end 404.794466 -218.173808)
		(width 0.18288)
		(layer "In11.Cu")
		(net "M_H_CPU0_SB_DQ<9>")
	)
	(segment
		(start 397.031464 -225.242628)
		(end 397.031464 -226.172268)
		(width 0.18288)
		(layer "In11.Cu")
		(net "M_H_CPU0_SB_DQ<9>")
	)
	(segment
		(start 412.665672 -215.877648)
		(end 411.39872 -215.877648)
		(width 0.18288)
		(layer "In11.Cu")
		(net "M_H_CPU0_SB_DQ<9>")
	)
	(arc
		(start 380.443232 -233.831892)
		(mid 380.256034 -233.781749)
		(end 380.068836 -233.831892)
		(width 0.088646)
		(layer "In11.Cu")
		(net "M_H_CPU0_SB_DQ<9>")
	)
	(arc
		(start 376.684032 -233.831892)
		(mid 376.496834 -233.781749)
		(end 376.309636 -233.831892)
		(width 0.088646)
		(layer "In11.Cu")
		(net "M_H_CPU0_SB_DQ<9>")
	)
	(arc
		(start 375.744232 -233.831892)
		(mid 375.557034 -233.781749)
		(end 375.369836 -233.831892)
		(width 0.088646)
		(layer "In11.Cu")
		(net "M_H_CPU0_SB_DQ<9>")
	)
	(arc
		(start 381.008636 -233.831892)
		(mid 380.725934 -233.907634)
		(end 380.443232 -233.831892)
		(width 0.088646)
		(layer "In11.Cu")
		(net "M_H_CPU0_SB_DQ<9>")
	)
	(arc
		(start 382.322832 -233.831892)
		(mid 382.135634 -233.781749)
		(end 381.948436 -233.831892)
		(width 0.088646)
		(layer "In11.Cu")
		(net "M_H_CPU0_SB_DQ<9>")
	)
	(arc
		(start 382.888236 -233.831892)
		(mid 382.605534 -233.907634)
		(end 382.322832 -233.831892)
		(width 0.088646)
		(layer "In11.Cu")
		(net "M_H_CPU0_SB_DQ<9>")
	)
	(arc
		(start 385.707636 -233.831892)
		(mid 385.424934 -233.907634)
		(end 385.142232 -233.831892)
		(width 0.088646)
		(layer "In11.Cu")
		(net "M_H_CPU0_SB_DQ<9>")
	)
	(arc
		(start 375.369836 -233.831892)
		(mid 375.095607 -233.907817)
		(end 374.819164 -233.840528)
		(width 0.088646)
		(layer "In11.Cu")
		(net "M_H_CPU0_SB_DQ<9>")
	)
	(arc
		(start 374.430036 -233.831892)
		(mid 374.147334 -233.907634)
		(end 373.864632 -233.831892)
		(width 0.088646)
		(layer "In11.Cu")
		(net "M_H_CPU0_SB_DQ<9>")
	)
	(arc
		(start 385.142232 -233.831892)
		(mid 384.955034 -233.781749)
		(end 384.767836 -233.831892)
		(width 0.088646)
		(layer "In11.Cu")
		(net "M_H_CPU0_SB_DQ<9>")
	)
	(arc
		(start 381.383032 -233.831892)
		(mid 381.195834 -233.781749)
		(end 381.008636 -233.831892)
		(width 0.088646)
		(layer "In11.Cu")
		(net "M_H_CPU0_SB_DQ<9>")
	)
	(arc
		(start 383.828036 -233.831892)
		(mid 383.545334 -233.907634)
		(end 383.262632 -233.831892)
		(width 0.088646)
		(layer "In11.Cu")
		(net "M_H_CPU0_SB_DQ<9>")
	)
	(arc
		(start 377.623578 -233.831892)
		(mid 377.43638 -233.781749)
		(end 377.249182 -233.831892)
		(width 0.088646)
		(layer "In11.Cu")
		(net "M_H_CPU0_SB_DQ<9>")
	)
	(arc
		(start 379.503432 -233.831892)
		(mid 379.316234 -233.781749)
		(end 379.129036 -233.831892)
		(width 0.088646)
		(layer "In11.Cu")
		(net "M_H_CPU0_SB_DQ<9>")
	)
	(arc
		(start 378.189236 -233.831892)
		(mid 377.912423 -233.907728)
		(end 377.633992 -233.837988)
		(width 0.088646)
		(layer "In11.Cu")
		(net "M_H_CPU0_SB_DQ<9>")
	)
	(arc
		(start 378.563632 -233.831892)
		(mid 378.376434 -233.781749)
		(end 378.189236 -233.831892)
		(width 0.088646)
		(layer "In11.Cu")
		(net "M_H_CPU0_SB_DQ<9>")
	)
	(arc
		(start 381.948436 -233.831892)
		(mid 381.665734 -233.907634)
		(end 381.383032 -233.831892)
		(width 0.088646)
		(layer "In11.Cu")
		(net "M_H_CPU0_SB_DQ<9>")
	)
	(arc
		(start 374.804432 -233.831892)
		(mid 374.617234 -233.781749)
		(end 374.430036 -233.831892)
		(width 0.088646)
		(layer "In11.Cu")
		(net "M_H_CPU0_SB_DQ<9>")
	)
	(arc
		(start 386.364988 -233.907838)
		(mid 386.218518 -233.888478)
		(end 386.082032 -233.831892)
		(width 0.088646)
		(layer "In11.Cu")
		(net "M_H_CPU0_SB_DQ<9>")
	)
	(arc
		(start 379.129036 -233.831892)
		(mid 378.854807 -233.907817)
		(end 378.578364 -233.840528)
		(width 0.088646)
		(layer "In11.Cu")
		(net "M_H_CPU0_SB_DQ<9>")
	)
	(arc
		(start 377.249182 -233.831892)
		(mid 376.972623 -233.907601)
		(end 376.694446 -233.837988)
		(width 0.088646)
		(layer "In11.Cu")
		(net "M_H_CPU0_SB_DQ<9>")
	)
	(arc
		(start 373.864632 -233.831892)
		(mid 373.677434 -233.781749)
		(end 373.490236 -233.831892)
		(width 0.088646)
		(layer "In11.Cu")
		(net "M_H_CPU0_SB_DQ<9>")
	)
	(arc
		(start 371.88775 -233.774742)
		(mid 371.593888 -233.576363)
		(end 371.32768 -233.34218)
		(width 0.088646)
		(layer "In11.Cu")
		(net "M_H_CPU0_SB_DQ<9>")
	)
	(arc
		(start 386.082032 -233.831892)
		(mid 385.894834 -233.781749)
		(end 385.707636 -233.831892)
		(width 0.088646)
		(layer "In11.Cu")
		(net "M_H_CPU0_SB_DQ<9>")
	)
	(arc
		(start 372.550436 -233.831892)
		(mid 372.276207 -233.907817)
		(end 371.999764 -233.840528)
		(width 0.088646)
		(layer "In11.Cu")
		(net "M_H_CPU0_SB_DQ<9>")
	)
	(arc
		(start 384.767836 -233.831892)
		(mid 384.485134 -233.907634)
		(end 384.202432 -233.831892)
		(width 0.088646)
		(layer "In11.Cu")
		(net "M_H_CPU0_SB_DQ<9>")
	)
	(arc
		(start 383.262632 -233.831892)
		(mid 383.075434 -233.781749)
		(end 382.888236 -233.831892)
		(width 0.088646)
		(layer "In11.Cu")
		(net "M_H_CPU0_SB_DQ<9>")
	)
	(arc
		(start 372.924832 -233.831892)
		(mid 372.737634 -233.781749)
		(end 372.550436 -233.831892)
		(width 0.088646)
		(layer "In11.Cu")
		(net "M_H_CPU0_SB_DQ<9>")
	)
	(arc
		(start 373.490236 -233.831892)
		(mid 373.216007 -233.907817)
		(end 372.939564 -233.840528)
		(width 0.088646)
		(layer "In11.Cu")
		(net "M_H_CPU0_SB_DQ<9>")
	)
	(arc
		(start 384.202432 -233.831892)
		(mid 384.015234 -233.781749)
		(end 383.828036 -233.831892)
		(width 0.088646)
		(layer "In11.Cu")
		(net "M_H_CPU0_SB_DQ<9>")
	)
	(arc
		(start 380.068836 -233.831892)
		(mid 379.794607 -233.907817)
		(end 379.518164 -233.840528)
		(width 0.088646)
		(layer "In11.Cu")
		(net "M_H_CPU0_SB_DQ<9>")
	)
	(arc
		(start 376.309636 -233.831892)
		(mid 376.035407 -233.907817)
		(end 375.758964 -233.840528)
		(width 0.088646)
		(layer "In11.Cu")
		(net "M_H_CPU0_SB_DQ<9>")
	)
	(segment
		(start 454.95845 -222.391732)
		(end 454.91146 -222.391732)
		(width 0.101854)
		(layer "F.Cu")
		(net "M_H_CPU0_SB_DQ<8>")
	)
	(segment
		(start 371.79758 -234.69219)
		(end 371.797834 -234.691936)
		(width 0.20066)
		(layer "F.Cu")
		(net "M_H_CPU0_SB_DQ<8>")
	)
	(segment
		(start 457.968096 -222.816928)
		(end 457.53655 -222.385382)
		(width 0.20066)
		(layer "F.Cu")
		(net "M_H_CPU0_SB_DQ<8>")
	)
	(segment
		(start 454.448672 -222.87738)
		(end 454.260712 -223.06534)
		(width 0.20066)
		(layer "F.Cu")
		(net "M_H_CPU0_SB_DQ<8>")
	)
	(segment
		(start 371.797834 -234.691936)
		(end 371.797834 -234.15625)
		(width 0.20066)
		(layer "F.Cu")
		(net "M_H_CPU0_SB_DQ<8>")
	)
	(segment
		(start 454.260712 -223.06534)
		(end 453.785478 -223.06534)
		(width 0.20066)
		(layer "F.Cu")
		(net "M_H_CPU0_SB_DQ<8>")
	)
	(segment
		(start 453.536812 -222.816674)
		(end 452.016114 -222.816674)
		(width 0.20066)
		(layer "F.Cu")
		(net "M_H_CPU0_SB_DQ<8>")
	)
	(segment
		(start 454.91146 -222.391732)
		(end 454.566782 -222.391732)
		(width 0.20066)
		(layer "F.Cu")
		(net "M_H_CPU0_SB_DQ<8>")
	)
	(segment
		(start 452.016114 -222.816674)
		(end 450.911214 -222.816674)
		(width 0.20066)
		(layer "F.Cu")
		(net "M_H_CPU0_SB_DQ<8>")
	)
	(segment
		(start 459.559914 -222.816674)
		(end 459.55966 -222.816928)
		(width 0.20066)
		(layer "F.Cu")
		(net "M_H_CPU0_SB_DQ<8>")
	)
	(segment
		(start 459.55966 -222.816928)
		(end 457.968096 -222.816928)
		(width 0.20066)
		(layer "F.Cu")
		(net "M_H_CPU0_SB_DQ<8>")
	)
	(segment
		(start 454.566782 -222.391732)
		(end 454.448672 -222.509842)
		(width 0.20066)
		(layer "F.Cu")
		(net "M_H_CPU0_SB_DQ<8>")
	)
	(segment
		(start 457.53655 -222.385382)
		(end 457.126594 -222.385382)
		(width 0.20066)
		(layer "F.Cu")
		(net "M_H_CPU0_SB_DQ<8>")
	)
	(segment
		(start 453.785478 -223.06534)
		(end 453.536812 -222.816674)
		(width 0.20066)
		(layer "F.Cu")
		(net "M_H_CPU0_SB_DQ<8>")
	)
	(segment
		(start 457.120244 -222.391732)
		(end 454.95845 -222.391732)
		(width 0.1016)
		(layer "F.Cu")
		(net "M_H_CPU0_SB_DQ<8>")
	)
	(segment
		(start 454.448672 -222.509842)
		(end 454.448672 -222.87738)
		(width 0.20066)
		(layer "F.Cu")
		(net "M_H_CPU0_SB_DQ<8>")
	)
	(segment
		(start 457.126594 -222.385382)
		(end 457.120244 -222.391732)
		(width 0.1016)
		(layer "F.Cu")
		(net "M_H_CPU0_SB_DQ<8>")
	)
	(segment
		(start 440.942476 -218.667076)
		(end 440.942476 -218.39428)
		(width 0.18288)
		(layer "In11.Cu")
		(net "M_H_CPU0_SB_DQ<8>")
	)
	(segment
		(start 424.60545 -217.28938)
		(end 424.459146 -217.143076)
		(width 0.18288)
		(layer "In11.Cu")
		(net "M_H_CPU0_SB_DQ<8>")
	)
	(segment
		(start 421.656764 -218.138756)
		(end 419.745414 -218.138756)
		(width 0.18288)
		(layer "In11.Cu")
		(net "M_H_CPU0_SB_DQ<8>")
	)
	(segment
		(start 410.488892 -218.137232)
		(end 410.488892 -217.580718)
		(width 0.18288)
		(layer "In11.Cu")
		(net "M_H_CPU0_SB_DQ<8>")
	)
	(segment
		(start 433.696618 -216.571322)
		(end 433.696618 -217.130122)
		(width 0.18288)
		(layer "In11.Cu")
		(net "M_H_CPU0_SB_DQ<8>")
	)
	(segment
		(start 418.338254 -218.138756)
		(end 418.145214 -218.331796)
		(width 0.18288)
		(layer "In11.Cu")
		(net "M_H_CPU0_SB_DQ<8>")
	)
	(segment
		(start 433.889658 -216.378282)
		(end 433.696618 -216.571322)
		(width 0.18288)
		(layer "In11.Cu")
		(net "M_H_CPU0_SB_DQ<8>")
	)
	(segment
		(start 375.839482 -234.645708)
		(end 375.82475 -234.654344)
		(width 0.088646)
		(layer "In11.Cu")
		(net "M_H_CPU0_SB_DQ<8>")
	)
	(segment
		(start 406.790144 -219.458032)
		(end 406.565354 -219.682822)
		(width 0.18288)
		(layer "In11.Cu")
		(net "M_H_CPU0_SB_DQ<8>")
	)
	(segment
		(start 417.441634 -218.91498)
		(end 417.441634 -218.331796)
		(width 0.18288)
		(layer "In11.Cu")
		(net "M_H_CPU0_SB_DQ<8>")
	)
	(segment
		(start 378.658882 -234.645708)
		(end 378.64415 -234.654344)
		(width 0.088646)
		(layer "In11.Cu")
		(net "M_H_CPU0_SB_DQ<8>")
	)
	(segment
		(start 406.348946 -218.744038)
		(end 406.790144 -219.185236)
		(width 0.18288)
		(layer "In11.Cu")
		(net "M_H_CPU0_SB_DQ<8>")
	)
	(segment
		(start 440.942476 -218.39428)
		(end 441.401962 -217.935048)
		(width 0.18288)
		(layer "In11.Cu")
		(net "M_H_CPU0_SB_DQ<8>")
	)
	(segment
		(start 446.280794 -220.845126)
		(end 445.036194 -220.845126)
		(width 0.18288)
		(layer "In11.Cu")
		(net "M_H_CPU0_SB_DQ<8>")
	)
	(segment
		(start 388.103364 -233.468164)
		(end 387.659626 -233.468164)
		(width 0.088646)
		(layer "In11.Cu")
		(net "M_H_CPU0_SB_DQ<8>")
	)
	(segment
		(start 429.838866 -217.43289)
		(end 429.645826 -217.62593)
		(width 0.18288)
		(layer "In11.Cu")
		(net "M_H_CPU0_SB_DQ<8>")
	)
	(segment
		(start 433.503578 -217.323162)
		(end 433.186078 -217.323162)
		(width 0.18288)
		(layer "In11.Cu")
		(net "M_H_CPU0_SB_DQ<8>")
	)
	(segment
		(start 405.85136 -219.241624)
		(end 405.578564 -219.241624)
		(width 0.18288)
		(layer "In11.Cu")
		(net "M_H_CPU0_SB_DQ<8>")
	)
	(segment
		(start 373.394732 -234.645708)
		(end 373.38889 -234.642152)
		(width 0.088646)
		(layer "In11.Cu")
		(net "M_H_CPU0_SB_DQ<8>")
	)
	(segment
		(start 412.514796 -217.428826)
		(end 411.385512 -217.428826)
		(width 0.18288)
		(layer "In11.Cu")
		(net "M_H_CPU0_SB_DQ<8>")
	)
	(segment
		(start 431.155094 -216.793826)
		(end 430.031906 -216.793826)
		(width 0.18288)
		(layer "In11.Cu")
		(net "M_H_CPU0_SB_DQ<8>")
	)
	(segment
		(start 441.440062 -218.891866)
		(end 441.167266 -218.891866)
		(width 0.18288)
		(layer "In11.Cu")
		(net "M_H_CPU0_SB_DQ<8>")
	)
	(segment
		(start 406.790144 -219.185236)
		(end 406.790144 -219.458032)
		(width 0.18288)
		(layer "In11.Cu")
		(net "M_H_CPU0_SB_DQ<8>")
	)
	(segment
		(start 437.327294 -217.124026)
		(end 436.647844 -216.444576)
		(width 0.18288)
		(layer "In11.Cu")
		(net "M_H_CPU0_SB_DQ<8>")
	)
	(segment
		(start 374.899682 -234.645708)
		(end 374.88495 -234.654344)
		(width 0.088646)
		(layer "In11.Cu")
		(net "M_H_CPU0_SB_DQ<8>")
	)
	(segment
		(start 422.652444 -217.143076)
		(end 421.656764 -218.138756)
		(width 0.18288)
		(layer "In11.Cu")
		(net "M_H_CPU0_SB_DQ<8>")
	)
	(segment
		(start 441.401962 -217.662252)
		(end 441.031376 -217.291666)
		(width 0.18288)
		(layer "In11.Cu")
		(net "M_H_CPU0_SB_DQ<8>")
	)
	(segment
		(start 419.552374 -218.91498)
		(end 419.359334 -219.10802)
		(width 0.18288)
		(layer "In11.Cu")
		(net "M_H_CPU0_SB_DQ<8>")
	)
	(segment
		(start 443.947296 -219.756228)
		(end 443.495938 -219.756228)
		(width 0.18288)
		(layer "In11.Cu")
		(net "M_H_CPU0_SB_DQ<8>")
	)
	(segment
		(start 425.428918 -217.29065)
		(end 425.335192 -217.29065)
		(width 0.18288)
		(layer "In11.Cu")
		(net "M_H_CPU0_SB_DQ<8>")
	)
	(segment
		(start 435.228492 -216.378282)
		(end 433.889658 -216.378282)
		(width 0.18288)
		(layer "In11.Cu")
		(net "M_H_CPU0_SB_DQ<8>")
	)
	(segment
		(start 435.8894 -216.444576)
		(end 435.889146 -216.444322)
		(width 0.18288)
		(layer "In11.Cu")
		(net "M_H_CPU0_SB_DQ<8>")
	)
	(segment
		(start 372.128288 -234.355132)
		(end 371.797834 -234.15625)
		(width 0.088646)
		(layer "In11.Cu")
		(net "M_H_CPU0_SB_DQ<8>")
	)
	(segment
		(start 411.192472 -217.621866)
		(end 411.192472 -218.137232)
		(width 0.18288)
		(layer "In11.Cu")
		(net "M_H_CPU0_SB_DQ<8>")
	)
	(segment
		(start 430.031906 -216.793826)
		(end 429.838866 -216.986866)
		(width 0.18288)
		(layer "In11.Cu")
		(net "M_H_CPU0_SB_DQ<8>")
	)
	(segment
		(start 441.401962 -217.935048)
		(end 441.401962 -217.662252)
		(width 0.18288)
		(layer "In11.Cu")
		(net "M_H_CPU0_SB_DQ<8>")
	)
	(segment
		(start 419.359334 -219.10802)
		(end 419.041834 -219.10802)
		(width 0.18288)
		(layer "In11.Cu")
		(net "M_H_CPU0_SB_DQ<8>")
	)
	(segment
		(start 409.098496 -217.387678)
		(end 408.911044 -217.200226)
		(width 0.18288)
		(layer "In11.Cu")
		(net "M_H_CPU0_SB_DQ<8>")
	)
	(segment
		(start 435.889146 -216.444322)
		(end 435.757066 -216.444068)
		(width 0.18288)
		(layer "In11.Cu")
		(net "M_H_CPU0_SB_DQ<8>")
	)
	(segment
		(start 405.081486 -219.608654)
		(end 391.221976 -233.468164)
		(width 0.18288)
		(layer "In11.Cu")
		(net "M_H_CPU0_SB_DQ<8>")
	)
	(segment
		(start 407.619962 -217.200226)
		(end 406.348946 -218.471242)
		(width 0.18288)
		(layer "In11.Cu")
		(net "M_H_CPU0_SB_DQ<8>")
	)
	(segment
		(start 425.335192 -217.29065)
		(end 424.89882 -217.28938)
		(width 0.18288)
		(layer "In11.Cu")
		(net "M_H_CPU0_SB_DQ<8>")
	)
	(segment
		(start 432.993038 -216.571322)
		(end 432.799998 -216.378282)
		(width 0.18288)
		(layer "In11.Cu")
		(net "M_H_CPU0_SB_DQ<8>")
	)
	(segment
		(start 418.145214 -218.331796)
		(end 418.145214 -218.91498)
		(width 0.18288)
		(layer "In11.Cu")
		(net "M_H_CPU0_SB_DQ<8>")
	)
	(segment
		(start 418.848794 -218.91498)
		(end 418.848794 -218.331796)
		(width 0.18288)
		(layer "In11.Cu")
		(net "M_H_CPU0_SB_DQ<8>")
	)
	(segment
		(start 429.135286 -216.986866)
		(end 428.942246 -216.793826)
		(width 0.18288)
		(layer "In11.Cu")
		(net "M_H_CPU0_SB_DQ<8>")
	)
	(segment
		(start 428.942246 -216.793826)
		(end 427.86554 -216.793826)
		(width 0.18288)
		(layer "In11.Cu")
		(net "M_H_CPU0_SB_DQ<8>")
	)
	(segment
		(start 408.911044 -217.200226)
		(end 407.619962 -217.200226)
		(width 0.18288)
		(layer "In11.Cu")
		(net "M_H_CPU0_SB_DQ<8>")
	)
	(segment
		(start 379.598936 -234.645708)
		(end 379.588522 -234.651804)
		(width 0.088646)
		(layer "In11.Cu")
		(net "M_H_CPU0_SB_DQ<8>")
	)
	(segment
		(start 384.297682 -234.645708)
		(end 384.287268 -234.651804)
		(width 0.088646)
		(layer "In11.Cu")
		(net "M_H_CPU0_SB_DQ<8>")
	)
	(segment
		(start 436.647844 -216.444576)
		(end 435.8894 -216.444576)
		(width 0.18288)
		(layer "In11.Cu")
		(net "M_H_CPU0_SB_DQ<8>")
	)
	(segment
		(start 445.036194 -220.845126)
		(end 443.947296 -219.756228)
		(width 0.18288)
		(layer "In11.Cu")
		(net "M_H_CPU0_SB_DQ<8>")
	)
	(segment
		(start 442.172344 -218.432634)
		(end 441.899548 -218.432634)
		(width 0.18288)
		(layer "In11.Cu")
		(net "M_H_CPU0_SB_DQ<8>")
	)
	(segment
		(start 427.86554 -216.793826)
		(end 427.22165 -217.437716)
		(width 0.18288)
		(layer "In11.Cu")
		(net "M_H_CPU0_SB_DQ<8>")
	)
	(segment
		(start 438.749694 -217.124026)
		(end 437.327294 -217.124026)
		(width 0.18288)
		(layer "In11.Cu")
		(net "M_H_CPU0_SB_DQ<8>")
	)
	(segment
		(start 443.495938 -219.756228)
		(end 442.172344 -218.432634)
		(width 0.18288)
		(layer "In11.Cu")
		(net "M_H_CPU0_SB_DQ<8>")
	)
	(segment
		(start 406.348946 -218.471242)
		(end 406.348946 -218.744038)
		(width 0.18288)
		(layer "In11.Cu")
		(net "M_H_CPU0_SB_DQ<8>")
	)
	(segment
		(start 432.799998 -216.378282)
		(end 431.570638 -216.378282)
		(width 0.18288)
		(layer "In11.Cu")
		(net "M_H_CPU0_SB_DQ<8>")
	)
	(segment
		(start 411.192472 -218.137232)
		(end 410.999432 -218.330272)
		(width 0.18288)
		(layer "In11.Cu")
		(net "M_H_CPU0_SB_DQ<8>")
	)
	(segment
		(start 417.952174 -219.10802)
		(end 417.634674 -219.10802)
		(width 0.18288)
		(layer "In11.Cu")
		(net "M_H_CPU0_SB_DQ<8>")
	)
	(segment
		(start 410.295852 -217.387678)
		(end 409.098496 -217.387678)
		(width 0.18288)
		(layer "In11.Cu")
		(net "M_H_CPU0_SB_DQ<8>")
	)
	(segment
		(start 424.459146 -217.143076)
		(end 422.652444 -217.143076)
		(width 0.18288)
		(layer "In11.Cu")
		(net "M_H_CPU0_SB_DQ<8>")
	)
	(segment
		(start 406.292558 -219.682822)
		(end 405.85136 -219.241624)
		(width 0.18288)
		(layer "In11.Cu")
		(net "M_H_CPU0_SB_DQ<8>")
	)
	(segment
		(start 416.802824 -218.138756)
		(end 415.864294 -217.200226)
		(width 0.18288)
		(layer "In11.Cu")
		(net "M_H_CPU0_SB_DQ<8>")
	)
	(segment
		(start 410.488892 -217.580718)
		(end 410.295852 -217.387678)
		(width 0.18288)
		(layer "In11.Cu")
		(net "M_H_CPU0_SB_DQ<8>")
	)
	(segment
		(start 419.041834 -219.10802)
		(end 418.848794 -218.91498)
		(width 0.18288)
		(layer "In11.Cu")
		(net "M_H_CPU0_SB_DQ<8>")
	)
	(segment
		(start 415.864294 -217.200226)
		(end 412.743396 -217.200226)
		(width 0.18288)
		(layer "In11.Cu")
		(net "M_H_CPU0_SB_DQ<8>")
	)
	(segment
		(start 380.538482 -234.645708)
		(end 380.528068 -234.651804)
		(width 0.088646)
		(layer "In11.Cu")
		(net "M_H_CPU0_SB_DQ<8>")
	)
	(segment
		(start 418.848794 -218.331796)
		(end 418.655754 -218.138756)
		(width 0.18288)
		(layer "In11.Cu")
		(net "M_H_CPU0_SB_DQ<8>")
	)
	(segment
		(start 387.659626 -233.468164)
		(end 386.532882 -234.594908)
		(width 0.088646)
		(layer "In11.Cu")
		(net "M_H_CPU0_SB_DQ<8>")
	)
	(segment
		(start 435.293262 -216.443052)
		(end 435.228492 -216.378282)
		(width 0.18288)
		(layer "In11.Cu")
		(net "M_H_CPU0_SB_DQ<8>")
	)
	(segment
		(start 381.478536 -234.645708)
		(end 381.468122 -234.651804)
		(width 0.088646)
		(layer "In11.Cu")
		(net "M_H_CPU0_SB_DQ<8>")
	)
	(segment
		(start 447.614294 -222.178626)
		(end 446.280794 -220.845126)
		(width 0.18288)
		(layer "In11.Cu")
		(net "M_H_CPU0_SB_DQ<8>")
	)
	(segment
		(start 441.899548 -218.432634)
		(end 441.440062 -218.891866)
		(width 0.18288)
		(layer "In11.Cu")
		(net "M_H_CPU0_SB_DQ<8>")
	)
	(segment
		(start 432.993038 -217.130122)
		(end 432.993038 -216.571322)
		(width 0.18288)
		(layer "In11.Cu")
		(net "M_H_CPU0_SB_DQ<8>")
	)
	(segment
		(start 450.911214 -222.816674)
		(end 450.911214 -222.510858)
		(width 0.18288)
		(layer "In11.Cu")
		(net "M_H_CPU0_SB_DQ<8>")
	)
	(segment
		(start 405.578564 -219.241624)
		(end 405.211534 -219.608654)
		(width 0.18288)
		(layer "In11.Cu")
		(net "M_H_CPU0_SB_DQ<8>")
	)
	(segment
		(start 386.532882 -234.594908)
		(end 386.364988 -234.594908)
		(width 0.088646)
		(layer "In11.Cu")
		(net "M_H_CPU0_SB_DQ<8>")
	)
	(segment
		(start 417.248594 -218.138756)
		(end 416.802824 -218.138756)
		(width 0.18288)
		(layer "In11.Cu")
		(net "M_H_CPU0_SB_DQ<8>")
	)
	(segment
		(start 424.89882 -217.28938)
		(end 424.60545 -217.28938)
		(width 0.18288)
		(layer "In11.Cu")
		(net "M_H_CPU0_SB_DQ<8>")
	)
	(segment
		(start 373.400574 -234.64901)
		(end 373.394732 -234.645708)
		(width 0.088646)
		(layer "In11.Cu")
		(net "M_H_CPU0_SB_DQ<8>")
	)
	(segment
		(start 429.135286 -217.43289)
		(end 429.135286 -216.986866)
		(width 0.18288)
		(layer "In11.Cu")
		(net "M_H_CPU0_SB_DQ<8>")
	)
	(segment
		(start 441.167266 -218.891866)
		(end 440.942476 -218.667076)
		(width 0.18288)
		(layer "In11.Cu")
		(net "M_H_CPU0_SB_DQ<8>")
	)
	(segment
		(start 385.237736 -234.645708)
		(end 385.227322 -234.651804)
		(width 0.088646)
		(layer "In11.Cu")
		(net "M_H_CPU0_SB_DQ<8>")
	)
	(segment
		(start 419.745414 -218.138756)
		(end 419.552374 -218.331796)
		(width 0.18288)
		(layer "In11.Cu")
		(net "M_H_CPU0_SB_DQ<8>")
	)
	(segment
		(start 435.757066 -216.444068)
		(end 435.293262 -216.443052)
		(width 0.18288)
		(layer "In11.Cu")
		(net "M_H_CPU0_SB_DQ<8>")
	)
	(segment
		(start 441.031376 -217.291666)
		(end 438.917334 -217.291666)
		(width 0.18288)
		(layer "In11.Cu")
		(net "M_H_CPU0_SB_DQ<8>")
	)
	(segment
		(start 391.221976 -233.468164)
		(end 388.103364 -233.468164)
		(width 0.18288)
		(layer "In11.Cu")
		(net "M_H_CPU0_SB_DQ<8>")
	)
	(segment
		(start 412.743396 -217.200226)
		(end 412.514796 -217.428826)
		(width 0.18288)
		(layer "In11.Cu")
		(net "M_H_CPU0_SB_DQ<8>")
	)
	(segment
		(start 405.211534 -219.608654)
		(end 405.081486 -219.608654)
		(width 0.18288)
		(layer "In11.Cu")
		(net "M_H_CPU0_SB_DQ<8>")
	)
	(segment
		(start 410.681932 -218.330272)
		(end 410.488892 -218.137232)
		(width 0.18288)
		(layer "In11.Cu")
		(net "M_H_CPU0_SB_DQ<8>")
	)
	(segment
		(start 410.999432 -218.330272)
		(end 410.681932 -218.330272)
		(width 0.18288)
		(layer "In11.Cu")
		(net "M_H_CPU0_SB_DQ<8>")
	)
	(segment
		(start 429.838866 -216.986866)
		(end 429.838866 -217.43289)
		(width 0.18288)
		(layer "In11.Cu")
		(net "M_H_CPU0_SB_DQ<8>")
	)
	(segment
		(start 450.458332 -222.178626)
		(end 447.614294 -222.178626)
		(width 0.18288)
		(layer "In11.Cu")
		(net "M_H_CPU0_SB_DQ<8>")
	)
	(segment
		(start 429.645826 -217.62593)
		(end 429.328326 -217.62593)
		(width 0.18288)
		(layer "In11.Cu")
		(net "M_H_CPU0_SB_DQ<8>")
	)
	(segment
		(start 411.385512 -217.428826)
		(end 411.192472 -217.621866)
		(width 0.18288)
		(layer "In11.Cu")
		(net "M_H_CPU0_SB_DQ<8>")
	)
	(segment
		(start 418.145214 -218.91498)
		(end 417.952174 -219.10802)
		(width 0.18288)
		(layer "In11.Cu")
		(net "M_H_CPU0_SB_DQ<8>")
	)
	(segment
		(start 433.696618 -217.130122)
		(end 433.503578 -217.323162)
		(width 0.18288)
		(layer "In11.Cu")
		(net "M_H_CPU0_SB_DQ<8>")
	)
	(segment
		(start 431.570638 -216.378282)
		(end 431.155094 -216.793826)
		(width 0.18288)
		(layer "In11.Cu")
		(net "M_H_CPU0_SB_DQ<8>")
	)
	(segment
		(start 417.634674 -219.10802)
		(end 417.441634 -218.91498)
		(width 0.18288)
		(layer "In11.Cu")
		(net "M_H_CPU0_SB_DQ<8>")
	)
	(segment
		(start 425.575984 -217.437716)
		(end 425.428918 -217.29065)
		(width 0.18288)
		(layer "In11.Cu")
		(net "M_H_CPU0_SB_DQ<8>")
	)
	(segment
		(start 429.328326 -217.62593)
		(end 429.135286 -217.43289)
		(width 0.18288)
		(layer "In11.Cu")
		(net "M_H_CPU0_SB_DQ<8>")
	)
	(segment
		(start 427.22165 -217.437716)
		(end 425.575984 -217.437716)
		(width 0.18288)
		(layer "In11.Cu")
		(net "M_H_CPU0_SB_DQ<8>")
	)
	(segment
		(start 376.779282 -234.645708)
		(end 376.76455 -234.654344)
		(width 0.088646)
		(layer "In11.Cu")
		(net "M_H_CPU0_SB_DQ<8>")
	)
	(segment
		(start 418.655754 -218.138756)
		(end 418.338254 -218.138756)
		(width 0.18288)
		(layer "In11.Cu")
		(net "M_H_CPU0_SB_DQ<8>")
	)
	(segment
		(start 450.822314 -222.421958)
		(end 450.458332 -222.178626)
		(width 0.18288)
		(layer "In11.Cu")
		(net "M_H_CPU0_SB_DQ<8>")
	)
	(segment
		(start 450.911214 -222.510858)
		(end 450.822314 -222.421958)
		(width 0.18288)
		(layer "In11.Cu")
		(net "M_H_CPU0_SB_DQ<8>")
	)
	(segment
		(start 438.917334 -217.291666)
		(end 438.749694 -217.124026)
		(width 0.18288)
		(layer "In11.Cu")
		(net "M_H_CPU0_SB_DQ<8>")
	)
	(segment
		(start 406.565354 -219.682822)
		(end 406.292558 -219.682822)
		(width 0.18288)
		(layer "In11.Cu")
		(net "M_H_CPU0_SB_DQ<8>")
	)
	(segment
		(start 417.441634 -218.331796)
		(end 417.248594 -218.138756)
		(width 0.18288)
		(layer "In11.Cu")
		(net "M_H_CPU0_SB_DQ<8>")
	)
	(segment
		(start 433.186078 -217.323162)
		(end 432.993038 -217.130122)
		(width 0.18288)
		(layer "In11.Cu")
		(net "M_H_CPU0_SB_DQ<8>")
	)
	(segment
		(start 419.552374 -218.331796)
		(end 419.552374 -218.91498)
		(width 0.18288)
		(layer "In11.Cu")
		(net "M_H_CPU0_SB_DQ<8>")
	)
	(arc
		(start 376.213878 -234.645708)
		(mid 376.02668 -234.595565)
		(end 375.839482 -234.645708)
		(width 0.088646)
		(layer "In11.Cu")
		(net "M_H_CPU0_SB_DQ<8>")
	)
	(arc
		(start 383.732532 -234.645708)
		(mid 383.545334 -234.595565)
		(end 383.358136 -234.645708)
		(width 0.088646)
		(layer "In11.Cu")
		(net "M_H_CPU0_SB_DQ<8>")
	)
	(arc
		(start 374.88495 -234.654344)
		(mid 374.608475 -234.721664)
		(end 374.334278 -234.645708)
		(width 0.088646)
		(layer "In11.Cu")
		(net "M_H_CPU0_SB_DQ<8>")
	)
	(arc
		(start 382.792732 -234.645708)
		(mid 382.605534 -234.595565)
		(end 382.418336 -234.645708)
		(width 0.088646)
		(layer "In11.Cu")
		(net "M_H_CPU0_SB_DQ<8>")
	)
	(arc
		(start 374.334278 -234.645708)
		(mid 374.14708 -234.595565)
		(end 373.959882 -234.645708)
		(width 0.088646)
		(layer "In11.Cu")
		(net "M_H_CPU0_SB_DQ<8>")
	)
	(arc
		(start 372.287038 -234.49788)
		(mid 372.214469 -234.418935)
		(end 372.128288 -234.355132)
		(width 0.088646)
		(layer "In11.Cu")
		(net "M_H_CPU0_SB_DQ<8>")
	)
	(arc
		(start 385.227322 -234.651804)
		(mid 384.94889 -234.72165)
		(end 384.672078 -234.645708)
		(width 0.088646)
		(layer "In11.Cu")
		(net "M_H_CPU0_SB_DQ<8>")
	)
	(arc
		(start 373.38889 -234.642152)
		(mid 373.204005 -234.595359)
		(end 373.020082 -234.645708)
		(width 0.088646)
		(layer "In11.Cu")
		(net "M_H_CPU0_SB_DQ<8>")
	)
	(arc
		(start 377.153678 -234.645708)
		(mid 376.96648 -234.595565)
		(end 376.779282 -234.645708)
		(width 0.088646)
		(layer "In11.Cu")
		(net "M_H_CPU0_SB_DQ<8>")
	)
	(arc
		(start 381.468122 -234.651804)
		(mid 381.18969 -234.72165)
		(end 380.912878 -234.645708)
		(width 0.088646)
		(layer "In11.Cu")
		(net "M_H_CPU0_SB_DQ<8>")
	)
	(arc
		(start 378.093478 -234.645708)
		(mid 377.90628 -234.595565)
		(end 377.719082 -234.645708)
		(width 0.088646)
		(layer "In11.Cu")
		(net "M_H_CPU0_SB_DQ<8>")
	)
	(arc
		(start 375.274078 -234.645708)
		(mid 375.08688 -234.595565)
		(end 374.899682 -234.645708)
		(width 0.088646)
		(layer "In11.Cu")
		(net "M_H_CPU0_SB_DQ<8>")
	)
	(arc
		(start 383.358136 -234.645708)
		(mid 383.075434 -234.721484)
		(end 382.792732 -234.645708)
		(width 0.088646)
		(layer "In11.Cu")
		(net "M_H_CPU0_SB_DQ<8>")
	)
	(arc
		(start 386.364988 -234.594908)
		(mid 386.267918 -234.607965)
		(end 386.177536 -234.645708)
		(width 0.088646)
		(layer "In11.Cu")
		(net "M_H_CPU0_SB_DQ<8>")
	)
	(arc
		(start 384.287268 -234.651804)
		(mid 384.00909 -234.721527)
		(end 383.732532 -234.645708)
		(width 0.088646)
		(layer "In11.Cu")
		(net "M_H_CPU0_SB_DQ<8>")
	)
	(arc
		(start 380.528068 -234.651804)
		(mid 380.24989 -234.721527)
		(end 379.973332 -234.645708)
		(width 0.088646)
		(layer "In11.Cu")
		(net "M_H_CPU0_SB_DQ<8>")
	)
	(arc
		(start 375.82475 -234.654344)
		(mid 375.548275 -234.721664)
		(end 375.274078 -234.645708)
		(width 0.088646)
		(layer "In11.Cu")
		(net "M_H_CPU0_SB_DQ<8>")
	)
	(arc
		(start 379.973332 -234.645708)
		(mid 379.786134 -234.595565)
		(end 379.598936 -234.645708)
		(width 0.088646)
		(layer "In11.Cu")
		(net "M_H_CPU0_SB_DQ<8>")
	)
	(arc
		(start 373.020082 -234.645708)
		(mid 372.625621 -234.710296)
		(end 372.287038 -234.49788)
		(width 0.088646)
		(layer "In11.Cu")
		(net "M_H_CPU0_SB_DQ<8>")
	)
	(arc
		(start 386.177536 -234.645708)
		(mid 385.894834 -234.721484)
		(end 385.612132 -234.645708)
		(width 0.088646)
		(layer "In11.Cu")
		(net "M_H_CPU0_SB_DQ<8>")
	)
	(arc
		(start 385.612132 -234.645708)
		(mid 385.424934 -234.595565)
		(end 385.237736 -234.645708)
		(width 0.088646)
		(layer "In11.Cu")
		(net "M_H_CPU0_SB_DQ<8>")
	)
	(arc
		(start 381.852932 -234.645708)
		(mid 381.665734 -234.595565)
		(end 381.478536 -234.645708)
		(width 0.088646)
		(layer "In11.Cu")
		(net "M_H_CPU0_SB_DQ<8>")
	)
	(arc
		(start 377.719082 -234.645708)
		(mid 377.43638 -234.721484)
		(end 377.153678 -234.645708)
		(width 0.088646)
		(layer "In11.Cu")
		(net "M_H_CPU0_SB_DQ<8>")
	)
	(arc
		(start 384.672078 -234.645708)
		(mid 384.48488 -234.595565)
		(end 384.297682 -234.645708)
		(width 0.088646)
		(layer "In11.Cu")
		(net "M_H_CPU0_SB_DQ<8>")
	)
	(arc
		(start 380.912878 -234.645708)
		(mid 380.72568 -234.595565)
		(end 380.538482 -234.645708)
		(width 0.088646)
		(layer "In11.Cu")
		(net "M_H_CPU0_SB_DQ<8>")
	)
	(arc
		(start 379.033278 -234.645708)
		(mid 378.84608 -234.595565)
		(end 378.658882 -234.645708)
		(width 0.088646)
		(layer "In11.Cu")
		(net "M_H_CPU0_SB_DQ<8>")
	)
	(arc
		(start 373.959882 -234.645708)
		(mid 373.680679 -234.721348)
		(end 373.400574 -234.64901)
		(width 0.088646)
		(layer "In11.Cu")
		(net "M_H_CPU0_SB_DQ<8>")
	)
	(arc
		(start 376.76455 -234.654344)
		(mid 376.488075 -234.721664)
		(end 376.213878 -234.645708)
		(width 0.088646)
		(layer "In11.Cu")
		(net "M_H_CPU0_SB_DQ<8>")
	)
	(arc
		(start 382.418336 -234.645708)
		(mid 382.135634 -234.721484)
		(end 381.852932 -234.645708)
		(width 0.088646)
		(layer "In11.Cu")
		(net "M_H_CPU0_SB_DQ<8>")
	)
	(arc
		(start 378.64415 -234.654344)
		(mid 378.367675 -234.721664)
		(end 378.093478 -234.645708)
		(width 0.088646)
		(layer "In11.Cu")
		(net "M_H_CPU0_SB_DQ<8>")
	)
	(arc
		(start 379.588522 -234.651804)
		(mid 379.31009 -234.72165)
		(end 379.033278 -234.645708)
		(width 0.088646)
		(layer "In11.Cu")
		(net "M_H_CPU0_SB_DQ<8>")
	)
	(segment
		(start 461.251554 -224.103692)
		(end 461.455516 -223.89973)
		(width 0.20066)
		(layer "F.Cu")
		(net "M_H_CPU0_SB_DQ<7>")
	)
	(segment
		(start 458.538326 -224.098612)
		(end 458.543152 -224.098612)
		(width 0.101854)
		(layer "F.Cu")
		(net "M_H_CPU0_SB_DQ<7>")
	)
	(segment
		(start 461.689704 -223.41459)
		(end 462.073752 -223.41459)
		(width 0.20066)
		(layer "F.Cu")
		(net "M_H_CPU0_SB_DQ<7>")
	)
	(segment
		(start 460.570326 -224.103692)
		(end 461.251554 -224.103692)
		(width 0.20066)
		(layer "F.Cu")
		(net "M_H_CPU0_SB_DQ<7>")
	)
	(segment
		(start 455.011282 -223.666558)
		(end 456.116182 -223.666558)
		(width 0.20066)
		(layer "F.Cu")
		(net "M_H_CPU0_SB_DQ<7>")
	)
	(segment
		(start 461.455516 -223.89973)
		(end 461.455516 -223.648778)
		(width 0.20066)
		(layer "F.Cu")
		(net "M_H_CPU0_SB_DQ<7>")
	)
	(segment
		(start 457.814426 -223.666558)
		(end 458.24648 -224.098612)
		(width 0.20066)
		(layer "F.Cu")
		(net "M_H_CPU0_SB_DQ<7>")
	)
	(segment
		(start 371.797834 -236.319568)
		(end 371.797834 -235.783882)
		(width 0.20066)
		(layer "F.Cu")
		(net "M_H_CPU0_SB_DQ<7>")
	)
	(segment
		(start 456.116182 -223.666558)
		(end 457.814426 -223.666558)
		(width 0.20066)
		(layer "F.Cu")
		(net "M_H_CPU0_SB_DQ<7>")
	)
	(segment
		(start 462.073752 -223.41459)
		(end 462.32572 -223.666558)
		(width 0.20066)
		(layer "F.Cu")
		(net "M_H_CPU0_SB_DQ<7>")
	)
	(segment
		(start 458.550264 -224.0915)
		(end 460.558134 -224.0915)
		(width 0.1016)
		(layer "F.Cu")
		(net "M_H_CPU0_SB_DQ<7>")
	)
	(segment
		(start 461.455516 -223.648778)
		(end 461.689704 -223.41459)
		(width 0.20066)
		(layer "F.Cu")
		(net "M_H_CPU0_SB_DQ<7>")
	)
	(segment
		(start 458.543152 -224.098612)
		(end 458.550264 -224.0915)
		(width 0.1016)
		(layer "F.Cu")
		(net "M_H_CPU0_SB_DQ<7>")
	)
	(segment
		(start 460.558134 -224.0915)
		(end 460.570326 -224.103692)
		(width 0.1016)
		(layer "F.Cu")
		(net "M_H_CPU0_SB_DQ<7>")
	)
	(segment
		(start 371.79758 -236.319822)
		(end 371.797834 -236.319568)
		(width 0.20066)
		(layer "F.Cu")
		(net "M_H_CPU0_SB_DQ<7>")
	)
	(segment
		(start 458.24648 -224.098612)
		(end 458.538326 -224.098612)
		(width 0.20066)
		(layer "F.Cu")
		(net "M_H_CPU0_SB_DQ<7>")
	)
	(segment
		(start 462.32572 -223.666558)
		(end 463.659982 -223.666558)
		(width 0.20066)
		(layer "F.Cu")
		(net "M_H_CPU0_SB_DQ<7>")
	)
	(segment
		(start 446.166494 -222.661226)
		(end 445.548258 -222.661226)
		(width 0.18288)
		(layer "In11.Cu")
		(net "M_H_CPU0_SB_DQ<7>")
	)
	(segment
		(start 421.172894 -219.841826)
		(end 420.169594 -219.841826)
		(width 0.18288)
		(layer "In11.Cu")
		(net "M_H_CPU0_SB_DQ<7>")
	)
	(segment
		(start 416.59937 -219.940632)
		(end 416.091624 -219.432886)
		(width 0.18288)
		(layer "In11.Cu")
		(net "M_H_CPU0_SB_DQ<7>")
	)
	(segment
		(start 373.400574 -235.291122)
		(end 373.394732 -235.294424)
		(width 0.088646)
		(layer "In11.Cu")
		(net "M_H_CPU0_SB_DQ<7>")
	)
	(segment
		(start 408.917394 -219.918026)
		(end 408.079194 -220.756226)
		(width 0.18288)
		(layer "In11.Cu")
		(net "M_H_CPU0_SB_DQ<7>")
	)
	(segment
		(start 442.386466 -219.892626)
		(end 441.005214 -219.892626)
		(width 0.18288)
		(layer "In11.Cu")
		(net "M_H_CPU0_SB_DQ<7>")
	)
	(segment
		(start 408.079194 -220.756226)
		(end 406.62987 -220.756226)
		(width 0.18288)
		(layer "In11.Cu")
		(net "M_H_CPU0_SB_DQ<7>")
	)
	(segment
		(start 387.6929 -235.130086)
		(end 387.436106 -235.38688)
		(width 0.088646)
		(layer "In11.Cu")
		(net "M_H_CPU0_SB_DQ<7>")
	)
	(segment
		(start 452.881238 -223.243394)
		(end 450.148452 -223.243394)
		(width 0.18288)
		(layer "In11.Cu")
		(net "M_H_CPU0_SB_DQ<7>")
	)
	(segment
		(start 453.331072 -222.79356)
		(end 452.881238 -223.243394)
		(width 0.18288)
		(layer "In11.Cu")
		(net "M_H_CPU0_SB_DQ<7>")
	)
	(segment
		(start 388.472426 -234.270804)
		(end 388.187184 -234.556046)
		(width 0.18288)
		(layer "In11.Cu")
		(net "M_H_CPU0_SB_DQ<7>")
	)
	(segment
		(start 435.339236 -217.29065)
		(end 434.499512 -218.130374)
		(width 0.18288)
		(layer "In11.Cu")
		(net "M_H_CPU0_SB_DQ<7>")
	)
	(segment
		(start 455.011282 -223.666558)
		(end 454.137268 -222.79356)
		(width 0.18288)
		(layer "In11.Cu")
		(net "M_H_CPU0_SB_DQ<7>")
	)
	(segment
		(start 439.689494 -218.978226)
		(end 439.398156 -218.978226)
		(width 0.18288)
		(layer "In11.Cu")
		(net "M_H_CPU0_SB_DQ<7>")
	)
	(segment
		(start 439.398156 -218.978226)
		(end 438.58307 -218.16314)
		(width 0.18288)
		(layer "In11.Cu")
		(net "M_H_CPU0_SB_DQ<7>")
	)
	(segment
		(start 425.351194 -218.990926)
		(end 422.500044 -218.990926)
		(width 0.18288)
		(layer "In11.Cu")
		(net "M_H_CPU0_SB_DQ<7>")
	)
	(segment
		(start 405.868378 -221.001082)
		(end 404.830788 -221.001082)
		(width 0.18288)
		(layer "In11.Cu")
		(net "M_H_CPU0_SB_DQ<7>")
	)
	(segment
		(start 445.548258 -222.661226)
		(end 443.58941 -220.702378)
		(width 0.18288)
		(layer "In11.Cu")
		(net "M_H_CPU0_SB_DQ<7>")
	)
	(segment
		(start 431.360326 -218.130374)
		(end 429.802036 -218.436698)
		(width 0.18288)
		(layer "In11.Cu")
		(net "M_H_CPU0_SB_DQ<7>")
	)
	(segment
		(start 391.561066 -234.270804)
		(end 388.472426 -234.270804)
		(width 0.18288)
		(layer "In11.Cu")
		(net "M_H_CPU0_SB_DQ<7>")
	)
	(segment
		(start 429.802036 -218.436698)
		(end 425.905422 -218.436698)
		(width 0.18288)
		(layer "In11.Cu")
		(net "M_H_CPU0_SB_DQ<7>")
	)
	(segment
		(start 372.653052 -235.33989)
		(end 371.797834 -235.783882)
		(width 0.088646)
		(layer "In11.Cu")
		(net "M_H_CPU0_SB_DQ<7>")
	)
	(segment
		(start 421.952674 -219.227146)
		(end 421.172894 -219.841826)
		(width 0.18288)
		(layer "In11.Cu")
		(net "M_H_CPU0_SB_DQ<7>")
	)
	(segment
		(start 440.105038 -218.99245)
		(end 439.703718 -218.99245)
		(width 0.18288)
		(layer "In11.Cu")
		(net "M_H_CPU0_SB_DQ<7>")
	)
	(segment
		(start 404.830788 -221.001082)
		(end 391.561066 -234.270804)
		(width 0.18288)
		(layer "In11.Cu")
		(net "M_H_CPU0_SB_DQ<7>")
	)
	(segment
		(start 420.169594 -219.841826)
		(end 420.070788 -219.940632)
		(width 0.18288)
		(layer "In11.Cu")
		(net "M_H_CPU0_SB_DQ<7>")
	)
	(segment
		(start 388.187184 -234.556046)
		(end 387.6929 -235.05033)
		(width 0.088646)
		(layer "In11.Cu")
		(net "M_H_CPU0_SB_DQ<7>")
	)
	(segment
		(start 384.297682 -235.294424)
		(end 384.287268 -235.288328)
		(width 0.088646)
		(layer "In11.Cu")
		(net "M_H_CPU0_SB_DQ<7>")
	)
	(segment
		(start 434.499512 -218.130374)
		(end 431.360326 -218.130374)
		(width 0.18288)
		(layer "In11.Cu")
		(net "M_H_CPU0_SB_DQ<7>")
	)
	(segment
		(start 454.137268 -222.79356)
		(end 453.331072 -222.79356)
		(width 0.18288)
		(layer "In11.Cu")
		(net "M_H_CPU0_SB_DQ<7>")
	)
	(segment
		(start 447.443352 -223.41586)
		(end 446.166494 -222.661226)
		(width 0.18288)
		(layer "In11.Cu")
		(net "M_H_CPU0_SB_DQ<7>")
	)
	(segment
		(start 387.436106 -235.38688)
		(end 386.296916 -235.38688)
		(width 0.088646)
		(layer "In11.Cu")
		(net "M_H_CPU0_SB_DQ<7>")
	)
	(segment
		(start 412.321502 -219.918026)
		(end 408.917394 -219.918026)
		(width 0.18288)
		(layer "In11.Cu")
		(net "M_H_CPU0_SB_DQ<7>")
	)
	(segment
		(start 379.598936 -235.294424)
		(end 379.588522 -235.288328)
		(width 0.088646)
		(layer "In11.Cu")
		(net "M_H_CPU0_SB_DQ<7>")
	)
	(segment
		(start 441.005214 -219.892626)
		(end 440.105038 -218.99245)
		(width 0.18288)
		(layer "In11.Cu")
		(net "M_H_CPU0_SB_DQ<7>")
	)
	(segment
		(start 375.280174 -235.291122)
		(end 375.26849 -235.297726)
		(width 0.088646)
		(layer "In11.Cu")
		(net "M_H_CPU0_SB_DQ<7>")
	)
	(segment
		(start 422.500044 -218.990926)
		(end 421.952674 -219.227146)
		(width 0.18288)
		(layer "In11.Cu")
		(net "M_H_CPU0_SB_DQ<7>")
	)
	(segment
		(start 377.719082 -235.294424)
		(end 377.70435 -235.285788)
		(width 0.088646)
		(layer "In11.Cu")
		(net "M_H_CPU0_SB_DQ<7>")
	)
	(segment
		(start 381.478536 -235.294424)
		(end 381.468122 -235.288328)
		(width 0.088646)
		(layer "In11.Cu")
		(net "M_H_CPU0_SB_DQ<7>")
	)
	(segment
		(start 376.779282 -235.294424)
		(end 376.76455 -235.285788)
		(width 0.088646)
		(layer "In11.Cu")
		(net "M_H_CPU0_SB_DQ<7>")
	)
	(segment
		(start 437.069992 -218.16314)
		(end 436.197502 -217.29065)
		(width 0.18288)
		(layer "In11.Cu")
		(net "M_H_CPU0_SB_DQ<7>")
	)
	(segment
		(start 450.148452 -223.243394)
		(end 449.975986 -223.41586)
		(width 0.18288)
		(layer "In11.Cu")
		(net "M_H_CPU0_SB_DQ<7>")
	)
	(segment
		(start 374.340374 -235.291122)
		(end 374.32869 -235.297726)
		(width 0.088646)
		(layer "In11.Cu")
		(net "M_H_CPU0_SB_DQ<7>")
	)
	(segment
		(start 449.975986 -223.41586)
		(end 447.443352 -223.41586)
		(width 0.18288)
		(layer "In11.Cu")
		(net "M_H_CPU0_SB_DQ<7>")
	)
	(segment
		(start 425.905422 -218.436698)
		(end 425.351194 -218.990926)
		(width 0.18288)
		(layer "In11.Cu")
		(net "M_H_CPU0_SB_DQ<7>")
	)
	(segment
		(start 386.296916 -235.38688)
		(end 386.294376 -235.384086)
		(width 0.088646)
		(layer "In11.Cu")
		(net "M_H_CPU0_SB_DQ<7>")
	)
	(segment
		(start 436.197502 -217.29065)
		(end 435.339236 -217.29065)
		(width 0.18288)
		(layer "In11.Cu")
		(net "M_H_CPU0_SB_DQ<7>")
	)
	(segment
		(start 387.6929 -235.05033)
		(end 387.6929 -235.130086)
		(width 0.088646)
		(layer "In11.Cu")
		(net "M_H_CPU0_SB_DQ<7>")
	)
	(segment
		(start 416.091624 -219.432886)
		(end 412.806642 -219.432886)
		(width 0.18288)
		(layer "In11.Cu")
		(net "M_H_CPU0_SB_DQ<7>")
	)
	(segment
		(start 443.58941 -220.702378)
		(end 443.196218 -220.702378)
		(width 0.18288)
		(layer "In11.Cu")
		(net "M_H_CPU0_SB_DQ<7>")
	)
	(segment
		(start 385.237482 -235.294424)
		(end 385.22275 -235.285788)
		(width 0.088646)
		(layer "In11.Cu")
		(net "M_H_CPU0_SB_DQ<7>")
	)
	(segment
		(start 420.070788 -219.940632)
		(end 416.59937 -219.940632)
		(width 0.18288)
		(layer "In11.Cu")
		(net "M_H_CPU0_SB_DQ<7>")
	)
	(segment
		(start 443.196218 -220.702378)
		(end 442.386466 -219.892626)
		(width 0.18288)
		(layer "In11.Cu")
		(net "M_H_CPU0_SB_DQ<7>")
	)
	(segment
		(start 386.177282 -235.294424)
		(end 386.16255 -235.285788)
		(width 0.088646)
		(layer "In11.Cu")
		(net "M_H_CPU0_SB_DQ<7>")
	)
	(segment
		(start 379.983746 -235.288328)
		(end 379.973332 -235.294424)
		(width 0.088646)
		(layer "In11.Cu")
		(net "M_H_CPU0_SB_DQ<7>")
	)
	(segment
		(start 412.806642 -219.432886)
		(end 412.321502 -219.918026)
		(width 0.18288)
		(layer "In11.Cu")
		(net "M_H_CPU0_SB_DQ<7>")
	)
	(segment
		(start 439.703718 -218.99245)
		(end 439.689494 -218.978226)
		(width 0.18288)
		(layer "In11.Cu")
		(net "M_H_CPU0_SB_DQ<7>")
	)
	(segment
		(start 438.58307 -218.16314)
		(end 437.069992 -218.16314)
		(width 0.18288)
		(layer "In11.Cu")
		(net "M_H_CPU0_SB_DQ<7>")
	)
	(segment
		(start 378.658882 -235.294424)
		(end 378.64415 -235.285788)
		(width 0.088646)
		(layer "In11.Cu")
		(net "M_H_CPU0_SB_DQ<7>")
	)
	(segment
		(start 406.62987 -220.756226)
		(end 405.868378 -221.001082)
		(width 0.18288)
		(layer "In11.Cu")
		(net "M_H_CPU0_SB_DQ<7>")
	)
	(arc
		(start 384.287268 -235.288328)
		(mid 384.00909 -235.218605)
		(end 383.732532 -235.294424)
		(width 0.088646)
		(layer "In11.Cu")
		(net "M_H_CPU0_SB_DQ<7>")
	)
	(arc
		(start 377.153678 -235.294424)
		(mid 376.96648 -235.344567)
		(end 376.779282 -235.294424)
		(width 0.088646)
		(layer "In11.Cu")
		(net "M_H_CPU0_SB_DQ<7>")
	)
	(arc
		(start 384.672078 -235.294424)
		(mid 384.48488 -235.344567)
		(end 384.297682 -235.294424)
		(width 0.088646)
		(layer "In11.Cu")
		(net "M_H_CPU0_SB_DQ<7>")
	)
	(arc
		(start 376.76455 -235.285788)
		(mid 376.488075 -235.218468)
		(end 376.213878 -235.294424)
		(width 0.088646)
		(layer "In11.Cu")
		(net "M_H_CPU0_SB_DQ<7>")
	)
	(arc
		(start 377.70435 -235.285788)
		(mid 377.427875 -235.218468)
		(end 377.153678 -235.294424)
		(width 0.088646)
		(layer "In11.Cu")
		(net "M_H_CPU0_SB_DQ<7>")
	)
	(arc
		(start 385.22275 -235.285788)
		(mid 384.946275 -235.218468)
		(end 384.672078 -235.294424)
		(width 0.088646)
		(layer "In11.Cu")
		(net "M_H_CPU0_SB_DQ<7>")
	)
	(arc
		(start 386.16255 -235.285788)
		(mid 385.886075 -235.218468)
		(end 385.611878 -235.294424)
		(width 0.088646)
		(layer "In11.Cu")
		(net "M_H_CPU0_SB_DQ<7>")
	)
	(arc
		(start 375.26849 -235.297726)
		(mid 375.083635 -235.344676)
		(end 374.899682 -235.294424)
		(width 0.088646)
		(layer "In11.Cu")
		(net "M_H_CPU0_SB_DQ<7>")
	)
	(arc
		(start 386.294376 -235.384086)
		(mid 386.281615 -235.371689)
		(end 386.268468 -235.359702)
		(width 0.088646)
		(layer "In11.Cu")
		(net "M_H_CPU0_SB_DQ<7>")
	)
	(arc
		(start 379.588522 -235.288328)
		(mid 379.31009 -235.218482)
		(end 379.033278 -235.294424)
		(width 0.088646)
		(layer "In11.Cu")
		(net "M_H_CPU0_SB_DQ<7>")
	)
	(arc
		(start 383.358136 -235.294424)
		(mid 383.075434 -235.218648)
		(end 382.792732 -235.294424)
		(width 0.088646)
		(layer "In11.Cu")
		(net "M_H_CPU0_SB_DQ<7>")
	)
	(arc
		(start 373.959882 -235.294424)
		(mid 373.680679 -235.218784)
		(end 373.400574 -235.291122)
		(width 0.088646)
		(layer "In11.Cu")
		(net "M_H_CPU0_SB_DQ<7>")
	)
	(arc
		(start 372.730776 -235.296456)
		(mid 372.692235 -235.318747)
		(end 372.653052 -235.33989)
		(width 0.088646)
		(layer "In11.Cu")
		(net "M_H_CPU0_SB_DQ<7>")
	)
	(arc
		(start 380.538482 -235.294424)
		(mid 380.261923 -235.218681)
		(end 379.983746 -235.288328)
		(width 0.088646)
		(layer "In11.Cu")
		(net "M_H_CPU0_SB_DQ<7>")
	)
	(arc
		(start 374.899682 -235.294424)
		(mid 374.620479 -235.218784)
		(end 374.340374 -235.291122)
		(width 0.088646)
		(layer "In11.Cu")
		(net "M_H_CPU0_SB_DQ<7>")
	)
	(arc
		(start 374.32869 -235.297726)
		(mid 374.143835 -235.344676)
		(end 373.959882 -235.294424)
		(width 0.088646)
		(layer "In11.Cu")
		(net "M_H_CPU0_SB_DQ<7>")
	)
	(arc
		(start 380.912878 -235.294424)
		(mid 380.72568 -235.344567)
		(end 380.538482 -235.294424)
		(width 0.088646)
		(layer "In11.Cu")
		(net "M_H_CPU0_SB_DQ<7>")
	)
	(arc
		(start 381.468122 -235.288328)
		(mid 381.18969 -235.218482)
		(end 380.912878 -235.294424)
		(width 0.088646)
		(layer "In11.Cu")
		(net "M_H_CPU0_SB_DQ<7>")
	)
	(arc
		(start 378.093478 -235.294424)
		(mid 377.90628 -235.344567)
		(end 377.719082 -235.294424)
		(width 0.088646)
		(layer "In11.Cu")
		(net "M_H_CPU0_SB_DQ<7>")
	)
	(arc
		(start 382.418336 -235.294424)
		(mid 382.135634 -235.218648)
		(end 381.852932 -235.294424)
		(width 0.088646)
		(layer "In11.Cu")
		(net "M_H_CPU0_SB_DQ<7>")
	)
	(arc
		(start 375.839482 -235.294424)
		(mid 375.560279 -235.218784)
		(end 375.280174 -235.291122)
		(width 0.088646)
		(layer "In11.Cu")
		(net "M_H_CPU0_SB_DQ<7>")
	)
	(arc
		(start 381.852932 -235.294424)
		(mid 381.665734 -235.344567)
		(end 381.478536 -235.294424)
		(width 0.088646)
		(layer "In11.Cu")
		(net "M_H_CPU0_SB_DQ<7>")
	)
	(arc
		(start 378.64415 -235.285788)
		(mid 378.367675 -235.218468)
		(end 378.093478 -235.294424)
		(width 0.088646)
		(layer "In11.Cu")
		(net "M_H_CPU0_SB_DQ<7>")
	)
	(arc
		(start 386.268468 -235.359702)
		(mid 386.224493 -235.324803)
		(end 386.177282 -235.294424)
		(width 0.088646)
		(layer "In11.Cu")
		(net "M_H_CPU0_SB_DQ<7>")
	)
	(arc
		(start 379.973332 -235.294424)
		(mid 379.786134 -235.344567)
		(end 379.598936 -235.294424)
		(width 0.088646)
		(layer "In11.Cu")
		(net "M_H_CPU0_SB_DQ<7>")
	)
	(arc
		(start 385.611878 -235.294424)
		(mid 385.42468 -235.344567)
		(end 385.237482 -235.294424)
		(width 0.088646)
		(layer "In11.Cu")
		(net "M_H_CPU0_SB_DQ<7>")
	)
	(arc
		(start 373.020336 -235.294424)
		(mid 372.875286 -235.256109)
		(end 372.730776 -235.296456)
		(width 0.088646)
		(layer "In11.Cu")
		(net "M_H_CPU0_SB_DQ<7>")
	)
	(arc
		(start 383.732532 -235.294424)
		(mid 383.545334 -235.344567)
		(end 383.358136 -235.294424)
		(width 0.088646)
		(layer "In11.Cu")
		(net "M_H_CPU0_SB_DQ<7>")
	)
	(arc
		(start 382.792732 -235.294424)
		(mid 382.605534 -235.344567)
		(end 382.418336 -235.294424)
		(width 0.088646)
		(layer "In11.Cu")
		(net "M_H_CPU0_SB_DQ<7>")
	)
	(arc
		(start 376.213878 -235.294424)
		(mid 376.02668 -235.344567)
		(end 375.839482 -235.294424)
		(width 0.088646)
		(layer "In11.Cu")
		(net "M_H_CPU0_SB_DQ<7>")
	)
	(arc
		(start 373.394732 -235.294424)
		(mid 373.207534 -235.344567)
		(end 373.020336 -235.294424)
		(width 0.088646)
		(layer "In11.Cu")
		(net "M_H_CPU0_SB_DQ<7>")
	)
	(arc
		(start 379.033278 -235.294424)
		(mid 378.84608 -235.344567)
		(end 378.658882 -235.294424)
		(width 0.088646)
		(layer "In11.Cu")
		(net "M_H_CPU0_SB_DQ<7>")
	)
	(segment
		(start 458.543152 -225.798634)
		(end 458.550264 -225.791522)
		(width 0.1016)
		(layer "F.Cu")
		(net "M_H_CPU0_SB_DQ<6>")
	)
	(segment
		(start 460.558134 -225.791522)
		(end 460.570326 -225.803714)
		(width 0.1016)
		(layer "F.Cu")
		(net "M_H_CPU0_SB_DQ<6>")
	)
	(segment
		(start 456.116182 -225.36658)
		(end 457.814426 -225.36658)
		(width 0.20066)
		(layer "F.Cu")
		(net "M_H_CPU0_SB_DQ<6>")
	)
	(segment
		(start 458.538326 -225.798634)
		(end 458.543152 -225.798634)
		(width 0.101854)
		(layer "F.Cu")
		(net "M_H_CPU0_SB_DQ<6>")
	)
	(segment
		(start 461.455516 -225.3488)
		(end 461.689704 -225.114612)
		(width 0.20066)
		(layer "F.Cu")
		(net "M_H_CPU0_SB_DQ<6>")
	)
	(segment
		(start 455.011282 -225.36658)
		(end 456.116182 -225.36658)
		(width 0.20066)
		(layer "F.Cu")
		(net "M_H_CPU0_SB_DQ<6>")
	)
	(segment
		(start 462.073752 -225.114612)
		(end 462.32572 -225.36658)
		(width 0.20066)
		(layer "F.Cu")
		(net "M_H_CPU0_SB_DQ<6>")
	)
	(segment
		(start 373.207534 -237.133892)
		(end 373.20728 -237.133638)
		(width 0.20066)
		(layer "F.Cu")
		(net "M_H_CPU0_SB_DQ<6>")
	)
	(segment
		(start 461.455516 -225.599752)
		(end 461.455516 -225.3488)
		(width 0.20066)
		(layer "F.Cu")
		(net "M_H_CPU0_SB_DQ<6>")
	)
	(segment
		(start 460.570326 -225.803714)
		(end 461.251554 -225.803714)
		(width 0.20066)
		(layer "F.Cu")
		(net "M_H_CPU0_SB_DQ<6>")
	)
	(segment
		(start 458.24648 -225.798634)
		(end 458.538326 -225.798634)
		(width 0.20066)
		(layer "F.Cu")
		(net "M_H_CPU0_SB_DQ<6>")
	)
	(segment
		(start 461.689704 -225.114612)
		(end 462.073752 -225.114612)
		(width 0.20066)
		(layer "F.Cu")
		(net "M_H_CPU0_SB_DQ<6>")
	)
	(segment
		(start 461.251554 -225.803714)
		(end 461.455516 -225.599752)
		(width 0.20066)
		(layer "F.Cu")
		(net "M_H_CPU0_SB_DQ<6>")
	)
	(segment
		(start 457.814426 -225.36658)
		(end 458.24648 -225.798634)
		(width 0.20066)
		(layer "F.Cu")
		(net "M_H_CPU0_SB_DQ<6>")
	)
	(segment
		(start 458.550264 -225.791522)
		(end 460.558134 -225.791522)
		(width 0.1016)
		(layer "F.Cu")
		(net "M_H_CPU0_SB_DQ<6>")
	)
	(segment
		(start 462.32572 -225.36658)
		(end 463.659982 -225.36658)
		(width 0.20066)
		(layer "F.Cu")
		(net "M_H_CPU0_SB_DQ<6>")
	)
	(segment
		(start 373.20728 -237.133638)
		(end 373.20728 -236.597952)
		(width 0.20066)
		(layer "F.Cu")
		(net "M_H_CPU0_SB_DQ<6>")
	)
	(segment
		(start 416.62096 -221.676976)
		(end 416.484054 -221.54007)
		(width 0.18288)
		(layer "In11.Cu")
		(net "M_H_CPU0_SB_DQ<6>")
	)
	(segment
		(start 454.00341 -224.358708)
		(end 452.304912 -224.358708)
		(width 0.18288)
		(layer "In11.Cu")
		(net "M_H_CPU0_SB_DQ<6>")
	)
	(segment
		(start 380.453392 -236.102144)
		(end 380.442978 -236.10824)
		(width 0.088646)
		(layer "In11.Cu")
		(net "M_H_CPU0_SB_DQ<6>")
	)
	(segment
		(start 412.778194 -221.53118)
		(end 412.587948 -221.721426)
		(width 0.18288)
		(layer "In11.Cu")
		(net "M_H_CPU0_SB_DQ<6>")
	)
	(segment
		(start 409.171394 -221.721426)
		(end 408.383994 -222.508826)
		(width 0.18288)
		(layer "In11.Cu")
		(net "M_H_CPU0_SB_DQ<6>")
	)
	(segment
		(start 384.217164 -236.099604)
		(end 384.202432 -236.10824)
		(width 0.088646)
		(layer "In11.Cu")
		(net "M_H_CPU0_SB_DQ<6>")
	)
	(segment
		(start 430.087532 -219.511626)
		(end 429.894492 -219.704666)
		(width 0.18288)
		(layer "In11.Cu")
		(net "M_H_CPU0_SB_DQ<6>")
	)
	(segment
		(start 429.894492 -220.206062)
		(end 429.701452 -220.399102)
		(width 0.18288)
		(layer "In11.Cu")
		(net "M_H_CPU0_SB_DQ<6>")
	)
	(segment
		(start 449.900294 -225.074226)
		(end 447.030094 -225.074226)
		(width 0.18288)
		(layer "In11.Cu")
		(net "M_H_CPU0_SB_DQ<6>")
	)
	(segment
		(start 419.92931 -221.54261)
		(end 419.794944 -221.676976)
		(width 0.18288)
		(layer "In11.Cu")
		(net "M_H_CPU0_SB_DQ<6>")
	)
	(segment
		(start 424.632628 -220.689932)
		(end 423.804588 -220.689932)
		(width 0.18288)
		(layer "In11.Cu")
		(net "M_H_CPU0_SB_DQ<6>")
	)
	(segment
		(start 423.804588 -220.689932)
		(end 423.662094 -220.832426)
		(width 0.18288)
		(layer "In11.Cu")
		(net "M_H_CPU0_SB_DQ<6>")
	)
	(segment
		(start 378.578364 -236.099604)
		(end 378.563632 -236.10824)
		(width 0.088646)
		(layer "In11.Cu")
		(net "M_H_CPU0_SB_DQ<6>")
	)
	(segment
		(start 438.570116 -219.840048)
		(end 435.973474 -219.840048)
		(width 0.18288)
		(layer "In11.Cu")
		(net "M_H_CPU0_SB_DQ<6>")
	)
	(segment
		(start 429.190912 -220.206062)
		(end 429.190912 -219.704666)
		(width 0.18288)
		(layer "In11.Cu")
		(net "M_H_CPU0_SB_DQ<6>")
	)
	(segment
		(start 419.794944 -221.676976)
		(end 416.62096 -221.676976)
		(width 0.18288)
		(layer "In11.Cu")
		(net "M_H_CPU0_SB_DQ<6>")
	)
	(segment
		(start 450.032374 -224.942146)
		(end 449.900294 -225.074226)
		(width 0.18288)
		(layer "In11.Cu")
		(net "M_H_CPU0_SB_DQ<6>")
	)
	(segment
		(start 431.45202 -219.960952)
		(end 431.002694 -219.511626)
		(width 0.18288)
		(layer "In11.Cu")
		(net "M_H_CPU0_SB_DQ<6>")
	)
	(segment
		(start 445.455294 -224.210626)
		(end 443.829694 -222.585026)
		(width 0.18288)
		(layer "In11.Cu")
		(net "M_H_CPU0_SB_DQ<6>")
	)
	(segment
		(start 387.46557 -236.032548)
		(end 386.36448 -236.032548)
		(width 0.088646)
		(layer "In11.Cu")
		(net "M_H_CPU0_SB_DQ<6>")
	)
	(segment
		(start 447.030094 -225.074226)
		(end 446.166494 -224.210626)
		(width 0.18288)
		(layer "In11.Cu")
		(net "M_H_CPU0_SB_DQ<6>")
	)
	(segment
		(start 435.972712 -219.84081)
		(end 435.621176 -219.84081)
		(width 0.18288)
		(layer "In11.Cu")
		(net "M_H_CPU0_SB_DQ<6>")
	)
	(segment
		(start 435.13375 -219.840048)
		(end 435.012846 -219.960952)
		(width 0.18288)
		(layer "In11.Cu")
		(net "M_H_CPU0_SB_DQ<6>")
	)
	(segment
		(start 422.239694 -220.832426)
		(end 421.52951 -221.54261)
		(width 0.18288)
		(layer "In11.Cu")
		(net "M_H_CPU0_SB_DQ<6>")
	)
	(segment
		(start 429.701452 -220.399102)
		(end 429.383952 -220.399102)
		(width 0.18288)
		(layer "In11.Cu")
		(net "M_H_CPU0_SB_DQ<6>")
	)
	(segment
		(start 385.156964 -236.099604)
		(end 385.142232 -236.10824)
		(width 0.088646)
		(layer "In11.Cu")
		(net "M_H_CPU0_SB_DQ<6>")
	)
	(segment
		(start 443.829694 -222.585026)
		(end 443.369954 -222.585026)
		(width 0.18288)
		(layer "In11.Cu")
		(net "M_H_CPU0_SB_DQ<6>")
	)
	(segment
		(start 429.190912 -219.704666)
		(end 428.997872 -219.511626)
		(width 0.18288)
		(layer "In11.Cu")
		(net "M_H_CPU0_SB_DQ<6>")
	)
	(segment
		(start 423.662094 -220.832426)
		(end 422.239694 -220.832426)
		(width 0.18288)
		(layer "In11.Cu")
		(net "M_H_CPU0_SB_DQ<6>")
	)
	(segment
		(start 414.91916 -221.53118)
		(end 412.778194 -221.53118)
		(width 0.18288)
		(layer "In11.Cu")
		(net "M_H_CPU0_SB_DQ<6>")
	)
	(segment
		(start 441.25007 -221.619826)
		(end 440.321192 -220.690948)
		(width 0.18288)
		(layer "In11.Cu")
		(net "M_H_CPU0_SB_DQ<6>")
	)
	(segment
		(start 435.621176 -219.84081)
		(end 435.620414 -219.840048)
		(width 0.18288)
		(layer "In11.Cu")
		(net "M_H_CPU0_SB_DQ<6>")
	)
	(segment
		(start 414.92805 -221.54007)
		(end 414.91916 -221.53118)
		(width 0.18288)
		(layer "In11.Cu")
		(net "M_H_CPU0_SB_DQ<6>")
	)
	(segment
		(start 426.379894 -219.994226)
		(end 425.683172 -220.690948)
		(width 0.18288)
		(layer "In11.Cu")
		(net "M_H_CPU0_SB_DQ<6>")
	)
	(segment
		(start 446.166494 -224.210626)
		(end 445.455294 -224.210626)
		(width 0.18288)
		(layer "In11.Cu")
		(net "M_H_CPU0_SB_DQ<6>")
	)
	(segment
		(start 388.211314 -235.286804)
		(end 387.46557 -236.032548)
		(width 0.088646)
		(layer "In11.Cu")
		(net "M_H_CPU0_SB_DQ<6>")
	)
	(segment
		(start 389.043164 -235.286804)
		(end 388.211314 -235.286804)
		(width 0.088646)
		(layer "In11.Cu")
		(net "M_H_CPU0_SB_DQ<6>")
	)
	(segment
		(start 412.587948 -221.721426)
		(end 409.171394 -221.721426)
		(width 0.18288)
		(layer "In11.Cu")
		(net "M_H_CPU0_SB_DQ<6>")
	)
	(segment
		(start 439.864246 -220.690948)
		(end 439.86323 -220.689932)
		(width 0.18288)
		(layer "In11.Cu")
		(net "M_H_CPU0_SB_DQ<6>")
	)
	(segment
		(start 406.687782 -223.143826)
		(end 404.17877 -223.143826)
		(width 0.18288)
		(layer "In11.Cu")
		(net "M_H_CPU0_SB_DQ<6>")
	)
	(segment
		(start 421.52951 -221.54261)
		(end 419.92931 -221.54261)
		(width 0.18288)
		(layer "In11.Cu")
		(net "M_H_CPU0_SB_DQ<6>")
	)
	(segment
		(start 424.633644 -220.690948)
		(end 424.632628 -220.689932)
		(width 0.18288)
		(layer "In11.Cu")
		(net "M_H_CPU0_SB_DQ<6>")
	)
	(segment
		(start 427.243494 -219.994226)
		(end 426.379894 -219.994226)
		(width 0.18288)
		(layer "In11.Cu")
		(net "M_H_CPU0_SB_DQ<6>")
	)
	(segment
		(start 377.638564 -236.099604)
		(end 377.623832 -236.10824)
		(width 0.088646)
		(layer "In11.Cu")
		(net "M_H_CPU0_SB_DQ<6>")
	)
	(segment
		(start 408.383994 -222.508826)
		(end 407.322782 -222.508826)
		(width 0.18288)
		(layer "In11.Cu")
		(net "M_H_CPU0_SB_DQ<6>")
	)
	(segment
		(start 404.17877 -223.143826)
		(end 392.035792 -235.286804)
		(width 0.18288)
		(layer "In11.Cu")
		(net "M_H_CPU0_SB_DQ<6>")
	)
	(segment
		(start 425.683172 -220.690948)
		(end 424.633644 -220.690948)
		(width 0.18288)
		(layer "In11.Cu")
		(net "M_H_CPU0_SB_DQ<6>")
	)
	(segment
		(start 435.620414 -219.840048)
		(end 435.13375 -219.840048)
		(width 0.18288)
		(layer "In11.Cu")
		(net "M_H_CPU0_SB_DQ<6>")
	)
	(segment
		(start 440.321192 -220.690948)
		(end 439.864246 -220.690948)
		(width 0.18288)
		(layer "In11.Cu")
		(net "M_H_CPU0_SB_DQ<6>")
	)
	(segment
		(start 373.77878 -236.168946)
		(end 373.20728 -236.597952)
		(width 0.088646)
		(layer "In11.Cu")
		(net "M_H_CPU0_SB_DQ<6>")
	)
	(segment
		(start 407.322782 -222.508826)
		(end 406.687782 -223.143826)
		(width 0.18288)
		(layer "In11.Cu")
		(net "M_H_CPU0_SB_DQ<6>")
	)
	(segment
		(start 452.304912 -224.358708)
		(end 451.721474 -224.942146)
		(width 0.18288)
		(layer "In11.Cu")
		(net "M_H_CPU0_SB_DQ<6>")
	)
	(segment
		(start 429.894492 -219.704666)
		(end 429.894492 -220.206062)
		(width 0.18288)
		(layer "In11.Cu")
		(net "M_H_CPU0_SB_DQ<6>")
	)
	(segment
		(start 383.277364 -236.099604)
		(end 383.262632 -236.10824)
		(width 0.088646)
		(layer "In11.Cu")
		(net "M_H_CPU0_SB_DQ<6>")
	)
	(segment
		(start 427.726094 -219.511626)
		(end 427.243494 -219.994226)
		(width 0.18288)
		(layer "In11.Cu")
		(net "M_H_CPU0_SB_DQ<6>")
	)
	(segment
		(start 375.758964 -236.099604)
		(end 375.744232 -236.10824)
		(width 0.088646)
		(layer "In11.Cu")
		(net "M_H_CPU0_SB_DQ<6>")
	)
	(segment
		(start 435.973474 -219.840048)
		(end 435.972712 -219.84081)
		(width 0.18288)
		(layer "In11.Cu")
		(net "M_H_CPU0_SB_DQ<6>")
	)
	(segment
		(start 455.011282 -225.36658)
		(end 454.00341 -224.358708)
		(width 0.18288)
		(layer "In11.Cu")
		(net "M_H_CPU0_SB_DQ<6>")
	)
	(segment
		(start 439.86323 -220.689932)
		(end 439.42 -220.689932)
		(width 0.18288)
		(layer "In11.Cu")
		(net "M_H_CPU0_SB_DQ<6>")
	)
	(segment
		(start 443.369954 -222.585026)
		(end 442.404754 -221.619826)
		(width 0.18288)
		(layer "In11.Cu")
		(net "M_H_CPU0_SB_DQ<6>")
	)
	(segment
		(start 416.484054 -221.54007)
		(end 414.92805 -221.54007)
		(width 0.18288)
		(layer "In11.Cu")
		(net "M_H_CPU0_SB_DQ<6>")
	)
	(segment
		(start 428.997872 -219.511626)
		(end 427.726094 -219.511626)
		(width 0.18288)
		(layer "In11.Cu")
		(net "M_H_CPU0_SB_DQ<6>")
	)
	(segment
		(start 431.002694 -219.511626)
		(end 430.087532 -219.511626)
		(width 0.18288)
		(layer "In11.Cu")
		(net "M_H_CPU0_SB_DQ<6>")
	)
	(segment
		(start 373.874792 -236.102144)
		(end 373.835676 -236.125004)
		(width 0.088646)
		(layer "In11.Cu")
		(net "M_H_CPU0_SB_DQ<6>")
	)
	(segment
		(start 439.42 -220.689932)
		(end 438.570116 -219.840048)
		(width 0.18288)
		(layer "In11.Cu")
		(net "M_H_CPU0_SB_DQ<6>")
	)
	(segment
		(start 435.012846 -219.960952)
		(end 431.45202 -219.960952)
		(width 0.18288)
		(layer "In11.Cu")
		(net "M_H_CPU0_SB_DQ<6>")
	)
	(segment
		(start 379.513846 -236.102144)
		(end 379.503432 -236.10824)
		(width 0.088646)
		(layer "In11.Cu")
		(net "M_H_CPU0_SB_DQ<6>")
	)
	(segment
		(start 442.404754 -221.619826)
		(end 441.25007 -221.619826)
		(width 0.18288)
		(layer "In11.Cu")
		(net "M_H_CPU0_SB_DQ<6>")
	)
	(segment
		(start 429.383952 -220.399102)
		(end 429.190912 -220.206062)
		(width 0.18288)
		(layer "In11.Cu")
		(net "M_H_CPU0_SB_DQ<6>")
	)
	(segment
		(start 392.035792 -235.286804)
		(end 389.043164 -235.286804)
		(width 0.18288)
		(layer "In11.Cu")
		(net "M_H_CPU0_SB_DQ<6>")
	)
	(segment
		(start 451.721474 -224.942146)
		(end 450.032374 -224.942146)
		(width 0.18288)
		(layer "In11.Cu")
		(net "M_H_CPU0_SB_DQ<6>")
	)
	(segment
		(start 374.819164 -236.099604)
		(end 374.804432 -236.10824)
		(width 0.088646)
		(layer "In11.Cu")
		(net "M_H_CPU0_SB_DQ<6>")
	)
	(arc
		(start 378.189236 -236.10824)
		(mid 377.915007 -236.032315)
		(end 377.638564 -236.099604)
		(width 0.088646)
		(layer "In11.Cu")
		(net "M_H_CPU0_SB_DQ<6>")
	)
	(arc
		(start 385.142232 -236.10824)
		(mid 384.955034 -236.158383)
		(end 384.767836 -236.10824)
		(width 0.088646)
		(layer "In11.Cu")
		(net "M_H_CPU0_SB_DQ<6>")
	)
	(arc
		(start 383.262632 -236.10824)
		(mid 383.075434 -236.158383)
		(end 382.888236 -236.10824)
		(width 0.088646)
		(layer "In11.Cu")
		(net "M_H_CPU0_SB_DQ<6>")
	)
	(arc
		(start 383.828036 -236.10824)
		(mid 383.553807 -236.032315)
		(end 383.277364 -236.099604)
		(width 0.088646)
		(layer "In11.Cu")
		(net "M_H_CPU0_SB_DQ<6>")
	)
	(arc
		(start 374.804432 -236.10824)
		(mid 374.617234 -236.158383)
		(end 374.430036 -236.10824)
		(width 0.088646)
		(layer "In11.Cu")
		(net "M_H_CPU0_SB_DQ<6>")
	)
	(arc
		(start 377.249436 -236.10824)
		(mid 376.966734 -236.032498)
		(end 376.684032 -236.10824)
		(width 0.088646)
		(layer "In11.Cu")
		(net "M_H_CPU0_SB_DQ<6>")
	)
	(arc
		(start 384.767836 -236.10824)
		(mid 384.493607 -236.032315)
		(end 384.217164 -236.099604)
		(width 0.088646)
		(layer "In11.Cu")
		(net "M_H_CPU0_SB_DQ<6>")
	)
	(arc
		(start 378.563632 -236.10824)
		(mid 378.376434 -236.158383)
		(end 378.189236 -236.10824)
		(width 0.088646)
		(layer "In11.Cu")
		(net "M_H_CPU0_SB_DQ<6>")
	)
	(arc
		(start 382.888236 -236.10824)
		(mid 382.605534 -236.032498)
		(end 382.322832 -236.10824)
		(width 0.088646)
		(layer "In11.Cu")
		(net "M_H_CPU0_SB_DQ<6>")
	)
	(arc
		(start 380.068582 -236.10824)
		(mid 379.792023 -236.032531)
		(end 379.513846 -236.102144)
		(width 0.088646)
		(layer "In11.Cu")
		(net "M_H_CPU0_SB_DQ<6>")
	)
	(arc
		(start 386.082032 -236.10824)
		(mid 385.894834 -236.158383)
		(end 385.707636 -236.10824)
		(width 0.088646)
		(layer "In11.Cu")
		(net "M_H_CPU0_SB_DQ<6>")
	)
	(arc
		(start 385.707636 -236.10824)
		(mid 385.433407 -236.032315)
		(end 385.156964 -236.099604)
		(width 0.088646)
		(layer "In11.Cu")
		(net "M_H_CPU0_SB_DQ<6>")
	)
	(arc
		(start 380.442978 -236.10824)
		(mid 380.25578 -236.158383)
		(end 380.068582 -236.10824)
		(width 0.088646)
		(layer "In11.Cu")
		(net "M_H_CPU0_SB_DQ<6>")
	)
	(arc
		(start 376.684032 -236.10824)
		(mid 376.496834 -236.158383)
		(end 376.309636 -236.10824)
		(width 0.088646)
		(layer "In11.Cu")
		(net "M_H_CPU0_SB_DQ<6>")
	)
	(arc
		(start 374.430036 -236.10824)
		(mid 374.153223 -236.032404)
		(end 373.874792 -236.102144)
		(width 0.088646)
		(layer "In11.Cu")
		(net "M_H_CPU0_SB_DQ<6>")
	)
	(arc
		(start 381.008636 -236.10824)
		(mid 380.731823 -236.032404)
		(end 380.453392 -236.102144)
		(width 0.088646)
		(layer "In11.Cu")
		(net "M_H_CPU0_SB_DQ<6>")
	)
	(arc
		(start 382.322832 -236.10824)
		(mid 382.135634 -236.158383)
		(end 381.948436 -236.10824)
		(width 0.088646)
		(layer "In11.Cu")
		(net "M_H_CPU0_SB_DQ<6>")
	)
	(arc
		(start 381.948436 -236.10824)
		(mid 381.665734 -236.032498)
		(end 381.383032 -236.10824)
		(width 0.088646)
		(layer "In11.Cu")
		(net "M_H_CPU0_SB_DQ<6>")
	)
	(arc
		(start 377.623832 -236.10824)
		(mid 377.436634 -236.158383)
		(end 377.249436 -236.10824)
		(width 0.088646)
		(layer "In11.Cu")
		(net "M_H_CPU0_SB_DQ<6>")
	)
	(arc
		(start 373.835676 -236.125004)
		(mid 373.805821 -236.145153)
		(end 373.77878 -236.168946)
		(width 0.088646)
		(layer "In11.Cu")
		(net "M_H_CPU0_SB_DQ<6>")
	)
	(arc
		(start 386.36448 -236.032548)
		(mid 386.218284 -236.051835)
		(end 386.082032 -236.10824)
		(width 0.088646)
		(layer "In11.Cu")
		(net "M_H_CPU0_SB_DQ<6>")
	)
	(arc
		(start 375.369836 -236.10824)
		(mid 375.095607 -236.032315)
		(end 374.819164 -236.099604)
		(width 0.088646)
		(layer "In11.Cu")
		(net "M_H_CPU0_SB_DQ<6>")
	)
	(arc
		(start 384.202432 -236.10824)
		(mid 384.015234 -236.158383)
		(end 383.828036 -236.10824)
		(width 0.088646)
		(layer "In11.Cu")
		(net "M_H_CPU0_SB_DQ<6>")
	)
	(arc
		(start 375.744232 -236.10824)
		(mid 375.557034 -236.158383)
		(end 375.369836 -236.10824)
		(width 0.088646)
		(layer "In11.Cu")
		(net "M_H_CPU0_SB_DQ<6>")
	)
	(arc
		(start 381.383032 -236.10824)
		(mid 381.195834 -236.158383)
		(end 381.008636 -236.10824)
		(width 0.088646)
		(layer "In11.Cu")
		(net "M_H_CPU0_SB_DQ<6>")
	)
	(arc
		(start 379.503432 -236.10824)
		(mid 379.316234 -236.158383)
		(end 379.129036 -236.10824)
		(width 0.088646)
		(layer "In11.Cu")
		(net "M_H_CPU0_SB_DQ<6>")
	)
	(arc
		(start 379.129036 -236.10824)
		(mid 378.854807 -236.032315)
		(end 378.578364 -236.099604)
		(width 0.088646)
		(layer "In11.Cu")
		(net "M_H_CPU0_SB_DQ<6>")
	)
	(arc
		(start 376.309636 -236.10824)
		(mid 376.035407 -236.032315)
		(end 375.758964 -236.099604)
		(width 0.088646)
		(layer "In11.Cu")
		(net "M_H_CPU0_SB_DQ<6>")
	)
	(segment
		(start 454.931526 -224.091754)
		(end 454.91146 -224.091754)
		(width 0.101854)
		(layer "F.Cu")
		(net "M_H_CPU0_SB_DQ<5>")
	)
	(segment
		(start 459.559914 -224.516696)
		(end 459.55966 -224.51695)
		(width 0.20066)
		(layer "F.Cu")
		(net "M_H_CPU0_SB_DQ<5>")
	)
	(segment
		(start 372.737634 -236.319568)
		(end 372.737634 -235.783882)
		(width 0.20066)
		(layer "F.Cu")
		(net "M_H_CPU0_SB_DQ<5>")
	)
	(segment
		(start 452.016114 -224.516696)
		(end 450.911214 -224.516696)
		(width 0.20066)
		(layer "F.Cu")
		(net "M_H_CPU0_SB_DQ<5>")
	)
	(segment
		(start 453.785478 -224.765362)
		(end 453.536812 -224.516696)
		(width 0.20066)
		(layer "F.Cu")
		(net "M_H_CPU0_SB_DQ<5>")
	)
	(segment
		(start 454.260712 -224.765362)
		(end 453.785478 -224.765362)
		(width 0.20066)
		(layer "F.Cu")
		(net "M_H_CPU0_SB_DQ<5>")
	)
	(segment
		(start 459.55966 -224.51695)
		(end 457.968096 -224.51695)
		(width 0.20066)
		(layer "F.Cu")
		(net "M_H_CPU0_SB_DQ<5>")
	)
	(segment
		(start 457.53655 -224.085404)
		(end 457.126594 -224.085404)
		(width 0.20066)
		(layer "F.Cu")
		(net "M_H_CPU0_SB_DQ<5>")
	)
	(segment
		(start 454.448672 -224.577402)
		(end 454.260712 -224.765362)
		(width 0.20066)
		(layer "F.Cu")
		(net "M_H_CPU0_SB_DQ<5>")
	)
	(segment
		(start 454.566782 -224.091754)
		(end 454.448672 -224.209864)
		(width 0.20066)
		(layer "F.Cu")
		(net "M_H_CPU0_SB_DQ<5>")
	)
	(segment
		(start 457.968096 -224.51695)
		(end 457.53655 -224.085404)
		(width 0.20066)
		(layer "F.Cu")
		(net "M_H_CPU0_SB_DQ<5>")
	)
	(segment
		(start 454.91146 -224.091754)
		(end 454.566782 -224.091754)
		(width 0.20066)
		(layer "F.Cu")
		(net "M_H_CPU0_SB_DQ<5>")
	)
	(segment
		(start 457.126594 -224.085404)
		(end 457.120244 -224.091754)
		(width 0.1016)
		(layer "F.Cu")
		(net "M_H_CPU0_SB_DQ<5>")
	)
	(segment
		(start 372.73738 -236.319822)
		(end 372.737634 -236.319568)
		(width 0.20066)
		(layer "F.Cu")
		(net "M_H_CPU0_SB_DQ<5>")
	)
	(segment
		(start 457.120244 -224.091754)
		(end 454.931526 -224.091754)
		(width 0.1016)
		(layer "F.Cu")
		(net "M_H_CPU0_SB_DQ<5>")
	)
	(segment
		(start 454.448672 -224.209864)
		(end 454.448672 -224.577402)
		(width 0.20066)
		(layer "F.Cu")
		(net "M_H_CPU0_SB_DQ<5>")
	)
	(segment
		(start 453.536812 -224.516696)
		(end 452.016114 -224.516696)
		(width 0.20066)
		(layer "F.Cu")
		(net "M_H_CPU0_SB_DQ<5>")
	)
	(segment
		(start 413.737298 -220.690186)
		(end 413.544258 -220.883226)
		(width 0.18288)
		(layer "In11.Cu")
		(net "M_H_CPU0_SB_DQ<5>")
	)
	(segment
		(start 406.49525 -222.168974)
		(end 406.49525 -222.44177)
		(width 0.18288)
		(layer "In11.Cu")
		(net "M_H_CPU0_SB_DQ<5>")
	)
	(segment
		(start 433.50434 -219.326206)
		(end 433.3113 -219.133166)
		(width 0.18288)
		(layer "In11.Cu")
		(net "M_H_CPU0_SB_DQ<5>")
	)
	(segment
		(start 413.544258 -220.883226)
		(end 412.752794 -220.883226)
		(width 0.18288)
		(layer "In11.Cu")
		(net "M_H_CPU0_SB_DQ<5>")
	)
	(segment
		(start 416.130994 -220.883226)
		(end 414.633918 -220.883226)
		(width 0.18288)
		(layer "In11.Cu")
		(net "M_H_CPU0_SB_DQ<5>")
	)
	(segment
		(start 437.780684 -218.86799)
		(end 437.780684 -219.132912)
		(width 0.18288)
		(layer "In11.Cu")
		(net "M_H_CPU0_SB_DQ<5>")
	)
	(segment
		(start 414.633918 -220.883226)
		(end 414.440878 -220.690186)
		(width 0.18288)
		(layer "In11.Cu")
		(net "M_H_CPU0_SB_DQ<5>")
	)
	(segment
		(start 426.481494 -218.952826)
		(end 425.594272 -219.840048)
		(width 0.18288)
		(layer "In11.Cu")
		(net "M_H_CPU0_SB_DQ<5>")
	)
	(segment
		(start 413.737298 -220.272864)
		(end 413.737298 -220.690186)
		(width 0.18288)
		(layer "In11.Cu")
		(net "M_H_CPU0_SB_DQ<5>")
	)
	(segment
		(start 439.531252 -219.840048)
		(end 438.366154 -218.67495)
		(width 0.18288)
		(layer "In11.Cu")
		(net "M_H_CPU0_SB_DQ<5>")
	)
	(segment
		(start 421.416734 -220.690186)
		(end 420.090854 -220.690186)
		(width 0.18288)
		(layer "In11.Cu")
		(net "M_H_CPU0_SB_DQ<5>")
	)
	(segment
		(start 437.780684 -219.132912)
		(end 437.587644 -219.325952)
		(width 0.18288)
		(layer "In11.Cu")
		(net "M_H_CPU0_SB_DQ<5>")
	)
	(segment
		(start 431.897282 -218.642438)
		(end 431.586894 -218.952826)
		(width 0.18288)
		(layer "In11.Cu")
		(net "M_H_CPU0_SB_DQ<5>")
	)
	(segment
		(start 414.440878 -220.272864)
		(end 414.247838 -220.079824)
		(width 0.18288)
		(layer "In11.Cu")
		(net "M_H_CPU0_SB_DQ<5>")
	)
	(segment
		(start 414.440878 -220.690186)
		(end 414.440878 -220.272864)
		(width 0.18288)
		(layer "In11.Cu")
		(net "M_H_CPU0_SB_DQ<5>")
	)
	(segment
		(start 440.898026 -220.530674)
		(end 440.208162 -219.84081)
		(width 0.18288)
		(layer "In11.Cu")
		(net "M_H_CPU0_SB_DQ<5>")
	)
	(segment
		(start 445.353694 -223.194626)
		(end 443.602364 -221.443296)
		(width 0.18288)
		(layer "In11.Cu")
		(net "M_H_CPU0_SB_DQ<5>")
	)
	(segment
		(start 410.629862 -221.185486)
		(end 410.436822 -220.992446)
		(width 0.18288)
		(layer "In11.Cu")
		(net "M_H_CPU0_SB_DQ<5>")
	)
	(segment
		(start 389.043164 -234.778804)
		(end 388.366762 -234.778804)
		(width 0.088646)
		(layer "In11.Cu")
		(net "M_H_CPU0_SB_DQ<5>")
	)
	(segment
		(start 406.189434 -221.590362)
		(end 406.189434 -221.863158)
		(width 0.18288)
		(layer "In11.Cu")
		(net "M_H_CPU0_SB_DQ<5>")
	)
	(segment
		(start 438.366154 -218.67495)
		(end 437.973724 -218.67495)
		(width 0.18288)
		(layer "In11.Cu")
		(net "M_H_CPU0_SB_DQ<5>")
	)
	(segment
		(start 407.265632 -221.671388)
		(end 406.992836 -221.671388)
		(width 0.18288)
		(layer "In11.Cu")
		(net "M_H_CPU0_SB_DQ<5>")
	)
	(segment
		(start 410.436822 -220.992446)
		(end 410.436822 -220.771466)
		(width 0.18288)
		(layer "In11.Cu")
		(net "M_H_CPU0_SB_DQ<5>")
	)
	(segment
		(start 406.314148 -222.622872)
		(end 403.96287 -222.622872)
		(width 0.18288)
		(layer "In11.Cu")
		(net "M_H_CPU0_SB_DQ<5>")
	)
	(segment
		(start 440.208162 -219.84081)
		(end 439.861706 -219.84081)
		(width 0.18288)
		(layer "In11.Cu")
		(net "M_H_CPU0_SB_DQ<5>")
	)
	(segment
		(start 408.37739 -221.442026)
		(end 407.494994 -221.442026)
		(width 0.18288)
		(layer "In11.Cu")
		(net "M_H_CPU0_SB_DQ<5>")
	)
	(segment
		(start 433.3113 -218.835478)
		(end 433.11826 -218.642438)
		(width 0.18288)
		(layer "In11.Cu")
		(net "M_H_CPU0_SB_DQ<5>")
	)
	(segment
		(start 376.698764 -235.46816)
		(end 376.684032 -235.459524)
		(width 0.088646)
		(layer "In11.Cu")
		(net "M_H_CPU0_SB_DQ<5>")
	)
	(segment
		(start 407.494994 -221.442026)
		(end 407.265632 -221.671388)
		(width 0.18288)
		(layer "In11.Cu")
		(net "M_H_CPU0_SB_DQ<5>")
	)
	(segment
		(start 437.973724 -218.67495)
		(end 437.780684 -218.86799)
		(width 0.18288)
		(layer "In11.Cu")
		(net "M_H_CPU0_SB_DQ<5>")
	)
	(segment
		(start 439.861706 -219.84081)
		(end 439.860944 -219.840048)
		(width 0.18288)
		(layer "In11.Cu")
		(net "M_H_CPU0_SB_DQ<5>")
	)
	(segment
		(start 406.992836 -221.671388)
		(end 406.68702 -221.365572)
		(width 0.18288)
		(layer "In11.Cu")
		(net "M_H_CPU0_SB_DQ<5>")
	)
	(segment
		(start 437.077104 -218.86799)
		(end 436.884064 -218.67495)
		(width 0.18288)
		(layer "In11.Cu")
		(net "M_H_CPU0_SB_DQ<5>")
	)
	(segment
		(start 434.01488 -219.133166)
		(end 433.82184 -219.326206)
		(width 0.18288)
		(layer "In11.Cu")
		(net "M_H_CPU0_SB_DQ<5>")
	)
	(segment
		(start 377.638564 -235.46816)
		(end 377.623832 -235.459524)
		(width 0.088646)
		(layer "In11.Cu")
		(net "M_H_CPU0_SB_DQ<5>")
	)
	(segment
		(start 436.884064 -218.67495)
		(end 436.760366 -218.67495)
		(width 0.18288)
		(layer "In11.Cu")
		(net "M_H_CPU0_SB_DQ<5>")
	)
	(segment
		(start 416.511994 -220.502226)
		(end 416.130994 -220.883226)
		(width 0.18288)
		(layer "In11.Cu")
		(net "M_H_CPU0_SB_DQ<5>")
	)
	(segment
		(start 406.414224 -221.365572)
		(end 406.189434 -221.590362)
		(width 0.18288)
		(layer "In11.Cu")
		(net "M_H_CPU0_SB_DQ<5>")
	)
	(segment
		(start 406.68702 -221.365572)
		(end 406.414224 -221.365572)
		(width 0.18288)
		(layer "In11.Cu")
		(net "M_H_CPU0_SB_DQ<5>")
	)
	(segment
		(start 375.758964 -235.46816)
		(end 375.744232 -235.459524)
		(width 0.088646)
		(layer "In11.Cu")
		(net "M_H_CPU0_SB_DQ<5>")
	)
	(segment
		(start 380.068582 -235.459524)
		(end 380.058168 -235.46562)
		(width 0.088646)
		(layer "In11.Cu")
		(net "M_H_CPU0_SB_DQ<5>")
	)
	(segment
		(start 409.24099 -220.578426)
		(end 408.37739 -221.442026)
		(width 0.18288)
		(layer "In11.Cu")
		(net "M_H_CPU0_SB_DQ<5>")
	)
	(segment
		(start 434.876448 -218.642438)
		(end 434.20792 -218.642438)
		(width 0.18288)
		(layer "In11.Cu")
		(net "M_H_CPU0_SB_DQ<5>")
	)
	(segment
		(start 436.228236 -218.14282)
		(end 435.376066 -218.14282)
		(width 0.18288)
		(layer "In11.Cu")
		(net "M_H_CPU0_SB_DQ<5>")
	)
	(segment
		(start 450.911214 -224.253552)
		(end 450.690488 -224.032826)
		(width 0.18288)
		(layer "In11.Cu")
		(net "M_H_CPU0_SB_DQ<5>")
	)
	(segment
		(start 420.090854 -220.690186)
		(end 419.902894 -220.502226)
		(width 0.18288)
		(layer "In11.Cu")
		(net "M_H_CPU0_SB_DQ<5>")
	)
	(segment
		(start 433.11826 -218.642438)
		(end 431.897282 -218.642438)
		(width 0.18288)
		(layer "In11.Cu")
		(net "M_H_CPU0_SB_DQ<5>")
	)
	(segment
		(start 391.806938 -234.778804)
		(end 389.043164 -234.778804)
		(width 0.18288)
		(layer "In11.Cu")
		(net "M_H_CPU0_SB_DQ<5>")
	)
	(segment
		(start 373.41302 -235.518452)
		(end 373.173752 -235.75772)
		(width 0.088646)
		(layer "In11.Cu")
		(net "M_H_CPU0_SB_DQ<5>")
	)
	(segment
		(start 384.217164 -235.46816)
		(end 384.202432 -235.459524)
		(width 0.088646)
		(layer "In11.Cu")
		(net "M_H_CPU0_SB_DQ<5>")
	)
	(segment
		(start 443.195964 -221.443296)
		(end 442.283342 -220.530674)
		(width 0.18288)
		(layer "In11.Cu")
		(net "M_H_CPU0_SB_DQ<5>")
	)
	(segment
		(start 450.911214 -224.516696)
		(end 450.911214 -224.253552)
		(width 0.18288)
		(layer "In11.Cu")
		(net "M_H_CPU0_SB_DQ<5>")
	)
	(segment
		(start 437.587644 -219.325952)
		(end 437.270144 -219.325952)
		(width 0.18288)
		(layer "In11.Cu")
		(net "M_H_CPU0_SB_DQ<5>")
	)
	(segment
		(start 406.189434 -221.863158)
		(end 406.49525 -222.168974)
		(width 0.18288)
		(layer "In11.Cu")
		(net "M_H_CPU0_SB_DQ<5>")
	)
	(segment
		(start 378.578364 -235.46816)
		(end 378.563632 -235.459524)
		(width 0.088646)
		(layer "In11.Cu")
		(net "M_H_CPU0_SB_DQ<5>")
	)
	(segment
		(start 403.96287 -222.622872)
		(end 391.806938 -234.778804)
		(width 0.18288)
		(layer "In11.Cu")
		(net "M_H_CPU0_SB_DQ<5>")
	)
	(segment
		(start 410.947362 -221.185486)
		(end 410.629862 -221.185486)
		(width 0.18288)
		(layer "In11.Cu")
		(net "M_H_CPU0_SB_DQ<5>")
	)
	(segment
		(start 431.586894 -218.952826)
		(end 426.481494 -218.952826)
		(width 0.18288)
		(layer "In11.Cu")
		(net "M_H_CPU0_SB_DQ<5>")
	)
	(segment
		(start 442.283342 -220.530674)
		(end 440.898026 -220.530674)
		(width 0.18288)
		(layer "In11.Cu")
		(net "M_H_CPU0_SB_DQ<5>")
	)
	(segment
		(start 437.077104 -219.132912)
		(end 437.077104 -218.86799)
		(width 0.18288)
		(layer "In11.Cu")
		(net "M_H_CPU0_SB_DQ<5>")
	)
	(segment
		(start 410.436822 -220.771466)
		(end 410.243782 -220.578426)
		(width 0.18288)
		(layer "In11.Cu")
		(net "M_H_CPU0_SB_DQ<5>")
	)
	(segment
		(start 434.20792 -218.642438)
		(end 434.01488 -218.835478)
		(width 0.18288)
		(layer "In11.Cu")
		(net "M_H_CPU0_SB_DQ<5>")
	)
	(segment
		(start 419.902894 -220.502226)
		(end 416.511994 -220.502226)
		(width 0.18288)
		(layer "In11.Cu")
		(net "M_H_CPU0_SB_DQ<5>")
	)
	(segment
		(start 387.56844 -235.577126)
		(end 386.217922 -235.577126)
		(width 0.088646)
		(layer "In11.Cu")
		(net "M_H_CPU0_SB_DQ<5>")
	)
	(segment
		(start 412.752794 -220.883226)
		(end 412.447994 -220.578426)
		(width 0.18288)
		(layer "In11.Cu")
		(net "M_H_CPU0_SB_DQ<5>")
	)
	(segment
		(start 411.333442 -220.578426)
		(end 411.140402 -220.771466)
		(width 0.18288)
		(layer "In11.Cu")
		(net "M_H_CPU0_SB_DQ<5>")
	)
	(segment
		(start 436.760366 -218.67495)
		(end 436.228236 -218.14282)
		(width 0.18288)
		(layer "In11.Cu")
		(net "M_H_CPU0_SB_DQ<5>")
	)
	(segment
		(start 424.263058 -219.840048)
		(end 424.14952 -219.72651)
		(width 0.18288)
		(layer "In11.Cu")
		(net "M_H_CPU0_SB_DQ<5>")
	)
	(segment
		(start 410.243782 -220.578426)
		(end 409.24099 -220.578426)
		(width 0.18288)
		(layer "In11.Cu")
		(net "M_H_CPU0_SB_DQ<5>")
	)
	(segment
		(start 388.366762 -234.778804)
		(end 387.56844 -235.577126)
		(width 0.088646)
		(layer "In11.Cu")
		(net "M_H_CPU0_SB_DQ<5>")
	)
	(segment
		(start 411.140402 -220.992446)
		(end 410.947362 -221.185486)
		(width 0.18288)
		(layer "In11.Cu")
		(net "M_H_CPU0_SB_DQ<5>")
	)
	(segment
		(start 380.453392 -235.46562)
		(end 380.442978 -235.459524)
		(width 0.088646)
		(layer "In11.Cu")
		(net "M_H_CPU0_SB_DQ<5>")
	)
	(segment
		(start 411.140402 -220.771466)
		(end 411.140402 -220.992446)
		(width 0.18288)
		(layer "In11.Cu")
		(net "M_H_CPU0_SB_DQ<5>")
	)
	(segment
		(start 435.376066 -218.14282)
		(end 434.876448 -218.642438)
		(width 0.18288)
		(layer "In11.Cu")
		(net "M_H_CPU0_SB_DQ<5>")
	)
	(segment
		(start 422.38041 -219.72651)
		(end 421.416734 -220.690186)
		(width 0.18288)
		(layer "In11.Cu")
		(net "M_H_CPU0_SB_DQ<5>")
	)
	(segment
		(start 437.270144 -219.325952)
		(end 437.077104 -219.132912)
		(width 0.18288)
		(layer "In11.Cu")
		(net "M_H_CPU0_SB_DQ<5>")
	)
	(segment
		(start 446.776094 -224.032826)
		(end 445.937894 -223.194626)
		(width 0.18288)
		(layer "In11.Cu")
		(net "M_H_CPU0_SB_DQ<5>")
	)
	(segment
		(start 406.49525 -222.44177)
		(end 406.314148 -222.622872)
		(width 0.18288)
		(layer "In11.Cu")
		(net "M_H_CPU0_SB_DQ<5>")
	)
	(segment
		(start 439.860944 -219.840048)
		(end 439.531252 -219.840048)
		(width 0.18288)
		(layer "In11.Cu")
		(net "M_H_CPU0_SB_DQ<5>")
	)
	(segment
		(start 385.156964 -235.46816)
		(end 385.142232 -235.459524)
		(width 0.088646)
		(layer "In11.Cu")
		(net "M_H_CPU0_SB_DQ<5>")
	)
	(segment
		(start 434.01488 -218.835478)
		(end 434.01488 -219.133166)
		(width 0.18288)
		(layer "In11.Cu")
		(net "M_H_CPU0_SB_DQ<5>")
	)
	(segment
		(start 424.14952 -219.72651)
		(end 422.38041 -219.72651)
		(width 0.18288)
		(layer "In11.Cu")
		(net "M_H_CPU0_SB_DQ<5>")
	)
	(segment
		(start 412.447994 -220.578426)
		(end 411.333442 -220.578426)
		(width 0.18288)
		(layer "In11.Cu")
		(net "M_H_CPU0_SB_DQ<5>")
	)
	(segment
		(start 443.602364 -221.443296)
		(end 443.195964 -221.443296)
		(width 0.18288)
		(layer "In11.Cu")
		(net "M_H_CPU0_SB_DQ<5>")
	)
	(segment
		(start 433.82184 -219.326206)
		(end 433.50434 -219.326206)
		(width 0.18288)
		(layer "In11.Cu")
		(net "M_H_CPU0_SB_DQ<5>")
	)
	(segment
		(start 445.937894 -223.194626)
		(end 445.353694 -223.194626)
		(width 0.18288)
		(layer "In11.Cu")
		(net "M_H_CPU0_SB_DQ<5>")
	)
	(segment
		(start 374.435624 -235.456222)
		(end 374.42394 -235.462826)
		(width 0.088646)
		(layer "In11.Cu")
		(net "M_H_CPU0_SB_DQ<5>")
	)
	(segment
		(start 375.375424 -235.456222)
		(end 375.36374 -235.462826)
		(width 0.088646)
		(layer "In11.Cu")
		(net "M_H_CPU0_SB_DQ<5>")
	)
	(segment
		(start 450.690488 -224.032826)
		(end 446.776094 -224.032826)
		(width 0.18288)
		(layer "In11.Cu")
		(net "M_H_CPU0_SB_DQ<5>")
	)
	(segment
		(start 425.594272 -219.840048)
		(end 424.263058 -219.840048)
		(width 0.18288)
		(layer "In11.Cu")
		(net "M_H_CPU0_SB_DQ<5>")
	)
	(segment
		(start 413.930338 -220.079824)
		(end 413.737298 -220.272864)
		(width 0.18288)
		(layer "In11.Cu")
		(net "M_H_CPU0_SB_DQ<5>")
	)
	(segment
		(start 373.11076 -235.783882)
		(end 372.737634 -235.783882)
		(width 0.088646)
		(layer "In11.Cu")
		(net "M_H_CPU0_SB_DQ<5>")
	)
	(segment
		(start 433.3113 -219.133166)
		(end 433.3113 -218.835478)
		(width 0.18288)
		(layer "In11.Cu")
		(net "M_H_CPU0_SB_DQ<5>")
	)
	(segment
		(start 414.247838 -220.079824)
		(end 413.930338 -220.079824)
		(width 0.18288)
		(layer "In11.Cu")
		(net "M_H_CPU0_SB_DQ<5>")
	)
	(segment
		(start 386.217922 -235.577126)
		(end 386.159756 -235.51896)
		(width 0.088646)
		(layer "In11.Cu")
		(net "M_H_CPU0_SB_DQ<5>")
	)
	(arc
		(start 382.322832 -235.459524)
		(mid 382.135634 -235.409381)
		(end 381.948436 -235.459524)
		(width 0.088646)
		(layer "In11.Cu")
		(net "M_H_CPU0_SB_DQ<5>")
	)
	(arc
		(start 378.563632 -235.459524)
		(mid 378.376434 -235.409381)
		(end 378.189236 -235.459524)
		(width 0.088646)
		(layer "In11.Cu")
		(net "M_H_CPU0_SB_DQ<5>")
	)
	(arc
		(start 381.008636 -235.459524)
		(mid 380.731823 -235.535394)
		(end 380.453392 -235.46562)
		(width 0.088646)
		(layer "In11.Cu")
		(net "M_H_CPU0_SB_DQ<5>")
	)
	(arc
		(start 384.202432 -235.459524)
		(mid 384.015234 -235.409381)
		(end 383.828036 -235.459524)
		(width 0.088646)
		(layer "In11.Cu")
		(net "M_H_CPU0_SB_DQ<5>")
	)
	(arc
		(start 375.744232 -235.459524)
		(mid 375.560278 -235.409395)
		(end 375.375424 -235.456222)
		(width 0.088646)
		(layer "In11.Cu")
		(net "M_H_CPU0_SB_DQ<5>")
	)
	(arc
		(start 383.262632 -235.459524)
		(mid 383.075434 -235.409381)
		(end 382.888236 -235.459524)
		(width 0.088646)
		(layer "In11.Cu")
		(net "M_H_CPU0_SB_DQ<5>")
	)
	(arc
		(start 385.707636 -235.459524)
		(mid 385.433437 -235.535359)
		(end 385.156964 -235.46816)
		(width 0.088646)
		(layer "In11.Cu")
		(net "M_H_CPU0_SB_DQ<5>")
	)
	(arc
		(start 385.142232 -235.459524)
		(mid 384.955034 -235.409381)
		(end 384.767836 -235.459524)
		(width 0.088646)
		(layer "In11.Cu")
		(net "M_H_CPU0_SB_DQ<5>")
	)
	(arc
		(start 374.42394 -235.462826)
		(mid 374.143835 -235.535268)
		(end 373.864632 -235.459524)
		(width 0.088646)
		(layer "In11.Cu")
		(net "M_H_CPU0_SB_DQ<5>")
	)
	(arc
		(start 375.36374 -235.462826)
		(mid 375.083635 -235.535268)
		(end 374.804432 -235.459524)
		(width 0.088646)
		(layer "In11.Cu")
		(net "M_H_CPU0_SB_DQ<5>")
	)
	(arc
		(start 380.058168 -235.46562)
		(mid 379.77999 -235.535343)
		(end 379.503432 -235.459524)
		(width 0.088646)
		(layer "In11.Cu")
		(net "M_H_CPU0_SB_DQ<5>")
	)
	(arc
		(start 381.383032 -235.459524)
		(mid 381.195834 -235.409381)
		(end 381.008636 -235.459524)
		(width 0.088646)
		(layer "In11.Cu")
		(net "M_H_CPU0_SB_DQ<5>")
	)
	(arc
		(start 378.189236 -235.459524)
		(mid 377.915037 -235.535359)
		(end 377.638564 -235.46816)
		(width 0.088646)
		(layer "In11.Cu")
		(net "M_H_CPU0_SB_DQ<5>")
	)
	(arc
		(start 380.442978 -235.459524)
		(mid 380.25578 -235.409381)
		(end 380.068582 -235.459524)
		(width 0.088646)
		(layer "In11.Cu")
		(net "M_H_CPU0_SB_DQ<5>")
	)
	(arc
		(start 377.623832 -235.459524)
		(mid 377.436634 -235.409381)
		(end 377.249436 -235.459524)
		(width 0.088646)
		(layer "In11.Cu")
		(net "M_H_CPU0_SB_DQ<5>")
	)
	(arc
		(start 382.888236 -235.459524)
		(mid 382.605534 -235.5353)
		(end 382.322832 -235.459524)
		(width 0.088646)
		(layer "In11.Cu")
		(net "M_H_CPU0_SB_DQ<5>")
	)
	(arc
		(start 386.082032 -235.459524)
		(mid 385.894834 -235.409381)
		(end 385.707636 -235.459524)
		(width 0.088646)
		(layer "In11.Cu")
		(net "M_H_CPU0_SB_DQ<5>")
	)
	(arc
		(start 386.159756 -235.51896)
		(mid 386.122846 -235.486689)
		(end 386.082032 -235.459524)
		(width 0.088646)
		(layer "In11.Cu")
		(net "M_H_CPU0_SB_DQ<5>")
	)
	(arc
		(start 374.804432 -235.459524)
		(mid 374.620478 -235.409395)
		(end 374.435624 -235.456222)
		(width 0.088646)
		(layer "In11.Cu")
		(net "M_H_CPU0_SB_DQ<5>")
	)
	(arc
		(start 373.864632 -235.459524)
		(mid 373.680708 -235.40927)
		(end 373.495824 -235.455968)
		(width 0.088646)
		(layer "In11.Cu")
		(net "M_H_CPU0_SB_DQ<5>")
	)
	(arc
		(start 373.495824 -235.455968)
		(mid 373.452251 -235.484333)
		(end 373.41302 -235.518452)
		(width 0.088646)
		(layer "In11.Cu")
		(net "M_H_CPU0_SB_DQ<5>")
	)
	(arc
		(start 373.173752 -235.75772)
		(mid 373.144865 -235.777085)
		(end 373.11076 -235.783882)
		(width 0.088646)
		(layer "In11.Cu")
		(net "M_H_CPU0_SB_DQ<5>")
	)
	(arc
		(start 384.767836 -235.459524)
		(mid 384.493637 -235.535359)
		(end 384.217164 -235.46816)
		(width 0.088646)
		(layer "In11.Cu")
		(net "M_H_CPU0_SB_DQ<5>")
	)
	(arc
		(start 379.129036 -235.459524)
		(mid 378.854837 -235.535359)
		(end 378.578364 -235.46816)
		(width 0.088646)
		(layer "In11.Cu")
		(net "M_H_CPU0_SB_DQ<5>")
	)
	(arc
		(start 383.828036 -235.459524)
		(mid 383.545334 -235.5353)
		(end 383.262632 -235.459524)
		(width 0.088646)
		(layer "In11.Cu")
		(net "M_H_CPU0_SB_DQ<5>")
	)
	(arc
		(start 377.249436 -235.459524)
		(mid 376.975237 -235.535359)
		(end 376.698764 -235.46816)
		(width 0.088646)
		(layer "In11.Cu")
		(net "M_H_CPU0_SB_DQ<5>")
	)
	(arc
		(start 381.948436 -235.459524)
		(mid 381.665734 -235.5353)
		(end 381.383032 -235.459524)
		(width 0.088646)
		(layer "In11.Cu")
		(net "M_H_CPU0_SB_DQ<5>")
	)
	(arc
		(start 379.503432 -235.459524)
		(mid 379.316234 -235.409381)
		(end 379.129036 -235.459524)
		(width 0.088646)
		(layer "In11.Cu")
		(net "M_H_CPU0_SB_DQ<5>")
	)
	(arc
		(start 376.309636 -235.459524)
		(mid 376.035437 -235.535359)
		(end 375.758964 -235.46816)
		(width 0.088646)
		(layer "In11.Cu")
		(net "M_H_CPU0_SB_DQ<5>")
	)
	(arc
		(start 376.684032 -235.459524)
		(mid 376.496834 -235.409381)
		(end 376.309636 -235.459524)
		(width 0.088646)
		(layer "In11.Cu")
		(net "M_H_CPU0_SB_DQ<5>")
	)
	(segment
		(start 457.120244 -225.791776)
		(end 454.95845 -225.791776)
		(width 0.1016)
		(layer "F.Cu")
		(net "M_H_CPU0_SB_DQ<4>")
	)
	(segment
		(start 459.55966 -226.216972)
		(end 457.968096 -226.216972)
		(width 0.20066)
		(layer "F.Cu")
		(net "M_H_CPU0_SB_DQ<4>")
	)
	(segment
		(start 453.536812 -226.216718)
		(end 452.016114 -226.216718)
		(width 0.20066)
		(layer "F.Cu")
		(net "M_H_CPU0_SB_DQ<4>")
	)
	(segment
		(start 454.448672 -225.909886)
		(end 454.448672 -226.277424)
		(width 0.20066)
		(layer "F.Cu")
		(net "M_H_CPU0_SB_DQ<4>")
	)
	(segment
		(start 452.016114 -226.216718)
		(end 450.911214 -226.216718)
		(width 0.20066)
		(layer "F.Cu")
		(net "M_H_CPU0_SB_DQ<4>")
	)
	(segment
		(start 457.53655 -225.785426)
		(end 457.126594 -225.785426)
		(width 0.20066)
		(layer "F.Cu")
		(net "M_H_CPU0_SB_DQ<4>")
	)
	(segment
		(start 454.95845 -225.791776)
		(end 454.91146 -225.791776)
		(width 0.101854)
		(layer "F.Cu")
		(net "M_H_CPU0_SB_DQ<4>")
	)
	(segment
		(start 457.968096 -226.216972)
		(end 457.53655 -225.785426)
		(width 0.20066)
		(layer "F.Cu")
		(net "M_H_CPU0_SB_DQ<4>")
	)
	(segment
		(start 453.785478 -226.465384)
		(end 453.536812 -226.216718)
		(width 0.20066)
		(layer "F.Cu")
		(net "M_H_CPU0_SB_DQ<4>")
	)
	(segment
		(start 454.91146 -225.791776)
		(end 454.566782 -225.791776)
		(width 0.20066)
		(layer "F.Cu")
		(net "M_H_CPU0_SB_DQ<4>")
	)
	(segment
		(start 459.559914 -226.216718)
		(end 459.55966 -226.216972)
		(width 0.20066)
		(layer "F.Cu")
		(net "M_H_CPU0_SB_DQ<4>")
	)
	(segment
		(start 371.32768 -237.133638)
		(end 371.32768 -236.597952)
		(width 0.20066)
		(layer "F.Cu")
		(net "M_H_CPU0_SB_DQ<4>")
	)
	(segment
		(start 371.327934 -237.133892)
		(end 371.32768 -237.133638)
		(width 0.20066)
		(layer "F.Cu")
		(net "M_H_CPU0_SB_DQ<4>")
	)
	(segment
		(start 454.260712 -226.465384)
		(end 453.785478 -226.465384)
		(width 0.20066)
		(layer "F.Cu")
		(net "M_H_CPU0_SB_DQ<4>")
	)
	(segment
		(start 454.448672 -226.277424)
		(end 454.260712 -226.465384)
		(width 0.20066)
		(layer "F.Cu")
		(net "M_H_CPU0_SB_DQ<4>")
	)
	(segment
		(start 457.126594 -225.785426)
		(end 457.120244 -225.791776)
		(width 0.1016)
		(layer "F.Cu")
		(net "M_H_CPU0_SB_DQ<4>")
	)
	(segment
		(start 454.566782 -225.791776)
		(end 454.448672 -225.909886)
		(width 0.20066)
		(layer "F.Cu")
		(net "M_H_CPU0_SB_DQ<4>")
	)
	(segment
		(start 410.53385 -223.167194)
		(end 410.53385 -222.524066)
		(width 0.18288)
		(layer "In11.Cu")
		(net "M_H_CPU0_SB_DQ<4>")
	)
	(segment
		(start 428.059596 -220.82506)
		(end 427.77283 -220.538294)
		(width 0.18288)
		(layer "In11.Cu")
		(net "M_H_CPU0_SB_DQ<4>")
	)
	(segment
		(start 412.803594 -222.966026)
		(end 412.168594 -222.331026)
		(width 0.18288)
		(layer "In11.Cu")
		(net "M_H_CPU0_SB_DQ<4>")
	)
	(segment
		(start 429.092614 -221.0181)
		(end 428.899574 -220.82506)
		(width 0.18288)
		(layer "In11.Cu")
		(net "M_H_CPU0_SB_DQ<4>")
	)
	(segment
		(start 427.77283 -220.538294)
		(end 426.699426 -220.538294)
		(width 0.18288)
		(layer "In11.Cu")
		(net "M_H_CPU0_SB_DQ<4>")
	)
	(segment
		(start 392.3792 -235.794804)
		(end 389.043164 -235.794804)
		(width 0.18288)
		(layer "In11.Cu")
		(net "M_H_CPU0_SB_DQ<4>")
	)
	(segment
		(start 443.601094 -223.118426)
		(end 443.143894 -223.118426)
		(width 0.18288)
		(layer "In11.Cu")
		(net "M_H_CPU0_SB_DQ<4>")
	)
	(segment
		(start 442.17209 -222.146622)
		(end 441.04179 -222.146622)
		(width 0.18288)
		(layer "In11.Cu")
		(net "M_H_CPU0_SB_DQ<4>")
	)
	(segment
		(start 373.020082 -236.92231)
		(end 373.00535 -236.913674)
		(width 0.088646)
		(layer "In11.Cu")
		(net "M_H_CPU0_SB_DQ<4>")
	)
	(segment
		(start 386.177282 -236.273594)
		(end 386.16255 -236.28223)
		(width 0.088646)
		(layer "In11.Cu")
		(net "M_H_CPU0_SB_DQ<4>")
	)
	(segment
		(start 387.92658 -236.223556)
		(end 386.362956 -236.223556)
		(width 0.088646)
		(layer "In11.Cu")
		(net "M_H_CPU0_SB_DQ<4>")
	)
	(segment
		(start 418.104066 -222.81388)
		(end 418.104066 -222.422466)
		(width 0.18288)
		(layer "In11.Cu")
		(net "M_H_CPU0_SB_DQ<4>")
	)
	(segment
		(start 435.430168 -220.692726)
		(end 435.22265 -220.485208)
		(width 0.18288)
		(layer "In11.Cu")
		(net "M_H_CPU0_SB_DQ<4>")
	)
	(segment
		(start 421.063166 -222.389954)
		(end 420.37127 -222.389954)
		(width 0.18288)
		(layer "In11.Cu")
		(net "M_H_CPU0_SB_DQ<4>")
	)
	(segment
		(start 372.080282 -236.92231)
		(end 371.699028 -236.69879)
		(width 0.088646)
		(layer "In11.Cu")
		(net "M_H_CPU0_SB_DQ<4>")
	)
	(segment
		(start 414.281366 -223.843342)
		(end 414.088326 -223.650302)
		(width 0.18288)
		(layer "In11.Cu")
		(net "M_H_CPU0_SB_DQ<4>")
	)
	(segment
		(start 412.168594 -222.331026)
		(end 411.43047 -222.331026)
		(width 0.18288)
		(layer "In11.Cu")
		(net "M_H_CPU0_SB_DQ<4>")
	)
	(segment
		(start 409.438094 -222.331026)
		(end 408.625294 -223.143826)
		(width 0.18288)
		(layer "In11.Cu")
		(net "M_H_CPU0_SB_DQ<4>")
	)
	(segment
		(start 429.285654 -221.439232)
		(end 429.092614 -221.246192)
		(width 0.18288)
		(layer "In11.Cu")
		(net "M_H_CPU0_SB_DQ<4>")
	)
	(segment
		(start 381.478536 -236.273594)
		(end 381.468122 -236.27969)
		(width 0.088646)
		(layer "In11.Cu")
		(net "M_H_CPU0_SB_DQ<4>")
	)
	(segment
		(start 450.755512 -225.80854)
		(end 450.393308 -225.658426)
		(width 0.18288)
		(layer "In11.Cu")
		(net "M_H_CPU0_SB_DQ<4>")
	)
	(segment
		(start 411.23743 -222.524066)
		(end 411.23743 -223.167194)
		(width 0.18288)
		(layer "In11.Cu")
		(net "M_H_CPU0_SB_DQ<4>")
	)
	(segment
		(start 416.867594 -222.229426)
		(end 416.130994 -222.966026)
		(width 0.18288)
		(layer "In11.Cu")
		(net "M_H_CPU0_SB_DQ<4>")
	)
	(segment
		(start 443.143894 -223.118426)
		(end 442.17209 -222.146622)
		(width 0.18288)
		(layer "In11.Cu")
		(net "M_H_CPU0_SB_DQ<4>")
	)
	(segment
		(start 445.328294 -224.845626)
		(end 443.601094 -223.118426)
		(width 0.18288)
		(layer "In11.Cu")
		(net "M_H_CPU0_SB_DQ<4>")
	)
	(segment
		(start 418.104066 -222.422466)
		(end 417.911026 -222.229426)
		(width 0.18288)
		(layer "In11.Cu")
		(net "M_H_CPU0_SB_DQ<4>")
	)
	(segment
		(start 378.658882 -236.273594)
		(end 378.64415 -236.28223)
		(width 0.088646)
		(layer "In11.Cu")
		(net "M_H_CPU0_SB_DQ<4>")
	)
	(segment
		(start 388.355332 -235.794804)
		(end 387.92658 -236.223556)
		(width 0.088646)
		(layer "In11.Cu")
		(net "M_H_CPU0_SB_DQ<4>")
	)
	(segment
		(start 450.911214 -226.216718)
		(end 450.911214 -225.964242)
		(width 0.18288)
		(layer "In11.Cu")
		(net "M_H_CPU0_SB_DQ<4>")
	)
	(segment
		(start 428.899574 -220.82506)
		(end 428.059596 -220.82506)
		(width 0.18288)
		(layer "In11.Cu")
		(net "M_H_CPU0_SB_DQ<4>")
	)
	(segment
		(start 414.984946 -222.966026)
		(end 414.791906 -223.159066)
		(width 0.18288)
		(layer "In11.Cu")
		(net "M_H_CPU0_SB_DQ<4>")
	)
	(segment
		(start 426.699426 -220.538294)
		(end 425.69511 -221.54261)
		(width 0.18288)
		(layer "In11.Cu")
		(net "M_H_CPU0_SB_DQ<4>")
	)
	(segment
		(start 429.989234 -220.82506)
		(end 429.796194 -221.0181)
		(width 0.18288)
		(layer "In11.Cu")
		(net "M_H_CPU0_SB_DQ<4>")
	)
	(segment
		(start 411.04439 -223.360234)
		(end 410.72689 -223.360234)
		(width 0.18288)
		(layer "In11.Cu")
		(net "M_H_CPU0_SB_DQ<4>")
	)
	(segment
		(start 429.796194 -221.246192)
		(end 429.603154 -221.439232)
		(width 0.18288)
		(layer "In11.Cu")
		(net "M_H_CPU0_SB_DQ<4>")
	)
	(segment
		(start 411.43047 -222.331026)
		(end 411.23743 -222.524066)
		(width 0.18288)
		(layer "In11.Cu")
		(net "M_H_CPU0_SB_DQ<4>")
	)
	(segment
		(start 406.68067 -224.090738)
		(end 404.083266 -224.090738)
		(width 0.18288)
		(layer "In11.Cu")
		(net "M_H_CPU0_SB_DQ<4>")
	)
	(segment
		(start 414.088326 -223.650302)
		(end 414.088326 -223.159066)
		(width 0.18288)
		(layer "In11.Cu")
		(net "M_H_CPU0_SB_DQ<4>")
	)
	(segment
		(start 421.884094 -222.127826)
		(end 421.325294 -222.127826)
		(width 0.18288)
		(layer "In11.Cu")
		(net "M_H_CPU0_SB_DQ<4>")
	)
	(segment
		(start 450.911214 -225.964242)
		(end 450.755512 -225.80854)
		(width 0.18288)
		(layer "In11.Cu")
		(net "M_H_CPU0_SB_DQ<4>")
	)
	(segment
		(start 419.000686 -222.229426)
		(end 418.807646 -222.422466)
		(width 0.18288)
		(layer "In11.Cu")
		(net "M_H_CPU0_SB_DQ<4>")
	)
	(segment
		(start 422.646094 -221.365826)
		(end 421.884094 -222.127826)
		(width 0.18288)
		(layer "In11.Cu")
		(net "M_H_CPU0_SB_DQ<4>")
	)
	(segment
		(start 407.627582 -223.143826)
		(end 406.68067 -224.090738)
		(width 0.18288)
		(layer "In11.Cu")
		(net "M_H_CPU0_SB_DQ<4>")
	)
	(segment
		(start 421.325294 -222.127826)
		(end 421.063166 -222.389954)
		(width 0.18288)
		(layer "In11.Cu")
		(net "M_H_CPU0_SB_DQ<4>")
	)
	(segment
		(start 410.72689 -223.360234)
		(end 410.53385 -223.167194)
		(width 0.18288)
		(layer "In11.Cu")
		(net "M_H_CPU0_SB_DQ<4>")
	)
	(segment
		(start 450.393308 -225.658426)
		(end 446.801494 -225.658426)
		(width 0.18288)
		(layer "In11.Cu")
		(net "M_H_CPU0_SB_DQ<4>")
	)
	(segment
		(start 418.297106 -223.00692)
		(end 418.104066 -222.81388)
		(width 0.18288)
		(layer "In11.Cu")
		(net "M_H_CPU0_SB_DQ<4>")
	)
	(segment
		(start 417.911026 -222.229426)
		(end 416.867594 -222.229426)
		(width 0.18288)
		(layer "In11.Cu")
		(net "M_H_CPU0_SB_DQ<4>")
	)
	(segment
		(start 429.603154 -221.439232)
		(end 429.285654 -221.439232)
		(width 0.18288)
		(layer "In11.Cu")
		(net "M_H_CPU0_SB_DQ<4>")
	)
	(segment
		(start 384.297682 -236.273594)
		(end 384.28295 -236.28223)
		(width 0.088646)
		(layer "In11.Cu")
		(net "M_H_CPU0_SB_DQ<4>")
	)
	(segment
		(start 385.237482 -236.273594)
		(end 385.22275 -236.28223)
		(width 0.088646)
		(layer "In11.Cu")
		(net "M_H_CPU0_SB_DQ<4>")
	)
	(segment
		(start 435.22265 -220.485208)
		(end 431.611532 -220.485208)
		(width 0.18288)
		(layer "In11.Cu")
		(net "M_H_CPU0_SB_DQ<4>")
	)
	(segment
		(start 418.807646 -222.81388)
		(end 418.614606 -223.00692)
		(width 0.18288)
		(layer "In11.Cu")
		(net "M_H_CPU0_SB_DQ<4>")
	)
	(segment
		(start 414.088326 -223.159066)
		(end 413.895286 -222.966026)
		(width 0.18288)
		(layer "In11.Cu")
		(net "M_H_CPU0_SB_DQ<4>")
	)
	(segment
		(start 374.899682 -236.273594)
		(end 374.88495 -236.28223)
		(width 0.088646)
		(layer "In11.Cu")
		(net "M_H_CPU0_SB_DQ<4>")
	)
	(segment
		(start 413.895286 -222.966026)
		(end 412.803594 -222.966026)
		(width 0.18288)
		(layer "In11.Cu")
		(net "M_H_CPU0_SB_DQ<4>")
	)
	(segment
		(start 425.69511 -221.54261)
		(end 424.143678 -221.54261)
		(width 0.18288)
		(layer "In11.Cu")
		(net "M_H_CPU0_SB_DQ<4>")
	)
	(segment
		(start 419.983412 -222.229426)
		(end 419.000686 -222.229426)
		(width 0.18288)
		(layer "In11.Cu")
		(net "M_H_CPU0_SB_DQ<4>")
	)
	(segment
		(start 377.719082 -236.273594)
		(end 377.708668 -236.27969)
		(width 0.088646)
		(layer "In11.Cu")
		(net "M_H_CPU0_SB_DQ<4>")
	)
	(segment
		(start 416.130994 -222.966026)
		(end 414.984946 -222.966026)
		(width 0.18288)
		(layer "In11.Cu")
		(net "M_H_CPU0_SB_DQ<4>")
	)
	(segment
		(start 440.436 -221.540832)
		(end 438.272428 -221.540832)
		(width 0.18288)
		(layer "In11.Cu")
		(net "M_H_CPU0_SB_DQ<4>")
	)
	(segment
		(start 429.092614 -221.246192)
		(end 429.092614 -221.0181)
		(width 0.18288)
		(layer "In11.Cu")
		(net "M_H_CPU0_SB_DQ<4>")
	)
	(segment
		(start 411.23743 -223.167194)
		(end 411.04439 -223.360234)
		(width 0.18288)
		(layer "In11.Cu")
		(net "M_H_CPU0_SB_DQ<4>")
	)
	(segment
		(start 424.143678 -221.54261)
		(end 423.966894 -221.365826)
		(width 0.18288)
		(layer "In11.Cu")
		(net "M_H_CPU0_SB_DQ<4>")
	)
	(segment
		(start 423.966894 -221.365826)
		(end 422.646094 -221.365826)
		(width 0.18288)
		(layer "In11.Cu")
		(net "M_H_CPU0_SB_DQ<4>")
	)
	(segment
		(start 431.27168 -220.82506)
		(end 429.989234 -220.82506)
		(width 0.18288)
		(layer "In11.Cu")
		(net "M_H_CPU0_SB_DQ<4>")
	)
	(segment
		(start 431.611532 -220.485208)
		(end 431.27168 -220.82506)
		(width 0.18288)
		(layer "In11.Cu")
		(net "M_H_CPU0_SB_DQ<4>")
	)
	(segment
		(start 408.625294 -223.143826)
		(end 407.627582 -223.143826)
		(width 0.18288)
		(layer "In11.Cu")
		(net "M_H_CPU0_SB_DQ<4>")
	)
	(segment
		(start 437.424322 -220.692726)
		(end 435.430168 -220.692726)
		(width 0.18288)
		(layer "In11.Cu")
		(net "M_H_CPU0_SB_DQ<4>")
	)
	(segment
		(start 438.272428 -221.540832)
		(end 437.424322 -220.692726)
		(width 0.18288)
		(layer "In11.Cu")
		(net "M_H_CPU0_SB_DQ<4>")
	)
	(segment
		(start 418.614606 -223.00692)
		(end 418.297106 -223.00692)
		(width 0.18288)
		(layer "In11.Cu")
		(net "M_H_CPU0_SB_DQ<4>")
	)
	(segment
		(start 446.801494 -225.658426)
		(end 445.988694 -224.845626)
		(width 0.18288)
		(layer "In11.Cu")
		(net "M_H_CPU0_SB_DQ<4>")
	)
	(segment
		(start 441.04179 -222.146622)
		(end 440.436 -221.540832)
		(width 0.18288)
		(layer "In11.Cu")
		(net "M_H_CPU0_SB_DQ<4>")
	)
	(segment
		(start 429.796194 -221.0181)
		(end 429.796194 -221.246192)
		(width 0.18288)
		(layer "In11.Cu")
		(net "M_H_CPU0_SB_DQ<4>")
	)
	(segment
		(start 410.34081 -222.331026)
		(end 409.438094 -222.331026)
		(width 0.18288)
		(layer "In11.Cu")
		(net "M_H_CPU0_SB_DQ<4>")
	)
	(segment
		(start 414.598866 -223.843342)
		(end 414.281366 -223.843342)
		(width 0.18288)
		(layer "In11.Cu")
		(net "M_H_CPU0_SB_DQ<4>")
	)
	(segment
		(start 373.703342 -236.661452)
		(end 373.600726 -236.764068)
		(width 0.088646)
		(layer "In11.Cu")
		(net "M_H_CPU0_SB_DQ<4>")
	)
	(segment
		(start 414.791906 -223.650302)
		(end 414.598866 -223.843342)
		(width 0.18288)
		(layer "In11.Cu")
		(net "M_H_CPU0_SB_DQ<4>")
	)
	(segment
		(start 383.357882 -236.273594)
		(end 383.347468 -236.27969)
		(width 0.088646)
		(layer "In11.Cu")
		(net "M_H_CPU0_SB_DQ<4>")
	)
	(segment
		(start 379.598682 -236.273594)
		(end 379.58395 -236.28223)
		(width 0.088646)
		(layer "In11.Cu")
		(net "M_H_CPU0_SB_DQ<4>")
	)
	(segment
		(start 375.839482 -236.273594)
		(end 375.82475 -236.28223)
		(width 0.088646)
		(layer "In11.Cu")
		(net "M_H_CPU0_SB_DQ<4>")
	)
	(segment
		(start 414.791906 -223.159066)
		(end 414.791906 -223.650302)
		(width 0.18288)
		(layer "In11.Cu")
		(net "M_H_CPU0_SB_DQ<4>")
	)
	(segment
		(start 389.043164 -235.794804)
		(end 388.355332 -235.794804)
		(width 0.088646)
		(layer "In11.Cu")
		(net "M_H_CPU0_SB_DQ<4>")
	)
	(segment
		(start 404.083266 -224.090738)
		(end 392.3792 -235.794804)
		(width 0.18288)
		(layer "In11.Cu")
		(net "M_H_CPU0_SB_DQ<4>")
	)
	(segment
		(start 445.988694 -224.845626)
		(end 445.328294 -224.845626)
		(width 0.18288)
		(layer "In11.Cu")
		(net "M_H_CPU0_SB_DQ<4>")
	)
	(segment
		(start 420.37127 -222.389954)
		(end 419.983412 -222.229426)
		(width 0.18288)
		(layer "In11.Cu")
		(net "M_H_CPU0_SB_DQ<4>")
	)
	(segment
		(start 418.807646 -222.422466)
		(end 418.807646 -222.81388)
		(width 0.18288)
		(layer "In11.Cu")
		(net "M_H_CPU0_SB_DQ<4>")
	)
	(segment
		(start 410.53385 -222.524066)
		(end 410.34081 -222.331026)
		(width 0.18288)
		(layer "In11.Cu")
		(net "M_H_CPU0_SB_DQ<4>")
	)
	(segment
		(start 376.779536 -236.273594)
		(end 376.769122 -236.27969)
		(width 0.088646)
		(layer "In11.Cu")
		(net "M_H_CPU0_SB_DQ<4>")
	)
	(arc
		(start 379.58395 -236.28223)
		(mid 379.307509 -236.349396)
		(end 379.033278 -236.273594)
		(width 0.088646)
		(layer "In11.Cu")
		(net "M_H_CPU0_SB_DQ<4>")
	)
	(arc
		(start 373.394478 -236.92231)
		(mid 373.20728 -236.972453)
		(end 373.020082 -236.92231)
		(width 0.088646)
		(layer "In11.Cu")
		(net "M_H_CPU0_SB_DQ<4>")
	)
	(arc
		(start 372.454678 -236.92231)
		(mid 372.26748 -236.972453)
		(end 372.080282 -236.92231)
		(width 0.088646)
		(layer "In11.Cu")
		(net "M_H_CPU0_SB_DQ<4>")
	)
	(arc
		(start 373.00535 -236.913674)
		(mid 372.728875 -236.846354)
		(end 372.454678 -236.92231)
		(width 0.088646)
		(layer "In11.Cu")
		(net "M_H_CPU0_SB_DQ<4>")
	)
	(arc
		(start 385.611878 -236.273594)
		(mid 385.42468 -236.223451)
		(end 385.237482 -236.273594)
		(width 0.088646)
		(layer "In11.Cu")
		(net "M_H_CPU0_SB_DQ<4>")
	)
	(arc
		(start 384.28295 -236.28223)
		(mid 384.006509 -236.349396)
		(end 383.732278 -236.273594)
		(width 0.088646)
		(layer "In11.Cu")
		(net "M_H_CPU0_SB_DQ<4>")
	)
	(arc
		(start 380.912878 -236.273594)
		(mid 380.72568 -236.223451)
		(end 380.538482 -236.273594)
		(width 0.088646)
		(layer "In11.Cu")
		(net "M_H_CPU0_SB_DQ<4>")
	)
	(arc
		(start 384.672078 -236.273594)
		(mid 384.48488 -236.223451)
		(end 384.297682 -236.273594)
		(width 0.088646)
		(layer "In11.Cu")
		(net "M_H_CPU0_SB_DQ<4>")
	)
	(arc
		(start 383.732278 -236.273594)
		(mid 383.54508 -236.223451)
		(end 383.357882 -236.273594)
		(width 0.088646)
		(layer "In11.Cu")
		(net "M_H_CPU0_SB_DQ<4>")
	)
	(arc
		(start 383.347468 -236.27969)
		(mid 383.06929 -236.349382)
		(end 382.792732 -236.273594)
		(width 0.088646)
		(layer "In11.Cu")
		(net "M_H_CPU0_SB_DQ<4>")
	)
	(arc
		(start 382.418336 -236.273594)
		(mid 382.135634 -236.349336)
		(end 381.852932 -236.273594)
		(width 0.088646)
		(layer "In11.Cu")
		(net "M_H_CPU0_SB_DQ<4>")
	)
	(arc
		(start 382.792732 -236.273594)
		(mid 382.605534 -236.223451)
		(end 382.418336 -236.273594)
		(width 0.088646)
		(layer "In11.Cu")
		(net "M_H_CPU0_SB_DQ<4>")
	)
	(arc
		(start 371.699028 -236.69879)
		(mid 371.52008 -236.623597)
		(end 371.32768 -236.597952)
		(width 0.088646)
		(layer "In11.Cu")
		(net "M_H_CPU0_SB_DQ<4>")
	)
	(arc
		(start 373.959882 -236.273594)
		(mid 373.956299 -236.275709)
		(end 373.95277 -236.277912)
		(width 0.088646)
		(layer "In11.Cu")
		(net "M_H_CPU0_SB_DQ<4>")
	)
	(arc
		(start 376.769122 -236.27969)
		(mid 376.49069 -236.349504)
		(end 376.213878 -236.273594)
		(width 0.088646)
		(layer "In11.Cu")
		(net "M_H_CPU0_SB_DQ<4>")
	)
	(arc
		(start 373.95277 -236.277912)
		(mid 373.842107 -236.380757)
		(end 373.781066 -236.518958)
		(width 0.088646)
		(layer "In11.Cu")
		(net "M_H_CPU0_SB_DQ<4>")
	)
	(arc
		(start 376.213878 -236.273594)
		(mid 376.02668 -236.223451)
		(end 375.839482 -236.273594)
		(width 0.088646)
		(layer "In11.Cu")
		(net "M_H_CPU0_SB_DQ<4>")
	)
	(arc
		(start 380.538482 -236.273594)
		(mid 380.25578 -236.349336)
		(end 379.973078 -236.273594)
		(width 0.088646)
		(layer "In11.Cu")
		(net "M_H_CPU0_SB_DQ<4>")
	)
	(arc
		(start 373.781066 -236.518958)
		(mid 373.752469 -236.595802)
		(end 373.703342 -236.661452)
		(width 0.088646)
		(layer "In11.Cu")
		(net "M_H_CPU0_SB_DQ<4>")
	)
	(arc
		(start 386.362956 -236.223556)
		(mid 386.26681 -236.236291)
		(end 386.177282 -236.273594)
		(width 0.088646)
		(layer "In11.Cu")
		(net "M_H_CPU0_SB_DQ<4>")
	)
	(arc
		(start 375.274078 -236.273594)
		(mid 375.08688 -236.223451)
		(end 374.899682 -236.273594)
		(width 0.088646)
		(layer "In11.Cu")
		(net "M_H_CPU0_SB_DQ<4>")
	)
	(arc
		(start 381.852932 -236.273594)
		(mid 381.665734 -236.223451)
		(end 381.478536 -236.273594)
		(width 0.088646)
		(layer "In11.Cu")
		(net "M_H_CPU0_SB_DQ<4>")
	)
	(arc
		(start 385.22275 -236.28223)
		(mid 384.946309 -236.349396)
		(end 384.672078 -236.273594)
		(width 0.088646)
		(layer "In11.Cu")
		(net "M_H_CPU0_SB_DQ<4>")
	)
	(arc
		(start 379.973078 -236.273594)
		(mid 379.78588 -236.223451)
		(end 379.598682 -236.273594)
		(width 0.088646)
		(layer "In11.Cu")
		(net "M_H_CPU0_SB_DQ<4>")
	)
	(arc
		(start 377.708668 -236.27969)
		(mid 377.43049 -236.349382)
		(end 377.153932 -236.273594)
		(width 0.088646)
		(layer "In11.Cu")
		(net "M_H_CPU0_SB_DQ<4>")
	)
	(arc
		(start 379.033278 -236.273594)
		(mid 378.84608 -236.223451)
		(end 378.658882 -236.273594)
		(width 0.088646)
		(layer "In11.Cu")
		(net "M_H_CPU0_SB_DQ<4>")
	)
	(arc
		(start 374.88495 -236.28223)
		(mid 374.608509 -236.349396)
		(end 374.334278 -236.273594)
		(width 0.088646)
		(layer "In11.Cu")
		(net "M_H_CPU0_SB_DQ<4>")
	)
	(arc
		(start 377.153932 -236.273594)
		(mid 376.966734 -236.223451)
		(end 376.779536 -236.273594)
		(width 0.088646)
		(layer "In11.Cu")
		(net "M_H_CPU0_SB_DQ<4>")
	)
	(arc
		(start 373.600726 -236.764068)
		(mid 373.502788 -236.849948)
		(end 373.394478 -236.92231)
		(width 0.088646)
		(layer "In11.Cu")
		(net "M_H_CPU0_SB_DQ<4>")
	)
	(arc
		(start 378.64415 -236.28223)
		(mid 378.367709 -236.349396)
		(end 378.093478 -236.273594)
		(width 0.088646)
		(layer "In11.Cu")
		(net "M_H_CPU0_SB_DQ<4>")
	)
	(arc
		(start 386.16255 -236.28223)
		(mid 385.886109 -236.349396)
		(end 385.611878 -236.273594)
		(width 0.088646)
		(layer "In11.Cu")
		(net "M_H_CPU0_SB_DQ<4>")
	)
	(arc
		(start 378.093478 -236.273594)
		(mid 377.90628 -236.223451)
		(end 377.719082 -236.273594)
		(width 0.088646)
		(layer "In11.Cu")
		(net "M_H_CPU0_SB_DQ<4>")
	)
	(arc
		(start 374.334278 -236.273594)
		(mid 374.14708 -236.223451)
		(end 373.959882 -236.273594)
		(width 0.088646)
		(layer "In11.Cu")
		(net "M_H_CPU0_SB_DQ<4>")
	)
	(arc
		(start 375.82475 -236.28223)
		(mid 375.548309 -236.349396)
		(end 375.274078 -236.273594)
		(width 0.088646)
		(layer "In11.Cu")
		(net "M_H_CPU0_SB_DQ<4>")
	)
	(arc
		(start 381.468122 -236.27969)
		(mid 381.18969 -236.349504)
		(end 380.912878 -236.273594)
		(width 0.088646)
		(layer "In11.Cu")
		(net "M_H_CPU0_SB_DQ<4>")
	)
	(segment
		(start 455.011282 -229.616762)
		(end 456.116182 -229.616762)
		(width 0.20066)
		(layer "F.Cu")
		(net "M_H_CPU0_SB_DQ<3>")
	)
	(segment
		(start 458.550264 -230.041704)
		(end 460.558134 -230.041704)
		(width 0.1016)
		(layer "F.Cu")
		(net "M_H_CPU0_SB_DQ<3>")
	)
	(segment
		(start 462.073752 -229.364794)
		(end 462.32572 -229.616762)
		(width 0.20066)
		(layer "F.Cu")
		(net "M_H_CPU0_SB_DQ<3>")
	)
	(segment
		(start 457.814426 -229.616762)
		(end 458.24648 -230.048816)
		(width 0.20066)
		(layer "F.Cu")
		(net "M_H_CPU0_SB_DQ<3>")
	)
	(segment
		(start 461.251554 -230.053896)
		(end 461.455516 -229.849934)
		(width 0.20066)
		(layer "F.Cu")
		(net "M_H_CPU0_SB_DQ<3>")
	)
	(segment
		(start 461.455516 -229.849934)
		(end 461.455516 -229.598982)
		(width 0.20066)
		(layer "F.Cu")
		(net "M_H_CPU0_SB_DQ<3>")
	)
	(segment
		(start 456.116182 -229.616762)
		(end 457.814426 -229.616762)
		(width 0.20066)
		(layer "F.Cu")
		(net "M_H_CPU0_SB_DQ<3>")
	)
	(segment
		(start 460.558134 -230.041704)
		(end 460.570326 -230.053896)
		(width 0.1016)
		(layer "F.Cu")
		(net "M_H_CPU0_SB_DQ<3>")
	)
	(segment
		(start 373.20728 -238.76127)
		(end 373.20728 -238.225584)
		(width 0.20066)
		(layer "F.Cu")
		(net "M_H_CPU0_SB_DQ<3>")
	)
	(segment
		(start 462.32572 -229.616762)
		(end 463.659982 -229.616762)
		(width 0.20066)
		(layer "F.Cu")
		(net "M_H_CPU0_SB_DQ<3>")
	)
	(segment
		(start 458.24648 -230.048816)
		(end 458.538326 -230.048816)
		(width 0.20066)
		(layer "F.Cu")
		(net "M_H_CPU0_SB_DQ<3>")
	)
	(segment
		(start 458.538326 -230.048816)
		(end 458.543152 -230.048816)
		(width 0.101854)
		(layer "F.Cu")
		(net "M_H_CPU0_SB_DQ<3>")
	)
	(segment
		(start 461.689704 -229.364794)
		(end 462.073752 -229.364794)
		(width 0.20066)
		(layer "F.Cu")
		(net "M_H_CPU0_SB_DQ<3>")
	)
	(segment
		(start 460.570326 -230.053896)
		(end 461.251554 -230.053896)
		(width 0.20066)
		(layer "F.Cu")
		(net "M_H_CPU0_SB_DQ<3>")
	)
	(segment
		(start 461.455516 -229.598982)
		(end 461.689704 -229.364794)
		(width 0.20066)
		(layer "F.Cu")
		(net "M_H_CPU0_SB_DQ<3>")
	)
	(segment
		(start 373.207534 -238.761524)
		(end 373.20728 -238.76127)
		(width 0.20066)
		(layer "F.Cu")
		(net "M_H_CPU0_SB_DQ<3>")
	)
	(segment
		(start 458.543152 -230.048816)
		(end 458.550264 -230.041704)
		(width 0.1016)
		(layer "F.Cu")
		(net "M_H_CPU0_SB_DQ<3>")
	)
	(segment
		(start 416.870388 -226.72421)
		(end 416.052508 -227.54209)
		(width 0.18288)
		(layer "In11.Cu")
		(net "M_H_CPU0_SB_DQ<3>")
	)
	(segment
		(start 425.617132 -225.367088)
		(end 425.19346 -225.79076)
		(width 0.18288)
		(layer "In11.Cu")
		(net "M_H_CPU0_SB_DQ<3>")
	)
	(segment
		(start 436.386986 -224.940114)
		(end 434.946806 -224.940114)
		(width 0.18288)
		(layer "In11.Cu")
		(net "M_H_CPU0_SB_DQ<3>")
	)
	(segment
		(start 433.517802 -224.325942)
		(end 433.200302 -224.325942)
		(width 0.18288)
		(layer "In11.Cu")
		(net "M_H_CPU0_SB_DQ<3>")
	)
	(segment
		(start 437.545226 -224.927414)
		(end 437.33847 -225.13417)
		(width 0.18288)
		(layer "In11.Cu")
		(net "M_H_CPU0_SB_DQ<3>")
	)
	(segment
		(start 451.533768 -229.195122)
		(end 447.11239 -229.195122)
		(width 0.18288)
		(layer "In11.Cu")
		(net "M_H_CPU0_SB_DQ<3>")
	)
	(segment
		(start 414.711642 -226.871784)
		(end 414.518602 -226.678744)
		(width 0.18288)
		(layer "In11.Cu")
		(net "M_H_CPU0_SB_DQ<3>")
	)
	(segment
		(start 423.777664 -225.991166)
		(end 422.440354 -225.991166)
		(width 0.18288)
		(layer "In11.Cu")
		(net "M_H_CPU0_SB_DQ<3>")
	)
	(segment
		(start 379.598682 -238.549942)
		(end 379.58395 -238.541306)
		(width 0.088646)
		(layer "In11.Cu")
		(net "M_H_CPU0_SB_DQ<3>")
	)
	(segment
		(start 408.508708 -228.342444)
		(end 408.315668 -228.149404)
		(width 0.18288)
		(layer "In11.Cu")
		(net "M_H_CPU0_SB_DQ<3>")
	)
	(segment
		(start 444.058294 -227.639626)
		(end 443.245494 -227.639626)
		(width 0.18288)
		(layer "In11.Cu")
		(net "M_H_CPU0_SB_DQ<3>")
	)
	(segment
		(start 455.011282 -229.616762)
		(end 454.362058 -228.967538)
		(width 0.18288)
		(layer "In11.Cu")
		(net "M_H_CPU0_SB_DQ<3>")
	)
	(segment
		(start 414.711642 -227.34905)
		(end 414.711642 -226.871784)
		(width 0.18288)
		(layer "In11.Cu")
		(net "M_H_CPU0_SB_DQ<3>")
	)
	(segment
		(start 388.31647 -237.958884)
		(end 387.777228 -238.498126)
		(width 0.088646)
		(layer "In11.Cu")
		(net "M_H_CPU0_SB_DQ<3>")
	)
	(segment
		(start 373.960136 -238.549942)
		(end 373.577612 -238.325914)
		(width 0.088646)
		(layer "In11.Cu")
		(net "M_H_CPU0_SB_DQ<3>")
	)
	(segment
		(start 412.484824 -227.284026)
		(end 411.140148 -227.284026)
		(width 0.18288)
		(layer "In11.Cu")
		(net "M_H_CPU0_SB_DQ<3>")
	)
	(segment
		(start 407.612088 -228.149404)
		(end 407.419048 -228.342444)
		(width 0.18288)
		(layer "In11.Cu")
		(net "M_H_CPU0_SB_DQ<3>")
	)
	(segment
		(start 433.710842 -224.518982)
		(end 433.517802 -224.325942)
		(width 0.18288)
		(layer "In11.Cu")
		(net "M_H_CPU0_SB_DQ<3>")
	)
	(segment
		(start 440.964828 -225.79076)
		(end 439.212228 -225.79076)
		(width 0.18288)
		(layer "In11.Cu")
		(net "M_H_CPU0_SB_DQ<3>")
	)
	(segment
		(start 442.508894 -226.903026)
		(end 442.077094 -226.903026)
		(width 0.18288)
		(layer "In11.Cu")
		(net "M_H_CPU0_SB_DQ<3>")
	)
	(segment
		(start 446.588642 -228.671374)
		(end 445.090042 -228.671374)
		(width 0.18288)
		(layer "In11.Cu")
		(net "M_H_CPU0_SB_DQ<3>")
	)
	(segment
		(start 421.790622 -226.640898)
		(end 420.215822 -226.640898)
		(width 0.18288)
		(layer "In11.Cu")
		(net "M_H_CPU0_SB_DQ<3>")
	)
	(segment
		(start 445.090042 -228.671374)
		(end 444.058294 -227.639626)
		(width 0.18288)
		(layer "In11.Cu")
		(net "M_H_CPU0_SB_DQ<3>")
	)
	(segment
		(start 406.823672 -228.342444)
		(end 405.976836 -229.18928)
		(width 0.18288)
		(layer "In11.Cu")
		(net "M_H_CPU0_SB_DQ<3>")
	)
	(segment
		(start 389.043164 -237.958884)
		(end 388.31647 -237.958884)
		(width 0.088646)
		(layer "In11.Cu")
		(net "M_H_CPU0_SB_DQ<3>")
	)
	(segment
		(start 442.077094 -226.903026)
		(end 440.964828 -225.79076)
		(width 0.18288)
		(layer "In11.Cu")
		(net "M_H_CPU0_SB_DQ<3>")
	)
	(segment
		(start 411.140148 -227.284026)
		(end 410.08173 -228.342444)
		(width 0.18288)
		(layer "In11.Cu")
		(net "M_H_CPU0_SB_DQ<3>")
	)
	(segment
		(start 429.792384 -225.202496)
		(end 429.599344 -225.009456)
		(width 0.18288)
		(layer "In11.Cu")
		(net "M_H_CPU0_SB_DQ<3>")
	)
	(segment
		(start 393.361164 -237.958884)
		(end 389.043164 -237.958884)
		(width 0.18288)
		(layer "In11.Cu")
		(net "M_H_CPU0_SB_DQ<3>")
	)
	(segment
		(start 380.538736 -238.549942)
		(end 380.528322 -238.543846)
		(width 0.088646)
		(layer "In11.Cu")
		(net "M_H_CPU0_SB_DQ<3>")
	)
	(segment
		(start 407.612088 -227.724462)
		(end 407.612088 -228.149404)
		(width 0.18288)
		(layer "In11.Cu")
		(net "M_H_CPU0_SB_DQ<3>")
	)
	(segment
		(start 438.348882 -224.927414)
		(end 437.545226 -224.927414)
		(width 0.18288)
		(layer "In11.Cu")
		(net "M_H_CPU0_SB_DQ<3>")
	)
	(segment
		(start 419.151562 -226.930966)
		(end 418.944806 -226.72421)
		(width 0.18288)
		(layer "In11.Cu")
		(net "M_H_CPU0_SB_DQ<3>")
	)
	(segment
		(start 439.212228 -225.79076)
		(end 438.348882 -224.927414)
		(width 0.18288)
		(layer "In11.Cu")
		(net "M_H_CPU0_SB_DQ<3>")
	)
	(segment
		(start 375.839482 -238.549942)
		(end 375.82475 -238.541306)
		(width 0.088646)
		(layer "In11.Cu")
		(net "M_H_CPU0_SB_DQ<3>")
	)
	(segment
		(start 427.802294 -225.810826)
		(end 427.358556 -225.367088)
		(width 0.18288)
		(layer "In11.Cu")
		(net "M_H_CPU0_SB_DQ<3>")
	)
	(segment
		(start 434.812694 -225.074226)
		(end 433.903882 -225.074226)
		(width 0.18288)
		(layer "In11.Cu")
		(net "M_H_CPU0_SB_DQ<3>")
	)
	(segment
		(start 414.904682 -227.54209)
		(end 414.711642 -227.34905)
		(width 0.18288)
		(layer "In11.Cu")
		(net "M_H_CPU0_SB_DQ<3>")
	)
	(segment
		(start 431.510694 -225.074226)
		(end 430.774094 -225.810826)
		(width 0.18288)
		(layer "In11.Cu")
		(net "M_H_CPU0_SB_DQ<3>")
	)
	(segment
		(start 378.658882 -238.549942)
		(end 378.64415 -238.541306)
		(width 0.088646)
		(layer "In11.Cu")
		(net "M_H_CPU0_SB_DQ<3>")
	)
	(segment
		(start 407.805128 -227.531422)
		(end 407.612088 -227.724462)
		(width 0.18288)
		(layer "In11.Cu")
		(net "M_H_CPU0_SB_DQ<3>")
	)
	(segment
		(start 414.008062 -226.871784)
		(end 414.008062 -227.34905)
		(width 0.18288)
		(layer "In11.Cu")
		(net "M_H_CPU0_SB_DQ<3>")
	)
	(segment
		(start 414.008062 -227.34905)
		(end 413.815022 -227.54209)
		(width 0.18288)
		(layer "In11.Cu")
		(net "M_H_CPU0_SB_DQ<3>")
	)
	(segment
		(start 407.419048 -228.342444)
		(end 406.823672 -228.342444)
		(width 0.18288)
		(layer "In11.Cu")
		(net "M_H_CPU0_SB_DQ<3>")
	)
	(segment
		(start 451.761352 -228.967538)
		(end 451.533768 -229.195122)
		(width 0.18288)
		(layer "In11.Cu")
		(net "M_H_CPU0_SB_DQ<3>")
	)
	(segment
		(start 414.201102 -226.678744)
		(end 414.008062 -226.871784)
		(width 0.18288)
		(layer "In11.Cu")
		(net "M_H_CPU0_SB_DQ<3>")
	)
	(segment
		(start 433.007262 -224.881186)
		(end 432.814222 -225.074226)
		(width 0.18288)
		(layer "In11.Cu")
		(net "M_H_CPU0_SB_DQ<3>")
	)
	(segment
		(start 387.777228 -238.498126)
		(end 386.126482 -238.498126)
		(width 0.088646)
		(layer "In11.Cu")
		(net "M_H_CPU0_SB_DQ<3>")
	)
	(segment
		(start 429.599344 -225.009456)
		(end 429.281844 -225.009456)
		(width 0.18288)
		(layer "In11.Cu")
		(net "M_H_CPU0_SB_DQ<3>")
	)
	(segment
		(start 429.088804 -225.202496)
		(end 429.088804 -225.617786)
		(width 0.18288)
		(layer "In11.Cu")
		(net "M_H_CPU0_SB_DQ<3>")
	)
	(segment
		(start 432.814222 -225.074226)
		(end 431.510694 -225.074226)
		(width 0.18288)
		(layer "In11.Cu")
		(net "M_H_CPU0_SB_DQ<3>")
	)
	(segment
		(start 414.518602 -226.678744)
		(end 414.201102 -226.678744)
		(width 0.18288)
		(layer "In11.Cu")
		(net "M_H_CPU0_SB_DQ<3>")
	)
	(segment
		(start 433.007262 -224.518982)
		(end 433.007262 -224.881186)
		(width 0.18288)
		(layer "In11.Cu")
		(net "M_H_CPU0_SB_DQ<3>")
	)
	(segment
		(start 433.903882 -225.074226)
		(end 433.710842 -224.881186)
		(width 0.18288)
		(layer "In11.Cu")
		(net "M_H_CPU0_SB_DQ<3>")
	)
	(segment
		(start 408.122628 -227.531422)
		(end 407.805128 -227.531422)
		(width 0.18288)
		(layer "In11.Cu")
		(net "M_H_CPU0_SB_DQ<3>")
	)
	(segment
		(start 433.710842 -224.881186)
		(end 433.710842 -224.518982)
		(width 0.18288)
		(layer "In11.Cu")
		(net "M_H_CPU0_SB_DQ<3>")
	)
	(segment
		(start 436.581042 -225.13417)
		(end 436.386986 -224.940114)
		(width 0.18288)
		(layer "In11.Cu")
		(net "M_H_CPU0_SB_DQ<3>")
	)
	(segment
		(start 420.215822 -226.640898)
		(end 419.925754 -226.930966)
		(width 0.18288)
		(layer "In11.Cu")
		(net "M_H_CPU0_SB_DQ<3>")
	)
	(segment
		(start 412.742888 -227.54209)
		(end 412.484824 -227.284026)
		(width 0.18288)
		(layer "In11.Cu")
		(net "M_H_CPU0_SB_DQ<3>")
	)
	(segment
		(start 429.792384 -225.617786)
		(end 429.792384 -225.202496)
		(width 0.18288)
		(layer "In11.Cu")
		(net "M_H_CPU0_SB_DQ<3>")
	)
	(segment
		(start 419.925754 -226.930966)
		(end 419.151562 -226.930966)
		(width 0.18288)
		(layer "In11.Cu")
		(net "M_H_CPU0_SB_DQ<3>")
	)
	(segment
		(start 422.440354 -225.991166)
		(end 421.790622 -226.640898)
		(width 0.18288)
		(layer "In11.Cu")
		(net "M_H_CPU0_SB_DQ<3>")
	)
	(segment
		(start 423.97807 -225.79076)
		(end 423.777664 -225.991166)
		(width 0.18288)
		(layer "In11.Cu")
		(net "M_H_CPU0_SB_DQ<3>")
	)
	(segment
		(start 434.946806 -224.940114)
		(end 434.812694 -225.074226)
		(width 0.18288)
		(layer "In11.Cu")
		(net "M_H_CPU0_SB_DQ<3>")
	)
	(segment
		(start 429.281844 -225.009456)
		(end 429.088804 -225.202496)
		(width 0.18288)
		(layer "In11.Cu")
		(net "M_H_CPU0_SB_DQ<3>")
	)
	(segment
		(start 437.33847 -225.13417)
		(end 436.581042 -225.13417)
		(width 0.18288)
		(layer "In11.Cu")
		(net "M_H_CPU0_SB_DQ<3>")
	)
	(segment
		(start 447.11239 -229.195122)
		(end 446.588642 -228.671374)
		(width 0.18288)
		(layer "In11.Cu")
		(net "M_H_CPU0_SB_DQ<3>")
	)
	(segment
		(start 405.976836 -229.18928)
		(end 402.130768 -229.18928)
		(width 0.18288)
		(layer "In11.Cu")
		(net "M_H_CPU0_SB_DQ<3>")
	)
	(segment
		(start 425.19346 -225.79076)
		(end 423.97807 -225.79076)
		(width 0.18288)
		(layer "In11.Cu")
		(net "M_H_CPU0_SB_DQ<3>")
	)
	(segment
		(start 408.315668 -228.149404)
		(end 408.315668 -227.724462)
		(width 0.18288)
		(layer "In11.Cu")
		(net "M_H_CPU0_SB_DQ<3>")
	)
	(segment
		(start 413.815022 -227.54209)
		(end 412.742888 -227.54209)
		(width 0.18288)
		(layer "In11.Cu")
		(net "M_H_CPU0_SB_DQ<3>")
	)
	(segment
		(start 416.052508 -227.54209)
		(end 414.904682 -227.54209)
		(width 0.18288)
		(layer "In11.Cu")
		(net "M_H_CPU0_SB_DQ<3>")
	)
	(segment
		(start 376.779282 -238.549942)
		(end 376.76455 -238.541306)
		(width 0.088646)
		(layer "In11.Cu")
		(net "M_H_CPU0_SB_DQ<3>")
	)
	(segment
		(start 408.315668 -227.724462)
		(end 408.122628 -227.531422)
		(width 0.18288)
		(layer "In11.Cu")
		(net "M_H_CPU0_SB_DQ<3>")
	)
	(segment
		(start 454.362058 -228.967538)
		(end 451.761352 -228.967538)
		(width 0.18288)
		(layer "In11.Cu")
		(net "M_H_CPU0_SB_DQ<3>")
	)
	(segment
		(start 443.245494 -227.639626)
		(end 442.508894 -226.903026)
		(width 0.18288)
		(layer "In11.Cu")
		(net "M_H_CPU0_SB_DQ<3>")
	)
	(segment
		(start 410.08173 -228.342444)
		(end 408.508708 -228.342444)
		(width 0.18288)
		(layer "In11.Cu")
		(net "M_H_CPU0_SB_DQ<3>")
	)
	(segment
		(start 433.200302 -224.325942)
		(end 433.007262 -224.518982)
		(width 0.18288)
		(layer "In11.Cu")
		(net "M_H_CPU0_SB_DQ<3>")
	)
	(segment
		(start 418.944806 -226.72421)
		(end 416.870388 -226.72421)
		(width 0.18288)
		(layer "In11.Cu")
		(net "M_H_CPU0_SB_DQ<3>")
	)
	(segment
		(start 428.895764 -225.810826)
		(end 427.802294 -225.810826)
		(width 0.18288)
		(layer "In11.Cu")
		(net "M_H_CPU0_SB_DQ<3>")
	)
	(segment
		(start 429.985424 -225.810826)
		(end 429.792384 -225.617786)
		(width 0.18288)
		(layer "In11.Cu")
		(net "M_H_CPU0_SB_DQ<3>")
	)
	(segment
		(start 374.899682 -238.549942)
		(end 374.889268 -238.543846)
		(width 0.088646)
		(layer "In11.Cu")
		(net "M_H_CPU0_SB_DQ<3>")
	)
	(segment
		(start 427.358556 -225.367088)
		(end 425.617132 -225.367088)
		(width 0.18288)
		(layer "In11.Cu")
		(net "M_H_CPU0_SB_DQ<3>")
	)
	(segment
		(start 402.130768 -229.18928)
		(end 393.361164 -237.958884)
		(width 0.18288)
		(layer "In11.Cu")
		(net "M_H_CPU0_SB_DQ<3>")
	)
	(segment
		(start 429.088804 -225.617786)
		(end 428.895764 -225.810826)
		(width 0.18288)
		(layer "In11.Cu")
		(net "M_H_CPU0_SB_DQ<3>")
	)
	(segment
		(start 430.774094 -225.810826)
		(end 429.985424 -225.810826)
		(width 0.18288)
		(layer "In11.Cu")
		(net "M_H_CPU0_SB_DQ<3>")
	)
	(arc
		(start 376.76455 -238.541306)
		(mid 376.488075 -238.473986)
		(end 376.213878 -238.549942)
		(width 0.088646)
		(layer "In11.Cu")
		(net "M_H_CPU0_SB_DQ<3>")
	)
	(arc
		(start 377.719082 -238.549942)
		(mid 377.43638 -238.474166)
		(end 377.153678 -238.549942)
		(width 0.088646)
		(layer "In11.Cu")
		(net "M_H_CPU0_SB_DQ<3>")
	)
	(arc
		(start 380.913132 -238.549942)
		(mid 380.725934 -238.600085)
		(end 380.538736 -238.549942)
		(width 0.088646)
		(layer "In11.Cu")
		(net "M_H_CPU0_SB_DQ<3>")
	)
	(arc
		(start 385.237736 -238.549942)
		(mid 384.955034 -238.474166)
		(end 384.672332 -238.549942)
		(width 0.088646)
		(layer "In11.Cu")
		(net "M_H_CPU0_SB_DQ<3>")
	)
	(arc
		(start 379.58395 -238.541306)
		(mid 379.307475 -238.473986)
		(end 379.033278 -238.549942)
		(width 0.088646)
		(layer "In11.Cu")
		(net "M_H_CPU0_SB_DQ<3>")
	)
	(arc
		(start 375.274078 -238.549942)
		(mid 375.08688 -238.600085)
		(end 374.899682 -238.549942)
		(width 0.088646)
		(layer "In11.Cu")
		(net "M_H_CPU0_SB_DQ<3>")
	)
	(arc
		(start 384.297936 -238.549942)
		(mid 384.015234 -238.474166)
		(end 383.732532 -238.549942)
		(width 0.088646)
		(layer "In11.Cu")
		(net "M_H_CPU0_SB_DQ<3>")
	)
	(arc
		(start 386.010658 -238.485934)
		(mid 385.805484 -238.48114)
		(end 385.612132 -238.549942)
		(width 0.088646)
		(layer "In11.Cu")
		(net "M_H_CPU0_SB_DQ<3>")
	)
	(arc
		(start 375.82475 -238.541306)
		(mid 375.548275 -238.473986)
		(end 375.274078 -238.549942)
		(width 0.088646)
		(layer "In11.Cu")
		(net "M_H_CPU0_SB_DQ<3>")
	)
	(arc
		(start 376.213878 -238.549942)
		(mid 376.02668 -238.600085)
		(end 375.839482 -238.549942)
		(width 0.088646)
		(layer "In11.Cu")
		(net "M_H_CPU0_SB_DQ<3>")
	)
	(arc
		(start 374.889268 -238.543846)
		(mid 374.61109 -238.474123)
		(end 374.334532 -238.549942)
		(width 0.088646)
		(layer "In11.Cu")
		(net "M_H_CPU0_SB_DQ<3>")
	)
	(arc
		(start 378.64415 -238.541306)
		(mid 378.367675 -238.473986)
		(end 378.093478 -238.549942)
		(width 0.088646)
		(layer "In11.Cu")
		(net "M_H_CPU0_SB_DQ<3>")
	)
	(arc
		(start 379.973078 -238.549942)
		(mid 379.78588 -238.600085)
		(end 379.598682 -238.549942)
		(width 0.088646)
		(layer "In11.Cu")
		(net "M_H_CPU0_SB_DQ<3>")
	)
	(arc
		(start 374.334532 -238.549942)
		(mid 374.147334 -238.600085)
		(end 373.960136 -238.549942)
		(width 0.088646)
		(layer "In11.Cu")
		(net "M_H_CPU0_SB_DQ<3>")
	)
	(arc
		(start 381.852932 -238.549942)
		(mid 381.665734 -238.600085)
		(end 381.478536 -238.549942)
		(width 0.088646)
		(layer "In11.Cu")
		(net "M_H_CPU0_SB_DQ<3>")
	)
	(arc
		(start 385.612132 -238.549942)
		(mid 385.424934 -238.600085)
		(end 385.237736 -238.549942)
		(width 0.088646)
		(layer "In11.Cu")
		(net "M_H_CPU0_SB_DQ<3>")
	)
	(arc
		(start 373.577612 -238.325914)
		(mid 373.399124 -238.251113)
		(end 373.20728 -238.225584)
		(width 0.088646)
		(layer "In11.Cu")
		(net "M_H_CPU0_SB_DQ<3>")
	)
	(arc
		(start 383.358136 -238.549942)
		(mid 383.075434 -238.474166)
		(end 382.792732 -238.549942)
		(width 0.088646)
		(layer "In11.Cu")
		(net "M_H_CPU0_SB_DQ<3>")
	)
	(arc
		(start 379.033278 -238.549942)
		(mid 378.84608 -238.600085)
		(end 378.658882 -238.549942)
		(width 0.088646)
		(layer "In11.Cu")
		(net "M_H_CPU0_SB_DQ<3>")
	)
	(arc
		(start 377.153678 -238.549942)
		(mid 376.96648 -238.600085)
		(end 376.779282 -238.549942)
		(width 0.088646)
		(layer "In11.Cu")
		(net "M_H_CPU0_SB_DQ<3>")
	)
	(arc
		(start 382.792732 -238.549942)
		(mid 382.605534 -238.600085)
		(end 382.418336 -238.549942)
		(width 0.088646)
		(layer "In11.Cu")
		(net "M_H_CPU0_SB_DQ<3>")
	)
	(arc
		(start 381.478536 -238.549942)
		(mid 381.195834 -238.474166)
		(end 380.913132 -238.549942)
		(width 0.088646)
		(layer "In11.Cu")
		(net "M_H_CPU0_SB_DQ<3>")
	)
	(arc
		(start 382.418336 -238.549942)
		(mid 382.135634 -238.474166)
		(end 381.852932 -238.549942)
		(width 0.088646)
		(layer "In11.Cu")
		(net "M_H_CPU0_SB_DQ<3>")
	)
	(arc
		(start 386.126482 -238.498126)
		(mid 386.068256 -238.495013)
		(end 386.010658 -238.485934)
		(width 0.088646)
		(layer "In11.Cu")
		(net "M_H_CPU0_SB_DQ<3>")
	)
	(arc
		(start 380.528322 -238.543846)
		(mid 380.24989 -238.474)
		(end 379.973078 -238.549942)
		(width 0.088646)
		(layer "In11.Cu")
		(net "M_H_CPU0_SB_DQ<3>")
	)
	(arc
		(start 378.093478 -238.549942)
		(mid 377.90628 -238.600085)
		(end 377.719082 -238.549942)
		(width 0.088646)
		(layer "In11.Cu")
		(net "M_H_CPU0_SB_DQ<3>")
	)
	(arc
		(start 383.732532 -238.549942)
		(mid 383.545334 -238.600085)
		(end 383.358136 -238.549942)
		(width 0.088646)
		(layer "In11.Cu")
		(net "M_H_CPU0_SB_DQ<3>")
	)
	(arc
		(start 384.672332 -238.549942)
		(mid 384.485134 -238.600085)
		(end 384.297936 -238.549942)
		(width 0.088646)
		(layer "In11.Cu")
		(net "M_H_CPU0_SB_DQ<3>")
	)
	(segment
		(start 371.327934 -227.367084)
		(end 371.32768 -227.36683)
		(width 0.20066)
		(layer "F.Cu")
		(net "M_H_CPU0_SB_DQ<31>")
	)
	(segment
		(start 455.011282 -195.616576)
		(end 456.116182 -195.616576)
		(width 0.20066)
		(layer "F.Cu")
		(net "M_H_CPU0_SB_DQ<31>")
	)
	(segment
		(start 462.073752 -195.364608)
		(end 462.32572 -195.616576)
		(width 0.20066)
		(layer "F.Cu")
		(net "M_H_CPU0_SB_DQ<31>")
	)
	(segment
		(start 460.570326 -196.05371)
		(end 461.251554 -196.05371)
		(width 0.20066)
		(layer "F.Cu")
		(net "M_H_CPU0_SB_DQ<31>")
	)
	(segment
		(start 458.538326 -196.04863)
		(end 458.543152 -196.04863)
		(width 0.101854)
		(layer "F.Cu")
		(net "M_H_CPU0_SB_DQ<31>")
	)
	(segment
		(start 460.558134 -196.041518)
		(end 460.570326 -196.05371)
		(width 0.1016)
		(layer "F.Cu")
		(net "M_H_CPU0_SB_DQ<31>")
	)
	(segment
		(start 458.550264 -196.041518)
		(end 460.558134 -196.041518)
		(width 0.1016)
		(layer "F.Cu")
		(net "M_H_CPU0_SB_DQ<31>")
	)
	(segment
		(start 457.814426 -195.616576)
		(end 458.24648 -196.04863)
		(width 0.20066)
		(layer "F.Cu")
		(net "M_H_CPU0_SB_DQ<31>")
	)
	(segment
		(start 458.24648 -196.04863)
		(end 458.538326 -196.04863)
		(width 0.20066)
		(layer "F.Cu")
		(net "M_H_CPU0_SB_DQ<31>")
	)
	(segment
		(start 458.543152 -196.04863)
		(end 458.550264 -196.041518)
		(width 0.1016)
		(layer "F.Cu")
		(net "M_H_CPU0_SB_DQ<31>")
	)
	(segment
		(start 371.32768 -227.36683)
		(end 371.32768 -226.831144)
		(width 0.20066)
		(layer "F.Cu")
		(net "M_H_CPU0_SB_DQ<31>")
	)
	(segment
		(start 461.251554 -196.05371)
		(end 461.455516 -195.849748)
		(width 0.20066)
		(layer "F.Cu")
		(net "M_H_CPU0_SB_DQ<31>")
	)
	(segment
		(start 461.455516 -195.598796)
		(end 461.689704 -195.364608)
		(width 0.20066)
		(layer "F.Cu")
		(net "M_H_CPU0_SB_DQ<31>")
	)
	(segment
		(start 456.116182 -195.616576)
		(end 457.814426 -195.616576)
		(width 0.20066)
		(layer "F.Cu")
		(net "M_H_CPU0_SB_DQ<31>")
	)
	(segment
		(start 461.689704 -195.364608)
		(end 462.073752 -195.364608)
		(width 0.20066)
		(layer "F.Cu")
		(net "M_H_CPU0_SB_DQ<31>")
	)
	(segment
		(start 462.32572 -195.616576)
		(end 463.659982 -195.616576)
		(width 0.20066)
		(layer "F.Cu")
		(net "M_H_CPU0_SB_DQ<31>")
	)
	(segment
		(start 461.455516 -195.849748)
		(end 461.455516 -195.598796)
		(width 0.20066)
		(layer "F.Cu")
		(net "M_H_CPU0_SB_DQ<31>")
	)
	(segment
		(start 377.638564 -225.701606)
		(end 377.623832 -225.69297)
		(width 0.088646)
		(layer "In11.Cu")
		(net "M_H_CPU0_SB_DQ<31>")
	)
	(segment
		(start 387.989826 -220.066108)
		(end 387.491478 -220.564456)
		(width 0.088646)
		(layer "In11.Cu")
		(net "M_H_CPU0_SB_DQ<31>")
	)
	(segment
		(start 438.387998 -195.083684)
		(end 437.669178 -195.083684)
		(width 0.18288)
		(layer "In11.Cu")
		(net "M_H_CPU0_SB_DQ<31>")
	)
	(segment
		(start 374.819164 -225.701606)
		(end 374.804432 -225.69297)
		(width 0.088646)
		(layer "In11.Cu")
		(net "M_H_CPU0_SB_DQ<31>")
	)
	(segment
		(start 428.595282 -196.265038)
		(end 425.339256 -195.191634)
		(width 0.18288)
		(layer "In11.Cu")
		(net "M_H_CPU0_SB_DQ<31>")
	)
	(segment
		(start 440.718702 -195.191634)
		(end 439.082434 -195.191634)
		(width 0.18288)
		(layer "In11.Cu")
		(net "M_H_CPU0_SB_DQ<31>")
	)
	(segment
		(start 378.578364 -225.701606)
		(end 378.563632 -225.69297)
		(width 0.088646)
		(layer "In11.Cu")
		(net "M_H_CPU0_SB_DQ<31>")
	)
	(segment
		(start 421.023034 -196.04101)
		(end 420.133526 -196.04101)
		(width 0.18288)
		(layer "In11.Cu")
		(net "M_H_CPU0_SB_DQ<31>")
	)
	(segment
		(start 417.484052 -195.85051)
		(end 415.835338 -196.394578)
		(width 0.18288)
		(layer "In11.Cu")
		(net "M_H_CPU0_SB_DQ<31>")
	)
	(segment
		(start 437.669178 -195.083684)
		(end 436.127144 -196.041518)
		(width 0.18288)
		(layer "In11.Cu")
		(net "M_H_CPU0_SB_DQ<31>")
	)
	(segment
		(start 387.491478 -222.963994)
		(end 387.264148 -223.191324)
		(width 0.088646)
		(layer "In11.Cu")
		(net "M_H_CPU0_SB_DQ<31>")
	)
	(segment
		(start 442.204094 -195.864226)
		(end 441.391294 -195.864226)
		(width 0.18288)
		(layer "In11.Cu")
		(net "M_H_CPU0_SB_DQ<31>")
	)
	(segment
		(start 400.989038 -203.971652)
		(end 393.082018 -211.878672)
		(width 0.18288)
		(layer "In11.Cu")
		(net "M_H_CPU0_SB_DQ<31>")
	)
	(segment
		(start 373.020082 -226.506786)
		(end 373.009668 -226.512882)
		(width 0.088646)
		(layer "In11.Cu")
		(net "M_H_CPU0_SB_DQ<31>")
	)
	(segment
		(start 386.177536 -223.251268)
		(end 386.168646 -223.256348)
		(width 0.088646)
		(layer "In11.Cu")
		(net "M_H_CPU0_SB_DQ<31>")
	)
	(segment
		(start 407.242772 -198.543418)
		(end 404.408386 -198.543418)
		(width 0.18288)
		(layer "In11.Cu")
		(net "M_H_CPU0_SB_DQ<31>")
	)
	(segment
		(start 372.080536 -226.506786)
		(end 372.070122 -226.512882)
		(width 0.088646)
		(layer "In11.Cu")
		(net "M_H_CPU0_SB_DQ<31>")
	)
	(segment
		(start 379.518164 -225.701606)
		(end 379.503432 -225.69297)
		(width 0.088646)
		(layer "In11.Cu")
		(net "M_H_CPU0_SB_DQ<31>")
	)
	(segment
		(start 423.136568 -195.051426)
		(end 422.012618 -195.051426)
		(width 0.18288)
		(layer "In11.Cu")
		(net "M_H_CPU0_SB_DQ<31>")
	)
	(segment
		(start 375.758964 -225.701606)
		(end 375.744232 -225.69297)
		(width 0.088646)
		(layer "In11.Cu")
		(net "M_H_CPU0_SB_DQ<31>")
	)
	(segment
		(start 455.011282 -195.616576)
		(end 454.990708 -195.68541)
		(width 0.18288)
		(layer "In11.Cu")
		(net "M_H_CPU0_SB_DQ<31>")
	)
	(segment
		(start 443.54496 -196.804026)
		(end 442.889894 -196.550026)
		(width 0.18288)
		(layer "In11.Cu")
		(net "M_H_CPU0_SB_DQ<31>")
	)
	(segment
		(start 432.55057 -195.92798)
		(end 430.24806 -196.265038)
		(width 0.18288)
		(layer "In11.Cu")
		(net "M_H_CPU0_SB_DQ<31>")
	)
	(segment
		(start 436.127144 -196.041518)
		(end 435.530244 -196.041518)
		(width 0.18288)
		(layer "In11.Cu")
		(net "M_H_CPU0_SB_DQ<31>")
	)
	(segment
		(start 380.457964 -225.701606)
		(end 380.443232 -225.69297)
		(width 0.088646)
		(layer "In11.Cu")
		(net "M_H_CPU0_SB_DQ<31>")
	)
	(segment
		(start 425.339256 -195.191634)
		(end 424.174158 -195.191634)
		(width 0.18288)
		(layer "In11.Cu")
		(net "M_H_CPU0_SB_DQ<31>")
	)
	(segment
		(start 387.491478 -220.564456)
		(end 387.491478 -222.963994)
		(width 0.088646)
		(layer "In11.Cu")
		(net "M_H_CPU0_SB_DQ<31>")
	)
	(segment
		(start 439.082434 -195.191634)
		(end 438.387998 -195.083684)
		(width 0.18288)
		(layer "In11.Cu")
		(net "M_H_CPU0_SB_DQ<31>")
	)
	(segment
		(start 383.170684 -225.203258)
		(end 383.170684 -225.2218)
		(width 0.088646)
		(layer "In11.Cu")
		(net "M_H_CPU0_SB_DQ<31>")
	)
	(segment
		(start 371.140482 -226.506786)
		(end 371.131592 -226.511866)
		(width 0.088646)
		(layer "In11.Cu")
		(net "M_H_CPU0_SB_DQ<31>")
	)
	(segment
		(start 404.408386 -198.543418)
		(end 400.989038 -201.962766)
		(width 0.18288)
		(layer "In11.Cu")
		(net "M_H_CPU0_SB_DQ<31>")
	)
	(segment
		(start 393.082018 -211.878672)
		(end 393.082018 -214.973916)
		(width 0.18288)
		(layer "In11.Cu")
		(net "M_H_CPU0_SB_DQ<31>")
	)
	(segment
		(start 386.599684 -223.279208)
		(end 386.551932 -223.251268)
		(width 0.088646)
		(layer "In11.Cu")
		(net "M_H_CPU0_SB_DQ<31>")
	)
	(segment
		(start 413.921194 -196.677026)
		(end 413.40913 -196.677026)
		(width 0.18288)
		(layer "In11.Cu")
		(net "M_H_CPU0_SB_DQ<31>")
	)
	(segment
		(start 422.012618 -195.051426)
		(end 421.023034 -196.04101)
		(width 0.18288)
		(layer "In11.Cu")
		(net "M_H_CPU0_SB_DQ<31>")
	)
	(segment
		(start 409.105608 -197.57898)
		(end 407.242772 -198.543418)
		(width 0.18288)
		(layer "In11.Cu")
		(net "M_H_CPU0_SB_DQ<31>")
	)
	(segment
		(start 373.879364 -225.701606)
		(end 373.864632 -225.69297)
		(width 0.088646)
		(layer "In11.Cu")
		(net "M_H_CPU0_SB_DQ<31>")
	)
	(segment
		(start 449.257928 -197.139052)
		(end 445.645794 -196.804026)
		(width 0.18288)
		(layer "In11.Cu")
		(net "M_H_CPU0_SB_DQ<31>")
	)
	(segment
		(start 420.133526 -196.04101)
		(end 419.943026 -195.85051)
		(width 0.18288)
		(layer "In11.Cu")
		(net "M_H_CPU0_SB_DQ<31>")
	)
	(segment
		(start 419.943026 -195.85051)
		(end 417.484052 -195.85051)
		(width 0.18288)
		(layer "In11.Cu")
		(net "M_H_CPU0_SB_DQ<31>")
	)
	(segment
		(start 434.84038 -195.92798)
		(end 432.55057 -195.92798)
		(width 0.18288)
		(layer "In11.Cu")
		(net "M_H_CPU0_SB_DQ<31>")
	)
	(segment
		(start 373.026178 -226.50323)
		(end 373.020082 -226.506786)
		(width 0.088646)
		(layer "In11.Cu")
		(net "M_H_CPU0_SB_DQ<31>")
	)
	(segment
		(start 393.082018 -214.973916)
		(end 387.989826 -220.066108)
		(width 0.18288)
		(layer "In11.Cu")
		(net "M_H_CPU0_SB_DQ<31>")
	)
	(segment
		(start 435.530244 -196.041518)
		(end 434.84038 -195.92798)
		(width 0.18288)
		(layer "In11.Cu")
		(net "M_H_CPU0_SB_DQ<31>")
	)
	(segment
		(start 442.889894 -196.550026)
		(end 442.204094 -195.864226)
		(width 0.18288)
		(layer "In11.Cu")
		(net "M_H_CPU0_SB_DQ<31>")
	)
	(segment
		(start 376.698764 -225.701606)
		(end 376.684032 -225.69297)
		(width 0.088646)
		(layer "In11.Cu")
		(net "M_H_CPU0_SB_DQ<31>")
	)
	(segment
		(start 413.40913 -196.677026)
		(end 412.232348 -197.007226)
		(width 0.18288)
		(layer "In11.Cu")
		(net "M_H_CPU0_SB_DQ<31>")
	)
	(segment
		(start 445.645794 -196.804026)
		(end 443.54496 -196.804026)
		(width 0.18288)
		(layer "In11.Cu")
		(net "M_H_CPU0_SB_DQ<31>")
	)
	(segment
		(start 424.174158 -195.191634)
		(end 423.136568 -195.051426)
		(width 0.18288)
		(layer "In11.Cu")
		(net "M_H_CPU0_SB_DQ<31>")
	)
	(segment
		(start 415.835338 -196.394578)
		(end 413.921194 -196.677026)
		(width 0.18288)
		(layer "In11.Cu")
		(net "M_H_CPU0_SB_DQ<31>")
	)
	(segment
		(start 370.957602 -226.77374)
		(end 371.015006 -226.831144)
		(width 0.088646)
		(layer "In11.Cu")
		(net "M_H_CPU0_SB_DQ<31>")
	)
	(segment
		(start 411.736794 -197.007226)
		(end 409.105608 -197.57898)
		(width 0.18288)
		(layer "In11.Cu")
		(net "M_H_CPU0_SB_DQ<31>")
	)
	(segment
		(start 450.542152 -197.742048)
		(end 449.257928 -197.139052)
		(width 0.18288)
		(layer "In11.Cu")
		(net "M_H_CPU0_SB_DQ<31>")
	)
	(segment
		(start 430.24806 -196.265038)
		(end 428.595282 -196.265038)
		(width 0.18288)
		(layer "In11.Cu")
		(net "M_H_CPU0_SB_DQ<31>")
	)
	(segment
		(start 454.990708 -195.68541)
		(end 451.19671 -197.742048)
		(width 0.18288)
		(layer "In11.Cu")
		(net "M_H_CPU0_SB_DQ<31>")
	)
	(segment
		(start 412.232348 -197.007226)
		(end 411.736794 -197.007226)
		(width 0.18288)
		(layer "In11.Cu")
		(net "M_H_CPU0_SB_DQ<31>")
	)
	(segment
		(start 373.490236 -225.69297)
		(end 373.481346 -225.69805)
		(width 0.088646)
		(layer "In11.Cu")
		(net "M_H_CPU0_SB_DQ<31>")
	)
	(segment
		(start 371.015006 -226.831144)
		(end 371.32768 -226.831144)
		(width 0.088646)
		(layer "In11.Cu")
		(net "M_H_CPU0_SB_DQ<31>")
	)
	(segment
		(start 400.989038 -201.962766)
		(end 400.989038 -203.971652)
		(width 0.18288)
		(layer "In11.Cu")
		(net "M_H_CPU0_SB_DQ<31>")
	)
	(segment
		(start 385.520184 -224.389442)
		(end 385.520184 -224.399348)
		(width 0.088646)
		(layer "In11.Cu")
		(net "M_H_CPU0_SB_DQ<31>")
	)
	(segment
		(start 385.990084 -223.575626)
		(end 385.990084 -223.585532)
		(width 0.088646)
		(layer "In11.Cu")
		(net "M_H_CPU0_SB_DQ<31>")
	)
	(segment
		(start 451.19671 -197.742048)
		(end 450.542152 -197.742048)
		(width 0.18288)
		(layer "In11.Cu")
		(net "M_H_CPU0_SB_DQ<31>")
	)
	(segment
		(start 441.391294 -195.864226)
		(end 440.718702 -195.191634)
		(width 0.18288)
		(layer "In11.Cu")
		(net "M_H_CPU0_SB_DQ<31>")
	)
	(segment
		(start 383.358136 -224.8789)
		(end 383.349246 -224.88398)
		(width 0.088646)
		(layer "In11.Cu")
		(net "M_H_CPU0_SB_DQ<31>")
	)
	(segment
		(start 385.707636 -224.065084)
		(end 385.698746 -224.070164)
		(width 0.088646)
		(layer "In11.Cu")
		(net "M_H_CPU0_SB_DQ<31>")
	)
	(arc
		(start 372.454932 -226.506786)
		(mid 372.267734 -226.456643)
		(end 372.080536 -226.506786)
		(width 0.088646)
		(layer "In11.Cu")
		(net "M_H_CPU0_SB_DQ<31>")
	)
	(arc
		(start 371.131592 -226.511866)
		(mid 371.015853 -226.62369)
		(end 370.957602 -226.77374)
		(width 0.088646)
		(layer "In11.Cu")
		(net "M_H_CPU0_SB_DQ<31>")
	)
	(arc
		(start 387.264148 -223.191324)
		(mid 387.208532 -223.239982)
		(end 387.147054 -223.280986)
		(width 0.088646)
		(layer "In11.Cu")
		(net "M_H_CPU0_SB_DQ<31>")
	)
	(arc
		(start 377.249436 -225.69297)
		(mid 376.975207 -225.768895)
		(end 376.698764 -225.701606)
		(width 0.088646)
		(layer "In11.Cu")
		(net "M_H_CPU0_SB_DQ<31>")
	)
	(arc
		(start 378.189236 -225.69297)
		(mid 377.915007 -225.768895)
		(end 377.638564 -225.701606)
		(width 0.088646)
		(layer "In11.Cu")
		(net "M_H_CPU0_SB_DQ<31>")
	)
	(arc
		(start 375.744232 -225.69297)
		(mid 375.557034 -225.642827)
		(end 375.369836 -225.69297)
		(width 0.088646)
		(layer "In11.Cu")
		(net "M_H_CPU0_SB_DQ<31>")
	)
	(arc
		(start 387.147054 -223.280986)
		(mid 386.873146 -223.353909)
		(end 386.599684 -223.279208)
		(width 0.088646)
		(layer "In11.Cu")
		(net "M_H_CPU0_SB_DQ<31>")
	)
	(arc
		(start 381.008636 -225.69297)
		(mid 380.734407 -225.768895)
		(end 380.457964 -225.701606)
		(width 0.088646)
		(layer "In11.Cu")
		(net "M_H_CPU0_SB_DQ<31>")
	)
	(arc
		(start 376.309636 -225.69297)
		(mid 376.035407 -225.768895)
		(end 375.758964 -225.701606)
		(width 0.088646)
		(layer "In11.Cu")
		(net "M_H_CPU0_SB_DQ<31>")
	)
	(arc
		(start 386.551932 -223.251268)
		(mid 386.364734 -223.201125)
		(end 386.177536 -223.251268)
		(width 0.088646)
		(layer "In11.Cu")
		(net "M_H_CPU0_SB_DQ<31>")
	)
	(arc
		(start 385.698746 -224.070164)
		(mid 385.567832 -224.206524)
		(end 385.520184 -224.389442)
		(width 0.088646)
		(layer "In11.Cu")
		(net "M_H_CPU0_SB_DQ<31>")
	)
	(arc
		(start 385.237736 -224.8789)
		(mid 384.955034 -224.954676)
		(end 384.672332 -224.8789)
		(width 0.088646)
		(layer "In11.Cu")
		(net "M_H_CPU0_SB_DQ<31>")
	)
	(arc
		(start 381.383032 -225.69297)
		(mid 381.195834 -225.642827)
		(end 381.008636 -225.69297)
		(width 0.088646)
		(layer "In11.Cu")
		(net "M_H_CPU0_SB_DQ<31>")
	)
	(arc
		(start 379.129036 -225.69297)
		(mid 378.854807 -225.768895)
		(end 378.578364 -225.701606)
		(width 0.088646)
		(layer "In11.Cu")
		(net "M_H_CPU0_SB_DQ<31>")
	)
	(arc
		(start 379.503432 -225.69297)
		(mid 379.316234 -225.642827)
		(end 379.129036 -225.69297)
		(width 0.088646)
		(layer "In11.Cu")
		(net "M_H_CPU0_SB_DQ<31>")
	)
	(arc
		(start 386.168646 -223.256348)
		(mid 386.037732 -223.392708)
		(end 385.990084 -223.575626)
		(width 0.088646)
		(layer "In11.Cu")
		(net "M_H_CPU0_SB_DQ<31>")
	)
	(arc
		(start 373.009668 -226.512882)
		(mid 372.73149 -226.582605)
		(end 372.454932 -226.506786)
		(width 0.088646)
		(layer "In11.Cu")
		(net "M_H_CPU0_SB_DQ<31>")
	)
	(arc
		(start 374.430036 -225.69297)
		(mid 374.155807 -225.768895)
		(end 373.879364 -225.701606)
		(width 0.088646)
		(layer "In11.Cu")
		(net "M_H_CPU0_SB_DQ<31>")
	)
	(arc
		(start 382.888236 -225.69297)
		(mid 382.605534 -225.768712)
		(end 382.322832 -225.69297)
		(width 0.088646)
		(layer "In11.Cu")
		(net "M_H_CPU0_SB_DQ<31>")
	)
	(arc
		(start 375.369836 -225.69297)
		(mid 375.095607 -225.768895)
		(end 374.819164 -225.701606)
		(width 0.088646)
		(layer "In11.Cu")
		(net "M_H_CPU0_SB_DQ<31>")
	)
	(arc
		(start 373.481346 -225.69805)
		(mid 373.350432 -225.83441)
		(end 373.302784 -226.017328)
		(width 0.088646)
		(layer "In11.Cu")
		(net "M_H_CPU0_SB_DQ<31>")
	)
	(arc
		(start 373.864632 -225.69297)
		(mid 373.677434 -225.642827)
		(end 373.490236 -225.69297)
		(width 0.088646)
		(layer "In11.Cu")
		(net "M_H_CPU0_SB_DQ<31>")
	)
	(arc
		(start 376.684032 -225.69297)
		(mid 376.496834 -225.642827)
		(end 376.309636 -225.69297)
		(width 0.088646)
		(layer "In11.Cu")
		(net "M_H_CPU0_SB_DQ<31>")
	)
	(arc
		(start 373.302784 -226.017328)
		(mid 373.228793 -226.296894)
		(end 373.026178 -226.50323)
		(width 0.088646)
		(layer "In11.Cu")
		(net "M_H_CPU0_SB_DQ<31>")
	)
	(arc
		(start 380.068836 -225.69297)
		(mid 379.794607 -225.768895)
		(end 379.518164 -225.701606)
		(width 0.088646)
		(layer "In11.Cu")
		(net "M_H_CPU0_SB_DQ<31>")
	)
	(arc
		(start 381.948436 -225.69297)
		(mid 381.665734 -225.768712)
		(end 381.383032 -225.69297)
		(width 0.088646)
		(layer "In11.Cu")
		(net "M_H_CPU0_SB_DQ<31>")
	)
	(arc
		(start 374.804432 -225.69297)
		(mid 374.617234 -225.642827)
		(end 374.430036 -225.69297)
		(width 0.088646)
		(layer "In11.Cu")
		(net "M_H_CPU0_SB_DQ<31>")
	)
	(arc
		(start 384.297936 -224.8789)
		(mid 384.015234 -224.954676)
		(end 383.732532 -224.8789)
		(width 0.088646)
		(layer "In11.Cu")
		(net "M_H_CPU0_SB_DQ<31>")
	)
	(arc
		(start 383.349246 -224.88398)
		(mid 383.218332 -225.02034)
		(end 383.170684 -225.203258)
		(width 0.088646)
		(layer "In11.Cu")
		(net "M_H_CPU0_SB_DQ<31>")
	)
	(arc
		(start 385.520184 -224.399348)
		(mid 385.442073 -224.676297)
		(end 385.237736 -224.8789)
		(width 0.088646)
		(layer "In11.Cu")
		(net "M_H_CPU0_SB_DQ<31>")
	)
	(arc
		(start 377.623832 -225.69297)
		(mid 377.436634 -225.642827)
		(end 377.249436 -225.69297)
		(width 0.088646)
		(layer "In11.Cu")
		(net "M_H_CPU0_SB_DQ<31>")
	)
	(arc
		(start 383.170684 -225.2218)
		(mid 383.090522 -225.493989)
		(end 382.888236 -225.69297)
		(width 0.088646)
		(layer "In11.Cu")
		(net "M_H_CPU0_SB_DQ<31>")
	)
	(arc
		(start 385.990084 -223.585532)
		(mid 385.911973 -223.862481)
		(end 385.707636 -224.065084)
		(width 0.088646)
		(layer "In11.Cu")
		(net "M_H_CPU0_SB_DQ<31>")
	)
	(arc
		(start 378.563632 -225.69297)
		(mid 378.376434 -225.642827)
		(end 378.189236 -225.69297)
		(width 0.088646)
		(layer "In11.Cu")
		(net "M_H_CPU0_SB_DQ<31>")
	)
	(arc
		(start 372.070122 -226.512882)
		(mid 371.79169 -226.582728)
		(end 371.514878 -226.506786)
		(width 0.088646)
		(layer "In11.Cu")
		(net "M_H_CPU0_SB_DQ<31>")
	)
	(arc
		(start 384.672332 -224.8789)
		(mid 384.485134 -224.828757)
		(end 384.297936 -224.8789)
		(width 0.088646)
		(layer "In11.Cu")
		(net "M_H_CPU0_SB_DQ<31>")
	)
	(arc
		(start 382.322832 -225.69297)
		(mid 382.135634 -225.642827)
		(end 381.948436 -225.69297)
		(width 0.088646)
		(layer "In11.Cu")
		(net "M_H_CPU0_SB_DQ<31>")
	)
	(arc
		(start 371.514878 -226.506786)
		(mid 371.32768 -226.456643)
		(end 371.140482 -226.506786)
		(width 0.088646)
		(layer "In11.Cu")
		(net "M_H_CPU0_SB_DQ<31>")
	)
	(arc
		(start 383.732532 -224.8789)
		(mid 383.545334 -224.828757)
		(end 383.358136 -224.8789)
		(width 0.088646)
		(layer "In11.Cu")
		(net "M_H_CPU0_SB_DQ<31>")
	)
	(arc
		(start 380.443232 -225.69297)
		(mid 380.256034 -225.642827)
		(end 380.068836 -225.69297)
		(width 0.088646)
		(layer "In11.Cu")
		(net "M_H_CPU0_SB_DQ<31>")
	)
	(segment
		(start 461.689704 -197.06463)
		(end 462.073752 -197.06463)
		(width 0.20066)
		(layer "F.Cu")
		(net "M_H_CPU0_SB_DQ<30>")
	)
	(segment
		(start 462.073752 -197.06463)
		(end 462.32572 -197.316598)
		(width 0.20066)
		(layer "F.Cu")
		(net "M_H_CPU0_SB_DQ<30>")
	)
	(segment
		(start 458.550264 -197.74154)
		(end 460.558134 -197.74154)
		(width 0.1016)
		(layer "F.Cu")
		(net "M_H_CPU0_SB_DQ<30>")
	)
	(segment
		(start 462.32572 -197.316598)
		(end 463.659982 -197.316598)
		(width 0.20066)
		(layer "F.Cu")
		(net "M_H_CPU0_SB_DQ<30>")
	)
	(segment
		(start 455.011282 -197.316598)
		(end 456.116182 -197.316598)
		(width 0.20066)
		(layer "F.Cu")
		(net "M_H_CPU0_SB_DQ<30>")
	)
	(segment
		(start 458.24648 -197.748652)
		(end 458.538326 -197.748652)
		(width 0.20066)
		(layer "F.Cu")
		(net "M_H_CPU0_SB_DQ<30>")
	)
	(segment
		(start 457.814426 -197.316598)
		(end 458.24648 -197.748652)
		(width 0.20066)
		(layer "F.Cu")
		(net "M_H_CPU0_SB_DQ<30>")
	)
	(segment
		(start 460.558134 -197.74154)
		(end 460.570326 -197.753732)
		(width 0.1016)
		(layer "F.Cu")
		(net "M_H_CPU0_SB_DQ<30>")
	)
	(segment
		(start 458.543152 -197.748652)
		(end 458.550264 -197.74154)
		(width 0.1016)
		(layer "F.Cu")
		(net "M_H_CPU0_SB_DQ<30>")
	)
	(segment
		(start 374.14708 -227.36683)
		(end 374.14708 -226.831144)
		(width 0.20066)
		(layer "F.Cu")
		(net "M_H_CPU0_SB_DQ<30>")
	)
	(segment
		(start 456.116182 -197.316598)
		(end 457.814426 -197.316598)
		(width 0.20066)
		(layer "F.Cu")
		(net "M_H_CPU0_SB_DQ<30>")
	)
	(segment
		(start 461.251554 -197.753732)
		(end 461.455516 -197.54977)
		(width 0.20066)
		(layer "F.Cu")
		(net "M_H_CPU0_SB_DQ<30>")
	)
	(segment
		(start 460.570326 -197.753732)
		(end 461.251554 -197.753732)
		(width 0.20066)
		(layer "F.Cu")
		(net "M_H_CPU0_SB_DQ<30>")
	)
	(segment
		(start 374.147334 -227.367084)
		(end 374.14708 -227.36683)
		(width 0.20066)
		(layer "F.Cu")
		(net "M_H_CPU0_SB_DQ<30>")
	)
	(segment
		(start 458.538326 -197.748652)
		(end 458.543152 -197.748652)
		(width 0.101854)
		(layer "F.Cu")
		(net "M_H_CPU0_SB_DQ<30>")
	)
	(segment
		(start 461.455516 -197.298818)
		(end 461.689704 -197.06463)
		(width 0.20066)
		(layer "F.Cu")
		(net "M_H_CPU0_SB_DQ<30>")
	)
	(segment
		(start 461.455516 -197.54977)
		(end 461.455516 -197.298818)
		(width 0.20066)
		(layer "F.Cu")
		(net "M_H_CPU0_SB_DQ<30>")
	)
	(segment
		(start 414.626298 -199.45223)
		(end 413.730694 -198.556626)
		(width 0.18288)
		(layer "In11.Cu")
		(net "M_H_CPU0_SB_DQ<30>")
	)
	(segment
		(start 373.777002 -226.77374)
		(end 373.834406 -226.831144)
		(width 0.088646)
		(layer "In11.Cu")
		(net "M_H_CPU0_SB_DQ<30>")
	)
	(segment
		(start 373.959882 -226.506786)
		(end 373.950992 -226.511866)
		(width 0.088646)
		(layer "In11.Cu")
		(net "M_H_CPU0_SB_DQ<30>")
	)
	(segment
		(start 388.024624 -221.489778)
		(end 388.024624 -223.217994)
		(width 0.088646)
		(layer "In11.Cu")
		(net "M_H_CPU0_SB_DQ<30>")
	)
	(segment
		(start 383.640584 -226.017328)
		(end 383.640584 -226.027234)
		(width 0.088646)
		(layer "In11.Cu")
		(net "M_H_CPU0_SB_DQ<30>")
	)
	(segment
		(start 409.158186 -199.369934)
		(end 408.290014 -200.238106)
		(width 0.18288)
		(layer "In11.Cu")
		(net "M_H_CPU0_SB_DQ<30>")
	)
	(segment
		(start 380.538482 -226.506786)
		(end 380.52375 -226.515422)
		(width 0.088646)
		(layer "In11.Cu")
		(net "M_H_CPU0_SB_DQ<30>")
	)
	(segment
		(start 416.657282 -199.45223)
		(end 414.626298 -199.45223)
		(width 0.18288)
		(layer "In11.Cu")
		(net "M_H_CPU0_SB_DQ<30>")
	)
	(segment
		(start 387.22808 -224.014538)
		(end 386.834634 -224.014538)
		(width 0.088646)
		(layer "In11.Cu")
		(net "M_H_CPU0_SB_DQ<30>")
	)
	(segment
		(start 455.011282 -197.316598)
		(end 454.090532 -197.316598)
		(width 0.18288)
		(layer "In11.Cu")
		(net "M_H_CPU0_SB_DQ<30>")
	)
	(segment
		(start 434.84927 -197.628002)
		(end 431.804318 -197.628002)
		(width 0.18288)
		(layer "In11.Cu")
		(net "M_H_CPU0_SB_DQ<30>")
	)
	(segment
		(start 394.223494 -212.430614)
		(end 394.223494 -215.290908)
		(width 0.18288)
		(layer "In11.Cu")
		(net "M_H_CPU0_SB_DQ<30>")
	)
	(segment
		(start 386.177536 -224.8789)
		(end 386.168646 -224.88398)
		(width 0.088646)
		(layer "In11.Cu")
		(net "M_H_CPU0_SB_DQ<30>")
	)
	(segment
		(start 419.750494 -197.489826)
		(end 418.619686 -197.489826)
		(width 0.18288)
		(layer "In11.Cu")
		(net "M_H_CPU0_SB_DQ<30>")
	)
	(segment
		(start 373.834406 -226.831144)
		(end 374.14708 -226.831144)
		(width 0.088646)
		(layer "In11.Cu")
		(net "M_H_CPU0_SB_DQ<30>")
	)
	(segment
		(start 383.358136 -226.506786)
		(end 383.347722 -226.512882)
		(width 0.088646)
		(layer "In11.Cu")
		(net "M_H_CPU0_SB_DQ<30>")
	)
	(segment
		(start 450.408548 -199.441816)
		(end 450.209158 -199.242426)
		(width 0.18288)
		(layer "In11.Cu")
		(net "M_H_CPU0_SB_DQ<30>")
	)
	(segment
		(start 426.773594 -197.604126)
		(end 426.557694 -197.388226)
		(width 0.18288)
		(layer "In11.Cu")
		(net "M_H_CPU0_SB_DQ<30>")
	)
	(segment
		(start 408.290014 -200.238106)
		(end 404.524464 -200.238106)
		(width 0.18288)
		(layer "In11.Cu")
		(net "M_H_CPU0_SB_DQ<30>")
	)
	(segment
		(start 434.962554 -197.741286)
		(end 434.84927 -197.628002)
		(width 0.18288)
		(layer "In11.Cu")
		(net "M_H_CPU0_SB_DQ<30>")
	)
	(segment
		(start 376.779282 -226.506786)
		(end 376.768868 -226.512882)
		(width 0.088646)
		(layer "In11.Cu")
		(net "M_H_CPU0_SB_DQ<30>")
	)
	(segment
		(start 411.850586 -199.369934)
		(end 409.158186 -199.369934)
		(width 0.18288)
		(layer "In11.Cu")
		(net "M_H_CPU0_SB_DQ<30>")
	)
	(segment
		(start 394.223494 -215.290908)
		(end 388.20471 -221.309692)
		(width 0.18288)
		(layer "In11.Cu")
		(net "M_H_CPU0_SB_DQ<30>")
	)
	(segment
		(start 377.719082 -226.506786)
		(end 377.70435 -226.515422)
		(width 0.088646)
		(layer "In11.Cu")
		(net "M_H_CPU0_SB_DQ<30>")
	)
	(segment
		(start 374.899936 -226.506786)
		(end 374.889522 -226.512882)
		(width 0.088646)
		(layer "In11.Cu")
		(net "M_H_CPU0_SB_DQ<30>")
	)
	(segment
		(start 440.69127 -196.891402)
		(end 438.681114 -196.891402)
		(width 0.18288)
		(layer "In11.Cu")
		(net "M_H_CPU0_SB_DQ<30>")
	)
	(segment
		(start 423.36847 -196.891402)
		(end 423.254932 -196.777864)
		(width 0.18288)
		(layer "In11.Cu")
		(net "M_H_CPU0_SB_DQ<30>")
	)
	(segment
		(start 430.93132 -198.501)
		(end 428.333408 -198.501)
		(width 0.18288)
		(layer "In11.Cu")
		(net "M_H_CPU0_SB_DQ<30>")
	)
	(segment
		(start 422.062656 -196.777864)
		(end 421.099234 -197.741286)
		(width 0.18288)
		(layer "In11.Cu")
		(net "M_H_CPU0_SB_DQ<30>")
	)
	(segment
		(start 420.001954 -197.741286)
		(end 419.750494 -197.489826)
		(width 0.18288)
		(layer "In11.Cu")
		(net "M_H_CPU0_SB_DQ<30>")
	)
	(segment
		(start 382.418082 -226.506786)
		(end 382.407668 -226.512882)
		(width 0.088646)
		(layer "In11.Cu")
		(net "M_H_CPU0_SB_DQ<30>")
	)
	(segment
		(start 438.521094 -196.731382)
		(end 437.958738 -196.731382)
		(width 0.18288)
		(layer "In11.Cu")
		(net "M_H_CPU0_SB_DQ<30>")
	)
	(segment
		(start 388.024624 -223.217994)
		(end 387.22808 -224.014538)
		(width 0.088646)
		(layer "In11.Cu")
		(net "M_H_CPU0_SB_DQ<30>")
	)
	(segment
		(start 427.436534 -197.604126)
		(end 426.773594 -197.604126)
		(width 0.18288)
		(layer "In11.Cu")
		(net "M_H_CPU0_SB_DQ<30>")
	)
	(segment
		(start 404.524464 -200.238106)
		(end 402.453602 -202.308968)
		(width 0.18288)
		(layer "In11.Cu")
		(net "M_H_CPU0_SB_DQ<30>")
	)
	(segment
		(start 428.333408 -198.501)
		(end 427.436534 -197.604126)
		(width 0.18288)
		(layer "In11.Cu")
		(net "M_H_CPU0_SB_DQ<30>")
	)
	(segment
		(start 451.965314 -199.441816)
		(end 450.408548 -199.441816)
		(width 0.18288)
		(layer "In11.Cu")
		(net "M_H_CPU0_SB_DQ<30>")
	)
	(segment
		(start 436.948834 -197.741286)
		(end 434.962554 -197.741286)
		(width 0.18288)
		(layer "In11.Cu")
		(net "M_H_CPU0_SB_DQ<30>")
	)
	(segment
		(start 425.770294 -197.388226)
		(end 425.27347 -196.891402)
		(width 0.18288)
		(layer "In11.Cu")
		(net "M_H_CPU0_SB_DQ<30>")
	)
	(segment
		(start 446.547494 -199.242426)
		(end 445.861694 -198.556626)
		(width 0.18288)
		(layer "In11.Cu")
		(net "M_H_CPU0_SB_DQ<30>")
	)
	(segment
		(start 379.598682 -226.506786)
		(end 379.588268 -226.512882)
		(width 0.088646)
		(layer "In11.Cu")
		(net "M_H_CPU0_SB_DQ<30>")
	)
	(segment
		(start 442.178694 -197.566026)
		(end 441.365894 -197.566026)
		(width 0.18288)
		(layer "In11.Cu")
		(net "M_H_CPU0_SB_DQ<30>")
	)
	(segment
		(start 388.20471 -221.309692)
		(end 388.024624 -221.489778)
		(width 0.088646)
		(layer "In11.Cu")
		(net "M_H_CPU0_SB_DQ<30>")
	)
	(segment
		(start 437.958738 -196.731382)
		(end 436.948834 -197.741286)
		(width 0.18288)
		(layer "In11.Cu")
		(net "M_H_CPU0_SB_DQ<30>")
	)
	(segment
		(start 381.478536 -226.506786)
		(end 381.468122 -226.512882)
		(width 0.088646)
		(layer "In11.Cu")
		(net "M_H_CPU0_SB_DQ<30>")
	)
	(segment
		(start 431.804318 -197.628002)
		(end 430.93132 -198.501)
		(width 0.18288)
		(layer "In11.Cu")
		(net "M_H_CPU0_SB_DQ<30>")
	)
	(segment
		(start 383.828036 -225.69297)
		(end 383.819146 -225.69805)
		(width 0.088646)
		(layer "In11.Cu")
		(net "M_H_CPU0_SB_DQ<30>")
	)
	(segment
		(start 413.730694 -198.556626)
		(end 412.663894 -198.556626)
		(width 0.18288)
		(layer "In11.Cu")
		(net "M_H_CPU0_SB_DQ<30>")
	)
	(segment
		(start 418.619686 -197.489826)
		(end 416.657282 -199.45223)
		(width 0.18288)
		(layer "In11.Cu")
		(net "M_H_CPU0_SB_DQ<30>")
	)
	(segment
		(start 385.990084 -225.203258)
		(end 385.990084 -225.2218)
		(width 0.088646)
		(layer "In11.Cu")
		(net "M_H_CPU0_SB_DQ<30>")
	)
	(segment
		(start 450.209158 -199.242426)
		(end 446.547494 -199.242426)
		(width 0.18288)
		(layer "In11.Cu")
		(net "M_H_CPU0_SB_DQ<30>")
	)
	(segment
		(start 443.169294 -198.556626)
		(end 442.178694 -197.566026)
		(width 0.18288)
		(layer "In11.Cu")
		(net "M_H_CPU0_SB_DQ<30>")
	)
	(segment
		(start 426.557694 -197.388226)
		(end 425.770294 -197.388226)
		(width 0.18288)
		(layer "In11.Cu")
		(net "M_H_CPU0_SB_DQ<30>")
	)
	(segment
		(start 412.663894 -198.556626)
		(end 411.850586 -199.369934)
		(width 0.18288)
		(layer "In11.Cu")
		(net "M_H_CPU0_SB_DQ<30>")
	)
	(segment
		(start 421.099234 -197.741286)
		(end 420.001954 -197.741286)
		(width 0.18288)
		(layer "In11.Cu")
		(net "M_H_CPU0_SB_DQ<30>")
	)
	(segment
		(start 438.681114 -196.891402)
		(end 438.521094 -196.731382)
		(width 0.18288)
		(layer "In11.Cu")
		(net "M_H_CPU0_SB_DQ<30>")
	)
	(segment
		(start 386.459984 -224.389442)
		(end 386.459984 -224.399348)
		(width 0.088646)
		(layer "In11.Cu")
		(net "M_H_CPU0_SB_DQ<30>")
	)
	(segment
		(start 402.453602 -202.308968)
		(end 402.453602 -204.200506)
		(width 0.18288)
		(layer "In11.Cu")
		(net "M_H_CPU0_SB_DQ<30>")
	)
	(segment
		(start 423.254932 -196.777864)
		(end 422.062656 -196.777864)
		(width 0.18288)
		(layer "In11.Cu")
		(net "M_H_CPU0_SB_DQ<30>")
	)
	(segment
		(start 378.659136 -226.506786)
		(end 378.648722 -226.512882)
		(width 0.088646)
		(layer "In11.Cu")
		(net "M_H_CPU0_SB_DQ<30>")
	)
	(segment
		(start 402.453602 -204.200506)
		(end 394.223494 -212.430614)
		(width 0.18288)
		(layer "In11.Cu")
		(net "M_H_CPU0_SB_DQ<30>")
	)
	(segment
		(start 425.27347 -196.891402)
		(end 423.36847 -196.891402)
		(width 0.18288)
		(layer "In11.Cu")
		(net "M_H_CPU0_SB_DQ<30>")
	)
	(segment
		(start 445.861694 -198.556626)
		(end 443.169294 -198.556626)
		(width 0.18288)
		(layer "In11.Cu")
		(net "M_H_CPU0_SB_DQ<30>")
	)
	(segment
		(start 454.090532 -197.316598)
		(end 451.965314 -199.441816)
		(width 0.18288)
		(layer "In11.Cu")
		(net "M_H_CPU0_SB_DQ<30>")
	)
	(segment
		(start 441.365894 -197.566026)
		(end 440.69127 -196.891402)
		(width 0.18288)
		(layer "In11.Cu")
		(net "M_H_CPU0_SB_DQ<30>")
	)
	(arc
		(start 386.834634 -224.014538)
		(mid 386.569701 -224.124435)
		(end 386.459984 -224.389442)
		(width 0.088646)
		(layer "In11.Cu")
		(net "M_H_CPU0_SB_DQ<30>")
	)
	(arc
		(start 386.168646 -224.88398)
		(mid 386.037732 -225.02034)
		(end 385.990084 -225.203258)
		(width 0.088646)
		(layer "In11.Cu")
		(net "M_H_CPU0_SB_DQ<30>")
	)
	(arc
		(start 378.648722 -226.512882)
		(mid 378.37029 -226.582728)
		(end 378.093478 -226.506786)
		(width 0.088646)
		(layer "In11.Cu")
		(net "M_H_CPU0_SB_DQ<30>")
	)
	(arc
		(start 385.142232 -225.69297)
		(mid 384.955034 -225.642827)
		(end 384.767836 -225.69297)
		(width 0.088646)
		(layer "In11.Cu")
		(net "M_H_CPU0_SB_DQ<30>")
	)
	(arc
		(start 379.973078 -226.506786)
		(mid 379.78588 -226.456643)
		(end 379.598682 -226.506786)
		(width 0.088646)
		(layer "In11.Cu")
		(net "M_H_CPU0_SB_DQ<30>")
	)
	(arc
		(start 374.334278 -226.506786)
		(mid 374.14708 -226.456643)
		(end 373.959882 -226.506786)
		(width 0.088646)
		(layer "In11.Cu")
		(net "M_H_CPU0_SB_DQ<30>")
	)
	(arc
		(start 383.640584 -226.027234)
		(mid 383.562473 -226.304183)
		(end 383.358136 -226.506786)
		(width 0.088646)
		(layer "In11.Cu")
		(net "M_H_CPU0_SB_DQ<30>")
	)
	(arc
		(start 385.990084 -225.2218)
		(mid 385.909922 -225.493989)
		(end 385.707636 -225.69297)
		(width 0.088646)
		(layer "In11.Cu")
		(net "M_H_CPU0_SB_DQ<30>")
	)
	(arc
		(start 381.468122 -226.512882)
		(mid 381.18969 -226.582728)
		(end 380.912878 -226.506786)
		(width 0.088646)
		(layer "In11.Cu")
		(net "M_H_CPU0_SB_DQ<30>")
	)
	(arc
		(start 380.912878 -226.506786)
		(mid 380.72568 -226.456643)
		(end 380.538482 -226.506786)
		(width 0.088646)
		(layer "In11.Cu")
		(net "M_H_CPU0_SB_DQ<30>")
	)
	(arc
		(start 386.459984 -224.399348)
		(mid 386.381873 -224.676297)
		(end 386.177536 -224.8789)
		(width 0.088646)
		(layer "In11.Cu")
		(net "M_H_CPU0_SB_DQ<30>")
	)
	(arc
		(start 375.274332 -226.506786)
		(mid 375.087134 -226.456643)
		(end 374.899936 -226.506786)
		(width 0.088646)
		(layer "In11.Cu")
		(net "M_H_CPU0_SB_DQ<30>")
	)
	(arc
		(start 377.70435 -226.515422)
		(mid 377.427875 -226.582742)
		(end 377.153678 -226.506786)
		(width 0.088646)
		(layer "In11.Cu")
		(net "M_H_CPU0_SB_DQ<30>")
	)
	(arc
		(start 382.407668 -226.512882)
		(mid 382.12949 -226.582605)
		(end 381.852932 -226.506786)
		(width 0.088646)
		(layer "In11.Cu")
		(net "M_H_CPU0_SB_DQ<30>")
	)
	(arc
		(start 385.707636 -225.69297)
		(mid 385.424934 -225.768712)
		(end 385.142232 -225.69297)
		(width 0.088646)
		(layer "In11.Cu")
		(net "M_H_CPU0_SB_DQ<30>")
	)
	(arc
		(start 377.153678 -226.506786)
		(mid 376.96648 -226.456643)
		(end 376.779282 -226.506786)
		(width 0.088646)
		(layer "In11.Cu")
		(net "M_H_CPU0_SB_DQ<30>")
	)
	(arc
		(start 375.839736 -226.506786)
		(mid 375.557034 -226.582562)
		(end 375.274332 -226.506786)
		(width 0.088646)
		(layer "In11.Cu")
		(net "M_H_CPU0_SB_DQ<30>")
	)
	(arc
		(start 383.347722 -226.512882)
		(mid 383.06929 -226.582728)
		(end 382.792478 -226.506786)
		(width 0.088646)
		(layer "In11.Cu")
		(net "M_H_CPU0_SB_DQ<30>")
	)
	(arc
		(start 380.52375 -226.515422)
		(mid 380.247275 -226.582742)
		(end 379.973078 -226.506786)
		(width 0.088646)
		(layer "In11.Cu")
		(net "M_H_CPU0_SB_DQ<30>")
	)
	(arc
		(start 373.950992 -226.511866)
		(mid 373.835253 -226.62369)
		(end 373.777002 -226.77374)
		(width 0.088646)
		(layer "In11.Cu")
		(net "M_H_CPU0_SB_DQ<30>")
	)
	(arc
		(start 383.819146 -225.69805)
		(mid 383.688232 -225.83441)
		(end 383.640584 -226.017328)
		(width 0.088646)
		(layer "In11.Cu")
		(net "M_H_CPU0_SB_DQ<30>")
	)
	(arc
		(start 376.214132 -226.506786)
		(mid 376.026934 -226.456643)
		(end 375.839736 -226.506786)
		(width 0.088646)
		(layer "In11.Cu")
		(net "M_H_CPU0_SB_DQ<30>")
	)
	(arc
		(start 376.768868 -226.512882)
		(mid 376.49069 -226.582605)
		(end 376.214132 -226.506786)
		(width 0.088646)
		(layer "In11.Cu")
		(net "M_H_CPU0_SB_DQ<30>")
	)
	(arc
		(start 384.767836 -225.69297)
		(mid 384.485134 -225.768712)
		(end 384.202432 -225.69297)
		(width 0.088646)
		(layer "In11.Cu")
		(net "M_H_CPU0_SB_DQ<30>")
	)
	(arc
		(start 378.093478 -226.506786)
		(mid 377.90628 -226.456643)
		(end 377.719082 -226.506786)
		(width 0.088646)
		(layer "In11.Cu")
		(net "M_H_CPU0_SB_DQ<30>")
	)
	(arc
		(start 379.033532 -226.506786)
		(mid 378.846334 -226.456643)
		(end 378.659136 -226.506786)
		(width 0.088646)
		(layer "In11.Cu")
		(net "M_H_CPU0_SB_DQ<30>")
	)
	(arc
		(start 384.202432 -225.69297)
		(mid 384.015234 -225.642827)
		(end 383.828036 -225.69297)
		(width 0.088646)
		(layer "In11.Cu")
		(net "M_H_CPU0_SB_DQ<30>")
	)
	(arc
		(start 381.852932 -226.506786)
		(mid 381.665734 -226.456643)
		(end 381.478536 -226.506786)
		(width 0.088646)
		(layer "In11.Cu")
		(net "M_H_CPU0_SB_DQ<30>")
	)
	(arc
		(start 379.588268 -226.512882)
		(mid 379.31009 -226.582605)
		(end 379.033532 -226.506786)
		(width 0.088646)
		(layer "In11.Cu")
		(net "M_H_CPU0_SB_DQ<30>")
	)
	(arc
		(start 374.889522 -226.512882)
		(mid 374.61109 -226.582728)
		(end 374.334278 -226.506786)
		(width 0.088646)
		(layer "In11.Cu")
		(net "M_H_CPU0_SB_DQ<30>")
	)
	(arc
		(start 382.792478 -226.506786)
		(mid 382.60528 -226.456643)
		(end 382.418082 -226.506786)
		(width 0.088646)
		(layer "In11.Cu")
		(net "M_H_CPU0_SB_DQ<30>")
	)
	(segment
		(start 455.011282 -231.316784)
		(end 456.116182 -231.316784)
		(width 0.20066)
		(layer "F.Cu")
		(net "M_H_CPU0_SB_DQ<2>")
	)
	(segment
		(start 456.116182 -231.316784)
		(end 457.814426 -231.316784)
		(width 0.20066)
		(layer "F.Cu")
		(net "M_H_CPU0_SB_DQ<2>")
	)
	(segment
		(start 461.455516 -231.549956)
		(end 461.455516 -231.299004)
		(width 0.20066)
		(layer "F.Cu")
		(net "M_H_CPU0_SB_DQ<2>")
	)
	(segment
		(start 372.73738 -239.57534)
		(end 372.737634 -239.575086)
		(width 0.20066)
		(layer "F.Cu")
		(net "M_H_CPU0_SB_DQ<2>")
	)
	(segment
		(start 458.24648 -231.748838)
		(end 458.538326 -231.748838)
		(width 0.20066)
		(layer "F.Cu")
		(net "M_H_CPU0_SB_DQ<2>")
	)
	(segment
		(start 458.550264 -231.741726)
		(end 460.558134 -231.741726)
		(width 0.1016)
		(layer "F.Cu")
		(net "M_H_CPU0_SB_DQ<2>")
	)
	(segment
		(start 458.538326 -231.748838)
		(end 458.543152 -231.748838)
		(width 0.101854)
		(layer "F.Cu")
		(net "M_H_CPU0_SB_DQ<2>")
	)
	(segment
		(start 461.251554 -231.753918)
		(end 461.455516 -231.549956)
		(width 0.20066)
		(layer "F.Cu")
		(net "M_H_CPU0_SB_DQ<2>")
	)
	(segment
		(start 460.558134 -231.741726)
		(end 460.570326 -231.753918)
		(width 0.1016)
		(layer "F.Cu")
		(net "M_H_CPU0_SB_DQ<2>")
	)
	(segment
		(start 460.570326 -231.753918)
		(end 461.251554 -231.753918)
		(width 0.20066)
		(layer "F.Cu")
		(net "M_H_CPU0_SB_DQ<2>")
	)
	(segment
		(start 461.455516 -231.299004)
		(end 461.689704 -231.064816)
		(width 0.20066)
		(layer "F.Cu")
		(net "M_H_CPU0_SB_DQ<2>")
	)
	(segment
		(start 372.737634 -239.575086)
		(end 372.737634 -239.0394)
		(width 0.20066)
		(layer "F.Cu")
		(net "M_H_CPU0_SB_DQ<2>")
	)
	(segment
		(start 462.073752 -231.064816)
		(end 462.32572 -231.316784)
		(width 0.20066)
		(layer "F.Cu")
		(net "M_H_CPU0_SB_DQ<2>")
	)
	(segment
		(start 457.814426 -231.316784)
		(end 458.24648 -231.748838)
		(width 0.20066)
		(layer "F.Cu")
		(net "M_H_CPU0_SB_DQ<2>")
	)
	(segment
		(start 458.543152 -231.748838)
		(end 458.550264 -231.741726)
		(width 0.1016)
		(layer "F.Cu")
		(net "M_H_CPU0_SB_DQ<2>")
	)
	(segment
		(start 462.32572 -231.316784)
		(end 463.659982 -231.316784)
		(width 0.20066)
		(layer "F.Cu")
		(net "M_H_CPU0_SB_DQ<2>")
	)
	(segment
		(start 461.689704 -231.064816)
		(end 462.073752 -231.064816)
		(width 0.20066)
		(layer "F.Cu")
		(net "M_H_CPU0_SB_DQ<2>")
	)
	(segment
		(start 431.477166 -226.801426)
		(end 430.715166 -227.563426)
		(width 0.18288)
		(layer "In11.Cu")
		(net "M_H_CPU0_SB_DQ<2>")
	)
	(segment
		(start 423.87774 -227.751894)
		(end 423.6847 -227.558854)
		(width 0.18288)
		(layer "In11.Cu")
		(net "M_H_CPU0_SB_DQ<2>")
	)
	(segment
		(start 416.555682 -229.347014)
		(end 416.092894 -228.884226)
		(width 0.18288)
		(layer "In11.Cu")
		(net "M_H_CPU0_SB_DQ<2>")
	)
	(segment
		(start 385.156964 -239.355122)
		(end 385.142232 -239.363758)
		(width 0.088646)
		(layer "In11.Cu")
		(net "M_H_CPU0_SB_DQ<2>")
	)
	(segment
		(start 421.169592 -229.192328)
		(end 420.374064 -229.192328)
		(width 0.18288)
		(layer "In11.Cu")
		(net "M_H_CPU0_SB_DQ<2>")
	)
	(segment
		(start 450.958966 -230.891842)
		(end 450.56171 -230.891842)
		(width 0.18288)
		(layer "In11.Cu")
		(net "M_H_CPU0_SB_DQ<2>")
	)
	(segment
		(start 443.067694 -229.011226)
		(end 442.153294 -228.096826)
		(width 0.18288)
		(layer "In11.Cu")
		(net "M_H_CPU0_SB_DQ<2>")
	)
	(segment
		(start 426.019722 -227.563426)
		(end 425.24045 -228.342698)
		(width 0.18288)
		(layer "In11.Cu")
		(net "M_H_CPU0_SB_DQ<2>")
	)
	(segment
		(start 408.784806 -230.042466)
		(end 408.674062 -230.15321)
		(width 0.18288)
		(layer "In11.Cu")
		(net "M_H_CPU0_SB_DQ<2>")
	)
	(segment
		(start 455.011282 -231.316784)
		(end 454.424034 -230.729536)
		(width 0.18288)
		(layer "In11.Cu")
		(net "M_H_CPU0_SB_DQ<2>")
	)
	(segment
		(start 445.074294 -230.255826)
		(end 443.829694 -229.011226)
		(width 0.18288)
		(layer "In11.Cu")
		(net "M_H_CPU0_SB_DQ<2>")
	)
	(segment
		(start 418.6555 -228.475794)
		(end 418.46246 -228.282754)
		(width 0.18288)
		(layer "In11.Cu")
		(net "M_H_CPU0_SB_DQ<2>")
	)
	(segment
		(start 422.98112 -228.355398)
		(end 422.006522 -228.355398)
		(width 0.18288)
		(layer "In11.Cu")
		(net "M_H_CPU0_SB_DQ<2>")
	)
	(segment
		(start 418.46246 -228.282754)
		(end 418.14496 -228.282754)
		(width 0.18288)
		(layer "In11.Cu")
		(net "M_H_CPU0_SB_DQ<2>")
	)
	(segment
		(start 424.07078 -228.342698)
		(end 423.87774 -228.149658)
		(width 0.18288)
		(layer "In11.Cu")
		(net "M_H_CPU0_SB_DQ<2>")
	)
	(segment
		(start 406.709626 -230.15321)
		(end 405.970486 -230.89235)
		(width 0.18288)
		(layer "In11.Cu")
		(net "M_H_CPU0_SB_DQ<2>")
	)
	(segment
		(start 408.674062 -230.15321)
		(end 406.709626 -230.15321)
		(width 0.18288)
		(layer "In11.Cu")
		(net "M_H_CPU0_SB_DQ<2>")
	)
	(segment
		(start 451.68693 -230.729536)
		(end 451.524116 -230.89235)
		(width 0.18288)
		(layer "In11.Cu")
		(net "M_H_CPU0_SB_DQ<2>")
	)
	(segment
		(start 423.87774 -228.149658)
		(end 423.87774 -227.751894)
		(width 0.18288)
		(layer "In11.Cu")
		(net "M_H_CPU0_SB_DQ<2>")
	)
	(segment
		(start 451.524116 -230.89235)
		(end 450.958966 -230.891842)
		(width 0.18288)
		(layer "In11.Cu")
		(net "M_H_CPU0_SB_DQ<2>")
	)
	(segment
		(start 414.630362 -229.793038)
		(end 414.437322 -229.986078)
		(width 0.18288)
		(layer "In11.Cu")
		(net "M_H_CPU0_SB_DQ<2>")
	)
	(segment
		(start 443.829694 -229.011226)
		(end 443.067694 -229.011226)
		(width 0.18288)
		(layer "In11.Cu")
		(net "M_H_CPU0_SB_DQ<2>")
	)
	(segment
		(start 446.318894 -230.255826)
		(end 445.074294 -230.255826)
		(width 0.18288)
		(layer "In11.Cu")
		(net "M_H_CPU0_SB_DQ<2>")
	)
	(segment
		(start 380.457964 -239.355122)
		(end 380.443232 -239.363758)
		(width 0.088646)
		(layer "In11.Cu")
		(net "M_H_CPU0_SB_DQ<2>")
	)
	(segment
		(start 454.424034 -230.729536)
		(end 451.68693 -230.729536)
		(width 0.18288)
		(layer "In11.Cu")
		(net "M_H_CPU0_SB_DQ<2>")
	)
	(segment
		(start 423.17416 -227.751894)
		(end 423.17416 -228.162358)
		(width 0.18288)
		(layer "In11.Cu")
		(net "M_H_CPU0_SB_DQ<2>")
	)
	(segment
		(start 382.337564 -239.355122)
		(end 382.322832 -239.363758)
		(width 0.088646)
		(layer "In11.Cu")
		(net "M_H_CPU0_SB_DQ<2>")
	)
	(segment
		(start 417.95192 -229.153974)
		(end 417.75888 -229.347014)
		(width 0.18288)
		(layer "In11.Cu")
		(net "M_H_CPU0_SB_DQ<2>")
	)
	(segment
		(start 416.092894 -228.884226)
		(end 414.823402 -228.884226)
		(width 0.18288)
		(layer "In11.Cu")
		(net "M_H_CPU0_SB_DQ<2>")
	)
	(segment
		(start 413.926782 -229.077266)
		(end 413.733742 -228.884226)
		(width 0.18288)
		(layer "In11.Cu")
		(net "M_H_CPU0_SB_DQ<2>")
	)
	(segment
		(start 420.374064 -229.192328)
		(end 420.219378 -229.347014)
		(width 0.18288)
		(layer "In11.Cu")
		(net "M_H_CPU0_SB_DQ<2>")
	)
	(segment
		(start 423.17416 -228.162358)
		(end 422.98112 -228.355398)
		(width 0.18288)
		(layer "In11.Cu")
		(net "M_H_CPU0_SB_DQ<2>")
	)
	(segment
		(start 425.24045 -228.342698)
		(end 424.07078 -228.342698)
		(width 0.18288)
		(layer "In11.Cu")
		(net "M_H_CPU0_SB_DQ<2>")
	)
	(segment
		(start 414.630362 -229.077266)
		(end 414.630362 -229.793038)
		(width 0.18288)
		(layer "In11.Cu")
		(net "M_H_CPU0_SB_DQ<2>")
	)
	(segment
		(start 377.633992 -239.357662)
		(end 377.623578 -239.363758)
		(width 0.088646)
		(layer "In11.Cu")
		(net "M_H_CPU0_SB_DQ<2>")
	)
	(segment
		(start 438.831228 -227.84689)
		(end 438.831228 -227.08616)
		(width 0.18288)
		(layer "In11.Cu")
		(net "M_H_CPU0_SB_DQ<2>")
	)
	(segment
		(start 440.406536 -228.339904)
		(end 439.324242 -228.339904)
		(width 0.18288)
		(layer "In11.Cu")
		(net "M_H_CPU0_SB_DQ<2>")
	)
	(segment
		(start 423.3672 -227.558854)
		(end 423.17416 -227.751894)
		(width 0.18288)
		(layer "In11.Cu")
		(net "M_H_CPU0_SB_DQ<2>")
	)
	(segment
		(start 373.490236 -239.363758)
		(end 373.092726 -239.134396)
		(width 0.088646)
		(layer "In11.Cu")
		(net "M_H_CPU0_SB_DQ<2>")
	)
	(segment
		(start 450.56171 -230.891842)
		(end 450.435726 -231.017826)
		(width 0.18288)
		(layer "In11.Cu")
		(net "M_H_CPU0_SB_DQ<2>")
	)
	(segment
		(start 435.757828 -226.640644)
		(end 435.049676 -226.640644)
		(width 0.18288)
		(layer "In11.Cu")
		(net "M_H_CPU0_SB_DQ<2>")
	)
	(segment
		(start 388.521194 -238.974884)
		(end 388.243318 -239.25276)
		(width 0.088646)
		(layer "In11.Cu")
		(net "M_H_CPU0_SB_DQ<2>")
	)
	(segment
		(start 384.217164 -239.355122)
		(end 384.202432 -239.363758)
		(width 0.088646)
		(layer "In11.Cu")
		(net "M_H_CPU0_SB_DQ<2>")
	)
	(segment
		(start 378.578364 -239.355122)
		(end 378.563632 -239.363758)
		(width 0.088646)
		(layer "In11.Cu")
		(net "M_H_CPU0_SB_DQ<2>")
	)
	(segment
		(start 437.43499 -226.522026)
		(end 437.314594 -226.642422)
		(width 0.18288)
		(layer "In11.Cu")
		(net "M_H_CPU0_SB_DQ<2>")
	)
	(segment
		(start 414.823402 -228.884226)
		(end 414.630362 -229.077266)
		(width 0.18288)
		(layer "In11.Cu")
		(net "M_H_CPU0_SB_DQ<2>")
	)
	(segment
		(start 413.926782 -229.793038)
		(end 413.926782 -229.077266)
		(width 0.18288)
		(layer "In11.Cu")
		(net "M_H_CPU0_SB_DQ<2>")
	)
	(segment
		(start 422.006522 -228.355398)
		(end 421.169592 -229.192328)
		(width 0.18288)
		(layer "In11.Cu")
		(net "M_H_CPU0_SB_DQ<2>")
	)
	(segment
		(start 435.049676 -226.640644)
		(end 434.888894 -226.801426)
		(width 0.18288)
		(layer "In11.Cu")
		(net "M_H_CPU0_SB_DQ<2>")
	)
	(segment
		(start 430.715166 -227.563426)
		(end 426.019722 -227.563426)
		(width 0.18288)
		(layer "In11.Cu")
		(net "M_H_CPU0_SB_DQ<2>")
	)
	(segment
		(start 414.119822 -229.986078)
		(end 413.926782 -229.793038)
		(width 0.18288)
		(layer "In11.Cu")
		(net "M_H_CPU0_SB_DQ<2>")
	)
	(segment
		(start 417.75888 -229.347014)
		(end 416.555682 -229.347014)
		(width 0.18288)
		(layer "In11.Cu")
		(net "M_H_CPU0_SB_DQ<2>")
	)
	(segment
		(start 375.758964 -239.355122)
		(end 375.744232 -239.363758)
		(width 0.088646)
		(layer "In11.Cu")
		(net "M_H_CPU0_SB_DQ<2>")
	)
	(segment
		(start 373.879364 -239.355122)
		(end 373.864632 -239.363758)
		(width 0.088646)
		(layer "In11.Cu")
		(net "M_H_CPU0_SB_DQ<2>")
	)
	(segment
		(start 388.243318 -239.25276)
		(end 386.84327 -239.25276)
		(width 0.088646)
		(layer "In11.Cu")
		(net "M_H_CPU0_SB_DQ<2>")
	)
	(segment
		(start 410.758894 -230.042466)
		(end 408.784806 -230.042466)
		(width 0.18288)
		(layer "In11.Cu")
		(net "M_H_CPU0_SB_DQ<2>")
	)
	(segment
		(start 437.314594 -226.642422)
		(end 435.759606 -226.642422)
		(width 0.18288)
		(layer "In11.Cu")
		(net "M_H_CPU0_SB_DQ<2>")
	)
	(segment
		(start 439.324242 -228.339904)
		(end 438.831228 -227.84689)
		(width 0.18288)
		(layer "In11.Cu")
		(net "M_H_CPU0_SB_DQ<2>")
	)
	(segment
		(start 420.219378 -229.347014)
		(end 418.84854 -229.347014)
		(width 0.18288)
		(layer "In11.Cu")
		(net "M_H_CPU0_SB_DQ<2>")
	)
	(segment
		(start 438.267094 -226.522026)
		(end 437.43499 -226.522026)
		(width 0.18288)
		(layer "In11.Cu")
		(net "M_H_CPU0_SB_DQ<2>")
	)
	(segment
		(start 386.681218 -239.414812)
		(end 385.895342 -239.414812)
		(width 0.088646)
		(layer "In11.Cu")
		(net "M_H_CPU0_SB_DQ<2>")
	)
	(segment
		(start 413.733742 -228.884226)
		(end 412.54807 -228.884226)
		(width 0.18288)
		(layer "In11.Cu")
		(net "M_H_CPU0_SB_DQ<2>")
	)
	(segment
		(start 412.54807 -228.884226)
		(end 412.07817 -229.354126)
		(width 0.18288)
		(layer "In11.Cu")
		(net "M_H_CPU0_SB_DQ<2>")
	)
	(segment
		(start 414.437322 -229.986078)
		(end 414.119822 -229.986078)
		(width 0.18288)
		(layer "In11.Cu")
		(net "M_H_CPU0_SB_DQ<2>")
	)
	(segment
		(start 417.95192 -228.475794)
		(end 417.95192 -229.153974)
		(width 0.18288)
		(layer "In11.Cu")
		(net "M_H_CPU0_SB_DQ<2>")
	)
	(segment
		(start 442.153294 -228.096826)
		(end 440.649614 -228.096826)
		(width 0.18288)
		(layer "In11.Cu")
		(net "M_H_CPU0_SB_DQ<2>")
	)
	(segment
		(start 402.090636 -230.89235)
		(end 394.008102 -238.974884)
		(width 0.18288)
		(layer "In11.Cu")
		(net "M_H_CPU0_SB_DQ<2>")
	)
	(segment
		(start 435.759606 -226.642422)
		(end 435.757828 -226.640644)
		(width 0.18288)
		(layer "In11.Cu")
		(net "M_H_CPU0_SB_DQ<2>")
	)
	(segment
		(start 394.008102 -238.974884)
		(end 389.043164 -238.974884)
		(width 0.18288)
		(layer "In11.Cu")
		(net "M_H_CPU0_SB_DQ<2>")
	)
	(segment
		(start 412.07817 -229.354126)
		(end 411.447234 -229.354126)
		(width 0.18288)
		(layer "In11.Cu")
		(net "M_H_CPU0_SB_DQ<2>")
	)
	(segment
		(start 423.6847 -227.558854)
		(end 423.3672 -227.558854)
		(width 0.18288)
		(layer "In11.Cu")
		(net "M_H_CPU0_SB_DQ<2>")
	)
	(segment
		(start 374.819164 -239.355122)
		(end 374.804432 -239.363758)
		(width 0.088646)
		(layer "In11.Cu")
		(net "M_H_CPU0_SB_DQ<2>")
	)
	(segment
		(start 447.080894 -231.017826)
		(end 446.318894 -230.255826)
		(width 0.18288)
		(layer "In11.Cu")
		(net "M_H_CPU0_SB_DQ<2>")
	)
	(segment
		(start 405.970486 -230.89235)
		(end 402.090636 -230.89235)
		(width 0.18288)
		(layer "In11.Cu")
		(net "M_H_CPU0_SB_DQ<2>")
	)
	(segment
		(start 440.649614 -228.096826)
		(end 440.406536 -228.339904)
		(width 0.18288)
		(layer "In11.Cu")
		(net "M_H_CPU0_SB_DQ<2>")
	)
	(segment
		(start 450.435726 -231.017826)
		(end 447.080894 -231.017826)
		(width 0.18288)
		(layer "In11.Cu")
		(net "M_H_CPU0_SB_DQ<2>")
	)
	(segment
		(start 389.043164 -238.974884)
		(end 388.521194 -238.974884)
		(width 0.088646)
		(layer "In11.Cu")
		(net "M_H_CPU0_SB_DQ<2>")
	)
	(segment
		(start 376.694446 -239.357662)
		(end 376.684032 -239.363758)
		(width 0.088646)
		(layer "In11.Cu")
		(net "M_H_CPU0_SB_DQ<2>")
	)
	(segment
		(start 418.14496 -228.282754)
		(end 417.95192 -228.475794)
		(width 0.18288)
		(layer "In11.Cu")
		(net "M_H_CPU0_SB_DQ<2>")
	)
	(segment
		(start 386.84327 -239.25276)
		(end 386.681218 -239.414812)
		(width 0.088646)
		(layer "In11.Cu")
		(net "M_H_CPU0_SB_DQ<2>")
	)
	(segment
		(start 418.6555 -229.153974)
		(end 418.6555 -228.475794)
		(width 0.18288)
		(layer "In11.Cu")
		(net "M_H_CPU0_SB_DQ<2>")
	)
	(segment
		(start 438.831228 -227.08616)
		(end 438.267094 -226.522026)
		(width 0.18288)
		(layer "In11.Cu")
		(net "M_H_CPU0_SB_DQ<2>")
	)
	(segment
		(start 434.888894 -226.801426)
		(end 431.477166 -226.801426)
		(width 0.18288)
		(layer "In11.Cu")
		(net "M_H_CPU0_SB_DQ<2>")
	)
	(segment
		(start 411.447234 -229.354126)
		(end 410.758894 -230.042466)
		(width 0.18288)
		(layer "In11.Cu")
		(net "M_H_CPU0_SB_DQ<2>")
	)
	(segment
		(start 418.84854 -229.347014)
		(end 418.6555 -229.153974)
		(width 0.18288)
		(layer "In11.Cu")
		(net "M_H_CPU0_SB_DQ<2>")
	)
	(arc
		(start 375.369836 -239.363758)
		(mid 375.095637 -239.287923)
		(end 374.819164 -239.355122)
		(width 0.088646)
		(layer "In11.Cu")
		(net "M_H_CPU0_SB_DQ<2>")
	)
	(arc
		(start 374.804432 -239.363758)
		(mid 374.617234 -239.413901)
		(end 374.430036 -239.363758)
		(width 0.088646)
		(layer "In11.Cu")
		(net "M_H_CPU0_SB_DQ<2>")
	)
	(arc
		(start 373.092726 -239.134396)
		(mid 372.921432 -239.063513)
		(end 372.737634 -239.0394)
		(width 0.088646)
		(layer "In11.Cu")
		(net "M_H_CPU0_SB_DQ<2>")
	)
	(arc
		(start 385.142232 -239.363758)
		(mid 384.955034 -239.413901)
		(end 384.767836 -239.363758)
		(width 0.088646)
		(layer "In11.Cu")
		(net "M_H_CPU0_SB_DQ<2>")
	)
	(arc
		(start 375.744232 -239.363758)
		(mid 375.557034 -239.413901)
		(end 375.369836 -239.363758)
		(width 0.088646)
		(layer "In11.Cu")
		(net "M_H_CPU0_SB_DQ<2>")
	)
	(arc
		(start 384.202432 -239.363758)
		(mid 384.015234 -239.413901)
		(end 383.828036 -239.363758)
		(width 0.088646)
		(layer "In11.Cu")
		(net "M_H_CPU0_SB_DQ<2>")
	)
	(arc
		(start 378.563632 -239.363758)
		(mid 378.376434 -239.413901)
		(end 378.189236 -239.363758)
		(width 0.088646)
		(layer "In11.Cu")
		(net "M_H_CPU0_SB_DQ<2>")
	)
	(arc
		(start 384.767836 -239.363758)
		(mid 384.493637 -239.287923)
		(end 384.217164 -239.355122)
		(width 0.088646)
		(layer "In11.Cu")
		(net "M_H_CPU0_SB_DQ<2>")
	)
	(arc
		(start 385.707636 -239.363758)
		(mid 385.433437 -239.287923)
		(end 385.156964 -239.355122)
		(width 0.088646)
		(layer "In11.Cu")
		(net "M_H_CPU0_SB_DQ<2>")
	)
	(arc
		(start 378.189236 -239.363758)
		(mid 377.912423 -239.287888)
		(end 377.633992 -239.357662)
		(width 0.088646)
		(layer "In11.Cu")
		(net "M_H_CPU0_SB_DQ<2>")
	)
	(arc
		(start 382.888236 -239.363758)
		(mid 382.614037 -239.287923)
		(end 382.337564 -239.355122)
		(width 0.088646)
		(layer "In11.Cu")
		(net "M_H_CPU0_SB_DQ<2>")
	)
	(arc
		(start 385.895342 -239.414812)
		(mid 385.798125 -239.401656)
		(end 385.707636 -239.363758)
		(width 0.088646)
		(layer "In11.Cu")
		(net "M_H_CPU0_SB_DQ<2>")
	)
	(arc
		(start 377.623578 -239.363758)
		(mid 377.43638 -239.413901)
		(end 377.249182 -239.363758)
		(width 0.088646)
		(layer "In11.Cu")
		(net "M_H_CPU0_SB_DQ<2>")
	)
	(arc
		(start 374.430036 -239.363758)
		(mid 374.155837 -239.287923)
		(end 373.879364 -239.355122)
		(width 0.088646)
		(layer "In11.Cu")
		(net "M_H_CPU0_SB_DQ<2>")
	)
	(arc
		(start 381.383032 -239.363758)
		(mid 381.195834 -239.413901)
		(end 381.008636 -239.363758)
		(width 0.088646)
		(layer "In11.Cu")
		(net "M_H_CPU0_SB_DQ<2>")
	)
	(arc
		(start 379.503432 -239.363758)
		(mid 379.316234 -239.413901)
		(end 379.129036 -239.363758)
		(width 0.088646)
		(layer "In11.Cu")
		(net "M_H_CPU0_SB_DQ<2>")
	)
	(arc
		(start 381.008636 -239.363758)
		(mid 380.734437 -239.287923)
		(end 380.457964 -239.355122)
		(width 0.088646)
		(layer "In11.Cu")
		(net "M_H_CPU0_SB_DQ<2>")
	)
	(arc
		(start 383.828036 -239.363758)
		(mid 383.545334 -239.287982)
		(end 383.262632 -239.363758)
		(width 0.088646)
		(layer "In11.Cu")
		(net "M_H_CPU0_SB_DQ<2>")
	)
	(arc
		(start 383.262632 -239.363758)
		(mid 383.075434 -239.413901)
		(end 382.888236 -239.363758)
		(width 0.088646)
		(layer "In11.Cu")
		(net "M_H_CPU0_SB_DQ<2>")
	)
	(arc
		(start 377.249182 -239.363758)
		(mid 376.972623 -239.288015)
		(end 376.694446 -239.357662)
		(width 0.088646)
		(layer "In11.Cu")
		(net "M_H_CPU0_SB_DQ<2>")
	)
	(arc
		(start 382.322832 -239.363758)
		(mid 382.135634 -239.413901)
		(end 381.948436 -239.363758)
		(width 0.088646)
		(layer "In11.Cu")
		(net "M_H_CPU0_SB_DQ<2>")
	)
	(arc
		(start 373.864632 -239.363758)
		(mid 373.677434 -239.413901)
		(end 373.490236 -239.363758)
		(width 0.088646)
		(layer "In11.Cu")
		(net "M_H_CPU0_SB_DQ<2>")
	)
	(arc
		(start 380.068836 -239.363758)
		(mid 379.786134 -239.287982)
		(end 379.503432 -239.363758)
		(width 0.088646)
		(layer "In11.Cu")
		(net "M_H_CPU0_SB_DQ<2>")
	)
	(arc
		(start 376.684032 -239.363758)
		(mid 376.496834 -239.413901)
		(end 376.309636 -239.363758)
		(width 0.088646)
		(layer "In11.Cu")
		(net "M_H_CPU0_SB_DQ<2>")
	)
	(arc
		(start 381.948436 -239.363758)
		(mid 381.665734 -239.287982)
		(end 381.383032 -239.363758)
		(width 0.088646)
		(layer "In11.Cu")
		(net "M_H_CPU0_SB_DQ<2>")
	)
	(arc
		(start 380.443232 -239.363758)
		(mid 380.256034 -239.413901)
		(end 380.068836 -239.363758)
		(width 0.088646)
		(layer "In11.Cu")
		(net "M_H_CPU0_SB_DQ<2>")
	)
	(arc
		(start 376.309636 -239.363758)
		(mid 376.035437 -239.287923)
		(end 375.758964 -239.355122)
		(width 0.088646)
		(layer "In11.Cu")
		(net "M_H_CPU0_SB_DQ<2>")
	)
	(arc
		(start 379.129036 -239.363758)
		(mid 378.854837 -239.287923)
		(end 378.578364 -239.355122)
		(width 0.088646)
		(layer "In11.Cu")
		(net "M_H_CPU0_SB_DQ<2>")
	)
	(segment
		(start 370.388134 -227.367084)
		(end 370.38788 -227.36683)
		(width 0.20066)
		(layer "F.Cu")
		(net "M_H_CPU0_SB_DQ<29>")
	)
	(segment
		(start 370.38788 -227.36683)
		(end 370.38788 -226.831144)
		(width 0.20066)
		(layer "F.Cu")
		(net "M_H_CPU0_SB_DQ<29>")
	)
	(segment
		(start 457.120244 -196.041772)
		(end 454.931526 -196.041772)
		(width 0.1016)
		(layer "F.Cu")
		(net "M_H_CPU0_SB_DQ<29>")
	)
	(segment
		(start 454.566782 -196.041772)
		(end 454.448672 -196.159882)
		(width 0.20066)
		(layer "F.Cu")
		(net "M_H_CPU0_SB_DQ<29>")
	)
	(segment
		(start 454.91146 -196.041772)
		(end 454.566782 -196.041772)
		(width 0.20066)
		(layer "F.Cu")
		(net "M_H_CPU0_SB_DQ<29>")
	)
	(segment
		(start 452.016114 -196.466714)
		(end 450.911214 -196.466714)
		(width 0.20066)
		(layer "F.Cu")
		(net "M_H_CPU0_SB_DQ<29>")
	)
	(segment
		(start 454.931526 -196.041772)
		(end 454.91146 -196.041772)
		(width 0.101854)
		(layer "F.Cu")
		(net "M_H_CPU0_SB_DQ<29>")
	)
	(segment
		(start 457.53655 -196.035422)
		(end 457.126594 -196.035422)
		(width 0.20066)
		(layer "F.Cu")
		(net "M_H_CPU0_SB_DQ<29>")
	)
	(segment
		(start 459.559914 -196.466714)
		(end 459.55966 -196.466968)
		(width 0.20066)
		(layer "F.Cu")
		(net "M_H_CPU0_SB_DQ<29>")
	)
	(segment
		(start 457.968096 -196.466968)
		(end 457.53655 -196.035422)
		(width 0.20066)
		(layer "F.Cu")
		(net "M_H_CPU0_SB_DQ<29>")
	)
	(segment
		(start 457.126594 -196.035422)
		(end 457.120244 -196.041772)
		(width 0.1016)
		(layer "F.Cu")
		(net "M_H_CPU0_SB_DQ<29>")
	)
	(segment
		(start 459.55966 -196.466968)
		(end 457.968096 -196.466968)
		(width 0.20066)
		(layer "F.Cu")
		(net "M_H_CPU0_SB_DQ<29>")
	)
	(segment
		(start 453.785478 -196.71538)
		(end 453.536812 -196.466714)
		(width 0.20066)
		(layer "F.Cu")
		(net "M_H_CPU0_SB_DQ<29>")
	)
	(segment
		(start 454.260712 -196.71538)
		(end 453.785478 -196.71538)
		(width 0.20066)
		(layer "F.Cu")
		(net "M_H_CPU0_SB_DQ<29>")
	)
	(segment
		(start 454.448672 -196.52742)
		(end 454.260712 -196.71538)
		(width 0.20066)
		(layer "F.Cu")
		(net "M_H_CPU0_SB_DQ<29>")
	)
	(segment
		(start 454.448672 -196.159882)
		(end 454.448672 -196.52742)
		(width 0.20066)
		(layer "F.Cu")
		(net "M_H_CPU0_SB_DQ<29>")
	)
	(segment
		(start 453.536812 -196.466714)
		(end 452.016114 -196.466714)
		(width 0.20066)
		(layer "F.Cu")
		(net "M_H_CPU0_SB_DQ<29>")
	)
	(segment
		(start 443.283086 -196.143626)
		(end 442.419486 -195.280026)
		(width 0.18288)
		(layer "In11.Cu")
		(net "M_H_CPU0_SB_DQ<29>")
	)
	(segment
		(start 371.045232 -226.341686)
		(end 371.039136 -226.345242)
		(width 0.088646)
		(layer "In11.Cu")
		(net "M_H_CPU0_SB_DQ<29>")
	)
	(segment
		(start 418.517324 -194.887596)
		(end 417.587684 -195.27266)
		(width 0.18288)
		(layer "In11.Cu")
		(net "M_H_CPU0_SB_DQ<29>")
	)
	(segment
		(start 441.721494 -195.280026)
		(end 440.400694 -193.959226)
		(width 0.18288)
		(layer "In11.Cu")
		(net "M_H_CPU0_SB_DQ<29>")
	)
	(segment
		(start 415.80562 -195.026534)
		(end 415.245804 -195.026534)
		(width 0.18288)
		(layer "In11.Cu")
		(net "M_H_CPU0_SB_DQ<29>")
	)
	(segment
		(start 392.528552 -211.71281)
		(end 392.528552 -214.499952)
		(width 0.18288)
		(layer "In11.Cu")
		(net "M_H_CPU0_SB_DQ<29>")
	)
	(segment
		(start 385.621022 -223.894904)
		(end 385.612132 -223.899984)
		(width 0.088646)
		(layer "In11.Cu")
		(net "M_H_CPU0_SB_DQ<29>")
	)
	(segment
		(start 416.39998 -195.27266)
		(end 415.80562 -195.026534)
		(width 0.18288)
		(layer "In11.Cu")
		(net "M_H_CPU0_SB_DQ<29>")
	)
	(segment
		(start 373.112284 -225.99523)
		(end 373.112284 -226.017328)
		(width 0.088646)
		(layer "In11.Cu")
		(net "M_H_CPU0_SB_DQ<29>")
	)
	(segment
		(start 430.532286 -193.959226)
		(end 430.339246 -194.152266)
		(width 0.18288)
		(layer "In11.Cu")
		(net "M_H_CPU0_SB_DQ<29>")
	)
	(segment
		(start 387.612636 -219.688918)
		(end 387.612636 -219.93606)
		(width 0.088646)
		(layer "In11.Cu")
		(net "M_H_CPU0_SB_DQ<29>")
	)
	(segment
		(start 385.329684 -224.379536)
		(end 385.329684 -224.389442)
		(width 0.088646)
		(layer "In11.Cu")
		(net "M_H_CPU0_SB_DQ<29>")
	)
	(segment
		(start 429.635666 -194.152266)
		(end 429.442626 -193.959226)
		(width 0.18288)
		(layer "In11.Cu")
		(net "M_H_CPU0_SB_DQ<29>")
	)
	(segment
		(start 450.911214 -196.466714)
		(end 450.41185 -195.96735)
		(width 0.18288)
		(layer "In11.Cu")
		(net "M_H_CPU0_SB_DQ<29>")
	)
	(segment
		(start 370.700554 -226.831144)
		(end 370.38788 -226.831144)
		(width 0.088646)
		(layer "In11.Cu")
		(net "M_H_CPU0_SB_DQ<29>")
	)
	(segment
		(start 387.612636 -219.93606)
		(end 387.216396 -220.3323)
		(width 0.088646)
		(layer "In11.Cu")
		(net "M_H_CPU0_SB_DQ<29>")
	)
	(segment
		(start 442.419486 -195.280026)
		(end 441.721494 -195.280026)
		(width 0.18288)
		(layer "In11.Cu")
		(net "M_H_CPU0_SB_DQ<29>")
	)
	(segment
		(start 445.93637 -195.96735)
		(end 445.760094 -196.143626)
		(width 0.18288)
		(layer "In11.Cu")
		(net "M_H_CPU0_SB_DQ<29>")
	)
	(segment
		(start 440.400694 -193.959226)
		(end 430.532286 -193.959226)
		(width 0.18288)
		(layer "In11.Cu")
		(net "M_H_CPU0_SB_DQ<29>")
	)
	(segment
		(start 409.311094 -195.915026)
		(end 408.625294 -196.600826)
		(width 0.18288)
		(layer "In11.Cu")
		(net "M_H_CPU0_SB_DQ<29>")
	)
	(segment
		(start 379.598682 -225.527616)
		(end 379.58395 -225.51898)
		(width 0.088646)
		(layer "In11.Cu")
		(net "M_H_CPU0_SB_DQ<29>")
	)
	(segment
		(start 386.647182 -223.085914)
		(end 386.636768 -223.079818)
		(width 0.088646)
		(layer "In11.Cu")
		(net "M_H_CPU0_SB_DQ<29>")
	)
	(segment
		(start 415.086546 -195.092574)
		(end 414.060894 -196.118226)
		(width 0.18288)
		(layer "In11.Cu")
		(net "M_H_CPU0_SB_DQ<29>")
	)
	(segment
		(start 406.301702 -197.93331)
		(end 404.25243 -197.93331)
		(width 0.18288)
		(layer "In11.Cu")
		(net "M_H_CPU0_SB_DQ<29>")
	)
	(segment
		(start 450.41185 -195.96735)
		(end 445.93637 -195.96735)
		(width 0.18288)
		(layer "In11.Cu")
		(net "M_H_CPU0_SB_DQ<29>")
	)
	(segment
		(start 404.25243 -197.93331)
		(end 400.468592 -201.717148)
		(width 0.18288)
		(layer "In11.Cu")
		(net "M_H_CPU0_SB_DQ<29>")
	)
	(segment
		(start 445.760094 -196.143626)
		(end 443.283086 -196.143626)
		(width 0.18288)
		(layer "In11.Cu")
		(net "M_H_CPU0_SB_DQ<29>")
	)
	(segment
		(start 430.146206 -194.698366)
		(end 429.828706 -194.698366)
		(width 0.18288)
		(layer "In11.Cu")
		(net "M_H_CPU0_SB_DQ<29>")
	)
	(segment
		(start 376.779282 -225.527616)
		(end 376.76455 -225.51898)
		(width 0.088646)
		(layer "In11.Cu")
		(net "M_H_CPU0_SB_DQ<29>")
	)
	(segment
		(start 387.612636 -219.415868)
		(end 387.612636 -219.688918)
		(width 0.18288)
		(layer "In11.Cu")
		(net "M_H_CPU0_SB_DQ<29>")
	)
	(segment
		(start 381.478536 -225.527616)
		(end 381.468122 -225.52152)
		(width 0.088646)
		(layer "In11.Cu")
		(net "M_H_CPU0_SB_DQ<29>")
	)
	(segment
		(start 429.635666 -194.505326)
		(end 429.635666 -194.152266)
		(width 0.18288)
		(layer "In11.Cu")
		(net "M_H_CPU0_SB_DQ<29>")
	)
	(segment
		(start 417.587684 -195.27266)
		(end 416.39998 -195.27266)
		(width 0.18288)
		(layer "In11.Cu")
		(net "M_H_CPU0_SB_DQ<29>")
	)
	(segment
		(start 383.828036 -224.7138)
		(end 383.817622 -224.707704)
		(width 0.088646)
		(layer "In11.Cu")
		(net "M_H_CPU0_SB_DQ<29>")
	)
	(segment
		(start 408.625294 -196.600826)
		(end 407.634186 -196.600826)
		(width 0.18288)
		(layer "In11.Cu")
		(net "M_H_CPU0_SB_DQ<29>")
	)
	(segment
		(start 370.76634 -226.765358)
		(end 370.700554 -226.831144)
		(width 0.088646)
		(layer "In11.Cu")
		(net "M_H_CPU0_SB_DQ<29>")
	)
	(segment
		(start 400.468592 -203.77277)
		(end 392.528552 -211.71281)
		(width 0.18288)
		(layer "In11.Cu")
		(net "M_H_CPU0_SB_DQ<29>")
	)
	(segment
		(start 430.339246 -194.505326)
		(end 430.146206 -194.698366)
		(width 0.18288)
		(layer "In11.Cu")
		(net "M_H_CPU0_SB_DQ<29>")
	)
	(segment
		(start 382.980184 -225.187764)
		(end 382.980184 -225.203258)
		(width 0.088646)
		(layer "In11.Cu")
		(net "M_H_CPU0_SB_DQ<29>")
	)
	(segment
		(start 375.839482 -225.527616)
		(end 375.82475 -225.51898)
		(width 0.088646)
		(layer "In11.Cu")
		(net "M_H_CPU0_SB_DQ<29>")
	)
	(segment
		(start 392.528552 -214.499952)
		(end 387.612636 -219.415868)
		(width 0.18288)
		(layer "In11.Cu")
		(net "M_H_CPU0_SB_DQ<29>")
	)
	(segment
		(start 378.658882 -225.527616)
		(end 378.64415 -225.51898)
		(width 0.088646)
		(layer "In11.Cu")
		(net "M_H_CPU0_SB_DQ<29>")
	)
	(segment
		(start 373.959882 -225.527616)
		(end 373.94515 -225.51898)
		(width 0.088646)
		(layer "In11.Cu")
		(net "M_H_CPU0_SB_DQ<29>")
	)
	(segment
		(start 372.933722 -226.336606)
		(end 372.924832 -226.341686)
		(width 0.088646)
		(layer "In11.Cu")
		(net "M_H_CPU0_SB_DQ<29>")
	)
	(segment
		(start 412.359094 -195.915026)
		(end 409.311094 -195.915026)
		(width 0.18288)
		(layer "In11.Cu")
		(net "M_H_CPU0_SB_DQ<29>")
	)
	(segment
		(start 429.828706 -194.698366)
		(end 429.635666 -194.505326)
		(width 0.18288)
		(layer "In11.Cu")
		(net "M_H_CPU0_SB_DQ<29>")
	)
	(segment
		(start 412.562294 -196.118226)
		(end 412.359094 -195.915026)
		(width 0.18288)
		(layer "In11.Cu")
		(net "M_H_CPU0_SB_DQ<29>")
	)
	(segment
		(start 387.216396 -220.3323)
		(end 387.216396 -222.9104)
		(width 0.088646)
		(layer "In11.Cu")
		(net "M_H_CPU0_SB_DQ<29>")
	)
	(segment
		(start 400.468592 -201.717148)
		(end 400.468592 -203.77277)
		(width 0.18288)
		(layer "In11.Cu")
		(net "M_H_CPU0_SB_DQ<29>")
	)
	(segment
		(start 382.801622 -225.522536)
		(end 382.792732 -225.527616)
		(width 0.088646)
		(layer "In11.Cu")
		(net "M_H_CPU0_SB_DQ<29>")
	)
	(segment
		(start 374.899682 -225.527616)
		(end 374.88495 -225.51898)
		(width 0.088646)
		(layer "In11.Cu")
		(net "M_H_CPU0_SB_DQ<29>")
	)
	(segment
		(start 371.059964 -226.33305)
		(end 371.045232 -226.341686)
		(width 0.088646)
		(layer "In11.Cu")
		(net "M_H_CPU0_SB_DQ<29>")
	)
	(segment
		(start 430.339246 -194.152266)
		(end 430.339246 -194.505326)
		(width 0.18288)
		(layer "In11.Cu")
		(net "M_H_CPU0_SB_DQ<29>")
	)
	(segment
		(start 387.216396 -222.9104)
		(end 387.09981 -223.026986)
		(width 0.088646)
		(layer "In11.Cu")
		(net "M_H_CPU0_SB_DQ<29>")
	)
	(segment
		(start 414.060894 -196.118226)
		(end 412.562294 -196.118226)
		(width 0.18288)
		(layer "In11.Cu")
		(net "M_H_CPU0_SB_DQ<29>")
	)
	(segment
		(start 385.151122 -224.70872)
		(end 385.142232 -224.7138)
		(width 0.088646)
		(layer "In11.Cu")
		(net "M_H_CPU0_SB_DQ<29>")
	)
	(segment
		(start 380.538482 -225.527616)
		(end 380.52375 -225.51898)
		(width 0.088646)
		(layer "In11.Cu")
		(net "M_H_CPU0_SB_DQ<29>")
	)
	(segment
		(start 415.245804 -195.026534)
		(end 415.086546 -195.092574)
		(width 0.18288)
		(layer "In11.Cu")
		(net "M_H_CPU0_SB_DQ<29>")
	)
	(segment
		(start 385.799584 -223.557084)
		(end 385.799584 -223.575626)
		(width 0.088646)
		(layer "In11.Cu")
		(net "M_H_CPU0_SB_DQ<29>")
	)
	(segment
		(start 429.442626 -193.959226)
		(end 419.445694 -193.959226)
		(width 0.18288)
		(layer "In11.Cu")
		(net "M_H_CPU0_SB_DQ<29>")
	)
	(segment
		(start 377.719082 -225.527616)
		(end 377.70435 -225.51898)
		(width 0.088646)
		(layer "In11.Cu")
		(net "M_H_CPU0_SB_DQ<29>")
	)
	(segment
		(start 407.634186 -196.600826)
		(end 406.301702 -197.93331)
		(width 0.18288)
		(layer "In11.Cu")
		(net "M_H_CPU0_SB_DQ<29>")
	)
	(segment
		(start 419.445694 -193.959226)
		(end 418.517324 -194.887596)
		(width 0.18288)
		(layer "In11.Cu")
		(net "M_H_CPU0_SB_DQ<29>")
	)
	(arc
		(start 380.52375 -225.51898)
		(mid 380.247309 -225.451814)
		(end 379.973078 -225.527616)
		(width 0.088646)
		(layer "In11.Cu")
		(net "M_H_CPU0_SB_DQ<29>")
	)
	(arc
		(start 377.153678 -225.527616)
		(mid 376.96648 -225.577759)
		(end 376.779282 -225.527616)
		(width 0.088646)
		(layer "In11.Cu")
		(net "M_H_CPU0_SB_DQ<29>")
	)
	(arc
		(start 372.924832 -226.341686)
		(mid 372.737634 -226.391829)
		(end 372.550436 -226.341686)
		(width 0.088646)
		(layer "In11.Cu")
		(net "M_H_CPU0_SB_DQ<29>")
	)
	(arc
		(start 379.973078 -225.527616)
		(mid 379.78588 -225.577759)
		(end 379.598682 -225.527616)
		(width 0.088646)
		(layer "In11.Cu")
		(net "M_H_CPU0_SB_DQ<29>")
	)
	(arc
		(start 385.799584 -223.575626)
		(mid 385.751905 -223.758526)
		(end 385.621022 -223.894904)
		(width 0.088646)
		(layer "In11.Cu")
		(net "M_H_CPU0_SB_DQ<29>")
	)
	(arc
		(start 374.88495 -225.51898)
		(mid 374.608509 -225.451814)
		(end 374.334278 -225.527616)
		(width 0.088646)
		(layer "In11.Cu")
		(net "M_H_CPU0_SB_DQ<29>")
	)
	(arc
		(start 371.039136 -226.345242)
		(mid 370.853681 -226.523437)
		(end 370.76634 -226.765358)
		(width 0.088646)
		(layer "In11.Cu")
		(net "M_H_CPU0_SB_DQ<29>")
	)
	(arc
		(start 385.612132 -223.899984)
		(mid 385.407797 -224.102589)
		(end 385.329684 -224.379536)
		(width 0.088646)
		(layer "In11.Cu")
		(net "M_H_CPU0_SB_DQ<29>")
	)
	(arc
		(start 384.202432 -224.7138)
		(mid 384.015234 -224.763943)
		(end 383.828036 -224.7138)
		(width 0.088646)
		(layer "In11.Cu")
		(net "M_H_CPU0_SB_DQ<29>")
	)
	(arc
		(start 387.09981 -223.026986)
		(mid 387.062619 -223.059004)
		(end 387.021578 -223.085914)
		(width 0.088646)
		(layer "In11.Cu")
		(net "M_H_CPU0_SB_DQ<29>")
	)
	(arc
		(start 379.033278 -225.527616)
		(mid 378.84608 -225.577759)
		(end 378.658882 -225.527616)
		(width 0.088646)
		(layer "In11.Cu")
		(net "M_H_CPU0_SB_DQ<29>")
	)
	(arc
		(start 371.985032 -226.341686)
		(mid 371.797834 -226.391829)
		(end 371.610636 -226.341686)
		(width 0.088646)
		(layer "In11.Cu")
		(net "M_H_CPU0_SB_DQ<29>")
	)
	(arc
		(start 372.550436 -226.341686)
		(mid 372.267734 -226.26591)
		(end 371.985032 -226.341686)
		(width 0.088646)
		(layer "In11.Cu")
		(net "M_H_CPU0_SB_DQ<29>")
	)
	(arc
		(start 382.418336 -225.527616)
		(mid 382.135634 -225.451874)
		(end 381.852932 -225.527616)
		(width 0.088646)
		(layer "In11.Cu")
		(net "M_H_CPU0_SB_DQ<29>")
	)
	(arc
		(start 383.262378 -224.7138)
		(mid 383.059555 -224.914031)
		(end 382.980184 -225.187764)
		(width 0.088646)
		(layer "In11.Cu")
		(net "M_H_CPU0_SB_DQ<29>")
	)
	(arc
		(start 371.610636 -226.341686)
		(mid 371.336437 -226.265851)
		(end 371.059964 -226.33305)
		(width 0.088646)
		(layer "In11.Cu")
		(net "M_H_CPU0_SB_DQ<29>")
	)
	(arc
		(start 386.636768 -223.079818)
		(mid 386.35859 -223.010126)
		(end 386.082032 -223.085914)
		(width 0.088646)
		(layer "In11.Cu")
		(net "M_H_CPU0_SB_DQ<29>")
	)
	(arc
		(start 377.70435 -225.51898)
		(mid 377.427909 -225.451814)
		(end 377.153678 -225.527616)
		(width 0.088646)
		(layer "In11.Cu")
		(net "M_H_CPU0_SB_DQ<29>")
	)
	(arc
		(start 385.329684 -224.389442)
		(mid 385.282005 -224.572342)
		(end 385.151122 -224.70872)
		(width 0.088646)
		(layer "In11.Cu")
		(net "M_H_CPU0_SB_DQ<29>")
	)
	(arc
		(start 373.394478 -225.527616)
		(mid 373.193196 -225.725103)
		(end 373.112284 -225.99523)
		(width 0.088646)
		(layer "In11.Cu")
		(net "M_H_CPU0_SB_DQ<29>")
	)
	(arc
		(start 378.093478 -225.527616)
		(mid 377.90628 -225.577759)
		(end 377.719082 -225.527616)
		(width 0.088646)
		(layer "In11.Cu")
		(net "M_H_CPU0_SB_DQ<29>")
	)
	(arc
		(start 376.76455 -225.51898)
		(mid 376.488109 -225.451814)
		(end 376.213878 -225.527616)
		(width 0.088646)
		(layer "In11.Cu")
		(net "M_H_CPU0_SB_DQ<29>")
	)
	(arc
		(start 376.213878 -225.527616)
		(mid 376.02668 -225.577759)
		(end 375.839482 -225.527616)
		(width 0.088646)
		(layer "In11.Cu")
		(net "M_H_CPU0_SB_DQ<29>")
	)
	(arc
		(start 374.334278 -225.527616)
		(mid 374.14708 -225.577759)
		(end 373.959882 -225.527616)
		(width 0.088646)
		(layer "In11.Cu")
		(net "M_H_CPU0_SB_DQ<29>")
	)
	(arc
		(start 382.792732 -225.527616)
		(mid 382.605534 -225.577759)
		(end 382.418336 -225.527616)
		(width 0.088646)
		(layer "In11.Cu")
		(net "M_H_CPU0_SB_DQ<29>")
	)
	(arc
		(start 386.082032 -223.085914)
		(mid 385.879746 -223.284895)
		(end 385.799584 -223.557084)
		(width 0.088646)
		(layer "In11.Cu")
		(net "M_H_CPU0_SB_DQ<29>")
	)
	(arc
		(start 380.912878 -225.527616)
		(mid 380.72568 -225.577759)
		(end 380.538482 -225.527616)
		(width 0.088646)
		(layer "In11.Cu")
		(net "M_H_CPU0_SB_DQ<29>")
	)
	(arc
		(start 379.58395 -225.51898)
		(mid 379.307509 -225.451814)
		(end 379.033278 -225.527616)
		(width 0.088646)
		(layer "In11.Cu")
		(net "M_H_CPU0_SB_DQ<29>")
	)
	(arc
		(start 373.112284 -226.017328)
		(mid 373.064605 -226.200228)
		(end 372.933722 -226.336606)
		(width 0.088646)
		(layer "In11.Cu")
		(net "M_H_CPU0_SB_DQ<29>")
	)
	(arc
		(start 382.980184 -225.203258)
		(mid 382.932505 -225.386158)
		(end 382.801622 -225.522536)
		(width 0.088646)
		(layer "In11.Cu")
		(net "M_H_CPU0_SB_DQ<29>")
	)
	(arc
		(start 381.852932 -225.527616)
		(mid 381.665734 -225.577759)
		(end 381.478536 -225.527616)
		(width 0.088646)
		(layer "In11.Cu")
		(net "M_H_CPU0_SB_DQ<29>")
	)
	(arc
		(start 373.94515 -225.51898)
		(mid 373.668709 -225.451814)
		(end 373.394478 -225.527616)
		(width 0.088646)
		(layer "In11.Cu")
		(net "M_H_CPU0_SB_DQ<29>")
	)
	(arc
		(start 384.767836 -224.7138)
		(mid 384.485134 -224.638024)
		(end 384.202432 -224.7138)
		(width 0.088646)
		(layer "In11.Cu")
		(net "M_H_CPU0_SB_DQ<29>")
	)
	(arc
		(start 385.142232 -224.7138)
		(mid 384.955034 -224.763943)
		(end 384.767836 -224.7138)
		(width 0.088646)
		(layer "In11.Cu")
		(net "M_H_CPU0_SB_DQ<29>")
	)
	(arc
		(start 375.82475 -225.51898)
		(mid 375.548309 -225.451814)
		(end 375.274078 -225.527616)
		(width 0.088646)
		(layer "In11.Cu")
		(net "M_H_CPU0_SB_DQ<29>")
	)
	(arc
		(start 381.468122 -225.52152)
		(mid 381.18969 -225.451706)
		(end 380.912878 -225.527616)
		(width 0.088646)
		(layer "In11.Cu")
		(net "M_H_CPU0_SB_DQ<29>")
	)
	(arc
		(start 383.817622 -224.707704)
		(mid 383.53919 -224.637858)
		(end 383.262378 -224.7138)
		(width 0.088646)
		(layer "In11.Cu")
		(net "M_H_CPU0_SB_DQ<29>")
	)
	(arc
		(start 375.274078 -225.527616)
		(mid 375.08688 -225.577759)
		(end 374.899682 -225.527616)
		(width 0.088646)
		(layer "In11.Cu")
		(net "M_H_CPU0_SB_DQ<29>")
	)
	(arc
		(start 387.021578 -223.085914)
		(mid 386.83438 -223.136057)
		(end 386.647182 -223.085914)
		(width 0.088646)
		(layer "In11.Cu")
		(net "M_H_CPU0_SB_DQ<29>")
	)
	(arc
		(start 378.64415 -225.51898)
		(mid 378.367709 -225.451814)
		(end 378.093478 -225.527616)
		(width 0.088646)
		(layer "In11.Cu")
		(net "M_H_CPU0_SB_DQ<29>")
	)
	(segment
		(start 454.91146 -197.741794)
		(end 454.566782 -197.741794)
		(width 0.20066)
		(layer "F.Cu")
		(net "M_H_CPU0_SB_DQ<28>")
	)
	(segment
		(start 454.95845 -197.741794)
		(end 454.91146 -197.741794)
		(width 0.101854)
		(layer "F.Cu")
		(net "M_H_CPU0_SB_DQ<28>")
	)
	(segment
		(start 373.20728 -227.36683)
		(end 373.20728 -226.831144)
		(width 0.20066)
		(layer "F.Cu")
		(net "M_H_CPU0_SB_DQ<28>")
	)
	(segment
		(start 457.126594 -197.735444)
		(end 457.120244 -197.741794)
		(width 0.1016)
		(layer "F.Cu")
		(net "M_H_CPU0_SB_DQ<28>")
	)
	(segment
		(start 457.120244 -197.741794)
		(end 454.95845 -197.741794)
		(width 0.1016)
		(layer "F.Cu")
		(net "M_H_CPU0_SB_DQ<28>")
	)
	(segment
		(start 452.016114 -198.166736)
		(end 450.911214 -198.166736)
		(width 0.20066)
		(layer "F.Cu")
		(net "M_H_CPU0_SB_DQ<28>")
	)
	(segment
		(start 373.207534 -227.367084)
		(end 373.20728 -227.36683)
		(width 0.20066)
		(layer "F.Cu")
		(net "M_H_CPU0_SB_DQ<28>")
	)
	(segment
		(start 459.559914 -198.166736)
		(end 459.55966 -198.16699)
		(width 0.20066)
		(layer "F.Cu")
		(net "M_H_CPU0_SB_DQ<28>")
	)
	(segment
		(start 454.448672 -197.859904)
		(end 454.448672 -198.227442)
		(width 0.20066)
		(layer "F.Cu")
		(net "M_H_CPU0_SB_DQ<28>")
	)
	(segment
		(start 454.566782 -197.741794)
		(end 454.448672 -197.859904)
		(width 0.20066)
		(layer "F.Cu")
		(net "M_H_CPU0_SB_DQ<28>")
	)
	(segment
		(start 453.785478 -198.415402)
		(end 453.536812 -198.166736)
		(width 0.20066)
		(layer "F.Cu")
		(net "M_H_CPU0_SB_DQ<28>")
	)
	(segment
		(start 454.448672 -198.227442)
		(end 454.260712 -198.415402)
		(width 0.20066)
		(layer "F.Cu")
		(net "M_H_CPU0_SB_DQ<28>")
	)
	(segment
		(start 457.968096 -198.16699)
		(end 457.53655 -197.735444)
		(width 0.20066)
		(layer "F.Cu")
		(net "M_H_CPU0_SB_DQ<28>")
	)
	(segment
		(start 457.53655 -197.735444)
		(end 457.126594 -197.735444)
		(width 0.20066)
		(layer "F.Cu")
		(net "M_H_CPU0_SB_DQ<28>")
	)
	(segment
		(start 459.55966 -198.16699)
		(end 457.968096 -198.16699)
		(width 0.20066)
		(layer "F.Cu")
		(net "M_H_CPU0_SB_DQ<28>")
	)
	(segment
		(start 453.536812 -198.166736)
		(end 452.016114 -198.166736)
		(width 0.20066)
		(layer "F.Cu")
		(net "M_H_CPU0_SB_DQ<28>")
	)
	(segment
		(start 454.260712 -198.415402)
		(end 453.785478 -198.415402)
		(width 0.20066)
		(layer "F.Cu")
		(net "M_H_CPU0_SB_DQ<28>")
	)
	(segment
		(start 417.878006 -197.487032)
		(end 417.560506 -197.487032)
		(width 0.18288)
		(layer "In11.Cu")
		(net "M_H_CPU0_SB_DQ<28>")
	)
	(segment
		(start 404.4696 -199.521826)
		(end 401.650962 -202.340464)
		(width 0.18288)
		(layer "In11.Cu")
		(net "M_H_CPU0_SB_DQ<28>")
	)
	(segment
		(start 433.03825 -196.62902)
		(end 433.03825 -196.92239)
		(width 0.18288)
		(layer "In11.Cu")
		(net "M_H_CPU0_SB_DQ<28>")
	)
	(segment
		(start 443.372494 -197.972426)
		(end 442.432694 -197.032626)
		(width 0.18288)
		(layer "In11.Cu")
		(net "M_H_CPU0_SB_DQ<28>")
	)
	(segment
		(start 448.199256 -198.465186)
		(end 448.006216 -198.658226)
		(width 0.18288)
		(layer "In11.Cu")
		(net "M_H_CPU0_SB_DQ<28>")
	)
	(segment
		(start 387.761226 -223.088708)
		(end 387.025642 -223.824292)
		(width 0.088646)
		(layer "In11.Cu")
		(net "M_H_CPU0_SB_DQ<28>")
	)
	(segment
		(start 377.638564 -226.33305)
		(end 377.623832 -226.341686)
		(width 0.088646)
		(layer "In11.Cu")
		(net "M_H_CPU0_SB_DQ<28>")
	)
	(segment
		(start 450.911214 -198.464932)
		(end 450.798946 -198.5772)
		(width 0.18288)
		(layer "In11.Cu")
		(net "M_H_CPU0_SB_DQ<28>")
	)
	(segment
		(start 427.319694 -196.981826)
		(end 426.913294 -196.981826)
		(width 0.18288)
		(layer "In11.Cu")
		(net "M_H_CPU0_SB_DQ<28>")
	)
	(segment
		(start 421.884094 -196.194426)
		(end 421.184324 -196.894196)
		(width 0.18288)
		(layer "In11.Cu")
		(net "M_H_CPU0_SB_DQ<28>")
	)
	(segment
		(start 440.628786 -196.041518)
		(end 438.877202 -196.041518)
		(width 0.18288)
		(layer "In11.Cu")
		(net "M_H_CPU0_SB_DQ<28>")
	)
	(segment
		(start 425.922694 -196.677026)
		(end 425.287186 -196.041518)
		(width 0.18288)
		(layer "In11.Cu")
		(net "M_H_CPU0_SB_DQ<28>")
	)
	(segment
		(start 434.00345 -197.11543)
		(end 433.81041 -196.92239)
		(width 0.18288)
		(layer "In11.Cu")
		(net "M_H_CPU0_SB_DQ<28>")
	)
	(segment
		(start 383.271522 -226.336606)
		(end 383.262632 -226.341686)
		(width 0.088646)
		(layer "In11.Cu")
		(net "M_H_CPU0_SB_DQ<28>")
	)
	(segment
		(start 380.457964 -226.33305)
		(end 380.443232 -226.341686)
		(width 0.088646)
		(layer "In11.Cu")
		(net "M_H_CPU0_SB_DQ<28>")
	)
	(segment
		(start 436.757318 -196.891402)
		(end 434.928518 -196.891402)
		(width 0.18288)
		(layer "In11.Cu")
		(net "M_H_CPU0_SB_DQ<28>")
	)
	(segment
		(start 373.864632 -226.341686)
		(end 373.858536 -226.345242)
		(width 0.088646)
		(layer "In11.Cu")
		(net "M_H_CPU0_SB_DQ<28>")
	)
	(segment
		(start 410.669994 -198.632826)
		(end 409.158694 -198.632826)
		(width 0.18288)
		(layer "In11.Cu")
		(net "M_H_CPU0_SB_DQ<28>")
	)
	(segment
		(start 408.269694 -199.521826)
		(end 404.4696 -199.521826)
		(width 0.18288)
		(layer "In11.Cu")
		(net "M_H_CPU0_SB_DQ<28>")
	)
	(segment
		(start 421.184324 -196.894196)
		(end 418.269166 -196.894196)
		(width 0.18288)
		(layer "In11.Cu")
		(net "M_H_CPU0_SB_DQ<28>")
	)
	(segment
		(start 448.199256 -198.217282)
		(end 448.199256 -198.465186)
		(width 0.18288)
		(layer "In11.Cu")
		(net "M_H_CPU0_SB_DQ<28>")
	)
	(segment
		(start 401.650962 -202.340464)
		(end 401.650962 -204.115416)
		(width 0.18288)
		(layer "In11.Cu")
		(net "M_H_CPU0_SB_DQ<28>")
	)
	(segment
		(start 388.20471 -220.572838)
		(end 387.761226 -221.016322)
		(width 0.088646)
		(layer "In11.Cu")
		(net "M_H_CPU0_SB_DQ<28>")
	)
	(segment
		(start 429.68926 -197.672198)
		(end 429.49622 -197.865238)
		(width 0.18288)
		(layer "In11.Cu")
		(net "M_H_CPU0_SB_DQ<28>")
	)
	(segment
		(start 417.367466 -197.293992)
		(end 417.367466 -197.092316)
		(width 0.18288)
		(layer "In11.Cu")
		(net "M_H_CPU0_SB_DQ<28>")
	)
	(segment
		(start 385.799584 -225.193352)
		(end 385.799584 -225.203258)
		(width 0.088646)
		(layer "In11.Cu")
		(net "M_H_CPU0_SB_DQ<28>")
	)
	(segment
		(start 418.269166 -196.894196)
		(end 418.071046 -197.092316)
		(width 0.18288)
		(layer "In11.Cu")
		(net "M_H_CPU0_SB_DQ<28>")
	)
	(segment
		(start 428.9171 -197.047866)
		(end 428.72406 -196.854826)
		(width 0.18288)
		(layer "In11.Cu")
		(net "M_H_CPU0_SB_DQ<28>")
	)
	(segment
		(start 385.621022 -225.522536)
		(end 385.612132 -225.527616)
		(width 0.088646)
		(layer "In11.Cu")
		(net "M_H_CPU0_SB_DQ<28>")
	)
	(segment
		(start 409.158694 -198.632826)
		(end 408.269694 -199.521826)
		(width 0.18288)
		(layer "In11.Cu")
		(net "M_H_CPU0_SB_DQ<28>")
	)
	(segment
		(start 416.026346 -198.290434)
		(end 414.72485 -198.290434)
		(width 0.18288)
		(layer "In11.Cu")
		(net "M_H_CPU0_SB_DQ<28>")
	)
	(segment
		(start 446.852294 -198.658226)
		(end 446.166494 -197.972426)
		(width 0.18288)
		(layer "In11.Cu")
		(net "M_H_CPU0_SB_DQ<28>")
	)
	(segment
		(start 417.174426 -196.899276)
		(end 416.835844 -196.899276)
		(width 0.18288)
		(layer "In11.Cu")
		(net "M_H_CPU0_SB_DQ<28>")
	)
	(segment
		(start 448.778376 -198.024242)
		(end 448.392296 -198.024242)
		(width 0.18288)
		(layer "In11.Cu")
		(net "M_H_CPU0_SB_DQ<28>")
	)
	(segment
		(start 423.281602 -196.041518)
		(end 423.128694 -196.194426)
		(width 0.18288)
		(layer "In11.Cu")
		(net "M_H_CPU0_SB_DQ<28>")
	)
	(segment
		(start 386.269738 -224.389442)
		(end 386.269484 -224.389442)
		(width 0.088646)
		(layer "In11.Cu")
		(net "M_H_CPU0_SB_DQ<28>")
	)
	(segment
		(start 412.282894 -197.693026)
		(end 411.609794 -197.693026)
		(width 0.18288)
		(layer "In11.Cu")
		(net "M_H_CPU0_SB_DQ<28>")
	)
	(segment
		(start 438.698894 -196.219826)
		(end 437.428894 -196.219826)
		(width 0.18288)
		(layer "In11.Cu")
		(net "M_H_CPU0_SB_DQ<28>")
	)
	(segment
		(start 428.9171 -197.672198)
		(end 428.9171 -197.047866)
		(width 0.18288)
		(layer "In11.Cu")
		(net "M_H_CPU0_SB_DQ<28>")
	)
	(segment
		(start 418.071046 -197.092316)
		(end 418.071046 -197.293992)
		(width 0.18288)
		(layer "In11.Cu")
		(net "M_H_CPU0_SB_DQ<28>")
	)
	(segment
		(start 431.332894 -196.854826)
		(end 429.8823 -196.854826)
		(width 0.18288)
		(layer "In11.Cu")
		(net "M_H_CPU0_SB_DQ<28>")
	)
	(segment
		(start 376.698764 -226.33305)
		(end 376.684032 -226.341686)
		(width 0.088646)
		(layer "In11.Cu")
		(net "M_H_CPU0_SB_DQ<28>")
	)
	(segment
		(start 416.507168 -197.809612)
		(end 416.026346 -198.290434)
		(width 0.18288)
		(layer "In11.Cu")
		(net "M_H_CPU0_SB_DQ<28>")
	)
	(segment
		(start 433.81041 -196.62902)
		(end 433.61737 -196.43598)
		(width 0.18288)
		(layer "In11.Cu")
		(net "M_H_CPU0_SB_DQ<28>")
	)
	(segment
		(start 446.166494 -197.972426)
		(end 443.372494 -197.972426)
		(width 0.18288)
		(layer "In11.Cu")
		(net "M_H_CPU0_SB_DQ<28>")
	)
	(segment
		(start 434.928518 -196.891402)
		(end 434.70449 -197.11543)
		(width 0.18288)
		(layer "In11.Cu")
		(net "M_H_CPU0_SB_DQ<28>")
	)
	(segment
		(start 442.432694 -197.032626)
		(end 441.619894 -197.032626)
		(width 0.18288)
		(layer "In11.Cu")
		(net "M_H_CPU0_SB_DQ<28>")
	)
	(segment
		(start 448.392296 -198.024242)
		(end 448.199256 -198.217282)
		(width 0.18288)
		(layer "In11.Cu")
		(net "M_H_CPU0_SB_DQ<28>")
	)
	(segment
		(start 429.8823 -196.854826)
		(end 429.68926 -197.047866)
		(width 0.18288)
		(layer "In11.Cu")
		(net "M_H_CPU0_SB_DQ<28>")
	)
	(segment
		(start 414.72485 -198.290434)
		(end 414.356042 -197.921626)
		(width 0.18288)
		(layer "In11.Cu")
		(net "M_H_CPU0_SB_DQ<28>")
	)
	(segment
		(start 373.519954 -226.831144)
		(end 373.20728 -226.831144)
		(width 0.088646)
		(layer "In11.Cu")
		(net "M_H_CPU0_SB_DQ<28>")
	)
	(segment
		(start 433.23129 -196.43598)
		(end 433.03825 -196.62902)
		(width 0.18288)
		(layer "In11.Cu")
		(net "M_H_CPU0_SB_DQ<28>")
	)
	(segment
		(start 426.608494 -196.677026)
		(end 425.922694 -196.677026)
		(width 0.18288)
		(layer "In11.Cu")
		(net "M_H_CPU0_SB_DQ<28>")
	)
	(segment
		(start 426.913294 -196.981826)
		(end 426.608494 -196.677026)
		(width 0.18288)
		(layer "In11.Cu")
		(net "M_H_CPU0_SB_DQ<28>")
	)
	(segment
		(start 373.879364 -226.33305)
		(end 373.864632 -226.341686)
		(width 0.088646)
		(layer "In11.Cu")
		(net "M_H_CPU0_SB_DQ<28>")
	)
	(segment
		(start 411.609794 -197.693026)
		(end 410.669994 -198.632826)
		(width 0.18288)
		(layer "In11.Cu")
		(net "M_H_CPU0_SB_DQ<28>")
	)
	(segment
		(start 418.071046 -197.293992)
		(end 417.878006 -197.487032)
		(width 0.18288)
		(layer "In11.Cu")
		(net "M_H_CPU0_SB_DQ<28>")
	)
	(segment
		(start 417.367466 -197.092316)
		(end 417.174426 -196.899276)
		(width 0.18288)
		(layer "In11.Cu")
		(net "M_H_CPU0_SB_DQ<28>")
	)
	(segment
		(start 441.619894 -197.032626)
		(end 440.628786 -196.041518)
		(width 0.18288)
		(layer "In11.Cu")
		(net "M_H_CPU0_SB_DQ<28>")
	)
	(segment
		(start 417.560506 -197.487032)
		(end 417.367466 -197.293992)
		(width 0.18288)
		(layer "In11.Cu")
		(net "M_H_CPU0_SB_DQ<28>")
	)
	(segment
		(start 429.11014 -197.865238)
		(end 428.9171 -197.672198)
		(width 0.18288)
		(layer "In11.Cu")
		(net "M_H_CPU0_SB_DQ<28>")
	)
	(segment
		(start 448.971416 -198.217282)
		(end 448.778376 -198.024242)
		(width 0.18288)
		(layer "In11.Cu")
		(net "M_H_CPU0_SB_DQ<28>")
	)
	(segment
		(start 450.603112 -198.658226)
		(end 449.164456 -198.658226)
		(width 0.18288)
		(layer "In11.Cu")
		(net "M_H_CPU0_SB_DQ<28>")
	)
	(segment
		(start 416.835844 -196.899276)
		(end 416.507168 -197.227952)
		(width 0.18288)
		(layer "In11.Cu")
		(net "M_H_CPU0_SB_DQ<28>")
	)
	(segment
		(start 425.287186 -196.041518)
		(end 423.281602 -196.041518)
		(width 0.18288)
		(layer "In11.Cu")
		(net "M_H_CPU0_SB_DQ<28>")
	)
	(segment
		(start 448.006216 -198.658226)
		(end 446.852294 -198.658226)
		(width 0.18288)
		(layer "In11.Cu")
		(net "M_H_CPU0_SB_DQ<28>")
	)
	(segment
		(start 412.511494 -197.921626)
		(end 412.282894 -197.693026)
		(width 0.18288)
		(layer "In11.Cu")
		(net "M_H_CPU0_SB_DQ<28>")
	)
	(segment
		(start 429.68926 -197.047866)
		(end 429.68926 -197.672198)
		(width 0.18288)
		(layer "In11.Cu")
		(net "M_H_CPU0_SB_DQ<28>")
	)
	(segment
		(start 379.518164 -226.33305)
		(end 379.503432 -226.341686)
		(width 0.088646)
		(layer "In11.Cu")
		(net "M_H_CPU0_SB_DQ<28>")
	)
	(segment
		(start 450.911214 -198.166736)
		(end 450.911214 -198.464932)
		(width 0.18288)
		(layer "In11.Cu")
		(net "M_H_CPU0_SB_DQ<28>")
	)
	(segment
		(start 373.58574 -226.765358)
		(end 373.519954 -226.831144)
		(width 0.088646)
		(layer "In11.Cu")
		(net "M_H_CPU0_SB_DQ<28>")
	)
	(segment
		(start 427.446694 -196.854826)
		(end 427.319694 -196.981826)
		(width 0.18288)
		(layer "In11.Cu")
		(net "M_H_CPU0_SB_DQ<28>")
	)
	(segment
		(start 387.025642 -223.824292)
		(end 386.83438 -223.824292)
		(width 0.088646)
		(layer "In11.Cu")
		(net "M_H_CPU0_SB_DQ<28>")
	)
	(segment
		(start 393.598908 -212.16747)
		(end 393.598908 -215.17864)
		(width 0.18288)
		(layer "In11.Cu")
		(net "M_H_CPU0_SB_DQ<28>")
	)
	(segment
		(start 416.507168 -197.227952)
		(end 416.507168 -197.809612)
		(width 0.18288)
		(layer "In11.Cu")
		(net "M_H_CPU0_SB_DQ<28>")
	)
	(segment
		(start 450.798946 -198.5772)
		(end 450.603112 -198.658226)
		(width 0.18288)
		(layer "In11.Cu")
		(net "M_H_CPU0_SB_DQ<28>")
	)
	(segment
		(start 432.84521 -197.11543)
		(end 431.593498 -197.11543)
		(width 0.18288)
		(layer "In11.Cu")
		(net "M_H_CPU0_SB_DQ<28>")
	)
	(segment
		(start 431.593498 -197.11543)
		(end 431.332894 -196.854826)
		(width 0.18288)
		(layer "In11.Cu")
		(net "M_H_CPU0_SB_DQ<28>")
	)
	(segment
		(start 438.877202 -196.041518)
		(end 438.698894 -196.219826)
		(width 0.18288)
		(layer "In11.Cu")
		(net "M_H_CPU0_SB_DQ<28>")
	)
	(segment
		(start 448.971416 -198.465186)
		(end 448.971416 -198.217282)
		(width 0.18288)
		(layer "In11.Cu")
		(net "M_H_CPU0_SB_DQ<28>")
	)
	(segment
		(start 386.090922 -224.70872)
		(end 386.082032 -224.7138)
		(width 0.088646)
		(layer "In11.Cu")
		(net "M_H_CPU0_SB_DQ<28>")
	)
	(segment
		(start 414.356042 -197.921626)
		(end 412.511494 -197.921626)
		(width 0.18288)
		(layer "In11.Cu")
		(net "M_H_CPU0_SB_DQ<28>")
	)
	(segment
		(start 423.128694 -196.194426)
		(end 421.884094 -196.194426)
		(width 0.18288)
		(layer "In11.Cu")
		(net "M_H_CPU0_SB_DQ<28>")
	)
	(segment
		(start 401.650962 -204.115416)
		(end 393.598908 -212.16747)
		(width 0.18288)
		(layer "In11.Cu")
		(net "M_H_CPU0_SB_DQ<28>")
	)
	(segment
		(start 383.450084 -225.998786)
		(end 383.450084 -226.017328)
		(width 0.088646)
		(layer "In11.Cu")
		(net "M_H_CPU0_SB_DQ<28>")
	)
	(segment
		(start 433.81041 -196.92239)
		(end 433.81041 -196.62902)
		(width 0.18288)
		(layer "In11.Cu")
		(net "M_H_CPU0_SB_DQ<28>")
	)
	(segment
		(start 433.61737 -196.43598)
		(end 433.23129 -196.43598)
		(width 0.18288)
		(layer "In11.Cu")
		(net "M_H_CPU0_SB_DQ<28>")
	)
	(segment
		(start 382.337564 -226.33305)
		(end 382.322832 -226.341686)
		(width 0.088646)
		(layer "In11.Cu")
		(net "M_H_CPU0_SB_DQ<28>")
	)
	(segment
		(start 428.72406 -196.854826)
		(end 427.446694 -196.854826)
		(width 0.18288)
		(layer "In11.Cu")
		(net "M_H_CPU0_SB_DQ<28>")
	)
	(segment
		(start 437.428894 -196.219826)
		(end 436.757318 -196.891402)
		(width 0.18288)
		(layer "In11.Cu")
		(net "M_H_CPU0_SB_DQ<28>")
	)
	(segment
		(start 393.598908 -215.17864)
		(end 388.20471 -220.572838)
		(width 0.18288)
		(layer "In11.Cu")
		(net "M_H_CPU0_SB_DQ<28>")
	)
	(segment
		(start 449.164456 -198.658226)
		(end 448.971416 -198.465186)
		(width 0.18288)
		(layer "In11.Cu")
		(net "M_H_CPU0_SB_DQ<28>")
	)
	(segment
		(start 434.70449 -197.11543)
		(end 434.00345 -197.11543)
		(width 0.18288)
		(layer "In11.Cu")
		(net "M_H_CPU0_SB_DQ<28>")
	)
	(segment
		(start 387.761226 -221.016322)
		(end 387.761226 -223.088708)
		(width 0.088646)
		(layer "In11.Cu")
		(net "M_H_CPU0_SB_DQ<28>")
	)
	(segment
		(start 429.49622 -197.865238)
		(end 429.11014 -197.865238)
		(width 0.18288)
		(layer "In11.Cu")
		(net "M_H_CPU0_SB_DQ<28>")
	)
	(segment
		(start 433.03825 -196.92239)
		(end 432.84521 -197.11543)
		(width 0.18288)
		(layer "In11.Cu")
		(net "M_H_CPU0_SB_DQ<28>")
	)
	(arc
		(start 382.322832 -226.341686)
		(mid 382.135634 -226.391829)
		(end 381.948436 -226.341686)
		(width 0.088646)
		(layer "In11.Cu")
		(net "M_H_CPU0_SB_DQ<28>")
	)
	(arc
		(start 384.297936 -225.527616)
		(mid 384.015234 -225.451874)
		(end 383.732532 -225.527616)
		(width 0.088646)
		(layer "In11.Cu")
		(net "M_H_CPU0_SB_DQ<28>")
	)
	(arc
		(start 376.684032 -226.341686)
		(mid 376.496834 -226.391829)
		(end 376.309636 -226.341686)
		(width 0.088646)
		(layer "In11.Cu")
		(net "M_H_CPU0_SB_DQ<28>")
	)
	(arc
		(start 377.249436 -226.341686)
		(mid 376.975237 -226.265851)
		(end 376.698764 -226.33305)
		(width 0.088646)
		(layer "In11.Cu")
		(net "M_H_CPU0_SB_DQ<28>")
	)
	(arc
		(start 378.563632 -226.341686)
		(mid 378.376434 -226.391829)
		(end 378.189236 -226.341686)
		(width 0.088646)
		(layer "In11.Cu")
		(net "M_H_CPU0_SB_DQ<28>")
	)
	(arc
		(start 380.443232 -226.341686)
		(mid 380.256034 -226.391829)
		(end 380.068836 -226.341686)
		(width 0.088646)
		(layer "In11.Cu")
		(net "M_H_CPU0_SB_DQ<28>")
	)
	(arc
		(start 377.623832 -226.341686)
		(mid 377.436634 -226.391829)
		(end 377.249436 -226.341686)
		(width 0.088646)
		(layer "In11.Cu")
		(net "M_H_CPU0_SB_DQ<28>")
	)
	(arc
		(start 382.888236 -226.341686)
		(mid 382.614037 -226.265851)
		(end 382.337564 -226.33305)
		(width 0.088646)
		(layer "In11.Cu")
		(net "M_H_CPU0_SB_DQ<28>")
	)
	(arc
		(start 385.799584 -225.203258)
		(mid 385.751905 -225.386158)
		(end 385.621022 -225.522536)
		(width 0.088646)
		(layer "In11.Cu")
		(net "M_H_CPU0_SB_DQ<28>")
	)
	(arc
		(start 379.503432 -226.341686)
		(mid 379.316234 -226.391829)
		(end 379.129036 -226.341686)
		(width 0.088646)
		(layer "In11.Cu")
		(net "M_H_CPU0_SB_DQ<28>")
	)
	(arc
		(start 386.082032 -224.7138)
		(mid 385.877697 -224.916405)
		(end 385.799584 -225.193352)
		(width 0.088646)
		(layer "In11.Cu")
		(net "M_H_CPU0_SB_DQ<28>")
	)
	(arc
		(start 381.948436 -226.341686)
		(mid 381.665734 -226.26591)
		(end 381.383032 -226.341686)
		(width 0.088646)
		(layer "In11.Cu")
		(net "M_H_CPU0_SB_DQ<28>")
	)
	(arc
		(start 385.237736 -225.527616)
		(mid 384.955034 -225.451874)
		(end 384.672332 -225.527616)
		(width 0.088646)
		(layer "In11.Cu")
		(net "M_H_CPU0_SB_DQ<28>")
	)
	(arc
		(start 385.612132 -225.527616)
		(mid 385.424934 -225.577759)
		(end 385.237736 -225.527616)
		(width 0.088646)
		(layer "In11.Cu")
		(net "M_H_CPU0_SB_DQ<28>")
	)
	(arc
		(start 381.008636 -226.341686)
		(mid 380.734437 -226.265851)
		(end 380.457964 -226.33305)
		(width 0.088646)
		(layer "In11.Cu")
		(net "M_H_CPU0_SB_DQ<28>")
	)
	(arc
		(start 378.189236 -226.341686)
		(mid 377.915037 -226.265851)
		(end 377.638564 -226.33305)
		(width 0.088646)
		(layer "In11.Cu")
		(net "M_H_CPU0_SB_DQ<28>")
	)
	(arc
		(start 383.450084 -226.017328)
		(mid 383.402405 -226.200228)
		(end 383.271522 -226.336606)
		(width 0.088646)
		(layer "In11.Cu")
		(net "M_H_CPU0_SB_DQ<28>")
	)
	(arc
		(start 386.83438 -223.824292)
		(mid 386.435087 -223.99)
		(end 386.269738 -224.389442)
		(width 0.088646)
		(layer "In11.Cu")
		(net "M_H_CPU0_SB_DQ<28>")
	)
	(arc
		(start 375.369836 -226.341686)
		(mid 375.087134 -226.26591)
		(end 374.804432 -226.341686)
		(width 0.088646)
		(layer "In11.Cu")
		(net "M_H_CPU0_SB_DQ<28>")
	)
	(arc
		(start 381.383032 -226.341686)
		(mid 381.195834 -226.391829)
		(end 381.008636 -226.341686)
		(width 0.088646)
		(layer "In11.Cu")
		(net "M_H_CPU0_SB_DQ<28>")
	)
	(arc
		(start 374.430036 -226.341686)
		(mid 374.155837 -226.265851)
		(end 373.879364 -226.33305)
		(width 0.088646)
		(layer "In11.Cu")
		(net "M_H_CPU0_SB_DQ<28>")
	)
	(arc
		(start 386.269484 -224.389442)
		(mid 386.221805 -224.572342)
		(end 386.090922 -224.70872)
		(width 0.088646)
		(layer "In11.Cu")
		(net "M_H_CPU0_SB_DQ<28>")
	)
	(arc
		(start 383.732532 -225.527616)
		(mid 383.530246 -225.726597)
		(end 383.450084 -225.998786)
		(width 0.088646)
		(layer "In11.Cu")
		(net "M_H_CPU0_SB_DQ<28>")
	)
	(arc
		(start 384.672332 -225.527616)
		(mid 384.485134 -225.577759)
		(end 384.297936 -225.527616)
		(width 0.088646)
		(layer "In11.Cu")
		(net "M_H_CPU0_SB_DQ<28>")
	)
	(arc
		(start 379.129036 -226.341686)
		(mid 378.846334 -226.26591)
		(end 378.563632 -226.341686)
		(width 0.088646)
		(layer "In11.Cu")
		(net "M_H_CPU0_SB_DQ<28>")
	)
	(arc
		(start 376.309636 -226.341686)
		(mid 376.026934 -226.26591)
		(end 375.744232 -226.341686)
		(width 0.088646)
		(layer "In11.Cu")
		(net "M_H_CPU0_SB_DQ<28>")
	)
	(arc
		(start 374.804432 -226.341686)
		(mid 374.617234 -226.391829)
		(end 374.430036 -226.341686)
		(width 0.088646)
		(layer "In11.Cu")
		(net "M_H_CPU0_SB_DQ<28>")
	)
	(arc
		(start 375.744232 -226.341686)
		(mid 375.557034 -226.391829)
		(end 375.369836 -226.341686)
		(width 0.088646)
		(layer "In11.Cu")
		(net "M_H_CPU0_SB_DQ<28>")
	)
	(arc
		(start 383.262632 -226.341686)
		(mid 383.075434 -226.391829)
		(end 382.888236 -226.341686)
		(width 0.088646)
		(layer "In11.Cu")
		(net "M_H_CPU0_SB_DQ<28>")
	)
	(arc
		(start 373.858536 -226.345242)
		(mid 373.673081 -226.523437)
		(end 373.58574 -226.765358)
		(width 0.088646)
		(layer "In11.Cu")
		(net "M_H_CPU0_SB_DQ<28>")
	)
	(arc
		(start 380.068836 -226.341686)
		(mid 379.794637 -226.265851)
		(end 379.518164 -226.33305)
		(width 0.088646)
		(layer "In11.Cu")
		(net "M_H_CPU0_SB_DQ<28>")
	)
	(segment
		(start 461.455516 -201.799952)
		(end 461.455516 -201.549)
		(width 0.20066)
		(layer "F.Cu")
		(net "M_H_CPU0_SB_DQ<27>")
	)
	(segment
		(start 461.455516 -201.549)
		(end 461.689704 -201.314812)
		(width 0.20066)
		(layer "F.Cu")
		(net "M_H_CPU0_SB_DQ<27>")
	)
	(segment
		(start 455.011282 -201.56678)
		(end 456.116182 -201.56678)
		(width 0.20066)
		(layer "F.Cu")
		(net "M_H_CPU0_SB_DQ<27>")
	)
	(segment
		(start 460.570326 -202.003914)
		(end 461.251554 -202.003914)
		(width 0.20066)
		(layer "F.Cu")
		(net "M_H_CPU0_SB_DQ<27>")
	)
	(segment
		(start 458.538326 -201.998834)
		(end 458.543152 -201.998834)
		(width 0.101854)
		(layer "F.Cu")
		(net "M_H_CPU0_SB_DQ<27>")
	)
	(segment
		(start 458.24648 -201.998834)
		(end 458.538326 -201.998834)
		(width 0.20066)
		(layer "F.Cu")
		(net "M_H_CPU0_SB_DQ<27>")
	)
	(segment
		(start 462.073752 -201.314812)
		(end 462.32572 -201.56678)
		(width 0.20066)
		(layer "F.Cu")
		(net "M_H_CPU0_SB_DQ<27>")
	)
	(segment
		(start 457.814426 -201.56678)
		(end 458.24648 -201.998834)
		(width 0.20066)
		(layer "F.Cu")
		(net "M_H_CPU0_SB_DQ<27>")
	)
	(segment
		(start 373.20728 -228.994716)
		(end 373.20728 -228.45903)
		(width 0.20066)
		(layer "F.Cu")
		(net "M_H_CPU0_SB_DQ<27>")
	)
	(segment
		(start 460.558134 -201.991722)
		(end 460.570326 -202.003914)
		(width 0.1016)
		(layer "F.Cu")
		(net "M_H_CPU0_SB_DQ<27>")
	)
	(segment
		(start 456.116182 -201.56678)
		(end 457.814426 -201.56678)
		(width 0.20066)
		(layer "F.Cu")
		(net "M_H_CPU0_SB_DQ<27>")
	)
	(segment
		(start 373.207534 -228.99497)
		(end 373.20728 -228.994716)
		(width 0.20066)
		(layer "F.Cu")
		(net "M_H_CPU0_SB_DQ<27>")
	)
	(segment
		(start 461.251554 -202.003914)
		(end 461.455516 -201.799952)
		(width 0.20066)
		(layer "F.Cu")
		(net "M_H_CPU0_SB_DQ<27>")
	)
	(segment
		(start 461.689704 -201.314812)
		(end 462.073752 -201.314812)
		(width 0.20066)
		(layer "F.Cu")
		(net "M_H_CPU0_SB_DQ<27>")
	)
	(segment
		(start 458.543152 -201.998834)
		(end 458.550264 -201.991722)
		(width 0.1016)
		(layer "F.Cu")
		(net "M_H_CPU0_SB_DQ<27>")
	)
	(segment
		(start 462.32572 -201.56678)
		(end 463.659982 -201.56678)
		(width 0.20066)
		(layer "F.Cu")
		(net "M_H_CPU0_SB_DQ<27>")
	)
	(segment
		(start 458.550264 -201.991722)
		(end 460.558134 -201.991722)
		(width 0.1016)
		(layer "F.Cu")
		(net "M_H_CPU0_SB_DQ<27>")
	)
	(segment
		(start 421.682418 -203.629514)
		(end 421.489378 -203.822554)
		(width 0.18288)
		(layer "In11.Cu")
		(net "M_H_CPU0_SB_DQ<27>")
	)
	(segment
		(start 450.587364 -203.691744)
		(end 450.38137 -203.48575)
		(width 0.18288)
		(layer "In11.Cu")
		(net "M_H_CPU0_SB_DQ<27>")
	)
	(segment
		(start 448.231006 -203.940156)
		(end 448.231006 -203.67879)
		(width 0.18288)
		(layer "In11.Cu")
		(net "M_H_CPU0_SB_DQ<27>")
	)
	(segment
		(start 438.33034 -203.87818)
		(end 437.101996 -203.87818)
		(width 0.18288)
		(layer "In11.Cu")
		(net "M_H_CPU0_SB_DQ<27>")
	)
	(segment
		(start 422.156636 -202.93457)
		(end 421.875458 -202.93457)
		(width 0.18288)
		(layer "In11.Cu")
		(net "M_H_CPU0_SB_DQ<27>")
	)
	(segment
		(start 425.43603 -203.69149)
		(end 424.880786 -203.69149)
		(width 0.18288)
		(layer "In11.Cu")
		(net "M_H_CPU0_SB_DQ<27>")
	)
	(segment
		(start 412.562294 -203.789026)
		(end 412.409894 -203.636626)
		(width 0.18288)
		(layer "In11.Cu")
		(net "M_H_CPU0_SB_DQ<27>")
	)
	(segment
		(start 433.050188 -203.55306)
		(end 430.971452 -203.55306)
		(width 0.18288)
		(layer "In11.Cu")
		(net "M_H_CPU0_SB_DQ<27>")
	)
	(segment
		(start 451.037706 -203.69149)
		(end 450.761608 -203.690728)
		(width 0.18288)
		(layer "In11.Cu")
		(net "M_H_CPU0_SB_DQ<27>")
	)
	(segment
		(start 382.337564 -228.957124)
		(end 382.322832 -228.948488)
		(width 0.088646)
		(layer "In11.Cu")
		(net "M_H_CPU0_SB_DQ<27>")
	)
	(segment
		(start 388.375906 -226.15271)
		(end 388.012686 -226.51593)
		(width 0.088646)
		(layer "In11.Cu")
		(net "M_H_CPU0_SB_DQ<27>")
	)
	(segment
		(start 450.761608 -203.690728)
		(end 450.746114 -203.690728)
		(width 0.18288)
		(layer "In11.Cu")
		(net "M_H_CPU0_SB_DQ<27>")
	)
	(segment
		(start 444.460122 -202.814682)
		(end 444.267082 -203.007722)
		(width 0.18288)
		(layer "In11.Cu")
		(net "M_H_CPU0_SB_DQ<27>")
	)
	(segment
		(start 455.011282 -201.56678)
		(end 454.064624 -201.56678)
		(width 0.18288)
		(layer "In11.Cu")
		(net "M_H_CPU0_SB_DQ<27>")
	)
	(segment
		(start 433.944268 -203.7461)
		(end 433.944268 -204.002386)
		(width 0.18288)
		(layer "In11.Cu")
		(net "M_H_CPU0_SB_DQ<27>")
	)
	(segment
		(start 425.490894 -203.636626)
		(end 425.43603 -203.69149)
		(width 0.18288)
		(layer "In11.Cu")
		(net "M_H_CPU0_SB_DQ<27>")
	)
	(segment
		(start 422.579038 -203.858368)
		(end 422.385998 -203.665328)
		(width 0.18288)
		(layer "In11.Cu")
		(net "M_H_CPU0_SB_DQ<27>")
	)
	(segment
		(start 433.243228 -203.7461)
		(end 433.050188 -203.55306)
		(width 0.18288)
		(layer "In11.Cu")
		(net "M_H_CPU0_SB_DQ<27>")
	)
	(segment
		(start 430.971452 -203.55306)
		(end 430.710086 -203.814426)
		(width 0.18288)
		(layer "In11.Cu")
		(net "M_H_CPU0_SB_DQ<27>")
	)
	(segment
		(start 450.746114 -203.690728)
		(end 450.745098 -203.691744)
		(width 0.18288)
		(layer "In11.Cu")
		(net "M_H_CPU0_SB_DQ<27>")
	)
	(segment
		(start 445.163702 -203.865226)
		(end 444.970662 -203.672186)
		(width 0.18288)
		(layer "In11.Cu")
		(net "M_H_CPU0_SB_DQ<27>")
	)
	(segment
		(start 406.068022 -204.397356)
		(end 406.068022 -204.872336)
		(width 0.18288)
		(layer "In11.Cu")
		(net "M_H_CPU0_SB_DQ<27>")
	)
	(segment
		(start 378.578364 -228.957124)
		(end 378.563632 -228.948488)
		(width 0.088646)
		(layer "In11.Cu")
		(net "M_H_CPU0_SB_DQ<27>")
	)
	(segment
		(start 420.08425 -203.690982)
		(end 419.902132 -203.508864)
		(width 0.18288)
		(layer "In11.Cu")
		(net "M_H_CPU0_SB_DQ<27>")
	)
	(segment
		(start 390.487916 -224.0407)
		(end 388.375906 -226.15271)
		(width 0.18288)
		(layer "In11.Cu")
		(net "M_H_CPU0_SB_DQ<27>")
	)
	(segment
		(start 413.745172 -203.789026)
		(end 412.562294 -203.789026)
		(width 0.18288)
		(layer "In11.Cu")
		(net "M_H_CPU0_SB_DQ<27>")
	)
	(segment
		(start 374.819164 -228.957124)
		(end 374.804432 -228.948488)
		(width 0.088646)
		(layer "In11.Cu")
		(net "M_H_CPU0_SB_DQ<27>")
	)
	(segment
		(start 387.335522 -226.877118)
		(end 387.335522 -227.493068)
		(width 0.088646)
		(layer "In11.Cu")
		(net "M_H_CPU0_SB_DQ<27>")
	)
	(segment
		(start 388.012686 -226.51593)
		(end 387.69671 -226.51593)
		(width 0.088646)
		(layer "In11.Cu")
		(net "M_H_CPU0_SB_DQ<27>")
	)
	(segment
		(start 454.064624 -201.56678)
		(end 453.521572 -202.109832)
		(width 0.18288)
		(layer "In11.Cu")
		(net "M_H_CPU0_SB_DQ<27>")
	)
	(segment
		(start 397.210534 -216.297256)
		(end 390.487916 -223.019874)
		(width 0.18288)
		(layer "In11.Cu")
		(net "M_H_CPU0_SB_DQ<27>")
	)
	(segment
		(start 421.489378 -203.822554)
		(end 421.216074 -203.822554)
		(width 0.18288)
		(layer "In11.Cu")
		(net "M_H_CPU0_SB_DQ<27>")
	)
	(segment
		(start 448.424046 -204.133196)
		(end 448.231006 -203.940156)
		(width 0.18288)
		(layer "In11.Cu")
		(net "M_H_CPU0_SB_DQ<27>")
	)
	(segment
		(start 444.777622 -202.814682)
		(end 444.460122 -202.814682)
		(width 0.18288)
		(layer "In11.Cu")
		(net "M_H_CPU0_SB_DQ<27>")
	)
	(segment
		(start 390.487916 -223.019874)
		(end 390.487916 -224.0407)
		(width 0.18288)
		(layer "In11.Cu")
		(net "M_H_CPU0_SB_DQ<27>")
	)
	(segment
		(start 416.728656 -203.508864)
		(end 416.448494 -203.789026)
		(width 0.18288)
		(layer "In11.Cu")
		(net "M_H_CPU0_SB_DQ<27>")
	)
	(segment
		(start 435.110128 -203.55306)
		(end 434.137308 -203.55306)
		(width 0.18288)
		(layer "In11.Cu")
		(net "M_H_CPU0_SB_DQ<27>")
	)
	(segment
		(start 433.243228 -204.002386)
		(end 433.243228 -203.7461)
		(width 0.18288)
		(layer "In11.Cu")
		(net "M_H_CPU0_SB_DQ<27>")
	)
	(segment
		(start 421.216074 -203.822554)
		(end 421.084502 -203.690982)
		(width 0.18288)
		(layer "In11.Cu")
		(net "M_H_CPU0_SB_DQ<27>")
	)
	(segment
		(start 444.074042 -203.865226)
		(end 442.864494 -203.865226)
		(width 0.18288)
		(layer "In11.Cu")
		(net "M_H_CPU0_SB_DQ<27>")
	)
	(segment
		(start 448.231006 -203.67879)
		(end 448.037966 -203.48575)
		(width 0.18288)
		(layer "In11.Cu")
		(net "M_H_CPU0_SB_DQ<27>")
	)
	(segment
		(start 450.38137 -203.48575)
		(end 449.127626 -203.48575)
		(width 0.18288)
		(layer "In11.Cu")
		(net "M_H_CPU0_SB_DQ<27>")
	)
	(segment
		(start 422.385998 -203.665328)
		(end 422.385998 -203.163932)
		(width 0.18288)
		(layer "In11.Cu")
		(net "M_H_CPU0_SB_DQ<27>")
	)
	(segment
		(start 377.633992 -228.954584)
		(end 377.623578 -228.948488)
		(width 0.088646)
		(layer "In11.Cu")
		(net "M_H_CPU0_SB_DQ<27>")
	)
	(segment
		(start 448.934586 -203.940156)
		(end 448.741546 -204.133196)
		(width 0.18288)
		(layer "In11.Cu")
		(net "M_H_CPU0_SB_DQ<27>")
	)
	(segment
		(start 444.267082 -203.007722)
		(end 444.267082 -203.672186)
		(width 0.18288)
		(layer "In11.Cu")
		(net "M_H_CPU0_SB_DQ<27>")
	)
	(segment
		(start 414.413192 -203.54925)
		(end 413.984948 -203.54925)
		(width 0.18288)
		(layer "In11.Cu")
		(net "M_H_CPU0_SB_DQ<27>")
	)
	(segment
		(start 424.784266 -203.691236)
		(end 424.783758 -203.690728)
		(width 0.18288)
		(layer "In11.Cu")
		(net "M_H_CPU0_SB_DQ<27>")
	)
	(segment
		(start 446.36817 -203.48575)
		(end 445.988694 -203.865226)
		(width 0.18288)
		(layer "In11.Cu")
		(net "M_H_CPU0_SB_DQ<27>")
	)
	(segment
		(start 430.710086 -203.814426)
		(end 427.446694 -203.814426)
		(width 0.18288)
		(layer "In11.Cu")
		(net "M_H_CPU0_SB_DQ<27>")
	)
	(segment
		(start 435.24805 -203.690982)
		(end 435.110128 -203.55306)
		(width 0.18288)
		(layer "In11.Cu")
		(net "M_H_CPU0_SB_DQ<27>")
	)
	(segment
		(start 448.741546 -204.133196)
		(end 448.424046 -204.133196)
		(width 0.18288)
		(layer "In11.Cu")
		(net "M_H_CPU0_SB_DQ<27>")
	)
	(segment
		(start 406.068022 -204.872336)
		(end 397.210534 -213.729824)
		(width 0.18288)
		(layer "In11.Cu")
		(net "M_H_CPU0_SB_DQ<27>")
	)
	(segment
		(start 438.517538 -203.690982)
		(end 438.33034 -203.87818)
		(width 0.18288)
		(layer "In11.Cu")
		(net "M_H_CPU0_SB_DQ<27>")
	)
	(segment
		(start 444.970662 -203.007722)
		(end 444.777622 -202.814682)
		(width 0.18288)
		(layer "In11.Cu")
		(net "M_H_CPU0_SB_DQ<27>")
	)
	(segment
		(start 433.751228 -204.195426)
		(end 433.436268 -204.195426)
		(width 0.18288)
		(layer "In11.Cu")
		(net "M_H_CPU0_SB_DQ<27>")
	)
	(segment
		(start 406.574752 -203.890626)
		(end 406.068022 -204.397356)
		(width 0.18288)
		(layer "In11.Cu")
		(net "M_H_CPU0_SB_DQ<27>")
	)
	(segment
		(start 433.436268 -204.195426)
		(end 433.243228 -204.002386)
		(width 0.18288)
		(layer "In11.Cu")
		(net "M_H_CPU0_SB_DQ<27>")
	)
	(segment
		(start 448.037966 -203.48575)
		(end 446.36817 -203.48575)
		(width 0.18288)
		(layer "In11.Cu")
		(net "M_H_CPU0_SB_DQ<27>")
	)
	(segment
		(start 442.585094 -203.585826)
		(end 440.502294 -203.585826)
		(width 0.18288)
		(layer "In11.Cu")
		(net "M_H_CPU0_SB_DQ<27>")
	)
	(segment
		(start 444.267082 -203.672186)
		(end 444.074042 -203.865226)
		(width 0.18288)
		(layer "In11.Cu")
		(net "M_H_CPU0_SB_DQ<27>")
	)
	(segment
		(start 453.521572 -202.109832)
		(end 452.929244 -202.110086)
		(width 0.18288)
		(layer "In11.Cu")
		(net "M_H_CPU0_SB_DQ<27>")
	)
	(segment
		(start 422.385998 -203.163932)
		(end 422.156636 -202.93457)
		(width 0.18288)
		(layer "In11.Cu")
		(net "M_H_CPU0_SB_DQ<27>")
	)
	(segment
		(start 433.944268 -204.002386)
		(end 433.751228 -204.195426)
		(width 0.18288)
		(layer "In11.Cu")
		(net "M_H_CPU0_SB_DQ<27>")
	)
	(segment
		(start 379.518164 -228.957124)
		(end 379.503432 -228.948488)
		(width 0.088646)
		(layer "In11.Cu")
		(net "M_H_CPU0_SB_DQ<27>")
	)
	(segment
		(start 386.744718 -228.083872)
		(end 386.364734 -228.083872)
		(width 0.088646)
		(layer "In11.Cu")
		(net "M_H_CPU0_SB_DQ<27>")
	)
	(segment
		(start 387.335522 -227.493068)
		(end 386.744718 -228.083872)
		(width 0.088646)
		(layer "In11.Cu")
		(net "M_H_CPU0_SB_DQ<27>")
	)
	(segment
		(start 413.984948 -203.54925)
		(end 413.745172 -203.789026)
		(width 0.18288)
		(layer "In11.Cu")
		(net "M_H_CPU0_SB_DQ<27>")
	)
	(segment
		(start 408.599894 -203.636626)
		(end 408.345894 -203.890626)
		(width 0.18288)
		(layer "In11.Cu")
		(net "M_H_CPU0_SB_DQ<27>")
	)
	(segment
		(start 423.912792 -203.690728)
		(end 423.745152 -203.858368)
		(width 0.18288)
		(layer "In11.Cu")
		(net "M_H_CPU0_SB_DQ<27>")
	)
	(segment
		(start 427.446694 -203.814426)
		(end 427.268894 -203.636626)
		(width 0.18288)
		(layer "In11.Cu")
		(net "M_H_CPU0_SB_DQ<27>")
	)
	(segment
		(start 444.970662 -203.672186)
		(end 444.970662 -203.007722)
		(width 0.18288)
		(layer "In11.Cu")
		(net "M_H_CPU0_SB_DQ<27>")
	)
	(segment
		(start 385.050284 -228.45903)
		(end 385.050284 -228.468936)
		(width 0.088646)
		(layer "In11.Cu")
		(net "M_H_CPU0_SB_DQ<27>")
	)
	(segment
		(start 387.69671 -226.51593)
		(end 387.335522 -226.877118)
		(width 0.088646)
		(layer "In11.Cu")
		(net "M_H_CPU0_SB_DQ<27>")
	)
	(segment
		(start 452.929244 -202.110086)
		(end 451.347586 -203.691744)
		(width 0.18288)
		(layer "In11.Cu")
		(net "M_H_CPU0_SB_DQ<27>")
	)
	(segment
		(start 451.347586 -203.691744)
		(end 451.086474 -203.691744)
		(width 0.18288)
		(layer "In11.Cu")
		(net "M_H_CPU0_SB_DQ<27>")
	)
	(segment
		(start 445.988694 -203.865226)
		(end 445.163702 -203.865226)
		(width 0.18288)
		(layer "In11.Cu")
		(net "M_H_CPU0_SB_DQ<27>")
	)
	(segment
		(start 397.210534 -213.729824)
		(end 397.210534 -216.297256)
		(width 0.18288)
		(layer "In11.Cu")
		(net "M_H_CPU0_SB_DQ<27>")
	)
	(segment
		(start 424.880786 -203.69149)
		(end 424.784266 -203.691236)
		(width 0.18288)
		(layer "In11.Cu")
		(net "M_H_CPU0_SB_DQ<27>")
	)
	(segment
		(start 436.914798 -203.690982)
		(end 435.24805 -203.690982)
		(width 0.18288)
		(layer "In11.Cu")
		(net "M_H_CPU0_SB_DQ<27>")
	)
	(segment
		(start 385.237736 -228.134672)
		(end 385.228846 -228.139752)
		(width 0.088646)
		(layer "In11.Cu")
		(net "M_H_CPU0_SB_DQ<27>")
	)
	(segment
		(start 440.397138 -203.690982)
		(end 438.517538 -203.690982)
		(width 0.18288)
		(layer "In11.Cu")
		(net "M_H_CPU0_SB_DQ<27>")
	)
	(segment
		(start 451.086474 -203.691744)
		(end 451.037706 -203.69149)
		(width 0.18288)
		(layer "In11.Cu")
		(net "M_H_CPU0_SB_DQ<27>")
	)
	(segment
		(start 424.783758 -203.690728)
		(end 423.912792 -203.690728)
		(width 0.18288)
		(layer "In11.Cu")
		(net "M_H_CPU0_SB_DQ<27>")
	)
	(segment
		(start 376.694446 -228.954584)
		(end 376.684032 -228.948488)
		(width 0.088646)
		(layer "In11.Cu")
		(net "M_H_CPU0_SB_DQ<27>")
	)
	(segment
		(start 423.745152 -203.858368)
		(end 422.579038 -203.858368)
		(width 0.18288)
		(layer "In11.Cu")
		(net "M_H_CPU0_SB_DQ<27>")
	)
	(segment
		(start 412.409894 -203.636626)
		(end 408.599894 -203.636626)
		(width 0.18288)
		(layer "In11.Cu")
		(net "M_H_CPU0_SB_DQ<27>")
	)
	(segment
		(start 448.934586 -203.67879)
		(end 448.934586 -203.940156)
		(width 0.18288)
		(layer "In11.Cu")
		(net "M_H_CPU0_SB_DQ<27>")
	)
	(segment
		(start 437.101996 -203.87818)
		(end 436.914798 -203.690982)
		(width 0.18288)
		(layer "In11.Cu")
		(net "M_H_CPU0_SB_DQ<27>")
	)
	(segment
		(start 440.502294 -203.585826)
		(end 440.397138 -203.690982)
		(width 0.18288)
		(layer "In11.Cu")
		(net "M_H_CPU0_SB_DQ<27>")
	)
	(segment
		(start 450.745098 -203.691744)
		(end 450.587364 -203.691744)
		(width 0.18288)
		(layer "In11.Cu")
		(net "M_H_CPU0_SB_DQ<27>")
	)
	(segment
		(start 375.758964 -228.957124)
		(end 375.744232 -228.948488)
		(width 0.088646)
		(layer "In11.Cu")
		(net "M_H_CPU0_SB_DQ<27>")
	)
	(segment
		(start 442.864494 -203.865226)
		(end 442.585094 -203.585826)
		(width 0.18288)
		(layer "In11.Cu")
		(net "M_H_CPU0_SB_DQ<27>")
	)
	(segment
		(start 421.084502 -203.690982)
		(end 420.08425 -203.690982)
		(width 0.18288)
		(layer "In11.Cu")
		(net "M_H_CPU0_SB_DQ<27>")
	)
	(segment
		(start 416.448494 -203.789026)
		(end 414.652968 -203.789026)
		(width 0.18288)
		(layer "In11.Cu")
		(net "M_H_CPU0_SB_DQ<27>")
	)
	(segment
		(start 421.875458 -202.93457)
		(end 421.682418 -203.12761)
		(width 0.18288)
		(layer "In11.Cu")
		(net "M_H_CPU0_SB_DQ<27>")
	)
	(segment
		(start 449.127626 -203.48575)
		(end 448.934586 -203.67879)
		(width 0.18288)
		(layer "In11.Cu")
		(net "M_H_CPU0_SB_DQ<27>")
	)
	(segment
		(start 408.345894 -203.890626)
		(end 406.574752 -203.890626)
		(width 0.18288)
		(layer "In11.Cu")
		(net "M_H_CPU0_SB_DQ<27>")
	)
	(segment
		(start 421.682418 -203.12761)
		(end 421.682418 -203.629514)
		(width 0.18288)
		(layer "In11.Cu")
		(net "M_H_CPU0_SB_DQ<27>")
	)
	(segment
		(start 373.864632 -228.948488)
		(end 373.85244 -228.941376)
		(width 0.088646)
		(layer "In11.Cu")
		(net "M_H_CPU0_SB_DQ<27>")
	)
	(segment
		(start 419.902132 -203.508864)
		(end 416.728656 -203.508864)
		(width 0.18288)
		(layer "In11.Cu")
		(net "M_H_CPU0_SB_DQ<27>")
	)
	(segment
		(start 414.652968 -203.789026)
		(end 414.413192 -203.54925)
		(width 0.18288)
		(layer "In11.Cu")
		(net "M_H_CPU0_SB_DQ<27>")
	)
	(segment
		(start 427.268894 -203.636626)
		(end 425.490894 -203.636626)
		(width 0.18288)
		(layer "In11.Cu")
		(net "M_H_CPU0_SB_DQ<27>")
	)
	(segment
		(start 434.137308 -203.55306)
		(end 433.944268 -203.7461)
		(width 0.18288)
		(layer "In11.Cu")
		(net "M_H_CPU0_SB_DQ<27>")
	)
	(arc
		(start 378.563632 -228.948488)
		(mid 378.376434 -228.898345)
		(end 378.189236 -228.948488)
		(width 0.088646)
		(layer "In11.Cu")
		(net "M_H_CPU0_SB_DQ<27>")
	)
	(arc
		(start 384.202432 -228.948488)
		(mid 384.015234 -228.898345)
		(end 383.828036 -228.948488)
		(width 0.088646)
		(layer "In11.Cu")
		(net "M_H_CPU0_SB_DQ<27>")
	)
	(arc
		(start 381.008636 -228.948488)
		(mid 380.725934 -229.024264)
		(end 380.443232 -228.948488)
		(width 0.088646)
		(layer "In11.Cu")
		(net "M_H_CPU0_SB_DQ<27>")
	)
	(arc
		(start 374.430036 -228.948488)
		(mid 374.147334 -229.024264)
		(end 373.864632 -228.948488)
		(width 0.088646)
		(layer "In11.Cu")
		(net "M_H_CPU0_SB_DQ<27>")
	)
	(arc
		(start 384.767836 -228.948488)
		(mid 384.485134 -229.024264)
		(end 384.202432 -228.948488)
		(width 0.088646)
		(layer "In11.Cu")
		(net "M_H_CPU0_SB_DQ<27>")
	)
	(arc
		(start 385.050284 -228.468936)
		(mid 384.972173 -228.745885)
		(end 384.767836 -228.948488)
		(width 0.088646)
		(layer "In11.Cu")
		(net "M_H_CPU0_SB_DQ<27>")
	)
	(arc
		(start 385.612132 -228.134672)
		(mid 385.424934 -228.084529)
		(end 385.237736 -228.134672)
		(width 0.088646)
		(layer "In11.Cu")
		(net "M_H_CPU0_SB_DQ<27>")
	)
	(arc
		(start 381.383032 -228.948488)
		(mid 381.195834 -228.898345)
		(end 381.008636 -228.948488)
		(width 0.088646)
		(layer "In11.Cu")
		(net "M_H_CPU0_SB_DQ<27>")
	)
	(arc
		(start 375.369836 -228.948488)
		(mid 375.095637 -229.024323)
		(end 374.819164 -228.957124)
		(width 0.088646)
		(layer "In11.Cu")
		(net "M_H_CPU0_SB_DQ<27>")
	)
	(arc
		(start 379.503432 -228.948488)
		(mid 379.316234 -228.898345)
		(end 379.129036 -228.948488)
		(width 0.088646)
		(layer "In11.Cu")
		(net "M_H_CPU0_SB_DQ<27>")
	)
	(arc
		(start 383.828036 -228.948488)
		(mid 383.545334 -229.024264)
		(end 383.262632 -228.948488)
		(width 0.088646)
		(layer "In11.Cu")
		(net "M_H_CPU0_SB_DQ<27>")
	)
	(arc
		(start 382.322832 -228.948488)
		(mid 382.135634 -228.898345)
		(end 381.948436 -228.948488)
		(width 0.088646)
		(layer "In11.Cu")
		(net "M_H_CPU0_SB_DQ<27>")
	)
	(arc
		(start 375.744232 -228.948488)
		(mid 375.557034 -228.898345)
		(end 375.369836 -228.948488)
		(width 0.088646)
		(layer "In11.Cu")
		(net "M_H_CPU0_SB_DQ<27>")
	)
	(arc
		(start 377.623578 -228.948488)
		(mid 377.43638 -228.898345)
		(end 377.249182 -228.948488)
		(width 0.088646)
		(layer "In11.Cu")
		(net "M_H_CPU0_SB_DQ<27>")
	)
	(arc
		(start 380.443232 -228.948488)
		(mid 380.256034 -228.898345)
		(end 380.068836 -228.948488)
		(width 0.088646)
		(layer "In11.Cu")
		(net "M_H_CPU0_SB_DQ<27>")
	)
	(arc
		(start 380.068836 -228.948488)
		(mid 379.794637 -229.024323)
		(end 379.518164 -228.957124)
		(width 0.088646)
		(layer "In11.Cu")
		(net "M_H_CPU0_SB_DQ<27>")
	)
	(arc
		(start 379.129036 -228.948488)
		(mid 378.854837 -229.024323)
		(end 378.578364 -228.957124)
		(width 0.088646)
		(layer "In11.Cu")
		(net "M_H_CPU0_SB_DQ<27>")
	)
	(arc
		(start 376.684032 -228.948488)
		(mid 376.496834 -228.898345)
		(end 376.309636 -228.948488)
		(width 0.088646)
		(layer "In11.Cu")
		(net "M_H_CPU0_SB_DQ<27>")
	)
	(arc
		(start 376.309636 -228.948488)
		(mid 376.035437 -229.024323)
		(end 375.758964 -228.957124)
		(width 0.088646)
		(layer "In11.Cu")
		(net "M_H_CPU0_SB_DQ<27>")
	)
	(arc
		(start 386.177536 -228.134672)
		(mid 385.894834 -228.210414)
		(end 385.612132 -228.134672)
		(width 0.088646)
		(layer "In11.Cu")
		(net "M_H_CPU0_SB_DQ<27>")
	)
	(arc
		(start 381.948436 -228.948488)
		(mid 381.665734 -229.024264)
		(end 381.383032 -228.948488)
		(width 0.088646)
		(layer "In11.Cu")
		(net "M_H_CPU0_SB_DQ<27>")
	)
	(arc
		(start 377.249182 -228.948488)
		(mid 376.972623 -229.024231)
		(end 376.694446 -228.954584)
		(width 0.088646)
		(layer "In11.Cu")
		(net "M_H_CPU0_SB_DQ<27>")
	)
	(arc
		(start 373.85244 -228.941376)
		(mid 373.516106 -228.718599)
		(end 373.20728 -228.45903)
		(width 0.088646)
		(layer "In11.Cu")
		(net "M_H_CPU0_SB_DQ<27>")
	)
	(arc
		(start 386.364734 -228.083872)
		(mid 386.267795 -228.096962)
		(end 386.177536 -228.134672)
		(width 0.088646)
		(layer "In11.Cu")
		(net "M_H_CPU0_SB_DQ<27>")
	)
	(arc
		(start 383.262632 -228.948488)
		(mid 383.075434 -228.898345)
		(end 382.888236 -228.948488)
		(width 0.088646)
		(layer "In11.Cu")
		(net "M_H_CPU0_SB_DQ<27>")
	)
	(arc
		(start 378.189236 -228.948488)
		(mid 377.912423 -229.024358)
		(end 377.633992 -228.954584)
		(width 0.088646)
		(layer "In11.Cu")
		(net "M_H_CPU0_SB_DQ<27>")
	)
	(arc
		(start 374.804432 -228.948488)
		(mid 374.617234 -228.898345)
		(end 374.430036 -228.948488)
		(width 0.088646)
		(layer "In11.Cu")
		(net "M_H_CPU0_SB_DQ<27>")
	)
	(arc
		(start 382.888236 -228.948488)
		(mid 382.614037 -229.024323)
		(end 382.337564 -228.957124)
		(width 0.088646)
		(layer "In11.Cu")
		(net "M_H_CPU0_SB_DQ<27>")
	)
	(arc
		(start 385.228846 -228.139752)
		(mid 385.097932 -228.276112)
		(end 385.050284 -228.45903)
		(width 0.088646)
		(layer "In11.Cu")
		(net "M_H_CPU0_SB_DQ<27>")
	)
	(segment
		(start 458.24648 -203.698856)
		(end 458.538326 -203.698856)
		(width 0.20066)
		(layer "F.Cu")
		(net "M_H_CPU0_SB_DQ<26>")
	)
	(segment
		(start 372.73738 -229.808786)
		(end 372.737634 -229.808532)
		(width 0.20066)
		(layer "F.Cu")
		(net "M_H_CPU0_SB_DQ<26>")
	)
	(segment
		(start 458.550264 -203.691744)
		(end 460.558134 -203.691744)
		(width 0.1016)
		(layer "F.Cu")
		(net "M_H_CPU0_SB_DQ<26>")
	)
	(segment
		(start 461.689704 -203.014834)
		(end 462.073752 -203.014834)
		(width 0.20066)
		(layer "F.Cu")
		(net "M_H_CPU0_SB_DQ<26>")
	)
	(segment
		(start 461.455516 -203.249022)
		(end 461.689704 -203.014834)
		(width 0.20066)
		(layer "F.Cu")
		(net "M_H_CPU0_SB_DQ<26>")
	)
	(segment
		(start 462.32572 -203.266802)
		(end 463.659982 -203.266802)
		(width 0.20066)
		(layer "F.Cu")
		(net "M_H_CPU0_SB_DQ<26>")
	)
	(segment
		(start 372.737634 -229.808532)
		(end 372.737634 -229.272846)
		(width 0.20066)
		(layer "F.Cu")
		(net "M_H_CPU0_SB_DQ<26>")
	)
	(segment
		(start 460.570326 -203.703936)
		(end 461.251554 -203.703936)
		(width 0.20066)
		(layer "F.Cu")
		(net "M_H_CPU0_SB_DQ<26>")
	)
	(segment
		(start 462.073752 -203.014834)
		(end 462.32572 -203.266802)
		(width 0.20066)
		(layer "F.Cu")
		(net "M_H_CPU0_SB_DQ<26>")
	)
	(segment
		(start 461.251554 -203.703936)
		(end 461.455516 -203.499974)
		(width 0.20066)
		(layer "F.Cu")
		(net "M_H_CPU0_SB_DQ<26>")
	)
	(segment
		(start 460.558134 -203.691744)
		(end 460.570326 -203.703936)
		(width 0.1016)
		(layer "F.Cu")
		(net "M_H_CPU0_SB_DQ<26>")
	)
	(segment
		(start 458.543152 -203.698856)
		(end 458.550264 -203.691744)
		(width 0.1016)
		(layer "F.Cu")
		(net "M_H_CPU0_SB_DQ<26>")
	)
	(segment
		(start 455.011282 -203.266802)
		(end 456.116182 -203.266802)
		(width 0.20066)
		(layer "F.Cu")
		(net "M_H_CPU0_SB_DQ<26>")
	)
	(segment
		(start 457.814426 -203.266802)
		(end 458.24648 -203.698856)
		(width 0.20066)
		(layer "F.Cu")
		(net "M_H_CPU0_SB_DQ<26>")
	)
	(segment
		(start 458.538326 -203.698856)
		(end 458.543152 -203.698856)
		(width 0.101854)
		(layer "F.Cu")
		(net "M_H_CPU0_SB_DQ<26>")
	)
	(segment
		(start 456.116182 -203.266802)
		(end 457.814426 -203.266802)
		(width 0.20066)
		(layer "F.Cu")
		(net "M_H_CPU0_SB_DQ<26>")
	)
	(segment
		(start 461.455516 -203.499974)
		(end 461.455516 -203.249022)
		(width 0.20066)
		(layer "F.Cu")
		(net "M_H_CPU0_SB_DQ<26>")
	)
	(segment
		(start 435.884066 -205.393798)
		(end 435.76748 -205.393798)
		(width 0.18288)
		(layer "In11.Cu")
		(net "M_H_CPU0_SB_DQ<26>")
	)
	(segment
		(start 409.082494 -205.236826)
		(end 408.616404 -205.702916)
		(width 0.18288)
		(layer "In11.Cu")
		(net "M_H_CPU0_SB_DQ<26>")
	)
	(segment
		(start 379.598936 -229.762304)
		(end 379.588522 -229.7684)
		(width 0.088646)
		(layer "In11.Cu")
		(net "M_H_CPU0_SB_DQ<26>")
	)
	(segment
		(start 428.081694 -205.643226)
		(end 427.675294 -205.236826)
		(width 0.18288)
		(layer "In11.Cu")
		(net "M_H_CPU0_SB_DQ<26>")
	)
	(segment
		(start 425.113704 -205.390496)
		(end 424.885866 -205.391004)
		(width 0.18288)
		(layer "In11.Cu")
		(net "M_H_CPU0_SB_DQ<26>")
	)
	(segment
		(start 380.538482 -229.762304)
		(end 380.528068 -229.7684)
		(width 0.088646)
		(layer "In11.Cu")
		(net "M_H_CPU0_SB_DQ<26>")
	)
	(segment
		(start 424.885866 -205.391004)
		(end 424.789346 -205.391004)
		(width 0.18288)
		(layer "In11.Cu")
		(net "M_H_CPU0_SB_DQ<26>")
	)
	(segment
		(start 455.011282 -203.266802)
		(end 454.158858 -203.266802)
		(width 0.18288)
		(layer "In11.Cu")
		(net "M_H_CPU0_SB_DQ<26>")
	)
	(segment
		(start 448.836542 -206.89697)
		(end 448.643502 -207.09001)
		(width 0.18288)
		(layer "In11.Cu")
		(net "M_H_CPU0_SB_DQ<26>")
	)
	(segment
		(start 387.75767 -227.425504)
		(end 387.75767 -227.69068)
		(width 0.088646)
		(layer "In11.Cu")
		(net "M_H_CPU0_SB_DQ<26>")
	)
	(segment
		(start 381.478536 -229.762304)
		(end 381.468122 -229.7684)
		(width 0.088646)
		(layer "In11.Cu")
		(net "M_H_CPU0_SB_DQ<26>")
	)
	(segment
		(start 435.767226 -205.393544)
		(end 435.137306 -205.393544)
		(width 0.18288)
		(layer "In11.Cu")
		(net "M_H_CPU0_SB_DQ<26>")
	)
	(segment
		(start 444.806324 -206.743808)
		(end 444.613284 -206.936848)
		(width 0.18288)
		(layer "In11.Cu")
		(net "M_H_CPU0_SB_DQ<26>")
	)
	(segment
		(start 388.677404 -227.32873)
		(end 388.10311 -227.32873)
		(width 0.18288)
		(layer "In11.Cu")
		(net "M_H_CPU0_SB_DQ<26>")
	)
	(segment
		(start 444.105284 -205.734666)
		(end 443.911736 -205.541118)
		(width 0.18288)
		(layer "In11.Cu")
		(net "M_H_CPU0_SB_DQ<26>")
	)
	(segment
		(start 435.137306 -205.393544)
		(end 434.969666 -205.225904)
		(width 0.18288)
		(layer "In11.Cu")
		(net "M_H_CPU0_SB_DQ<26>")
	)
	(segment
		(start 423.222928 -205.592426)
		(end 421.601646 -205.592426)
		(width 0.18288)
		(layer "In11.Cu")
		(net "M_H_CPU0_SB_DQ<26>")
	)
	(segment
		(start 387.75767 -227.69068)
		(end 387.143244 -228.305106)
		(width 0.088646)
		(layer "In11.Cu")
		(net "M_H_CPU0_SB_DQ<26>")
	)
	(segment
		(start 420.657782 -205.38694)
		(end 416.27298 -205.38694)
		(width 0.18288)
		(layer "In11.Cu")
		(net "M_H_CPU0_SB_DQ<26>")
	)
	(segment
		(start 412.689294 -205.592426)
		(end 412.333694 -205.236826)
		(width 0.18288)
		(layer "In11.Cu")
		(net "M_H_CPU0_SB_DQ<26>")
	)
	(segment
		(start 454.158858 -203.266802)
		(end 452.033386 -205.392274)
		(width 0.18288)
		(layer "In11.Cu")
		(net "M_H_CPU0_SB_DQ<26>")
	)
	(segment
		(start 424.789346 -205.391004)
		(end 423.422318 -205.393036)
		(width 0.18288)
		(layer "In11.Cu")
		(net "M_H_CPU0_SB_DQ<26>")
	)
	(segment
		(start 376.779282 -229.762304)
		(end 376.76455 -229.77094)
		(width 0.088646)
		(layer "In11.Cu")
		(net "M_H_CPU0_SB_DQ<26>")
	)
	(segment
		(start 449.109084 -205.296262)
		(end 448.836542 -205.568804)
		(width 0.18288)
		(layer "In11.Cu")
		(net "M_H_CPU0_SB_DQ<26>")
	)
	(segment
		(start 408.616404 -205.702916)
		(end 407.760932 -205.702916)
		(width 0.18288)
		(layer "In11.Cu")
		(net "M_H_CPU0_SB_DQ<26>")
	)
	(segment
		(start 425.267374 -205.236826)
		(end 425.113704 -205.390496)
		(width 0.18288)
		(layer "In11.Cu")
		(net "M_H_CPU0_SB_DQ<26>")
	)
	(segment
		(start 446.794382 -205.541626)
		(end 444.999364 -205.541626)
		(width 0.18288)
		(layer "In11.Cu")
		(net "M_H_CPU0_SB_DQ<26>")
	)
	(segment
		(start 444.613284 -206.936848)
		(end 444.298324 -206.936848)
		(width 0.18288)
		(layer "In11.Cu")
		(net "M_H_CPU0_SB_DQ<26>")
	)
	(segment
		(start 421.601646 -205.592426)
		(end 421.397684 -205.388464)
		(width 0.18288)
		(layer "In11.Cu")
		(net "M_H_CPU0_SB_DQ<26>")
	)
	(segment
		(start 387.143244 -228.491288)
		(end 386.81279 -228.821742)
		(width 0.088646)
		(layer "In11.Cu")
		(net "M_H_CPU0_SB_DQ<26>")
	)
	(segment
		(start 447.19494 -205.375764)
		(end 446.794382 -205.541626)
		(width 0.18288)
		(layer "In11.Cu")
		(net "M_H_CPU0_SB_DQ<26>")
	)
	(segment
		(start 388.10311 -227.32873)
		(end 387.854444 -227.32873)
		(width 0.088646)
		(layer "In11.Cu")
		(net "M_H_CPU0_SB_DQ<26>")
	)
	(segment
		(start 443.911736 -205.541118)
		(end 443.080902 -205.541118)
		(width 0.18288)
		(layer "In11.Cu")
		(net "M_H_CPU0_SB_DQ<26>")
	)
	(segment
		(start 448.132962 -206.89697)
		(end 448.132962 -205.568804)
		(width 0.18288)
		(layer "In11.Cu")
		(net "M_H_CPU0_SB_DQ<26>")
	)
	(segment
		(start 448.132962 -205.568804)
		(end 447.939922 -205.375764)
		(width 0.18288)
		(layer "In11.Cu")
		(net "M_H_CPU0_SB_DQ<26>")
	)
	(segment
		(start 416.067494 -205.592426)
		(end 412.689294 -205.592426)
		(width 0.18288)
		(layer "In11.Cu")
		(net "M_H_CPU0_SB_DQ<26>")
	)
	(segment
		(start 391.601452 -223.364298)
		(end 391.601452 -224.404682)
		(width 0.18288)
		(layer "In11.Cu")
		(net "M_H_CPU0_SB_DQ<26>")
	)
	(segment
		(start 434.969666 -205.225904)
		(end 431.173636 -205.225904)
		(width 0.18288)
		(layer "In11.Cu")
		(net "M_H_CPU0_SB_DQ<26>")
	)
	(segment
		(start 444.298324 -206.936848)
		(end 444.105284 -206.743808)
		(width 0.18288)
		(layer "In11.Cu")
		(net "M_H_CPU0_SB_DQ<26>")
	)
	(segment
		(start 448.836542 -205.568804)
		(end 448.836542 -206.89697)
		(width 0.18288)
		(layer "In11.Cu")
		(net "M_H_CPU0_SB_DQ<26>")
	)
	(segment
		(start 443.080902 -205.541118)
		(end 442.876178 -205.336394)
		(width 0.18288)
		(layer "In11.Cu")
		(net "M_H_CPU0_SB_DQ<26>")
	)
	(segment
		(start 448.326002 -207.09001)
		(end 448.132962 -206.89697)
		(width 0.18288)
		(layer "In11.Cu")
		(net "M_H_CPU0_SB_DQ<26>")
	)
	(segment
		(start 416.27298 -205.38694)
		(end 416.067494 -205.592426)
		(width 0.18288)
		(layer "In11.Cu")
		(net "M_H_CPU0_SB_DQ<26>")
	)
	(segment
		(start 441.35294 -205.39456)
		(end 436.56885 -205.39456)
		(width 0.18288)
		(layer "In11.Cu")
		(net "M_H_CPU0_SB_DQ<26>")
	)
	(segment
		(start 452.033386 -205.392274)
		(end 450.152262 -205.392274)
		(width 0.18288)
		(layer "In11.Cu")
		(net "M_H_CPU0_SB_DQ<26>")
	)
	(segment
		(start 448.643502 -207.09001)
		(end 448.326002 -207.09001)
		(width 0.18288)
		(layer "In11.Cu")
		(net "M_H_CPU0_SB_DQ<26>")
	)
	(segment
		(start 378.658882 -229.762304)
		(end 378.64415 -229.77094)
		(width 0.088646)
		(layer "In11.Cu")
		(net "M_H_CPU0_SB_DQ<26>")
	)
	(segment
		(start 374.899682 -229.762304)
		(end 374.88495 -229.77094)
		(width 0.088646)
		(layer "In11.Cu")
		(net "M_H_CPU0_SB_DQ<26>")
	)
	(segment
		(start 385.520184 -229.272846)
		(end 385.520184 -229.282752)
		(width 0.088646)
		(layer "In11.Cu")
		(net "M_H_CPU0_SB_DQ<26>")
	)
	(segment
		(start 423.422318 -205.393036)
		(end 423.222928 -205.592426)
		(width 0.18288)
		(layer "In11.Cu")
		(net "M_H_CPU0_SB_DQ<26>")
	)
	(segment
		(start 430.756314 -205.643226)
		(end 428.081694 -205.643226)
		(width 0.18288)
		(layer "In11.Cu")
		(net "M_H_CPU0_SB_DQ<26>")
	)
	(segment
		(start 373.053356 -229.537768)
		(end 372.737634 -229.272846)
		(width 0.088646)
		(layer "In11.Cu")
		(net "M_H_CPU0_SB_DQ<26>")
	)
	(segment
		(start 431.173636 -205.225904)
		(end 430.756314 -205.643226)
		(width 0.18288)
		(layer "In11.Cu")
		(net "M_H_CPU0_SB_DQ<26>")
	)
	(segment
		(start 442.876178 -205.336394)
		(end 441.411106 -205.336394)
		(width 0.18288)
		(layer "In11.Cu")
		(net "M_H_CPU0_SB_DQ<26>")
	)
	(segment
		(start 436.56885 -205.39456)
		(end 435.884066 -205.393798)
		(width 0.18288)
		(layer "In11.Cu")
		(net "M_H_CPU0_SB_DQ<26>")
	)
	(segment
		(start 444.806324 -205.734666)
		(end 444.806324 -206.743808)
		(width 0.18288)
		(layer "In11.Cu")
		(net "M_H_CPU0_SB_DQ<26>")
	)
	(segment
		(start 385.707636 -228.948488)
		(end 385.698746 -228.953568)
		(width 0.088646)
		(layer "In11.Cu")
		(net "M_H_CPU0_SB_DQ<26>")
	)
	(segment
		(start 441.411106 -205.336394)
		(end 441.35294 -205.39456)
		(width 0.18288)
		(layer "In11.Cu")
		(net "M_H_CPU0_SB_DQ<26>")
	)
	(segment
		(start 387.143244 -228.305106)
		(end 387.143244 -228.491288)
		(width 0.088646)
		(layer "In11.Cu")
		(net "M_H_CPU0_SB_DQ<26>")
	)
	(segment
		(start 398.532858 -214.29853)
		(end 398.532858 -216.432892)
		(width 0.18288)
		(layer "In11.Cu")
		(net "M_H_CPU0_SB_DQ<26>")
	)
	(segment
		(start 447.939922 -205.375764)
		(end 447.19494 -205.375764)
		(width 0.18288)
		(layer "In11.Cu")
		(net "M_H_CPU0_SB_DQ<26>")
	)
	(segment
		(start 435.76748 -205.393798)
		(end 435.767226 -205.393544)
		(width 0.18288)
		(layer "In11.Cu")
		(net "M_H_CPU0_SB_DQ<26>")
	)
	(segment
		(start 444.105284 -206.743808)
		(end 444.105284 -205.734666)
		(width 0.18288)
		(layer "In11.Cu")
		(net "M_H_CPU0_SB_DQ<26>")
	)
	(segment
		(start 427.675294 -205.236826)
		(end 425.267374 -205.236826)
		(width 0.18288)
		(layer "In11.Cu")
		(net "M_H_CPU0_SB_DQ<26>")
	)
	(segment
		(start 444.999364 -205.541626)
		(end 444.806324 -205.734666)
		(width 0.18288)
		(layer "In11.Cu")
		(net "M_H_CPU0_SB_DQ<26>")
	)
	(segment
		(start 375.839482 -229.762304)
		(end 375.82475 -229.77094)
		(width 0.088646)
		(layer "In11.Cu")
		(net "M_H_CPU0_SB_DQ<26>")
	)
	(segment
		(start 373.959882 -229.762304)
		(end 373.949468 -229.7684)
		(width 0.088646)
		(layer "In11.Cu")
		(net "M_H_CPU0_SB_DQ<26>")
	)
	(segment
		(start 450.05625 -205.296262)
		(end 449.109084 -205.296262)
		(width 0.18288)
		(layer "In11.Cu")
		(net "M_H_CPU0_SB_DQ<26>")
	)
	(segment
		(start 405.609806 -207.854042)
		(end 404.977346 -207.854042)
		(width 0.18288)
		(layer "In11.Cu")
		(net "M_H_CPU0_SB_DQ<26>")
	)
	(segment
		(start 421.397684 -205.388464)
		(end 420.659306 -205.388464)
		(width 0.18288)
		(layer "In11.Cu")
		(net "M_H_CPU0_SB_DQ<26>")
	)
	(segment
		(start 450.152262 -205.392274)
		(end 450.05625 -205.296262)
		(width 0.18288)
		(layer "In11.Cu")
		(net "M_H_CPU0_SB_DQ<26>")
	)
	(segment
		(start 407.760932 -205.702916)
		(end 405.609806 -207.854042)
		(width 0.18288)
		(layer "In11.Cu")
		(net "M_H_CPU0_SB_DQ<26>")
	)
	(segment
		(start 412.333694 -205.236826)
		(end 409.082494 -205.236826)
		(width 0.18288)
		(layer "In11.Cu")
		(net "M_H_CPU0_SB_DQ<26>")
	)
	(segment
		(start 398.532858 -216.432892)
		(end 391.601452 -223.364298)
		(width 0.18288)
		(layer "In11.Cu")
		(net "M_H_CPU0_SB_DQ<26>")
	)
	(segment
		(start 404.977346 -207.854042)
		(end 398.532858 -214.29853)
		(width 0.18288)
		(layer "In11.Cu")
		(net "M_H_CPU0_SB_DQ<26>")
	)
	(segment
		(start 420.659306 -205.388464)
		(end 420.657782 -205.38694)
		(width 0.18288)
		(layer "In11.Cu")
		(net "M_H_CPU0_SB_DQ<26>")
	)
	(segment
		(start 387.854444 -227.32873)
		(end 387.75767 -227.425504)
		(width 0.088646)
		(layer "In11.Cu")
		(net "M_H_CPU0_SB_DQ<26>")
	)
	(segment
		(start 391.601452 -224.404682)
		(end 388.677404 -227.32873)
		(width 0.18288)
		(layer "In11.Cu")
		(net "M_H_CPU0_SB_DQ<26>")
	)
	(arc
		(start 379.973332 -229.762304)
		(mid 379.786134 -229.712161)
		(end 379.598936 -229.762304)
		(width 0.088646)
		(layer "In11.Cu")
		(net "M_H_CPU0_SB_DQ<26>")
	)
	(arc
		(start 386.082032 -228.948488)
		(mid 385.894834 -228.898345)
		(end 385.707636 -228.948488)
		(width 0.088646)
		(layer "In11.Cu")
		(net "M_H_CPU0_SB_DQ<26>")
	)
	(arc
		(start 376.213878 -229.762304)
		(mid 376.02668 -229.712161)
		(end 375.839482 -229.762304)
		(width 0.088646)
		(layer "In11.Cu")
		(net "M_H_CPU0_SB_DQ<26>")
	)
	(arc
		(start 382.418336 -229.762304)
		(mid 382.135634 -229.83808)
		(end 381.852932 -229.762304)
		(width 0.088646)
		(layer "In11.Cu")
		(net "M_H_CPU0_SB_DQ<26>")
	)
	(arc
		(start 373.394732 -229.762304)
		(mid 373.220789 -229.654984)
		(end 373.053356 -229.537768)
		(width 0.088646)
		(layer "In11.Cu")
		(net "M_H_CPU0_SB_DQ<26>")
	)
	(arc
		(start 386.81279 -228.821742)
		(mid 386.734286 -228.89056)
		(end 386.647436 -228.948488)
		(width 0.088646)
		(layer "In11.Cu")
		(net "M_H_CPU0_SB_DQ<26>")
	)
	(arc
		(start 384.297936 -229.762304)
		(mid 384.015234 -229.83808)
		(end 383.732532 -229.762304)
		(width 0.088646)
		(layer "In11.Cu")
		(net "M_H_CPU0_SB_DQ<26>")
	)
	(arc
		(start 380.528068 -229.7684)
		(mid 380.24989 -229.838123)
		(end 379.973332 -229.762304)
		(width 0.088646)
		(layer "In11.Cu")
		(net "M_H_CPU0_SB_DQ<26>")
	)
	(arc
		(start 381.468122 -229.7684)
		(mid 381.18969 -229.838246)
		(end 380.912878 -229.762304)
		(width 0.088646)
		(layer "In11.Cu")
		(net "M_H_CPU0_SB_DQ<26>")
	)
	(arc
		(start 377.153678 -229.762304)
		(mid 376.96648 -229.712161)
		(end 376.779282 -229.762304)
		(width 0.088646)
		(layer "In11.Cu")
		(net "M_H_CPU0_SB_DQ<26>")
	)
	(arc
		(start 383.358136 -229.762304)
		(mid 383.075434 -229.83808)
		(end 382.792732 -229.762304)
		(width 0.088646)
		(layer "In11.Cu")
		(net "M_H_CPU0_SB_DQ<26>")
	)
	(arc
		(start 382.792732 -229.762304)
		(mid 382.605534 -229.712161)
		(end 382.418336 -229.762304)
		(width 0.088646)
		(layer "In11.Cu")
		(net "M_H_CPU0_SB_DQ<26>")
	)
	(arc
		(start 383.732532 -229.762304)
		(mid 383.545334 -229.712161)
		(end 383.358136 -229.762304)
		(width 0.088646)
		(layer "In11.Cu")
		(net "M_H_CPU0_SB_DQ<26>")
	)
	(arc
		(start 385.520184 -229.282752)
		(mid 385.442073 -229.559701)
		(end 385.237736 -229.762304)
		(width 0.088646)
		(layer "In11.Cu")
		(net "M_H_CPU0_SB_DQ<26>")
	)
	(arc
		(start 378.093478 -229.762304)
		(mid 377.90628 -229.712161)
		(end 377.719082 -229.762304)
		(width 0.088646)
		(layer "In11.Cu")
		(net "M_H_CPU0_SB_DQ<26>")
	)
	(arc
		(start 378.64415 -229.77094)
		(mid 378.367675 -229.83826)
		(end 378.093478 -229.762304)
		(width 0.088646)
		(layer "In11.Cu")
		(net "M_H_CPU0_SB_DQ<26>")
	)
	(arc
		(start 374.334278 -229.762304)
		(mid 374.14708 -229.712161)
		(end 373.959882 -229.762304)
		(width 0.088646)
		(layer "In11.Cu")
		(net "M_H_CPU0_SB_DQ<26>")
	)
	(arc
		(start 375.274078 -229.762304)
		(mid 375.08688 -229.712161)
		(end 374.899682 -229.762304)
		(width 0.088646)
		(layer "In11.Cu")
		(net "M_H_CPU0_SB_DQ<26>")
	)
	(arc
		(start 379.033278 -229.762304)
		(mid 378.84608 -229.712161)
		(end 378.658882 -229.762304)
		(width 0.088646)
		(layer "In11.Cu")
		(net "M_H_CPU0_SB_DQ<26>")
	)
	(arc
		(start 385.698746 -228.953568)
		(mid 385.567832 -229.089928)
		(end 385.520184 -229.272846)
		(width 0.088646)
		(layer "In11.Cu")
		(net "M_H_CPU0_SB_DQ<26>")
	)
	(arc
		(start 380.912878 -229.762304)
		(mid 380.72568 -229.712161)
		(end 380.538482 -229.762304)
		(width 0.088646)
		(layer "In11.Cu")
		(net "M_H_CPU0_SB_DQ<26>")
	)
	(arc
		(start 386.647436 -228.948488)
		(mid 386.364734 -229.024264)
		(end 386.082032 -228.948488)
		(width 0.088646)
		(layer "In11.Cu")
		(net "M_H_CPU0_SB_DQ<26>")
	)
	(arc
		(start 375.82475 -229.77094)
		(mid 375.548275 -229.83826)
		(end 375.274078 -229.762304)
		(width 0.088646)
		(layer "In11.Cu")
		(net "M_H_CPU0_SB_DQ<26>")
	)
	(arc
		(start 373.949468 -229.7684)
		(mid 373.67129 -229.838123)
		(end 373.394732 -229.762304)
		(width 0.088646)
		(layer "In11.Cu")
		(net "M_H_CPU0_SB_DQ<26>")
	)
	(arc
		(start 376.76455 -229.77094)
		(mid 376.488075 -229.83826)
		(end 376.213878 -229.762304)
		(width 0.088646)
		(layer "In11.Cu")
		(net "M_H_CPU0_SB_DQ<26>")
	)
	(arc
		(start 381.852932 -229.762304)
		(mid 381.665734 -229.712161)
		(end 381.478536 -229.762304)
		(width 0.088646)
		(layer "In11.Cu")
		(net "M_H_CPU0_SB_DQ<26>")
	)
	(arc
		(start 384.672332 -229.762304)
		(mid 384.485134 -229.712161)
		(end 384.297936 -229.762304)
		(width 0.088646)
		(layer "In11.Cu")
		(net "M_H_CPU0_SB_DQ<26>")
	)
	(arc
		(start 379.588522 -229.7684)
		(mid 379.31009 -229.838246)
		(end 379.033278 -229.762304)
		(width 0.088646)
		(layer "In11.Cu")
		(net "M_H_CPU0_SB_DQ<26>")
	)
	(arc
		(start 377.719082 -229.762304)
		(mid 377.43638 -229.83808)
		(end 377.153678 -229.762304)
		(width 0.088646)
		(layer "In11.Cu")
		(net "M_H_CPU0_SB_DQ<26>")
	)
	(arc
		(start 385.237736 -229.762304)
		(mid 384.955034 -229.83808)
		(end 384.672332 -229.762304)
		(width 0.088646)
		(layer "In11.Cu")
		(net "M_H_CPU0_SB_DQ<26>")
	)
	(arc
		(start 374.88495 -229.77094)
		(mid 374.608475 -229.83826)
		(end 374.334278 -229.762304)
		(width 0.088646)
		(layer "In11.Cu")
		(net "M_H_CPU0_SB_DQ<26>")
	)
	(segment
		(start 457.120244 -201.991722)
		(end 454.931526 -201.991722)
		(width 0.1016)
		(layer "F.Cu")
		(net "M_H_CPU0_SB_DQ<25>")
	)
	(segment
		(start 454.448672 -202.109832)
		(end 454.448672 -202.47737)
		(width 0.20066)
		(layer "F.Cu")
		(net "M_H_CPU0_SB_DQ<25>")
	)
	(segment
		(start 454.260712 -202.66533)
		(end 453.785478 -202.66533)
		(width 0.20066)
		(layer "F.Cu")
		(net "M_H_CPU0_SB_DQ<25>")
	)
	(segment
		(start 371.327934 -228.459284)
		(end 371.32768 -228.45903)
		(width 0.20066)
		(layer "F.Cu")
		(net "M_H_CPU0_SB_DQ<25>")
	)
	(segment
		(start 371.327934 -228.99497)
		(end 371.327934 -228.459284)
		(width 0.20066)
		(layer "F.Cu")
		(net "M_H_CPU0_SB_DQ<25>")
	)
	(segment
		(start 459.559914 -202.416664)
		(end 459.55966 -202.416918)
		(width 0.20066)
		(layer "F.Cu")
		(net "M_H_CPU0_SB_DQ<25>")
	)
	(segment
		(start 454.91146 -201.991722)
		(end 454.566782 -201.991722)
		(width 0.20066)
		(layer "F.Cu")
		(net "M_H_CPU0_SB_DQ<25>")
	)
	(segment
		(start 452.016114 -202.416664)
		(end 450.911214 -202.416664)
		(width 0.20066)
		(layer "F.Cu")
		(net "M_H_CPU0_SB_DQ<25>")
	)
	(segment
		(start 454.931526 -201.991722)
		(end 454.91146 -201.991722)
		(width 0.101854)
		(layer "F.Cu")
		(net "M_H_CPU0_SB_DQ<25>")
	)
	(segment
		(start 459.55966 -202.416918)
		(end 457.968096 -202.416918)
		(width 0.20066)
		(layer "F.Cu")
		(net "M_H_CPU0_SB_DQ<25>")
	)
	(segment
		(start 454.566782 -201.991722)
		(end 454.448672 -202.109832)
		(width 0.20066)
		(layer "F.Cu")
		(net "M_H_CPU0_SB_DQ<25>")
	)
	(segment
		(start 457.968096 -202.416918)
		(end 457.53655 -201.985372)
		(width 0.20066)
		(layer "F.Cu")
		(net "M_H_CPU0_SB_DQ<25>")
	)
	(segment
		(start 453.536812 -202.416664)
		(end 452.016114 -202.416664)
		(width 0.20066)
		(layer "F.Cu")
		(net "M_H_CPU0_SB_DQ<25>")
	)
	(segment
		(start 457.53655 -201.985372)
		(end 457.126594 -201.985372)
		(width 0.20066)
		(layer "F.Cu")
		(net "M_H_CPU0_SB_DQ<25>")
	)
	(segment
		(start 453.785478 -202.66533)
		(end 453.536812 -202.416664)
		(width 0.20066)
		(layer "F.Cu")
		(net "M_H_CPU0_SB_DQ<25>")
	)
	(segment
		(start 457.126594 -201.985372)
		(end 457.120244 -201.991722)
		(width 0.1016)
		(layer "F.Cu")
		(net "M_H_CPU0_SB_DQ<25>")
	)
	(segment
		(start 454.448672 -202.47737)
		(end 454.260712 -202.66533)
		(width 0.20066)
		(layer "F.Cu")
		(net "M_H_CPU0_SB_DQ<25>")
	)
	(segment
		(start 425.024804 -202.842368)
		(end 424.191176 -202.842368)
		(width 0.18288)
		(layer "In11.Cu")
		(net "M_H_CPU0_SB_DQ<25>")
	)
	(segment
		(start 412.885128 -202.831192)
		(end 412.689294 -203.027026)
		(width 0.18288)
		(layer "In11.Cu")
		(net "M_H_CPU0_SB_DQ<25>")
	)
	(segment
		(start 423.729658 -201.944224)
		(end 423.414698 -201.944224)
		(width 0.18288)
		(layer "In11.Cu")
		(net "M_H_CPU0_SB_DQ<25>")
	)
	(segment
		(start 422.520618 -202.57389)
		(end 422.520618 -202.182476)
		(width 0.18288)
		(layer "In11.Cu")
		(net "M_H_CPU0_SB_DQ<25>")
	)
	(segment
		(start 425.64685 -202.286108)
		(end 425.64685 -202.80503)
		(width 0.18288)
		(layer "In11.Cu")
		(net "M_H_CPU0_SB_DQ<25>")
	)
	(segment
		(start 433.202334 -202.23099)
		(end 433.009294 -202.42403)
		(width 0.18288)
		(layer "In11.Cu")
		(net "M_H_CPU0_SB_DQ<25>")
	)
	(segment
		(start 444.144146 -202.097386)
		(end 443.951106 -202.290426)
		(width 0.18288)
		(layer "In11.Cu")
		(net "M_H_CPU0_SB_DQ<25>")
	)
	(segment
		(start 408.498294 -203.027026)
		(end 408.304238 -202.83297)
		(width 0.18288)
		(layer "In11.Cu")
		(net "M_H_CPU0_SB_DQ<25>")
	)
	(segment
		(start 426.34789 -202.286108)
		(end 426.15485 -202.093068)
		(width 0.18288)
		(layer "In11.Cu")
		(net "M_H_CPU0_SB_DQ<25>")
	)
	(segment
		(start 425.180506 -202.99807)
		(end 425.024804 -202.842368)
		(width 0.18288)
		(layer "In11.Cu")
		(net "M_H_CPU0_SB_DQ<25>")
	)
	(segment
		(start 408.304238 -202.83297)
		(end 407.657046 -202.83297)
		(width 0.18288)
		(layer "In11.Cu")
		(net "M_H_CPU0_SB_DQ<25>")
	)
	(segment
		(start 450.774562 -202.835002)
		(end 450.556122 -202.925426)
		(width 0.18288)
		(layer "In11.Cu")
		(net "M_H_CPU0_SB_DQ<25>")
	)
	(segment
		(start 406.384506 -203.27239)
		(end 405.704548 -203.952348)
		(width 0.18288)
		(layer "In11.Cu")
		(net "M_H_CPU0_SB_DQ<25>")
	)
	(segment
		(start 433.712874 -202.757786)
		(end 433.712874 -202.42403)
		(width 0.18288)
		(layer "In11.Cu")
		(net "M_H_CPU0_SB_DQ<25>")
	)
	(segment
		(start 435.19979 -202.84313)
		(end 435.092094 -202.950826)
		(width 0.18288)
		(layer "In11.Cu")
		(net "M_H_CPU0_SB_DQ<25>")
	)
	(segment
		(start 423.922698 -202.57389)
		(end 423.922698 -202.137264)
		(width 0.18288)
		(layer "In11.Cu")
		(net "M_H_CPU0_SB_DQ<25>")
	)
	(segment
		(start 432.816254 -202.950826)
		(end 431.43043 -202.950826)
		(width 0.18288)
		(layer "In11.Cu")
		(net "M_H_CPU0_SB_DQ<25>")
	)
	(segment
		(start 419.999414 -202.976226)
		(end 419.075362 -202.976226)
		(width 0.18288)
		(layer "In11.Cu")
		(net "M_H_CPU0_SB_DQ<25>")
	)
	(segment
		(start 375.839482 -228.783388)
		(end 375.82475 -228.774752)
		(width 0.088646)
		(layer "In11.Cu")
		(net "M_H_CPU0_SB_DQ<25>")
	)
	(segment
		(start 422.520618 -202.182476)
		(end 422.327578 -201.989436)
		(width 0.18288)
		(layer "In11.Cu")
		(net "M_H_CPU0_SB_DQ<25>")
	)
	(segment
		(start 382.418082 -228.783388)
		(end 382.407668 -228.777292)
		(width 0.088646)
		(layer "In11.Cu")
		(net "M_H_CPU0_SB_DQ<25>")
	)
	(segment
		(start 405.704548 -203.952348)
		(end 405.704548 -203.954126)
		(width 0.18288)
		(layer "In11.Cu")
		(net "M_H_CPU0_SB_DQ<25>")
	)
	(segment
		(start 444.847726 -201.86142)
		(end 444.654686 -201.66838)
		(width 0.18288)
		(layer "In11.Cu")
		(net "M_H_CPU0_SB_DQ<25>")
	)
	(segment
		(start 407.657046 -202.83297)
		(end 407.217626 -203.27239)
		(width 0.18288)
		(layer "In11.Cu")
		(net "M_H_CPU0_SB_DQ<25>")
	)
	(segment
		(start 373.960136 -228.783388)
		(end 373.951246 -228.778308)
		(width 0.088646)
		(layer "In11.Cu")
		(net "M_H_CPU0_SB_DQ<25>")
	)
	(segment
		(start 426.34789 -202.808586)
		(end 426.34789 -202.286108)
		(width 0.18288)
		(layer "In11.Cu")
		(net "M_H_CPU0_SB_DQ<25>")
	)
	(segment
		(start 431.30343 -202.823826)
		(end 427.599094 -202.823826)
		(width 0.18288)
		(layer "In11.Cu")
		(net "M_H_CPU0_SB_DQ<25>")
	)
	(segment
		(start 433.009294 -202.42403)
		(end 433.009294 -202.757786)
		(width 0.18288)
		(layer "In11.Cu")
		(net "M_H_CPU0_SB_DQ<25>")
	)
	(segment
		(start 431.43043 -202.950826)
		(end 431.30343 -202.823826)
		(width 0.18288)
		(layer "In11.Cu")
		(net "M_H_CPU0_SB_DQ<25>")
	)
	(segment
		(start 425.64685 -202.80503)
		(end 425.45381 -202.99807)
		(width 0.18288)
		(layer "In11.Cu")
		(net "M_H_CPU0_SB_DQ<25>")
	)
	(segment
		(start 387.143244 -227.400866)
		(end 386.650484 -227.893626)
		(width 0.088646)
		(layer "In11.Cu")
		(net "M_H_CPU0_SB_DQ<25>")
	)
	(segment
		(start 439.317892 -202.65517)
		(end 436.915306 -202.65517)
		(width 0.18288)
		(layer "In11.Cu")
		(net "M_H_CPU0_SB_DQ<25>")
	)
	(segment
		(start 418.689282 -202.2729)
		(end 418.303202 -202.2729)
		(width 0.18288)
		(layer "In11.Cu")
		(net "M_H_CPU0_SB_DQ<25>")
	)
	(segment
		(start 425.45381 -202.99807)
		(end 425.180506 -202.99807)
		(width 0.18288)
		(layer "In11.Cu")
		(net "M_H_CPU0_SB_DQ<25>")
	)
	(segment
		(start 422.012618 -201.989436)
		(end 421.159432 -202.842622)
		(width 0.18288)
		(layer "In11.Cu")
		(net "M_H_CPU0_SB_DQ<25>")
	)
	(segment
		(start 444.337186 -201.66838)
		(end 444.144146 -201.86142)
		(width 0.18288)
		(layer "In11.Cu")
		(net "M_H_CPU0_SB_DQ<25>")
	)
	(segment
		(start 384.859784 -228.440488)
		(end 384.859784 -228.45903)
		(width 0.088646)
		(layer "In11.Cu")
		(net "M_H_CPU0_SB_DQ<25>")
	)
	(segment
		(start 376.779282 -228.783388)
		(end 376.76455 -228.774752)
		(width 0.088646)
		(layer "In11.Cu")
		(net "M_H_CPU0_SB_DQ<25>")
	)
	(segment
		(start 379.598682 -228.783388)
		(end 379.58395 -228.774752)
		(width 0.088646)
		(layer "In11.Cu")
		(net "M_H_CPU0_SB_DQ<25>")
	)
	(segment
		(start 423.922698 -202.137264)
		(end 423.729658 -201.944224)
		(width 0.18288)
		(layer "In11.Cu")
		(net "M_H_CPU0_SB_DQ<25>")
	)
	(segment
		(start 433.905914 -202.950826)
		(end 433.712874 -202.757786)
		(width 0.18288)
		(layer "In11.Cu")
		(net "M_H_CPU0_SB_DQ<25>")
	)
	(segment
		(start 412.689294 -203.027026)
		(end 408.498294 -203.027026)
		(width 0.18288)
		(layer "In11.Cu")
		(net "M_H_CPU0_SB_DQ<25>")
	)
	(segment
		(start 423.221658 -202.137264)
		(end 423.221658 -202.57389)
		(width 0.18288)
		(layer "In11.Cu")
		(net "M_H_CPU0_SB_DQ<25>")
	)
	(segment
		(start 404.79853 -205.270862)
		(end 396.592298 -213.477094)
		(width 0.18288)
		(layer "In11.Cu")
		(net "M_H_CPU0_SB_DQ<25>")
	)
	(segment
		(start 450.911214 -202.69835)
		(end 450.774562 -202.835002)
		(width 0.18288)
		(layer "In11.Cu")
		(net "M_H_CPU0_SB_DQ<25>")
	)
	(segment
		(start 389.955532 -222.802196)
		(end 389.955532 -223.846644)
		(width 0.18288)
		(layer "In11.Cu")
		(net "M_H_CPU0_SB_DQ<25>")
	)
	(segment
		(start 415.79546 -202.831192)
		(end 412.885128 -202.831192)
		(width 0.18288)
		(layer "In11.Cu")
		(net "M_H_CPU0_SB_DQ<25>")
	)
	(segment
		(start 444.654686 -201.66838)
		(end 444.337186 -201.66838)
		(width 0.18288)
		(layer "In11.Cu")
		(net "M_H_CPU0_SB_DQ<25>")
	)
	(segment
		(start 427.599094 -202.823826)
		(end 427.421294 -203.001626)
		(width 0.18288)
		(layer "In11.Cu")
		(net "M_H_CPU0_SB_DQ<25>")
	)
	(segment
		(start 396.592298 -213.477094)
		(end 396.592298 -216.16543)
		(width 0.18288)
		(layer "In11.Cu")
		(net "M_H_CPU0_SB_DQ<25>")
	)
	(segment
		(start 423.028618 -202.76693)
		(end 422.713658 -202.76693)
		(width 0.18288)
		(layer "In11.Cu")
		(net "M_H_CPU0_SB_DQ<25>")
	)
	(segment
		(start 447.131694 -202.925426)
		(end 446.496694 -202.290426)
		(width 0.18288)
		(layer "In11.Cu")
		(net "M_H_CPU0_SB_DQ<25>")
	)
	(segment
		(start 444.144146 -201.86142)
		(end 444.144146 -202.097386)
		(width 0.18288)
		(layer "In11.Cu")
		(net "M_H_CPU0_SB_DQ<25>")
	)
	(segment
		(start 378.658882 -228.783388)
		(end 378.64415 -228.774752)
		(width 0.088646)
		(layer "In11.Cu")
		(net "M_H_CPU0_SB_DQ<25>")
	)
	(segment
		(start 373.020082 -228.134672)
		(end 373.00535 -228.143308)
		(width 0.088646)
		(layer "In11.Cu")
		(net "M_H_CPU0_SB_DQ<25>")
	)
	(segment
		(start 389.955532 -223.846644)
		(end 388.665974 -225.136202)
		(width 0.18288)
		(layer "In11.Cu")
		(net "M_H_CPU0_SB_DQ<25>")
	)
	(segment
		(start 441.479432 -203.058776)
		(end 441.261754 -202.841098)
		(width 0.18288)
		(layer "In11.Cu")
		(net "M_H_CPU0_SB_DQ<25>")
	)
	(segment
		(start 386.650484 -227.893626)
		(end 386.364734 -227.893626)
		(width 0.088646)
		(layer "In11.Cu")
		(net "M_H_CPU0_SB_DQ<25>")
	)
	(segment
		(start 418.110162 -202.46594)
		(end 418.110162 -202.783186)
		(width 0.18288)
		(layer "In11.Cu")
		(net "M_H_CPU0_SB_DQ<25>")
	)
	(segment
		(start 404.79853 -204.860144)
		(end 404.79853 -205.270862)
		(width 0.18288)
		(layer "In11.Cu")
		(net "M_H_CPU0_SB_DQ<25>")
	)
	(segment
		(start 445.040766 -202.290426)
		(end 444.847726 -202.097386)
		(width 0.18288)
		(layer "In11.Cu")
		(net "M_H_CPU0_SB_DQ<25>")
	)
	(segment
		(start 374.899682 -228.783388)
		(end 374.889268 -228.777292)
		(width 0.088646)
		(layer "In11.Cu")
		(net "M_H_CPU0_SB_DQ<25>")
	)
	(segment
		(start 423.414698 -201.944224)
		(end 423.221658 -202.137264)
		(width 0.18288)
		(layer "In11.Cu")
		(net "M_H_CPU0_SB_DQ<25>")
	)
	(segment
		(start 387.359398 -226.55022)
		(end 387.143244 -226.766374)
		(width 0.088646)
		(layer "In11.Cu")
		(net "M_H_CPU0_SB_DQ<25>")
	)
	(segment
		(start 387.143244 -226.766374)
		(end 387.143244 -227.400866)
		(width 0.088646)
		(layer "In11.Cu")
		(net "M_H_CPU0_SB_DQ<25>")
	)
	(segment
		(start 433.712874 -202.42403)
		(end 433.519834 -202.23099)
		(width 0.18288)
		(layer "In11.Cu")
		(net "M_H_CPU0_SB_DQ<25>")
	)
	(segment
		(start 424.191176 -202.842368)
		(end 423.922698 -202.57389)
		(width 0.18288)
		(layer "In11.Cu")
		(net "M_H_CPU0_SB_DQ<25>")
	)
	(segment
		(start 423.221658 -202.57389)
		(end 423.028618 -202.76693)
		(width 0.18288)
		(layer "In11.Cu")
		(net "M_H_CPU0_SB_DQ<25>")
	)
	(segment
		(start 444.847726 -202.097386)
		(end 444.847726 -201.86142)
		(width 0.18288)
		(layer "In11.Cu")
		(net "M_H_CPU0_SB_DQ<25>")
	)
	(segment
		(start 426.15485 -202.093068)
		(end 425.83989 -202.093068)
		(width 0.18288)
		(layer "In11.Cu")
		(net "M_H_CPU0_SB_DQ<25>")
	)
	(segment
		(start 435.092094 -202.950826)
		(end 433.905914 -202.950826)
		(width 0.18288)
		(layer "In11.Cu")
		(net "M_H_CPU0_SB_DQ<25>")
	)
	(segment
		(start 439.50382 -202.841098)
		(end 439.317892 -202.65517)
		(width 0.18288)
		(layer "In11.Cu")
		(net "M_H_CPU0_SB_DQ<25>")
	)
	(segment
		(start 446.496694 -202.290426)
		(end 445.040766 -202.290426)
		(width 0.18288)
		(layer "In11.Cu")
		(net "M_H_CPU0_SB_DQ<25>")
	)
	(segment
		(start 415.940494 -202.976226)
		(end 415.79546 -202.831192)
		(width 0.18288)
		(layer "In11.Cu")
		(net "M_H_CPU0_SB_DQ<25>")
	)
	(segment
		(start 421.159432 -202.842622)
		(end 420.133018 -202.842622)
		(width 0.18288)
		(layer "In11.Cu")
		(net "M_H_CPU0_SB_DQ<25>")
	)
	(segment
		(start 433.519834 -202.23099)
		(end 433.202334 -202.23099)
		(width 0.18288)
		(layer "In11.Cu")
		(net "M_H_CPU0_SB_DQ<25>")
	)
	(segment
		(start 420.133018 -202.842622)
		(end 419.999414 -202.976226)
		(width 0.18288)
		(layer "In11.Cu")
		(net "M_H_CPU0_SB_DQ<25>")
	)
	(segment
		(start 388.665974 -225.136202)
		(end 388.246366 -225.55581)
		(width 0.088646)
		(layer "In11.Cu")
		(net "M_H_CPU0_SB_DQ<25>")
	)
	(segment
		(start 443.951106 -202.290426)
		(end 443.169294 -202.290426)
		(width 0.18288)
		(layer "In11.Cu")
		(net "M_H_CPU0_SB_DQ<25>")
	)
	(segment
		(start 422.327578 -201.989436)
		(end 422.012618 -201.989436)
		(width 0.18288)
		(layer "In11.Cu")
		(net "M_H_CPU0_SB_DQ<25>")
	)
	(segment
		(start 426.54093 -203.001626)
		(end 426.34789 -202.808586)
		(width 0.18288)
		(layer "In11.Cu")
		(net "M_H_CPU0_SB_DQ<25>")
	)
	(segment
		(start 427.421294 -203.001626)
		(end 426.54093 -203.001626)
		(width 0.18288)
		(layer "In11.Cu")
		(net "M_H_CPU0_SB_DQ<25>")
	)
	(segment
		(start 436.727346 -202.84313)
		(end 435.19979 -202.84313)
		(width 0.18288)
		(layer "In11.Cu")
		(net "M_H_CPU0_SB_DQ<25>")
	)
	(segment
		(start 441.261754 -202.841098)
		(end 439.50382 -202.841098)
		(width 0.18288)
		(layer "In11.Cu")
		(net "M_H_CPU0_SB_DQ<25>")
	)
	(segment
		(start 418.303202 -202.2729)
		(end 418.110162 -202.46594)
		(width 0.18288)
		(layer "In11.Cu")
		(net "M_H_CPU0_SB_DQ<25>")
	)
	(segment
		(start 383.358136 -228.783388)
		(end 383.347722 -228.777292)
		(width 0.088646)
		(layer "In11.Cu")
		(net "M_H_CPU0_SB_DQ<25>")
	)
	(segment
		(start 443.169294 -202.290426)
		(end 442.400944 -203.058776)
		(width 0.18288)
		(layer "In11.Cu")
		(net "M_H_CPU0_SB_DQ<25>")
	)
	(segment
		(start 450.556122 -202.925426)
		(end 447.131694 -202.925426)
		(width 0.18288)
		(layer "In11.Cu")
		(net "M_H_CPU0_SB_DQ<25>")
	)
	(segment
		(start 418.882322 -202.783186)
		(end 418.882322 -202.46594)
		(width 0.18288)
		(layer "In11.Cu")
		(net "M_H_CPU0_SB_DQ<25>")
	)
	(segment
		(start 418.882322 -202.46594)
		(end 418.689282 -202.2729)
		(width 0.18288)
		(layer "In11.Cu")
		(net "M_H_CPU0_SB_DQ<25>")
	)
	(segment
		(start 380.538736 -228.783388)
		(end 380.528322 -228.777292)
		(width 0.088646)
		(layer "In11.Cu")
		(net "M_H_CPU0_SB_DQ<25>")
	)
	(segment
		(start 450.911214 -202.416664)
		(end 450.911214 -202.69835)
		(width 0.18288)
		(layer "In11.Cu")
		(net "M_H_CPU0_SB_DQ<25>")
	)
	(segment
		(start 417.917122 -202.976226)
		(end 415.940494 -202.976226)
		(width 0.18288)
		(layer "In11.Cu")
		(net "M_H_CPU0_SB_DQ<25>")
	)
	(segment
		(start 418.110162 -202.783186)
		(end 417.917122 -202.976226)
		(width 0.18288)
		(layer "In11.Cu")
		(net "M_H_CPU0_SB_DQ<25>")
	)
	(segment
		(start 407.217626 -203.27239)
		(end 406.384506 -203.27239)
		(width 0.18288)
		(layer "In11.Cu")
		(net "M_H_CPU0_SB_DQ<25>")
	)
	(segment
		(start 388.246366 -225.55581)
		(end 387.69798 -225.55581)
		(width 0.088646)
		(layer "In11.Cu")
		(net "M_H_CPU0_SB_DQ<25>")
	)
	(segment
		(start 425.83989 -202.093068)
		(end 425.64685 -202.286108)
		(width 0.18288)
		(layer "In11.Cu")
		(net "M_H_CPU0_SB_DQ<25>")
	)
	(segment
		(start 387.69798 -225.55581)
		(end 387.359398 -225.894392)
		(width 0.088646)
		(layer "In11.Cu")
		(net "M_H_CPU0_SB_DQ<25>")
	)
	(segment
		(start 384.681222 -228.778308)
		(end 384.672332 -228.783388)
		(width 0.088646)
		(layer "In11.Cu")
		(net "M_H_CPU0_SB_DQ<25>")
	)
	(segment
		(start 436.915306 -202.65517)
		(end 436.727346 -202.84313)
		(width 0.18288)
		(layer "In11.Cu")
		(net "M_H_CPU0_SB_DQ<25>")
	)
	(segment
		(start 419.075362 -202.976226)
		(end 418.882322 -202.783186)
		(width 0.18288)
		(layer "In11.Cu")
		(net "M_H_CPU0_SB_DQ<25>")
	)
	(segment
		(start 433.009294 -202.757786)
		(end 432.816254 -202.950826)
		(width 0.18288)
		(layer "In11.Cu")
		(net "M_H_CPU0_SB_DQ<25>")
	)
	(segment
		(start 405.704548 -203.954126)
		(end 404.79853 -204.860144)
		(width 0.18288)
		(layer "In11.Cu")
		(net "M_H_CPU0_SB_DQ<25>")
	)
	(segment
		(start 442.400944 -203.058776)
		(end 441.479432 -203.058776)
		(width 0.18288)
		(layer "In11.Cu")
		(net "M_H_CPU0_SB_DQ<25>")
	)
	(segment
		(start 396.592298 -216.16543)
		(end 389.955532 -222.802196)
		(width 0.18288)
		(layer "In11.Cu")
		(net "M_H_CPU0_SB_DQ<25>")
	)
	(segment
		(start 422.713658 -202.76693)
		(end 422.520618 -202.57389)
		(width 0.18288)
		(layer "In11.Cu")
		(net "M_H_CPU0_SB_DQ<25>")
	)
	(segment
		(start 387.359398 -225.894392)
		(end 387.359398 -226.55022)
		(width 0.088646)
		(layer "In11.Cu")
		(net "M_H_CPU0_SB_DQ<25>")
	)
	(arc
		(start 372.454678 -228.134672)
		(mid 371.82217 -228.057106)
		(end 371.32768 -228.45903)
		(width 0.088646)
		(layer "In11.Cu")
		(net "M_H_CPU0_SB_DQ<25>")
	)
	(arc
		(start 382.792478 -228.783388)
		(mid 382.60528 -228.833531)
		(end 382.418082 -228.783388)
		(width 0.088646)
		(layer "In11.Cu")
		(net "M_H_CPU0_SB_DQ<25>")
	)
	(arc
		(start 381.478536 -228.783388)
		(mid 381.195834 -228.707612)
		(end 380.913132 -228.783388)
		(width 0.088646)
		(layer "In11.Cu")
		(net "M_H_CPU0_SB_DQ<25>")
	)
	(arc
		(start 381.852932 -228.783388)
		(mid 381.665734 -228.833531)
		(end 381.478536 -228.783388)
		(width 0.088646)
		(layer "In11.Cu")
		(net "M_H_CPU0_SB_DQ<25>")
	)
	(arc
		(start 383.732532 -228.783388)
		(mid 383.545334 -228.833531)
		(end 383.358136 -228.783388)
		(width 0.088646)
		(layer "In11.Cu")
		(net "M_H_CPU0_SB_DQ<25>")
	)
	(arc
		(start 386.364734 -227.893626)
		(mid 386.218411 -227.912888)
		(end 386.082032 -227.969318)
		(width 0.088646)
		(layer "In11.Cu")
		(net "M_H_CPU0_SB_DQ<25>")
	)
	(arc
		(start 373.00535 -228.143308)
		(mid 372.728909 -228.210474)
		(end 372.454678 -228.134672)
		(width 0.088646)
		(layer "In11.Cu")
		(net "M_H_CPU0_SB_DQ<25>")
	)
	(arc
		(start 373.624094 -228.401626)
		(mid 373.531976 -228.248637)
		(end 373.394478 -228.134672)
		(width 0.088646)
		(layer "In11.Cu")
		(net "M_H_CPU0_SB_DQ<25>")
	)
	(arc
		(start 379.973078 -228.783388)
		(mid 379.78588 -228.833531)
		(end 379.598682 -228.783388)
		(width 0.088646)
		(layer "In11.Cu")
		(net "M_H_CPU0_SB_DQ<25>")
	)
	(arc
		(start 373.394478 -228.134672)
		(mid 373.20728 -228.084529)
		(end 373.020082 -228.134672)
		(width 0.088646)
		(layer "In11.Cu")
		(net "M_H_CPU0_SB_DQ<25>")
	)
	(arc
		(start 386.082032 -227.969318)
		(mid 385.894834 -228.019461)
		(end 385.707636 -227.969318)
		(width 0.088646)
		(layer "In11.Cu")
		(net "M_H_CPU0_SB_DQ<25>")
	)
	(arc
		(start 374.334532 -228.783388)
		(mid 374.147334 -228.833531)
		(end 373.960136 -228.783388)
		(width 0.088646)
		(layer "In11.Cu")
		(net "M_H_CPU0_SB_DQ<25>")
	)
	(arc
		(start 379.033278 -228.783388)
		(mid 378.84608 -228.833531)
		(end 378.658882 -228.783388)
		(width 0.088646)
		(layer "In11.Cu")
		(net "M_H_CPU0_SB_DQ<25>")
	)
	(arc
		(start 373.951246 -228.778308)
		(mid 373.755718 -228.617728)
		(end 373.624094 -228.401626)
		(width 0.088646)
		(layer "In11.Cu")
		(net "M_H_CPU0_SB_DQ<25>")
	)
	(arc
		(start 380.913132 -228.783388)
		(mid 380.725934 -228.833531)
		(end 380.538736 -228.783388)
		(width 0.088646)
		(layer "In11.Cu")
		(net "M_H_CPU0_SB_DQ<25>")
	)
	(arc
		(start 382.407668 -228.777292)
		(mid 382.12949 -228.707569)
		(end 381.852932 -228.783388)
		(width 0.088646)
		(layer "In11.Cu")
		(net "M_H_CPU0_SB_DQ<25>")
	)
	(arc
		(start 377.719082 -228.783388)
		(mid 377.43638 -228.707612)
		(end 377.153678 -228.783388)
		(width 0.088646)
		(layer "In11.Cu")
		(net "M_H_CPU0_SB_DQ<25>")
	)
	(arc
		(start 375.82475 -228.774752)
		(mid 375.548275 -228.707432)
		(end 375.274078 -228.783388)
		(width 0.088646)
		(layer "In11.Cu")
		(net "M_H_CPU0_SB_DQ<25>")
	)
	(arc
		(start 385.707636 -227.969318)
		(mid 385.424934 -227.893576)
		(end 385.142232 -227.969318)
		(width 0.088646)
		(layer "In11.Cu")
		(net "M_H_CPU0_SB_DQ<25>")
	)
	(arc
		(start 383.347722 -228.777292)
		(mid 383.06929 -228.707446)
		(end 382.792478 -228.783388)
		(width 0.088646)
		(layer "In11.Cu")
		(net "M_H_CPU0_SB_DQ<25>")
	)
	(arc
		(start 385.142232 -227.969318)
		(mid 384.939946 -228.168299)
		(end 384.859784 -228.440488)
		(width 0.088646)
		(layer "In11.Cu")
		(net "M_H_CPU0_SB_DQ<25>")
	)
	(arc
		(start 384.672332 -228.783388)
		(mid 384.485134 -228.833531)
		(end 384.297936 -228.783388)
		(width 0.088646)
		(layer "In11.Cu")
		(net "M_H_CPU0_SB_DQ<25>")
	)
	(arc
		(start 384.297936 -228.783388)
		(mid 384.015234 -228.707612)
		(end 383.732532 -228.783388)
		(width 0.088646)
		(layer "In11.Cu")
		(net "M_H_CPU0_SB_DQ<25>")
	)
	(arc
		(start 375.274078 -228.783388)
		(mid 375.08688 -228.833531)
		(end 374.899682 -228.783388)
		(width 0.088646)
		(layer "In11.Cu")
		(net "M_H_CPU0_SB_DQ<25>")
	)
	(arc
		(start 379.58395 -228.774752)
		(mid 379.307475 -228.707432)
		(end 379.033278 -228.783388)
		(width 0.088646)
		(layer "In11.Cu")
		(net "M_H_CPU0_SB_DQ<25>")
	)
	(arc
		(start 380.528322 -228.777292)
		(mid 380.24989 -228.707446)
		(end 379.973078 -228.783388)
		(width 0.088646)
		(layer "In11.Cu")
		(net "M_H_CPU0_SB_DQ<25>")
	)
	(arc
		(start 378.093478 -228.783388)
		(mid 377.90628 -228.833531)
		(end 377.719082 -228.783388)
		(width 0.088646)
		(layer "In11.Cu")
		(net "M_H_CPU0_SB_DQ<25>")
	)
	(arc
		(start 376.213878 -228.783388)
		(mid 376.02668 -228.833531)
		(end 375.839482 -228.783388)
		(width 0.088646)
		(layer "In11.Cu")
		(net "M_H_CPU0_SB_DQ<25>")
	)
	(arc
		(start 378.64415 -228.774752)
		(mid 378.367675 -228.707432)
		(end 378.093478 -228.783388)
		(width 0.088646)
		(layer "In11.Cu")
		(net "M_H_CPU0_SB_DQ<25>")
	)
	(arc
		(start 384.859784 -228.45903)
		(mid 384.812105 -228.64193)
		(end 384.681222 -228.778308)
		(width 0.088646)
		(layer "In11.Cu")
		(net "M_H_CPU0_SB_DQ<25>")
	)
	(arc
		(start 376.76455 -228.774752)
		(mid 376.488075 -228.707432)
		(end 376.213878 -228.783388)
		(width 0.088646)
		(layer "In11.Cu")
		(net "M_H_CPU0_SB_DQ<25>")
	)
	(arc
		(start 377.153678 -228.783388)
		(mid 376.96648 -228.833531)
		(end 376.779282 -228.783388)
		(width 0.088646)
		(layer "In11.Cu")
		(net "M_H_CPU0_SB_DQ<25>")
	)
	(arc
		(start 374.889268 -228.777292)
		(mid 374.61109 -228.707569)
		(end 374.334532 -228.783388)
		(width 0.088646)
		(layer "In11.Cu")
		(net "M_H_CPU0_SB_DQ<25>")
	)
	(segment
		(start 459.55966 -204.11694)
		(end 457.968096 -204.11694)
		(width 0.20066)
		(layer "F.Cu")
		(net "M_H_CPU0_SB_DQ<24>")
	)
	(segment
		(start 454.91146 -203.691744)
		(end 454.566782 -203.691744)
		(width 0.20066)
		(layer "F.Cu")
		(net "M_H_CPU0_SB_DQ<24>")
	)
	(segment
		(start 454.260712 -204.365352)
		(end 453.785478 -204.365352)
		(width 0.20066)
		(layer "F.Cu")
		(net "M_H_CPU0_SB_DQ<24>")
	)
	(segment
		(start 454.566782 -203.691744)
		(end 454.448672 -203.809854)
		(width 0.20066)
		(layer "F.Cu")
		(net "M_H_CPU0_SB_DQ<24>")
	)
	(segment
		(start 459.559914 -204.116686)
		(end 459.55966 -204.11694)
		(width 0.20066)
		(layer "F.Cu")
		(net "M_H_CPU0_SB_DQ<24>")
	)
	(segment
		(start 371.79758 -229.2731)
		(end 371.797834 -229.272846)
		(width 0.20066)
		(layer "F.Cu")
		(net "M_H_CPU0_SB_DQ<24>")
	)
	(segment
		(start 371.79758 -229.808786)
		(end 371.79758 -229.2731)
		(width 0.20066)
		(layer "F.Cu")
		(net "M_H_CPU0_SB_DQ<24>")
	)
	(segment
		(start 457.120244 -203.691744)
		(end 454.95845 -203.691744)
		(width 0.1016)
		(layer "F.Cu")
		(net "M_H_CPU0_SB_DQ<24>")
	)
	(segment
		(start 457.968096 -204.11694)
		(end 457.53655 -203.685394)
		(width 0.20066)
		(layer "F.Cu")
		(net "M_H_CPU0_SB_DQ<24>")
	)
	(segment
		(start 454.448672 -204.177392)
		(end 454.260712 -204.365352)
		(width 0.20066)
		(layer "F.Cu")
		(net "M_H_CPU0_SB_DQ<24>")
	)
	(segment
		(start 454.95845 -203.691744)
		(end 454.91146 -203.691744)
		(width 0.101854)
		(layer "F.Cu")
		(net "M_H_CPU0_SB_DQ<24>")
	)
	(segment
		(start 453.785478 -204.365352)
		(end 453.536812 -204.116686)
		(width 0.20066)
		(layer "F.Cu")
		(net "M_H_CPU0_SB_DQ<24>")
	)
	(segment
		(start 457.53655 -203.685394)
		(end 457.126594 -203.685394)
		(width 0.20066)
		(layer "F.Cu")
		(net "M_H_CPU0_SB_DQ<24>")
	)
	(segment
		(start 452.016114 -204.116686)
		(end 450.911214 -204.116686)
		(width 0.20066)
		(layer "F.Cu")
		(net "M_H_CPU0_SB_DQ<24>")
	)
	(segment
		(start 453.536812 -204.116686)
		(end 452.016114 -204.116686)
		(width 0.20066)
		(layer "F.Cu")
		(net "M_H_CPU0_SB_DQ<24>")
	)
	(segment
		(start 454.448672 -203.809854)
		(end 454.448672 -204.177392)
		(width 0.20066)
		(layer "F.Cu")
		(net "M_H_CPU0_SB_DQ<24>")
	)
	(segment
		(start 457.126594 -203.685394)
		(end 457.120244 -203.691744)
		(width 0.1016)
		(layer "F.Cu")
		(net "M_H_CPU0_SB_DQ<24>")
	)
	(segment
		(start 377.633992 -229.591108)
		(end 377.623578 -229.597204)
		(width 0.088646)
		(layer "In11.Cu")
		(net "M_H_CPU0_SB_DQ<24>")
	)
	(segment
		(start 387.533388 -227.635562)
		(end 386.946648 -228.222302)
		(width 0.088646)
		(layer "In11.Cu")
		(net "M_H_CPU0_SB_DQ<24>")
	)
	(segment
		(start 387.753606 -226.819206)
		(end 387.533388 -227.039424)
		(width 0.088646)
		(layer "In11.Cu")
		(net "M_H_CPU0_SB_DQ<24>")
	)
	(segment
		(start 386.946648 -228.407722)
		(end 386.62991 -228.724206)
		(width 0.088646)
		(layer "In11.Cu")
		(net "M_H_CPU0_SB_DQ<24>")
	)
	(segment
		(start 373.879364 -229.588568)
		(end 373.864632 -229.597204)
		(width 0.088646)
		(layer "In11.Cu")
		(net "M_H_CPU0_SB_DQ<24>")
	)
	(segment
		(start 421.719502 -204.890116)
		(end 421.719502 -204.575664)
		(width 0.18288)
		(layer "In11.Cu")
		(net "M_H_CPU0_SB_DQ<24>")
	)
	(segment
		(start 425.216574 -204.541882)
		(end 423.55135 -204.541882)
		(width 0.18288)
		(layer "In11.Cu")
		(net "M_H_CPU0_SB_DQ<24>")
	)
	(segment
		(start 417.90874 -204.861414)
		(end 416.809682 -204.861414)
		(width 0.18288)
		(layer "In11.Cu")
		(net "M_H_CPU0_SB_DQ<24>")
	)
	(segment
		(start 425.843192 -204.34681)
		(end 425.843192 -204.508354)
		(width 0.18288)
		(layer "In11.Cu")
		(net "M_H_CPU0_SB_DQ<24>")
	)
	(segment
		(start 414.02381 -204.591666)
		(end 413.83077 -204.398626)
		(width 0.18288)
		(layer "In11.Cu")
		(net "M_H_CPU0_SB_DQ<24>")
	)
	(segment
		(start 414.92043 -204.398626)
		(end 414.72739 -204.591666)
		(width 0.18288)
		(layer "In11.Cu")
		(net "M_H_CPU0_SB_DQ<24>")
	)
	(segment
		(start 414.21685 -205.071726)
		(end 414.02381 -204.878686)
		(width 0.18288)
		(layer "In11.Cu")
		(net "M_H_CPU0_SB_DQ<24>")
	)
	(segment
		(start 408.383994 -204.398626)
		(end 407.68397 -204.398626)
		(width 0.18288)
		(layer "In11.Cu")
		(net "M_H_CPU0_SB_DQ<24>")
	)
	(segment
		(start 414.72739 -204.878686)
		(end 414.53435 -205.071726)
		(width 0.18288)
		(layer "In11.Cu")
		(net "M_H_CPU0_SB_DQ<24>")
	)
	(segment
		(start 441.903104 -204.813154)
		(end 441.710064 -204.620114)
		(width 0.18288)
		(layer "In11.Cu")
		(net "M_H_CPU0_SB_DQ<24>")
	)
	(segment
		(start 428.43069 -204.474826)
		(end 427.802294 -204.474826)
		(width 0.18288)
		(layer "In11.Cu")
		(net "M_H_CPU0_SB_DQ<24>")
	)
	(segment
		(start 414.53435 -205.071726)
		(end 414.21685 -205.071726)
		(width 0.18288)
		(layer "In11.Cu")
		(net "M_H_CPU0_SB_DQ<24>")
	)
	(segment
		(start 427.575726 -204.701394)
		(end 426.808392 -204.701394)
		(width 0.18288)
		(layer "In11.Cu")
		(net "M_H_CPU0_SB_DQ<24>")
	)
	(segment
		(start 440.815984 -204.813154)
		(end 440.385454 -204.813154)
		(width 0.18288)
		(layer "In11.Cu")
		(net "M_H_CPU0_SB_DQ<24>")
	)
	(segment
		(start 425.650152 -204.701394)
		(end 425.376086 -204.701394)
		(width 0.18288)
		(layer "In11.Cu")
		(net "M_H_CPU0_SB_DQ<24>")
	)
	(segment
		(start 386.946648 -228.222302)
		(end 386.946648 -228.407722)
		(width 0.088646)
		(layer "In11.Cu")
		(net "M_H_CPU0_SB_DQ<24>")
	)
	(segment
		(start 410.417772 -204.703426)
		(end 408.688794 -204.703426)
		(width 0.18288)
		(layer "In11.Cu")
		(net "M_H_CPU0_SB_DQ<24>")
	)
	(segment
		(start 442.914532 -204.398626)
		(end 442.500004 -204.813154)
		(width 0.18288)
		(layer "In11.Cu")
		(net "M_H_CPU0_SB_DQ<24>")
	)
	(segment
		(start 445.017906 -204.398626)
		(end 444.824866 -204.591666)
		(width 0.18288)
		(layer "In11.Cu")
		(net "M_H_CPU0_SB_DQ<24>")
	)
	(segment
		(start 418.10178 -204.668374)
		(end 417.90874 -204.861414)
		(width 0.18288)
		(layer "In11.Cu")
		(net "M_H_CPU0_SB_DQ<24>")
	)
	(segment
		(start 441.009024 -204.620114)
		(end 440.815984 -204.813154)
		(width 0.18288)
		(layer "In11.Cu")
		(net "M_H_CPU0_SB_DQ<24>")
	)
	(segment
		(start 406.517094 -205.944724)
		(end 406.310338 -205.737968)
		(width 0.18288)
		(layer "In11.Cu")
		(net "M_H_CPU0_SB_DQ<24>")
	)
	(segment
		(start 418.80536 -204.216762)
		(end 418.61232 -204.023722)
		(width 0.18288)
		(layer "In11.Cu")
		(net "M_H_CPU0_SB_DQ<24>")
	)
	(segment
		(start 434.812694 -204.703426)
		(end 431.205386 -204.703426)
		(width 0.18288)
		(layer "In11.Cu")
		(net "M_H_CPU0_SB_DQ<24>")
	)
	(segment
		(start 440.113166 -204.540866)
		(end 439.171334 -204.540866)
		(width 0.18288)
		(layer "In11.Cu")
		(net "M_H_CPU0_SB_DQ<24>")
	)
	(segment
		(start 435.979316 -204.54239)
		(end 435.915054 -204.542136)
		(width 0.18288)
		(layer "In11.Cu")
		(net "M_H_CPU0_SB_DQ<24>")
	)
	(segment
		(start 450.820536 -204.526388)
		(end 450.33184 -204.728826)
		(width 0.18288)
		(layer "In11.Cu")
		(net "M_H_CPU0_SB_DQ<24>")
	)
	(segment
		(start 439.02884 -204.398372)
		(end 438.022238 -204.398372)
		(width 0.18288)
		(layer "In11.Cu")
		(net "M_H_CPU0_SB_DQ<24>")
	)
	(segment
		(start 429.850042 -204.474826)
		(end 429.420274 -204.904594)
		(width 0.18288)
		(layer "In11.Cu")
		(net "M_H_CPU0_SB_DQ<24>")
	)
	(segment
		(start 388.43331 -226.819206)
		(end 388.10311 -226.819206)
		(width 0.18288)
		(layer "In11.Cu")
		(net "M_H_CPU0_SB_DQ<24>")
	)
	(segment
		(start 422.230042 -205.083156)
		(end 421.912542 -205.083156)
		(width 0.18288)
		(layer "In11.Cu")
		(net "M_H_CPU0_SB_DQ<24>")
	)
	(segment
		(start 444.121286 -204.99578)
		(end 444.121286 -204.591666)
		(width 0.18288)
		(layer "In11.Cu")
		(net "M_H_CPU0_SB_DQ<24>")
	)
	(segment
		(start 441.710064 -204.300582)
		(end 441.517024 -204.107542)
		(width 0.18288)
		(layer "In11.Cu")
		(net "M_H_CPU0_SB_DQ<24>")
	)
	(segment
		(start 416.346894 -204.398626)
		(end 414.92043 -204.398626)
		(width 0.18288)
		(layer "In11.Cu")
		(net "M_H_CPU0_SB_DQ<24>")
	)
	(segment
		(start 439.171334 -204.540866)
		(end 439.02884 -204.398372)
		(width 0.18288)
		(layer "In11.Cu")
		(net "M_H_CPU0_SB_DQ<24>")
	)
	(segment
		(start 426.615352 -204.508354)
		(end 426.615352 -204.34681)
		(width 0.18288)
		(layer "In11.Cu")
		(net "M_H_CPU0_SB_DQ<24>")
	)
	(segment
		(start 421.719502 -204.575664)
		(end 421.526462 -204.382624)
		(width 0.18288)
		(layer "In11.Cu")
		(net "M_H_CPU0_SB_DQ<24>")
	)
	(segment
		(start 418.10178 -204.216762)
		(end 418.10178 -204.668374)
		(width 0.18288)
		(layer "In11.Cu")
		(net "M_H_CPU0_SB_DQ<24>")
	)
	(segment
		(start 387.533388 -227.039424)
		(end 387.533388 -227.635562)
		(width 0.088646)
		(layer "In11.Cu")
		(net "M_H_CPU0_SB_DQ<24>")
	)
	(segment
		(start 405.444198 -207.290416)
		(end 404.542752 -207.290416)
		(width 0.18288)
		(layer "In11.Cu")
		(net "M_H_CPU0_SB_DQ<24>")
	)
	(segment
		(start 406.78989 -205.944724)
		(end 406.517094 -205.944724)
		(width 0.18288)
		(layer "In11.Cu")
		(net "M_H_CPU0_SB_DQ<24>")
	)
	(segment
		(start 405.812752 -206.235554)
		(end 406.019508 -206.44231)
		(width 0.18288)
		(layer "In11.Cu")
		(net "M_H_CPU0_SB_DQ<24>")
	)
	(segment
		(start 397.846804 -213.986364)
		(end 397.846804 -216.398348)
		(width 0.18288)
		(layer "In11.Cu")
		(net "M_H_CPU0_SB_DQ<24>")
	)
	(segment
		(start 440.385454 -204.813154)
		(end 440.113166 -204.540866)
		(width 0.18288)
		(layer "In11.Cu")
		(net "M_H_CPU0_SB_DQ<24>")
	)
	(segment
		(start 421.120824 -204.382624)
		(end 420.962582 -204.540866)
		(width 0.18288)
		(layer "In11.Cu")
		(net "M_H_CPU0_SB_DQ<24>")
	)
	(segment
		(start 406.019508 -206.44231)
		(end 406.019508 -206.715106)
		(width 0.18288)
		(layer "In11.Cu")
		(net "M_H_CPU0_SB_DQ<24>")
	)
	(segment
		(start 444.824866 -204.591666)
		(end 444.824866 -204.99578)
		(width 0.18288)
		(layer "In11.Cu")
		(net "M_H_CPU0_SB_DQ<24>")
	)
	(segment
		(start 437.87822 -204.54239)
		(end 435.979316 -204.54239)
		(width 0.18288)
		(layer "In11.Cu")
		(net "M_H_CPU0_SB_DQ<24>")
	)
	(segment
		(start 391.028428 -223.216724)
		(end 391.028428 -224.224088)
		(width 0.18288)
		(layer "In11.Cu")
		(net "M_H_CPU0_SB_DQ<24>")
	)
	(segment
		(start 428.860458 -204.904594)
		(end 428.43069 -204.474826)
		(width 0.18288)
		(layer "In11.Cu")
		(net "M_H_CPU0_SB_DQ<24>")
	)
	(segment
		(start 373.011192 -228.833426)
		(end 372.557294 -228.833426)
		(width 0.088646)
		(layer "In11.Cu")
		(net "M_H_CPU0_SB_DQ<24>")
	)
	(segment
		(start 413.83077 -204.398626)
		(end 412.689294 -204.398626)
		(width 0.18288)
		(layer "In11.Cu")
		(net "M_H_CPU0_SB_DQ<24>")
	)
	(segment
		(start 435.69636 -204.541628)
		(end 434.974492 -204.541628)
		(width 0.18288)
		(layer "In11.Cu")
		(net "M_H_CPU0_SB_DQ<24>")
	)
	(segment
		(start 426.036232 -204.15377)
		(end 425.843192 -204.34681)
		(width 0.18288)
		(layer "In11.Cu")
		(net "M_H_CPU0_SB_DQ<24>")
	)
	(segment
		(start 438.022238 -204.398372)
		(end 437.87822 -204.54239)
		(width 0.18288)
		(layer "In11.Cu")
		(net "M_H_CPU0_SB_DQ<24>")
	)
	(segment
		(start 418.9984 -204.861414)
		(end 418.80536 -204.668374)
		(width 0.18288)
		(layer "In11.Cu")
		(net "M_H_CPU0_SB_DQ<24>")
	)
	(segment
		(start 423.392092 -204.382624)
		(end 422.616122 -204.382624)
		(width 0.18288)
		(layer "In11.Cu")
		(net "M_H_CPU0_SB_DQ<24>")
	)
	(segment
		(start 426.615352 -204.34681)
		(end 426.422312 -204.15377)
		(width 0.18288)
		(layer "In11.Cu")
		(net "M_H_CPU0_SB_DQ<24>")
	)
	(segment
		(start 420.192454 -204.540866)
		(end 419.871906 -204.861414)
		(width 0.18288)
		(layer "In11.Cu")
		(net "M_H_CPU0_SB_DQ<24>")
	)
	(segment
		(start 406.019508 -206.715106)
		(end 405.444198 -207.290416)
		(width 0.18288)
		(layer "In11.Cu")
		(net "M_H_CPU0_SB_DQ<24>")
	)
	(segment
		(start 441.517024 -204.107542)
		(end 441.202064 -204.107542)
		(width 0.18288)
		(layer "In11.Cu")
		(net "M_H_CPU0_SB_DQ<24>")
	)
	(segment
		(start 418.61232 -204.023722)
		(end 418.29482 -204.023722)
		(width 0.18288)
		(layer "In11.Cu")
		(net "M_H_CPU0_SB_DQ<24>")
	)
	(segment
		(start 372.01094 -229.05974)
		(end 371.797834 -229.272846)
		(width 0.088646)
		(layer "In11.Cu")
		(net "M_H_CPU0_SB_DQ<24>")
	)
	(segment
		(start 426.808392 -204.701394)
		(end 426.615352 -204.508354)
		(width 0.18288)
		(layer "In11.Cu")
		(net "M_H_CPU0_SB_DQ<24>")
	)
	(segment
		(start 380.457964 -229.588568)
		(end 380.443232 -229.597204)
		(width 0.088646)
		(layer "In11.Cu")
		(net "M_H_CPU0_SB_DQ<24>")
	)
	(segment
		(start 407.189686 -204.89291)
		(end 407.189686 -205.544928)
		(width 0.18288)
		(layer "In11.Cu")
		(net "M_H_CPU0_SB_DQ<24>")
	)
	(segment
		(start 406.310338 -205.737968)
		(end 406.037542 -205.737968)
		(width 0.18288)
		(layer "In11.Cu")
		(net "M_H_CPU0_SB_DQ<24>")
	)
	(segment
		(start 376.694446 -229.591108)
		(end 376.684032 -229.597204)
		(width 0.088646)
		(layer "In11.Cu")
		(net "M_H_CPU0_SB_DQ<24>")
	)
	(segment
		(start 404.542752 -207.290416)
		(end 397.846804 -213.986364)
		(width 0.18288)
		(layer "In11.Cu")
		(net "M_H_CPU0_SB_DQ<24>")
	)
	(segment
		(start 385.329684 -229.26294)
		(end 385.329684 -229.272846)
		(width 0.088646)
		(layer "In11.Cu")
		(net "M_H_CPU0_SB_DQ<24>")
	)
	(segment
		(start 427.802294 -204.474826)
		(end 427.575726 -204.701394)
		(width 0.18288)
		(layer "In11.Cu")
		(net "M_H_CPU0_SB_DQ<24>")
	)
	(segment
		(start 425.843192 -204.508354)
		(end 425.650152 -204.701394)
		(width 0.18288)
		(layer "In11.Cu")
		(net "M_H_CPU0_SB_DQ<24>")
	)
	(segment
		(start 429.420274 -204.904594)
		(end 428.860458 -204.904594)
		(width 0.18288)
		(layer "In11.Cu")
		(net "M_H_CPU0_SB_DQ<24>")
	)
	(segment
		(start 444.121286 -204.591666)
		(end 443.928246 -204.398626)
		(width 0.18288)
		(layer "In11.Cu")
		(net "M_H_CPU0_SB_DQ<24>")
	)
	(segment
		(start 444.824866 -204.99578)
		(end 444.631826 -205.18882)
		(width 0.18288)
		(layer "In11.Cu")
		(net "M_H_CPU0_SB_DQ<24>")
	)
	(segment
		(start 446.749932 -204.728826)
		(end 446.419732 -204.398626)
		(width 0.18288)
		(layer "In11.Cu")
		(net "M_H_CPU0_SB_DQ<24>")
	)
	(segment
		(start 411.395672 -204.347826)
		(end 410.773372 -204.347826)
		(width 0.18288)
		(layer "In11.Cu")
		(net "M_H_CPU0_SB_DQ<24>")
	)
	(segment
		(start 430.976786 -204.474826)
		(end 429.850042 -204.474826)
		(width 0.18288)
		(layer "In11.Cu")
		(net "M_H_CPU0_SB_DQ<24>")
	)
	(segment
		(start 426.422312 -204.15377)
		(end 426.036232 -204.15377)
		(width 0.18288)
		(layer "In11.Cu")
		(net "M_H_CPU0_SB_DQ<24>")
	)
	(segment
		(start 441.009024 -204.300582)
		(end 441.009024 -204.620114)
		(width 0.18288)
		(layer "In11.Cu")
		(net "M_H_CPU0_SB_DQ<24>")
	)
	(segment
		(start 416.809682 -204.861414)
		(end 416.346894 -204.398626)
		(width 0.18288)
		(layer "In11.Cu")
		(net "M_H_CPU0_SB_DQ<24>")
	)
	(segment
		(start 378.578364 -229.588568)
		(end 378.563632 -229.597204)
		(width 0.088646)
		(layer "In11.Cu")
		(net "M_H_CPU0_SB_DQ<24>")
	)
	(segment
		(start 446.419732 -204.398626)
		(end 445.017906 -204.398626)
		(width 0.18288)
		(layer "In11.Cu")
		(net "M_H_CPU0_SB_DQ<24>")
	)
	(segment
		(start 412.384494 -204.703426)
		(end 411.751272 -204.703426)
		(width 0.18288)
		(layer "In11.Cu")
		(net "M_H_CPU0_SB_DQ<24>")
	)
	(segment
		(start 414.02381 -204.878686)
		(end 414.02381 -204.591666)
		(width 0.18288)
		(layer "In11.Cu")
		(net "M_H_CPU0_SB_DQ<24>")
	)
	(segment
		(start 444.631826 -205.18882)
		(end 444.314326 -205.18882)
		(width 0.18288)
		(layer "In11.Cu")
		(net "M_H_CPU0_SB_DQ<24>")
	)
	(segment
		(start 412.689294 -204.398626)
		(end 412.384494 -204.703426)
		(width 0.18288)
		(layer "In11.Cu")
		(net "M_H_CPU0_SB_DQ<24>")
	)
	(segment
		(start 441.710064 -204.620114)
		(end 441.710064 -204.300582)
		(width 0.18288)
		(layer "In11.Cu")
		(net "M_H_CPU0_SB_DQ<24>")
	)
	(segment
		(start 373.30253 -229.272846)
		(end 373.30253 -229.124764)
		(width 0.088646)
		(layer "In11.Cu")
		(net "M_H_CPU0_SB_DQ<24>")
	)
	(segment
		(start 418.80536 -204.668374)
		(end 418.80536 -204.216762)
		(width 0.18288)
		(layer "In11.Cu")
		(net "M_H_CPU0_SB_DQ<24>")
	)
	(segment
		(start 422.616122 -204.382624)
		(end 422.423082 -204.575664)
		(width 0.18288)
		(layer "In11.Cu")
		(net "M_H_CPU0_SB_DQ<24>")
	)
	(segment
		(start 425.376086 -204.701394)
		(end 425.216574 -204.541882)
		(width 0.18288)
		(layer "In11.Cu")
		(net "M_H_CPU0_SB_DQ<24>")
	)
	(segment
		(start 423.55135 -204.541882)
		(end 423.392092 -204.382624)
		(width 0.18288)
		(layer "In11.Cu")
		(net "M_H_CPU0_SB_DQ<24>")
	)
	(segment
		(start 422.423082 -204.890116)
		(end 422.230042 -205.083156)
		(width 0.18288)
		(layer "In11.Cu")
		(net "M_H_CPU0_SB_DQ<24>")
	)
	(segment
		(start 442.500004 -204.813154)
		(end 441.903104 -204.813154)
		(width 0.18288)
		(layer "In11.Cu")
		(net "M_H_CPU0_SB_DQ<24>")
	)
	(segment
		(start 419.871906 -204.861414)
		(end 418.9984 -204.861414)
		(width 0.18288)
		(layer "In11.Cu")
		(net "M_H_CPU0_SB_DQ<24>")
	)
	(segment
		(start 422.423082 -204.575664)
		(end 422.423082 -204.890116)
		(width 0.18288)
		(layer "In11.Cu")
		(net "M_H_CPU0_SB_DQ<24>")
	)
	(segment
		(start 405.812752 -205.962758)
		(end 405.812752 -206.235554)
		(width 0.18288)
		(layer "In11.Cu")
		(net "M_H_CPU0_SB_DQ<24>")
	)
	(segment
		(start 414.72739 -204.591666)
		(end 414.72739 -204.878686)
		(width 0.18288)
		(layer "In11.Cu")
		(net "M_H_CPU0_SB_DQ<24>")
	)
	(segment
		(start 408.688794 -204.703426)
		(end 408.383994 -204.398626)
		(width 0.18288)
		(layer "In11.Cu")
		(net "M_H_CPU0_SB_DQ<24>")
	)
	(segment
		(start 374.819164 -229.588568)
		(end 374.804432 -229.597204)
		(width 0.088646)
		(layer "In11.Cu")
		(net "M_H_CPU0_SB_DQ<24>")
	)
	(segment
		(start 407.189686 -205.544928)
		(end 406.78989 -205.944724)
		(width 0.18288)
		(layer "In11.Cu")
		(net "M_H_CPU0_SB_DQ<24>")
	)
	(segment
		(start 388.10311 -226.819206)
		(end 387.753606 -226.819206)
		(width 0.088646)
		(layer "In11.Cu")
		(net "M_H_CPU0_SB_DQ<24>")
	)
	(segment
		(start 375.758964 -229.588568)
		(end 375.744232 -229.597204)
		(width 0.088646)
		(layer "In11.Cu")
		(net "M_H_CPU0_SB_DQ<24>")
	)
	(segment
		(start 434.974492 -204.541628)
		(end 434.812694 -204.703426)
		(width 0.18288)
		(layer "In11.Cu")
		(net "M_H_CPU0_SB_DQ<24>")
	)
	(segment
		(start 441.202064 -204.107542)
		(end 441.009024 -204.300582)
		(width 0.18288)
		(layer "In11.Cu")
		(net "M_H_CPU0_SB_DQ<24>")
	)
	(segment
		(start 421.526462 -204.382624)
		(end 421.120824 -204.382624)
		(width 0.18288)
		(layer "In11.Cu")
		(net "M_H_CPU0_SB_DQ<24>")
	)
	(segment
		(start 431.205386 -204.703426)
		(end 430.976786 -204.474826)
		(width 0.18288)
		(layer "In11.Cu")
		(net "M_H_CPU0_SB_DQ<24>")
	)
	(segment
		(start 443.928246 -204.398626)
		(end 442.914532 -204.398626)
		(width 0.18288)
		(layer "In11.Cu")
		(net "M_H_CPU0_SB_DQ<24>")
	)
	(segment
		(start 421.912542 -205.083156)
		(end 421.719502 -204.890116)
		(width 0.18288)
		(layer "In11.Cu")
		(net "M_H_CPU0_SB_DQ<24>")
	)
	(segment
		(start 420.962582 -204.540866)
		(end 420.192454 -204.540866)
		(width 0.18288)
		(layer "In11.Cu")
		(net "M_H_CPU0_SB_DQ<24>")
	)
	(segment
		(start 450.911214 -204.43571)
		(end 450.820536 -204.526388)
		(width 0.18288)
		(layer "In11.Cu")
		(net "M_H_CPU0_SB_DQ<24>")
	)
	(segment
		(start 397.846804 -216.398348)
		(end 391.028428 -223.216724)
		(width 0.18288)
		(layer "In11.Cu")
		(net "M_H_CPU0_SB_DQ<24>")
	)
	(segment
		(start 385.151122 -229.592124)
		(end 385.142232 -229.597204)
		(width 0.088646)
		(layer "In11.Cu")
		(net "M_H_CPU0_SB_DQ<24>")
	)
	(segment
		(start 450.911214 -204.116686)
		(end 450.911214 -204.43571)
		(width 0.18288)
		(layer "In11.Cu")
		(net "M_H_CPU0_SB_DQ<24>")
	)
	(segment
		(start 410.773372 -204.347826)
		(end 410.417772 -204.703426)
		(width 0.18288)
		(layer "In11.Cu")
		(net "M_H_CPU0_SB_DQ<24>")
	)
	(segment
		(start 418.29482 -204.023722)
		(end 418.10178 -204.216762)
		(width 0.18288)
		(layer "In11.Cu")
		(net "M_H_CPU0_SB_DQ<24>")
	)
	(segment
		(start 411.751272 -204.703426)
		(end 411.395672 -204.347826)
		(width 0.18288)
		(layer "In11.Cu")
		(net "M_H_CPU0_SB_DQ<24>")
	)
	(segment
		(start 450.33184 -204.728826)
		(end 446.749932 -204.728826)
		(width 0.18288)
		(layer "In11.Cu")
		(net "M_H_CPU0_SB_DQ<24>")
	)
	(segment
		(start 444.314326 -205.18882)
		(end 444.121286 -204.99578)
		(width 0.18288)
		(layer "In11.Cu")
		(net "M_H_CPU0_SB_DQ<24>")
	)
	(segment
		(start 435.915054 -204.542136)
		(end 435.69636 -204.541628)
		(width 0.18288)
		(layer "In11.Cu")
		(net "M_H_CPU0_SB_DQ<24>")
	)
	(segment
		(start 391.028428 -224.224088)
		(end 388.43331 -226.819206)
		(width 0.18288)
		(layer "In11.Cu")
		(net "M_H_CPU0_SB_DQ<24>")
	)
	(segment
		(start 407.68397 -204.398626)
		(end 407.189686 -204.89291)
		(width 0.18288)
		(layer "In11.Cu")
		(net "M_H_CPU0_SB_DQ<24>")
	)
	(segment
		(start 406.037542 -205.737968)
		(end 405.812752 -205.962758)
		(width 0.18288)
		(layer "In11.Cu")
		(net "M_H_CPU0_SB_DQ<24>")
	)
	(arc
		(start 377.623578 -229.597204)
		(mid 377.43638 -229.647347)
		(end 377.249182 -229.597204)
		(width 0.088646)
		(layer "In11.Cu")
		(net "M_H_CPU0_SB_DQ<24>")
	)
	(arc
		(start 377.249182 -229.597204)
		(mid 376.972623 -229.521461)
		(end 376.694446 -229.591108)
		(width 0.088646)
		(layer "In11.Cu")
		(net "M_H_CPU0_SB_DQ<24>")
	)
	(arc
		(start 380.068836 -229.597204)
		(mid 379.786134 -229.521428)
		(end 379.503432 -229.597204)
		(width 0.088646)
		(layer "In11.Cu")
		(net "M_H_CPU0_SB_DQ<24>")
	)
	(arc
		(start 373.864632 -229.597204)
		(mid 373.677434 -229.647347)
		(end 373.490236 -229.597204)
		(width 0.088646)
		(layer "In11.Cu")
		(net "M_H_CPU0_SB_DQ<24>")
	)
	(arc
		(start 383.828036 -229.597204)
		(mid 383.545334 -229.521428)
		(end 383.262632 -229.597204)
		(width 0.088646)
		(layer "In11.Cu")
		(net "M_H_CPU0_SB_DQ<24>")
	)
	(arc
		(start 375.369836 -229.597204)
		(mid 375.095637 -229.521369)
		(end 374.819164 -229.588568)
		(width 0.088646)
		(layer "In11.Cu")
		(net "M_H_CPU0_SB_DQ<24>")
	)
	(arc
		(start 379.129036 -229.597204)
		(mid 378.854837 -229.521369)
		(end 378.578364 -229.588568)
		(width 0.088646)
		(layer "In11.Cu")
		(net "M_H_CPU0_SB_DQ<24>")
	)
	(arc
		(start 372.557294 -228.833426)
		(mid 372.261607 -228.892242)
		(end 372.01094 -229.05974)
		(width 0.088646)
		(layer "In11.Cu")
		(net "M_H_CPU0_SB_DQ<24>")
	)
	(arc
		(start 381.383032 -229.597204)
		(mid 381.195834 -229.647347)
		(end 381.008636 -229.597204)
		(width 0.088646)
		(layer "In11.Cu")
		(net "M_H_CPU0_SB_DQ<24>")
	)
	(arc
		(start 373.30253 -229.124764)
		(mid 373.217199 -228.918757)
		(end 373.011192 -228.833426)
		(width 0.088646)
		(layer "In11.Cu")
		(net "M_H_CPU0_SB_DQ<24>")
	)
	(arc
		(start 385.612132 -228.783388)
		(mid 385.407797 -228.985993)
		(end 385.329684 -229.26294)
		(width 0.088646)
		(layer "In11.Cu")
		(net "M_H_CPU0_SB_DQ<24>")
	)
	(arc
		(start 383.262632 -229.597204)
		(mid 383.075434 -229.647347)
		(end 382.888236 -229.597204)
		(width 0.088646)
		(layer "In11.Cu")
		(net "M_H_CPU0_SB_DQ<24>")
	)
	(arc
		(start 375.744232 -229.597204)
		(mid 375.557034 -229.647347)
		(end 375.369836 -229.597204)
		(width 0.088646)
		(layer "In11.Cu")
		(net "M_H_CPU0_SB_DQ<24>")
	)
	(arc
		(start 380.443232 -229.597204)
		(mid 380.256034 -229.647347)
		(end 380.068836 -229.597204)
		(width 0.088646)
		(layer "In11.Cu")
		(net "M_H_CPU0_SB_DQ<24>")
	)
	(arc
		(start 386.177536 -228.783388)
		(mid 385.894834 -228.707612)
		(end 385.612132 -228.783388)
		(width 0.088646)
		(layer "In11.Cu")
		(net "M_H_CPU0_SB_DQ<24>")
	)
	(arc
		(start 381.948436 -229.597204)
		(mid 381.665734 -229.521428)
		(end 381.383032 -229.597204)
		(width 0.088646)
		(layer "In11.Cu")
		(net "M_H_CPU0_SB_DQ<24>")
	)
	(arc
		(start 373.490236 -229.597204)
		(mid 373.353014 -229.460122)
		(end 373.30253 -229.272846)
		(width 0.088646)
		(layer "In11.Cu")
		(net "M_H_CPU0_SB_DQ<24>")
	)
	(arc
		(start 385.329684 -229.272846)
		(mid 385.282005 -229.455746)
		(end 385.151122 -229.592124)
		(width 0.088646)
		(layer "In11.Cu")
		(net "M_H_CPU0_SB_DQ<24>")
	)
	(arc
		(start 382.888236 -229.597204)
		(mid 382.605534 -229.521428)
		(end 382.322832 -229.597204)
		(width 0.088646)
		(layer "In11.Cu")
		(net "M_H_CPU0_SB_DQ<24>")
	)
	(arc
		(start 378.189236 -229.597204)
		(mid 377.912423 -229.521334)
		(end 377.633992 -229.591108)
		(width 0.088646)
		(layer "In11.Cu")
		(net "M_H_CPU0_SB_DQ<24>")
	)
	(arc
		(start 381.008636 -229.597204)
		(mid 380.734437 -229.521369)
		(end 380.457964 -229.588568)
		(width 0.088646)
		(layer "In11.Cu")
		(net "M_H_CPU0_SB_DQ<24>")
	)
	(arc
		(start 386.551932 -228.783388)
		(mid 386.364734 -228.833531)
		(end 386.177536 -228.783388)
		(width 0.088646)
		(layer "In11.Cu")
		(net "M_H_CPU0_SB_DQ<24>")
	)
	(arc
		(start 376.684032 -229.597204)
		(mid 376.496834 -229.647347)
		(end 376.309636 -229.597204)
		(width 0.088646)
		(layer "In11.Cu")
		(net "M_H_CPU0_SB_DQ<24>")
	)
	(arc
		(start 382.322832 -229.597204)
		(mid 382.135634 -229.647347)
		(end 381.948436 -229.597204)
		(width 0.088646)
		(layer "In11.Cu")
		(net "M_H_CPU0_SB_DQ<24>")
	)
	(arc
		(start 374.804432 -229.597204)
		(mid 374.617234 -229.647347)
		(end 374.430036 -229.597204)
		(width 0.088646)
		(layer "In11.Cu")
		(net "M_H_CPU0_SB_DQ<24>")
	)
	(arc
		(start 379.503432 -229.597204)
		(mid 379.316234 -229.647347)
		(end 379.129036 -229.597204)
		(width 0.088646)
		(layer "In11.Cu")
		(net "M_H_CPU0_SB_DQ<24>")
	)
	(arc
		(start 386.62991 -228.724206)
		(mid 386.59286 -228.756352)
		(end 386.551932 -228.783388)
		(width 0.088646)
		(layer "In11.Cu")
		(net "M_H_CPU0_SB_DQ<24>")
	)
	(arc
		(start 374.430036 -229.597204)
		(mid 374.155837 -229.521369)
		(end 373.879364 -229.588568)
		(width 0.088646)
		(layer "In11.Cu")
		(net "M_H_CPU0_SB_DQ<24>")
	)
	(arc
		(start 376.309636 -229.597204)
		(mid 376.035437 -229.521369)
		(end 375.758964 -229.588568)
		(width 0.088646)
		(layer "In11.Cu")
		(net "M_H_CPU0_SB_DQ<24>")
	)
	(arc
		(start 384.767836 -229.597204)
		(mid 384.485134 -229.521428)
		(end 384.202432 -229.597204)
		(width 0.088646)
		(layer "In11.Cu")
		(net "M_H_CPU0_SB_DQ<24>")
	)
	(arc
		(start 384.202432 -229.597204)
		(mid 384.015234 -229.647347)
		(end 383.828036 -229.597204)
		(width 0.088646)
		(layer "In11.Cu")
		(net "M_H_CPU0_SB_DQ<24>")
	)
	(arc
		(start 385.142232 -229.597204)
		(mid 384.955034 -229.647347)
		(end 384.767836 -229.597204)
		(width 0.088646)
		(layer "In11.Cu")
		(net "M_H_CPU0_SB_DQ<24>")
	)
	(arc
		(start 378.563632 -229.597204)
		(mid 378.376434 -229.647347)
		(end 378.189236 -229.597204)
		(width 0.088646)
		(layer "In11.Cu")
		(net "M_H_CPU0_SB_DQ<24>")
	)
	(segment
		(start 376.026934 -228.99497)
		(end 376.02668 -228.994716)
		(width 0.20066)
		(layer "F.Cu")
		(net "M_H_CPU0_SB_DQ<23>")
	)
	(segment
		(start 461.689704 -204.714602)
		(end 462.073752 -204.714602)
		(width 0.20066)
		(layer "F.Cu")
		(net "M_H_CPU0_SB_DQ<23>")
	)
	(segment
		(start 458.550264 -205.391512)
		(end 460.558134 -205.391512)
		(width 0.1016)
		(layer "F.Cu")
		(net "M_H_CPU0_SB_DQ<23>")
	)
	(segment
		(start 462.32572 -204.96657)
		(end 463.659982 -204.96657)
		(width 0.20066)
		(layer "F.Cu")
		(net "M_H_CPU0_SB_DQ<23>")
	)
	(segment
		(start 457.814426 -204.96657)
		(end 458.24648 -205.398624)
		(width 0.20066)
		(layer "F.Cu")
		(net "M_H_CPU0_SB_DQ<23>")
	)
	(segment
		(start 455.011282 -204.96657)
		(end 456.116182 -204.96657)
		(width 0.20066)
		(layer "F.Cu")
		(net "M_H_CPU0_SB_DQ<23>")
	)
	(segment
		(start 461.251554 -205.403704)
		(end 461.455516 -205.199742)
		(width 0.20066)
		(layer "F.Cu")
		(net "M_H_CPU0_SB_DQ<23>")
	)
	(segment
		(start 460.558134 -205.391512)
		(end 460.570326 -205.403704)
		(width 0.1016)
		(layer "F.Cu")
		(net "M_H_CPU0_SB_DQ<23>")
	)
	(segment
		(start 458.24648 -205.398624)
		(end 458.538326 -205.398624)
		(width 0.20066)
		(layer "F.Cu")
		(net "M_H_CPU0_SB_DQ<23>")
	)
	(segment
		(start 462.073752 -204.714602)
		(end 462.32572 -204.96657)
		(width 0.20066)
		(layer "F.Cu")
		(net "M_H_CPU0_SB_DQ<23>")
	)
	(segment
		(start 376.02668 -228.994716)
		(end 376.02668 -228.45903)
		(width 0.20066)
		(layer "F.Cu")
		(net "M_H_CPU0_SB_DQ<23>")
	)
	(segment
		(start 458.543152 -205.398624)
		(end 458.550264 -205.391512)
		(width 0.1016)
		(layer "F.Cu")
		(net "M_H_CPU0_SB_DQ<23>")
	)
	(segment
		(start 456.116182 -204.96657)
		(end 457.814426 -204.96657)
		(width 0.20066)
		(layer "F.Cu")
		(net "M_H_CPU0_SB_DQ<23>")
	)
	(segment
		(start 461.455516 -204.94879)
		(end 461.689704 -204.714602)
		(width 0.20066)
		(layer "F.Cu")
		(net "M_H_CPU0_SB_DQ<23>")
	)
	(segment
		(start 458.538326 -205.398624)
		(end 458.543152 -205.398624)
		(width 0.101854)
		(layer "F.Cu")
		(net "M_H_CPU0_SB_DQ<23>")
	)
	(segment
		(start 460.570326 -205.403704)
		(end 461.251554 -205.403704)
		(width 0.20066)
		(layer "F.Cu")
		(net "M_H_CPU0_SB_DQ<23>")
	)
	(segment
		(start 461.455516 -205.199742)
		(end 461.455516 -204.94879)
		(width 0.20066)
		(layer "F.Cu")
		(net "M_H_CPU0_SB_DQ<23>")
	)
	(segment
		(start 422.767506 -205.886304)
		(end 422.273476 -205.392274)
		(width 0.18288)
		(layer "In6.Cu")
		(net "M_H_CPU0_SB_DQ<23>")
	)
	(segment
		(start 448.278758 -204.35951)
		(end 448.095878 -204.54239)
		(width 0.18288)
		(layer "In6.Cu")
		(net "M_H_CPU0_SB_DQ<23>")
	)
	(segment
		(start 383.358136 -227.155502)
		(end 383.347722 -227.149406)
		(width 0.088646)
		(layer "In6.Cu")
		(net "M_H_CPU0_SB_DQ<23>")
	)
	(segment
		(start 446.684146 -204.54239)
		(end 445.834262 -203.692506)
		(width 0.18288)
		(layer "In6.Cu")
		(net "M_H_CPU0_SB_DQ<23>")
	)
	(segment
		(start 437.682894 -203.916026)
		(end 436.057294 -204.54239)
		(width 0.18288)
		(layer "In6.Cu")
		(net "M_H_CPU0_SB_DQ<23>")
	)
	(segment
		(start 377.719082 -227.155502)
		(end 377.70435 -227.146866)
		(width 0.088646)
		(layer "In6.Cu")
		(net "M_H_CPU0_SB_DQ<23>")
	)
	(segment
		(start 439.698638 -203.692506)
		(end 439.475118 -203.916026)
		(width 0.18288)
		(layer "In6.Cu")
		(net "M_H_CPU0_SB_DQ<23>")
	)
	(segment
		(start 422.273476 -205.392274)
		(end 409.028392 -205.392274)
		(width 0.18288)
		(layer "In6.Cu")
		(net "M_H_CPU0_SB_DQ<23>")
	)
	(segment
		(start 378.659136 -227.155502)
		(end 378.648722 -227.149406)
		(width 0.088646)
		(layer "In6.Cu")
		(net "M_H_CPU0_SB_DQ<23>")
	)
	(segment
		(start 379.598682 -227.155502)
		(end 379.588268 -227.149406)
		(width 0.088646)
		(layer "In6.Cu")
		(net "M_H_CPU0_SB_DQ<23>")
	)
	(segment
		(start 409.028392 -205.392274)
		(end 408.851608 -205.569058)
		(width 0.18288)
		(layer "In6.Cu")
		(net "M_H_CPU0_SB_DQ<23>")
	)
	(segment
		(start 448.789298 -203.810362)
		(end 448.461638 -203.810362)
		(width 0.18288)
		(layer "In6.Cu")
		(net "M_H_CPU0_SB_DQ<23>")
	)
	(segment
		(start 381.478536 -227.155502)
		(end 381.468122 -227.149406)
		(width 0.088646)
		(layer "In6.Cu")
		(net "M_H_CPU0_SB_DQ<23>")
	)
	(segment
		(start 408.851608 -205.569058)
		(end 404.99284 -205.569058)
		(width 0.18288)
		(layer "In6.Cu")
		(net "M_H_CPU0_SB_DQ<23>")
	)
	(segment
		(start 448.095878 -204.54239)
		(end 446.684146 -204.54239)
		(width 0.18288)
		(layer "In6.Cu")
		(net "M_H_CPU0_SB_DQ<23>")
	)
	(segment
		(start 386.752846 -223.882204)
		(end 386.3086 -224.32645)
		(width 0.088646)
		(layer "In6.Cu")
		(net "M_H_CPU0_SB_DQ<23>")
	)
	(segment
		(start 448.972178 -203.993242)
		(end 448.789298 -203.810362)
		(width 0.18288)
		(layer "In6.Cu")
		(net "M_H_CPU0_SB_DQ<23>")
	)
	(segment
		(start 382.418082 -227.155502)
		(end 382.407668 -227.149406)
		(width 0.088646)
		(layer "In6.Cu")
		(net "M_H_CPU0_SB_DQ<23>")
	)
	(segment
		(start 377.153678 -227.155502)
		(end 377.14936 -227.158042)
		(width 0.088646)
		(layer "In6.Cu")
		(net "M_H_CPU0_SB_DQ<23>")
	)
	(segment
		(start 385.802886 -226.043744)
		(end 384.75031 -227.09632)
		(width 0.088646)
		(layer "In6.Cu")
		(net "M_H_CPU0_SB_DQ<23>")
	)
	(segment
		(start 385.802886 -225.05162)
		(end 385.802886 -226.043744)
		(width 0.088646)
		(layer "In6.Cu")
		(net "M_H_CPU0_SB_DQ<23>")
	)
	(segment
		(start 451.885558 -204.54239)
		(end 449.155058 -204.54239)
		(width 0.18288)
		(layer "In6.Cu")
		(net "M_H_CPU0_SB_DQ<23>")
	)
	(segment
		(start 445.834262 -203.692506)
		(end 439.698638 -203.692506)
		(width 0.18288)
		(layer "In6.Cu")
		(net "M_H_CPU0_SB_DQ<23>")
	)
	(segment
		(start 387.986016 -223.128078)
		(end 387.496304 -223.61779)
		(width 0.18288)
		(layer "In6.Cu")
		(net "M_H_CPU0_SB_DQ<23>")
	)
	(segment
		(start 377.14936 -227.158042)
		(end 377.147582 -227.159058)
		(width 0.088646)
		(layer "In6.Cu")
		(net "M_H_CPU0_SB_DQ<23>")
	)
	(segment
		(start 387.985762 -222.669354)
		(end 387.985762 -222.870014)
		(width 0.18288)
		(layer "In6.Cu")
		(net "M_H_CPU0_SB_DQ<23>")
	)
	(segment
		(start 386.3086 -224.32645)
		(end 386.3086 -224.545906)
		(width 0.088646)
		(layer "In6.Cu")
		(net "M_H_CPU0_SB_DQ<23>")
	)
	(segment
		(start 380.538482 -227.155502)
		(end 380.52375 -227.146866)
		(width 0.088646)
		(layer "In6.Cu")
		(net "M_H_CPU0_SB_DQ<23>")
	)
	(segment
		(start 387.01726 -223.61779)
		(end 386.752846 -223.882204)
		(width 0.18288)
		(layer "In6.Cu")
		(net "M_H_CPU0_SB_DQ<23>")
	)
	(segment
		(start 387.496304 -223.61779)
		(end 387.01726 -223.61779)
		(width 0.18288)
		(layer "In6.Cu")
		(net "M_H_CPU0_SB_DQ<23>")
	)
	(segment
		(start 388.503414 -222.41002)
		(end 388.244842 -222.410274)
		(width 0.18288)
		(layer "In6.Cu")
		(net "M_H_CPU0_SB_DQ<23>")
	)
	(segment
		(start 453.40905 -206.065882)
		(end 451.885558 -204.54239)
		(width 0.18288)
		(layer "In6.Cu")
		(net "M_H_CPU0_SB_DQ<23>")
	)
	(segment
		(start 386.3086 -224.545906)
		(end 385.802886 -225.05162)
		(width 0.088646)
		(layer "In6.Cu")
		(net "M_H_CPU0_SB_DQ<23>")
	)
	(segment
		(start 434.33873 -204.54239)
		(end 433.489862 -205.391258)
		(width 0.18288)
		(layer "In6.Cu")
		(net "M_H_CPU0_SB_DQ<23>")
	)
	(segment
		(start 425.917868 -205.661768)
		(end 425.335446 -206.24419)
		(width 0.18288)
		(layer "In6.Cu")
		(net "M_H_CPU0_SB_DQ<23>")
	)
	(segment
		(start 424.260264 -206.24419)
		(end 423.902378 -205.886304)
		(width 0.18288)
		(layer "In6.Cu")
		(net "M_H_CPU0_SB_DQ<23>")
	)
	(segment
		(start 387.985762 -222.870014)
		(end 387.986016 -223.128078)
		(width 0.18288)
		(layer "In6.Cu")
		(net "M_H_CPU0_SB_DQ<23>")
	)
	(segment
		(start 449.155058 -204.54239)
		(end 448.972178 -204.35951)
		(width 0.18288)
		(layer "In6.Cu")
		(net "M_H_CPU0_SB_DQ<23>")
	)
	(segment
		(start 376.692668 -227.964238)
		(end 376.683778 -227.969318)
		(width 0.088646)
		(layer "In6.Cu")
		(net "M_H_CPU0_SB_DQ<23>")
	)
	(segment
		(start 400.595592 -210.518502)
		(end 388.704074 -222.41002)
		(width 0.18288)
		(layer "In6.Cu")
		(net "M_H_CPU0_SB_DQ<23>")
	)
	(segment
		(start 455.011282 -204.96657)
		(end 453.91197 -206.065882)
		(width 0.18288)
		(layer "In6.Cu")
		(net "M_H_CPU0_SB_DQ<23>")
	)
	(segment
		(start 426.784262 -205.391258)
		(end 426.513752 -205.661768)
		(width 0.18288)
		(layer "In6.Cu")
		(net "M_H_CPU0_SB_DQ<23>")
	)
	(segment
		(start 439.475118 -203.916026)
		(end 437.682894 -203.916026)
		(width 0.18288)
		(layer "In6.Cu")
		(net "M_H_CPU0_SB_DQ<23>")
	)
	(segment
		(start 376.610372 -228.019864)
		(end 376.02668 -228.45903)
		(width 0.088646)
		(layer "In6.Cu")
		(net "M_H_CPU0_SB_DQ<23>")
	)
	(segment
		(start 400.595592 -209.966306)
		(end 400.595592 -210.518502)
		(width 0.18288)
		(layer "In6.Cu")
		(net "M_H_CPU0_SB_DQ<23>")
	)
	(segment
		(start 423.902378 -205.886304)
		(end 422.767506 -205.886304)
		(width 0.18288)
		(layer "In6.Cu")
		(net "M_H_CPU0_SB_DQ<23>")
	)
	(segment
		(start 448.461638 -203.810362)
		(end 448.278758 -203.993242)
		(width 0.18288)
		(layer "In6.Cu")
		(net "M_H_CPU0_SB_DQ<23>")
	)
	(segment
		(start 448.278758 -203.993242)
		(end 448.278758 -204.35951)
		(width 0.18288)
		(layer "In6.Cu")
		(net "M_H_CPU0_SB_DQ<23>")
	)
	(segment
		(start 388.244842 -222.410274)
		(end 387.985762 -222.669354)
		(width 0.18288)
		(layer "In6.Cu")
		(net "M_H_CPU0_SB_DQ<23>")
	)
	(segment
		(start 426.513752 -205.661768)
		(end 425.917868 -205.661768)
		(width 0.18288)
		(layer "In6.Cu")
		(net "M_H_CPU0_SB_DQ<23>")
	)
	(segment
		(start 453.91197 -206.065882)
		(end 453.40905 -206.065882)
		(width 0.18288)
		(layer "In6.Cu")
		(net "M_H_CPU0_SB_DQ<23>")
	)
	(segment
		(start 388.704074 -222.41002)
		(end 388.503414 -222.41002)
		(width 0.18288)
		(layer "In6.Cu")
		(net "M_H_CPU0_SB_DQ<23>")
	)
	(segment
		(start 425.335446 -206.24419)
		(end 424.260264 -206.24419)
		(width 0.18288)
		(layer "In6.Cu")
		(net "M_H_CPU0_SB_DQ<23>")
	)
	(segment
		(start 436.057294 -204.54239)
		(end 434.33873 -204.54239)
		(width 0.18288)
		(layer "In6.Cu")
		(net "M_H_CPU0_SB_DQ<23>")
	)
	(segment
		(start 433.489862 -205.391258)
		(end 426.784262 -205.391258)
		(width 0.18288)
		(layer "In6.Cu")
		(net "M_H_CPU0_SB_DQ<23>")
	)
	(segment
		(start 448.972178 -204.35951)
		(end 448.972178 -203.993242)
		(width 0.18288)
		(layer "In6.Cu")
		(net "M_H_CPU0_SB_DQ<23>")
	)
	(segment
		(start 404.99284 -205.569058)
		(end 400.595592 -209.966306)
		(width 0.18288)
		(layer "In6.Cu")
		(net "M_H_CPU0_SB_DQ<23>")
	)
	(arc
		(start 381.852932 -227.155502)
		(mid 381.665734 -227.205645)
		(end 381.478536 -227.155502)
		(width 0.088646)
		(layer "In6.Cu")
		(net "M_H_CPU0_SB_DQ<23>")
	)
	(arc
		(start 382.407668 -227.149406)
		(mid 382.12949 -227.079683)
		(end 381.852932 -227.155502)
		(width 0.088646)
		(layer "In6.Cu")
		(net "M_H_CPU0_SB_DQ<23>")
	)
	(arc
		(start 376.87123 -227.64496)
		(mid 376.823551 -227.82786)
		(end 376.692668 -227.964238)
		(width 0.088646)
		(layer "In6.Cu")
		(net "M_H_CPU0_SB_DQ<23>")
	)
	(arc
		(start 384.297936 -227.155502)
		(mid 384.015234 -227.079726)
		(end 383.732532 -227.155502)
		(width 0.088646)
		(layer "In6.Cu")
		(net "M_H_CPU0_SB_DQ<23>")
	)
	(arc
		(start 382.792478 -227.155502)
		(mid 382.60528 -227.205645)
		(end 382.418082 -227.155502)
		(width 0.088646)
		(layer "In6.Cu")
		(net "M_H_CPU0_SB_DQ<23>")
	)
	(arc
		(start 378.648722 -227.149406)
		(mid 378.37029 -227.07956)
		(end 378.093478 -227.155502)
		(width 0.088646)
		(layer "In6.Cu")
		(net "M_H_CPU0_SB_DQ<23>")
	)
	(arc
		(start 383.732532 -227.155502)
		(mid 383.545334 -227.205645)
		(end 383.358136 -227.155502)
		(width 0.088646)
		(layer "In6.Cu")
		(net "M_H_CPU0_SB_DQ<23>")
	)
	(arc
		(start 380.52375 -227.146866)
		(mid 380.247275 -227.079546)
		(end 379.973078 -227.155502)
		(width 0.088646)
		(layer "In6.Cu")
		(net "M_H_CPU0_SB_DQ<23>")
	)
	(arc
		(start 376.683778 -227.969318)
		(mid 376.646079 -227.993144)
		(end 376.610372 -228.019864)
		(width 0.088646)
		(layer "In6.Cu")
		(net "M_H_CPU0_SB_DQ<23>")
	)
	(arc
		(start 383.347722 -227.149406)
		(mid 383.06929 -227.07956)
		(end 382.792478 -227.155502)
		(width 0.088646)
		(layer "In6.Cu")
		(net "M_H_CPU0_SB_DQ<23>")
	)
	(arc
		(start 378.093478 -227.155502)
		(mid 377.90628 -227.205645)
		(end 377.719082 -227.155502)
		(width 0.088646)
		(layer "In6.Cu")
		(net "M_H_CPU0_SB_DQ<23>")
	)
	(arc
		(start 377.147582 -227.159058)
		(mid 376.945169 -227.365471)
		(end 376.87123 -227.64496)
		(width 0.088646)
		(layer "In6.Cu")
		(net "M_H_CPU0_SB_DQ<23>")
	)
	(arc
		(start 379.588268 -227.149406)
		(mid 379.31009 -227.079683)
		(end 379.033532 -227.155502)
		(width 0.088646)
		(layer "In6.Cu")
		(net "M_H_CPU0_SB_DQ<23>")
	)
	(arc
		(start 379.973078 -227.155502)
		(mid 379.78588 -227.205645)
		(end 379.598682 -227.155502)
		(width 0.088646)
		(layer "In6.Cu")
		(net "M_H_CPU0_SB_DQ<23>")
	)
	(arc
		(start 381.468122 -227.149406)
		(mid 381.18969 -227.07956)
		(end 380.912878 -227.155502)
		(width 0.088646)
		(layer "In6.Cu")
		(net "M_H_CPU0_SB_DQ<23>")
	)
	(arc
		(start 380.912878 -227.155502)
		(mid 380.72568 -227.205645)
		(end 380.538482 -227.155502)
		(width 0.088646)
		(layer "In6.Cu")
		(net "M_H_CPU0_SB_DQ<23>")
	)
	(arc
		(start 384.672332 -227.155502)
		(mid 384.485134 -227.205645)
		(end 384.297936 -227.155502)
		(width 0.088646)
		(layer "In6.Cu")
		(net "M_H_CPU0_SB_DQ<23>")
	)
	(arc
		(start 377.70435 -227.146866)
		(mid 377.427875 -227.079546)
		(end 377.153678 -227.155502)
		(width 0.088646)
		(layer "In6.Cu")
		(net "M_H_CPU0_SB_DQ<23>")
	)
	(arc
		(start 379.033532 -227.155502)
		(mid 378.846334 -227.205645)
		(end 378.659136 -227.155502)
		(width 0.088646)
		(layer "In6.Cu")
		(net "M_H_CPU0_SB_DQ<23>")
	)
	(arc
		(start 384.75031 -227.09632)
		(mid 384.71326 -227.128466)
		(end 384.672332 -227.155502)
		(width 0.088646)
		(layer "In6.Cu")
		(net "M_H_CPU0_SB_DQ<23>")
	)
	(segment
		(start 461.455516 -206.899764)
		(end 461.455516 -206.648812)
		(width 0.20066)
		(layer "F.Cu")
		(net "M_H_CPU0_SB_DQ<22>")
	)
	(segment
		(start 458.543152 -207.098646)
		(end 458.550264 -207.091534)
		(width 0.1016)
		(layer "F.Cu")
		(net "M_H_CPU0_SB_DQ<22>")
	)
	(segment
		(start 461.251554 -207.103726)
		(end 461.455516 -206.899764)
		(width 0.20066)
		(layer "F.Cu")
		(net "M_H_CPU0_SB_DQ<22>")
	)
	(segment
		(start 455.011282 -206.666592)
		(end 456.116182 -206.666592)
		(width 0.20066)
		(layer "F.Cu")
		(net "M_H_CPU0_SB_DQ<22>")
	)
	(segment
		(start 376.496834 -229.808532)
		(end 376.496834 -229.272846)
		(width 0.20066)
		(layer "F.Cu")
		(net "M_H_CPU0_SB_DQ<22>")
	)
	(segment
		(start 462.073752 -206.414624)
		(end 462.32572 -206.666592)
		(width 0.20066)
		(layer "F.Cu")
		(net "M_H_CPU0_SB_DQ<22>")
	)
	(segment
		(start 458.550264 -207.091534)
		(end 460.558134 -207.091534)
		(width 0.1016)
		(layer "F.Cu")
		(net "M_H_CPU0_SB_DQ<22>")
	)
	(segment
		(start 456.116182 -206.666592)
		(end 457.814426 -206.666592)
		(width 0.20066)
		(layer "F.Cu")
		(net "M_H_CPU0_SB_DQ<22>")
	)
	(segment
		(start 458.24648 -207.098646)
		(end 458.538326 -207.098646)
		(width 0.20066)
		(layer "F.Cu")
		(net "M_H_CPU0_SB_DQ<22>")
	)
	(segment
		(start 458.538326 -207.098646)
		(end 458.543152 -207.098646)
		(width 0.101854)
		(layer "F.Cu")
		(net "M_H_CPU0_SB_DQ<22>")
	)
	(segment
		(start 461.689704 -206.414624)
		(end 462.073752 -206.414624)
		(width 0.20066)
		(layer "F.Cu")
		(net "M_H_CPU0_SB_DQ<22>")
	)
	(segment
		(start 460.558134 -207.091534)
		(end 460.570326 -207.103726)
		(width 0.1016)
		(layer "F.Cu")
		(net "M_H_CPU0_SB_DQ<22>")
	)
	(segment
		(start 457.814426 -206.666592)
		(end 458.24648 -207.098646)
		(width 0.20066)
		(layer "F.Cu")
		(net "M_H_CPU0_SB_DQ<22>")
	)
	(segment
		(start 460.570326 -207.103726)
		(end 461.251554 -207.103726)
		(width 0.20066)
		(layer "F.Cu")
		(net "M_H_CPU0_SB_DQ<22>")
	)
	(segment
		(start 376.49658 -229.808786)
		(end 376.496834 -229.808532)
		(width 0.20066)
		(layer "F.Cu")
		(net "M_H_CPU0_SB_DQ<22>")
	)
	(segment
		(start 461.455516 -206.648812)
		(end 461.689704 -206.414624)
		(width 0.20066)
		(layer "F.Cu")
		(net "M_H_CPU0_SB_DQ<22>")
	)
	(segment
		(start 462.32572 -206.666592)
		(end 463.659982 -206.666592)
		(width 0.20066)
		(layer "F.Cu")
		(net "M_H_CPU0_SB_DQ<22>")
	)
	(segment
		(start 444.163196 -205.392528)
		(end 437.883046 -205.392528)
		(width 0.18288)
		(layer "In6.Cu")
		(net "M_H_CPU0_SB_DQ<22>")
	)
	(segment
		(start 410.235908 -206.982568)
		(end 409.165298 -206.982568)
		(width 0.18288)
		(layer "In6.Cu")
		(net "M_H_CPU0_SB_DQ<22>")
	)
	(segment
		(start 447.4845 -206.459836)
		(end 446.881504 -206.459836)
		(width 0.18288)
		(layer "In6.Cu")
		(net "M_H_CPU0_SB_DQ<22>")
	)
	(segment
		(start 454.060306 -207.617568)
		(end 452.974964 -207.617568)
		(width 0.18288)
		(layer "In6.Cu")
		(net "M_H_CPU0_SB_DQ<22>")
	)
	(segment
		(start 423.772838 -207.93837)
		(end 423.663364 -207.828896)
		(width 0.18288)
		(layer "In6.Cu")
		(net "M_H_CPU0_SB_DQ<22>")
	)
	(segment
		(start 451.599808 -206.242412)
		(end 450.317108 -206.242412)
		(width 0.18288)
		(layer "In6.Cu")
		(net "M_H_CPU0_SB_DQ<22>")
	)
	(segment
		(start 422.012872 -207.092296)
		(end 415.49574 -207.092296)
		(width 0.18288)
		(layer "In6.Cu")
		(net "M_H_CPU0_SB_DQ<22>")
	)
	(segment
		(start 446.881504 -206.459836)
		(end 446.445894 -206.024226)
		(width 0.18288)
		(layer "In6.Cu")
		(net "M_H_CPU0_SB_DQ<22>")
	)
	(segment
		(start 450.074284 -206.485236)
		(end 449.5419 -206.485236)
		(width 0.18288)
		(layer "In6.Cu")
		(net "M_H_CPU0_SB_DQ<22>")
	)
	(segment
		(start 450.317108 -206.242412)
		(end 450.074284 -206.485236)
		(width 0.18288)
		(layer "In6.Cu")
		(net "M_H_CPU0_SB_DQ<22>")
	)
	(segment
		(start 409.165298 -206.982568)
		(end 408.92984 -207.218026)
		(width 0.18288)
		(layer "In6.Cu")
		(net "M_H_CPU0_SB_DQ<22>")
	)
	(segment
		(start 434.888894 -206.456026)
		(end 433.974748 -206.456026)
		(width 0.18288)
		(layer "In6.Cu")
		(net "M_H_CPU0_SB_DQ<22>")
	)
	(segment
		(start 427.748192 -207.268826)
		(end 427.315122 -206.835756)
		(width 0.18288)
		(layer "In6.Cu")
		(net "M_H_CPU0_SB_DQ<22>")
	)
	(segment
		(start 411.232604 -207.215232)
		(end 411.232604 -207.628236)
		(width 0.18288)
		(layer "In6.Cu")
		(net "M_H_CPU0_SB_DQ<22>")
	)
	(segment
		(start 405.170132 -207.218026)
		(end 401.731734 -210.656424)
		(width 0.18288)
		(layer "In6.Cu")
		(net "M_H_CPU0_SB_DQ<22>")
	)
	(segment
		(start 411.232604 -207.628236)
		(end 411.0355 -207.82534)
		(width 0.18288)
		(layer "In6.Cu")
		(net "M_H_CPU0_SB_DQ<22>")
	)
	(segment
		(start 435.102762 -206.242158)
		(end 434.888894 -206.456026)
		(width 0.18288)
		(layer "In6.Cu")
		(net "M_H_CPU0_SB_DQ<22>")
	)
	(segment
		(start 433.974748 -206.456026)
		(end 433.390548 -207.040226)
		(width 0.18288)
		(layer "In6.Cu")
		(net "M_H_CPU0_SB_DQ<22>")
	)
	(segment
		(start 452.974964 -207.617568)
		(end 451.599808 -206.242412)
		(width 0.18288)
		(layer "In6.Cu")
		(net "M_H_CPU0_SB_DQ<22>")
	)
	(segment
		(start 431.129694 -207.040226)
		(end 430.901094 -207.268826)
		(width 0.18288)
		(layer "In6.Cu")
		(net "M_H_CPU0_SB_DQ<22>")
	)
	(segment
		(start 412.602172 -207.283304)
		(end 412.301436 -206.982568)
		(width 0.18288)
		(layer "In6.Cu")
		(net "M_H_CPU0_SB_DQ<22>")
	)
	(segment
		(start 414.040066 -206.726028)
		(end 413.48279 -207.283304)
		(width 0.18288)
		(layer "In6.Cu")
		(net "M_H_CPU0_SB_DQ<22>")
	)
	(segment
		(start 423.663364 -207.828896)
		(end 422.749472 -207.828896)
		(width 0.18288)
		(layer "In6.Cu")
		(net "M_H_CPU0_SB_DQ<22>")
	)
	(segment
		(start 449.2117 -206.155036)
		(end 447.7893 -206.155036)
		(width 0.18288)
		(layer "In6.Cu")
		(net "M_H_CPU0_SB_DQ<22>")
	)
	(segment
		(start 377.162568 -228.778308)
		(end 377.153678 -228.783388)
		(width 0.088646)
		(layer "In6.Cu")
		(net "M_H_CPU0_SB_DQ<22>")
	)
	(segment
		(start 410.481018 -207.227678)
		(end 410.235908 -206.982568)
		(width 0.18288)
		(layer "In6.Cu")
		(net "M_H_CPU0_SB_DQ<22>")
	)
	(segment
		(start 430.901094 -207.268826)
		(end 427.748192 -207.268826)
		(width 0.18288)
		(layer "In6.Cu")
		(net "M_H_CPU0_SB_DQ<22>")
	)
	(segment
		(start 410.481018 -207.665066)
		(end 410.481018 -207.227678)
		(width 0.18288)
		(layer "In6.Cu")
		(net "M_H_CPU0_SB_DQ<22>")
	)
	(segment
		(start 411.0355 -207.82534)
		(end 410.641292 -207.82534)
		(width 0.18288)
		(layer "In6.Cu")
		(net "M_H_CPU0_SB_DQ<22>")
	)
	(segment
		(start 437.033416 -206.242158)
		(end 435.102762 -206.242158)
		(width 0.18288)
		(layer "In6.Cu")
		(net "M_H_CPU0_SB_DQ<22>")
	)
	(segment
		(start 413.48279 -207.283304)
		(end 412.602172 -207.283304)
		(width 0.18288)
		(layer "In6.Cu")
		(net "M_H_CPU0_SB_DQ<22>")
	)
	(segment
		(start 386.761482 -225.797618)
		(end 386.369814 -226.189286)
		(width 0.088646)
		(layer "In6.Cu")
		(net "M_H_CPU0_SB_DQ<22>")
	)
	(segment
		(start 377.34113 -228.444806)
		(end 377.34113 -228.45903)
		(width 0.088646)
		(layer "In6.Cu")
		(net "M_H_CPU0_SB_DQ<22>")
	)
	(segment
		(start 386.369814 -226.189286)
		(end 386.369814 -226.64293)
		(width 0.088646)
		(layer "In6.Cu")
		(net "M_H_CPU0_SB_DQ<22>")
	)
	(segment
		(start 447.7893 -206.155036)
		(end 447.4845 -206.459836)
		(width 0.18288)
		(layer "In6.Cu")
		(net "M_H_CPU0_SB_DQ<22>")
	)
	(segment
		(start 446.445894 -206.024226)
		(end 444.794894 -206.024226)
		(width 0.18288)
		(layer "In6.Cu")
		(net "M_H_CPU0_SB_DQ<22>")
	)
	(segment
		(start 415.49574 -207.092296)
		(end 415.129472 -206.726028)
		(width 0.18288)
		(layer "In6.Cu")
		(net "M_H_CPU0_SB_DQ<22>")
	)
	(segment
		(start 382.337564 -227.960682)
		(end 382.322832 -227.969318)
		(width 0.088646)
		(layer "In6.Cu")
		(net "M_H_CPU0_SB_DQ<22>")
	)
	(segment
		(start 379.518164 -227.960682)
		(end 379.503432 -227.969318)
		(width 0.088646)
		(layer "In6.Cu")
		(net "M_H_CPU0_SB_DQ<22>")
	)
	(segment
		(start 408.92984 -207.218026)
		(end 405.170132 -207.218026)
		(width 0.18288)
		(layer "In6.Cu")
		(net "M_H_CPU0_SB_DQ<22>")
	)
	(segment
		(start 455.011282 -206.666592)
		(end 454.060306 -207.617568)
		(width 0.18288)
		(layer "In6.Cu")
		(net "M_H_CPU0_SB_DQ<22>")
	)
	(segment
		(start 401.731734 -210.656424)
		(end 401.731734 -210.827366)
		(width 0.18288)
		(layer "In6.Cu")
		(net "M_H_CPU0_SB_DQ<22>")
	)
	(segment
		(start 433.390548 -207.040226)
		(end 431.129694 -207.040226)
		(width 0.18288)
		(layer "In6.Cu")
		(net "M_H_CPU0_SB_DQ<22>")
	)
	(segment
		(start 378.578364 -227.960682)
		(end 378.563632 -227.969318)
		(width 0.088646)
		(layer "In6.Cu")
		(net "M_H_CPU0_SB_DQ<22>")
	)
	(segment
		(start 411.465268 -206.982568)
		(end 411.232604 -207.215232)
		(width 0.18288)
		(layer "In6.Cu")
		(net "M_H_CPU0_SB_DQ<22>")
	)
	(segment
		(start 410.641292 -207.82534)
		(end 410.481018 -207.665066)
		(width 0.18288)
		(layer "In6.Cu")
		(net "M_H_CPU0_SB_DQ<22>")
	)
	(segment
		(start 376.934476 -229.013004)
		(end 376.496834 -229.272846)
		(width 0.088646)
		(layer "In6.Cu")
		(net "M_H_CPU0_SB_DQ<22>")
	)
	(segment
		(start 425.531026 -207.93837)
		(end 423.772838 -207.93837)
		(width 0.18288)
		(layer "In6.Cu")
		(net "M_H_CPU0_SB_DQ<22>")
	)
	(segment
		(start 415.129472 -206.726028)
		(end 414.040066 -206.726028)
		(width 0.18288)
		(layer "In6.Cu")
		(net "M_H_CPU0_SB_DQ<22>")
	)
	(segment
		(start 401.731734 -210.827366)
		(end 386.761482 -225.797618)
		(width 0.18288)
		(layer "In6.Cu")
		(net "M_H_CPU0_SB_DQ<22>")
	)
	(segment
		(start 449.5419 -206.485236)
		(end 449.2117 -206.155036)
		(width 0.18288)
		(layer "In6.Cu")
		(net "M_H_CPU0_SB_DQ<22>")
	)
	(segment
		(start 427.315122 -206.835756)
		(end 426.63364 -206.835756)
		(width 0.18288)
		(layer "In6.Cu")
		(net "M_H_CPU0_SB_DQ<22>")
	)
	(segment
		(start 412.301436 -206.982568)
		(end 411.465268 -206.982568)
		(width 0.18288)
		(layer "In6.Cu")
		(net "M_H_CPU0_SB_DQ<22>")
	)
	(segment
		(start 444.794894 -206.024226)
		(end 444.163196 -205.392528)
		(width 0.18288)
		(layer "In6.Cu")
		(net "M_H_CPU0_SB_DQ<22>")
	)
	(segment
		(start 386.369814 -226.64293)
		(end 386.133086 -226.99726)
		(width 0.088646)
		(layer "In6.Cu")
		(net "M_H_CPU0_SB_DQ<22>")
	)
	(segment
		(start 426.63364 -206.835756)
		(end 425.531026 -207.93837)
		(width 0.18288)
		(layer "In6.Cu")
		(net "M_H_CPU0_SB_DQ<22>")
	)
	(segment
		(start 386.133086 -226.99726)
		(end 385.22021 -227.910136)
		(width 0.088646)
		(layer "In6.Cu")
		(net "M_H_CPU0_SB_DQ<22>")
	)
	(segment
		(start 377.638564 -227.960682)
		(end 377.623832 -227.969318)
		(width 0.088646)
		(layer "In6.Cu")
		(net "M_H_CPU0_SB_DQ<22>")
	)
	(segment
		(start 422.749472 -207.828896)
		(end 422.012872 -207.092296)
		(width 0.18288)
		(layer "In6.Cu")
		(net "M_H_CPU0_SB_DQ<22>")
	)
	(segment
		(start 437.883046 -205.392528)
		(end 437.033416 -206.242158)
		(width 0.18288)
		(layer "In6.Cu")
		(net "M_H_CPU0_SB_DQ<22>")
	)
	(arc
		(start 380.068836 -227.969318)
		(mid 379.794607 -227.893393)
		(end 379.518164 -227.960682)
		(width 0.088646)
		(layer "In6.Cu")
		(net "M_H_CPU0_SB_DQ<22>")
	)
	(arc
		(start 383.828036 -227.969318)
		(mid 383.545334 -227.893576)
		(end 383.262632 -227.969318)
		(width 0.088646)
		(layer "In6.Cu")
		(net "M_H_CPU0_SB_DQ<22>")
	)
	(arc
		(start 380.443232 -227.969318)
		(mid 380.256034 -228.019461)
		(end 380.068836 -227.969318)
		(width 0.088646)
		(layer "In6.Cu")
		(net "M_H_CPU0_SB_DQ<22>")
	)
	(arc
		(start 385.22021 -227.910136)
		(mid 385.18316 -227.942282)
		(end 385.142232 -227.969318)
		(width 0.088646)
		(layer "In6.Cu")
		(net "M_H_CPU0_SB_DQ<22>")
	)
	(arc
		(start 377.623832 -227.969318)
		(mid 377.420351 -228.170122)
		(end 377.34113 -228.444806)
		(width 0.088646)
		(layer "In6.Cu")
		(net "M_H_CPU0_SB_DQ<22>")
	)
	(arc
		(start 379.503432 -227.969318)
		(mid 379.316234 -228.019461)
		(end 379.129036 -227.969318)
		(width 0.088646)
		(layer "In6.Cu")
		(net "M_H_CPU0_SB_DQ<22>")
	)
	(arc
		(start 377.153678 -228.783388)
		(mid 377.027602 -228.882474)
		(end 376.934476 -229.013004)
		(width 0.088646)
		(layer "In6.Cu")
		(net "M_H_CPU0_SB_DQ<22>")
	)
	(arc
		(start 381.383032 -227.969318)
		(mid 381.195834 -228.019461)
		(end 381.008636 -227.969318)
		(width 0.088646)
		(layer "In6.Cu")
		(net "M_H_CPU0_SB_DQ<22>")
	)
	(arc
		(start 382.322832 -227.969318)
		(mid 382.135634 -228.019461)
		(end 381.948436 -227.969318)
		(width 0.088646)
		(layer "In6.Cu")
		(net "M_H_CPU0_SB_DQ<22>")
	)
	(arc
		(start 378.563632 -227.969318)
		(mid 378.376434 -228.019461)
		(end 378.189236 -227.969318)
		(width 0.088646)
		(layer "In6.Cu")
		(net "M_H_CPU0_SB_DQ<22>")
	)
	(arc
		(start 378.189236 -227.969318)
		(mid 377.915007 -227.893393)
		(end 377.638564 -227.960682)
		(width 0.088646)
		(layer "In6.Cu")
		(net "M_H_CPU0_SB_DQ<22>")
	)
	(arc
		(start 379.129036 -227.969318)
		(mid 378.854807 -227.893393)
		(end 378.578364 -227.960682)
		(width 0.088646)
		(layer "In6.Cu")
		(net "M_H_CPU0_SB_DQ<22>")
	)
	(arc
		(start 381.948436 -227.969318)
		(mid 381.665734 -227.893576)
		(end 381.383032 -227.969318)
		(width 0.088646)
		(layer "In6.Cu")
		(net "M_H_CPU0_SB_DQ<22>")
	)
	(arc
		(start 377.34113 -228.45903)
		(mid 377.293451 -228.64193)
		(end 377.162568 -228.778308)
		(width 0.088646)
		(layer "In6.Cu")
		(net "M_H_CPU0_SB_DQ<22>")
	)
	(arc
		(start 385.142232 -227.969318)
		(mid 384.955034 -228.019461)
		(end 384.767836 -227.969318)
		(width 0.088646)
		(layer "In6.Cu")
		(net "M_H_CPU0_SB_DQ<22>")
	)
	(arc
		(start 382.888236 -227.969318)
		(mid 382.614007 -227.893393)
		(end 382.337564 -227.960682)
		(width 0.088646)
		(layer "In6.Cu")
		(net "M_H_CPU0_SB_DQ<22>")
	)
	(arc
		(start 381.008636 -227.969318)
		(mid 380.725934 -227.893576)
		(end 380.443232 -227.969318)
		(width 0.088646)
		(layer "In6.Cu")
		(net "M_H_CPU0_SB_DQ<22>")
	)
	(arc
		(start 383.262632 -227.969318)
		(mid 383.075434 -228.019461)
		(end 382.888236 -227.969318)
		(width 0.088646)
		(layer "In6.Cu")
		(net "M_H_CPU0_SB_DQ<22>")
	)
	(arc
		(start 384.202432 -227.969318)
		(mid 384.015234 -228.019461)
		(end 383.828036 -227.969318)
		(width 0.088646)
		(layer "In6.Cu")
		(net "M_H_CPU0_SB_DQ<22>")
	)
	(arc
		(start 384.767836 -227.969318)
		(mid 384.485134 -227.893576)
		(end 384.202432 -227.969318)
		(width 0.088646)
		(layer "In6.Cu")
		(net "M_H_CPU0_SB_DQ<22>")
	)
	(segment
		(start 454.566782 -205.391766)
		(end 454.448672 -205.509876)
		(width 0.20066)
		(layer "F.Cu")
		(net "M_H_CPU0_SB_DQ<21>")
	)
	(segment
		(start 454.260712 -206.065374)
		(end 453.785478 -206.065374)
		(width 0.20066)
		(layer "F.Cu")
		(net "M_H_CPU0_SB_DQ<21>")
	)
	(segment
		(start 457.126594 -205.385416)
		(end 457.120244 -205.391766)
		(width 0.1016)
		(layer "F.Cu")
		(net "M_H_CPU0_SB_DQ<21>")
	)
	(segment
		(start 375.08688 -228.994716)
		(end 375.08688 -228.45903)
		(width 0.20066)
		(layer "F.Cu")
		(net "M_H_CPU0_SB_DQ<21>")
	)
	(segment
		(start 453.785478 -206.065374)
		(end 453.536812 -205.816708)
		(width 0.20066)
		(layer "F.Cu")
		(net "M_H_CPU0_SB_DQ<21>")
	)
	(segment
		(start 457.53655 -205.385416)
		(end 457.126594 -205.385416)
		(width 0.20066)
		(layer "F.Cu")
		(net "M_H_CPU0_SB_DQ<21>")
	)
	(segment
		(start 459.559914 -205.816708)
		(end 459.55966 -205.816962)
		(width 0.20066)
		(layer "F.Cu")
		(net "M_H_CPU0_SB_DQ<21>")
	)
	(segment
		(start 454.91146 -205.391766)
		(end 454.566782 -205.391766)
		(width 0.20066)
		(layer "F.Cu")
		(net "M_H_CPU0_SB_DQ<21>")
	)
	(segment
		(start 454.931526 -205.391766)
		(end 454.91146 -205.391766)
		(width 0.101854)
		(layer "F.Cu")
		(net "M_H_CPU0_SB_DQ<21>")
	)
	(segment
		(start 452.016114 -205.816708)
		(end 450.911214 -205.816708)
		(width 0.20066)
		(layer "F.Cu")
		(net "M_H_CPU0_SB_DQ<21>")
	)
	(segment
		(start 459.55966 -205.816962)
		(end 457.968096 -205.816962)
		(width 0.20066)
		(layer "F.Cu")
		(net "M_H_CPU0_SB_DQ<21>")
	)
	(segment
		(start 454.448672 -205.509876)
		(end 454.448672 -205.877414)
		(width 0.20066)
		(layer "F.Cu")
		(net "M_H_CPU0_SB_DQ<21>")
	)
	(segment
		(start 457.968096 -205.816962)
		(end 457.53655 -205.385416)
		(width 0.20066)
		(layer "F.Cu")
		(net "M_H_CPU0_SB_DQ<21>")
	)
	(segment
		(start 454.448672 -205.877414)
		(end 454.260712 -206.065374)
		(width 0.20066)
		(layer "F.Cu")
		(net "M_H_CPU0_SB_DQ<21>")
	)
	(segment
		(start 375.087134 -228.99497)
		(end 375.08688 -228.994716)
		(width 0.20066)
		(layer "F.Cu")
		(net "M_H_CPU0_SB_DQ<21>")
	)
	(segment
		(start 457.120244 -205.391766)
		(end 454.931526 -205.391766)
		(width 0.1016)
		(layer "F.Cu")
		(net "M_H_CPU0_SB_DQ<21>")
	)
	(segment
		(start 453.536812 -205.816708)
		(end 452.016114 -205.816708)
		(width 0.20066)
		(layer "F.Cu")
		(net "M_H_CPU0_SB_DQ<21>")
	)
	(segment
		(start 441.569094 -204.54239)
		(end 437.81853 -204.54239)
		(width 0.18288)
		(layer "In6.Cu")
		(net "M_H_CPU0_SB_DQ<21>")
	)
	(segment
		(start 448.739514 -205.230984)
		(end 448.739514 -205.495652)
		(width 0.18288)
		(layer "In6.Cu")
		(net "M_H_CPU0_SB_DQ<21>")
	)
	(segment
		(start 429.077628 -206.750666)
		(end 428.917608 -206.590646)
		(width 0.18288)
		(layer "In6.Cu")
		(net "M_H_CPU0_SB_DQ<21>")
	)
	(segment
		(start 415.058352 -206.208376)
		(end 414.63849 -206.208376)
		(width 0.18288)
		(layer "In6.Cu")
		(net "M_H_CPU0_SB_DQ<21>")
	)
	(segment
		(start 429.611028 -206.590646)
		(end 429.451008 -206.750666)
		(width 0.18288)
		(layer "In6.Cu")
		(net "M_H_CPU0_SB_DQ<21>")
	)
	(segment
		(start 444.954152 -204.201776)
		(end 444.728092 -204.201776)
		(width 0.18288)
		(layer "In6.Cu")
		(net "M_H_CPU0_SB_DQ<21>")
	)
	(segment
		(start 446.536572 -205.070964)
		(end 446.1129 -205.494636)
		(width 0.18288)
		(layer "In6.Cu")
		(net "M_H_CPU0_SB_DQ<21>")
	)
	(segment
		(start 414.364932 -205.934818)
		(end 413.94507 -205.934818)
		(width 0.18288)
		(layer "In6.Cu")
		(net "M_H_CPU0_SB_DQ<21>")
	)
	(segment
		(start 448.899534 -205.070964)
		(end 448.739514 -205.230984)
		(width 0.18288)
		(layer "In6.Cu")
		(net "M_H_CPU0_SB_DQ<21>")
	)
	(segment
		(start 428.917608 -206.590646)
		(end 428.917608 -206.128874)
		(width 0.18288)
		(layer "In6.Cu")
		(net "M_H_CPU0_SB_DQ<21>")
	)
	(segment
		(start 433.1716 -206.44612)
		(end 431.409094 -206.44612)
		(width 0.18288)
		(layer "In6.Cu")
		(net "M_H_CPU0_SB_DQ<21>")
	)
	(segment
		(start 426.240194 -206.241142)
		(end 425.391326 -207.09001)
		(width 0.18288)
		(layer "In6.Cu")
		(net "M_H_CPU0_SB_DQ<21>")
	)
	(segment
		(start 416.454336 -205.934818)
		(end 415.33191 -205.934818)
		(width 0.18288)
		(layer "In6.Cu")
		(net "M_H_CPU0_SB_DQ<21>")
	)
	(segment
		(start 445.230504 -205.494636)
		(end 444.936372 -205.200504)
		(width 0.18288)
		(layer "In6.Cu")
		(net "M_H_CPU0_SB_DQ<21>")
	)
	(segment
		(start 443.143894 -204.347826)
		(end 442.604652 -204.887068)
		(width 0.18288)
		(layer "In6.Cu")
		(net "M_H_CPU0_SB_DQ<21>")
	)
	(segment
		(start 377.061984 -227.64496)
		(end 377.061984 -227.65258)
		(width 0.088646)
		(layer "In6.Cu")
		(net "M_H_CPU0_SB_DQ<21>")
	)
	(segment
		(start 386.53974 -225.57613)
		(end 384.88493 -227.23094)
		(width 0.088646)
		(layer "In6.Cu")
		(net "M_H_CPU0_SB_DQ<21>")
	)
	(segment
		(start 429.451008 -206.750666)
		(end 429.077628 -206.750666)
		(width 0.18288)
		(layer "In6.Cu")
		(net "M_H_CPU0_SB_DQ<21>")
	)
	(segment
		(start 376.779282 -228.134672)
		(end 376.770392 -228.139752)
		(width 0.088646)
		(layer "In6.Cu")
		(net "M_H_CPU0_SB_DQ<21>")
	)
	(segment
		(start 423.579798 -207.09001)
		(end 423.426382 -207.243426)
		(width 0.18288)
		(layer "In6.Cu")
		(net "M_H_CPU0_SB_DQ<21>")
	)
	(segment
		(start 429.771048 -205.968854)
		(end 429.611028 -206.128874)
		(width 0.18288)
		(layer "In6.Cu")
		(net "M_H_CPU0_SB_DQ<21>")
	)
	(segment
		(start 446.1129 -205.494636)
		(end 445.230504 -205.494636)
		(width 0.18288)
		(layer "In6.Cu")
		(net "M_H_CPU0_SB_DQ<21>")
	)
	(segment
		(start 405.396446 -206.079344)
		(end 401.165568 -210.310222)
		(width 0.18288)
		(layer "In6.Cu")
		(net "M_H_CPU0_SB_DQ<21>")
	)
	(segment
		(start 423.426382 -207.243426)
		(end 422.875202 -207.243426)
		(width 0.18288)
		(layer "In6.Cu")
		(net "M_H_CPU0_SB_DQ<21>")
	)
	(segment
		(start 413.635444 -206.244444)
		(end 411.461966 -206.244444)
		(width 0.18288)
		(layer "In6.Cu")
		(net "M_H_CPU0_SB_DQ<21>")
	)
	(segment
		(start 377.638564 -227.329238)
		(end 377.623832 -227.320602)
		(width 0.088646)
		(layer "In6.Cu")
		(net "M_H_CPU0_SB_DQ<21>")
	)
	(segment
		(start 445.218566 -204.69225)
		(end 445.218566 -204.46619)
		(width 0.18288)
		(layer "In6.Cu")
		(net "M_H_CPU0_SB_DQ<21>")
	)
	(segment
		(start 409.362402 -206.43088)
		(end 409.010866 -206.079344)
		(width 0.18288)
		(layer "In6.Cu")
		(net "M_H_CPU0_SB_DQ<21>")
	)
	(segment
		(start 431.409094 -206.430626)
		(end 430.947322 -205.968854)
		(width 0.18288)
		(layer "In6.Cu")
		(net "M_H_CPU0_SB_DQ<21>")
	)
	(segment
		(start 401.165568 -210.668108)
		(end 387.352286 -224.48139)
		(width 0.18288)
		(layer "In6.Cu")
		(net "M_H_CPU0_SB_DQ<21>")
	)
	(segment
		(start 411.461966 -206.244444)
		(end 411.115256 -205.897734)
		(width 0.18288)
		(layer "In6.Cu")
		(net "M_H_CPU0_SB_DQ<21>")
	)
	(segment
		(start 444.728092 -204.201776)
		(end 444.582042 -204.347826)
		(width 0.18288)
		(layer "In6.Cu")
		(net "M_H_CPU0_SB_DQ<21>")
	)
	(segment
		(start 413.94507 -205.934818)
		(end 413.635444 -206.244444)
		(width 0.18288)
		(layer "In6.Cu")
		(net "M_H_CPU0_SB_DQ<21>")
	)
	(segment
		(start 436.9689 -205.39202)
		(end 434.2257 -205.39202)
		(width 0.18288)
		(layer "In6.Cu")
		(net "M_H_CPU0_SB_DQ<21>")
	)
	(segment
		(start 375.700798 -228.91369)
		(end 375.08688 -228.45903)
		(width 0.088646)
		(layer "In6.Cu")
		(net "M_H_CPU0_SB_DQ<21>")
	)
	(segment
		(start 448.046094 -205.495652)
		(end 448.046094 -205.230984)
		(width 0.18288)
		(layer "In6.Cu")
		(net "M_H_CPU0_SB_DQ<21>")
	)
	(segment
		(start 444.936372 -205.200504)
		(end 444.936372 -204.974444)
		(width 0.18288)
		(layer "In6.Cu")
		(net "M_H_CPU0_SB_DQ<21>")
	)
	(segment
		(start 437.81853 -204.54239)
		(end 436.9689 -205.39202)
		(width 0.18288)
		(layer "In6.Cu")
		(net "M_H_CPU0_SB_DQ<21>")
	)
	(segment
		(start 441.913772 -204.887068)
		(end 441.569094 -204.54239)
		(width 0.18288)
		(layer "In6.Cu")
		(net "M_H_CPU0_SB_DQ<21>")
	)
	(segment
		(start 444.582042 -204.347826)
		(end 443.143894 -204.347826)
		(width 0.18288)
		(layer "In6.Cu")
		(net "M_H_CPU0_SB_DQ<21>")
	)
	(segment
		(start 450.911214 -205.816708)
		(end 450.16547 -205.070964)
		(width 0.18288)
		(layer "In6.Cu")
		(net "M_H_CPU0_SB_DQ<21>")
	)
	(segment
		(start 409.010866 -206.079344)
		(end 405.396446 -206.079344)
		(width 0.18288)
		(layer "In6.Cu")
		(net "M_H_CPU0_SB_DQ<21>")
	)
	(segment
		(start 401.165568 -210.310222)
		(end 401.165568 -210.668108)
		(width 0.18288)
		(layer "In6.Cu")
		(net "M_H_CPU0_SB_DQ<21>")
	)
	(segment
		(start 377.249436 -227.320602)
		(end 377.240546 -227.325682)
		(width 0.088646)
		(layer "In6.Cu")
		(net "M_H_CPU0_SB_DQ<21>")
	)
	(segment
		(start 448.046094 -205.230984)
		(end 447.886074 -205.070964)
		(width 0.18288)
		(layer "In6.Cu")
		(net "M_H_CPU0_SB_DQ<21>")
	)
	(segment
		(start 387.352286 -224.48139)
		(end 386.83057 -225.003106)
		(width 0.088646)
		(layer "In6.Cu")
		(net "M_H_CPU0_SB_DQ<21>")
	)
	(segment
		(start 448.579494 -205.655672)
		(end 448.206114 -205.655672)
		(width 0.18288)
		(layer "In6.Cu")
		(net "M_H_CPU0_SB_DQ<21>")
	)
	(segment
		(start 450.16547 -205.070964)
		(end 448.899534 -205.070964)
		(width 0.18288)
		(layer "In6.Cu")
		(net "M_H_CPU0_SB_DQ<21>")
	)
	(segment
		(start 410.209746 -206.43088)
		(end 409.362402 -206.43088)
		(width 0.18288)
		(layer "In6.Cu")
		(net "M_H_CPU0_SB_DQ<21>")
	)
	(segment
		(start 379.518164 -227.329238)
		(end 379.503432 -227.320602)
		(width 0.088646)
		(layer "In6.Cu")
		(net "M_H_CPU0_SB_DQ<21>")
	)
	(segment
		(start 447.886074 -205.070964)
		(end 446.536572 -205.070964)
		(width 0.18288)
		(layer "In6.Cu")
		(net "M_H_CPU0_SB_DQ<21>")
	)
	(segment
		(start 386.53974 -225.575876)
		(end 386.53974 -225.57613)
		(width 0.088646)
		(layer "In6.Cu")
		(net "M_H_CPU0_SB_DQ<21>")
	)
	(segment
		(start 422.875202 -207.243426)
		(end 421.874188 -206.242412)
		(width 0.18288)
		(layer "In6.Cu")
		(net "M_H_CPU0_SB_DQ<21>")
	)
	(segment
		(start 429.611028 -206.128874)
		(end 429.611028 -206.590646)
		(width 0.18288)
		(layer "In6.Cu")
		(net "M_H_CPU0_SB_DQ<21>")
	)
	(segment
		(start 382.337564 -227.329238)
		(end 382.322832 -227.320602)
		(width 0.088646)
		(layer "In6.Cu")
		(net "M_H_CPU0_SB_DQ<21>")
	)
	(segment
		(start 380.457964 -227.329238)
		(end 380.443232 -227.320602)
		(width 0.088646)
		(layer "In6.Cu")
		(net "M_H_CPU0_SB_DQ<21>")
	)
	(segment
		(start 445.218566 -204.46619)
		(end 444.954152 -204.201776)
		(width 0.18288)
		(layer "In6.Cu")
		(net "M_H_CPU0_SB_DQ<21>")
	)
	(segment
		(start 386.83057 -225.003106)
		(end 386.83057 -225.285046)
		(width 0.088646)
		(layer "In6.Cu")
		(net "M_H_CPU0_SB_DQ<21>")
	)
	(segment
		(start 430.947322 -205.968854)
		(end 429.771048 -205.968854)
		(width 0.18288)
		(layer "In6.Cu")
		(net "M_H_CPU0_SB_DQ<21>")
	)
	(segment
		(start 427.681644 -205.968854)
		(end 427.409356 -206.241142)
		(width 0.18288)
		(layer "In6.Cu")
		(net "M_H_CPU0_SB_DQ<21>")
	)
	(segment
		(start 425.391326 -207.09001)
		(end 423.579798 -207.09001)
		(width 0.18288)
		(layer "In6.Cu")
		(net "M_H_CPU0_SB_DQ<21>")
	)
	(segment
		(start 415.33191 -205.934818)
		(end 415.058352 -206.208376)
		(width 0.18288)
		(layer "In6.Cu")
		(net "M_H_CPU0_SB_DQ<21>")
	)
	(segment
		(start 386.83057 -225.285046)
		(end 386.53974 -225.575876)
		(width 0.088646)
		(layer "In6.Cu")
		(net "M_H_CPU0_SB_DQ<21>")
	)
	(segment
		(start 448.206114 -205.655672)
		(end 448.046094 -205.495652)
		(width 0.18288)
		(layer "In6.Cu")
		(net "M_H_CPU0_SB_DQ<21>")
	)
	(segment
		(start 428.757588 -205.968854)
		(end 427.681644 -205.968854)
		(width 0.18288)
		(layer "In6.Cu")
		(net "M_H_CPU0_SB_DQ<21>")
	)
	(segment
		(start 444.936372 -204.974444)
		(end 445.218566 -204.69225)
		(width 0.18288)
		(layer "In6.Cu")
		(net "M_H_CPU0_SB_DQ<21>")
	)
	(segment
		(start 421.874188 -206.242412)
		(end 416.76193 -206.242412)
		(width 0.18288)
		(layer "In6.Cu")
		(net "M_H_CPU0_SB_DQ<21>")
	)
	(segment
		(start 442.604652 -204.887068)
		(end 441.913772 -204.887068)
		(width 0.18288)
		(layer "In6.Cu")
		(net "M_H_CPU0_SB_DQ<21>")
	)
	(segment
		(start 414.63849 -206.208376)
		(end 414.364932 -205.934818)
		(width 0.18288)
		(layer "In6.Cu")
		(net "M_H_CPU0_SB_DQ<21>")
	)
	(segment
		(start 428.917608 -206.128874)
		(end 428.757588 -205.968854)
		(width 0.18288)
		(layer "In6.Cu")
		(net "M_H_CPU0_SB_DQ<21>")
	)
	(segment
		(start 416.76193 -206.242412)
		(end 416.454336 -205.934818)
		(width 0.18288)
		(layer "In6.Cu")
		(net "M_H_CPU0_SB_DQ<21>")
	)
	(segment
		(start 410.742892 -205.897734)
		(end 410.209746 -206.43088)
		(width 0.18288)
		(layer "In6.Cu")
		(net "M_H_CPU0_SB_DQ<21>")
	)
	(segment
		(start 427.409356 -206.241142)
		(end 426.240194 -206.241142)
		(width 0.18288)
		(layer "In6.Cu")
		(net "M_H_CPU0_SB_DQ<21>")
	)
	(segment
		(start 448.739514 -205.495652)
		(end 448.579494 -205.655672)
		(width 0.18288)
		(layer "In6.Cu")
		(net "M_H_CPU0_SB_DQ<21>")
	)
	(segment
		(start 376.59183 -228.45903)
		(end 376.59183 -228.474524)
		(width 0.088646)
		(layer "In6.Cu")
		(net "M_H_CPU0_SB_DQ<21>")
	)
	(segment
		(start 434.2257 -205.39202)
		(end 433.1716 -206.44612)
		(width 0.18288)
		(layer "In6.Cu")
		(net "M_H_CPU0_SB_DQ<21>")
	)
	(segment
		(start 411.115256 -205.897734)
		(end 410.742892 -205.897734)
		(width 0.18288)
		(layer "In6.Cu")
		(net "M_H_CPU0_SB_DQ<21>")
	)
	(segment
		(start 431.409094 -206.44612)
		(end 431.409094 -206.430626)
		(width 0.18288)
		(layer "In6.Cu")
		(net "M_H_CPU0_SB_DQ<21>")
	)
	(arc
		(start 384.767836 -227.320602)
		(mid 384.485134 -227.396378)
		(end 384.202432 -227.320602)
		(width 0.088646)
		(layer "In6.Cu")
		(net "M_H_CPU0_SB_DQ<21>")
	)
	(arc
		(start 384.202432 -227.320602)
		(mid 384.015234 -227.270459)
		(end 383.828036 -227.320602)
		(width 0.088646)
		(layer "In6.Cu")
		(net "M_H_CPU0_SB_DQ<21>")
	)
	(arc
		(start 378.189236 -227.320602)
		(mid 377.915037 -227.396437)
		(end 377.638564 -227.329238)
		(width 0.088646)
		(layer "In6.Cu")
		(net "M_H_CPU0_SB_DQ<21>")
	)
	(arc
		(start 382.888236 -227.320602)
		(mid 382.614037 -227.396437)
		(end 382.337564 -227.329238)
		(width 0.088646)
		(layer "In6.Cu")
		(net "M_H_CPU0_SB_DQ<21>")
	)
	(arc
		(start 377.240546 -227.325682)
		(mid 377.109632 -227.462042)
		(end 377.061984 -227.64496)
		(width 0.088646)
		(layer "In6.Cu")
		(net "M_H_CPU0_SB_DQ<21>")
	)
	(arc
		(start 376.59183 -228.474524)
		(mid 376.51246 -228.748258)
		(end 376.309636 -228.948488)
		(width 0.088646)
		(layer "In6.Cu")
		(net "M_H_CPU0_SB_DQ<21>")
	)
	(arc
		(start 379.503432 -227.320602)
		(mid 379.316234 -227.270459)
		(end 379.129036 -227.320602)
		(width 0.088646)
		(layer "In6.Cu")
		(net "M_H_CPU0_SB_DQ<21>")
	)
	(arc
		(start 383.828036 -227.320602)
		(mid 383.545334 -227.396378)
		(end 383.262632 -227.320602)
		(width 0.088646)
		(layer "In6.Cu")
		(net "M_H_CPU0_SB_DQ<21>")
	)
	(arc
		(start 381.008636 -227.320602)
		(mid 380.734437 -227.396437)
		(end 380.457964 -227.329238)
		(width 0.088646)
		(layer "In6.Cu")
		(net "M_H_CPU0_SB_DQ<21>")
	)
	(arc
		(start 384.88493 -227.23094)
		(mid 384.829325 -227.279614)
		(end 384.767836 -227.320602)
		(width 0.088646)
		(layer "In6.Cu")
		(net "M_H_CPU0_SB_DQ<21>")
	)
	(arc
		(start 381.383032 -227.320602)
		(mid 381.195834 -227.270459)
		(end 381.008636 -227.320602)
		(width 0.088646)
		(layer "In6.Cu")
		(net "M_H_CPU0_SB_DQ<21>")
	)
	(arc
		(start 381.948436 -227.320602)
		(mid 381.665734 -227.396378)
		(end 381.383032 -227.320602)
		(width 0.088646)
		(layer "In6.Cu")
		(net "M_H_CPU0_SB_DQ<21>")
	)
	(arc
		(start 376.770392 -228.139752)
		(mid 376.639478 -228.276112)
		(end 376.59183 -228.45903)
		(width 0.088646)
		(layer "In6.Cu")
		(net "M_H_CPU0_SB_DQ<21>")
	)
	(arc
		(start 379.129036 -227.320602)
		(mid 378.846334 -227.396378)
		(end 378.563632 -227.320602)
		(width 0.088646)
		(layer "In6.Cu")
		(net "M_H_CPU0_SB_DQ<21>")
	)
	(arc
		(start 383.262632 -227.320602)
		(mid 383.075434 -227.270459)
		(end 382.888236 -227.320602)
		(width 0.088646)
		(layer "In6.Cu")
		(net "M_H_CPU0_SB_DQ<21>")
	)
	(arc
		(start 377.623832 -227.320602)
		(mid 377.436634 -227.270459)
		(end 377.249436 -227.320602)
		(width 0.088646)
		(layer "In6.Cu")
		(net "M_H_CPU0_SB_DQ<21>")
	)
	(arc
		(start 378.563632 -227.320602)
		(mid 378.376434 -227.270459)
		(end 378.189236 -227.320602)
		(width 0.088646)
		(layer "In6.Cu")
		(net "M_H_CPU0_SB_DQ<21>")
	)
	(arc
		(start 376.309636 -228.948488)
		(mid 376.000024 -229.022101)
		(end 375.700798 -228.91369)
		(width 0.088646)
		(layer "In6.Cu")
		(net "M_H_CPU0_SB_DQ<21>")
	)
	(arc
		(start 382.322832 -227.320602)
		(mid 382.135634 -227.270459)
		(end 381.948436 -227.320602)
		(width 0.088646)
		(layer "In6.Cu")
		(net "M_H_CPU0_SB_DQ<21>")
	)
	(arc
		(start 377.061984 -227.65258)
		(mid 376.984355 -227.930993)
		(end 376.779282 -228.134672)
		(width 0.088646)
		(layer "In6.Cu")
		(net "M_H_CPU0_SB_DQ<21>")
	)
	(arc
		(start 380.068836 -227.320602)
		(mid 379.794637 -227.396437)
		(end 379.518164 -227.329238)
		(width 0.088646)
		(layer "In6.Cu")
		(net "M_H_CPU0_SB_DQ<21>")
	)
	(arc
		(start 380.443232 -227.320602)
		(mid 380.256034 -227.270459)
		(end 380.068836 -227.320602)
		(width 0.088646)
		(layer "In6.Cu")
		(net "M_H_CPU0_SB_DQ<21>")
	)
	(segment
		(start 374.61698 -229.808786)
		(end 374.617234 -229.808532)
		(width 0.20066)
		(layer "F.Cu")
		(net "M_H_CPU0_SB_DQ<20>")
	)
	(segment
		(start 454.260712 -207.765396)
		(end 453.785478 -207.765396)
		(width 0.20066)
		(layer "F.Cu")
		(net "M_H_CPU0_SB_DQ<20>")
	)
	(segment
		(start 457.126594 -207.085438)
		(end 457.120244 -207.091788)
		(width 0.1016)
		(layer "F.Cu")
		(net "M_H_CPU0_SB_DQ<20>")
	)
	(segment
		(start 457.968096 -207.516984)
		(end 457.53655 -207.085438)
		(width 0.20066)
		(layer "F.Cu")
		(net "M_H_CPU0_SB_DQ<20>")
	)
	(segment
		(start 454.95845 -207.091788)
		(end 454.91146 -207.091788)
		(width 0.101854)
		(layer "F.Cu")
		(net "M_H_CPU0_SB_DQ<20>")
	)
	(segment
		(start 457.120244 -207.091788)
		(end 454.95845 -207.091788)
		(width 0.1016)
		(layer "F.Cu")
		(net "M_H_CPU0_SB_DQ<20>")
	)
	(segment
		(start 454.448672 -207.209898)
		(end 454.448672 -207.577436)
		(width 0.20066)
		(layer "F.Cu")
		(net "M_H_CPU0_SB_DQ<20>")
	)
	(segment
		(start 457.53655 -207.085438)
		(end 457.126594 -207.085438)
		(width 0.20066)
		(layer "F.Cu")
		(net "M_H_CPU0_SB_DQ<20>")
	)
	(segment
		(start 374.617234 -229.808532)
		(end 374.617234 -229.272846)
		(width 0.20066)
		(layer "F.Cu")
		(net "M_H_CPU0_SB_DQ<20>")
	)
	(segment
		(start 459.55966 -207.516984)
		(end 457.968096 -207.516984)
		(width 0.20066)
		(layer "F.Cu")
		(net "M_H_CPU0_SB_DQ<20>")
	)
	(segment
		(start 454.91146 -207.091788)
		(end 454.566782 -207.091788)
		(width 0.20066)
		(layer "F.Cu")
		(net "M_H_CPU0_SB_DQ<20>")
	)
	(segment
		(start 453.536812 -207.51673)
		(end 452.016114 -207.51673)
		(width 0.20066)
		(layer "F.Cu")
		(net "M_H_CPU0_SB_DQ<20>")
	)
	(segment
		(start 454.566782 -207.091788)
		(end 454.448672 -207.209898)
		(width 0.20066)
		(layer "F.Cu")
		(net "M_H_CPU0_SB_DQ<20>")
	)
	(segment
		(start 453.785478 -207.765396)
		(end 453.536812 -207.51673)
		(width 0.20066)
		(layer "F.Cu")
		(net "M_H_CPU0_SB_DQ<20>")
	)
	(segment
		(start 454.448672 -207.577436)
		(end 454.260712 -207.765396)
		(width 0.20066)
		(layer "F.Cu")
		(net "M_H_CPU0_SB_DQ<20>")
	)
	(segment
		(start 452.016114 -207.51673)
		(end 450.911214 -207.51673)
		(width 0.20066)
		(layer "F.Cu")
		(net "M_H_CPU0_SB_DQ<20>")
	)
	(segment
		(start 459.559914 -207.51673)
		(end 459.55966 -207.516984)
		(width 0.20066)
		(layer "F.Cu")
		(net "M_H_CPU0_SB_DQ<20>")
	)
	(segment
		(start 421.682926 -209.18297)
		(end 421.395906 -209.18297)
		(width 0.18288)
		(layer "In6.Cu")
		(net "M_H_CPU0_SB_DQ<20>")
	)
	(segment
		(start 422.493186 -208.38541)
		(end 422.048686 -208.38541)
		(width 0.18288)
		(layer "In6.Cu")
		(net "M_H_CPU0_SB_DQ<20>")
	)
	(segment
		(start 431.582576 -208.305908)
		(end 431.129694 -207.853026)
		(width 0.18288)
		(layer "In6.Cu")
		(net "M_H_CPU0_SB_DQ<20>")
	)
	(segment
		(start 423.027602 -208.919826)
		(end 422.493186 -208.38541)
		(width 0.18288)
		(layer "In6.Cu")
		(net "M_H_CPU0_SB_DQ<20>")
	)
	(segment
		(start 428.964852 -208.355184)
		(end 428.551086 -207.941418)
		(width 0.18288)
		(layer "In6.Cu")
		(net "M_H_CPU0_SB_DQ<20>")
	)
	(segment
		(start 412.549086 -207.942434)
		(end 412.164276 -208.327244)
		(width 0.18288)
		(layer "In6.Cu")
		(net "M_H_CPU0_SB_DQ<20>")
	)
	(segment
		(start 387.620256 -225.62566)
		(end 386.57784 -226.668076)
		(width 0.088646)
		(layer "In6.Cu")
		(net "M_H_CPU0_SB_DQ<20>")
	)
	(segment
		(start 419.10762 -207.942434)
		(end 418.9476 -208.102454)
		(width 0.18288)
		(layer "In6.Cu")
		(net "M_H_CPU0_SB_DQ<20>")
	)
	(segment
		(start 446.376298 -207.014826)
		(end 446.061084 -207.33004)
		(width 0.18288)
		(layer "In6.Cu")
		(net "M_H_CPU0_SB_DQ<20>")
	)
	(segment
		(start 421.395906 -209.18297)
		(end 421.174926 -208.96199)
		(width 0.18288)
		(layer "In6.Cu")
		(net "M_H_CPU0_SB_DQ<20>")
	)
	(segment
		(start 430.269904 -207.853026)
		(end 429.767746 -208.355184)
		(width 0.18288)
		(layer "In6.Cu")
		(net "M_H_CPU0_SB_DQ<20>")
	)
	(segment
		(start 448.294252 -207.174846)
		(end 448.134232 -207.014826)
		(width 0.18288)
		(layer "In6.Cu")
		(net "M_H_CPU0_SB_DQ<20>")
	)
	(segment
		(start 428.551086 -207.941418)
		(end 426.380402 -207.941672)
		(width 0.18288)
		(layer "In6.Cu")
		(net "M_H_CPU0_SB_DQ<20>")
	)
	(segment
		(start 431.129694 -207.853026)
		(end 430.269904 -207.853026)
		(width 0.18288)
		(layer "In6.Cu")
		(net "M_H_CPU0_SB_DQ<20>")
	)
	(segment
		(start 418.9476 -208.102454)
		(end 418.9476 -208.797652)
		(width 0.18288)
		(layer "In6.Cu")
		(net "M_H_CPU0_SB_DQ<20>")
	)
	(segment
		(start 377.719082 -228.134672)
		(end 377.710192 -228.139752)
		(width 0.088646)
		(layer "In6.Cu")
		(net "M_H_CPU0_SB_DQ<20>")
	)
	(segment
		(start 375.758964 -229.588568)
		(end 375.744232 -229.597204)
		(width 0.088646)
		(layer "In6.Cu")
		(net "M_H_CPU0_SB_DQ<20>")
	)
	(segment
		(start 375.341134 -229.58044)
		(end 374.617234 -229.272846)
		(width 0.088646)
		(layer "In6.Cu")
		(net "M_H_CPU0_SB_DQ<20>")
	)
	(segment
		(start 420.97833 -207.942434)
		(end 419.10762 -207.942434)
		(width 0.18288)
		(layer "In6.Cu")
		(net "M_H_CPU0_SB_DQ<20>")
	)
	(segment
		(start 448.134232 -207.014826)
		(end 446.376298 -207.014826)
		(width 0.18288)
		(layer "In6.Cu")
		(net "M_H_CPU0_SB_DQ<20>")
	)
	(segment
		(start 423.462958 -208.919826)
		(end 423.027602 -208.919826)
		(width 0.18288)
		(layer "In6.Cu")
		(net "M_H_CPU0_SB_DQ<20>")
	)
	(segment
		(start 380.538736 -228.134672)
		(end 380.528322 -228.140768)
		(width 0.088646)
		(layer "In6.Cu")
		(net "M_H_CPU0_SB_DQ<20>")
	)
	(segment
		(start 421.174926 -208.96199)
		(end 421.174926 -208.13903)
		(width 0.18288)
		(layer "In6.Cu")
		(net "M_H_CPU0_SB_DQ<20>")
	)
	(segment
		(start 446.061084 -207.33004)
		(end 445.205104 -207.33004)
		(width 0.18288)
		(layer "In6.Cu")
		(net "M_H_CPU0_SB_DQ<20>")
	)
	(segment
		(start 448.827652 -207.69834)
		(end 448.454272 -207.69834)
		(width 0.18288)
		(layer "In6.Cu")
		(net "M_H_CPU0_SB_DQ<20>")
	)
	(segment
		(start 405.47671 -207.878426)
		(end 387.855206 -225.49993)
		(width 0.18288)
		(layer "In6.Cu")
		(net "M_H_CPU0_SB_DQ<20>")
	)
	(segment
		(start 386.57784 -226.668076)
		(end 386.468874 -226.930712)
		(width 0.088646)
		(layer "In6.Cu")
		(net "M_H_CPU0_SB_DQ<20>")
	)
	(segment
		(start 379.598682 -228.134672)
		(end 379.58395 -228.143308)
		(width 0.088646)
		(layer "In6.Cu")
		(net "M_H_CPU0_SB_DQ<20>")
	)
	(segment
		(start 426.023024 -208.79181)
		(end 423.591228 -208.791556)
		(width 0.18288)
		(layer "In6.Cu")
		(net "M_H_CPU0_SB_DQ<20>")
	)
	(segment
		(start 375.369836 -229.597204)
		(end 375.341134 -229.58044)
		(width 0.088646)
		(layer "In6.Cu")
		(net "M_H_CPU0_SB_DQ<20>")
	)
	(segment
		(start 445.205104 -207.33004)
		(end 443.97549 -206.100426)
		(width 0.18288)
		(layer "In6.Cu")
		(net "M_H_CPU0_SB_DQ<20>")
	)
	(segment
		(start 377.53163 -228.45903)
		(end 377.53163 -228.468936)
		(width 0.088646)
		(layer "In6.Cu")
		(net "M_H_CPU0_SB_DQ<20>")
	)
	(segment
		(start 443.16269 -206.100426)
		(end 442.635894 -206.627222)
		(width 0.18288)
		(layer "In6.Cu")
		(net "M_H_CPU0_SB_DQ<20>")
	)
	(segment
		(start 426.220382 -208.101692)
		(end 426.220382 -208.594452)
		(width 0.18288)
		(layer "In6.Cu")
		(net "M_H_CPU0_SB_DQ<20>")
	)
	(segment
		(start 429.767746 -208.355184)
		(end 428.964852 -208.355184)
		(width 0.18288)
		(layer "In6.Cu")
		(net "M_H_CPU0_SB_DQ<20>")
	)
	(segment
		(start 437.794908 -206.242412)
		(end 436.945024 -207.092296)
		(width 0.18288)
		(layer "In6.Cu")
		(net "M_H_CPU0_SB_DQ<20>")
	)
	(segment
		(start 418.25418 -208.797652)
		(end 418.25418 -208.102454)
		(width 0.18288)
		(layer "In6.Cu")
		(net "M_H_CPU0_SB_DQ<20>")
	)
	(segment
		(start 426.220382 -208.594452)
		(end 426.023024 -208.79181)
		(width 0.18288)
		(layer "In6.Cu")
		(net "M_H_CPU0_SB_DQ<20>")
	)
	(segment
		(start 408.803348 -207.878426)
		(end 405.47671 -207.878426)
		(width 0.18288)
		(layer "In6.Cu")
		(net "M_H_CPU0_SB_DQ<20>")
	)
	(segment
		(start 423.591228 -208.791556)
		(end 423.462958 -208.919826)
		(width 0.18288)
		(layer "In6.Cu")
		(net "M_H_CPU0_SB_DQ<20>")
	)
	(segment
		(start 449.147692 -207.014826)
		(end 448.987672 -207.174846)
		(width 0.18288)
		(layer "In6.Cu")
		(net "M_H_CPU0_SB_DQ<20>")
	)
	(segment
		(start 383.358136 -228.134672)
		(end 383.347722 -228.140768)
		(width 0.088646)
		(layer "In6.Cu")
		(net "M_H_CPU0_SB_DQ<20>")
	)
	(segment
		(start 436.945024 -207.092296)
		(end 434.100224 -207.092296)
		(width 0.18288)
		(layer "In6.Cu")
		(net "M_H_CPU0_SB_DQ<20>")
	)
	(segment
		(start 409.252166 -208.327244)
		(end 408.803348 -207.878426)
		(width 0.18288)
		(layer "In6.Cu")
		(net "M_H_CPU0_SB_DQ<20>")
	)
	(segment
		(start 426.380402 -207.941672)
		(end 426.220382 -208.101692)
		(width 0.18288)
		(layer "In6.Cu")
		(net "M_H_CPU0_SB_DQ<20>")
	)
	(segment
		(start 418.09416 -207.942434)
		(end 412.549086 -207.942434)
		(width 0.18288)
		(layer "In6.Cu")
		(net "M_H_CPU0_SB_DQ<20>")
	)
	(segment
		(start 378.658882 -228.134672)
		(end 378.64415 -228.143308)
		(width 0.088646)
		(layer "In6.Cu")
		(net "M_H_CPU0_SB_DQ<20>")
	)
	(segment
		(start 448.294252 -207.53832)
		(end 448.294252 -207.174846)
		(width 0.18288)
		(layer "In6.Cu")
		(net "M_H_CPU0_SB_DQ<20>")
	)
	(segment
		(start 440.676284 -206.242412)
		(end 437.794908 -206.242412)
		(width 0.18288)
		(layer "In6.Cu")
		(net "M_H_CPU0_SB_DQ<20>")
	)
	(segment
		(start 386.468874 -226.930712)
		(end 385.35483 -228.044756)
		(width 0.088646)
		(layer "In6.Cu")
		(net "M_H_CPU0_SB_DQ<20>")
	)
	(segment
		(start 448.454272 -207.69834)
		(end 448.294252 -207.53832)
		(width 0.18288)
		(layer "In6.Cu")
		(net "M_H_CPU0_SB_DQ<20>")
	)
	(segment
		(start 412.164276 -208.327244)
		(end 409.252166 -208.327244)
		(width 0.18288)
		(layer "In6.Cu")
		(net "M_H_CPU0_SB_DQ<20>")
	)
	(segment
		(start 450.911214 -207.51673)
		(end 450.40931 -207.014826)
		(width 0.18288)
		(layer "In6.Cu")
		(net "M_H_CPU0_SB_DQ<20>")
	)
	(segment
		(start 418.4142 -208.957672)
		(end 418.25418 -208.797652)
		(width 0.18288)
		(layer "In6.Cu")
		(net "M_H_CPU0_SB_DQ<20>")
	)
	(segment
		(start 421.865806 -208.56829)
		(end 421.865806 -209.00009)
		(width 0.18288)
		(layer "In6.Cu")
		(net "M_H_CPU0_SB_DQ<20>")
	)
	(segment
		(start 432.886612 -208.305908)
		(end 431.582576 -208.305908)
		(width 0.18288)
		(layer "In6.Cu")
		(net "M_H_CPU0_SB_DQ<20>")
	)
	(segment
		(start 442.635894 -206.627222)
		(end 441.061094 -206.627222)
		(width 0.18288)
		(layer "In6.Cu")
		(net "M_H_CPU0_SB_DQ<20>")
	)
	(segment
		(start 387.855206 -225.49993)
		(end 387.729476 -225.62566)
		(width 0.088646)
		(layer "In6.Cu")
		(net "M_H_CPU0_SB_DQ<20>")
	)
	(segment
		(start 422.048686 -208.38541)
		(end 421.865806 -208.56829)
		(width 0.18288)
		(layer "In6.Cu")
		(net "M_H_CPU0_SB_DQ<20>")
	)
	(segment
		(start 418.25418 -208.102454)
		(end 418.09416 -207.942434)
		(width 0.18288)
		(layer "In6.Cu")
		(net "M_H_CPU0_SB_DQ<20>")
	)
	(segment
		(start 450.40931 -207.014826)
		(end 449.147692 -207.014826)
		(width 0.18288)
		(layer "In6.Cu")
		(net "M_H_CPU0_SB_DQ<20>")
	)
	(segment
		(start 418.78758 -208.957672)
		(end 418.4142 -208.957672)
		(width 0.18288)
		(layer "In6.Cu")
		(net "M_H_CPU0_SB_DQ<20>")
	)
	(segment
		(start 377.080526 -229.15626)
		(end 376.85599 -229.400354)
		(width 0.088646)
		(layer "In6.Cu")
		(net "M_H_CPU0_SB_DQ<20>")
	)
	(segment
		(start 382.418082 -228.134672)
		(end 382.407668 -228.140768)
		(width 0.088646)
		(layer "In6.Cu")
		(net "M_H_CPU0_SB_DQ<20>")
	)
	(segment
		(start 434.100224 -207.092296)
		(end 432.886612 -208.305908)
		(width 0.18288)
		(layer "In6.Cu")
		(net "M_H_CPU0_SB_DQ<20>")
	)
	(segment
		(start 387.729476 -225.62566)
		(end 387.620256 -225.62566)
		(width 0.088646)
		(layer "In6.Cu")
		(net "M_H_CPU0_SB_DQ<20>")
	)
	(segment
		(start 443.97549 -206.100426)
		(end 443.16269 -206.100426)
		(width 0.18288)
		(layer "In6.Cu")
		(net "M_H_CPU0_SB_DQ<20>")
	)
	(segment
		(start 448.987672 -207.174846)
		(end 448.987672 -207.53832)
		(width 0.18288)
		(layer "In6.Cu")
		(net "M_H_CPU0_SB_DQ<20>")
	)
	(segment
		(start 448.987672 -207.53832)
		(end 448.827652 -207.69834)
		(width 0.18288)
		(layer "In6.Cu")
		(net "M_H_CPU0_SB_DQ<20>")
	)
	(segment
		(start 421.174926 -208.13903)
		(end 420.97833 -207.942434)
		(width 0.18288)
		(layer "In6.Cu")
		(net "M_H_CPU0_SB_DQ<20>")
	)
	(segment
		(start 418.9476 -208.797652)
		(end 418.78758 -208.957672)
		(width 0.18288)
		(layer "In6.Cu")
		(net "M_H_CPU0_SB_DQ<20>")
	)
	(segment
		(start 441.061094 -206.627222)
		(end 440.676284 -206.242412)
		(width 0.18288)
		(layer "In6.Cu")
		(net "M_H_CPU0_SB_DQ<20>")
	)
	(segment
		(start 421.865806 -209.00009)
		(end 421.682926 -209.18297)
		(width 0.18288)
		(layer "In6.Cu")
		(net "M_H_CPU0_SB_DQ<20>")
	)
	(arc
		(start 376.684032 -229.597204)
		(mid 376.496834 -229.647347)
		(end 376.309636 -229.597204)
		(width 0.088646)
		(layer "In6.Cu")
		(net "M_H_CPU0_SB_DQ<20>")
	)
	(arc
		(start 376.85599 -229.400354)
		(mid 376.785879 -229.51264)
		(end 376.684032 -229.597204)
		(width 0.088646)
		(layer "In6.Cu")
		(net "M_H_CPU0_SB_DQ<20>")
	)
	(arc
		(start 375.744232 -229.597204)
		(mid 375.557034 -229.647347)
		(end 375.369836 -229.597204)
		(width 0.088646)
		(layer "In6.Cu")
		(net "M_H_CPU0_SB_DQ<20>")
	)
	(arc
		(start 379.58395 -228.143308)
		(mid 379.307509 -228.210474)
		(end 379.033278 -228.134672)
		(width 0.088646)
		(layer "In6.Cu")
		(net "M_H_CPU0_SB_DQ<20>")
	)
	(arc
		(start 377.710192 -228.139752)
		(mid 377.579278 -228.276112)
		(end 377.53163 -228.45903)
		(width 0.088646)
		(layer "In6.Cu")
		(net "M_H_CPU0_SB_DQ<20>")
	)
	(arc
		(start 380.528322 -228.140768)
		(mid 380.24989 -228.210582)
		(end 379.973078 -228.134672)
		(width 0.088646)
		(layer "In6.Cu")
		(net "M_H_CPU0_SB_DQ<20>")
	)
	(arc
		(start 379.973078 -228.134672)
		(mid 379.78588 -228.084529)
		(end 379.598682 -228.134672)
		(width 0.088646)
		(layer "In6.Cu")
		(net "M_H_CPU0_SB_DQ<20>")
	)
	(arc
		(start 382.407668 -228.140768)
		(mid 382.12949 -228.21046)
		(end 381.852932 -228.134672)
		(width 0.088646)
		(layer "In6.Cu")
		(net "M_H_CPU0_SB_DQ<20>")
	)
	(arc
		(start 385.35483 -228.044756)
		(mid 385.299228 -228.093549)
		(end 385.237736 -228.134672)
		(width 0.088646)
		(layer "In6.Cu")
		(net "M_H_CPU0_SB_DQ<20>")
	)
	(arc
		(start 377.53163 -228.468936)
		(mid 377.453519 -228.745885)
		(end 377.249182 -228.948488)
		(width 0.088646)
		(layer "In6.Cu")
		(net "M_H_CPU0_SB_DQ<20>")
	)
	(arc
		(start 383.347722 -228.140768)
		(mid 383.06929 -228.210582)
		(end 382.792478 -228.134672)
		(width 0.088646)
		(layer "In6.Cu")
		(net "M_H_CPU0_SB_DQ<20>")
	)
	(arc
		(start 382.792478 -228.134672)
		(mid 382.60528 -228.084529)
		(end 382.418082 -228.134672)
		(width 0.088646)
		(layer "In6.Cu")
		(net "M_H_CPU0_SB_DQ<20>")
	)
	(arc
		(start 384.297936 -228.134672)
		(mid 384.015234 -228.210414)
		(end 383.732532 -228.134672)
		(width 0.088646)
		(layer "In6.Cu")
		(net "M_H_CPU0_SB_DQ<20>")
	)
	(arc
		(start 378.093478 -228.134672)
		(mid 377.90628 -228.084529)
		(end 377.719082 -228.134672)
		(width 0.088646)
		(layer "In6.Cu")
		(net "M_H_CPU0_SB_DQ<20>")
	)
	(arc
		(start 385.237736 -228.134672)
		(mid 384.955034 -228.210414)
		(end 384.672332 -228.134672)
		(width 0.088646)
		(layer "In6.Cu")
		(net "M_H_CPU0_SB_DQ<20>")
	)
	(arc
		(start 381.478536 -228.134672)
		(mid 381.195834 -228.210414)
		(end 380.913132 -228.134672)
		(width 0.088646)
		(layer "In6.Cu")
		(net "M_H_CPU0_SB_DQ<20>")
	)
	(arc
		(start 381.852932 -228.134672)
		(mid 381.665734 -228.084529)
		(end 381.478536 -228.134672)
		(width 0.088646)
		(layer "In6.Cu")
		(net "M_H_CPU0_SB_DQ<20>")
	)
	(arc
		(start 384.672332 -228.134672)
		(mid 384.485134 -228.084529)
		(end 384.297936 -228.134672)
		(width 0.088646)
		(layer "In6.Cu")
		(net "M_H_CPU0_SB_DQ<20>")
	)
	(arc
		(start 377.249182 -228.948488)
		(mid 377.145645 -229.036786)
		(end 377.080526 -229.15626)
		(width 0.088646)
		(layer "In6.Cu")
		(net "M_H_CPU0_SB_DQ<20>")
	)
	(arc
		(start 383.732532 -228.134672)
		(mid 383.545334 -228.084529)
		(end 383.358136 -228.134672)
		(width 0.088646)
		(layer "In6.Cu")
		(net "M_H_CPU0_SB_DQ<20>")
	)
	(arc
		(start 378.64415 -228.143308)
		(mid 378.367709 -228.210474)
		(end 378.093478 -228.134672)
		(width 0.088646)
		(layer "In6.Cu")
		(net "M_H_CPU0_SB_DQ<20>")
	)
	(arc
		(start 376.309636 -229.597204)
		(mid 376.035437 -229.521369)
		(end 375.758964 -229.588568)
		(width 0.088646)
		(layer "In6.Cu")
		(net "M_H_CPU0_SB_DQ<20>")
	)
	(arc
		(start 379.033278 -228.134672)
		(mid 378.84608 -228.084529)
		(end 378.658882 -228.134672)
		(width 0.088646)
		(layer "In6.Cu")
		(net "M_H_CPU0_SB_DQ<20>")
	)
	(arc
		(start 380.913132 -228.134672)
		(mid 380.725934 -228.084529)
		(end 380.538736 -228.134672)
		(width 0.088646)
		(layer "In6.Cu")
		(net "M_H_CPU0_SB_DQ<20>")
	)
	(segment
		(start 453.785478 -230.715312)
		(end 453.536812 -230.466646)
		(width 0.20066)
		(layer "F.Cu")
		(net "M_H_CPU0_SB_DQ<1>")
	)
	(segment
		(start 457.968096 -230.4669)
		(end 457.53655 -230.035354)
		(width 0.20066)
		(layer "F.Cu")
		(net "M_H_CPU0_SB_DQ<1>")
	)
	(segment
		(start 454.91146 -230.041704)
		(end 454.566782 -230.041704)
		(width 0.20066)
		(layer "F.Cu")
		(net "M_H_CPU0_SB_DQ<1>")
	)
	(segment
		(start 454.931526 -230.041704)
		(end 454.91146 -230.041704)
		(width 0.101854)
		(layer "F.Cu")
		(net "M_H_CPU0_SB_DQ<1>")
	)
	(segment
		(start 457.126594 -230.035354)
		(end 457.120244 -230.041704)
		(width 0.1016)
		(layer "F.Cu")
		(net "M_H_CPU0_SB_DQ<1>")
	)
	(segment
		(start 454.448672 -230.159814)
		(end 454.448672 -230.527352)
		(width 0.20066)
		(layer "F.Cu")
		(net "M_H_CPU0_SB_DQ<1>")
	)
	(segment
		(start 459.55966 -230.4669)
		(end 457.968096 -230.4669)
		(width 0.20066)
		(layer "F.Cu")
		(net "M_H_CPU0_SB_DQ<1>")
	)
	(segment
		(start 452.016114 -230.466646)
		(end 450.911214 -230.466646)
		(width 0.20066)
		(layer "F.Cu")
		(net "M_H_CPU0_SB_DQ<1>")
	)
	(segment
		(start 454.448672 -230.527352)
		(end 454.260712 -230.715312)
		(width 0.20066)
		(layer "F.Cu")
		(net "M_H_CPU0_SB_DQ<1>")
	)
	(segment
		(start 454.260712 -230.715312)
		(end 453.785478 -230.715312)
		(width 0.20066)
		(layer "F.Cu")
		(net "M_H_CPU0_SB_DQ<1>")
	)
	(segment
		(start 453.536812 -230.466646)
		(end 452.016114 -230.466646)
		(width 0.20066)
		(layer "F.Cu")
		(net "M_H_CPU0_SB_DQ<1>")
	)
	(segment
		(start 457.53655 -230.035354)
		(end 457.126594 -230.035354)
		(width 0.20066)
		(layer "F.Cu")
		(net "M_H_CPU0_SB_DQ<1>")
	)
	(segment
		(start 371.32768 -238.76127)
		(end 371.32768 -238.225584)
		(width 0.20066)
		(layer "F.Cu")
		(net "M_H_CPU0_SB_DQ<1>")
	)
	(segment
		(start 454.566782 -230.041704)
		(end 454.448672 -230.159814)
		(width 0.20066)
		(layer "F.Cu")
		(net "M_H_CPU0_SB_DQ<1>")
	)
	(segment
		(start 459.559914 -230.466646)
		(end 459.55966 -230.4669)
		(width 0.20066)
		(layer "F.Cu")
		(net "M_H_CPU0_SB_DQ<1>")
	)
	(segment
		(start 457.120244 -230.041704)
		(end 454.931526 -230.041704)
		(width 0.1016)
		(layer "F.Cu")
		(net "M_H_CPU0_SB_DQ<1>")
	)
	(segment
		(start 371.327934 -238.761524)
		(end 371.32768 -238.76127)
		(width 0.20066)
		(layer "F.Cu")
		(net "M_H_CPU0_SB_DQ<1>")
	)
	(segment
		(start 434.10505 -225.586036)
		(end 433.91201 -225.779076)
		(width 0.18288)
		(layer "In11.Cu")
		(net "M_H_CPU0_SB_DQ<1>")
	)
	(segment
		(start 450.911214 -230.466646)
		(end 450.911214 -230.19131)
		(width 0.18288)
		(layer "In11.Cu")
		(net "M_H_CPU0_SB_DQ<1>")
	)
	(segment
		(start 419.065202 -228.138736)
		(end 419.065202 -227.683822)
		(width 0.18288)
		(layer "In11.Cu")
		(net "M_H_CPU0_SB_DQ<1>")
	)
	(segment
		(start 393.72159 -238.466884)
		(end 389.043164 -238.466884)
		(width 0.18288)
		(layer "In11.Cu")
		(net "M_H_CPU0_SB_DQ<1>")
	)
	(segment
		(start 419.575742 -228.331776)
		(end 419.258242 -228.331776)
		(width 0.18288)
		(layer "In11.Cu")
		(net "M_H_CPU0_SB_DQ<1>")
	)
	(segment
		(start 419.961822 -227.490782)
		(end 419.768782 -227.683822)
		(width 0.18288)
		(layer "In11.Cu")
		(net "M_H_CPU0_SB_DQ<1>")
	)
	(segment
		(start 411.018228 -228.465888)
		(end 411.180534 -228.628194)
		(width 0.18288)
		(layer "In11.Cu")
		(net "M_H_CPU0_SB_DQ<1>")
	)
	(segment
		(start 410.247846 -228.963474)
		(end 410.018738 -229.192582)
		(width 0.18288)
		(layer "In11.Cu")
		(net "M_H_CPU0_SB_DQ<1>")
	)
	(segment
		(start 433.20843 -226.097338)
		(end 433.20843 -225.779076)
		(width 0.18288)
		(layer "In11.Cu")
		(net "M_H_CPU0_SB_DQ<1>")
	)
	(segment
		(start 412.232094 -227.893626)
		(end 411.317694 -227.893626)
		(width 0.18288)
		(layer "In11.Cu")
		(net "M_H_CPU0_SB_DQ<1>")
	)
	(segment
		(start 450.271642 -229.824026)
		(end 449.278756 -229.824026)
		(width 0.18288)
		(layer "In11.Cu")
		(net "M_H_CPU0_SB_DQ<1>")
	)
	(segment
		(start 429.805592 -226.323144)
		(end 429.612552 -226.516184)
		(width 0.18288)
		(layer "In11.Cu")
		(net "M_H_CPU0_SB_DQ<1>")
	)
	(segment
		(start 376.694446 -238.721138)
		(end 376.684032 -238.715042)
		(width 0.088646)
		(layer "In11.Cu")
		(net "M_H_CPU0_SB_DQ<1>")
	)
	(segment
		(start 442.289438 -227.411026)
		(end 441.797694 -227.411026)
		(width 0.18288)
		(layer "In11.Cu")
		(net "M_H_CPU0_SB_DQ<1>")
	)
	(segment
		(start 428.715932 -226.323144)
		(end 427.823376 -226.323144)
		(width 0.18288)
		(layer "In11.Cu")
		(net "M_H_CPU0_SB_DQ<1>")
	)
	(segment
		(start 412.46298 -228.124512)
		(end 412.232094 -227.893626)
		(width 0.18288)
		(layer "In11.Cu")
		(net "M_H_CPU0_SB_DQ<1>")
	)
	(segment
		(start 443.178438 -228.300026)
		(end 442.289438 -227.411026)
		(width 0.18288)
		(layer "In11.Cu")
		(net "M_H_CPU0_SB_DQ<1>")
	)
	(segment
		(start 441.797694 -227.411026)
		(end 441.027312 -226.640644)
		(width 0.18288)
		(layer "In11.Cu")
		(net "M_H_CPU0_SB_DQ<1>")
	)
	(segment
		(start 388.135622 -238.71301)
		(end 386.137404 -238.71301)
		(width 0.088646)
		(layer "In11.Cu")
		(net "M_H_CPU0_SB_DQ<1>")
	)
	(segment
		(start 411.018228 -228.193092)
		(end 411.018228 -228.465888)
		(width 0.18288)
		(layer "In11.Cu")
		(net "M_H_CPU0_SB_DQ<1>")
	)
	(segment
		(start 425.68241 -226.108768)
		(end 425.68241 -226.445826)
		(width 0.18288)
		(layer "In11.Cu")
		(net "M_H_CPU0_SB_DQ<1>")
	)
	(segment
		(start 419.258242 -228.331776)
		(end 419.065202 -228.138736)
		(width 0.18288)
		(layer "In11.Cu")
		(net "M_H_CPU0_SB_DQ<1>")
	)
	(segment
		(start 378.578364 -238.723678)
		(end 378.563632 -238.715042)
		(width 0.088646)
		(layer "In11.Cu")
		(net "M_H_CPU0_SB_DQ<1>")
	)
	(segment
		(start 386.137404 -238.71301)
		(end 386.12572 -238.701326)
		(width 0.088646)
		(layer "In11.Cu")
		(net "M_H_CPU0_SB_DQ<1>")
	)
	(segment
		(start 433.71897 -226.290378)
		(end 433.40147 -226.290378)
		(width 0.18288)
		(layer "In11.Cu")
		(net "M_H_CPU0_SB_DQ<1>")
	)
	(segment
		(start 449.085716 -230.017066)
		(end 449.085716 -230.304594)
		(width 0.18288)
		(layer "In11.Cu")
		(net "M_H_CPU0_SB_DQ<1>")
	)
	(segment
		(start 428.908972 -226.850702)
		(end 428.908972 -226.516184)
		(width 0.18288)
		(layer "In11.Cu")
		(net "M_H_CPU0_SB_DQ<1>")
	)
	(segment
		(start 448.382136 -230.017066)
		(end 448.189096 -229.824026)
		(width 0.18288)
		(layer "In11.Cu")
		(net "M_H_CPU0_SB_DQ<1>")
	)
	(segment
		(start 389.043164 -238.466884)
		(end 388.381748 -238.466884)
		(width 0.088646)
		(layer "In11.Cu")
		(net "M_H_CPU0_SB_DQ<1>")
	)
	(segment
		(start 425.87545 -225.915728)
		(end 425.68241 -226.108768)
		(width 0.18288)
		(layer "In11.Cu")
		(net "M_H_CPU0_SB_DQ<1>")
	)
	(segment
		(start 425.48937 -226.638866)
		(end 424.249342 -226.638866)
		(width 0.18288)
		(layer "In11.Cu")
		(net "M_H_CPU0_SB_DQ<1>")
	)
	(segment
		(start 429.102012 -227.043742)
		(end 428.908972 -226.850702)
		(width 0.18288)
		(layer "In11.Cu")
		(net "M_H_CPU0_SB_DQ<1>")
	)
	(segment
		(start 449.278756 -229.824026)
		(end 449.085716 -230.017066)
		(width 0.18288)
		(layer "In11.Cu")
		(net "M_H_CPU0_SB_DQ<1>")
	)
	(segment
		(start 374.819164 -238.723678)
		(end 374.804432 -238.715042)
		(width 0.088646)
		(layer "In11.Cu")
		(net "M_H_CPU0_SB_DQ<1>")
	)
	(segment
		(start 429.419512 -227.043742)
		(end 429.102012 -227.043742)
		(width 0.18288)
		(layer "In11.Cu")
		(net "M_H_CPU0_SB_DQ<1>")
	)
	(segment
		(start 435.146704 -225.586036)
		(end 434.10505 -225.586036)
		(width 0.18288)
		(layer "In11.Cu")
		(net "M_H_CPU0_SB_DQ<1>")
	)
	(segment
		(start 433.20843 -225.779076)
		(end 433.01539 -225.586036)
		(width 0.18288)
		(layer "In11.Cu")
		(net "M_H_CPU0_SB_DQ<1>")
	)
	(segment
		(start 416.851338 -227.490782)
		(end 416.217608 -228.124512)
		(width 0.18288)
		(layer "In11.Cu")
		(net "M_H_CPU0_SB_DQ<1>")
	)
	(segment
		(start 411.180534 -228.628194)
		(end 411.180534 -228.90099)
		(width 0.18288)
		(layer "In11.Cu")
		(net "M_H_CPU0_SB_DQ<1>")
	)
	(segment
		(start 448.189096 -229.824026)
		(end 446.953894 -229.824026)
		(width 0.18288)
		(layer "In11.Cu")
		(net "M_H_CPU0_SB_DQ<1>")
	)
	(segment
		(start 417.60902 -227.787454)
		(end 417.312348 -227.490782)
		(width 0.18288)
		(layer "In11.Cu")
		(net "M_H_CPU0_SB_DQ<1>")
	)
	(segment
		(start 439.27649 -226.642422)
		(end 438.597294 -225.963226)
		(width 0.18288)
		(layer "In11.Cu")
		(net "M_H_CPU0_SB_DQ<1>")
	)
	(segment
		(start 406.996646 -229.04577)
		(end 405.99995 -230.042466)
		(width 0.18288)
		(layer "In11.Cu")
		(net "M_H_CPU0_SB_DQ<1>")
	)
	(segment
		(start 418.872162 -227.490782)
		(end 418.3126 -227.490782)
		(width 0.18288)
		(layer "In11.Cu")
		(net "M_H_CPU0_SB_DQ<1>")
	)
	(segment
		(start 449.085716 -230.304594)
		(end 448.892676 -230.497634)
		(width 0.18288)
		(layer "In11.Cu")
		(net "M_H_CPU0_SB_DQ<1>")
	)
	(segment
		(start 448.892676 -230.497634)
		(end 448.575176 -230.497634)
		(width 0.18288)
		(layer "In11.Cu")
		(net "M_H_CPU0_SB_DQ<1>")
	)
	(segment
		(start 418.3126 -227.490782)
		(end 418.015928 -227.787454)
		(width 0.18288)
		(layer "In11.Cu")
		(net "M_H_CPU0_SB_DQ<1>")
	)
	(segment
		(start 419.768782 -227.683822)
		(end 419.768782 -228.138736)
		(width 0.18288)
		(layer "In11.Cu")
		(net "M_H_CPU0_SB_DQ<1>")
	)
	(segment
		(start 424.249342 -226.638866)
		(end 424.113452 -226.502976)
		(width 0.18288)
		(layer "In11.Cu")
		(net "M_H_CPU0_SB_DQ<1>")
	)
	(segment
		(start 446.310512 -229.180644)
		(end 444.761112 -229.180644)
		(width 0.18288)
		(layer "In11.Cu")
		(net "M_H_CPU0_SB_DQ<1>")
	)
	(segment
		(start 371.985032 -238.715042)
		(end 371.89283 -238.661194)
		(width 0.088646)
		(layer "In11.Cu")
		(net "M_H_CPU0_SB_DQ<1>")
	)
	(segment
		(start 436.18531 -225.963226)
		(end 436.012844 -225.79076)
		(width 0.18288)
		(layer "In11.Cu")
		(net "M_H_CPU0_SB_DQ<1>")
	)
	(segment
		(start 425.68241 -226.445826)
		(end 425.48937 -226.638866)
		(width 0.18288)
		(layer "In11.Cu")
		(net "M_H_CPU0_SB_DQ<1>")
	)
	(segment
		(start 416.217608 -228.124512)
		(end 412.46298 -228.124512)
		(width 0.18288)
		(layer "In11.Cu")
		(net "M_H_CPU0_SB_DQ<1>")
	)
	(segment
		(start 410.955744 -229.12578)
		(end 410.682948 -229.12578)
		(width 0.18288)
		(layer "In11.Cu")
		(net "M_H_CPU0_SB_DQ<1>")
	)
	(segment
		(start 411.180534 -228.90099)
		(end 410.955744 -229.12578)
		(width 0.18288)
		(layer "In11.Cu")
		(net "M_H_CPU0_SB_DQ<1>")
	)
	(segment
		(start 450.911214 -230.19131)
		(end 450.736462 -230.016558)
		(width 0.18288)
		(layer "In11.Cu")
		(net "M_H_CPU0_SB_DQ<1>")
	)
	(segment
		(start 450.736462 -230.016558)
		(end 450.271642 -229.824026)
		(width 0.18288)
		(layer "In11.Cu")
		(net "M_H_CPU0_SB_DQ<1>")
	)
	(segment
		(start 426.38599 -226.108768)
		(end 426.19295 -225.915728)
		(width 0.18288)
		(layer "In11.Cu")
		(net "M_H_CPU0_SB_DQ<1>")
	)
	(segment
		(start 408.693874 -229.04577)
		(end 406.996646 -229.04577)
		(width 0.18288)
		(layer "In11.Cu")
		(net "M_H_CPU0_SB_DQ<1>")
	)
	(segment
		(start 388.381748 -238.466884)
		(end 388.135622 -238.71301)
		(width 0.088646)
		(layer "In11.Cu")
		(net "M_H_CPU0_SB_DQ<1>")
	)
	(segment
		(start 436.012844 -225.79076)
		(end 435.351428 -225.79076)
		(width 0.18288)
		(layer "In11.Cu")
		(net "M_H_CPU0_SB_DQ<1>")
	)
	(segment
		(start 433.40147 -226.290378)
		(end 433.20843 -226.097338)
		(width 0.18288)
		(layer "In11.Cu")
		(net "M_H_CPU0_SB_DQ<1>")
	)
	(segment
		(start 446.953894 -229.824026)
		(end 446.310512 -229.180644)
		(width 0.18288)
		(layer "In11.Cu")
		(net "M_H_CPU0_SB_DQ<1>")
	)
	(segment
		(start 410.682948 -229.12578)
		(end 410.520642 -228.963474)
		(width 0.18288)
		(layer "In11.Cu")
		(net "M_H_CPU0_SB_DQ<1>")
	)
	(segment
		(start 421.675814 -227.490782)
		(end 419.961822 -227.490782)
		(width 0.18288)
		(layer "In11.Cu")
		(net "M_H_CPU0_SB_DQ<1>")
	)
	(segment
		(start 448.575176 -230.497634)
		(end 448.382136 -230.304594)
		(width 0.18288)
		(layer "In11.Cu")
		(net "M_H_CPU0_SB_DQ<1>")
	)
	(segment
		(start 417.312348 -227.490782)
		(end 416.851338 -227.490782)
		(width 0.18288)
		(layer "In11.Cu")
		(net "M_H_CPU0_SB_DQ<1>")
	)
	(segment
		(start 427.497494 -226.649026)
		(end 426.57903 -226.649026)
		(width 0.18288)
		(layer "In11.Cu")
		(net "M_H_CPU0_SB_DQ<1>")
	)
	(segment
		(start 443.880494 -228.300026)
		(end 443.178438 -228.300026)
		(width 0.18288)
		(layer "In11.Cu")
		(net "M_H_CPU0_SB_DQ<1>")
	)
	(segment
		(start 426.19295 -225.915728)
		(end 425.87545 -225.915728)
		(width 0.18288)
		(layer "In11.Cu")
		(net "M_H_CPU0_SB_DQ<1>")
	)
	(segment
		(start 431.758852 -225.586036)
		(end 431.021744 -226.323144)
		(width 0.18288)
		(layer "In11.Cu")
		(net "M_H_CPU0_SB_DQ<1>")
	)
	(segment
		(start 410.520642 -228.963474)
		(end 410.247846 -228.963474)
		(width 0.18288)
		(layer "In11.Cu")
		(net "M_H_CPU0_SB_DQ<1>")
	)
	(segment
		(start 426.57903 -226.649026)
		(end 426.38599 -226.455986)
		(width 0.18288)
		(layer "In11.Cu")
		(net "M_H_CPU0_SB_DQ<1>")
	)
	(segment
		(start 402.146008 -230.042466)
		(end 393.72159 -238.466884)
		(width 0.18288)
		(layer "In11.Cu")
		(net "M_H_CPU0_SB_DQ<1>")
	)
	(segment
		(start 433.01539 -225.586036)
		(end 431.758852 -225.586036)
		(width 0.18288)
		(layer "In11.Cu")
		(net "M_H_CPU0_SB_DQ<1>")
	)
	(segment
		(start 372.939564 -238.723678)
		(end 372.924832 -238.715042)
		(width 0.088646)
		(layer "In11.Cu")
		(net "M_H_CPU0_SB_DQ<1>")
	)
	(segment
		(start 438.597294 -225.963226)
		(end 436.18531 -225.963226)
		(width 0.18288)
		(layer "In11.Cu")
		(net "M_H_CPU0_SB_DQ<1>")
	)
	(segment
		(start 371.999764 -238.723678)
		(end 371.985032 -238.715042)
		(width 0.088646)
		(layer "In11.Cu")
		(net "M_H_CPU0_SB_DQ<1>")
	)
	(segment
		(start 411.317694 -227.893626)
		(end 411.018228 -228.193092)
		(width 0.18288)
		(layer "In11.Cu")
		(net "M_H_CPU0_SB_DQ<1>")
	)
	(segment
		(start 435.351428 -225.79076)
		(end 435.146704 -225.586036)
		(width 0.18288)
		(layer "In11.Cu")
		(net "M_H_CPU0_SB_DQ<1>")
	)
	(segment
		(start 418.015928 -227.787454)
		(end 417.60902 -227.787454)
		(width 0.18288)
		(layer "In11.Cu")
		(net "M_H_CPU0_SB_DQ<1>")
	)
	(segment
		(start 428.908972 -226.516184)
		(end 428.715932 -226.323144)
		(width 0.18288)
		(layer "In11.Cu")
		(net "M_H_CPU0_SB_DQ<1>")
	)
	(segment
		(start 419.065202 -227.683822)
		(end 418.872162 -227.490782)
		(width 0.18288)
		(layer "In11.Cu")
		(net "M_H_CPU0_SB_DQ<1>")
	)
	(segment
		(start 441.027312 -226.640644)
		(end 439.874406 -226.640644)
		(width 0.18288)
		(layer "In11.Cu")
		(net "M_H_CPU0_SB_DQ<1>")
	)
	(segment
		(start 433.91201 -226.097338)
		(end 433.71897 -226.290378)
		(width 0.18288)
		(layer "In11.Cu")
		(net "M_H_CPU0_SB_DQ<1>")
	)
	(segment
		(start 439.874406 -226.640644)
		(end 439.872628 -226.642422)
		(width 0.18288)
		(layer "In11.Cu")
		(net "M_H_CPU0_SB_DQ<1>")
	)
	(segment
		(start 433.91201 -225.779076)
		(end 433.91201 -226.097338)
		(width 0.18288)
		(layer "In11.Cu")
		(net "M_H_CPU0_SB_DQ<1>")
	)
	(segment
		(start 426.38599 -226.455986)
		(end 426.38599 -226.108768)
		(width 0.18288)
		(layer "In11.Cu")
		(net "M_H_CPU0_SB_DQ<1>")
	)
	(segment
		(start 375.758964 -238.723678)
		(end 375.744232 -238.715042)
		(width 0.088646)
		(layer "In11.Cu")
		(net "M_H_CPU0_SB_DQ<1>")
	)
	(segment
		(start 424.113452 -226.502976)
		(end 422.66362 -226.502976)
		(width 0.18288)
		(layer "In11.Cu")
		(net "M_H_CPU0_SB_DQ<1>")
	)
	(segment
		(start 429.612552 -226.516184)
		(end 429.612552 -226.850702)
		(width 0.18288)
		(layer "In11.Cu")
		(net "M_H_CPU0_SB_DQ<1>")
	)
	(segment
		(start 444.761112 -229.180644)
		(end 443.880494 -228.300026)
		(width 0.18288)
		(layer "In11.Cu")
		(net "M_H_CPU0_SB_DQ<1>")
	)
	(segment
		(start 429.612552 -226.850702)
		(end 429.419512 -227.043742)
		(width 0.18288)
		(layer "In11.Cu")
		(net "M_H_CPU0_SB_DQ<1>")
	)
	(segment
		(start 410.018738 -229.192582)
		(end 408.840686 -229.192582)
		(width 0.18288)
		(layer "In11.Cu")
		(net "M_H_CPU0_SB_DQ<1>")
	)
	(segment
		(start 379.518164 -238.723678)
		(end 379.503432 -238.715042)
		(width 0.088646)
		(layer "In11.Cu")
		(net "M_H_CPU0_SB_DQ<1>")
	)
	(segment
		(start 405.99995 -230.042466)
		(end 402.146008 -230.042466)
		(width 0.18288)
		(layer "In11.Cu")
		(net "M_H_CPU0_SB_DQ<1>")
	)
	(segment
		(start 419.768782 -228.138736)
		(end 419.575742 -228.331776)
		(width 0.18288)
		(layer "In11.Cu")
		(net "M_H_CPU0_SB_DQ<1>")
	)
	(segment
		(start 408.840686 -229.192582)
		(end 408.693874 -229.04577)
		(width 0.18288)
		(layer "In11.Cu")
		(net "M_H_CPU0_SB_DQ<1>")
	)
	(segment
		(start 422.66362 -226.502976)
		(end 421.675814 -227.490782)
		(width 0.18288)
		(layer "In11.Cu")
		(net "M_H_CPU0_SB_DQ<1>")
	)
	(segment
		(start 439.872628 -226.642422)
		(end 439.27649 -226.642422)
		(width 0.18288)
		(layer "In11.Cu")
		(net "M_H_CPU0_SB_DQ<1>")
	)
	(segment
		(start 448.382136 -230.304594)
		(end 448.382136 -230.017066)
		(width 0.18288)
		(layer "In11.Cu")
		(net "M_H_CPU0_SB_DQ<1>")
	)
	(segment
		(start 377.633992 -238.721138)
		(end 377.623578 -238.715042)
		(width 0.088646)
		(layer "In11.Cu")
		(net "M_H_CPU0_SB_DQ<1>")
	)
	(segment
		(start 431.021744 -226.323144)
		(end 429.805592 -226.323144)
		(width 0.18288)
		(layer "In11.Cu")
		(net "M_H_CPU0_SB_DQ<1>")
	)
	(segment
		(start 427.823376 -226.323144)
		(end 427.497494 -226.649026)
		(width 0.18288)
		(layer "In11.Cu")
		(net "M_H_CPU0_SB_DQ<1>")
	)
	(arc
		(start 384.202432 -238.715042)
		(mid 384.015234 -238.664899)
		(end 383.828036 -238.715042)
		(width 0.088646)
		(layer "In11.Cu")
		(net "M_H_CPU0_SB_DQ<1>")
	)
	(arc
		(start 379.129036 -238.715042)
		(mid 378.854837 -238.790877)
		(end 378.578364 -238.723678)
		(width 0.088646)
		(layer "In11.Cu")
		(net "M_H_CPU0_SB_DQ<1>")
	)
	(arc
		(start 371.89283 -238.661194)
		(mid 371.596227 -238.461589)
		(end 371.32768 -238.225584)
		(width 0.088646)
		(layer "In11.Cu")
		(net "M_H_CPU0_SB_DQ<1>")
	)
	(arc
		(start 376.684032 -238.715042)
		(mid 376.496834 -238.664899)
		(end 376.309636 -238.715042)
		(width 0.088646)
		(layer "In11.Cu")
		(net "M_H_CPU0_SB_DQ<1>")
	)
	(arc
		(start 386.010404 -238.683038)
		(mid 385.855633 -238.666929)
		(end 385.707636 -238.715042)
		(width 0.088646)
		(layer "In11.Cu")
		(net "M_H_CPU0_SB_DQ<1>")
	)
	(arc
		(start 372.550436 -238.715042)
		(mid 372.276237 -238.790877)
		(end 371.999764 -238.723678)
		(width 0.088646)
		(layer "In11.Cu")
		(net "M_H_CPU0_SB_DQ<1>")
	)
	(arc
		(start 377.623578 -238.715042)
		(mid 377.43638 -238.664899)
		(end 377.249182 -238.715042)
		(width 0.088646)
		(layer "In11.Cu")
		(net "M_H_CPU0_SB_DQ<1>")
	)
	(arc
		(start 375.744232 -238.715042)
		(mid 375.557034 -238.664899)
		(end 375.369836 -238.715042)
		(width 0.088646)
		(layer "In11.Cu")
		(net "M_H_CPU0_SB_DQ<1>")
	)
	(arc
		(start 381.008636 -238.715042)
		(mid 380.725934 -238.790818)
		(end 380.443232 -238.715042)
		(width 0.088646)
		(layer "In11.Cu")
		(net "M_H_CPU0_SB_DQ<1>")
	)
	(arc
		(start 373.490236 -238.715042)
		(mid 373.216037 -238.790877)
		(end 372.939564 -238.723678)
		(width 0.088646)
		(layer "In11.Cu")
		(net "M_H_CPU0_SB_DQ<1>")
	)
	(arc
		(start 385.142232 -238.715042)
		(mid 384.955034 -238.664899)
		(end 384.767836 -238.715042)
		(width 0.088646)
		(layer "In11.Cu")
		(net "M_H_CPU0_SB_DQ<1>")
	)
	(arc
		(start 375.369836 -238.715042)
		(mid 375.095637 -238.790877)
		(end 374.819164 -238.723678)
		(width 0.088646)
		(layer "In11.Cu")
		(net "M_H_CPU0_SB_DQ<1>")
	)
	(arc
		(start 377.249182 -238.715042)
		(mid 376.972623 -238.790785)
		(end 376.694446 -238.721138)
		(width 0.088646)
		(layer "In11.Cu")
		(net "M_H_CPU0_SB_DQ<1>")
	)
	(arc
		(start 381.948436 -238.715042)
		(mid 381.665734 -238.790818)
		(end 381.383032 -238.715042)
		(width 0.088646)
		(layer "In11.Cu")
		(net "M_H_CPU0_SB_DQ<1>")
	)
	(arc
		(start 374.430036 -238.715042)
		(mid 374.147334 -238.790818)
		(end 373.864632 -238.715042)
		(width 0.088646)
		(layer "In11.Cu")
		(net "M_H_CPU0_SB_DQ<1>")
	)
	(arc
		(start 380.443232 -238.715042)
		(mid 380.256034 -238.664899)
		(end 380.068836 -238.715042)
		(width 0.088646)
		(layer "In11.Cu")
		(net "M_H_CPU0_SB_DQ<1>")
	)
	(arc
		(start 378.189236 -238.715042)
		(mid 377.912423 -238.790912)
		(end 377.633992 -238.721138)
		(width 0.088646)
		(layer "In11.Cu")
		(net "M_H_CPU0_SB_DQ<1>")
	)
	(arc
		(start 374.804432 -238.715042)
		(mid 374.617234 -238.664899)
		(end 374.430036 -238.715042)
		(width 0.088646)
		(layer "In11.Cu")
		(net "M_H_CPU0_SB_DQ<1>")
	)
	(arc
		(start 386.12572 -238.701326)
		(mid 386.067344 -238.696707)
		(end 386.010404 -238.683038)
		(width 0.088646)
		(layer "In11.Cu")
		(net "M_H_CPU0_SB_DQ<1>")
	)
	(arc
		(start 373.864632 -238.715042)
		(mid 373.677434 -238.664899)
		(end 373.490236 -238.715042)
		(width 0.088646)
		(layer "In11.Cu")
		(net "M_H_CPU0_SB_DQ<1>")
	)
	(arc
		(start 384.767836 -238.715042)
		(mid 384.485134 -238.790818)
		(end 384.202432 -238.715042)
		(width 0.088646)
		(layer "In11.Cu")
		(net "M_H_CPU0_SB_DQ<1>")
	)
	(arc
		(start 379.503432 -238.715042)
		(mid 379.316234 -238.664899)
		(end 379.129036 -238.715042)
		(width 0.088646)
		(layer "In11.Cu")
		(net "M_H_CPU0_SB_DQ<1>")
	)
	(arc
		(start 381.383032 -238.715042)
		(mid 381.195834 -238.664899)
		(end 381.008636 -238.715042)
		(width 0.088646)
		(layer "In11.Cu")
		(net "M_H_CPU0_SB_DQ<1>")
	)
	(arc
		(start 378.563632 -238.715042)
		(mid 378.376434 -238.664899)
		(end 378.189236 -238.715042)
		(width 0.088646)
		(layer "In11.Cu")
		(net "M_H_CPU0_SB_DQ<1>")
	)
	(arc
		(start 372.924832 -238.715042)
		(mid 372.737634 -238.664899)
		(end 372.550436 -238.715042)
		(width 0.088646)
		(layer "In11.Cu")
		(net "M_H_CPU0_SB_DQ<1>")
	)
	(arc
		(start 383.828036 -238.715042)
		(mid 383.545334 -238.790818)
		(end 383.262632 -238.715042)
		(width 0.088646)
		(layer "In11.Cu")
		(net "M_H_CPU0_SB_DQ<1>")
	)
	(arc
		(start 382.888236 -238.715042)
		(mid 382.605534 -238.790818)
		(end 382.322832 -238.715042)
		(width 0.088646)
		(layer "In11.Cu")
		(net "M_H_CPU0_SB_DQ<1>")
	)
	(arc
		(start 376.309636 -238.715042)
		(mid 376.035437 -238.790877)
		(end 375.758964 -238.723678)
		(width 0.088646)
		(layer "In11.Cu")
		(net "M_H_CPU0_SB_DQ<1>")
	)
	(arc
		(start 385.707636 -238.715042)
		(mid 385.424934 -238.790818)
		(end 385.142232 -238.715042)
		(width 0.088646)
		(layer "In11.Cu")
		(net "M_H_CPU0_SB_DQ<1>")
	)
	(arc
		(start 382.322832 -238.715042)
		(mid 382.135634 -238.664899)
		(end 381.948436 -238.715042)
		(width 0.088646)
		(layer "In11.Cu")
		(net "M_H_CPU0_SB_DQ<1>")
	)
	(arc
		(start 380.068836 -238.715042)
		(mid 379.794637 -238.790877)
		(end 379.518164 -238.723678)
		(width 0.088646)
		(layer "In11.Cu")
		(net "M_H_CPU0_SB_DQ<1>")
	)
	(arc
		(start 383.262632 -238.715042)
		(mid 383.075434 -238.664899)
		(end 382.888236 -238.715042)
		(width 0.088646)
		(layer "In11.Cu")
		(net "M_H_CPU0_SB_DQ<1>")
	)
	(segment
		(start 461.455516 -211.149946)
		(end 461.455516 -210.898994)
		(width 0.20066)
		(layer "F.Cu")
		(net "M_H_CPU0_SB_DQ<19>")
	)
	(segment
		(start 458.24648 -211.348828)
		(end 458.538326 -211.348828)
		(width 0.20066)
		(layer "F.Cu")
		(net "M_H_CPU0_SB_DQ<19>")
	)
	(segment
		(start 461.689704 -210.664806)
		(end 462.073752 -210.664806)
		(width 0.20066)
		(layer "F.Cu")
		(net "M_H_CPU0_SB_DQ<19>")
	)
	(segment
		(start 460.558134 -211.341716)
		(end 460.570326 -211.353908)
		(width 0.1016)
		(layer "F.Cu")
		(net "M_H_CPU0_SB_DQ<19>")
	)
	(segment
		(start 376.49658 -230.900732)
		(end 376.496834 -230.900478)
		(width 0.20066)
		(layer "F.Cu")
		(net "M_H_CPU0_SB_DQ<19>")
	)
	(segment
		(start 455.011282 -210.916774)
		(end 456.116182 -210.916774)
		(width 0.20066)
		(layer "F.Cu")
		(net "M_H_CPU0_SB_DQ<19>")
	)
	(segment
		(start 461.455516 -210.898994)
		(end 461.689704 -210.664806)
		(width 0.20066)
		(layer "F.Cu")
		(net "M_H_CPU0_SB_DQ<19>")
	)
	(segment
		(start 462.073752 -210.664806)
		(end 462.32572 -210.916774)
		(width 0.20066)
		(layer "F.Cu")
		(net "M_H_CPU0_SB_DQ<19>")
	)
	(segment
		(start 456.116182 -210.916774)
		(end 457.814426 -210.916774)
		(width 0.20066)
		(layer "F.Cu")
		(net "M_H_CPU0_SB_DQ<19>")
	)
	(segment
		(start 458.538326 -211.348828)
		(end 458.543152 -211.348828)
		(width 0.101854)
		(layer "F.Cu")
		(net "M_H_CPU0_SB_DQ<19>")
	)
	(segment
		(start 458.543152 -211.348828)
		(end 458.550264 -211.341716)
		(width 0.1016)
		(layer "F.Cu")
		(net "M_H_CPU0_SB_DQ<19>")
	)
	(segment
		(start 461.251554 -211.353908)
		(end 461.455516 -211.149946)
		(width 0.20066)
		(layer "F.Cu")
		(net "M_H_CPU0_SB_DQ<19>")
	)
	(segment
		(start 462.32572 -210.916774)
		(end 463.659982 -210.916774)
		(width 0.20066)
		(layer "F.Cu")
		(net "M_H_CPU0_SB_DQ<19>")
	)
	(segment
		(start 457.814426 -210.916774)
		(end 458.24648 -211.348828)
		(width 0.20066)
		(layer "F.Cu")
		(net "M_H_CPU0_SB_DQ<19>")
	)
	(segment
		(start 460.570326 -211.353908)
		(end 461.251554 -211.353908)
		(width 0.20066)
		(layer "F.Cu")
		(net "M_H_CPU0_SB_DQ<19>")
	)
	(segment
		(start 376.49658 -231.436418)
		(end 376.49658 -230.900732)
		(width 0.20066)
		(layer "F.Cu")
		(net "M_H_CPU0_SB_DQ<19>")
	)
	(segment
		(start 458.550264 -211.341716)
		(end 460.558134 -211.341716)
		(width 0.1016)
		(layer "F.Cu")
		(net "M_H_CPU0_SB_DQ<19>")
	)
	(segment
		(start 448.762882 -210.761072)
		(end 448.389502 -210.761072)
		(width 0.18288)
		(layer "In6.Cu")
		(net "M_H_CPU0_SB_DQ<19>")
	)
	(segment
		(start 407.169366 -210.99526)
		(end 406.986486 -210.81238)
		(width 0.18288)
		(layer "In6.Cu")
		(net "M_H_CPU0_SB_DQ<19>")
	)
	(segment
		(start 377.638564 -231.2162)
		(end 377.623832 -231.224836)
		(width 0.088646)
		(layer "In6.Cu")
		(net "M_H_CPU0_SB_DQ<19>")
	)
	(segment
		(start 449.082922 -211.342224)
		(end 448.922902 -211.182204)
		(width 0.18288)
		(layer "In6.Cu")
		(net "M_H_CPU0_SB_DQ<19>")
	)
	(segment
		(start 379.983746 -230.404924)
		(end 379.973332 -230.41102)
		(width 0.088646)
		(layer "In6.Cu")
		(net "M_H_CPU0_SB_DQ<19>")
	)
	(segment
		(start 377.249436 -231.224836)
		(end 377.221496 -231.20858)
		(width 0.088646)
		(layer "In6.Cu")
		(net "M_H_CPU0_SB_DQ<19>")
	)
	(segment
		(start 387.21411 -228.28631)
		(end 386.90296 -228.28631)
		(width 0.088646)
		(layer "In6.Cu")
		(net "M_H_CPU0_SB_DQ<19>")
	)
	(segment
		(start 414.726628 -210.873848)
		(end 414.543748 -210.690968)
		(width 0.18288)
		(layer "In6.Cu")
		(net "M_H_CPU0_SB_DQ<19>")
	)
	(segment
		(start 438.444894 -211.561426)
		(end 437.225694 -211.561426)
		(width 0.18288)
		(layer "In6.Cu")
		(net "M_H_CPU0_SB_DQ<19>")
	)
	(segment
		(start 409.311348 -212.32368)
		(end 408.811984 -211.824316)
		(width 0.18288)
		(layer "In6.Cu")
		(net "M_H_CPU0_SB_DQ<19>")
	)
	(segment
		(start 410.4767 -212.32368)
		(end 409.311348 -212.32368)
		(width 0.18288)
		(layer "In6.Cu")
		(net "M_H_CPU0_SB_DQ<19>")
	)
	(segment
		(start 442.37275 -210.665568)
		(end 441.067952 -210.665568)
		(width 0.18288)
		(layer "In6.Cu")
		(net "M_H_CPU0_SB_DQ<19>")
	)
	(segment
		(start 381.478536 -230.41102)
		(end 381.468122 -230.404924)
		(width 0.088646)
		(layer "In6.Cu")
		(net "M_H_CPU0_SB_DQ<19>")
	)
	(segment
		(start 406.475946 -211.641436)
		(end 406.293066 -211.824316)
		(width 0.18288)
		(layer "In6.Cu")
		(net "M_H_CPU0_SB_DQ<19>")
	)
	(segment
		(start 448.922902 -211.182204)
		(end 448.922902 -210.921092)
		(width 0.18288)
		(layer "In6.Cu")
		(net "M_H_CPU0_SB_DQ<19>")
	)
	(segment
		(start 406.986486 -210.81238)
		(end 406.658826 -210.81238)
		(width 0.18288)
		(layer "In6.Cu")
		(net "M_H_CPU0_SB_DQ<19>")
	)
	(segment
		(start 414.543748 -210.690968)
		(end 414.216088 -210.690968)
		(width 0.18288)
		(layer "In6.Cu")
		(net "M_H_CPU0_SB_DQ<19>")
	)
	(segment
		(start 441.067952 -210.665568)
		(end 440.391042 -211.342478)
		(width 0.18288)
		(layer "In6.Cu")
		(net "M_H_CPU0_SB_DQ<19>")
	)
	(segment
		(start 448.229482 -210.921092)
		(end 448.229482 -211.182204)
		(width 0.18288)
		(layer "In6.Cu")
		(net "M_H_CPU0_SB_DQ<19>")
	)
	(segment
		(start 440.391042 -211.342478)
		(end 438.663842 -211.342478)
		(width 0.18288)
		(layer "In6.Cu")
		(net "M_H_CPU0_SB_DQ<19>")
	)
	(segment
		(start 427.905418 -211.553806)
		(end 427.072552 -212.386672)
		(width 0.18288)
		(layer "In6.Cu")
		(net "M_H_CPU0_SB_DQ<19>")
	)
	(segment
		(start 431.249074 -211.553806)
		(end 427.905418 -211.553806)
		(width 0.18288)
		(layer "In6.Cu")
		(net "M_H_CPU0_SB_DQ<19>")
	)
	(segment
		(start 451.675246 -211.342224)
		(end 449.082922 -211.342224)
		(width 0.18288)
		(layer "In6.Cu")
		(net "M_H_CPU0_SB_DQ<19>")
	)
	(segment
		(start 431.88763 -212.192362)
		(end 431.249074 -211.553806)
		(width 0.18288)
		(layer "In6.Cu")
		(net "M_H_CPU0_SB_DQ<19>")
	)
	(segment
		(start 416.973766 -212.374226)
		(end 415.940494 -211.340954)
		(width 0.18288)
		(layer "In6.Cu")
		(net "M_H_CPU0_SB_DQ<19>")
	)
	(segment
		(start 407.169366 -211.641436)
		(end 407.169366 -210.99526)
		(width 0.18288)
		(layer "In6.Cu")
		(net "M_H_CPU0_SB_DQ<19>")
	)
	(segment
		(start 406.293066 -211.824316)
		(end 405.137874 -211.824316)
		(width 0.18288)
		(layer "In6.Cu")
		(net "M_H_CPU0_SB_DQ<19>")
	)
	(segment
		(start 414.726628 -211.158074)
		(end 414.726628 -210.873848)
		(width 0.18288)
		(layer "In6.Cu")
		(net "M_H_CPU0_SB_DQ<19>")
	)
	(segment
		(start 386.72008 -228.46919)
		(end 386.72008 -229.3112)
		(width 0.088646)
		(layer "In6.Cu")
		(net "M_H_CPU0_SB_DQ<19>")
	)
	(segment
		(start 405.137874 -211.824316)
		(end 388.67588 -228.28631)
		(width 0.18288)
		(layer "In6.Cu")
		(net "M_H_CPU0_SB_DQ<19>")
	)
	(segment
		(start 411.459426 -211.340954)
		(end 410.4767 -212.32368)
		(width 0.18288)
		(layer "In6.Cu")
		(net "M_H_CPU0_SB_DQ<19>")
	)
	(segment
		(start 443.049406 -211.342224)
		(end 442.37275 -210.665568)
		(width 0.18288)
		(layer "In6.Cu")
		(net "M_H_CPU0_SB_DQ<19>")
	)
	(segment
		(start 452.421498 -212.088476)
		(end 451.675246 -211.342224)
		(width 0.18288)
		(layer "In6.Cu")
		(net "M_H_CPU0_SB_DQ<19>")
	)
	(segment
		(start 388.67588 -228.28631)
		(end 387.21411 -228.28631)
		(width 0.18288)
		(layer "In6.Cu")
		(net "M_H_CPU0_SB_DQ<19>")
	)
	(segment
		(start 436.594758 -212.192362)
		(end 431.88763 -212.192362)
		(width 0.18288)
		(layer "In6.Cu")
		(net "M_H_CPU0_SB_DQ<19>")
	)
	(segment
		(start 386.90296 -228.28631)
		(end 386.72008 -228.46919)
		(width 0.088646)
		(layer "In6.Cu")
		(net "M_H_CPU0_SB_DQ<19>")
	)
	(segment
		(start 414.033208 -210.873848)
		(end 414.033208 -211.158074)
		(width 0.18288)
		(layer "In6.Cu")
		(net "M_H_CPU0_SB_DQ<19>")
	)
	(segment
		(start 455.011282 -210.916774)
		(end 453.83958 -212.088476)
		(width 0.18288)
		(layer "In6.Cu")
		(net "M_H_CPU0_SB_DQ<19>")
	)
	(segment
		(start 407.352246 -211.824316)
		(end 407.169366 -211.641436)
		(width 0.18288)
		(layer "In6.Cu")
		(net "M_H_CPU0_SB_DQ<19>")
	)
	(segment
		(start 406.658826 -210.81238)
		(end 406.475946 -210.99526)
		(width 0.18288)
		(layer "In6.Cu")
		(net "M_H_CPU0_SB_DQ<19>")
	)
	(segment
		(start 417.693094 -212.374226)
		(end 416.973766 -212.374226)
		(width 0.18288)
		(layer "In6.Cu")
		(net "M_H_CPU0_SB_DQ<19>")
	)
	(segment
		(start 414.909508 -211.340954)
		(end 414.726628 -211.158074)
		(width 0.18288)
		(layer "In6.Cu")
		(net "M_H_CPU0_SB_DQ<19>")
	)
	(segment
		(start 415.940494 -211.340954)
		(end 414.909508 -211.340954)
		(width 0.18288)
		(layer "In6.Cu")
		(net "M_H_CPU0_SB_DQ<19>")
	)
	(segment
		(start 448.069462 -211.342224)
		(end 443.049406 -211.342224)
		(width 0.18288)
		(layer "In6.Cu")
		(net "M_H_CPU0_SB_DQ<19>")
	)
	(segment
		(start 422.181274 -213.0425)
		(end 421.33139 -213.892384)
		(width 0.18288)
		(layer "In6.Cu")
		(net "M_H_CPU0_SB_DQ<19>")
	)
	(segment
		(start 425.116244 -213.0425)
		(end 422.181274 -213.0425)
		(width 0.18288)
		(layer "In6.Cu")
		(net "M_H_CPU0_SB_DQ<19>")
	)
	(segment
		(start 419.211252 -213.892384)
		(end 417.693094 -212.374226)
		(width 0.18288)
		(layer "In6.Cu")
		(net "M_H_CPU0_SB_DQ<19>")
	)
	(segment
		(start 377.221496 -231.20858)
		(end 376.496834 -230.900478)
		(width 0.088646)
		(layer "In6.Cu")
		(net "M_H_CPU0_SB_DQ<19>")
	)
	(segment
		(start 414.216088 -210.690968)
		(end 414.033208 -210.873848)
		(width 0.18288)
		(layer "In6.Cu")
		(net "M_H_CPU0_SB_DQ<19>")
	)
	(segment
		(start 378.572522 -231.219756)
		(end 378.563632 -231.224836)
		(width 0.088646)
		(layer "In6.Cu")
		(net "M_H_CPU0_SB_DQ<19>")
	)
	(segment
		(start 448.229482 -211.182204)
		(end 448.069462 -211.342224)
		(width 0.18288)
		(layer "In6.Cu")
		(net "M_H_CPU0_SB_DQ<19>")
	)
	(segment
		(start 453.83958 -212.088476)
		(end 452.421498 -212.088476)
		(width 0.18288)
		(layer "In6.Cu")
		(net "M_H_CPU0_SB_DQ<19>")
	)
	(segment
		(start 437.225694 -211.561426)
		(end 436.594758 -212.192362)
		(width 0.18288)
		(layer "In6.Cu")
		(net "M_H_CPU0_SB_DQ<19>")
	)
	(segment
		(start 414.033208 -211.158074)
		(end 413.850328 -211.340954)
		(width 0.18288)
		(layer "In6.Cu")
		(net "M_H_CPU0_SB_DQ<19>")
	)
	(segment
		(start 379.598936 -230.41102)
		(end 379.588522 -230.404924)
		(width 0.088646)
		(layer "In6.Cu")
		(net "M_H_CPU0_SB_DQ<19>")
	)
	(segment
		(start 448.389502 -210.761072)
		(end 448.229482 -210.921092)
		(width 0.18288)
		(layer "In6.Cu")
		(net "M_H_CPU0_SB_DQ<19>")
	)
	(segment
		(start 408.811984 -211.824316)
		(end 407.352246 -211.824316)
		(width 0.18288)
		(layer "In6.Cu")
		(net "M_H_CPU0_SB_DQ<19>")
	)
	(segment
		(start 425.772072 -212.386672)
		(end 425.116244 -213.0425)
		(width 0.18288)
		(layer "In6.Cu")
		(net "M_H_CPU0_SB_DQ<19>")
	)
	(segment
		(start 427.072552 -212.386672)
		(end 425.772072 -212.386672)
		(width 0.18288)
		(layer "In6.Cu")
		(net "M_H_CPU0_SB_DQ<19>")
	)
	(segment
		(start 413.850328 -211.340954)
		(end 411.459426 -211.340954)
		(width 0.18288)
		(layer "In6.Cu")
		(net "M_H_CPU0_SB_DQ<19>")
	)
	(segment
		(start 378.751084 -230.884984)
		(end 378.751084 -230.900478)
		(width 0.088646)
		(layer "In6.Cu")
		(net "M_H_CPU0_SB_DQ<19>")
	)
	(segment
		(start 438.663842 -211.342478)
		(end 438.444894 -211.561426)
		(width 0.18288)
		(layer "In6.Cu")
		(net "M_H_CPU0_SB_DQ<19>")
	)
	(segment
		(start 448.922902 -210.921092)
		(end 448.762882 -210.761072)
		(width 0.18288)
		(layer "In6.Cu")
		(net "M_H_CPU0_SB_DQ<19>")
	)
	(segment
		(start 406.475946 -210.99526)
		(end 406.475946 -211.641436)
		(width 0.18288)
		(layer "In6.Cu")
		(net "M_H_CPU0_SB_DQ<19>")
	)
	(segment
		(start 386.72008 -229.3112)
		(end 385.646422 -230.384858)
		(width 0.088646)
		(layer "In6.Cu")
		(net "M_H_CPU0_SB_DQ<19>")
	)
	(segment
		(start 421.33139 -213.892384)
		(end 419.211252 -213.892384)
		(width 0.18288)
		(layer "In6.Cu")
		(net "M_H_CPU0_SB_DQ<19>")
	)
	(arc
		(start 377.623832 -231.224836)
		(mid 377.436634 -231.274979)
		(end 377.249436 -231.224836)
		(width 0.088646)
		(layer "In6.Cu")
		(net "M_H_CPU0_SB_DQ<19>")
	)
	(arc
		(start 381.468122 -230.404924)
		(mid 381.18969 -230.335078)
		(end 380.912878 -230.41102)
		(width 0.088646)
		(layer "In6.Cu")
		(net "M_H_CPU0_SB_DQ<19>")
	)
	(arc
		(start 379.588522 -230.404924)
		(mid 379.31009 -230.335078)
		(end 379.033278 -230.41102)
		(width 0.088646)
		(layer "In6.Cu")
		(net "M_H_CPU0_SB_DQ<19>")
	)
	(arc
		(start 379.033278 -230.41102)
		(mid 378.830455 -230.611251)
		(end 378.751084 -230.884984)
		(width 0.088646)
		(layer "In6.Cu")
		(net "M_H_CPU0_SB_DQ<19>")
	)
	(arc
		(start 382.418336 -230.41102)
		(mid 382.135634 -230.335244)
		(end 381.852932 -230.41102)
		(width 0.088646)
		(layer "In6.Cu")
		(net "M_H_CPU0_SB_DQ<19>")
	)
	(arc
		(start 378.189236 -231.224836)
		(mid 377.915007 -231.148911)
		(end 377.638564 -231.2162)
		(width 0.088646)
		(layer "In6.Cu")
		(net "M_H_CPU0_SB_DQ<19>")
	)
	(arc
		(start 378.563632 -231.224836)
		(mid 378.376434 -231.274979)
		(end 378.189236 -231.224836)
		(width 0.088646)
		(layer "In6.Cu")
		(net "M_H_CPU0_SB_DQ<19>")
	)
	(arc
		(start 379.973332 -230.41102)
		(mid 379.786134 -230.461163)
		(end 379.598936 -230.41102)
		(width 0.088646)
		(layer "In6.Cu")
		(net "M_H_CPU0_SB_DQ<19>")
	)
	(arc
		(start 381.852932 -230.41102)
		(mid 381.665734 -230.461163)
		(end 381.478536 -230.41102)
		(width 0.088646)
		(layer "In6.Cu")
		(net "M_H_CPU0_SB_DQ<19>")
	)
	(arc
		(start 385.612132 -230.41102)
		(mid 385.424934 -230.461163)
		(end 385.237736 -230.41102)
		(width 0.088646)
		(layer "In6.Cu")
		(net "M_H_CPU0_SB_DQ<19>")
	)
	(arc
		(start 385.646422 -230.384858)
		(mid 385.630153 -230.399088)
		(end 385.612132 -230.41102)
		(width 0.088646)
		(layer "In6.Cu")
		(net "M_H_CPU0_SB_DQ<19>")
	)
	(arc
		(start 385.237736 -230.41102)
		(mid 384.955034 -230.335244)
		(end 384.672332 -230.41102)
		(width 0.088646)
		(layer "In6.Cu")
		(net "M_H_CPU0_SB_DQ<19>")
	)
	(arc
		(start 380.912878 -230.41102)
		(mid 380.72568 -230.461163)
		(end 380.538482 -230.41102)
		(width 0.088646)
		(layer "In6.Cu")
		(net "M_H_CPU0_SB_DQ<19>")
	)
	(arc
		(start 384.672332 -230.41102)
		(mid 384.485134 -230.461163)
		(end 384.297936 -230.41102)
		(width 0.088646)
		(layer "In6.Cu")
		(net "M_H_CPU0_SB_DQ<19>")
	)
	(arc
		(start 378.751084 -230.900478)
		(mid 378.703405 -231.083378)
		(end 378.572522 -231.219756)
		(width 0.088646)
		(layer "In6.Cu")
		(net "M_H_CPU0_SB_DQ<19>")
	)
	(arc
		(start 382.792732 -230.41102)
		(mid 382.605534 -230.461163)
		(end 382.418336 -230.41102)
		(width 0.088646)
		(layer "In6.Cu")
		(net "M_H_CPU0_SB_DQ<19>")
	)
	(arc
		(start 380.538482 -230.41102)
		(mid 380.261923 -230.335277)
		(end 379.983746 -230.404924)
		(width 0.088646)
		(layer "In6.Cu")
		(net "M_H_CPU0_SB_DQ<19>")
	)
	(arc
		(start 383.358136 -230.41102)
		(mid 383.075434 -230.335244)
		(end 382.792732 -230.41102)
		(width 0.088646)
		(layer "In6.Cu")
		(net "M_H_CPU0_SB_DQ<19>")
	)
	(arc
		(start 384.297936 -230.41102)
		(mid 384.015234 -230.335244)
		(end 383.732532 -230.41102)
		(width 0.088646)
		(layer "In6.Cu")
		(net "M_H_CPU0_SB_DQ<19>")
	)
	(arc
		(start 383.732532 -230.41102)
		(mid 383.545334 -230.461163)
		(end 383.358136 -230.41102)
		(width 0.088646)
		(layer "In6.Cu")
		(net "M_H_CPU0_SB_DQ<19>")
	)
	(segment
		(start 458.543152 -213.04885)
		(end 458.550264 -213.041738)
		(width 0.1016)
		(layer "F.Cu")
		(net "M_H_CPU0_SB_DQ<18>")
	)
	(segment
		(start 461.689704 -212.364828)
		(end 462.073752 -212.364828)
		(width 0.20066)
		(layer "F.Cu")
		(net "M_H_CPU0_SB_DQ<18>")
	)
	(segment
		(start 461.455516 -212.599016)
		(end 461.689704 -212.364828)
		(width 0.20066)
		(layer "F.Cu")
		(net "M_H_CPU0_SB_DQ<18>")
	)
	(segment
		(start 376.02668 -232.250234)
		(end 376.02668 -231.714548)
		(width 0.20066)
		(layer "F.Cu")
		(net "M_H_CPU0_SB_DQ<18>")
	)
	(segment
		(start 455.011282 -212.616796)
		(end 456.116182 -212.616796)
		(width 0.20066)
		(layer "F.Cu")
		(net "M_H_CPU0_SB_DQ<18>")
	)
	(segment
		(start 461.455516 -212.849968)
		(end 461.455516 -212.599016)
		(width 0.20066)
		(layer "F.Cu")
		(net "M_H_CPU0_SB_DQ<18>")
	)
	(segment
		(start 462.073752 -212.364828)
		(end 462.32572 -212.616796)
		(width 0.20066)
		(layer "F.Cu")
		(net "M_H_CPU0_SB_DQ<18>")
	)
	(segment
		(start 462.32572 -212.616796)
		(end 463.659982 -212.616796)
		(width 0.20066)
		(layer "F.Cu")
		(net "M_H_CPU0_SB_DQ<18>")
	)
	(segment
		(start 457.814426 -212.616796)
		(end 458.24648 -213.04885)
		(width 0.20066)
		(layer "F.Cu")
		(net "M_H_CPU0_SB_DQ<18>")
	)
	(segment
		(start 456.116182 -212.616796)
		(end 457.814426 -212.616796)
		(width 0.20066)
		(layer "F.Cu")
		(net "M_H_CPU0_SB_DQ<18>")
	)
	(segment
		(start 458.24648 -213.04885)
		(end 458.538326 -213.04885)
		(width 0.20066)
		(layer "F.Cu")
		(net "M_H_CPU0_SB_DQ<18>")
	)
	(segment
		(start 376.026934 -232.250488)
		(end 376.02668 -232.250234)
		(width 0.20066)
		(layer "F.Cu")
		(net "M_H_CPU0_SB_DQ<18>")
	)
	(segment
		(start 460.570326 -213.05393)
		(end 461.251554 -213.05393)
		(width 0.20066)
		(layer "F.Cu")
		(net "M_H_CPU0_SB_DQ<18>")
	)
	(segment
		(start 458.550264 -213.041738)
		(end 460.558134 -213.041738)
		(width 0.1016)
		(layer "F.Cu")
		(net "M_H_CPU0_SB_DQ<18>")
	)
	(segment
		(start 460.558134 -213.041738)
		(end 460.570326 -213.05393)
		(width 0.1016)
		(layer "F.Cu")
		(net "M_H_CPU0_SB_DQ<18>")
	)
	(segment
		(start 461.251554 -213.05393)
		(end 461.455516 -212.849968)
		(width 0.20066)
		(layer "F.Cu")
		(net "M_H_CPU0_SB_DQ<18>")
	)
	(segment
		(start 458.538326 -213.04885)
		(end 458.543152 -213.04885)
		(width 0.101854)
		(layer "F.Cu")
		(net "M_H_CPU0_SB_DQ<18>")
	)
	(segment
		(start 386.764784 -229.913688)
		(end 386.764784 -230.56088)
		(width 0.088646)
		(layer "In6.Cu")
		(net "M_H_CPU0_SB_DQ<18>")
	)
	(segment
		(start 387.226556 -229.71379)
		(end 386.964682 -229.71379)
		(width 0.088646)
		(layer "In6.Cu")
		(net "M_H_CPU0_SB_DQ<18>")
	)
	(segment
		(start 428.899828 -214.547196)
		(end 428.659798 -214.787226)
		(width 0.18288)
		(layer "In6.Cu")
		(net "M_H_CPU0_SB_DQ<18>")
	)
	(segment
		(start 448.508374 -213.859872)
		(end 448.348354 -213.699852)
		(width 0.18288)
		(layer "In6.Cu")
		(net "M_H_CPU0_SB_DQ<18>")
	)
	(segment
		(start 425.30903 -214.742268)
		(end 421.911018 -214.742268)
		(width 0.18288)
		(layer "In6.Cu")
		(net "M_H_CPU0_SB_DQ<18>")
	)
	(segment
		(start 430.107598 -213.339426)
		(end 429.616362 -213.830662)
		(width 0.18288)
		(layer "In6.Cu")
		(net "M_H_CPU0_SB_DQ<18>")
	)
	(segment
		(start 425.538646 -214.512652)
		(end 425.30903 -214.742268)
		(width 0.18288)
		(layer "In6.Cu")
		(net "M_H_CPU0_SB_DQ<18>")
	)
	(segment
		(start 378.658882 -232.038906)
		(end 378.64415 -232.03027)
		(width 0.088646)
		(layer "In6.Cu")
		(net "M_H_CPU0_SB_DQ<18>")
	)
	(segment
		(start 449.041774 -213.202266)
		(end 449.041774 -213.699852)
		(width 0.18288)
		(layer "In6.Cu")
		(net "M_H_CPU0_SB_DQ<18>")
	)
	(segment
		(start 417.725606 -213.999826)
		(end 416.70224 -213.999826)
		(width 0.18288)
		(layer "In6.Cu")
		(net "M_H_CPU0_SB_DQ<18>")
	)
	(segment
		(start 429.095662 -213.536022)
		(end 428.869602 -213.536022)
		(width 0.18288)
		(layer "In6.Cu")
		(net "M_H_CPU0_SB_DQ<18>")
	)
	(segment
		(start 451.738746 -213.225126)
		(end 451.555866 -213.042246)
		(width 0.18288)
		(layer "In6.Cu")
		(net "M_H_CPU0_SB_DQ<18>")
	)
	(segment
		(start 452.432166 -213.762336)
		(end 452.249286 -213.945216)
		(width 0.18288)
		(layer "In6.Cu")
		(net "M_H_CPU0_SB_DQ<18>")
	)
	(segment
		(start 386.964682 -229.71379)
		(end 386.764784 -229.913688)
		(width 0.088646)
		(layer "In6.Cu")
		(net "M_H_CPU0_SB_DQ<18>")
	)
	(segment
		(start 452.249286 -213.945216)
		(end 451.921626 -213.945216)
		(width 0.18288)
		(layer "In6.Cu")
		(net "M_H_CPU0_SB_DQ<18>")
	)
	(segment
		(start 454.585832 -213.042246)
		(end 452.615046 -213.042246)
		(width 0.18288)
		(layer "In6.Cu")
		(net "M_H_CPU0_SB_DQ<18>")
	)
	(segment
		(start 436.95239 -213.89213)
		(end 431.809398 -213.89213)
		(width 0.18288)
		(layer "In6.Cu")
		(net "M_H_CPU0_SB_DQ<18>")
	)
	(segment
		(start 428.899828 -214.321136)
		(end 428.899828 -214.547196)
		(width 0.18288)
		(layer "In6.Cu")
		(net "M_H_CPU0_SB_DQ<18>")
	)
	(segment
		(start 428.869602 -213.536022)
		(end 428.605188 -213.800436)
		(width 0.18288)
		(layer "In6.Cu")
		(net "M_H_CPU0_SB_DQ<18>")
	)
	(segment
		(start 411.647894 -212.983826)
		(end 410.708094 -213.923626)
		(width 0.18288)
		(layer "In6.Cu")
		(net "M_H_CPU0_SB_DQ<18>")
	)
	(segment
		(start 451.921626 -213.945216)
		(end 451.738746 -213.762336)
		(width 0.18288)
		(layer "In6.Cu")
		(net "M_H_CPU0_SB_DQ<18>")
	)
	(segment
		(start 409.172156 -213.759288)
		(end 404.698708 -213.759288)
		(width 0.18288)
		(layer "In6.Cu")
		(net "M_H_CPU0_SB_DQ<18>")
	)
	(segment
		(start 427.37532 -214.512652)
		(end 425.538646 -214.512652)
		(width 0.18288)
		(layer "In6.Cu")
		(net "M_H_CPU0_SB_DQ<18>")
	)
	(segment
		(start 387.640322 -229.300024)
		(end 387.3373 -229.603046)
		(width 0.18288)
		(layer "In6.Cu")
		(net "M_H_CPU0_SB_DQ<18>")
	)
	(segment
		(start 376.779536 -232.038906)
		(end 376.750072 -232.021634)
		(width 0.088646)
		(layer "In6.Cu")
		(net "M_H_CPU0_SB_DQ<18>")
	)
	(segment
		(start 451.555866 -213.042246)
		(end 449.201794 -213.042246)
		(width 0.18288)
		(layer "In6.Cu")
		(net "M_H_CPU0_SB_DQ<18>")
	)
	(segment
		(start 404.698708 -213.759288)
		(end 389.157972 -229.300024)
		(width 0.18288)
		(layer "In6.Cu")
		(net "M_H_CPU0_SB_DQ<18>")
	)
	(segment
		(start 379.042168 -232.033826)
		(end 379.033278 -232.038906)
		(width 0.088646)
		(layer "In6.Cu")
		(net "M_H_CPU0_SB_DQ<18>")
	)
	(segment
		(start 449.201794 -213.042246)
		(end 449.041774 -213.202266)
		(width 0.18288)
		(layer "In6.Cu")
		(net "M_H_CPU0_SB_DQ<18>")
	)
	(segment
		(start 379.22073 -231.700324)
		(end 379.22073 -231.714548)
		(width 0.088646)
		(layer "In6.Cu")
		(net "M_H_CPU0_SB_DQ<18>")
	)
	(segment
		(start 451.738746 -213.762336)
		(end 451.738746 -213.225126)
		(width 0.18288)
		(layer "In6.Cu")
		(net "M_H_CPU0_SB_DQ<18>")
	)
	(segment
		(start 448.348354 -213.699852)
		(end 448.348354 -213.202266)
		(width 0.18288)
		(layer "In6.Cu")
		(net "M_H_CPU0_SB_DQ<18>")
	)
	(segment
		(start 431.256694 -213.339426)
		(end 430.107598 -213.339426)
		(width 0.18288)
		(layer "In6.Cu")
		(net "M_H_CPU0_SB_DQ<18>")
	)
	(segment
		(start 419.315646 -215.589866)
		(end 417.725606 -213.999826)
		(width 0.18288)
		(layer "In6.Cu")
		(net "M_H_CPU0_SB_DQ<18>")
	)
	(segment
		(start 448.881754 -213.859872)
		(end 448.508374 -213.859872)
		(width 0.18288)
		(layer "In6.Cu")
		(net "M_H_CPU0_SB_DQ<18>")
	)
	(segment
		(start 412.206694 -212.983826)
		(end 411.647894 -212.983826)
		(width 0.18288)
		(layer "In6.Cu")
		(net "M_H_CPU0_SB_DQ<18>")
	)
	(segment
		(start 455.011282 -212.616796)
		(end 454.585832 -213.042246)
		(width 0.18288)
		(layer "In6.Cu")
		(net "M_H_CPU0_SB_DQ<18>")
	)
	(segment
		(start 410.708094 -213.923626)
		(end 409.336494 -213.923626)
		(width 0.18288)
		(layer "In6.Cu")
		(net "M_H_CPU0_SB_DQ<18>")
	)
	(segment
		(start 428.605188 -214.026496)
		(end 428.899828 -214.321136)
		(width 0.18288)
		(layer "In6.Cu")
		(net "M_H_CPU0_SB_DQ<18>")
	)
	(segment
		(start 421.06342 -215.589866)
		(end 419.315646 -215.589866)
		(width 0.18288)
		(layer "In6.Cu")
		(net "M_H_CPU0_SB_DQ<18>")
	)
	(segment
		(start 409.336494 -213.923626)
		(end 409.172156 -213.759288)
		(width 0.18288)
		(layer "In6.Cu")
		(net "M_H_CPU0_SB_DQ<18>")
	)
	(segment
		(start 379.513846 -231.21874)
		(end 379.503432 -231.224836)
		(width 0.088646)
		(layer "In6.Cu")
		(net "M_H_CPU0_SB_DQ<18>")
	)
	(segment
		(start 452.615046 -213.042246)
		(end 452.432166 -213.225126)
		(width 0.18288)
		(layer "In6.Cu")
		(net "M_H_CPU0_SB_DQ<18>")
	)
	(segment
		(start 421.911018 -214.742268)
		(end 421.06342 -215.589866)
		(width 0.18288)
		(layer "In6.Cu")
		(net "M_H_CPU0_SB_DQ<18>")
	)
	(segment
		(start 377.719082 -232.038906)
		(end 377.708668 -232.03281)
		(width 0.088646)
		(layer "In6.Cu")
		(net "M_H_CPU0_SB_DQ<18>")
	)
	(segment
		(start 448.188334 -213.042246)
		(end 437.802274 -213.042246)
		(width 0.18288)
		(layer "In6.Cu")
		(net "M_H_CPU0_SB_DQ<18>")
	)
	(segment
		(start 449.041774 -213.699852)
		(end 448.881754 -213.859872)
		(width 0.18288)
		(layer "In6.Cu")
		(net "M_H_CPU0_SB_DQ<18>")
	)
	(segment
		(start 427.649894 -214.787226)
		(end 427.37532 -214.512652)
		(width 0.18288)
		(layer "In6.Cu")
		(net "M_H_CPU0_SB_DQ<18>")
	)
	(segment
		(start 448.348354 -213.202266)
		(end 448.188334 -213.042246)
		(width 0.18288)
		(layer "In6.Cu")
		(net "M_H_CPU0_SB_DQ<18>")
	)
	(segment
		(start 431.809398 -213.89213)
		(end 431.256694 -213.339426)
		(width 0.18288)
		(layer "In6.Cu")
		(net "M_H_CPU0_SB_DQ<18>")
	)
	(segment
		(start 376.750072 -232.021634)
		(end 376.02668 -231.714548)
		(width 0.088646)
		(layer "In6.Cu")
		(net "M_H_CPU0_SB_DQ<18>")
	)
	(segment
		(start 389.157972 -229.300024)
		(end 387.640322 -229.300024)
		(width 0.18288)
		(layer "In6.Cu")
		(net "M_H_CPU0_SB_DQ<18>")
	)
	(segment
		(start 387.3373 -229.603046)
		(end 387.226556 -229.71379)
		(width 0.088646)
		(layer "In6.Cu")
		(net "M_H_CPU0_SB_DQ<18>")
	)
	(segment
		(start 429.390302 -213.830662)
		(end 429.095662 -213.536022)
		(width 0.18288)
		(layer "In6.Cu")
		(net "M_H_CPU0_SB_DQ<18>")
	)
	(segment
		(start 386.764784 -230.56088)
		(end 386.16001 -231.165654)
		(width 0.088646)
		(layer "In6.Cu")
		(net "M_H_CPU0_SB_DQ<18>")
	)
	(segment
		(start 412.460694 -213.237826)
		(end 412.206694 -212.983826)
		(width 0.18288)
		(layer "In6.Cu")
		(net "M_H_CPU0_SB_DQ<18>")
	)
	(segment
		(start 437.802274 -213.042246)
		(end 436.95239 -213.89213)
		(width 0.18288)
		(layer "In6.Cu")
		(net "M_H_CPU0_SB_DQ<18>")
	)
	(segment
		(start 452.432166 -213.225126)
		(end 452.432166 -213.762336)
		(width 0.18288)
		(layer "In6.Cu")
		(net "M_H_CPU0_SB_DQ<18>")
	)
	(segment
		(start 416.70224 -213.999826)
		(end 415.94024 -213.237826)
		(width 0.18288)
		(layer "In6.Cu")
		(net "M_H_CPU0_SB_DQ<18>")
	)
	(segment
		(start 428.659798 -214.787226)
		(end 427.649894 -214.787226)
		(width 0.18288)
		(layer "In6.Cu")
		(net "M_H_CPU0_SB_DQ<18>")
	)
	(segment
		(start 429.616362 -213.830662)
		(end 429.390302 -213.830662)
		(width 0.18288)
		(layer "In6.Cu")
		(net "M_H_CPU0_SB_DQ<18>")
	)
	(segment
		(start 428.605188 -213.800436)
		(end 428.605188 -214.026496)
		(width 0.18288)
		(layer "In6.Cu")
		(net "M_H_CPU0_SB_DQ<18>")
	)
	(segment
		(start 415.94024 -213.237826)
		(end 412.460694 -213.237826)
		(width 0.18288)
		(layer "In6.Cu")
		(net "M_H_CPU0_SB_DQ<18>")
	)
	(segment
		(start 380.453392 -231.21874)
		(end 380.442978 -231.224836)
		(width 0.088646)
		(layer "In6.Cu")
		(net "M_H_CPU0_SB_DQ<18>")
	)
	(arc
		(start 380.442978 -231.224836)
		(mid 380.25578 -231.274979)
		(end 380.068582 -231.224836)
		(width 0.088646)
		(layer "In6.Cu")
		(net "M_H_CPU0_SB_DQ<18>")
	)
	(arc
		(start 386.082032 -231.224836)
		(mid 385.894834 -231.274979)
		(end 385.707636 -231.224836)
		(width 0.088646)
		(layer "In6.Cu")
		(net "M_H_CPU0_SB_DQ<18>")
	)
	(arc
		(start 381.008636 -231.224836)
		(mid 380.731823 -231.149)
		(end 380.453392 -231.21874)
		(width 0.088646)
		(layer "In6.Cu")
		(net "M_H_CPU0_SB_DQ<18>")
	)
	(arc
		(start 378.64415 -232.03027)
		(mid 378.367675 -231.96295)
		(end 378.093478 -232.038906)
		(width 0.088646)
		(layer "In6.Cu")
		(net "M_H_CPU0_SB_DQ<18>")
	)
	(arc
		(start 382.888236 -231.224836)
		(mid 382.605534 -231.149094)
		(end 382.322832 -231.224836)
		(width 0.088646)
		(layer "In6.Cu")
		(net "M_H_CPU0_SB_DQ<18>")
	)
	(arc
		(start 378.093478 -232.038906)
		(mid 377.90628 -232.089049)
		(end 377.719082 -232.038906)
		(width 0.088646)
		(layer "In6.Cu")
		(net "M_H_CPU0_SB_DQ<18>")
	)
	(arc
		(start 383.262632 -231.224836)
		(mid 383.075434 -231.274979)
		(end 382.888236 -231.224836)
		(width 0.088646)
		(layer "In6.Cu")
		(net "M_H_CPU0_SB_DQ<18>")
	)
	(arc
		(start 381.948436 -231.224836)
		(mid 381.665734 -231.149094)
		(end 381.383032 -231.224836)
		(width 0.088646)
		(layer "In6.Cu")
		(net "M_H_CPU0_SB_DQ<18>")
	)
	(arc
		(start 379.22073 -231.714548)
		(mid 379.173051 -231.897448)
		(end 379.042168 -232.033826)
		(width 0.088646)
		(layer "In6.Cu")
		(net "M_H_CPU0_SB_DQ<18>")
	)
	(arc
		(start 386.16001 -231.165654)
		(mid 386.12296 -231.1978)
		(end 386.082032 -231.224836)
		(width 0.088646)
		(layer "In6.Cu")
		(net "M_H_CPU0_SB_DQ<18>")
	)
	(arc
		(start 380.068582 -231.224836)
		(mid 379.792023 -231.149127)
		(end 379.513846 -231.21874)
		(width 0.088646)
		(layer "In6.Cu")
		(net "M_H_CPU0_SB_DQ<18>")
	)
	(arc
		(start 385.707636 -231.224836)
		(mid 385.424934 -231.149094)
		(end 385.142232 -231.224836)
		(width 0.088646)
		(layer "In6.Cu")
		(net "M_H_CPU0_SB_DQ<18>")
	)
	(arc
		(start 384.767836 -231.224836)
		(mid 384.485134 -231.149094)
		(end 384.202432 -231.224836)
		(width 0.088646)
		(layer "In6.Cu")
		(net "M_H_CPU0_SB_DQ<18>")
	)
	(arc
		(start 379.033278 -232.038906)
		(mid 378.84608 -232.089049)
		(end 378.658882 -232.038906)
		(width 0.088646)
		(layer "In6.Cu")
		(net "M_H_CPU0_SB_DQ<18>")
	)
	(arc
		(start 381.383032 -231.224836)
		(mid 381.195834 -231.274979)
		(end 381.008636 -231.224836)
		(width 0.088646)
		(layer "In6.Cu")
		(net "M_H_CPU0_SB_DQ<18>")
	)
	(arc
		(start 384.202432 -231.224836)
		(mid 384.015234 -231.274979)
		(end 383.828036 -231.224836)
		(width 0.088646)
		(layer "In6.Cu")
		(net "M_H_CPU0_SB_DQ<18>")
	)
	(arc
		(start 382.322832 -231.224836)
		(mid 382.135634 -231.274979)
		(end 381.948436 -231.224836)
		(width 0.088646)
		(layer "In6.Cu")
		(net "M_H_CPU0_SB_DQ<18>")
	)
	(arc
		(start 383.828036 -231.224836)
		(mid 383.545334 -231.149094)
		(end 383.262632 -231.224836)
		(width 0.088646)
		(layer "In6.Cu")
		(net "M_H_CPU0_SB_DQ<18>")
	)
	(arc
		(start 385.142232 -231.224836)
		(mid 384.955034 -231.274979)
		(end 384.767836 -231.224836)
		(width 0.088646)
		(layer "In6.Cu")
		(net "M_H_CPU0_SB_DQ<18>")
	)
	(arc
		(start 377.153932 -232.038906)
		(mid 376.966734 -232.089049)
		(end 376.779536 -232.038906)
		(width 0.088646)
		(layer "In6.Cu")
		(net "M_H_CPU0_SB_DQ<18>")
	)
	(arc
		(start 377.708668 -232.03281)
		(mid 377.43049 -231.963087)
		(end 377.153932 -232.038906)
		(width 0.088646)
		(layer "In6.Cu")
		(net "M_H_CPU0_SB_DQ<18>")
	)
	(arc
		(start 379.503432 -231.224836)
		(mid 379.299951 -231.42564)
		(end 379.22073 -231.700324)
		(width 0.088646)
		(layer "In6.Cu")
		(net "M_H_CPU0_SB_DQ<18>")
	)
	(segment
		(start 457.120244 -211.341716)
		(end 454.931526 -211.341716)
		(width 0.1016)
		(layer "F.Cu")
		(net "M_H_CPU0_SB_DQ<17>")
	)
	(segment
		(start 454.260712 -212.015324)
		(end 453.785478 -212.015324)
		(width 0.20066)
		(layer "F.Cu")
		(net "M_H_CPU0_SB_DQ<17>")
	)
	(segment
		(start 452.016114 -211.766658)
		(end 450.911214 -211.766658)
		(width 0.20066)
		(layer "F.Cu")
		(net "M_H_CPU0_SB_DQ<17>")
	)
	(segment
		(start 374.61698 -231.436418)
		(end 374.61698 -230.900732)
		(width 0.20066)
		(layer "F.Cu")
		(net "M_H_CPU0_SB_DQ<17>")
	)
	(segment
		(start 454.448672 -211.459826)
		(end 454.448672 -211.827364)
		(width 0.20066)
		(layer "F.Cu")
		(net "M_H_CPU0_SB_DQ<17>")
	)
	(segment
		(start 454.91146 -211.341716)
		(end 454.566782 -211.341716)
		(width 0.20066)
		(layer "F.Cu")
		(net "M_H_CPU0_SB_DQ<17>")
	)
	(segment
		(start 454.566782 -211.341716)
		(end 454.448672 -211.459826)
		(width 0.20066)
		(layer "F.Cu")
		(net "M_H_CPU0_SB_DQ<17>")
	)
	(segment
		(start 457.53655 -211.335366)
		(end 457.126594 -211.335366)
		(width 0.20066)
		(layer "F.Cu")
		(net "M_H_CPU0_SB_DQ<17>")
	)
	(segment
		(start 459.559914 -211.766658)
		(end 459.55966 -211.766912)
		(width 0.20066)
		(layer "F.Cu")
		(net "M_H_CPU0_SB_DQ<17>")
	)
	(segment
		(start 459.55966 -211.766912)
		(end 457.968096 -211.766912)
		(width 0.20066)
		(layer "F.Cu")
		(net "M_H_CPU0_SB_DQ<17>")
	)
	(segment
		(start 374.61698 -230.900732)
		(end 374.617234 -230.900478)
		(width 0.20066)
		(layer "F.Cu")
		(net "M_H_CPU0_SB_DQ<17>")
	)
	(segment
		(start 453.785478 -212.015324)
		(end 453.536812 -211.766658)
		(width 0.20066)
		(layer "F.Cu")
		(net "M_H_CPU0_SB_DQ<17>")
	)
	(segment
		(start 454.448672 -211.827364)
		(end 454.260712 -212.015324)
		(width 0.20066)
		(layer "F.Cu")
		(net "M_H_CPU0_SB_DQ<17>")
	)
	(segment
		(start 454.931526 -211.341716)
		(end 454.91146 -211.341716)
		(width 0.101854)
		(layer "F.Cu")
		(net "M_H_CPU0_SB_DQ<17>")
	)
	(segment
		(start 457.126594 -211.335366)
		(end 457.120244 -211.341716)
		(width 0.1016)
		(layer "F.Cu")
		(net "M_H_CPU0_SB_DQ<17>")
	)
	(segment
		(start 453.536812 -211.766658)
		(end 452.016114 -211.766658)
		(width 0.20066)
		(layer "F.Cu")
		(net "M_H_CPU0_SB_DQ<17>")
	)
	(segment
		(start 457.968096 -211.766912)
		(end 457.53655 -211.335366)
		(width 0.20066)
		(layer "F.Cu")
		(net "M_H_CPU0_SB_DQ<17>")
	)
	(segment
		(start 422.042082 -213.89213)
		(end 421.192198 -214.742014)
		(width 0.18288)
		(layer "In6.Cu")
		(net "M_H_CPU0_SB_DQ<17>")
	)
	(segment
		(start 378.658882 -231.39019)
		(end 378.64415 -231.398826)
		(width 0.088646)
		(layer "In6.Cu")
		(net "M_H_CPU0_SB_DQ<17>")
	)
	(segment
		(start 436.532274 -213.041992)
		(end 431.84826 -213.041992)
		(width 0.18288)
		(layer "In6.Cu")
		(net "M_H_CPU0_SB_DQ<17>")
	)
	(segment
		(start 376.779536 -231.39019)
		(end 376.769122 -231.396286)
		(width 0.088646)
		(layer "In6.Cu")
		(net "M_H_CPU0_SB_DQ<17>")
	)
	(segment
		(start 374.683274 -230.950262)
		(end 374.617234 -230.900478)
		(width 0.088646)
		(layer "In6.Cu")
		(net "M_H_CPU0_SB_DQ<17>")
	)
	(segment
		(start 440.819794 -212.009228)
		(end 440.636914 -212.192108)
		(width 0.18288)
		(layer "In6.Cu")
		(net "M_H_CPU0_SB_DQ<17>")
	)
	(segment
		(start 426.37329 -212.894672)
		(end 425.99991 -212.894672)
		(width 0.18288)
		(layer "In6.Cu")
		(net "M_H_CPU0_SB_DQ<17>")
	)
	(segment
		(start 440.819794 -211.638388)
		(end 440.819794 -212.009228)
		(width 0.18288)
		(layer "In6.Cu")
		(net "M_H_CPU0_SB_DQ<17>")
	)
	(segment
		(start 427.80839 -213.89213)
		(end 426.69333 -213.89213)
		(width 0.18288)
		(layer "In6.Cu")
		(net "M_H_CPU0_SB_DQ<17>")
	)
	(segment
		(start 407.23185 -212.509354)
		(end 407.04897 -212.326474)
		(width 0.18288)
		(layer "In6.Cu")
		(net "M_H_CPU0_SB_DQ<17>")
	)
	(segment
		(start 407.23185 -213.008464)
		(end 407.23185 -212.509354)
		(width 0.18288)
		(layer "In6.Cu")
		(net "M_H_CPU0_SB_DQ<17>")
	)
	(segment
		(start 416.683444 -212.964776)
		(end 415.640266 -211.921598)
		(width 0.18288)
		(layer "In6.Cu")
		(net "M_H_CPU0_SB_DQ<17>")
	)
	(segment
		(start 421.192198 -214.742014)
		(end 419.324282 -214.742014)
		(width 0.18288)
		(layer "In6.Cu")
		(net "M_H_CPU0_SB_DQ<17>")
	)
	(segment
		(start 380.453392 -230.582216)
		(end 380.442978 -230.57612)
		(width 0.088646)
		(layer "In6.Cu")
		(net "M_H_CPU0_SB_DQ<17>")
	)
	(segment
		(start 414.689798 -212.104478)
		(end 414.689798 -212.52815)
		(width 0.18288)
		(layer "In6.Cu")
		(net "M_H_CPU0_SB_DQ<17>")
	)
	(segment
		(start 388.924038 -228.794056)
		(end 387.21411 -228.794056)
		(width 0.18288)
		(layer "In6.Cu")
		(net "M_H_CPU0_SB_DQ<17>")
	)
	(segment
		(start 412.710122 -211.921598)
		(end 412.270194 -212.361526)
		(width 0.18288)
		(layer "In6.Cu")
		(net "M_H_CPU0_SB_DQ<17>")
	)
	(segment
		(start 409.158694 -212.933026)
		(end 408.900376 -213.191344)
		(width 0.18288)
		(layer "In6.Cu")
		(net "M_H_CPU0_SB_DQ<17>")
	)
	(segment
		(start 413.996378 -212.104478)
		(end 413.813498 -211.921598)
		(width 0.18288)
		(layer "In6.Cu")
		(net "M_H_CPU0_SB_DQ<17>")
	)
	(segment
		(start 441.002674 -211.455508)
		(end 440.819794 -211.638388)
		(width 0.18288)
		(layer "In6.Cu")
		(net "M_H_CPU0_SB_DQ<17>")
	)
	(segment
		(start 425.83989 -213.73211)
		(end 425.67987 -213.89213)
		(width 0.18288)
		(layer "In6.Cu")
		(net "M_H_CPU0_SB_DQ<17>")
	)
	(segment
		(start 411.381194 -212.361526)
		(end 410.809694 -212.933026)
		(width 0.18288)
		(layer "In6.Cu")
		(net "M_H_CPU0_SB_DQ<17>")
	)
	(segment
		(start 450.911214 -211.766658)
		(end 450.498464 -212.192108)
		(width 0.18288)
		(layer "In6.Cu")
		(net "M_H_CPU0_SB_DQ<17>")
	)
	(segment
		(start 414.872678 -211.921598)
		(end 414.689798 -212.104478)
		(width 0.18288)
		(layer "In6.Cu")
		(net "M_H_CPU0_SB_DQ<17>")
	)
	(segment
		(start 441.513214 -211.638388)
		(end 441.330334 -211.455508)
		(width 0.18288)
		(layer "In6.Cu")
		(net "M_H_CPU0_SB_DQ<17>")
	)
	(segment
		(start 441.513214 -212.009228)
		(end 441.513214 -211.638388)
		(width 0.18288)
		(layer "In6.Cu")
		(net "M_H_CPU0_SB_DQ<17>")
	)
	(segment
		(start 424.140122 -214.190072)
		(end 423.744644 -214.190072)
		(width 0.18288)
		(layer "In6.Cu")
		(net "M_H_CPU0_SB_DQ<17>")
	)
	(segment
		(start 448.166744 -212.192108)
		(end 441.696094 -212.192108)
		(width 0.18288)
		(layer "In6.Cu")
		(net "M_H_CPU0_SB_DQ<17>")
	)
	(segment
		(start 419.324282 -214.742014)
		(end 417.547044 -212.964776)
		(width 0.18288)
		(layer "In6.Cu")
		(net "M_H_CPU0_SB_DQ<17>")
	)
	(segment
		(start 414.689798 -212.52815)
		(end 414.506918 -212.71103)
		(width 0.18288)
		(layer "In6.Cu")
		(net "M_H_CPU0_SB_DQ<17>")
	)
	(segment
		(start 410.809694 -212.933026)
		(end 409.158694 -212.933026)
		(width 0.18288)
		(layer "In6.Cu")
		(net "M_H_CPU0_SB_DQ<17>")
	)
	(segment
		(start 449.180204 -212.192108)
		(end 449.020184 -212.352128)
		(width 0.18288)
		(layer "In6.Cu")
		(net "M_H_CPU0_SB_DQ<17>")
	)
	(segment
		(start 379.129036 -230.57612)
		(end 379.120146 -230.5812)
		(width 0.088646)
		(layer "In6.Cu")
		(net "M_H_CPU0_SB_DQ<17>")
	)
	(segment
		(start 441.696094 -212.192108)
		(end 441.513214 -212.009228)
		(width 0.18288)
		(layer "In6.Cu")
		(net "M_H_CPU0_SB_DQ<17>")
	)
	(segment
		(start 426.53331 -213.73211)
		(end 426.53331 -213.054692)
		(width 0.18288)
		(layer "In6.Cu")
		(net "M_H_CPU0_SB_DQ<17>")
	)
	(segment
		(start 448.326764 -212.352128)
		(end 448.166744 -212.192108)
		(width 0.18288)
		(layer "In6.Cu")
		(net "M_H_CPU0_SB_DQ<17>")
	)
	(segment
		(start 375.839482 -231.39019)
		(end 375.82475 -231.398826)
		(width 0.088646)
		(layer "In6.Cu")
		(net "M_H_CPU0_SB_DQ<17>")
	)
	(segment
		(start 378.941584 -230.900478)
		(end 378.941584 -230.914702)
		(width 0.088646)
		(layer "In6.Cu")
		(net "M_H_CPU0_SB_DQ<17>")
	)
	(segment
		(start 375.274078 -231.39019)
		(end 375.246392 -231.374442)
		(width 0.088646)
		(layer "In6.Cu")
		(net "M_H_CPU0_SB_DQ<17>")
	)
	(segment
		(start 425.99991 -212.894672)
		(end 425.83989 -213.054692)
		(width 0.18288)
		(layer "In6.Cu")
		(net "M_H_CPU0_SB_DQ<17>")
	)
	(segment
		(start 429.529494 -212.171026)
		(end 427.80839 -213.89213)
		(width 0.18288)
		(layer "In6.Cu")
		(net "M_H_CPU0_SB_DQ<17>")
	)
	(segment
		(start 423.446702 -213.89213)
		(end 422.042082 -213.89213)
		(width 0.18288)
		(layer "In6.Cu")
		(net "M_H_CPU0_SB_DQ<17>")
	)
	(segment
		(start 440.636914 -212.192108)
		(end 437.382158 -212.192108)
		(width 0.18288)
		(layer "In6.Cu")
		(net "M_H_CPU0_SB_DQ<17>")
	)
	(segment
		(start 406.35555 -213.191344)
		(end 404.52675 -213.191344)
		(width 0.18288)
		(layer "In6.Cu")
		(net "M_H_CPU0_SB_DQ<17>")
	)
	(segment
		(start 380.068582 -230.57612)
		(end 380.058168 -230.582216)
		(width 0.088646)
		(layer "In6.Cu")
		(net "M_H_CPU0_SB_DQ<17>")
	)
	(segment
		(start 415.640266 -211.921598)
		(end 414.872678 -211.921598)
		(width 0.18288)
		(layer "In6.Cu")
		(net "M_H_CPU0_SB_DQ<17>")
	)
	(segment
		(start 448.860164 -212.640672)
		(end 448.486784 -212.640672)
		(width 0.18288)
		(layer "In6.Cu")
		(net "M_H_CPU0_SB_DQ<17>")
	)
	(segment
		(start 425.83989 -213.054692)
		(end 425.83989 -213.73211)
		(width 0.18288)
		(layer "In6.Cu")
		(net "M_H_CPU0_SB_DQ<17>")
	)
	(segment
		(start 414.179258 -212.71103)
		(end 413.996378 -212.52815)
		(width 0.18288)
		(layer "In6.Cu")
		(net "M_H_CPU0_SB_DQ<17>")
	)
	(segment
		(start 414.506918 -212.71103)
		(end 414.179258 -212.71103)
		(width 0.18288)
		(layer "In6.Cu")
		(net "M_H_CPU0_SB_DQ<17>")
	)
	(segment
		(start 413.996378 -212.52815)
		(end 413.996378 -212.104478)
		(width 0.18288)
		(layer "In6.Cu")
		(net "M_H_CPU0_SB_DQ<17>")
	)
	(segment
		(start 386.918962 -229.392226)
		(end 385.82473 -230.486458)
		(width 0.088646)
		(layer "In6.Cu")
		(net "M_H_CPU0_SB_DQ<17>")
	)
	(segment
		(start 448.486784 -212.640672)
		(end 448.326764 -212.480652)
		(width 0.18288)
		(layer "In6.Cu")
		(net "M_H_CPU0_SB_DQ<17>")
	)
	(segment
		(start 450.498464 -212.192108)
		(end 449.180204 -212.192108)
		(width 0.18288)
		(layer "In6.Cu")
		(net "M_H_CPU0_SB_DQ<17>")
	)
	(segment
		(start 449.020184 -212.480652)
		(end 448.860164 -212.640672)
		(width 0.18288)
		(layer "In6.Cu")
		(net "M_H_CPU0_SB_DQ<17>")
	)
	(segment
		(start 448.326764 -212.480652)
		(end 448.326764 -212.352128)
		(width 0.18288)
		(layer "In6.Cu")
		(net "M_H_CPU0_SB_DQ<17>")
	)
	(segment
		(start 413.813498 -211.921598)
		(end 412.710122 -211.921598)
		(width 0.18288)
		(layer "In6.Cu")
		(net "M_H_CPU0_SB_DQ<17>")
	)
	(segment
		(start 387.21411 -228.794056)
		(end 387.074664 -228.794056)
		(width 0.088646)
		(layer "In6.Cu")
		(net "M_H_CPU0_SB_DQ<17>")
	)
	(segment
		(start 407.41473 -213.191344)
		(end 407.23185 -213.008464)
		(width 0.18288)
		(layer "In6.Cu")
		(net "M_H_CPU0_SB_DQ<17>")
	)
	(segment
		(start 412.270194 -212.361526)
		(end 411.381194 -212.361526)
		(width 0.18288)
		(layer "In6.Cu")
		(net "M_H_CPU0_SB_DQ<17>")
	)
	(segment
		(start 423.744644 -214.190072)
		(end 423.446702 -213.89213)
		(width 0.18288)
		(layer "In6.Cu")
		(net "M_H_CPU0_SB_DQ<17>")
	)
	(segment
		(start 417.547044 -212.964776)
		(end 416.683444 -212.964776)
		(width 0.18288)
		(layer "In6.Cu")
		(net "M_H_CPU0_SB_DQ<17>")
	)
	(segment
		(start 377.719082 -231.39019)
		(end 377.708668 -231.396286)
		(width 0.088646)
		(layer "In6.Cu")
		(net "M_H_CPU0_SB_DQ<17>")
	)
	(segment
		(start 424.438064 -213.89213)
		(end 424.140122 -214.190072)
		(width 0.18288)
		(layer "In6.Cu")
		(net "M_H_CPU0_SB_DQ<17>")
	)
	(segment
		(start 437.382158 -212.192108)
		(end 436.532274 -213.041992)
		(width 0.18288)
		(layer "In6.Cu")
		(net "M_H_CPU0_SB_DQ<17>")
	)
	(segment
		(start 387.074664 -228.794056)
		(end 386.918962 -228.949758)
		(width 0.088646)
		(layer "In6.Cu")
		(net "M_H_CPU0_SB_DQ<17>")
	)
	(segment
		(start 449.020184 -212.352128)
		(end 449.020184 -212.480652)
		(width 0.18288)
		(layer "In6.Cu")
		(net "M_H_CPU0_SB_DQ<17>")
	)
	(segment
		(start 407.04897 -212.326474)
		(end 406.72131 -212.326474)
		(width 0.18288)
		(layer "In6.Cu")
		(net "M_H_CPU0_SB_DQ<17>")
	)
	(segment
		(start 431.84826 -213.041992)
		(end 430.977294 -212.171026)
		(width 0.18288)
		(layer "In6.Cu")
		(net "M_H_CPU0_SB_DQ<17>")
	)
	(segment
		(start 386.918962 -228.949758)
		(end 386.918962 -229.392226)
		(width 0.088646)
		(layer "In6.Cu")
		(net "M_H_CPU0_SB_DQ<17>")
	)
	(segment
		(start 408.900376 -213.191344)
		(end 407.41473 -213.191344)
		(width 0.18288)
		(layer "In6.Cu")
		(net "M_H_CPU0_SB_DQ<17>")
	)
	(segment
		(start 406.72131 -212.326474)
		(end 406.53843 -212.509354)
		(width 0.18288)
		(layer "In6.Cu")
		(net "M_H_CPU0_SB_DQ<17>")
	)
	(segment
		(start 404.52675 -213.191344)
		(end 388.924038 -228.794056)
		(width 0.18288)
		(layer "In6.Cu")
		(net "M_H_CPU0_SB_DQ<17>")
	)
	(segment
		(start 406.53843 -212.509354)
		(end 406.53843 -213.008464)
		(width 0.18288)
		(layer "In6.Cu")
		(net "M_H_CPU0_SB_DQ<17>")
	)
	(segment
		(start 426.69333 -213.89213)
		(end 426.53331 -213.73211)
		(width 0.18288)
		(layer "In6.Cu")
		(net "M_H_CPU0_SB_DQ<17>")
	)
	(segment
		(start 441.330334 -211.455508)
		(end 441.002674 -211.455508)
		(width 0.18288)
		(layer "In6.Cu")
		(net "M_H_CPU0_SB_DQ<17>")
	)
	(segment
		(start 375.246392 -231.374442)
		(end 374.683274 -230.950262)
		(width 0.088646)
		(layer "In6.Cu")
		(net "M_H_CPU0_SB_DQ<17>")
	)
	(segment
		(start 406.53843 -213.008464)
		(end 406.35555 -213.191344)
		(width 0.18288)
		(layer "In6.Cu")
		(net "M_H_CPU0_SB_DQ<17>")
	)
	(segment
		(start 425.67987 -213.89213)
		(end 424.438064 -213.89213)
		(width 0.18288)
		(layer "In6.Cu")
		(net "M_H_CPU0_SB_DQ<17>")
	)
	(segment
		(start 430.977294 -212.171026)
		(end 429.529494 -212.171026)
		(width 0.18288)
		(layer "In6.Cu")
		(net "M_H_CPU0_SB_DQ<17>")
	)
	(segment
		(start 426.53331 -213.054692)
		(end 426.37329 -212.894672)
		(width 0.18288)
		(layer "In6.Cu")
		(net "M_H_CPU0_SB_DQ<17>")
	)
	(arc
		(start 376.213878 -231.39019)
		(mid 376.02668 -231.340047)
		(end 375.839482 -231.39019)
		(width 0.088646)
		(layer "In6.Cu")
		(net "M_H_CPU0_SB_DQ<17>")
	)
	(arc
		(start 377.708668 -231.396286)
		(mid 377.43049 -231.465978)
		(end 377.153932 -231.39019)
		(width 0.088646)
		(layer "In6.Cu")
		(net "M_H_CPU0_SB_DQ<17>")
	)
	(arc
		(start 383.262632 -230.57612)
		(mid 383.075434 -230.525977)
		(end 382.888236 -230.57612)
		(width 0.088646)
		(layer "In6.Cu")
		(net "M_H_CPU0_SB_DQ<17>")
	)
	(arc
		(start 384.767836 -230.57612)
		(mid 384.485134 -230.651896)
		(end 384.202432 -230.57612)
		(width 0.088646)
		(layer "In6.Cu")
		(net "M_H_CPU0_SB_DQ<17>")
	)
	(arc
		(start 378.64415 -231.398826)
		(mid 378.367709 -231.465992)
		(end 378.093478 -231.39019)
		(width 0.088646)
		(layer "In6.Cu")
		(net "M_H_CPU0_SB_DQ<17>")
	)
	(arc
		(start 378.941584 -230.914702)
		(mid 378.862365 -231.189387)
		(end 378.658882 -231.39019)
		(width 0.088646)
		(layer "In6.Cu")
		(net "M_H_CPU0_SB_DQ<17>")
	)
	(arc
		(start 378.093478 -231.39019)
		(mid 377.90628 -231.340047)
		(end 377.719082 -231.39019)
		(width 0.088646)
		(layer "In6.Cu")
		(net "M_H_CPU0_SB_DQ<17>")
	)
	(arc
		(start 377.153932 -231.39019)
		(mid 376.966734 -231.340047)
		(end 376.779536 -231.39019)
		(width 0.088646)
		(layer "In6.Cu")
		(net "M_H_CPU0_SB_DQ<17>")
	)
	(arc
		(start 380.442978 -230.57612)
		(mid 380.25578 -230.525977)
		(end 380.068582 -230.57612)
		(width 0.088646)
		(layer "In6.Cu")
		(net "M_H_CPU0_SB_DQ<17>")
	)
	(arc
		(start 379.120146 -230.5812)
		(mid 378.989232 -230.71756)
		(end 378.941584 -230.900478)
		(width 0.088646)
		(layer "In6.Cu")
		(net "M_H_CPU0_SB_DQ<17>")
	)
	(arc
		(start 375.82475 -231.398826)
		(mid 375.548309 -231.465992)
		(end 375.274078 -231.39019)
		(width 0.088646)
		(layer "In6.Cu")
		(net "M_H_CPU0_SB_DQ<17>")
	)
	(arc
		(start 384.202432 -230.57612)
		(mid 384.015234 -230.525977)
		(end 383.828036 -230.57612)
		(width 0.088646)
		(layer "In6.Cu")
		(net "M_H_CPU0_SB_DQ<17>")
	)
	(arc
		(start 385.707636 -230.57612)
		(mid 385.424934 -230.651896)
		(end 385.142232 -230.57612)
		(width 0.088646)
		(layer "In6.Cu")
		(net "M_H_CPU0_SB_DQ<17>")
	)
	(arc
		(start 382.322832 -230.57612)
		(mid 382.135634 -230.525977)
		(end 381.948436 -230.57612)
		(width 0.088646)
		(layer "In6.Cu")
		(net "M_H_CPU0_SB_DQ<17>")
	)
	(arc
		(start 382.888236 -230.57612)
		(mid 382.605534 -230.651896)
		(end 382.322832 -230.57612)
		(width 0.088646)
		(layer "In6.Cu")
		(net "M_H_CPU0_SB_DQ<17>")
	)
	(arc
		(start 385.142232 -230.57612)
		(mid 384.955034 -230.525977)
		(end 384.767836 -230.57612)
		(width 0.088646)
		(layer "In6.Cu")
		(net "M_H_CPU0_SB_DQ<17>")
	)
	(arc
		(start 381.008636 -230.57612)
		(mid 380.731823 -230.65199)
		(end 380.453392 -230.582216)
		(width 0.088646)
		(layer "In6.Cu")
		(net "M_H_CPU0_SB_DQ<17>")
	)
	(arc
		(start 380.058168 -230.582216)
		(mid 379.77999 -230.651939)
		(end 379.503432 -230.57612)
		(width 0.088646)
		(layer "In6.Cu")
		(net "M_H_CPU0_SB_DQ<17>")
	)
	(arc
		(start 381.383032 -230.57612)
		(mid 381.195834 -230.525977)
		(end 381.008636 -230.57612)
		(width 0.088646)
		(layer "In6.Cu")
		(net "M_H_CPU0_SB_DQ<17>")
	)
	(arc
		(start 385.82473 -230.486458)
		(mid 385.769125 -230.535132)
		(end 385.707636 -230.57612)
		(width 0.088646)
		(layer "In6.Cu")
		(net "M_H_CPU0_SB_DQ<17>")
	)
	(arc
		(start 383.828036 -230.57612)
		(mid 383.545334 -230.651896)
		(end 383.262632 -230.57612)
		(width 0.088646)
		(layer "In6.Cu")
		(net "M_H_CPU0_SB_DQ<17>")
	)
	(arc
		(start 376.769122 -231.396286)
		(mid 376.49069 -231.4661)
		(end 376.213878 -231.39019)
		(width 0.088646)
		(layer "In6.Cu")
		(net "M_H_CPU0_SB_DQ<17>")
	)
	(arc
		(start 379.503432 -230.57612)
		(mid 379.316234 -230.525977)
		(end 379.129036 -230.57612)
		(width 0.088646)
		(layer "In6.Cu")
		(net "M_H_CPU0_SB_DQ<17>")
	)
	(arc
		(start 381.948436 -230.57612)
		(mid 381.665734 -230.651896)
		(end 381.383032 -230.57612)
		(width 0.088646)
		(layer "In6.Cu")
		(net "M_H_CPU0_SB_DQ<17>")
	)
	(segment
		(start 454.91146 -213.041738)
		(end 454.566782 -213.041738)
		(width 0.20066)
		(layer "F.Cu")
		(net "M_H_CPU0_SB_DQ<16>")
	)
	(segment
		(start 375.087134 -232.250488)
		(end 375.08688 -232.250234)
		(width 0.20066)
		(layer "F.Cu")
		(net "M_H_CPU0_SB_DQ<16>")
	)
	(segment
		(start 453.536812 -213.46668)
		(end 452.016114 -213.46668)
		(width 0.20066)
		(layer "F.Cu")
		(net "M_H_CPU0_SB_DQ<16>")
	)
	(segment
		(start 454.448672 -213.159848)
		(end 454.448672 -213.527386)
		(width 0.20066)
		(layer "F.Cu")
		(net "M_H_CPU0_SB_DQ<16>")
	)
	(segment
		(start 454.566782 -213.041738)
		(end 454.448672 -213.159848)
		(width 0.20066)
		(layer "F.Cu")
		(net "M_H_CPU0_SB_DQ<16>")
	)
	(segment
		(start 453.785478 -213.715346)
		(end 453.536812 -213.46668)
		(width 0.20066)
		(layer "F.Cu")
		(net "M_H_CPU0_SB_DQ<16>")
	)
	(segment
		(start 454.95845 -213.041738)
		(end 454.91146 -213.041738)
		(width 0.101854)
		(layer "F.Cu")
		(net "M_H_CPU0_SB_DQ<16>")
	)
	(segment
		(start 454.260712 -213.715346)
		(end 453.785478 -213.715346)
		(width 0.20066)
		(layer "F.Cu")
		(net "M_H_CPU0_SB_DQ<16>")
	)
	(segment
		(start 375.08688 -232.250234)
		(end 375.08688 -231.714548)
		(width 0.20066)
		(layer "F.Cu")
		(net "M_H_CPU0_SB_DQ<16>")
	)
	(segment
		(start 457.120244 -213.041738)
		(end 454.95845 -213.041738)
		(width 0.1016)
		(layer "F.Cu")
		(net "M_H_CPU0_SB_DQ<16>")
	)
	(segment
		(start 459.55966 -213.466934)
		(end 457.968096 -213.466934)
		(width 0.20066)
		(layer "F.Cu")
		(net "M_H_CPU0_SB_DQ<16>")
	)
	(segment
		(start 452.016114 -213.46668)
		(end 450.911214 -213.46668)
		(width 0.20066)
		(layer "F.Cu")
		(net "M_H_CPU0_SB_DQ<16>")
	)
	(segment
		(start 457.53655 -213.035388)
		(end 457.126594 -213.035388)
		(width 0.20066)
		(layer "F.Cu")
		(net "M_H_CPU0_SB_DQ<16>")
	)
	(segment
		(start 454.448672 -213.527386)
		(end 454.260712 -213.715346)
		(width 0.20066)
		(layer "F.Cu")
		(net "M_H_CPU0_SB_DQ<16>")
	)
	(segment
		(start 457.126594 -213.035388)
		(end 457.120244 -213.041738)
		(width 0.1016)
		(layer "F.Cu")
		(net "M_H_CPU0_SB_DQ<16>")
	)
	(segment
		(start 457.968096 -213.466934)
		(end 457.53655 -213.035388)
		(width 0.20066)
		(layer "F.Cu")
		(net "M_H_CPU0_SB_DQ<16>")
	)
	(segment
		(start 459.559914 -213.46668)
		(end 459.55966 -213.466934)
		(width 0.20066)
		(layer "F.Cu")
		(net "M_H_CPU0_SB_DQ<16>")
	)
	(segment
		(start 407.392632 -215.148668)
		(end 407.209752 -214.965788)
		(width 0.18288)
		(layer "In6.Cu")
		(net "M_H_CPU0_SB_DQ<16>")
	)
	(segment
		(start 414.894776 -213.796626)
		(end 414.711896 -213.979506)
		(width 0.18288)
		(layer "In6.Cu")
		(net "M_H_CPU0_SB_DQ<16>")
	)
	(segment
		(start 414.018476 -213.979506)
		(end 413.835596 -213.796626)
		(width 0.18288)
		(layer "In6.Cu")
		(net "M_H_CPU0_SB_DQ<16>")
	)
	(segment
		(start 444.741554 -215.040464)
		(end 444.558674 -215.223344)
		(width 0.18288)
		(layer "In6.Cu")
		(net "M_H_CPU0_SB_DQ<16>")
	)
	(segment
		(start 444.048134 -215.040464)
		(end 444.048134 -214.034116)
		(width 0.18288)
		(layer "In6.Cu")
		(net "M_H_CPU0_SB_DQ<16>")
	)
	(segment
		(start 375.744232 -232.204006)
		(end 375.714006 -232.186734)
		(width 0.088646)
		(layer "In6.Cu")
		(net "M_H_CPU0_SB_DQ<16>")
	)
	(segment
		(start 409.215844 -214.590376)
		(end 408.657552 -215.148668)
		(width 0.18288)
		(layer "In6.Cu")
		(net "M_H_CPU0_SB_DQ<16>")
	)
	(segment
		(start 428.569374 -215.594946)
		(end 421.78224 -215.594946)
		(width 0.18288)
		(layer "In6.Cu")
		(net "M_H_CPU0_SB_DQ<16>")
	)
	(segment
		(start 441.925202 -214.254334)
		(end 441.562998 -213.89213)
		(width 0.18288)
		(layer "In6.Cu")
		(net "M_H_CPU0_SB_DQ<16>")
	)
	(segment
		(start 411.536896 -214.091774)
		(end 411.038294 -214.590376)
		(width 0.18288)
		(layer "In6.Cu")
		(net "M_H_CPU0_SB_DQ<16>")
	)
	(segment
		(start 377.638564 -232.212642)
		(end 377.623832 -232.204006)
		(width 0.088646)
		(layer "In6.Cu")
		(net "M_H_CPU0_SB_DQ<16>")
	)
	(segment
		(start 388.00151 -229.801674)
		(end 387.793484 -229.801674)
		(width 0.088646)
		(layer "In6.Cu")
		(net "M_H_CPU0_SB_DQ<16>")
	)
	(segment
		(start 408.657552 -215.148668)
		(end 407.392632 -215.148668)
		(width 0.18288)
		(layer "In6.Cu")
		(net "M_H_CPU0_SB_DQ<16>")
	)
	(segment
		(start 443.865254 -213.851236)
		(end 443.084204 -213.851236)
		(width 0.18288)
		(layer "In6.Cu")
		(net "M_H_CPU0_SB_DQ<16>")
	)
	(segment
		(start 421.78224 -215.594946)
		(end 420.93896 -216.438226)
		(width 0.18288)
		(layer "In6.Cu")
		(net "M_H_CPU0_SB_DQ<16>")
	)
	(segment
		(start 413.835596 -213.796626)
		(end 412.721044 -213.796626)
		(width 0.18288)
		(layer "In6.Cu")
		(net "M_H_CPU0_SB_DQ<16>")
	)
	(segment
		(start 387.475222 -230.477314)
		(end 387.11759 -230.477314)
		(width 0.088646)
		(layer "In6.Cu")
		(net "M_H_CPU0_SB_DQ<16>")
	)
	(segment
		(start 406.333452 -215.148668)
		(end 404.161752 -215.148668)
		(width 0.18288)
		(layer "In6.Cu")
		(net "M_H_CPU0_SB_DQ<16>")
	)
	(segment
		(start 406.699212 -214.284052)
		(end 406.516332 -214.466932)
		(width 0.18288)
		(layer "In6.Cu")
		(net "M_H_CPU0_SB_DQ<16>")
	)
	(segment
		(start 420.559738 -216.438226)
		(end 420.317168 -216.195656)
		(width 0.18288)
		(layer "In6.Cu")
		(net "M_H_CPU0_SB_DQ<16>")
	)
	(segment
		(start 448.816984 -215.079072)
		(end 448.443604 -215.079072)
		(width 0.18288)
		(layer "In6.Cu")
		(net "M_H_CPU0_SB_DQ<16>")
	)
	(segment
		(start 378.578364 -232.212642)
		(end 378.563632 -232.204006)
		(width 0.088646)
		(layer "In6.Cu")
		(net "M_H_CPU0_SB_DQ<16>")
	)
	(segment
		(start 448.443604 -215.079072)
		(end 448.283584 -214.919052)
		(width 0.18288)
		(layer "In6.Cu")
		(net "M_H_CPU0_SB_DQ<16>")
	)
	(segment
		(start 420.317168 -216.195656)
		(end 419.195504 -216.195656)
		(width 0.18288)
		(layer "In6.Cu")
		(net "M_H_CPU0_SB_DQ<16>")
	)
	(segment
		(start 417.704524 -214.704676)
		(end 416.594544 -214.704676)
		(width 0.18288)
		(layer "In6.Cu")
		(net "M_H_CPU0_SB_DQ<16>")
	)
	(segment
		(start 411.038294 -214.590376)
		(end 409.215844 -214.590376)
		(width 0.18288)
		(layer "In6.Cu")
		(net "M_H_CPU0_SB_DQ<16>")
	)
	(segment
		(start 444.558674 -215.223344)
		(end 444.231014 -215.223344)
		(width 0.18288)
		(layer "In6.Cu")
		(net "M_H_CPU0_SB_DQ<16>")
	)
	(segment
		(start 404.161752 -215.148668)
		(end 389.508746 -229.801674)
		(width 0.18288)
		(layer "In6.Cu")
		(net "M_H_CPU0_SB_DQ<16>")
	)
	(segment
		(start 441.562998 -213.89213)
		(end 437.83377 -213.89213)
		(width 0.18288)
		(layer "In6.Cu")
		(net "M_H_CPU0_SB_DQ<16>")
	)
	(segment
		(start 407.209752 -214.466932)
		(end 407.026872 -214.284052)
		(width 0.18288)
		(layer "In6.Cu")
		(net "M_H_CPU0_SB_DQ<16>")
	)
	(segment
		(start 406.516332 -214.466932)
		(end 406.516332 -214.965788)
		(width 0.18288)
		(layer "In6.Cu")
		(net "M_H_CPU0_SB_DQ<16>")
	)
	(segment
		(start 415.686494 -213.796626)
		(end 414.894776 -213.796626)
		(width 0.18288)
		(layer "In6.Cu")
		(net "M_H_CPU0_SB_DQ<16>")
	)
	(segment
		(start 448.123564 -214.352124)
		(end 446.747392 -214.352124)
		(width 0.18288)
		(layer "In6.Cu")
		(net "M_H_CPU0_SB_DQ<16>")
	)
	(segment
		(start 387.697472 -229.897686)
		(end 387.697472 -230.255064)
		(width 0.088646)
		(layer "In6.Cu")
		(net "M_H_CPU0_SB_DQ<16>")
	)
	(segment
		(start 430.316894 -213.847426)
		(end 428.569374 -215.594946)
		(width 0.18288)
		(layer "In6.Cu")
		(net "M_H_CPU0_SB_DQ<16>")
	)
	(segment
		(start 414.711896 -213.979506)
		(end 414.711896 -214.345774)
		(width 0.18288)
		(layer "In6.Cu")
		(net "M_H_CPU0_SB_DQ<16>")
	)
	(segment
		(start 443.084204 -213.851236)
		(end 442.681106 -214.254334)
		(width 0.18288)
		(layer "In6.Cu")
		(net "M_H_CPU0_SB_DQ<16>")
	)
	(segment
		(start 431.710846 -214.530178)
		(end 431.028094 -213.847426)
		(width 0.18288)
		(layer "In6.Cu")
		(net "M_H_CPU0_SB_DQ<16>")
	)
	(segment
		(start 389.508746 -229.801674)
		(end 388.00151 -229.801674)
		(width 0.18288)
		(layer "In6.Cu")
		(net "M_H_CPU0_SB_DQ<16>")
	)
	(segment
		(start 387.793484 -229.801674)
		(end 387.697472 -229.897686)
		(width 0.088646)
		(layer "In6.Cu")
		(net "M_H_CPU0_SB_DQ<16>")
	)
	(segment
		(start 407.026872 -214.284052)
		(end 406.699212 -214.284052)
		(width 0.18288)
		(layer "In6.Cu")
		(net "M_H_CPU0_SB_DQ<16>")
	)
	(segment
		(start 444.048134 -214.034116)
		(end 443.865254 -213.851236)
		(width 0.18288)
		(layer "In6.Cu")
		(net "M_H_CPU0_SB_DQ<16>")
	)
	(segment
		(start 414.201356 -214.528654)
		(end 414.018476 -214.345774)
		(width 0.18288)
		(layer "In6.Cu")
		(net "M_H_CPU0_SB_DQ<16>")
	)
	(segment
		(start 449.137024 -214.352124)
		(end 448.977004 -214.512144)
		(width 0.18288)
		(layer "In6.Cu")
		(net "M_H_CPU0_SB_DQ<16>")
	)
	(segment
		(start 444.231014 -215.223344)
		(end 444.048134 -215.040464)
		(width 0.18288)
		(layer "In6.Cu")
		(net "M_H_CPU0_SB_DQ<16>")
	)
	(segment
		(start 375.714006 -232.186734)
		(end 375.08688 -231.714548)
		(width 0.088646)
		(layer "In6.Cu")
		(net "M_H_CPU0_SB_DQ<16>")
	)
	(segment
		(start 434.048662 -214.530178)
		(end 431.710846 -214.530178)
		(width 0.18288)
		(layer "In6.Cu")
		(net "M_H_CPU0_SB_DQ<16>")
	)
	(segment
		(start 437.83377 -213.89213)
		(end 436.984902 -214.740998)
		(width 0.18288)
		(layer "In6.Cu")
		(net "M_H_CPU0_SB_DQ<16>")
	)
	(segment
		(start 407.209752 -214.965788)
		(end 407.209752 -214.466932)
		(width 0.18288)
		(layer "In6.Cu")
		(net "M_H_CPU0_SB_DQ<16>")
	)
	(segment
		(start 414.711896 -214.345774)
		(end 414.529016 -214.528654)
		(width 0.18288)
		(layer "In6.Cu")
		(net "M_H_CPU0_SB_DQ<16>")
	)
	(segment
		(start 431.028094 -213.847426)
		(end 430.316894 -213.847426)
		(width 0.18288)
		(layer "In6.Cu")
		(net "M_H_CPU0_SB_DQ<16>")
	)
	(segment
		(start 450.02577 -214.352124)
		(end 449.137024 -214.352124)
		(width 0.18288)
		(layer "In6.Cu")
		(net "M_H_CPU0_SB_DQ<16>")
	)
	(segment
		(start 448.977004 -214.919052)
		(end 448.816984 -215.079072)
		(width 0.18288)
		(layer "In6.Cu")
		(net "M_H_CPU0_SB_DQ<16>")
	)
	(segment
		(start 387.697472 -230.255064)
		(end 387.475222 -230.477314)
		(width 0.088646)
		(layer "In6.Cu")
		(net "M_H_CPU0_SB_DQ<16>")
	)
	(segment
		(start 446.747392 -214.352124)
		(end 446.246504 -213.851236)
		(width 0.18288)
		(layer "In6.Cu")
		(net "M_H_CPU0_SB_DQ<16>")
	)
	(segment
		(start 450.911214 -213.46668)
		(end 450.02577 -214.352124)
		(width 0.18288)
		(layer "In6.Cu")
		(net "M_H_CPU0_SB_DQ<16>")
	)
	(segment
		(start 416.594544 -214.704676)
		(end 415.686494 -213.796626)
		(width 0.18288)
		(layer "In6.Cu")
		(net "M_H_CPU0_SB_DQ<16>")
	)
	(segment
		(start 446.246504 -213.851236)
		(end 444.924434 -213.851236)
		(width 0.18288)
		(layer "In6.Cu")
		(net "M_H_CPU0_SB_DQ<16>")
	)
	(segment
		(start 414.018476 -214.345774)
		(end 414.018476 -213.979506)
		(width 0.18288)
		(layer "In6.Cu")
		(net "M_H_CPU0_SB_DQ<16>")
	)
	(segment
		(start 448.977004 -214.512144)
		(end 448.977004 -214.919052)
		(width 0.18288)
		(layer "In6.Cu")
		(net "M_H_CPU0_SB_DQ<16>")
	)
	(segment
		(start 442.681106 -214.254334)
		(end 441.925202 -214.254334)
		(width 0.18288)
		(layer "In6.Cu")
		(net "M_H_CPU0_SB_DQ<16>")
	)
	(segment
		(start 379.41123 -231.714548)
		(end 379.41123 -231.730042)
		(width 0.088646)
		(layer "In6.Cu")
		(net "M_H_CPU0_SB_DQ<16>")
	)
	(segment
		(start 434.259482 -214.740998)
		(end 434.048662 -214.530178)
		(width 0.18288)
		(layer "In6.Cu")
		(net "M_H_CPU0_SB_DQ<16>")
	)
	(segment
		(start 444.924434 -213.851236)
		(end 444.741554 -214.034116)
		(width 0.18288)
		(layer "In6.Cu")
		(net "M_H_CPU0_SB_DQ<16>")
	)
	(segment
		(start 436.984902 -214.740998)
		(end 434.259482 -214.740998)
		(width 0.18288)
		(layer "In6.Cu")
		(net "M_H_CPU0_SB_DQ<16>")
	)
	(segment
		(start 406.516332 -214.965788)
		(end 406.333452 -215.148668)
		(width 0.18288)
		(layer "In6.Cu")
		(net "M_H_CPU0_SB_DQ<16>")
	)
	(segment
		(start 448.283584 -214.919052)
		(end 448.283584 -214.512144)
		(width 0.18288)
		(layer "In6.Cu")
		(net "M_H_CPU0_SB_DQ<16>")
	)
	(segment
		(start 375.758964 -232.212642)
		(end 375.744232 -232.204006)
		(width 0.088646)
		(layer "In6.Cu")
		(net "M_H_CPU0_SB_DQ<16>")
	)
	(segment
		(start 448.283584 -214.512144)
		(end 448.123564 -214.352124)
		(width 0.18288)
		(layer "In6.Cu")
		(net "M_H_CPU0_SB_DQ<16>")
	)
	(segment
		(start 412.721044 -213.796626)
		(end 412.425896 -214.091774)
		(width 0.18288)
		(layer "In6.Cu")
		(net "M_H_CPU0_SB_DQ<16>")
	)
	(segment
		(start 412.425896 -214.091774)
		(end 411.536896 -214.091774)
		(width 0.18288)
		(layer "In6.Cu")
		(net "M_H_CPU0_SB_DQ<16>")
	)
	(segment
		(start 381.478536 -231.39019)
		(end 381.468122 -231.396286)
		(width 0.088646)
		(layer "In6.Cu")
		(net "M_H_CPU0_SB_DQ<16>")
	)
	(segment
		(start 379.598682 -231.39019)
		(end 379.589792 -231.39527)
		(width 0.088646)
		(layer "In6.Cu")
		(net "M_H_CPU0_SB_DQ<16>")
	)
	(segment
		(start 444.741554 -214.034116)
		(end 444.741554 -215.040464)
		(width 0.18288)
		(layer "In6.Cu")
		(net "M_H_CPU0_SB_DQ<16>")
	)
	(segment
		(start 387.11759 -230.477314)
		(end 386.29463 -231.300274)
		(width 0.088646)
		(layer "In6.Cu")
		(net "M_H_CPU0_SB_DQ<16>")
	)
	(segment
		(start 414.529016 -214.528654)
		(end 414.201356 -214.528654)
		(width 0.18288)
		(layer "In6.Cu")
		(net "M_H_CPU0_SB_DQ<16>")
	)
	(segment
		(start 419.195504 -216.195656)
		(end 417.704524 -214.704676)
		(width 0.18288)
		(layer "In6.Cu")
		(net "M_H_CPU0_SB_DQ<16>")
	)
	(segment
		(start 420.93896 -216.438226)
		(end 420.559738 -216.438226)
		(width 0.18288)
		(layer "In6.Cu")
		(net "M_H_CPU0_SB_DQ<16>")
	)
	(arc
		(start 383.358136 -231.39019)
		(mid 383.075434 -231.465932)
		(end 382.792732 -231.39019)
		(width 0.088646)
		(layer "In6.Cu")
		(net "M_H_CPU0_SB_DQ<16>")
	)
	(arc
		(start 380.538482 -231.39019)
		(mid 380.25578 -231.465932)
		(end 379.973078 -231.39019)
		(width 0.088646)
		(layer "In6.Cu")
		(net "M_H_CPU0_SB_DQ<16>")
	)
	(arc
		(start 379.973078 -231.39019)
		(mid 379.78588 -231.340047)
		(end 379.598682 -231.39019)
		(width 0.088646)
		(layer "In6.Cu")
		(net "M_H_CPU0_SB_DQ<16>")
	)
	(arc
		(start 384.297936 -231.39019)
		(mid 384.015234 -231.465932)
		(end 383.732532 -231.39019)
		(width 0.088646)
		(layer "In6.Cu")
		(net "M_H_CPU0_SB_DQ<16>")
	)
	(arc
		(start 377.249436 -232.204006)
		(mid 376.966734 -232.279782)
		(end 376.684032 -232.204006)
		(width 0.088646)
		(layer "In6.Cu")
		(net "M_H_CPU0_SB_DQ<16>")
	)
	(arc
		(start 378.563632 -232.204006)
		(mid 378.376434 -232.153863)
		(end 378.189236 -232.204006)
		(width 0.088646)
		(layer "In6.Cu")
		(net "M_H_CPU0_SB_DQ<16>")
	)
	(arc
		(start 386.29463 -231.300274)
		(mid 385.968647 -231.461036)
		(end 385.612132 -231.39019)
		(width 0.088646)
		(layer "In6.Cu")
		(net "M_H_CPU0_SB_DQ<16>")
	)
	(arc
		(start 378.189236 -232.204006)
		(mid 377.915037 -232.279841)
		(end 377.638564 -232.212642)
		(width 0.088646)
		(layer "In6.Cu")
		(net "M_H_CPU0_SB_DQ<16>")
	)
	(arc
		(start 385.612132 -231.39019)
		(mid 385.424934 -231.340047)
		(end 385.237736 -231.39019)
		(width 0.088646)
		(layer "In6.Cu")
		(net "M_H_CPU0_SB_DQ<16>")
	)
	(arc
		(start 382.418336 -231.39019)
		(mid 382.135634 -231.465932)
		(end 381.852932 -231.39019)
		(width 0.088646)
		(layer "In6.Cu")
		(net "M_H_CPU0_SB_DQ<16>")
	)
	(arc
		(start 379.41123 -231.730042)
		(mid 379.33186 -232.003776)
		(end 379.129036 -232.204006)
		(width 0.088646)
		(layer "In6.Cu")
		(net "M_H_CPU0_SB_DQ<16>")
	)
	(arc
		(start 379.589792 -231.39527)
		(mid 379.458878 -231.53163)
		(end 379.41123 -231.714548)
		(width 0.088646)
		(layer "In6.Cu")
		(net "M_H_CPU0_SB_DQ<16>")
	)
	(arc
		(start 381.468122 -231.396286)
		(mid 381.18969 -231.4661)
		(end 380.912878 -231.39019)
		(width 0.088646)
		(layer "In6.Cu")
		(net "M_H_CPU0_SB_DQ<16>")
	)
	(arc
		(start 384.672332 -231.39019)
		(mid 384.485134 -231.340047)
		(end 384.297936 -231.39019)
		(width 0.088646)
		(layer "In6.Cu")
		(net "M_H_CPU0_SB_DQ<16>")
	)
	(arc
		(start 376.684032 -232.204006)
		(mid 376.496834 -232.153863)
		(end 376.309636 -232.204006)
		(width 0.088646)
		(layer "In6.Cu")
		(net "M_H_CPU0_SB_DQ<16>")
	)
	(arc
		(start 376.309636 -232.204006)
		(mid 376.035437 -232.279841)
		(end 375.758964 -232.212642)
		(width 0.088646)
		(layer "In6.Cu")
		(net "M_H_CPU0_SB_DQ<16>")
	)
	(arc
		(start 380.912878 -231.39019)
		(mid 380.72568 -231.340047)
		(end 380.538482 -231.39019)
		(width 0.088646)
		(layer "In6.Cu")
		(net "M_H_CPU0_SB_DQ<16>")
	)
	(arc
		(start 381.852932 -231.39019)
		(mid 381.665734 -231.340047)
		(end 381.478536 -231.39019)
		(width 0.088646)
		(layer "In6.Cu")
		(net "M_H_CPU0_SB_DQ<16>")
	)
	(arc
		(start 379.129036 -232.204006)
		(mid 378.854837 -232.279841)
		(end 378.578364 -232.212642)
		(width 0.088646)
		(layer "In6.Cu")
		(net "M_H_CPU0_SB_DQ<16>")
	)
	(arc
		(start 383.732532 -231.39019)
		(mid 383.545334 -231.340047)
		(end 383.358136 -231.39019)
		(width 0.088646)
		(layer "In6.Cu")
		(net "M_H_CPU0_SB_DQ<16>")
	)
	(arc
		(start 377.623832 -232.204006)
		(mid 377.436634 -232.153863)
		(end 377.249436 -232.204006)
		(width 0.088646)
		(layer "In6.Cu")
		(net "M_H_CPU0_SB_DQ<16>")
	)
	(arc
		(start 385.237736 -231.39019)
		(mid 384.955034 -231.465932)
		(end 384.672332 -231.39019)
		(width 0.088646)
		(layer "In6.Cu")
		(net "M_H_CPU0_SB_DQ<16>")
	)
	(arc
		(start 382.792732 -231.39019)
		(mid 382.605534 -231.340047)
		(end 382.418336 -231.39019)
		(width 0.088646)
		(layer "In6.Cu")
		(net "M_H_CPU0_SB_DQ<16>")
	)
	(segment
		(start 372.73738 -230.900732)
		(end 372.737634 -230.900478)
		(width 0.20066)
		(layer "F.Cu")
		(net "M_H_CPU0_SB_DQ<15>")
	)
	(segment
		(start 458.24648 -214.748618)
		(end 458.538326 -214.748618)
		(width 0.20066)
		(layer "F.Cu")
		(net "M_H_CPU0_SB_DQ<15>")
	)
	(segment
		(start 461.251554 -214.753698)
		(end 461.455516 -214.549736)
		(width 0.20066)
		(layer "F.Cu")
		(net "M_H_CPU0_SB_DQ<15>")
	)
	(segment
		(start 461.689704 -214.064596)
		(end 462.073752 -214.064596)
		(width 0.20066)
		(layer "F.Cu")
		(net "M_H_CPU0_SB_DQ<15>")
	)
	(segment
		(start 458.543152 -214.748618)
		(end 458.550264 -214.741506)
		(width 0.1016)
		(layer "F.Cu")
		(net "M_H_CPU0_SB_DQ<15>")
	)
	(segment
		(start 372.73738 -231.436418)
		(end 372.73738 -230.900732)
		(width 0.20066)
		(layer "F.Cu")
		(net "M_H_CPU0_SB_DQ<15>")
	)
	(segment
		(start 455.011282 -214.316564)
		(end 456.116182 -214.316564)
		(width 0.20066)
		(layer "F.Cu")
		(net "M_H_CPU0_SB_DQ<15>")
	)
	(segment
		(start 462.073752 -214.064596)
		(end 462.32572 -214.316564)
		(width 0.20066)
		(layer "F.Cu")
		(net "M_H_CPU0_SB_DQ<15>")
	)
	(segment
		(start 458.550264 -214.741506)
		(end 460.558134 -214.741506)
		(width 0.1016)
		(layer "F.Cu")
		(net "M_H_CPU0_SB_DQ<15>")
	)
	(segment
		(start 460.558134 -214.741506)
		(end 460.570326 -214.753698)
		(width 0.1016)
		(layer "F.Cu")
		(net "M_H_CPU0_SB_DQ<15>")
	)
	(segment
		(start 456.116182 -214.316564)
		(end 457.814426 -214.316564)
		(width 0.20066)
		(layer "F.Cu")
		(net "M_H_CPU0_SB_DQ<15>")
	)
	(segment
		(start 460.570326 -214.753698)
		(end 461.251554 -214.753698)
		(width 0.20066)
		(layer "F.Cu")
		(net "M_H_CPU0_SB_DQ<15>")
	)
	(segment
		(start 457.814426 -214.316564)
		(end 458.24648 -214.748618)
		(width 0.20066)
		(layer "F.Cu")
		(net "M_H_CPU0_SB_DQ<15>")
	)
	(segment
		(start 461.455516 -214.549736)
		(end 461.455516 -214.298784)
		(width 0.20066)
		(layer "F.Cu")
		(net "M_H_CPU0_SB_DQ<15>")
	)
	(segment
		(start 462.32572 -214.316564)
		(end 463.659982 -214.316564)
		(width 0.20066)
		(layer "F.Cu")
		(net "M_H_CPU0_SB_DQ<15>")
	)
	(segment
		(start 458.538326 -214.748618)
		(end 458.543152 -214.748618)
		(width 0.101854)
		(layer "F.Cu")
		(net "M_H_CPU0_SB_DQ<15>")
	)
	(segment
		(start 461.455516 -214.298784)
		(end 461.689704 -214.064596)
		(width 0.20066)
		(layer "F.Cu")
		(net "M_H_CPU0_SB_DQ<15>")
	)
	(segment
		(start 409.5115 -208.181702)
		(end 409.298394 -208.106264)
		(width 0.18288)
		(layer "In11.Cu")
		(net "M_H_CPU0_SB_DQ<15>")
	)
	(segment
		(start 408.923998 -207.322928)
		(end 408.710892 -207.24749)
		(width 0.18288)
		(layer "In11.Cu")
		(net "M_H_CPU0_SB_DQ<15>")
	)
	(segment
		(start 450.281294 -211.612226)
		(end 449.976494 -211.307426)
		(width 0.18288)
		(layer "In11.Cu")
		(net "M_H_CPU0_SB_DQ<15>")
	)
	(segment
		(start 453.078088 -213.310216)
		(end 451.95871 -212.190838)
		(width 0.18288)
		(layer "In11.Cu")
		(net "M_H_CPU0_SB_DQ<15>")
	)
	(segment
		(start 388.10311 -228.146864)
		(end 387.704076 -228.146864)
		(width 0.088646)
		(layer "In11.Cu")
		(net "M_H_CPU0_SB_DQ<15>")
	)
	(segment
		(start 385.621022 -230.40594)
		(end 385.612132 -230.41102)
		(width 0.088646)
		(layer "In11.Cu")
		(net "M_H_CPU0_SB_DQ<15>")
	)
	(segment
		(start 379.983746 -230.404924)
		(end 379.973332 -230.41102)
		(width 0.088646)
		(layer "In11.Cu")
		(net "M_H_CPU0_SB_DQ<15>")
	)
	(segment
		(start 450.281294 -211.853526)
		(end 450.281294 -211.612226)
		(width 0.18288)
		(layer "In11.Cu")
		(net "M_H_CPU0_SB_DQ<15>")
	)
	(segment
		(start 408.672538 -208.405222)
		(end 408.5971 -208.618328)
		(width 0.18288)
		(layer "In11.Cu")
		(net "M_H_CPU0_SB_DQ<15>")
	)
	(segment
		(start 387.471158 -228.473)
		(end 386.422646 -229.521512)
		(width 0.088646)
		(layer "In11.Cu")
		(net "M_H_CPU0_SB_DQ<15>")
	)
	(segment
		(start 416.067494 -207.292194)
		(end 413.527748 -207.292194)
		(width 0.18288)
		(layer "In11.Cu")
		(net "M_H_CPU0_SB_DQ<15>")
	)
	(segment
		(start 424.27525 -206.241142)
		(end 423.374566 -207.141826)
		(width 0.18288)
		(layer "In11.Cu")
		(net "M_H_CPU0_SB_DQ<15>")
	)
	(segment
		(start 385.799584 -230.076756)
		(end 385.799584 -230.086662)
		(width 0.088646)
		(layer "In11.Cu")
		(net "M_H_CPU0_SB_DQ<15>")
	)
	(segment
		(start 377.719082 -230.41102)
		(end 377.70435 -230.402384)
		(width 0.088646)
		(layer "In11.Cu")
		(net "M_H_CPU0_SB_DQ<15>")
	)
	(segment
		(start 378.658882 -230.41102)
		(end 378.64415 -230.402384)
		(width 0.088646)
		(layer "In11.Cu")
		(net "M_H_CPU0_SB_DQ<15>")
	)
	(segment
		(start 419.215062 -206.97571)
		(end 416.383978 -206.97571)
		(width 0.18288)
		(layer "In11.Cu")
		(net "M_H_CPU0_SB_DQ<15>")
	)
	(segment
		(start 375.839482 -230.41102)
		(end 375.82475 -230.402384)
		(width 0.088646)
		(layer "In11.Cu")
		(net "M_H_CPU0_SB_DQ<15>")
	)
	(segment
		(start 405.060658 -208.919826)
		(end 399.336514 -214.64397)
		(width 0.18288)
		(layer "In11.Cu")
		(net "M_H_CPU0_SB_DQ<15>")
	)
	(segment
		(start 455.011282 -214.316564)
		(end 453.078088 -213.310216)
		(width 0.18288)
		(layer "In11.Cu")
		(net "M_H_CPU0_SB_DQ<15>")
	)
	(segment
		(start 441.665868 -206.238602)
		(end 435.051962 -206.238602)
		(width 0.18288)
		(layer "In11.Cu")
		(net "M_H_CPU0_SB_DQ<15>")
	)
	(segment
		(start 431.442876 -206.39659)
		(end 430.722278 -207.117188)
		(width 0.18288)
		(layer "In11.Cu")
		(net "M_H_CPU0_SB_DQ<15>")
	)
	(segment
		(start 451.95871 -212.190838)
		(end 450.618606 -212.190838)
		(width 0.18288)
		(layer "In11.Cu")
		(net "M_H_CPU0_SB_DQ<15>")
	)
	(segment
		(start 445.938148 -207.739488)
		(end 443.166754 -207.739488)
		(width 0.18288)
		(layer "In11.Cu")
		(net "M_H_CPU0_SB_DQ<15>")
	)
	(segment
		(start 449.976494 -211.307426)
		(end 448.118484 -209.919824)
		(width 0.18288)
		(layer "In11.Cu")
		(net "M_H_CPU0_SB_DQ<15>")
	)
	(segment
		(start 422.02481 -207.141826)
		(end 421.12692 -206.243936)
		(width 0.18288)
		(layer "In11.Cu")
		(net "M_H_CPU0_SB_DQ<15>")
	)
	(segment
		(start 435.051962 -206.238602)
		(end 434.893974 -206.39659)
		(width 0.18288)
		(layer "In11.Cu")
		(net "M_H_CPU0_SB_DQ<15>")
	)
	(segment
		(start 373.394732 -230.41102)
		(end 373.3165 -230.456232)
		(width 0.088646)
		(layer "In11.Cu")
		(net "M_H_CPU0_SB_DQ<15>")
	)
	(segment
		(start 392.416792 -224.724468)
		(end 388.994396 -228.146864)
		(width 0.18288)
		(layer "In11.Cu")
		(net "M_H_CPU0_SB_DQ<15>")
	)
	(segment
		(start 430.722278 -207.117188)
		(end 427.57725 -207.117188)
		(width 0.18288)
		(layer "In11.Cu")
		(net "M_H_CPU0_SB_DQ<15>")
	)
	(segment
		(start 376.779282 -230.41102)
		(end 376.76455 -230.402384)
		(width 0.088646)
		(layer "In11.Cu")
		(net "M_H_CPU0_SB_DQ<15>")
	)
	(segment
		(start 448.118484 -209.919824)
		(end 445.938148 -207.739488)
		(width 0.18288)
		(layer "In11.Cu")
		(net "M_H_CPU0_SB_DQ<15>")
	)
	(segment
		(start 412.477712 -206.990442)
		(end 412.004764 -206.990442)
		(width 0.18288)
		(layer "In11.Cu")
		(net "M_H_CPU0_SB_DQ<15>")
	)
	(segment
		(start 399.336514 -214.64397)
		(end 399.336514 -216.775538)
		(width 0.18288)
		(layer "In11.Cu")
		(net "M_H_CPU0_SB_DQ<15>")
	)
	(segment
		(start 387.704076 -228.146864)
		(end 387.471158 -228.379782)
		(width 0.088646)
		(layer "In11.Cu")
		(net "M_H_CPU0_SB_DQ<15>")
	)
	(segment
		(start 427.57725 -207.117188)
		(end 426.701204 -206.241142)
		(width 0.18288)
		(layer "In11.Cu")
		(net "M_H_CPU0_SB_DQ<15>")
	)
	(segment
		(start 412.004764 -206.990442)
		(end 409.5115 -208.181702)
		(width 0.18288)
		(layer "In11.Cu")
		(net "M_H_CPU0_SB_DQ<15>")
	)
	(segment
		(start 426.701204 -206.241142)
		(end 424.27525 -206.241142)
		(width 0.18288)
		(layer "In11.Cu")
		(net "M_H_CPU0_SB_DQ<15>")
	)
	(segment
		(start 407.966164 -208.919826)
		(end 405.060658 -208.919826)
		(width 0.18288)
		(layer "In11.Cu")
		(net "M_H_CPU0_SB_DQ<15>")
	)
	(segment
		(start 421.12692 -206.243936)
		(end 420.360602 -206.243936)
		(width 0.18288)
		(layer "In11.Cu")
		(net "M_H_CPU0_SB_DQ<15>")
	)
	(segment
		(start 443.166754 -207.739488)
		(end 441.665868 -206.238602)
		(width 0.18288)
		(layer "In11.Cu")
		(net "M_H_CPU0_SB_DQ<15>")
	)
	(segment
		(start 408.710892 -207.24749)
		(end 408.37358 -207.40878)
		(width 0.18288)
		(layer "In11.Cu")
		(net "M_H_CPU0_SB_DQ<15>")
	)
	(segment
		(start 386.422646 -229.521512)
		(end 386.364734 -229.521512)
		(width 0.088646)
		(layer "In11.Cu")
		(net "M_H_CPU0_SB_DQ<15>")
	)
	(segment
		(start 373.959882 -230.41102)
		(end 373.949468 -230.404924)
		(width 0.088646)
		(layer "In11.Cu")
		(net "M_H_CPU0_SB_DQ<15>")
	)
	(segment
		(start 409.298394 -208.106264)
		(end 408.923998 -207.322928)
		(width 0.18288)
		(layer "In11.Cu")
		(net "M_H_CPU0_SB_DQ<15>")
	)
	(segment
		(start 434.893974 -206.39659)
		(end 431.442876 -206.39659)
		(width 0.18288)
		(layer "In11.Cu")
		(net "M_H_CPU0_SB_DQ<15>")
	)
	(segment
		(start 416.383978 -206.97571)
		(end 416.067494 -207.292194)
		(width 0.18288)
		(layer "In11.Cu")
		(net "M_H_CPU0_SB_DQ<15>")
	)
	(segment
		(start 408.298142 -207.621886)
		(end 408.672538 -208.405222)
		(width 0.18288)
		(layer "In11.Cu")
		(net "M_H_CPU0_SB_DQ<15>")
	)
	(segment
		(start 408.37358 -207.40878)
		(end 408.298142 -207.621886)
		(width 0.18288)
		(layer "In11.Cu")
		(net "M_H_CPU0_SB_DQ<15>")
	)
	(segment
		(start 423.374566 -207.141826)
		(end 422.02481 -207.141826)
		(width 0.18288)
		(layer "In11.Cu")
		(net "M_H_CPU0_SB_DQ<15>")
	)
	(segment
		(start 379.598936 -230.41102)
		(end 379.588522 -230.404924)
		(width 0.088646)
		(layer "In11.Cu")
		(net "M_H_CPU0_SB_DQ<15>")
	)
	(segment
		(start 387.471158 -228.379782)
		(end 387.471158 -228.473)
		(width 0.088646)
		(layer "In11.Cu")
		(net "M_H_CPU0_SB_DQ<15>")
	)
	(segment
		(start 420.360602 -206.243936)
		(end 419.921436 -206.683102)
		(width 0.18288)
		(layer "In11.Cu")
		(net "M_H_CPU0_SB_DQ<15>")
	)
	(segment
		(start 399.336514 -216.775538)
		(end 392.416792 -223.69526)
		(width 0.18288)
		(layer "In11.Cu")
		(net "M_H_CPU0_SB_DQ<15>")
	)
	(segment
		(start 381.478536 -230.41102)
		(end 381.468122 -230.404924)
		(width 0.088646)
		(layer "In11.Cu")
		(net "M_H_CPU0_SB_DQ<15>")
	)
	(segment
		(start 450.618606 -212.190838)
		(end 450.281294 -211.853526)
		(width 0.18288)
		(layer "In11.Cu")
		(net "M_H_CPU0_SB_DQ<15>")
	)
	(segment
		(start 392.416792 -223.69526)
		(end 392.416792 -224.724468)
		(width 0.18288)
		(layer "In11.Cu")
		(net "M_H_CPU0_SB_DQ<15>")
	)
	(segment
		(start 419.921436 -206.683102)
		(end 419.215062 -206.97571)
		(width 0.18288)
		(layer "In11.Cu")
		(net "M_H_CPU0_SB_DQ<15>")
	)
	(segment
		(start 388.994396 -228.146864)
		(end 388.10311 -228.146864)
		(width 0.18288)
		(layer "In11.Cu")
		(net "M_H_CPU0_SB_DQ<15>")
	)
	(segment
		(start 408.5971 -208.618328)
		(end 407.966164 -208.919826)
		(width 0.18288)
		(layer "In11.Cu")
		(net "M_H_CPU0_SB_DQ<15>")
	)
	(segment
		(start 413.527748 -207.292194)
		(end 412.477712 -206.990442)
		(width 0.18288)
		(layer "In11.Cu")
		(net "M_H_CPU0_SB_DQ<15>")
	)
	(segment
		(start 374.899682 -230.41102)
		(end 374.88495 -230.402384)
		(width 0.088646)
		(layer "In11.Cu")
		(net "M_H_CPU0_SB_DQ<15>")
	)
	(arc
		(start 383.358136 -230.41102)
		(mid 383.075434 -230.335244)
		(end 382.792732 -230.41102)
		(width 0.088646)
		(layer "In11.Cu")
		(net "M_H_CPU0_SB_DQ<15>")
	)
	(arc
		(start 381.468122 -230.404924)
		(mid 381.18969 -230.335078)
		(end 380.912878 -230.41102)
		(width 0.088646)
		(layer "In11.Cu")
		(net "M_H_CPU0_SB_DQ<15>")
	)
	(arc
		(start 378.64415 -230.402384)
		(mid 378.367675 -230.335064)
		(end 378.093478 -230.41102)
		(width 0.088646)
		(layer "In11.Cu")
		(net "M_H_CPU0_SB_DQ<15>")
	)
	(arc
		(start 379.033278 -230.41102)
		(mid 378.84608 -230.461163)
		(end 378.658882 -230.41102)
		(width 0.088646)
		(layer "In11.Cu")
		(net "M_H_CPU0_SB_DQ<15>")
	)
	(arc
		(start 377.70435 -230.402384)
		(mid 377.427875 -230.335064)
		(end 377.153678 -230.41102)
		(width 0.088646)
		(layer "In11.Cu")
		(net "M_H_CPU0_SB_DQ<15>")
	)
	(arc
		(start 376.76455 -230.402384)
		(mid 376.488075 -230.335064)
		(end 376.213878 -230.41102)
		(width 0.088646)
		(layer "In11.Cu")
		(net "M_H_CPU0_SB_DQ<15>")
	)
	(arc
		(start 385.612132 -230.41102)
		(mid 385.424934 -230.461163)
		(end 385.237736 -230.41102)
		(width 0.088646)
		(layer "In11.Cu")
		(net "M_H_CPU0_SB_DQ<15>")
	)
	(arc
		(start 377.153678 -230.41102)
		(mid 376.96648 -230.461163)
		(end 376.779282 -230.41102)
		(width 0.088646)
		(layer "In11.Cu")
		(net "M_H_CPU0_SB_DQ<15>")
	)
	(arc
		(start 385.237736 -230.41102)
		(mid 384.955034 -230.335244)
		(end 384.672332 -230.41102)
		(width 0.088646)
		(layer "In11.Cu")
		(net "M_H_CPU0_SB_DQ<15>")
	)
	(arc
		(start 385.799584 -230.086662)
		(mid 385.751905 -230.269562)
		(end 385.621022 -230.40594)
		(width 0.088646)
		(layer "In11.Cu")
		(net "M_H_CPU0_SB_DQ<15>")
	)
	(arc
		(start 374.88495 -230.402384)
		(mid 374.608475 -230.335064)
		(end 374.334278 -230.41102)
		(width 0.088646)
		(layer "In11.Cu")
		(net "M_H_CPU0_SB_DQ<15>")
	)
	(arc
		(start 382.418336 -230.41102)
		(mid 382.135634 -230.335244)
		(end 381.852932 -230.41102)
		(width 0.088646)
		(layer "In11.Cu")
		(net "M_H_CPU0_SB_DQ<15>")
	)
	(arc
		(start 375.274078 -230.41102)
		(mid 375.08688 -230.461163)
		(end 374.899682 -230.41102)
		(width 0.088646)
		(layer "In11.Cu")
		(net "M_H_CPU0_SB_DQ<15>")
	)
	(arc
		(start 380.538482 -230.41102)
		(mid 380.261923 -230.335277)
		(end 379.983746 -230.404924)
		(width 0.088646)
		(layer "In11.Cu")
		(net "M_H_CPU0_SB_DQ<15>")
	)
	(arc
		(start 383.732532 -230.41102)
		(mid 383.545334 -230.461163)
		(end 383.358136 -230.41102)
		(width 0.088646)
		(layer "In11.Cu")
		(net "M_H_CPU0_SB_DQ<15>")
	)
	(arc
		(start 378.093478 -230.41102)
		(mid 377.90628 -230.461163)
		(end 377.719082 -230.41102)
		(width 0.088646)
		(layer "In11.Cu")
		(net "M_H_CPU0_SB_DQ<15>")
	)
	(arc
		(start 382.792732 -230.41102)
		(mid 382.605534 -230.461163)
		(end 382.418336 -230.41102)
		(width 0.088646)
		(layer "In11.Cu")
		(net "M_H_CPU0_SB_DQ<15>")
	)
	(arc
		(start 373.3165 -230.456232)
		(mid 373.012512 -230.65939)
		(end 372.737634 -230.900478)
		(width 0.088646)
		(layer "In11.Cu")
		(net "M_H_CPU0_SB_DQ<15>")
	)
	(arc
		(start 376.213878 -230.41102)
		(mid 376.02668 -230.461163)
		(end 375.839482 -230.41102)
		(width 0.088646)
		(layer "In11.Cu")
		(net "M_H_CPU0_SB_DQ<15>")
	)
	(arc
		(start 381.852932 -230.41102)
		(mid 381.665734 -230.461163)
		(end 381.478536 -230.41102)
		(width 0.088646)
		(layer "In11.Cu")
		(net "M_H_CPU0_SB_DQ<15>")
	)
	(arc
		(start 373.949468 -230.404924)
		(mid 373.67129 -230.335201)
		(end 373.394732 -230.41102)
		(width 0.088646)
		(layer "In11.Cu")
		(net "M_H_CPU0_SB_DQ<15>")
	)
	(arc
		(start 384.297936 -230.41102)
		(mid 384.015234 -230.335244)
		(end 383.732532 -230.41102)
		(width 0.088646)
		(layer "In11.Cu")
		(net "M_H_CPU0_SB_DQ<15>")
	)
	(arc
		(start 379.973332 -230.41102)
		(mid 379.786134 -230.461163)
		(end 379.598936 -230.41102)
		(width 0.088646)
		(layer "In11.Cu")
		(net "M_H_CPU0_SB_DQ<15>")
	)
	(arc
		(start 384.672332 -230.41102)
		(mid 384.485134 -230.461163)
		(end 384.297936 -230.41102)
		(width 0.088646)
		(layer "In11.Cu")
		(net "M_H_CPU0_SB_DQ<15>")
	)
	(arc
		(start 375.82475 -230.402384)
		(mid 375.548275 -230.335064)
		(end 375.274078 -230.41102)
		(width 0.088646)
		(layer "In11.Cu")
		(net "M_H_CPU0_SB_DQ<15>")
	)
	(arc
		(start 386.364734 -229.521512)
		(mid 385.96863 -229.683554)
		(end 385.799584 -230.076756)
		(width 0.088646)
		(layer "In11.Cu")
		(net "M_H_CPU0_SB_DQ<15>")
	)
	(arc
		(start 374.334278 -230.41102)
		(mid 374.14708 -230.461163)
		(end 373.959882 -230.41102)
		(width 0.088646)
		(layer "In11.Cu")
		(net "M_H_CPU0_SB_DQ<15>")
	)
	(arc
		(start 380.912878 -230.41102)
		(mid 380.72568 -230.461163)
		(end 380.538482 -230.41102)
		(width 0.088646)
		(layer "In11.Cu")
		(net "M_H_CPU0_SB_DQ<15>")
	)
	(arc
		(start 379.588522 -230.404924)
		(mid 379.31009 -230.335078)
		(end 379.033278 -230.41102)
		(width 0.088646)
		(layer "In11.Cu")
		(net "M_H_CPU0_SB_DQ<15>")
	)
	(segment
		(start 461.689704 -215.764618)
		(end 462.073752 -215.764618)
		(width 0.20066)
		(layer "F.Cu")
		(net "M_H_CPU0_SB_DQ<14>")
	)
	(segment
		(start 462.073752 -215.764618)
		(end 462.32572 -216.016586)
		(width 0.20066)
		(layer "F.Cu")
		(net "M_H_CPU0_SB_DQ<14>")
	)
	(segment
		(start 373.20728 -232.250234)
		(end 373.20728 -231.714548)
		(width 0.20066)
		(layer "F.Cu")
		(net "M_H_CPU0_SB_DQ<14>")
	)
	(segment
		(start 457.814426 -216.016586)
		(end 458.24648 -216.44864)
		(width 0.20066)
		(layer "F.Cu")
		(net "M_H_CPU0_SB_DQ<14>")
	)
	(segment
		(start 462.32572 -216.016586)
		(end 463.659982 -216.016586)
		(width 0.20066)
		(layer "F.Cu")
		(net "M_H_CPU0_SB_DQ<14>")
	)
	(segment
		(start 458.538326 -216.44864)
		(end 458.543152 -216.44864)
		(width 0.101854)
		(layer "F.Cu")
		(net "M_H_CPU0_SB_DQ<14>")
	)
	(segment
		(start 458.550264 -216.441528)
		(end 460.558134 -216.441528)
		(width 0.1016)
		(layer "F.Cu")
		(net "M_H_CPU0_SB_DQ<14>")
	)
	(segment
		(start 461.251554 -216.45372)
		(end 461.455516 -216.249758)
		(width 0.20066)
		(layer "F.Cu")
		(net "M_H_CPU0_SB_DQ<14>")
	)
	(segment
		(start 461.455516 -216.249758)
		(end 461.455516 -215.998806)
		(width 0.20066)
		(layer "F.Cu")
		(net "M_H_CPU0_SB_DQ<14>")
	)
	(segment
		(start 373.207534 -232.250488)
		(end 373.20728 -232.250234)
		(width 0.20066)
		(layer "F.Cu")
		(net "M_H_CPU0_SB_DQ<14>")
	)
	(segment
		(start 460.570326 -216.45372)
		(end 461.251554 -216.45372)
		(width 0.20066)
		(layer "F.Cu")
		(net "M_H_CPU0_SB_DQ<14>")
	)
	(segment
		(start 458.543152 -216.44864)
		(end 458.550264 -216.441528)
		(width 0.1016)
		(layer "F.Cu")
		(net "M_H_CPU0_SB_DQ<14>")
	)
	(segment
		(start 458.24648 -216.44864)
		(end 458.538326 -216.44864)
		(width 0.20066)
		(layer "F.Cu")
		(net "M_H_CPU0_SB_DQ<14>")
	)
	(segment
		(start 461.455516 -215.998806)
		(end 461.689704 -215.764618)
		(width 0.20066)
		(layer "F.Cu")
		(net "M_H_CPU0_SB_DQ<14>")
	)
	(segment
		(start 456.116182 -216.016586)
		(end 457.814426 -216.016586)
		(width 0.20066)
		(layer "F.Cu")
		(net "M_H_CPU0_SB_DQ<14>")
	)
	(segment
		(start 455.011282 -216.016586)
		(end 456.116182 -216.016586)
		(width 0.20066)
		(layer "F.Cu")
		(net "M_H_CPU0_SB_DQ<14>")
	)
	(segment
		(start 460.558134 -216.441528)
		(end 460.570326 -216.45372)
		(width 0.1016)
		(layer "F.Cu")
		(net "M_H_CPU0_SB_DQ<14>")
	)
	(segment
		(start 420.690802 -208.792572)
		(end 420.689786 -208.791556)
		(width 0.18288)
		(layer "In11.Cu")
		(net "M_H_CPU0_SB_DQ<14>")
	)
	(segment
		(start 386.090922 -231.219756)
		(end 386.082032 -231.224836)
		(width 0.088646)
		(layer "In11.Cu")
		(net "M_H_CPU0_SB_DQ<14>")
	)
	(segment
		(start 426.27042 -208.814162)
		(end 425.440094 -209.644488)
		(width 0.18288)
		(layer "In11.Cu")
		(net "M_H_CPU0_SB_DQ<14>")
	)
	(segment
		(start 431.078894 -208.636362)
		(end 430.901094 -208.814162)
		(width 0.18288)
		(layer "In11.Cu")
		(net "M_H_CPU0_SB_DQ<14>")
	)
	(segment
		(start 413.447992 -209.023204)
		(end 412.511494 -209.402426)
		(width 0.18288)
		(layer "In11.Cu")
		(net "M_H_CPU0_SB_DQ<14>")
	)
	(segment
		(start 416.036252 -209.023204)
		(end 413.447992 -209.023204)
		(width 0.18288)
		(layer "In11.Cu")
		(net "M_H_CPU0_SB_DQ<14>")
	)
	(segment
		(start 411.553914 -209.402426)
		(end 410.296868 -210.427062)
		(width 0.18288)
		(layer "In11.Cu")
		(net "M_H_CPU0_SB_DQ<14>")
	)
	(segment
		(start 449.112894 -212.729826)
		(end 447.512694 -211.129626)
		(width 0.18288)
		(layer "In11.Cu")
		(net "M_H_CPU0_SB_DQ<14>")
	)
	(segment
		(start 452.628508 -216.75725)
		(end 451.462394 -215.591136)
		(width 0.18288)
		(layer "In11.Cu")
		(net "M_H_CPU0_SB_DQ<14>")
	)
	(segment
		(start 420.689786 -208.791556)
		(end 416.2679 -208.791556)
		(width 0.18288)
		(layer "In11.Cu")
		(net "M_H_CPU0_SB_DQ<14>")
	)
	(segment
		(start 393.458954 -224.198942)
		(end 393.458954 -225.152458)
		(width 0.18288)
		(layer "In11.Cu")
		(net "M_H_CPU0_SB_DQ<14>")
	)
	(segment
		(start 423.256202 -209.644488)
		(end 422.404286 -208.792572)
		(width 0.18288)
		(layer "In11.Cu")
		(net "M_H_CPU0_SB_DQ<14>")
	)
	(segment
		(start 435.56174 -207.939132)
		(end 434.86451 -208.636362)
		(width 0.18288)
		(layer "In11.Cu")
		(net "M_H_CPU0_SB_DQ<14>")
	)
	(segment
		(start 400.73707 -216.920826)
		(end 393.458954 -224.198942)
		(width 0.18288)
		(layer "In11.Cu")
		(net "M_H_CPU0_SB_DQ<14>")
	)
	(segment
		(start 373.735854 -231.300528)
		(end 373.616982 -231.370378)
		(width 0.088646)
		(layer "In11.Cu")
		(net "M_H_CPU0_SB_DQ<14>")
	)
	(segment
		(start 387.335776 -229.178358)
		(end 386.703062 -229.811072)
		(width 0.088646)
		(layer "In11.Cu")
		(net "M_H_CPU0_SB_DQ<14>")
	)
	(segment
		(start 409.270454 -210.545426)
		(end 408.36596 -210.367626)
		(width 0.18288)
		(layer "In11.Cu")
		(net "M_H_CPU0_SB_DQ<14>")
	)
	(segment
		(start 375.758964 -231.2162)
		(end 375.744232 -231.224836)
		(width 0.088646)
		(layer "In11.Cu")
		(net "M_H_CPU0_SB_DQ<14>")
	)
	(segment
		(start 388.103364 -229.178358)
		(end 387.335776 -229.178358)
		(width 0.088646)
		(layer "In11.Cu")
		(net "M_H_CPU0_SB_DQ<14>")
	)
	(segment
		(start 408.36596 -210.367626)
		(end 405.186642 -210.367626)
		(width 0.18288)
		(layer "In11.Cu")
		(net "M_H_CPU0_SB_DQ<14>")
	)
	(segment
		(start 410.15158 -210.545426)
		(end 409.270454 -210.545426)
		(width 0.18288)
		(layer "In11.Cu")
		(net "M_H_CPU0_SB_DQ<14>")
	)
	(segment
		(start 447.183002 -211.129626)
		(end 445.45885 -209.405474)
		(width 0.18288)
		(layer "In11.Cu")
		(net "M_H_CPU0_SB_DQ<14>")
	)
	(segment
		(start 445.45885 -209.405474)
		(end 442.87059 -209.405474)
		(width 0.18288)
		(layer "In11.Cu")
		(net "M_H_CPU0_SB_DQ<14>")
	)
	(segment
		(start 442.538612 -209.073496)
		(end 441.979304 -209.073496)
		(width 0.18288)
		(layer "In11.Cu")
		(net "M_H_CPU0_SB_DQ<14>")
	)
	(segment
		(start 378.578364 -231.2162)
		(end 378.563632 -231.224836)
		(width 0.088646)
		(layer "In11.Cu")
		(net "M_H_CPU0_SB_DQ<14>")
	)
	(segment
		(start 449.112894 -215.377014)
		(end 449.112894 -212.729826)
		(width 0.18288)
		(layer "In11.Cu")
		(net "M_H_CPU0_SB_DQ<14>")
	)
	(segment
		(start 389.433054 -229.178358)
		(end 388.103364 -229.178358)
		(width 0.18288)
		(layer "In11.Cu")
		(net "M_H_CPU0_SB_DQ<14>")
	)
	(segment
		(start 400.73707 -214.817198)
		(end 400.73707 -216.920826)
		(width 0.18288)
		(layer "In11.Cu")
		(net "M_H_CPU0_SB_DQ<14>")
	)
	(segment
		(start 450.30898 -215.763856)
		(end 449.499736 -215.763856)
		(width 0.18288)
		(layer "In11.Cu")
		(net "M_H_CPU0_SB_DQ<14>")
	)
	(segment
		(start 450.4817 -215.591136)
		(end 450.30898 -215.763856)
		(width 0.18288)
		(layer "In11.Cu")
		(net "M_H_CPU0_SB_DQ<14>")
	)
	(segment
		(start 410.296868 -210.427062)
		(end 410.15158 -210.545426)
		(width 0.18288)
		(layer "In11.Cu")
		(net "M_H_CPU0_SB_DQ<14>")
	)
	(segment
		(start 393.458954 -225.152458)
		(end 389.433054 -229.178358)
		(width 0.18288)
		(layer "In11.Cu")
		(net "M_H_CPU0_SB_DQ<14>")
	)
	(segment
		(start 447.512694 -211.129626)
		(end 447.183002 -211.129626)
		(width 0.18288)
		(layer "In11.Cu")
		(net "M_H_CPU0_SB_DQ<14>")
	)
	(segment
		(start 380.453392 -231.21874)
		(end 380.442978 -231.224836)
		(width 0.088646)
		(layer "In11.Cu")
		(net "M_H_CPU0_SB_DQ<14>")
	)
	(segment
		(start 379.513846 -231.21874)
		(end 379.503432 -231.224836)
		(width 0.088646)
		(layer "In11.Cu")
		(net "M_H_CPU0_SB_DQ<14>")
	)
	(segment
		(start 386.269484 -230.890572)
		(end 386.269484 -230.900478)
		(width 0.088646)
		(layer "In11.Cu")
		(net "M_H_CPU0_SB_DQ<14>")
	)
	(segment
		(start 451.462394 -215.591136)
		(end 450.4817 -215.591136)
		(width 0.18288)
		(layer "In11.Cu")
		(net "M_H_CPU0_SB_DQ<14>")
	)
	(segment
		(start 442.87059 -209.405474)
		(end 442.538612 -209.073496)
		(width 0.18288)
		(layer "In11.Cu")
		(net "M_H_CPU0_SB_DQ<14>")
	)
	(segment
		(start 425.440094 -209.644488)
		(end 423.256202 -209.644488)
		(width 0.18288)
		(layer "In11.Cu")
		(net "M_H_CPU0_SB_DQ<14>")
	)
	(segment
		(start 430.901094 -208.814162)
		(end 426.27042 -208.814162)
		(width 0.18288)
		(layer "In11.Cu")
		(net "M_H_CPU0_SB_DQ<14>")
	)
	(segment
		(start 374.819164 -231.2162)
		(end 374.804432 -231.224836)
		(width 0.088646)
		(layer "In11.Cu")
		(net "M_H_CPU0_SB_DQ<14>")
	)
	(segment
		(start 412.511494 -209.402426)
		(end 411.553914 -209.402426)
		(width 0.18288)
		(layer "In11.Cu")
		(net "M_H_CPU0_SB_DQ<14>")
	)
	(segment
		(start 454.270618 -216.75725)
		(end 452.628508 -216.75725)
		(width 0.18288)
		(layer "In11.Cu")
		(net "M_H_CPU0_SB_DQ<14>")
	)
	(segment
		(start 434.86451 -208.636362)
		(end 431.078894 -208.636362)
		(width 0.18288)
		(layer "In11.Cu")
		(net "M_H_CPU0_SB_DQ<14>")
	)
	(segment
		(start 440.84494 -207.939132)
		(end 435.56174 -207.939132)
		(width 0.18288)
		(layer "In11.Cu")
		(net "M_H_CPU0_SB_DQ<14>")
	)
	(segment
		(start 373.879364 -231.2162)
		(end 373.76735 -231.281986)
		(width 0.088646)
		(layer "In11.Cu")
		(net "M_H_CPU0_SB_DQ<14>")
	)
	(segment
		(start 455.011282 -216.016586)
		(end 454.270618 -216.75725)
		(width 0.18288)
		(layer "In11.Cu")
		(net "M_H_CPU0_SB_DQ<14>")
	)
	(segment
		(start 416.2679 -208.791556)
		(end 416.036252 -209.023204)
		(width 0.18288)
		(layer "In11.Cu")
		(net "M_H_CPU0_SB_DQ<14>")
	)
	(segment
		(start 449.499736 -215.763856)
		(end 449.112894 -215.377014)
		(width 0.18288)
		(layer "In11.Cu")
		(net "M_H_CPU0_SB_DQ<14>")
	)
	(segment
		(start 386.703062 -229.811072)
		(end 386.703062 -230.278178)
		(width 0.088646)
		(layer "In11.Cu")
		(net "M_H_CPU0_SB_DQ<14>")
	)
	(segment
		(start 405.186642 -210.367626)
		(end 400.73707 -214.817198)
		(width 0.18288)
		(layer "In11.Cu")
		(net "M_H_CPU0_SB_DQ<14>")
	)
	(segment
		(start 377.638564 -231.2162)
		(end 377.623832 -231.224836)
		(width 0.088646)
		(layer "In11.Cu")
		(net "M_H_CPU0_SB_DQ<14>")
	)
	(segment
		(start 441.979304 -209.073496)
		(end 440.84494 -207.939132)
		(width 0.18288)
		(layer "In11.Cu")
		(net "M_H_CPU0_SB_DQ<14>")
	)
	(segment
		(start 422.404286 -208.792572)
		(end 420.690802 -208.792572)
		(width 0.18288)
		(layer "In11.Cu")
		(net "M_H_CPU0_SB_DQ<14>")
	)
	(arc
		(start 374.804432 -231.224836)
		(mid 374.617234 -231.274979)
		(end 374.430036 -231.224836)
		(width 0.088646)
		(layer "In11.Cu")
		(net "M_H_CPU0_SB_DQ<14>")
	)
	(arc
		(start 380.068582 -231.224836)
		(mid 379.792023 -231.149127)
		(end 379.513846 -231.21874)
		(width 0.088646)
		(layer "In11.Cu")
		(net "M_H_CPU0_SB_DQ<14>")
	)
	(arc
		(start 373.616982 -231.370378)
		(mid 373.5754 -231.397701)
		(end 373.536972 -231.429306)
		(width 0.088646)
		(layer "In11.Cu")
		(net "M_H_CPU0_SB_DQ<14>")
	)
	(arc
		(start 377.249436 -231.224836)
		(mid 376.966734 -231.149094)
		(end 376.684032 -231.224836)
		(width 0.088646)
		(layer "In11.Cu")
		(net "M_H_CPU0_SB_DQ<14>")
	)
	(arc
		(start 385.707636 -231.224836)
		(mid 385.424934 -231.149094)
		(end 385.142232 -231.224836)
		(width 0.088646)
		(layer "In11.Cu")
		(net "M_H_CPU0_SB_DQ<14>")
	)
	(arc
		(start 382.888236 -231.224836)
		(mid 382.605534 -231.149094)
		(end 382.322832 -231.224836)
		(width 0.088646)
		(layer "In11.Cu")
		(net "M_H_CPU0_SB_DQ<14>")
	)
	(arc
		(start 381.948436 -231.224836)
		(mid 381.665734 -231.149094)
		(end 381.383032 -231.224836)
		(width 0.088646)
		(layer "In11.Cu")
		(net "M_H_CPU0_SB_DQ<14>")
	)
	(arc
		(start 384.767836 -231.224836)
		(mid 384.485134 -231.149094)
		(end 384.202432 -231.224836)
		(width 0.088646)
		(layer "In11.Cu")
		(net "M_H_CPU0_SB_DQ<14>")
	)
	(arc
		(start 383.828036 -231.224836)
		(mid 383.545334 -231.149094)
		(end 383.262632 -231.224836)
		(width 0.088646)
		(layer "In11.Cu")
		(net "M_H_CPU0_SB_DQ<14>")
	)
	(arc
		(start 386.703062 -230.278178)
		(mid 386.612695 -230.360509)
		(end 386.515102 -230.434134)
		(width 0.088646)
		(layer "In11.Cu")
		(net "M_H_CPU0_SB_DQ<14>")
	)
	(arc
		(start 382.322832 -231.224836)
		(mid 382.135634 -231.274979)
		(end 381.948436 -231.224836)
		(width 0.088646)
		(layer "In11.Cu")
		(net "M_H_CPU0_SB_DQ<14>")
	)
	(arc
		(start 386.515102 -230.434134)
		(mid 386.336857 -230.632532)
		(end 386.269484 -230.890572)
		(width 0.088646)
		(layer "In11.Cu")
		(net "M_H_CPU0_SB_DQ<14>")
	)
	(arc
		(start 386.082032 -231.224836)
		(mid 385.894834 -231.274979)
		(end 385.707636 -231.224836)
		(width 0.088646)
		(layer "In11.Cu")
		(net "M_H_CPU0_SB_DQ<14>")
	)
	(arc
		(start 377.623832 -231.224836)
		(mid 377.436634 -231.274979)
		(end 377.249436 -231.224836)
		(width 0.088646)
		(layer "In11.Cu")
		(net "M_H_CPU0_SB_DQ<14>")
	)
	(arc
		(start 375.369836 -231.224836)
		(mid 375.095607 -231.148911)
		(end 374.819164 -231.2162)
		(width 0.088646)
		(layer "In11.Cu")
		(net "M_H_CPU0_SB_DQ<14>")
	)
	(arc
		(start 373.76735 -231.281986)
		(mid 373.751572 -231.291206)
		(end 373.735854 -231.300528)
		(width 0.088646)
		(layer "In11.Cu")
		(net "M_H_CPU0_SB_DQ<14>")
	)
	(arc
		(start 373.536972 -231.429306)
		(mid 373.519688 -231.444481)
		(end 373.501666 -231.45877)
		(width 0.088646)
		(layer "In11.Cu")
		(net "M_H_CPU0_SB_DQ<14>")
	)
	(arc
		(start 380.442978 -231.224836)
		(mid 380.25578 -231.274979)
		(end 380.068582 -231.224836)
		(width 0.088646)
		(layer "In11.Cu")
		(net "M_H_CPU0_SB_DQ<14>")
	)
	(arc
		(start 375.744232 -231.224836)
		(mid 375.557034 -231.274979)
		(end 375.369836 -231.224836)
		(width 0.088646)
		(layer "In11.Cu")
		(net "M_H_CPU0_SB_DQ<14>")
	)
	(arc
		(start 379.503432 -231.224836)
		(mid 379.316234 -231.274979)
		(end 379.129036 -231.224836)
		(width 0.088646)
		(layer "In11.Cu")
		(net "M_H_CPU0_SB_DQ<14>")
	)
	(arc
		(start 381.383032 -231.224836)
		(mid 381.195834 -231.274979)
		(end 381.008636 -231.224836)
		(width 0.088646)
		(layer "In11.Cu")
		(net "M_H_CPU0_SB_DQ<14>")
	)
	(arc
		(start 374.430036 -231.224836)
		(mid 374.155807 -231.148911)
		(end 373.879364 -231.2162)
		(width 0.088646)
		(layer "In11.Cu")
		(net "M_H_CPU0_SB_DQ<14>")
	)
	(arc
		(start 379.129036 -231.224836)
		(mid 378.854807 -231.148911)
		(end 378.578364 -231.2162)
		(width 0.088646)
		(layer "In11.Cu")
		(net "M_H_CPU0_SB_DQ<14>")
	)
	(arc
		(start 383.262632 -231.224836)
		(mid 383.075434 -231.274979)
		(end 382.888236 -231.224836)
		(width 0.088646)
		(layer "In11.Cu")
		(net "M_H_CPU0_SB_DQ<14>")
	)
	(arc
		(start 384.202432 -231.224836)
		(mid 384.015234 -231.274979)
		(end 383.828036 -231.224836)
		(width 0.088646)
		(layer "In11.Cu")
		(net "M_H_CPU0_SB_DQ<14>")
	)
	(arc
		(start 386.269484 -230.900478)
		(mid 386.221805 -231.083378)
		(end 386.090922 -231.219756)
		(width 0.088646)
		(layer "In11.Cu")
		(net "M_H_CPU0_SB_DQ<14>")
	)
	(arc
		(start 385.142232 -231.224836)
		(mid 384.955034 -231.274979)
		(end 384.767836 -231.224836)
		(width 0.088646)
		(layer "In11.Cu")
		(net "M_H_CPU0_SB_DQ<14>")
	)
	(arc
		(start 378.189236 -231.224836)
		(mid 377.915007 -231.148911)
		(end 377.638564 -231.2162)
		(width 0.088646)
		(layer "In11.Cu")
		(net "M_H_CPU0_SB_DQ<14>")
	)
	(arc
		(start 373.501666 -231.45877)
		(mid 373.349984 -231.581493)
		(end 373.20728 -231.714548)
		(width 0.088646)
		(layer "In11.Cu")
		(net "M_H_CPU0_SB_DQ<14>")
	)
	(arc
		(start 376.684032 -231.224836)
		(mid 376.496834 -231.274979)
		(end 376.309636 -231.224836)
		(width 0.088646)
		(layer "In11.Cu")
		(net "M_H_CPU0_SB_DQ<14>")
	)
	(arc
		(start 381.008636 -231.224836)
		(mid 380.731823 -231.149)
		(end 380.453392 -231.21874)
		(width 0.088646)
		(layer "In11.Cu")
		(net "M_H_CPU0_SB_DQ<14>")
	)
	(arc
		(start 376.309636 -231.224836)
		(mid 376.035407 -231.148911)
		(end 375.758964 -231.2162)
		(width 0.088646)
		(layer "In11.Cu")
		(net "M_H_CPU0_SB_DQ<14>")
	)
	(arc
		(start 378.563632 -231.224836)
		(mid 378.376434 -231.274979)
		(end 378.189236 -231.224836)
		(width 0.088646)
		(layer "In11.Cu")
		(net "M_H_CPU0_SB_DQ<14>")
	)
	(segment
		(start 457.53655 -214.73541)
		(end 457.126594 -214.73541)
		(width 0.20066)
		(layer "F.Cu")
		(net "M_H_CPU0_SB_DQ<13>")
	)
	(segment
		(start 454.448672 -215.227408)
		(end 454.260712 -215.415368)
		(width 0.20066)
		(layer "F.Cu")
		(net "M_H_CPU0_SB_DQ<13>")
	)
	(segment
		(start 454.931526 -214.74176)
		(end 454.91146 -214.74176)
		(width 0.101854)
		(layer "F.Cu")
		(net "M_H_CPU0_SB_DQ<13>")
	)
	(segment
		(start 371.79758 -230.900732)
		(end 371.797834 -230.900478)
		(width 0.20066)
		(layer "F.Cu")
		(net "M_H_CPU0_SB_DQ<13>")
	)
	(segment
		(start 459.559914 -215.166702)
		(end 459.55966 -215.166956)
		(width 0.20066)
		(layer "F.Cu")
		(net "M_H_CPU0_SB_DQ<13>")
	)
	(segment
		(start 457.120244 -214.74176)
		(end 454.931526 -214.74176)
		(width 0.1016)
		(layer "F.Cu")
		(net "M_H_CPU0_SB_DQ<13>")
	)
	(segment
		(start 454.260712 -215.415368)
		(end 453.785478 -215.415368)
		(width 0.20066)
		(layer "F.Cu")
		(net "M_H_CPU0_SB_DQ<13>")
	)
	(segment
		(start 371.79758 -231.436418)
		(end 371.79758 -230.900732)
		(width 0.20066)
		(layer "F.Cu")
		(net "M_H_CPU0_SB_DQ<13>")
	)
	(segment
		(start 457.126594 -214.73541)
		(end 457.120244 -214.74176)
		(width 0.1016)
		(layer "F.Cu")
		(net "M_H_CPU0_SB_DQ<13>")
	)
	(segment
		(start 453.785478 -215.415368)
		(end 453.536812 -215.166702)
		(width 0.20066)
		(layer "F.Cu")
		(net "M_H_CPU0_SB_DQ<13>")
	)
	(segment
		(start 459.55966 -215.166956)
		(end 457.968096 -215.166956)
		(width 0.20066)
		(layer "F.Cu")
		(net "M_H_CPU0_SB_DQ<13>")
	)
	(segment
		(start 454.448672 -214.85987)
		(end 454.448672 -215.227408)
		(width 0.20066)
		(layer "F.Cu")
		(net "M_H_CPU0_SB_DQ<13>")
	)
	(segment
		(start 457.968096 -215.166956)
		(end 457.53655 -214.73541)
		(width 0.20066)
		(layer "F.Cu")
		(net "M_H_CPU0_SB_DQ<13>")
	)
	(segment
		(start 452.016114 -215.166702)
		(end 450.911214 -215.166702)
		(width 0.20066)
		(layer "F.Cu")
		(net "M_H_CPU0_SB_DQ<13>")
	)
	(segment
		(start 454.566782 -214.74176)
		(end 454.448672 -214.85987)
		(width 0.20066)
		(layer "F.Cu")
		(net "M_H_CPU0_SB_DQ<13>")
	)
	(segment
		(start 454.91146 -214.74176)
		(end 454.566782 -214.74176)
		(width 0.20066)
		(layer "F.Cu")
		(net "M_H_CPU0_SB_DQ<13>")
	)
	(segment
		(start 453.536812 -215.166702)
		(end 452.016114 -215.166702)
		(width 0.20066)
		(layer "F.Cu")
		(net "M_H_CPU0_SB_DQ<13>")
	)
	(segment
		(start 429.092868 -207.822546)
		(end 428.899828 -207.629506)
		(width 0.18288)
		(layer "In11.Cu")
		(net "M_H_CPU0_SB_DQ<13>")
	)
	(segment
		(start 433.348384 -206.920592)
		(end 433.155344 -207.113632)
		(width 0.18288)
		(layer "In11.Cu")
		(net "M_H_CPU0_SB_DQ<13>")
	)
	(segment
		(start 450.911214 -215.166702)
		(end 450.911214 -215.03132)
		(width 0.18288)
		(layer "In11.Cu")
		(net "M_H_CPU0_SB_DQ<13>")
	)
	(segment
		(start 386.52704 -229.711758)
		(end 386.364734 -229.711758)
		(width 0.088646)
		(layer "In11.Cu")
		(net "M_H_CPU0_SB_DQ<13>")
	)
	(segment
		(start 419.961822 -208.268316)
		(end 416.87115 -208.268316)
		(width 0.18288)
		(layer "In11.Cu")
		(net "M_H_CPU0_SB_DQ<13>")
	)
	(segment
		(start 442.313314 -208.107026)
		(end 441.899294 -208.107026)
		(width 0.18288)
		(layer "In11.Cu")
		(net "M_H_CPU0_SB_DQ<13>")
	)
	(segment
		(start 434.80863 -207.964278)
		(end 434.051964 -207.964278)
		(width 0.18288)
		(layer "In11.Cu")
		(net "M_H_CPU0_SB_DQ<13>")
	)
	(segment
		(start 420.291514 -207.938624)
		(end 419.961822 -208.268316)
		(width 0.18288)
		(layer "In11.Cu")
		(net "M_H_CPU0_SB_DQ<13>")
	)
	(segment
		(start 429.285908 -208.301336)
		(end 429.092868 -208.108296)
		(width 0.18288)
		(layer "In11.Cu")
		(net "M_H_CPU0_SB_DQ<13>")
	)
	(segment
		(start 372.175786 -230.96601)
		(end 372.110254 -230.900478)
		(width 0.088646)
		(layer "In11.Cu")
		(net "M_H_CPU0_SB_DQ<13>")
	)
	(segment
		(start 413.065214 -207.85201)
		(end 412.149798 -208.767426)
		(width 0.18288)
		(layer "In11.Cu")
		(net "M_H_CPU0_SB_DQ<13>")
	)
	(segment
		(start 429.603408 -208.301336)
		(end 429.285908 -208.301336)
		(width 0.18288)
		(layer "In11.Cu")
		(net "M_H_CPU0_SB_DQ<13>")
	)
	(segment
		(start 435.20995 -207.30845)
		(end 435.20995 -207.562958)
		(width 0.18288)
		(layer "In11.Cu")
		(net "M_H_CPU0_SB_DQ<13>")
	)
	(segment
		(start 400.05 -216.866216)
		(end 392.92911 -223.987106)
		(width 0.18288)
		(layer "In11.Cu")
		(net "M_H_CPU0_SB_DQ<13>")
	)
	(segment
		(start 424.08221 -207.939132)
		(end 420.672006 -207.939132)
		(width 0.18288)
		(layer "In11.Cu")
		(net "M_H_CPU0_SB_DQ<13>")
	)
	(segment
		(start 416.454844 -207.85201)
		(end 413.065214 -207.85201)
		(width 0.18288)
		(layer "In11.Cu")
		(net "M_H_CPU0_SB_DQ<13>")
	)
	(segment
		(start 378.578364 -230.584756)
		(end 378.563632 -230.57612)
		(width 0.088646)
		(layer "In11.Cu")
		(net "M_H_CPU0_SB_DQ<13>")
	)
	(segment
		(start 388.10311 -228.670358)
		(end 387.56844 -228.670358)
		(width 0.088646)
		(layer "In11.Cu")
		(net "M_H_CPU0_SB_DQ<13>")
	)
	(segment
		(start 433.155344 -207.771238)
		(end 432.962304 -207.964278)
		(width 0.18288)
		(layer "In11.Cu")
		(net "M_H_CPU0_SB_DQ<13>")
	)
	(segment
		(start 374.819164 -230.584756)
		(end 374.804432 -230.57612)
		(width 0.088646)
		(layer "In11.Cu")
		(net "M_H_CPU0_SB_DQ<13>")
	)
	(segment
		(start 380.068582 -230.57612)
		(end 380.058168 -230.582216)
		(width 0.088646)
		(layer "In11.Cu")
		(net "M_H_CPU0_SB_DQ<13>")
	)
	(segment
		(start 429.796448 -208.108296)
		(end 429.603408 -208.301336)
		(width 0.18288)
		(layer "In11.Cu")
		(net "M_H_CPU0_SB_DQ<13>")
	)
	(segment
		(start 441.899294 -208.107026)
		(end 440.886088 -207.09382)
		(width 0.18288)
		(layer "In11.Cu")
		(net "M_H_CPU0_SB_DQ<13>")
	)
	(segment
		(start 435.20995 -207.562958)
		(end 434.80863 -207.964278)
		(width 0.18288)
		(layer "In11.Cu")
		(net "M_H_CPU0_SB_DQ<13>")
	)
	(segment
		(start 425.464732 -207.940402)
		(end 424.903646 -207.938624)
		(width 0.18288)
		(layer "In11.Cu")
		(net "M_H_CPU0_SB_DQ<13>")
	)
	(segment
		(start 373.30253 -230.90124)
		(end 373.30253 -230.922576)
		(width 0.088646)
		(layer "In11.Cu")
		(net "M_H_CPU0_SB_DQ<13>")
	)
	(segment
		(start 428.899828 -207.629506)
		(end 427.801024 -207.629506)
		(width 0.18288)
		(layer "In11.Cu")
		(net "M_H_CPU0_SB_DQ<13>")
	)
	(segment
		(start 410.901642 -208.574386)
		(end 410.708602 -208.767426)
		(width 0.18288)
		(layer "In11.Cu")
		(net "M_H_CPU0_SB_DQ<13>")
	)
	(segment
		(start 447.842894 -210.596226)
		(end 447.378582 -210.596226)
		(width 0.18288)
		(layer "In11.Cu")
		(net "M_H_CPU0_SB_DQ<13>")
	)
	(segment
		(start 429.796448 -207.822546)
		(end 429.796448 -208.108296)
		(width 0.18288)
		(layer "In11.Cu")
		(net "M_H_CPU0_SB_DQ<13>")
	)
	(segment
		(start 411.412182 -207.988916)
		(end 411.094682 -207.988916)
		(width 0.18288)
		(layer "In11.Cu")
		(net "M_H_CPU0_SB_DQ<13>")
	)
	(segment
		(start 387.56844 -228.670358)
		(end 386.52704 -229.711758)
		(width 0.088646)
		(layer "In11.Cu")
		(net "M_H_CPU0_SB_DQ<13>")
	)
	(segment
		(start 409.082494 -209.681826)
		(end 405.150828 -209.681826)
		(width 0.18288)
		(layer "In11.Cu")
		(net "M_H_CPU0_SB_DQ<13>")
	)
	(segment
		(start 429.989488 -207.629506)
		(end 429.796448 -207.822546)
		(width 0.18288)
		(layer "In11.Cu")
		(net "M_H_CPU0_SB_DQ<13>")
	)
	(segment
		(start 447.378582 -210.596226)
		(end 445.6557 -208.873344)
		(width 0.18288)
		(layer "In11.Cu")
		(net "M_H_CPU0_SB_DQ<13>")
	)
	(segment
		(start 431.22088 -207.629506)
		(end 429.989488 -207.629506)
		(width 0.18288)
		(layer "In11.Cu")
		(net "M_H_CPU0_SB_DQ<13>")
	)
	(segment
		(start 427.801024 -207.629506)
		(end 427.30166 -208.12887)
		(width 0.18288)
		(layer "In11.Cu")
		(net "M_H_CPU0_SB_DQ<13>")
	)
	(segment
		(start 373.879364 -230.584756)
		(end 373.864632 -230.57612)
		(width 0.088646)
		(layer "In11.Cu")
		(net "M_H_CPU0_SB_DQ<13>")
	)
	(segment
		(start 445.6557 -208.873344)
		(end 443.079632 -208.873344)
		(width 0.18288)
		(layer "In11.Cu")
		(net "M_H_CPU0_SB_DQ<13>")
	)
	(segment
		(start 420.672006 -207.939132)
		(end 420.291514 -207.938624)
		(width 0.18288)
		(layer "In11.Cu")
		(net "M_H_CPU0_SB_DQ<13>")
	)
	(segment
		(start 405.150828 -209.681826)
		(end 400.05 -214.782654)
		(width 0.18288)
		(layer "In11.Cu")
		(net "M_H_CPU0_SB_DQ<13>")
	)
	(segment
		(start 450.84238 -214.865204)
		(end 450.332094 -214.354918)
		(width 0.18288)
		(layer "In11.Cu")
		(net "M_H_CPU0_SB_DQ<13>")
	)
	(segment
		(start 431.555652 -207.964278)
		(end 431.22088 -207.629506)
		(width 0.18288)
		(layer "In11.Cu")
		(net "M_H_CPU0_SB_DQ<13>")
	)
	(segment
		(start 389.220202 -228.670358)
		(end 388.10311 -228.670358)
		(width 0.18288)
		(layer "In11.Cu")
		(net "M_H_CPU0_SB_DQ<13>")
	)
	(segment
		(start 377.638564 -230.584756)
		(end 377.623832 -230.57612)
		(width 0.088646)
		(layer "In11.Cu")
		(net "M_H_CPU0_SB_DQ<13>")
	)
	(segment
		(start 385.990084 -230.086662)
		(end 385.990084 -230.096568)
		(width 0.088646)
		(layer "In11.Cu")
		(net "M_H_CPU0_SB_DQ<13>")
	)
	(segment
		(start 411.094682 -207.988916)
		(end 410.901642 -208.181956)
		(width 0.18288)
		(layer "In11.Cu")
		(net "M_H_CPU0_SB_DQ<13>")
	)
	(segment
		(start 380.453392 -230.582216)
		(end 380.442978 -230.57612)
		(width 0.088646)
		(layer "In11.Cu")
		(net "M_H_CPU0_SB_DQ<13>")
	)
	(segment
		(start 432.962304 -207.964278)
		(end 431.555652 -207.964278)
		(width 0.18288)
		(layer "In11.Cu")
		(net "M_H_CPU0_SB_DQ<13>")
	)
	(segment
		(start 450.332094 -214.354918)
		(end 450.332094 -213.085426)
		(width 0.18288)
		(layer "In11.Cu")
		(net "M_H_CPU0_SB_DQ<13>")
	)
	(segment
		(start 372.110254 -230.900478)
		(end 371.797834 -230.900478)
		(width 0.088646)
		(layer "In11.Cu")
		(net "M_H_CPU0_SB_DQ<13>")
	)
	(segment
		(start 450.911214 -215.03132)
		(end 450.84238 -214.865204)
		(width 0.18288)
		(layer "In11.Cu")
		(net "M_H_CPU0_SB_DQ<13>")
	)
	(segment
		(start 416.87115 -208.268316)
		(end 416.454844 -207.85201)
		(width 0.18288)
		(layer "In11.Cu")
		(net "M_H_CPU0_SB_DQ<13>")
	)
	(segment
		(start 433.665884 -206.920592)
		(end 433.348384 -206.920592)
		(width 0.18288)
		(layer "In11.Cu")
		(net "M_H_CPU0_SB_DQ<13>")
	)
	(segment
		(start 450.332094 -213.085426)
		(end 447.842894 -210.596226)
		(width 0.18288)
		(layer "In11.Cu")
		(net "M_H_CPU0_SB_DQ<13>")
	)
	(segment
		(start 410.901642 -208.181956)
		(end 410.901642 -208.574386)
		(width 0.18288)
		(layer "In11.Cu")
		(net "M_H_CPU0_SB_DQ<13>")
	)
	(segment
		(start 433.155344 -207.113632)
		(end 433.155344 -207.771238)
		(width 0.18288)
		(layer "In11.Cu")
		(net "M_H_CPU0_SB_DQ<13>")
	)
	(segment
		(start 409.996894 -208.767426)
		(end 409.082494 -209.681826)
		(width 0.18288)
		(layer "In11.Cu")
		(net "M_H_CPU0_SB_DQ<13>")
	)
	(segment
		(start 425.6532 -208.12887)
		(end 425.464732 -207.940402)
		(width 0.18288)
		(layer "In11.Cu")
		(net "M_H_CPU0_SB_DQ<13>")
	)
	(segment
		(start 392.92911 -224.96145)
		(end 389.220202 -228.670358)
		(width 0.18288)
		(layer "In11.Cu")
		(net "M_H_CPU0_SB_DQ<13>")
	)
	(segment
		(start 400.05 -214.782654)
		(end 400.05 -216.866216)
		(width 0.18288)
		(layer "In11.Cu")
		(net "M_H_CPU0_SB_DQ<13>")
	)
	(segment
		(start 411.798262 -208.767426)
		(end 411.605222 -208.574386)
		(width 0.18288)
		(layer "In11.Cu")
		(net "M_H_CPU0_SB_DQ<13>")
	)
	(segment
		(start 412.149798 -208.767426)
		(end 411.798262 -208.767426)
		(width 0.18288)
		(layer "In11.Cu")
		(net "M_H_CPU0_SB_DQ<13>")
	)
	(segment
		(start 433.858924 -207.113632)
		(end 433.665884 -206.920592)
		(width 0.18288)
		(layer "In11.Cu")
		(net "M_H_CPU0_SB_DQ<13>")
	)
	(segment
		(start 427.30166 -208.12887)
		(end 425.6532 -208.12887)
		(width 0.18288)
		(layer "In11.Cu")
		(net "M_H_CPU0_SB_DQ<13>")
	)
	(segment
		(start 440.886088 -207.09382)
		(end 435.42458 -207.09382)
		(width 0.18288)
		(layer "In11.Cu")
		(net "M_H_CPU0_SB_DQ<13>")
	)
	(segment
		(start 433.858924 -207.771238)
		(end 433.858924 -207.113632)
		(width 0.18288)
		(layer "In11.Cu")
		(net "M_H_CPU0_SB_DQ<13>")
	)
	(segment
		(start 434.051964 -207.964278)
		(end 433.858924 -207.771238)
		(width 0.18288)
		(layer "In11.Cu")
		(net "M_H_CPU0_SB_DQ<13>")
	)
	(segment
		(start 411.605222 -208.181956)
		(end 411.412182 -207.988916)
		(width 0.18288)
		(layer "In11.Cu")
		(net "M_H_CPU0_SB_DQ<13>")
	)
	(segment
		(start 410.708602 -208.767426)
		(end 409.996894 -208.767426)
		(width 0.18288)
		(layer "In11.Cu")
		(net "M_H_CPU0_SB_DQ<13>")
	)
	(segment
		(start 375.758964 -230.584756)
		(end 375.744232 -230.57612)
		(width 0.088646)
		(layer "In11.Cu")
		(net "M_H_CPU0_SB_DQ<13>")
	)
	(segment
		(start 376.698764 -230.584756)
		(end 376.684032 -230.57612)
		(width 0.088646)
		(layer "In11.Cu")
		(net "M_H_CPU0_SB_DQ<13>")
	)
	(segment
		(start 392.92911 -223.987106)
		(end 392.92911 -224.96145)
		(width 0.18288)
		(layer "In11.Cu")
		(net "M_H_CPU0_SB_DQ<13>")
	)
	(segment
		(start 424.903646 -207.938624)
		(end 424.769026 -207.938624)
		(width 0.18288)
		(layer "In11.Cu")
		(net "M_H_CPU0_SB_DQ<13>")
	)
	(segment
		(start 443.079632 -208.873344)
		(end 442.313314 -208.107026)
		(width 0.18288)
		(layer "In11.Cu")
		(net "M_H_CPU0_SB_DQ<13>")
	)
	(segment
		(start 435.42458 -207.09382)
		(end 435.20995 -207.30845)
		(width 0.18288)
		(layer "In11.Cu")
		(net "M_H_CPU0_SB_DQ<13>")
	)
	(segment
		(start 429.092868 -208.108296)
		(end 429.092868 -207.822546)
		(width 0.18288)
		(layer "In11.Cu")
		(net "M_H_CPU0_SB_DQ<13>")
	)
	(segment
		(start 411.605222 -208.574386)
		(end 411.605222 -208.181956)
		(width 0.18288)
		(layer "In11.Cu")
		(net "M_H_CPU0_SB_DQ<13>")
	)
	(segment
		(start 424.769026 -207.938624)
		(end 424.08221 -207.939132)
		(width 0.18288)
		(layer "In11.Cu")
		(net "M_H_CPU0_SB_DQ<13>")
	)
	(arc
		(start 382.888236 -230.57612)
		(mid 382.605534 -230.651896)
		(end 382.322832 -230.57612)
		(width 0.088646)
		(layer "In11.Cu")
		(net "M_H_CPU0_SB_DQ<13>")
	)
	(arc
		(start 373.490236 -230.57612)
		(mid 373.352823 -230.713532)
		(end 373.30253 -230.90124)
		(width 0.088646)
		(layer "In11.Cu")
		(net "M_H_CPU0_SB_DQ<13>")
	)
	(arc
		(start 373.30253 -230.922576)
		(mid 372.759173 -231.46564)
		(end 372.175786 -230.96601)
		(width 0.088646)
		(layer "In11.Cu")
		(net "M_H_CPU0_SB_DQ<13>")
	)
	(arc
		(start 381.948436 -230.57612)
		(mid 381.665734 -230.651896)
		(end 381.383032 -230.57612)
		(width 0.088646)
		(layer "In11.Cu")
		(net "M_H_CPU0_SB_DQ<13>")
	)
	(arc
		(start 384.202432 -230.57612)
		(mid 384.015234 -230.525977)
		(end 383.828036 -230.57612)
		(width 0.088646)
		(layer "In11.Cu")
		(net "M_H_CPU0_SB_DQ<13>")
	)
	(arc
		(start 373.864632 -230.57612)
		(mid 373.677434 -230.525977)
		(end 373.490236 -230.57612)
		(width 0.088646)
		(layer "In11.Cu")
		(net "M_H_CPU0_SB_DQ<13>")
	)
	(arc
		(start 379.129036 -230.57612)
		(mid 378.854837 -230.651955)
		(end 378.578364 -230.584756)
		(width 0.088646)
		(layer "In11.Cu")
		(net "M_H_CPU0_SB_DQ<13>")
	)
	(arc
		(start 375.369836 -230.57612)
		(mid 375.095637 -230.651955)
		(end 374.819164 -230.584756)
		(width 0.088646)
		(layer "In11.Cu")
		(net "M_H_CPU0_SB_DQ<13>")
	)
	(arc
		(start 379.503432 -230.57612)
		(mid 379.316234 -230.525977)
		(end 379.129036 -230.57612)
		(width 0.088646)
		(layer "In11.Cu")
		(net "M_H_CPU0_SB_DQ<13>")
	)
	(arc
		(start 385.707636 -230.57612)
		(mid 385.424934 -230.651896)
		(end 385.142232 -230.57612)
		(width 0.088646)
		(layer "In11.Cu")
		(net "M_H_CPU0_SB_DQ<13>")
	)
	(arc
		(start 384.767836 -230.57612)
		(mid 384.485134 -230.651896)
		(end 384.202432 -230.57612)
		(width 0.088646)
		(layer "In11.Cu")
		(net "M_H_CPU0_SB_DQ<13>")
	)
	(arc
		(start 380.442978 -230.57612)
		(mid 380.25578 -230.525977)
		(end 380.068582 -230.57612)
		(width 0.088646)
		(layer "In11.Cu")
		(net "M_H_CPU0_SB_DQ<13>")
	)
	(arc
		(start 382.322832 -230.57612)
		(mid 382.135634 -230.525977)
		(end 381.948436 -230.57612)
		(width 0.088646)
		(layer "In11.Cu")
		(net "M_H_CPU0_SB_DQ<13>")
	)
	(arc
		(start 375.744232 -230.57612)
		(mid 375.557034 -230.525977)
		(end 375.369836 -230.57612)
		(width 0.088646)
		(layer "In11.Cu")
		(net "M_H_CPU0_SB_DQ<13>")
	)
	(arc
		(start 377.249436 -230.57612)
		(mid 376.975237 -230.651955)
		(end 376.698764 -230.584756)
		(width 0.088646)
		(layer "In11.Cu")
		(net "M_H_CPU0_SB_DQ<13>")
	)
	(arc
		(start 381.008636 -230.57612)
		(mid 380.731823 -230.65199)
		(end 380.453392 -230.582216)
		(width 0.088646)
		(layer "In11.Cu")
		(net "M_H_CPU0_SB_DQ<13>")
	)
	(arc
		(start 374.804432 -230.57612)
		(mid 374.617234 -230.525977)
		(end 374.430036 -230.57612)
		(width 0.088646)
		(layer "In11.Cu")
		(net "M_H_CPU0_SB_DQ<13>")
	)
	(arc
		(start 383.828036 -230.57612)
		(mid 383.545334 -230.651896)
		(end 383.262632 -230.57612)
		(width 0.088646)
		(layer "In11.Cu")
		(net "M_H_CPU0_SB_DQ<13>")
	)
	(arc
		(start 376.309636 -230.57612)
		(mid 376.035437 -230.651955)
		(end 375.758964 -230.584756)
		(width 0.088646)
		(layer "In11.Cu")
		(net "M_H_CPU0_SB_DQ<13>")
	)
	(arc
		(start 378.563632 -230.57612)
		(mid 378.376434 -230.525977)
		(end 378.189236 -230.57612)
		(width 0.088646)
		(layer "In11.Cu")
		(net "M_H_CPU0_SB_DQ<13>")
	)
	(arc
		(start 385.142232 -230.57612)
		(mid 384.955034 -230.525977)
		(end 384.767836 -230.57612)
		(width 0.088646)
		(layer "In11.Cu")
		(net "M_H_CPU0_SB_DQ<13>")
	)
	(arc
		(start 385.990084 -230.096568)
		(mid 385.911973 -230.373517)
		(end 385.707636 -230.57612)
		(width 0.088646)
		(layer "In11.Cu")
		(net "M_H_CPU0_SB_DQ<13>")
	)
	(arc
		(start 386.364734 -229.711758)
		(mid 386.099801 -229.821655)
		(end 385.990084 -230.086662)
		(width 0.088646)
		(layer "In11.Cu")
		(net "M_H_CPU0_SB_DQ<13>")
	)
	(arc
		(start 381.383032 -230.57612)
		(mid 381.195834 -230.525977)
		(end 381.008636 -230.57612)
		(width 0.088646)
		(layer "In11.Cu")
		(net "M_H_CPU0_SB_DQ<13>")
	)
	(arc
		(start 376.684032 -230.57612)
		(mid 376.496834 -230.525977)
		(end 376.309636 -230.57612)
		(width 0.088646)
		(layer "In11.Cu")
		(net "M_H_CPU0_SB_DQ<13>")
	)
	(arc
		(start 383.262632 -230.57612)
		(mid 383.075434 -230.525977)
		(end 382.888236 -230.57612)
		(width 0.088646)
		(layer "In11.Cu")
		(net "M_H_CPU0_SB_DQ<13>")
	)
	(arc
		(start 378.189236 -230.57612)
		(mid 377.915037 -230.651955)
		(end 377.638564 -230.584756)
		(width 0.088646)
		(layer "In11.Cu")
		(net "M_H_CPU0_SB_DQ<13>")
	)
	(arc
		(start 374.430036 -230.57612)
		(mid 374.155837 -230.651955)
		(end 373.879364 -230.584756)
		(width 0.088646)
		(layer "In11.Cu")
		(net "M_H_CPU0_SB_DQ<13>")
	)
	(arc
		(start 377.623832 -230.57612)
		(mid 377.436634 -230.525977)
		(end 377.249436 -230.57612)
		(width 0.088646)
		(layer "In11.Cu")
		(net "M_H_CPU0_SB_DQ<13>")
	)
	(arc
		(start 380.058168 -230.582216)
		(mid 379.77999 -230.651939)
		(end 379.503432 -230.57612)
		(width 0.088646)
		(layer "In11.Cu")
		(net "M_H_CPU0_SB_DQ<13>")
	)
	(segment
		(start 371.327934 -232.250488)
		(end 371.32768 -232.250234)
		(width 0.20066)
		(layer "F.Cu")
		(net "M_H_CPU0_SB_DQ<12>")
	)
	(segment
		(start 457.968096 -216.866978)
		(end 457.53655 -216.435432)
		(width 0.20066)
		(layer "F.Cu")
		(net "M_H_CPU0_SB_DQ<12>")
	)
	(segment
		(start 454.566782 -216.441782)
		(end 454.448672 -216.559892)
		(width 0.20066)
		(layer "F.Cu")
		(net "M_H_CPU0_SB_DQ<12>")
	)
	(segment
		(start 453.536812 -216.866724)
		(end 452.016114 -216.866724)
		(width 0.20066)
		(layer "F.Cu")
		(net "M_H_CPU0_SB_DQ<12>")
	)
	(segment
		(start 454.91146 -216.441782)
		(end 454.566782 -216.441782)
		(width 0.20066)
		(layer "F.Cu")
		(net "M_H_CPU0_SB_DQ<12>")
	)
	(segment
		(start 454.448672 -216.92743)
		(end 454.260712 -217.11539)
		(width 0.20066)
		(layer "F.Cu")
		(net "M_H_CPU0_SB_DQ<12>")
	)
	(segment
		(start 457.120244 -216.441782)
		(end 454.95845 -216.441782)
		(width 0.1016)
		(layer "F.Cu")
		(net "M_H_CPU0_SB_DQ<12>")
	)
	(segment
		(start 454.95845 -216.441782)
		(end 454.91146 -216.441782)
		(width 0.101854)
		(layer "F.Cu")
		(net "M_H_CPU0_SB_DQ<12>")
	)
	(segment
		(start 457.126594 -216.435432)
		(end 457.120244 -216.441782)
		(width 0.1016)
		(layer "F.Cu")
		(net "M_H_CPU0_SB_DQ<12>")
	)
	(segment
		(start 454.260712 -217.11539)
		(end 453.785478 -217.11539)
		(width 0.20066)
		(layer "F.Cu")
		(net "M_H_CPU0_SB_DQ<12>")
	)
	(segment
		(start 459.559914 -216.866724)
		(end 459.55966 -216.866978)
		(width 0.20066)
		(layer "F.Cu")
		(net "M_H_CPU0_SB_DQ<12>")
	)
	(segment
		(start 371.32768 -232.250234)
		(end 371.32768 -231.714548)
		(width 0.20066)
		(layer "F.Cu")
		(net "M_H_CPU0_SB_DQ<12>")
	)
	(segment
		(start 454.448672 -216.559892)
		(end 454.448672 -216.92743)
		(width 0.20066)
		(layer "F.Cu")
		(net "M_H_CPU0_SB_DQ<12>")
	)
	(segment
		(start 452.016114 -216.866724)
		(end 450.911214 -216.866724)
		(width 0.20066)
		(layer "F.Cu")
		(net "M_H_CPU0_SB_DQ<12>")
	)
	(segment
		(start 457.53655 -216.435432)
		(end 457.126594 -216.435432)
		(width 0.20066)
		(layer "F.Cu")
		(net "M_H_CPU0_SB_DQ<12>")
	)
	(segment
		(start 453.785478 -217.11539)
		(end 453.536812 -216.866724)
		(width 0.20066)
		(layer "F.Cu")
		(net "M_H_CPU0_SB_DQ<12>")
	)
	(segment
		(start 459.55966 -216.866978)
		(end 457.968096 -216.866978)
		(width 0.20066)
		(layer "F.Cu")
		(net "M_H_CPU0_SB_DQ<12>")
	)
	(segment
		(start 373.020082 -232.038906)
		(end 373.00535 -232.03027)
		(width 0.088646)
		(layer "In11.Cu")
		(net "M_H_CPU0_SB_DQ<12>")
	)
	(segment
		(start 378.658882 -231.39019)
		(end 378.64415 -231.398826)
		(width 0.088646)
		(layer "In11.Cu")
		(net "M_H_CPU0_SB_DQ<12>")
	)
	(segment
		(start 425.568872 -210.49107)
		(end 424.16095 -210.49107)
		(width 0.18288)
		(layer "In11.Cu")
		(net "M_H_CPU0_SB_DQ<12>")
	)
	(segment
		(start 386.926836 -229.931468)
		(end 386.926836 -230.347012)
		(width 0.088646)
		(layer "In11.Cu")
		(net "M_H_CPU0_SB_DQ<12>")
	)
	(segment
		(start 375.839482 -231.39019)
		(end 375.82475 -231.398826)
		(width 0.088646)
		(layer "In11.Cu")
		(net "M_H_CPU0_SB_DQ<12>")
	)
	(segment
		(start 414.016698 -210.302348)
		(end 413.823658 -210.109308)
		(width 0.18288)
		(layer "In11.Cu")
		(net "M_H_CPU0_SB_DQ<12>")
	)
	(segment
		(start 401.342098 -215.03894)
		(end 401.342098 -217.069416)
		(width 0.18288)
		(layer "In11.Cu")
		(net "M_H_CPU0_SB_DQ<12>")
	)
	(segment
		(start 372.080282 -232.038906)
		(end 372.06555 -232.03027)
		(width 0.088646)
		(layer "In11.Cu")
		(net "M_H_CPU0_SB_DQ<12>")
	)
	(segment
		(start 416.649662 -209.453226)
		(end 415.99358 -210.109308)
		(width 0.18288)
		(layer "In11.Cu")
		(net "M_H_CPU0_SB_DQ<12>")
	)
	(segment
		(start 393.995402 -224.416112)
		(end 393.995402 -225.344736)
		(width 0.18288)
		(layer "In11.Cu")
		(net "M_H_CPU0_SB_DQ<12>")
	)
	(segment
		(start 438.01665 -209.642456)
		(end 437.144414 -209.642456)
		(width 0.18288)
		(layer "In11.Cu")
		(net "M_H_CPU0_SB_DQ<12>")
	)
	(segment
		(start 393.995402 -225.344736)
		(end 389.65251 -229.687628)
		(width 0.18288)
		(layer "In11.Cu")
		(net "M_H_CPU0_SB_DQ<12>")
	)
	(segment
		(start 446.720722 -212.094826)
		(end 445.582294 -212.094826)
		(width 0.18288)
		(layer "In11.Cu")
		(net "M_H_CPU0_SB_DQ<12>")
	)
	(segment
		(start 412.744412 -210.109308)
		(end 411.73146 -211.12226)
		(width 0.18288)
		(layer "In11.Cu")
		(net "M_H_CPU0_SB_DQ<12>")
	)
	(segment
		(start 441.432442 -209.587846)
		(end 441.213494 -209.806794)
		(width 0.18288)
		(layer "In11.Cu")
		(net "M_H_CPU0_SB_DQ<12>")
	)
	(segment
		(start 371.455696 -231.842564)
		(end 371.32768 -231.714548)
		(width 0.088646)
		(layer "In11.Cu")
		(net "M_H_CPU0_SB_DQ<12>")
	)
	(segment
		(start 419.521132 -210.49361)
		(end 418.480748 -209.453226)
		(width 0.18288)
		(layer "In11.Cu")
		(net "M_H_CPU0_SB_DQ<12>")
	)
	(segment
		(start 443.660022 -210.172554)
		(end 442.898022 -210.172554)
		(width 0.18288)
		(layer "In11.Cu")
		(net "M_H_CPU0_SB_DQ<12>")
	)
	(segment
		(start 438.20969 -209.449416)
		(end 438.01665 -209.642456)
		(width 0.18288)
		(layer "In11.Cu")
		(net "M_H_CPU0_SB_DQ<12>")
	)
	(segment
		(start 408.758898 -211.344002)
		(end 405.037036 -211.344002)
		(width 0.18288)
		(layer "In11.Cu")
		(net "M_H_CPU0_SB_DQ<12>")
	)
	(segment
		(start 405.037036 -211.344002)
		(end 401.342098 -215.03894)
		(width 0.18288)
		(layer "In11.Cu")
		(net "M_H_CPU0_SB_DQ<12>")
	)
	(segment
		(start 414.527238 -211.062316)
		(end 414.209738 -211.062316)
		(width 0.18288)
		(layer "In11.Cu")
		(net "M_H_CPU0_SB_DQ<12>")
	)
	(segment
		(start 376.779536 -231.39019)
		(end 376.769122 -231.396286)
		(width 0.088646)
		(layer "In11.Cu")
		(net "M_H_CPU0_SB_DQ<12>")
	)
	(segment
		(start 373.403368 -232.033826)
		(end 373.394478 -232.038906)
		(width 0.088646)
		(layer "In11.Cu")
		(net "M_H_CPU0_SB_DQ<12>")
	)
	(segment
		(start 423.855642 -210.185762)
		(end 422.435274 -210.185762)
		(width 0.18288)
		(layer "In11.Cu")
		(net "M_H_CPU0_SB_DQ<12>")
	)
	(segment
		(start 386.764784 -230.509064)
		(end 386.638546 -230.5812)
		(width 0.088646)
		(layer "In11.Cu")
		(net "M_H_CPU0_SB_DQ<12>")
	)
	(segment
		(start 422.435274 -210.185762)
		(end 422.127426 -210.49361)
		(width 0.18288)
		(layer "In11.Cu")
		(net "M_H_CPU0_SB_DQ<12>")
	)
	(segment
		(start 450.911214 -216.866724)
		(end 450.911214 -216.748106)
		(width 0.18288)
		(layer "In11.Cu")
		(net "M_H_CPU0_SB_DQ<12>")
	)
	(segment
		(start 438.40273 -208.611978)
		(end 438.20969 -208.805018)
		(width 0.18288)
		(layer "In11.Cu")
		(net "M_H_CPU0_SB_DQ<12>")
	)
	(segment
		(start 401.342098 -217.069416)
		(end 393.995402 -224.416112)
		(width 0.18288)
		(layer "In11.Cu")
		(net "M_H_CPU0_SB_DQ<12>")
	)
	(segment
		(start 418.480748 -209.453226)
		(end 416.649662 -209.453226)
		(width 0.18288)
		(layer "In11.Cu")
		(net "M_H_CPU0_SB_DQ<12>")
	)
	(segment
		(start 414.720278 -210.869276)
		(end 414.527238 -211.062316)
		(width 0.18288)
		(layer "In11.Cu")
		(net "M_H_CPU0_SB_DQ<12>")
	)
	(segment
		(start 450.911214 -216.748106)
		(end 450.838062 -216.571576)
		(width 0.18288)
		(layer "In11.Cu")
		(net "M_H_CPU0_SB_DQ<12>")
	)
	(segment
		(start 440.389518 -209.806794)
		(end 440.22518 -209.642456)
		(width 0.18288)
		(layer "In11.Cu")
		(net "M_H_CPU0_SB_DQ<12>")
	)
	(segment
		(start 450.838062 -216.571576)
		(end 450.548756 -216.28227)
		(width 0.18288)
		(layer "In11.Cu")
		(net "M_H_CPU0_SB_DQ<12>")
	)
	(segment
		(start 411.73146 -211.12226)
		(end 408.98064 -211.12226)
		(width 0.18288)
		(layer "In11.Cu")
		(net "M_H_CPU0_SB_DQ<12>")
	)
	(segment
		(start 381.478536 -231.39019)
		(end 381.468122 -231.396286)
		(width 0.088646)
		(layer "In11.Cu")
		(net "M_H_CPU0_SB_DQ<12>")
	)
	(segment
		(start 386.926836 -230.347012)
		(end 386.764784 -230.509064)
		(width 0.088646)
		(layer "In11.Cu")
		(net "M_H_CPU0_SB_DQ<12>")
	)
	(segment
		(start 414.209738 -211.062316)
		(end 414.016698 -210.869276)
		(width 0.18288)
		(layer "In11.Cu")
		(net "M_H_CPU0_SB_DQ<12>")
	)
	(segment
		(start 413.823658 -210.109308)
		(end 412.744412 -210.109308)
		(width 0.18288)
		(layer "In11.Cu")
		(net "M_H_CPU0_SB_DQ<12>")
	)
	(segment
		(start 373.959882 -231.39019)
		(end 373.713248 -231.534716)
		(width 0.088646)
		(layer "In11.Cu")
		(net "M_H_CPU0_SB_DQ<12>")
	)
	(segment
		(start 436.29326 -208.791302)
		(end 435.481222 -208.791302)
		(width 0.18288)
		(layer "In11.Cu")
		(net "M_H_CPU0_SB_DQ<12>")
	)
	(segment
		(start 424.16095 -210.49107)
		(end 423.855642 -210.185762)
		(width 0.18288)
		(layer "In11.Cu")
		(net "M_H_CPU0_SB_DQ<12>")
	)
	(segment
		(start 441.213494 -209.806794)
		(end 440.389518 -209.806794)
		(width 0.18288)
		(layer "In11.Cu")
		(net "M_H_CPU0_SB_DQ<12>")
	)
	(segment
		(start 438.91327 -209.449416)
		(end 438.91327 -208.805018)
		(width 0.18288)
		(layer "In11.Cu")
		(net "M_H_CPU0_SB_DQ<12>")
	)
	(segment
		(start 414.913318 -210.109308)
		(end 414.720278 -210.302348)
		(width 0.18288)
		(layer "In11.Cu")
		(net "M_H_CPU0_SB_DQ<12>")
	)
	(segment
		(start 408.98064 -211.12226)
		(end 408.758898 -211.344002)
		(width 0.18288)
		(layer "In11.Cu")
		(net "M_H_CPU0_SB_DQ<12>")
	)
	(segment
		(start 374.899682 -231.39019)
		(end 374.88495 -231.398826)
		(width 0.088646)
		(layer "In11.Cu")
		(net "M_H_CPU0_SB_DQ<12>")
	)
	(segment
		(start 434.895498 -209.377026)
		(end 426.682916 -209.377026)
		(width 0.18288)
		(layer "In11.Cu")
		(net "M_H_CPU0_SB_DQ<12>")
	)
	(segment
		(start 415.99358 -210.109308)
		(end 414.913318 -210.109308)
		(width 0.18288)
		(layer "In11.Cu")
		(net "M_H_CPU0_SB_DQ<12>")
	)
	(segment
		(start 388.103364 -229.687628)
		(end 387.170676 -229.687628)
		(width 0.088646)
		(layer "In11.Cu")
		(net "M_H_CPU0_SB_DQ<12>")
	)
	(segment
		(start 438.72023 -208.611978)
		(end 438.40273 -208.611978)
		(width 0.18288)
		(layer "In11.Cu")
		(net "M_H_CPU0_SB_DQ<12>")
	)
	(segment
		(start 379.598682 -231.39019)
		(end 379.58395 -231.398826)
		(width 0.088646)
		(layer "In11.Cu")
		(net "M_H_CPU0_SB_DQ<12>")
	)
	(segment
		(start 435.481222 -208.791302)
		(end 434.895498 -209.377026)
		(width 0.18288)
		(layer "In11.Cu")
		(net "M_H_CPU0_SB_DQ<12>")
	)
	(segment
		(start 442.313314 -209.587846)
		(end 441.432442 -209.587846)
		(width 0.18288)
		(layer "In11.Cu")
		(net "M_H_CPU0_SB_DQ<12>")
	)
	(segment
		(start 438.20969 -208.805018)
		(end 438.20969 -209.449416)
		(width 0.18288)
		(layer "In11.Cu")
		(net "M_H_CPU0_SB_DQ<12>")
	)
	(segment
		(start 450.548756 -216.28227)
		(end 449.160138 -216.28227)
		(width 0.18288)
		(layer "In11.Cu")
		(net "M_H_CPU0_SB_DQ<12>")
	)
	(segment
		(start 386.459984 -230.900478)
		(end 386.459984 -230.91902)
		(width 0.088646)
		(layer "In11.Cu")
		(net "M_H_CPU0_SB_DQ<12>")
	)
	(segment
		(start 377.719082 -231.39019)
		(end 377.708668 -231.396286)
		(width 0.088646)
		(layer "In11.Cu")
		(net "M_H_CPU0_SB_DQ<12>")
	)
	(segment
		(start 438.91327 -208.805018)
		(end 438.72023 -208.611978)
		(width 0.18288)
		(layer "In11.Cu")
		(net "M_H_CPU0_SB_DQ<12>")
	)
	(segment
		(start 389.65251 -229.687628)
		(end 388.103364 -229.687628)
		(width 0.18288)
		(layer "In11.Cu")
		(net "M_H_CPU0_SB_DQ<12>")
	)
	(segment
		(start 387.170676 -229.687628)
		(end 386.926836 -229.931468)
		(width 0.088646)
		(layer "In11.Cu")
		(net "M_H_CPU0_SB_DQ<12>")
	)
	(segment
		(start 448.249294 -215.371426)
		(end 448.249294 -213.623398)
		(width 0.18288)
		(layer "In11.Cu")
		(net "M_H_CPU0_SB_DQ<12>")
	)
	(segment
		(start 422.127426 -210.49361)
		(end 419.521132 -210.49361)
		(width 0.18288)
		(layer "In11.Cu")
		(net "M_H_CPU0_SB_DQ<12>")
	)
	(segment
		(start 442.898022 -210.172554)
		(end 442.313314 -209.587846)
		(width 0.18288)
		(layer "In11.Cu")
		(net "M_H_CPU0_SB_DQ<12>")
	)
	(segment
		(start 448.249294 -213.623398)
		(end 446.720722 -212.094826)
		(width 0.18288)
		(layer "In11.Cu")
		(net "M_H_CPU0_SB_DQ<12>")
	)
	(segment
		(start 445.582294 -212.094826)
		(end 443.660022 -210.172554)
		(width 0.18288)
		(layer "In11.Cu")
		(net "M_H_CPU0_SB_DQ<12>")
	)
	(segment
		(start 439.10631 -209.642456)
		(end 438.91327 -209.449416)
		(width 0.18288)
		(layer "In11.Cu")
		(net "M_H_CPU0_SB_DQ<12>")
	)
	(segment
		(start 440.22518 -209.642456)
		(end 439.10631 -209.642456)
		(width 0.18288)
		(layer "In11.Cu")
		(net "M_H_CPU0_SB_DQ<12>")
	)
	(segment
		(start 414.016698 -210.869276)
		(end 414.016698 -210.302348)
		(width 0.18288)
		(layer "In11.Cu")
		(net "M_H_CPU0_SB_DQ<12>")
	)
	(segment
		(start 437.144414 -209.642456)
		(end 436.29326 -208.791302)
		(width 0.18288)
		(layer "In11.Cu")
		(net "M_H_CPU0_SB_DQ<12>")
	)
	(segment
		(start 414.720278 -210.302348)
		(end 414.720278 -210.869276)
		(width 0.18288)
		(layer "In11.Cu")
		(net "M_H_CPU0_SB_DQ<12>")
	)
	(segment
		(start 449.160138 -216.28227)
		(end 448.249294 -215.371426)
		(width 0.18288)
		(layer "In11.Cu")
		(net "M_H_CPU0_SB_DQ<12>")
	)
	(segment
		(start 426.682916 -209.377026)
		(end 425.568872 -210.49107)
		(width 0.18288)
		(layer "In11.Cu")
		(net "M_H_CPU0_SB_DQ<12>")
	)
	(arc
		(start 381.852932 -231.39019)
		(mid 381.665734 -231.340047)
		(end 381.478536 -231.39019)
		(width 0.088646)
		(layer "In11.Cu")
		(net "M_H_CPU0_SB_DQ<12>")
	)
	(arc
		(start 381.468122 -231.396286)
		(mid 381.18969 -231.4661)
		(end 380.912878 -231.39019)
		(width 0.088646)
		(layer "In11.Cu")
		(net "M_H_CPU0_SB_DQ<12>")
	)
	(arc
		(start 386.177536 -231.39019)
		(mid 385.894834 -231.465932)
		(end 385.612132 -231.39019)
		(width 0.088646)
		(layer "In11.Cu")
		(net "M_H_CPU0_SB_DQ<12>")
	)
	(arc
		(start 386.638546 -230.5812)
		(mid 386.507632 -230.71756)
		(end 386.459984 -230.900478)
		(width 0.088646)
		(layer "In11.Cu")
		(net "M_H_CPU0_SB_DQ<12>")
	)
	(arc
		(start 383.732532 -231.39019)
		(mid 383.545334 -231.340047)
		(end 383.358136 -231.39019)
		(width 0.088646)
		(layer "In11.Cu")
		(net "M_H_CPU0_SB_DQ<12>")
	)
	(arc
		(start 379.973078 -231.39019)
		(mid 379.78588 -231.340047)
		(end 379.598682 -231.39019)
		(width 0.088646)
		(layer "In11.Cu")
		(net "M_H_CPU0_SB_DQ<12>")
	)
	(arc
		(start 379.033278 -231.39019)
		(mid 378.84608 -231.340047)
		(end 378.658882 -231.39019)
		(width 0.088646)
		(layer "In11.Cu")
		(net "M_H_CPU0_SB_DQ<12>")
	)
	(arc
		(start 374.88495 -231.398826)
		(mid 374.608509 -231.465992)
		(end 374.334278 -231.39019)
		(width 0.088646)
		(layer "In11.Cu")
		(net "M_H_CPU0_SB_DQ<12>")
	)
	(arc
		(start 375.82475 -231.398826)
		(mid 375.548309 -231.465992)
		(end 375.274078 -231.39019)
		(width 0.088646)
		(layer "In11.Cu")
		(net "M_H_CPU0_SB_DQ<12>")
	)
	(arc
		(start 378.093478 -231.39019)
		(mid 377.90628 -231.340047)
		(end 377.719082 -231.39019)
		(width 0.088646)
		(layer "In11.Cu")
		(net "M_H_CPU0_SB_DQ<12>")
	)
	(arc
		(start 373.603012 -231.65562)
		(mid 373.588035 -231.697794)
		(end 373.580914 -231.74198)
		(width 0.088646)
		(layer "In11.Cu")
		(net "M_H_CPU0_SB_DQ<12>")
	)
	(arc
		(start 373.00535 -232.03027)
		(mid 372.728875 -231.96295)
		(end 372.454678 -232.038906)
		(width 0.088646)
		(layer "In11.Cu")
		(net "M_H_CPU0_SB_DQ<12>")
	)
	(arc
		(start 385.612132 -231.39019)
		(mid 385.424934 -231.340047)
		(end 385.237736 -231.39019)
		(width 0.088646)
		(layer "In11.Cu")
		(net "M_H_CPU0_SB_DQ<12>")
	)
	(arc
		(start 373.577358 -231.771444)
		(mid 373.577358 -231.771698)
		(end 373.577358 -231.771952)
		(width 0.088646)
		(layer "In11.Cu")
		(net "M_H_CPU0_SB_DQ<12>")
	)
	(arc
		(start 373.394478 -232.038906)
		(mid 373.20728 -232.089049)
		(end 373.020082 -232.038906)
		(width 0.088646)
		(layer "In11.Cu")
		(net "M_H_CPU0_SB_DQ<12>")
	)
	(arc
		(start 385.237736 -231.39019)
		(mid 384.955034 -231.465932)
		(end 384.672332 -231.39019)
		(width 0.088646)
		(layer "In11.Cu")
		(net "M_H_CPU0_SB_DQ<12>")
	)
	(arc
		(start 374.334278 -231.39019)
		(mid 374.14708 -231.340047)
		(end 373.959882 -231.39019)
		(width 0.088646)
		(layer "In11.Cu")
		(net "M_H_CPU0_SB_DQ<12>")
	)
	(arc
		(start 373.713248 -231.534716)
		(mid 373.648907 -231.586763)
		(end 373.603012 -231.65562)
		(width 0.088646)
		(layer "In11.Cu")
		(net "M_H_CPU0_SB_DQ<12>")
	)
	(arc
		(start 373.577358 -231.771952)
		(mid 373.519202 -231.922065)
		(end 373.403368 -232.033826)
		(width 0.088646)
		(layer "In11.Cu")
		(net "M_H_CPU0_SB_DQ<12>")
	)
	(arc
		(start 383.358136 -231.39019)
		(mid 383.075434 -231.465932)
		(end 382.792732 -231.39019)
		(width 0.088646)
		(layer "In11.Cu")
		(net "M_H_CPU0_SB_DQ<12>")
	)
	(arc
		(start 386.459984 -230.91902)
		(mid 386.379822 -231.191209)
		(end 386.177536 -231.39019)
		(width 0.088646)
		(layer "In11.Cu")
		(net "M_H_CPU0_SB_DQ<12>")
	)
	(arc
		(start 380.538482 -231.39019)
		(mid 380.25578 -231.465932)
		(end 379.973078 -231.39019)
		(width 0.088646)
		(layer "In11.Cu")
		(net "M_H_CPU0_SB_DQ<12>")
	)
	(arc
		(start 384.672332 -231.39019)
		(mid 384.485134 -231.340047)
		(end 384.297936 -231.39019)
		(width 0.088646)
		(layer "In11.Cu")
		(net "M_H_CPU0_SB_DQ<12>")
	)
	(arc
		(start 376.769122 -231.396286)
		(mid 376.49069 -231.4661)
		(end 376.213878 -231.39019)
		(width 0.088646)
		(layer "In11.Cu")
		(net "M_H_CPU0_SB_DQ<12>")
	)
	(arc
		(start 372.06555 -232.03027)
		(mid 371.922389 -231.976836)
		(end 371.770148 -231.963722)
		(width 0.088646)
		(layer "In11.Cu")
		(net "M_H_CPU0_SB_DQ<12>")
	)
	(arc
		(start 375.274078 -231.39019)
		(mid 375.08688 -231.340047)
		(end 374.899682 -231.39019)
		(width 0.088646)
		(layer "In11.Cu")
		(net "M_H_CPU0_SB_DQ<12>")
	)
	(arc
		(start 379.58395 -231.398826)
		(mid 379.307509 -231.465992)
		(end 379.033278 -231.39019)
		(width 0.088646)
		(layer "In11.Cu")
		(net "M_H_CPU0_SB_DQ<12>")
	)
	(arc
		(start 372.454678 -232.038906)
		(mid 372.26748 -232.089049)
		(end 372.080282 -232.038906)
		(width 0.088646)
		(layer "In11.Cu")
		(net "M_H_CPU0_SB_DQ<12>")
	)
	(arc
		(start 384.297936 -231.39019)
		(mid 384.015234 -231.465932)
		(end 383.732532 -231.39019)
		(width 0.088646)
		(layer "In11.Cu")
		(net "M_H_CPU0_SB_DQ<12>")
	)
	(arc
		(start 377.153932 -231.39019)
		(mid 376.966734 -231.340047)
		(end 376.779536 -231.39019)
		(width 0.088646)
		(layer "In11.Cu")
		(net "M_H_CPU0_SB_DQ<12>")
	)
	(arc
		(start 382.418336 -231.39019)
		(mid 382.135634 -231.465932)
		(end 381.852932 -231.39019)
		(width 0.088646)
		(layer "In11.Cu")
		(net "M_H_CPU0_SB_DQ<12>")
	)
	(arc
		(start 373.580914 -231.74198)
		(mid 373.579424 -231.756747)
		(end 373.577358 -231.771444)
		(width 0.088646)
		(layer "In11.Cu")
		(net "M_H_CPU0_SB_DQ<12>")
	)
	(arc
		(start 377.708668 -231.396286)
		(mid 377.43049 -231.465978)
		(end 377.153932 -231.39019)
		(width 0.088646)
		(layer "In11.Cu")
		(net "M_H_CPU0_SB_DQ<12>")
	)
	(arc
		(start 378.64415 -231.398826)
		(mid 378.367709 -231.465992)
		(end 378.093478 -231.39019)
		(width 0.088646)
		(layer "In11.Cu")
		(net "M_H_CPU0_SB_DQ<12>")
	)
	(arc
		(start 371.770148 -231.963722)
		(mid 371.600094 -231.936433)
		(end 371.455696 -231.842564)
		(width 0.088646)
		(layer "In11.Cu")
		(net "M_H_CPU0_SB_DQ<12>")
	)
	(arc
		(start 380.912878 -231.39019)
		(mid 380.72568 -231.340047)
		(end 380.538482 -231.39019)
		(width 0.088646)
		(layer "In11.Cu")
		(net "M_H_CPU0_SB_DQ<12>")
	)
	(arc
		(start 382.792732 -231.39019)
		(mid 382.605534 -231.340047)
		(end 382.418336 -231.39019)
		(width 0.088646)
		(layer "In11.Cu")
		(net "M_H_CPU0_SB_DQ<12>")
	)
	(arc
		(start 376.213878 -231.39019)
		(mid 376.02668 -231.340047)
		(end 375.839482 -231.39019)
		(width 0.088646)
		(layer "In11.Cu")
		(net "M_H_CPU0_SB_DQ<12>")
	)
	(segment
		(start 462.073752 -220.0148)
		(end 462.32572 -220.266768)
		(width 0.20066)
		(layer "F.Cu")
		(net "M_H_CPU0_SB_DQ<11>")
	)
	(segment
		(start 456.116182 -220.266768)
		(end 457.814426 -220.266768)
		(width 0.20066)
		(layer "F.Cu")
		(net "M_H_CPU0_SB_DQ<11>")
	)
	(segment
		(start 455.011282 -220.266768)
		(end 456.116182 -220.266768)
		(width 0.20066)
		(layer "F.Cu")
		(net "M_H_CPU0_SB_DQ<11>")
	)
	(segment
		(start 373.207534 -233.87812)
		(end 373.20728 -233.877866)
		(width 0.20066)
		(layer "F.Cu")
		(net "M_H_CPU0_SB_DQ<11>")
	)
	(segment
		(start 461.455516 -220.248988)
		(end 461.689704 -220.0148)
		(width 0.20066)
		(layer "F.Cu")
		(net "M_H_CPU0_SB_DQ<11>")
	)
	(segment
		(start 461.251554 -220.703902)
		(end 461.455516 -220.49994)
		(width 0.20066)
		(layer "F.Cu")
		(net "M_H_CPU0_SB_DQ<11>")
	)
	(segment
		(start 458.550264 -220.69171)
		(end 460.558134 -220.69171)
		(width 0.1016)
		(layer "F.Cu")
		(net "M_H_CPU0_SB_DQ<11>")
	)
	(segment
		(start 460.558134 -220.69171)
		(end 460.570326 -220.703902)
		(width 0.1016)
		(layer "F.Cu")
		(net "M_H_CPU0_SB_DQ<11>")
	)
	(segment
		(start 458.538326 -220.698822)
		(end 458.543152 -220.698822)
		(width 0.101854)
		(layer "F.Cu")
		(net "M_H_CPU0_SB_DQ<11>")
	)
	(segment
		(start 462.32572 -220.266768)
		(end 463.659982 -220.266768)
		(width 0.20066)
		(layer "F.Cu")
		(net "M_H_CPU0_SB_DQ<11>")
	)
	(segment
		(start 457.814426 -220.266768)
		(end 458.24648 -220.698822)
		(width 0.20066)
		(layer "F.Cu")
		(net "M_H_CPU0_SB_DQ<11>")
	)
	(segment
		(start 461.689704 -220.0148)
		(end 462.073752 -220.0148)
		(width 0.20066)
		(layer "F.Cu")
		(net "M_H_CPU0_SB_DQ<11>")
	)
	(segment
		(start 458.24648 -220.698822)
		(end 458.538326 -220.698822)
		(width 0.20066)
		(layer "F.Cu")
		(net "M_H_CPU0_SB_DQ<11>")
	)
	(segment
		(start 373.20728 -233.877866)
		(end 373.20728 -233.34218)
		(width 0.20066)
		(layer "F.Cu")
		(net "M_H_CPU0_SB_DQ<11>")
	)
	(segment
		(start 461.455516 -220.49994)
		(end 461.455516 -220.248988)
		(width 0.20066)
		(layer "F.Cu")
		(net "M_H_CPU0_SB_DQ<11>")
	)
	(segment
		(start 460.570326 -220.703902)
		(end 461.251554 -220.703902)
		(width 0.20066)
		(layer "F.Cu")
		(net "M_H_CPU0_SB_DQ<11>")
	)
	(segment
		(start 458.543152 -220.698822)
		(end 458.550264 -220.69171)
		(width 0.1016)
		(layer "F.Cu")
		(net "M_H_CPU0_SB_DQ<11>")
	)
	(segment
		(start 430.951894 -213.453472)
		(end 429.85944 -213.453472)
		(width 0.18288)
		(layer "In11.Cu")
		(net "M_H_CPU0_SB_DQ<11>")
	)
	(segment
		(start 424.391582 -214.740744)
		(end 424.249088 -214.883238)
		(width 0.18288)
		(layer "In11.Cu")
		(net "M_H_CPU0_SB_DQ<11>")
	)
	(segment
		(start 422.270682 -214.883238)
		(end 421.56507 -215.58885)
		(width 0.18288)
		(layer "In11.Cu")
		(net "M_H_CPU0_SB_DQ<11>")
	)
	(segment
		(start 404.683214 -215.56218)
		(end 404.991824 -215.871044)
		(width 0.18288)
		(layer "In11.Cu")
		(net "M_H_CPU0_SB_DQ<11>")
	)
	(segment
		(start 404.991824 -215.871044)
		(end 404.991824 -216.14384)
		(width 0.18288)
		(layer "In11.Cu")
		(net "M_H_CPU0_SB_DQ<11>")
	)
	(segment
		(start 404.185628 -216.059766)
		(end 403.912832 -216.059766)
		(width 0.18288)
		(layer "In11.Cu")
		(net "M_H_CPU0_SB_DQ<11>")
	)
	(segment
		(start 434.174646 -214.004652)
		(end 433.981606 -213.811612)
		(width 0.18288)
		(layer "In11.Cu")
		(net "M_H_CPU0_SB_DQ<11>")
	)
	(segment
		(start 380.913132 -233.666538)
		(end 380.913386 -233.666538)
		(width 0.088646)
		(layer "In11.Cu")
		(net "M_H_CPU0_SB_DQ<11>")
	)
	(segment
		(start 424.249088 -214.883238)
		(end 422.270682 -214.883238)
		(width 0.18288)
		(layer "In11.Cu")
		(net "M_H_CPU0_SB_DQ<11>")
	)
	(segment
		(start 451.537324 -219.842588)
		(end 450.974968 -219.842588)
		(width 0.18288)
		(layer "In11.Cu")
		(net "M_H_CPU0_SB_DQ<11>")
	)
	(segment
		(start 431.503074 -214.004652)
		(end 430.951894 -213.453472)
		(width 0.18288)
		(layer "In11.Cu")
		(net "M_H_CPU0_SB_DQ<11>")
	)
	(segment
		(start 378.659136 -233.666538)
		(end 378.644404 -233.657902)
		(width 0.088646)
		(layer "In11.Cu")
		(net "M_H_CPU0_SB_DQ<11>")
	)
	(segment
		(start 429.6664 -213.260432)
		(end 429.6664 -212.720936)
		(width 0.18288)
		(layer "In11.Cu")
		(net "M_H_CPU0_SB_DQ<11>")
	)
	(segment
		(start 379.598936 -233.666538)
		(end 379.584204 -233.657902)
		(width 0.088646)
		(layer "In11.Cu")
		(net "M_H_CPU0_SB_DQ<11>")
	)
	(segment
		(start 427.15434 -214.050626)
		(end 426.41139 -214.050626)
		(width 0.18288)
		(layer "In11.Cu")
		(net "M_H_CPU0_SB_DQ<11>")
	)
	(segment
		(start 420.096442 -215.58885)
		(end 419.958266 -215.727026)
		(width 0.18288)
		(layer "In11.Cu")
		(net "M_H_CPU0_SB_DQ<11>")
	)
	(segment
		(start 376.214386 -233.666538)
		(end 376.213878 -233.666538)
		(width 0.088646)
		(layer "In11.Cu")
		(net "M_H_CPU0_SB_DQ<11>")
	)
	(segment
		(start 448.667378 -219.95511)
		(end 446.953894 -218.241626)
		(width 0.18288)
		(layer "In11.Cu")
		(net "M_H_CPU0_SB_DQ<11>")
	)
	(segment
		(start 442.305694 -215.650826)
		(end 441.950094 -215.650826)
		(width 0.18288)
		(layer "In11.Cu")
		(net "M_H_CPU0_SB_DQ<11>")
	)
	(segment
		(start 433.278026 -213.503002)
		(end 433.278026 -213.811612)
		(width 0.18288)
		(layer "In11.Cu")
		(net "M_H_CPU0_SB_DQ<11>")
	)
	(segment
		(start 409.499308 -214.738712)
		(end 409.298394 -214.939626)
		(width 0.18288)
		(layer "In11.Cu")
		(net "M_H_CPU0_SB_DQ<11>")
	)
	(segment
		(start 429.6664 -212.720936)
		(end 429.47336 -212.527896)
		(width 0.18288)
		(layer "In11.Cu")
		(net "M_H_CPU0_SB_DQ<11>")
	)
	(segment
		(start 412.52394 -214.914226)
		(end 412.348426 -214.738712)
		(width 0.18288)
		(layer "In11.Cu")
		(net "M_H_CPU0_SB_DQ<11>")
	)
	(segment
		(start 426.41139 -214.050626)
		(end 425.721272 -214.740744)
		(width 0.18288)
		(layer "In11.Cu")
		(net "M_H_CPU0_SB_DQ<11>")
	)
	(segment
		(start 377.719336 -233.666538)
		(end 377.704604 -233.657902)
		(width 0.088646)
		(layer "In11.Cu")
		(net "M_H_CPU0_SB_DQ<11>")
	)
	(segment
		(start 404.683214 -215.289384)
		(end 404.683214 -215.56218)
		(width 0.18288)
		(layer "In11.Cu")
		(net "M_H_CPU0_SB_DQ<11>")
	)
	(segment
		(start 449.96481 -219.95511)
		(end 448.667378 -219.95511)
		(width 0.18288)
		(layer "In11.Cu")
		(net "M_H_CPU0_SB_DQ<11>")
	)
	(segment
		(start 373.58701 -233.566462)
		(end 373.478298 -233.566462)
		(width 0.088646)
		(layer "In11.Cu")
		(net "M_H_CPU0_SB_DQ<11>")
	)
	(segment
		(start 443.270894 -216.616026)
		(end 442.305694 -215.650826)
		(width 0.18288)
		(layer "In11.Cu")
		(net "M_H_CPU0_SB_DQ<11>")
	)
	(segment
		(start 404.767034 -216.36863)
		(end 404.494238 -216.36863)
		(width 0.18288)
		(layer "In11.Cu")
		(net "M_H_CPU0_SB_DQ<11>")
	)
	(segment
		(start 428.76978 -213.453472)
		(end 427.751494 -213.453472)
		(width 0.18288)
		(layer "In11.Cu")
		(net "M_H_CPU0_SB_DQ<11>")
	)
	(segment
		(start 433.084986 -214.004652)
		(end 431.503074 -214.004652)
		(width 0.18288)
		(layer "In11.Cu")
		(net "M_H_CPU0_SB_DQ<11>")
	)
	(segment
		(start 433.788566 -213.309962)
		(end 433.471066 -213.309962)
		(width 0.18288)
		(layer "In11.Cu")
		(net "M_H_CPU0_SB_DQ<11>")
	)
	(segment
		(start 433.278026 -213.811612)
		(end 433.084986 -214.004652)
		(width 0.18288)
		(layer "In11.Cu")
		(net "M_H_CPU0_SB_DQ<11>")
	)
	(segment
		(start 416.846258 -215.727026)
		(end 416.033458 -214.914226)
		(width 0.18288)
		(layer "In11.Cu")
		(net "M_H_CPU0_SB_DQ<11>")
	)
	(segment
		(start 454.248774 -220.073728)
		(end 454.248774 -219.50426)
		(width 0.18288)
		(layer "In11.Cu")
		(net "M_H_CPU0_SB_DQ<11>")
	)
	(segment
		(start 454.248774 -219.50426)
		(end 453.945752 -219.201238)
		(width 0.18288)
		(layer "In11.Cu")
		(net "M_H_CPU0_SB_DQ<11>")
	)
	(segment
		(start 429.47336 -212.527896)
		(end 429.15586 -212.527896)
		(width 0.18288)
		(layer "In11.Cu")
		(net "M_H_CPU0_SB_DQ<11>")
	)
	(segment
		(start 438.567576 -214.740744)
		(end 438.405778 -214.902542)
		(width 0.18288)
		(layer "In11.Cu")
		(net "M_H_CPU0_SB_DQ<11>")
	)
	(segment
		(start 441.040012 -214.740744)
		(end 438.567576 -214.740744)
		(width 0.18288)
		(layer "In11.Cu")
		(net "M_H_CPU0_SB_DQ<11>")
	)
	(segment
		(start 412.348426 -214.738712)
		(end 409.499308 -214.738712)
		(width 0.18288)
		(layer "In11.Cu")
		(net "M_H_CPU0_SB_DQ<11>")
	)
	(segment
		(start 387.980682 -232.12425)
		(end 386.38734 -233.717592)
		(width 0.088646)
		(layer "In11.Cu")
		(net "M_H_CPU0_SB_DQ<11>")
	)
	(segment
		(start 450.974968 -219.842588)
		(end 450.974206 -219.841826)
		(width 0.18288)
		(layer "In11.Cu")
		(net "M_H_CPU0_SB_DQ<11>")
	)
	(segment
		(start 396.42796 -225.086926)
		(end 396.42796 -225.99269)
		(width 0.18288)
		(layer "In11.Cu")
		(net "M_H_CPU0_SB_DQ<11>")
	)
	(segment
		(start 434.833268 -214.004652)
		(end 434.174646 -214.004652)
		(width 0.18288)
		(layer "In11.Cu")
		(net "M_H_CPU0_SB_DQ<11>")
	)
	(segment
		(start 419.958266 -215.727026)
		(end 416.846258 -215.727026)
		(width 0.18288)
		(layer "In11.Cu")
		(net "M_H_CPU0_SB_DQ<11>")
	)
	(segment
		(start 441.950094 -215.650826)
		(end 441.040012 -214.740744)
		(width 0.18288)
		(layer "In11.Cu")
		(net "M_H_CPU0_SB_DQ<11>")
	)
	(segment
		(start 450.974206 -219.841826)
		(end 450.078094 -219.841826)
		(width 0.18288)
		(layer "In11.Cu")
		(net "M_H_CPU0_SB_DQ<11>")
	)
	(segment
		(start 376.779536 -233.666538)
		(end 376.769122 -233.660442)
		(width 0.088646)
		(layer "In11.Cu")
		(net "M_H_CPU0_SB_DQ<11>")
	)
	(segment
		(start 450.078094 -219.841826)
		(end 449.96481 -219.95511)
		(width 0.18288)
		(layer "In11.Cu")
		(net "M_H_CPU0_SB_DQ<11>")
	)
	(segment
		(start 379.983746 -233.660442)
		(end 379.973332 -233.666538)
		(width 0.088646)
		(layer "In11.Cu")
		(net "M_H_CPU0_SB_DQ<11>")
	)
	(segment
		(start 388.312406 -231.902762)
		(end 388.140448 -231.902762)
		(width 0.088646)
		(layer "In11.Cu")
		(net "M_H_CPU0_SB_DQ<11>")
	)
	(segment
		(start 455.011282 -220.266768)
		(end 454.441814 -220.266768)
		(width 0.18288)
		(layer "In11.Cu")
		(net "M_H_CPU0_SB_DQ<11>")
	)
	(segment
		(start 433.981606 -213.811612)
		(end 433.981606 -213.503002)
		(width 0.18288)
		(layer "In11.Cu")
		(net "M_H_CPU0_SB_DQ<11>")
	)
	(segment
		(start 437.726074 -214.902542)
		(end 436.714646 -213.891114)
		(width 0.18288)
		(layer "In11.Cu")
		(net "M_H_CPU0_SB_DQ<11>")
	)
	(segment
		(start 433.471066 -213.309962)
		(end 433.278026 -213.503002)
		(width 0.18288)
		(layer "In11.Cu")
		(net "M_H_CPU0_SB_DQ<11>")
	)
	(segment
		(start 390.517888 -231.902762)
		(end 388.312406 -231.902762)
		(width 0.18288)
		(layer "In11.Cu")
		(net "M_H_CPU0_SB_DQ<11>")
	)
	(segment
		(start 374.899682 -233.666538)
		(end 374.885204 -233.657902)
		(width 0.088646)
		(layer "In11.Cu")
		(net "M_H_CPU0_SB_DQ<11>")
	)
	(segment
		(start 443.753494 -216.616026)
		(end 443.270894 -216.616026)
		(width 0.18288)
		(layer "In11.Cu")
		(net "M_H_CPU0_SB_DQ<11>")
	)
	(segment
		(start 446.953894 -218.241626)
		(end 445.379094 -218.241626)
		(width 0.18288)
		(layer "In11.Cu")
		(net "M_H_CPU0_SB_DQ<11>")
	)
	(segment
		(start 445.379094 -218.241626)
		(end 443.753494 -216.616026)
		(width 0.18288)
		(layer "In11.Cu")
		(net "M_H_CPU0_SB_DQ<11>")
	)
	(segment
		(start 453.945752 -219.201238)
		(end 452.178674 -219.201238)
		(width 0.18288)
		(layer "In11.Cu")
		(net "M_H_CPU0_SB_DQ<11>")
	)
	(segment
		(start 429.15586 -212.527896)
		(end 428.96282 -212.720936)
		(width 0.18288)
		(layer "In11.Cu")
		(net "M_H_CPU0_SB_DQ<11>")
	)
	(segment
		(start 386.38734 -233.717592)
		(end 386.365242 -233.717592)
		(width 0.088646)
		(layer "In11.Cu")
		(net "M_H_CPU0_SB_DQ<11>")
	)
	(segment
		(start 403.660864 -216.311734)
		(end 403.660864 -217.854022)
		(width 0.18288)
		(layer "In11.Cu")
		(net "M_H_CPU0_SB_DQ<11>")
	)
	(segment
		(start 405.032972 -214.939626)
		(end 404.683214 -215.289384)
		(width 0.18288)
		(layer "In11.Cu")
		(net "M_H_CPU0_SB_DQ<11>")
	)
	(segment
		(start 409.298394 -214.939626)
		(end 405.032972 -214.939626)
		(width 0.18288)
		(layer "In11.Cu")
		(net "M_H_CPU0_SB_DQ<11>")
	)
	(segment
		(start 428.96282 -213.260432)
		(end 428.76978 -213.453472)
		(width 0.18288)
		(layer "In11.Cu")
		(net "M_H_CPU0_SB_DQ<11>")
	)
	(segment
		(start 429.85944 -213.453472)
		(end 429.6664 -213.260432)
		(width 0.18288)
		(layer "In11.Cu")
		(net "M_H_CPU0_SB_DQ<11>")
	)
	(segment
		(start 403.660864 -217.854022)
		(end 396.42796 -225.086926)
		(width 0.18288)
		(layer "In11.Cu")
		(net "M_H_CPU0_SB_DQ<11>")
	)
	(segment
		(start 404.494238 -216.36863)
		(end 404.185628 -216.059766)
		(width 0.18288)
		(layer "In11.Cu")
		(net "M_H_CPU0_SB_DQ<11>")
	)
	(segment
		(start 428.96282 -212.720936)
		(end 428.96282 -213.260432)
		(width 0.18288)
		(layer "In11.Cu")
		(net "M_H_CPU0_SB_DQ<11>")
	)
	(segment
		(start 373.398542 -233.533442)
		(end 373.20728 -233.34218)
		(width 0.088646)
		(layer "In11.Cu")
		(net "M_H_CPU0_SB_DQ<11>")
	)
	(segment
		(start 438.405778 -214.902542)
		(end 437.726074 -214.902542)
		(width 0.18288)
		(layer "In11.Cu")
		(net "M_H_CPU0_SB_DQ<11>")
	)
	(segment
		(start 433.981606 -213.503002)
		(end 433.788566 -213.309962)
		(width 0.18288)
		(layer "In11.Cu")
		(net "M_H_CPU0_SB_DQ<11>")
	)
	(segment
		(start 421.56507 -215.58885)
		(end 420.096442 -215.58885)
		(width 0.18288)
		(layer "In11.Cu")
		(net "M_H_CPU0_SB_DQ<11>")
	)
	(segment
		(start 416.033458 -214.914226)
		(end 412.52394 -214.914226)
		(width 0.18288)
		(layer "In11.Cu")
		(net "M_H_CPU0_SB_DQ<11>")
	)
	(segment
		(start 403.912832 -216.059766)
		(end 403.660864 -216.311734)
		(width 0.18288)
		(layer "In11.Cu")
		(net "M_H_CPU0_SB_DQ<11>")
	)
	(segment
		(start 425.721272 -214.740744)
		(end 424.391582 -214.740744)
		(width 0.18288)
		(layer "In11.Cu")
		(net "M_H_CPU0_SB_DQ<11>")
	)
	(segment
		(start 454.441814 -220.266768)
		(end 454.248774 -220.073728)
		(width 0.18288)
		(layer "In11.Cu")
		(net "M_H_CPU0_SB_DQ<11>")
	)
	(segment
		(start 427.751494 -213.453472)
		(end 427.15434 -214.050626)
		(width 0.18288)
		(layer "In11.Cu")
		(net "M_H_CPU0_SB_DQ<11>")
	)
	(segment
		(start 436.714646 -213.891114)
		(end 434.946806 -213.891114)
		(width 0.18288)
		(layer "In11.Cu")
		(net "M_H_CPU0_SB_DQ<11>")
	)
	(segment
		(start 404.991824 -216.14384)
		(end 404.767034 -216.36863)
		(width 0.18288)
		(layer "In11.Cu")
		(net "M_H_CPU0_SB_DQ<11>")
	)
	(segment
		(start 452.178674 -219.201238)
		(end 451.537324 -219.842588)
		(width 0.18288)
		(layer "In11.Cu")
		(net "M_H_CPU0_SB_DQ<11>")
	)
	(segment
		(start 387.980682 -232.062528)
		(end 387.980682 -232.12425)
		(width 0.088646)
		(layer "In11.Cu")
		(net "M_H_CPU0_SB_DQ<11>")
	)
	(segment
		(start 375.839482 -233.666538)
		(end 375.82475 -233.657902)
		(width 0.088646)
		(layer "In11.Cu")
		(net "M_H_CPU0_SB_DQ<11>")
	)
	(segment
		(start 434.946806 -213.891114)
		(end 434.833268 -214.004652)
		(width 0.18288)
		(layer "In11.Cu")
		(net "M_H_CPU0_SB_DQ<11>")
	)
	(segment
		(start 388.140448 -231.902762)
		(end 387.980682 -232.062528)
		(width 0.088646)
		(layer "In11.Cu")
		(net "M_H_CPU0_SB_DQ<11>")
	)
	(segment
		(start 396.42796 -225.99269)
		(end 390.517888 -231.902762)
		(width 0.18288)
		(layer "In11.Cu")
		(net "M_H_CPU0_SB_DQ<11>")
	)
	(arc
		(start 383.358136 -233.666538)
		(mid 383.075434 -233.590796)
		(end 382.792732 -233.666538)
		(width 0.088646)
		(layer "In11.Cu")
		(net "M_H_CPU0_SB_DQ<11>")
	)
	(arc
		(start 382.418336 -233.666538)
		(mid 382.135634 -233.590796)
		(end 381.852932 -233.666538)
		(width 0.088646)
		(layer "In11.Cu")
		(net "M_H_CPU0_SB_DQ<11>")
	)
	(arc
		(start 383.732532 -233.666538)
		(mid 383.545334 -233.716681)
		(end 383.358136 -233.666538)
		(width 0.088646)
		(layer "In11.Cu")
		(net "M_H_CPU0_SB_DQ<11>")
	)
	(arc
		(start 377.153932 -233.666538)
		(mid 376.966734 -233.716681)
		(end 376.779536 -233.666538)
		(width 0.088646)
		(layer "In11.Cu")
		(net "M_H_CPU0_SB_DQ<11>")
	)
	(arc
		(start 375.274078 -233.666538)
		(mid 375.08688 -233.716681)
		(end 374.899682 -233.666538)
		(width 0.088646)
		(layer "In11.Cu")
		(net "M_H_CPU0_SB_DQ<11>")
	)
	(arc
		(start 373.960136 -233.666538)
		(mid 373.780165 -233.591927)
		(end 373.58701 -233.566462)
		(width 0.088646)
		(layer "In11.Cu")
		(net "M_H_CPU0_SB_DQ<11>")
	)
	(arc
		(start 385.612132 -233.666538)
		(mid 385.424934 -233.716681)
		(end 385.237736 -233.666538)
		(width 0.088646)
		(layer "In11.Cu")
		(net "M_H_CPU0_SB_DQ<11>")
	)
	(arc
		(start 379.973332 -233.666538)
		(mid 379.786134 -233.716681)
		(end 379.598936 -233.666538)
		(width 0.088646)
		(layer "In11.Cu")
		(net "M_H_CPU0_SB_DQ<11>")
	)
	(arc
		(start 384.672332 -233.666538)
		(mid 384.485134 -233.716681)
		(end 384.297936 -233.666538)
		(width 0.088646)
		(layer "In11.Cu")
		(net "M_H_CPU0_SB_DQ<11>")
	)
	(arc
		(start 376.769122 -233.660442)
		(mid 376.490944 -233.590719)
		(end 376.214386 -233.666538)
		(width 0.088646)
		(layer "In11.Cu")
		(net "M_H_CPU0_SB_DQ<11>")
	)
	(arc
		(start 378.644404 -233.657902)
		(mid 378.367929 -233.590582)
		(end 378.093732 -233.666538)
		(width 0.088646)
		(layer "In11.Cu")
		(net "M_H_CPU0_SB_DQ<11>")
	)
	(arc
		(start 379.584204 -233.657902)
		(mid 379.307729 -233.590582)
		(end 379.033532 -233.666538)
		(width 0.088646)
		(layer "In11.Cu")
		(net "M_H_CPU0_SB_DQ<11>")
	)
	(arc
		(start 382.792732 -233.666538)
		(mid 382.605534 -233.716681)
		(end 382.418336 -233.666538)
		(width 0.088646)
		(layer "In11.Cu")
		(net "M_H_CPU0_SB_DQ<11>")
	)
	(arc
		(start 374.334532 -233.666538)
		(mid 374.147334 -233.716681)
		(end 373.960136 -233.666538)
		(width 0.088646)
		(layer "In11.Cu")
		(net "M_H_CPU0_SB_DQ<11>")
	)
	(arc
		(start 380.913386 -233.666538)
		(mid 380.726188 -233.716681)
		(end 380.53899 -233.666538)
		(width 0.088646)
		(layer "In11.Cu")
		(net "M_H_CPU0_SB_DQ<11>")
	)
	(arc
		(start 374.885204 -233.657902)
		(mid 374.608729 -233.590582)
		(end 374.334532 -233.666538)
		(width 0.088646)
		(layer "In11.Cu")
		(net "M_H_CPU0_SB_DQ<11>")
	)
	(arc
		(start 373.478298 -233.566462)
		(mid 373.43514 -233.557877)
		(end 373.398542 -233.533442)
		(width 0.088646)
		(layer "In11.Cu")
		(net "M_H_CPU0_SB_DQ<11>")
	)
	(arc
		(start 386.177536 -233.666538)
		(mid 385.894834 -233.590796)
		(end 385.612132 -233.666538)
		(width 0.088646)
		(layer "In11.Cu")
		(net "M_H_CPU0_SB_DQ<11>")
	)
	(arc
		(start 375.82475 -233.657902)
		(mid 375.548309 -233.590736)
		(end 375.274078 -233.666538)
		(width 0.088646)
		(layer "In11.Cu")
		(net "M_H_CPU0_SB_DQ<11>")
	)
	(arc
		(start 380.53899 -233.666538)
		(mid 380.262177 -233.590668)
		(end 379.983746 -233.660442)
		(width 0.088646)
		(layer "In11.Cu")
		(net "M_H_CPU0_SB_DQ<11>")
	)
	(arc
		(start 385.237736 -233.666538)
		(mid 384.955034 -233.590796)
		(end 384.672332 -233.666538)
		(width 0.088646)
		(layer "In11.Cu")
		(net "M_H_CPU0_SB_DQ<11>")
	)
	(arc
		(start 386.365242 -233.717592)
		(mid 386.26803 -233.704428)
		(end 386.177536 -233.666538)
		(width 0.088646)
		(layer "In11.Cu")
		(net "M_H_CPU0_SB_DQ<11>")
	)
	(arc
		(start 381.478536 -233.666538)
		(mid 381.195834 -233.590796)
		(end 380.913132 -233.666538)
		(width 0.088646)
		(layer "In11.Cu")
		(net "M_H_CPU0_SB_DQ<11>")
	)
	(arc
		(start 378.093732 -233.666538)
		(mid 377.906534 -233.716681)
		(end 377.719336 -233.666538)
		(width 0.088646)
		(layer "In11.Cu")
		(net "M_H_CPU0_SB_DQ<11>")
	)
	(arc
		(start 381.852932 -233.666538)
		(mid 381.665734 -233.716681)
		(end 381.478536 -233.666538)
		(width 0.088646)
		(layer "In11.Cu")
		(net "M_H_CPU0_SB_DQ<11>")
	)
	(arc
		(start 377.704604 -233.657902)
		(mid 377.428129 -233.590582)
		(end 377.153932 -233.666538)
		(width 0.088646)
		(layer "In11.Cu")
		(net "M_H_CPU0_SB_DQ<11>")
	)
	(arc
		(start 376.213878 -233.666538)
		(mid 376.02668 -233.716681)
		(end 375.839482 -233.666538)
		(width 0.088646)
		(layer "In11.Cu")
		(net "M_H_CPU0_SB_DQ<11>")
	)
	(arc
		(start 379.033532 -233.666538)
		(mid 378.846334 -233.716681)
		(end 378.659136 -233.666538)
		(width 0.088646)
		(layer "In11.Cu")
		(net "M_H_CPU0_SB_DQ<11>")
	)
	(arc
		(start 384.297936 -233.666538)
		(mid 384.015234 -233.590796)
		(end 383.732532 -233.666538)
		(width 0.088646)
		(layer "In11.Cu")
		(net "M_H_CPU0_SB_DQ<11>")
	)
	(segment
		(start 462.32572 -221.96679)
		(end 463.659982 -221.96679)
		(width 0.20066)
		(layer "F.Cu")
		(net "M_H_CPU0_SB_DQ<10>")
	)
	(segment
		(start 461.251554 -222.403924)
		(end 461.455516 -222.199962)
		(width 0.20066)
		(layer "F.Cu")
		(net "M_H_CPU0_SB_DQ<10>")
	)
	(segment
		(start 460.558134 -222.391732)
		(end 460.570326 -222.403924)
		(width 0.1016)
		(layer "F.Cu")
		(net "M_H_CPU0_SB_DQ<10>")
	)
	(segment
		(start 455.011282 -221.96679)
		(end 456.116182 -221.96679)
		(width 0.20066)
		(layer "F.Cu")
		(net "M_H_CPU0_SB_DQ<10>")
	)
	(segment
		(start 456.116182 -221.96679)
		(end 457.814426 -221.96679)
		(width 0.20066)
		(layer "F.Cu")
		(net "M_H_CPU0_SB_DQ<10>")
	)
	(segment
		(start 458.538326 -222.398844)
		(end 458.543152 -222.398844)
		(width 0.101854)
		(layer "F.Cu")
		(net "M_H_CPU0_SB_DQ<10>")
	)
	(segment
		(start 372.737634 -234.691936)
		(end 372.737634 -234.15625)
		(width 0.20066)
		(layer "F.Cu")
		(net "M_H_CPU0_SB_DQ<10>")
	)
	(segment
		(start 461.689704 -221.714822)
		(end 462.073752 -221.714822)
		(width 0.20066)
		(layer "F.Cu")
		(net "M_H_CPU0_SB_DQ<10>")
	)
	(segment
		(start 460.570326 -222.403924)
		(end 461.251554 -222.403924)
		(width 0.20066)
		(layer "F.Cu")
		(net "M_H_CPU0_SB_DQ<10>")
	)
	(segment
		(start 458.543152 -222.398844)
		(end 458.550264 -222.391732)
		(width 0.1016)
		(layer "F.Cu")
		(net "M_H_CPU0_SB_DQ<10>")
	)
	(segment
		(start 461.455516 -222.199962)
		(end 461.455516 -221.94901)
		(width 0.20066)
		(layer "F.Cu")
		(net "M_H_CPU0_SB_DQ<10>")
	)
	(segment
		(start 461.455516 -221.94901)
		(end 461.689704 -221.714822)
		(width 0.20066)
		(layer "F.Cu")
		(net "M_H_CPU0_SB_DQ<10>")
	)
	(segment
		(start 372.73738 -234.69219)
		(end 372.737634 -234.691936)
		(width 0.20066)
		(layer "F.Cu")
		(net "M_H_CPU0_SB_DQ<10>")
	)
	(segment
		(start 457.814426 -221.96679)
		(end 458.24648 -222.398844)
		(width 0.20066)
		(layer "F.Cu")
		(net "M_H_CPU0_SB_DQ<10>")
	)
	(segment
		(start 458.550264 -222.391732)
		(end 460.558134 -222.391732)
		(width 0.1016)
		(layer "F.Cu")
		(net "M_H_CPU0_SB_DQ<10>")
	)
	(segment
		(start 458.24648 -222.398844)
		(end 458.538326 -222.398844)
		(width 0.20066)
		(layer "F.Cu")
		(net "M_H_CPU0_SB_DQ<10>")
	)
	(segment
		(start 462.073752 -221.714822)
		(end 462.32572 -221.96679)
		(width 0.20066)
		(layer "F.Cu")
		(net "M_H_CPU0_SB_DQ<10>")
	)
	(segment
		(start 408.803094 -216.387426)
		(end 408.521916 -216.668604)
		(width 0.18288)
		(layer "In11.Cu")
		(net "M_H_CPU0_SB_DQ<10>")
	)
	(segment
		(start 418.574982 -216.808812)
		(end 418.257482 -216.808812)
		(width 0.18288)
		(layer "In11.Cu")
		(net "M_H_CPU0_SB_DQ<10>")
	)
	(segment
		(start 431.917094 -215.473026)
		(end 429.865536 -215.473026)
		(width 0.18288)
		(layer "In11.Cu")
		(net "M_H_CPU0_SB_DQ<10>")
	)
	(segment
		(start 401.626324 -221.365572)
		(end 401.401534 -221.590362)
		(width 0.18288)
		(layer "In11.Cu")
		(net "M_H_CPU0_SB_DQ<10>")
	)
	(segment
		(start 408.521916 -216.668604)
		(end 407.30297 -216.668604)
		(width 0.18288)
		(layer "In11.Cu")
		(net "M_H_CPU0_SB_DQ<10>")
	)
	(segment
		(start 423.982896 -216.631266)
		(end 422.326054 -216.631266)
		(width 0.18288)
		(layer "In11.Cu")
		(net "M_H_CPU0_SB_DQ<10>")
	)
	(segment
		(start 417.073334 -217.545666)
		(end 416.218116 -216.690448)
		(width 0.18288)
		(layer "In11.Cu")
		(net "M_H_CPU0_SB_DQ<10>")
	)
	(segment
		(start 373.489982 -234.480608)
		(end 373.48414 -234.477052)
		(width 0.088646)
		(layer "In11.Cu")
		(net "M_H_CPU0_SB_DQ<10>")
	)
	(segment
		(start 418.961062 -217.545666)
		(end 418.768022 -217.352626)
		(width 0.18288)
		(layer "In11.Cu")
		(net "M_H_CPU0_SB_DQ<10>")
	)
	(segment
		(start 374.819164 -234.471972)
		(end 374.804432 -234.480608)
		(width 0.088646)
		(layer "In11.Cu")
		(net "M_H_CPU0_SB_DQ<10>")
	)
	(segment
		(start 428.968916 -215.666066)
		(end 428.775876 -215.473026)
		(width 0.18288)
		(layer "In11.Cu")
		(net "M_H_CPU0_SB_DQ<10>")
	)
	(segment
		(start 403.111208 -220.58757)
		(end 402.894292 -220.3704)
		(width 0.18288)
		(layer "In11.Cu")
		(net "M_H_CPU0_SB_DQ<10>")
	)
	(segment
		(start 435.10581 -215.727026)
		(end 432.171094 -215.727026)
		(width 0.18288)
		(layer "In11.Cu")
		(net "M_H_CPU0_SB_DQ<10>")
	)
	(segment
		(start 451.394322 -221.542356)
		(end 450.182488 -221.542356)
		(width 0.18288)
		(layer "In11.Cu")
		(net "M_H_CPU0_SB_DQ<10>")
	)
	(segment
		(start 372.424706 -234.15625)
		(end 372.737634 -234.15625)
		(width 0.088646)
		(layer "In11.Cu")
		(net "M_H_CPU0_SB_DQ<10>")
	)
	(segment
		(start 448.833494 -221.670626)
		(end 447.715894 -220.553026)
		(width 0.18288)
		(layer "In11.Cu")
		(net "M_H_CPU0_SB_DQ<10>")
	)
	(segment
		(start 455.011282 -221.96679)
		(end 454.533254 -221.489524)
		(width 0.18288)
		(layer "In11.Cu")
		(net "M_H_CPU0_SB_DQ<10>")
	)
	(segment
		(start 429.865536 -215.473026)
		(end 429.672496 -215.666066)
		(width 0.18288)
		(layer "In11.Cu")
		(net "M_H_CPU0_SB_DQ<10>")
	)
	(segment
		(start 428.968916 -215.919812)
		(end 428.968916 -215.666066)
		(width 0.18288)
		(layer "In11.Cu")
		(net "M_H_CPU0_SB_DQ<10>")
	)
	(segment
		(start 378.578364 -234.471972)
		(end 378.563632 -234.480608)
		(width 0.088646)
		(layer "In11.Cu")
		(net "M_H_CPU0_SB_DQ<10>")
	)
	(segment
		(start 402.613622 -221.357952)
		(end 402.388832 -221.582742)
		(width 0.18288)
		(layer "In11.Cu")
		(net "M_H_CPU0_SB_DQ<10>")
	)
	(segment
		(start 388.103364 -232.960164)
		(end 387.896862 -232.960164)
		(width 0.088646)
		(layer "In11.Cu")
		(net "M_H_CPU0_SB_DQ<10>")
	)
	(segment
		(start 384.217164 -234.471972)
		(end 384.202432 -234.480608)
		(width 0.088646)
		(layer "In11.Cu")
		(net "M_H_CPU0_SB_DQ<10>")
	)
	(segment
		(start 428.775876 -215.473026)
		(end 427.769782 -215.473026)
		(width 0.18288)
		(layer "In11.Cu")
		(net "M_H_CPU0_SB_DQ<10>")
	)
	(segment
		(start 401.61845 -222.080328)
		(end 401.61845 -222.353124)
		(width 0.18288)
		(layer "In11.Cu")
		(net "M_H_CPU0_SB_DQ<10>")
	)
	(segment
		(start 387.896862 -232.960164)
		(end 386.452364 -234.404662)
		(width 0.088646)
		(layer "In11.Cu")
		(net "M_H_CPU0_SB_DQ<10>")
	)
	(segment
		(start 451.780402 -222.439484)
		(end 451.587362 -222.246444)
		(width 0.18288)
		(layer "In11.Cu")
		(net "M_H_CPU0_SB_DQ<10>")
	)
	(segment
		(start 429.672496 -215.919812)
		(end 429.479456 -216.112852)
		(width 0.18288)
		(layer "In11.Cu")
		(net "M_H_CPU0_SB_DQ<10>")
	)
	(segment
		(start 438.921906 -216.440258)
		(end 438.762394 -216.59977)
		(width 0.18288)
		(layer "In11.Cu")
		(net "M_H_CPU0_SB_DQ<10>")
	)
	(segment
		(start 452.290942 -222.246444)
		(end 452.097902 -222.439484)
		(width 0.18288)
		(layer "In11.Cu")
		(net "M_H_CPU0_SB_DQ<10>")
	)
	(segment
		(start 452.53656 -221.489778)
		(end 452.290942 -221.735396)
		(width 0.18288)
		(layer "In11.Cu")
		(net "M_H_CPU0_SB_DQ<10>")
	)
	(segment
		(start 376.694446 -234.474512)
		(end 376.684032 -234.480608)
		(width 0.088646)
		(layer "In11.Cu")
		(net "M_H_CPU0_SB_DQ<10>")
	)
	(segment
		(start 427.769782 -215.473026)
		(end 426.7962 -216.446608)
		(width 0.18288)
		(layer "In11.Cu")
		(net "M_H_CPU0_SB_DQ<10>")
	)
	(segment
		(start 451.587362 -222.246444)
		(end 451.587362 -221.735396)
		(width 0.18288)
		(layer "In11.Cu")
		(net "M_H_CPU0_SB_DQ<10>")
	)
	(segment
		(start 407.30297 -216.668604)
		(end 403.384004 -220.58757)
		(width 0.18288)
		(layer "In11.Cu")
		(net "M_H_CPU0_SB_DQ<10>")
	)
	(segment
		(start 437.641492 -216.59977)
		(end 436.631588 -215.589866)
		(width 0.18288)
		(layer "In11.Cu")
		(net "M_H_CPU0_SB_DQ<10>")
	)
	(segment
		(start 401.61845 -222.353124)
		(end 391.01141 -232.960164)
		(width 0.18288)
		(layer "In11.Cu")
		(net "M_H_CPU0_SB_DQ<10>")
	)
	(segment
		(start 418.064442 -217.001852)
		(end 418.064442 -217.352626)
		(width 0.18288)
		(layer "In11.Cu")
		(net "M_H_CPU0_SB_DQ<10>")
	)
	(segment
		(start 411.048454 -217.046556)
		(end 410.730954 -217.046556)
		(width 0.18288)
		(layer "In11.Cu")
		(net "M_H_CPU0_SB_DQ<10>")
	)
	(segment
		(start 418.768022 -217.001852)
		(end 418.574982 -216.808812)
		(width 0.18288)
		(layer "In11.Cu")
		(net "M_H_CPU0_SB_DQ<10>")
	)
	(segment
		(start 452.290942 -221.735396)
		(end 452.290942 -222.246444)
		(width 0.18288)
		(layer "In11.Cu")
		(net "M_H_CPU0_SB_DQ<10>")
	)
	(segment
		(start 451.587362 -221.735396)
		(end 451.394322 -221.542356)
		(width 0.18288)
		(layer "In11.Cu")
		(net "M_H_CPU0_SB_DQ<10>")
	)
	(segment
		(start 410.730954 -217.046556)
		(end 410.537914 -216.853516)
		(width 0.18288)
		(layer "In11.Cu")
		(net "M_H_CPU0_SB_DQ<10>")
	)
	(segment
		(start 454.287128 -221.489778)
		(end 452.53656 -221.489778)
		(width 0.18288)
		(layer "In11.Cu")
		(net "M_H_CPU0_SB_DQ<10>")
	)
	(segment
		(start 421.666924 -217.290396)
		(end 420.34968 -217.290396)
		(width 0.18288)
		(layer "In11.Cu")
		(net "M_H_CPU0_SB_DQ<10>")
	)
	(segment
		(start 401.401534 -221.590362)
		(end 401.401534 -221.863158)
		(width 0.18288)
		(layer "In11.Cu")
		(net "M_H_CPU0_SB_DQ<10>")
	)
	(segment
		(start 375.758964 -234.471972)
		(end 375.744232 -234.480608)
		(width 0.088646)
		(layer "In11.Cu")
		(net "M_H_CPU0_SB_DQ<10>")
	)
	(segment
		(start 377.633992 -234.474512)
		(end 377.623578 -234.480608)
		(width 0.088646)
		(layer "In11.Cu")
		(net "M_H_CPU0_SB_DQ<10>")
	)
	(segment
		(start 372.556024 -234.48391)
		(end 372.550182 -234.480608)
		(width 0.088646)
		(layer "In11.Cu")
		(net "M_H_CPU0_SB_DQ<10>")
	)
	(segment
		(start 373.879364 -234.471972)
		(end 373.864632 -234.480608)
		(width 0.088646)
		(layer "In11.Cu")
		(net "M_H_CPU0_SB_DQ<10>")
	)
	(segment
		(start 410.344874 -216.387426)
		(end 408.803094 -216.387426)
		(width 0.18288)
		(layer "In11.Cu")
		(net "M_H_CPU0_SB_DQ<10>")
	)
	(segment
		(start 373.495824 -234.48391)
		(end 373.489982 -234.480608)
		(width 0.088646)
		(layer "In11.Cu")
		(net "M_H_CPU0_SB_DQ<10>")
	)
	(segment
		(start 403.384004 -220.58757)
		(end 403.111208 -220.58757)
		(width 0.18288)
		(layer "In11.Cu")
		(net "M_H_CPU0_SB_DQ<10>")
	)
	(segment
		(start 422.326054 -216.631266)
		(end 421.666924 -217.290396)
		(width 0.18288)
		(layer "In11.Cu")
		(net "M_H_CPU0_SB_DQ<10>")
	)
	(segment
		(start 410.537914 -216.580466)
		(end 410.344874 -216.387426)
		(width 0.18288)
		(layer "In11.Cu")
		(net "M_H_CPU0_SB_DQ<10>")
	)
	(segment
		(start 372.550182 -234.480608)
		(end 372.545102 -234.477814)
		(width 0.088646)
		(layer "In11.Cu")
		(net "M_H_CPU0_SB_DQ<10>")
	)
	(segment
		(start 411.241494 -216.853516)
		(end 411.048454 -217.046556)
		(width 0.18288)
		(layer "In11.Cu")
		(net "M_H_CPU0_SB_DQ<10>")
	)
	(segment
		(start 402.621496 -220.3704)
		(end 402.396706 -220.59519)
		(width 0.18288)
		(layer "In11.Cu")
		(net "M_H_CPU0_SB_DQ<10>")
	)
	(segment
		(start 429.672496 -215.666066)
		(end 429.672496 -215.919812)
		(width 0.18288)
		(layer "In11.Cu")
		(net "M_H_CPU0_SB_DQ<10>")
	)
	(segment
		(start 410.537914 -216.853516)
		(end 410.537914 -216.580466)
		(width 0.18288)
		(layer "In11.Cu")
		(net "M_H_CPU0_SB_DQ<10>")
	)
	(segment
		(start 391.01141 -232.960164)
		(end 388.103364 -232.960164)
		(width 0.18288)
		(layer "In11.Cu")
		(net "M_H_CPU0_SB_DQ<10>")
	)
	(segment
		(start 424.781472 -216.442036)
		(end 424.172126 -216.442036)
		(width 0.18288)
		(layer "In11.Cu")
		(net "M_H_CPU0_SB_DQ<10>")
	)
	(segment
		(start 429.479456 -216.112852)
		(end 429.161956 -216.112852)
		(width 0.18288)
		(layer "In11.Cu")
		(net "M_H_CPU0_SB_DQ<10>")
	)
	(segment
		(start 420.34968 -217.290396)
		(end 420.09441 -217.545666)
		(width 0.18288)
		(layer "In11.Cu")
		(net "M_H_CPU0_SB_DQ<10>")
	)
	(segment
		(start 386.452364 -234.404662)
		(end 386.364734 -234.404662)
		(width 0.088646)
		(layer "In11.Cu")
		(net "M_H_CPU0_SB_DQ<10>")
	)
	(segment
		(start 446.014094 -219.410026)
		(end 444.337694 -219.410026)
		(width 0.18288)
		(layer "In11.Cu")
		(net "M_H_CPU0_SB_DQ<10>")
	)
	(segment
		(start 402.396706 -220.867986)
		(end 402.613622 -221.085156)
		(width 0.18288)
		(layer "In11.Cu")
		(net "M_H_CPU0_SB_DQ<10>")
	)
	(segment
		(start 411.434534 -216.387426)
		(end 411.241494 -216.580466)
		(width 0.18288)
		(layer "In11.Cu")
		(net "M_H_CPU0_SB_DQ<10>")
	)
	(segment
		(start 401.89912 -221.365572)
		(end 401.626324 -221.365572)
		(width 0.18288)
		(layer "In11.Cu")
		(net "M_H_CPU0_SB_DQ<10>")
	)
	(segment
		(start 412.397194 -216.387426)
		(end 411.434534 -216.387426)
		(width 0.18288)
		(layer "In11.Cu")
		(net "M_H_CPU0_SB_DQ<10>")
	)
	(segment
		(start 418.768022 -217.352626)
		(end 418.768022 -217.001852)
		(width 0.18288)
		(layer "In11.Cu")
		(net "M_H_CPU0_SB_DQ<10>")
	)
	(segment
		(start 442.483494 -217.555826)
		(end 442.178694 -217.555826)
		(width 0.18288)
		(layer "In11.Cu")
		(net "M_H_CPU0_SB_DQ<10>")
	)
	(segment
		(start 401.401534 -221.863158)
		(end 401.61845 -222.080328)
		(width 0.18288)
		(layer "In11.Cu")
		(net "M_H_CPU0_SB_DQ<10>")
	)
	(segment
		(start 432.171094 -215.727026)
		(end 431.917094 -215.473026)
		(width 0.18288)
		(layer "In11.Cu")
		(net "M_H_CPU0_SB_DQ<10>")
	)
	(segment
		(start 436.631588 -215.589866)
		(end 435.920134 -215.589866)
		(width 0.18288)
		(layer "In11.Cu")
		(net "M_H_CPU0_SB_DQ<10>")
	)
	(segment
		(start 454.533254 -221.489524)
		(end 454.287128 -221.489778)
		(width 0.18288)
		(layer "In11.Cu")
		(net "M_H_CPU0_SB_DQ<10>")
	)
	(segment
		(start 450.181726 -221.541594)
		(end 450.052694 -221.670626)
		(width 0.18288)
		(layer "In11.Cu")
		(net "M_H_CPU0_SB_DQ<10>")
	)
	(segment
		(start 442.178694 -217.555826)
		(end 441.063126 -216.440258)
		(width 0.18288)
		(layer "In11.Cu")
		(net "M_H_CPU0_SB_DQ<10>")
	)
	(segment
		(start 424.781726 -216.44229)
		(end 424.781472 -216.442036)
		(width 0.18288)
		(layer "In11.Cu")
		(net "M_H_CPU0_SB_DQ<10>")
	)
	(segment
		(start 424.172126 -216.442036)
		(end 423.982896 -216.631266)
		(width 0.18288)
		(layer "In11.Cu")
		(net "M_H_CPU0_SB_DQ<10>")
	)
	(segment
		(start 402.388832 -221.582742)
		(end 402.116036 -221.582742)
		(width 0.18288)
		(layer "In11.Cu")
		(net "M_H_CPU0_SB_DQ<10>")
	)
	(segment
		(start 418.064442 -217.352626)
		(end 417.871402 -217.545666)
		(width 0.18288)
		(layer "In11.Cu")
		(net "M_H_CPU0_SB_DQ<10>")
	)
	(segment
		(start 412.700216 -216.690448)
		(end 412.397194 -216.387426)
		(width 0.18288)
		(layer "In11.Cu")
		(net "M_H_CPU0_SB_DQ<10>")
	)
	(segment
		(start 447.157094 -220.553026)
		(end 446.014094 -219.410026)
		(width 0.18288)
		(layer "In11.Cu")
		(net "M_H_CPU0_SB_DQ<10>")
	)
	(segment
		(start 441.063126 -216.440258)
		(end 438.921906 -216.440258)
		(width 0.18288)
		(layer "In11.Cu")
		(net "M_H_CPU0_SB_DQ<10>")
	)
	(segment
		(start 426.7962 -216.446608)
		(end 424.896026 -216.442544)
		(width 0.18288)
		(layer "In11.Cu")
		(net "M_H_CPU0_SB_DQ<10>")
	)
	(segment
		(start 435.920134 -215.589866)
		(end 435.762146 -215.589612)
		(width 0.18288)
		(layer "In11.Cu")
		(net "M_H_CPU0_SB_DQ<10>")
	)
	(segment
		(start 402.894292 -220.3704)
		(end 402.621496 -220.3704)
		(width 0.18288)
		(layer "In11.Cu")
		(net "M_H_CPU0_SB_DQ<10>")
	)
	(segment
		(start 435.243224 -215.589612)
		(end 435.10581 -215.727026)
		(width 0.18288)
		(layer "In11.Cu")
		(net "M_H_CPU0_SB_DQ<10>")
	)
	(segment
		(start 402.396706 -220.59519)
		(end 402.396706 -220.867986)
		(width 0.18288)
		(layer "In11.Cu")
		(net "M_H_CPU0_SB_DQ<10>")
	)
	(segment
		(start 450.052694 -221.670626)
		(end 448.833494 -221.670626)
		(width 0.18288)
		(layer "In11.Cu")
		(net "M_H_CPU0_SB_DQ<10>")
	)
	(segment
		(start 402.613622 -221.085156)
		(end 402.613622 -221.357952)
		(width 0.18288)
		(layer "In11.Cu")
		(net "M_H_CPU0_SB_DQ<10>")
	)
	(segment
		(start 438.762394 -216.59977)
		(end 437.641492 -216.59977)
		(width 0.18288)
		(layer "In11.Cu")
		(net "M_H_CPU0_SB_DQ<10>")
	)
	(segment
		(start 411.241494 -216.580466)
		(end 411.241494 -216.853516)
		(width 0.18288)
		(layer "In11.Cu")
		(net "M_H_CPU0_SB_DQ<10>")
	)
	(segment
		(start 380.457964 -234.471972)
		(end 380.443232 -234.480608)
		(width 0.088646)
		(layer "In11.Cu")
		(net "M_H_CPU0_SB_DQ<10>")
	)
	(segment
		(start 429.161956 -216.112852)
		(end 428.968916 -215.919812)
		(width 0.18288)
		(layer "In11.Cu")
		(net "M_H_CPU0_SB_DQ<10>")
	)
	(segment
		(start 418.257482 -216.808812)
		(end 418.064442 -217.001852)
		(width 0.18288)
		(layer "In11.Cu")
		(net "M_H_CPU0_SB_DQ<10>")
	)
	(segment
		(start 435.762146 -215.589612)
		(end 435.243224 -215.589612)
		(width 0.18288)
		(layer "In11.Cu")
		(net "M_H_CPU0_SB_DQ<10>")
	)
	(segment
		(start 444.337694 -219.410026)
		(end 442.483494 -217.555826)
		(width 0.18288)
		(layer "In11.Cu")
		(net "M_H_CPU0_SB_DQ<10>")
	)
	(segment
		(start 416.218116 -216.690448)
		(end 412.700216 -216.690448)
		(width 0.18288)
		(layer "In11.Cu")
		(net "M_H_CPU0_SB_DQ<10>")
	)
	(segment
		(start 417.871402 -217.545666)
		(end 417.073334 -217.545666)
		(width 0.18288)
		(layer "In11.Cu")
		(net "M_H_CPU0_SB_DQ<10>")
	)
	(segment
		(start 447.715894 -220.553026)
		(end 447.157094 -220.553026)
		(width 0.18288)
		(layer "In11.Cu")
		(net "M_H_CPU0_SB_DQ<10>")
	)
	(segment
		(start 402.116036 -221.582742)
		(end 401.89912 -221.365572)
		(width 0.18288)
		(layer "In11.Cu")
		(net "M_H_CPU0_SB_DQ<10>")
	)
	(segment
		(start 452.097902 -222.439484)
		(end 451.780402 -222.439484)
		(width 0.18288)
		(layer "In11.Cu")
		(net "M_H_CPU0_SB_DQ<10>")
	)
	(segment
		(start 424.896026 -216.442544)
		(end 424.781726 -216.44229)
		(width 0.18288)
		(layer "In11.Cu")
		(net "M_H_CPU0_SB_DQ<10>")
	)
	(segment
		(start 420.09441 -217.545666)
		(end 418.961062 -217.545666)
		(width 0.18288)
		(layer "In11.Cu")
		(net "M_H_CPU0_SB_DQ<10>")
	)
	(segment
		(start 372.367302 -234.213654)
		(end 372.424706 -234.15625)
		(width 0.088646)
		(layer "In11.Cu")
		(net "M_H_CPU0_SB_DQ<10>")
	)
	(segment
		(start 450.182488 -221.542356)
		(end 450.181726 -221.541594)
		(width 0.18288)
		(layer "In11.Cu")
		(net "M_H_CPU0_SB_DQ<10>")
	)
	(arc
		(start 380.068836 -234.480608)
		(mid 379.786134 -234.404832)
		(end 379.503432 -234.480608)
		(width 0.088646)
		(layer "In11.Cu")
		(net "M_H_CPU0_SB_DQ<10>")
	)
	(arc
		(start 372.924832 -234.480608)
		(mid 372.740878 -234.530737)
		(end 372.556024 -234.48391)
		(width 0.088646)
		(layer "In11.Cu")
		(net "M_H_CPU0_SB_DQ<10>")
	)
	(arc
		(start 385.707636 -234.480608)
		(mid 385.424934 -234.404832)
		(end 385.142232 -234.480608)
		(width 0.088646)
		(layer "In11.Cu")
		(net "M_H_CPU0_SB_DQ<10>")
	)
	(arc
		(start 376.309636 -234.480608)
		(mid 376.035437 -234.404773)
		(end 375.758964 -234.471972)
		(width 0.088646)
		(layer "In11.Cu")
		(net "M_H_CPU0_SB_DQ<10>")
	)
	(arc
		(start 382.888236 -234.480608)
		(mid 382.605534 -234.404832)
		(end 382.322832 -234.480608)
		(width 0.088646)
		(layer "In11.Cu")
		(net "M_H_CPU0_SB_DQ<10>")
	)
	(arc
		(start 377.249182 -234.480608)
		(mid 376.972623 -234.404865)
		(end 376.694446 -234.474512)
		(width 0.088646)
		(layer "In11.Cu")
		(net "M_H_CPU0_SB_DQ<10>")
	)
	(arc
		(start 376.684032 -234.480608)
		(mid 376.496834 -234.530751)
		(end 376.309636 -234.480608)
		(width 0.088646)
		(layer "In11.Cu")
		(net "M_H_CPU0_SB_DQ<10>")
	)
	(arc
		(start 384.202432 -234.480608)
		(mid 384.015234 -234.530751)
		(end 383.828036 -234.480608)
		(width 0.088646)
		(layer "In11.Cu")
		(net "M_H_CPU0_SB_DQ<10>")
	)
	(arc
		(start 375.369836 -234.480608)
		(mid 375.095637 -234.404773)
		(end 374.819164 -234.471972)
		(width 0.088646)
		(layer "In11.Cu")
		(net "M_H_CPU0_SB_DQ<10>")
	)
	(arc
		(start 379.503432 -234.480608)
		(mid 379.316234 -234.530751)
		(end 379.129036 -234.480608)
		(width 0.088646)
		(layer "In11.Cu")
		(net "M_H_CPU0_SB_DQ<10>")
	)
	(arc
		(start 378.189236 -234.480608)
		(mid 377.912423 -234.404738)
		(end 377.633992 -234.474512)
		(width 0.088646)
		(layer "In11.Cu")
		(net "M_H_CPU0_SB_DQ<10>")
	)
	(arc
		(start 374.430036 -234.480608)
		(mid 374.155837 -234.404773)
		(end 373.879364 -234.471972)
		(width 0.088646)
		(layer "In11.Cu")
		(net "M_H_CPU0_SB_DQ<10>")
	)
	(arc
		(start 377.623578 -234.480608)
		(mid 377.43638 -234.530751)
		(end 377.249182 -234.480608)
		(width 0.088646)
		(layer "In11.Cu")
		(net "M_H_CPU0_SB_DQ<10>")
	)
	(arc
		(start 386.315712 -234.406694)
		(mid 386.194808 -234.430813)
		(end 386.082032 -234.480608)
		(width 0.088646)
		(layer "In11.Cu")
		(net "M_H_CPU0_SB_DQ<10>")
	)
	(arc
		(start 386.364734 -234.404662)
		(mid 386.340201 -234.40515)
		(end 386.315712 -234.406694)
		(width 0.088646)
		(layer "In11.Cu")
		(net "M_H_CPU0_SB_DQ<10>")
	)
	(arc
		(start 383.828036 -234.480608)
		(mid 383.545334 -234.404832)
		(end 383.262632 -234.480608)
		(width 0.088646)
		(layer "In11.Cu")
		(net "M_H_CPU0_SB_DQ<10>")
	)
	(arc
		(start 383.262632 -234.480608)
		(mid 383.075434 -234.530751)
		(end 382.888236 -234.480608)
		(width 0.088646)
		(layer "In11.Cu")
		(net "M_H_CPU0_SB_DQ<10>")
	)
	(arc
		(start 385.142232 -234.480608)
		(mid 384.955034 -234.530751)
		(end 384.767836 -234.480608)
		(width 0.088646)
		(layer "In11.Cu")
		(net "M_H_CPU0_SB_DQ<10>")
	)
	(arc
		(start 381.383032 -234.480608)
		(mid 381.195834 -234.530751)
		(end 381.008636 -234.480608)
		(width 0.088646)
		(layer "In11.Cu")
		(net "M_H_CPU0_SB_DQ<10>")
	)
	(arc
		(start 381.948436 -234.480608)
		(mid 381.665734 -234.404832)
		(end 381.383032 -234.480608)
		(width 0.088646)
		(layer "In11.Cu")
		(net "M_H_CPU0_SB_DQ<10>")
	)
	(arc
		(start 372.545102 -234.477814)
		(mid 372.426732 -234.365564)
		(end 372.367302 -234.213654)
		(width 0.088646)
		(layer "In11.Cu")
		(net "M_H_CPU0_SB_DQ<10>")
	)
	(arc
		(start 380.443232 -234.480608)
		(mid 380.256034 -234.530751)
		(end 380.068836 -234.480608)
		(width 0.088646)
		(layer "In11.Cu")
		(net "M_H_CPU0_SB_DQ<10>")
	)
	(arc
		(start 373.48414 -234.477052)
		(mid 373.204005 -234.404769)
		(end 372.924832 -234.480608)
		(width 0.088646)
		(layer "In11.Cu")
		(net "M_H_CPU0_SB_DQ<10>")
	)
	(arc
		(start 381.008636 -234.480608)
		(mid 380.734437 -234.404773)
		(end 380.457964 -234.471972)
		(width 0.088646)
		(layer "In11.Cu")
		(net "M_H_CPU0_SB_DQ<10>")
	)
	(arc
		(start 379.129036 -234.480608)
		(mid 378.854837 -234.404773)
		(end 378.578364 -234.471972)
		(width 0.088646)
		(layer "In11.Cu")
		(net "M_H_CPU0_SB_DQ<10>")
	)
	(arc
		(start 375.744232 -234.480608)
		(mid 375.557034 -234.530751)
		(end 375.369836 -234.480608)
		(width 0.088646)
		(layer "In11.Cu")
		(net "M_H_CPU0_SB_DQ<10>")
	)
	(arc
		(start 374.804432 -234.480608)
		(mid 374.617234 -234.530751)
		(end 374.430036 -234.480608)
		(width 0.088646)
		(layer "In11.Cu")
		(net "M_H_CPU0_SB_DQ<10>")
	)
	(arc
		(start 382.322832 -234.480608)
		(mid 382.135634 -234.530751)
		(end 381.948436 -234.480608)
		(width 0.088646)
		(layer "In11.Cu")
		(net "M_H_CPU0_SB_DQ<10>")
	)
	(arc
		(start 373.864632 -234.480608)
		(mid 373.680678 -234.530737)
		(end 373.495824 -234.48391)
		(width 0.088646)
		(layer "In11.Cu")
		(net "M_H_CPU0_SB_DQ<10>")
	)
	(arc
		(start 378.563632 -234.480608)
		(mid 378.376434 -234.530751)
		(end 378.189236 -234.480608)
		(width 0.088646)
		(layer "In11.Cu")
		(net "M_H_CPU0_SB_DQ<10>")
	)
	(arc
		(start 384.767836 -234.480608)
		(mid 384.493637 -234.404773)
		(end 384.217164 -234.471972)
		(width 0.088646)
		(layer "In11.Cu")
		(net "M_H_CPU0_SB_DQ<10>")
	)
	(arc
		(start 386.082032 -234.480608)
		(mid 385.894834 -234.530751)
		(end 385.707636 -234.480608)
		(width 0.088646)
		(layer "In11.Cu")
		(net "M_H_CPU0_SB_DQ<10>")
	)
	(segment
		(start 452.016114 -232.166668)
		(end 450.911214 -232.166668)
		(width 0.20066)
		(layer "F.Cu")
		(net "M_H_CPU0_SB_DQ<0>")
	)
	(segment
		(start 459.559914 -232.166668)
		(end 459.55966 -232.166922)
		(width 0.20066)
		(layer "F.Cu")
		(net "M_H_CPU0_SB_DQ<0>")
	)
	(segment
		(start 454.91146 -231.741726)
		(end 454.566782 -231.741726)
		(width 0.20066)
		(layer "F.Cu")
		(net "M_H_CPU0_SB_DQ<0>")
	)
	(segment
		(start 457.120244 -231.741726)
		(end 454.95845 -231.741726)
		(width 0.1016)
		(layer "F.Cu")
		(net "M_H_CPU0_SB_DQ<0>")
	)
	(segment
		(start 453.785478 -232.415334)
		(end 453.536812 -232.166668)
		(width 0.20066)
		(layer "F.Cu")
		(net "M_H_CPU0_SB_DQ<0>")
	)
	(segment
		(start 371.79758 -239.57534)
		(end 371.797834 -239.575086)
		(width 0.20066)
		(layer "F.Cu")
		(net "M_H_CPU0_SB_DQ<0>")
	)
	(segment
		(start 454.448672 -231.859836)
		(end 454.448672 -232.227374)
		(width 0.20066)
		(layer "F.Cu")
		(net "M_H_CPU0_SB_DQ<0>")
	)
	(segment
		(start 454.260712 -232.415334)
		(end 453.785478 -232.415334)
		(width 0.20066)
		(layer "F.Cu")
		(net "M_H_CPU0_SB_DQ<0>")
	)
	(segment
		(start 371.797834 -239.575086)
		(end 371.797834 -239.0394)
		(width 0.20066)
		(layer "F.Cu")
		(net "M_H_CPU0_SB_DQ<0>")
	)
	(segment
		(start 457.968096 -232.166922)
		(end 457.53655 -231.735376)
		(width 0.20066)
		(layer "F.Cu")
		(net "M_H_CPU0_SB_DQ<0>")
	)
	(segment
		(start 457.126594 -231.735376)
		(end 457.120244 -231.741726)
		(width 0.1016)
		(layer "F.Cu")
		(net "M_H_CPU0_SB_DQ<0>")
	)
	(segment
		(start 454.95845 -231.741726)
		(end 454.91146 -231.741726)
		(width 0.101854)
		(layer "F.Cu")
		(net "M_H_CPU0_SB_DQ<0>")
	)
	(segment
		(start 454.566782 -231.741726)
		(end 454.448672 -231.859836)
		(width 0.20066)
		(layer "F.Cu")
		(net "M_H_CPU0_SB_DQ<0>")
	)
	(segment
		(start 457.53655 -231.735376)
		(end 457.126594 -231.735376)
		(width 0.20066)
		(layer "F.Cu")
		(net "M_H_CPU0_SB_DQ<0>")
	)
	(segment
		(start 459.55966 -232.166922)
		(end 457.968096 -232.166922)
		(width 0.20066)
		(layer "F.Cu")
		(net "M_H_CPU0_SB_DQ<0>")
	)
	(segment
		(start 454.448672 -232.227374)
		(end 454.260712 -232.415334)
		(width 0.20066)
		(layer "F.Cu")
		(net "M_H_CPU0_SB_DQ<0>")
	)
	(segment
		(start 453.536812 -232.166668)
		(end 452.016114 -232.166668)
		(width 0.20066)
		(layer "F.Cu")
		(net "M_H_CPU0_SB_DQ<0>")
	)
	(segment
		(start 445.912494 -230.865426)
		(end 444.820294 -230.865426)
		(width 0.18288)
		(layer "In11.Cu")
		(net "M_H_CPU0_SB_DQ<0>")
	)
	(segment
		(start 434.065172 -227.683568)
		(end 433.872132 -227.490528)
		(width 0.18288)
		(layer "In11.Cu")
		(net "M_H_CPU0_SB_DQ<0>")
	)
	(segment
		(start 381.478536 -239.528858)
		(end 381.468122 -239.534954)
		(width 0.088646)
		(layer "In11.Cu")
		(net "M_H_CPU0_SB_DQ<0>")
	)
	(segment
		(start 371.998748 -239.240314)
		(end 371.797834 -239.0394)
		(width 0.088646)
		(layer "In11.Cu")
		(net "M_H_CPU0_SB_DQ<0>")
	)
	(segment
		(start 373.102886 -239.450626)
		(end 372.506494 -239.450626)
		(width 0.088646)
		(layer "In11.Cu")
		(net "M_H_CPU0_SB_DQ<0>")
	)
	(segment
		(start 434.768752 -227.683568)
		(end 434.768752 -227.915216)
		(width 0.18288)
		(layer "In11.Cu")
		(net "M_H_CPU0_SB_DQ<0>")
	)
	(segment
		(start 436.454042 -227.683568)
		(end 436.261002 -227.490528)
		(width 0.18288)
		(layer "In11.Cu")
		(net "M_H_CPU0_SB_DQ<0>")
	)
	(segment
		(start 408.90063 -230.76789)
		(end 406.956006 -230.76789)
		(width 0.18288)
		(layer "In11.Cu")
		(net "M_H_CPU0_SB_DQ<0>")
	)
	(segment
		(start 421.131492 -230.043228)
		(end 420.296086 -230.043228)
		(width 0.18288)
		(layer "In11.Cu")
		(net "M_H_CPU0_SB_DQ<0>")
	)
	(segment
		(start 444.820294 -230.865426)
		(end 444.286894 -230.332026)
		(width 0.18288)
		(layer "In11.Cu")
		(net "M_H_CPU0_SB_DQ<0>")
	)
	(segment
		(start 431.558192 -227.490528)
		(end 430.951894 -228.096826)
		(width 0.18288)
		(layer "In11.Cu")
		(net "M_H_CPU0_SB_DQ<0>")
	)
	(segment
		(start 386.922264 -239.443006)
		(end 386.760212 -239.605058)
		(width 0.088646)
		(layer "In11.Cu")
		(net "M_H_CPU0_SB_DQ<0>")
	)
	(segment
		(start 429.203104 -228.096826)
		(end 429.010064 -228.289866)
		(width 0.18288)
		(layer "In11.Cu")
		(net "M_H_CPU0_SB_DQ<0>")
	)
	(segment
		(start 379.598936 -239.528858)
		(end 379.588522 -239.534954)
		(width 0.088646)
		(layer "In11.Cu")
		(net "M_H_CPU0_SB_DQ<0>")
	)
	(segment
		(start 425.157138 -229.194106)
		(end 424.005248 -229.194106)
		(width 0.18288)
		(layer "In11.Cu")
		(net "M_H_CPU0_SB_DQ<0>")
	)
	(segment
		(start 430.951894 -228.096826)
		(end 429.203104 -228.096826)
		(width 0.18288)
		(layer "In11.Cu")
		(net "M_H_CPU0_SB_DQ<0>")
	)
	(segment
		(start 428.306484 -228.289866)
		(end 428.113444 -228.096826)
		(width 0.18288)
		(layer "In11.Cu")
		(net "M_H_CPU0_SB_DQ<0>")
	)
	(segment
		(start 439.438796 -229.193852)
		(end 437.735472 -227.490528)
		(width 0.18288)
		(layer "In11.Cu")
		(net "M_H_CPU0_SB_DQ<0>")
	)
	(segment
		(start 433.168552 -228.108256)
		(end 432.851052 -228.108256)
		(width 0.18288)
		(layer "In11.Cu")
		(net "M_H_CPU0_SB_DQ<0>")
	)
	(segment
		(start 406.956006 -230.76789)
		(end 405.981408 -231.742488)
		(width 0.18288)
		(layer "In11.Cu")
		(net "M_H_CPU0_SB_DQ<0>")
	)
	(segment
		(start 444.286894 -230.332026)
		(end 443.347094 -230.332026)
		(width 0.18288)
		(layer "In11.Cu")
		(net "M_H_CPU0_SB_DQ<0>")
	)
	(segment
		(start 385.237482 -239.528858)
		(end 385.22275 -239.537494)
		(width 0.088646)
		(layer "In11.Cu")
		(net "M_H_CPU0_SB_DQ<0>")
	)
	(segment
		(start 437.735472 -227.490528)
		(end 437.350662 -227.490528)
		(width 0.18288)
		(layer "In11.Cu")
		(net "M_H_CPU0_SB_DQ<0>")
	)
	(segment
		(start 386.760212 -239.605058)
		(end 385.895342 -239.605058)
		(width 0.088646)
		(layer "In11.Cu")
		(net "M_H_CPU0_SB_DQ<0>")
	)
	(segment
		(start 375.839482 -239.528858)
		(end 375.82475 -239.537494)
		(width 0.088646)
		(layer "In11.Cu")
		(net "M_H_CPU0_SB_DQ<0>")
	)
	(segment
		(start 436.964582 -230.049578)
		(end 436.647082 -230.049578)
		(width 0.18288)
		(layer "In11.Cu")
		(net "M_H_CPU0_SB_DQ<0>")
	)
	(segment
		(start 428.306484 -228.682296)
		(end 428.306484 -228.289866)
		(width 0.18288)
		(layer "In11.Cu")
		(net "M_H_CPU0_SB_DQ<0>")
	)
	(segment
		(start 388.542022 -239.482884)
		(end 388.502144 -239.443006)
		(width 0.088646)
		(layer "In11.Cu")
		(net "M_H_CPU0_SB_DQ<0>")
	)
	(segment
		(start 450.911214 -232.166668)
		(end 450.371972 -231.627426)
		(width 0.18288)
		(layer "In11.Cu")
		(net "M_H_CPU0_SB_DQ<0>")
	)
	(segment
		(start 420.296086 -230.043228)
		(end 420.140892 -229.888034)
		(width 0.18288)
		(layer "In11.Cu")
		(net "M_H_CPU0_SB_DQ<0>")
	)
	(segment
		(start 429.010064 -228.289866)
		(end 429.010064 -228.682296)
		(width 0.18288)
		(layer "In11.Cu")
		(net "M_H_CPU0_SB_DQ<0>")
	)
	(segment
		(start 435.754526 -227.49256)
		(end 435.752494 -227.490528)
		(width 0.18288)
		(layer "In11.Cu")
		(net "M_H_CPU0_SB_DQ<0>")
	)
	(segment
		(start 422.285668 -228.889052)
		(end 421.131492 -230.043228)
		(width 0.18288)
		(layer "In11.Cu")
		(net "M_H_CPU0_SB_DQ<0>")
	)
	(segment
		(start 384.297682 -239.528858)
		(end 384.287268 -239.534954)
		(width 0.088646)
		(layer "In11.Cu")
		(net "M_H_CPU0_SB_DQ<0>")
	)
	(segment
		(start 450.371972 -231.627426)
		(end 446.674494 -231.627426)
		(width 0.18288)
		(layer "In11.Cu")
		(net "M_H_CPU0_SB_DQ<0>")
	)
	(segment
		(start 401.961604 -231.742488)
		(end 394.221208 -239.482884)
		(width 0.18288)
		(layer "In11.Cu")
		(net "M_H_CPU0_SB_DQ<0>")
	)
	(segment
		(start 443.347094 -230.332026)
		(end 442.745622 -229.730554)
		(width 0.18288)
		(layer "In11.Cu")
		(net "M_H_CPU0_SB_DQ<0>")
	)
	(segment
		(start 436.454042 -229.856538)
		(end 436.454042 -227.683568)
		(width 0.18288)
		(layer "In11.Cu")
		(net "M_H_CPU0_SB_DQ<0>")
	)
	(segment
		(start 434.768752 -227.915216)
		(end 434.575712 -228.108256)
		(width 0.18288)
		(layer "In11.Cu")
		(net "M_H_CPU0_SB_DQ<0>")
	)
	(segment
		(start 412.486094 -229.976426)
		(end 411.825694 -229.976426)
		(width 0.18288)
		(layer "In11.Cu")
		(net "M_H_CPU0_SB_DQ<0>")
	)
	(segment
		(start 382.418082 -239.528858)
		(end 382.407668 -239.534954)
		(width 0.088646)
		(layer "In11.Cu")
		(net "M_H_CPU0_SB_DQ<0>")
	)
	(segment
		(start 428.113444 -228.096826)
		(end 426.254418 -228.096826)
		(width 0.18288)
		(layer "In11.Cu")
		(net "M_H_CPU0_SB_DQ<0>")
	)
	(segment
		(start 429.010064 -228.682296)
		(end 428.817024 -228.875336)
		(width 0.18288)
		(layer "In11.Cu")
		(net "M_H_CPU0_SB_DQ<0>")
	)
	(segment
		(start 413.02432 -230.514652)
		(end 412.486094 -229.976426)
		(width 0.18288)
		(layer "In11.Cu")
		(net "M_H_CPU0_SB_DQ<0>")
	)
	(segment
		(start 441.253626 -229.730554)
		(end 440.716924 -229.193852)
		(width 0.18288)
		(layer "In11.Cu")
		(net "M_H_CPU0_SB_DQ<0>")
	)
	(segment
		(start 432.658012 -227.915216)
		(end 432.658012 -227.683568)
		(width 0.18288)
		(layer "In11.Cu")
		(net "M_H_CPU0_SB_DQ<0>")
	)
	(segment
		(start 420.140892 -229.888034)
		(end 416.587686 -229.888034)
		(width 0.18288)
		(layer "In11.Cu")
		(net "M_H_CPU0_SB_DQ<0>")
	)
	(segment
		(start 388.502144 -239.443006)
		(end 386.922264 -239.443006)
		(width 0.088646)
		(layer "In11.Cu")
		(net "M_H_CPU0_SB_DQ<0>")
	)
	(segment
		(start 440.716924 -229.193852)
		(end 439.438796 -229.193852)
		(width 0.18288)
		(layer "In11.Cu")
		(net "M_H_CPU0_SB_DQ<0>")
	)
	(segment
		(start 380.538482 -239.528858)
		(end 380.528068 -239.534954)
		(width 0.088646)
		(layer "In11.Cu")
		(net "M_H_CPU0_SB_DQ<0>")
	)
	(segment
		(start 446.674494 -231.627426)
		(end 445.912494 -230.865426)
		(width 0.18288)
		(layer "In11.Cu")
		(net "M_H_CPU0_SB_DQ<0>")
	)
	(segment
		(start 437.350662 -227.490528)
		(end 437.157622 -227.683568)
		(width 0.18288)
		(layer "In11.Cu")
		(net "M_H_CPU0_SB_DQ<0>")
	)
	(segment
		(start 383.358136 -239.528858)
		(end 383.347722 -239.534954)
		(width 0.088646)
		(layer "In11.Cu")
		(net "M_H_CPU0_SB_DQ<0>")
	)
	(segment
		(start 434.258212 -228.108256)
		(end 434.065172 -227.915216)
		(width 0.18288)
		(layer "In11.Cu")
		(net "M_H_CPU0_SB_DQ<0>")
	)
	(segment
		(start 389.043164 -239.482884)
		(end 388.542022 -239.482884)
		(width 0.088646)
		(layer "In11.Cu")
		(net "M_H_CPU0_SB_DQ<0>")
	)
	(segment
		(start 437.157622 -227.683568)
		(end 437.157622 -229.856538)
		(width 0.18288)
		(layer "In11.Cu")
		(net "M_H_CPU0_SB_DQ<0>")
	)
	(segment
		(start 423.700194 -228.889052)
		(end 422.285668 -228.889052)
		(width 0.18288)
		(layer "In11.Cu")
		(net "M_H_CPU0_SB_DQ<0>")
	)
	(segment
		(start 428.817024 -228.875336)
		(end 428.499524 -228.875336)
		(width 0.18288)
		(layer "In11.Cu")
		(net "M_H_CPU0_SB_DQ<0>")
	)
	(segment
		(start 426.254418 -228.096826)
		(end 425.157138 -229.194106)
		(width 0.18288)
		(layer "In11.Cu")
		(net "M_H_CPU0_SB_DQ<0>")
	)
	(segment
		(start 433.361592 -227.915216)
		(end 433.168552 -228.108256)
		(width 0.18288)
		(layer "In11.Cu")
		(net "M_H_CPU0_SB_DQ<0>")
	)
	(segment
		(start 405.981408 -231.742488)
		(end 401.961604 -231.742488)
		(width 0.18288)
		(layer "In11.Cu")
		(net "M_H_CPU0_SB_DQ<0>")
	)
	(segment
		(start 394.221208 -239.482884)
		(end 389.043164 -239.482884)
		(width 0.18288)
		(layer "In11.Cu")
		(net "M_H_CPU0_SB_DQ<0>")
	)
	(segment
		(start 442.745622 -229.730554)
		(end 441.253626 -229.730554)
		(width 0.18288)
		(layer "In11.Cu")
		(net "M_H_CPU0_SB_DQ<0>")
	)
	(segment
		(start 428.499524 -228.875336)
		(end 428.306484 -228.682296)
		(width 0.18288)
		(layer "In11.Cu")
		(net "M_H_CPU0_SB_DQ<0>")
	)
	(segment
		(start 432.851052 -228.108256)
		(end 432.658012 -227.915216)
		(width 0.18288)
		(layer "In11.Cu")
		(net "M_H_CPU0_SB_DQ<0>")
	)
	(segment
		(start 373.959882 -239.528858)
		(end 373.949468 -239.534954)
		(width 0.088646)
		(layer "In11.Cu")
		(net "M_H_CPU0_SB_DQ<0>")
	)
	(segment
		(start 433.361592 -227.683568)
		(end 433.361592 -227.915216)
		(width 0.18288)
		(layer "In11.Cu")
		(net "M_H_CPU0_SB_DQ<0>")
	)
	(segment
		(start 436.261002 -227.490528)
		(end 435.875938 -227.490528)
		(width 0.18288)
		(layer "In11.Cu")
		(net "M_H_CPU0_SB_DQ<0>")
	)
	(segment
		(start 435.873906 -227.49256)
		(end 435.754526 -227.49256)
		(width 0.18288)
		(layer "In11.Cu")
		(net "M_H_CPU0_SB_DQ<0>")
	)
	(segment
		(start 411.825694 -229.976426)
		(end 410.911294 -230.890826)
		(width 0.18288)
		(layer "In11.Cu")
		(net "M_H_CPU0_SB_DQ<0>")
	)
	(segment
		(start 374.899682 -239.528858)
		(end 374.88495 -239.537494)
		(width 0.088646)
		(layer "In11.Cu")
		(net "M_H_CPU0_SB_DQ<0>")
	)
	(segment
		(start 424.005248 -229.194106)
		(end 423.700194 -228.889052)
		(width 0.18288)
		(layer "In11.Cu")
		(net "M_H_CPU0_SB_DQ<0>")
	)
	(segment
		(start 434.961792 -227.490528)
		(end 434.768752 -227.683568)
		(width 0.18288)
		(layer "In11.Cu")
		(net "M_H_CPU0_SB_DQ<0>")
	)
	(segment
		(start 415.961068 -230.514652)
		(end 413.02432 -230.514652)
		(width 0.18288)
		(layer "In11.Cu")
		(net "M_H_CPU0_SB_DQ<0>")
	)
	(segment
		(start 416.587686 -229.888034)
		(end 415.961068 -230.514652)
		(width 0.18288)
		(layer "In11.Cu")
		(net "M_H_CPU0_SB_DQ<0>")
	)
	(segment
		(start 436.647082 -230.049578)
		(end 436.454042 -229.856538)
		(width 0.18288)
		(layer "In11.Cu")
		(net "M_H_CPU0_SB_DQ<0>")
	)
	(segment
		(start 376.779282 -239.528858)
		(end 376.76455 -239.537494)
		(width 0.088646)
		(layer "In11.Cu")
		(net "M_H_CPU0_SB_DQ<0>")
	)
	(segment
		(start 409.023566 -230.890826)
		(end 408.90063 -230.76789)
		(width 0.18288)
		(layer "In11.Cu")
		(net "M_H_CPU0_SB_DQ<0>")
	)
	(segment
		(start 437.157622 -229.856538)
		(end 436.964582 -230.049578)
		(width 0.18288)
		(layer "In11.Cu")
		(net "M_H_CPU0_SB_DQ<0>")
	)
	(segment
		(start 432.464972 -227.490528)
		(end 431.558192 -227.490528)
		(width 0.18288)
		(layer "In11.Cu")
		(net "M_H_CPU0_SB_DQ<0>")
	)
	(segment
		(start 410.911294 -230.890826)
		(end 409.023566 -230.890826)
		(width 0.18288)
		(layer "In11.Cu")
		(net "M_H_CPU0_SB_DQ<0>")
	)
	(segment
		(start 432.658012 -227.683568)
		(end 432.464972 -227.490528)
		(width 0.18288)
		(layer "In11.Cu")
		(net "M_H_CPU0_SB_DQ<0>")
	)
	(segment
		(start 434.575712 -228.108256)
		(end 434.258212 -228.108256)
		(width 0.18288)
		(layer "In11.Cu")
		(net "M_H_CPU0_SB_DQ<0>")
	)
	(segment
		(start 435.752494 -227.490528)
		(end 434.961792 -227.490528)
		(width 0.18288)
		(layer "In11.Cu")
		(net "M_H_CPU0_SB_DQ<0>")
	)
	(segment
		(start 434.065172 -227.915216)
		(end 434.065172 -227.683568)
		(width 0.18288)
		(layer "In11.Cu")
		(net "M_H_CPU0_SB_DQ<0>")
	)
	(segment
		(start 433.554632 -227.490528)
		(end 433.361592 -227.683568)
		(width 0.18288)
		(layer "In11.Cu")
		(net "M_H_CPU0_SB_DQ<0>")
	)
	(segment
		(start 433.872132 -227.490528)
		(end 433.554632 -227.490528)
		(width 0.18288)
		(layer "In11.Cu")
		(net "M_H_CPU0_SB_DQ<0>")
	)
	(segment
		(start 435.875938 -227.490528)
		(end 435.873906 -227.49256)
		(width 0.18288)
		(layer "In11.Cu")
		(net "M_H_CPU0_SB_DQ<0>")
	)
	(segment
		(start 378.658882 -239.528858)
		(end 378.64415 -239.537494)
		(width 0.088646)
		(layer "In11.Cu")
		(net "M_H_CPU0_SB_DQ<0>")
	)
	(arc
		(start 380.912878 -239.528858)
		(mid 380.72568 -239.478715)
		(end 380.538482 -239.528858)
		(width 0.088646)
		(layer "In11.Cu")
		(net "M_H_CPU0_SB_DQ<0>")
	)
	(arc
		(start 383.347722 -239.534954)
		(mid 383.06929 -239.6048)
		(end 382.792478 -239.528858)
		(width 0.088646)
		(layer "In11.Cu")
		(net "M_H_CPU0_SB_DQ<0>")
	)
	(arc
		(start 379.973332 -239.528858)
		(mid 379.786134 -239.478715)
		(end 379.598936 -239.528858)
		(width 0.088646)
		(layer "In11.Cu")
		(net "M_H_CPU0_SB_DQ<0>")
	)
	(arc
		(start 385.22275 -239.537494)
		(mid 384.946275 -239.604814)
		(end 384.672078 -239.528858)
		(width 0.088646)
		(layer "In11.Cu")
		(net "M_H_CPU0_SB_DQ<0>")
	)
	(arc
		(start 375.274078 -239.528858)
		(mid 375.08688 -239.478715)
		(end 374.899682 -239.528858)
		(width 0.088646)
		(layer "In11.Cu")
		(net "M_H_CPU0_SB_DQ<0>")
	)
	(arc
		(start 383.732532 -239.528858)
		(mid 383.545334 -239.478715)
		(end 383.358136 -239.528858)
		(width 0.088646)
		(layer "In11.Cu")
		(net "M_H_CPU0_SB_DQ<0>")
	)
	(arc
		(start 379.588522 -239.534954)
		(mid 379.31009 -239.6048)
		(end 379.033278 -239.528858)
		(width 0.088646)
		(layer "In11.Cu")
		(net "M_H_CPU0_SB_DQ<0>")
	)
	(arc
		(start 374.88495 -239.537494)
		(mid 374.608475 -239.604814)
		(end 374.334278 -239.528858)
		(width 0.088646)
		(layer "In11.Cu")
		(net "M_H_CPU0_SB_DQ<0>")
	)
	(arc
		(start 385.895342 -239.605058)
		(mid 385.748577 -239.585678)
		(end 385.611878 -239.528858)
		(width 0.088646)
		(layer "In11.Cu")
		(net "M_H_CPU0_SB_DQ<0>")
	)
	(arc
		(start 377.719082 -239.528858)
		(mid 377.43638 -239.604634)
		(end 377.153678 -239.528858)
		(width 0.088646)
		(layer "In11.Cu")
		(net "M_H_CPU0_SB_DQ<0>")
	)
	(arc
		(start 376.213878 -239.528858)
		(mid 376.02668 -239.478715)
		(end 375.839482 -239.528858)
		(width 0.088646)
		(layer "In11.Cu")
		(net "M_H_CPU0_SB_DQ<0>")
	)
	(arc
		(start 384.672078 -239.528858)
		(mid 384.48488 -239.478715)
		(end 384.297682 -239.528858)
		(width 0.088646)
		(layer "In11.Cu")
		(net "M_H_CPU0_SB_DQ<0>")
	)
	(arc
		(start 385.611878 -239.528858)
		(mid 385.42468 -239.478715)
		(end 385.237482 -239.528858)
		(width 0.088646)
		(layer "In11.Cu")
		(net "M_H_CPU0_SB_DQ<0>")
	)
	(arc
		(start 382.407668 -239.534954)
		(mid 382.12949 -239.604677)
		(end 381.852932 -239.528858)
		(width 0.088646)
		(layer "In11.Cu")
		(net "M_H_CPU0_SB_DQ<0>")
	)
	(arc
		(start 373.394732 -239.528858)
		(mid 373.253962 -239.470519)
		(end 373.102886 -239.450626)
		(width 0.088646)
		(layer "In11.Cu")
		(net "M_H_CPU0_SB_DQ<0>")
	)
	(arc
		(start 378.64415 -239.537494)
		(mid 378.367675 -239.604814)
		(end 378.093478 -239.528858)
		(width 0.088646)
		(layer "In11.Cu")
		(net "M_H_CPU0_SB_DQ<0>")
	)
	(arc
		(start 377.153678 -239.528858)
		(mid 376.96648 -239.478715)
		(end 376.779282 -239.528858)
		(width 0.088646)
		(layer "In11.Cu")
		(net "M_H_CPU0_SB_DQ<0>")
	)
	(arc
		(start 376.76455 -239.537494)
		(mid 376.488075 -239.604814)
		(end 376.213878 -239.528858)
		(width 0.088646)
		(layer "In11.Cu")
		(net "M_H_CPU0_SB_DQ<0>")
	)
	(arc
		(start 381.852932 -239.528858)
		(mid 381.665734 -239.478715)
		(end 381.478536 -239.528858)
		(width 0.088646)
		(layer "In11.Cu")
		(net "M_H_CPU0_SB_DQ<0>")
	)
	(arc
		(start 382.792478 -239.528858)
		(mid 382.60528 -239.478715)
		(end 382.418082 -239.528858)
		(width 0.088646)
		(layer "In11.Cu")
		(net "M_H_CPU0_SB_DQ<0>")
	)
	(arc
		(start 374.334278 -239.528858)
		(mid 374.14708 -239.478715)
		(end 373.959882 -239.528858)
		(width 0.088646)
		(layer "In11.Cu")
		(net "M_H_CPU0_SB_DQ<0>")
	)
	(arc
		(start 384.287268 -239.534954)
		(mid 384.00909 -239.604677)
		(end 383.732532 -239.528858)
		(width 0.088646)
		(layer "In11.Cu")
		(net "M_H_CPU0_SB_DQ<0>")
	)
	(arc
		(start 380.528068 -239.534954)
		(mid 380.24989 -239.604677)
		(end 379.973332 -239.528858)
		(width 0.088646)
		(layer "In11.Cu")
		(net "M_H_CPU0_SB_DQ<0>")
	)
	(arc
		(start 381.468122 -239.534954)
		(mid 381.18969 -239.6048)
		(end 380.912878 -239.528858)
		(width 0.088646)
		(layer "In11.Cu")
		(net "M_H_CPU0_SB_DQ<0>")
	)
	(arc
		(start 375.82475 -239.537494)
		(mid 375.548275 -239.604814)
		(end 375.274078 -239.528858)
		(width 0.088646)
		(layer "In11.Cu")
		(net "M_H_CPU0_SB_DQ<0>")
	)
	(arc
		(start 373.949468 -239.534954)
		(mid 373.67129 -239.604677)
		(end 373.394732 -239.528858)
		(width 0.088646)
		(layer "In11.Cu")
		(net "M_H_CPU0_SB_DQ<0>")
	)
	(arc
		(start 372.506494 -239.450626)
		(mid 372.231705 -239.395967)
		(end 371.998748 -239.240314)
		(width 0.088646)
		(layer "In11.Cu")
		(net "M_H_CPU0_SB_DQ<0>")
	)
	(arc
		(start 378.093478 -239.528858)
		(mid 377.90628 -239.478715)
		(end 377.719082 -239.528858)
		(width 0.088646)
		(layer "In11.Cu")
		(net "M_H_CPU0_SB_DQ<0>")
	)
	(arc
		(start 379.033278 -239.528858)
		(mid 378.84608 -239.478715)
		(end 378.658882 -239.528858)
		(width 0.088646)
		(layer "In11.Cu")
		(net "M_H_CPU0_SB_DQ<0>")
	)
	(segment
		(start 376.49658 -244.458744)
		(end 376.496834 -244.45849)
		(width 0.20066)
		(layer "F.Cu")
		(net "M_H_CPU0_SB_CS_N<3>")
	)
	(segment
		(start 376.496834 -244.45849)
		(end 376.496834 -243.922804)
		(width 0.20066)
		(layer "F.Cu")
		(net "M_H_CPU0_SB_CS_N<3>")
	)
	(segment
		(start 455.011282 -244.916706)
		(end 456.116182 -244.916706)
		(width 0.20066)
		(layer "F.Cu")
		(net "M_H_CPU0_SB_CS_N<3>")
	)
	(segment
		(start 376.504962 -243.930932)
		(end 376.496834 -243.922804)
		(width 0.088646)
		(layer "In6.Cu")
		(net "M_H_CPU0_SB_CS_N<3>")
	)
	(segment
		(start 404.529036 -240.796572)
		(end 401.602194 -240.796572)
		(width 0.18288)
		(layer "In6.Cu")
		(net "M_H_CPU0_SB_CS_N<3>")
	)
	(segment
		(start 440.761374 -241.942366)
		(end 439.333894 -241.942366)
		(width 0.18288)
		(layer "In6.Cu")
		(net "M_H_CPU0_SB_CS_N<3>")
	)
	(segment
		(start 452.92645 -242.831874)
		(end 452.503794 -242.831874)
		(width 0.18288)
		(layer "In6.Cu")
		(net "M_H_CPU0_SB_CS_N<3>")
	)
	(segment
		(start 450.189854 -241.942366)
		(end 449.935854 -242.196366)
		(width 0.18288)
		(layer "In6.Cu")
		(net "M_H_CPU0_SB_CS_N<3>")
	)
	(segment
		(start 425.881038 -241.092482)
		(end 424.175682 -241.092482)
		(width 0.18288)
		(layer "In6.Cu")
		(net "M_H_CPU0_SB_CS_N<3>")
	)
	(segment
		(start 386.834634 -244.64137)
		(end 385.342638 -244.64137)
		(width 0.18288)
		(layer "In6.Cu")
		(net "M_H_CPU0_SB_CS_N<3>")
	)
	(segment
		(start 427.428152 -240.478564)
		(end 426.494956 -240.478564)
		(width 0.18288)
		(layer "In6.Cu")
		(net "M_H_CPU0_SB_CS_N<3>")
	)
	(segment
		(start 408.39136 -239.912652)
		(end 405.412956 -239.912652)
		(width 0.18288)
		(layer "In6.Cu")
		(net "M_H_CPU0_SB_CS_N<3>")
	)
	(segment
		(start 441.655454 -241.048286)
		(end 440.761374 -241.942366)
		(width 0.18288)
		(layer "In6.Cu")
		(net "M_H_CPU0_SB_CS_N<3>")
	)
	(segment
		(start 412.86303 -241.257074)
		(end 412.16199 -241.958114)
		(width 0.18288)
		(layer "In6.Cu")
		(net "M_H_CPU0_SB_CS_N<3>")
	)
	(segment
		(start 442.818774 -241.208306)
		(end 442.658754 -241.048286)
		(width 0.18288)
		(layer "In6.Cu")
		(net "M_H_CPU0_SB_CS_N<3>")
	)
	(segment
		(start 424.175682 -241.092482)
		(end 423.325798 -241.942366)
		(width 0.18288)
		(layer "In6.Cu")
		(net "M_H_CPU0_SB_CS_N<3>")
	)
	(segment
		(start 452.503794 -242.831874)
		(end 451.614286 -241.942366)
		(width 0.18288)
		(layer "In6.Cu")
		(net "M_H_CPU0_SB_CS_N<3>")
	)
	(segment
		(start 428.367698 -241.41811)
		(end 427.428152 -240.478564)
		(width 0.18288)
		(layer "In6.Cu")
		(net "M_H_CPU0_SB_CS_N<3>")
	)
	(segment
		(start 401.602194 -240.796572)
		(end 398.35455 -244.044216)
		(width 0.18288)
		(layer "In6.Cu")
		(net "M_H_CPU0_SB_CS_N<3>")
	)
	(segment
		(start 384.900678 -244.352826)
		(end 384.884676 -244.336824)
		(width 0.088646)
		(layer "In6.Cu")
		(net "M_H_CPU0_SB_CS_N<3>")
	)
	(segment
		(start 430.901856 -241.092482)
		(end 430.576228 -241.41811)
		(width 0.18288)
		(layer "In6.Cu")
		(net "M_H_CPU0_SB_CS_N<3>")
	)
	(segment
		(start 408.94 -240.461292)
		(end 408.39136 -239.912652)
		(width 0.18288)
		(layer "In6.Cu")
		(net "M_H_CPU0_SB_CS_N<3>")
	)
	(segment
		(start 405.412956 -239.912652)
		(end 404.529036 -240.796572)
		(width 0.18288)
		(layer "In6.Cu")
		(net "M_H_CPU0_SB_CS_N<3>")
	)
	(segment
		(start 415.900362 -241.257074)
		(end 412.86303 -241.257074)
		(width 0.18288)
		(layer "In6.Cu")
		(net "M_H_CPU0_SB_CS_N<3>")
	)
	(segment
		(start 412.16199 -241.958114)
		(end 411.680914 -241.958114)
		(width 0.18288)
		(layer "In6.Cu")
		(net "M_H_CPU0_SB_CS_N<3>")
	)
	(segment
		(start 449.935854 -242.196366)
		(end 447.967862 -242.196366)
		(width 0.18288)
		(layer "In6.Cu")
		(net "M_H_CPU0_SB_CS_N<3>")
	)
	(segment
		(start 398.35455 -244.044216)
		(end 388.756906 -244.044216)
		(width 0.18288)
		(layer "In6.Cu")
		(net "M_H_CPU0_SB_CS_N<3>")
	)
	(segment
		(start 442.658754 -241.048286)
		(end 441.655454 -241.048286)
		(width 0.18288)
		(layer "In6.Cu")
		(net "M_H_CPU0_SB_CS_N<3>")
	)
	(segment
		(start 388.756906 -244.044216)
		(end 387.905498 -244.895624)
		(width 0.18288)
		(layer "In6.Cu")
		(net "M_H_CPU0_SB_CS_N<3>")
	)
	(segment
		(start 410.184092 -240.461292)
		(end 408.94 -240.461292)
		(width 0.18288)
		(layer "In6.Cu")
		(net "M_H_CPU0_SB_CS_N<3>")
	)
	(segment
		(start 446.199514 -241.942366)
		(end 445.465454 -241.208306)
		(width 0.18288)
		(layer "In6.Cu")
		(net "M_H_CPU0_SB_CS_N<3>")
	)
	(segment
		(start 447.967862 -242.196366)
		(end 447.713862 -241.942366)
		(width 0.18288)
		(layer "In6.Cu")
		(net "M_H_CPU0_SB_CS_N<3>")
	)
	(segment
		(start 411.680914 -241.958114)
		(end 410.184092 -240.461292)
		(width 0.18288)
		(layer "In6.Cu")
		(net "M_H_CPU0_SB_CS_N<3>")
	)
	(segment
		(start 378.578364 -244.238526)
		(end 378.563632 -244.247162)
		(width 0.088646)
		(layer "In6.Cu")
		(net "M_H_CPU0_SB_CS_N<3>")
	)
	(segment
		(start 438.48401 -241.092482)
		(end 430.901856 -241.092482)
		(width 0.18288)
		(layer "In6.Cu")
		(net "M_H_CPU0_SB_CS_N<3>")
	)
	(segment
		(start 382.337564 -244.238526)
		(end 382.322832 -244.247162)
		(width 0.088646)
		(layer "In6.Cu")
		(net "M_H_CPU0_SB_CS_N<3>")
	)
	(segment
		(start 384.217164 -244.238526)
		(end 384.202432 -244.247162)
		(width 0.088646)
		(layer "In6.Cu")
		(net "M_H_CPU0_SB_CS_N<3>")
	)
	(segment
		(start 455.011282 -244.916706)
		(end 452.92645 -242.831874)
		(width 0.18288)
		(layer "In6.Cu")
		(net "M_H_CPU0_SB_CS_N<3>")
	)
	(segment
		(start 380.457964 -244.238526)
		(end 380.443232 -244.247162)
		(width 0.088646)
		(layer "In6.Cu")
		(net "M_H_CPU0_SB_CS_N<3>")
	)
	(segment
		(start 439.333894 -241.942366)
		(end 438.48401 -241.092482)
		(width 0.18288)
		(layer "In6.Cu")
		(net "M_H_CPU0_SB_CS_N<3>")
	)
	(segment
		(start 385.25069 -244.549422)
		(end 385.054094 -244.352826)
		(width 0.088646)
		(layer "In6.Cu")
		(net "M_H_CPU0_SB_CS_N<3>")
	)
	(segment
		(start 385.054094 -244.352826)
		(end 384.900678 -244.352826)
		(width 0.088646)
		(layer "In6.Cu")
		(net "M_H_CPU0_SB_CS_N<3>")
	)
	(segment
		(start 385.342638 -244.64137)
		(end 385.25069 -244.549422)
		(width 0.18288)
		(layer "In6.Cu")
		(net "M_H_CPU0_SB_CS_N<3>")
	)
	(segment
		(start 387.448806 -244.895624)
		(end 386.834634 -244.64137)
		(width 0.18288)
		(layer "In6.Cu")
		(net "M_H_CPU0_SB_CS_N<3>")
	)
	(segment
		(start 426.494956 -240.478564)
		(end 425.881038 -241.092482)
		(width 0.18288)
		(layer "In6.Cu")
		(net "M_H_CPU0_SB_CS_N<3>")
	)
	(segment
		(start 423.325798 -241.942366)
		(end 416.585654 -241.942366)
		(width 0.18288)
		(layer "In6.Cu")
		(net "M_H_CPU0_SB_CS_N<3>")
	)
	(segment
		(start 451.614286 -241.942366)
		(end 450.189854 -241.942366)
		(width 0.18288)
		(layer "In6.Cu")
		(net "M_H_CPU0_SB_CS_N<3>")
	)
	(segment
		(start 387.905498 -244.895624)
		(end 387.448806 -244.895624)
		(width 0.18288)
		(layer "In6.Cu")
		(net "M_H_CPU0_SB_CS_N<3>")
	)
	(segment
		(start 445.465454 -241.208306)
		(end 442.818774 -241.208306)
		(width 0.18288)
		(layer "In6.Cu")
		(net "M_H_CPU0_SB_CS_N<3>")
	)
	(segment
		(start 447.713862 -241.942366)
		(end 446.199514 -241.942366)
		(width 0.18288)
		(layer "In6.Cu")
		(net "M_H_CPU0_SB_CS_N<3>")
	)
	(segment
		(start 416.585654 -241.942366)
		(end 415.900362 -241.257074)
		(width 0.18288)
		(layer "In6.Cu")
		(net "M_H_CPU0_SB_CS_N<3>")
	)
	(segment
		(start 377.633992 -244.241066)
		(end 377.623578 -244.247162)
		(width 0.088646)
		(layer "In6.Cu")
		(net "M_H_CPU0_SB_CS_N<3>")
	)
	(segment
		(start 430.576228 -241.41811)
		(end 428.367698 -241.41811)
		(width 0.18288)
		(layer "In6.Cu")
		(net "M_H_CPU0_SB_CS_N<3>")
	)
	(arc
		(start 378.189236 -244.247162)
		(mid 377.912423 -244.171292)
		(end 377.633992 -244.241066)
		(width 0.088646)
		(layer "In6.Cu")
		(net "M_H_CPU0_SB_CS_N<3>")
	)
	(arc
		(start 382.322832 -244.247162)
		(mid 382.135634 -244.297305)
		(end 381.948436 -244.247162)
		(width 0.088646)
		(layer "In6.Cu")
		(net "M_H_CPU0_SB_CS_N<3>")
	)
	(arc
		(start 381.383032 -244.247162)
		(mid 381.195834 -244.297305)
		(end 381.008636 -244.247162)
		(width 0.088646)
		(layer "In6.Cu")
		(net "M_H_CPU0_SB_CS_N<3>")
	)
	(arc
		(start 381.948436 -244.247162)
		(mid 381.665734 -244.171386)
		(end 381.383032 -244.247162)
		(width 0.088646)
		(layer "In6.Cu")
		(net "M_H_CPU0_SB_CS_N<3>")
	)
	(arc
		(start 384.884676 -244.336824)
		(mid 384.567196 -244.177247)
		(end 384.217164 -244.238526)
		(width 0.088646)
		(layer "In6.Cu")
		(net "M_H_CPU0_SB_CS_N<3>")
	)
	(arc
		(start 383.828036 -244.247162)
		(mid 383.545334 -244.171386)
		(end 383.262632 -244.247162)
		(width 0.088646)
		(layer "In6.Cu")
		(net "M_H_CPU0_SB_CS_N<3>")
	)
	(arc
		(start 379.129036 -244.247162)
		(mid 378.854837 -244.171327)
		(end 378.578364 -244.238526)
		(width 0.088646)
		(layer "In6.Cu")
		(net "M_H_CPU0_SB_CS_N<3>")
	)
	(arc
		(start 377.020582 -244.17401)
		(mid 376.74162 -244.09734)
		(end 376.504962 -243.930932)
		(width 0.088646)
		(layer "In6.Cu")
		(net "M_H_CPU0_SB_CS_N<3>")
	)
	(arc
		(start 383.262632 -244.247162)
		(mid 383.075434 -244.297305)
		(end 382.888236 -244.247162)
		(width 0.088646)
		(layer "In6.Cu")
		(net "M_H_CPU0_SB_CS_N<3>")
	)
	(arc
		(start 382.888236 -244.247162)
		(mid 382.614037 -244.171327)
		(end 382.337564 -244.238526)
		(width 0.088646)
		(layer "In6.Cu")
		(net "M_H_CPU0_SB_CS_N<3>")
	)
	(arc
		(start 380.068836 -244.247162)
		(mid 379.786134 -244.171386)
		(end 379.503432 -244.247162)
		(width 0.088646)
		(layer "In6.Cu")
		(net "M_H_CPU0_SB_CS_N<3>")
	)
	(arc
		(start 381.008636 -244.247162)
		(mid 380.734437 -244.171327)
		(end 380.457964 -244.238526)
		(width 0.088646)
		(layer "In6.Cu")
		(net "M_H_CPU0_SB_CS_N<3>")
	)
	(arc
		(start 379.503432 -244.247162)
		(mid 379.316234 -244.297305)
		(end 379.129036 -244.247162)
		(width 0.088646)
		(layer "In6.Cu")
		(net "M_H_CPU0_SB_CS_N<3>")
	)
	(arc
		(start 378.563632 -244.247162)
		(mid 378.376434 -244.297305)
		(end 378.189236 -244.247162)
		(width 0.088646)
		(layer "In6.Cu")
		(net "M_H_CPU0_SB_CS_N<3>")
	)
	(arc
		(start 384.202432 -244.247162)
		(mid 384.015234 -244.297305)
		(end 383.828036 -244.247162)
		(width 0.088646)
		(layer "In6.Cu")
		(net "M_H_CPU0_SB_CS_N<3>")
	)
	(arc
		(start 380.443232 -244.247162)
		(mid 380.256034 -244.297305)
		(end 380.068836 -244.247162)
		(width 0.088646)
		(layer "In6.Cu")
		(net "M_H_CPU0_SB_CS_N<3>")
	)
	(arc
		(start 377.623578 -244.247162)
		(mid 377.43638 -244.297305)
		(end 377.249182 -244.247162)
		(width 0.088646)
		(layer "In6.Cu")
		(net "M_H_CPU0_SB_CS_N<3>")
	)
	(arc
		(start 377.249182 -244.247162)
		(mid 377.138813 -244.198298)
		(end 377.020582 -244.17401)
		(width 0.088646)
		(layer "In6.Cu")
		(net "M_H_CPU0_SB_CS_N<3>")
	)
	(segment
		(start 374.61698 -244.458744)
		(end 374.617234 -244.45849)
		(width 0.20066)
		(layer "F.Cu")
		(net "M_H_CPU0_SB_CS_N<2>")
	)
	(segment
		(start 452.016114 -245.76659)
		(end 450.911214 -245.76659)
		(width 0.20066)
		(layer "F.Cu")
		(net "M_H_CPU0_SB_CS_N<2>")
	)
	(segment
		(start 374.617234 -244.45849)
		(end 374.617234 -243.922804)
		(width 0.20066)
		(layer "F.Cu")
		(net "M_H_CPU0_SB_CS_N<2>")
	)
	(segment
		(start 379.598936 -244.412262)
		(end 379.588522 -244.418358)
		(width 0.088646)
		(layer "In6.Cu")
		(net "M_H_CPU0_SB_CS_N<2>")
	)
	(segment
		(start 384.2893 -244.417088)
		(end 384.287268 -244.418358)
		(width 0.088646)
		(layer "In6.Cu")
		(net "M_H_CPU0_SB_CS_N<2>")
	)
	(segment
		(start 384.957574 -245.218458)
		(end 384.859784 -245.120668)
		(width 0.088646)
		(layer "In6.Cu")
		(net "M_H_CPU0_SB_CS_N<2>")
	)
	(segment
		(start 409.975812 -241.046)
		(end 409.12542 -241.046)
		(width 0.18288)
		(layer "In6.Cu")
		(net "M_H_CPU0_SB_CS_N<2>")
	)
	(segment
		(start 401.656042 -241.488468)
		(end 398.602454 -244.542056)
		(width 0.18288)
		(layer "In6.Cu")
		(net "M_H_CPU0_SB_CS_N<2>")
	)
	(segment
		(start 387.692138 -245.54688)
		(end 387.251448 -245.729252)
		(width 0.18288)
		(layer "In6.Cu")
		(net "M_H_CPU0_SB_CS_N<2>")
	)
	(segment
		(start 409.12542 -241.046)
		(end 408.682952 -241.488468)
		(width 0.18288)
		(layer "In6.Cu")
		(net "M_H_CPU0_SB_CS_N<2>")
	)
	(segment
		(start 428.140114 -241.942366)
		(end 427.207934 -241.010186)
		(width 0.18288)
		(layer "In6.Cu")
		(net "M_H_CPU0_SB_CS_N<2>")
	)
	(segment
		(start 451.894194 -244.75821)
		(end 451.894194 -243.31168)
		(width 0.18288)
		(layer "In6.Cu")
		(net "M_H_CPU0_SB_CS_N<2>")
	)
	(segment
		(start 441.50407 -241.939318)
		(end 440.650884 -242.792504)
		(width 0.18288)
		(layer "In6.Cu")
		(net "M_H_CPU0_SB_CS_N<2>")
	)
	(segment
		(start 440.650884 -242.792504)
		(end 439.363612 -242.792504)
		(width 0.18288)
		(layer "In6.Cu")
		(net "M_H_CPU0_SB_CS_N<2>")
	)
	(segment
		(start 386.194808 -245.729252)
		(end 385.684014 -245.218458)
		(width 0.18288)
		(layer "In6.Cu")
		(net "M_H_CPU0_SB_CS_N<2>")
	)
	(segment
		(start 426.715174 -241.010186)
		(end 425.782994 -241.942366)
		(width 0.18288)
		(layer "In6.Cu")
		(net "M_H_CPU0_SB_CS_N<2>")
	)
	(segment
		(start 451.375018 -242.792504)
		(end 445.243712 -242.792504)
		(width 0.18288)
		(layer "In6.Cu")
		(net "M_H_CPU0_SB_CS_N<2>")
	)
	(segment
		(start 415.658554 -241.840766)
		(end 413.039814 -241.840766)
		(width 0.18288)
		(layer "In6.Cu")
		(net "M_H_CPU0_SB_CS_N<2>")
	)
	(segment
		(start 387.251448 -245.729252)
		(end 386.194808 -245.729252)
		(width 0.18288)
		(layer "In6.Cu")
		(net "M_H_CPU0_SB_CS_N<2>")
	)
	(segment
		(start 450.911214 -245.76659)
		(end 450.911214 -245.74119)
		(width 0.18288)
		(layer "In6.Cu")
		(net "M_H_CPU0_SB_CS_N<2>")
	)
	(segment
		(start 385.684014 -245.218458)
		(end 385.111498 -245.218458)
		(width 0.18288)
		(layer "In6.Cu")
		(net "M_H_CPU0_SB_CS_N<2>")
	)
	(segment
		(start 385.111498 -245.218458)
		(end 384.957574 -245.218458)
		(width 0.088646)
		(layer "In6.Cu")
		(net "M_H_CPU0_SB_CS_N<2>")
	)
	(segment
		(start 412.344108 -242.536472)
		(end 411.466284 -242.536472)
		(width 0.18288)
		(layer "In6.Cu")
		(net "M_H_CPU0_SB_CS_N<2>")
	)
	(segment
		(start 389.473948 -244.542056)
		(end 388.469124 -245.54688)
		(width 0.18288)
		(layer "In6.Cu")
		(net "M_H_CPU0_SB_CS_N<2>")
	)
	(segment
		(start 425.782994 -241.942366)
		(end 424.404282 -241.942366)
		(width 0.18288)
		(layer "In6.Cu")
		(net "M_H_CPU0_SB_CS_N<2>")
	)
	(segment
		(start 413.039814 -241.840766)
		(end 412.344108 -242.536472)
		(width 0.18288)
		(layer "In6.Cu")
		(net "M_H_CPU0_SB_CS_N<2>")
	)
	(segment
		(start 388.469124 -245.54688)
		(end 387.692138 -245.54688)
		(width 0.18288)
		(layer "In6.Cu")
		(net "M_H_CPU0_SB_CS_N<2>")
	)
	(segment
		(start 383.358136 -244.412262)
		(end 383.347722 -244.418358)
		(width 0.088646)
		(layer "In6.Cu")
		(net "M_H_CPU0_SB_CS_N<2>")
	)
	(segment
		(start 445.243712 -242.792504)
		(end 444.390526 -241.939318)
		(width 0.18288)
		(layer "In6.Cu")
		(net "M_H_CPU0_SB_CS_N<2>")
	)
	(segment
		(start 451.894194 -243.31168)
		(end 451.375018 -242.792504)
		(width 0.18288)
		(layer "In6.Cu")
		(net "M_H_CPU0_SB_CS_N<2>")
	)
	(segment
		(start 376.779282 -244.412262)
		(end 376.76455 -244.420898)
		(width 0.088646)
		(layer "In6.Cu")
		(net "M_H_CPU0_SB_CS_N<2>")
	)
	(segment
		(start 375.274332 -244.412262)
		(end 375.1961 -244.36705)
		(width 0.088646)
		(layer "In6.Cu")
		(net "M_H_CPU0_SB_CS_N<2>")
	)
	(segment
		(start 416.610038 -242.79225)
		(end 415.658554 -241.840766)
		(width 0.18288)
		(layer "In6.Cu")
		(net "M_H_CPU0_SB_CS_N<2>")
	)
	(segment
		(start 408.682952 -241.488468)
		(end 401.656042 -241.488468)
		(width 0.18288)
		(layer "In6.Cu")
		(net "M_H_CPU0_SB_CS_N<2>")
	)
	(segment
		(start 423.554398 -242.79225)
		(end 416.610038 -242.79225)
		(width 0.18288)
		(layer "In6.Cu")
		(net "M_H_CPU0_SB_CS_N<2>")
	)
	(segment
		(start 398.602454 -244.542056)
		(end 389.473948 -244.542056)
		(width 0.18288)
		(layer "In6.Cu")
		(net "M_H_CPU0_SB_CS_N<2>")
	)
	(segment
		(start 439.363612 -242.792504)
		(end 438.513474 -241.942366)
		(width 0.18288)
		(layer "In6.Cu")
		(net "M_H_CPU0_SB_CS_N<2>")
	)
	(segment
		(start 424.404282 -241.942366)
		(end 423.554398 -242.79225)
		(width 0.18288)
		(layer "In6.Cu")
		(net "M_H_CPU0_SB_CS_N<2>")
	)
	(segment
		(start 381.478536 -244.412262)
		(end 381.468122 -244.418358)
		(width 0.088646)
		(layer "In6.Cu")
		(net "M_H_CPU0_SB_CS_N<2>")
	)
	(segment
		(start 444.390526 -241.939318)
		(end 441.50407 -241.939318)
		(width 0.18288)
		(layer "In6.Cu")
		(net "M_H_CPU0_SB_CS_N<2>")
	)
	(segment
		(start 450.911214 -245.74119)
		(end 451.894194 -244.75821)
		(width 0.18288)
		(layer "In6.Cu")
		(net "M_H_CPU0_SB_CS_N<2>")
	)
	(segment
		(start 375.839482 -244.412262)
		(end 375.829068 -244.418358)
		(width 0.088646)
		(layer "In6.Cu")
		(net "M_H_CPU0_SB_CS_N<2>")
	)
	(segment
		(start 384.859784 -245.120668)
		(end 384.859784 -244.73662)
		(width 0.088646)
		(layer "In6.Cu")
		(net "M_H_CPU0_SB_CS_N<2>")
	)
	(segment
		(start 384.297936 -244.412262)
		(end 384.2893 -244.417088)
		(width 0.088646)
		(layer "In6.Cu")
		(net "M_H_CPU0_SB_CS_N<2>")
	)
	(segment
		(start 384.672586 -244.412516)
		(end 384.672332 -244.412262)
		(width 0.088646)
		(layer "In6.Cu")
		(net "M_H_CPU0_SB_CS_N<2>")
	)
	(segment
		(start 438.513474 -241.942366)
		(end 428.140114 -241.942366)
		(width 0.18288)
		(layer "In6.Cu")
		(net "M_H_CPU0_SB_CS_N<2>")
	)
	(segment
		(start 427.207934 -241.010186)
		(end 426.715174 -241.010186)
		(width 0.18288)
		(layer "In6.Cu")
		(net "M_H_CPU0_SB_CS_N<2>")
	)
	(segment
		(start 380.538482 -244.412262)
		(end 380.528068 -244.418358)
		(width 0.088646)
		(layer "In6.Cu")
		(net "M_H_CPU0_SB_CS_N<2>")
	)
	(segment
		(start 411.466284 -242.536472)
		(end 409.975812 -241.046)
		(width 0.18288)
		(layer "In6.Cu")
		(net "M_H_CPU0_SB_CS_N<2>")
	)
	(segment
		(start 382.418082 -244.412262)
		(end 382.407668 -244.418358)
		(width 0.088646)
		(layer "In6.Cu")
		(net "M_H_CPU0_SB_CS_N<2>")
	)
	(segment
		(start 378.658882 -244.412262)
		(end 378.64415 -244.420898)
		(width 0.088646)
		(layer "In6.Cu")
		(net "M_H_CPU0_SB_CS_N<2>")
	)
	(arc
		(start 384.859784 -244.73662)
		(mid 384.80962 -244.549482)
		(end 384.672586 -244.412516)
		(width 0.088646)
		(layer "In6.Cu")
		(net "M_H_CPU0_SB_CS_N<2>")
	)
	(arc
		(start 380.912878 -244.412262)
		(mid 380.72568 -244.362119)
		(end 380.538482 -244.412262)
		(width 0.088646)
		(layer "In6.Cu")
		(net "M_H_CPU0_SB_CS_N<2>")
	)
	(arc
		(start 378.093478 -244.412262)
		(mid 377.90628 -244.362119)
		(end 377.719082 -244.412262)
		(width 0.088646)
		(layer "In6.Cu")
		(net "M_H_CPU0_SB_CS_N<2>")
	)
	(arc
		(start 384.287268 -244.418358)
		(mid 384.00909 -244.488081)
		(end 383.732532 -244.412262)
		(width 0.088646)
		(layer "In6.Cu")
		(net "M_H_CPU0_SB_CS_N<2>")
	)
	(arc
		(start 379.033278 -244.412262)
		(mid 378.84608 -244.362119)
		(end 378.658882 -244.412262)
		(width 0.088646)
		(layer "In6.Cu")
		(net "M_H_CPU0_SB_CS_N<2>")
	)
	(arc
		(start 383.732532 -244.412262)
		(mid 383.545334 -244.362119)
		(end 383.358136 -244.412262)
		(width 0.088646)
		(layer "In6.Cu")
		(net "M_H_CPU0_SB_CS_N<2>")
	)
	(arc
		(start 375.1961 -244.36705)
		(mid 374.892112 -244.163892)
		(end 374.617234 -243.922804)
		(width 0.088646)
		(layer "In6.Cu")
		(net "M_H_CPU0_SB_CS_N<2>")
	)
	(arc
		(start 376.213878 -244.412262)
		(mid 376.02668 -244.362119)
		(end 375.839482 -244.412262)
		(width 0.088646)
		(layer "In6.Cu")
		(net "M_H_CPU0_SB_CS_N<2>")
	)
	(arc
		(start 381.468122 -244.418358)
		(mid 381.18969 -244.488204)
		(end 380.912878 -244.412262)
		(width 0.088646)
		(layer "In6.Cu")
		(net "M_H_CPU0_SB_CS_N<2>")
	)
	(arc
		(start 375.829068 -244.418358)
		(mid 375.55089 -244.488081)
		(end 375.274332 -244.412262)
		(width 0.088646)
		(layer "In6.Cu")
		(net "M_H_CPU0_SB_CS_N<2>")
	)
	(arc
		(start 382.792478 -244.412262)
		(mid 382.60528 -244.362119)
		(end 382.418082 -244.412262)
		(width 0.088646)
		(layer "In6.Cu")
		(net "M_H_CPU0_SB_CS_N<2>")
	)
	(arc
		(start 383.347722 -244.418358)
		(mid 383.06929 -244.488204)
		(end 382.792478 -244.412262)
		(width 0.088646)
		(layer "In6.Cu")
		(net "M_H_CPU0_SB_CS_N<2>")
	)
	(arc
		(start 382.407668 -244.418358)
		(mid 382.12949 -244.488081)
		(end 381.852932 -244.412262)
		(width 0.088646)
		(layer "In6.Cu")
		(net "M_H_CPU0_SB_CS_N<2>")
	)
	(arc
		(start 377.153678 -244.412262)
		(mid 376.96648 -244.362119)
		(end 376.779282 -244.412262)
		(width 0.088646)
		(layer "In6.Cu")
		(net "M_H_CPU0_SB_CS_N<2>")
	)
	(arc
		(start 377.719082 -244.412262)
		(mid 377.43638 -244.488038)
		(end 377.153678 -244.412262)
		(width 0.088646)
		(layer "In6.Cu")
		(net "M_H_CPU0_SB_CS_N<2>")
	)
	(arc
		(start 379.973332 -244.412262)
		(mid 379.786134 -244.362119)
		(end 379.598936 -244.412262)
		(width 0.088646)
		(layer "In6.Cu")
		(net "M_H_CPU0_SB_CS_N<2>")
	)
	(arc
		(start 381.852932 -244.412262)
		(mid 381.665734 -244.362119)
		(end 381.478536 -244.412262)
		(width 0.088646)
		(layer "In6.Cu")
		(net "M_H_CPU0_SB_CS_N<2>")
	)
	(arc
		(start 379.588522 -244.418358)
		(mid 379.31009 -244.488204)
		(end 379.033278 -244.412262)
		(width 0.088646)
		(layer "In6.Cu")
		(net "M_H_CPU0_SB_CS_N<2>")
	)
	(arc
		(start 376.76455 -244.420898)
		(mid 376.488075 -244.488218)
		(end 376.213878 -244.412262)
		(width 0.088646)
		(layer "In6.Cu")
		(net "M_H_CPU0_SB_CS_N<2>")
	)
	(arc
		(start 378.64415 -244.420898)
		(mid 378.367675 -244.488218)
		(end 378.093478 -244.412262)
		(width 0.088646)
		(layer "In6.Cu")
		(net "M_H_CPU0_SB_CS_N<2>")
	)
	(arc
		(start 384.672332 -244.412262)
		(mid 384.485134 -244.362119)
		(end 384.297936 -244.412262)
		(width 0.088646)
		(layer "In6.Cu")
		(net "M_H_CPU0_SB_CS_N<2>")
	)
	(arc
		(start 380.528068 -244.418358)
		(mid 380.24989 -244.488081)
		(end 379.973332 -244.412262)
		(width 0.088646)
		(layer "In6.Cu")
		(net "M_H_CPU0_SB_CS_N<2>")
	)
	(segment
		(start 376.02668 -243.644674)
		(end 376.02668 -243.108988)
		(width 0.20066)
		(layer "F.Cu")
		(net "M_H_CPU0_SB_CS_N<1>")
	)
	(segment
		(start 462.555082 -244.916706)
		(end 463.659982 -244.916706)
		(width 0.20066)
		(layer "F.Cu")
		(net "M_H_CPU0_SB_CS_N<1>")
	)
	(segment
		(start 376.026934 -243.644928)
		(end 376.02668 -243.644674)
		(width 0.20066)
		(layer "F.Cu")
		(net "M_H_CPU0_SB_CS_N<1>")
	)
	(segment
		(start 461.814672 -241.779806)
		(end 461.126586 -241.09172)
		(width 0.18288)
		(layer "In6.Cu")
		(net "M_H_CPU0_SB_CS_N<1>")
	)
	(segment
		(start 444.55969 -238.469678)
		(end 444.37681 -238.652558)
		(width 0.18288)
		(layer "In6.Cu")
		(net "M_H_CPU0_SB_CS_N<1>")
	)
	(segment
		(start 385.09067 -243.357654)
		(end 384.955034 -243.357654)
		(width 0.088646)
		(layer "In6.Cu")
		(net "M_H_CPU0_SB_CS_N<1>")
	)
	(segment
		(start 461.814672 -244.176296)
		(end 461.814672 -241.779806)
		(width 0.18288)
		(layer "In6.Cu")
		(net "M_H_CPU0_SB_CS_N<1>")
	)
	(segment
		(start 444.88735 -238.469678)
		(end 444.55969 -238.469678)
		(width 0.18288)
		(layer "In6.Cu")
		(net "M_H_CPU0_SB_CS_N<1>")
	)
	(segment
		(start 444.37681 -238.652558)
		(end 444.37681 -239.374426)
		(width 0.18288)
		(layer "In6.Cu")
		(net "M_H_CPU0_SB_CS_N<1>")
	)
	(segment
		(start 439.589672 -240.242344)
		(end 438.739788 -239.39246)
		(width 0.18288)
		(layer "In6.Cu")
		(net "M_H_CPU0_SB_CS_N<1>")
	)
	(segment
		(start 442.930534 -239.557306)
		(end 442.673994 -239.300766)
		(width 0.18288)
		(layer "In6.Cu")
		(net "M_H_CPU0_SB_CS_N<1>")
	)
	(segment
		(start 438.739788 -239.39246)
		(end 428.026068 -239.39246)
		(width 0.18288)
		(layer "In6.Cu")
		(net "M_H_CPU0_SB_CS_N<1>")
	)
	(segment
		(start 444.37681 -239.374426)
		(end 444.19393 -239.557306)
		(width 0.18288)
		(layer "In6.Cu")
		(net "M_H_CPU0_SB_CS_N<1>")
	)
	(segment
		(start 416.671252 -240.242344)
		(end 415.956242 -239.527334)
		(width 0.18288)
		(layer "In6.Cu")
		(net "M_H_CPU0_SB_CS_N<1>")
	)
	(segment
		(start 383.358136 -243.433346)
		(end 383.347722 -243.42725)
		(width 0.088646)
		(layer "In6.Cu")
		(net "M_H_CPU0_SB_CS_N<1>")
	)
	(segment
		(start 424.322748 -239.691164)
		(end 423.663872 -239.691164)
		(width 0.18288)
		(layer "In6.Cu")
		(net "M_H_CPU0_SB_CS_N<1>")
	)
	(segment
		(start 401.314666 -239.586008)
		(end 397.899636 -243.001038)
		(width 0.18288)
		(layer "In6.Cu")
		(net "M_H_CPU0_SB_CS_N<1>")
	)
	(segment
		(start 415.956242 -239.527334)
		(end 412.458662 -239.527334)
		(width 0.18288)
		(layer "In6.Cu")
		(net "M_H_CPU0_SB_CS_N<1>")
	)
	(segment
		(start 427.474888 -238.84128)
		(end 426.457872 -238.84128)
		(width 0.18288)
		(layer "In6.Cu")
		(net "M_H_CPU0_SB_CS_N<1>")
	)
	(segment
		(start 379.598682 -243.433346)
		(end 379.58395 -243.42471)
		(width 0.088646)
		(layer "In6.Cu")
		(net "M_H_CPU0_SB_CS_N<1>")
	)
	(segment
		(start 375.656602 -243.166138)
		(end 375.713752 -243.108988)
		(width 0.088646)
		(layer "In6.Cu")
		(net "M_H_CPU0_SB_CS_N<1>")
	)
	(segment
		(start 441.599574 -239.300766)
		(end 440.657996 -240.242344)
		(width 0.18288)
		(layer "In6.Cu")
		(net "M_H_CPU0_SB_CS_N<1>")
	)
	(segment
		(start 411.470602 -238.539274)
		(end 404.543006 -238.539274)
		(width 0.18288)
		(layer "In6.Cu")
		(net "M_H_CPU0_SB_CS_N<1>")
	)
	(segment
		(start 412.458662 -239.527334)
		(end 411.470602 -238.539274)
		(width 0.18288)
		(layer "In6.Cu")
		(net "M_H_CPU0_SB_CS_N<1>")
	)
	(segment
		(start 446.793112 -240.242344)
		(end 446.108074 -239.557306)
		(width 0.18288)
		(layer "In6.Cu")
		(net "M_H_CPU0_SB_CS_N<1>")
	)
	(segment
		(start 423.112692 -240.242344)
		(end 416.671252 -240.242344)
		(width 0.18288)
		(layer "In6.Cu")
		(net "M_H_CPU0_SB_CS_N<1>")
	)
	(segment
		(start 453.549512 -240.242344)
		(end 446.793112 -240.242344)
		(width 0.18288)
		(layer "In6.Cu")
		(net "M_H_CPU0_SB_CS_N<1>")
	)
	(segment
		(start 403.496272 -239.586008)
		(end 401.314666 -239.586008)
		(width 0.18288)
		(layer "In6.Cu")
		(net "M_H_CPU0_SB_CS_N<1>")
	)
	(segment
		(start 461.126586 -241.09172)
		(end 454.398888 -241.09172)
		(width 0.18288)
		(layer "In6.Cu")
		(net "M_H_CPU0_SB_CS_N<1>")
	)
	(segment
		(start 426.457872 -238.84128)
		(end 425.904152 -239.395)
		(width 0.18288)
		(layer "In6.Cu")
		(net "M_H_CPU0_SB_CS_N<1>")
	)
	(segment
		(start 375.713752 -243.108988)
		(end 376.02668 -243.108988)
		(width 0.088646)
		(layer "In6.Cu")
		(net "M_H_CPU0_SB_CS_N<1>")
	)
	(segment
		(start 423.663872 -239.691164)
		(end 423.112692 -240.242344)
		(width 0.18288)
		(layer "In6.Cu")
		(net "M_H_CPU0_SB_CS_N<1>")
	)
	(segment
		(start 375.839482 -243.433346)
		(end 375.830592 -243.428266)
		(width 0.088646)
		(layer "In6.Cu")
		(net "M_H_CPU0_SB_CS_N<1>")
	)
	(segment
		(start 445.07023 -238.652558)
		(end 444.88735 -238.469678)
		(width 0.18288)
		(layer "In6.Cu")
		(net "M_H_CPU0_SB_CS_N<1>")
	)
	(segment
		(start 382.418082 -243.433346)
		(end 382.407668 -243.42725)
		(width 0.088646)
		(layer "In6.Cu")
		(net "M_H_CPU0_SB_CS_N<1>")
	)
	(segment
		(start 385.447286 -243.001038)
		(end 385.09067 -243.357654)
		(width 0.088646)
		(layer "In6.Cu")
		(net "M_H_CPU0_SB_CS_N<1>")
	)
	(segment
		(start 454.398888 -241.09172)
		(end 453.549512 -240.242344)
		(width 0.18288)
		(layer "In6.Cu")
		(net "M_H_CPU0_SB_CS_N<1>")
	)
	(segment
		(start 380.538736 -243.433346)
		(end 380.528322 -243.42725)
		(width 0.088646)
		(layer "In6.Cu")
		(net "M_H_CPU0_SB_CS_N<1>")
	)
	(segment
		(start 404.543006 -238.539274)
		(end 403.496272 -239.586008)
		(width 0.18288)
		(layer "In6.Cu")
		(net "M_H_CPU0_SB_CS_N<1>")
	)
	(segment
		(start 378.658882 -243.433346)
		(end 378.64415 -243.42471)
		(width 0.088646)
		(layer "In6.Cu")
		(net "M_H_CPU0_SB_CS_N<1>")
	)
	(segment
		(start 445.25311 -239.557306)
		(end 445.07023 -239.374426)
		(width 0.18288)
		(layer "In6.Cu")
		(net "M_H_CPU0_SB_CS_N<1>")
	)
	(segment
		(start 425.904152 -239.395)
		(end 424.618912 -239.395)
		(width 0.18288)
		(layer "In6.Cu")
		(net "M_H_CPU0_SB_CS_N<1>")
	)
	(segment
		(start 376.779282 -243.433346)
		(end 376.76455 -243.42471)
		(width 0.088646)
		(layer "In6.Cu")
		(net "M_H_CPU0_SB_CS_N<1>")
	)
	(segment
		(start 444.19393 -239.557306)
		(end 442.930534 -239.557306)
		(width 0.18288)
		(layer "In6.Cu")
		(net "M_H_CPU0_SB_CS_N<1>")
	)
	(segment
		(start 445.07023 -239.374426)
		(end 445.07023 -238.652558)
		(width 0.18288)
		(layer "In6.Cu")
		(net "M_H_CPU0_SB_CS_N<1>")
	)
	(segment
		(start 428.026068 -239.39246)
		(end 427.474888 -238.84128)
		(width 0.18288)
		(layer "In6.Cu")
		(net "M_H_CPU0_SB_CS_N<1>")
	)
	(segment
		(start 442.673994 -239.300766)
		(end 441.599574 -239.300766)
		(width 0.18288)
		(layer "In6.Cu")
		(net "M_H_CPU0_SB_CS_N<1>")
	)
	(segment
		(start 385.653026 -243.001038)
		(end 385.447286 -243.001038)
		(width 0.088646)
		(layer "In6.Cu")
		(net "M_H_CPU0_SB_CS_N<1>")
	)
	(segment
		(start 424.618912 -239.395)
		(end 424.322748 -239.691164)
		(width 0.18288)
		(layer "In6.Cu")
		(net "M_H_CPU0_SB_CS_N<1>")
	)
	(segment
		(start 397.899636 -243.001038)
		(end 385.653026 -243.001038)
		(width 0.18288)
		(layer "In6.Cu")
		(net "M_H_CPU0_SB_CS_N<1>")
	)
	(segment
		(start 446.108074 -239.557306)
		(end 445.25311 -239.557306)
		(width 0.18288)
		(layer "In6.Cu")
		(net "M_H_CPU0_SB_CS_N<1>")
	)
	(segment
		(start 462.555082 -244.916706)
		(end 461.814672 -244.176296)
		(width 0.18288)
		(layer "In6.Cu")
		(net "M_H_CPU0_SB_CS_N<1>")
	)
	(segment
		(start 440.657996 -240.242344)
		(end 439.589672 -240.242344)
		(width 0.18288)
		(layer "In6.Cu")
		(net "M_H_CPU0_SB_CS_N<1>")
	)
	(arc
		(start 383.732532 -243.433346)
		(mid 383.545334 -243.483489)
		(end 383.358136 -243.433346)
		(width 0.088646)
		(layer "In6.Cu")
		(net "M_H_CPU0_SB_CS_N<1>")
	)
	(arc
		(start 384.955034 -243.357654)
		(mid 384.80869 -243.376862)
		(end 384.672332 -243.433346)
		(width 0.088646)
		(layer "In6.Cu")
		(net "M_H_CPU0_SB_CS_N<1>")
	)
	(arc
		(start 382.792478 -243.433346)
		(mid 382.60528 -243.483489)
		(end 382.418082 -243.433346)
		(width 0.088646)
		(layer "In6.Cu")
		(net "M_H_CPU0_SB_CS_N<1>")
	)
	(arc
		(start 375.830592 -243.428266)
		(mid 375.714783 -243.316337)
		(end 375.656602 -243.166138)
		(width 0.088646)
		(layer "In6.Cu")
		(net "M_H_CPU0_SB_CS_N<1>")
	)
	(arc
		(start 380.913132 -243.433346)
		(mid 380.725934 -243.483489)
		(end 380.538736 -243.433346)
		(width 0.088646)
		(layer "In6.Cu")
		(net "M_H_CPU0_SB_CS_N<1>")
	)
	(arc
		(start 381.478536 -243.433346)
		(mid 381.195834 -243.35757)
		(end 380.913132 -243.433346)
		(width 0.088646)
		(layer "In6.Cu")
		(net "M_H_CPU0_SB_CS_N<1>")
	)
	(arc
		(start 380.528322 -243.42725)
		(mid 380.24989 -243.357404)
		(end 379.973078 -243.433346)
		(width 0.088646)
		(layer "In6.Cu")
		(net "M_H_CPU0_SB_CS_N<1>")
	)
	(arc
		(start 379.033278 -243.433346)
		(mid 378.84608 -243.483489)
		(end 378.658882 -243.433346)
		(width 0.088646)
		(layer "In6.Cu")
		(net "M_H_CPU0_SB_CS_N<1>")
	)
	(arc
		(start 379.58395 -243.42471)
		(mid 379.307475 -243.35739)
		(end 379.033278 -243.433346)
		(width 0.088646)
		(layer "In6.Cu")
		(net "M_H_CPU0_SB_CS_N<1>")
	)
	(arc
		(start 384.297936 -243.433346)
		(mid 384.015234 -243.35757)
		(end 383.732532 -243.433346)
		(width 0.088646)
		(layer "In6.Cu")
		(net "M_H_CPU0_SB_CS_N<1>")
	)
	(arc
		(start 377.719082 -243.433346)
		(mid 377.43638 -243.35757)
		(end 377.153678 -243.433346)
		(width 0.088646)
		(layer "In6.Cu")
		(net "M_H_CPU0_SB_CS_N<1>")
	)
	(arc
		(start 377.153678 -243.433346)
		(mid 376.96648 -243.483489)
		(end 376.779282 -243.433346)
		(width 0.088646)
		(layer "In6.Cu")
		(net "M_H_CPU0_SB_CS_N<1>")
	)
	(arc
		(start 376.213878 -243.433346)
		(mid 376.02668 -243.483489)
		(end 375.839482 -243.433346)
		(width 0.088646)
		(layer "In6.Cu")
		(net "M_H_CPU0_SB_CS_N<1>")
	)
	(arc
		(start 376.76455 -243.42471)
		(mid 376.488075 -243.35739)
		(end 376.213878 -243.433346)
		(width 0.088646)
		(layer "In6.Cu")
		(net "M_H_CPU0_SB_CS_N<1>")
	)
	(arc
		(start 383.347722 -243.42725)
		(mid 383.06929 -243.357404)
		(end 382.792478 -243.433346)
		(width 0.088646)
		(layer "In6.Cu")
		(net "M_H_CPU0_SB_CS_N<1>")
	)
	(arc
		(start 382.407668 -243.42725)
		(mid 382.12949 -243.357527)
		(end 381.852932 -243.433346)
		(width 0.088646)
		(layer "In6.Cu")
		(net "M_H_CPU0_SB_CS_N<1>")
	)
	(arc
		(start 378.093478 -243.433346)
		(mid 377.90628 -243.483489)
		(end 377.719082 -243.433346)
		(width 0.088646)
		(layer "In6.Cu")
		(net "M_H_CPU0_SB_CS_N<1>")
	)
	(arc
		(start 378.64415 -243.42471)
		(mid 378.367675 -243.35739)
		(end 378.093478 -243.433346)
		(width 0.088646)
		(layer "In6.Cu")
		(net "M_H_CPU0_SB_CS_N<1>")
	)
	(arc
		(start 381.852932 -243.433346)
		(mid 381.665734 -243.483489)
		(end 381.478536 -243.433346)
		(width 0.088646)
		(layer "In6.Cu")
		(net "M_H_CPU0_SB_CS_N<1>")
	)
	(arc
		(start 384.672332 -243.433346)
		(mid 384.485134 -243.483489)
		(end 384.297936 -243.433346)
		(width 0.088646)
		(layer "In6.Cu")
		(net "M_H_CPU0_SB_CS_N<1>")
	)
	(arc
		(start 379.973078 -243.433346)
		(mid 379.78588 -243.483489)
		(end 379.598682 -243.433346)
		(width 0.088646)
		(layer "In6.Cu")
		(net "M_H_CPU0_SB_CS_N<1>")
	)
	(segment
		(start 458.455014 -245.76659)
		(end 459.559914 -245.76659)
		(width 0.20066)
		(layer "F.Cu")
		(net "M_H_CPU0_SB_CS_N<0>")
	)
	(segment
		(start 375.08688 -243.644674)
		(end 375.08688 -243.108988)
		(width 0.20066)
		(layer "F.Cu")
		(net "M_H_CPU0_SB_CS_N<0>")
	)
	(segment
		(start 375.087134 -243.644928)
		(end 375.08688 -243.644674)
		(width 0.20066)
		(layer "F.Cu")
		(net "M_H_CPU0_SB_CS_N<0>")
	)
	(segment
		(start 427.852586 -239.932718)
		(end 427.273974 -239.354106)
		(width 0.18288)
		(layer "In6.Cu")
		(net "M_H_CPU0_SB_CS_N<0>")
	)
	(segment
		(start 444.130684 -240.521236)
		(end 444.130684 -240.329466)
		(width 0.18288)
		(layer "In6.Cu")
		(net "M_H_CPU0_SB_CS_N<0>")
	)
	(segment
		(start 429.270922 -240.848642)
		(end 429.088042 -240.665762)
		(width 0.18288)
		(layer "In6.Cu")
		(net "M_H_CPU0_SB_CS_N<0>")
	)
	(segment
		(start 398.123918 -243.546376)
		(end 386.887974 -243.546376)
		(width 0.18288)
		(layer "In6.Cu")
		(net "M_H_CPU0_SB_CS_N<0>")
	)
	(segment
		(start 423.984674 -240.242344)
		(end 423.13479 -241.092228)
		(width 0.18288)
		(layer "In6.Cu")
		(net "M_H_CPU0_SB_CS_N<0>")
	)
	(segment
		(start 427.273974 -239.354106)
		(end 426.727874 -239.354106)
		(width 0.18288)
		(layer "In6.Cu")
		(net "M_H_CPU0_SB_CS_N<0>")
	)
	(segment
		(start 405.744934 -239.393222)
		(end 404.974552 -239.393222)
		(width 0.18288)
		(layer "In6.Cu")
		(net "M_H_CPU0_SB_CS_N<0>")
	)
	(segment
		(start 446.486534 -240.748566)
		(end 445.884554 -240.146586)
		(width 0.18288)
		(layer "In6.Cu")
		(net "M_H_CPU0_SB_CS_N<0>")
	)
	(segment
		(start 445.006984 -240.146586)
		(end 444.824104 -240.329466)
		(width 0.18288)
		(layer "In6.Cu")
		(net "M_H_CPU0_SB_CS_N<0>")
	)
	(segment
		(start 429.088042 -240.115598)
		(end 428.905162 -239.932718)
		(width 0.18288)
		(layer "In6.Cu")
		(net "M_H_CPU0_SB_CS_N<0>")
	)
	(segment
		(start 439.266838 -241.092482)
		(end 438.4167 -240.242344)
		(width 0.18288)
		(layer "In6.Cu")
		(net "M_H_CPU0_SB_CS_N<0>")
	)
	(segment
		(start 426.727874 -239.354106)
		(end 425.839636 -240.242344)
		(width 0.18288)
		(layer "In6.Cu")
		(net "M_H_CPU0_SB_CS_N<0>")
	)
	(segment
		(start 444.130684 -240.329466)
		(end 443.947804 -240.146586)
		(width 0.18288)
		(layer "In6.Cu")
		(net "M_H_CPU0_SB_CS_N<0>")
	)
	(segment
		(start 448.972178 -241.492278)
		(end 448.789298 -241.675158)
		(width 0.18288)
		(layer "In6.Cu")
		(net "M_H_CPU0_SB_CS_N<0>")
	)
	(segment
		(start 385.753102 -243.866416)
		(end 385.410202 -243.866416)
		(width 0.088646)
		(layer "In6.Cu")
		(net "M_H_CPU0_SB_CS_N<0>")
	)
	(segment
		(start 448.278758 -241.492278)
		(end 448.278758 -240.931446)
		(width 0.18288)
		(layer "In6.Cu")
		(net "M_H_CPU0_SB_CS_N<0>")
	)
	(segment
		(start 445.884554 -240.146586)
		(end 445.006984 -240.146586)
		(width 0.18288)
		(layer "In6.Cu")
		(net "M_H_CPU0_SB_CS_N<0>")
	)
	(segment
		(start 401.42414 -240.246154)
		(end 398.123918 -243.546376)
		(width 0.18288)
		(layer "In6.Cu")
		(net "M_H_CPU0_SB_CS_N<0>")
	)
	(segment
		(start 413.095694 -240.111026)
		(end 412.371794 -240.834926)
		(width 0.18288)
		(layer "In6.Cu")
		(net "M_H_CPU0_SB_CS_N<0>")
	)
	(segment
		(start 385.410202 -243.866416)
		(end 385.142232 -243.598446)
		(width 0.088646)
		(layer "In6.Cu")
		(net "M_H_CPU0_SB_CS_N<0>")
	)
	(segment
		(start 429.781462 -240.115598)
		(end 429.781462 -240.665762)
		(width 0.18288)
		(layer "In6.Cu")
		(net "M_H_CPU0_SB_CS_N<0>")
	)
	(segment
		(start 459.64094 -244.580664)
		(end 459.64094 -242.402106)
		(width 0.18288)
		(layer "In6.Cu")
		(net "M_H_CPU0_SB_CS_N<0>")
	)
	(segment
		(start 453.524874 -241.944906)
		(end 452.67245 -241.092482)
		(width 0.18288)
		(layer "In6.Cu")
		(net "M_H_CPU0_SB_CS_N<0>")
	)
	(segment
		(start 386.887974 -243.546376)
		(end 386.567934 -243.866416)
		(width 0.18288)
		(layer "In6.Cu")
		(net "M_H_CPU0_SB_CS_N<0>")
	)
	(segment
		(start 444.641224 -240.704116)
		(end 444.313564 -240.704116)
		(width 0.18288)
		(layer "In6.Cu")
		(net "M_H_CPU0_SB_CS_N<0>")
	)
	(segment
		(start 428.905162 -239.932718)
		(end 427.852586 -239.932718)
		(width 0.18288)
		(layer "In6.Cu")
		(net "M_H_CPU0_SB_CS_N<0>")
	)
	(segment
		(start 411.498034 -240.834926)
		(end 410.056584 -239.393476)
		(width 0.18288)
		(layer "In6.Cu")
		(net "M_H_CPU0_SB_CS_N<0>")
	)
	(segment
		(start 442.463174 -240.492026)
		(end 441.320174 -240.492026)
		(width 0.18288)
		(layer "In6.Cu")
		(net "M_H_CPU0_SB_CS_N<0>")
	)
	(segment
		(start 459.18374 -241.944906)
		(end 453.524874 -241.944906)
		(width 0.18288)
		(layer "In6.Cu")
		(net "M_H_CPU0_SB_CS_N<0>")
	)
	(segment
		(start 448.278758 -240.931446)
		(end 448.095878 -240.748566)
		(width 0.18288)
		(layer "In6.Cu")
		(net "M_H_CPU0_SB_CS_N<0>")
	)
	(segment
		(start 448.461638 -241.675158)
		(end 448.278758 -241.492278)
		(width 0.18288)
		(layer "In6.Cu")
		(net "M_H_CPU0_SB_CS_N<0>")
	)
	(segment
		(start 444.824104 -240.329466)
		(end 444.824104 -240.521236)
		(width 0.18288)
		(layer "In6.Cu")
		(net "M_H_CPU0_SB_CS_N<0>")
	)
	(segment
		(start 452.67245 -241.092482)
		(end 450.576696 -241.092482)
		(width 0.18288)
		(layer "In6.Cu")
		(net "M_H_CPU0_SB_CS_N<0>")
	)
	(segment
		(start 429.598582 -240.848642)
		(end 429.270922 -240.848642)
		(width 0.18288)
		(layer "In6.Cu")
		(net "M_H_CPU0_SB_CS_N<0>")
	)
	(segment
		(start 375.399808 -243.108988)
		(end 375.08688 -243.108988)
		(width 0.088646)
		(layer "In6.Cu")
		(net "M_H_CPU0_SB_CS_N<0>")
	)
	(segment
		(start 440.719718 -241.092482)
		(end 439.266838 -241.092482)
		(width 0.18288)
		(layer "In6.Cu")
		(net "M_H_CPU0_SB_CS_N<0>")
	)
	(segment
		(start 386.567934 -243.866416)
		(end 385.753102 -243.866416)
		(width 0.18288)
		(layer "In6.Cu")
		(net "M_H_CPU0_SB_CS_N<0>")
	)
	(segment
		(start 405.745188 -239.393476)
		(end 405.744934 -239.393222)
		(width 0.18288)
		(layer "In6.Cu")
		(net "M_H_CPU0_SB_CS_N<0>")
	)
	(segment
		(start 450.576696 -241.092482)
		(end 450.23278 -240.748566)
		(width 0.18288)
		(layer "In6.Cu")
		(net "M_H_CPU0_SB_CS_N<0>")
	)
	(segment
		(start 382.337564 -243.607082)
		(end 382.322832 -243.598446)
		(width 0.088646)
		(layer "In6.Cu")
		(net "M_H_CPU0_SB_CS_N<0>")
	)
	(segment
		(start 429.088042 -240.665762)
		(end 429.088042 -240.115598)
		(width 0.18288)
		(layer "In6.Cu")
		(net "M_H_CPU0_SB_CS_N<0>")
	)
	(segment
		(start 448.095878 -240.748566)
		(end 446.486534 -240.748566)
		(width 0.18288)
		(layer "In6.Cu")
		(net "M_H_CPU0_SB_CS_N<0>")
	)
	(segment
		(start 429.964342 -239.932718)
		(end 429.781462 -240.115598)
		(width 0.18288)
		(layer "In6.Cu")
		(net "M_H_CPU0_SB_CS_N<0>")
	)
	(segment
		(start 429.781462 -240.665762)
		(end 429.598582 -240.848642)
		(width 0.18288)
		(layer "In6.Cu")
		(net "M_H_CPU0_SB_CS_N<0>")
	)
	(segment
		(start 431.04816 -239.932718)
		(end 429.964342 -239.932718)
		(width 0.18288)
		(layer "In6.Cu")
		(net "M_H_CPU0_SB_CS_N<0>")
	)
	(segment
		(start 448.972178 -240.931446)
		(end 448.972178 -241.492278)
		(width 0.18288)
		(layer "In6.Cu")
		(net "M_H_CPU0_SB_CS_N<0>")
	)
	(segment
		(start 412.371794 -240.834926)
		(end 411.498034 -240.834926)
		(width 0.18288)
		(layer "In6.Cu")
		(net "M_H_CPU0_SB_CS_N<0>")
	)
	(segment
		(start 449.155058 -240.748566)
		(end 448.972178 -240.931446)
		(width 0.18288)
		(layer "In6.Cu")
		(net "M_H_CPU0_SB_CS_N<0>")
	)
	(segment
		(start 379.518164 -243.607082)
		(end 379.503432 -243.598446)
		(width 0.088646)
		(layer "In6.Cu")
		(net "M_H_CPU0_SB_CS_N<0>")
	)
	(segment
		(start 416.695636 -241.092228)
		(end 415.714434 -240.111026)
		(width 0.18288)
		(layer "In6.Cu")
		(net "M_H_CPU0_SB_CS_N<0>")
	)
	(segment
		(start 404.12162 -240.246154)
		(end 401.42414 -240.246154)
		(width 0.18288)
		(layer "In6.Cu")
		(net "M_H_CPU0_SB_CS_N<0>")
	)
	(segment
		(start 410.056584 -239.393476)
		(end 405.745188 -239.393476)
		(width 0.18288)
		(layer "In6.Cu")
		(net "M_H_CPU0_SB_CS_N<0>")
	)
	(segment
		(start 458.455014 -245.76659)
		(end 459.64094 -244.580664)
		(width 0.18288)
		(layer "In6.Cu")
		(net "M_H_CPU0_SB_CS_N<0>")
	)
	(segment
		(start 444.824104 -240.521236)
		(end 444.641224 -240.704116)
		(width 0.18288)
		(layer "In6.Cu")
		(net "M_H_CPU0_SB_CS_N<0>")
	)
	(segment
		(start 375.744232 -243.598446)
		(end 375.738136 -243.59489)
		(width 0.088646)
		(layer "In6.Cu")
		(net "M_H_CPU0_SB_CS_N<0>")
	)
	(segment
		(start 438.4167 -240.242344)
		(end 431.357786 -240.242344)
		(width 0.18288)
		(layer "In6.Cu")
		(net "M_H_CPU0_SB_CS_N<0>")
	)
	(segment
		(start 442.808614 -240.146586)
		(end 442.463174 -240.492026)
		(width 0.18288)
		(layer "In6.Cu")
		(net "M_H_CPU0_SB_CS_N<0>")
	)
	(segment
		(start 431.357786 -240.242344)
		(end 431.04816 -239.932718)
		(width 0.18288)
		(layer "In6.Cu")
		(net "M_H_CPU0_SB_CS_N<0>")
	)
	(segment
		(start 378.578364 -243.607082)
		(end 378.563632 -243.598446)
		(width 0.088646)
		(layer "In6.Cu")
		(net "M_H_CPU0_SB_CS_N<0>")
	)
	(segment
		(start 450.23278 -240.748566)
		(end 449.155058 -240.748566)
		(width 0.18288)
		(layer "In6.Cu")
		(net "M_H_CPU0_SB_CS_N<0>")
	)
	(segment
		(start 375.46534 -243.17452)
		(end 375.399808 -243.108988)
		(width 0.088646)
		(layer "In6.Cu")
		(net "M_H_CPU0_SB_CS_N<0>")
	)
	(segment
		(start 415.714434 -240.111026)
		(end 413.095694 -240.111026)
		(width 0.18288)
		(layer "In6.Cu")
		(net "M_H_CPU0_SB_CS_N<0>")
	)
	(segment
		(start 376.694446 -243.604542)
		(end 376.684032 -243.598446)
		(width 0.088646)
		(layer "In6.Cu")
		(net "M_H_CPU0_SB_CS_N<0>")
	)
	(segment
		(start 377.633992 -243.604542)
		(end 377.623578 -243.598446)
		(width 0.088646)
		(layer "In6.Cu")
		(net "M_H_CPU0_SB_CS_N<0>")
	)
	(segment
		(start 404.974552 -239.393222)
		(end 404.12162 -240.246154)
		(width 0.18288)
		(layer "In6.Cu")
		(net "M_H_CPU0_SB_CS_N<0>")
	)
	(segment
		(start 459.64094 -242.402106)
		(end 459.18374 -241.944906)
		(width 0.18288)
		(layer "In6.Cu")
		(net "M_H_CPU0_SB_CS_N<0>")
	)
	(segment
		(start 444.313564 -240.704116)
		(end 444.130684 -240.521236)
		(width 0.18288)
		(layer "In6.Cu")
		(net "M_H_CPU0_SB_CS_N<0>")
	)
	(segment
		(start 375.758964 -243.607082)
		(end 375.744232 -243.598446)
		(width 0.088646)
		(layer "In6.Cu")
		(net "M_H_CPU0_SB_CS_N<0>")
	)
	(segment
		(start 441.320174 -240.492026)
		(end 440.719718 -241.092482)
		(width 0.18288)
		(layer "In6.Cu")
		(net "M_H_CPU0_SB_CS_N<0>")
	)
	(segment
		(start 448.789298 -241.675158)
		(end 448.461638 -241.675158)
		(width 0.18288)
		(layer "In6.Cu")
		(net "M_H_CPU0_SB_CS_N<0>")
	)
	(segment
		(start 443.947804 -240.146586)
		(end 442.808614 -240.146586)
		(width 0.18288)
		(layer "In6.Cu")
		(net "M_H_CPU0_SB_CS_N<0>")
	)
	(segment
		(start 423.13479 -241.092228)
		(end 416.695636 -241.092228)
		(width 0.18288)
		(layer "In6.Cu")
		(net "M_H_CPU0_SB_CS_N<0>")
	)
	(segment
		(start 425.839636 -240.242344)
		(end 423.984674 -240.242344)
		(width 0.18288)
		(layer "In6.Cu")
		(net "M_H_CPU0_SB_CS_N<0>")
	)
	(arc
		(start 380.068836 -243.598446)
		(mid 379.794637 -243.674281)
		(end 379.518164 -243.607082)
		(width 0.088646)
		(layer "In6.Cu")
		(net "M_H_CPU0_SB_CS_N<0>")
	)
	(arc
		(start 383.828036 -243.598446)
		(mid 383.545334 -243.674222)
		(end 383.262632 -243.598446)
		(width 0.088646)
		(layer "In6.Cu")
		(net "M_H_CPU0_SB_CS_N<0>")
	)
	(arc
		(start 382.322832 -243.598446)
		(mid 382.135634 -243.548303)
		(end 381.948436 -243.598446)
		(width 0.088646)
		(layer "In6.Cu")
		(net "M_H_CPU0_SB_CS_N<0>")
	)
	(arc
		(start 384.202432 -243.598446)
		(mid 384.015234 -243.548303)
		(end 383.828036 -243.598446)
		(width 0.088646)
		(layer "In6.Cu")
		(net "M_H_CPU0_SB_CS_N<0>")
	)
	(arc
		(start 377.249182 -243.598446)
		(mid 376.972623 -243.674189)
		(end 376.694446 -243.604542)
		(width 0.088646)
		(layer "In6.Cu")
		(net "M_H_CPU0_SB_CS_N<0>")
	)
	(arc
		(start 379.503432 -243.598446)
		(mid 379.316234 -243.548303)
		(end 379.129036 -243.598446)
		(width 0.088646)
		(layer "In6.Cu")
		(net "M_H_CPU0_SB_CS_N<0>")
	)
	(arc
		(start 378.563632 -243.598446)
		(mid 378.376434 -243.548303)
		(end 378.189236 -243.598446)
		(width 0.088646)
		(layer "In6.Cu")
		(net "M_H_CPU0_SB_CS_N<0>")
	)
	(arc
		(start 381.008636 -243.598446)
		(mid 380.725934 -243.674222)
		(end 380.443232 -243.598446)
		(width 0.088646)
		(layer "In6.Cu")
		(net "M_H_CPU0_SB_CS_N<0>")
	)
	(arc
		(start 381.948436 -243.598446)
		(mid 381.665734 -243.674222)
		(end 381.383032 -243.598446)
		(width 0.088646)
		(layer "In6.Cu")
		(net "M_H_CPU0_SB_CS_N<0>")
	)
	(arc
		(start 376.684032 -243.598446)
		(mid 376.496834 -243.548303)
		(end 376.309636 -243.598446)
		(width 0.088646)
		(layer "In6.Cu")
		(net "M_H_CPU0_SB_CS_N<0>")
	)
	(arc
		(start 384.767836 -243.598446)
		(mid 384.485134 -243.674222)
		(end 384.202432 -243.598446)
		(width 0.088646)
		(layer "In6.Cu")
		(net "M_H_CPU0_SB_CS_N<0>")
	)
	(arc
		(start 379.129036 -243.598446)
		(mid 378.854837 -243.674281)
		(end 378.578364 -243.607082)
		(width 0.088646)
		(layer "In6.Cu")
		(net "M_H_CPU0_SB_CS_N<0>")
	)
	(arc
		(start 382.888236 -243.598446)
		(mid 382.614037 -243.674281)
		(end 382.337564 -243.607082)
		(width 0.088646)
		(layer "In6.Cu")
		(net "M_H_CPU0_SB_CS_N<0>")
	)
	(arc
		(start 383.262632 -243.598446)
		(mid 383.075434 -243.548303)
		(end 382.888236 -243.598446)
		(width 0.088646)
		(layer "In6.Cu")
		(net "M_H_CPU0_SB_CS_N<0>")
	)
	(arc
		(start 377.623578 -243.598446)
		(mid 377.43638 -243.548303)
		(end 377.249182 -243.598446)
		(width 0.088646)
		(layer "In6.Cu")
		(net "M_H_CPU0_SB_CS_N<0>")
	)
	(arc
		(start 375.738136 -243.59489)
		(mid 375.552613 -243.416589)
		(end 375.46534 -243.17452)
		(width 0.088646)
		(layer "In6.Cu")
		(net "M_H_CPU0_SB_CS_N<0>")
	)
	(arc
		(start 378.189236 -243.598446)
		(mid 377.912423 -243.674316)
		(end 377.633992 -243.604542)
		(width 0.088646)
		(layer "In6.Cu")
		(net "M_H_CPU0_SB_CS_N<0>")
	)
	(arc
		(start 381.383032 -243.598446)
		(mid 381.195834 -243.548303)
		(end 381.008636 -243.598446)
		(width 0.088646)
		(layer "In6.Cu")
		(net "M_H_CPU0_SB_CS_N<0>")
	)
	(arc
		(start 376.309636 -243.598446)
		(mid 376.035437 -243.674281)
		(end 375.758964 -243.607082)
		(width 0.088646)
		(layer "In6.Cu")
		(net "M_H_CPU0_SB_CS_N<0>")
	)
	(arc
		(start 385.142232 -243.598446)
		(mid 384.955034 -243.548303)
		(end 384.767836 -243.598446)
		(width 0.088646)
		(layer "In6.Cu")
		(net "M_H_CPU0_SB_CS_N<0>")
	)
	(arc
		(start 380.443232 -243.598446)
		(mid 380.256034 -243.548303)
		(end 380.068836 -243.598446)
		(width 0.088646)
		(layer "In6.Cu")
		(net "M_H_CPU0_SB_CS_N<0>")
	)
	(segment
		(start 456.116182 -238.966756)
		(end 457.814426 -238.966756)
		(width 0.20066)
		(layer "F.Cu")
		(net "M_H_CPU0_SB_CB<7>")
	)
	(segment
		(start 455.011282 -238.966756)
		(end 456.116182 -238.966756)
		(width 0.20066)
		(layer "F.Cu")
		(net "M_H_CPU0_SB_CB<7>")
	)
	(segment
		(start 458.24648 -239.39881)
		(end 458.538326 -239.39881)
		(width 0.20066)
		(layer "F.Cu")
		(net "M_H_CPU0_SB_CB<7>")
	)
	(segment
		(start 461.455516 -238.948976)
		(end 461.689704 -238.714788)
		(width 0.20066)
		(layer "F.Cu")
		(net "M_H_CPU0_SB_CB<7>")
	)
	(segment
		(start 461.455516 -239.199928)
		(end 461.455516 -238.948976)
		(width 0.20066)
		(layer "F.Cu")
		(net "M_H_CPU0_SB_CB<7>")
	)
	(segment
		(start 371.327934 -243.644928)
		(end 371.32768 -243.644674)
		(width 0.20066)
		(layer "F.Cu")
		(net "M_H_CPU0_SB_CB<7>")
	)
	(segment
		(start 457.814426 -238.966756)
		(end 458.24648 -239.39881)
		(width 0.20066)
		(layer "F.Cu")
		(net "M_H_CPU0_SB_CB<7>")
	)
	(segment
		(start 462.073752 -238.714788)
		(end 462.32572 -238.966756)
		(width 0.20066)
		(layer "F.Cu")
		(net "M_H_CPU0_SB_CB<7>")
	)
	(segment
		(start 458.543152 -239.39881)
		(end 458.550264 -239.391698)
		(width 0.1016)
		(layer "F.Cu")
		(net "M_H_CPU0_SB_CB<7>")
	)
	(segment
		(start 461.689704 -238.714788)
		(end 462.073752 -238.714788)
		(width 0.20066)
		(layer "F.Cu")
		(net "M_H_CPU0_SB_CB<7>")
	)
	(segment
		(start 462.32572 -238.966756)
		(end 463.659982 -238.966756)
		(width 0.20066)
		(layer "F.Cu")
		(net "M_H_CPU0_SB_CB<7>")
	)
	(segment
		(start 371.32768 -243.644674)
		(end 371.32768 -243.108988)
		(width 0.20066)
		(layer "F.Cu")
		(net "M_H_CPU0_SB_CB<7>")
	)
	(segment
		(start 460.570326 -239.40389)
		(end 461.251554 -239.40389)
		(width 0.20066)
		(layer "F.Cu")
		(net "M_H_CPU0_SB_CB<7>")
	)
	(segment
		(start 461.251554 -239.40389)
		(end 461.455516 -239.199928)
		(width 0.20066)
		(layer "F.Cu")
		(net "M_H_CPU0_SB_CB<7>")
	)
	(segment
		(start 458.538326 -239.39881)
		(end 458.543152 -239.39881)
		(width 0.101854)
		(layer "F.Cu")
		(net "M_H_CPU0_SB_CB<7>")
	)
	(segment
		(start 458.550264 -239.391698)
		(end 460.558134 -239.391698)
		(width 0.1016)
		(layer "F.Cu")
		(net "M_H_CPU0_SB_CB<7>")
	)
	(segment
		(start 460.558134 -239.391698)
		(end 460.570326 -239.40389)
		(width 0.1016)
		(layer "F.Cu")
		(net "M_H_CPU0_SB_CB<7>")
	)
	(segment
		(start 454.654158 -239.099852)
		(end 451.807834 -240.242344)
		(width 0.18288)
		(layer "In11.Cu")
		(net "M_H_CPU0_SB_CB<7>")
	)
	(segment
		(start 396.707868 -244.33657)
		(end 391.108692 -244.33657)
		(width 0.18288)
		(layer "In11.Cu")
		(net "M_H_CPU0_SB_CB<7>")
	)
	(segment
		(start 441.759594 -239.323626)
		(end 440.56427 -240.241582)
		(width 0.18288)
		(layer "In11.Cu")
		(net "M_H_CPU0_SB_CB<7>")
	)
	(segment
		(start 431.677826 -238.538512)
		(end 429.686466 -238.538512)
		(width 0.18288)
		(layer "In11.Cu")
		(net "M_H_CPU0_SB_CB<7>")
	)
	(segment
		(start 429.686466 -238.538512)
		(end 429.493426 -238.345472)
		(width 0.18288)
		(layer "In11.Cu")
		(net "M_H_CPU0_SB_CB<7>")
	)
	(segment
		(start 376.694446 -243.604542)
		(end 376.684032 -243.598446)
		(width 0.088646)
		(layer "In11.Cu")
		(net "M_H_CPU0_SB_CB<7>")
	)
	(segment
		(start 440.56427 -240.241582)
		(end 439.18505 -240.241582)
		(width 0.18288)
		(layer "In11.Cu")
		(net "M_H_CPU0_SB_CB<7>")
	)
	(segment
		(start 388.23265 -244.482112)
		(end 387.811264 -244.060726)
		(width 0.088646)
		(layer "In11.Cu")
		(net "M_H_CPU0_SB_CB<7>")
	)
	(segment
		(start 378.578364 -243.607082)
		(end 378.563632 -243.598446)
		(width 0.088646)
		(layer "In11.Cu")
		(net "M_H_CPU0_SB_CB<7>")
	)
	(segment
		(start 390.96315 -244.482112)
		(end 389.043164 -244.482112)
		(width 0.18288)
		(layer "In11.Cu")
		(net "M_H_CPU0_SB_CB<7>")
	)
	(segment
		(start 442.991494 -239.628426)
		(end 442.686694 -239.323626)
		(width 0.18288)
		(layer "In11.Cu")
		(net "M_H_CPU0_SB_CB<7>")
	)
	(segment
		(start 407.131774 -240.720626)
		(end 406.057862 -241.165634)
		(width 0.18288)
		(layer "In11.Cu")
		(net "M_H_CPU0_SB_CB<7>")
	)
	(segment
		(start 428.982886 -237.760764)
		(end 428.789846 -237.953804)
		(width 0.18288)
		(layer "In11.Cu")
		(net "M_H_CPU0_SB_CB<7>")
	)
	(segment
		(start 451.807834 -240.242344)
		(end 450.18325 -240.242344)
		(width 0.18288)
		(layer "In11.Cu")
		(net "M_H_CPU0_SB_CB<7>")
	)
	(segment
		(start 408.580082 -239.272318)
		(end 407.131774 -240.720626)
		(width 0.18288)
		(layer "In11.Cu")
		(net "M_H_CPU0_SB_CB<7>")
	)
	(segment
		(start 447.068194 -239.349026)
		(end 445.639952 -239.628426)
		(width 0.18288)
		(layer "In11.Cu")
		(net "M_H_CPU0_SB_CB<7>")
	)
	(segment
		(start 428.596806 -238.538512)
		(end 427.657514 -238.538512)
		(width 0.18288)
		(layer "In11.Cu")
		(net "M_H_CPU0_SB_CB<7>")
	)
	(segment
		(start 412.499048 -239.46358)
		(end 412.307786 -239.272318)
		(width 0.18288)
		(layer "In11.Cu")
		(net "M_H_CPU0_SB_CB<7>")
	)
	(segment
		(start 442.686694 -239.323626)
		(end 441.759594 -239.323626)
		(width 0.18288)
		(layer "In11.Cu")
		(net "M_H_CPU0_SB_CB<7>")
	)
	(segment
		(start 434.928518 -239.390936)
		(end 434.716682 -239.1791)
		(width 0.18288)
		(layer "In11.Cu")
		(net "M_H_CPU0_SB_CB<7>")
	)
	(segment
		(start 377.633992 -243.604542)
		(end 377.623578 -243.598446)
		(width 0.088646)
		(layer "In11.Cu")
		(net "M_H_CPU0_SB_CB<7>")
	)
	(segment
		(start 429.300386 -237.760764)
		(end 428.982886 -237.760764)
		(width 0.18288)
		(layer "In11.Cu")
		(net "M_H_CPU0_SB_CB<7>")
	)
	(segment
		(start 416.016694 -238.510826)
		(end 414.968436 -238.510826)
		(width 0.18288)
		(layer "In11.Cu")
		(net "M_H_CPU0_SB_CB<7>")
	)
	(segment
		(start 427.462188 -238.733838)
		(end 426.423582 -238.733838)
		(width 0.18288)
		(layer "In11.Cu")
		(net "M_H_CPU0_SB_CB<7>")
	)
	(segment
		(start 373.772938 -243.545614)
		(end 373.398542 -243.555774)
		(width 0.088646)
		(layer "In11.Cu")
		(net "M_H_CPU0_SB_CB<7>")
	)
	(segment
		(start 428.789846 -238.345472)
		(end 428.596806 -238.538512)
		(width 0.18288)
		(layer "In11.Cu")
		(net "M_H_CPU0_SB_CB<7>")
	)
	(segment
		(start 433.679854 -239.1791)
		(end 432.944524 -238.764826)
		(width 0.18288)
		(layer "In11.Cu")
		(net "M_H_CPU0_SB_CB<7>")
	)
	(segment
		(start 447.814446 -239.349026)
		(end 447.068194 -239.349026)
		(width 0.18288)
		(layer "In11.Cu")
		(net "M_H_CPU0_SB_CB<7>")
	)
	(segment
		(start 428.789846 -237.953804)
		(end 428.789846 -238.345472)
		(width 0.18288)
		(layer "In11.Cu")
		(net "M_H_CPU0_SB_CB<7>")
	)
	(segment
		(start 374.819164 -243.607082)
		(end 374.804432 -243.598446)
		(width 0.088646)
		(layer "In11.Cu")
		(net "M_H_CPU0_SB_CB<7>")
	)
	(segment
		(start 427.657514 -238.538512)
		(end 427.462188 -238.733838)
		(width 0.18288)
		(layer "In11.Cu")
		(net "M_H_CPU0_SB_CB<7>")
	)
	(segment
		(start 414.968436 -238.510826)
		(end 413.351472 -239.46358)
		(width 0.18288)
		(layer "In11.Cu")
		(net "M_H_CPU0_SB_CB<7>")
	)
	(segment
		(start 417.769294 -238.739426)
		(end 416.245294 -238.739426)
		(width 0.18288)
		(layer "In11.Cu")
		(net "M_H_CPU0_SB_CB<7>")
	)
	(segment
		(start 434.716682 -239.1791)
		(end 433.679854 -239.1791)
		(width 0.18288)
		(layer "In11.Cu")
		(net "M_H_CPU0_SB_CB<7>")
	)
	(segment
		(start 379.518164 -243.607082)
		(end 379.503432 -243.598446)
		(width 0.088646)
		(layer "In11.Cu")
		(net "M_H_CPU0_SB_CB<7>")
	)
	(segment
		(start 389.043164 -244.482112)
		(end 388.23265 -244.482112)
		(width 0.088646)
		(layer "In11.Cu")
		(net "M_H_CPU0_SB_CB<7>")
	)
	(segment
		(start 416.245294 -238.739426)
		(end 416.016694 -238.510826)
		(width 0.18288)
		(layer "In11.Cu")
		(net "M_H_CPU0_SB_CB<7>")
	)
	(segment
		(start 426.228256 -238.538512)
		(end 421.958008 -238.538512)
		(width 0.18288)
		(layer "In11.Cu")
		(net "M_H_CPU0_SB_CB<7>")
	)
	(segment
		(start 382.337564 -243.607082)
		(end 382.322832 -243.598446)
		(width 0.088646)
		(layer "In11.Cu")
		(net "M_H_CPU0_SB_CB<7>")
	)
	(segment
		(start 387.811264 -244.060726)
		(end 384.683508 -244.060726)
		(width 0.088646)
		(layer "In11.Cu")
		(net "M_H_CPU0_SB_CB<7>")
	)
	(segment
		(start 426.423582 -238.733838)
		(end 426.228256 -238.538512)
		(width 0.18288)
		(layer "In11.Cu")
		(net "M_H_CPU0_SB_CB<7>")
	)
	(segment
		(start 406.057862 -241.165634)
		(end 399.878804 -241.165634)
		(width 0.18288)
		(layer "In11.Cu")
		(net "M_H_CPU0_SB_CB<7>")
	)
	(segment
		(start 432.082194 -238.764826)
		(end 431.677826 -238.538512)
		(width 0.18288)
		(layer "In11.Cu")
		(net "M_H_CPU0_SB_CB<7>")
	)
	(segment
		(start 384.683508 -244.060726)
		(end 384.28041 -243.657628)
		(width 0.088646)
		(layer "In11.Cu")
		(net "M_H_CPU0_SB_CB<7>")
	)
	(segment
		(start 375.758964 -243.607082)
		(end 375.744232 -243.598446)
		(width 0.088646)
		(layer "In11.Cu")
		(net "M_H_CPU0_SB_CB<7>")
	)
	(segment
		(start 439.18505 -240.241582)
		(end 439.003694 -240.060226)
		(width 0.18288)
		(layer "In11.Cu")
		(net "M_H_CPU0_SB_CB<7>")
	)
	(segment
		(start 454.99909 -238.961422)
		(end 454.654158 -239.099852)
		(width 0.18288)
		(layer "In11.Cu")
		(net "M_H_CPU0_SB_CB<7>")
	)
	(segment
		(start 391.108692 -244.33657)
		(end 390.96315 -244.482112)
		(width 0.18288)
		(layer "In11.Cu")
		(net "M_H_CPU0_SB_CB<7>")
	)
	(segment
		(start 437.012588 -239.390936)
		(end 434.928518 -239.390936)
		(width 0.18288)
		(layer "In11.Cu")
		(net "M_H_CPU0_SB_CB<7>")
	)
	(segment
		(start 421.958008 -238.538512)
		(end 421.105076 -239.391444)
		(width 0.18288)
		(layer "In11.Cu")
		(net "M_H_CPU0_SB_CB<7>")
	)
	(segment
		(start 399.878804 -241.165634)
		(end 396.707868 -244.33657)
		(width 0.18288)
		(layer "In11.Cu")
		(net "M_H_CPU0_SB_CB<7>")
	)
	(segment
		(start 445.639952 -239.628426)
		(end 442.991494 -239.628426)
		(width 0.18288)
		(layer "In11.Cu")
		(net "M_H_CPU0_SB_CB<7>")
	)
	(segment
		(start 373.864632 -243.598446)
		(end 373.772938 -243.545614)
		(width 0.088646)
		(layer "In11.Cu")
		(net "M_H_CPU0_SB_CB<7>")
	)
	(segment
		(start 429.493426 -237.953804)
		(end 429.300386 -237.760764)
		(width 0.18288)
		(layer "In11.Cu")
		(net "M_H_CPU0_SB_CB<7>")
	)
	(segment
		(start 420.046912 -239.391444)
		(end 419.928294 -239.272826)
		(width 0.18288)
		(layer "In11.Cu")
		(net "M_H_CPU0_SB_CB<7>")
	)
	(segment
		(start 429.493426 -238.345472)
		(end 429.493426 -237.953804)
		(width 0.18288)
		(layer "In11.Cu")
		(net "M_H_CPU0_SB_CB<7>")
	)
	(segment
		(start 413.351472 -239.46358)
		(end 412.499048 -239.46358)
		(width 0.18288)
		(layer "In11.Cu")
		(net "M_H_CPU0_SB_CB<7>")
	)
	(segment
		(start 450.18325 -240.242344)
		(end 450.060568 -240.365026)
		(width 0.18288)
		(layer "In11.Cu")
		(net "M_H_CPU0_SB_CB<7>")
	)
	(segment
		(start 450.060568 -240.365026)
		(end 448.830446 -240.365026)
		(width 0.18288)
		(layer "In11.Cu")
		(net "M_H_CPU0_SB_CB<7>")
	)
	(segment
		(start 412.307786 -239.272318)
		(end 408.580082 -239.272318)
		(width 0.18288)
		(layer "In11.Cu")
		(net "M_H_CPU0_SB_CB<7>")
	)
	(segment
		(start 432.944524 -238.764826)
		(end 432.082194 -238.764826)
		(width 0.18288)
		(layer "In11.Cu")
		(net "M_H_CPU0_SB_CB<7>")
	)
	(segment
		(start 439.003694 -240.060226)
		(end 437.681878 -240.060226)
		(width 0.18288)
		(layer "In11.Cu")
		(net "M_H_CPU0_SB_CB<7>")
	)
	(segment
		(start 455.011282 -238.966756)
		(end 454.99909 -238.961422)
		(width 0.18288)
		(layer "In11.Cu")
		(net "M_H_CPU0_SB_CB<7>")
	)
	(segment
		(start 419.928294 -239.272826)
		(end 418.302694 -239.272826)
		(width 0.18288)
		(layer "In11.Cu")
		(net "M_H_CPU0_SB_CB<7>")
	)
	(segment
		(start 421.105076 -239.391444)
		(end 420.046912 -239.391444)
		(width 0.18288)
		(layer "In11.Cu")
		(net "M_H_CPU0_SB_CB<7>")
	)
	(segment
		(start 437.681878 -240.060226)
		(end 437.012588 -239.390936)
		(width 0.18288)
		(layer "In11.Cu")
		(net "M_H_CPU0_SB_CB<7>")
	)
	(segment
		(start 418.302694 -239.272826)
		(end 417.769294 -238.739426)
		(width 0.18288)
		(layer "In11.Cu")
		(net "M_H_CPU0_SB_CB<7>")
	)
	(segment
		(start 448.830446 -240.365026)
		(end 447.814446 -239.349026)
		(width 0.18288)
		(layer "In11.Cu")
		(net "M_H_CPU0_SB_CB<7>")
	)
	(segment
		(start 371.404896 -243.108988)
		(end 371.32768 -243.108988)
		(width 0.088646)
		(layer "In11.Cu")
		(net "M_H_CPU0_SB_CB<7>")
	)
	(arc
		(start 382.888236 -243.598446)
		(mid 382.614037 -243.674281)
		(end 382.337564 -243.607082)
		(width 0.088646)
		(layer "In11.Cu")
		(net "M_H_CPU0_SB_CB<7>")
	)
	(arc
		(start 384.202432 -243.598446)
		(mid 384.015234 -243.548303)
		(end 383.828036 -243.598446)
		(width 0.088646)
		(layer "In11.Cu")
		(net "M_H_CPU0_SB_CB<7>")
	)
	(arc
		(start 381.383032 -243.598446)
		(mid 381.195834 -243.548303)
		(end 381.008636 -243.598446)
		(width 0.088646)
		(layer "In11.Cu")
		(net "M_H_CPU0_SB_CB<7>")
	)
	(arc
		(start 376.309636 -243.598446)
		(mid 376.035437 -243.674281)
		(end 375.758964 -243.607082)
		(width 0.088646)
		(layer "In11.Cu")
		(net "M_H_CPU0_SB_CB<7>")
	)
	(arc
		(start 381.948436 -243.598446)
		(mid 381.665734 -243.674222)
		(end 381.383032 -243.598446)
		(width 0.088646)
		(layer "In11.Cu")
		(net "M_H_CPU0_SB_CB<7>")
	)
	(arc
		(start 373.398542 -243.555774)
		(mid 373.168204 -243.521114)
		(end 372.964202 -243.408708)
		(width 0.088646)
		(layer "In11.Cu")
		(net "M_H_CPU0_SB_CB<7>")
	)
	(arc
		(start 371.993922 -243.364766)
		(mid 371.725989 -243.175652)
		(end 371.404896 -243.108988)
		(width 0.088646)
		(layer "In11.Cu")
		(net "M_H_CPU0_SB_CB<7>")
	)
	(arc
		(start 372.964202 -243.408708)
		(mid 372.731921 -243.325198)
		(end 372.498112 -243.40439)
		(width 0.088646)
		(layer "In11.Cu")
		(net "M_H_CPU0_SB_CB<7>")
	)
	(arc
		(start 375.369836 -243.598446)
		(mid 375.095637 -243.674281)
		(end 374.819164 -243.607082)
		(width 0.088646)
		(layer "In11.Cu")
		(net "M_H_CPU0_SB_CB<7>")
	)
	(arc
		(start 380.443232 -243.598446)
		(mid 380.256034 -243.548303)
		(end 380.068836 -243.598446)
		(width 0.088646)
		(layer "In11.Cu")
		(net "M_H_CPU0_SB_CB<7>")
	)
	(arc
		(start 379.503432 -243.598446)
		(mid 379.316234 -243.548303)
		(end 379.129036 -243.598446)
		(width 0.088646)
		(layer "In11.Cu")
		(net "M_H_CPU0_SB_CB<7>")
	)
	(arc
		(start 374.804432 -243.598446)
		(mid 374.617234 -243.548303)
		(end 374.430036 -243.598446)
		(width 0.088646)
		(layer "In11.Cu")
		(net "M_H_CPU0_SB_CB<7>")
	)
	(arc
		(start 378.563632 -243.598446)
		(mid 378.376434 -243.548303)
		(end 378.189236 -243.598446)
		(width 0.088646)
		(layer "In11.Cu")
		(net "M_H_CPU0_SB_CB<7>")
	)
	(arc
		(start 380.068836 -243.598446)
		(mid 379.794637 -243.674281)
		(end 379.518164 -243.607082)
		(width 0.088646)
		(layer "In11.Cu")
		(net "M_H_CPU0_SB_CB<7>")
	)
	(arc
		(start 381.008636 -243.598446)
		(mid 380.725934 -243.674222)
		(end 380.443232 -243.598446)
		(width 0.088646)
		(layer "In11.Cu")
		(net "M_H_CPU0_SB_CB<7>")
	)
	(arc
		(start 384.28041 -243.657628)
		(mid 384.24336 -243.625482)
		(end 384.202432 -243.598446)
		(width 0.088646)
		(layer "In11.Cu")
		(net "M_H_CPU0_SB_CB<7>")
	)
	(arc
		(start 372.498112 -243.40439)
		(mid 372.238341 -243.482448)
		(end 371.993922 -243.364766)
		(width 0.088646)
		(layer "In11.Cu")
		(net "M_H_CPU0_SB_CB<7>")
	)
	(arc
		(start 376.684032 -243.598446)
		(mid 376.496834 -243.548303)
		(end 376.309636 -243.598446)
		(width 0.088646)
		(layer "In11.Cu")
		(net "M_H_CPU0_SB_CB<7>")
	)
	(arc
		(start 377.249182 -243.598446)
		(mid 376.972623 -243.674189)
		(end 376.694446 -243.604542)
		(width 0.088646)
		(layer "In11.Cu")
		(net "M_H_CPU0_SB_CB<7>")
	)
	(arc
		(start 383.262632 -243.598446)
		(mid 383.075434 -243.548303)
		(end 382.888236 -243.598446)
		(width 0.088646)
		(layer "In11.Cu")
		(net "M_H_CPU0_SB_CB<7>")
	)
	(arc
		(start 377.623578 -243.598446)
		(mid 377.43638 -243.548303)
		(end 377.249182 -243.598446)
		(width 0.088646)
		(layer "In11.Cu")
		(net "M_H_CPU0_SB_CB<7>")
	)
	(arc
		(start 375.744232 -243.598446)
		(mid 375.557034 -243.548303)
		(end 375.369836 -243.598446)
		(width 0.088646)
		(layer "In11.Cu")
		(net "M_H_CPU0_SB_CB<7>")
	)
	(arc
		(start 378.189236 -243.598446)
		(mid 377.912423 -243.674316)
		(end 377.633992 -243.604542)
		(width 0.088646)
		(layer "In11.Cu")
		(net "M_H_CPU0_SB_CB<7>")
	)
	(arc
		(start 379.129036 -243.598446)
		(mid 378.854837 -243.674281)
		(end 378.578364 -243.607082)
		(width 0.088646)
		(layer "In11.Cu")
		(net "M_H_CPU0_SB_CB<7>")
	)
	(arc
		(start 374.430036 -243.598446)
		(mid 374.147334 -243.674222)
		(end 373.864632 -243.598446)
		(width 0.088646)
		(layer "In11.Cu")
		(net "M_H_CPU0_SB_CB<7>")
	)
	(arc
		(start 382.322832 -243.598446)
		(mid 382.135634 -243.548303)
		(end 381.948436 -243.598446)
		(width 0.088646)
		(layer "In11.Cu")
		(net "M_H_CPU0_SB_CB<7>")
	)
	(arc
		(start 383.828036 -243.598446)
		(mid 383.545334 -243.674222)
		(end 383.262632 -243.598446)
		(width 0.088646)
		(layer "In11.Cu")
		(net "M_H_CPU0_SB_CB<7>")
	)
	(segment
		(start 455.011282 -240.666778)
		(end 456.116182 -240.666778)
		(width 0.20066)
		(layer "F.Cu")
		(net "M_H_CPU0_SB_CB<6>")
	)
	(segment
		(start 456.116182 -240.666778)
		(end 457.814426 -240.666778)
		(width 0.20066)
		(layer "F.Cu")
		(net "M_H_CPU0_SB_CB<6>")
	)
	(segment
		(start 462.32572 -240.666778)
		(end 463.659982 -240.666778)
		(width 0.20066)
		(layer "F.Cu")
		(net "M_H_CPU0_SB_CB<6>")
	)
	(segment
		(start 461.689704 -240.41481)
		(end 462.073752 -240.41481)
		(width 0.20066)
		(layer "F.Cu")
		(net "M_H_CPU0_SB_CB<6>")
	)
	(segment
		(start 462.073752 -240.41481)
		(end 462.32572 -240.666778)
		(width 0.20066)
		(layer "F.Cu")
		(net "M_H_CPU0_SB_CB<6>")
	)
	(segment
		(start 461.251554 -241.103912)
		(end 461.455516 -240.89995)
		(width 0.20066)
		(layer "F.Cu")
		(net "M_H_CPU0_SB_CB<6>")
	)
	(segment
		(start 371.79758 -244.458744)
		(end 371.797834 -244.45849)
		(width 0.20066)
		(layer "F.Cu")
		(net "M_H_CPU0_SB_CB<6>")
	)
	(segment
		(start 458.538326 -241.098832)
		(end 458.543152 -241.098832)
		(width 0.101854)
		(layer "F.Cu")
		(net "M_H_CPU0_SB_CB<6>")
	)
	(segment
		(start 371.797834 -244.45849)
		(end 371.797834 -243.922804)
		(width 0.20066)
		(layer "F.Cu")
		(net "M_H_CPU0_SB_CB<6>")
	)
	(segment
		(start 458.550264 -241.09172)
		(end 460.558134 -241.09172)
		(width 0.1016)
		(layer "F.Cu")
		(net "M_H_CPU0_SB_CB<6>")
	)
	(segment
		(start 460.570326 -241.103912)
		(end 461.251554 -241.103912)
		(width 0.20066)
		(layer "F.Cu")
		(net "M_H_CPU0_SB_CB<6>")
	)
	(segment
		(start 461.455516 -240.89995)
		(end 461.455516 -240.648998)
		(width 0.20066)
		(layer "F.Cu")
		(net "M_H_CPU0_SB_CB<6>")
	)
	(segment
		(start 458.543152 -241.098832)
		(end 458.550264 -241.09172)
		(width 0.1016)
		(layer "F.Cu")
		(net "M_H_CPU0_SB_CB<6>")
	)
	(segment
		(start 461.455516 -240.648998)
		(end 461.689704 -240.41481)
		(width 0.20066)
		(layer "F.Cu")
		(net "M_H_CPU0_SB_CB<6>")
	)
	(segment
		(start 457.814426 -240.666778)
		(end 458.24648 -241.098832)
		(width 0.20066)
		(layer "F.Cu")
		(net "M_H_CPU0_SB_CB<6>")
	)
	(segment
		(start 460.558134 -241.09172)
		(end 460.570326 -241.103912)
		(width 0.1016)
		(layer "F.Cu")
		(net "M_H_CPU0_SB_CB<6>")
	)
	(segment
		(start 458.24648 -241.098832)
		(end 458.538326 -241.098832)
		(width 0.20066)
		(layer "F.Cu")
		(net "M_H_CPU0_SB_CB<6>")
	)
	(segment
		(start 440.146694 -241.94135)
		(end 439.614818 -241.94135)
		(width 0.18288)
		(layer "In11.Cu")
		(net "M_H_CPU0_SB_CB<6>")
	)
	(segment
		(start 372.110508 -243.922804)
		(end 371.797834 -243.922804)
		(width 0.088646)
		(layer "In11.Cu")
		(net "M_H_CPU0_SB_CB<6>")
	)
	(segment
		(start 391.510266 -245.498874)
		(end 389.043164 -245.498874)
		(width 0.18288)
		(layer "In11.Cu")
		(net "M_H_CPU0_SB_CB<6>")
	)
	(segment
		(start 445.213994 -241.330226)
		(end 443.664594 -241.330226)
		(width 0.18288)
		(layer "In11.Cu")
		(net "M_H_CPU0_SB_CB<6>")
	)
	(segment
		(start 382.418082 -244.412262)
		(end 382.407668 -244.418358)
		(width 0.088646)
		(layer "In11.Cu")
		(net "M_H_CPU0_SB_CB<6>")
	)
	(segment
		(start 439.511694 -241.838226)
		(end 437.809894 -241.838226)
		(width 0.18288)
		(layer "In11.Cu")
		(net "M_H_CPU0_SB_CB<6>")
	)
	(segment
		(start 448.42557 -241.66195)
		(end 447.741294 -240.977674)
		(width 0.18288)
		(layer "In11.Cu")
		(net "M_H_CPU0_SB_CB<6>")
	)
	(segment
		(start 446.941194 -240.977674)
		(end 445.213994 -241.330226)
		(width 0.18288)
		(layer "In11.Cu")
		(net "M_H_CPU0_SB_CB<6>")
	)
	(segment
		(start 455.011282 -240.666778)
		(end 455.003662 -240.664238)
		(width 0.18288)
		(layer "In11.Cu")
		(net "M_H_CPU0_SB_CB<6>")
	)
	(segment
		(start 417.464494 -240.466626)
		(end 416.118294 -240.466626)
		(width 0.18288)
		(layer "In11.Cu")
		(net "M_H_CPU0_SB_CB<6>")
	)
	(segment
		(start 443.664594 -241.330226)
		(end 442.445394 -241.076226)
		(width 0.18288)
		(layer "In11.Cu")
		(net "M_H_CPU0_SB_CB<6>")
	)
	(segment
		(start 412.714694 -241.050826)
		(end 409.463494 -241.050826)
		(width 0.18288)
		(layer "In11.Cu")
		(net "M_H_CPU0_SB_CB<6>")
	)
	(segment
		(start 423.47769 -240.38941)
		(end 423.326306 -240.238026)
		(width 0.18288)
		(layer "In11.Cu")
		(net "M_H_CPU0_SB_CB<6>")
	)
	(segment
		(start 422.49344 -240.238026)
		(end 421.639746 -241.09172)
		(width 0.18288)
		(layer "In11.Cu")
		(net "M_H_CPU0_SB_CB<6>")
	)
	(segment
		(start 451.179184 -241.941096)
		(end 451.169786 -241.942366)
		(width 0.18288)
		(layer "In11.Cu")
		(net "M_H_CPU0_SB_CB<6>")
	)
	(segment
		(start 416.118294 -240.466626)
		(end 415.788094 -240.136426)
		(width 0.18288)
		(layer "In11.Cu")
		(net "M_H_CPU0_SB_CB<6>")
	)
	(segment
		(start 427.735238 -240.238026)
		(end 427.488604 -240.48466)
		(width 0.18288)
		(layer "In11.Cu")
		(net "M_H_CPU0_SB_CB<6>")
	)
	(segment
		(start 379.598936 -244.412262)
		(end 379.588522 -244.418358)
		(width 0.088646)
		(layer "In11.Cu")
		(net "M_H_CPU0_SB_CB<6>")
	)
	(segment
		(start 436.069994 -241.091212)
		(end 435.05628 -241.091212)
		(width 0.18288)
		(layer "In11.Cu")
		(net "M_H_CPU0_SB_CB<6>")
	)
	(segment
		(start 413.892238 -241.228626)
		(end 412.892494 -241.228626)
		(width 0.18288)
		(layer "In11.Cu")
		(net "M_H_CPU0_SB_CB<6>")
	)
	(segment
		(start 420.096188 -241.09172)
		(end 419.926262 -240.921794)
		(width 0.18288)
		(layer "In11.Cu")
		(net "M_H_CPU0_SB_CB<6>")
	)
	(segment
		(start 419.926262 -240.921794)
		(end 417.919662 -240.921794)
		(width 0.18288)
		(layer "In11.Cu")
		(net "M_H_CPU0_SB_CB<6>")
	)
	(segment
		(start 427.488604 -240.48466)
		(end 426.09008 -240.48466)
		(width 0.18288)
		(layer "In11.Cu")
		(net "M_H_CPU0_SB_CB<6>")
	)
	(segment
		(start 398.721326 -245.36527)
		(end 398.568926 -245.21287)
		(width 0.18288)
		(layer "In11.Cu")
		(net "M_H_CPU0_SB_CB<6>")
	)
	(segment
		(start 451.169786 -241.942366)
		(end 450.219318 -241.942366)
		(width 0.18288)
		(layer "In11.Cu")
		(net "M_H_CPU0_SB_CB<6>")
	)
	(segment
		(start 375.839482 -244.412262)
		(end 375.829068 -244.418358)
		(width 0.088646)
		(layer "In11.Cu")
		(net "M_H_CPU0_SB_CB<6>")
	)
	(segment
		(start 387.023864 -245.686326)
		(end 386.639562 -245.302024)
		(width 0.088646)
		(layer "In11.Cu")
		(net "M_H_CPU0_SB_CB<6>")
	)
	(segment
		(start 381.478536 -244.412262)
		(end 381.468122 -244.418358)
		(width 0.088646)
		(layer "In11.Cu")
		(net "M_H_CPU0_SB_CB<6>")
	)
	(segment
		(start 439.614818 -241.94135)
		(end 439.511694 -241.838226)
		(width 0.18288)
		(layer "In11.Cu")
		(net "M_H_CPU0_SB_CB<6>")
	)
	(segment
		(start 454.654158 -240.831878)
		(end 452.756524 -241.741706)
		(width 0.18288)
		(layer "In11.Cu")
		(net "M_H_CPU0_SB_CB<6>")
	)
	(segment
		(start 450.145658 -242.016026)
		(end 449.443094 -242.016026)
		(width 0.18288)
		(layer "In11.Cu")
		(net "M_H_CPU0_SB_CB<6>")
	)
	(segment
		(start 434.888894 -240.923826)
		(end 433.326794 -240.923826)
		(width 0.18288)
		(layer "In11.Cu")
		(net "M_H_CPU0_SB_CB<6>")
	)
	(segment
		(start 376.779282 -244.412262)
		(end 376.76455 -244.420898)
		(width 0.088646)
		(layer "In11.Cu")
		(net "M_H_CPU0_SB_CB<6>")
	)
	(segment
		(start 373.020336 -244.412262)
		(end 373.009922 -244.418358)
		(width 0.088646)
		(layer "In11.Cu")
		(net "M_H_CPU0_SB_CB<6>")
	)
	(segment
		(start 373.959882 -244.412262)
		(end 373.949468 -244.418358)
		(width 0.088646)
		(layer "In11.Cu")
		(net "M_H_CPU0_SB_CB<6>")
	)
	(segment
		(start 430.862994 -240.238026)
		(end 427.735238 -240.238026)
		(width 0.18288)
		(layer "In11.Cu")
		(net "M_H_CPU0_SB_CB<6>")
	)
	(segment
		(start 398.568926 -245.21287)
		(end 391.79627 -245.21287)
		(width 0.18288)
		(layer "In11.Cu")
		(net "M_H_CPU0_SB_CB<6>")
	)
	(segment
		(start 432.712114 -240.649506)
		(end 430.862994 -240.238026)
		(width 0.18288)
		(layer "In11.Cu")
		(net "M_H_CPU0_SB_CB<6>")
	)
	(segment
		(start 440.376818 -241.711226)
		(end 440.146694 -241.94135)
		(width 0.18288)
		(layer "In11.Cu")
		(net "M_H_CPU0_SB_CB<6>")
	)
	(segment
		(start 452.756524 -241.741706)
		(end 451.179184 -241.941096)
		(width 0.18288)
		(layer "In11.Cu")
		(net "M_H_CPU0_SB_CB<6>")
	)
	(segment
		(start 441.279026 -241.711226)
		(end 440.376818 -241.711226)
		(width 0.18288)
		(layer "In11.Cu")
		(net "M_H_CPU0_SB_CB<6>")
	)
	(segment
		(start 389.043164 -245.498874)
		(end 387.668516 -245.498874)
		(width 0.088646)
		(layer "In11.Cu")
		(net "M_H_CPU0_SB_CB<6>")
	)
	(segment
		(start 383.919984 -244.755162)
		(end 383.919984 -244.73662)
		(width 0.088646)
		(layer "In11.Cu")
		(net "M_H_CPU0_SB_CB<6>")
	)
	(segment
		(start 378.658882 -244.412262)
		(end 378.64415 -244.420898)
		(width 0.088646)
		(layer "In11.Cu")
		(net "M_H_CPU0_SB_CB<6>")
	)
	(segment
		(start 449.306442 -241.968528)
		(end 448.42557 -241.66195)
		(width 0.18288)
		(layer "In11.Cu")
		(net "M_H_CPU0_SB_CB<6>")
	)
	(segment
		(start 450.219318 -241.942366)
		(end 450.145658 -242.016026)
		(width 0.18288)
		(layer "In11.Cu")
		(net "M_H_CPU0_SB_CB<6>")
	)
	(segment
		(start 417.919662 -240.921794)
		(end 417.464494 -240.466626)
		(width 0.18288)
		(layer "In11.Cu")
		(net "M_H_CPU0_SB_CB<6>")
	)
	(segment
		(start 423.326306 -240.238026)
		(end 422.49344 -240.238026)
		(width 0.18288)
		(layer "In11.Cu")
		(net "M_H_CPU0_SB_CB<6>")
	)
	(segment
		(start 383.358136 -244.412262)
		(end 383.347722 -244.418358)
		(width 0.088646)
		(layer "In11.Cu")
		(net "M_H_CPU0_SB_CB<6>")
	)
	(segment
		(start 408.470862 -242.043458)
		(end 408.470862 -243.618258)
		(width 0.18288)
		(layer "In11.Cu")
		(net "M_H_CPU0_SB_CB<6>")
	)
	(segment
		(start 414.984438 -240.136426)
		(end 413.892238 -241.228626)
		(width 0.18288)
		(layer "In11.Cu")
		(net "M_H_CPU0_SB_CB<6>")
	)
	(segment
		(start 425.845986 -240.240566)
		(end 424.258486 -240.240566)
		(width 0.18288)
		(layer "In11.Cu")
		(net "M_H_CPU0_SB_CB<6>")
	)
	(segment
		(start 391.79627 -245.21287)
		(end 391.510266 -245.498874)
		(width 0.18288)
		(layer "In11.Cu")
		(net "M_H_CPU0_SB_CB<6>")
	)
	(segment
		(start 424.258486 -240.240566)
		(end 424.109642 -240.38941)
		(width 0.18288)
		(layer "In11.Cu")
		(net "M_H_CPU0_SB_CB<6>")
	)
	(segment
		(start 412.892494 -241.228626)
		(end 412.714694 -241.050826)
		(width 0.18288)
		(layer "In11.Cu")
		(net "M_H_CPU0_SB_CB<6>")
	)
	(segment
		(start 447.741294 -240.977674)
		(end 446.941194 -240.977674)
		(width 0.18288)
		(layer "In11.Cu")
		(net "M_H_CPU0_SB_CB<6>")
	)
	(segment
		(start 415.788094 -240.136426)
		(end 414.984438 -240.136426)
		(width 0.18288)
		(layer "In11.Cu")
		(net "M_H_CPU0_SB_CB<6>")
	)
	(segment
		(start 441.914026 -241.076226)
		(end 441.279026 -241.711226)
		(width 0.18288)
		(layer "In11.Cu")
		(net "M_H_CPU0_SB_CB<6>")
	)
	(segment
		(start 435.05628 -241.091212)
		(end 434.888894 -240.923826)
		(width 0.18288)
		(layer "In11.Cu")
		(net "M_H_CPU0_SB_CB<6>")
	)
	(segment
		(start 409.463494 -241.050826)
		(end 408.470862 -242.043458)
		(width 0.18288)
		(layer "In11.Cu")
		(net "M_H_CPU0_SB_CB<6>")
	)
	(segment
		(start 449.443094 -242.016026)
		(end 449.306442 -241.968528)
		(width 0.18288)
		(layer "In11.Cu")
		(net "M_H_CPU0_SB_CB<6>")
	)
	(segment
		(start 421.639746 -241.09172)
		(end 420.096188 -241.09172)
		(width 0.18288)
		(layer "In11.Cu")
		(net "M_H_CPU0_SB_CB<6>")
	)
	(segment
		(start 455.003662 -240.664238)
		(end 454.654158 -240.831878)
		(width 0.18288)
		(layer "In11.Cu")
		(net "M_H_CPU0_SB_CB<6>")
	)
	(segment
		(start 386.639562 -245.302024)
		(end 384.485134 -245.302024)
		(width 0.088646)
		(layer "In11.Cu")
		(net "M_H_CPU0_SB_CB<6>")
	)
	(segment
		(start 426.09008 -240.48466)
		(end 425.845986 -240.240566)
		(width 0.18288)
		(layer "In11.Cu")
		(net "M_H_CPU0_SB_CB<6>")
	)
	(segment
		(start 372.17604 -243.988336)
		(end 372.110508 -243.922804)
		(width 0.088646)
		(layer "In11.Cu")
		(net "M_H_CPU0_SB_CB<6>")
	)
	(segment
		(start 424.109642 -240.38941)
		(end 423.47769 -240.38941)
		(width 0.18288)
		(layer "In11.Cu")
		(net "M_H_CPU0_SB_CB<6>")
	)
	(segment
		(start 374.899936 -244.412262)
		(end 374.889522 -244.418358)
		(width 0.088646)
		(layer "In11.Cu")
		(net "M_H_CPU0_SB_CB<6>")
	)
	(segment
		(start 442.445394 -241.076226)
		(end 441.914026 -241.076226)
		(width 0.18288)
		(layer "In11.Cu")
		(net "M_H_CPU0_SB_CB<6>")
	)
	(segment
		(start 406.72385 -245.36527)
		(end 398.721326 -245.36527)
		(width 0.18288)
		(layer "In11.Cu")
		(net "M_H_CPU0_SB_CB<6>")
	)
	(segment
		(start 383.741422 -244.417342)
		(end 383.732532 -244.412262)
		(width 0.088646)
		(layer "In11.Cu")
		(net "M_H_CPU0_SB_CB<6>")
	)
	(segment
		(start 387.668516 -245.498874)
		(end 387.481064 -245.686326)
		(width 0.088646)
		(layer "In11.Cu")
		(net "M_H_CPU0_SB_CB<6>")
	)
	(segment
		(start 437.809894 -241.838226)
		(end 436.069994 -241.091212)
		(width 0.18288)
		(layer "In11.Cu")
		(net "M_H_CPU0_SB_CB<6>")
	)
	(segment
		(start 380.538482 -244.412262)
		(end 380.528068 -244.418358)
		(width 0.088646)
		(layer "In11.Cu")
		(net "M_H_CPU0_SB_CB<6>")
	)
	(segment
		(start 408.470862 -243.618258)
		(end 406.72385 -245.36527)
		(width 0.18288)
		(layer "In11.Cu")
		(net "M_H_CPU0_SB_CB<6>")
	)
	(segment
		(start 387.481064 -245.686326)
		(end 387.023864 -245.686326)
		(width 0.088646)
		(layer "In11.Cu")
		(net "M_H_CPU0_SB_CB<6>")
	)
	(segment
		(start 433.326794 -240.923826)
		(end 432.712114 -240.649506)
		(width 0.18288)
		(layer "In11.Cu")
		(net "M_H_CPU0_SB_CB<6>")
	)
	(arc
		(start 372.454678 -244.412262)
		(mid 372.265165 -244.233297)
		(end 372.17604 -243.988336)
		(width 0.088646)
		(layer "In11.Cu")
		(net "M_H_CPU0_SB_CB<6>")
	)
	(arc
		(start 380.528068 -244.418358)
		(mid 380.24989 -244.488081)
		(end 379.973332 -244.412262)
		(width 0.088646)
		(layer "In11.Cu")
		(net "M_H_CPU0_SB_CB<6>")
	)
	(arc
		(start 381.468122 -244.418358)
		(mid 381.18969 -244.488204)
		(end 380.912878 -244.412262)
		(width 0.088646)
		(layer "In11.Cu")
		(net "M_H_CPU0_SB_CB<6>")
	)
	(arc
		(start 379.033278 -244.412262)
		(mid 378.84608 -244.362119)
		(end 378.658882 -244.412262)
		(width 0.088646)
		(layer "In11.Cu")
		(net "M_H_CPU0_SB_CB<6>")
	)
	(arc
		(start 376.76455 -244.420898)
		(mid 376.488075 -244.488218)
		(end 376.213878 -244.412262)
		(width 0.088646)
		(layer "In11.Cu")
		(net "M_H_CPU0_SB_CB<6>")
	)
	(arc
		(start 377.719082 -244.412262)
		(mid 377.43638 -244.488038)
		(end 377.153678 -244.412262)
		(width 0.088646)
		(layer "In11.Cu")
		(net "M_H_CPU0_SB_CB<6>")
	)
	(arc
		(start 375.829068 -244.418358)
		(mid 375.55089 -244.488081)
		(end 375.274332 -244.412262)
		(width 0.088646)
		(layer "In11.Cu")
		(net "M_H_CPU0_SB_CB<6>")
	)
	(arc
		(start 383.732532 -244.412262)
		(mid 383.545334 -244.362119)
		(end 383.358136 -244.412262)
		(width 0.088646)
		(layer "In11.Cu")
		(net "M_H_CPU0_SB_CB<6>")
	)
	(arc
		(start 382.792478 -244.412262)
		(mid 382.60528 -244.362119)
		(end 382.418082 -244.412262)
		(width 0.088646)
		(layer "In11.Cu")
		(net "M_H_CPU0_SB_CB<6>")
	)
	(arc
		(start 373.009922 -244.418358)
		(mid 372.73149 -244.488204)
		(end 372.454678 -244.412262)
		(width 0.088646)
		(layer "In11.Cu")
		(net "M_H_CPU0_SB_CB<6>")
	)
	(arc
		(start 383.919984 -244.73662)
		(mid 383.872305 -244.55372)
		(end 383.741422 -244.417342)
		(width 0.088646)
		(layer "In11.Cu")
		(net "M_H_CPU0_SB_CB<6>")
	)
	(arc
		(start 380.912878 -244.412262)
		(mid 380.72568 -244.362119)
		(end 380.538482 -244.412262)
		(width 0.088646)
		(layer "In11.Cu")
		(net "M_H_CPU0_SB_CB<6>")
	)
	(arc
		(start 376.213878 -244.412262)
		(mid 376.02668 -244.362119)
		(end 375.839482 -244.412262)
		(width 0.088646)
		(layer "In11.Cu")
		(net "M_H_CPU0_SB_CB<6>")
	)
	(arc
		(start 384.485134 -245.302024)
		(mid 384.091943 -245.142923)
		(end 383.919984 -244.755162)
		(width 0.088646)
		(layer "In11.Cu")
		(net "M_H_CPU0_SB_CB<6>")
	)
	(arc
		(start 374.334278 -244.412262)
		(mid 374.14708 -244.362119)
		(end 373.959882 -244.412262)
		(width 0.088646)
		(layer "In11.Cu")
		(net "M_H_CPU0_SB_CB<6>")
	)
	(arc
		(start 373.394732 -244.412262)
		(mid 373.207534 -244.362119)
		(end 373.020336 -244.412262)
		(width 0.088646)
		(layer "In11.Cu")
		(net "M_H_CPU0_SB_CB<6>")
	)
	(arc
		(start 381.852932 -244.412262)
		(mid 381.665734 -244.362119)
		(end 381.478536 -244.412262)
		(width 0.088646)
		(layer "In11.Cu")
		(net "M_H_CPU0_SB_CB<6>")
	)
	(arc
		(start 379.588522 -244.418358)
		(mid 379.31009 -244.488204)
		(end 379.033278 -244.412262)
		(width 0.088646)
		(layer "In11.Cu")
		(net "M_H_CPU0_SB_CB<6>")
	)
	(arc
		(start 374.889522 -244.418358)
		(mid 374.61109 -244.488204)
		(end 374.334278 -244.412262)
		(width 0.088646)
		(layer "In11.Cu")
		(net "M_H_CPU0_SB_CB<6>")
	)
	(arc
		(start 382.407668 -244.418358)
		(mid 382.12949 -244.488081)
		(end 381.852932 -244.412262)
		(width 0.088646)
		(layer "In11.Cu")
		(net "M_H_CPU0_SB_CB<6>")
	)
	(arc
		(start 375.274332 -244.412262)
		(mid 375.087134 -244.362119)
		(end 374.899936 -244.412262)
		(width 0.088646)
		(layer "In11.Cu")
		(net "M_H_CPU0_SB_CB<6>")
	)
	(arc
		(start 377.153678 -244.412262)
		(mid 376.96648 -244.362119)
		(end 376.779282 -244.412262)
		(width 0.088646)
		(layer "In11.Cu")
		(net "M_H_CPU0_SB_CB<6>")
	)
	(arc
		(start 373.949468 -244.418358)
		(mid 373.67129 -244.488081)
		(end 373.394732 -244.412262)
		(width 0.088646)
		(layer "In11.Cu")
		(net "M_H_CPU0_SB_CB<6>")
	)
	(arc
		(start 378.093478 -244.412262)
		(mid 377.90628 -244.362119)
		(end 377.719082 -244.412262)
		(width 0.088646)
		(layer "In11.Cu")
		(net "M_H_CPU0_SB_CB<6>")
	)
	(arc
		(start 379.973332 -244.412262)
		(mid 379.786134 -244.362119)
		(end 379.598936 -244.412262)
		(width 0.088646)
		(layer "In11.Cu")
		(net "M_H_CPU0_SB_CB<6>")
	)
	(arc
		(start 378.64415 -244.420898)
		(mid 378.367675 -244.488218)
		(end 378.093478 -244.412262)
		(width 0.088646)
		(layer "In11.Cu")
		(net "M_H_CPU0_SB_CB<6>")
	)
	(arc
		(start 383.347722 -244.418358)
		(mid 383.06929 -244.488204)
		(end 382.792478 -244.412262)
		(width 0.088646)
		(layer "In11.Cu")
		(net "M_H_CPU0_SB_CB<6>")
	)
	(segment
		(start 453.785478 -240.065306)
		(end 453.536812 -239.81664)
		(width 0.20066)
		(layer "F.Cu")
		(net "M_H_CPU0_SB_CB<5>")
	)
	(segment
		(start 454.448672 -239.509808)
		(end 454.448672 -239.877346)
		(width 0.20066)
		(layer "F.Cu")
		(net "M_H_CPU0_SB_CB<5>")
	)
	(segment
		(start 457.120244 -239.391698)
		(end 454.931526 -239.391698)
		(width 0.1016)
		(layer "F.Cu")
		(net "M_H_CPU0_SB_CB<5>")
	)
	(segment
		(start 457.126594 -239.385348)
		(end 457.120244 -239.391698)
		(width 0.1016)
		(layer "F.Cu")
		(net "M_H_CPU0_SB_CB<5>")
	)
	(segment
		(start 457.53655 -239.385348)
		(end 457.126594 -239.385348)
		(width 0.20066)
		(layer "F.Cu")
		(net "M_H_CPU0_SB_CB<5>")
	)
	(segment
		(start 454.448672 -239.877346)
		(end 454.260712 -240.065306)
		(width 0.20066)
		(layer "F.Cu")
		(net "M_H_CPU0_SB_CB<5>")
	)
	(segment
		(start 459.559914 -239.81664)
		(end 459.55966 -239.816894)
		(width 0.20066)
		(layer "F.Cu")
		(net "M_H_CPU0_SB_CB<5>")
	)
	(segment
		(start 459.55966 -239.816894)
		(end 457.968096 -239.816894)
		(width 0.20066)
		(layer "F.Cu")
		(net "M_H_CPU0_SB_CB<5>")
	)
	(segment
		(start 454.91146 -239.391698)
		(end 454.566782 -239.391698)
		(width 0.20066)
		(layer "F.Cu")
		(net "M_H_CPU0_SB_CB<5>")
	)
	(segment
		(start 452.016114 -239.81664)
		(end 450.911214 -239.81664)
		(width 0.20066)
		(layer "F.Cu")
		(net "M_H_CPU0_SB_CB<5>")
	)
	(segment
		(start 454.566782 -239.391698)
		(end 454.448672 -239.509808)
		(width 0.20066)
		(layer "F.Cu")
		(net "M_H_CPU0_SB_CB<5>")
	)
	(segment
		(start 457.968096 -239.816894)
		(end 457.53655 -239.385348)
		(width 0.20066)
		(layer "F.Cu")
		(net "M_H_CPU0_SB_CB<5>")
	)
	(segment
		(start 373.20728 -243.644674)
		(end 373.20728 -243.108988)
		(width 0.20066)
		(layer "F.Cu")
		(net "M_H_CPU0_SB_CB<5>")
	)
	(segment
		(start 454.260712 -240.065306)
		(end 453.785478 -240.065306)
		(width 0.20066)
		(layer "F.Cu")
		(net "M_H_CPU0_SB_CB<5>")
	)
	(segment
		(start 373.207534 -243.644928)
		(end 373.20728 -243.644674)
		(width 0.20066)
		(layer "F.Cu")
		(net "M_H_CPU0_SB_CB<5>")
	)
	(segment
		(start 454.931526 -239.391698)
		(end 454.91146 -239.391698)
		(width 0.101854)
		(layer "F.Cu")
		(net "M_H_CPU0_SB_CB<5>")
	)
	(segment
		(start 453.536812 -239.81664)
		(end 452.016114 -239.81664)
		(width 0.20066)
		(layer "F.Cu")
		(net "M_H_CPU0_SB_CB<5>")
	)
	(segment
		(start 412.460694 -238.612426)
		(end 409.209494 -238.612426)
		(width 0.18288)
		(layer "In11.Cu")
		(net "M_H_CPU0_SB_CB<5>")
	)
	(segment
		(start 439.171842 -238.94161)
		(end 438.978802 -238.74857)
		(width 0.18288)
		(layer "In11.Cu")
		(net "M_H_CPU0_SB_CB<5>")
	)
	(segment
		(start 373.960136 -243.433346)
		(end 373.814848 -243.349526)
		(width 0.088646)
		(layer "In11.Cu")
		(net "M_H_CPU0_SB_CB<5>")
	)
	(segment
		(start 450.019928 -239.155224)
		(end 450.019928 -238.73841)
		(width 0.18288)
		(layer "In11.Cu")
		(net "M_H_CPU0_SB_CB<5>")
	)
	(segment
		(start 418.97554 -238.347758)
		(end 418.870892 -238.09579)
		(width 0.18288)
		(layer "In11.Cu")
		(net "M_H_CPU0_SB_CB<5>")
	)
	(segment
		(start 444.434214 -239.117124)
		(end 444.241174 -238.924084)
		(width 0.18288)
		(layer "In11.Cu")
		(net "M_H_CPU0_SB_CB<5>")
	)
	(segment
		(start 380.538736 -243.433346)
		(end 380.528322 -243.42725)
		(width 0.088646)
		(layer "In11.Cu")
		(net "M_H_CPU0_SB_CB<5>")
	)
	(segment
		(start 373.337074 -243.238782)
		(end 373.20728 -243.108988)
		(width 0.088646)
		(layer "In11.Cu")
		(net "M_H_CPU0_SB_CB<5>")
	)
	(segment
		(start 418.72535 -237.112556)
		(end 418.473636 -237.21695)
		(width 0.18288)
		(layer "In11.Cu")
		(net "M_H_CPU0_SB_CB<5>")
	)
	(segment
		(start 409.209494 -238.612426)
		(end 408.980894 -238.383826)
		(width 0.18288)
		(layer "In11.Cu")
		(net "M_H_CPU0_SB_CB<5>")
	)
	(segment
		(start 439.171842 -239.32134)
		(end 439.171842 -238.94161)
		(width 0.18288)
		(layer "In11.Cu")
		(net "M_H_CPU0_SB_CB<5>")
	)
	(segment
		(start 445.137794 -238.206026)
		(end 444.944754 -238.399066)
		(width 0.18288)
		(layer "In11.Cu")
		(net "M_H_CPU0_SB_CB<5>")
	)
	(segment
		(start 438.978802 -238.74857)
		(end 438.661302 -238.74857)
		(width 0.18288)
		(layer "In11.Cu")
		(net "M_H_CPU0_SB_CB<5>")
	)
	(segment
		(start 441.140342 -238.815626)
		(end 440.56427 -239.391698)
		(width 0.18288)
		(layer "In11.Cu")
		(net "M_H_CPU0_SB_CB<5>")
	)
	(segment
		(start 417.968684 -237.930944)
		(end 417.257484 -237.636304)
		(width 0.18288)
		(layer "In11.Cu")
		(net "M_H_CPU0_SB_CB<5>")
	)
	(segment
		(start 443.220094 -238.206026)
		(end 442.610494 -238.815626)
		(width 0.18288)
		(layer "In11.Cu")
		(net "M_H_CPU0_SB_CB<5>")
	)
	(segment
		(start 375.839482 -243.433346)
		(end 375.82475 -243.42471)
		(width 0.088646)
		(layer "In11.Cu")
		(net "M_H_CPU0_SB_CB<5>")
	)
	(segment
		(start 373.814848 -243.349526)
		(end 373.64797 -243.358162)
		(width 0.088646)
		(layer "In11.Cu")
		(net "M_H_CPU0_SB_CB<5>")
	)
	(segment
		(start 419.624002 -238.616744)
		(end 418.97554 -238.347758)
		(width 0.18288)
		(layer "In11.Cu")
		(net "M_H_CPU0_SB_CB<5>")
	)
	(segment
		(start 419.019482 -237.234476)
		(end 418.72535 -237.112556)
		(width 0.18288)
		(layer "In11.Cu")
		(net "M_H_CPU0_SB_CB<5>")
	)
	(segment
		(start 406.962102 -239.463072)
		(end 400.729704 -239.463072)
		(width 0.18288)
		(layer "In11.Cu")
		(net "M_H_CPU0_SB_CB<5>")
	)
	(segment
		(start 408.980894 -238.383826)
		(end 408.041348 -238.383826)
		(width 0.18288)
		(layer "In11.Cu")
		(net "M_H_CPU0_SB_CB<5>")
	)
	(segment
		(start 400.729704 -239.463072)
		(end 396.218664 -243.974112)
		(width 0.18288)
		(layer "In11.Cu")
		(net "M_H_CPU0_SB_CB<5>")
	)
	(segment
		(start 444.944754 -238.399066)
		(end 444.944754 -238.924084)
		(width 0.18288)
		(layer "In11.Cu")
		(net "M_H_CPU0_SB_CB<5>")
	)
	(segment
		(start 439.738262 -239.391698)
		(end 439.61558 -239.51438)
		(width 0.18288)
		(layer "In11.Cu")
		(net "M_H_CPU0_SB_CB<5>")
	)
	(segment
		(start 418.473636 -237.21695)
		(end 418.220906 -237.826296)
		(width 0.18288)
		(layer "In11.Cu")
		(net "M_H_CPU0_SB_CB<5>")
	)
	(segment
		(start 449.123308 -239.388904)
		(end 448.743324 -239.388904)
		(width 0.18288)
		(layer "In11.Cu")
		(net "M_H_CPU0_SB_CB<5>")
	)
	(segment
		(start 438.275222 -239.51438)
		(end 437.899048 -239.51438)
		(width 0.18288)
		(layer "In11.Cu")
		(net "M_H_CPU0_SB_CB<5>")
	)
	(segment
		(start 387.890258 -243.87048)
		(end 384.762756 -243.87048)
		(width 0.088646)
		(layer "In11.Cu")
		(net "M_H_CPU0_SB_CB<5>")
	)
	(segment
		(start 432.48326 -237.227872)
		(end 425.785788 -237.227872)
		(width 0.18288)
		(layer "In11.Cu")
		(net "M_H_CPU0_SB_CB<5>")
	)
	(segment
		(start 450.911214 -239.543844)
		(end 450.715634 -239.348264)
		(width 0.18288)
		(layer "In11.Cu")
		(net "M_H_CPU0_SB_CB<5>")
	)
	(segment
		(start 439.61558 -239.51438)
		(end 439.364882 -239.51438)
		(width 0.18288)
		(layer "In11.Cu")
		(net "M_H_CPU0_SB_CB<5>")
	)
	(segment
		(start 414.51022 -237.926626)
		(end 414.065974 -238.370872)
		(width 0.18288)
		(layer "In11.Cu")
		(net "M_H_CPU0_SB_CB<5>")
	)
	(segment
		(start 418.220906 -237.826296)
		(end 417.968684 -237.930944)
		(width 0.18288)
		(layer "In11.Cu")
		(net "M_H_CPU0_SB_CB<5>")
	)
	(segment
		(start 421.866314 -237.692692)
		(end 421.017446 -238.54156)
		(width 0.18288)
		(layer "In11.Cu")
		(net "M_H_CPU0_SB_CB<5>")
	)
	(segment
		(start 378.658882 -243.433346)
		(end 378.64415 -243.42471)
		(width 0.088646)
		(layer "In11.Cu")
		(net "M_H_CPU0_SB_CB<5>")
	)
	(segment
		(start 440.56427 -239.391698)
		(end 439.738262 -239.391698)
		(width 0.18288)
		(layer "In11.Cu")
		(net "M_H_CPU0_SB_CB<5>")
	)
	(segment
		(start 449.826888 -238.54537)
		(end 449.509388 -238.54537)
		(width 0.18288)
		(layer "In11.Cu")
		(net "M_H_CPU0_SB_CB<5>")
	)
	(segment
		(start 408.041348 -238.383826)
		(end 406.962102 -239.463072)
		(width 0.18288)
		(layer "In11.Cu")
		(net "M_H_CPU0_SB_CB<5>")
	)
	(segment
		(start 449.316348 -238.73841)
		(end 449.316348 -239.195864)
		(width 0.18288)
		(layer "In11.Cu")
		(net "M_H_CPU0_SB_CB<5>")
	)
	(segment
		(start 434.945028 -238.657892)
		(end 433.91328 -238.657892)
		(width 0.18288)
		(layer "In11.Cu")
		(net "M_H_CPU0_SB_CB<5>")
	)
	(segment
		(start 425.785788 -237.227872)
		(end 425.320968 -237.692692)
		(width 0.18288)
		(layer "In11.Cu")
		(net "M_H_CPU0_SB_CB<5>")
	)
	(segment
		(start 389.043164 -243.974112)
		(end 387.99389 -243.974112)
		(width 0.088646)
		(layer "In11.Cu")
		(net "M_H_CPU0_SB_CB<5>")
	)
	(segment
		(start 447.944494 -238.590074)
		(end 446.499742 -238.590074)
		(width 0.18288)
		(layer "In11.Cu")
		(net "M_H_CPU0_SB_CB<5>")
	)
	(segment
		(start 444.944754 -238.924084)
		(end 444.751714 -239.117124)
		(width 0.18288)
		(layer "In11.Cu")
		(net "M_H_CPU0_SB_CB<5>")
	)
	(segment
		(start 387.99389 -243.974112)
		(end 387.890258 -243.87048)
		(width 0.088646)
		(layer "In11.Cu")
		(net "M_H_CPU0_SB_CB<5>")
	)
	(segment
		(start 418.870892 -238.09579)
		(end 419.123622 -237.48619)
		(width 0.18288)
		(layer "In11.Cu")
		(net "M_H_CPU0_SB_CB<5>")
	)
	(segment
		(start 444.751714 -239.117124)
		(end 444.434214 -239.117124)
		(width 0.18288)
		(layer "In11.Cu")
		(net "M_H_CPU0_SB_CB<5>")
	)
	(segment
		(start 446.499742 -238.590074)
		(end 446.115694 -238.206026)
		(width 0.18288)
		(layer "In11.Cu")
		(net "M_H_CPU0_SB_CB<5>")
	)
	(segment
		(start 415.797492 -237.926626)
		(end 414.51022 -237.926626)
		(width 0.18288)
		(layer "In11.Cu")
		(net "M_H_CPU0_SB_CB<5>")
	)
	(segment
		(start 436.92572 -238.541052)
		(end 435.061868 -238.541052)
		(width 0.18288)
		(layer "In11.Cu")
		(net "M_H_CPU0_SB_CB<5>")
	)
	(segment
		(start 448.743324 -239.388904)
		(end 447.944494 -238.590074)
		(width 0.18288)
		(layer "In11.Cu")
		(net "M_H_CPU0_SB_CB<5>")
	)
	(segment
		(start 383.358136 -243.433346)
		(end 383.347722 -243.42725)
		(width 0.088646)
		(layer "In11.Cu")
		(net "M_H_CPU0_SB_CB<5>")
	)
	(segment
		(start 437.899048 -239.51438)
		(end 436.92572 -238.541052)
		(width 0.18288)
		(layer "In11.Cu")
		(net "M_H_CPU0_SB_CB<5>")
	)
	(segment
		(start 442.610494 -238.815626)
		(end 441.140342 -238.815626)
		(width 0.18288)
		(layer "In11.Cu")
		(net "M_H_CPU0_SB_CB<5>")
	)
	(segment
		(start 450.019928 -238.73841)
		(end 449.826888 -238.54537)
		(width 0.18288)
		(layer "In11.Cu")
		(net "M_H_CPU0_SB_CB<5>")
	)
	(segment
		(start 384.762756 -243.87048)
		(end 384.414776 -243.5225)
		(width 0.088646)
		(layer "In11.Cu")
		(net "M_H_CPU0_SB_CB<5>")
	)
	(segment
		(start 425.320968 -237.692692)
		(end 421.866314 -237.692692)
		(width 0.18288)
		(layer "In11.Cu")
		(net "M_H_CPU0_SB_CB<5>")
	)
	(segment
		(start 419.123622 -237.48619)
		(end 419.019482 -237.234476)
		(width 0.18288)
		(layer "In11.Cu")
		(net "M_H_CPU0_SB_CB<5>")
	)
	(segment
		(start 433.91328 -238.657892)
		(end 432.48326 -237.227872)
		(width 0.18288)
		(layer "In11.Cu")
		(net "M_H_CPU0_SB_CB<5>")
	)
	(segment
		(start 449.316348 -239.195864)
		(end 449.123308 -239.388904)
		(width 0.18288)
		(layer "In11.Cu")
		(net "M_H_CPU0_SB_CB<5>")
	)
	(segment
		(start 449.509388 -238.54537)
		(end 449.316348 -238.73841)
		(width 0.18288)
		(layer "In11.Cu")
		(net "M_H_CPU0_SB_CB<5>")
	)
	(segment
		(start 446.115694 -238.206026)
		(end 445.137794 -238.206026)
		(width 0.18288)
		(layer "In11.Cu")
		(net "M_H_CPU0_SB_CB<5>")
	)
	(segment
		(start 444.241174 -238.399066)
		(end 444.048134 -238.206026)
		(width 0.18288)
		(layer "In11.Cu")
		(net "M_H_CPU0_SB_CB<5>")
	)
	(segment
		(start 382.418082 -243.433346)
		(end 382.407668 -243.42725)
		(width 0.088646)
		(layer "In11.Cu")
		(net "M_H_CPU0_SB_CB<5>")
	)
	(segment
		(start 450.212968 -239.348264)
		(end 450.019928 -239.155224)
		(width 0.18288)
		(layer "In11.Cu")
		(net "M_H_CPU0_SB_CB<5>")
	)
	(segment
		(start 396.218664 -243.974112)
		(end 389.043164 -243.974112)
		(width 0.18288)
		(layer "In11.Cu")
		(net "M_H_CPU0_SB_CB<5>")
	)
	(segment
		(start 420.206932 -238.54156)
		(end 420.131748 -238.616744)
		(width 0.18288)
		(layer "In11.Cu")
		(net "M_H_CPU0_SB_CB<5>")
	)
	(segment
		(start 414.065974 -238.370872)
		(end 412.702248 -238.370872)
		(width 0.18288)
		(layer "In11.Cu")
		(net "M_H_CPU0_SB_CB<5>")
	)
	(segment
		(start 444.048134 -238.206026)
		(end 443.220094 -238.206026)
		(width 0.18288)
		(layer "In11.Cu")
		(net "M_H_CPU0_SB_CB<5>")
	)
	(segment
		(start 438.468262 -238.94161)
		(end 438.468262 -239.32134)
		(width 0.18288)
		(layer "In11.Cu")
		(net "M_H_CPU0_SB_CB<5>")
	)
	(segment
		(start 379.598682 -243.433346)
		(end 379.58395 -243.42471)
		(width 0.088646)
		(layer "In11.Cu")
		(net "M_H_CPU0_SB_CB<5>")
	)
	(segment
		(start 417.257484 -237.636304)
		(end 415.797492 -237.926626)
		(width 0.18288)
		(layer "In11.Cu")
		(net "M_H_CPU0_SB_CB<5>")
	)
	(segment
		(start 438.661302 -238.74857)
		(end 438.468262 -238.94161)
		(width 0.18288)
		(layer "In11.Cu")
		(net "M_H_CPU0_SB_CB<5>")
	)
	(segment
		(start 376.779282 -243.433346)
		(end 376.76455 -243.42471)
		(width 0.088646)
		(layer "In11.Cu")
		(net "M_H_CPU0_SB_CB<5>")
	)
	(segment
		(start 450.911214 -239.81664)
		(end 450.911214 -239.543844)
		(width 0.18288)
		(layer "In11.Cu")
		(net "M_H_CPU0_SB_CB<5>")
	)
	(segment
		(start 420.131748 -238.616744)
		(end 419.624002 -238.616744)
		(width 0.18288)
		(layer "In11.Cu")
		(net "M_H_CPU0_SB_CB<5>")
	)
	(segment
		(start 439.364882 -239.51438)
		(end 439.171842 -239.32134)
		(width 0.18288)
		(layer "In11.Cu")
		(net "M_H_CPU0_SB_CB<5>")
	)
	(segment
		(start 412.702248 -238.370872)
		(end 412.460694 -238.612426)
		(width 0.18288)
		(layer "In11.Cu")
		(net "M_H_CPU0_SB_CB<5>")
	)
	(segment
		(start 374.899682 -243.433346)
		(end 374.889268 -243.42725)
		(width 0.088646)
		(layer "In11.Cu")
		(net "M_H_CPU0_SB_CB<5>")
	)
	(segment
		(start 450.715634 -239.348264)
		(end 450.212968 -239.348264)
		(width 0.18288)
		(layer "In11.Cu")
		(net "M_H_CPU0_SB_CB<5>")
	)
	(segment
		(start 421.017446 -238.54156)
		(end 420.206932 -238.54156)
		(width 0.18288)
		(layer "In11.Cu")
		(net "M_H_CPU0_SB_CB<5>")
	)
	(segment
		(start 435.061868 -238.541052)
		(end 434.945028 -238.657892)
		(width 0.18288)
		(layer "In11.Cu")
		(net "M_H_CPU0_SB_CB<5>")
	)
	(segment
		(start 444.241174 -238.924084)
		(end 444.241174 -238.399066)
		(width 0.18288)
		(layer "In11.Cu")
		(net "M_H_CPU0_SB_CB<5>")
	)
	(segment
		(start 438.468262 -239.32134)
		(end 438.275222 -239.51438)
		(width 0.18288)
		(layer "In11.Cu")
		(net "M_H_CPU0_SB_CB<5>")
	)
	(arc
		(start 379.58395 -243.42471)
		(mid 379.307475 -243.35739)
		(end 379.033278 -243.433346)
		(width 0.088646)
		(layer "In11.Cu")
		(net "M_H_CPU0_SB_CB<5>")
	)
	(arc
		(start 375.274078 -243.433346)
		(mid 375.08688 -243.483489)
		(end 374.899682 -243.433346)
		(width 0.088646)
		(layer "In11.Cu")
		(net "M_H_CPU0_SB_CB<5>")
	)
	(arc
		(start 376.213878 -243.433346)
		(mid 376.02668 -243.483489)
		(end 375.839482 -243.433346)
		(width 0.088646)
		(layer "In11.Cu")
		(net "M_H_CPU0_SB_CB<5>")
	)
	(arc
		(start 376.76455 -243.42471)
		(mid 376.488075 -243.35739)
		(end 376.213878 -243.433346)
		(width 0.088646)
		(layer "In11.Cu")
		(net "M_H_CPU0_SB_CB<5>")
	)
	(arc
		(start 383.347722 -243.42725)
		(mid 383.06929 -243.357404)
		(end 382.792478 -243.433346)
		(width 0.088646)
		(layer "In11.Cu")
		(net "M_H_CPU0_SB_CB<5>")
	)
	(arc
		(start 377.719082 -243.433346)
		(mid 377.43638 -243.35757)
		(end 377.153678 -243.433346)
		(width 0.088646)
		(layer "In11.Cu")
		(net "M_H_CPU0_SB_CB<5>")
	)
	(arc
		(start 373.64797 -243.358162)
		(mid 373.479839 -243.331503)
		(end 373.337074 -243.238782)
		(width 0.088646)
		(layer "In11.Cu")
		(net "M_H_CPU0_SB_CB<5>")
	)
	(arc
		(start 380.913132 -243.433346)
		(mid 380.725934 -243.483489)
		(end 380.538736 -243.433346)
		(width 0.088646)
		(layer "In11.Cu")
		(net "M_H_CPU0_SB_CB<5>")
	)
	(arc
		(start 375.82475 -243.42471)
		(mid 375.548275 -243.35739)
		(end 375.274078 -243.433346)
		(width 0.088646)
		(layer "In11.Cu")
		(net "M_H_CPU0_SB_CB<5>")
	)
	(arc
		(start 379.973078 -243.433346)
		(mid 379.78588 -243.483489)
		(end 379.598682 -243.433346)
		(width 0.088646)
		(layer "In11.Cu")
		(net "M_H_CPU0_SB_CB<5>")
	)
	(arc
		(start 384.361944 -243.476272)
		(mid 384.330672 -243.453717)
		(end 384.297936 -243.433346)
		(width 0.088646)
		(layer "In11.Cu")
		(net "M_H_CPU0_SB_CB<5>")
	)
	(arc
		(start 379.033278 -243.433346)
		(mid 378.84608 -243.483489)
		(end 378.658882 -243.433346)
		(width 0.088646)
		(layer "In11.Cu")
		(net "M_H_CPU0_SB_CB<5>")
	)
	(arc
		(start 381.478536 -243.433346)
		(mid 381.195834 -243.35757)
		(end 380.913132 -243.433346)
		(width 0.088646)
		(layer "In11.Cu")
		(net "M_H_CPU0_SB_CB<5>")
	)
	(arc
		(start 381.852932 -243.433346)
		(mid 381.665734 -243.483489)
		(end 381.478536 -243.433346)
		(width 0.088646)
		(layer "In11.Cu")
		(net "M_H_CPU0_SB_CB<5>")
	)
	(arc
		(start 383.732532 -243.433346)
		(mid 383.545334 -243.483489)
		(end 383.358136 -243.433346)
		(width 0.088646)
		(layer "In11.Cu")
		(net "M_H_CPU0_SB_CB<5>")
	)
	(arc
		(start 378.64415 -243.42471)
		(mid 378.367675 -243.35739)
		(end 378.093478 -243.433346)
		(width 0.088646)
		(layer "In11.Cu")
		(net "M_H_CPU0_SB_CB<5>")
	)
	(arc
		(start 380.528322 -243.42725)
		(mid 380.24989 -243.357404)
		(end 379.973078 -243.433346)
		(width 0.088646)
		(layer "In11.Cu")
		(net "M_H_CPU0_SB_CB<5>")
	)
	(arc
		(start 374.334532 -243.433346)
		(mid 374.147334 -243.483489)
		(end 373.960136 -243.433346)
		(width 0.088646)
		(layer "In11.Cu")
		(net "M_H_CPU0_SB_CB<5>")
	)
	(arc
		(start 384.297936 -243.433346)
		(mid 384.015234 -243.35757)
		(end 383.732532 -243.433346)
		(width 0.088646)
		(layer "In11.Cu")
		(net "M_H_CPU0_SB_CB<5>")
	)
	(arc
		(start 378.093478 -243.433346)
		(mid 377.90628 -243.483489)
		(end 377.719082 -243.433346)
		(width 0.088646)
		(layer "In11.Cu")
		(net "M_H_CPU0_SB_CB<5>")
	)
	(arc
		(start 384.414776 -243.5225)
		(mid 384.389078 -243.498566)
		(end 384.361944 -243.476272)
		(width 0.088646)
		(layer "In11.Cu")
		(net "M_H_CPU0_SB_CB<5>")
	)
	(arc
		(start 377.153678 -243.433346)
		(mid 376.96648 -243.483489)
		(end 376.779282 -243.433346)
		(width 0.088646)
		(layer "In11.Cu")
		(net "M_H_CPU0_SB_CB<5>")
	)
	(arc
		(start 374.889268 -243.42725)
		(mid 374.61109 -243.357527)
		(end 374.334532 -243.433346)
		(width 0.088646)
		(layer "In11.Cu")
		(net "M_H_CPU0_SB_CB<5>")
	)
	(arc
		(start 382.407668 -243.42725)
		(mid 382.12949 -243.357527)
		(end 381.852932 -243.433346)
		(width 0.088646)
		(layer "In11.Cu")
		(net "M_H_CPU0_SB_CB<5>")
	)
	(arc
		(start 382.792478 -243.433346)
		(mid 382.60528 -243.483489)
		(end 382.418082 -243.433346)
		(width 0.088646)
		(layer "In11.Cu")
		(net "M_H_CPU0_SB_CB<5>")
	)
	(segment
		(start 457.126594 -241.08537)
		(end 457.120244 -241.09172)
		(width 0.1016)
		(layer "F.Cu")
		(net "M_H_CPU0_SB_CB<4>")
	)
	(segment
		(start 453.785478 -241.765328)
		(end 453.536812 -241.516662)
		(width 0.20066)
		(layer "F.Cu")
		(net "M_H_CPU0_SB_CB<4>")
	)
	(segment
		(start 454.260712 -241.765328)
		(end 453.785478 -241.765328)
		(width 0.20066)
		(layer "F.Cu")
		(net "M_H_CPU0_SB_CB<4>")
	)
	(segment
		(start 459.55966 -241.516916)
		(end 457.968096 -241.516916)
		(width 0.20066)
		(layer "F.Cu")
		(net "M_H_CPU0_SB_CB<4>")
	)
	(segment
		(start 457.968096 -241.516916)
		(end 457.53655 -241.08537)
		(width 0.20066)
		(layer "F.Cu")
		(net "M_H_CPU0_SB_CB<4>")
	)
	(segment
		(start 459.559914 -241.516662)
		(end 459.55966 -241.516916)
		(width 0.20066)
		(layer "F.Cu")
		(net "M_H_CPU0_SB_CB<4>")
	)
	(segment
		(start 372.737634 -244.45849)
		(end 372.737634 -243.922804)
		(width 0.20066)
		(layer "F.Cu")
		(net "M_H_CPU0_SB_CB<4>")
	)
	(segment
		(start 454.448672 -241.20983)
		(end 454.448672 -241.577368)
		(width 0.20066)
		(layer "F.Cu")
		(net "M_H_CPU0_SB_CB<4>")
	)
	(segment
		(start 454.448672 -241.577368)
		(end 454.260712 -241.765328)
		(width 0.20066)
		(layer "F.Cu")
		(net "M_H_CPU0_SB_CB<4>")
	)
	(segment
		(start 454.566782 -241.09172)
		(end 454.448672 -241.20983)
		(width 0.20066)
		(layer "F.Cu")
		(net "M_H_CPU0_SB_CB<4>")
	)
	(segment
		(start 452.016114 -241.516662)
		(end 450.911214 -241.516662)
		(width 0.20066)
		(layer "F.Cu")
		(net "M_H_CPU0_SB_CB<4>")
	)
	(segment
		(start 457.53655 -241.08537)
		(end 457.126594 -241.08537)
		(width 0.20066)
		(layer "F.Cu")
		(net "M_H_CPU0_SB_CB<4>")
	)
	(segment
		(start 457.120244 -241.09172)
		(end 454.95845 -241.09172)
		(width 0.1016)
		(layer "F.Cu")
		(net "M_H_CPU0_SB_CB<4>")
	)
	(segment
		(start 372.73738 -244.458744)
		(end 372.737634 -244.45849)
		(width 0.20066)
		(layer "F.Cu")
		(net "M_H_CPU0_SB_CB<4>")
	)
	(segment
		(start 454.95845 -241.09172)
		(end 454.91146 -241.09172)
		(width 0.101854)
		(layer "F.Cu")
		(net "M_H_CPU0_SB_CB<4>")
	)
	(segment
		(start 454.91146 -241.09172)
		(end 454.566782 -241.09172)
		(width 0.20066)
		(layer "F.Cu")
		(net "M_H_CPU0_SB_CB<4>")
	)
	(segment
		(start 453.536812 -241.516662)
		(end 452.016114 -241.516662)
		(width 0.20066)
		(layer "F.Cu")
		(net "M_H_CPU0_SB_CB<4>")
	)
	(segment
		(start 441.444126 -240.504726)
		(end 440.857386 -241.091466)
		(width 0.18288)
		(layer "In11.Cu")
		(net "M_H_CPU0_SB_CB<4>")
	)
	(segment
		(start 372.550436 -244.247162)
		(end 372.541546 -244.242082)
		(width 0.088646)
		(layer "In11.Cu")
		(net "M_H_CPU0_SB_CB<4>")
	)
	(segment
		(start 429.035718 -238.931196)
		(end 428.842678 -239.124236)
		(width 0.18288)
		(layer "In11.Cu")
		(net "M_H_CPU0_SB_CB<4>")
	)
	(segment
		(start 418.496496 -240.404396)
		(end 417.41471 -239.32261)
		(width 0.18288)
		(layer "In11.Cu")
		(net "M_H_CPU0_SB_CB<4>")
	)
	(segment
		(start 419.990524 -240.404396)
		(end 418.496496 -240.404396)
		(width 0.18288)
		(layer "In11.Cu")
		(net "M_H_CPU0_SB_CB<4>")
	)
	(segment
		(start 440.857386 -241.091466)
		(end 438.937654 -241.091466)
		(width 0.18288)
		(layer "In11.Cu")
		(net "M_H_CPU0_SB_CB<4>")
	)
	(segment
		(start 386.760212 -245.111778)
		(end 384.485134 -245.111778)
		(width 0.088646)
		(layer "In11.Cu")
		(net "M_H_CPU0_SB_CB<4>")
	)
	(segment
		(start 416.219894 -239.552226)
		(end 414.619694 -239.552226)
		(width 0.18288)
		(layer "In11.Cu")
		(net "M_H_CPU0_SB_CB<4>")
	)
	(segment
		(start 448.466718 -240.898426)
		(end 447.936366 -240.368074)
		(width 0.18288)
		(layer "In11.Cu")
		(net "M_H_CPU0_SB_CB<4>")
	)
	(segment
		(start 442.661294 -240.161826)
		(end 442.318394 -240.504726)
		(width 0.18288)
		(layer "In11.Cu")
		(net "M_H_CPU0_SB_CB<4>")
	)
	(segment
		(start 429.353218 -238.931196)
		(end 429.035718 -238.931196)
		(width 0.18288)
		(layer "In11.Cu")
		(net "M_H_CPU0_SB_CB<4>")
	)
	(segment
		(start 375.758964 -244.238526)
		(end 375.744232 -244.247162)
		(width 0.088646)
		(layer "In11.Cu")
		(net "M_H_CPU0_SB_CB<4>")
	)
	(segment
		(start 384.110484 -244.73662)
		(end 384.110484 -244.726714)
		(width 0.088646)
		(layer "In11.Cu")
		(net "M_H_CPU0_SB_CB<4>")
	)
	(segment
		(start 429.546258 -239.124236)
		(end 429.353218 -238.931196)
		(width 0.18288)
		(layer "In11.Cu")
		(net "M_H_CPU0_SB_CB<4>")
	)
	(segment
		(start 427.950884 -239.70488)
		(end 427.498002 -239.251998)
		(width 0.18288)
		(layer "In11.Cu")
		(net "M_H_CPU0_SB_CB<4>")
	)
	(segment
		(start 412.409894 -240.441226)
		(end 409.234894 -240.441226)
		(width 0.18288)
		(layer "In11.Cu")
		(net "M_H_CPU0_SB_CB<4>")
	)
	(segment
		(start 389.043164 -244.990112)
		(end 387.67385 -244.990112)
		(width 0.088646)
		(layer "In11.Cu")
		(net "M_H_CPU0_SB_CB<4>")
	)
	(segment
		(start 431.659284 -239.70488)
		(end 429.739298 -239.70488)
		(width 0.18288)
		(layer "In11.Cu")
		(net "M_H_CPU0_SB_CB<4>")
	)
	(segment
		(start 406.358852 -243.750846)
		(end 406.358852 -242.033806)
		(width 0.18288)
		(layer "In11.Cu")
		(net "M_H_CPU0_SB_CB<4>")
	)
	(segment
		(start 450.747638 -241.097562)
		(end 450.26707 -240.898426)
		(width 0.18288)
		(layer "In11.Cu")
		(net "M_H_CPU0_SB_CB<4>")
	)
	(segment
		(start 407.062432 -243.750846)
		(end 406.869392 -243.943886)
		(width 0.18288)
		(layer "In11.Cu")
		(net "M_H_CPU0_SB_CB<4>")
	)
	(segment
		(start 446.550542 -240.368074)
		(end 446.344294 -240.161826)
		(width 0.18288)
		(layer "In11.Cu")
		(net "M_H_CPU0_SB_CB<4>")
	)
	(segment
		(start 450.911214 -241.261138)
		(end 450.747638 -241.097562)
		(width 0.18288)
		(layer "In11.Cu")
		(net "M_H_CPU0_SB_CB<4>")
	)
	(segment
		(start 397.074898 -244.78869)
		(end 391.457688 -244.78869)
		(width 0.18288)
		(layer "In11.Cu")
		(net "M_H_CPU0_SB_CB<4>")
	)
	(segment
		(start 378.578364 -244.238526)
		(end 378.563632 -244.247162)
		(width 0.088646)
		(layer "In11.Cu")
		(net "M_H_CPU0_SB_CB<4>")
	)
	(segment
		(start 447.936366 -240.368074)
		(end 446.550542 -240.368074)
		(width 0.18288)
		(layer "In11.Cu")
		(net "M_H_CPU0_SB_CB<4>")
	)
	(segment
		(start 414.187894 -239.984026)
		(end 412.867094 -239.984026)
		(width 0.18288)
		(layer "In11.Cu")
		(net "M_H_CPU0_SB_CB<4>")
	)
	(segment
		(start 406.165812 -241.840766)
		(end 400.022822 -241.840766)
		(width 0.18288)
		(layer "In11.Cu")
		(net "M_H_CPU0_SB_CB<4>")
	)
	(segment
		(start 434.863494 -240.390426)
		(end 433.733194 -240.390426)
		(width 0.18288)
		(layer "In11.Cu")
		(net "M_H_CPU0_SB_CB<4>")
	)
	(segment
		(start 431.999136 -239.365028)
		(end 431.659284 -239.70488)
		(width 0.18288)
		(layer "In11.Cu")
		(net "M_H_CPU0_SB_CB<4>")
	)
	(segment
		(start 427.498002 -239.251998)
		(end 425.356528 -239.251998)
		(width 0.18288)
		(layer "In11.Cu")
		(net "M_H_CPU0_SB_CB<4>")
	)
	(segment
		(start 432.707796 -239.365028)
		(end 431.999136 -239.365028)
		(width 0.18288)
		(layer "In11.Cu")
		(net "M_H_CPU0_SB_CB<4>")
	)
	(segment
		(start 438.004712 -241.279426)
		(end 436.966106 -240.24082)
		(width 0.18288)
		(layer "In11.Cu")
		(net "M_H_CPU0_SB_CB<4>")
	)
	(segment
		(start 412.867094 -239.984026)
		(end 412.409894 -240.441226)
		(width 0.18288)
		(layer "In11.Cu")
		(net "M_H_CPU0_SB_CB<4>")
	)
	(segment
		(start 424.026584 -239.391952)
		(end 423.692574 -239.725962)
		(width 0.18288)
		(layer "In11.Cu")
		(net "M_H_CPU0_SB_CB<4>")
	)
	(segment
		(start 428.842678 -239.51184)
		(end 428.649638 -239.70488)
		(width 0.18288)
		(layer "In11.Cu")
		(net "M_H_CPU0_SB_CB<4>")
	)
	(segment
		(start 438.749694 -241.279426)
		(end 438.004712 -241.279426)
		(width 0.18288)
		(layer "In11.Cu")
		(net "M_H_CPU0_SB_CB<4>")
	)
	(segment
		(start 372.367556 -243.980208)
		(end 372.42496 -243.922804)
		(width 0.088646)
		(layer "In11.Cu")
		(net "M_H_CPU0_SB_CB<4>")
	)
	(segment
		(start 421.53332 -239.725962)
		(end 421.017954 -240.241328)
		(width 0.18288)
		(layer "In11.Cu")
		(net "M_H_CPU0_SB_CB<4>")
	)
	(segment
		(start 416.44951 -239.32261)
		(end 416.219894 -239.552226)
		(width 0.18288)
		(layer "In11.Cu")
		(net "M_H_CPU0_SB_CB<4>")
	)
	(segment
		(start 428.842678 -239.124236)
		(end 428.842678 -239.51184)
		(width 0.18288)
		(layer "In11.Cu")
		(net "M_H_CPU0_SB_CB<4>")
	)
	(segment
		(start 421.017954 -240.241328)
		(end 420.153592 -240.241328)
		(width 0.18288)
		(layer "In11.Cu")
		(net "M_H_CPU0_SB_CB<4>")
	)
	(segment
		(start 407.062432 -242.033806)
		(end 407.062432 -243.750846)
		(width 0.18288)
		(layer "In11.Cu")
		(net "M_H_CPU0_SB_CB<4>")
	)
	(segment
		(start 406.551892 -243.943886)
		(end 406.358852 -243.750846)
		(width 0.18288)
		(layer "In11.Cu")
		(net "M_H_CPU0_SB_CB<4>")
	)
	(segment
		(start 373.879364 -244.238526)
		(end 373.864632 -244.247162)
		(width 0.088646)
		(layer "In11.Cu")
		(net "M_H_CPU0_SB_CB<4>")
	)
	(segment
		(start 433.733194 -240.390426)
		(end 432.707796 -239.365028)
		(width 0.18288)
		(layer "In11.Cu")
		(net "M_H_CPU0_SB_CB<4>")
	)
	(segment
		(start 436.966106 -240.24082)
		(end 435.0131 -240.24082)
		(width 0.18288)
		(layer "In11.Cu")
		(net "M_H_CPU0_SB_CB<4>")
	)
	(segment
		(start 387.67385 -244.990112)
		(end 387.557264 -244.873526)
		(width 0.088646)
		(layer "In11.Cu")
		(net "M_H_CPU0_SB_CB<4>")
	)
	(segment
		(start 372.42496 -243.922804)
		(end 372.737634 -243.922804)
		(width 0.088646)
		(layer "In11.Cu")
		(net "M_H_CPU0_SB_CB<4>")
	)
	(segment
		(start 425.216574 -239.391952)
		(end 424.026584 -239.391952)
		(width 0.18288)
		(layer "In11.Cu")
		(net "M_H_CPU0_SB_CB<4>")
	)
	(segment
		(start 414.619694 -239.552226)
		(end 414.187894 -239.984026)
		(width 0.18288)
		(layer "In11.Cu")
		(net "M_H_CPU0_SB_CB<4>")
	)
	(segment
		(start 429.546258 -239.51184)
		(end 429.546258 -239.124236)
		(width 0.18288)
		(layer "In11.Cu")
		(net "M_H_CPU0_SB_CB<4>")
	)
	(segment
		(start 423.692574 -239.725962)
		(end 421.53332 -239.725962)
		(width 0.18288)
		(layer "In11.Cu")
		(net "M_H_CPU0_SB_CB<4>")
	)
	(segment
		(start 446.344294 -240.161826)
		(end 442.661294 -240.161826)
		(width 0.18288)
		(layer "In11.Cu")
		(net "M_H_CPU0_SB_CB<4>")
	)
	(segment
		(start 386.998464 -244.873526)
		(end 386.760212 -245.111778)
		(width 0.088646)
		(layer "In11.Cu")
		(net "M_H_CPU0_SB_CB<4>")
	)
	(segment
		(start 406.869392 -243.943886)
		(end 406.551892 -243.943886)
		(width 0.18288)
		(layer "In11.Cu")
		(net "M_H_CPU0_SB_CB<4>")
	)
	(segment
		(start 382.337564 -244.238526)
		(end 382.322832 -244.247162)
		(width 0.088646)
		(layer "In11.Cu")
		(net "M_H_CPU0_SB_CB<4>")
	)
	(segment
		(start 387.557264 -244.873526)
		(end 386.998464 -244.873526)
		(width 0.088646)
		(layer "In11.Cu")
		(net "M_H_CPU0_SB_CB<4>")
	)
	(segment
		(start 391.256266 -244.990112)
		(end 389.043164 -244.990112)
		(width 0.18288)
		(layer "In11.Cu")
		(net "M_H_CPU0_SB_CB<4>")
	)
	(segment
		(start 391.457688 -244.78869)
		(end 391.256266 -244.990112)
		(width 0.18288)
		(layer "In11.Cu")
		(net "M_H_CPU0_SB_CB<4>")
	)
	(segment
		(start 425.356528 -239.251998)
		(end 425.216574 -239.391952)
		(width 0.18288)
		(layer "In11.Cu")
		(net "M_H_CPU0_SB_CB<4>")
	)
	(segment
		(start 406.358852 -242.033806)
		(end 406.165812 -241.840766)
		(width 0.18288)
		(layer "In11.Cu")
		(net "M_H_CPU0_SB_CB<4>")
	)
	(segment
		(start 420.153592 -240.241328)
		(end 419.990524 -240.404396)
		(width 0.18288)
		(layer "In11.Cu")
		(net "M_H_CPU0_SB_CB<4>")
	)
	(segment
		(start 438.937654 -241.091466)
		(end 438.749694 -241.279426)
		(width 0.18288)
		(layer "In11.Cu")
		(net "M_H_CPU0_SB_CB<4>")
	)
	(segment
		(start 428.649638 -239.70488)
		(end 427.950884 -239.70488)
		(width 0.18288)
		(layer "In11.Cu")
		(net "M_H_CPU0_SB_CB<4>")
	)
	(segment
		(start 400.022822 -241.840766)
		(end 397.074898 -244.78869)
		(width 0.18288)
		(layer "In11.Cu")
		(net "M_H_CPU0_SB_CB<4>")
	)
	(segment
		(start 407.255472 -241.840766)
		(end 407.062432 -242.033806)
		(width 0.18288)
		(layer "In11.Cu")
		(net "M_H_CPU0_SB_CB<4>")
	)
	(segment
		(start 429.739298 -239.70488)
		(end 429.546258 -239.51184)
		(width 0.18288)
		(layer "In11.Cu")
		(net "M_H_CPU0_SB_CB<4>")
	)
	(segment
		(start 450.911214 -241.516662)
		(end 450.911214 -241.261138)
		(width 0.18288)
		(layer "In11.Cu")
		(net "M_H_CPU0_SB_CB<4>")
	)
	(segment
		(start 409.234894 -240.441226)
		(end 407.835354 -241.840766)
		(width 0.18288)
		(layer "In11.Cu")
		(net "M_H_CPU0_SB_CB<4>")
	)
	(segment
		(start 450.26707 -240.898426)
		(end 448.466718 -240.898426)
		(width 0.18288)
		(layer "In11.Cu")
		(net "M_H_CPU0_SB_CB<4>")
	)
	(segment
		(start 380.457964 -244.238526)
		(end 380.443232 -244.247162)
		(width 0.088646)
		(layer "In11.Cu")
		(net "M_H_CPU0_SB_CB<4>")
	)
	(segment
		(start 417.41471 -239.32261)
		(end 416.44951 -239.32261)
		(width 0.18288)
		(layer "In11.Cu")
		(net "M_H_CPU0_SB_CB<4>")
	)
	(segment
		(start 377.633992 -244.241066)
		(end 377.623578 -244.247162)
		(width 0.088646)
		(layer "In11.Cu")
		(net "M_H_CPU0_SB_CB<4>")
	)
	(segment
		(start 407.835354 -241.840766)
		(end 407.255472 -241.840766)
		(width 0.18288)
		(layer "In11.Cu")
		(net "M_H_CPU0_SB_CB<4>")
	)
	(segment
		(start 376.694446 -244.241066)
		(end 376.684032 -244.247162)
		(width 0.088646)
		(layer "In11.Cu")
		(net "M_H_CPU0_SB_CB<4>")
	)
	(segment
		(start 442.318394 -240.504726)
		(end 441.444126 -240.504726)
		(width 0.18288)
		(layer "In11.Cu")
		(net "M_H_CPU0_SB_CB<4>")
	)
	(segment
		(start 435.0131 -240.24082)
		(end 434.863494 -240.390426)
		(width 0.18288)
		(layer "In11.Cu")
		(net "M_H_CPU0_SB_CB<4>")
	)
	(arc
		(start 375.369836 -244.247162)
		(mid 375.087134 -244.171386)
		(end 374.804432 -244.247162)
		(width 0.088646)
		(layer "In11.Cu")
		(net "M_H_CPU0_SB_CB<4>")
	)
	(arc
		(start 372.541546 -244.242082)
		(mid 372.425807 -244.130258)
		(end 372.367556 -243.980208)
		(width 0.088646)
		(layer "In11.Cu")
		(net "M_H_CPU0_SB_CB<4>")
	)
	(arc
		(start 380.443232 -244.247162)
		(mid 380.256034 -244.297305)
		(end 380.068836 -244.247162)
		(width 0.088646)
		(layer "In11.Cu")
		(net "M_H_CPU0_SB_CB<4>")
	)
	(arc
		(start 376.309636 -244.247162)
		(mid 376.035437 -244.171327)
		(end 375.758964 -244.238526)
		(width 0.088646)
		(layer "In11.Cu")
		(net "M_H_CPU0_SB_CB<4>")
	)
	(arc
		(start 379.503432 -244.247162)
		(mid 379.316234 -244.297305)
		(end 379.129036 -244.247162)
		(width 0.088646)
		(layer "In11.Cu")
		(net "M_H_CPU0_SB_CB<4>")
	)
	(arc
		(start 378.563632 -244.247162)
		(mid 378.376434 -244.297305)
		(end 378.189236 -244.247162)
		(width 0.088646)
		(layer "In11.Cu")
		(net "M_H_CPU0_SB_CB<4>")
	)
	(arc
		(start 382.888236 -244.247162)
		(mid 382.614037 -244.171327)
		(end 382.337564 -244.238526)
		(width 0.088646)
		(layer "In11.Cu")
		(net "M_H_CPU0_SB_CB<4>")
	)
	(arc
		(start 374.804432 -244.247162)
		(mid 374.617234 -244.297305)
		(end 374.430036 -244.247162)
		(width 0.088646)
		(layer "In11.Cu")
		(net "M_H_CPU0_SB_CB<4>")
	)
	(arc
		(start 373.864632 -244.247162)
		(mid 373.677434 -244.297305)
		(end 373.490236 -244.247162)
		(width 0.088646)
		(layer "In11.Cu")
		(net "M_H_CPU0_SB_CB<4>")
	)
	(arc
		(start 380.068836 -244.247162)
		(mid 379.786134 -244.171386)
		(end 379.503432 -244.247162)
		(width 0.088646)
		(layer "In11.Cu")
		(net "M_H_CPU0_SB_CB<4>")
	)
	(arc
		(start 374.430036 -244.247162)
		(mid 374.155837 -244.171327)
		(end 373.879364 -244.238526)
		(width 0.088646)
		(layer "In11.Cu")
		(net "M_H_CPU0_SB_CB<4>")
	)
	(arc
		(start 383.828036 -244.247162)
		(mid 383.545334 -244.171386)
		(end 383.262632 -244.247162)
		(width 0.088646)
		(layer "In11.Cu")
		(net "M_H_CPU0_SB_CB<4>")
	)
	(arc
		(start 379.129036 -244.247162)
		(mid 378.854837 -244.171327)
		(end 378.578364 -244.238526)
		(width 0.088646)
		(layer "In11.Cu")
		(net "M_H_CPU0_SB_CB<4>")
	)
	(arc
		(start 375.744232 -244.247162)
		(mid 375.557034 -244.297305)
		(end 375.369836 -244.247162)
		(width 0.088646)
		(layer "In11.Cu")
		(net "M_H_CPU0_SB_CB<4>")
	)
	(arc
		(start 376.684032 -244.247162)
		(mid 376.496834 -244.297305)
		(end 376.309636 -244.247162)
		(width 0.088646)
		(layer "In11.Cu")
		(net "M_H_CPU0_SB_CB<4>")
	)
	(arc
		(start 377.623578 -244.247162)
		(mid 377.43638 -244.297305)
		(end 377.249182 -244.247162)
		(width 0.088646)
		(layer "In11.Cu")
		(net "M_H_CPU0_SB_CB<4>")
	)
	(arc
		(start 377.249182 -244.247162)
		(mid 376.972623 -244.171419)
		(end 376.694446 -244.241066)
		(width 0.088646)
		(layer "In11.Cu")
		(net "M_H_CPU0_SB_CB<4>")
	)
	(arc
		(start 382.322832 -244.247162)
		(mid 382.135634 -244.297305)
		(end 381.948436 -244.247162)
		(width 0.088646)
		(layer "In11.Cu")
		(net "M_H_CPU0_SB_CB<4>")
	)
	(arc
		(start 384.110484 -244.726714)
		(mid 384.032373 -244.449765)
		(end 383.828036 -244.247162)
		(width 0.088646)
		(layer "In11.Cu")
		(net "M_H_CPU0_SB_CB<4>")
	)
	(arc
		(start 381.383032 -244.247162)
		(mid 381.195834 -244.297305)
		(end 381.008636 -244.247162)
		(width 0.088646)
		(layer "In11.Cu")
		(net "M_H_CPU0_SB_CB<4>")
	)
	(arc
		(start 373.490236 -244.247162)
		(mid 373.207534 -244.171386)
		(end 372.924832 -244.247162)
		(width 0.088646)
		(layer "In11.Cu")
		(net "M_H_CPU0_SB_CB<4>")
	)
	(arc
		(start 372.924832 -244.247162)
		(mid 372.737634 -244.297305)
		(end 372.550436 -244.247162)
		(width 0.088646)
		(layer "In11.Cu")
		(net "M_H_CPU0_SB_CB<4>")
	)
	(arc
		(start 384.289046 -245.055898)
		(mid 384.158132 -244.919538)
		(end 384.110484 -244.73662)
		(width 0.088646)
		(layer "In11.Cu")
		(net "M_H_CPU0_SB_CB<4>")
	)
	(arc
		(start 381.948436 -244.247162)
		(mid 381.665734 -244.171386)
		(end 381.383032 -244.247162)
		(width 0.088646)
		(layer "In11.Cu")
		(net "M_H_CPU0_SB_CB<4>")
	)
	(arc
		(start 378.189236 -244.247162)
		(mid 377.912423 -244.171292)
		(end 377.633992 -244.241066)
		(width 0.088646)
		(layer "In11.Cu")
		(net "M_H_CPU0_SB_CB<4>")
	)
	(arc
		(start 384.485134 -245.111778)
		(mid 384.383211 -245.097442)
		(end 384.289046 -245.055898)
		(width 0.088646)
		(layer "In11.Cu")
		(net "M_H_CPU0_SB_CB<4>")
	)
	(arc
		(start 383.262632 -244.247162)
		(mid 383.075434 -244.297305)
		(end 382.888236 -244.247162)
		(width 0.088646)
		(layer "In11.Cu")
		(net "M_H_CPU0_SB_CB<4>")
	)
	(arc
		(start 381.008636 -244.247162)
		(mid 380.734437 -244.171327)
		(end 380.457964 -244.238526)
		(width 0.088646)
		(layer "In11.Cu")
		(net "M_H_CPU0_SB_CB<4>")
	)
	(segment
		(start 461.689704 -232.764838)
		(end 462.073752 -232.764838)
		(width 0.20066)
		(layer "F.Cu")
		(net "M_H_CPU0_SB_CB<3>")
	)
	(segment
		(start 461.455516 -232.999026)
		(end 461.689704 -232.764838)
		(width 0.20066)
		(layer "F.Cu")
		(net "M_H_CPU0_SB_CB<3>")
	)
	(segment
		(start 460.570326 -233.45394)
		(end 461.251554 -233.45394)
		(width 0.20066)
		(layer "F.Cu")
		(net "M_H_CPU0_SB_CB<3>")
	)
	(segment
		(start 457.814426 -233.016806)
		(end 458.24648 -233.44886)
		(width 0.20066)
		(layer "F.Cu")
		(net "M_H_CPU0_SB_CB<3>")
	)
	(segment
		(start 461.455516 -233.249978)
		(end 461.455516 -232.999026)
		(width 0.20066)
		(layer "F.Cu")
		(net "M_H_CPU0_SB_CB<3>")
	)
	(segment
		(start 455.011282 -233.016806)
		(end 456.116182 -233.016806)
		(width 0.20066)
		(layer "F.Cu")
		(net "M_H_CPU0_SB_CB<3>")
	)
	(segment
		(start 372.737634 -241.202972)
		(end 372.737634 -240.667286)
		(width 0.20066)
		(layer "F.Cu")
		(net "M_H_CPU0_SB_CB<3>")
	)
	(segment
		(start 458.538326 -233.44886)
		(end 458.543152 -233.44886)
		(width 0.101854)
		(layer "F.Cu")
		(net "M_H_CPU0_SB_CB<3>")
	)
	(segment
		(start 460.558134 -233.441748)
		(end 460.570326 -233.45394)
		(width 0.1016)
		(layer "F.Cu")
		(net "M_H_CPU0_SB_CB<3>")
	)
	(segment
		(start 462.32572 -233.016806)
		(end 463.659982 -233.016806)
		(width 0.20066)
		(layer "F.Cu")
		(net "M_H_CPU0_SB_CB<3>")
	)
	(segment
		(start 458.550264 -233.441748)
		(end 460.558134 -233.441748)
		(width 0.1016)
		(layer "F.Cu")
		(net "M_H_CPU0_SB_CB<3>")
	)
	(segment
		(start 372.73738 -241.203226)
		(end 372.737634 -241.202972)
		(width 0.20066)
		(layer "F.Cu")
		(net "M_H_CPU0_SB_CB<3>")
	)
	(segment
		(start 458.24648 -233.44886)
		(end 458.538326 -233.44886)
		(width 0.20066)
		(layer "F.Cu")
		(net "M_H_CPU0_SB_CB<3>")
	)
	(segment
		(start 458.543152 -233.44886)
		(end 458.550264 -233.441748)
		(width 0.1016)
		(layer "F.Cu")
		(net "M_H_CPU0_SB_CB<3>")
	)
	(segment
		(start 456.116182 -233.016806)
		(end 457.814426 -233.016806)
		(width 0.20066)
		(layer "F.Cu")
		(net "M_H_CPU0_SB_CB<3>")
	)
	(segment
		(start 461.251554 -233.45394)
		(end 461.455516 -233.249978)
		(width 0.20066)
		(layer "F.Cu")
		(net "M_H_CPU0_SB_CB<3>")
	)
	(segment
		(start 462.073752 -232.764838)
		(end 462.32572 -233.016806)
		(width 0.20066)
		(layer "F.Cu")
		(net "M_H_CPU0_SB_CB<3>")
	)
	(segment
		(start 374.899682 -240.177574)
		(end 374.88495 -240.168938)
		(width 0.088646)
		(layer "In11.Cu")
		(net "M_H_CPU0_SB_CB<3>")
	)
	(segment
		(start 454.654158 -233.145838)
		(end 453.392794 -233.637074)
		(width 0.18288)
		(layer "In11.Cu")
		(net "M_H_CPU0_SB_CB<3>")
	)
	(segment
		(start 372.841774 -240.563146)
		(end 372.737634 -240.667286)
		(width 0.088646)
		(layer "In11.Cu")
		(net "M_H_CPU0_SB_CB<3>")
	)
	(segment
		(start 384.297682 -240.177574)
		(end 384.287268 -240.171478)
		(width 0.088646)
		(layer "In11.Cu")
		(net "M_H_CPU0_SB_CB<3>")
	)
	(segment
		(start 454.999344 -233.011472)
		(end 454.654158 -233.145838)
		(width 0.18288)
		(layer "In11.Cu")
		(net "M_H_CPU0_SB_CB<3>")
	)
	(segment
		(start 422.51884 -230.230426)
		(end 421.27424 -230.891588)
		(width 0.18288)
		(layer "In11.Cu")
		(net "M_H_CPU0_SB_CB<3>")
	)
	(segment
		(start 434.989986 -230.891334)
		(end 434.787294 -231.094026)
		(width 0.18288)
		(layer "In11.Cu")
		(net "M_H_CPU0_SB_CB<3>")
	)
	(segment
		(start 388.056374 -240.285524)
		(end 387.773418 -240.56848)
		(width 0.088646)
		(layer "In11.Cu")
		(net "M_H_CPU0_SB_CB<3>")
	)
	(segment
		(start 446.51422 -232.665524)
		(end 444.58382 -232.033826)
		(width 0.18288)
		(layer "In11.Cu")
		(net "M_H_CPU0_SB_CB<3>")
	)
	(segment
		(start 421.27424 -230.891588)
		(end 419.907466 -230.891588)
		(width 0.18288)
		(layer "In11.Cu")
		(net "M_H_CPU0_SB_CB<3>")
	)
	(segment
		(start 387.773418 -240.56848)
		(end 386.59562 -240.56848)
		(width 0.088646)
		(layer "In11.Cu")
		(net "M_H_CPU0_SB_CB<3>")
	)
	(segment
		(start 419.767258 -231.031796)
		(end 416.993324 -231.031796)
		(width 0.18288)
		(layer "In11.Cu")
		(net "M_H_CPU0_SB_CB<3>")
	)
	(segment
		(start 385.237736 -240.177574)
		(end 385.227322 -240.171478)
		(width 0.088646)
		(layer "In11.Cu")
		(net "M_H_CPU0_SB_CB<3>")
	)
	(segment
		(start 449.918582 -232.734612)
		(end 447.971418 -232.734612)
		(width 0.18288)
		(layer "In11.Cu")
		(net "M_H_CPU0_SB_CB<3>")
	)
	(segment
		(start 394.573252 -240.285524)
		(end 389.043164 -240.285524)
		(width 0.18288)
		(layer "In11.Cu")
		(net "M_H_CPU0_SB_CB<3>")
	)
	(segment
		(start 447.971418 -232.734612)
		(end 446.51422 -232.665524)
		(width 0.18288)
		(layer "In11.Cu")
		(net "M_H_CPU0_SB_CB<3>")
	)
	(segment
		(start 383.358136 -240.177574)
		(end 383.347722 -240.171478)
		(width 0.088646)
		(layer "In11.Cu")
		(net "M_H_CPU0_SB_CB<3>")
	)
	(segment
		(start 412.565596 -231.751632)
		(end 412.320994 -231.652826)
		(width 0.18288)
		(layer "In11.Cu")
		(net "M_H_CPU0_SB_CB<3>")
	)
	(segment
		(start 409.807918 -232.706418)
		(end 409.537154 -232.670858)
		(width 0.18288)
		(layer "In11.Cu")
		(net "M_H_CPU0_SB_CB<3>")
	)
	(segment
		(start 444.58382 -232.033826)
		(end 443.486794 -232.033826)
		(width 0.18288)
		(layer "In11.Cu")
		(net "M_H_CPU0_SB_CB<3>")
	)
	(segment
		(start 440.362594 -231.741726)
		(end 439.734706 -231.741726)
		(width 0.18288)
		(layer "In11.Cu")
		(net "M_H_CPU0_SB_CB<3>")
	)
	(segment
		(start 441.556394 -231.602026)
		(end 440.362594 -231.741726)
		(width 0.18288)
		(layer "In11.Cu")
		(net "M_H_CPU0_SB_CB<3>")
	)
	(segment
		(start 426.417994 -229.824026)
		(end 425.122594 -230.041704)
		(width 0.18288)
		(layer "In11.Cu")
		(net "M_H_CPU0_SB_CB<3>")
	)
	(segment
		(start 423.090594 -230.230426)
		(end 422.51884 -230.230426)
		(width 0.18288)
		(layer "In11.Cu")
		(net "M_H_CPU0_SB_CB<3>")
	)
	(segment
		(start 379.598936 -240.177574)
		(end 379.588522 -240.171478)
		(width 0.088646)
		(layer "In11.Cu")
		(net "M_H_CPU0_SB_CB<3>")
	)
	(segment
		(start 401.35556 -233.503216)
		(end 394.573252 -240.285524)
		(width 0.18288)
		(layer "In11.Cu")
		(net "M_H_CPU0_SB_CB<3>")
	)
	(segment
		(start 376.779282 -240.177574)
		(end 376.76455 -240.168938)
		(width 0.088646)
		(layer "In11.Cu")
		(net "M_H_CPU0_SB_CB<3>")
	)
	(segment
		(start 428.653194 -230.433626)
		(end 427.154594 -229.824026)
		(width 0.18288)
		(layer "In11.Cu")
		(net "M_H_CPU0_SB_CB<3>")
	)
	(segment
		(start 409.537154 -232.670858)
		(end 408.896566 -232.03027)
		(width 0.18288)
		(layer "In11.Cu")
		(net "M_H_CPU0_SB_CB<3>")
	)
	(segment
		(start 453.392794 -233.637074)
		(end 453.011794 -233.637074)
		(width 0.18288)
		(layer "In11.Cu")
		(net "M_H_CPU0_SB_CB<3>")
	)
	(segment
		(start 419.907466 -230.891588)
		(end 419.767258 -231.031796)
		(width 0.18288)
		(layer "In11.Cu")
		(net "M_H_CPU0_SB_CB<3>")
	)
	(segment
		(start 433.375308 -229.99827)
		(end 433.182268 -230.19131)
		(width 0.18288)
		(layer "In11.Cu")
		(net "M_H_CPU0_SB_CB<3>")
	)
	(segment
		(start 424.258994 -230.041704)
		(end 423.090594 -230.230426)
		(width 0.18288)
		(layer "In11.Cu")
		(net "M_H_CPU0_SB_CB<3>")
	)
	(segment
		(start 416.993324 -231.031796)
		(end 416.273488 -231.751632)
		(width 0.18288)
		(layer "In11.Cu")
		(net "M_H_CPU0_SB_CB<3>")
	)
	(segment
		(start 438.495186 -230.706168)
		(end 437.761634 -230.706168)
		(width 0.18288)
		(layer "In11.Cu")
		(net "M_H_CPU0_SB_CB<3>")
	)
	(segment
		(start 378.658882 -240.177574)
		(end 378.64415 -240.168938)
		(width 0.088646)
		(layer "In11.Cu")
		(net "M_H_CPU0_SB_CB<3>")
	)
	(segment
		(start 377.719082 -240.177574)
		(end 377.70435 -240.168938)
		(width 0.088646)
		(layer "In11.Cu")
		(net "M_H_CPU0_SB_CB<3>")
	)
	(segment
		(start 416.273488 -231.751632)
		(end 412.565596 -231.751632)
		(width 0.18288)
		(layer "In11.Cu")
		(net "M_H_CPU0_SB_CB<3>")
	)
	(segment
		(start 434.078888 -231.094026)
		(end 433.885848 -230.900986)
		(width 0.18288)
		(layer "In11.Cu")
		(net "M_H_CPU0_SB_CB<3>")
	)
	(segment
		(start 439.734706 -231.741726)
		(end 438.495186 -230.706168)
		(width 0.18288)
		(layer "In11.Cu")
		(net "M_H_CPU0_SB_CB<3>")
	)
	(segment
		(start 433.182268 -230.19131)
		(end 433.182268 -230.900986)
		(width 0.18288)
		(layer "In11.Cu")
		(net "M_H_CPU0_SB_CB<3>")
	)
	(segment
		(start 433.182268 -230.900986)
		(end 432.989228 -231.094026)
		(width 0.18288)
		(layer "In11.Cu")
		(net "M_H_CPU0_SB_CB<3>")
	)
	(segment
		(start 389.043164 -240.285524)
		(end 388.056374 -240.285524)
		(width 0.088646)
		(layer "In11.Cu")
		(net "M_H_CPU0_SB_CB<3>")
	)
	(segment
		(start 442.533786 -231.602026)
		(end 441.556394 -231.602026)
		(width 0.18288)
		(layer "In11.Cu")
		(net "M_H_CPU0_SB_CB<3>")
	)
	(segment
		(start 381.478536 -240.177574)
		(end 381.468122 -240.171478)
		(width 0.088646)
		(layer "In11.Cu")
		(net "M_H_CPU0_SB_CB<3>")
	)
	(segment
		(start 434.787294 -231.094026)
		(end 434.078888 -231.094026)
		(width 0.18288)
		(layer "In11.Cu")
		(net "M_H_CPU0_SB_CB<3>")
	)
	(segment
		(start 432.989228 -231.094026)
		(end 432.234594 -231.094026)
		(width 0.18288)
		(layer "In11.Cu")
		(net "M_H_CPU0_SB_CB<3>")
	)
	(segment
		(start 432.234594 -231.094026)
		(end 430.431194 -230.433626)
		(width 0.18288)
		(layer "In11.Cu")
		(net "M_H_CPU0_SB_CB<3>")
	)
	(segment
		(start 407.364692 -232.03027)
		(end 405.891746 -233.503216)
		(width 0.18288)
		(layer "In11.Cu")
		(net "M_H_CPU0_SB_CB<3>")
	)
	(segment
		(start 425.122594 -230.041704)
		(end 424.258994 -230.041704)
		(width 0.18288)
		(layer "In11.Cu")
		(net "M_H_CPU0_SB_CB<3>")
	)
	(segment
		(start 443.486794 -232.033826)
		(end 442.533786 -231.602026)
		(width 0.18288)
		(layer "In11.Cu")
		(net "M_H_CPU0_SB_CB<3>")
	)
	(segment
		(start 437.576468 -230.891334)
		(end 434.989986 -230.891334)
		(width 0.18288)
		(layer "In11.Cu")
		(net "M_H_CPU0_SB_CB<3>")
	)
	(segment
		(start 411.635194 -231.652826)
		(end 409.807918 -232.706418)
		(width 0.18288)
		(layer "In11.Cu")
		(net "M_H_CPU0_SB_CB<3>")
	)
	(segment
		(start 451.58279 -233.444796)
		(end 450.628766 -233.444796)
		(width 0.18288)
		(layer "In11.Cu")
		(net "M_H_CPU0_SB_CB<3>")
	)
	(segment
		(start 433.692808 -229.99827)
		(end 433.375308 -229.99827)
		(width 0.18288)
		(layer "In11.Cu")
		(net "M_H_CPU0_SB_CB<3>")
	)
	(segment
		(start 386.59562 -240.56848)
		(end 386.29463 -240.26749)
		(width 0.088646)
		(layer "In11.Cu")
		(net "M_H_CPU0_SB_CB<3>")
	)
	(segment
		(start 405.891746 -233.503216)
		(end 401.35556 -233.503216)
		(width 0.18288)
		(layer "In11.Cu")
		(net "M_H_CPU0_SB_CB<3>")
	)
	(segment
		(start 412.320994 -231.652826)
		(end 411.635194 -231.652826)
		(width 0.18288)
		(layer "In11.Cu")
		(net "M_H_CPU0_SB_CB<3>")
	)
	(segment
		(start 408.896566 -232.03027)
		(end 407.364692 -232.03027)
		(width 0.18288)
		(layer "In11.Cu")
		(net "M_H_CPU0_SB_CB<3>")
	)
	(segment
		(start 375.839482 -240.177574)
		(end 375.82475 -240.168938)
		(width 0.088646)
		(layer "In11.Cu")
		(net "M_H_CPU0_SB_CB<3>")
	)
	(segment
		(start 450.628766 -233.444796)
		(end 449.918582 -232.734612)
		(width 0.18288)
		(layer "In11.Cu")
		(net "M_H_CPU0_SB_CB<3>")
	)
	(segment
		(start 433.885848 -230.900986)
		(end 433.885848 -230.19131)
		(width 0.18288)
		(layer "In11.Cu")
		(net "M_H_CPU0_SB_CB<3>")
	)
	(segment
		(start 453.011794 -233.637074)
		(end 451.58279 -233.444796)
		(width 0.18288)
		(layer "In11.Cu")
		(net "M_H_CPU0_SB_CB<3>")
	)
	(segment
		(start 455.011282 -233.016806)
		(end 454.999344 -233.011472)
		(width 0.18288)
		(layer "In11.Cu")
		(net "M_H_CPU0_SB_CB<3>")
	)
	(segment
		(start 437.761634 -230.706168)
		(end 437.576468 -230.891334)
		(width 0.18288)
		(layer "In11.Cu")
		(net "M_H_CPU0_SB_CB<3>")
	)
	(segment
		(start 430.431194 -230.433626)
		(end 428.653194 -230.433626)
		(width 0.18288)
		(layer "In11.Cu")
		(net "M_H_CPU0_SB_CB<3>")
	)
	(segment
		(start 382.418082 -240.177574)
		(end 382.407668 -240.171478)
		(width 0.088646)
		(layer "In11.Cu")
		(net "M_H_CPU0_SB_CB<3>")
	)
	(segment
		(start 433.885848 -230.19131)
		(end 433.692808 -229.99827)
		(width 0.18288)
		(layer "In11.Cu")
		(net "M_H_CPU0_SB_CB<3>")
	)
	(segment
		(start 427.154594 -229.824026)
		(end 426.417994 -229.824026)
		(width 0.18288)
		(layer "In11.Cu")
		(net "M_H_CPU0_SB_CB<3>")
	)
	(segment
		(start 379.983746 -240.171478)
		(end 379.973332 -240.177574)
		(width 0.088646)
		(layer "In11.Cu")
		(net "M_H_CPU0_SB_CB<3>")
	)
	(arc
		(start 377.153678 -240.177574)
		(mid 376.96648 -240.227717)
		(end 376.779282 -240.177574)
		(width 0.088646)
		(layer "In11.Cu")
		(net "M_H_CPU0_SB_CB<3>")
	)
	(arc
		(start 379.033278 -240.177574)
		(mid 378.84608 -240.227717)
		(end 378.658882 -240.177574)
		(width 0.088646)
		(layer "In11.Cu")
		(net "M_H_CPU0_SB_CB<3>")
	)
	(arc
		(start 373.414798 -240.165128)
		(mid 373.384113 -240.183531)
		(end 373.351806 -240.19891)
		(width 0.088646)
		(layer "In11.Cu")
		(net "M_H_CPU0_SB_CB<3>")
	)
	(arc
		(start 376.76455 -240.168938)
		(mid 376.488109 -240.101772)
		(end 376.213878 -240.177574)
		(width 0.088646)
		(layer "In11.Cu")
		(net "M_H_CPU0_SB_CB<3>")
	)
	(arc
		(start 373.959882 -240.177574)
		(mid 373.709892 -240.102779)
		(end 373.452898 -240.14811)
		(width 0.088646)
		(layer "In11.Cu")
		(net "M_H_CPU0_SB_CB<3>")
	)
	(arc
		(start 376.213878 -240.177574)
		(mid 376.02668 -240.227717)
		(end 375.839482 -240.177574)
		(width 0.088646)
		(layer "In11.Cu")
		(net "M_H_CPU0_SB_CB<3>")
	)
	(arc
		(start 379.973332 -240.177574)
		(mid 379.786134 -240.227717)
		(end 379.598936 -240.177574)
		(width 0.088646)
		(layer "In11.Cu")
		(net "M_H_CPU0_SB_CB<3>")
	)
	(arc
		(start 374.334278 -240.177574)
		(mid 374.14708 -240.227717)
		(end 373.959882 -240.177574)
		(width 0.088646)
		(layer "In11.Cu")
		(net "M_H_CPU0_SB_CB<3>")
	)
	(arc
		(start 373.452898 -240.14811)
		(mid 373.433803 -240.156519)
		(end 373.414798 -240.165128)
		(width 0.088646)
		(layer "In11.Cu")
		(net "M_H_CPU0_SB_CB<3>")
	)
	(arc
		(start 374.88495 -240.168938)
		(mid 374.608509 -240.101772)
		(end 374.334278 -240.177574)
		(width 0.088646)
		(layer "In11.Cu")
		(net "M_H_CPU0_SB_CB<3>")
	)
	(arc
		(start 380.912878 -240.177574)
		(mid 380.72568 -240.227717)
		(end 380.538482 -240.177574)
		(width 0.088646)
		(layer "In11.Cu")
		(net "M_H_CPU0_SB_CB<3>")
	)
	(arc
		(start 377.70435 -240.168938)
		(mid 377.427909 -240.101772)
		(end 377.153678 -240.177574)
		(width 0.088646)
		(layer "In11.Cu")
		(net "M_H_CPU0_SB_CB<3>")
	)
	(arc
		(start 381.468122 -240.171478)
		(mid 381.18969 -240.101664)
		(end 380.912878 -240.177574)
		(width 0.088646)
		(layer "In11.Cu")
		(net "M_H_CPU0_SB_CB<3>")
	)
	(arc
		(start 373.351806 -240.19891)
		(mid 373.311248 -240.217068)
		(end 373.271796 -240.237518)
		(width 0.088646)
		(layer "In11.Cu")
		(net "M_H_CPU0_SB_CB<3>")
	)
	(arc
		(start 386.29463 -240.26749)
		(mid 385.968647 -240.106728)
		(end 385.612132 -240.177574)
		(width 0.088646)
		(layer "In11.Cu")
		(net "M_H_CPU0_SB_CB<3>")
	)
	(arc
		(start 378.64415 -240.168938)
		(mid 378.367709 -240.101772)
		(end 378.093478 -240.177574)
		(width 0.088646)
		(layer "In11.Cu")
		(net "M_H_CPU0_SB_CB<3>")
	)
	(arc
		(start 383.347722 -240.171478)
		(mid 383.06929 -240.101664)
		(end 382.792478 -240.177574)
		(width 0.088646)
		(layer "In11.Cu")
		(net "M_H_CPU0_SB_CB<3>")
	)
	(arc
		(start 373.271796 -240.237518)
		(mid 373.045576 -240.38553)
		(end 372.841774 -240.563146)
		(width 0.088646)
		(layer "In11.Cu")
		(net "M_H_CPU0_SB_CB<3>")
	)
	(arc
		(start 379.588522 -240.171478)
		(mid 379.31009 -240.101664)
		(end 379.033278 -240.177574)
		(width 0.088646)
		(layer "In11.Cu")
		(net "M_H_CPU0_SB_CB<3>")
	)
	(arc
		(start 382.792478 -240.177574)
		(mid 382.60528 -240.227717)
		(end 382.418082 -240.177574)
		(width 0.088646)
		(layer "In11.Cu")
		(net "M_H_CPU0_SB_CB<3>")
	)
	(arc
		(start 385.227322 -240.171478)
		(mid 384.94889 -240.101664)
		(end 384.672078 -240.177574)
		(width 0.088646)
		(layer "In11.Cu")
		(net "M_H_CPU0_SB_CB<3>")
	)
	(arc
		(start 382.407668 -240.171478)
		(mid 382.12949 -240.101786)
		(end 381.852932 -240.177574)
		(width 0.088646)
		(layer "In11.Cu")
		(net "M_H_CPU0_SB_CB<3>")
	)
	(arc
		(start 385.612132 -240.177574)
		(mid 385.424934 -240.227717)
		(end 385.237736 -240.177574)
		(width 0.088646)
		(layer "In11.Cu")
		(net "M_H_CPU0_SB_CB<3>")
	)
	(arc
		(start 381.852932 -240.177574)
		(mid 381.665734 -240.227717)
		(end 381.478536 -240.177574)
		(width 0.088646)
		(layer "In11.Cu")
		(net "M_H_CPU0_SB_CB<3>")
	)
	(arc
		(start 380.538482 -240.177574)
		(mid 380.261923 -240.101865)
		(end 379.983746 -240.171478)
		(width 0.088646)
		(layer "In11.Cu")
		(net "M_H_CPU0_SB_CB<3>")
	)
	(arc
		(start 375.82475 -240.168938)
		(mid 375.548309 -240.101772)
		(end 375.274078 -240.177574)
		(width 0.088646)
		(layer "In11.Cu")
		(net "M_H_CPU0_SB_CB<3>")
	)
	(arc
		(start 378.093478 -240.177574)
		(mid 377.90628 -240.227717)
		(end 377.719082 -240.177574)
		(width 0.088646)
		(layer "In11.Cu")
		(net "M_H_CPU0_SB_CB<3>")
	)
	(arc
		(start 384.287268 -240.171478)
		(mid 384.00909 -240.101786)
		(end 383.732532 -240.177574)
		(width 0.088646)
		(layer "In11.Cu")
		(net "M_H_CPU0_SB_CB<3>")
	)
	(arc
		(start 383.732532 -240.177574)
		(mid 383.545334 -240.227717)
		(end 383.358136 -240.177574)
		(width 0.088646)
		(layer "In11.Cu")
		(net "M_H_CPU0_SB_CB<3>")
	)
	(arc
		(start 384.672078 -240.177574)
		(mid 384.48488 -240.227717)
		(end 384.297682 -240.177574)
		(width 0.088646)
		(layer "In11.Cu")
		(net "M_H_CPU0_SB_CB<3>")
	)
	(arc
		(start 375.274078 -240.177574)
		(mid 375.08688 -240.227717)
		(end 374.899682 -240.177574)
		(width 0.088646)
		(layer "In11.Cu")
		(net "M_H_CPU0_SB_CB<3>")
	)
	(segment
		(start 462.32572 -234.716574)
		(end 463.659982 -234.716574)
		(width 0.20066)
		(layer "F.Cu")
		(net "M_H_CPU0_SB_CB<2>")
	)
	(segment
		(start 373.207534 -242.017042)
		(end 373.20728 -242.016788)
		(width 0.20066)
		(layer "F.Cu")
		(net "M_H_CPU0_SB_CB<2>")
	)
	(segment
		(start 461.455516 -234.698794)
		(end 461.689704 -234.464606)
		(width 0.20066)
		(layer "F.Cu")
		(net "M_H_CPU0_SB_CB<2>")
	)
	(segment
		(start 458.550264 -235.141516)
		(end 460.558134 -235.141516)
		(width 0.1016)
		(layer "F.Cu")
		(net "M_H_CPU0_SB_CB<2>")
	)
	(segment
		(start 458.24648 -235.148628)
		(end 458.538326 -235.148628)
		(width 0.20066)
		(layer "F.Cu")
		(net "M_H_CPU0_SB_CB<2>")
	)
	(segment
		(start 455.011282 -234.716574)
		(end 456.116182 -234.716574)
		(width 0.20066)
		(layer "F.Cu")
		(net "M_H_CPU0_SB_CB<2>")
	)
	(segment
		(start 460.558134 -235.141516)
		(end 460.570326 -235.153708)
		(width 0.1016)
		(layer "F.Cu")
		(net "M_H_CPU0_SB_CB<2>")
	)
	(segment
		(start 458.538326 -235.148628)
		(end 458.543152 -235.148628)
		(width 0.101854)
		(layer "F.Cu")
		(net "M_H_CPU0_SB_CB<2>")
	)
	(segment
		(start 456.116182 -234.716574)
		(end 457.814426 -234.716574)
		(width 0.20066)
		(layer "F.Cu")
		(net "M_H_CPU0_SB_CB<2>")
	)
	(segment
		(start 373.20728 -242.016788)
		(end 373.20728 -241.481102)
		(width 0.20066)
		(layer "F.Cu")
		(net "M_H_CPU0_SB_CB<2>")
	)
	(segment
		(start 461.251554 -235.153708)
		(end 461.455516 -234.949746)
		(width 0.20066)
		(layer "F.Cu")
		(net "M_H_CPU0_SB_CB<2>")
	)
	(segment
		(start 461.689704 -234.464606)
		(end 462.073752 -234.464606)
		(width 0.20066)
		(layer "F.Cu")
		(net "M_H_CPU0_SB_CB<2>")
	)
	(segment
		(start 460.570326 -235.153708)
		(end 461.251554 -235.153708)
		(width 0.20066)
		(layer "F.Cu")
		(net "M_H_CPU0_SB_CB<2>")
	)
	(segment
		(start 458.543152 -235.148628)
		(end 458.550264 -235.141516)
		(width 0.1016)
		(layer "F.Cu")
		(net "M_H_CPU0_SB_CB<2>")
	)
	(segment
		(start 461.455516 -234.949746)
		(end 461.455516 -234.698794)
		(width 0.20066)
		(layer "F.Cu")
		(net "M_H_CPU0_SB_CB<2>")
	)
	(segment
		(start 457.814426 -234.716574)
		(end 458.24648 -235.148628)
		(width 0.20066)
		(layer "F.Cu")
		(net "M_H_CPU0_SB_CB<2>")
	)
	(segment
		(start 462.073752 -234.464606)
		(end 462.32572 -234.716574)
		(width 0.20066)
		(layer "F.Cu")
		(net "M_H_CPU0_SB_CB<2>")
	)
	(segment
		(start 427.274736 -231.734868)
		(end 426.365416 -231.734868)
		(width 0.18288)
		(layer "In11.Cu")
		(net "M_H_CPU0_SB_CB<2>")
	)
	(segment
		(start 379.513846 -240.985548)
		(end 379.503432 -240.991644)
		(width 0.088646)
		(layer "In11.Cu")
		(net "M_H_CPU0_SB_CB<2>")
	)
	(segment
		(start 454.430384 -235.297472)
		(end 452.707248 -235.297472)
		(width 0.18288)
		(layer "In11.Cu")
		(net "M_H_CPU0_SB_CB<2>")
	)
	(segment
		(start 431.593498 -232.82783)
		(end 431.256694 -232.491026)
		(width 0.18288)
		(layer "In11.Cu")
		(net "M_H_CPU0_SB_CB<2>")
	)
	(segment
		(start 411.186122 -233.278426)
		(end 410.160978 -234.30357)
		(width 0.18288)
		(layer "In11.Cu")
		(net "M_H_CPU0_SB_CB<2>")
	)
	(segment
		(start 449.87591 -234.424474)
		(end 446.702942 -234.424474)
		(width 0.18288)
		(layer "In11.Cu")
		(net "M_H_CPU0_SB_CB<2>")
	)
	(segment
		(start 422.450514 -231.81056)
		(end 421.669718 -232.591356)
		(width 0.18288)
		(layer "In11.Cu")
		(net "M_H_CPU0_SB_CB<2>")
	)
	(segment
		(start 423.490136 -231.741472)
		(end 423.421048 -231.81056)
		(width 0.18288)
		(layer "In11.Cu")
		(net "M_H_CPU0_SB_CB<2>")
	)
	(segment
		(start 452.707248 -235.297472)
		(end 452.552054 -235.142278)
		(width 0.18288)
		(layer "In11.Cu")
		(net "M_H_CPU0_SB_CB<2>")
	)
	(segment
		(start 387.522974 -241.86388)
		(end 386.607304 -241.86388)
		(width 0.088646)
		(layer "In11.Cu")
		(net "M_H_CPU0_SB_CB<2>")
	)
	(segment
		(start 455.011282 -234.716574)
		(end 454.430384 -235.297472)
		(width 0.18288)
		(layer "In11.Cu")
		(net "M_H_CPU0_SB_CB<2>")
	)
	(segment
		(start 434.69179 -232.82783)
		(end 431.593498 -232.82783)
		(width 0.18288)
		(layer "In11.Cu")
		(net "M_H_CPU0_SB_CB<2>")
	)
	(segment
		(start 444.393066 -233.824272)
		(end 443.992 -233.824272)
		(width 0.18288)
		(layer "In11.Cu")
		(net "M_H_CPU0_SB_CB<2>")
	)
	(segment
		(start 374.819164 -240.983008)
		(end 374.804432 -240.991644)
		(width 0.088646)
		(layer "In11.Cu")
		(net "M_H_CPU0_SB_CB<2>")
	)
	(segment
		(start 395.08049 -241.301524)
		(end 389.043164 -241.301524)
		(width 0.18288)
		(layer "In11.Cu")
		(net "M_H_CPU0_SB_CB<2>")
	)
	(segment
		(start 388.08533 -241.301524)
		(end 387.522974 -241.86388)
		(width 0.088646)
		(layer "In11.Cu")
		(net "M_H_CPU0_SB_CB<2>")
	)
	(segment
		(start 410.160978 -234.30357)
		(end 409.165806 -234.30357)
		(width 0.18288)
		(layer "In11.Cu")
		(net "M_H_CPU0_SB_CB<2>")
	)
	(segment
		(start 412.867094 -233.557826)
		(end 412.587694 -233.278426)
		(width 0.18288)
		(layer "In11.Cu")
		(net "M_H_CPU0_SB_CB<2>")
	)
	(segment
		(start 440.562238 -233.441494)
		(end 439.217562 -233.441494)
		(width 0.18288)
		(layer "In11.Cu")
		(net "M_H_CPU0_SB_CB<2>")
	)
	(segment
		(start 441.56884 -233.43489)
		(end 441.255658 -233.748072)
		(width 0.18288)
		(layer "In11.Cu")
		(net "M_H_CPU0_SB_CB<2>")
	)
	(segment
		(start 441.255658 -233.748072)
		(end 440.868816 -233.748072)
		(width 0.18288)
		(layer "In11.Cu")
		(net "M_H_CPU0_SB_CB<2>")
	)
	(segment
		(start 377.638564 -240.983008)
		(end 377.623832 -240.991644)
		(width 0.088646)
		(layer "In11.Cu")
		(net "M_H_CPU0_SB_CB<2>")
	)
	(segment
		(start 440.868816 -233.748072)
		(end 440.562238 -233.441494)
		(width 0.18288)
		(layer "In11.Cu")
		(net "M_H_CPU0_SB_CB<2>")
	)
	(segment
		(start 443.776354 -234.039918)
		(end 443.549786 -234.039918)
		(width 0.18288)
		(layer "In11.Cu")
		(net "M_H_CPU0_SB_CB<2>")
	)
	(segment
		(start 428.030894 -232.491026)
		(end 427.274736 -231.734868)
		(width 0.18288)
		(layer "In11.Cu")
		(net "M_H_CPU0_SB_CB<2>")
	)
	(segment
		(start 436.97652 -232.833672)
		(end 436.52567 -232.833672)
		(width 0.18288)
		(layer "In11.Cu")
		(net "M_H_CPU0_SB_CB<2>")
	)
	(segment
		(start 419.933628 -232.815892)
		(end 416.682428 -232.815892)
		(width 0.18288)
		(layer "In11.Cu")
		(net "M_H_CPU0_SB_CB<2>")
	)
	(segment
		(start 425.665392 -232.046272)
		(end 425.360592 -231.741472)
		(width 0.18288)
		(layer "In11.Cu")
		(net "M_H_CPU0_SB_CB<2>")
	)
	(segment
		(start 436.52567 -232.833672)
		(end 436.2831 -232.591102)
		(width 0.18288)
		(layer "In11.Cu")
		(net "M_H_CPU0_SB_CB<2>")
	)
	(segment
		(start 452.552054 -235.142278)
		(end 450.593714 -235.142278)
		(width 0.18288)
		(layer "In11.Cu")
		(net "M_H_CPU0_SB_CB<2>")
	)
	(segment
		(start 375.758964 -240.983008)
		(end 375.744232 -240.991644)
		(width 0.088646)
		(layer "In11.Cu")
		(net "M_H_CPU0_SB_CB<2>")
	)
	(segment
		(start 408.474926 -233.61269)
		(end 407.355802 -233.61269)
		(width 0.18288)
		(layer "In11.Cu")
		(net "M_H_CPU0_SB_CB<2>")
	)
	(segment
		(start 409.165806 -234.30357)
		(end 408.474926 -233.61269)
		(width 0.18288)
		(layer "In11.Cu")
		(net "M_H_CPU0_SB_CB<2>")
	)
	(segment
		(start 378.578364 -240.983008)
		(end 378.563632 -240.991644)
		(width 0.088646)
		(layer "In11.Cu")
		(net "M_H_CPU0_SB_CB<2>")
	)
	(segment
		(start 425.360592 -231.741472)
		(end 423.490136 -231.741472)
		(width 0.18288)
		(layer "In11.Cu")
		(net "M_H_CPU0_SB_CB<2>")
	)
	(segment
		(start 434.928518 -232.591102)
		(end 434.69179 -232.82783)
		(width 0.18288)
		(layer "In11.Cu")
		(net "M_H_CPU0_SB_CB<2>")
	)
	(segment
		(start 423.421048 -231.81056)
		(end 422.450514 -231.81056)
		(width 0.18288)
		(layer "In11.Cu")
		(net "M_H_CPU0_SB_CB<2>")
	)
	(segment
		(start 407.355802 -233.61269)
		(end 405.792178 -235.176314)
		(width 0.18288)
		(layer "In11.Cu")
		(net "M_H_CPU0_SB_CB<2>")
	)
	(segment
		(start 443.992 -233.824272)
		(end 443.776354 -234.039918)
		(width 0.18288)
		(layer "In11.Cu")
		(net "M_H_CPU0_SB_CB<2>")
	)
	(segment
		(start 415.940494 -233.557826)
		(end 412.867094 -233.557826)
		(width 0.18288)
		(layer "In11.Cu")
		(net "M_H_CPU0_SB_CB<2>")
	)
	(segment
		(start 389.043164 -241.301524)
		(end 388.08533 -241.301524)
		(width 0.088646)
		(layer "In11.Cu")
		(net "M_H_CPU0_SB_CB<2>")
	)
	(segment
		(start 444.68542 -234.116626)
		(end 444.393066 -233.824272)
		(width 0.18288)
		(layer "In11.Cu")
		(net "M_H_CPU0_SB_CB<2>")
	)
	(segment
		(start 443.549786 -234.039918)
		(end 442.944758 -233.43489)
		(width 0.18288)
		(layer "In11.Cu")
		(net "M_H_CPU0_SB_CB<2>")
	)
	(segment
		(start 436.2831 -232.591102)
		(end 434.928518 -232.591102)
		(width 0.18288)
		(layer "In11.Cu")
		(net "M_H_CPU0_SB_CB<2>")
	)
	(segment
		(start 386.607304 -241.86388)
		(end 385.824476 -241.080798)
		(width 0.088646)
		(layer "In11.Cu")
		(net "M_H_CPU0_SB_CB<2>")
	)
	(segment
		(start 382.337564 -240.983008)
		(end 382.322832 -240.991644)
		(width 0.088646)
		(layer "In11.Cu")
		(net "M_H_CPU0_SB_CB<2>")
	)
	(segment
		(start 446.395094 -234.116626)
		(end 444.68542 -234.116626)
		(width 0.18288)
		(layer "In11.Cu")
		(net "M_H_CPU0_SB_CB<2>")
	)
	(segment
		(start 437.355488 -232.454704)
		(end 436.97652 -232.833672)
		(width 0.18288)
		(layer "In11.Cu")
		(net "M_H_CPU0_SB_CB<2>")
	)
	(segment
		(start 446.702942 -234.424474)
		(end 446.395094 -234.116626)
		(width 0.18288)
		(layer "In11.Cu")
		(net "M_H_CPU0_SB_CB<2>")
	)
	(segment
		(start 450.593714 -235.142278)
		(end 449.87591 -234.424474)
		(width 0.18288)
		(layer "In11.Cu")
		(net "M_H_CPU0_SB_CB<2>")
	)
	(segment
		(start 416.682428 -232.815892)
		(end 415.940494 -233.557826)
		(width 0.18288)
		(layer "In11.Cu")
		(net "M_H_CPU0_SB_CB<2>")
	)
	(segment
		(start 405.792178 -235.176314)
		(end 401.2057 -235.176314)
		(width 0.18288)
		(layer "In11.Cu")
		(net "M_H_CPU0_SB_CB<2>")
	)
	(segment
		(start 412.587694 -233.278426)
		(end 411.186122 -233.278426)
		(width 0.18288)
		(layer "In11.Cu")
		(net "M_H_CPU0_SB_CB<2>")
	)
	(segment
		(start 439.217562 -233.441494)
		(end 438.230772 -232.454704)
		(width 0.18288)
		(layer "In11.Cu")
		(net "M_H_CPU0_SB_CB<2>")
	)
	(segment
		(start 421.669718 -232.591356)
		(end 420.158164 -232.591356)
		(width 0.18288)
		(layer "In11.Cu")
		(net "M_H_CPU0_SB_CB<2>")
	)
	(segment
		(start 426.365416 -231.734868)
		(end 426.054012 -232.046272)
		(width 0.18288)
		(layer "In11.Cu")
		(net "M_H_CPU0_SB_CB<2>")
	)
	(segment
		(start 380.453392 -240.985548)
		(end 380.442978 -240.991644)
		(width 0.088646)
		(layer "In11.Cu")
		(net "M_H_CPU0_SB_CB<2>")
	)
	(segment
		(start 426.054012 -232.046272)
		(end 425.665392 -232.046272)
		(width 0.18288)
		(layer "In11.Cu")
		(net "M_H_CPU0_SB_CB<2>")
	)
	(segment
		(start 438.230772 -232.454704)
		(end 437.355488 -232.454704)
		(width 0.18288)
		(layer "In11.Cu")
		(net "M_H_CPU0_SB_CB<2>")
	)
	(segment
		(start 373.874792 -240.985548)
		(end 373.870728 -240.987834)
		(width 0.088646)
		(layer "In11.Cu")
		(net "M_H_CPU0_SB_CB<2>")
	)
	(segment
		(start 420.158164 -232.591356)
		(end 419.933628 -232.815892)
		(width 0.18288)
		(layer "In11.Cu")
		(net "M_H_CPU0_SB_CB<2>")
	)
	(segment
		(start 442.944758 -233.43489)
		(end 441.56884 -233.43489)
		(width 0.18288)
		(layer "In11.Cu")
		(net "M_H_CPU0_SB_CB<2>")
	)
	(segment
		(start 431.256694 -232.491026)
		(end 428.030894 -232.491026)
		(width 0.18288)
		(layer "In11.Cu")
		(net "M_H_CPU0_SB_CB<2>")
	)
	(segment
		(start 401.2057 -235.176314)
		(end 395.08049 -241.301524)
		(width 0.18288)
		(layer "In11.Cu")
		(net "M_H_CPU0_SB_CB<2>")
	)
	(arc
		(start 377.249436 -240.991644)
		(mid 376.966734 -240.915868)
		(end 376.684032 -240.991644)
		(width 0.088646)
		(layer "In11.Cu")
		(net "M_H_CPU0_SB_CB<2>")
	)
	(arc
		(start 383.262632 -240.991644)
		(mid 383.075434 -241.041787)
		(end 382.888236 -240.991644)
		(width 0.088646)
		(layer "In11.Cu")
		(net "M_H_CPU0_SB_CB<2>")
	)
	(arc
		(start 373.870728 -240.987834)
		(mid 373.856799 -240.995887)
		(end 373.842534 -241.003328)
		(width 0.088646)
		(layer "In11.Cu")
		(net "M_H_CPU0_SB_CB<2>")
	)
	(arc
		(start 376.309636 -240.991644)
		(mid 376.035437 -240.915809)
		(end 375.758964 -240.983008)
		(width 0.088646)
		(layer "In11.Cu")
		(net "M_H_CPU0_SB_CB<2>")
	)
	(arc
		(start 374.804432 -240.991644)
		(mid 374.617234 -241.041787)
		(end 374.430036 -240.991644)
		(width 0.088646)
		(layer "In11.Cu")
		(net "M_H_CPU0_SB_CB<2>")
	)
	(arc
		(start 382.322832 -240.991644)
		(mid 382.135634 -241.041787)
		(end 381.948436 -240.991644)
		(width 0.088646)
		(layer "In11.Cu")
		(net "M_H_CPU0_SB_CB<2>")
	)
	(arc
		(start 380.442978 -240.991644)
		(mid 380.25578 -241.041787)
		(end 380.068582 -240.991644)
		(width 0.088646)
		(layer "In11.Cu")
		(net "M_H_CPU0_SB_CB<2>")
	)
	(arc
		(start 378.189236 -240.991644)
		(mid 377.915037 -240.915809)
		(end 377.638564 -240.983008)
		(width 0.088646)
		(layer "In11.Cu")
		(net "M_H_CPU0_SB_CB<2>")
	)
	(arc
		(start 383.828036 -240.991644)
		(mid 383.545334 -240.915868)
		(end 383.262632 -240.991644)
		(width 0.088646)
		(layer "In11.Cu")
		(net "M_H_CPU0_SB_CB<2>")
	)
	(arc
		(start 381.008636 -240.991644)
		(mid 380.731823 -240.915774)
		(end 380.453392 -240.985548)
		(width 0.088646)
		(layer "In11.Cu")
		(net "M_H_CPU0_SB_CB<2>")
	)
	(arc
		(start 375.744232 -240.991644)
		(mid 375.557034 -241.041787)
		(end 375.369836 -240.991644)
		(width 0.088646)
		(layer "In11.Cu")
		(net "M_H_CPU0_SB_CB<2>")
	)
	(arc
		(start 381.383032 -240.991644)
		(mid 381.195834 -241.041787)
		(end 381.008636 -240.991644)
		(width 0.088646)
		(layer "In11.Cu")
		(net "M_H_CPU0_SB_CB<2>")
	)
	(arc
		(start 380.068582 -240.991644)
		(mid 379.792023 -240.915901)
		(end 379.513846 -240.985548)
		(width 0.088646)
		(layer "In11.Cu")
		(net "M_H_CPU0_SB_CB<2>")
	)
	(arc
		(start 379.503432 -240.991644)
		(mid 379.316234 -241.041787)
		(end 379.129036 -240.991644)
		(width 0.088646)
		(layer "In11.Cu")
		(net "M_H_CPU0_SB_CB<2>")
	)
	(arc
		(start 385.707636 -240.991644)
		(mid 385.424934 -240.915868)
		(end 385.142232 -240.991644)
		(width 0.088646)
		(layer "In11.Cu")
		(net "M_H_CPU0_SB_CB<2>")
	)
	(arc
		(start 384.202432 -240.991644)
		(mid 384.015234 -241.041787)
		(end 383.828036 -240.991644)
		(width 0.088646)
		(layer "In11.Cu")
		(net "M_H_CPU0_SB_CB<2>")
	)
	(arc
		(start 385.771644 -241.03457)
		(mid 385.740372 -241.012015)
		(end 385.707636 -240.991644)
		(width 0.088646)
		(layer "In11.Cu")
		(net "M_H_CPU0_SB_CB<2>")
	)
	(arc
		(start 385.142232 -240.991644)
		(mid 384.955034 -241.041787)
		(end 384.767836 -240.991644)
		(width 0.088646)
		(layer "In11.Cu")
		(net "M_H_CPU0_SB_CB<2>")
	)
	(arc
		(start 374.430036 -240.991644)
		(mid 374.153223 -240.915774)
		(end 373.874792 -240.985548)
		(width 0.088646)
		(layer "In11.Cu")
		(net "M_H_CPU0_SB_CB<2>")
	)
	(arc
		(start 384.767836 -240.991644)
		(mid 384.485134 -240.915868)
		(end 384.202432 -240.991644)
		(width 0.088646)
		(layer "In11.Cu")
		(net "M_H_CPU0_SB_CB<2>")
	)
	(arc
		(start 381.948436 -240.991644)
		(mid 381.665734 -240.915868)
		(end 381.383032 -240.991644)
		(width 0.088646)
		(layer "In11.Cu")
		(net "M_H_CPU0_SB_CB<2>")
	)
	(arc
		(start 378.563632 -240.991644)
		(mid 378.376434 -241.041787)
		(end 378.189236 -240.991644)
		(width 0.088646)
		(layer "In11.Cu")
		(net "M_H_CPU0_SB_CB<2>")
	)
	(arc
		(start 379.129036 -240.991644)
		(mid 378.854837 -240.915809)
		(end 378.578364 -240.983008)
		(width 0.088646)
		(layer "In11.Cu")
		(net "M_H_CPU0_SB_CB<2>")
	)
	(arc
		(start 373.842534 -241.003328)
		(mid 373.508094 -241.21986)
		(end 373.20728 -241.481102)
		(width 0.088646)
		(layer "In11.Cu")
		(net "M_H_CPU0_SB_CB<2>")
	)
	(arc
		(start 377.623832 -240.991644)
		(mid 377.436634 -241.041787)
		(end 377.249436 -240.991644)
		(width 0.088646)
		(layer "In11.Cu")
		(net "M_H_CPU0_SB_CB<2>")
	)
	(arc
		(start 376.684032 -240.991644)
		(mid 376.496834 -241.041787)
		(end 376.309636 -240.991644)
		(width 0.088646)
		(layer "In11.Cu")
		(net "M_H_CPU0_SB_CB<2>")
	)
	(arc
		(start 375.369836 -240.991644)
		(mid 375.095637 -240.915809)
		(end 374.819164 -240.983008)
		(width 0.088646)
		(layer "In11.Cu")
		(net "M_H_CPU0_SB_CB<2>")
	)
	(arc
		(start 385.824476 -241.080798)
		(mid 385.798778 -241.056864)
		(end 385.771644 -241.03457)
		(width 0.088646)
		(layer "In11.Cu")
		(net "M_H_CPU0_SB_CB<2>")
	)
	(arc
		(start 382.888236 -240.991644)
		(mid 382.614037 -240.915809)
		(end 382.337564 -240.983008)
		(width 0.088646)
		(layer "In11.Cu")
		(net "M_H_CPU0_SB_CB<2>")
	)
	(segment
		(start 457.120244 -233.441748)
		(end 454.931526 -233.441748)
		(width 0.1016)
		(layer "F.Cu")
		(net "M_H_CPU0_SB_CB<1>")
	)
	(segment
		(start 457.53655 -233.435398)
		(end 457.126594 -233.435398)
		(width 0.20066)
		(layer "F.Cu")
		(net "M_H_CPU0_SB_CB<1>")
	)
	(segment
		(start 454.260712 -234.115356)
		(end 453.785478 -234.115356)
		(width 0.20066)
		(layer "F.Cu")
		(net "M_H_CPU0_SB_CB<1>")
	)
	(segment
		(start 454.931526 -233.441748)
		(end 454.91146 -233.441748)
		(width 0.101854)
		(layer "F.Cu")
		(net "M_H_CPU0_SB_CB<1>")
	)
	(segment
		(start 457.968096 -233.866944)
		(end 457.53655 -233.435398)
		(width 0.20066)
		(layer "F.Cu")
		(net "M_H_CPU0_SB_CB<1>")
	)
	(segment
		(start 454.91146 -233.441748)
		(end 454.566782 -233.441748)
		(width 0.20066)
		(layer "F.Cu")
		(net "M_H_CPU0_SB_CB<1>")
	)
	(segment
		(start 454.448672 -233.559858)
		(end 454.448672 -233.927396)
		(width 0.20066)
		(layer "F.Cu")
		(net "M_H_CPU0_SB_CB<1>")
	)
	(segment
		(start 453.785478 -234.115356)
		(end 453.536812 -233.86669)
		(width 0.20066)
		(layer "F.Cu")
		(net "M_H_CPU0_SB_CB<1>")
	)
	(segment
		(start 454.566782 -233.441748)
		(end 454.448672 -233.559858)
		(width 0.20066)
		(layer "F.Cu")
		(net "M_H_CPU0_SB_CB<1>")
	)
	(segment
		(start 457.126594 -233.435398)
		(end 457.120244 -233.441748)
		(width 0.1016)
		(layer "F.Cu")
		(net "M_H_CPU0_SB_CB<1>")
	)
	(segment
		(start 459.55966 -233.866944)
		(end 457.968096 -233.866944)
		(width 0.20066)
		(layer "F.Cu")
		(net "M_H_CPU0_SB_CB<1>")
	)
	(segment
		(start 371.79758 -241.203226)
		(end 371.797834 -241.202972)
		(width 0.20066)
		(layer "F.Cu")
		(net "M_H_CPU0_SB_CB<1>")
	)
	(segment
		(start 452.016114 -233.86669)
		(end 450.911214 -233.86669)
		(width 0.20066)
		(layer "F.Cu")
		(net "M_H_CPU0_SB_CB<1>")
	)
	(segment
		(start 371.797834 -241.202972)
		(end 371.797834 -240.667286)
		(width 0.20066)
		(layer "F.Cu")
		(net "M_H_CPU0_SB_CB<1>")
	)
	(segment
		(start 453.536812 -233.86669)
		(end 452.016114 -233.86669)
		(width 0.20066)
		(layer "F.Cu")
		(net "M_H_CPU0_SB_CB<1>")
	)
	(segment
		(start 459.559914 -233.86669)
		(end 459.55966 -233.866944)
		(width 0.20066)
		(layer "F.Cu")
		(net "M_H_CPU0_SB_CB<1>")
	)
	(segment
		(start 454.448672 -233.927396)
		(end 454.260712 -234.115356)
		(width 0.20066)
		(layer "F.Cu")
		(net "M_H_CPU0_SB_CB<1>")
	)
	(segment
		(start 450.911214 -233.959908)
		(end 450.71792 -234.153202)
		(width 0.18288)
		(layer "In11.Cu")
		(net "M_H_CPU0_SB_CB<1>")
	)
	(segment
		(start 417.943792 -231.744266)
		(end 417.750752 -231.551226)
		(width 0.18288)
		(layer "In11.Cu")
		(net "M_H_CPU0_SB_CB<1>")
	)
	(segment
		(start 389.043164 -240.793524)
		(end 387.642862 -240.793524)
		(width 0.088646)
		(layer "In11.Cu")
		(net "M_H_CPU0_SB_CB<1>")
	)
	(segment
		(start 387.608064 -240.758726)
		(end 386.516626 -240.758726)
		(width 0.088646)
		(layer "In11.Cu")
		(net "M_H_CPU0_SB_CB<1>")
	)
	(segment
		(start 438.63641 -231.934766)
		(end 437.710834 -231.934766)
		(width 0.18288)
		(layer "In11.Cu")
		(net "M_H_CPU0_SB_CB<1>")
	)
	(segment
		(start 417.750752 -231.551226)
		(end 417.235894 -231.551226)
		(width 0.18288)
		(layer "In11.Cu")
		(net "M_H_CPU0_SB_CB<1>")
	)
	(segment
		(start 419.623494 -231.551226)
		(end 418.840412 -231.551226)
		(width 0.18288)
		(layer "In11.Cu")
		(net "M_H_CPU0_SB_CB<1>")
	)
	(segment
		(start 401.452842 -234.200446)
		(end 394.859764 -240.793524)
		(width 0.18288)
		(layer "In11.Cu")
		(net "M_H_CPU0_SB_CB<1>")
	)
	(segment
		(start 442.712094 -232.541826)
		(end 442.338714 -232.915206)
		(width 0.18288)
		(layer "In11.Cu")
		(net "M_H_CPU0_SB_CB<1>")
	)
	(segment
		(start 419.81374 -231.741472)
		(end 419.623494 -231.551226)
		(width 0.18288)
		(layer "In11.Cu")
		(net "M_H_CPU0_SB_CB<1>")
	)
	(segment
		(start 418.136832 -232.30586)
		(end 417.943792 -232.11282)
		(width 0.18288)
		(layer "In11.Cu")
		(net "M_H_CPU0_SB_CB<1>")
	)
	(segment
		(start 446.776094 -233.383074)
		(end 446.601342 -233.557826)
		(width 0.18288)
		(layer "In11.Cu")
		(net "M_H_CPU0_SB_CB<1>")
	)
	(segment
		(start 418.454332 -232.30586)
		(end 418.136832 -232.30586)
		(width 0.18288)
		(layer "In11.Cu")
		(net "M_H_CPU0_SB_CB<1>")
	)
	(segment
		(start 407.560018 -232.55351)
		(end 405.913082 -234.200446)
		(width 0.18288)
		(layer "In11.Cu")
		(net "M_H_CPU0_SB_CB<1>")
	)
	(segment
		(start 405.913082 -234.200446)
		(end 401.452842 -234.200446)
		(width 0.18288)
		(layer "In11.Cu")
		(net "M_H_CPU0_SB_CB<1>")
	)
	(segment
		(start 413.918908 -233.046524)
		(end 413.725868 -232.853484)
		(width 0.18288)
		(layer "In11.Cu")
		(net "M_H_CPU0_SB_CB<1>")
	)
	(segment
		(start 434.787294 -231.602026)
		(end 433.992528 -231.602026)
		(width 0.18288)
		(layer "In11.Cu")
		(net "M_H_CPU0_SB_CB<1>")
	)
	(segment
		(start 413.532828 -232.264458)
		(end 412.839662 -232.264458)
		(width 0.18288)
		(layer "In11.Cu")
		(net "M_H_CPU0_SB_CB<1>")
	)
	(segment
		(start 433.606448 -232.319576)
		(end 433.288948 -232.319576)
		(width 0.18288)
		(layer "In11.Cu")
		(net "M_H_CPU0_SB_CB<1>")
	)
	(segment
		(start 380.068582 -240.342928)
		(end 380.058168 -240.349024)
		(width 0.088646)
		(layer "In11.Cu")
		(net "M_H_CPU0_SB_CB<1>")
	)
	(segment
		(start 377.638564 -240.351564)
		(end 377.623832 -240.342928)
		(width 0.088646)
		(layer "In11.Cu")
		(net "M_H_CPU0_SB_CB<1>")
	)
	(segment
		(start 417.943792 -232.11282)
		(end 417.943792 -231.744266)
		(width 0.18288)
		(layer "In11.Cu")
		(net "M_H_CPU0_SB_CB<1>")
	)
	(segment
		(start 449.80225 -233.383074)
		(end 446.776094 -233.383074)
		(width 0.18288)
		(layer "In11.Cu")
		(net "M_H_CPU0_SB_CB<1>")
	)
	(segment
		(start 431.586894 -231.602026)
		(end 431.205894 -231.983026)
		(width 0.18288)
		(layer "In11.Cu")
		(net "M_H_CPU0_SB_CB<1>")
	)
	(segment
		(start 423.662094 -230.738426)
		(end 422.705784 -230.738426)
		(width 0.18288)
		(layer "In11.Cu")
		(net "M_H_CPU0_SB_CB<1>")
	)
	(segment
		(start 434.926486 -231.741218)
		(end 434.787294 -231.602026)
		(width 0.18288)
		(layer "In11.Cu")
		(net "M_H_CPU0_SB_CB<1>")
	)
	(segment
		(start 408.411426 -232.55351)
		(end 407.560018 -232.55351)
		(width 0.18288)
		(layer "In11.Cu")
		(net "M_H_CPU0_SB_CB<1>")
	)
	(segment
		(start 450.06895 -233.649774)
		(end 449.80225 -233.383074)
		(width 0.18288)
		(layer "In11.Cu")
		(net "M_H_CPU0_SB_CB<1>")
	)
	(segment
		(start 442.338714 -232.915206)
		(end 441.937902 -232.915206)
		(width 0.18288)
		(layer "In11.Cu")
		(net "M_H_CPU0_SB_CB<1>")
	)
	(segment
		(start 425.77893 -231.193848)
		(end 425.47667 -230.891588)
		(width 0.18288)
		(layer "In11.Cu")
		(net "M_H_CPU0_SB_CB<1>")
	)
	(segment
		(start 376.698764 -240.351564)
		(end 376.684032 -240.342928)
		(width 0.088646)
		(layer "In11.Cu")
		(net "M_H_CPU0_SB_CB<1>")
	)
	(segment
		(start 441.937902 -232.915206)
		(end 441.614306 -232.59161)
		(width 0.18288)
		(layer "In11.Cu")
		(net "M_H_CPU0_SB_CB<1>")
	)
	(segment
		(start 373.302784 -240.667032)
		(end 373.30253 -240.667286)
		(width 0.088646)
		(layer "In11.Cu")
		(net "M_H_CPU0_SB_CB<1>")
	)
	(segment
		(start 439.293254 -232.59161)
		(end 438.63641 -231.934766)
		(width 0.18288)
		(layer "In11.Cu")
		(net "M_H_CPU0_SB_CB<1>")
	)
	(segment
		(start 433.799488 -231.795066)
		(end 433.799488 -232.126536)
		(width 0.18288)
		(layer "In11.Cu")
		(net "M_H_CPU0_SB_CB<1>")
	)
	(segment
		(start 414.622488 -232.264458)
		(end 414.429448 -232.457498)
		(width 0.18288)
		(layer "In11.Cu")
		(net "M_H_CPU0_SB_CB<1>")
	)
	(segment
		(start 382.337564 -240.351564)
		(end 382.322832 -240.342928)
		(width 0.088646)
		(layer "In11.Cu")
		(net "M_H_CPU0_SB_CB<1>")
	)
	(segment
		(start 378.578364 -240.351564)
		(end 378.563632 -240.342928)
		(width 0.088646)
		(layer "In11.Cu")
		(net "M_H_CPU0_SB_CB<1>")
	)
	(segment
		(start 450.71792 -234.153202)
		(end 450.351906 -234.153202)
		(width 0.18288)
		(layer "In11.Cu")
		(net "M_H_CPU0_SB_CB<1>")
	)
	(segment
		(start 418.647372 -232.11282)
		(end 418.454332 -232.30586)
		(width 0.18288)
		(layer "In11.Cu")
		(net "M_H_CPU0_SB_CB<1>")
	)
	(segment
		(start 416.522662 -232.264458)
		(end 414.622488 -232.264458)
		(width 0.18288)
		(layer "In11.Cu")
		(net "M_H_CPU0_SB_CB<1>")
	)
	(segment
		(start 427.470316 -231.193848)
		(end 425.77893 -231.193848)
		(width 0.18288)
		(layer "In11.Cu")
		(net "M_H_CPU0_SB_CB<1>")
	)
	(segment
		(start 414.429448 -232.457498)
		(end 414.429448 -232.853484)
		(width 0.18288)
		(layer "In11.Cu")
		(net "M_H_CPU0_SB_CB<1>")
	)
	(segment
		(start 436.738014 -231.525826)
		(end 436.522622 -231.741218)
		(width 0.18288)
		(layer "In11.Cu")
		(net "M_H_CPU0_SB_CB<1>")
	)
	(segment
		(start 409.187142 -233.329226)
		(end 408.411426 -232.55351)
		(width 0.18288)
		(layer "In11.Cu")
		(net "M_H_CPU0_SB_CB<1>")
	)
	(segment
		(start 432.902868 -231.602026)
		(end 431.586894 -231.602026)
		(width 0.18288)
		(layer "In11.Cu")
		(net "M_H_CPU0_SB_CB<1>")
	)
	(segment
		(start 450.911214 -233.86669)
		(end 450.911214 -233.959908)
		(width 0.18288)
		(layer "In11.Cu")
		(net "M_H_CPU0_SB_CB<1>")
	)
	(segment
		(start 446.601342 -233.557826)
		(end 444.896494 -233.557826)
		(width 0.18288)
		(layer "In11.Cu")
		(net "M_H_CPU0_SB_CB<1>")
	)
	(segment
		(start 450.351906 -234.153202)
		(end 450.224906 -234.026202)
		(width 0.18288)
		(layer "In11.Cu")
		(net "M_H_CPU0_SB_CB<1>")
	)
	(segment
		(start 384.217164 -240.351564)
		(end 384.202432 -240.342928)
		(width 0.088646)
		(layer "In11.Cu")
		(net "M_H_CPU0_SB_CB<1>")
	)
	(segment
		(start 433.799488 -232.126536)
		(end 433.606448 -232.319576)
		(width 0.18288)
		(layer "In11.Cu")
		(net "M_H_CPU0_SB_CB<1>")
	)
	(segment
		(start 386.516626 -240.758726)
		(end 386.16001 -240.40211)
		(width 0.088646)
		(layer "In11.Cu")
		(net "M_H_CPU0_SB_CB<1>")
	)
	(segment
		(start 387.642862 -240.793524)
		(end 387.608064 -240.758726)
		(width 0.088646)
		(layer "In11.Cu")
		(net "M_H_CPU0_SB_CB<1>")
	)
	(segment
		(start 413.725868 -232.457498)
		(end 413.532828 -232.264458)
		(width 0.18288)
		(layer "In11.Cu")
		(net "M_H_CPU0_SB_CB<1>")
	)
	(segment
		(start 412.839662 -232.264458)
		(end 412.460694 -232.643426)
		(width 0.18288)
		(layer "In11.Cu")
		(net "M_H_CPU0_SB_CB<1>")
	)
	(segment
		(start 441.614306 -232.59161)
		(end 439.293254 -232.59161)
		(width 0.18288)
		(layer "In11.Cu")
		(net "M_H_CPU0_SB_CB<1>")
	)
	(segment
		(start 409.659836 -233.329226)
		(end 409.187142 -233.329226)
		(width 0.18288)
		(layer "In11.Cu")
		(net "M_H_CPU0_SB_CB<1>")
	)
	(segment
		(start 433.095908 -231.795066)
		(end 432.902868 -231.602026)
		(width 0.18288)
		(layer "In11.Cu")
		(net "M_H_CPU0_SB_CB<1>")
	)
	(segment
		(start 412.460694 -232.643426)
		(end 411.315662 -232.643426)
		(width 0.18288)
		(layer "In11.Cu")
		(net "M_H_CPU0_SB_CB<1>")
	)
	(segment
		(start 443.880494 -232.541826)
		(end 442.712094 -232.541826)
		(width 0.18288)
		(layer "In11.Cu")
		(net "M_H_CPU0_SB_CB<1>")
	)
	(segment
		(start 373.874792 -240.349024)
		(end 373.864378 -240.342928)
		(width 0.088646)
		(layer "In11.Cu")
		(net "M_H_CPU0_SB_CB<1>")
	)
	(segment
		(start 428.259494 -231.983026)
		(end 427.470316 -231.193848)
		(width 0.18288)
		(layer "In11.Cu")
		(net "M_H_CPU0_SB_CB<1>")
	)
	(segment
		(start 437.710834 -231.934766)
		(end 437.301894 -231.525826)
		(width 0.18288)
		(layer "In11.Cu")
		(net "M_H_CPU0_SB_CB<1>")
	)
	(segment
		(start 436.522622 -231.741218)
		(end 434.926486 -231.741218)
		(width 0.18288)
		(layer "In11.Cu")
		(net "M_H_CPU0_SB_CB<1>")
	)
	(segment
		(start 437.301894 -231.525826)
		(end 436.738014 -231.525826)
		(width 0.18288)
		(layer "In11.Cu")
		(net "M_H_CPU0_SB_CB<1>")
	)
	(segment
		(start 380.453392 -240.349024)
		(end 380.442978 -240.342928)
		(width 0.088646)
		(layer "In11.Cu")
		(net "M_H_CPU0_SB_CB<1>")
	)
	(segment
		(start 423.815256 -230.891588)
		(end 423.662094 -230.738426)
		(width 0.18288)
		(layer "In11.Cu")
		(net "M_H_CPU0_SB_CB<1>")
	)
	(segment
		(start 433.288948 -232.319576)
		(end 433.095908 -232.126536)
		(width 0.18288)
		(layer "In11.Cu")
		(net "M_H_CPU0_SB_CB<1>")
	)
	(segment
		(start 444.896494 -233.557826)
		(end 443.880494 -232.541826)
		(width 0.18288)
		(layer "In11.Cu")
		(net "M_H_CPU0_SB_CB<1>")
	)
	(segment
		(start 375.758964 -240.351564)
		(end 375.744232 -240.342928)
		(width 0.088646)
		(layer "In11.Cu")
		(net "M_H_CPU0_SB_CB<1>")
	)
	(segment
		(start 418.840412 -231.551226)
		(end 418.647372 -231.744266)
		(width 0.18288)
		(layer "In11.Cu")
		(net "M_H_CPU0_SB_CB<1>")
	)
	(segment
		(start 433.992528 -231.602026)
		(end 433.799488 -231.795066)
		(width 0.18288)
		(layer "In11.Cu")
		(net "M_H_CPU0_SB_CB<1>")
	)
	(segment
		(start 373.30253 -240.667286)
		(end 373.30253 -240.68278)
		(width 0.088646)
		(layer "In11.Cu")
		(net "M_H_CPU0_SB_CB<1>")
	)
	(segment
		(start 414.236408 -233.046524)
		(end 413.918908 -233.046524)
		(width 0.18288)
		(layer "In11.Cu")
		(net "M_H_CPU0_SB_CB<1>")
	)
	(segment
		(start 431.205894 -231.983026)
		(end 428.259494 -231.983026)
		(width 0.18288)
		(layer "In11.Cu")
		(net "M_H_CPU0_SB_CB<1>")
	)
	(segment
		(start 425.47667 -230.891588)
		(end 423.815256 -230.891588)
		(width 0.18288)
		(layer "In11.Cu")
		(net "M_H_CPU0_SB_CB<1>")
	)
	(segment
		(start 414.429448 -232.853484)
		(end 414.236408 -233.046524)
		(width 0.18288)
		(layer "In11.Cu")
		(net "M_H_CPU0_SB_CB<1>")
	)
	(segment
		(start 394.859764 -240.793524)
		(end 389.043164 -240.793524)
		(width 0.18288)
		(layer "In11.Cu")
		(net "M_H_CPU0_SB_CB<1>")
	)
	(segment
		(start 422.705784 -230.738426)
		(end 421.94226 -231.50195)
		(width 0.18288)
		(layer "In11.Cu")
		(net "M_H_CPU0_SB_CB<1>")
	)
	(segment
		(start 417.235894 -231.551226)
		(end 416.522662 -232.264458)
		(width 0.18288)
		(layer "In11.Cu")
		(net "M_H_CPU0_SB_CB<1>")
	)
	(segment
		(start 433.095908 -232.126536)
		(end 433.095908 -231.795066)
		(width 0.18288)
		(layer "In11.Cu")
		(net "M_H_CPU0_SB_CB<1>")
	)
	(segment
		(start 450.224906 -234.026202)
		(end 450.06895 -233.649774)
		(width 0.18288)
		(layer "In11.Cu")
		(net "M_H_CPU0_SB_CB<1>")
	)
	(segment
		(start 413.725868 -232.853484)
		(end 413.725868 -232.457498)
		(width 0.18288)
		(layer "In11.Cu")
		(net "M_H_CPU0_SB_CB<1>")
	)
	(segment
		(start 374.819164 -240.351564)
		(end 374.804432 -240.342928)
		(width 0.088646)
		(layer "In11.Cu")
		(net "M_H_CPU0_SB_CB<1>")
	)
	(segment
		(start 421.94226 -231.50195)
		(end 421.363902 -231.741472)
		(width 0.18288)
		(layer "In11.Cu")
		(net "M_H_CPU0_SB_CB<1>")
	)
	(segment
		(start 421.363902 -231.741472)
		(end 419.81374 -231.741472)
		(width 0.18288)
		(layer "In11.Cu")
		(net "M_H_CPU0_SB_CB<1>")
	)
	(segment
		(start 418.647372 -231.744266)
		(end 418.647372 -232.11282)
		(width 0.18288)
		(layer "In11.Cu")
		(net "M_H_CPU0_SB_CB<1>")
	)
	(segment
		(start 411.315662 -232.643426)
		(end 409.659836 -233.329226)
		(width 0.18288)
		(layer "In11.Cu")
		(net "M_H_CPU0_SB_CB<1>")
	)
	(segment
		(start 372.44147 -241.004598)
		(end 371.797834 -240.667286)
		(width 0.088646)
		(layer "In11.Cu")
		(net "M_H_CPU0_SB_CB<1>")
	)
	(arc
		(start 373.864378 -240.342928)
		(mid 373.775542 -240.305995)
		(end 373.680228 -240.29289)
		(width 0.088646)
		(layer "In11.Cu")
		(net "M_H_CPU0_SB_CB<1>")
	)
	(arc
		(start 378.189236 -240.342928)
		(mid 377.915007 -240.418853)
		(end 377.638564 -240.351564)
		(width 0.088646)
		(layer "In11.Cu")
		(net "M_H_CPU0_SB_CB<1>")
	)
	(arc
		(start 375.369836 -240.342928)
		(mid 375.095607 -240.418853)
		(end 374.819164 -240.351564)
		(width 0.088646)
		(layer "In11.Cu")
		(net "M_H_CPU0_SB_CB<1>")
	)
	(arc
		(start 382.888236 -240.342928)
		(mid 382.614007 -240.418853)
		(end 382.337564 -240.351564)
		(width 0.088646)
		(layer "In11.Cu")
		(net "M_H_CPU0_SB_CB<1>")
	)
	(arc
		(start 386.082032 -240.342928)
		(mid 385.894834 -240.292785)
		(end 385.707636 -240.342928)
		(width 0.088646)
		(layer "In11.Cu")
		(net "M_H_CPU0_SB_CB<1>")
	)
	(arc
		(start 374.430036 -240.342928)
		(mid 374.153223 -240.418764)
		(end 373.874792 -240.349024)
		(width 0.088646)
		(layer "In11.Cu")
		(net "M_H_CPU0_SB_CB<1>")
	)
	(arc
		(start 377.249436 -240.342928)
		(mid 376.975207 -240.418853)
		(end 376.698764 -240.351564)
		(width 0.088646)
		(layer "In11.Cu")
		(net "M_H_CPU0_SB_CB<1>")
	)
	(arc
		(start 384.767836 -240.342928)
		(mid 384.493607 -240.418853)
		(end 384.217164 -240.351564)
		(width 0.088646)
		(layer "In11.Cu")
		(net "M_H_CPU0_SB_CB<1>")
	)
	(arc
		(start 372.52656 -241.030506)
		(mid 372.482779 -241.021619)
		(end 372.44147 -241.004598)
		(width 0.088646)
		(layer "In11.Cu")
		(net "M_H_CPU0_SB_CB<1>")
	)
	(arc
		(start 383.262632 -240.342928)
		(mid 383.075434 -240.292785)
		(end 382.888236 -240.342928)
		(width 0.088646)
		(layer "In11.Cu")
		(net "M_H_CPU0_SB_CB<1>")
	)
	(arc
		(start 386.16001 -240.40211)
		(mid 386.12296 -240.369964)
		(end 386.082032 -240.342928)
		(width 0.088646)
		(layer "In11.Cu")
		(net "M_H_CPU0_SB_CB<1>")
	)
	(arc
		(start 379.129036 -240.342928)
		(mid 378.854807 -240.418853)
		(end 378.578364 -240.351564)
		(width 0.088646)
		(layer "In11.Cu")
		(net "M_H_CPU0_SB_CB<1>")
	)
	(arc
		(start 381.008636 -240.342928)
		(mid 380.731823 -240.418764)
		(end 380.453392 -240.349024)
		(width 0.088646)
		(layer "In11.Cu")
		(net "M_H_CPU0_SB_CB<1>")
	)
	(arc
		(start 382.322832 -240.342928)
		(mid 382.135634 -240.292785)
		(end 381.948436 -240.342928)
		(width 0.088646)
		(layer "In11.Cu")
		(net "M_H_CPU0_SB_CB<1>")
	)
	(arc
		(start 380.058168 -240.349024)
		(mid 379.77999 -240.418716)
		(end 379.503432 -240.342928)
		(width 0.088646)
		(layer "In11.Cu")
		(net "M_H_CPU0_SB_CB<1>")
	)
	(arc
		(start 379.503432 -240.342928)
		(mid 379.316234 -240.292785)
		(end 379.129036 -240.342928)
		(width 0.088646)
		(layer "In11.Cu")
		(net "M_H_CPU0_SB_CB<1>")
	)
	(arc
		(start 378.563632 -240.342928)
		(mid 378.376434 -240.292785)
		(end 378.189236 -240.342928)
		(width 0.088646)
		(layer "In11.Cu")
		(net "M_H_CPU0_SB_CB<1>")
	)
	(arc
		(start 372.938294 -241.050826)
		(mid 372.732174 -241.045803)
		(end 372.52656 -241.030506)
		(width 0.088646)
		(layer "In11.Cu")
		(net "M_H_CPU0_SB_CB<1>")
	)
	(arc
		(start 376.309636 -240.342928)
		(mid 376.035407 -240.418853)
		(end 375.758964 -240.351564)
		(width 0.088646)
		(layer "In11.Cu")
		(net "M_H_CPU0_SB_CB<1>")
	)
	(arc
		(start 380.442978 -240.342928)
		(mid 380.25578 -240.292785)
		(end 380.068582 -240.342928)
		(width 0.088646)
		(layer "In11.Cu")
		(net "M_H_CPU0_SB_CB<1>")
	)
	(arc
		(start 377.623832 -240.342928)
		(mid 377.436634 -240.292785)
		(end 377.249436 -240.342928)
		(width 0.088646)
		(layer "In11.Cu")
		(net "M_H_CPU0_SB_CB<1>")
	)
	(arc
		(start 376.684032 -240.342928)
		(mid 376.496834 -240.292785)
		(end 376.309636 -240.342928)
		(width 0.088646)
		(layer "In11.Cu")
		(net "M_H_CPU0_SB_CB<1>")
	)
	(arc
		(start 384.202432 -240.342928)
		(mid 384.015234 -240.292785)
		(end 383.828036 -240.342928)
		(width 0.088646)
		(layer "In11.Cu")
		(net "M_H_CPU0_SB_CB<1>")
	)
	(arc
		(start 381.383032 -240.342928)
		(mid 381.195834 -240.292785)
		(end 381.008636 -240.342928)
		(width 0.088646)
		(layer "In11.Cu")
		(net "M_H_CPU0_SB_CB<1>")
	)
	(arc
		(start 373.680228 -240.29289)
		(mid 373.413603 -240.401374)
		(end 373.302784 -240.667032)
		(width 0.088646)
		(layer "In11.Cu")
		(net "M_H_CPU0_SB_CB<1>")
	)
	(arc
		(start 375.744232 -240.342928)
		(mid 375.557034 -240.292785)
		(end 375.369836 -240.342928)
		(width 0.088646)
		(layer "In11.Cu")
		(net "M_H_CPU0_SB_CB<1>")
	)
	(arc
		(start 385.707636 -240.342928)
		(mid 385.424934 -240.41867)
		(end 385.142232 -240.342928)
		(width 0.088646)
		(layer "In11.Cu")
		(net "M_H_CPU0_SB_CB<1>")
	)
	(arc
		(start 381.948436 -240.342928)
		(mid 381.665734 -240.41867)
		(end 381.383032 -240.342928)
		(width 0.088646)
		(layer "In11.Cu")
		(net "M_H_CPU0_SB_CB<1>")
	)
	(arc
		(start 374.804432 -240.342928)
		(mid 374.617234 -240.292785)
		(end 374.430036 -240.342928)
		(width 0.088646)
		(layer "In11.Cu")
		(net "M_H_CPU0_SB_CB<1>")
	)
	(arc
		(start 383.828036 -240.342928)
		(mid 383.545334 -240.41867)
		(end 383.262632 -240.342928)
		(width 0.088646)
		(layer "In11.Cu")
		(net "M_H_CPU0_SB_CB<1>")
	)
	(arc
		(start 373.30253 -240.68278)
		(mid 373.196075 -240.941677)
		(end 372.938294 -241.050826)
		(width 0.088646)
		(layer "In11.Cu")
		(net "M_H_CPU0_SB_CB<1>")
	)
	(arc
		(start 385.142232 -240.342928)
		(mid 384.955034 -240.292785)
		(end 384.767836 -240.342928)
		(width 0.088646)
		(layer "In11.Cu")
		(net "M_H_CPU0_SB_CB<1>")
	)
	(segment
		(start 457.126594 -235.13542)
		(end 457.120244 -235.14177)
		(width 0.1016)
		(layer "F.Cu")
		(net "M_H_CPU0_SB_CB<0>")
	)
	(segment
		(start 371.32768 -242.016788)
		(end 371.32768 -241.481102)
		(width 0.20066)
		(layer "F.Cu")
		(net "M_H_CPU0_SB_CB<0>")
	)
	(segment
		(start 454.448672 -235.25988)
		(end 454.448672 -235.627418)
		(width 0.20066)
		(layer "F.Cu")
		(net "M_H_CPU0_SB_CB<0>")
	)
	(segment
		(start 454.448672 -235.627418)
		(end 454.260712 -235.815378)
		(width 0.20066)
		(layer "F.Cu")
		(net "M_H_CPU0_SB_CB<0>")
	)
	(segment
		(start 371.327934 -242.017042)
		(end 371.32768 -242.016788)
		(width 0.20066)
		(layer "F.Cu")
		(net "M_H_CPU0_SB_CB<0>")
	)
	(segment
		(start 454.566782 -235.14177)
		(end 454.448672 -235.25988)
		(width 0.20066)
		(layer "F.Cu")
		(net "M_H_CPU0_SB_CB<0>")
	)
	(segment
		(start 453.785478 -235.815378)
		(end 453.536812 -235.566712)
		(width 0.20066)
		(layer "F.Cu")
		(net "M_H_CPU0_SB_CB<0>")
	)
	(segment
		(start 454.95845 -235.14177)
		(end 454.91146 -235.14177)
		(width 0.101854)
		(layer "F.Cu")
		(net "M_H_CPU0_SB_CB<0>")
	)
	(segment
		(start 457.968096 -235.566966)
		(end 457.53655 -235.13542)
		(width 0.20066)
		(layer "F.Cu")
		(net "M_H_CPU0_SB_CB<0>")
	)
	(segment
		(start 452.016114 -235.566712)
		(end 450.911214 -235.566712)
		(width 0.20066)
		(layer "F.Cu")
		(net "M_H_CPU0_SB_CB<0>")
	)
	(segment
		(start 459.559914 -235.566712)
		(end 459.55966 -235.566966)
		(width 0.20066)
		(layer "F.Cu")
		(net "M_H_CPU0_SB_CB<0>")
	)
	(segment
		(start 453.536812 -235.566712)
		(end 452.016114 -235.566712)
		(width 0.20066)
		(layer "F.Cu")
		(net "M_H_CPU0_SB_CB<0>")
	)
	(segment
		(start 459.55966 -235.566966)
		(end 457.968096 -235.566966)
		(width 0.20066)
		(layer "F.Cu")
		(net "M_H_CPU0_SB_CB<0>")
	)
	(segment
		(start 454.260712 -235.815378)
		(end 453.785478 -235.815378)
		(width 0.20066)
		(layer "F.Cu")
		(net "M_H_CPU0_SB_CB<0>")
	)
	(segment
		(start 457.120244 -235.14177)
		(end 454.95845 -235.14177)
		(width 0.1016)
		(layer "F.Cu")
		(net "M_H_CPU0_SB_CB<0>")
	)
	(segment
		(start 457.53655 -235.13542)
		(end 457.126594 -235.13542)
		(width 0.20066)
		(layer "F.Cu")
		(net "M_H_CPU0_SB_CB<0>")
	)
	(segment
		(start 454.91146 -235.14177)
		(end 454.566782 -235.14177)
		(width 0.20066)
		(layer "F.Cu")
		(net "M_H_CPU0_SB_CB<0>")
	)
	(segment
		(start 434.76164 -233.405172)
		(end 431.587148 -233.405172)
		(width 0.18288)
		(layer "In11.Cu")
		(net "M_H_CPU0_SB_CB<0>")
	)
	(segment
		(start 403.959822 -236.191298)
		(end 403.959822 -235.905802)
		(width 0.18288)
		(layer "In11.Cu")
		(net "M_H_CPU0_SB_CB<0>")
	)
	(segment
		(start 402.552662 -235.905802)
		(end 402.359622 -235.712762)
		(width 0.18288)
		(layer "In11.Cu")
		(net "M_H_CPU0_SB_CB<0>")
	)
	(segment
		(start 374.899682 -241.156744)
		(end 374.88495 -241.16538)
		(width 0.088646)
		(layer "In11.Cu")
		(net "M_H_CPU0_SB_CB<0>")
	)
	(segment
		(start 414.52546 -234.95254)
		(end 414.20796 -234.95254)
		(width 0.18288)
		(layer "In11.Cu")
		(net "M_H_CPU0_SB_CB<0>")
	)
	(segment
		(start 414.7185 -234.284266)
		(end 414.7185 -234.7595)
		(width 0.18288)
		(layer "In11.Cu")
		(net "M_H_CPU0_SB_CB<0>")
	)
	(segment
		(start 417.036758 -233.325162)
		(end 416.270694 -234.091226)
		(width 0.18288)
		(layer "In11.Cu")
		(net "M_H_CPU0_SB_CB<0>")
	)
	(segment
		(start 373.706136 -241.563144)
		(end 373.445786 -241.772186)
		(width 0.088646)
		(layer "In11.Cu")
		(net "M_H_CPU0_SB_CB<0>")
	)
	(segment
		(start 442.839094 -235.158026)
		(end 441.972446 -234.291378)
		(width 0.18288)
		(layer "In11.Cu")
		(net "M_H_CPU0_SB_CB<0>")
	)
	(segment
		(start 425.961302 -232.591356)
		(end 423.66692 -232.591356)
		(width 0.18288)
		(layer "In11.Cu")
		(net "M_H_CPU0_SB_CB<0>")
	)
	(segment
		(start 402.745702 -236.384338)
		(end 402.552662 -236.191298)
		(width 0.18288)
		(layer "In11.Cu")
		(net "M_H_CPU0_SB_CB<0>")
	)
	(segment
		(start 419.837108 -233.44124)
		(end 419.72103 -233.325162)
		(width 0.18288)
		(layer "In11.Cu")
		(net "M_H_CPU0_SB_CB<0>")
	)
	(segment
		(start 414.01492 -234.7595)
		(end 414.01492 -234.284266)
		(width 0.18288)
		(layer "In11.Cu")
		(net "M_H_CPU0_SB_CB<0>")
	)
	(segment
		(start 403.449282 -235.712762)
		(end 403.256242 -235.905802)
		(width 0.18288)
		(layer "In11.Cu")
		(net "M_H_CPU0_SB_CB<0>")
	)
	(segment
		(start 404.470362 -236.384338)
		(end 404.152862 -236.384338)
		(width 0.18288)
		(layer "In11.Cu")
		(net "M_H_CPU0_SB_CB<0>")
	)
	(segment
		(start 413.82188 -234.091226)
		(end 412.778194 -234.091226)
		(width 0.18288)
		(layer "In11.Cu")
		(net "M_H_CPU0_SB_CB<0>")
	)
	(segment
		(start 389.043164 -241.809524)
		(end 387.876542 -241.809524)
		(width 0.088646)
		(layer "In11.Cu")
		(net "M_H_CPU0_SB_CB<0>")
	)
	(segment
		(start 418.801042 -233.518202)
		(end 418.801042 -233.865928)
		(width 0.18288)
		(layer "In11.Cu")
		(net "M_H_CPU0_SB_CB<0>")
	)
	(segment
		(start 446.509394 -235.043726)
		(end 446.395094 -235.158026)
		(width 0.18288)
		(layer "In11.Cu")
		(net "M_H_CPU0_SB_CB<0>")
	)
	(segment
		(start 414.20796 -234.95254)
		(end 414.01492 -234.7595)
		(width 0.18288)
		(layer "In11.Cu")
		(net "M_H_CPU0_SB_CB<0>")
	)
	(segment
		(start 382.418082 -241.156744)
		(end 382.407668 -241.16284)
		(width 0.088646)
		(layer "In11.Cu")
		(net "M_H_CPU0_SB_CB<0>")
	)
	(segment
		(start 403.063202 -236.384338)
		(end 402.745702 -236.384338)
		(width 0.18288)
		(layer "In11.Cu")
		(net "M_H_CPU0_SB_CB<0>")
	)
	(segment
		(start 441.511436 -234.57408)
		(end 441.06338 -234.57408)
		(width 0.18288)
		(layer "In11.Cu")
		(net "M_H_CPU0_SB_CB<0>")
	)
	(segment
		(start 408.198066 -234.24769)
		(end 407.456386 -234.24769)
		(width 0.18288)
		(layer "In11.Cu")
		(net "M_H_CPU0_SB_CB<0>")
	)
	(segment
		(start 441.972446 -234.291378)
		(end 441.794138 -234.291378)
		(width 0.18288)
		(layer "In11.Cu")
		(net "M_H_CPU0_SB_CB<0>")
	)
	(segment
		(start 387.612128 -242.073938)
		(end 386.548122 -242.073938)
		(width 0.088646)
		(layer "In11.Cu")
		(net "M_H_CPU0_SB_CB<0>")
	)
	(segment
		(start 446.395094 -235.158026)
		(end 442.839094 -235.158026)
		(width 0.18288)
		(layer "In11.Cu")
		(net "M_H_CPU0_SB_CB<0>")
	)
	(segment
		(start 412.552134 -234.317286)
		(end 410.880306 -234.317286)
		(width 0.18288)
		(layer "In11.Cu")
		(net "M_H_CPU0_SB_CB<0>")
	)
	(segment
		(start 419.72103 -233.325162)
		(end 418.994082 -233.325162)
		(width 0.18288)
		(layer "In11.Cu")
		(net "M_H_CPU0_SB_CB<0>")
	)
	(segment
		(start 403.959822 -235.905802)
		(end 403.766782 -235.712762)
		(width 0.18288)
		(layer "In11.Cu")
		(net "M_H_CPU0_SB_CB<0>")
	)
	(segment
		(start 450.911214 -235.566712)
		(end 450.292724 -235.566712)
		(width 0.18288)
		(layer "In11.Cu")
		(net "M_H_CPU0_SB_CB<0>")
	)
	(segment
		(start 403.766782 -235.712762)
		(end 403.449282 -235.712762)
		(width 0.18288)
		(layer "In11.Cu")
		(net "M_H_CPU0_SB_CB<0>")
	)
	(segment
		(start 449.769738 -235.043726)
		(end 446.509394 -235.043726)
		(width 0.18288)
		(layer "In11.Cu")
		(net "M_H_CPU0_SB_CB<0>")
	)
	(segment
		(start 423.49928 -232.423716)
		(end 422.878758 -232.423716)
		(width 0.18288)
		(layer "In11.Cu")
		(net "M_H_CPU0_SB_CB<0>")
	)
	(segment
		(start 414.7185 -234.7595)
		(end 414.52546 -234.95254)
		(width 0.18288)
		(layer "In11.Cu")
		(net "M_H_CPU0_SB_CB<0>")
	)
	(segment
		(start 418.097462 -233.865928)
		(end 418.097462 -233.518202)
		(width 0.18288)
		(layer "In11.Cu")
		(net "M_H_CPU0_SB_CB<0>")
	)
	(segment
		(start 416.270694 -234.091226)
		(end 414.91154 -234.091226)
		(width 0.18288)
		(layer "In11.Cu")
		(net "M_H_CPU0_SB_CB<0>")
	)
	(segment
		(start 410.880306 -234.317286)
		(end 410.369766 -234.827826)
		(width 0.18288)
		(layer "In11.Cu")
		(net "M_H_CPU0_SB_CB<0>")
	)
	(segment
		(start 372.080282 -241.80546)
		(end 371.68328 -241.576352)
		(width 0.088646)
		(layer "In11.Cu")
		(net "M_H_CPU0_SB_CB<0>")
	)
	(segment
		(start 450.292724 -235.566712)
		(end 449.769738 -235.043726)
		(width 0.18288)
		(layer "In11.Cu")
		(net "M_H_CPU0_SB_CB<0>")
	)
	(segment
		(start 418.290502 -234.058968)
		(end 418.097462 -233.865928)
		(width 0.18288)
		(layer "In11.Cu")
		(net "M_H_CPU0_SB_CB<0>")
	)
	(segment
		(start 408.778202 -234.827826)
		(end 408.198066 -234.24769)
		(width 0.18288)
		(layer "In11.Cu")
		(net "M_H_CPU0_SB_CB<0>")
	)
	(segment
		(start 414.01492 -234.284266)
		(end 413.82188 -234.091226)
		(width 0.18288)
		(layer "In11.Cu")
		(net "M_H_CPU0_SB_CB<0>")
	)
	(segment
		(start 376.779536 -241.156744)
		(end 376.769122 -241.16284)
		(width 0.088646)
		(layer "In11.Cu")
		(net "M_H_CPU0_SB_CB<0>")
	)
	(segment
		(start 441.06338 -234.57408)
		(end 440.780678 -234.291378)
		(width 0.18288)
		(layer "In11.Cu")
		(net "M_H_CPU0_SB_CB<0>")
	)
	(segment
		(start 412.778194 -234.091226)
		(end 412.552134 -234.317286)
		(width 0.18288)
		(layer "In11.Cu")
		(net "M_H_CPU0_SB_CB<0>")
	)
	(segment
		(start 404.856442 -235.712762)
		(end 404.663402 -235.905802)
		(width 0.18288)
		(layer "In11.Cu")
		(net "M_H_CPU0_SB_CB<0>")
	)
	(segment
		(start 431.587148 -233.405172)
		(end 431.541682 -233.450638)
		(width 0.18288)
		(layer "In11.Cu")
		(net "M_H_CPU0_SB_CB<0>")
	)
	(segment
		(start 439.062622 -234.291378)
		(end 438.519824 -233.74858)
		(width 0.18288)
		(layer "In11.Cu")
		(net "M_H_CPU0_SB_CB<0>")
	)
	(segment
		(start 381.478536 -241.156744)
		(end 381.468122 -241.16284)
		(width 0.088646)
		(layer "In11.Cu")
		(net "M_H_CPU0_SB_CB<0>")
	)
	(segment
		(start 395.300962 -241.809524)
		(end 389.043164 -241.809524)
		(width 0.18288)
		(layer "In11.Cu")
		(net "M_H_CPU0_SB_CB<0>")
	)
	(segment
		(start 404.663402 -235.905802)
		(end 404.663402 -236.191298)
		(width 0.18288)
		(layer "In11.Cu")
		(net "M_H_CPU0_SB_CB<0>")
	)
	(segment
		(start 426.140372 -232.770426)
		(end 425.961302 -232.591356)
		(width 0.18288)
		(layer "In11.Cu")
		(net "M_H_CPU0_SB_CB<0>")
	)
	(segment
		(start 423.66692 -232.591356)
		(end 423.49928 -232.423716)
		(width 0.18288)
		(layer "In11.Cu")
		(net "M_H_CPU0_SB_CB<0>")
	)
	(segment
		(start 427.872906 -233.450638)
		(end 427.192694 -232.770426)
		(width 0.18288)
		(layer "In11.Cu")
		(net "M_H_CPU0_SB_CB<0>")
	)
	(segment
		(start 383.358136 -241.156744)
		(end 383.347722 -241.16284)
		(width 0.088646)
		(layer "In11.Cu")
		(net "M_H_CPU0_SB_CB<0>")
	)
	(segment
		(start 421.861234 -233.44124)
		(end 419.837108 -233.44124)
		(width 0.18288)
		(layer "In11.Cu")
		(net "M_H_CPU0_SB_CB<0>")
	)
	(segment
		(start 441.794138 -234.291378)
		(end 441.511436 -234.57408)
		(width 0.18288)
		(layer "In11.Cu")
		(net "M_H_CPU0_SB_CB<0>")
	)
	(segment
		(start 375.839482 -241.156744)
		(end 375.82475 -241.16538)
		(width 0.088646)
		(layer "In11.Cu")
		(net "M_H_CPU0_SB_CB<0>")
	)
	(segment
		(start 431.541682 -233.450638)
		(end 427.872906 -233.450638)
		(width 0.18288)
		(layer "In11.Cu")
		(net "M_H_CPU0_SB_CB<0>")
	)
	(segment
		(start 418.608002 -234.058968)
		(end 418.290502 -234.058968)
		(width 0.18288)
		(layer "In11.Cu")
		(net "M_H_CPU0_SB_CB<0>")
	)
	(segment
		(start 422.878758 -232.423716)
		(end 421.861234 -233.44124)
		(width 0.18288)
		(layer "In11.Cu")
		(net "M_H_CPU0_SB_CB<0>")
	)
	(segment
		(start 403.256242 -235.905802)
		(end 403.256242 -236.191298)
		(width 0.18288)
		(layer "In11.Cu")
		(net "M_H_CPU0_SB_CB<0>")
	)
	(segment
		(start 405.991314 -235.712762)
		(end 404.856442 -235.712762)
		(width 0.18288)
		(layer "In11.Cu")
		(net "M_H_CPU0_SB_CB<0>")
	)
	(segment
		(start 437.050434 -233.443526)
		(end 434.799994 -233.443526)
		(width 0.18288)
		(layer "In11.Cu")
		(net "M_H_CPU0_SB_CB<0>")
	)
	(segment
		(start 403.256242 -236.191298)
		(end 403.063202 -236.384338)
		(width 0.18288)
		(layer "In11.Cu")
		(net "M_H_CPU0_SB_CB<0>")
	)
	(segment
		(start 402.552662 -236.191298)
		(end 402.552662 -235.905802)
		(width 0.18288)
		(layer "In11.Cu")
		(net "M_H_CPU0_SB_CB<0>")
	)
	(segment
		(start 377.719082 -241.156744)
		(end 377.708668 -241.16284)
		(width 0.088646)
		(layer "In11.Cu")
		(net "M_H_CPU0_SB_CB<0>")
	)
	(segment
		(start 404.152862 -236.384338)
		(end 403.959822 -236.191298)
		(width 0.18288)
		(layer "In11.Cu")
		(net "M_H_CPU0_SB_CB<0>")
	)
	(segment
		(start 418.801042 -233.865928)
		(end 418.608002 -234.058968)
		(width 0.18288)
		(layer "In11.Cu")
		(net "M_H_CPU0_SB_CB<0>")
	)
	(segment
		(start 434.799994 -233.443526)
		(end 434.76164 -233.405172)
		(width 0.18288)
		(layer "In11.Cu")
		(net "M_H_CPU0_SB_CB<0>")
	)
	(segment
		(start 379.598682 -241.156744)
		(end 379.58395 -241.16538)
		(width 0.088646)
		(layer "In11.Cu")
		(net "M_H_CPU0_SB_CB<0>")
	)
	(segment
		(start 410.369766 -234.827826)
		(end 408.778202 -234.827826)
		(width 0.18288)
		(layer "In11.Cu")
		(net "M_H_CPU0_SB_CB<0>")
	)
	(segment
		(start 440.780678 -234.291378)
		(end 439.062622 -234.291378)
		(width 0.18288)
		(layer "In11.Cu")
		(net "M_H_CPU0_SB_CB<0>")
	)
	(segment
		(start 418.994082 -233.325162)
		(end 418.801042 -233.518202)
		(width 0.18288)
		(layer "In11.Cu")
		(net "M_H_CPU0_SB_CB<0>")
	)
	(segment
		(start 414.91154 -234.091226)
		(end 414.7185 -234.284266)
		(width 0.18288)
		(layer "In11.Cu")
		(net "M_H_CPU0_SB_CB<0>")
	)
	(segment
		(start 402.359622 -235.712762)
		(end 401.397724 -235.712762)
		(width 0.18288)
		(layer "In11.Cu")
		(net "M_H_CPU0_SB_CB<0>")
	)
	(segment
		(start 378.658882 -241.156744)
		(end 378.64415 -241.16538)
		(width 0.088646)
		(layer "In11.Cu")
		(net "M_H_CPU0_SB_CB<0>")
	)
	(segment
		(start 437.355488 -233.74858)
		(end 437.050434 -233.443526)
		(width 0.18288)
		(layer "In11.Cu")
		(net "M_H_CPU0_SB_CB<0>")
	)
	(segment
		(start 427.192694 -232.770426)
		(end 426.140372 -232.770426)
		(width 0.18288)
		(layer "In11.Cu")
		(net "M_H_CPU0_SB_CB<0>")
	)
	(segment
		(start 404.663402 -236.191298)
		(end 404.470362 -236.384338)
		(width 0.18288)
		(layer "In11.Cu")
		(net "M_H_CPU0_SB_CB<0>")
	)
	(segment
		(start 417.904422 -233.325162)
		(end 417.036758 -233.325162)
		(width 0.18288)
		(layer "In11.Cu")
		(net "M_H_CPU0_SB_CB<0>")
	)
	(segment
		(start 401.397724 -235.712762)
		(end 395.300962 -241.809524)
		(width 0.18288)
		(layer "In11.Cu")
		(net "M_H_CPU0_SB_CB<0>")
	)
	(segment
		(start 386.548122 -242.073938)
		(end 385.69011 -241.215926)
		(width 0.088646)
		(layer "In11.Cu")
		(net "M_H_CPU0_SB_CB<0>")
	)
	(segment
		(start 407.456386 -234.24769)
		(end 405.991314 -235.712762)
		(width 0.18288)
		(layer "In11.Cu")
		(net "M_H_CPU0_SB_CB<0>")
	)
	(segment
		(start 387.876542 -241.809524)
		(end 387.612128 -242.073938)
		(width 0.088646)
		(layer "In11.Cu")
		(net "M_H_CPU0_SB_CB<0>")
	)
	(segment
		(start 418.097462 -233.518202)
		(end 417.904422 -233.325162)
		(width 0.18288)
		(layer "In11.Cu")
		(net "M_H_CPU0_SB_CB<0>")
	)
	(segment
		(start 438.519824 -233.74858)
		(end 437.355488 -233.74858)
		(width 0.18288)
		(layer "In11.Cu")
		(net "M_H_CPU0_SB_CB<0>")
	)
	(arc
		(start 380.538482 -241.156744)
		(mid 380.25578 -241.23252)
		(end 379.973078 -241.156744)
		(width 0.088646)
		(layer "In11.Cu")
		(net "M_H_CPU0_SB_CB<0>")
	)
	(arc
		(start 377.153932 -241.156744)
		(mid 376.966734 -241.106601)
		(end 376.779536 -241.156744)
		(width 0.088646)
		(layer "In11.Cu")
		(net "M_H_CPU0_SB_CB<0>")
	)
	(arc
		(start 384.672332 -241.156744)
		(mid 384.485134 -241.106601)
		(end 384.297936 -241.156744)
		(width 0.088646)
		(layer "In11.Cu")
		(net "M_H_CPU0_SB_CB<0>")
	)
	(arc
		(start 382.407668 -241.16284)
		(mid 382.12949 -241.232563)
		(end 381.852932 -241.156744)
		(width 0.088646)
		(layer "In11.Cu")
		(net "M_H_CPU0_SB_CB<0>")
	)
	(arc
		(start 374.334278 -241.156744)
		(mid 374.14708 -241.106601)
		(end 373.959882 -241.156744)
		(width 0.088646)
		(layer "In11.Cu")
		(net "M_H_CPU0_SB_CB<0>")
	)
	(arc
		(start 374.88495 -241.16538)
		(mid 374.608475 -241.2327)
		(end 374.334278 -241.156744)
		(width 0.088646)
		(layer "In11.Cu")
		(net "M_H_CPU0_SB_CB<0>")
	)
	(arc
		(start 377.708668 -241.16284)
		(mid 377.43049 -241.232563)
		(end 377.153932 -241.156744)
		(width 0.088646)
		(layer "In11.Cu")
		(net "M_H_CPU0_SB_CB<0>")
	)
	(arc
		(start 385.69011 -241.215926)
		(mid 385.65306 -241.18378)
		(end 385.612132 -241.156744)
		(width 0.088646)
		(layer "In11.Cu")
		(net "M_H_CPU0_SB_CB<0>")
	)
	(arc
		(start 373.394478 -241.80546)
		(mid 373.205443 -241.858154)
		(end 373.014494 -241.812826)
		(width 0.088646)
		(layer "In11.Cu")
		(net "M_H_CPU0_SB_CB<0>")
	)
	(arc
		(start 379.973078 -241.156744)
		(mid 379.78588 -241.106601)
		(end 379.598682 -241.156744)
		(width 0.088646)
		(layer "In11.Cu")
		(net "M_H_CPU0_SB_CB<0>")
	)
	(arc
		(start 373.404892 -241.799364)
		(mid 373.399669 -241.802384)
		(end 373.394478 -241.80546)
		(width 0.088646)
		(layer "In11.Cu")
		(net "M_H_CPU0_SB_CB<0>")
	)
	(arc
		(start 376.213878 -241.156744)
		(mid 376.02668 -241.106601)
		(end 375.839482 -241.156744)
		(width 0.088646)
		(layer "In11.Cu")
		(net "M_H_CPU0_SB_CB<0>")
	)
	(arc
		(start 373.911368 -241.190018)
		(mid 373.826741 -241.287134)
		(end 373.78005 -241.407188)
		(width 0.088646)
		(layer "In11.Cu")
		(net "M_H_CPU0_SB_CB<0>")
	)
	(arc
		(start 382.792478 -241.156744)
		(mid 382.60528 -241.106601)
		(end 382.418082 -241.156744)
		(width 0.088646)
		(layer "In11.Cu")
		(net "M_H_CPU0_SB_CB<0>")
	)
	(arc
		(start 384.297936 -241.156744)
		(mid 384.015234 -241.23252)
		(end 383.732532 -241.156744)
		(width 0.088646)
		(layer "In11.Cu")
		(net "M_H_CPU0_SB_CB<0>")
	)
	(arc
		(start 373.77497 -241.43843)
		(mid 373.752863 -241.507576)
		(end 373.706136 -241.563144)
		(width 0.088646)
		(layer "In11.Cu")
		(net "M_H_CPU0_SB_CB<0>")
	)
	(arc
		(start 385.237736 -241.156744)
		(mid 384.955034 -241.23252)
		(end 384.672332 -241.156744)
		(width 0.088646)
		(layer "In11.Cu")
		(net "M_H_CPU0_SB_CB<0>")
	)
	(arc
		(start 385.612132 -241.156744)
		(mid 385.424934 -241.106601)
		(end 385.237736 -241.156744)
		(width 0.088646)
		(layer "In11.Cu")
		(net "M_H_CPU0_SB_CB<0>")
	)
	(arc
		(start 381.468122 -241.16284)
		(mid 381.18969 -241.232686)
		(end 380.912878 -241.156744)
		(width 0.088646)
		(layer "In11.Cu")
		(net "M_H_CPU0_SB_CB<0>")
	)
	(arc
		(start 373.959882 -241.156744)
		(mid 373.934957 -241.172408)
		(end 373.911368 -241.190018)
		(width 0.088646)
		(layer "In11.Cu")
		(net "M_H_CPU0_SB_CB<0>")
	)
	(arc
		(start 379.58395 -241.16538)
		(mid 379.307475 -241.2327)
		(end 379.033278 -241.156744)
		(width 0.088646)
		(layer "In11.Cu")
		(net "M_H_CPU0_SB_CB<0>")
	)
	(arc
		(start 373.445786 -241.772186)
		(mid 373.425928 -241.786661)
		(end 373.404892 -241.799364)
		(width 0.088646)
		(layer "In11.Cu")
		(net "M_H_CPU0_SB_CB<0>")
	)
	(arc
		(start 383.732532 -241.156744)
		(mid 383.545334 -241.106601)
		(end 383.358136 -241.156744)
		(width 0.088646)
		(layer "In11.Cu")
		(net "M_H_CPU0_SB_CB<0>")
	)
	(arc
		(start 376.769122 -241.16284)
		(mid 376.49069 -241.232686)
		(end 376.213878 -241.156744)
		(width 0.088646)
		(layer "In11.Cu")
		(net "M_H_CPU0_SB_CB<0>")
	)
	(arc
		(start 381.852932 -241.156744)
		(mid 381.665734 -241.106601)
		(end 381.478536 -241.156744)
		(width 0.088646)
		(layer "In11.Cu")
		(net "M_H_CPU0_SB_CB<0>")
	)
	(arc
		(start 378.093478 -241.156744)
		(mid 377.90628 -241.106601)
		(end 377.719082 -241.156744)
		(width 0.088646)
		(layer "In11.Cu")
		(net "M_H_CPU0_SB_CB<0>")
	)
	(arc
		(start 383.347722 -241.16284)
		(mid 383.06929 -241.232686)
		(end 382.792478 -241.156744)
		(width 0.088646)
		(layer "In11.Cu")
		(net "M_H_CPU0_SB_CB<0>")
	)
	(arc
		(start 379.033278 -241.156744)
		(mid 378.84608 -241.106601)
		(end 378.658882 -241.156744)
		(width 0.088646)
		(layer "In11.Cu")
		(net "M_H_CPU0_SB_CB<0>")
	)
	(arc
		(start 378.64415 -241.16538)
		(mid 378.367675 -241.2327)
		(end 378.093478 -241.156744)
		(width 0.088646)
		(layer "In11.Cu")
		(net "M_H_CPU0_SB_CB<0>")
	)
	(arc
		(start 372.454678 -241.80546)
		(mid 372.26748 -241.855603)
		(end 372.080282 -241.80546)
		(width 0.088646)
		(layer "In11.Cu")
		(net "M_H_CPU0_SB_CB<0>")
	)
	(arc
		(start 373.014494 -241.812826)
		(mid 372.735482 -241.741753)
		(end 372.454678 -241.80546)
		(width 0.088646)
		(layer "In11.Cu")
		(net "M_H_CPU0_SB_CB<0>")
	)
	(arc
		(start 373.78005 -241.407188)
		(mid 373.777179 -241.422755)
		(end 373.77497 -241.43843)
		(width 0.088646)
		(layer "In11.Cu")
		(net "M_H_CPU0_SB_CB<0>")
	)
	(arc
		(start 371.68328 -241.576352)
		(mid 371.511747 -241.505331)
		(end 371.32768 -241.481102)
		(width 0.088646)
		(layer "In11.Cu")
		(net "M_H_CPU0_SB_CB<0>")
	)
	(arc
		(start 380.912878 -241.156744)
		(mid 380.72568 -241.106601)
		(end 380.538482 -241.156744)
		(width 0.088646)
		(layer "In11.Cu")
		(net "M_H_CPU0_SB_CB<0>")
	)
	(arc
		(start 375.82475 -241.16538)
		(mid 375.548275 -241.2327)
		(end 375.274078 -241.156744)
		(width 0.088646)
		(layer "In11.Cu")
		(net "M_H_CPU0_SB_CB<0>")
	)
	(arc
		(start 375.274078 -241.156744)
		(mid 375.08688 -241.106601)
		(end 374.899682 -241.156744)
		(width 0.088646)
		(layer "In11.Cu")
		(net "M_H_CPU0_SB_CB<0>")
	)
	(segment
		(start 457.114148 -247.891554)
		(end 457.126594 -247.904)
		(width 0.1016)
		(layer "F.Cu")
		(net "M_H_CPU0_SB_CA<6>")
	)
	(segment
		(start 454.941686 -247.891554)
		(end 457.114148 -247.891554)
		(width 0.1016)
		(layer "F.Cu")
		(net "M_H_CPU0_SB_CA<6>")
	)
	(segment
		(start 453.081644 -247.466612)
		(end 453.575928 -246.972328)
		(width 0.20066)
		(layer "F.Cu")
		(net "M_H_CPU0_SB_CA<6>")
	)
	(segment
		(start 454.92797 -247.891554)
		(end 454.941686 -247.891554)
		(width 0.101854)
		(layer "F.Cu")
		(net "M_H_CPU0_SB_CA<6>")
	)
	(segment
		(start 459.55966 -247.466358)
		(end 459.559914 -247.466612)
		(width 0.20066)
		(layer "F.Cu")
		(net "M_H_CPU0_SB_CA<6>")
	)
	(segment
		(start 374.147334 -245.27256)
		(end 374.14708 -245.272306)
		(width 0.20066)
		(layer "F.Cu")
		(net "M_H_CPU0_SB_CA<6>")
	)
	(segment
		(start 452.016114 -247.466612)
		(end 453.081644 -247.466612)
		(width 0.20066)
		(layer "F.Cu")
		(net "M_H_CPU0_SB_CA<6>")
	)
	(segment
		(start 457.126594 -247.904)
		(end 457.542646 -247.904)
		(width 0.20066)
		(layer "F.Cu")
		(net "M_H_CPU0_SB_CA<6>")
	)
	(segment
		(start 450.911214 -247.466612)
		(end 452.016114 -247.466612)
		(width 0.20066)
		(layer "F.Cu")
		(net "M_H_CPU0_SB_CA<6>")
	)
	(segment
		(start 454.820528 -247.891554)
		(end 454.92797 -247.891554)
		(width 0.20066)
		(layer "F.Cu")
		(net "M_H_CPU0_SB_CA<6>")
	)
	(segment
		(start 453.575928 -246.972328)
		(end 453.901302 -246.972328)
		(width 0.20066)
		(layer "F.Cu")
		(net "M_H_CPU0_SB_CA<6>")
	)
	(segment
		(start 453.901302 -246.972328)
		(end 454.820528 -247.891554)
		(width 0.20066)
		(layer "F.Cu")
		(net "M_H_CPU0_SB_CA<6>")
	)
	(segment
		(start 374.14708 -245.272306)
		(end 374.14708 -244.73662)
		(width 0.20066)
		(layer "F.Cu")
		(net "M_H_CPU0_SB_CA<6>")
	)
	(segment
		(start 457.980288 -247.466358)
		(end 459.55966 -247.466358)
		(width 0.20066)
		(layer "F.Cu")
		(net "M_H_CPU0_SB_CA<6>")
	)
	(segment
		(start 457.542646 -247.904)
		(end 457.980288 -247.466358)
		(width 0.20066)
		(layer "F.Cu")
		(net "M_H_CPU0_SB_CA<6>")
	)
	(segment
		(start 376.871484 -245.560596)
		(end 376.871484 -245.55069)
		(width 0.088646)
		(layer "In11.Cu")
		(net "M_H_CPU0_SB_CA<6>")
	)
	(segment
		(start 435.216046 -248.741184)
		(end 435.009544 -248.534682)
		(width 0.18288)
		(layer "In11.Cu")
		(net "M_H_CPU0_SB_CA<6>")
	)
	(segment
		(start 389.225536 -247.725946)
		(end 387.701282 -247.725946)
		(width 0.18288)
		(layer "In11.Cu")
		(net "M_H_CPU0_SB_CA<6>")
	)
	(segment
		(start 440.979306 -248.594372)
		(end 440.832494 -248.741184)
		(width 0.18288)
		(layer "In11.Cu")
		(net "M_H_CPU0_SB_CA<6>")
	)
	(segment
		(start 438.59069 -248.741184)
		(end 438.42813 -248.903744)
		(width 0.18288)
		(layer "In11.Cu")
		(net "M_H_CPU0_SB_CA<6>")
	)
	(segment
		(start 378.658882 -246.040148)
		(end 378.64415 -246.048784)
		(width 0.088646)
		(layer "In11.Cu")
		(net "M_H_CPU0_SB_CA<6>")
	)
	(segment
		(start 423.465244 -247.724676)
		(end 422.340024 -247.724676)
		(width 0.18288)
		(layer "In11.Cu")
		(net "M_H_CPU0_SB_CA<6>")
	)
	(segment
		(start 422.340024 -247.724676)
		(end 422.173654 -247.891046)
		(width 0.18288)
		(layer "In11.Cu")
		(net "M_H_CPU0_SB_CA<6>")
	)
	(segment
		(start 403.475952 -248.000012)
		(end 403.475952 -248.433082)
		(width 0.18288)
		(layer "In11.Cu")
		(net "M_H_CPU0_SB_CA<6>")
	)
	(segment
		(start 414.199324 -246.487696)
		(end 414.006284 -246.680736)
		(width 0.18288)
		(layer "In11.Cu")
		(net "M_H_CPU0_SB_CA<6>")
	)
	(segment
		(start 386.052568 -247.069864)
		(end 385.563618 -247.069864)
		(width 0.088646)
		(layer "In11.Cu")
		(net "M_H_CPU0_SB_CA<6>")
	)
	(segment
		(start 450.911214 -247.778016)
		(end 450.807074 -247.882156)
		(width 0.18288)
		(layer "In11.Cu")
		(net "M_H_CPU0_SB_CA<6>")
	)
	(segment
		(start 418.91585 -248.063512)
		(end 418.72281 -247.870472)
		(width 0.18288)
		(layer "In11.Cu")
		(net "M_H_CPU0_SB_CA<6>")
	)
	(segment
		(start 425.817792 -247.041162)
		(end 424.148758 -247.041162)
		(width 0.18288)
		(layer "In11.Cu")
		(net "M_H_CPU0_SB_CA<6>")
	)
	(segment
		(start 450.352922 -248.07037)
		(end 447.22415 -248.07037)
		(width 0.18288)
		(layer "In11.Cu")
		(net "M_H_CPU0_SB_CA<6>")
	)
	(segment
		(start 446.369694 -248.924826)
		(end 442.839094 -248.924826)
		(width 0.18288)
		(layer "In11.Cu")
		(net "M_H_CPU0_SB_CA<6>")
	)
	(segment
		(start 427.245018 -246.895874)
		(end 425.96308 -246.895874)
		(width 0.18288)
		(layer "In11.Cu")
		(net "M_H_CPU0_SB_CA<6>")
	)
	(segment
		(start 379.598682 -246.040148)
		(end 379.58395 -246.048784)
		(width 0.088646)
		(layer "In11.Cu")
		(net "M_H_CPU0_SB_CA<6>")
	)
	(segment
		(start 414.902904 -247.711214)
		(end 414.709864 -247.518174)
		(width 0.18288)
		(layer "In11.Cu")
		(net "M_H_CPU0_SB_CA<6>")
	)
	(segment
		(start 442.50864 -248.594372)
		(end 440.979306 -248.594372)
		(width 0.18288)
		(layer "In11.Cu")
		(net "M_H_CPU0_SB_CA<6>")
	)
	(segment
		(start 432.81092 -248.08434)
		(end 431.649124 -248.08434)
		(width 0.18288)
		(layer "In11.Cu")
		(net "M_H_CPU0_SB_CA<6>")
	)
	(segment
		(start 404.883112 -248.000012)
		(end 404.883112 -248.433082)
		(width 0.18288)
		(layer "In11.Cu")
		(net "M_H_CPU0_SB_CA<6>")
	)
	(segment
		(start 424.148758 -247.041162)
		(end 423.465244 -247.724676)
		(width 0.18288)
		(layer "In11.Cu")
		(net "M_H_CPU0_SB_CA<6>")
	)
	(segment
		(start 403.282912 -248.626122)
		(end 402.965412 -248.626122)
		(width 0.18288)
		(layer "In11.Cu")
		(net "M_H_CPU0_SB_CA<6>")
	)
	(segment
		(start 375.369582 -245.226332)
		(end 375.359168 -245.232428)
		(width 0.088646)
		(layer "In11.Cu")
		(net "M_H_CPU0_SB_CA<6>")
	)
	(segment
		(start 414.006284 -246.680736)
		(end 414.006284 -247.518174)
		(width 0.18288)
		(layer "In11.Cu")
		(net "M_H_CPU0_SB_CA<6>")
	)
	(segment
		(start 422.173654 -247.891046)
		(end 420.682166 -247.891046)
		(width 0.18288)
		(layer "In11.Cu")
		(net "M_H_CPU0_SB_CA<6>")
	)
	(segment
		(start 385.563618 -247.069864)
		(end 385.295394 -246.91467)
		(width 0.088646)
		(layer "In11.Cu")
		(net "M_H_CPU0_SB_CA<6>")
	)
	(segment
		(start 413.813244 -247.711214)
		(end 412.772606 -247.711214)
		(width 0.18288)
		(layer "In11.Cu")
		(net "M_H_CPU0_SB_CA<6>")
	)
	(segment
		(start 404.690072 -248.626122)
		(end 404.372572 -248.626122)
		(width 0.18288)
		(layer "In11.Cu")
		(net "M_H_CPU0_SB_CA<6>")
	)
	(segment
		(start 420.682166 -247.891046)
		(end 420.681912 -247.8913)
		(width 0.18288)
		(layer "In11.Cu")
		(net "M_H_CPU0_SB_CA<6>")
	)
	(segment
		(start 391.150856 -246.92864)
		(end 389.225536 -247.725946)
		(width 0.18288)
		(layer "In11.Cu")
		(net "M_H_CPU0_SB_CA<6>")
	)
	(segment
		(start 414.516824 -246.487696)
		(end 414.199324 -246.487696)
		(width 0.18288)
		(layer "In11.Cu")
		(net "M_H_CPU0_SB_CA<6>")
	)
	(segment
		(start 405.076152 -247.806972)
		(end 404.883112 -248.000012)
		(width 0.18288)
		(layer "In11.Cu")
		(net "M_H_CPU0_SB_CA<6>")
	)
	(segment
		(start 433.48275 -247.891046)
		(end 433.004214 -247.891046)
		(width 0.18288)
		(layer "In11.Cu")
		(net "M_H_CPU0_SB_CA<6>")
	)
	(segment
		(start 431.649124 -248.08434)
		(end 431.337974 -247.77319)
		(width 0.18288)
		(layer "In11.Cu")
		(net "M_H_CPU0_SB_CA<6>")
	)
	(segment
		(start 409.450794 -248.061226)
		(end 409.19654 -247.806972)
		(width 0.18288)
		(layer "In11.Cu")
		(net "M_H_CPU0_SB_CA<6>")
	)
	(segment
		(start 419.716458 -248.063512)
		(end 418.91585 -248.063512)
		(width 0.18288)
		(layer "In11.Cu")
		(net "M_H_CPU0_SB_CA<6>")
	)
	(segment
		(start 402.772372 -248.433082)
		(end 402.772372 -248.000012)
		(width 0.18288)
		(layer "In11.Cu")
		(net "M_H_CPU0_SB_CA<6>")
	)
	(segment
		(start 400.876516 -247.646444)
		(end 398.818354 -247.646444)
		(width 0.18288)
		(layer "In11.Cu")
		(net "M_H_CPU0_SB_CA<6>")
	)
	(segment
		(start 414.709864 -247.518174)
		(end 414.709864 -246.680736)
		(width 0.18288)
		(layer "In11.Cu")
		(net "M_H_CPU0_SB_CA<6>")
	)
	(segment
		(start 404.372572 -248.626122)
		(end 404.179532 -248.433082)
		(width 0.18288)
		(layer "In11.Cu")
		(net "M_H_CPU0_SB_CA<6>")
	)
	(segment
		(start 412.422594 -248.061226)
		(end 409.450794 -248.061226)
		(width 0.18288)
		(layer "In11.Cu")
		(net "M_H_CPU0_SB_CA<6>")
	)
	(segment
		(start 435.009544 -248.534682)
		(end 434.126386 -248.534682)
		(width 0.18288)
		(layer "In11.Cu")
		(net "M_H_CPU0_SB_CA<6>")
	)
	(segment
		(start 434.126386 -248.534682)
		(end 433.48275 -247.891046)
		(width 0.18288)
		(layer "In11.Cu")
		(net "M_H_CPU0_SB_CA<6>")
	)
	(segment
		(start 402.579332 -247.806972)
		(end 401.037044 -247.806972)
		(width 0.18288)
		(layer "In11.Cu")
		(net "M_H_CPU0_SB_CA<6>")
	)
	(segment
		(start 418.21227 -246.790464)
		(end 418.01923 -246.983504)
		(width 0.18288)
		(layer "In11.Cu")
		(net "M_H_CPU0_SB_CA<6>")
	)
	(segment
		(start 429.277526 -247.277382)
		(end 427.626526 -247.277382)
		(width 0.18288)
		(layer "In11.Cu")
		(net "M_H_CPU0_SB_CA<6>")
	)
	(segment
		(start 414.709864 -246.680736)
		(end 414.516824 -246.487696)
		(width 0.18288)
		(layer "In11.Cu")
		(net "M_H_CPU0_SB_CA<6>")
	)
	(segment
		(start 404.179532 -248.433082)
		(end 404.179532 -248.000012)
		(width 0.18288)
		(layer "In11.Cu")
		(net "M_H_CPU0_SB_CA<6>")
	)
	(segment
		(start 418.72281 -247.870472)
		(end 418.72281 -246.983504)
		(width 0.18288)
		(layer "In11.Cu")
		(net "M_H_CPU0_SB_CA<6>")
	)
	(segment
		(start 403.475952 -248.433082)
		(end 403.282912 -248.626122)
		(width 0.18288)
		(layer "In11.Cu")
		(net "M_H_CPU0_SB_CA<6>")
	)
	(segment
		(start 402.965412 -248.626122)
		(end 402.772372 -248.433082)
		(width 0.18288)
		(layer "In11.Cu")
		(net "M_H_CPU0_SB_CA<6>")
	)
	(segment
		(start 403.986492 -247.806972)
		(end 403.668992 -247.806972)
		(width 0.18288)
		(layer "In11.Cu")
		(net "M_H_CPU0_SB_CA<6>")
	)
	(segment
		(start 409.19654 -247.806972)
		(end 405.076152 -247.806972)
		(width 0.18288)
		(layer "In11.Cu")
		(net "M_H_CPU0_SB_CA<6>")
	)
	(segment
		(start 440.832494 -248.741184)
		(end 438.59069 -248.741184)
		(width 0.18288)
		(layer "In11.Cu")
		(net "M_H_CPU0_SB_CA<6>")
	)
	(segment
		(start 450.911214 -247.466612)
		(end 450.911214 -247.778016)
		(width 0.18288)
		(layer "In11.Cu")
		(net "M_H_CPU0_SB_CA<6>")
	)
	(segment
		(start 416.621468 -248.063512)
		(end 416.26917 -247.711214)
		(width 0.18288)
		(layer "In11.Cu")
		(net "M_H_CPU0_SB_CA<6>")
	)
	(segment
		(start 397.71828 -246.54637)
		(end 393.072112 -246.54637)
		(width 0.18288)
		(layer "In11.Cu")
		(net "M_H_CPU0_SB_CA<6>")
	)
	(segment
		(start 450.807074 -247.882156)
		(end 450.352922 -248.07037)
		(width 0.18288)
		(layer "In11.Cu")
		(net "M_H_CPU0_SB_CA<6>")
	)
	(segment
		(start 429.773334 -247.77319)
		(end 429.277526 -247.277382)
		(width 0.18288)
		(layer "In11.Cu")
		(net "M_H_CPU0_SB_CA<6>")
	)
	(segment
		(start 418.01923 -247.870472)
		(end 417.82619 -248.063512)
		(width 0.18288)
		(layer "In11.Cu")
		(net "M_H_CPU0_SB_CA<6>")
	)
	(segment
		(start 403.668992 -247.806972)
		(end 403.475952 -248.000012)
		(width 0.18288)
		(layer "In11.Cu")
		(net "M_H_CPU0_SB_CA<6>")
	)
	(segment
		(start 419.88867 -247.8913)
		(end 419.716458 -248.063512)
		(width 0.18288)
		(layer "In11.Cu")
		(net "M_H_CPU0_SB_CA<6>")
	)
	(segment
		(start 412.772606 -247.711214)
		(end 412.422594 -248.061226)
		(width 0.18288)
		(layer "In11.Cu")
		(net "M_H_CPU0_SB_CA<6>")
	)
	(segment
		(start 418.01923 -246.983504)
		(end 418.01923 -247.870472)
		(width 0.18288)
		(layer "In11.Cu")
		(net "M_H_CPU0_SB_CA<6>")
	)
	(segment
		(start 387.0452 -247.069864)
		(end 386.052568 -247.069864)
		(width 0.18288)
		(layer "In11.Cu")
		(net "M_H_CPU0_SB_CA<6>")
	)
	(segment
		(start 387.701282 -247.725946)
		(end 387.0452 -247.069864)
		(width 0.18288)
		(layer "In11.Cu")
		(net "M_H_CPU0_SB_CA<6>")
	)
	(segment
		(start 418.52977 -246.790464)
		(end 418.21227 -246.790464)
		(width 0.18288)
		(layer "In11.Cu")
		(net "M_H_CPU0_SB_CA<6>")
	)
	(segment
		(start 376.692922 -245.231412)
		(end 376.684032 -245.226332)
		(width 0.088646)
		(layer "In11.Cu")
		(net "M_H_CPU0_SB_CA<6>")
	)
	(segment
		(start 401.037044 -247.806972)
		(end 400.876516 -247.646444)
		(width 0.18288)
		(layer "In11.Cu")
		(net "M_H_CPU0_SB_CA<6>")
	)
	(segment
		(start 416.26917 -247.711214)
		(end 414.902904 -247.711214)
		(width 0.18288)
		(layer "In11.Cu")
		(net "M_H_CPU0_SB_CA<6>")
	)
	(segment
		(start 438.42813 -248.903744)
		(end 437.582056 -248.903744)
		(width 0.18288)
		(layer "In11.Cu")
		(net "M_H_CPU0_SB_CA<6>")
	)
	(segment
		(start 418.72281 -246.983504)
		(end 418.52977 -246.790464)
		(width 0.18288)
		(layer "In11.Cu")
		(net "M_H_CPU0_SB_CA<6>")
	)
	(segment
		(start 374.804432 -245.226332)
		(end 374.727216 -245.181882)
		(width 0.088646)
		(layer "In11.Cu")
		(net "M_H_CPU0_SB_CA<6>")
	)
	(segment
		(start 417.82619 -248.063512)
		(end 416.621468 -248.063512)
		(width 0.18288)
		(layer "In11.Cu")
		(net "M_H_CPU0_SB_CA<6>")
	)
	(segment
		(start 404.179532 -248.000012)
		(end 403.986492 -247.806972)
		(width 0.18288)
		(layer "In11.Cu")
		(net "M_H_CPU0_SB_CA<6>")
	)
	(segment
		(start 433.004214 -247.891046)
		(end 432.81092 -248.08434)
		(width 0.18288)
		(layer "In11.Cu")
		(net "M_H_CPU0_SB_CA<6>")
	)
	(segment
		(start 447.22415 -248.07037)
		(end 446.369694 -248.924826)
		(width 0.18288)
		(layer "In11.Cu")
		(net "M_H_CPU0_SB_CA<6>")
	)
	(segment
		(start 404.883112 -248.433082)
		(end 404.690072 -248.626122)
		(width 0.18288)
		(layer "In11.Cu")
		(net "M_H_CPU0_SB_CA<6>")
	)
	(segment
		(start 437.582056 -248.903744)
		(end 437.419496 -248.741184)
		(width 0.18288)
		(layer "In11.Cu")
		(net "M_H_CPU0_SB_CA<6>")
	)
	(segment
		(start 425.96308 -246.895874)
		(end 425.817792 -247.041162)
		(width 0.18288)
		(layer "In11.Cu")
		(net "M_H_CPU0_SB_CA<6>")
	)
	(segment
		(start 381.478536 -246.040148)
		(end 381.468122 -246.046244)
		(width 0.088646)
		(layer "In11.Cu")
		(net "M_H_CPU0_SB_CA<6>")
	)
	(segment
		(start 398.818354 -247.646444)
		(end 397.71828 -246.54637)
		(width 0.18288)
		(layer "In11.Cu")
		(net "M_H_CPU0_SB_CA<6>")
	)
	(segment
		(start 375.754392 -245.232428)
		(end 375.743978 -245.226332)
		(width 0.088646)
		(layer "In11.Cu")
		(net "M_H_CPU0_SB_CA<6>")
	)
	(segment
		(start 377.719082 -246.040148)
		(end 377.708668 -246.046244)
		(width 0.088646)
		(layer "In11.Cu")
		(net "M_H_CPU0_SB_CA<6>")
	)
	(segment
		(start 402.772372 -248.000012)
		(end 402.579332 -247.806972)
		(width 0.18288)
		(layer "In11.Cu")
		(net "M_H_CPU0_SB_CA<6>")
	)
	(segment
		(start 393.072112 -246.54637)
		(end 391.150856 -246.92864)
		(width 0.18288)
		(layer "In11.Cu")
		(net "M_H_CPU0_SB_CA<6>")
	)
	(segment
		(start 427.626526 -247.277382)
		(end 427.245018 -246.895874)
		(width 0.18288)
		(layer "In11.Cu")
		(net "M_H_CPU0_SB_CA<6>")
	)
	(segment
		(start 383.919984 -246.374412)
		(end 383.919984 -246.364506)
		(width 0.088646)
		(layer "In11.Cu")
		(net "M_H_CPU0_SB_CA<6>")
	)
	(segment
		(start 420.681912 -247.8913)
		(end 419.88867 -247.8913)
		(width 0.18288)
		(layer "In11.Cu")
		(net "M_H_CPU0_SB_CA<6>")
	)
	(segment
		(start 431.337974 -247.77319)
		(end 429.773334 -247.77319)
		(width 0.18288)
		(layer "In11.Cu")
		(net "M_H_CPU0_SB_CA<6>")
	)
	(segment
		(start 442.839094 -248.924826)
		(end 442.50864 -248.594372)
		(width 0.18288)
		(layer "In11.Cu")
		(net "M_H_CPU0_SB_CA<6>")
	)
	(segment
		(start 437.419496 -248.741184)
		(end 435.216046 -248.741184)
		(width 0.18288)
		(layer "In11.Cu")
		(net "M_H_CPU0_SB_CA<6>")
	)
	(segment
		(start 414.006284 -247.518174)
		(end 413.813244 -247.711214)
		(width 0.18288)
		(layer "In11.Cu")
		(net "M_H_CPU0_SB_CA<6>")
	)
	(segment
		(start 383.741422 -246.045228)
		(end 383.732532 -246.040148)
		(width 0.088646)
		(layer "In11.Cu")
		(net "M_H_CPU0_SB_CA<6>")
	)
	(arc
		(start 379.033278 -246.040148)
		(mid 378.84608 -245.990005)
		(end 378.658882 -246.040148)
		(width 0.088646)
		(layer "In11.Cu")
		(net "M_H_CPU0_SB_CA<6>")
	)
	(arc
		(start 383.919984 -246.364506)
		(mid 383.872305 -246.181606)
		(end 383.741422 -246.045228)
		(width 0.088646)
		(layer "In11.Cu")
		(net "M_H_CPU0_SB_CA<6>")
	)
	(arc
		(start 382.792732 -246.040148)
		(mid 382.605534 -245.990005)
		(end 382.418336 -246.040148)
		(width 0.088646)
		(layer "In11.Cu")
		(net "M_H_CPU0_SB_CA<6>")
	)
	(arc
		(start 375.359168 -245.232428)
		(mid 375.08099 -245.30212)
		(end 374.804432 -245.226332)
		(width 0.088646)
		(layer "In11.Cu")
		(net "M_H_CPU0_SB_CA<6>")
	)
	(arc
		(start 385.295394 -246.91467)
		(mid 385.216595 -246.889916)
		(end 385.142232 -246.853964)
		(width 0.088646)
		(layer "In11.Cu")
		(net "M_H_CPU0_SB_CA<6>")
	)
	(arc
		(start 380.912878 -246.040148)
		(mid 380.72568 -245.990005)
		(end 380.538482 -246.040148)
		(width 0.088646)
		(layer "In11.Cu")
		(net "M_H_CPU0_SB_CA<6>")
	)
	(arc
		(start 380.538482 -246.040148)
		(mid 380.25578 -246.115924)
		(end 379.973078 -246.040148)
		(width 0.088646)
		(layer "In11.Cu")
		(net "M_H_CPU0_SB_CA<6>")
	)
	(arc
		(start 381.852932 -246.040148)
		(mid 381.665734 -245.990005)
		(end 381.478536 -246.040148)
		(width 0.088646)
		(layer "In11.Cu")
		(net "M_H_CPU0_SB_CA<6>")
	)
	(arc
		(start 377.708668 -246.046244)
		(mid 377.152991 -246.039692)
		(end 376.871484 -245.560596)
		(width 0.088646)
		(layer "In11.Cu")
		(net "M_H_CPU0_SB_CA<6>")
	)
	(arc
		(start 383.358136 -246.040148)
		(mid 383.075434 -246.115924)
		(end 382.792732 -246.040148)
		(width 0.088646)
		(layer "In11.Cu")
		(net "M_H_CPU0_SB_CA<6>")
	)
	(arc
		(start 376.684032 -245.226332)
		(mid 376.496834 -245.176189)
		(end 376.309636 -245.226332)
		(width 0.088646)
		(layer "In11.Cu")
		(net "M_H_CPU0_SB_CA<6>")
	)
	(arc
		(start 379.973078 -246.040148)
		(mid 379.78588 -245.990005)
		(end 379.598682 -246.040148)
		(width 0.088646)
		(layer "In11.Cu")
		(net "M_H_CPU0_SB_CA<6>")
	)
	(arc
		(start 383.732532 -246.040148)
		(mid 383.545334 -245.990005)
		(end 383.358136 -246.040148)
		(width 0.088646)
		(layer "In11.Cu")
		(net "M_H_CPU0_SB_CA<6>")
	)
	(arc
		(start 375.743978 -245.226332)
		(mid 375.55678 -245.176189)
		(end 375.369582 -245.226332)
		(width 0.088646)
		(layer "In11.Cu")
		(net "M_H_CPU0_SB_CA<6>")
	)
	(arc
		(start 376.871484 -245.55069)
		(mid 376.823805 -245.36779)
		(end 376.692922 -245.231412)
		(width 0.088646)
		(layer "In11.Cu")
		(net "M_H_CPU0_SB_CA<6>")
	)
	(arc
		(start 378.093478 -246.040148)
		(mid 377.90628 -245.990005)
		(end 377.719082 -246.040148)
		(width 0.088646)
		(layer "In11.Cu")
		(net "M_H_CPU0_SB_CA<6>")
	)
	(arc
		(start 376.309636 -245.226332)
		(mid 376.032823 -245.302168)
		(end 375.754392 -245.232428)
		(width 0.088646)
		(layer "In11.Cu")
		(net "M_H_CPU0_SB_CA<6>")
	)
	(arc
		(start 385.142232 -246.853964)
		(mid 384.955034 -246.803821)
		(end 384.767836 -246.853964)
		(width 0.088646)
		(layer "In11.Cu")
		(net "M_H_CPU0_SB_CA<6>")
	)
	(arc
		(start 382.418336 -246.040148)
		(mid 382.135634 -246.115924)
		(end 381.852932 -246.040148)
		(width 0.088646)
		(layer "In11.Cu")
		(net "M_H_CPU0_SB_CA<6>")
	)
	(arc
		(start 384.767836 -246.853964)
		(mid 384.485134 -246.92974)
		(end 384.202432 -246.853964)
		(width 0.088646)
		(layer "In11.Cu")
		(net "M_H_CPU0_SB_CA<6>")
	)
	(arc
		(start 374.727216 -245.181882)
		(mid 374.422548 -244.978272)
		(end 374.14708 -244.73662)
		(width 0.088646)
		(layer "In11.Cu")
		(net "M_H_CPU0_SB_CA<6>")
	)
	(arc
		(start 378.64415 -246.048784)
		(mid 378.367675 -246.116104)
		(end 378.093478 -246.040148)
		(width 0.088646)
		(layer "In11.Cu")
		(net "M_H_CPU0_SB_CA<6>")
	)
	(arc
		(start 384.202432 -246.853964)
		(mid 383.998097 -246.651359)
		(end 383.919984 -246.374412)
		(width 0.088646)
		(layer "In11.Cu")
		(net "M_H_CPU0_SB_CA<6>")
	)
	(arc
		(start 381.468122 -246.046244)
		(mid 381.18969 -246.11609)
		(end 380.912878 -246.040148)
		(width 0.088646)
		(layer "In11.Cu")
		(net "M_H_CPU0_SB_CA<6>")
	)
	(arc
		(start 379.58395 -246.048784)
		(mid 379.307475 -246.116104)
		(end 379.033278 -246.040148)
		(width 0.088646)
		(layer "In11.Cu")
		(net "M_H_CPU0_SB_CA<6>")
	)
	(segment
		(start 461.709262 -247.884188)
		(end 462.112868 -247.884188)
		(width 0.20066)
		(layer "F.Cu")
		(net "M_H_CPU0_SB_CA<5>")
	)
	(segment
		(start 462.54543 -248.31675)
		(end 463.659982 -248.31675)
		(width 0.20066)
		(layer "F.Cu")
		(net "M_H_CPU0_SB_CA<5>")
	)
	(segment
		(start 460.570326 -248.749058)
		(end 460.844392 -248.749058)
		(width 0.20066)
		(layer "F.Cu")
		(net "M_H_CPU0_SB_CA<5>")
	)
	(segment
		(start 457.751942 -248.31675)
		(end 458.187552 -248.75236)
		(width 0.20066)
		(layer "F.Cu")
		(net "M_H_CPU0_SB_CA<5>")
	)
	(segment
		(start 455.011282 -248.31675)
		(end 456.116182 -248.31675)
		(width 0.20066)
		(layer "F.Cu")
		(net "M_H_CPU0_SB_CA<5>")
	)
	(segment
		(start 458.543152 -248.75236)
		(end 458.55382 -248.741692)
		(width 0.1016)
		(layer "F.Cu")
		(net "M_H_CPU0_SB_CA<5>")
	)
	(segment
		(start 460.844392 -248.749058)
		(end 461.709262 -247.884188)
		(width 0.20066)
		(layer "F.Cu")
		(net "M_H_CPU0_SB_CA<5>")
	)
	(segment
		(start 458.538326 -248.75236)
		(end 458.543152 -248.75236)
		(width 0.101854)
		(layer "F.Cu")
		(net "M_H_CPU0_SB_CA<5>")
	)
	(segment
		(start 456.116182 -248.31675)
		(end 457.751942 -248.31675)
		(width 0.20066)
		(layer "F.Cu")
		(net "M_H_CPU0_SB_CA<5>")
	)
	(segment
		(start 458.55382 -248.741692)
		(end 460.56296 -248.741692)
		(width 0.1016)
		(layer "F.Cu")
		(net "M_H_CPU0_SB_CA<5>")
	)
	(segment
		(start 460.56296 -248.741692)
		(end 460.570326 -248.749058)
		(width 0.1016)
		(layer "F.Cu")
		(net "M_H_CPU0_SB_CA<5>")
	)
	(segment
		(start 376.496834 -246.086376)
		(end 376.496834 -245.55069)
		(width 0.20066)
		(layer "F.Cu")
		(net "M_H_CPU0_SB_CA<5>")
	)
	(segment
		(start 458.187552 -248.75236)
		(end 458.538326 -248.75236)
		(width 0.20066)
		(layer "F.Cu")
		(net "M_H_CPU0_SB_CA<5>")
	)
	(segment
		(start 462.112868 -247.884188)
		(end 462.54543 -248.31675)
		(width 0.20066)
		(layer "F.Cu")
		(net "M_H_CPU0_SB_CA<5>")
	)
	(segment
		(start 376.49658 -246.08663)
		(end 376.496834 -246.086376)
		(width 0.20066)
		(layer "F.Cu")
		(net "M_H_CPU0_SB_CA<5>")
	)
	(segment
		(start 404.997158 -249.142504)
		(end 402.422614 -249.142504)
		(width 0.18288)
		(layer "In11.Cu")
		(net "M_H_CPU0_SB_CA<5>")
	)
	(segment
		(start 386.052568 -247.58269)
		(end 385.838446 -247.58269)
		(width 0.088646)
		(layer "In11.Cu")
		(net "M_H_CPU0_SB_CA<5>")
	)
	(segment
		(start 423.9514 -248.741184)
		(end 423.780712 -248.911872)
		(width 0.18288)
		(layer "In11.Cu")
		(net "M_H_CPU0_SB_CA<5>")
	)
	(segment
		(start 441.074556 -249.776742)
		(end 440.888882 -249.591068)
		(width 0.18288)
		(layer "In11.Cu")
		(net "M_H_CPU0_SB_CA<5>")
	)
	(segment
		(start 450.230494 -248.743724)
		(end 450.082666 -248.595896)
		(width 0.18288)
		(layer "In11.Cu")
		(net "M_H_CPU0_SB_CA<5>")
	)
	(segment
		(start 393.131548 -246.89689)
		(end 391.38352 -247.244616)
		(width 0.18288)
		(layer "In11.Cu")
		(net "M_H_CPU0_SB_CA<5>")
	)
	(segment
		(start 380.538482 -246.688864)
		(end 380.52375 -246.680228)
		(width 0.088646)
		(layer "In11.Cu")
		(net "M_H_CPU0_SB_CA<5>")
	)
	(segment
		(start 454.453752 -248.31675)
		(end 453.860662 -248.90984)
		(width 0.18288)
		(layer "In11.Cu")
		(net "M_H_CPU0_SB_CA<5>")
	)
	(segment
		(start 398.742662 -248.31167)
		(end 397.327882 -246.89689)
		(width 0.18288)
		(layer "In11.Cu")
		(net "M_H_CPU0_SB_CA<5>")
	)
	(segment
		(start 425.639992 -248.548144)
		(end 425.446952 -248.741184)
		(width 0.18288)
		(layer "In11.Cu")
		(net "M_H_CPU0_SB_CA<5>")
	)
	(segment
		(start 447.745866 -249.788426)
		(end 446.953894 -249.788426)
		(width 0.18288)
		(layer "In11.Cu")
		(net "M_H_CPU0_SB_CA<5>")
	)
	(segment
		(start 383.640584 -247.178322)
		(end 383.640584 -247.168416)
		(width 0.088646)
		(layer "In11.Cu")
		(net "M_H_CPU0_SB_CA<5>")
	)
	(segment
		(start 425.833032 -247.700292)
		(end 425.639992 -247.893332)
		(width 0.18288)
		(layer "In11.Cu")
		(net "M_H_CPU0_SB_CA<5>")
	)
	(segment
		(start 448.938396 -248.595896)
		(end 447.745866 -249.788426)
		(width 0.18288)
		(layer "In11.Cu")
		(net "M_H_CPU0_SB_CA<5>")
	)
	(segment
		(start 413.953198 -248.787666)
		(end 413.760158 -248.980706)
		(width 0.18288)
		(layer "In11.Cu")
		(net "M_H_CPU0_SB_CA<5>")
	)
	(segment
		(start 380.923292 -246.682768)
		(end 380.912878 -246.688864)
		(width 0.088646)
		(layer "In11.Cu")
		(net "M_H_CPU0_SB_CA<5>")
	)
	(segment
		(start 418.002974 -248.772426)
		(end 417.809934 -248.579386)
		(width 0.18288)
		(layer "In11.Cu")
		(net "M_H_CPU0_SB_CA<5>")
	)
	(segment
		(start 446.953894 -249.788426)
		(end 446.608454 -249.442986)
		(width 0.18288)
		(layer "In11.Cu")
		(net "M_H_CPU0_SB_CA<5>")
	)
	(segment
		(start 414.849818 -248.980706)
		(end 414.656778 -248.787666)
		(width 0.18288)
		(layer "In11.Cu")
		(net "M_H_CPU0_SB_CA<5>")
	)
	(segment
		(start 389.370824 -248.078244)
		(end 387.29412 -248.078244)
		(width 0.18288)
		(layer "In11.Cu")
		(net "M_H_CPU0_SB_CA<5>")
	)
	(segment
		(start 409.542996 -248.58345)
		(end 409.372308 -248.754138)
		(width 0.18288)
		(layer "In11.Cu")
		(net "M_H_CPU0_SB_CA<5>")
	)
	(segment
		(start 429.051466 -247.832626)
		(end 427.869858 -247.832626)
		(width 0.18288)
		(layer "In11.Cu")
		(net "M_H_CPU0_SB_CA<5>")
	)
	(segment
		(start 455.011282 -248.31675)
		(end 454.453752 -248.31675)
		(width 0.18288)
		(layer "In11.Cu")
		(net "M_H_CPU0_SB_CA<5>")
	)
	(segment
		(start 423.780712 -248.911872)
		(end 422.058338 -248.911872)
		(width 0.18288)
		(layer "In11.Cu")
		(net "M_H_CPU0_SB_CA<5>")
	)
	(segment
		(start 425.639992 -247.893332)
		(end 425.639992 -248.548144)
		(width 0.18288)
		(layer "In11.Cu")
		(net "M_H_CPU0_SB_CA<5>")
	)
	(segment
		(start 417.809934 -248.579386)
		(end 416.449002 -248.579386)
		(width 0.18288)
		(layer "In11.Cu")
		(net "M_H_CPU0_SB_CA<5>")
	)
	(segment
		(start 414.656778 -248.787666)
		(end 414.656778 -248.294652)
		(width 0.18288)
		(layer "In11.Cu")
		(net "M_H_CPU0_SB_CA<5>")
	)
	(segment
		(start 416.047682 -248.980706)
		(end 414.849818 -248.980706)
		(width 0.18288)
		(layer "In11.Cu")
		(net "M_H_CPU0_SB_CA<5>")
	)
	(segment
		(start 385.838446 -247.58269)
		(end 385.801108 -247.545352)
		(width 0.088646)
		(layer "In11.Cu")
		(net "M_H_CPU0_SB_CA<5>")
	)
	(segment
		(start 426.9613 -248.741184)
		(end 426.536612 -248.741184)
		(width 0.18288)
		(layer "In11.Cu")
		(net "M_H_CPU0_SB_CA<5>")
	)
	(segment
		(start 442.608208 -249.776742)
		(end 441.074556 -249.776742)
		(width 0.18288)
		(layer "In11.Cu")
		(net "M_H_CPU0_SB_CA<5>")
	)
	(segment
		(start 401.714462 -248.434352)
		(end 401.010882 -248.434352)
		(width 0.18288)
		(layer "In11.Cu")
		(net "M_H_CPU0_SB_CA<5>")
	)
	(segment
		(start 431.406554 -248.724166)
		(end 431.254408 -248.876312)
		(width 0.18288)
		(layer "In11.Cu")
		(net "M_H_CPU0_SB_CA<5>")
	)
	(segment
		(start 418.513514 -249.251724)
		(end 418.196014 -249.251724)
		(width 0.18288)
		(layer "In11.Cu")
		(net "M_H_CPU0_SB_CA<5>")
	)
	(segment
		(start 431.254408 -248.876312)
		(end 430.095152 -248.876312)
		(width 0.18288)
		(layer "In11.Cu")
		(net "M_H_CPU0_SB_CA<5>")
	)
	(segment
		(start 412.33979 -248.58345)
		(end 409.542996 -248.58345)
		(width 0.18288)
		(layer "In11.Cu")
		(net "M_H_CPU0_SB_CA<5>")
	)
	(segment
		(start 418.899594 -248.579386)
		(end 418.706554 -248.772426)
		(width 0.18288)
		(layer "In11.Cu")
		(net "M_H_CPU0_SB_CA<5>")
	)
	(segment
		(start 440.888882 -249.591068)
		(end 438.839102 -249.591068)
		(width 0.18288)
		(layer "In11.Cu")
		(net "M_H_CPU0_SB_CA<5>")
	)
	(segment
		(start 418.196014 -249.251724)
		(end 418.002974 -249.058684)
		(width 0.18288)
		(layer "In11.Cu")
		(net "M_H_CPU0_SB_CA<5>")
	)
	(segment
		(start 397.327882 -246.89689)
		(end 393.131548 -246.89689)
		(width 0.18288)
		(layer "In11.Cu")
		(net "M_H_CPU0_SB_CA<5>")
	)
	(segment
		(start 426.150532 -247.700292)
		(end 425.833032 -247.700292)
		(width 0.18288)
		(layer "In11.Cu")
		(net "M_H_CPU0_SB_CA<5>")
	)
	(segment
		(start 383.828036 -247.50268)
		(end 383.819146 -247.4976)
		(width 0.088646)
		(layer "In11.Cu")
		(net "M_H_CPU0_SB_CA<5>")
	)
	(segment
		(start 401.010882 -248.434352)
		(end 400.8882 -248.31167)
		(width 0.18288)
		(layer "In11.Cu")
		(net "M_H_CPU0_SB_CA<5>")
	)
	(segment
		(start 434.908452 -249.591068)
		(end 434.692044 -249.807476)
		(width 0.18288)
		(layer "In11.Cu")
		(net "M_H_CPU0_SB_CA<5>")
	)
	(segment
		(start 414.463738 -248.101612)
		(end 414.146238 -248.101612)
		(width 0.18288)
		(layer "In11.Cu")
		(net "M_H_CPU0_SB_CA<5>")
	)
	(segment
		(start 434.692044 -249.807476)
		(end 434.2765 -249.807476)
		(width 0.18288)
		(layer "In11.Cu")
		(net "M_H_CPU0_SB_CA<5>")
	)
	(segment
		(start 413.760158 -248.980706)
		(end 412.737046 -248.980706)
		(width 0.18288)
		(layer "In11.Cu")
		(net "M_H_CPU0_SB_CA<5>")
	)
	(segment
		(start 387.29412 -248.078244)
		(end 386.798566 -247.58269)
		(width 0.18288)
		(layer "In11.Cu")
		(net "M_H_CPU0_SB_CA<5>")
	)
	(segment
		(start 421.88765 -248.741184)
		(end 419.978586 -248.741184)
		(width 0.18288)
		(layer "In11.Cu")
		(net "M_H_CPU0_SB_CA<5>")
	)
	(segment
		(start 378.658882 -246.688864)
		(end 378.64415 -246.680228)
		(width 0.088646)
		(layer "In11.Cu")
		(net "M_H_CPU0_SB_CA<5>")
	)
	(segment
		(start 400.8882 -248.31167)
		(end 398.742662 -248.31167)
		(width 0.18288)
		(layer "In11.Cu")
		(net "M_H_CPU0_SB_CA<5>")
	)
	(segment
		(start 451.35292 -248.743724)
		(end 450.230494 -248.743724)
		(width 0.18288)
		(layer "In11.Cu")
		(net "M_H_CPU0_SB_CA<5>")
	)
	(segment
		(start 451.519036 -248.90984)
		(end 451.35292 -248.743724)
		(width 0.18288)
		(layer "In11.Cu")
		(net "M_H_CPU0_SB_CA<5>")
	)
	(segment
		(start 437.215788 -249.41657)
		(end 437.04129 -249.591068)
		(width 0.18288)
		(layer "In11.Cu")
		(net "M_H_CPU0_SB_CA<5>")
	)
	(segment
		(start 426.343572 -248.548144)
		(end 426.343572 -247.893332)
		(width 0.18288)
		(layer "In11.Cu")
		(net "M_H_CPU0_SB_CA<5>")
	)
	(segment
		(start 442.941964 -249.442986)
		(end 442.608208 -249.776742)
		(width 0.18288)
		(layer "In11.Cu")
		(net "M_H_CPU0_SB_CA<5>")
	)
	(segment
		(start 418.706554 -249.058684)
		(end 418.513514 -249.251724)
		(width 0.18288)
		(layer "In11.Cu")
		(net "M_H_CPU0_SB_CA<5>")
	)
	(segment
		(start 376.779536 -246.688864)
		(end 376.770646 -246.683784)
		(width 0.088646)
		(layer "In11.Cu")
		(net "M_H_CPU0_SB_CA<5>")
	)
	(segment
		(start 405.385524 -248.754138)
		(end 404.997158 -249.142504)
		(width 0.18288)
		(layer "In11.Cu")
		(net "M_H_CPU0_SB_CA<5>")
	)
	(segment
		(start 433.19319 -248.724166)
		(end 431.406554 -248.724166)
		(width 0.18288)
		(layer "In11.Cu")
		(net "M_H_CPU0_SB_CA<5>")
	)
	(segment
		(start 426.536612 -248.741184)
		(end 426.343572 -248.548144)
		(width 0.18288)
		(layer "In11.Cu")
		(net "M_H_CPU0_SB_CA<5>")
	)
	(segment
		(start 416.449002 -248.579386)
		(end 416.047682 -248.980706)
		(width 0.18288)
		(layer "In11.Cu")
		(net "M_H_CPU0_SB_CA<5>")
	)
	(segment
		(start 402.422614 -249.142504)
		(end 401.714462 -248.434352)
		(width 0.18288)
		(layer "In11.Cu")
		(net "M_H_CPU0_SB_CA<5>")
	)
	(segment
		(start 427.869858 -247.832626)
		(end 426.9613 -248.741184)
		(width 0.18288)
		(layer "In11.Cu")
		(net "M_H_CPU0_SB_CA<5>")
	)
	(segment
		(start 391.38352 -247.244616)
		(end 389.370824 -248.078244)
		(width 0.18288)
		(layer "In11.Cu")
		(net "M_H_CPU0_SB_CA<5>")
	)
	(segment
		(start 453.860662 -248.90984)
		(end 451.519036 -248.90984)
		(width 0.18288)
		(layer "In11.Cu")
		(net "M_H_CPU0_SB_CA<5>")
	)
	(segment
		(start 414.146238 -248.101612)
		(end 413.953198 -248.294652)
		(width 0.18288)
		(layer "In11.Cu")
		(net "M_H_CPU0_SB_CA<5>")
	)
	(segment
		(start 377.719082 -246.688864)
		(end 377.708668 -246.682768)
		(width 0.088646)
		(layer "In11.Cu")
		(net "M_H_CPU0_SB_CA<5>")
	)
	(segment
		(start 430.095152 -248.876312)
		(end 429.051466 -247.832626)
		(width 0.18288)
		(layer "In11.Cu")
		(net "M_H_CPU0_SB_CA<5>")
	)
	(segment
		(start 437.04129 -249.591068)
		(end 434.908452 -249.591068)
		(width 0.18288)
		(layer "In11.Cu")
		(net "M_H_CPU0_SB_CA<5>")
	)
	(segment
		(start 413.953198 -248.294652)
		(end 413.953198 -248.787666)
		(width 0.18288)
		(layer "In11.Cu")
		(net "M_H_CPU0_SB_CA<5>")
	)
	(segment
		(start 419.816788 -248.579386)
		(end 418.899594 -248.579386)
		(width 0.18288)
		(layer "In11.Cu")
		(net "M_H_CPU0_SB_CA<5>")
	)
	(segment
		(start 418.706554 -248.772426)
		(end 418.706554 -249.058684)
		(width 0.18288)
		(layer "In11.Cu")
		(net "M_H_CPU0_SB_CA<5>")
	)
	(segment
		(start 450.082666 -248.595896)
		(end 448.938396 -248.595896)
		(width 0.18288)
		(layer "In11.Cu")
		(net "M_H_CPU0_SB_CA<5>")
	)
	(segment
		(start 409.372308 -248.754138)
		(end 405.385524 -248.754138)
		(width 0.18288)
		(layer "In11.Cu")
		(net "M_H_CPU0_SB_CA<5>")
	)
	(segment
		(start 438.839102 -249.591068)
		(end 438.664604 -249.41657)
		(width 0.18288)
		(layer "In11.Cu")
		(net "M_H_CPU0_SB_CA<5>")
	)
	(segment
		(start 434.2765 -249.807476)
		(end 433.19319 -248.724166)
		(width 0.18288)
		(layer "In11.Cu")
		(net "M_H_CPU0_SB_CA<5>")
	)
	(segment
		(start 418.002974 -249.058684)
		(end 418.002974 -248.772426)
		(width 0.18288)
		(layer "In11.Cu")
		(net "M_H_CPU0_SB_CA<5>")
	)
	(segment
		(start 422.058338 -248.911872)
		(end 421.88765 -248.741184)
		(width 0.18288)
		(layer "In11.Cu")
		(net "M_H_CPU0_SB_CA<5>")
	)
	(segment
		(start 425.446952 -248.741184)
		(end 423.9514 -248.741184)
		(width 0.18288)
		(layer "In11.Cu")
		(net "M_H_CPU0_SB_CA<5>")
	)
	(segment
		(start 426.343572 -247.893332)
		(end 426.150532 -247.700292)
		(width 0.18288)
		(layer "In11.Cu")
		(net "M_H_CPU0_SB_CA<5>")
	)
	(segment
		(start 414.656778 -248.294652)
		(end 414.463738 -248.101612)
		(width 0.18288)
		(layer "In11.Cu")
		(net "M_H_CPU0_SB_CA<5>")
	)
	(segment
		(start 412.737046 -248.980706)
		(end 412.33979 -248.58345)
		(width 0.18288)
		(layer "In11.Cu")
		(net "M_H_CPU0_SB_CA<5>")
	)
	(segment
		(start 386.798566 -247.58269)
		(end 386.052568 -247.58269)
		(width 0.18288)
		(layer "In11.Cu")
		(net "M_H_CPU0_SB_CA<5>")
	)
	(segment
		(start 446.608454 -249.442986)
		(end 442.941964 -249.442986)
		(width 0.18288)
		(layer "In11.Cu")
		(net "M_H_CPU0_SB_CA<5>")
	)
	(segment
		(start 376.496834 -245.961154)
		(end 376.496834 -245.55069)
		(width 0.088646)
		(layer "In11.Cu")
		(net "M_H_CPU0_SB_CA<5>")
	)
	(segment
		(start 419.978586 -248.741184)
		(end 419.816788 -248.579386)
		(width 0.18288)
		(layer "In11.Cu")
		(net "M_H_CPU0_SB_CA<5>")
	)
	(segment
		(start 438.664604 -249.41657)
		(end 437.215788 -249.41657)
		(width 0.18288)
		(layer "In11.Cu")
		(net "M_H_CPU0_SB_CA<5>")
	)
	(arc
		(start 383.358136 -246.688864)
		(mid 383.075434 -246.613088)
		(end 382.792732 -246.688864)
		(width 0.088646)
		(layer "In11.Cu")
		(net "M_H_CPU0_SB_CA<5>")
	)
	(arc
		(start 381.478536 -246.688864)
		(mid 381.201723 -246.612994)
		(end 380.923292 -246.682768)
		(width 0.088646)
		(layer "In11.Cu")
		(net "M_H_CPU0_SB_CA<5>")
	)
	(arc
		(start 383.640584 -247.168416)
		(mid 383.562473 -246.891467)
		(end 383.358136 -246.688864)
		(width 0.088646)
		(layer "In11.Cu")
		(net "M_H_CPU0_SB_CA<5>")
	)
	(arc
		(start 381.852932 -246.688864)
		(mid 381.665734 -246.739007)
		(end 381.478536 -246.688864)
		(width 0.088646)
		(layer "In11.Cu")
		(net "M_H_CPU0_SB_CA<5>")
	)
	(arc
		(start 379.973078 -246.688864)
		(mid 379.78588 -246.739007)
		(end 379.598682 -246.688864)
		(width 0.088646)
		(layer "In11.Cu")
		(net "M_H_CPU0_SB_CA<5>")
	)
	(arc
		(start 382.792732 -246.688864)
		(mid 382.605534 -246.739007)
		(end 382.418336 -246.688864)
		(width 0.088646)
		(layer "In11.Cu")
		(net "M_H_CPU0_SB_CA<5>")
	)
	(arc
		(start 376.592084 -246.364506)
		(mid 376.576972 -246.234658)
		(end 376.532394 -246.111776)
		(width 0.088646)
		(layer "In11.Cu")
		(net "M_H_CPU0_SB_CA<5>")
	)
	(arc
		(start 383.819146 -247.4976)
		(mid 383.688232 -247.36124)
		(end 383.640584 -247.178322)
		(width 0.088646)
		(layer "In11.Cu")
		(net "M_H_CPU0_SB_CA<5>")
	)
	(arc
		(start 385.142232 -247.50268)
		(mid 384.955034 -247.552823)
		(end 384.767836 -247.50268)
		(width 0.088646)
		(layer "In11.Cu")
		(net "M_H_CPU0_SB_CA<5>")
	)
	(arc
		(start 384.202432 -247.50268)
		(mid 384.015234 -247.552823)
		(end 383.828036 -247.50268)
		(width 0.088646)
		(layer "In11.Cu")
		(net "M_H_CPU0_SB_CA<5>")
	)
	(arc
		(start 377.153932 -246.688864)
		(mid 376.966734 -246.739007)
		(end 376.779536 -246.688864)
		(width 0.088646)
		(layer "In11.Cu")
		(net "M_H_CPU0_SB_CA<5>")
	)
	(arc
		(start 376.770646 -246.683784)
		(mid 376.639732 -246.547424)
		(end 376.592084 -246.364506)
		(width 0.088646)
		(layer "In11.Cu")
		(net "M_H_CPU0_SB_CA<5>")
	)
	(arc
		(start 379.598682 -246.688864)
		(mid 379.31598 -246.613088)
		(end 379.033278 -246.688864)
		(width 0.088646)
		(layer "In11.Cu")
		(net "M_H_CPU0_SB_CA<5>")
	)
	(arc
		(start 379.033278 -246.688864)
		(mid 378.84608 -246.739007)
		(end 378.658882 -246.688864)
		(width 0.088646)
		(layer "In11.Cu")
		(net "M_H_CPU0_SB_CA<5>")
	)
	(arc
		(start 378.64415 -246.680228)
		(mid 378.367675 -246.612908)
		(end 378.093478 -246.688864)
		(width 0.088646)
		(layer "In11.Cu")
		(net "M_H_CPU0_SB_CA<5>")
	)
	(arc
		(start 380.52375 -246.680228)
		(mid 380.247275 -246.612908)
		(end 379.973078 -246.688864)
		(width 0.088646)
		(layer "In11.Cu")
		(net "M_H_CPU0_SB_CA<5>")
	)
	(arc
		(start 385.801108 -247.545352)
		(mid 385.478131 -247.424141)
		(end 385.142232 -247.50268)
		(width 0.088646)
		(layer "In11.Cu")
		(net "M_H_CPU0_SB_CA<5>")
	)
	(arc
		(start 378.093478 -246.688864)
		(mid 377.90628 -246.739007)
		(end 377.719082 -246.688864)
		(width 0.088646)
		(layer "In11.Cu")
		(net "M_H_CPU0_SB_CA<5>")
	)
	(arc
		(start 384.767836 -247.50268)
		(mid 384.485134 -247.426904)
		(end 384.202432 -247.50268)
		(width 0.088646)
		(layer "In11.Cu")
		(net "M_H_CPU0_SB_CA<5>")
	)
	(arc
		(start 382.418336 -246.688864)
		(mid 382.135634 -246.613088)
		(end 381.852932 -246.688864)
		(width 0.088646)
		(layer "In11.Cu")
		(net "M_H_CPU0_SB_CA<5>")
	)
	(arc
		(start 380.912878 -246.688864)
		(mid 380.72568 -246.739007)
		(end 380.538482 -246.688864)
		(width 0.088646)
		(layer "In11.Cu")
		(net "M_H_CPU0_SB_CA<5>")
	)
	(arc
		(start 376.532394 -246.111776)
		(mid 376.505867 -246.038532)
		(end 376.496834 -245.961154)
		(width 0.088646)
		(layer "In11.Cu")
		(net "M_H_CPU0_SB_CA<5>")
	)
	(arc
		(start 377.708668 -246.682768)
		(mid 377.43049 -246.613045)
		(end 377.153932 -246.688864)
		(width 0.088646)
		(layer "In11.Cu")
		(net "M_H_CPU0_SB_CA<5>")
	)
	(segment
		(start 374.61698 -246.08663)
		(end 374.617234 -246.086376)
		(width 0.20066)
		(layer "F.Cu")
		(net "M_H_CPU0_SB_CA<4>")
	)
	(segment
		(start 452.016114 -249.166634)
		(end 453.081644 -249.166634)
		(width 0.20066)
		(layer "F.Cu")
		(net "M_H_CPU0_SB_CA<4>")
	)
	(segment
		(start 450.911214 -249.166634)
		(end 452.016114 -249.166634)
		(width 0.20066)
		(layer "F.Cu")
		(net "M_H_CPU0_SB_CA<4>")
	)
	(segment
		(start 454.92797 -249.591576)
		(end 454.941686 -249.591576)
		(width 0.101854)
		(layer "F.Cu")
		(net "M_H_CPU0_SB_CA<4>")
	)
	(segment
		(start 459.55966 -249.16638)
		(end 459.559914 -249.166634)
		(width 0.20066)
		(layer "F.Cu")
		(net "M_H_CPU0_SB_CA<4>")
	)
	(segment
		(start 453.081644 -249.166634)
		(end 453.575928 -248.67235)
		(width 0.20066)
		(layer "F.Cu")
		(net "M_H_CPU0_SB_CA<4>")
	)
	(segment
		(start 374.617234 -246.086376)
		(end 374.617234 -245.55069)
		(width 0.20066)
		(layer "F.Cu")
		(net "M_H_CPU0_SB_CA<4>")
	)
	(segment
		(start 454.941686 -249.591576)
		(end 457.114148 -249.591576)
		(width 0.1016)
		(layer "F.Cu")
		(net "M_H_CPU0_SB_CA<4>")
	)
	(segment
		(start 457.980288 -249.16638)
		(end 459.55966 -249.16638)
		(width 0.20066)
		(layer "F.Cu")
		(net "M_H_CPU0_SB_CA<4>")
	)
	(segment
		(start 453.575928 -248.67235)
		(end 453.901302 -248.67235)
		(width 0.20066)
		(layer "F.Cu")
		(net "M_H_CPU0_SB_CA<4>")
	)
	(segment
		(start 457.126594 -249.604022)
		(end 457.542646 -249.604022)
		(width 0.20066)
		(layer "F.Cu")
		(net "M_H_CPU0_SB_CA<4>")
	)
	(segment
		(start 457.542646 -249.604022)
		(end 457.980288 -249.16638)
		(width 0.20066)
		(layer "F.Cu")
		(net "M_H_CPU0_SB_CA<4>")
	)
	(segment
		(start 453.901302 -248.67235)
		(end 454.820528 -249.591576)
		(width 0.20066)
		(layer "F.Cu")
		(net "M_H_CPU0_SB_CA<4>")
	)
	(segment
		(start 454.820528 -249.591576)
		(end 454.92797 -249.591576)
		(width 0.20066)
		(layer "F.Cu")
		(net "M_H_CPU0_SB_CA<4>")
	)
	(segment
		(start 457.114148 -249.591576)
		(end 457.126594 -249.604022)
		(width 0.1016)
		(layer "F.Cu")
		(net "M_H_CPU0_SB_CA<4>")
	)
	(segment
		(start 419.858698 -249.770646)
		(end 416.921696 -249.770646)
		(width 0.18288)
		(layer "In11.Cu")
		(net "M_H_CPU0_SB_CA<4>")
	)
	(segment
		(start 416.70478 -249.55373)
		(end 414.07715 -249.55373)
		(width 0.18288)
		(layer "In11.Cu")
		(net "M_H_CPU0_SB_CA<4>")
	)
	(segment
		(start 437.02986 -250.607068)
		(end 436.863998 -250.441206)
		(width 0.18288)
		(layer "In11.Cu")
		(net "M_H_CPU0_SB_CA<4>")
	)
	(segment
		(start 423.639742 -249.42038)
		(end 422.2369 -249.42038)
		(width 0.18288)
		(layer "In11.Cu")
		(net "M_H_CPU0_SB_CA<4>")
	)
	(segment
		(start 406.59812 -250.031758)
		(end 406.40508 -249.838718)
		(width 0.18288)
		(layer "In11.Cu")
		(net "M_H_CPU0_SB_CA<4>")
	)
	(segment
		(start 385.80822 -248.22023)
		(end 385.807966 -248.22023)
		(width 0.088646)
		(layer "In11.Cu")
		(net "M_H_CPU0_SB_CA<4>")
	)
	(segment
		(start 428.842424 -248.942352)
		(end 428.649384 -248.749312)
		(width 0.18288)
		(layer "In11.Cu")
		(net "M_H_CPU0_SB_CA<4>")
	)
	(segment
		(start 442.99759 -250.601734)
		(end 442.684408 -250.288552)
		(width 0.18288)
		(layer "In11.Cu")
		(net "M_H_CPU0_SB_CA<4>")
	)
	(segment
		(start 387.707124 -249.146822)
		(end 386.799328 -248.239026)
		(width 0.18288)
		(layer "In11.Cu")
		(net "M_H_CPU0_SB_CA<4>")
	)
	(segment
		(start 428.138844 -248.942352)
		(end 428.138844 -249.396504)
		(width 0.18288)
		(layer "In11.Cu")
		(net "M_H_CPU0_SB_CA<4>")
	)
	(segment
		(start 446.312798 -250.601734)
		(end 442.99759 -250.601734)
		(width 0.18288)
		(layer "In11.Cu")
		(net "M_H_CPU0_SB_CA<4>")
	)
	(segment
		(start 399.142966 -249.440954)
		(end 396.944342 -247.24233)
		(width 0.18288)
		(layer "In11.Cu")
		(net "M_H_CPU0_SB_CA<4>")
	)
	(segment
		(start 439.273696 -250.607068)
		(end 437.02986 -250.607068)
		(width 0.18288)
		(layer "In11.Cu")
		(net "M_H_CPU0_SB_CA<4>")
	)
	(segment
		(start 406.21204 -249.278394)
		(end 405.7523 -249.278394)
		(width 0.18288)
		(layer "In11.Cu")
		(net "M_H_CPU0_SB_CA<4>")
	)
	(segment
		(start 433.761388 -251.464826)
		(end 433.568348 -251.271786)
		(width 0.18288)
		(layer "In11.Cu")
		(net "M_H_CPU0_SB_CA<4>")
	)
	(segment
		(start 427.945804 -249.589544)
		(end 427.216316 -249.589544)
		(width 0.18288)
		(layer "In11.Cu")
		(net "M_H_CPU0_SB_CA<4>")
	)
	(segment
		(start 413.879792 -250.365006)
		(end 413.719772 -250.525026)
		(width 0.18288)
		(layer "In11.Cu")
		(net "M_H_CPU0_SB_CA<4>")
	)
	(segment
		(start 407.3017 -249.278394)
		(end 407.10866 -249.471434)
		(width 0.18288)
		(layer "In11.Cu")
		(net "M_H_CPU0_SB_CA<4>")
	)
	(segment
		(start 428.842424 -249.396504)
		(end 428.842424 -248.942352)
		(width 0.18288)
		(layer "In11.Cu")
		(net "M_H_CPU0_SB_CA<4>")
	)
	(segment
		(start 411.396434 -250.25604)
		(end 410.819854 -249.67946)
		(width 0.18288)
		(layer "In11.Cu")
		(net "M_H_CPU0_SB_CA<4>")
	)
	(segment
		(start 385.807966 -248.22023)
		(end 385.71932 -248.131584)
		(width 0.088646)
		(layer "In11.Cu")
		(net "M_H_CPU0_SB_CA<4>")
	)
	(segment
		(start 436.863998 -250.441206)
		(end 435.239414 -250.441206)
		(width 0.18288)
		(layer "In11.Cu")
		(net "M_H_CPU0_SB_CA<4>")
	)
	(segment
		(start 377.638564 -246.8626)
		(end 377.623832 -246.853964)
		(width 0.088646)
		(layer "In11.Cu")
		(net "M_H_CPU0_SB_CA<4>")
	)
	(segment
		(start 406.40508 -249.471434)
		(end 406.21204 -249.278394)
		(width 0.18288)
		(layer "In11.Cu")
		(net "M_H_CPU0_SB_CA<4>")
	)
	(segment
		(start 442.684408 -250.288552)
		(end 441.04306 -250.288552)
		(width 0.18288)
		(layer "In11.Cu")
		(net "M_H_CPU0_SB_CA<4>")
	)
	(segment
		(start 428.331884 -248.749312)
		(end 428.138844 -248.942352)
		(width 0.18288)
		(layer "In11.Cu")
		(net "M_H_CPU0_SB_CA<4>")
	)
	(segment
		(start 380.453646 -246.86006)
		(end 380.443232 -246.853964)
		(width 0.088646)
		(layer "In11.Cu")
		(net "M_H_CPU0_SB_CA<4>")
	)
	(segment
		(start 408.931618 -249.278394)
		(end 407.3017 -249.278394)
		(width 0.18288)
		(layer "In11.Cu")
		(net "M_H_CPU0_SB_CA<4>")
	)
	(segment
		(start 412.511494 -250.525026)
		(end 412.242508 -250.25604)
		(width 0.18288)
		(layer "In11.Cu")
		(net "M_H_CPU0_SB_CA<4>")
	)
	(segment
		(start 376.684032 -246.853964)
		(end 376.67184 -246.846852)
		(width 0.088646)
		(layer "In11.Cu")
		(net "M_H_CPU0_SB_CA<4>")
	)
	(segment
		(start 427.052994 -249.752866)
		(end 426.28693 -249.752866)
		(width 0.18288)
		(layer "In11.Cu")
		(net "M_H_CPU0_SB_CA<4>")
	)
	(segment
		(start 374.929908 -245.55069)
		(end 374.617234 -245.55069)
		(width 0.088646)
		(layer "In11.Cu")
		(net "M_H_CPU0_SB_CA<4>")
	)
	(segment
		(start 392.100816 -247.48363)
		(end 388.08533 -249.146822)
		(width 0.18288)
		(layer "In11.Cu")
		(net "M_H_CPU0_SB_CA<4>")
	)
	(segment
		(start 431.423572 -249.589544)
		(end 429.035464 -249.589544)
		(width 0.18288)
		(layer "In11.Cu")
		(net "M_H_CPU0_SB_CA<4>")
	)
	(segment
		(start 405.7523 -249.278394)
		(end 405.177244 -249.85345)
		(width 0.18288)
		(layer "In11.Cu")
		(net "M_H_CPU0_SB_CA<4>")
	)
	(segment
		(start 385.827016 -248.239026)
		(end 385.80822 -248.22023)
		(width 0.088646)
		(layer "In11.Cu")
		(net "M_H_CPU0_SB_CA<4>")
	)
	(segment
		(start 413.879792 -249.751088)
		(end 413.879792 -250.365006)
		(width 0.18288)
		(layer "In11.Cu")
		(net "M_H_CPU0_SB_CA<4>")
	)
	(segment
		(start 433.568348 -251.271786)
		(end 433.568348 -250.158504)
		(width 0.18288)
		(layer "In11.Cu")
		(net "M_H_CPU0_SB_CA<4>")
	)
	(segment
		(start 448.493642 -249.761502)
		(end 447.93789 -250.317254)
		(width 0.18288)
		(layer "In11.Cu")
		(net "M_H_CPU0_SB_CA<4>")
	)
	(segment
		(start 431.799492 -249.965464)
		(end 431.423572 -249.589544)
		(width 0.18288)
		(layer "In11.Cu")
		(net "M_H_CPU0_SB_CA<4>")
	)
	(segment
		(start 433.375308 -249.965464)
		(end 431.799492 -249.965464)
		(width 0.18288)
		(layer "In11.Cu")
		(net "M_H_CPU0_SB_CA<4>")
	)
	(segment
		(start 405.177244 -249.85345)
		(end 402.809964 -249.85345)
		(width 0.18288)
		(layer "In11.Cu")
		(net "M_H_CPU0_SB_CA<4>")
	)
	(segment
		(start 407.10866 -249.471434)
		(end 407.10866 -249.838718)
		(width 0.18288)
		(layer "In11.Cu")
		(net "M_H_CPU0_SB_CA<4>")
	)
	(segment
		(start 414.07715 -249.55373)
		(end 413.879792 -249.751088)
		(width 0.18288)
		(layer "In11.Cu")
		(net "M_H_CPU0_SB_CA<4>")
	)
	(segment
		(start 447.93789 -250.317254)
		(end 446.597278 -250.317254)
		(width 0.18288)
		(layer "In11.Cu")
		(net "M_H_CPU0_SB_CA<4>")
	)
	(segment
		(start 435.239414 -250.441206)
		(end 435.079394 -250.601226)
		(width 0.18288)
		(layer "In11.Cu")
		(net "M_H_CPU0_SB_CA<4>")
	)
	(segment
		(start 422.2369 -249.42038)
		(end 422.066212 -249.591068)
		(width 0.18288)
		(layer "In11.Cu")
		(net "M_H_CPU0_SB_CA<4>")
	)
	(segment
		(start 413.719772 -250.525026)
		(end 412.511494 -250.525026)
		(width 0.18288)
		(layer "In11.Cu")
		(net "M_H_CPU0_SB_CA<4>")
	)
	(segment
		(start 388.08533 -249.146822)
		(end 387.707124 -249.146822)
		(width 0.18288)
		(layer "In11.Cu")
		(net "M_H_CPU0_SB_CA<4>")
	)
	(segment
		(start 433.568348 -250.158504)
		(end 433.375308 -249.965464)
		(width 0.18288)
		(layer "In11.Cu")
		(net "M_H_CPU0_SB_CA<4>")
	)
	(segment
		(start 378.574046 -246.86006)
		(end 378.563632 -246.853964)
		(width 0.088646)
		(layer "In11.Cu")
		(net "M_H_CPU0_SB_CA<4>")
	)
	(segment
		(start 435.079394 -251.254006)
		(end 434.868574 -251.464826)
		(width 0.18288)
		(layer "In11.Cu")
		(net "M_H_CPU0_SB_CA<4>")
	)
	(segment
		(start 385.71932 -247.774968)
		(end 385.612132 -247.66778)
		(width 0.088646)
		(layer "In11.Cu")
		(net "M_H_CPU0_SB_CA<4>")
	)
	(segment
		(start 422.066212 -249.591068)
		(end 420.038276 -249.591068)
		(width 0.18288)
		(layer "In11.Cu")
		(net "M_H_CPU0_SB_CA<4>")
	)
	(segment
		(start 440.890406 -250.441206)
		(end 439.439558 -250.441206)
		(width 0.18288)
		(layer "In11.Cu")
		(net "M_H_CPU0_SB_CA<4>")
	)
	(segment
		(start 439.439558 -250.441206)
		(end 439.273696 -250.607068)
		(width 0.18288)
		(layer "In11.Cu")
		(net "M_H_CPU0_SB_CA<4>")
	)
	(segment
		(start 434.868574 -251.464826)
		(end 433.761388 -251.464826)
		(width 0.18288)
		(layer "In11.Cu")
		(net "M_H_CPU0_SB_CA<4>")
	)
	(segment
		(start 386.052568 -248.239026)
		(end 385.827016 -248.239026)
		(width 0.088646)
		(layer "In11.Cu")
		(net "M_H_CPU0_SB_CA<4>")
	)
	(segment
		(start 429.035464 -249.589544)
		(end 428.842424 -249.396504)
		(width 0.18288)
		(layer "In11.Cu")
		(net "M_H_CPU0_SB_CA<4>")
	)
	(segment
		(start 393.313666 -247.24233)
		(end 392.100816 -247.48363)
		(width 0.18288)
		(layer "In11.Cu")
		(net "M_H_CPU0_SB_CA<4>")
	)
	(segment
		(start 406.40508 -249.838718)
		(end 406.40508 -249.471434)
		(width 0.18288)
		(layer "In11.Cu")
		(net "M_H_CPU0_SB_CA<4>")
	)
	(segment
		(start 416.921696 -249.770646)
		(end 416.70478 -249.55373)
		(width 0.18288)
		(layer "In11.Cu")
		(net "M_H_CPU0_SB_CA<4>")
	)
	(segment
		(start 409.332684 -249.67946)
		(end 408.931618 -249.278394)
		(width 0.18288)
		(layer "In11.Cu")
		(net "M_H_CPU0_SB_CA<4>")
	)
	(segment
		(start 412.242508 -250.25604)
		(end 411.396434 -250.25604)
		(width 0.18288)
		(layer "In11.Cu")
		(net "M_H_CPU0_SB_CA<4>")
	)
	(segment
		(start 402.809964 -249.85345)
		(end 401.81403 -249.440954)
		(width 0.18288)
		(layer "In11.Cu")
		(net "M_H_CPU0_SB_CA<4>")
	)
	(segment
		(start 446.597278 -250.317254)
		(end 446.312798 -250.601734)
		(width 0.18288)
		(layer "In11.Cu")
		(net "M_H_CPU0_SB_CA<4>")
	)
	(segment
		(start 450.911214 -249.440954)
		(end 450.779134 -249.573034)
		(width 0.18288)
		(layer "In11.Cu")
		(net "M_H_CPU0_SB_CA<4>")
	)
	(segment
		(start 435.079394 -250.601226)
		(end 435.079394 -251.254006)
		(width 0.18288)
		(layer "In11.Cu")
		(net "M_H_CPU0_SB_CA<4>")
	)
	(segment
		(start 383.271522 -246.859044)
		(end 383.262632 -246.853964)
		(width 0.088646)
		(layer "In11.Cu")
		(net "M_H_CPU0_SB_CA<4>")
	)
	(segment
		(start 410.819854 -249.67946)
		(end 409.332684 -249.67946)
		(width 0.18288)
		(layer "In11.Cu")
		(net "M_H_CPU0_SB_CA<4>")
	)
	(segment
		(start 423.81043 -249.591068)
		(end 423.639742 -249.42038)
		(width 0.18288)
		(layer "In11.Cu")
		(net "M_H_CPU0_SB_CA<4>")
	)
	(segment
		(start 376.222768 -246.045228)
		(end 376.213878 -246.040148)
		(width 0.088646)
		(layer "In11.Cu")
		(net "M_H_CPU0_SB_CA<4>")
	)
	(segment
		(start 428.138844 -249.396504)
		(end 427.945804 -249.589544)
		(width 0.18288)
		(layer "In11.Cu")
		(net "M_H_CPU0_SB_CA<4>")
	)
	(segment
		(start 379.513592 -246.86006)
		(end 379.503178 -246.853964)
		(width 0.088646)
		(layer "In11.Cu")
		(net "M_H_CPU0_SB_CA<4>")
	)
	(segment
		(start 428.649384 -248.749312)
		(end 428.331884 -248.749312)
		(width 0.18288)
		(layer "In11.Cu")
		(net "M_H_CPU0_SB_CA<4>")
	)
	(segment
		(start 427.216316 -249.589544)
		(end 427.052994 -249.752866)
		(width 0.18288)
		(layer "In11.Cu")
		(net "M_H_CPU0_SB_CA<4>")
	)
	(segment
		(start 386.799328 -248.239026)
		(end 386.052568 -248.239026)
		(width 0.18288)
		(layer "In11.Cu")
		(net "M_H_CPU0_SB_CA<4>")
	)
	(segment
		(start 407.10866 -249.838718)
		(end 406.91562 -250.031758)
		(width 0.18288)
		(layer "In11.Cu")
		(net "M_H_CPU0_SB_CA<4>")
	)
	(segment
		(start 426.28693 -249.752866)
		(end 426.125132 -249.591068)
		(width 0.18288)
		(layer "In11.Cu")
		(net "M_H_CPU0_SB_CA<4>")
	)
	(segment
		(start 450.779134 -249.573034)
		(end 450.323966 -249.761502)
		(width 0.18288)
		(layer "In11.Cu")
		(net "M_H_CPU0_SB_CA<4>")
	)
	(segment
		(start 441.04306 -250.288552)
		(end 440.890406 -250.441206)
		(width 0.18288)
		(layer "In11.Cu")
		(net "M_H_CPU0_SB_CA<4>")
	)
	(segment
		(start 381.948436 -246.853964)
		(end 381.938022 -246.86006)
		(width 0.088646)
		(layer "In11.Cu")
		(net "M_H_CPU0_SB_CA<4>")
	)
	(segment
		(start 420.038276 -249.591068)
		(end 419.858698 -249.770646)
		(width 0.18288)
		(layer "In11.Cu")
		(net "M_H_CPU0_SB_CA<4>")
	)
	(segment
		(start 383.450084 -247.188228)
		(end 383.450084 -247.178322)
		(width 0.088646)
		(layer "In11.Cu")
		(net "M_H_CPU0_SB_CA<4>")
	)
	(segment
		(start 406.91562 -250.031758)
		(end 406.59812 -250.031758)
		(width 0.18288)
		(layer "In11.Cu")
		(net "M_H_CPU0_SB_CA<4>")
	)
	(segment
		(start 450.323966 -249.761502)
		(end 448.493642 -249.761502)
		(width 0.18288)
		(layer "In11.Cu")
		(net "M_H_CPU0_SB_CA<4>")
	)
	(segment
		(start 374.995186 -245.615968)
		(end 374.929908 -245.55069)
		(width 0.088646)
		(layer "In11.Cu")
		(net "M_H_CPU0_SB_CA<4>")
	)
	(segment
		(start 450.911214 -249.166634)
		(end 450.911214 -249.440954)
		(width 0.18288)
		(layer "In11.Cu")
		(net "M_H_CPU0_SB_CA<4>")
	)
	(segment
		(start 385.71932 -248.131584)
		(end 385.71932 -247.774968)
		(width 0.088646)
		(layer "In11.Cu")
		(net "M_H_CPU0_SB_CA<4>")
	)
	(segment
		(start 401.81403 -249.440954)
		(end 399.142966 -249.440954)
		(width 0.18288)
		(layer "In11.Cu")
		(net "M_H_CPU0_SB_CA<4>")
	)
	(segment
		(start 396.944342 -247.24233)
		(end 393.313666 -247.24233)
		(width 0.18288)
		(layer "In11.Cu")
		(net "M_H_CPU0_SB_CA<4>")
	)
	(segment
		(start 426.125132 -249.591068)
		(end 423.81043 -249.591068)
		(width 0.18288)
		(layer "In11.Cu")
		(net "M_H_CPU0_SB_CA<4>")
	)
	(arc
		(start 379.503178 -246.853964)
		(mid 379.31598 -246.803821)
		(end 379.128782 -246.853964)
		(width 0.088646)
		(layer "In11.Cu")
		(net "M_H_CPU0_SB_CA<4>")
	)
	(arc
		(start 383.732532 -247.66778)
		(mid 383.528197 -247.465175)
		(end 383.450084 -247.188228)
		(width 0.088646)
		(layer "In11.Cu")
		(net "M_H_CPU0_SB_CA<4>")
	)
	(arc
		(start 379.128782 -246.853964)
		(mid 378.852223 -246.929707)
		(end 378.574046 -246.86006)
		(width 0.088646)
		(layer "In11.Cu")
		(net "M_H_CPU0_SB_CA<4>")
	)
	(arc
		(start 381.382778 -246.853964)
		(mid 381.19558 -246.803821)
		(end 381.008382 -246.853964)
		(width 0.088646)
		(layer "In11.Cu")
		(net "M_H_CPU0_SB_CA<4>")
	)
	(arc
		(start 382.888236 -246.853964)
		(mid 382.605534 -246.92974)
		(end 382.322832 -246.853964)
		(width 0.088646)
		(layer "In11.Cu")
		(net "M_H_CPU0_SB_CA<4>")
	)
	(arc
		(start 377.249436 -246.853964)
		(mid 376.966734 -246.92974)
		(end 376.684032 -246.853964)
		(width 0.088646)
		(layer "In11.Cu")
		(net "M_H_CPU0_SB_CA<4>")
	)
	(arc
		(start 378.563632 -246.853964)
		(mid 378.376434 -246.803821)
		(end 378.189236 -246.853964)
		(width 0.088646)
		(layer "In11.Cu")
		(net "M_H_CPU0_SB_CA<4>")
	)
	(arc
		(start 376.67184 -246.846852)
		(mid 376.473612 -246.641004)
		(end 376.40133 -246.364506)
		(width 0.088646)
		(layer "In11.Cu")
		(net "M_H_CPU0_SB_CA<4>")
	)
	(arc
		(start 385.612132 -247.66778)
		(mid 385.424934 -247.617637)
		(end 385.237736 -247.66778)
		(width 0.088646)
		(layer "In11.Cu")
		(net "M_H_CPU0_SB_CA<4>")
	)
	(arc
		(start 384.297936 -247.66778)
		(mid 384.015234 -247.743556)
		(end 383.732532 -247.66778)
		(width 0.088646)
		(layer "In11.Cu")
		(net "M_H_CPU0_SB_CA<4>")
	)
	(arc
		(start 376.40133 -246.364506)
		(mid 376.353651 -246.181606)
		(end 376.222768 -246.045228)
		(width 0.088646)
		(layer "In11.Cu")
		(net "M_H_CPU0_SB_CA<4>")
	)
	(arc
		(start 377.623832 -246.853964)
		(mid 377.436634 -246.803821)
		(end 377.249436 -246.853964)
		(width 0.088646)
		(layer "In11.Cu")
		(net "M_H_CPU0_SB_CA<4>")
	)
	(arc
		(start 376.213878 -246.040148)
		(mid 376.02668 -245.990005)
		(end 375.839482 -246.040148)
		(width 0.088646)
		(layer "In11.Cu")
		(net "M_H_CPU0_SB_CA<4>")
	)
	(arc
		(start 382.322832 -246.853964)
		(mid 382.135634 -246.803821)
		(end 381.948436 -246.853964)
		(width 0.088646)
		(layer "In11.Cu")
		(net "M_H_CPU0_SB_CA<4>")
	)
	(arc
		(start 380.443232 -246.853964)
		(mid 380.256034 -246.803821)
		(end 380.068836 -246.853964)
		(width 0.088646)
		(layer "In11.Cu")
		(net "M_H_CPU0_SB_CA<4>")
	)
	(arc
		(start 381.008382 -246.853964)
		(mid 380.731823 -246.929707)
		(end 380.453646 -246.86006)
		(width 0.088646)
		(layer "In11.Cu")
		(net "M_H_CPU0_SB_CA<4>")
	)
	(arc
		(start 375.839482 -246.040148)
		(mid 375.55678 -246.115924)
		(end 375.274078 -246.040148)
		(width 0.088646)
		(layer "In11.Cu")
		(net "M_H_CPU0_SB_CA<4>")
	)
	(arc
		(start 384.672332 -247.66778)
		(mid 384.485134 -247.617637)
		(end 384.297936 -247.66778)
		(width 0.088646)
		(layer "In11.Cu")
		(net "M_H_CPU0_SB_CA<4>")
	)
	(arc
		(start 378.189236 -246.853964)
		(mid 377.915037 -246.929799)
		(end 377.638564 -246.8626)
		(width 0.088646)
		(layer "In11.Cu")
		(net "M_H_CPU0_SB_CA<4>")
	)
	(arc
		(start 383.450084 -247.178322)
		(mid 383.402405 -246.995422)
		(end 383.271522 -246.859044)
		(width 0.088646)
		(layer "In11.Cu")
		(net "M_H_CPU0_SB_CA<4>")
	)
	(arc
		(start 383.262632 -246.853964)
		(mid 383.075434 -246.803821)
		(end 382.888236 -246.853964)
		(width 0.088646)
		(layer "In11.Cu")
		(net "M_H_CPU0_SB_CA<4>")
	)
	(arc
		(start 381.938022 -246.86006)
		(mid 381.65959 -246.929906)
		(end 381.382778 -246.853964)
		(width 0.088646)
		(layer "In11.Cu")
		(net "M_H_CPU0_SB_CA<4>")
	)
	(arc
		(start 380.068836 -246.853964)
		(mid 379.792023 -246.929834)
		(end 379.513592 -246.86006)
		(width 0.088646)
		(layer "In11.Cu")
		(net "M_H_CPU0_SB_CA<4>")
	)
	(arc
		(start 385.237736 -247.66778)
		(mid 384.955034 -247.743556)
		(end 384.672332 -247.66778)
		(width 0.088646)
		(layer "In11.Cu")
		(net "M_H_CPU0_SB_CA<4>")
	)
	(arc
		(start 375.274078 -246.040148)
		(mid 375.084328 -245.861134)
		(end 374.995186 -245.615968)
		(width 0.088646)
		(layer "In11.Cu")
		(net "M_H_CPU0_SB_CA<4>")
	)
	(segment
		(start 460.570326 -250.44908)
		(end 460.844392 -250.44908)
		(width 0.20066)
		(layer "F.Cu")
		(net "M_H_CPU0_SB_CA<3>")
	)
	(segment
		(start 376.026934 -246.900446)
		(end 376.02668 -246.900192)
		(width 0.20066)
		(layer "F.Cu")
		(net "M_H_CPU0_SB_CA<3>")
	)
	(segment
		(start 376.02668 -246.900192)
		(end 376.02668 -246.364506)
		(width 0.20066)
		(layer "F.Cu")
		(net "M_H_CPU0_SB_CA<3>")
	)
	(segment
		(start 455.011282 -250.016772)
		(end 456.116182 -250.016772)
		(width 0.20066)
		(layer "F.Cu")
		(net "M_H_CPU0_SB_CA<3>")
	)
	(segment
		(start 456.116182 -250.016772)
		(end 457.751942 -250.016772)
		(width 0.20066)
		(layer "F.Cu")
		(net "M_H_CPU0_SB_CA<3>")
	)
	(segment
		(start 458.187552 -250.452382)
		(end 458.538326 -250.452382)
		(width 0.20066)
		(layer "F.Cu")
		(net "M_H_CPU0_SB_CA<3>")
	)
	(segment
		(start 458.538326 -250.452382)
		(end 458.543152 -250.452382)
		(width 0.101854)
		(layer "F.Cu")
		(net "M_H_CPU0_SB_CA<3>")
	)
	(segment
		(start 462.54543 -250.016772)
		(end 463.659982 -250.016772)
		(width 0.20066)
		(layer "F.Cu")
		(net "M_H_CPU0_SB_CA<3>")
	)
	(segment
		(start 462.112868 -249.58421)
		(end 462.54543 -250.016772)
		(width 0.20066)
		(layer "F.Cu")
		(net "M_H_CPU0_SB_CA<3>")
	)
	(segment
		(start 458.543152 -250.452382)
		(end 458.55382 -250.441714)
		(width 0.1016)
		(layer "F.Cu")
		(net "M_H_CPU0_SB_CA<3>")
	)
	(segment
		(start 460.56296 -250.441714)
		(end 460.570326 -250.44908)
		(width 0.1016)
		(layer "F.Cu")
		(net "M_H_CPU0_SB_CA<3>")
	)
	(segment
		(start 457.751942 -250.016772)
		(end 458.187552 -250.452382)
		(width 0.20066)
		(layer "F.Cu")
		(net "M_H_CPU0_SB_CA<3>")
	)
	(segment
		(start 460.844392 -250.44908)
		(end 461.709262 -249.58421)
		(width 0.20066)
		(layer "F.Cu")
		(net "M_H_CPU0_SB_CA<3>")
	)
	(segment
		(start 461.709262 -249.58421)
		(end 462.112868 -249.58421)
		(width 0.20066)
		(layer "F.Cu")
		(net "M_H_CPU0_SB_CA<3>")
	)
	(segment
		(start 458.55382 -250.441714)
		(end 460.56296 -250.441714)
		(width 0.1016)
		(layer "F.Cu")
		(net "M_H_CPU0_SB_CA<3>")
	)
	(segment
		(start 408.961336 -250.308618)
		(end 408.723592 -250.546362)
		(width 0.18288)
		(layer "In11.Cu")
		(net "M_H_CPU0_SB_CA<3>")
	)
	(segment
		(start 412.359094 -251.210826)
		(end 412.155894 -251.414026)
		(width 0.18288)
		(layer "In11.Cu")
		(net "M_H_CPU0_SB_CA<3>")
	)
	(segment
		(start 437.244998 -251.116846)
		(end 436.220616 -252.141228)
		(width 0.18288)
		(layer "In11.Cu")
		(net "M_H_CPU0_SB_CA<3>")
	)
	(segment
		(start 438.858406 -251.29109)
		(end 438.684162 -251.116846)
		(width 0.18288)
		(layer "In11.Cu")
		(net "M_H_CPU0_SB_CA<3>")
	)
	(segment
		(start 424.430444 -251.291344)
		(end 423.765218 -250.626118)
		(width 0.18288)
		(layer "In11.Cu")
		(net "M_H_CPU0_SB_CA<3>")
	)
	(segment
		(start 392.231372 -247.83542)
		(end 388.003288 -249.58675)
		(width 0.18288)
		(layer "In11.Cu")
		(net "M_H_CPU0_SB_CA<3>")
	)
	(segment
		(start 408.723592 -250.546362)
		(end 405.22779 -250.546362)
		(width 0.18288)
		(layer "In11.Cu")
		(net "M_H_CPU0_SB_CA<3>")
	)
	(segment
		(start 436.220616 -252.141228)
		(end 433.398676 -252.141228)
		(width 0.18288)
		(layer "In11.Cu")
		(net "M_H_CPU0_SB_CA<3>")
	)
	(segment
		(start 431.230024 -251.490226)
		(end 430.455832 -250.716034)
		(width 0.18288)
		(layer "In11.Cu")
		(net "M_H_CPU0_SB_CA<3>")
	)
	(segment
		(start 375.656602 -246.42191)
		(end 375.714006 -246.364506)
		(width 0.088646)
		(layer "In11.Cu")
		(net "M_H_CPU0_SB_CA<3>")
	)
	(segment
		(start 446.385696 -251.247148)
		(end 443.008512 -251.247148)
		(width 0.18288)
		(layer "In11.Cu")
		(net "M_H_CPU0_SB_CA<3>")
	)
	(segment
		(start 386.052568 -248.625868)
		(end 385.574286 -248.625868)
		(width 0.088646)
		(layer "In11.Cu")
		(net "M_H_CPU0_SB_CA<3>")
	)
	(segment
		(start 438.684162 -251.116846)
		(end 437.244998 -251.116846)
		(width 0.18288)
		(layer "In11.Cu")
		(net "M_H_CPU0_SB_CA<3>")
	)
	(segment
		(start 385.574286 -248.625868)
		(end 385.35483 -248.406412)
		(width 0.088646)
		(layer "In11.Cu")
		(net "M_H_CPU0_SB_CA<3>")
	)
	(segment
		(start 412.155894 -251.414026)
		(end 411.626812 -251.414026)
		(width 0.18288)
		(layer "In11.Cu")
		(net "M_H_CPU0_SB_CA<3>")
	)
	(segment
		(start 377.638564 -247.494044)
		(end 377.623832 -247.50268)
		(width 0.088646)
		(layer "In11.Cu")
		(net "M_H_CPU0_SB_CA<3>")
	)
	(segment
		(start 422.111932 -250.441206)
		(end 419.837616 -250.441206)
		(width 0.18288)
		(layer "In11.Cu")
		(net "M_H_CPU0_SB_CA<3>")
	)
	(segment
		(start 411.626812 -251.414026)
		(end 410.521404 -250.308618)
		(width 0.18288)
		(layer "In11.Cu")
		(net "M_H_CPU0_SB_CA<3>")
	)
	(segment
		(start 449.611242 -250.306586)
		(end 448.493388 -251.42444)
		(width 0.18288)
		(layer "In11.Cu")
		(net "M_H_CPU0_SB_CA<3>")
	)
	(segment
		(start 375.714006 -246.364506)
		(end 376.02668 -246.364506)
		(width 0.088646)
		(layer "In11.Cu")
		(net "M_H_CPU0_SB_CA<3>")
	)
	(segment
		(start 410.521404 -250.308618)
		(end 408.961336 -250.308618)
		(width 0.18288)
		(layer "In11.Cu")
		(net "M_H_CPU0_SB_CA<3>")
	)
	(segment
		(start 443.008512 -251.247148)
		(end 442.723524 -251.532136)
		(width 0.18288)
		(layer "In11.Cu")
		(net "M_H_CPU0_SB_CA<3>")
	)
	(segment
		(start 419.690296 -250.293886)
		(end 416.946842 -250.293886)
		(width 0.18288)
		(layer "In11.Cu")
		(net "M_H_CPU0_SB_CA<3>")
	)
	(segment
		(start 425.97324 -250.359926)
		(end 425.769278 -250.563888)
		(width 0.18288)
		(layer "In11.Cu")
		(net "M_H_CPU0_SB_CA<3>")
	)
	(segment
		(start 425.529248 -251.291344)
		(end 424.430444 -251.291344)
		(width 0.18288)
		(layer "In11.Cu")
		(net "M_H_CPU0_SB_CA<3>")
	)
	(segment
		(start 446.562988 -251.42444)
		(end 446.385696 -251.247148)
		(width 0.18288)
		(layer "In11.Cu")
		(net "M_H_CPU0_SB_CA<3>")
	)
	(segment
		(start 381.014478 -247.506236)
		(end 381.008382 -247.50268)
		(width 0.088646)
		(layer "In11.Cu")
		(net "M_H_CPU0_SB_CA<3>")
	)
	(segment
		(start 433.398676 -252.141228)
		(end 432.747674 -251.490226)
		(width 0.18288)
		(layer "In11.Cu")
		(net "M_H_CPU0_SB_CA<3>")
	)
	(segment
		(start 423.765218 -250.626118)
		(end 422.296844 -250.626118)
		(width 0.18288)
		(layer "In11.Cu")
		(net "M_H_CPU0_SB_CA<3>")
	)
	(segment
		(start 381.478536 -248.316496)
		(end 381.469646 -248.311416)
		(width 0.088646)
		(layer "In11.Cu")
		(net "M_H_CPU0_SB_CA<3>")
	)
	(segment
		(start 425.769278 -251.051314)
		(end 425.529248 -251.291344)
		(width 0.18288)
		(layer "In11.Cu")
		(net "M_H_CPU0_SB_CA<3>")
	)
	(segment
		(start 379.513592 -247.496584)
		(end 379.503178 -247.50268)
		(width 0.088646)
		(layer "In11.Cu")
		(net "M_H_CPU0_SB_CA<3>")
	)
	(segment
		(start 396.544038 -247.58777)
		(end 393.476226 -247.58777)
		(width 0.18288)
		(layer "In11.Cu")
		(net "M_H_CPU0_SB_CA<3>")
	)
	(segment
		(start 401.721066 -249.956574)
		(end 398.912842 -249.956574)
		(width 0.18288)
		(layer "In11.Cu")
		(net "M_H_CPU0_SB_CA<3>")
	)
	(segment
		(start 427.762416 -250.716034)
		(end 427.406308 -250.359926)
		(width 0.18288)
		(layer "In11.Cu")
		(net "M_H_CPU0_SB_CA<3>")
	)
	(segment
		(start 442.723524 -251.532136)
		(end 441.134246 -251.532136)
		(width 0.18288)
		(layer "In11.Cu")
		(net "M_H_CPU0_SB_CA<3>")
	)
	(segment
		(start 403.144228 -250.546108)
		(end 401.721066 -249.956574)
		(width 0.18288)
		(layer "In11.Cu")
		(net "M_H_CPU0_SB_CA<3>")
	)
	(segment
		(start 427.406308 -250.359926)
		(end 425.97324 -250.359926)
		(width 0.18288)
		(layer "In11.Cu")
		(net "M_H_CPU0_SB_CA<3>")
	)
	(segment
		(start 455.011282 -250.016772)
		(end 454.52284 -250.016772)
		(width 0.18288)
		(layer "In11.Cu")
		(net "M_H_CPU0_SB_CA<3>")
	)
	(segment
		(start 454.52284 -250.016772)
		(end 453.954896 -250.584716)
		(width 0.18288)
		(layer "In11.Cu")
		(net "M_H_CPU0_SB_CA<3>")
	)
	(segment
		(start 416.946842 -250.293886)
		(end 416.724846 -250.515882)
		(width 0.18288)
		(layer "In11.Cu")
		(net "M_H_CPU0_SB_CA<3>")
	)
	(segment
		(start 453.954896 -250.584716)
		(end 451.86092 -250.584716)
		(width 0.18288)
		(layer "In11.Cu")
		(net "M_H_CPU0_SB_CA<3>")
	)
	(segment
		(start 432.747674 -251.490226)
		(end 431.230024 -251.490226)
		(width 0.18288)
		(layer "In11.Cu")
		(net "M_H_CPU0_SB_CA<3>")
	)
	(segment
		(start 451.86092 -250.584716)
		(end 451.718172 -250.441968)
		(width 0.18288)
		(layer "In11.Cu")
		(net "M_H_CPU0_SB_CA<3>")
	)
	(segment
		(start 451.718172 -250.441968)
		(end 450.356732 -250.441968)
		(width 0.18288)
		(layer "In11.Cu")
		(net "M_H_CPU0_SB_CA<3>")
	)
	(segment
		(start 419.837616 -250.441206)
		(end 419.690296 -250.293886)
		(width 0.18288)
		(layer "In11.Cu")
		(net "M_H_CPU0_SB_CA<3>")
	)
	(segment
		(start 388.003288 -249.58675)
		(end 387.53034 -249.58675)
		(width 0.18288)
		(layer "In11.Cu")
		(net "M_H_CPU0_SB_CA<3>")
	)
	(segment
		(start 413.753046 -251.210826)
		(end 412.359094 -251.210826)
		(width 0.18288)
		(layer "In11.Cu")
		(net "M_H_CPU0_SB_CA<3>")
	)
	(segment
		(start 393.476226 -247.58777)
		(end 392.231372 -247.83542)
		(width 0.18288)
		(layer "In11.Cu")
		(net "M_H_CPU0_SB_CA<3>")
	)
	(segment
		(start 450.22135 -250.306586)
		(end 449.611242 -250.306586)
		(width 0.18288)
		(layer "In11.Cu")
		(net "M_H_CPU0_SB_CA<3>")
	)
	(segment
		(start 440.8932 -251.29109)
		(end 438.858406 -251.29109)
		(width 0.18288)
		(layer "In11.Cu")
		(net "M_H_CPU0_SB_CA<3>")
	)
	(segment
		(start 441.134246 -251.532136)
		(end 440.8932 -251.29109)
		(width 0.18288)
		(layer "In11.Cu")
		(net "M_H_CPU0_SB_CA<3>")
	)
	(segment
		(start 405.22779 -250.546362)
		(end 405.227536 -250.546108)
		(width 0.18288)
		(layer "In11.Cu")
		(net "M_H_CPU0_SB_CA<3>")
	)
	(segment
		(start 414.44799 -250.515882)
		(end 413.753046 -251.210826)
		(width 0.18288)
		(layer "In11.Cu")
		(net "M_H_CPU0_SB_CA<3>")
	)
	(segment
		(start 448.493388 -251.42444)
		(end 446.562988 -251.42444)
		(width 0.18288)
		(layer "In11.Cu")
		(net "M_H_CPU0_SB_CA<3>")
	)
	(segment
		(start 376.309636 -247.50268)
		(end 376.300746 -247.4976)
		(width 0.088646)
		(layer "In11.Cu")
		(net "M_H_CPU0_SB_CA<3>")
	)
	(segment
		(start 384.672332 -248.316496)
		(end 384.654298 -248.32691)
		(width 0.088646)
		(layer "In11.Cu")
		(net "M_H_CPU0_SB_CA<3>")
	)
	(segment
		(start 384.654298 -248.32691)
		(end 384.635756 -248.335038)
		(width 0.088646)
		(layer "In11.Cu")
		(net "M_H_CPU0_SB_CA<3>")
	)
	(segment
		(start 450.356732 -250.441968)
		(end 450.22135 -250.306586)
		(width 0.18288)
		(layer "In11.Cu")
		(net "M_H_CPU0_SB_CA<3>")
	)
	(segment
		(start 422.296844 -250.626118)
		(end 422.111932 -250.441206)
		(width 0.18288)
		(layer "In11.Cu")
		(net "M_H_CPU0_SB_CA<3>")
	)
	(segment
		(start 416.724846 -250.515882)
		(end 414.44799 -250.515882)
		(width 0.18288)
		(layer "In11.Cu")
		(net "M_H_CPU0_SB_CA<3>")
	)
	(segment
		(start 387.53034 -249.58675)
		(end 386.569458 -248.625868)
		(width 0.18288)
		(layer "In11.Cu")
		(net "M_H_CPU0_SB_CA<3>")
	)
	(segment
		(start 381.008382 -247.50268)
		(end 380.997968 -247.496584)
		(width 0.088646)
		(layer "In11.Cu")
		(net "M_H_CPU0_SB_CA<3>")
	)
	(segment
		(start 405.227536 -250.546108)
		(end 403.144228 -250.546108)
		(width 0.18288)
		(layer "In11.Cu")
		(net "M_H_CPU0_SB_CA<3>")
	)
	(segment
		(start 376.698764 -247.494044)
		(end 376.684032 -247.50268)
		(width 0.088646)
		(layer "In11.Cu")
		(net "M_H_CPU0_SB_CA<3>")
	)
	(segment
		(start 375.845578 -246.69242)
		(end 375.839482 -246.688864)
		(width 0.088646)
		(layer "In11.Cu")
		(net "M_H_CPU0_SB_CA<3>")
	)
	(segment
		(start 379.128782 -247.50268)
		(end 379.118368 -247.496584)
		(width 0.088646)
		(layer "In11.Cu")
		(net "M_H_CPU0_SB_CA<3>")
	)
	(segment
		(start 430.455832 -250.716034)
		(end 427.762416 -250.716034)
		(width 0.18288)
		(layer "In11.Cu")
		(net "M_H_CPU0_SB_CA<3>")
	)
	(segment
		(start 398.912842 -249.956574)
		(end 396.544038 -247.58777)
		(width 0.18288)
		(layer "In11.Cu")
		(net "M_H_CPU0_SB_CA<3>")
	)
	(segment
		(start 425.769278 -250.563888)
		(end 425.769278 -251.051314)
		(width 0.18288)
		(layer "In11.Cu")
		(net "M_H_CPU0_SB_CA<3>")
	)
	(segment
		(start 386.569458 -248.625868)
		(end 386.052568 -248.625868)
		(width 0.18288)
		(layer "In11.Cu")
		(net "M_H_CPU0_SB_CA<3>")
	)
	(segment
		(start 375.839482 -246.688864)
		(end 375.830592 -246.683784)
		(width 0.088646)
		(layer "In11.Cu")
		(net "M_H_CPU0_SB_CA<3>")
	)
	(arc
		(start 376.300746 -247.4976)
		(mid 376.169832 -247.36124)
		(end 376.122184 -247.178322)
		(width 0.088646)
		(layer "In11.Cu")
		(net "M_H_CPU0_SB_CA<3>")
	)
	(arc
		(start 376.684032 -247.50268)
		(mid 376.496834 -247.552823)
		(end 376.309636 -247.50268)
		(width 0.088646)
		(layer "In11.Cu")
		(net "M_H_CPU0_SB_CA<3>")
	)
	(arc
		(start 379.503178 -247.50268)
		(mid 379.31598 -247.552823)
		(end 379.128782 -247.50268)
		(width 0.088646)
		(layer "In11.Cu")
		(net "M_H_CPU0_SB_CA<3>")
	)
	(arc
		(start 381.469646 -248.311416)
		(mid 381.338732 -248.175056)
		(end 381.291084 -247.992138)
		(width 0.088646)
		(layer "In11.Cu")
		(net "M_H_CPU0_SB_CA<3>")
	)
	(arc
		(start 383.358136 -248.316496)
		(mid 383.075434 -248.240754)
		(end 382.792732 -248.316496)
		(width 0.088646)
		(layer "In11.Cu")
		(net "M_H_CPU0_SB_CA<3>")
	)
	(arc
		(start 378.563632 -247.50268)
		(mid 378.376434 -247.552823)
		(end 378.189236 -247.50268)
		(width 0.088646)
		(layer "In11.Cu")
		(net "M_H_CPU0_SB_CA<3>")
	)
	(arc
		(start 377.623832 -247.50268)
		(mid 377.436634 -247.552823)
		(end 377.249436 -247.50268)
		(width 0.088646)
		(layer "In11.Cu")
		(net "M_H_CPU0_SB_CA<3>")
	)
	(arc
		(start 378.189236 -247.50268)
		(mid 377.915037 -247.426845)
		(end 377.638564 -247.494044)
		(width 0.088646)
		(layer "In11.Cu")
		(net "M_H_CPU0_SB_CA<3>")
	)
	(arc
		(start 382.418336 -248.316496)
		(mid 382.135634 -248.240754)
		(end 381.852932 -248.316496)
		(width 0.088646)
		(layer "In11.Cu")
		(net "M_H_CPU0_SB_CA<3>")
	)
	(arc
		(start 381.852932 -248.316496)
		(mid 381.665734 -248.366639)
		(end 381.478536 -248.316496)
		(width 0.088646)
		(layer "In11.Cu")
		(net "M_H_CPU0_SB_CA<3>")
	)
	(arc
		(start 376.122184 -247.178322)
		(mid 376.048193 -246.898756)
		(end 375.845578 -246.69242)
		(width 0.088646)
		(layer "In11.Cu")
		(net "M_H_CPU0_SB_CA<3>")
	)
	(arc
		(start 377.249436 -247.50268)
		(mid 376.975237 -247.426845)
		(end 376.698764 -247.494044)
		(width 0.088646)
		(layer "In11.Cu")
		(net "M_H_CPU0_SB_CA<3>")
	)
	(arc
		(start 385.35483 -248.406412)
		(mid 385.299228 -248.357619)
		(end 385.237736 -248.316496)
		(width 0.088646)
		(layer "In11.Cu")
		(net "M_H_CPU0_SB_CA<3>")
	)
	(arc
		(start 382.792732 -248.316496)
		(mid 382.605534 -248.366639)
		(end 382.418336 -248.316496)
		(width 0.088646)
		(layer "In11.Cu")
		(net "M_H_CPU0_SB_CA<3>")
	)
	(arc
		(start 381.291084 -247.992138)
		(mid 381.217093 -247.712572)
		(end 381.014478 -247.506236)
		(width 0.088646)
		(layer "In11.Cu")
		(net "M_H_CPU0_SB_CA<3>")
	)
	(arc
		(start 384.635756 -248.335038)
		(mid 384.46463 -248.366099)
		(end 384.297936 -248.316496)
		(width 0.088646)
		(layer "In11.Cu")
		(net "M_H_CPU0_SB_CA<3>")
	)
	(arc
		(start 380.443232 -247.50268)
		(mid 380.256034 -247.552823)
		(end 380.068836 -247.50268)
		(width 0.088646)
		(layer "In11.Cu")
		(net "M_H_CPU0_SB_CA<3>")
	)
	(arc
		(start 383.732532 -248.316496)
		(mid 383.545334 -248.366639)
		(end 383.358136 -248.316496)
		(width 0.088646)
		(layer "In11.Cu")
		(net "M_H_CPU0_SB_CA<3>")
	)
	(arc
		(start 384.297936 -248.316496)
		(mid 384.015234 -248.240754)
		(end 383.732532 -248.316496)
		(width 0.088646)
		(layer "In11.Cu")
		(net "M_H_CPU0_SB_CA<3>")
	)
	(arc
		(start 375.830592 -246.683784)
		(mid 375.714853 -246.57196)
		(end 375.656602 -246.42191)
		(width 0.088646)
		(layer "In11.Cu")
		(net "M_H_CPU0_SB_CA<3>")
	)
	(arc
		(start 380.997968 -247.496584)
		(mid 380.71979 -247.426861)
		(end 380.443232 -247.50268)
		(width 0.088646)
		(layer "In11.Cu")
		(net "M_H_CPU0_SB_CA<3>")
	)
	(arc
		(start 385.237736 -248.316496)
		(mid 384.955034 -248.240754)
		(end 384.672332 -248.316496)
		(width 0.088646)
		(layer "In11.Cu")
		(net "M_H_CPU0_SB_CA<3>")
	)
	(arc
		(start 379.118368 -247.496584)
		(mid 378.84019 -247.426861)
		(end 378.563632 -247.50268)
		(width 0.088646)
		(layer "In11.Cu")
		(net "M_H_CPU0_SB_CA<3>")
	)
	(arc
		(start 380.068836 -247.50268)
		(mid 379.792023 -247.42681)
		(end 379.513592 -247.496584)
		(width 0.088646)
		(layer "In11.Cu")
		(net "M_H_CPU0_SB_CA<3>")
	)
	(segment
		(start 452.016114 -250.866656)
		(end 453.081644 -250.866656)
		(width 0.20066)
		(layer "F.Cu")
		(net "M_H_CPU0_SB_CA<2>")
	)
	(segment
		(start 459.55966 -250.866402)
		(end 459.559914 -250.866656)
		(width 0.20066)
		(layer "F.Cu")
		(net "M_H_CPU0_SB_CA<2>")
	)
	(segment
		(start 457.542646 -251.304044)
		(end 457.980288 -250.866402)
		(width 0.20066)
		(layer "F.Cu")
		(net "M_H_CPU0_SB_CA<2>")
	)
	(segment
		(start 457.980288 -250.866402)
		(end 459.55966 -250.866402)
		(width 0.20066)
		(layer "F.Cu")
		(net "M_H_CPU0_SB_CA<2>")
	)
	(segment
		(start 453.081644 -250.866656)
		(end 453.575928 -250.372372)
		(width 0.20066)
		(layer "F.Cu")
		(net "M_H_CPU0_SB_CA<2>")
	)
	(segment
		(start 453.901302 -250.372372)
		(end 454.820528 -251.291598)
		(width 0.20066)
		(layer "F.Cu")
		(net "M_H_CPU0_SB_CA<2>")
	)
	(segment
		(start 457.126594 -251.304044)
		(end 457.542646 -251.304044)
		(width 0.20066)
		(layer "F.Cu")
		(net "M_H_CPU0_SB_CA<2>")
	)
	(segment
		(start 450.911214 -250.866656)
		(end 452.016114 -250.866656)
		(width 0.20066)
		(layer "F.Cu")
		(net "M_H_CPU0_SB_CA<2>")
	)
	(segment
		(start 454.941686 -251.291598)
		(end 457.114148 -251.291598)
		(width 0.1016)
		(layer "F.Cu")
		(net "M_H_CPU0_SB_CA<2>")
	)
	(segment
		(start 454.92797 -251.291598)
		(end 454.941686 -251.291598)
		(width 0.101854)
		(layer "F.Cu")
		(net "M_H_CPU0_SB_CA<2>")
	)
	(segment
		(start 454.820528 -251.291598)
		(end 454.92797 -251.291598)
		(width 0.20066)
		(layer "F.Cu")
		(net "M_H_CPU0_SB_CA<2>")
	)
	(segment
		(start 375.08688 -246.900192)
		(end 375.08688 -246.364506)
		(width 0.20066)
		(layer "F.Cu")
		(net "M_H_CPU0_SB_CA<2>")
	)
	(segment
		(start 453.575928 -250.372372)
		(end 453.901302 -250.372372)
		(width 0.20066)
		(layer "F.Cu")
		(net "M_H_CPU0_SB_CA<2>")
	)
	(segment
		(start 457.114148 -251.291598)
		(end 457.126594 -251.304044)
		(width 0.1016)
		(layer "F.Cu")
		(net "M_H_CPU0_SB_CA<2>")
	)
	(segment
		(start 375.087134 -246.900446)
		(end 375.08688 -246.900192)
		(width 0.20066)
		(layer "F.Cu")
		(net "M_H_CPU0_SB_CA<2>")
	)
	(segment
		(start 385.660138 -248.98096)
		(end 385.22021 -248.541032)
		(width 0.088646)
		(layer "In11.Cu")
		(net "M_H_CPU0_SB_CA<2>")
	)
	(segment
		(start 437.057292 -252.377194)
		(end 436.13324 -253.301246)
		(width 0.18288)
		(layer "In11.Cu")
		(net "M_H_CPU0_SB_CA<2>")
	)
	(segment
		(start 419.847776 -251.290328)
		(end 419.636702 -251.501402)
		(width 0.18288)
		(layer "In11.Cu")
		(net "M_H_CPU0_SB_CA<2>")
	)
	(segment
		(start 428.297086 -252.341634)
		(end 428.09668 -252.141228)
		(width 0.18288)
		(layer "In11.Cu")
		(net "M_H_CPU0_SB_CA<2>")
	)
	(segment
		(start 436.13324 -253.301246)
		(end 433.760118 -253.301246)
		(width 0.18288)
		(layer "In11.Cu")
		(net "M_H_CPU0_SB_CA<2>")
	)
	(segment
		(start 403.029166 -251.055124)
		(end 401.681696 -250.497086)
		(width 0.18288)
		(layer "In11.Cu")
		(net "M_H_CPU0_SB_CA<2>")
	)
	(segment
		(start 426.293534 -251.441712)
		(end 426.293534 -251.948188)
		(width 0.18288)
		(layer "In11.Cu")
		(net "M_H_CPU0_SB_CA<2>")
	)
	(segment
		(start 426.100494 -252.141228)
		(end 424.323256 -252.141228)
		(width 0.18288)
		(layer "In11.Cu")
		(net "M_H_CPU0_SB_CA<2>")
	)
	(segment
		(start 429.769778 -251.429012)
		(end 429.576738 -251.235972)
		(width 0.18288)
		(layer "In11.Cu")
		(net "M_H_CPU0_SB_CA<2>")
	)
	(segment
		(start 426.486574 -251.248672)
		(end 426.293534 -251.441712)
		(width 0.18288)
		(layer "In11.Cu")
		(net "M_H_CPU0_SB_CA<2>")
	)
	(segment
		(start 442.929264 -252.328172)
		(end 442.74232 -252.141228)
		(width 0.18288)
		(layer "In11.Cu")
		(net "M_H_CPU0_SB_CA<2>")
	)
	(segment
		(start 375.399554 -246.364506)
		(end 375.08688 -246.364506)
		(width 0.088646)
		(layer "In11.Cu")
		(net "M_H_CPU0_SB_CA<2>")
	)
	(segment
		(start 422.811702 -251.161804)
		(end 422.678098 -251.295408)
		(width 0.18288)
		(layer "In11.Cu")
		(net "M_H_CPU0_SB_CA<2>")
	)
	(segment
		(start 375.46534 -246.430292)
		(end 375.399554 -246.364506)
		(width 0.088646)
		(layer "In11.Cu")
		(net "M_H_CPU0_SB_CA<2>")
	)
	(segment
		(start 423.343832 -251.161804)
		(end 422.811702 -251.161804)
		(width 0.18288)
		(layer "In11.Cu")
		(net "M_H_CPU0_SB_CA<2>")
	)
	(segment
		(start 428.09668 -252.141228)
		(end 427.190154 -252.141228)
		(width 0.18288)
		(layer "In11.Cu")
		(net "M_H_CPU0_SB_CA<2>")
	)
	(segment
		(start 446.301368 -251.964952)
		(end 445.938148 -252.328172)
		(width 0.18288)
		(layer "In11.Cu")
		(net "M_H_CPU0_SB_CA<2>")
	)
	(segment
		(start 424.323256 -252.141228)
		(end 423.343832 -251.161804)
		(width 0.18288)
		(layer "In11.Cu")
		(net "M_H_CPU0_SB_CA<2>")
	)
	(segment
		(start 429.962818 -252.341634)
		(end 429.769778 -252.148594)
		(width 0.18288)
		(layer "In11.Cu")
		(net "M_H_CPU0_SB_CA<2>")
	)
	(segment
		(start 384.74396 -248.495566)
		(end 384.720846 -248.506234)
		(width 0.088646)
		(layer "In11.Cu")
		(net "M_H_CPU0_SB_CA<2>")
	)
	(segment
		(start 421.458136 -252.070616)
		(end 421.458136 -251.488448)
		(width 0.18288)
		(layer "In11.Cu")
		(net "M_H_CPU0_SB_CA<2>")
	)
	(segment
		(start 413.912304 -252.168914)
		(end 411.530546 -252.168914)
		(width 0.18288)
		(layer "In11.Cu")
		(net "M_H_CPU0_SB_CA<2>")
	)
	(segment
		(start 428.873158 -252.341634)
		(end 428.297086 -252.341634)
		(width 0.18288)
		(layer "In11.Cu")
		(net "M_H_CPU0_SB_CA<2>")
	)
	(segment
		(start 432.474878 -252.016006)
		(end 431.860706 -252.016006)
		(width 0.18288)
		(layer "In11.Cu")
		(net "M_H_CPU0_SB_CA<2>")
	)
	(segment
		(start 386.052568 -248.98096)
		(end 385.660138 -248.98096)
		(width 0.088646)
		(layer "In11.Cu")
		(net "M_H_CPU0_SB_CA<2>")
	)
	(segment
		(start 392.382756 -248.164604)
		(end 388.043928 -249.961654)
		(width 0.18288)
		(layer "In11.Cu")
		(net "M_H_CPU0_SB_CA<2>")
	)
	(segment
		(start 429.066198 -251.429012)
		(end 429.066198 -252.148594)
		(width 0.18288)
		(layer "In11.Cu")
		(net "M_H_CPU0_SB_CA<2>")
	)
	(segment
		(start 431.860706 -252.016006)
		(end 431.535078 -252.341634)
		(width 0.18288)
		(layer "In11.Cu")
		(net "M_H_CPU0_SB_CA<2>")
	)
	(segment
		(start 398.73301 -250.497086)
		(end 396.174214 -247.93829)
		(width 0.18288)
		(layer "In11.Cu")
		(net "M_H_CPU0_SB_CA<2>")
	)
	(segment
		(start 384.767836 -248.48185)
		(end 384.74396 -248.495566)
		(width 0.088646)
		(layer "In11.Cu")
		(net "M_H_CPU0_SB_CA<2>")
	)
	(segment
		(start 421.458136 -251.488448)
		(end 421.260016 -251.290328)
		(width 0.18288)
		(layer "In11.Cu")
		(net "M_H_CPU0_SB_CA<2>")
	)
	(segment
		(start 377.719082 -247.66778)
		(end 377.70435 -247.676416)
		(width 0.088646)
		(layer "In11.Cu")
		(net "M_H_CPU0_SB_CA<2>")
	)
	(segment
		(start 429.576738 -251.235972)
		(end 429.259238 -251.235972)
		(width 0.18288)
		(layer "In11.Cu")
		(net "M_H_CPU0_SB_CA<2>")
	)
	(segment
		(start 426.997114 -251.441712)
		(end 426.804074 -251.248672)
		(width 0.18288)
		(layer "In11.Cu")
		(net "M_H_CPU0_SB_CA<2>")
	)
	(segment
		(start 445.938148 -252.328172)
		(end 442.929264 -252.328172)
		(width 0.18288)
		(layer "In11.Cu")
		(net "M_H_CPU0_SB_CA<2>")
	)
	(segment
		(start 378.659136 -247.66778)
		(end 378.648722 -247.673876)
		(width 0.088646)
		(layer "In11.Cu")
		(net "M_H_CPU0_SB_CA<2>")
	)
	(segment
		(start 396.174214 -247.93829)
		(end 393.520422 -247.93829)
		(width 0.18288)
		(layer "In11.Cu")
		(net "M_H_CPU0_SB_CA<2>")
	)
	(segment
		(start 433.760118 -253.301246)
		(end 432.474878 -252.016006)
		(width 0.18288)
		(layer "In11.Cu")
		(net "M_H_CPU0_SB_CA<2>")
	)
	(segment
		(start 422.354756 -251.295408)
		(end 422.161716 -251.488448)
		(width 0.18288)
		(layer "In11.Cu")
		(net "M_H_CPU0_SB_CA<2>")
	)
	(segment
		(start 388.043928 -249.961654)
		(end 387.26237 -249.961654)
		(width 0.18288)
		(layer "In11.Cu")
		(net "M_H_CPU0_SB_CA<2>")
	)
	(segment
		(start 410.695394 -251.333762)
		(end 408.652218 -251.333762)
		(width 0.18288)
		(layer "In11.Cu")
		(net "M_H_CPU0_SB_CA<2>")
	)
	(segment
		(start 450.78396 -251.297694)
		(end 450.27723 -251.507752)
		(width 0.18288)
		(layer "In11.Cu")
		(net "M_H_CPU0_SB_CA<2>")
	)
	(segment
		(start 416.510978 -251.063252)
		(end 415.017966 -251.063252)
		(width 0.18288)
		(layer "In11.Cu")
		(net "M_H_CPU0_SB_CA<2>")
	)
	(segment
		(start 422.161716 -252.070616)
		(end 421.968676 -252.263656)
		(width 0.18288)
		(layer "In11.Cu")
		(net "M_H_CPU0_SB_CA<2>")
	)
	(segment
		(start 429.259238 -251.235972)
		(end 429.066198 -251.429012)
		(width 0.18288)
		(layer "In11.Cu")
		(net "M_H_CPU0_SB_CA<2>")
	)
	(segment
		(start 429.769778 -252.148594)
		(end 429.769778 -251.429012)
		(width 0.18288)
		(layer "In11.Cu")
		(net "M_H_CPU0_SB_CA<2>")
	)
	(segment
		(start 415.017966 -251.063252)
		(end 413.912304 -252.168914)
		(width 0.18288)
		(layer "In11.Cu")
		(net "M_H_CPU0_SB_CA<2>")
	)
	(segment
		(start 376.779282 -247.66778)
		(end 376.76455 -247.676416)
		(width 0.088646)
		(layer "In11.Cu")
		(net "M_H_CPU0_SB_CA<2>")
	)
	(segment
		(start 375.753122 -246.859044)
		(end 375.744232 -246.853964)
		(width 0.088646)
		(layer "In11.Cu")
		(net "M_H_CPU0_SB_CA<2>")
	)
	(segment
		(start 450.911214 -251.17044)
		(end 450.78396 -251.297694)
		(width 0.18288)
		(layer "In11.Cu")
		(net "M_H_CPU0_SB_CA<2>")
	)
	(segment
		(start 426.997114 -251.948188)
		(end 426.997114 -251.441712)
		(width 0.18288)
		(layer "In11.Cu")
		(net "M_H_CPU0_SB_CA<2>")
	)
	(segment
		(start 426.293534 -251.948188)
		(end 426.100494 -252.141228)
		(width 0.18288)
		(layer "In11.Cu")
		(net "M_H_CPU0_SB_CA<2>")
	)
	(segment
		(start 438.962546 -252.377194)
		(end 437.057292 -252.377194)
		(width 0.18288)
		(layer "In11.Cu")
		(net "M_H_CPU0_SB_CA<2>")
	)
	(segment
		(start 450.27723 -251.507752)
		(end 449.82003 -251.964952)
		(width 0.18288)
		(layer "In11.Cu")
		(net "M_H_CPU0_SB_CA<2>")
	)
	(segment
		(start 380.538736 -247.66778)
		(end 380.528322 -247.673876)
		(width 0.088646)
		(layer "In11.Cu")
		(net "M_H_CPU0_SB_CA<2>")
	)
	(segment
		(start 386.281676 -248.98096)
		(end 386.052568 -248.98096)
		(width 0.18288)
		(layer "In11.Cu")
		(net "M_H_CPU0_SB_CA<2>")
	)
	(segment
		(start 416.949128 -251.501402)
		(end 416.510978 -251.063252)
		(width 0.18288)
		(layer "In11.Cu")
		(net "M_H_CPU0_SB_CA<2>")
	)
	(segment
		(start 422.678098 -251.295408)
		(end 422.354756 -251.295408)
		(width 0.18288)
		(layer "In11.Cu")
		(net "M_H_CPU0_SB_CA<2>")
	)
	(segment
		(start 431.535078 -252.341634)
		(end 429.962818 -252.341634)
		(width 0.18288)
		(layer "In11.Cu")
		(net "M_H_CPU0_SB_CA<2>")
	)
	(segment
		(start 380.922022 -247.67286)
		(end 380.913132 -247.66778)
		(width 0.088646)
		(layer "In11.Cu")
		(net "M_H_CPU0_SB_CA<2>")
	)
	(segment
		(start 427.190154 -252.141228)
		(end 426.997114 -251.948188)
		(width 0.18288)
		(layer "In11.Cu")
		(net "M_H_CPU0_SB_CA<2>")
	)
	(segment
		(start 401.681696 -250.497086)
		(end 398.73301 -250.497086)
		(width 0.18288)
		(layer "In11.Cu")
		(net "M_H_CPU0_SB_CA<2>")
	)
	(segment
		(start 375.931684 -247.193816)
		(end 375.931684 -247.178322)
		(width 0.088646)
		(layer "In11.Cu")
		(net "M_H_CPU0_SB_CA<2>")
	)
	(segment
		(start 421.968676 -252.263656)
		(end 421.651176 -252.263656)
		(width 0.18288)
		(layer "In11.Cu")
		(net "M_H_CPU0_SB_CA<2>")
	)
	(segment
		(start 421.260016 -251.290328)
		(end 419.847776 -251.290328)
		(width 0.18288)
		(layer "In11.Cu")
		(net "M_H_CPU0_SB_CA<2>")
	)
	(segment
		(start 375.744232 -246.853964)
		(end 375.738136 -246.850408)
		(width 0.088646)
		(layer "In11.Cu")
		(net "M_H_CPU0_SB_CA<2>")
	)
	(segment
		(start 422.161716 -251.488448)
		(end 422.161716 -252.070616)
		(width 0.18288)
		(layer "In11.Cu")
		(net "M_H_CPU0_SB_CA<2>")
	)
	(segment
		(start 426.804074 -251.248672)
		(end 426.486574 -251.248672)
		(width 0.18288)
		(layer "In11.Cu")
		(net "M_H_CPU0_SB_CA<2>")
	)
	(segment
		(start 442.74232 -252.141228)
		(end 439.198512 -252.141228)
		(width 0.18288)
		(layer "In11.Cu")
		(net "M_H_CPU0_SB_CA<2>")
	)
	(segment
		(start 408.37358 -251.055124)
		(end 403.029166 -251.055124)
		(width 0.18288)
		(layer "In11.Cu")
		(net "M_H_CPU0_SB_CA<2>")
	)
	(segment
		(start 429.066198 -252.148594)
		(end 428.873158 -252.341634)
		(width 0.18288)
		(layer "In11.Cu")
		(net "M_H_CPU0_SB_CA<2>")
	)
	(segment
		(start 408.652218 -251.333762)
		(end 408.37358 -251.055124)
		(width 0.18288)
		(layer "In11.Cu")
		(net "M_H_CPU0_SB_CA<2>")
	)
	(segment
		(start 393.520422 -247.93829)
		(end 392.382756 -248.164604)
		(width 0.18288)
		(layer "In11.Cu")
		(net "M_H_CPU0_SB_CA<2>")
	)
	(segment
		(start 439.198512 -252.141228)
		(end 438.962546 -252.377194)
		(width 0.18288)
		(layer "In11.Cu")
		(net "M_H_CPU0_SB_CA<2>")
	)
	(segment
		(start 387.26237 -249.961654)
		(end 386.281676 -248.98096)
		(width 0.18288)
		(layer "In11.Cu")
		(net "M_H_CPU0_SB_CA<2>")
	)
	(segment
		(start 450.911214 -250.866656)
		(end 450.911214 -251.17044)
		(width 0.18288)
		(layer "In11.Cu")
		(net "M_H_CPU0_SB_CA<2>")
	)
	(segment
		(start 421.651176 -252.263656)
		(end 421.458136 -252.070616)
		(width 0.18288)
		(layer "In11.Cu")
		(net "M_H_CPU0_SB_CA<2>")
	)
	(segment
		(start 381.100584 -248.01068)
		(end 381.100584 -247.992138)
		(width 0.088646)
		(layer "In11.Cu")
		(net "M_H_CPU0_SB_CA<2>")
	)
	(segment
		(start 379.043946 -247.673876)
		(end 379.033532 -247.66778)
		(width 0.088646)
		(layer "In11.Cu")
		(net "M_H_CPU0_SB_CA<2>")
	)
	(segment
		(start 449.82003 -251.964952)
		(end 446.301368 -251.964952)
		(width 0.18288)
		(layer "In11.Cu")
		(net "M_H_CPU0_SB_CA<2>")
	)
	(segment
		(start 419.636702 -251.501402)
		(end 416.949128 -251.501402)
		(width 0.18288)
		(layer "In11.Cu")
		(net "M_H_CPU0_SB_CA<2>")
	)
	(segment
		(start 411.530546 -252.168914)
		(end 410.695394 -251.333762)
		(width 0.18288)
		(layer "In11.Cu")
		(net "M_H_CPU0_SB_CA<2>")
	)
	(arc
		(start 379.033532 -247.66778)
		(mid 378.846334 -247.617637)
		(end 378.659136 -247.66778)
		(width 0.088646)
		(layer "In11.Cu")
		(net "M_H_CPU0_SB_CA<2>")
	)
	(arc
		(start 377.153678 -247.66778)
		(mid 376.96648 -247.617637)
		(end 376.779282 -247.66778)
		(width 0.088646)
		(layer "In11.Cu")
		(net "M_H_CPU0_SB_CA<2>")
	)
	(arc
		(start 384.720846 -248.506234)
		(mid 384.458662 -248.557075)
		(end 384.202432 -248.48185)
		(width 0.088646)
		(layer "In11.Cu")
		(net "M_H_CPU0_SB_CA<2>")
	)
	(arc
		(start 381.383032 -248.48185)
		(mid 381.180746 -248.282869)
		(end 381.100584 -248.01068)
		(width 0.088646)
		(layer "In11.Cu")
		(net "M_H_CPU0_SB_CA<2>")
	)
	(arc
		(start 376.76455 -247.676416)
		(mid 376.488075 -247.743736)
		(end 376.213878 -247.66778)
		(width 0.088646)
		(layer "In11.Cu")
		(net "M_H_CPU0_SB_CA<2>")
	)
	(arc
		(start 385.22021 -248.541032)
		(mid 385.18316 -248.508886)
		(end 385.142232 -248.48185)
		(width 0.088646)
		(layer "In11.Cu")
		(net "M_H_CPU0_SB_CA<2>")
	)
	(arc
		(start 381.100584 -247.992138)
		(mid 381.052905 -247.809238)
		(end 380.922022 -247.67286)
		(width 0.088646)
		(layer "In11.Cu")
		(net "M_H_CPU0_SB_CA<2>")
	)
	(arc
		(start 385.142232 -248.48185)
		(mid 384.955034 -248.431707)
		(end 384.767836 -248.48185)
		(width 0.088646)
		(layer "In11.Cu")
		(net "M_H_CPU0_SB_CA<2>")
	)
	(arc
		(start 375.931684 -247.178322)
		(mid 375.884005 -246.995422)
		(end 375.753122 -246.859044)
		(width 0.088646)
		(layer "In11.Cu")
		(net "M_H_CPU0_SB_CA<2>")
	)
	(arc
		(start 378.648722 -247.673876)
		(mid 378.37029 -247.743722)
		(end 378.093478 -247.66778)
		(width 0.088646)
		(layer "In11.Cu")
		(net "M_H_CPU0_SB_CA<2>")
	)
	(arc
		(start 383.262632 -248.48185)
		(mid 383.075434 -248.431707)
		(end 382.888236 -248.48185)
		(width 0.088646)
		(layer "In11.Cu")
		(net "M_H_CPU0_SB_CA<2>")
	)
	(arc
		(start 379.973078 -247.66778)
		(mid 379.78588 -247.617637)
		(end 379.598682 -247.66778)
		(width 0.088646)
		(layer "In11.Cu")
		(net "M_H_CPU0_SB_CA<2>")
	)
	(arc
		(start 380.528322 -247.673876)
		(mid 380.24989 -247.743722)
		(end 379.973078 -247.66778)
		(width 0.088646)
		(layer "In11.Cu")
		(net "M_H_CPU0_SB_CA<2>")
	)
	(arc
		(start 380.913132 -247.66778)
		(mid 380.725934 -247.617637)
		(end 380.538736 -247.66778)
		(width 0.088646)
		(layer "In11.Cu")
		(net "M_H_CPU0_SB_CA<2>")
	)
	(arc
		(start 379.598682 -247.66778)
		(mid 379.322123 -247.743523)
		(end 379.043946 -247.673876)
		(width 0.088646)
		(layer "In11.Cu")
		(net "M_H_CPU0_SB_CA<2>")
	)
	(arc
		(start 382.322832 -248.48185)
		(mid 382.135634 -248.431707)
		(end 381.948436 -248.48185)
		(width 0.088646)
		(layer "In11.Cu")
		(net "M_H_CPU0_SB_CA<2>")
	)
	(arc
		(start 382.888236 -248.48185)
		(mid 382.605534 -248.557592)
		(end 382.322832 -248.48185)
		(width 0.088646)
		(layer "In11.Cu")
		(net "M_H_CPU0_SB_CA<2>")
	)
	(arc
		(start 378.093478 -247.66778)
		(mid 377.90628 -247.617637)
		(end 377.719082 -247.66778)
		(width 0.088646)
		(layer "In11.Cu")
		(net "M_H_CPU0_SB_CA<2>")
	)
	(arc
		(start 384.202432 -248.48185)
		(mid 384.015234 -248.431707)
		(end 383.828036 -248.48185)
		(width 0.088646)
		(layer "In11.Cu")
		(net "M_H_CPU0_SB_CA<2>")
	)
	(arc
		(start 383.828036 -248.48185)
		(mid 383.545334 -248.557592)
		(end 383.262632 -248.48185)
		(width 0.088646)
		(layer "In11.Cu")
		(net "M_H_CPU0_SB_CA<2>")
	)
	(arc
		(start 375.738136 -246.850408)
		(mid 375.552681 -246.672213)
		(end 375.46534 -246.430292)
		(width 0.088646)
		(layer "In11.Cu")
		(net "M_H_CPU0_SB_CA<2>")
	)
	(arc
		(start 381.948436 -248.48185)
		(mid 381.665734 -248.557592)
		(end 381.383032 -248.48185)
		(width 0.088646)
		(layer "In11.Cu")
		(net "M_H_CPU0_SB_CA<2>")
	)
	(arc
		(start 377.70435 -247.676416)
		(mid 377.427875 -247.743736)
		(end 377.153678 -247.66778)
		(width 0.088646)
		(layer "In11.Cu")
		(net "M_H_CPU0_SB_CA<2>")
	)
	(arc
		(start 376.213878 -247.66778)
		(mid 376.011055 -247.467549)
		(end 375.931684 -247.193816)
		(width 0.088646)
		(layer "In11.Cu")
		(net "M_H_CPU0_SB_CA<2>")
	)
	(segment
		(start 460.844392 -252.149102)
		(end 461.709262 -251.284232)
		(width 0.20066)
		(layer "F.Cu")
		(net "M_H_CPU0_SB_CA<1>")
	)
	(segment
		(start 462.112868 -251.284232)
		(end 462.54543 -251.716794)
		(width 0.20066)
		(layer "F.Cu")
		(net "M_H_CPU0_SB_CA<1>")
	)
	(segment
		(start 457.751942 -251.716794)
		(end 458.187552 -252.152404)
		(width 0.20066)
		(layer "F.Cu")
		(net "M_H_CPU0_SB_CA<1>")
	)
	(segment
		(start 373.207534 -246.900446)
		(end 373.20728 -246.900192)
		(width 0.20066)
		(layer "F.Cu")
		(net "M_H_CPU0_SB_CA<1>")
	)
	(segment
		(start 458.187552 -252.152404)
		(end 458.538326 -252.152404)
		(width 0.20066)
		(layer "F.Cu")
		(net "M_H_CPU0_SB_CA<1>")
	)
	(segment
		(start 460.570326 -252.149102)
		(end 460.844392 -252.149102)
		(width 0.20066)
		(layer "F.Cu")
		(net "M_H_CPU0_SB_CA<1>")
	)
	(segment
		(start 458.538326 -252.152404)
		(end 458.543152 -252.152404)
		(width 0.101854)
		(layer "F.Cu")
		(net "M_H_CPU0_SB_CA<1>")
	)
	(segment
		(start 461.709262 -251.284232)
		(end 462.112868 -251.284232)
		(width 0.20066)
		(layer "F.Cu")
		(net "M_H_CPU0_SB_CA<1>")
	)
	(segment
		(start 458.543152 -252.152404)
		(end 458.55382 -252.141736)
		(width 0.1016)
		(layer "F.Cu")
		(net "M_H_CPU0_SB_CA<1>")
	)
	(segment
		(start 373.20728 -246.900192)
		(end 373.20728 -246.364506)
		(width 0.20066)
		(layer "F.Cu")
		(net "M_H_CPU0_SB_CA<1>")
	)
	(segment
		(start 455.011282 -251.716794)
		(end 456.116182 -251.716794)
		(width 0.20066)
		(layer "F.Cu")
		(net "M_H_CPU0_SB_CA<1>")
	)
	(segment
		(start 462.54543 -251.716794)
		(end 463.659982 -251.716794)
		(width 0.20066)
		(layer "F.Cu")
		(net "M_H_CPU0_SB_CA<1>")
	)
	(segment
		(start 456.116182 -251.716794)
		(end 457.751942 -251.716794)
		(width 0.20066)
		(layer "F.Cu")
		(net "M_H_CPU0_SB_CA<1>")
	)
	(segment
		(start 458.55382 -252.141736)
		(end 460.56296 -252.141736)
		(width 0.1016)
		(layer "F.Cu")
		(net "M_H_CPU0_SB_CA<1>")
	)
	(segment
		(start 460.56296 -252.141736)
		(end 460.570326 -252.149102)
		(width 0.1016)
		(layer "F.Cu")
		(net "M_H_CPU0_SB_CA<1>")
	)
	(segment
		(start 393.570968 -248.28373)
		(end 392.582146 -248.480326)
		(width 0.18288)
		(layer "In11.Cu")
		(net "M_H_CPU0_SB_CA<1>")
	)
	(segment
		(start 386.052568 -249.684794)
		(end 385.36499 -249.684794)
		(width 0.088646)
		(layer "In11.Cu")
		(net "M_H_CPU0_SB_CA<1>")
	)
	(segment
		(start 414.5153 -252.717808)
		(end 411.207966 -252.717808)
		(width 0.18288)
		(layer "In11.Cu")
		(net "M_H_CPU0_SB_CA<1>")
	)
	(segment
		(start 375.839482 -248.316496)
		(end 375.82475 -248.30786)
		(width 0.088646)
		(layer "In11.Cu")
		(net "M_H_CPU0_SB_CA<1>")
	)
	(segment
		(start 433.641246 -253.90348)
		(end 432.807872 -253.070106)
		(width 0.18288)
		(layer "In11.Cu")
		(net "M_H_CPU0_SB_CA<1>")
	)
	(segment
		(start 451.854316 -252.378464)
		(end 451.61708 -252.141228)
		(width 0.18288)
		(layer "In11.Cu")
		(net "M_H_CPU0_SB_CA<1>")
	)
	(segment
		(start 410.402532 -251.912374)
		(end 408.51201 -251.912374)
		(width 0.18288)
		(layer "In11.Cu")
		(net "M_H_CPU0_SB_CA<1>")
	)
	(segment
		(start 379.598682 -248.316496)
		(end 379.588268 -248.3104)
		(width 0.088646)
		(layer "In11.Cu")
		(net "M_H_CPU0_SB_CA<1>")
	)
	(segment
		(start 401.546568 -251.021088)
		(end 398.536414 -251.021088)
		(width 0.18288)
		(layer "In11.Cu")
		(net "M_H_CPU0_SB_CA<1>")
	)
	(segment
		(start 451.61708 -252.141228)
		(end 450.620892 -252.141228)
		(width 0.18288)
		(layer "In11.Cu")
		(net "M_H_CPU0_SB_CA<1>")
	)
	(segment
		(start 376.779282 -248.316496)
		(end 376.76455 -248.30786)
		(width 0.088646)
		(layer "In11.Cu")
		(net "M_H_CPU0_SB_CA<1>")
	)
	(segment
		(start 404.74773 -252.346968)
		(end 401.546568 -251.021088)
		(width 0.18288)
		(layer "In11.Cu")
		(net "M_H_CPU0_SB_CA<1>")
	)
	(segment
		(start 449.746116 -253.016004)
		(end 437.383936 -253.016004)
		(width 0.18288)
		(layer "In11.Cu")
		(net "M_H_CPU0_SB_CA<1>")
	)
	(segment
		(start 381.008636 -249.130566)
		(end 380.999746 -249.125486)
		(width 0.088646)
		(layer "In11.Cu")
		(net "M_H_CPU0_SB_CA<1>")
	)
	(segment
		(start 419.398196 -252.363732)
		(end 414.869376 -252.363732)
		(width 0.18288)
		(layer "In11.Cu")
		(net "M_H_CPU0_SB_CA<1>")
	)
	(segment
		(start 414.869376 -252.363732)
		(end 414.5153 -252.717808)
		(width 0.18288)
		(layer "In11.Cu")
		(net "M_H_CPU0_SB_CA<1>")
	)
	(segment
		(start 384.90017 -249.219974)
		(end 384.096006 -249.219974)
		(width 0.088646)
		(layer "In11.Cu")
		(net "M_H_CPU0_SB_CA<1>")
	)
	(segment
		(start 374.435878 -247.506236)
		(end 374.429782 -247.50268)
		(width 0.088646)
		(layer "In11.Cu")
		(net "M_H_CPU0_SB_CA<1>")
	)
	(segment
		(start 380.538736 -248.316496)
		(end 380.528322 -248.3104)
		(width 0.088646)
		(layer "In11.Cu")
		(net "M_H_CPU0_SB_CA<1>")
	)
	(segment
		(start 373.965978 -246.69242)
		(end 373.950992 -246.683784)
		(width 0.088646)
		(layer "In11.Cu")
		(net "M_H_CPU0_SB_CA<1>")
	)
	(segment
		(start 420.10457 -253.070106)
		(end 419.398196 -252.363732)
		(width 0.18288)
		(layer "In11.Cu")
		(net "M_H_CPU0_SB_CA<1>")
	)
	(segment
		(start 398.536414 -251.021088)
		(end 395.799056 -248.28373)
		(width 0.18288)
		(layer "In11.Cu")
		(net "M_H_CPU0_SB_CA<1>")
	)
	(segment
		(start 450.620892 -252.141228)
		(end 449.746116 -253.016004)
		(width 0.18288)
		(layer "In11.Cu")
		(net "M_H_CPU0_SB_CA<1>")
	)
	(segment
		(start 386.232654 -249.684794)
		(end 386.052568 -249.684794)
		(width 0.18288)
		(layer "In11.Cu")
		(net "M_H_CPU0_SB_CA<1>")
	)
	(segment
		(start 392.582146 -248.480326)
		(end 388.139686 -250.320556)
		(width 0.18288)
		(layer "In11.Cu")
		(net "M_H_CPU0_SB_CA<1>")
	)
	(segment
		(start 454.349612 -252.378464)
		(end 451.854316 -252.378464)
		(width 0.18288)
		(layer "In11.Cu")
		(net "M_H_CPU0_SB_CA<1>")
	)
	(segment
		(start 436.49646 -253.90348)
		(end 433.641246 -253.90348)
		(width 0.18288)
		(layer "In11.Cu")
		(net "M_H_CPU0_SB_CA<1>")
	)
	(segment
		(start 408.077416 -252.346968)
		(end 404.74773 -252.346968)
		(width 0.18288)
		(layer "In11.Cu")
		(net "M_H_CPU0_SB_CA<1>")
	)
	(segment
		(start 378.659136 -248.316496)
		(end 378.648722 -248.3104)
		(width 0.088646)
		(layer "In11.Cu")
		(net "M_H_CPU0_SB_CA<1>")
	)
	(segment
		(start 380.821184 -248.806208)
		(end 380.821184 -248.787666)
		(width 0.088646)
		(layer "In11.Cu")
		(net "M_H_CPU0_SB_CA<1>")
	)
	(segment
		(start 437.383936 -253.016004)
		(end 436.49646 -253.90348)
		(width 0.18288)
		(layer "In11.Cu")
		(net "M_H_CPU0_SB_CA<1>")
	)
	(segment
		(start 388.139686 -250.320556)
		(end 386.868416 -250.320556)
		(width 0.18288)
		(layer "In11.Cu")
		(net "M_H_CPU0_SB_CA<1>")
	)
	(segment
		(start 411.207966 -252.717808)
		(end 410.402532 -251.912374)
		(width 0.18288)
		(layer "In11.Cu")
		(net "M_H_CPU0_SB_CA<1>")
	)
	(segment
		(start 374.712484 -248.000774)
		(end 374.712484 -247.992138)
		(width 0.088646)
		(layer "In11.Cu")
		(net "M_H_CPU0_SB_CA<1>")
	)
	(segment
		(start 432.807872 -253.070106)
		(end 420.10457 -253.070106)
		(width 0.18288)
		(layer "In11.Cu")
		(net "M_H_CPU0_SB_CA<1>")
	)
	(segment
		(start 374.242584 -247.186958)
		(end 374.242584 -247.178322)
		(width 0.088646)
		(layer "In11.Cu")
		(net "M_H_CPU0_SB_CA<1>")
	)
	(segment
		(start 455.011282 -251.716794)
		(end 454.349612 -252.378464)
		(width 0.18288)
		(layer "In11.Cu")
		(net "M_H_CPU0_SB_CA<1>")
	)
	(segment
		(start 395.799056 -248.28373)
		(end 393.570968 -248.28373)
		(width 0.18288)
		(layer "In11.Cu")
		(net "M_H_CPU0_SB_CA<1>")
	)
	(segment
		(start 385.36499 -249.684794)
		(end 384.90017 -249.219974)
		(width 0.088646)
		(layer "In11.Cu")
		(net "M_H_CPU0_SB_CA<1>")
	)
	(segment
		(start 383.855722 -249.460258)
		(end 383.24536 -249.460258)
		(width 0.088646)
		(layer "In11.Cu")
		(net "M_H_CPU0_SB_CA<1>")
	)
	(segment
		(start 373.540528 -246.364506)
		(end 373.20728 -246.364506)
		(width 0.088646)
		(layer "In11.Cu")
		(net "M_H_CPU0_SB_CA<1>")
	)
	(segment
		(start 408.51201 -251.912374)
		(end 408.077416 -252.346968)
		(width 0.18288)
		(layer "In11.Cu")
		(net "M_H_CPU0_SB_CA<1>")
	)
	(segment
		(start 384.096006 -249.219974)
		(end 383.855722 -249.460258)
		(width 0.088646)
		(layer "In11.Cu")
		(net "M_H_CPU0_SB_CA<1>")
	)
	(segment
		(start 383.24536 -249.460258)
		(end 383.00533 -249.220228)
		(width 0.088646)
		(layer "In11.Cu")
		(net "M_H_CPU0_SB_CA<1>")
	)
	(segment
		(start 386.868416 -250.320556)
		(end 386.232654 -249.684794)
		(width 0.18288)
		(layer "In11.Cu")
		(net "M_H_CPU0_SB_CA<1>")
	)
	(arc
		(start 373.950992 -246.683784)
		(mid 373.87089 -246.617702)
		(end 373.812054 -246.532146)
		(width 0.088646)
		(layer "In11.Cu")
		(net "M_H_CPU0_SB_CA<1>")
	)
	(arc
		(start 380.999746 -249.125486)
		(mid 380.868832 -248.989126)
		(end 380.821184 -248.806208)
		(width 0.088646)
		(layer "In11.Cu")
		(net "M_H_CPU0_SB_CA<1>")
	)
	(arc
		(start 375.82475 -248.30786)
		(mid 375.548309 -248.240694)
		(end 375.274078 -248.316496)
		(width 0.088646)
		(layer "In11.Cu")
		(net "M_H_CPU0_SB_CA<1>")
	)
	(arc
		(start 377.719082 -248.316496)
		(mid 377.43638 -248.240754)
		(end 377.153678 -248.316496)
		(width 0.088646)
		(layer "In11.Cu")
		(net "M_H_CPU0_SB_CA<1>")
	)
	(arc
		(start 379.033532 -248.316496)
		(mid 378.846334 -248.366639)
		(end 378.659136 -248.316496)
		(width 0.088646)
		(layer "In11.Cu")
		(net "M_H_CPU0_SB_CA<1>")
	)
	(arc
		(start 383.00533 -249.220228)
		(mid 382.949725 -249.171554)
		(end 382.888236 -249.130566)
		(width 0.088646)
		(layer "In11.Cu")
		(net "M_H_CPU0_SB_CA<1>")
	)
	(arc
		(start 376.76455 -248.30786)
		(mid 376.488109 -248.240694)
		(end 376.213878 -248.316496)
		(width 0.088646)
		(layer "In11.Cu")
		(net "M_H_CPU0_SB_CA<1>")
	)
	(arc
		(start 374.899682 -248.316496)
		(mid 374.764749 -248.183142)
		(end 374.712484 -248.000774)
		(width 0.088646)
		(layer "In11.Cu")
		(net "M_H_CPU0_SB_CA<1>")
	)
	(arc
		(start 380.821184 -248.787666)
		(mid 380.741022 -248.515477)
		(end 380.538736 -248.316496)
		(width 0.088646)
		(layer "In11.Cu")
		(net "M_H_CPU0_SB_CA<1>")
	)
	(arc
		(start 376.213878 -248.316496)
		(mid 376.02668 -248.366639)
		(end 375.839482 -248.316496)
		(width 0.088646)
		(layer "In11.Cu")
		(net "M_H_CPU0_SB_CA<1>")
	)
	(arc
		(start 374.712484 -247.992138)
		(mid 374.638493 -247.712572)
		(end 374.435878 -247.506236)
		(width 0.088646)
		(layer "In11.Cu")
		(net "M_H_CPU0_SB_CA<1>")
	)
	(arc
		(start 377.153678 -248.316496)
		(mid 376.96648 -248.366639)
		(end 376.779282 -248.316496)
		(width 0.088646)
		(layer "In11.Cu")
		(net "M_H_CPU0_SB_CA<1>")
	)
	(arc
		(start 378.648722 -248.3104)
		(mid 378.37029 -248.240586)
		(end 378.093478 -248.316496)
		(width 0.088646)
		(layer "In11.Cu")
		(net "M_H_CPU0_SB_CA<1>")
	)
	(arc
		(start 374.242584 -247.178322)
		(mid 374.168593 -246.898756)
		(end 373.965978 -246.69242)
		(width 0.088646)
		(layer "In11.Cu")
		(net "M_H_CPU0_SB_CA<1>")
	)
	(arc
		(start 379.973078 -248.316496)
		(mid 379.78588 -248.366639)
		(end 379.598682 -248.316496)
		(width 0.088646)
		(layer "In11.Cu")
		(net "M_H_CPU0_SB_CA<1>")
	)
	(arc
		(start 381.948436 -249.130566)
		(mid 381.665734 -249.05479)
		(end 381.383032 -249.130566)
		(width 0.088646)
		(layer "In11.Cu")
		(net "M_H_CPU0_SB_CA<1>")
	)
	(arc
		(start 382.888236 -249.130566)
		(mid 382.605534 -249.05479)
		(end 382.322832 -249.130566)
		(width 0.088646)
		(layer "In11.Cu")
		(net "M_H_CPU0_SB_CA<1>")
	)
	(arc
		(start 375.274078 -248.316496)
		(mid 375.08688 -248.366639)
		(end 374.899682 -248.316496)
		(width 0.088646)
		(layer "In11.Cu")
		(net "M_H_CPU0_SB_CA<1>")
	)
	(arc
		(start 373.812054 -246.532146)
		(mid 373.700087 -246.409818)
		(end 373.540528 -246.364506)
		(width 0.088646)
		(layer "In11.Cu")
		(net "M_H_CPU0_SB_CA<1>")
	)
	(arc
		(start 379.588268 -248.3104)
		(mid 379.31009 -248.240708)
		(end 379.033532 -248.316496)
		(width 0.088646)
		(layer "In11.Cu")
		(net "M_H_CPU0_SB_CA<1>")
	)
	(arc
		(start 381.383032 -249.130566)
		(mid 381.195834 -249.180709)
		(end 381.008636 -249.130566)
		(width 0.088646)
		(layer "In11.Cu")
		(net "M_H_CPU0_SB_CA<1>")
	)
	(arc
		(start 382.322832 -249.130566)
		(mid 382.135634 -249.180709)
		(end 381.948436 -249.130566)
		(width 0.088646)
		(layer "In11.Cu")
		(net "M_H_CPU0_SB_CA<1>")
	)
	(arc
		(start 374.429782 -247.50268)
		(mid 374.294849 -247.369326)
		(end 374.242584 -247.186958)
		(width 0.088646)
		(layer "In11.Cu")
		(net "M_H_CPU0_SB_CA<1>")
	)
	(arc
		(start 378.093478 -248.316496)
		(mid 377.90628 -248.366639)
		(end 377.719082 -248.316496)
		(width 0.088646)
		(layer "In11.Cu")
		(net "M_H_CPU0_SB_CA<1>")
	)
	(arc
		(start 380.528322 -248.3104)
		(mid 380.24989 -248.240586)
		(end 379.973078 -248.316496)
		(width 0.088646)
		(layer "In11.Cu")
		(net "M_H_CPU0_SB_CA<1>")
	)
	(segment
		(start 452.016114 -252.566678)
		(end 453.238362 -252.566678)
		(width 0.20066)
		(layer "F.Cu")
		(net "M_H_CPU0_SB_CA<0>")
	)
	(segment
		(start 454.089008 -252.262132)
		(end 455.006456 -253.17958)
		(width 0.20066)
		(layer "F.Cu")
		(net "M_H_CPU0_SB_CA<0>")
	)
	(segment
		(start 372.73738 -246.08663)
		(end 372.737634 -246.086376)
		(width 0.20066)
		(layer "F.Cu")
		(net "M_H_CPU0_SB_CA<0>")
	)
	(segment
		(start 372.737634 -246.086376)
		(end 372.737634 -245.55069)
		(width 0.20066)
		(layer "F.Cu")
		(net "M_H_CPU0_SB_CA<0>")
	)
	(segment
		(start 458.458824 -252.566678)
		(end 459.559914 -252.566678)
		(width 0.20066)
		(layer "F.Cu")
		(net "M_H_CPU0_SB_CA<0>")
	)
	(segment
		(start 457.845922 -253.17958)
		(end 458.458824 -252.566678)
		(width 0.20066)
		(layer "F.Cu")
		(net "M_H_CPU0_SB_CA<0>")
	)
	(segment
		(start 450.911214 -252.566678)
		(end 452.016114 -252.566678)
		(width 0.20066)
		(layer "F.Cu")
		(net "M_H_CPU0_SB_CA<0>")
	)
	(segment
		(start 453.238362 -252.566678)
		(end 453.542908 -252.262132)
		(width 0.20066)
		(layer "F.Cu")
		(net "M_H_CPU0_SB_CA<0>")
	)
	(segment
		(start 453.542908 -252.262132)
		(end 454.089008 -252.262132)
		(width 0.20066)
		(layer "F.Cu")
		(net "M_H_CPU0_SB_CA<0>")
	)
	(segment
		(start 455.006456 -253.17958)
		(end 457.845922 -253.17958)
		(width 0.20066)
		(layer "F.Cu")
		(net "M_H_CPU0_SB_CA<0>")
	)
	(segment
		(start 374.05183 -247.178322)
		(end 374.05183 -247.169686)
		(width 0.088646)
		(layer "In11.Cu")
		(net "M_H_CPU0_SB_CA<0>")
	)
	(segment
		(start 450.333618 -255.541526)
		(end 450.03466 -255.242568)
		(width 0.18288)
		(layer "In11.Cu")
		(net "M_H_CPU0_SB_CA<0>")
	)
	(segment
		(start 450.03466 -255.242568)
		(end 421.550338 -255.242568)
		(width 0.18288)
		(layer "In11.Cu")
		(net "M_H_CPU0_SB_CA<0>")
	)
	(segment
		(start 398.340072 -251.5616)
		(end 395.407642 -248.62917)
		(width 0.18288)
		(layer "In11.Cu")
		(net "M_H_CPU0_SB_CA<0>")
	)
	(segment
		(start 405.09063 -253.065026)
		(end 401.46097 -251.5616)
		(width 0.18288)
		(layer "In11.Cu")
		(net "M_H_CPU0_SB_CA<0>")
	)
	(segment
		(start 380.630684 -248.816114)
		(end 380.630684 -248.806208)
		(width 0.088646)
		(layer "In11.Cu")
		(net "M_H_CPU0_SB_CA<0>")
	)
	(segment
		(start 374.52173 -248.006362)
		(end 374.52173 -247.983502)
		(width 0.088646)
		(layer "In11.Cu")
		(net "M_H_CPU0_SB_CA<0>")
	)
	(segment
		(start 414.975548 -253.090172)
		(end 414.78073 -253.28499)
		(width 0.18288)
		(layer "In11.Cu")
		(net "M_H_CPU0_SB_CA<0>")
	)
	(segment
		(start 401.46097 -251.5616)
		(end 398.340072 -251.5616)
		(width 0.18288)
		(layer "In11.Cu")
		(net "M_H_CPU0_SB_CA<0>")
	)
	(segment
		(start 385.044188 -250.015248)
		(end 383.53111 -250.015248)
		(width 0.088646)
		(layer "In11.Cu")
		(net "M_H_CPU0_SB_CA<0>")
	)
	(segment
		(start 383.53111 -250.015248)
		(end 382.87071 -249.354848)
		(width 0.088646)
		(layer "In11.Cu")
		(net "M_H_CPU0_SB_CA<0>")
	)
	(segment
		(start 410.750512 -253.065026)
		(end 405.09063 -253.065026)
		(width 0.18288)
		(layer "In11.Cu")
		(net "M_H_CPU0_SB_CA<0>")
	)
	(segment
		(start 395.407642 -248.62917)
		(end 393.60602 -248.62917)
		(width 0.18288)
		(layer "In11.Cu")
		(net "M_H_CPU0_SB_CA<0>")
	)
	(segment
		(start 393.60602 -248.62917)
		(end 392.73353 -248.802652)
		(width 0.18288)
		(layer "In11.Cu")
		(net "M_H_CPU0_SB_CA<0>")
	)
	(segment
		(start 374.334532 -247.66778)
		(end 374.328436 -247.664224)
		(width 0.088646)
		(layer "In11.Cu")
		(net "M_H_CPU0_SB_CA<0>")
	)
	(segment
		(start 375.758964 -248.490486)
		(end 375.744232 -248.48185)
		(width 0.088646)
		(layer "In11.Cu")
		(net "M_H_CPU0_SB_CA<0>")
	)
	(segment
		(start 388.190994 -250.684284)
		(end 385.713224 -250.684284)
		(width 0.18288)
		(layer "In11.Cu")
		(net "M_H_CPU0_SB_CA<0>")
	)
	(segment
		(start 410.970476 -253.28499)
		(end 410.750512 -253.065026)
		(width 0.18288)
		(layer "In11.Cu")
		(net "M_H_CPU0_SB_CA<0>")
	)
	(segment
		(start 414.78073 -253.28499)
		(end 410.970476 -253.28499)
		(width 0.18288)
		(layer "In11.Cu")
		(net "M_H_CPU0_SB_CA<0>")
	)
	(segment
		(start 376.694446 -248.487946)
		(end 376.684032 -248.48185)
		(width 0.088646)
		(layer "In11.Cu")
		(net "M_H_CPU0_SB_CA<0>")
	)
	(segment
		(start 372.737634 -246.422672)
		(end 372.737634 -245.55069)
		(width 0.088646)
		(layer "In11.Cu")
		(net "M_H_CPU0_SB_CA<0>")
	)
	(segment
		(start 392.73353 -248.802652)
		(end 388.190994 -250.684284)
		(width 0.18288)
		(layer "In11.Cu")
		(net "M_H_CPU0_SB_CA<0>")
	)
	(segment
		(start 385.234434 -250.205494)
		(end 385.044188 -250.015248)
		(width 0.088646)
		(layer "In11.Cu")
		(net "M_H_CPU0_SB_CA<0>")
	)
	(segment
		(start 380.452122 -248.48693)
		(end 380.443232 -248.48185)
		(width 0.088646)
		(layer "In11.Cu")
		(net "M_H_CPU0_SB_CA<0>")
	)
	(segment
		(start 450.911214 -252.566678)
		(end 450.911214 -255.311656)
		(width 0.18288)
		(layer "In11.Cu")
		(net "M_H_CPU0_SB_CA<0>")
	)
	(segment
		(start 450.681344 -255.541526)
		(end 450.333618 -255.541526)
		(width 0.18288)
		(layer "In11.Cu")
		(net "M_H_CPU0_SB_CA<0>")
	)
	(segment
		(start 450.911214 -255.311656)
		(end 450.681344 -255.541526)
		(width 0.18288)
		(layer "In11.Cu")
		(net "M_H_CPU0_SB_CA<0>")
	)
	(segment
		(start 374.819164 -248.490486)
		(end 374.804432 -248.48185)
		(width 0.088646)
		(layer "In11.Cu")
		(net "M_H_CPU0_SB_CA<0>")
	)
	(segment
		(start 377.633992 -248.487946)
		(end 377.623578 -248.48185)
		(width 0.088646)
		(layer "In11.Cu")
		(net "M_H_CPU0_SB_CA<0>")
	)
	(segment
		(start 385.713224 -250.684284)
		(end 385.234434 -250.205494)
		(width 0.18288)
		(layer "In11.Cu")
		(net "M_H_CPU0_SB_CA<0>")
	)
	(segment
		(start 421.550338 -255.242568)
		(end 419.397942 -253.090172)
		(width 0.18288)
		(layer "In11.Cu")
		(net "M_H_CPU0_SB_CA<0>")
	)
	(segment
		(start 419.397942 -253.090172)
		(end 414.975548 -253.090172)
		(width 0.18288)
		(layer "In11.Cu")
		(net "M_H_CPU0_SB_CA<0>")
	)
	(segment
		(start 379.518164 -248.490486)
		(end 379.503432 -248.48185)
		(width 0.088646)
		(layer "In11.Cu")
		(net "M_H_CPU0_SB_CA<0>")
	)
	(arc
		(start 380.443232 -248.48185)
		(mid 380.256034 -248.431707)
		(end 380.068836 -248.48185)
		(width 0.088646)
		(layer "In11.Cu")
		(net "M_H_CPU0_SB_CA<0>")
	)
	(arc
		(start 374.804432 -248.48185)
		(mid 374.600951 -248.281046)
		(end 374.52173 -248.006362)
		(width 0.088646)
		(layer "In11.Cu")
		(net "M_H_CPU0_SB_CA<0>")
	)
	(arc
		(start 373.850154 -246.84609)
		(mid 373.668454 -246.803983)
		(end 373.488966 -246.854726)
		(width 0.088646)
		(layer "In11.Cu")
		(net "M_H_CPU0_SB_CA<0>")
	)
	(arc
		(start 380.068836 -248.48185)
		(mid 379.794607 -248.557775)
		(end 379.518164 -248.490486)
		(width 0.088646)
		(layer "In11.Cu")
		(net "M_H_CPU0_SB_CA<0>")
	)
	(arc
		(start 380.630684 -248.806208)
		(mid 380.583005 -248.623308)
		(end 380.452122 -248.48693)
		(width 0.088646)
		(layer "In11.Cu")
		(net "M_H_CPU0_SB_CA<0>")
	)
	(arc
		(start 374.05183 -247.169686)
		(mid 373.99956 -246.987321)
		(end 373.864632 -246.853964)
		(width 0.088646)
		(layer "In11.Cu")
		(net "M_H_CPU0_SB_CA<0>")
	)
	(arc
		(start 381.478536 -249.295666)
		(mid 381.195834 -249.371442)
		(end 380.913132 -249.295666)
		(width 0.088646)
		(layer "In11.Cu")
		(net "M_H_CPU0_SB_CA<0>")
	)
	(arc
		(start 375.369836 -248.48185)
		(mid 375.095607 -248.557775)
		(end 374.819164 -248.490486)
		(width 0.088646)
		(layer "In11.Cu")
		(net "M_H_CPU0_SB_CA<0>")
	)
	(arc
		(start 373.864632 -246.853964)
		(mid 373.85745 -246.849922)
		(end 373.850154 -246.84609)
		(width 0.088646)
		(layer "In11.Cu")
		(net "M_H_CPU0_SB_CA<0>")
	)
	(arc
		(start 377.623578 -248.48185)
		(mid 377.43638 -248.431707)
		(end 377.249182 -248.48185)
		(width 0.088646)
		(layer "In11.Cu")
		(net "M_H_CPU0_SB_CA<0>")
	)
	(arc
		(start 379.129036 -248.48185)
		(mid 378.846334 -248.557592)
		(end 378.563632 -248.48185)
		(width 0.088646)
		(layer "In11.Cu")
		(net "M_H_CPU0_SB_CA<0>")
	)
	(arc
		(start 376.684032 -248.48185)
		(mid 376.496834 -248.431707)
		(end 376.309636 -248.48185)
		(width 0.088646)
		(layer "In11.Cu")
		(net "M_H_CPU0_SB_CA<0>")
	)
	(arc
		(start 382.792732 -249.295666)
		(mid 382.605534 -249.245523)
		(end 382.418336 -249.295666)
		(width 0.088646)
		(layer "In11.Cu")
		(net "M_H_CPU0_SB_CA<0>")
	)
	(arc
		(start 373.488966 -246.854726)
		(mid 372.988365 -246.856068)
		(end 372.737634 -246.422672)
		(width 0.088646)
		(layer "In11.Cu")
		(net "M_H_CPU0_SB_CA<0>")
	)
	(arc
		(start 378.189236 -248.48185)
		(mid 377.912423 -248.557686)
		(end 377.633992 -248.487946)
		(width 0.088646)
		(layer "In11.Cu")
		(net "M_H_CPU0_SB_CA<0>")
	)
	(arc
		(start 375.744232 -248.48185)
		(mid 375.557034 -248.431707)
		(end 375.369836 -248.48185)
		(width 0.088646)
		(layer "In11.Cu")
		(net "M_H_CPU0_SB_CA<0>")
	)
	(arc
		(start 378.563632 -248.48185)
		(mid 378.376434 -248.431707)
		(end 378.189236 -248.48185)
		(width 0.088646)
		(layer "In11.Cu")
		(net "M_H_CPU0_SB_CA<0>")
	)
	(arc
		(start 374.52173 -247.983502)
		(mid 374.46946 -247.801137)
		(end 374.334532 -247.66778)
		(width 0.088646)
		(layer "In11.Cu")
		(net "M_H_CPU0_SB_CA<0>")
	)
	(arc
		(start 381.852932 -249.295666)
		(mid 381.665734 -249.245523)
		(end 381.478536 -249.295666)
		(width 0.088646)
		(layer "In11.Cu")
		(net "M_H_CPU0_SB_CA<0>")
	)
	(arc
		(start 382.418336 -249.295666)
		(mid 382.135634 -249.371442)
		(end 381.852932 -249.295666)
		(width 0.088646)
		(layer "In11.Cu")
		(net "M_H_CPU0_SB_CA<0>")
	)
	(arc
		(start 376.309636 -248.48185)
		(mid 376.035407 -248.557775)
		(end 375.758964 -248.490486)
		(width 0.088646)
		(layer "In11.Cu")
		(net "M_H_CPU0_SB_CA<0>")
	)
	(arc
		(start 377.249182 -248.48185)
		(mid 376.972623 -248.557559)
		(end 376.694446 -248.487946)
		(width 0.088646)
		(layer "In11.Cu")
		(net "M_H_CPU0_SB_CA<0>")
	)
	(arc
		(start 380.913132 -249.295666)
		(mid 380.708797 -249.093061)
		(end 380.630684 -248.816114)
		(width 0.088646)
		(layer "In11.Cu")
		(net "M_H_CPU0_SB_CA<0>")
	)
	(arc
		(start 382.87071 -249.354848)
		(mid 382.83366 -249.322702)
		(end 382.792732 -249.295666)
		(width 0.088646)
		(layer "In11.Cu")
		(net "M_H_CPU0_SB_CA<0>")
	)
	(arc
		(start 379.503432 -248.48185)
		(mid 379.316234 -248.431707)
		(end 379.129036 -248.48185)
		(width 0.088646)
		(layer "In11.Cu")
		(net "M_H_CPU0_SB_CA<0>")
	)
	(arc
		(start 374.328436 -247.664224)
		(mid 374.125849 -247.457873)
		(end 374.05183 -247.178322)
		(width 0.088646)
		(layer "In11.Cu")
		(net "M_H_CPU0_SB_CA<0>")
	)
	(segment
		(start 383.185162 -253.383796)
		(end 383.185162 -253.919736)
		(width 0.20066)
		(layer "F.Cu")
		(net "M_H_CPU0_SA_RSP<1>")
	)
	(segment
		(start 452.016114 -244.066568)
		(end 450.911214 -244.066568)
		(width 0.20066)
		(layer "F.Cu")
		(net "M_H_CPU0_SA_RSP<1>")
	)
	(segment
		(start 434.555646 -252.076712)
		(end 434.297074 -252.076712)
		(width 0.18288)
		(layer "In6.Cu")
		(net "M_H_CPU0_SA_RSP<1>")
	)
	(segment
		(start 392.298936 -256.323338)
		(end 390.757918 -255.685036)
		(width 0.18288)
		(layer "In6.Cu")
		(net "M_H_CPU0_SA_RSP<1>")
	)
	(segment
		(start 387.212332 -254.981964)
		(end 386.944616 -254.981964)
		(width 0.088646)
		(layer "In6.Cu")
		(net "M_H_CPU0_SA_RSP<1>")
	)
	(segment
		(start 450.911214 -244.066568)
		(end 450.622924 -243.947188)
		(width 0.18288)
		(layer "In6.Cu")
		(net "M_H_CPU0_SA_RSP<1>")
	)
	(segment
		(start 383.467864 -255.05791)
		(end 383.458974 -255.05283)
		(width 0.088646)
		(layer "In6.Cu")
		(net "M_H_CPU0_SA_RSP<1>")
	)
	(segment
		(start 433.574698 -253.05766)
		(end 433.316126 -253.05766)
		(width 0.18288)
		(layer "In6.Cu")
		(net "M_H_CPU0_SA_RSP<1>")
	)
	(segment
		(start 434.894228 -254.118618)
		(end 434.635656 -254.118618)
		(width 0.18288)
		(layer "In6.Cu")
		(net "M_H_CPU0_SA_RSP<1>")
	)
	(segment
		(start 433.084224 -253.289562)
		(end 433.084224 -253.548134)
		(width 0.18288)
		(layer "In6.Cu")
		(net "M_H_CPU0_SA_RSP<1>")
	)
	(segment
		(start 448.255898 -246.150892)
		(end 443.720474 -248.602246)
		(width 0.18288)
		(layer "In6.Cu")
		(net "M_H_CPU0_SA_RSP<1>")
	)
	(segment
		(start 387.6167 -254.577596)
		(end 387.212332 -254.981964)
		(width 0.088646)
		(layer "In6.Cu")
		(net "M_H_CPU0_SA_RSP<1>")
	)
	(segment
		(start 389.650478 -254.577596)
		(end 387.875018 -254.577596)
		(width 0.18288)
		(layer "In6.Cu")
		(net "M_H_CPU0_SA_RSP<1>")
	)
	(segment
		(start 390.757918 -255.685036)
		(end 389.650478 -254.577596)
		(width 0.18288)
		(layer "In6.Cu")
		(net "M_H_CPU0_SA_RSP<1>")
	)
	(segment
		(start 434.297074 -252.076712)
		(end 434.065172 -252.308614)
		(width 0.18288)
		(layer "In6.Cu")
		(net "M_H_CPU0_SA_RSP<1>")
	)
	(segment
		(start 450.622924 -243.947188)
		(end 450.459602 -243.947188)
		(width 0.18288)
		(layer "In6.Cu")
		(net "M_H_CPU0_SA_RSP<1>")
	)
	(segment
		(start 412.844742 -255.381506)
		(end 412.844742 -255.381252)
		(width 0.18288)
		(layer "In6.Cu")
		(net "M_H_CPU0_SA_RSP<1>")
	)
	(segment
		(start 434.145182 -254.867664)
		(end 433.63134 -255.381506)
		(width 0.18288)
		(layer "In6.Cu")
		(net "M_H_CPU0_SA_RSP<1>")
	)
	(segment
		(start 433.084224 -253.548134)
		(end 434.145182 -254.609092)
		(width 0.18288)
		(layer "In6.Cu")
		(net "M_H_CPU0_SA_RSP<1>")
	)
	(segment
		(start 385.347464 -255.05791)
		(end 385.332732 -255.049274)
		(width 0.088646)
		(layer "In6.Cu")
		(net "M_H_CPU0_SA_RSP<1>")
	)
	(segment
		(start 434.065172 -252.308614)
		(end 434.065172 -252.567186)
		(width 0.18288)
		(layer "In6.Cu")
		(net "M_H_CPU0_SA_RSP<1>")
	)
	(segment
		(start 412.844742 -255.381252)
		(end 397.835628 -255.381252)
		(width 0.18288)
		(layer "In6.Cu")
		(net "M_H_CPU0_SA_RSP<1>")
	)
	(segment
		(start 393.681712 -256.59842)
		(end 392.298936 -256.323338)
		(width 0.18288)
		(layer "In6.Cu")
		(net "M_H_CPU0_SA_RSP<1>")
	)
	(segment
		(start 383.280412 -254.733552)
		(end 383.280412 -254.331216)
		(width 0.088646)
		(layer "In6.Cu")
		(net "M_H_CPU0_SA_RSP<1>")
	)
	(segment
		(start 383.280412 -254.331216)
		(end 383.185162 -254.235966)
		(width 0.088646)
		(layer "In6.Cu")
		(net "M_H_CPU0_SA_RSP<1>")
	)
	(segment
		(start 383.185162 -254.235966)
		(end 383.185162 -253.919736)
		(width 0.088646)
		(layer "In6.Cu")
		(net "M_H_CPU0_SA_RSP<1>")
	)
	(segment
		(start 435.616604 -253.13767)
		(end 434.555646 -252.076712)
		(width 0.18288)
		(layer "In6.Cu")
		(net "M_H_CPU0_SA_RSP<1>")
	)
	(segment
		(start 441.880244 -250.442476)
		(end 438.57037 -250.442476)
		(width 0.18288)
		(layer "In6.Cu")
		(net "M_H_CPU0_SA_RSP<1>")
	)
	(segment
		(start 450.459602 -243.947188)
		(end 448.255898 -246.150892)
		(width 0.18288)
		(layer "In6.Cu")
		(net "M_H_CPU0_SA_RSP<1>")
	)
	(segment
		(start 387.875018 -254.577596)
		(end 387.6167 -254.577596)
		(width 0.088646)
		(layer "In6.Cu")
		(net "M_H_CPU0_SA_RSP<1>")
	)
	(segment
		(start 438.57037 -250.442476)
		(end 435.875176 -253.13767)
		(width 0.18288)
		(layer "In6.Cu")
		(net "M_H_CPU0_SA_RSP<1>")
	)
	(segment
		(start 396.61846 -256.59842)
		(end 393.681712 -256.59842)
		(width 0.18288)
		(layer "In6.Cu")
		(net "M_H_CPU0_SA_RSP<1>")
	)
	(segment
		(start 435.12613 -253.886716)
		(end 434.894228 -254.118618)
		(width 0.18288)
		(layer "In6.Cu")
		(net "M_H_CPU0_SA_RSP<1>")
	)
	(segment
		(start 397.835628 -255.381252)
		(end 396.61846 -256.59842)
		(width 0.18288)
		(layer "In6.Cu")
		(net "M_H_CPU0_SA_RSP<1>")
	)
	(segment
		(start 443.720474 -248.602246)
		(end 441.880244 -250.442476)
		(width 0.18288)
		(layer "In6.Cu")
		(net "M_H_CPU0_SA_RSP<1>")
	)
	(segment
		(start 433.63134 -255.381506)
		(end 412.844742 -255.381506)
		(width 0.18288)
		(layer "In6.Cu")
		(net "M_H_CPU0_SA_RSP<1>")
	)
	(segment
		(start 434.145182 -254.609092)
		(end 434.145182 -254.867664)
		(width 0.18288)
		(layer "In6.Cu")
		(net "M_H_CPU0_SA_RSP<1>")
	)
	(segment
		(start 435.12613 -253.628144)
		(end 435.12613 -253.886716)
		(width 0.18288)
		(layer "In6.Cu")
		(net "M_H_CPU0_SA_RSP<1>")
	)
	(segment
		(start 433.316126 -253.05766)
		(end 433.084224 -253.289562)
		(width 0.18288)
		(layer "In6.Cu")
		(net "M_H_CPU0_SA_RSP<1>")
	)
	(segment
		(start 386.287264 -255.05791)
		(end 386.272532 -255.049274)
		(width 0.088646)
		(layer "In6.Cu")
		(net "M_H_CPU0_SA_RSP<1>")
	)
	(segment
		(start 434.065172 -252.567186)
		(end 435.12613 -253.628144)
		(width 0.18288)
		(layer "In6.Cu")
		(net "M_H_CPU0_SA_RSP<1>")
	)
	(segment
		(start 434.635656 -254.118618)
		(end 433.574698 -253.05766)
		(width 0.18288)
		(layer "In6.Cu")
		(net "M_H_CPU0_SA_RSP<1>")
	)
	(segment
		(start 435.875176 -253.13767)
		(end 435.616604 -253.13767)
		(width 0.18288)
		(layer "In6.Cu")
		(net "M_H_CPU0_SA_RSP<1>")
	)
	(arc
		(start 384.407664 -255.05791)
		(mid 384.124962 -254.982168)
		(end 383.84226 -255.05791)
		(width 0.088646)
		(layer "In6.Cu")
		(net "M_H_CPU0_SA_RSP<1>")
	)
	(arc
		(start 385.72186 -255.05791)
		(mid 385.534662 -255.108053)
		(end 385.347464 -255.05791)
		(width 0.088646)
		(layer "In6.Cu")
		(net "M_H_CPU0_SA_RSP<1>")
	)
	(arc
		(start 386.944616 -254.981964)
		(mid 386.798129 -255.001279)
		(end 386.66166 -255.05791)
		(width 0.088646)
		(layer "In6.Cu")
		(net "M_H_CPU0_SA_RSP<1>")
	)
	(arc
		(start 386.66166 -255.05791)
		(mid 386.474462 -255.108053)
		(end 386.287264 -255.05791)
		(width 0.088646)
		(layer "In6.Cu")
		(net "M_H_CPU0_SA_RSP<1>")
	)
	(arc
		(start 385.332732 -255.049274)
		(mid 385.056257 -254.981954)
		(end 384.78206 -255.05791)
		(width 0.088646)
		(layer "In6.Cu")
		(net "M_H_CPU0_SA_RSP<1>")
	)
	(arc
		(start 383.458974 -255.05283)
		(mid 383.32806 -254.91647)
		(end 383.280412 -254.733552)
		(width 0.088646)
		(layer "In6.Cu")
		(net "M_H_CPU0_SA_RSP<1>")
	)
	(arc
		(start 383.84226 -255.05791)
		(mid 383.655062 -255.108053)
		(end 383.467864 -255.05791)
		(width 0.088646)
		(layer "In6.Cu")
		(net "M_H_CPU0_SA_RSP<1>")
	)
	(arc
		(start 386.272532 -255.049274)
		(mid 385.996057 -254.981954)
		(end 385.72186 -255.05791)
		(width 0.088646)
		(layer "In6.Cu")
		(net "M_H_CPU0_SA_RSP<1>")
	)
	(arc
		(start 384.78206 -255.05791)
		(mid 384.594862 -255.108053)
		(end 384.407664 -255.05791)
		(width 0.088646)
		(layer "In6.Cu")
		(net "M_H_CPU0_SA_RSP<1>")
	)
	(segment
		(start 382.715516 -254.197612)
		(end 382.715516 -254.733298)
		(width 0.20066)
		(layer "F.Cu")
		(net "M_H_CPU0_SA_RSP<0>")
	)
	(segment
		(start 459.559914 -244.066568)
		(end 458.455014 -244.066568)
		(width 0.20066)
		(layer "F.Cu")
		(net "M_H_CPU0_SA_RSP<0>")
	)
	(segment
		(start 382.715516 -254.733298)
		(end 382.715262 -254.733552)
		(width 0.20066)
		(layer "F.Cu")
		(net "M_H_CPU0_SA_RSP<0>")
	)
	(segment
		(start 458.455014 -244.066568)
		(end 458.429614 -244.066568)
		(width 0.18288)
		(layer "In6.Cu")
		(net "M_H_CPU0_SA_RSP<0>")
	)
	(segment
		(start 384.329432 -255.86182)
		(end 384.31216 -255.87198)
		(width 0.088646)
		(layer "In6.Cu")
		(net "M_H_CPU0_SA_RSP<0>")
	)
	(segment
		(start 385.266946 -255.86309)
		(end 385.252214 -255.871726)
		(width 0.088646)
		(layer "In6.Cu")
		(net "M_H_CPU0_SA_RSP<0>")
	)
	(segment
		(start 446.254632 -250.044966)
		(end 439.90768 -256.391918)
		(width 0.18288)
		(layer "In6.Cu")
		(net "M_H_CPU0_SA_RSP<0>")
	)
	(segment
		(start 386.206746 -255.86309)
		(end 386.180076 -255.878584)
		(width 0.088646)
		(layer "In6.Cu")
		(net "M_H_CPU0_SA_RSP<0>")
	)
	(segment
		(start 447.287142 -250.044966)
		(end 446.254632 -250.044966)
		(width 0.18288)
		(layer "In6.Cu")
		(net "M_H_CPU0_SA_RSP<0>")
	)
	(segment
		(start 437.709056 -255.236472)
		(end 437.526176 -255.419352)
		(width 0.18288)
		(layer "In6.Cu")
		(net "M_H_CPU0_SA_RSP<0>")
	)
	(segment
		(start 437.343296 -256.391664)
		(end 399.296128 -256.391664)
		(width 0.18288)
		(layer "In6.Cu")
		(net "M_H_CPU0_SA_RSP<0>")
	)
	(segment
		(start 439.62193 -256.391664)
		(end 438.402476 -256.391664)
		(width 0.18288)
		(layer "In6.Cu")
		(net "M_H_CPU0_SA_RSP<0>")
	)
	(segment
		(start 389.489696 -256.266696)
		(end 388.8994 -255.6764)
		(width 0.18288)
		(layer "In6.Cu")
		(net "M_H_CPU0_SA_RSP<0>")
	)
	(segment
		(start 393.587986 -257.595116)
		(end 391.873232 -257.253994)
		(width 0.18288)
		(layer "In6.Cu")
		(net "M_H_CPU0_SA_RSP<0>")
	)
	(segment
		(start 438.219596 -255.419352)
		(end 438.036716 -255.236472)
		(width 0.18288)
		(layer "In6.Cu")
		(net "M_H_CPU0_SA_RSP<0>")
	)
	(segment
		(start 382.345184 -254.790702)
		(end 382.402334 -254.733552)
		(width 0.088646)
		(layer "In6.Cu")
		(net "M_H_CPU0_SA_RSP<0>")
	)
	(segment
		(start 439.622184 -256.391918)
		(end 439.62193 -256.391664)
		(width 0.18288)
		(layer "In6.Cu")
		(net "M_H_CPU0_SA_RSP<0>")
	)
	(segment
		(start 437.526176 -256.208784)
		(end 437.343296 -256.391664)
		(width 0.18288)
		(layer "In6.Cu")
		(net "M_H_CPU0_SA_RSP<0>")
	)
	(segment
		(start 382.810766 -255.556258)
		(end 382.810766 -255.533398)
		(width 0.088646)
		(layer "In6.Cu")
		(net "M_H_CPU0_SA_RSP<0>")
	)
	(segment
		(start 455.85761 -244.772942)
		(end 455.85761 -246.533416)
		(width 0.18288)
		(layer "In6.Cu")
		(net "M_H_CPU0_SA_RSP<0>")
	)
	(segment
		(start 455.348594 -247.042432)
		(end 452.875396 -247.042432)
		(width 0.18288)
		(layer "In6.Cu")
		(net "M_H_CPU0_SA_RSP<0>")
	)
	(segment
		(start 437.526176 -255.419352)
		(end 437.526176 -256.208784)
		(width 0.18288)
		(layer "In6.Cu")
		(net "M_H_CPU0_SA_RSP<0>")
	)
	(segment
		(start 391.873232 -257.253994)
		(end 389.489696 -256.266696)
		(width 0.18288)
		(layer "In6.Cu")
		(net "M_H_CPU0_SA_RSP<0>")
	)
	(segment
		(start 438.402476 -256.391664)
		(end 438.219596 -256.208784)
		(width 0.18288)
		(layer "In6.Cu")
		(net "M_H_CPU0_SA_RSP<0>")
	)
	(segment
		(start 386.964936 -256.052066)
		(end 386.874258 -255.961388)
		(width 0.088646)
		(layer "In6.Cu")
		(net "M_H_CPU0_SA_RSP<0>")
	)
	(segment
		(start 387.151626 -256.052066)
		(end 386.964936 -256.052066)
		(width 0.088646)
		(layer "In6.Cu")
		(net "M_H_CPU0_SA_RSP<0>")
	)
	(segment
		(start 457.169266 -243.461286)
		(end 455.85761 -244.772942)
		(width 0.18288)
		(layer "In6.Cu")
		(net "M_H_CPU0_SA_RSP<0>")
	)
	(segment
		(start 439.90768 -256.391918)
		(end 439.622184 -256.391918)
		(width 0.18288)
		(layer "In6.Cu")
		(net "M_H_CPU0_SA_RSP<0>")
	)
	(segment
		(start 388.8994 -255.6764)
		(end 387.875018 -255.6764)
		(width 0.18288)
		(layer "In6.Cu")
		(net "M_H_CPU0_SA_RSP<0>")
	)
	(segment
		(start 387.527292 -255.6764)
		(end 387.151626 -256.052066)
		(width 0.088646)
		(layer "In6.Cu")
		(net "M_H_CPU0_SA_RSP<0>")
	)
	(segment
		(start 398.092676 -257.595116)
		(end 393.587986 -257.595116)
		(width 0.18288)
		(layer "In6.Cu")
		(net "M_H_CPU0_SA_RSP<0>")
	)
	(segment
		(start 452.875396 -247.042432)
		(end 451.175374 -248.742454)
		(width 0.18288)
		(layer "In6.Cu")
		(net "M_H_CPU0_SA_RSP<0>")
	)
	(segment
		(start 448.589654 -248.742454)
		(end 447.287142 -250.044966)
		(width 0.18288)
		(layer "In6.Cu")
		(net "M_H_CPU0_SA_RSP<0>")
	)
	(segment
		(start 438.219596 -256.208784)
		(end 438.219596 -255.419352)
		(width 0.18288)
		(layer "In6.Cu")
		(net "M_H_CPU0_SA_RSP<0>")
	)
	(segment
		(start 438.036716 -255.236472)
		(end 437.709056 -255.236472)
		(width 0.18288)
		(layer "In6.Cu")
		(net "M_H_CPU0_SA_RSP<0>")
	)
	(segment
		(start 399.296128 -256.391664)
		(end 398.092676 -257.595116)
		(width 0.18288)
		(layer "In6.Cu")
		(net "M_H_CPU0_SA_RSP<0>")
	)
	(segment
		(start 382.402334 -254.733552)
		(end 382.715262 -254.733552)
		(width 0.088646)
		(layer "In6.Cu")
		(net "M_H_CPU0_SA_RSP<0>")
	)
	(segment
		(start 382.528064 -255.05791)
		(end 382.519174 -255.05283)
		(width 0.088646)
		(layer "In6.Cu")
		(net "M_H_CPU0_SA_RSP<0>")
	)
	(segment
		(start 457.824332 -243.461286)
		(end 457.169266 -243.461286)
		(width 0.18288)
		(layer "In6.Cu")
		(net "M_H_CPU0_SA_RSP<0>")
	)
	(segment
		(start 458.429614 -244.066568)
		(end 457.824332 -243.461286)
		(width 0.18288)
		(layer "In6.Cu")
		(net "M_H_CPU0_SA_RSP<0>")
	)
	(segment
		(start 387.875018 -255.6764)
		(end 387.527292 -255.6764)
		(width 0.088646)
		(layer "In6.Cu")
		(net "M_H_CPU0_SA_RSP<0>")
	)
	(segment
		(start 455.85761 -246.533416)
		(end 455.348594 -247.042432)
		(width 0.18288)
		(layer "In6.Cu")
		(net "M_H_CPU0_SA_RSP<0>")
	)
	(segment
		(start 451.175374 -248.742454)
		(end 448.589654 -248.742454)
		(width 0.18288)
		(layer "In6.Cu")
		(net "M_H_CPU0_SA_RSP<0>")
	)
	(arc
		(start 382.810766 -255.533398)
		(mid 382.731547 -255.258713)
		(end 382.528064 -255.05791)
		(width 0.088646)
		(layer "In6.Cu")
		(net "M_H_CPU0_SA_RSP<0>")
	)
	(arc
		(start 385.817618 -255.871726)
		(mid 385.543389 -255.795801)
		(end 385.266946 -255.86309)
		(width 0.088646)
		(layer "In6.Cu")
		(net "M_H_CPU0_SA_RSP<0>")
	)
	(arc
		(start 382.997964 -255.87198)
		(mid 382.863031 -255.738626)
		(end 382.810766 -255.556258)
		(width 0.088646)
		(layer "In6.Cu")
		(net "M_H_CPU0_SA_RSP<0>")
	)
	(arc
		(start 384.31216 -255.87198)
		(mid 384.124962 -255.922123)
		(end 383.937764 -255.87198)
		(width 0.088646)
		(layer "In6.Cu")
		(net "M_H_CPU0_SA_RSP<0>")
	)
	(arc
		(start 386.180076 -255.878584)
		(mid 385.997965 -255.921909)
		(end 385.817618 -255.871726)
		(width 0.088646)
		(layer "In6.Cu")
		(net "M_H_CPU0_SA_RSP<0>")
	)
	(arc
		(start 383.937764 -255.87198)
		(mid 383.655062 -255.796204)
		(end 383.37236 -255.87198)
		(width 0.088646)
		(layer "In6.Cu")
		(net "M_H_CPU0_SA_RSP<0>")
	)
	(arc
		(start 382.519174 -255.05283)
		(mid 382.403365 -254.940901)
		(end 382.345184 -254.790702)
		(width 0.088646)
		(layer "In6.Cu")
		(net "M_H_CPU0_SA_RSP<0>")
	)
	(arc
		(start 383.37236 -255.87198)
		(mid 383.185162 -255.922123)
		(end 382.997964 -255.87198)
		(width 0.088646)
		(layer "In6.Cu")
		(net "M_H_CPU0_SA_RSP<0>")
	)
	(arc
		(start 386.874258 -255.961388)
		(mid 386.556775 -255.801883)
		(end 386.206746 -255.86309)
		(width 0.088646)
		(layer "In6.Cu")
		(net "M_H_CPU0_SA_RSP<0>")
	)
	(arc
		(start 385.252214 -255.871726)
		(mid 385.065016 -255.921869)
		(end 384.877818 -255.871726)
		(width 0.088646)
		(layer "In6.Cu")
		(net "M_H_CPU0_SA_RSP<0>")
	)
	(arc
		(start 384.877818 -255.871726)
		(mid 384.604896 -255.795823)
		(end 384.329432 -255.86182)
		(width 0.088646)
		(layer "In6.Cu")
		(net "M_H_CPU0_SA_RSP<0>")
	)
	(segment
		(start 452.016114 -259.366766)
		(end 452.903844 -259.366766)
		(width 0.20066)
		(layer "F.Cu")
		(net "M_H_CPU0_SA_PAR")
	)
	(segment
		(start 454.172574 -258.474464)
		(end 454.639934 -258.941824)
		(width 0.20066)
		(layer "F.Cu")
		(net "M_H_CPU0_SA_PAR")
	)
	(segment
		(start 454.918826 -258.941824)
		(end 454.939146 -258.941824)
		(width 0.101854)
		(layer "F.Cu")
		(net "M_H_CPU0_SA_PAR")
	)
	(segment
		(start 452.903844 -259.366766)
		(end 453.796146 -258.474464)
		(width 0.20066)
		(layer "F.Cu")
		(net "M_H_CPU0_SA_PAR")
	)
	(segment
		(start 371.79758 -246.08663)
		(end 371.797834 -246.086376)
		(width 0.20066)
		(layer "F.Cu")
		(net "M_H_CPU0_SA_PAR")
	)
	(segment
		(start 458.093572 -259.366766)
		(end 459.559914 -259.366766)
		(width 0.20066)
		(layer "F.Cu")
		(net "M_H_CPU0_SA_PAR")
	)
	(segment
		(start 457.126594 -258.95427)
		(end 457.681076 -258.95427)
		(width 0.20066)
		(layer "F.Cu")
		(net "M_H_CPU0_SA_PAR")
	)
	(segment
		(start 371.797834 -246.086376)
		(end 371.797834 -245.55069)
		(width 0.20066)
		(layer "F.Cu")
		(net "M_H_CPU0_SA_PAR")
	)
	(segment
		(start 453.796146 -258.474464)
		(end 454.172574 -258.474464)
		(width 0.20066)
		(layer "F.Cu")
		(net "M_H_CPU0_SA_PAR")
	)
	(segment
		(start 457.114148 -258.941824)
		(end 457.126594 -258.95427)
		(width 0.1016)
		(layer "F.Cu")
		(net "M_H_CPU0_SA_PAR")
	)
	(segment
		(start 454.639934 -258.941824)
		(end 454.918826 -258.941824)
		(width 0.20066)
		(layer "F.Cu")
		(net "M_H_CPU0_SA_PAR")
	)
	(segment
		(start 457.681076 -258.95427)
		(end 458.093572 -259.366766)
		(width 0.20066)
		(layer "F.Cu")
		(net "M_H_CPU0_SA_PAR")
	)
	(segment
		(start 450.911214 -259.366766)
		(end 452.016114 -259.366766)
		(width 0.20066)
		(layer "F.Cu")
		(net "M_H_CPU0_SA_PAR")
	)
	(segment
		(start 454.939146 -258.941824)
		(end 457.114148 -258.941824)
		(width 0.1016)
		(layer "F.Cu")
		(net "M_H_CPU0_SA_PAR")
	)
	(segment
		(start 396.475712 -253.86792)
		(end 395.445996 -254.897636)
		(width 0.18288)
		(layer "In11.Cu")
		(net "M_H_CPU0_SA_PAR")
	)
	(segment
		(start 449.19519 -258.736338)
		(end 447.5988 -258.075176)
		(width 0.18288)
		(layer "In11.Cu")
		(net "M_H_CPU0_SA_PAR")
	)
	(segment
		(start 405.039322 -256.7813)
		(end 403.108668 -254.850646)
		(width 0.18288)
		(layer "In11.Cu")
		(net "M_H_CPU0_SA_PAR")
	)
	(segment
		(start 371.045232 -246.853964)
		(end 371.059964 -246.8626)
		(width 0.088646)
		(layer "In11.Cu")
		(net "M_H_CPU0_SA_PAR")
	)
	(segment
		(start 370.95303 -247.992138)
		(end 370.95303 -247.976644)
		(width 0.088646)
		(layer "In11.Cu")
		(net "M_H_CPU0_SA_PAR")
	)
	(segment
		(start 403.108668 -254.850646)
		(end 400.7358 -253.86792)
		(width 0.18288)
		(layer "In11.Cu")
		(net "M_H_CPU0_SA_PAR")
	)
	(segment
		(start 400.7358 -253.86792)
		(end 396.475712 -253.86792)
		(width 0.18288)
		(layer "In11.Cu")
		(net "M_H_CPU0_SA_PAR")
	)
	(segment
		(start 372.508526 -252.438408)
		(end 372.36781 -252.438408)
		(width 0.088646)
		(layer "In11.Cu")
		(net "M_H_CPU0_SA_PAR")
	)
	(segment
		(start 372.36781 -252.438408)
		(end 371.89283 -251.963428)
		(width 0.088646)
		(layer "In11.Cu")
		(net "M_H_CPU0_SA_PAR")
	)
	(segment
		(start 445.81318 -258.075176)
		(end 441.226956 -257.576066)
		(width 0.18288)
		(layer "In11.Cu")
		(net "M_H_CPU0_SA_PAR")
	)
	(segment
		(start 371.140482 -248.316496)
		(end 371.131592 -248.311416)
		(width 0.088646)
		(layer "In11.Cu")
		(net "M_H_CPU0_SA_PAR")
	)
	(segment
		(start 406.301702 -256.7813)
		(end 405.039322 -256.7813)
		(width 0.18288)
		(layer "In11.Cu")
		(net "M_H_CPU0_SA_PAR")
	)
	(segment
		(start 370.661946 -246.859044)
		(end 370.670836 -246.853964)
		(width 0.088646)
		(layer "In11.Cu")
		(net "M_H_CPU0_SA_PAR")
	)
	(segment
		(start 450.911214 -259.366766)
		(end 450.55409 -259.009642)
		(width 0.18288)
		(layer "In11.Cu")
		(net "M_H_CPU0_SA_PAR")
	)
	(segment
		(start 371.610636 -249.130566)
		(end 371.601746 -249.125486)
		(width 0.088646)
		(layer "In11.Cu")
		(net "M_H_CPU0_SA_PAR")
	)
	(segment
		(start 371.6655 -245.910862)
		(end 371.64137 -245.821708)
		(width 0.088646)
		(layer "In11.Cu")
		(net "M_H_CPU0_SA_PAR")
	)
	(segment
		(start 408.625802 -257.576066)
		(end 406.301702 -256.7813)
		(width 0.18288)
		(layer "In11.Cu")
		(net "M_H_CPU0_SA_PAR")
	)
	(segment
		(start 371.89283 -251.963428)
		(end 371.89283 -249.60453)
		(width 0.088646)
		(layer "In11.Cu")
		(net "M_H_CPU0_SA_PAR")
	)
	(segment
		(start 371.64137 -245.821708)
		(end 371.797834 -245.55069)
		(width 0.088646)
		(layer "In11.Cu")
		(net "M_H_CPU0_SA_PAR")
	)
	(segment
		(start 371.423184 -248.806208)
		(end 371.423184 -248.798588)
		(width 0.088646)
		(layer "In11.Cu")
		(net "M_H_CPU0_SA_PAR")
	)
	(segment
		(start 449.468494 -259.009642)
		(end 449.19519 -258.736338)
		(width 0.18288)
		(layer "In11.Cu")
		(net "M_H_CPU0_SA_PAR")
	)
	(segment
		(start 370.670836 -247.50268)
		(end 370.661946 -247.4976)
		(width 0.088646)
		(layer "In11.Cu")
		(net "M_H_CPU0_SA_PAR")
	)
	(segment
		(start 450.55409 -259.009642)
		(end 449.468494 -259.009642)
		(width 0.18288)
		(layer "In11.Cu")
		(net "M_H_CPU0_SA_PAR")
	)
	(segment
		(start 447.5988 -258.075176)
		(end 445.81318 -258.075176)
		(width 0.18288)
		(layer "In11.Cu")
		(net "M_H_CPU0_SA_PAR")
	)
	(segment
		(start 395.445996 -254.897636)
		(end 392.556492 -254.897636)
		(width 0.18288)
		(layer "In11.Cu")
		(net "M_H_CPU0_SA_PAR")
	)
	(segment
		(start 371.89283 -246.38)
		(end 371.89283 -246.349012)
		(width 0.088646)
		(layer "In11.Cu")
		(net "M_H_CPU0_SA_PAR")
	)
	(segment
		(start 392.556492 -254.897636)
		(end 390.097264 -252.438408)
		(width 0.18288)
		(layer "In11.Cu")
		(net "M_H_CPU0_SA_PAR")
	)
	(segment
		(start 441.226956 -257.576066)
		(end 408.625802 -257.576066)
		(width 0.18288)
		(layer "In11.Cu")
		(net "M_H_CPU0_SA_PAR")
	)
	(segment
		(start 390.097264 -252.438408)
		(end 372.508526 -252.438408)
		(width 0.18288)
		(layer "In11.Cu")
		(net "M_H_CPU0_SA_PAR")
	)
	(arc
		(start 370.661946 -247.4976)
		(mid 370.483349 -247.178322)
		(end 370.661946 -246.859044)
		(width 0.088646)
		(layer "In11.Cu")
		(net "M_H_CPU0_SA_PAR")
	)
	(arc
		(start 371.89283 -246.349012)
		(mid 371.829486 -246.103835)
		(end 371.6655 -245.910862)
		(width 0.088646)
		(layer "In11.Cu")
		(net "M_H_CPU0_SA_PAR")
	)
	(arc
		(start 371.610636 -246.853964)
		(mid 371.813459 -246.653733)
		(end 371.89283 -246.38)
		(width 0.088646)
		(layer "In11.Cu")
		(net "M_H_CPU0_SA_PAR")
	)
	(arc
		(start 371.059964 -246.8626)
		(mid 371.336439 -246.92992)
		(end 371.610636 -246.853964)
		(width 0.088646)
		(layer "In11.Cu")
		(net "M_H_CPU0_SA_PAR")
	)
	(arc
		(start 371.89283 -249.60453)
		(mid 371.81346 -249.330796)
		(end 371.610636 -249.130566)
		(width 0.088646)
		(layer "In11.Cu")
		(net "M_H_CPU0_SA_PAR")
	)
	(arc
		(start 370.95303 -247.976644)
		(mid 370.87366 -247.70291)
		(end 370.670836 -247.50268)
		(width 0.088646)
		(layer "In11.Cu")
		(net "M_H_CPU0_SA_PAR")
	)
	(arc
		(start 370.670836 -246.853964)
		(mid 370.858034 -246.803821)
		(end 371.045232 -246.853964)
		(width 0.088646)
		(layer "In11.Cu")
		(net "M_H_CPU0_SA_PAR")
	)
	(arc
		(start 371.423184 -248.798588)
		(mid 371.345555 -248.520175)
		(end 371.140482 -248.316496)
		(width 0.088646)
		(layer "In11.Cu")
		(net "M_H_CPU0_SA_PAR")
	)
	(arc
		(start 371.601746 -249.125486)
		(mid 371.470832 -248.989126)
		(end 371.423184 -248.806208)
		(width 0.088646)
		(layer "In11.Cu")
		(net "M_H_CPU0_SA_PAR")
	)
	(arc
		(start 371.131592 -248.311416)
		(mid 371.000678 -248.175056)
		(end 370.95303 -247.992138)
		(width 0.088646)
		(layer "In11.Cu")
		(net "M_H_CPU0_SA_PAR")
	)
	(segment
		(start 458.227176 -273.384518)
		(end 457.968858 -273.642836)
		(width 0.20066)
		(layer "F.Cu")
		(net "M_H_CPU0_SA_DQS_DP<9>")
	)
	(segment
		(start 460.892144 -273.384264)
		(end 460.570326 -273.384264)
		(width 0.20066)
		(layer "F.Cu")
		(net "M_H_CPU0_SA_DQS_DP<9>")
	)
	(segment
		(start 456.960732 -274.067778)
		(end 456.709526 -273.816572)
		(width 0.20066)
		(layer "F.Cu")
		(net "M_H_CPU0_SA_DQS_DP<9>")
	)
	(segment
		(start 461.800702 -273.63928)
		(end 461.14716 -273.63928)
		(width 0.20066)
		(layer "F.Cu")
		(net "M_H_CPU0_SA_DQS_DP<9>")
	)
	(segment
		(start 460.570326 -273.384264)
		(end 460.56296 -273.39163)
		(width 0.1016)
		(layer "F.Cu")
		(net "M_H_CPU0_SA_DQS_DP<9>")
	)
	(segment
		(start 463.092038 -273.816572)
		(end 462.823814 -274.084796)
		(width 0.20066)
		(layer "F.Cu")
		(net "M_H_CPU0_SA_DQS_DP<9>")
	)
	(segment
		(start 457.265532 -274.067778)
		(end 456.960732 -274.067778)
		(width 0.20066)
		(layer "F.Cu")
		(net "M_H_CPU0_SA_DQS_DP<9>")
	)
	(segment
		(start 458.543152 -273.384518)
		(end 458.538326 -273.384518)
		(width 0.101854)
		(layer "F.Cu")
		(net "M_H_CPU0_SA_DQS_DP<9>")
	)
	(segment
		(start 457.690474 -273.642836)
		(end 457.265532 -274.067778)
		(width 0.20066)
		(layer "F.Cu")
		(net "M_H_CPU0_SA_DQS_DP<9>")
	)
	(segment
		(start 372.847362 -259.894832)
		(end 372.847362 -260.430518)
		(width 0.20066)
		(layer "F.Cu")
		(net "M_H_CPU0_SA_DQS_DP<9>")
	)
	(segment
		(start 458.550264 -273.39163)
		(end 458.543152 -273.384518)
		(width 0.1016)
		(layer "F.Cu")
		(net "M_H_CPU0_SA_DQS_DP<9>")
	)
	(segment
		(start 458.538326 -273.384518)
		(end 458.227176 -273.384518)
		(width 0.20066)
		(layer "F.Cu")
		(net "M_H_CPU0_SA_DQS_DP<9>")
	)
	(segment
		(start 461.14716 -273.63928)
		(end 460.892144 -273.384264)
		(width 0.20066)
		(layer "F.Cu")
		(net "M_H_CPU0_SA_DQS_DP<9>")
	)
	(segment
		(start 462.823814 -274.084796)
		(end 462.246218 -274.084796)
		(width 0.20066)
		(layer "F.Cu")
		(net "M_H_CPU0_SA_DQS_DP<9>")
	)
	(segment
		(start 462.246218 -274.084796)
		(end 461.800702 -273.63928)
		(width 0.20066)
		(layer "F.Cu")
		(net "M_H_CPU0_SA_DQS_DP<9>")
	)
	(segment
		(start 463.659982 -273.816572)
		(end 463.092038 -273.816572)
		(width 0.20066)
		(layer "F.Cu")
		(net "M_H_CPU0_SA_DQS_DP<9>")
	)
	(segment
		(start 456.709526 -273.816572)
		(end 456.116182 -273.816572)
		(width 0.20066)
		(layer "F.Cu")
		(net "M_H_CPU0_SA_DQS_DP<9>")
	)
	(segment
		(start 372.847362 -260.430518)
		(end 372.847616 -260.430772)
		(width 0.20066)
		(layer "F.Cu")
		(net "M_H_CPU0_SA_DQS_DP<9>")
	)
	(segment
		(start 455.011282 -273.816572)
		(end 456.116182 -273.816572)
		(width 0.20066)
		(layer "F.Cu")
		(net "M_H_CPU0_SA_DQS_DP<9>")
	)
	(segment
		(start 460.56296 -273.39163)
		(end 458.550264 -273.39163)
		(width 0.1016)
		(layer "F.Cu")
		(net "M_H_CPU0_SA_DQS_DP<9>")
	)
	(segment
		(start 457.968858 -273.642836)
		(end 457.690474 -273.642836)
		(width 0.20066)
		(layer "F.Cu")
		(net "M_H_CPU0_SA_DQS_DP<9>")
	)
	(segment
		(start 376.889264 -259.941314)
		(end 376.874532 -259.932678)
		(width 0.088646)
		(layer "In11.Cu")
		(net "M_H_CPU0_SA_DQS_DP<9>")
	)
	(segment
		(start 448.823334 -273.9263)
		(end 445.541654 -275.29028)
		(width 0.18288)
		(layer "In11.Cu")
		(net "M_H_CPU0_SA_DQS_DP<9>")
	)
	(segment
		(start 383.46761 -259.941314)
		(end 383.457196 -259.935218)
		(width 0.088646)
		(layer "In11.Cu")
		(net "M_H_CPU0_SA_DQS_DP<9>")
	)
	(segment
		(start 424.28922 -275.369528)
		(end 423.604944 -275.369528)
		(width 0.18288)
		(layer "In11.Cu")
		(net "M_H_CPU0_SA_DQS_DP<9>")
	)
	(segment
		(start 450.64299 -273.391376)
		(end 450.43344 -273.600926)
		(width 0.18288)
		(layer "In11.Cu")
		(net "M_H_CPU0_SA_DQS_DP<9>")
	)
	(segment
		(start 423.604944 -275.369528)
		(end 421.93464 -273.699224)
		(width 0.18288)
		(layer "In11.Cu")
		(net "M_H_CPU0_SA_DQS_DP<9>")
	)
	(segment
		(start 384.40741 -259.941314)
		(end 384.392678 -259.932678)
		(width 0.088646)
		(layer "In11.Cu")
		(net "M_H_CPU0_SA_DQS_DP<9>")
	)
	(segment
		(start 420.180262 -273.678396)
		(end 418.98062 -273.678396)
		(width 0.18288)
		(layer "In11.Cu")
		(net "M_H_CPU0_SA_DQS_DP<9>")
	)
	(segment
		(start 382.528064 -259.941314)
		(end 382.513332 -259.932678)
		(width 0.088646)
		(layer "In11.Cu")
		(net "M_H_CPU0_SA_DQS_DP<9>")
	)
	(segment
		(start 387.509766 -262.06704)
		(end 387.509766 -262.030464)
		(width 0.088646)
		(layer "In11.Cu")
		(net "M_H_CPU0_SA_DQS_DP<9>")
	)
	(segment
		(start 437.087772 -273.694906)
		(end 436.331868 -273.694906)
		(width 0.18288)
		(layer "In11.Cu")
		(net "M_H_CPU0_SA_DQS_DP<9>")
	)
	(segment
		(start 412.898082 -274.32254)
		(end 410.707586 -273.41576)
		(width 0.18288)
		(layer "In11.Cu")
		(net "M_H_CPU0_SA_DQS_DP<9>")
	)
	(segment
		(start 374.287542 -260.002528)
		(end 373.848884 -260.01091)
		(width 0.088646)
		(layer "In11.Cu")
		(net "M_H_CPU0_SA_DQS_DP<9>")
	)
	(segment
		(start 388.330694 -262.556244)
		(end 388.207758 -262.433308)
		(width 0.088646)
		(layer "In11.Cu")
		(net "M_H_CPU0_SA_DQS_DP<9>")
	)
	(segment
		(start 373.420132 -260.356604)
		(end 373.345964 -260.430772)
		(width 0.088646)
		(layer "In11.Cu")
		(net "M_H_CPU0_SA_DQS_DP<9>")
	)
	(segment
		(start 373.726964 -260.038596)
		(end 373.600218 -260.106414)
		(width 0.088646)
		(layer "In11.Cu")
		(net "M_H_CPU0_SA_DQS_DP<9>")
	)
	(segment
		(start 410.70784 -273.415506)
		(end 409.090114 -273.415506)
		(width 0.18288)
		(layer "In11.Cu")
		(net "M_H_CPU0_SA_DQS_DP<9>")
	)
	(segment
		(start 451.746366 -273.666712)
		(end 451.401942 -273.666712)
		(width 0.18288)
		(layer "In11.Cu")
		(net "M_H_CPU0_SA_DQS_DP<9>")
	)
	(segment
		(start 375.949464 -259.941314)
		(end 375.934732 -259.932678)
		(width 0.088646)
		(layer "In11.Cu")
		(net "M_H_CPU0_SA_DQS_DP<9>")
	)
	(segment
		(start 420.990014 -273.390868)
		(end 420.46779 -273.390868)
		(width 0.18288)
		(layer "In11.Cu")
		(net "M_H_CPU0_SA_DQS_DP<9>")
	)
	(segment
		(start 421.29837 -273.699224)
		(end 420.990014 -273.390868)
		(width 0.18288)
		(layer "In11.Cu")
		(net "M_H_CPU0_SA_DQS_DP<9>")
	)
	(segment
		(start 438.62752 -275.234654)
		(end 437.087772 -273.694906)
		(width 0.18288)
		(layer "In11.Cu")
		(net "M_H_CPU0_SA_DQS_DP<9>")
	)
	(segment
		(start 450.323966 -273.9263)
		(end 448.823334 -273.9263)
		(width 0.18288)
		(layer "In11.Cu")
		(net "M_H_CPU0_SA_DQS_DP<9>")
	)
	(segment
		(start 386.672582 -261.562596)
		(end 386.662168 -261.568692)
		(width 0.088646)
		(layer "In11.Cu")
		(net "M_H_CPU0_SA_DQS_DP<9>")
	)
	(segment
		(start 373.824246 -260.014212)
		(end 373.726964 -260.038596)
		(width 0.088646)
		(layer "In11.Cu")
		(net "M_H_CPU0_SA_DQS_DP<9>")
	)
	(segment
		(start 450.43344 -273.816826)
		(end 450.323966 -273.9263)
		(width 0.18288)
		(layer "In11.Cu")
		(net "M_H_CPU0_SA_DQS_DP<9>")
	)
	(segment
		(start 438.936384 -275.362162)
		(end 438.62752 -275.234654)
		(width 0.18288)
		(layer "In11.Cu")
		(net "M_H_CPU0_SA_DQS_DP<9>")
	)
	(segment
		(start 410.707586 -273.41576)
		(end 410.70784 -273.415506)
		(width 0.18288)
		(layer "In11.Cu")
		(net "M_H_CPU0_SA_DQS_DP<9>")
	)
	(segment
		(start 454.74128 -274.086574)
		(end 454.284334 -274.086574)
		(width 0.18288)
		(layer "In11.Cu")
		(net "M_H_CPU0_SA_DQS_DP<9>")
	)
	(segment
		(start 385.347972 -259.941822)
		(end 385.332478 -259.932678)
		(width 0.088646)
		(layer "In11.Cu")
		(net "M_H_CPU0_SA_DQS_DP<9>")
	)
	(segment
		(start 445.541654 -275.29028)
		(end 443.535816 -275.29028)
		(width 0.18288)
		(layer "In11.Cu")
		(net "M_H_CPU0_SA_DQS_DP<9>")
	)
	(segment
		(start 374.381014 -259.976874)
		(end 374.287542 -260.002528)
		(width 0.088646)
		(layer "In11.Cu")
		(net "M_H_CPU0_SA_DQS_DP<9>")
	)
	(segment
		(start 385.816602 -260.754622)
		(end 385.808474 -260.75005)
		(width 0.088646)
		(layer "In11.Cu")
		(net "M_H_CPU0_SA_DQS_DP<9>")
	)
	(segment
		(start 386.099812 -261.244842)
		(end 386.099812 -261.2263)
		(width 0.088646)
		(layer "In11.Cu")
		(net "M_H_CPU0_SA_DQS_DP<9>")
	)
	(segment
		(start 440.689238 -275.394928)
		(end 440.427364 -275.394928)
		(width 0.18288)
		(layer "In11.Cu")
		(net "M_H_CPU0_SA_DQS_DP<9>")
	)
	(segment
		(start 440.427364 -275.394928)
		(end 440.123326 -275.09089)
		(width 0.18288)
		(layer "In11.Cu")
		(net "M_H_CPU0_SA_DQS_DP<9>")
	)
	(segment
		(start 418.98062 -273.678396)
		(end 415.743136 -274.32254)
		(width 0.18288)
		(layer "In11.Cu")
		(net "M_H_CPU0_SA_DQS_DP<9>")
	)
	(segment
		(start 433.168552 -273.685)
		(end 431.741072 -274.276058)
		(width 0.18288)
		(layer "In11.Cu")
		(net "M_H_CPU0_SA_DQS_DP<9>")
	)
	(segment
		(start 426.397928 -275.10232)
		(end 425.715684 -275.38553)
		(width 0.18288)
		(layer "In11.Cu")
		(net "M_H_CPU0_SA_DQS_DP<9>")
	)
	(segment
		(start 426.628306 -274.871434)
		(end 426.397928 -275.10232)
		(width 0.18288)
		(layer "In11.Cu")
		(net "M_H_CPU0_SA_DQS_DP<9>")
	)
	(segment
		(start 394.065252 -262.496554)
		(end 388.842504 -262.496554)
		(width 0.18288)
		(layer "In11.Cu")
		(net "M_H_CPU0_SA_DQS_DP<9>")
	)
	(segment
		(start 455.011282 -273.816572)
		(end 454.74128 -274.086574)
		(width 0.18288)
		(layer "In11.Cu")
		(net "M_H_CPU0_SA_DQS_DP<9>")
	)
	(segment
		(start 374.444006 -259.941822)
		(end 374.381014 -259.976874)
		(width 0.088646)
		(layer "In11.Cu")
		(net "M_H_CPU0_SA_DQS_DP<9>")
	)
	(segment
		(start 408.266138 -273.074384)
		(end 404.643082 -273.074384)
		(width 0.18288)
		(layer "In11.Cu")
		(net "M_H_CPU0_SA_DQS_DP<9>")
	)
	(segment
		(start 385.817364 -260.75513)
		(end 385.816602 -260.754622)
		(width 0.088646)
		(layer "In11.Cu")
		(net "M_H_CPU0_SA_DQS_DP<9>")
	)
	(segment
		(start 404.643082 -273.074384)
		(end 394.065252 -262.496554)
		(width 0.18288)
		(layer "In11.Cu")
		(net "M_H_CPU0_SA_DQS_DP<9>")
	)
	(segment
		(start 452.328026 -274.248372)
		(end 451.746366 -273.666712)
		(width 0.18288)
		(layer "In11.Cu")
		(net "M_H_CPU0_SA_DQS_DP<9>")
	)
	(segment
		(start 451.126606 -273.391376)
		(end 451.009766 -273.391376)
		(width 0.18288)
		(layer "In11.Cu")
		(net "M_H_CPU0_SA_DQS_DP<9>")
	)
	(segment
		(start 425.359322 -275.38553)
		(end 425.064682 -275.09089)
		(width 0.18288)
		(layer "In11.Cu")
		(net "M_H_CPU0_SA_DQS_DP<9>")
	)
	(segment
		(start 450.43344 -273.600926)
		(end 450.43344 -273.816826)
		(width 0.18288)
		(layer "In11.Cu")
		(net "M_H_CPU0_SA_DQS_DP<9>")
	)
	(segment
		(start 409.090114 -273.415506)
		(end 408.266138 -273.074384)
		(width 0.18288)
		(layer "In11.Cu")
		(net "M_H_CPU0_SA_DQS_DP<9>")
	)
	(segment
		(start 421.93464 -273.699224)
		(end 421.29837 -273.699224)
		(width 0.18288)
		(layer "In11.Cu")
		(net "M_H_CPU0_SA_DQS_DP<9>")
	)
	(segment
		(start 415.743136 -274.32254)
		(end 412.898082 -274.32254)
		(width 0.18288)
		(layer "In11.Cu")
		(net "M_H_CPU0_SA_DQS_DP<9>")
	)
	(segment
		(start 440.852052 -275.232114)
		(end 440.689238 -275.394928)
		(width 0.18288)
		(layer "In11.Cu")
		(net "M_H_CPU0_SA_DQS_DP<9>")
	)
	(segment
		(start 385.353306 -259.94487)
		(end 385.347972 -259.941822)
		(width 0.088646)
		(layer "In11.Cu")
		(net "M_H_CPU0_SA_DQS_DP<9>")
	)
	(segment
		(start 375.009664 -259.941314)
		(end 375.009664 -259.941568)
		(width 0.088646)
		(layer "In11.Cu")
		(net "M_H_CPU0_SA_DQS_DP<9>")
	)
	(segment
		(start 380.648464 -259.941314)
		(end 380.633732 -259.932678)
		(width 0.088646)
		(layer "In11.Cu")
		(net "M_H_CPU0_SA_DQS_DP<9>")
	)
	(segment
		(start 379.708664 -259.941314)
		(end 379.693932 -259.932678)
		(width 0.088646)
		(layer "In11.Cu")
		(net "M_H_CPU0_SA_DQS_DP<9>")
	)
	(segment
		(start 420.46779 -273.390868)
		(end 420.180262 -273.678396)
		(width 0.18288)
		(layer "In11.Cu")
		(net "M_H_CPU0_SA_DQS_DP<9>")
	)
	(segment
		(start 388.207758 -262.433308)
		(end 387.884416 -262.433308)
		(width 0.088646)
		(layer "In11.Cu")
		(net "M_H_CPU0_SA_DQS_DP<9>")
	)
	(segment
		(start 435.261258 -273.685)
		(end 433.168552 -273.685)
		(width 0.18288)
		(layer "In11.Cu")
		(net "M_H_CPU0_SA_DQS_DP<9>")
	)
	(segment
		(start 373.345964 -260.430772)
		(end 372.847616 -260.430772)
		(width 0.088646)
		(layer "In11.Cu")
		(net "M_H_CPU0_SA_DQS_DP<9>")
	)
	(segment
		(start 440.123326 -275.09089)
		(end 439.655458 -275.09089)
		(width 0.18288)
		(layer "In11.Cu")
		(net "M_H_CPU0_SA_DQS_DP<9>")
	)
	(segment
		(start 386.662168 -261.568692)
		(end 386.66166 -261.5692)
		(width 0.088646)
		(layer "In11.Cu")
		(net "M_H_CPU0_SA_DQS_DP<9>")
	)
	(segment
		(start 442.278008 -274.768564)
		(end 441.969906 -274.768564)
		(width 0.18288)
		(layer "In11.Cu")
		(net "M_H_CPU0_SA_DQS_DP<9>")
	)
	(segment
		(start 451.009766 -273.391376)
		(end 450.794628 -273.391376)
		(width 0.16002)
		(layer "In11.Cu")
		(net "M_H_CPU0_SA_DQS_DP<9>")
	)
	(segment
		(start 425.064682 -275.09089)
		(end 424.567858 -275.09089)
		(width 0.18288)
		(layer "In11.Cu")
		(net "M_H_CPU0_SA_DQS_DP<9>")
	)
	(segment
		(start 377.829064 -259.941314)
		(end 377.814332 -259.932678)
		(width 0.088646)
		(layer "In11.Cu")
		(net "M_H_CPU0_SA_DQS_DP<9>")
	)
	(segment
		(start 428.064168 -274.276058)
		(end 426.628306 -274.871434)
		(width 0.18288)
		(layer "In11.Cu")
		(net "M_H_CPU0_SA_DQS_DP<9>")
	)
	(segment
		(start 373.600218 -260.106414)
		(end 373.591328 -260.111494)
		(width 0.088646)
		(layer "In11.Cu")
		(net "M_H_CPU0_SA_DQS_DP<9>")
	)
	(segment
		(start 450.794628 -273.391376)
		(end 450.64299 -273.391376)
		(width 0.18288)
		(layer "In11.Cu")
		(net "M_H_CPU0_SA_DQS_DP<9>")
	)
	(segment
		(start 436.02783 -273.390868)
		(end 435.55539 -273.390868)
		(width 0.18288)
		(layer "In11.Cu")
		(net "M_H_CPU0_SA_DQS_DP<9>")
	)
	(segment
		(start 431.741072 -274.276058)
		(end 428.064168 -274.276058)
		(width 0.18288)
		(layer "In11.Cu")
		(net "M_H_CPU0_SA_DQS_DP<9>")
	)
	(segment
		(start 435.55539 -273.390868)
		(end 435.261258 -273.685)
		(width 0.18288)
		(layer "In11.Cu")
		(net "M_H_CPU0_SA_DQS_DP<9>")
	)
	(segment
		(start 439.383678 -275.362162)
		(end 438.936384 -275.362162)
		(width 0.18288)
		(layer "In11.Cu")
		(net "M_H_CPU0_SA_DQS_DP<9>")
	)
	(segment
		(start 378.768864 -259.941314)
		(end 378.754132 -259.932678)
		(width 0.088646)
		(layer "In11.Cu")
		(net "M_H_CPU0_SA_DQS_DP<9>")
	)
	(segment
		(start 439.655458 -275.09089)
		(end 439.383678 -275.362162)
		(width 0.18288)
		(layer "In11.Cu")
		(net "M_H_CPU0_SA_DQS_DP<9>")
	)
	(segment
		(start 388.842504 -262.496554)
		(end 388.782814 -262.556244)
		(width 0.088646)
		(layer "In11.Cu")
		(net "M_H_CPU0_SA_DQS_DP<9>")
	)
	(segment
		(start 454.284334 -274.086574)
		(end 453.893682 -274.248372)
		(width 0.18288)
		(layer "In11.Cu")
		(net "M_H_CPU0_SA_DQS_DP<9>")
	)
	(segment
		(start 451.401942 -273.666712)
		(end 451.126606 -273.391376)
		(width 0.18288)
		(layer "In11.Cu")
		(net "M_H_CPU0_SA_DQS_DP<9>")
	)
	(segment
		(start 388.782814 -262.556244)
		(end 388.330694 -262.556244)
		(width 0.088646)
		(layer "In11.Cu")
		(net "M_H_CPU0_SA_DQS_DP<9>")
	)
	(segment
		(start 441.969906 -274.768564)
		(end 440.852052 -275.232114)
		(width 0.18288)
		(layer "In11.Cu")
		(net "M_H_CPU0_SA_DQS_DP<9>")
	)
	(segment
		(start 424.567858 -275.09089)
		(end 424.28922 -275.369528)
		(width 0.18288)
		(layer "In11.Cu")
		(net "M_H_CPU0_SA_DQS_DP<9>")
	)
	(segment
		(start 443.535816 -275.29028)
		(end 442.278008 -274.768564)
		(width 0.18288)
		(layer "In11.Cu")
		(net "M_H_CPU0_SA_DQS_DP<9>")
	)
	(segment
		(start 453.893682 -274.248372)
		(end 452.328026 -274.248372)
		(width 0.18288)
		(layer "In11.Cu")
		(net "M_H_CPU0_SA_DQS_DP<9>")
	)
	(segment
		(start 436.331868 -273.694906)
		(end 436.02783 -273.390868)
		(width 0.18288)
		(layer "In11.Cu")
		(net "M_H_CPU0_SA_DQS_DP<9>")
	)
	(segment
		(start 425.715684 -275.38553)
		(end 425.359322 -275.38553)
		(width 0.18288)
		(layer "In11.Cu")
		(net "M_H_CPU0_SA_DQS_DP<9>")
	)
	(arc
		(start 387.884416 -262.433308)
		(mid 387.787366 -262.420374)
		(end 387.696964 -262.382762)
		(width 0.088646)
		(layer "In11.Cu")
		(net "M_H_CPU0_SA_DQS_DP<9>")
	)
	(arc
		(start 380.08306 -259.941314)
		(mid 379.895862 -259.991457)
		(end 379.708664 -259.941314)
		(width 0.088646)
		(layer "In11.Cu")
		(net "M_H_CPU0_SA_DQS_DP<9>")
	)
	(arc
		(start 383.842006 -259.941314)
		(mid 383.654808 -259.991457)
		(end 383.46761 -259.941314)
		(width 0.088646)
		(layer "In11.Cu")
		(net "M_H_CPU0_SA_DQS_DP<9>")
	)
	(arc
		(start 383.457196 -259.935218)
		(mid 383.179018 -259.865495)
		(end 382.90246 -259.941314)
		(width 0.088646)
		(layer "In11.Cu")
		(net "M_H_CPU0_SA_DQS_DP<9>")
	)
	(arc
		(start 377.814332 -259.932678)
		(mid 377.537857 -259.865358)
		(end 377.26366 -259.941314)
		(width 0.088646)
		(layer "In11.Cu")
		(net "M_H_CPU0_SA_DQS_DP<9>")
	)
	(arc
		(start 373.591328 -260.111494)
		(mid 373.48023 -260.216237)
		(end 373.420132 -260.356604)
		(width 0.088646)
		(layer "In11.Cu")
		(net "M_H_CPU0_SA_DQS_DP<9>")
	)
	(arc
		(start 384.392678 -259.932678)
		(mid 384.116203 -259.865358)
		(end 383.842006 -259.941314)
		(width 0.088646)
		(layer "In11.Cu")
		(net "M_H_CPU0_SA_DQS_DP<9>")
	)
	(arc
		(start 376.32386 -259.941314)
		(mid 376.136662 -259.991457)
		(end 375.949464 -259.941314)
		(width 0.088646)
		(layer "In11.Cu")
		(net "M_H_CPU0_SA_DQS_DP<9>")
	)
	(arc
		(start 385.332478 -259.932678)
		(mid 385.056003 -259.865358)
		(end 384.781806 -259.941314)
		(width 0.088646)
		(layer "In11.Cu")
		(net "M_H_CPU0_SA_DQS_DP<9>")
	)
	(arc
		(start 384.781806 -259.941314)
		(mid 384.594608 -259.991457)
		(end 384.40741 -259.941314)
		(width 0.088646)
		(layer "In11.Cu")
		(net "M_H_CPU0_SA_DQS_DP<9>")
	)
	(arc
		(start 380.633732 -259.932678)
		(mid 380.357257 -259.865358)
		(end 380.08306 -259.941314)
		(width 0.088646)
		(layer "In11.Cu")
		(net "M_H_CPU0_SA_DQS_DP<9>")
	)
	(arc
		(start 382.90246 -259.941314)
		(mid 382.715262 -259.991457)
		(end 382.528064 -259.941314)
		(width 0.088646)
		(layer "In11.Cu")
		(net "M_H_CPU0_SA_DQS_DP<9>")
	)
	(arc
		(start 385.629912 -260.430772)
		(mid 385.555921 -260.151206)
		(end 385.353306 -259.94487)
		(width 0.088646)
		(layer "In11.Cu")
		(net "M_H_CPU0_SA_DQS_DP<9>")
	)
	(arc
		(start 385.808474 -260.75005)
		(mid 385.67756 -260.61369)
		(end 385.629912 -260.430772)
		(width 0.088646)
		(layer "In11.Cu")
		(net "M_H_CPU0_SA_DQS_DP<9>")
	)
	(arc
		(start 382.513332 -259.932678)
		(mid 382.236857 -259.865358)
		(end 381.96266 -259.941314)
		(width 0.088646)
		(layer "In11.Cu")
		(net "M_H_CPU0_SA_DQS_DP<9>")
	)
	(arc
		(start 373.848884 -260.01091)
		(mid 373.836469 -260.011848)
		(end 373.824246 -260.014212)
		(width 0.088646)
		(layer "In11.Cu")
		(net "M_H_CPU0_SA_DQS_DP<9>")
	)
	(arc
		(start 375.934732 -259.932678)
		(mid 375.658257 -259.865358)
		(end 375.38406 -259.941314)
		(width 0.088646)
		(layer "In11.Cu")
		(net "M_H_CPU0_SA_DQS_DP<9>")
	)
	(arc
		(start 386.099812 -261.2263)
		(mid 386.01965 -260.954111)
		(end 385.817364 -260.75513)
		(width 0.088646)
		(layer "In11.Cu")
		(net "M_H_CPU0_SA_DQS_DP<9>")
	)
	(arc
		(start 381.02286 -259.941314)
		(mid 380.835662 -259.991457)
		(end 380.648464 -259.941314)
		(width 0.088646)
		(layer "In11.Cu")
		(net "M_H_CPU0_SA_DQS_DP<9>")
	)
	(arc
		(start 379.693932 -259.932678)
		(mid 379.417457 -259.865358)
		(end 379.14326 -259.941314)
		(width 0.088646)
		(layer "In11.Cu")
		(net "M_H_CPU0_SA_DQS_DP<9>")
	)
	(arc
		(start 378.20346 -259.941314)
		(mid 378.016262 -259.991457)
		(end 377.829064 -259.941314)
		(width 0.088646)
		(layer "In11.Cu")
		(net "M_H_CPU0_SA_DQS_DP<9>")
	)
	(arc
		(start 375.009664 -259.941568)
		(mid 374.726788 -259.865758)
		(end 374.444006 -259.941822)
		(width 0.088646)
		(layer "In11.Cu")
		(net "M_H_CPU0_SA_DQS_DP<9>")
	)
	(arc
		(start 375.38406 -259.941314)
		(mid 375.196862 -259.991457)
		(end 375.009664 -259.941314)
		(width 0.088646)
		(layer "In11.Cu")
		(net "M_H_CPU0_SA_DQS_DP<9>")
	)
	(arc
		(start 381.96266 -259.941314)
		(mid 381.775462 -259.991457)
		(end 381.588264 -259.941314)
		(width 0.088646)
		(layer "In11.Cu")
		(net "M_H_CPU0_SA_DQS_DP<9>")
	)
	(arc
		(start 381.588264 -259.941314)
		(mid 381.305562 -259.865538)
		(end 381.02286 -259.941314)
		(width 0.088646)
		(layer "In11.Cu")
		(net "M_H_CPU0_SA_DQS_DP<9>")
	)
	(arc
		(start 376.874532 -259.932678)
		(mid 376.598057 -259.865358)
		(end 376.32386 -259.941314)
		(width 0.088646)
		(layer "In11.Cu")
		(net "M_H_CPU0_SA_DQS_DP<9>")
	)
	(arc
		(start 379.14326 -259.941314)
		(mid 378.956062 -259.991457)
		(end 378.768864 -259.941314)
		(width 0.088646)
		(layer "In11.Cu")
		(net "M_H_CPU0_SA_DQS_DP<9>")
	)
	(arc
		(start 386.66166 -261.5692)
		(mid 386.287185 -261.569154)
		(end 386.099812 -261.244842)
		(width 0.088646)
		(layer "In11.Cu")
		(net "M_H_CPU0_SA_DQS_DP<9>")
	)
	(arc
		(start 377.26366 -259.941314)
		(mid 377.076462 -259.991457)
		(end 376.889264 -259.941314)
		(width 0.088646)
		(layer "In11.Cu")
		(net "M_H_CPU0_SA_DQS_DP<9>")
	)
	(arc
		(start 378.754132 -259.932678)
		(mid 378.477657 -259.865358)
		(end 378.20346 -259.941314)
		(width 0.088646)
		(layer "In11.Cu")
		(net "M_H_CPU0_SA_DQS_DP<9>")
	)
	(arc
		(start 387.696964 -262.382762)
		(mid 387.562031 -262.249408)
		(end 387.509766 -262.06704)
		(width 0.088646)
		(layer "In11.Cu")
		(net "M_H_CPU0_SA_DQS_DP<9>")
	)
	(arc
		(start 387.509766 -262.030464)
		(mid 387.22077 -261.564676)
		(end 386.672582 -261.562596)
		(width 0.088646)
		(layer "In11.Cu")
		(net "M_H_CPU0_SA_DQS_DP<9>")
	)
	(segment
		(start 461.800702 -282.989274)
		(end 461.14716 -282.989274)
		(width 0.20066)
		(layer "F.Cu")
		(net "M_H_CPU0_SA_DQS_DP<8>")
	)
	(segment
		(start 456.709526 -283.166566)
		(end 456.116182 -283.166566)
		(width 0.20066)
		(layer "F.Cu")
		(net "M_H_CPU0_SA_DQS_DP<8>")
	)
	(segment
		(start 462.246218 -283.43479)
		(end 461.800702 -282.989274)
		(width 0.20066)
		(layer "F.Cu")
		(net "M_H_CPU0_SA_DQS_DP<8>")
	)
	(segment
		(start 457.265532 -283.417772)
		(end 456.960732 -283.417772)
		(width 0.20066)
		(layer "F.Cu")
		(net "M_H_CPU0_SA_DQS_DP<8>")
	)
	(segment
		(start 458.550264 -282.741624)
		(end 458.543152 -282.734512)
		(width 0.1016)
		(layer "F.Cu")
		(net "M_H_CPU0_SA_DQS_DP<8>")
	)
	(segment
		(start 463.659982 -283.166566)
		(end 463.092038 -283.166566)
		(width 0.20066)
		(layer "F.Cu")
		(net "M_H_CPU0_SA_DQS_DP<8>")
	)
	(segment
		(start 455.011282 -283.166566)
		(end 456.116182 -283.166566)
		(width 0.20066)
		(layer "F.Cu")
		(net "M_H_CPU0_SA_DQS_DP<8>")
	)
	(segment
		(start 458.543152 -282.734512)
		(end 458.538326 -282.734512)
		(width 0.101854)
		(layer "F.Cu")
		(net "M_H_CPU0_SA_DQS_DP<8>")
	)
	(segment
		(start 460.570326 -282.734258)
		(end 460.56296 -282.741624)
		(width 0.1016)
		(layer "F.Cu")
		(net "M_H_CPU0_SA_DQS_DP<8>")
	)
	(segment
		(start 457.968858 -282.99283)
		(end 457.690474 -282.99283)
		(width 0.20066)
		(layer "F.Cu")
		(net "M_H_CPU0_SA_DQS_DP<8>")
	)
	(segment
		(start 460.892144 -282.734258)
		(end 460.570326 -282.734258)
		(width 0.20066)
		(layer "F.Cu")
		(net "M_H_CPU0_SA_DQS_DP<8>")
	)
	(segment
		(start 456.960732 -283.417772)
		(end 456.709526 -283.166566)
		(width 0.20066)
		(layer "F.Cu")
		(net "M_H_CPU0_SA_DQS_DP<8>")
	)
	(segment
		(start 461.14716 -282.989274)
		(end 460.892144 -282.734258)
		(width 0.20066)
		(layer "F.Cu")
		(net "M_H_CPU0_SA_DQS_DP<8>")
	)
	(segment
		(start 457.690474 -282.99283)
		(end 457.265532 -283.417772)
		(width 0.20066)
		(layer "F.Cu")
		(net "M_H_CPU0_SA_DQS_DP<8>")
	)
	(segment
		(start 458.227176 -282.734512)
		(end 457.968858 -282.99283)
		(width 0.20066)
		(layer "F.Cu")
		(net "M_H_CPU0_SA_DQS_DP<8>")
	)
	(segment
		(start 372.847362 -265.313922)
		(end 372.847616 -265.314176)
		(width 0.20066)
		(layer "F.Cu")
		(net "M_H_CPU0_SA_DQS_DP<8>")
	)
	(segment
		(start 458.538326 -282.734512)
		(end 458.227176 -282.734512)
		(width 0.20066)
		(layer "F.Cu")
		(net "M_H_CPU0_SA_DQS_DP<8>")
	)
	(segment
		(start 460.56296 -282.741624)
		(end 458.550264 -282.741624)
		(width 0.1016)
		(layer "F.Cu")
		(net "M_H_CPU0_SA_DQS_DP<8>")
	)
	(segment
		(start 462.823814 -283.43479)
		(end 462.246218 -283.43479)
		(width 0.20066)
		(layer "F.Cu")
		(net "M_H_CPU0_SA_DQS_DP<8>")
	)
	(segment
		(start 463.092038 -283.166566)
		(end 462.823814 -283.43479)
		(width 0.20066)
		(layer "F.Cu")
		(net "M_H_CPU0_SA_DQS_DP<8>")
	)
	(segment
		(start 372.847362 -264.778236)
		(end 372.847362 -265.313922)
		(width 0.20066)
		(layer "F.Cu")
		(net "M_H_CPU0_SA_DQS_DP<8>")
	)
	(segment
		(start 420.46779 -286.991044)
		(end 420.166038 -287.292796)
		(width 0.18288)
		(layer "In11.Cu")
		(net "M_H_CPU0_SA_DQS_DP<8>")
	)
	(segment
		(start 377.27128 -264.8204)
		(end 377.263914 -264.824718)
		(width 0.088646)
		(layer "In11.Cu")
		(net "M_H_CPU0_SA_DQS_DP<8>")
	)
	(segment
		(start 438.563766 -286.413702)
		(end 437.706516 -286.058356)
		(width 0.18288)
		(layer "In11.Cu")
		(net "M_H_CPU0_SA_DQS_DP<8>")
	)
	(segment
		(start 387.274308 -268.375384)
		(end 387.044692 -268.145514)
		(width 0.088646)
		(layer "In11.Cu")
		(net "M_H_CPU0_SA_DQS_DP<8>")
	)
	(segment
		(start 453.629268 -283.445966)
		(end 453.242172 -283.60624)
		(width 0.18288)
		(layer "In11.Cu")
		(net "M_H_CPU0_SA_DQS_DP<8>")
	)
	(segment
		(start 384.220212 -267.755878)
		(end 384.220212 -267.737336)
		(width 0.088646)
		(layer "In11.Cu")
		(net "M_H_CPU0_SA_DQS_DP<8>")
	)
	(segment
		(start 412.950152 -284.752034)
		(end 412.318708 -284.12059)
		(width 0.18288)
		(layer "In11.Cu")
		(net "M_H_CPU0_SA_DQS_DP<8>")
	)
	(segment
		(start 430.654206 -284.900878)
		(end 428.204376 -284.900878)
		(width 0.18288)
		(layer "In11.Cu")
		(net "M_H_CPU0_SA_DQS_DP<8>")
	)
	(segment
		(start 446.746884 -284.070552)
		(end 446.01003 -284.807406)
		(width 0.18288)
		(layer "In11.Cu")
		(net "M_H_CPU0_SA_DQS_DP<8>")
	)
	(segment
		(start 449.90893 -283.275532)
		(end 448.882008 -283.275532)
		(width 0.18288)
		(layer "In11.Cu")
		(net "M_H_CPU0_SA_DQS_DP<8>")
	)
	(segment
		(start 413.42691 -284.949392)
		(end 412.950152 -284.752034)
		(width 0.18288)
		(layer "In11.Cu")
		(net "M_H_CPU0_SA_DQS_DP<8>")
	)
	(segment
		(start 428.204376 -284.900878)
		(end 426.677328 -285.533338)
		(width 0.18288)
		(layer "In11.Cu")
		(net "M_H_CPU0_SA_DQS_DP<8>")
	)
	(segment
		(start 451.412102 -282.996132)
		(end 451.404482 -282.988512)
		(width 0.18288)
		(layer "In11.Cu")
		(net "M_H_CPU0_SA_DQS_DP<8>")
	)
	(segment
		(start 410.161486 -284.12059)
		(end 408.450288 -282.409392)
		(width 0.18288)
		(layer "In11.Cu")
		(net "M_H_CPU0_SA_DQS_DP<8>")
	)
	(segment
		(start 382.53416 -264.828274)
		(end 382.528826 -264.825226)
		(width 0.088646)
		(layer "In11.Cu")
		(net "M_H_CPU0_SA_DQS_DP<8>")
	)
	(segment
		(start 417.770056 -285.771336)
		(end 415.784792 -284.949392)
		(width 0.18288)
		(layer "In11.Cu")
		(net "M_H_CPU0_SA_DQS_DP<8>")
	)
	(segment
		(start 388.541514 -268.650466)
		(end 387.780022 -268.650466)
		(width 0.088646)
		(layer "In11.Cu")
		(net "M_H_CPU0_SA_DQS_DP<8>")
	)
	(segment
		(start 442.362336 -285.652718)
		(end 441.225686 -286.123634)
		(width 0.18288)
		(layer "In11.Cu")
		(net "M_H_CPU0_SA_DQS_DP<8>")
	)
	(segment
		(start 455.011282 -283.166566)
		(end 454.731882 -283.445966)
		(width 0.18288)
		(layer "In11.Cu")
		(net "M_H_CPU0_SA_DQS_DP<8>")
	)
	(segment
		(start 436.293514 -285.566358)
		(end 436.018178 -285.291022)
		(width 0.18288)
		(layer "In11.Cu")
		(net "M_H_CPU0_SA_DQS_DP<8>")
	)
	(segment
		(start 437.706516 -286.058356)
		(end 437.214264 -285.566358)
		(width 0.18288)
		(layer "In11.Cu")
		(net "M_H_CPU0_SA_DQS_DP<8>")
	)
	(segment
		(start 451.39102 -282.988512)
		(end 451.143624 -282.741116)
		(width 0.18288)
		(layer "In11.Cu")
		(net "M_H_CPU0_SA_DQS_DP<8>")
	)
	(segment
		(start 408.450288 -282.409392)
		(end 405.398732 -282.409392)
		(width 0.18288)
		(layer "In11.Cu")
		(net "M_H_CPU0_SA_DQS_DP<8>")
	)
	(segment
		(start 382.997202 -265.638026)
		(end 382.989328 -265.633454)
		(width 0.088646)
		(layer "In11.Cu")
		(net "M_H_CPU0_SA_DQS_DP<8>")
	)
	(segment
		(start 381.033528 -264.818622)
		(end 381.023114 -264.824718)
		(width 0.088646)
		(layer "In11.Cu")
		(net "M_H_CPU0_SA_DQS_DP<8>")
	)
	(segment
		(start 452.987156 -283.60624)
		(end 452.457566 -283.386784)
		(width 0.18288)
		(layer "In11.Cu")
		(net "M_H_CPU0_SA_DQS_DP<8>")
	)
	(segment
		(start 377.263914 -264.824718)
		(end 377.259342 -264.827512)
		(width 0.088646)
		(layer "In11.Cu")
		(net "M_H_CPU0_SA_DQS_DP<8>")
	)
	(segment
		(start 421.197278 -287.26638)
		(end 420.921942 -286.991044)
		(width 0.18288)
		(layer "In11.Cu")
		(net "M_H_CPU0_SA_DQS_DP<8>")
	)
	(segment
		(start 421.865806 -287.179258)
		(end 421.655494 -287.26638)
		(width 0.18288)
		(layer "In11.Cu")
		(net "M_H_CPU0_SA_DQS_DP<8>")
	)
	(segment
		(start 386.346954 -268.109954)
		(end 386.346954 -268.1097)
		(width 0.088646)
		(layer "In11.Cu")
		(net "M_H_CPU0_SA_DQS_DP<8>")
	)
	(segment
		(start 439.655458 -286.140906)
		(end 439.3819 -286.413702)
		(width 0.18288)
		(layer "In11.Cu")
		(net "M_H_CPU0_SA_DQS_DP<8>")
	)
	(segment
		(start 383.47396 -266.455906)
		(end 383.45364 -266.444222)
		(width 0.088646)
		(layer "In11.Cu")
		(net "M_H_CPU0_SA_DQS_DP<8>")
	)
	(segment
		(start 373.345964 -265.314176)
		(end 372.847616 -265.314176)
		(width 0.088646)
		(layer "In11.Cu")
		(net "M_H_CPU0_SA_DQS_DP<8>")
	)
	(segment
		(start 387.044692 -268.145514)
		(end 386.529072 -268.145514)
		(width 0.088646)
		(layer "In11.Cu")
		(net "M_H_CPU0_SA_DQS_DP<8>")
	)
	(segment
		(start 419.851332 -287.292796)
		(end 418.731192 -286.732726)
		(width 0.18288)
		(layer "In11.Cu")
		(net "M_H_CPU0_SA_DQS_DP<8>")
	)
	(segment
		(start 382.528826 -264.825226)
		(end 382.513332 -264.816082)
		(width 0.088646)
		(layer "In11.Cu")
		(net "M_H_CPU0_SA_DQS_DP<8>")
	)
	(segment
		(start 383.750566 -266.950444)
		(end 383.750566 -266.941808)
		(width 0.088646)
		(layer "In11.Cu")
		(net "M_H_CPU0_SA_DQS_DP<8>")
	)
	(segment
		(start 425.794678 -286.416242)
		(end 425.307506 -286.416242)
		(width 0.18288)
		(layer "In11.Cu")
		(net "M_H_CPU0_SA_DQS_DP<8>")
	)
	(segment
		(start 446.01003 -284.807406)
		(end 443.207902 -284.807406)
		(width 0.18288)
		(layer "In11.Cu")
		(net "M_H_CPU0_SA_DQS_DP<8>")
	)
	(segment
		(start 440.129422 -286.140906)
		(end 439.655458 -286.140906)
		(width 0.18288)
		(layer "In11.Cu")
		(net "M_H_CPU0_SA_DQS_DP<8>")
	)
	(segment
		(start 451.143624 -282.741116)
		(end 450.991478 -282.741116)
		(width 0.18288)
		(layer "In11.Cu")
		(net "M_H_CPU0_SA_DQS_DP<8>")
	)
	(segment
		(start 440.933332 -286.416242)
		(end 440.404758 -286.416242)
		(width 0.18288)
		(layer "In11.Cu")
		(net "M_H_CPU0_SA_DQS_DP<8>")
	)
	(segment
		(start 426.677328 -285.533338)
		(end 425.794678 -286.416242)
		(width 0.18288)
		(layer "In11.Cu")
		(net "M_H_CPU0_SA_DQS_DP<8>")
	)
	(segment
		(start 388.601204 -268.590776)
		(end 388.541514 -268.650466)
		(width 0.088646)
		(layer "In11.Cu")
		(net "M_H_CPU0_SA_DQS_DP<8>")
	)
	(segment
		(start 375.39168 -264.8204)
		(end 375.384314 -264.824718)
		(width 0.088646)
		(layer "In11.Cu")
		(net "M_H_CPU0_SA_DQS_DP<8>")
	)
	(segment
		(start 425.307506 -286.416242)
		(end 425.03217 -286.140906)
		(width 0.18288)
		(layer "In11.Cu")
		(net "M_H_CPU0_SA_DQS_DP<8>")
	)
	(segment
		(start 405.398732 -282.409392)
		(end 391.580116 -268.590776)
		(width 0.18288)
		(layer "In11.Cu")
		(net "M_H_CPU0_SA_DQS_DP<8>")
	)
	(segment
		(start 450.44995 -283.014166)
		(end 450.170296 -283.014166)
		(width 0.18288)
		(layer "In11.Cu")
		(net "M_H_CPU0_SA_DQS_DP<8>")
	)
	(segment
		(start 421.655494 -287.26638)
		(end 421.197278 -287.26638)
		(width 0.18288)
		(layer "In11.Cu")
		(net "M_H_CPU0_SA_DQS_DP<8>")
	)
	(segment
		(start 452.457566 -283.386784)
		(end 452.06666 -282.996132)
		(width 0.18288)
		(layer "In11.Cu")
		(net "M_H_CPU0_SA_DQS_DP<8>")
	)
	(segment
		(start 374.439942 -264.827512)
		(end 374.437656 -264.829036)
		(width 0.088646)
		(layer "In11.Cu")
		(net "M_H_CPU0_SA_DQS_DP<8>")
	)
	(segment
		(start 376.33148 -264.8204)
		(end 376.324114 -264.824718)
		(width 0.088646)
		(layer "In11.Cu")
		(net "M_H_CPU0_SA_DQS_DP<8>")
	)
	(segment
		(start 380.648718 -264.824718)
		(end 380.638304 -264.818622)
		(width 0.088646)
		(layer "In11.Cu")
		(net "M_H_CPU0_SA_DQS_DP<8>")
	)
	(segment
		(start 435.25948 -285.586932)
		(end 432.31054 -285.586932)
		(width 0.18288)
		(layer "In11.Cu")
		(net "M_H_CPU0_SA_DQS_DP<8>")
	)
	(segment
		(start 425.03217 -286.140906)
		(end 424.567858 -286.140906)
		(width 0.18288)
		(layer "In11.Cu")
		(net "M_H_CPU0_SA_DQS_DP<8>")
	)
	(segment
		(start 378.768864 -264.824718)
		(end 378.754132 -264.816082)
		(width 0.088646)
		(layer "In11.Cu")
		(net "M_H_CPU0_SA_DQS_DP<8>")
	)
	(segment
		(start 373.420132 -265.240008)
		(end 373.345964 -265.314176)
		(width 0.088646)
		(layer "In11.Cu")
		(net "M_H_CPU0_SA_DQS_DP<8>")
	)
	(segment
		(start 387.50494 -268.375384)
		(end 387.274308 -268.375384)
		(width 0.088646)
		(layer "In11.Cu")
		(net "M_H_CPU0_SA_DQS_DP<8>")
	)
	(segment
		(start 424.30065 -286.408114)
		(end 423.155872 -286.408114)
		(width 0.18288)
		(layer "In11.Cu")
		(net "M_H_CPU0_SA_DQS_DP<8>")
	)
	(segment
		(start 376.324114 -264.824718)
		(end 376.319542 -264.827512)
		(width 0.088646)
		(layer "In11.Cu")
		(net "M_H_CPU0_SA_DQS_DP<8>")
	)
	(segment
		(start 412.318708 -284.12059)
		(end 410.161486 -284.12059)
		(width 0.18288)
		(layer "In11.Cu")
		(net "M_H_CPU0_SA_DQS_DP<8>")
	)
	(segment
		(start 423.155872 -286.408114)
		(end 422.269158 -286.77616)
		(width 0.18288)
		(layer "In11.Cu")
		(net "M_H_CPU0_SA_DQS_DP<8>")
	)
	(segment
		(start 450.857366 -282.741116)
		(end 450.723 -282.741116)
		(width 0.18288)
		(layer "In11.Cu")
		(net "M_H_CPU0_SA_DQS_DP<8>")
	)
	(segment
		(start 391.580116 -268.590776)
		(end 388.601204 -268.590776)
		(width 0.18288)
		(layer "In11.Cu")
		(net "M_H_CPU0_SA_DQS_DP<8>")
	)
	(segment
		(start 375.384314 -264.824718)
		(end 375.379742 -264.827512)
		(width 0.088646)
		(layer "In11.Cu")
		(net "M_H_CPU0_SA_DQS_DP<8>")
	)
	(segment
		(start 373.824246 -264.897616)
		(end 373.726964 -264.922)
		(width 0.088646)
		(layer "In11.Cu")
		(net "M_H_CPU0_SA_DQS_DP<8>")
	)
	(segment
		(start 373.726964 -264.922)
		(end 373.600218 -264.989818)
		(width 0.088646)
		(layer "In11.Cu")
		(net "M_H_CPU0_SA_DQS_DP<8>")
	)
	(segment
		(start 437.214264 -285.566358)
		(end 436.293514 -285.566358)
		(width 0.18288)
		(layer "In11.Cu")
		(net "M_H_CPU0_SA_DQS_DP<8>")
	)
	(segment
		(start 374.45188 -264.8204)
		(end 374.439942 -264.827512)
		(width 0.088646)
		(layer "In11.Cu")
		(net "M_H_CPU0_SA_DQS_DP<8>")
	)
	(segment
		(start 387.780022 -268.650466)
		(end 387.50494 -268.375384)
		(width 0.088646)
		(layer "In11.Cu")
		(net "M_H_CPU0_SA_DQS_DP<8>")
	)
	(segment
		(start 453.242172 -283.60624)
		(end 452.987156 -283.60624)
		(width 0.18288)
		(layer "In11.Cu")
		(net "M_H_CPU0_SA_DQS_DP<8>")
	)
	(segment
		(start 450.991478 -282.741116)
		(end 450.857366 -282.741116)
		(width 0.16002)
		(layer "In11.Cu")
		(net "M_H_CPU0_SA_DQS_DP<8>")
	)
	(segment
		(start 435.55539 -285.291022)
		(end 435.25948 -285.586932)
		(width 0.18288)
		(layer "In11.Cu")
		(net "M_H_CPU0_SA_DQS_DP<8>")
	)
	(segment
		(start 436.018178 -285.291022)
		(end 435.55539 -285.291022)
		(width 0.18288)
		(layer "In11.Cu")
		(net "M_H_CPU0_SA_DQS_DP<8>")
	)
	(segment
		(start 452.06666 -282.996132)
		(end 451.412102 -282.996132)
		(width 0.18288)
		(layer "In11.Cu")
		(net "M_H_CPU0_SA_DQS_DP<8>")
	)
	(segment
		(start 373.600218 -264.989818)
		(end 373.591328 -264.994898)
		(width 0.088646)
		(layer "In11.Cu")
		(net "M_H_CPU0_SA_DQS_DP<8>")
	)
	(segment
		(start 440.404758 -286.416242)
		(end 440.129422 -286.140906)
		(width 0.18288)
		(layer "In11.Cu")
		(net "M_H_CPU0_SA_DQS_DP<8>")
	)
	(segment
		(start 439.3819 -286.413702)
		(end 438.563766 -286.413702)
		(width 0.18288)
		(layer "In11.Cu")
		(net "M_H_CPU0_SA_DQS_DP<8>")
	)
	(segment
		(start 379.708664 -264.824718)
		(end 379.693932 -264.816082)
		(width 0.088646)
		(layer "In11.Cu")
		(net "M_H_CPU0_SA_DQS_DP<8>")
	)
	(segment
		(start 424.567858 -286.140906)
		(end 424.30065 -286.408114)
		(width 0.18288)
		(layer "In11.Cu")
		(net "M_H_CPU0_SA_DQS_DP<8>")
	)
	(segment
		(start 441.225686 -286.123634)
		(end 440.933332 -286.416242)
		(width 0.18288)
		(layer "In11.Cu")
		(net "M_H_CPU0_SA_DQS_DP<8>")
	)
	(segment
		(start 432.31054 -285.586932)
		(end 430.654206 -284.900878)
		(width 0.18288)
		(layer "In11.Cu")
		(net "M_H_CPU0_SA_DQS_DP<8>")
	)
	(segment
		(start 420.921942 -286.991044)
		(end 420.46779 -286.991044)
		(width 0.18288)
		(layer "In11.Cu")
		(net "M_H_CPU0_SA_DQS_DP<8>")
	)
	(segment
		(start 450.170296 -283.014166)
		(end 449.90893 -283.275532)
		(width 0.18288)
		(layer "In11.Cu")
		(net "M_H_CPU0_SA_DQS_DP<8>")
	)
	(segment
		(start 450.723 -282.741116)
		(end 450.44995 -283.014166)
		(width 0.18288)
		(layer "In11.Cu")
		(net "M_H_CPU0_SA_DQS_DP<8>")
	)
	(segment
		(start 420.166038 -287.292796)
		(end 419.851332 -287.292796)
		(width 0.18288)
		(layer "In11.Cu")
		(net "M_H_CPU0_SA_DQS_DP<8>")
	)
	(segment
		(start 382.998218 -265.638534)
		(end 382.997202 -265.638026)
		(width 0.088646)
		(layer "In11.Cu")
		(net "M_H_CPU0_SA_DQS_DP<8>")
	)
	(segment
		(start 418.731192 -286.732726)
		(end 417.770056 -285.771336)
		(width 0.18288)
		(layer "In11.Cu")
		(net "M_H_CPU0_SA_DQS_DP<8>")
	)
	(segment
		(start 383.280412 -266.128246)
		(end 383.280412 -266.106148)
		(width 0.088646)
		(layer "In11.Cu")
		(net "M_H_CPU0_SA_DQS_DP<8>")
	)
	(segment
		(start 374.217946 -264.887456)
		(end 373.848884 -264.894314)
		(width 0.088646)
		(layer "In11.Cu")
		(net "M_H_CPU0_SA_DQS_DP<8>")
	)
	(segment
		(start 451.404482 -282.988512)
		(end 451.39102 -282.988512)
		(width 0.18288)
		(layer "In11.Cu")
		(net "M_H_CPU0_SA_DQS_DP<8>")
	)
	(segment
		(start 448.882008 -283.275532)
		(end 448.086988 -284.070552)
		(width 0.18288)
		(layer "In11.Cu")
		(net "M_H_CPU0_SA_DQS_DP<8>")
	)
	(segment
		(start 454.731882 -283.445966)
		(end 453.629268 -283.445966)
		(width 0.18288)
		(layer "In11.Cu")
		(net "M_H_CPU0_SA_DQS_DP<8>")
	)
	(segment
		(start 448.086988 -284.070552)
		(end 446.746884 -284.070552)
		(width 0.18288)
		(layer "In11.Cu")
		(net "M_H_CPU0_SA_DQS_DP<8>")
	)
	(segment
		(start 415.784792 -284.949392)
		(end 413.42691 -284.949392)
		(width 0.18288)
		(layer "In11.Cu")
		(net "M_H_CPU0_SA_DQS_DP<8>")
	)
	(segment
		(start 443.207902 -284.807406)
		(end 442.362336 -285.652718)
		(width 0.18288)
		(layer "In11.Cu")
		(net "M_H_CPU0_SA_DQS_DP<8>")
	)
	(segment
		(start 422.269158 -286.77616)
		(end 421.865806 -287.179258)
		(width 0.18288)
		(layer "In11.Cu")
		(net "M_H_CPU0_SA_DQS_DP<8>")
	)
	(arc
		(start 384.78206 -268.080236)
		(mid 384.407585 -268.08019)
		(end 384.220212 -267.755878)
		(width 0.088646)
		(layer "In11.Cu")
		(net "M_H_CPU0_SA_DQS_DP<8>")
	)
	(arc
		(start 386.529072 -268.145514)
		(mid 386.436302 -268.136507)
		(end 386.346954 -268.109954)
		(width 0.088646)
		(layer "In11.Cu")
		(net "M_H_CPU0_SA_DQS_DP<8>")
	)
	(arc
		(start 380.08306 -264.824718)
		(mid 379.895862 -264.874861)
		(end 379.708664 -264.824718)
		(width 0.088646)
		(layer "In11.Cu")
		(net "M_H_CPU0_SA_DQS_DP<8>")
	)
	(arc
		(start 383.280412 -266.106148)
		(mid 383.199501 -265.83602)
		(end 382.998218 -265.638534)
		(width 0.088646)
		(layer "In11.Cu")
		(net "M_H_CPU0_SA_DQS_DP<8>")
	)
	(arc
		(start 385.347464 -268.080236)
		(mid 385.064762 -268.00446)
		(end 384.78206 -268.080236)
		(width 0.088646)
		(layer "In11.Cu")
		(net "M_H_CPU0_SA_DQS_DP<8>")
	)
	(arc
		(start 382.513332 -264.816082)
		(mid 382.236857 -264.748762)
		(end 381.96266 -264.824718)
		(width 0.088646)
		(layer "In11.Cu")
		(net "M_H_CPU0_SA_DQS_DP<8>")
	)
	(arc
		(start 378.754132 -264.816082)
		(mid 378.477657 -264.748762)
		(end 378.20346 -264.824718)
		(width 0.088646)
		(layer "In11.Cu")
		(net "M_H_CPU0_SA_DQS_DP<8>")
	)
	(arc
		(start 382.989328 -265.633454)
		(mid 382.862074 -265.503488)
		(end 382.81102 -265.328908)
		(width 0.088646)
		(layer "In11.Cu")
		(net "M_H_CPU0_SA_DQS_DP<8>")
	)
	(arc
		(start 382.81102 -265.328908)
		(mid 382.810823 -265.321543)
		(end 382.810766 -265.314176)
		(width 0.088646)
		(layer "In11.Cu")
		(net "M_H_CPU0_SA_DQS_DP<8>")
	)
	(arc
		(start 386.346954 -268.1097)
		(mid 386.316579 -268.096041)
		(end 386.287264 -268.080236)
		(width 0.088646)
		(layer "In11.Cu")
		(net "M_H_CPU0_SA_DQS_DP<8>")
	)
	(arc
		(start 374.437656 -264.829036)
		(mid 374.331333 -264.871531)
		(end 374.217946 -264.887456)
		(width 0.088646)
		(layer "In11.Cu")
		(net "M_H_CPU0_SA_DQS_DP<8>")
	)
	(arc
		(start 386.287264 -268.080236)
		(mid 386.004562 -268.00446)
		(end 385.72186 -268.080236)
		(width 0.088646)
		(layer "In11.Cu")
		(net "M_H_CPU0_SA_DQS_DP<8>")
	)
	(arc
		(start 379.14326 -264.824718)
		(mid 378.956062 -264.874861)
		(end 378.768864 -264.824718)
		(width 0.088646)
		(layer "In11.Cu")
		(net "M_H_CPU0_SA_DQS_DP<8>")
	)
	(arc
		(start 373.848884 -264.894314)
		(mid 373.836469 -264.895252)
		(end 373.824246 -264.897616)
		(width 0.088646)
		(layer "In11.Cu")
		(net "M_H_CPU0_SA_DQS_DP<8>")
	)
	(arc
		(start 385.72186 -268.080236)
		(mid 385.534662 -268.130379)
		(end 385.347464 -268.080236)
		(width 0.088646)
		(layer "In11.Cu")
		(net "M_H_CPU0_SA_DQS_DP<8>")
	)
	(arc
		(start 381.023114 -264.824718)
		(mid 380.835916 -264.874861)
		(end 380.648718 -264.824718)
		(width 0.088646)
		(layer "In11.Cu")
		(net "M_H_CPU0_SA_DQS_DP<8>")
	)
	(arc
		(start 379.693932 -264.816082)
		(mid 379.417457 -264.748762)
		(end 379.14326 -264.824718)
		(width 0.088646)
		(layer "In11.Cu")
		(net "M_H_CPU0_SA_DQS_DP<8>")
	)
	(arc
		(start 377.259342 -264.827512)
		(mid 377.073928 -264.875024)
		(end 376.889264 -264.824718)
		(width 0.088646)
		(layer "In11.Cu")
		(net "M_H_CPU0_SA_DQS_DP<8>")
	)
	(arc
		(start 383.937764 -267.266166)
		(mid 383.802831 -267.132812)
		(end 383.750566 -266.950444)
		(width 0.088646)
		(layer "In11.Cu")
		(net "M_H_CPU0_SA_DQS_DP<8>")
	)
	(arc
		(start 384.220212 -267.737336)
		(mid 384.14005 -267.465147)
		(end 383.937764 -267.266166)
		(width 0.088646)
		(layer "In11.Cu")
		(net "M_H_CPU0_SA_DQS_DP<8>")
	)
	(arc
		(start 381.588264 -264.824718)
		(mid 381.311705 -264.748975)
		(end 381.033528 -264.818622)
		(width 0.088646)
		(layer "In11.Cu")
		(net "M_H_CPU0_SA_DQS_DP<8>")
	)
	(arc
		(start 375.949464 -264.824718)
		(mid 375.671141 -264.748959)
		(end 375.39168 -264.8204)
		(width 0.088646)
		(layer "In11.Cu")
		(net "M_H_CPU0_SA_DQS_DP<8>")
	)
	(arc
		(start 373.591328 -264.994898)
		(mid 373.48023 -265.099641)
		(end 373.420132 -265.240008)
		(width 0.088646)
		(layer "In11.Cu")
		(net "M_H_CPU0_SA_DQS_DP<8>")
	)
	(arc
		(start 381.96266 -264.824718)
		(mid 381.775462 -264.874861)
		(end 381.588264 -264.824718)
		(width 0.088646)
		(layer "In11.Cu")
		(net "M_H_CPU0_SA_DQS_DP<8>")
	)
	(arc
		(start 380.638304 -264.818622)
		(mid 380.359872 -264.748776)
		(end 380.08306 -264.824718)
		(width 0.088646)
		(layer "In11.Cu")
		(net "M_H_CPU0_SA_DQS_DP<8>")
	)
	(arc
		(start 375.009664 -264.824718)
		(mid 374.731341 -264.748959)
		(end 374.45188 -264.8204)
		(width 0.088646)
		(layer "In11.Cu")
		(net "M_H_CPU0_SA_DQS_DP<8>")
	)
	(arc
		(start 383.750566 -266.941808)
		(mid 383.676575 -266.662242)
		(end 383.47396 -266.455906)
		(width 0.088646)
		(layer "In11.Cu")
		(net "M_H_CPU0_SA_DQS_DP<8>")
	)
	(arc
		(start 383.45364 -266.444222)
		(mid 383.326597 -266.308406)
		(end 383.280412 -266.128246)
		(width 0.088646)
		(layer "In11.Cu")
		(net "M_H_CPU0_SA_DQS_DP<8>")
	)
	(arc
		(start 377.829064 -264.824718)
		(mid 377.550741 -264.748959)
		(end 377.27128 -264.8204)
		(width 0.088646)
		(layer "In11.Cu")
		(net "M_H_CPU0_SA_DQS_DP<8>")
	)
	(arc
		(start 378.20346 -264.824718)
		(mid 378.016262 -264.874861)
		(end 377.829064 -264.824718)
		(width 0.088646)
		(layer "In11.Cu")
		(net "M_H_CPU0_SA_DQS_DP<8>")
	)
	(arc
		(start 376.319542 -264.827512)
		(mid 376.134128 -264.875024)
		(end 375.949464 -264.824718)
		(width 0.088646)
		(layer "In11.Cu")
		(net "M_H_CPU0_SA_DQS_DP<8>")
	)
	(arc
		(start 382.810766 -265.314176)
		(mid 382.736775 -265.03461)
		(end 382.53416 -264.828274)
		(width 0.088646)
		(layer "In11.Cu")
		(net "M_H_CPU0_SA_DQS_DP<8>")
	)
	(arc
		(start 376.889264 -264.824718)
		(mid 376.610941 -264.748959)
		(end 376.33148 -264.8204)
		(width 0.088646)
		(layer "In11.Cu")
		(net "M_H_CPU0_SA_DQS_DP<8>")
	)
	(arc
		(start 375.379742 -264.827512)
		(mid 375.194328 -264.875024)
		(end 375.009664 -264.824718)
		(width 0.088646)
		(layer "In11.Cu")
		(net "M_H_CPU0_SA_DQS_DP<8>")
	)
	(segment
		(start 460.56296 -292.091872)
		(end 460.570326 -292.084506)
		(width 0.1016)
		(layer "F.Cu")
		(net "M_H_CPU0_SA_DQS_DP<7>")
	)
	(segment
		(start 461.800702 -292.339268)
		(end 462.246218 -292.784784)
		(width 0.20066)
		(layer "F.Cu")
		(net "M_H_CPU0_SA_DQS_DP<7>")
	)
	(segment
		(start 461.14716 -292.339268)
		(end 461.800702 -292.339268)
		(width 0.20066)
		(layer "F.Cu")
		(net "M_H_CPU0_SA_DQS_DP<7>")
	)
	(segment
		(start 372.847362 -269.66164)
		(end 372.847616 -270.167862)
		(width 0.20066)
		(layer "F.Cu")
		(net "M_H_CPU0_SA_DQS_DP<7>")
	)
	(segment
		(start 372.847616 -270.167862)
		(end 372.847616 -270.19758)
		(width 0.20066)
		(layer "F.Cu")
		(net "M_H_CPU0_SA_DQS_DP<7>")
	)
	(segment
		(start 458.550264 -292.091872)
		(end 460.56296 -292.091872)
		(width 0.1016)
		(layer "F.Cu")
		(net "M_H_CPU0_SA_DQS_DP<7>")
	)
	(segment
		(start 456.960732 -292.767766)
		(end 457.265532 -292.767766)
		(width 0.20066)
		(layer "F.Cu")
		(net "M_H_CPU0_SA_DQS_DP<7>")
	)
	(segment
		(start 460.570326 -292.084506)
		(end 460.892398 -292.084506)
		(width 0.20066)
		(layer "F.Cu")
		(net "M_H_CPU0_SA_DQS_DP<7>")
	)
	(segment
		(start 463.091784 -292.516814)
		(end 463.659982 -292.516814)
		(width 0.20066)
		(layer "F.Cu")
		(net "M_H_CPU0_SA_DQS_DP<7>")
	)
	(segment
		(start 458.543152 -292.08476)
		(end 458.550264 -292.091872)
		(width 0.1016)
		(layer "F.Cu")
		(net "M_H_CPU0_SA_DQS_DP<7>")
	)
	(segment
		(start 456.70978 -292.516814)
		(end 456.960732 -292.767766)
		(width 0.20066)
		(layer "F.Cu")
		(net "M_H_CPU0_SA_DQS_DP<7>")
	)
	(segment
		(start 458.538326 -292.08476)
		(end 458.543152 -292.08476)
		(width 0.101854)
		(layer "F.Cu")
		(net "M_H_CPU0_SA_DQS_DP<7>")
	)
	(segment
		(start 457.265532 -292.767766)
		(end 457.690474 -292.342824)
		(width 0.20066)
		(layer "F.Cu")
		(net "M_H_CPU0_SA_DQS_DP<7>")
	)
	(segment
		(start 455.011282 -292.51656)
		(end 455.011536 -292.516814)
		(width 0.20066)
		(layer "F.Cu")
		(net "M_H_CPU0_SA_DQS_DP<7>")
	)
	(segment
		(start 457.968858 -292.342824)
		(end 458.226922 -292.08476)
		(width 0.20066)
		(layer "F.Cu")
		(net "M_H_CPU0_SA_DQS_DP<7>")
	)
	(segment
		(start 456.116182 -292.516814)
		(end 456.70978 -292.516814)
		(width 0.20066)
		(layer "F.Cu")
		(net "M_H_CPU0_SA_DQS_DP<7>")
	)
	(segment
		(start 462.246218 -292.784784)
		(end 462.823814 -292.784784)
		(width 0.20066)
		(layer "F.Cu")
		(net "M_H_CPU0_SA_DQS_DP<7>")
	)
	(segment
		(start 458.226922 -292.08476)
		(end 458.538326 -292.08476)
		(width 0.20066)
		(layer "F.Cu")
		(net "M_H_CPU0_SA_DQS_DP<7>")
	)
	(segment
		(start 460.892398 -292.084506)
		(end 461.14716 -292.339268)
		(width 0.20066)
		(layer "F.Cu")
		(net "M_H_CPU0_SA_DQS_DP<7>")
	)
	(segment
		(start 462.823814 -292.784784)
		(end 463.091784 -292.516814)
		(width 0.20066)
		(layer "F.Cu")
		(net "M_H_CPU0_SA_DQS_DP<7>")
	)
	(segment
		(start 455.011536 -292.516814)
		(end 456.116182 -292.516814)
		(width 0.20066)
		(layer "F.Cu")
		(net "M_H_CPU0_SA_DQS_DP<7>")
	)
	(segment
		(start 457.690474 -292.342824)
		(end 457.968858 -292.342824)
		(width 0.20066)
		(layer "F.Cu")
		(net "M_H_CPU0_SA_DQS_DP<7>")
	)
	(segment
		(start 436.016654 -296.341038)
		(end 435.55539 -296.341038)
		(width 0.18288)
		(layer "In11.Cu")
		(net "M_H_CPU0_SA_DQS_DP<7>")
	)
	(segment
		(start 439.655458 -297.190922)
		(end 439.359548 -297.48607)
		(width 0.18288)
		(layer "In11.Cu")
		(net "M_H_CPU0_SA_DQS_DP<7>")
	)
	(segment
		(start 442.917072 -295.869868)
		(end 442.007752 -296.779188)
		(width 0.18288)
		(layer "In11.Cu")
		(net "M_H_CPU0_SA_DQS_DP<7>")
	)
	(segment
		(start 452.461376 -292.963854)
		(end 451.8533 -292.355778)
		(width 0.18288)
		(layer "In11.Cu")
		(net "M_H_CPU0_SA_DQS_DP<7>")
	)
	(segment
		(start 425.35221 -297.499278)
		(end 425.043854 -297.190922)
		(width 0.18288)
		(layer "In11.Cu")
		(net "M_H_CPU0_SA_DQS_DP<7>")
	)
	(segment
		(start 440.400694 -297.466258)
		(end 440.125358 -297.190922)
		(width 0.18288)
		(layer "In11.Cu")
		(net "M_H_CPU0_SA_DQS_DP<7>")
	)
	(segment
		(start 378.581412 -271.011396)
		(end 378.581412 -270.995902)
		(width 0.088646)
		(layer "In11.Cu")
		(net "M_H_CPU0_SA_DQS_DP<7>")
	)
	(segment
		(start 425.043854 -297.190922)
		(end 424.567858 -297.190922)
		(width 0.18288)
		(layer "In11.Cu")
		(net "M_H_CPU0_SA_DQS_DP<7>")
	)
	(segment
		(start 379.521466 -272.639282)
		(end 379.521466 -272.625058)
		(width 0.088646)
		(layer "In11.Cu")
		(net "M_H_CPU0_SA_DQS_DP<7>")
	)
	(segment
		(start 420.190676 -298.341288)
		(end 419.586156 -298.341288)
		(width 0.18288)
		(layer "In11.Cu")
		(net "M_H_CPU0_SA_DQS_DP<7>")
	)
	(segment
		(start 373.726964 -269.805404)
		(end 373.600218 -269.873222)
		(width 0.088646)
		(layer "In11.Cu")
		(net "M_H_CPU0_SA_DQS_DP<7>")
	)
	(segment
		(start 385.411472 -273.00682)
		(end 385.411472 -273.006566)
		(width 0.088646)
		(layer "In11.Cu")
		(net "M_H_CPU0_SA_DQS_DP<7>")
	)
	(segment
		(start 449.61048 -292.630606)
		(end 448.814444 -292.630606)
		(width 0.18288)
		(layer "In11.Cu")
		(net "M_H_CPU0_SA_DQS_DP<7>")
	)
	(segment
		(start 450.692266 -292.091364)
		(end 450.463158 -292.320472)
		(width 0.18288)
		(layer "In11.Cu")
		(net "M_H_CPU0_SA_DQS_DP<7>")
	)
	(segment
		(start 411.498034 -295.168574)
		(end 411.023308 -294.693848)
		(width 0.18288)
		(layer "In11.Cu")
		(net "M_H_CPU0_SA_DQS_DP<7>")
	)
	(segment
		(start 379.70079 -272.959068)
		(end 379.700028 -272.95856)
		(width 0.088646)
		(layer "In11.Cu")
		(net "M_H_CPU0_SA_DQS_DP<7>")
	)
	(segment
		(start 450.463158 -292.320472)
		(end 449.920614 -292.320472)
		(width 0.18288)
		(layer "In11.Cu")
		(net "M_H_CPU0_SA_DQS_DP<7>")
	)
	(segment
		(start 405.61641 -292.99281)
		(end 404.657814 -292.99281)
		(width 0.18288)
		(layer "In11.Cu")
		(net "M_H_CPU0_SA_DQS_DP<7>")
	)
	(segment
		(start 387.242558 -274.338542)
		(end 387.182868 -274.398232)
		(width 0.088646)
		(layer "In11.Cu")
		(net "M_H_CPU0_SA_DQS_DP<7>")
	)
	(segment
		(start 374.260364 -269.757906)
		(end 373.916702 -269.757906)
		(width 0.088646)
		(layer "In11.Cu")
		(net "M_H_CPU0_SA_DQS_DP<7>")
	)
	(segment
		(start 381.588264 -272.96364)
		(end 381.573532 -272.955004)
		(width 0.088646)
		(layer "In11.Cu")
		(net "M_H_CPU0_SA_DQS_DP<7>")
	)
	(segment
		(start 417.944046 -296.699178)
		(end 417.233354 -296.699178)
		(width 0.18288)
		(layer "In11.Cu")
		(net "M_H_CPU0_SA_DQS_DP<7>")
	)
	(segment
		(start 375.009664 -269.707868)
		(end 375.009664 -269.708122)
		(width 0.088646)
		(layer "In11.Cu")
		(net "M_H_CPU0_SA_DQS_DP<7>")
	)
	(segment
		(start 401.036536 -289.371532)
		(end 401.036536 -287.768284)
		(width 0.18288)
		(layer "In11.Cu")
		(net "M_H_CPU0_SA_DQS_DP<7>")
	)
	(segment
		(start 426.67555 -296.871136)
		(end 426.047408 -297.499278)
		(width 0.18288)
		(layer "In11.Cu")
		(net "M_H_CPU0_SA_DQS_DP<7>")
	)
	(segment
		(start 421.259 -298.280328)
		(end 421.020494 -298.041822)
		(width 0.18288)
		(layer "In11.Cu")
		(net "M_H_CPU0_SA_DQS_DP<7>")
	)
	(segment
		(start 426.047408 -297.499278)
		(end 425.35221 -297.499278)
		(width 0.18288)
		(layer "In11.Cu")
		(net "M_H_CPU0_SA_DQS_DP<7>")
	)
	(segment
		(start 438.132982 -297.48607)
		(end 437.296306 -296.649394)
		(width 0.18288)
		(layer "In11.Cu")
		(net "M_H_CPU0_SA_DQS_DP<7>")
	)
	(segment
		(start 408.625802 -294.693848)
		(end 407.850086 -293.918132)
		(width 0.18288)
		(layer "In11.Cu")
		(net "M_H_CPU0_SA_DQS_DP<7>")
	)
	(segment
		(start 448.814444 -292.630606)
		(end 447.979546 -293.465504)
		(width 0.18288)
		(layer "In11.Cu")
		(net "M_H_CPU0_SA_DQS_DP<7>")
	)
	(segment
		(start 387.182868 -274.398232)
		(end 386.809488 -274.398232)
		(width 0.088646)
		(layer "In11.Cu")
		(net "M_H_CPU0_SA_DQS_DP<7>")
	)
	(segment
		(start 376.889264 -269.707868)
		(end 376.874532 -269.699232)
		(width 0.088646)
		(layer "In11.Cu")
		(net "M_H_CPU0_SA_DQS_DP<7>")
	)
	(segment
		(start 446.963546 -293.465504)
		(end 446.193164 -294.235886)
		(width 0.18288)
		(layer "In11.Cu")
		(net "M_H_CPU0_SA_DQS_DP<7>")
	)
	(segment
		(start 383.467864 -272.96364)
		(end 383.453132 -272.955004)
		(width 0.088646)
		(layer "In11.Cu")
		(net "M_H_CPU0_SA_DQS_DP<7>")
	)
	(segment
		(start 386.809488 -274.398232)
		(end 385.464304 -273.053048)
		(width 0.088646)
		(layer "In11.Cu")
		(net "M_H_CPU0_SA_DQS_DP<7>")
	)
	(segment
		(start 378.768864 -271.335754)
		(end 378.759974 -271.330674)
		(width 0.088646)
		(layer "In11.Cu")
		(net "M_H_CPU0_SA_DQS_DP<7>")
	)
	(segment
		(start 377.171966 -270.19758)
		(end 377.171966 -270.183356)
		(width 0.088646)
		(layer "In11.Cu")
		(net "M_H_CPU0_SA_DQS_DP<7>")
	)
	(segment
		(start 411.023308 -294.693848)
		(end 408.625802 -294.693848)
		(width 0.18288)
		(layer "In11.Cu")
		(net "M_H_CPU0_SA_DQS_DP<7>")
	)
	(segment
		(start 429.682656 -296.01287)
		(end 428.491904 -297.203622)
		(width 0.18288)
		(layer "In11.Cu")
		(net "M_H_CPU0_SA_DQS_DP<7>")
	)
	(segment
		(start 428.491904 -297.203622)
		(end 427.788578 -297.203622)
		(width 0.18288)
		(layer "In11.Cu")
		(net "M_H_CPU0_SA_DQS_DP<7>")
	)
	(segment
		(start 375.949464 -269.707868)
		(end 375.934732 -269.699232)
		(width 0.088646)
		(layer "In11.Cu")
		(net "M_H_CPU0_SA_DQS_DP<7>")
	)
	(segment
		(start 420.490142 -298.041822)
		(end 420.190676 -298.341288)
		(width 0.18288)
		(layer "In11.Cu")
		(net "M_H_CPU0_SA_DQS_DP<7>")
	)
	(segment
		(start 455.011282 -292.51656)
		(end 454.725278 -292.802564)
		(width 0.18288)
		(layer "In11.Cu")
		(net "M_H_CPU0_SA_DQS_DP<7>")
	)
	(segment
		(start 379.239018 -272.14957)
		(end 379.230128 -272.14449)
		(width 0.088646)
		(layer "In11.Cu")
		(net "M_H_CPU0_SA_DQS_DP<7>")
	)
	(segment
		(start 380.648464 -272.96364)
		(end 380.63805 -272.957544)
		(width 0.088646)
		(layer "In11.Cu")
		(net "M_H_CPU0_SA_DQS_DP<7>")
	)
	(segment
		(start 439.359548 -297.48607)
		(end 438.132982 -297.48607)
		(width 0.18288)
		(layer "In11.Cu")
		(net "M_H_CPU0_SA_DQS_DP<7>")
	)
	(segment
		(start 379.708918 -272.96364)
		(end 379.70714 -272.962624)
		(width 0.088646)
		(layer "In11.Cu")
		(net "M_H_CPU0_SA_DQS_DP<7>")
	)
	(segment
		(start 401.036536 -287.768284)
		(end 387.606794 -274.338542)
		(width 0.18288)
		(layer "In11.Cu")
		(net "M_H_CPU0_SA_DQS_DP<7>")
	)
	(segment
		(start 449.920614 -292.320472)
		(end 449.61048 -292.630606)
		(width 0.18288)
		(layer "In11.Cu")
		(net "M_H_CPU0_SA_DQS_DP<7>")
	)
	(segment
		(start 451.3961 -292.355778)
		(end 451.131686 -292.091364)
		(width 0.18288)
		(layer "In11.Cu")
		(net "M_H_CPU0_SA_DQS_DP<7>")
	)
	(segment
		(start 424.299126 -297.459654)
		(end 423.394886 -297.459654)
		(width 0.18288)
		(layer "In11.Cu")
		(net "M_H_CPU0_SA_DQS_DP<7>")
	)
	(segment
		(start 412.316676 -295.168574)
		(end 411.498034 -295.168574)
		(width 0.18288)
		(layer "In11.Cu")
		(net "M_H_CPU0_SA_DQS_DP<7>")
	)
	(segment
		(start 373.345964 -270.19758)
		(end 372.847616 -270.19758)
		(width 0.088646)
		(layer "In11.Cu")
		(net "M_H_CPU0_SA_DQS_DP<7>")
	)
	(segment
		(start 382.528064 -272.96364)
		(end 382.513332 -272.955004)
		(width 0.088646)
		(layer "In11.Cu")
		(net "M_H_CPU0_SA_DQS_DP<7>")
	)
	(segment
		(start 442.007752 -296.779188)
		(end 441.423044 -296.779188)
		(width 0.18288)
		(layer "In11.Cu")
		(net "M_H_CPU0_SA_DQS_DP<7>")
	)
	(segment
		(start 377.359418 -270.521938)
		(end 377.350528 -270.516858)
		(width 0.088646)
		(layer "In11.Cu")
		(net "M_H_CPU0_SA_DQS_DP<7>")
	)
	(segment
		(start 423.394886 -297.459654)
		(end 421.413432 -298.280328)
		(width 0.18288)
		(layer "In11.Cu")
		(net "M_H_CPU0_SA_DQS_DP<7>")
	)
	(segment
		(start 373.420132 -270.123412)
		(end 373.345964 -270.19758)
		(width 0.088646)
		(layer "In11.Cu")
		(net "M_H_CPU0_SA_DQS_DP<7>")
	)
	(segment
		(start 373.916702 -269.757906)
		(end 373.726964 -269.805404)
		(width 0.088646)
		(layer "In11.Cu")
		(net "M_H_CPU0_SA_DQS_DP<7>")
	)
	(segment
		(start 427.788578 -297.203622)
		(end 427.456092 -296.871136)
		(width 0.18288)
		(layer "In11.Cu")
		(net "M_H_CPU0_SA_DQS_DP<7>")
	)
	(segment
		(start 377.748546 -270.513302)
		(end 377.733814 -270.521938)
		(width 0.088646)
		(layer "In11.Cu")
		(net "M_H_CPU0_SA_DQS_DP<7>")
	)
	(segment
		(start 419.586156 -298.341288)
		(end 417.944046 -296.699178)
		(width 0.18288)
		(layer "In11.Cu")
		(net "M_H_CPU0_SA_DQS_DP<7>")
	)
	(segment
		(start 440.735974 -297.466258)
		(end 440.400694 -297.466258)
		(width 0.18288)
		(layer "In11.Cu")
		(net "M_H_CPU0_SA_DQS_DP<7>")
	)
	(segment
		(start 443.57544 -295.869868)
		(end 442.917072 -295.869868)
		(width 0.18288)
		(layer "In11.Cu")
		(net "M_H_CPU0_SA_DQS_DP<7>")
	)
	(segment
		(start 427.456092 -296.871136)
		(end 426.67555 -296.871136)
		(width 0.18288)
		(layer "In11.Cu")
		(net "M_H_CPU0_SA_DQS_DP<7>")
	)
	(segment
		(start 417.233354 -296.699178)
		(end 415.59607 -296.020998)
		(width 0.18288)
		(layer "In11.Cu")
		(net "M_H_CPU0_SA_DQS_DP<7>")
	)
	(segment
		(start 379.70714 -272.962624)
		(end 379.705616 -272.961608)
		(width 0.088646)
		(layer "In11.Cu")
		(net "M_H_CPU0_SA_DQS_DP<7>")
	)
	(segment
		(start 431.571908 -296.627804)
		(end 430.956974 -296.01287)
		(width 0.18288)
		(layer "In11.Cu")
		(net "M_H_CPU0_SA_DQS_DP<7>")
	)
	(segment
		(start 441.423044 -296.779188)
		(end 440.735974 -297.466258)
		(width 0.18288)
		(layer "In11.Cu")
		(net "M_H_CPU0_SA_DQS_DP<7>")
	)
	(segment
		(start 421.413432 -298.280328)
		(end 421.259 -298.280328)
		(width 0.18288)
		(layer "In11.Cu")
		(net "M_H_CPU0_SA_DQS_DP<7>")
	)
	(segment
		(start 451.131686 -292.091364)
		(end 450.692266 -292.091364)
		(width 0.18288)
		(layer "In11.Cu")
		(net "M_H_CPU0_SA_DQS_DP<7>")
	)
	(segment
		(start 424.567858 -297.190922)
		(end 424.299126 -297.459654)
		(width 0.18288)
		(layer "In11.Cu")
		(net "M_H_CPU0_SA_DQS_DP<7>")
	)
	(segment
		(start 373.600218 -269.873222)
		(end 373.591328 -269.878302)
		(width 0.088646)
		(layer "In11.Cu")
		(net "M_H_CPU0_SA_DQS_DP<7>")
	)
	(segment
		(start 454.344278 -292.802564)
		(end 454.182988 -292.963854)
		(width 0.18288)
		(layer "In11.Cu")
		(net "M_H_CPU0_SA_DQS_DP<7>")
	)
	(segment
		(start 445.209422 -294.235886)
		(end 443.57544 -295.869868)
		(width 0.18288)
		(layer "In11.Cu")
		(net "M_H_CPU0_SA_DQS_DP<7>")
	)
	(segment
		(start 454.182988 -292.963854)
		(end 452.461376 -292.963854)
		(width 0.18288)
		(layer "In11.Cu")
		(net "M_H_CPU0_SA_DQS_DP<7>")
	)
	(segment
		(start 387.606794 -274.338542)
		(end 387.242558 -274.338542)
		(width 0.18288)
		(layer "In11.Cu")
		(net "M_H_CPU0_SA_DQS_DP<7>")
	)
	(segment
		(start 447.979546 -293.465504)
		(end 446.963546 -293.465504)
		(width 0.18288)
		(layer "In11.Cu")
		(net "M_H_CPU0_SA_DQS_DP<7>")
	)
	(segment
		(start 446.193164 -294.235886)
		(end 445.209422 -294.235886)
		(width 0.18288)
		(layer "In11.Cu")
		(net "M_H_CPU0_SA_DQS_DP<7>")
	)
	(segment
		(start 379.705616 -272.961608)
		(end 379.70079 -272.959068)
		(width 0.088646)
		(layer "In11.Cu")
		(net "M_H_CPU0_SA_DQS_DP<7>")
	)
	(segment
		(start 378.77496 -271.33931)
		(end 378.768864 -271.335754)
		(width 0.088646)
		(layer "In11.Cu")
		(net "M_H_CPU0_SA_DQS_DP<7>")
	)
	(segment
		(start 435.55539 -296.341038)
		(end 435.268624 -296.627804)
		(width 0.18288)
		(layer "In11.Cu")
		(net "M_H_CPU0_SA_DQS_DP<7>")
	)
	(segment
		(start 436.32501 -296.649394)
		(end 436.016654 -296.341038)
		(width 0.18288)
		(layer "In11.Cu")
		(net "M_H_CPU0_SA_DQS_DP<7>")
	)
	(segment
		(start 413.1691 -296.020998)
		(end 412.316676 -295.168574)
		(width 0.18288)
		(layer "In11.Cu")
		(net "M_H_CPU0_SA_DQS_DP<7>")
	)
	(segment
		(start 415.59607 -296.020998)
		(end 413.1691 -296.020998)
		(width 0.18288)
		(layer "In11.Cu")
		(net "M_H_CPU0_SA_DQS_DP<7>")
	)
	(segment
		(start 454.725278 -292.802564)
		(end 454.344278 -292.802564)
		(width 0.18288)
		(layer "In11.Cu")
		(net "M_H_CPU0_SA_DQS_DP<7>")
	)
	(segment
		(start 440.125358 -297.190922)
		(end 439.655458 -297.190922)
		(width 0.18288)
		(layer "In11.Cu")
		(net "M_H_CPU0_SA_DQS_DP<7>")
	)
	(segment
		(start 404.657814 -292.99281)
		(end 401.036536 -289.371532)
		(width 0.18288)
		(layer "In11.Cu")
		(net "M_H_CPU0_SA_DQS_DP<7>")
	)
	(segment
		(start 421.020494 -298.041822)
		(end 420.490142 -298.041822)
		(width 0.18288)
		(layer "In11.Cu")
		(net "M_H_CPU0_SA_DQS_DP<7>")
	)
	(segment
		(start 407.850086 -293.918132)
		(end 405.61641 -292.99281)
		(width 0.18288)
		(layer "In11.Cu")
		(net "M_H_CPU0_SA_DQS_DP<7>")
	)
	(segment
		(start 437.296306 -296.649394)
		(end 436.32501 -296.649394)
		(width 0.18288)
		(layer "In11.Cu")
		(net "M_H_CPU0_SA_DQS_DP<7>")
	)
	(segment
		(start 430.956974 -296.01287)
		(end 429.682656 -296.01287)
		(width 0.18288)
		(layer "In11.Cu")
		(net "M_H_CPU0_SA_DQS_DP<7>")
	)
	(segment
		(start 451.8533 -292.355778)
		(end 451.3961 -292.355778)
		(width 0.18288)
		(layer "In11.Cu")
		(net "M_H_CPU0_SA_DQS_DP<7>")
	)
	(segment
		(start 435.268624 -296.627804)
		(end 431.571908 -296.627804)
		(width 0.18288)
		(layer "In11.Cu")
		(net "M_H_CPU0_SA_DQS_DP<7>")
	)
	(arc
		(start 378.581412 -270.995902)
		(mid 378.502042 -270.722168)
		(end 378.299218 -270.521938)
		(width 0.088646)
		(layer "In11.Cu")
		(net "M_H_CPU0_SA_DQS_DP<7>")
	)
	(arc
		(start 383.84226 -272.96364)
		(mid 383.655062 -273.013783)
		(end 383.467864 -272.96364)
		(width 0.088646)
		(layer "In11.Cu")
		(net "M_H_CPU0_SA_DQS_DP<7>")
	)
	(arc
		(start 373.591328 -269.878302)
		(mid 373.48023 -269.983045)
		(end 373.420132 -270.123412)
		(width 0.088646)
		(layer "In11.Cu")
		(net "M_H_CPU0_SA_DQS_DP<7>")
	)
	(arc
		(start 379.521466 -272.625058)
		(mid 379.442325 -272.350435)
		(end 379.239018 -272.14957)
		(width 0.088646)
		(layer "In11.Cu")
		(net "M_H_CPU0_SA_DQS_DP<7>")
	)
	(arc
		(start 379.230128 -272.14449)
		(mid 379.102874 -272.014524)
		(end 379.05182 -271.839944)
		(width 0.088646)
		(layer "In11.Cu")
		(net "M_H_CPU0_SA_DQS_DP<7>")
	)
	(arc
		(start 381.96266 -272.96364)
		(mid 381.775462 -273.013783)
		(end 381.588264 -272.96364)
		(width 0.088646)
		(layer "In11.Cu")
		(net "M_H_CPU0_SA_DQS_DP<7>")
	)
	(arc
		(start 374.444768 -269.708376)
		(mid 374.355838 -269.745333)
		(end 374.260364 -269.757906)
		(width 0.088646)
		(layer "In11.Cu")
		(net "M_H_CPU0_SA_DQS_DP<7>")
	)
	(arc
		(start 381.02286 -272.96364)
		(mid 380.835662 -273.013783)
		(end 380.648464 -272.96364)
		(width 0.088646)
		(layer "In11.Cu")
		(net "M_H_CPU0_SA_DQS_DP<7>")
	)
	(arc
		(start 384.78206 -272.96364)
		(mid 384.594862 -273.013783)
		(end 384.407664 -272.96364)
		(width 0.088646)
		(layer "In11.Cu")
		(net "M_H_CPU0_SA_DQS_DP<7>")
	)
	(arc
		(start 385.347464 -272.96364)
		(mid 385.064762 -272.887864)
		(end 384.78206 -272.96364)
		(width 0.088646)
		(layer "In11.Cu")
		(net "M_H_CPU0_SA_DQS_DP<7>")
	)
	(arc
		(start 378.759974 -271.330674)
		(mid 378.62906 -271.194314)
		(end 378.581412 -271.011396)
		(width 0.088646)
		(layer "In11.Cu")
		(net "M_H_CPU0_SA_DQS_DP<7>")
	)
	(arc
		(start 382.513332 -272.955004)
		(mid 382.236857 -272.887684)
		(end 381.96266 -272.96364)
		(width 0.088646)
		(layer "In11.Cu")
		(net "M_H_CPU0_SA_DQS_DP<7>")
	)
	(arc
		(start 375.009664 -269.708122)
		(mid 374.727187 -269.6326)
		(end 374.444768 -269.708376)
		(width 0.088646)
		(layer "In11.Cu")
		(net "M_H_CPU0_SA_DQS_DP<7>")
	)
	(arc
		(start 383.453132 -272.955004)
		(mid 383.176657 -272.887684)
		(end 382.90246 -272.96364)
		(width 0.088646)
		(layer "In11.Cu")
		(net "M_H_CPU0_SA_DQS_DP<7>")
	)
	(arc
		(start 384.407664 -272.96364)
		(mid 384.124962 -272.887864)
		(end 383.84226 -272.96364)
		(width 0.088646)
		(layer "In11.Cu")
		(net "M_H_CPU0_SA_DQS_DP<7>")
	)
	(arc
		(start 375.38406 -269.707868)
		(mid 375.196862 -269.758011)
		(end 375.009664 -269.707868)
		(width 0.088646)
		(layer "In11.Cu")
		(net "M_H_CPU0_SA_DQS_DP<7>")
	)
	(arc
		(start 385.464304 -273.053048)
		(mid 385.438606 -273.029114)
		(end 385.411472 -273.00682)
		(width 0.088646)
		(layer "In11.Cu")
		(net "M_H_CPU0_SA_DQS_DP<7>")
	)
	(arc
		(start 382.90246 -272.96364)
		(mid 382.715262 -273.013783)
		(end 382.528064 -272.96364)
		(width 0.088646)
		(layer "In11.Cu")
		(net "M_H_CPU0_SA_DQS_DP<7>")
	)
	(arc
		(start 385.411472 -273.006566)
		(mid 385.3802 -272.984011)
		(end 385.347464 -272.96364)
		(width 0.088646)
		(layer "In11.Cu")
		(net "M_H_CPU0_SA_DQS_DP<7>")
	)
	(arc
		(start 375.934732 -269.699232)
		(mid 375.658291 -269.632066)
		(end 375.38406 -269.707868)
		(width 0.088646)
		(layer "In11.Cu")
		(net "M_H_CPU0_SA_DQS_DP<7>")
	)
	(arc
		(start 376.874532 -269.699232)
		(mid 376.598091 -269.632066)
		(end 376.32386 -269.707868)
		(width 0.088646)
		(layer "In11.Cu")
		(net "M_H_CPU0_SA_DQS_DP<7>")
	)
	(arc
		(start 381.573532 -272.955004)
		(mid 381.297057 -272.887684)
		(end 381.02286 -272.96364)
		(width 0.088646)
		(layer "In11.Cu")
		(net "M_H_CPU0_SA_DQS_DP<7>")
	)
	(arc
		(start 378.299218 -270.521938)
		(mid 378.025019 -270.446103)
		(end 377.748546 -270.513302)
		(width 0.088646)
		(layer "In11.Cu")
		(net "M_H_CPU0_SA_DQS_DP<7>")
	)
	(arc
		(start 377.733814 -270.521938)
		(mid 377.546616 -270.572081)
		(end 377.359418 -270.521938)
		(width 0.088646)
		(layer "In11.Cu")
		(net "M_H_CPU0_SA_DQS_DP<7>")
	)
	(arc
		(start 380.63805 -272.957544)
		(mid 380.359872 -272.887821)
		(end 380.083314 -272.96364)
		(width 0.088646)
		(layer "In11.Cu")
		(net "M_H_CPU0_SA_DQS_DP<7>")
	)
	(arc
		(start 376.32386 -269.707868)
		(mid 376.136662 -269.758011)
		(end 375.949464 -269.707868)
		(width 0.088646)
		(layer "In11.Cu")
		(net "M_H_CPU0_SA_DQS_DP<7>")
	)
	(arc
		(start 377.171966 -270.183356)
		(mid 377.092747 -269.908671)
		(end 376.889264 -269.707868)
		(width 0.088646)
		(layer "In11.Cu")
		(net "M_H_CPU0_SA_DQS_DP<7>")
	)
	(arc
		(start 379.05182 -271.839944)
		(mid 379.051623 -271.832579)
		(end 379.051566 -271.825212)
		(width 0.088646)
		(layer "In11.Cu")
		(net "M_H_CPU0_SA_DQS_DP<7>")
	)
	(arc
		(start 379.051566 -271.825212)
		(mid 378.977575 -271.545646)
		(end 378.77496 -271.33931)
		(width 0.088646)
		(layer "In11.Cu")
		(net "M_H_CPU0_SA_DQS_DP<7>")
	)
	(arc
		(start 379.700028 -272.95856)
		(mid 379.569114 -272.8222)
		(end 379.521466 -272.639282)
		(width 0.088646)
		(layer "In11.Cu")
		(net "M_H_CPU0_SA_DQS_DP<7>")
	)
	(arc
		(start 377.350528 -270.516858)
		(mid 377.219614 -270.380498)
		(end 377.171966 -270.19758)
		(width 0.088646)
		(layer "In11.Cu")
		(net "M_H_CPU0_SA_DQS_DP<7>")
	)
	(arc
		(start 380.083314 -272.96364)
		(mid 379.896116 -273.013783)
		(end 379.708918 -272.96364)
		(width 0.088646)
		(layer "In11.Cu")
		(net "M_H_CPU0_SA_DQS_DP<7>")
	)
	(segment
		(start 455.011536 -301.866808)
		(end 456.116182 -301.866808)
		(width 0.20066)
		(layer "F.Cu")
		(net "M_H_CPU0_SA_DQS_DP<6>")
	)
	(segment
		(start 458.543152 -301.434754)
		(end 458.550264 -301.441866)
		(width 0.1016)
		(layer "F.Cu")
		(net "M_H_CPU0_SA_DQS_DP<6>")
	)
	(segment
		(start 458.226922 -301.434754)
		(end 458.538326 -301.434754)
		(width 0.20066)
		(layer "F.Cu")
		(net "M_H_CPU0_SA_DQS_DP<6>")
	)
	(segment
		(start 456.70978 -301.866808)
		(end 456.960732 -302.11776)
		(width 0.20066)
		(layer "F.Cu")
		(net "M_H_CPU0_SA_DQS_DP<6>")
	)
	(segment
		(start 372.847616 -274.545044)
		(end 372.847616 -275.08073)
		(width 0.20066)
		(layer "F.Cu")
		(net "M_H_CPU0_SA_DQS_DP<6>")
	)
	(segment
		(start 462.246218 -302.134778)
		(end 462.823814 -302.134778)
		(width 0.20066)
		(layer "F.Cu")
		(net "M_H_CPU0_SA_DQS_DP<6>")
	)
	(segment
		(start 458.550264 -301.441866)
		(end 460.56296 -301.441866)
		(width 0.1016)
		(layer "F.Cu")
		(net "M_H_CPU0_SA_DQS_DP<6>")
	)
	(segment
		(start 457.265532 -302.11776)
		(end 457.690474 -301.692818)
		(width 0.20066)
		(layer "F.Cu")
		(net "M_H_CPU0_SA_DQS_DP<6>")
	)
	(segment
		(start 458.538326 -301.434754)
		(end 458.543152 -301.434754)
		(width 0.101854)
		(layer "F.Cu")
		(net "M_H_CPU0_SA_DQS_DP<6>")
	)
	(segment
		(start 463.091784 -301.866808)
		(end 463.659982 -301.866808)
		(width 0.20066)
		(layer "F.Cu")
		(net "M_H_CPU0_SA_DQS_DP<6>")
	)
	(segment
		(start 456.960732 -302.11776)
		(end 457.265532 -302.11776)
		(width 0.20066)
		(layer "F.Cu")
		(net "M_H_CPU0_SA_DQS_DP<6>")
	)
	(segment
		(start 457.690474 -301.692818)
		(end 457.968858 -301.692818)
		(width 0.20066)
		(layer "F.Cu")
		(net "M_H_CPU0_SA_DQS_DP<6>")
	)
	(segment
		(start 455.011282 -301.866554)
		(end 455.011536 -301.866808)
		(width 0.20066)
		(layer "F.Cu")
		(net "M_H_CPU0_SA_DQS_DP<6>")
	)
	(segment
		(start 457.968858 -301.692818)
		(end 458.226922 -301.434754)
		(width 0.20066)
		(layer "F.Cu")
		(net "M_H_CPU0_SA_DQS_DP<6>")
	)
	(segment
		(start 372.847362 -274.54479)
		(end 372.847616 -274.545044)
		(width 0.20066)
		(layer "F.Cu")
		(net "M_H_CPU0_SA_DQS_DP<6>")
	)
	(segment
		(start 460.56296 -301.441866)
		(end 460.570326 -301.4345)
		(width 0.1016)
		(layer "F.Cu")
		(net "M_H_CPU0_SA_DQS_DP<6>")
	)
	(segment
		(start 461.800702 -301.689262)
		(end 462.246218 -302.134778)
		(width 0.20066)
		(layer "F.Cu")
		(net "M_H_CPU0_SA_DQS_DP<6>")
	)
	(segment
		(start 460.570326 -301.4345)
		(end 460.892398 -301.4345)
		(width 0.20066)
		(layer "F.Cu")
		(net "M_H_CPU0_SA_DQS_DP<6>")
	)
	(segment
		(start 461.14716 -301.689262)
		(end 461.800702 -301.689262)
		(width 0.20066)
		(layer "F.Cu")
		(net "M_H_CPU0_SA_DQS_DP<6>")
	)
	(segment
		(start 456.116182 -301.866808)
		(end 456.70978 -301.866808)
		(width 0.20066)
		(layer "F.Cu")
		(net "M_H_CPU0_SA_DQS_DP<6>")
	)
	(segment
		(start 460.892398 -301.4345)
		(end 461.14716 -301.689262)
		(width 0.20066)
		(layer "F.Cu")
		(net "M_H_CPU0_SA_DQS_DP<6>")
	)
	(segment
		(start 462.823814 -302.134778)
		(end 463.091784 -301.866808)
		(width 0.20066)
		(layer "F.Cu")
		(net "M_H_CPU0_SA_DQS_DP<6>")
	)
	(segment
		(start 402.813012 -300.23943)
		(end 394.64361 -292.070028)
		(width 0.18288)
		(layer "In11.Cu")
		(net "M_H_CPU0_SA_DQS_DP<6>")
	)
	(segment
		(start 386.100066 -280.778204)
		(end 386.100066 -280.76398)
		(width 0.088646)
		(layer "In11.Cu")
		(net "M_H_CPU0_SA_DQS_DP<6>")
	)
	(segment
		(start 440.646312 -308.520338)
		(end 440.400694 -308.520338)
		(width 0.18288)
		(layer "In11.Cu")
		(net "M_H_CPU0_SA_DQS_DP<6>")
	)
	(segment
		(start 435.313328 -307.694584)
		(end 431.803302 -307.694584)
		(width 0.18288)
		(layer "In11.Cu")
		(net "M_H_CPU0_SA_DQS_DP<6>")
	)
	(segment
		(start 405.471884 -305.689508)
		(end 405.211788 -305.949604)
		(width 0.18288)
		(layer "In11.Cu")
		(net "M_H_CPU0_SA_DQS_DP<6>")
	)
	(segment
		(start 375.01576 -276.222714)
		(end 375.012458 -276.220682)
		(width 0.088646)
		(layer "In11.Cu")
		(net "M_H_CPU0_SA_DQS_DP<6>")
	)
	(segment
		(start 441.692538 -307.474112)
		(end 440.646312 -308.520338)
		(width 0.18288)
		(layer "In11.Cu")
		(net "M_H_CPU0_SA_DQS_DP<6>")
	)
	(segment
		(start 447.412364 -304.395886)
		(end 447.121788 -304.395886)
		(width 0.18288)
		(layer "In11.Cu")
		(net "M_H_CPU0_SA_DQS_DP<6>")
	)
	(segment
		(start 420.168832 -309.390034)
		(end 419.59403 -309.390034)
		(width 0.18288)
		(layer "In11.Cu")
		(net "M_H_CPU0_SA_DQS_DP<6>")
	)
	(segment
		(start 373.360188 -275.08073)
		(end 372.847616 -275.08073)
		(width 0.088646)
		(layer "In11.Cu")
		(net "M_H_CPU0_SA_DQS_DP<6>")
	)
	(segment
		(start 451.792086 -301.716694)
		(end 451.41515 -301.716694)
		(width 0.18288)
		(layer "In11.Cu")
		(net "M_H_CPU0_SA_DQS_DP<6>")
	)
	(segment
		(start 450.852286 -301.441358)
		(end 450.722492 -301.441358)
		(width 0.18288)
		(layer "In11.Cu")
		(net "M_H_CPU0_SA_DQS_DP<6>")
	)
	(segment
		(start 426.734478 -307.91277)
		(end 426.10532 -308.541928)
		(width 0.18288)
		(layer "In11.Cu")
		(net "M_H_CPU0_SA_DQS_DP<6>")
	)
	(segment
		(start 394.64361 -292.070028)
		(end 394.64361 -290.54679)
		(width 0.18288)
		(layer "In11.Cu")
		(net "M_H_CPU0_SA_DQS_DP<6>")
	)
	(segment
		(start 394.64361 -290.54679)
		(end 388.249668 -284.152848)
		(width 0.18288)
		(layer "In11.Cu")
		(net "M_H_CPU0_SA_DQS_DP<6>")
	)
	(segment
		(start 452.378826 -302.303434)
		(end 451.792086 -301.716694)
		(width 0.18288)
		(layer "In11.Cu")
		(net "M_H_CPU0_SA_DQS_DP<6>")
	)
	(segment
		(start 454.161652 -302.303434)
		(end 452.378826 -302.303434)
		(width 0.18288)
		(layer "In11.Cu")
		(net "M_H_CPU0_SA_DQS_DP<6>")
	)
	(segment
		(start 387.052312 -282.465272)
		(end 387.052312 -281.840178)
		(width 0.088646)
		(layer "In11.Cu")
		(net "M_H_CPU0_SA_DQS_DP<6>")
	)
	(segment
		(start 421.365426 -309.366412)
		(end 421.216582 -309.366412)
		(width 0.18288)
		(layer "In11.Cu")
		(net "M_H_CPU0_SA_DQS_DP<6>")
	)
	(segment
		(start 443.18682 -306.758086)
		(end 442.470794 -307.474112)
		(width 0.18288)
		(layer "In11.Cu")
		(net "M_H_CPU0_SA_DQS_DP<6>")
	)
	(segment
		(start 450.722492 -301.441358)
		(end 450.452744 -301.711106)
		(width 0.18288)
		(layer "In11.Cu")
		(net "M_H_CPU0_SA_DQS_DP<6>")
	)
	(segment
		(start 454.333864 -302.131222)
		(end 454.161652 -302.303434)
		(width 0.18288)
		(layer "In11.Cu")
		(net "M_H_CPU0_SA_DQS_DP<6>")
	)
	(segment
		(start 419.59403 -309.390034)
		(end 418.01669 -307.813456)
		(width 0.18288)
		(layer "In11.Cu")
		(net "M_H_CPU0_SA_DQS_DP<6>")
	)
	(segment
		(start 426.10532 -308.541928)
		(end 425.329604 -308.541928)
		(width 0.18288)
		(layer "In11.Cu")
		(net "M_H_CPU0_SA_DQS_DP<6>")
	)
	(segment
		(start 439.352944 -308.54269)
		(end 437.479948 -308.54269)
		(width 0.18288)
		(layer "In11.Cu")
		(net "M_H_CPU0_SA_DQS_DP<6>")
	)
	(segment
		(start 412.84525 -306.693062)
		(end 412.129732 -307.40858)
		(width 0.18288)
		(layer "In11.Cu")
		(net "M_H_CPU0_SA_DQS_DP<6>")
	)
	(segment
		(start 425.028614 -308.240938)
		(end 424.567858 -308.240938)
		(width 0.18288)
		(layer "In11.Cu")
		(net "M_H_CPU0_SA_DQS_DP<6>")
	)
	(segment
		(start 374.822212 -275.8948)
		(end 374.822212 -275.876258)
		(width 0.088646)
		(layer "In11.Cu")
		(net "M_H_CPU0_SA_DQS_DP<6>")
	)
	(segment
		(start 378.683774 -278.654764)
		(end 378.67336 -278.66086)
		(width 0.088646)
		(layer "In11.Cu")
		(net "M_H_CPU0_SA_DQS_DP<6>")
	)
	(segment
		(start 440.121294 -308.240938)
		(end 439.655458 -308.240938)
		(width 0.18288)
		(layer "In11.Cu")
		(net "M_H_CPU0_SA_DQS_DP<6>")
	)
	(segment
		(start 405.832564 -305.689508)
		(end 405.471884 -305.689508)
		(width 0.18288)
		(layer "In11.Cu")
		(net "M_H_CPU0_SA_DQS_DP<6>")
	)
	(segment
		(start 375.479818 -277.032974)
		(end 375.470928 -277.027894)
		(width 0.088646)
		(layer "In11.Cu")
		(net "M_H_CPU0_SA_DQS_DP<6>")
	)
	(segment
		(start 447.918332 -303.034954)
		(end 447.918332 -303.889918)
		(width 0.18288)
		(layer "In11.Cu")
		(net "M_H_CPU0_SA_DQS_DP<6>")
	)
	(segment
		(start 436.619904 -307.682646)
		(end 436.30215 -307.682646)
		(width 0.18288)
		(layer "In11.Cu")
		(net "M_H_CPU0_SA_DQS_DP<6>")
	)
	(segment
		(start 420.46779 -309.091076)
		(end 420.168832 -309.390034)
		(width 0.18288)
		(layer "In11.Cu")
		(net "M_H_CPU0_SA_DQS_DP<6>")
	)
	(segment
		(start 384.407664 -279.474676)
		(end 384.398774 -279.469596)
		(width 0.088646)
		(layer "In11.Cu")
		(net "M_H_CPU0_SA_DQS_DP<6>")
	)
	(segment
		(start 436.30215 -307.682646)
		(end 436.010558 -307.391054)
		(width 0.18288)
		(layer "In11.Cu")
		(net "M_H_CPU0_SA_DQS_DP<6>")
	)
	(segment
		(start 406.109424 -305.966368)
		(end 405.832564 -305.689508)
		(width 0.18288)
		(layer "In11.Cu")
		(net "M_H_CPU0_SA_DQS_DP<6>")
	)
	(segment
		(start 454.746614 -302.131222)
		(end 454.333864 -302.131222)
		(width 0.18288)
		(layer "In11.Cu")
		(net "M_H_CPU0_SA_DQS_DP<6>")
	)
	(segment
		(start 442.470794 -307.474112)
		(end 441.692538 -307.474112)
		(width 0.18288)
		(layer "In11.Cu")
		(net "M_H_CPU0_SA_DQS_DP<6>")
	)
	(segment
		(start 388.249668 -284.152848)
		(end 388.249668 -283.87167)
		(width 0.18288)
		(layer "In11.Cu")
		(net "M_H_CPU0_SA_DQS_DP<6>")
	)
	(segment
		(start 427.731936 -307.91277)
		(end 426.734478 -307.91277)
		(width 0.18288)
		(layer "In11.Cu")
		(net "M_H_CPU0_SA_DQS_DP<6>")
	)
	(segment
		(start 416.267392 -306.693062)
		(end 412.84525 -306.693062)
		(width 0.18288)
		(layer "In11.Cu")
		(net "M_H_CPU0_SA_DQS_DP<6>")
	)
	(segment
		(start 375.009664 -276.219158)
		(end 375.00814 -276.218396)
		(width 0.088646)
		(layer "In11.Cu")
		(net "M_H_CPU0_SA_DQS_DP<6>")
	)
	(segment
		(start 447.918332 -303.889918)
		(end 447.412364 -304.395886)
		(width 0.18288)
		(layer "In11.Cu")
		(net "M_H_CPU0_SA_DQS_DP<6>")
	)
	(segment
		(start 405.211788 -305.949604)
		(end 404.96871 -305.949604)
		(width 0.18288)
		(layer "In11.Cu")
		(net "M_H_CPU0_SA_DQS_DP<6>")
	)
	(segment
		(start 384.690112 -279.964134)
		(end 384.690112 -279.954228)
		(width 0.088646)
		(layer "In11.Cu")
		(net "M_H_CPU0_SA_DQS_DP<6>")
	)
	(segment
		(start 404.96871 -305.949604)
		(end 402.813012 -303.793906)
		(width 0.18288)
		(layer "In11.Cu")
		(net "M_H_CPU0_SA_DQS_DP<6>")
	)
	(segment
		(start 420.941246 -309.091076)
		(end 420.46779 -309.091076)
		(width 0.18288)
		(layer "In11.Cu")
		(net "M_H_CPU0_SA_DQS_DP<6>")
	)
	(segment
		(start 384.220212 -279.150318)
		(end 384.220212 -279.140412)
		(width 0.088646)
		(layer "In11.Cu")
		(net "M_H_CPU0_SA_DQS_DP<6>")
	)
	(segment
		(start 449.24218 -301.711106)
		(end 447.918332 -303.034954)
		(width 0.18288)
		(layer "In11.Cu")
		(net "M_H_CPU0_SA_DQS_DP<6>")
	)
	(segment
		(start 451.139814 -301.441358)
		(end 450.985636 -301.441358)
		(width 0.18288)
		(layer "In11.Cu")
		(net "M_H_CPU0_SA_DQS_DP<6>")
	)
	(segment
		(start 388.190486 -283.603446)
		(end 387.052312 -282.465272)
		(width 0.088646)
		(layer "In11.Cu")
		(net "M_H_CPU0_SA_DQS_DP<6>")
	)
	(segment
		(start 418.01669 -307.813456)
		(end 417.387786 -307.813456)
		(width 0.18288)
		(layer "In11.Cu")
		(net "M_H_CPU0_SA_DQS_DP<6>")
	)
	(segment
		(start 388.249668 -283.87167)
		(end 388.190486 -283.812488)
		(width 0.088646)
		(layer "In11.Cu")
		(net "M_H_CPU0_SA_DQS_DP<6>")
	)
	(segment
		(start 440.400694 -308.520338)
		(end 440.121294 -308.240938)
		(width 0.18288)
		(layer "In11.Cu")
		(net "M_H_CPU0_SA_DQS_DP<6>")
	)
	(segment
		(start 412.129732 -307.40858)
		(end 408.539188 -307.40858)
		(width 0.18288)
		(layer "In11.Cu")
		(net "M_H_CPU0_SA_DQS_DP<6>")
	)
	(segment
		(start 447.121788 -304.395886)
		(end 446.156588 -305.361086)
		(width 0.18288)
		(layer "In11.Cu")
		(net "M_H_CPU0_SA_DQS_DP<6>")
	)
	(segment
		(start 443.830964 -306.758086)
		(end 443.18682 -306.758086)
		(width 0.18288)
		(layer "In11.Cu")
		(net "M_H_CPU0_SA_DQS_DP<6>")
	)
	(segment
		(start 374.393714 -275.323046)
		(end 374.23725 -275.205698)
		(width 0.088646)
		(layer "In11.Cu")
		(net "M_H_CPU0_SA_DQS_DP<6>")
	)
	(segment
		(start 402.813012 -303.793906)
		(end 402.813012 -300.23943)
		(width 0.18288)
		(layer "In11.Cu")
		(net "M_H_CPU0_SA_DQS_DP<6>")
	)
	(segment
		(start 381.503428 -278.654764)
		(end 381.493014 -278.66086)
		(width 0.088646)
		(layer "In11.Cu")
		(net "M_H_CPU0_SA_DQS_DP<6>")
	)
	(segment
		(start 436.010558 -307.391054)
		(end 435.616858 -307.391054)
		(width 0.18288)
		(layer "In11.Cu")
		(net "M_H_CPU0_SA_DQS_DP<6>")
	)
	(segment
		(start 375.012458 -276.220682)
		(end 375.009664 -276.219158)
		(width 0.088646)
		(layer "In11.Cu")
		(net "M_H_CPU0_SA_DQS_DP<6>")
	)
	(segment
		(start 455.011282 -301.866554)
		(end 454.746614 -302.131222)
		(width 0.18288)
		(layer "In11.Cu")
		(net "M_H_CPU0_SA_DQS_DP<6>")
	)
	(segment
		(start 407.096976 -305.966368)
		(end 406.109424 -305.966368)
		(width 0.18288)
		(layer "In11.Cu")
		(net "M_H_CPU0_SA_DQS_DP<6>")
	)
	(segment
		(start 378.298964 -278.66086)
		(end 378.28855 -278.654764)
		(width 0.088646)
		(layer "In11.Cu")
		(net "M_H_CPU0_SA_DQS_DP<6>")
	)
	(segment
		(start 424.567858 -308.240938)
		(end 424.261534 -308.547262)
		(width 0.18288)
		(layer "In11.Cu")
		(net "M_H_CPU0_SA_DQS_DP<6>")
	)
	(segment
		(start 388.190486 -283.812488)
		(end 388.190486 -283.603446)
		(width 0.088646)
		(layer "In11.Cu")
		(net "M_H_CPU0_SA_DQS_DP<6>")
	)
	(segment
		(start 373.417338 -275.02358)
		(end 373.360188 -275.08073)
		(width 0.088646)
		(layer "In11.Cu")
		(net "M_H_CPU0_SA_DQS_DP<6>")
	)
	(segment
		(start 422.184576 -308.547262)
		(end 421.365426 -309.366412)
		(width 0.18288)
		(layer "In11.Cu")
		(net "M_H_CPU0_SA_DQS_DP<6>")
	)
	(segment
		(start 445.227964 -305.361086)
		(end 443.830964 -306.758086)
		(width 0.18288)
		(layer "In11.Cu")
		(net "M_H_CPU0_SA_DQS_DP<6>")
	)
	(segment
		(start 374.225566 -275.194014)
		(end 374.162066 -275.08073)
		(width 0.088646)
		(layer "In11.Cu")
		(net "M_H_CPU0_SA_DQS_DP<6>")
	)
	(segment
		(start 428.337472 -308.518306)
		(end 427.731936 -307.91277)
		(width 0.18288)
		(layer "In11.Cu")
		(net "M_H_CPU0_SA_DQS_DP<6>")
	)
	(segment
		(start 435.616858 -307.391054)
		(end 435.313328 -307.694584)
		(width 0.18288)
		(layer "In11.Cu")
		(net "M_H_CPU0_SA_DQS_DP<6>")
	)
	(segment
		(start 439.655458 -308.240938)
		(end 439.352944 -308.54269)
		(width 0.18288)
		(layer "In11.Cu")
		(net "M_H_CPU0_SA_DQS_DP<6>")
	)
	(segment
		(start 430.97958 -308.518306)
		(end 428.337472 -308.518306)
		(width 0.18288)
		(layer "In11.Cu")
		(net "M_H_CPU0_SA_DQS_DP<6>")
	)
	(segment
		(start 377.171966 -278.336502)
		(end 377.171966 -278.322278)
		(width 0.088646)
		(layer "In11.Cu")
		(net "M_H_CPU0_SA_DQS_DP<6>")
	)
	(segment
		(start 451.41515 -301.716694)
		(end 451.139814 -301.441358)
		(width 0.18288)
		(layer "In11.Cu")
		(net "M_H_CPU0_SA_DQS_DP<6>")
	)
	(segment
		(start 450.985636 -301.441358)
		(end 450.852286 -301.441358)
		(width 0.16002)
		(layer "In11.Cu")
		(net "M_H_CPU0_SA_DQS_DP<6>")
	)
	(segment
		(start 431.803302 -307.694584)
		(end 430.97958 -308.518306)
		(width 0.18288)
		(layer "In11.Cu")
		(net "M_H_CPU0_SA_DQS_DP<6>")
	)
	(segment
		(start 424.261534 -308.547262)
		(end 422.184576 -308.547262)
		(width 0.18288)
		(layer "In11.Cu")
		(net "M_H_CPU0_SA_DQS_DP<6>")
	)
	(segment
		(start 417.387786 -307.813456)
		(end 416.267392 -306.693062)
		(width 0.18288)
		(layer "In11.Cu")
		(net "M_H_CPU0_SA_DQS_DP<6>")
	)
	(segment
		(start 450.452744 -301.711106)
		(end 449.24218 -301.711106)
		(width 0.18288)
		(layer "In11.Cu")
		(net "M_H_CPU0_SA_DQS_DP<6>")
	)
	(segment
		(start 425.329604 -308.541928)
		(end 425.028614 -308.240938)
		(width 0.18288)
		(layer "In11.Cu")
		(net "M_H_CPU0_SA_DQS_DP<6>")
	)
	(segment
		(start 374.539764 -275.405088)
		(end 374.393714 -275.323046)
		(width 0.088646)
		(layer "In11.Cu")
		(net "M_H_CPU0_SA_DQS_DP<6>")
	)
	(segment
		(start 421.216582 -309.366412)
		(end 420.941246 -309.091076)
		(width 0.18288)
		(layer "In11.Cu")
		(net "M_H_CPU0_SA_DQS_DP<6>")
	)
	(segment
		(start 408.539188 -307.40858)
		(end 407.096976 -305.966368)
		(width 0.18288)
		(layer "In11.Cu")
		(net "M_H_CPU0_SA_DQS_DP<6>")
	)
	(segment
		(start 374.23725 -275.205698)
		(end 374.225566 -275.194014)
		(width 0.088646)
		(layer "In11.Cu")
		(net "M_H_CPU0_SA_DQS_DP<6>")
	)
	(segment
		(start 446.156588 -305.361086)
		(end 445.227964 -305.361086)
		(width 0.18288)
		(layer "In11.Cu")
		(net "M_H_CPU0_SA_DQS_DP<6>")
	)
	(segment
		(start 437.479948 -308.54269)
		(end 436.619904 -307.682646)
		(width 0.18288)
		(layer "In11.Cu")
		(net "M_H_CPU0_SA_DQS_DP<6>")
	)
	(segment
		(start 387.052312 -281.840178)
		(end 386.404358 -281.192224)
		(width 0.088646)
		(layer "In11.Cu")
		(net "M_H_CPU0_SA_DQS_DP<6>")
	)
	(segment
		(start 375.762012 -277.522432)
		(end 375.762012 -277.506938)
		(width 0.088646)
		(layer "In11.Cu")
		(net "M_H_CPU0_SA_DQS_DP<6>")
	)
	(segment
		(start 375.00814 -276.218396)
		(end 375.000774 -276.214078)
		(width 0.088646)
		(layer "In11.Cu")
		(net "M_H_CPU0_SA_DQS_DP<6>")
	)
	(arc
		(start 374.822212 -275.876258)
		(mid 374.74205 -275.604069)
		(end 374.539764 -275.405088)
		(width 0.088646)
		(layer "In11.Cu")
		(net "M_H_CPU0_SA_DQS_DP<6>")
	)
	(arc
		(start 375.292366 -276.708616)
		(mid 375.218375 -276.42905)
		(end 375.01576 -276.222714)
		(width 0.088646)
		(layer "In11.Cu")
		(net "M_H_CPU0_SA_DQS_DP<6>")
	)
	(arc
		(start 380.553214 -278.66086)
		(mid 380.366016 -278.711003)
		(end 380.178818 -278.66086)
		(width 0.088646)
		(layer "In11.Cu")
		(net "M_H_CPU0_SA_DQS_DP<6>")
	)
	(arc
		(start 374.162066 -275.08073)
		(mid 373.816091 -274.706925)
		(end 373.417338 -275.02358)
		(width 0.088646)
		(layer "In11.Cu")
		(net "M_H_CPU0_SA_DQS_DP<6>")
	)
	(arc
		(start 380.178818 -278.66086)
		(mid 379.896116 -278.585084)
		(end 379.613414 -278.66086)
		(width 0.088646)
		(layer "In11.Cu")
		(net "M_H_CPU0_SA_DQS_DP<6>")
	)
	(arc
		(start 375.470928 -277.027894)
		(mid 375.340014 -276.891534)
		(end 375.292366 -276.708616)
		(width 0.088646)
		(layer "In11.Cu")
		(net "M_H_CPU0_SA_DQS_DP<6>")
	)
	(arc
		(start 384.220212 -279.140412)
		(mid 383.933337 -278.658327)
		(end 383.37236 -278.66086)
		(width 0.088646)
		(layer "In11.Cu")
		(net "M_H_CPU0_SA_DQS_DP<6>")
	)
	(arc
		(start 379.239018 -278.66086)
		(mid 378.962205 -278.58499)
		(end 378.683774 -278.654764)
		(width 0.088646)
		(layer "In11.Cu")
		(net "M_H_CPU0_SA_DQS_DP<6>")
	)
	(arc
		(start 382.058164 -278.66086)
		(mid 381.781605 -278.585117)
		(end 381.503428 -278.654764)
		(width 0.088646)
		(layer "In11.Cu")
		(net "M_H_CPU0_SA_DQS_DP<6>")
	)
	(arc
		(start 381.118618 -278.66086)
		(mid 380.835916 -278.585084)
		(end 380.553214 -278.66086)
		(width 0.088646)
		(layer "In11.Cu")
		(net "M_H_CPU0_SA_DQS_DP<6>")
	)
	(arc
		(start 382.43256 -278.66086)
		(mid 382.245362 -278.711003)
		(end 382.058164 -278.66086)
		(width 0.088646)
		(layer "In11.Cu")
		(net "M_H_CPU0_SA_DQS_DP<6>")
	)
	(arc
		(start 378.67336 -278.66086)
		(mid 378.486162 -278.711003)
		(end 378.298964 -278.66086)
		(width 0.088646)
		(layer "In11.Cu")
		(net "M_H_CPU0_SA_DQS_DP<6>")
	)
	(arc
		(start 382.997964 -278.66086)
		(mid 382.715262 -278.585084)
		(end 382.43256 -278.66086)
		(width 0.088646)
		(layer "In11.Cu")
		(net "M_H_CPU0_SA_DQS_DP<6>")
	)
	(arc
		(start 383.37236 -278.66086)
		(mid 383.185162 -278.711003)
		(end 382.997964 -278.66086)
		(width 0.088646)
		(layer "In11.Cu")
		(net "M_H_CPU0_SA_DQS_DP<6>")
	)
	(arc
		(start 384.398774 -279.469596)
		(mid 384.26786 -279.333236)
		(end 384.220212 -279.150318)
		(width 0.088646)
		(layer "In11.Cu")
		(net "M_H_CPU0_SA_DQS_DP<6>")
	)
	(arc
		(start 386.404358 -281.192224)
		(mid 386.344805 -281.140458)
		(end 386.278628 -281.097482)
		(width 0.088646)
		(layer "In11.Cu")
		(net "M_H_CPU0_SA_DQS_DP<6>")
	)
	(arc
		(start 381.493014 -278.66086)
		(mid 381.305816 -278.711003)
		(end 381.118618 -278.66086)
		(width 0.088646)
		(layer "In11.Cu")
		(net "M_H_CPU0_SA_DQS_DP<6>")
	)
	(arc
		(start 375.000774 -276.214078)
		(mid 374.86986 -276.077718)
		(end 374.822212 -275.8948)
		(width 0.088646)
		(layer "In11.Cu")
		(net "M_H_CPU0_SA_DQS_DP<6>")
	)
	(arc
		(start 378.28855 -278.654764)
		(mid 378.010372 -278.585041)
		(end 377.733814 -278.66086)
		(width 0.088646)
		(layer "In11.Cu")
		(net "M_H_CPU0_SA_DQS_DP<6>")
	)
	(arc
		(start 386.100066 -280.76398)
		(mid 385.811284 -280.284884)
		(end 385.25196 -280.288492)
		(width 0.088646)
		(layer "In11.Cu")
		(net "M_H_CPU0_SA_DQS_DP<6>")
	)
	(arc
		(start 386.278628 -281.097482)
		(mid 386.147714 -280.961122)
		(end 386.100066 -280.778204)
		(width 0.088646)
		(layer "In11.Cu")
		(net "M_H_CPU0_SA_DQS_DP<6>")
	)
	(arc
		(start 376.32386 -277.84679)
		(mid 375.949385 -277.846744)
		(end 375.762012 -277.522432)
		(width 0.088646)
		(layer "In11.Cu")
		(net "M_H_CPU0_SA_DQS_DP<6>")
	)
	(arc
		(start 375.762012 -277.506938)
		(mid 375.682642 -277.233204)
		(end 375.479818 -277.032974)
		(width 0.088646)
		(layer "In11.Cu")
		(net "M_H_CPU0_SA_DQS_DP<6>")
	)
	(arc
		(start 377.733814 -278.66086)
		(mid 377.359339 -278.660814)
		(end 377.171966 -278.336502)
		(width 0.088646)
		(layer "In11.Cu")
		(net "M_H_CPU0_SA_DQS_DP<6>")
	)
	(arc
		(start 385.25196 -280.288492)
		(mid 384.877485 -280.288446)
		(end 384.690112 -279.964134)
		(width 0.088646)
		(layer "In11.Cu")
		(net "M_H_CPU0_SA_DQS_DP<6>")
	)
	(arc
		(start 379.613414 -278.66086)
		(mid 379.426216 -278.711003)
		(end 379.239018 -278.66086)
		(width 0.088646)
		(layer "In11.Cu")
		(net "M_H_CPU0_SA_DQS_DP<6>")
	)
	(arc
		(start 377.171966 -278.322278)
		(mid 376.883184 -277.843182)
		(end 376.32386 -277.84679)
		(width 0.088646)
		(layer "In11.Cu")
		(net "M_H_CPU0_SA_DQS_DP<6>")
	)
	(arc
		(start 384.690112 -279.954228)
		(mid 384.612001 -279.677279)
		(end 384.407664 -279.474676)
		(width 0.088646)
		(layer "In11.Cu")
		(net "M_H_CPU0_SA_DQS_DP<6>")
	)
	(segment
		(start 461.14716 -311.039256)
		(end 461.800702 -311.039256)
		(width 0.20066)
		(layer "F.Cu")
		(net "M_H_CPU0_SA_DQS_DP<5>")
	)
	(segment
		(start 456.116182 -311.216802)
		(end 456.70978 -311.216802)
		(width 0.20066)
		(layer "F.Cu")
		(net "M_H_CPU0_SA_DQS_DP<5>")
	)
	(segment
		(start 456.960732 -311.467754)
		(end 457.265532 -311.467754)
		(width 0.20066)
		(layer "F.Cu")
		(net "M_H_CPU0_SA_DQS_DP<5>")
	)
	(segment
		(start 460.570326 -310.784494)
		(end 460.892398 -310.784494)
		(width 0.20066)
		(layer "F.Cu")
		(net "M_H_CPU0_SA_DQS_DP<5>")
	)
	(segment
		(start 376.136916 -277.522178)
		(end 376.136662 -277.522432)
		(width 0.20066)
		(layer "F.Cu")
		(net "M_H_CPU0_SA_DQS_DP<5>")
	)
	(segment
		(start 460.892398 -310.784494)
		(end 461.14716 -311.039256)
		(width 0.20066)
		(layer "F.Cu")
		(net "M_H_CPU0_SA_DQS_DP<5>")
	)
	(segment
		(start 462.823814 -311.484772)
		(end 463.091784 -311.216802)
		(width 0.20066)
		(layer "F.Cu")
		(net "M_H_CPU0_SA_DQS_DP<5>")
	)
	(segment
		(start 462.246218 -311.484772)
		(end 462.823814 -311.484772)
		(width 0.20066)
		(layer "F.Cu")
		(net "M_H_CPU0_SA_DQS_DP<5>")
	)
	(segment
		(start 463.091784 -311.216802)
		(end 463.659982 -311.216802)
		(width 0.20066)
		(layer "F.Cu")
		(net "M_H_CPU0_SA_DQS_DP<5>")
	)
	(segment
		(start 457.690474 -311.042812)
		(end 457.968858 -311.042812)
		(width 0.20066)
		(layer "F.Cu")
		(net "M_H_CPU0_SA_DQS_DP<5>")
	)
	(segment
		(start 458.550264 -310.79186)
		(end 460.56296 -310.79186)
		(width 0.1016)
		(layer "F.Cu")
		(net "M_H_CPU0_SA_DQS_DP<5>")
	)
	(segment
		(start 455.011282 -311.216802)
		(end 456.116182 -311.216802)
		(width 0.20066)
		(layer "F.Cu")
		(net "M_H_CPU0_SA_DQS_DP<5>")
	)
	(segment
		(start 457.265532 -311.467754)
		(end 457.690474 -311.042812)
		(width 0.20066)
		(layer "F.Cu")
		(net "M_H_CPU0_SA_DQS_DP<5>")
	)
	(segment
		(start 458.226922 -310.784748)
		(end 458.538326 -310.784748)
		(width 0.20066)
		(layer "F.Cu")
		(net "M_H_CPU0_SA_DQS_DP<5>")
	)
	(segment
		(start 456.70978 -311.216802)
		(end 456.960732 -311.467754)
		(width 0.20066)
		(layer "F.Cu")
		(net "M_H_CPU0_SA_DQS_DP<5>")
	)
	(segment
		(start 458.538326 -310.784748)
		(end 458.543152 -310.784748)
		(width 0.101854)
		(layer "F.Cu")
		(net "M_H_CPU0_SA_DQS_DP<5>")
	)
	(segment
		(start 460.56296 -310.79186)
		(end 460.570326 -310.784494)
		(width 0.1016)
		(layer "F.Cu")
		(net "M_H_CPU0_SA_DQS_DP<5>")
	)
	(segment
		(start 376.136916 -276.986492)
		(end 376.136916 -277.522178)
		(width 0.20066)
		(layer "F.Cu")
		(net "M_H_CPU0_SA_DQS_DP<5>")
	)
	(segment
		(start 458.543152 -310.784748)
		(end 458.550264 -310.79186)
		(width 0.1016)
		(layer "F.Cu")
		(net "M_H_CPU0_SA_DQS_DP<5>")
	)
	(segment
		(start 457.968858 -311.042812)
		(end 458.226922 -310.784748)
		(width 0.20066)
		(layer "F.Cu")
		(net "M_H_CPU0_SA_DQS_DP<5>")
	)
	(segment
		(start 461.800702 -311.039256)
		(end 462.246218 -311.484772)
		(width 0.20066)
		(layer "F.Cu")
		(net "M_H_CPU0_SA_DQS_DP<5>")
	)
	(segment
		(start 386.099812 -277.522432)
		(end 386.099812 -277.512526)
		(width 0.088646)
		(layer "In6.Cu")
		(net "M_H_CPU0_SA_DQS_DP<5>")
	)
	(segment
		(start 377.73483 -277.032466)
		(end 377.728988 -277.035768)
		(width 0.088646)
		(layer "In6.Cu")
		(net "M_H_CPU0_SA_DQS_DP<5>")
	)
	(segment
		(start 442.966094 -310.449214)
		(end 442.566552 -310.848756)
		(width 0.18288)
		(layer "In6.Cu")
		(net "M_H_CPU0_SA_DQS_DP<5>")
	)
	(segment
		(start 445.88176 -311.736994)
		(end 445.283082 -311.736994)
		(width 0.18288)
		(layer "In6.Cu")
		(net "M_H_CPU0_SA_DQS_DP<5>")
	)
	(segment
		(start 424.643042 -306.543456)
		(end 424.36161 -306.824888)
		(width 0.18288)
		(layer "In6.Cu")
		(net "M_H_CPU0_SA_DQS_DP<5>")
	)
	(segment
		(start 404.780496 -300.622208)
		(end 396.91183 -292.753542)
		(width 0.18288)
		(layer "In6.Cu")
		(net "M_H_CPU0_SA_DQS_DP<5>")
	)
	(segment
		(start 452.17969 -311.070752)
		(end 451.366382 -311.070752)
		(width 0.18288)
		(layer "In6.Cu")
		(net "M_H_CPU0_SA_DQS_DP<5>")
	)
	(segment
		(start 454.74763 -311.480454)
		(end 453.981566 -311.480454)
		(width 0.18288)
		(layer "In6.Cu")
		(net "M_H_CPU0_SA_DQS_DP<5>")
	)
	(segment
		(start 451.366382 -311.070752)
		(end 451.088252 -310.792622)
		(width 0.18288)
		(layer "In6.Cu")
		(net "M_H_CPU0_SA_DQS_DP<5>")
	)
	(segment
		(start 377.099322 -277.126192)
		(end 377.07951 -277.130256)
		(width 0.088646)
		(layer "In6.Cu")
		(net "M_H_CPU0_SA_DQS_DP<5>")
	)
	(segment
		(start 377.695714 -277.053548)
		(end 377.585224 -277.099522)
		(width 0.088646)
		(layer "In6.Cu")
		(net "M_H_CPU0_SA_DQS_DP<5>")
	)
	(segment
		(start 409.92552 -303.14265)
		(end 409.573984 -303.14265)
		(width 0.18288)
		(layer "In6.Cu")
		(net "M_H_CPU0_SA_DQS_DP<5>")
	)
	(segment
		(start 405.4602 -303.988216)
		(end 405.166576 -304.28184)
		(width 0.18288)
		(layer "In6.Cu")
		(net "M_H_CPU0_SA_DQS_DP<5>")
	)
	(segment
		(start 405.836882 -303.988216)
		(end 405.4602 -303.988216)
		(width 0.18288)
		(layer "In6.Cu")
		(net "M_H_CPU0_SA_DQS_DP<5>")
	)
	(segment
		(start 388.040626 -279.751536)
		(end 387.945122 -279.522174)
		(width 0.088646)
		(layer "In6.Cu")
		(net "M_H_CPU0_SA_DQS_DP<5>")
	)
	(segment
		(start 452.757794 -311.648856)
		(end 452.17969 -311.070752)
		(width 0.18288)
		(layer "In6.Cu")
		(net "M_H_CPU0_SA_DQS_DP<5>")
	)
	(segment
		(start 382.447546 -277.024338)
		(end 382.432814 -277.032974)
		(width 0.088646)
		(layer "In6.Cu")
		(net "M_H_CPU0_SA_DQS_DP<5>")
	)
	(segment
		(start 388.283958 -279.77592)
		(end 388.224268 -279.83561)
		(width 0.088646)
		(layer "In6.Cu")
		(net "M_H_CPU0_SA_DQS_DP<5>")
	)
	(segment
		(start 436.573676 -311.055512)
		(end 436.267606 -311.055512)
		(width 0.18288)
		(layer "In6.Cu")
		(net "M_H_CPU0_SA_DQS_DP<5>")
	)
	(segment
		(start 414.954466 -306.811426)
		(end 413.110426 -304.967386)
		(width 0.18288)
		(layer "In6.Cu")
		(net "M_H_CPU0_SA_DQS_DP<5>")
	)
	(segment
		(start 377.099322 -277.126446)
		(end 377.099322 -277.126192)
		(width 0.088646)
		(layer "In6.Cu")
		(net "M_H_CPU0_SA_DQS_DP<5>")
	)
	(segment
		(start 379.623828 -277.026878)
		(end 379.613414 -277.032974)
		(width 0.088646)
		(layer "In6.Cu")
		(net "M_H_CPU0_SA_DQS_DP<5>")
	)
	(segment
		(start 388.1247 -279.83561)
		(end 388.040626 -279.751536)
		(width 0.088646)
		(layer "In6.Cu")
		(net "M_H_CPU0_SA_DQS_DP<5>")
	)
	(segment
		(start 410.190696 -303.407826)
		(end 409.92552 -303.14265)
		(width 0.18288)
		(layer "In6.Cu")
		(net "M_H_CPU0_SA_DQS_DP<5>")
	)
	(segment
		(start 453.574912 -311.648856)
		(end 452.757794 -311.648856)
		(width 0.18288)
		(layer "In6.Cu")
		(net "M_H_CPU0_SA_DQS_DP<5>")
	)
	(segment
		(start 443.995302 -310.449214)
		(end 442.966094 -310.449214)
		(width 0.18288)
		(layer "In6.Cu")
		(net "M_H_CPU0_SA_DQS_DP<5>")
	)
	(segment
		(start 386.287264 -277.84679)
		(end 386.278374 -277.84171)
		(width 0.088646)
		(layer "In6.Cu")
		(net "M_H_CPU0_SA_DQS_DP<5>")
	)
	(segment
		(start 376.649234 -277.522432)
		(end 376.136662 -277.522432)
		(width 0.088646)
		(layer "In6.Cu")
		(net "M_H_CPU0_SA_DQS_DP<5>")
	)
	(segment
		(start 422.289732 -306.824888)
		(end 421.469566 -307.645054)
		(width 0.18288)
		(layer "In6.Cu")
		(net "M_H_CPU0_SA_DQS_DP<5>")
	)
	(segment
		(start 421.22217 -307.645054)
		(end 420.969948 -307.392832)
		(width 0.18288)
		(layer "In6.Cu")
		(net "M_H_CPU0_SA_DQS_DP<5>")
	)
	(segment
		(start 413.110426 -304.967386)
		(end 412.759398 -304.967386)
		(width 0.18288)
		(layer "In6.Cu")
		(net "M_H_CPU0_SA_DQS_DP<5>")
	)
	(segment
		(start 445.283082 -311.736994)
		(end 443.995302 -310.449214)
		(width 0.18288)
		(layer "In6.Cu")
		(net "M_H_CPU0_SA_DQS_DP<5>")
	)
	(segment
		(start 407.717244 -303.425606)
		(end 406.86609 -304.27676)
		(width 0.18288)
		(layer "In6.Cu")
		(net "M_H_CPU0_SA_DQS_DP<5>")
	)
	(segment
		(start 388.464806 -279.77592)
		(end 388.307326 -279.77592)
		(width 0.18288)
		(layer "In6.Cu")
		(net "M_H_CPU0_SA_DQS_DP<5>")
	)
	(segment
		(start 411.199838 -303.407826)
		(end 410.190696 -303.407826)
		(width 0.18288)
		(layer "In6.Cu")
		(net "M_H_CPU0_SA_DQS_DP<5>")
	)
	(segment
		(start 377.728988 -277.035768)
		(end 377.696476 -277.05304)
		(width 0.088646)
		(layer "In6.Cu")
		(net "M_H_CPU0_SA_DQS_DP<5>")
	)
	(segment
		(start 383.387092 -277.024338)
		(end 383.37236 -277.032974)
		(width 0.088646)
		(layer "In6.Cu")
		(net "M_H_CPU0_SA_DQS_DP<5>")
	)
	(segment
		(start 396.91183 -283.150056)
		(end 393.75207 -279.990296)
		(width 0.18288)
		(layer "In6.Cu")
		(net "M_H_CPU0_SA_DQS_DP<5>")
	)
	(segment
		(start 425.280328 -306.800758)
		(end 425.023026 -306.543456)
		(width 0.18288)
		(layer "In6.Cu")
		(net "M_H_CPU0_SA_DQS_DP<5>")
	)
	(segment
		(start 437.398668 -310.23052)
		(end 436.573676 -311.055512)
		(width 0.18288)
		(layer "In6.Cu")
		(net "M_H_CPU0_SA_DQS_DP<5>")
	)
	(segment
		(start 425.023026 -306.543456)
		(end 424.643042 -306.543456)
		(width 0.18288)
		(layer "In6.Cu")
		(net "M_H_CPU0_SA_DQS_DP<5>")
	)
	(segment
		(start 388.982458 -279.990296)
		(end 388.464806 -279.77592)
		(width 0.18288)
		(layer "In6.Cu")
		(net "M_H_CPU0_SA_DQS_DP<5>")
	)
	(segment
		(start 387.134608 -278.71166)
		(end 386.944108 -278.71166)
		(width 0.088646)
		(layer "In6.Cu")
		(net "M_H_CPU0_SA_DQS_DP<5>")
	)
	(segment
		(start 430.404524 -310.131206)
		(end 428.880524 -308.607206)
		(width 0.18288)
		(layer "In6.Cu")
		(net "M_H_CPU0_SA_DQS_DP<5>")
	)
	(segment
		(start 440.368436 -310.20893)
		(end 440.100466 -309.94096)
		(width 0.18288)
		(layer "In6.Cu")
		(net "M_H_CPU0_SA_DQS_DP<5>")
	)
	(segment
		(start 425.949872 -306.800758)
		(end 425.280328 -306.800758)
		(width 0.18288)
		(layer "In6.Cu")
		(net "M_H_CPU0_SA_DQS_DP<5>")
	)
	(segment
		(start 386.569712 -278.336502)
		(end 386.569712 -278.31796)
		(width 0.088646)
		(layer "In6.Cu")
		(net "M_H_CPU0_SA_DQS_DP<5>")
	)
	(segment
		(start 416.89782 -307.717952)
		(end 415.991294 -306.811426)
		(width 0.18288)
		(layer "In6.Cu")
		(net "M_H_CPU0_SA_DQS_DP<5>")
	)
	(segment
		(start 377.84024 -276.98319)
		(end 377.794266 -277.002748)
		(width 0.088646)
		(layer "In6.Cu")
		(net "M_H_CPU0_SA_DQS_DP<5>")
	)
	(segment
		(start 436.267606 -311.055512)
		(end 436.004716 -310.792622)
		(width 0.18288)
		(layer "In6.Cu")
		(net "M_H_CPU0_SA_DQS_DP<5>")
	)
	(segment
		(start 378.24918 -277.007574)
		(end 378.203714 -276.987)
		(width 0.088646)
		(layer "In6.Cu")
		(net "M_H_CPU0_SA_DQS_DP<5>")
	)
	(segment
		(start 380.563374 -277.026878)
		(end 380.55296 -277.032974)
		(width 0.088646)
		(layer "In6.Cu")
		(net "M_H_CPU0_SA_DQS_DP<5>")
	)
	(segment
		(start 420.238428 -307.717952)
		(end 416.89782 -307.717952)
		(width 0.18288)
		(layer "In6.Cu")
		(net "M_H_CPU0_SA_DQS_DP<5>")
	)
	(segment
		(start 387.945122 -279.522174)
		(end 387.134608 -278.71166)
		(width 0.088646)
		(layer "In6.Cu")
		(net "M_H_CPU0_SA_DQS_DP<5>")
	)
	(segment
		(start 381.507746 -277.024338)
		(end 381.493014 -277.032974)
		(width 0.088646)
		(layer "In6.Cu")
		(net "M_H_CPU0_SA_DQS_DP<5>")
	)
	(segment
		(start 455.011282 -311.216802)
		(end 454.74763 -311.480454)
		(width 0.18288)
		(layer "In6.Cu")
		(net "M_H_CPU0_SA_DQS_DP<5>")
	)
	(segment
		(start 424.36161 -306.824888)
		(end 422.289732 -306.824888)
		(width 0.18288)
		(layer "In6.Cu")
		(net "M_H_CPU0_SA_DQS_DP<5>")
	)
	(segment
		(start 446.547494 -311.07126)
		(end 445.88176 -311.736994)
		(width 0.18288)
		(layer "In6.Cu")
		(net "M_H_CPU0_SA_DQS_DP<5>")
	)
	(segment
		(start 441.945268 -310.848756)
		(end 441.305442 -310.20893)
		(width 0.18288)
		(layer "In6.Cu")
		(net "M_H_CPU0_SA_DQS_DP<5>")
	)
	(segment
		(start 426.533818 -307.384704)
		(end 425.949872 -306.800758)
		(width 0.18288)
		(layer "In6.Cu")
		(net "M_H_CPU0_SA_DQS_DP<5>")
	)
	(segment
		(start 376.706384 -277.465282)
		(end 376.649234 -277.522432)
		(width 0.088646)
		(layer "In6.Cu")
		(net "M_H_CPU0_SA_DQS_DP<5>")
	)
	(segment
		(start 435.632352 -310.792622)
		(end 435.365652 -311.059322)
		(width 0.18288)
		(layer "In6.Cu")
		(net "M_H_CPU0_SA_DQS_DP<5>")
	)
	(segment
		(start 396.91183 -292.753542)
		(end 396.91183 -283.150056)
		(width 0.18288)
		(layer "In6.Cu")
		(net "M_H_CPU0_SA_DQS_DP<5>")
	)
	(segment
		(start 450.732144 -310.792622)
		(end 450.453506 -311.07126)
		(width 0.18288)
		(layer "In6.Cu")
		(net "M_H_CPU0_SA_DQS_DP<5>")
	)
	(segment
		(start 376.88774 -277.198836)
		(end 376.880374 -277.203154)
		(width 0.088646)
		(layer "In6.Cu")
		(net "M_H_CPU0_SA_DQS_DP<5>")
	)
	(segment
		(start 439.743342 -309.94096)
		(end 439.453782 -310.23052)
		(width 0.18288)
		(layer "In6.Cu")
		(net "M_H_CPU0_SA_DQS_DP<5>")
	)
	(segment
		(start 377.07951 -277.130256)
		(end 377.029726 -277.15083)
		(width 0.088646)
		(layer "In6.Cu")
		(net "M_H_CPU0_SA_DQS_DP<5>")
	)
	(segment
		(start 388.224268 -279.83561)
		(end 388.1247 -279.83561)
		(width 0.088646)
		(layer "In6.Cu")
		(net "M_H_CPU0_SA_DQS_DP<5>")
	)
	(segment
		(start 377.696476 -277.05304)
		(end 377.695714 -277.053548)
		(width 0.088646)
		(layer "In6.Cu")
		(net "M_H_CPU0_SA_DQS_DP<5>")
	)
	(segment
		(start 435.365652 -311.059322)
		(end 432.284632 -311.059322)
		(width 0.18288)
		(layer "In6.Cu")
		(net "M_H_CPU0_SA_DQS_DP<5>")
	)
	(segment
		(start 420.563548 -307.392832)
		(end 420.238428 -307.717952)
		(width 0.18288)
		(layer "In6.Cu")
		(net "M_H_CPU0_SA_DQS_DP<5>")
	)
	(segment
		(start 428.207424 -308.607206)
		(end 426.984922 -307.384704)
		(width 0.18288)
		(layer "In6.Cu")
		(net "M_H_CPU0_SA_DQS_DP<5>")
	)
	(segment
		(start 377.585224 -277.099522)
		(end 377.233688 -277.099522)
		(width 0.088646)
		(layer "In6.Cu")
		(net "M_H_CPU0_SA_DQS_DP<5>")
	)
	(segment
		(start 388.307326 -279.77592)
		(end 388.283958 -279.77592)
		(width 0.088646)
		(layer "In6.Cu")
		(net "M_H_CPU0_SA_DQS_DP<5>")
	)
	(segment
		(start 406.86609 -304.27676)
		(end 406.125426 -304.27676)
		(width 0.18288)
		(layer "In6.Cu")
		(net "M_H_CPU0_SA_DQS_DP<5>")
	)
	(segment
		(start 432.284632 -311.059322)
		(end 431.356516 -310.131206)
		(width 0.18288)
		(layer "In6.Cu")
		(net "M_H_CPU0_SA_DQS_DP<5>")
	)
	(segment
		(start 404.780496 -304.049176)
		(end 404.780496 -300.622208)
		(width 0.18288)
		(layer "In6.Cu")
		(net "M_H_CPU0_SA_DQS_DP<5>")
	)
	(segment
		(start 421.469566 -307.645054)
		(end 421.22217 -307.645054)
		(width 0.18288)
		(layer "In6.Cu")
		(net "M_H_CPU0_SA_DQS_DP<5>")
	)
	(segment
		(start 420.969948 -307.392832)
		(end 420.563548 -307.392832)
		(width 0.18288)
		(layer "In6.Cu")
		(net "M_H_CPU0_SA_DQS_DP<5>")
	)
	(segment
		(start 409.291028 -303.425606)
		(end 407.717244 -303.425606)
		(width 0.18288)
		(layer "In6.Cu")
		(net "M_H_CPU0_SA_DQS_DP<5>")
	)
	(segment
		(start 428.880524 -308.607206)
		(end 428.207424 -308.607206)
		(width 0.18288)
		(layer "In6.Cu")
		(net "M_H_CPU0_SA_DQS_DP<5>")
	)
	(segment
		(start 378.249688 -277.007574)
		(end 378.24918 -277.007574)
		(width 0.088646)
		(layer "In6.Cu")
		(net "M_H_CPU0_SA_DQS_DP<5>")
	)
	(segment
		(start 426.984922 -307.384704)
		(end 426.533818 -307.384704)
		(width 0.18288)
		(layer "In6.Cu")
		(net "M_H_CPU0_SA_DQS_DP<5>")
	)
	(segment
		(start 393.75207 -279.990296)
		(end 388.982458 -279.990296)
		(width 0.18288)
		(layer "In6.Cu")
		(net "M_H_CPU0_SA_DQS_DP<5>")
	)
	(segment
		(start 441.305442 -310.20893)
		(end 440.368436 -310.20893)
		(width 0.18288)
		(layer "In6.Cu")
		(net "M_H_CPU0_SA_DQS_DP<5>")
	)
	(segment
		(start 377.233688 -277.099522)
		(end 377.099322 -277.126446)
		(width 0.088646)
		(layer "In6.Cu")
		(net "M_H_CPU0_SA_DQS_DP<5>")
	)
	(segment
		(start 440.100466 -309.94096)
		(end 439.743342 -309.94096)
		(width 0.18288)
		(layer "In6.Cu")
		(net "M_H_CPU0_SA_DQS_DP<5>")
	)
	(segment
		(start 453.981566 -311.480454)
		(end 453.574912 -311.648856)
		(width 0.18288)
		(layer "In6.Cu")
		(net "M_H_CPU0_SA_DQS_DP<5>")
	)
	(segment
		(start 415.991294 -306.811426)
		(end 414.954466 -306.811426)
		(width 0.18288)
		(layer "In6.Cu")
		(net "M_H_CPU0_SA_DQS_DP<5>")
	)
	(segment
		(start 409.573984 -303.14265)
		(end 409.291028 -303.425606)
		(width 0.18288)
		(layer "In6.Cu")
		(net "M_H_CPU0_SA_DQS_DP<5>")
	)
	(segment
		(start 406.125426 -304.27676)
		(end 405.836882 -303.988216)
		(width 0.18288)
		(layer "In6.Cu")
		(net "M_H_CPU0_SA_DQS_DP<5>")
	)
	(segment
		(start 383.37236 -277.032974)
		(end 383.363978 -277.0378)
		(width 0.088646)
		(layer "In6.Cu")
		(net "M_H_CPU0_SA_DQS_DP<5>")
	)
	(segment
		(start 436.004716 -310.792622)
		(end 435.632352 -310.792622)
		(width 0.18288)
		(layer "In6.Cu")
		(net "M_H_CPU0_SA_DQS_DP<5>")
	)
	(segment
		(start 412.759398 -304.967386)
		(end 411.199838 -303.407826)
		(width 0.18288)
		(layer "In6.Cu")
		(net "M_H_CPU0_SA_DQS_DP<5>")
	)
	(segment
		(start 450.453506 -311.07126)
		(end 446.547494 -311.07126)
		(width 0.18288)
		(layer "In6.Cu")
		(net "M_H_CPU0_SA_DQS_DP<5>")
	)
	(segment
		(start 439.453782 -310.23052)
		(end 437.398668 -310.23052)
		(width 0.18288)
		(layer "In6.Cu")
		(net "M_H_CPU0_SA_DQS_DP<5>")
	)
	(segment
		(start 451.088252 -310.792622)
		(end 450.732144 -310.792622)
		(width 0.18288)
		(layer "In6.Cu")
		(net "M_H_CPU0_SA_DQS_DP<5>")
	)
	(segment
		(start 405.01316 -304.28184)
		(end 404.780496 -304.049176)
		(width 0.18288)
		(layer "In6.Cu")
		(net "M_H_CPU0_SA_DQS_DP<5>")
	)
	(segment
		(start 405.166576 -304.28184)
		(end 405.01316 -304.28184)
		(width 0.18288)
		(layer "In6.Cu")
		(net "M_H_CPU0_SA_DQS_DP<5>")
	)
	(segment
		(start 376.889264 -277.198074)
		(end 376.88774 -277.198836)
		(width 0.088646)
		(layer "In6.Cu")
		(net "M_H_CPU0_SA_DQS_DP<5>")
	)
	(segment
		(start 442.566552 -310.848756)
		(end 441.945268 -310.848756)
		(width 0.18288)
		(layer "In6.Cu")
		(net "M_H_CPU0_SA_DQS_DP<5>")
	)
	(segment
		(start 431.356516 -310.131206)
		(end 430.404524 -310.131206)
		(width 0.18288)
		(layer "In6.Cu")
		(net "M_H_CPU0_SA_DQS_DP<5>")
	)
	(arc
		(start 376.880374 -277.203154)
		(mid 376.764565 -277.315083)
		(end 376.706384 -277.465282)
		(width 0.088646)
		(layer "In6.Cu")
		(net "M_H_CPU0_SA_DQS_DP<5>")
	)
	(arc
		(start 382.058418 -277.032974)
		(mid 381.784219 -276.957139)
		(end 381.507746 -277.024338)
		(width 0.088646)
		(layer "In6.Cu")
		(net "M_H_CPU0_SA_DQS_DP<5>")
	)
	(arc
		(start 379.239018 -277.032974)
		(mid 378.956316 -276.957198)
		(end 378.673614 -277.032974)
		(width 0.088646)
		(layer "In6.Cu")
		(net "M_H_CPU0_SA_DQS_DP<5>")
	)
	(arc
		(start 378.673614 -277.032974)
		(mid 378.486416 -277.083117)
		(end 378.299218 -277.032974)
		(width 0.088646)
		(layer "In6.Cu")
		(net "M_H_CPU0_SA_DQS_DP<5>")
	)
	(arc
		(start 380.178564 -277.032974)
		(mid 379.902005 -276.957231)
		(end 379.623828 -277.026878)
		(width 0.088646)
		(layer "In6.Cu")
		(net "M_H_CPU0_SA_DQS_DP<5>")
	)
	(arc
		(start 386.944108 -278.71166)
		(mid 386.847081 -278.698828)
		(end 386.756656 -278.661368)
		(width 0.088646)
		(layer "In6.Cu")
		(net "M_H_CPU0_SA_DQS_DP<5>")
	)
	(arc
		(start 383.937764 -277.032974)
		(mid 383.663565 -276.957139)
		(end 383.387092 -277.024338)
		(width 0.088646)
		(layer "In6.Cu")
		(net "M_H_CPU0_SA_DQS_DP<5>")
	)
	(arc
		(start 379.613414 -277.032974)
		(mid 379.426216 -277.083117)
		(end 379.239018 -277.032974)
		(width 0.088646)
		(layer "In6.Cu")
		(net "M_H_CPU0_SA_DQS_DP<5>")
	)
	(arc
		(start 378.299218 -277.032974)
		(mid 378.274766 -277.019663)
		(end 378.249688 -277.007574)
		(width 0.088646)
		(layer "In6.Cu")
		(net "M_H_CPU0_SA_DQS_DP<5>")
	)
	(arc
		(start 385.25196 -277.032974)
		(mid 385.064762 -277.083117)
		(end 384.877564 -277.032974)
		(width 0.088646)
		(layer "In6.Cu")
		(net "M_H_CPU0_SA_DQS_DP<5>")
	)
	(arc
		(start 380.55296 -277.032974)
		(mid 380.365762 -277.083117)
		(end 380.178564 -277.032974)
		(width 0.088646)
		(layer "In6.Cu")
		(net "M_H_CPU0_SA_DQS_DP<5>")
	)
	(arc
		(start 382.998218 -277.032974)
		(mid 382.724019 -276.957139)
		(end 382.447546 -277.024338)
		(width 0.088646)
		(layer "In6.Cu")
		(net "M_H_CPU0_SA_DQS_DP<5>")
	)
	(arc
		(start 385.817364 -277.032974)
		(mid 385.534662 -276.957198)
		(end 385.25196 -277.032974)
		(width 0.088646)
		(layer "In6.Cu")
		(net "M_H_CPU0_SA_DQS_DP<5>")
	)
	(arc
		(start 384.877564 -277.032974)
		(mid 384.594862 -276.957198)
		(end 384.31216 -277.032974)
		(width 0.088646)
		(layer "In6.Cu")
		(net "M_H_CPU0_SA_DQS_DP<5>")
	)
	(arc
		(start 383.363978 -277.0378)
		(mid 383.18047 -277.083078)
		(end 382.998218 -277.032974)
		(width 0.088646)
		(layer "In6.Cu")
		(net "M_H_CPU0_SA_DQS_DP<5>")
	)
	(arc
		(start 386.569712 -278.31796)
		(mid 386.48955 -278.045771)
		(end 386.287264 -277.84679)
		(width 0.088646)
		(layer "In6.Cu")
		(net "M_H_CPU0_SA_DQS_DP<5>")
	)
	(arc
		(start 382.432814 -277.032974)
		(mid 382.245616 -277.083117)
		(end 382.058418 -277.032974)
		(width 0.088646)
		(layer "In6.Cu")
		(net "M_H_CPU0_SA_DQS_DP<5>")
	)
	(arc
		(start 381.493014 -277.032974)
		(mid 381.305816 -277.083117)
		(end 381.118618 -277.032974)
		(width 0.088646)
		(layer "In6.Cu")
		(net "M_H_CPU0_SA_DQS_DP<5>")
	)
	(arc
		(start 381.118618 -277.032974)
		(mid 380.841805 -276.957104)
		(end 380.563374 -277.026878)
		(width 0.088646)
		(layer "In6.Cu")
		(net "M_H_CPU0_SA_DQS_DP<5>")
	)
	(arc
		(start 377.029726 -277.15083)
		(mid 376.957129 -277.167422)
		(end 376.889264 -277.198074)
		(width 0.088646)
		(layer "In6.Cu")
		(net "M_H_CPU0_SA_DQS_DP<5>")
	)
	(arc
		(start 384.31216 -277.032974)
		(mid 384.124962 -277.083117)
		(end 383.937764 -277.032974)
		(width 0.088646)
		(layer "In6.Cu")
		(net "M_H_CPU0_SA_DQS_DP<5>")
	)
	(arc
		(start 377.794266 -277.002748)
		(mid 377.764109 -277.01673)
		(end 377.73483 -277.032466)
		(width 0.088646)
		(layer "In6.Cu")
		(net "M_H_CPU0_SA_DQS_DP<5>")
	)
	(arc
		(start 386.278374 -277.84171)
		(mid 386.14746 -277.70535)
		(end 386.099812 -277.522432)
		(width 0.088646)
		(layer "In6.Cu")
		(net "M_H_CPU0_SA_DQS_DP<5>")
	)
	(arc
		(start 386.756656 -278.661368)
		(mid 386.752447 -278.658601)
		(end 386.748274 -278.65578)
		(width 0.088646)
		(layer "In6.Cu")
		(net "M_H_CPU0_SA_DQS_DP<5>")
	)
	(arc
		(start 386.099812 -277.512526)
		(mid 386.021701 -277.235577)
		(end 385.817364 -277.032974)
		(width 0.088646)
		(layer "In6.Cu")
		(net "M_H_CPU0_SA_DQS_DP<5>")
	)
	(arc
		(start 386.748274 -278.65578)
		(mid 386.61736 -278.51942)
		(end 386.569712 -278.336502)
		(width 0.088646)
		(layer "In6.Cu")
		(net "M_H_CPU0_SA_DQS_DP<5>")
	)
	(arc
		(start 378.203714 -276.987)
		(mid 378.022368 -276.946865)
		(end 377.84024 -276.98319)
		(width 0.088646)
		(layer "In6.Cu")
		(net "M_H_CPU0_SA_DQS_DP<5>")
	)
	(segment
		(start 454.963276 -275.94179)
		(end 454.937368 -275.94179)
		(width 0.101854)
		(layer "F.Cu")
		(net "M_H_CPU0_SA_DQS_DP<4>")
	)
	(segment
		(start 458.5335 -275.234908)
		(end 458.123036 -275.645372)
		(width 0.20066)
		(layer "F.Cu")
		(net "M_H_CPU0_SA_DQS_DP<4>")
	)
	(segment
		(start 454.937368 -275.94179)
		(end 454.797922 -275.94179)
		(width 0.20066)
		(layer "F.Cu")
		(net "M_H_CPU0_SA_DQS_DP<4>")
	)
	(segment
		(start 459.559914 -275.516594)
		(end 459.011274 -275.516594)
		(width 0.20066)
		(layer "F.Cu")
		(net "M_H_CPU0_SA_DQS_DP<4>")
	)
	(segment
		(start 457.75245 -275.645372)
		(end 457.449936 -275.947886)
		(width 0.20066)
		(layer "F.Cu")
		(net "M_H_CPU0_SA_DQS_DP<4>")
	)
	(segment
		(start 457.449936 -275.947886)
		(end 457.126594 -275.947886)
		(width 0.20066)
		(layer "F.Cu")
		(net "M_H_CPU0_SA_DQS_DP<4>")
	)
	(segment
		(start 457.120498 -275.94179)
		(end 454.963276 -275.94179)
		(width 0.1016)
		(layer "F.Cu")
		(net "M_H_CPU0_SA_DQS_DP<4>")
	)
	(segment
		(start 457.126594 -275.947886)
		(end 457.120498 -275.94179)
		(width 0.1016)
		(layer "F.Cu")
		(net "M_H_CPU0_SA_DQS_DP<4>")
	)
	(segment
		(start 370.967762 -259.894832)
		(end 370.967762 -260.430518)
		(width 0.20066)
		(layer "F.Cu")
		(net "M_H_CPU0_SA_DQS_DP<4>")
	)
	(segment
		(start 458.729588 -275.234908)
		(end 458.5335 -275.234908)
		(width 0.20066)
		(layer "F.Cu")
		(net "M_H_CPU0_SA_DQS_DP<4>")
	)
	(segment
		(start 452.845932 -275.276056)
		(end 452.605394 -275.516594)
		(width 0.20066)
		(layer "F.Cu")
		(net "M_H_CPU0_SA_DQS_DP<4>")
	)
	(segment
		(start 453.860916 -275.690584)
		(end 453.446388 -275.276056)
		(width 0.20066)
		(layer "F.Cu")
		(net "M_H_CPU0_SA_DQS_DP<4>")
	)
	(segment
		(start 459.011274 -275.516594)
		(end 458.729588 -275.234908)
		(width 0.20066)
		(layer "F.Cu")
		(net "M_H_CPU0_SA_DQS_DP<4>")
	)
	(segment
		(start 458.123036 -275.645372)
		(end 457.75245 -275.645372)
		(width 0.20066)
		(layer "F.Cu")
		(net "M_H_CPU0_SA_DQS_DP<4>")
	)
	(segment
		(start 370.967762 -260.430518)
		(end 370.968016 -260.430772)
		(width 0.20066)
		(layer "F.Cu")
		(net "M_H_CPU0_SA_DQS_DP<4>")
	)
	(segment
		(start 450.911214 -275.516594)
		(end 452.016114 -275.516594)
		(width 0.20066)
		(layer "F.Cu")
		(net "M_H_CPU0_SA_DQS_DP<4>")
	)
	(segment
		(start 453.446388 -275.276056)
		(end 452.845932 -275.276056)
		(width 0.20066)
		(layer "F.Cu")
		(net "M_H_CPU0_SA_DQS_DP<4>")
	)
	(segment
		(start 454.546716 -275.690584)
		(end 453.860916 -275.690584)
		(width 0.20066)
		(layer "F.Cu")
		(net "M_H_CPU0_SA_DQS_DP<4>")
	)
	(segment
		(start 452.605394 -275.516594)
		(end 452.016114 -275.516594)
		(width 0.20066)
		(layer "F.Cu")
		(net "M_H_CPU0_SA_DQS_DP<4>")
	)
	(segment
		(start 454.797922 -275.94179)
		(end 454.546716 -275.690584)
		(width 0.20066)
		(layer "F.Cu")
		(net "M_H_CPU0_SA_DQS_DP<4>")
	)
	(segment
		(start 445.904112 -277.114)
		(end 443.003686 -277.114)
		(width 0.18288)
		(layer "In11.Cu")
		(net "M_H_CPU0_SA_DQS_DP<4>")
	)
	(segment
		(start 428.014892 -275.851366)
		(end 427.202092 -276.664166)
		(width 0.18288)
		(layer "In11.Cu")
		(net "M_H_CPU0_SA_DQS_DP<4>")
	)
	(segment
		(start 430.506632 -275.851366)
		(end 428.014892 -275.851366)
		(width 0.18288)
		(layer "In11.Cu")
		(net "M_H_CPU0_SA_DQS_DP<4>")
	)
	(segment
		(start 411.609794 -276.26945)
		(end 410.720286 -275.379942)
		(width 0.18288)
		(layer "In11.Cu")
		(net "M_H_CPU0_SA_DQS_DP<4>")
	)
	(segment
		(start 450.911214 -275.516594)
		(end 450.621908 -275.227288)
		(width 0.18288)
		(layer "In11.Cu")
		(net "M_H_CPU0_SA_DQS_DP<4>")
	)
	(segment
		(start 382.528064 -260.920484)
		(end 382.513332 -260.92912)
		(width 0.088646)
		(layer "In11.Cu")
		(net "M_H_CPU0_SA_DQS_DP<4>")
	)
	(segment
		(start 448.07886 -276.263354)
		(end 446.754758 -276.263354)
		(width 0.18288)
		(layer "In11.Cu")
		(net "M_H_CPU0_SA_DQS_DP<4>")
	)
	(segment
		(start 449.03263 -275.309838)
		(end 448.07886 -276.263354)
		(width 0.18288)
		(layer "In11.Cu")
		(net "M_H_CPU0_SA_DQS_DP<4>")
	)
	(segment
		(start 450.1007 -275.065998)
		(end 449.621402 -275.065998)
		(width 0.18288)
		(layer "In11.Cu")
		(net "M_H_CPU0_SA_DQS_DP<4>")
	)
	(segment
		(start 446.754758 -276.263354)
		(end 445.904112 -277.114)
		(width 0.18288)
		(layer "In11.Cu")
		(net "M_H_CPU0_SA_DQS_DP<4>")
	)
	(segment
		(start 432.021234 -276.516338)
		(end 430.506632 -275.851366)
		(width 0.18288)
		(layer "In11.Cu")
		(net "M_H_CPU0_SA_DQS_DP<4>")
	)
	(segment
		(start 404.46452 -274.568666)
		(end 393.546584 -263.65073)
		(width 0.18288)
		(layer "In11.Cu")
		(net "M_H_CPU0_SA_DQS_DP<4>")
	)
	(segment
		(start 439.346594 -277.357586)
		(end 437.6801 -277.357586)
		(width 0.18288)
		(layer "In11.Cu")
		(net "M_H_CPU0_SA_DQS_DP<4>")
	)
	(segment
		(start 450.621908 -275.227288)
		(end 450.26199 -275.227288)
		(width 0.18288)
		(layer "In11.Cu")
		(net "M_H_CPU0_SA_DQS_DP<4>")
	)
	(segment
		(start 393.546584 -263.65073)
		(end 388.842504 -263.65073)
		(width 0.18288)
		(layer "In11.Cu")
		(net "M_H_CPU0_SA_DQS_DP<4>")
	)
	(segment
		(start 376.889264 -260.920484)
		(end 376.874532 -260.92912)
		(width 0.088646)
		(layer "In11.Cu")
		(net "M_H_CPU0_SA_DQS_DP<4>")
	)
	(segment
		(start 426.008038 -277.39594)
		(end 425.308776 -277.39594)
		(width 0.18288)
		(layer "In11.Cu")
		(net "M_H_CPU0_SA_DQS_DP<4>")
	)
	(segment
		(start 388.166102 -263.590786)
		(end 388.013194 -263.437878)
		(width 0.088646)
		(layer "In11.Cu")
		(net "M_H_CPU0_SA_DQS_DP<4>")
	)
	(segment
		(start 440.41695 -277.375366)
		(end 440.15152 -277.640796)
		(width 0.18288)
		(layer "In11.Cu")
		(net "M_H_CPU0_SA_DQS_DP<4>")
	)
	(segment
		(start 416.175444 -275.77161)
		(end 412.770574 -275.77161)
		(width 0.18288)
		(layer "In11.Cu")
		(net "M_H_CPU0_SA_DQS_DP<4>")
	)
	(segment
		(start 435.255162 -276.516338)
		(end 432.021234 -276.516338)
		(width 0.18288)
		(layer "In11.Cu")
		(net "M_H_CPU0_SA_DQS_DP<4>")
	)
	(segment
		(start 442.629036 -276.73935)
		(end 441.696856 -276.73935)
		(width 0.18288)
		(layer "In11.Cu")
		(net "M_H_CPU0_SA_DQS_DP<4>")
	)
	(segment
		(start 373.130064 -260.920484)
		(end 373.115332 -260.92912)
		(width 0.088646)
		(layer "In11.Cu")
		(net "M_H_CPU0_SA_DQS_DP<4>")
	)
	(segment
		(start 427.202092 -276.664166)
		(end 426.739812 -276.664166)
		(width 0.18288)
		(layer "In11.Cu")
		(net "M_H_CPU0_SA_DQS_DP<4>")
	)
	(segment
		(start 420.184072 -276.533102)
		(end 416.936936 -276.533102)
		(width 0.18288)
		(layer "In11.Cu")
		(net "M_H_CPU0_SA_DQS_DP<4>")
	)
	(segment
		(start 436.848504 -276.52599)
		(end 436.316374 -276.52599)
		(width 0.18288)
		(layer "In11.Cu")
		(net "M_H_CPU0_SA_DQS_DP<4>")
	)
	(segment
		(start 421.96512 -276.531832)
		(end 421.223186 -276.531832)
		(width 0.18288)
		(layer "In11.Cu")
		(net "M_H_CPU0_SA_DQS_DP<4>")
	)
	(segment
		(start 374.069864 -260.920484)
		(end 374.055132 -260.92912)
		(width 0.088646)
		(layer "In11.Cu")
		(net "M_H_CPU0_SA_DQS_DP<4>")
	)
	(segment
		(start 420.964106 -276.790912)
		(end 420.441882 -276.790912)
		(width 0.18288)
		(layer "In11.Cu")
		(net "M_H_CPU0_SA_DQS_DP<4>")
	)
	(segment
		(start 385.26085 -261.73938)
		(end 385.25196 -261.7343)
		(width 0.088646)
		(layer "In11.Cu")
		(net "M_H_CPU0_SA_DQS_DP<4>")
	)
	(segment
		(start 440.15152 -277.640796)
		(end 439.629804 -277.640796)
		(width 0.18288)
		(layer "In11.Cu")
		(net "M_H_CPU0_SA_DQS_DP<4>")
	)
	(segment
		(start 384.969512 -261.254748)
		(end 384.969512 -261.244842)
		(width 0.088646)
		(layer "In11.Cu")
		(net "M_H_CPU0_SA_DQS_DP<4>")
	)
	(segment
		(start 388.78256 -263.590786)
		(end 388.166102 -263.590786)
		(width 0.088646)
		(layer "In11.Cu")
		(net "M_H_CPU0_SA_DQS_DP<4>")
	)
	(segment
		(start 378.768864 -260.920484)
		(end 378.754132 -260.92912)
		(width 0.088646)
		(layer "In11.Cu")
		(net "M_H_CPU0_SA_DQS_DP<4>")
	)
	(segment
		(start 386.287518 -262.548116)
		(end 386.277104 -262.554212)
		(width 0.088646)
		(layer "In11.Cu")
		(net "M_H_CPU0_SA_DQS_DP<4>")
	)
	(segment
		(start 423.937684 -277.398226)
		(end 422.46042 -277.027386)
		(width 0.18288)
		(layer "In11.Cu")
		(net "M_H_CPU0_SA_DQS_DP<4>")
	)
	(segment
		(start 408.762708 -274.568666)
		(end 404.46452 -274.568666)
		(width 0.18288)
		(layer "In11.Cu")
		(net "M_H_CPU0_SA_DQS_DP<4>")
	)
	(segment
		(start 372.190264 -260.920484)
		(end 372.175532 -260.92912)
		(width 0.088646)
		(layer "In11.Cu")
		(net "M_H_CPU0_SA_DQS_DP<4>")
	)
	(segment
		(start 388.013194 -263.437878)
		(end 387.414516 -263.437878)
		(width 0.088646)
		(layer "In11.Cu")
		(net "M_H_CPU0_SA_DQS_DP<4>")
	)
	(segment
		(start 371.345968 -260.49605)
		(end 371.28069 -260.430772)
		(width 0.088646)
		(layer "In11.Cu")
		(net "M_H_CPU0_SA_DQS_DP<4>")
	)
	(segment
		(start 449.621402 -275.065998)
		(end 449.03263 -275.309838)
		(width 0.18288)
		(layer "In11.Cu")
		(net "M_H_CPU0_SA_DQS_DP<4>")
	)
	(segment
		(start 424.542204 -277.640796)
		(end 424.299634 -277.398226)
		(width 0.18288)
		(layer "In11.Cu")
		(net "M_H_CPU0_SA_DQS_DP<4>")
	)
	(segment
		(start 375.949464 -260.920484)
		(end 375.934732 -260.92912)
		(width 0.088646)
		(layer "In11.Cu")
		(net "M_H_CPU0_SA_DQS_DP<4>")
	)
	(segment
		(start 379.708664 -260.920484)
		(end 379.693932 -260.92912)
		(width 0.088646)
		(layer "In11.Cu")
		(net "M_H_CPU0_SA_DQS_DP<4>")
	)
	(segment
		(start 441.696856 -276.73935)
		(end 441.06084 -277.375366)
		(width 0.18288)
		(layer "In11.Cu")
		(net "M_H_CPU0_SA_DQS_DP<4>")
	)
	(segment
		(start 435.529736 -276.790912)
		(end 435.255162 -276.516338)
		(width 0.18288)
		(layer "In11.Cu")
		(net "M_H_CPU0_SA_DQS_DP<4>")
	)
	(segment
		(start 437.6801 -277.357586)
		(end 436.848504 -276.52599)
		(width 0.18288)
		(layer "In11.Cu")
		(net "M_H_CPU0_SA_DQS_DP<4>")
	)
	(segment
		(start 412.770574 -275.77161)
		(end 412.272734 -276.26945)
		(width 0.18288)
		(layer "In11.Cu")
		(net "M_H_CPU0_SA_DQS_DP<4>")
	)
	(segment
		(start 386.849366 -262.891016)
		(end 386.849366 -262.872474)
		(width 0.088646)
		(layer "In11.Cu")
		(net "M_H_CPU0_SA_DQS_DP<4>")
	)
	(segment
		(start 436.051452 -276.790912)
		(end 435.529736 -276.790912)
		(width 0.18288)
		(layer "In11.Cu")
		(net "M_H_CPU0_SA_DQS_DP<4>")
	)
	(segment
		(start 443.003686 -277.114)
		(end 442.629036 -276.73935)
		(width 0.18288)
		(layer "In11.Cu")
		(net "M_H_CPU0_SA_DQS_DP<4>")
	)
	(segment
		(start 450.26199 -275.227288)
		(end 450.1007 -275.065998)
		(width 0.18288)
		(layer "In11.Cu")
		(net "M_H_CPU0_SA_DQS_DP<4>")
	)
	(segment
		(start 385.439412 -262.068564)
		(end 385.439412 -262.058658)
		(width 0.088646)
		(layer "In11.Cu")
		(net "M_H_CPU0_SA_DQS_DP<4>")
	)
	(segment
		(start 436.316374 -276.52599)
		(end 436.051452 -276.790912)
		(width 0.18288)
		(layer "In11.Cu")
		(net "M_H_CPU0_SA_DQS_DP<4>")
	)
	(segment
		(start 425.308776 -277.39594)
		(end 425.06392 -277.640796)
		(width 0.18288)
		(layer "In11.Cu")
		(net "M_H_CPU0_SA_DQS_DP<4>")
	)
	(segment
		(start 421.223186 -276.531832)
		(end 420.964106 -276.790912)
		(width 0.18288)
		(layer "In11.Cu")
		(net "M_H_CPU0_SA_DQS_DP<4>")
	)
	(segment
		(start 416.936936 -276.533102)
		(end 416.175444 -275.77161)
		(width 0.18288)
		(layer "In11.Cu")
		(net "M_H_CPU0_SA_DQS_DP<4>")
	)
	(segment
		(start 412.272734 -276.26945)
		(end 411.609794 -276.26945)
		(width 0.18288)
		(layer "In11.Cu")
		(net "M_H_CPU0_SA_DQS_DP<4>")
	)
	(segment
		(start 371.28069 -260.430772)
		(end 370.968016 -260.430772)
		(width 0.088646)
		(layer "In11.Cu")
		(net "M_H_CPU0_SA_DQS_DP<4>")
	)
	(segment
		(start 410.720286 -275.379942)
		(end 408.762708 -274.568666)
		(width 0.18288)
		(layer "In11.Cu")
		(net "M_H_CPU0_SA_DQS_DP<4>")
	)
	(segment
		(start 424.299634 -277.398226)
		(end 423.937684 -277.398226)
		(width 0.18288)
		(layer "In11.Cu")
		(net "M_H_CPU0_SA_DQS_DP<4>")
	)
	(segment
		(start 420.441882 -276.790912)
		(end 420.184072 -276.533102)
		(width 0.18288)
		(layer "In11.Cu")
		(net "M_H_CPU0_SA_DQS_DP<4>")
	)
	(segment
		(start 441.06084 -277.375366)
		(end 440.41695 -277.375366)
		(width 0.18288)
		(layer "In11.Cu")
		(net "M_H_CPU0_SA_DQS_DP<4>")
	)
	(segment
		(start 426.739812 -276.664166)
		(end 426.008038 -277.39594)
		(width 0.18288)
		(layer "In11.Cu")
		(net "M_H_CPU0_SA_DQS_DP<4>")
	)
	(segment
		(start 422.46042 -277.027386)
		(end 421.96512 -276.531832)
		(width 0.18288)
		(layer "In11.Cu")
		(net "M_H_CPU0_SA_DQS_DP<4>")
	)
	(segment
		(start 380.648464 -260.920484)
		(end 380.633732 -260.92912)
		(width 0.088646)
		(layer "In11.Cu")
		(net "M_H_CPU0_SA_DQS_DP<4>")
	)
	(segment
		(start 425.06392 -277.640796)
		(end 424.542204 -277.640796)
		(width 0.18288)
		(layer "In11.Cu")
		(net "M_H_CPU0_SA_DQS_DP<4>")
	)
	(segment
		(start 388.842504 -263.65073)
		(end 388.78256 -263.590786)
		(width 0.088646)
		(layer "In11.Cu")
		(net "M_H_CPU0_SA_DQS_DP<4>")
	)
	(segment
		(start 439.629804 -277.640796)
		(end 439.346594 -277.357586)
		(width 0.18288)
		(layer "In11.Cu")
		(net "M_H_CPU0_SA_DQS_DP<4>")
	)
	(segment
		(start 377.829064 -260.920484)
		(end 377.814332 -260.92912)
		(width 0.088646)
		(layer "In11.Cu")
		(net "M_H_CPU0_SA_DQS_DP<4>")
	)
	(arc
		(start 383.84226 -260.920484)
		(mid 383.655062 -260.870341)
		(end 383.467864 -260.920484)
		(width 0.088646)
		(layer "In11.Cu")
		(net "M_H_CPU0_SA_DQS_DP<4>")
	)
	(arc
		(start 386.277104 -262.554212)
		(mid 385.998672 -262.624026)
		(end 385.72186 -262.548116)
		(width 0.088646)
		(layer "In11.Cu")
		(net "M_H_CPU0_SA_DQS_DP<4>")
	)
	(arc
		(start 386.849112 -262.857742)
		(mid 386.655669 -262.54438)
		(end 386.287518 -262.548116)
		(width 0.088646)
		(layer "In11.Cu")
		(net "M_H_CPU0_SA_DQS_DP<4>")
	)
	(arc
		(start 373.50446 -260.920484)
		(mid 373.317262 -260.870341)
		(end 373.130064 -260.920484)
		(width 0.088646)
		(layer "In11.Cu")
		(net "M_H_CPU0_SA_DQS_DP<4>")
	)
	(arc
		(start 386.849366 -262.872474)
		(mid 386.849314 -262.865107)
		(end 386.849112 -262.857742)
		(width 0.088646)
		(layer "In11.Cu")
		(net "M_H_CPU0_SA_DQS_DP<4>")
	)
	(arc
		(start 375.009664 -260.920484)
		(mid 374.726962 -260.996226)
		(end 374.44426 -260.920484)
		(width 0.088646)
		(layer "In11.Cu")
		(net "M_H_CPU0_SA_DQS_DP<4>")
	)
	(arc
		(start 385.72186 -262.548116)
		(mid 385.517525 -262.345511)
		(end 385.439412 -262.068564)
		(width 0.088646)
		(layer "In11.Cu")
		(net "M_H_CPU0_SA_DQS_DP<4>")
	)
	(arc
		(start 381.588264 -260.920484)
		(mid 381.305562 -260.996226)
		(end 381.02286 -260.920484)
		(width 0.088646)
		(layer "In11.Cu")
		(net "M_H_CPU0_SA_DQS_DP<4>")
	)
	(arc
		(start 382.90246 -260.920484)
		(mid 382.715262 -260.870341)
		(end 382.528064 -260.920484)
		(width 0.088646)
		(layer "In11.Cu")
		(net "M_H_CPU0_SA_DQS_DP<4>")
	)
	(arc
		(start 387.414516 -263.437878)
		(mid 387.021325 -263.278777)
		(end 386.849366 -262.891016)
		(width 0.088646)
		(layer "In11.Cu")
		(net "M_H_CPU0_SA_DQS_DP<4>")
	)
	(arc
		(start 380.08306 -260.920484)
		(mid 379.895862 -260.870341)
		(end 379.708664 -260.920484)
		(width 0.088646)
		(layer "In11.Cu")
		(net "M_H_CPU0_SA_DQS_DP<4>")
	)
	(arc
		(start 376.874532 -260.92912)
		(mid 376.598091 -260.996286)
		(end 376.32386 -260.920484)
		(width 0.088646)
		(layer "In11.Cu")
		(net "M_H_CPU0_SA_DQS_DP<4>")
	)
	(arc
		(start 377.26366 -260.920484)
		(mid 377.076462 -260.870341)
		(end 376.889264 -260.920484)
		(width 0.088646)
		(layer "In11.Cu")
		(net "M_H_CPU0_SA_DQS_DP<4>")
	)
	(arc
		(start 383.467864 -260.920484)
		(mid 383.185162 -260.996226)
		(end 382.90246 -260.920484)
		(width 0.088646)
		(layer "In11.Cu")
		(net "M_H_CPU0_SA_DQS_DP<4>")
	)
	(arc
		(start 379.14326 -260.920484)
		(mid 378.956062 -260.870341)
		(end 378.768864 -260.920484)
		(width 0.088646)
		(layer "In11.Cu")
		(net "M_H_CPU0_SA_DQS_DP<4>")
	)
	(arc
		(start 385.439412 -262.058658)
		(mid 385.391733 -261.875758)
		(end 385.26085 -261.73938)
		(width 0.088646)
		(layer "In11.Cu")
		(net "M_H_CPU0_SA_DQS_DP<4>")
	)
	(arc
		(start 373.115332 -260.92912)
		(mid 372.838891 -260.996286)
		(end 372.56466 -260.920484)
		(width 0.088646)
		(layer "In11.Cu")
		(net "M_H_CPU0_SA_DQS_DP<4>")
	)
	(arc
		(start 380.633732 -260.92912)
		(mid 380.357291 -260.996286)
		(end 380.08306 -260.920484)
		(width 0.088646)
		(layer "In11.Cu")
		(net "M_H_CPU0_SA_DQS_DP<4>")
	)
	(arc
		(start 378.20346 -260.920484)
		(mid 378.016262 -260.870341)
		(end 377.829064 -260.920484)
		(width 0.088646)
		(layer "In11.Cu")
		(net "M_H_CPU0_SA_DQS_DP<4>")
	)
	(arc
		(start 385.25196 -261.7343)
		(mid 385.047625 -261.531695)
		(end 384.969512 -261.254748)
		(width 0.088646)
		(layer "In11.Cu")
		(net "M_H_CPU0_SA_DQS_DP<4>")
	)
	(arc
		(start 378.754132 -260.92912)
		(mid 378.477691 -260.996286)
		(end 378.20346 -260.920484)
		(width 0.088646)
		(layer "In11.Cu")
		(net "M_H_CPU0_SA_DQS_DP<4>")
	)
	(arc
		(start 372.56466 -260.920484)
		(mid 372.377462 -260.870341)
		(end 372.190264 -260.920484)
		(width 0.088646)
		(layer "In11.Cu")
		(net "M_H_CPU0_SA_DQS_DP<4>")
	)
	(arc
		(start 375.38406 -260.920484)
		(mid 375.196862 -260.870341)
		(end 375.009664 -260.920484)
		(width 0.088646)
		(layer "In11.Cu")
		(net "M_H_CPU0_SA_DQS_DP<4>")
	)
	(arc
		(start 371.348762 -260.517386)
		(mid 371.347264 -260.506731)
		(end 371.345968 -260.49605)
		(width 0.088646)
		(layer "In11.Cu")
		(net "M_H_CPU0_SA_DQS_DP<4>")
	)
	(arc
		(start 379.693932 -260.92912)
		(mid 379.417491 -260.996286)
		(end 379.14326 -260.920484)
		(width 0.088646)
		(layer "In11.Cu")
		(net "M_H_CPU0_SA_DQS_DP<4>")
	)
	(arc
		(start 377.814332 -260.92912)
		(mid 377.537891 -260.996286)
		(end 377.26366 -260.920484)
		(width 0.088646)
		(layer "In11.Cu")
		(net "M_H_CPU0_SA_DQS_DP<4>")
	)
	(arc
		(start 374.055132 -260.92912)
		(mid 373.778691 -260.996286)
		(end 373.50446 -260.920484)
		(width 0.088646)
		(layer "In11.Cu")
		(net "M_H_CPU0_SA_DQS_DP<4>")
	)
	(arc
		(start 381.96266 -260.920484)
		(mid 381.775462 -260.870341)
		(end 381.588264 -260.920484)
		(width 0.088646)
		(layer "In11.Cu")
		(net "M_H_CPU0_SA_DQS_DP<4>")
	)
	(arc
		(start 384.407664 -260.920484)
		(mid 384.124962 -260.996226)
		(end 383.84226 -260.920484)
		(width 0.088646)
		(layer "In11.Cu")
		(net "M_H_CPU0_SA_DQS_DP<4>")
	)
	(arc
		(start 374.44426 -260.920484)
		(mid 374.257062 -260.870341)
		(end 374.069864 -260.920484)
		(width 0.088646)
		(layer "In11.Cu")
		(net "M_H_CPU0_SA_DQS_DP<4>")
	)
	(arc
		(start 376.32386 -260.920484)
		(mid 376.136662 -260.870341)
		(end 375.949464 -260.920484)
		(width 0.088646)
		(layer "In11.Cu")
		(net "M_H_CPU0_SA_DQS_DP<4>")
	)
	(arc
		(start 375.934732 -260.92912)
		(mid 375.658291 -260.996286)
		(end 375.38406 -260.920484)
		(width 0.088646)
		(layer "In11.Cu")
		(net "M_H_CPU0_SA_DQS_DP<4>")
	)
	(arc
		(start 372.175532 -260.92912)
		(mid 371.655628 -260.937155)
		(end 371.348762 -260.517386)
		(width 0.088646)
		(layer "In11.Cu")
		(net "M_H_CPU0_SA_DQS_DP<4>")
	)
	(arc
		(start 384.969512 -261.244842)
		(mid 384.782213 -260.920401)
		(end 384.407664 -260.920484)
		(width 0.088646)
		(layer "In11.Cu")
		(net "M_H_CPU0_SA_DQS_DP<4>")
	)
	(arc
		(start 381.02286 -260.920484)
		(mid 380.835662 -260.870341)
		(end 380.648464 -260.920484)
		(width 0.088646)
		(layer "In11.Cu")
		(net "M_H_CPU0_SA_DQS_DP<4>")
	)
	(arc
		(start 382.513332 -260.92912)
		(mid 382.236891 -260.996286)
		(end 381.96266 -260.920484)
		(width 0.088646)
		(layer "In11.Cu")
		(net "M_H_CPU0_SA_DQS_DP<4>")
	)
	(segment
		(start 458.5335 -284.584902)
		(end 458.123036 -284.995366)
		(width 0.20066)
		(layer "F.Cu")
		(net "M_H_CPU0_SA_DQS_DP<3>")
	)
	(segment
		(start 458.729588 -284.584902)
		(end 458.5335 -284.584902)
		(width 0.20066)
		(layer "F.Cu")
		(net "M_H_CPU0_SA_DQS_DP<3>")
	)
	(segment
		(start 454.963276 -285.291784)
		(end 454.937368 -285.291784)
		(width 0.101854)
		(layer "F.Cu")
		(net "M_H_CPU0_SA_DQS_DP<3>")
	)
	(segment
		(start 457.120498 -285.291784)
		(end 454.963276 -285.291784)
		(width 0.1016)
		(layer "F.Cu")
		(net "M_H_CPU0_SA_DQS_DP<3>")
	)
	(segment
		(start 454.937368 -285.291784)
		(end 454.797922 -285.291784)
		(width 0.20066)
		(layer "F.Cu")
		(net "M_H_CPU0_SA_DQS_DP<3>")
	)
	(segment
		(start 452.605394 -284.866588)
		(end 452.016114 -284.866588)
		(width 0.20066)
		(layer "F.Cu")
		(net "M_H_CPU0_SA_DQS_DP<3>")
	)
	(segment
		(start 458.123036 -284.995366)
		(end 457.75245 -284.995366)
		(width 0.20066)
		(layer "F.Cu")
		(net "M_H_CPU0_SA_DQS_DP<3>")
	)
	(segment
		(start 457.449936 -285.29788)
		(end 457.126594 -285.29788)
		(width 0.20066)
		(layer "F.Cu")
		(net "M_H_CPU0_SA_DQS_DP<3>")
	)
	(segment
		(start 453.860916 -285.040578)
		(end 453.446388 -284.62605)
		(width 0.20066)
		(layer "F.Cu")
		(net "M_H_CPU0_SA_DQS_DP<3>")
	)
	(segment
		(start 454.546716 -285.040578)
		(end 453.860916 -285.040578)
		(width 0.20066)
		(layer "F.Cu")
		(net "M_H_CPU0_SA_DQS_DP<3>")
	)
	(segment
		(start 453.446388 -284.62605)
		(end 452.845932 -284.62605)
		(width 0.20066)
		(layer "F.Cu")
		(net "M_H_CPU0_SA_DQS_DP<3>")
	)
	(segment
		(start 457.126594 -285.29788)
		(end 457.120498 -285.291784)
		(width 0.1016)
		(layer "F.Cu")
		(net "M_H_CPU0_SA_DQS_DP<3>")
	)
	(segment
		(start 454.797922 -285.291784)
		(end 454.546716 -285.040578)
		(width 0.20066)
		(layer "F.Cu")
		(net "M_H_CPU0_SA_DQS_DP<3>")
	)
	(segment
		(start 450.911214 -284.866588)
		(end 452.016114 -284.866588)
		(width 0.20066)
		(layer "F.Cu")
		(net "M_H_CPU0_SA_DQS_DP<3>")
	)
	(segment
		(start 370.967762 -264.778236)
		(end 370.967762 -265.313922)
		(width 0.20066)
		(layer "F.Cu")
		(net "M_H_CPU0_SA_DQS_DP<3>")
	)
	(segment
		(start 370.967762 -265.313922)
		(end 370.968016 -265.314176)
		(width 0.20066)
		(layer "F.Cu")
		(net "M_H_CPU0_SA_DQS_DP<3>")
	)
	(segment
		(start 457.75245 -284.995366)
		(end 457.449936 -285.29788)
		(width 0.20066)
		(layer "F.Cu")
		(net "M_H_CPU0_SA_DQS_DP<3>")
	)
	(segment
		(start 452.845932 -284.62605)
		(end 452.605394 -284.866588)
		(width 0.20066)
		(layer "F.Cu")
		(net "M_H_CPU0_SA_DQS_DP<3>")
	)
	(segment
		(start 459.011274 -284.866588)
		(end 458.729588 -284.584902)
		(width 0.20066)
		(layer "F.Cu")
		(net "M_H_CPU0_SA_DQS_DP<3>")
	)
	(segment
		(start 459.559914 -284.866588)
		(end 459.011274 -284.866588)
		(width 0.20066)
		(layer "F.Cu")
		(net "M_H_CPU0_SA_DQS_DP<3>")
	)
	(segment
		(start 382.441704 -268.250416)
		(end 382.426718 -268.24178)
		(width 0.088646)
		(layer "In11.Cu")
		(net "M_H_CPU0_SA_DQS_DP<3>")
	)
	(segment
		(start 424.265598 -288.407602)
		(end 423.514266 -288.407602)
		(width 0.18288)
		(layer "In11.Cu")
		(net "M_H_CPU0_SA_DQS_DP<3>")
	)
	(segment
		(start 442.437012 -287.597596)
		(end 441.61456 -287.938464)
		(width 0.18288)
		(layer "In11.Cu")
		(net "M_H_CPU0_SA_DQS_DP<3>")
	)
	(segment
		(start 440.412378 -288.429954)
		(end 440.15152 -288.690812)
		(width 0.18288)
		(layer "In11.Cu")
		(net "M_H_CPU0_SA_DQS_DP<3>")
	)
	(segment
		(start 387.911086 -269.46733)
		(end 387.343142 -269.46733)
		(width 0.088646)
		(layer "In11.Cu")
		(net "M_H_CPU0_SA_DQS_DP<3>")
	)
	(segment
		(start 420.442136 -289.54095)
		(end 420.158926 -289.25774)
		(width 0.18288)
		(layer "In11.Cu")
		(net "M_H_CPU0_SA_DQS_DP<3>")
	)
	(segment
		(start 450.656706 -284.61208)
		(end 450.064378 -284.61208)
		(width 0.18288)
		(layer "In11.Cu")
		(net "M_H_CPU0_SA_DQS_DP<3>")
	)
	(segment
		(start 426.701712 -287.55975)
		(end 425.828206 -288.433256)
		(width 0.18288)
		(layer "In11.Cu")
		(net "M_H_CPU0_SA_DQS_DP<3>")
	)
	(segment
		(start 381.496062 -266.619482)
		(end 381.493522 -266.617958)
		(width 0.088646)
		(layer "In11.Cu")
		(net "M_H_CPU0_SA_DQS_DP<3>")
	)
	(segment
		(start 437.049926 -287.567878)
		(end 436.324502 -287.567878)
		(width 0.18288)
		(layer "In11.Cu")
		(net "M_H_CPU0_SA_DQS_DP<3>")
	)
	(segment
		(start 381.50165 -266.62253)
		(end 381.496062 -266.619482)
		(width 0.088646)
		(layer "In11.Cu")
		(net "M_H_CPU0_SA_DQS_DP<3>")
	)
	(segment
		(start 407.553414 -284.018736)
		(end 405.112474 -284.018736)
		(width 0.18288)
		(layer "In11.Cu")
		(net "M_H_CPU0_SA_DQS_DP<3>")
	)
	(segment
		(start 380.648464 -265.803888)
		(end 380.633732 -265.812524)
		(width 0.088646)
		(layer "In11.Cu")
		(net "M_H_CPU0_SA_DQS_DP<3>")
	)
	(segment
		(start 440.15152 -288.690812)
		(end 439.629804 -288.690812)
		(width 0.18288)
		(layer "In11.Cu")
		(net "M_H_CPU0_SA_DQS_DP<3>")
	)
	(segment
		(start 376.889264 -265.803888)
		(end 376.874532 -265.812524)
		(width 0.088646)
		(layer "In11.Cu")
		(net "M_H_CPU0_SA_DQS_DP<3>")
	)
	(segment
		(start 430.845468 -286.96539)
		(end 428.136304 -286.96539)
		(width 0.18288)
		(layer "In11.Cu")
		(net "M_H_CPU0_SA_DQS_DP<3>")
	)
	(segment
		(start 438.95772 -288.44494)
		(end 438.67197 -288.15919)
		(width 0.18288)
		(layer "In11.Cu")
		(net "M_H_CPU0_SA_DQS_DP<3>")
	)
	(segment
		(start 381.97155 -267.4366)
		(end 381.963676 -267.432028)
		(width 0.088646)
		(layer "In11.Cu")
		(net "M_H_CPU0_SA_DQS_DP<3>")
	)
	(segment
		(start 387.343142 -269.46733)
		(end 387.147308 -269.271496)
		(width 0.088646)
		(layer "In11.Cu")
		(net "M_H_CPU0_SA_DQS_DP<3>")
	)
	(segment
		(start 450.911214 -284.866588)
		(end 450.656706 -284.61208)
		(width 0.18288)
		(layer "In11.Cu")
		(net "M_H_CPU0_SA_DQS_DP<3>")
	)
	(segment
		(start 373.130064 -265.803888)
		(end 373.115332 -265.812524)
		(width 0.088646)
		(layer "In11.Cu")
		(net "M_H_CPU0_SA_DQS_DP<3>")
	)
	(segment
		(start 418.526722 -288.44621)
		(end 415.883344 -286.67964)
		(width 0.18288)
		(layer "In11.Cu")
		(net "M_H_CPU0_SA_DQS_DP<3>")
	)
	(segment
		(start 439.629804 -288.690812)
		(end 439.383932 -288.44494)
		(width 0.18288)
		(layer "In11.Cu")
		(net "M_H_CPU0_SA_DQS_DP<3>")
	)
	(segment
		(start 445.290194 -286.642048)
		(end 444.099188 -286.642048)
		(width 0.18288)
		(layer "In11.Cu")
		(net "M_H_CPU0_SA_DQS_DP<3>")
	)
	(segment
		(start 441.61456 -287.938464)
		(end 441.122816 -288.429954)
		(width 0.18288)
		(layer "In11.Cu")
		(net "M_H_CPU0_SA_DQS_DP<3>")
	)
	(segment
		(start 386.874004 -269.271496)
		(end 386.661406 -269.058898)
		(width 0.088646)
		(layer "In11.Cu")
		(net "M_H_CPU0_SA_DQS_DP<3>")
	)
	(segment
		(start 388.552944 -269.688056)
		(end 388.131812 -269.688056)
		(width 0.088646)
		(layer "In11.Cu")
		(net "M_H_CPU0_SA_DQS_DP<3>")
	)
	(segment
		(start 386.655056 -269.055088)
		(end 386.649468 -269.052294)
		(width 0.088646)
		(layer "In11.Cu")
		(net "M_H_CPU0_SA_DQS_DP<3>")
	)
	(segment
		(start 421.839898 -289.276028)
		(end 421.228774 -289.276028)
		(width 0.18288)
		(layer "In11.Cu")
		(net "M_H_CPU0_SA_DQS_DP<3>")
	)
	(segment
		(start 412.439866 -286.401002)
		(end 412.166308 -286.12592)
		(width 0.18288)
		(layer "In11.Cu")
		(net "M_H_CPU0_SA_DQS_DP<3>")
	)
	(segment
		(start 415.883344 -286.67964)
		(end 414.36798 -286.67964)
		(width 0.18288)
		(layer "In11.Cu")
		(net "M_H_CPU0_SA_DQS_DP<3>")
	)
	(segment
		(start 435.529736 -287.840928)
		(end 435.285388 -287.59658)
		(width 0.18288)
		(layer "In11.Cu")
		(net "M_H_CPU0_SA_DQS_DP<3>")
	)
	(segment
		(start 405.112474 -284.018736)
		(end 390.841738 -269.748)
		(width 0.18288)
		(layer "In11.Cu")
		(net "M_H_CPU0_SA_DQS_DP<3>")
	)
	(segment
		(start 381.493522 -266.617958)
		(end 381.49276 -266.61745)
		(width 0.088646)
		(layer "In11.Cu")
		(net "M_H_CPU0_SA_DQS_DP<3>")
	)
	(segment
		(start 371.345968 -265.3792)
		(end 371.280944 -265.314176)
		(width 0.088646)
		(layer "In11.Cu")
		(net "M_H_CPU0_SA_DQS_DP<3>")
	)
	(segment
		(start 387.147308 -269.271496)
		(end 386.874004 -269.271496)
		(width 0.088646)
		(layer "In11.Cu")
		(net "M_H_CPU0_SA_DQS_DP<3>")
	)
	(segment
		(start 447.745104 -285.625032)
		(end 445.290194 -286.642048)
		(width 0.18288)
		(layer "In11.Cu")
		(net "M_H_CPU0_SA_DQS_DP<3>")
	)
	(segment
		(start 435.285388 -287.59658)
		(end 432.369468 -287.59658)
		(width 0.18288)
		(layer "In11.Cu")
		(net "M_H_CPU0_SA_DQS_DP<3>")
	)
	(segment
		(start 372.190264 -265.803888)
		(end 372.175532 -265.812524)
		(width 0.088646)
		(layer "In11.Cu")
		(net "M_H_CPU0_SA_DQS_DP<3>")
	)
	(segment
		(start 442.892942 -287.141666)
		(end 442.437012 -287.597596)
		(width 0.18288)
		(layer "In11.Cu")
		(net "M_H_CPU0_SA_DQS_DP<3>")
	)
	(segment
		(start 378.768864 -265.803888)
		(end 378.754132 -265.812524)
		(width 0.088646)
		(layer "In11.Cu")
		(net "M_H_CPU0_SA_DQS_DP<3>")
	)
	(segment
		(start 425.06392 -288.690812)
		(end 424.548808 -288.690812)
		(width 0.18288)
		(layer "In11.Cu")
		(net "M_H_CPU0_SA_DQS_DP<3>")
	)
	(segment
		(start 379.708664 -265.803888)
		(end 379.693932 -265.812524)
		(width 0.088646)
		(layer "In11.Cu")
		(net "M_H_CPU0_SA_DQS_DP<3>")
	)
	(segment
		(start 414.089342 -286.401002)
		(end 412.439866 -286.401002)
		(width 0.18288)
		(layer "In11.Cu")
		(net "M_H_CPU0_SA_DQS_DP<3>")
	)
	(segment
		(start 450.064378 -284.61208)
		(end 449.87718 -284.424882)
		(width 0.18288)
		(layer "In11.Cu")
		(net "M_H_CPU0_SA_DQS_DP<3>")
	)
	(segment
		(start 437.641238 -288.15919)
		(end 437.049926 -287.567878)
		(width 0.18288)
		(layer "In11.Cu")
		(net "M_H_CPU0_SA_DQS_DP<3>")
	)
	(segment
		(start 386.661406 -269.058898)
		(end 386.655056 -269.055088)
		(width 0.088646)
		(layer "In11.Cu")
		(net "M_H_CPU0_SA_DQS_DP<3>")
	)
	(segment
		(start 444.099188 -286.642048)
		(end 442.892942 -287.141666)
		(width 0.18288)
		(layer "In11.Cu")
		(net "M_H_CPU0_SA_DQS_DP<3>")
	)
	(segment
		(start 448.240404 -285.625032)
		(end 447.745104 -285.625032)
		(width 0.18288)
		(layer "In11.Cu")
		(net "M_H_CPU0_SA_DQS_DP<3>")
	)
	(segment
		(start 438.67197 -288.15919)
		(end 437.641238 -288.15919)
		(width 0.18288)
		(layer "In11.Cu")
		(net "M_H_CPU0_SA_DQS_DP<3>")
	)
	(segment
		(start 422.34485 -289.066986)
		(end 421.839898 -289.276028)
		(width 0.18288)
		(layer "In11.Cu")
		(net "M_H_CPU0_SA_DQS_DP<3>")
	)
	(segment
		(start 436.051452 -287.840928)
		(end 435.529736 -287.840928)
		(width 0.18288)
		(layer "In11.Cu")
		(net "M_H_CPU0_SA_DQS_DP<3>")
	)
	(segment
		(start 381.963676 -267.432028)
		(end 381.96266 -267.43152)
		(width 0.088646)
		(layer "In11.Cu")
		(net "M_H_CPU0_SA_DQS_DP<3>")
	)
	(segment
		(start 425.321476 -288.433256)
		(end 425.06392 -288.690812)
		(width 0.18288)
		(layer "In11.Cu")
		(net "M_H_CPU0_SA_DQS_DP<3>")
	)
	(segment
		(start 388.612888 -269.748)
		(end 388.552944 -269.688056)
		(width 0.088646)
		(layer "In11.Cu")
		(net "M_H_CPU0_SA_DQS_DP<3>")
	)
	(segment
		(start 388.131812 -269.688056)
		(end 387.911086 -269.46733)
		(width 0.088646)
		(layer "In11.Cu")
		(net "M_H_CPU0_SA_DQS_DP<3>")
	)
	(segment
		(start 420.158926 -289.25774)
		(end 419.338252 -289.25774)
		(width 0.18288)
		(layer "In11.Cu")
		(net "M_H_CPU0_SA_DQS_DP<3>")
	)
	(segment
		(start 381.680212 -266.956032)
		(end 381.680212 -266.941808)
		(width 0.088646)
		(layer "In11.Cu")
		(net "M_H_CPU0_SA_DQS_DP<3>")
	)
	(segment
		(start 419.338252 -289.25774)
		(end 418.526722 -288.44621)
		(width 0.18288)
		(layer "In11.Cu")
		(net "M_H_CPU0_SA_DQS_DP<3>")
	)
	(segment
		(start 441.122816 -288.429954)
		(end 440.412378 -288.429954)
		(width 0.18288)
		(layer "In11.Cu")
		(net "M_H_CPU0_SA_DQS_DP<3>")
	)
	(segment
		(start 383.467864 -269.059152)
		(end 383.453132 -269.067788)
		(width 0.088646)
		(layer "In11.Cu")
		(net "M_H_CPU0_SA_DQS_DP<3>")
	)
	(segment
		(start 436.324502 -287.567878)
		(end 436.051452 -287.840928)
		(width 0.18288)
		(layer "In11.Cu")
		(net "M_H_CPU0_SA_DQS_DP<3>")
	)
	(segment
		(start 412.166308 -286.12592)
		(end 409.660598 -286.12592)
		(width 0.18288)
		(layer "In11.Cu")
		(net "M_H_CPU0_SA_DQS_DP<3>")
	)
	(segment
		(start 449.87718 -284.424882)
		(end 449.440554 -284.424882)
		(width 0.18288)
		(layer "In11.Cu")
		(net "M_H_CPU0_SA_DQS_DP<3>")
	)
	(segment
		(start 390.841738 -269.748)
		(end 388.612888 -269.748)
		(width 0.18288)
		(layer "In11.Cu")
		(net "M_H_CPU0_SA_DQS_DP<3>")
	)
	(segment
		(start 422.642792 -288.768536)
		(end 422.34485 -289.066986)
		(width 0.18288)
		(layer "In11.Cu")
		(net "M_H_CPU0_SA_DQS_DP<3>")
	)
	(segment
		(start 409.660598 -286.12592)
		(end 407.553414 -284.018736)
		(width 0.18288)
		(layer "In11.Cu")
		(net "M_H_CPU0_SA_DQS_DP<3>")
	)
	(segment
		(start 381.210566 -266.138152)
		(end 381.210312 -266.128246)
		(width 0.088646)
		(layer "In11.Cu")
		(net "M_H_CPU0_SA_DQS_DP<3>")
	)
	(segment
		(start 424.548808 -288.690812)
		(end 424.265598 -288.407602)
		(width 0.18288)
		(layer "In11.Cu")
		(net "M_H_CPU0_SA_DQS_DP<3>")
	)
	(segment
		(start 449.440554 -284.424882)
		(end 448.240404 -285.625032)
		(width 0.18288)
		(layer "In11.Cu")
		(net "M_H_CPU0_SA_DQS_DP<3>")
	)
	(segment
		(start 382.620266 -268.585188)
		(end 382.620266 -268.569694)
		(width 0.088646)
		(layer "In11.Cu")
		(net "M_H_CPU0_SA_DQS_DP<3>")
	)
	(segment
		(start 432.369468 -287.59658)
		(end 430.845468 -286.96539)
		(width 0.18288)
		(layer "In11.Cu")
		(net "M_H_CPU0_SA_DQS_DP<3>")
	)
	(segment
		(start 375.949464 -265.803888)
		(end 375.934732 -265.812524)
		(width 0.088646)
		(layer "In11.Cu")
		(net "M_H_CPU0_SA_DQS_DP<3>")
	)
	(segment
		(start 371.280944 -265.314176)
		(end 370.968016 -265.314176)
		(width 0.088646)
		(layer "In11.Cu")
		(net "M_H_CPU0_SA_DQS_DP<3>")
	)
	(segment
		(start 377.829064 -265.803888)
		(end 377.814332 -265.812524)
		(width 0.088646)
		(layer "In11.Cu")
		(net "M_H_CPU0_SA_DQS_DP<3>")
	)
	(segment
		(start 385.736338 -269.067788)
		(end 385.713224 -269.054326)
		(width 0.088646)
		(layer "In11.Cu")
		(net "M_H_CPU0_SA_DQS_DP<3>")
	)
	(segment
		(start 421.228774 -289.276028)
		(end 420.963852 -289.54095)
		(width 0.18288)
		(layer "In11.Cu")
		(net "M_H_CPU0_SA_DQS_DP<3>")
	)
	(segment
		(start 439.383932 -288.44494)
		(end 438.95772 -288.44494)
		(width 0.18288)
		(layer "In11.Cu")
		(net "M_H_CPU0_SA_DQS_DP<3>")
	)
	(segment
		(start 425.828206 -288.433256)
		(end 425.321476 -288.433256)
		(width 0.18288)
		(layer "In11.Cu")
		(net "M_H_CPU0_SA_DQS_DP<3>")
	)
	(segment
		(start 428.136304 -286.96539)
		(end 426.701712 -287.55975)
		(width 0.18288)
		(layer "In11.Cu")
		(net "M_H_CPU0_SA_DQS_DP<3>")
	)
	(segment
		(start 423.514266 -288.407602)
		(end 422.642792 -288.768536)
		(width 0.18288)
		(layer "In11.Cu")
		(net "M_H_CPU0_SA_DQS_DP<3>")
	)
	(segment
		(start 414.36798 -286.67964)
		(end 414.089342 -286.401002)
		(width 0.18288)
		(layer "In11.Cu")
		(net "M_H_CPU0_SA_DQS_DP<3>")
	)
	(segment
		(start 420.963852 -289.54095)
		(end 420.442136 -289.54095)
		(width 0.18288)
		(layer "In11.Cu")
		(net "M_H_CPU0_SA_DQS_DP<3>")
	)
	(segment
		(start 374.069864 -265.803888)
		(end 374.055132 -265.812524)
		(width 0.088646)
		(layer "In11.Cu")
		(net "M_H_CPU0_SA_DQS_DP<3>")
	)
	(arc
		(start 378.20346 -265.803888)
		(mid 378.016262 -265.753745)
		(end 377.829064 -265.803888)
		(width 0.088646)
		(layer "In11.Cu")
		(net "M_H_CPU0_SA_DQS_DP<3>")
	)
	(arc
		(start 375.009664 -265.803888)
		(mid 374.726962 -265.87963)
		(end 374.44426 -265.803888)
		(width 0.088646)
		(layer "In11.Cu")
		(net "M_H_CPU0_SA_DQS_DP<3>")
	)
	(arc
		(start 371.348762 -265.400536)
		(mid 371.347264 -265.389881)
		(end 371.345968 -265.3792)
		(width 0.088646)
		(layer "In11.Cu")
		(net "M_H_CPU0_SA_DQS_DP<3>")
	)
	(arc
		(start 372.175532 -265.812524)
		(mid 371.655516 -265.820503)
		(end 371.348762 -265.400536)
		(width 0.088646)
		(layer "In11.Cu")
		(net "M_H_CPU0_SA_DQS_DP<3>")
	)
	(arc
		(start 381.210312 -266.128246)
		(mid 381.023013 -265.803805)
		(end 380.648464 -265.803888)
		(width 0.088646)
		(layer "In11.Cu")
		(net "M_H_CPU0_SA_DQS_DP<3>")
	)
	(arc
		(start 380.633732 -265.812524)
		(mid 380.357291 -265.87969)
		(end 380.08306 -265.803888)
		(width 0.088646)
		(layer "In11.Cu")
		(net "M_H_CPU0_SA_DQS_DP<3>")
	)
	(arc
		(start 374.44426 -265.803888)
		(mid 374.257062 -265.753745)
		(end 374.069864 -265.803888)
		(width 0.088646)
		(layer "In11.Cu")
		(net "M_H_CPU0_SA_DQS_DP<3>")
	)
	(arc
		(start 373.115332 -265.812524)
		(mid 372.838891 -265.87969)
		(end 372.56466 -265.803888)
		(width 0.088646)
		(layer "In11.Cu")
		(net "M_H_CPU0_SA_DQS_DP<3>")
	)
	(arc
		(start 385.347464 -269.059152)
		(mid 385.064762 -269.134928)
		(end 384.78206 -269.059152)
		(width 0.088646)
		(layer "In11.Cu")
		(net "M_H_CPU0_SA_DQS_DP<3>")
	)
	(arc
		(start 383.84226 -269.059152)
		(mid 383.655062 -269.009009)
		(end 383.467864 -269.059152)
		(width 0.088646)
		(layer "In11.Cu")
		(net "M_H_CPU0_SA_DQS_DP<3>")
	)
	(arc
		(start 375.38406 -265.803888)
		(mid 375.196862 -265.753745)
		(end 375.009664 -265.803888)
		(width 0.088646)
		(layer "In11.Cu")
		(net "M_H_CPU0_SA_DQS_DP<3>")
	)
	(arc
		(start 377.814332 -265.812524)
		(mid 377.537891 -265.87969)
		(end 377.26366 -265.803888)
		(width 0.088646)
		(layer "In11.Cu")
		(net "M_H_CPU0_SA_DQS_DP<3>")
	)
	(arc
		(start 383.453132 -269.067788)
		(mid 382.901939 -269.05899)
		(end 382.620266 -268.585188)
		(width 0.088646)
		(layer "In11.Cu")
		(net "M_H_CPU0_SA_DQS_DP<3>")
	)
	(arc
		(start 382.149858 -267.741146)
		(mid 382.098804 -267.566566)
		(end 381.97155 -267.4366)
		(width 0.088646)
		(layer "In11.Cu")
		(net "M_H_CPU0_SA_DQS_DP<3>")
	)
	(arc
		(start 380.08306 -265.803888)
		(mid 379.895862 -265.753745)
		(end 379.708664 -265.803888)
		(width 0.088646)
		(layer "In11.Cu")
		(net "M_H_CPU0_SA_DQS_DP<3>")
	)
	(arc
		(start 378.754132 -265.812524)
		(mid 378.477691 -265.87969)
		(end 378.20346 -265.803888)
		(width 0.088646)
		(layer "In11.Cu")
		(net "M_H_CPU0_SA_DQS_DP<3>")
	)
	(arc
		(start 381.96266 -267.43152)
		(mid 381.759355 -267.230654)
		(end 381.680212 -266.956032)
		(width 0.088646)
		(layer "In11.Cu")
		(net "M_H_CPU0_SA_DQS_DP<3>")
	)
	(arc
		(start 386.28701 -269.059152)
		(mid 386.012811 -269.134987)
		(end 385.736338 -269.067788)
		(width 0.088646)
		(layer "In11.Cu")
		(net "M_H_CPU0_SA_DQS_DP<3>")
	)
	(arc
		(start 386.649468 -269.052294)
		(mid 386.467357 -269.008969)
		(end 386.28701 -269.059152)
		(width 0.088646)
		(layer "In11.Cu")
		(net "M_H_CPU0_SA_DQS_DP<3>")
	)
	(arc
		(start 382.150112 -267.755878)
		(mid 382.15006 -267.748511)
		(end 382.149858 -267.741146)
		(width 0.088646)
		(layer "In11.Cu")
		(net "M_H_CPU0_SA_DQS_DP<3>")
	)
	(arc
		(start 379.693932 -265.812524)
		(mid 379.417491 -265.87969)
		(end 379.14326 -265.803888)
		(width 0.088646)
		(layer "In11.Cu")
		(net "M_H_CPU0_SA_DQS_DP<3>")
	)
	(arc
		(start 374.055132 -265.812524)
		(mid 373.778691 -265.87969)
		(end 373.50446 -265.803888)
		(width 0.088646)
		(layer "In11.Cu")
		(net "M_H_CPU0_SA_DQS_DP<3>")
	)
	(arc
		(start 384.407664 -269.059152)
		(mid 384.124962 -269.134928)
		(end 383.84226 -269.059152)
		(width 0.088646)
		(layer "In11.Cu")
		(net "M_H_CPU0_SA_DQS_DP<3>")
	)
	(arc
		(start 376.874532 -265.812524)
		(mid 376.598091 -265.87969)
		(end 376.32386 -265.803888)
		(width 0.088646)
		(layer "In11.Cu")
		(net "M_H_CPU0_SA_DQS_DP<3>")
	)
	(arc
		(start 377.26366 -265.803888)
		(mid 377.076462 -265.753745)
		(end 376.889264 -265.803888)
		(width 0.088646)
		(layer "In11.Cu")
		(net "M_H_CPU0_SA_DQS_DP<3>")
	)
	(arc
		(start 384.78206 -269.059152)
		(mid 384.594862 -269.009009)
		(end 384.407664 -269.059152)
		(width 0.088646)
		(layer "In11.Cu")
		(net "M_H_CPU0_SA_DQS_DP<3>")
	)
	(arc
		(start 382.620266 -268.569694)
		(mid 382.572587 -268.386794)
		(end 382.441704 -268.250416)
		(width 0.088646)
		(layer "In11.Cu")
		(net "M_H_CPU0_SA_DQS_DP<3>")
	)
	(arc
		(start 375.934732 -265.812524)
		(mid 375.658291 -265.87969)
		(end 375.38406 -265.803888)
		(width 0.088646)
		(layer "In11.Cu")
		(net "M_H_CPU0_SA_DQS_DP<3>")
	)
	(arc
		(start 376.32386 -265.803888)
		(mid 376.136662 -265.753745)
		(end 375.949464 -265.803888)
		(width 0.088646)
		(layer "In11.Cu")
		(net "M_H_CPU0_SA_DQS_DP<3>")
	)
	(arc
		(start 385.713224 -269.054326)
		(mid 385.529716 -269.009048)
		(end 385.347464 -269.059152)
		(width 0.088646)
		(layer "In11.Cu")
		(net "M_H_CPU0_SA_DQS_DP<3>")
	)
	(arc
		(start 379.14326 -265.803888)
		(mid 378.956062 -265.753745)
		(end 378.768864 -265.803888)
		(width 0.088646)
		(layer "In11.Cu")
		(net "M_H_CPU0_SA_DQS_DP<3>")
	)
	(arc
		(start 372.56466 -265.803888)
		(mid 372.377462 -265.753745)
		(end 372.190264 -265.803888)
		(width 0.088646)
		(layer "In11.Cu")
		(net "M_H_CPU0_SA_DQS_DP<3>")
	)
	(arc
		(start 373.50446 -265.803888)
		(mid 373.317262 -265.753745)
		(end 373.130064 -265.803888)
		(width 0.088646)
		(layer "In11.Cu")
		(net "M_H_CPU0_SA_DQS_DP<3>")
	)
	(arc
		(start 381.680212 -266.941808)
		(mid 381.632533 -266.758908)
		(end 381.50165 -266.62253)
		(width 0.088646)
		(layer "In11.Cu")
		(net "M_H_CPU0_SA_DQS_DP<3>")
	)
	(arc
		(start 381.49276 -266.61745)
		(mid 381.288671 -266.414903)
		(end 381.210566 -266.138152)
		(width 0.088646)
		(layer "In11.Cu")
		(net "M_H_CPU0_SA_DQS_DP<3>")
	)
	(arc
		(start 382.426718 -268.24178)
		(mid 382.224131 -268.035429)
		(end 382.150112 -267.755878)
		(width 0.088646)
		(layer "In11.Cu")
		(net "M_H_CPU0_SA_DQS_DP<3>")
	)
	(segment
		(start 370.968016 -270.167862)
		(end 370.968016 -270.19758)
		(width 0.20066)
		(layer "F.Cu")
		(net "M_H_CPU0_SA_DQS_DP<2>")
	)
	(segment
		(start 457.126594 -294.647874)
		(end 457.120498 -294.641778)
		(width 0.1016)
		(layer "F.Cu")
		(net "M_H_CPU0_SA_DQS_DP<2>")
	)
	(segment
		(start 459.559914 -294.216582)
		(end 459.011274 -294.216582)
		(width 0.20066)
		(layer "F.Cu")
		(net "M_H_CPU0_SA_DQS_DP<2>")
	)
	(segment
		(start 370.967762 -269.66164)
		(end 370.968016 -270.167862)
		(width 0.20066)
		(layer "F.Cu")
		(net "M_H_CPU0_SA_DQS_DP<2>")
	)
	(segment
		(start 458.5335 -293.934896)
		(end 458.123036 -294.34536)
		(width 0.20066)
		(layer "F.Cu")
		(net "M_H_CPU0_SA_DQS_DP<2>")
	)
	(segment
		(start 457.75245 -294.34536)
		(end 457.449936 -294.647874)
		(width 0.20066)
		(layer "F.Cu")
		(net "M_H_CPU0_SA_DQS_DP<2>")
	)
	(segment
		(start 450.911214 -294.216582)
		(end 452.016114 -294.216582)
		(width 0.20066)
		(layer "F.Cu")
		(net "M_H_CPU0_SA_DQS_DP<2>")
	)
	(segment
		(start 459.011274 -294.216582)
		(end 458.729588 -293.934896)
		(width 0.20066)
		(layer "F.Cu")
		(net "M_H_CPU0_SA_DQS_DP<2>")
	)
	(segment
		(start 457.120498 -294.641778)
		(end 454.963276 -294.641778)
		(width 0.1016)
		(layer "F.Cu")
		(net "M_H_CPU0_SA_DQS_DP<2>")
	)
	(segment
		(start 454.963276 -294.641778)
		(end 454.937368 -294.641778)
		(width 0.101854)
		(layer "F.Cu")
		(net "M_H_CPU0_SA_DQS_DP<2>")
	)
	(segment
		(start 453.446388 -293.976044)
		(end 452.845932 -293.976044)
		(width 0.20066)
		(layer "F.Cu")
		(net "M_H_CPU0_SA_DQS_DP<2>")
	)
	(segment
		(start 452.845932 -293.976044)
		(end 452.605394 -294.216582)
		(width 0.20066)
		(layer "F.Cu")
		(net "M_H_CPU0_SA_DQS_DP<2>")
	)
	(segment
		(start 454.937368 -294.641778)
		(end 454.797922 -294.641778)
		(width 0.20066)
		(layer "F.Cu")
		(net "M_H_CPU0_SA_DQS_DP<2>")
	)
	(segment
		(start 454.797922 -294.641778)
		(end 454.546716 -294.390572)
		(width 0.20066)
		(layer "F.Cu")
		(net "M_H_CPU0_SA_DQS_DP<2>")
	)
	(segment
		(start 458.729588 -293.934896)
		(end 458.5335 -293.934896)
		(width 0.20066)
		(layer "F.Cu")
		(net "M_H_CPU0_SA_DQS_DP<2>")
	)
	(segment
		(start 454.546716 -294.390572)
		(end 453.860916 -294.390572)
		(width 0.20066)
		(layer "F.Cu")
		(net "M_H_CPU0_SA_DQS_DP<2>")
	)
	(segment
		(start 457.449936 -294.647874)
		(end 457.126594 -294.647874)
		(width 0.20066)
		(layer "F.Cu")
		(net "M_H_CPU0_SA_DQS_DP<2>")
	)
	(segment
		(start 458.123036 -294.34536)
		(end 457.75245 -294.34536)
		(width 0.20066)
		(layer "F.Cu")
		(net "M_H_CPU0_SA_DQS_DP<2>")
	)
	(segment
		(start 452.605394 -294.216582)
		(end 452.016114 -294.216582)
		(width 0.20066)
		(layer "F.Cu")
		(net "M_H_CPU0_SA_DQS_DP<2>")
	)
	(segment
		(start 453.860916 -294.390572)
		(end 453.446388 -293.976044)
		(width 0.20066)
		(layer "F.Cu")
		(net "M_H_CPU0_SA_DQS_DP<2>")
	)
	(segment
		(start 371.630956 -270.69034)
		(end 371.625114 -270.687038)
		(width 0.088646)
		(layer "In11.Cu")
		(net "M_H_CPU0_SA_DQS_DP<2>")
	)
	(segment
		(start 425.351194 -299.475906)
		(end 425.086272 -299.740828)
		(width 0.18288)
		(layer "In11.Cu")
		(net "M_H_CPU0_SA_DQS_DP<2>")
	)
	(segment
		(start 404.313644 -294.611552)
		(end 399.841212 -290.13912)
		(width 0.18288)
		(layer "In11.Cu")
		(net "M_H_CPU0_SA_DQS_DP<2>")
	)
	(segment
		(start 417.5252 -298.435268)
		(end 416.493452 -298.435268)
		(width 0.18288)
		(layer "In11.Cu")
		(net "M_H_CPU0_SA_DQS_DP<2>")
	)
	(segment
		(start 442.61786 -298.431966)
		(end 442.142626 -298.431966)
		(width 0.18288)
		(layer "In11.Cu")
		(net "M_H_CPU0_SA_DQS_DP<2>")
	)
	(segment
		(start 408.562302 -296.66184)
		(end 407.723848 -295.823386)
		(width 0.18288)
		(layer "In11.Cu")
		(net "M_H_CPU0_SA_DQS_DP<2>")
	)
	(segment
		(start 443.89675 -297.517566)
		(end 443.53226 -297.517566)
		(width 0.18288)
		(layer "In11.Cu")
		(net "M_H_CPU0_SA_DQS_DP<2>")
	)
	(segment
		(start 419.408102 -300.31817)
		(end 417.5252 -298.435268)
		(width 0.18288)
		(layer "In11.Cu")
		(net "M_H_CPU0_SA_DQS_DP<2>")
	)
	(segment
		(start 424.258994 -299.457618)
		(end 422.773602 -299.457618)
		(width 0.18288)
		(layer "In11.Cu")
		(net "M_H_CPU0_SA_DQS_DP<2>")
	)
	(segment
		(start 439.629804 -299.740828)
		(end 439.36285 -299.473874)
		(width 0.18288)
		(layer "In11.Cu")
		(net "M_H_CPU0_SA_DQS_DP<2>")
	)
	(segment
		(start 415.842196 -297.784012)
		(end 413.12846 -297.784012)
		(width 0.18288)
		(layer "In11.Cu")
		(net "M_H_CPU0_SA_DQS_DP<2>")
	)
	(segment
		(start 407.723848 -295.823386)
		(end 407.057098 -295.823386)
		(width 0.18288)
		(layer "In11.Cu")
		(net "M_H_CPU0_SA_DQS_DP<2>")
	)
	(segment
		(start 440.407552 -299.488352)
		(end 440.155076 -299.740828)
		(width 0.18288)
		(layer "In11.Cu")
		(net "M_H_CPU0_SA_DQS_DP<2>")
	)
	(segment
		(start 435.529736 -298.890944)
		(end 435.26964 -298.630848)
		(width 0.18288)
		(layer "In11.Cu")
		(net "M_H_CPU0_SA_DQS_DP<2>")
	)
	(segment
		(start 437.051196 -298.626022)
		(end 436.316374 -298.626022)
		(width 0.18288)
		(layer "In11.Cu")
		(net "M_H_CPU0_SA_DQS_DP<2>")
	)
	(segment
		(start 421.91305 -300.31817)
		(end 421.199818 -300.31817)
		(width 0.18288)
		(layer "In11.Cu")
		(net "M_H_CPU0_SA_DQS_DP<2>")
	)
	(segment
		(start 373.510556 -270.69034)
		(end 373.506238 -270.6878)
		(width 0.088646)
		(layer "In11.Cu")
		(net "M_H_CPU0_SA_DQS_DP<2>")
	)
	(segment
		(start 371.625114 -270.687038)
		(end 371.623082 -270.685768)
		(width 0.088646)
		(layer "In11.Cu")
		(net "M_H_CPU0_SA_DQS_DP<2>")
	)
	(segment
		(start 427.558454 -298.808648)
		(end 426.77588 -298.808648)
		(width 0.18288)
		(layer "In11.Cu")
		(net "M_H_CPU0_SA_DQS_DP<2>")
	)
	(segment
		(start 426.77588 -298.808648)
		(end 426.108622 -299.475906)
		(width 0.18288)
		(layer "In11.Cu")
		(net "M_H_CPU0_SA_DQS_DP<2>")
	)
	(segment
		(start 439.36285 -299.473874)
		(end 437.899048 -299.473874)
		(width 0.18288)
		(layer "In11.Cu")
		(net "M_H_CPU0_SA_DQS_DP<2>")
	)
	(segment
		(start 381.588264 -273.942556)
		(end 381.57785 -273.948652)
		(width 0.088646)
		(layer "In11.Cu")
		(net "M_H_CPU0_SA_DQS_DP<2>")
	)
	(segment
		(start 378.21235 -272.320004)
		(end 378.20346 -272.314924)
		(width 0.088646)
		(layer "In11.Cu")
		(net "M_H_CPU0_SA_DQS_DP<2>")
	)
	(segment
		(start 424.542204 -299.740828)
		(end 424.258994 -299.457618)
		(width 0.18288)
		(layer "In11.Cu")
		(net "M_H_CPU0_SA_DQS_DP<2>")
	)
	(segment
		(start 443.53226 -297.517566)
		(end 442.61786 -298.431966)
		(width 0.18288)
		(layer "In11.Cu")
		(net "M_H_CPU0_SA_DQS_DP<2>")
	)
	(segment
		(start 436.316374 -298.626022)
		(end 436.051452 -298.890944)
		(width 0.18288)
		(layer "In11.Cu")
		(net "M_H_CPU0_SA_DQS_DP<2>")
	)
	(segment
		(start 383.467864 -273.942556)
		(end 383.453132 -273.951192)
		(width 0.088646)
		(layer "In11.Cu")
		(net "M_H_CPU0_SA_DQS_DP<2>")
	)
	(segment
		(start 420.50589 -300.591474)
		(end 420.232586 -300.31817)
		(width 0.18288)
		(layer "In11.Cu")
		(net "M_H_CPU0_SA_DQS_DP<2>")
	)
	(segment
		(start 440.155076 -299.740828)
		(end 439.629804 -299.740828)
		(width 0.18288)
		(layer "In11.Cu")
		(net "M_H_CPU0_SA_DQS_DP<2>")
	)
	(segment
		(start 399.841212 -288.18967)
		(end 387.557772 -275.90623)
		(width 0.18288)
		(layer "In11.Cu")
		(net "M_H_CPU0_SA_DQS_DP<2>")
	)
	(segment
		(start 420.232586 -300.31817)
		(end 419.408102 -300.31817)
		(width 0.18288)
		(layer "In11.Cu")
		(net "M_H_CPU0_SA_DQS_DP<2>")
	)
	(segment
		(start 371.346222 -270.263112)
		(end 371.28069 -270.19758)
		(width 0.088646)
		(layer "In11.Cu")
		(net "M_H_CPU0_SA_DQS_DP<2>")
	)
	(segment
		(start 387.242558 -275.90623)
		(end 387.182614 -275.846286)
		(width 0.088646)
		(layer "In11.Cu")
		(net "M_H_CPU0_SA_DQS_DP<2>")
	)
	(segment
		(start 426.108622 -299.475906)
		(end 425.351194 -299.475906)
		(width 0.18288)
		(layer "In11.Cu")
		(net "M_H_CPU0_SA_DQS_DP<2>")
	)
	(segment
		(start 413.12846 -297.784012)
		(end 412.006288 -296.66184)
		(width 0.18288)
		(layer "In11.Cu")
		(net "M_H_CPU0_SA_DQS_DP<2>")
	)
	(segment
		(start 372.570756 -270.69034)
		(end 372.566438 -270.6878)
		(width 0.088646)
		(layer "In11.Cu")
		(net "M_H_CPU0_SA_DQS_DP<2>")
	)
	(segment
		(start 405.845264 -294.611552)
		(end 404.313644 -294.611552)
		(width 0.18288)
		(layer "In11.Cu")
		(net "M_H_CPU0_SA_DQS_DP<2>")
	)
	(segment
		(start 378.682504 -273.13382)
		(end 378.673614 -273.12874)
		(width 0.088646)
		(layer "In11.Cu")
		(net "M_H_CPU0_SA_DQS_DP<2>")
	)
	(segment
		(start 386.704332 -275.846286)
		(end 384.85953 -274.001484)
		(width 0.088646)
		(layer "In11.Cu")
		(net "M_H_CPU0_SA_DQS_DP<2>")
	)
	(segment
		(start 420.926514 -300.591474)
		(end 420.50589 -300.591474)
		(width 0.18288)
		(layer "In11.Cu")
		(net "M_H_CPU0_SA_DQS_DP<2>")
	)
	(segment
		(start 445.3001 -296.114216)
		(end 443.89675 -297.517566)
		(width 0.18288)
		(layer "In11.Cu")
		(net "M_H_CPU0_SA_DQS_DP<2>")
	)
	(segment
		(start 430.088294 -297.761914)
		(end 428.597822 -299.252386)
		(width 0.18288)
		(layer "In11.Cu")
		(net "M_H_CPU0_SA_DQS_DP<2>")
	)
	(segment
		(start 407.057098 -295.823386)
		(end 405.845264 -294.611552)
		(width 0.18288)
		(layer "In11.Cu")
		(net "M_H_CPU0_SA_DQS_DP<2>")
	)
	(segment
		(start 431.185066 -297.761914)
		(end 430.088294 -297.761914)
		(width 0.18288)
		(layer "In11.Cu")
		(net "M_H_CPU0_SA_DQS_DP<2>")
	)
	(segment
		(start 377.742704 -271.505934)
		(end 377.735338 -271.501616)
		(width 0.088646)
		(layer "In11.Cu")
		(net "M_H_CPU0_SA_DQS_DP<2>")
	)
	(segment
		(start 437.899048 -299.473874)
		(end 437.051196 -298.626022)
		(width 0.18288)
		(layer "In11.Cu")
		(net "M_H_CPU0_SA_DQS_DP<2>")
	)
	(segment
		(start 378.861066 -273.468592)
		(end 378.861066 -273.453098)
		(width 0.088646)
		(layer "In11.Cu")
		(net "M_H_CPU0_SA_DQS_DP<2>")
	)
	(segment
		(start 379.708664 -273.942556)
		(end 379.693932 -273.951192)
		(width 0.088646)
		(layer "In11.Cu")
		(net "M_H_CPU0_SA_DQS_DP<2>")
	)
	(segment
		(start 380.648718 -273.942556)
		(end 380.638304 -273.948652)
		(width 0.088646)
		(layer "In11.Cu")
		(net "M_H_CPU0_SA_DQS_DP<2>")
	)
	(segment
		(start 416.493452 -298.435268)
		(end 415.842196 -297.784012)
		(width 0.18288)
		(layer "In11.Cu")
		(net "M_H_CPU0_SA_DQS_DP<2>")
	)
	(segment
		(start 428.597822 -299.252386)
		(end 428.002192 -299.252386)
		(width 0.18288)
		(layer "In11.Cu")
		(net "M_H_CPU0_SA_DQS_DP<2>")
	)
	(segment
		(start 374.446038 -270.6878)
		(end 374.438672 -270.683736)
		(width 0.088646)
		(layer "In11.Cu")
		(net "M_H_CPU0_SA_DQS_DP<2>")
	)
	(segment
		(start 450.911214 -294.216582)
		(end 450.658738 -293.964106)
		(width 0.18288)
		(layer "In11.Cu")
		(net "M_H_CPU0_SA_DQS_DP<2>")
	)
	(segment
		(start 387.182614 -275.846286)
		(end 386.704332 -275.846286)
		(width 0.088646)
		(layer "In11.Cu")
		(net "M_H_CPU0_SA_DQS_DP<2>")
	)
	(segment
		(start 371.28069 -270.19758)
		(end 370.968016 -270.19758)
		(width 0.088646)
		(layer "In11.Cu")
		(net "M_H_CPU0_SA_DQS_DP<2>")
	)
	(segment
		(start 450.658738 -293.964106)
		(end 450.158358 -293.964106)
		(width 0.18288)
		(layer "In11.Cu")
		(net "M_H_CPU0_SA_DQS_DP<2>")
	)
	(segment
		(start 412.006288 -296.66184)
		(end 408.562302 -296.66184)
		(width 0.18288)
		(layer "In11.Cu")
		(net "M_H_CPU0_SA_DQS_DP<2>")
	)
	(segment
		(start 432.054 -298.630848)
		(end 431.185066 -297.761914)
		(width 0.18288)
		(layer "In11.Cu")
		(net "M_H_CPU0_SA_DQS_DP<2>")
	)
	(segment
		(start 441.08624 -299.488352)
		(end 440.407552 -299.488352)
		(width 0.18288)
		(layer "In11.Cu")
		(net "M_H_CPU0_SA_DQS_DP<2>")
	)
	(segment
		(start 449.36918 -293.779956)
		(end 448.024504 -295.124632)
		(width 0.18288)
		(layer "In11.Cu")
		(net "M_H_CPU0_SA_DQS_DP<2>")
	)
	(segment
		(start 450.158358 -293.964106)
		(end 449.974208 -293.779956)
		(width 0.18288)
		(layer "In11.Cu")
		(net "M_H_CPU0_SA_DQS_DP<2>")
	)
	(segment
		(start 449.974208 -293.779956)
		(end 449.36918 -293.779956)
		(width 0.18288)
		(layer "In11.Cu")
		(net "M_H_CPU0_SA_DQS_DP<2>")
	)
	(segment
		(start 425.086272 -299.740828)
		(end 424.542204 -299.740828)
		(width 0.18288)
		(layer "In11.Cu")
		(net "M_H_CPU0_SA_DQS_DP<2>")
	)
	(segment
		(start 421.199818 -300.31817)
		(end 420.926514 -300.591474)
		(width 0.18288)
		(layer "In11.Cu")
		(net "M_H_CPU0_SA_DQS_DP<2>")
	)
	(segment
		(start 376.33275 -270.692118)
		(end 376.32386 -270.687038)
		(width 0.088646)
		(layer "In11.Cu")
		(net "M_H_CPU0_SA_DQS_DP<2>")
	)
	(segment
		(start 373.506238 -270.6878)
		(end 373.498872 -270.683736)
		(width 0.088646)
		(layer "In11.Cu")
		(net "M_H_CPU0_SA_DQS_DP<2>")
	)
	(segment
		(start 447.110104 -295.124632)
		(end 446.12052 -296.114216)
		(width 0.18288)
		(layer "In11.Cu")
		(net "M_H_CPU0_SA_DQS_DP<2>")
	)
	(segment
		(start 435.26964 -298.630848)
		(end 432.054 -298.630848)
		(width 0.18288)
		(layer "In11.Cu")
		(net "M_H_CPU0_SA_DQS_DP<2>")
	)
	(segment
		(start 428.002192 -299.252386)
		(end 427.558454 -298.808648)
		(width 0.18288)
		(layer "In11.Cu")
		(net "M_H_CPU0_SA_DQS_DP<2>")
	)
	(segment
		(start 375.949464 -270.687038)
		(end 375.934732 -270.695674)
		(width 0.088646)
		(layer "In11.Cu")
		(net "M_H_CPU0_SA_DQS_DP<2>")
	)
	(segment
		(start 376.809254 -271.50949)
		(end 376.787918 -271.497298)
		(width 0.088646)
		(layer "In11.Cu")
		(net "M_H_CPU0_SA_DQS_DP<2>")
	)
	(segment
		(start 399.841212 -290.13912)
		(end 399.841212 -288.18967)
		(width 0.18288)
		(layer "In11.Cu")
		(net "M_H_CPU0_SA_DQS_DP<2>")
	)
	(segment
		(start 422.773602 -299.457618)
		(end 421.91305 -300.31817)
		(width 0.18288)
		(layer "In11.Cu")
		(net "M_H_CPU0_SA_DQS_DP<2>")
	)
	(segment
		(start 376.808746 -271.50949)
		(end 376.809254 -271.50949)
		(width 0.088646)
		(layer "In11.Cu")
		(net "M_H_CPU0_SA_DQS_DP<2>")
	)
	(segment
		(start 446.12052 -296.114216)
		(end 445.3001 -296.114216)
		(width 0.18288)
		(layer "In11.Cu")
		(net "M_H_CPU0_SA_DQS_DP<2>")
	)
	(segment
		(start 372.566438 -270.6878)
		(end 372.559072 -270.683736)
		(width 0.088646)
		(layer "In11.Cu")
		(net "M_H_CPU0_SA_DQS_DP<2>")
	)
	(segment
		(start 442.142626 -298.431966)
		(end 441.08624 -299.488352)
		(width 0.18288)
		(layer "In11.Cu")
		(net "M_H_CPU0_SA_DQS_DP<2>")
	)
	(segment
		(start 382.528064 -273.942556)
		(end 382.513332 -273.951192)
		(width 0.088646)
		(layer "In11.Cu")
		(net "M_H_CPU0_SA_DQS_DP<2>")
	)
	(segment
		(start 377.735338 -271.501616)
		(end 377.733814 -271.500854)
		(width 0.088646)
		(layer "In11.Cu")
		(net "M_H_CPU0_SA_DQS_DP<2>")
	)
	(segment
		(start 377.921266 -271.84731)
		(end 377.921266 -271.825212)
		(width 0.088646)
		(layer "In11.Cu")
		(net "M_H_CPU0_SA_DQS_DP<2>")
	)
	(segment
		(start 436.051452 -298.890944)
		(end 435.529736 -298.890944)
		(width 0.18288)
		(layer "In11.Cu")
		(net "M_H_CPU0_SA_DQS_DP<2>")
	)
	(segment
		(start 374.450356 -270.69034)
		(end 374.446038 -270.6878)
		(width 0.088646)
		(layer "In11.Cu")
		(net "M_H_CPU0_SA_DQS_DP<2>")
	)
	(segment
		(start 448.024504 -295.124632)
		(end 447.110104 -295.124632)
		(width 0.18288)
		(layer "In11.Cu")
		(net "M_H_CPU0_SA_DQS_DP<2>")
	)
	(segment
		(start 378.673614 -273.12874)
		(end 378.667518 -273.125184)
		(width 0.088646)
		(layer "In11.Cu")
		(net "M_H_CPU0_SA_DQS_DP<2>")
	)
	(segment
		(start 387.557772 -275.90623)
		(end 387.242558 -275.90623)
		(width 0.18288)
		(layer "In11.Cu")
		(net "M_H_CPU0_SA_DQS_DP<2>")
	)
	(arc
		(start 372.559072 -270.683736)
		(mid 372.374217 -270.636786)
		(end 372.190264 -270.687038)
		(width 0.088646)
		(layer "In11.Cu")
		(net "M_H_CPU0_SA_DQS_DP<2>")
	)
	(arc
		(start 375.38406 -270.687038)
		(mid 375.196862 -270.636895)
		(end 375.009664 -270.687038)
		(width 0.088646)
		(layer "In11.Cu")
		(net "M_H_CPU0_SA_DQS_DP<2>")
	)
	(arc
		(start 379.693932 -273.951192)
		(mid 379.417457 -274.018512)
		(end 379.14326 -273.942556)
		(width 0.088646)
		(layer "In11.Cu")
		(net "M_H_CPU0_SA_DQS_DP<2>")
	)
	(arc
		(start 376.511312 -271.011396)
		(mid 376.463633 -270.828496)
		(end 376.33275 -270.692118)
		(width 0.088646)
		(layer "In11.Cu")
		(net "M_H_CPU0_SA_DQS_DP<2>")
	)
	(arc
		(start 377.921266 -271.825212)
		(mid 377.873587 -271.642312)
		(end 377.742704 -271.505934)
		(width 0.088646)
		(layer "In11.Cu")
		(net "M_H_CPU0_SA_DQS_DP<2>")
	)
	(arc
		(start 382.90246 -273.942556)
		(mid 382.715262 -273.892413)
		(end 382.528064 -273.942556)
		(width 0.088646)
		(layer "In11.Cu")
		(net "M_H_CPU0_SA_DQS_DP<2>")
	)
	(arc
		(start 384.85953 -274.001484)
		(mid 384.822718 -273.969491)
		(end 384.78206 -273.942556)
		(width 0.088646)
		(layer "In11.Cu")
		(net "M_H_CPU0_SA_DQS_DP<2>")
	)
	(arc
		(start 384.407664 -273.942556)
		(mid 384.124962 -274.018332)
		(end 383.84226 -273.942556)
		(width 0.088646)
		(layer "In11.Cu")
		(net "M_H_CPU0_SA_DQS_DP<2>")
	)
	(arc
		(start 383.84226 -273.942556)
		(mid 383.655062 -273.892413)
		(end 383.467864 -273.942556)
		(width 0.088646)
		(layer "In11.Cu")
		(net "M_H_CPU0_SA_DQS_DP<2>")
	)
	(arc
		(start 380.638304 -273.948652)
		(mid 380.359872 -274.018498)
		(end 380.08306 -273.942556)
		(width 0.088646)
		(layer "In11.Cu")
		(net "M_H_CPU0_SA_DQS_DP<2>")
	)
	(arc
		(start 377.359418 -271.500854)
		(mid 377.085219 -271.576689)
		(end 376.808746 -271.50949)
		(width 0.088646)
		(layer "In11.Cu")
		(net "M_H_CPU0_SA_DQS_DP<2>")
	)
	(arc
		(start 371.623082 -270.685768)
		(mid 371.471428 -270.556806)
		(end 371.373908 -270.383254)
		(width 0.088646)
		(layer "In11.Cu")
		(net "M_H_CPU0_SA_DQS_DP<2>")
	)
	(arc
		(start 376.787918 -271.497298)
		(mid 376.585331 -271.290947)
		(end 376.511312 -271.011396)
		(width 0.088646)
		(layer "In11.Cu")
		(net "M_H_CPU0_SA_DQS_DP<2>")
	)
	(arc
		(start 380.08306 -273.942556)
		(mid 379.895862 -273.892413)
		(end 379.708664 -273.942556)
		(width 0.088646)
		(layer "In11.Cu")
		(net "M_H_CPU0_SA_DQS_DP<2>")
	)
	(arc
		(start 378.861066 -273.453098)
		(mid 378.813387 -273.270198)
		(end 378.682504 -273.13382)
		(width 0.088646)
		(layer "In11.Cu")
		(net "M_H_CPU0_SA_DQS_DP<2>")
	)
	(arc
		(start 374.438672 -270.683736)
		(mid 374.253817 -270.636786)
		(end 374.069864 -270.687038)
		(width 0.088646)
		(layer "In11.Cu")
		(net "M_H_CPU0_SA_DQS_DP<2>")
	)
	(arc
		(start 379.14326 -273.942556)
		(mid 378.940437 -273.742325)
		(end 378.861066 -273.468592)
		(width 0.088646)
		(layer "In11.Cu")
		(net "M_H_CPU0_SA_DQS_DP<2>")
	)
	(arc
		(start 374.069864 -270.687038)
		(mid 373.790661 -270.762678)
		(end 373.510556 -270.69034)
		(width 0.088646)
		(layer "In11.Cu")
		(net "M_H_CPU0_SA_DQS_DP<2>")
	)
	(arc
		(start 382.513332 -273.951192)
		(mid 382.236857 -274.018512)
		(end 381.96266 -273.942556)
		(width 0.088646)
		(layer "In11.Cu")
		(net "M_H_CPU0_SA_DQS_DP<2>")
	)
	(arc
		(start 383.453132 -273.951192)
		(mid 383.176657 -274.018512)
		(end 382.90246 -273.942556)
		(width 0.088646)
		(layer "In11.Cu")
		(net "M_H_CPU0_SA_DQS_DP<2>")
	)
	(arc
		(start 373.498872 -270.683736)
		(mid 373.314017 -270.636786)
		(end 373.130064 -270.687038)
		(width 0.088646)
		(layer "In11.Cu")
		(net "M_H_CPU0_SA_DQS_DP<2>")
	)
	(arc
		(start 371.34927 -270.284194)
		(mid 371.347646 -270.273667)
		(end 371.346222 -270.263112)
		(width 0.088646)
		(layer "In11.Cu")
		(net "M_H_CPU0_SA_DQS_DP<2>")
	)
	(arc
		(start 378.667518 -273.125184)
		(mid 378.464931 -272.918833)
		(end 378.390912 -272.639282)
		(width 0.088646)
		(layer "In11.Cu")
		(net "M_H_CPU0_SA_DQS_DP<2>")
	)
	(arc
		(start 371.373908 -270.383254)
		(mid 371.359345 -270.334282)
		(end 371.34927 -270.284194)
		(width 0.088646)
		(layer "In11.Cu")
		(net "M_H_CPU0_SA_DQS_DP<2>")
	)
	(arc
		(start 378.20346 -272.314924)
		(mid 378.002178 -272.117437)
		(end 377.921266 -271.84731)
		(width 0.088646)
		(layer "In11.Cu")
		(net "M_H_CPU0_SA_DQS_DP<2>")
	)
	(arc
		(start 378.390658 -272.62455)
		(mid 378.339604 -272.44997)
		(end 378.21235 -272.320004)
		(width 0.088646)
		(layer "In11.Cu")
		(net "M_H_CPU0_SA_DQS_DP<2>")
	)
	(arc
		(start 377.733814 -271.500854)
		(mid 377.546616 -271.450711)
		(end 377.359418 -271.500854)
		(width 0.088646)
		(layer "In11.Cu")
		(net "M_H_CPU0_SA_DQS_DP<2>")
	)
	(arc
		(start 373.130064 -270.687038)
		(mid 372.850861 -270.762678)
		(end 372.570756 -270.69034)
		(width 0.088646)
		(layer "In11.Cu")
		(net "M_H_CPU0_SA_DQS_DP<2>")
	)
	(arc
		(start 381.57785 -273.948652)
		(mid 381.299672 -274.018375)
		(end 381.023114 -273.942556)
		(width 0.088646)
		(layer "In11.Cu")
		(net "M_H_CPU0_SA_DQS_DP<2>")
	)
	(arc
		(start 381.96266 -273.942556)
		(mid 381.775462 -273.892413)
		(end 381.588264 -273.942556)
		(width 0.088646)
		(layer "In11.Cu")
		(net "M_H_CPU0_SA_DQS_DP<2>")
	)
	(arc
		(start 378.390912 -272.639282)
		(mid 378.39086 -272.631915)
		(end 378.390658 -272.62455)
		(width 0.088646)
		(layer "In11.Cu")
		(net "M_H_CPU0_SA_DQS_DP<2>")
	)
	(arc
		(start 372.190264 -270.687038)
		(mid 371.911061 -270.762678)
		(end 371.630956 -270.69034)
		(width 0.088646)
		(layer "In11.Cu")
		(net "M_H_CPU0_SA_DQS_DP<2>")
	)
	(arc
		(start 375.934732 -270.695674)
		(mid 375.658257 -270.762994)
		(end 375.38406 -270.687038)
		(width 0.088646)
		(layer "In11.Cu")
		(net "M_H_CPU0_SA_DQS_DP<2>")
	)
	(arc
		(start 384.78206 -273.942556)
		(mid 384.594862 -273.892413)
		(end 384.407664 -273.942556)
		(width 0.088646)
		(layer "In11.Cu")
		(net "M_H_CPU0_SA_DQS_DP<2>")
	)
	(arc
		(start 375.009664 -270.687038)
		(mid 374.730461 -270.762678)
		(end 374.450356 -270.69034)
		(width 0.088646)
		(layer "In11.Cu")
		(net "M_H_CPU0_SA_DQS_DP<2>")
	)
	(arc
		(start 376.32386 -270.687038)
		(mid 376.136662 -270.636895)
		(end 375.949464 -270.687038)
		(width 0.088646)
		(layer "In11.Cu")
		(net "M_H_CPU0_SA_DQS_DP<2>")
	)
	(arc
		(start 381.023114 -273.942556)
		(mid 380.835916 -273.892413)
		(end 380.648718 -273.942556)
		(width 0.088646)
		(layer "In11.Cu")
		(net "M_H_CPU0_SA_DQS_DP<2>")
	)
	(segment
		(start 458.5335 -303.28489)
		(end 458.123036 -303.695354)
		(width 0.20066)
		(layer "F.Cu")
		(net "M_H_CPU0_SA_DQS_DP<1>")
	)
	(segment
		(start 371.907562 -274.54479)
		(end 371.907816 -274.545044)
		(width 0.20066)
		(layer "F.Cu")
		(net "M_H_CPU0_SA_DQS_DP<1>")
	)
	(segment
		(start 454.963276 -303.991772)
		(end 454.937368 -303.991772)
		(width 0.101854)
		(layer "F.Cu")
		(net "M_H_CPU0_SA_DQS_DP<1>")
	)
	(segment
		(start 459.559914 -303.566576)
		(end 459.011274 -303.566576)
		(width 0.20066)
		(layer "F.Cu")
		(net "M_H_CPU0_SA_DQS_DP<1>")
	)
	(segment
		(start 458.123036 -303.695354)
		(end 457.75245 -303.695354)
		(width 0.20066)
		(layer "F.Cu")
		(net "M_H_CPU0_SA_DQS_DP<1>")
	)
	(segment
		(start 454.546716 -303.740566)
		(end 453.860916 -303.740566)
		(width 0.20066)
		(layer "F.Cu")
		(net "M_H_CPU0_SA_DQS_DP<1>")
	)
	(segment
		(start 457.449936 -303.997868)
		(end 457.126594 -303.997868)
		(width 0.20066)
		(layer "F.Cu")
		(net "M_H_CPU0_SA_DQS_DP<1>")
	)
	(segment
		(start 454.937368 -303.991772)
		(end 454.797922 -303.991772)
		(width 0.20066)
		(layer "F.Cu")
		(net "M_H_CPU0_SA_DQS_DP<1>")
	)
	(segment
		(start 371.907816 -274.545044)
		(end 371.907816 -275.08073)
		(width 0.20066)
		(layer "F.Cu")
		(net "M_H_CPU0_SA_DQS_DP<1>")
	)
	(segment
		(start 452.605394 -303.566576)
		(end 452.016114 -303.566576)
		(width 0.20066)
		(layer "F.Cu")
		(net "M_H_CPU0_SA_DQS_DP<1>")
	)
	(segment
		(start 457.126594 -303.997868)
		(end 457.120498 -303.991772)
		(width 0.1016)
		(layer "F.Cu")
		(net "M_H_CPU0_SA_DQS_DP<1>")
	)
	(segment
		(start 453.446388 -303.326038)
		(end 452.845932 -303.326038)
		(width 0.20066)
		(layer "F.Cu")
		(net "M_H_CPU0_SA_DQS_DP<1>")
	)
	(segment
		(start 459.011274 -303.566576)
		(end 458.729588 -303.28489)
		(width 0.20066)
		(layer "F.Cu")
		(net "M_H_CPU0_SA_DQS_DP<1>")
	)
	(segment
		(start 452.845932 -303.326038)
		(end 452.605394 -303.566576)
		(width 0.20066)
		(layer "F.Cu")
		(net "M_H_CPU0_SA_DQS_DP<1>")
	)
	(segment
		(start 454.797922 -303.991772)
		(end 454.546716 -303.740566)
		(width 0.20066)
		(layer "F.Cu")
		(net "M_H_CPU0_SA_DQS_DP<1>")
	)
	(segment
		(start 457.120498 -303.991772)
		(end 454.963276 -303.991772)
		(width 0.1016)
		(layer "F.Cu")
		(net "M_H_CPU0_SA_DQS_DP<1>")
	)
	(segment
		(start 453.860916 -303.740566)
		(end 453.446388 -303.326038)
		(width 0.20066)
		(layer "F.Cu")
		(net "M_H_CPU0_SA_DQS_DP<1>")
	)
	(segment
		(start 458.729588 -303.28489)
		(end 458.5335 -303.28489)
		(width 0.20066)
		(layer "F.Cu")
		(net "M_H_CPU0_SA_DQS_DP<1>")
	)
	(segment
		(start 457.75245 -303.695354)
		(end 457.449936 -303.997868)
		(width 0.20066)
		(layer "F.Cu")
		(net "M_H_CPU0_SA_DQS_DP<1>")
	)
	(segment
		(start 450.911214 -303.566576)
		(end 452.016114 -303.566576)
		(width 0.20066)
		(layer "F.Cu")
		(net "M_H_CPU0_SA_DQS_DP<1>")
	)
	(segment
		(start 443.346332 -308.769766)
		(end 442.508132 -309.607966)
		(width 0.18288)
		(layer "In11.Cu")
		(net "M_H_CPU0_SA_DQS_DP<1>")
	)
	(segment
		(start 411.28188 -309.66537)
		(end 411.15742 -309.54091)
		(width 0.18288)
		(layer "In11.Cu")
		(net "M_H_CPU0_SA_DQS_DP<1>")
	)
	(segment
		(start 440.384692 -310.557672)
		(end 440.15152 -310.790844)
		(width 0.18288)
		(layer "In11.Cu")
		(net "M_H_CPU0_SA_DQS_DP<1>")
	)
	(segment
		(start 418.898578 -310.905398)
		(end 418.722556 -310.905398)
		(width 0.18288)
		(layer "In11.Cu")
		(net "M_H_CPU0_SA_DQS_DP<1>")
	)
	(segment
		(start 436.316374 -309.676038)
		(end 436.051452 -309.94096)
		(width 0.18288)
		(layer "In11.Cu")
		(net "M_H_CPU0_SA_DQS_DP<1>")
	)
	(segment
		(start 418.722556 -310.905398)
		(end 418.334444 -310.517286)
		(width 0.18288)
		(layer "In11.Cu")
		(net "M_H_CPU0_SA_DQS_DP<1>")
	)
	(segment
		(start 446.870074 -306.362862)
		(end 446.09385 -307.139086)
		(width 0.18288)
		(layer "In11.Cu")
		(net "M_H_CPU0_SA_DQS_DP<1>")
	)
	(segment
		(start 393.251944 -292.291516)
		(end 393.251944 -290.768278)
		(width 0.18288)
		(layer "In11.Cu")
		(net "M_H_CPU0_SA_DQS_DP<1>")
	)
	(segment
		(start 436.977536 -309.676038)
		(end 436.316374 -309.676038)
		(width 0.18288)
		(layer "In11.Cu")
		(net "M_H_CPU0_SA_DQS_DP<1>")
	)
	(segment
		(start 439.629804 -310.790844)
		(end 439.346594 -310.507634)
		(width 0.18288)
		(layer "In11.Cu")
		(net "M_H_CPU0_SA_DQS_DP<1>")
	)
	(segment
		(start 372.409974 -275.482812)
		(end 372.232428 -275.34997)
		(width 0.088646)
		(layer "In11.Cu")
		(net "M_H_CPU0_SA_DQS_DP<1>")
	)
	(segment
		(start 448.210178 -305.636676)
		(end 447.483992 -306.362862)
		(width 0.18288)
		(layer "In11.Cu")
		(net "M_H_CPU0_SA_DQS_DP<1>")
	)
	(segment
		(start 426.779944 -309.798974)
		(end 426.052996 -310.525922)
		(width 0.18288)
		(layer "In11.Cu")
		(net "M_H_CPU0_SA_DQS_DP<1>")
	)
	(segment
		(start 383.380996 -279.644856)
		(end 383.373122 -279.640284)
		(width 0.088646)
		(layer "In11.Cu")
		(net "M_H_CPU0_SA_DQS_DP<1>")
	)
	(segment
		(start 383.85115 -280.458926)
		(end 383.84226 -280.453846)
		(width 0.088646)
		(layer "In11.Cu")
		(net "M_H_CPU0_SA_DQS_DP<1>")
	)
	(segment
		(start 428.482252 -310.38546)
		(end 428.357792 -310.261)
		(width 0.18288)
		(layer "In11.Cu")
		(net "M_H_CPU0_SA_DQS_DP<1>")
	)
	(segment
		(start 411.95498 -309.54091)
		(end 411.83052 -309.66537)
		(width 0.18288)
		(layer "In11.Cu")
		(net "M_H_CPU0_SA_DQS_DP<1>")
	)
	(segment
		(start 424.292014 -310.540654)
		(end 423.551096 -310.540654)
		(width 0.18288)
		(layer "In11.Cu")
		(net "M_H_CPU0_SA_DQS_DP<1>")
	)
	(segment
		(start 373.977662 -276.38629)
		(end 373.9769 -276.385782)
		(width 0.088646)
		(layer "In11.Cu")
		(net "M_H_CPU0_SA_DQS_DP<1>")
	)
	(segment
		(start 385.26085 -281.272742)
		(end 385.25196 -281.267662)
		(width 0.088646)
		(layer "In11.Cu")
		(net "M_H_CPU0_SA_DQS_DP<1>")
	)
	(segment
		(start 406.334722 -308.8767)
		(end 406.236932 -308.730142)
		(width 0.18288)
		(layer "In11.Cu")
		(net "M_H_CPU0_SA_DQS_DP<1>")
	)
	(segment
		(start 418.334444 -310.341264)
		(end 417.410392 -309.417212)
		(width 0.18288)
		(layer "In11.Cu")
		(net "M_H_CPU0_SA_DQS_DP<1>")
	)
	(segment
		(start 386.986018 -284.502352)
		(end 386.986018 -283.740352)
		(width 0.18288)
		(layer "In11.Cu")
		(net "M_H_CPU0_SA_DQS_DP<1>")
	)
	(segment
		(start 414.75279 -308.66588)
		(end 414.62833 -308.79034)
		(width 0.18288)
		(layer "In11.Cu")
		(net "M_H_CPU0_SA_DQS_DP<1>")
	)
	(segment
		(start 383.559558 -279.971754)
		(end 383.559558 -279.964134)
		(width 0.088646)
		(layer "In11.Cu")
		(net "M_H_CPU0_SA_DQS_DP<1>")
	)
	(segment
		(start 378.688346 -279.648412)
		(end 378.673614 -279.639776)
		(width 0.088646)
		(layer "In11.Cu")
		(net "M_H_CPU0_SA_DQS_DP<1>")
	)
	(segment
		(start 421.200326 -311.37606)
		(end 420.935404 -311.640982)
		(width 0.18288)
		(layer "In11.Cu")
		(net "M_H_CPU0_SA_DQS_DP<1>")
	)
	(segment
		(start 402.989542 -306.208938)
		(end 402.601684 -305.82108)
		(width 0.18288)
		(layer "In11.Cu")
		(net "M_H_CPU0_SA_DQS_DP<1>")
	)
	(segment
		(start 444.118746 -308.381908)
		(end 443.730888 -308.769766)
		(width 0.18288)
		(layer "In11.Cu")
		(net "M_H_CPU0_SA_DQS_DP<1>")
	)
	(segment
		(start 432.954938 -309.667656)
		(end 431.552858 -309.667656)
		(width 0.18288)
		(layer "In11.Cu")
		(net "M_H_CPU0_SA_DQS_DP<1>")
	)
	(segment
		(start 383.373122 -279.640284)
		(end 383.372106 -279.639776)
		(width 0.088646)
		(layer "In11.Cu")
		(net "M_H_CPU0_SA_DQS_DP<1>")
	)
	(segment
		(start 433.752498 -309.667656)
		(end 433.628038 -309.792116)
		(width 0.18288)
		(layer "In11.Cu")
		(net "M_H_CPU0_SA_DQS_DP<1>")
	)
	(segment
		(start 375.949464 -278.82596)
		(end 375.934732 -278.834596)
		(width 0.088646)
		(layer "In11.Cu")
		(net "M_H_CPU0_SA_DQS_DP<1>")
	)
	(segment
		(start 440.984386 -310.557672)
		(end 440.384692 -310.557672)
		(width 0.18288)
		(layer "In11.Cu")
		(net "M_H_CPU0_SA_DQS_DP<1>")
	)
	(segment
		(start 420.935404 -311.640982)
		(end 420.442136 -311.640982)
		(width 0.18288)
		(layer "In11.Cu")
		(net "M_H_CPU0_SA_DQS_DP<1>")
	)
	(segment
		(start 385.909312 -282.42006)
		(end 385.909312 -282.405836)
		(width 0.088646)
		(layer "In11.Cu")
		(net "M_H_CPU0_SA_DQS_DP<1>")
	)
	(segment
		(start 381.507746 -279.648412)
		(end 381.493014 -279.639776)
		(width 0.088646)
		(layer "In11.Cu")
		(net "M_H_CPU0_SA_DQS_DP<1>")
	)
	(segment
		(start 447.483992 -306.362862)
		(end 446.870074 -306.362862)
		(width 0.18288)
		(layer "In11.Cu")
		(net "M_H_CPU0_SA_DQS_DP<1>")
	)
	(segment
		(start 433.628038 -309.792116)
		(end 433.079398 -309.792116)
		(width 0.18288)
		(layer "In11.Cu")
		(net "M_H_CPU0_SA_DQS_DP<1>")
	)
	(segment
		(start 419.335712 -311.342532)
		(end 418.898578 -310.905398)
		(width 0.18288)
		(layer "In11.Cu")
		(net "M_H_CPU0_SA_DQS_DP<1>")
	)
	(segment
		(start 407.019252 -308.88686)
		(end 406.872948 -308.984396)
		(width 0.18288)
		(layer "In11.Cu")
		(net "M_H_CPU0_SA_DQS_DP<1>")
	)
	(segment
		(start 444.294768 -308.381908)
		(end 444.118746 -308.381908)
		(width 0.18288)
		(layer "In11.Cu")
		(net "M_H_CPU0_SA_DQS_DP<1>")
	)
	(segment
		(start 401.649692 -300.689264)
		(end 393.251944 -292.291516)
		(width 0.18288)
		(layer "In11.Cu")
		(net "M_H_CPU0_SA_DQS_DP<1>")
	)
	(segment
		(start 372.562628 -275.569172)
		(end 372.51894 -275.544026)
		(width 0.088646)
		(layer "In11.Cu")
		(net "M_H_CPU0_SA_DQS_DP<1>")
	)
	(segment
		(start 420.442136 -311.640982)
		(end 420.143686 -311.342532)
		(width 0.18288)
		(layer "In11.Cu")
		(net "M_H_CPU0_SA_DQS_DP<1>")
	)
	(segment
		(start 449.465192 -303.105566)
		(end 449.174108 -303.39665)
		(width 0.18288)
		(layer "In11.Cu")
		(net "M_H_CPU0_SA_DQS_DP<1>")
	)
	(segment
		(start 373.983504 -278.017224)
		(end 373.974614 -278.012144)
		(width 0.088646)
		(layer "In11.Cu")
		(net "M_H_CPU0_SA_DQS_DP<1>")
	)
	(segment
		(start 422.04132 -311.166002)
		(end 421.53459 -311.375806)
		(width 0.18288)
		(layer "In11.Cu")
		(net "M_H_CPU0_SA_DQS_DP<1>")
	)
	(segment
		(start 404.505668 -307.725064)
		(end 404.329646 -307.725064)
		(width 0.18288)
		(layer "In11.Cu")
		(net "M_H_CPU0_SA_DQS_DP<1>")
	)
	(segment
		(start 402.03755 -305.432968)
		(end 402.03755 -305.256946)
		(width 0.18288)
		(layer "In11.Cu")
		(net "M_H_CPU0_SA_DQS_DP<1>")
	)
	(segment
		(start 373.691912 -277.536656)
		(end 373.691912 -277.512526)
		(width 0.088646)
		(layer "In11.Cu")
		(net "M_H_CPU0_SA_DQS_DP<1>")
	)
	(segment
		(start 422.778428 -310.860694)
		(end 422.711118 -311.023508)
		(width 0.18288)
		(layer "In11.Cu")
		(net "M_H_CPU0_SA_DQS_DP<1>")
	)
	(segment
		(start 373.97436 -277.032974)
		(end 373.98325 -277.027894)
		(width 0.088646)
		(layer "In11.Cu")
		(net "M_H_CPU0_SA_DQS_DP<1>")
	)
	(segment
		(start 380.178564 -279.639776)
		(end 380.16815 -279.645872)
		(width 0.088646)
		(layer "In11.Cu")
		(net "M_H_CPU0_SA_DQS_DP<1>")
	)
	(segment
		(start 373.982488 -276.38883)
		(end 373.977662 -276.38629)
		(width 0.088646)
		(layer "In11.Cu")
		(net "M_H_CPU0_SA_DQS_DP<1>")
	)
	(segment
		(start 372.201948 -275.326856)
		(end 372.199916 -275.323554)
		(width 0.088646)
		(layer "In11.Cu")
		(net "M_H_CPU0_SA_DQS_DP<1>")
	)
	(segment
		(start 421.53459 -311.375806)
		(end 421.534844 -311.37606)
		(width 0.18288)
		(layer "In11.Cu")
		(net "M_H_CPU0_SA_DQS_DP<1>")
	)
	(segment
		(start 422.20388 -311.233312)
		(end 422.04132 -311.166002)
		(width 0.18288)
		(layer "In11.Cu")
		(net "M_H_CPU0_SA_DQS_DP<1>")
	)
	(segment
		(start 401.649692 -304.869088)
		(end 401.649692 -300.689264)
		(width 0.18288)
		(layer "In11.Cu")
		(net "M_H_CPU0_SA_DQS_DP<1>")
	)
	(segment
		(start 411.83052 -309.66537)
		(end 411.28188 -309.66537)
		(width 0.18288)
		(layer "In11.Cu")
		(net "M_H_CPU0_SA_DQS_DP<1>")
	)
	(segment
		(start 425.328842 -310.525922)
		(end 425.06392 -310.790844)
		(width 0.18288)
		(layer "In11.Cu")
		(net "M_H_CPU0_SA_DQS_DP<1>")
	)
	(segment
		(start 444.68288 -307.817774)
		(end 444.68288 -307.993796)
		(width 0.18288)
		(layer "In11.Cu")
		(net "M_H_CPU0_SA_DQS_DP<1>")
	)
	(segment
		(start 439.346594 -310.507634)
		(end 437.809132 -310.507634)
		(width 0.18288)
		(layer "In11.Cu")
		(net "M_H_CPU0_SA_DQS_DP<1>")
	)
	(segment
		(start 372.209314 -275.326856)
		(end 372.201948 -275.326856)
		(width 0.088646)
		(layer "In11.Cu")
		(net "M_H_CPU0_SA_DQS_DP<1>")
	)
	(segment
		(start 422.711118 -311.023508)
		(end 422.20388 -311.233312)
		(width 0.18288)
		(layer "In11.Cu")
		(net "M_H_CPU0_SA_DQS_DP<1>")
	)
	(segment
		(start 413.40659 -308.66588)
		(end 412.53156 -309.54091)
		(width 0.18288)
		(layer "In11.Cu")
		(net "M_H_CPU0_SA_DQS_DP<1>")
	)
	(segment
		(start 409.93568 -309.66537)
		(end 409.81122 -309.54091)
		(width 0.18288)
		(layer "In11.Cu")
		(net "M_H_CPU0_SA_DQS_DP<1>")
	)
	(segment
		(start 429.030892 -310.38546)
		(end 428.482252 -310.38546)
		(width 0.18288)
		(layer "In11.Cu")
		(net "M_H_CPU0_SA_DQS_DP<1>")
	)
	(segment
		(start 443.730888 -308.769766)
		(end 443.346332 -308.769766)
		(width 0.18288)
		(layer "In11.Cu")
		(net "M_H_CPU0_SA_DQS_DP<1>")
	)
	(segment
		(start 376.789696 -279.637236)
		(end 376.787918 -279.63622)
		(width 0.088646)
		(layer "In11.Cu")
		(net "M_H_CPU0_SA_DQS_DP<1>")
	)
	(segment
		(start 437.809132 -310.507634)
		(end 436.977536 -309.676038)
		(width 0.18288)
		(layer "In11.Cu")
		(net "M_H_CPU0_SA_DQS_DP<1>")
	)
	(segment
		(start 373.691912 -275.886418)
		(end 373.691658 -275.880068)
		(width 0.088646)
		(layer "In11.Cu")
		(net "M_H_CPU0_SA_DQS_DP<1>")
	)
	(segment
		(start 372.046246 -275.21916)
		(end 371.907816 -275.08073)
		(width 0.088646)
		(layer "In11.Cu")
		(net "M_H_CPU0_SA_DQS_DP<1>")
	)
	(segment
		(start 450.116702 -303.296574)
		(end 449.925694 -303.105566)
		(width 0.18288)
		(layer "In11.Cu")
		(net "M_H_CPU0_SA_DQS_DP<1>")
	)
	(segment
		(start 427.347126 -309.798974)
		(end 426.779944 -309.798974)
		(width 0.18288)
		(layer "In11.Cu")
		(net "M_H_CPU0_SA_DQS_DP<1>")
	)
	(segment
		(start 411.15742 -309.54091)
		(end 410.60878 -309.54091)
		(width 0.18288)
		(layer "In11.Cu")
		(net "M_H_CPU0_SA_DQS_DP<1>")
	)
	(segment
		(start 373.51335 -275.575522)
		(end 373.50446 -275.570442)
		(width 0.088646)
		(layer "In11.Cu")
		(net "M_H_CPU0_SA_DQS_DP<1>")
	)
	(segment
		(start 372.56466 -275.570442)
		(end 372.562628 -275.569172)
		(width 0.088646)
		(layer "In11.Cu")
		(net "M_H_CPU0_SA_DQS_DP<1>")
	)
	(segment
		(start 373.691912 -275.904706)
		(end 373.691912 -275.886418)
		(width 0.088646)
		(layer "In11.Cu")
		(net "M_H_CPU0_SA_DQS_DP<1>")
	)
	(segment
		(start 410.60878 -309.54091)
		(end 410.48432 -309.66537)
		(width 0.18288)
		(layer "In11.Cu")
		(net "M_H_CPU0_SA_DQS_DP<1>")
	)
	(segment
		(start 376.33275 -278.83104)
		(end 376.32386 -278.82596)
		(width 0.088646)
		(layer "In11.Cu")
		(net "M_H_CPU0_SA_DQS_DP<1>")
	)
	(segment
		(start 376.808746 -279.648412)
		(end 376.794014 -279.639776)
		(width 0.088646)
		(layer "In11.Cu")
		(net "M_H_CPU0_SA_DQS_DP<1>")
	)
	(segment
		(start 440.15152 -310.790844)
		(end 439.629804 -310.790844)
		(width 0.18288)
		(layer "In11.Cu")
		(net "M_H_CPU0_SA_DQS_DP<1>")
	)
	(segment
		(start 403.941534 -307.16093)
		(end 403.553676 -306.773072)
		(width 0.18288)
		(layer "In11.Cu")
		(net "M_H_CPU0_SA_DQS_DP<1>")
	)
	(segment
		(start 376.791728 -279.638506)
		(end 376.789696 -279.637236)
		(width 0.088646)
		(layer "In11.Cu")
		(net "M_H_CPU0_SA_DQS_DP<1>")
	)
	(segment
		(start 415.977832 -308.66588)
		(end 414.75279 -308.66588)
		(width 0.18288)
		(layer "In11.Cu")
		(net "M_H_CPU0_SA_DQS_DP<1>")
	)
	(segment
		(start 375.009664 -278.82596)
		(end 374.994932 -278.834596)
		(width 0.088646)
		(layer "In11.Cu")
		(net "M_H_CPU0_SA_DQS_DP<1>")
	)
	(segment
		(start 403.553676 -306.773072)
		(end 403.377654 -306.773072)
		(width 0.18288)
		(layer "In11.Cu")
		(net "M_H_CPU0_SA_DQS_DP<1>")
	)
	(segment
		(start 372.232428 -275.34997)
		(end 372.209314 -275.326856)
		(width 0.088646)
		(layer "In11.Cu")
		(net "M_H_CPU0_SA_DQS_DP<1>")
	)
	(segment
		(start 444.68288 -307.993796)
		(end 444.294768 -308.381908)
		(width 0.18288)
		(layer "In11.Cu")
		(net "M_H_CPU0_SA_DQS_DP<1>")
	)
	(segment
		(start 402.03755 -305.256946)
		(end 401.649692 -304.869088)
		(width 0.18288)
		(layer "In11.Cu")
		(net "M_H_CPU0_SA_DQS_DP<1>")
	)
	(segment
		(start 442.508132 -309.607966)
		(end 441.934092 -309.607966)
		(width 0.18288)
		(layer "In11.Cu")
		(net "M_H_CPU0_SA_DQS_DP<1>")
	)
	(segment
		(start 409.138374 -309.54091)
		(end 408.453844 -309.174134)
		(width 0.18288)
		(layer "In11.Cu")
		(net "M_H_CPU0_SA_DQS_DP<1>")
	)
	(segment
		(start 409.81122 -309.54091)
		(end 409.138374 -309.54091)
		(width 0.18288)
		(layer "In11.Cu")
		(net "M_H_CPU0_SA_DQS_DP<1>")
	)
	(segment
		(start 433.079398 -309.792116)
		(end 432.954938 -309.667656)
		(width 0.18288)
		(layer "In11.Cu")
		(net "M_H_CPU0_SA_DQS_DP<1>")
	)
	(segment
		(start 420.143686 -311.342532)
		(end 419.335712 -311.342532)
		(width 0.18288)
		(layer "In11.Cu")
		(net "M_H_CPU0_SA_DQS_DP<1>")
	)
	(segment
		(start 426.052996 -310.525922)
		(end 425.328842 -310.525922)
		(width 0.18288)
		(layer "In11.Cu")
		(net "M_H_CPU0_SA_DQS_DP<1>")
	)
	(segment
		(start 423.551096 -310.540654)
		(end 422.778428 -310.860694)
		(width 0.18288)
		(layer "In11.Cu")
		(net "M_H_CPU0_SA_DQS_DP<1>")
	)
	(segment
		(start 428.357792 -310.261)
		(end 427.809152 -310.261)
		(width 0.18288)
		(layer "In11.Cu")
		(net "M_H_CPU0_SA_DQS_DP<1>")
	)
	(segment
		(start 424.542204 -310.790844)
		(end 424.292014 -310.540654)
		(width 0.18288)
		(layer "In11.Cu")
		(net "M_H_CPU0_SA_DQS_DP<1>")
	)
	(segment
		(start 373.98325 -276.389338)
		(end 373.982488 -276.38883)
		(width 0.088646)
		(layer "In11.Cu")
		(net "M_H_CPU0_SA_DQS_DP<1>")
	)
	(segment
		(start 393.251944 -290.768278)
		(end 386.986018 -284.502352)
		(width 0.18288)
		(layer "In11.Cu")
		(net "M_H_CPU0_SA_DQS_DP<1>")
	)
	(segment
		(start 406.872948 -308.984396)
		(end 406.334722 -308.8767)
		(width 0.18288)
		(layer "In11.Cu")
		(net "M_H_CPU0_SA_DQS_DP<1>")
	)
	(segment
		(start 376.794014 -279.639776)
		(end 376.791728 -279.638506)
		(width 0.088646)
		(layer "In11.Cu")
		(net "M_H_CPU0_SA_DQS_DP<1>")
	)
	(segment
		(start 386.581142 -283.244036)
		(end 386.516626 -283.17952)
		(width 0.088646)
		(layer "In11.Cu")
		(net "M_H_CPU0_SA_DQS_DP<1>")
	)
	(segment
		(start 414.62833 -308.79034)
		(end 414.07969 -308.79034)
		(width 0.18288)
		(layer "In11.Cu")
		(net "M_H_CPU0_SA_DQS_DP<1>")
	)
	(segment
		(start 441.934092 -309.607966)
		(end 440.984386 -310.557672)
		(width 0.18288)
		(layer "In11.Cu")
		(net "M_H_CPU0_SA_DQS_DP<1>")
	)
	(segment
		(start 406.236932 -308.730142)
		(end 405.329136 -308.548532)
		(width 0.18288)
		(layer "In11.Cu")
		(net "M_H_CPU0_SA_DQS_DP<1>")
	)
	(segment
		(start 421.534844 -311.37606)
		(end 421.200326 -311.37606)
		(width 0.18288)
		(layer "In11.Cu")
		(net "M_H_CPU0_SA_DQS_DP<1>")
	)
	(segment
		(start 450.641212 -303.296574)
		(end 450.116702 -303.296574)
		(width 0.18288)
		(layer "In11.Cu")
		(net "M_H_CPU0_SA_DQS_DP<1>")
	)
	(segment
		(start 431.552858 -309.667656)
		(end 430.959514 -310.261)
		(width 0.18288)
		(layer "In11.Cu")
		(net "M_H_CPU0_SA_DQS_DP<1>")
	)
	(segment
		(start 402.601684 -305.82108)
		(end 402.425662 -305.82108)
		(width 0.18288)
		(layer "In11.Cu")
		(net "M_H_CPU0_SA_DQS_DP<1>")
	)
	(segment
		(start 372.199916 -275.323554)
		(end 372.046246 -275.21916)
		(width 0.088646)
		(layer "In11.Cu")
		(net "M_H_CPU0_SA_DQS_DP<1>")
	)
	(segment
		(start 385.439412 -281.601926)
		(end 385.439412 -281.59202)
		(width 0.088646)
		(layer "In11.Cu")
		(net "M_H_CPU0_SA_DQS_DP<1>")
	)
	(segment
		(start 435.529736 -309.94096)
		(end 435.256432 -309.667656)
		(width 0.18288)
		(layer "In11.Cu")
		(net "M_H_CPU0_SA_DQS_DP<1>")
	)
	(segment
		(start 408.45232 -309.173372)
		(end 407.019252 -308.88686)
		(width 0.18288)
		(layer "In11.Cu")
		(net "M_H_CPU0_SA_DQS_DP<1>")
	)
	(segment
		(start 418.334444 -310.517286)
		(end 418.334444 -310.341264)
		(width 0.18288)
		(layer "In11.Cu")
		(net "M_H_CPU0_SA_DQS_DP<1>")
	)
	(segment
		(start 403.941534 -307.336952)
		(end 403.941534 -307.16093)
		(width 0.18288)
		(layer "In11.Cu")
		(net "M_H_CPU0_SA_DQS_DP<1>")
	)
	(segment
		(start 404.329646 -307.725064)
		(end 403.941534 -307.336952)
		(width 0.18288)
		(layer "In11.Cu")
		(net "M_H_CPU0_SA_DQS_DP<1>")
	)
	(segment
		(start 425.06392 -310.790844)
		(end 424.542204 -310.790844)
		(width 0.18288)
		(layer "In11.Cu")
		(net "M_H_CPU0_SA_DQS_DP<1>")
	)
	(segment
		(start 436.051452 -309.94096)
		(end 435.529736 -309.94096)
		(width 0.18288)
		(layer "In11.Cu")
		(net "M_H_CPU0_SA_DQS_DP<1>")
	)
	(segment
		(start 450.911214 -303.566576)
		(end 450.641212 -303.296574)
		(width 0.18288)
		(layer "In11.Cu")
		(net "M_H_CPU0_SA_DQS_DP<1>")
	)
	(segment
		(start 416.729164 -309.417212)
		(end 415.977832 -308.66588)
		(width 0.18288)
		(layer "In11.Cu")
		(net "M_H_CPU0_SA_DQS_DP<1>")
	)
	(segment
		(start 429.155352 -310.261)
		(end 429.030892 -310.38546)
		(width 0.18288)
		(layer "In11.Cu")
		(net "M_H_CPU0_SA_DQS_DP<1>")
	)
	(segment
		(start 405.329136 -308.548532)
		(end 404.505668 -307.725064)
		(width 0.18288)
		(layer "In11.Cu")
		(net "M_H_CPU0_SA_DQS_DP<1>")
	)
	(segment
		(start 410.48432 -309.66537)
		(end 409.93568 -309.66537)
		(width 0.18288)
		(layer "In11.Cu")
		(net "M_H_CPU0_SA_DQS_DP<1>")
	)
	(segment
		(start 435.256432 -309.667656)
		(end 433.752498 -309.667656)
		(width 0.18288)
		(layer "In11.Cu")
		(net "M_H_CPU0_SA_DQS_DP<1>")
	)
	(segment
		(start 414.07969 -308.79034)
		(end 413.95523 -308.66588)
		(width 0.18288)
		(layer "In11.Cu")
		(net "M_H_CPU0_SA_DQS_DP<1>")
	)
	(segment
		(start 448.210178 -305.25593)
		(end 448.210178 -305.636676)
		(width 0.18288)
		(layer "In11.Cu")
		(net "M_H_CPU0_SA_DQS_DP<1>")
	)
	(segment
		(start 449.174108 -303.39665)
		(end 449.174108 -304.292)
		(width 0.18288)
		(layer "In11.Cu")
		(net "M_H_CPU0_SA_DQS_DP<1>")
	)
	(segment
		(start 402.989542 -306.38496)
		(end 402.989542 -306.208938)
		(width 0.18288)
		(layer "In11.Cu")
		(net "M_H_CPU0_SA_DQS_DP<1>")
	)
	(segment
		(start 446.09385 -307.139086)
		(end 445.361568 -307.139086)
		(width 0.18288)
		(layer "In11.Cu")
		(net "M_H_CPU0_SA_DQS_DP<1>")
	)
	(segment
		(start 417.410392 -309.417212)
		(end 416.729164 -309.417212)
		(width 0.18288)
		(layer "In11.Cu")
		(net "M_H_CPU0_SA_DQS_DP<1>")
	)
	(segment
		(start 373.9769 -276.385782)
		(end 373.975122 -276.384766)
		(width 0.088646)
		(layer "In11.Cu")
		(net "M_H_CPU0_SA_DQS_DP<1>")
	)
	(segment
		(start 385.73075 -282.086558)
		(end 385.72186 -282.081478)
		(width 0.088646)
		(layer "In11.Cu")
		(net "M_H_CPU0_SA_DQS_DP<1>")
	)
	(segment
		(start 408.453844 -309.174134)
		(end 408.45232 -309.173372)
		(width 0.18288)
		(layer "In11.Cu")
		(net "M_H_CPU0_SA_DQS_DP<1>")
	)
	(segment
		(start 372.51894 -275.544026)
		(end 372.409974 -275.482812)
		(width 0.088646)
		(layer "In11.Cu")
		(net "M_H_CPU0_SA_DQS_DP<1>")
	)
	(segment
		(start 381.118618 -279.639776)
		(end 381.108204 -279.645872)
		(width 0.088646)
		(layer "In11.Cu")
		(net "M_H_CPU0_SA_DQS_DP<1>")
	)
	(segment
		(start 373.130064 -275.570442)
		(end 373.115332 -275.579078)
		(width 0.088646)
		(layer "In11.Cu")
		(net "M_H_CPU0_SA_DQS_DP<1>")
	)
	(segment
		(start 403.377654 -306.773072)
		(end 402.989542 -306.38496)
		(width 0.18288)
		(layer "In11.Cu")
		(net "M_H_CPU0_SA_DQS_DP<1>")
	)
	(segment
		(start 427.809152 -310.261)
		(end 427.347126 -309.798974)
		(width 0.18288)
		(layer "In11.Cu")
		(net "M_H_CPU0_SA_DQS_DP<1>")
	)
	(segment
		(start 386.581142 -283.335476)
		(end 386.581142 -283.244036)
		(width 0.088646)
		(layer "In11.Cu")
		(net "M_H_CPU0_SA_DQS_DP<1>")
	)
	(segment
		(start 413.95523 -308.66588)
		(end 413.40659 -308.66588)
		(width 0.18288)
		(layer "In11.Cu")
		(net "M_H_CPU0_SA_DQS_DP<1>")
	)
	(segment
		(start 374.162066 -278.351996)
		(end 374.162066 -278.336502)
		(width 0.088646)
		(layer "In11.Cu")
		(net "M_H_CPU0_SA_DQS_DP<1>")
	)
	(segment
		(start 373.975122 -276.384766)
		(end 373.97436 -276.384258)
		(width 0.088646)
		(layer "In11.Cu")
		(net "M_H_CPU0_SA_DQS_DP<1>")
	)
	(segment
		(start 445.361568 -307.139086)
		(end 444.68288 -307.817774)
		(width 0.18288)
		(layer "In11.Cu")
		(net "M_H_CPU0_SA_DQS_DP<1>")
	)
	(segment
		(start 430.959514 -310.261)
		(end 429.155352 -310.261)
		(width 0.18288)
		(layer "In11.Cu")
		(net "M_H_CPU0_SA_DQS_DP<1>")
	)
	(segment
		(start 449.925694 -303.105566)
		(end 449.465192 -303.105566)
		(width 0.18288)
		(layer "In11.Cu")
		(net "M_H_CPU0_SA_DQS_DP<1>")
	)
	(segment
		(start 412.53156 -309.54091)
		(end 411.95498 -309.54091)
		(width 0.18288)
		(layer "In11.Cu")
		(net "M_H_CPU0_SA_DQS_DP<1>")
	)
	(segment
		(start 449.174108 -304.292)
		(end 448.210178 -305.25593)
		(width 0.18288)
		(layer "In11.Cu")
		(net "M_H_CPU0_SA_DQS_DP<1>")
	)
	(segment
		(start 386.986018 -283.740352)
		(end 386.581142 -283.335476)
		(width 0.18288)
		(layer "In11.Cu")
		(net "M_H_CPU0_SA_DQS_DP<1>")
	)
	(segment
		(start 402.425662 -305.82108)
		(end 402.03755 -305.432968)
		(width 0.18288)
		(layer "In11.Cu")
		(net "M_H_CPU0_SA_DQS_DP<1>")
	)
	(segment
		(start 384.029712 -280.78811)
		(end 384.029712 -280.778204)
		(width 0.088646)
		(layer "In11.Cu")
		(net "M_H_CPU0_SA_DQS_DP<1>")
	)
	(arc
		(start 383.559558 -279.964134)
		(mid 383.511879 -279.781234)
		(end 383.380996 -279.644856)
		(width 0.088646)
		(layer "In11.Cu")
		(net "M_H_CPU0_SA_DQS_DP<1>")
	)
	(arc
		(start 386.192014 -282.895548)
		(mid 385.988533 -282.694744)
		(end 385.909312 -282.42006)
		(width 0.088646)
		(layer "In11.Cu")
		(net "M_H_CPU0_SA_DQS_DP<1>")
	)
	(arc
		(start 376.787918 -279.63622)
		(mid 376.585331 -279.429869)
		(end 376.511312 -279.150318)
		(width 0.088646)
		(layer "In11.Cu")
		(net "M_H_CPU0_SA_DQS_DP<1>")
	)
	(arc
		(start 382.432814 -279.639776)
		(mid 382.245616 -279.589633)
		(end 382.058418 -279.639776)
		(width 0.088646)
		(layer "In11.Cu")
		(net "M_H_CPU0_SA_DQS_DP<1>")
	)
	(arc
		(start 381.108204 -279.645872)
		(mid 380.829772 -279.715718)
		(end 380.55296 -279.639776)
		(width 0.088646)
		(layer "In11.Cu")
		(net "M_H_CPU0_SA_DQS_DP<1>")
	)
	(arc
		(start 378.299218 -279.639776)
		(mid 378.016516 -279.715552)
		(end 377.733814 -279.639776)
		(width 0.088646)
		(layer "In11.Cu")
		(net "M_H_CPU0_SA_DQS_DP<1>")
	)
	(arc
		(start 379.613414 -279.639776)
		(mid 379.426216 -279.589633)
		(end 379.239018 -279.639776)
		(width 0.088646)
		(layer "In11.Cu")
		(net "M_H_CPU0_SA_DQS_DP<1>")
	)
	(arc
		(start 380.55296 -279.639776)
		(mid 380.365762 -279.589633)
		(end 380.178564 -279.639776)
		(width 0.088646)
		(layer "In11.Cu")
		(net "M_H_CPU0_SA_DQS_DP<1>")
	)
	(arc
		(start 386.516626 -283.17952)
		(mid 386.383741 -283.052663)
		(end 386.2451 -282.932124)
		(width 0.088646)
		(layer "In11.Cu")
		(net "M_H_CPU0_SA_DQS_DP<1>")
	)
	(arc
		(start 374.162066 -278.336502)
		(mid 374.114387 -278.153602)
		(end 373.983504 -278.017224)
		(width 0.088646)
		(layer "In11.Cu")
		(net "M_H_CPU0_SA_DQS_DP<1>")
	)
	(arc
		(start 385.72186 -282.081478)
		(mid 385.517525 -281.878873)
		(end 385.439412 -281.601926)
		(width 0.088646)
		(layer "In11.Cu")
		(net "M_H_CPU0_SA_DQS_DP<1>")
	)
	(arc
		(start 373.50446 -275.570442)
		(mid 373.317262 -275.520299)
		(end 373.130064 -275.570442)
		(width 0.088646)
		(layer "In11.Cu")
		(net "M_H_CPU0_SA_DQS_DP<1>")
	)
	(arc
		(start 373.974614 -278.012144)
		(mid 373.771133 -277.81134)
		(end 373.691912 -277.536656)
		(width 0.088646)
		(layer "In11.Cu")
		(net "M_H_CPU0_SA_DQS_DP<1>")
	)
	(arc
		(start 384.877564 -281.267662)
		(mid 384.594862 -281.343438)
		(end 384.31216 -281.267662)
		(width 0.088646)
		(layer "In11.Cu")
		(net "M_H_CPU0_SA_DQS_DP<1>")
	)
	(arc
		(start 377.733814 -279.639776)
		(mid 377.546616 -279.589633)
		(end 377.359418 -279.639776)
		(width 0.088646)
		(layer "In11.Cu")
		(net "M_H_CPU0_SA_DQS_DP<1>")
	)
	(arc
		(start 382.99771 -279.639776)
		(mid 382.715262 -279.715425)
		(end 382.432814 -279.639776)
		(width 0.088646)
		(layer "In11.Cu")
		(net "M_H_CPU0_SA_DQS_DP<1>")
	)
	(arc
		(start 373.691658 -275.880068)
		(mid 373.640604 -275.705488)
		(end 373.51335 -275.575522)
		(width 0.088646)
		(layer "In11.Cu")
		(net "M_H_CPU0_SA_DQS_DP<1>")
	)
	(arc
		(start 377.359418 -279.639776)
		(mid 377.085219 -279.715611)
		(end 376.808746 -279.648412)
		(width 0.088646)
		(layer "In11.Cu")
		(net "M_H_CPU0_SA_DQS_DP<1>")
	)
	(arc
		(start 384.029712 -280.778204)
		(mid 383.982033 -280.595304)
		(end 383.85115 -280.458926)
		(width 0.088646)
		(layer "In11.Cu")
		(net "M_H_CPU0_SA_DQS_DP<1>")
	)
	(arc
		(start 374.44426 -278.82596)
		(mid 374.241437 -278.625729)
		(end 374.162066 -278.351996)
		(width 0.088646)
		(layer "In11.Cu")
		(net "M_H_CPU0_SA_DQS_DP<1>")
	)
	(arc
		(start 383.372106 -279.639776)
		(mid 383.184908 -279.589633)
		(end 382.99771 -279.639776)
		(width 0.088646)
		(layer "In11.Cu")
		(net "M_H_CPU0_SA_DQS_DP<1>")
	)
	(arc
		(start 375.38406 -278.82596)
		(mid 375.196862 -278.775817)
		(end 375.009664 -278.82596)
		(width 0.088646)
		(layer "In11.Cu")
		(net "M_H_CPU0_SA_DQS_DP<1>")
	)
	(arc
		(start 373.98325 -277.027894)
		(mid 374.161847 -276.708616)
		(end 373.98325 -276.389338)
		(width 0.088646)
		(layer "In11.Cu")
		(net "M_H_CPU0_SA_DQS_DP<1>")
	)
	(arc
		(start 382.058418 -279.639776)
		(mid 381.784219 -279.715611)
		(end 381.507746 -279.648412)
		(width 0.088646)
		(layer "In11.Cu")
		(net "M_H_CPU0_SA_DQS_DP<1>")
	)
	(arc
		(start 373.115332 -275.579078)
		(mid 372.838891 -275.646244)
		(end 372.56466 -275.570442)
		(width 0.088646)
		(layer "In11.Cu")
		(net "M_H_CPU0_SA_DQS_DP<1>")
	)
	(arc
		(start 378.673614 -279.639776)
		(mid 378.486416 -279.589633)
		(end 378.299218 -279.639776)
		(width 0.088646)
		(layer "In11.Cu")
		(net "M_H_CPU0_SA_DQS_DP<1>")
	)
	(arc
		(start 376.511312 -279.150318)
		(mid 376.463633 -278.967418)
		(end 376.33275 -278.83104)
		(width 0.088646)
		(layer "In11.Cu")
		(net "M_H_CPU0_SA_DQS_DP<1>")
	)
	(arc
		(start 385.909312 -282.405836)
		(mid 385.861633 -282.222936)
		(end 385.73075 -282.086558)
		(width 0.088646)
		(layer "In11.Cu")
		(net "M_H_CPU0_SA_DQS_DP<1>")
	)
	(arc
		(start 383.84226 -280.453846)
		(mid 383.637188 -280.250167)
		(end 383.559558 -279.971754)
		(width 0.088646)
		(layer "In11.Cu")
		(net "M_H_CPU0_SA_DQS_DP<1>")
	)
	(arc
		(start 384.31216 -281.267662)
		(mid 384.107825 -281.065057)
		(end 384.029712 -280.78811)
		(width 0.088646)
		(layer "In11.Cu")
		(net "M_H_CPU0_SA_DQS_DP<1>")
	)
	(arc
		(start 375.934732 -278.834596)
		(mid 375.658257 -278.901916)
		(end 375.38406 -278.82596)
		(width 0.088646)
		(layer "In11.Cu")
		(net "M_H_CPU0_SA_DQS_DP<1>")
	)
	(arc
		(start 385.439412 -281.59202)
		(mid 385.391733 -281.40912)
		(end 385.26085 -281.272742)
		(width 0.088646)
		(layer "In11.Cu")
		(net "M_H_CPU0_SA_DQS_DP<1>")
	)
	(arc
		(start 379.239018 -279.639776)
		(mid 378.964819 -279.715611)
		(end 378.688346 -279.648412)
		(width 0.088646)
		(layer "In11.Cu")
		(net "M_H_CPU0_SA_DQS_DP<1>")
	)
	(arc
		(start 374.994932 -278.834596)
		(mid 374.718457 -278.901916)
		(end 374.44426 -278.82596)
		(width 0.088646)
		(layer "In11.Cu")
		(net "M_H_CPU0_SA_DQS_DP<1>")
	)
	(arc
		(start 381.493014 -279.639776)
		(mid 381.305816 -279.589633)
		(end 381.118618 -279.639776)
		(width 0.088646)
		(layer "In11.Cu")
		(net "M_H_CPU0_SA_DQS_DP<1>")
	)
	(arc
		(start 376.32386 -278.82596)
		(mid 376.136662 -278.775817)
		(end 375.949464 -278.82596)
		(width 0.088646)
		(layer "In11.Cu")
		(net "M_H_CPU0_SA_DQS_DP<1>")
	)
	(arc
		(start 373.691912 -277.512526)
		(mid 373.770023 -277.235577)
		(end 373.97436 -277.032974)
		(width 0.088646)
		(layer "In11.Cu")
		(net "M_H_CPU0_SA_DQS_DP<1>")
	)
	(arc
		(start 373.97436 -276.384258)
		(mid 373.770025 -276.181653)
		(end 373.691912 -275.904706)
		(width 0.088646)
		(layer "In11.Cu")
		(net "M_H_CPU0_SA_DQS_DP<1>")
	)
	(arc
		(start 385.25196 -281.267662)
		(mid 385.064762 -281.217519)
		(end 384.877564 -281.267662)
		(width 0.088646)
		(layer "In11.Cu")
		(net "M_H_CPU0_SA_DQS_DP<1>")
	)
	(arc
		(start 380.16815 -279.645872)
		(mid 379.889972 -279.715595)
		(end 379.613414 -279.639776)
		(width 0.088646)
		(layer "In11.Cu")
		(net "M_H_CPU0_SA_DQS_DP<1>")
	)
	(arc
		(start 386.2451 -282.932124)
		(mid 386.219346 -282.912691)
		(end 386.192014 -282.895548)
		(width 0.088646)
		(layer "In11.Cu")
		(net "M_H_CPU0_SA_DQS_DP<1>")
	)
	(segment
		(start 454.963276 -313.341766)
		(end 457.120498 -313.341766)
		(width 0.1016)
		(layer "F.Cu")
		(net "M_H_CPU0_SA_DQS_DP<0>")
	)
	(segment
		(start 458.729588 -312.634884)
		(end 459.011274 -312.91657)
		(width 0.20066)
		(layer "F.Cu")
		(net "M_H_CPU0_SA_DQS_DP<0>")
	)
	(segment
		(start 457.75245 -313.045348)
		(end 458.123036 -313.045348)
		(width 0.20066)
		(layer "F.Cu")
		(net "M_H_CPU0_SA_DQS_DP<0>")
	)
	(segment
		(start 457.120498 -313.341766)
		(end 457.126594 -313.347862)
		(width 0.1016)
		(layer "F.Cu")
		(net "M_H_CPU0_SA_DQS_DP<0>")
	)
	(segment
		(start 453.860916 -313.09056)
		(end 454.546716 -313.09056)
		(width 0.20066)
		(layer "F.Cu")
		(net "M_H_CPU0_SA_DQS_DP<0>")
	)
	(segment
		(start 375.197116 -276.986492)
		(end 375.197116 -277.522178)
		(width 0.20066)
		(layer "F.Cu")
		(net "M_H_CPU0_SA_DQS_DP<0>")
	)
	(segment
		(start 458.123036 -313.045348)
		(end 458.5335 -312.634884)
		(width 0.20066)
		(layer "F.Cu")
		(net "M_H_CPU0_SA_DQS_DP<0>")
	)
	(segment
		(start 452.016114 -312.91657)
		(end 452.605394 -312.91657)
		(width 0.20066)
		(layer "F.Cu")
		(net "M_H_CPU0_SA_DQS_DP<0>")
	)
	(segment
		(start 452.845932 -312.676032)
		(end 453.446388 -312.676032)
		(width 0.20066)
		(layer "F.Cu")
		(net "M_H_CPU0_SA_DQS_DP<0>")
	)
	(segment
		(start 458.5335 -312.634884)
		(end 458.729588 -312.634884)
		(width 0.20066)
		(layer "F.Cu")
		(net "M_H_CPU0_SA_DQS_DP<0>")
	)
	(segment
		(start 459.011274 -312.91657)
		(end 459.559914 -312.91657)
		(width 0.20066)
		(layer "F.Cu")
		(net "M_H_CPU0_SA_DQS_DP<0>")
	)
	(segment
		(start 453.446388 -312.676032)
		(end 453.860916 -313.09056)
		(width 0.20066)
		(layer "F.Cu")
		(net "M_H_CPU0_SA_DQS_DP<0>")
	)
	(segment
		(start 457.126594 -313.347862)
		(end 457.449936 -313.347862)
		(width 0.20066)
		(layer "F.Cu")
		(net "M_H_CPU0_SA_DQS_DP<0>")
	)
	(segment
		(start 454.546716 -313.09056)
		(end 454.797922 -313.341766)
		(width 0.20066)
		(layer "F.Cu")
		(net "M_H_CPU0_SA_DQS_DP<0>")
	)
	(segment
		(start 457.449936 -313.347862)
		(end 457.75245 -313.045348)
		(width 0.20066)
		(layer "F.Cu")
		(net "M_H_CPU0_SA_DQS_DP<0>")
	)
	(segment
		(start 450.911214 -312.91657)
		(end 452.016114 -312.91657)
		(width 0.20066)
		(layer "F.Cu")
		(net "M_H_CPU0_SA_DQS_DP<0>")
	)
	(segment
		(start 454.797922 -313.341766)
		(end 454.937368 -313.341766)
		(width 0.20066)
		(layer "F.Cu")
		(net "M_H_CPU0_SA_DQS_DP<0>")
	)
	(segment
		(start 454.937368 -313.341766)
		(end 454.963276 -313.341766)
		(width 0.101854)
		(layer "F.Cu")
		(net "M_H_CPU0_SA_DQS_DP<0>")
	)
	(segment
		(start 452.605394 -312.91657)
		(end 452.845932 -312.676032)
		(width 0.20066)
		(layer "F.Cu")
		(net "M_H_CPU0_SA_DQS_DP<0>")
	)
	(segment
		(start 375.197116 -277.522178)
		(end 375.196862 -277.522432)
		(width 0.20066)
		(layer "F.Cu")
		(net "M_H_CPU0_SA_DQS_DP<0>")
	)
	(segment
		(start 408.569922 -305.556158)
		(end 408.023822 -305.556158)
		(width 0.18288)
		(layer "In6.Cu")
		(net "M_H_CPU0_SA_DQS_DP<0>")
	)
	(segment
		(start 414.7185 -308.443122)
		(end 414.68421 -308.270402)
		(width 0.18288)
		(layer "In6.Cu")
		(net "M_H_CPU0_SA_DQS_DP<0>")
	)
	(segment
		(start 405.47163 -306.538376)
		(end 405.187658 -306.254404)
		(width 0.18288)
		(layer "In6.Cu")
		(net "M_H_CPU0_SA_DQS_DP<0>")
	)
	(segment
		(start 439.488326 -313.080654)
		(end 438.94629 -313.080654)
		(width 0.18288)
		(layer "In6.Cu")
		(net "M_H_CPU0_SA_DQS_DP<0>")
	)
	(segment
		(start 409.932886 -305.691032)
		(end 409.560776 -305.691032)
		(width 0.18288)
		(layer "In6.Cu")
		(net "M_H_CPU0_SA_DQS_DP<0>")
	)
	(segment
		(start 403.658578 -301.097188)
		(end 395.79423 -293.23284)
		(width 0.18288)
		(layer "In6.Cu")
		(net "M_H_CPU0_SA_DQS_DP<0>")
	)
	(segment
		(start 375.868946 -278.02078)
		(end 375.854214 -278.012144)
		(width 0.088646)
		(layer "In6.Cu")
		(net "M_H_CPU0_SA_DQS_DP<0>")
	)
	(segment
		(start 427.813216 -310.476646)
		(end 427.108366 -309.771796)
		(width 0.18288)
		(layer "In6.Cu")
		(net "M_H_CPU0_SA_DQS_DP<0>")
	)
	(segment
		(start 415.172906 -308.746906)
		(end 414.7185 -308.443122)
		(width 0.18288)
		(layer "In6.Cu")
		(net "M_H_CPU0_SA_DQS_DP<0>")
	)
	(segment
		(start 443.010036 -312.435494)
		(end 442.885576 -312.311034)
		(width 0.18288)
		(layer "In6.Cu")
		(net "M_H_CPU0_SA_DQS_DP<0>")
	)
	(segment
		(start 421.61333 -309.674768)
		(end 421.182546 -309.674768)
		(width 0.18288)
		(layer "In6.Cu")
		(net "M_H_CPU0_SA_DQS_DP<0>")
	)
	(segment
		(start 447.771774 -312.191654)
		(end 447.02857 -312.191654)
		(width 0.18288)
		(layer "In6.Cu")
		(net "M_H_CPU0_SA_DQS_DP<0>")
	)
	(segment
		(start 450.911214 -312.91657)
		(end 450.632322 -312.637678)
		(width 0.18288)
		(layer "In6.Cu")
		(net "M_H_CPU0_SA_DQS_DP<0>")
	)
	(segment
		(start 385.909312 -279.160224)
		(end 385.909312 -279.150318)
		(width 0.088646)
		(layer "In6.Cu")
		(net "M_H_CPU0_SA_DQS_DP<0>")
	)
	(segment
		(start 388.082536 -281.058874)
		(end 387.919976 -280.896314)
		(width 0.088646)
		(layer "In6.Cu")
		(net "M_H_CPU0_SA_DQS_DP<0>")
	)
	(segment
		(start 427.108366 -309.771796)
		(end 426.932344 -309.771796)
		(width 0.18288)
		(layer "In6.Cu")
		(net "M_H_CPU0_SA_DQS_DP<0>")
	)
	(segment
		(start 412.339028 -306.703222)
		(end 411.053534 -305.417728)
		(width 0.18288)
		(layer "In6.Cu")
		(net "M_H_CPU0_SA_DQS_DP<0>")
	)
	(segment
		(start 383.387092 -278.02078)
		(end 383.37236 -278.012144)
		(width 0.088646)
		(layer "In6.Cu")
		(net "M_H_CPU0_SA_DQS_DP<0>")
	)
	(segment
		(start 444.226696 -312.311034)
		(end 443.680596 -312.311034)
		(width 0.18288)
		(layer "In6.Cu")
		(net "M_H_CPU0_SA_DQS_DP<0>")
	)
	(segment
		(start 433.638198 -313.523376)
		(end 433.462176 -313.523376)
		(width 0.18288)
		(layer "In6.Cu")
		(net "M_H_CPU0_SA_DQS_DP<0>")
	)
	(segment
		(start 418.219382 -309.654194)
		(end 418.094922 -309.778654)
		(width 0.18288)
		(layer "In6.Cu")
		(net "M_H_CPU0_SA_DQS_DP<0>")
	)
	(segment
		(start 431.099468 -312.325766)
		(end 430.975008 -312.201306)
		(width 0.18288)
		(layer "In6.Cu")
		(net "M_H_CPU0_SA_DQS_DP<0>")
	)
	(segment
		(start 438.82183 -313.205114)
		(end 438.27573 -313.205114)
		(width 0.18288)
		(layer "In6.Cu")
		(net "M_H_CPU0_SA_DQS_DP<0>")
	)
	(segment
		(start 419.74135 -309.654194)
		(end 419.61689 -309.778654)
		(width 0.18288)
		(layer "In6.Cu")
		(net "M_H_CPU0_SA_DQS_DP<0>")
	)
	(segment
		(start 411.053534 -305.417728)
		(end 410.20619 -305.417728)
		(width 0.18288)
		(layer "In6.Cu")
		(net "M_H_CPU0_SA_DQS_DP<0>")
	)
	(segment
		(start 426.54601 -309.20944)
		(end 426.15993 -308.82336)
		(width 0.18288)
		(layer "In6.Cu")
		(net "M_H_CPU0_SA_DQS_DP<0>")
	)
	(segment
		(start 429.83023 -311.754012)
		(end 429.654208 -311.754012)
		(width 0.18288)
		(layer "In6.Cu")
		(net "M_H_CPU0_SA_DQS_DP<0>")
	)
	(segment
		(start 431.645568 -312.325766)
		(end 431.099468 -312.325766)
		(width 0.18288)
		(layer "In6.Cu")
		(net "M_H_CPU0_SA_DQS_DP<0>")
	)
	(segment
		(start 426.932344 -309.771796)
		(end 426.54601 -309.385462)
		(width 0.18288)
		(layer "In6.Cu")
		(net "M_H_CPU0_SA_DQS_DP<0>")
	)
	(segment
		(start 387.324346 -279.813766)
		(end 387.20776 -279.697434)
		(width 0.088646)
		(layer "In6.Cu")
		(net "M_H_CPU0_SA_DQS_DP<0>")
	)
	(segment
		(start 446.355216 -312.865008)
		(end 444.78067 -312.865008)
		(width 0.18288)
		(layer "In6.Cu")
		(net "M_H_CPU0_SA_DQS_DP<0>")
	)
	(segment
		(start 443.680596 -312.311034)
		(end 443.556136 -312.435494)
		(width 0.18288)
		(layer "In6.Cu")
		(net "M_H_CPU0_SA_DQS_DP<0>")
	)
	(segment
		(start 430.975008 -312.201306)
		(end 430.277524 -312.201306)
		(width 0.18288)
		(layer "In6.Cu")
		(net "M_H_CPU0_SA_DQS_DP<0>")
	)
	(segment
		(start 388.283958 -281.118818)
		(end 388.224014 -281.058874)
		(width 0.088646)
		(layer "In6.Cu")
		(net "M_H_CPU0_SA_DQS_DP<0>")
	)
	(segment
		(start 431.770028 -312.201306)
		(end 431.645568 -312.325766)
		(width 0.18288)
		(layer "In6.Cu")
		(net "M_H_CPU0_SA_DQS_DP<0>")
	)
	(segment
		(start 424.643296 -309.090822)
		(end 424.365928 -308.813454)
		(width 0.18288)
		(layer "In6.Cu")
		(net "M_H_CPU0_SA_DQS_DP<0>")
	)
	(segment
		(start 405.187658 -306.254404)
		(end 404.699216 -306.254404)
		(width 0.18288)
		(layer "In6.Cu")
		(net "M_H_CPU0_SA_DQS_DP<0>")
	)
	(segment
		(start 422.474644 -308.813454)
		(end 421.61333 -309.674768)
		(width 0.18288)
		(layer "In6.Cu")
		(net "M_H_CPU0_SA_DQS_DP<0>")
	)
	(segment
		(start 418.94633 -309.654194)
		(end 418.219382 -309.654194)
		(width 0.18288)
		(layer "In6.Cu")
		(net "M_H_CPU0_SA_DQS_DP<0>")
	)
	(segment
		(start 376.808746 -278.02078)
		(end 376.794014 -278.012144)
		(width 0.088646)
		(layer "In6.Cu")
		(net "M_H_CPU0_SA_DQS_DP<0>")
	)
	(segment
		(start 442.885576 -312.311034)
		(end 441.819284 -312.311034)
		(width 0.18288)
		(layer "In6.Cu")
		(net "M_H_CPU0_SA_DQS_DP<0>")
	)
	(segment
		(start 432.316128 -312.201306)
		(end 431.770028 -312.201306)
		(width 0.18288)
		(layer "In6.Cu")
		(net "M_H_CPU0_SA_DQS_DP<0>")
	)
	(segment
		(start 441.819284 -312.311034)
		(end 441.049664 -313.080654)
		(width 0.18288)
		(layer "In6.Cu")
		(net "M_H_CPU0_SA_DQS_DP<0>")
	)
	(segment
		(start 379.628146 -278.02078)
		(end 379.613414 -278.012144)
		(width 0.088646)
		(layer "In6.Cu")
		(net "M_H_CPU0_SA_DQS_DP<0>")
	)
	(segment
		(start 425.290996 -308.82336)
		(end 425.023534 -309.090822)
		(width 0.18288)
		(layer "In6.Cu")
		(net "M_H_CPU0_SA_DQS_DP<0>")
	)
	(segment
		(start 395.79423 -293.23284)
		(end 395.79423 -283.613606)
		(width 0.18288)
		(layer "In6.Cu")
		(net "M_H_CPU0_SA_DQS_DP<0>")
	)
	(segment
		(start 388.224014 -281.058874)
		(end 388.082536 -281.058874)
		(width 0.088646)
		(layer "In6.Cu")
		(net "M_H_CPU0_SA_DQS_DP<0>")
	)
	(segment
		(start 426.54601 -309.385462)
		(end 426.54601 -309.20944)
		(width 0.18288)
		(layer "In6.Cu")
		(net "M_H_CPU0_SA_DQS_DP<0>")
	)
	(segment
		(start 447.02857 -312.191654)
		(end 446.355216 -312.865008)
		(width 0.18288)
		(layer "In6.Cu")
		(net "M_H_CPU0_SA_DQS_DP<0>")
	)
	(segment
		(start 436.272686 -313.919616)
		(end 436.00116 -314.191142)
		(width 0.18288)
		(layer "In6.Cu")
		(net "M_H_CPU0_SA_DQS_DP<0>")
	)
	(segment
		(start 448.566794 -312.191654)
		(end 448.442334 -312.316114)
		(width 0.18288)
		(layer "In6.Cu")
		(net "M_H_CPU0_SA_DQS_DP<0>")
	)
	(segment
		(start 423.043604 -308.937914)
		(end 422.919144 -308.813454)
		(width 0.18288)
		(layer "In6.Cu")
		(net "M_H_CPU0_SA_DQS_DP<0>")
	)
	(segment
		(start 416.754564 -309.654194)
		(end 415.345372 -308.712616)
		(width 0.18288)
		(layer "In6.Cu")
		(net "M_H_CPU0_SA_DQS_DP<0>")
	)
	(segment
		(start 409.301442 -305.431698)
		(end 408.694382 -305.431698)
		(width 0.18288)
		(layer "In6.Cu")
		(net "M_H_CPU0_SA_DQS_DP<0>")
	)
	(segment
		(start 433.075842 -313.137042)
		(end 433.075842 -312.96102)
		(width 0.18288)
		(layer "In6.Cu")
		(net "M_H_CPU0_SA_DQS_DP<0>")
	)
	(segment
		(start 436.734458 -313.919616)
		(end 436.272686 -313.919616)
		(width 0.18288)
		(layer "In6.Cu")
		(net "M_H_CPU0_SA_DQS_DP<0>")
	)
	(segment
		(start 381.503428 -278.01824)
		(end 381.493014 -278.012144)
		(width 0.088646)
		(layer "In6.Cu")
		(net "M_H_CPU0_SA_DQS_DP<0>")
	)
	(segment
		(start 387.919976 -280.896314)
		(end 387.610604 -280.318718)
		(width 0.088646)
		(layer "In6.Cu")
		(net "M_H_CPU0_SA_DQS_DP<0>")
	)
	(segment
		(start 421.182546 -309.674768)
		(end 420.916354 -309.94096)
		(width 0.18288)
		(layer "In6.Cu")
		(net "M_H_CPU0_SA_DQS_DP<0>")
	)
	(segment
		(start 441.049664 -313.080654)
		(end 440.362086 -313.080654)
		(width 0.18288)
		(layer "In6.Cu")
		(net "M_H_CPU0_SA_DQS_DP<0>")
	)
	(segment
		(start 408.694382 -305.431698)
		(end 408.569922 -305.556158)
		(width 0.18288)
		(layer "In6.Cu")
		(net "M_H_CPU0_SA_DQS_DP<0>")
	)
	(segment
		(start 408.023822 -305.556158)
		(end 407.899362 -305.431698)
		(width 0.18288)
		(layer "In6.Cu")
		(net "M_H_CPU0_SA_DQS_DP<0>")
	)
	(segment
		(start 418.094922 -309.778654)
		(end 417.548822 -309.778654)
		(width 0.18288)
		(layer "In6.Cu")
		(net "M_H_CPU0_SA_DQS_DP<0>")
	)
	(segment
		(start 426.15993 -308.82336)
		(end 425.290996 -308.82336)
		(width 0.18288)
		(layer "In6.Cu")
		(net "M_H_CPU0_SA_DQS_DP<0>")
	)
	(segment
		(start 435.647084 -314.191142)
		(end 435.374034 -313.918092)
		(width 0.18288)
		(layer "In6.Cu")
		(net "M_H_CPU0_SA_DQS_DP<0>")
	)
	(segment
		(start 449.592954 -312.191654)
		(end 448.566794 -312.191654)
		(width 0.18288)
		(layer "In6.Cu")
		(net "M_H_CPU0_SA_DQS_DP<0>")
	)
	(segment
		(start 415.345372 -308.712616)
		(end 415.172906 -308.746906)
		(width 0.18288)
		(layer "In6.Cu")
		(net "M_H_CPU0_SA_DQS_DP<0>")
	)
	(segment
		(start 378.298964 -278.012144)
		(end 378.28855 -278.01824)
		(width 0.088646)
		(layer "In6.Cu")
		(net "M_H_CPU0_SA_DQS_DP<0>")
	)
	(segment
		(start 422.919144 -308.813454)
		(end 422.474644 -308.813454)
		(width 0.18288)
		(layer "In6.Cu")
		(net "M_H_CPU0_SA_DQS_DP<0>")
	)
	(segment
		(start 419.61689 -309.778654)
		(end 419.07079 -309.778654)
		(width 0.18288)
		(layer "In6.Cu")
		(net "M_H_CPU0_SA_DQS_DP<0>")
	)
	(segment
		(start 443.556136 -312.435494)
		(end 443.010036 -312.435494)
		(width 0.18288)
		(layer "In6.Cu")
		(net "M_H_CPU0_SA_DQS_DP<0>")
	)
	(segment
		(start 429.26762 -311.191402)
		(end 428.552864 -310.476646)
		(width 0.18288)
		(layer "In6.Cu")
		(net "M_H_CPU0_SA_DQS_DP<0>")
	)
	(segment
		(start 407.353262 -305.431698)
		(end 406.50922 -306.27574)
		(width 0.18288)
		(layer "In6.Cu")
		(net "M_H_CPU0_SA_DQS_DP<0>")
	)
	(segment
		(start 414.68421 -308.270402)
		(end 412.339028 -306.703222)
		(width 0.18288)
		(layer "In6.Cu")
		(net "M_H_CPU0_SA_DQS_DP<0>")
	)
	(segment
		(start 439.748676 -313.341004)
		(end 439.488326 -313.080654)
		(width 0.18288)
		(layer "In6.Cu")
		(net "M_H_CPU0_SA_DQS_DP<0>")
	)
	(segment
		(start 448.442334 -312.316114)
		(end 447.896234 -312.316114)
		(width 0.18288)
		(layer "In6.Cu")
		(net "M_H_CPU0_SA_DQS_DP<0>")
	)
	(segment
		(start 403.658578 -305.213766)
		(end 403.658578 -301.097188)
		(width 0.18288)
		(layer "In6.Cu")
		(net "M_H_CPU0_SA_DQS_DP<0>")
	)
	(segment
		(start 417.424362 -309.654194)
		(end 416.754564 -309.654194)
		(width 0.18288)
		(layer "In6.Cu")
		(net "M_H_CPU0_SA_DQS_DP<0>")
	)
	(segment
		(start 387.16966 -279.664668)
		(end 387.169152 -279.664668)
		(width 0.088646)
		(layer "In6.Cu")
		(net "M_H_CPU0_SA_DQS_DP<0>")
	)
	(segment
		(start 385.73075 -278.83104)
		(end 385.72186 -278.82596)
		(width 0.088646)
		(layer "In6.Cu")
		(net "M_H_CPU0_SA_DQS_DP<0>")
	)
	(segment
		(start 428.552864 -310.476646)
		(end 427.813216 -310.476646)
		(width 0.18288)
		(layer "In6.Cu")
		(net "M_H_CPU0_SA_DQS_DP<0>")
	)
	(segment
		(start 433.075842 -312.96102)
		(end 432.316128 -312.201306)
		(width 0.18288)
		(layer "In6.Cu")
		(net "M_H_CPU0_SA_DQS_DP<0>")
	)
	(segment
		(start 436.00116 -314.191142)
		(end 435.647084 -314.191142)
		(width 0.18288)
		(layer "In6.Cu")
		(net "M_H_CPU0_SA_DQS_DP<0>")
	)
	(segment
		(start 409.560776 -305.691032)
		(end 409.301442 -305.431698)
		(width 0.18288)
		(layer "In6.Cu")
		(net "M_H_CPU0_SA_DQS_DP<0>")
	)
	(segment
		(start 419.07079 -309.778654)
		(end 418.94633 -309.654194)
		(width 0.18288)
		(layer "In6.Cu")
		(net "M_H_CPU0_SA_DQS_DP<0>")
	)
	(segment
		(start 433.462176 -313.523376)
		(end 433.075842 -313.137042)
		(width 0.18288)
		(layer "In6.Cu")
		(net "M_H_CPU0_SA_DQS_DP<0>")
	)
	(segment
		(start 406.107646 -306.27574)
		(end 405.84501 -306.538376)
		(width 0.18288)
		(layer "In6.Cu")
		(net "M_H_CPU0_SA_DQS_DP<0>")
	)
	(segment
		(start 405.84501 -306.538376)
		(end 405.47163 -306.538376)
		(width 0.18288)
		(layer "In6.Cu")
		(net "M_H_CPU0_SA_DQS_DP<0>")
	)
	(segment
		(start 440.362086 -313.080654)
		(end 440.101736 -313.341004)
		(width 0.18288)
		(layer "In6.Cu")
		(net "M_H_CPU0_SA_DQS_DP<0>")
	)
	(segment
		(start 380.567946 -278.02078)
		(end 380.553214 -278.012144)
		(width 0.088646)
		(layer "In6.Cu")
		(net "M_H_CPU0_SA_DQS_DP<0>")
	)
	(segment
		(start 420.521384 -309.94096)
		(end 420.234618 -309.654194)
		(width 0.18288)
		(layer "In6.Cu")
		(net "M_H_CPU0_SA_DQS_DP<0>")
	)
	(segment
		(start 404.699216 -306.254404)
		(end 403.658578 -305.213766)
		(width 0.18288)
		(layer "In6.Cu")
		(net "M_H_CPU0_SA_DQS_DP<0>")
	)
	(segment
		(start 444.78067 -312.865008)
		(end 444.226696 -312.311034)
		(width 0.18288)
		(layer "In6.Cu")
		(net "M_H_CPU0_SA_DQS_DP<0>")
	)
	(segment
		(start 434.032914 -313.918092)
		(end 433.638198 -313.523376)
		(width 0.18288)
		(layer "In6.Cu")
		(net "M_H_CPU0_SA_DQS_DP<0>")
	)
	(segment
		(start 440.101736 -313.341004)
		(end 439.748676 -313.341004)
		(width 0.18288)
		(layer "In6.Cu")
		(net "M_H_CPU0_SA_DQS_DP<0>")
	)
	(segment
		(start 447.896234 -312.316114)
		(end 447.771774 -312.191654)
		(width 0.18288)
		(layer "In6.Cu")
		(net "M_H_CPU0_SA_DQS_DP<0>")
	)
	(segment
		(start 438.94629 -313.080654)
		(end 438.82183 -313.205114)
		(width 0.18288)
		(layer "In6.Cu")
		(net "M_H_CPU0_SA_DQS_DP<0>")
	)
	(segment
		(start 420.916354 -309.94096)
		(end 420.521384 -309.94096)
		(width 0.18288)
		(layer "In6.Cu")
		(net "M_H_CPU0_SA_DQS_DP<0>")
	)
	(segment
		(start 417.548822 -309.778654)
		(end 417.424362 -309.654194)
		(width 0.18288)
		(layer "In6.Cu")
		(net "M_H_CPU0_SA_DQS_DP<0>")
	)
	(segment
		(start 450.038978 -312.637678)
		(end 449.592954 -312.191654)
		(width 0.18288)
		(layer "In6.Cu")
		(net "M_H_CPU0_SA_DQS_DP<0>")
	)
	(segment
		(start 450.632322 -312.637678)
		(end 450.038978 -312.637678)
		(width 0.18288)
		(layer "In6.Cu")
		(net "M_H_CPU0_SA_DQS_DP<0>")
	)
	(segment
		(start 395.79423 -283.613606)
		(end 393.299442 -281.118818)
		(width 0.18288)
		(layer "In6.Cu")
		(net "M_H_CPU0_SA_DQS_DP<0>")
	)
	(segment
		(start 410.20619 -305.417728)
		(end 409.932886 -305.691032)
		(width 0.18288)
		(layer "In6.Cu")
		(net "M_H_CPU0_SA_DQS_DP<0>")
	)
	(segment
		(start 388.307326 -281.118818)
		(end 388.283958 -281.118818)
		(width 0.088646)
		(layer "In6.Cu")
		(net "M_H_CPU0_SA_DQS_DP<0>")
	)
	(segment
		(start 423.589704 -308.937914)
		(end 423.043604 -308.937914)
		(width 0.18288)
		(layer "In6.Cu")
		(net "M_H_CPU0_SA_DQS_DP<0>")
	)
	(segment
		(start 429.26762 -311.367424)
		(end 429.26762 -311.191402)
		(width 0.18288)
		(layer "In6.Cu")
		(net "M_H_CPU0_SA_DQS_DP<0>")
	)
	(segment
		(start 406.50922 -306.27574)
		(end 406.107646 -306.27574)
		(width 0.18288)
		(layer "In6.Cu")
		(net "M_H_CPU0_SA_DQS_DP<0>")
	)
	(segment
		(start 387.52653 -280.115772)
		(end 387.324346 -279.813766)
		(width 0.088646)
		(layer "In6.Cu")
		(net "M_H_CPU0_SA_DQS_DP<0>")
	)
	(segment
		(start 387.610604 -280.318718)
		(end 387.52653 -280.115772)
		(width 0.088646)
		(layer "In6.Cu")
		(net "M_H_CPU0_SA_DQS_DP<0>")
	)
	(segment
		(start 385.439412 -278.346408)
		(end 385.439412 -278.336502)
		(width 0.088646)
		(layer "In6.Cu")
		(net "M_H_CPU0_SA_DQS_DP<0>")
	)
	(segment
		(start 393.299442 -281.118818)
		(end 388.307326 -281.118818)
		(width 0.18288)
		(layer "In6.Cu")
		(net "M_H_CPU0_SA_DQS_DP<0>")
	)
	(segment
		(start 420.234618 -309.654194)
		(end 419.74135 -309.654194)
		(width 0.18288)
		(layer "In6.Cu")
		(net "M_H_CPU0_SA_DQS_DP<0>")
	)
	(segment
		(start 424.365928 -308.813454)
		(end 423.714164 -308.813454)
		(width 0.18288)
		(layer "In6.Cu")
		(net "M_H_CPU0_SA_DQS_DP<0>")
	)
	(segment
		(start 407.899362 -305.431698)
		(end 407.353262 -305.431698)
		(width 0.18288)
		(layer "In6.Cu")
		(net "M_H_CPU0_SA_DQS_DP<0>")
	)
	(segment
		(start 435.374034 -313.918092)
		(end 434.032914 -313.918092)
		(width 0.18288)
		(layer "In6.Cu")
		(net "M_H_CPU0_SA_DQS_DP<0>")
	)
	(segment
		(start 423.714164 -308.813454)
		(end 423.589704 -308.937914)
		(width 0.18288)
		(layer "In6.Cu")
		(net "M_H_CPU0_SA_DQS_DP<0>")
	)
	(segment
		(start 425.023534 -309.090822)
		(end 424.643296 -309.090822)
		(width 0.18288)
		(layer "In6.Cu")
		(net "M_H_CPU0_SA_DQS_DP<0>")
	)
	(segment
		(start 437.57342 -313.080654)
		(end 436.734458 -313.919616)
		(width 0.18288)
		(layer "In6.Cu")
		(net "M_H_CPU0_SA_DQS_DP<0>")
	)
	(segment
		(start 379.239018 -278.012144)
		(end 379.228604 -278.01824)
		(width 0.088646)
		(layer "In6.Cu")
		(net "M_H_CPU0_SA_DQS_DP<0>")
	)
	(segment
		(start 429.654208 -311.754012)
		(end 429.26762 -311.367424)
		(width 0.18288)
		(layer "In6.Cu")
		(net "M_H_CPU0_SA_DQS_DP<0>")
	)
	(segment
		(start 438.15127 -313.080654)
		(end 437.57342 -313.080654)
		(width 0.18288)
		(layer "In6.Cu")
		(net "M_H_CPU0_SA_DQS_DP<0>")
	)
	(segment
		(start 438.27573 -313.205114)
		(end 438.15127 -313.080654)
		(width 0.18288)
		(layer "In6.Cu")
		(net "M_H_CPU0_SA_DQS_DP<0>")
	)
	(segment
		(start 430.277524 -312.201306)
		(end 429.83023 -311.754012)
		(width 0.18288)
		(layer "In6.Cu")
		(net "M_H_CPU0_SA_DQS_DP<0>")
	)
	(arc
		(start 382.058164 -278.012144)
		(mid 381.781605 -278.087853)
		(end 381.503428 -278.01824)
		(width 0.088646)
		(layer "In6.Cu")
		(net "M_H_CPU0_SA_DQS_DP<0>")
	)
	(arc
		(start 384.31216 -278.012144)
		(mid 384.124962 -277.962001)
		(end 383.937764 -278.012144)
		(width 0.088646)
		(layer "In6.Cu")
		(net "M_H_CPU0_SA_DQS_DP<0>")
	)
	(arc
		(start 376.419618 -278.012144)
		(mid 376.145389 -278.088069)
		(end 375.868946 -278.02078)
		(width 0.088646)
		(layer "In6.Cu")
		(net "M_H_CPU0_SA_DQS_DP<0>")
	)
	(arc
		(start 384.877564 -278.012144)
		(mid 384.594862 -278.087886)
		(end 384.31216 -278.012144)
		(width 0.088646)
		(layer "In6.Cu")
		(net "M_H_CPU0_SA_DQS_DP<0>")
	)
	(arc
		(start 378.67336 -278.012144)
		(mid 378.486162 -277.962001)
		(end 378.298964 -278.012144)
		(width 0.088646)
		(layer "In6.Cu")
		(net "M_H_CPU0_SA_DQS_DP<0>")
	)
	(arc
		(start 381.493014 -278.012144)
		(mid 381.305816 -277.962001)
		(end 381.118618 -278.012144)
		(width 0.088646)
		(layer "In6.Cu")
		(net "M_H_CPU0_SA_DQS_DP<0>")
	)
	(arc
		(start 381.118618 -278.012144)
		(mid 380.844389 -278.088069)
		(end 380.567946 -278.02078)
		(width 0.088646)
		(layer "In6.Cu")
		(net "M_H_CPU0_SA_DQS_DP<0>")
	)
	(arc
		(start 385.439412 -278.336502)
		(mid 385.252113 -278.012061)
		(end 384.877564 -278.012144)
		(width 0.088646)
		(layer "In6.Cu")
		(net "M_H_CPU0_SA_DQS_DP<0>")
	)
	(arc
		(start 387.169152 -279.664668)
		(mid 386.966903 -279.590366)
		(end 386.757164 -279.639776)
		(width 0.088646)
		(layer "In6.Cu")
		(net "M_H_CPU0_SA_DQS_DP<0>")
	)
	(arc
		(start 387.20776 -279.697434)
		(mid 387.189257 -279.680415)
		(end 387.16966 -279.664668)
		(width 0.088646)
		(layer "In6.Cu")
		(net "M_H_CPU0_SA_DQS_DP<0>")
	)
	(arc
		(start 383.937764 -278.012144)
		(mid 383.663535 -278.088069)
		(end 383.387092 -278.02078)
		(width 0.088646)
		(layer "In6.Cu")
		(net "M_H_CPU0_SA_DQS_DP<0>")
	)
	(arc
		(start 378.28855 -278.01824)
		(mid 378.010372 -278.087932)
		(end 377.733814 -278.012144)
		(width 0.088646)
		(layer "In6.Cu")
		(net "M_H_CPU0_SA_DQS_DP<0>")
	)
	(arc
		(start 385.72186 -278.82596)
		(mid 385.517525 -278.623355)
		(end 385.439412 -278.346408)
		(width 0.088646)
		(layer "In6.Cu")
		(net "M_H_CPU0_SA_DQS_DP<0>")
	)
	(arc
		(start 377.359418 -278.012144)
		(mid 377.085189 -278.088069)
		(end 376.808746 -278.02078)
		(width 0.088646)
		(layer "In6.Cu")
		(net "M_H_CPU0_SA_DQS_DP<0>")
	)
	(arc
		(start 379.613414 -278.012144)
		(mid 379.426216 -277.962001)
		(end 379.239018 -278.012144)
		(width 0.088646)
		(layer "In6.Cu")
		(net "M_H_CPU0_SA_DQS_DP<0>")
	)
	(arc
		(start 382.997964 -278.012144)
		(mid 382.715262 -278.087886)
		(end 382.43256 -278.012144)
		(width 0.088646)
		(layer "In6.Cu")
		(net "M_H_CPU0_SA_DQS_DP<0>")
	)
	(arc
		(start 377.733814 -278.012144)
		(mid 377.546616 -277.962001)
		(end 377.359418 -278.012144)
		(width 0.088646)
		(layer "In6.Cu")
		(net "M_H_CPU0_SA_DQS_DP<0>")
	)
	(arc
		(start 385.909312 -279.150318)
		(mid 385.861633 -278.967418)
		(end 385.73075 -278.83104)
		(width 0.088646)
		(layer "In6.Cu")
		(net "M_H_CPU0_SA_DQS_DP<0>")
	)
	(arc
		(start 386.757164 -279.639776)
		(mid 386.196188 -279.642307)
		(end 385.909312 -279.160224)
		(width 0.088646)
		(layer "In6.Cu")
		(net "M_H_CPU0_SA_DQS_DP<0>")
	)
	(arc
		(start 376.794014 -278.012144)
		(mid 376.606816 -277.962001)
		(end 376.419618 -278.012144)
		(width 0.088646)
		(layer "In6.Cu")
		(net "M_H_CPU0_SA_DQS_DP<0>")
	)
	(arc
		(start 379.228604 -278.01824)
		(mid 378.950172 -278.088054)
		(end 378.67336 -278.012144)
		(width 0.088646)
		(layer "In6.Cu")
		(net "M_H_CPU0_SA_DQS_DP<0>")
	)
	(arc
		(start 383.37236 -278.012144)
		(mid 383.185162 -277.962001)
		(end 382.997964 -278.012144)
		(width 0.088646)
		(layer "In6.Cu")
		(net "M_H_CPU0_SA_DQS_DP<0>")
	)
	(arc
		(start 382.43256 -278.012144)
		(mid 382.245362 -277.962001)
		(end 382.058164 -278.012144)
		(width 0.088646)
		(layer "In6.Cu")
		(net "M_H_CPU0_SA_DQS_DP<0>")
	)
	(arc
		(start 380.553214 -278.012144)
		(mid 380.366016 -277.962001)
		(end 380.178818 -278.012144)
		(width 0.088646)
		(layer "In6.Cu")
		(net "M_H_CPU0_SA_DQS_DP<0>")
	)
	(arc
		(start 375.854214 -278.012144)
		(mid 375.51205 -277.785393)
		(end 375.196862 -277.522432)
		(width 0.088646)
		(layer "In6.Cu")
		(net "M_H_CPU0_SA_DQS_DP<0>")
	)
	(arc
		(start 380.178818 -278.012144)
		(mid 379.904589 -278.088069)
		(end 379.628146 -278.02078)
		(width 0.088646)
		(layer "In6.Cu")
		(net "M_H_CPU0_SA_DQS_DP<0>")
	)
	(segment
		(start 462.110328 -274.412456)
		(end 461.664812 -273.96694)
		(width 0.20066)
		(layer "F.Cu")
		(net "M_H_CPU0_SA_DQS_DN<9>")
	)
	(segment
		(start 457.948792 -273.970496)
		(end 457.826364 -273.970496)
		(width 0.20066)
		(layer "F.Cu")
		(net "M_H_CPU0_SA_DQS_DN<9>")
	)
	(segment
		(start 463.1563 -274.66671)
		(end 462.902046 -274.412456)
		(width 0.20066)
		(layer "F.Cu")
		(net "M_H_CPU0_SA_DQS_DN<9>")
	)
	(segment
		(start 458.22616 -274.247864)
		(end 457.948792 -273.970496)
		(width 0.20066)
		(layer "F.Cu")
		(net "M_H_CPU0_SA_DQS_DN<9>")
	)
	(segment
		(start 461.664812 -273.96694)
		(end 461.174846 -273.96694)
		(width 0.20066)
		(layer "F.Cu")
		(net "M_H_CPU0_SA_DQS_DN<9>")
	)
	(segment
		(start 373.787162 -260.430518)
		(end 373.787416 -260.430772)
		(width 0.20066)
		(layer "F.Cu")
		(net "M_H_CPU0_SA_DQS_DN<9>")
	)
	(segment
		(start 458.543152 -274.247864)
		(end 458.538326 -274.247864)
		(width 0.101854)
		(layer "F.Cu")
		(net "M_H_CPU0_SA_DQS_DN<9>")
	)
	(segment
		(start 456.646788 -274.66671)
		(end 456.116182 -274.66671)
		(width 0.20066)
		(layer "F.Cu")
		(net "M_H_CPU0_SA_DQS_DN<9>")
	)
	(segment
		(start 460.570326 -274.25269)
		(end 460.559404 -274.241768)
		(width 0.1016)
		(layer "F.Cu")
		(net "M_H_CPU0_SA_DQS_DN<9>")
	)
	(segment
		(start 461.174846 -273.96694)
		(end 460.889096 -274.25269)
		(width 0.20066)
		(layer "F.Cu")
		(net "M_H_CPU0_SA_DQS_DN<9>")
	)
	(segment
		(start 373.787162 -259.894832)
		(end 373.787162 -260.430518)
		(width 0.20066)
		(layer "F.Cu")
		(net "M_H_CPU0_SA_DQS_DN<9>")
	)
	(segment
		(start 455.011282 -274.66671)
		(end 456.116182 -274.66671)
		(width 0.20066)
		(layer "F.Cu")
		(net "M_H_CPU0_SA_DQS_DN<9>")
	)
	(segment
		(start 457.401422 -274.395438)
		(end 456.91806 -274.395438)
		(width 0.20066)
		(layer "F.Cu")
		(net "M_H_CPU0_SA_DQS_DN<9>")
	)
	(segment
		(start 460.889096 -274.25269)
		(end 460.570326 -274.25269)
		(width 0.20066)
		(layer "F.Cu")
		(net "M_H_CPU0_SA_DQS_DN<9>")
	)
	(segment
		(start 462.902046 -274.412456)
		(end 462.110328 -274.412456)
		(width 0.20066)
		(layer "F.Cu")
		(net "M_H_CPU0_SA_DQS_DN<9>")
	)
	(segment
		(start 458.549248 -274.241768)
		(end 458.543152 -274.247864)
		(width 0.1016)
		(layer "F.Cu")
		(net "M_H_CPU0_SA_DQS_DN<9>")
	)
	(segment
		(start 460.559404 -274.241768)
		(end 458.549248 -274.241768)
		(width 0.1016)
		(layer "F.Cu")
		(net "M_H_CPU0_SA_DQS_DN<9>")
	)
	(segment
		(start 456.91806 -274.395438)
		(end 456.646788 -274.66671)
		(width 0.20066)
		(layer "F.Cu")
		(net "M_H_CPU0_SA_DQS_DN<9>")
	)
	(segment
		(start 458.538326 -274.247864)
		(end 458.22616 -274.247864)
		(width 0.20066)
		(layer "F.Cu")
		(net "M_H_CPU0_SA_DQS_DN<9>")
	)
	(segment
		(start 463.659982 -274.66671)
		(end 463.1563 -274.66671)
		(width 0.20066)
		(layer "F.Cu")
		(net "M_H_CPU0_SA_DQS_DN<9>")
	)
	(segment
		(start 457.826364 -273.970496)
		(end 457.401422 -274.395438)
		(width 0.20066)
		(layer "F.Cu")
		(net "M_H_CPU0_SA_DQS_DN<9>")
	)
	(segment
		(start 433.904644 -274.11934)
		(end 433.780184 -273.99488)
		(width 0.18288)
		(layer "In11.Cu")
		(net "M_H_CPU0_SA_DQS_DN<9>")
	)
	(segment
		(start 451.403974 -273.976592)
		(end 451.144386 -274.23618)
		(width 0.18288)
		(layer "In11.Cu")
		(net "M_H_CPU0_SA_DQS_DN<9>")
	)
	(segment
		(start 380.563628 -260.11251)
		(end 380.553214 -260.106414)
		(width 0.088646)
		(layer "In11.Cu")
		(net "M_H_CPU0_SA_DQS_DN<9>")
	)
	(segment
		(start 388.128764 -262.623554)
		(end 387.884162 -262.623554)
		(width 0.088646)
		(layer "In11.Cu")
		(net "M_H_CPU0_SA_DQS_DN<9>")
	)
	(segment
		(start 378.688346 -260.11505)
		(end 378.673614 -260.106414)
		(width 0.088646)
		(layer "In11.Cu")
		(net "M_H_CPU0_SA_DQS_DN<9>")
	)
	(segment
		(start 408.2034 -273.384264)
		(end 406.902412 -273.384264)
		(width 0.18288)
		(layer "In11.Cu")
		(net "M_H_CPU0_SA_DQS_DN<9>")
	)
	(segment
		(start 374.53951 -260.106668)
		(end 374.537986 -260.10743)
		(width 0.088646)
		(layer "In11.Cu")
		(net "M_H_CPU0_SA_DQS_DN<9>")
	)
	(segment
		(start 383.387092 -260.11505)
		(end 383.37236 -260.106414)
		(width 0.088646)
		(layer "In11.Cu")
		(net "M_H_CPU0_SA_DQS_DN<9>")
	)
	(segment
		(start 446.780412 -275.246084)
		(end 446.273682 -275.45665)
		(width 0.18288)
		(layer "In11.Cu")
		(net "M_H_CPU0_SA_DQS_DN<9>")
	)
	(segment
		(start 414.811464 -274.63242)
		(end 414.687004 -274.75688)
		(width 0.18288)
		(layer "In11.Cu")
		(net "M_H_CPU0_SA_DQS_DN<9>")
	)
	(segment
		(start 448.091052 -274.56638)
		(end 448.023742 -274.729194)
		(width 0.18288)
		(layer "In11.Cu")
		(net "M_H_CPU0_SA_DQS_DN<9>")
	)
	(segment
		(start 452.748142 -274.558252)
		(end 452.199502 -274.558252)
		(width 0.18288)
		(layer "In11.Cu")
		(net "M_H_CPU0_SA_DQS_DN<9>")
	)
	(segment
		(start 453.421242 -274.682712)
		(end 452.872602 -274.682712)
		(width 0.18288)
		(layer "In11.Cu")
		(net "M_H_CPU0_SA_DQS_DN<9>")
	)
	(segment
		(start 439.62955 -275.940774)
		(end 439.360818 -275.672042)
		(width 0.18288)
		(layer "In11.Cu")
		(net "M_H_CPU0_SA_DQS_DN<9>")
	)
	(segment
		(start 424.54195 -275.940774)
		(end 424.280584 -275.679408)
		(width 0.18288)
		(layer "In11.Cu")
		(net "M_H_CPU0_SA_DQS_DN<9>")
	)
	(segment
		(start 454.346056 -274.396454)
		(end 453.955404 -274.558252)
		(width 0.18288)
		(layer "In11.Cu")
		(net "M_H_CPU0_SA_DQS_DN<9>")
	)
	(segment
		(start 430.325276 -274.710398)
		(end 430.200816 -274.585938)
		(width 0.18288)
		(layer "In11.Cu")
		(net "M_H_CPU0_SA_DQS_DN<9>")
	)
	(segment
		(start 422.193974 -274.396962)
		(end 421.806116 -274.009104)
		(width 0.18288)
		(layer "In11.Cu")
		(net "M_H_CPU0_SA_DQS_DN<9>")
	)
	(segment
		(start 428.126906 -274.585938)
		(end 426.80382 -275.134578)
		(width 0.18288)
		(layer "In11.Cu")
		(net "M_H_CPU0_SA_DQS_DN<9>")
	)
	(segment
		(start 385.26085 -260.111494)
		(end 385.253484 -260.107176)
		(width 0.088646)
		(layer "In11.Cu")
		(net "M_H_CPU0_SA_DQS_DN<9>")
	)
	(segment
		(start 417.703 -274.248626)
		(end 417.60521 -274.395438)
		(width 0.18288)
		(layer "In11.Cu")
		(net "M_H_CPU0_SA_DQS_DN<9>")
	)
	(segment
		(start 436.051706 -274.240752)
		(end 435.529482 -274.240752)
		(width 0.18288)
		(layer "In11.Cu")
		(net "M_H_CPU0_SA_DQS_DN<9>")
	)
	(segment
		(start 439.360818 -275.672042)
		(end 438.874408 -275.672042)
		(width 0.18288)
		(layer "In11.Cu")
		(net "M_H_CPU0_SA_DQS_DN<9>")
	)
	(segment
		(start 404.514558 -273.384264)
		(end 393.936728 -262.806434)
		(width 0.18288)
		(layer "In11.Cu")
		(net "M_H_CPU0_SA_DQS_DN<9>")
	)
	(segment
		(start 438.032398 -275.077936)
		(end 437.856376 -275.077936)
		(width 0.18288)
		(layer "In11.Cu")
		(net "M_H_CPU0_SA_DQS_DN<9>")
	)
	(segment
		(start 436.959248 -274.004786)
		(end 436.287672 -274.004786)
		(width 0.18288)
		(layer "In11.Cu")
		(net "M_H_CPU0_SA_DQS_DN<9>")
	)
	(segment
		(start 426.80382 -275.134578)
		(end 426.573442 -275.365464)
		(width 0.18288)
		(layer "In11.Cu")
		(net "M_H_CPU0_SA_DQS_DN<9>")
	)
	(segment
		(start 444.23838 -275.72462)
		(end 444.11392 -275.60016)
		(width 0.18288)
		(layer "In11.Cu")
		(net "M_H_CPU0_SA_DQS_DN<9>")
	)
	(segment
		(start 437.46801 -274.68957)
		(end 437.46801 -274.513548)
		(width 0.18288)
		(layer "In11.Cu")
		(net "M_H_CPU0_SA_DQS_DN<9>")
	)
	(segment
		(start 444.78702 -275.72462)
		(end 444.23838 -275.72462)
		(width 0.18288)
		(layer "In11.Cu")
		(net "M_H_CPU0_SA_DQS_DN<9>")
	)
	(segment
		(start 437.856376 -275.077936)
		(end 437.46801 -274.68957)
		(width 0.18288)
		(layer "In11.Cu")
		(net "M_H_CPU0_SA_DQS_DN<9>")
	)
	(segment
		(start 406.229312 -273.508724)
		(end 406.104852 -273.384264)
		(width 0.18288)
		(layer "In11.Cu")
		(net "M_H_CPU0_SA_DQS_DN<9>")
	)
	(segment
		(start 417.06673 -274.502372)
		(end 416.920426 -274.404582)
		(width 0.18288)
		(layer "In11.Cu")
		(net "M_H_CPU0_SA_DQS_DN<9>")
	)
	(segment
		(start 438.452514 -275.498052)
		(end 438.032398 -275.077936)
		(width 0.18288)
		(layer "In11.Cu")
		(net "M_H_CPU0_SA_DQS_DN<9>")
	)
	(segment
		(start 430.998376 -274.585938)
		(end 430.873916 -274.710398)
		(width 0.18288)
		(layer "In11.Cu")
		(net "M_H_CPU0_SA_DQS_DN<9>")
	)
	(segment
		(start 409.027376 -273.725386)
		(end 408.2034 -273.384264)
		(width 0.18288)
		(layer "In11.Cu")
		(net "M_H_CPU0_SA_DQS_DN<9>")
	)
	(segment
		(start 385.73075 -260.925564)
		(end 385.72186 -260.920484)
		(width 0.088646)
		(layer "In11.Cu")
		(net "M_H_CPU0_SA_DQS_DN<9>")
	)
	(segment
		(start 429.527716 -274.710398)
		(end 428.979076 -274.710398)
		(width 0.18288)
		(layer "In11.Cu")
		(net "M_H_CPU0_SA_DQS_DN<9>")
	)
	(segment
		(start 433.23129 -273.99488)
		(end 431.80381 -274.585938)
		(width 0.18288)
		(layer "In11.Cu")
		(net "M_H_CPU0_SA_DQS_DN<9>")
	)
	(segment
		(start 411.219142 -274.098004)
		(end 411.151578 -273.93519)
		(width 0.18288)
		(layer "In11.Cu")
		(net "M_H_CPU0_SA_DQS_DN<9>")
	)
	(segment
		(start 452.199502 -274.558252)
		(end 451.617842 -273.976592)
		(width 0.18288)
		(layer "In11.Cu")
		(net "M_H_CPU0_SA_DQS_DN<9>")
	)
	(segment
		(start 447.354198 -274.872704)
		(end 446.847722 -275.083016)
		(width 0.18288)
		(layer "In11.Cu")
		(net "M_H_CPU0_SA_DQS_DN<9>")
	)
	(segment
		(start 420.189406 -273.988276)
		(end 419.01237 -273.988276)
		(width 0.18288)
		(layer "In11.Cu")
		(net "M_H_CPU0_SA_DQS_DN<9>")
	)
	(segment
		(start 374.537986 -260.10743)
		(end 374.453658 -260.15442)
		(width 0.088646)
		(layer "In11.Cu")
		(net "M_H_CPU0_SA_DQS_DN<9>")
	)
	(segment
		(start 446.847722 -275.083016)
		(end 446.780412 -275.246084)
		(width 0.18288)
		(layer "In11.Cu")
		(net "M_H_CPU0_SA_DQS_DN<9>")
	)
	(segment
		(start 373.892318 -260.200648)
		(end 373.87022 -260.210046)
		(width 0.088646)
		(layer "In11.Cu")
		(net "M_H_CPU0_SA_DQS_DN<9>")
	)
	(segment
		(start 388.2517 -262.74649)
		(end 388.128764 -262.623554)
		(width 0.088646)
		(layer "In11.Cu")
		(net "M_H_CPU0_SA_DQS_DN<9>")
	)
	(segment
		(start 425.064174 -275.940774)
		(end 424.54195 -275.940774)
		(width 0.18288)
		(layer "In11.Cu")
		(net "M_H_CPU0_SA_DQS_DN<9>")
	)
	(segment
		(start 422.582086 -274.961096)
		(end 422.193974 -274.572984)
		(width 0.18288)
		(layer "In11.Cu")
		(net "M_H_CPU0_SA_DQS_DN<9>")
	)
	(segment
		(start 406.777952 -273.508724)
		(end 406.229312 -273.508724)
		(width 0.18288)
		(layer "In11.Cu")
		(net "M_H_CPU0_SA_DQS_DN<9>")
	)
	(segment
		(start 430.873916 -274.710398)
		(end 430.325276 -274.710398)
		(width 0.18288)
		(layer "In11.Cu")
		(net "M_H_CPU0_SA_DQS_DN<9>")
	)
	(segment
		(start 453.545702 -274.558252)
		(end 453.421242 -274.682712)
		(width 0.18288)
		(layer "In11.Cu")
		(net "M_H_CPU0_SA_DQS_DN<9>")
	)
	(segment
		(start 410.644848 -273.725386)
		(end 409.027376 -273.725386)
		(width 0.18288)
		(layer "In11.Cu")
		(net "M_H_CPU0_SA_DQS_DN<9>")
	)
	(segment
		(start 434.453284 -274.11934)
		(end 433.904644 -274.11934)
		(width 0.18288)
		(layer "In11.Cu")
		(net "M_H_CPU0_SA_DQS_DN<9>")
	)
	(segment
		(start 387.31952 -262.06069)
		(end 387.319266 -262.049768)
		(width 0.088646)
		(layer "In11.Cu")
		(net "M_H_CPU0_SA_DQS_DN<9>")
	)
	(segment
		(start 424.280584 -275.679408)
		(end 423.47642 -275.679408)
		(width 0.18288)
		(layer "In11.Cu")
		(net "M_H_CPU0_SA_DQS_DN<9>")
	)
	(segment
		(start 411.151578 -273.93519)
		(end 410.644848 -273.725386)
		(width 0.18288)
		(layer "In11.Cu")
		(net "M_H_CPU0_SA_DQS_DN<9>")
	)
	(segment
		(start 414.138364 -274.75688)
		(end 414.013904 -274.63242)
		(width 0.18288)
		(layer "In11.Cu")
		(net "M_H_CPU0_SA_DQS_DN<9>")
	)
	(segment
		(start 453.955404 -274.558252)
		(end 453.545702 -274.558252)
		(width 0.18288)
		(layer "In11.Cu")
		(net "M_H_CPU0_SA_DQS_DN<9>")
	)
	(segment
		(start 385.439412 -260.449314)
		(end 385.439412 -260.430772)
		(width 0.088646)
		(layer "In11.Cu")
		(net "M_H_CPU0_SA_DQS_DN<9>")
	)
	(segment
		(start 388.78256 -262.74649)
		(end 388.2517 -262.74649)
		(width 0.088646)
		(layer "In11.Cu")
		(net "M_H_CPU0_SA_DQS_DN<9>")
	)
	(segment
		(start 387.31952 -262.069072)
		(end 387.31952 -262.06069)
		(width 0.088646)
		(layer "In11.Cu")
		(net "M_H_CPU0_SA_DQS_DN<9>")
	)
	(segment
		(start 442.032644 -275.078444)
		(end 441.027312 -275.495258)
		(width 0.18288)
		(layer "In11.Cu")
		(net "M_H_CPU0_SA_DQS_DN<9>")
	)
	(segment
		(start 445.604392 -275.599906)
		(end 445.604646 -275.60016)
		(width 0.18288)
		(layer "In11.Cu")
		(net "M_H_CPU0_SA_DQS_DN<9>")
	)
	(segment
		(start 425.309538 -275.69541)
		(end 425.064174 -275.940774)
		(width 0.18288)
		(layer "In11.Cu")
		(net "M_H_CPU0_SA_DQS_DN<9>")
	)
	(segment
		(start 435.529482 -274.240752)
		(end 435.28361 -273.99488)
		(width 0.18288)
		(layer "In11.Cu")
		(net "M_H_CPU0_SA_DQS_DN<9>")
	)
	(segment
		(start 379.628146 -260.11505)
		(end 379.613414 -260.106414)
		(width 0.088646)
		(layer "In11.Cu")
		(net "M_H_CPU0_SA_DQS_DN<9>")
	)
	(segment
		(start 438.874408 -275.672042)
		(end 438.452514 -275.498052)
		(width 0.18288)
		(layer "In11.Cu")
		(net "M_H_CPU0_SA_DQS_DN<9>")
	)
	(segment
		(start 375.868946 -260.11505)
		(end 375.854214 -260.106414)
		(width 0.088646)
		(layer "In11.Cu")
		(net "M_H_CPU0_SA_DQS_DN<9>")
	)
	(segment
		(start 446.273682 -275.45665)
		(end 446.110868 -275.389594)
		(width 0.18288)
		(layer "In11.Cu")
		(net "M_H_CPU0_SA_DQS_DN<9>")
	)
	(segment
		(start 440.817762 -275.704808)
		(end 440.38774 -275.704808)
		(width 0.18288)
		(layer "In11.Cu")
		(net "M_H_CPU0_SA_DQS_DN<9>")
	)
	(segment
		(start 451.144386 -274.23618)
		(end 450.961506 -274.23618)
		(width 0.18288)
		(layer "In11.Cu")
		(net "M_H_CPU0_SA_DQS_DN<9>")
	)
	(segment
		(start 433.780184 -273.99488)
		(end 433.23129 -273.99488)
		(width 0.18288)
		(layer "In11.Cu")
		(net "M_H_CPU0_SA_DQS_DN<9>")
	)
	(segment
		(start 455.011282 -274.66671)
		(end 454.741026 -274.396454)
		(width 0.18288)
		(layer "In11.Cu")
		(net "M_H_CPU0_SA_DQS_DN<9>")
	)
	(segment
		(start 411.888686 -274.240498)
		(end 411.726126 -274.307808)
		(width 0.18288)
		(layer "In11.Cu")
		(net "M_H_CPU0_SA_DQS_DN<9>")
	)
	(segment
		(start 440.38774 -275.704808)
		(end 440.151774 -275.940774)
		(width 0.18288)
		(layer "In11.Cu")
		(net "M_H_CPU0_SA_DQS_DN<9>")
	)
	(segment
		(start 444.11392 -275.60016)
		(end 443.473078 -275.60016)
		(width 0.18288)
		(layer "In11.Cu")
		(net "M_H_CPU0_SA_DQS_DN<9>")
	)
	(segment
		(start 428.854616 -274.585938)
		(end 428.126906 -274.585938)
		(width 0.18288)
		(layer "In11.Cu")
		(net "M_H_CPU0_SA_DQS_DN<9>")
	)
	(segment
		(start 436.287672 -274.004786)
		(end 436.051706 -274.240752)
		(width 0.18288)
		(layer "In11.Cu")
		(net "M_H_CPU0_SA_DQS_DN<9>")
	)
	(segment
		(start 450.735446 -274.23618)
		(end 448.885564 -274.23618)
		(width 0.18288)
		(layer "In11.Cu")
		(net "M_H_CPU0_SA_DQS_DN<9>")
	)
	(segment
		(start 381.503174 -260.11251)
		(end 381.49276 -260.106414)
		(width 0.088646)
		(layer "In11.Cu")
		(net "M_H_CPU0_SA_DQS_DN<9>")
	)
	(segment
		(start 431.80381 -274.585938)
		(end 430.998376 -274.585938)
		(width 0.18288)
		(layer "In11.Cu")
		(net "M_H_CPU0_SA_DQS_DN<9>")
	)
	(segment
		(start 374.453658 -260.15442)
		(end 374.314974 -260.19252)
		(width 0.088646)
		(layer "In11.Cu")
		(net "M_H_CPU0_SA_DQS_DN<9>")
	)
	(segment
		(start 435.28361 -273.99488)
		(end 434.577744 -273.99488)
		(width 0.18288)
		(layer "In11.Cu")
		(net "M_H_CPU0_SA_DQS_DN<9>")
	)
	(segment
		(start 443.473078 -275.60016)
		(end 442.21527 -275.078444)
		(width 0.18288)
		(layer "In11.Cu")
		(net "M_H_CPU0_SA_DQS_DN<9>")
	)
	(segment
		(start 421.255698 -274.009104)
		(end 421.02405 -274.240752)
		(width 0.18288)
		(layer "In11.Cu")
		(net "M_H_CPU0_SA_DQS_DN<9>")
	)
	(segment
		(start 434.577744 -273.99488)
		(end 434.453284 -274.11934)
		(width 0.18288)
		(layer "In11.Cu")
		(net "M_H_CPU0_SA_DQS_DN<9>")
	)
	(segment
		(start 388.842504 -262.806434)
		(end 388.78256 -262.74649)
		(width 0.088646)
		(layer "In11.Cu")
		(net "M_H_CPU0_SA_DQS_DN<9>")
	)
	(segment
		(start 444.91148 -275.60016)
		(end 444.78702 -275.72462)
		(width 0.18288)
		(layer "In11.Cu")
		(net "M_H_CPU0_SA_DQS_DN<9>")
	)
	(segment
		(start 406.902412 -273.384264)
		(end 406.777952 -273.508724)
		(width 0.18288)
		(layer "In11.Cu")
		(net "M_H_CPU0_SA_DQS_DN<9>")
	)
	(segment
		(start 445.604646 -275.60016)
		(end 444.91148 -275.60016)
		(width 0.18288)
		(layer "In11.Cu")
		(net "M_H_CPU0_SA_DQS_DN<9>")
	)
	(segment
		(start 421.02405 -274.240752)
		(end 420.441882 -274.240752)
		(width 0.18288)
		(layer "In11.Cu")
		(net "M_H_CPU0_SA_DQS_DN<9>")
	)
	(segment
		(start 373.787416 -260.305804)
		(end 373.787416 -260.430772)
		(width 0.088646)
		(layer "In11.Cu")
		(net "M_H_CPU0_SA_DQS_DN<9>")
	)
	(segment
		(start 425.778676 -275.69541)
		(end 425.309538 -275.69541)
		(width 0.18288)
		(layer "In11.Cu")
		(net "M_H_CPU0_SA_DQS_DN<9>")
	)
	(segment
		(start 406.104852 -273.384264)
		(end 404.514558 -273.384264)
		(width 0.18288)
		(layer "In11.Cu")
		(net "M_H_CPU0_SA_DQS_DN<9>")
	)
	(segment
		(start 422.758108 -274.961096)
		(end 422.582086 -274.961096)
		(width 0.18288)
		(layer "In11.Cu")
		(net "M_H_CPU0_SA_DQS_DN<9>")
	)
	(segment
		(start 422.193974 -274.572984)
		(end 422.193974 -274.396962)
		(width 0.18288)
		(layer "In11.Cu")
		(net "M_H_CPU0_SA_DQS_DN<9>")
	)
	(segment
		(start 448.023742 -274.729194)
		(end 447.517012 -274.93976)
		(width 0.18288)
		(layer "In11.Cu")
		(net "M_H_CPU0_SA_DQS_DN<9>")
	)
	(segment
		(start 411.726126 -274.307808)
		(end 411.219142 -274.098004)
		(width 0.18288)
		(layer "In11.Cu")
		(net "M_H_CPU0_SA_DQS_DN<9>")
	)
	(segment
		(start 385.909312 -261.254748)
		(end 385.909312 -261.244842)
		(width 0.088646)
		(layer "In11.Cu")
		(net "M_H_CPU0_SA_DQS_DN<9>")
	)
	(segment
		(start 386.757672 -261.734046)
		(end 386.757164 -261.7343)
		(width 0.088646)
		(layer "In11.Cu")
		(net "M_H_CPU0_SA_DQS_DN<9>")
	)
	(segment
		(start 437.46801 -274.513548)
		(end 436.959248 -274.004786)
		(width 0.18288)
		(layer "In11.Cu")
		(net "M_H_CPU0_SA_DQS_DN<9>")
	)
	(segment
		(start 414.013904 -274.63242)
		(end 412.835852 -274.63242)
		(width 0.18288)
		(layer "In11.Cu")
		(net "M_H_CPU0_SA_DQS_DN<9>")
	)
	(segment
		(start 385.253484 -260.107176)
		(end 385.25196 -260.106414)
		(width 0.088646)
		(layer "In11.Cu")
		(net "M_H_CPU0_SA_DQS_DN<9>")
	)
	(segment
		(start 374.314974 -260.19252)
		(end 373.892318 -260.200648)
		(width 0.088646)
		(layer "In11.Cu")
		(net "M_H_CPU0_SA_DQS_DN<9>")
	)
	(segment
		(start 376.808746 -260.11505)
		(end 376.794014 -260.106414)
		(width 0.088646)
		(layer "In11.Cu")
		(net "M_H_CPU0_SA_DQS_DN<9>")
	)
	(segment
		(start 423.47642 -275.679408)
		(end 422.758108 -274.961096)
		(width 0.18288)
		(layer "In11.Cu")
		(net "M_H_CPU0_SA_DQS_DN<9>")
	)
	(segment
		(start 442.21527 -275.078444)
		(end 442.032644 -275.078444)
		(width 0.18288)
		(layer "In11.Cu")
		(net "M_H_CPU0_SA_DQS_DN<9>")
	)
	(segment
		(start 426.573442 -275.365464)
		(end 425.778676 -275.69541)
		(width 0.18288)
		(layer "In11.Cu")
		(net "M_H_CPU0_SA_DQS_DN<9>")
	)
	(segment
		(start 454.741026 -274.396454)
		(end 454.346056 -274.396454)
		(width 0.18288)
		(layer "In11.Cu")
		(net "M_H_CPU0_SA_DQS_DN<9>")
	)
	(segment
		(start 415.776156 -274.63242)
		(end 414.811464 -274.63242)
		(width 0.18288)
		(layer "In11.Cu")
		(net "M_H_CPU0_SA_DQS_DN<9>")
	)
	(segment
		(start 450.961506 -274.23618)
		(end 450.735446 -274.23618)
		(width 0.16002)
		(layer "In11.Cu")
		(net "M_H_CPU0_SA_DQS_DN<9>")
	)
	(segment
		(start 373.796814 -260.283452)
		(end 373.787416 -260.305804)
		(width 0.088646)
		(layer "In11.Cu")
		(net "M_H_CPU0_SA_DQS_DN<9>")
	)
	(segment
		(start 374.924574 -260.11251)
		(end 374.91416 -260.106414)
		(width 0.088646)
		(layer "In11.Cu")
		(net "M_H_CPU0_SA_DQS_DN<9>")
	)
	(segment
		(start 415.776156 -274.632166)
		(end 415.776156 -274.63242)
		(width 0.18288)
		(layer "In11.Cu")
		(net "M_H_CPU0_SA_DQS_DN<9>")
	)
	(segment
		(start 420.441882 -274.240752)
		(end 420.189406 -273.988276)
		(width 0.18288)
		(layer "In11.Cu")
		(net "M_H_CPU0_SA_DQS_DN<9>")
	)
	(segment
		(start 417.60521 -274.395438)
		(end 417.06673 -274.502372)
		(width 0.18288)
		(layer "In11.Cu")
		(net "M_H_CPU0_SA_DQS_DN<9>")
	)
	(segment
		(start 419.01237 -273.988276)
		(end 417.703 -274.248626)
		(width 0.18288)
		(layer "In11.Cu")
		(net "M_H_CPU0_SA_DQS_DN<9>")
	)
	(segment
		(start 384.326892 -260.11505)
		(end 384.31216 -260.106414)
		(width 0.088646)
		(layer "In11.Cu")
		(net "M_H_CPU0_SA_DQS_DN<9>")
	)
	(segment
		(start 377.748546 -260.11505)
		(end 377.733814 -260.106414)
		(width 0.088646)
		(layer "In11.Cu")
		(net "M_H_CPU0_SA_DQS_DN<9>")
	)
	(segment
		(start 440.151774 -275.940774)
		(end 439.62955 -275.940774)
		(width 0.18288)
		(layer "In11.Cu")
		(net "M_H_CPU0_SA_DQS_DN<9>")
	)
	(segment
		(start 428.979076 -274.710398)
		(end 428.854616 -274.585938)
		(width 0.18288)
		(layer "In11.Cu")
		(net "M_H_CPU0_SA_DQS_DN<9>")
	)
	(segment
		(start 448.885564 -274.23618)
		(end 448.091052 -274.56638)
		(width 0.18288)
		(layer "In11.Cu")
		(net "M_H_CPU0_SA_DQS_DN<9>")
	)
	(segment
		(start 393.936728 -262.806434)
		(end 388.842504 -262.806434)
		(width 0.18288)
		(layer "In11.Cu")
		(net "M_H_CPU0_SA_DQS_DN<9>")
	)
	(segment
		(start 373.87022 -260.210046)
		(end 373.796814 -260.283452)
		(width 0.088646)
		(layer "In11.Cu")
		(net "M_H_CPU0_SA_DQS_DN<9>")
	)
	(segment
		(start 446.110868 -275.389594)
		(end 445.604392 -275.599906)
		(width 0.18288)
		(layer "In11.Cu")
		(net "M_H_CPU0_SA_DQS_DN<9>")
	)
	(segment
		(start 452.872602 -274.682712)
		(end 452.748142 -274.558252)
		(width 0.18288)
		(layer "In11.Cu")
		(net "M_H_CPU0_SA_DQS_DN<9>")
	)
	(segment
		(start 441.027312 -275.495258)
		(end 440.817762 -275.704808)
		(width 0.18288)
		(layer "In11.Cu")
		(net "M_H_CPU0_SA_DQS_DN<9>")
	)
	(segment
		(start 451.617842 -273.976592)
		(end 451.403974 -273.976592)
		(width 0.18288)
		(layer "In11.Cu")
		(net "M_H_CPU0_SA_DQS_DN<9>")
	)
	(segment
		(start 447.517012 -274.93976)
		(end 447.354198 -274.872704)
		(width 0.18288)
		(layer "In11.Cu")
		(net "M_H_CPU0_SA_DQS_DN<9>")
	)
	(segment
		(start 430.200816 -274.585938)
		(end 429.652176 -274.585938)
		(width 0.18288)
		(layer "In11.Cu")
		(net "M_H_CPU0_SA_DQS_DN<9>")
	)
	(segment
		(start 429.652176 -274.585938)
		(end 429.527716 -274.710398)
		(width 0.18288)
		(layer "In11.Cu")
		(net "M_H_CPU0_SA_DQS_DN<9>")
	)
	(segment
		(start 421.806116 -274.009104)
		(end 421.255698 -274.009104)
		(width 0.18288)
		(layer "In11.Cu")
		(net "M_H_CPU0_SA_DQS_DN<9>")
	)
	(segment
		(start 414.687004 -274.75688)
		(end 414.138364 -274.75688)
		(width 0.18288)
		(layer "In11.Cu")
		(net "M_H_CPU0_SA_DQS_DN<9>")
	)
	(segment
		(start 412.835852 -274.63242)
		(end 411.888686 -274.240498)
		(width 0.18288)
		(layer "In11.Cu")
		(net "M_H_CPU0_SA_DQS_DN<9>")
	)
	(segment
		(start 416.920426 -274.404582)
		(end 415.776156 -274.632166)
		(width 0.18288)
		(layer "In11.Cu")
		(net "M_H_CPU0_SA_DQS_DN<9>")
	)
	(segment
		(start 382.443228 -260.11251)
		(end 382.432814 -260.106414)
		(width 0.088646)
		(layer "In11.Cu")
		(net "M_H_CPU0_SA_DQS_DN<9>")
	)
	(arc
		(start 377.359418 -260.106414)
		(mid 377.085219 -260.182249)
		(end 376.808746 -260.11505)
		(width 0.088646)
		(layer "In11.Cu")
		(net "M_H_CPU0_SA_DQS_DN<9>")
	)
	(arc
		(start 376.419618 -260.106414)
		(mid 376.145419 -260.182249)
		(end 375.868946 -260.11505)
		(width 0.088646)
		(layer "In11.Cu")
		(net "M_H_CPU0_SA_DQS_DN<9>")
	)
	(arc
		(start 375.854214 -260.106414)
		(mid 375.667016 -260.056271)
		(end 375.479818 -260.106414)
		(width 0.088646)
		(layer "In11.Cu")
		(net "M_H_CPU0_SA_DQS_DN<9>")
	)
	(arc
		(start 384.877564 -260.106414)
		(mid 384.603365 -260.182249)
		(end 384.326892 -260.11505)
		(width 0.088646)
		(layer "In11.Cu")
		(net "M_H_CPU0_SA_DQS_DN<9>")
	)
	(arc
		(start 378.673614 -260.106414)
		(mid 378.486416 -260.056271)
		(end 378.299218 -260.106414)
		(width 0.088646)
		(layer "In11.Cu")
		(net "M_H_CPU0_SA_DQS_DN<9>")
	)
	(arc
		(start 378.299218 -260.106414)
		(mid 378.025019 -260.182249)
		(end 377.748546 -260.11505)
		(width 0.088646)
		(layer "In11.Cu")
		(net "M_H_CPU0_SA_DQS_DN<9>")
	)
	(arc
		(start 377.733814 -260.106414)
		(mid 377.546616 -260.056271)
		(end 377.359418 -260.106414)
		(width 0.088646)
		(layer "In11.Cu")
		(net "M_H_CPU0_SA_DQS_DN<9>")
	)
	(arc
		(start 382.997964 -260.106414)
		(mid 382.721405 -260.182157)
		(end 382.443228 -260.11251)
		(width 0.088646)
		(layer "In11.Cu")
		(net "M_H_CPU0_SA_DQS_DN<9>")
	)
	(arc
		(start 385.72186 -260.920484)
		(mid 385.519574 -260.721503)
		(end 385.439412 -260.449314)
		(width 0.088646)
		(layer "In11.Cu")
		(net "M_H_CPU0_SA_DQS_DN<9>")
	)
	(arc
		(start 384.31216 -260.106414)
		(mid 384.124962 -260.056271)
		(end 383.937764 -260.106414)
		(width 0.088646)
		(layer "In11.Cu")
		(net "M_H_CPU0_SA_DQS_DN<9>")
	)
	(arc
		(start 387.319266 -262.049768)
		(mid 387.128392 -261.731959)
		(end 386.757672 -261.734046)
		(width 0.088646)
		(layer "In11.Cu")
		(net "M_H_CPU0_SA_DQS_DN<9>")
	)
	(arc
		(start 380.553214 -260.106414)
		(mid 380.366016 -260.056271)
		(end 380.178818 -260.106414)
		(width 0.088646)
		(layer "In11.Cu")
		(net "M_H_CPU0_SA_DQS_DN<9>")
	)
	(arc
		(start 379.613414 -260.106414)
		(mid 379.426216 -260.056271)
		(end 379.239018 -260.106414)
		(width 0.088646)
		(layer "In11.Cu")
		(net "M_H_CPU0_SA_DQS_DN<9>")
	)
	(arc
		(start 386.757164 -261.7343)
		(mid 386.196188 -261.736831)
		(end 385.909312 -261.254748)
		(width 0.088646)
		(layer "In11.Cu")
		(net "M_H_CPU0_SA_DQS_DN<9>")
	)
	(arc
		(start 375.479818 -260.106414)
		(mid 375.203005 -260.182284)
		(end 374.924574 -260.11251)
		(width 0.088646)
		(layer "In11.Cu")
		(net "M_H_CPU0_SA_DQS_DN<9>")
	)
	(arc
		(start 387.884162 -262.623554)
		(mid 387.48842 -262.461766)
		(end 387.31952 -262.069072)
		(width 0.088646)
		(layer "In11.Cu")
		(net "M_H_CPU0_SA_DQS_DN<9>")
	)
	(arc
		(start 374.91416 -260.106414)
		(mid 374.726788 -260.056271)
		(end 374.53951 -260.106668)
		(width 0.088646)
		(layer "In11.Cu")
		(net "M_H_CPU0_SA_DQS_DN<9>")
	)
	(arc
		(start 376.794014 -260.106414)
		(mid 376.606816 -260.056271)
		(end 376.419618 -260.106414)
		(width 0.088646)
		(layer "In11.Cu")
		(net "M_H_CPU0_SA_DQS_DN<9>")
	)
	(arc
		(start 385.439412 -260.430772)
		(mid 385.391733 -260.247872)
		(end 385.26085 -260.111494)
		(width 0.088646)
		(layer "In11.Cu")
		(net "M_H_CPU0_SA_DQS_DN<9>")
	)
	(arc
		(start 379.239018 -260.106414)
		(mid 378.964819 -260.182249)
		(end 378.688346 -260.11505)
		(width 0.088646)
		(layer "In11.Cu")
		(net "M_H_CPU0_SA_DQS_DN<9>")
	)
	(arc
		(start 382.432814 -260.106414)
		(mid 382.245616 -260.056271)
		(end 382.058418 -260.106414)
		(width 0.088646)
		(layer "In11.Cu")
		(net "M_H_CPU0_SA_DQS_DN<9>")
	)
	(arc
		(start 385.909312 -261.244842)
		(mid 385.861633 -261.061942)
		(end 385.73075 -260.925564)
		(width 0.088646)
		(layer "In11.Cu")
		(net "M_H_CPU0_SA_DQS_DN<9>")
	)
	(arc
		(start 385.25196 -260.106414)
		(mid 385.064762 -260.056271)
		(end 384.877564 -260.106414)
		(width 0.088646)
		(layer "In11.Cu")
		(net "M_H_CPU0_SA_DQS_DN<9>")
	)
	(arc
		(start 382.058418 -260.106414)
		(mid 381.781605 -260.182284)
		(end 381.503174 -260.11251)
		(width 0.088646)
		(layer "In11.Cu")
		(net "M_H_CPU0_SA_DQS_DN<9>")
	)
	(arc
		(start 383.37236 -260.106414)
		(mid 383.185162 -260.056271)
		(end 382.997964 -260.106414)
		(width 0.088646)
		(layer "In11.Cu")
		(net "M_H_CPU0_SA_DQS_DN<9>")
	)
	(arc
		(start 383.937764 -260.106414)
		(mid 383.663565 -260.182249)
		(end 383.387092 -260.11505)
		(width 0.088646)
		(layer "In11.Cu")
		(net "M_H_CPU0_SA_DQS_DN<9>")
	)
	(arc
		(start 380.178818 -260.106414)
		(mid 379.904619 -260.182249)
		(end 379.628146 -260.11505)
		(width 0.088646)
		(layer "In11.Cu")
		(net "M_H_CPU0_SA_DQS_DN<9>")
	)
	(arc
		(start 381.49276 -260.106414)
		(mid 381.305562 -260.056271)
		(end 381.118364 -260.106414)
		(width 0.088646)
		(layer "In11.Cu")
		(net "M_H_CPU0_SA_DQS_DN<9>")
	)
	(arc
		(start 381.118364 -260.106414)
		(mid 380.841805 -260.182157)
		(end 380.563628 -260.11251)
		(width 0.088646)
		(layer "In11.Cu")
		(net "M_H_CPU0_SA_DQS_DN<9>")
	)
	(segment
		(start 462.110328 -283.76245)
		(end 461.664812 -283.316934)
		(width 0.20066)
		(layer "F.Cu")
		(net "M_H_CPU0_SA_DQS_DN<8>")
	)
	(segment
		(start 457.826364 -283.32049)
		(end 457.401422 -283.745432)
		(width 0.20066)
		(layer "F.Cu")
		(net "M_H_CPU0_SA_DQS_DN<8>")
	)
	(segment
		(start 461.174846 -283.316934)
		(end 460.889096 -283.602684)
		(width 0.20066)
		(layer "F.Cu")
		(net "M_H_CPU0_SA_DQS_DN<8>")
	)
	(segment
		(start 373.787162 -264.778236)
		(end 373.787162 -265.313922)
		(width 0.20066)
		(layer "F.Cu")
		(net "M_H_CPU0_SA_DQS_DN<8>")
	)
	(segment
		(start 458.543152 -283.597858)
		(end 458.538326 -283.597858)
		(width 0.101854)
		(layer "F.Cu")
		(net "M_H_CPU0_SA_DQS_DN<8>")
	)
	(segment
		(start 463.659982 -284.016704)
		(end 463.1563 -284.016704)
		(width 0.20066)
		(layer "F.Cu")
		(net "M_H_CPU0_SA_DQS_DN<8>")
	)
	(segment
		(start 461.664812 -283.316934)
		(end 461.174846 -283.316934)
		(width 0.20066)
		(layer "F.Cu")
		(net "M_H_CPU0_SA_DQS_DN<8>")
	)
	(segment
		(start 462.902046 -283.76245)
		(end 462.110328 -283.76245)
		(width 0.20066)
		(layer "F.Cu")
		(net "M_H_CPU0_SA_DQS_DN<8>")
	)
	(segment
		(start 457.948792 -283.32049)
		(end 457.826364 -283.32049)
		(width 0.20066)
		(layer "F.Cu")
		(net "M_H_CPU0_SA_DQS_DN<8>")
	)
	(segment
		(start 457.401422 -283.745432)
		(end 456.91806 -283.745432)
		(width 0.20066)
		(layer "F.Cu")
		(net "M_H_CPU0_SA_DQS_DN<8>")
	)
	(segment
		(start 460.559404 -283.591762)
		(end 458.549248 -283.591762)
		(width 0.1016)
		(layer "F.Cu")
		(net "M_H_CPU0_SA_DQS_DN<8>")
	)
	(segment
		(start 463.1563 -284.016704)
		(end 462.902046 -283.76245)
		(width 0.20066)
		(layer "F.Cu")
		(net "M_H_CPU0_SA_DQS_DN<8>")
	)
	(segment
		(start 458.22616 -283.597858)
		(end 457.948792 -283.32049)
		(width 0.20066)
		(layer "F.Cu")
		(net "M_H_CPU0_SA_DQS_DN<8>")
	)
	(segment
		(start 456.646788 -284.016704)
		(end 456.116182 -284.016704)
		(width 0.20066)
		(layer "F.Cu")
		(net "M_H_CPU0_SA_DQS_DN<8>")
	)
	(segment
		(start 460.570326 -283.602684)
		(end 460.559404 -283.591762)
		(width 0.1016)
		(layer "F.Cu")
		(net "M_H_CPU0_SA_DQS_DN<8>")
	)
	(segment
		(start 373.787162 -265.313922)
		(end 373.787416 -265.314176)
		(width 0.20066)
		(layer "F.Cu")
		(net "M_H_CPU0_SA_DQS_DN<8>")
	)
	(segment
		(start 458.549248 -283.591762)
		(end 458.543152 -283.597858)
		(width 0.1016)
		(layer "F.Cu")
		(net "M_H_CPU0_SA_DQS_DN<8>")
	)
	(segment
		(start 458.538326 -283.597858)
		(end 458.22616 -283.597858)
		(width 0.20066)
		(layer "F.Cu")
		(net "M_H_CPU0_SA_DQS_DN<8>")
	)
	(segment
		(start 455.011282 -284.016704)
		(end 456.116182 -284.016704)
		(width 0.20066)
		(layer "F.Cu")
		(net "M_H_CPU0_SA_DQS_DN<8>")
	)
	(segment
		(start 460.889096 -283.602684)
		(end 460.570326 -283.602684)
		(width 0.20066)
		(layer "F.Cu")
		(net "M_H_CPU0_SA_DQS_DN<8>")
	)
	(segment
		(start 456.91806 -283.745432)
		(end 456.646788 -284.016704)
		(width 0.20066)
		(layer "F.Cu")
		(net "M_H_CPU0_SA_DQS_DN<8>")
	)
	(segment
		(start 406.330658 -282.843732)
		(end 406.206198 -282.719272)
		(width 0.18288)
		(layer "In11.Cu")
		(net "M_H_CPU0_SA_DQS_DN<8>")
	)
	(segment
		(start 441.061856 -286.726122)
		(end 440.416442 -286.726122)
		(width 0.18288)
		(layer "In11.Cu")
		(net "M_H_CPU0_SA_DQS_DN<8>")
	)
	(segment
		(start 414.16351 -285.383732)
		(end 414.03905 -285.259272)
		(width 0.18288)
		(layer "In11.Cu")
		(net "M_H_CPU0_SA_DQS_DN<8>")
	)
	(segment
		(start 429.829722 -285.210758)
		(end 429.705262 -285.335218)
		(width 0.18288)
		(layer "In11.Cu")
		(net "M_H_CPU0_SA_DQS_DN<8>")
	)
	(segment
		(start 403.754336 -281.379422)
		(end 403.366224 -280.99131)
		(width 0.18288)
		(layer "In11.Cu")
		(net "M_H_CPU0_SA_DQS_DN<8>")
	)
	(segment
		(start 425.064174 -286.99079)
		(end 424.54195 -286.99079)
		(width 0.18288)
		(layer "In11.Cu")
		(net "M_H_CPU0_SA_DQS_DN<8>")
	)
	(segment
		(start 384.029712 -267.765784)
		(end 384.029712 -267.755878)
		(width 0.088646)
		(layer "In11.Cu")
		(net "M_H_CPU0_SA_DQS_DN<8>")
	)
	(segment
		(start 450.462142 -283.324046)
		(end 450.29882 -283.324046)
		(width 0.18288)
		(layer "In11.Cu")
		(net "M_H_CPU0_SA_DQS_DN<8>")
	)
	(segment
		(start 403.930358 -281.379422)
		(end 403.754336 -281.379422)
		(width 0.18288)
		(layer "In11.Cu")
		(net "M_H_CPU0_SA_DQS_DN<8>")
	)
	(segment
		(start 387.425946 -268.56563)
		(end 387.195314 -268.56563)
		(width 0.088646)
		(layer "In11.Cu")
		(net "M_H_CPU0_SA_DQS_DN<8>")
	)
	(segment
		(start 437.531256 -286.321754)
		(end 437.08574 -285.876238)
		(width 0.18288)
		(layer "In11.Cu")
		(net "M_H_CPU0_SA_DQS_DN<8>")
	)
	(segment
		(start 414.71215 -285.383732)
		(end 414.16351 -285.383732)
		(width 0.18288)
		(layer "In11.Cu")
		(net "M_H_CPU0_SA_DQS_DN<8>")
	)
	(segment
		(start 422.041066 -287.442656)
		(end 421.718486 -287.57626)
		(width 0.18288)
		(layer "In11.Cu")
		(net "M_H_CPU0_SA_DQS_DN<8>")
	)
	(segment
		(start 444.009526 -285.241746)
		(end 443.885066 -285.117286)
		(width 0.18288)
		(layer "In11.Cu")
		(net "M_H_CPU0_SA_DQS_DN<8>")
	)
	(segment
		(start 404.706328 -282.331414)
		(end 404.318216 -281.943302)
		(width 0.18288)
		(layer "In11.Cu")
		(net "M_H_CPU0_SA_DQS_DN<8>")
	)
	(segment
		(start 383.559812 -266.96035)
		(end 383.559812 -266.941808)
		(width 0.088646)
		(layer "In11.Cu")
		(net "M_H_CPU0_SA_DQS_DN<8>")
	)
	(segment
		(start 413.364426 -285.259272)
		(end 412.774892 -285.015432)
		(width 0.18288)
		(layer "In11.Cu")
		(net "M_H_CPU0_SA_DQS_DN<8>")
	)
	(segment
		(start 378.688346 -264.998454)
		(end 378.673614 -264.989818)
		(width 0.088646)
		(layer "In11.Cu")
		(net "M_H_CPU0_SA_DQS_DN<8>")
	)
	(segment
		(start 452.924418 -283.91612)
		(end 452.282306 -283.650182)
		(width 0.18288)
		(layer "In11.Cu")
		(net "M_H_CPU0_SA_DQS_DN<8>")
	)
	(segment
		(start 424.54195 -286.99079)
		(end 424.269154 -286.717994)
		(width 0.18288)
		(layer "In11.Cu")
		(net "M_H_CPU0_SA_DQS_DN<8>")
	)
	(segment
		(start 402.414232 -279.863296)
		(end 391.451592 -268.900656)
		(width 0.18288)
		(layer "In11.Cu")
		(net "M_H_CPU0_SA_DQS_DN<8>")
	)
	(segment
		(start 436.316374 -285.876238)
		(end 436.051706 -286.140906)
		(width 0.18288)
		(layer "In11.Cu")
		(net "M_H_CPU0_SA_DQS_DN<8>")
	)
	(segment
		(start 450.037454 -283.585412)
		(end 449.010532 -283.585412)
		(width 0.18288)
		(layer "In11.Cu")
		(net "M_H_CPU0_SA_DQS_DN<8>")
	)
	(segment
		(start 388.601204 -268.900656)
		(end 388.54126 -268.840712)
		(width 0.088646)
		(layer "In11.Cu")
		(net "M_H_CPU0_SA_DQS_DN<8>")
	)
	(segment
		(start 439.362342 -286.723582)
		(end 438.501028 -286.723582)
		(width 0.18288)
		(layer "In11.Cu")
		(net "M_H_CPU0_SA_DQS_DN<8>")
	)
	(segment
		(start 376.419364 -264.989818)
		(end 376.411998 -264.994136)
		(width 0.088646)
		(layer "In11.Cu")
		(net "M_H_CPU0_SA_DQS_DN<8>")
	)
	(segment
		(start 412.774892 -285.015432)
		(end 412.190184 -284.43047)
		(width 0.18288)
		(layer "In11.Cu")
		(net "M_H_CPU0_SA_DQS_DN<8>")
	)
	(segment
		(start 373.796814 -265.166856)
		(end 373.787416 -265.189208)
		(width 0.088646)
		(layer "In11.Cu")
		(net "M_H_CPU0_SA_DQS_DN<8>")
	)
	(segment
		(start 429.156622 -285.335218)
		(end 429.032162 -285.210758)
		(width 0.18288)
		(layer "In11.Cu")
		(net "M_H_CPU0_SA_DQS_DN<8>")
	)
	(segment
		(start 375.484136 -264.987024)
		(end 375.479564 -264.989818)
		(width 0.088646)
		(layer "In11.Cu")
		(net "M_H_CPU0_SA_DQS_DN<8>")
	)
	(segment
		(start 446.138554 -285.117286)
		(end 444.682626 -285.117286)
		(width 0.18288)
		(layer "In11.Cu")
		(net "M_H_CPU0_SA_DQS_DN<8>")
	)
	(segment
		(start 412.190184 -284.43047)
		(end 411.379162 -284.43047)
		(width 0.18288)
		(layer "In11.Cu")
		(net "M_H_CPU0_SA_DQS_DN<8>")
	)
	(segment
		(start 377.748546 -264.998454)
		(end 377.733814 -264.989818)
		(width 0.088646)
		(layer "In11.Cu")
		(net "M_H_CPU0_SA_DQS_DN<8>")
	)
	(segment
		(start 424.269154 -286.717994)
		(end 423.218864 -286.717994)
		(width 0.18288)
		(layer "In11.Cu")
		(net "M_H_CPU0_SA_DQS_DN<8>")
	)
	(segment
		(start 406.879298 -282.843732)
		(end 406.330658 -282.843732)
		(width 0.18288)
		(layer "In11.Cu")
		(net "M_H_CPU0_SA_DQS_DN<8>")
	)
	(segment
		(start 420.441882 -287.840928)
		(end 420.20363 -287.602676)
		(width 0.18288)
		(layer "In11.Cu")
		(net "M_H_CPU0_SA_DQS_DN<8>")
	)
	(segment
		(start 381.503174 -264.995914)
		(end 381.49276 -264.989818)
		(width 0.088646)
		(layer "In11.Cu")
		(net "M_H_CPU0_SA_DQS_DN<8>")
	)
	(segment
		(start 420.964106 -287.840928)
		(end 420.441882 -287.840928)
		(width 0.18288)
		(layer "In11.Cu")
		(net "M_H_CPU0_SA_DQS_DN<8>")
	)
	(segment
		(start 426.852588 -285.796736)
		(end 425.923202 -286.726122)
		(width 0.18288)
		(layer "In11.Cu")
		(net "M_H_CPU0_SA_DQS_DN<8>")
	)
	(segment
		(start 374.544336 -264.987024)
		(end 374.532398 -264.994136)
		(width 0.088646)
		(layer "In11.Cu")
		(net "M_H_CPU0_SA_DQS_DN<8>")
	)
	(segment
		(start 402.978366 -280.42743)
		(end 402.802344 -280.42743)
		(width 0.18288)
		(layer "In11.Cu")
		(net "M_H_CPU0_SA_DQS_DN<8>")
	)
	(segment
		(start 418.54882 -286.988758)
		(end 417.594796 -286.034734)
		(width 0.18288)
		(layer "In11.Cu")
		(net "M_H_CPU0_SA_DQS_DN<8>")
	)
	(segment
		(start 444.558166 -285.241746)
		(end 444.009526 -285.241746)
		(width 0.18288)
		(layer "In11.Cu")
		(net "M_H_CPU0_SA_DQS_DN<8>")
	)
	(segment
		(start 432.247802 -285.896812)
		(end 430.591468 -285.210758)
		(width 0.18288)
		(layer "In11.Cu")
		(net "M_H_CPU0_SA_DQS_DN<8>")
	)
	(segment
		(start 417.594796 -286.034734)
		(end 415.722054 -285.259272)
		(width 0.18288)
		(layer "In11.Cu")
		(net "M_H_CPU0_SA_DQS_DN<8>")
	)
	(segment
		(start 388.54126 -268.840712)
		(end 387.701028 -268.840712)
		(width 0.088646)
		(layer "In11.Cu")
		(net "M_H_CPU0_SA_DQS_DN<8>")
	)
	(segment
		(start 450.71665 -283.578554)
		(end 450.462142 -283.324046)
		(width 0.18288)
		(layer "In11.Cu")
		(net "M_H_CPU0_SA_DQS_DN<8>")
	)
	(segment
		(start 440.151774 -286.99079)
		(end 439.62955 -286.99079)
		(width 0.18288)
		(layer "In11.Cu")
		(net "M_H_CPU0_SA_DQS_DN<8>")
	)
	(segment
		(start 446.875408 -284.380432)
		(end 446.138554 -285.117286)
		(width 0.18288)
		(layer "In11.Cu")
		(net "M_H_CPU0_SA_DQS_DN<8>")
	)
	(segment
		(start 450.788786 -283.578554)
		(end 450.71665 -283.578554)
		(width 0.18288)
		(layer "In11.Cu")
		(net "M_H_CPU0_SA_DQS_DN<8>")
	)
	(segment
		(start 403.366224 -280.815288)
		(end 402.978366 -280.42743)
		(width 0.18288)
		(layer "In11.Cu")
		(net "M_H_CPU0_SA_DQS_DN<8>")
	)
	(segment
		(start 408.851608 -283.425138)
		(end 408.851608 -283.249116)
		(width 0.18288)
		(layer "In11.Cu")
		(net "M_H_CPU0_SA_DQS_DN<8>")
	)
	(segment
		(start 433.856638 -286.021272)
		(end 433.307998 -286.021272)
		(width 0.18288)
		(layer "In11.Cu")
		(net "M_H_CPU0_SA_DQS_DN<8>")
	)
	(segment
		(start 379.628146 -264.998454)
		(end 379.613414 -264.989818)
		(width 0.088646)
		(layer "In11.Cu")
		(net "M_H_CPU0_SA_DQS_DN<8>")
	)
	(segment
		(start 454.750424 -283.755846)
		(end 453.692006 -283.755846)
		(width 0.18288)
		(layer "In11.Cu")
		(net "M_H_CPU0_SA_DQS_DN<8>")
	)
	(segment
		(start 437.08574 -285.876238)
		(end 436.316374 -285.876238)
		(width 0.18288)
		(layer "In11.Cu")
		(net "M_H_CPU0_SA_DQS_DN<8>")
	)
	(segment
		(start 451.139052 -283.578554)
		(end 451.022466 -283.578554)
		(width 0.18288)
		(layer "In11.Cu")
		(net "M_H_CPU0_SA_DQS_DN<8>")
	)
	(segment
		(start 438.501028 -286.723582)
		(end 437.531256 -286.321754)
		(width 0.18288)
		(layer "In11.Cu")
		(net "M_H_CPU0_SA_DQS_DN<8>")
	)
	(segment
		(start 387.195314 -268.56563)
		(end 386.965698 -268.33576)
		(width 0.088646)
		(layer "In11.Cu")
		(net "M_H_CPU0_SA_DQS_DN<8>")
	)
	(segment
		(start 443.885066 -285.117286)
		(end 443.336426 -285.117286)
		(width 0.18288)
		(layer "In11.Cu")
		(net "M_H_CPU0_SA_DQS_DN<8>")
	)
	(segment
		(start 425.328842 -286.726122)
		(end 425.064174 -286.99079)
		(width 0.18288)
		(layer "In11.Cu")
		(net "M_H_CPU0_SA_DQS_DN<8>")
	)
	(segment
		(start 451.938136 -283.306012)
		(end 451.411594 -283.306012)
		(width 0.18288)
		(layer "In11.Cu")
		(net "M_H_CPU0_SA_DQS_DN<8>")
	)
	(segment
		(start 430.591468 -285.210758)
		(end 429.829722 -285.210758)
		(width 0.18288)
		(layer "In11.Cu")
		(net "M_H_CPU0_SA_DQS_DN<8>")
	)
	(segment
		(start 375.479564 -264.989818)
		(end 375.472198 -264.994136)
		(width 0.088646)
		(layer "In11.Cu")
		(net "M_H_CPU0_SA_DQS_DN<8>")
	)
	(segment
		(start 410.032962 -284.43047)
		(end 409.415996 -283.813504)
		(width 0.18288)
		(layer "In11.Cu")
		(net "M_H_CPU0_SA_DQS_DN<8>")
	)
	(segment
		(start 410.581602 -284.43047)
		(end 410.032962 -284.43047)
		(width 0.18288)
		(layer "In11.Cu")
		(net "M_H_CPU0_SA_DQS_DN<8>")
	)
	(segment
		(start 415.722054 -285.259272)
		(end 414.83661 -285.259272)
		(width 0.18288)
		(layer "In11.Cu")
		(net "M_H_CPU0_SA_DQS_DN<8>")
	)
	(segment
		(start 402.802344 -280.42743)
		(end 402.414232 -280.039318)
		(width 0.18288)
		(layer "In11.Cu")
		(net "M_H_CPU0_SA_DQS_DN<8>")
	)
	(segment
		(start 374.221502 -265.077702)
		(end 373.892318 -265.084052)
		(width 0.088646)
		(layer "In11.Cu")
		(net "M_H_CPU0_SA_DQS_DN<8>")
	)
	(segment
		(start 404.318216 -281.943302)
		(end 404.318216 -281.76728)
		(width 0.18288)
		(layer "In11.Cu")
		(net "M_H_CPU0_SA_DQS_DN<8>")
	)
	(segment
		(start 376.423936 -264.987024)
		(end 376.419364 -264.989818)
		(width 0.088646)
		(layer "In11.Cu")
		(net "M_H_CPU0_SA_DQS_DN<8>")
	)
	(segment
		(start 409.415996 -283.813504)
		(end 409.239974 -283.813504)
		(width 0.18288)
		(layer "In11.Cu")
		(net "M_H_CPU0_SA_DQS_DN<8>")
	)
	(segment
		(start 387.701028 -268.840712)
		(end 387.425946 -268.56563)
		(width 0.088646)
		(layer "In11.Cu")
		(net "M_H_CPU0_SA_DQS_DN<8>")
	)
	(segment
		(start 451.022466 -283.578554)
		(end 450.788786 -283.578554)
		(width 0.16002)
		(layer "In11.Cu")
		(net "M_H_CPU0_SA_DQS_DN<8>")
	)
	(segment
		(start 435.529482 -286.140906)
		(end 435.285388 -285.896812)
		(width 0.18288)
		(layer "In11.Cu")
		(net "M_H_CPU0_SA_DQS_DN<8>")
	)
	(segment
		(start 411.379162 -284.43047)
		(end 411.254702 -284.55493)
		(width 0.18288)
		(layer "In11.Cu")
		(net "M_H_CPU0_SA_DQS_DN<8>")
	)
	(segment
		(start 453.30491 -283.91612)
		(end 452.924418 -283.91612)
		(width 0.18288)
		(layer "In11.Cu")
		(net "M_H_CPU0_SA_DQS_DN<8>")
	)
	(segment
		(start 435.285388 -285.896812)
		(end 433.981098 -285.896812)
		(width 0.18288)
		(layer "In11.Cu")
		(net "M_H_CPU0_SA_DQS_DN<8>")
	)
	(segment
		(start 443.336426 -285.117286)
		(end 442.537596 -285.916116)
		(width 0.18288)
		(layer "In11.Cu")
		(net "M_H_CPU0_SA_DQS_DN<8>")
	)
	(segment
		(start 448.215512 -284.380432)
		(end 446.875408 -284.380432)
		(width 0.18288)
		(layer "In11.Cu")
		(net "M_H_CPU0_SA_DQS_DN<8>")
	)
	(segment
		(start 421.228774 -287.57626)
		(end 420.964106 -287.840928)
		(width 0.18288)
		(layer "In11.Cu")
		(net "M_H_CPU0_SA_DQS_DN<8>")
	)
	(segment
		(start 382.434338 -264.99058)
		(end 382.432814 -264.989818)
		(width 0.088646)
		(layer "In11.Cu")
		(net "M_H_CPU0_SA_DQS_DN<8>")
	)
	(segment
		(start 442.537596 -285.916116)
		(end 441.400946 -286.387032)
		(width 0.18288)
		(layer "In11.Cu")
		(net "M_H_CPU0_SA_DQS_DN<8>")
	)
	(segment
		(start 382.620266 -265.336274)
		(end 382.620266 -265.314176)
		(width 0.088646)
		(layer "In11.Cu")
		(net "M_H_CPU0_SA_DQS_DN<8>")
	)
	(segment
		(start 407.003758 -282.719272)
		(end 406.879298 -282.843732)
		(width 0.18288)
		(layer "In11.Cu")
		(net "M_H_CPU0_SA_DQS_DN<8>")
	)
	(segment
		(start 419.776656 -287.602676)
		(end 418.54882 -286.988758)
		(width 0.18288)
		(layer "In11.Cu")
		(net "M_H_CPU0_SA_DQS_DN<8>")
	)
	(segment
		(start 381.118364 -264.989818)
		(end 381.10795 -264.995914)
		(width 0.088646)
		(layer "In11.Cu")
		(net "M_H_CPU0_SA_DQS_DN<8>")
	)
	(segment
		(start 455.011282 -284.016704)
		(end 454.750424 -283.755846)
		(width 0.18288)
		(layer "In11.Cu")
		(net "M_H_CPU0_SA_DQS_DN<8>")
	)
	(segment
		(start 403.366224 -280.99131)
		(end 403.366224 -280.815288)
		(width 0.18288)
		(layer "In11.Cu")
		(net "M_H_CPU0_SA_DQS_DN<8>")
	)
	(segment
		(start 414.03905 -285.259272)
		(end 413.364426 -285.259272)
		(width 0.18288)
		(layer "In11.Cu")
		(net "M_H_CPU0_SA_DQS_DN<8>")
	)
	(segment
		(start 428.267114 -285.210758)
		(end 426.852588 -285.796736)
		(width 0.18288)
		(layer "In11.Cu")
		(net "M_H_CPU0_SA_DQS_DN<8>")
	)
	(segment
		(start 439.62955 -286.99079)
		(end 439.362342 -286.723582)
		(width 0.18288)
		(layer "In11.Cu")
		(net "M_H_CPU0_SA_DQS_DN<8>")
	)
	(segment
		(start 436.051706 -286.140906)
		(end 435.529482 -286.140906)
		(width 0.18288)
		(layer "In11.Cu")
		(net "M_H_CPU0_SA_DQS_DN<8>")
	)
	(segment
		(start 405.270208 -282.719272)
		(end 404.88235 -282.331414)
		(width 0.18288)
		(layer "In11.Cu")
		(net "M_H_CPU0_SA_DQS_DN<8>")
	)
	(segment
		(start 410.706062 -284.55493)
		(end 410.581602 -284.43047)
		(width 0.18288)
		(layer "In11.Cu")
		(net "M_H_CPU0_SA_DQS_DN<8>")
	)
	(segment
		(start 408.321764 -282.719272)
		(end 407.003758 -282.719272)
		(width 0.18288)
		(layer "In11.Cu")
		(net "M_H_CPU0_SA_DQS_DN<8>")
	)
	(segment
		(start 444.682626 -285.117286)
		(end 444.558166 -285.241746)
		(width 0.18288)
		(layer "In11.Cu")
		(net "M_H_CPU0_SA_DQS_DN<8>")
	)
	(segment
		(start 440.416442 -286.726122)
		(end 440.151774 -286.99079)
		(width 0.18288)
		(layer "In11.Cu")
		(net "M_H_CPU0_SA_DQS_DN<8>")
	)
	(segment
		(start 453.692006 -283.755846)
		(end 453.30491 -283.91612)
		(width 0.18288)
		(layer "In11.Cu")
		(net "M_H_CPU0_SA_DQS_DN<8>")
	)
	(segment
		(start 377.359164 -264.989818)
		(end 377.351798 -264.994136)
		(width 0.088646)
		(layer "In11.Cu")
		(net "M_H_CPU0_SA_DQS_DN<8>")
	)
	(segment
		(start 406.206198 -282.719272)
		(end 405.270208 -282.719272)
		(width 0.18288)
		(layer "In11.Cu")
		(net "M_H_CPU0_SA_DQS_DN<8>")
	)
	(segment
		(start 391.451592 -268.900656)
		(end 388.601204 -268.900656)
		(width 0.18288)
		(layer "In11.Cu")
		(net "M_H_CPU0_SA_DQS_DN<8>")
	)
	(segment
		(start 423.218864 -286.717994)
		(end 422.444418 -287.039304)
		(width 0.18288)
		(layer "In11.Cu")
		(net "M_H_CPU0_SA_DQS_DN<8>")
	)
	(segment
		(start 441.400946 -286.387032)
		(end 441.061856 -286.726122)
		(width 0.18288)
		(layer "In11.Cu")
		(net "M_H_CPU0_SA_DQS_DN<8>")
	)
	(segment
		(start 414.83661 -285.259272)
		(end 414.71215 -285.383732)
		(width 0.18288)
		(layer "In11.Cu")
		(net "M_H_CPU0_SA_DQS_DN<8>")
	)
	(segment
		(start 411.254702 -284.55493)
		(end 410.706062 -284.55493)
		(width 0.18288)
		(layer "In11.Cu")
		(net "M_H_CPU0_SA_DQS_DN<8>")
	)
	(segment
		(start 373.787416 -265.189208)
		(end 373.787416 -265.314176)
		(width 0.088646)
		(layer "In11.Cu")
		(net "M_H_CPU0_SA_DQS_DN<8>")
	)
	(segment
		(start 422.444418 -287.039304)
		(end 422.041066 -287.442656)
		(width 0.18288)
		(layer "In11.Cu")
		(net "M_H_CPU0_SA_DQS_DN<8>")
	)
	(segment
		(start 402.414232 -280.039318)
		(end 402.414232 -279.863296)
		(width 0.18288)
		(layer "In11.Cu")
		(net "M_H_CPU0_SA_DQS_DN<8>")
	)
	(segment
		(start 383.089912 -266.128246)
		(end 383.089912 -266.119864)
		(width 0.088646)
		(layer "In11.Cu")
		(net "M_H_CPU0_SA_DQS_DN<8>")
	)
	(segment
		(start 451.411594 -283.306012)
		(end 451.139052 -283.578554)
		(width 0.18288)
		(layer "In11.Cu")
		(net "M_H_CPU0_SA_DQS_DN<8>")
	)
	(segment
		(start 449.010532 -283.585412)
		(end 448.215512 -284.380432)
		(width 0.18288)
		(layer "In11.Cu")
		(net "M_H_CPU0_SA_DQS_DN<8>")
	)
	(segment
		(start 404.88235 -282.331414)
		(end 404.706328 -282.331414)
		(width 0.18288)
		(layer "In11.Cu")
		(net "M_H_CPU0_SA_DQS_DN<8>")
	)
	(segment
		(start 421.718486 -287.57626)
		(end 421.228774 -287.57626)
		(width 0.18288)
		(layer "In11.Cu")
		(net "M_H_CPU0_SA_DQS_DN<8>")
	)
	(segment
		(start 433.183538 -285.896812)
		(end 432.247802 -285.896812)
		(width 0.18288)
		(layer "In11.Cu")
		(net "M_H_CPU0_SA_DQS_DN<8>")
	)
	(segment
		(start 382.91135 -265.808968)
		(end 382.90246 -265.803888)
		(width 0.088646)
		(layer "In11.Cu")
		(net "M_H_CPU0_SA_DQS_DN<8>")
	)
	(segment
		(start 383.380488 -266.622276)
		(end 383.366518 -266.614148)
		(width 0.088646)
		(layer "In11.Cu")
		(net "M_H_CPU0_SA_DQS_DN<8>")
	)
	(segment
		(start 433.307998 -286.021272)
		(end 433.183538 -285.896812)
		(width 0.18288)
		(layer "In11.Cu")
		(net "M_H_CPU0_SA_DQS_DN<8>")
	)
	(segment
		(start 409.239974 -283.813504)
		(end 408.851608 -283.425138)
		(width 0.18288)
		(layer "In11.Cu")
		(net "M_H_CPU0_SA_DQS_DN<8>")
	)
	(segment
		(start 429.705262 -285.335218)
		(end 429.156622 -285.335218)
		(width 0.18288)
		(layer "In11.Cu")
		(net "M_H_CPU0_SA_DQS_DN<8>")
	)
	(segment
		(start 386.965698 -268.33576)
		(end 386.529326 -268.33576)
		(width 0.088646)
		(layer "In11.Cu")
		(net "M_H_CPU0_SA_DQS_DN<8>")
	)
	(segment
		(start 425.923202 -286.726122)
		(end 425.328842 -286.726122)
		(width 0.18288)
		(layer "In11.Cu")
		(net "M_H_CPU0_SA_DQS_DN<8>")
	)
	(segment
		(start 382.441704 -264.994898)
		(end 382.434338 -264.99058)
		(width 0.088646)
		(layer "In11.Cu")
		(net "M_H_CPU0_SA_DQS_DN<8>")
	)
	(segment
		(start 433.981098 -285.896812)
		(end 433.856638 -286.021272)
		(width 0.18288)
		(layer "In11.Cu")
		(net "M_H_CPU0_SA_DQS_DN<8>")
	)
	(segment
		(start 377.363736 -264.987024)
		(end 377.359164 -264.989818)
		(width 0.088646)
		(layer "In11.Cu")
		(net "M_H_CPU0_SA_DQS_DN<8>")
	)
	(segment
		(start 429.032162 -285.210758)
		(end 428.267114 -285.210758)
		(width 0.18288)
		(layer "In11.Cu")
		(net "M_H_CPU0_SA_DQS_DN<8>")
	)
	(segment
		(start 383.089912 -266.119864)
		(end 383.089658 -266.113514)
		(width 0.088646)
		(layer "In11.Cu")
		(net "M_H_CPU0_SA_DQS_DN<8>")
	)
	(segment
		(start 404.318216 -281.76728)
		(end 403.930358 -281.379422)
		(width 0.18288)
		(layer "In11.Cu")
		(net "M_H_CPU0_SA_DQS_DN<8>")
	)
	(segment
		(start 408.851608 -283.249116)
		(end 408.321764 -282.719272)
		(width 0.18288)
		(layer "In11.Cu")
		(net "M_H_CPU0_SA_DQS_DN<8>")
	)
	(segment
		(start 383.85115 -267.4366)
		(end 383.84226 -267.43152)
		(width 0.088646)
		(layer "In11.Cu")
		(net "M_H_CPU0_SA_DQS_DN<8>")
	)
	(segment
		(start 452.282306 -283.650182)
		(end 451.938136 -283.306012)
		(width 0.18288)
		(layer "In11.Cu")
		(net "M_H_CPU0_SA_DQS_DN<8>")
	)
	(segment
		(start 420.20363 -287.602676)
		(end 419.776656 -287.602676)
		(width 0.18288)
		(layer "In11.Cu")
		(net "M_H_CPU0_SA_DQS_DN<8>")
	)
	(segment
		(start 450.29882 -283.324046)
		(end 450.037454 -283.585412)
		(width 0.18288)
		(layer "In11.Cu")
		(net "M_H_CPU0_SA_DQS_DN<8>")
	)
	(segment
		(start 373.87022 -265.09345)
		(end 373.796814 -265.166856)
		(width 0.088646)
		(layer "In11.Cu")
		(net "M_H_CPU0_SA_DQS_DN<8>")
	)
	(arc
		(start 381.49276 -264.989818)
		(mid 381.305562 -264.939675)
		(end 381.118364 -264.989818)
		(width 0.088646)
		(layer "In11.Cu")
		(net "M_H_CPU0_SA_DQS_DN<8>")
	)
	(arc
		(start 386.529326 -268.33576)
		(mid 386.399927 -268.323293)
		(end 386.275326 -268.28623)
		(width 0.088646)
		(layer "In11.Cu")
		(net "M_H_CPU0_SA_DQS_DN<8>")
	)
	(arc
		(start 380.178818 -264.989818)
		(mid 379.904619 -265.065653)
		(end 379.628146 -264.998454)
		(width 0.088646)
		(layer "In11.Cu")
		(net "M_H_CPU0_SA_DQS_DN<8>")
	)
	(arc
		(start 380.553214 -264.989818)
		(mid 380.366016 -264.939675)
		(end 380.178818 -264.989818)
		(width 0.088646)
		(layer "In11.Cu")
		(net "M_H_CPU0_SA_DQS_DN<8>")
	)
	(arc
		(start 377.733814 -264.989818)
		(mid 377.54915 -264.939558)
		(end 377.363736 -264.987024)
		(width 0.088646)
		(layer "In11.Cu")
		(net "M_H_CPU0_SA_DQS_DN<8>")
	)
	(arc
		(start 385.25196 -268.245336)
		(mid 385.064762 -268.195193)
		(end 384.877564 -268.245336)
		(width 0.088646)
		(layer "In11.Cu")
		(net "M_H_CPU0_SA_DQS_DN<8>")
	)
	(arc
		(start 379.613414 -264.989818)
		(mid 379.426216 -264.939675)
		(end 379.239018 -264.989818)
		(width 0.088646)
		(layer "In11.Cu")
		(net "M_H_CPU0_SA_DQS_DN<8>")
	)
	(arc
		(start 385.817364 -268.245336)
		(mid 385.534662 -268.321112)
		(end 385.25196 -268.245336)
		(width 0.088646)
		(layer "In11.Cu")
		(net "M_H_CPU0_SA_DQS_DN<8>")
	)
	(arc
		(start 375.472198 -264.994136)
		(mid 375.192847 -265.065574)
		(end 374.914668 -264.989818)
		(width 0.088646)
		(layer "In11.Cu")
		(net "M_H_CPU0_SA_DQS_DN<8>")
	)
	(arc
		(start 375.854214 -264.989818)
		(mid 375.66955 -264.939558)
		(end 375.484136 -264.987024)
		(width 0.088646)
		(layer "In11.Cu")
		(net "M_H_CPU0_SA_DQS_DN<8>")
	)
	(arc
		(start 383.84226 -267.43152)
		(mid 383.639974 -267.232539)
		(end 383.559812 -266.96035)
		(width 0.088646)
		(layer "In11.Cu")
		(net "M_H_CPU0_SA_DQS_DN<8>")
	)
	(arc
		(start 376.794014 -264.989818)
		(mid 376.60935 -264.939558)
		(end 376.423936 -264.987024)
		(width 0.088646)
		(layer "In11.Cu")
		(net "M_H_CPU0_SA_DQS_DN<8>")
	)
	(arc
		(start 377.351798 -264.994136)
		(mid 377.072337 -265.065573)
		(end 376.794014 -264.989818)
		(width 0.088646)
		(layer "In11.Cu")
		(net "M_H_CPU0_SA_DQS_DN<8>")
	)
	(arc
		(start 382.90246 -265.803888)
		(mid 382.701178 -265.606401)
		(end 382.620266 -265.336274)
		(width 0.088646)
		(layer "In11.Cu")
		(net "M_H_CPU0_SA_DQS_DN<8>")
	)
	(arc
		(start 373.892318 -265.084052)
		(mid 373.880366 -265.086631)
		(end 373.87022 -265.09345)
		(width 0.088646)
		(layer "In11.Cu")
		(net "M_H_CPU0_SA_DQS_DN<8>")
	)
	(arc
		(start 382.432814 -264.989818)
		(mid 382.245616 -264.939675)
		(end 382.058418 -264.989818)
		(width 0.088646)
		(layer "In11.Cu")
		(net "M_H_CPU0_SA_DQS_DN<8>")
	)
	(arc
		(start 378.673614 -264.989818)
		(mid 378.486416 -264.939675)
		(end 378.299218 -264.989818)
		(width 0.088646)
		(layer "In11.Cu")
		(net "M_H_CPU0_SA_DQS_DN<8>")
	)
	(arc
		(start 379.239018 -264.989818)
		(mid 378.964819 -265.065653)
		(end 378.688346 -264.998454)
		(width 0.088646)
		(layer "In11.Cu")
		(net "M_H_CPU0_SA_DQS_DN<8>")
	)
	(arc
		(start 374.914668 -264.989818)
		(mid 374.729861 -264.939432)
		(end 374.544336 -264.987024)
		(width 0.088646)
		(layer "In11.Cu")
		(net "M_H_CPU0_SA_DQS_DN<8>")
	)
	(arc
		(start 384.877564 -268.245336)
		(mid 384.316588 -268.247867)
		(end 384.029712 -267.765784)
		(width 0.088646)
		(layer "In11.Cu")
		(net "M_H_CPU0_SA_DQS_DN<8>")
	)
	(arc
		(start 386.275326 -268.28623)
		(mid 386.232835 -268.267229)
		(end 386.19176 -268.245336)
		(width 0.088646)
		(layer "In11.Cu")
		(net "M_H_CPU0_SA_DQS_DN<8>")
	)
	(arc
		(start 383.559812 -266.941808)
		(mid 383.511921 -266.758596)
		(end 383.380488 -266.622276)
		(width 0.088646)
		(layer "In11.Cu")
		(net "M_H_CPU0_SA_DQS_DN<8>")
	)
	(arc
		(start 381.10795 -264.995914)
		(mid 380.829772 -265.065637)
		(end 380.553214 -264.989818)
		(width 0.088646)
		(layer "In11.Cu")
		(net "M_H_CPU0_SA_DQS_DN<8>")
	)
	(arc
		(start 376.411998 -264.994136)
		(mid 376.132537 -265.065573)
		(end 375.854214 -264.989818)
		(width 0.088646)
		(layer "In11.Cu")
		(net "M_H_CPU0_SA_DQS_DN<8>")
	)
	(arc
		(start 378.299218 -264.989818)
		(mid 378.025019 -265.065653)
		(end 377.748546 -264.998454)
		(width 0.088646)
		(layer "In11.Cu")
		(net "M_H_CPU0_SA_DQS_DN<8>")
	)
	(arc
		(start 383.089658 -266.113514)
		(mid 383.038604 -265.938934)
		(end 382.91135 -265.808968)
		(width 0.088646)
		(layer "In11.Cu")
		(net "M_H_CPU0_SA_DQS_DN<8>")
	)
	(arc
		(start 382.058418 -264.989818)
		(mid 381.781605 -265.065688)
		(end 381.503174 -264.995914)
		(width 0.088646)
		(layer "In11.Cu")
		(net "M_H_CPU0_SA_DQS_DN<8>")
	)
	(arc
		(start 374.529096 -264.995914)
		(mid 374.380249 -265.055424)
		(end 374.221502 -265.077702)
		(width 0.088646)
		(layer "In11.Cu")
		(net "M_H_CPU0_SA_DQS_DN<8>")
	)
	(arc
		(start 382.620266 -265.314176)
		(mid 382.572587 -265.131276)
		(end 382.441704 -264.994898)
		(width 0.088646)
		(layer "In11.Cu")
		(net "M_H_CPU0_SA_DQS_DN<8>")
	)
	(arc
		(start 374.532398 -264.994136)
		(mid 374.530749 -264.995028)
		(end 374.529096 -264.995914)
		(width 0.088646)
		(layer "In11.Cu")
		(net "M_H_CPU0_SA_DQS_DN<8>")
	)
	(arc
		(start 383.366518 -266.614148)
		(mid 383.163931 -266.407797)
		(end 383.089912 -266.128246)
		(width 0.088646)
		(layer "In11.Cu")
		(net "M_H_CPU0_SA_DQS_DN<8>")
	)
	(arc
		(start 386.19176 -268.245336)
		(mid 386.004562 -268.195193)
		(end 385.817364 -268.245336)
		(width 0.088646)
		(layer "In11.Cu")
		(net "M_H_CPU0_SA_DQS_DN<8>")
	)
	(arc
		(start 384.029712 -267.755878)
		(mid 383.982033 -267.572978)
		(end 383.85115 -267.4366)
		(width 0.088646)
		(layer "In11.Cu")
		(net "M_H_CPU0_SA_DQS_DN<8>")
	)
	(segment
		(start 457.948792 -292.670484)
		(end 457.826364 -292.670484)
		(width 0.20066)
		(layer "F.Cu")
		(net "M_H_CPU0_SA_DQS_DN<7>")
	)
	(segment
		(start 373.787162 -269.66164)
		(end 373.787416 -270.167862)
		(width 0.20066)
		(layer "F.Cu")
		(net "M_H_CPU0_SA_DQS_DN<7>")
	)
	(segment
		(start 456.91806 -293.095426)
		(end 456.646788 -293.366698)
		(width 0.20066)
		(layer "F.Cu")
		(net "M_H_CPU0_SA_DQS_DN<7>")
	)
	(segment
		(start 462.902046 -293.112444)
		(end 462.110328 -293.112444)
		(width 0.20066)
		(layer "F.Cu")
		(net "M_H_CPU0_SA_DQS_DN<7>")
	)
	(segment
		(start 458.538326 -292.947852)
		(end 458.22616 -292.947852)
		(width 0.20066)
		(layer "F.Cu")
		(net "M_H_CPU0_SA_DQS_DN<7>")
	)
	(segment
		(start 463.1563 -293.366698)
		(end 462.902046 -293.112444)
		(width 0.20066)
		(layer "F.Cu")
		(net "M_H_CPU0_SA_DQS_DN<7>")
	)
	(segment
		(start 460.889096 -292.952678)
		(end 460.570326 -292.952678)
		(width 0.20066)
		(layer "F.Cu")
		(net "M_H_CPU0_SA_DQS_DN<7>")
	)
	(segment
		(start 456.646788 -293.366698)
		(end 456.116182 -293.366698)
		(width 0.20066)
		(layer "F.Cu")
		(net "M_H_CPU0_SA_DQS_DN<7>")
	)
	(segment
		(start 455.011282 -293.366698)
		(end 456.116182 -293.366698)
		(width 0.20066)
		(layer "F.Cu")
		(net "M_H_CPU0_SA_DQS_DN<7>")
	)
	(segment
		(start 373.787416 -270.167862)
		(end 373.787416 -270.19758)
		(width 0.20066)
		(layer "F.Cu")
		(net "M_H_CPU0_SA_DQS_DN<7>")
	)
	(segment
		(start 460.559404 -292.941756)
		(end 458.549248 -292.941756)
		(width 0.1016)
		(layer "F.Cu")
		(net "M_H_CPU0_SA_DQS_DN<7>")
	)
	(segment
		(start 463.659982 -293.366698)
		(end 463.1563 -293.366698)
		(width 0.20066)
		(layer "F.Cu")
		(net "M_H_CPU0_SA_DQS_DN<7>")
	)
	(segment
		(start 460.570326 -292.952678)
		(end 460.559404 -292.941756)
		(width 0.1016)
		(layer "F.Cu")
		(net "M_H_CPU0_SA_DQS_DN<7>")
	)
	(segment
		(start 462.110328 -293.112444)
		(end 461.664812 -292.666928)
		(width 0.20066)
		(layer "F.Cu")
		(net "M_H_CPU0_SA_DQS_DN<7>")
	)
	(segment
		(start 461.664812 -292.666928)
		(end 461.174846 -292.666928)
		(width 0.20066)
		(layer "F.Cu")
		(net "M_H_CPU0_SA_DQS_DN<7>")
	)
	(segment
		(start 458.22616 -292.947852)
		(end 457.948792 -292.670484)
		(width 0.20066)
		(layer "F.Cu")
		(net "M_H_CPU0_SA_DQS_DN<7>")
	)
	(segment
		(start 457.826364 -292.670484)
		(end 457.401422 -293.095426)
		(width 0.20066)
		(layer "F.Cu")
		(net "M_H_CPU0_SA_DQS_DN<7>")
	)
	(segment
		(start 457.401422 -293.095426)
		(end 456.91806 -293.095426)
		(width 0.20066)
		(layer "F.Cu")
		(net "M_H_CPU0_SA_DQS_DN<7>")
	)
	(segment
		(start 458.549248 -292.941756)
		(end 458.543152 -292.947852)
		(width 0.1016)
		(layer "F.Cu")
		(net "M_H_CPU0_SA_DQS_DN<7>")
	)
	(segment
		(start 461.174846 -292.666928)
		(end 460.889096 -292.952678)
		(width 0.20066)
		(layer "F.Cu")
		(net "M_H_CPU0_SA_DQS_DN<7>")
	)
	(segment
		(start 458.543152 -292.947852)
		(end 458.538326 -292.947852)
		(width 0.101854)
		(layer "F.Cu")
		(net "M_H_CPU0_SA_DQS_DN<7>")
	)
	(segment
		(start 420.50589 -298.891452)
		(end 420.265606 -298.651168)
		(width 0.18288)
		(layer "In11.Cu")
		(net "M_H_CPU0_SA_DQS_DN<7>")
	)
	(segment
		(start 436.283354 -296.959274)
		(end 436.051706 -297.190922)
		(width 0.18288)
		(layer "In11.Cu")
		(net "M_H_CPU0_SA_DQS_DN<7>")
	)
	(segment
		(start 409.225242 -295.128188)
		(end 409.100782 -295.003728)
		(width 0.18288)
		(layer "In11.Cu")
		(net "M_H_CPU0_SA_DQS_DN<7>")
	)
	(segment
		(start 376.802904 -269.878302)
		(end 376.794014 -269.873222)
		(width 0.088646)
		(layer "In11.Cu")
		(net "M_H_CPU0_SA_DQS_DN<7>")
	)
	(segment
		(start 408.497278 -295.003728)
		(end 407.674826 -294.18153)
		(width 0.18288)
		(layer "In11.Cu")
		(net "M_H_CPU0_SA_DQS_DN<7>")
	)
	(segment
		(start 411.36951 -295.478454)
		(end 410.894784 -295.003728)
		(width 0.18288)
		(layer "In11.Cu")
		(net "M_H_CPU0_SA_DQS_DN<7>")
	)
	(segment
		(start 403.013418 -291.96284)
		(end 402.625306 -291.574728)
		(width 0.18288)
		(layer "In11.Cu")
		(net "M_H_CPU0_SA_DQS_DN<7>")
	)
	(segment
		(start 400.726656 -289.500056)
		(end 400.726656 -287.896808)
		(width 0.18288)
		(layer "In11.Cu")
		(net "M_H_CPU0_SA_DQS_DN<7>")
	)
	(segment
		(start 427.660054 -297.513502)
		(end 427.327568 -297.181016)
		(width 0.18288)
		(layer "In11.Cu")
		(net "M_H_CPU0_SA_DQS_DN<7>")
	)
	(segment
		(start 445.337946 -294.545766)
		(end 444.708534 -295.175178)
		(width 0.18288)
		(layer "In11.Cu")
		(net "M_H_CPU0_SA_DQS_DN<7>")
	)
	(segment
		(start 430.82845 -296.32275)
		(end 429.81118 -296.32275)
		(width 0.18288)
		(layer "In11.Cu")
		(net "M_H_CPU0_SA_DQS_DN<7>")
	)
	(segment
		(start 450.049138 -292.630352)
		(end 449.739004 -292.940486)
		(width 0.18288)
		(layer "In11.Cu")
		(net "M_H_CPU0_SA_DQS_DN<7>")
	)
	(segment
		(start 433.526438 -297.062144)
		(end 432.977798 -297.062144)
		(width 0.18288)
		(layer "In11.Cu")
		(net "M_H_CPU0_SA_DQS_DN<7>")
	)
	(segment
		(start 379.15215 -272.320004)
		(end 379.14326 -272.314924)
		(width 0.088646)
		(layer "In11.Cu")
		(net "M_H_CPU0_SA_DQS_DN<7>")
	)
	(segment
		(start 400.726656 -287.896808)
		(end 387.47827 -274.648422)
		(width 0.18288)
		(layer "In11.Cu")
		(net "M_H_CPU0_SA_DQS_DN<7>")
	)
	(segment
		(start 413.040576 -296.330878)
		(end 412.188152 -295.478454)
		(width 0.18288)
		(layer "In11.Cu")
		(net "M_H_CPU0_SA_DQS_DN<7>")
	)
	(segment
		(start 415.533332 -296.330878)
		(end 414.519364 -296.330878)
		(width 0.18288)
		(layer "In11.Cu")
		(net "M_H_CPU0_SA_DQS_DN<7>")
	)
	(segment
		(start 409.100782 -295.003728)
		(end 408.497278 -295.003728)
		(width 0.18288)
		(layer "In11.Cu")
		(net "M_H_CPU0_SA_DQS_DN<7>")
	)
	(segment
		(start 413.846264 -296.455338)
		(end 413.721804 -296.330878)
		(width 0.18288)
		(layer "In11.Cu")
		(net "M_H_CPU0_SA_DQS_DN<7>")
	)
	(segment
		(start 414.519364 -296.330878)
		(end 414.394904 -296.455338)
		(width 0.18288)
		(layer "In11.Cu")
		(net "M_H_CPU0_SA_DQS_DN<7>")
	)
	(segment
		(start 451.140322 -292.940232)
		(end 450.720714 -292.940232)
		(width 0.18288)
		(layer "In11.Cu")
		(net "M_H_CPU0_SA_DQS_DN<7>")
	)
	(segment
		(start 426.175932 -297.809158)
		(end 425.295822 -297.809158)
		(width 0.18288)
		(layer "In11.Cu")
		(net "M_H_CPU0_SA_DQS_DN<7>")
	)
	(segment
		(start 385.329938 -273.187922)
		(end 385.329938 -273.188176)
		(width 0.088646)
		(layer "In11.Cu")
		(net "M_H_CPU0_SA_DQS_DN<7>")
	)
	(segment
		(start 431.443384 -296.937684)
		(end 430.82845 -296.32275)
		(width 0.18288)
		(layer "In11.Cu")
		(net "M_H_CPU0_SA_DQS_DN<7>")
	)
	(segment
		(start 378.861066 -271.84731)
		(end 378.861066 -271.825212)
		(width 0.088646)
		(layer "In11.Cu")
		(net "M_H_CPU0_SA_DQS_DN<7>")
	)
	(segment
		(start 425.064174 -298.040806)
		(end 424.54195 -298.040806)
		(width 0.18288)
		(layer "In11.Cu")
		(net "M_H_CPU0_SA_DQS_DN<7>")
	)
	(segment
		(start 454.472802 -293.112444)
		(end 454.311512 -293.273734)
		(width 0.18288)
		(layer "In11.Cu")
		(net "M_H_CPU0_SA_DQS_DN<7>")
	)
	(segment
		(start 454.311512 -293.273734)
		(end 453.709278 -293.273734)
		(width 0.18288)
		(layer "In11.Cu")
		(net "M_H_CPU0_SA_DQS_DN<7>")
	)
	(segment
		(start 444.708534 -295.175178)
		(end 444.708534 -295.3512)
		(width 0.18288)
		(layer "In11.Cu")
		(net "M_H_CPU0_SA_DQS_DN<7>")
	)
	(segment
		(start 403.577298 -292.350698)
		(end 403.18944 -291.96284)
		(width 0.18288)
		(layer "In11.Cu")
		(net "M_H_CPU0_SA_DQS_DN<7>")
	)
	(segment
		(start 444.320422 -295.739312)
		(end 444.1444 -295.739312)
		(width 0.18288)
		(layer "In11.Cu")
		(net "M_H_CPU0_SA_DQS_DN<7>")
	)
	(segment
		(start 441.551568 -297.089068)
		(end 440.864498 -297.776138)
		(width 0.18288)
		(layer "In11.Cu")
		(net "M_H_CPU0_SA_DQS_DN<7>")
	)
	(segment
		(start 454.757028 -293.112444)
		(end 454.472802 -293.112444)
		(width 0.18288)
		(layer "In11.Cu")
		(net "M_H_CPU0_SA_DQS_DN<7>")
	)
	(segment
		(start 453.036178 -293.398194)
		(end 452.911718 -293.273734)
		(width 0.18288)
		(layer "In11.Cu")
		(net "M_H_CPU0_SA_DQS_DN<7>")
	)
	(segment
		(start 440.151774 -298.040806)
		(end 439.62955 -298.040806)
		(width 0.18288)
		(layer "In11.Cu")
		(net "M_H_CPU0_SA_DQS_DN<7>")
	)
	(segment
		(start 453.709278 -293.273734)
		(end 453.584818 -293.398194)
		(width 0.18288)
		(layer "In11.Cu")
		(net "M_H_CPU0_SA_DQS_DN<7>")
	)
	(segment
		(start 418.90696 -298.100496)
		(end 418.730938 -298.100496)
		(width 0.18288)
		(layer "In11.Cu")
		(net "M_H_CPU0_SA_DQS_DN<7>")
	)
	(segment
		(start 423.457624 -297.769534)
		(end 421.47617 -298.590208)
		(width 0.18288)
		(layer "In11.Cu")
		(net "M_H_CPU0_SA_DQS_DN<7>")
	)
	(segment
		(start 444.1444 -295.739312)
		(end 443.703964 -296.179748)
		(width 0.18288)
		(layer "In11.Cu")
		(net "M_H_CPU0_SA_DQS_DN<7>")
	)
	(segment
		(start 443.703964 -296.179748)
		(end 443.045596 -296.179748)
		(width 0.18288)
		(layer "In11.Cu")
		(net "M_H_CPU0_SA_DQS_DN<7>")
	)
	(segment
		(start 377.829064 -270.687038)
		(end 377.814332 -270.695674)
		(width 0.088646)
		(layer "In11.Cu")
		(net "M_H_CPU0_SA_DQS_DN<7>")
	)
	(segment
		(start 387.182614 -274.588478)
		(end 386.730494 -274.588478)
		(width 0.088646)
		(layer "In11.Cu")
		(net "M_H_CPU0_SA_DQS_DN<7>")
	)
	(segment
		(start 378.673614 -271.500854)
		(end 378.667518 -271.497298)
		(width 0.088646)
		(layer "In11.Cu")
		(net "M_H_CPU0_SA_DQS_DN<7>")
	)
	(segment
		(start 418.730938 -298.100496)
		(end 418.342826 -297.712384)
		(width 0.18288)
		(layer "In11.Cu")
		(net "M_H_CPU0_SA_DQS_DN<7>")
	)
	(segment
		(start 402.237448 -291.010848)
		(end 402.061426 -291.010848)
		(width 0.18288)
		(layer "In11.Cu")
		(net "M_H_CPU0_SA_DQS_DN<7>")
	)
	(segment
		(start 420.926514 -298.891452)
		(end 420.50589 -298.891452)
		(width 0.18288)
		(layer "In11.Cu")
		(net "M_H_CPU0_SA_DQS_DN<7>")
	)
	(segment
		(start 451.724776 -292.665658)
		(end 451.414896 -292.665658)
		(width 0.18288)
		(layer "In11.Cu")
		(net "M_H_CPU0_SA_DQS_DN<7>")
	)
	(segment
		(start 381.507746 -273.137376)
		(end 381.493014 -273.12874)
		(width 0.088646)
		(layer "In11.Cu")
		(net "M_H_CPU0_SA_DQS_DN<7>")
	)
	(segment
		(start 409.898342 -295.003728)
		(end 409.773882 -295.128188)
		(width 0.18288)
		(layer "In11.Cu")
		(net "M_H_CPU0_SA_DQS_DN<7>")
	)
	(segment
		(start 376.981466 -270.213074)
		(end 376.981466 -270.19758)
		(width 0.088646)
		(layer "In11.Cu")
		(net "M_H_CPU0_SA_DQS_DN<7>")
	)
	(segment
		(start 404.52929 -293.30269)
		(end 404.141432 -292.914832)
		(width 0.18288)
		(layer "In11.Cu")
		(net "M_H_CPU0_SA_DQS_DN<7>")
	)
	(segment
		(start 402.625306 -291.398706)
		(end 402.237448 -291.010848)
		(width 0.18288)
		(layer "In11.Cu")
		(net "M_H_CPU0_SA_DQS_DN<7>")
	)
	(segment
		(start 435.529482 -297.190922)
		(end 435.276244 -296.937684)
		(width 0.18288)
		(layer "In11.Cu")
		(net "M_H_CPU0_SA_DQS_DN<7>")
	)
	(segment
		(start 374.26011 -269.948152)
		(end 373.940324 -269.948152)
		(width 0.088646)
		(layer "In11.Cu")
		(net "M_H_CPU0_SA_DQS_DN<7>")
	)
	(segment
		(start 418.342826 -297.536362)
		(end 417.815522 -297.009058)
		(width 0.18288)
		(layer "In11.Cu")
		(net "M_H_CPU0_SA_DQS_DN<7>")
	)
	(segment
		(start 443.045596 -296.179748)
		(end 442.136276 -297.089068)
		(width 0.18288)
		(layer "In11.Cu")
		(net "M_H_CPU0_SA_DQS_DN<7>")
	)
	(segment
		(start 403.96541 -292.914832)
		(end 403.577298 -292.52672)
		(width 0.18288)
		(layer "In11.Cu")
		(net "M_H_CPU0_SA_DQS_DN<7>")
	)
	(segment
		(start 374.929146 -269.881858)
		(end 374.914668 -269.873222)
		(width 0.088646)
		(layer "In11.Cu")
		(net "M_H_CPU0_SA_DQS_DN<7>")
	)
	(segment
		(start 429.81118 -296.32275)
		(end 428.620428 -297.513502)
		(width 0.18288)
		(layer "In11.Cu")
		(net "M_H_CPU0_SA_DQS_DN<7>")
	)
	(segment
		(start 373.787416 -270.059404)
		(end 373.787416 -270.19758)
		(width 0.088646)
		(layer "In11.Cu")
		(net "M_H_CPU0_SA_DQS_DN<7>")
	)
	(segment
		(start 378.682504 -271.505934)
		(end 378.673614 -271.500854)
		(width 0.088646)
		(layer "In11.Cu")
		(net "M_H_CPU0_SA_DQS_DN<7>")
	)
	(segment
		(start 432.977798 -297.062144)
		(end 432.853338 -296.937684)
		(width 0.18288)
		(layer "In11.Cu")
		(net "M_H_CPU0_SA_DQS_DN<7>")
	)
	(segment
		(start 380.567946 -273.137376)
		(end 380.553214 -273.12874)
		(width 0.088646)
		(layer "In11.Cu")
		(net "M_H_CPU0_SA_DQS_DN<7>")
	)
	(segment
		(start 444.708534 -295.3512)
		(end 444.320422 -295.739312)
		(width 0.18288)
		(layer "In11.Cu")
		(net "M_H_CPU0_SA_DQS_DN<7>")
	)
	(segment
		(start 383.383028 -273.134836)
		(end 383.372614 -273.12874)
		(width 0.088646)
		(layer "In11.Cu")
		(net "M_H_CPU0_SA_DQS_DN<7>")
	)
	(segment
		(start 450.410834 -292.630352)
		(end 450.049138 -292.630352)
		(width 0.18288)
		(layer "In11.Cu")
		(net "M_H_CPU0_SA_DQS_DN<7>")
	)
	(segment
		(start 425.295822 -297.809158)
		(end 425.064174 -298.040806)
		(width 0.18288)
		(layer "In11.Cu")
		(net "M_H_CPU0_SA_DQS_DN<7>")
	)
	(segment
		(start 378.21235 -270.692118)
		(end 378.20346 -270.687038)
		(width 0.088646)
		(layer "In11.Cu")
		(net "M_H_CPU0_SA_DQS_DN<7>")
	)
	(segment
		(start 439.62955 -298.040806)
		(end 439.384694 -297.79595)
		(width 0.18288)
		(layer "In11.Cu")
		(net "M_H_CPU0_SA_DQS_DN<7>")
	)
	(segment
		(start 412.188152 -295.478454)
		(end 411.36951 -295.478454)
		(width 0.18288)
		(layer "In11.Cu")
		(net "M_H_CPU0_SA_DQS_DN<7>")
	)
	(segment
		(start 402.061426 -291.010848)
		(end 401.673314 -290.622736)
		(width 0.18288)
		(layer "In11.Cu")
		(net "M_H_CPU0_SA_DQS_DN<7>")
	)
	(segment
		(start 452.332852 -293.273734)
		(end 451.724776 -292.665658)
		(width 0.18288)
		(layer "In11.Cu")
		(net "M_H_CPU0_SA_DQS_DN<7>")
	)
	(segment
		(start 375.868946 -269.881858)
		(end 375.854214 -269.873222)
		(width 0.088646)
		(layer "In11.Cu")
		(net "M_H_CPU0_SA_DQS_DN<7>")
	)
	(segment
		(start 433.650898 -296.937684)
		(end 433.526438 -297.062144)
		(width 0.18288)
		(layer "In11.Cu")
		(net "M_H_CPU0_SA_DQS_DN<7>")
	)
	(segment
		(start 421.47617 -298.590208)
		(end 421.227758 -298.590208)
		(width 0.18288)
		(layer "In11.Cu")
		(net "M_H_CPU0_SA_DQS_DN<7>")
	)
	(segment
		(start 442.136276 -297.089068)
		(end 441.551568 -297.089068)
		(width 0.18288)
		(layer "In11.Cu")
		(net "M_H_CPU0_SA_DQS_DN<7>")
	)
	(segment
		(start 420.265606 -298.651168)
		(end 419.457632 -298.651168)
		(width 0.18288)
		(layer "In11.Cu")
		(net "M_H_CPU0_SA_DQS_DN<7>")
	)
	(segment
		(start 379.603254 -273.122898)
		(end 379.601222 -273.121628)
		(width 0.088646)
		(layer "In11.Cu")
		(net "M_H_CPU0_SA_DQS_DN<7>")
	)
	(segment
		(start 401.673314 -290.446714)
		(end 400.726656 -289.500056)
		(width 0.18288)
		(layer "In11.Cu")
		(net "M_H_CPU0_SA_DQS_DN<7>")
	)
	(segment
		(start 424.270678 -297.769534)
		(end 423.457624 -297.769534)
		(width 0.18288)
		(layer "In11.Cu")
		(net "M_H_CPU0_SA_DQS_DN<7>")
	)
	(segment
		(start 439.384694 -297.79595)
		(end 438.004458 -297.79595)
		(width 0.18288)
		(layer "In11.Cu")
		(net "M_H_CPU0_SA_DQS_DN<7>")
	)
	(segment
		(start 446.321688 -294.545766)
		(end 445.337946 -294.545766)
		(width 0.18288)
		(layer "In11.Cu")
		(net "M_H_CPU0_SA_DQS_DN<7>")
	)
	(segment
		(start 410.894784 -295.003728)
		(end 409.898342 -295.003728)
		(width 0.18288)
		(layer "In11.Cu")
		(net "M_H_CPU0_SA_DQS_DN<7>")
	)
	(segment
		(start 448.10807 -293.775384)
		(end 447.09207 -293.775384)
		(width 0.18288)
		(layer "In11.Cu")
		(net "M_H_CPU0_SA_DQS_DN<7>")
	)
	(segment
		(start 373.940324 -269.948152)
		(end 373.884698 -269.962376)
		(width 0.088646)
		(layer "In11.Cu")
		(net "M_H_CPU0_SA_DQS_DN<7>")
	)
	(segment
		(start 428.620428 -297.513502)
		(end 427.660054 -297.513502)
		(width 0.18288)
		(layer "In11.Cu")
		(net "M_H_CPU0_SA_DQS_DN<7>")
	)
	(segment
		(start 424.54195 -298.040806)
		(end 424.270678 -297.769534)
		(width 0.18288)
		(layer "In11.Cu")
		(net "M_H_CPU0_SA_DQS_DN<7>")
	)
	(segment
		(start 414.394904 -296.455338)
		(end 413.846264 -296.455338)
		(width 0.18288)
		(layer "In11.Cu")
		(net "M_H_CPU0_SA_DQS_DN<7>")
	)
	(segment
		(start 440.416442 -297.776138)
		(end 440.151774 -298.040806)
		(width 0.18288)
		(layer "In11.Cu")
		(net "M_H_CPU0_SA_DQS_DN<7>")
	)
	(segment
		(start 403.18944 -291.96284)
		(end 403.013418 -291.96284)
		(width 0.18288)
		(layer "In11.Cu")
		(net "M_H_CPU0_SA_DQS_DN<7>")
	)
	(segment
		(start 413.721804 -296.330878)
		(end 413.040576 -296.330878)
		(width 0.18288)
		(layer "In11.Cu")
		(net "M_H_CPU0_SA_DQS_DN<7>")
	)
	(segment
		(start 432.853338 -296.937684)
		(end 431.443384 -296.937684)
		(width 0.18288)
		(layer "In11.Cu")
		(net "M_H_CPU0_SA_DQS_DN<7>")
	)
	(segment
		(start 426.804074 -297.181016)
		(end 426.175932 -297.809158)
		(width 0.18288)
		(layer "In11.Cu")
		(net "M_H_CPU0_SA_DQS_DN<7>")
	)
	(segment
		(start 405.553672 -293.30269)
		(end 404.52929 -293.30269)
		(width 0.18288)
		(layer "In11.Cu")
		(net "M_H_CPU0_SA_DQS_DN<7>")
	)
	(segment
		(start 417.815522 -297.009058)
		(end 417.170616 -297.009058)
		(width 0.18288)
		(layer "In11.Cu")
		(net "M_H_CPU0_SA_DQS_DN<7>")
	)
	(segment
		(start 386.730494 -274.588478)
		(end 385.329938 -273.187922)
		(width 0.088646)
		(layer "In11.Cu")
		(net "M_H_CPU0_SA_DQS_DN<7>")
	)
	(segment
		(start 417.170616 -297.009058)
		(end 415.533332 -296.330878)
		(width 0.18288)
		(layer "In11.Cu")
		(net "M_H_CPU0_SA_DQS_DN<7>")
	)
	(segment
		(start 379.613414 -273.12874)
		(end 379.612144 -273.127978)
		(width 0.088646)
		(layer "In11.Cu")
		(net "M_H_CPU0_SA_DQS_DN<7>")
	)
	(segment
		(start 448.942968 -292.940486)
		(end 448.10807 -293.775384)
		(width 0.18288)
		(layer "In11.Cu")
		(net "M_H_CPU0_SA_DQS_DN<7>")
	)
	(segment
		(start 438.004458 -297.79595)
		(end 437.167782 -296.959274)
		(width 0.18288)
		(layer "In11.Cu")
		(net "M_H_CPU0_SA_DQS_DN<7>")
	)
	(segment
		(start 402.625306 -291.574728)
		(end 402.625306 -291.398706)
		(width 0.18288)
		(layer "In11.Cu")
		(net "M_H_CPU0_SA_DQS_DN<7>")
	)
	(segment
		(start 440.864498 -297.776138)
		(end 440.416442 -297.776138)
		(width 0.18288)
		(layer "In11.Cu")
		(net "M_H_CPU0_SA_DQS_DN<7>")
	)
	(segment
		(start 451.414896 -292.665658)
		(end 451.140322 -292.940232)
		(width 0.18288)
		(layer "In11.Cu")
		(net "M_H_CPU0_SA_DQS_DN<7>")
	)
	(segment
		(start 387.47827 -274.648422)
		(end 387.242558 -274.648422)
		(width 0.18288)
		(layer "In11.Cu")
		(net "M_H_CPU0_SA_DQS_DN<7>")
	)
	(segment
		(start 403.577298 -292.52672)
		(end 403.577298 -292.350698)
		(width 0.18288)
		(layer "In11.Cu")
		(net "M_H_CPU0_SA_DQS_DN<7>")
	)
	(segment
		(start 435.276244 -296.937684)
		(end 433.650898 -296.937684)
		(width 0.18288)
		(layer "In11.Cu")
		(net "M_H_CPU0_SA_DQS_DN<7>")
	)
	(segment
		(start 409.773882 -295.128188)
		(end 409.225242 -295.128188)
		(width 0.18288)
		(layer "In11.Cu")
		(net "M_H_CPU0_SA_DQS_DN<7>")
	)
	(segment
		(start 404.141432 -292.914832)
		(end 403.96541 -292.914832)
		(width 0.18288)
		(layer "In11.Cu")
		(net "M_H_CPU0_SA_DQS_DN<7>")
	)
	(segment
		(start 437.167782 -296.959274)
		(end 436.283354 -296.959274)
		(width 0.18288)
		(layer "In11.Cu")
		(net "M_H_CPU0_SA_DQS_DN<7>")
	)
	(segment
		(start 453.584818 -293.398194)
		(end 453.036178 -293.398194)
		(width 0.18288)
		(layer "In11.Cu")
		(net "M_H_CPU0_SA_DQS_DN<7>")
	)
	(segment
		(start 374.914668 -269.873222)
		(end 374.914668 -269.872968)
		(width 0.088646)
		(layer "In11.Cu")
		(net "M_H_CPU0_SA_DQS_DN<7>")
	)
	(segment
		(start 436.051706 -297.190922)
		(end 435.529482 -297.190922)
		(width 0.18288)
		(layer "In11.Cu")
		(net "M_H_CPU0_SA_DQS_DN<7>")
	)
	(segment
		(start 455.011282 -293.366698)
		(end 454.757028 -293.112444)
		(width 0.18288)
		(layer "In11.Cu")
		(net "M_H_CPU0_SA_DQS_DN<7>")
	)
	(segment
		(start 452.911718 -293.273734)
		(end 452.332852 -293.273734)
		(width 0.18288)
		(layer "In11.Cu")
		(net "M_H_CPU0_SA_DQS_DN<7>")
	)
	(segment
		(start 421.227758 -298.590208)
		(end 420.926514 -298.891452)
		(width 0.18288)
		(layer "In11.Cu")
		(net "M_H_CPU0_SA_DQS_DN<7>")
	)
	(segment
		(start 382.447546 -273.137376)
		(end 382.432814 -273.12874)
		(width 0.088646)
		(layer "In11.Cu")
		(net "M_H_CPU0_SA_DQS_DN<7>")
	)
	(segment
		(start 418.342826 -297.712384)
		(end 418.342826 -297.536362)
		(width 0.18288)
		(layer "In11.Cu")
		(net "M_H_CPU0_SA_DQS_DN<7>")
	)
	(segment
		(start 401.673314 -290.622736)
		(end 401.673314 -290.446714)
		(width 0.18288)
		(layer "In11.Cu")
		(net "M_H_CPU0_SA_DQS_DN<7>")
	)
	(segment
		(start 427.327568 -297.181016)
		(end 426.804074 -297.181016)
		(width 0.18288)
		(layer "In11.Cu")
		(net "M_H_CPU0_SA_DQS_DN<7>")
	)
	(segment
		(start 450.720714 -292.940232)
		(end 450.410834 -292.630352)
		(width 0.18288)
		(layer "In11.Cu")
		(net "M_H_CPU0_SA_DQS_DN<7>")
	)
	(segment
		(start 447.09207 -293.775384)
		(end 446.321688 -294.545766)
		(width 0.18288)
		(layer "In11.Cu")
		(net "M_H_CPU0_SA_DQS_DN<7>")
	)
	(segment
		(start 449.739004 -292.940486)
		(end 448.942968 -292.940486)
		(width 0.18288)
		(layer "In11.Cu")
		(net "M_H_CPU0_SA_DQS_DN<7>")
	)
	(segment
		(start 379.612144 -273.127978)
		(end 379.603254 -273.122898)
		(width 0.088646)
		(layer "In11.Cu")
		(net "M_H_CPU0_SA_DQS_DN<7>")
	)
	(segment
		(start 387.242558 -274.648422)
		(end 387.182614 -274.588478)
		(width 0.088646)
		(layer "In11.Cu")
		(net "M_H_CPU0_SA_DQS_DN<7>")
	)
	(segment
		(start 407.674826 -294.18153)
		(end 405.553672 -293.30269)
		(width 0.18288)
		(layer "In11.Cu")
		(net "M_H_CPU0_SA_DQS_DN<7>")
	)
	(segment
		(start 419.457632 -298.651168)
		(end 418.90696 -298.100496)
		(width 0.18288)
		(layer "In11.Cu")
		(net "M_H_CPU0_SA_DQS_DN<7>")
	)
	(segment
		(start 373.884698 -269.962376)
		(end 373.787416 -270.059404)
		(width 0.088646)
		(layer "In11.Cu")
		(net "M_H_CPU0_SA_DQS_DN<7>")
	)
	(arc
		(start 381.118618 -273.12874)
		(mid 380.844419 -273.204575)
		(end 380.567946 -273.137376)
		(width 0.088646)
		(layer "In11.Cu")
		(net "M_H_CPU0_SA_DQS_DN<7>")
	)
	(arc
		(start 382.432814 -273.12874)
		(mid 382.245616 -273.078597)
		(end 382.058418 -273.12874)
		(width 0.088646)
		(layer "In11.Cu")
		(net "M_H_CPU0_SA_DQS_DN<7>")
	)
	(arc
		(start 385.329938 -273.188176)
		(mid 385.313015 -273.172271)
		(end 385.29514 -273.157442)
		(width 0.088646)
		(layer "In11.Cu")
		(net "M_H_CPU0_SA_DQS_DN<7>")
	)
	(arc
		(start 383.372614 -273.12874)
		(mid 383.185416 -273.078597)
		(end 382.998218 -273.12874)
		(width 0.088646)
		(layer "In11.Cu")
		(net "M_H_CPU0_SA_DQS_DN<7>")
	)
	(arc
		(start 375.479818 -269.873222)
		(mid 375.205589 -269.949147)
		(end 374.929146 -269.881858)
		(width 0.088646)
		(layer "In11.Cu")
		(net "M_H_CPU0_SA_DQS_DN<7>")
	)
	(arc
		(start 376.419618 -269.873222)
		(mid 376.145389 -269.949147)
		(end 375.868946 -269.881858)
		(width 0.088646)
		(layer "In11.Cu")
		(net "M_H_CPU0_SA_DQS_DN<7>")
	)
	(arc
		(start 382.058418 -273.12874)
		(mid 381.784219 -273.204575)
		(end 381.507746 -273.137376)
		(width 0.088646)
		(layer "In11.Cu")
		(net "M_H_CPU0_SA_DQS_DN<7>")
	)
	(arc
		(start 378.390912 -271.011396)
		(mid 378.343233 -270.828496)
		(end 378.21235 -270.692118)
		(width 0.088646)
		(layer "In11.Cu")
		(net "M_H_CPU0_SA_DQS_DN<7>")
	)
	(arc
		(start 385.29514 -273.157442)
		(mid 385.27405 -273.142338)
		(end 385.25196 -273.12874)
		(width 0.088646)
		(layer "In11.Cu")
		(net "M_H_CPU0_SA_DQS_DN<7>")
	)
	(arc
		(start 384.877564 -273.12874)
		(mid 384.594862 -273.204516)
		(end 384.31216 -273.12874)
		(width 0.088646)
		(layer "In11.Cu")
		(net "M_H_CPU0_SA_DQS_DN<7>")
	)
	(arc
		(start 374.540272 -269.872968)
		(mid 374.405159 -269.92906)
		(end 374.26011 -269.948152)
		(width 0.088646)
		(layer "In11.Cu")
		(net "M_H_CPU0_SA_DQS_DN<7>")
	)
	(arc
		(start 380.178818 -273.12874)
		(mid 379.896116 -273.204516)
		(end 379.613414 -273.12874)
		(width 0.088646)
		(layer "In11.Cu")
		(net "M_H_CPU0_SA_DQS_DN<7>")
	)
	(arc
		(start 382.998218 -273.12874)
		(mid 382.724019 -273.204575)
		(end 382.447546 -273.137376)
		(width 0.088646)
		(layer "In11.Cu")
		(net "M_H_CPU0_SA_DQS_DN<7>")
	)
	(arc
		(start 385.25196 -273.12874)
		(mid 385.064762 -273.078597)
		(end 384.877564 -273.12874)
		(width 0.088646)
		(layer "In11.Cu")
		(net "M_H_CPU0_SA_DQS_DN<7>")
	)
	(arc
		(start 379.601222 -273.121628)
		(mid 379.402994 -272.91578)
		(end 379.330712 -272.639282)
		(width 0.088646)
		(layer "In11.Cu")
		(net "M_H_CPU0_SA_DQS_DN<7>")
	)
	(arc
		(start 381.493014 -273.12874)
		(mid 381.305816 -273.078597)
		(end 381.118618 -273.12874)
		(width 0.088646)
		(layer "In11.Cu")
		(net "M_H_CPU0_SA_DQS_DN<7>")
	)
	(arc
		(start 376.794014 -269.873222)
		(mid 376.606816 -269.823079)
		(end 376.419618 -269.873222)
		(width 0.088646)
		(layer "In11.Cu")
		(net "M_H_CPU0_SA_DQS_DN<7>")
	)
	(arc
		(start 383.937764 -273.12874)
		(mid 383.661205 -273.204483)
		(end 383.383028 -273.134836)
		(width 0.088646)
		(layer "In11.Cu")
		(net "M_H_CPU0_SA_DQS_DN<7>")
	)
	(arc
		(start 376.981466 -270.19758)
		(mid 376.933787 -270.01468)
		(end 376.802904 -269.878302)
		(width 0.088646)
		(layer "In11.Cu")
		(net "M_H_CPU0_SA_DQS_DN<7>")
	)
	(arc
		(start 378.861066 -271.825212)
		(mid 378.813387 -271.642312)
		(end 378.682504 -271.505934)
		(width 0.088646)
		(layer "In11.Cu")
		(net "M_H_CPU0_SA_DQS_DN<7>")
	)
	(arc
		(start 374.914668 -269.872968)
		(mid 374.72747 -269.822859)
		(end 374.540272 -269.872968)
		(width 0.088646)
		(layer "In11.Cu")
		(net "M_H_CPU0_SA_DQS_DN<7>")
	)
	(arc
		(start 384.31216 -273.12874)
		(mid 384.124962 -273.078597)
		(end 383.937764 -273.12874)
		(width 0.088646)
		(layer "In11.Cu")
		(net "M_H_CPU0_SA_DQS_DN<7>")
	)
	(arc
		(start 378.667518 -271.497298)
		(mid 378.464931 -271.290947)
		(end 378.390912 -271.011396)
		(width 0.088646)
		(layer "In11.Cu")
		(net "M_H_CPU0_SA_DQS_DN<7>")
	)
	(arc
		(start 380.553214 -273.12874)
		(mid 380.366016 -273.078597)
		(end 380.178818 -273.12874)
		(width 0.088646)
		(layer "In11.Cu")
		(net "M_H_CPU0_SA_DQS_DN<7>")
	)
	(arc
		(start 375.854214 -269.873222)
		(mid 375.667016 -269.823079)
		(end 375.479818 -269.873222)
		(width 0.088646)
		(layer "In11.Cu")
		(net "M_H_CPU0_SA_DQS_DN<7>")
	)
	(arc
		(start 379.14326 -272.314924)
		(mid 378.941978 -272.117437)
		(end 378.861066 -271.84731)
		(width 0.088646)
		(layer "In11.Cu")
		(net "M_H_CPU0_SA_DQS_DN<7>")
	)
	(arc
		(start 378.20346 -270.687038)
		(mid 378.016262 -270.636895)
		(end 377.829064 -270.687038)
		(width 0.088646)
		(layer "In11.Cu")
		(net "M_H_CPU0_SA_DQS_DN<7>")
	)
	(arc
		(start 379.330712 -272.639282)
		(mid 379.283033 -272.456382)
		(end 379.15215 -272.320004)
		(width 0.088646)
		(layer "In11.Cu")
		(net "M_H_CPU0_SA_DQS_DN<7>")
	)
	(arc
		(start 377.26366 -270.687038)
		(mid 377.060837 -270.486807)
		(end 376.981466 -270.213074)
		(width 0.088646)
		(layer "In11.Cu")
		(net "M_H_CPU0_SA_DQS_DN<7>")
	)
	(arc
		(start 377.814332 -270.695674)
		(mid 377.537857 -270.762994)
		(end 377.26366 -270.687038)
		(width 0.088646)
		(layer "In11.Cu")
		(net "M_H_CPU0_SA_DQS_DN<7>")
	)
	(segment
		(start 458.22616 -302.297846)
		(end 457.948792 -302.020478)
		(width 0.20066)
		(layer "F.Cu")
		(net "M_H_CPU0_SA_DQS_DN<6>")
	)
	(segment
		(start 460.559404 -302.29175)
		(end 458.549248 -302.29175)
		(width 0.1016)
		(layer "F.Cu")
		(net "M_H_CPU0_SA_DQS_DN<6>")
	)
	(segment
		(start 463.1563 -302.716692)
		(end 462.902046 -302.462438)
		(width 0.20066)
		(layer "F.Cu")
		(net "M_H_CPU0_SA_DQS_DN<6>")
	)
	(segment
		(start 460.570326 -302.302672)
		(end 460.559404 -302.29175)
		(width 0.1016)
		(layer "F.Cu")
		(net "M_H_CPU0_SA_DQS_DN<6>")
	)
	(segment
		(start 457.401422 -302.44542)
		(end 456.91806 -302.44542)
		(width 0.20066)
		(layer "F.Cu")
		(net "M_H_CPU0_SA_DQS_DN<6>")
	)
	(segment
		(start 458.538326 -302.297846)
		(end 458.22616 -302.297846)
		(width 0.20066)
		(layer "F.Cu")
		(net "M_H_CPU0_SA_DQS_DN<6>")
	)
	(segment
		(start 455.011282 -302.716692)
		(end 456.116182 -302.716692)
		(width 0.20066)
		(layer "F.Cu")
		(net "M_H_CPU0_SA_DQS_DN<6>")
	)
	(segment
		(start 457.948792 -302.020478)
		(end 457.826364 -302.020478)
		(width 0.20066)
		(layer "F.Cu")
		(net "M_H_CPU0_SA_DQS_DN<6>")
	)
	(segment
		(start 458.543152 -302.297846)
		(end 458.538326 -302.297846)
		(width 0.101854)
		(layer "F.Cu")
		(net "M_H_CPU0_SA_DQS_DN<6>")
	)
	(segment
		(start 463.659982 -302.716692)
		(end 463.1563 -302.716692)
		(width 0.20066)
		(layer "F.Cu")
		(net "M_H_CPU0_SA_DQS_DN<6>")
	)
	(segment
		(start 373.787162 -274.54479)
		(end 373.787416 -274.545044)
		(width 0.20066)
		(layer "F.Cu")
		(net "M_H_CPU0_SA_DQS_DN<6>")
	)
	(segment
		(start 456.646788 -302.716692)
		(end 456.116182 -302.716692)
		(width 0.20066)
		(layer "F.Cu")
		(net "M_H_CPU0_SA_DQS_DN<6>")
	)
	(segment
		(start 461.664812 -302.016922)
		(end 461.174846 -302.016922)
		(width 0.20066)
		(layer "F.Cu")
		(net "M_H_CPU0_SA_DQS_DN<6>")
	)
	(segment
		(start 457.826364 -302.020478)
		(end 457.401422 -302.44542)
		(width 0.20066)
		(layer "F.Cu")
		(net "M_H_CPU0_SA_DQS_DN<6>")
	)
	(segment
		(start 373.787416 -274.545044)
		(end 373.787416 -275.08073)
		(width 0.20066)
		(layer "F.Cu")
		(net "M_H_CPU0_SA_DQS_DN<6>")
	)
	(segment
		(start 461.174846 -302.016922)
		(end 460.889096 -302.302672)
		(width 0.20066)
		(layer "F.Cu")
		(net "M_H_CPU0_SA_DQS_DN<6>")
	)
	(segment
		(start 456.91806 -302.44542)
		(end 456.646788 -302.716692)
		(width 0.20066)
		(layer "F.Cu")
		(net "M_H_CPU0_SA_DQS_DN<6>")
	)
	(segment
		(start 460.889096 -302.302672)
		(end 460.570326 -302.302672)
		(width 0.20066)
		(layer "F.Cu")
		(net "M_H_CPU0_SA_DQS_DN<6>")
	)
	(segment
		(start 458.549248 -302.29175)
		(end 458.543152 -302.297846)
		(width 0.1016)
		(layer "F.Cu")
		(net "M_H_CPU0_SA_DQS_DN<6>")
	)
	(segment
		(start 462.902046 -302.462438)
		(end 462.110328 -302.462438)
		(width 0.20066)
		(layer "F.Cu")
		(net "M_H_CPU0_SA_DQS_DN<6>")
	)
	(segment
		(start 462.110328 -302.462438)
		(end 461.664812 -302.016922)
		(width 0.20066)
		(layer "F.Cu")
		(net "M_H_CPU0_SA_DQS_DN<6>")
	)
	(segment
		(start 450.991732 -302.291242)
		(end 450.814186 -302.291242)
		(width 0.16002)
		(layer "In11.Cu")
		(net "M_H_CPU0_SA_DQS_DN<6>")
	)
	(segment
		(start 412.973774 -307.002942)
		(end 412.258256 -307.71846)
		(width 0.18288)
		(layer "In11.Cu")
		(net "M_H_CPU0_SA_DQS_DN<6>")
	)
	(segment
		(start 433.951126 -308.128924)
		(end 433.826666 -308.004464)
		(width 0.18288)
		(layer "In11.Cu")
		(net "M_H_CPU0_SA_DQS_DN<6>")
	)
	(segment
		(start 374.43791 -275.566124)
		(end 374.289574 -275.482812)
		(width 0.088646)
		(layer "In11.Cu")
		(net "M_H_CPU0_SA_DQS_DN<6>")
	)
	(segment
		(start 415.52241 -307.002942)
		(end 415.39795 -307.127402)
		(width 0.18288)
		(layer "In11.Cu")
		(net "M_H_CPU0_SA_DQS_DN<6>")
	)
	(segment
		(start 443.959488 -307.067966)
		(end 443.315344 -307.067966)
		(width 0.18288)
		(layer "In11.Cu")
		(net "M_H_CPU0_SA_DQS_DN<6>")
	)
	(segment
		(start 440.774836 -308.830218)
		(end 440.412378 -308.830218)
		(width 0.18288)
		(layer "In11.Cu")
		(net "M_H_CPU0_SA_DQS_DN<6>")
	)
	(segment
		(start 453.596502 -302.613314)
		(end 453.472042 -302.737774)
		(width 0.18288)
		(layer "In11.Cu")
		(net "M_H_CPU0_SA_DQS_DN<6>")
	)
	(segment
		(start 374.923304 -276.389338)
		(end 374.908318 -276.380702)
		(width 0.088646)
		(layer "In11.Cu")
		(net "M_H_CPU0_SA_DQS_DN<6>")
	)
	(segment
		(start 379.708918 -278.82596)
		(end 379.698504 -278.832056)
		(width 0.088646)
		(layer "In11.Cu")
		(net "M_H_CPU0_SA_DQS_DN<6>")
	)
	(segment
		(start 423.08653 -308.981602)
		(end 422.96207 -308.857142)
		(width 0.18288)
		(layer "In11.Cu")
		(net "M_H_CPU0_SA_DQS_DN<6>")
	)
	(segment
		(start 452.798942 -302.613314)
		(end 452.250302 -302.613314)
		(width 0.18288)
		(layer "In11.Cu")
		(net "M_H_CPU0_SA_DQS_DN<6>")
	)
	(segment
		(start 453.472042 -302.737774)
		(end 452.923402 -302.737774)
		(width 0.18288)
		(layer "In11.Cu")
		(net "M_H_CPU0_SA_DQS_DN<6>")
	)
	(segment
		(start 434.624226 -308.004464)
		(end 434.499766 -308.128924)
		(width 0.18288)
		(layer "In11.Cu")
		(net "M_H_CPU0_SA_DQS_DN<6>")
	)
	(segment
		(start 426.863002 -308.22265)
		(end 426.233844 -308.851808)
		(width 0.18288)
		(layer "In11.Cu")
		(net "M_H_CPU0_SA_DQS_DN<6>")
	)
	(segment
		(start 411.00248 -307.84292)
		(end 410.87802 -307.71846)
		(width 0.18288)
		(layer "In11.Cu")
		(net "M_H_CPU0_SA_DQS_DN<6>")
	)
	(segment
		(start 420.441882 -309.94096)
		(end 420.200836 -309.699914)
		(width 0.18288)
		(layer "In11.Cu")
		(net "M_H_CPU0_SA_DQS_DN<6>")
	)
	(segment
		(start 421.228774 -309.676292)
		(end 420.964106 -309.94096)
		(width 0.18288)
		(layer "In11.Cu")
		(net "M_H_CPU0_SA_DQS_DN<6>")
	)
	(segment
		(start 419.465506 -309.699914)
		(end 419.061138 -309.2958)
		(width 0.18288)
		(layer "In11.Cu")
		(net "M_H_CPU0_SA_DQS_DN<6>")
	)
	(segment
		(start 438.70626 -308.97703)
		(end 438.15762 -308.97703)
		(width 0.18288)
		(layer "In11.Cu")
		(net "M_H_CPU0_SA_DQS_DN<6>")
	)
	(segment
		(start 410.32938 -307.71846)
		(end 410.20492 -307.84292)
		(width 0.18288)
		(layer "In11.Cu")
		(net "M_H_CPU0_SA_DQS_DN<6>")
	)
	(segment
		(start 424.30827 -308.857142)
		(end 423.75963 -308.857142)
		(width 0.18288)
		(layer "In11.Cu")
		(net "M_H_CPU0_SA_DQS_DN<6>")
	)
	(segment
		(start 374.289574 -275.482812)
		(end 374.112028 -275.34997)
		(width 0.088646)
		(layer "In11.Cu")
		(net "M_H_CPU0_SA_DQS_DN<6>")
	)
	(segment
		(start 374.079516 -275.323554)
		(end 373.925846 -275.21916)
		(width 0.088646)
		(layer "In11.Cu")
		(net "M_H_CPU0_SA_DQS_DN<6>")
	)
	(segment
		(start 450.814186 -302.291242)
		(end 450.701918 -302.291242)
		(width 0.18288)
		(layer "In11.Cu")
		(net "M_H_CPU0_SA_DQS_DN<6>")
	)
	(segment
		(start 425.303188 -308.851808)
		(end 425.064174 -309.090822)
		(width 0.18288)
		(layer "In11.Cu")
		(net "M_H_CPU0_SA_DQS_DN<6>")
	)
	(segment
		(start 417.259262 -308.123336)
		(end 416.138868 -307.002942)
		(width 0.18288)
		(layer "In11.Cu")
		(net "M_H_CPU0_SA_DQS_DN<6>")
	)
	(segment
		(start 378.214128 -278.832056)
		(end 378.203714 -278.82596)
		(width 0.088646)
		(layer "In11.Cu")
		(net "M_H_CPU0_SA_DQS_DN<6>")
	)
	(segment
		(start 402.503132 -303.92243)
		(end 402.503132 -300.367954)
		(width 0.18288)
		(layer "In11.Cu")
		(net "M_H_CPU0_SA_DQS_DN<6>")
	)
	(segment
		(start 433.826666 -308.004464)
		(end 433.278026 -308.004464)
		(width 0.18288)
		(layer "In11.Cu")
		(net "M_H_CPU0_SA_DQS_DN<6>")
	)
	(segment
		(start 386.862066 -281.919172)
		(end 386.269738 -281.326844)
		(width 0.088646)
		(layer "In11.Cu")
		(net "M_H_CPU0_SA_DQS_DN<6>")
	)
	(segment
		(start 421.49395 -309.676292)
		(end 421.228774 -309.676292)
		(width 0.18288)
		(layer "In11.Cu")
		(net "M_H_CPU0_SA_DQS_DN<6>")
	)
	(segment
		(start 432.480466 -308.004464)
		(end 431.931826 -308.004464)
		(width 0.18288)
		(layer "In11.Cu")
		(net "M_H_CPU0_SA_DQS_DN<6>")
	)
	(segment
		(start 451.663562 -302.026574)
		(end 451.403974 -302.026574)
		(width 0.18288)
		(layer "In11.Cu")
		(net "M_H_CPU0_SA_DQS_DN<6>")
	)
	(segment
		(start 425.064174 -309.090822)
		(end 424.54195 -309.090822)
		(width 0.18288)
		(layer "In11.Cu")
		(net "M_H_CPU0_SA_DQS_DN<6>")
	)
	(segment
		(start 376.981466 -278.351996)
		(end 376.981466 -278.336502)
		(width 0.088646)
		(layer "In11.Cu")
		(net "M_H_CPU0_SA_DQS_DN<6>")
	)
	(segment
		(start 448.228212 -303.163478)
		(end 448.228212 -304.018442)
		(width 0.18288)
		(layer "In11.Cu")
		(net "M_H_CPU0_SA_DQS_DN<6>")
	)
	(segment
		(start 419.061138 -309.2958)
		(end 418.885116 -309.2958)
		(width 0.18288)
		(layer "In11.Cu")
		(net "M_H_CPU0_SA_DQS_DN<6>")
	)
	(segment
		(start 374.081548 -275.326856)
		(end 374.079516 -275.323554)
		(width 0.088646)
		(layer "In11.Cu")
		(net "M_H_CPU0_SA_DQS_DN<6>")
	)
	(segment
		(start 436.26913 -307.992526)
		(end 436.020718 -308.240938)
		(width 0.18288)
		(layer "In11.Cu")
		(net "M_H_CPU0_SA_DQS_DN<6>")
	)
	(segment
		(start 447.250312 -304.705766)
		(end 446.285112 -305.670966)
		(width 0.18288)
		(layer "In11.Cu")
		(net "M_H_CPU0_SA_DQS_DN<6>")
	)
	(segment
		(start 438.03316 -308.85257)
		(end 437.351424 -308.85257)
		(width 0.18288)
		(layer "In11.Cu")
		(net "M_H_CPU0_SA_DQS_DN<6>")
	)
	(segment
		(start 442.599318 -307.783992)
		(end 441.821062 -307.783992)
		(width 0.18288)
		(layer "In11.Cu")
		(net "M_H_CPU0_SA_DQS_DN<6>")
	)
	(segment
		(start 436.49138 -307.992526)
		(end 436.26913 -307.992526)
		(width 0.18288)
		(layer "In11.Cu")
		(net "M_H_CPU0_SA_DQS_DN<6>")
	)
	(segment
		(start 417.888166 -308.123336)
		(end 417.259262 -308.123336)
		(width 0.18288)
		(layer "In11.Cu")
		(net "M_H_CPU0_SA_DQS_DN<6>")
	)
	(segment
		(start 386.186172 -281.263852)
		(end 386.185664 -281.264106)
		(width 0.088646)
		(layer "In11.Cu")
		(net "M_H_CPU0_SA_DQS_DN<6>")
	)
	(segment
		(start 405.172672 -306.259484)
		(end 404.840186 -306.259484)
		(width 0.18288)
		(layer "In11.Cu")
		(net "M_H_CPU0_SA_DQS_DN<6>")
	)
	(segment
		(start 452.250302 -302.613314)
		(end 451.663562 -302.026574)
		(width 0.18288)
		(layer "In11.Cu")
		(net "M_H_CPU0_SA_DQS_DN<6>")
	)
	(segment
		(start 377.829318 -278.82596)
		(end 377.818904 -278.832056)
		(width 0.088646)
		(layer "In11.Cu")
		(net "M_H_CPU0_SA_DQS_DN<6>")
	)
	(segment
		(start 402.503132 -300.367954)
		(end 394.33373 -292.198552)
		(width 0.18288)
		(layer "In11.Cu")
		(net "M_H_CPU0_SA_DQS_DN<6>")
	)
	(segment
		(start 411.55112 -307.84292)
		(end 411.00248 -307.84292)
		(width 0.18288)
		(layer "In11.Cu")
		(net "M_H_CPU0_SA_DQS_DN<6>")
	)
	(segment
		(start 407.920444 -307.22824)
		(end 407.744422 -307.22824)
		(width 0.18288)
		(layer "In11.Cu")
		(net "M_H_CPU0_SA_DQS_DN<6>")
	)
	(segment
		(start 420.964106 -309.94096)
		(end 420.441882 -309.94096)
		(width 0.18288)
		(layer "In11.Cu")
		(net "M_H_CPU0_SA_DQS_DN<6>")
	)
	(segment
		(start 443.315344 -307.067966)
		(end 442.599318 -307.783992)
		(width 0.18288)
		(layer "In11.Cu")
		(net "M_H_CPU0_SA_DQS_DN<6>")
	)
	(segment
		(start 451.403974 -302.026574)
		(end 451.139306 -302.291242)
		(width 0.18288)
		(layer "In11.Cu")
		(net "M_H_CPU0_SA_DQS_DN<6>")
	)
	(segment
		(start 424.54195 -309.090822)
		(end 424.30827 -308.857142)
		(width 0.18288)
		(layer "In11.Cu")
		(net "M_H_CPU0_SA_DQS_DN<6>")
	)
	(segment
		(start 374.088914 -275.326856)
		(end 374.081548 -275.326856)
		(width 0.088646)
		(layer "In11.Cu")
		(net "M_H_CPU0_SA_DQS_DN<6>")
	)
	(segment
		(start 406.968452 -306.276248)
		(end 406.115012 -306.276248)
		(width 0.18288)
		(layer "In11.Cu")
		(net "M_H_CPU0_SA_DQS_DN<6>")
	)
	(segment
		(start 427.603412 -308.22265)
		(end 426.863002 -308.22265)
		(width 0.18288)
		(layer "In11.Cu")
		(net "M_H_CPU0_SA_DQS_DN<6>")
	)
	(segment
		(start 405.850852 -306.540408)
		(end 405.453596 -306.540408)
		(width 0.18288)
		(layer "In11.Cu")
		(net "M_H_CPU0_SA_DQS_DN<6>")
	)
	(segment
		(start 455.011282 -302.716692)
		(end 454.735692 -302.441102)
		(width 0.18288)
		(layer "In11.Cu")
		(net "M_H_CPU0_SA_DQS_DN<6>")
	)
	(segment
		(start 410.87802 -307.71846)
		(end 410.32938 -307.71846)
		(width 0.18288)
		(layer "In11.Cu")
		(net "M_H_CPU0_SA_DQS_DN<6>")
	)
	(segment
		(start 416.138868 -307.002942)
		(end 415.52241 -307.002942)
		(width 0.18288)
		(layer "In11.Cu")
		(net "M_H_CPU0_SA_DQS_DN<6>")
	)
	(segment
		(start 435.378352 -308.004464)
		(end 434.624226 -308.004464)
		(width 0.18288)
		(layer "In11.Cu")
		(net "M_H_CPU0_SA_DQS_DN<6>")
	)
	(segment
		(start 454.735692 -302.441102)
		(end 454.462388 -302.441102)
		(width 0.18288)
		(layer "In11.Cu")
		(net "M_H_CPU0_SA_DQS_DN<6>")
	)
	(segment
		(start 386.862066 -282.544266)
		(end 386.862066 -281.919172)
		(width 0.088646)
		(layer "In11.Cu")
		(net "M_H_CPU0_SA_DQS_DN<6>")
	)
	(segment
		(start 403.484588 -304.903886)
		(end 402.503132 -303.92243)
		(width 0.18288)
		(layer "In11.Cu")
		(net "M_H_CPU0_SA_DQS_DN<6>")
	)
	(segment
		(start 384.499612 -279.982676)
		(end 384.499612 -279.964134)
		(width 0.088646)
		(layer "In11.Cu")
		(net "M_H_CPU0_SA_DQS_DN<6>")
	)
	(segment
		(start 415.39795 -307.127402)
		(end 414.84931 -307.127402)
		(width 0.18288)
		(layer "In11.Cu")
		(net "M_H_CPU0_SA_DQS_DN<6>")
	)
	(segment
		(start 394.33373 -292.198552)
		(end 394.33373 -290.675314)
		(width 0.18288)
		(layer "In11.Cu")
		(net "M_H_CPU0_SA_DQS_DN<6>")
	)
	(segment
		(start 441.821062 -307.783992)
		(end 440.774836 -308.830218)
		(width 0.18288)
		(layer "In11.Cu")
		(net "M_H_CPU0_SA_DQS_DN<6>")
	)
	(segment
		(start 422.96207 -308.857142)
		(end 422.3131 -308.857142)
		(width 0.18288)
		(layer "In11.Cu")
		(net "M_H_CPU0_SA_DQS_DN<6>")
	)
	(segment
		(start 432.604926 -308.128924)
		(end 432.480466 -308.004464)
		(width 0.18288)
		(layer "In11.Cu")
		(net "M_H_CPU0_SA_DQS_DN<6>")
	)
	(segment
		(start 420.200836 -309.699914)
		(end 419.465506 -309.699914)
		(width 0.18288)
		(layer "In11.Cu")
		(net "M_H_CPU0_SA_DQS_DN<6>")
	)
	(segment
		(start 407.35631 -306.840128)
		(end 407.35631 -306.664106)
		(width 0.18288)
		(layer "In11.Cu")
		(net "M_H_CPU0_SA_DQS_DN<6>")
	)
	(segment
		(start 436.020718 -308.240938)
		(end 435.614826 -308.240938)
		(width 0.18288)
		(layer "In11.Cu")
		(net "M_H_CPU0_SA_DQS_DN<6>")
	)
	(segment
		(start 448.228212 -304.018442)
		(end 447.540888 -304.705766)
		(width 0.18288)
		(layer "In11.Cu")
		(net "M_H_CPU0_SA_DQS_DN<6>")
	)
	(segment
		(start 394.33373 -290.675314)
		(end 387.939788 -284.281372)
		(width 0.18288)
		(layer "In11.Cu")
		(net "M_H_CPU0_SA_DQS_DN<6>")
	)
	(segment
		(start 407.744422 -307.22824)
		(end 407.35631 -306.840128)
		(width 0.18288)
		(layer "In11.Cu")
		(net "M_H_CPU0_SA_DQS_DN<6>")
	)
	(segment
		(start 423.63517 -308.981602)
		(end 423.08653 -308.981602)
		(width 0.18288)
		(layer "In11.Cu")
		(net "M_H_CPU0_SA_DQS_DN<6>")
	)
	(segment
		(start 446.285112 -305.670966)
		(end 445.356488 -305.670966)
		(width 0.18288)
		(layer "In11.Cu")
		(net "M_H_CPU0_SA_DQS_DN<6>")
	)
	(segment
		(start 452.923402 -302.737774)
		(end 452.798942 -302.613314)
		(width 0.18288)
		(layer "In11.Cu")
		(net "M_H_CPU0_SA_DQS_DN<6>")
	)
	(segment
		(start 431.108104 -308.828186)
		(end 429.626522 -308.828186)
		(width 0.18288)
		(layer "In11.Cu")
		(net "M_H_CPU0_SA_DQS_DN<6>")
	)
	(segment
		(start 429.626522 -308.828186)
		(end 429.502062 -308.952646)
		(width 0.18288)
		(layer "In11.Cu")
		(net "M_H_CPU0_SA_DQS_DN<6>")
	)
	(segment
		(start 434.499766 -308.128924)
		(end 433.951126 -308.128924)
		(width 0.18288)
		(layer "In11.Cu")
		(net "M_H_CPU0_SA_DQS_DN<6>")
	)
	(segment
		(start 387.939788 -284.281372)
		(end 387.939788 -283.87167)
		(width 0.18288)
		(layer "In11.Cu")
		(net "M_H_CPU0_SA_DQS_DN<6>")
	)
	(segment
		(start 404.840186 -306.259484)
		(end 404.048976 -305.468274)
		(width 0.18288)
		(layer "In11.Cu")
		(net "M_H_CPU0_SA_DQS_DN<6>")
	)
	(segment
		(start 375.571512 -277.536656)
		(end 375.571512 -277.522432)
		(width 0.088646)
		(layer "In11.Cu")
		(net "M_H_CPU0_SA_DQS_DN<6>")
	)
	(segment
		(start 438.83072 -308.85257)
		(end 438.70626 -308.97703)
		(width 0.18288)
		(layer "In11.Cu")
		(net "M_H_CPU0_SA_DQS_DN<6>")
	)
	(segment
		(start 404.048976 -305.468274)
		(end 403.872954 -305.468274)
		(width 0.18288)
		(layer "In11.Cu")
		(net "M_H_CPU0_SA_DQS_DN<6>")
	)
	(segment
		(start 418.49675 -308.731666)
		(end 417.888166 -308.123336)
		(width 0.18288)
		(layer "In11.Cu")
		(net "M_H_CPU0_SA_DQS_DN<6>")
	)
	(segment
		(start 388.00024 -283.68244)
		(end 386.862066 -282.544266)
		(width 0.088646)
		(layer "In11.Cu")
		(net "M_H_CPU0_SA_DQS_DN<6>")
	)
	(segment
		(start 414.72485 -307.002942)
		(end 412.973774 -307.002942)
		(width 0.18288)
		(layer "In11.Cu")
		(net "M_H_CPU0_SA_DQS_DN<6>")
	)
	(segment
		(start 403.484588 -305.079908)
		(end 403.484588 -304.903886)
		(width 0.18288)
		(layer "In11.Cu")
		(net "M_H_CPU0_SA_DQS_DN<6>")
	)
	(segment
		(start 439.391298 -308.85257)
		(end 438.83072 -308.85257)
		(width 0.18288)
		(layer "In11.Cu")
		(net "M_H_CPU0_SA_DQS_DN<6>")
	)
	(segment
		(start 435.614826 -308.240938)
		(end 435.378352 -308.004464)
		(width 0.18288)
		(layer "In11.Cu")
		(net "M_H_CPU0_SA_DQS_DN<6>")
	)
	(segment
		(start 418.497004 -308.907688)
		(end 418.49675 -308.731666)
		(width 0.18288)
		(layer "In11.Cu")
		(net "M_H_CPU0_SA_DQS_DN<6>")
	)
	(segment
		(start 384.32105 -279.644856)
		(end 384.31216 -279.639776)
		(width 0.088646)
		(layer "In11.Cu")
		(net "M_H_CPU0_SA_DQS_DN<6>")
	)
	(segment
		(start 433.278026 -308.004464)
		(end 433.153566 -308.128924)
		(width 0.18288)
		(layer "In11.Cu")
		(net "M_H_CPU0_SA_DQS_DN<6>")
	)
	(segment
		(start 454.290176 -302.613314)
		(end 453.596502 -302.613314)
		(width 0.18288)
		(layer "In11.Cu")
		(net "M_H_CPU0_SA_DQS_DN<6>")
	)
	(segment
		(start 375.101866 -276.72411)
		(end 375.101866 -276.708616)
		(width 0.088646)
		(layer "In11.Cu")
		(net "M_H_CPU0_SA_DQS_DN<6>")
	)
	(segment
		(start 405.453596 -306.540408)
		(end 405.172672 -306.259484)
		(width 0.18288)
		(layer "In11.Cu")
		(net "M_H_CPU0_SA_DQS_DN<6>")
	)
	(segment
		(start 433.153566 -308.128924)
		(end 432.604926 -308.128924)
		(width 0.18288)
		(layer "In11.Cu")
		(net "M_H_CPU0_SA_DQS_DN<6>")
	)
	(segment
		(start 447.540888 -304.705766)
		(end 447.250312 -304.705766)
		(width 0.18288)
		(layer "In11.Cu")
		(net "M_H_CPU0_SA_DQS_DN<6>")
	)
	(segment
		(start 429.502062 -308.952646)
		(end 428.953422 -308.952646)
		(width 0.18288)
		(layer "In11.Cu")
		(net "M_H_CPU0_SA_DQS_DN<6>")
	)
	(segment
		(start 438.15762 -308.97703)
		(end 438.03316 -308.85257)
		(width 0.18288)
		(layer "In11.Cu")
		(net "M_H_CPU0_SA_DQS_DN<6>")
	)
	(segment
		(start 384.029712 -279.160224)
		(end 384.029712 -279.150318)
		(width 0.088646)
		(layer "In11.Cu")
		(net "M_H_CPU0_SA_DQS_DN<6>")
	)
	(segment
		(start 428.208948 -308.828186)
		(end 427.603412 -308.22265)
		(width 0.18288)
		(layer "In11.Cu")
		(net "M_H_CPU0_SA_DQS_DN<6>")
	)
	(segment
		(start 409.53182 -307.71846)
		(end 408.410664 -307.71846)
		(width 0.18288)
		(layer "In11.Cu")
		(net "M_H_CPU0_SA_DQS_DN<6>")
	)
	(segment
		(start 437.351424 -308.85257)
		(end 436.49138 -307.992526)
		(width 0.18288)
		(layer "In11.Cu")
		(net "M_H_CPU0_SA_DQS_DN<6>")
	)
	(segment
		(start 454.462388 -302.441102)
		(end 454.290176 -302.613314)
		(width 0.18288)
		(layer "In11.Cu")
		(net "M_H_CPU0_SA_DQS_DN<6>")
	)
	(segment
		(start 374.45315 -275.575522)
		(end 374.43791 -275.566124)
		(width 0.088646)
		(layer "In11.Cu")
		(net "M_H_CPU0_SA_DQS_DN<6>")
	)
	(segment
		(start 375.39295 -277.203154)
		(end 375.38406 -277.198074)
		(width 0.088646)
		(layer "In11.Cu")
		(net "M_H_CPU0_SA_DQS_DN<6>")
	)
	(segment
		(start 450.431662 -302.020986)
		(end 449.370704 -302.020986)
		(width 0.18288)
		(layer "In11.Cu")
		(net "M_H_CPU0_SA_DQS_DN<6>")
	)
	(segment
		(start 422.3131 -308.857142)
		(end 421.49395 -309.676292)
		(width 0.18288)
		(layer "In11.Cu")
		(net "M_H_CPU0_SA_DQS_DN<6>")
	)
	(segment
		(start 409.65628 -307.84292)
		(end 409.53182 -307.71846)
		(width 0.18288)
		(layer "In11.Cu")
		(net "M_H_CPU0_SA_DQS_DN<6>")
	)
	(segment
		(start 451.139306 -302.291242)
		(end 450.991732 -302.291242)
		(width 0.18288)
		(layer "In11.Cu")
		(net "M_H_CPU0_SA_DQS_DN<6>")
	)
	(segment
		(start 426.233844 -308.851808)
		(end 425.303188 -308.851808)
		(width 0.18288)
		(layer "In11.Cu")
		(net "M_H_CPU0_SA_DQS_DN<6>")
	)
	(segment
		(start 431.931826 -308.004464)
		(end 431.108104 -308.828186)
		(width 0.18288)
		(layer "In11.Cu")
		(net "M_H_CPU0_SA_DQS_DN<6>")
	)
	(segment
		(start 388.00024 -283.811218)
		(end 388.00024 -283.68244)
		(width 0.088646)
		(layer "In11.Cu")
		(net "M_H_CPU0_SA_DQS_DN<6>")
	)
	(segment
		(start 381.588264 -278.82596)
		(end 381.57785 -278.832056)
		(width 0.088646)
		(layer "In11.Cu")
		(net "M_H_CPU0_SA_DQS_DN<6>")
	)
	(segment
		(start 428.953422 -308.952646)
		(end 428.828962 -308.828186)
		(width 0.18288)
		(layer "In11.Cu")
		(net "M_H_CPU0_SA_DQS_DN<6>")
	)
	(segment
		(start 449.370704 -302.020986)
		(end 448.228212 -303.163478)
		(width 0.18288)
		(layer "In11.Cu")
		(net "M_H_CPU0_SA_DQS_DN<6>")
	)
	(segment
		(start 408.410664 -307.71846)
		(end 407.920444 -307.22824)
		(width 0.18288)
		(layer "In11.Cu")
		(net "M_H_CPU0_SA_DQS_DN<6>")
	)
	(segment
		(start 440.151774 -309.090822)
		(end 439.62955 -309.090822)
		(width 0.18288)
		(layer "In11.Cu")
		(net "M_H_CPU0_SA_DQS_DN<6>")
	)
	(segment
		(start 387.939788 -283.87167)
		(end 388.00024 -283.811218)
		(width 0.088646)
		(layer "In11.Cu")
		(net "M_H_CPU0_SA_DQS_DN<6>")
	)
	(segment
		(start 411.67558 -307.71846)
		(end 411.55112 -307.84292)
		(width 0.18288)
		(layer "In11.Cu")
		(net "M_H_CPU0_SA_DQS_DN<6>")
	)
	(segment
		(start 439.62955 -309.090822)
		(end 439.391298 -308.85257)
		(width 0.18288)
		(layer "In11.Cu")
		(net "M_H_CPU0_SA_DQS_DN<6>")
	)
	(segment
		(start 414.84931 -307.127402)
		(end 414.72485 -307.002942)
		(width 0.18288)
		(layer "In11.Cu")
		(net "M_H_CPU0_SA_DQS_DN<6>")
	)
	(segment
		(start 406.115012 -306.276248)
		(end 405.850852 -306.540408)
		(width 0.18288)
		(layer "In11.Cu")
		(net "M_H_CPU0_SA_DQS_DN<6>")
	)
	(segment
		(start 410.20492 -307.84292)
		(end 409.65628 -307.84292)
		(width 0.18288)
		(layer "In11.Cu")
		(net "M_H_CPU0_SA_DQS_DN<6>")
	)
	(segment
		(start 428.828962 -308.828186)
		(end 428.208948 -308.828186)
		(width 0.18288)
		(layer "In11.Cu")
		(net "M_H_CPU0_SA_DQS_DN<6>")
	)
	(segment
		(start 374.112028 -275.34997)
		(end 374.088914 -275.326856)
		(width 0.088646)
		(layer "In11.Cu")
		(net "M_H_CPU0_SA_DQS_DN<6>")
	)
	(segment
		(start 412.258256 -307.71846)
		(end 411.67558 -307.71846)
		(width 0.18288)
		(layer "In11.Cu")
		(net "M_H_CPU0_SA_DQS_DN<6>")
	)
	(segment
		(start 440.412378 -308.830218)
		(end 440.151774 -309.090822)
		(width 0.18288)
		(layer "In11.Cu")
		(net "M_H_CPU0_SA_DQS_DN<6>")
	)
	(segment
		(start 418.885116 -309.2958)
		(end 418.497004 -308.907688)
		(width 0.18288)
		(layer "In11.Cu")
		(net "M_H_CPU0_SA_DQS_DN<6>")
	)
	(segment
		(start 450.701918 -302.291242)
		(end 450.431662 -302.020986)
		(width 0.18288)
		(layer "In11.Cu")
		(net "M_H_CPU0_SA_DQS_DN<6>")
	)
	(segment
		(start 407.35631 -306.664106)
		(end 406.968452 -306.276248)
		(width 0.18288)
		(layer "In11.Cu")
		(net "M_H_CPU0_SA_DQS_DN<6>")
	)
	(segment
		(start 403.872954 -305.468274)
		(end 403.484588 -305.079908)
		(width 0.18288)
		(layer "In11.Cu")
		(net "M_H_CPU0_SA_DQS_DN<6>")
	)
	(segment
		(start 373.925846 -275.21916)
		(end 373.787416 -275.08073)
		(width 0.088646)
		(layer "In11.Cu")
		(net "M_H_CPU0_SA_DQS_DN<6>")
	)
	(segment
		(start 445.356488 -305.670966)
		(end 443.959488 -307.067966)
		(width 0.18288)
		(layer "In11.Cu")
		(net "M_H_CPU0_SA_DQS_DN<6>")
	)
	(segment
		(start 423.75963 -308.857142)
		(end 423.63517 -308.981602)
		(width 0.18288)
		(layer "In11.Cu")
		(net "M_H_CPU0_SA_DQS_DN<6>")
	)
	(arc
		(start 376.981466 -278.336502)
		(mid 376.794167 -278.012061)
		(end 376.419618 -278.012144)
		(width 0.088646)
		(layer "In11.Cu")
		(net "M_H_CPU0_SA_DQS_DN<6>")
	)
	(arc
		(start 380.083314 -278.82596)
		(mid 379.896116 -278.775817)
		(end 379.708918 -278.82596)
		(width 0.088646)
		(layer "In11.Cu")
		(net "M_H_CPU0_SA_DQS_DN<6>")
	)
	(arc
		(start 384.029712 -279.150318)
		(mid 383.842413 -278.825877)
		(end 383.467864 -278.82596)
		(width 0.088646)
		(layer "In11.Cu")
		(net "M_H_CPU0_SA_DQS_DN<6>")
	)
	(arc
		(start 379.698504 -278.832056)
		(mid 379.420072 -278.901902)
		(end 379.14326 -278.82596)
		(width 0.088646)
		(layer "In11.Cu")
		(net "M_H_CPU0_SA_DQS_DN<6>")
	)
	(arc
		(start 384.31216 -279.639776)
		(mid 384.107825 -279.437171)
		(end 384.029712 -279.160224)
		(width 0.088646)
		(layer "In11.Cu")
		(net "M_H_CPU0_SA_DQS_DN<6>")
	)
	(arc
		(start 378.768864 -278.82596)
		(mid 378.492305 -278.901703)
		(end 378.214128 -278.832056)
		(width 0.088646)
		(layer "In11.Cu")
		(net "M_H_CPU0_SA_DQS_DN<6>")
	)
	(arc
		(start 384.499612 -279.964134)
		(mid 384.451933 -279.781234)
		(end 384.32105 -279.644856)
		(width 0.088646)
		(layer "In11.Cu")
		(net "M_H_CPU0_SA_DQS_DN<6>")
	)
	(arc
		(start 382.528064 -278.82596)
		(mid 382.245362 -278.901736)
		(end 381.96266 -278.82596)
		(width 0.088646)
		(layer "In11.Cu")
		(net "M_H_CPU0_SA_DQS_DN<6>")
	)
	(arc
		(start 385.909312 -280.778204)
		(mid 385.722013 -280.453763)
		(end 385.347464 -280.453846)
		(width 0.088646)
		(layer "In11.Cu")
		(net "M_H_CPU0_SA_DQS_DN<6>")
	)
	(arc
		(start 376.419618 -278.012144)
		(mid 375.860192 -278.015837)
		(end 375.571512 -277.536656)
		(width 0.088646)
		(layer "In11.Cu")
		(net "M_H_CPU0_SA_DQS_DN<6>")
	)
	(arc
		(start 381.57785 -278.832056)
		(mid 381.299672 -278.901779)
		(end 381.023114 -278.82596)
		(width 0.088646)
		(layer "In11.Cu")
		(net "M_H_CPU0_SA_DQS_DN<6>")
	)
	(arc
		(start 378.203714 -278.82596)
		(mid 378.016516 -278.775817)
		(end 377.829318 -278.82596)
		(width 0.088646)
		(layer "In11.Cu")
		(net "M_H_CPU0_SA_DQS_DN<6>")
	)
	(arc
		(start 383.467864 -278.82596)
		(mid 383.185162 -278.901736)
		(end 382.90246 -278.82596)
		(width 0.088646)
		(layer "In11.Cu")
		(net "M_H_CPU0_SA_DQS_DN<6>")
	)
	(arc
		(start 377.818904 -278.832056)
		(mid 377.265429 -278.827061)
		(end 376.981466 -278.351996)
		(width 0.088646)
		(layer "In11.Cu")
		(net "M_H_CPU0_SA_DQS_DN<6>")
	)
	(arc
		(start 382.90246 -278.82596)
		(mid 382.715262 -278.775817)
		(end 382.528064 -278.82596)
		(width 0.088646)
		(layer "In11.Cu")
		(net "M_H_CPU0_SA_DQS_DN<6>")
	)
	(arc
		(start 386.185664 -281.264106)
		(mid 385.983251 -281.057693)
		(end 385.909312 -280.778204)
		(width 0.088646)
		(layer "In11.Cu")
		(net "M_H_CPU0_SA_DQS_DN<6>")
	)
	(arc
		(start 385.347464 -280.453846)
		(mid 384.79009 -280.458395)
		(end 384.499612 -279.982676)
		(width 0.088646)
		(layer "In11.Cu")
		(net "M_H_CPU0_SA_DQS_DN<6>")
	)
	(arc
		(start 374.631712 -275.8948)
		(mid 374.584033 -275.7119)
		(end 374.45315 -275.575522)
		(width 0.088646)
		(layer "In11.Cu")
		(net "M_H_CPU0_SA_DQS_DN<6>")
	)
	(arc
		(start 375.101866 -276.708616)
		(mid 375.054187 -276.525716)
		(end 374.923304 -276.389338)
		(width 0.088646)
		(layer "In11.Cu")
		(net "M_H_CPU0_SA_DQS_DN<6>")
	)
	(arc
		(start 374.908318 -276.380702)
		(mid 374.705731 -276.174351)
		(end 374.631712 -275.8948)
		(width 0.088646)
		(layer "In11.Cu")
		(net "M_H_CPU0_SA_DQS_DN<6>")
	)
	(arc
		(start 381.023114 -278.82596)
		(mid 380.835916 -278.775817)
		(end 380.648718 -278.82596)
		(width 0.088646)
		(layer "In11.Cu")
		(net "M_H_CPU0_SA_DQS_DN<6>")
	)
	(arc
		(start 375.38406 -277.198074)
		(mid 375.181237 -276.997843)
		(end 375.101866 -276.72411)
		(width 0.088646)
		(layer "In11.Cu")
		(net "M_H_CPU0_SA_DQS_DN<6>")
	)
	(arc
		(start 381.96266 -278.82596)
		(mid 381.775462 -278.775817)
		(end 381.588264 -278.82596)
		(width 0.088646)
		(layer "In11.Cu")
		(net "M_H_CPU0_SA_DQS_DN<6>")
	)
	(arc
		(start 386.269738 -281.326844)
		(mid 386.230163 -281.292419)
		(end 386.186172 -281.263852)
		(width 0.088646)
		(layer "In11.Cu")
		(net "M_H_CPU0_SA_DQS_DN<6>")
	)
	(arc
		(start 379.14326 -278.82596)
		(mid 378.956062 -278.775817)
		(end 378.768864 -278.82596)
		(width 0.088646)
		(layer "In11.Cu")
		(net "M_H_CPU0_SA_DQS_DN<6>")
	)
	(arc
		(start 375.571512 -277.522432)
		(mid 375.523833 -277.339532)
		(end 375.39295 -277.203154)
		(width 0.088646)
		(layer "In11.Cu")
		(net "M_H_CPU0_SA_DQS_DN<6>")
	)
	(arc
		(start 380.648718 -278.82596)
		(mid 380.366016 -278.901736)
		(end 380.083314 -278.82596)
		(width 0.088646)
		(layer "In11.Cu")
		(net "M_H_CPU0_SA_DQS_DN<6>")
	)
	(segment
		(start 457.401422 -311.795414)
		(end 457.826364 -311.370472)
		(width 0.20066)
		(layer "F.Cu")
		(net "M_H_CPU0_SA_DQS_DN<5>")
	)
	(segment
		(start 460.570326 -311.652666)
		(end 460.889096 -311.652666)
		(width 0.20066)
		(layer "F.Cu")
		(net "M_H_CPU0_SA_DQS_DN<5>")
	)
	(segment
		(start 460.889096 -311.652666)
		(end 461.174846 -311.366916)
		(width 0.20066)
		(layer "F.Cu")
		(net "M_H_CPU0_SA_DQS_DN<5>")
	)
	(segment
		(start 458.549248 -311.641744)
		(end 460.559404 -311.641744)
		(width 0.1016)
		(layer "F.Cu")
		(net "M_H_CPU0_SA_DQS_DN<5>")
	)
	(segment
		(start 377.076716 -277.522178)
		(end 377.076462 -277.522432)
		(width 0.20066)
		(layer "F.Cu")
		(net "M_H_CPU0_SA_DQS_DN<5>")
	)
	(segment
		(start 456.646788 -312.066686)
		(end 456.91806 -311.795414)
		(width 0.20066)
		(layer "F.Cu")
		(net "M_H_CPU0_SA_DQS_DN<5>")
	)
	(segment
		(start 458.22616 -311.64784)
		(end 458.538326 -311.64784)
		(width 0.20066)
		(layer "F.Cu")
		(net "M_H_CPU0_SA_DQS_DN<5>")
	)
	(segment
		(start 458.538326 -311.64784)
		(end 458.543152 -311.64784)
		(width 0.101854)
		(layer "F.Cu")
		(net "M_H_CPU0_SA_DQS_DN<5>")
	)
	(segment
		(start 461.174846 -311.366916)
		(end 461.664812 -311.366916)
		(width 0.20066)
		(layer "F.Cu")
		(net "M_H_CPU0_SA_DQS_DN<5>")
	)
	(segment
		(start 457.948792 -311.370472)
		(end 458.22616 -311.64784)
		(width 0.20066)
		(layer "F.Cu")
		(net "M_H_CPU0_SA_DQS_DN<5>")
	)
	(segment
		(start 461.664812 -311.366916)
		(end 462.110328 -311.812432)
		(width 0.20066)
		(layer "F.Cu")
		(net "M_H_CPU0_SA_DQS_DN<5>")
	)
	(segment
		(start 462.902046 -311.812432)
		(end 463.1563 -312.066686)
		(width 0.20066)
		(layer "F.Cu")
		(net "M_H_CPU0_SA_DQS_DN<5>")
	)
	(segment
		(start 460.559404 -311.641744)
		(end 460.570326 -311.652666)
		(width 0.1016)
		(layer "F.Cu")
		(net "M_H_CPU0_SA_DQS_DN<5>")
	)
	(segment
		(start 463.1563 -312.066686)
		(end 463.659982 -312.066686)
		(width 0.20066)
		(layer "F.Cu")
		(net "M_H_CPU0_SA_DQS_DN<5>")
	)
	(segment
		(start 457.826364 -311.370472)
		(end 457.948792 -311.370472)
		(width 0.20066)
		(layer "F.Cu")
		(net "M_H_CPU0_SA_DQS_DN<5>")
	)
	(segment
		(start 456.116182 -312.066686)
		(end 456.646788 -312.066686)
		(width 0.20066)
		(layer "F.Cu")
		(net "M_H_CPU0_SA_DQS_DN<5>")
	)
	(segment
		(start 455.011282 -312.066686)
		(end 456.116182 -312.066686)
		(width 0.20066)
		(layer "F.Cu")
		(net "M_H_CPU0_SA_DQS_DN<5>")
	)
	(segment
		(start 456.91806 -311.795414)
		(end 457.401422 -311.795414)
		(width 0.20066)
		(layer "F.Cu")
		(net "M_H_CPU0_SA_DQS_DN<5>")
	)
	(segment
		(start 458.543152 -311.64784)
		(end 458.549248 -311.641744)
		(width 0.1016)
		(layer "F.Cu")
		(net "M_H_CPU0_SA_DQS_DN<5>")
	)
	(segment
		(start 377.076716 -276.986492)
		(end 377.076716 -277.522178)
		(width 0.20066)
		(layer "F.Cu")
		(net "M_H_CPU0_SA_DQS_DN<5>")
	)
	(segment
		(start 462.110328 -311.812432)
		(end 462.902046 -311.812432)
		(width 0.20066)
		(layer "F.Cu")
		(net "M_H_CPU0_SA_DQS_DN<5>")
	)
	(segment
		(start 438.868312 -310.5404)
		(end 438.743852 -310.66486)
		(width 0.18288)
		(layer "In6.Cu")
		(net "M_H_CPU0_SA_DQS_DN<5>")
	)
	(segment
		(start 441.816744 -311.158636)
		(end 441.176918 -310.51881)
		(width 0.18288)
		(layer "In6.Cu")
		(net "M_H_CPU0_SA_DQS_DN<5>")
	)
	(segment
		(start 416.769296 -308.027832)
		(end 415.86277 -307.121306)
		(width 0.18288)
		(layer "In6.Cu")
		(net "M_H_CPU0_SA_DQS_DN<5>")
	)
	(segment
		(start 432.672744 -311.369202)
		(end 432.156108 -311.369202)
		(width 0.18288)
		(layer "In6.Cu")
		(net "M_H_CPU0_SA_DQS_DN<5>")
	)
	(segment
		(start 418.40658 -308.027832)
		(end 418.28212 -308.152292)
		(width 0.18288)
		(layer "In6.Cu")
		(net "M_H_CPU0_SA_DQS_DN<5>")
	)
	(segment
		(start 412.05531 -304.701702)
		(end 411.879288 -304.701702)
		(width 0.18288)
		(layer "In6.Cu")
		(net "M_H_CPU0_SA_DQS_DN<5>")
	)
	(segment
		(start 417.73602 -308.152292)
		(end 417.61156 -308.027832)
		(width 0.18288)
		(layer "In6.Cu")
		(net "M_H_CPU0_SA_DQS_DN<5>")
	)
	(segment
		(start 377.7869 -277.22068)
		(end 377.786138 -277.221188)
		(width 0.088646)
		(layer "In6.Cu")
		(net "M_H_CPU0_SA_DQS_DN<5>")
	)
	(segment
		(start 396.60195 -283.27858)
		(end 393.623546 -280.300176)
		(width 0.18288)
		(layer "In6.Cu")
		(net "M_H_CPU0_SA_DQS_DN<5>")
	)
	(segment
		(start 435.626764 -311.640982)
		(end 435.354984 -311.369202)
		(width 0.18288)
		(layer "In6.Cu")
		(net "M_H_CPU0_SA_DQS_DN<5>")
	)
	(segment
		(start 385.909312 -277.540974)
		(end 385.909312 -277.522432)
		(width 0.088646)
		(layer "In6.Cu")
		(net "M_H_CPU0_SA_DQS_DN<5>")
	)
	(segment
		(start 434.138324 -311.493662)
		(end 434.013864 -311.369202)
		(width 0.18288)
		(layer "In6.Cu")
		(net "M_H_CPU0_SA_DQS_DN<5>")
	)
	(segment
		(start 425.030138 -307.391054)
		(end 424.644312 -307.391054)
		(width 0.18288)
		(layer "In6.Cu")
		(net "M_H_CPU0_SA_DQS_DN<5>")
	)
	(segment
		(start 454.73493 -311.790334)
		(end 454.043288 -311.790334)
		(width 0.18288)
		(layer "In6.Cu")
		(net "M_H_CPU0_SA_DQS_DN<5>")
	)
	(segment
		(start 420.273988 -308.027832)
		(end 419.7477 -308.027832)
		(width 0.18288)
		(layer "In6.Cu")
		(net "M_H_CPU0_SA_DQS_DN<5>")
	)
	(segment
		(start 417.61156 -308.027832)
		(end 416.769296 -308.027832)
		(width 0.18288)
		(layer "In6.Cu")
		(net "M_H_CPU0_SA_DQS_DN<5>")
	)
	(segment
		(start 438.197752 -310.66486)
		(end 438.073292 -310.5404)
		(width 0.18288)
		(layer "In6.Cu")
		(net "M_H_CPU0_SA_DQS_DN<5>")
	)
	(segment
		(start 404.884636 -304.59172)
		(end 404.470616 -304.1777)
		(width 0.18288)
		(layer "In6.Cu")
		(net "M_H_CPU0_SA_DQS_DN<5>")
	)
	(segment
		(start 423.634916 -307.259228)
		(end 423.088816 -307.259228)
		(width 0.18288)
		(layer "In6.Cu")
		(net "M_H_CPU0_SA_DQS_DN<5>")
	)
	(segment
		(start 406.994614 -304.58664)
		(end 406.088088 -304.58664)
		(width 0.18288)
		(layer "In6.Cu")
		(net "M_H_CPU0_SA_DQS_DN<5>")
	)
	(segment
		(start 440.098688 -310.791098)
		(end 439.716672 -310.791098)
		(width 0.18288)
		(layer "In6.Cu")
		(net "M_H_CPU0_SA_DQS_DN<5>")
	)
	(segment
		(start 388.283958 -280.0858)
		(end 388.224014 -280.025856)
		(width 0.088646)
		(layer "In6.Cu")
		(net "M_H_CPU0_SA_DQS_DN<5>")
	)
	(segment
		(start 386.20065 -278.017224)
		(end 386.19176 -278.012144)
		(width 0.088646)
		(layer "In6.Cu")
		(net "M_H_CPU0_SA_DQS_DN<5>")
	)
	(segment
		(start 377.786138 -277.221188)
		(end 377.77674 -277.226268)
		(width 0.088646)
		(layer "In6.Cu")
		(net "M_H_CPU0_SA_DQS_DN<5>")
	)
	(segment
		(start 377.914916 -277.158196)
		(end 377.869196 -277.177754)
		(width 0.088646)
		(layer "In6.Cu")
		(net "M_H_CPU0_SA_DQS_DN<5>")
	)
	(segment
		(start 431.227992 -310.441086)
		(end 430.276 -310.441086)
		(width 0.18288)
		(layer "In6.Cu")
		(net "M_H_CPU0_SA_DQS_DN<5>")
	)
	(segment
		(start 387.879336 -279.859486)
		(end 387.783832 -279.630124)
		(width 0.088646)
		(layer "In6.Cu")
		(net "M_H_CPU0_SA_DQS_DN<5>")
	)
	(segment
		(start 413.69107 -306.162456)
		(end 413.69107 -305.986434)
		(width 0.18288)
		(layer "In6.Cu")
		(net "M_H_CPU0_SA_DQS_DN<5>")
	)
	(segment
		(start 434.013864 -311.369202)
		(end 433.467764 -311.369202)
		(width 0.18288)
		(layer "In6.Cu")
		(net "M_H_CPU0_SA_DQS_DN<5>")
	)
	(segment
		(start 433.467764 -311.369202)
		(end 433.343304 -311.493662)
		(width 0.18288)
		(layer "In6.Cu")
		(net "M_H_CPU0_SA_DQS_DN<5>")
	)
	(segment
		(start 446.676018 -311.38114)
		(end 446.010284 -312.046874)
		(width 0.18288)
		(layer "In6.Cu")
		(net "M_H_CPU0_SA_DQS_DN<5>")
	)
	(segment
		(start 377.076462 -277.373334)
		(end 377.076462 -277.522432)
		(width 0.088646)
		(layer "In6.Cu")
		(net "M_H_CPU0_SA_DQS_DN<5>")
	)
	(segment
		(start 429.749712 -309.914798)
		(end 429.57369 -309.914798)
		(width 0.18288)
		(layer "In6.Cu")
		(net "M_H_CPU0_SA_DQS_DN<5>")
	)
	(segment
		(start 415.86277 -307.121306)
		(end 414.825942 -307.121306)
		(width 0.18288)
		(layer "In6.Cu")
		(net "M_H_CPU0_SA_DQS_DN<5>")
	)
	(segment
		(start 409.923742 -303.99101)
		(end 409.575 -303.99101)
		(width 0.18288)
		(layer "In6.Cu")
		(net "M_H_CPU0_SA_DQS_DN<5>")
	)
	(segment
		(start 377.252738 -277.289768)
		(end 377.13666 -277.313136)
		(width 0.088646)
		(layer "In6.Cu")
		(net "M_H_CPU0_SA_DQS_DN<5>")
	)
	(segment
		(start 419.62324 -308.152292)
		(end 419.07714 -308.152292)
		(width 0.18288)
		(layer "In6.Cu")
		(net "M_H_CPU0_SA_DQS_DN<5>")
	)
	(segment
		(start 420.916354 -308.241192)
		(end 420.487348 -308.241192)
		(width 0.18288)
		(layer "In6.Cu")
		(net "M_H_CPU0_SA_DQS_DN<5>")
	)
	(segment
		(start 388.045706 -280.025856)
		(end 387.879336 -279.859486)
		(width 0.088646)
		(layer "In6.Cu")
		(net "M_H_CPU0_SA_DQS_DN<5>")
	)
	(segment
		(start 437.527192 -310.5404)
		(end 436.7022 -311.365392)
		(width 0.18288)
		(layer "In6.Cu")
		(net "M_H_CPU0_SA_DQS_DN<5>")
	)
	(segment
		(start 421.59809 -307.954934)
		(end 421.202612 -307.954934)
		(width 0.18288)
		(layer "In6.Cu")
		(net "M_H_CPU0_SA_DQS_DN<5>")
	)
	(segment
		(start 452.051166 -311.380632)
		(end 451.372478 -311.380632)
		(width 0.18288)
		(layer "In6.Cu")
		(net "M_H_CPU0_SA_DQS_DN<5>")
	)
	(segment
		(start 438.073292 -310.5404)
		(end 437.527192 -310.5404)
		(width 0.18288)
		(layer "In6.Cu")
		(net "M_H_CPU0_SA_DQS_DN<5>")
	)
	(segment
		(start 433.343304 -311.493662)
		(end 432.797204 -311.493662)
		(width 0.18288)
		(layer "In6.Cu")
		(net "M_H_CPU0_SA_DQS_DN<5>")
	)
	(segment
		(start 377.77674 -277.226268)
		(end 377.776486 -277.226268)
		(width 0.088646)
		(layer "In6.Cu")
		(net "M_H_CPU0_SA_DQS_DN<5>")
	)
	(segment
		(start 413.69107 -305.986434)
		(end 412.981902 -305.277266)
		(width 0.18288)
		(layer "In6.Cu")
		(net "M_H_CPU0_SA_DQS_DN<5>")
	)
	(segment
		(start 410.197046 -303.717706)
		(end 409.923742 -303.99101)
		(width 0.18288)
		(layer "In6.Cu")
		(net "M_H_CPU0_SA_DQS_DN<5>")
	)
	(segment
		(start 443.866778 -310.759094)
		(end 443.094618 -310.759094)
		(width 0.18288)
		(layer "In6.Cu")
		(net "M_H_CPU0_SA_DQS_DN<5>")
	)
	(segment
		(start 393.623546 -280.300176)
		(end 388.920736 -280.300176)
		(width 0.18288)
		(layer "In6.Cu")
		(net "M_H_CPU0_SA_DQS_DN<5>")
	)
	(segment
		(start 414.825942 -307.121306)
		(end 414.253426 -306.54879)
		(width 0.18288)
		(layer "In6.Cu")
		(net "M_H_CPU0_SA_DQS_DN<5>")
	)
	(segment
		(start 411.492954 -304.315368)
		(end 411.492954 -304.139346)
		(width 0.18288)
		(layer "In6.Cu")
		(net "M_H_CPU0_SA_DQS_DN<5>")
	)
	(segment
		(start 387.783832 -279.630124)
		(end 387.055614 -278.901906)
		(width 0.088646)
		(layer "In6.Cu")
		(net "M_H_CPU0_SA_DQS_DN<5>")
	)
	(segment
		(start 435.354984 -311.369202)
		(end 434.808884 -311.369202)
		(width 0.18288)
		(layer "In6.Cu")
		(net "M_H_CPU0_SA_DQS_DN<5>")
	)
	(segment
		(start 378.204222 -277.19782)
		(end 378.203968 -277.19782)
		(width 0.088646)
		(layer "In6.Cu")
		(net "M_H_CPU0_SA_DQS_DN<5>")
	)
	(segment
		(start 409.575 -303.99101)
		(end 409.319476 -303.735486)
		(width 0.18288)
		(layer "In6.Cu")
		(net "M_H_CPU0_SA_DQS_DN<5>")
	)
	(segment
		(start 450.725032 -311.640982)
		(end 450.46519 -311.38114)
		(width 0.18288)
		(layer "In6.Cu")
		(net "M_H_CPU0_SA_DQS_DN<5>")
	)
	(segment
		(start 384.407664 -277.198074)
		(end 384.39725 -277.20417)
		(width 0.088646)
		(layer "In6.Cu")
		(net "M_H_CPU0_SA_DQS_DN<5>")
	)
	(segment
		(start 396.60195 -292.882066)
		(end 396.60195 -283.27858)
		(width 0.18288)
		(layer "In6.Cu")
		(net "M_H_CPU0_SA_DQS_DN<5>")
	)
	(segment
		(start 405.835866 -304.838862)
		(end 405.447754 -304.838862)
		(width 0.18288)
		(layer "In6.Cu")
		(net "M_H_CPU0_SA_DQS_DN<5>")
	)
	(segment
		(start 432.797204 -311.493662)
		(end 432.672744 -311.369202)
		(width 0.18288)
		(layer "In6.Cu")
		(net "M_H_CPU0_SA_DQS_DN<5>")
	)
	(segment
		(start 443.094618 -310.759094)
		(end 442.695076 -311.158636)
		(width 0.18288)
		(layer "In6.Cu")
		(net "M_H_CPU0_SA_DQS_DN<5>")
	)
	(segment
		(start 404.470616 -304.1777)
		(end 404.470616 -300.750732)
		(width 0.18288)
		(layer "In6.Cu")
		(net "M_H_CPU0_SA_DQS_DN<5>")
	)
	(segment
		(start 412.630874 -305.277266)
		(end 412.05531 -304.701702)
		(width 0.18288)
		(layer "In6.Cu")
		(net "M_H_CPU0_SA_DQS_DN<5>")
	)
	(segment
		(start 411.071314 -303.717706)
		(end 410.197046 -303.717706)
		(width 0.18288)
		(layer "In6.Cu")
		(net "M_H_CPU0_SA_DQS_DN<5>")
	)
	(segment
		(start 411.492954 -304.139346)
		(end 411.071314 -303.717706)
		(width 0.18288)
		(layer "In6.Cu")
		(net "M_H_CPU0_SA_DQS_DN<5>")
	)
	(segment
		(start 387.055614 -278.901906)
		(end 386.944108 -278.901906)
		(width 0.088646)
		(layer "In6.Cu")
		(net "M_H_CPU0_SA_DQS_DN<5>")
	)
	(segment
		(start 385.73075 -277.203154)
		(end 385.72186 -277.198074)
		(width 0.088646)
		(layer "In6.Cu")
		(net "M_H_CPU0_SA_DQS_DN<5>")
	)
	(segment
		(start 404.470616 -300.750732)
		(end 396.60195 -292.882066)
		(width 0.18288)
		(layer "In6.Cu")
		(net "M_H_CPU0_SA_DQS_DN<5>")
	)
	(segment
		(start 388.224014 -280.025856)
		(end 388.045706 -280.025856)
		(width 0.088646)
		(layer "In6.Cu")
		(net "M_H_CPU0_SA_DQS_DN<5>")
	)
	(segment
		(start 377.829572 -277.19782)
		(end 377.7869 -277.22068)
		(width 0.088646)
		(layer "In6.Cu")
		(net "M_H_CPU0_SA_DQS_DN<5>")
	)
	(segment
		(start 411.879288 -304.701702)
		(end 411.492954 -304.315368)
		(width 0.18288)
		(layer "In6.Cu")
		(net "M_H_CPU0_SA_DQS_DN<5>")
	)
	(segment
		(start 429.57369 -309.914798)
		(end 429.187102 -309.52821)
		(width 0.18288)
		(layer "In6.Cu")
		(net "M_H_CPU0_SA_DQS_DN<5>")
	)
	(segment
		(start 414.077404 -306.54879)
		(end 413.69107 -306.162456)
		(width 0.18288)
		(layer "In6.Cu")
		(net "M_H_CPU0_SA_DQS_DN<5>")
	)
	(segment
		(start 432.156108 -311.369202)
		(end 431.227992 -310.441086)
		(width 0.18288)
		(layer "In6.Cu")
		(net "M_H_CPU0_SA_DQS_DN<5>")
	)
	(segment
		(start 423.759376 -307.134768)
		(end 423.634916 -307.259228)
		(width 0.18288)
		(layer "In6.Cu")
		(net "M_H_CPU0_SA_DQS_DN<5>")
	)
	(segment
		(start 388.307326 -280.0858)
		(end 388.283958 -280.0858)
		(width 0.088646)
		(layer "In6.Cu")
		(net "M_H_CPU0_SA_DQS_DN<5>")
	)
	(segment
		(start 418.95268 -308.027832)
		(end 418.40658 -308.027832)
		(width 0.18288)
		(layer "In6.Cu")
		(net "M_H_CPU0_SA_DQS_DN<5>")
	)
	(segment
		(start 440.370976 -310.51881)
		(end 440.098688 -310.791098)
		(width 0.18288)
		(layer "In6.Cu")
		(net "M_H_CPU0_SA_DQS_DN<5>")
	)
	(segment
		(start 407.845768 -303.735486)
		(end 406.994614 -304.58664)
		(width 0.18288)
		(layer "In6.Cu")
		(net "M_H_CPU0_SA_DQS_DN<5>")
	)
	(segment
		(start 434.684424 -311.493662)
		(end 434.138324 -311.493662)
		(width 0.18288)
		(layer "In6.Cu")
		(net "M_H_CPU0_SA_DQS_DN<5>")
	)
	(segment
		(start 412.981902 -305.277266)
		(end 412.630874 -305.277266)
		(width 0.18288)
		(layer "In6.Cu")
		(net "M_H_CPU0_SA_DQS_DN<5>")
	)
	(segment
		(start 428.0789 -308.917086)
		(end 426.856398 -307.694584)
		(width 0.18288)
		(layer "In6.Cu")
		(net "M_H_CPU0_SA_DQS_DN<5>")
	)
	(segment
		(start 451.112128 -311.640982)
		(end 450.725032 -311.640982)
		(width 0.18288)
		(layer "In6.Cu")
		(net "M_H_CPU0_SA_DQS_DN<5>")
	)
	(segment
		(start 377.776486 -277.226268)
		(end 377.62307 -277.289768)
		(width 0.088646)
		(layer "In6.Cu")
		(net "M_H_CPU0_SA_DQS_DN<5>")
	)
	(segment
		(start 424.388026 -307.134768)
		(end 423.759376 -307.134768)
		(width 0.18288)
		(layer "In6.Cu")
		(net "M_H_CPU0_SA_DQS_DN<5>")
	)
	(segment
		(start 451.372478 -311.380632)
		(end 451.112128 -311.640982)
		(width 0.18288)
		(layer "In6.Cu")
		(net "M_H_CPU0_SA_DQS_DN<5>")
	)
	(segment
		(start 428.752 -308.917086)
		(end 428.0789 -308.917086)
		(width 0.18288)
		(layer "In6.Cu")
		(net "M_H_CPU0_SA_DQS_DN<5>")
	)
	(segment
		(start 377.13666 -277.313136)
		(end 377.076462 -277.373334)
		(width 0.088646)
		(layer "In6.Cu")
		(net "M_H_CPU0_SA_DQS_DN<5>")
	)
	(segment
		(start 383.467864 -277.198074)
		(end 383.453132 -277.20671)
		(width 0.088646)
		(layer "In6.Cu")
		(net "M_H_CPU0_SA_DQS_DN<5>")
	)
	(segment
		(start 378.183648 -277.186898)
		(end 378.125228 -277.160482)
		(width 0.088646)
		(layer "In6.Cu")
		(net "M_H_CPU0_SA_DQS_DN<5>")
	)
	(segment
		(start 453.636634 -311.958736)
		(end 452.62927 -311.958736)
		(width 0.18288)
		(layer "In6.Cu")
		(net "M_H_CPU0_SA_DQS_DN<5>")
	)
	(segment
		(start 383.476246 -277.193248)
		(end 383.467864 -277.198074)
		(width 0.088646)
		(layer "In6.Cu")
		(net "M_H_CPU0_SA_DQS_DN<5>")
	)
	(segment
		(start 406.088088 -304.58664)
		(end 405.835866 -304.838862)
		(width 0.18288)
		(layer "In6.Cu")
		(net "M_H_CPU0_SA_DQS_DN<5>")
	)
	(segment
		(start 450.46519 -311.38114)
		(end 446.676018 -311.38114)
		(width 0.18288)
		(layer "In6.Cu")
		(net "M_H_CPU0_SA_DQS_DN<5>")
	)
	(segment
		(start 388.403084 -280.0858)
		(end 388.307326 -280.0858)
		(width 0.18288)
		(layer "In6.Cu")
		(net "M_H_CPU0_SA_DQS_DN<5>")
	)
	(segment
		(start 422.964356 -307.134768)
		(end 422.418256 -307.134768)
		(width 0.18288)
		(layer "In6.Cu")
		(net "M_H_CPU0_SA_DQS_DN<5>")
	)
	(segment
		(start 452.62927 -311.958736)
		(end 452.051166 -311.380632)
		(width 0.18288)
		(layer "In6.Cu")
		(net "M_H_CPU0_SA_DQS_DN<5>")
	)
	(segment
		(start 426.856398 -307.694584)
		(end 426.405294 -307.694584)
		(width 0.18288)
		(layer "In6.Cu")
		(net "M_H_CPU0_SA_DQS_DN<5>")
	)
	(segment
		(start 425.310554 -307.110638)
		(end 425.030138 -307.391054)
		(width 0.18288)
		(layer "In6.Cu")
		(net "M_H_CPU0_SA_DQS_DN<5>")
	)
	(segment
		(start 436.275734 -311.365392)
		(end 436.000144 -311.640982)
		(width 0.18288)
		(layer "In6.Cu")
		(net "M_H_CPU0_SA_DQS_DN<5>")
	)
	(segment
		(start 439.716672 -310.791098)
		(end 439.465974 -310.5404)
		(width 0.18288)
		(layer "In6.Cu")
		(net "M_H_CPU0_SA_DQS_DN<5>")
	)
	(segment
		(start 377.829826 -277.197312)
		(end 377.829572 -277.19782)
		(width 0.088646)
		(layer "In6.Cu")
		(net "M_H_CPU0_SA_DQS_DN<5>")
	)
	(segment
		(start 421.202612 -307.954934)
		(end 420.916354 -308.241192)
		(width 0.18288)
		(layer "In6.Cu")
		(net "M_H_CPU0_SA_DQS_DN<5>")
	)
	(segment
		(start 425.821348 -307.110638)
		(end 425.310554 -307.110638)
		(width 0.18288)
		(layer "In6.Cu")
		(net "M_H_CPU0_SA_DQS_DN<5>")
	)
	(segment
		(start 382.528064 -277.198074)
		(end 382.513332 -277.20671)
		(width 0.088646)
		(layer "In6.Cu")
		(net "M_H_CPU0_SA_DQS_DN<5>")
	)
	(segment
		(start 418.28212 -308.152292)
		(end 417.73602 -308.152292)
		(width 0.18288)
		(layer "In6.Cu")
		(net "M_H_CPU0_SA_DQS_DN<5>")
	)
	(segment
		(start 426.405294 -307.694584)
		(end 425.821348 -307.110638)
		(width 0.18288)
		(layer "In6.Cu")
		(net "M_H_CPU0_SA_DQS_DN<5>")
	)
	(segment
		(start 424.644312 -307.391054)
		(end 424.388026 -307.134768)
		(width 0.18288)
		(layer "In6.Cu")
		(net "M_H_CPU0_SA_DQS_DN<5>")
	)
	(segment
		(start 439.465974 -310.5404)
		(end 438.868312 -310.5404)
		(width 0.18288)
		(layer "In6.Cu")
		(net "M_H_CPU0_SA_DQS_DN<5>")
	)
	(segment
		(start 420.487348 -308.241192)
		(end 420.273988 -308.027832)
		(width 0.18288)
		(layer "In6.Cu")
		(net "M_H_CPU0_SA_DQS_DN<5>")
	)
	(segment
		(start 430.276 -310.441086)
		(end 429.749712 -309.914798)
		(width 0.18288)
		(layer "In6.Cu")
		(net "M_H_CPU0_SA_DQS_DN<5>")
	)
	(segment
		(start 419.07714 -308.152292)
		(end 418.95268 -308.027832)
		(width 0.18288)
		(layer "In6.Cu")
		(net "M_H_CPU0_SA_DQS_DN<5>")
	)
	(segment
		(start 434.808884 -311.369202)
		(end 434.684424 -311.493662)
		(width 0.18288)
		(layer "In6.Cu")
		(net "M_H_CPU0_SA_DQS_DN<5>")
	)
	(segment
		(start 381.588264 -277.198074)
		(end 381.573532 -277.20671)
		(width 0.088646)
		(layer "In6.Cu")
		(net "M_H_CPU0_SA_DQS_DN<5>")
	)
	(segment
		(start 414.253426 -306.54879)
		(end 414.077404 -306.54879)
		(width 0.18288)
		(layer "In6.Cu")
		(net "M_H_CPU0_SA_DQS_DN<5>")
	)
	(segment
		(start 436.7022 -311.365392)
		(end 436.275734 -311.365392)
		(width 0.18288)
		(layer "In6.Cu")
		(net "M_H_CPU0_SA_DQS_DN<5>")
	)
	(segment
		(start 429.187102 -309.52821)
		(end 429.187102 -309.352188)
		(width 0.18288)
		(layer "In6.Cu")
		(net "M_H_CPU0_SA_DQS_DN<5>")
	)
	(segment
		(start 405.200612 -304.59172)
		(end 404.884636 -304.59172)
		(width 0.18288)
		(layer "In6.Cu")
		(net "M_H_CPU0_SA_DQS_DN<5>")
	)
	(segment
		(start 445.154558 -312.046874)
		(end 443.866778 -310.759094)
		(width 0.18288)
		(layer "In6.Cu")
		(net "M_H_CPU0_SA_DQS_DN<5>")
	)
	(segment
		(start 405.447754 -304.838862)
		(end 405.200612 -304.59172)
		(width 0.18288)
		(layer "In6.Cu")
		(net "M_H_CPU0_SA_DQS_DN<5>")
	)
	(segment
		(start 409.319476 -303.735486)
		(end 407.845768 -303.735486)
		(width 0.18288)
		(layer "In6.Cu")
		(net "M_H_CPU0_SA_DQS_DN<5>")
	)
	(segment
		(start 429.187102 -309.352188)
		(end 428.752 -308.917086)
		(width 0.18288)
		(layer "In6.Cu")
		(net "M_H_CPU0_SA_DQS_DN<5>")
	)
	(segment
		(start 423.088816 -307.259228)
		(end 422.964356 -307.134768)
		(width 0.18288)
		(layer "In6.Cu")
		(net "M_H_CPU0_SA_DQS_DN<5>")
	)
	(segment
		(start 438.743852 -310.66486)
		(end 438.197752 -310.66486)
		(width 0.18288)
		(layer "In6.Cu")
		(net "M_H_CPU0_SA_DQS_DN<5>")
	)
	(segment
		(start 419.7477 -308.027832)
		(end 419.62324 -308.152292)
		(width 0.18288)
		(layer "In6.Cu")
		(net "M_H_CPU0_SA_DQS_DN<5>")
	)
	(segment
		(start 436.000144 -311.640982)
		(end 435.626764 -311.640982)
		(width 0.18288)
		(layer "In6.Cu")
		(net "M_H_CPU0_SA_DQS_DN<5>")
	)
	(segment
		(start 442.695076 -311.158636)
		(end 441.816744 -311.158636)
		(width 0.18288)
		(layer "In6.Cu")
		(net "M_H_CPU0_SA_DQS_DN<5>")
	)
	(segment
		(start 377.62307 -277.289768)
		(end 377.252738 -277.289768)
		(width 0.088646)
		(layer "In6.Cu")
		(net "M_H_CPU0_SA_DQS_DN<5>")
	)
	(segment
		(start 441.176918 -310.51881)
		(end 440.370976 -310.51881)
		(width 0.18288)
		(layer "In6.Cu")
		(net "M_H_CPU0_SA_DQS_DN<5>")
	)
	(segment
		(start 388.920736 -280.300176)
		(end 388.403084 -280.0858)
		(width 0.18288)
		(layer "In6.Cu")
		(net "M_H_CPU0_SA_DQS_DN<5>")
	)
	(segment
		(start 378.203968 -277.198328)
		(end 378.204222 -277.19782)
		(width 0.088646)
		(layer "In6.Cu")
		(net "M_H_CPU0_SA_DQS_DN<5>")
	)
	(segment
		(start 379.708664 -277.198074)
		(end 379.69825 -277.20417)
		(width 0.088646)
		(layer "In6.Cu")
		(net "M_H_CPU0_SA_DQS_DN<5>")
	)
	(segment
		(start 386.379212 -278.355044)
		(end 386.379212 -278.336502)
		(width 0.088646)
		(layer "In6.Cu")
		(net "M_H_CPU0_SA_DQS_DN<5>")
	)
	(segment
		(start 422.418256 -307.134768)
		(end 421.59809 -307.954934)
		(width 0.18288)
		(layer "In6.Cu")
		(net "M_H_CPU0_SA_DQS_DN<5>")
	)
	(segment
		(start 446.010284 -312.046874)
		(end 445.154558 -312.046874)
		(width 0.18288)
		(layer "In6.Cu")
		(net "M_H_CPU0_SA_DQS_DN<5>")
	)
	(segment
		(start 455.011282 -312.066686)
		(end 454.73493 -311.790334)
		(width 0.18288)
		(layer "In6.Cu")
		(net "M_H_CPU0_SA_DQS_DN<5>")
	)
	(segment
		(start 378.200666 -277.196042)
		(end 378.183648 -277.186898)
		(width 0.088646)
		(layer "In6.Cu")
		(net "M_H_CPU0_SA_DQS_DN<5>")
	)
	(segment
		(start 454.043288 -311.790334)
		(end 453.636634 -311.958736)
		(width 0.18288)
		(layer "In6.Cu")
		(net "M_H_CPU0_SA_DQS_DN<5>")
	)
	(arc
		(start 382.90246 -277.198074)
		(mid 382.715262 -277.147931)
		(end 382.528064 -277.198074)
		(width 0.088646)
		(layer "In6.Cu")
		(net "M_H_CPU0_SA_DQS_DN<5>")
	)
	(arc
		(start 378.769118 -277.198074)
		(mid 378.486589 -277.27385)
		(end 378.203968 -277.198328)
		(width 0.088646)
		(layer "In6.Cu")
		(net "M_H_CPU0_SA_DQS_DN<5>")
	)
	(arc
		(start 379.143514 -277.198074)
		(mid 378.956316 -277.147931)
		(end 378.769118 -277.198074)
		(width 0.088646)
		(layer "In6.Cu")
		(net "M_H_CPU0_SA_DQS_DN<5>")
	)
	(arc
		(start 384.78206 -277.198074)
		(mid 384.594862 -277.147931)
		(end 384.407664 -277.198074)
		(width 0.088646)
		(layer "In6.Cu")
		(net "M_H_CPU0_SA_DQS_DN<5>")
	)
	(arc
		(start 386.944108 -278.901906)
		(mid 386.551079 -278.742717)
		(end 386.379212 -278.355044)
		(width 0.088646)
		(layer "In6.Cu")
		(net "M_H_CPU0_SA_DQS_DN<5>")
	)
	(arc
		(start 385.347464 -277.198074)
		(mid 385.064762 -277.27385)
		(end 384.78206 -277.198074)
		(width 0.088646)
		(layer "In6.Cu")
		(net "M_H_CPU0_SA_DQS_DN<5>")
	)
	(arc
		(start 382.513332 -277.20671)
		(mid 382.236857 -277.27403)
		(end 381.96266 -277.198074)
		(width 0.088646)
		(layer "In6.Cu")
		(net "M_H_CPU0_SA_DQS_DN<5>")
	)
	(arc
		(start 383.842006 -277.198074)
		(mid 383.659755 -277.147963)
		(end 383.476246 -277.193248)
		(width 0.088646)
		(layer "In6.Cu")
		(net "M_H_CPU0_SA_DQS_DN<5>")
	)
	(arc
		(start 380.648464 -277.198074)
		(mid 380.365762 -277.27385)
		(end 380.08306 -277.198074)
		(width 0.088646)
		(layer "In6.Cu")
		(net "M_H_CPU0_SA_DQS_DN<5>")
	)
	(arc
		(start 386.19176 -278.012144)
		(mid 385.989474 -277.813163)
		(end 385.909312 -277.540974)
		(width 0.088646)
		(layer "In6.Cu")
		(net "M_H_CPU0_SA_DQS_DN<5>")
	)
	(arc
		(start 383.453132 -277.20671)
		(mid 383.176657 -277.27403)
		(end 382.90246 -277.198074)
		(width 0.088646)
		(layer "In6.Cu")
		(net "M_H_CPU0_SA_DQS_DN<5>")
	)
	(arc
		(start 378.125228 -277.160482)
		(mid 378.020317 -277.137264)
		(end 377.914916 -277.158196)
		(width 0.088646)
		(layer "In6.Cu")
		(net "M_H_CPU0_SA_DQS_DN<5>")
	)
	(arc
		(start 378.203968 -277.19782)
		(mid 378.202319 -277.196927)
		(end 378.200666 -277.196042)
		(width 0.088646)
		(layer "In6.Cu")
		(net "M_H_CPU0_SA_DQS_DN<5>")
	)
	(arc
		(start 381.02286 -277.198074)
		(mid 380.835662 -277.147931)
		(end 380.648464 -277.198074)
		(width 0.088646)
		(layer "In6.Cu")
		(net "M_H_CPU0_SA_DQS_DN<5>")
	)
	(arc
		(start 380.08306 -277.198074)
		(mid 379.895862 -277.147931)
		(end 379.708664 -277.198074)
		(width 0.088646)
		(layer "In6.Cu")
		(net "M_H_CPU0_SA_DQS_DN<5>")
	)
	(arc
		(start 379.69825 -277.20417)
		(mid 379.420072 -277.273893)
		(end 379.143514 -277.198074)
		(width 0.088646)
		(layer "In6.Cu")
		(net "M_H_CPU0_SA_DQS_DN<5>")
	)
	(arc
		(start 385.72186 -277.198074)
		(mid 385.534662 -277.147931)
		(end 385.347464 -277.198074)
		(width 0.088646)
		(layer "In6.Cu")
		(net "M_H_CPU0_SA_DQS_DN<5>")
	)
	(arc
		(start 377.869196 -277.177754)
		(mid 377.849224 -277.186955)
		(end 377.829826 -277.197312)
		(width 0.088646)
		(layer "In6.Cu")
		(net "M_H_CPU0_SA_DQS_DN<5>")
	)
	(arc
		(start 381.573532 -277.20671)
		(mid 381.297057 -277.27403)
		(end 381.02286 -277.198074)
		(width 0.088646)
		(layer "In6.Cu")
		(net "M_H_CPU0_SA_DQS_DN<5>")
	)
	(arc
		(start 385.909312 -277.522432)
		(mid 385.861633 -277.339532)
		(end 385.73075 -277.203154)
		(width 0.088646)
		(layer "In6.Cu")
		(net "M_H_CPU0_SA_DQS_DN<5>")
	)
	(arc
		(start 386.379212 -278.336502)
		(mid 386.331533 -278.153602)
		(end 386.20065 -278.017224)
		(width 0.088646)
		(layer "In6.Cu")
		(net "M_H_CPU0_SA_DQS_DN<5>")
	)
	(arc
		(start 381.96266 -277.198074)
		(mid 381.775462 -277.147931)
		(end 381.588264 -277.198074)
		(width 0.088646)
		(layer "In6.Cu")
		(net "M_H_CPU0_SA_DQS_DN<5>")
	)
	(arc
		(start 384.39725 -277.20417)
		(mid 384.118818 -277.274016)
		(end 383.842006 -277.198074)
		(width 0.088646)
		(layer "In6.Cu")
		(net "M_H_CPU0_SA_DQS_DN<5>")
	)
	(segment
		(start 453.582278 -274.948396)
		(end 452.84644 -274.948396)
		(width 0.20066)
		(layer "F.Cu")
		(net "M_H_CPU0_SA_DQS_DN<4>")
	)
	(segment
		(start 454.518522 -275.362924)
		(end 453.996806 -275.362924)
		(width 0.20066)
		(layer "F.Cu")
		(net "M_H_CPU0_SA_DQS_DN<4>")
	)
	(segment
		(start 452.84644 -274.948396)
		(end 452.564754 -274.66671)
		(width 0.20066)
		(layer "F.Cu")
		(net "M_H_CPU0_SA_DQS_DN<4>")
	)
	(segment
		(start 457.682092 -275.317712)
		(end 457.450698 -275.086318)
		(width 0.20066)
		(layer "F.Cu")
		(net "M_H_CPU0_SA_DQS_DN<4>")
	)
	(segment
		(start 450.911214 -274.66671)
		(end 452.016114 -274.66671)
		(width 0.20066)
		(layer "F.Cu")
		(net "M_H_CPU0_SA_DQS_DN<4>")
	)
	(segment
		(start 457.12126 -275.091652)
		(end 454.941686 -275.091652)
		(width 0.1016)
		(layer "F.Cu")
		(net "M_H_CPU0_SA_DQS_DN<4>")
	)
	(segment
		(start 457.126594 -275.086318)
		(end 457.12126 -275.091652)
		(width 0.1016)
		(layer "F.Cu")
		(net "M_H_CPU0_SA_DQS_DN<4>")
	)
	(segment
		(start 458.970634 -274.66671)
		(end 458.730096 -274.907248)
		(width 0.20066)
		(layer "F.Cu")
		(net "M_H_CPU0_SA_DQS_DN<4>")
	)
	(segment
		(start 371.907562 -260.430518)
		(end 371.907816 -260.430772)
		(width 0.20066)
		(layer "F.Cu")
		(net "M_H_CPU0_SA_DQS_DN<4>")
	)
	(segment
		(start 454.941686 -275.091652)
		(end 454.937368 -275.091652)
		(width 0.101854)
		(layer "F.Cu")
		(net "M_H_CPU0_SA_DQS_DN<4>")
	)
	(segment
		(start 453.996806 -275.362924)
		(end 453.582278 -274.948396)
		(width 0.20066)
		(layer "F.Cu")
		(net "M_H_CPU0_SA_DQS_DN<4>")
	)
	(segment
		(start 458.39761 -274.907248)
		(end 457.987146 -275.317712)
		(width 0.20066)
		(layer "F.Cu")
		(net "M_H_CPU0_SA_DQS_DN<4>")
	)
	(segment
		(start 458.730096 -274.907248)
		(end 458.39761 -274.907248)
		(width 0.20066)
		(layer "F.Cu")
		(net "M_H_CPU0_SA_DQS_DN<4>")
	)
	(segment
		(start 457.987146 -275.317712)
		(end 457.682092 -275.317712)
		(width 0.20066)
		(layer "F.Cu")
		(net "M_H_CPU0_SA_DQS_DN<4>")
	)
	(segment
		(start 454.937368 -275.091652)
		(end 454.789794 -275.091652)
		(width 0.20066)
		(layer "F.Cu")
		(net "M_H_CPU0_SA_DQS_DN<4>")
	)
	(segment
		(start 459.559914 -274.66671)
		(end 458.970634 -274.66671)
		(width 0.20066)
		(layer "F.Cu")
		(net "M_H_CPU0_SA_DQS_DN<4>")
	)
	(segment
		(start 457.450698 -275.086318)
		(end 457.126594 -275.086318)
		(width 0.20066)
		(layer "F.Cu")
		(net "M_H_CPU0_SA_DQS_DN<4>")
	)
	(segment
		(start 371.907562 -259.894832)
		(end 371.907562 -260.430518)
		(width 0.20066)
		(layer "F.Cu")
		(net "M_H_CPU0_SA_DQS_DN<4>")
	)
	(segment
		(start 452.564754 -274.66671)
		(end 452.016114 -274.66671)
		(width 0.20066)
		(layer "F.Cu")
		(net "M_H_CPU0_SA_DQS_DN<4>")
	)
	(segment
		(start 454.789794 -275.091652)
		(end 454.518522 -275.362924)
		(width 0.20066)
		(layer "F.Cu")
		(net "M_H_CPU0_SA_DQS_DN<4>")
	)
	(segment
		(start 433.526692 -276.081998)
		(end 432.978052 -276.081998)
		(width 0.18288)
		(layer "In11.Cu")
		(net "M_H_CPU0_SA_DQS_DN<4>")
	)
	(segment
		(start 444.16218 -276.67966)
		(end 444.03772 -276.80412)
		(width 0.18288)
		(layer "In11.Cu")
		(net "M_H_CPU0_SA_DQS_DN<4>")
	)
	(segment
		(start 450.660516 -274.917408)
		(end 450.390514 -274.917408)
		(width 0.18288)
		(layer "In11.Cu")
		(net "M_H_CPU0_SA_DQS_DN<4>")
	)
	(segment
		(start 371.595142 -260.430772)
		(end 371.907816 -260.430772)
		(width 0.088646)
		(layer "In11.Cu")
		(net "M_H_CPU0_SA_DQS_DN<4>")
	)
	(segment
		(start 385.629912 -262.058658)
		(end 385.629912 -262.048752)
		(width 0.088646)
		(layer "In11.Cu")
		(net "M_H_CPU0_SA_DQS_DN<4>")
	)
	(segment
		(start 388.842504 -263.34085)
		(end 388.782814 -263.40054)
		(width 0.088646)
		(layer "In11.Cu")
		(net "M_H_CPU0_SA_DQS_DN<4>")
	)
	(segment
		(start 427.073568 -276.354286)
		(end 426.611288 -276.354286)
		(width 0.18288)
		(layer "In11.Cu")
		(net "M_H_CPU0_SA_DQS_DN<4>")
	)
	(segment
		(start 375.868946 -260.746494)
		(end 375.854214 -260.75513)
		(width 0.088646)
		(layer "In11.Cu")
		(net "M_H_CPU0_SA_DQS_DN<4>")
	)
	(segment
		(start 450.911214 -274.66671)
		(end 450.660516 -274.917408)
		(width 0.18288)
		(layer "In11.Cu")
		(net "M_H_CPU0_SA_DQS_DN<4>")
	)
	(segment
		(start 432.08702 -276.206458)
		(end 430.572418 -275.541486)
		(width 0.18288)
		(layer "In11.Cu")
		(net "M_H_CPU0_SA_DQS_DN<4>")
	)
	(segment
		(start 442.75756 -276.42947)
		(end 441.568332 -276.42947)
		(width 0.18288)
		(layer "In11.Cu")
		(net "M_H_CPU0_SA_DQS_DN<4>")
	)
	(segment
		(start 404.593044 -274.258786)
		(end 393.675108 -263.34085)
		(width 0.18288)
		(layer "In11.Cu")
		(net "M_H_CPU0_SA_DQS_DN<4>")
	)
	(segment
		(start 437.808624 -277.047706)
		(end 436.977028 -276.21611)
		(width 0.18288)
		(layer "In11.Cu")
		(net "M_H_CPU0_SA_DQS_DN<4>")
	)
	(segment
		(start 425.879514 -277.08606)
		(end 425.32681 -277.08606)
		(width 0.18288)
		(layer "In11.Cu")
		(net "M_H_CPU0_SA_DQS_DN<4>")
	)
	(segment
		(start 387.039866 -262.872474)
		(end 387.039866 -262.850376)
		(width 0.088646)
		(layer "In11.Cu")
		(net "M_H_CPU0_SA_DQS_DN<4>")
	)
	(segment
		(start 416.303968 -275.46173)
		(end 412.64205 -275.46173)
		(width 0.18288)
		(layer "In11.Cu")
		(net "M_H_CPU0_SA_DQS_DN<4>")
	)
	(segment
		(start 386.202428 -262.376666)
		(end 386.192014 -262.382762)
		(width 0.088646)
		(layer "In11.Cu")
		(net "M_H_CPU0_SA_DQS_DN<4>")
	)
	(segment
		(start 388.092188 -263.247632)
		(end 387.414262 -263.247632)
		(width 0.088646)
		(layer "In11.Cu")
		(net "M_H_CPU0_SA_DQS_DN<4>")
	)
	(segment
		(start 380.563628 -260.749034)
		(end 380.553214 -260.75513)
		(width 0.088646)
		(layer "In11.Cu")
		(net "M_H_CPU0_SA_DQS_DN<4>")
	)
	(segment
		(start 421.199818 -276.221952)
		(end 420.918894 -275.941028)
		(width 0.18288)
		(layer "In11.Cu")
		(net "M_H_CPU0_SA_DQS_DN<4>")
	)
	(segment
		(start 408.825446 -274.258786)
		(end 404.593044 -274.258786)
		(width 0.18288)
		(layer "In11.Cu")
		(net "M_H_CPU0_SA_DQS_DN<4>")
	)
	(segment
		(start 439.655458 -276.790658)
		(end 439.39841 -277.047706)
		(width 0.18288)
		(layer "In11.Cu")
		(net "M_H_CPU0_SA_DQS_DN<4>")
	)
	(segment
		(start 382.443228 -260.749034)
		(end 382.432814 -260.75513)
		(width 0.088646)
		(layer "In11.Cu")
		(net "M_H_CPU0_SA_DQS_DN<4>")
	)
	(segment
		(start 385.347464 -261.5692)
		(end 385.338574 -261.56412)
		(width 0.088646)
		(layer "In11.Cu")
		(net "M_H_CPU0_SA_DQS_DN<4>")
	)
	(segment
		(start 447.950336 -275.953474)
		(end 446.626234 -275.953474)
		(width 0.18288)
		(layer "In11.Cu")
		(net "M_H_CPU0_SA_DQS_DN<4>")
	)
	(segment
		(start 425.32681 -277.08606)
		(end 425.033186 -276.792436)
		(width 0.18288)
		(layer "In11.Cu")
		(net "M_H_CPU0_SA_DQS_DN<4>")
	)
	(segment
		(start 441.568332 -276.42947)
		(end 440.932316 -277.065486)
		(width 0.18288)
		(layer "In11.Cu")
		(net "M_H_CPU0_SA_DQS_DN<4>")
	)
	(segment
		(start 430.572418 -275.541486)
		(end 427.886368 -275.541486)
		(width 0.18288)
		(layer "In11.Cu")
		(net "M_H_CPU0_SA_DQS_DN<4>")
	)
	(segment
		(start 436.977028 -276.21611)
		(end 436.303166 -276.21611)
		(width 0.18288)
		(layer "In11.Cu")
		(net "M_H_CPU0_SA_DQS_DN<4>")
	)
	(segment
		(start 377.748546 -260.746494)
		(end 377.733814 -260.75513)
		(width 0.088646)
		(layer "In11.Cu")
		(net "M_H_CPU0_SA_DQS_DN<4>")
	)
	(segment
		(start 420.194232 -276.214586)
		(end 420.17696 -276.214586)
		(width 0.18288)
		(layer "In11.Cu")
		(net "M_H_CPU0_SA_DQS_DN<4>")
	)
	(segment
		(start 439.39841 -277.047706)
		(end 437.808624 -277.047706)
		(width 0.18288)
		(layer "In11.Cu")
		(net "M_H_CPU0_SA_DQS_DN<4>")
	)
	(segment
		(start 422.61917 -276.747478)
		(end 422.093644 -276.221952)
		(width 0.18288)
		(layer "In11.Cu")
		(net "M_H_CPU0_SA_DQS_DN<4>")
	)
	(segment
		(start 436.303166 -276.21611)
		(end 436.02783 -275.940774)
		(width 0.18288)
		(layer "In11.Cu")
		(net "M_H_CPU0_SA_DQS_DN<4>")
	)
	(segment
		(start 422.093644 -276.221952)
		(end 421.199818 -276.221952)
		(width 0.18288)
		(layer "In11.Cu")
		(net "M_H_CPU0_SA_DQS_DN<4>")
	)
	(segment
		(start 444.03772 -276.80412)
		(end 443.13221 -276.80412)
		(width 0.18288)
		(layer "In11.Cu")
		(net "M_H_CPU0_SA_DQS_DN<4>")
	)
	(segment
		(start 411.738318 -275.95957)
		(end 410.895546 -275.116544)
		(width 0.18288)
		(layer "In11.Cu")
		(net "M_H_CPU0_SA_DQS_DN<4>")
	)
	(segment
		(start 427.886368 -275.541486)
		(end 427.073568 -276.354286)
		(width 0.18288)
		(layer "In11.Cu")
		(net "M_H_CPU0_SA_DQS_DN<4>")
	)
	(segment
		(start 440.116214 -276.790658)
		(end 439.655458 -276.790658)
		(width 0.18288)
		(layer "In11.Cu")
		(net "M_H_CPU0_SA_DQS_DN<4>")
	)
	(segment
		(start 376.808746 -260.746494)
		(end 376.794014 -260.75513)
		(width 0.088646)
		(layer "In11.Cu")
		(net "M_H_CPU0_SA_DQS_DN<4>")
	)
	(segment
		(start 425.033186 -276.792436)
		(end 424.551856 -276.792436)
		(width 0.18288)
		(layer "In11.Cu")
		(net "M_H_CPU0_SA_DQS_DN<4>")
	)
	(segment
		(start 412.64205 -275.46173)
		(end 412.14421 -275.95957)
		(width 0.18288)
		(layer "In11.Cu")
		(net "M_H_CPU0_SA_DQS_DN<4>")
	)
	(segment
		(start 412.14421 -275.95957)
		(end 411.738318 -275.95957)
		(width 0.18288)
		(layer "In11.Cu")
		(net "M_H_CPU0_SA_DQS_DN<4>")
	)
	(segment
		(start 450.229224 -274.756118)
		(end 449.558664 -274.756118)
		(width 0.18288)
		(layer "In11.Cu")
		(net "M_H_CPU0_SA_DQS_DN<4>")
	)
	(segment
		(start 420.168324 -276.223222)
		(end 417.06546 -276.223222)
		(width 0.18288)
		(layer "In11.Cu")
		(net "M_H_CPU0_SA_DQS_DN<4>")
	)
	(segment
		(start 393.675108 -263.34085)
		(end 388.842504 -263.34085)
		(width 0.18288)
		(layer "In11.Cu")
		(net "M_H_CPU0_SA_DQS_DN<4>")
	)
	(segment
		(start 426.611288 -276.354286)
		(end 425.879514 -277.08606)
		(width 0.18288)
		(layer "In11.Cu")
		(net "M_H_CPU0_SA_DQS_DN<4>")
	)
	(segment
		(start 446.626234 -275.953474)
		(end 445.775588 -276.80412)
		(width 0.18288)
		(layer "In11.Cu")
		(net "M_H_CPU0_SA_DQS_DN<4>")
	)
	(segment
		(start 420.17696 -276.214586)
		(end 420.168324 -276.223222)
		(width 0.18288)
		(layer "In11.Cu")
		(net "M_H_CPU0_SA_DQS_DN<4>")
	)
	(segment
		(start 424.551856 -276.792436)
		(end 424.255946 -277.088346)
		(width 0.18288)
		(layer "In11.Cu")
		(net "M_H_CPU0_SA_DQS_DN<4>")
	)
	(segment
		(start 374.924574 -260.749034)
		(end 374.914668 -260.75513)
		(width 0.088646)
		(layer "In11.Cu")
		(net "M_H_CPU0_SA_DQS_DN<4>")
	)
	(segment
		(start 378.688346 -260.746494)
		(end 378.673614 -260.75513)
		(width 0.088646)
		(layer "In11.Cu")
		(net "M_H_CPU0_SA_DQS_DN<4>")
	)
	(segment
		(start 420.918894 -275.941028)
		(end 420.46779 -275.941028)
		(width 0.18288)
		(layer "In11.Cu")
		(net "M_H_CPU0_SA_DQS_DN<4>")
	)
	(segment
		(start 435.289706 -276.206458)
		(end 433.651152 -276.206458)
		(width 0.18288)
		(layer "In11.Cu")
		(net "M_H_CPU0_SA_DQS_DN<4>")
	)
	(segment
		(start 432.978052 -276.081998)
		(end 432.853592 -276.206458)
		(width 0.18288)
		(layer "In11.Cu")
		(net "M_H_CPU0_SA_DQS_DN<4>")
	)
	(segment
		(start 444.71082 -276.67966)
		(end 444.16218 -276.67966)
		(width 0.18288)
		(layer "In11.Cu")
		(net "M_H_CPU0_SA_DQS_DN<4>")
	)
	(segment
		(start 388.782814 -263.40054)
		(end 388.245096 -263.40054)
		(width 0.088646)
		(layer "In11.Cu")
		(net "M_H_CPU0_SA_DQS_DN<4>")
	)
	(segment
		(start 373.985028 -260.749034)
		(end 373.974614 -260.75513)
		(width 0.088646)
		(layer "In11.Cu")
		(net "M_H_CPU0_SA_DQS_DN<4>")
	)
	(segment
		(start 417.06546 -276.223222)
		(end 416.303968 -275.46173)
		(width 0.18288)
		(layer "In11.Cu")
		(net "M_H_CPU0_SA_DQS_DN<4>")
	)
	(segment
		(start 387.039612 -262.88492)
		(end 387.039866 -262.884666)
		(width 0.088646)
		(layer "In11.Cu")
		(net "M_H_CPU0_SA_DQS_DN<4>")
	)
	(segment
		(start 449.558664 -274.756118)
		(end 448.85737 -275.04644)
		(width 0.18288)
		(layer "In11.Cu")
		(net "M_H_CPU0_SA_DQS_DN<4>")
	)
	(segment
		(start 372.109746 -260.746494)
		(end 372.095014 -260.75513)
		(width 0.088646)
		(layer "In11.Cu")
		(net "M_H_CPU0_SA_DQS_DN<4>")
	)
	(segment
		(start 445.775588 -276.80412)
		(end 444.83528 -276.80412)
		(width 0.18288)
		(layer "In11.Cu")
		(net "M_H_CPU0_SA_DQS_DN<4>")
	)
	(segment
		(start 423.977308 -277.088346)
		(end 422.61917 -276.747478)
		(width 0.18288)
		(layer "In11.Cu")
		(net "M_H_CPU0_SA_DQS_DN<4>")
	)
	(segment
		(start 433.651152 -276.206458)
		(end 433.526692 -276.081998)
		(width 0.18288)
		(layer "In11.Cu")
		(net "M_H_CPU0_SA_DQS_DN<4>")
	)
	(segment
		(start 373.049546 -260.746494)
		(end 373.034814 -260.75513)
		(width 0.088646)
		(layer "In11.Cu")
		(net "M_H_CPU0_SA_DQS_DN<4>")
	)
	(segment
		(start 440.391042 -277.065486)
		(end 440.116214 -276.790658)
		(width 0.18288)
		(layer "In11.Cu")
		(net "M_H_CPU0_SA_DQS_DN<4>")
	)
	(segment
		(start 448.85737 -275.04644)
		(end 447.950336 -275.953474)
		(width 0.18288)
		(layer "In11.Cu")
		(net "M_H_CPU0_SA_DQS_DN<4>")
	)
	(segment
		(start 443.13221 -276.80412)
		(end 442.75756 -276.42947)
		(width 0.18288)
		(layer "In11.Cu")
		(net "M_H_CPU0_SA_DQS_DN<4>")
	)
	(segment
		(start 444.83528 -276.80412)
		(end 444.71082 -276.67966)
		(width 0.18288)
		(layer "In11.Cu")
		(net "M_H_CPU0_SA_DQS_DN<4>")
	)
	(segment
		(start 432.853592 -276.206458)
		(end 432.08702 -276.206458)
		(width 0.18288)
		(layer "In11.Cu")
		(net "M_H_CPU0_SA_DQS_DN<4>")
	)
	(segment
		(start 420.46779 -275.941028)
		(end 420.194232 -276.214586)
		(width 0.18288)
		(layer "In11.Cu")
		(net "M_H_CPU0_SA_DQS_DN<4>")
	)
	(segment
		(start 381.503174 -260.749034)
		(end 381.49276 -260.75513)
		(width 0.088646)
		(layer "In11.Cu")
		(net "M_H_CPU0_SA_DQS_DN<4>")
	)
	(segment
		(start 440.932316 -277.065486)
		(end 440.391042 -277.065486)
		(width 0.18288)
		(layer "In11.Cu")
		(net "M_H_CPU0_SA_DQS_DN<4>")
	)
	(segment
		(start 388.245096 -263.40054)
		(end 388.092188 -263.247632)
		(width 0.088646)
		(layer "In11.Cu")
		(net "M_H_CPU0_SA_DQS_DN<4>")
	)
	(segment
		(start 379.628146 -260.746494)
		(end 379.613414 -260.75513)
		(width 0.088646)
		(layer "In11.Cu")
		(net "M_H_CPU0_SA_DQS_DN<4>")
	)
	(segment
		(start 436.02783 -275.940774)
		(end 435.55539 -275.940774)
		(width 0.18288)
		(layer "In11.Cu")
		(net "M_H_CPU0_SA_DQS_DN<4>")
	)
	(segment
		(start 371.537738 -260.488176)
		(end 371.595142 -260.430772)
		(width 0.088646)
		(layer "In11.Cu")
		(net "M_H_CPU0_SA_DQS_DN<4>")
	)
	(segment
		(start 410.895546 -275.116544)
		(end 408.825446 -274.258786)
		(width 0.18288)
		(layer "In11.Cu")
		(net "M_H_CPU0_SA_DQS_DN<4>")
	)
	(segment
		(start 385.160012 -261.244842)
		(end 385.160012 -261.2263)
		(width 0.088646)
		(layer "In11.Cu")
		(net "M_H_CPU0_SA_DQS_DN<4>")
	)
	(segment
		(start 424.255946 -277.088346)
		(end 423.977308 -277.088346)
		(width 0.18288)
		(layer "In11.Cu")
		(net "M_H_CPU0_SA_DQS_DN<4>")
	)
	(segment
		(start 450.390514 -274.917408)
		(end 450.229224 -274.756118)
		(width 0.18288)
		(layer "In11.Cu")
		(net "M_H_CPU0_SA_DQS_DN<4>")
	)
	(segment
		(start 435.55539 -275.940774)
		(end 435.289706 -276.206458)
		(width 0.18288)
		(layer "In11.Cu")
		(net "M_H_CPU0_SA_DQS_DN<4>")
	)
	(arc
		(start 377.359418 -260.75513)
		(mid 377.085189 -260.679205)
		(end 376.808746 -260.746494)
		(width 0.088646)
		(layer "In11.Cu")
		(net "M_H_CPU0_SA_DQS_DN<4>")
	)
	(arc
		(start 380.553214 -260.75513)
		(mid 380.366016 -260.805273)
		(end 380.178818 -260.75513)
		(width 0.088646)
		(layer "In11.Cu")
		(net "M_H_CPU0_SA_DQS_DN<4>")
	)
	(arc
		(start 385.338574 -261.56412)
		(mid 385.20766 -261.42776)
		(end 385.160012 -261.244842)
		(width 0.088646)
		(layer "In11.Cu")
		(net "M_H_CPU0_SA_DQS_DN<4>")
	)
	(arc
		(start 387.414262 -263.247632)
		(mid 387.153586 -263.142027)
		(end 387.039612 -262.88492)
		(width 0.088646)
		(layer "In11.Cu")
		(net "M_H_CPU0_SA_DQS_DN<4>")
	)
	(arc
		(start 379.613414 -260.75513)
		(mid 379.426216 -260.805273)
		(end 379.239018 -260.75513)
		(width 0.088646)
		(layer "In11.Cu")
		(net "M_H_CPU0_SA_DQS_DN<4>")
	)
	(arc
		(start 375.854214 -260.75513)
		(mid 375.667016 -260.805273)
		(end 375.479818 -260.75513)
		(width 0.088646)
		(layer "In11.Cu")
		(net "M_H_CPU0_SA_DQS_DN<4>")
	)
	(arc
		(start 374.914668 -260.75513)
		(mid 374.727216 -260.8054)
		(end 374.539764 -260.75513)
		(width 0.088646)
		(layer "In11.Cu")
		(net "M_H_CPU0_SA_DQS_DN<4>")
	)
	(arc
		(start 387.039866 -262.850376)
		(mid 386.753162 -262.380183)
		(end 386.202428 -262.376666)
		(width 0.088646)
		(layer "In11.Cu")
		(net "M_H_CPU0_SA_DQS_DN<4>")
	)
	(arc
		(start 381.49276 -260.75513)
		(mid 381.305562 -260.805273)
		(end 381.118364 -260.75513)
		(width 0.088646)
		(layer "In11.Cu")
		(net "M_H_CPU0_SA_DQS_DN<4>")
	)
	(arc
		(start 372.095014 -260.75513)
		(mid 371.746022 -260.76852)
		(end 371.537738 -260.488176)
		(width 0.088646)
		(layer "In11.Cu")
		(net "M_H_CPU0_SA_DQS_DN<4>")
	)
	(arc
		(start 376.419618 -260.75513)
		(mid 376.145389 -260.679205)
		(end 375.868946 -260.746494)
		(width 0.088646)
		(layer "In11.Cu")
		(net "M_H_CPU0_SA_DQS_DN<4>")
	)
	(arc
		(start 381.118364 -260.75513)
		(mid 380.841805 -260.679421)
		(end 380.563628 -260.749034)
		(width 0.088646)
		(layer "In11.Cu")
		(net "M_H_CPU0_SA_DQS_DN<4>")
	)
	(arc
		(start 373.974614 -260.75513)
		(mid 373.787416 -260.805273)
		(end 373.600218 -260.75513)
		(width 0.088646)
		(layer "In11.Cu")
		(net "M_H_CPU0_SA_DQS_DN<4>")
	)
	(arc
		(start 385.629912 -262.048752)
		(mid 385.551801 -261.771803)
		(end 385.347464 -261.5692)
		(width 0.088646)
		(layer "In11.Cu")
		(net "M_H_CPU0_SA_DQS_DN<4>")
	)
	(arc
		(start 373.034814 -260.75513)
		(mid 372.847616 -260.805273)
		(end 372.660418 -260.75513)
		(width 0.088646)
		(layer "In11.Cu")
		(net "M_H_CPU0_SA_DQS_DN<4>")
	)
	(arc
		(start 378.299218 -260.75513)
		(mid 378.024989 -260.679205)
		(end 377.748546 -260.746494)
		(width 0.088646)
		(layer "In11.Cu")
		(net "M_H_CPU0_SA_DQS_DN<4>")
	)
	(arc
		(start 387.039866 -262.884666)
		(mid 387.039816 -262.87857)
		(end 387.039866 -262.872474)
		(width 0.088646)
		(layer "In11.Cu")
		(net "M_H_CPU0_SA_DQS_DN<4>")
	)
	(arc
		(start 378.673614 -260.75513)
		(mid 378.486416 -260.805273)
		(end 378.299218 -260.75513)
		(width 0.088646)
		(layer "In11.Cu")
		(net "M_H_CPU0_SA_DQS_DN<4>")
	)
	(arc
		(start 386.192014 -262.382762)
		(mid 385.817259 -262.383142)
		(end 385.629912 -262.058658)
		(width 0.088646)
		(layer "In11.Cu")
		(net "M_H_CPU0_SA_DQS_DN<4>")
	)
	(arc
		(start 384.31216 -260.75513)
		(mid 384.124962 -260.805273)
		(end 383.937764 -260.75513)
		(width 0.088646)
		(layer "In11.Cu")
		(net "M_H_CPU0_SA_DQS_DN<4>")
	)
	(arc
		(start 385.160012 -261.2263)
		(mid 384.869534 -260.750581)
		(end 384.31216 -260.75513)
		(width 0.088646)
		(layer "In11.Cu")
		(net "M_H_CPU0_SA_DQS_DN<4>")
	)
	(arc
		(start 377.733814 -260.75513)
		(mid 377.546616 -260.805273)
		(end 377.359418 -260.75513)
		(width 0.088646)
		(layer "In11.Cu")
		(net "M_H_CPU0_SA_DQS_DN<4>")
	)
	(arc
		(start 379.239018 -260.75513)
		(mid 378.964789 -260.679205)
		(end 378.688346 -260.746494)
		(width 0.088646)
		(layer "In11.Cu")
		(net "M_H_CPU0_SA_DQS_DN<4>")
	)
	(arc
		(start 375.479818 -260.75513)
		(mid 375.203005 -260.679294)
		(end 374.924574 -260.749034)
		(width 0.088646)
		(layer "In11.Cu")
		(net "M_H_CPU0_SA_DQS_DN<4>")
	)
	(arc
		(start 380.178818 -260.75513)
		(mid 379.904589 -260.679205)
		(end 379.628146 -260.746494)
		(width 0.088646)
		(layer "In11.Cu")
		(net "M_H_CPU0_SA_DQS_DN<4>")
	)
	(arc
		(start 372.660418 -260.75513)
		(mid 372.386189 -260.679205)
		(end 372.109746 -260.746494)
		(width 0.088646)
		(layer "In11.Cu")
		(net "M_H_CPU0_SA_DQS_DN<4>")
	)
	(arc
		(start 374.539764 -260.75513)
		(mid 374.263205 -260.679421)
		(end 373.985028 -260.749034)
		(width 0.088646)
		(layer "In11.Cu")
		(net "M_H_CPU0_SA_DQS_DN<4>")
	)
	(arc
		(start 382.432814 -260.75513)
		(mid 382.245616 -260.805273)
		(end 382.058418 -260.75513)
		(width 0.088646)
		(layer "In11.Cu")
		(net "M_H_CPU0_SA_DQS_DN<4>")
	)
	(arc
		(start 382.058418 -260.75513)
		(mid 381.781605 -260.679294)
		(end 381.503174 -260.749034)
		(width 0.088646)
		(layer "In11.Cu")
		(net "M_H_CPU0_SA_DQS_DN<4>")
	)
	(arc
		(start 383.37236 -260.75513)
		(mid 383.185162 -260.805273)
		(end 382.997964 -260.75513)
		(width 0.088646)
		(layer "In11.Cu")
		(net "M_H_CPU0_SA_DQS_DN<4>")
	)
	(arc
		(start 382.997964 -260.75513)
		(mid 382.721405 -260.679421)
		(end 382.443228 -260.749034)
		(width 0.088646)
		(layer "In11.Cu")
		(net "M_H_CPU0_SA_DQS_DN<4>")
	)
	(arc
		(start 383.937764 -260.75513)
		(mid 383.655062 -260.679388)
		(end 383.37236 -260.75513)
		(width 0.088646)
		(layer "In11.Cu")
		(net "M_H_CPU0_SA_DQS_DN<4>")
	)
	(arc
		(start 376.794014 -260.75513)
		(mid 376.606816 -260.805273)
		(end 376.419618 -260.75513)
		(width 0.088646)
		(layer "In11.Cu")
		(net "M_H_CPU0_SA_DQS_DN<4>")
	)
	(arc
		(start 373.600218 -260.75513)
		(mid 373.325989 -260.679205)
		(end 373.049546 -260.746494)
		(width 0.088646)
		(layer "In11.Cu")
		(net "M_H_CPU0_SA_DQS_DN<4>")
	)
	(segment
		(start 457.987146 -284.667706)
		(end 457.682092 -284.667706)
		(width 0.20066)
		(layer "F.Cu")
		(net "M_H_CPU0_SA_DQS_DN<3>")
	)
	(segment
		(start 450.911214 -284.016704)
		(end 452.016114 -284.016704)
		(width 0.20066)
		(layer "F.Cu")
		(net "M_H_CPU0_SA_DQS_DN<3>")
	)
	(segment
		(start 454.937368 -284.441646)
		(end 454.789794 -284.441646)
		(width 0.20066)
		(layer "F.Cu")
		(net "M_H_CPU0_SA_DQS_DN<3>")
	)
	(segment
		(start 371.907562 -265.313922)
		(end 371.907816 -265.314176)
		(width 0.20066)
		(layer "F.Cu")
		(net "M_H_CPU0_SA_DQS_DN<3>")
	)
	(segment
		(start 458.970634 -284.016704)
		(end 458.730096 -284.257242)
		(width 0.20066)
		(layer "F.Cu")
		(net "M_H_CPU0_SA_DQS_DN<3>")
	)
	(segment
		(start 452.564754 -284.016704)
		(end 452.016114 -284.016704)
		(width 0.20066)
		(layer "F.Cu")
		(net "M_H_CPU0_SA_DQS_DN<3>")
	)
	(segment
		(start 457.450698 -284.436312)
		(end 457.126594 -284.436312)
		(width 0.20066)
		(layer "F.Cu")
		(net "M_H_CPU0_SA_DQS_DN<3>")
	)
	(segment
		(start 459.559914 -284.016704)
		(end 458.970634 -284.016704)
		(width 0.20066)
		(layer "F.Cu")
		(net "M_H_CPU0_SA_DQS_DN<3>")
	)
	(segment
		(start 454.789794 -284.441646)
		(end 454.518522 -284.712918)
		(width 0.20066)
		(layer "F.Cu")
		(net "M_H_CPU0_SA_DQS_DN<3>")
	)
	(segment
		(start 452.84644 -284.29839)
		(end 452.564754 -284.016704)
		(width 0.20066)
		(layer "F.Cu")
		(net "M_H_CPU0_SA_DQS_DN<3>")
	)
	(segment
		(start 453.582278 -284.29839)
		(end 452.84644 -284.29839)
		(width 0.20066)
		(layer "F.Cu")
		(net "M_H_CPU0_SA_DQS_DN<3>")
	)
	(segment
		(start 457.126594 -284.436312)
		(end 457.12126 -284.441646)
		(width 0.1016)
		(layer "F.Cu")
		(net "M_H_CPU0_SA_DQS_DN<3>")
	)
	(segment
		(start 371.907562 -264.778236)
		(end 371.907562 -265.313922)
		(width 0.20066)
		(layer "F.Cu")
		(net "M_H_CPU0_SA_DQS_DN<3>")
	)
	(segment
		(start 453.996806 -284.712918)
		(end 453.582278 -284.29839)
		(width 0.20066)
		(layer "F.Cu")
		(net "M_H_CPU0_SA_DQS_DN<3>")
	)
	(segment
		(start 454.941686 -284.441646)
		(end 454.937368 -284.441646)
		(width 0.101854)
		(layer "F.Cu")
		(net "M_H_CPU0_SA_DQS_DN<3>")
	)
	(segment
		(start 457.682092 -284.667706)
		(end 457.450698 -284.436312)
		(width 0.20066)
		(layer "F.Cu")
		(net "M_H_CPU0_SA_DQS_DN<3>")
	)
	(segment
		(start 458.730096 -284.257242)
		(end 458.39761 -284.257242)
		(width 0.20066)
		(layer "F.Cu")
		(net "M_H_CPU0_SA_DQS_DN<3>")
	)
	(segment
		(start 457.12126 -284.441646)
		(end 454.941686 -284.441646)
		(width 0.1016)
		(layer "F.Cu")
		(net "M_H_CPU0_SA_DQS_DN<3>")
	)
	(segment
		(start 454.518522 -284.712918)
		(end 453.996806 -284.712918)
		(width 0.20066)
		(layer "F.Cu")
		(net "M_H_CPU0_SA_DQS_DN<3>")
	)
	(segment
		(start 458.39761 -284.257242)
		(end 457.987146 -284.667706)
		(width 0.20066)
		(layer "F.Cu")
		(net "M_H_CPU0_SA_DQS_DN<3>")
	)
	(segment
		(start 408.384502 -284.235398)
		(end 408.20848 -284.235398)
		(width 0.18288)
		(layer "In11.Cu")
		(net "M_H_CPU0_SA_DQS_DN<3>")
	)
	(segment
		(start 447.683382 -285.315152)
		(end 445.228472 -286.332168)
		(width 0.18288)
		(layer "In11.Cu")
		(net "M_H_CPU0_SA_DQS_DN<3>")
	)
	(segment
		(start 381.400812 -266.127992)
		(end 381.400558 -266.10945)
		(width 0.088646)
		(layer "In11.Cu")
		(net "M_H_CPU0_SA_DQS_DN<3>")
	)
	(segment
		(start 426.526452 -287.296352)
		(end 425.699682 -288.123376)
		(width 0.18288)
		(layer "In11.Cu")
		(net "M_H_CPU0_SA_DQS_DN<3>")
	)
	(segment
		(start 408.772614 -284.799532)
		(end 408.772614 -284.62351)
		(width 0.18288)
		(layer "In11.Cu")
		(net "M_H_CPU0_SA_DQS_DN<3>")
	)
	(segment
		(start 372.109746 -265.629898)
		(end 372.095014 -265.638534)
		(width 0.088646)
		(layer "In11.Cu")
		(net "M_H_CPU0_SA_DQS_DN<3>")
	)
	(segment
		(start 439.655458 -287.840674)
		(end 439.361072 -288.13506)
		(width 0.18288)
		(layer "In11.Cu")
		(net "M_H_CPU0_SA_DQS_DN<3>")
	)
	(segment
		(start 425.699682 -288.123376)
		(end 425.370752 -288.123376)
		(width 0.18288)
		(layer "In11.Cu")
		(net "M_H_CPU0_SA_DQS_DN<3>")
	)
	(segment
		(start 409.789122 -285.81604)
		(end 408.772614 -284.799532)
		(width 0.18288)
		(layer "In11.Cu")
		(net "M_H_CPU0_SA_DQS_DN<3>")
	)
	(segment
		(start 435.553612 -286.992568)
		(end 435.270402 -287.275778)
		(width 0.18288)
		(layer "In11.Cu")
		(net "M_H_CPU0_SA_DQS_DN<3>")
	)
	(segment
		(start 450.911214 -284.016704)
		(end 450.625718 -284.3022)
		(width 0.18288)
		(layer "In11.Cu")
		(net "M_H_CPU0_SA_DQS_DN<3>")
	)
	(segment
		(start 414.496504 -286.36976)
		(end 414.217866 -286.091122)
		(width 0.18288)
		(layer "In11.Cu")
		(net "M_H_CPU0_SA_DQS_DN<3>")
	)
	(segment
		(start 420.926768 -288.69259)
		(end 420.466012 -288.69259)
		(width 0.18288)
		(layer "In11.Cu")
		(net "M_H_CPU0_SA_DQS_DN<3>")
	)
	(segment
		(start 408.20848 -284.235398)
		(end 407.681938 -283.708856)
		(width 0.18288)
		(layer "In11.Cu")
		(net "M_H_CPU0_SA_DQS_DN<3>")
	)
	(segment
		(start 385.829048 -268.90091)
		(end 385.806696 -268.887956)
		(width 0.088646)
		(layer "In11.Cu")
		(net "M_H_CPU0_SA_DQS_DN<3>")
	)
	(segment
		(start 418.723572 -288.204656)
		(end 415.978086 -286.36976)
		(width 0.18288)
		(layer "In11.Cu")
		(net "M_H_CPU0_SA_DQS_DN<3>")
	)
	(segment
		(start 377.748546 -265.629898)
		(end 377.733814 -265.638534)
		(width 0.088646)
		(layer "In11.Cu")
		(net "M_H_CPU0_SA_DQS_DN<3>")
	)
	(segment
		(start 387.226302 -269.08125)
		(end 386.952998 -269.08125)
		(width 0.088646)
		(layer "In11.Cu")
		(net "M_H_CPU0_SA_DQS_DN<3>")
	)
	(segment
		(start 445.228472 -286.332168)
		(end 444.037466 -286.332168)
		(width 0.18288)
		(layer "In11.Cu")
		(net "M_H_CPU0_SA_DQS_DN<3>")
	)
	(segment
		(start 411.271974 -285.69158)
		(end 410.723334 -285.69158)
		(width 0.18288)
		(layer "In11.Cu")
		(net "M_H_CPU0_SA_DQS_DN<3>")
	)
	(segment
		(start 382.810512 -268.58214)
		(end 382.810512 -268.569694)
		(width 0.088646)
		(layer "In11.Cu")
		(net "M_H_CPU0_SA_DQS_DN<3>")
	)
	(segment
		(start 428.073566 -286.65551)
		(end 426.526452 -287.296352)
		(width 0.18288)
		(layer "In11.Cu")
		(net "M_H_CPU0_SA_DQS_DN<3>")
	)
	(segment
		(start 390.970262 -269.43812)
		(end 388.612888 -269.43812)
		(width 0.18288)
		(layer "In11.Cu")
		(net "M_H_CPU0_SA_DQS_DN<3>")
	)
	(segment
		(start 435.254654 -287.2867)
		(end 432.432206 -287.2867)
		(width 0.18288)
		(layer "In11.Cu")
		(net "M_H_CPU0_SA_DQS_DN<3>")
	)
	(segment
		(start 387.99008 -269.277084)
		(end 387.422136 -269.277084)
		(width 0.088646)
		(layer "In11.Cu")
		(net "M_H_CPU0_SA_DQS_DN<3>")
	)
	(segment
		(start 414.217866 -286.091122)
		(end 412.568898 -286.091122)
		(width 0.18288)
		(layer "In11.Cu")
		(net "M_H_CPU0_SA_DQS_DN<3>")
	)
	(segment
		(start 432.432206 -287.2867)
		(end 430.908206 -286.65551)
		(width 0.18288)
		(layer "In11.Cu")
		(net "M_H_CPU0_SA_DQS_DN<3>")
	)
	(segment
		(start 440.13501 -287.840674)
		(end 439.655458 -287.840674)
		(width 0.18288)
		(layer "In11.Cu")
		(net "M_H_CPU0_SA_DQS_DN<3>")
	)
	(segment
		(start 374.924574 -265.632438)
		(end 374.91416 -265.638534)
		(width 0.088646)
		(layer "In11.Cu")
		(net "M_H_CPU0_SA_DQS_DN<3>")
	)
	(segment
		(start 379.628146 -265.629898)
		(end 379.613414 -265.638534)
		(width 0.088646)
		(layer "In11.Cu")
		(net "M_H_CPU0_SA_DQS_DN<3>")
	)
	(segment
		(start 422.467024 -288.505646)
		(end 422.169082 -288.804096)
		(width 0.18288)
		(layer "In11.Cu")
		(net "M_H_CPU0_SA_DQS_DN<3>")
	)
	(segment
		(start 410.723334 -285.69158)
		(end 410.598874 -285.81604)
		(width 0.18288)
		(layer "In11.Cu")
		(net "M_H_CPU0_SA_DQS_DN<3>")
	)
	(segment
		(start 410.598874 -285.81604)
		(end 409.789122 -285.81604)
		(width 0.18288)
		(layer "In11.Cu")
		(net "M_H_CPU0_SA_DQS_DN<3>")
	)
	(segment
		(start 438.800494 -287.84931)
		(end 437.769762 -287.84931)
		(width 0.18288)
		(layer "In11.Cu")
		(net "M_H_CPU0_SA_DQS_DN<3>")
	)
	(segment
		(start 412.29534 -285.81604)
		(end 411.396434 -285.81604)
		(width 0.18288)
		(layer "In11.Cu")
		(net "M_H_CPU0_SA_DQS_DN<3>")
	)
	(segment
		(start 420.210742 -288.94786)
		(end 419.466776 -288.94786)
		(width 0.18288)
		(layer "In11.Cu")
		(net "M_H_CPU0_SA_DQS_DN<3>")
	)
	(segment
		(start 448.11188 -285.315152)
		(end 447.683382 -285.315152)
		(width 0.18288)
		(layer "In11.Cu")
		(net "M_H_CPU0_SA_DQS_DN<3>")
	)
	(segment
		(start 423.452544 -288.097722)
		(end 422.467024 -288.505646)
		(width 0.18288)
		(layer "In11.Cu")
		(net "M_H_CPU0_SA_DQS_DN<3>")
	)
	(segment
		(start 382.068324 -267.27277)
		(end 382.058418 -267.266166)
		(width 0.088646)
		(layer "In11.Cu")
		(net "M_H_CPU0_SA_DQS_DN<3>")
	)
	(segment
		(start 373.049546 -265.629898)
		(end 373.034814 -265.638534)
		(width 0.088646)
		(layer "In11.Cu")
		(net "M_H_CPU0_SA_DQS_DN<3>")
	)
	(segment
		(start 373.985028 -265.632438)
		(end 373.974614 -265.638534)
		(width 0.088646)
		(layer "In11.Cu")
		(net "M_H_CPU0_SA_DQS_DN<3>")
	)
	(segment
		(start 439.086244 -288.13506)
		(end 438.800494 -287.84931)
		(width 0.18288)
		(layer "In11.Cu")
		(net "M_H_CPU0_SA_DQS_DN<3>")
	)
	(segment
		(start 449.31203 -284.115002)
		(end 448.11188 -285.315152)
		(width 0.18288)
		(layer "In11.Cu")
		(net "M_H_CPU0_SA_DQS_DN<3>")
	)
	(segment
		(start 437.769762 -287.84931)
		(end 437.17845 -287.257998)
		(width 0.18288)
		(layer "In11.Cu")
		(net "M_H_CPU0_SA_DQS_DN<3>")
	)
	(segment
		(start 382.340104 -267.734288)
		(end 382.340104 -267.73378)
		(width 0.088646)
		(layer "In11.Cu")
		(net "M_H_CPU0_SA_DQS_DN<3>")
	)
	(segment
		(start 441.438538 -287.675574)
		(end 440.994292 -288.120074)
		(width 0.18288)
		(layer "In11.Cu")
		(net "M_H_CPU0_SA_DQS_DN<3>")
	)
	(segment
		(start 412.568898 -286.091122)
		(end 412.29534 -285.81604)
		(width 0.18288)
		(layer "In11.Cu")
		(net "M_H_CPU0_SA_DQS_DN<3>")
	)
	(segment
		(start 411.396434 -285.81604)
		(end 411.271974 -285.69158)
		(width 0.18288)
		(layer "In11.Cu")
		(net "M_H_CPU0_SA_DQS_DN<3>")
	)
	(segment
		(start 380.563628 -265.632438)
		(end 380.553214 -265.638534)
		(width 0.088646)
		(layer "In11.Cu")
		(net "M_H_CPU0_SA_DQS_DN<3>")
	)
	(segment
		(start 424.27779 -288.097722)
		(end 423.452544 -288.097722)
		(width 0.18288)
		(layer "In11.Cu")
		(net "M_H_CPU0_SA_DQS_DN<3>")
	)
	(segment
		(start 415.978086 -286.36976)
		(end 414.496504 -286.36976)
		(width 0.18288)
		(layer "In11.Cu")
		(net "M_H_CPU0_SA_DQS_DN<3>")
	)
	(segment
		(start 376.808746 -265.629898)
		(end 376.794014 -265.638534)
		(width 0.088646)
		(layer "In11.Cu")
		(net "M_H_CPU0_SA_DQS_DN<3>")
	)
	(segment
		(start 420.466012 -288.69259)
		(end 420.210742 -288.94786)
		(width 0.18288)
		(layer "In11.Cu")
		(net "M_H_CPU0_SA_DQS_DN<3>")
	)
	(segment
		(start 382.998218 -268.894052)
		(end 382.99771 -268.894306)
		(width 0.088646)
		(layer "In11.Cu")
		(net "M_H_CPU0_SA_DQS_DN<3>")
	)
	(segment
		(start 421.200326 -288.966148)
		(end 420.926768 -288.69259)
		(width 0.18288)
		(layer "In11.Cu")
		(net "M_H_CPU0_SA_DQS_DN<3>")
	)
	(segment
		(start 405.240998 -283.708856)
		(end 390.970262 -269.43812)
		(width 0.18288)
		(layer "In11.Cu")
		(net "M_H_CPU0_SA_DQS_DN<3>")
	)
	(segment
		(start 424.53306 -287.842452)
		(end 424.27779 -288.097722)
		(width 0.18288)
		(layer "In11.Cu")
		(net "M_H_CPU0_SA_DQS_DN<3>")
	)
	(segment
		(start 440.994292 -288.120074)
		(end 440.41441 -288.120074)
		(width 0.18288)
		(layer "In11.Cu")
		(net "M_H_CPU0_SA_DQS_DN<3>")
	)
	(segment
		(start 371.537738 -265.371326)
		(end 371.594888 -265.314176)
		(width 0.088646)
		(layer "In11.Cu")
		(net "M_H_CPU0_SA_DQS_DN<3>")
	)
	(segment
		(start 425.089828 -287.842452)
		(end 424.53306 -287.842452)
		(width 0.18288)
		(layer "In11.Cu")
		(net "M_H_CPU0_SA_DQS_DN<3>")
	)
	(segment
		(start 371.594888 -265.314176)
		(end 371.907816 -265.314176)
		(width 0.088646)
		(layer "In11.Cu")
		(net "M_H_CPU0_SA_DQS_DN<3>")
	)
	(segment
		(start 450.192902 -284.3022)
		(end 450.005704 -284.115002)
		(width 0.18288)
		(layer "In11.Cu")
		(net "M_H_CPU0_SA_DQS_DN<3>")
	)
	(segment
		(start 382.058418 -267.266166)
		(end 382.049528 -267.261086)
		(width 0.088646)
		(layer "In11.Cu")
		(net "M_H_CPU0_SA_DQS_DN<3>")
	)
	(segment
		(start 419.466776 -288.94786)
		(end 418.723572 -288.204656)
		(width 0.18288)
		(layer "In11.Cu")
		(net "M_H_CPU0_SA_DQS_DN<3>")
	)
	(segment
		(start 421.777414 -288.966148)
		(end 421.200326 -288.966148)
		(width 0.18288)
		(layer "In11.Cu")
		(net "M_H_CPU0_SA_DQS_DN<3>")
	)
	(segment
		(start 386.778246 -268.906498)
		(end 386.738622 -268.883638)
		(width 0.088646)
		(layer "In11.Cu")
		(net "M_H_CPU0_SA_DQS_DN<3>")
	)
	(segment
		(start 387.422136 -269.277084)
		(end 387.226302 -269.08125)
		(width 0.088646)
		(layer "In11.Cu")
		(net "M_H_CPU0_SA_DQS_DN<3>")
	)
	(segment
		(start 388.612888 -269.43812)
		(end 388.553198 -269.49781)
		(width 0.088646)
		(layer "In11.Cu")
		(net "M_H_CPU0_SA_DQS_DN<3>")
	)
	(segment
		(start 407.681938 -283.708856)
		(end 405.240998 -283.708856)
		(width 0.18288)
		(layer "In11.Cu")
		(net "M_H_CPU0_SA_DQS_DN<3>")
	)
	(segment
		(start 436.030624 -286.992568)
		(end 435.553612 -286.992568)
		(width 0.18288)
		(layer "In11.Cu")
		(net "M_H_CPU0_SA_DQS_DN<3>")
	)
	(segment
		(start 388.553198 -269.49781)
		(end 388.210806 -269.49781)
		(width 0.088646)
		(layer "In11.Cu")
		(net "M_H_CPU0_SA_DQS_DN<3>")
	)
	(segment
		(start 436.296054 -287.257998)
		(end 436.030624 -286.992568)
		(width 0.18288)
		(layer "In11.Cu")
		(net "M_H_CPU0_SA_DQS_DN<3>")
	)
	(segment
		(start 437.17845 -287.257998)
		(end 436.296054 -287.257998)
		(width 0.18288)
		(layer "In11.Cu")
		(net "M_H_CPU0_SA_DQS_DN<3>")
	)
	(segment
		(start 382.538478 -268.086586)
		(end 382.52273 -268.077442)
		(width 0.088646)
		(layer "In11.Cu")
		(net "M_H_CPU0_SA_DQS_DN<3>")
	)
	(segment
		(start 450.625718 -284.3022)
		(end 450.192902 -284.3022)
		(width 0.18288)
		(layer "In11.Cu")
		(net "M_H_CPU0_SA_DQS_DN<3>")
	)
	(segment
		(start 378.688346 -265.629898)
		(end 378.673614 -265.638534)
		(width 0.088646)
		(layer "In11.Cu")
		(net "M_H_CPU0_SA_DQS_DN<3>")
	)
	(segment
		(start 408.772614 -284.62351)
		(end 408.384502 -284.235398)
		(width 0.18288)
		(layer "In11.Cu")
		(net "M_H_CPU0_SA_DQS_DN<3>")
	)
	(segment
		(start 422.169082 -288.804096)
		(end 421.777414 -288.966148)
		(width 0.18288)
		(layer "In11.Cu")
		(net "M_H_CPU0_SA_DQS_DN<3>")
	)
	(segment
		(start 425.370752 -288.123376)
		(end 425.089828 -287.842452)
		(width 0.18288)
		(layer "In11.Cu")
		(net "M_H_CPU0_SA_DQS_DN<3>")
	)
	(segment
		(start 435.270402 -287.275778)
		(end 435.265576 -287.275778)
		(width 0.18288)
		(layer "In11.Cu")
		(net "M_H_CPU0_SA_DQS_DN<3>")
	)
	(segment
		(start 386.952998 -269.08125)
		(end 386.778246 -268.906498)
		(width 0.088646)
		(layer "In11.Cu")
		(net "M_H_CPU0_SA_DQS_DN<3>")
	)
	(segment
		(start 444.037466 -286.332168)
		(end 442.717174 -286.878776)
		(width 0.18288)
		(layer "In11.Cu")
		(net "M_H_CPU0_SA_DQS_DN<3>")
	)
	(segment
		(start 442.261244 -287.334706)
		(end 441.438538 -287.675574)
		(width 0.18288)
		(layer "In11.Cu")
		(net "M_H_CPU0_SA_DQS_DN<3>")
	)
	(segment
		(start 375.868946 -265.629898)
		(end 375.854214 -265.638534)
		(width 0.088646)
		(layer "In11.Cu")
		(net "M_H_CPU0_SA_DQS_DN<3>")
	)
	(segment
		(start 435.265576 -287.275778)
		(end 435.254654 -287.2867)
		(width 0.18288)
		(layer "In11.Cu")
		(net "M_H_CPU0_SA_DQS_DN<3>")
	)
	(segment
		(start 440.41441 -288.120074)
		(end 440.13501 -287.840674)
		(width 0.18288)
		(layer "In11.Cu")
		(net "M_H_CPU0_SA_DQS_DN<3>")
	)
	(segment
		(start 430.908206 -286.65551)
		(end 428.073566 -286.65551)
		(width 0.18288)
		(layer "In11.Cu")
		(net "M_H_CPU0_SA_DQS_DN<3>")
	)
	(segment
		(start 383.383028 -268.887956)
		(end 383.372614 -268.894052)
		(width 0.088646)
		(layer "In11.Cu")
		(net "M_H_CPU0_SA_DQS_DN<3>")
	)
	(segment
		(start 388.210806 -269.49781)
		(end 387.99008 -269.277084)
		(width 0.088646)
		(layer "In11.Cu")
		(net "M_H_CPU0_SA_DQS_DN<3>")
	)
	(segment
		(start 450.005704 -284.115002)
		(end 449.31203 -284.115002)
		(width 0.18288)
		(layer "In11.Cu")
		(net "M_H_CPU0_SA_DQS_DN<3>")
	)
	(segment
		(start 381.600456 -266.459462)
		(end 381.579374 -266.44727)
		(width 0.088646)
		(layer "In11.Cu")
		(net "M_H_CPU0_SA_DQS_DN<3>")
	)
	(segment
		(start 439.361072 -288.13506)
		(end 439.086244 -288.13506)
		(width 0.18288)
		(layer "In11.Cu")
		(net "M_H_CPU0_SA_DQS_DN<3>")
	)
	(segment
		(start 442.717174 -286.878776)
		(end 442.261244 -287.334706)
		(width 0.18288)
		(layer "In11.Cu")
		(net "M_H_CPU0_SA_DQS_DN<3>")
	)
	(arc
		(start 382.810512 -268.569694)
		(mid 382.73782 -268.292489)
		(end 382.538478 -268.086586)
		(width 0.088646)
		(layer "In11.Cu")
		(net "M_H_CPU0_SA_DQS_DN<3>")
	)
	(arc
		(start 378.673614 -265.638534)
		(mid 378.486416 -265.688677)
		(end 378.299218 -265.638534)
		(width 0.088646)
		(layer "In11.Cu")
		(net "M_H_CPU0_SA_DQS_DN<3>")
	)
	(arc
		(start 380.553214 -265.638534)
		(mid 380.366016 -265.688677)
		(end 380.178818 -265.638534)
		(width 0.088646)
		(layer "In11.Cu")
		(net "M_H_CPU0_SA_DQS_DN<3>")
	)
	(arc
		(start 383.937764 -268.894052)
		(mid 383.661205 -268.818309)
		(end 383.383028 -268.887956)
		(width 0.088646)
		(layer "In11.Cu")
		(net "M_H_CPU0_SA_DQS_DN<3>")
	)
	(arc
		(start 373.600218 -265.638534)
		(mid 373.325989 -265.562609)
		(end 373.049546 -265.629898)
		(width 0.088646)
		(layer "In11.Cu")
		(net "M_H_CPU0_SA_DQS_DN<3>")
	)
	(arc
		(start 382.99771 -268.894306)
		(mid 382.863678 -268.762458)
		(end 382.810512 -268.58214)
		(width 0.088646)
		(layer "In11.Cu")
		(net "M_H_CPU0_SA_DQS_DN<3>")
	)
	(arc
		(start 372.660418 -265.638534)
		(mid 372.386189 -265.562609)
		(end 372.109746 -265.629898)
		(width 0.088646)
		(layer "In11.Cu")
		(net "M_H_CPU0_SA_DQS_DN<3>")
	)
	(arc
		(start 381.870966 -266.941808)
		(mid 381.798731 -266.665284)
		(end 381.600456 -266.459462)
		(width 0.088646)
		(layer "In11.Cu")
		(net "M_H_CPU0_SA_DQS_DN<3>")
	)
	(arc
		(start 386.191506 -268.894052)
		(mid 386.011159 -268.944255)
		(end 385.829048 -268.90091)
		(width 0.088646)
		(layer "In11.Cu")
		(net "M_H_CPU0_SA_DQS_DN<3>")
	)
	(arc
		(start 380.178818 -265.638534)
		(mid 379.904589 -265.562609)
		(end 379.628146 -265.629898)
		(width 0.088646)
		(layer "In11.Cu")
		(net "M_H_CPU0_SA_DQS_DN<3>")
	)
	(arc
		(start 375.854214 -265.638534)
		(mid 375.667016 -265.688677)
		(end 375.479818 -265.638534)
		(width 0.088646)
		(layer "In11.Cu")
		(net "M_H_CPU0_SA_DQS_DN<3>")
	)
	(arc
		(start 382.340612 -267.755878)
		(mid 382.34046 -267.745081)
		(end 382.340104 -267.734288)
		(width 0.088646)
		(layer "In11.Cu")
		(net "M_H_CPU0_SA_DQS_DN<3>")
	)
	(arc
		(start 379.613414 -265.638534)
		(mid 379.426216 -265.688677)
		(end 379.239018 -265.638534)
		(width 0.088646)
		(layer "In11.Cu")
		(net "M_H_CPU0_SA_DQS_DN<3>")
	)
	(arc
		(start 381.579374 -266.44727)
		(mid 381.44846 -266.31091)
		(end 381.400812 -266.127992)
		(width 0.088646)
		(layer "In11.Cu")
		(net "M_H_CPU0_SA_DQS_DN<3>")
	)
	(arc
		(start 386.738622 -268.883638)
		(mid 386.463718 -268.818234)
		(end 386.191506 -268.894052)
		(width 0.088646)
		(layer "In11.Cu")
		(net "M_H_CPU0_SA_DQS_DN<3>")
	)
	(arc
		(start 381.400558 -266.10945)
		(mid 381.115424 -265.636983)
		(end 380.563628 -265.632438)
		(width 0.088646)
		(layer "In11.Cu")
		(net "M_H_CPU0_SA_DQS_DN<3>")
	)
	(arc
		(start 373.974614 -265.638534)
		(mid 373.787416 -265.688677)
		(end 373.600218 -265.638534)
		(width 0.088646)
		(layer "In11.Cu")
		(net "M_H_CPU0_SA_DQS_DN<3>")
	)
	(arc
		(start 377.733814 -265.638534)
		(mid 377.546616 -265.688677)
		(end 377.359418 -265.638534)
		(width 0.088646)
		(layer "In11.Cu")
		(net "M_H_CPU0_SA_DQS_DN<3>")
	)
	(arc
		(start 374.539764 -265.638534)
		(mid 374.263205 -265.562825)
		(end 373.985028 -265.632438)
		(width 0.088646)
		(layer "In11.Cu")
		(net "M_H_CPU0_SA_DQS_DN<3>")
	)
	(arc
		(start 378.299218 -265.638534)
		(mid 378.024989 -265.562609)
		(end 377.748546 -265.629898)
		(width 0.088646)
		(layer "In11.Cu")
		(net "M_H_CPU0_SA_DQS_DN<3>")
	)
	(arc
		(start 379.239018 -265.638534)
		(mid 378.964789 -265.562609)
		(end 378.688346 -265.629898)
		(width 0.088646)
		(layer "In11.Cu")
		(net "M_H_CPU0_SA_DQS_DN<3>")
	)
	(arc
		(start 372.095014 -265.638534)
		(mid 371.745909 -265.65187)
		(end 371.537738 -265.371326)
		(width 0.088646)
		(layer "In11.Cu")
		(net "M_H_CPU0_SA_DQS_DN<3>")
	)
	(arc
		(start 376.794014 -265.638534)
		(mid 376.606816 -265.688677)
		(end 376.419618 -265.638534)
		(width 0.088646)
		(layer "In11.Cu")
		(net "M_H_CPU0_SA_DQS_DN<3>")
	)
	(arc
		(start 377.359418 -265.638534)
		(mid 377.085189 -265.562609)
		(end 376.808746 -265.629898)
		(width 0.088646)
		(layer "In11.Cu")
		(net "M_H_CPU0_SA_DQS_DN<3>")
	)
	(arc
		(start 385.806696 -268.887956)
		(mid 385.528518 -268.818233)
		(end 385.25196 -268.894052)
		(width 0.088646)
		(layer "In11.Cu")
		(net "M_H_CPU0_SA_DQS_DN<3>")
	)
	(arc
		(start 375.479818 -265.638534)
		(mid 375.203005 -265.562698)
		(end 374.924574 -265.632438)
		(width 0.088646)
		(layer "In11.Cu")
		(net "M_H_CPU0_SA_DQS_DN<3>")
	)
	(arc
		(start 382.52273 -268.077442)
		(mid 382.389295 -267.94067)
		(end 382.340612 -267.755878)
		(width 0.088646)
		(layer "In11.Cu")
		(net "M_H_CPU0_SA_DQS_DN<3>")
	)
	(arc
		(start 376.419618 -265.638534)
		(mid 376.145389 -265.562609)
		(end 375.868946 -265.629898)
		(width 0.088646)
		(layer "In11.Cu")
		(net "M_H_CPU0_SA_DQS_DN<3>")
	)
	(arc
		(start 384.877564 -268.894052)
		(mid 384.594862 -268.818276)
		(end 384.31216 -268.894052)
		(width 0.088646)
		(layer "In11.Cu")
		(net "M_H_CPU0_SA_DQS_DN<3>")
	)
	(arc
		(start 383.372614 -268.894052)
		(mid 383.185416 -268.944195)
		(end 382.998218 -268.894052)
		(width 0.088646)
		(layer "In11.Cu")
		(net "M_H_CPU0_SA_DQS_DN<3>")
	)
	(arc
		(start 382.340104 -267.73378)
		(mid 382.262215 -267.469093)
		(end 382.068324 -267.27277)
		(width 0.088646)
		(layer "In11.Cu")
		(net "M_H_CPU0_SA_DQS_DN<3>")
	)
	(arc
		(start 384.31216 -268.894052)
		(mid 384.124962 -268.944195)
		(end 383.937764 -268.894052)
		(width 0.088646)
		(layer "In11.Cu")
		(net "M_H_CPU0_SA_DQS_DN<3>")
	)
	(arc
		(start 382.049528 -267.261086)
		(mid 381.918614 -267.124726)
		(end 381.870966 -266.941808)
		(width 0.088646)
		(layer "In11.Cu")
		(net "M_H_CPU0_SA_DQS_DN<3>")
	)
	(arc
		(start 373.034814 -265.638534)
		(mid 372.847616 -265.688677)
		(end 372.660418 -265.638534)
		(width 0.088646)
		(layer "In11.Cu")
		(net "M_H_CPU0_SA_DQS_DN<3>")
	)
	(arc
		(start 385.25196 -268.894052)
		(mid 385.064762 -268.944195)
		(end 384.877564 -268.894052)
		(width 0.088646)
		(layer "In11.Cu")
		(net "M_H_CPU0_SA_DQS_DN<3>")
	)
	(arc
		(start 374.91416 -265.638534)
		(mid 374.726962 -265.688677)
		(end 374.539764 -265.638534)
		(width 0.088646)
		(layer "In11.Cu")
		(net "M_H_CPU0_SA_DQS_DN<3>")
	)
	(segment
		(start 371.907562 -269.66164)
		(end 371.907816 -270.167862)
		(width 0.20066)
		(layer "F.Cu")
		(net "M_H_CPU0_SA_DQS_DN<2>")
	)
	(segment
		(start 458.730096 -293.607236)
		(end 458.39761 -293.607236)
		(width 0.20066)
		(layer "F.Cu")
		(net "M_H_CPU0_SA_DQS_DN<2>")
	)
	(segment
		(start 452.564754 -293.366698)
		(end 452.016114 -293.366698)
		(width 0.20066)
		(layer "F.Cu")
		(net "M_H_CPU0_SA_DQS_DN<2>")
	)
	(segment
		(start 457.126594 -293.786306)
		(end 457.12126 -293.79164)
		(width 0.1016)
		(layer "F.Cu")
		(net "M_H_CPU0_SA_DQS_DN<2>")
	)
	(segment
		(start 454.789794 -293.79164)
		(end 454.518522 -294.062912)
		(width 0.20066)
		(layer "F.Cu")
		(net "M_H_CPU0_SA_DQS_DN<2>")
	)
	(segment
		(start 457.987146 -294.0177)
		(end 457.682092 -294.0177)
		(width 0.20066)
		(layer "F.Cu")
		(net "M_H_CPU0_SA_DQS_DN<2>")
	)
	(segment
		(start 459.559914 -293.366698)
		(end 458.970634 -293.366698)
		(width 0.20066)
		(layer "F.Cu")
		(net "M_H_CPU0_SA_DQS_DN<2>")
	)
	(segment
		(start 453.582278 -293.648384)
		(end 452.84644 -293.648384)
		(width 0.20066)
		(layer "F.Cu")
		(net "M_H_CPU0_SA_DQS_DN<2>")
	)
	(segment
		(start 457.12126 -293.79164)
		(end 454.941686 -293.79164)
		(width 0.1016)
		(layer "F.Cu")
		(net "M_H_CPU0_SA_DQS_DN<2>")
	)
	(segment
		(start 457.682092 -294.0177)
		(end 457.450698 -293.786306)
		(width 0.20066)
		(layer "F.Cu")
		(net "M_H_CPU0_SA_DQS_DN<2>")
	)
	(segment
		(start 452.84644 -293.648384)
		(end 452.564754 -293.366698)
		(width 0.20066)
		(layer "F.Cu")
		(net "M_H_CPU0_SA_DQS_DN<2>")
	)
	(segment
		(start 450.911214 -293.366698)
		(end 452.016114 -293.366698)
		(width 0.20066)
		(layer "F.Cu")
		(net "M_H_CPU0_SA_DQS_DN<2>")
	)
	(segment
		(start 454.937368 -293.79164)
		(end 454.789794 -293.79164)
		(width 0.20066)
		(layer "F.Cu")
		(net "M_H_CPU0_SA_DQS_DN<2>")
	)
	(segment
		(start 453.996806 -294.062912)
		(end 453.582278 -293.648384)
		(width 0.20066)
		(layer "F.Cu")
		(net "M_H_CPU0_SA_DQS_DN<2>")
	)
	(segment
		(start 454.518522 -294.062912)
		(end 453.996806 -294.062912)
		(width 0.20066)
		(layer "F.Cu")
		(net "M_H_CPU0_SA_DQS_DN<2>")
	)
	(segment
		(start 457.450698 -293.786306)
		(end 457.126594 -293.786306)
		(width 0.20066)
		(layer "F.Cu")
		(net "M_H_CPU0_SA_DQS_DN<2>")
	)
	(segment
		(start 458.970634 -293.366698)
		(end 458.730096 -293.607236)
		(width 0.20066)
		(layer "F.Cu")
		(net "M_H_CPU0_SA_DQS_DN<2>")
	)
	(segment
		(start 454.941686 -293.79164)
		(end 454.937368 -293.79164)
		(width 0.101854)
		(layer "F.Cu")
		(net "M_H_CPU0_SA_DQS_DN<2>")
	)
	(segment
		(start 371.907816 -270.167862)
		(end 371.907816 -270.19758)
		(width 0.20066)
		(layer "F.Cu")
		(net "M_H_CPU0_SA_DQS_DN<2>")
	)
	(segment
		(start 458.39761 -293.607236)
		(end 457.987146 -294.0177)
		(width 0.20066)
		(layer "F.Cu")
		(net "M_H_CPU0_SA_DQS_DN<2>")
	)
	(segment
		(start 400.151092 -290.010596)
		(end 400.151092 -288.061146)
		(width 0.18288)
		(layer "In11.Cu")
		(net "M_H_CPU0_SA_DQS_DN<2>")
	)
	(segment
		(start 420.935912 -299.741844)
		(end 420.490142 -299.741844)
		(width 0.18288)
		(layer "In11.Cu")
		(net "M_H_CPU0_SA_DQS_DN<2>")
	)
	(segment
		(start 407.185622 -295.513506)
		(end 405.973788 -294.301672)
		(width 0.18288)
		(layer "In11.Cu")
		(net "M_H_CPU0_SA_DQS_DN<2>")
	)
	(segment
		(start 374.539764 -270.521938)
		(end 374.532652 -270.517874)
		(width 0.088646)
		(layer "In11.Cu")
		(net "M_H_CPU0_SA_DQS_DN<2>")
	)
	(segment
		(start 374.54459 -270.524732)
		(end 374.539764 -270.521938)
		(width 0.088646)
		(layer "In11.Cu")
		(net "M_H_CPU0_SA_DQS_DN<2>")
	)
	(segment
		(start 419.536626 -300.00829)
		(end 417.653724 -298.125388)
		(width 0.18288)
		(layer "In11.Cu")
		(net "M_H_CPU0_SA_DQS_DN<2>")
	)
	(segment
		(start 387.182868 -275.65604)
		(end 386.78358 -275.65604)
		(width 0.088646)
		(layer "In11.Cu")
		(net "M_H_CPU0_SA_DQS_DN<2>")
	)
	(segment
		(start 387.242558 -275.59635)
		(end 387.182868 -275.65604)
		(width 0.088646)
		(layer "In11.Cu")
		(net "M_H_CPU0_SA_DQS_DN<2>")
	)
	(segment
		(start 375.868946 -270.513302)
		(end 375.854214 -270.521938)
		(width 0.088646)
		(layer "In11.Cu")
		(net "M_H_CPU0_SA_DQS_DN<2>")
	)
	(segment
		(start 371.537484 -270.254984)
		(end 371.594888 -270.19758)
		(width 0.088646)
		(layer "In11.Cu")
		(net "M_H_CPU0_SA_DQS_DN<2>")
	)
	(segment
		(start 428.130716 -298.942506)
		(end 427.686978 -298.498768)
		(width 0.18288)
		(layer "In11.Cu")
		(net "M_H_CPU0_SA_DQS_DN<2>")
	)
	(segment
		(start 437.17972 -298.316142)
		(end 436.292498 -298.316142)
		(width 0.18288)
		(layer "In11.Cu")
		(net "M_H_CPU0_SA_DQS_DN<2>")
	)
	(segment
		(start 424.260518 -299.147738)
		(end 422.645078 -299.147738)
		(width 0.18288)
		(layer "In11.Cu")
		(net "M_H_CPU0_SA_DQS_DN<2>")
	)
	(segment
		(start 412.134812 -296.35196)
		(end 408.690826 -296.35196)
		(width 0.18288)
		(layer "In11.Cu")
		(net "M_H_CPU0_SA_DQS_DN<2>")
	)
	(segment
		(start 425.980098 -299.166026)
		(end 425.358306 -299.166026)
		(width 0.18288)
		(layer "In11.Cu")
		(net "M_H_CPU0_SA_DQS_DN<2>")
	)
	(segment
		(start 440.957716 -299.178472)
		(end 440.406028 -299.178472)
		(width 0.18288)
		(layer "In11.Cu")
		(net "M_H_CPU0_SA_DQS_DN<2>")
	)
	(segment
		(start 378.768864 -272.96364)
		(end 378.759974 -272.95856)
		(width 0.088646)
		(layer "In11.Cu")
		(net "M_H_CPU0_SA_DQS_DN<2>")
	)
	(segment
		(start 408.690826 -296.35196)
		(end 407.852372 -295.513506)
		(width 0.18288)
		(layer "In11.Cu")
		(net "M_H_CPU0_SA_DQS_DN<2>")
	)
	(segment
		(start 445.171576 -295.804336)
		(end 443.768226 -297.207686)
		(width 0.18288)
		(layer "In11.Cu")
		(net "M_H_CPU0_SA_DQS_DN<2>")
	)
	(segment
		(start 382.447546 -273.76882)
		(end 382.432814 -273.777456)
		(width 0.088646)
		(layer "In11.Cu")
		(net "M_H_CPU0_SA_DQS_DN<2>")
	)
	(segment
		(start 373.599964 -270.521938)
		(end 373.592852 -270.517874)
		(width 0.088646)
		(layer "In11.Cu")
		(net "M_H_CPU0_SA_DQS_DN<2>")
	)
	(segment
		(start 438.027572 -299.163994)
		(end 437.17972 -298.316142)
		(width 0.18288)
		(layer "In11.Cu")
		(net "M_H_CPU0_SA_DQS_DN<2>")
	)
	(segment
		(start 440.12231 -298.894754)
		(end 439.651394 -298.894754)
		(width 0.18288)
		(layer "In11.Cu")
		(net "M_H_CPU0_SA_DQS_DN<2>")
	)
	(segment
		(start 436.292498 -298.316142)
		(end 436.017162 -298.040806)
		(width 0.18288)
		(layer "In11.Cu")
		(net "M_H_CPU0_SA_DQS_DN<2>")
	)
	(segment
		(start 422.645078 -299.147738)
		(end 421.784526 -300.00829)
		(width 0.18288)
		(layer "In11.Cu")
		(net "M_H_CPU0_SA_DQS_DN<2>")
	)
	(segment
		(start 449.240656 -293.470076)
		(end 447.89598 -294.814752)
		(width 0.18288)
		(layer "In11.Cu")
		(net "M_H_CPU0_SA_DQS_DN<2>")
	)
	(segment
		(start 386.78358 -275.65604)
		(end 384.993896 -273.866356)
		(width 0.088646)
		(layer "In11.Cu")
		(net "M_H_CPU0_SA_DQS_DN<2>")
	)
	(segment
		(start 435.275228 -298.320968)
		(end 433.828698 -298.320968)
		(width 0.18288)
		(layer "In11.Cu")
		(net "M_H_CPU0_SA_DQS_DN<2>")
	)
	(segment
		(start 405.973788 -294.301672)
		(end 404.442168 -294.301672)
		(width 0.18288)
		(layer "In11.Cu")
		(net "M_H_CPU0_SA_DQS_DN<2>")
	)
	(segment
		(start 443.768226 -297.207686)
		(end 443.403736 -297.207686)
		(width 0.18288)
		(layer "In11.Cu")
		(net "M_H_CPU0_SA_DQS_DN<2>")
	)
	(segment
		(start 416.621976 -298.125388)
		(end 415.97072 -297.474132)
		(width 0.18288)
		(layer "In11.Cu")
		(net "M_H_CPU0_SA_DQS_DN<2>")
	)
	(segment
		(start 407.852372 -295.513506)
		(end 407.185622 -295.513506)
		(width 0.18288)
		(layer "In11.Cu")
		(net "M_H_CPU0_SA_DQS_DN<2>")
	)
	(segment
		(start 378.77496 -272.967196)
		(end 378.768864 -272.96364)
		(width 0.088646)
		(layer "In11.Cu")
		(net "M_H_CPU0_SA_DQS_DN<2>")
	)
	(segment
		(start 374.929146 -270.513302)
		(end 374.914668 -270.521938)
		(width 0.088646)
		(layer "In11.Cu")
		(net "M_H_CPU0_SA_DQS_DN<2>")
	)
	(segment
		(start 432.182524 -298.320968)
		(end 431.31359 -297.452034)
		(width 0.18288)
		(layer "In11.Cu")
		(net "M_H_CPU0_SA_DQS_DN<2>")
	)
	(segment
		(start 383.383028 -273.77136)
		(end 383.372614 -273.777456)
		(width 0.088646)
		(layer "In11.Cu")
		(net "M_H_CPU0_SA_DQS_DN<2>")
	)
	(segment
		(start 433.828698 -298.320968)
		(end 433.704238 -298.196508)
		(width 0.18288)
		(layer "In11.Cu")
		(net "M_H_CPU0_SA_DQS_DN<2>")
	)
	(segment
		(start 433.031138 -298.320968)
		(end 432.182524 -298.320968)
		(width 0.18288)
		(layer "In11.Cu")
		(net "M_H_CPU0_SA_DQS_DN<2>")
	)
	(segment
		(start 445.991996 -295.804336)
		(end 445.171576 -295.804336)
		(width 0.18288)
		(layer "In11.Cu")
		(net "M_H_CPU0_SA_DQS_DN<2>")
	)
	(segment
		(start 429.95977 -297.452034)
		(end 428.469298 -298.942506)
		(width 0.18288)
		(layer "In11.Cu")
		(net "M_H_CPU0_SA_DQS_DN<2>")
	)
	(segment
		(start 378.581412 -272.639282)
		(end 378.581412 -272.617184)
		(width 0.088646)
		(layer "In11.Cu")
		(net "M_H_CPU0_SA_DQS_DN<2>")
	)
	(segment
		(start 415.97072 -297.474132)
		(end 414.671764 -297.474132)
		(width 0.18288)
		(layer "In11.Cu")
		(net "M_H_CPU0_SA_DQS_DN<2>")
	)
	(segment
		(start 442.489336 -298.122086)
		(end 442.014102 -298.122086)
		(width 0.18288)
		(layer "In11.Cu")
		(net "M_H_CPU0_SA_DQS_DN<2>")
	)
	(segment
		(start 446.98158 -294.814752)
		(end 445.991996 -295.804336)
		(width 0.18288)
		(layer "In11.Cu")
		(net "M_H_CPU0_SA_DQS_DN<2>")
	)
	(segment
		(start 387.686296 -275.59635)
		(end 387.242558 -275.59635)
		(width 0.18288)
		(layer "In11.Cu")
		(net "M_H_CPU0_SA_DQS_DN<2>")
	)
	(segment
		(start 414.547304 -297.349672)
		(end 413.998664 -297.349672)
		(width 0.18288)
		(layer "In11.Cu")
		(net "M_H_CPU0_SA_DQS_DN<2>")
	)
	(segment
		(start 440.406028 -299.178472)
		(end 440.12231 -298.894754)
		(width 0.18288)
		(layer "In11.Cu")
		(net "M_H_CPU0_SA_DQS_DN<2>")
	)
	(segment
		(start 450.623686 -293.654226)
		(end 450.286882 -293.654226)
		(width 0.18288)
		(layer "In11.Cu")
		(net "M_H_CPU0_SA_DQS_DN<2>")
	)
	(segment
		(start 439.651394 -298.894754)
		(end 439.382154 -299.163994)
		(width 0.18288)
		(layer "In11.Cu")
		(net "M_H_CPU0_SA_DQS_DN<2>")
	)
	(segment
		(start 421.202358 -300.00829)
		(end 420.935912 -299.741844)
		(width 0.18288)
		(layer "In11.Cu")
		(net "M_H_CPU0_SA_DQS_DN<2>")
	)
	(segment
		(start 371.72519 -270.524732)
		(end 371.720872 -270.522446)
		(width 0.088646)
		(layer "In11.Cu")
		(net "M_H_CPU0_SA_DQS_DN<2>")
	)
	(segment
		(start 433.704238 -298.196508)
		(end 433.155598 -298.196508)
		(width 0.18288)
		(layer "In11.Cu")
		(net "M_H_CPU0_SA_DQS_DN<2>")
	)
	(segment
		(start 421.784526 -300.00829)
		(end 421.202358 -300.00829)
		(width 0.18288)
		(layer "In11.Cu")
		(net "M_H_CPU0_SA_DQS_DN<2>")
	)
	(segment
		(start 381.507746 -273.76882)
		(end 381.493014 -273.777456)
		(width 0.088646)
		(layer "In11.Cu")
		(net "M_H_CPU0_SA_DQS_DN<2>")
	)
	(segment
		(start 450.286882 -293.654226)
		(end 450.102732 -293.470076)
		(width 0.18288)
		(layer "In11.Cu")
		(net "M_H_CPU0_SA_DQS_DN<2>")
	)
	(segment
		(start 425.358306 -299.166026)
		(end 425.084748 -298.892468)
		(width 0.18288)
		(layer "In11.Cu")
		(net "M_H_CPU0_SA_DQS_DN<2>")
	)
	(segment
		(start 404.442168 -294.301672)
		(end 400.151092 -290.010596)
		(width 0.18288)
		(layer "In11.Cu")
		(net "M_H_CPU0_SA_DQS_DN<2>")
	)
	(segment
		(start 373.60479 -270.524732)
		(end 373.599964 -270.521938)
		(width 0.088646)
		(layer "In11.Cu")
		(net "M_H_CPU0_SA_DQS_DN<2>")
	)
	(segment
		(start 426.647356 -298.498768)
		(end 425.980098 -299.166026)
		(width 0.18288)
		(layer "In11.Cu")
		(net "M_H_CPU0_SA_DQS_DN<2>")
	)
	(segment
		(start 424.515788 -298.892468)
		(end 424.260518 -299.147738)
		(width 0.18288)
		(layer "In11.Cu")
		(net "M_H_CPU0_SA_DQS_DN<2>")
	)
	(segment
		(start 376.701812 -271.011396)
		(end 376.701812 -270.995902)
		(width 0.088646)
		(layer "In11.Cu")
		(net "M_H_CPU0_SA_DQS_DN<2>")
	)
	(segment
		(start 427.686978 -298.498768)
		(end 426.647356 -298.498768)
		(width 0.18288)
		(layer "In11.Cu")
		(net "M_H_CPU0_SA_DQS_DN<2>")
	)
	(segment
		(start 417.653724 -298.125388)
		(end 416.621976 -298.125388)
		(width 0.18288)
		(layer "In11.Cu")
		(net "M_H_CPU0_SA_DQS_DN<2>")
	)
	(segment
		(start 413.874204 -297.474132)
		(end 413.256984 -297.474132)
		(width 0.18288)
		(layer "In11.Cu")
		(net "M_H_CPU0_SA_DQS_DN<2>")
	)
	(segment
		(start 379.239018 -273.777456)
		(end 379.230128 -273.772376)
		(width 0.088646)
		(layer "In11.Cu")
		(net "M_H_CPU0_SA_DQS_DN<2>")
	)
	(segment
		(start 447.89598 -294.814752)
		(end 446.98158 -294.814752)
		(width 0.18288)
		(layer "In11.Cu")
		(net "M_H_CPU0_SA_DQS_DN<2>")
	)
	(segment
		(start 425.084748 -298.892468)
		(end 424.515788 -298.892468)
		(width 0.18288)
		(layer "In11.Cu")
		(net "M_H_CPU0_SA_DQS_DN<2>")
	)
	(segment
		(start 376.889264 -271.335754)
		(end 376.88774 -271.334992)
		(width 0.088646)
		(layer "In11.Cu")
		(net "M_H_CPU0_SA_DQS_DN<2>")
	)
	(segment
		(start 442.014102 -298.122086)
		(end 440.957716 -299.178472)
		(width 0.18288)
		(layer "In11.Cu")
		(net "M_H_CPU0_SA_DQS_DN<2>")
	)
	(segment
		(start 371.719348 -270.52143)
		(end 371.719094 -270.521176)
		(width 0.088646)
		(layer "In11.Cu")
		(net "M_H_CPU0_SA_DQS_DN<2>")
	)
	(segment
		(start 420.490142 -299.741844)
		(end 420.223696 -300.00829)
		(width 0.18288)
		(layer "In11.Cu")
		(net "M_H_CPU0_SA_DQS_DN<2>")
	)
	(segment
		(start 371.594888 -270.19758)
		(end 371.907816 -270.19758)
		(width 0.088646)
		(layer "In11.Cu")
		(net "M_H_CPU0_SA_DQS_DN<2>")
	)
	(segment
		(start 414.671764 -297.474132)
		(end 414.547304 -297.349672)
		(width 0.18288)
		(layer "In11.Cu")
		(net "M_H_CPU0_SA_DQS_DN<2>")
	)
	(segment
		(start 377.83516 -271.33931)
		(end 377.814332 -271.327118)
		(width 0.088646)
		(layer "In11.Cu")
		(net "M_H_CPU0_SA_DQS_DN<2>")
	)
	(segment
		(start 400.151092 -288.061146)
		(end 387.686296 -275.59635)
		(width 0.18288)
		(layer "In11.Cu")
		(net "M_H_CPU0_SA_DQS_DN<2>")
	)
	(segment
		(start 372.660164 -270.521938)
		(end 372.653052 -270.517874)
		(width 0.088646)
		(layer "In11.Cu")
		(net "M_H_CPU0_SA_DQS_DN<2>")
	)
	(segment
		(start 376.88774 -271.334992)
		(end 376.880374 -271.330674)
		(width 0.088646)
		(layer "In11.Cu")
		(net "M_H_CPU0_SA_DQS_DN<2>")
	)
	(segment
		(start 413.256984 -297.474132)
		(end 412.134812 -296.35196)
		(width 0.18288)
		(layer "In11.Cu")
		(net "M_H_CPU0_SA_DQS_DN<2>")
	)
	(segment
		(start 379.628146 -273.76882)
		(end 379.613414 -273.777456)
		(width 0.088646)
		(layer "In11.Cu")
		(net "M_H_CPU0_SA_DQS_DN<2>")
	)
	(segment
		(start 443.403736 -297.207686)
		(end 442.489336 -298.122086)
		(width 0.18288)
		(layer "In11.Cu")
		(net "M_H_CPU0_SA_DQS_DN<2>")
	)
	(segment
		(start 450.911214 -293.366698)
		(end 450.623686 -293.654226)
		(width 0.18288)
		(layer "In11.Cu")
		(net "M_H_CPU0_SA_DQS_DN<2>")
	)
	(segment
		(start 420.223696 -300.00829)
		(end 419.536626 -300.00829)
		(width 0.18288)
		(layer "In11.Cu")
		(net "M_H_CPU0_SA_DQS_DN<2>")
	)
	(segment
		(start 413.998664 -297.349672)
		(end 413.874204 -297.474132)
		(width 0.18288)
		(layer "In11.Cu")
		(net "M_H_CPU0_SA_DQS_DN<2>")
	)
	(segment
		(start 372.66499 -270.524732)
		(end 372.660164 -270.521938)
		(width 0.088646)
		(layer "In11.Cu")
		(net "M_H_CPU0_SA_DQS_DN<2>")
	)
	(segment
		(start 431.31359 -297.452034)
		(end 429.95977 -297.452034)
		(width 0.18288)
		(layer "In11.Cu")
		(net "M_H_CPU0_SA_DQS_DN<2>")
	)
	(segment
		(start 428.469298 -298.942506)
		(end 428.130716 -298.942506)
		(width 0.18288)
		(layer "In11.Cu")
		(net "M_H_CPU0_SA_DQS_DN<2>")
	)
	(segment
		(start 371.720872 -270.522446)
		(end 371.719348 -270.52143)
		(width 0.088646)
		(layer "In11.Cu")
		(net "M_H_CPU0_SA_DQS_DN<2>")
	)
	(segment
		(start 433.155598 -298.196508)
		(end 433.031138 -298.320968)
		(width 0.18288)
		(layer "In11.Cu")
		(net "M_H_CPU0_SA_DQS_DN<2>")
	)
	(segment
		(start 439.382154 -299.163994)
		(end 438.027572 -299.163994)
		(width 0.18288)
		(layer "In11.Cu")
		(net "M_H_CPU0_SA_DQS_DN<2>")
	)
	(segment
		(start 450.102732 -293.470076)
		(end 449.240656 -293.470076)
		(width 0.18288)
		(layer "In11.Cu")
		(net "M_H_CPU0_SA_DQS_DN<2>")
	)
	(segment
		(start 378.299218 -272.14957)
		(end 378.290328 -272.14449)
		(width 0.088646)
		(layer "In11.Cu")
		(net "M_H_CPU0_SA_DQS_DN<2>")
	)
	(segment
		(start 435.55539 -298.040806)
		(end 435.275228 -298.320968)
		(width 0.18288)
		(layer "In11.Cu")
		(net "M_H_CPU0_SA_DQS_DN<2>")
	)
	(segment
		(start 436.017162 -298.040806)
		(end 435.55539 -298.040806)
		(width 0.18288)
		(layer "In11.Cu")
		(net "M_H_CPU0_SA_DQS_DN<2>")
	)
	(arc
		(start 384.993896 -273.866356)
		(mid 384.93802 -273.81792)
		(end 384.876294 -273.777202)
		(width 0.088646)
		(layer "In11.Cu")
		(net "M_H_CPU0_SA_DQS_DN<2>")
	)
	(arc
		(start 377.814332 -271.327118)
		(mid 377.537857 -271.259798)
		(end 377.26366 -271.335754)
		(width 0.088646)
		(layer "In11.Cu")
		(net "M_H_CPU0_SA_DQS_DN<2>")
	)
	(arc
		(start 371.719094 -270.521176)
		(mid 371.618509 -270.435753)
		(end 371.55374 -270.32077)
		(width 0.088646)
		(layer "In11.Cu")
		(net "M_H_CPU0_SA_DQS_DN<2>")
	)
	(arc
		(start 382.432814 -273.777456)
		(mid 382.245616 -273.827599)
		(end 382.058418 -273.777456)
		(width 0.088646)
		(layer "In11.Cu")
		(net "M_H_CPU0_SA_DQS_DN<2>")
	)
	(arc
		(start 381.118618 -273.777456)
		(mid 380.835916 -273.70168)
		(end 380.553214 -273.777456)
		(width 0.088646)
		(layer "In11.Cu")
		(net "M_H_CPU0_SA_DQS_DN<2>")
	)
	(arc
		(start 376.701812 -270.995902)
		(mid 376.622442 -270.722168)
		(end 376.419618 -270.521938)
		(width 0.088646)
		(layer "In11.Cu")
		(net "M_H_CPU0_SA_DQS_DN<2>")
	)
	(arc
		(start 372.653052 -270.517874)
		(mid 372.37351 -270.44628)
		(end 372.095014 -270.521938)
		(width 0.088646)
		(layer "In11.Cu")
		(net "M_H_CPU0_SA_DQS_DN<2>")
	)
	(arc
		(start 378.11202 -271.839944)
		(mid 378.111823 -271.832579)
		(end 378.111766 -271.825212)
		(width 0.088646)
		(layer "In11.Cu")
		(net "M_H_CPU0_SA_DQS_DN<2>")
	)
	(arc
		(start 378.581412 -272.617184)
		(mid 378.500501 -272.347056)
		(end 378.299218 -272.14957)
		(width 0.088646)
		(layer "In11.Cu")
		(net "M_H_CPU0_SA_DQS_DN<2>")
	)
	(arc
		(start 371.55374 -270.32077)
		(mid 371.544119 -270.288246)
		(end 371.537484 -270.254984)
		(width 0.088646)
		(layer "In11.Cu")
		(net "M_H_CPU0_SA_DQS_DN<2>")
	)
	(arc
		(start 373.034814 -270.521938)
		(mid 372.850261 -270.572197)
		(end 372.66499 -270.524732)
		(width 0.088646)
		(layer "In11.Cu")
		(net "M_H_CPU0_SA_DQS_DN<2>")
	)
	(arc
		(start 380.553214 -273.777456)
		(mid 380.366016 -273.827599)
		(end 380.178818 -273.777456)
		(width 0.088646)
		(layer "In11.Cu")
		(net "M_H_CPU0_SA_DQS_DN<2>")
	)
	(arc
		(start 375.479818 -270.521938)
		(mid 375.205619 -270.446103)
		(end 374.929146 -270.513302)
		(width 0.088646)
		(layer "In11.Cu")
		(net "M_H_CPU0_SA_DQS_DN<2>")
	)
	(arc
		(start 373.592852 -270.517874)
		(mid 373.31331 -270.44628)
		(end 373.034814 -270.521938)
		(width 0.088646)
		(layer "In11.Cu")
		(net "M_H_CPU0_SA_DQS_DN<2>")
	)
	(arc
		(start 384.31216 -273.777456)
		(mid 384.124962 -273.827599)
		(end 383.937764 -273.777456)
		(width 0.088646)
		(layer "In11.Cu")
		(net "M_H_CPU0_SA_DQS_DN<2>")
	)
	(arc
		(start 381.493014 -273.777456)
		(mid 381.305816 -273.827599)
		(end 381.118618 -273.777456)
		(width 0.088646)
		(layer "In11.Cu")
		(net "M_H_CPU0_SA_DQS_DN<2>")
	)
	(arc
		(start 375.854214 -270.521938)
		(mid 375.667016 -270.572081)
		(end 375.479818 -270.521938)
		(width 0.088646)
		(layer "In11.Cu")
		(net "M_H_CPU0_SA_DQS_DN<2>")
	)
	(arc
		(start 382.998218 -273.777456)
		(mid 382.724019 -273.701621)
		(end 382.447546 -273.76882)
		(width 0.088646)
		(layer "In11.Cu")
		(net "M_H_CPU0_SA_DQS_DN<2>")
	)
	(arc
		(start 379.230128 -273.772376)
		(mid 379.099214 -273.636016)
		(end 379.051566 -273.453098)
		(width 0.088646)
		(layer "In11.Cu")
		(net "M_H_CPU0_SA_DQS_DN<2>")
	)
	(arc
		(start 378.290328 -272.14449)
		(mid 378.163074 -272.014524)
		(end 378.11202 -271.839944)
		(width 0.088646)
		(layer "In11.Cu")
		(net "M_H_CPU0_SA_DQS_DN<2>")
	)
	(arc
		(start 374.532652 -270.517874)
		(mid 374.25311 -270.44628)
		(end 373.974614 -270.521938)
		(width 0.088646)
		(layer "In11.Cu")
		(net "M_H_CPU0_SA_DQS_DN<2>")
	)
	(arc
		(start 374.914668 -270.521938)
		(mid 374.730004 -270.572198)
		(end 374.54459 -270.524732)
		(width 0.088646)
		(layer "In11.Cu")
		(net "M_H_CPU0_SA_DQS_DN<2>")
	)
	(arc
		(start 373.974614 -270.521938)
		(mid 373.790061 -270.572197)
		(end 373.60479 -270.524732)
		(width 0.088646)
		(layer "In11.Cu")
		(net "M_H_CPU0_SA_DQS_DN<2>")
	)
	(arc
		(start 379.613414 -273.777456)
		(mid 379.426216 -273.827599)
		(end 379.239018 -273.777456)
		(width 0.088646)
		(layer "In11.Cu")
		(net "M_H_CPU0_SA_DQS_DN<2>")
	)
	(arc
		(start 376.880374 -271.330674)
		(mid 376.74946 -271.194314)
		(end 376.701812 -271.011396)
		(width 0.088646)
		(layer "In11.Cu")
		(net "M_H_CPU0_SA_DQS_DN<2>")
	)
	(arc
		(start 377.26366 -271.335754)
		(mid 377.076462 -271.385897)
		(end 376.889264 -271.335754)
		(width 0.088646)
		(layer "In11.Cu")
		(net "M_H_CPU0_SA_DQS_DN<2>")
	)
	(arc
		(start 382.058418 -273.777456)
		(mid 381.784219 -273.701621)
		(end 381.507746 -273.76882)
		(width 0.088646)
		(layer "In11.Cu")
		(net "M_H_CPU0_SA_DQS_DN<2>")
	)
	(arc
		(start 378.759974 -272.95856)
		(mid 378.62906 -272.8222)
		(end 378.581412 -272.639282)
		(width 0.088646)
		(layer "In11.Cu")
		(net "M_H_CPU0_SA_DQS_DN<2>")
	)
	(arc
		(start 384.876294 -273.777202)
		(mid 384.594181 -273.701841)
		(end 384.31216 -273.777456)
		(width 0.088646)
		(layer "In11.Cu")
		(net "M_H_CPU0_SA_DQS_DN<2>")
	)
	(arc
		(start 383.937764 -273.777456)
		(mid 383.661205 -273.701713)
		(end 383.383028 -273.77136)
		(width 0.088646)
		(layer "In11.Cu")
		(net "M_H_CPU0_SA_DQS_DN<2>")
	)
	(arc
		(start 378.111766 -271.825212)
		(mid 378.037775 -271.545646)
		(end 377.83516 -271.33931)
		(width 0.088646)
		(layer "In11.Cu")
		(net "M_H_CPU0_SA_DQS_DN<2>")
	)
	(arc
		(start 376.419618 -270.521938)
		(mid 376.145419 -270.446103)
		(end 375.868946 -270.513302)
		(width 0.088646)
		(layer "In11.Cu")
		(net "M_H_CPU0_SA_DQS_DN<2>")
	)
	(arc
		(start 383.372614 -273.777456)
		(mid 383.185416 -273.827599)
		(end 382.998218 -273.777456)
		(width 0.088646)
		(layer "In11.Cu")
		(net "M_H_CPU0_SA_DQS_DN<2>")
	)
	(arc
		(start 380.178818 -273.777456)
		(mid 379.904619 -273.701621)
		(end 379.628146 -273.76882)
		(width 0.088646)
		(layer "In11.Cu")
		(net "M_H_CPU0_SA_DQS_DN<2>")
	)
	(arc
		(start 379.051566 -273.453098)
		(mid 378.977575 -273.173532)
		(end 378.77496 -272.967196)
		(width 0.088646)
		(layer "In11.Cu")
		(net "M_H_CPU0_SA_DQS_DN<2>")
	)
	(arc
		(start 372.095014 -270.521938)
		(mid 371.910461 -270.572197)
		(end 371.72519 -270.524732)
		(width 0.088646)
		(layer "In11.Cu")
		(net "M_H_CPU0_SA_DQS_DN<2>")
	)
	(segment
		(start 458.39761 -302.95723)
		(end 457.987146 -303.367694)
		(width 0.20066)
		(layer "F.Cu")
		(net "M_H_CPU0_SA_DQS_DN<1>")
	)
	(segment
		(start 454.789794 -303.141634)
		(end 454.518522 -303.412906)
		(width 0.20066)
		(layer "F.Cu")
		(net "M_H_CPU0_SA_DQS_DN<1>")
	)
	(segment
		(start 453.582278 -302.998378)
		(end 452.84644 -302.998378)
		(width 0.20066)
		(layer "F.Cu")
		(net "M_H_CPU0_SA_DQS_DN<1>")
	)
	(segment
		(start 450.911214 -302.716692)
		(end 452.016114 -302.716692)
		(width 0.20066)
		(layer "F.Cu")
		(net "M_H_CPU0_SA_DQS_DN<1>")
	)
	(segment
		(start 454.941686 -303.141634)
		(end 454.937368 -303.141634)
		(width 0.101854)
		(layer "F.Cu")
		(net "M_H_CPU0_SA_DQS_DN<1>")
	)
	(segment
		(start 452.564754 -302.716692)
		(end 452.016114 -302.716692)
		(width 0.20066)
		(layer "F.Cu")
		(net "M_H_CPU0_SA_DQS_DN<1>")
	)
	(segment
		(start 458.970634 -302.716692)
		(end 458.730096 -302.95723)
		(width 0.20066)
		(layer "F.Cu")
		(net "M_H_CPU0_SA_DQS_DN<1>")
	)
	(segment
		(start 454.518522 -303.412906)
		(end 453.996806 -303.412906)
		(width 0.20066)
		(layer "F.Cu")
		(net "M_H_CPU0_SA_DQS_DN<1>")
	)
	(segment
		(start 457.12126 -303.141634)
		(end 454.941686 -303.141634)
		(width 0.1016)
		(layer "F.Cu")
		(net "M_H_CPU0_SA_DQS_DN<1>")
	)
	(segment
		(start 457.682092 -303.367694)
		(end 457.450698 -303.1363)
		(width 0.20066)
		(layer "F.Cu")
		(net "M_H_CPU0_SA_DQS_DN<1>")
	)
	(segment
		(start 370.968016 -274.545044)
		(end 370.968016 -275.08073)
		(width 0.20066)
		(layer "F.Cu")
		(net "M_H_CPU0_SA_DQS_DN<1>")
	)
	(segment
		(start 457.126594 -303.1363)
		(end 457.12126 -303.141634)
		(width 0.1016)
		(layer "F.Cu")
		(net "M_H_CPU0_SA_DQS_DN<1>")
	)
	(segment
		(start 453.996806 -303.412906)
		(end 453.582278 -302.998378)
		(width 0.20066)
		(layer "F.Cu")
		(net "M_H_CPU0_SA_DQS_DN<1>")
	)
	(segment
		(start 452.84644 -302.998378)
		(end 452.564754 -302.716692)
		(width 0.20066)
		(layer "F.Cu")
		(net "M_H_CPU0_SA_DQS_DN<1>")
	)
	(segment
		(start 457.450698 -303.1363)
		(end 457.126594 -303.1363)
		(width 0.20066)
		(layer "F.Cu")
		(net "M_H_CPU0_SA_DQS_DN<1>")
	)
	(segment
		(start 454.937368 -303.141634)
		(end 454.789794 -303.141634)
		(width 0.20066)
		(layer "F.Cu")
		(net "M_H_CPU0_SA_DQS_DN<1>")
	)
	(segment
		(start 457.987146 -303.367694)
		(end 457.682092 -303.367694)
		(width 0.20066)
		(layer "F.Cu")
		(net "M_H_CPU0_SA_DQS_DN<1>")
	)
	(segment
		(start 459.559914 -302.716692)
		(end 458.970634 -302.716692)
		(width 0.20066)
		(layer "F.Cu")
		(net "M_H_CPU0_SA_DQS_DN<1>")
	)
	(segment
		(start 370.967762 -274.54479)
		(end 370.968016 -274.545044)
		(width 0.20066)
		(layer "F.Cu")
		(net "M_H_CPU0_SA_DQS_DN<1>")
	)
	(segment
		(start 458.730096 -302.95723)
		(end 458.39761 -302.95723)
		(width 0.20066)
		(layer "F.Cu")
		(net "M_H_CPU0_SA_DQS_DN<1>")
	)
	(segment
		(start 386.287264 -282.730194)
		(end 386.278374 -282.725114)
		(width 0.088646)
		(layer "In11.Cu")
		(net "M_H_CPU0_SA_DQS_DN<1>")
	)
	(segment
		(start 435.553612 -309.0926)
		(end 435.288436 -309.357776)
		(width 0.18288)
		(layer "In11.Cu")
		(net "M_H_CPU0_SA_DQS_DN<1>")
	)
	(segment
		(start 405.48179 -308.262782)
		(end 401.959572 -304.740564)
		(width 0.18288)
		(layer "In11.Cu")
		(net "M_H_CPU0_SA_DQS_DN<1>")
	)
	(segment
		(start 378.768864 -279.474676)
		(end 378.75845 -279.46858)
		(width 0.088646)
		(layer "In11.Cu")
		(net "M_H_CPU0_SA_DQS_DN<1>")
	)
	(segment
		(start 386.366766 -282.78582)
		(end 386.366512 -282.785312)
		(width 0.088646)
		(layer "In11.Cu")
		(net "M_H_CPU0_SA_DQS_DN<1>")
	)
	(segment
		(start 443.217808 -308.459886)
		(end 442.379608 -309.298086)
		(width 0.18288)
		(layer "In11.Cu")
		(net "M_H_CPU0_SA_DQS_DN<1>")
	)
	(segment
		(start 384.220212 -280.778204)
		(end 384.220212 -280.759662)
		(width 0.088646)
		(layer "In11.Cu")
		(net "M_H_CPU0_SA_DQS_DN<1>")
	)
	(segment
		(start 409.21686 -309.23103)
		(end 408.559762 -308.878732)
		(width 0.18288)
		(layer "In11.Cu")
		(net "M_H_CPU0_SA_DQS_DN<1>")
	)
	(segment
		(start 386.72262 -283.116274)
		(end 386.64642 -283.040074)
		(width 0.088646)
		(layer "In11.Cu")
		(net "M_H_CPU0_SA_DQS_DN<1>")
	)
	(segment
		(start 372.514114 -275.323046)
		(end 372.35765 -275.205698)
		(width 0.088646)
		(layer "In11.Cu")
		(net "M_H_CPU0_SA_DQS_DN<1>")
	)
	(segment
		(start 382.917192 -279.46604)
		(end 382.90246 -279.474676)
		(width 0.088646)
		(layer "In11.Cu")
		(net "M_H_CPU0_SA_DQS_DN<1>")
	)
	(segment
		(start 383.47396 -279.478232)
		(end 383.467864 -279.474676)
		(width 0.088646)
		(layer "In11.Cu")
		(net "M_H_CPU0_SA_DQS_DN<1>")
	)
	(segment
		(start 419.464236 -311.032652)
		(end 417.538916 -309.107332)
		(width 0.18288)
		(layer "In11.Cu")
		(net "M_H_CPU0_SA_DQS_DN<1>")
	)
	(segment
		(start 383.937764 -280.288492)
		(end 383.928874 -280.283412)
		(width 0.088646)
		(layer "In11.Cu")
		(net "M_H_CPU0_SA_DQS_DN<1>")
	)
	(segment
		(start 374.069864 -276.219158)
		(end 374.060974 -276.214078)
		(width 0.088646)
		(layer "In11.Cu")
		(net "M_H_CPU0_SA_DQS_DN<1>")
	)
	(segment
		(start 450.245226 -302.986694)
		(end 450.054218 -302.795686)
		(width 0.18288)
		(layer "In11.Cu")
		(net "M_H_CPU0_SA_DQS_DN<1>")
	)
	(segment
		(start 450.641212 -302.986694)
		(end 450.245226 -302.986694)
		(width 0.18288)
		(layer "In11.Cu")
		(net "M_H_CPU0_SA_DQS_DN<1>")
	)
	(segment
		(start 408.559762 -308.878732)
		(end 405.48179 -308.262782)
		(width 0.18288)
		(layer "In11.Cu")
		(net "M_H_CPU0_SA_DQS_DN<1>")
	)
	(segment
		(start 375.864628 -278.654764)
		(end 375.854214 -278.66086)
		(width 0.088646)
		(layer "In11.Cu")
		(net "M_H_CPU0_SA_DQS_DN<1>")
	)
	(segment
		(start 435.288436 -309.357776)
		(end 431.424334 -309.357776)
		(width 0.18288)
		(layer "In11.Cu")
		(net "M_H_CPU0_SA_DQS_DN<1>")
	)
	(segment
		(start 413.278066 -308.356)
		(end 412.403036 -309.23103)
		(width 0.18288)
		(layer "In11.Cu")
		(net "M_H_CPU0_SA_DQS_DN<1>")
	)
	(segment
		(start 376.701812 -279.150318)
		(end 376.701812 -279.140412)
		(width 0.088646)
		(layer "In11.Cu")
		(net "M_H_CPU0_SA_DQS_DN<1>")
	)
	(segment
		(start 425.924472 -310.216042)
		(end 425.312078 -310.216042)
		(width 0.18288)
		(layer "In11.Cu")
		(net "M_H_CPU0_SA_DQS_DN<1>")
	)
	(segment
		(start 372.660418 -275.405088)
		(end 372.660164 -275.405088)
		(width 0.088646)
		(layer "In11.Cu")
		(net "M_H_CPU0_SA_DQS_DN<1>")
	)
	(segment
		(start 379.708918 -279.474676)
		(end 379.698504 -279.46858)
		(width 0.088646)
		(layer "In11.Cu")
		(net "M_H_CPU0_SA_DQS_DN<1>")
	)
	(segment
		(start 373.882412 -275.8948)
		(end 373.882412 -275.872702)
		(width 0.088646)
		(layer "In11.Cu")
		(net "M_H_CPU0_SA_DQS_DN<1>")
	)
	(segment
		(start 387.295898 -283.611828)
		(end 386.800344 -283.116274)
		(width 0.18288)
		(layer "In11.Cu")
		(net "M_H_CPU0_SA_DQS_DN<1>")
	)
	(segment
		(start 372.659402 -275.40458)
		(end 372.514114 -275.323046)
		(width 0.088646)
		(layer "In11.Cu")
		(net "M_H_CPU0_SA_DQS_DN<1>")
	)
	(segment
		(start 447.900298 -305.127406)
		(end 447.900298 -305.508152)
		(width 0.18288)
		(layer "In11.Cu")
		(net "M_H_CPU0_SA_DQS_DN<1>")
	)
	(segment
		(start 374.352566 -278.336502)
		(end 374.352566 -278.322278)
		(width 0.088646)
		(layer "In11.Cu")
		(net "M_H_CPU0_SA_DQS_DN<1>")
	)
	(segment
		(start 448.864228 -304.163476)
		(end 447.900298 -305.127406)
		(width 0.18288)
		(layer "In11.Cu")
		(net "M_H_CPU0_SA_DQS_DN<1>")
	)
	(segment
		(start 374.929146 -278.652224)
		(end 374.914414 -278.66086)
		(width 0.088646)
		(layer "In11.Cu")
		(net "M_H_CPU0_SA_DQS_DN<1>")
	)
	(segment
		(start 371.720618 -274.756372)
		(end 371.711728 -274.761452)
		(width 0.088646)
		(layer "In11.Cu")
		(net "M_H_CPU0_SA_DQS_DN<1>")
	)
	(segment
		(start 427.937676 -309.95112)
		(end 427.47565 -309.489094)
		(width 0.18288)
		(layer "In11.Cu")
		(net "M_H_CPU0_SA_DQS_DN<1>")
	)
	(segment
		(start 416.106356 -308.356)
		(end 413.278066 -308.356)
		(width 0.18288)
		(layer "In11.Cu")
		(net "M_H_CPU0_SA_DQS_DN<1>")
	)
	(segment
		(start 445.233044 -306.829206)
		(end 443.602364 -308.459886)
		(width 0.18288)
		(layer "In11.Cu")
		(net "M_H_CPU0_SA_DQS_DN<1>")
	)
	(segment
		(start 440.855862 -310.247792)
		(end 440.439556 -310.247792)
		(width 0.18288)
		(layer "In11.Cu")
		(net "M_H_CPU0_SA_DQS_DN<1>")
	)
	(segment
		(start 441.805568 -309.298086)
		(end 440.855862 -310.247792)
		(width 0.18288)
		(layer "In11.Cu")
		(net "M_H_CPU0_SA_DQS_DN<1>")
	)
	(segment
		(start 372.345966 -275.194014)
		(end 372.282466 -275.08073)
		(width 0.088646)
		(layer "In11.Cu")
		(net "M_H_CPU0_SA_DQS_DN<1>")
	)
	(segment
		(start 440.439556 -310.247792)
		(end 440.13247 -309.940706)
		(width 0.18288)
		(layer "In11.Cu")
		(net "M_H_CPU0_SA_DQS_DN<1>")
	)
	(segment
		(start 425.036742 -309.940706)
		(end 424.567858 -309.940706)
		(width 0.18288)
		(layer "In11.Cu")
		(net "M_H_CPU0_SA_DQS_DN<1>")
	)
	(segment
		(start 424.27779 -310.230774)
		(end 423.488866 -310.230774)
		(width 0.18288)
		(layer "In11.Cu")
		(net "M_H_CPU0_SA_DQS_DN<1>")
	)
	(segment
		(start 416.857688 -309.107332)
		(end 416.106356 -308.356)
		(width 0.18288)
		(layer "In11.Cu")
		(net "M_H_CPU0_SA_DQS_DN<1>")
	)
	(segment
		(start 437.10606 -309.366158)
		(end 436.296054 -309.366158)
		(width 0.18288)
		(layer "In11.Cu")
		(net "M_H_CPU0_SA_DQS_DN<1>")
	)
	(segment
		(start 401.959572 -300.56074)
		(end 393.561824 -292.162992)
		(width 0.18288)
		(layer "In11.Cu")
		(net "M_H_CPU0_SA_DQS_DN<1>")
	)
	(segment
		(start 371.537738 -275.02358)
		(end 371.480588 -275.08073)
		(width 0.088646)
		(layer "In11.Cu")
		(net "M_H_CPU0_SA_DQS_DN<1>")
	)
	(segment
		(start 374.540018 -278.66086)
		(end 374.531128 -278.65578)
		(width 0.088646)
		(layer "In11.Cu")
		(net "M_H_CPU0_SA_DQS_DN<1>")
	)
	(segment
		(start 437.937656 -310.197754)
		(end 437.10606 -309.366158)
		(width 0.18288)
		(layer "In11.Cu")
		(net "M_H_CPU0_SA_DQS_DN<1>")
	)
	(segment
		(start 374.069864 -277.198074)
		(end 374.082056 -277.190962)
		(width 0.088646)
		(layer "In11.Cu")
		(net "M_H_CPU0_SA_DQS_DN<1>")
	)
	(segment
		(start 420.964614 -310.790844)
		(end 420.46779 -310.790844)
		(width 0.18288)
		(layer "In11.Cu")
		(net "M_H_CPU0_SA_DQS_DN<1>")
	)
	(segment
		(start 417.538916 -309.107332)
		(end 416.857688 -309.107332)
		(width 0.18288)
		(layer "In11.Cu")
		(net "M_H_CPU0_SA_DQS_DN<1>")
	)
	(segment
		(start 374.082056 -276.22627)
		(end 374.073928 -276.221444)
		(width 0.088646)
		(layer "In11.Cu")
		(net "M_H_CPU0_SA_DQS_DN<1>")
	)
	(segment
		(start 440.13247 -309.940706)
		(end 439.655458 -309.940706)
		(width 0.18288)
		(layer "In11.Cu")
		(net "M_H_CPU0_SA_DQS_DN<1>")
	)
	(segment
		(start 377.829318 -279.474676)
		(end 377.818904 -279.46858)
		(width 0.088646)
		(layer "In11.Cu")
		(net "M_H_CPU0_SA_DQS_DN<1>")
	)
	(segment
		(start 371.480588 -275.08073)
		(end 370.968016 -275.08073)
		(width 0.088646)
		(layer "In11.Cu")
		(net "M_H_CPU0_SA_DQS_DN<1>")
	)
	(segment
		(start 421.472106 -311.06618)
		(end 421.23995 -311.06618)
		(width 0.18288)
		(layer "In11.Cu")
		(net "M_H_CPU0_SA_DQS_DN<1>")
	)
	(segment
		(start 423.488866 -310.230774)
		(end 421.472106 -311.06618)
		(width 0.18288)
		(layer "In11.Cu")
		(net "M_H_CPU0_SA_DQS_DN<1>")
	)
	(segment
		(start 426.65142 -309.489094)
		(end 425.924472 -310.216042)
		(width 0.18288)
		(layer "In11.Cu")
		(net "M_H_CPU0_SA_DQS_DN<1>")
	)
	(segment
		(start 420.225982 -311.032652)
		(end 419.464236 -311.032652)
		(width 0.18288)
		(layer "In11.Cu")
		(net "M_H_CPU0_SA_DQS_DN<1>")
	)
	(segment
		(start 401.959572 -304.740564)
		(end 401.959572 -300.56074)
		(width 0.18288)
		(layer "In11.Cu")
		(net "M_H_CPU0_SA_DQS_DN<1>")
	)
	(segment
		(start 386.099812 -282.405836)
		(end 386.099812 -282.39593)
		(width 0.088646)
		(layer "In11.Cu")
		(net "M_H_CPU0_SA_DQS_DN<1>")
	)
	(segment
		(start 430.83099 -309.95112)
		(end 427.937676 -309.95112)
		(width 0.18288)
		(layer "In11.Cu")
		(net "M_H_CPU0_SA_DQS_DN<1>")
	)
	(segment
		(start 393.561824 -292.162992)
		(end 393.561824 -290.639754)
		(width 0.18288)
		(layer "In11.Cu")
		(net "M_H_CPU0_SA_DQS_DN<1>")
	)
	(segment
		(start 384.407664 -281.102562)
		(end 384.398774 -281.097482)
		(width 0.088646)
		(layer "In11.Cu")
		(net "M_H_CPU0_SA_DQS_DN<1>")
	)
	(segment
		(start 427.47565 -309.489094)
		(end 426.65142 -309.489094)
		(width 0.18288)
		(layer "In11.Cu")
		(net "M_H_CPU0_SA_DQS_DN<1>")
	)
	(segment
		(start 387.295898 -284.373828)
		(end 387.295898 -283.611828)
		(width 0.18288)
		(layer "In11.Cu")
		(net "M_H_CPU0_SA_DQS_DN<1>")
	)
	(segment
		(start 421.23995 -311.06618)
		(end 420.964614 -310.790844)
		(width 0.18288)
		(layer "In11.Cu")
		(net "M_H_CPU0_SA_DQS_DN<1>")
	)
	(segment
		(start 448.864228 -303.268126)
		(end 448.864228 -304.163476)
		(width 0.18288)
		(layer "In11.Cu")
		(net "M_H_CPU0_SA_DQS_DN<1>")
	)
	(segment
		(start 439.655458 -309.940706)
		(end 439.39841 -310.197754)
		(width 0.18288)
		(layer "In11.Cu")
		(net "M_H_CPU0_SA_DQS_DN<1>")
	)
	(segment
		(start 382.528064 -279.474676)
		(end 382.513332 -279.46604)
		(width 0.088646)
		(layer "In11.Cu")
		(net "M_H_CPU0_SA_DQS_DN<1>")
	)
	(segment
		(start 446.74155 -306.052982)
		(end 445.965326 -306.829206)
		(width 0.18288)
		(layer "In11.Cu")
		(net "M_H_CPU0_SA_DQS_DN<1>")
	)
	(segment
		(start 381.588264 -279.474676)
		(end 381.57785 -279.46858)
		(width 0.088646)
		(layer "In11.Cu")
		(net "M_H_CPU0_SA_DQS_DN<1>")
	)
	(segment
		(start 447.355468 -306.052982)
		(end 446.74155 -306.052982)
		(width 0.18288)
		(layer "In11.Cu")
		(net "M_H_CPU0_SA_DQS_DN<1>")
	)
	(segment
		(start 373.882666 -277.531068)
		(end 373.882666 -277.513796)
		(width 0.088646)
		(layer "In11.Cu")
		(net "M_H_CPU0_SA_DQS_DN<1>")
	)
	(segment
		(start 412.403036 -309.23103)
		(end 409.21686 -309.23103)
		(width 0.18288)
		(layer "In11.Cu")
		(net "M_H_CPU0_SA_DQS_DN<1>")
	)
	(segment
		(start 450.054218 -302.795686)
		(end 449.336668 -302.795686)
		(width 0.18288)
		(layer "In11.Cu")
		(net "M_H_CPU0_SA_DQS_DN<1>")
	)
	(segment
		(start 442.379608 -309.298086)
		(end 441.805568 -309.298086)
		(width 0.18288)
		(layer "In11.Cu")
		(net "M_H_CPU0_SA_DQS_DN<1>")
	)
	(segment
		(start 373.049546 -275.396452)
		(end 373.034814 -275.405088)
		(width 0.088646)
		(layer "In11.Cu")
		(net "M_H_CPU0_SA_DQS_DN<1>")
	)
	(segment
		(start 425.312078 -310.216042)
		(end 425.036742 -309.940706)
		(width 0.18288)
		(layer "In11.Cu")
		(net "M_H_CPU0_SA_DQS_DN<1>")
	)
	(segment
		(start 385.629912 -281.59202)
		(end 385.629912 -281.582114)
		(width 0.088646)
		(layer "In11.Cu")
		(net "M_H_CPU0_SA_DQS_DN<1>")
	)
	(segment
		(start 385.817364 -281.916378)
		(end 385.816602 -281.91587)
		(width 0.088646)
		(layer "In11.Cu")
		(net "M_H_CPU0_SA_DQS_DN<1>")
	)
	(segment
		(start 372.096538 -274.757134)
		(end 372.095014 -274.756372)
		(width 0.088646)
		(layer "In11.Cu")
		(net "M_H_CPU0_SA_DQS_DN<1>")
	)
	(segment
		(start 385.816602 -281.91587)
		(end 385.808474 -281.911298)
		(width 0.088646)
		(layer "In11.Cu")
		(net "M_H_CPU0_SA_DQS_DN<1>")
	)
	(segment
		(start 376.889264 -279.474676)
		(end 376.88774 -279.473914)
		(width 0.088646)
		(layer "In11.Cu")
		(net "M_H_CPU0_SA_DQS_DN<1>")
	)
	(segment
		(start 439.39841 -310.197754)
		(end 437.937656 -310.197754)
		(width 0.18288)
		(layer "In11.Cu")
		(net "M_H_CPU0_SA_DQS_DN<1>")
	)
	(segment
		(start 420.46779 -310.790844)
		(end 420.225982 -311.032652)
		(width 0.18288)
		(layer "In11.Cu")
		(net "M_H_CPU0_SA_DQS_DN<1>")
	)
	(segment
		(start 372.660164 -275.405088)
		(end 372.659402 -275.40458)
		(width 0.088646)
		(layer "In11.Cu")
		(net "M_H_CPU0_SA_DQS_DN<1>")
	)
	(segment
		(start 445.965326 -306.829206)
		(end 445.233044 -306.829206)
		(width 0.18288)
		(layer "In11.Cu")
		(net "M_H_CPU0_SA_DQS_DN<1>")
	)
	(segment
		(start 376.88774 -279.473914)
		(end 376.880374 -279.469596)
		(width 0.088646)
		(layer "In11.Cu")
		(net "M_H_CPU0_SA_DQS_DN<1>")
	)
	(segment
		(start 393.561824 -290.639754)
		(end 387.295898 -284.373828)
		(width 0.18288)
		(layer "In11.Cu")
		(net "M_H_CPU0_SA_DQS_DN<1>")
	)
	(segment
		(start 435.910482 -309.0926)
		(end 435.553612 -309.0926)
		(width 0.18288)
		(layer "In11.Cu")
		(net "M_H_CPU0_SA_DQS_DN<1>")
	)
	(segment
		(start 436.296054 -309.366158)
		(end 436.020718 -309.090822)
		(width 0.18288)
		(layer "In11.Cu")
		(net "M_H_CPU0_SA_DQS_DN<1>")
	)
	(segment
		(start 447.900298 -305.508152)
		(end 447.355468 -306.052982)
		(width 0.18288)
		(layer "In11.Cu")
		(net "M_H_CPU0_SA_DQS_DN<1>")
	)
	(segment
		(start 374.073928 -276.221444)
		(end 374.069864 -276.219158)
		(width 0.088646)
		(layer "In11.Cu")
		(net "M_H_CPU0_SA_DQS_DN<1>")
	)
	(segment
		(start 372.35765 -275.205698)
		(end 372.345966 -275.194014)
		(width 0.088646)
		(layer "In11.Cu")
		(net "M_H_CPU0_SA_DQS_DN<1>")
	)
	(segment
		(start 443.602364 -308.459886)
		(end 443.217808 -308.459886)
		(width 0.18288)
		(layer "In11.Cu")
		(net "M_H_CPU0_SA_DQS_DN<1>")
	)
	(segment
		(start 436.020718 -309.090822)
		(end 435.91226 -309.090822)
		(width 0.18288)
		(layer "In11.Cu")
		(net "M_H_CPU0_SA_DQS_DN<1>")
	)
	(segment
		(start 450.911214 -302.716692)
		(end 450.641212 -302.986694)
		(width 0.18288)
		(layer "In11.Cu")
		(net "M_H_CPU0_SA_DQS_DN<1>")
	)
	(segment
		(start 449.336668 -302.795686)
		(end 448.864228 -303.268126)
		(width 0.18288)
		(layer "In11.Cu")
		(net "M_H_CPU0_SA_DQS_DN<1>")
	)
	(segment
		(start 435.91226 -309.090822)
		(end 435.910482 -309.0926)
		(width 0.18288)
		(layer "In11.Cu")
		(net "M_H_CPU0_SA_DQS_DN<1>")
	)
	(segment
		(start 380.098046 -279.46604)
		(end 380.083314 -279.474676)
		(width 0.088646)
		(layer "In11.Cu")
		(net "M_H_CPU0_SA_DQS_DN<1>")
	)
	(segment
		(start 386.800344 -283.116274)
		(end 386.72262 -283.116274)
		(width 0.088646)
		(layer "In11.Cu")
		(net "M_H_CPU0_SA_DQS_DN<1>")
	)
	(segment
		(start 431.424334 -309.357776)
		(end 430.83099 -309.95112)
		(width 0.18288)
		(layer "In11.Cu")
		(net "M_H_CPU0_SA_DQS_DN<1>")
	)
	(segment
		(start 424.567858 -309.940706)
		(end 424.27779 -310.230774)
		(width 0.18288)
		(layer "In11.Cu")
		(net "M_H_CPU0_SA_DQS_DN<1>")
	)
	(arc
		(start 376.419364 -278.66086)
		(mid 376.142805 -278.585117)
		(end 375.864628 -278.654764)
		(width 0.088646)
		(layer "In11.Cu")
		(net "M_H_CPU0_SA_DQS_DN<1>")
	)
	(arc
		(start 378.203714 -279.474676)
		(mid 378.016516 -279.524819)
		(end 377.829318 -279.474676)
		(width 0.088646)
		(layer "In11.Cu")
		(net "M_H_CPU0_SA_DQS_DN<1>")
	)
	(arc
		(start 373.034814 -275.405088)
		(mid 372.847616 -275.455231)
		(end 372.660418 -275.405088)
		(width 0.088646)
		(layer "In11.Cu")
		(net "M_H_CPU0_SA_DQS_DN<1>")
	)
	(arc
		(start 379.14326 -279.474676)
		(mid 378.956062 -279.524819)
		(end 378.768864 -279.474676)
		(width 0.088646)
		(layer "In11.Cu")
		(net "M_H_CPU0_SA_DQS_DN<1>")
	)
	(arc
		(start 385.808474 -281.911298)
		(mid 385.67756 -281.774938)
		(end 385.629912 -281.59202)
		(width 0.088646)
		(layer "In11.Cu")
		(net "M_H_CPU0_SA_DQS_DN<1>")
	)
	(arc
		(start 373.600218 -275.405088)
		(mid 373.325989 -275.329163)
		(end 373.049546 -275.396452)
		(width 0.088646)
		(layer "In11.Cu")
		(net "M_H_CPU0_SA_DQS_DN<1>")
	)
	(arc
		(start 386.64642 -283.040074)
		(mid 386.509611 -282.909627)
		(end 386.366766 -282.78582)
		(width 0.088646)
		(layer "In11.Cu")
		(net "M_H_CPU0_SA_DQS_DN<1>")
	)
	(arc
		(start 374.531128 -278.65578)
		(mid 374.400214 -278.51942)
		(end 374.352566 -278.336502)
		(width 0.088646)
		(layer "In11.Cu")
		(net "M_H_CPU0_SA_DQS_DN<1>")
	)
	(arc
		(start 381.57785 -279.46858)
		(mid 381.299672 -279.398857)
		(end 381.023114 -279.474676)
		(width 0.088646)
		(layer "In11.Cu")
		(net "M_H_CPU0_SA_DQS_DN<1>")
	)
	(arc
		(start 384.398774 -281.097482)
		(mid 384.26786 -280.961122)
		(end 384.220212 -280.778204)
		(width 0.088646)
		(layer "In11.Cu")
		(net "M_H_CPU0_SA_DQS_DN<1>")
	)
	(arc
		(start 377.818904 -279.46858)
		(mid 377.540472 -279.398734)
		(end 377.26366 -279.474676)
		(width 0.088646)
		(layer "In11.Cu")
		(net "M_H_CPU0_SA_DQS_DN<1>")
	)
	(arc
		(start 378.75845 -279.46858)
		(mid 378.480272 -279.398857)
		(end 378.203714 -279.474676)
		(width 0.088646)
		(layer "In11.Cu")
		(net "M_H_CPU0_SA_DQS_DN<1>")
	)
	(arc
		(start 384.220212 -280.759662)
		(mid 384.14005 -280.487473)
		(end 383.937764 -280.288492)
		(width 0.088646)
		(layer "In11.Cu")
		(net "M_H_CPU0_SA_DQS_DN<1>")
	)
	(arc
		(start 382.90246 -279.474676)
		(mid 382.715262 -279.524819)
		(end 382.528064 -279.474676)
		(width 0.088646)
		(layer "In11.Cu")
		(net "M_H_CPU0_SA_DQS_DN<1>")
	)
	(arc
		(start 376.701812 -279.140412)
		(mid 376.623701 -278.863463)
		(end 376.419364 -278.66086)
		(width 0.088646)
		(layer "In11.Cu")
		(net "M_H_CPU0_SA_DQS_DN<1>")
	)
	(arc
		(start 375.479818 -278.66086)
		(mid 375.205619 -278.585025)
		(end 374.929146 -278.652224)
		(width 0.088646)
		(layer "In11.Cu")
		(net "M_H_CPU0_SA_DQS_DN<1>")
	)
	(arc
		(start 374.352566 -278.322278)
		(mid 374.273347 -278.047593)
		(end 374.069864 -277.84679)
		(width 0.088646)
		(layer "In11.Cu")
		(net "M_H_CPU0_SA_DQS_DN<1>")
	)
	(arc
		(start 381.96266 -279.474676)
		(mid 381.775462 -279.524819)
		(end 381.588264 -279.474676)
		(width 0.088646)
		(layer "In11.Cu")
		(net "M_H_CPU0_SA_DQS_DN<1>")
	)
	(arc
		(start 376.880374 -279.469596)
		(mid 376.74946 -279.333236)
		(end 376.701812 -279.150318)
		(width 0.088646)
		(layer "In11.Cu")
		(net "M_H_CPU0_SA_DQS_DN<1>")
	)
	(arc
		(start 374.060974 -276.214078)
		(mid 373.93006 -276.077718)
		(end 373.882412 -275.8948)
		(width 0.088646)
		(layer "In11.Cu")
		(net "M_H_CPU0_SA_DQS_DN<1>")
	)
	(arc
		(start 384.78206 -281.102562)
		(mid 384.594862 -281.152705)
		(end 384.407664 -281.102562)
		(width 0.088646)
		(layer "In11.Cu")
		(net "M_H_CPU0_SA_DQS_DN<1>")
	)
	(arc
		(start 373.882412 -275.872702)
		(mid 373.801501 -275.602574)
		(end 373.600218 -275.405088)
		(width 0.088646)
		(layer "In11.Cu")
		(net "M_H_CPU0_SA_DQS_DN<1>")
	)
	(arc
		(start 373.882666 -277.513796)
		(mid 373.934936 -277.331431)
		(end 374.069864 -277.198074)
		(width 0.088646)
		(layer "In11.Cu")
		(net "M_H_CPU0_SA_DQS_DN<1>")
	)
	(arc
		(start 374.082056 -277.190962)
		(mid 374.352512 -276.708616)
		(end 374.082056 -276.22627)
		(width 0.088646)
		(layer "In11.Cu")
		(net "M_H_CPU0_SA_DQS_DN<1>")
	)
	(arc
		(start 385.347464 -281.102562)
		(mid 385.064762 -281.026786)
		(end 384.78206 -281.102562)
		(width 0.088646)
		(layer "In11.Cu")
		(net "M_H_CPU0_SA_DQS_DN<1>")
	)
	(arc
		(start 375.854214 -278.66086)
		(mid 375.667016 -278.711003)
		(end 375.479818 -278.66086)
		(width 0.088646)
		(layer "In11.Cu")
		(net "M_H_CPU0_SA_DQS_DN<1>")
	)
	(arc
		(start 386.278374 -282.725114)
		(mid 386.14746 -282.588754)
		(end 386.099812 -282.405836)
		(width 0.088646)
		(layer "In11.Cu")
		(net "M_H_CPU0_SA_DQS_DN<1>")
	)
	(arc
		(start 371.711728 -274.761452)
		(mid 371.595919 -274.873381)
		(end 371.537738 -275.02358)
		(width 0.088646)
		(layer "In11.Cu")
		(net "M_H_CPU0_SA_DQS_DN<1>")
	)
	(arc
		(start 385.629912 -281.582114)
		(mid 385.551801 -281.305165)
		(end 385.347464 -281.102562)
		(width 0.088646)
		(layer "In11.Cu")
		(net "M_H_CPU0_SA_DQS_DN<1>")
	)
	(arc
		(start 386.099812 -282.39593)
		(mid 386.021701 -282.118981)
		(end 385.817364 -281.916378)
		(width 0.088646)
		(layer "In11.Cu")
		(net "M_H_CPU0_SA_DQS_DN<1>")
	)
	(arc
		(start 382.513332 -279.46604)
		(mid 382.236857 -279.39872)
		(end 381.96266 -279.474676)
		(width 0.088646)
		(layer "In11.Cu")
		(net "M_H_CPU0_SA_DQS_DN<1>")
	)
	(arc
		(start 386.366512 -282.785312)
		(mid 386.328065 -282.756061)
		(end 386.287264 -282.730194)
		(width 0.088646)
		(layer "In11.Cu")
		(net "M_H_CPU0_SA_DQS_DN<1>")
	)
	(arc
		(start 379.698504 -279.46858)
		(mid 379.420072 -279.398734)
		(end 379.14326 -279.474676)
		(width 0.088646)
		(layer "In11.Cu")
		(net "M_H_CPU0_SA_DQS_DN<1>")
	)
	(arc
		(start 381.023114 -279.474676)
		(mid 380.835916 -279.524819)
		(end 380.648718 -279.474676)
		(width 0.088646)
		(layer "In11.Cu")
		(net "M_H_CPU0_SA_DQS_DN<1>")
	)
	(arc
		(start 380.648718 -279.474676)
		(mid 380.374519 -279.398841)
		(end 380.098046 -279.46604)
		(width 0.088646)
		(layer "In11.Cu")
		(net "M_H_CPU0_SA_DQS_DN<1>")
	)
	(arc
		(start 383.928874 -280.283412)
		(mid 383.79796 -280.147052)
		(end 383.750312 -279.964134)
		(width 0.088646)
		(layer "In11.Cu")
		(net "M_H_CPU0_SA_DQS_DN<1>")
	)
	(arc
		(start 374.069864 -277.84679)
		(mid 373.934931 -277.713436)
		(end 373.882666 -277.531068)
		(width 0.088646)
		(layer "In11.Cu")
		(net "M_H_CPU0_SA_DQS_DN<1>")
	)
	(arc
		(start 372.095014 -274.756372)
		(mid 371.907816 -274.706229)
		(end 371.720618 -274.756372)
		(width 0.088646)
		(layer "In11.Cu")
		(net "M_H_CPU0_SA_DQS_DN<1>")
	)
	(arc
		(start 383.750312 -279.964134)
		(mid 383.676396 -279.684632)
		(end 383.47396 -279.478232)
		(width 0.088646)
		(layer "In11.Cu")
		(net "M_H_CPU0_SA_DQS_DN<1>")
	)
	(arc
		(start 372.282466 -275.08073)
		(mid 372.232682 -274.894116)
		(end 372.096538 -274.757134)
		(width 0.088646)
		(layer "In11.Cu")
		(net "M_H_CPU0_SA_DQS_DN<1>")
	)
	(arc
		(start 374.914414 -278.66086)
		(mid 374.727216 -278.711003)
		(end 374.540018 -278.66086)
		(width 0.088646)
		(layer "In11.Cu")
		(net "M_H_CPU0_SA_DQS_DN<1>")
	)
	(arc
		(start 383.467864 -279.474676)
		(mid 383.193665 -279.398841)
		(end 382.917192 -279.46604)
		(width 0.088646)
		(layer "In11.Cu")
		(net "M_H_CPU0_SA_DQS_DN<1>")
	)
	(arc
		(start 377.26366 -279.474676)
		(mid 377.076462 -279.524819)
		(end 376.889264 -279.474676)
		(width 0.088646)
		(layer "In11.Cu")
		(net "M_H_CPU0_SA_DQS_DN<1>")
	)
	(arc
		(start 380.083314 -279.474676)
		(mid 379.896116 -279.524819)
		(end 379.708918 -279.474676)
		(width 0.088646)
		(layer "In11.Cu")
		(net "M_H_CPU0_SA_DQS_DN<1>")
	)
	(segment
		(start 457.126594 -312.486294)
		(end 457.450698 -312.486294)
		(width 0.20066)
		(layer "F.Cu")
		(net "M_H_CPU0_SA_DQS_DN<0>")
	)
	(segment
		(start 454.518522 -312.7629)
		(end 454.789794 -312.491628)
		(width 0.20066)
		(layer "F.Cu")
		(net "M_H_CPU0_SA_DQS_DN<0>")
	)
	(segment
		(start 458.970634 -312.066686)
		(end 459.559914 -312.066686)
		(width 0.20066)
		(layer "F.Cu")
		(net "M_H_CPU0_SA_DQS_DN<0>")
	)
	(segment
		(start 450.911214 -312.066686)
		(end 452.016114 -312.066686)
		(width 0.20066)
		(layer "F.Cu")
		(net "M_H_CPU0_SA_DQS_DN<0>")
	)
	(segment
		(start 458.39761 -312.307224)
		(end 458.730096 -312.307224)
		(width 0.20066)
		(layer "F.Cu")
		(net "M_H_CPU0_SA_DQS_DN<0>")
	)
	(segment
		(start 457.12126 -312.491628)
		(end 457.126594 -312.486294)
		(width 0.1016)
		(layer "F.Cu")
		(net "M_H_CPU0_SA_DQS_DN<0>")
	)
	(segment
		(start 454.941686 -312.491628)
		(end 457.12126 -312.491628)
		(width 0.1016)
		(layer "F.Cu")
		(net "M_H_CPU0_SA_DQS_DN<0>")
	)
	(segment
		(start 457.682092 -312.717688)
		(end 457.987146 -312.717688)
		(width 0.20066)
		(layer "F.Cu")
		(net "M_H_CPU0_SA_DQS_DN<0>")
	)
	(segment
		(start 453.582278 -312.348372)
		(end 453.996806 -312.7629)
		(width 0.20066)
		(layer "F.Cu")
		(net "M_H_CPU0_SA_DQS_DN<0>")
	)
	(segment
		(start 454.789794 -312.491628)
		(end 454.937368 -312.491628)
		(width 0.20066)
		(layer "F.Cu")
		(net "M_H_CPU0_SA_DQS_DN<0>")
	)
	(segment
		(start 457.987146 -312.717688)
		(end 458.39761 -312.307224)
		(width 0.20066)
		(layer "F.Cu")
		(net "M_H_CPU0_SA_DQS_DN<0>")
	)
	(segment
		(start 452.564754 -312.066686)
		(end 452.84644 -312.348372)
		(width 0.20066)
		(layer "F.Cu")
		(net "M_H_CPU0_SA_DQS_DN<0>")
	)
	(segment
		(start 454.937368 -312.491628)
		(end 454.941686 -312.491628)
		(width 0.101854)
		(layer "F.Cu")
		(net "M_H_CPU0_SA_DQS_DN<0>")
	)
	(segment
		(start 374.257316 -276.986492)
		(end 374.257316 -277.522178)
		(width 0.20066)
		(layer "F.Cu")
		(net "M_H_CPU0_SA_DQS_DN<0>")
	)
	(segment
		(start 457.450698 -312.486294)
		(end 457.682092 -312.717688)
		(width 0.20066)
		(layer "F.Cu")
		(net "M_H_CPU0_SA_DQS_DN<0>")
	)
	(segment
		(start 453.996806 -312.7629)
		(end 454.518522 -312.7629)
		(width 0.20066)
		(layer "F.Cu")
		(net "M_H_CPU0_SA_DQS_DN<0>")
	)
	(segment
		(start 452.84644 -312.348372)
		(end 453.582278 -312.348372)
		(width 0.20066)
		(layer "F.Cu")
		(net "M_H_CPU0_SA_DQS_DN<0>")
	)
	(segment
		(start 374.257316 -277.522178)
		(end 374.257062 -277.522432)
		(width 0.20066)
		(layer "F.Cu")
		(net "M_H_CPU0_SA_DQS_DN<0>")
	)
	(segment
		(start 458.730096 -312.307224)
		(end 458.970634 -312.066686)
		(width 0.20066)
		(layer "F.Cu")
		(net "M_H_CPU0_SA_DQS_DN<0>")
	)
	(segment
		(start 452.016114 -312.066686)
		(end 452.564754 -312.066686)
		(width 0.20066)
		(layer "F.Cu")
		(net "M_H_CPU0_SA_DQS_DN<0>")
	)
	(segment
		(start 434.161438 -313.608212)
		(end 432.444652 -311.891426)
		(width 0.18288)
		(layer "In6.Cu")
		(net "M_H_CPU0_SA_DQS_DN<0>")
	)
	(segment
		(start 374.769634 -277.522432)
		(end 374.257062 -277.522432)
		(width 0.088646)
		(layer "In6.Cu")
		(net "M_H_CPU0_SA_DQS_DN<0>")
	)
	(segment
		(start 450.167502 -312.327798)
		(end 449.721478 -311.881774)
		(width 0.18288)
		(layer "In6.Cu")
		(net "M_H_CPU0_SA_DQS_DN<0>")
	)
	(segment
		(start 432.444652 -311.891426)
		(end 430.406048 -311.891426)
		(width 0.18288)
		(layer "In6.Cu")
		(net "M_H_CPU0_SA_DQS_DN<0>")
	)
	(segment
		(start 386.099812 -279.150318)
		(end 386.099812 -279.140412)
		(width 0.088646)
		(layer "In6.Cu")
		(net "M_H_CPU0_SA_DQS_DN<0>")
	)
	(segment
		(start 439.471562 -312.770774)
		(end 437.444896 -312.770774)
		(width 0.18288)
		(layer "In6.Cu")
		(net "M_H_CPU0_SA_DQS_DN<0>")
	)
	(segment
		(start 422.34612 -308.503574)
		(end 421.484806 -309.364888)
		(width 0.18288)
		(layer "In6.Cu")
		(net "M_H_CPU0_SA_DQS_DN<0>")
	)
	(segment
		(start 387.782816 -280.237184)
		(end 387.695186 -280.025602)
		(width 0.088646)
		(layer "In6.Cu")
		(net "M_H_CPU0_SA_DQS_DN<0>")
	)
	(segment
		(start 440.92114 -312.770774)
		(end 440.378342 -312.770774)
		(width 0.18288)
		(layer "In6.Cu")
		(net "M_H_CPU0_SA_DQS_DN<0>")
	)
	(segment
		(start 405.19223 -305.944524)
		(end 404.82774 -305.944524)
		(width 0.18288)
		(layer "In6.Cu")
		(net "M_H_CPU0_SA_DQS_DN<0>")
	)
	(segment
		(start 409.288742 -305.121818)
		(end 407.224738 -305.121818)
		(width 0.18288)
		(layer "In6.Cu")
		(net "M_H_CPU0_SA_DQS_DN<0>")
	)
	(segment
		(start 425.284646 -308.51348)
		(end 425.013628 -308.242462)
		(width 0.18288)
		(layer "In6.Cu")
		(net "M_H_CPU0_SA_DQS_DN<0>")
	)
	(segment
		(start 409.567888 -304.842672)
		(end 409.288742 -305.121818)
		(width 0.18288)
		(layer "In6.Cu")
		(net "M_H_CPU0_SA_DQS_DN<0>")
	)
	(segment
		(start 388.16153 -280.868628)
		(end 388.074662 -280.781506)
		(width 0.088646)
		(layer "In6.Cu")
		(net "M_H_CPU0_SA_DQS_DN<0>")
	)
	(segment
		(start 396.10411 -283.485082)
		(end 393.427966 -280.808938)
		(width 0.18288)
		(layer "In6.Cu")
		(net "M_H_CPU0_SA_DQS_DN<0>")
	)
	(segment
		(start 388.307326 -280.808938)
		(end 388.283958 -280.808938)
		(width 0.088646)
		(layer "In6.Cu")
		(net "M_H_CPU0_SA_DQS_DN<0>")
	)
	(segment
		(start 404.82774 -305.944524)
		(end 403.968458 -305.085242)
		(width 0.18288)
		(layer "In6.Cu")
		(net "M_H_CPU0_SA_DQS_DN<0>")
	)
	(segment
		(start 379.708664 -277.84679)
		(end 379.69825 -277.840694)
		(width 0.088646)
		(layer "In6.Cu")
		(net "M_H_CPU0_SA_DQS_DN<0>")
	)
	(segment
		(start 409.942284 -304.842672)
		(end 409.567888 -304.842672)
		(width 0.18288)
		(layer "In6.Cu")
		(net "M_H_CPU0_SA_DQS_DN<0>")
	)
	(segment
		(start 386.661914 -279.47493)
		(end 386.66166 -279.474676)
		(width 0.088646)
		(layer "In6.Cu")
		(net "M_H_CPU0_SA_DQS_DN<0>")
	)
	(segment
		(start 444.909194 -312.555128)
		(end 444.35522 -312.001154)
		(width 0.18288)
		(layer "In6.Cu")
		(net "M_H_CPU0_SA_DQS_DN<0>")
	)
	(segment
		(start 403.968458 -300.968664)
		(end 396.10411 -293.104316)
		(width 0.18288)
		(layer "In6.Cu")
		(net "M_H_CPU0_SA_DQS_DN<0>")
	)
	(segment
		(start 410.20746 -305.107848)
		(end 409.942284 -304.842672)
		(width 0.18288)
		(layer "In6.Cu")
		(net "M_H_CPU0_SA_DQS_DN<0>")
	)
	(segment
		(start 436.273702 -313.609736)
		(end 436.004716 -313.34075)
		(width 0.18288)
		(layer "In6.Cu")
		(net "M_H_CPU0_SA_DQS_DN<0>")
	)
	(segment
		(start 437.444896 -312.770774)
		(end 436.605934 -313.609736)
		(width 0.18288)
		(layer "In6.Cu")
		(net "M_H_CPU0_SA_DQS_DN<0>")
	)
	(segment
		(start 439.749692 -312.492644)
		(end 439.471562 -312.770774)
		(width 0.18288)
		(layer "In6.Cu")
		(net "M_H_CPU0_SA_DQS_DN<0>")
	)
	(segment
		(start 387.472174 -279.6921)
		(end 387.341618 -279.562052)
		(width 0.088646)
		(layer "In6.Cu")
		(net "M_H_CPU0_SA_DQS_DN<0>")
	)
	(segment
		(start 385.629912 -278.336502)
		(end 385.629912 -278.31796)
		(width 0.088646)
		(layer "In6.Cu")
		(net "M_H_CPU0_SA_DQS_DN<0>")
	)
	(segment
		(start 421.193976 -309.364888)
		(end 420.921688 -309.0926)
		(width 0.18288)
		(layer "In6.Cu")
		(net "M_H_CPU0_SA_DQS_DN<0>")
	)
	(segment
		(start 387.695186 -280.025602)
		(end 387.472174 -279.6921)
		(width 0.088646)
		(layer "In6.Cu")
		(net "M_H_CPU0_SA_DQS_DN<0>")
	)
	(segment
		(start 441.69076 -312.001154)
		(end 440.92114 -312.770774)
		(width 0.18288)
		(layer "In6.Cu")
		(net "M_H_CPU0_SA_DQS_DN<0>")
	)
	(segment
		(start 412.53664 -306.46243)
		(end 411.182058 -305.107848)
		(width 0.18288)
		(layer "In6.Cu")
		(net "M_H_CPU0_SA_DQS_DN<0>")
	)
	(segment
		(start 407.224738 -305.121818)
		(end 406.380696 -305.96586)
		(width 0.18288)
		(layer "In6.Cu")
		(net "M_H_CPU0_SA_DQS_DN<0>")
	)
	(segment
		(start 424.652948 -308.242462)
		(end 424.391836 -308.503574)
		(width 0.18288)
		(layer "In6.Cu")
		(net "M_H_CPU0_SA_DQS_DN<0>")
	)
	(segment
		(start 416.848798 -309.344314)
		(end 412.53664 -306.46243)
		(width 0.18288)
		(layer "In6.Cu")
		(net "M_H_CPU0_SA_DQS_DN<0>")
	)
	(segment
		(start 406.380696 -305.96586)
		(end 406.121616 -305.96586)
		(width 0.18288)
		(layer "In6.Cu")
		(net "M_H_CPU0_SA_DQS_DN<0>")
	)
	(segment
		(start 388.283958 -280.808938)
		(end 388.224268 -280.868628)
		(width 0.088646)
		(layer "In6.Cu")
		(net "M_H_CPU0_SA_DQS_DN<0>")
	)
	(segment
		(start 427.94174 -310.166766)
		(end 426.288454 -308.51348)
		(width 0.18288)
		(layer "In6.Cu")
		(net "M_H_CPU0_SA_DQS_DN<0>")
	)
	(segment
		(start 376.889264 -277.84679)
		(end 376.874532 -277.838154)
		(width 0.088646)
		(layer "In6.Cu")
		(net "M_H_CPU0_SA_DQS_DN<0>")
	)
	(segment
		(start 403.968458 -305.085242)
		(end 403.968458 -300.968664)
		(width 0.18288)
		(layer "In6.Cu")
		(net "M_H_CPU0_SA_DQS_DN<0>")
	)
	(segment
		(start 384.407664 -277.84679)
		(end 384.39725 -277.840694)
		(width 0.088646)
		(layer "In6.Cu")
		(net "M_H_CPU0_SA_DQS_DN<0>")
	)
	(segment
		(start 450.911214 -312.066686)
		(end 450.650102 -312.327798)
		(width 0.18288)
		(layer "In6.Cu")
		(net "M_H_CPU0_SA_DQS_DN<0>")
	)
	(segment
		(start 421.484806 -309.364888)
		(end 421.193976 -309.364888)
		(width 0.18288)
		(layer "In6.Cu")
		(net "M_H_CPU0_SA_DQS_DN<0>")
	)
	(segment
		(start 406.121616 -305.96586)
		(end 405.850852 -305.695096)
		(width 0.18288)
		(layer "In6.Cu")
		(net "M_H_CPU0_SA_DQS_DN<0>")
	)
	(segment
		(start 426.288454 -308.51348)
		(end 425.284646 -308.51348)
		(width 0.18288)
		(layer "In6.Cu")
		(net "M_H_CPU0_SA_DQS_DN<0>")
	)
	(segment
		(start 405.441658 -305.695096)
		(end 405.19223 -305.944524)
		(width 0.18288)
		(layer "In6.Cu")
		(net "M_H_CPU0_SA_DQS_DN<0>")
	)
	(segment
		(start 383.46761 -277.84679)
		(end 383.457196 -277.840694)
		(width 0.088646)
		(layer "In6.Cu")
		(net "M_H_CPU0_SA_DQS_DN<0>")
	)
	(segment
		(start 430.406048 -311.891426)
		(end 428.681388 -310.166766)
		(width 0.18288)
		(layer "In6.Cu")
		(net "M_H_CPU0_SA_DQS_DN<0>")
	)
	(segment
		(start 380.648464 -277.84679)
		(end 380.633732 -277.838154)
		(width 0.088646)
		(layer "In6.Cu")
		(net "M_H_CPU0_SA_DQS_DN<0>")
	)
	(segment
		(start 440.100212 -312.492644)
		(end 439.749692 -312.492644)
		(width 0.18288)
		(layer "In6.Cu")
		(net "M_H_CPU0_SA_DQS_DN<0>")
	)
	(segment
		(start 446.900046 -311.881774)
		(end 446.226692 -312.555128)
		(width 0.18288)
		(layer "In6.Cu")
		(net "M_H_CPU0_SA_DQS_DN<0>")
	)
	(segment
		(start 375.39295 -277.203154)
		(end 375.38406 -277.198074)
		(width 0.088646)
		(layer "In6.Cu")
		(net "M_H_CPU0_SA_DQS_DN<0>")
	)
	(segment
		(start 420.29761 -309.344314)
		(end 416.848798 -309.344314)
		(width 0.18288)
		(layer "In6.Cu")
		(net "M_H_CPU0_SA_DQS_DN<0>")
	)
	(segment
		(start 436.004716 -313.34075)
		(end 435.636162 -313.34075)
		(width 0.18288)
		(layer "In6.Cu")
		(net "M_H_CPU0_SA_DQS_DN<0>")
	)
	(segment
		(start 420.549324 -309.0926)
		(end 420.29761 -309.344314)
		(width 0.18288)
		(layer "In6.Cu")
		(net "M_H_CPU0_SA_DQS_DN<0>")
	)
	(segment
		(start 444.35522 -312.001154)
		(end 441.69076 -312.001154)
		(width 0.18288)
		(layer "In6.Cu")
		(net "M_H_CPU0_SA_DQS_DN<0>")
	)
	(segment
		(start 428.681388 -310.166766)
		(end 427.94174 -310.166766)
		(width 0.18288)
		(layer "In6.Cu")
		(net "M_H_CPU0_SA_DQS_DN<0>")
	)
	(segment
		(start 374.826784 -277.465282)
		(end 374.769634 -277.522432)
		(width 0.088646)
		(layer "In6.Cu")
		(net "M_H_CPU0_SA_DQS_DN<0>")
	)
	(segment
		(start 396.10411 -293.104316)
		(end 396.10411 -283.485082)
		(width 0.18288)
		(layer "In6.Cu")
		(net "M_H_CPU0_SA_DQS_DN<0>")
	)
	(segment
		(start 377.829318 -277.84679)
		(end 377.818904 -277.840694)
		(width 0.088646)
		(layer "In6.Cu")
		(net "M_H_CPU0_SA_DQS_DN<0>")
	)
	(segment
		(start 446.226692 -312.555128)
		(end 444.909194 -312.555128)
		(width 0.18288)
		(layer "In6.Cu")
		(net "M_H_CPU0_SA_DQS_DN<0>")
	)
	(segment
		(start 424.391836 -308.503574)
		(end 422.34612 -308.503574)
		(width 0.18288)
		(layer "In6.Cu")
		(net "M_H_CPU0_SA_DQS_DN<0>")
	)
	(segment
		(start 440.378342 -312.770774)
		(end 440.100212 -312.492644)
		(width 0.18288)
		(layer "In6.Cu")
		(net "M_H_CPU0_SA_DQS_DN<0>")
	)
	(segment
		(start 375.708672 -277.469092)
		(end 375.60377 -277.36419)
		(width 0.088646)
		(layer "In6.Cu")
		(net "M_H_CPU0_SA_DQS_DN<0>")
	)
	(segment
		(start 420.921688 -309.0926)
		(end 420.549324 -309.0926)
		(width 0.18288)
		(layer "In6.Cu")
		(net "M_H_CPU0_SA_DQS_DN<0>")
	)
	(segment
		(start 381.588264 -277.84679)
		(end 381.573532 -277.838154)
		(width 0.088646)
		(layer "In6.Cu")
		(net "M_H_CPU0_SA_DQS_DN<0>")
	)
	(segment
		(start 425.013628 -308.242462)
		(end 424.652948 -308.242462)
		(width 0.18288)
		(layer "In6.Cu")
		(net "M_H_CPU0_SA_DQS_DN<0>")
	)
	(segment
		(start 411.182058 -305.107848)
		(end 410.20746 -305.107848)
		(width 0.18288)
		(layer "In6.Cu")
		(net "M_H_CPU0_SA_DQS_DN<0>")
	)
	(segment
		(start 388.224268 -280.868628)
		(end 388.16153 -280.868628)
		(width 0.088646)
		(layer "In6.Cu")
		(net "M_H_CPU0_SA_DQS_DN<0>")
	)
	(segment
		(start 435.3687 -313.608212)
		(end 434.161438 -313.608212)
		(width 0.18288)
		(layer "In6.Cu")
		(net "M_H_CPU0_SA_DQS_DN<0>")
	)
	(segment
		(start 386.662168 -279.47493)
		(end 386.661914 -279.47493)
		(width 0.088646)
		(layer "In6.Cu")
		(net "M_H_CPU0_SA_DQS_DN<0>")
	)
	(segment
		(start 393.427966 -280.808938)
		(end 388.307326 -280.808938)
		(width 0.18288)
		(layer "In6.Cu")
		(net "M_H_CPU0_SA_DQS_DN<0>")
	)
	(segment
		(start 388.074662 -280.781506)
		(end 387.782816 -280.237184)
		(width 0.088646)
		(layer "In6.Cu")
		(net "M_H_CPU0_SA_DQS_DN<0>")
	)
	(segment
		(start 435.636162 -313.34075)
		(end 435.3687 -313.608212)
		(width 0.18288)
		(layer "In6.Cu")
		(net "M_H_CPU0_SA_DQS_DN<0>")
	)
	(segment
		(start 405.850852 -305.695096)
		(end 405.441658 -305.695096)
		(width 0.18288)
		(layer "In6.Cu")
		(net "M_H_CPU0_SA_DQS_DN<0>")
	)
	(segment
		(start 450.650102 -312.327798)
		(end 450.167502 -312.327798)
		(width 0.18288)
		(layer "In6.Cu")
		(net "M_H_CPU0_SA_DQS_DN<0>")
	)
	(segment
		(start 378.218446 -277.838154)
		(end 378.203714 -277.84679)
		(width 0.088646)
		(layer "In6.Cu")
		(net "M_H_CPU0_SA_DQS_DN<0>")
	)
	(segment
		(start 385.817364 -278.66086)
		(end 385.808474 -278.65578)
		(width 0.088646)
		(layer "In6.Cu")
		(net "M_H_CPU0_SA_DQS_DN<0>")
	)
	(segment
		(start 436.605934 -313.609736)
		(end 436.273702 -313.609736)
		(width 0.18288)
		(layer "In6.Cu")
		(net "M_H_CPU0_SA_DQS_DN<0>")
	)
	(segment
		(start 449.721478 -311.881774)
		(end 446.900046 -311.881774)
		(width 0.18288)
		(layer "In6.Cu")
		(net "M_H_CPU0_SA_DQS_DN<0>")
	)
	(arc
		(start 377.818904 -277.840694)
		(mid 377.540472 -277.77088)
		(end 377.26366 -277.84679)
		(width 0.088646)
		(layer "In6.Cu")
		(net "M_H_CPU0_SA_DQS_DN<0>")
	)
	(arc
		(start 375.60377 -277.36419)
		(mid 375.503723 -277.276652)
		(end 375.39295 -277.203154)
		(width 0.088646)
		(layer "In6.Cu")
		(net "M_H_CPU0_SA_DQS_DN<0>")
	)
	(arc
		(start 381.02286 -277.84679)
		(mid 380.835662 -277.896933)
		(end 380.648464 -277.84679)
		(width 0.088646)
		(layer "In6.Cu")
		(net "M_H_CPU0_SA_DQS_DN<0>")
	)
	(arc
		(start 380.08306 -277.84679)
		(mid 379.895862 -277.896933)
		(end 379.708664 -277.84679)
		(width 0.088646)
		(layer "In6.Cu")
		(net "M_H_CPU0_SA_DQS_DN<0>")
	)
	(arc
		(start 375.766838 -277.58263)
		(mid 375.746706 -277.521272)
		(end 375.708672 -277.469092)
		(width 0.088646)
		(layer "In6.Cu")
		(net "M_H_CPU0_SA_DQS_DN<0>")
	)
	(arc
		(start 386.099812 -279.140412)
		(mid 386.021701 -278.863463)
		(end 385.817364 -278.66086)
		(width 0.088646)
		(layer "In6.Cu")
		(net "M_H_CPU0_SA_DQS_DN<0>")
	)
	(arc
		(start 384.39725 -277.840694)
		(mid 384.118818 -277.77088)
		(end 383.842006 -277.84679)
		(width 0.088646)
		(layer "In6.Cu")
		(net "M_H_CPU0_SA_DQS_DN<0>")
	)
	(arc
		(start 376.874532 -277.838154)
		(mid 376.598091 -277.770988)
		(end 376.32386 -277.84679)
		(width 0.088646)
		(layer "In6.Cu")
		(net "M_H_CPU0_SA_DQS_DN<0>")
	)
	(arc
		(start 383.457196 -277.840694)
		(mid 383.179018 -277.771002)
		(end 382.90246 -277.84679)
		(width 0.088646)
		(layer "In6.Cu")
		(net "M_H_CPU0_SA_DQS_DN<0>")
	)
	(arc
		(start 381.573532 -277.838154)
		(mid 381.297091 -277.770988)
		(end 381.02286 -277.84679)
		(width 0.088646)
		(layer "In6.Cu")
		(net "M_H_CPU0_SA_DQS_DN<0>")
	)
	(arc
		(start 386.66166 -279.474676)
		(mid 386.287185 -279.47463)
		(end 386.099812 -279.150318)
		(width 0.088646)
		(layer "In6.Cu")
		(net "M_H_CPU0_SA_DQS_DN<0>")
	)
	(arc
		(start 376.32386 -277.84679)
		(mid 375.976131 -277.860783)
		(end 375.766838 -277.58263)
		(width 0.088646)
		(layer "In6.Cu")
		(net "M_H_CPU0_SA_DQS_DN<0>")
	)
	(arc
		(start 375.38406 -277.198074)
		(mid 375.034955 -277.184738)
		(end 374.826784 -277.465282)
		(width 0.088646)
		(layer "In6.Cu")
		(net "M_H_CPU0_SA_DQS_DN<0>")
	)
	(arc
		(start 378.769118 -277.84679)
		(mid 378.494889 -277.770865)
		(end 378.218446 -277.838154)
		(width 0.088646)
		(layer "In6.Cu")
		(net "M_H_CPU0_SA_DQS_DN<0>")
	)
	(arc
		(start 385.629912 -278.31796)
		(mid 385.339434 -277.842241)
		(end 384.78206 -277.84679)
		(width 0.088646)
		(layer "In6.Cu")
		(net "M_H_CPU0_SA_DQS_DN<0>")
	)
	(arc
		(start 387.341618 -279.562052)
		(mid 387.313255 -279.536045)
		(end 387.283198 -279.512014)
		(width 0.088646)
		(layer "In6.Cu")
		(net "M_H_CPU0_SA_DQS_DN<0>")
	)
	(arc
		(start 384.78206 -277.84679)
		(mid 384.594862 -277.896933)
		(end 384.407664 -277.84679)
		(width 0.088646)
		(layer "In6.Cu")
		(net "M_H_CPU0_SA_DQS_DN<0>")
	)
	(arc
		(start 382.528064 -277.84679)
		(mid 382.245362 -277.771048)
		(end 381.96266 -277.84679)
		(width 0.088646)
		(layer "In6.Cu")
		(net "M_H_CPU0_SA_DQS_DN<0>")
	)
	(arc
		(start 379.143514 -277.84679)
		(mid 378.956316 -277.896933)
		(end 378.769118 -277.84679)
		(width 0.088646)
		(layer "In6.Cu")
		(net "M_H_CPU0_SA_DQS_DN<0>")
	)
	(arc
		(start 387.283198 -279.512014)
		(mid 386.978253 -279.400291)
		(end 386.662168 -279.47493)
		(width 0.088646)
		(layer "In6.Cu")
		(net "M_H_CPU0_SA_DQS_DN<0>")
	)
	(arc
		(start 385.808474 -278.65578)
		(mid 385.67756 -278.51942)
		(end 385.629912 -278.336502)
		(width 0.088646)
		(layer "In6.Cu")
		(net "M_H_CPU0_SA_DQS_DN<0>")
	)
	(arc
		(start 379.69825 -277.840694)
		(mid 379.420072 -277.771002)
		(end 379.143514 -277.84679)
		(width 0.088646)
		(layer "In6.Cu")
		(net "M_H_CPU0_SA_DQS_DN<0>")
	)
	(arc
		(start 382.90246 -277.84679)
		(mid 382.715262 -277.896933)
		(end 382.528064 -277.84679)
		(width 0.088646)
		(layer "In6.Cu")
		(net "M_H_CPU0_SA_DQS_DN<0>")
	)
	(arc
		(start 381.96266 -277.84679)
		(mid 381.775462 -277.896933)
		(end 381.588264 -277.84679)
		(width 0.088646)
		(layer "In6.Cu")
		(net "M_H_CPU0_SA_DQS_DN<0>")
	)
	(arc
		(start 377.26366 -277.84679)
		(mid 377.076462 -277.896933)
		(end 376.889264 -277.84679)
		(width 0.088646)
		(layer "In6.Cu")
		(net "M_H_CPU0_SA_DQS_DN<0>")
	)
	(arc
		(start 380.633732 -277.838154)
		(mid 380.357291 -277.770988)
		(end 380.08306 -277.84679)
		(width 0.088646)
		(layer "In6.Cu")
		(net "M_H_CPU0_SA_DQS_DN<0>")
	)
	(arc
		(start 378.203714 -277.84679)
		(mid 378.016516 -277.896933)
		(end 377.829318 -277.84679)
		(width 0.088646)
		(layer "In6.Cu")
		(net "M_H_CPU0_SA_DQS_DN<0>")
	)
	(arc
		(start 383.842006 -277.84679)
		(mid 383.654808 -277.896933)
		(end 383.46761 -277.84679)
		(width 0.088646)
		(layer "In6.Cu")
		(net "M_H_CPU0_SA_DQS_DN<0>")
	)
	(segment
		(start 453.785478 -305.515264)
		(end 453.536812 -305.266598)
		(width 0.20066)
		(layer "F.Cu")
		(net "M_H_CPU0_SA_DQ<9>")
	)
	(segment
		(start 454.260712 -305.515264)
		(end 453.785478 -305.515264)
		(width 0.20066)
		(layer "F.Cu")
		(net "M_H_CPU0_SA_DQ<9>")
	)
	(segment
		(start 454.931526 -304.841656)
		(end 454.91146 -304.841656)
		(width 0.101854)
		(layer "F.Cu")
		(net "M_H_CPU0_SA_DQ<9>")
	)
	(segment
		(start 457.53655 -304.835306)
		(end 457.126594 -304.835306)
		(width 0.20066)
		(layer "F.Cu")
		(net "M_H_CPU0_SA_DQ<9>")
	)
	(segment
		(start 459.559914 -305.266598)
		(end 459.55966 -305.266852)
		(width 0.20066)
		(layer "F.Cu")
		(net "M_H_CPU0_SA_DQ<9>")
	)
	(segment
		(start 371.437916 -275.894546)
		(end 371.437662 -275.8948)
		(width 0.20066)
		(layer "F.Cu")
		(net "M_H_CPU0_SA_DQ<9>")
	)
	(segment
		(start 457.126594 -304.835306)
		(end 457.120244 -304.841656)
		(width 0.1016)
		(layer "F.Cu")
		(net "M_H_CPU0_SA_DQ<9>")
	)
	(segment
		(start 454.91146 -304.841656)
		(end 454.566782 -304.841656)
		(width 0.20066)
		(layer "F.Cu")
		(net "M_H_CPU0_SA_DQ<9>")
	)
	(segment
		(start 459.55966 -305.266852)
		(end 457.968096 -305.266852)
		(width 0.20066)
		(layer "F.Cu")
		(net "M_H_CPU0_SA_DQ<9>")
	)
	(segment
		(start 453.536812 -305.266598)
		(end 452.016114 -305.266598)
		(width 0.20066)
		(layer "F.Cu")
		(net "M_H_CPU0_SA_DQ<9>")
	)
	(segment
		(start 371.437916 -275.35886)
		(end 371.437916 -275.894546)
		(width 0.20066)
		(layer "F.Cu")
		(net "M_H_CPU0_SA_DQ<9>")
	)
	(segment
		(start 457.120244 -304.841656)
		(end 454.931526 -304.841656)
		(width 0.1016)
		(layer "F.Cu")
		(net "M_H_CPU0_SA_DQ<9>")
	)
	(segment
		(start 457.968096 -305.266852)
		(end 457.53655 -304.835306)
		(width 0.20066)
		(layer "F.Cu")
		(net "M_H_CPU0_SA_DQ<9>")
	)
	(segment
		(start 452.016114 -305.266598)
		(end 450.911214 -305.266598)
		(width 0.20066)
		(layer "F.Cu")
		(net "M_H_CPU0_SA_DQ<9>")
	)
	(segment
		(start 454.448672 -304.959766)
		(end 454.448672 -305.327304)
		(width 0.20066)
		(layer "F.Cu")
		(net "M_H_CPU0_SA_DQ<9>")
	)
	(segment
		(start 454.448672 -305.327304)
		(end 454.260712 -305.515264)
		(width 0.20066)
		(layer "F.Cu")
		(net "M_H_CPU0_SA_DQ<9>")
	)
	(segment
		(start 454.566782 -304.841656)
		(end 454.448672 -304.959766)
		(width 0.20066)
		(layer "F.Cu")
		(net "M_H_CPU0_SA_DQ<9>")
	)
	(segment
		(start 384.79095 -282.086558)
		(end 384.78206 -282.081478)
		(width 0.088646)
		(layer "In11.Cu")
		(net "M_H_CPU0_SA_DQ<9>")
	)
	(segment
		(start 447.880994 -308.106826)
		(end 447.144394 -308.106826)
		(width 0.18288)
		(layer "In11.Cu")
		(net "M_H_CPU0_SA_DQ<9>")
	)
	(segment
		(start 443.486794 -311.916826)
		(end 442.426852 -311.916826)
		(width 0.18288)
		(layer "In11.Cu")
		(net "M_H_CPU0_SA_DQ<9>")
	)
	(segment
		(start 373.51335 -278.83104)
		(end 373.50446 -278.82596)
		(width 0.088646)
		(layer "In11.Cu")
		(net "M_H_CPU0_SA_DQ<9>")
	)
	(segment
		(start 425.479972 -313.340242)
		(end 423.628566 -313.340242)
		(width 0.18288)
		(layer "In11.Cu")
		(net "M_H_CPU0_SA_DQ<9>")
	)
	(segment
		(start 373.974614 -279.639776)
		(end 373.968518 -279.63622)
		(width 0.088646)
		(layer "In11.Cu")
		(net "M_H_CPU0_SA_DQ<9>")
	)
	(segment
		(start 421.185086 -314.18911)
		(end 419.355524 -314.18911)
		(width 0.18288)
		(layer "In11.Cu")
		(net "M_H_CPU0_SA_DQ<9>")
	)
	(segment
		(start 386.995162 -285.65221)
		(end 386.739384 -285.396432)
		(width 0.088646)
		(layer "In11.Cu")
		(net "M_H_CPU0_SA_DQ<9>")
	)
	(segment
		(start 429.028098 -312.404252)
		(end 426.415962 -312.404252)
		(width 0.18288)
		(layer "In11.Cu")
		(net "M_H_CPU0_SA_DQ<9>")
	)
	(segment
		(start 450.911214 -305.539902)
		(end 450.777102 -305.674014)
		(width 0.18288)
		(layer "In11.Cu")
		(net "M_H_CPU0_SA_DQ<9>")
	)
	(segment
		(start 437.618124 -312.491882)
		(end 436.767986 -311.641744)
		(width 0.18288)
		(layer "In11.Cu")
		(net "M_H_CPU0_SA_DQ<9>")
	)
	(segment
		(start 387.30555 -286.35452)
		(end 386.995162 -286.044132)
		(width 0.088646)
		(layer "In11.Cu")
		(net "M_H_CPU0_SA_DQ<9>")
	)
	(segment
		(start 431.715926 -311.83072)
		(end 429.60163 -311.83072)
		(width 0.18288)
		(layer "In11.Cu")
		(net "M_H_CPU0_SA_DQ<9>")
	)
	(segment
		(start 450.777102 -305.674014)
		(end 449.985892 -306.001928)
		(width 0.18288)
		(layer "In11.Cu")
		(net "M_H_CPU0_SA_DQ<9>")
	)
	(segment
		(start 423.628566 -313.340242)
		(end 423.499534 -313.21121)
		(width 0.18288)
		(layer "In11.Cu")
		(net "M_H_CPU0_SA_DQ<9>")
	)
	(segment
		(start 383.089912 -280.78811)
		(end 383.089912 -280.778204)
		(width 0.088646)
		(layer "In11.Cu")
		(net "M_H_CPU0_SA_DQ<9>")
	)
	(segment
		(start 415.88944 -310.723026)
		(end 414.97631 -310.723026)
		(width 0.18288)
		(layer "In11.Cu")
		(net "M_H_CPU0_SA_DQ<9>")
	)
	(segment
		(start 414.507426 -311.842658)
		(end 407.858468 -311.842658)
		(width 0.18288)
		(layer "In11.Cu")
		(net "M_H_CPU0_SA_DQ<9>")
	)
	(segment
		(start 439.4454 -313.343798)
		(end 438.593484 -312.491882)
		(width 0.18288)
		(layer "In11.Cu")
		(net "M_H_CPU0_SA_DQ<9>")
	)
	(segment
		(start 446.356994 -308.894226)
		(end 445.544194 -308.894226)
		(width 0.18288)
		(layer "In11.Cu")
		(net "M_H_CPU0_SA_DQ<9>")
	)
	(segment
		(start 414.667446 -311.03189)
		(end 414.667446 -311.682638)
		(width 0.18288)
		(layer "In11.Cu")
		(net "M_H_CPU0_SA_DQ<9>")
	)
	(segment
		(start 423.499534 -313.21121)
		(end 422.162986 -313.21121)
		(width 0.18288)
		(layer "In11.Cu")
		(net "M_H_CPU0_SA_DQ<9>")
	)
	(segment
		(start 382.528064 -280.453846)
		(end 382.513332 -280.462482)
		(width 0.088646)
		(layer "In11.Cu")
		(net "M_H_CPU0_SA_DQ<9>")
	)
	(segment
		(start 373.985028 -279.645872)
		(end 373.974614 -279.639776)
		(width 0.088646)
		(layer "In11.Cu")
		(net "M_H_CPU0_SA_DQ<9>")
	)
	(segment
		(start 392.006582 -291.055552)
		(end 387.30555 -286.35452)
		(width 0.18288)
		(layer "In11.Cu")
		(net "M_H_CPU0_SA_DQ<9>")
	)
	(segment
		(start 416.352228 -311.185814)
		(end 415.88944 -310.723026)
		(width 0.18288)
		(layer "In11.Cu")
		(net "M_H_CPU0_SA_DQ<9>")
	)
	(segment
		(start 386.379212 -284.863032)
		(end 386.379212 -284.838902)
		(width 0.088646)
		(layer "In11.Cu")
		(net "M_H_CPU0_SA_DQ<9>")
	)
	(segment
		(start 407.858468 -311.842658)
		(end 406.72639 -310.71058)
		(width 0.18288)
		(layer "In11.Cu")
		(net "M_H_CPU0_SA_DQ<9>")
	)
	(segment
		(start 375.863104 -279.644856)
		(end 375.854214 -279.639776)
		(width 0.088646)
		(layer "In11.Cu")
		(net "M_H_CPU0_SA_DQ<9>")
	)
	(segment
		(start 422.162986 -313.21121)
		(end 421.185086 -314.18911)
		(width 0.18288)
		(layer "In11.Cu")
		(net "M_H_CPU0_SA_DQ<9>")
	)
	(segment
		(start 414.667446 -311.682638)
		(end 414.507426 -311.842658)
		(width 0.18288)
		(layer "In11.Cu")
		(net "M_H_CPU0_SA_DQ<9>")
	)
	(segment
		(start 416.207448 -312.325512)
		(end 415.982658 -312.100722)
		(width 0.18288)
		(layer "In11.Cu")
		(net "M_H_CPU0_SA_DQ<9>")
	)
	(segment
		(start 415.982658 -311.827926)
		(end 416.352228 -311.458356)
		(width 0.18288)
		(layer "In11.Cu")
		(net "M_H_CPU0_SA_DQ<9>")
	)
	(segment
		(start 417.12261 -311.956196)
		(end 416.84956 -311.956196)
		(width 0.18288)
		(layer "In11.Cu")
		(net "M_H_CPU0_SA_DQ<9>")
	)
	(segment
		(start 383.38125 -281.272742)
		(end 383.37236 -281.267662)
		(width 0.088646)
		(layer "In11.Cu")
		(net "M_H_CPU0_SA_DQ<9>")
	)
	(segment
		(start 440.99988 -313.343798)
		(end 439.4454 -313.343798)
		(width 0.18288)
		(layer "In11.Cu")
		(net "M_H_CPU0_SA_DQ<9>")
	)
	(segment
		(start 414.97631 -310.723026)
		(end 414.667446 -311.03189)
		(width 0.18288)
		(layer "In11.Cu")
		(net "M_H_CPU0_SA_DQ<9>")
	)
	(segment
		(start 386.995162 -286.044132)
		(end 386.995162 -285.65221)
		(width 0.088646)
		(layer "In11.Cu")
		(net "M_H_CPU0_SA_DQ<9>")
	)
	(segment
		(start 436.767986 -311.641744)
		(end 431.904902 -311.641744)
		(width 0.18288)
		(layer "In11.Cu")
		(net "M_H_CPU0_SA_DQ<9>")
	)
	(segment
		(start 376.889264 -280.453846)
		(end 376.874532 -280.462482)
		(width 0.088646)
		(layer "In11.Cu")
		(net "M_H_CPU0_SA_DQ<9>")
	)
	(segment
		(start 450.911214 -305.266598)
		(end 450.911214 -305.539902)
		(width 0.18288)
		(layer "In11.Cu")
		(net "M_H_CPU0_SA_DQ<9>")
	)
	(segment
		(start 429.60163 -311.83072)
		(end 429.028098 -312.404252)
		(width 0.18288)
		(layer "In11.Cu")
		(net "M_H_CPU0_SA_DQ<9>")
	)
	(segment
		(start 372.064788 -276.366986)
		(end 371.437662 -275.8948)
		(width 0.088646)
		(layer "In11.Cu")
		(net "M_H_CPU0_SA_DQ<9>")
	)
	(segment
		(start 378.768864 -280.453846)
		(end 378.754132 -280.462482)
		(width 0.088646)
		(layer "In11.Cu")
		(net "M_H_CPU0_SA_DQ<9>")
	)
	(segment
		(start 445.544194 -308.894226)
		(end 444.819786 -309.618634)
		(width 0.18288)
		(layer "In11.Cu")
		(net "M_H_CPU0_SA_DQ<9>")
	)
	(segment
		(start 382.91135 -280.458926)
		(end 382.90246 -280.453846)
		(width 0.088646)
		(layer "In11.Cu")
		(net "M_H_CPU0_SA_DQ<9>")
	)
	(segment
		(start 406.72639 -310.71058)
		(end 405.519636 -310.71058)
		(width 0.18288)
		(layer "In11.Cu")
		(net "M_H_CPU0_SA_DQ<9>")
	)
	(segment
		(start 392.006582 -292.490652)
		(end 392.006582 -291.055552)
		(width 0.18288)
		(layer "In11.Cu")
		(net "M_H_CPU0_SA_DQ<9>")
	)
	(segment
		(start 415.982658 -312.100722)
		(end 415.982658 -311.827926)
		(width 0.18288)
		(layer "In11.Cu")
		(net "M_H_CPU0_SA_DQ<9>")
	)
	(segment
		(start 373.222012 -276.708616)
		(end 373.222012 -276.708362)
		(width 0.088646)
		(layer "In11.Cu")
		(net "M_H_CPU0_SA_DQ<9>")
	)
	(segment
		(start 376.041666 -279.986232)
		(end 376.041666 -279.964134)
		(width 0.088646)
		(layer "In11.Cu")
		(net "M_H_CPU0_SA_DQ<9>")
	)
	(segment
		(start 385.261104 -282.900628)
		(end 385.252214 -282.895548)
		(width 0.088646)
		(layer "In11.Cu")
		(net "M_H_CPU0_SA_DQ<9>")
	)
	(segment
		(start 416.352228 -311.458356)
		(end 416.352228 -311.185814)
		(width 0.18288)
		(layer "In11.Cu")
		(net "M_H_CPU0_SA_DQ<9>")
	)
	(segment
		(start 442.426852 -311.916826)
		(end 440.99988 -313.343798)
		(width 0.18288)
		(layer "In11.Cu")
		(net "M_H_CPU0_SA_DQ<9>")
	)
	(segment
		(start 431.904902 -311.641744)
		(end 431.715926 -311.83072)
		(width 0.18288)
		(layer "In11.Cu")
		(net "M_H_CPU0_SA_DQ<9>")
	)
	(segment
		(start 400.628612 -301.112682)
		(end 392.006582 -292.490652)
		(width 0.18288)
		(layer "In11.Cu")
		(net "M_H_CPU0_SA_DQ<9>")
	)
	(segment
		(start 426.415962 -312.404252)
		(end 425.479972 -313.340242)
		(width 0.18288)
		(layer "In11.Cu")
		(net "M_H_CPU0_SA_DQ<9>")
	)
	(segment
		(start 386.192014 -284.52318)
		(end 386.188204 -284.520894)
		(width 0.088646)
		(layer "In11.Cu")
		(net "M_H_CPU0_SA_DQ<9>")
	)
	(segment
		(start 444.819786 -309.618634)
		(end 444.137034 -311.266586)
		(width 0.18288)
		(layer "In11.Cu")
		(net "M_H_CPU0_SA_DQ<9>")
	)
	(segment
		(start 381.588264 -280.453846)
		(end 381.573532 -280.462482)
		(width 0.088646)
		(layer "In11.Cu")
		(net "M_H_CPU0_SA_DQ<9>")
	)
	(segment
		(start 379.708664 -280.453846)
		(end 379.693932 -280.462482)
		(width 0.088646)
		(layer "In11.Cu")
		(net "M_H_CPU0_SA_DQ<9>")
	)
	(segment
		(start 416.84956 -311.956196)
		(end 416.480244 -312.325512)
		(width 0.18288)
		(layer "In11.Cu")
		(net "M_H_CPU0_SA_DQ<9>")
	)
	(segment
		(start 386.188204 -284.520894)
		(end 386.185918 -284.519624)
		(width 0.088646)
		(layer "In11.Cu")
		(net "M_H_CPU0_SA_DQ<9>")
	)
	(segment
		(start 416.480244 -312.325512)
		(end 416.207448 -312.325512)
		(width 0.18288)
		(layer "In11.Cu")
		(net "M_H_CPU0_SA_DQ<9>")
	)
	(segment
		(start 405.519636 -310.71058)
		(end 400.628612 -305.819556)
		(width 0.18288)
		(layer "In11.Cu")
		(net "M_H_CPU0_SA_DQ<9>")
	)
	(segment
		(start 383.559812 -281.601926)
		(end 383.559812 -281.59202)
		(width 0.088646)
		(layer "In11.Cu")
		(net "M_H_CPU0_SA_DQ<9>")
	)
	(segment
		(start 385.73075 -283.714444)
		(end 385.72186 -283.709364)
		(width 0.088646)
		(layer "In11.Cu")
		(net "M_H_CPU0_SA_DQ<9>")
	)
	(segment
		(start 444.137034 -311.266586)
		(end 443.486794 -311.916826)
		(width 0.18288)
		(layer "In11.Cu")
		(net "M_H_CPU0_SA_DQ<9>")
	)
	(segment
		(start 372.095268 -276.384258)
		(end 372.064788 -276.366986)
		(width 0.088646)
		(layer "In11.Cu")
		(net "M_H_CPU0_SA_DQ<9>")
	)
	(segment
		(start 373.034814 -277.033228)
		(end 373.034814 -277.032974)
		(width 0.088646)
		(layer "In11.Cu")
		(net "M_H_CPU0_SA_DQ<9>")
	)
	(segment
		(start 400.628612 -305.819556)
		(end 400.628612 -301.112682)
		(width 0.18288)
		(layer "In11.Cu")
		(net "M_H_CPU0_SA_DQ<9>")
	)
	(segment
		(start 385.439666 -283.2354)
		(end 385.439666 -283.219906)
		(width 0.088646)
		(layer "In11.Cu")
		(net "M_H_CPU0_SA_DQ<9>")
	)
	(segment
		(start 377.829064 -280.453846)
		(end 377.814332 -280.462482)
		(width 0.088646)
		(layer "In11.Cu")
		(net "M_H_CPU0_SA_DQ<9>")
	)
	(segment
		(start 438.593484 -312.491882)
		(end 437.618124 -312.491882)
		(width 0.18288)
		(layer "In11.Cu")
		(net "M_H_CPU0_SA_DQ<9>")
	)
	(segment
		(start 449.985892 -306.001928)
		(end 447.880994 -308.106826)
		(width 0.18288)
		(layer "In11.Cu")
		(net "M_H_CPU0_SA_DQ<9>")
	)
	(segment
		(start 373.222266 -278.351996)
		(end 373.222266 -278.336502)
		(width 0.088646)
		(layer "In11.Cu")
		(net "M_H_CPU0_SA_DQ<9>")
	)
	(segment
		(start 447.144394 -308.106826)
		(end 446.356994 -308.894226)
		(width 0.18288)
		(layer "In11.Cu")
		(net "M_H_CPU0_SA_DQ<9>")
	)
	(segment
		(start 419.355524 -314.18911)
		(end 417.12261 -311.956196)
		(width 0.18288)
		(layer "In11.Cu")
		(net "M_H_CPU0_SA_DQ<9>")
	)
	(segment
		(start 373.034814 -278.012398)
		(end 373.034814 -278.012144)
		(width 0.088646)
		(layer "In11.Cu")
		(net "M_H_CPU0_SA_DQ<9>")
	)
	(segment
		(start 384.969512 -282.42006)
		(end 384.969512 -282.405836)
		(width 0.088646)
		(layer "In11.Cu")
		(net "M_H_CPU0_SA_DQ<9>")
	)
	(segment
		(start 374.924574 -279.645872)
		(end 374.91416 -279.639776)
		(width 0.088646)
		(layer "In11.Cu")
		(net "M_H_CPU0_SA_DQ<9>")
	)
	(arc
		(start 382.90246 -280.453846)
		(mid 382.715262 -280.403703)
		(end 382.528064 -280.453846)
		(width 0.088646)
		(layer "In11.Cu")
		(net "M_H_CPU0_SA_DQ<9>")
	)
	(arc
		(start 383.559812 -281.59202)
		(mid 383.512133 -281.40912)
		(end 383.38125 -281.272742)
		(width 0.088646)
		(layer "In11.Cu")
		(net "M_H_CPU0_SA_DQ<9>")
	)
	(arc
		(start 376.874532 -280.462482)
		(mid 376.598091 -280.529648)
		(end 376.32386 -280.453846)
		(width 0.088646)
		(layer "In11.Cu")
		(net "M_H_CPU0_SA_DQ<9>")
	)
	(arc
		(start 376.041666 -279.964134)
		(mid 375.993987 -279.781234)
		(end 375.863104 -279.644856)
		(width 0.088646)
		(layer "In11.Cu")
		(net "M_H_CPU0_SA_DQ<9>")
	)
	(arc
		(start 383.84226 -282.081478)
		(mid 383.637925 -281.878873)
		(end 383.559812 -281.601926)
		(width 0.088646)
		(layer "In11.Cu")
		(net "M_H_CPU0_SA_DQ<9>")
	)
	(arc
		(start 377.814332 -280.462482)
		(mid 377.537891 -280.529648)
		(end 377.26366 -280.453846)
		(width 0.088646)
		(layer "In11.Cu")
		(net "M_H_CPU0_SA_DQ<9>")
	)
	(arc
		(start 386.185918 -284.519624)
		(mid 385.983331 -284.313273)
		(end 385.909312 -284.033722)
		(width 0.088646)
		(layer "In11.Cu")
		(net "M_H_CPU0_SA_DQ<9>")
	)
	(arc
		(start 372.660418 -276.384258)
		(mid 372.37786 -276.459907)
		(end 372.095268 -276.384258)
		(width 0.088646)
		(layer "In11.Cu")
		(net "M_H_CPU0_SA_DQ<9>")
	)
	(arc
		(start 384.407664 -282.081478)
		(mid 384.124962 -282.157254)
		(end 383.84226 -282.081478)
		(width 0.088646)
		(layer "In11.Cu")
		(net "M_H_CPU0_SA_DQ<9>")
	)
	(arc
		(start 375.854214 -279.639776)
		(mid 375.667016 -279.589633)
		(end 375.479818 -279.639776)
		(width 0.088646)
		(layer "In11.Cu")
		(net "M_H_CPU0_SA_DQ<9>")
	)
	(arc
		(start 384.969512 -282.405836)
		(mid 384.921833 -282.222936)
		(end 384.79095 -282.086558)
		(width 0.088646)
		(layer "In11.Cu")
		(net "M_H_CPU0_SA_DQ<9>")
	)
	(arc
		(start 386.379212 -284.838902)
		(mid 386.326942 -284.656537)
		(end 386.192014 -284.52318)
		(width 0.088646)
		(layer "In11.Cu")
		(net "M_H_CPU0_SA_DQ<9>")
	)
	(arc
		(start 386.66166 -285.336996)
		(mid 386.458662 -285.136827)
		(end 386.379212 -284.863032)
		(width 0.088646)
		(layer "In11.Cu")
		(net "M_H_CPU0_SA_DQ<9>")
	)
	(arc
		(start 385.252214 -282.895548)
		(mid 385.048733 -282.694744)
		(end 384.969512 -282.42006)
		(width 0.088646)
		(layer "In11.Cu")
		(net "M_H_CPU0_SA_DQ<9>")
	)
	(arc
		(start 382.513332 -280.462482)
		(mid 382.236891 -280.529648)
		(end 381.96266 -280.453846)
		(width 0.088646)
		(layer "In11.Cu")
		(net "M_H_CPU0_SA_DQ<9>")
	)
	(arc
		(start 373.034814 -276.384258)
		(mid 372.847616 -276.334115)
		(end 372.660418 -276.384258)
		(width 0.088646)
		(layer "In11.Cu")
		(net "M_H_CPU0_SA_DQ<9>")
	)
	(arc
		(start 381.96266 -280.453846)
		(mid 381.775462 -280.403703)
		(end 381.588264 -280.453846)
		(width 0.088646)
		(layer "In11.Cu")
		(net "M_H_CPU0_SA_DQ<9>")
	)
	(arc
		(start 374.539764 -279.639776)
		(mid 374.263205 -279.715519)
		(end 373.985028 -279.645872)
		(width 0.088646)
		(layer "In11.Cu")
		(net "M_H_CPU0_SA_DQ<9>")
	)
	(arc
		(start 373.222012 -276.708362)
		(mid 373.171848 -276.521224)
		(end 373.034814 -276.384258)
		(width 0.088646)
		(layer "In11.Cu")
		(net "M_H_CPU0_SA_DQ<9>")
	)
	(arc
		(start 381.02286 -280.453846)
		(mid 380.835662 -280.403703)
		(end 380.648464 -280.453846)
		(width 0.088646)
		(layer "In11.Cu")
		(net "M_H_CPU0_SA_DQ<9>")
	)
	(arc
		(start 373.034814 -278.012144)
		(mid 372.827826 -277.805172)
		(end 372.752112 -277.522432)
		(width 0.088646)
		(layer "In11.Cu")
		(net "M_H_CPU0_SA_DQ<9>")
	)
	(arc
		(start 380.648464 -280.453846)
		(mid 380.365762 -280.529588)
		(end 380.08306 -280.453846)
		(width 0.088646)
		(layer "In11.Cu")
		(net "M_H_CPU0_SA_DQ<9>")
	)
	(arc
		(start 373.50446 -278.82596)
		(mid 373.301637 -278.625729)
		(end 373.222266 -278.351996)
		(width 0.088646)
		(layer "In11.Cu")
		(net "M_H_CPU0_SA_DQ<9>")
	)
	(arc
		(start 375.479818 -279.639776)
		(mid 375.203005 -279.715646)
		(end 374.924574 -279.645872)
		(width 0.088646)
		(layer "In11.Cu")
		(net "M_H_CPU0_SA_DQ<9>")
	)
	(arc
		(start 380.08306 -280.453846)
		(mid 379.895862 -280.403703)
		(end 379.708664 -280.453846)
		(width 0.088646)
		(layer "In11.Cu")
		(net "M_H_CPU0_SA_DQ<9>")
	)
	(arc
		(start 383.089912 -280.778204)
		(mid 383.042233 -280.595304)
		(end 382.91135 -280.458926)
		(width 0.088646)
		(layer "In11.Cu")
		(net "M_H_CPU0_SA_DQ<9>")
	)
	(arc
		(start 385.439666 -283.219906)
		(mid 385.391987 -283.037006)
		(end 385.261104 -282.900628)
		(width 0.088646)
		(layer "In11.Cu")
		(net "M_H_CPU0_SA_DQ<9>")
	)
	(arc
		(start 386.739384 -285.396432)
		(mid 386.702474 -285.364161)
		(end 386.66166 -285.336996)
		(width 0.088646)
		(layer "In11.Cu")
		(net "M_H_CPU0_SA_DQ<9>")
	)
	(arc
		(start 381.573532 -280.462482)
		(mid 381.297091 -280.529648)
		(end 381.02286 -280.453846)
		(width 0.088646)
		(layer "In11.Cu")
		(net "M_H_CPU0_SA_DQ<9>")
	)
	(arc
		(start 376.32386 -280.453846)
		(mid 376.122578 -280.256359)
		(end 376.041666 -279.986232)
		(width 0.088646)
		(layer "In11.Cu")
		(net "M_H_CPU0_SA_DQ<9>")
	)
	(arc
		(start 373.222266 -278.336502)
		(mid 373.171973 -278.149326)
		(end 373.034814 -278.012398)
		(width 0.088646)
		(layer "In11.Cu")
		(net "M_H_CPU0_SA_DQ<9>")
	)
	(arc
		(start 378.20346 -280.453846)
		(mid 378.016262 -280.403703)
		(end 377.829064 -280.453846)
		(width 0.088646)
		(layer "In11.Cu")
		(net "M_H_CPU0_SA_DQ<9>")
	)
	(arc
		(start 378.754132 -280.462482)
		(mid 378.477691 -280.529648)
		(end 378.20346 -280.453846)
		(width 0.088646)
		(layer "In11.Cu")
		(net "M_H_CPU0_SA_DQ<9>")
	)
	(arc
		(start 373.968518 -279.63622)
		(mid 373.765931 -279.429869)
		(end 373.691912 -279.150318)
		(width 0.088646)
		(layer "In11.Cu")
		(net "M_H_CPU0_SA_DQ<9>")
	)
	(arc
		(start 377.26366 -280.453846)
		(mid 377.076462 -280.403703)
		(end 376.889264 -280.453846)
		(width 0.088646)
		(layer "In11.Cu")
		(net "M_H_CPU0_SA_DQ<9>")
	)
	(arc
		(start 372.752112 -277.522432)
		(mid 372.827922 -277.239948)
		(end 373.034814 -277.033228)
		(width 0.088646)
		(layer "In11.Cu")
		(net "M_H_CPU0_SA_DQ<9>")
	)
	(arc
		(start 373.691912 -279.150318)
		(mid 373.644233 -278.967418)
		(end 373.51335 -278.83104)
		(width 0.088646)
		(layer "In11.Cu")
		(net "M_H_CPU0_SA_DQ<9>")
	)
	(arc
		(start 385.909312 -284.033722)
		(mid 385.861633 -283.850822)
		(end 385.73075 -283.714444)
		(width 0.088646)
		(layer "In11.Cu")
		(net "M_H_CPU0_SA_DQ<9>")
	)
	(arc
		(start 383.37236 -281.267662)
		(mid 383.168025 -281.065057)
		(end 383.089912 -280.78811)
		(width 0.088646)
		(layer "In11.Cu")
		(net "M_H_CPU0_SA_DQ<9>")
	)
	(arc
		(start 374.91416 -279.639776)
		(mid 374.726962 -279.589633)
		(end 374.539764 -279.639776)
		(width 0.088646)
		(layer "In11.Cu")
		(net "M_H_CPU0_SA_DQ<9>")
	)
	(arc
		(start 379.14326 -280.453846)
		(mid 378.956062 -280.403703)
		(end 378.768864 -280.453846)
		(width 0.088646)
		(layer "In11.Cu")
		(net "M_H_CPU0_SA_DQ<9>")
	)
	(arc
		(start 385.72186 -283.709364)
		(mid 385.519037 -283.509133)
		(end 385.439666 -283.2354)
		(width 0.088646)
		(layer "In11.Cu")
		(net "M_H_CPU0_SA_DQ<9>")
	)
	(arc
		(start 379.693932 -280.462482)
		(mid 379.417491 -280.529648)
		(end 379.14326 -280.453846)
		(width 0.088646)
		(layer "In11.Cu")
		(net "M_H_CPU0_SA_DQ<9>")
	)
	(arc
		(start 384.78206 -282.081478)
		(mid 384.594862 -282.031335)
		(end 384.407664 -282.081478)
		(width 0.088646)
		(layer "In11.Cu")
		(net "M_H_CPU0_SA_DQ<9>")
	)
	(arc
		(start 373.034814 -277.032974)
		(mid 373.171839 -276.895861)
		(end 373.222012 -276.708616)
		(width 0.088646)
		(layer "In11.Cu")
		(net "M_H_CPU0_SA_DQ<9>")
	)
	(segment
		(start 454.448672 -307.027326)
		(end 454.260712 -307.215286)
		(width 0.20066)
		(layer "F.Cu")
		(net "M_H_CPU0_SA_DQ<8>")
	)
	(segment
		(start 453.536812 -306.96662)
		(end 452.016114 -306.96662)
		(width 0.20066)
		(layer "F.Cu")
		(net "M_H_CPU0_SA_DQ<8>")
	)
	(segment
		(start 457.126594 -306.535328)
		(end 457.120244 -306.541678)
		(width 0.1016)
		(layer "F.Cu")
		(net "M_H_CPU0_SA_DQ<8>")
	)
	(segment
		(start 454.448672 -306.659788)
		(end 454.448672 -307.027326)
		(width 0.20066)
		(layer "F.Cu")
		(net "M_H_CPU0_SA_DQ<8>")
	)
	(segment
		(start 459.559914 -306.96662)
		(end 459.55966 -306.966874)
		(width 0.20066)
		(layer "F.Cu")
		(net "M_H_CPU0_SA_DQ<8>")
	)
	(segment
		(start 457.53655 -306.535328)
		(end 457.126594 -306.535328)
		(width 0.20066)
		(layer "F.Cu")
		(net "M_H_CPU0_SA_DQ<8>")
	)
	(segment
		(start 453.785478 -307.215286)
		(end 453.536812 -306.96662)
		(width 0.20066)
		(layer "F.Cu")
		(net "M_H_CPU0_SA_DQ<8>")
	)
	(segment
		(start 459.55966 -306.966874)
		(end 457.968096 -306.966874)
		(width 0.20066)
		(layer "F.Cu")
		(net "M_H_CPU0_SA_DQ<8>")
	)
	(segment
		(start 454.566782 -306.541678)
		(end 454.448672 -306.659788)
		(width 0.20066)
		(layer "F.Cu")
		(net "M_H_CPU0_SA_DQ<8>")
	)
	(segment
		(start 454.91146 -306.541678)
		(end 454.566782 -306.541678)
		(width 0.20066)
		(layer "F.Cu")
		(net "M_H_CPU0_SA_DQ<8>")
	)
	(segment
		(start 457.968096 -306.966874)
		(end 457.53655 -306.535328)
		(width 0.20066)
		(layer "F.Cu")
		(net "M_H_CPU0_SA_DQ<8>")
	)
	(segment
		(start 454.95845 -306.541678)
		(end 454.91146 -306.541678)
		(width 0.101854)
		(layer "F.Cu")
		(net "M_H_CPU0_SA_DQ<8>")
	)
	(segment
		(start 457.120244 -306.541678)
		(end 454.95845 -306.541678)
		(width 0.1016)
		(layer "F.Cu")
		(net "M_H_CPU0_SA_DQ<8>")
	)
	(segment
		(start 454.260712 -307.215286)
		(end 453.785478 -307.215286)
		(width 0.20066)
		(layer "F.Cu")
		(net "M_H_CPU0_SA_DQ<8>")
	)
	(segment
		(start 452.016114 -306.96662)
		(end 450.911214 -306.96662)
		(width 0.20066)
		(layer "F.Cu")
		(net "M_H_CPU0_SA_DQ<8>")
	)
	(segment
		(start 371.907562 -276.172676)
		(end 371.907816 -276.708616)
		(width 0.20066)
		(layer "F.Cu")
		(net "M_H_CPU0_SA_DQ<8>")
	)
	(segment
		(start 433.11191 -313.331606)
		(end 432.985926 -313.45759)
		(width 0.18288)
		(layer "In11.Cu")
		(net "M_H_CPU0_SA_DQ<8>")
	)
	(segment
		(start 435.00421 -314.188348)
		(end 434.147468 -313.331606)
		(width 0.18288)
		(layer "In11.Cu")
		(net "M_H_CPU0_SA_DQ<8>")
	)
	(segment
		(start 419.609524 -315.88964)
		(end 418.34054 -315.364114)
		(width 0.18288)
		(layer "In11.Cu")
		(net "M_H_CPU0_SA_DQ<8>")
	)
	(segment
		(start 372.088918 -277.03653)
		(end 372.095014 -277.032974)
		(width 0.088646)
		(layer "In11.Cu")
		(net "M_H_CPU0_SA_DQ<8>")
	)
	(segment
		(start 372.282466 -278.351996)
		(end 372.282466 -278.336502)
		(width 0.088646)
		(layer "In11.Cu")
		(net "M_H_CPU0_SA_DQ<8>")
	)
	(segment
		(start 431.637186 -313.331606)
		(end 430.272444 -313.331606)
		(width 0.18288)
		(layer "In11.Cu")
		(net "M_H_CPU0_SA_DQ<8>")
	)
	(segment
		(start 423.89552 -315.043058)
		(end 423.76979 -314.917328)
		(width 0.18288)
		(layer "In11.Cu")
		(net "M_H_CPU0_SA_DQ<8>")
	)
	(segment
		(start 374.070118 -280.453846)
		(end 374.059704 -280.459942)
		(width 0.088646)
		(layer "In11.Cu")
		(net "M_H_CPU0_SA_DQ<8>")
	)
	(segment
		(start 440.48553 -315.214508)
		(end 440.312302 -315.04128)
		(width 0.18288)
		(layer "In11.Cu")
		(net "M_H_CPU0_SA_DQ<8>")
	)
	(segment
		(start 418.34054 -315.364114)
		(end 416.78987 -315.364114)
		(width 0.18288)
		(layer "In11.Cu")
		(net "M_H_CPU0_SA_DQ<8>")
	)
	(segment
		(start 384.32105 -282.900628)
		(end 384.31216 -282.895548)
		(width 0.088646)
		(layer "In11.Cu")
		(net "M_H_CPU0_SA_DQ<8>")
	)
	(segment
		(start 450.481954 -307.64226)
		(end 450.319394 -308.034436)
		(width 0.18288)
		(layer "In11.Cu")
		(net "M_H_CPU0_SA_DQ<8>")
	)
	(segment
		(start 399.612612 -301.534322)
		(end 390.828784 -292.750494)
		(width 0.18288)
		(layer "In11.Cu")
		(net "M_H_CPU0_SA_DQ<8>")
	)
	(segment
		(start 450.911214 -306.96662)
		(end 450.911214 -307.124608)
		(width 0.18288)
		(layer "In11.Cu")
		(net "M_H_CPU0_SA_DQ<8>")
	)
	(segment
		(start 384.79095 -283.714444)
		(end 384.78206 -283.709364)
		(width 0.088646)
		(layer "In11.Cu")
		(net "M_H_CPU0_SA_DQ<8>")
	)
	(segment
		(start 373.03202 -279.638252)
		(end 373.028718 -279.63622)
		(width 0.088646)
		(layer "In11.Cu")
		(net "M_H_CPU0_SA_DQ<8>")
	)
	(segment
		(start 432.985926 -313.45759)
		(end 431.76317 -313.45759)
		(width 0.18288)
		(layer "In11.Cu")
		(net "M_H_CPU0_SA_DQ<8>")
	)
	(segment
		(start 416.78987 -315.364114)
		(end 415.891726 -314.46597)
		(width 0.18288)
		(layer "In11.Cu")
		(net "M_H_CPU0_SA_DQ<8>")
	)
	(segment
		(start 450.11467 -308.837838)
		(end 445.765682 -313.186826)
		(width 0.18288)
		(layer "In11.Cu")
		(net "M_H_CPU0_SA_DQ<8>")
	)
	(segment
		(start 450.319394 -308.034436)
		(end 450.319394 -308.343808)
		(width 0.18288)
		(layer "In11.Cu")
		(net "M_H_CPU0_SA_DQ<8>")
	)
	(segment
		(start 438.465468 -315.04128)
		(end 437.612536 -314.188348)
		(width 0.18288)
		(layer "In11.Cu")
		(net "M_H_CPU0_SA_DQ<8>")
	)
	(segment
		(start 415.891726 -314.46597)
		(end 414.583372 -314.46597)
		(width 0.18288)
		(layer "In11.Cu")
		(net "M_H_CPU0_SA_DQ<8>")
	)
	(segment
		(start 382.620012 -281.59202)
		(end 382.620012 -281.583384)
		(width 0.088646)
		(layer "In11.Cu")
		(net "M_H_CPU0_SA_DQ<8>")
	)
	(segment
		(start 381.507746 -281.276298)
		(end 381.493014 -281.267662)
		(width 0.088646)
		(layer "In11.Cu")
		(net "M_H_CPU0_SA_DQ<8>")
	)
	(segment
		(start 411.714696 -313.34329)
		(end 411.521656 -313.53633)
		(width 0.18288)
		(layer "In11.Cu")
		(net "M_H_CPU0_SA_DQ<8>")
	)
	(segment
		(start 374.454928 -280.459942)
		(end 374.444514 -280.453846)
		(width 0.088646)
		(layer "In11.Cu")
		(net "M_H_CPU0_SA_DQ<8>")
	)
	(segment
		(start 372.095014 -277.032974)
		(end 372.103904 -277.027894)
		(width 0.088646)
		(layer "In11.Cu")
		(net "M_H_CPU0_SA_DQ<8>")
	)
	(segment
		(start 372.103904 -278.017224)
		(end 372.095014 -278.012144)
		(width 0.088646)
		(layer "In11.Cu")
		(net "M_H_CPU0_SA_DQ<8>")
	)
	(segment
		(start 450.911214 -307.124608)
		(end 450.84873 -307.275484)
		(width 0.18288)
		(layer "In11.Cu")
		(net "M_H_CPU0_SA_DQ<8>")
	)
	(segment
		(start 406.231344 -313.122056)
		(end 399.612612 -306.503324)
		(width 0.18288)
		(layer "In11.Cu")
		(net "M_H_CPU0_SA_DQ<8>")
	)
	(segment
		(start 421.704008 -315.88964)
		(end 419.609524 -315.88964)
		(width 0.18288)
		(layer "In11.Cu")
		(net "M_H_CPU0_SA_DQ<8>")
	)
	(segment
		(start 450.84873 -307.275484)
		(end 450.481954 -307.64226)
		(width 0.18288)
		(layer "In11.Cu")
		(net "M_H_CPU0_SA_DQ<8>")
	)
	(segment
		(start 373.034814 -279.639776)
		(end 373.03202 -279.638252)
		(width 0.088646)
		(layer "In11.Cu")
		(net "M_H_CPU0_SA_DQ<8>")
	)
	(segment
		(start 412.583884 -313.34329)
		(end 411.714696 -313.34329)
		(width 0.18288)
		(layer "In11.Cu")
		(net "M_H_CPU0_SA_DQ<8>")
	)
	(segment
		(start 385.909312 -285.675578)
		(end 385.909312 -285.661354)
		(width 0.088646)
		(layer "In11.Cu")
		(net "M_H_CPU0_SA_DQ<8>")
	)
	(segment
		(start 423.76979 -314.917328)
		(end 422.67632 -314.917328)
		(width 0.18288)
		(layer "In11.Cu")
		(net "M_H_CPU0_SA_DQ<8>")
	)
	(segment
		(start 383.089912 -282.424378)
		(end 383.089912 -282.3972)
		(width 0.088646)
		(layer "In11.Cu")
		(net "M_H_CPU0_SA_DQ<8>")
	)
	(segment
		(start 437.612536 -314.188348)
		(end 435.00421 -314.188348)
		(width 0.18288)
		(layer "In11.Cu")
		(net "M_H_CPU0_SA_DQ<8>")
	)
	(segment
		(start 427.662086 -314.291218)
		(end 427.319694 -313.948826)
		(width 0.18288)
		(layer "In11.Cu")
		(net "M_H_CPU0_SA_DQ<8>")
	)
	(segment
		(start 384.78206 -283.709364)
		(end 384.775964 -283.705808)
		(width 0.088646)
		(layer "In11.Cu")
		(net "M_H_CPU0_SA_DQ<8>")
	)
	(segment
		(start 386.40639 -286.893)
		(end 386.40639 -286.346646)
		(width 0.088646)
		(layer "In11.Cu")
		(net "M_H_CPU0_SA_DQ<8>")
	)
	(segment
		(start 444.909194 -313.186826)
		(end 442.881512 -315.214508)
		(width 0.18288)
		(layer "In11.Cu")
		(net "M_H_CPU0_SA_DQ<8>")
	)
	(segment
		(start 385.261104 -284.52826)
		(end 385.252214 -284.52318)
		(width 0.088646)
		(layer "In11.Cu")
		(net "M_H_CPU0_SA_DQ<8>")
	)
	(segment
		(start 376.808746 -281.276298)
		(end 376.794014 -281.267662)
		(width 0.088646)
		(layer "In11.Cu")
		(net "M_H_CPU0_SA_DQ<8>")
	)
	(segment
		(start 372.220744 -276.708616)
		(end 371.907816 -276.708616)
		(width 0.088646)
		(layer "In11.Cu")
		(net "M_H_CPU0_SA_DQ<8>")
	)
	(segment
		(start 408.726386 -313.34329)
		(end 408.505152 -313.122056)
		(width 0.18288)
		(layer "In11.Cu")
		(net "M_H_CPU0_SA_DQ<8>")
	)
	(segment
		(start 413.198564 -313.081162)
		(end 412.846012 -313.081162)
		(width 0.18288)
		(layer "In11.Cu")
		(net "M_H_CPU0_SA_DQ<8>")
	)
	(segment
		(start 386.409184 -286.895794)
		(end 386.40639 -286.893)
		(width 0.088646)
		(layer "In11.Cu")
		(net "M_H_CPU0_SA_DQ<8>")
	)
	(segment
		(start 377.748546 -281.276298)
		(end 377.733814 -281.267662)
		(width 0.088646)
		(layer "In11.Cu")
		(net "M_H_CPU0_SA_DQ<8>")
	)
	(segment
		(start 425.742862 -315.043058)
		(end 423.89552 -315.043058)
		(width 0.18288)
		(layer "In11.Cu")
		(net "M_H_CPU0_SA_DQ<8>")
	)
	(segment
		(start 426.837094 -313.948826)
		(end 425.742862 -315.043058)
		(width 0.18288)
		(layer "In11.Cu")
		(net "M_H_CPU0_SA_DQ<8>")
	)
	(segment
		(start 442.881512 -315.214508)
		(end 440.48553 -315.214508)
		(width 0.18288)
		(layer "In11.Cu")
		(net "M_H_CPU0_SA_DQ<8>")
	)
	(segment
		(start 411.521656 -313.53633)
		(end 411.521656 -314.168028)
		(width 0.18288)
		(layer "In11.Cu")
		(net "M_H_CPU0_SA_DQ<8>")
	)
	(segment
		(start 410.818076 -313.53633)
		(end 410.625036 -313.34329)
		(width 0.18288)
		(layer "In11.Cu")
		(net "M_H_CPU0_SA_DQ<8>")
	)
	(segment
		(start 373.222266 -279.986232)
		(end 373.222266 -279.964134)
		(width 0.088646)
		(layer "In11.Cu")
		(net "M_H_CPU0_SA_DQ<8>")
	)
	(segment
		(start 390.828784 -291.842444)
		(end 386.409184 -287.422844)
		(width 0.18288)
		(layer "In11.Cu")
		(net "M_H_CPU0_SA_DQ<8>")
	)
	(segment
		(start 422.67632 -314.917328)
		(end 421.704008 -315.88964)
		(width 0.18288)
		(layer "In11.Cu")
		(net "M_H_CPU0_SA_DQ<8>")
	)
	(segment
		(start 378.688346 -281.276298)
		(end 378.673614 -281.267662)
		(width 0.088646)
		(layer "In11.Cu")
		(net "M_H_CPU0_SA_DQ<8>")
	)
	(segment
		(start 408.505152 -313.122056)
		(end 406.231344 -313.122056)
		(width 0.18288)
		(layer "In11.Cu")
		(net "M_H_CPU0_SA_DQ<8>")
	)
	(segment
		(start 440.312302 -315.04128)
		(end 438.465468 -315.04128)
		(width 0.18288)
		(layer "In11.Cu")
		(net "M_H_CPU0_SA_DQ<8>")
	)
	(segment
		(start 411.521656 -314.168028)
		(end 411.328616 -314.361068)
		(width 0.18288)
		(layer "In11.Cu")
		(net "M_H_CPU0_SA_DQ<8>")
	)
	(segment
		(start 382.902714 -282.081478)
		(end 382.896618 -282.077922)
		(width 0.088646)
		(layer "In11.Cu")
		(net "M_H_CPU0_SA_DQ<8>")
	)
	(segment
		(start 399.612612 -306.503324)
		(end 399.612612 -301.534322)
		(width 0.18288)
		(layer "In11.Cu")
		(net "M_H_CPU0_SA_DQ<8>")
	)
	(segment
		(start 385.252214 -284.52318)
		(end 385.246118 -284.519624)
		(width 0.088646)
		(layer "In11.Cu")
		(net "M_H_CPU0_SA_DQ<8>")
	)
	(segment
		(start 385.439666 -284.863032)
		(end 385.439666 -284.847538)
		(width 0.088646)
		(layer "In11.Cu")
		(net "M_H_CPU0_SA_DQ<8>")
	)
	(segment
		(start 412.846012 -313.081162)
		(end 412.583884 -313.34329)
		(width 0.18288)
		(layer "In11.Cu")
		(net "M_H_CPU0_SA_DQ<8>")
	)
	(segment
		(start 411.011116 -314.361068)
		(end 410.818076 -314.168028)
		(width 0.18288)
		(layer "In11.Cu")
		(net "M_H_CPU0_SA_DQ<8>")
	)
	(segment
		(start 371.812312 -277.536656)
		(end 371.812312 -277.522432)
		(width 0.088646)
		(layer "In11.Cu")
		(net "M_H_CPU0_SA_DQ<8>")
	)
	(segment
		(start 429.312832 -314.291218)
		(end 427.662086 -314.291218)
		(width 0.18288)
		(layer "In11.Cu")
		(net "M_H_CPU0_SA_DQ<8>")
	)
	(segment
		(start 450.319394 -308.343808)
		(end 450.11467 -308.837838)
		(width 0.18288)
		(layer "In11.Cu")
		(net "M_H_CPU0_SA_DQ<8>")
	)
	(segment
		(start 375.854214 -281.267662)
		(end 375.848118 -281.264106)
		(width 0.088646)
		(layer "In11.Cu")
		(net "M_H_CPU0_SA_DQ<8>")
	)
	(segment
		(start 445.765682 -313.186826)
		(end 444.909194 -313.186826)
		(width 0.18288)
		(layer "In11.Cu")
		(net "M_H_CPU0_SA_DQ<8>")
	)
	(segment
		(start 386.40639 -286.346646)
		(end 386.269992 -286.210248)
		(width 0.088646)
		(layer "In11.Cu")
		(net "M_H_CPU0_SA_DQ<8>")
	)
	(segment
		(start 430.272444 -313.331606)
		(end 429.312832 -314.291218)
		(width 0.18288)
		(layer "In11.Cu")
		(net "M_H_CPU0_SA_DQ<8>")
	)
	(segment
		(start 375.868946 -281.276298)
		(end 375.854214 -281.267662)
		(width 0.088646)
		(layer "In11.Cu")
		(net "M_H_CPU0_SA_DQ<8>")
	)
	(segment
		(start 390.828784 -292.750494)
		(end 390.828784 -291.842444)
		(width 0.18288)
		(layer "In11.Cu")
		(net "M_H_CPU0_SA_DQ<8>")
	)
	(segment
		(start 372.57355 -278.83104)
		(end 372.56466 -278.82596)
		(width 0.088646)
		(layer "In11.Cu")
		(net "M_H_CPU0_SA_DQ<8>")
	)
	(segment
		(start 385.73075 -285.342076)
		(end 385.72186 -285.336996)
		(width 0.088646)
		(layer "In11.Cu")
		(net "M_H_CPU0_SA_DQ<8>")
	)
	(segment
		(start 380.567946 -281.276298)
		(end 380.553214 -281.267662)
		(width 0.088646)
		(layer "In11.Cu")
		(net "M_H_CPU0_SA_DQ<8>")
	)
	(segment
		(start 414.583372 -314.46597)
		(end 413.198564 -313.081162)
		(width 0.18288)
		(layer "In11.Cu")
		(net "M_H_CPU0_SA_DQ<8>")
	)
	(segment
		(start 375.39295 -280.458926)
		(end 375.38406 -280.453846)
		(width 0.088646)
		(layer "In11.Cu")
		(net "M_H_CPU0_SA_DQ<8>")
	)
	(segment
		(start 379.628146 -281.276298)
		(end 379.613414 -281.267662)
		(width 0.088646)
		(layer "In11.Cu")
		(net "M_H_CPU0_SA_DQ<8>")
	)
	(segment
		(start 427.319694 -313.948826)
		(end 426.837094 -313.948826)
		(width 0.18288)
		(layer "In11.Cu")
		(net "M_H_CPU0_SA_DQ<8>")
	)
	(segment
		(start 410.625036 -313.34329)
		(end 408.726386 -313.34329)
		(width 0.18288)
		(layer "In11.Cu")
		(net "M_H_CPU0_SA_DQ<8>")
	)
	(segment
		(start 431.76317 -313.45759)
		(end 431.637186 -313.331606)
		(width 0.18288)
		(layer "In11.Cu")
		(net "M_H_CPU0_SA_DQ<8>")
	)
	(segment
		(start 373.043704 -279.644856)
		(end 373.034814 -279.639776)
		(width 0.088646)
		(layer "In11.Cu")
		(net "M_H_CPU0_SA_DQ<8>")
	)
	(segment
		(start 410.818076 -314.168028)
		(end 410.818076 -313.53633)
		(width 0.18288)
		(layer "In11.Cu")
		(net "M_H_CPU0_SA_DQ<8>")
	)
	(segment
		(start 411.328616 -314.361068)
		(end 411.011116 -314.361068)
		(width 0.18288)
		(layer "In11.Cu")
		(net "M_H_CPU0_SA_DQ<8>")
	)
	(segment
		(start 434.147468 -313.331606)
		(end 433.11191 -313.331606)
		(width 0.18288)
		(layer "In11.Cu")
		(net "M_H_CPU0_SA_DQ<8>")
	)
	(segment
		(start 372.277894 -276.765766)
		(end 372.220744 -276.708616)
		(width 0.088646)
		(layer "In11.Cu")
		(net "M_H_CPU0_SA_DQ<8>")
	)
	(segment
		(start 386.409184 -287.422844)
		(end 386.409184 -286.895794)
		(width 0.18288)
		(layer "In11.Cu")
		(net "M_H_CPU0_SA_DQ<8>")
	)
	(arc
		(start 377.359418 -281.267662)
		(mid 377.085219 -281.343497)
		(end 376.808746 -281.276298)
		(width 0.088646)
		(layer "In11.Cu")
		(net "M_H_CPU0_SA_DQ<8>")
	)
	(arc
		(start 383.089912 -282.3972)
		(mid 383.037642 -282.214835)
		(end 382.902714 -282.081478)
		(width 0.088646)
		(layer "In11.Cu")
		(net "M_H_CPU0_SA_DQ<8>")
	)
	(arc
		(start 384.31216 -282.895548)
		(mid 384.124962 -282.845405)
		(end 383.937764 -282.895548)
		(width 0.088646)
		(layer "In11.Cu")
		(net "M_H_CPU0_SA_DQ<8>")
	)
	(arc
		(start 386.192014 -286.151066)
		(mid 385.988533 -285.950262)
		(end 385.909312 -285.675578)
		(width 0.088646)
		(layer "In11.Cu")
		(net "M_H_CPU0_SA_DQ<8>")
	)
	(arc
		(start 379.613414 -281.267662)
		(mid 379.426216 -281.217519)
		(end 379.239018 -281.267662)
		(width 0.088646)
		(layer "In11.Cu")
		(net "M_H_CPU0_SA_DQ<8>")
	)
	(arc
		(start 381.493014 -281.267662)
		(mid 381.305816 -281.217519)
		(end 381.118618 -281.267662)
		(width 0.088646)
		(layer "In11.Cu")
		(net "M_H_CPU0_SA_DQ<8>")
	)
	(arc
		(start 372.752112 -279.150318)
		(mid 372.704433 -278.967418)
		(end 372.57355 -278.83104)
		(width 0.088646)
		(layer "In11.Cu")
		(net "M_H_CPU0_SA_DQ<8>")
	)
	(arc
		(start 382.896618 -282.077922)
		(mid 382.694031 -281.871571)
		(end 382.620012 -281.59202)
		(width 0.088646)
		(layer "In11.Cu")
		(net "M_H_CPU0_SA_DQ<8>")
	)
	(arc
		(start 380.553214 -281.267662)
		(mid 380.366016 -281.217519)
		(end 380.178818 -281.267662)
		(width 0.088646)
		(layer "In11.Cu")
		(net "M_H_CPU0_SA_DQ<8>")
	)
	(arc
		(start 376.794014 -281.267662)
		(mid 376.606816 -281.217519)
		(end 376.419618 -281.267662)
		(width 0.088646)
		(layer "In11.Cu")
		(net "M_H_CPU0_SA_DQ<8>")
	)
	(arc
		(start 371.812312 -277.522432)
		(mid 371.886303 -277.242866)
		(end 372.088918 -277.03653)
		(width 0.088646)
		(layer "In11.Cu")
		(net "M_H_CPU0_SA_DQ<8>")
	)
	(arc
		(start 383.937764 -282.895548)
		(mid 383.655062 -282.97129)
		(end 383.37236 -282.895548)
		(width 0.088646)
		(layer "In11.Cu")
		(net "M_H_CPU0_SA_DQ<8>")
	)
	(arc
		(start 376.419618 -281.267662)
		(mid 376.145419 -281.343497)
		(end 375.868946 -281.276298)
		(width 0.088646)
		(layer "In11.Cu")
		(net "M_H_CPU0_SA_DQ<8>")
	)
	(arc
		(start 382.620012 -281.583384)
		(mid 382.567742 -281.401019)
		(end 382.432814 -281.267662)
		(width 0.088646)
		(layer "In11.Cu")
		(net "M_H_CPU0_SA_DQ<8>")
	)
	(arc
		(start 385.439666 -284.847538)
		(mid 385.391987 -284.664638)
		(end 385.261104 -284.52826)
		(width 0.088646)
		(layer "In11.Cu")
		(net "M_H_CPU0_SA_DQ<8>")
	)
	(arc
		(start 377.733814 -281.267662)
		(mid 377.546616 -281.217519)
		(end 377.359418 -281.267662)
		(width 0.088646)
		(layer "In11.Cu")
		(net "M_H_CPU0_SA_DQ<8>")
	)
	(arc
		(start 375.38406 -280.453846)
		(mid 375.196862 -280.403703)
		(end 375.009664 -280.453846)
		(width 0.088646)
		(layer "In11.Cu")
		(net "M_H_CPU0_SA_DQ<8>")
	)
	(arc
		(start 380.178818 -281.267662)
		(mid 379.904619 -281.343497)
		(end 379.628146 -281.276298)
		(width 0.088646)
		(layer "In11.Cu")
		(net "M_H_CPU0_SA_DQ<8>")
	)
	(arc
		(start 385.909312 -285.661354)
		(mid 385.861633 -285.478454)
		(end 385.73075 -285.342076)
		(width 0.088646)
		(layer "In11.Cu")
		(net "M_H_CPU0_SA_DQ<8>")
	)
	(arc
		(start 372.095014 -278.012144)
		(mid 371.891533 -277.81134)
		(end 371.812312 -277.536656)
		(width 0.088646)
		(layer "In11.Cu")
		(net "M_H_CPU0_SA_DQ<8>")
	)
	(arc
		(start 375.848118 -281.264106)
		(mid 375.645531 -281.057755)
		(end 375.571512 -280.778204)
		(width 0.088646)
		(layer "In11.Cu")
		(net "M_H_CPU0_SA_DQ<8>")
	)
	(arc
		(start 373.50446 -280.453846)
		(mid 373.303178 -280.256359)
		(end 373.222266 -279.986232)
		(width 0.088646)
		(layer "In11.Cu")
		(net "M_H_CPU0_SA_DQ<8>")
	)
	(arc
		(start 378.673614 -281.267662)
		(mid 378.486416 -281.217519)
		(end 378.299218 -281.267662)
		(width 0.088646)
		(layer "In11.Cu")
		(net "M_H_CPU0_SA_DQ<8>")
	)
	(arc
		(start 382.058418 -281.267662)
		(mid 381.784219 -281.343497)
		(end 381.507746 -281.276298)
		(width 0.088646)
		(layer "In11.Cu")
		(net "M_H_CPU0_SA_DQ<8>")
	)
	(arc
		(start 384.969512 -284.033722)
		(mid 384.921833 -283.850822)
		(end 384.79095 -283.714444)
		(width 0.088646)
		(layer "In11.Cu")
		(net "M_H_CPU0_SA_DQ<8>")
	)
	(arc
		(start 373.222266 -279.964134)
		(mid 373.174587 -279.781234)
		(end 373.043704 -279.644856)
		(width 0.088646)
		(layer "In11.Cu")
		(net "M_H_CPU0_SA_DQ<8>")
	)
	(arc
		(start 385.72186 -285.336996)
		(mid 385.519037 -285.136765)
		(end 385.439666 -284.863032)
		(width 0.088646)
		(layer "In11.Cu")
		(net "M_H_CPU0_SA_DQ<8>")
	)
	(arc
		(start 385.246118 -284.519624)
		(mid 385.043531 -284.313273)
		(end 384.969512 -284.033722)
		(width 0.088646)
		(layer "In11.Cu")
		(net "M_H_CPU0_SA_DQ<8>")
	)
	(arc
		(start 374.059704 -280.459942)
		(mid 373.781272 -280.529756)
		(end 373.50446 -280.453846)
		(width 0.088646)
		(layer "In11.Cu")
		(net "M_H_CPU0_SA_DQ<8>")
	)
	(arc
		(start 372.103904 -277.027894)
		(mid 372.219713 -276.915965)
		(end 372.277894 -276.765766)
		(width 0.088646)
		(layer "In11.Cu")
		(net "M_H_CPU0_SA_DQ<8>")
	)
	(arc
		(start 383.37236 -282.895548)
		(mid 383.170074 -282.696567)
		(end 383.089912 -282.424378)
		(width 0.088646)
		(layer "In11.Cu")
		(net "M_H_CPU0_SA_DQ<8>")
	)
	(arc
		(start 372.282466 -278.336502)
		(mid 372.234787 -278.153602)
		(end 372.103904 -278.017224)
		(width 0.088646)
		(layer "In11.Cu")
		(net "M_H_CPU0_SA_DQ<8>")
	)
	(arc
		(start 372.56466 -278.82596)
		(mid 372.361837 -278.625729)
		(end 372.282466 -278.351996)
		(width 0.088646)
		(layer "In11.Cu")
		(net "M_H_CPU0_SA_DQ<8>")
	)
	(arc
		(start 375.009664 -280.453846)
		(mid 374.733105 -280.529555)
		(end 374.454928 -280.459942)
		(width 0.088646)
		(layer "In11.Cu")
		(net "M_H_CPU0_SA_DQ<8>")
	)
	(arc
		(start 386.269992 -286.210248)
		(mid 386.232942 -286.178102)
		(end 386.192014 -286.151066)
		(width 0.088646)
		(layer "In11.Cu")
		(net "M_H_CPU0_SA_DQ<8>")
	)
	(arc
		(start 379.239018 -281.267662)
		(mid 378.964819 -281.343497)
		(end 378.688346 -281.276298)
		(width 0.088646)
		(layer "In11.Cu")
		(net "M_H_CPU0_SA_DQ<8>")
	)
	(arc
		(start 382.432814 -281.267662)
		(mid 382.245616 -281.217519)
		(end 382.058418 -281.267662)
		(width 0.088646)
		(layer "In11.Cu")
		(net "M_H_CPU0_SA_DQ<8>")
	)
	(arc
		(start 381.118618 -281.267662)
		(mid 380.844419 -281.343497)
		(end 380.567946 -281.276298)
		(width 0.088646)
		(layer "In11.Cu")
		(net "M_H_CPU0_SA_DQ<8>")
	)
	(arc
		(start 374.444514 -280.453846)
		(mid 374.257316 -280.403703)
		(end 374.070118 -280.453846)
		(width 0.088646)
		(layer "In11.Cu")
		(net "M_H_CPU0_SA_DQ<8>")
	)
	(arc
		(start 373.028718 -279.63622)
		(mid 372.826131 -279.429869)
		(end 372.752112 -279.150318)
		(width 0.088646)
		(layer "In11.Cu")
		(net "M_H_CPU0_SA_DQ<8>")
	)
	(arc
		(start 378.299218 -281.267662)
		(mid 378.025019 -281.343497)
		(end 377.748546 -281.276298)
		(width 0.088646)
		(layer "In11.Cu")
		(net "M_H_CPU0_SA_DQ<8>")
	)
	(arc
		(start 384.499612 -283.219906)
		(mid 384.451933 -283.037006)
		(end 384.32105 -282.900628)
		(width 0.088646)
		(layer "In11.Cu")
		(net "M_H_CPU0_SA_DQ<8>")
	)
	(arc
		(start 375.571512 -280.778204)
		(mid 375.523833 -280.595304)
		(end 375.39295 -280.458926)
		(width 0.088646)
		(layer "In11.Cu")
		(net "M_H_CPU0_SA_DQ<8>")
	)
	(arc
		(start 384.775964 -283.705808)
		(mid 384.573551 -283.499395)
		(end 384.499612 -283.219906)
		(width 0.088646)
		(layer "In11.Cu")
		(net "M_H_CPU0_SA_DQ<8>")
	)
	(segment
		(start 458.550264 -308.2417)
		(end 460.558134 -308.2417)
		(width 0.1016)
		(layer "F.Cu")
		(net "M_H_CPU0_SA_DQ<7>")
	)
	(segment
		(start 456.116182 -307.816758)
		(end 457.814426 -307.816758)
		(width 0.20066)
		(layer "F.Cu")
		(net "M_H_CPU0_SA_DQ<7>")
	)
	(segment
		(start 461.455516 -308.04993)
		(end 461.455516 -307.798978)
		(width 0.20066)
		(layer "F.Cu")
		(net "M_H_CPU0_SA_DQ<7>")
	)
	(segment
		(start 462.073752 -307.56479)
		(end 462.32572 -307.816758)
		(width 0.20066)
		(layer "F.Cu")
		(net "M_H_CPU0_SA_DQ<7>")
	)
	(segment
		(start 462.32572 -307.816758)
		(end 463.659982 -307.816758)
		(width 0.20066)
		(layer "F.Cu")
		(net "M_H_CPU0_SA_DQ<7>")
	)
	(segment
		(start 458.24648 -308.248812)
		(end 458.538326 -308.248812)
		(width 0.20066)
		(layer "F.Cu")
		(net "M_H_CPU0_SA_DQ<7>")
	)
	(segment
		(start 455.011282 -307.816758)
		(end 456.116182 -307.816758)
		(width 0.20066)
		(layer "F.Cu")
		(net "M_H_CPU0_SA_DQ<7>")
	)
	(segment
		(start 461.455516 -307.798978)
		(end 461.689704 -307.56479)
		(width 0.20066)
		(layer "F.Cu")
		(net "M_H_CPU0_SA_DQ<7>")
	)
	(segment
		(start 457.814426 -307.816758)
		(end 458.24648 -308.248812)
		(width 0.20066)
		(layer "F.Cu")
		(net "M_H_CPU0_SA_DQ<7>")
	)
	(segment
		(start 461.689704 -307.56479)
		(end 462.073752 -307.56479)
		(width 0.20066)
		(layer "F.Cu")
		(net "M_H_CPU0_SA_DQ<7>")
	)
	(segment
		(start 458.543152 -308.248812)
		(end 458.550264 -308.2417)
		(width 0.1016)
		(layer "F.Cu")
		(net "M_H_CPU0_SA_DQ<7>")
	)
	(segment
		(start 460.570326 -308.253892)
		(end 461.251554 -308.253892)
		(width 0.20066)
		(layer "F.Cu")
		(net "M_H_CPU0_SA_DQ<7>")
	)
	(segment
		(start 376.136916 -275.894546)
		(end 376.136662 -275.8948)
		(width 0.20066)
		(layer "F.Cu")
		(net "M_H_CPU0_SA_DQ<7>")
	)
	(segment
		(start 461.251554 -308.253892)
		(end 461.455516 -308.04993)
		(width 0.20066)
		(layer "F.Cu")
		(net "M_H_CPU0_SA_DQ<7>")
	)
	(segment
		(start 458.538326 -308.248812)
		(end 458.543152 -308.248812)
		(width 0.101854)
		(layer "F.Cu")
		(net "M_H_CPU0_SA_DQ<7>")
	)
	(segment
		(start 376.136916 -275.35886)
		(end 376.136916 -275.894546)
		(width 0.20066)
		(layer "F.Cu")
		(net "M_H_CPU0_SA_DQ<7>")
	)
	(segment
		(start 460.558134 -308.2417)
		(end 460.570326 -308.253892)
		(width 0.1016)
		(layer "F.Cu")
		(net "M_H_CPU0_SA_DQ<7>")
	)
	(segment
		(start 421.274494 -303.992026)
		(end 418.88029 -303.992026)
		(width 0.18288)
		(layer "In6.Cu")
		(net "M_H_CPU0_SA_DQ<7>")
	)
	(segment
		(start 431.170842 -306.735226)
		(end 430.332642 -306.735226)
		(width 0.18288)
		(layer "In6.Cu")
		(net "M_H_CPU0_SA_DQ<7>")
	)
	(segment
		(start 417.747196 -303.669192)
		(end 418.02304 -303.393348)
		(width 0.18288)
		(layer "In6.Cu")
		(net "M_H_CPU0_SA_DQ<7>")
	)
	(segment
		(start 375.766584 -275.952204)
		(end 375.823988 -275.8948)
		(width 0.088646)
		(layer "In6.Cu")
		(net "M_H_CPU0_SA_DQ<7>")
	)
	(segment
		(start 449.888356 -307.42128)
		(end 446.547494 -307.42128)
		(width 0.18288)
		(layer "In6.Cu")
		(net "M_H_CPU0_SA_DQ<7>")
	)
	(segment
		(start 416.052762 -301.390558)
		(end 416.052762 -301.164498)
		(width 0.18288)
		(layer "In6.Cu")
		(net "M_H_CPU0_SA_DQ<7>")
	)
	(segment
		(start 431.828194 -307.392578)
		(end 431.170842 -306.735226)
		(width 0.18288)
		(layer "In6.Cu")
		(net "M_H_CPU0_SA_DQ<7>")
	)
	(segment
		(start 439.66765 -306.580286)
		(end 439.218578 -306.766214)
		(width 0.18288)
		(layer "In6.Cu")
		(net "M_H_CPU0_SA_DQ<7>")
	)
	(segment
		(start 411.71876 -299.742352)
		(end 410.868622 -298.892214)
		(width 0.18288)
		(layer "In6.Cu")
		(net "M_H_CPU0_SA_DQ<7>")
	)
	(segment
		(start 418.88029 -303.992026)
		(end 418.772086 -303.883822)
		(width 0.18288)
		(layer "In6.Cu")
		(net "M_H_CPU0_SA_DQ<7>")
	)
	(segment
		(start 427.312582 -304.144426)
		(end 426.265594 -304.144426)
		(width 0.18288)
		(layer "In6.Cu")
		(net "M_H_CPU0_SA_DQ<7>")
	)
	(segment
		(start 384.327146 -275.396706)
		(end 384.312414 -275.405342)
		(width 0.088646)
		(layer "In6.Cu")
		(net "M_H_CPU0_SA_DQ<7>")
	)
	(segment
		(start 407.235152 -297.40606)
		(end 407.235152 -297.940476)
		(width 0.18288)
		(layer "In6.Cu")
		(net "M_H_CPU0_SA_DQ<7>")
	)
	(segment
		(start 417.747196 -303.927764)
		(end 417.747196 -303.669192)
		(width 0.18288)
		(layer "In6.Cu")
		(net "M_H_CPU0_SA_DQ<7>")
	)
	(segment
		(start 418.02304 -303.134776)
		(end 417.750244 -302.86198)
		(width 0.18288)
		(layer "In6.Cu")
		(net "M_H_CPU0_SA_DQ<7>")
	)
	(segment
		(start 376.33275 -276.214078)
		(end 376.32386 -276.219158)
		(width 0.088646)
		(layer "In6.Cu")
		(net "M_H_CPU0_SA_DQ<7>")
	)
	(segment
		(start 383.387346 -275.396706)
		(end 383.372614 -275.405342)
		(width 0.088646)
		(layer "In6.Cu")
		(net "M_H_CPU0_SA_DQ<7>")
	)
	(segment
		(start 422.124124 -303.142396)
		(end 421.274494 -303.992026)
		(width 0.18288)
		(layer "In6.Cu")
		(net "M_H_CPU0_SA_DQ<7>")
	)
	(segment
		(start 416.774122 -302.857154)
		(end 416.774122 -302.631094)
		(width 0.18288)
		(layer "In6.Cu")
		(net "M_H_CPU0_SA_DQ<7>")
	)
	(segment
		(start 417.03371 -302.145446)
		(end 416.769296 -301.881032)
		(width 0.18288)
		(layer "In6.Cu")
		(net "M_H_CPU0_SA_DQ<7>")
	)
	(segment
		(start 408.178 -298.742354)
		(end 408.613864 -298.30649)
		(width 0.18288)
		(layer "In6.Cu")
		(net "M_H_CPU0_SA_DQ<7>")
	)
	(segment
		(start 436.74919 -307.392578)
		(end 431.828194 -307.392578)
		(width 0.18288)
		(layer "In6.Cu")
		(net "M_H_CPU0_SA_DQ<7>")
	)
	(segment
		(start 404.976076 -297.22318)
		(end 398.90319 -291.150294)
		(width 0.18288)
		(layer "In6.Cu")
		(net "M_H_CPU0_SA_DQ<7>")
	)
	(segment
		(start 416.543236 -301.881032)
		(end 416.343084 -302.081184)
		(width 0.18288)
		(layer "In6.Cu")
		(net "M_H_CPU0_SA_DQ<7>")
	)
	(segment
		(start 385.266946 -275.396706)
		(end 385.252214 -275.405342)
		(width 0.088646)
		(layer "In6.Cu")
		(net "M_H_CPU0_SA_DQ<7>")
	)
	(segment
		(start 413.408114 -299.491146)
		(end 412.704534 -299.491146)
		(width 0.18288)
		(layer "In6.Cu")
		(net "M_H_CPU0_SA_DQ<7>")
	)
	(segment
		(start 418.772086 -303.883822)
		(end 418.513514 -303.883822)
		(width 0.18288)
		(layer "In6.Cu")
		(net "M_H_CPU0_SA_DQ<7>")
	)
	(segment
		(start 430.332642 -306.735226)
		(end 428.503842 -304.906426)
		(width 0.18288)
		(layer "In6.Cu")
		(net "M_H_CPU0_SA_DQ<7>")
	)
	(segment
		(start 408.613864 -298.047918)
		(end 407.789126 -297.22318)
		(width 0.18288)
		(layer "In6.Cu")
		(net "M_H_CPU0_SA_DQ<7>")
	)
	(segment
		(start 454.585324 -308.242716)
		(end 450.709792 -308.242716)
		(width 0.18288)
		(layer "In6.Cu")
		(net "M_H_CPU0_SA_DQ<7>")
	)
	(segment
		(start 406.358852 -297.22318)
		(end 404.976076 -297.22318)
		(width 0.18288)
		(layer "In6.Cu")
		(net "M_H_CPU0_SA_DQ<7>")
	)
	(segment
		(start 408.409902 -299.232828)
		(end 408.178 -299.000926)
		(width 0.18288)
		(layer "In6.Cu")
		(net "M_H_CPU0_SA_DQ<7>")
	)
	(segment
		(start 376.511312 -275.88718)
		(end 376.511312 -275.8948)
		(width 0.088646)
		(layer "In6.Cu")
		(net "M_H_CPU0_SA_DQ<7>")
	)
	(segment
		(start 416.769296 -301.881032)
		(end 416.543236 -301.881032)
		(width 0.18288)
		(layer "In6.Cu")
		(net "M_H_CPU0_SA_DQ<7>")
	)
	(segment
		(start 416.774122 -302.631094)
		(end 417.03371 -302.371506)
		(width 0.18288)
		(layer "In6.Cu")
		(net "M_H_CPU0_SA_DQ<7>")
	)
	(segment
		(start 398.90319 -291.150294)
		(end 398.90319 -282.325064)
		(width 0.18288)
		(layer "In6.Cu")
		(net "M_H_CPU0_SA_DQ<7>")
	)
	(segment
		(start 417.03371 -302.371506)
		(end 417.03371 -302.145446)
		(width 0.18288)
		(layer "In6.Cu")
		(net "M_H_CPU0_SA_DQ<7>")
	)
	(segment
		(start 409.36291 -298.796964)
		(end 409.104338 -298.796964)
		(width 0.18288)
		(layer "In6.Cu")
		(net "M_H_CPU0_SA_DQ<7>")
	)
	(segment
		(start 455.011282 -307.816758)
		(end 454.585324 -308.242716)
		(width 0.18288)
		(layer "In6.Cu")
		(net "M_H_CPU0_SA_DQ<7>")
	)
	(segment
		(start 406.541732 -297.40606)
		(end 406.358852 -297.22318)
		(width 0.18288)
		(layer "In6.Cu")
		(net "M_H_CPU0_SA_DQ<7>")
	)
	(segment
		(start 407.235152 -297.940476)
		(end 407.052272 -298.123356)
		(width 0.18288)
		(layer "In6.Cu")
		(net "M_H_CPU0_SA_DQ<7>")
	)
	(segment
		(start 388.13359 -277.76043)
		(end 387.509512 -277.136352)
		(width 0.088646)
		(layer "In6.Cu")
		(net "M_H_CPU0_SA_DQ<7>")
	)
	(segment
		(start 416.343084 -302.081184)
		(end 416.117024 -302.081184)
		(width 0.18288)
		(layer "In6.Cu")
		(net "M_H_CPU0_SA_DQ<7>")
	)
	(segment
		(start 412.704534 -299.491146)
		(end 412.453328 -299.742352)
		(width 0.18288)
		(layer "In6.Cu")
		(net "M_H_CPU0_SA_DQ<7>")
	)
	(segment
		(start 410.868622 -298.892214)
		(end 409.45816 -298.892214)
		(width 0.18288)
		(layer "In6.Cu")
		(net "M_H_CPU0_SA_DQ<7>")
	)
	(segment
		(start 406.724612 -298.123356)
		(end 406.541732 -297.940476)
		(width 0.18288)
		(layer "In6.Cu")
		(net "M_H_CPU0_SA_DQ<7>")
	)
	(segment
		(start 408.178 -299.000926)
		(end 408.178 -298.742354)
		(width 0.18288)
		(layer "In6.Cu")
		(net "M_H_CPU0_SA_DQ<7>")
	)
	(segment
		(start 437.375554 -306.766214)
		(end 436.74919 -307.392578)
		(width 0.18288)
		(layer "In6.Cu")
		(net "M_H_CPU0_SA_DQ<7>")
	)
	(segment
		(start 450.709792 -308.242716)
		(end 449.888356 -307.42128)
		(width 0.18288)
		(layer "In6.Cu")
		(net "M_H_CPU0_SA_DQ<7>")
	)
	(segment
		(start 417.750244 -302.86198)
		(end 417.524184 -302.86198)
		(width 0.18288)
		(layer "In6.Cu")
		(net "M_H_CPU0_SA_DQ<7>")
	)
	(segment
		(start 388.815326 -277.76043)
		(end 388.307326 -277.76043)
		(width 0.18288)
		(layer "In6.Cu")
		(net "M_H_CPU0_SA_DQ<7>")
	)
	(segment
		(start 416.117024 -302.081184)
		(end 415.85261 -301.81677)
		(width 0.18288)
		(layer "In6.Cu")
		(net "M_H_CPU0_SA_DQ<7>")
	)
	(segment
		(start 378.688346 -275.396452)
		(end 378.673614 -275.405088)
		(width 0.088646)
		(layer "In6.Cu")
		(net "M_H_CPU0_SA_DQ<7>")
	)
	(segment
		(start 418.23767 -304.159666)
		(end 417.979098 -304.159666)
		(width 0.18288)
		(layer "In6.Cu")
		(net "M_H_CPU0_SA_DQ<7>")
	)
	(segment
		(start 417.979098 -304.159666)
		(end 417.747196 -303.927764)
		(width 0.18288)
		(layer "In6.Cu")
		(net "M_H_CPU0_SA_DQ<7>")
	)
	(segment
		(start 415.85261 -301.81677)
		(end 415.85261 -301.59071)
		(width 0.18288)
		(layer "In6.Cu")
		(net "M_H_CPU0_SA_DQ<7>")
	)
	(segment
		(start 398.90319 -282.325064)
		(end 394.577062 -277.998936)
		(width 0.18288)
		(layer "In6.Cu")
		(net "M_H_CPU0_SA_DQ<7>")
	)
	(segment
		(start 407.418032 -297.22318)
		(end 407.235152 -297.40606)
		(width 0.18288)
		(layer "In6.Cu")
		(net "M_H_CPU0_SA_DQ<7>")
	)
	(segment
		(start 425.263564 -303.142396)
		(end 424.254676 -303.142396)
		(width 0.18288)
		(layer "In6.Cu")
		(net "M_H_CPU0_SA_DQ<7>")
	)
	(segment
		(start 423.249598 -303.142396)
		(end 422.124124 -303.142396)
		(width 0.18288)
		(layer "In6.Cu")
		(net "M_H_CPU0_SA_DQ<7>")
	)
	(segment
		(start 417.264596 -303.121568)
		(end 417.038536 -303.121568)
		(width 0.18288)
		(layer "In6.Cu")
		(net "M_H_CPU0_SA_DQ<7>")
	)
	(segment
		(start 382.438402 -275.401786)
		(end 382.432814 -275.405088)
		(width 0.088646)
		(layer "In6.Cu")
		(net "M_H_CPU0_SA_DQ<7>")
	)
	(segment
		(start 386.206746 -275.396706)
		(end 386.192014 -275.405342)
		(width 0.088646)
		(layer "In6.Cu")
		(net "M_H_CPU0_SA_DQ<7>")
	)
	(segment
		(start 444.34379 -306.542694)
		(end 439.758328 -306.542694)
		(width 0.18288)
		(layer "In6.Cu")
		(net "M_H_CPU0_SA_DQ<7>")
	)
	(segment
		(start 418.02304 -303.393348)
		(end 418.02304 -303.134776)
		(width 0.18288)
		(layer "In6.Cu")
		(net "M_H_CPU0_SA_DQ<7>")
	)
	(segment
		(start 418.513514 -303.883822)
		(end 418.23767 -304.159666)
		(width 0.18288)
		(layer "In6.Cu")
		(net "M_H_CPU0_SA_DQ<7>")
	)
	(segment
		(start 426.265594 -304.144426)
		(end 425.263564 -303.142396)
		(width 0.18288)
		(layer "In6.Cu")
		(net "M_H_CPU0_SA_DQ<7>")
	)
	(segment
		(start 415.85261 -301.59071)
		(end 416.052762 -301.390558)
		(width 0.18288)
		(layer "In6.Cu")
		(net "M_H_CPU0_SA_DQ<7>")
	)
	(segment
		(start 408.668474 -299.232828)
		(end 408.409902 -299.232828)
		(width 0.18288)
		(layer "In6.Cu")
		(net "M_H_CPU0_SA_DQ<7>")
	)
	(segment
		(start 414.860994 -300.944026)
		(end 413.408114 -299.491146)
		(width 0.18288)
		(layer "In6.Cu")
		(net "M_H_CPU0_SA_DQ<7>")
	)
	(segment
		(start 387.509512 -277.136352)
		(end 387.509512 -276.69871)
		(width 0.088646)
		(layer "In6.Cu")
		(net "M_H_CPU0_SA_DQ<7>")
	)
	(segment
		(start 409.45816 -298.892214)
		(end 409.36291 -298.796964)
		(width 0.18288)
		(layer "In6.Cu")
		(net "M_H_CPU0_SA_DQ<7>")
	)
	(segment
		(start 439.218578 -306.766214)
		(end 437.375554 -306.766214)
		(width 0.18288)
		(layer "In6.Cu")
		(net "M_H_CPU0_SA_DQ<7>")
	)
	(segment
		(start 423.561256 -303.454054)
		(end 423.249598 -303.142396)
		(width 0.18288)
		(layer "In6.Cu")
		(net "M_H_CPU0_SA_DQ<7>")
	)
	(segment
		(start 381.503174 -275.398992)
		(end 381.49276 -275.405088)
		(width 0.088646)
		(layer "In6.Cu")
		(net "M_H_CPU0_SA_DQ<7>")
	)
	(segment
		(start 439.758328 -306.542694)
		(end 439.66765 -306.580286)
		(width 0.18288)
		(layer "In6.Cu")
		(net "M_H_CPU0_SA_DQ<7>")
	)
	(segment
		(start 423.943018 -303.454054)
		(end 423.561256 -303.454054)
		(width 0.18288)
		(layer "In6.Cu")
		(net "M_H_CPU0_SA_DQ<7>")
	)
	(segment
		(start 379.628146 -275.396452)
		(end 379.613414 -275.405088)
		(width 0.088646)
		(layer "In6.Cu")
		(net "M_H_CPU0_SA_DQ<7>")
	)
	(segment
		(start 428.074582 -304.906426)
		(end 427.312582 -304.144426)
		(width 0.18288)
		(layer "In6.Cu")
		(net "M_H_CPU0_SA_DQ<7>")
	)
	(segment
		(start 408.613864 -298.30649)
		(end 408.613864 -298.047918)
		(width 0.18288)
		(layer "In6.Cu")
		(net "M_H_CPU0_SA_DQ<7>")
	)
	(segment
		(start 377.748546 -275.396452)
		(end 377.733814 -275.405088)
		(width 0.088646)
		(layer "In6.Cu")
		(net "M_H_CPU0_SA_DQ<7>")
	)
	(segment
		(start 446.547494 -307.42128)
		(end 444.34379 -306.542694)
		(width 0.18288)
		(layer "In6.Cu")
		(net "M_H_CPU0_SA_DQ<7>")
	)
	(segment
		(start 407.052272 -298.123356)
		(end 406.724612 -298.123356)
		(width 0.18288)
		(layer "In6.Cu")
		(net "M_H_CPU0_SA_DQ<7>")
	)
	(segment
		(start 406.541732 -297.940476)
		(end 406.541732 -297.40606)
		(width 0.18288)
		(layer "In6.Cu")
		(net "M_H_CPU0_SA_DQ<7>")
	)
	(segment
		(start 424.254676 -303.142396)
		(end 423.943018 -303.454054)
		(width 0.18288)
		(layer "In6.Cu")
		(net "M_H_CPU0_SA_DQ<7>")
	)
	(segment
		(start 375.949464 -276.219158)
		(end 375.940574 -276.214078)
		(width 0.088646)
		(layer "In6.Cu")
		(net "M_H_CPU0_SA_DQ<7>")
	)
	(segment
		(start 417.524184 -302.86198)
		(end 417.264596 -303.121568)
		(width 0.18288)
		(layer "In6.Cu")
		(net "M_H_CPU0_SA_DQ<7>")
	)
	(segment
		(start 387.227064 -276.219158)
		(end 387.218174 -276.214078)
		(width 0.088646)
		(layer "In6.Cu")
		(net "M_H_CPU0_SA_DQ<7>")
	)
	(segment
		(start 409.104338 -298.796964)
		(end 408.668474 -299.232828)
		(width 0.18288)
		(layer "In6.Cu")
		(net "M_H_CPU0_SA_DQ<7>")
	)
	(segment
		(start 416.052762 -301.164498)
		(end 415.83229 -300.944026)
		(width 0.18288)
		(layer "In6.Cu")
		(net "M_H_CPU0_SA_DQ<7>")
	)
	(segment
		(start 428.503842 -304.906426)
		(end 428.074582 -304.906426)
		(width 0.18288)
		(layer "In6.Cu")
		(net "M_H_CPU0_SA_DQ<7>")
	)
	(segment
		(start 375.823988 -275.8948)
		(end 376.136662 -275.8948)
		(width 0.088646)
		(layer "In6.Cu")
		(net "M_H_CPU0_SA_DQ<7>")
	)
	(segment
		(start 417.038536 -303.121568)
		(end 416.774122 -302.857154)
		(width 0.18288)
		(layer "In6.Cu")
		(net "M_H_CPU0_SA_DQ<7>")
	)
	(segment
		(start 387.039612 -275.8948)
		(end 387.039612 -275.879306)
		(width 0.088646)
		(layer "In6.Cu")
		(net "M_H_CPU0_SA_DQ<7>")
	)
	(segment
		(start 394.577062 -277.998936)
		(end 389.391144 -277.998936)
		(width 0.18288)
		(layer "In6.Cu")
		(net "M_H_CPU0_SA_DQ<7>")
	)
	(segment
		(start 388.307326 -277.76043)
		(end 388.13359 -277.76043)
		(width 0.088646)
		(layer "In6.Cu")
		(net "M_H_CPU0_SA_DQ<7>")
	)
	(segment
		(start 415.83229 -300.944026)
		(end 414.860994 -300.944026)
		(width 0.18288)
		(layer "In6.Cu")
		(net "M_H_CPU0_SA_DQ<7>")
	)
	(segment
		(start 412.453328 -299.742352)
		(end 411.71876 -299.742352)
		(width 0.18288)
		(layer "In6.Cu")
		(net "M_H_CPU0_SA_DQ<7>")
	)
	(segment
		(start 407.789126 -297.22318)
		(end 407.418032 -297.22318)
		(width 0.18288)
		(layer "In6.Cu")
		(net "M_H_CPU0_SA_DQ<7>")
	)
	(segment
		(start 380.563628 -275.398992)
		(end 380.553214 -275.405088)
		(width 0.088646)
		(layer "In6.Cu")
		(net "M_H_CPU0_SA_DQ<7>")
	)
	(segment
		(start 389.391144 -277.998936)
		(end 388.815326 -277.76043)
		(width 0.18288)
		(layer "In6.Cu")
		(net "M_H_CPU0_SA_DQ<7>")
	)
	(arc
		(start 378.299218 -275.405088)
		(mid 378.024989 -275.329163)
		(end 377.748546 -275.396452)
		(width 0.088646)
		(layer "In6.Cu")
		(net "M_H_CPU0_SA_DQ<7>")
	)
	(arc
		(start 385.252214 -275.405342)
		(mid 385.065016 -275.455485)
		(end 384.877818 -275.405342)
		(width 0.088646)
		(layer "In6.Cu")
		(net "M_H_CPU0_SA_DQ<7>")
	)
	(arc
		(start 386.757418 -275.405342)
		(mid 386.483219 -275.329507)
		(end 386.206746 -275.396706)
		(width 0.088646)
		(layer "In6.Cu")
		(net "M_H_CPU0_SA_DQ<7>")
	)
	(arc
		(start 382.058418 -275.405088)
		(mid 381.781605 -275.329252)
		(end 381.503174 -275.398992)
		(width 0.088646)
		(layer "In6.Cu")
		(net "M_H_CPU0_SA_DQ<7>")
	)
	(arc
		(start 387.509512 -276.69871)
		(mid 387.431401 -276.421761)
		(end 387.227064 -276.219158)
		(width 0.088646)
		(layer "In6.Cu")
		(net "M_H_CPU0_SA_DQ<7>")
	)
	(arc
		(start 387.218174 -276.214078)
		(mid 387.08726 -276.077718)
		(end 387.039612 -275.8948)
		(width 0.088646)
		(layer "In6.Cu")
		(net "M_H_CPU0_SA_DQ<7>")
	)
	(arc
		(start 386.192014 -275.405342)
		(mid 386.004816 -275.455485)
		(end 385.817618 -275.405342)
		(width 0.088646)
		(layer "In6.Cu")
		(net "M_H_CPU0_SA_DQ<7>")
	)
	(arc
		(start 380.553214 -275.405088)
		(mid 380.366016 -275.455231)
		(end 380.178818 -275.405088)
		(width 0.088646)
		(layer "In6.Cu")
		(net "M_H_CPU0_SA_DQ<7>")
	)
	(arc
		(start 383.372614 -275.405342)
		(mid 383.185416 -275.455485)
		(end 382.998218 -275.405342)
		(width 0.088646)
		(layer "In6.Cu")
		(net "M_H_CPU0_SA_DQ<7>")
	)
	(arc
		(start 377.359418 -275.405088)
		(mid 377.076716 -275.329346)
		(end 376.794014 -275.405088)
		(width 0.088646)
		(layer "In6.Cu")
		(net "M_H_CPU0_SA_DQ<7>")
	)
	(arc
		(start 379.239018 -275.405088)
		(mid 378.964789 -275.329163)
		(end 378.688346 -275.396452)
		(width 0.088646)
		(layer "In6.Cu")
		(net "M_H_CPU0_SA_DQ<7>")
	)
	(arc
		(start 381.49276 -275.405088)
		(mid 381.305562 -275.455231)
		(end 381.118364 -275.405088)
		(width 0.088646)
		(layer "In6.Cu")
		(net "M_H_CPU0_SA_DQ<7>")
	)
	(arc
		(start 382.998218 -275.405342)
		(mid 382.71879 -275.32945)
		(end 382.438402 -275.401786)
		(width 0.088646)
		(layer "In6.Cu")
		(net "M_H_CPU0_SA_DQ<7>")
	)
	(arc
		(start 387.039612 -275.879306)
		(mid 386.960242 -275.605572)
		(end 386.757418 -275.405342)
		(width 0.088646)
		(layer "In6.Cu")
		(net "M_H_CPU0_SA_DQ<7>")
	)
	(arc
		(start 378.673614 -275.405088)
		(mid 378.486416 -275.455231)
		(end 378.299218 -275.405088)
		(width 0.088646)
		(layer "In6.Cu")
		(net "M_H_CPU0_SA_DQ<7>")
	)
	(arc
		(start 380.178818 -275.405088)
		(mid 379.904589 -275.329163)
		(end 379.628146 -275.396452)
		(width 0.088646)
		(layer "In6.Cu")
		(net "M_H_CPU0_SA_DQ<7>")
	)
	(arc
		(start 377.733814 -275.405088)
		(mid 377.546616 -275.455231)
		(end 377.359418 -275.405088)
		(width 0.088646)
		(layer "In6.Cu")
		(net "M_H_CPU0_SA_DQ<7>")
	)
	(arc
		(start 381.118364 -275.405088)
		(mid 380.841805 -275.329379)
		(end 380.563628 -275.398992)
		(width 0.088646)
		(layer "In6.Cu")
		(net "M_H_CPU0_SA_DQ<7>")
	)
	(arc
		(start 383.938018 -275.405342)
		(mid 383.663819 -275.329507)
		(end 383.387346 -275.396706)
		(width 0.088646)
		(layer "In6.Cu")
		(net "M_H_CPU0_SA_DQ<7>")
	)
	(arc
		(start 376.794014 -275.405088)
		(mid 376.588942 -275.608767)
		(end 376.511312 -275.88718)
		(width 0.088646)
		(layer "In6.Cu")
		(net "M_H_CPU0_SA_DQ<7>")
	)
	(arc
		(start 375.940574 -276.214078)
		(mid 375.824835 -276.102254)
		(end 375.766584 -275.952204)
		(width 0.088646)
		(layer "In6.Cu")
		(net "M_H_CPU0_SA_DQ<7>")
	)
	(arc
		(start 379.613414 -275.405088)
		(mid 379.426216 -275.455231)
		(end 379.239018 -275.405088)
		(width 0.088646)
		(layer "In6.Cu")
		(net "M_H_CPU0_SA_DQ<7>")
	)
	(arc
		(start 384.312414 -275.405342)
		(mid 384.125216 -275.455485)
		(end 383.938018 -275.405342)
		(width 0.088646)
		(layer "In6.Cu")
		(net "M_H_CPU0_SA_DQ<7>")
	)
	(arc
		(start 384.877818 -275.405342)
		(mid 384.603619 -275.329507)
		(end 384.327146 -275.396706)
		(width 0.088646)
		(layer "In6.Cu")
		(net "M_H_CPU0_SA_DQ<7>")
	)
	(arc
		(start 382.432814 -275.405088)
		(mid 382.245616 -275.455231)
		(end 382.058418 -275.405088)
		(width 0.088646)
		(layer "In6.Cu")
		(net "M_H_CPU0_SA_DQ<7>")
	)
	(arc
		(start 376.32386 -276.219158)
		(mid 376.136662 -276.269301)
		(end 375.949464 -276.219158)
		(width 0.088646)
		(layer "In6.Cu")
		(net "M_H_CPU0_SA_DQ<7>")
	)
	(arc
		(start 385.817618 -275.405342)
		(mid 385.543419 -275.329507)
		(end 385.266946 -275.396706)
		(width 0.088646)
		(layer "In6.Cu")
		(net "M_H_CPU0_SA_DQ<7>")
	)
	(arc
		(start 376.511312 -275.8948)
		(mid 376.463633 -276.0777)
		(end 376.33275 -276.214078)
		(width 0.088646)
		(layer "In6.Cu")
		(net "M_H_CPU0_SA_DQ<7>")
	)
	(segment
		(start 462.073752 -309.264812)
		(end 462.32572 -309.51678)
		(width 0.20066)
		(layer "F.Cu")
		(net "M_H_CPU0_SA_DQ<6>")
	)
	(segment
		(start 458.543152 -309.948834)
		(end 458.550264 -309.941722)
		(width 0.1016)
		(layer "F.Cu")
		(net "M_H_CPU0_SA_DQ<6>")
	)
	(segment
		(start 456.116182 -309.51678)
		(end 457.814426 -309.51678)
		(width 0.20066)
		(layer "F.Cu")
		(net "M_H_CPU0_SA_DQ<6>")
	)
	(segment
		(start 461.251554 -309.953914)
		(end 461.455516 -309.749952)
		(width 0.20066)
		(layer "F.Cu")
		(net "M_H_CPU0_SA_DQ<6>")
	)
	(segment
		(start 461.689704 -309.264812)
		(end 462.073752 -309.264812)
		(width 0.20066)
		(layer "F.Cu")
		(net "M_H_CPU0_SA_DQ<6>")
	)
	(segment
		(start 462.32572 -309.51678)
		(end 463.659982 -309.51678)
		(width 0.20066)
		(layer "F.Cu")
		(net "M_H_CPU0_SA_DQ<6>")
	)
	(segment
		(start 458.538326 -309.948834)
		(end 458.543152 -309.948834)
		(width 0.101854)
		(layer "F.Cu")
		(net "M_H_CPU0_SA_DQ<6>")
	)
	(segment
		(start 461.455516 -309.749952)
		(end 461.455516 -309.499)
		(width 0.20066)
		(layer "F.Cu")
		(net "M_H_CPU0_SA_DQ<6>")
	)
	(segment
		(start 376.606562 -276.172676)
		(end 376.606816 -276.708616)
		(width 0.20066)
		(layer "F.Cu")
		(net "M_H_CPU0_SA_DQ<6>")
	)
	(segment
		(start 461.455516 -309.499)
		(end 461.689704 -309.264812)
		(width 0.20066)
		(layer "F.Cu")
		(net "M_H_CPU0_SA_DQ<6>")
	)
	(segment
		(start 460.570326 -309.953914)
		(end 461.251554 -309.953914)
		(width 0.20066)
		(layer "F.Cu")
		(net "M_H_CPU0_SA_DQ<6>")
	)
	(segment
		(start 455.011282 -309.51678)
		(end 456.116182 -309.51678)
		(width 0.20066)
		(layer "F.Cu")
		(net "M_H_CPU0_SA_DQ<6>")
	)
	(segment
		(start 457.814426 -309.51678)
		(end 458.24648 -309.948834)
		(width 0.20066)
		(layer "F.Cu")
		(net "M_H_CPU0_SA_DQ<6>")
	)
	(segment
		(start 458.550264 -309.941722)
		(end 460.558134 -309.941722)
		(width 0.1016)
		(layer "F.Cu")
		(net "M_H_CPU0_SA_DQ<6>")
	)
	(segment
		(start 460.558134 -309.941722)
		(end 460.570326 -309.953914)
		(width 0.1016)
		(layer "F.Cu")
		(net "M_H_CPU0_SA_DQ<6>")
	)
	(segment
		(start 458.24648 -309.948834)
		(end 458.538326 -309.948834)
		(width 0.20066)
		(layer "F.Cu")
		(net "M_H_CPU0_SA_DQ<6>")
	)
	(segment
		(start 448.906392 -308.56047)
		(end 448.578732 -308.56047)
		(width 0.18288)
		(layer "In6.Cu")
		(net "M_H_CPU0_SA_DQ<6>")
	)
	(segment
		(start 409.279852 -300.912276)
		(end 409.025344 -301.166784)
		(width 0.18288)
		(layer "In6.Cu")
		(net "M_H_CPU0_SA_DQ<6>")
	)
	(segment
		(start 446.609724 -309.335424)
		(end 446.148714 -308.874414)
		(width 0.18288)
		(layer "In6.Cu")
		(net "M_H_CPU0_SA_DQ<6>")
	)
	(segment
		(start 406.674574 -300.592236)
		(end 405.823674 -299.741336)
		(width 0.18288)
		(layer "In6.Cu")
		(net "M_H_CPU0_SA_DQ<6>")
	)
	(segment
		(start 438.724294 -308.442614)
		(end 437.683148 -308.442614)
		(width 0.18288)
		(layer "In6.Cu")
		(net "M_H_CPU0_SA_DQ<6>")
	)
	(segment
		(start 421.299894 -305.692302)
		(end 419.955218 -305.692302)
		(width 0.18288)
		(layer "In6.Cu")
		(net "M_H_CPU0_SA_DQ<6>")
	)
	(segment
		(start 407.359612 -301.635922)
		(end 407.199592 -301.475902)
		(width 0.18288)
		(layer "In6.Cu")
		(net "M_H_CPU0_SA_DQ<6>")
	)
	(segment
		(start 444.768478 -308.417214)
		(end 443.220094 -308.417214)
		(width 0.18288)
		(layer "In6.Cu")
		(net "M_H_CPU0_SA_DQ<6>")
	)
	(segment
		(start 450.485764 -309.335424)
		(end 449.272152 -309.335424)
		(width 0.18288)
		(layer "In6.Cu")
		(net "M_H_CPU0_SA_DQ<6>")
	)
	(segment
		(start 448.578732 -308.56047)
		(end 448.395852 -308.74335)
		(width 0.18288)
		(layer "In6.Cu")
		(net "M_H_CPU0_SA_DQ<6>")
	)
	(segment
		(start 440.983116 -308.242716)
		(end 438.924192 -308.242716)
		(width 0.18288)
		(layer "In6.Cu")
		(net "M_H_CPU0_SA_DQ<6>")
	)
	(segment
		(start 453.318118 -310.534558)
		(end 452.667878 -310.535574)
		(width 0.18288)
		(layer "In6.Cu")
		(net "M_H_CPU0_SA_DQ<6>")
	)
	(segment
		(start 450.728588 -309.0926)
		(end 450.485764 -309.335424)
		(width 0.18288)
		(layer "In6.Cu")
		(net "M_H_CPU0_SA_DQ<6>")
	)
	(segment
		(start 397.90751 -292.197536)
		(end 397.90751 -282.73756)
		(width 0.18288)
		(layer "In6.Cu")
		(net "M_H_CPU0_SA_DQ<6>")
	)
	(segment
		(start 428.63516 -306.633626)
		(end 428.12716 -306.633626)
		(width 0.18288)
		(layer "In6.Cu")
		(net "M_H_CPU0_SA_DQ<6>")
	)
	(segment
		(start 407.893012 -300.752256)
		(end 407.893012 -301.475902)
		(width 0.18288)
		(layer "In6.Cu")
		(net "M_H_CPU0_SA_DQ<6>")
	)
	(segment
		(start 407.732992 -301.635922)
		(end 407.359612 -301.635922)
		(width 0.18288)
		(layer "In6.Cu")
		(net "M_H_CPU0_SA_DQ<6>")
	)
	(segment
		(start 409.962096 -300.592236)
		(end 409.439872 -300.592236)
		(width 0.18288)
		(layer "In6.Cu")
		(net "M_H_CPU0_SA_DQ<6>")
	)
	(segment
		(start 415.303208 -304.943002)
		(end 412.300674 -301.940468)
		(width 0.18288)
		(layer "In6.Cu")
		(net "M_H_CPU0_SA_DQ<6>")
	)
	(segment
		(start 388.654036 -278.771604)
		(end 388.457186 -278.771604)
		(width 0.18288)
		(layer "In6.Cu")
		(net "M_H_CPU0_SA_DQ<6>")
	)
	(segment
		(start 408.586432 -301.006764)
		(end 408.586432 -300.752256)
		(width 0.18288)
		(layer "In6.Cu")
		(net "M_H_CPU0_SA_DQ<6>")
	)
	(segment
		(start 452.667878 -310.535574)
		(end 452.484744 -310.352948)
		(width 0.18288)
		(layer "In6.Cu")
		(net "M_H_CPU0_SA_DQ<6>")
	)
	(segment
		(start 409.439872 -300.592236)
		(end 409.279852 -300.752256)
		(width 0.18288)
		(layer "In6.Cu")
		(net "M_H_CPU0_SA_DQ<6>")
	)
	(segment
		(start 386.569712 -276.708616)
		(end 386.569712 -276.69871)
		(width 0.088646)
		(layer "In6.Cu")
		(net "M_H_CPU0_SA_DQ<6>")
	)
	(segment
		(start 454.031604 -308.837076)
		(end 453.799194 -309.069486)
		(width 0.18288)
		(layer "In6.Cu")
		(net "M_H_CPU0_SA_DQ<6>")
	)
	(segment
		(start 387.039612 -277.522432)
		(end 387.039612 -277.512526)
		(width 0.088646)
		(layer "In6.Cu")
		(net "M_H_CPU0_SA_DQ<6>")
	)
	(segment
		(start 389.192262 -278.994616)
		(end 388.654036 -278.771604)
		(width 0.18288)
		(layer "In6.Cu")
		(net "M_H_CPU0_SA_DQ<6>")
	)
	(segment
		(start 388.276592 -278.771604)
		(end 387.538468 -278.03348)
		(width 0.088646)
		(layer "In6.Cu")
		(net "M_H_CPU0_SA_DQ<6>")
	)
	(segment
		(start 411.310328 -301.940468)
		(end 409.962096 -300.592236)
		(width 0.18288)
		(layer "In6.Cu")
		(net "M_H_CPU0_SA_DQ<6>")
	)
	(segment
		(start 452.484744 -310.352948)
		(end 452.484744 -309.25262)
		(width 0.18288)
		(layer "In6.Cu")
		(net "M_H_CPU0_SA_DQ<6>")
	)
	(segment
		(start 442.864494 -308.061614)
		(end 441.164218 -308.061614)
		(width 0.18288)
		(layer "In6.Cu")
		(net "M_H_CPU0_SA_DQ<6>")
	)
	(segment
		(start 397.90751 -282.73756)
		(end 394.164566 -278.994616)
		(width 0.18288)
		(layer "In6.Cu")
		(net "M_H_CPU0_SA_DQ<6>")
	)
	(segment
		(start 431.14976 -308.386226)
		(end 430.38776 -308.386226)
		(width 0.18288)
		(layer "In6.Cu")
		(net "M_H_CPU0_SA_DQ<6>")
	)
	(segment
		(start 409.025344 -301.166784)
		(end 408.746452 -301.166784)
		(width 0.18288)
		(layer "In6.Cu")
		(net "M_H_CPU0_SA_DQ<6>")
	)
	(segment
		(start 452.324724 -309.0926)
		(end 450.728588 -309.0926)
		(width 0.18288)
		(layer "In6.Cu")
		(net "M_H_CPU0_SA_DQ<6>")
	)
	(segment
		(start 405.45131 -299.741336)
		(end 397.90751 -292.197536)
		(width 0.18288)
		(layer "In6.Cu")
		(net "M_H_CPU0_SA_DQ<6>")
	)
	(segment
		(start 426.446188 -305.871626)
		(end 425.416726 -304.842164)
		(width 0.18288)
		(layer "In6.Cu")
		(net "M_H_CPU0_SA_DQ<6>")
	)
	(segment
		(start 405.823674 -299.741336)
		(end 405.45131 -299.741336)
		(width 0.18288)
		(layer "In6.Cu")
		(net "M_H_CPU0_SA_DQ<6>")
	)
	(segment
		(start 419.955218 -305.692302)
		(end 419.801294 -305.846226)
		(width 0.18288)
		(layer "In6.Cu")
		(net "M_H_CPU0_SA_DQ<6>")
	)
	(segment
		(start 436.296562 -309.092346)
		(end 431.85588 -309.092346)
		(width 0.18288)
		(layer "In6.Cu")
		(net "M_H_CPU0_SA_DQ<6>")
	)
	(segment
		(start 408.586432 -300.752256)
		(end 408.426412 -300.592236)
		(width 0.18288)
		(layer "In6.Cu")
		(net "M_H_CPU0_SA_DQ<6>")
	)
	(segment
		(start 408.053032 -300.592236)
		(end 407.893012 -300.752256)
		(width 0.18288)
		(layer "In6.Cu")
		(net "M_H_CPU0_SA_DQ<6>")
	)
	(segment
		(start 383.467864 -276.219158)
		(end 383.453132 -276.210522)
		(width 0.088646)
		(layer "In6.Cu")
		(net "M_H_CPU0_SA_DQ<6>")
	)
	(segment
		(start 394.164566 -278.994616)
		(end 389.192262 -278.994616)
		(width 0.18288)
		(layer "In6.Cu")
		(net "M_H_CPU0_SA_DQ<6>")
	)
	(segment
		(start 377.18746 -276.27199)
		(end 376.606816 -276.708616)
		(width 0.088646)
		(layer "In6.Cu")
		(net "M_H_CPU0_SA_DQ<6>")
	)
	(segment
		(start 437.683148 -308.442614)
		(end 437.022748 -309.103014)
		(width 0.18288)
		(layer "In6.Cu")
		(net "M_H_CPU0_SA_DQ<6>")
	)
	(segment
		(start 448.212972 -309.335424)
		(end 446.609724 -309.335424)
		(width 0.18288)
		(layer "In6.Cu")
		(net "M_H_CPU0_SA_DQ<6>")
	)
	(segment
		(start 379.708664 -276.219158)
		(end 379.693932 -276.210522)
		(width 0.088646)
		(layer "In6.Cu")
		(net "M_H_CPU0_SA_DQ<6>")
	)
	(segment
		(start 387.440932 -278.03348)
		(end 387.344158 -277.936706)
		(width 0.088646)
		(layer "In6.Cu")
		(net "M_H_CPU0_SA_DQ<6>")
	)
	(segment
		(start 453.799194 -309.069486)
		(end 453.799194 -310.374284)
		(width 0.18288)
		(layer "In6.Cu")
		(net "M_H_CPU0_SA_DQ<6>")
	)
	(segment
		(start 454.331578 -308.837076)
		(end 454.031604 -308.837076)
		(width 0.18288)
		(layer "In6.Cu")
		(net "M_H_CPU0_SA_DQ<6>")
	)
	(segment
		(start 428.12716 -306.633626)
		(end 427.36516 -305.871626)
		(width 0.18288)
		(layer "In6.Cu")
		(net "M_H_CPU0_SA_DQ<6>")
	)
	(segment
		(start 407.199592 -301.475902)
		(end 407.199592 -300.752256)
		(width 0.18288)
		(layer "In6.Cu")
		(net "M_H_CPU0_SA_DQ<6>")
	)
	(segment
		(start 407.893012 -301.475902)
		(end 407.732992 -301.635922)
		(width 0.18288)
		(layer "In6.Cu")
		(net "M_H_CPU0_SA_DQ<6>")
	)
	(segment
		(start 453.63892 -310.534558)
		(end 453.318118 -310.534558)
		(width 0.18288)
		(layer "In6.Cu")
		(net "M_H_CPU0_SA_DQ<6>")
	)
	(segment
		(start 422.150032 -304.842164)
		(end 421.299894 -305.692302)
		(width 0.18288)
		(layer "In6.Cu")
		(net "M_H_CPU0_SA_DQ<6>")
	)
	(segment
		(start 416.02787 -304.943002)
		(end 415.303208 -304.943002)
		(width 0.18288)
		(layer "In6.Cu")
		(net "M_H_CPU0_SA_DQ<6>")
	)
	(segment
		(start 448.395852 -309.152544)
		(end 448.212972 -309.335424)
		(width 0.18288)
		(layer "In6.Cu")
		(net "M_H_CPU0_SA_DQ<6>")
	)
	(segment
		(start 408.426412 -300.592236)
		(end 408.053032 -300.592236)
		(width 0.18288)
		(layer "In6.Cu")
		(net "M_H_CPU0_SA_DQ<6>")
	)
	(segment
		(start 445.225678 -308.874414)
		(end 444.768478 -308.417214)
		(width 0.18288)
		(layer "In6.Cu")
		(net "M_H_CPU0_SA_DQ<6>")
	)
	(segment
		(start 382.528064 -276.219158)
		(end 382.513332 -276.210522)
		(width 0.088646)
		(layer "In6.Cu")
		(net "M_H_CPU0_SA_DQ<6>")
	)
	(segment
		(start 431.85588 -309.092346)
		(end 431.14976 -308.386226)
		(width 0.18288)
		(layer "In6.Cu")
		(net "M_H_CPU0_SA_DQ<6>")
	)
	(segment
		(start 441.164218 -308.061614)
		(end 440.983116 -308.242716)
		(width 0.18288)
		(layer "In6.Cu")
		(net "M_H_CPU0_SA_DQ<6>")
	)
	(segment
		(start 449.089272 -309.152544)
		(end 449.089272 -308.74335)
		(width 0.18288)
		(layer "In6.Cu")
		(net "M_H_CPU0_SA_DQ<6>")
	)
	(segment
		(start 425.416726 -304.842164)
		(end 422.150032 -304.842164)
		(width 0.18288)
		(layer "In6.Cu")
		(net "M_H_CPU0_SA_DQ<6>")
	)
	(segment
		(start 446.148714 -308.874414)
		(end 445.225678 -308.874414)
		(width 0.18288)
		(layer "In6.Cu")
		(net "M_H_CPU0_SA_DQ<6>")
	)
	(segment
		(start 449.272152 -309.335424)
		(end 449.089272 -309.152544)
		(width 0.18288)
		(layer "In6.Cu")
		(net "M_H_CPU0_SA_DQ<6>")
	)
	(segment
		(start 437.022748 -309.103014)
		(end 436.30723 -309.103014)
		(width 0.18288)
		(layer "In6.Cu")
		(net "M_H_CPU0_SA_DQ<6>")
	)
	(segment
		(start 412.300674 -301.940468)
		(end 411.310328 -301.940468)
		(width 0.18288)
		(layer "In6.Cu")
		(net "M_H_CPU0_SA_DQ<6>")
	)
	(segment
		(start 453.799194 -310.374284)
		(end 453.63892 -310.534558)
		(width 0.18288)
		(layer "In6.Cu")
		(net "M_H_CPU0_SA_DQ<6>")
	)
	(segment
		(start 407.199592 -300.752256)
		(end 407.039572 -300.592236)
		(width 0.18288)
		(layer "In6.Cu")
		(net "M_H_CPU0_SA_DQ<6>")
	)
	(segment
		(start 455.011282 -309.51678)
		(end 454.331578 -308.837076)
		(width 0.18288)
		(layer "In6.Cu")
		(net "M_H_CPU0_SA_DQ<6>")
	)
	(segment
		(start 381.588264 -276.219158)
		(end 381.573532 -276.210522)
		(width 0.088646)
		(layer "In6.Cu")
		(net "M_H_CPU0_SA_DQ<6>")
	)
	(segment
		(start 416.931094 -305.846226)
		(end 416.02787 -304.943002)
		(width 0.18288)
		(layer "In6.Cu")
		(net "M_H_CPU0_SA_DQ<6>")
	)
	(segment
		(start 386.757164 -277.032974)
		(end 386.748274 -277.027894)
		(width 0.088646)
		(layer "In6.Cu")
		(net "M_H_CPU0_SA_DQ<6>")
	)
	(segment
		(start 427.36516 -305.871626)
		(end 426.446188 -305.871626)
		(width 0.18288)
		(layer "In6.Cu")
		(net "M_H_CPU0_SA_DQ<6>")
	)
	(segment
		(start 452.484744 -309.25262)
		(end 452.324724 -309.0926)
		(width 0.18288)
		(layer "In6.Cu")
		(net "M_H_CPU0_SA_DQ<6>")
	)
	(segment
		(start 388.457186 -278.771604)
		(end 388.276592 -278.771604)
		(width 0.088646)
		(layer "In6.Cu")
		(net "M_H_CPU0_SA_DQ<6>")
	)
	(segment
		(start 387.538468 -278.03348)
		(end 387.440932 -278.03348)
		(width 0.088646)
		(layer "In6.Cu")
		(net "M_H_CPU0_SA_DQ<6>")
	)
	(segment
		(start 436.30723 -309.103014)
		(end 436.296562 -309.092346)
		(width 0.18288)
		(layer "In6.Cu")
		(net "M_H_CPU0_SA_DQ<6>")
	)
	(segment
		(start 377.829064 -276.219158)
		(end 377.81865 -276.213062)
		(width 0.088646)
		(layer "In6.Cu")
		(net "M_H_CPU0_SA_DQ<6>")
	)
	(segment
		(start 430.38776 -308.386226)
		(end 428.63516 -306.633626)
		(width 0.18288)
		(layer "In6.Cu")
		(net "M_H_CPU0_SA_DQ<6>")
	)
	(segment
		(start 449.089272 -308.74335)
		(end 448.906392 -308.56047)
		(width 0.18288)
		(layer "In6.Cu")
		(net "M_H_CPU0_SA_DQ<6>")
	)
	(segment
		(start 408.746452 -301.166784)
		(end 408.586432 -301.006764)
		(width 0.18288)
		(layer "In6.Cu")
		(net "M_H_CPU0_SA_DQ<6>")
	)
	(segment
		(start 378.768864 -276.219158)
		(end 378.754132 -276.210522)
		(width 0.088646)
		(layer "In6.Cu")
		(net "M_H_CPU0_SA_DQ<6>")
	)
	(segment
		(start 409.279852 -300.752256)
		(end 409.279852 -300.912276)
		(width 0.18288)
		(layer "In6.Cu")
		(net "M_H_CPU0_SA_DQ<6>")
	)
	(segment
		(start 407.039572 -300.592236)
		(end 406.674574 -300.592236)
		(width 0.18288)
		(layer "In6.Cu")
		(net "M_H_CPU0_SA_DQ<6>")
	)
	(segment
		(start 443.220094 -308.417214)
		(end 442.864494 -308.061614)
		(width 0.18288)
		(layer "In6.Cu")
		(net "M_H_CPU0_SA_DQ<6>")
	)
	(segment
		(start 438.924192 -308.242716)
		(end 438.724294 -308.442614)
		(width 0.18288)
		(layer "In6.Cu")
		(net "M_H_CPU0_SA_DQ<6>")
	)
	(segment
		(start 448.395852 -308.74335)
		(end 448.395852 -309.152544)
		(width 0.18288)
		(layer "In6.Cu")
		(net "M_H_CPU0_SA_DQ<6>")
	)
	(segment
		(start 419.801294 -305.846226)
		(end 416.931094 -305.846226)
		(width 0.18288)
		(layer "In6.Cu")
		(net "M_H_CPU0_SA_DQ<6>")
	)
	(arc
		(start 381.02286 -276.219158)
		(mid 380.835662 -276.269301)
		(end 380.648464 -276.219158)
		(width 0.088646)
		(layer "In6.Cu")
		(net "M_H_CPU0_SA_DQ<6>")
	)
	(arc
		(start 387.039612 -277.512526)
		(mid 386.961501 -277.235577)
		(end 386.757164 -277.032974)
		(width 0.088646)
		(layer "In6.Cu")
		(net "M_H_CPU0_SA_DQ<6>")
	)
	(arc
		(start 382.513332 -276.210522)
		(mid 382.236857 -276.143202)
		(end 381.96266 -276.219158)
		(width 0.088646)
		(layer "In6.Cu")
		(net "M_H_CPU0_SA_DQ<6>")
	)
	(arc
		(start 378.20346 -276.219158)
		(mid 378.016262 -276.269301)
		(end 377.829064 -276.219158)
		(width 0.088646)
		(layer "In6.Cu")
		(net "M_H_CPU0_SA_DQ<6>")
	)
	(arc
		(start 383.84226 -276.219158)
		(mid 383.655062 -276.269301)
		(end 383.467864 -276.219158)
		(width 0.088646)
		(layer "In6.Cu")
		(net "M_H_CPU0_SA_DQ<6>")
	)
	(arc
		(start 386.748274 -277.027894)
		(mid 386.61736 -276.891534)
		(end 386.569712 -276.708616)
		(width 0.088646)
		(layer "In6.Cu")
		(net "M_H_CPU0_SA_DQ<6>")
	)
	(arc
		(start 382.90246 -276.219158)
		(mid 382.715262 -276.269301)
		(end 382.528064 -276.219158)
		(width 0.088646)
		(layer "In6.Cu")
		(net "M_H_CPU0_SA_DQ<6>")
	)
	(arc
		(start 385.72186 -276.219158)
		(mid 385.534662 -276.269301)
		(end 385.347464 -276.219158)
		(width 0.088646)
		(layer "In6.Cu")
		(net "M_H_CPU0_SA_DQ<6>")
	)
	(arc
		(start 377.81865 -276.213062)
		(mid 377.540472 -276.143339)
		(end 377.263914 -276.219158)
		(width 0.088646)
		(layer "In6.Cu")
		(net "M_H_CPU0_SA_DQ<6>")
	)
	(arc
		(start 379.693932 -276.210522)
		(mid 379.417457 -276.143202)
		(end 379.14326 -276.219158)
		(width 0.088646)
		(layer "In6.Cu")
		(net "M_H_CPU0_SA_DQ<6>")
	)
	(arc
		(start 385.347464 -276.219158)
		(mid 385.064762 -276.143382)
		(end 384.78206 -276.219158)
		(width 0.088646)
		(layer "In6.Cu")
		(net "M_H_CPU0_SA_DQ<6>")
	)
	(arc
		(start 377.263914 -276.219158)
		(mid 377.224593 -276.243992)
		(end 377.18746 -276.27199)
		(width 0.088646)
		(layer "In6.Cu")
		(net "M_H_CPU0_SA_DQ<6>")
	)
	(arc
		(start 386.569712 -276.69871)
		(mid 386.491601 -276.421761)
		(end 386.287264 -276.219158)
		(width 0.088646)
		(layer "In6.Cu")
		(net "M_H_CPU0_SA_DQ<6>")
	)
	(arc
		(start 384.78206 -276.219158)
		(mid 384.594862 -276.269301)
		(end 384.407664 -276.219158)
		(width 0.088646)
		(layer "In6.Cu")
		(net "M_H_CPU0_SA_DQ<6>")
	)
	(arc
		(start 386.287264 -276.219158)
		(mid 386.004562 -276.143382)
		(end 385.72186 -276.219158)
		(width 0.088646)
		(layer "In6.Cu")
		(net "M_H_CPU0_SA_DQ<6>")
	)
	(arc
		(start 384.407664 -276.219158)
		(mid 384.124962 -276.143382)
		(end 383.84226 -276.219158)
		(width 0.088646)
		(layer "In6.Cu")
		(net "M_H_CPU0_SA_DQ<6>")
	)
	(arc
		(start 381.96266 -276.219158)
		(mid 381.775462 -276.269301)
		(end 381.588264 -276.219158)
		(width 0.088646)
		(layer "In6.Cu")
		(net "M_H_CPU0_SA_DQ<6>")
	)
	(arc
		(start 378.754132 -276.210522)
		(mid 378.477657 -276.143202)
		(end 378.20346 -276.219158)
		(width 0.088646)
		(layer "In6.Cu")
		(net "M_H_CPU0_SA_DQ<6>")
	)
	(arc
		(start 383.453132 -276.210522)
		(mid 383.176657 -276.143202)
		(end 382.90246 -276.219158)
		(width 0.088646)
		(layer "In6.Cu")
		(net "M_H_CPU0_SA_DQ<6>")
	)
	(arc
		(start 380.08306 -276.219158)
		(mid 379.895862 -276.269301)
		(end 379.708664 -276.219158)
		(width 0.088646)
		(layer "In6.Cu")
		(net "M_H_CPU0_SA_DQ<6>")
	)
	(arc
		(start 379.14326 -276.219158)
		(mid 378.956062 -276.269301)
		(end 378.768864 -276.219158)
		(width 0.088646)
		(layer "In6.Cu")
		(net "M_H_CPU0_SA_DQ<6>")
	)
	(arc
		(start 380.648464 -276.219158)
		(mid 380.365762 -276.143382)
		(end 380.08306 -276.219158)
		(width 0.088646)
		(layer "In6.Cu")
		(net "M_H_CPU0_SA_DQ<6>")
	)
	(arc
		(start 387.218174 -277.84171)
		(mid 387.08726 -277.70535)
		(end 387.039612 -277.522432)
		(width 0.088646)
		(layer "In6.Cu")
		(net "M_H_CPU0_SA_DQ<6>")
	)
	(arc
		(start 381.573532 -276.210522)
		(mid 381.297057 -276.143202)
		(end 381.02286 -276.219158)
		(width 0.088646)
		(layer "In6.Cu")
		(net "M_H_CPU0_SA_DQ<6>")
	)
	(arc
		(start 387.344158 -277.936706)
		(mid 387.284495 -277.884794)
		(end 387.218174 -277.84171)
		(width 0.088646)
		(layer "In6.Cu")
		(net "M_H_CPU0_SA_DQ<6>")
	)
	(segment
		(start 454.91146 -308.2417)
		(end 454.566782 -308.2417)
		(width 0.20066)
		(layer "F.Cu")
		(net "M_H_CPU0_SA_DQ<5>")
	)
	(segment
		(start 457.126594 -308.23535)
		(end 457.120244 -308.2417)
		(width 0.1016)
		(layer "F.Cu")
		(net "M_H_CPU0_SA_DQ<5>")
	)
	(segment
		(start 375.197116 -275.35886)
		(end 375.197116 -275.894546)
		(width 0.20066)
		(layer "F.Cu")
		(net "M_H_CPU0_SA_DQ<5>")
	)
	(segment
		(start 454.260712 -308.915308)
		(end 453.785478 -308.915308)
		(width 0.20066)
		(layer "F.Cu")
		(net "M_H_CPU0_SA_DQ<5>")
	)
	(segment
		(start 459.55966 -308.666896)
		(end 457.968096 -308.666896)
		(width 0.20066)
		(layer "F.Cu")
		(net "M_H_CPU0_SA_DQ<5>")
	)
	(segment
		(start 459.559914 -308.666642)
		(end 459.55966 -308.666896)
		(width 0.20066)
		(layer "F.Cu")
		(net "M_H_CPU0_SA_DQ<5>")
	)
	(segment
		(start 453.785478 -308.915308)
		(end 453.536812 -308.666642)
		(width 0.20066)
		(layer "F.Cu")
		(net "M_H_CPU0_SA_DQ<5>")
	)
	(segment
		(start 454.931526 -308.2417)
		(end 454.91146 -308.2417)
		(width 0.101854)
		(layer "F.Cu")
		(net "M_H_CPU0_SA_DQ<5>")
	)
	(segment
		(start 454.566782 -308.2417)
		(end 454.448672 -308.35981)
		(width 0.20066)
		(layer "F.Cu")
		(net "M_H_CPU0_SA_DQ<5>")
	)
	(segment
		(start 457.120244 -308.2417)
		(end 454.931526 -308.2417)
		(width 0.1016)
		(layer "F.Cu")
		(net "M_H_CPU0_SA_DQ<5>")
	)
	(segment
		(start 457.53655 -308.23535)
		(end 457.126594 -308.23535)
		(width 0.20066)
		(layer "F.Cu")
		(net "M_H_CPU0_SA_DQ<5>")
	)
	(segment
		(start 452.016114 -308.666642)
		(end 450.911214 -308.666642)
		(width 0.20066)
		(layer "F.Cu")
		(net "M_H_CPU0_SA_DQ<5>")
	)
	(segment
		(start 454.448672 -308.35981)
		(end 454.448672 -308.727348)
		(width 0.20066)
		(layer "F.Cu")
		(net "M_H_CPU0_SA_DQ<5>")
	)
	(segment
		(start 454.448672 -308.727348)
		(end 454.260712 -308.915308)
		(width 0.20066)
		(layer "F.Cu")
		(net "M_H_CPU0_SA_DQ<5>")
	)
	(segment
		(start 375.197116 -275.894546)
		(end 375.196862 -275.8948)
		(width 0.20066)
		(layer "F.Cu")
		(net "M_H_CPU0_SA_DQ<5>")
	)
	(segment
		(start 457.968096 -308.666896)
		(end 457.53655 -308.23535)
		(width 0.20066)
		(layer "F.Cu")
		(net "M_H_CPU0_SA_DQ<5>")
	)
	(segment
		(start 453.536812 -308.666642)
		(end 452.016114 -308.666642)
		(width 0.20066)
		(layer "F.Cu")
		(net "M_H_CPU0_SA_DQ<5>")
	)
	(segment
		(start 411.133798 -300.872906)
		(end 410.830522 -300.747176)
		(width 0.18288)
		(layer "In6.Cu")
		(net "M_H_CPU0_SA_DQ<5>")
	)
	(segment
		(start 432.865784 -308.242208)
		(end 431.887376 -308.242208)
		(width 0.18288)
		(layer "In6.Cu")
		(net "M_H_CPU0_SA_DQ<5>")
	)
	(segment
		(start 442.813694 -307.528214)
		(end 442.053218 -307.528214)
		(width 0.18288)
		(layer "In6.Cu")
		(net "M_H_CPU0_SA_DQ<5>")
	)
	(segment
		(start 415.646108 -303.801272)
		(end 415.987738 -303.459642)
		(width 0.18288)
		(layer "In6.Cu")
		(net "M_H_CPU0_SA_DQ<5>")
	)
	(segment
		(start 411.372304 -300.773846)
		(end 411.133798 -300.872906)
		(width 0.18288)
		(layer "In6.Cu")
		(net "M_H_CPU0_SA_DQ<5>")
	)
	(segment
		(start 415.87801 -304.291746)
		(end 415.646108 -304.059844)
		(width 0.18288)
		(layer "In6.Cu")
		(net "M_H_CPU0_SA_DQ<5>")
	)
	(segment
		(start 417.463986 -304.677318)
		(end 416.736784 -303.950116)
		(width 0.18288)
		(layer "In6.Cu")
		(net "M_H_CPU0_SA_DQ<5>")
	)
	(segment
		(start 408.705304 -300.034198)
		(end 408.413712 -299.742606)
		(width 0.18288)
		(layer "In6.Cu")
		(net "M_H_CPU0_SA_DQ<5>")
	)
	(segment
		(start 416.478212 -303.950116)
		(end 416.136582 -304.291746)
		(width 0.18288)
		(layer "In6.Cu")
		(net "M_H_CPU0_SA_DQ<5>")
	)
	(segment
		(start 418.764974 -304.860198)
		(end 418.764974 -305.159156)
		(width 0.18288)
		(layer "In6.Cu")
		(net "M_H_CPU0_SA_DQ<5>")
	)
	(segment
		(start 413.916114 -302.32985)
		(end 413.684212 -302.097948)
		(width 0.18288)
		(layer "In6.Cu")
		(net "M_H_CPU0_SA_DQ<5>")
	)
	(segment
		(start 388.1247 -278.267414)
		(end 387.319012 -277.461726)
		(width 0.088646)
		(layer "In6.Cu")
		(net "M_H_CPU0_SA_DQ<5>")
	)
	(segment
		(start 419.902132 -304.842164)
		(end 419.737286 -304.677318)
		(width 0.18288)
		(layer "In6.Cu")
		(net "M_H_CPU0_SA_DQ<5>")
	)
	(segment
		(start 416.736784 -303.950116)
		(end 416.478212 -303.950116)
		(width 0.18288)
		(layer "In6.Cu")
		(net "M_H_CPU0_SA_DQ<5>")
	)
	(segment
		(start 398.40535 -282.531312)
		(end 394.370814 -278.496776)
		(width 0.18288)
		(layer "In6.Cu")
		(net "M_H_CPU0_SA_DQ<5>")
	)
	(segment
		(start 414.66516 -303.078896)
		(end 414.66516 -302.820324)
		(width 0.18288)
		(layer "In6.Cu")
		(net "M_H_CPU0_SA_DQ<5>")
	)
	(segment
		(start 386.287264 -275.570442)
		(end 386.272532 -275.579078)
		(width 0.088646)
		(layer "In6.Cu")
		(net "M_H_CPU0_SA_DQ<5>")
	)
	(segment
		(start 405.018494 -297.97121)
		(end 398.40535 -291.358066)
		(width 0.18288)
		(layer "In6.Cu")
		(net "M_H_CPU0_SA_DQ<5>")
	)
	(segment
		(start 378.768864 -275.570442)
		(end 378.754132 -275.579078)
		(width 0.088646)
		(layer "In6.Cu")
		(net "M_H_CPU0_SA_DQ<5>")
	)
	(segment
		(start 376.889518 -275.570442)
		(end 376.880628 -275.575522)
		(width 0.088646)
		(layer "In6.Cu")
		(net "M_H_CPU0_SA_DQ<5>")
	)
	(segment
		(start 382.528064 -275.570442)
		(end 382.513332 -275.579078)
		(width 0.088646)
		(layer "In6.Cu")
		(net "M_H_CPU0_SA_DQ<5>")
	)
	(segment
		(start 415.00679 -302.478694)
		(end 415.00679 -302.220122)
		(width 0.18288)
		(layer "In6.Cu")
		(net "M_H_CPU0_SA_DQ<5>")
	)
	(segment
		(start 430.939194 -307.294026)
		(end 430.100994 -307.294026)
		(width 0.18288)
		(layer "In6.Cu")
		(net "M_H_CPU0_SA_DQ<5>")
	)
	(segment
		(start 409.427172 -299.742606)
		(end 409.13558 -300.034198)
		(width 0.18288)
		(layer "In6.Cu")
		(net "M_H_CPU0_SA_DQ<5>")
	)
	(segment
		(start 415.155634 -303.310798)
		(end 414.897062 -303.310798)
		(width 0.18288)
		(layer "In6.Cu")
		(net "M_H_CPU0_SA_DQ<5>")
	)
	(segment
		(start 413.684212 -302.097948)
		(end 413.684212 -301.839376)
		(width 0.18288)
		(layer "In6.Cu")
		(net "M_H_CPU0_SA_DQ<5>")
	)
	(segment
		(start 446.522856 -307.934868)
		(end 446.1129 -308.344824)
		(width 0.18288)
		(layer "In6.Cu")
		(net "M_H_CPU0_SA_DQ<5>")
	)
	(segment
		(start 388.307326 -278.267414)
		(end 388.1247 -278.267414)
		(width 0.088646)
		(layer "In6.Cu")
		(net "M_H_CPU0_SA_DQ<5>")
	)
	(segment
		(start 439.479944 -307.392578)
		(end 439.167016 -307.705506)
		(width 0.18288)
		(layer "In6.Cu")
		(net "M_H_CPU0_SA_DQ<5>")
	)
	(segment
		(start 424.297856 -303.992026)
		(end 423.996358 -304.293524)
		(width 0.18288)
		(layer "In6.Cu")
		(net "M_H_CPU0_SA_DQ<5>")
	)
	(segment
		(start 437.251094 -308.059582)
		(end 437.068468 -308.242208)
		(width 0.18288)
		(layer "In6.Cu")
		(net "M_H_CPU0_SA_DQ<5>")
	)
	(segment
		(start 430.100994 -307.294026)
		(end 428.272194 -305.465226)
		(width 0.18288)
		(layer "In6.Cu")
		(net "M_H_CPU0_SA_DQ<5>")
	)
	(segment
		(start 419.737286 -304.677318)
		(end 418.947854 -304.677318)
		(width 0.18288)
		(layer "In6.Cu")
		(net "M_H_CPU0_SA_DQ<5>")
	)
	(segment
		(start 449.621148 -307.934868)
		(end 446.522856 -307.934868)
		(width 0.18288)
		(layer "In6.Cu")
		(net "M_H_CPU0_SA_DQ<5>")
	)
	(segment
		(start 406.8191 -299.790866)
		(end 406.59304 -299.790866)
		(width 0.18288)
		(layer "In6.Cu")
		(net "M_H_CPU0_SA_DQ<5>")
	)
	(segment
		(start 387.14045 -276.389338)
		(end 387.13156 -276.384258)
		(width 0.088646)
		(layer "In6.Cu")
		(net "M_H_CPU0_SA_DQ<5>")
	)
	(segment
		(start 407.623264 -299.742606)
		(end 407.358342 -299.477684)
		(width 0.18288)
		(layer "In6.Cu")
		(net "M_H_CPU0_SA_DQ<5>")
	)
	(segment
		(start 440.43854 -307.392578)
		(end 439.479944 -307.392578)
		(width 0.18288)
		(layer "In6.Cu")
		(net "M_H_CPU0_SA_DQ<5>")
	)
	(segment
		(start 380.648464 -275.570442)
		(end 380.633732 -275.579078)
		(width 0.088646)
		(layer "In6.Cu")
		(net "M_H_CPU0_SA_DQ<5>")
	)
	(segment
		(start 423.604436 -304.293524)
		(end 423.302938 -303.992026)
		(width 0.18288)
		(layer "In6.Cu")
		(net "M_H_CPU0_SA_DQ<5>")
	)
	(segment
		(start 377.829064 -275.570442)
		(end 377.81865 -275.576538)
		(width 0.088646)
		(layer "In6.Cu")
		(net "M_H_CPU0_SA_DQ<5>")
	)
	(segment
		(start 423.302938 -303.992026)
		(end 422.036494 -303.992026)
		(width 0.18288)
		(layer "In6.Cu")
		(net "M_H_CPU0_SA_DQ<5>")
	)
	(segment
		(start 414.66516 -302.820324)
		(end 415.00679 -302.478694)
		(width 0.18288)
		(layer "In6.Cu")
		(net "M_H_CPU0_SA_DQ<5>")
	)
	(segment
		(start 450.352922 -308.666642)
		(end 449.621148 -307.934868)
		(width 0.18288)
		(layer "In6.Cu")
		(net "M_H_CPU0_SA_DQ<5>")
	)
	(segment
		(start 414.025842 -301.239174)
		(end 413.811974 -301.025306)
		(width 0.18288)
		(layer "In6.Cu")
		(net "M_H_CPU0_SA_DQ<5>")
	)
	(segment
		(start 394.370814 -278.496776)
		(end 389.29183 -278.496776)
		(width 0.18288)
		(layer "In6.Cu")
		(net "M_H_CPU0_SA_DQ<5>")
	)
	(segment
		(start 410.78658 -299.897292)
		(end 410.413454 -299.742606)
		(width 0.18288)
		(layer "In6.Cu")
		(net "M_H_CPU0_SA_DQ<5>")
	)
	(segment
		(start 438.786524 -307.705506)
		(end 438.473596 -307.392578)
		(width 0.18288)
		(layer "In6.Cu")
		(net "M_H_CPU0_SA_DQ<5>")
	)
	(segment
		(start 383.467864 -275.570442)
		(end 383.453132 -275.579078)
		(width 0.088646)
		(layer "In6.Cu")
		(net "M_H_CPU0_SA_DQ<5>")
	)
	(segment
		(start 410.88564 -300.136052)
		(end 410.78658 -299.897292)
		(width 0.18288)
		(layer "In6.Cu")
		(net "M_H_CPU0_SA_DQ<5>")
	)
	(segment
		(start 414.025842 -301.497746)
		(end 414.025842 -301.239174)
		(width 0.18288)
		(layer "In6.Cu")
		(net "M_H_CPU0_SA_DQ<5>")
	)
	(segment
		(start 379.708664 -275.570442)
		(end 379.693932 -275.579078)
		(width 0.088646)
		(layer "In6.Cu")
		(net "M_H_CPU0_SA_DQ<5>")
	)
	(segment
		(start 389.29183 -278.496776)
		(end 388.73811 -278.267414)
		(width 0.18288)
		(layer "In6.Cu")
		(net "M_H_CPU0_SA_DQ<5>")
	)
	(segment
		(start 410.413454 -299.742606)
		(end 409.427172 -299.742606)
		(width 0.18288)
		(layer "In6.Cu")
		(net "M_H_CPU0_SA_DQ<5>")
	)
	(segment
		(start 439.167016 -307.705506)
		(end 438.786524 -307.705506)
		(width 0.18288)
		(layer "In6.Cu")
		(net "M_H_CPU0_SA_DQ<5>")
	)
	(segment
		(start 444.310262 -307.198014)
		(end 443.143894 -307.198014)
		(width 0.18288)
		(layer "In6.Cu")
		(net "M_H_CPU0_SA_DQ<5>")
	)
	(segment
		(start 410.830522 -300.747176)
		(end 410.731462 -300.508416)
		(width 0.18288)
		(layer "In6.Cu")
		(net "M_H_CPU0_SA_DQ<5>")
	)
	(segment
		(start 375.854214 -276.384258)
		(end 375.848118 -276.380702)
		(width 0.088646)
		(layer "In6.Cu")
		(net "M_H_CPU0_SA_DQ<5>")
	)
	(segment
		(start 407.132282 -299.477684)
		(end 406.8191 -299.790866)
		(width 0.18288)
		(layer "In6.Cu")
		(net "M_H_CPU0_SA_DQ<5>")
	)
	(segment
		(start 406.328626 -299.300392)
		(end 406.641808 -298.98721)
		(width 0.18288)
		(layer "In6.Cu")
		(net "M_H_CPU0_SA_DQ<5>")
	)
	(segment
		(start 446.1129 -308.344824)
		(end 445.457072 -308.344824)
		(width 0.18288)
		(layer "In6.Cu")
		(net "M_H_CPU0_SA_DQ<5>")
	)
	(segment
		(start 418.764974 -305.159156)
		(end 418.582094 -305.342036)
		(width 0.18288)
		(layer "In6.Cu")
		(net "M_H_CPU0_SA_DQ<5>")
	)
	(segment
		(start 418.071554 -304.860198)
		(end 417.888674 -304.677318)
		(width 0.18288)
		(layer "In6.Cu")
		(net "M_H_CPU0_SA_DQ<5>")
	)
	(segment
		(start 398.40535 -291.358066)
		(end 398.40535 -282.531312)
		(width 0.18288)
		(layer "In6.Cu")
		(net "M_H_CPU0_SA_DQ<5>")
	)
	(segment
		(start 418.071554 -305.159156)
		(end 418.071554 -304.860198)
		(width 0.18288)
		(layer "In6.Cu")
		(net "M_H_CPU0_SA_DQ<5>")
	)
	(segment
		(start 376.425714 -276.380702)
		(end 376.419618 -276.384258)
		(width 0.088646)
		(layer "In6.Cu")
		(net "M_H_CPU0_SA_DQ<5>")
	)
	(segment
		(start 440.59856 -307.222144)
		(end 440.59856 -307.232558)
		(width 0.18288)
		(layer "In6.Cu")
		(net "M_H_CPU0_SA_DQ<5>")
	)
	(segment
		(start 437.251094 -307.78831)
		(end 437.251094 -308.059582)
		(width 0.18288)
		(layer "In6.Cu")
		(net "M_H_CPU0_SA_DQ<5>")
	)
	(segment
		(start 415.987738 -303.459642)
		(end 415.987738 -303.20107)
		(width 0.18288)
		(layer "In6.Cu")
		(net "M_H_CPU0_SA_DQ<5>")
	)
	(segment
		(start 375.868946 -276.392894)
		(end 375.854214 -276.384258)
		(width 0.088646)
		(layer "In6.Cu")
		(net "M_H_CPU0_SA_DQ<5>")
	)
	(segment
		(start 431.887376 -308.242208)
		(end 430.939194 -307.294026)
		(width 0.18288)
		(layer "In6.Cu")
		(net "M_H_CPU0_SA_DQ<5>")
	)
	(segment
		(start 414.897062 -303.310798)
		(end 414.66516 -303.078896)
		(width 0.18288)
		(layer "In6.Cu")
		(net "M_H_CPU0_SA_DQ<5>")
	)
	(segment
		(start 415.987738 -303.20107)
		(end 415.755836 -302.969168)
		(width 0.18288)
		(layer "In6.Cu")
		(net "M_H_CPU0_SA_DQ<5>")
	)
	(segment
		(start 385.347464 -275.570442)
		(end 385.332732 -275.579078)
		(width 0.088646)
		(layer "In6.Cu")
		(net "M_H_CPU0_SA_DQ<5>")
	)
	(segment
		(start 418.582094 -305.342036)
		(end 418.254434 -305.342036)
		(width 0.18288)
		(layer "In6.Cu")
		(net "M_H_CPU0_SA_DQ<5>")
	)
	(segment
		(start 450.911214 -308.666642)
		(end 450.352922 -308.666642)
		(width 0.18288)
		(layer "In6.Cu")
		(net "M_H_CPU0_SA_DQ<5>")
	)
	(segment
		(start 421.186356 -304.842164)
		(end 419.902132 -304.842164)
		(width 0.18288)
		(layer "In6.Cu")
		(net "M_H_CPU0_SA_DQ<5>")
	)
	(segment
		(start 438.473596 -307.392578)
		(end 437.646826 -307.392578)
		(width 0.18288)
		(layer "In6.Cu")
		(net "M_H_CPU0_SA_DQ<5>")
	)
	(segment
		(start 412.277814 -300.514766)
		(end 411.765242 -300.302422)
		(width 0.18288)
		(layer "In6.Cu")
		(net "M_H_CPU0_SA_DQ<5>")
	)
	(segment
		(start 428.272194 -305.465226)
		(end 427.916594 -305.465226)
		(width 0.18288)
		(layer "In6.Cu")
		(net "M_H_CPU0_SA_DQ<5>")
	)
	(segment
		(start 416.136582 -304.291746)
		(end 415.87801 -304.291746)
		(width 0.18288)
		(layer "In6.Cu")
		(net "M_H_CPU0_SA_DQ<5>")
	)
	(segment
		(start 440.75858 -307.062124)
		(end 440.59856 -307.222144)
		(width 0.18288)
		(layer "In6.Cu")
		(net "M_H_CPU0_SA_DQ<5>")
	)
	(segment
		(start 415.00679 -302.220122)
		(end 414.774888 -301.98822)
		(width 0.18288)
		(layer "In6.Cu")
		(net "M_H_CPU0_SA_DQ<5>")
	)
	(segment
		(start 445.457072 -308.344824)
		(end 444.310262 -307.198014)
		(width 0.18288)
		(layer "In6.Cu")
		(net "M_H_CPU0_SA_DQ<5>")
	)
	(segment
		(start 406.641808 -298.98721)
		(end 406.641808 -298.76115)
		(width 0.18288)
		(layer "In6.Cu")
		(net "M_H_CPU0_SA_DQ<5>")
	)
	(segment
		(start 433.548028 -307.89499)
		(end 433.213002 -307.89499)
		(width 0.18288)
		(layer "In6.Cu")
		(net "M_H_CPU0_SA_DQ<5>")
	)
	(segment
		(start 413.811974 -301.025306)
		(end 412.788354 -301.025306)
		(width 0.18288)
		(layer "In6.Cu")
		(net "M_H_CPU0_SA_DQ<5>")
	)
	(segment
		(start 437.068468 -308.242208)
		(end 433.895246 -308.242208)
		(width 0.18288)
		(layer "In6.Cu")
		(net "M_H_CPU0_SA_DQ<5>")
	)
	(segment
		(start 388.73811 -278.267414)
		(end 388.307326 -278.267414)
		(width 0.18288)
		(layer "In6.Cu")
		(net "M_H_CPU0_SA_DQ<5>")
	)
	(segment
		(start 415.646108 -304.059844)
		(end 415.646108 -303.801272)
		(width 0.18288)
		(layer "In6.Cu")
		(net "M_H_CPU0_SA_DQ<5>")
	)
	(segment
		(start 440.59856 -307.232558)
		(end 440.43854 -307.392578)
		(width 0.18288)
		(layer "In6.Cu")
		(net "M_H_CPU0_SA_DQ<5>")
	)
	(segment
		(start 423.996358 -304.293524)
		(end 423.604436 -304.293524)
		(width 0.18288)
		(layer "In6.Cu")
		(net "M_H_CPU0_SA_DQ<5>")
	)
	(segment
		(start 405.851868 -297.97121)
		(end 405.018494 -297.97121)
		(width 0.18288)
		(layer "In6.Cu")
		(net "M_H_CPU0_SA_DQ<5>")
	)
	(segment
		(start 442.053218 -307.528214)
		(end 441.587128 -307.062124)
		(width 0.18288)
		(layer "In6.Cu")
		(net "M_H_CPU0_SA_DQ<5>")
	)
	(segment
		(start 386.67055 -275.575522)
		(end 386.66166 -275.570442)
		(width 0.088646)
		(layer "In6.Cu")
		(net "M_H_CPU0_SA_DQ<5>")
	)
	(segment
		(start 375.575322 -275.960586)
		(end 375.509536 -275.8948)
		(width 0.088646)
		(layer "In6.Cu")
		(net "M_H_CPU0_SA_DQ<5>")
	)
	(segment
		(start 406.328626 -299.526452)
		(end 406.328626 -299.300392)
		(width 0.18288)
		(layer "In6.Cu")
		(net "M_H_CPU0_SA_DQ<5>")
	)
	(segment
		(start 415.497264 -302.969168)
		(end 415.155634 -303.310798)
		(width 0.18288)
		(layer "In6.Cu")
		(net "M_H_CPU0_SA_DQ<5>")
	)
	(segment
		(start 418.254434 -305.342036)
		(end 418.071554 -305.159156)
		(width 0.18288)
		(layer "In6.Cu")
		(net "M_H_CPU0_SA_DQ<5>")
	)
	(segment
		(start 427.154594 -304.703226)
		(end 426.06849 -304.703226)
		(width 0.18288)
		(layer "In6.Cu")
		(net "M_H_CPU0_SA_DQ<5>")
	)
	(segment
		(start 426.06849 -304.703226)
		(end 425.35729 -303.992026)
		(width 0.18288)
		(layer "In6.Cu")
		(net "M_H_CPU0_SA_DQ<5>")
	)
	(segment
		(start 414.174686 -302.32985)
		(end 413.916114 -302.32985)
		(width 0.18288)
		(layer "In6.Cu")
		(net "M_H_CPU0_SA_DQ<5>")
	)
	(segment
		(start 406.59304 -299.790866)
		(end 406.328626 -299.526452)
		(width 0.18288)
		(layer "In6.Cu")
		(net "M_H_CPU0_SA_DQ<5>")
	)
	(segment
		(start 411.765242 -300.302422)
		(end 411.526482 -300.401482)
		(width 0.18288)
		(layer "In6.Cu")
		(net "M_H_CPU0_SA_DQ<5>")
	)
	(segment
		(start 433.895246 -308.242208)
		(end 433.548028 -307.89499)
		(width 0.18288)
		(layer "In6.Cu")
		(net "M_H_CPU0_SA_DQ<5>")
	)
	(segment
		(start 411.526482 -300.401482)
		(end 411.372304 -300.773846)
		(width 0.18288)
		(layer "In6.Cu")
		(net "M_H_CPU0_SA_DQ<5>")
	)
	(segment
		(start 433.213002 -307.89499)
		(end 432.865784 -308.242208)
		(width 0.18288)
		(layer "In6.Cu")
		(net "M_H_CPU0_SA_DQ<5>")
	)
	(segment
		(start 441.587128 -307.062124)
		(end 440.75858 -307.062124)
		(width 0.18288)
		(layer "In6.Cu")
		(net "M_H_CPU0_SA_DQ<5>")
	)
	(segment
		(start 406.641808 -298.76115)
		(end 405.851868 -297.97121)
		(width 0.18288)
		(layer "In6.Cu")
		(net "M_H_CPU0_SA_DQ<5>")
	)
	(segment
		(start 408.413712 -299.742606)
		(end 407.623264 -299.742606)
		(width 0.18288)
		(layer "In6.Cu")
		(net "M_H_CPU0_SA_DQ<5>")
	)
	(segment
		(start 422.036494 -303.992026)
		(end 421.186356 -304.842164)
		(width 0.18288)
		(layer "In6.Cu")
		(net "M_H_CPU0_SA_DQ<5>")
	)
	(segment
		(start 414.516316 -301.98822)
		(end 414.174686 -302.32985)
		(width 0.18288)
		(layer "In6.Cu")
		(net "M_H_CPU0_SA_DQ<5>")
	)
	(segment
		(start 414.774888 -301.98822)
		(end 414.516316 -301.98822)
		(width 0.18288)
		(layer "In6.Cu")
		(net "M_H_CPU0_SA_DQ<5>")
	)
	(segment
		(start 387.319012 -277.461726)
		(end 387.319012 -276.708616)
		(width 0.088646)
		(layer "In6.Cu")
		(net "M_H_CPU0_SA_DQ<5>")
	)
	(segment
		(start 375.509536 -275.8948)
		(end 375.196862 -275.8948)
		(width 0.088646)
		(layer "In6.Cu")
		(net "M_H_CPU0_SA_DQ<5>")
	)
	(segment
		(start 425.35729 -303.992026)
		(end 424.297856 -303.992026)
		(width 0.18288)
		(layer "In6.Cu")
		(net "M_H_CPU0_SA_DQ<5>")
	)
	(segment
		(start 412.788354 -301.025306)
		(end 412.277814 -300.514766)
		(width 0.18288)
		(layer "In6.Cu")
		(net "M_H_CPU0_SA_DQ<5>")
	)
	(segment
		(start 410.731462 -300.508416)
		(end 410.88564 -300.136052)
		(width 0.18288)
		(layer "In6.Cu")
		(net "M_H_CPU0_SA_DQ<5>")
	)
	(segment
		(start 418.947854 -304.677318)
		(end 418.764974 -304.860198)
		(width 0.18288)
		(layer "In6.Cu")
		(net "M_H_CPU0_SA_DQ<5>")
	)
	(segment
		(start 443.143894 -307.198014)
		(end 442.813694 -307.528214)
		(width 0.18288)
		(layer "In6.Cu")
		(net "M_H_CPU0_SA_DQ<5>")
	)
	(segment
		(start 437.646826 -307.392578)
		(end 437.251094 -307.78831)
		(width 0.18288)
		(layer "In6.Cu")
		(net "M_H_CPU0_SA_DQ<5>")
	)
	(segment
		(start 407.358342 -299.477684)
		(end 407.132282 -299.477684)
		(width 0.18288)
		(layer "In6.Cu")
		(net "M_H_CPU0_SA_DQ<5>")
	)
	(segment
		(start 409.13558 -300.034198)
		(end 408.705304 -300.034198)
		(width 0.18288)
		(layer "In6.Cu")
		(net "M_H_CPU0_SA_DQ<5>")
	)
	(segment
		(start 417.888674 -304.677318)
		(end 417.463986 -304.677318)
		(width 0.18288)
		(layer "In6.Cu")
		(net "M_H_CPU0_SA_DQ<5>")
	)
	(segment
		(start 427.916594 -305.465226)
		(end 427.154594 -304.703226)
		(width 0.18288)
		(layer "In6.Cu")
		(net "M_H_CPU0_SA_DQ<5>")
	)
	(segment
		(start 386.849112 -275.904706)
		(end 386.849112 -275.8948)
		(width 0.088646)
		(layer "In6.Cu")
		(net "M_H_CPU0_SA_DQ<5>")
	)
	(segment
		(start 384.407664 -275.570442)
		(end 384.392932 -275.579078)
		(width 0.088646)
		(layer "In6.Cu")
		(net "M_H_CPU0_SA_DQ<5>")
	)
	(segment
		(start 413.684212 -301.839376)
		(end 414.025842 -301.497746)
		(width 0.18288)
		(layer "In6.Cu")
		(net "M_H_CPU0_SA_DQ<5>")
	)
	(segment
		(start 415.755836 -302.969168)
		(end 415.497264 -302.969168)
		(width 0.18288)
		(layer "In6.Cu")
		(net "M_H_CPU0_SA_DQ<5>")
	)
	(arc
		(start 381.96266 -275.570442)
		(mid 381.775462 -275.520299)
		(end 381.588264 -275.570442)
		(width 0.088646)
		(layer "In6.Cu")
		(net "M_H_CPU0_SA_DQ<5>")
	)
	(arc
		(start 386.66166 -275.570442)
		(mid 386.474462 -275.520299)
		(end 386.287264 -275.570442)
		(width 0.088646)
		(layer "In6.Cu")
		(net "M_H_CPU0_SA_DQ<5>")
	)
	(arc
		(start 375.848118 -276.380702)
		(mid 375.662663 -276.202507)
		(end 375.575322 -275.960586)
		(width 0.088646)
		(layer "In6.Cu")
		(net "M_H_CPU0_SA_DQ<5>")
	)
	(arc
		(start 376.419618 -276.384258)
		(mid 376.145419 -276.460093)
		(end 375.868946 -276.392894)
		(width 0.088646)
		(layer "In6.Cu")
		(net "M_H_CPU0_SA_DQ<5>")
	)
	(arc
		(start 385.72186 -275.570442)
		(mid 385.534662 -275.520299)
		(end 385.347464 -275.570442)
		(width 0.088646)
		(layer "In6.Cu")
		(net "M_H_CPU0_SA_DQ<5>")
	)
	(arc
		(start 379.693932 -275.579078)
		(mid 379.417491 -275.646244)
		(end 379.14326 -275.570442)
		(width 0.088646)
		(layer "In6.Cu")
		(net "M_H_CPU0_SA_DQ<5>")
	)
	(arc
		(start 381.02286 -275.570442)
		(mid 380.835662 -275.520299)
		(end 380.648464 -275.570442)
		(width 0.088646)
		(layer "In6.Cu")
		(net "M_H_CPU0_SA_DQ<5>")
	)
	(arc
		(start 378.20346 -275.570442)
		(mid 378.016262 -275.520299)
		(end 377.829064 -275.570442)
		(width 0.088646)
		(layer "In6.Cu")
		(net "M_H_CPU0_SA_DQ<5>")
	)
	(arc
		(start 385.332732 -275.579078)
		(mid 385.056257 -275.646398)
		(end 384.78206 -275.570442)
		(width 0.088646)
		(layer "In6.Cu")
		(net "M_H_CPU0_SA_DQ<5>")
	)
	(arc
		(start 386.272532 -275.579078)
		(mid 385.996057 -275.646398)
		(end 385.72186 -275.570442)
		(width 0.088646)
		(layer "In6.Cu")
		(net "M_H_CPU0_SA_DQ<5>")
	)
	(arc
		(start 381.588264 -275.570442)
		(mid 381.305562 -275.646184)
		(end 381.02286 -275.570442)
		(width 0.088646)
		(layer "In6.Cu")
		(net "M_H_CPU0_SA_DQ<5>")
	)
	(arc
		(start 377.263914 -275.570442)
		(mid 377.076716 -275.520299)
		(end 376.889518 -275.570442)
		(width 0.088646)
		(layer "In6.Cu")
		(net "M_H_CPU0_SA_DQ<5>")
	)
	(arc
		(start 387.319012 -276.708616)
		(mid 387.271333 -276.525716)
		(end 387.14045 -276.389338)
		(width 0.088646)
		(layer "In6.Cu")
		(net "M_H_CPU0_SA_DQ<5>")
	)
	(arc
		(start 376.880628 -275.575522)
		(mid 376.749714 -275.711882)
		(end 376.702066 -275.8948)
		(width 0.088646)
		(layer "In6.Cu")
		(net "M_H_CPU0_SA_DQ<5>")
	)
	(arc
		(start 380.08306 -275.570442)
		(mid 379.895862 -275.520299)
		(end 379.708664 -275.570442)
		(width 0.088646)
		(layer "In6.Cu")
		(net "M_H_CPU0_SA_DQ<5>")
	)
	(arc
		(start 383.84226 -275.570442)
		(mid 383.655062 -275.520299)
		(end 383.467864 -275.570442)
		(width 0.088646)
		(layer "In6.Cu")
		(net "M_H_CPU0_SA_DQ<5>")
	)
	(arc
		(start 377.81865 -275.576538)
		(mid 377.540472 -275.64623)
		(end 377.263914 -275.570442)
		(width 0.088646)
		(layer "In6.Cu")
		(net "M_H_CPU0_SA_DQ<5>")
	)
	(arc
		(start 386.849112 -275.8948)
		(mid 386.801433 -275.7119)
		(end 386.67055 -275.575522)
		(width 0.088646)
		(layer "In6.Cu")
		(net "M_H_CPU0_SA_DQ<5>")
	)
	(arc
		(start 379.14326 -275.570442)
		(mid 378.956062 -275.520299)
		(end 378.768864 -275.570442)
		(width 0.088646)
		(layer "In6.Cu")
		(net "M_H_CPU0_SA_DQ<5>")
	)
	(arc
		(start 383.453132 -275.579078)
		(mid 383.176657 -275.646398)
		(end 382.90246 -275.570442)
		(width 0.088646)
		(layer "In6.Cu")
		(net "M_H_CPU0_SA_DQ<5>")
	)
	(arc
		(start 384.78206 -275.570442)
		(mid 384.594862 -275.520299)
		(end 384.407664 -275.570442)
		(width 0.088646)
		(layer "In6.Cu")
		(net "M_H_CPU0_SA_DQ<5>")
	)
	(arc
		(start 382.90246 -275.570442)
		(mid 382.715262 -275.520299)
		(end 382.528064 -275.570442)
		(width 0.088646)
		(layer "In6.Cu")
		(net "M_H_CPU0_SA_DQ<5>")
	)
	(arc
		(start 387.13156 -276.384258)
		(mid 386.927225 -276.181653)
		(end 386.849112 -275.904706)
		(width 0.088646)
		(layer "In6.Cu")
		(net "M_H_CPU0_SA_DQ<5>")
	)
	(arc
		(start 378.754132 -275.579078)
		(mid 378.477691 -275.646244)
		(end 378.20346 -275.570442)
		(width 0.088646)
		(layer "In6.Cu")
		(net "M_H_CPU0_SA_DQ<5>")
	)
	(arc
		(start 376.702066 -275.8948)
		(mid 376.62815 -276.174302)
		(end 376.425714 -276.380702)
		(width 0.088646)
		(layer "In6.Cu")
		(net "M_H_CPU0_SA_DQ<5>")
	)
	(arc
		(start 382.513332 -275.579078)
		(mid 382.236891 -275.646244)
		(end 381.96266 -275.570442)
		(width 0.088646)
		(layer "In6.Cu")
		(net "M_H_CPU0_SA_DQ<5>")
	)
	(arc
		(start 384.392932 -275.579078)
		(mid 384.116457 -275.646398)
		(end 383.84226 -275.570442)
		(width 0.088646)
		(layer "In6.Cu")
		(net "M_H_CPU0_SA_DQ<5>")
	)
	(arc
		(start 380.633732 -275.579078)
		(mid 380.357291 -275.646244)
		(end 380.08306 -275.570442)
		(width 0.088646)
		(layer "In6.Cu")
		(net "M_H_CPU0_SA_DQ<5>")
	)
	(segment
		(start 452.016114 -310.366664)
		(end 450.911214 -310.366664)
		(width 0.20066)
		(layer "F.Cu")
		(net "M_H_CPU0_SA_DQ<4>")
	)
	(segment
		(start 453.536812 -310.366664)
		(end 452.016114 -310.366664)
		(width 0.20066)
		(layer "F.Cu")
		(net "M_H_CPU0_SA_DQ<4>")
	)
	(segment
		(start 374.726962 -276.172676)
		(end 374.727216 -276.708616)
		(width 0.20066)
		(layer "F.Cu")
		(net "M_H_CPU0_SA_DQ<4>")
	)
	(segment
		(start 459.55966 -310.366918)
		(end 457.968096 -310.366918)
		(width 0.20066)
		(layer "F.Cu")
		(net "M_H_CPU0_SA_DQ<4>")
	)
	(segment
		(start 457.53655 -309.935372)
		(end 457.126594 -309.935372)
		(width 0.20066)
		(layer "F.Cu")
		(net "M_H_CPU0_SA_DQ<4>")
	)
	(segment
		(start 454.566782 -309.941722)
		(end 454.448672 -310.059832)
		(width 0.20066)
		(layer "F.Cu")
		(net "M_H_CPU0_SA_DQ<4>")
	)
	(segment
		(start 454.448672 -310.059832)
		(end 454.448672 -310.42737)
		(width 0.20066)
		(layer "F.Cu")
		(net "M_H_CPU0_SA_DQ<4>")
	)
	(segment
		(start 454.448672 -310.42737)
		(end 454.260712 -310.61533)
		(width 0.20066)
		(layer "F.Cu")
		(net "M_H_CPU0_SA_DQ<4>")
	)
	(segment
		(start 457.968096 -310.366918)
		(end 457.53655 -309.935372)
		(width 0.20066)
		(layer "F.Cu")
		(net "M_H_CPU0_SA_DQ<4>")
	)
	(segment
		(start 454.95845 -309.941722)
		(end 454.91146 -309.941722)
		(width 0.101854)
		(layer "F.Cu")
		(net "M_H_CPU0_SA_DQ<4>")
	)
	(segment
		(start 457.126594 -309.935372)
		(end 457.120244 -309.941722)
		(width 0.1016)
		(layer "F.Cu")
		(net "M_H_CPU0_SA_DQ<4>")
	)
	(segment
		(start 454.91146 -309.941722)
		(end 454.566782 -309.941722)
		(width 0.20066)
		(layer "F.Cu")
		(net "M_H_CPU0_SA_DQ<4>")
	)
	(segment
		(start 454.260712 -310.61533)
		(end 453.785478 -310.61533)
		(width 0.20066)
		(layer "F.Cu")
		(net "M_H_CPU0_SA_DQ<4>")
	)
	(segment
		(start 459.559914 -310.366664)
		(end 459.55966 -310.366918)
		(width 0.20066)
		(layer "F.Cu")
		(net "M_H_CPU0_SA_DQ<4>")
	)
	(segment
		(start 453.785478 -310.61533)
		(end 453.536812 -310.366664)
		(width 0.20066)
		(layer "F.Cu")
		(net "M_H_CPU0_SA_DQ<4>")
	)
	(segment
		(start 457.120244 -309.941722)
		(end 454.95845 -309.941722)
		(width 0.1016)
		(layer "F.Cu")
		(net "M_H_CPU0_SA_DQ<4>")
	)
	(segment
		(start 412.735268 -303.845976)
		(end 412.470854 -303.581562)
		(width 0.18288)
		(layer "In6.Cu")
		(net "M_H_CPU0_SA_DQ<4>")
	)
	(segment
		(start 409.516326 -301.44212)
		(end 409.125166 -301.83328)
		(width 0.18288)
		(layer "In6.Cu")
		(net "M_H_CPU0_SA_DQ<4>")
	)
	(segment
		(start 393.958318 -279.492456)
		(end 389.092948 -279.492456)
		(width 0.18288)
		(layer "In6.Cu")
		(net "M_H_CPU0_SA_DQ<4>")
	)
	(segment
		(start 416.626294 -306.354226)
		(end 415.831782 -305.559714)
		(width 0.18288)
		(layer "In6.Cu")
		(net "M_H_CPU0_SA_DQ<4>")
	)
	(segment
		(start 441.42406 -309.494428)
		(end 441.26404 -309.654448)
		(width 0.18288)
		(layer "In6.Cu")
		(net "M_H_CPU0_SA_DQ<4>")
	)
	(segment
		(start 418.813234 -306.985416)
		(end 418.659056 -307.139594)
		(width 0.18288)
		(layer "In6.Cu")
		(net "M_H_CPU0_SA_DQ<4>")
	)
	(segment
		(start 442.20892 -309.25262)
		(end 442.0489 -309.0926)
		(width 0.18288)
		(layer "In6.Cu")
		(net "M_H_CPU0_SA_DQ<4>")
	)
	(segment
		(start 415.831782 -305.559714)
		(end 415.200846 -305.559714)
		(width 0.18288)
		(layer "In6.Cu")
		(net "M_H_CPU0_SA_DQ<4>")
	)
	(segment
		(start 440.89066 -309.654448)
		(end 440.73064 -309.494428)
		(width 0.18288)
		(layer "In6.Cu")
		(net "M_H_CPU0_SA_DQ<4>")
	)
	(segment
		(start 397.40967 -292.534848)
		(end 397.40967 -282.943808)
		(width 0.18288)
		(layer "In6.Cu")
		(net "M_H_CPU0_SA_DQ<4>")
	)
	(segment
		(start 445.408812 -309.948072)
		(end 444.55334 -309.0926)
		(width 0.18288)
		(layer "In6.Cu")
		(net "M_H_CPU0_SA_DQ<4>")
	)
	(segment
		(start 442.90234 -309.25262)
		(end 442.90234 -309.670958)
		(width 0.18288)
		(layer "In6.Cu")
		(net "M_H_CPU0_SA_DQ<4>")
	)
	(segment
		(start 443.06236 -309.0926)
		(end 442.90234 -309.25262)
		(width 0.18288)
		(layer "In6.Cu")
		(net "M_H_CPU0_SA_DQ<4>")
	)
	(segment
		(start 412.470854 -303.581562)
		(end 412.470854 -303.355502)
		(width 0.18288)
		(layer "In6.Cu")
		(net "M_H_CPU0_SA_DQ<4>")
	)
	(segment
		(start 442.20892 -309.670958)
		(end 442.20892 -309.25262)
		(width 0.18288)
		(layer "In6.Cu")
		(net "M_H_CPU0_SA_DQ<4>")
	)
	(segment
		(start 448.299078 -310.382158)
		(end 448.299078 -310.023764)
		(width 0.18288)
		(layer "In6.Cu")
		(net "M_H_CPU0_SA_DQ<4>")
	)
	(segment
		(start 397.40967 -282.943808)
		(end 393.958318 -279.492456)
		(width 0.18288)
		(layer "In6.Cu")
		(net "M_H_CPU0_SA_DQ<4>")
	)
	(segment
		(start 380.563374 -276.390354)
		(end 380.55296 -276.384258)
		(width 0.088646)
		(layer "In6.Cu")
		(net "M_H_CPU0_SA_DQ<4>")
	)
	(segment
		(start 448.992498 -310.023764)
		(end 448.992498 -310.382158)
		(width 0.18288)
		(layer "In6.Cu")
		(net "M_H_CPU0_SA_DQ<4>")
	)
	(segment
		(start 386.67055 -277.203154)
		(end 386.66166 -277.198074)
		(width 0.088646)
		(layer "In6.Cu")
		(net "M_H_CPU0_SA_DQ<4>")
	)
	(segment
		(start 375.868946 -277.024338)
		(end 375.854214 -277.032974)
		(width 0.088646)
		(layer "In6.Cu")
		(net "M_H_CPU0_SA_DQ<4>")
	)
	(segment
		(start 413.337248 -303.696116)
		(end 413.111188 -303.696116)
		(width 0.18288)
		(layer "In6.Cu")
		(net "M_H_CPU0_SA_DQ<4>")
	)
	(segment
		(start 427.916594 -307.141626)
		(end 427.154594 -306.379626)
		(width 0.18288)
		(layer "In6.Cu")
		(net "M_H_CPU0_SA_DQ<4>")
	)
	(segment
		(start 389.092948 -279.492456)
		(end 388.568438 -279.275032)
		(width 0.18288)
		(layer "In6.Cu")
		(net "M_H_CPU0_SA_DQ<4>")
	)
	(segment
		(start 414.98266 -305.341528)
		(end 414.7566 -305.341528)
		(width 0.18288)
		(layer "In6.Cu")
		(net "M_H_CPU0_SA_DQ<4>")
	)
	(segment
		(start 386.379212 -276.718522)
		(end 386.379212 -276.708616)
		(width 0.088646)
		(layer "In6.Cu")
		(net "M_H_CPU0_SA_DQ<4>")
	)
	(segment
		(start 375.479818 -277.032974)
		(end 375.299478 -276.928834)
		(width 0.088646)
		(layer "In6.Cu")
		(net "M_H_CPU0_SA_DQ<4>")
	)
	(segment
		(start 440.73064 -309.25262)
		(end 440.57062 -309.0926)
		(width 0.18288)
		(layer "In6.Cu")
		(net "M_H_CPU0_SA_DQ<4>")
	)
	(segment
		(start 448.116198 -309.840884)
		(end 447.116454 -309.840884)
		(width 0.18288)
		(layer "In6.Cu")
		(net "M_H_CPU0_SA_DQ<4>")
	)
	(segment
		(start 382.447546 -276.392894)
		(end 382.432814 -276.384258)
		(width 0.088646)
		(layer "In6.Cu")
		(net "M_H_CPU0_SA_DQ<4>")
	)
	(segment
		(start 406.612852 -302.636428)
		(end 406.612852 -301.30115)
		(width 0.18288)
		(layer "In6.Cu")
		(net "M_H_CPU0_SA_DQ<4>")
	)
	(segment
		(start 448.481958 -310.565038)
		(end 448.299078 -310.382158)
		(width 0.18288)
		(layer "In6.Cu")
		(net "M_H_CPU0_SA_DQ<4>")
	)
	(segment
		(start 412.961328 -303.845976)
		(end 412.735268 -303.845976)
		(width 0.18288)
		(layer "In6.Cu")
		(net "M_H_CPU0_SA_DQ<4>")
	)
	(segment
		(start 408.807666 -302.723042)
		(end 408.634692 -302.549814)
		(width 0.18288)
		(layer "In6.Cu")
		(net "M_H_CPU0_SA_DQ<4>")
	)
	(segment
		(start 414.266126 -304.624994)
		(end 413.337248 -303.696116)
		(width 0.18288)
		(layer "In6.Cu")
		(net "M_H_CPU0_SA_DQ<4>")
	)
	(segment
		(start 414.668716 -305.429412)
		(end 414.442656 -305.429412)
		(width 0.18288)
		(layer "In6.Cu")
		(net "M_H_CPU0_SA_DQ<4>")
	)
	(segment
		(start 412.127192 -302.48606)
		(end 410.922216 -302.48606)
		(width 0.18288)
		(layer "In6.Cu")
		(net "M_H_CPU0_SA_DQ<4>")
	)
	(segment
		(start 448.299078 -310.023764)
		(end 448.116198 -309.840884)
		(width 0.18288)
		(layer "In6.Cu")
		(net "M_H_CPU0_SA_DQ<4>")
	)
	(segment
		(start 441.58408 -309.0926)
		(end 441.42406 -309.25262)
		(width 0.18288)
		(layer "In6.Cu")
		(net "M_H_CPU0_SA_DQ<4>")
	)
	(segment
		(start 450.385434 -309.840884)
		(end 449.175378 -309.840884)
		(width 0.18288)
		(layer "In6.Cu")
		(net "M_H_CPU0_SA_DQ<4>")
	)
	(segment
		(start 408.634692 -302.549814)
		(end 408.408632 -302.549814)
		(width 0.18288)
		(layer "In6.Cu")
		(net "M_H_CPU0_SA_DQ<4>")
	)
	(segment
		(start 410.177996 -302.475392)
		(end 410.177996 -302.249332)
		(width 0.18288)
		(layer "In6.Cu")
		(net "M_H_CPU0_SA_DQ<4>")
	)
	(segment
		(start 410.44241 -302.739806)
		(end 410.177996 -302.475392)
		(width 0.18288)
		(layer "In6.Cu")
		(net "M_H_CPU0_SA_DQ<4>")
	)
	(segment
		(start 413.111188 -303.696116)
		(end 412.961328 -303.845976)
		(width 0.18288)
		(layer "In6.Cu")
		(net "M_H_CPU0_SA_DQ<4>")
	)
	(segment
		(start 444.55334 -309.0926)
		(end 443.06236 -309.0926)
		(width 0.18288)
		(layer "In6.Cu")
		(net "M_H_CPU0_SA_DQ<4>")
	)
	(segment
		(start 410.431742 -301.995586)
		(end 410.431742 -301.769526)
		(width 0.18288)
		(layer "In6.Cu")
		(net "M_H_CPU0_SA_DQ<4>")
	)
	(segment
		(start 440.73064 -309.494428)
		(end 440.73064 -309.25262)
		(width 0.18288)
		(layer "In6.Cu")
		(net "M_H_CPU0_SA_DQ<4>")
	)
	(segment
		(start 379.623828 -276.390354)
		(end 379.613414 -276.384258)
		(width 0.088646)
		(layer "In6.Cu")
		(net "M_H_CPU0_SA_DQ<4>")
	)
	(segment
		(start 442.90234 -309.670958)
		(end 442.74232 -309.830978)
		(width 0.18288)
		(layer "In6.Cu")
		(net "M_H_CPU0_SA_DQ<4>")
	)
	(segment
		(start 376.808746 -277.024338)
		(end 376.794014 -277.032974)
		(width 0.088646)
		(layer "In6.Cu")
		(net "M_H_CPU0_SA_DQ<4>")
	)
	(segment
		(start 447.009266 -309.948072)
		(end 445.408812 -309.948072)
		(width 0.18288)
		(layer "In6.Cu")
		(net "M_H_CPU0_SA_DQ<4>")
	)
	(segment
		(start 388.457186 -279.275032)
		(end 388.282688 -279.275032)
		(width 0.088646)
		(layer "In6.Cu")
		(net "M_H_CPU0_SA_DQ<4>")
	)
	(segment
		(start 422.150032 -305.692302)
		(end 421.299894 -306.54244)
		(width 0.18288)
		(layer "In6.Cu")
		(net "M_H_CPU0_SA_DQ<4>")
	)
	(segment
		(start 410.104336 -301.44212)
		(end 409.516326 -301.44212)
		(width 0.18288)
		(layer "In6.Cu")
		(net "M_H_CPU0_SA_DQ<4>")
	)
	(segment
		(start 448.809618 -310.565038)
		(end 448.481958 -310.565038)
		(width 0.18288)
		(layer "In6.Cu")
		(net "M_H_CPU0_SA_DQ<4>")
	)
	(segment
		(start 410.431742 -301.769526)
		(end 410.104336 -301.44212)
		(width 0.18288)
		(layer "In6.Cu")
		(net "M_H_CPU0_SA_DQ<4>")
	)
	(segment
		(start 409.29814 -302.458628)
		(end 409.033726 -302.723042)
		(width 0.18288)
		(layer "In6.Cu")
		(net "M_H_CPU0_SA_DQ<4>")
	)
	(segment
		(start 386.20065 -276.389338)
		(end 386.19176 -276.384258)
		(width 0.088646)
		(layer "In6.Cu")
		(net "M_H_CPU0_SA_DQ<4>")
	)
	(segment
		(start 414.442656 -305.429412)
		(end 414.178242 -305.164998)
		(width 0.18288)
		(layer "In6.Cu")
		(net "M_H_CPU0_SA_DQ<4>")
	)
	(segment
		(start 450.911214 -310.366664)
		(end 450.385434 -309.840884)
		(width 0.18288)
		(layer "In6.Cu")
		(net "M_H_CPU0_SA_DQ<4>")
	)
	(segment
		(start 406.612852 -301.30115)
		(end 405.902414 -300.590712)
		(width 0.18288)
		(layer "In6.Cu")
		(net "M_H_CPU0_SA_DQ<4>")
	)
	(segment
		(start 448.992498 -310.382158)
		(end 448.809618 -310.565038)
		(width 0.18288)
		(layer "In6.Cu")
		(net "M_H_CPU0_SA_DQ<4>")
	)
	(segment
		(start 437.794908 -309.0926)
		(end 436.945024 -309.942484)
		(width 0.18288)
		(layer "In6.Cu")
		(net "M_H_CPU0_SA_DQ<4>")
	)
	(segment
		(start 425.554394 -305.692302)
		(end 422.150032 -305.692302)
		(width 0.18288)
		(layer "In6.Cu")
		(net "M_H_CPU0_SA_DQ<4>")
	)
	(segment
		(start 410.177996 -302.249332)
		(end 410.431742 -301.995586)
		(width 0.18288)
		(layer "In6.Cu")
		(net "M_H_CPU0_SA_DQ<4>")
	)
	(segment
		(start 419.775894 -306.354226)
		(end 418.986462 -306.354226)
		(width 0.18288)
		(layer "In6.Cu")
		(net "M_H_CPU0_SA_DQ<4>")
	)
	(segment
		(start 414.7566 -305.341528)
		(end 414.668716 -305.429412)
		(width 0.18288)
		(layer "In6.Cu")
		(net "M_H_CPU0_SA_DQ<4>")
	)
	(segment
		(start 377.748546 -276.392894)
		(end 377.733814 -276.384258)
		(width 0.088646)
		(layer "In6.Cu")
		(net "M_H_CPU0_SA_DQ<4>")
	)
	(segment
		(start 417.796218 -306.354226)
		(end 416.626294 -306.354226)
		(width 0.18288)
		(layer "In6.Cu")
		(net "M_H_CPU0_SA_DQ<4>")
	)
	(segment
		(start 440.57062 -309.0926)
		(end 437.794908 -309.0926)
		(width 0.18288)
		(layer "In6.Cu")
		(net "M_H_CPU0_SA_DQ<4>")
	)
	(segment
		(start 442.74232 -309.830978)
		(end 442.36894 -309.830978)
		(width 0.18288)
		(layer "In6.Cu")
		(net "M_H_CPU0_SA_DQ<4>")
	)
	(segment
		(start 442.0489 -309.0926)
		(end 441.58408 -309.0926)
		(width 0.18288)
		(layer "In6.Cu")
		(net "M_H_CPU0_SA_DQ<4>")
	)
	(segment
		(start 426.241718 -306.379626)
		(end 425.554394 -305.692302)
		(width 0.18288)
		(layer "In6.Cu")
		(net "M_H_CPU0_SA_DQ<4>")
	)
	(segment
		(start 383.383028 -276.390354)
		(end 383.372614 -276.384258)
		(width 0.088646)
		(layer "In6.Cu")
		(net "M_H_CPU0_SA_DQ<4>")
	)
	(segment
		(start 431.987452 -309.942484)
		(end 430.939194 -308.894226)
		(width 0.18288)
		(layer "In6.Cu")
		(net "M_H_CPU0_SA_DQ<4>")
	)
	(segment
		(start 414.178242 -304.938938)
		(end 414.266126 -304.851054)
		(width 0.18288)
		(layer "In6.Cu")
		(net "M_H_CPU0_SA_DQ<4>")
	)
	(segment
		(start 409.033726 -302.723042)
		(end 408.807666 -302.723042)
		(width 0.18288)
		(layer "In6.Cu")
		(net "M_H_CPU0_SA_DQ<4>")
	)
	(segment
		(start 418.024564 -306.966874)
		(end 418.024564 -306.582572)
		(width 0.18288)
		(layer "In6.Cu")
		(net "M_H_CPU0_SA_DQ<4>")
	)
	(segment
		(start 412.620714 -303.205642)
		(end 412.620714 -302.979582)
		(width 0.18288)
		(layer "In6.Cu")
		(net "M_H_CPU0_SA_DQ<4>")
	)
	(segment
		(start 427.154594 -306.379626)
		(end 426.241718 -306.379626)
		(width 0.18288)
		(layer "In6.Cu")
		(net "M_H_CPU0_SA_DQ<4>")
	)
	(segment
		(start 418.024564 -306.582572)
		(end 417.796218 -306.354226)
		(width 0.18288)
		(layer "In6.Cu")
		(net "M_H_CPU0_SA_DQ<4>")
	)
	(segment
		(start 410.922216 -302.48606)
		(end 410.66847 -302.739806)
		(width 0.18288)
		(layer "In6.Cu")
		(net "M_H_CPU0_SA_DQ<4>")
	)
	(segment
		(start 375.219214 -276.891242)
		(end 374.727216 -276.708616)
		(width 0.088646)
		(layer "In6.Cu")
		(net "M_H_CPU0_SA_DQ<4>")
	)
	(segment
		(start 418.986462 -306.354226)
		(end 418.813234 -306.527454)
		(width 0.18288)
		(layer "In6.Cu")
		(net "M_H_CPU0_SA_DQ<4>")
	)
	(segment
		(start 387.362192 -278.22398)
		(end 387.209538 -278.071326)
		(width 0.088646)
		(layer "In6.Cu")
		(net "M_H_CPU0_SA_DQ<4>")
	)
	(segment
		(start 418.659056 -307.139594)
		(end 418.197284 -307.139594)
		(width 0.18288)
		(layer "In6.Cu")
		(net "M_H_CPU0_SA_DQ<4>")
	)
	(segment
		(start 388.282688 -279.275032)
		(end 387.362192 -278.354536)
		(width 0.088646)
		(layer "In6.Cu")
		(net "M_H_CPU0_SA_DQ<4>")
	)
	(segment
		(start 408.408632 -302.549814)
		(end 408.055318 -302.903128)
		(width 0.18288)
		(layer "In6.Cu")
		(net "M_H_CPU0_SA_DQ<4>")
	)
	(segment
		(start 419.964108 -306.54244)
		(end 419.775894 -306.354226)
		(width 0.18288)
		(layer "In6.Cu")
		(net "M_H_CPU0_SA_DQ<4>")
	)
	(segment
		(start 410.66847 -302.739806)
		(end 410.44241 -302.739806)
		(width 0.18288)
		(layer "In6.Cu")
		(net "M_H_CPU0_SA_DQ<4>")
	)
	(segment
		(start 442.36894 -309.830978)
		(end 442.20892 -309.670958)
		(width 0.18288)
		(layer "In6.Cu")
		(net "M_H_CPU0_SA_DQ<4>")
	)
	(segment
		(start 414.266126 -304.851054)
		(end 414.266126 -304.624994)
		(width 0.18288)
		(layer "In6.Cu")
		(net "M_H_CPU0_SA_DQ<4>")
	)
	(segment
		(start 436.945024 -309.942484)
		(end 431.987452 -309.942484)
		(width 0.18288)
		(layer "In6.Cu")
		(net "M_H_CPU0_SA_DQ<4>")
	)
	(segment
		(start 406.879552 -302.903128)
		(end 406.612852 -302.636428)
		(width 0.18288)
		(layer "In6.Cu")
		(net "M_H_CPU0_SA_DQ<4>")
	)
	(segment
		(start 386.849112 -277.540974)
		(end 386.849112 -277.522432)
		(width 0.088646)
		(layer "In6.Cu")
		(net "M_H_CPU0_SA_DQ<4>")
	)
	(segment
		(start 421.299894 -306.54244)
		(end 419.964108 -306.54244)
		(width 0.18288)
		(layer "In6.Cu")
		(net "M_H_CPU0_SA_DQ<4>")
	)
	(segment
		(start 381.507746 -276.392894)
		(end 381.493014 -276.384258)
		(width 0.088646)
		(layer "In6.Cu")
		(net "M_H_CPU0_SA_DQ<4>")
	)
	(segment
		(start 409.29814 -302.232568)
		(end 409.29814 -302.458628)
		(width 0.18288)
		(layer "In6.Cu")
		(net "M_H_CPU0_SA_DQ<4>")
	)
	(segment
		(start 441.42406 -309.25262)
		(end 441.42406 -309.494428)
		(width 0.18288)
		(layer "In6.Cu")
		(net "M_H_CPU0_SA_DQ<4>")
	)
	(segment
		(start 430.939194 -308.894226)
		(end 430.177194 -308.894226)
		(width 0.18288)
		(layer "In6.Cu")
		(net "M_H_CPU0_SA_DQ<4>")
	)
	(segment
		(start 408.055318 -302.903128)
		(end 406.879552 -302.903128)
		(width 0.18288)
		(layer "In6.Cu")
		(net "M_H_CPU0_SA_DQ<4>")
	)
	(segment
		(start 388.568438 -279.275032)
		(end 388.457186 -279.275032)
		(width 0.18288)
		(layer "In6.Cu")
		(net "M_H_CPU0_SA_DQ<4>")
	)
	(segment
		(start 409.125166 -302.05934)
		(end 409.29814 -302.232568)
		(width 0.18288)
		(layer "In6.Cu")
		(net "M_H_CPU0_SA_DQ<4>")
	)
	(segment
		(start 405.902414 -300.590712)
		(end 405.465534 -300.590712)
		(width 0.18288)
		(layer "In6.Cu")
		(net "M_H_CPU0_SA_DQ<4>")
	)
	(segment
		(start 430.177194 -308.894226)
		(end 428.424594 -307.141626)
		(width 0.18288)
		(layer "In6.Cu")
		(net "M_H_CPU0_SA_DQ<4>")
	)
	(segment
		(start 418.813234 -306.527454)
		(end 418.813234 -306.985416)
		(width 0.18288)
		(layer "In6.Cu")
		(net "M_H_CPU0_SA_DQ<4>")
	)
	(segment
		(start 412.470854 -303.355502)
		(end 412.620714 -303.205642)
		(width 0.18288)
		(layer "In6.Cu")
		(net "M_H_CPU0_SA_DQ<4>")
	)
	(segment
		(start 387.362192 -278.354536)
		(end 387.362192 -278.22398)
		(width 0.088646)
		(layer "In6.Cu")
		(net "M_H_CPU0_SA_DQ<4>")
	)
	(segment
		(start 449.175378 -309.840884)
		(end 448.992498 -310.023764)
		(width 0.18288)
		(layer "In6.Cu")
		(net "M_H_CPU0_SA_DQ<4>")
	)
	(segment
		(start 447.116454 -309.840884)
		(end 447.009266 -309.948072)
		(width 0.18288)
		(layer "In6.Cu")
		(net "M_H_CPU0_SA_DQ<4>")
	)
	(segment
		(start 415.200846 -305.559714)
		(end 414.98266 -305.341528)
		(width 0.18288)
		(layer "In6.Cu")
		(net "M_H_CPU0_SA_DQ<4>")
	)
	(segment
		(start 428.424594 -307.141626)
		(end 427.916594 -307.141626)
		(width 0.18288)
		(layer "In6.Cu")
		(net "M_H_CPU0_SA_DQ<4>")
	)
	(segment
		(start 405.465534 -300.590712)
		(end 397.40967 -292.534848)
		(width 0.18288)
		(layer "In6.Cu")
		(net "M_H_CPU0_SA_DQ<4>")
	)
	(segment
		(start 412.620714 -302.979582)
		(end 412.127192 -302.48606)
		(width 0.18288)
		(layer "In6.Cu")
		(net "M_H_CPU0_SA_DQ<4>")
	)
	(segment
		(start 414.178242 -305.164998)
		(end 414.178242 -304.938938)
		(width 0.18288)
		(layer "In6.Cu")
		(net "M_H_CPU0_SA_DQ<4>")
	)
	(segment
		(start 441.26404 -309.654448)
		(end 440.89066 -309.654448)
		(width 0.18288)
		(layer "In6.Cu")
		(net "M_H_CPU0_SA_DQ<4>")
	)
	(segment
		(start 378.688346 -276.392894)
		(end 378.673614 -276.384258)
		(width 0.088646)
		(layer "In6.Cu")
		(net "M_H_CPU0_SA_DQ<4>")
	)
	(segment
		(start 409.125166 -301.83328)
		(end 409.125166 -302.05934)
		(width 0.18288)
		(layer "In6.Cu")
		(net "M_H_CPU0_SA_DQ<4>")
	)
	(segment
		(start 418.197284 -307.139594)
		(end 418.024564 -306.966874)
		(width 0.18288)
		(layer "In6.Cu")
		(net "M_H_CPU0_SA_DQ<4>")
	)
	(arc
		(start 386.849112 -277.522432)
		(mid 386.801433 -277.339532)
		(end 386.67055 -277.203154)
		(width 0.088646)
		(layer "In6.Cu")
		(net "M_H_CPU0_SA_DQ<4>")
	)
	(arc
		(start 384.31216 -276.384258)
		(mid 384.124962 -276.334115)
		(end 383.937764 -276.384258)
		(width 0.088646)
		(layer "In6.Cu")
		(net "M_H_CPU0_SA_DQ<4>")
	)
	(arc
		(start 379.239018 -276.384258)
		(mid 378.964819 -276.460093)
		(end 378.688346 -276.392894)
		(width 0.088646)
		(layer "In6.Cu")
		(net "M_H_CPU0_SA_DQ<4>")
	)
	(arc
		(start 380.178564 -276.384258)
		(mid 379.902005 -276.460001)
		(end 379.623828 -276.390354)
		(width 0.088646)
		(layer "In6.Cu")
		(net "M_H_CPU0_SA_DQ<4>")
	)
	(arc
		(start 386.379212 -276.708616)
		(mid 386.331533 -276.525716)
		(end 386.20065 -276.389338)
		(width 0.088646)
		(layer "In6.Cu")
		(net "M_H_CPU0_SA_DQ<4>")
	)
	(arc
		(start 382.998218 -276.384258)
		(mid 382.724019 -276.460093)
		(end 382.447546 -276.392894)
		(width 0.088646)
		(layer "In6.Cu")
		(net "M_H_CPU0_SA_DQ<4>")
	)
	(arc
		(start 386.66166 -277.198074)
		(mid 386.457325 -276.995469)
		(end 386.379212 -276.718522)
		(width 0.088646)
		(layer "In6.Cu")
		(net "M_H_CPU0_SA_DQ<4>")
	)
	(arc
		(start 378.673614 -276.384258)
		(mid 378.486416 -276.334115)
		(end 378.299218 -276.384258)
		(width 0.088646)
		(layer "In6.Cu")
		(net "M_H_CPU0_SA_DQ<4>")
	)
	(arc
		(start 376.419618 -277.032974)
		(mid 376.145419 -276.957139)
		(end 375.868946 -277.024338)
		(width 0.088646)
		(layer "In6.Cu")
		(net "M_H_CPU0_SA_DQ<4>")
	)
	(arc
		(start 383.937764 -276.384258)
		(mid 383.661205 -276.460001)
		(end 383.383028 -276.390354)
		(width 0.088646)
		(layer "In6.Cu")
		(net "M_H_CPU0_SA_DQ<4>")
	)
	(arc
		(start 384.877564 -276.384258)
		(mid 384.594862 -276.460034)
		(end 384.31216 -276.384258)
		(width 0.088646)
		(layer "In6.Cu")
		(net "M_H_CPU0_SA_DQ<4>")
	)
	(arc
		(start 385.817364 -276.384258)
		(mid 385.534662 -276.460034)
		(end 385.25196 -276.384258)
		(width 0.088646)
		(layer "In6.Cu")
		(net "M_H_CPU0_SA_DQ<4>")
	)
	(arc
		(start 379.613414 -276.384258)
		(mid 379.426216 -276.334115)
		(end 379.239018 -276.384258)
		(width 0.088646)
		(layer "In6.Cu")
		(net "M_H_CPU0_SA_DQ<4>")
	)
	(arc
		(start 376.794014 -277.032974)
		(mid 376.606816 -277.083117)
		(end 376.419618 -277.032974)
		(width 0.088646)
		(layer "In6.Cu")
		(net "M_H_CPU0_SA_DQ<4>")
	)
	(arc
		(start 382.058418 -276.384258)
		(mid 381.784219 -276.460093)
		(end 381.507746 -276.392894)
		(width 0.088646)
		(layer "In6.Cu")
		(net "M_H_CPU0_SA_DQ<4>")
	)
	(arc
		(start 381.493014 -276.384258)
		(mid 381.305816 -276.334115)
		(end 381.118618 -276.384258)
		(width 0.088646)
		(layer "In6.Cu")
		(net "M_H_CPU0_SA_DQ<4>")
	)
	(arc
		(start 386.19176 -276.384258)
		(mid 386.004562 -276.334115)
		(end 385.817364 -276.384258)
		(width 0.088646)
		(layer "In6.Cu")
		(net "M_H_CPU0_SA_DQ<4>")
	)
	(arc
		(start 375.854214 -277.032974)
		(mid 375.667016 -277.083151)
		(end 375.479818 -277.032974)
		(width 0.088646)
		(layer "In6.Cu")
		(net "M_H_CPU0_SA_DQ<4>")
	)
	(arc
		(start 380.55296 -276.384258)
		(mid 380.365762 -276.334115)
		(end 380.178564 -276.384258)
		(width 0.088646)
		(layer "In6.Cu")
		(net "M_H_CPU0_SA_DQ<4>")
	)
	(arc
		(start 385.25196 -276.384258)
		(mid 385.064762 -276.334115)
		(end 384.877564 -276.384258)
		(width 0.088646)
		(layer "In6.Cu")
		(net "M_H_CPU0_SA_DQ<4>")
	)
	(arc
		(start 387.209538 -278.071326)
		(mid 387.172488 -278.03918)
		(end 387.13156 -278.012144)
		(width 0.088646)
		(layer "In6.Cu")
		(net "M_H_CPU0_SA_DQ<4>")
	)
	(arc
		(start 377.733814 -276.384258)
		(mid 377.412056 -276.359124)
		(end 377.190254 -276.593554)
		(width 0.088646)
		(layer "In6.Cu")
		(net "M_H_CPU0_SA_DQ<4>")
	)
	(arc
		(start 387.13156 -278.012144)
		(mid 386.929274 -277.813163)
		(end 386.849112 -277.540974)
		(width 0.088646)
		(layer "In6.Cu")
		(net "M_H_CPU0_SA_DQ<4>")
	)
	(arc
		(start 383.372614 -276.384258)
		(mid 383.185416 -276.334115)
		(end 382.998218 -276.384258)
		(width 0.088646)
		(layer "In6.Cu")
		(net "M_H_CPU0_SA_DQ<4>")
	)
	(arc
		(start 378.299218 -276.384258)
		(mid 378.025019 -276.460093)
		(end 377.748546 -276.392894)
		(width 0.088646)
		(layer "In6.Cu")
		(net "M_H_CPU0_SA_DQ<4>")
	)
	(arc
		(start 382.432814 -276.384258)
		(mid 382.245616 -276.334115)
		(end 382.058418 -276.384258)
		(width 0.088646)
		(layer "In6.Cu")
		(net "M_H_CPU0_SA_DQ<4>")
	)
	(arc
		(start 377.190254 -276.593554)
		(mid 377.03379 -276.839315)
		(end 376.808746 -277.024338)
		(width 0.088646)
		(layer "In6.Cu")
		(net "M_H_CPU0_SA_DQ<4>")
	)
	(arc
		(start 381.118618 -276.384258)
		(mid 380.841805 -276.460128)
		(end 380.563374 -276.390354)
		(width 0.088646)
		(layer "In6.Cu")
		(net "M_H_CPU0_SA_DQ<4>")
	)
	(arc
		(start 375.299478 -276.928834)
		(mid 375.260138 -276.908347)
		(end 375.219214 -276.891242)
		(width 0.088646)
		(layer "In6.Cu")
		(net "M_H_CPU0_SA_DQ<4>")
	)
	(segment
		(start 458.538326 -314.198762)
		(end 458.543152 -314.198762)
		(width 0.101854)
		(layer "F.Cu")
		(net "M_H_CPU0_SA_DQ<3>")
	)
	(segment
		(start 376.606562 -277.800562)
		(end 376.606562 -278.336502)
		(width 0.20066)
		(layer "F.Cu")
		(net "M_H_CPU0_SA_DQ<3>")
	)
	(segment
		(start 461.689704 -313.51474)
		(end 462.073752 -313.51474)
		(width 0.20066)
		(layer "F.Cu")
		(net "M_H_CPU0_SA_DQ<3>")
	)
	(segment
		(start 462.32572 -313.766708)
		(end 463.659982 -313.766708)
		(width 0.20066)
		(layer "F.Cu")
		(net "M_H_CPU0_SA_DQ<3>")
	)
	(segment
		(start 455.011282 -313.766708)
		(end 456.116182 -313.766708)
		(width 0.20066)
		(layer "F.Cu")
		(net "M_H_CPU0_SA_DQ<3>")
	)
	(segment
		(start 458.550264 -314.19165)
		(end 460.558134 -314.19165)
		(width 0.1016)
		(layer "F.Cu")
		(net "M_H_CPU0_SA_DQ<3>")
	)
	(segment
		(start 461.455516 -313.748928)
		(end 461.689704 -313.51474)
		(width 0.20066)
		(layer "F.Cu")
		(net "M_H_CPU0_SA_DQ<3>")
	)
	(segment
		(start 461.251554 -314.203842)
		(end 461.455516 -313.99988)
		(width 0.20066)
		(layer "F.Cu")
		(net "M_H_CPU0_SA_DQ<3>")
	)
	(segment
		(start 456.116182 -313.766708)
		(end 457.814426 -313.766708)
		(width 0.20066)
		(layer "F.Cu")
		(net "M_H_CPU0_SA_DQ<3>")
	)
	(segment
		(start 458.543152 -314.198762)
		(end 458.550264 -314.19165)
		(width 0.1016)
		(layer "F.Cu")
		(net "M_H_CPU0_SA_DQ<3>")
	)
	(segment
		(start 462.073752 -313.51474)
		(end 462.32572 -313.766708)
		(width 0.20066)
		(layer "F.Cu")
		(net "M_H_CPU0_SA_DQ<3>")
	)
	(segment
		(start 457.814426 -313.766708)
		(end 458.24648 -314.198762)
		(width 0.20066)
		(layer "F.Cu")
		(net "M_H_CPU0_SA_DQ<3>")
	)
	(segment
		(start 458.24648 -314.198762)
		(end 458.538326 -314.198762)
		(width 0.20066)
		(layer "F.Cu")
		(net "M_H_CPU0_SA_DQ<3>")
	)
	(segment
		(start 460.558134 -314.19165)
		(end 460.570326 -314.203842)
		(width 0.1016)
		(layer "F.Cu")
		(net "M_H_CPU0_SA_DQ<3>")
	)
	(segment
		(start 461.455516 -313.99988)
		(end 461.455516 -313.748928)
		(width 0.20066)
		(layer "F.Cu")
		(net "M_H_CPU0_SA_DQ<3>")
	)
	(segment
		(start 460.570326 -314.203842)
		(end 461.251554 -314.203842)
		(width 0.20066)
		(layer "F.Cu")
		(net "M_H_CPU0_SA_DQ<3>")
	)
	(segment
		(start 411.206188 -309.26532)
		(end 409.380182 -309.26532)
		(width 0.18288)
		(layer "In6.Cu")
		(net "M_H_CPU0_SA_DQ<3>")
	)
	(segment
		(start 431.751994 -314.101226)
		(end 430.993042 -313.342274)
		(width 0.18288)
		(layer "In6.Cu")
		(net "M_H_CPU0_SA_DQ<3>")
	)
	(segment
		(start 402.63445 -305.908964)
		(end 402.63445 -301.514256)
		(width 0.18288)
		(layer "In6.Cu")
		(net "M_H_CPU0_SA_DQ<3>")
	)
	(segment
		(start 425.99229 -310.792114)
		(end 422.94556 -310.792114)
		(width 0.18288)
		(layer "In6.Cu")
		(net "M_H_CPU0_SA_DQ<3>")
	)
	(segment
		(start 387.860286 -281.970226)
		(end 387.368034 -280.780744)
		(width 0.088646)
		(layer "In6.Cu")
		(net "M_H_CPU0_SA_DQ<3>")
	)
	(segment
		(start 414.200848 -310.365648)
		(end 414.200848 -310.590946)
		(width 0.18288)
		(layer "In6.Cu")
		(net "M_H_CPU0_SA_DQ<3>")
	)
	(segment
		(start 453.873362 -315.031374)
		(end 453.61479 -315.031374)
		(width 0.18288)
		(layer "In6.Cu")
		(net "M_H_CPU0_SA_DQ<3>")
	)
	(segment
		(start 408.568398 -308.453536)
		(end 407.2255 -308.453536)
		(width 0.18288)
		(layer "In6.Cu")
		(net "M_H_CPU0_SA_DQ<3>")
	)
	(segment
		(start 418.94887 -311.642252)
		(end 416.83432 -311.642252)
		(width 0.18288)
		(layer "In6.Cu")
		(net "M_H_CPU0_SA_DQ<3>")
	)
	(segment
		(start 392.764772 -282.13304)
		(end 388.279132 -282.13304)
		(width 0.18288)
		(layer "In6.Cu")
		(net "M_H_CPU0_SA_DQ<3>")
	)
	(segment
		(start 453.733408 -313.910472)
		(end 453.733408 -314.169044)
		(width 0.18288)
		(layer "In6.Cu")
		(net "M_H_CPU0_SA_DQ<3>")
	)
	(segment
		(start 379.708918 -278.82596)
		(end 379.698504 -278.832056)
		(width 0.088646)
		(layer "In6.Cu")
		(net "M_H_CPU0_SA_DQ<3>")
	)
	(segment
		(start 420.00805 -311.642252)
		(end 419.82517 -311.825132)
		(width 0.18288)
		(layer "In6.Cu")
		(net "M_H_CPU0_SA_DQ<3>")
	)
	(segment
		(start 442.933582 -314.799472)
		(end 442.690758 -315.042296)
		(width 0.18288)
		(layer "In6.Cu")
		(net "M_H_CPU0_SA_DQ<3>")
	)
	(segment
		(start 407.01722 -308.245256)
		(end 406.55748 -308.245256)
		(width 0.18288)
		(layer "In6.Cu")
		(net "M_H_CPU0_SA_DQ<3>")
	)
	(segment
		(start 434.304948 -315.89218)
		(end 432.513994 -314.101226)
		(width 0.18288)
		(layer "In6.Cu")
		(net "M_H_CPU0_SA_DQ<3>")
	)
	(segment
		(start 388.017512 -282.13304)
		(end 387.860286 -281.975814)
		(width 0.088646)
		(layer "In6.Cu")
		(net "M_H_CPU0_SA_DQ<3>")
	)
	(segment
		(start 422.94556 -310.792114)
		(end 422.095422 -311.642252)
		(width 0.18288)
		(layer "In6.Cu")
		(net "M_H_CPU0_SA_DQ<3>")
	)
	(segment
		(start 378.130054 -278.783034)
		(end 378.038868 -278.747728)
		(width 0.088646)
		(layer "In6.Cu")
		(net "M_H_CPU0_SA_DQ<3>")
	)
	(segment
		(start 416.83432 -311.642252)
		(end 415.965894 -310.773826)
		(width 0.18288)
		(layer "In6.Cu")
		(net "M_H_CPU0_SA_DQ<3>")
	)
	(segment
		(start 455.011282 -313.766708)
		(end 453.877172 -313.766708)
		(width 0.18288)
		(layer "In6.Cu")
		(net "M_H_CPU0_SA_DQ<3>")
	)
	(segment
		(start 414.383728 -310.182768)
		(end 414.200848 -310.365648)
		(width 0.18288)
		(layer "In6.Cu")
		(net "M_H_CPU0_SA_DQ<3>")
	)
	(segment
		(start 414.894268 -310.365648)
		(end 414.711388 -310.182768)
		(width 0.18288)
		(layer "In6.Cu")
		(net "M_H_CPU0_SA_DQ<3>")
	)
	(segment
		(start 384.79095 -278.83104)
		(end 384.78206 -278.82596)
		(width 0.088646)
		(layer "In6.Cu")
		(net "M_H_CPU0_SA_DQ<3>")
	)
	(segment
		(start 453.733408 -314.169044)
		(end 454.105264 -314.5409)
		(width 0.18288)
		(layer "In6.Cu")
		(net "M_H_CPU0_SA_DQ<3>")
	)
	(segment
		(start 419.13175 -312.031126)
		(end 419.13175 -311.825132)
		(width 0.18288)
		(layer "In6.Cu")
		(net "M_H_CPU0_SA_DQ<3>")
	)
	(segment
		(start 381.588264 -278.82596)
		(end 381.57785 -278.832056)
		(width 0.088646)
		(layer "In6.Cu")
		(net "M_H_CPU0_SA_DQ<3>")
	)
	(segment
		(start 384.969512 -279.160224)
		(end 384.969512 -279.150318)
		(width 0.088646)
		(layer "In6.Cu")
		(net "M_H_CPU0_SA_DQ<3>")
	)
	(segment
		(start 454.105264 -314.799472)
		(end 453.873362 -315.031374)
		(width 0.18288)
		(layer "In6.Cu")
		(net "M_H_CPU0_SA_DQ<3>")
	)
	(segment
		(start 406.55748 -308.245256)
		(end 406.3492 -308.453536)
		(width 0.18288)
		(layer "In6.Cu")
		(net "M_H_CPU0_SA_DQ<3>")
	)
	(segment
		(start 406.3492 -308.453536)
		(end 405.179022 -308.453536)
		(width 0.18288)
		(layer "In6.Cu")
		(net "M_H_CPU0_SA_DQ<3>")
	)
	(segment
		(start 394.79855 -293.678356)
		(end 394.79855 -284.166818)
		(width 0.18288)
		(layer "In6.Cu")
		(net "M_H_CPU0_SA_DQ<3>")
	)
	(segment
		(start 385.26085 -279.644856)
		(end 385.25196 -279.639776)
		(width 0.088646)
		(layer "In6.Cu")
		(net "M_H_CPU0_SA_DQ<3>")
	)
	(segment
		(start 453.61479 -315.031374)
		(end 453.242934 -314.659518)
		(width 0.18288)
		(layer "In6.Cu")
		(net "M_H_CPU0_SA_DQ<3>")
	)
	(segment
		(start 387.860286 -281.975814)
		(end 387.860286 -281.970226)
		(width 0.088646)
		(layer "In6.Cu")
		(net "M_H_CPU0_SA_DQ<3>")
	)
	(segment
		(start 386.287518 -280.453846)
		(end 386.277104 -280.459942)
		(width 0.088646)
		(layer "In6.Cu")
		(net "M_H_CPU0_SA_DQ<3>")
	)
	(segment
		(start 452.601584 -315.042296)
		(end 449.228464 -315.042296)
		(width 0.18288)
		(layer "In6.Cu")
		(net "M_H_CPU0_SA_DQ<3>")
	)
	(segment
		(start 412.359094 -309.732426)
		(end 411.673294 -309.732426)
		(width 0.18288)
		(layer "In6.Cu")
		(net "M_H_CPU0_SA_DQ<3>")
	)
	(segment
		(start 436.532274 -315.89218)
		(end 434.304948 -315.89218)
		(width 0.18288)
		(layer "In6.Cu")
		(net "M_H_CPU0_SA_DQ<3>")
	)
	(segment
		(start 385.439412 -279.982676)
		(end 385.439412 -279.964134)
		(width 0.088646)
		(layer "In6.Cu")
		(net "M_H_CPU0_SA_DQ<3>")
	)
	(segment
		(start 454.105264 -314.5409)
		(end 454.105264 -314.799472)
		(width 0.18288)
		(layer "In6.Cu")
		(net "M_H_CPU0_SA_DQ<3>")
	)
	(segment
		(start 411.673294 -309.732426)
		(end 411.206188 -309.26532)
		(width 0.18288)
		(layer "In6.Cu")
		(net "M_H_CPU0_SA_DQ<3>")
	)
	(segment
		(start 427.483016 -312.28284)
		(end 425.99229 -310.792114)
		(width 0.18288)
		(layer "In6.Cu")
		(net "M_H_CPU0_SA_DQ<3>")
	)
	(segment
		(start 407.2255 -308.453536)
		(end 407.01722 -308.245256)
		(width 0.18288)
		(layer "In6.Cu")
		(net "M_H_CPU0_SA_DQ<3>")
	)
	(segment
		(start 419.82517 -312.031126)
		(end 419.64229 -312.214006)
		(width 0.18288)
		(layer "In6.Cu")
		(net "M_H_CPU0_SA_DQ<3>")
	)
	(segment
		(start 414.200848 -310.590946)
		(end 414.017968 -310.773826)
		(width 0.18288)
		(layer "In6.Cu")
		(net "M_H_CPU0_SA_DQ<3>")
	)
	(segment
		(start 419.31463 -312.214006)
		(end 419.13175 -312.031126)
		(width 0.18288)
		(layer "In6.Cu")
		(net "M_H_CPU0_SA_DQ<3>")
	)
	(segment
		(start 453.877172 -313.766708)
		(end 453.733408 -313.910472)
		(width 0.18288)
		(layer "In6.Cu")
		(net "M_H_CPU0_SA_DQ<3>")
	)
	(segment
		(start 449.228464 -315.042296)
		(end 448.338194 -314.152026)
		(width 0.18288)
		(layer "In6.Cu")
		(net "M_H_CPU0_SA_DQ<3>")
	)
	(segment
		(start 419.64229 -312.214006)
		(end 419.31463 -312.214006)
		(width 0.18288)
		(layer "In6.Cu")
		(net "M_H_CPU0_SA_DQ<3>")
	)
	(segment
		(start 446.446148 -314.799472)
		(end 442.933582 -314.799472)
		(width 0.18288)
		(layer "In6.Cu")
		(net "M_H_CPU0_SA_DQ<3>")
	)
	(segment
		(start 419.13175 -311.825132)
		(end 418.94887 -311.642252)
		(width 0.18288)
		(layer "In6.Cu")
		(net "M_H_CPU0_SA_DQ<3>")
	)
	(segment
		(start 415.965894 -310.773826)
		(end 415.077148 -310.773826)
		(width 0.18288)
		(layer "In6.Cu")
		(net "M_H_CPU0_SA_DQ<3>")
	)
	(segment
		(start 414.894268 -310.590946)
		(end 414.894268 -310.365648)
		(width 0.18288)
		(layer "In6.Cu")
		(net "M_H_CPU0_SA_DQ<3>")
	)
	(segment
		(start 405.179022 -308.453536)
		(end 402.63445 -305.908964)
		(width 0.18288)
		(layer "In6.Cu")
		(net "M_H_CPU0_SA_DQ<3>")
	)
	(segment
		(start 409.380182 -309.26532)
		(end 408.568398 -308.453536)
		(width 0.18288)
		(layer "In6.Cu")
		(net "M_H_CPU0_SA_DQ<3>")
	)
	(segment
		(start 402.63445 -301.514256)
		(end 394.79855 -293.678356)
		(width 0.18288)
		(layer "In6.Cu")
		(net "M_H_CPU0_SA_DQ<3>")
	)
	(segment
		(start 414.711388 -310.182768)
		(end 414.383728 -310.182768)
		(width 0.18288)
		(layer "In6.Cu")
		(net "M_H_CPU0_SA_DQ<3>")
	)
	(segment
		(start 437.50484 -314.919614)
		(end 436.532274 -315.89218)
		(width 0.18288)
		(layer "In6.Cu")
		(net "M_H_CPU0_SA_DQ<3>")
	)
	(segment
		(start 413.400494 -310.773826)
		(end 412.359094 -309.732426)
		(width 0.18288)
		(layer "In6.Cu")
		(net "M_H_CPU0_SA_DQ<3>")
	)
	(segment
		(start 414.017968 -310.773826)
		(end 413.400494 -310.773826)
		(width 0.18288)
		(layer "In6.Cu")
		(net "M_H_CPU0_SA_DQ<3>")
	)
	(segment
		(start 377.278646 -278.834596)
		(end 377.171458 -278.772112)
		(width 0.088646)
		(layer "In6.Cu")
		(net "M_H_CPU0_SA_DQ<3>")
	)
	(segment
		(start 387.167882 -280.580592)
		(end 387.134354 -280.580592)
		(width 0.088646)
		(layer "In6.Cu")
		(net "M_H_CPU0_SA_DQ<3>")
	)
	(segment
		(start 422.095422 -311.642252)
		(end 420.00805 -311.642252)
		(width 0.18288)
		(layer "In6.Cu")
		(net "M_H_CPU0_SA_DQ<3>")
	)
	(segment
		(start 438.648094 -314.919614)
		(end 437.50484 -314.919614)
		(width 0.18288)
		(layer "In6.Cu")
		(net "M_H_CPU0_SA_DQ<3>")
	)
	(segment
		(start 388.279132 -282.13304)
		(end 388.017512 -282.13304)
		(width 0.088646)
		(layer "In6.Cu")
		(net "M_H_CPU0_SA_DQ<3>")
	)
	(segment
		(start 452.984362 -314.659518)
		(end 452.601584 -315.042296)
		(width 0.18288)
		(layer "In6.Cu")
		(net "M_H_CPU0_SA_DQ<3>")
	)
	(segment
		(start 429.779176 -313.342274)
		(end 428.719742 -312.28284)
		(width 0.18288)
		(layer "In6.Cu")
		(net "M_H_CPU0_SA_DQ<3>")
	)
	(segment
		(start 428.719742 -312.28284)
		(end 427.483016 -312.28284)
		(width 0.18288)
		(layer "In6.Cu")
		(net "M_H_CPU0_SA_DQ<3>")
	)
	(segment
		(start 448.338194 -314.152026)
		(end 447.093594 -314.152026)
		(width 0.18288)
		(layer "In6.Cu")
		(net "M_H_CPU0_SA_DQ<3>")
	)
	(segment
		(start 438.770776 -315.042296)
		(end 438.648094 -314.919614)
		(width 0.18288)
		(layer "In6.Cu")
		(net "M_H_CPU0_SA_DQ<3>")
	)
	(segment
		(start 447.093594 -314.152026)
		(end 446.446148 -314.799472)
		(width 0.18288)
		(layer "In6.Cu")
		(net "M_H_CPU0_SA_DQ<3>")
	)
	(segment
		(start 387.368034 -280.780744)
		(end 387.167882 -280.580592)
		(width 0.088646)
		(layer "In6.Cu")
		(net "M_H_CPU0_SA_DQ<3>")
	)
	(segment
		(start 419.82517 -311.825132)
		(end 419.82517 -312.031126)
		(width 0.18288)
		(layer "In6.Cu")
		(net "M_H_CPU0_SA_DQ<3>")
	)
	(segment
		(start 378.038868 -278.747728)
		(end 377.937522 -278.769826)
		(width 0.088646)
		(layer "In6.Cu")
		(net "M_H_CPU0_SA_DQ<3>")
	)
	(segment
		(start 394.79855 -284.166818)
		(end 392.764772 -282.13304)
		(width 0.18288)
		(layer "In6.Cu")
		(net "M_H_CPU0_SA_DQ<3>")
	)
	(segment
		(start 453.242934 -314.659518)
		(end 452.984362 -314.659518)
		(width 0.18288)
		(layer "In6.Cu")
		(net "M_H_CPU0_SA_DQ<3>")
	)
	(segment
		(start 378.214128 -278.832056)
		(end 378.130054 -278.783034)
		(width 0.088646)
		(layer "In6.Cu")
		(net "M_H_CPU0_SA_DQ<3>")
	)
	(segment
		(start 430.993042 -313.342274)
		(end 429.779176 -313.342274)
		(width 0.18288)
		(layer "In6.Cu")
		(net "M_H_CPU0_SA_DQ<3>")
	)
	(segment
		(start 432.513994 -314.101226)
		(end 431.751994 -314.101226)
		(width 0.18288)
		(layer "In6.Cu")
		(net "M_H_CPU0_SA_DQ<3>")
	)
	(segment
		(start 377.907042 -278.781002)
		(end 377.829318 -278.82596)
		(width 0.088646)
		(layer "In6.Cu")
		(net "M_H_CPU0_SA_DQ<3>")
	)
	(segment
		(start 415.077148 -310.773826)
		(end 414.894268 -310.590946)
		(width 0.18288)
		(layer "In6.Cu")
		(net "M_H_CPU0_SA_DQ<3>")
	)
	(segment
		(start 442.690758 -315.042296)
		(end 438.770776 -315.042296)
		(width 0.18288)
		(layer "In6.Cu")
		(net "M_H_CPU0_SA_DQ<3>")
	)
	(arc
		(start 383.84226 -278.82596)
		(mid 383.655062 -278.775817)
		(end 383.467864 -278.82596)
		(width 0.088646)
		(layer "In6.Cu")
		(net "M_H_CPU0_SA_DQ<3>")
	)
	(arc
		(start 381.57785 -278.832056)
		(mid 381.299672 -278.901779)
		(end 381.023114 -278.82596)
		(width 0.088646)
		(layer "In6.Cu")
		(net "M_H_CPU0_SA_DQ<3>")
	)
	(arc
		(start 385.72186 -280.453846)
		(mid 385.519574 -280.254865)
		(end 385.439412 -279.982676)
		(width 0.088646)
		(layer "In6.Cu")
		(net "M_H_CPU0_SA_DQ<3>")
	)
	(arc
		(start 385.439412 -279.964134)
		(mid 385.391733 -279.781234)
		(end 385.26085 -279.644856)
		(width 0.088646)
		(layer "In6.Cu")
		(net "M_H_CPU0_SA_DQ<3>")
	)
	(arc
		(start 384.78206 -278.82596)
		(mid 384.594862 -278.775817)
		(end 384.407664 -278.82596)
		(width 0.088646)
		(layer "In6.Cu")
		(net "M_H_CPU0_SA_DQ<3>")
	)
	(arc
		(start 382.90246 -278.82596)
		(mid 382.715262 -278.775817)
		(end 382.528064 -278.82596)
		(width 0.088646)
		(layer "In6.Cu")
		(net "M_H_CPU0_SA_DQ<3>")
	)
	(arc
		(start 386.661914 -280.453846)
		(mid 386.474716 -280.403703)
		(end 386.287518 -280.453846)
		(width 0.088646)
		(layer "In6.Cu")
		(net "M_H_CPU0_SA_DQ<3>")
	)
	(arc
		(start 381.96266 -278.82596)
		(mid 381.775462 -278.775817)
		(end 381.588264 -278.82596)
		(width 0.088646)
		(layer "In6.Cu")
		(net "M_H_CPU0_SA_DQ<3>")
	)
	(arc
		(start 380.648718 -278.82596)
		(mid 380.366016 -278.901736)
		(end 380.083314 -278.82596)
		(width 0.088646)
		(layer "In6.Cu")
		(net "M_H_CPU0_SA_DQ<3>")
	)
	(arc
		(start 377.829318 -278.82596)
		(mid 377.555119 -278.901795)
		(end 377.278646 -278.834596)
		(width 0.088646)
		(layer "In6.Cu")
		(net "M_H_CPU0_SA_DQ<3>")
	)
	(arc
		(start 386.277104 -280.459942)
		(mid 385.998672 -280.529756)
		(end 385.72186 -280.453846)
		(width 0.088646)
		(layer "In6.Cu")
		(net "M_H_CPU0_SA_DQ<3>")
	)
	(arc
		(start 377.171458 -278.772112)
		(mid 376.874861 -278.572656)
		(end 376.606562 -278.336502)
		(width 0.088646)
		(layer "In6.Cu")
		(net "M_H_CPU0_SA_DQ<3>")
	)
	(arc
		(start 387.134354 -280.580592)
		(mid 386.889777 -280.548363)
		(end 386.661914 -280.453846)
		(width 0.088646)
		(layer "In6.Cu")
		(net "M_H_CPU0_SA_DQ<3>")
	)
	(arc
		(start 383.467864 -278.82596)
		(mid 383.185162 -278.901736)
		(end 382.90246 -278.82596)
		(width 0.088646)
		(layer "In6.Cu")
		(net "M_H_CPU0_SA_DQ<3>")
	)
	(arc
		(start 379.698504 -278.832056)
		(mid 379.420072 -278.901902)
		(end 379.14326 -278.82596)
		(width 0.088646)
		(layer "In6.Cu")
		(net "M_H_CPU0_SA_DQ<3>")
	)
	(arc
		(start 378.768864 -278.82596)
		(mid 378.492305 -278.901703)
		(end 378.214128 -278.832056)
		(width 0.088646)
		(layer "In6.Cu")
		(net "M_H_CPU0_SA_DQ<3>")
	)
	(arc
		(start 385.25196 -279.639776)
		(mid 385.047625 -279.437171)
		(end 384.969512 -279.160224)
		(width 0.088646)
		(layer "In6.Cu")
		(net "M_H_CPU0_SA_DQ<3>")
	)
	(arc
		(start 384.969512 -279.150318)
		(mid 384.921833 -278.967418)
		(end 384.79095 -278.83104)
		(width 0.088646)
		(layer "In6.Cu")
		(net "M_H_CPU0_SA_DQ<3>")
	)
	(arc
		(start 379.14326 -278.82596)
		(mid 378.956062 -278.775817)
		(end 378.768864 -278.82596)
		(width 0.088646)
		(layer "In6.Cu")
		(net "M_H_CPU0_SA_DQ<3>")
	)
	(arc
		(start 380.083314 -278.82596)
		(mid 379.896116 -278.775817)
		(end 379.708918 -278.82596)
		(width 0.088646)
		(layer "In6.Cu")
		(net "M_H_CPU0_SA_DQ<3>")
	)
	(arc
		(start 381.023114 -278.82596)
		(mid 380.835916 -278.775817)
		(end 380.648718 -278.82596)
		(width 0.088646)
		(layer "In6.Cu")
		(net "M_H_CPU0_SA_DQ<3>")
	)
	(arc
		(start 382.528064 -278.82596)
		(mid 382.245362 -278.901736)
		(end 381.96266 -278.82596)
		(width 0.088646)
		(layer "In6.Cu")
		(net "M_H_CPU0_SA_DQ<3>")
	)
	(arc
		(start 384.407664 -278.82596)
		(mid 384.124962 -278.901736)
		(end 383.84226 -278.82596)
		(width 0.088646)
		(layer "In6.Cu")
		(net "M_H_CPU0_SA_DQ<3>")
	)
	(arc
		(start 377.937522 -278.769826)
		(mid 377.921783 -278.774056)
		(end 377.907042 -278.781002)
		(width 0.088646)
		(layer "In6.Cu")
		(net "M_H_CPU0_SA_DQ<3>")
	)
	(segment
		(start 460.570326 -280.20391)
		(end 461.251554 -280.20391)
		(width 0.20066)
		(layer "F.Cu")
		(net "M_H_CPU0_SA_DQ<31>")
	)
	(segment
		(start 458.538326 -280.19883)
		(end 458.543152 -280.19883)
		(width 0.101854)
		(layer "F.Cu")
		(net "M_H_CPU0_SA_DQ<31>")
	)
	(segment
		(start 458.550264 -280.191718)
		(end 460.558134 -280.191718)
		(width 0.1016)
		(layer "F.Cu")
		(net "M_H_CPU0_SA_DQ<31>")
	)
	(segment
		(start 372.847362 -263.150604)
		(end 372.847362 -263.68629)
		(width 0.20066)
		(layer "F.Cu")
		(net "M_H_CPU0_SA_DQ<31>")
	)
	(segment
		(start 456.116182 -279.766776)
		(end 457.814426 -279.766776)
		(width 0.20066)
		(layer "F.Cu")
		(net "M_H_CPU0_SA_DQ<31>")
	)
	(segment
		(start 460.558134 -280.191718)
		(end 460.570326 -280.20391)
		(width 0.1016)
		(layer "F.Cu")
		(net "M_H_CPU0_SA_DQ<31>")
	)
	(segment
		(start 461.689704 -279.514808)
		(end 462.073752 -279.514808)
		(width 0.20066)
		(layer "F.Cu")
		(net "M_H_CPU0_SA_DQ<31>")
	)
	(segment
		(start 462.32572 -279.766776)
		(end 463.659982 -279.766776)
		(width 0.20066)
		(layer "F.Cu")
		(net "M_H_CPU0_SA_DQ<31>")
	)
	(segment
		(start 461.251554 -280.20391)
		(end 461.455516 -279.999948)
		(width 0.20066)
		(layer "F.Cu")
		(net "M_H_CPU0_SA_DQ<31>")
	)
	(segment
		(start 455.011282 -279.766776)
		(end 456.116182 -279.766776)
		(width 0.20066)
		(layer "F.Cu")
		(net "M_H_CPU0_SA_DQ<31>")
	)
	(segment
		(start 461.455516 -279.999948)
		(end 461.455516 -279.748996)
		(width 0.20066)
		(layer "F.Cu")
		(net "M_H_CPU0_SA_DQ<31>")
	)
	(segment
		(start 461.455516 -279.748996)
		(end 461.689704 -279.514808)
		(width 0.20066)
		(layer "F.Cu")
		(net "M_H_CPU0_SA_DQ<31>")
	)
	(segment
		(start 462.073752 -279.514808)
		(end 462.32572 -279.766776)
		(width 0.20066)
		(layer "F.Cu")
		(net "M_H_CPU0_SA_DQ<31>")
	)
	(segment
		(start 458.543152 -280.19883)
		(end 458.550264 -280.191718)
		(width 0.1016)
		(layer "F.Cu")
		(net "M_H_CPU0_SA_DQ<31>")
	)
	(segment
		(start 458.24648 -280.19883)
		(end 458.538326 -280.19883)
		(width 0.20066)
		(layer "F.Cu")
		(net "M_H_CPU0_SA_DQ<31>")
	)
	(segment
		(start 372.847362 -263.68629)
		(end 372.847616 -263.686544)
		(width 0.20066)
		(layer "F.Cu")
		(net "M_H_CPU0_SA_DQ<31>")
	)
	(segment
		(start 457.814426 -279.766776)
		(end 458.24648 -280.19883)
		(width 0.20066)
		(layer "F.Cu")
		(net "M_H_CPU0_SA_DQ<31>")
	)
	(segment
		(start 429.67529 -281.427936)
		(end 429.48225 -281.234896)
		(width 0.18288)
		(layer "In11.Cu")
		(net "M_H_CPU0_SA_DQ<31>")
	)
	(segment
		(start 410.774642 -280.141426)
		(end 409.535122 -280.141426)
		(width 0.18288)
		(layer "In11.Cu")
		(net "M_H_CPU0_SA_DQ<31>")
	)
	(segment
		(start 382.528064 -263.196832)
		(end 382.513332 -263.188196)
		(width 0.088646)
		(layer "In11.Cu")
		(net "M_H_CPU0_SA_DQ<31>")
	)
	(segment
		(start 448.126104 -280.5811)
		(end 447.605912 -281.101292)
		(width 0.18288)
		(layer "In11.Cu")
		(net "M_H_CPU0_SA_DQ<31>")
	)
	(segment
		(start 442.610494 -281.767026)
		(end 440.887612 -281.767026)
		(width 0.18288)
		(layer "In11.Cu")
		(net "M_H_CPU0_SA_DQ<31>")
	)
	(segment
		(start 427.469808 -281.71394)
		(end 426.933868 -281.71394)
		(width 0.18288)
		(layer "In11.Cu")
		(net "M_H_CPU0_SA_DQ<31>")
	)
	(segment
		(start 440.887612 -281.767026)
		(end 440.760358 -281.89428)
		(width 0.18288)
		(layer "In11.Cu")
		(net "M_H_CPU0_SA_DQ<31>")
	)
	(segment
		(start 428.97171 -281.78125)
		(end 428.77867 -281.97429)
		(width 0.18288)
		(layer "In11.Cu")
		(net "M_H_CPU0_SA_DQ<31>")
	)
	(segment
		(start 405.214836 -278.53767)
		(end 404.41626 -278.53767)
		(width 0.18288)
		(layer "In11.Cu")
		(net "M_H_CPU0_SA_DQ<31>")
	)
	(segment
		(start 374.069864 -263.196832)
		(end 374.05945 -263.190736)
		(width 0.088646)
		(layer "In11.Cu")
		(net "M_H_CPU0_SA_DQ<31>")
	)
	(segment
		(start 388.027672 -266.531852)
		(end 387.86308 -266.531852)
		(width 0.088646)
		(layer "In11.Cu")
		(net "M_H_CPU0_SA_DQ<31>")
	)
	(segment
		(start 437.127904 -281.89428)
		(end 436.271924 -281.0383)
		(width 0.18288)
		(layer "In11.Cu")
		(net "M_H_CPU0_SA_DQ<31>")
	)
	(segment
		(start 444.853568 -281.38882)
		(end 444.660528 -281.19578)
		(width 0.18288)
		(layer "In11.Cu")
		(net "M_H_CPU0_SA_DQ<31>")
	)
	(segment
		(start 419.522402 -282.961334)
		(end 418.78631 -282.225242)
		(width 0.18288)
		(layer "In11.Cu")
		(net "M_H_CPU0_SA_DQ<31>")
	)
	(segment
		(start 443.956948 -281.919426)
		(end 442.762894 -281.919426)
		(width 0.18288)
		(layer "In11.Cu")
		(net "M_H_CPU0_SA_DQ<31>")
	)
	(segment
		(start 372.660418 -264.010902)
		(end 372.651528 -264.005822)
		(width 0.088646)
		(layer "In11.Cu")
		(net "M_H_CPU0_SA_DQ<31>")
	)
	(segment
		(start 376.889264 -263.196832)
		(end 376.874532 -263.188196)
		(width 0.088646)
		(layer "In11.Cu")
		(net "M_H_CPU0_SA_DQ<31>")
	)
	(segment
		(start 454.429876 -280.348182)
		(end 452.028814 -280.348182)
		(width 0.18288)
		(layer "In11.Cu")
		(net "M_H_CPU0_SA_DQ<31>")
	)
	(segment
		(start 418.78631 -282.225242)
		(end 418.095938 -282.225242)
		(width 0.18288)
		(layer "In11.Cu")
		(net "M_H_CPU0_SA_DQ<31>")
	)
	(segment
		(start 429.48225 -281.234896)
		(end 429.16475 -281.234896)
		(width 0.18288)
		(layer "In11.Cu")
		(net "M_H_CPU0_SA_DQ<31>")
	)
	(segment
		(start 444.660528 -281.19578)
		(end 444.343028 -281.19578)
		(width 0.18288)
		(layer "In11.Cu")
		(net "M_H_CPU0_SA_DQ<31>")
	)
	(segment
		(start 413.100012 -280.670508)
		(end 412.70301 -281.06751)
		(width 0.18288)
		(layer "In11.Cu")
		(net "M_H_CPU0_SA_DQ<31>")
	)
	(segment
		(start 434.694584 -281.293062)
		(end 431.959258 -281.293062)
		(width 0.18288)
		(layer "In11.Cu")
		(net "M_H_CPU0_SA_DQ<31>")
	)
	(segment
		(start 422.660572 -282.742894)
		(end 420.047166 -282.742894)
		(width 0.18288)
		(layer "In11.Cu")
		(net "M_H_CPU0_SA_DQ<31>")
	)
	(segment
		(start 440.760358 -281.89428)
		(end 437.127904 -281.89428)
		(width 0.18288)
		(layer "In11.Cu")
		(net "M_H_CPU0_SA_DQ<31>")
	)
	(segment
		(start 384.877818 -265.638534)
		(end 384.868928 -265.633454)
		(width 0.088646)
		(layer "In11.Cu")
		(net "M_H_CPU0_SA_DQ<31>")
	)
	(segment
		(start 409.209494 -279.815798)
		(end 409.209494 -279.582626)
		(width 0.18288)
		(layer "In11.Cu")
		(net "M_H_CPU0_SA_DQ<31>")
	)
	(segment
		(start 383.750312 -263.686544)
		(end 383.750312 -263.668002)
		(width 0.088646)
		(layer "In11.Cu")
		(net "M_H_CPU0_SA_DQ<31>")
	)
	(segment
		(start 431.959258 -281.293062)
		(end 431.27803 -281.97429)
		(width 0.18288)
		(layer "In11.Cu")
		(net "M_H_CPU0_SA_DQ<31>")
	)
	(segment
		(start 380.648464 -263.196832)
		(end 380.63805 -263.190736)
		(width 0.088646)
		(layer "In11.Cu")
		(net "M_H_CPU0_SA_DQ<31>")
	)
	(segment
		(start 450.14134 -280.06167)
		(end 449.181728 -280.06167)
		(width 0.18288)
		(layer "In11.Cu")
		(net "M_H_CPU0_SA_DQ<31>")
	)
	(segment
		(start 375.949464 -263.196832)
		(end 375.934732 -263.188196)
		(width 0.088646)
		(layer "In11.Cu")
		(net "M_H_CPU0_SA_DQ<31>")
	)
	(segment
		(start 426.756322 -281.891486)
		(end 423.51198 -281.891486)
		(width 0.18288)
		(layer "In11.Cu")
		(net "M_H_CPU0_SA_DQ<31>")
	)
	(segment
		(start 416.541204 -280.670508)
		(end 413.100012 -280.670508)
		(width 0.18288)
		(layer "In11.Cu")
		(net "M_H_CPU0_SA_DQ<31>")
	)
	(segment
		(start 426.933868 -281.71394)
		(end 426.756322 -281.891486)
		(width 0.18288)
		(layer "In11.Cu")
		(net "M_H_CPU0_SA_DQ<31>")
	)
	(segment
		(start 434.949346 -281.0383)
		(end 434.694584 -281.293062)
		(width 0.18288)
		(layer "In11.Cu")
		(net "M_H_CPU0_SA_DQ<31>")
	)
	(segment
		(start 445.836294 -281.919426)
		(end 445.046608 -281.919426)
		(width 0.18288)
		(layer "In11.Cu")
		(net "M_H_CPU0_SA_DQ<31>")
	)
	(segment
		(start 427.730158 -281.97429)
		(end 427.469808 -281.71394)
		(width 0.18288)
		(layer "In11.Cu")
		(net "M_H_CPU0_SA_DQ<31>")
	)
	(segment
		(start 448.662298 -280.5811)
		(end 448.126104 -280.5811)
		(width 0.18288)
		(layer "In11.Cu")
		(net "M_H_CPU0_SA_DQ<31>")
	)
	(segment
		(start 405.374094 -278.696928)
		(end 405.214836 -278.53767)
		(width 0.18288)
		(layer "In11.Cu")
		(net "M_H_CPU0_SA_DQ<31>")
	)
	(segment
		(start 384.41376 -264.828274)
		(end 384.398774 -264.819638)
		(width 0.088646)
		(layer "In11.Cu")
		(net "M_H_CPU0_SA_DQ<31>")
	)
	(segment
		(start 442.762894 -281.919426)
		(end 442.610494 -281.767026)
		(width 0.18288)
		(layer "In11.Cu")
		(net "M_H_CPU0_SA_DQ<31>")
	)
	(segment
		(start 409.209494 -279.582626)
		(end 408.323796 -278.696928)
		(width 0.18288)
		(layer "In11.Cu")
		(net "M_H_CPU0_SA_DQ<31>")
	)
	(segment
		(start 444.149988 -281.38882)
		(end 444.149988 -281.726386)
		(width 0.18288)
		(layer "In11.Cu")
		(net "M_H_CPU0_SA_DQ<31>")
	)
	(segment
		(start 372.477538 -263.743694)
		(end 372.534688 -263.686544)
		(width 0.088646)
		(layer "In11.Cu")
		(net "M_H_CPU0_SA_DQ<31>")
	)
	(segment
		(start 385.817364 -265.638788)
		(end 385.808474 -265.633454)
		(width 0.088646)
		(layer "In11.Cu")
		(net "M_H_CPU0_SA_DQ<31>")
	)
	(segment
		(start 384.220212 -264.50036)
		(end 384.220212 -264.490454)
		(width 0.088646)
		(layer "In11.Cu")
		(net "M_H_CPU0_SA_DQ<31>")
	)
	(segment
		(start 447.605912 -281.101292)
		(end 446.654428 -281.101292)
		(width 0.18288)
		(layer "In11.Cu")
		(net "M_H_CPU0_SA_DQ<31>")
	)
	(segment
		(start 404.41626 -278.53767)
		(end 392.410442 -266.531852)
		(width 0.18288)
		(layer "In11.Cu")
		(net "M_H_CPU0_SA_DQ<31>")
	)
	(segment
		(start 418.095938 -282.225242)
		(end 416.541204 -280.670508)
		(width 0.18288)
		(layer "In11.Cu")
		(net "M_H_CPU0_SA_DQ<31>")
	)
	(segment
		(start 381.588264 -263.196832)
		(end 381.573532 -263.188196)
		(width 0.088646)
		(layer "In11.Cu")
		(net "M_H_CPU0_SA_DQ<31>")
	)
	(segment
		(start 411.700726 -281.06751)
		(end 410.774642 -280.141426)
		(width 0.18288)
		(layer "In11.Cu")
		(net "M_H_CPU0_SA_DQ<31>")
	)
	(segment
		(start 373.043704 -264.005822)
		(end 373.034814 -264.010902)
		(width 0.088646)
		(layer "In11.Cu")
		(net "M_H_CPU0_SA_DQ<31>")
	)
	(segment
		(start 409.535122 -280.141426)
		(end 409.209494 -279.815798)
		(width 0.18288)
		(layer "In11.Cu")
		(net "M_H_CPU0_SA_DQ<31>")
	)
	(segment
		(start 378.768864 -263.196832)
		(end 378.754132 -263.188196)
		(width 0.088646)
		(layer "In11.Cu")
		(net "M_H_CPU0_SA_DQ<31>")
	)
	(segment
		(start 429.86833 -281.97429)
		(end 429.67529 -281.78125)
		(width 0.18288)
		(layer "In11.Cu")
		(net "M_H_CPU0_SA_DQ<31>")
	)
	(segment
		(start 444.853568 -281.726386)
		(end 444.853568 -281.38882)
		(width 0.18288)
		(layer "In11.Cu")
		(net "M_H_CPU0_SA_DQ<31>")
	)
	(segment
		(start 387.86308 -266.531852)
		(end 387.552946 -266.221718)
		(width 0.088646)
		(layer "In11.Cu")
		(net "M_H_CPU0_SA_DQ<31>")
	)
	(segment
		(start 446.654428 -281.101292)
		(end 445.836294 -281.919426)
		(width 0.18288)
		(layer "In11.Cu")
		(net "M_H_CPU0_SA_DQ<31>")
	)
	(segment
		(start 444.149988 -281.726386)
		(end 443.956948 -281.919426)
		(width 0.18288)
		(layer "In11.Cu")
		(net "M_H_CPU0_SA_DQ<31>")
	)
	(segment
		(start 387.552946 -266.221718)
		(end 387.367526 -266.221718)
		(width 0.088646)
		(layer "In11.Cu")
		(net "M_H_CPU0_SA_DQ<31>")
	)
	(segment
		(start 379.708918 -263.196832)
		(end 379.698504 -263.190736)
		(width 0.088646)
		(layer "In11.Cu")
		(net "M_H_CPU0_SA_DQ<31>")
	)
	(segment
		(start 419.828726 -282.961334)
		(end 419.522402 -282.961334)
		(width 0.18288)
		(layer "In11.Cu")
		(net "M_H_CPU0_SA_DQ<31>")
	)
	(segment
		(start 429.67529 -281.78125)
		(end 429.67529 -281.427936)
		(width 0.18288)
		(layer "In11.Cu")
		(net "M_H_CPU0_SA_DQ<31>")
	)
	(segment
		(start 373.222266 -263.66978)
		(end 373.222266 -263.686544)
		(width 0.088646)
		(layer "In11.Cu")
		(net "M_H_CPU0_SA_DQ<31>")
	)
	(segment
		(start 445.046608 -281.919426)
		(end 444.853568 -281.726386)
		(width 0.18288)
		(layer "In11.Cu")
		(net "M_H_CPU0_SA_DQ<31>")
	)
	(segment
		(start 383.937764 -264.010902)
		(end 383.928874 -264.005822)
		(width 0.088646)
		(layer "In11.Cu")
		(net "M_H_CPU0_SA_DQ<31>")
	)
	(segment
		(start 372.534688 -263.686544)
		(end 372.847616 -263.686544)
		(width 0.088646)
		(layer "In11.Cu")
		(net "M_H_CPU0_SA_DQ<31>")
	)
	(segment
		(start 452.028814 -280.348182)
		(end 451.871842 -280.19121)
		(width 0.18288)
		(layer "In11.Cu")
		(net "M_H_CPU0_SA_DQ<31>")
	)
	(segment
		(start 449.181728 -280.06167)
		(end 448.662298 -280.5811)
		(width 0.18288)
		(layer "In11.Cu")
		(net "M_H_CPU0_SA_DQ<31>")
	)
	(segment
		(start 455.011282 -279.766776)
		(end 454.429876 -280.348182)
		(width 0.18288)
		(layer "In11.Cu")
		(net "M_H_CPU0_SA_DQ<31>")
	)
	(segment
		(start 375.009664 -263.196832)
		(end 374.994932 -263.188196)
		(width 0.088646)
		(layer "In11.Cu")
		(net "M_H_CPU0_SA_DQ<31>")
	)
	(segment
		(start 420.047166 -282.742894)
		(end 419.828726 -282.961334)
		(width 0.18288)
		(layer "In11.Cu")
		(net "M_H_CPU0_SA_DQ<31>")
	)
	(segment
		(start 431.27803 -281.97429)
		(end 429.86833 -281.97429)
		(width 0.18288)
		(layer "In11.Cu")
		(net "M_H_CPU0_SA_DQ<31>")
	)
	(segment
		(start 408.323796 -278.696928)
		(end 405.374094 -278.696928)
		(width 0.18288)
		(layer "In11.Cu")
		(net "M_H_CPU0_SA_DQ<31>")
	)
	(segment
		(start 428.77867 -281.97429)
		(end 427.730158 -281.97429)
		(width 0.18288)
		(layer "In11.Cu")
		(net "M_H_CPU0_SA_DQ<31>")
	)
	(segment
		(start 436.271924 -281.0383)
		(end 434.949346 -281.0383)
		(width 0.18288)
		(layer "In11.Cu")
		(net "M_H_CPU0_SA_DQ<31>")
	)
	(segment
		(start 444.343028 -281.19578)
		(end 444.149988 -281.38882)
		(width 0.18288)
		(layer "In11.Cu")
		(net "M_H_CPU0_SA_DQ<31>")
	)
	(segment
		(start 423.51198 -281.891486)
		(end 422.660572 -282.742894)
		(width 0.18288)
		(layer "In11.Cu")
		(net "M_H_CPU0_SA_DQ<31>")
	)
	(segment
		(start 392.410442 -266.531852)
		(end 388.027672 -266.531852)
		(width 0.18288)
		(layer "In11.Cu")
		(net "M_H_CPU0_SA_DQ<31>")
	)
	(segment
		(start 451.871842 -280.19121)
		(end 450.27088 -280.19121)
		(width 0.18288)
		(layer "In11.Cu")
		(net "M_H_CPU0_SA_DQ<31>")
	)
	(segment
		(start 429.16475 -281.234896)
		(end 428.97171 -281.427936)
		(width 0.18288)
		(layer "In11.Cu")
		(net "M_H_CPU0_SA_DQ<31>")
	)
	(segment
		(start 412.70301 -281.06751)
		(end 411.700726 -281.06751)
		(width 0.18288)
		(layer "In11.Cu")
		(net "M_H_CPU0_SA_DQ<31>")
	)
	(segment
		(start 450.27088 -280.19121)
		(end 450.14134 -280.06167)
		(width 0.18288)
		(layer "In11.Cu")
		(net "M_H_CPU0_SA_DQ<31>")
	)
	(segment
		(start 428.97171 -281.427936)
		(end 428.97171 -281.78125)
		(width 0.18288)
		(layer "In11.Cu")
		(net "M_H_CPU0_SA_DQ<31>")
	)
	(segment
		(start 387.367526 -266.221718)
		(end 386.874258 -265.72845)
		(width 0.088646)
		(layer "In11.Cu")
		(net "M_H_CPU0_SA_DQ<31>")
	)
	(arc
		(start 386.19176 -265.638788)
		(mid 386.004562 -265.688965)
		(end 385.817364 -265.638788)
		(width 0.088646)
		(layer "In11.Cu")
		(net "M_H_CPU0_SA_DQ<31>")
	)
	(arc
		(start 379.698504 -263.190736)
		(mid 379.420072 -263.120922)
		(end 379.14326 -263.196832)
		(width 0.088646)
		(layer "In11.Cu")
		(net "M_H_CPU0_SA_DQ<31>")
	)
	(arc
		(start 374.05945 -263.190736)
		(mid 373.781272 -263.121044)
		(end 373.504714 -263.196832)
		(width 0.088646)
		(layer "In11.Cu")
		(net "M_H_CPU0_SA_DQ<31>")
	)
	(arc
		(start 378.754132 -263.188196)
		(mid 378.477691 -263.12103)
		(end 378.20346 -263.196832)
		(width 0.088646)
		(layer "In11.Cu")
		(net "M_H_CPU0_SA_DQ<31>")
	)
	(arc
		(start 373.222266 -263.686544)
		(mid 373.174587 -263.869444)
		(end 373.043704 -264.005822)
		(width 0.088646)
		(layer "In11.Cu")
		(net "M_H_CPU0_SA_DQ<31>")
	)
	(arc
		(start 376.32386 -263.196832)
		(mid 376.136662 -263.246975)
		(end 375.949464 -263.196832)
		(width 0.088646)
		(layer "In11.Cu")
		(net "M_H_CPU0_SA_DQ<31>")
	)
	(arc
		(start 375.38406 -263.196832)
		(mid 375.196862 -263.246975)
		(end 375.009664 -263.196832)
		(width 0.088646)
		(layer "In11.Cu")
		(net "M_H_CPU0_SA_DQ<31>")
	)
	(arc
		(start 373.504714 -263.196832)
		(mid 373.301972 -263.396575)
		(end 373.222266 -263.66978)
		(width 0.088646)
		(layer "In11.Cu")
		(net "M_H_CPU0_SA_DQ<31>")
	)
	(arc
		(start 377.829064 -263.196832)
		(mid 377.546362 -263.12109)
		(end 377.26366 -263.196832)
		(width 0.088646)
		(layer "In11.Cu")
		(net "M_H_CPU0_SA_DQ<31>")
	)
	(arc
		(start 380.083314 -263.196832)
		(mid 379.896116 -263.246975)
		(end 379.708918 -263.196832)
		(width 0.088646)
		(layer "In11.Cu")
		(net "M_H_CPU0_SA_DQ<31>")
	)
	(arc
		(start 386.874258 -265.72845)
		(mid 386.818653 -265.679776)
		(end 386.757164 -265.638788)
		(width 0.088646)
		(layer "In11.Cu")
		(net "M_H_CPU0_SA_DQ<31>")
	)
	(arc
		(start 381.573532 -263.188196)
		(mid 381.297091 -263.12103)
		(end 381.02286 -263.196832)
		(width 0.088646)
		(layer "In11.Cu")
		(net "M_H_CPU0_SA_DQ<31>")
	)
	(arc
		(start 384.868928 -265.633454)
		(mid 384.738014 -265.497094)
		(end 384.690366 -265.314176)
		(width 0.088646)
		(layer "In11.Cu")
		(net "M_H_CPU0_SA_DQ<31>")
	)
	(arc
		(start 376.874532 -263.188196)
		(mid 376.598091 -263.12103)
		(end 376.32386 -263.196832)
		(width 0.088646)
		(layer "In11.Cu")
		(net "M_H_CPU0_SA_DQ<31>")
	)
	(arc
		(start 381.96266 -263.196832)
		(mid 381.775462 -263.246975)
		(end 381.588264 -263.196832)
		(width 0.088646)
		(layer "In11.Cu")
		(net "M_H_CPU0_SA_DQ<31>")
	)
	(arc
		(start 383.467864 -263.196832)
		(mid 383.185162 -263.12109)
		(end 382.90246 -263.196832)
		(width 0.088646)
		(layer "In11.Cu")
		(net "M_H_CPU0_SA_DQ<31>")
	)
	(arc
		(start 382.513332 -263.188196)
		(mid 382.236891 -263.12103)
		(end 381.96266 -263.196832)
		(width 0.088646)
		(layer "In11.Cu")
		(net "M_H_CPU0_SA_DQ<31>")
	)
	(arc
		(start 380.63805 -263.190736)
		(mid 380.359872 -263.121044)
		(end 380.083314 -263.196832)
		(width 0.088646)
		(layer "In11.Cu")
		(net "M_H_CPU0_SA_DQ<31>")
	)
	(arc
		(start 385.808474 -265.633454)
		(mid 385.529686 -265.562891)
		(end 385.252214 -265.638534)
		(width 0.088646)
		(layer "In11.Cu")
		(net "M_H_CPU0_SA_DQ<31>")
	)
	(arc
		(start 385.252214 -265.638534)
		(mid 385.065016 -265.688677)
		(end 384.877818 -265.638534)
		(width 0.088646)
		(layer "In11.Cu")
		(net "M_H_CPU0_SA_DQ<31>")
	)
	(arc
		(start 375.934732 -263.188196)
		(mid 375.658291 -263.12103)
		(end 375.38406 -263.196832)
		(width 0.088646)
		(layer "In11.Cu")
		(net "M_H_CPU0_SA_DQ<31>")
	)
	(arc
		(start 383.750312 -263.668002)
		(mid 383.67015 -263.395813)
		(end 383.467864 -263.196832)
		(width 0.088646)
		(layer "In11.Cu")
		(net "M_H_CPU0_SA_DQ<31>")
	)
	(arc
		(start 381.02286 -263.196832)
		(mid 380.835662 -263.246975)
		(end 380.648464 -263.196832)
		(width 0.088646)
		(layer "In11.Cu")
		(net "M_H_CPU0_SA_DQ<31>")
	)
	(arc
		(start 379.14326 -263.196832)
		(mid 378.956062 -263.246975)
		(end 378.768864 -263.196832)
		(width 0.088646)
		(layer "In11.Cu")
		(net "M_H_CPU0_SA_DQ<31>")
	)
	(arc
		(start 383.928874 -264.005822)
		(mid 383.79796 -263.869462)
		(end 383.750312 -263.686544)
		(width 0.088646)
		(layer "In11.Cu")
		(net "M_H_CPU0_SA_DQ<31>")
	)
	(arc
		(start 372.651528 -264.005822)
		(mid 372.535719 -263.893893)
		(end 372.477538 -263.743694)
		(width 0.088646)
		(layer "In11.Cu")
		(net "M_H_CPU0_SA_DQ<31>")
	)
	(arc
		(start 384.220212 -264.490454)
		(mid 384.142101 -264.213505)
		(end 383.937764 -264.010902)
		(width 0.088646)
		(layer "In11.Cu")
		(net "M_H_CPU0_SA_DQ<31>")
	)
	(arc
		(start 377.26366 -263.196832)
		(mid 377.076462 -263.246975)
		(end 376.889264 -263.196832)
		(width 0.088646)
		(layer "In11.Cu")
		(net "M_H_CPU0_SA_DQ<31>")
	)
	(arc
		(start 374.44426 -263.196832)
		(mid 374.257062 -263.246975)
		(end 374.069864 -263.196832)
		(width 0.088646)
		(layer "In11.Cu")
		(net "M_H_CPU0_SA_DQ<31>")
	)
	(arc
		(start 378.20346 -263.196832)
		(mid 378.016262 -263.246975)
		(end 377.829064 -263.196832)
		(width 0.088646)
		(layer "In11.Cu")
		(net "M_H_CPU0_SA_DQ<31>")
	)
	(arc
		(start 384.690366 -265.314176)
		(mid 384.616375 -265.03461)
		(end 384.41376 -264.828274)
		(width 0.088646)
		(layer "In11.Cu")
		(net "M_H_CPU0_SA_DQ<31>")
	)
	(arc
		(start 386.757164 -265.638788)
		(mid 386.474462 -265.563012)
		(end 386.19176 -265.638788)
		(width 0.088646)
		(layer "In11.Cu")
		(net "M_H_CPU0_SA_DQ<31>")
	)
	(arc
		(start 384.398774 -264.819638)
		(mid 384.26786 -264.683278)
		(end 384.220212 -264.50036)
		(width 0.088646)
		(layer "In11.Cu")
		(net "M_H_CPU0_SA_DQ<31>")
	)
	(arc
		(start 382.90246 -263.196832)
		(mid 382.715262 -263.246975)
		(end 382.528064 -263.196832)
		(width 0.088646)
		(layer "In11.Cu")
		(net "M_H_CPU0_SA_DQ<31>")
	)
	(arc
		(start 374.994932 -263.188196)
		(mid 374.718491 -263.12103)
		(end 374.44426 -263.196832)
		(width 0.088646)
		(layer "In11.Cu")
		(net "M_H_CPU0_SA_DQ<31>")
	)
	(arc
		(start 373.034814 -264.010902)
		(mid 372.847616 -264.061045)
		(end 372.660418 -264.010902)
		(width 0.088646)
		(layer "In11.Cu")
		(net "M_H_CPU0_SA_DQ<31>")
	)
	(segment
		(start 458.538326 -281.898852)
		(end 458.543152 -281.898852)
		(width 0.101854)
		(layer "F.Cu")
		(net "M_H_CPU0_SA_DQ<30>")
	)
	(segment
		(start 458.550264 -281.89174)
		(end 460.558134 -281.89174)
		(width 0.1016)
		(layer "F.Cu")
		(net "M_H_CPU0_SA_DQ<30>")
	)
	(segment
		(start 373.317516 -264.500106)
		(end 373.317262 -264.50036)
		(width 0.20066)
		(layer "F.Cu")
		(net "M_H_CPU0_SA_DQ<30>")
	)
	(segment
		(start 460.558134 -281.89174)
		(end 460.570326 -281.903932)
		(width 0.1016)
		(layer "F.Cu")
		(net "M_H_CPU0_SA_DQ<30>")
	)
	(segment
		(start 461.251554 -281.903932)
		(end 461.455516 -281.69997)
		(width 0.20066)
		(layer "F.Cu")
		(net "M_H_CPU0_SA_DQ<30>")
	)
	(segment
		(start 456.116182 -281.466798)
		(end 457.814426 -281.466798)
		(width 0.20066)
		(layer "F.Cu")
		(net "M_H_CPU0_SA_DQ<30>")
	)
	(segment
		(start 460.570326 -281.903932)
		(end 461.251554 -281.903932)
		(width 0.20066)
		(layer "F.Cu")
		(net "M_H_CPU0_SA_DQ<30>")
	)
	(segment
		(start 461.455516 -281.449018)
		(end 461.689704 -281.21483)
		(width 0.20066)
		(layer "F.Cu")
		(net "M_H_CPU0_SA_DQ<30>")
	)
	(segment
		(start 457.814426 -281.466798)
		(end 458.24648 -281.898852)
		(width 0.20066)
		(layer "F.Cu")
		(net "M_H_CPU0_SA_DQ<30>")
	)
	(segment
		(start 462.073752 -281.21483)
		(end 462.32572 -281.466798)
		(width 0.20066)
		(layer "F.Cu")
		(net "M_H_CPU0_SA_DQ<30>")
	)
	(segment
		(start 373.317516 -263.96442)
		(end 373.317516 -264.500106)
		(width 0.20066)
		(layer "F.Cu")
		(net "M_H_CPU0_SA_DQ<30>")
	)
	(segment
		(start 461.689704 -281.21483)
		(end 462.073752 -281.21483)
		(width 0.20066)
		(layer "F.Cu")
		(net "M_H_CPU0_SA_DQ<30>")
	)
	(segment
		(start 461.455516 -281.69997)
		(end 461.455516 -281.449018)
		(width 0.20066)
		(layer "F.Cu")
		(net "M_H_CPU0_SA_DQ<30>")
	)
	(segment
		(start 458.24648 -281.898852)
		(end 458.538326 -281.898852)
		(width 0.20066)
		(layer "F.Cu")
		(net "M_H_CPU0_SA_DQ<30>")
	)
	(segment
		(start 462.32572 -281.466798)
		(end 463.659982 -281.466798)
		(width 0.20066)
		(layer "F.Cu")
		(net "M_H_CPU0_SA_DQ<30>")
	)
	(segment
		(start 455.011536 -281.466798)
		(end 456.116182 -281.466798)
		(width 0.20066)
		(layer "F.Cu")
		(net "M_H_CPU0_SA_DQ<30>")
	)
	(segment
		(start 455.011282 -281.466544)
		(end 455.011536 -281.466798)
		(width 0.20066)
		(layer "F.Cu")
		(net "M_H_CPU0_SA_DQ<30>")
	)
	(segment
		(start 458.543152 -281.898852)
		(end 458.550264 -281.89174)
		(width 0.1016)
		(layer "F.Cu")
		(net "M_H_CPU0_SA_DQ<30>")
	)
	(segment
		(start 454.406 -282.071826)
		(end 453.870314 -282.071826)
		(width 0.18288)
		(layer "In11.Cu")
		(net "M_H_CPU0_SA_DQ<30>")
	)
	(segment
		(start 383.938018 -265.638534)
		(end 383.929128 -265.633454)
		(width 0.088646)
		(layer "In11.Cu")
		(net "M_H_CPU0_SA_DQ<30>")
	)
	(segment
		(start 387.175502 -267.547852)
		(end 386.569458 -266.941808)
		(width 0.088646)
		(layer "In11.Cu")
		(net "M_H_CPU0_SA_DQ<30>")
	)
	(segment
		(start 376.804428 -264.004806)
		(end 376.794014 -264.010902)
		(width 0.088646)
		(layer "In11.Cu")
		(net "M_H_CPU0_SA_DQ<30>")
	)
	(segment
		(start 453.406256 -280.954226)
		(end 452.829168 -280.954226)
		(width 0.18288)
		(layer "In11.Cu")
		(net "M_H_CPU0_SA_DQ<30>")
	)
	(segment
		(start 452.829168 -280.954226)
		(end 452.668894 -281.1145)
		(width 0.18288)
		(layer "In11.Cu")
		(net "M_H_CPU0_SA_DQ<30>")
	)
	(segment
		(start 419.352984 -285.323026)
		(end 418.652706 -284.622748)
		(width 0.18288)
		(layer "In11.Cu")
		(net "M_H_CPU0_SA_DQ<30>")
	)
	(segment
		(start 383.280412 -264.50036)
		(end 383.280412 -264.490454)
		(width 0.088646)
		(layer "In11.Cu")
		(net "M_H_CPU0_SA_DQ<30>")
	)
	(segment
		(start 418.652706 -284.622748)
		(end 418.652706 -284.366208)
		(width 0.18288)
		(layer "In11.Cu")
		(net "M_H_CPU0_SA_DQ<30>")
	)
	(segment
		(start 391.989056 -267.547852)
		(end 388.027672 -267.547852)
		(width 0.18288)
		(layer "In11.Cu")
		(net "M_H_CPU0_SA_DQ<30>")
	)
	(segment
		(start 383.467864 -264.824718)
		(end 383.458974 -264.819638)
		(width 0.088646)
		(layer "In11.Cu")
		(net "M_H_CPU0_SA_DQ<30>")
	)
	(segment
		(start 452.508874 -282.071826)
		(end 451.985888 -282.071826)
		(width 0.18288)
		(layer "In11.Cu")
		(net "M_H_CPU0_SA_DQ<30>")
	)
	(segment
		(start 418.91458 -284.10408)
		(end 418.91458 -283.87802)
		(width 0.18288)
		(layer "In11.Cu")
		(net "M_H_CPU0_SA_DQ<30>")
	)
	(segment
		(start 418.6682 -283.63164)
		(end 418.44214 -283.63164)
		(width 0.18288)
		(layer "In11.Cu")
		(net "M_H_CPU0_SA_DQ<30>")
	)
	(segment
		(start 419.979094 -285.323026)
		(end 419.352984 -285.323026)
		(width 0.18288)
		(layer "In11.Cu")
		(net "M_H_CPU0_SA_DQ<30>")
	)
	(segment
		(start 434.55463 -283.748226)
		(end 426.085 -283.748226)
		(width 0.18288)
		(layer "In11.Cu")
		(net "M_H_CPU0_SA_DQ<30>")
	)
	(segment
		(start 412.333694 -283.037026)
		(end 411.927294 -283.037026)
		(width 0.18288)
		(layer "In11.Cu")
		(net "M_H_CPU0_SA_DQ<30>")
	)
	(segment
		(start 388.027672 -267.547852)
		(end 387.175502 -267.547852)
		(width 0.088646)
		(layer "In11.Cu")
		(net "M_H_CPU0_SA_DQ<30>")
	)
	(segment
		(start 436.297324 -282.740862)
		(end 435.561994 -282.740862)
		(width 0.18288)
		(layer "In11.Cu")
		(net "M_H_CPU0_SA_DQ<30>")
	)
	(segment
		(start 450.433948 -281.665426)
		(end 448.895978 -281.665426)
		(width 0.18288)
		(layer "In11.Cu")
		(net "M_H_CPU0_SA_DQ<30>")
	)
	(segment
		(start 377.743974 -264.004806)
		(end 377.73356 -264.010902)
		(width 0.088646)
		(layer "In11.Cu")
		(net "M_H_CPU0_SA_DQ<30>")
	)
	(segment
		(start 420.010336 -285.291784)
		(end 419.979094 -285.323026)
		(width 0.18288)
		(layer "In11.Cu")
		(net "M_H_CPU0_SA_DQ<30>")
	)
	(segment
		(start 410.638244 -281.747976)
		(end 409.343098 -281.747976)
		(width 0.18288)
		(layer "In11.Cu")
		(net "M_H_CPU0_SA_DQ<30>")
	)
	(segment
		(start 451.985888 -282.071826)
		(end 451.805294 -281.891232)
		(width 0.18288)
		(layer "In11.Cu")
		(net "M_H_CPU0_SA_DQ<30>")
	)
	(segment
		(start 373.898414 -264.056114)
		(end 373.317262 -264.50036)
		(width 0.088646)
		(layer "In11.Cu")
		(net "M_H_CPU0_SA_DQ<30>")
	)
	(segment
		(start 435.561994 -282.740862)
		(end 434.55463 -283.748226)
		(width 0.18288)
		(layer "In11.Cu")
		(net "M_H_CPU0_SA_DQ<30>")
	)
	(segment
		(start 453.710294 -281.911806)
		(end 453.710294 -281.258264)
		(width 0.18288)
		(layer "In11.Cu")
		(net "M_H_CPU0_SA_DQ<30>")
	)
	(segment
		(start 422.24071 -284.441138)
		(end 421.390064 -285.291784)
		(width 0.18288)
		(layer "In11.Cu")
		(net "M_H_CPU0_SA_DQ<30>")
	)
	(segment
		(start 378.688346 -264.002266)
		(end 378.673614 -264.010902)
		(width 0.088646)
		(layer "In11.Cu")
		(net "M_H_CPU0_SA_DQ<30>")
	)
	(segment
		(start 452.668894 -281.911806)
		(end 452.508874 -282.071826)
		(width 0.18288)
		(layer "In11.Cu")
		(net "M_H_CPU0_SA_DQ<30>")
	)
	(segment
		(start 451.805294 -281.891232)
		(end 450.659754 -281.891232)
		(width 0.18288)
		(layer "In11.Cu")
		(net "M_H_CPU0_SA_DQ<30>")
	)
	(segment
		(start 447.656712 -282.904692)
		(end 446.455292 -282.904692)
		(width 0.18288)
		(layer "In11.Cu")
		(net "M_H_CPU0_SA_DQ<30>")
	)
	(segment
		(start 412.740094 -282.630626)
		(end 412.333694 -283.037026)
		(width 0.18288)
		(layer "In11.Cu")
		(net "M_H_CPU0_SA_DQ<30>")
	)
	(segment
		(start 417.014152 -283.692092)
		(end 415.952686 -282.630626)
		(width 0.18288)
		(layer "In11.Cu")
		(net "M_H_CPU0_SA_DQ<30>")
	)
	(segment
		(start 418.91458 -283.87802)
		(end 418.6682 -283.63164)
		(width 0.18288)
		(layer "In11.Cu")
		(net "M_H_CPU0_SA_DQ<30>")
	)
	(segment
		(start 409.343098 -281.747976)
		(end 407.921968 -280.326846)
		(width 0.18288)
		(layer "In11.Cu")
		(net "M_H_CPU0_SA_DQ<30>")
	)
	(segment
		(start 384.220212 -266.128246)
		(end 384.220212 -266.106148)
		(width 0.088646)
		(layer "In11.Cu")
		(net "M_H_CPU0_SA_DQ<30>")
	)
	(segment
		(start 445.701166 -283.658818)
		(end 441.617608 -283.658818)
		(width 0.18288)
		(layer "In11.Cu")
		(net "M_H_CPU0_SA_DQ<30>")
	)
	(segment
		(start 441.617608 -283.658818)
		(end 440.835288 -284.441138)
		(width 0.18288)
		(layer "In11.Cu")
		(net "M_H_CPU0_SA_DQ<30>")
	)
	(segment
		(start 425.392088 -284.441138)
		(end 422.24071 -284.441138)
		(width 0.18288)
		(layer "In11.Cu")
		(net "M_H_CPU0_SA_DQ<30>")
	)
	(segment
		(start 407.921968 -280.326846)
		(end 405.444706 -280.326846)
		(width 0.18288)
		(layer "In11.Cu")
		(net "M_H_CPU0_SA_DQ<30>")
	)
	(segment
		(start 418.652706 -284.366208)
		(end 418.91458 -284.10408)
		(width 0.18288)
		(layer "In11.Cu")
		(net "M_H_CPU0_SA_DQ<30>")
	)
	(segment
		(start 379.628146 -264.002266)
		(end 379.613414 -264.010902)
		(width 0.088646)
		(layer "In11.Cu")
		(net "M_H_CPU0_SA_DQ<30>")
	)
	(segment
		(start 417.945316 -283.902658)
		(end 417.73475 -283.692092)
		(width 0.18288)
		(layer "In11.Cu")
		(net "M_H_CPU0_SA_DQ<30>")
	)
	(segment
		(start 453.710294 -281.258264)
		(end 453.406256 -280.954226)
		(width 0.18288)
		(layer "In11.Cu")
		(net "M_H_CPU0_SA_DQ<30>")
	)
	(segment
		(start 453.870314 -282.071826)
		(end 453.710294 -281.911806)
		(width 0.18288)
		(layer "In11.Cu")
		(net "M_H_CPU0_SA_DQ<30>")
	)
	(segment
		(start 455.011282 -281.466544)
		(end 454.406 -282.071826)
		(width 0.18288)
		(layer "In11.Cu")
		(net "M_H_CPU0_SA_DQ<30>")
	)
	(segment
		(start 374.929146 -264.002266)
		(end 374.914414 -264.010902)
		(width 0.088646)
		(layer "In11.Cu")
		(net "M_H_CPU0_SA_DQ<30>")
	)
	(segment
		(start 421.390064 -285.291784)
		(end 420.010336 -285.291784)
		(width 0.18288)
		(layer "In11.Cu")
		(net "M_H_CPU0_SA_DQ<30>")
	)
	(segment
		(start 382.443228 -264.004806)
		(end 382.432814 -264.010902)
		(width 0.088646)
		(layer "In11.Cu")
		(net "M_H_CPU0_SA_DQ<30>")
	)
	(segment
		(start 446.455292 -282.904692)
		(end 445.701166 -283.658818)
		(width 0.18288)
		(layer "In11.Cu")
		(net "M_H_CPU0_SA_DQ<30>")
	)
	(segment
		(start 440.835288 -284.441138)
		(end 437.9976 -284.441138)
		(width 0.18288)
		(layer "In11.Cu")
		(net "M_H_CPU0_SA_DQ<30>")
	)
	(segment
		(start 375.868946 -264.002266)
		(end 375.854214 -264.010902)
		(width 0.088646)
		(layer "In11.Cu")
		(net "M_H_CPU0_SA_DQ<30>")
	)
	(segment
		(start 381.507746 -264.002266)
		(end 381.493014 -264.010902)
		(width 0.088646)
		(layer "In11.Cu")
		(net "M_H_CPU0_SA_DQ<30>")
	)
	(segment
		(start 437.9976 -284.441138)
		(end 436.297324 -282.740862)
		(width 0.18288)
		(layer "In11.Cu")
		(net "M_H_CPU0_SA_DQ<30>")
	)
	(segment
		(start 384.407664 -266.45235)
		(end 384.39344 -266.444222)
		(width 0.088646)
		(layer "In11.Cu")
		(net "M_H_CPU0_SA_DQ<30>")
	)
	(segment
		(start 411.927294 -283.037026)
		(end 410.638244 -281.747976)
		(width 0.18288)
		(layer "In11.Cu")
		(net "M_H_CPU0_SA_DQ<30>")
	)
	(segment
		(start 450.659754 -281.891232)
		(end 450.433948 -281.665426)
		(width 0.18288)
		(layer "In11.Cu")
		(net "M_H_CPU0_SA_DQ<30>")
	)
	(segment
		(start 426.085 -283.748226)
		(end 425.392088 -284.441138)
		(width 0.18288)
		(layer "In11.Cu")
		(net "M_H_CPU0_SA_DQ<30>")
	)
	(segment
		(start 418.171376 -283.902658)
		(end 417.945316 -283.902658)
		(width 0.18288)
		(layer "In11.Cu")
		(net "M_H_CPU0_SA_DQ<30>")
	)
	(segment
		(start 452.668894 -281.1145)
		(end 452.668894 -281.911806)
		(width 0.18288)
		(layer "In11.Cu")
		(net "M_H_CPU0_SA_DQ<30>")
	)
	(segment
		(start 417.73475 -283.692092)
		(end 417.014152 -283.692092)
		(width 0.18288)
		(layer "In11.Cu")
		(net "M_H_CPU0_SA_DQ<30>")
	)
	(segment
		(start 405.444706 -280.326846)
		(end 405.083518 -279.965658)
		(width 0.18288)
		(layer "In11.Cu")
		(net "M_H_CPU0_SA_DQ<30>")
	)
	(segment
		(start 404.406862 -279.965658)
		(end 391.989056 -267.547852)
		(width 0.18288)
		(layer "In11.Cu")
		(net "M_H_CPU0_SA_DQ<30>")
	)
	(segment
		(start 415.952686 -282.630626)
		(end 412.740094 -282.630626)
		(width 0.18288)
		(layer "In11.Cu")
		(net "M_H_CPU0_SA_DQ<30>")
	)
	(segment
		(start 405.083518 -279.965658)
		(end 404.406862 -279.965658)
		(width 0.18288)
		(layer "In11.Cu")
		(net "M_H_CPU0_SA_DQ<30>")
	)
	(segment
		(start 418.44214 -283.63164)
		(end 418.171376 -283.902658)
		(width 0.18288)
		(layer "In11.Cu")
		(net "M_H_CPU0_SA_DQ<30>")
	)
	(segment
		(start 383.47396 -264.828274)
		(end 383.467864 -264.824718)
		(width 0.088646)
		(layer "In11.Cu")
		(net "M_H_CPU0_SA_DQ<30>")
	)
	(segment
		(start 448.895978 -281.665426)
		(end 447.656712 -282.904692)
		(width 0.18288)
		(layer "In11.Cu")
		(net "M_H_CPU0_SA_DQ<30>")
	)
	(segment
		(start 373.974614 -264.010902)
		(end 373.898414 -264.056114)
		(width 0.088646)
		(layer "In11.Cu")
		(net "M_H_CPU0_SA_DQ<30>")
	)
	(arc
		(start 379.239018 -264.010902)
		(mid 378.964819 -263.935067)
		(end 378.688346 -264.002266)
		(width 0.088646)
		(layer "In11.Cu")
		(net "M_H_CPU0_SA_DQ<30>")
	)
	(arc
		(start 377.73356 -264.010902)
		(mid 377.546362 -264.061045)
		(end 377.359164 -264.010902)
		(width 0.088646)
		(layer "In11.Cu")
		(net "M_H_CPU0_SA_DQ<30>")
	)
	(arc
		(start 374.540018 -264.010902)
		(mid 374.257316 -263.935126)
		(end 373.974614 -264.010902)
		(width 0.088646)
		(layer "In11.Cu")
		(net "M_H_CPU0_SA_DQ<30>")
	)
	(arc
		(start 382.058418 -264.010902)
		(mid 381.784219 -263.935067)
		(end 381.507746 -264.002266)
		(width 0.088646)
		(layer "In11.Cu")
		(net "M_H_CPU0_SA_DQ<30>")
	)
	(arc
		(start 384.39344 -266.444222)
		(mid 384.266397 -266.308406)
		(end 384.220212 -266.128246)
		(width 0.088646)
		(layer "In11.Cu")
		(net "M_H_CPU0_SA_DQ<30>")
	)
	(arc
		(start 383.458974 -264.819638)
		(mid 383.32806 -264.683278)
		(end 383.280412 -264.50036)
		(width 0.088646)
		(layer "In11.Cu")
		(net "M_H_CPU0_SA_DQ<30>")
	)
	(arc
		(start 379.613414 -264.010902)
		(mid 379.426216 -264.061045)
		(end 379.239018 -264.010902)
		(width 0.088646)
		(layer "In11.Cu")
		(net "M_H_CPU0_SA_DQ<30>")
	)
	(arc
		(start 385.347464 -266.45235)
		(mid 385.064762 -266.376574)
		(end 384.78206 -266.45235)
		(width 0.088646)
		(layer "In11.Cu")
		(net "M_H_CPU0_SA_DQ<30>")
	)
	(arc
		(start 381.493014 -264.010902)
		(mid 381.305816 -264.061045)
		(end 381.118618 -264.010902)
		(width 0.088646)
		(layer "In11.Cu")
		(net "M_H_CPU0_SA_DQ<30>")
	)
	(arc
		(start 380.178818 -264.010902)
		(mid 379.904619 -263.935067)
		(end 379.628146 -264.002266)
		(width 0.088646)
		(layer "In11.Cu")
		(net "M_H_CPU0_SA_DQ<30>")
	)
	(arc
		(start 384.78206 -266.45235)
		(mid 384.594862 -266.502527)
		(end 384.407664 -266.45235)
		(width 0.088646)
		(layer "In11.Cu")
		(net "M_H_CPU0_SA_DQ<30>")
	)
	(arc
		(start 383.929128 -265.633454)
		(mid 383.798214 -265.497094)
		(end 383.750566 -265.314176)
		(width 0.088646)
		(layer "In11.Cu")
		(net "M_H_CPU0_SA_DQ<30>")
	)
	(arc
		(start 376.419618 -264.010902)
		(mid 376.145419 -263.935067)
		(end 375.868946 -264.002266)
		(width 0.088646)
		(layer "In11.Cu")
		(net "M_H_CPU0_SA_DQ<30>")
	)
	(arc
		(start 374.914414 -264.010902)
		(mid 374.727216 -264.061045)
		(end 374.540018 -264.010902)
		(width 0.088646)
		(layer "In11.Cu")
		(net "M_H_CPU0_SA_DQ<30>")
	)
	(arc
		(start 382.432814 -264.010902)
		(mid 382.245616 -264.061045)
		(end 382.058418 -264.010902)
		(width 0.088646)
		(layer "In11.Cu")
		(net "M_H_CPU0_SA_DQ<30>")
	)
	(arc
		(start 375.479818 -264.010902)
		(mid 375.205619 -263.935067)
		(end 374.929146 -264.002266)
		(width 0.088646)
		(layer "In11.Cu")
		(net "M_H_CPU0_SA_DQ<30>")
	)
	(arc
		(start 380.553214 -264.010902)
		(mid 380.366016 -264.061045)
		(end 380.178818 -264.010902)
		(width 0.088646)
		(layer "In11.Cu")
		(net "M_H_CPU0_SA_DQ<30>")
	)
	(arc
		(start 386.569458 -266.941808)
		(mid 386.526799 -266.725434)
		(end 386.404358 -266.542012)
		(width 0.088646)
		(layer "In11.Cu")
		(net "M_H_CPU0_SA_DQ<30>")
	)
	(arc
		(start 381.118618 -264.010902)
		(mid 380.835916 -263.935126)
		(end 380.553214 -264.010902)
		(width 0.088646)
		(layer "In11.Cu")
		(net "M_H_CPU0_SA_DQ<30>")
	)
	(arc
		(start 377.359164 -264.010902)
		(mid 377.082605 -263.935159)
		(end 376.804428 -264.004806)
		(width 0.088646)
		(layer "In11.Cu")
		(net "M_H_CPU0_SA_DQ<30>")
	)
	(arc
		(start 385.72186 -266.45235)
		(mid 385.534662 -266.502527)
		(end 385.347464 -266.45235)
		(width 0.088646)
		(layer "In11.Cu")
		(net "M_H_CPU0_SA_DQ<30>")
	)
	(arc
		(start 376.794014 -264.010902)
		(mid 376.606816 -264.061045)
		(end 376.419618 -264.010902)
		(width 0.088646)
		(layer "In11.Cu")
		(net "M_H_CPU0_SA_DQ<30>")
	)
	(arc
		(start 384.220212 -266.106148)
		(mid 384.139301 -265.83602)
		(end 383.938018 -265.638534)
		(width 0.088646)
		(layer "In11.Cu")
		(net "M_H_CPU0_SA_DQ<30>")
	)
	(arc
		(start 378.673614 -264.010902)
		(mid 378.486416 -264.061045)
		(end 378.299218 -264.010902)
		(width 0.088646)
		(layer "In11.Cu")
		(net "M_H_CPU0_SA_DQ<30>")
	)
	(arc
		(start 375.854214 -264.010902)
		(mid 375.667016 -264.061045)
		(end 375.479818 -264.010902)
		(width 0.088646)
		(layer "In11.Cu")
		(net "M_H_CPU0_SA_DQ<30>")
	)
	(arc
		(start 382.997964 -264.010902)
		(mid 382.721405 -263.935159)
		(end 382.443228 -264.004806)
		(width 0.088646)
		(layer "In11.Cu")
		(net "M_H_CPU0_SA_DQ<30>")
	)
	(arc
		(start 378.299218 -264.010902)
		(mid 378.022405 -263.935032)
		(end 377.743974 -264.004806)
		(width 0.088646)
		(layer "In11.Cu")
		(net "M_H_CPU0_SA_DQ<30>")
	)
	(arc
		(start 386.287264 -266.45235)
		(mid 386.004562 -266.376574)
		(end 385.72186 -266.45235)
		(width 0.088646)
		(layer "In11.Cu")
		(net "M_H_CPU0_SA_DQ<30>")
	)
	(arc
		(start 383.750566 -265.314176)
		(mid 383.676575 -265.03461)
		(end 383.47396 -264.828274)
		(width 0.088646)
		(layer "In11.Cu")
		(net "M_H_CPU0_SA_DQ<30>")
	)
	(arc
		(start 386.404358 -266.542012)
		(mid 386.348753 -266.493338)
		(end 386.287264 -266.45235)
		(width 0.088646)
		(layer "In11.Cu")
		(net "M_H_CPU0_SA_DQ<30>")
	)
	(arc
		(start 383.280412 -264.490454)
		(mid 383.202301 -264.213505)
		(end 382.997964 -264.010902)
		(width 0.088646)
		(layer "In11.Cu")
		(net "M_H_CPU0_SA_DQ<30>")
	)
	(segment
		(start 458.543152 -315.898784)
		(end 458.550264 -315.891672)
		(width 0.1016)
		(layer "F.Cu")
		(net "M_H_CPU0_SA_DQ<2>")
	)
	(segment
		(start 378.956316 -279.150064)
		(end 378.956062 -279.150318)
		(width 0.20066)
		(layer "F.Cu")
		(net "M_H_CPU0_SA_DQ<2>")
	)
	(segment
		(start 458.538326 -315.898784)
		(end 458.543152 -315.898784)
		(width 0.101854)
		(layer "F.Cu")
		(net "M_H_CPU0_SA_DQ<2>")
	)
	(segment
		(start 462.073752 -315.214762)
		(end 462.32572 -315.46673)
		(width 0.20066)
		(layer "F.Cu")
		(net "M_H_CPU0_SA_DQ<2>")
	)
	(segment
		(start 378.956316 -278.614378)
		(end 378.956316 -279.150064)
		(width 0.20066)
		(layer "F.Cu")
		(net "M_H_CPU0_SA_DQ<2>")
	)
	(segment
		(start 456.116182 -315.46673)
		(end 457.814426 -315.46673)
		(width 0.20066)
		(layer "F.Cu")
		(net "M_H_CPU0_SA_DQ<2>")
	)
	(segment
		(start 457.814426 -315.46673)
		(end 458.24648 -315.898784)
		(width 0.20066)
		(layer "F.Cu")
		(net "M_H_CPU0_SA_DQ<2>")
	)
	(segment
		(start 462.32572 -315.46673)
		(end 463.659982 -315.46673)
		(width 0.20066)
		(layer "F.Cu")
		(net "M_H_CPU0_SA_DQ<2>")
	)
	(segment
		(start 461.251554 -315.903864)
		(end 461.455516 -315.699902)
		(width 0.20066)
		(layer "F.Cu")
		(net "M_H_CPU0_SA_DQ<2>")
	)
	(segment
		(start 461.689704 -315.214762)
		(end 462.073752 -315.214762)
		(width 0.20066)
		(layer "F.Cu")
		(net "M_H_CPU0_SA_DQ<2>")
	)
	(segment
		(start 461.455516 -315.44895)
		(end 461.689704 -315.214762)
		(width 0.20066)
		(layer "F.Cu")
		(net "M_H_CPU0_SA_DQ<2>")
	)
	(segment
		(start 458.24648 -315.898784)
		(end 458.538326 -315.898784)
		(width 0.20066)
		(layer "F.Cu")
		(net "M_H_CPU0_SA_DQ<2>")
	)
	(segment
		(start 455.011282 -315.46673)
		(end 456.116182 -315.46673)
		(width 0.20066)
		(layer "F.Cu")
		(net "M_H_CPU0_SA_DQ<2>")
	)
	(segment
		(start 460.558134 -315.891672)
		(end 460.570326 -315.903864)
		(width 0.1016)
		(layer "F.Cu")
		(net "M_H_CPU0_SA_DQ<2>")
	)
	(segment
		(start 460.570326 -315.903864)
		(end 461.251554 -315.903864)
		(width 0.20066)
		(layer "F.Cu")
		(net "M_H_CPU0_SA_DQ<2>")
	)
	(segment
		(start 458.550264 -315.891672)
		(end 460.558134 -315.891672)
		(width 0.1016)
		(layer "F.Cu")
		(net "M_H_CPU0_SA_DQ<2>")
	)
	(segment
		(start 461.455516 -315.699902)
		(end 461.455516 -315.44895)
		(width 0.20066)
		(layer "F.Cu")
		(net "M_H_CPU0_SA_DQ<2>")
	)
	(segment
		(start 415.131504 -311.83326)
		(end 415.17443 -311.56402)
		(width 0.18288)
		(layer "In6.Cu")
		(net "M_H_CPU0_SA_DQ<2>")
	)
	(segment
		(start 445.155066 -315.889132)
		(end 444.972186 -315.706252)
		(width 0.18288)
		(layer "In6.Cu")
		(net "M_H_CPU0_SA_DQ<2>")
	)
	(segment
		(start 414.237424 -311.876694)
		(end 412.662878 -311.627266)
		(width 0.18288)
		(layer "In6.Cu")
		(net "M_H_CPU0_SA_DQ<2>")
	)
	(segment
		(start 451.843648 -316.075822)
		(end 451.660768 -315.892942)
		(width 0.18288)
		(layer "In6.Cu")
		(net "M_H_CPU0_SA_DQ<2>")
	)
	(segment
		(start 449.344796 -315.892942)
		(end 447.865754 -315.295026)
		(width 0.18288)
		(layer "In6.Cu")
		(net "M_H_CPU0_SA_DQ<2>")
	)
	(segment
		(start 428.104808 -314.265056)
		(end 427.620938 -313.781186)
		(width 0.18288)
		(layer "In6.Cu")
		(net "M_H_CPU0_SA_DQ<2>")
	)
	(segment
		(start 409.297124 -309.90032)
		(end 408.426158 -309.029354)
		(width 0.18288)
		(layer "In6.Cu")
		(net "M_H_CPU0_SA_DQ<2>")
	)
	(segment
		(start 415.17443 -311.56402)
		(end 415.022284 -311.354978)
		(width 0.18288)
		(layer "In6.Cu")
		(net "M_H_CPU0_SA_DQ<2>")
	)
	(segment
		(start 407.459942 -309.029354)
		(end 407.277062 -309.212234)
		(width 0.18288)
		(layer "In6.Cu")
		(net "M_H_CPU0_SA_DQ<2>")
	)
	(segment
		(start 402.135086 -306.406296)
		(end 402.135086 -301.735744)
		(width 0.18288)
		(layer "In6.Cu")
		(net "M_H_CPU0_SA_DQ<2>")
	)
	(segment
		(start 446.912238 -315.295026)
		(end 445.787018 -315.889132)
		(width 0.18288)
		(layer "In6.Cu")
		(net "M_H_CPU0_SA_DQ<2>")
	)
	(segment
		(start 379.708918 -279.474676)
		(end 379.698504 -279.46858)
		(width 0.088646)
		(layer "In6.Cu")
		(net "M_H_CPU0_SA_DQ<2>")
	)
	(segment
		(start 385.732274 -281.096466)
		(end 385.72186 -281.102562)
		(width 0.088646)
		(layer "In6.Cu")
		(net "M_H_CPU0_SA_DQ<2>")
	)
	(segment
		(start 444.972186 -315.706252)
		(end 444.972186 -315.480192)
		(width 0.18288)
		(layer "In6.Cu")
		(net "M_H_CPU0_SA_DQ<2>")
	)
	(segment
		(start 432.445414 -315.295026)
		(end 431.863754 -315.127386)
		(width 0.18288)
		(layer "In6.Cu")
		(net "M_H_CPU0_SA_DQ<2>")
	)
	(segment
		(start 418.33038 -312.91784)
		(end 418.250878 -312.706258)
		(width 0.18288)
		(layer "In6.Cu")
		(net "M_H_CPU0_SA_DQ<2>")
	)
	(segment
		(start 384.690112 -279.964134)
		(end 384.690112 -279.954228)
		(width 0.088646)
		(layer "In6.Cu")
		(net "M_H_CPU0_SA_DQ<2>")
	)
	(segment
		(start 418.262562 -312.294524)
		(end 417.945316 -312.149998)
		(width 0.18288)
		(layer "In6.Cu")
		(net "M_H_CPU0_SA_DQ<2>")
	)
	(segment
		(start 438.115964 -315.889132)
		(end 436.056786 -316.742318)
		(width 0.18288)
		(layer "In6.Cu")
		(net "M_H_CPU0_SA_DQ<2>")
	)
	(segment
		(start 423.081704 -311.769506)
		(end 422.944544 -311.949338)
		(width 0.18288)
		(layer "In6.Cu")
		(net "M_H_CPU0_SA_DQ<2>")
	)
	(segment
		(start 387.601206 -282.29179)
		(end 387.601206 -281.892248)
		(width 0.088646)
		(layer "In6.Cu")
		(net "M_H_CPU0_SA_DQ<2>")
	)
	(segment
		(start 425.343574 -312.49239)
		(end 424.664124 -312.49239)
		(width 0.18288)
		(layer "In6.Cu")
		(net "M_H_CPU0_SA_DQ<2>")
	)
	(segment
		(start 429.55337 -313.786012)
		(end 429.22571 -313.786012)
		(width 0.18288)
		(layer "In6.Cu")
		(net "M_H_CPU0_SA_DQ<2>")
	)
	(segment
		(start 424.200574 -312.518044)
		(end 423.863262 -312.56351)
		(width 0.18288)
		(layer "In6.Cu")
		(net "M_H_CPU0_SA_DQ<2>")
	)
	(segment
		(start 379.20168 -279.445212)
		(end 379.112526 -279.421336)
		(width 0.088646)
		(layer "In6.Cu")
		(net "M_H_CPU0_SA_DQ<2>")
	)
	(segment
		(start 387.943598 -282.634182)
		(end 387.860794 -282.551378)
		(width 0.18288)
		(layer "In6.Cu")
		(net "M_H_CPU0_SA_DQ<2>")
	)
	(segment
		(start 452.026528 -316.79388)
		(end 451.843648 -316.611)
		(width 0.18288)
		(layer "In6.Cu")
		(net "M_H_CPU0_SA_DQ<2>")
	)
	(segment
		(start 434.316886 -316.742318)
		(end 433.124864 -315.550296)
		(width 0.18288)
		(layer "In6.Cu")
		(net "M_H_CPU0_SA_DQ<2>")
	)
	(segment
		(start 386.672328 -281.096466)
		(end 386.661914 -281.102562)
		(width 0.088646)
		(layer "In6.Cu")
		(net "M_H_CPU0_SA_DQ<2>")
	)
	(segment
		(start 406.583642 -309.212234)
		(end 406.400762 -309.029354)
		(width 0.18288)
		(layer "In6.Cu")
		(net "M_H_CPU0_SA_DQ<2>")
	)
	(segment
		(start 417.642548 -312.429652)
		(end 417.430966 -312.509154)
		(width 0.18288)
		(layer "In6.Cu")
		(net "M_H_CPU0_SA_DQ<2>")
	)
	(segment
		(start 380.098046 -279.46604)
		(end 380.083314 -279.474676)
		(width 0.088646)
		(layer "In6.Cu")
		(net "M_H_CPU0_SA_DQ<2>")
	)
	(segment
		(start 392.483848 -282.634182)
		(end 387.943598 -282.634182)
		(width 0.18288)
		(layer "In6.Cu")
		(net "M_H_CPU0_SA_DQ<2>")
	)
	(segment
		(start 414.489392 -311.455562)
		(end 414.446466 -311.724548)
		(width 0.18288)
		(layer "In6.Cu")
		(net "M_H_CPU0_SA_DQ<2>")
	)
	(segment
		(start 424.664124 -312.49239)
		(end 424.200574 -312.518044)
		(width 0.18288)
		(layer "In6.Cu")
		(net "M_H_CPU0_SA_DQ<2>")
	)
	(segment
		(start 419.264338 -313.342274)
		(end 418.33038 -312.91784)
		(width 0.18288)
		(layer "In6.Cu")
		(net "M_H_CPU0_SA_DQ<2>")
	)
	(segment
		(start 387.860794 -282.551378)
		(end 387.601206 -282.29179)
		(width 0.088646)
		(layer "In6.Cu")
		(net "M_H_CPU0_SA_DQ<2>")
	)
	(segment
		(start 394.30071 -293.901368)
		(end 394.30071 -284.451044)
		(width 0.18288)
		(layer "In6.Cu")
		(net "M_H_CPU0_SA_DQ<2>")
	)
	(segment
		(start 382.917192 -279.46604)
		(end 382.90246 -279.474676)
		(width 0.088646)
		(layer "In6.Cu")
		(net "M_H_CPU0_SA_DQ<2>")
	)
	(segment
		(start 417.430966 -312.509154)
		(end 417.002468 -312.314082)
		(width 0.18288)
		(layer "In6.Cu")
		(net "M_H_CPU0_SA_DQ<2>")
	)
	(segment
		(start 412.473902 -311.523634)
		(end 410.850588 -309.90032)
		(width 0.18288)
		(layer "In6.Cu")
		(net "M_H_CPU0_SA_DQ<2>")
	)
	(segment
		(start 406.400762 -309.029354)
		(end 404.758144 -309.029354)
		(width 0.18288)
		(layer "In6.Cu")
		(net "M_H_CPU0_SA_DQ<2>")
	)
	(segment
		(start 417.002468 -312.314082)
		(end 415.283396 -312.042048)
		(width 0.18288)
		(layer "In6.Cu")
		(net "M_H_CPU0_SA_DQ<2>")
	)
	(segment
		(start 406.766522 -309.865268)
		(end 406.583642 -309.682388)
		(width 0.18288)
		(layer "In6.Cu")
		(net "M_H_CPU0_SA_DQ<2>")
	)
	(segment
		(start 454.58507 -315.892942)
		(end 452.719948 -315.892942)
		(width 0.18288)
		(layer "In6.Cu")
		(net "M_H_CPU0_SA_DQ<2>")
	)
	(segment
		(start 418.250878 -312.706258)
		(end 418.342064 -312.506106)
		(width 0.18288)
		(layer "In6.Cu")
		(net "M_H_CPU0_SA_DQ<2>")
	)
	(segment
		(start 423.021252 -312.516012)
		(end 422.884092 -312.695844)
		(width 0.18288)
		(layer "In6.Cu")
		(net "M_H_CPU0_SA_DQ<2>")
	)
	(segment
		(start 420.992046 -313.342274)
		(end 419.264338 -313.342274)
		(width 0.18288)
		(layer "In6.Cu")
		(net "M_H_CPU0_SA_DQ<2>")
	)
	(segment
		(start 452.719948 -315.892942)
		(end 452.537068 -316.075822)
		(width 0.18288)
		(layer "In6.Cu")
		(net "M_H_CPU0_SA_DQ<2>")
	)
	(segment
		(start 418.342064 -312.506106)
		(end 418.262562 -312.294524)
		(width 0.18288)
		(layer "In6.Cu")
		(net "M_H_CPU0_SA_DQ<2>")
	)
	(segment
		(start 385.160012 -280.778204)
		(end 385.160012 -280.759662)
		(width 0.088646)
		(layer "In6.Cu")
		(net "M_H_CPU0_SA_DQ<2>")
	)
	(segment
		(start 385.347464 -281.102562)
		(end 385.338574 -281.097482)
		(width 0.088646)
		(layer "In6.Cu")
		(net "M_H_CPU0_SA_DQ<2>")
	)
	(segment
		(start 427.620938 -313.781186)
		(end 425.343574 -312.49239)
		(width 0.18288)
		(layer "In6.Cu")
		(net "M_H_CPU0_SA_DQ<2>")
	)
	(segment
		(start 429.04283 -313.968892)
		(end 429.04283 -314.197746)
		(width 0.18288)
		(layer "In6.Cu")
		(net "M_H_CPU0_SA_DQ<2>")
	)
	(segment
		(start 387.601206 -281.892248)
		(end 387.307074 -281.182064)
		(width 0.088646)
		(layer "In6.Cu")
		(net "M_H_CPU0_SA_DQ<2>")
	)
	(segment
		(start 384.877564 -280.288492)
		(end 384.868674 -280.283412)
		(width 0.088646)
		(layer "In6.Cu")
		(net "M_H_CPU0_SA_DQ<2>")
	)
	(segment
		(start 433.124864 -315.550296)
		(end 432.445414 -315.295026)
		(width 0.18288)
		(layer "In6.Cu")
		(net "M_H_CPU0_SA_DQ<2>")
	)
	(segment
		(start 415.022284 -311.354978)
		(end 414.698434 -311.303416)
		(width 0.18288)
		(layer "In6.Cu")
		(net "M_H_CPU0_SA_DQ<2>")
	)
	(segment
		(start 407.277062 -309.682388)
		(end 407.094182 -309.865268)
		(width 0.18288)
		(layer "In6.Cu")
		(net "M_H_CPU0_SA_DQ<2>")
	)
	(segment
		(start 408.426158 -309.029354)
		(end 407.459942 -309.029354)
		(width 0.18288)
		(layer "In6.Cu")
		(net "M_H_CPU0_SA_DQ<2>")
	)
	(segment
		(start 444.095886 -315.889132)
		(end 438.115964 -315.889132)
		(width 0.18288)
		(layer "In6.Cu")
		(net "M_H_CPU0_SA_DQ<2>")
	)
	(segment
		(start 429.22571 -313.786012)
		(end 429.04283 -313.968892)
		(width 0.18288)
		(layer "In6.Cu")
		(net "M_H_CPU0_SA_DQ<2>")
	)
	(segment
		(start 451.843648 -316.611)
		(end 451.843648 -316.075822)
		(width 0.18288)
		(layer "In6.Cu")
		(net "M_H_CPU0_SA_DQ<2>")
	)
	(segment
		(start 429.73625 -314.197746)
		(end 429.73625 -313.968892)
		(width 0.18288)
		(layer "In6.Cu")
		(net "M_H_CPU0_SA_DQ<2>")
	)
	(segment
		(start 422.884092 -312.695844)
		(end 422.380664 -312.76417)
		(width 0.18288)
		(layer "In6.Cu")
		(net "M_H_CPU0_SA_DQ<2>")
	)
	(segment
		(start 445.787018 -315.889132)
		(end 445.155066 -315.889132)
		(width 0.18288)
		(layer "In6.Cu")
		(net "M_H_CPU0_SA_DQ<2>")
	)
	(segment
		(start 452.537068 -316.075822)
		(end 452.537068 -316.611)
		(width 0.18288)
		(layer "In6.Cu")
		(net "M_H_CPU0_SA_DQ<2>")
	)
	(segment
		(start 447.865754 -315.295026)
		(end 446.912238 -315.295026)
		(width 0.18288)
		(layer "In6.Cu")
		(net "M_H_CPU0_SA_DQ<2>")
	)
	(segment
		(start 379.112526 -279.421336)
		(end 378.956062 -279.150318)
		(width 0.088646)
		(layer "In6.Cu")
		(net "M_H_CPU0_SA_DQ<2>")
	)
	(segment
		(start 452.354188 -316.79388)
		(end 452.026528 -316.79388)
		(width 0.18288)
		(layer "In6.Cu")
		(net "M_H_CPU0_SA_DQ<2>")
	)
	(segment
		(start 444.461646 -315.297312)
		(end 444.278766 -315.480192)
		(width 0.18288)
		(layer "In6.Cu")
		(net "M_H_CPU0_SA_DQ<2>")
	)
	(segment
		(start 422.380664 -312.76417)
		(end 421.055546 -313.315858)
		(width 0.18288)
		(layer "In6.Cu")
		(net "M_H_CPU0_SA_DQ<2>")
	)
	(segment
		(start 406.583642 -309.682388)
		(end 406.583642 -309.212234)
		(width 0.18288)
		(layer "In6.Cu")
		(net "M_H_CPU0_SA_DQ<2>")
	)
	(segment
		(start 417.733734 -312.2295)
		(end 417.642548 -312.429652)
		(width 0.18288)
		(layer "In6.Cu")
		(net "M_H_CPU0_SA_DQ<2>")
	)
	(segment
		(start 414.446466 -311.724548)
		(end 414.237424 -311.876694)
		(width 0.18288)
		(layer "In6.Cu")
		(net "M_H_CPU0_SA_DQ<2>")
	)
	(segment
		(start 407.094182 -309.865268)
		(end 406.766522 -309.865268)
		(width 0.18288)
		(layer "In6.Cu")
		(net "M_H_CPU0_SA_DQ<2>")
	)
	(segment
		(start 428.660814 -314.380626)
		(end 428.104808 -314.265056)
		(width 0.18288)
		(layer "In6.Cu")
		(net "M_H_CPU0_SA_DQ<2>")
	)
	(segment
		(start 444.972186 -315.480192)
		(end 444.789306 -315.297312)
		(width 0.18288)
		(layer "In6.Cu")
		(net "M_H_CPU0_SA_DQ<2>")
	)
	(segment
		(start 407.277062 -309.212234)
		(end 407.277062 -309.682388)
		(width 0.18288)
		(layer "In6.Cu")
		(net "M_H_CPU0_SA_DQ<2>")
	)
	(segment
		(start 415.283396 -312.042048)
		(end 415.131504 -311.83326)
		(width 0.18288)
		(layer "In6.Cu")
		(net "M_H_CPU0_SA_DQ<2>")
	)
	(segment
		(start 429.73625 -313.968892)
		(end 429.55337 -313.786012)
		(width 0.18288)
		(layer "In6.Cu")
		(net "M_H_CPU0_SA_DQ<2>")
	)
	(segment
		(start 455.011282 -315.46673)
		(end 454.58507 -315.892942)
		(width 0.18288)
		(layer "In6.Cu")
		(net "M_H_CPU0_SA_DQ<2>")
	)
	(segment
		(start 444.789306 -315.297312)
		(end 444.461646 -315.297312)
		(width 0.18288)
		(layer "In6.Cu")
		(net "M_H_CPU0_SA_DQ<2>")
	)
	(segment
		(start 444.278766 -315.706252)
		(end 444.095886 -315.889132)
		(width 0.18288)
		(layer "In6.Cu")
		(net "M_H_CPU0_SA_DQ<2>")
	)
	(segment
		(start 428.85995 -314.380626)
		(end 428.660814 -314.380626)
		(width 0.18288)
		(layer "In6.Cu")
		(net "M_H_CPU0_SA_DQ<2>")
	)
	(segment
		(start 381.588264 -279.474676)
		(end 381.57785 -279.46858)
		(width 0.088646)
		(layer "In6.Cu")
		(net "M_H_CPU0_SA_DQ<2>")
	)
	(segment
		(start 412.662878 -311.627266)
		(end 412.473902 -311.523634)
		(width 0.18288)
		(layer "In6.Cu")
		(net "M_H_CPU0_SA_DQ<2>")
	)
	(segment
		(start 423.606722 -311.859676)
		(end 423.42689 -311.722516)
		(width 0.18288)
		(layer "In6.Cu")
		(net "M_H_CPU0_SA_DQ<2>")
	)
	(segment
		(start 382.528064 -279.474676)
		(end 382.513332 -279.46604)
		(width 0.088646)
		(layer "In6.Cu")
		(net "M_H_CPU0_SA_DQ<2>")
	)
	(segment
		(start 423.42689 -311.722516)
		(end 423.081704 -311.769506)
		(width 0.18288)
		(layer "In6.Cu")
		(net "M_H_CPU0_SA_DQ<2>")
	)
	(segment
		(start 410.850588 -309.90032)
		(end 409.297124 -309.90032)
		(width 0.18288)
		(layer "In6.Cu")
		(net "M_H_CPU0_SA_DQ<2>")
	)
	(segment
		(start 452.537068 -316.611)
		(end 452.354188 -316.79388)
		(width 0.18288)
		(layer "In6.Cu")
		(net "M_H_CPU0_SA_DQ<2>")
	)
	(segment
		(start 387.307074 -281.182064)
		(end 387.227572 -281.102562)
		(width 0.088646)
		(layer "In6.Cu")
		(net "M_H_CPU0_SA_DQ<2>")
	)
	(segment
		(start 394.30071 -284.451044)
		(end 392.483848 -282.634182)
		(width 0.18288)
		(layer "In6.Cu")
		(net "M_H_CPU0_SA_DQ<2>")
	)
	(segment
		(start 431.863754 -315.127386)
		(end 431.116994 -314.380626)
		(width 0.18288)
		(layer "In6.Cu")
		(net "M_H_CPU0_SA_DQ<2>")
	)
	(segment
		(start 429.04283 -314.197746)
		(end 428.85995 -314.380626)
		(width 0.18288)
		(layer "In6.Cu")
		(net "M_H_CPU0_SA_DQ<2>")
	)
	(segment
		(start 444.278766 -315.480192)
		(end 444.278766 -315.706252)
		(width 0.18288)
		(layer "In6.Cu")
		(net "M_H_CPU0_SA_DQ<2>")
	)
	(segment
		(start 423.863262 -312.56351)
		(end 423.68343 -312.42635)
		(width 0.18288)
		(layer "In6.Cu")
		(net "M_H_CPU0_SA_DQ<2>")
	)
	(segment
		(start 451.660768 -315.892942)
		(end 449.344796 -315.892942)
		(width 0.18288)
		(layer "In6.Cu")
		(net "M_H_CPU0_SA_DQ<2>")
	)
	(segment
		(start 423.68343 -312.42635)
		(end 423.606722 -311.859676)
		(width 0.18288)
		(layer "In6.Cu")
		(net "M_H_CPU0_SA_DQ<2>")
	)
	(segment
		(start 436.056786 -316.742318)
		(end 434.316886 -316.742318)
		(width 0.18288)
		(layer "In6.Cu")
		(net "M_H_CPU0_SA_DQ<2>")
	)
	(segment
		(start 417.945316 -312.149998)
		(end 417.733734 -312.2295)
		(width 0.18288)
		(layer "In6.Cu")
		(net "M_H_CPU0_SA_DQ<2>")
	)
	(segment
		(start 421.055546 -313.315858)
		(end 420.992046 -313.342274)
		(width 0.18288)
		(layer "In6.Cu")
		(net "M_H_CPU0_SA_DQ<2>")
	)
	(segment
		(start 414.698434 -311.303416)
		(end 414.489392 -311.455562)
		(width 0.18288)
		(layer "In6.Cu")
		(net "M_H_CPU0_SA_DQ<2>")
	)
	(segment
		(start 404.758144 -309.029354)
		(end 402.135086 -306.406296)
		(width 0.18288)
		(layer "In6.Cu")
		(net "M_H_CPU0_SA_DQ<2>")
	)
	(segment
		(start 429.91913 -314.380626)
		(end 429.73625 -314.197746)
		(width 0.18288)
		(layer "In6.Cu")
		(net "M_H_CPU0_SA_DQ<2>")
	)
	(segment
		(start 422.944544 -311.949338)
		(end 423.021252 -312.516012)
		(width 0.18288)
		(layer "In6.Cu")
		(net "M_H_CPU0_SA_DQ<2>")
	)
	(segment
		(start 402.135086 -301.735744)
		(end 394.30071 -293.901368)
		(width 0.18288)
		(layer "In6.Cu")
		(net "M_H_CPU0_SA_DQ<2>")
	)
	(segment
		(start 431.116994 -314.380626)
		(end 429.91913 -314.380626)
		(width 0.18288)
		(layer "In6.Cu")
		(net "M_H_CPU0_SA_DQ<2>")
	)
	(arc
		(start 385.160012 -280.759662)
		(mid 385.07985 -280.487473)
		(end 384.877564 -280.288492)
		(width 0.088646)
		(layer "In6.Cu")
		(net "M_H_CPU0_SA_DQ<2>")
	)
	(arc
		(start 383.467864 -279.474676)
		(mid 383.193665 -279.398841)
		(end 382.917192 -279.46604)
		(width 0.088646)
		(layer "In6.Cu")
		(net "M_H_CPU0_SA_DQ<2>")
	)
	(arc
		(start 379.698504 -279.46858)
		(mid 379.452798 -279.399326)
		(end 379.20168 -279.445212)
		(width 0.088646)
		(layer "In6.Cu")
		(net "M_H_CPU0_SA_DQ<2>")
	)
	(arc
		(start 381.96266 -279.474676)
		(mid 381.775462 -279.524819)
		(end 381.588264 -279.474676)
		(width 0.088646)
		(layer "In6.Cu")
		(net "M_H_CPU0_SA_DQ<2>")
	)
	(arc
		(start 384.407664 -279.474676)
		(mid 384.124962 -279.3989)
		(end 383.84226 -279.474676)
		(width 0.088646)
		(layer "In6.Cu")
		(net "M_H_CPU0_SA_DQ<2>")
	)
	(arc
		(start 386.661914 -281.102562)
		(mid 386.474716 -281.152705)
		(end 386.287518 -281.102562)
		(width 0.088646)
		(layer "In6.Cu")
		(net "M_H_CPU0_SA_DQ<2>")
	)
	(arc
		(start 382.90246 -279.474676)
		(mid 382.715262 -279.524819)
		(end 382.528064 -279.474676)
		(width 0.088646)
		(layer "In6.Cu")
		(net "M_H_CPU0_SA_DQ<2>")
	)
	(arc
		(start 386.287518 -281.102562)
		(mid 386.010705 -281.026692)
		(end 385.732274 -281.096466)
		(width 0.088646)
		(layer "In6.Cu")
		(net "M_H_CPU0_SA_DQ<2>")
	)
	(arc
		(start 383.84226 -279.474676)
		(mid 383.655062 -279.524819)
		(end 383.467864 -279.474676)
		(width 0.088646)
		(layer "In6.Cu")
		(net "M_H_CPU0_SA_DQ<2>")
	)
	(arc
		(start 385.72186 -281.102562)
		(mid 385.534662 -281.152705)
		(end 385.347464 -281.102562)
		(width 0.088646)
		(layer "In6.Cu")
		(net "M_H_CPU0_SA_DQ<2>")
	)
	(arc
		(start 380.648718 -279.474676)
		(mid 380.374519 -279.398841)
		(end 380.098046 -279.46604)
		(width 0.088646)
		(layer "In6.Cu")
		(net "M_H_CPU0_SA_DQ<2>")
	)
	(arc
		(start 384.868674 -280.283412)
		(mid 384.73776 -280.147052)
		(end 384.690112 -279.964134)
		(width 0.088646)
		(layer "In6.Cu")
		(net "M_H_CPU0_SA_DQ<2>")
	)
	(arc
		(start 380.083314 -279.474676)
		(mid 379.896116 -279.524819)
		(end 379.708918 -279.474676)
		(width 0.088646)
		(layer "In6.Cu")
		(net "M_H_CPU0_SA_DQ<2>")
	)
	(arc
		(start 384.690112 -279.954228)
		(mid 384.612001 -279.677279)
		(end 384.407664 -279.474676)
		(width 0.088646)
		(layer "In6.Cu")
		(net "M_H_CPU0_SA_DQ<2>")
	)
	(arc
		(start 387.227572 -281.102562)
		(mid 386.950759 -281.026692)
		(end 386.672328 -281.096466)
		(width 0.088646)
		(layer "In6.Cu")
		(net "M_H_CPU0_SA_DQ<2>")
	)
	(arc
		(start 381.023114 -279.474676)
		(mid 380.835916 -279.524819)
		(end 380.648718 -279.474676)
		(width 0.088646)
		(layer "In6.Cu")
		(net "M_H_CPU0_SA_DQ<2>")
	)
	(arc
		(start 382.513332 -279.46604)
		(mid 382.236857 -279.39872)
		(end 381.96266 -279.474676)
		(width 0.088646)
		(layer "In6.Cu")
		(net "M_H_CPU0_SA_DQ<2>")
	)
	(arc
		(start 381.57785 -279.46858)
		(mid 381.299672 -279.398857)
		(end 381.023114 -279.474676)
		(width 0.088646)
		(layer "In6.Cu")
		(net "M_H_CPU0_SA_DQ<2>")
	)
	(arc
		(start 385.338574 -281.097482)
		(mid 385.20766 -280.961122)
		(end 385.160012 -280.778204)
		(width 0.088646)
		(layer "In6.Cu")
		(net "M_H_CPU0_SA_DQ<2>")
	)
	(segment
		(start 454.448672 -280.309828)
		(end 454.448672 -280.677366)
		(width 0.20066)
		(layer "F.Cu")
		(net "M_H_CPU0_SA_DQ<29>")
	)
	(segment
		(start 453.536812 -280.61666)
		(end 452.016114 -280.61666)
		(width 0.20066)
		(layer "F.Cu")
		(net "M_H_CPU0_SA_DQ<29>")
	)
	(segment
		(start 452.016114 -280.61666)
		(end 450.911214 -280.61666)
		(width 0.20066)
		(layer "F.Cu")
		(net "M_H_CPU0_SA_DQ<29>")
	)
	(segment
		(start 371.907562 -263.68629)
		(end 371.907816 -263.686544)
		(width 0.20066)
		(layer "F.Cu")
		(net "M_H_CPU0_SA_DQ<29>")
	)
	(segment
		(start 454.448672 -280.677366)
		(end 454.260712 -280.865326)
		(width 0.20066)
		(layer "F.Cu")
		(net "M_H_CPU0_SA_DQ<29>")
	)
	(segment
		(start 457.53655 -280.185368)
		(end 457.126594 -280.185368)
		(width 0.20066)
		(layer "F.Cu")
		(net "M_H_CPU0_SA_DQ<29>")
	)
	(segment
		(start 457.126594 -280.185368)
		(end 457.120244 -280.191718)
		(width 0.1016)
		(layer "F.Cu")
		(net "M_H_CPU0_SA_DQ<29>")
	)
	(segment
		(start 459.559914 -280.61666)
		(end 459.55966 -280.616914)
		(width 0.20066)
		(layer "F.Cu")
		(net "M_H_CPU0_SA_DQ<29>")
	)
	(segment
		(start 454.566782 -280.191718)
		(end 454.448672 -280.309828)
		(width 0.20066)
		(layer "F.Cu")
		(net "M_H_CPU0_SA_DQ<29>")
	)
	(segment
		(start 457.968096 -280.616914)
		(end 457.53655 -280.185368)
		(width 0.20066)
		(layer "F.Cu")
		(net "M_H_CPU0_SA_DQ<29>")
	)
	(segment
		(start 459.55966 -280.616914)
		(end 457.968096 -280.616914)
		(width 0.20066)
		(layer "F.Cu")
		(net "M_H_CPU0_SA_DQ<29>")
	)
	(segment
		(start 454.260712 -280.865326)
		(end 453.785478 -280.865326)
		(width 0.20066)
		(layer "F.Cu")
		(net "M_H_CPU0_SA_DQ<29>")
	)
	(segment
		(start 457.120244 -280.191718)
		(end 454.931526 -280.191718)
		(width 0.1016)
		(layer "F.Cu")
		(net "M_H_CPU0_SA_DQ<29>")
	)
	(segment
		(start 371.907562 -263.150604)
		(end 371.907562 -263.68629)
		(width 0.20066)
		(layer "F.Cu")
		(net "M_H_CPU0_SA_DQ<29>")
	)
	(segment
		(start 454.91146 -280.191718)
		(end 454.566782 -280.191718)
		(width 0.20066)
		(layer "F.Cu")
		(net "M_H_CPU0_SA_DQ<29>")
	)
	(segment
		(start 453.785478 -280.865326)
		(end 453.536812 -280.61666)
		(width 0.20066)
		(layer "F.Cu")
		(net "M_H_CPU0_SA_DQ<29>")
	)
	(segment
		(start 454.931526 -280.191718)
		(end 454.91146 -280.191718)
		(width 0.101854)
		(layer "F.Cu")
		(net "M_H_CPU0_SA_DQ<29>")
	)
	(segment
		(start 375.868946 -263.370822)
		(end 375.854214 -263.362186)
		(width 0.088646)
		(layer "In11.Cu")
		(net "M_H_CPU0_SA_DQ<29>")
	)
	(segment
		(start 432.901852 -282.986226)
		(end 431.840894 -282.986226)
		(width 0.18288)
		(layer "In11.Cu")
		(net "M_H_CPU0_SA_DQ<29>")
	)
	(segment
		(start 374.929146 -263.370822)
		(end 374.914668 -263.362186)
		(width 0.088646)
		(layer "In11.Cu")
		(net "M_H_CPU0_SA_DQ<29>")
	)
	(segment
		(start 437.177434 -282.734766)
		(end 436.331614 -281.888946)
		(width 0.18288)
		(layer "In11.Cu")
		(net "M_H_CPU0_SA_DQ<29>")
	)
	(segment
		(start 384.321304 -264.994898)
		(end 384.312414 -264.989818)
		(width 0.088646)
		(layer "In11.Cu")
		(net "M_H_CPU0_SA_DQ<29>")
	)
	(segment
		(start 410.957776 -281.174444)
		(end 409.658058 -281.174444)
		(width 0.18288)
		(layer "In11.Cu")
		(net "M_H_CPU0_SA_DQ<29>")
	)
	(segment
		(start 409.658058 -281.174444)
		(end 408.701494 -280.21788)
		(width 0.18288)
		(layer "In11.Cu")
		(net "M_H_CPU0_SA_DQ<29>")
	)
	(segment
		(start 381.507746 -263.370822)
		(end 381.493014 -263.362186)
		(width 0.088646)
		(layer "In11.Cu")
		(net "M_H_CPU0_SA_DQ<29>")
	)
	(segment
		(start 423.260774 -283.829252)
		(end 422.437814 -283.829252)
		(width 0.18288)
		(layer "In11.Cu")
		(net "M_H_CPU0_SA_DQ<29>")
	)
	(segment
		(start 436.331614 -281.888946)
		(end 435.282848 -281.888946)
		(width 0.18288)
		(layer "In11.Cu")
		(net "M_H_CPU0_SA_DQ<29>")
	)
	(segment
		(start 383.38125 -263.367266)
		(end 383.37236 -263.362186)
		(width 0.088646)
		(layer "In11.Cu")
		(net "M_H_CPU0_SA_DQ<29>")
	)
	(segment
		(start 445.103758 -282.478226)
		(end 444.910718 -282.671266)
		(width 0.18288)
		(layer "In11.Cu")
		(net "M_H_CPU0_SA_DQ<29>")
	)
	(segment
		(start 433.094892 -282.05303)
		(end 433.094892 -282.793186)
		(width 0.18288)
		(layer "In11.Cu")
		(net "M_H_CPU0_SA_DQ<29>")
	)
	(segment
		(start 387.91642 -267.039852)
		(end 386.739638 -265.86307)
		(width 0.088646)
		(layer "In11.Cu")
		(net "M_H_CPU0_SA_DQ<29>")
	)
	(segment
		(start 438.614566 -283.69387)
		(end 438.614566 -282.927806)
		(width 0.18288)
		(layer "In11.Cu")
		(net "M_H_CPU0_SA_DQ<29>")
	)
	(segment
		(start 414.53943 -281.186636)
		(end 414.22193 -281.186636)
		(width 0.18288)
		(layer "In11.Cu")
		(net "M_H_CPU0_SA_DQ<29>")
	)
	(segment
		(start 413.83585 -281.944826)
		(end 412.663894 -281.944826)
		(width 0.18288)
		(layer "In11.Cu")
		(net "M_H_CPU0_SA_DQ<29>")
	)
	(segment
		(start 438.614566 -282.927806)
		(end 438.421526 -282.734766)
		(width 0.18288)
		(layer "In11.Cu")
		(net "M_H_CPU0_SA_DQ<29>")
	)
	(segment
		(start 435.159658 -282.421838)
		(end 434.59527 -282.986226)
		(width 0.18288)
		(layer "In11.Cu")
		(net "M_H_CPU0_SA_DQ<29>")
	)
	(segment
		(start 377.743974 -263.368282)
		(end 377.73356 -263.362186)
		(width 0.088646)
		(layer "In11.Cu")
		(net "M_H_CPU0_SA_DQ<29>")
	)
	(segment
		(start 446.039494 -282.478226)
		(end 445.103758 -282.478226)
		(width 0.18288)
		(layer "In11.Cu")
		(net "M_H_CPU0_SA_DQ<29>")
	)
	(segment
		(start 414.02889 -281.751786)
		(end 413.83585 -281.944826)
		(width 0.18288)
		(layer "In11.Cu")
		(net "M_H_CPU0_SA_DQ<29>")
	)
	(segment
		(start 433.798472 -282.793186)
		(end 433.798472 -282.05303)
		(width 0.18288)
		(layer "In11.Cu")
		(net "M_H_CPU0_SA_DQ<29>")
	)
	(segment
		(start 444.400178 -283.144976)
		(end 444.207138 -282.951936)
		(width 0.18288)
		(layer "In11.Cu")
		(net "M_H_CPU0_SA_DQ<29>")
	)
	(segment
		(start 382.443228 -263.368282)
		(end 382.432814 -263.362186)
		(width 0.088646)
		(layer "In11.Cu")
		(net "M_H_CPU0_SA_DQ<29>")
	)
	(segment
		(start 450.911214 -280.61666)
		(end 450.391276 -281.136598)
		(width 0.18288)
		(layer "In11.Cu")
		(net "M_H_CPU0_SA_DQ<29>")
	)
	(segment
		(start 373.13616 -264.172446)
		(end 373.130064 -264.176002)
		(width 0.088646)
		(layer "In11.Cu")
		(net "M_H_CPU0_SA_DQ<29>")
	)
	(segment
		(start 444.207138 -282.671266)
		(end 444.014098 -282.478226)
		(width 0.18288)
		(layer "In11.Cu")
		(net "M_H_CPU0_SA_DQ<29>")
	)
	(segment
		(start 426.860462 -283.164026)
		(end 426.439584 -282.743148)
		(width 0.18288)
		(layer "In11.Cu")
		(net "M_H_CPU0_SA_DQ<29>")
	)
	(segment
		(start 438.807606 -283.88691)
		(end 438.614566 -283.69387)
		(width 0.18288)
		(layer "In11.Cu")
		(net "M_H_CPU0_SA_DQ<29>")
	)
	(segment
		(start 385.72186 -265.804142)
		(end 385.710938 -265.797792)
		(width 0.088646)
		(layer "In11.Cu")
		(net "M_H_CPU0_SA_DQ<29>")
	)
	(segment
		(start 385.347464 -265.803888)
		(end 385.332732 -265.812524)
		(width 0.088646)
		(layer "In11.Cu")
		(net "M_H_CPU0_SA_DQ<29>")
	)
	(segment
		(start 383.559812 -263.69645)
		(end 383.559812 -263.686544)
		(width 0.088646)
		(layer "In11.Cu")
		(net "M_H_CPU0_SA_DQ<29>")
	)
	(segment
		(start 444.207138 -282.951936)
		(end 444.207138 -282.671266)
		(width 0.18288)
		(layer "In11.Cu")
		(net "M_H_CPU0_SA_DQ<29>")
	)
	(segment
		(start 442.152786 -283.129736)
		(end 441.246514 -283.129736)
		(width 0.18288)
		(layer "In11.Cu")
		(net "M_H_CPU0_SA_DQ<29>")
	)
	(segment
		(start 414.73247 -281.751786)
		(end 414.73247 -281.379676)
		(width 0.18288)
		(layer "In11.Cu")
		(net "M_H_CPU0_SA_DQ<29>")
	)
	(segment
		(start 414.73247 -281.379676)
		(end 414.53943 -281.186636)
		(width 0.18288)
		(layer "In11.Cu")
		(net "M_H_CPU0_SA_DQ<29>")
	)
	(segment
		(start 446.756028 -281.761692)
		(end 446.039494 -282.478226)
		(width 0.18288)
		(layer "In11.Cu")
		(net "M_H_CPU0_SA_DQ<29>")
	)
	(segment
		(start 404.480776 -279.320752)
		(end 392.199876 -267.039852)
		(width 0.18288)
		(layer "In11.Cu")
		(net "M_H_CPU0_SA_DQ<29>")
	)
	(segment
		(start 428.17415 -282.563316)
		(end 427.57344 -283.164026)
		(width 0.18288)
		(layer "In11.Cu")
		(net "M_H_CPU0_SA_DQ<29>")
	)
	(segment
		(start 426.439584 -282.743148)
		(end 424.346878 -282.743148)
		(width 0.18288)
		(layer "In11.Cu")
		(net "M_H_CPU0_SA_DQ<29>")
	)
	(segment
		(start 444.014098 -282.478226)
		(end 442.804296 -282.478226)
		(width 0.18288)
		(layer "In11.Cu")
		(net "M_H_CPU0_SA_DQ<29>")
	)
	(segment
		(start 433.991512 -282.986226)
		(end 433.798472 -282.793186)
		(width 0.18288)
		(layer "In11.Cu")
		(net "M_H_CPU0_SA_DQ<29>")
	)
	(segment
		(start 435.159658 -282.012136)
		(end 435.159658 -282.421838)
		(width 0.18288)
		(layer "In11.Cu")
		(net "M_H_CPU0_SA_DQ<29>")
	)
	(segment
		(start 408.701494 -280.21788)
		(end 408.701494 -279.836626)
		(width 0.18288)
		(layer "In11.Cu")
		(net "M_H_CPU0_SA_DQ<29>")
	)
	(segment
		(start 372.220744 -263.686544)
		(end 371.907816 -263.686544)
		(width 0.088646)
		(layer "In11.Cu")
		(net "M_H_CPU0_SA_DQ<29>")
	)
	(segment
		(start 378.688346 -263.370822)
		(end 378.673614 -263.362186)
		(width 0.088646)
		(layer "In11.Cu")
		(net "M_H_CPU0_SA_DQ<29>")
	)
	(segment
		(start 433.094892 -282.793186)
		(end 432.901852 -282.986226)
		(width 0.18288)
		(layer "In11.Cu")
		(net "M_H_CPU0_SA_DQ<29>")
	)
	(segment
		(start 439.318146 -283.69387)
		(end 439.125106 -283.88691)
		(width 0.18288)
		(layer "In11.Cu")
		(net "M_H_CPU0_SA_DQ<29>")
	)
	(segment
		(start 439.511186 -282.739846)
		(end 439.318146 -282.932886)
		(width 0.18288)
		(layer "In11.Cu")
		(net "M_H_CPU0_SA_DQ<29>")
	)
	(segment
		(start 411.423358 -281.640026)
		(end 410.957776 -281.174444)
		(width 0.18288)
		(layer "In11.Cu")
		(net "M_H_CPU0_SA_DQ<29>")
	)
	(segment
		(start 435.282848 -281.888946)
		(end 435.159658 -282.012136)
		(width 0.18288)
		(layer "In11.Cu")
		(net "M_H_CPU0_SA_DQ<29>")
	)
	(segment
		(start 450.391276 -281.136598)
		(end 448.535806 -281.136598)
		(width 0.18288)
		(layer "In11.Cu")
		(net "M_H_CPU0_SA_DQ<29>")
	)
	(segment
		(start 439.318146 -282.932886)
		(end 439.318146 -283.69387)
		(width 0.18288)
		(layer "In11.Cu")
		(net "M_H_CPU0_SA_DQ<29>")
	)
	(segment
		(start 380.567946 -263.370822)
		(end 380.553214 -263.362186)
		(width 0.088646)
		(layer "In11.Cu")
		(net "M_H_CPU0_SA_DQ<29>")
	)
	(segment
		(start 439.125106 -283.88691)
		(end 438.807606 -283.88691)
		(width 0.18288)
		(layer "In11.Cu")
		(net "M_H_CPU0_SA_DQ<29>")
	)
	(segment
		(start 373.600218 -263.362186)
		(end 373.591328 -263.367266)
		(width 0.088646)
		(layer "In11.Cu")
		(net "M_H_CPU0_SA_DQ<29>")
	)
	(segment
		(start 444.910718 -282.671266)
		(end 444.910718 -282.951936)
		(width 0.18288)
		(layer "In11.Cu")
		(net "M_H_CPU0_SA_DQ<29>")
	)
	(segment
		(start 412.359094 -281.640026)
		(end 411.423358 -281.640026)
		(width 0.18288)
		(layer "In11.Cu")
		(net "M_H_CPU0_SA_DQ<29>")
	)
	(segment
		(start 447.910712 -281.761692)
		(end 446.756028 -281.761692)
		(width 0.18288)
		(layer "In11.Cu")
		(net "M_H_CPU0_SA_DQ<29>")
	)
	(segment
		(start 388.027672 -267.039852)
		(end 387.91642 -267.039852)
		(width 0.088646)
		(layer "In11.Cu")
		(net "M_H_CPU0_SA_DQ<29>")
	)
	(segment
		(start 440.856624 -282.739846)
		(end 439.511186 -282.739846)
		(width 0.18288)
		(layer "In11.Cu")
		(net "M_H_CPU0_SA_DQ<29>")
	)
	(segment
		(start 444.717678 -283.144976)
		(end 444.400178 -283.144976)
		(width 0.18288)
		(layer "In11.Cu")
		(net "M_H_CPU0_SA_DQ<29>")
	)
	(segment
		(start 431.840894 -282.986226)
		(end 431.417984 -282.563316)
		(width 0.18288)
		(layer "In11.Cu")
		(net "M_H_CPU0_SA_DQ<29>")
	)
	(segment
		(start 442.804296 -282.478226)
		(end 442.152786 -283.129736)
		(width 0.18288)
		(layer "In11.Cu")
		(net "M_H_CPU0_SA_DQ<29>")
	)
	(segment
		(start 444.910718 -282.951936)
		(end 444.717678 -283.144976)
		(width 0.18288)
		(layer "In11.Cu")
		(net "M_H_CPU0_SA_DQ<29>")
	)
	(segment
		(start 427.57344 -283.164026)
		(end 426.860462 -283.164026)
		(width 0.18288)
		(layer "In11.Cu")
		(net "M_H_CPU0_SA_DQ<29>")
	)
	(segment
		(start 408.701494 -279.836626)
		(end 408.18562 -279.320752)
		(width 0.18288)
		(layer "In11.Cu")
		(net "M_H_CPU0_SA_DQ<29>")
	)
	(segment
		(start 433.798472 -282.05303)
		(end 433.605432 -281.85999)
		(width 0.18288)
		(layer "In11.Cu")
		(net "M_H_CPU0_SA_DQ<29>")
	)
	(segment
		(start 433.605432 -281.85999)
		(end 433.287932 -281.85999)
		(width 0.18288)
		(layer "In11.Cu")
		(net "M_H_CPU0_SA_DQ<29>")
	)
	(segment
		(start 433.287932 -281.85999)
		(end 433.094892 -282.05303)
		(width 0.18288)
		(layer "In11.Cu")
		(net "M_H_CPU0_SA_DQ<29>")
	)
	(segment
		(start 372.286022 -263.751822)
		(end 372.220744 -263.686544)
		(width 0.088646)
		(layer "In11.Cu")
		(net "M_H_CPU0_SA_DQ<29>")
	)
	(segment
		(start 422.200324 -283.591762)
		(end 419.407086 -283.591762)
		(width 0.18288)
		(layer "In11.Cu")
		(net "M_H_CPU0_SA_DQ<29>")
	)
	(segment
		(start 392.199876 -267.039852)
		(end 388.027672 -267.039852)
		(width 0.18288)
		(layer "In11.Cu")
		(net "M_H_CPU0_SA_DQ<29>")
	)
	(segment
		(start 408.18562 -279.320752)
		(end 404.480776 -279.320752)
		(width 0.18288)
		(layer "In11.Cu")
		(net "M_H_CPU0_SA_DQ<29>")
	)
	(segment
		(start 422.437814 -283.829252)
		(end 422.200324 -283.591762)
		(width 0.18288)
		(layer "In11.Cu")
		(net "M_H_CPU0_SA_DQ<29>")
	)
	(segment
		(start 434.59527 -282.986226)
		(end 433.991512 -282.986226)
		(width 0.18288)
		(layer "In11.Cu")
		(net "M_H_CPU0_SA_DQ<29>")
	)
	(segment
		(start 384.312414 -264.989818)
		(end 384.306318 -264.986262)
		(width 0.088646)
		(layer "In11.Cu")
		(net "M_H_CPU0_SA_DQ<29>")
	)
	(segment
		(start 373.989346 -263.370822)
		(end 373.974614 -263.362186)
		(width 0.088646)
		(layer "In11.Cu")
		(net "M_H_CPU0_SA_DQ<29>")
	)
	(segment
		(start 419.407086 -283.591762)
		(end 418.678614 -282.86329)
		(width 0.18288)
		(layer "In11.Cu")
		(net "M_H_CPU0_SA_DQ<29>")
	)
	(segment
		(start 414.02889 -281.379676)
		(end 414.02889 -281.751786)
		(width 0.18288)
		(layer "In11.Cu")
		(net "M_H_CPU0_SA_DQ<29>")
	)
	(segment
		(start 431.417984 -282.563316)
		(end 428.17415 -282.563316)
		(width 0.18288)
		(layer "In11.Cu")
		(net "M_H_CPU0_SA_DQ<29>")
	)
	(segment
		(start 438.421526 -282.734766)
		(end 437.177434 -282.734766)
		(width 0.18288)
		(layer "In11.Cu")
		(net "M_H_CPU0_SA_DQ<29>")
	)
	(segment
		(start 448.535806 -281.136598)
		(end 447.910712 -281.761692)
		(width 0.18288)
		(layer "In11.Cu")
		(net "M_H_CPU0_SA_DQ<29>")
	)
	(segment
		(start 414.22193 -281.186636)
		(end 414.02889 -281.379676)
		(width 0.18288)
		(layer "In11.Cu")
		(net "M_H_CPU0_SA_DQ<29>")
	)
	(segment
		(start 414.92551 -281.944826)
		(end 414.73247 -281.751786)
		(width 0.18288)
		(layer "In11.Cu")
		(net "M_H_CPU0_SA_DQ<29>")
	)
	(segment
		(start 416.016694 -281.944826)
		(end 414.92551 -281.944826)
		(width 0.18288)
		(layer "In11.Cu")
		(net "M_H_CPU0_SA_DQ<29>")
	)
	(segment
		(start 424.346878 -282.743148)
		(end 423.260774 -283.829252)
		(width 0.18288)
		(layer "In11.Cu")
		(net "M_H_CPU0_SA_DQ<29>")
	)
	(segment
		(start 418.678614 -282.86329)
		(end 416.935158 -282.86329)
		(width 0.18288)
		(layer "In11.Cu")
		(net "M_H_CPU0_SA_DQ<29>")
	)
	(segment
		(start 416.935158 -282.86329)
		(end 416.016694 -281.944826)
		(width 0.18288)
		(layer "In11.Cu")
		(net "M_H_CPU0_SA_DQ<29>")
	)
	(segment
		(start 383.85115 -264.181082)
		(end 383.84226 -264.176002)
		(width 0.088646)
		(layer "In11.Cu")
		(net "M_H_CPU0_SA_DQ<29>")
	)
	(segment
		(start 384.499866 -265.336274)
		(end 384.499866 -265.314176)
		(width 0.088646)
		(layer "In11.Cu")
		(net "M_H_CPU0_SA_DQ<29>")
	)
	(segment
		(start 376.804428 -263.368282)
		(end 376.794014 -263.362186)
		(width 0.088646)
		(layer "In11.Cu")
		(net "M_H_CPU0_SA_DQ<29>")
	)
	(segment
		(start 412.663894 -281.944826)
		(end 412.359094 -281.640026)
		(width 0.18288)
		(layer "In11.Cu")
		(net "M_H_CPU0_SA_DQ<29>")
	)
	(segment
		(start 373.130064 -264.176002)
		(end 373.115332 -264.184638)
		(width 0.088646)
		(layer "In11.Cu")
		(net "M_H_CPU0_SA_DQ<29>")
	)
	(segment
		(start 441.246514 -283.129736)
		(end 440.856624 -282.739846)
		(width 0.18288)
		(layer "In11.Cu")
		(net "M_H_CPU0_SA_DQ<29>")
	)
	(arc
		(start 373.115332 -264.184638)
		(mid 372.838857 -264.251958)
		(end 372.56466 -264.176002)
		(width 0.088646)
		(layer "In11.Cu")
		(net "M_H_CPU0_SA_DQ<29>")
	)
	(arc
		(start 383.559812 -263.686544)
		(mid 383.512133 -263.503644)
		(end 383.38125 -263.367266)
		(width 0.088646)
		(layer "In11.Cu")
		(net "M_H_CPU0_SA_DQ<29>")
	)
	(arc
		(start 376.794014 -263.362186)
		(mid 376.606816 -263.312043)
		(end 376.419618 -263.362186)
		(width 0.088646)
		(layer "In11.Cu")
		(net "M_H_CPU0_SA_DQ<29>")
	)
	(arc
		(start 382.058418 -263.362186)
		(mid 381.784189 -263.438111)
		(end 381.507746 -263.370822)
		(width 0.088646)
		(layer "In11.Cu")
		(net "M_H_CPU0_SA_DQ<29>")
	)
	(arc
		(start 386.66166 -265.804142)
		(mid 386.474462 -265.753965)
		(end 386.287264 -265.804142)
		(width 0.088646)
		(layer "In11.Cu")
		(net "M_H_CPU0_SA_DQ<29>")
	)
	(arc
		(start 383.84226 -264.176002)
		(mid 383.637925 -263.973397)
		(end 383.559812 -263.69645)
		(width 0.088646)
		(layer "In11.Cu")
		(net "M_H_CPU0_SA_DQ<29>")
	)
	(arc
		(start 385.710938 -265.797792)
		(mid 385.528408 -265.753768)
		(end 385.347464 -265.803888)
		(width 0.088646)
		(layer "In11.Cu")
		(net "M_H_CPU0_SA_DQ<29>")
	)
	(arc
		(start 382.432814 -263.362186)
		(mid 382.245616 -263.312043)
		(end 382.058418 -263.362186)
		(width 0.088646)
		(layer "In11.Cu")
		(net "M_H_CPU0_SA_DQ<29>")
	)
	(arc
		(start 381.118618 -263.362186)
		(mid 380.844389 -263.438111)
		(end 380.567946 -263.370822)
		(width 0.088646)
		(layer "In11.Cu")
		(net "M_H_CPU0_SA_DQ<29>")
	)
	(arc
		(start 383.37236 -263.362186)
		(mid 383.185162 -263.312043)
		(end 382.997964 -263.362186)
		(width 0.088646)
		(layer "In11.Cu")
		(net "M_H_CPU0_SA_DQ<29>")
	)
	(arc
		(start 379.613414 -263.362186)
		(mid 379.426216 -263.312043)
		(end 379.239018 -263.362186)
		(width 0.088646)
		(layer "In11.Cu")
		(net "M_H_CPU0_SA_DQ<29>")
	)
	(arc
		(start 382.997964 -263.362186)
		(mid 382.721405 -263.437895)
		(end 382.443228 -263.368282)
		(width 0.088646)
		(layer "In11.Cu")
		(net "M_H_CPU0_SA_DQ<29>")
	)
	(arc
		(start 375.854214 -263.362186)
		(mid 375.667016 -263.312043)
		(end 375.479818 -263.362186)
		(width 0.088646)
		(layer "In11.Cu")
		(net "M_H_CPU0_SA_DQ<29>")
	)
	(arc
		(start 372.56466 -264.176002)
		(mid 372.375077 -263.996932)
		(end 372.286022 -263.751822)
		(width 0.088646)
		(layer "In11.Cu")
		(net "M_H_CPU0_SA_DQ<29>")
	)
	(arc
		(start 386.739638 -265.86307)
		(mid 386.702573 -265.831061)
		(end 386.66166 -265.804142)
		(width 0.088646)
		(layer "In11.Cu")
		(net "M_H_CPU0_SA_DQ<29>")
	)
	(arc
		(start 385.332732 -265.812524)
		(mid 385.056291 -265.87969)
		(end 384.78206 -265.803888)
		(width 0.088646)
		(layer "In11.Cu")
		(net "M_H_CPU0_SA_DQ<29>")
	)
	(arc
		(start 380.553214 -263.362186)
		(mid 380.366016 -263.312043)
		(end 380.178818 -263.362186)
		(width 0.088646)
		(layer "In11.Cu")
		(net "M_H_CPU0_SA_DQ<29>")
	)
	(arc
		(start 375.479818 -263.362186)
		(mid 375.205589 -263.438111)
		(end 374.929146 -263.370822)
		(width 0.088646)
		(layer "In11.Cu")
		(net "M_H_CPU0_SA_DQ<29>")
	)
	(arc
		(start 373.412766 -263.686544)
		(mid 373.338775 -263.96611)
		(end 373.13616 -264.172446)
		(width 0.088646)
		(layer "In11.Cu")
		(net "M_H_CPU0_SA_DQ<29>")
	)
	(arc
		(start 374.914668 -263.362186)
		(mid 374.72736 -263.312043)
		(end 374.540018 -263.362186)
		(width 0.088646)
		(layer "In11.Cu")
		(net "M_H_CPU0_SA_DQ<29>")
	)
	(arc
		(start 377.359164 -263.362186)
		(mid 377.082605 -263.437895)
		(end 376.804428 -263.368282)
		(width 0.088646)
		(layer "In11.Cu")
		(net "M_H_CPU0_SA_DQ<29>")
	)
	(arc
		(start 384.499866 -265.314176)
		(mid 384.452187 -265.131276)
		(end 384.321304 -264.994898)
		(width 0.088646)
		(layer "In11.Cu")
		(net "M_H_CPU0_SA_DQ<29>")
	)
	(arc
		(start 384.78206 -265.803888)
		(mid 384.580778 -265.606401)
		(end 384.499866 -265.336274)
		(width 0.088646)
		(layer "In11.Cu")
		(net "M_H_CPU0_SA_DQ<29>")
	)
	(arc
		(start 381.493014 -263.362186)
		(mid 381.305816 -263.312043)
		(end 381.118618 -263.362186)
		(width 0.088646)
		(layer "In11.Cu")
		(net "M_H_CPU0_SA_DQ<29>")
	)
	(arc
		(start 376.419618 -263.362186)
		(mid 376.145389 -263.438111)
		(end 375.868946 -263.370822)
		(width 0.088646)
		(layer "In11.Cu")
		(net "M_H_CPU0_SA_DQ<29>")
	)
	(arc
		(start 378.299218 -263.362186)
		(mid 378.022405 -263.438022)
		(end 377.743974 -263.368282)
		(width 0.088646)
		(layer "In11.Cu")
		(net "M_H_CPU0_SA_DQ<29>")
	)
	(arc
		(start 386.287264 -265.804142)
		(mid 386.004562 -265.879918)
		(end 385.72186 -265.804142)
		(width 0.088646)
		(layer "In11.Cu")
		(net "M_H_CPU0_SA_DQ<29>")
	)
	(arc
		(start 373.974614 -263.362186)
		(mid 373.787416 -263.312043)
		(end 373.600218 -263.362186)
		(width 0.088646)
		(layer "In11.Cu")
		(net "M_H_CPU0_SA_DQ<29>")
	)
	(arc
		(start 380.178818 -263.362186)
		(mid 379.896116 -263.437928)
		(end 379.613414 -263.362186)
		(width 0.088646)
		(layer "In11.Cu")
		(net "M_H_CPU0_SA_DQ<29>")
	)
	(arc
		(start 374.540018 -263.362186)
		(mid 374.265789 -263.438111)
		(end 373.989346 -263.370822)
		(width 0.088646)
		(layer "In11.Cu")
		(net "M_H_CPU0_SA_DQ<29>")
	)
	(arc
		(start 379.239018 -263.362186)
		(mid 378.964789 -263.438111)
		(end 378.688346 -263.370822)
		(width 0.088646)
		(layer "In11.Cu")
		(net "M_H_CPU0_SA_DQ<29>")
	)
	(arc
		(start 378.673614 -263.362186)
		(mid 378.486416 -263.312043)
		(end 378.299218 -263.362186)
		(width 0.088646)
		(layer "In11.Cu")
		(net "M_H_CPU0_SA_DQ<29>")
	)
	(arc
		(start 377.73356 -263.362186)
		(mid 377.546362 -263.312043)
		(end 377.359164 -263.362186)
		(width 0.088646)
		(layer "In11.Cu")
		(net "M_H_CPU0_SA_DQ<29>")
	)
	(arc
		(start 384.029712 -264.50036)
		(mid 383.982033 -264.31746)
		(end 383.85115 -264.181082)
		(width 0.088646)
		(layer "In11.Cu")
		(net "M_H_CPU0_SA_DQ<29>")
	)
	(arc
		(start 373.591328 -263.367266)
		(mid 373.460414 -263.503626)
		(end 373.412766 -263.686544)
		(width 0.088646)
		(layer "In11.Cu")
		(net "M_H_CPU0_SA_DQ<29>")
	)
	(arc
		(start 384.306318 -264.986262)
		(mid 384.103731 -264.779911)
		(end 384.029712 -264.50036)
		(width 0.088646)
		(layer "In11.Cu")
		(net "M_H_CPU0_SA_DQ<29>")
	)
	(segment
		(start 457.126594 -281.88539)
		(end 457.120244 -281.89174)
		(width 0.1016)
		(layer "F.Cu")
		(net "M_H_CPU0_SA_DQ<28>")
	)
	(segment
		(start 454.566782 -281.89174)
		(end 454.448672 -282.00985)
		(width 0.20066)
		(layer "F.Cu")
		(net "M_H_CPU0_SA_DQ<28>")
	)
	(segment
		(start 454.448672 -282.377388)
		(end 454.260712 -282.565348)
		(width 0.20066)
		(layer "F.Cu")
		(net "M_H_CPU0_SA_DQ<28>")
	)
	(segment
		(start 454.448672 -282.00985)
		(end 454.448672 -282.377388)
		(width 0.20066)
		(layer "F.Cu")
		(net "M_H_CPU0_SA_DQ<28>")
	)
	(segment
		(start 459.55966 -282.316936)
		(end 457.968096 -282.316936)
		(width 0.20066)
		(layer "F.Cu")
		(net "M_H_CPU0_SA_DQ<28>")
	)
	(segment
		(start 371.437916 -264.500106)
		(end 371.437662 -264.50036)
		(width 0.20066)
		(layer "F.Cu")
		(net "M_H_CPU0_SA_DQ<28>")
	)
	(segment
		(start 454.260712 -282.565348)
		(end 453.785478 -282.565348)
		(width 0.20066)
		(layer "F.Cu")
		(net "M_H_CPU0_SA_DQ<28>")
	)
	(segment
		(start 457.53655 -281.88539)
		(end 457.126594 -281.88539)
		(width 0.20066)
		(layer "F.Cu")
		(net "M_H_CPU0_SA_DQ<28>")
	)
	(segment
		(start 453.536812 -282.316682)
		(end 452.016114 -282.316682)
		(width 0.20066)
		(layer "F.Cu")
		(net "M_H_CPU0_SA_DQ<28>")
	)
	(segment
		(start 454.95845 -281.89174)
		(end 454.91146 -281.89174)
		(width 0.101854)
		(layer "F.Cu")
		(net "M_H_CPU0_SA_DQ<28>")
	)
	(segment
		(start 371.437916 -263.96442)
		(end 371.437916 -264.500106)
		(width 0.20066)
		(layer "F.Cu")
		(net "M_H_CPU0_SA_DQ<28>")
	)
	(segment
		(start 457.968096 -282.316936)
		(end 457.53655 -281.88539)
		(width 0.20066)
		(layer "F.Cu")
		(net "M_H_CPU0_SA_DQ<28>")
	)
	(segment
		(start 459.559914 -282.316682)
		(end 459.55966 -282.316936)
		(width 0.20066)
		(layer "F.Cu")
		(net "M_H_CPU0_SA_DQ<28>")
	)
	(segment
		(start 453.785478 -282.565348)
		(end 453.536812 -282.316682)
		(width 0.20066)
		(layer "F.Cu")
		(net "M_H_CPU0_SA_DQ<28>")
	)
	(segment
		(start 454.91146 -281.89174)
		(end 454.566782 -281.89174)
		(width 0.20066)
		(layer "F.Cu")
		(net "M_H_CPU0_SA_DQ<28>")
	)
	(segment
		(start 457.120244 -281.89174)
		(end 454.95845 -281.89174)
		(width 0.1016)
		(layer "F.Cu")
		(net "M_H_CPU0_SA_DQ<28>")
	)
	(segment
		(start 452.016114 -282.316682)
		(end 450.911214 -282.316682)
		(width 0.20066)
		(layer "F.Cu")
		(net "M_H_CPU0_SA_DQ<28>")
	)
	(segment
		(start 413.783018 -284.250892)
		(end 413.289242 -284.250892)
		(width 0.18288)
		(layer "In11.Cu")
		(net "M_H_CPU0_SA_DQ<28>")
	)
	(segment
		(start 441.856876 -284.27299)
		(end 440.838844 -285.291022)
		(width 0.18288)
		(layer "In11.Cu")
		(net "M_H_CPU0_SA_DQ<28>")
	)
	(segment
		(start 415.244026 -284.250892)
		(end 414.872678 -284.250892)
		(width 0.18288)
		(layer "In11.Cu")
		(net "M_H_CPU0_SA_DQ<28>")
	)
	(segment
		(start 374.070118 -264.176002)
		(end 374.069864 -264.176256)
		(width 0.088646)
		(layer "In11.Cu")
		(net "M_H_CPU0_SA_DQ<28>")
	)
	(segment
		(start 419.688264 -285.893256)
		(end 419.193218 -285.893256)
		(width 0.18288)
		(layer "In11.Cu")
		(net "M_H_CPU0_SA_DQ<28>")
	)
	(segment
		(start 373.703088 -264.679938)
		(end 373.693436 -264.679938)
		(width 0.088646)
		(layer "In11.Cu")
		(net "M_H_CPU0_SA_DQ<28>")
	)
	(segment
		(start 378.768864 -264.176002)
		(end 378.754132 -264.184638)
		(width 0.088646)
		(layer "In11.Cu")
		(net "M_H_CPU0_SA_DQ<28>")
	)
	(segment
		(start 450.288406 -282.316682)
		(end 449.858892 -282.746196)
		(width 0.18288)
		(layer "In11.Cu")
		(net "M_H_CPU0_SA_DQ<28>")
	)
	(segment
		(start 415.630106 -283.539692)
		(end 415.437066 -283.732732)
		(width 0.18288)
		(layer "In11.Cu")
		(net "M_H_CPU0_SA_DQ<28>")
	)
	(segment
		(start 414.169098 -283.144214)
		(end 413.976058 -283.337254)
		(width 0.18288)
		(layer "In11.Cu")
		(net "M_H_CPU0_SA_DQ<28>")
	)
	(segment
		(start 379.708664 -264.176002)
		(end 379.693932 -264.184638)
		(width 0.088646)
		(layer "In11.Cu")
		(net "M_H_CPU0_SA_DQ<28>")
	)
	(segment
		(start 439.435494 -285.291022)
		(end 439.139076 -284.994604)
		(width 0.18288)
		(layer "In11.Cu")
		(net "M_H_CPU0_SA_DQ<28>")
	)
	(segment
		(start 383.381504 -264.994898)
		(end 383.372614 -264.989818)
		(width 0.088646)
		(layer "In11.Cu")
		(net "M_H_CPU0_SA_DQ<28>")
	)
	(segment
		(start 426.458888 -284.263338)
		(end 425.43095 -285.291276)
		(width 0.18288)
		(layer "In11.Cu")
		(net "M_H_CPU0_SA_DQ<28>")
	)
	(segment
		(start 414.872678 -284.250892)
		(end 414.679638 -284.057852)
		(width 0.18288)
		(layer "In11.Cu")
		(net "M_H_CPU0_SA_DQ<28>")
	)
	(segment
		(start 381.588264 -264.176002)
		(end 381.57785 -264.182098)
		(width 0.088646)
		(layer "In11.Cu")
		(net "M_H_CPU0_SA_DQ<28>")
	)
	(segment
		(start 388.027672 -268.055852)
		(end 387.771894 -268.055852)
		(width 0.088646)
		(layer "In11.Cu")
		(net "M_H_CPU0_SA_DQ<28>")
	)
	(segment
		(start 433.374546 -285.049976)
		(end 433.181506 -284.856936)
		(width 0.18288)
		(layer "In11.Cu")
		(net "M_H_CPU0_SA_DQ<28>")
	)
	(segment
		(start 434.796692 -284.263338)
		(end 434.078126 -284.263338)
		(width 0.18288)
		(layer "In11.Cu")
		(net "M_H_CPU0_SA_DQ<28>")
	)
	(segment
		(start 387.091936 -267.82014)
		(end 386.379212 -267.107416)
		(width 0.088646)
		(layer "In11.Cu")
		(net "M_H_CPU0_SA_DQ<28>")
	)
	(segment
		(start 406.912826 -281.547062)
		(end 406.912064 -281.350212)
		(width 0.18288)
		(layer "In11.Cu")
		(net "M_H_CPU0_SA_DQ<28>")
	)
	(segment
		(start 408.699208 -281.894026)
		(end 407.25979 -281.894026)
		(width 0.18288)
		(layer "In11.Cu")
		(net "M_H_CPU0_SA_DQ<28>")
	)
	(segment
		(start 424.119294 -285.043626)
		(end 422.880536 -285.043626)
		(width 0.18288)
		(layer "In11.Cu")
		(net "M_H_CPU0_SA_DQ<28>")
	)
	(segment
		(start 384.029712 -266.138152)
		(end 384.029712 -266.128246)
		(width 0.088646)
		(layer "In11.Cu")
		(net "M_H_CPU0_SA_DQ<28>")
	)
	(segment
		(start 447.936112 -283.488892)
		(end 446.591944 -283.488892)
		(width 0.18288)
		(layer "In11.Cu")
		(net "M_H_CPU0_SA_DQ<28>")
	)
	(segment
		(start 419.193218 -285.893256)
		(end 417.550854 -284.250892)
		(width 0.18288)
		(layer "In11.Cu")
		(net "M_H_CPU0_SA_DQ<28>")
	)
	(segment
		(start 432.988466 -284.263338)
		(end 426.458888 -284.263338)
		(width 0.18288)
		(layer "In11.Cu")
		(net "M_H_CPU0_SA_DQ<28>")
	)
	(segment
		(start 382.528064 -264.176002)
		(end 382.513332 -264.184638)
		(width 0.088646)
		(layer "In11.Cu")
		(net "M_H_CPU0_SA_DQ<28>")
	)
	(segment
		(start 433.885086 -284.456378)
		(end 433.885086 -284.856936)
		(width 0.18288)
		(layer "In11.Cu")
		(net "M_H_CPU0_SA_DQ<28>")
	)
	(segment
		(start 382.91135 -264.181082)
		(end 382.90246 -264.176002)
		(width 0.088646)
		(layer "In11.Cu")
		(net "M_H_CPU0_SA_DQ<28>")
	)
	(segment
		(start 414.486598 -283.144214)
		(end 414.169098 -283.144214)
		(width 0.18288)
		(layer "In11.Cu")
		(net "M_H_CPU0_SA_DQ<28>")
	)
	(segment
		(start 383.36982 -264.988294)
		(end 383.366518 -264.986262)
		(width 0.088646)
		(layer "In11.Cu")
		(net "M_H_CPU0_SA_DQ<28>")
	)
	(segment
		(start 433.885086 -284.856936)
		(end 433.692046 -285.049976)
		(width 0.18288)
		(layer "In11.Cu")
		(net "M_H_CPU0_SA_DQ<28>")
	)
	(segment
		(start 425.43095 -285.291276)
		(end 424.366944 -285.291276)
		(width 0.18288)
		(layer "In11.Cu")
		(net "M_H_CPU0_SA_DQ<28>")
	)
	(segment
		(start 414.679638 -284.057852)
		(end 414.679638 -283.337254)
		(width 0.18288)
		(layer "In11.Cu")
		(net "M_H_CPU0_SA_DQ<28>")
	)
	(segment
		(start 413.976058 -283.337254)
		(end 413.976058 -284.057852)
		(width 0.18288)
		(layer "In11.Cu")
		(net "M_H_CPU0_SA_DQ<28>")
	)
	(segment
		(start 439.139076 -284.994604)
		(end 437.55437 -284.994604)
		(width 0.18288)
		(layer "In11.Cu")
		(net "M_H_CPU0_SA_DQ<28>")
	)
	(segment
		(start 380.648718 -264.176002)
		(end 380.638304 -264.182098)
		(width 0.088646)
		(layer "In11.Cu")
		(net "M_H_CPU0_SA_DQ<28>")
	)
	(segment
		(start 411.548326 -283.567124)
		(end 410.799788 -282.818586)
		(width 0.18288)
		(layer "In11.Cu")
		(net "M_H_CPU0_SA_DQ<28>")
	)
	(segment
		(start 387.771894 -268.055852)
		(end 387.536182 -267.82014)
		(width 0.088646)
		(layer "In11.Cu")
		(net "M_H_CPU0_SA_DQ<28>")
	)
	(segment
		(start 437.55437 -284.994604)
		(end 436.149496 -283.58973)
		(width 0.18288)
		(layer "In11.Cu")
		(net "M_H_CPU0_SA_DQ<28>")
	)
	(segment
		(start 424.366944 -285.291276)
		(end 424.119294 -285.043626)
		(width 0.18288)
		(layer "In11.Cu")
		(net "M_H_CPU0_SA_DQ<28>")
	)
	(segment
		(start 409.623768 -282.818586)
		(end 408.699208 -281.894026)
		(width 0.18288)
		(layer "In11.Cu")
		(net "M_H_CPU0_SA_DQ<28>")
	)
	(segment
		(start 412.605474 -283.567124)
		(end 411.548326 -283.567124)
		(width 0.18288)
		(layer "In11.Cu")
		(net "M_H_CPU0_SA_DQ<28>")
	)
	(segment
		(start 416.140646 -283.732732)
		(end 415.947606 -283.539692)
		(width 0.18288)
		(layer "In11.Cu")
		(net "M_H_CPU0_SA_DQ<28>")
	)
	(segment
		(start 417.550854 -284.250892)
		(end 416.333686 -284.250892)
		(width 0.18288)
		(layer "In11.Cu")
		(net "M_H_CPU0_SA_DQ<28>")
	)
	(segment
		(start 406.725374 -280.947114)
		(end 405.308816 -280.947114)
		(width 0.18288)
		(layer "In11.Cu")
		(net "M_H_CPU0_SA_DQ<28>")
	)
	(segment
		(start 433.692046 -285.049976)
		(end 433.374546 -285.049976)
		(width 0.18288)
		(layer "In11.Cu")
		(net "M_H_CPU0_SA_DQ<28>")
	)
	(segment
		(start 375.009664 -264.176002)
		(end 374.99925 -264.182098)
		(width 0.088646)
		(layer "In11.Cu")
		(net "M_H_CPU0_SA_DQ<28>")
	)
	(segment
		(start 386.379212 -267.107416)
		(end 386.379212 -266.941554)
		(width 0.088646)
		(layer "In11.Cu")
		(net "M_H_CPU0_SA_DQ<28>")
	)
	(segment
		(start 407.25979 -281.894026)
		(end 406.912826 -281.547062)
		(width 0.18288)
		(layer "In11.Cu")
		(net "M_H_CPU0_SA_DQ<28>")
	)
	(segment
		(start 404.946104 -280.584402)
		(end 404.306786 -280.584402)
		(width 0.18288)
		(layer "In11.Cu")
		(net "M_H_CPU0_SA_DQ<28>")
	)
	(segment
		(start 375.949464 -264.176002)
		(end 375.934732 -264.184638)
		(width 0.088646)
		(layer "In11.Cu")
		(net "M_H_CPU0_SA_DQ<28>")
	)
	(segment
		(start 373.504714 -264.824718)
		(end 373.49303 -264.831322)
		(width 0.088646)
		(layer "In11.Cu")
		(net "M_H_CPU0_SA_DQ<28>")
	)
	(segment
		(start 416.333686 -284.250892)
		(end 416.140646 -284.057852)
		(width 0.18288)
		(layer "In11.Cu")
		(net "M_H_CPU0_SA_DQ<28>")
	)
	(segment
		(start 383.372614 -264.989818)
		(end 383.36982 -264.988294)
		(width 0.088646)
		(layer "In11.Cu")
		(net "M_H_CPU0_SA_DQ<28>")
	)
	(segment
		(start 383.85115 -265.808968)
		(end 383.84226 -265.803888)
		(width 0.088646)
		(layer "In11.Cu")
		(net "M_H_CPU0_SA_DQ<28>")
	)
	(segment
		(start 419.936676 -286.141668)
		(end 419.688264 -285.893256)
		(width 0.18288)
		(layer "In11.Cu")
		(net "M_H_CPU0_SA_DQ<28>")
	)
	(segment
		(start 372.108222 -264.847832)
		(end 371.988842 -264.728452)
		(width 0.088646)
		(layer "In11.Cu")
		(net "M_H_CPU0_SA_DQ<28>")
	)
	(segment
		(start 376.889264 -264.176002)
		(end 376.874532 -264.184638)
		(width 0.088646)
		(layer "In11.Cu")
		(net "M_H_CPU0_SA_DQ<28>")
	)
	(segment
		(start 413.289242 -284.250892)
		(end 412.605474 -283.567124)
		(width 0.18288)
		(layer "In11.Cu")
		(net "M_H_CPU0_SA_DQ<28>")
	)
	(segment
		(start 449.858892 -282.746196)
		(end 448.678808 -282.746196)
		(width 0.18288)
		(layer "In11.Cu")
		(net "M_H_CPU0_SA_DQ<28>")
	)
	(segment
		(start 445.807846 -284.27299)
		(end 441.856876 -284.27299)
		(width 0.18288)
		(layer "In11.Cu")
		(net "M_H_CPU0_SA_DQ<28>")
	)
	(segment
		(start 415.947606 -283.539692)
		(end 415.630106 -283.539692)
		(width 0.18288)
		(layer "In11.Cu")
		(net "M_H_CPU0_SA_DQ<28>")
	)
	(segment
		(start 433.181506 -284.856936)
		(end 433.181506 -284.456378)
		(width 0.18288)
		(layer "In11.Cu")
		(net "M_H_CPU0_SA_DQ<28>")
	)
	(segment
		(start 373.882666 -264.50036)
		(end 373.703088 -264.679938)
		(width 0.088646)
		(layer "In11.Cu")
		(net "M_H_CPU0_SA_DQ<28>")
	)
	(segment
		(start 391.778236 -268.055852)
		(end 388.027672 -268.055852)
		(width 0.18288)
		(layer "In11.Cu")
		(net "M_H_CPU0_SA_DQ<28>")
	)
	(segment
		(start 440.838844 -285.291022)
		(end 439.435494 -285.291022)
		(width 0.18288)
		(layer "In11.Cu")
		(net "M_H_CPU0_SA_DQ<28>")
	)
	(segment
		(start 448.678808 -282.746196)
		(end 447.936112 -283.488892)
		(width 0.18288)
		(layer "In11.Cu")
		(net "M_H_CPU0_SA_DQ<28>")
	)
	(segment
		(start 410.799788 -282.818586)
		(end 409.623768 -282.818586)
		(width 0.18288)
		(layer "In11.Cu")
		(net "M_H_CPU0_SA_DQ<28>")
	)
	(segment
		(start 433.181506 -284.456378)
		(end 432.988466 -284.263338)
		(width 0.18288)
		(layer "In11.Cu")
		(net "M_H_CPU0_SA_DQ<28>")
	)
	(segment
		(start 414.679638 -283.337254)
		(end 414.486598 -283.144214)
		(width 0.18288)
		(layer "In11.Cu")
		(net "M_H_CPU0_SA_DQ<28>")
	)
	(segment
		(start 387.536182 -267.82014)
		(end 387.091936 -267.82014)
		(width 0.088646)
		(layer "In11.Cu")
		(net "M_H_CPU0_SA_DQ<28>")
	)
	(segment
		(start 405.308816 -280.947114)
		(end 404.946104 -280.584402)
		(width 0.18288)
		(layer "In11.Cu")
		(net "M_H_CPU0_SA_DQ<28>")
	)
	(segment
		(start 415.437066 -283.732732)
		(end 415.437066 -284.057852)
		(width 0.18288)
		(layer "In11.Cu")
		(net "M_H_CPU0_SA_DQ<28>")
	)
	(segment
		(start 406.912064 -281.350212)
		(end 406.912064 -281.133804)
		(width 0.18288)
		(layer "In11.Cu")
		(net "M_H_CPU0_SA_DQ<28>")
	)
	(segment
		(start 383.560066 -265.336274)
		(end 383.560066 -265.314176)
		(width 0.088646)
		(layer "In11.Cu")
		(net "M_H_CPU0_SA_DQ<28>")
	)
	(segment
		(start 406.912064 -281.133804)
		(end 406.725374 -280.947114)
		(width 0.18288)
		(layer "In11.Cu")
		(net "M_H_CPU0_SA_DQ<28>")
	)
	(segment
		(start 446.591944 -283.488892)
		(end 445.807846 -284.27299)
		(width 0.18288)
		(layer "In11.Cu")
		(net "M_H_CPU0_SA_DQ<28>")
	)
	(segment
		(start 422.880536 -285.043626)
		(end 421.782494 -286.141668)
		(width 0.18288)
		(layer "In11.Cu")
		(net "M_H_CPU0_SA_DQ<28>")
	)
	(segment
		(start 435.4703 -283.58973)
		(end 434.796692 -284.263338)
		(width 0.18288)
		(layer "In11.Cu")
		(net "M_H_CPU0_SA_DQ<28>")
	)
	(segment
		(start 413.976058 -284.057852)
		(end 413.783018 -284.250892)
		(width 0.18288)
		(layer "In11.Cu")
		(net "M_H_CPU0_SA_DQ<28>")
	)
	(segment
		(start 371.988842 -264.728452)
		(end 371.437662 -264.50036)
		(width 0.088646)
		(layer "In11.Cu")
		(net "M_H_CPU0_SA_DQ<28>")
	)
	(segment
		(start 404.306786 -280.584402)
		(end 391.778236 -268.055852)
		(width 0.18288)
		(layer "In11.Cu")
		(net "M_H_CPU0_SA_DQ<28>")
	)
	(segment
		(start 450.911214 -282.316682)
		(end 450.288406 -282.316682)
		(width 0.18288)
		(layer "In11.Cu")
		(net "M_H_CPU0_SA_DQ<28>")
	)
	(segment
		(start 436.149496 -283.58973)
		(end 435.4703 -283.58973)
		(width 0.18288)
		(layer "In11.Cu")
		(net "M_H_CPU0_SA_DQ<28>")
	)
	(segment
		(start 416.140646 -284.057852)
		(end 416.140646 -283.732732)
		(width 0.18288)
		(layer "In11.Cu")
		(net "M_H_CPU0_SA_DQ<28>")
	)
	(segment
		(start 415.437066 -284.057852)
		(end 415.244026 -284.250892)
		(width 0.18288)
		(layer "In11.Cu")
		(net "M_H_CPU0_SA_DQ<28>")
	)
	(segment
		(start 434.078126 -284.263338)
		(end 433.885086 -284.456378)
		(width 0.18288)
		(layer "In11.Cu")
		(net "M_H_CPU0_SA_DQ<28>")
	)
	(segment
		(start 421.782494 -286.141668)
		(end 419.936676 -286.141668)
		(width 0.18288)
		(layer "In11.Cu")
		(net "M_H_CPU0_SA_DQ<28>")
	)
	(segment
		(start 373.117364 -264.83056)
		(end 373.055896 -264.794746)
		(width 0.088646)
		(layer "In11.Cu")
		(net "M_H_CPU0_SA_DQ<28>")
	)
	(arc
		(start 374.069864 -264.176256)
		(mid 373.932819 -264.313216)
		(end 373.882666 -264.50036)
		(width 0.088646)
		(layer "In11.Cu")
		(net "M_H_CPU0_SA_DQ<28>")
	)
	(arc
		(start 383.560066 -265.314176)
		(mid 383.512387 -265.131276)
		(end 383.381504 -264.994898)
		(width 0.088646)
		(layer "In11.Cu")
		(net "M_H_CPU0_SA_DQ<28>")
	)
	(arc
		(start 384.029712 -266.128246)
		(mid 383.982033 -265.945346)
		(end 383.85115 -265.808968)
		(width 0.088646)
		(layer "In11.Cu")
		(net "M_H_CPU0_SA_DQ<28>")
	)
	(arc
		(start 380.638304 -264.182098)
		(mid 380.359872 -264.251944)
		(end 380.08306 -264.176002)
		(width 0.088646)
		(layer "In11.Cu")
		(net "M_H_CPU0_SA_DQ<28>")
	)
	(arc
		(start 373.49303 -264.831322)
		(mid 373.305092 -264.881499)
		(end 373.117364 -264.83056)
		(width 0.088646)
		(layer "In11.Cu")
		(net "M_H_CPU0_SA_DQ<28>")
	)
	(arc
		(start 383.089912 -264.50036)
		(mid 383.042233 -264.31746)
		(end 382.91135 -264.181082)
		(width 0.088646)
		(layer "In11.Cu")
		(net "M_H_CPU0_SA_DQ<28>")
	)
	(arc
		(start 381.57785 -264.182098)
		(mid 381.299672 -264.251821)
		(end 381.023114 -264.176002)
		(width 0.088646)
		(layer "In11.Cu")
		(net "M_H_CPU0_SA_DQ<28>")
	)
	(arc
		(start 373.693436 -264.679938)
		(mid 373.603826 -264.758522)
		(end 373.504714 -264.824718)
		(width 0.088646)
		(layer "In11.Cu")
		(net "M_H_CPU0_SA_DQ<28>")
	)
	(arc
		(start 376.874532 -264.184638)
		(mid 376.598057 -264.251958)
		(end 376.32386 -264.176002)
		(width 0.088646)
		(layer "In11.Cu")
		(net "M_H_CPU0_SA_DQ<28>")
	)
	(arc
		(start 373.055896 -264.794746)
		(mid 372.84545 -264.752888)
		(end 372.653052 -264.847832)
		(width 0.088646)
		(layer "In11.Cu")
		(net "M_H_CPU0_SA_DQ<28>")
	)
	(arc
		(start 384.877564 -266.617704)
		(mid 384.594862 -266.69348)
		(end 384.31216 -266.617704)
		(width 0.088646)
		(layer "In11.Cu")
		(net "M_H_CPU0_SA_DQ<28>")
	)
	(arc
		(start 383.84226 -265.803888)
		(mid 383.640978 -265.606401)
		(end 383.560066 -265.336274)
		(width 0.088646)
		(layer "In11.Cu")
		(net "M_H_CPU0_SA_DQ<28>")
	)
	(arc
		(start 385.25196 -266.617704)
		(mid 385.064762 -266.567527)
		(end 384.877564 -266.617704)
		(width 0.088646)
		(layer "In11.Cu")
		(net "M_H_CPU0_SA_DQ<28>")
	)
	(arc
		(start 378.20346 -264.176002)
		(mid 378.016262 -264.125859)
		(end 377.829064 -264.176002)
		(width 0.088646)
		(layer "In11.Cu")
		(net "M_H_CPU0_SA_DQ<28>")
	)
	(arc
		(start 376.32386 -264.176002)
		(mid 376.136662 -264.125859)
		(end 375.949464 -264.176002)
		(width 0.088646)
		(layer "In11.Cu")
		(net "M_H_CPU0_SA_DQ<28>")
	)
	(arc
		(start 385.817364 -266.617704)
		(mid 385.534662 -266.69348)
		(end 385.25196 -266.617704)
		(width 0.088646)
		(layer "In11.Cu")
		(net "M_H_CPU0_SA_DQ<28>")
	)
	(arc
		(start 386.19176 -266.617704)
		(mid 386.004562 -266.567527)
		(end 385.817364 -266.617704)
		(width 0.088646)
		(layer "In11.Cu")
		(net "M_H_CPU0_SA_DQ<28>")
	)
	(arc
		(start 374.99925 -264.182098)
		(mid 374.721072 -264.251821)
		(end 374.444514 -264.176002)
		(width 0.088646)
		(layer "In11.Cu")
		(net "M_H_CPU0_SA_DQ<28>")
	)
	(arc
		(start 386.269738 -266.676632)
		(mid 386.232673 -266.644623)
		(end 386.19176 -266.617704)
		(width 0.088646)
		(layer "In11.Cu")
		(net "M_H_CPU0_SA_DQ<28>")
	)
	(arc
		(start 382.90246 -264.176002)
		(mid 382.715262 -264.125859)
		(end 382.528064 -264.176002)
		(width 0.088646)
		(layer "In11.Cu")
		(net "M_H_CPU0_SA_DQ<28>")
	)
	(arc
		(start 372.653052 -264.847832)
		(mid 372.380674 -264.960617)
		(end 372.108222 -264.847832)
		(width 0.088646)
		(layer "In11.Cu")
		(net "M_H_CPU0_SA_DQ<28>")
	)
	(arc
		(start 374.444514 -264.176002)
		(mid 374.257316 -264.125859)
		(end 374.070118 -264.176002)
		(width 0.088646)
		(layer "In11.Cu")
		(net "M_H_CPU0_SA_DQ<28>")
	)
	(arc
		(start 383.366518 -264.986262)
		(mid 383.163931 -264.779911)
		(end 383.089912 -264.50036)
		(width 0.088646)
		(layer "In11.Cu")
		(net "M_H_CPU0_SA_DQ<28>")
	)
	(arc
		(start 379.693932 -264.184638)
		(mid 379.417457 -264.251958)
		(end 379.14326 -264.176002)
		(width 0.088646)
		(layer "In11.Cu")
		(net "M_H_CPU0_SA_DQ<28>")
	)
	(arc
		(start 377.829064 -264.176002)
		(mid 377.546362 -264.251778)
		(end 377.26366 -264.176002)
		(width 0.088646)
		(layer "In11.Cu")
		(net "M_H_CPU0_SA_DQ<28>")
	)
	(arc
		(start 379.14326 -264.176002)
		(mid 378.956062 -264.125859)
		(end 378.768864 -264.176002)
		(width 0.088646)
		(layer "In11.Cu")
		(net "M_H_CPU0_SA_DQ<28>")
	)
	(arc
		(start 375.934732 -264.184638)
		(mid 375.658257 -264.251958)
		(end 375.38406 -264.176002)
		(width 0.088646)
		(layer "In11.Cu")
		(net "M_H_CPU0_SA_DQ<28>")
	)
	(arc
		(start 378.754132 -264.184638)
		(mid 378.477657 -264.251958)
		(end 378.20346 -264.176002)
		(width 0.088646)
		(layer "In11.Cu")
		(net "M_H_CPU0_SA_DQ<28>")
	)
	(arc
		(start 384.31216 -266.617704)
		(mid 384.107825 -266.415099)
		(end 384.029712 -266.138152)
		(width 0.088646)
		(layer "In11.Cu")
		(net "M_H_CPU0_SA_DQ<28>")
	)
	(arc
		(start 380.08306 -264.176002)
		(mid 379.895862 -264.125859)
		(end 379.708664 -264.176002)
		(width 0.088646)
		(layer "In11.Cu")
		(net "M_H_CPU0_SA_DQ<28>")
	)
	(arc
		(start 386.379212 -266.941554)
		(mid 386.350902 -266.798174)
		(end 386.269738 -266.676632)
		(width 0.088646)
		(layer "In11.Cu")
		(net "M_H_CPU0_SA_DQ<28>")
	)
	(arc
		(start 375.38406 -264.176002)
		(mid 375.196862 -264.125859)
		(end 375.009664 -264.176002)
		(width 0.088646)
		(layer "In11.Cu")
		(net "M_H_CPU0_SA_DQ<28>")
	)
	(arc
		(start 381.96266 -264.176002)
		(mid 381.775462 -264.125859)
		(end 381.588264 -264.176002)
		(width 0.088646)
		(layer "In11.Cu")
		(net "M_H_CPU0_SA_DQ<28>")
	)
	(arc
		(start 381.023114 -264.176002)
		(mid 380.835916 -264.125859)
		(end 380.648718 -264.176002)
		(width 0.088646)
		(layer "In11.Cu")
		(net "M_H_CPU0_SA_DQ<28>")
	)
	(arc
		(start 377.26366 -264.176002)
		(mid 377.076462 -264.125859)
		(end 376.889264 -264.176002)
		(width 0.088646)
		(layer "In11.Cu")
		(net "M_H_CPU0_SA_DQ<28>")
	)
	(arc
		(start 382.513332 -264.184638)
		(mid 382.236857 -264.251958)
		(end 381.96266 -264.176002)
		(width 0.088646)
		(layer "In11.Cu")
		(net "M_H_CPU0_SA_DQ<28>")
	)
	(segment
		(start 461.455516 -285.698946)
		(end 461.689704 -285.464758)
		(width 0.20066)
		(layer "F.Cu")
		(net "M_H_CPU0_SA_DQ<27>")
	)
	(segment
		(start 457.814426 -285.716726)
		(end 458.24648 -286.14878)
		(width 0.20066)
		(layer "F.Cu")
		(net "M_H_CPU0_SA_DQ<27>")
	)
	(segment
		(start 461.689704 -285.464758)
		(end 462.073752 -285.464758)
		(width 0.20066)
		(layer "F.Cu")
		(net "M_H_CPU0_SA_DQ<27>")
	)
	(segment
		(start 460.570326 -286.15386)
		(end 461.251554 -286.15386)
		(width 0.20066)
		(layer "F.Cu")
		(net "M_H_CPU0_SA_DQ<27>")
	)
	(segment
		(start 461.455516 -285.949898)
		(end 461.455516 -285.698946)
		(width 0.20066)
		(layer "F.Cu")
		(net "M_H_CPU0_SA_DQ<27>")
	)
	(segment
		(start 461.251554 -286.15386)
		(end 461.455516 -285.949898)
		(width 0.20066)
		(layer "F.Cu")
		(net "M_H_CPU0_SA_DQ<27>")
	)
	(segment
		(start 458.543152 -286.14878)
		(end 458.550264 -286.141668)
		(width 0.1016)
		(layer "F.Cu")
		(net "M_H_CPU0_SA_DQ<27>")
	)
	(segment
		(start 373.317516 -266.127992)
		(end 373.317262 -266.128246)
		(width 0.20066)
		(layer "F.Cu")
		(net "M_H_CPU0_SA_DQ<27>")
	)
	(segment
		(start 373.317516 -265.592306)
		(end 373.317516 -266.127992)
		(width 0.20066)
		(layer "F.Cu")
		(net "M_H_CPU0_SA_DQ<27>")
	)
	(segment
		(start 462.073752 -285.464758)
		(end 462.32572 -285.716726)
		(width 0.20066)
		(layer "F.Cu")
		(net "M_H_CPU0_SA_DQ<27>")
	)
	(segment
		(start 458.24648 -286.14878)
		(end 458.538326 -286.14878)
		(width 0.20066)
		(layer "F.Cu")
		(net "M_H_CPU0_SA_DQ<27>")
	)
	(segment
		(start 458.538326 -286.14878)
		(end 458.543152 -286.14878)
		(width 0.101854)
		(layer "F.Cu")
		(net "M_H_CPU0_SA_DQ<27>")
	)
	(segment
		(start 458.550264 -286.141668)
		(end 460.558134 -286.141668)
		(width 0.1016)
		(layer "F.Cu")
		(net "M_H_CPU0_SA_DQ<27>")
	)
	(segment
		(start 460.558134 -286.141668)
		(end 460.570326 -286.15386)
		(width 0.1016)
		(layer "F.Cu")
		(net "M_H_CPU0_SA_DQ<27>")
	)
	(segment
		(start 455.011282 -285.716726)
		(end 456.116182 -285.716726)
		(width 0.20066)
		(layer "F.Cu")
		(net "M_H_CPU0_SA_DQ<27>")
	)
	(segment
		(start 462.32572 -285.716726)
		(end 463.659982 -285.716726)
		(width 0.20066)
		(layer "F.Cu")
		(net "M_H_CPU0_SA_DQ<27>")
	)
	(segment
		(start 456.116182 -285.716726)
		(end 457.814426 -285.716726)
		(width 0.20066)
		(layer "F.Cu")
		(net "M_H_CPU0_SA_DQ<27>")
	)
	(segment
		(start 417.620958 -288.75609)
		(end 417.011358 -288.75609)
		(width 0.18288)
		(layer "In11.Cu")
		(net "M_H_CPU0_SA_DQ<27>")
	)
	(segment
		(start 376.889264 -266.45235)
		(end 376.874532 -266.443714)
		(width 0.088646)
		(layer "In11.Cu")
		(net "M_H_CPU0_SA_DQ<27>")
	)
	(segment
		(start 450.626988 -285.291022)
		(end 450.442584 -285.475426)
		(width 0.18288)
		(layer "In11.Cu")
		(net "M_H_CPU0_SA_DQ<27>")
	)
	(segment
		(start 373.319294 -266.128754)
		(end 373.317262 -266.128246)
		(width 0.088646)
		(layer "In11.Cu")
		(net "M_H_CPU0_SA_DQ<27>")
	)
	(segment
		(start 413.79267 -287.661604)
		(end 412.985458 -287.661604)
		(width 0.18288)
		(layer "In11.Cu")
		(net "M_H_CPU0_SA_DQ<27>")
	)
	(segment
		(start 432.260502 -288.866834)
		(end 431.336958 -287.94329)
		(width 0.18288)
		(layer "In11.Cu")
		(net "M_H_CPU0_SA_DQ<27>")
	)
	(segment
		(start 444.648336 -287.503108)
		(end 444.455296 -287.310068)
		(width 0.18288)
		(layer "In11.Cu")
		(net "M_H_CPU0_SA_DQ<27>")
	)
	(segment
		(start 419.419024 -290.554156)
		(end 417.620958 -288.75609)
		(width 0.18288)
		(layer "In11.Cu")
		(net "M_H_CPU0_SA_DQ<27>")
	)
	(segment
		(start 382.340612 -269.38351)
		(end 382.340612 -269.368016)
		(width 0.088646)
		(layer "In11.Cu")
		(net "M_H_CPU0_SA_DQ<27>")
	)
	(segment
		(start 404.918926 -284.550866)
		(end 390.631934 -270.263874)
		(width 0.18288)
		(layer "In11.Cu")
		(net "M_H_CPU0_SA_DQ<27>")
	)
	(segment
		(start 381.59436 -268.083792)
		(end 381.588264 -268.080236)
		(width 0.088646)
		(layer "In11.Cu")
		(net "M_H_CPU0_SA_DQ<27>")
	)
	(segment
		(start 385.347464 -269.707868)
		(end 385.332732 -269.699232)
		(width 0.088646)
		(layer "In11.Cu")
		(net "M_H_CPU0_SA_DQ<27>")
	)
	(segment
		(start 379.991366 -266.950444)
		(end 379.991366 -266.941808)
		(width 0.088646)
		(layer "In11.Cu")
		(net "M_H_CPU0_SA_DQ<27>")
	)
	(segment
		(start 440.074304 -289.539426)
		(end 440.07278 -289.54095)
		(width 0.18288)
		(layer "In11.Cu")
		(net "M_H_CPU0_SA_DQ<27>")
	)
	(segment
		(start 377.829064 -266.45235)
		(end 377.814332 -266.443714)
		(width 0.088646)
		(layer "In11.Cu")
		(net "M_H_CPU0_SA_DQ<27>")
	)
	(segment
		(start 444.648336 -287.815274)
		(end 444.648336 -287.503108)
		(width 0.18288)
		(layer "In11.Cu")
		(net "M_H_CPU0_SA_DQ<27>")
	)
	(segment
		(start 412.985458 -287.661604)
		(end 412.527496 -287.203642)
		(width 0.18288)
		(layer "In11.Cu")
		(net "M_H_CPU0_SA_DQ<27>")
	)
	(segment
		(start 415.381694 -288.040826)
		(end 414.670494 -287.329626)
		(width 0.18288)
		(layer "In11.Cu")
		(net "M_H_CPU0_SA_DQ<27>")
	)
	(segment
		(start 417.011358 -288.75609)
		(end 416.296094 -288.040826)
		(width 0.18288)
		(layer "In11.Cu")
		(net "M_H_CPU0_SA_DQ<27>")
	)
	(segment
		(start 444.841376 -288.008314)
		(end 444.648336 -287.815274)
		(width 0.18288)
		(layer "In11.Cu")
		(net "M_H_CPU0_SA_DQ<27>")
	)
	(segment
		(start 424.152314 -289.71113)
		(end 422.208452 -289.71113)
		(width 0.18288)
		(layer "In11.Cu")
		(net "M_H_CPU0_SA_DQ<27>")
	)
	(segment
		(start 442.21654 -288.834068)
		(end 441.524136 -288.834068)
		(width 0.18288)
		(layer "In11.Cu")
		(net "M_H_CPU0_SA_DQ<27>")
	)
	(segment
		(start 444.455296 -287.310068)
		(end 444.137796 -287.310068)
		(width 0.18288)
		(layer "In11.Cu")
		(net "M_H_CPU0_SA_DQ<27>")
	)
	(segment
		(start 428.02683 -287.94329)
		(end 427.22546 -288.74466)
		(width 0.18288)
		(layer "In11.Cu")
		(net "M_H_CPU0_SA_DQ<27>")
	)
	(segment
		(start 454.692512 -285.424118)
		(end 454.540112 -285.272226)
		(width 0.18288)
		(layer "In11.Cu")
		(net "M_H_CPU0_SA_DQ<27>")
	)
	(segment
		(start 407.704544 -286.281114)
		(end 407.387552 -285.964122)
		(width 0.18288)
		(layer "In11.Cu")
		(net "M_H_CPU0_SA_DQ<27>")
	)
	(segment
		(start 443.944756 -287.815274)
		(end 443.751716 -288.008314)
		(width 0.18288)
		(layer "In11.Cu")
		(net "M_H_CPU0_SA_DQ<27>")
	)
	(segment
		(start 375.009664 -266.45235)
		(end 374.994932 -266.443714)
		(width 0.088646)
		(layer "In11.Cu")
		(net "M_H_CPU0_SA_DQ<27>")
	)
	(segment
		(start 379.708664 -266.45235)
		(end 379.693932 -266.443714)
		(width 0.088646)
		(layer "In11.Cu")
		(net "M_H_CPU0_SA_DQ<27>")
	)
	(segment
		(start 380.461266 -267.764514)
		(end 380.461266 -267.741654)
		(width 0.088646)
		(layer "In11.Cu")
		(net "M_H_CPU0_SA_DQ<27>")
	)
	(segment
		(start 387.821424 -269.883128)
		(end 386.586222 -269.883128)
		(width 0.088646)
		(layer "In11.Cu")
		(net "M_H_CPU0_SA_DQ<27>")
	)
	(segment
		(start 420.408608 -290.391596)
		(end 420.246048 -290.554156)
		(width 0.18288)
		(layer "In11.Cu")
		(net "M_H_CPU0_SA_DQ<27>")
	)
	(segment
		(start 379.71476 -266.455906)
		(end 379.708664 -266.45235)
		(width 0.088646)
		(layer "In11.Cu")
		(net "M_H_CPU0_SA_DQ<27>")
	)
	(segment
		(start 435.069996 -288.68878)
		(end 434.891942 -288.866834)
		(width 0.18288)
		(layer "In11.Cu")
		(net "M_H_CPU0_SA_DQ<27>")
	)
	(segment
		(start 378.768864 -266.45235)
		(end 378.754132 -266.443714)
		(width 0.088646)
		(layer "In11.Cu")
		(net "M_H_CPU0_SA_DQ<27>")
	)
	(segment
		(start 384.407664 -269.707868)
		(end 384.392932 -269.699232)
		(width 0.088646)
		(layer "In11.Cu")
		(net "M_H_CPU0_SA_DQ<27>")
	)
	(segment
		(start 443.944756 -287.503108)
		(end 443.944756 -287.815274)
		(width 0.18288)
		(layer "In11.Cu")
		(net "M_H_CPU0_SA_DQ<27>")
	)
	(segment
		(start 408.397202 -286.281114)
		(end 407.704544 -286.281114)
		(width 0.18288)
		(layer "In11.Cu")
		(net "M_H_CPU0_SA_DQ<27>")
	)
	(segment
		(start 440.817254 -289.54095)
		(end 440.074304 -289.539426)
		(width 0.18288)
		(layer "In11.Cu")
		(net "M_H_CPU0_SA_DQ<27>")
	)
	(segment
		(start 407.387552 -285.964122)
		(end 407.387552 -285.388812)
		(width 0.18288)
		(layer "In11.Cu")
		(net "M_H_CPU0_SA_DQ<27>")
	)
	(segment
		(start 450.442584 -285.475426)
		(end 449.175378 -285.475426)
		(width 0.18288)
		(layer "In11.Cu")
		(net "M_H_CPU0_SA_DQ<27>")
	)
	(segment
		(start 422.208452 -289.71113)
		(end 421.527986 -290.391596)
		(width 0.18288)
		(layer "In11.Cu")
		(net "M_H_CPU0_SA_DQ<27>")
	)
	(segment
		(start 434.891942 -288.866834)
		(end 432.260502 -288.866834)
		(width 0.18288)
		(layer "In11.Cu")
		(net "M_H_CPU0_SA_DQ<27>")
	)
	(segment
		(start 375.949464 -266.45235)
		(end 375.934732 -266.443714)
		(width 0.088646)
		(layer "In11.Cu")
		(net "M_H_CPU0_SA_DQ<27>")
	)
	(segment
		(start 382.528064 -269.707868)
		(end 382.519174 -269.702788)
		(width 0.088646)
		(layer "In11.Cu")
		(net "M_H_CPU0_SA_DQ<27>")
	)
	(segment
		(start 390.631934 -270.263874)
		(end 388.591806 -270.263874)
		(width 0.18288)
		(layer "In11.Cu")
		(net "M_H_CPU0_SA_DQ<27>")
	)
	(segment
		(start 444.137796 -287.310068)
		(end 443.944756 -287.503108)
		(width 0.18288)
		(layer "In11.Cu")
		(net "M_H_CPU0_SA_DQ<27>")
	)
	(segment
		(start 381.588264 -268.080236)
		(end 381.573532 -268.0716)
		(width 0.088646)
		(layer "In11.Cu")
		(net "M_H_CPU0_SA_DQ<27>")
	)
	(segment
		(start 441.524136 -288.834068)
		(end 440.817254 -289.54095)
		(width 0.18288)
		(layer "In11.Cu")
		(net "M_H_CPU0_SA_DQ<27>")
	)
	(segment
		(start 424.322494 -289.54095)
		(end 424.152314 -289.71113)
		(width 0.18288)
		(layer "In11.Cu")
		(net "M_H_CPU0_SA_DQ<27>")
	)
	(segment
		(start 427.22546 -288.74466)
		(end 426.651928 -288.74466)
		(width 0.18288)
		(layer "In11.Cu")
		(net "M_H_CPU0_SA_DQ<27>")
	)
	(segment
		(start 388.20217 -270.263874)
		(end 387.821424 -269.883128)
		(width 0.088646)
		(layer "In11.Cu")
		(net "M_H_CPU0_SA_DQ<27>")
	)
	(segment
		(start 406.549606 -284.550866)
		(end 404.918926 -284.550866)
		(width 0.18288)
		(layer "In11.Cu")
		(net "M_H_CPU0_SA_DQ<27>")
	)
	(segment
		(start 445.661288 -288.008314)
		(end 444.841376 -288.008314)
		(width 0.18288)
		(layer "In11.Cu")
		(net "M_H_CPU0_SA_DQ<27>")
	)
	(segment
		(start 414.670494 -287.329626)
		(end 414.124648 -287.329626)
		(width 0.18288)
		(layer "In11.Cu")
		(net "M_H_CPU0_SA_DQ<27>")
	)
	(segment
		(start 425.855638 -289.54095)
		(end 424.322494 -289.54095)
		(width 0.18288)
		(layer "In11.Cu")
		(net "M_H_CPU0_SA_DQ<27>")
	)
	(segment
		(start 439.208418 -289.54095)
		(end 438.356248 -288.68878)
		(width 0.18288)
		(layer "In11.Cu")
		(net "M_H_CPU0_SA_DQ<27>")
	)
	(segment
		(start 383.467864 -269.707868)
		(end 383.453132 -269.699232)
		(width 0.088646)
		(layer "In11.Cu")
		(net "M_H_CPU0_SA_DQ<27>")
	)
	(segment
		(start 438.356248 -288.68878)
		(end 435.069996 -288.68878)
		(width 0.18288)
		(layer "In11.Cu")
		(net "M_H_CPU0_SA_DQ<27>")
	)
	(segment
		(start 443.751716 -288.008314)
		(end 443.042294 -288.008314)
		(width 0.18288)
		(layer "In11.Cu")
		(net "M_H_CPU0_SA_DQ<27>")
	)
	(segment
		(start 454.985882 -285.716726)
		(end 454.692512 -285.424118)
		(width 0.18288)
		(layer "In11.Cu")
		(net "M_H_CPU0_SA_DQ<27>")
	)
	(segment
		(start 388.591806 -270.263874)
		(end 388.20217 -270.263874)
		(width 0.088646)
		(layer "In11.Cu")
		(net "M_H_CPU0_SA_DQ<27>")
	)
	(segment
		(start 446.54851 -287.121092)
		(end 445.661288 -288.008314)
		(width 0.18288)
		(layer "In11.Cu")
		(net "M_H_CPU0_SA_DQ<27>")
	)
	(segment
		(start 443.042294 -288.008314)
		(end 442.21654 -288.834068)
		(width 0.18288)
		(layer "In11.Cu")
		(net "M_H_CPU0_SA_DQ<27>")
	)
	(segment
		(start 431.336958 -287.94329)
		(end 428.02683 -287.94329)
		(width 0.18288)
		(layer "In11.Cu")
		(net "M_H_CPU0_SA_DQ<27>")
	)
	(segment
		(start 420.246048 -290.554156)
		(end 419.419024 -290.554156)
		(width 0.18288)
		(layer "In11.Cu")
		(net "M_H_CPU0_SA_DQ<27>")
	)
	(segment
		(start 421.527986 -290.391596)
		(end 420.408608 -290.391596)
		(width 0.18288)
		(layer "In11.Cu")
		(net "M_H_CPU0_SA_DQ<27>")
	)
	(segment
		(start 416.296094 -288.040826)
		(end 415.381694 -288.040826)
		(width 0.18288)
		(layer "In11.Cu")
		(net "M_H_CPU0_SA_DQ<27>")
	)
	(segment
		(start 451.90664 -285.272226)
		(end 451.887844 -285.291022)
		(width 0.18288)
		(layer "In11.Cu")
		(net "M_H_CPU0_SA_DQ<27>")
	)
	(segment
		(start 440.07278 -289.54095)
		(end 439.208418 -289.54095)
		(width 0.18288)
		(layer "In11.Cu")
		(net "M_H_CPU0_SA_DQ<27>")
	)
	(segment
		(start 407.387552 -285.388812)
		(end 406.549606 -284.550866)
		(width 0.18288)
		(layer "In11.Cu")
		(net "M_H_CPU0_SA_DQ<27>")
	)
	(segment
		(start 386.586222 -269.883128)
		(end 386.272532 -269.699232)
		(width 0.088646)
		(layer "In11.Cu")
		(net "M_H_CPU0_SA_DQ<27>")
	)
	(segment
		(start 449.175378 -285.475426)
		(end 447.529712 -287.121092)
		(width 0.18288)
		(layer "In11.Cu")
		(net "M_H_CPU0_SA_DQ<27>")
	)
	(segment
		(start 454.540112 -285.272226)
		(end 451.90664 -285.272226)
		(width 0.18288)
		(layer "In11.Cu")
		(net "M_H_CPU0_SA_DQ<27>")
	)
	(segment
		(start 412.527496 -287.203642)
		(end 409.31973 -287.203642)
		(width 0.18288)
		(layer "In11.Cu")
		(net "M_H_CPU0_SA_DQ<27>")
	)
	(segment
		(start 382.058418 -268.894052)
		(end 382.049528 -268.888972)
		(width 0.088646)
		(layer "In11.Cu")
		(net "M_H_CPU0_SA_DQ<27>")
	)
	(segment
		(start 447.529712 -287.121092)
		(end 446.54851 -287.121092)
		(width 0.18288)
		(layer "In11.Cu")
		(net "M_H_CPU0_SA_DQ<27>")
	)
	(segment
		(start 451.887844 -285.291022)
		(end 450.626988 -285.291022)
		(width 0.18288)
		(layer "In11.Cu")
		(net "M_H_CPU0_SA_DQ<27>")
	)
	(segment
		(start 409.31973 -287.203642)
		(end 408.397202 -286.281114)
		(width 0.18288)
		(layer "In11.Cu")
		(net "M_H_CPU0_SA_DQ<27>")
	)
	(segment
		(start 414.124648 -287.329626)
		(end 413.79267 -287.661604)
		(width 0.18288)
		(layer "In11.Cu")
		(net "M_H_CPU0_SA_DQ<27>")
	)
	(segment
		(start 455.011282 -285.716726)
		(end 454.985882 -285.716726)
		(width 0.18288)
		(layer "In11.Cu")
		(net "M_H_CPU0_SA_DQ<27>")
	)
	(segment
		(start 426.651928 -288.74466)
		(end 425.855638 -289.54095)
		(width 0.18288)
		(layer "In11.Cu")
		(net "M_H_CPU0_SA_DQ<27>")
	)
	(arc
		(start 379.693932 -266.443714)
		(mid 379.417457 -266.376394)
		(end 379.14326 -266.45235)
		(width 0.088646)
		(layer "In11.Cu")
		(net "M_H_CPU0_SA_DQ<27>")
	)
	(arc
		(start 384.392932 -269.699232)
		(mid 384.116491 -269.632066)
		(end 383.84226 -269.707868)
		(width 0.088646)
		(layer "In11.Cu")
		(net "M_H_CPU0_SA_DQ<27>")
	)
	(arc
		(start 376.32386 -266.45235)
		(mid 376.136662 -266.502527)
		(end 375.949464 -266.45235)
		(width 0.088646)
		(layer "In11.Cu")
		(net "M_H_CPU0_SA_DQ<27>")
	)
	(arc
		(start 382.049528 -268.888972)
		(mid 381.918614 -268.752612)
		(end 381.870966 -268.569694)
		(width 0.088646)
		(layer "In11.Cu")
		(net "M_H_CPU0_SA_DQ<27>")
	)
	(arc
		(start 374.994932 -266.443714)
		(mid 374.718457 -266.376394)
		(end 374.44426 -266.45235)
		(width 0.088646)
		(layer "In11.Cu")
		(net "M_H_CPU0_SA_DQ<27>")
	)
	(arc
		(start 381.573532 -268.0716)
		(mid 381.297057 -268.00428)
		(end 381.02286 -268.080236)
		(width 0.088646)
		(layer "In11.Cu")
		(net "M_H_CPU0_SA_DQ<27>")
	)
	(arc
		(start 380.648464 -268.080236)
		(mid 380.513531 -267.946882)
		(end 380.461266 -267.764514)
		(width 0.088646)
		(layer "In11.Cu")
		(net "M_H_CPU0_SA_DQ<27>")
	)
	(arc
		(start 377.26366 -266.45235)
		(mid 377.076462 -266.502527)
		(end 376.889264 -266.45235)
		(width 0.088646)
		(layer "In11.Cu")
		(net "M_H_CPU0_SA_DQ<27>")
	)
	(arc
		(start 382.90246 -269.707868)
		(mid 382.715262 -269.758011)
		(end 382.528064 -269.707868)
		(width 0.088646)
		(layer "In11.Cu")
		(net "M_H_CPU0_SA_DQ<27>")
	)
	(arc
		(start 374.44426 -266.45235)
		(mid 374.257062 -266.502527)
		(end 374.069864 -266.45235)
		(width 0.088646)
		(layer "In11.Cu")
		(net "M_H_CPU0_SA_DQ<27>")
	)
	(arc
		(start 380.178564 -267.266166)
		(mid 380.043631 -267.132812)
		(end 379.991366 -266.950444)
		(width 0.088646)
		(layer "In11.Cu")
		(net "M_H_CPU0_SA_DQ<27>")
	)
	(arc
		(start 375.934732 -266.443714)
		(mid 375.658257 -266.376394)
		(end 375.38406 -266.45235)
		(width 0.088646)
		(layer "In11.Cu")
		(net "M_H_CPU0_SA_DQ<27>")
	)
	(arc
		(start 375.38406 -266.45235)
		(mid 375.196862 -266.502527)
		(end 375.009664 -266.45235)
		(width 0.088646)
		(layer "In11.Cu")
		(net "M_H_CPU0_SA_DQ<27>")
	)
	(arc
		(start 385.72186 -269.707868)
		(mid 385.534662 -269.758011)
		(end 385.347464 -269.707868)
		(width 0.088646)
		(layer "In11.Cu")
		(net "M_H_CPU0_SA_DQ<27>")
	)
	(arc
		(start 377.814332 -266.443714)
		(mid 377.537857 -266.376394)
		(end 377.26366 -266.45235)
		(width 0.088646)
		(layer "In11.Cu")
		(net "M_H_CPU0_SA_DQ<27>")
	)
	(arc
		(start 379.14326 -266.45235)
		(mid 378.956062 -266.502527)
		(end 378.768864 -266.45235)
		(width 0.088646)
		(layer "In11.Cu")
		(net "M_H_CPU0_SA_DQ<27>")
	)
	(arc
		(start 382.519174 -269.702788)
		(mid 382.38826 -269.566428)
		(end 382.340612 -269.38351)
		(width 0.088646)
		(layer "In11.Cu")
		(net "M_H_CPU0_SA_DQ<27>")
	)
	(arc
		(start 378.20346 -266.45235)
		(mid 378.016262 -266.502527)
		(end 377.829064 -266.45235)
		(width 0.088646)
		(layer "In11.Cu")
		(net "M_H_CPU0_SA_DQ<27>")
	)
	(arc
		(start 383.84226 -269.707868)
		(mid 383.655062 -269.758011)
		(end 383.467864 -269.707868)
		(width 0.088646)
		(layer "In11.Cu")
		(net "M_H_CPU0_SA_DQ<27>")
	)
	(arc
		(start 376.874532 -266.443714)
		(mid 376.598057 -266.376394)
		(end 376.32386 -266.45235)
		(width 0.088646)
		(layer "In11.Cu")
		(net "M_H_CPU0_SA_DQ<27>")
	)
	(arc
		(start 380.461266 -267.741654)
		(mid 380.382047 -267.466969)
		(end 380.178564 -267.266166)
		(width 0.088646)
		(layer "In11.Cu")
		(net "M_H_CPU0_SA_DQ<27>")
	)
	(arc
		(start 374.069864 -266.45235)
		(mid 373.704008 -266.268681)
		(end 373.319294 -266.128754)
		(width 0.088646)
		(layer "In11.Cu")
		(net "M_H_CPU0_SA_DQ<27>")
	)
	(arc
		(start 378.754132 -266.443714)
		(mid 378.477657 -266.376394)
		(end 378.20346 -266.45235)
		(width 0.088646)
		(layer "In11.Cu")
		(net "M_H_CPU0_SA_DQ<27>")
	)
	(arc
		(start 384.78206 -269.707868)
		(mid 384.594862 -269.758011)
		(end 384.407664 -269.707868)
		(width 0.088646)
		(layer "In11.Cu")
		(net "M_H_CPU0_SA_DQ<27>")
	)
	(arc
		(start 382.340612 -269.368016)
		(mid 382.261242 -269.094282)
		(end 382.058418 -268.894052)
		(width 0.088646)
		(layer "In11.Cu")
		(net "M_H_CPU0_SA_DQ<27>")
	)
	(arc
		(start 386.272532 -269.699232)
		(mid 385.996091 -269.632066)
		(end 385.72186 -269.707868)
		(width 0.088646)
		(layer "In11.Cu")
		(net "M_H_CPU0_SA_DQ<27>")
	)
	(arc
		(start 385.332732 -269.699232)
		(mid 385.056291 -269.632066)
		(end 384.78206 -269.707868)
		(width 0.088646)
		(layer "In11.Cu")
		(net "M_H_CPU0_SA_DQ<27>")
	)
	(arc
		(start 381.870966 -268.569694)
		(mid 381.796975 -268.290128)
		(end 381.59436 -268.083792)
		(width 0.088646)
		(layer "In11.Cu")
		(net "M_H_CPU0_SA_DQ<27>")
	)
	(arc
		(start 381.02286 -268.080236)
		(mid 380.835662 -268.130379)
		(end 380.648464 -268.080236)
		(width 0.088646)
		(layer "In11.Cu")
		(net "M_H_CPU0_SA_DQ<27>")
	)
	(arc
		(start 379.991366 -266.941808)
		(mid 379.917375 -266.662242)
		(end 379.71476 -266.455906)
		(width 0.088646)
		(layer "In11.Cu")
		(net "M_H_CPU0_SA_DQ<27>")
	)
	(arc
		(start 383.453132 -269.699232)
		(mid 383.176691 -269.632066)
		(end 382.90246 -269.707868)
		(width 0.088646)
		(layer "In11.Cu")
		(net "M_H_CPU0_SA_DQ<27>")
	)
	(segment
		(start 458.24648 -287.848802)
		(end 458.538326 -287.848802)
		(width 0.20066)
		(layer "F.Cu")
		(net "M_H_CPU0_SA_DQ<26>")
	)
	(segment
		(start 461.251554 -287.853882)
		(end 461.455516 -287.64992)
		(width 0.20066)
		(layer "F.Cu")
		(net "M_H_CPU0_SA_DQ<26>")
	)
	(segment
		(start 458.550264 -287.84169)
		(end 460.558134 -287.84169)
		(width 0.1016)
		(layer "F.Cu")
		(net "M_H_CPU0_SA_DQ<26>")
	)
	(segment
		(start 372.847362 -266.405868)
		(end 372.847362 -266.941554)
		(width 0.20066)
		(layer "F.Cu")
		(net "M_H_CPU0_SA_DQ<26>")
	)
	(segment
		(start 457.814426 -287.416748)
		(end 458.24648 -287.848802)
		(width 0.20066)
		(layer "F.Cu")
		(net "M_H_CPU0_SA_DQ<26>")
	)
	(segment
		(start 372.847362 -266.941554)
		(end 372.847616 -266.941808)
		(width 0.20066)
		(layer "F.Cu")
		(net "M_H_CPU0_SA_DQ<26>")
	)
	(segment
		(start 460.570326 -287.853882)
		(end 461.251554 -287.853882)
		(width 0.20066)
		(layer "F.Cu")
		(net "M_H_CPU0_SA_DQ<26>")
	)
	(segment
		(start 461.455516 -287.64992)
		(end 461.455516 -287.398968)
		(width 0.20066)
		(layer "F.Cu")
		(net "M_H_CPU0_SA_DQ<26>")
	)
	(segment
		(start 456.116182 -287.416748)
		(end 457.814426 -287.416748)
		(width 0.20066)
		(layer "F.Cu")
		(net "M_H_CPU0_SA_DQ<26>")
	)
	(segment
		(start 458.543152 -287.848802)
		(end 458.550264 -287.84169)
		(width 0.1016)
		(layer "F.Cu")
		(net "M_H_CPU0_SA_DQ<26>")
	)
	(segment
		(start 460.558134 -287.84169)
		(end 460.570326 -287.853882)
		(width 0.1016)
		(layer "F.Cu")
		(net "M_H_CPU0_SA_DQ<26>")
	)
	(segment
		(start 462.32572 -287.416748)
		(end 463.659982 -287.416748)
		(width 0.20066)
		(layer "F.Cu")
		(net "M_H_CPU0_SA_DQ<26>")
	)
	(segment
		(start 461.689704 -287.16478)
		(end 462.073752 -287.16478)
		(width 0.20066)
		(layer "F.Cu")
		(net "M_H_CPU0_SA_DQ<26>")
	)
	(segment
		(start 462.073752 -287.16478)
		(end 462.32572 -287.416748)
		(width 0.20066)
		(layer "F.Cu")
		(net "M_H_CPU0_SA_DQ<26>")
	)
	(segment
		(start 458.538326 -287.848802)
		(end 458.543152 -287.848802)
		(width 0.101854)
		(layer "F.Cu")
		(net "M_H_CPU0_SA_DQ<26>")
	)
	(segment
		(start 455.011282 -287.416748)
		(end 456.116182 -287.416748)
		(width 0.20066)
		(layer "F.Cu")
		(net "M_H_CPU0_SA_DQ<26>")
	)
	(segment
		(start 461.455516 -287.398968)
		(end 461.689704 -287.16478)
		(width 0.20066)
		(layer "F.Cu")
		(net "M_H_CPU0_SA_DQ<26>")
	)
	(segment
		(start 428.041562 -289.769296)
		(end 427.769274 -289.903662)
		(width 0.18288)
		(layer "In11.Cu")
		(net "M_H_CPU0_SA_DQ<26>")
	)
	(segment
		(start 444.922148 -289.795712)
		(end 442.93282 -289.795712)
		(width 0.18288)
		(layer "In11.Cu")
		(net "M_H_CPU0_SA_DQ<26>")
	)
	(segment
		(start 451.348094 -286.991044)
		(end 450.408294 -286.991044)
		(width 0.18288)
		(layer "In11.Cu")
		(net "M_H_CPU0_SA_DQ<26>")
	)
	(segment
		(start 446.476374 -288.881312)
		(end 445.79286 -289.564826)
		(width 0.18288)
		(layer "In11.Cu")
		(net "M_H_CPU0_SA_DQ<26>")
	)
	(segment
		(start 442.93282 -289.795712)
		(end 442.204856 -290.523168)
		(width 0.18288)
		(layer "In11.Cu")
		(net "M_H_CPU0_SA_DQ<26>")
	)
	(segment
		(start 418.085524 -290.770056)
		(end 417.646104 -290.595812)
		(width 0.18288)
		(layer "In11.Cu")
		(net "M_H_CPU0_SA_DQ<26>")
	)
	(segment
		(start 407.914094 -288.650426)
		(end 407.12644 -287.862772)
		(width 0.18288)
		(layer "In11.Cu")
		(net "M_H_CPU0_SA_DQ<26>")
	)
	(segment
		(start 383.387346 -270.513302)
		(end 383.372614 -270.521938)
		(width 0.088646)
		(layer "In11.Cu")
		(net "M_H_CPU0_SA_DQ<26>")
	)
	(segment
		(start 406.584658 -287.47085)
		(end 404.93442 -285.820612)
		(width 0.18288)
		(layer "In11.Cu")
		(net "M_H_CPU0_SA_DQ<26>")
	)
	(segment
		(start 380.178818 -268.894052)
		(end 380.169928 -268.888972)
		(width 0.088646)
		(layer "In11.Cu")
		(net "M_H_CPU0_SA_DQ<26>")
	)
	(segment
		(start 379.521466 -267.755878)
		(end 379.521466 -267.741654)
		(width 0.088646)
		(layer "In11.Cu")
		(net "M_H_CPU0_SA_DQ<26>")
	)
	(segment
		(start 386.206746 -270.513302)
		(end 386.192014 -270.521938)
		(width 0.088646)
		(layer "In11.Cu")
		(net "M_H_CPU0_SA_DQ<26>")
	)
	(segment
		(start 425.544742 -291.180266)
		(end 425.14647 -291.240972)
		(width 0.18288)
		(layer "In11.Cu")
		(net "M_H_CPU0_SA_DQ<26>")
	)
	(segment
		(start 427.229016 -290.44392)
		(end 426.630084 -290.6268)
		(width 0.18288)
		(layer "In11.Cu")
		(net "M_H_CPU0_SA_DQ<26>")
	)
	(segment
		(start 379.708918 -268.080236)
		(end 379.700028 -268.075156)
		(width 0.088646)
		(layer "In11.Cu")
		(net "M_H_CPU0_SA_DQ<26>")
	)
	(segment
		(start 417.646104 -290.595812)
		(end 417.000944 -290.434268)
		(width 0.18288)
		(layer "In11.Cu")
		(net "M_H_CPU0_SA_DQ<26>")
	)
	(segment
		(start 436.255414 -290.390834)
		(end 435.880764 -290.390834)
		(width 0.18288)
		(layer "In11.Cu")
		(net "M_H_CPU0_SA_DQ<26>")
	)
	(segment
		(start 435.032404 -290.392612)
		(end 434.893212 -290.531804)
		(width 0.18288)
		(layer "In11.Cu")
		(net "M_H_CPU0_SA_DQ<26>")
	)
	(segment
		(start 387.935216 -271.30629)
		(end 387.79577 -271.166844)
		(width 0.18288)
		(layer "In11.Cu")
		(net "M_H_CPU0_SA_DQ<26>")
	)
	(segment
		(start 442.204856 -290.523168)
		(end 441.63996 -290.523168)
		(width 0.18288)
		(layer "In11.Cu")
		(net "M_H_CPU0_SA_DQ<26>")
	)
	(segment
		(start 408.595068 -288.879026)
		(end 408.36596 -288.650426)
		(width 0.18288)
		(layer "In11.Cu")
		(net "M_H_CPU0_SA_DQ<26>")
	)
	(segment
		(start 384.327146 -270.513302)
		(end 384.312414 -270.521938)
		(width 0.088646)
		(layer "In11.Cu")
		(net "M_H_CPU0_SA_DQ<26>")
	)
	(segment
		(start 387.586728 -270.957802)
		(end 387.22046 -270.957802)
		(width 0.088646)
		(layer "In11.Cu")
		(net "M_H_CPU0_SA_DQ<26>")
	)
	(segment
		(start 387.79577 -271.166844)
		(end 387.586728 -270.957802)
		(width 0.088646)
		(layer "In11.Cu")
		(net "M_H_CPU0_SA_DQ<26>")
	)
	(segment
		(start 426.630084 -290.6268)
		(end 425.544742 -291.180266)
		(width 0.18288)
		(layer "In11.Cu")
		(net "M_H_CPU0_SA_DQ<26>")
	)
	(segment
		(start 408.36596 -288.650426)
		(end 407.914094 -288.650426)
		(width 0.18288)
		(layer "In11.Cu")
		(net "M_H_CPU0_SA_DQ<26>")
	)
	(segment
		(start 421.233854 -292.092126)
		(end 420.437818 -292.092126)
		(width 0.18288)
		(layer "In11.Cu")
		(net "M_H_CPU0_SA_DQ<26>")
	)
	(segment
		(start 387.22046 -270.957802)
		(end 386.874258 -270.6116)
		(width 0.088646)
		(layer "In11.Cu")
		(net "M_H_CPU0_SA_DQ<26>")
	)
	(segment
		(start 447.626232 -288.746692)
		(end 447.075814 -288.746692)
		(width 0.18288)
		(layer "In11.Cu")
		(net "M_H_CPU0_SA_DQ<26>")
	)
	(segment
		(start 445.153034 -289.564826)
		(end 444.922148 -289.795712)
		(width 0.18288)
		(layer "In11.Cu")
		(net "M_H_CPU0_SA_DQ<26>")
	)
	(segment
		(start 455.001376 -287.421828)
		(end 453.468486 -286.918146)
		(width 0.18288)
		(layer "In11.Cu")
		(net "M_H_CPU0_SA_DQ<26>")
	)
	(segment
		(start 412.549594 -288.879026)
		(end 408.595068 -288.879026)
		(width 0.18288)
		(layer "In11.Cu")
		(net "M_H_CPU0_SA_DQ<26>")
	)
	(segment
		(start 419.581838 -292.265862)
		(end 419.581076 -292.265608)
		(width 0.18288)
		(layer "In11.Cu")
		(net "M_H_CPU0_SA_DQ<26>")
	)
	(segment
		(start 415.927794 -289.784282)
		(end 414.530794 -289.784282)
		(width 0.18288)
		(layer "In11.Cu")
		(net "M_H_CPU0_SA_DQ<26>")
	)
	(segment
		(start 385.266946 -270.513302)
		(end 385.252214 -270.521938)
		(width 0.088646)
		(layer "In11.Cu")
		(net "M_H_CPU0_SA_DQ<26>")
	)
	(segment
		(start 424.322494 -291.240972)
		(end 422.730168 -291.431726)
		(width 0.18288)
		(layer "In11.Cu")
		(net "M_H_CPU0_SA_DQ<26>")
	)
	(segment
		(start 413.436562 -288.69005)
		(end 412.73857 -288.69005)
		(width 0.18288)
		(layer "In11.Cu")
		(net "M_H_CPU0_SA_DQ<26>")
	)
	(segment
		(start 451.658736 -286.918146)
		(end 451.348094 -286.991044)
		(width 0.18288)
		(layer "In11.Cu")
		(net "M_H_CPU0_SA_DQ<26>")
	)
	(segment
		(start 447.075814 -288.746692)
		(end 446.476374 -288.881312)
		(width 0.18288)
		(layer "In11.Cu")
		(net "M_H_CPU0_SA_DQ<26>")
	)
	(segment
		(start 445.79286 -289.564826)
		(end 445.153034 -289.564826)
		(width 0.18288)
		(layer "In11.Cu")
		(net "M_H_CPU0_SA_DQ<26>")
	)
	(segment
		(start 381.870966 -270.19758)
		(end 381.870966 -270.18996)
		(width 0.088646)
		(layer "In11.Cu")
		(net "M_H_CPU0_SA_DQ<26>")
	)
	(segment
		(start 372.477538 -266.999212)
		(end 372.534942 -266.941808)
		(width 0.088646)
		(layer "In11.Cu")
		(net "M_H_CPU0_SA_DQ<26>")
	)
	(segment
		(start 373.984774 -267.26007)
		(end 373.97436 -267.266166)
		(width 0.088646)
		(layer "In11.Cu")
		(net "M_H_CPU0_SA_DQ<26>")
	)
	(segment
		(start 435.880764 -290.390834)
		(end 435.878986 -290.392612)
		(width 0.18288)
		(layer "In11.Cu")
		(net "M_H_CPU0_SA_DQ<26>")
	)
	(segment
		(start 430.646332 -289.59429)
		(end 429.082454 -289.59429)
		(width 0.18288)
		(layer "In11.Cu")
		(net "M_H_CPU0_SA_DQ<26>")
	)
	(segment
		(start 449.129912 -287.243012)
		(end 447.626232 -288.746692)
		(width 0.18288)
		(layer "In11.Cu")
		(net "M_H_CPU0_SA_DQ<26>")
	)
	(segment
		(start 422.730168 -291.431726)
		(end 421.233854 -292.092126)
		(width 0.18288)
		(layer "In11.Cu")
		(net "M_H_CPU0_SA_DQ<26>")
	)
	(segment
		(start 432.424078 -290.531804)
		(end 431.508408 -289.998658)
		(width 0.18288)
		(layer "In11.Cu")
		(net "M_H_CPU0_SA_DQ<26>")
	)
	(segment
		(start 412.73857 -288.69005)
		(end 412.549594 -288.879026)
		(width 0.18288)
		(layer "In11.Cu")
		(net "M_H_CPU0_SA_DQ<26>")
	)
	(segment
		(start 425.14647 -291.240972)
		(end 424.322494 -291.240972)
		(width 0.18288)
		(layer "In11.Cu")
		(net "M_H_CPU0_SA_DQ<26>")
	)
	(segment
		(start 439.970926 -291.240972)
		(end 439.35904 -291.240972)
		(width 0.18288)
		(layer "In11.Cu")
		(net "M_H_CPU0_SA_DQ<26>")
	)
	(segment
		(start 450.408294 -286.991044)
		(end 449.129912 -287.243012)
		(width 0.18288)
		(layer "In11.Cu")
		(net "M_H_CPU0_SA_DQ<26>")
	)
	(segment
		(start 429.082454 -289.59429)
		(end 428.041562 -289.769296)
		(width 0.18288)
		(layer "In11.Cu")
		(net "M_H_CPU0_SA_DQ<26>")
	)
	(segment
		(start 414.530794 -289.784282)
		(end 413.436562 -288.69005)
		(width 0.18288)
		(layer "In11.Cu")
		(net "M_H_CPU0_SA_DQ<26>")
	)
	(segment
		(start 427.769274 -289.903662)
		(end 427.229016 -290.44392)
		(width 0.18288)
		(layer "In11.Cu")
		(net "M_H_CPU0_SA_DQ<26>")
	)
	(segment
		(start 420.264082 -292.265862)
		(end 419.581838 -292.265862)
		(width 0.18288)
		(layer "In11.Cu")
		(net "M_H_CPU0_SA_DQ<26>")
	)
	(segment
		(start 419.581076 -292.265608)
		(end 418.085524 -290.770056)
		(width 0.18288)
		(layer "In11.Cu")
		(net "M_H_CPU0_SA_DQ<26>")
	)
	(segment
		(start 438.762394 -290.644326)
		(end 438.142634 -290.276026)
		(width 0.18288)
		(layer "In11.Cu")
		(net "M_H_CPU0_SA_DQ<26>")
	)
	(segment
		(start 438.142634 -290.276026)
		(end 437.682894 -290.276026)
		(width 0.18288)
		(layer "In11.Cu")
		(net "M_H_CPU0_SA_DQ<26>")
	)
	(segment
		(start 381.401066 -269.392146)
		(end 381.401066 -269.373604)
		(width 0.088646)
		(layer "In11.Cu")
		(net "M_H_CPU0_SA_DQ<26>")
	)
	(segment
		(start 431.508408 -289.998658)
		(end 430.646332 -289.59429)
		(width 0.18288)
		(layer "In11.Cu")
		(net "M_H_CPU0_SA_DQ<26>")
	)
	(segment
		(start 372.660418 -267.266166)
		(end 372.651528 -267.261086)
		(width 0.088646)
		(layer "In11.Cu")
		(net "M_H_CPU0_SA_DQ<26>")
	)
	(segment
		(start 373.045228 -267.26007)
		(end 373.034814 -267.266166)
		(width 0.088646)
		(layer "In11.Cu")
		(net "M_H_CPU0_SA_DQ<26>")
	)
	(segment
		(start 439.35904 -291.240972)
		(end 438.762394 -290.644326)
		(width 0.18288)
		(layer "In11.Cu")
		(net "M_H_CPU0_SA_DQ<26>")
	)
	(segment
		(start 377.748546 -267.25753)
		(end 377.733814 -267.266166)
		(width 0.088646)
		(layer "In11.Cu")
		(net "M_H_CPU0_SA_DQ<26>")
	)
	(segment
		(start 453.468486 -286.918146)
		(end 451.658736 -286.918146)
		(width 0.18288)
		(layer "In11.Cu")
		(net "M_H_CPU0_SA_DQ<26>")
	)
	(segment
		(start 407.12644 -287.862772)
		(end 406.584658 -287.47085)
		(width 0.18288)
		(layer "In11.Cu")
		(net "M_H_CPU0_SA_DQ<26>")
	)
	(segment
		(start 417.000944 -290.434268)
		(end 415.927794 -289.784282)
		(width 0.18288)
		(layer "In11.Cu")
		(net "M_H_CPU0_SA_DQ<26>")
	)
	(segment
		(start 390.131554 -271.30629)
		(end 387.935216 -271.30629)
		(width 0.18288)
		(layer "In11.Cu")
		(net "M_H_CPU0_SA_DQ<26>")
	)
	(segment
		(start 441.63996 -290.523168)
		(end 440.922664 -291.241988)
		(width 0.18288)
		(layer "In11.Cu")
		(net "M_H_CPU0_SA_DQ<26>")
	)
	(segment
		(start 378.688346 -267.25753)
		(end 378.673614 -267.266166)
		(width 0.088646)
		(layer "In11.Cu")
		(net "M_H_CPU0_SA_DQ<26>")
	)
	(segment
		(start 376.808746 -267.25753)
		(end 376.794014 -267.266166)
		(width 0.088646)
		(layer "In11.Cu")
		(net "M_H_CPU0_SA_DQ<26>")
	)
	(segment
		(start 440.922664 -291.241988)
		(end 439.970926 -291.240972)
		(width 0.18288)
		(layer "In11.Cu")
		(net "M_H_CPU0_SA_DQ<26>")
	)
	(segment
		(start 404.645876 -285.820612)
		(end 390.131554 -271.30629)
		(width 0.18288)
		(layer "In11.Cu")
		(net "M_H_CPU0_SA_DQ<26>")
	)
	(segment
		(start 382.447546 -270.513302)
		(end 382.432814 -270.521938)
		(width 0.088646)
		(layer "In11.Cu")
		(net "M_H_CPU0_SA_DQ<26>")
	)
	(segment
		(start 434.893212 -290.531804)
		(end 432.424078 -290.531804)
		(width 0.18288)
		(layer "In11.Cu")
		(net "M_H_CPU0_SA_DQ<26>")
	)
	(segment
		(start 455.011282 -287.416748)
		(end 455.001376 -287.421828)
		(width 0.18288)
		(layer "In11.Cu")
		(net "M_H_CPU0_SA_DQ<26>")
	)
	(segment
		(start 420.437818 -292.092126)
		(end 420.264082 -292.265862)
		(width 0.18288)
		(layer "In11.Cu")
		(net "M_H_CPU0_SA_DQ<26>")
	)
	(segment
		(start 374.929146 -267.25753)
		(end 374.914668 -267.266166)
		(width 0.088646)
		(layer "In11.Cu")
		(net "M_H_CPU0_SA_DQ<26>")
	)
	(segment
		(start 404.93442 -285.820612)
		(end 404.645876 -285.820612)
		(width 0.18288)
		(layer "In11.Cu")
		(net "M_H_CPU0_SA_DQ<26>")
	)
	(segment
		(start 379.991366 -268.569694)
		(end 379.991366 -268.559788)
		(width 0.088646)
		(layer "In11.Cu")
		(net "M_H_CPU0_SA_DQ<26>")
	)
	(segment
		(start 375.868946 -267.25753)
		(end 375.854214 -267.266166)
		(width 0.088646)
		(layer "In11.Cu")
		(net "M_H_CPU0_SA_DQ<26>")
	)
	(segment
		(start 435.878986 -290.392612)
		(end 435.032404 -290.392612)
		(width 0.18288)
		(layer "In11.Cu")
		(net "M_H_CPU0_SA_DQ<26>")
	)
	(segment
		(start 372.534942 -266.941808)
		(end 372.847616 -266.941808)
		(width 0.088646)
		(layer "In11.Cu")
		(net "M_H_CPU0_SA_DQ<26>")
	)
	(segment
		(start 382.058418 -270.521938)
		(end 382.049528 -270.516858)
		(width 0.088646)
		(layer "In11.Cu")
		(net "M_H_CPU0_SA_DQ<26>")
	)
	(segment
		(start 437.682894 -290.276026)
		(end 436.255414 -290.390834)
		(width 0.18288)
		(layer "In11.Cu")
		(net "M_H_CPU0_SA_DQ<26>")
	)
	(arc
		(start 375.854214 -267.266166)
		(mid 375.667016 -267.316309)
		(end 375.479818 -267.266166)
		(width 0.088646)
		(layer "In11.Cu")
		(net "M_H_CPU0_SA_DQ<26>")
	)
	(arc
		(start 382.432814 -270.521938)
		(mid 382.245616 -270.572081)
		(end 382.058418 -270.521938)
		(width 0.088646)
		(layer "In11.Cu")
		(net "M_H_CPU0_SA_DQ<26>")
	)
	(arc
		(start 373.599964 -267.266166)
		(mid 373.323405 -267.190457)
		(end 373.045228 -267.26007)
		(width 0.088646)
		(layer "In11.Cu")
		(net "M_H_CPU0_SA_DQ<26>")
	)
	(arc
		(start 381.401066 -269.373604)
		(mid 381.322955 -269.096655)
		(end 381.118618 -268.894052)
		(width 0.088646)
		(layer "In11.Cu")
		(net "M_H_CPU0_SA_DQ<26>")
	)
	(arc
		(start 383.372614 -270.521938)
		(mid 383.185416 -270.572081)
		(end 382.998218 -270.521938)
		(width 0.088646)
		(layer "In11.Cu")
		(net "M_H_CPU0_SA_DQ<26>")
	)
	(arc
		(start 386.874258 -270.6116)
		(mid 386.556778 -270.452023)
		(end 386.206746 -270.513302)
		(width 0.088646)
		(layer "In11.Cu")
		(net "M_H_CPU0_SA_DQ<26>")
	)
	(arc
		(start 385.252214 -270.521938)
		(mid 385.065016 -270.572081)
		(end 384.877818 -270.521938)
		(width 0.088646)
		(layer "In11.Cu")
		(net "M_H_CPU0_SA_DQ<26>")
	)
	(arc
		(start 380.553214 -268.894052)
		(mid 380.366016 -268.944195)
		(end 380.178818 -268.894052)
		(width 0.088646)
		(layer "In11.Cu")
		(net "M_H_CPU0_SA_DQ<26>")
	)
	(arc
		(start 381.588264 -269.707868)
		(mid 381.453331 -269.574514)
		(end 381.401066 -269.392146)
		(width 0.088646)
		(layer "In11.Cu")
		(net "M_H_CPU0_SA_DQ<26>")
	)
	(arc
		(start 373.034814 -267.266166)
		(mid 372.847616 -267.316309)
		(end 372.660418 -267.266166)
		(width 0.088646)
		(layer "In11.Cu")
		(net "M_H_CPU0_SA_DQ<26>")
	)
	(arc
		(start 384.877818 -270.521938)
		(mid 384.603619 -270.446103)
		(end 384.327146 -270.513302)
		(width 0.088646)
		(layer "In11.Cu")
		(net "M_H_CPU0_SA_DQ<26>")
	)
	(arc
		(start 381.870966 -270.18996)
		(mid 381.793337 -269.911547)
		(end 381.588264 -269.707868)
		(width 0.088646)
		(layer "In11.Cu")
		(net "M_H_CPU0_SA_DQ<26>")
	)
	(arc
		(start 379.700028 -268.075156)
		(mid 379.569114 -267.938796)
		(end 379.521466 -267.755878)
		(width 0.088646)
		(layer "In11.Cu")
		(net "M_H_CPU0_SA_DQ<26>")
	)
	(arc
		(start 378.299218 -267.266166)
		(mid 378.024989 -267.190241)
		(end 377.748546 -267.25753)
		(width 0.088646)
		(layer "In11.Cu")
		(net "M_H_CPU0_SA_DQ<26>")
	)
	(arc
		(start 376.794014 -267.266166)
		(mid 376.606816 -267.316309)
		(end 376.419618 -267.266166)
		(width 0.088646)
		(layer "In11.Cu")
		(net "M_H_CPU0_SA_DQ<26>")
	)
	(arc
		(start 380.169928 -268.888972)
		(mid 380.039014 -268.752612)
		(end 379.991366 -268.569694)
		(width 0.088646)
		(layer "In11.Cu")
		(net "M_H_CPU0_SA_DQ<26>")
	)
	(arc
		(start 378.673614 -267.266166)
		(mid 378.486416 -267.316309)
		(end 378.299218 -267.266166)
		(width 0.088646)
		(layer "In11.Cu")
		(net "M_H_CPU0_SA_DQ<26>")
	)
	(arc
		(start 379.239018 -267.266166)
		(mid 378.964789 -267.190241)
		(end 378.688346 -267.25753)
		(width 0.088646)
		(layer "In11.Cu")
		(net "M_H_CPU0_SA_DQ<26>")
	)
	(arc
		(start 382.998218 -270.521938)
		(mid 382.724019 -270.446103)
		(end 382.447546 -270.513302)
		(width 0.088646)
		(layer "In11.Cu")
		(net "M_H_CPU0_SA_DQ<26>")
	)
	(arc
		(start 382.049528 -270.516858)
		(mid 381.918614 -270.380498)
		(end 381.870966 -270.19758)
		(width 0.088646)
		(layer "In11.Cu")
		(net "M_H_CPU0_SA_DQ<26>")
	)
	(arc
		(start 381.118618 -268.894052)
		(mid 380.835916 -268.818276)
		(end 380.553214 -268.894052)
		(width 0.088646)
		(layer "In11.Cu")
		(net "M_H_CPU0_SA_DQ<26>")
	)
	(arc
		(start 384.312414 -270.521938)
		(mid 384.125216 -270.572081)
		(end 383.938018 -270.521938)
		(width 0.088646)
		(layer "In11.Cu")
		(net "M_H_CPU0_SA_DQ<26>")
	)
	(arc
		(start 377.359418 -267.266166)
		(mid 377.085189 -267.190241)
		(end 376.808746 -267.25753)
		(width 0.088646)
		(layer "In11.Cu")
		(net "M_H_CPU0_SA_DQ<26>")
	)
	(arc
		(start 379.521466 -267.741654)
		(mid 379.442325 -267.467031)
		(end 379.239018 -267.266166)
		(width 0.088646)
		(layer "In11.Cu")
		(net "M_H_CPU0_SA_DQ<26>")
	)
	(arc
		(start 376.419618 -267.266166)
		(mid 376.145389 -267.190241)
		(end 375.868946 -267.25753)
		(width 0.088646)
		(layer "In11.Cu")
		(net "M_H_CPU0_SA_DQ<26>")
	)
	(arc
		(start 372.651528 -267.261086)
		(mid 372.535789 -267.149262)
		(end 372.477538 -266.999212)
		(width 0.088646)
		(layer "In11.Cu")
		(net "M_H_CPU0_SA_DQ<26>")
	)
	(arc
		(start 375.479818 -267.266166)
		(mid 375.205589 -267.190241)
		(end 374.929146 -267.25753)
		(width 0.088646)
		(layer "In11.Cu")
		(net "M_H_CPU0_SA_DQ<26>")
	)
	(arc
		(start 385.817618 -270.521938)
		(mid 385.543419 -270.446103)
		(end 385.266946 -270.513302)
		(width 0.088646)
		(layer "In11.Cu")
		(net "M_H_CPU0_SA_DQ<26>")
	)
	(arc
		(start 374.540018 -267.266166)
		(mid 374.263205 -267.19033)
		(end 373.984774 -267.26007)
		(width 0.088646)
		(layer "In11.Cu")
		(net "M_H_CPU0_SA_DQ<26>")
	)
	(arc
		(start 379.991366 -268.559788)
		(mid 379.913255 -268.282839)
		(end 379.708918 -268.080236)
		(width 0.088646)
		(layer "In11.Cu")
		(net "M_H_CPU0_SA_DQ<26>")
	)
	(arc
		(start 374.914668 -267.266166)
		(mid 374.72736 -267.316309)
		(end 374.540018 -267.266166)
		(width 0.088646)
		(layer "In11.Cu")
		(net "M_H_CPU0_SA_DQ<26>")
	)
	(arc
		(start 383.938018 -270.521938)
		(mid 383.663819 -270.446103)
		(end 383.387346 -270.513302)
		(width 0.088646)
		(layer "In11.Cu")
		(net "M_H_CPU0_SA_DQ<26>")
	)
	(arc
		(start 386.192014 -270.521938)
		(mid 386.004816 -270.572081)
		(end 385.817618 -270.521938)
		(width 0.088646)
		(layer "In11.Cu")
		(net "M_H_CPU0_SA_DQ<26>")
	)
	(arc
		(start 373.97436 -267.266166)
		(mid 373.787162 -267.316309)
		(end 373.599964 -267.266166)
		(width 0.088646)
		(layer "In11.Cu")
		(net "M_H_CPU0_SA_DQ<26>")
	)
	(arc
		(start 377.733814 -267.266166)
		(mid 377.546616 -267.316309)
		(end 377.359418 -267.266166)
		(width 0.088646)
		(layer "In11.Cu")
		(net "M_H_CPU0_SA_DQ<26>")
	)
	(segment
		(start 454.566782 -286.141668)
		(end 454.448672 -286.259778)
		(width 0.20066)
		(layer "F.Cu")
		(net "M_H_CPU0_SA_DQ<25>")
	)
	(segment
		(start 457.53655 -286.135318)
		(end 457.126594 -286.135318)
		(width 0.20066)
		(layer "F.Cu")
		(net "M_H_CPU0_SA_DQ<25>")
	)
	(segment
		(start 457.126594 -286.135318)
		(end 457.120244 -286.141668)
		(width 0.1016)
		(layer "F.Cu")
		(net "M_H_CPU0_SA_DQ<25>")
	)
	(segment
		(start 453.785478 -286.815276)
		(end 453.536812 -286.56661)
		(width 0.20066)
		(layer "F.Cu")
		(net "M_H_CPU0_SA_DQ<25>")
	)
	(segment
		(start 454.931526 -286.141668)
		(end 454.91146 -286.141668)
		(width 0.101854)
		(layer "F.Cu")
		(net "M_H_CPU0_SA_DQ<25>")
	)
	(segment
		(start 459.55966 -286.566864)
		(end 457.968096 -286.566864)
		(width 0.20066)
		(layer "F.Cu")
		(net "M_H_CPU0_SA_DQ<25>")
	)
	(segment
		(start 454.448672 -286.627316)
		(end 454.260712 -286.815276)
		(width 0.20066)
		(layer "F.Cu")
		(net "M_H_CPU0_SA_DQ<25>")
	)
	(segment
		(start 453.536812 -286.56661)
		(end 452.016114 -286.56661)
		(width 0.20066)
		(layer "F.Cu")
		(net "M_H_CPU0_SA_DQ<25>")
	)
	(segment
		(start 371.437916 -265.592306)
		(end 371.437916 -266.127992)
		(width 0.20066)
		(layer "F.Cu")
		(net "M_H_CPU0_SA_DQ<25>")
	)
	(segment
		(start 454.91146 -286.141668)
		(end 454.566782 -286.141668)
		(width 0.20066)
		(layer "F.Cu")
		(net "M_H_CPU0_SA_DQ<25>")
	)
	(segment
		(start 459.559914 -286.56661)
		(end 459.55966 -286.566864)
		(width 0.20066)
		(layer "F.Cu")
		(net "M_H_CPU0_SA_DQ<25>")
	)
	(segment
		(start 457.968096 -286.566864)
		(end 457.53655 -286.135318)
		(width 0.20066)
		(layer "F.Cu")
		(net "M_H_CPU0_SA_DQ<25>")
	)
	(segment
		(start 457.120244 -286.141668)
		(end 454.931526 -286.141668)
		(width 0.1016)
		(layer "F.Cu")
		(net "M_H_CPU0_SA_DQ<25>")
	)
	(segment
		(start 371.437916 -266.127992)
		(end 371.437662 -266.128246)
		(width 0.20066)
		(layer "F.Cu")
		(net "M_H_CPU0_SA_DQ<25>")
	)
	(segment
		(start 454.448672 -286.259778)
		(end 454.448672 -286.627316)
		(width 0.20066)
		(layer "F.Cu")
		(net "M_H_CPU0_SA_DQ<25>")
	)
	(segment
		(start 452.016114 -286.56661)
		(end 450.911214 -286.56661)
		(width 0.20066)
		(layer "F.Cu")
		(net "M_H_CPU0_SA_DQ<25>")
	)
	(segment
		(start 454.260712 -286.815276)
		(end 453.785478 -286.815276)
		(width 0.20066)
		(layer "F.Cu")
		(net "M_H_CPU0_SA_DQ<25>")
	)
	(segment
		(start 387.671564 -270.093948)
		(end 386.418836 -270.093948)
		(width 0.088646)
		(layer "In11.Cu")
		(net "M_H_CPU0_SA_DQ<25>")
	)
	(segment
		(start 406.60574 -286.530288)
		(end 406.37968 -286.530288)
		(width 0.18288)
		(layer "In11.Cu")
		(net "M_H_CPU0_SA_DQ<25>")
	)
	(segment
		(start 424.065192 -290.390834)
		(end 423.93362 -290.259262)
		(width 0.18288)
		(layer "In11.Cu")
		(net "M_H_CPU0_SA_DQ<25>")
	)
	(segment
		(start 387.987286 -270.51127)
		(end 387.987286 -270.40967)
		(width 0.088646)
		(layer "In11.Cu")
		(net "M_H_CPU0_SA_DQ<25>")
	)
	(segment
		(start 380.270512 -267.755878)
		(end 380.270512 -267.747242)
		(width 0.088646)
		(layer "In11.Cu")
		(net "M_H_CPU0_SA_DQ<25>")
	)
	(segment
		(start 450.911214 -286.417004)
		(end 450.850254 -286.269684)
		(width 0.18288)
		(layer "In11.Cu")
		(net "M_H_CPU0_SA_DQ<25>")
	)
	(segment
		(start 386.418836 -270.093948)
		(end 386.206746 -269.881858)
		(width 0.088646)
		(layer "In11.Cu")
		(net "M_H_CPU0_SA_DQ<25>")
	)
	(segment
		(start 388.591806 -270.774414)
		(end 388.25043 -270.774414)
		(width 0.088646)
		(layer "In11.Cu")
		(net "M_H_CPU0_SA_DQ<25>")
	)
	(segment
		(start 387.987286 -270.40967)
		(end 387.671564 -270.093948)
		(width 0.088646)
		(layer "In11.Cu")
		(net "M_H_CPU0_SA_DQ<25>")
	)
	(segment
		(start 444.787528 -288.787332)
		(end 444.787528 -289.02533)
		(width 0.18288)
		(layer "In11.Cu")
		(net "M_H_CPU0_SA_DQ<25>")
	)
	(segment
		(start 378.688346 -266.62634)
		(end 378.673614 -266.617704)
		(width 0.088646)
		(layer "In11.Cu")
		(net "M_H_CPU0_SA_DQ<25>")
	)
	(segment
		(start 409.94711 -287.736026)
		(end 409.052522 -287.736026)
		(width 0.18288)
		(layer "In11.Cu")
		(net "M_H_CPU0_SA_DQ<25>")
	)
	(segment
		(start 429.740314 -288.74593)
		(end 429.740314 -288.886646)
		(width 0.18288)
		(layer "In11.Cu")
		(net "M_H_CPU0_SA_DQ<25>")
	)
	(segment
		(start 444.083948 -289.02533)
		(end 444.083948 -288.787332)
		(width 0.18288)
		(layer "In11.Cu")
		(net "M_H_CPU0_SA_DQ<25>")
	)
	(segment
		(start 434.913024 -289.382962)
		(end 432.02225 -289.382962)
		(width 0.18288)
		(layer "In11.Cu")
		(net "M_H_CPU0_SA_DQ<25>")
	)
	(segment
		(start 379.621288 -266.622276)
		(end 379.613414 -266.617704)
		(width 0.088646)
		(layer "In11.Cu")
		(net "M_H_CPU0_SA_DQ<25>")
	)
	(segment
		(start 374.929146 -266.62634)
		(end 374.914414 -266.617704)
		(width 0.088646)
		(layer "In11.Cu")
		(net "M_H_CPU0_SA_DQ<25>")
	)
	(segment
		(start 443.890908 -288.594292)
		(end 443.199774 -288.594292)
		(width 0.18288)
		(layer "In11.Cu")
		(net "M_H_CPU0_SA_DQ<25>")
	)
	(segment
		(start 386.206746 -269.881858)
		(end 386.192014 -269.873222)
		(width 0.088646)
		(layer "In11.Cu")
		(net "M_H_CPU0_SA_DQ<25>")
	)
	(segment
		(start 419.151562 -291.074094)
		(end 417.468558 -289.39109)
		(width 0.18288)
		(layer "In11.Cu")
		(net "M_H_CPU0_SA_DQ<25>")
	)
	(segment
		(start 442.401198 -289.392868)
		(end 441.803536 -289.392868)
		(width 0.18288)
		(layer "In11.Cu")
		(net "M_H_CPU0_SA_DQ<25>")
	)
	(segment
		(start 440.80557 -290.390834)
		(end 439.245756 -290.390834)
		(width 0.18288)
		(layer "In11.Cu")
		(net "M_H_CPU0_SA_DQ<25>")
	)
	(segment
		(start 432.02225 -289.382962)
		(end 431.192178 -288.55289)
		(width 0.18288)
		(layer "In11.Cu")
		(net "M_H_CPU0_SA_DQ<25>")
	)
	(segment
		(start 425.793154 -290.390834)
		(end 424.065192 -290.390834)
		(width 0.18288)
		(layer "In11.Cu")
		(net "M_H_CPU0_SA_DQ<25>")
	)
	(segment
		(start 382.447546 -269.881858)
		(end 382.432814 -269.873222)
		(width 0.088646)
		(layer "In11.Cu")
		(net "M_H_CPU0_SA_DQ<25>")
	)
	(segment
		(start 382.150112 -269.397734)
		(end 382.150112 -269.38351)
		(width 0.088646)
		(layer "In11.Cu")
		(net "M_H_CPU0_SA_DQ<25>")
	)
	(segment
		(start 377.748546 -266.62634)
		(end 377.733814 -266.617704)
		(width 0.088646)
		(layer "In11.Cu")
		(net "M_H_CPU0_SA_DQ<25>")
	)
	(segment
		(start 380.567946 -268.253972)
		(end 380.553214 -268.245336)
		(width 0.088646)
		(layer "In11.Cu")
		(net "M_H_CPU0_SA_DQ<25>")
	)
	(segment
		(start 423.93362 -290.259262)
		(end 422.382442 -290.259262)
		(width 0.18288)
		(layer "In11.Cu")
		(net "M_H_CPU0_SA_DQ<25>")
	)
	(segment
		(start 406.315164 -285.64967)
		(end 405.769826 -285.104332)
		(width 0.18288)
		(layer "In11.Cu")
		(net "M_H_CPU0_SA_DQ<25>")
	)
	(segment
		(start 429.740314 -288.886646)
		(end 429.547274 -289.079686)
		(width 0.18288)
		(layer "In11.Cu")
		(net "M_H_CPU0_SA_DQ<25>")
	)
	(segment
		(start 447.656712 -287.781492)
		(end 446.629028 -287.781492)
		(width 0.18288)
		(layer "In11.Cu")
		(net "M_H_CPU0_SA_DQ<25>")
	)
	(segment
		(start 410.398214 -288.18713)
		(end 409.94711 -287.736026)
		(width 0.18288)
		(layer "In11.Cu")
		(net "M_H_CPU0_SA_DQ<25>")
	)
	(segment
		(start 446.629028 -287.781492)
		(end 445.816228 -288.594292)
		(width 0.18288)
		(layer "In11.Cu")
		(net "M_H_CPU0_SA_DQ<25>")
	)
	(segment
		(start 376.808746 -266.62634)
		(end 376.794014 -266.617704)
		(width 0.088646)
		(layer "In11.Cu")
		(net "M_H_CPU0_SA_DQ<25>")
	)
	(segment
		(start 431.192178 -288.55289)
		(end 429.933354 -288.55289)
		(width 0.18288)
		(layer "In11.Cu")
		(net "M_H_CPU0_SA_DQ<25>")
	)
	(segment
		(start 414.295336 -288.567114)
		(end 413.898334 -288.170112)
		(width 0.18288)
		(layer "In11.Cu")
		(net "M_H_CPU0_SA_DQ<25>")
	)
	(segment
		(start 413.898334 -288.170112)
		(end 412.70428 -288.170112)
		(width 0.18288)
		(layer "In11.Cu")
		(net "M_H_CPU0_SA_DQ<25>")
	)
	(segment
		(start 411.719522 -287.736026)
		(end 411.268418 -288.18713)
		(width 0.18288)
		(layer "In11.Cu")
		(net "M_H_CPU0_SA_DQ<25>")
	)
	(segment
		(start 407.584402 -286.918908)
		(end 407.013664 -286.34817)
		(width 0.18288)
		(layer "In11.Cu")
		(net "M_H_CPU0_SA_DQ<25>")
	)
	(segment
		(start 426.918628 -289.26536)
		(end 425.793154 -290.390834)
		(width 0.18288)
		(layer "In11.Cu")
		(net "M_H_CPU0_SA_DQ<25>")
	)
	(segment
		(start 412.70428 -288.170112)
		(end 412.270194 -287.736026)
		(width 0.18288)
		(layer "In11.Cu")
		(net "M_H_CPU0_SA_DQ<25>")
	)
	(segment
		(start 427.48454 -289.26536)
		(end 426.918628 -289.26536)
		(width 0.18288)
		(layer "In11.Cu")
		(net "M_H_CPU0_SA_DQ<25>")
	)
	(segment
		(start 390.423908 -270.774414)
		(end 388.591806 -270.774414)
		(width 0.18288)
		(layer "In11.Cu")
		(net "M_H_CPU0_SA_DQ<25>")
	)
	(segment
		(start 383.387346 -269.881858)
		(end 383.372614 -269.873222)
		(width 0.088646)
		(layer "In11.Cu")
		(net "M_H_CPU0_SA_DQ<25>")
	)
	(segment
		(start 375.868946 -266.62634)
		(end 375.854214 -266.617704)
		(width 0.088646)
		(layer "In11.Cu")
		(net "M_H_CPU0_SA_DQ<25>")
	)
	(segment
		(start 384.327146 -269.881858)
		(end 384.312414 -269.873222)
		(width 0.088646)
		(layer "In11.Cu")
		(net "M_H_CPU0_SA_DQ<25>")
	)
	(segment
		(start 428.19701 -288.55289)
		(end 427.48454 -289.26536)
		(width 0.18288)
		(layer "In11.Cu")
		(net "M_H_CPU0_SA_DQ<25>")
	)
	(segment
		(start 420.081202 -291.074094)
		(end 419.151562 -291.074094)
		(width 0.18288)
		(layer "In11.Cu")
		(net "M_H_CPU0_SA_DQ<25>")
	)
	(segment
		(start 411.268418 -288.18713)
		(end 410.398214 -288.18713)
		(width 0.18288)
		(layer "In11.Cu")
		(net "M_H_CPU0_SA_DQ<25>")
	)
	(segment
		(start 417.468558 -289.39109)
		(end 416.753294 -289.39109)
		(width 0.18288)
		(layer "In11.Cu")
		(net "M_H_CPU0_SA_DQ<25>")
	)
	(segment
		(start 416.753294 -289.39109)
		(end 415.929318 -288.567114)
		(width 0.18288)
		(layer "In11.Cu")
		(net "M_H_CPU0_SA_DQ<25>")
	)
	(segment
		(start 406.1333 -286.057848)
		(end 406.315164 -285.87573)
		(width 0.18288)
		(layer "In11.Cu")
		(net "M_H_CPU0_SA_DQ<25>")
	)
	(segment
		(start 381.97155 -269.064232)
		(end 381.96266 -269.059152)
		(width 0.088646)
		(layer "In11.Cu")
		(net "M_H_CPU0_SA_DQ<25>")
	)
	(segment
		(start 449.403978 -286.034226)
		(end 447.656712 -287.781492)
		(width 0.18288)
		(layer "In11.Cu")
		(net "M_H_CPU0_SA_DQ<25>")
	)
	(segment
		(start 406.787604 -286.34817)
		(end 406.60574 -286.530288)
		(width 0.18288)
		(layer "In11.Cu")
		(net "M_H_CPU0_SA_DQ<25>")
	)
	(segment
		(start 422.382442 -290.259262)
		(end 421.39997 -291.241734)
		(width 0.18288)
		(layer "In11.Cu")
		(net "M_H_CPU0_SA_DQ<25>")
	)
	(segment
		(start 381.501904 -268.250416)
		(end 381.493014 -268.245336)
		(width 0.088646)
		(layer "In11.Cu")
		(net "M_H_CPU0_SA_DQ<25>")
	)
	(segment
		(start 407.013664 -286.34817)
		(end 406.787604 -286.34817)
		(width 0.18288)
		(layer "In11.Cu")
		(net "M_H_CPU0_SA_DQ<25>")
	)
	(segment
		(start 435.072028 -289.541966)
		(end 434.913024 -289.382962)
		(width 0.18288)
		(layer "In11.Cu")
		(net "M_H_CPU0_SA_DQ<25>")
	)
	(segment
		(start 381.680466 -268.585188)
		(end 381.680466 -268.569694)
		(width 0.088646)
		(layer "In11.Cu")
		(net "M_H_CPU0_SA_DQ<25>")
	)
	(segment
		(start 406.315164 -285.87573)
		(end 406.315164 -285.64967)
		(width 0.18288)
		(layer "In11.Cu")
		(net "M_H_CPU0_SA_DQ<25>")
	)
	(segment
		(start 405.769826 -285.104332)
		(end 404.753826 -285.104332)
		(width 0.18288)
		(layer "In11.Cu")
		(net "M_H_CPU0_SA_DQ<25>")
	)
	(segment
		(start 372.368318 -266.502642)
		(end 372.222268 -266.502134)
		(width 0.088646)
		(layer "In11.Cu")
		(net "M_H_CPU0_SA_DQ<25>")
	)
	(segment
		(start 404.753826 -285.104332)
		(end 390.423908 -270.774414)
		(width 0.18288)
		(layer "In11.Cu")
		(net "M_H_CPU0_SA_DQ<25>")
	)
	(segment
		(start 373.975122 -266.617704)
		(end 373.97436 -266.61745)
		(width 0.088646)
		(layer "In11.Cu")
		(net "M_H_CPU0_SA_DQ<25>")
	)
	(segment
		(start 412.270194 -287.736026)
		(end 411.719522 -287.736026)
		(width 0.18288)
		(layer "In11.Cu")
		(net "M_H_CPU0_SA_DQ<25>")
	)
	(segment
		(start 429.933354 -288.55289)
		(end 429.740314 -288.74593)
		(width 0.18288)
		(layer "In11.Cu")
		(net "M_H_CPU0_SA_DQ<25>")
	)
	(segment
		(start 450.911214 -286.56661)
		(end 450.911214 -286.417004)
		(width 0.18288)
		(layer "In11.Cu")
		(net "M_H_CPU0_SA_DQ<25>")
	)
	(segment
		(start 444.594488 -289.21837)
		(end 444.276988 -289.21837)
		(width 0.18288)
		(layer "In11.Cu")
		(net "M_H_CPU0_SA_DQ<25>")
	)
	(segment
		(start 429.036734 -288.74593)
		(end 428.843694 -288.55289)
		(width 0.18288)
		(layer "In11.Cu")
		(net "M_H_CPU0_SA_DQ<25>")
	)
	(segment
		(start 438.584594 -289.729672)
		(end 436.585106 -289.729672)
		(width 0.18288)
		(layer "In11.Cu")
		(net "M_H_CPU0_SA_DQ<25>")
	)
	(segment
		(start 444.980568 -288.594292)
		(end 444.787528 -288.787332)
		(width 0.18288)
		(layer "In11.Cu")
		(net "M_H_CPU0_SA_DQ<25>")
	)
	(segment
		(start 372.222268 -266.502134)
		(end 371.437662 -266.128246)
		(width 0.088646)
		(layer "In11.Cu")
		(net "M_H_CPU0_SA_DQ<25>")
	)
	(segment
		(start 409.052522 -287.736026)
		(end 408.235404 -286.918908)
		(width 0.18288)
		(layer "In11.Cu")
		(net "M_H_CPU0_SA_DQ<25>")
	)
	(segment
		(start 444.083948 -288.787332)
		(end 443.890908 -288.594292)
		(width 0.18288)
		(layer "In11.Cu")
		(net "M_H_CPU0_SA_DQ<25>")
	)
	(segment
		(start 443.199774 -288.594292)
		(end 442.401198 -289.392868)
		(width 0.18288)
		(layer "In11.Cu")
		(net "M_H_CPU0_SA_DQ<25>")
	)
	(segment
		(start 429.036734 -288.886646)
		(end 429.036734 -288.74593)
		(width 0.18288)
		(layer "In11.Cu")
		(net "M_H_CPU0_SA_DQ<25>")
	)
	(segment
		(start 415.929318 -288.567114)
		(end 414.295336 -288.567114)
		(width 0.18288)
		(layer "In11.Cu")
		(net "M_H_CPU0_SA_DQ<25>")
	)
	(segment
		(start 388.25043 -270.774414)
		(end 387.987286 -270.51127)
		(width 0.088646)
		(layer "In11.Cu")
		(net "M_H_CPU0_SA_DQ<25>")
	)
	(segment
		(start 429.547274 -289.079686)
		(end 429.229774 -289.079686)
		(width 0.18288)
		(layer "In11.Cu")
		(net "M_H_CPU0_SA_DQ<25>")
	)
	(segment
		(start 439.245756 -290.390834)
		(end 438.584594 -289.729672)
		(width 0.18288)
		(layer "In11.Cu")
		(net "M_H_CPU0_SA_DQ<25>")
	)
	(segment
		(start 406.37968 -286.530288)
		(end 406.1333 -286.283908)
		(width 0.18288)
		(layer "In11.Cu")
		(net "M_H_CPU0_SA_DQ<25>")
	)
	(segment
		(start 444.276988 -289.21837)
		(end 444.083948 -289.02533)
		(width 0.18288)
		(layer "In11.Cu")
		(net "M_H_CPU0_SA_DQ<25>")
	)
	(segment
		(start 420.248842 -291.241734)
		(end 420.081202 -291.074094)
		(width 0.18288)
		(layer "In11.Cu")
		(net "M_H_CPU0_SA_DQ<25>")
	)
	(segment
		(start 379.800612 -266.956032)
		(end 379.800612 -266.941808)
		(width 0.088646)
		(layer "In11.Cu")
		(net "M_H_CPU0_SA_DQ<25>")
	)
	(segment
		(start 408.235404 -286.918908)
		(end 407.584402 -286.918908)
		(width 0.18288)
		(layer "In11.Cu")
		(net "M_H_CPU0_SA_DQ<25>")
	)
	(segment
		(start 444.787528 -289.02533)
		(end 444.594488 -289.21837)
		(width 0.18288)
		(layer "In11.Cu")
		(net "M_H_CPU0_SA_DQ<25>")
	)
	(segment
		(start 373.550942 -266.502642)
		(end 372.368318 -266.502642)
		(width 0.088646)
		(layer "In11.Cu")
		(net "M_H_CPU0_SA_DQ<25>")
	)
	(segment
		(start 429.229774 -289.079686)
		(end 429.036734 -288.886646)
		(width 0.18288)
		(layer "In11.Cu")
		(net "M_H_CPU0_SA_DQ<25>")
	)
	(segment
		(start 380.553214 -268.245336)
		(end 380.547118 -268.24178)
		(width 0.088646)
		(layer "In11.Cu")
		(net "M_H_CPU0_SA_DQ<25>")
	)
	(segment
		(start 445.816228 -288.594292)
		(end 444.980568 -288.594292)
		(width 0.18288)
		(layer "In11.Cu")
		(net "M_H_CPU0_SA_DQ<25>")
	)
	(segment
		(start 385.266946 -269.881858)
		(end 385.252214 -269.873222)
		(width 0.088646)
		(layer "In11.Cu")
		(net "M_H_CPU0_SA_DQ<25>")
	)
	(segment
		(start 450.614796 -286.034226)
		(end 449.403978 -286.034226)
		(width 0.18288)
		(layer "In11.Cu")
		(net "M_H_CPU0_SA_DQ<25>")
	)
	(segment
		(start 406.1333 -286.283908)
		(end 406.1333 -286.057848)
		(width 0.18288)
		(layer "In11.Cu")
		(net "M_H_CPU0_SA_DQ<25>")
	)
	(segment
		(start 436.3974 -289.541966)
		(end 435.072028 -289.541966)
		(width 0.18288)
		(layer "In11.Cu")
		(net "M_H_CPU0_SA_DQ<25>")
	)
	(segment
		(start 428.843694 -288.55289)
		(end 428.19701 -288.55289)
		(width 0.18288)
		(layer "In11.Cu")
		(net "M_H_CPU0_SA_DQ<25>")
	)
	(segment
		(start 436.585106 -289.729672)
		(end 436.3974 -289.541966)
		(width 0.18288)
		(layer "In11.Cu")
		(net "M_H_CPU0_SA_DQ<25>")
	)
	(segment
		(start 441.803536 -289.392868)
		(end 440.80557 -290.390834)
		(width 0.18288)
		(layer "In11.Cu")
		(net "M_H_CPU0_SA_DQ<25>")
	)
	(segment
		(start 421.39997 -291.241734)
		(end 420.248842 -291.241734)
		(width 0.18288)
		(layer "In11.Cu")
		(net "M_H_CPU0_SA_DQ<25>")
	)
	(segment
		(start 450.850254 -286.269684)
		(end 450.614796 -286.034226)
		(width 0.18288)
		(layer "In11.Cu")
		(net "M_H_CPU0_SA_DQ<25>")
	)
	(arc
		(start 374.914414 -266.617704)
		(mid 374.727216 -266.567527)
		(end 374.540018 -266.617704)
		(width 0.088646)
		(layer "In11.Cu")
		(net "M_H_CPU0_SA_DQ<25>")
	)
	(arc
		(start 386.192014 -269.873222)
		(mid 386.004816 -269.823079)
		(end 385.817618 -269.873222)
		(width 0.088646)
		(layer "In11.Cu")
		(net "M_H_CPU0_SA_DQ<25>")
	)
	(arc
		(start 383.938018 -269.873222)
		(mid 383.663789 -269.949147)
		(end 383.387346 -269.881858)
		(width 0.088646)
		(layer "In11.Cu")
		(net "M_H_CPU0_SA_DQ<25>")
	)
	(arc
		(start 373.97436 -266.61745)
		(mid 373.770295 -266.531853)
		(end 373.550942 -266.502642)
		(width 0.088646)
		(layer "In11.Cu")
		(net "M_H_CPU0_SA_DQ<25>")
	)
	(arc
		(start 383.372614 -269.873222)
		(mid 383.185416 -269.823079)
		(end 382.998218 -269.873222)
		(width 0.088646)
		(layer "In11.Cu")
		(net "M_H_CPU0_SA_DQ<25>")
	)
	(arc
		(start 380.083314 -267.43152)
		(mid 379.879833 -267.230716)
		(end 379.800612 -266.956032)
		(width 0.088646)
		(layer "In11.Cu")
		(net "M_H_CPU0_SA_DQ<25>")
	)
	(arc
		(start 381.493014 -268.245336)
		(mid 381.305816 -268.195193)
		(end 381.118618 -268.245336)
		(width 0.088646)
		(layer "In11.Cu")
		(net "M_H_CPU0_SA_DQ<25>")
	)
	(arc
		(start 382.998218 -269.873222)
		(mid 382.723989 -269.949147)
		(end 382.447546 -269.881858)
		(width 0.088646)
		(layer "In11.Cu")
		(net "M_H_CPU0_SA_DQ<25>")
	)
	(arc
		(start 384.312414 -269.873222)
		(mid 384.125216 -269.823079)
		(end 383.938018 -269.873222)
		(width 0.088646)
		(layer "In11.Cu")
		(net "M_H_CPU0_SA_DQ<25>")
	)
	(arc
		(start 384.877818 -269.873222)
		(mid 384.603589 -269.949147)
		(end 384.327146 -269.881858)
		(width 0.088646)
		(layer "In11.Cu")
		(net "M_H_CPU0_SA_DQ<25>")
	)
	(arc
		(start 380.547118 -268.24178)
		(mid 380.344531 -268.035429)
		(end 380.270512 -267.755878)
		(width 0.088646)
		(layer "In11.Cu")
		(net "M_H_CPU0_SA_DQ<25>")
	)
	(arc
		(start 382.432814 -269.873222)
		(mid 382.229333 -269.672418)
		(end 382.150112 -269.397734)
		(width 0.088646)
		(layer "In11.Cu")
		(net "M_H_CPU0_SA_DQ<25>")
	)
	(arc
		(start 377.733814 -266.617704)
		(mid 377.546616 -266.567527)
		(end 377.359418 -266.617704)
		(width 0.088646)
		(layer "In11.Cu")
		(net "M_H_CPU0_SA_DQ<25>")
	)
	(arc
		(start 378.299218 -266.617704)
		(mid 378.025019 -266.693539)
		(end 377.748546 -266.62634)
		(width 0.088646)
		(layer "In11.Cu")
		(net "M_H_CPU0_SA_DQ<25>")
	)
	(arc
		(start 380.270512 -267.747242)
		(mid 380.218242 -267.564877)
		(end 380.083314 -267.43152)
		(width 0.088646)
		(layer "In11.Cu")
		(net "M_H_CPU0_SA_DQ<25>")
	)
	(arc
		(start 381.96266 -269.059152)
		(mid 381.759837 -268.858921)
		(end 381.680466 -268.585188)
		(width 0.088646)
		(layer "In11.Cu")
		(net "M_H_CPU0_SA_DQ<25>")
	)
	(arc
		(start 378.673614 -266.617704)
		(mid 378.486416 -266.567527)
		(end 378.299218 -266.617704)
		(width 0.088646)
		(layer "In11.Cu")
		(net "M_H_CPU0_SA_DQ<25>")
	)
	(arc
		(start 381.680466 -268.569694)
		(mid 381.632787 -268.386794)
		(end 381.501904 -268.250416)
		(width 0.088646)
		(layer "In11.Cu")
		(net "M_H_CPU0_SA_DQ<25>")
	)
	(arc
		(start 381.118618 -268.245336)
		(mid 380.844419 -268.321171)
		(end 380.567946 -268.253972)
		(width 0.088646)
		(layer "In11.Cu")
		(net "M_H_CPU0_SA_DQ<25>")
	)
	(arc
		(start 379.239018 -266.617704)
		(mid 378.964819 -266.693539)
		(end 378.688346 -266.62634)
		(width 0.088646)
		(layer "In11.Cu")
		(net "M_H_CPU0_SA_DQ<25>")
	)
	(arc
		(start 382.150112 -269.38351)
		(mid 382.102433 -269.20061)
		(end 381.97155 -269.064232)
		(width 0.088646)
		(layer "In11.Cu")
		(net "M_H_CPU0_SA_DQ<25>")
	)
	(arc
		(start 385.252214 -269.873222)
		(mid 385.065016 -269.823079)
		(end 384.877818 -269.873222)
		(width 0.088646)
		(layer "In11.Cu")
		(net "M_H_CPU0_SA_DQ<25>")
	)
	(arc
		(start 375.854214 -266.617704)
		(mid 375.667016 -266.567527)
		(end 375.479818 -266.617704)
		(width 0.088646)
		(layer "In11.Cu")
		(net "M_H_CPU0_SA_DQ<25>")
	)
	(arc
		(start 375.479818 -266.617704)
		(mid 375.205619 -266.693539)
		(end 374.929146 -266.62634)
		(width 0.088646)
		(layer "In11.Cu")
		(net "M_H_CPU0_SA_DQ<25>")
	)
	(arc
		(start 377.359418 -266.617704)
		(mid 377.085219 -266.693539)
		(end 376.808746 -266.62634)
		(width 0.088646)
		(layer "In11.Cu")
		(net "M_H_CPU0_SA_DQ<25>")
	)
	(arc
		(start 374.540018 -266.617704)
		(mid 374.25757 -266.693421)
		(end 373.975122 -266.617704)
		(width 0.088646)
		(layer "In11.Cu")
		(net "M_H_CPU0_SA_DQ<25>")
	)
	(arc
		(start 376.794014 -266.617704)
		(mid 376.606816 -266.567527)
		(end 376.419618 -266.617704)
		(width 0.088646)
		(layer "In11.Cu")
		(net "M_H_CPU0_SA_DQ<25>")
	)
	(arc
		(start 379.800612 -266.941808)
		(mid 379.752721 -266.758596)
		(end 379.621288 -266.622276)
		(width 0.088646)
		(layer "In11.Cu")
		(net "M_H_CPU0_SA_DQ<25>")
	)
	(arc
		(start 385.817618 -269.873222)
		(mid 385.543389 -269.949147)
		(end 385.266946 -269.881858)
		(width 0.088646)
		(layer "In11.Cu")
		(net "M_H_CPU0_SA_DQ<25>")
	)
	(arc
		(start 376.419618 -266.617704)
		(mid 376.145419 -266.693539)
		(end 375.868946 -266.62634)
		(width 0.088646)
		(layer "In11.Cu")
		(net "M_H_CPU0_SA_DQ<25>")
	)
	(arc
		(start 379.613414 -266.617704)
		(mid 379.426216 -266.567527)
		(end 379.239018 -266.617704)
		(width 0.088646)
		(layer "In11.Cu")
		(net "M_H_CPU0_SA_DQ<25>")
	)
	(segment
		(start 454.448672 -287.9598)
		(end 454.448672 -288.327338)
		(width 0.20066)
		(layer "F.Cu")
		(net "M_H_CPU0_SA_DQ<24>")
	)
	(segment
		(start 454.91146 -287.84169)
		(end 454.566782 -287.84169)
		(width 0.20066)
		(layer "F.Cu")
		(net "M_H_CPU0_SA_DQ<24>")
	)
	(segment
		(start 454.448672 -288.327338)
		(end 454.260712 -288.515298)
		(width 0.20066)
		(layer "F.Cu")
		(net "M_H_CPU0_SA_DQ<24>")
	)
	(segment
		(start 457.968096 -288.266886)
		(end 457.53655 -287.83534)
		(width 0.20066)
		(layer "F.Cu")
		(net "M_H_CPU0_SA_DQ<24>")
	)
	(segment
		(start 457.53655 -287.83534)
		(end 457.126594 -287.83534)
		(width 0.20066)
		(layer "F.Cu")
		(net "M_H_CPU0_SA_DQ<24>")
	)
	(segment
		(start 459.559914 -288.266632)
		(end 459.55966 -288.266886)
		(width 0.20066)
		(layer "F.Cu")
		(net "M_H_CPU0_SA_DQ<24>")
	)
	(segment
		(start 454.260712 -288.515298)
		(end 453.785478 -288.515298)
		(width 0.20066)
		(layer "F.Cu")
		(net "M_H_CPU0_SA_DQ<24>")
	)
	(segment
		(start 452.016114 -288.266632)
		(end 450.911214 -288.266632)
		(width 0.20066)
		(layer "F.Cu")
		(net "M_H_CPU0_SA_DQ<24>")
	)
	(segment
		(start 453.785478 -288.515298)
		(end 453.536812 -288.266632)
		(width 0.20066)
		(layer "F.Cu")
		(net "M_H_CPU0_SA_DQ<24>")
	)
	(segment
		(start 454.566782 -287.84169)
		(end 454.448672 -287.9598)
		(width 0.20066)
		(layer "F.Cu")
		(net "M_H_CPU0_SA_DQ<24>")
	)
	(segment
		(start 457.126594 -287.83534)
		(end 457.120244 -287.84169)
		(width 0.1016)
		(layer "F.Cu")
		(net "M_H_CPU0_SA_DQ<24>")
	)
	(segment
		(start 457.120244 -287.84169)
		(end 454.95845 -287.84169)
		(width 0.1016)
		(layer "F.Cu")
		(net "M_H_CPU0_SA_DQ<24>")
	)
	(segment
		(start 454.95845 -287.84169)
		(end 454.91146 -287.84169)
		(width 0.101854)
		(layer "F.Cu")
		(net "M_H_CPU0_SA_DQ<24>")
	)
	(segment
		(start 453.536812 -288.266632)
		(end 452.016114 -288.266632)
		(width 0.20066)
		(layer "F.Cu")
		(net "M_H_CPU0_SA_DQ<24>")
	)
	(segment
		(start 459.55966 -288.266886)
		(end 457.968096 -288.266886)
		(width 0.20066)
		(layer "F.Cu")
		(net "M_H_CPU0_SA_DQ<24>")
	)
	(segment
		(start 371.907562 -266.941554)
		(end 371.907816 -266.941808)
		(width 0.20066)
		(layer "F.Cu")
		(net "M_H_CPU0_SA_DQ<24>")
	)
	(segment
		(start 371.907562 -266.405868)
		(end 371.907562 -266.941554)
		(width 0.20066)
		(layer "F.Cu")
		(net "M_H_CPU0_SA_DQ<24>")
	)
	(segment
		(start 380.648718 -269.059152)
		(end 380.638304 -269.065248)
		(width 0.088646)
		(layer "In11.Cu")
		(net "M_H_CPU0_SA_DQ<24>")
	)
	(segment
		(start 379.15215 -267.4366)
		(end 379.14326 -267.43152)
		(width 0.088646)
		(layer "In11.Cu")
		(net "M_H_CPU0_SA_DQ<24>")
	)
	(segment
		(start 438.720484 -291.600636)
		(end 437.30164 -291.600636)
		(width 0.18288)
		(layer "In11.Cu")
		(net "M_H_CPU0_SA_DQ<24>")
	)
	(segment
		(start 386.287264 -270.687038)
		(end 386.272532 -270.695674)
		(width 0.088646)
		(layer "In11.Cu")
		(net "M_H_CPU0_SA_DQ<24>")
	)
	(segment
		(start 428.194978 -290.28009)
		(end 427.310042 -291.165026)
		(width 0.18288)
		(layer "In11.Cu")
		(net "M_H_CPU0_SA_DQ<24>")
	)
	(segment
		(start 412.632906 -289.463226)
		(end 411.451044 -289.463226)
		(width 0.18288)
		(layer "In11.Cu")
		(net "M_H_CPU0_SA_DQ<24>")
	)
	(segment
		(start 447.729356 -289.363912)
		(end 446.750948 -289.363912)
		(width 0.18288)
		(layer "In11.Cu")
		(net "M_H_CPU0_SA_DQ<24>")
	)
	(segment
		(start 389.910828 -271.81937)
		(end 387.700012 -271.81937)
		(width 0.18288)
		(layer "In11.Cu")
		(net "M_H_CPU0_SA_DQ<24>")
	)
	(segment
		(start 387.700012 -271.81937)
		(end 387.538722 -271.65808)
		(width 0.18288)
		(layer "In11.Cu")
		(net "M_H_CPU0_SA_DQ<24>")
	)
	(segment
		(start 384.407664 -270.687038)
		(end 384.392932 -270.695674)
		(width 0.088646)
		(layer "In11.Cu")
		(net "M_H_CPU0_SA_DQ<24>")
	)
	(segment
		(start 429.91786 -290.47313)
		(end 429.91786 -290.813744)
		(width 0.18288)
		(layer "In11.Cu")
		(net "M_H_CPU0_SA_DQ<24>")
	)
	(segment
		(start 381.958342 -270.684498)
		(end 381.956564 -270.683482)
		(width 0.088646)
		(layer "In11.Cu")
		(net "M_H_CPU0_SA_DQ<24>")
	)
	(segment
		(start 377.829064 -267.43152)
		(end 377.814332 -267.440156)
		(width 0.088646)
		(layer "In11.Cu")
		(net "M_H_CPU0_SA_DQ<24>")
	)
	(segment
		(start 446.750948 -289.363912)
		(end 445.762126 -290.352734)
		(width 0.18288)
		(layer "In11.Cu")
		(net "M_H_CPU0_SA_DQ<24>")
	)
	(segment
		(start 383.467864 -270.687038)
		(end 383.453132 -270.695674)
		(width 0.088646)
		(layer "In11.Cu")
		(net "M_H_CPU0_SA_DQ<24>")
	)
	(segment
		(start 407.573226 -289.564064)
		(end 406.53208 -288.522918)
		(width 0.18288)
		(layer "In11.Cu")
		(net "M_H_CPU0_SA_DQ<24>")
	)
	(segment
		(start 450.592444 -288.309812)
		(end 450.093588 -287.812226)
		(width 0.18288)
		(layer "In11.Cu")
		(net "M_H_CPU0_SA_DQ<24>")
	)
	(segment
		(start 381.210312 -269.402052)
		(end 381.210312 -269.374874)
		(width 0.088646)
		(layer "In11.Cu")
		(net "M_H_CPU0_SA_DQ<24>")
	)
	(segment
		(start 429.72482 -291.006784)
		(end 429.40732 -291.006784)
		(width 0.18288)
		(layer "In11.Cu")
		(net "M_H_CPU0_SA_DQ<24>")
	)
	(segment
		(start 379.613414 -268.245336)
		(end 379.601222 -268.238224)
		(width 0.088646)
		(layer "In11.Cu")
		(net "M_H_CPU0_SA_DQ<24>")
	)
	(segment
		(start 417.384738 -291.14369)
		(end 416.635438 -291.14369)
		(width 0.18288)
		(layer "In11.Cu")
		(net "M_H_CPU0_SA_DQ<24>")
	)
	(segment
		(start 381.50165 -269.878302)
		(end 381.49276 -269.873222)
		(width 0.088646)
		(layer "In11.Cu")
		(net "M_H_CPU0_SA_DQ<24>")
	)
	(segment
		(start 429.21428 -290.47313)
		(end 429.02124 -290.28009)
		(width 0.18288)
		(layer "In11.Cu")
		(net "M_H_CPU0_SA_DQ<24>")
	)
	(segment
		(start 442.038994 -291.04082)
		(end 440.988958 -292.090856)
		(width 0.18288)
		(layer "In11.Cu")
		(net "M_H_CPU0_SA_DQ<24>")
	)
	(segment
		(start 379.622304 -268.250416)
		(end 379.613414 -268.245336)
		(width 0.088646)
		(layer "In11.Cu")
		(net "M_H_CPU0_SA_DQ<24>")
	)
	(segment
		(start 387.538722 -271.65808)
		(end 387.11759 -271.236948)
		(width 0.088646)
		(layer "In11.Cu")
		(net "M_H_CPU0_SA_DQ<24>")
	)
	(segment
		(start 411.258004 -290.035742)
		(end 411.064964 -290.228782)
		(width 0.18288)
		(layer "In11.Cu")
		(net "M_H_CPU0_SA_DQ<24>")
	)
	(segment
		(start 376.889264 -267.43152)
		(end 376.874532 -267.440156)
		(width 0.088646)
		(layer "In11.Cu")
		(net "M_H_CPU0_SA_DQ<24>")
	)
	(segment
		(start 445.762126 -290.352734)
		(end 443.168532 -290.352734)
		(width 0.18288)
		(layer "In11.Cu")
		(net "M_H_CPU0_SA_DQ<24>")
	)
	(segment
		(start 416.635438 -291.14369)
		(end 415.836862 -290.345114)
		(width 0.18288)
		(layer "In11.Cu")
		(net "M_H_CPU0_SA_DQ<24>")
	)
	(segment
		(start 408.917394 -289.463226)
		(end 408.816556 -289.564064)
		(width 0.18288)
		(layer "In11.Cu")
		(net "M_H_CPU0_SA_DQ<24>")
	)
	(segment
		(start 437.30164 -291.600636)
		(end 436.941976 -291.240972)
		(width 0.18288)
		(layer "In11.Cu")
		(net "M_H_CPU0_SA_DQ<24>")
	)
	(segment
		(start 372.285768 -267.007086)
		(end 372.22049 -266.941808)
		(width 0.088646)
		(layer "In11.Cu")
		(net "M_H_CPU0_SA_DQ<24>")
	)
	(segment
		(start 381.96266 -270.687038)
		(end 381.958342 -270.684498)
		(width 0.088646)
		(layer "In11.Cu")
		(net "M_H_CPU0_SA_DQ<24>")
	)
	(segment
		(start 424.257724 -292.090856)
		(end 424.092116 -291.925248)
		(width 0.18288)
		(layer "In11.Cu")
		(net "M_H_CPU0_SA_DQ<24>")
	)
	(segment
		(start 382.528064 -270.687038)
		(end 382.513332 -270.695674)
		(width 0.088646)
		(layer "In11.Cu")
		(net "M_H_CPU0_SA_DQ<24>")
	)
	(segment
		(start 406.106122 -288.522918)
		(end 405.209502 -287.626298)
		(width 0.18288)
		(layer "In11.Cu")
		(net "M_H_CPU0_SA_DQ<24>")
	)
	(segment
		(start 411.258004 -289.656266)
		(end 411.258004 -290.035742)
		(width 0.18288)
		(layer "In11.Cu")
		(net "M_H_CPU0_SA_DQ<24>")
	)
	(segment
		(start 385.347464 -270.687038)
		(end 385.332732 -270.695674)
		(width 0.088646)
		(layer "In11.Cu")
		(net "M_H_CPU0_SA_DQ<24>")
	)
	(segment
		(start 405.209502 -287.118044)
		(end 389.910828 -271.81937)
		(width 0.18288)
		(layer "In11.Cu")
		(net "M_H_CPU0_SA_DQ<24>")
	)
	(segment
		(start 415.836862 -290.345114)
		(end 413.514794 -290.345114)
		(width 0.18288)
		(layer "In11.Cu")
		(net "M_H_CPU0_SA_DQ<24>")
	)
	(segment
		(start 429.91786 -290.813744)
		(end 429.72482 -291.006784)
		(width 0.18288)
		(layer "In11.Cu")
		(net "M_H_CPU0_SA_DQ<24>")
	)
	(segment
		(start 450.822822 -288.355024)
		(end 450.637656 -288.355024)
		(width 0.18288)
		(layer "In11.Cu")
		(net "M_H_CPU0_SA_DQ<24>")
	)
	(segment
		(start 419.183058 -292.94201)
		(end 417.384738 -291.14369)
		(width 0.18288)
		(layer "In11.Cu")
		(net "M_H_CPU0_SA_DQ<24>")
	)
	(segment
		(start 379.800866 -268.585188)
		(end 379.800866 -268.569694)
		(width 0.088646)
		(layer "In11.Cu")
		(net "M_H_CPU0_SA_DQ<24>")
	)
	(segment
		(start 410.747464 -290.228782)
		(end 410.554424 -290.035742)
		(width 0.18288)
		(layer "In11.Cu")
		(net "M_H_CPU0_SA_DQ<24>")
	)
	(segment
		(start 378.768864 -267.43152)
		(end 378.754132 -267.440156)
		(width 0.088646)
		(layer "In11.Cu")
		(net "M_H_CPU0_SA_DQ<24>")
	)
	(segment
		(start 450.093588 -287.812226)
		(end 449.281042 -287.812226)
		(width 0.18288)
		(layer "In11.Cu")
		(net "M_H_CPU0_SA_DQ<24>")
	)
	(segment
		(start 410.554424 -290.035742)
		(end 410.554424 -289.656266)
		(width 0.18288)
		(layer "In11.Cu")
		(net "M_H_CPU0_SA_DQ<24>")
	)
	(segment
		(start 405.209502 -287.626298)
		(end 405.209502 -287.118044)
		(width 0.18288)
		(layer "In11.Cu")
		(net "M_H_CPU0_SA_DQ<24>")
	)
	(segment
		(start 424.092116 -291.925248)
		(end 422.939972 -291.925248)
		(width 0.18288)
		(layer "In11.Cu")
		(net "M_H_CPU0_SA_DQ<24>")
	)
	(segment
		(start 408.816556 -289.564064)
		(end 407.573226 -289.564064)
		(width 0.18288)
		(layer "In11.Cu")
		(net "M_H_CPU0_SA_DQ<24>")
	)
	(segment
		(start 411.451044 -289.463226)
		(end 411.258004 -289.656266)
		(width 0.18288)
		(layer "In11.Cu")
		(net "M_H_CPU0_SA_DQ<24>")
	)
	(segment
		(start 430.1109 -290.28009)
		(end 429.91786 -290.47313)
		(width 0.18288)
		(layer "In11.Cu")
		(net "M_H_CPU0_SA_DQ<24>")
	)
	(segment
		(start 411.064964 -290.228782)
		(end 410.747464 -290.228782)
		(width 0.18288)
		(layer "In11.Cu")
		(net "M_H_CPU0_SA_DQ<24>")
	)
	(segment
		(start 439.210704 -292.090856)
		(end 438.720484 -291.600636)
		(width 0.18288)
		(layer "In11.Cu")
		(net "M_H_CPU0_SA_DQ<24>")
	)
	(segment
		(start 413.514794 -290.345114)
		(end 412.632906 -289.463226)
		(width 0.18288)
		(layer "In11.Cu")
		(net "M_H_CPU0_SA_DQ<24>")
	)
	(segment
		(start 449.281042 -287.812226)
		(end 447.729356 -289.363912)
		(width 0.18288)
		(layer "In11.Cu")
		(net "M_H_CPU0_SA_DQ<24>")
	)
	(segment
		(start 427.310042 -291.165026)
		(end 426.720762 -291.165026)
		(width 0.18288)
		(layer "In11.Cu")
		(net "M_H_CPU0_SA_DQ<24>")
	)
	(segment
		(start 450.911214 -288.266632)
		(end 450.822822 -288.355024)
		(width 0.18288)
		(layer "In11.Cu")
		(net "M_H_CPU0_SA_DQ<24>")
	)
	(segment
		(start 426.720762 -291.165026)
		(end 425.794932 -292.090856)
		(width 0.18288)
		(layer "In11.Cu")
		(net "M_H_CPU0_SA_DQ<24>")
	)
	(segment
		(start 429.40732 -291.006784)
		(end 429.21428 -290.813744)
		(width 0.18288)
		(layer "In11.Cu")
		(net "M_H_CPU0_SA_DQ<24>")
	)
	(segment
		(start 430.905158 -290.28009)
		(end 430.1109 -290.28009)
		(width 0.18288)
		(layer "In11.Cu")
		(net "M_H_CPU0_SA_DQ<24>")
	)
	(segment
		(start 387.11759 -271.236948)
		(end 387.11759 -271.124172)
		(width 0.088646)
		(layer "In11.Cu")
		(net "M_H_CPU0_SA_DQ<24>")
	)
	(segment
		(start 387.11759 -271.124172)
		(end 386.739638 -270.74622)
		(width 0.088646)
		(layer "In11.Cu")
		(net "M_H_CPU0_SA_DQ<24>")
	)
	(segment
		(start 435.068472 -291.11321)
		(end 431.738278 -291.11321)
		(width 0.18288)
		(layer "In11.Cu")
		(net "M_H_CPU0_SA_DQ<24>")
	)
	(segment
		(start 373.130064 -267.43152)
		(end 373.115332 -267.440156)
		(width 0.088646)
		(layer "In11.Cu")
		(net "M_H_CPU0_SA_DQ<24>")
	)
	(segment
		(start 429.02124 -290.28009)
		(end 428.194978 -290.28009)
		(width 0.18288)
		(layer "In11.Cu")
		(net "M_H_CPU0_SA_DQ<24>")
	)
	(segment
		(start 442.480446 -291.04082)
		(end 442.038994 -291.04082)
		(width 0.18288)
		(layer "In11.Cu")
		(net "M_H_CPU0_SA_DQ<24>")
	)
	(segment
		(start 372.22049 -266.941808)
		(end 371.907816 -266.941808)
		(width 0.088646)
		(layer "In11.Cu")
		(net "M_H_CPU0_SA_DQ<24>")
	)
	(segment
		(start 431.738278 -291.11321)
		(end 430.905158 -290.28009)
		(width 0.18288)
		(layer "In11.Cu")
		(net "M_H_CPU0_SA_DQ<24>")
	)
	(segment
		(start 443.168532 -290.352734)
		(end 442.480446 -291.04082)
		(width 0.18288)
		(layer "In11.Cu")
		(net "M_H_CPU0_SA_DQ<24>")
	)
	(segment
		(start 421.92321 -292.94201)
		(end 419.183058 -292.94201)
		(width 0.18288)
		(layer "In11.Cu")
		(net "M_H_CPU0_SA_DQ<24>")
	)
	(segment
		(start 450.637656 -288.355024)
		(end 450.592444 -288.309812)
		(width 0.18288)
		(layer "In11.Cu")
		(net "M_H_CPU0_SA_DQ<24>")
	)
	(segment
		(start 410.554424 -289.656266)
		(end 410.361384 -289.463226)
		(width 0.18288)
		(layer "In11.Cu")
		(net "M_H_CPU0_SA_DQ<24>")
	)
	(segment
		(start 440.988958 -292.090856)
		(end 439.210704 -292.090856)
		(width 0.18288)
		(layer "In11.Cu")
		(net "M_H_CPU0_SA_DQ<24>")
	)
	(segment
		(start 406.53208 -288.522918)
		(end 406.106122 -288.522918)
		(width 0.18288)
		(layer "In11.Cu")
		(net "M_H_CPU0_SA_DQ<24>")
	)
	(segment
		(start 436.941976 -291.240972)
		(end 435.196234 -291.240972)
		(width 0.18288)
		(layer "In11.Cu")
		(net "M_H_CPU0_SA_DQ<24>")
	)
	(segment
		(start 410.361384 -289.463226)
		(end 408.917394 -289.463226)
		(width 0.18288)
		(layer "In11.Cu")
		(net "M_H_CPU0_SA_DQ<24>")
	)
	(segment
		(start 429.21428 -290.813744)
		(end 429.21428 -290.47313)
		(width 0.18288)
		(layer "In11.Cu")
		(net "M_H_CPU0_SA_DQ<24>")
	)
	(segment
		(start 435.196234 -291.240972)
		(end 435.068472 -291.11321)
		(width 0.18288)
		(layer "In11.Cu")
		(net "M_H_CPU0_SA_DQ<24>")
	)
	(segment
		(start 375.949464 -267.43152)
		(end 375.934732 -267.440156)
		(width 0.088646)
		(layer "In11.Cu")
		(net "M_H_CPU0_SA_DQ<24>")
	)
	(segment
		(start 422.939972 -291.925248)
		(end 421.92321 -292.94201)
		(width 0.18288)
		(layer "In11.Cu")
		(net "M_H_CPU0_SA_DQ<24>")
	)
	(segment
		(start 425.794932 -292.090856)
		(end 424.257724 -292.090856)
		(width 0.18288)
		(layer "In11.Cu")
		(net "M_H_CPU0_SA_DQ<24>")
	)
	(segment
		(start 375.009664 -267.43152)
		(end 374.994932 -267.440156)
		(width 0.088646)
		(layer "In11.Cu")
		(net "M_H_CPU0_SA_DQ<24>")
	)
	(arc
		(start 376.874532 -267.440156)
		(mid 376.598091 -267.507322)
		(end 376.32386 -267.43152)
		(width 0.088646)
		(layer "In11.Cu")
		(net "M_H_CPU0_SA_DQ<24>")
	)
	(arc
		(start 386.272532 -270.695674)
		(mid 385.996057 -270.762994)
		(end 385.72186 -270.687038)
		(width 0.088646)
		(layer "In11.Cu")
		(net "M_H_CPU0_SA_DQ<24>")
	)
	(arc
		(start 385.332732 -270.695674)
		(mid 385.056257 -270.762994)
		(end 384.78206 -270.687038)
		(width 0.088646)
		(layer "In11.Cu")
		(net "M_H_CPU0_SA_DQ<24>")
	)
	(arc
		(start 376.32386 -267.43152)
		(mid 376.136662 -267.381377)
		(end 375.949464 -267.43152)
		(width 0.088646)
		(layer "In11.Cu")
		(net "M_H_CPU0_SA_DQ<24>")
	)
	(arc
		(start 379.800866 -268.569694)
		(mid 379.753187 -268.386794)
		(end 379.622304 -268.250416)
		(width 0.088646)
		(layer "In11.Cu")
		(net "M_H_CPU0_SA_DQ<24>")
	)
	(arc
		(start 380.638304 -269.065248)
		(mid 380.359872 -269.135094)
		(end 380.08306 -269.059152)
		(width 0.088646)
		(layer "In11.Cu")
		(net "M_H_CPU0_SA_DQ<24>")
	)
	(arc
		(start 373.115332 -267.440156)
		(mid 372.838891 -267.507322)
		(end 372.56466 -267.43152)
		(width 0.088646)
		(layer "In11.Cu")
		(net "M_H_CPU0_SA_DQ<24>")
	)
	(arc
		(start 374.44426 -267.43152)
		(mid 374.257062 -267.381377)
		(end 374.069864 -267.43152)
		(width 0.088646)
		(layer "In11.Cu")
		(net "M_H_CPU0_SA_DQ<24>")
	)
	(arc
		(start 381.210312 -269.374874)
		(mid 381.158042 -269.192509)
		(end 381.023114 -269.059152)
		(width 0.088646)
		(layer "In11.Cu")
		(net "M_H_CPU0_SA_DQ<24>")
	)
	(arc
		(start 383.84226 -270.687038)
		(mid 383.655062 -270.636895)
		(end 383.467864 -270.687038)
		(width 0.088646)
		(layer "In11.Cu")
		(net "M_H_CPU0_SA_DQ<24>")
	)
	(arc
		(start 385.72186 -270.687038)
		(mid 385.534662 -270.636895)
		(end 385.347464 -270.687038)
		(width 0.088646)
		(layer "In11.Cu")
		(net "M_H_CPU0_SA_DQ<24>")
	)
	(arc
		(start 377.814332 -267.440156)
		(mid 377.537891 -267.507322)
		(end 377.26366 -267.43152)
		(width 0.088646)
		(layer "In11.Cu")
		(net "M_H_CPU0_SA_DQ<24>")
	)
	(arc
		(start 381.956564 -270.683482)
		(mid 381.754151 -270.477069)
		(end 381.680212 -270.19758)
		(width 0.088646)
		(layer "In11.Cu")
		(net "M_H_CPU0_SA_DQ<24>")
	)
	(arc
		(start 373.50446 -267.43152)
		(mid 373.317262 -267.381377)
		(end 373.130064 -267.43152)
		(width 0.088646)
		(layer "In11.Cu")
		(net "M_H_CPU0_SA_DQ<24>")
	)
	(arc
		(start 378.20346 -267.43152)
		(mid 378.016262 -267.381377)
		(end 377.829064 -267.43152)
		(width 0.088646)
		(layer "In11.Cu")
		(net "M_H_CPU0_SA_DQ<24>")
	)
	(arc
		(start 386.66166 -270.687038)
		(mid 386.474462 -270.636895)
		(end 386.287264 -270.687038)
		(width 0.088646)
		(layer "In11.Cu")
		(net "M_H_CPU0_SA_DQ<24>")
	)
	(arc
		(start 383.453132 -270.695674)
		(mid 383.176657 -270.762994)
		(end 382.90246 -270.687038)
		(width 0.088646)
		(layer "In11.Cu")
		(net "M_H_CPU0_SA_DQ<24>")
	)
	(arc
		(start 386.739638 -270.74622)
		(mid 386.702588 -270.714074)
		(end 386.66166 -270.687038)
		(width 0.088646)
		(layer "In11.Cu")
		(net "M_H_CPU0_SA_DQ<24>")
	)
	(arc
		(start 384.78206 -270.687038)
		(mid 384.594862 -270.636895)
		(end 384.407664 -270.687038)
		(width 0.088646)
		(layer "In11.Cu")
		(net "M_H_CPU0_SA_DQ<24>")
	)
	(arc
		(start 380.08306 -269.059152)
		(mid 379.880237 -268.858921)
		(end 379.800866 -268.585188)
		(width 0.088646)
		(layer "In11.Cu")
		(net "M_H_CPU0_SA_DQ<24>")
	)
	(arc
		(start 375.38406 -267.43152)
		(mid 375.196862 -267.381377)
		(end 375.009664 -267.43152)
		(width 0.088646)
		(layer "In11.Cu")
		(net "M_H_CPU0_SA_DQ<24>")
	)
	(arc
		(start 375.934732 -267.440156)
		(mid 375.658291 -267.507322)
		(end 375.38406 -267.43152)
		(width 0.088646)
		(layer "In11.Cu")
		(net "M_H_CPU0_SA_DQ<24>")
	)
	(arc
		(start 382.513332 -270.695674)
		(mid 382.236857 -270.762994)
		(end 381.96266 -270.687038)
		(width 0.088646)
		(layer "In11.Cu")
		(net "M_H_CPU0_SA_DQ<24>")
	)
	(arc
		(start 374.994932 -267.440156)
		(mid 374.718491 -267.507322)
		(end 374.44426 -267.43152)
		(width 0.088646)
		(layer "In11.Cu")
		(net "M_H_CPU0_SA_DQ<24>")
	)
	(arc
		(start 379.601222 -268.238224)
		(mid 379.402994 -268.032376)
		(end 379.330712 -267.755878)
		(width 0.088646)
		(layer "In11.Cu")
		(net "M_H_CPU0_SA_DQ<24>")
	)
	(arc
		(start 379.14326 -267.43152)
		(mid 378.956062 -267.381377)
		(end 378.768864 -267.43152)
		(width 0.088646)
		(layer "In11.Cu")
		(net "M_H_CPU0_SA_DQ<24>")
	)
	(arc
		(start 381.023114 -269.059152)
		(mid 380.835916 -269.009009)
		(end 380.648718 -269.059152)
		(width 0.088646)
		(layer "In11.Cu")
		(net "M_H_CPU0_SA_DQ<24>")
	)
	(arc
		(start 374.069864 -267.43152)
		(mid 373.787162 -267.507262)
		(end 373.50446 -267.43152)
		(width 0.088646)
		(layer "In11.Cu")
		(net "M_H_CPU0_SA_DQ<24>")
	)
	(arc
		(start 377.26366 -267.43152)
		(mid 377.076462 -267.381377)
		(end 376.889264 -267.43152)
		(width 0.088646)
		(layer "In11.Cu")
		(net "M_H_CPU0_SA_DQ<24>")
	)
	(arc
		(start 372.56466 -267.43152)
		(mid 372.37492 -267.252357)
		(end 372.285768 -267.007086)
		(width 0.088646)
		(layer "In11.Cu")
		(net "M_H_CPU0_SA_DQ<24>")
	)
	(arc
		(start 378.754132 -267.440156)
		(mid 378.477691 -267.507322)
		(end 378.20346 -267.43152)
		(width 0.088646)
		(layer "In11.Cu")
		(net "M_H_CPU0_SA_DQ<24>")
	)
	(arc
		(start 384.392932 -270.695674)
		(mid 384.116457 -270.762994)
		(end 383.84226 -270.687038)
		(width 0.088646)
		(layer "In11.Cu")
		(net "M_H_CPU0_SA_DQ<24>")
	)
	(arc
		(start 379.330712 -267.755878)
		(mid 379.283033 -267.572978)
		(end 379.15215 -267.4366)
		(width 0.088646)
		(layer "In11.Cu")
		(net "M_H_CPU0_SA_DQ<24>")
	)
	(arc
		(start 382.90246 -270.687038)
		(mid 382.715262 -270.636895)
		(end 382.528064 -270.687038)
		(width 0.088646)
		(layer "In11.Cu")
		(net "M_H_CPU0_SA_DQ<24>")
	)
	(arc
		(start 381.680212 -270.19758)
		(mid 381.632533 -270.01468)
		(end 381.50165 -269.878302)
		(width 0.088646)
		(layer "In11.Cu")
		(net "M_H_CPU0_SA_DQ<24>")
	)
	(arc
		(start 381.49276 -269.873222)
		(mid 381.290474 -269.674241)
		(end 381.210312 -269.402052)
		(width 0.088646)
		(layer "In11.Cu")
		(net "M_H_CPU0_SA_DQ<24>")
	)
	(segment
		(start 458.543152 -289.548824)
		(end 458.550264 -289.541712)
		(width 0.1016)
		(layer "F.Cu")
		(net "M_H_CPU0_SA_DQ<23>")
	)
	(segment
		(start 372.847362 -268.56944)
		(end 372.847616 -268.569694)
		(width 0.20066)
		(layer "F.Cu")
		(net "M_H_CPU0_SA_DQ<23>")
	)
	(segment
		(start 460.570326 -289.553904)
		(end 461.251554 -289.553904)
		(width 0.20066)
		(layer "F.Cu")
		(net "M_H_CPU0_SA_DQ<23>")
	)
	(segment
		(start 456.116182 -289.11677)
		(end 457.814426 -289.11677)
		(width 0.20066)
		(layer "F.Cu")
		(net "M_H_CPU0_SA_DQ<23>")
	)
	(segment
		(start 458.538326 -289.548824)
		(end 458.543152 -289.548824)
		(width 0.101854)
		(layer "F.Cu")
		(net "M_H_CPU0_SA_DQ<23>")
	)
	(segment
		(start 460.558134 -289.541712)
		(end 460.570326 -289.553904)
		(width 0.1016)
		(layer "F.Cu")
		(net "M_H_CPU0_SA_DQ<23>")
	)
	(segment
		(start 372.847362 -268.033754)
		(end 372.847362 -268.56944)
		(width 0.20066)
		(layer "F.Cu")
		(net "M_H_CPU0_SA_DQ<23>")
	)
	(segment
		(start 461.251554 -289.553904)
		(end 461.455516 -289.349942)
		(width 0.20066)
		(layer "F.Cu")
		(net "M_H_CPU0_SA_DQ<23>")
	)
	(segment
		(start 461.689704 -288.864802)
		(end 462.073752 -288.864802)
		(width 0.20066)
		(layer "F.Cu")
		(net "M_H_CPU0_SA_DQ<23>")
	)
	(segment
		(start 461.455516 -289.09899)
		(end 461.689704 -288.864802)
		(width 0.20066)
		(layer "F.Cu")
		(net "M_H_CPU0_SA_DQ<23>")
	)
	(segment
		(start 458.550264 -289.541712)
		(end 460.558134 -289.541712)
		(width 0.1016)
		(layer "F.Cu")
		(net "M_H_CPU0_SA_DQ<23>")
	)
	(segment
		(start 458.24648 -289.548824)
		(end 458.538326 -289.548824)
		(width 0.20066)
		(layer "F.Cu")
		(net "M_H_CPU0_SA_DQ<23>")
	)
	(segment
		(start 462.073752 -288.864802)
		(end 462.32572 -289.11677)
		(width 0.20066)
		(layer "F.Cu")
		(net "M_H_CPU0_SA_DQ<23>")
	)
	(segment
		(start 462.32572 -289.11677)
		(end 463.659982 -289.11677)
		(width 0.20066)
		(layer "F.Cu")
		(net "M_H_CPU0_SA_DQ<23>")
	)
	(segment
		(start 455.011282 -289.11677)
		(end 456.116182 -289.11677)
		(width 0.20066)
		(layer "F.Cu")
		(net "M_H_CPU0_SA_DQ<23>")
	)
	(segment
		(start 457.814426 -289.11677)
		(end 458.24648 -289.548824)
		(width 0.20066)
		(layer "F.Cu")
		(net "M_H_CPU0_SA_DQ<23>")
	)
	(segment
		(start 461.455516 -289.349942)
		(end 461.455516 -289.09899)
		(width 0.20066)
		(layer "F.Cu")
		(net "M_H_CPU0_SA_DQ<23>")
	)
	(segment
		(start 410.206952 -290.82619)
		(end 410.013912 -290.63315)
		(width 0.18288)
		(layer "In11.Cu")
		(net "M_H_CPU0_SA_DQ<23>")
	)
	(segment
		(start 450.136514 -289.016186)
		(end 449.261738 -289.016186)
		(width 0.18288)
		(layer "In11.Cu")
		(net "M_H_CPU0_SA_DQ<23>")
	)
	(segment
		(start 431.917094 -293.070026)
		(end 425.930822 -293.070026)
		(width 0.18288)
		(layer "In11.Cu")
		(net "M_H_CPU0_SA_DQ<23>")
	)
	(segment
		(start 413.647636 -291.624258)
		(end 413.454596 -291.431218)
		(width 0.18288)
		(layer "In11.Cu")
		(net "M_H_CPU0_SA_DQ<23>")
	)
	(segment
		(start 383.467864 -271.335754)
		(end 383.453132 -271.327118)
		(width 0.088646)
		(layer "In11.Cu")
		(net "M_H_CPU0_SA_DQ<23>")
	)
	(segment
		(start 446.102994 -291.368226)
		(end 443.306454 -291.368226)
		(width 0.18288)
		(layer "In11.Cu")
		(net "M_H_CPU0_SA_DQ<23>")
	)
	(segment
		(start 436.267098 -292.095174)
		(end 432.891946 -292.095174)
		(width 0.18288)
		(layer "In11.Cu")
		(net "M_H_CPU0_SA_DQ<23>")
	)
	(segment
		(start 450.662548 -289.54222)
		(end 450.136514 -289.016186)
		(width 0.18288)
		(layer "In11.Cu")
		(net "M_H_CPU0_SA_DQ<23>")
	)
	(segment
		(start 380.931166 -270.206216)
		(end 380.931166 -270.179038)
		(width 0.088646)
		(layer "In11.Cu")
		(net "M_H_CPU0_SA_DQ<23>")
	)
	(segment
		(start 415.77133 -293.06901)
		(end 415.350198 -293.06901)
		(width 0.18288)
		(layer "In11.Cu")
		(net "M_H_CPU0_SA_DQ<23>")
	)
	(segment
		(start 407.256742 -290.382706)
		(end 406.489154 -289.615118)
		(width 0.18288)
		(layer "In11.Cu")
		(net "M_H_CPU0_SA_DQ<23>")
	)
	(segment
		(start 421.527986 -294.642286)
		(end 420.235634 -294.642286)
		(width 0.18288)
		(layer "In11.Cu")
		(net "M_H_CPU0_SA_DQ<23>")
	)
	(segment
		(start 420.235634 -294.642286)
		(end 420.105586 -294.772334)
		(width 0.18288)
		(layer "In11.Cu")
		(net "M_H_CPU0_SA_DQ<23>")
	)
	(segment
		(start 382.528064 -271.335754)
		(end 382.513332 -271.327118)
		(width 0.088646)
		(layer "In11.Cu")
		(net "M_H_CPU0_SA_DQ<23>")
	)
	(segment
		(start 415.350198 -293.06901)
		(end 414.371282 -292.090094)
		(width 0.18288)
		(layer "In11.Cu")
		(net "M_H_CPU0_SA_DQ<23>")
	)
	(segment
		(start 409.503372 -291.022786)
		(end 409.310332 -291.215826)
		(width 0.18288)
		(layer "In11.Cu")
		(net "M_H_CPU0_SA_DQ<23>")
	)
	(segment
		(start 432.891946 -292.095174)
		(end 431.917094 -293.070026)
		(width 0.18288)
		(layer "In11.Cu")
		(net "M_H_CPU0_SA_DQ<23>")
	)
	(segment
		(start 410.399992 -291.215826)
		(end 410.206952 -291.022786)
		(width 0.18288)
		(layer "In11.Cu")
		(net "M_H_CPU0_SA_DQ<23>")
	)
	(segment
		(start 409.503372 -290.82619)
		(end 409.503372 -291.022786)
		(width 0.18288)
		(layer "In11.Cu")
		(net "M_H_CPU0_SA_DQ<23>")
	)
	(segment
		(start 419.259766 -294.772334)
		(end 417.532566 -293.046658)
		(width 0.18288)
		(layer "In11.Cu")
		(net "M_H_CPU0_SA_DQ<23>")
	)
	(segment
		(start 376.889264 -268.080236)
		(end 376.874532 -268.0716)
		(width 0.088646)
		(layer "In11.Cu")
		(net "M_H_CPU0_SA_DQ<23>")
	)
	(segment
		(start 410.013912 -290.63315)
		(end 409.696412 -290.63315)
		(width 0.18288)
		(layer "In11.Cu")
		(net "M_H_CPU0_SA_DQ<23>")
	)
	(segment
		(start 417.144454 -292.579552)
		(end 416.951414 -292.386512)
		(width 0.18288)
		(layer "In11.Cu")
		(net "M_H_CPU0_SA_DQ<23>")
	)
	(segment
		(start 387.265672 -272.829782)
		(end 387.031738 -272.829782)
		(width 0.088646)
		(layer "In11.Cu")
		(net "M_H_CPU0_SA_DQ<23>")
	)
	(segment
		(start 405.396954 -289.615118)
		(end 404.919942 -289.138106)
		(width 0.18288)
		(layer "In11.Cu")
		(net "M_H_CPU0_SA_DQ<23>")
	)
	(segment
		(start 413.137096 -291.431218)
		(end 412.944056 -291.624258)
		(width 0.18288)
		(layer "In11.Cu")
		(net "M_H_CPU0_SA_DQ<23>")
	)
	(segment
		(start 385.347464 -271.335754)
		(end 385.332732 -271.327118)
		(width 0.088646)
		(layer "In11.Cu")
		(net "M_H_CPU0_SA_DQ<23>")
	)
	(segment
		(start 413.647636 -291.897054)
		(end 413.647636 -291.624258)
		(width 0.18288)
		(layer "In11.Cu")
		(net "M_H_CPU0_SA_DQ<23>")
	)
	(segment
		(start 437.25465 -293.082726)
		(end 436.267098 -292.095174)
		(width 0.18288)
		(layer "In11.Cu")
		(net "M_H_CPU0_SA_DQ<23>")
	)
	(segment
		(start 379.239018 -268.894052)
		(end 379.230128 -268.888972)
		(width 0.088646)
		(layer "In11.Cu")
		(net "M_H_CPU0_SA_DQ<23>")
	)
	(segment
		(start 413.840676 -292.090094)
		(end 413.647636 -291.897054)
		(width 0.18288)
		(layer "In11.Cu")
		(net "M_H_CPU0_SA_DQ<23>")
	)
	(segment
		(start 404.919942 -289.138106)
		(end 404.919942 -288.521902)
		(width 0.18288)
		(layer "In11.Cu")
		(net "M_H_CPU0_SA_DQ<23>")
	)
	(segment
		(start 406.489154 -289.615118)
		(end 405.396954 -289.615118)
		(width 0.18288)
		(layer "In11.Cu")
		(net "M_H_CPU0_SA_DQ<23>")
	)
	(segment
		(start 412.751016 -292.090094)
		(end 412.551626 -292.090094)
		(width 0.18288)
		(layer "In11.Cu")
		(net "M_H_CPU0_SA_DQ<23>")
	)
	(segment
		(start 438.762648 -293.082726)
		(end 437.25465 -293.082726)
		(width 0.18288)
		(layer "In11.Cu")
		(net "M_H_CPU0_SA_DQ<23>")
	)
	(segment
		(start 417.532566 -293.046658)
		(end 417.337494 -293.046658)
		(width 0.18288)
		(layer "In11.Cu")
		(net "M_H_CPU0_SA_DQ<23>")
	)
	(segment
		(start 446.991994 -290.479226)
		(end 446.102994 -291.368226)
		(width 0.18288)
		(layer "In11.Cu")
		(net "M_H_CPU0_SA_DQ<23>")
	)
	(segment
		(start 373.50446 -268.080236)
		(end 373.426228 -268.125448)
		(width 0.088646)
		(layer "In11.Cu")
		(net "M_H_CPU0_SA_DQ<23>")
	)
	(segment
		(start 411.720284 -292.093396)
		(end 410.842714 -291.215826)
		(width 0.18288)
		(layer "In11.Cu")
		(net "M_H_CPU0_SA_DQ<23>")
	)
	(segment
		(start 414.371282 -292.090094)
		(end 413.840676 -292.090094)
		(width 0.18288)
		(layer "In11.Cu")
		(net "M_H_CPU0_SA_DQ<23>")
	)
	(segment
		(start 455.011282 -289.11677)
		(end 454.985882 -289.11677)
		(width 0.18288)
		(layer "In11.Cu")
		(net "M_H_CPU0_SA_DQ<23>")
	)
	(segment
		(start 375.949464 -268.080236)
		(end 375.934732 -268.0716)
		(width 0.088646)
		(layer "In11.Cu")
		(net "M_H_CPU0_SA_DQ<23>")
	)
	(segment
		(start 416.951414 -292.386512)
		(end 416.633914 -292.386512)
		(width 0.18288)
		(layer "In11.Cu")
		(net "M_H_CPU0_SA_DQ<23>")
	)
	(segment
		(start 410.206952 -291.022786)
		(end 410.206952 -290.82619)
		(width 0.18288)
		(layer "In11.Cu")
		(net "M_H_CPU0_SA_DQ<23>")
	)
	(segment
		(start 409.310332 -291.215826)
		(end 408.93873 -291.215826)
		(width 0.18288)
		(layer "In11.Cu")
		(net "M_H_CPU0_SA_DQ<23>")
	)
	(segment
		(start 386.55371 -272.351754)
		(end 386.55371 -271.59331)
		(width 0.088646)
		(layer "In11.Cu")
		(net "M_H_CPU0_SA_DQ<23>")
	)
	(segment
		(start 408.10561 -290.382706)
		(end 407.256742 -290.382706)
		(width 0.18288)
		(layer "In11.Cu")
		(net "M_H_CPU0_SA_DQ<23>")
	)
	(segment
		(start 379.708664 -269.707868)
		(end 379.699774 -269.702788)
		(width 0.088646)
		(layer "In11.Cu")
		(net "M_H_CPU0_SA_DQ<23>")
	)
	(segment
		(start 386.308346 -271.347946)
		(end 386.272532 -271.327118)
		(width 0.088646)
		(layer "In11.Cu")
		(net "M_H_CPU0_SA_DQ<23>")
	)
	(segment
		(start 381.400812 -271.011396)
		(end 381.400812 -271.00149)
		(width 0.088646)
		(layer "In11.Cu")
		(net "M_H_CPU0_SA_DQ<23>")
	)
	(segment
		(start 447.798698 -290.479226)
		(end 446.991994 -290.479226)
		(width 0.18288)
		(layer "In11.Cu")
		(net "M_H_CPU0_SA_DQ<23>")
	)
	(segment
		(start 375.009664 -268.080236)
		(end 374.994932 -268.0716)
		(width 0.088646)
		(layer "In11.Cu")
		(net "M_H_CPU0_SA_DQ<23>")
	)
	(segment
		(start 413.454596 -291.431218)
		(end 413.137096 -291.431218)
		(width 0.18288)
		(layer "In11.Cu")
		(net "M_H_CPU0_SA_DQ<23>")
	)
	(segment
		(start 439.472324 -293.792402)
		(end 438.762648 -293.082726)
		(width 0.18288)
		(layer "In11.Cu")
		(net "M_H_CPU0_SA_DQ<23>")
	)
	(segment
		(start 380.648718 -269.707868)
		(end 380.638304 -269.701772)
		(width 0.088646)
		(layer "In11.Cu")
		(net "M_H_CPU0_SA_DQ<23>")
	)
	(segment
		(start 454.307956 -289.793426)
		(end 452.732648 -289.793426)
		(width 0.18288)
		(layer "In11.Cu")
		(net "M_H_CPU0_SA_DQ<23>")
	)
	(segment
		(start 452.481442 -289.54222)
		(end 450.662548 -289.54222)
		(width 0.18288)
		(layer "In11.Cu")
		(net "M_H_CPU0_SA_DQ<23>")
	)
	(segment
		(start 412.548324 -292.093396)
		(end 411.720284 -292.093396)
		(width 0.18288)
		(layer "In11.Cu")
		(net "M_H_CPU0_SA_DQ<23>")
	)
	(segment
		(start 422.37787 -293.792402)
		(end 421.527986 -294.642286)
		(width 0.18288)
		(layer "In11.Cu")
		(net "M_H_CPU0_SA_DQ<23>")
	)
	(segment
		(start 387.031738 -272.829782)
		(end 386.55371 -272.351754)
		(width 0.088646)
		(layer "In11.Cu")
		(net "M_H_CPU0_SA_DQ<23>")
	)
	(segment
		(start 377.829064 -268.080236)
		(end 377.82881 -268.080236)
		(width 0.088646)
		(layer "In11.Cu")
		(net "M_H_CPU0_SA_DQ<23>")
	)
	(segment
		(start 449.261738 -289.016186)
		(end 447.798698 -290.479226)
		(width 0.18288)
		(layer "In11.Cu")
		(net "M_H_CPU0_SA_DQ<23>")
	)
	(segment
		(start 416.247834 -293.046658)
		(end 415.793682 -293.046658)
		(width 0.18288)
		(layer "In11.Cu")
		(net "M_H_CPU0_SA_DQ<23>")
	)
	(segment
		(start 409.696412 -290.63315)
		(end 409.503372 -290.82619)
		(width 0.18288)
		(layer "In11.Cu")
		(net "M_H_CPU0_SA_DQ<23>")
	)
	(segment
		(start 381.588264 -271.335754)
		(end 381.579374 -271.330674)
		(width 0.088646)
		(layer "In11.Cu")
		(net "M_H_CPU0_SA_DQ<23>")
	)
	(segment
		(start 416.440874 -292.853618)
		(end 416.247834 -293.046658)
		(width 0.18288)
		(layer "In11.Cu")
		(net "M_H_CPU0_SA_DQ<23>")
	)
	(segment
		(start 374.069864 -268.080236)
		(end 374.055132 -268.0716)
		(width 0.088646)
		(layer "In11.Cu")
		(net "M_H_CPU0_SA_DQ<23>")
	)
	(segment
		(start 410.842714 -291.215826)
		(end 410.399992 -291.215826)
		(width 0.18288)
		(layer "In11.Cu")
		(net "M_H_CPU0_SA_DQ<23>")
	)
	(segment
		(start 416.633914 -292.386512)
		(end 416.440874 -292.579552)
		(width 0.18288)
		(layer "In11.Cu")
		(net "M_H_CPU0_SA_DQ<23>")
	)
	(segment
		(start 412.944056 -291.897054)
		(end 412.751016 -292.090094)
		(width 0.18288)
		(layer "In11.Cu")
		(net "M_H_CPU0_SA_DQ<23>")
	)
	(segment
		(start 386.55371 -271.59331)
		(end 386.308346 -271.347946)
		(width 0.088646)
		(layer "In11.Cu")
		(net "M_H_CPU0_SA_DQ<23>")
	)
	(segment
		(start 452.732648 -289.793426)
		(end 452.481442 -289.54222)
		(width 0.18288)
		(layer "In11.Cu")
		(net "M_H_CPU0_SA_DQ<23>")
	)
	(segment
		(start 417.144454 -292.853618)
		(end 417.144454 -292.579552)
		(width 0.18288)
		(layer "In11.Cu")
		(net "M_H_CPU0_SA_DQ<23>")
	)
	(segment
		(start 408.93873 -291.215826)
		(end 408.10561 -290.382706)
		(width 0.18288)
		(layer "In11.Cu")
		(net "M_H_CPU0_SA_DQ<23>")
	)
	(segment
		(start 412.944056 -291.624258)
		(end 412.944056 -291.897054)
		(width 0.18288)
		(layer "In11.Cu")
		(net "M_H_CPU0_SA_DQ<23>")
	)
	(segment
		(start 378.768864 -268.080236)
		(end 378.754132 -268.0716)
		(width 0.088646)
		(layer "In11.Cu")
		(net "M_H_CPU0_SA_DQ<23>")
	)
	(segment
		(start 454.985882 -289.11677)
		(end 454.307956 -289.793426)
		(width 0.18288)
		(layer "In11.Cu")
		(net "M_H_CPU0_SA_DQ<23>")
	)
	(segment
		(start 378.77496 -268.083792)
		(end 378.768864 -268.080236)
		(width 0.088646)
		(layer "In11.Cu")
		(net "M_H_CPU0_SA_DQ<23>")
	)
	(segment
		(start 420.105586 -294.772334)
		(end 419.259766 -294.772334)
		(width 0.18288)
		(layer "In11.Cu")
		(net "M_H_CPU0_SA_DQ<23>")
	)
	(segment
		(start 412.551626 -292.090094)
		(end 412.548324 -292.093396)
		(width 0.18288)
		(layer "In11.Cu")
		(net "M_H_CPU0_SA_DQ<23>")
	)
	(segment
		(start 389.227822 -272.829782)
		(end 387.265672 -272.829782)
		(width 0.18288)
		(layer "In11.Cu")
		(net "M_H_CPU0_SA_DQ<23>")
	)
	(segment
		(start 425.208446 -293.792402)
		(end 422.37787 -293.792402)
		(width 0.18288)
		(layer "In11.Cu")
		(net "M_H_CPU0_SA_DQ<23>")
	)
	(segment
		(start 379.521212 -269.38351)
		(end 379.521212 -269.368016)
		(width 0.088646)
		(layer "In11.Cu")
		(net "M_H_CPU0_SA_DQ<23>")
	)
	(segment
		(start 425.930822 -293.070026)
		(end 425.208446 -293.792402)
		(width 0.18288)
		(layer "In11.Cu")
		(net "M_H_CPU0_SA_DQ<23>")
	)
	(segment
		(start 417.337494 -293.046658)
		(end 417.144454 -292.853618)
		(width 0.18288)
		(layer "In11.Cu")
		(net "M_H_CPU0_SA_DQ<23>")
	)
	(segment
		(start 415.793682 -293.046658)
		(end 415.77133 -293.06901)
		(width 0.18288)
		(layer "In11.Cu")
		(net "M_H_CPU0_SA_DQ<23>")
	)
	(segment
		(start 440.882278 -293.792402)
		(end 439.472324 -293.792402)
		(width 0.18288)
		(layer "In11.Cu")
		(net "M_H_CPU0_SA_DQ<23>")
	)
	(segment
		(start 404.919942 -288.521902)
		(end 389.227822 -272.829782)
		(width 0.18288)
		(layer "In11.Cu")
		(net "M_H_CPU0_SA_DQ<23>")
	)
	(segment
		(start 384.407664 -271.335754)
		(end 384.392932 -271.327118)
		(width 0.088646)
		(layer "In11.Cu")
		(net "M_H_CPU0_SA_DQ<23>")
	)
	(segment
		(start 443.306454 -291.368226)
		(end 440.882278 -293.792402)
		(width 0.18288)
		(layer "In11.Cu")
		(net "M_H_CPU0_SA_DQ<23>")
	)
	(segment
		(start 416.440874 -292.579552)
		(end 416.440874 -292.853618)
		(width 0.18288)
		(layer "In11.Cu")
		(net "M_H_CPU0_SA_DQ<23>")
	)
	(arc
		(start 377.26366 -268.080236)
		(mid 377.076462 -268.130379)
		(end 376.889264 -268.080236)
		(width 0.088646)
		(layer "In11.Cu")
		(net "M_H_CPU0_SA_DQ<23>")
	)
	(arc
		(start 379.699774 -269.702788)
		(mid 379.56886 -269.566428)
		(end 379.521212 -269.38351)
		(width 0.088646)
		(layer "In11.Cu")
		(net "M_H_CPU0_SA_DQ<23>")
	)
	(arc
		(start 375.38406 -268.080236)
		(mid 375.196862 -268.130379)
		(end 375.009664 -268.080236)
		(width 0.088646)
		(layer "In11.Cu")
		(net "M_H_CPU0_SA_DQ<23>")
	)
	(arc
		(start 374.44426 -268.080236)
		(mid 374.257062 -268.130379)
		(end 374.069864 -268.080236)
		(width 0.088646)
		(layer "In11.Cu")
		(net "M_H_CPU0_SA_DQ<23>")
	)
	(arc
		(start 376.32386 -268.080236)
		(mid 376.136662 -268.130379)
		(end 375.949464 -268.080236)
		(width 0.088646)
		(layer "In11.Cu")
		(net "M_H_CPU0_SA_DQ<23>")
	)
	(arc
		(start 384.78206 -271.335754)
		(mid 384.594862 -271.385897)
		(end 384.407664 -271.335754)
		(width 0.088646)
		(layer "In11.Cu")
		(net "M_H_CPU0_SA_DQ<23>")
	)
	(arc
		(start 381.96266 -271.335754)
		(mid 381.775462 -271.385897)
		(end 381.588264 -271.335754)
		(width 0.088646)
		(layer "In11.Cu")
		(net "M_H_CPU0_SA_DQ<23>")
	)
	(arc
		(start 376.874532 -268.0716)
		(mid 376.598057 -268.00428)
		(end 376.32386 -268.080236)
		(width 0.088646)
		(layer "In11.Cu")
		(net "M_H_CPU0_SA_DQ<23>")
	)
	(arc
		(start 384.392932 -271.327118)
		(mid 384.116457 -271.259798)
		(end 383.84226 -271.335754)
		(width 0.088646)
		(layer "In11.Cu")
		(net "M_H_CPU0_SA_DQ<23>")
	)
	(arc
		(start 381.579374 -271.330674)
		(mid 381.44846 -271.194314)
		(end 381.400812 -271.011396)
		(width 0.088646)
		(layer "In11.Cu")
		(net "M_H_CPU0_SA_DQ<23>")
	)
	(arc
		(start 380.931166 -270.179038)
		(mid 380.851004 -269.906849)
		(end 380.648718 -269.707868)
		(width 0.088646)
		(layer "In11.Cu")
		(net "M_H_CPU0_SA_DQ<23>")
	)
	(arc
		(start 378.20346 -268.080236)
		(mid 378.016262 -268.130379)
		(end 377.829064 -268.080236)
		(width 0.088646)
		(layer "In11.Cu")
		(net "M_H_CPU0_SA_DQ<23>")
	)
	(arc
		(start 385.72186 -271.335754)
		(mid 385.534662 -271.385897)
		(end 385.347464 -271.335754)
		(width 0.088646)
		(layer "In11.Cu")
		(net "M_H_CPU0_SA_DQ<23>")
	)
	(arc
		(start 375.934732 -268.0716)
		(mid 375.658257 -268.00428)
		(end 375.38406 -268.080236)
		(width 0.088646)
		(layer "In11.Cu")
		(net "M_H_CPU0_SA_DQ<23>")
	)
	(arc
		(start 381.118364 -270.521938)
		(mid 380.983431 -270.388584)
		(end 380.931166 -270.206216)
		(width 0.088646)
		(layer "In11.Cu")
		(net "M_H_CPU0_SA_DQ<23>")
	)
	(arc
		(start 385.332732 -271.327118)
		(mid 385.056257 -271.259798)
		(end 384.78206 -271.335754)
		(width 0.088646)
		(layer "In11.Cu")
		(net "M_H_CPU0_SA_DQ<23>")
	)
	(arc
		(start 381.400812 -271.00149)
		(mid 381.322701 -270.724541)
		(end 381.118364 -270.521938)
		(width 0.088646)
		(layer "In11.Cu")
		(net "M_H_CPU0_SA_DQ<23>")
	)
	(arc
		(start 374.055132 -268.0716)
		(mid 373.778657 -268.00428)
		(end 373.50446 -268.080236)
		(width 0.088646)
		(layer "In11.Cu")
		(net "M_H_CPU0_SA_DQ<23>")
	)
	(arc
		(start 380.638304 -269.701772)
		(mid 380.359872 -269.631958)
		(end 380.08306 -269.707868)
		(width 0.088646)
		(layer "In11.Cu")
		(net "M_H_CPU0_SA_DQ<23>")
	)
	(arc
		(start 380.08306 -269.707868)
		(mid 379.895862 -269.758011)
		(end 379.708664 -269.707868)
		(width 0.088646)
		(layer "In11.Cu")
		(net "M_H_CPU0_SA_DQ<23>")
	)
	(arc
		(start 377.82881 -268.080236)
		(mid 377.546252 -268.004587)
		(end 377.26366 -268.080236)
		(width 0.088646)
		(layer "In11.Cu")
		(net "M_H_CPU0_SA_DQ<23>")
	)
	(arc
		(start 379.230128 -268.888972)
		(mid 379.099214 -268.752612)
		(end 379.051566 -268.569694)
		(width 0.088646)
		(layer "In11.Cu")
		(net "M_H_CPU0_SA_DQ<23>")
	)
	(arc
		(start 373.426228 -268.125448)
		(mid 373.122388 -268.328642)
		(end 372.847616 -268.569694)
		(width 0.088646)
		(layer "In11.Cu")
		(net "M_H_CPU0_SA_DQ<23>")
	)
	(arc
		(start 386.272532 -271.327118)
		(mid 385.996057 -271.259798)
		(end 385.72186 -271.335754)
		(width 0.088646)
		(layer "In11.Cu")
		(net "M_H_CPU0_SA_DQ<23>")
	)
	(arc
		(start 379.521212 -269.368016)
		(mid 379.441842 -269.094282)
		(end 379.239018 -268.894052)
		(width 0.088646)
		(layer "In11.Cu")
		(net "M_H_CPU0_SA_DQ<23>")
	)
	(arc
		(start 382.513332 -271.327118)
		(mid 382.236857 -271.259798)
		(end 381.96266 -271.335754)
		(width 0.088646)
		(layer "In11.Cu")
		(net "M_H_CPU0_SA_DQ<23>")
	)
	(arc
		(start 374.994932 -268.0716)
		(mid 374.718457 -268.00428)
		(end 374.44426 -268.080236)
		(width 0.088646)
		(layer "In11.Cu")
		(net "M_H_CPU0_SA_DQ<23>")
	)
	(arc
		(start 382.90246 -271.335754)
		(mid 382.715262 -271.385897)
		(end 382.528064 -271.335754)
		(width 0.088646)
		(layer "In11.Cu")
		(net "M_H_CPU0_SA_DQ<23>")
	)
	(arc
		(start 383.453132 -271.327118)
		(mid 383.176657 -271.259798)
		(end 382.90246 -271.335754)
		(width 0.088646)
		(layer "In11.Cu")
		(net "M_H_CPU0_SA_DQ<23>")
	)
	(arc
		(start 378.754132 -268.0716)
		(mid 378.477657 -268.00428)
		(end 378.20346 -268.080236)
		(width 0.088646)
		(layer "In11.Cu")
		(net "M_H_CPU0_SA_DQ<23>")
	)
	(arc
		(start 379.051566 -268.569694)
		(mid 378.977575 -268.290128)
		(end 378.77496 -268.083792)
		(width 0.088646)
		(layer "In11.Cu")
		(net "M_H_CPU0_SA_DQ<23>")
	)
	(arc
		(start 383.84226 -271.335754)
		(mid 383.655062 -271.385897)
		(end 383.467864 -271.335754)
		(width 0.088646)
		(layer "In11.Cu")
		(net "M_H_CPU0_SA_DQ<23>")
	)
	(segment
		(start 456.116182 -290.816792)
		(end 457.814426 -290.816792)
		(width 0.20066)
		(layer "F.Cu")
		(net "M_H_CPU0_SA_DQ<22>")
	)
	(segment
		(start 455.011282 -290.816538)
		(end 455.011536 -290.816792)
		(width 0.20066)
		(layer "F.Cu")
		(net "M_H_CPU0_SA_DQ<22>")
	)
	(segment
		(start 373.317516 -268.84757)
		(end 373.317516 -269.383256)
		(width 0.20066)
		(layer "F.Cu")
		(net "M_H_CPU0_SA_DQ<22>")
	)
	(segment
		(start 460.558134 -291.241734)
		(end 460.570326 -291.253926)
		(width 0.1016)
		(layer "F.Cu")
		(net "M_H_CPU0_SA_DQ<22>")
	)
	(segment
		(start 457.814426 -290.816792)
		(end 458.24648 -291.248846)
		(width 0.20066)
		(layer "F.Cu")
		(net "M_H_CPU0_SA_DQ<22>")
	)
	(segment
		(start 461.251554 -291.253926)
		(end 461.455516 -291.049964)
		(width 0.20066)
		(layer "F.Cu")
		(net "M_H_CPU0_SA_DQ<22>")
	)
	(segment
		(start 458.24648 -291.248846)
		(end 458.538326 -291.248846)
		(width 0.20066)
		(layer "F.Cu")
		(net "M_H_CPU0_SA_DQ<22>")
	)
	(segment
		(start 373.317516 -269.383256)
		(end 373.317262 -269.38351)
		(width 0.20066)
		(layer "F.Cu")
		(net "M_H_CPU0_SA_DQ<22>")
	)
	(segment
		(start 461.455516 -291.049964)
		(end 461.455516 -290.799012)
		(width 0.20066)
		(layer "F.Cu")
		(net "M_H_CPU0_SA_DQ<22>")
	)
	(segment
		(start 462.32572 -290.816792)
		(end 463.659982 -290.816792)
		(width 0.20066)
		(layer "F.Cu")
		(net "M_H_CPU0_SA_DQ<22>")
	)
	(segment
		(start 461.689704 -290.564824)
		(end 462.073752 -290.564824)
		(width 0.20066)
		(layer "F.Cu")
		(net "M_H_CPU0_SA_DQ<22>")
	)
	(segment
		(start 458.550264 -291.241734)
		(end 460.558134 -291.241734)
		(width 0.1016)
		(layer "F.Cu")
		(net "M_H_CPU0_SA_DQ<22>")
	)
	(segment
		(start 461.455516 -290.799012)
		(end 461.689704 -290.564824)
		(width 0.20066)
		(layer "F.Cu")
		(net "M_H_CPU0_SA_DQ<22>")
	)
	(segment
		(start 455.011536 -290.816792)
		(end 456.116182 -290.816792)
		(width 0.20066)
		(layer "F.Cu")
		(net "M_H_CPU0_SA_DQ<22>")
	)
	(segment
		(start 462.073752 -290.564824)
		(end 462.32572 -290.816792)
		(width 0.20066)
		(layer "F.Cu")
		(net "M_H_CPU0_SA_DQ<22>")
	)
	(segment
		(start 458.538326 -291.248846)
		(end 458.543152 -291.248846)
		(width 0.101854)
		(layer "F.Cu")
		(net "M_H_CPU0_SA_DQ<22>")
	)
	(segment
		(start 460.570326 -291.253926)
		(end 461.251554 -291.253926)
		(width 0.20066)
		(layer "F.Cu")
		(net "M_H_CPU0_SA_DQ<22>")
	)
	(segment
		(start 458.543152 -291.248846)
		(end 458.550264 -291.241734)
		(width 0.1016)
		(layer "F.Cu")
		(net "M_H_CPU0_SA_DQ<22>")
	)
	(segment
		(start 428.33544 -295.640252)
		(end 427.85792 -295.640252)
		(width 0.18288)
		(layer "In11.Cu")
		(net "M_H_CPU0_SA_DQ<22>")
	)
	(segment
		(start 425.531534 -295.765982)
		(end 425.257976 -295.492424)
		(width 0.18288)
		(layer "In11.Cu")
		(net "M_H_CPU0_SA_DQ<22>")
	)
	(segment
		(start 379.71476 -271.33931)
		(end 379.708664 -271.335754)
		(width 0.088646)
		(layer "In11.Cu")
		(net "M_H_CPU0_SA_DQ<22>")
	)
	(segment
		(start 434.957728 -294.779192)
		(end 431.842672 -294.779192)
		(width 0.18288)
		(layer "In11.Cu")
		(net "M_H_CPU0_SA_DQ<22>")
	)
	(segment
		(start 420.245032 -296.342308)
		(end 420.186104 -296.401236)
		(width 0.18288)
		(layer "In11.Cu")
		(net "M_H_CPU0_SA_DQ<22>")
	)
	(segment
		(start 430.22139 -294.174164)
		(end 429.801528 -294.174164)
		(width 0.18288)
		(layer "In11.Cu")
		(net "M_H_CPU0_SA_DQ<22>")
	)
	(segment
		(start 450.6976 -291.242496)
		(end 450.09689 -290.641786)
		(width 0.18288)
		(layer "In11.Cu")
		(net "M_H_CPU0_SA_DQ<22>")
	)
	(segment
		(start 452.49465 -290.651438)
		(end 452.30161 -290.458398)
		(width 0.18288)
		(layer "In11.Cu")
		(net "M_H_CPU0_SA_DQ<22>")
	)
	(segment
		(start 407.8097 -291.821616)
		(end 406.607772 -291.821616)
		(width 0.18288)
		(layer "In11.Cu")
		(net "M_H_CPU0_SA_DQ<22>")
	)
	(segment
		(start 373.974614 -268.894052)
		(end 373.898414 -268.93901)
		(width 0.088646)
		(layer "In11.Cu")
		(net "M_H_CPU0_SA_DQ<22>")
	)
	(segment
		(start 443.223142 -293.750492)
		(end 442.27115 -294.702484)
		(width 0.18288)
		(layer "In11.Cu")
		(net "M_H_CPU0_SA_DQ<22>")
	)
	(segment
		(start 413.45358 -294.006524)
		(end 412.880556 -294.006524)
		(width 0.18288)
		(layer "In11.Cu")
		(net "M_H_CPU0_SA_DQ<22>")
	)
	(segment
		(start 443.816994 -293.750492)
		(end 443.223142 -293.750492)
		(width 0.18288)
		(layer "In11.Cu")
		(net "M_H_CPU0_SA_DQ<22>")
	)
	(segment
		(start 421.40124 -296.342308)
		(end 420.245032 -296.342308)
		(width 0.18288)
		(layer "In11.Cu")
		(net "M_H_CPU0_SA_DQ<22>")
	)
	(segment
		(start 385.266946 -272.140934)
		(end 385.252214 -272.14957)
		(width 0.088646)
		(layer "In11.Cu")
		(net "M_H_CPU0_SA_DQ<22>")
	)
	(segment
		(start 413.823912 -293.636192)
		(end 413.45358 -294.006524)
		(width 0.18288)
		(layer "In11.Cu")
		(net "M_H_CPU0_SA_DQ<22>")
	)
	(segment
		(start 386.158486 -272.63217)
		(end 386.158486 -272.463006)
		(width 0.088646)
		(layer "In11.Cu")
		(net "M_H_CPU0_SA_DQ<22>")
	)
	(segment
		(start 424.052746 -295.669716)
		(end 422.073832 -295.669716)
		(width 0.18288)
		(layer "In11.Cu")
		(net "M_H_CPU0_SA_DQ<22>")
	)
	(segment
		(start 381.507746 -272.140934)
		(end 381.493014 -272.14957)
		(width 0.088646)
		(layer "In11.Cu")
		(net "M_H_CPU0_SA_DQ<22>")
	)
	(segment
		(start 454.692512 -291.109146)
		(end 454.692512 -291.242496)
		(width 0.18288)
		(layer "In11.Cu")
		(net "M_H_CPU0_SA_DQ<22>")
	)
	(segment
		(start 441.112656 -295.492424)
		(end 438.698386 -295.492424)
		(width 0.18288)
		(layer "In11.Cu")
		(net "M_H_CPU0_SA_DQ<22>")
	)
	(segment
		(start 379.991366 -271.833848)
		(end 379.991366 -271.825212)
		(width 0.088646)
		(layer "In11.Cu")
		(net "M_H_CPU0_SA_DQ<22>")
	)
	(segment
		(start 453.495156 -291.668708)
		(end 453.068944 -291.242496)
		(width 0.18288)
		(layer "In11.Cu")
		(net "M_H_CPU0_SA_DQ<22>")
	)
	(segment
		(start 442.27115 -294.702484)
		(end 441.902596 -294.702484)
		(width 0.18288)
		(layer "In11.Cu")
		(net "M_H_CPU0_SA_DQ<22>")
	)
	(segment
		(start 424.230038 -295.492424)
		(end 424.052746 -295.669716)
		(width 0.18288)
		(layer "In11.Cu")
		(net "M_H_CPU0_SA_DQ<22>")
	)
	(segment
		(start 387.065266 -273.53895)
		(end 386.158486 -272.63217)
		(width 0.088646)
		(layer "In11.Cu")
		(net "M_H_CPU0_SA_DQ<22>")
	)
	(segment
		(start 437.84901 -295.59758)
		(end 436.89397 -294.64254)
		(width 0.18288)
		(layer "In11.Cu")
		(net "M_H_CPU0_SA_DQ<22>")
	)
	(segment
		(start 427.85792 -295.640252)
		(end 427.649894 -295.432226)
		(width 0.18288)
		(layer "In11.Cu")
		(net "M_H_CPU0_SA_DQ<22>")
	)
	(segment
		(start 435.09438 -294.64254)
		(end 434.957728 -294.779192)
		(width 0.18288)
		(layer "In11.Cu")
		(net "M_H_CPU0_SA_DQ<22>")
	)
	(segment
		(start 386.158486 -272.463006)
		(end 385.934712 -272.239232)
		(width 0.088646)
		(layer "In11.Cu")
		(net "M_H_CPU0_SA_DQ<22>")
	)
	(segment
		(start 431.21961 -294.198548)
		(end 430.869344 -294.548814)
		(width 0.18288)
		(layer "In11.Cu")
		(net "M_H_CPU0_SA_DQ<22>")
	)
	(segment
		(start 431.842672 -294.779192)
		(end 431.742088 -294.678608)
		(width 0.18288)
		(layer "In11.Cu")
		(net "M_H_CPU0_SA_DQ<22>")
	)
	(segment
		(start 451.98411 -290.458398)
		(end 451.79107 -290.651438)
		(width 0.18288)
		(layer "In11.Cu")
		(net "M_H_CPU0_SA_DQ<22>")
	)
	(segment
		(start 426.697902 -295.432226)
		(end 426.364146 -295.765982)
		(width 0.18288)
		(layer "In11.Cu")
		(net "M_H_CPU0_SA_DQ<22>")
	)
	(segment
		(start 451.59803 -291.242496)
		(end 450.6976 -291.242496)
		(width 0.18288)
		(layer "In11.Cu")
		(net "M_H_CPU0_SA_DQ<22>")
	)
	(segment
		(start 388.317486 -273.53895)
		(end 387.289294 -273.53895)
		(width 0.18288)
		(layer "In11.Cu")
		(net "M_H_CPU0_SA_DQ<22>")
	)
	(segment
		(start 374.545606 -268.897608)
		(end 374.539764 -268.894052)
		(width 0.088646)
		(layer "In11.Cu")
		(net "M_H_CPU0_SA_DQ<22>")
	)
	(segment
		(start 379.708664 -271.335754)
		(end 379.699774 -271.330674)
		(width 0.088646)
		(layer "In11.Cu")
		(net "M_H_CPU0_SA_DQ<22>")
	)
	(segment
		(start 376.419364 -268.894052)
		(end 376.413522 -268.89075)
		(width 0.088646)
		(layer "In11.Cu")
		(net "M_H_CPU0_SA_DQ<22>")
	)
	(segment
		(start 426.364146 -295.765982)
		(end 425.531534 -295.765982)
		(width 0.18288)
		(layer "In11.Cu")
		(net "M_H_CPU0_SA_DQ<22>")
	)
	(segment
		(start 420.186104 -296.401236)
		(end 419.270434 -296.401236)
		(width 0.18288)
		(layer "In11.Cu")
		(net "M_H_CPU0_SA_DQ<22>")
	)
	(segment
		(start 450.09689 -290.641786)
		(end 449.19265 -290.641786)
		(width 0.18288)
		(layer "In11.Cu")
		(net "M_H_CPU0_SA_DQ<22>")
	)
	(segment
		(start 406.607772 -291.821616)
		(end 406.094184 -291.308028)
		(width 0.18288)
		(layer "In11.Cu")
		(net "M_H_CPU0_SA_DQ<22>")
	)
	(segment
		(start 403.721062 -288.942526)
		(end 388.317486 -273.53895)
		(width 0.18288)
		(layer "In11.Cu")
		(net "M_H_CPU0_SA_DQ<22>")
	)
	(segment
		(start 414.330388 -293.636192)
		(end 413.823912 -293.636192)
		(width 0.18288)
		(layer "In11.Cu")
		(net "M_H_CPU0_SA_DQ<22>")
	)
	(segment
		(start 449.19265 -290.641786)
		(end 447.52641 -292.308026)
		(width 0.18288)
		(layer "In11.Cu")
		(net "M_H_CPU0_SA_DQ<22>")
	)
	(segment
		(start 416.523932 -294.26662)
		(end 414.960816 -294.26662)
		(width 0.18288)
		(layer "In11.Cu")
		(net "M_H_CPU0_SA_DQ<22>")
	)
	(segment
		(start 453.068944 -291.242496)
		(end 452.68769 -291.242496)
		(width 0.18288)
		(layer "In11.Cu")
		(net "M_H_CPU0_SA_DQ<22>")
	)
	(segment
		(start 422.073832 -295.669716)
		(end 421.40124 -296.342308)
		(width 0.18288)
		(layer "In11.Cu")
		(net "M_H_CPU0_SA_DQ<22>")
	)
	(segment
		(start 452.49465 -291.049456)
		(end 452.49465 -290.651438)
		(width 0.18288)
		(layer "In11.Cu")
		(net "M_H_CPU0_SA_DQ<22>")
	)
	(segment
		(start 375.485406 -268.897608)
		(end 375.479564 -268.894052)
		(width 0.088646)
		(layer "In11.Cu")
		(net "M_H_CPU0_SA_DQ<22>")
	)
	(segment
		(start 403.721062 -289.508946)
		(end 403.721062 -288.942526)
		(width 0.18288)
		(layer "In11.Cu")
		(net "M_H_CPU0_SA_DQ<22>")
	)
	(segment
		(start 379.239018 -270.521938)
		(end 379.230128 -270.516858)
		(width 0.088646)
		(layer "In11.Cu")
		(net "M_H_CPU0_SA_DQ<22>")
	)
	(segment
		(start 445.95669 -292.993826)
		(end 444.57366 -292.993826)
		(width 0.18288)
		(layer "In11.Cu")
		(net "M_H_CPU0_SA_DQ<22>")
	)
	(segment
		(start 383.387346 -272.140934)
		(end 383.372614 -272.14957)
		(width 0.088646)
		(layer "In11.Cu")
		(net "M_H_CPU0_SA_DQ<22>")
	)
	(segment
		(start 378.768864 -269.707868)
		(end 378.759974 -269.702788)
		(width 0.088646)
		(layer "In11.Cu")
		(net "M_H_CPU0_SA_DQ<22>")
	)
	(segment
		(start 446.64249 -292.308026)
		(end 445.95669 -292.993826)
		(width 0.18288)
		(layer "In11.Cu")
		(net "M_H_CPU0_SA_DQ<22>")
	)
	(segment
		(start 454.692512 -291.242496)
		(end 454.2663 -291.668708)
		(width 0.18288)
		(layer "In11.Cu")
		(net "M_H_CPU0_SA_DQ<22>")
	)
	(segment
		(start 454.985882 -290.816538)
		(end 454.692512 -291.109146)
		(width 0.18288)
		(layer "In11.Cu")
		(net "M_H_CPU0_SA_DQ<22>")
	)
	(segment
		(start 436.89397 -294.64254)
		(end 435.09438 -294.64254)
		(width 0.18288)
		(layer "In11.Cu")
		(net "M_H_CPU0_SA_DQ<22>")
	)
	(segment
		(start 444.57366 -292.993826)
		(end 443.816994 -293.750492)
		(width 0.18288)
		(layer "In11.Cu")
		(net "M_H_CPU0_SA_DQ<22>")
	)
	(segment
		(start 438.698386 -295.492424)
		(end 438.59323 -295.59758)
		(width 0.18288)
		(layer "In11.Cu")
		(net "M_H_CPU0_SA_DQ<22>")
	)
	(segment
		(start 380.563374 -272.143474)
		(end 380.55296 -272.14957)
		(width 0.088646)
		(layer "In11.Cu")
		(net "M_H_CPU0_SA_DQ<22>")
	)
	(segment
		(start 375.479564 -268.894052)
		(end 375.473722 -268.89075)
		(width 0.088646)
		(layer "In11.Cu")
		(net "M_H_CPU0_SA_DQ<22>")
	)
	(segment
		(start 384.327146 -272.140934)
		(end 384.312414 -272.14957)
		(width 0.088646)
		(layer "In11.Cu")
		(net "M_H_CPU0_SA_DQ<22>")
	)
	(segment
		(start 431.63617 -294.198548)
		(end 431.21961 -294.198548)
		(width 0.18288)
		(layer "In11.Cu")
		(net "M_H_CPU0_SA_DQ<22>")
	)
	(segment
		(start 414.960816 -294.26662)
		(end 414.330388 -293.636192)
		(width 0.18288)
		(layer "In11.Cu")
		(net "M_H_CPU0_SA_DQ<22>")
	)
	(segment
		(start 373.895366 -268.940026)
		(end 373.891556 -268.942058)
		(width 0.088646)
		(layer "In11.Cu")
		(net "M_H_CPU0_SA_DQ<22>")
	)
	(segment
		(start 412.880556 -294.006524)
		(end 412.071058 -293.197026)
		(width 0.18288)
		(layer "In11.Cu")
		(net "M_H_CPU0_SA_DQ<22>")
	)
	(segment
		(start 405.520144 -291.308028)
		(end 403.721062 -289.508946)
		(width 0.18288)
		(layer "In11.Cu")
		(net "M_H_CPU0_SA_DQ<22>")
	)
	(segment
		(start 419.270434 -296.401236)
		(end 417.550854 -294.680132)
		(width 0.18288)
		(layer "In11.Cu")
		(net "M_H_CPU0_SA_DQ<22>")
	)
	(segment
		(start 431.742088 -294.678608)
		(end 431.742088 -294.304466)
		(width 0.18288)
		(layer "In11.Cu")
		(net "M_H_CPU0_SA_DQ<22>")
	)
	(segment
		(start 379.051566 -270.19758)
		(end 379.051566 -270.183356)
		(width 0.088646)
		(layer "In11.Cu")
		(net "M_H_CPU0_SA_DQ<22>")
	)
	(segment
		(start 451.79107 -291.049456)
		(end 451.59803 -291.242496)
		(width 0.18288)
		(layer "In11.Cu")
		(net "M_H_CPU0_SA_DQ<22>")
	)
	(segment
		(start 455.011282 -290.816538)
		(end 454.985882 -290.816538)
		(width 0.18288)
		(layer "In11.Cu")
		(net "M_H_CPU0_SA_DQ<22>")
	)
	(segment
		(start 451.79107 -290.651438)
		(end 451.79107 -291.049456)
		(width 0.18288)
		(layer "In11.Cu")
		(net "M_H_CPU0_SA_DQ<22>")
	)
	(segment
		(start 377.748546 -268.885416)
		(end 377.733814 -268.894052)
		(width 0.088646)
		(layer "In11.Cu")
		(net "M_H_CPU0_SA_DQ<22>")
	)
	(segment
		(start 438.59323 -295.59758)
		(end 437.84901 -295.59758)
		(width 0.18288)
		(layer "In11.Cu")
		(net "M_H_CPU0_SA_DQ<22>")
	)
	(segment
		(start 376.425206 -268.897608)
		(end 376.419364 -268.894052)
		(width 0.088646)
		(layer "In11.Cu")
		(net "M_H_CPU0_SA_DQ<22>")
	)
	(segment
		(start 376.808746 -268.885416)
		(end 376.794014 -268.894052)
		(width 0.088646)
		(layer "In11.Cu")
		(net "M_H_CPU0_SA_DQ<22>")
	)
	(segment
		(start 379.521212 -271.011396)
		(end 379.521212 -270.995902)
		(width 0.088646)
		(layer "In11.Cu")
		(net "M_H_CPU0_SA_DQ<22>")
	)
	(segment
		(start 454.2663 -291.668708)
		(end 453.495156 -291.668708)
		(width 0.18288)
		(layer "In11.Cu")
		(net "M_H_CPU0_SA_DQ<22>")
	)
	(segment
		(start 431.742088 -294.304466)
		(end 431.63617 -294.198548)
		(width 0.18288)
		(layer "In11.Cu")
		(net "M_H_CPU0_SA_DQ<22>")
	)
	(segment
		(start 417.550854 -294.680132)
		(end 416.937444 -294.680132)
		(width 0.18288)
		(layer "In11.Cu")
		(net "M_H_CPU0_SA_DQ<22>")
	)
	(segment
		(start 382.447546 -272.140934)
		(end 382.432814 -272.14957)
		(width 0.088646)
		(layer "In11.Cu")
		(net "M_H_CPU0_SA_DQ<22>")
	)
	(segment
		(start 416.937444 -294.680132)
		(end 416.523932 -294.26662)
		(width 0.18288)
		(layer "In11.Cu")
		(net "M_H_CPU0_SA_DQ<22>")
	)
	(segment
		(start 425.257976 -295.492424)
		(end 424.230038 -295.492424)
		(width 0.18288)
		(layer "In11.Cu")
		(net "M_H_CPU0_SA_DQ<22>")
	)
	(segment
		(start 378.581412 -269.38351)
		(end 378.581412 -269.368016)
		(width 0.088646)
		(layer "In11.Cu")
		(net "M_H_CPU0_SA_DQ<22>")
	)
	(segment
		(start 430.869344 -294.548814)
		(end 430.59604 -294.548814)
		(width 0.18288)
		(layer "In11.Cu")
		(net "M_H_CPU0_SA_DQ<22>")
	)
	(segment
		(start 441.902596 -294.702484)
		(end 441.112656 -295.492424)
		(width 0.18288)
		(layer "In11.Cu")
		(net "M_H_CPU0_SA_DQ<22>")
	)
	(segment
		(start 447.52641 -292.308026)
		(end 446.64249 -292.308026)
		(width 0.18288)
		(layer "In11.Cu")
		(net "M_H_CPU0_SA_DQ<22>")
	)
	(segment
		(start 427.649894 -295.432226)
		(end 426.697902 -295.432226)
		(width 0.18288)
		(layer "In11.Cu")
		(net "M_H_CPU0_SA_DQ<22>")
	)
	(segment
		(start 452.68769 -291.242496)
		(end 452.49465 -291.049456)
		(width 0.18288)
		(layer "In11.Cu")
		(net "M_H_CPU0_SA_DQ<22>")
	)
	(segment
		(start 412.071058 -293.197026)
		(end 409.18511 -293.197026)
		(width 0.18288)
		(layer "In11.Cu")
		(net "M_H_CPU0_SA_DQ<22>")
	)
	(segment
		(start 406.094184 -291.308028)
		(end 405.520144 -291.308028)
		(width 0.18288)
		(layer "In11.Cu")
		(net "M_H_CPU0_SA_DQ<22>")
	)
	(segment
		(start 409.18511 -293.197026)
		(end 407.8097 -291.821616)
		(width 0.18288)
		(layer "In11.Cu")
		(net "M_H_CPU0_SA_DQ<22>")
	)
	(segment
		(start 374.539764 -268.894052)
		(end 374.533922 -268.89075)
		(width 0.088646)
		(layer "In11.Cu")
		(net "M_H_CPU0_SA_DQ<22>")
	)
	(segment
		(start 429.801528 -294.174164)
		(end 428.33544 -295.640252)
		(width 0.18288)
		(layer "In11.Cu")
		(net "M_H_CPU0_SA_DQ<22>")
	)
	(segment
		(start 430.59604 -294.548814)
		(end 430.22139 -294.174164)
		(width 0.18288)
		(layer "In11.Cu")
		(net "M_H_CPU0_SA_DQ<22>")
	)
	(segment
		(start 452.30161 -290.458398)
		(end 451.98411 -290.458398)
		(width 0.18288)
		(layer "In11.Cu")
		(net "M_H_CPU0_SA_DQ<22>")
	)
	(segment
		(start 387.289294 -273.53895)
		(end 387.065266 -273.53895)
		(width 0.088646)
		(layer "In11.Cu")
		(net "M_H_CPU0_SA_DQ<22>")
	)
	(arc
		(start 377.359418 -268.894052)
		(mid 377.085219 -268.818217)
		(end 376.808746 -268.885416)
		(width 0.088646)
		(layer "In11.Cu")
		(net "M_H_CPU0_SA_DQ<22>")
	)
	(arc
		(start 378.759974 -269.702788)
		(mid 378.62906 -269.566428)
		(end 378.581412 -269.38351)
		(width 0.088646)
		(layer "In11.Cu")
		(net "M_H_CPU0_SA_DQ<22>")
	)
	(arc
		(start 379.521212 -270.995902)
		(mid 379.441842 -270.722168)
		(end 379.239018 -270.521938)
		(width 0.088646)
		(layer "In11.Cu")
		(net "M_H_CPU0_SA_DQ<22>")
	)
	(arc
		(start 382.998218 -272.14957)
		(mid 382.723989 -272.073645)
		(end 382.447546 -272.140934)
		(width 0.088646)
		(layer "In11.Cu")
		(net "M_H_CPU0_SA_DQ<22>")
	)
	(arc
		(start 385.252214 -272.14957)
		(mid 385.065016 -272.199713)
		(end 384.877818 -272.14957)
		(width 0.088646)
		(layer "In11.Cu")
		(net "M_H_CPU0_SA_DQ<22>")
	)
	(arc
		(start 384.877818 -272.14957)
		(mid 384.603589 -272.073645)
		(end 384.327146 -272.140934)
		(width 0.088646)
		(layer "In11.Cu")
		(net "M_H_CPU0_SA_DQ<22>")
	)
	(arc
		(start 375.473722 -268.89075)
		(mid 375.193761 -268.818433)
		(end 374.914668 -268.894052)
		(width 0.088646)
		(layer "In11.Cu")
		(net "M_H_CPU0_SA_DQ<22>")
	)
	(arc
		(start 384.312414 -272.14957)
		(mid 384.125216 -272.199713)
		(end 383.938018 -272.14957)
		(width 0.088646)
		(layer "In11.Cu")
		(net "M_H_CPU0_SA_DQ<22>")
	)
	(arc
		(start 376.413522 -268.89075)
		(mid 376.133417 -268.818308)
		(end 375.854214 -268.894052)
		(width 0.088646)
		(layer "In11.Cu")
		(net "M_H_CPU0_SA_DQ<22>")
	)
	(arc
		(start 373.898414 -268.93901)
		(mid 373.896895 -268.939534)
		(end 373.895366 -268.940026)
		(width 0.088646)
		(layer "In11.Cu")
		(net "M_H_CPU0_SA_DQ<22>")
	)
	(arc
		(start 375.854214 -268.894052)
		(mid 375.67029 -268.944306)
		(end 375.485406 -268.897608)
		(width 0.088646)
		(layer "In11.Cu")
		(net "M_H_CPU0_SA_DQ<22>")
	)
	(arc
		(start 380.178564 -272.14957)
		(mid 380.043631 -272.016216)
		(end 379.991366 -271.833848)
		(width 0.088646)
		(layer "In11.Cu")
		(net "M_H_CPU0_SA_DQ<22>")
	)
	(arc
		(start 378.299218 -268.894052)
		(mid 378.025019 -268.818217)
		(end 377.748546 -268.885416)
		(width 0.088646)
		(layer "In11.Cu")
		(net "M_H_CPU0_SA_DQ<22>")
	)
	(arc
		(start 385.934712 -272.239232)
		(mid 385.879096 -272.190574)
		(end 385.817618 -272.14957)
		(width 0.088646)
		(layer "In11.Cu")
		(net "M_H_CPU0_SA_DQ<22>")
	)
	(arc
		(start 379.991366 -271.825212)
		(mid 379.917375 -271.545646)
		(end 379.71476 -271.33931)
		(width 0.088646)
		(layer "In11.Cu")
		(net "M_H_CPU0_SA_DQ<22>")
	)
	(arc
		(start 383.372614 -272.14957)
		(mid 383.185416 -272.199713)
		(end 382.998218 -272.14957)
		(width 0.088646)
		(layer "In11.Cu")
		(net "M_H_CPU0_SA_DQ<22>")
	)
	(arc
		(start 378.581412 -269.368016)
		(mid 378.502042 -269.094282)
		(end 378.299218 -268.894052)
		(width 0.088646)
		(layer "In11.Cu")
		(net "M_H_CPU0_SA_DQ<22>")
	)
	(arc
		(start 381.493014 -272.14957)
		(mid 381.305816 -272.199713)
		(end 381.118618 -272.14957)
		(width 0.088646)
		(layer "In11.Cu")
		(net "M_H_CPU0_SA_DQ<22>")
	)
	(arc
		(start 382.058418 -272.14957)
		(mid 381.784189 -272.073645)
		(end 381.507746 -272.140934)
		(width 0.088646)
		(layer "In11.Cu")
		(net "M_H_CPU0_SA_DQ<22>")
	)
	(arc
		(start 376.794014 -268.894052)
		(mid 376.61009 -268.944306)
		(end 376.425206 -268.897608)
		(width 0.088646)
		(layer "In11.Cu")
		(net "M_H_CPU0_SA_DQ<22>")
	)
	(arc
		(start 383.938018 -272.14957)
		(mid 383.663789 -272.073645)
		(end 383.387346 -272.140934)
		(width 0.088646)
		(layer "In11.Cu")
		(net "M_H_CPU0_SA_DQ<22>")
	)
	(arc
		(start 379.230128 -270.516858)
		(mid 379.099214 -270.380498)
		(end 379.051566 -270.19758)
		(width 0.088646)
		(layer "In11.Cu")
		(net "M_H_CPU0_SA_DQ<22>")
	)
	(arc
		(start 382.432814 -272.14957)
		(mid 382.245616 -272.199713)
		(end 382.058418 -272.14957)
		(width 0.088646)
		(layer "In11.Cu")
		(net "M_H_CPU0_SA_DQ<22>")
	)
	(arc
		(start 385.817618 -272.14957)
		(mid 385.543389 -272.073645)
		(end 385.266946 -272.140934)
		(width 0.088646)
		(layer "In11.Cu")
		(net "M_H_CPU0_SA_DQ<22>")
	)
	(arc
		(start 374.533922 -268.89075)
		(mid 374.253817 -268.818308)
		(end 373.974614 -268.894052)
		(width 0.088646)
		(layer "In11.Cu")
		(net "M_H_CPU0_SA_DQ<22>")
	)
	(arc
		(start 377.733814 -268.894052)
		(mid 377.546616 -268.944195)
		(end 377.359418 -268.894052)
		(width 0.088646)
		(layer "In11.Cu")
		(net "M_H_CPU0_SA_DQ<22>")
	)
	(arc
		(start 381.118618 -272.14957)
		(mid 380.841805 -272.073734)
		(end 380.563374 -272.143474)
		(width 0.088646)
		(layer "In11.Cu")
		(net "M_H_CPU0_SA_DQ<22>")
	)
	(arc
		(start 379.699774 -271.330674)
		(mid 379.56886 -271.194314)
		(end 379.521212 -271.011396)
		(width 0.088646)
		(layer "In11.Cu")
		(net "M_H_CPU0_SA_DQ<22>")
	)
	(arc
		(start 373.891556 -268.942058)
		(mid 373.590025 -269.144072)
		(end 373.317262 -269.38351)
		(width 0.088646)
		(layer "In11.Cu")
		(net "M_H_CPU0_SA_DQ<22>")
	)
	(arc
		(start 379.051566 -270.183356)
		(mid 378.972347 -269.908671)
		(end 378.768864 -269.707868)
		(width 0.088646)
		(layer "In11.Cu")
		(net "M_H_CPU0_SA_DQ<22>")
	)
	(arc
		(start 374.914668 -268.894052)
		(mid 374.730601 -268.944432)
		(end 374.545606 -268.897608)
		(width 0.088646)
		(layer "In11.Cu")
		(net "M_H_CPU0_SA_DQ<22>")
	)
	(arc
		(start 380.55296 -272.14957)
		(mid 380.365762 -272.199713)
		(end 380.178564 -272.14957)
		(width 0.088646)
		(layer "In11.Cu")
		(net "M_H_CPU0_SA_DQ<22>")
	)
	(segment
		(start 459.55966 -289.966908)
		(end 457.968096 -289.966908)
		(width 0.20066)
		(layer "F.Cu")
		(net "M_H_CPU0_SA_DQ<21>")
	)
	(segment
		(start 457.120244 -289.541712)
		(end 454.931526 -289.541712)
		(width 0.1016)
		(layer "F.Cu")
		(net "M_H_CPU0_SA_DQ<21>")
	)
	(segment
		(start 371.907562 -268.56944)
		(end 371.907816 -268.569694)
		(width 0.20066)
		(layer "F.Cu")
		(net "M_H_CPU0_SA_DQ<21>")
	)
	(segment
		(start 454.566782 -289.541712)
		(end 454.448672 -289.659822)
		(width 0.20066)
		(layer "F.Cu")
		(net "M_H_CPU0_SA_DQ<21>")
	)
	(segment
		(start 454.448672 -289.659822)
		(end 454.448672 -290.02736)
		(width 0.20066)
		(layer "F.Cu")
		(net "M_H_CPU0_SA_DQ<21>")
	)
	(segment
		(start 454.260712 -290.21532)
		(end 453.785478 -290.21532)
		(width 0.20066)
		(layer "F.Cu")
		(net "M_H_CPU0_SA_DQ<21>")
	)
	(segment
		(start 453.536812 -289.966654)
		(end 452.016114 -289.966654)
		(width 0.20066)
		(layer "F.Cu")
		(net "M_H_CPU0_SA_DQ<21>")
	)
	(segment
		(start 452.016114 -289.966654)
		(end 450.911214 -289.966654)
		(width 0.20066)
		(layer "F.Cu")
		(net "M_H_CPU0_SA_DQ<21>")
	)
	(segment
		(start 454.931526 -289.541712)
		(end 454.91146 -289.541712)
		(width 0.101854)
		(layer "F.Cu")
		(net "M_H_CPU0_SA_DQ<21>")
	)
	(segment
		(start 371.907562 -268.033754)
		(end 371.907562 -268.56944)
		(width 0.20066)
		(layer "F.Cu")
		(net "M_H_CPU0_SA_DQ<21>")
	)
	(segment
		(start 457.53655 -289.535362)
		(end 457.126594 -289.535362)
		(width 0.20066)
		(layer "F.Cu")
		(net "M_H_CPU0_SA_DQ<21>")
	)
	(segment
		(start 454.448672 -290.02736)
		(end 454.260712 -290.21532)
		(width 0.20066)
		(layer "F.Cu")
		(net "M_H_CPU0_SA_DQ<21>")
	)
	(segment
		(start 454.91146 -289.541712)
		(end 454.566782 -289.541712)
		(width 0.20066)
		(layer "F.Cu")
		(net "M_H_CPU0_SA_DQ<21>")
	)
	(segment
		(start 457.968096 -289.966908)
		(end 457.53655 -289.535362)
		(width 0.20066)
		(layer "F.Cu")
		(net "M_H_CPU0_SA_DQ<21>")
	)
	(segment
		(start 457.126594 -289.535362)
		(end 457.120244 -289.541712)
		(width 0.1016)
		(layer "F.Cu")
		(net "M_H_CPU0_SA_DQ<21>")
	)
	(segment
		(start 453.785478 -290.21532)
		(end 453.536812 -289.966654)
		(width 0.20066)
		(layer "F.Cu")
		(net "M_H_CPU0_SA_DQ<21>")
	)
	(segment
		(start 459.559914 -289.966654)
		(end 459.55966 -289.966908)
		(width 0.20066)
		(layer "F.Cu")
		(net "M_H_CPU0_SA_DQ<21>")
	)
	(segment
		(start 413.375094 -292.996366)
		(end 412.641288 -292.996366)
		(width 0.18288)
		(layer "In11.Cu")
		(net "M_H_CPU0_SA_DQ<21>")
	)
	(segment
		(start 373.600218 -268.245336)
		(end 373.59971 -268.245844)
		(width 0.088646)
		(layer "In11.Cu")
		(net "M_H_CPU0_SA_DQ<21>")
	)
	(segment
		(start 386.363464 -271.672304)
		(end 386.192014 -271.500854)
		(width 0.088646)
		(layer "In11.Cu")
		(net "M_H_CPU0_SA_DQ<21>")
	)
	(segment
		(start 405.912574 -290.241482)
		(end 405.283924 -290.241482)
		(width 0.18288)
		(layer "In11.Cu")
		(net "M_H_CPU0_SA_DQ<21>")
	)
	(segment
		(start 378.673614 -268.245336)
		(end 378.67336 -268.245336)
		(width 0.088646)
		(layer "In11.Cu")
		(net "M_H_CPU0_SA_DQ<21>")
	)
	(segment
		(start 450.432678 -290.041838)
		(end 449.915026 -289.524186)
		(width 0.18288)
		(layer "In11.Cu")
		(net "M_H_CPU0_SA_DQ<21>")
	)
	(segment
		(start 387.069838 -273.187668)
		(end 386.363464 -272.481294)
		(width 0.088646)
		(layer "In11.Cu")
		(net "M_H_CPU0_SA_DQ<21>")
	)
	(segment
		(start 410.071062 -292.641274)
		(end 409.636722 -292.641274)
		(width 0.18288)
		(layer "In11.Cu")
		(net "M_H_CPU0_SA_DQ<21>")
	)
	(segment
		(start 410.457142 -291.881814)
		(end 410.264102 -292.074854)
		(width 0.18288)
		(layer "In11.Cu")
		(net "M_H_CPU0_SA_DQ<21>")
	)
	(segment
		(start 447.964052 -291.032692)
		(end 447.200528 -291.032692)
		(width 0.18288)
		(layer "In11.Cu")
		(net "M_H_CPU0_SA_DQ<21>")
	)
	(segment
		(start 410.967682 -292.448234)
		(end 410.967682 -292.074854)
		(width 0.18288)
		(layer "In11.Cu")
		(net "M_H_CPU0_SA_DQ<21>")
	)
	(segment
		(start 424.3324 -294.641524)
		(end 424.008042 -294.317166)
		(width 0.18288)
		(layer "In11.Cu")
		(net "M_H_CPU0_SA_DQ<21>")
	)
	(segment
		(start 424.008042 -294.317166)
		(end 422.70299 -294.317166)
		(width 0.18288)
		(layer "In11.Cu")
		(net "M_H_CPU0_SA_DQ<21>")
	)
	(segment
		(start 428.526448 -294.377872)
		(end 428.037244 -294.377872)
		(width 0.18288)
		(layer "In11.Cu")
		(net "M_H_CPU0_SA_DQ<21>")
	)
	(segment
		(start 425.859956 -294.448484)
		(end 425.666916 -294.641524)
		(width 0.18288)
		(layer "In11.Cu")
		(net "M_H_CPU0_SA_DQ<21>")
	)
	(segment
		(start 410.774642 -291.881814)
		(end 410.457142 -291.881814)
		(width 0.18288)
		(layer "In11.Cu")
		(net "M_H_CPU0_SA_DQ<21>")
	)
	(segment
		(start 405.283924 -290.241482)
		(end 404.298404 -289.255962)
		(width 0.18288)
		(layer "In11.Cu")
		(net "M_H_CPU0_SA_DQ<21>")
	)
	(segment
		(start 415.760408 -293.755826)
		(end 415.300414 -293.755826)
		(width 0.18288)
		(layer "In11.Cu")
		(net "M_H_CPU0_SA_DQ<21>")
	)
	(segment
		(start 437.95696 -294.222678)
		(end 437.76392 -294.415718)
		(width 0.18288)
		(layer "In11.Cu")
		(net "M_H_CPU0_SA_DQ<21>")
	)
	(segment
		(start 426.563536 -294.469566)
		(end 426.563536 -293.951914)
		(width 0.18288)
		(layer "In11.Cu")
		(net "M_H_CPU0_SA_DQ<21>")
	)
	(segment
		(start 444.655194 -291.901626)
		(end 443.562994 -292.993826)
		(width 0.18288)
		(layer "In11.Cu")
		(net "M_H_CPU0_SA_DQ<21>")
	)
	(segment
		(start 379.330712 -269.397734)
		(end 379.330712 -269.38351)
		(width 0.088646)
		(layer "In11.Cu")
		(net "M_H_CPU0_SA_DQ<21>")
	)
	(segment
		(start 450.911214 -289.966654)
		(end 450.83603 -290.041838)
		(width 0.18288)
		(layer "In11.Cu")
		(net "M_H_CPU0_SA_DQ<21>")
	)
	(segment
		(start 382.447546 -271.50949)
		(end 382.432814 -271.500854)
		(width 0.088646)
		(layer "In11.Cu")
		(net "M_H_CPU0_SA_DQ<21>")
	)
	(segment
		(start 411.160722 -292.641274)
		(end 410.967682 -292.448234)
		(width 0.18288)
		(layer "In11.Cu")
		(net "M_H_CPU0_SA_DQ<21>")
	)
	(segment
		(start 419.709854 -295.285668)
		(end 419.022022 -295.285668)
		(width 0.18288)
		(layer "In11.Cu")
		(net "M_H_CPU0_SA_DQ<21>")
	)
	(segment
		(start 436.35295 -292.938708)
		(end 435.392322 -292.938708)
		(width 0.18288)
		(layer "In11.Cu")
		(net "M_H_CPU0_SA_DQ<21>")
	)
	(segment
		(start 410.264102 -292.448234)
		(end 410.071062 -292.641274)
		(width 0.18288)
		(layer "In11.Cu")
		(net "M_H_CPU0_SA_DQ<21>")
	)
	(segment
		(start 421.527986 -295.49217)
		(end 419.916356 -295.49217)
		(width 0.18288)
		(layer "In11.Cu")
		(net "M_H_CPU0_SA_DQ<21>")
	)
	(segment
		(start 381.507746 -271.50949)
		(end 381.493014 -271.500854)
		(width 0.088646)
		(layer "In11.Cu")
		(net "M_H_CPU0_SA_DQ<21>")
	)
	(segment
		(start 426.052996 -293.758874)
		(end 425.859956 -293.951914)
		(width 0.18288)
		(layer "In11.Cu")
		(net "M_H_CPU0_SA_DQ<21>")
	)
	(segment
		(start 406.959054 -291.287962)
		(end 405.912574 -290.241482)
		(width 0.18288)
		(layer "In11.Cu")
		(net "M_H_CPU0_SA_DQ<21>")
	)
	(segment
		(start 413.702754 -292.668706)
		(end 413.375094 -292.996366)
		(width 0.18288)
		(layer "In11.Cu")
		(net "M_H_CPU0_SA_DQ<21>")
	)
	(segment
		(start 416.428428 -293.554658)
		(end 415.961576 -293.554658)
		(width 0.18288)
		(layer "In11.Cu")
		(net "M_H_CPU0_SA_DQ<21>")
	)
	(segment
		(start 404.298404 -288.694114)
		(end 388.791958 -273.187668)
		(width 0.18288)
		(layer "In11.Cu")
		(net "M_H_CPU0_SA_DQ<21>")
	)
	(segment
		(start 385.266946 -271.50949)
		(end 385.252214 -271.500854)
		(width 0.088646)
		(layer "In11.Cu")
		(net "M_H_CPU0_SA_DQ<21>")
	)
	(segment
		(start 425.666916 -294.641524)
		(end 424.3324 -294.641524)
		(width 0.18288)
		(layer "In11.Cu")
		(net "M_H_CPU0_SA_DQ<21>")
	)
	(segment
		(start 415.961576 -293.554658)
		(end 415.760408 -293.755826)
		(width 0.18288)
		(layer "In11.Cu")
		(net "M_H_CPU0_SA_DQ<21>")
	)
	(segment
		(start 446.331594 -291.901626)
		(end 444.655194 -291.901626)
		(width 0.18288)
		(layer "In11.Cu")
		(net "M_H_CPU0_SA_DQ<21>")
	)
	(segment
		(start 383.387346 -271.50949)
		(end 383.372614 -271.500854)
		(width 0.088646)
		(layer "In11.Cu")
		(net "M_H_CPU0_SA_DQ<21>")
	)
	(segment
		(start 381.03175 -270.692118)
		(end 381.02286 -270.687038)
		(width 0.088646)
		(layer "In11.Cu")
		(net "M_H_CPU0_SA_DQ<21>")
	)
	(segment
		(start 412.641288 -292.996366)
		(end 412.286196 -292.641274)
		(width 0.18288)
		(layer "In11.Cu")
		(net "M_H_CPU0_SA_DQ<21>")
	)
	(segment
		(start 435.392322 -292.938708)
		(end 434.91912 -293.41191)
		(width 0.18288)
		(layer "In11.Cu")
		(net "M_H_CPU0_SA_DQ<21>")
	)
	(segment
		(start 433.198778 -293.21887)
		(end 433.005738 -293.41191)
		(width 0.18288)
		(layer "In11.Cu")
		(net "M_H_CPU0_SA_DQ<21>")
	)
	(segment
		(start 375.868946 -268.253972)
		(end 375.854214 -268.245336)
		(width 0.088646)
		(layer "In11.Cu")
		(net "M_H_CPU0_SA_DQ<21>")
	)
	(segment
		(start 426.370496 -293.758874)
		(end 426.052996 -293.758874)
		(width 0.18288)
		(layer "In11.Cu")
		(net "M_H_CPU0_SA_DQ<21>")
	)
	(segment
		(start 410.967682 -292.074854)
		(end 410.774642 -291.881814)
		(width 0.18288)
		(layer "In11.Cu")
		(net "M_H_CPU0_SA_DQ<21>")
	)
	(segment
		(start 433.709318 -292.641274)
		(end 433.391818 -292.641274)
		(width 0.18288)
		(layer "In11.Cu")
		(net "M_H_CPU0_SA_DQ<21>")
	)
	(segment
		(start 438.66054 -293.79672)
		(end 438.4675 -293.60368)
		(width 0.18288)
		(layer "In11.Cu")
		(net "M_H_CPU0_SA_DQ<21>")
	)
	(segment
		(start 378.682504 -268.250416)
		(end 378.673614 -268.245336)
		(width 0.088646)
		(layer "In11.Cu")
		(net "M_H_CPU0_SA_DQ<21>")
	)
	(segment
		(start 447.200528 -291.032692)
		(end 446.331594 -291.901626)
		(width 0.18288)
		(layer "In11.Cu")
		(net "M_H_CPU0_SA_DQ<21>")
	)
	(segment
		(start 416.629596 -293.755826)
		(end 416.428428 -293.554658)
		(width 0.18288)
		(layer "In11.Cu")
		(net "M_H_CPU0_SA_DQ<21>")
	)
	(segment
		(start 372.48973 -269.007336)
		(end 371.907816 -268.569694)
		(width 0.088646)
		(layer "In11.Cu")
		(net "M_H_CPU0_SA_DQ<21>")
	)
	(segment
		(start 373.130064 -269.059152)
		(end 373.12727 -269.060676)
		(width 0.088646)
		(layer "In11.Cu")
		(net "M_H_CPU0_SA_DQ<21>")
	)
	(segment
		(start 439.640472 -294.642286)
		(end 439.413904 -294.415718)
		(width 0.18288)
		(layer "In11.Cu")
		(net "M_H_CPU0_SA_DQ<21>")
	)
	(segment
		(start 415.300414 -293.755826)
		(end 414.213294 -292.668706)
		(width 0.18288)
		(layer "In11.Cu")
		(net "M_H_CPU0_SA_DQ<21>")
	)
	(segment
		(start 437.429656 -294.415718)
		(end 436.866792 -293.852854)
		(width 0.18288)
		(layer "In11.Cu")
		(net "M_H_CPU0_SA_DQ<21>")
	)
	(segment
		(start 378.861066 -268.585188)
		(end 378.861066 -268.569694)
		(width 0.088646)
		(layer "In11.Cu")
		(net "M_H_CPU0_SA_DQ<21>")
	)
	(segment
		(start 419.022022 -295.285668)
		(end 417.49218 -293.755826)
		(width 0.18288)
		(layer "In11.Cu")
		(net "M_H_CPU0_SA_DQ<21>")
	)
	(segment
		(start 433.391818 -292.641274)
		(end 433.198778 -292.834314)
		(width 0.18288)
		(layer "In11.Cu")
		(net "M_H_CPU0_SA_DQ<21>")
	)
	(segment
		(start 438.66054 -294.222678)
		(end 438.66054 -293.79672)
		(width 0.18288)
		(layer "In11.Cu")
		(net "M_H_CPU0_SA_DQ<21>")
	)
	(segment
		(start 425.859956 -293.951914)
		(end 425.859956 -294.448484)
		(width 0.18288)
		(layer "In11.Cu")
		(net "M_H_CPU0_SA_DQ<21>")
	)
	(segment
		(start 436.866792 -293.852854)
		(end 436.866792 -293.45255)
		(width 0.18288)
		(layer "In11.Cu")
		(net "M_H_CPU0_SA_DQ<21>")
	)
	(segment
		(start 410.264102 -292.074854)
		(end 410.264102 -292.448234)
		(width 0.18288)
		(layer "In11.Cu")
		(net "M_H_CPU0_SA_DQ<21>")
	)
	(segment
		(start 449.915026 -289.524186)
		(end 449.472558 -289.524186)
		(width 0.18288)
		(layer "In11.Cu")
		(net "M_H_CPU0_SA_DQ<21>")
	)
	(segment
		(start 372.564914 -269.059152)
		(end 372.558818 -269.055596)
		(width 0.088646)
		(layer "In11.Cu")
		(net "M_H_CPU0_SA_DQ<21>")
	)
	(segment
		(start 387.265672 -273.187668)
		(end 387.069838 -273.187668)
		(width 0.088646)
		(layer "In11.Cu")
		(net "M_H_CPU0_SA_DQ<21>")
	)
	(segment
		(start 388.791958 -273.187668)
		(end 387.265672 -273.187668)
		(width 0.18288)
		(layer "In11.Cu")
		(net "M_H_CPU0_SA_DQ<21>")
	)
	(segment
		(start 433.005738 -293.41191)
		(end 432.580034 -293.41191)
		(width 0.18288)
		(layer "In11.Cu")
		(net "M_H_CPU0_SA_DQ<21>")
	)
	(segment
		(start 426.563536 -293.951914)
		(end 426.370496 -293.758874)
		(width 0.18288)
		(layer "In11.Cu")
		(net "M_H_CPU0_SA_DQ<21>")
	)
	(segment
		(start 384.327146 -271.50949)
		(end 384.312414 -271.500854)
		(width 0.088646)
		(layer "In11.Cu")
		(net "M_H_CPU0_SA_DQ<21>")
	)
	(segment
		(start 432.580034 -293.41191)
		(end 432.34864 -293.411656)
		(width 0.18288)
		(layer "In11.Cu")
		(net "M_H_CPU0_SA_DQ<21>")
	)
	(segment
		(start 441.012834 -294.642286)
		(end 439.640472 -294.642286)
		(width 0.18288)
		(layer "In11.Cu")
		(net "M_H_CPU0_SA_DQ<21>")
	)
	(segment
		(start 379.628146 -269.881858)
		(end 379.613414 -269.873222)
		(width 0.088646)
		(layer "In11.Cu")
		(net "M_H_CPU0_SA_DQ<21>")
	)
	(segment
		(start 380.740412 -270.207486)
		(end 380.740412 -270.188944)
		(width 0.088646)
		(layer "In11.Cu")
		(net "M_H_CPU0_SA_DQ<21>")
	)
	(segment
		(start 376.808746 -268.253972)
		(end 376.794014 -268.245336)
		(width 0.088646)
		(layer "In11.Cu")
		(net "M_H_CPU0_SA_DQ<21>")
	)
	(segment
		(start 409.636722 -292.641274)
		(end 408.28341 -291.287962)
		(width 0.18288)
		(layer "In11.Cu")
		(net "M_H_CPU0_SA_DQ<21>")
	)
	(segment
		(start 450.83603 -290.041838)
		(end 450.432678 -290.041838)
		(width 0.18288)
		(layer "In11.Cu")
		(net "M_H_CPU0_SA_DQ<21>")
	)
	(segment
		(start 438.4675 -293.60368)
		(end 438.15 -293.60368)
		(width 0.18288)
		(layer "In11.Cu")
		(net "M_H_CPU0_SA_DQ<21>")
	)
	(segment
		(start 436.866792 -293.45255)
		(end 436.35295 -292.938708)
		(width 0.18288)
		(layer "In11.Cu")
		(net "M_H_CPU0_SA_DQ<21>")
	)
	(segment
		(start 438.15 -293.60368)
		(end 437.95696 -293.79672)
		(width 0.18288)
		(layer "In11.Cu")
		(net "M_H_CPU0_SA_DQ<21>")
	)
	(segment
		(start 432.10353 -293.656512)
		(end 429.247808 -293.656512)
		(width 0.18288)
		(layer "In11.Cu")
		(net "M_H_CPU0_SA_DQ<21>")
	)
	(segment
		(start 442.661294 -292.993826)
		(end 441.012834 -294.642286)
		(width 0.18288)
		(layer "In11.Cu")
		(net "M_H_CPU0_SA_DQ<21>")
	)
	(segment
		(start 437.76392 -294.415718)
		(end 437.429656 -294.415718)
		(width 0.18288)
		(layer "In11.Cu")
		(net "M_H_CPU0_SA_DQ<21>")
	)
	(segment
		(start 433.902358 -292.834314)
		(end 433.709318 -292.641274)
		(width 0.18288)
		(layer "In11.Cu")
		(net "M_H_CPU0_SA_DQ<21>")
	)
	(segment
		(start 377.748546 -268.253972)
		(end 377.733814 -268.245336)
		(width 0.088646)
		(layer "In11.Cu")
		(net "M_H_CPU0_SA_DQ<21>")
	)
	(segment
		(start 426.756576 -294.662606)
		(end 426.563536 -294.469566)
		(width 0.18288)
		(layer "In11.Cu")
		(net "M_H_CPU0_SA_DQ<21>")
	)
	(segment
		(start 429.247808 -293.656512)
		(end 428.526448 -294.377872)
		(width 0.18288)
		(layer "In11.Cu")
		(net "M_H_CPU0_SA_DQ<21>")
	)
	(segment
		(start 374.929146 -268.253972)
		(end 374.914414 -268.245336)
		(width 0.088646)
		(layer "In11.Cu")
		(net "M_H_CPU0_SA_DQ<21>")
	)
	(segment
		(start 381.493014 -271.500854)
		(end 381.486918 -271.497298)
		(width 0.088646)
		(layer "In11.Cu")
		(net "M_H_CPU0_SA_DQ<21>")
	)
	(segment
		(start 412.286196 -292.641274)
		(end 411.160722 -292.641274)
		(width 0.18288)
		(layer "In11.Cu")
		(net "M_H_CPU0_SA_DQ<21>")
	)
	(segment
		(start 414.213294 -292.668706)
		(end 413.702754 -292.668706)
		(width 0.18288)
		(layer "In11.Cu")
		(net "M_H_CPU0_SA_DQ<21>")
	)
	(segment
		(start 439.413904 -294.415718)
		(end 438.85358 -294.415718)
		(width 0.18288)
		(layer "In11.Cu")
		(net "M_H_CPU0_SA_DQ<21>")
	)
	(segment
		(start 404.298404 -289.255962)
		(end 404.298404 -288.694114)
		(width 0.18288)
		(layer "In11.Cu")
		(net "M_H_CPU0_SA_DQ<21>")
	)
	(segment
		(start 438.85358 -294.415718)
		(end 438.66054 -294.222678)
		(width 0.18288)
		(layer "In11.Cu")
		(net "M_H_CPU0_SA_DQ<21>")
	)
	(segment
		(start 433.198778 -292.834314)
		(end 433.198778 -293.21887)
		(width 0.18288)
		(layer "In11.Cu")
		(net "M_H_CPU0_SA_DQ<21>")
	)
	(segment
		(start 434.91912 -293.41191)
		(end 434.095398 -293.41191)
		(width 0.18288)
		(layer "In11.Cu")
		(net "M_H_CPU0_SA_DQ<21>")
	)
	(segment
		(start 379.15215 -269.064232)
		(end 379.14326 -269.059152)
		(width 0.088646)
		(layer "In11.Cu")
		(net "M_H_CPU0_SA_DQ<21>")
	)
	(segment
		(start 433.902358 -293.21887)
		(end 433.902358 -292.834314)
		(width 0.18288)
		(layer "In11.Cu")
		(net "M_H_CPU0_SA_DQ<21>")
	)
	(segment
		(start 373.974868 -268.245336)
		(end 373.974614 -268.245336)
		(width 0.088646)
		(layer "In11.Cu")
		(net "M_H_CPU0_SA_DQ<21>")
	)
	(segment
		(start 437.95696 -293.79672)
		(end 437.95696 -294.222678)
		(width 0.18288)
		(layer "In11.Cu")
		(net "M_H_CPU0_SA_DQ<21>")
	)
	(segment
		(start 417.49218 -293.755826)
		(end 416.629596 -293.755826)
		(width 0.18288)
		(layer "In11.Cu")
		(net "M_H_CPU0_SA_DQ<21>")
	)
	(segment
		(start 449.472558 -289.524186)
		(end 447.964052 -291.032692)
		(width 0.18288)
		(layer "In11.Cu")
		(net "M_H_CPU0_SA_DQ<21>")
	)
	(segment
		(start 434.095398 -293.41191)
		(end 433.902358 -293.21887)
		(width 0.18288)
		(layer "In11.Cu")
		(net "M_H_CPU0_SA_DQ<21>")
	)
	(segment
		(start 432.34864 -293.411656)
		(end 432.10353 -293.656512)
		(width 0.18288)
		(layer "In11.Cu")
		(net "M_H_CPU0_SA_DQ<21>")
	)
	(segment
		(start 408.28341 -291.287962)
		(end 406.959054 -291.287962)
		(width 0.18288)
		(layer "In11.Cu")
		(net "M_H_CPU0_SA_DQ<21>")
	)
	(segment
		(start 427.753018 -294.662606)
		(end 426.756576 -294.662606)
		(width 0.18288)
		(layer "In11.Cu")
		(net "M_H_CPU0_SA_DQ<21>")
	)
	(segment
		(start 422.70299 -294.317166)
		(end 421.527986 -295.49217)
		(width 0.18288)
		(layer "In11.Cu")
		(net "M_H_CPU0_SA_DQ<21>")
	)
	(segment
		(start 428.037244 -294.377872)
		(end 427.753018 -294.662606)
		(width 0.18288)
		(layer "In11.Cu")
		(net "M_H_CPU0_SA_DQ<21>")
	)
	(segment
		(start 443.562994 -292.993826)
		(end 442.661294 -292.993826)
		(width 0.18288)
		(layer "In11.Cu")
		(net "M_H_CPU0_SA_DQ<21>")
	)
	(segment
		(start 386.363464 -272.481294)
		(end 386.363464 -271.672304)
		(width 0.088646)
		(layer "In11.Cu")
		(net "M_H_CPU0_SA_DQ<21>")
	)
	(segment
		(start 419.916356 -295.49217)
		(end 419.709854 -295.285668)
		(width 0.18288)
		(layer "In11.Cu")
		(net "M_H_CPU0_SA_DQ<21>")
	)
	(arc
		(start 380.740412 -270.188944)
		(mid 380.688142 -270.006579)
		(end 380.553214 -269.873222)
		(width 0.088646)
		(layer "In11.Cu")
		(net "M_H_CPU0_SA_DQ<21>")
	)
	(arc
		(start 377.733814 -268.245336)
		(mid 377.546616 -268.195193)
		(end 377.359418 -268.245336)
		(width 0.088646)
		(layer "In11.Cu")
		(net "M_H_CPU0_SA_DQ<21>")
	)
	(arc
		(start 380.553214 -269.873222)
		(mid 380.366016 -269.823079)
		(end 380.178818 -269.873222)
		(width 0.088646)
		(layer "In11.Cu")
		(net "M_H_CPU0_SA_DQ<21>")
	)
	(arc
		(start 381.02286 -270.687038)
		(mid 380.818525 -270.484433)
		(end 380.740412 -270.207486)
		(width 0.088646)
		(layer "In11.Cu")
		(net "M_H_CPU0_SA_DQ<21>")
	)
	(arc
		(start 382.432814 -271.500854)
		(mid 382.245616 -271.450711)
		(end 382.058418 -271.500854)
		(width 0.088646)
		(layer "In11.Cu")
		(net "M_H_CPU0_SA_DQ<21>")
	)
	(arc
		(start 378.299218 -268.245336)
		(mid 378.025019 -268.321171)
		(end 377.748546 -268.253972)
		(width 0.088646)
		(layer "In11.Cu")
		(net "M_H_CPU0_SA_DQ<21>")
	)
	(arc
		(start 382.998218 -271.500854)
		(mid 382.724019 -271.576689)
		(end 382.447546 -271.50949)
		(width 0.088646)
		(layer "In11.Cu")
		(net "M_H_CPU0_SA_DQ<21>")
	)
	(arc
		(start 379.14326 -269.059152)
		(mid 378.940437 -268.858921)
		(end 378.861066 -268.585188)
		(width 0.088646)
		(layer "In11.Cu")
		(net "M_H_CPU0_SA_DQ<21>")
	)
	(arc
		(start 386.192014 -271.500854)
		(mid 386.004816 -271.450711)
		(end 385.817618 -271.500854)
		(width 0.088646)
		(layer "In11.Cu")
		(net "M_H_CPU0_SA_DQ<21>")
	)
	(arc
		(start 373.412512 -268.569694)
		(mid 373.336842 -268.852258)
		(end 373.130064 -269.059152)
		(width 0.088646)
		(layer "In11.Cu")
		(net "M_H_CPU0_SA_DQ<21>")
	)
	(arc
		(start 373.59971 -268.245844)
		(mid 373.462729 -268.382694)
		(end 373.412512 -268.569694)
		(width 0.088646)
		(layer "In11.Cu")
		(net "M_H_CPU0_SA_DQ<21>")
	)
	(arc
		(start 383.938018 -271.500854)
		(mid 383.663819 -271.576689)
		(end 383.387346 -271.50949)
		(width 0.088646)
		(layer "In11.Cu")
		(net "M_H_CPU0_SA_DQ<21>")
	)
	(arc
		(start 385.252214 -271.500854)
		(mid 385.065016 -271.450711)
		(end 384.877818 -271.500854)
		(width 0.088646)
		(layer "In11.Cu")
		(net "M_H_CPU0_SA_DQ<21>")
	)
	(arc
		(start 373.974614 -268.245336)
		(mid 373.787416 -268.195193)
		(end 373.600218 -268.245336)
		(width 0.088646)
		(layer "In11.Cu")
		(net "M_H_CPU0_SA_DQ<21>")
	)
	(arc
		(start 373.12727 -269.060676)
		(mid 372.845881 -269.13587)
		(end 372.564914 -269.059152)
		(width 0.088646)
		(layer "In11.Cu")
		(net "M_H_CPU0_SA_DQ<21>")
	)
	(arc
		(start 385.817618 -271.500854)
		(mid 385.543419 -271.576689)
		(end 385.266946 -271.50949)
		(width 0.088646)
		(layer "In11.Cu")
		(net "M_H_CPU0_SA_DQ<21>")
	)
	(arc
		(start 384.312414 -271.500854)
		(mid 384.125216 -271.450711)
		(end 383.938018 -271.500854)
		(width 0.088646)
		(layer "In11.Cu")
		(net "M_H_CPU0_SA_DQ<21>")
	)
	(arc
		(start 375.854214 -268.245336)
		(mid 375.667016 -268.195193)
		(end 375.479818 -268.245336)
		(width 0.088646)
		(layer "In11.Cu")
		(net "M_H_CPU0_SA_DQ<21>")
	)
	(arc
		(start 376.794014 -268.245336)
		(mid 376.606816 -268.195193)
		(end 376.419618 -268.245336)
		(width 0.088646)
		(layer "In11.Cu")
		(net "M_H_CPU0_SA_DQ<21>")
	)
	(arc
		(start 382.058418 -271.500854)
		(mid 381.784219 -271.576689)
		(end 381.507746 -271.50949)
		(width 0.088646)
		(layer "In11.Cu")
		(net "M_H_CPU0_SA_DQ<21>")
	)
	(arc
		(start 383.372614 -271.500854)
		(mid 383.185416 -271.450711)
		(end 382.998218 -271.500854)
		(width 0.088646)
		(layer "In11.Cu")
		(net "M_H_CPU0_SA_DQ<21>")
	)
	(arc
		(start 379.613414 -269.873222)
		(mid 379.409933 -269.672418)
		(end 379.330712 -269.397734)
		(width 0.088646)
		(layer "In11.Cu")
		(net "M_H_CPU0_SA_DQ<21>")
	)
	(arc
		(start 374.914414 -268.245336)
		(mid 374.727216 -268.195193)
		(end 374.540018 -268.245336)
		(width 0.088646)
		(layer "In11.Cu")
		(net "M_H_CPU0_SA_DQ<21>")
	)
	(arc
		(start 372.558818 -269.055596)
		(mid 372.523377 -269.032751)
		(end 372.48973 -269.007336)
		(width 0.088646)
		(layer "In11.Cu")
		(net "M_H_CPU0_SA_DQ<21>")
	)
	(arc
		(start 380.178818 -269.873222)
		(mid 379.904589 -269.949147)
		(end 379.628146 -269.881858)
		(width 0.088646)
		(layer "In11.Cu")
		(net "M_H_CPU0_SA_DQ<21>")
	)
	(arc
		(start 379.330712 -269.38351)
		(mid 379.283033 -269.20061)
		(end 379.15215 -269.064232)
		(width 0.088646)
		(layer "In11.Cu")
		(net "M_H_CPU0_SA_DQ<21>")
	)
	(arc
		(start 378.861066 -268.569694)
		(mid 378.813387 -268.386794)
		(end 378.682504 -268.250416)
		(width 0.088646)
		(layer "In11.Cu")
		(net "M_H_CPU0_SA_DQ<21>")
	)
	(arc
		(start 377.359418 -268.245336)
		(mid 377.085219 -268.321171)
		(end 376.808746 -268.253972)
		(width 0.088646)
		(layer "In11.Cu")
		(net "M_H_CPU0_SA_DQ<21>")
	)
	(arc
		(start 381.486918 -271.497298)
		(mid 381.284331 -271.290947)
		(end 381.210312 -271.011396)
		(width 0.088646)
		(layer "In11.Cu")
		(net "M_H_CPU0_SA_DQ<21>")
	)
	(arc
		(start 376.419618 -268.245336)
		(mid 376.145419 -268.321171)
		(end 375.868946 -268.253972)
		(width 0.088646)
		(layer "In11.Cu")
		(net "M_H_CPU0_SA_DQ<21>")
	)
	(arc
		(start 378.67336 -268.245336)
		(mid 378.486306 -268.195286)
		(end 378.299218 -268.245336)
		(width 0.088646)
		(layer "In11.Cu")
		(net "M_H_CPU0_SA_DQ<21>")
	)
	(arc
		(start 381.210312 -271.011396)
		(mid 381.162633 -270.828496)
		(end 381.03175 -270.692118)
		(width 0.088646)
		(layer "In11.Cu")
		(net "M_H_CPU0_SA_DQ<21>")
	)
	(arc
		(start 384.877818 -271.500854)
		(mid 384.603619 -271.576689)
		(end 384.327146 -271.50949)
		(width 0.088646)
		(layer "In11.Cu")
		(net "M_H_CPU0_SA_DQ<21>")
	)
	(arc
		(start 374.540018 -268.245336)
		(mid 374.25746 -268.320985)
		(end 373.974868 -268.245336)
		(width 0.088646)
		(layer "In11.Cu")
		(net "M_H_CPU0_SA_DQ<21>")
	)
	(arc
		(start 375.479818 -268.245336)
		(mid 375.205619 -268.321171)
		(end 374.929146 -268.253972)
		(width 0.088646)
		(layer "In11.Cu")
		(net "M_H_CPU0_SA_DQ<21>")
	)
	(segment
		(start 457.53655 -291.235384)
		(end 457.126594 -291.235384)
		(width 0.20066)
		(layer "F.Cu")
		(net "M_H_CPU0_SA_DQ<20>")
	)
	(segment
		(start 457.120244 -291.241734)
		(end 454.95845 -291.241734)
		(width 0.1016)
		(layer "F.Cu")
		(net "M_H_CPU0_SA_DQ<20>")
	)
	(segment
		(start 371.437916 -268.84757)
		(end 371.437916 -269.383256)
		(width 0.20066)
		(layer "F.Cu")
		(net "M_H_CPU0_SA_DQ<20>")
	)
	(segment
		(start 459.559914 -291.666676)
		(end 459.55966 -291.66693)
		(width 0.20066)
		(layer "F.Cu")
		(net "M_H_CPU0_SA_DQ<20>")
	)
	(segment
		(start 371.437916 -269.383256)
		(end 371.437662 -269.38351)
		(width 0.20066)
		(layer "F.Cu")
		(net "M_H_CPU0_SA_DQ<20>")
	)
	(segment
		(start 457.126594 -291.235384)
		(end 457.120244 -291.241734)
		(width 0.1016)
		(layer "F.Cu")
		(net "M_H_CPU0_SA_DQ<20>")
	)
	(segment
		(start 454.260712 -291.915342)
		(end 453.785478 -291.915342)
		(width 0.20066)
		(layer "F.Cu")
		(net "M_H_CPU0_SA_DQ<20>")
	)
	(segment
		(start 453.536812 -291.666676)
		(end 452.016114 -291.666676)
		(width 0.20066)
		(layer "F.Cu")
		(net "M_H_CPU0_SA_DQ<20>")
	)
	(segment
		(start 454.95845 -291.241734)
		(end 454.91146 -291.241734)
		(width 0.101854)
		(layer "F.Cu")
		(net "M_H_CPU0_SA_DQ<20>")
	)
	(segment
		(start 454.566782 -291.241734)
		(end 454.448672 -291.359844)
		(width 0.20066)
		(layer "F.Cu")
		(net "M_H_CPU0_SA_DQ<20>")
	)
	(segment
		(start 454.91146 -291.241734)
		(end 454.566782 -291.241734)
		(width 0.20066)
		(layer "F.Cu")
		(net "M_H_CPU0_SA_DQ<20>")
	)
	(segment
		(start 452.016114 -291.666676)
		(end 450.911214 -291.666676)
		(width 0.20066)
		(layer "F.Cu")
		(net "M_H_CPU0_SA_DQ<20>")
	)
	(segment
		(start 457.968096 -291.66693)
		(end 457.53655 -291.235384)
		(width 0.20066)
		(layer "F.Cu")
		(net "M_H_CPU0_SA_DQ<20>")
	)
	(segment
		(start 459.55966 -291.66693)
		(end 457.968096 -291.66693)
		(width 0.20066)
		(layer "F.Cu")
		(net "M_H_CPU0_SA_DQ<20>")
	)
	(segment
		(start 454.448672 -291.359844)
		(end 454.448672 -291.727382)
		(width 0.20066)
		(layer "F.Cu")
		(net "M_H_CPU0_SA_DQ<20>")
	)
	(segment
		(start 453.785478 -291.915342)
		(end 453.536812 -291.666676)
		(width 0.20066)
		(layer "F.Cu")
		(net "M_H_CPU0_SA_DQ<20>")
	)
	(segment
		(start 454.448672 -291.727382)
		(end 454.260712 -291.915342)
		(width 0.20066)
		(layer "F.Cu")
		(net "M_H_CPU0_SA_DQ<20>")
	)
	(segment
		(start 405.38908 -291.909754)
		(end 405.128222 -291.649404)
		(width 0.18288)
		(layer "In11.Cu")
		(net "M_H_CPU0_SA_DQ<20>")
	)
	(segment
		(start 420.199312 -297.192446)
		(end 419.931342 -296.924476)
		(width 0.18288)
		(layer "In11.Cu")
		(net "M_H_CPU0_SA_DQ<20>")
	)
	(segment
		(start 438.655968 -296.535348)
		(end 438.462928 -296.342308)
		(width 0.18288)
		(layer "In11.Cu")
		(net "M_H_CPU0_SA_DQ<20>")
	)
	(segment
		(start 382.528064 -272.314924)
		(end 382.513332 -272.32356)
		(width 0.088646)
		(layer "In11.Cu")
		(net "M_H_CPU0_SA_DQ<20>")
	)
	(segment
		(start 410.814012 -293.747952)
		(end 408.92984 -293.747952)
		(width 0.18288)
		(layer "In11.Cu")
		(net "M_H_CPU0_SA_DQ<20>")
	)
	(segment
		(start 373.8626 -269.218156)
		(end 373.72163 -269.35938)
		(width 0.088646)
		(layer "In11.Cu")
		(net "M_H_CPU0_SA_DQ<20>")
	)
	(segment
		(start 417.403534 -295.316402)
		(end 416.462718 -295.316402)
		(width 0.18288)
		(layer "In11.Cu")
		(net "M_H_CPU0_SA_DQ<20>")
	)
	(segment
		(start 403.597872 -290.916614)
		(end 403.325076 -290.916614)
		(width 0.18288)
		(layer "In11.Cu")
		(net "M_H_CPU0_SA_DQ<20>")
	)
	(segment
		(start 449.147184 -291.519356)
		(end 449.147184 -291.91585)
		(width 0.18288)
		(layer "In11.Cu")
		(net "M_H_CPU0_SA_DQ<20>")
	)
	(segment
		(start 433.230782 -295.585896)
		(end 433.037742 -295.392856)
		(width 0.18288)
		(layer "In11.Cu")
		(net "M_H_CPU0_SA_DQ<20>")
	)
	(segment
		(start 376.889518 -269.059152)
		(end 376.889264 -269.059152)
		(width 0.088646)
		(layer "In11.Cu")
		(net "M_H_CPU0_SA_DQ<20>")
	)
	(segment
		(start 404.593044 -291.911786)
		(end 404.320248 -291.911786)
		(width 0.18288)
		(layer "In11.Cu")
		(net "M_H_CPU0_SA_DQ<20>")
	)
	(segment
		(start 436.153052 -295.492424)
		(end 435.539388 -295.492424)
		(width 0.18288)
		(layer "In11.Cu")
		(net "M_H_CPU0_SA_DQ<20>")
	)
	(segment
		(start 379.15215 -270.692118)
		(end 379.14326 -270.687038)
		(width 0.088646)
		(layer "In11.Cu")
		(net "M_H_CPU0_SA_DQ<20>")
	)
	(segment
		(start 384.407664 -272.314924)
		(end 384.392932 -272.32356)
		(width 0.088646)
		(layer "In11.Cu")
		(net "M_H_CPU0_SA_DQ<20>")
	)
	(segment
		(start 423.063416 -296.181526)
		(end 422.455086 -296.181526)
		(width 0.18288)
		(layer "In11.Cu")
		(net "M_H_CPU0_SA_DQ<20>")
	)
	(segment
		(start 404.13305 -290.654232)
		(end 403.860254 -290.654232)
		(width 0.18288)
		(layer "In11.Cu")
		(net "M_H_CPU0_SA_DQ<20>")
	)
	(segment
		(start 422.295066 -296.341546)
		(end 422.295066 -296.68343)
		(width 0.18288)
		(layer "In11.Cu")
		(net "M_H_CPU0_SA_DQ<20>")
	)
	(segment
		(start 423.384218 -296.502328)
		(end 423.063416 -296.181526)
		(width 0.18288)
		(layer "In11.Cu")
		(net "M_H_CPU0_SA_DQ<20>")
	)
	(segment
		(start 403.100286 -290.691824)
		(end 403.100286 -290.419028)
		(width 0.18288)
		(layer "In11.Cu")
		(net "M_H_CPU0_SA_DQ<20>")
	)
	(segment
		(start 444.655448 -294.062404)
		(end 444.123826 -294.594026)
		(width 0.18288)
		(layer "In11.Cu")
		(net "M_H_CPU0_SA_DQ<20>")
	)
	(segment
		(start 404.320248 -291.911786)
		(end 404.095458 -291.686996)
		(width 0.18288)
		(layer "In11.Cu")
		(net "M_H_CPU0_SA_DQ<20>")
	)
	(segment
		(start 433.934362 -295.585896)
		(end 433.934362 -295.875456)
		(width 0.18288)
		(layer "In11.Cu")
		(net "M_H_CPU0_SA_DQ<20>")
	)
	(segment
		(start 429.448976 -295.248838)
		(end 428.545752 -296.152062)
		(width 0.18288)
		(layer "In11.Cu")
		(net "M_H_CPU0_SA_DQ<20>")
	)
	(segment
		(start 436.742586 -295.232836)
		(end 436.41264 -295.232836)
		(width 0.18288)
		(layer "In11.Cu")
		(net "M_H_CPU0_SA_DQ<20>")
	)
	(segment
		(start 404.855426 -291.649404)
		(end 404.593044 -291.911786)
		(width 0.18288)
		(layer "In11.Cu")
		(net "M_H_CPU0_SA_DQ<20>")
	)
	(segment
		(start 403.100286 -290.419028)
		(end 403.362668 -290.156646)
		(width 0.18288)
		(layer "In11.Cu")
		(net "M_H_CPU0_SA_DQ<20>")
	)
	(segment
		(start 435.43982 -295.392856)
		(end 434.127402 -295.392856)
		(width 0.18288)
		(layer "In11.Cu")
		(net "M_H_CPU0_SA_DQ<20>")
	)
	(segment
		(start 416.462718 -295.316402)
		(end 416.27171 -295.50741)
		(width 0.18288)
		(layer "In11.Cu")
		(net "M_H_CPU0_SA_DQ<20>")
	)
	(segment
		(start 414.497266 -294.531034)
		(end 414.203388 -294.409114)
		(width 0.18288)
		(layer "In11.Cu")
		(net "M_H_CPU0_SA_DQ<20>")
	)
	(segment
		(start 419.931342 -296.924476)
		(end 419.011608 -296.924476)
		(width 0.18288)
		(layer "In11.Cu")
		(net "M_H_CPU0_SA_DQ<20>")
	)
	(segment
		(start 438.32399 -296.342308)
		(end 438.103264 -296.121582)
		(width 0.18288)
		(layer "In11.Cu")
		(net "M_H_CPU0_SA_DQ<20>")
	)
	(segment
		(start 385.347464 -272.314924)
		(end 385.332732 -272.32356)
		(width 0.088646)
		(layer "In11.Cu")
		(net "M_H_CPU0_SA_DQ<20>")
	)
	(segment
		(start 412.711392 -294.648128)
		(end 411.714188 -294.648128)
		(width 0.18288)
		(layer "In11.Cu")
		(net "M_H_CPU0_SA_DQ<20>")
	)
	(segment
		(start 381.588264 -272.314924)
		(end 381.573532 -272.32356)
		(width 0.088646)
		(layer "In11.Cu")
		(net "M_H_CPU0_SA_DQ<20>")
	)
	(segment
		(start 433.230782 -295.875456)
		(end 433.230782 -295.585896)
		(width 0.18288)
		(layer "In11.Cu")
		(net "M_H_CPU0_SA_DQ<20>")
	)
	(segment
		(start 430.15662 -295.49979)
		(end 429.905668 -295.248838)
		(width 0.18288)
		(layer "In11.Cu")
		(net "M_H_CPU0_SA_DQ<20>")
	)
	(segment
		(start 408.141678 -292.95979)
		(end 407.015442 -292.95979)
		(width 0.18288)
		(layer "In11.Cu")
		(net "M_H_CPU0_SA_DQ<20>")
	)
	(segment
		(start 378.861066 -270.213074)
		(end 378.861066 -270.19758)
		(width 0.088646)
		(layer "In11.Cu")
		(net "M_H_CPU0_SA_DQ<20>")
	)
	(segment
		(start 434.127402 -295.392856)
		(end 433.934362 -295.585896)
		(width 0.18288)
		(layer "In11.Cu")
		(net "M_H_CPU0_SA_DQ<20>")
	)
	(segment
		(start 413.632142 -294.780462)
		(end 412.9913 -294.514778)
		(width 0.18288)
		(layer "In11.Cu")
		(net "M_H_CPU0_SA_DQ<20>")
	)
	(segment
		(start 403.325076 -290.916614)
		(end 403.100286 -290.691824)
		(width 0.18288)
		(layer "In11.Cu")
		(net "M_H_CPU0_SA_DQ<20>")
	)
	(segment
		(start 403.362668 -289.88385)
		(end 403.16531 -289.686492)
		(width 0.18288)
		(layer "In11.Cu")
		(net "M_H_CPU0_SA_DQ<20>")
	)
	(segment
		(start 422.295066 -296.68343)
		(end 421.78605 -297.192446)
		(width 0.18288)
		(layer "In11.Cu")
		(net "M_H_CPU0_SA_DQ<20>")
	)
	(segment
		(start 385.937506 -272.511266)
		(end 385.800092 -272.373852)
		(width 0.088646)
		(layer "In11.Cu")
		(net "M_H_CPU0_SA_DQ<20>")
	)
	(segment
		(start 441.040012 -296.342308)
		(end 439.552588 -296.342308)
		(width 0.18288)
		(layer "In11.Cu")
		(net "M_H_CPU0_SA_DQ<20>")
	)
	(segment
		(start 433.44592 -296.090594)
		(end 433.230782 -295.875456)
		(width 0.18288)
		(layer "In11.Cu")
		(net "M_H_CPU0_SA_DQ<20>")
	)
	(segment
		(start 425.68876 -296.759376)
		(end 425.271692 -296.342308)
		(width 0.18288)
		(layer "In11.Cu")
		(net "M_H_CPU0_SA_DQ<20>")
	)
	(segment
		(start 444.655448 -293.704772)
		(end 444.655448 -294.062404)
		(width 0.18288)
		(layer "In11.Cu")
		(net "M_H_CPU0_SA_DQ<20>")
	)
	(segment
		(start 378.682504 -269.878302)
		(end 378.673614 -269.873222)
		(width 0.088646)
		(layer "In11.Cu")
		(net "M_H_CPU0_SA_DQ<20>")
	)
	(segment
		(start 438.849008 -296.952924)
		(end 438.655968 -296.759884)
		(width 0.18288)
		(layer "In11.Cu")
		(net "M_H_CPU0_SA_DQ<20>")
	)
	(segment
		(start 408.92984 -293.747952)
		(end 408.141678 -292.95979)
		(width 0.18288)
		(layer "In11.Cu")
		(net "M_H_CPU0_SA_DQ<20>")
	)
	(segment
		(start 371.68328 -269.678404)
		(end 371.594126 -269.654528)
		(width 0.088646)
		(layer "In11.Cu")
		(net "M_H_CPU0_SA_DQ<20>")
	)
	(segment
		(start 372.190264 -269.707868)
		(end 372.175532 -269.699232)
		(width 0.088646)
		(layer "In11.Cu")
		(net "M_H_CPU0_SA_DQ<20>")
	)
	(segment
		(start 449.147184 -291.91585)
		(end 448.954144 -292.10889)
		(width 0.18288)
		(layer "In11.Cu")
		(net "M_H_CPU0_SA_DQ<20>")
	)
	(segment
		(start 433.934362 -295.875456)
		(end 433.719224 -296.090594)
		(width 0.18288)
		(layer "In11.Cu")
		(net "M_H_CPU0_SA_DQ<20>")
	)
	(segment
		(start 427.7741 -296.152062)
		(end 427.57598 -296.350182)
		(width 0.18288)
		(layer "In11.Cu")
		(net "M_H_CPU0_SA_DQ<20>")
	)
	(segment
		(start 426.371004 -296.350182)
		(end 425.96181 -296.759376)
		(width 0.18288)
		(layer "In11.Cu")
		(net "M_H_CPU0_SA_DQ<20>")
	)
	(segment
		(start 407.015442 -292.95979)
		(end 405.965406 -291.909754)
		(width 0.18288)
		(layer "In11.Cu")
		(net "M_H_CPU0_SA_DQ<20>")
	)
	(segment
		(start 442.365892 -295.372028)
		(end 442.010292 -295.372028)
		(width 0.18288)
		(layer "In11.Cu")
		(net "M_H_CPU0_SA_DQ<20>")
	)
	(segment
		(start 379.800612 -271.839436)
		(end 379.800612 -271.816576)
		(width 0.088646)
		(layer "In11.Cu")
		(net "M_H_CPU0_SA_DQ<20>")
	)
	(segment
		(start 387.04774 -273.907504)
		(end 385.937506 -272.79727)
		(width 0.088646)
		(layer "In11.Cu")
		(net "M_H_CPU0_SA_DQ<20>")
	)
	(segment
		(start 403.16531 -289.686492)
		(end 403.16531 -289.16376)
		(width 0.18288)
		(layer "In11.Cu")
		(net "M_H_CPU0_SA_DQ<20>")
	)
	(segment
		(start 429.905668 -295.248838)
		(end 429.448976 -295.248838)
		(width 0.18288)
		(layer "In11.Cu")
		(net "M_H_CPU0_SA_DQ<20>")
	)
	(segment
		(start 446.814194 -292.866826)
		(end 446.153794 -293.527226)
		(width 0.18288)
		(layer "In11.Cu")
		(net "M_H_CPU0_SA_DQ<20>")
	)
	(segment
		(start 376.329956 -269.062708)
		(end 376.32386 -269.059152)
		(width 0.088646)
		(layer "In11.Cu")
		(net "M_H_CPU0_SA_DQ<20>")
	)
	(segment
		(start 412.9913 -294.514778)
		(end 412.844742 -294.514778)
		(width 0.18288)
		(layer "In11.Cu")
		(net "M_H_CPU0_SA_DQ<20>")
	)
	(segment
		(start 425.271692 -296.342308)
		(end 424.045126 -296.342308)
		(width 0.18288)
		(layer "In11.Cu")
		(net "M_H_CPU0_SA_DQ<20>")
	)
	(segment
		(start 442.010292 -295.372028)
		(end 441.040012 -296.342308)
		(width 0.18288)
		(layer "In11.Cu")
		(net "M_H_CPU0_SA_DQ<20>")
	)
	(segment
		(start 446.153794 -293.527226)
		(end 444.832994 -293.527226)
		(width 0.18288)
		(layer "In11.Cu")
		(net "M_H_CPU0_SA_DQ<20>")
	)
	(segment
		(start 375.009918 -269.059152)
		(end 375.00941 -269.059152)
		(width 0.088646)
		(layer "In11.Cu")
		(net "M_H_CPU0_SA_DQ<20>")
	)
	(segment
		(start 414.203388 -294.409114)
		(end 413.951674 -294.513254)
		(width 0.18288)
		(layer "In11.Cu")
		(net "M_H_CPU0_SA_DQ<20>")
	)
	(segment
		(start 403.362668 -290.156646)
		(end 403.362668 -289.88385)
		(width 0.18288)
		(layer "In11.Cu")
		(net "M_H_CPU0_SA_DQ<20>")
	)
	(segment
		(start 444.832994 -293.527226)
		(end 444.655448 -293.704772)
		(width 0.18288)
		(layer "In11.Cu")
		(net "M_H_CPU0_SA_DQ<20>")
	)
	(segment
		(start 405.128222 -291.649404)
		(end 404.855426 -291.649404)
		(width 0.18288)
		(layer "In11.Cu")
		(net "M_H_CPU0_SA_DQ<20>")
	)
	(segment
		(start 404.35784 -290.879022)
		(end 404.13305 -290.654232)
		(width 0.18288)
		(layer "In11.Cu")
		(net "M_H_CPU0_SA_DQ<20>")
	)
	(segment
		(start 450.911214 -291.666676)
		(end 450.32676 -291.666676)
		(width 0.18288)
		(layer "In11.Cu")
		(net "M_H_CPU0_SA_DQ<20>")
	)
	(segment
		(start 373.130064 -269.707868)
		(end 373.115332 -269.699232)
		(width 0.088646)
		(layer "In11.Cu")
		(net "M_H_CPU0_SA_DQ<20>")
	)
	(segment
		(start 387.265672 -273.907504)
		(end 387.04774 -273.907504)
		(width 0.088646)
		(layer "In11.Cu")
		(net "M_H_CPU0_SA_DQ<20>")
	)
	(segment
		(start 413.951674 -294.513254)
		(end 413.88411 -294.675814)
		(width 0.18288)
		(layer "In11.Cu")
		(net "M_H_CPU0_SA_DQ<20>")
	)
	(segment
		(start 404.35784 -291.151818)
		(end 404.35784 -290.879022)
		(width 0.18288)
		(layer "In11.Cu")
		(net "M_H_CPU0_SA_DQ<20>")
	)
	(segment
		(start 439.359548 -296.759884)
		(end 439.166508 -296.952924)
		(width 0.18288)
		(layer "In11.Cu")
		(net "M_H_CPU0_SA_DQ<20>")
	)
	(segment
		(start 413.88411 -294.675814)
		(end 413.632142 -294.780462)
		(width 0.18288)
		(layer "In11.Cu")
		(net "M_H_CPU0_SA_DQ<20>")
	)
	(segment
		(start 449.450714 -291.215826)
		(end 449.147184 -291.519356)
		(width 0.18288)
		(layer "In11.Cu")
		(net "M_H_CPU0_SA_DQ<20>")
	)
	(segment
		(start 379.613414 -271.500854)
		(end 379.607318 -271.497298)
		(width 0.088646)
		(layer "In11.Cu")
		(net "M_H_CPU0_SA_DQ<20>")
	)
	(segment
		(start 448.444366 -292.10889)
		(end 447.68643 -292.866826)
		(width 0.18288)
		(layer "In11.Cu")
		(net "M_H_CPU0_SA_DQ<20>")
	)
	(segment
		(start 380.093728 -272.32102)
		(end 380.083314 -272.314924)
		(width 0.088646)
		(layer "In11.Cu")
		(net "M_H_CPU0_SA_DQ<20>")
	)
	(segment
		(start 387.909054 -273.907504)
		(end 387.265672 -273.907504)
		(width 0.18288)
		(layer "In11.Cu")
		(net "M_H_CPU0_SA_DQ<20>")
	)
	(segment
		(start 378.21235 -269.064232)
		(end 378.20346 -269.059152)
		(width 0.088646)
		(layer "In11.Cu")
		(net "M_H_CPU0_SA_DQ<20>")
	)
	(segment
		(start 433.719224 -296.090594)
		(end 433.44592 -296.090594)
		(width 0.18288)
		(layer "In11.Cu")
		(net "M_H_CPU0_SA_DQ<20>")
	)
	(segment
		(start 373.51335 -269.702788)
		(end 373.50446 -269.707868)
		(width 0.088646)
		(layer "In11.Cu")
		(net "M_H_CPU0_SA_DQ<20>")
	)
	(segment
		(start 378.390912 -269.397734)
		(end 378.390912 -269.38351)
		(width 0.088646)
		(layer "In11.Cu")
		(net "M_H_CPU0_SA_DQ<20>")
	)
	(segment
		(start 439.552588 -296.342308)
		(end 439.359548 -296.535348)
		(width 0.18288)
		(layer "In11.Cu")
		(net "M_H_CPU0_SA_DQ<20>")
	)
	(segment
		(start 411.714188 -294.648128)
		(end 410.814012 -293.747952)
		(width 0.18288)
		(layer "In11.Cu")
		(net "M_H_CPU0_SA_DQ<20>")
	)
	(segment
		(start 414.985454 -295.340786)
		(end 414.638998 -295.197276)
		(width 0.18288)
		(layer "In11.Cu")
		(net "M_H_CPU0_SA_DQ<20>")
	)
	(segment
		(start 437.631332 -296.121582)
		(end 436.742586 -295.232836)
		(width 0.18288)
		(layer "In11.Cu")
		(net "M_H_CPU0_SA_DQ<20>")
	)
	(segment
		(start 438.103264 -296.121582)
		(end 437.631332 -296.121582)
		(width 0.18288)
		(layer "In11.Cu")
		(net "M_H_CPU0_SA_DQ<20>")
	)
	(segment
		(start 377.829064 -269.059152)
		(end 377.814332 -269.067788)
		(width 0.088646)
		(layer "In11.Cu")
		(net "M_H_CPU0_SA_DQ<20>")
	)
	(segment
		(start 414.60166 -294.782748)
		(end 414.497266 -294.531034)
		(width 0.18288)
		(layer "In11.Cu")
		(net "M_H_CPU0_SA_DQ<20>")
	)
	(segment
		(start 403.860254 -290.654232)
		(end 403.597872 -290.916614)
		(width 0.18288)
		(layer "In11.Cu")
		(net "M_H_CPU0_SA_DQ<20>")
	)
	(segment
		(start 425.96181 -296.759376)
		(end 425.68876 -296.759376)
		(width 0.18288)
		(layer "In11.Cu")
		(net "M_H_CPU0_SA_DQ<20>")
	)
	(segment
		(start 436.41264 -295.232836)
		(end 436.153052 -295.492424)
		(width 0.18288)
		(layer "In11.Cu")
		(net "M_H_CPU0_SA_DQ<20>")
	)
	(segment
		(start 416.27171 -295.50741)
		(end 415.152078 -295.50741)
		(width 0.18288)
		(layer "In11.Cu")
		(net "M_H_CPU0_SA_DQ<20>")
	)
	(segment
		(start 431.97653 -295.49979)
		(end 430.15662 -295.49979)
		(width 0.18288)
		(layer "In11.Cu")
		(net "M_H_CPU0_SA_DQ<20>")
	)
	(segment
		(start 385.937506 -272.79727)
		(end 385.937506 -272.511266)
		(width 0.088646)
		(layer "In11.Cu")
		(net "M_H_CPU0_SA_DQ<20>")
	)
	(segment
		(start 428.545752 -296.152062)
		(end 427.7741 -296.152062)
		(width 0.18288)
		(layer "In11.Cu")
		(net "M_H_CPU0_SA_DQ<20>")
	)
	(segment
		(start 439.166508 -296.952924)
		(end 438.849008 -296.952924)
		(width 0.18288)
		(layer "In11.Cu")
		(net "M_H_CPU0_SA_DQ<20>")
	)
	(segment
		(start 414.53435 -294.945308)
		(end 414.60166 -294.782748)
		(width 0.18288)
		(layer "In11.Cu")
		(net "M_H_CPU0_SA_DQ<20>")
	)
	(segment
		(start 412.844742 -294.514778)
		(end 412.711392 -294.648128)
		(width 0.18288)
		(layer "In11.Cu")
		(net "M_H_CPU0_SA_DQ<20>")
	)
	(segment
		(start 405.965406 -291.909754)
		(end 405.38908 -291.909754)
		(width 0.18288)
		(layer "In11.Cu")
		(net "M_H_CPU0_SA_DQ<20>")
	)
	(segment
		(start 404.095458 -291.4142)
		(end 404.35784 -291.151818)
		(width 0.18288)
		(layer "In11.Cu")
		(net "M_H_CPU0_SA_DQ<20>")
	)
	(segment
		(start 421.78605 -297.192446)
		(end 420.199312 -297.192446)
		(width 0.18288)
		(layer "In11.Cu")
		(net "M_H_CPU0_SA_DQ<20>")
	)
	(segment
		(start 404.095458 -291.686996)
		(end 404.095458 -291.4142)
		(width 0.18288)
		(layer "In11.Cu")
		(net "M_H_CPU0_SA_DQ<20>")
	)
	(segment
		(start 371.594126 -269.654528)
		(end 371.437662 -269.38351)
		(width 0.088646)
		(layer "In11.Cu")
		(net "M_H_CPU0_SA_DQ<20>")
	)
	(segment
		(start 438.462928 -296.342308)
		(end 438.32399 -296.342308)
		(width 0.18288)
		(layer "In11.Cu")
		(net "M_H_CPU0_SA_DQ<20>")
	)
	(segment
		(start 450.32676 -291.666676)
		(end 449.87591 -291.215826)
		(width 0.18288)
		(layer "In11.Cu")
		(net "M_H_CPU0_SA_DQ<20>")
	)
	(segment
		(start 447.68643 -292.866826)
		(end 446.814194 -292.866826)
		(width 0.18288)
		(layer "In11.Cu")
		(net "M_H_CPU0_SA_DQ<20>")
	)
	(segment
		(start 448.954144 -292.10889)
		(end 448.444366 -292.10889)
		(width 0.18288)
		(layer "In11.Cu")
		(net "M_H_CPU0_SA_DQ<20>")
	)
	(segment
		(start 439.359548 -296.535348)
		(end 439.359548 -296.759884)
		(width 0.18288)
		(layer "In11.Cu")
		(net "M_H_CPU0_SA_DQ<20>")
	)
	(segment
		(start 444.123826 -294.594026)
		(end 443.143894 -294.594026)
		(width 0.18288)
		(layer "In11.Cu")
		(net "M_H_CPU0_SA_DQ<20>")
	)
	(segment
		(start 433.037742 -295.392856)
		(end 432.083464 -295.392856)
		(width 0.18288)
		(layer "In11.Cu")
		(net "M_H_CPU0_SA_DQ<20>")
	)
	(segment
		(start 419.011608 -296.924476)
		(end 417.403534 -295.316402)
		(width 0.18288)
		(layer "In11.Cu")
		(net "M_H_CPU0_SA_DQ<20>")
	)
	(segment
		(start 432.083464 -295.392856)
		(end 431.97653 -295.49979)
		(width 0.18288)
		(layer "In11.Cu")
		(net "M_H_CPU0_SA_DQ<20>")
	)
	(segment
		(start 427.57598 -296.350182)
		(end 426.371004 -296.350182)
		(width 0.18288)
		(layer "In11.Cu")
		(net "M_H_CPU0_SA_DQ<20>")
	)
	(segment
		(start 438.655968 -296.759884)
		(end 438.655968 -296.535348)
		(width 0.18288)
		(layer "In11.Cu")
		(net "M_H_CPU0_SA_DQ<20>")
	)
	(segment
		(start 443.143894 -294.594026)
		(end 442.365892 -295.372028)
		(width 0.18288)
		(layer "In11.Cu")
		(net "M_H_CPU0_SA_DQ<20>")
	)
	(segment
		(start 424.045126 -296.342308)
		(end 423.885106 -296.502328)
		(width 0.18288)
		(layer "In11.Cu")
		(net "M_H_CPU0_SA_DQ<20>")
	)
	(segment
		(start 435.539388 -295.492424)
		(end 435.43982 -295.392856)
		(width 0.18288)
		(layer "In11.Cu")
		(net "M_H_CPU0_SA_DQ<20>")
	)
	(segment
		(start 423.885106 -296.502328)
		(end 423.384218 -296.502328)
		(width 0.18288)
		(layer "In11.Cu")
		(net "M_H_CPU0_SA_DQ<20>")
	)
	(segment
		(start 403.16531 -289.16376)
		(end 387.909054 -273.907504)
		(width 0.18288)
		(layer "In11.Cu")
		(net "M_H_CPU0_SA_DQ<20>")
	)
	(segment
		(start 383.467864 -272.314924)
		(end 383.453132 -272.32356)
		(width 0.088646)
		(layer "In11.Cu")
		(net "M_H_CPU0_SA_DQ<20>")
	)
	(segment
		(start 422.455086 -296.181526)
		(end 422.295066 -296.341546)
		(width 0.18288)
		(layer "In11.Cu")
		(net "M_H_CPU0_SA_DQ<20>")
	)
	(segment
		(start 414.638998 -295.197276)
		(end 414.53435 -294.945308)
		(width 0.18288)
		(layer "In11.Cu")
		(net "M_H_CPU0_SA_DQ<20>")
	)
	(segment
		(start 375.949464 -269.059152)
		(end 375.94921 -269.059152)
		(width 0.088646)
		(layer "In11.Cu")
		(net "M_H_CPU0_SA_DQ<20>")
	)
	(segment
		(start 449.87591 -291.215826)
		(end 449.450714 -291.215826)
		(width 0.18288)
		(layer "In11.Cu")
		(net "M_H_CPU0_SA_DQ<20>")
	)
	(segment
		(start 415.152078 -295.50741)
		(end 414.985454 -295.340786)
		(width 0.18288)
		(layer "In11.Cu")
		(net "M_H_CPU0_SA_DQ<20>")
	)
	(arc
		(start 379.330712 -271.011396)
		(mid 379.283033 -270.828496)
		(end 379.15215 -270.692118)
		(width 0.088646)
		(layer "In11.Cu")
		(net "M_H_CPU0_SA_DQ<20>")
	)
	(arc
		(start 373.620538 -269.60322)
		(mid 373.572701 -269.659202)
		(end 373.51335 -269.702788)
		(width 0.088646)
		(layer "In11.Cu")
		(net "M_H_CPU0_SA_DQ<20>")
	)
	(arc
		(start 383.453132 -272.32356)
		(mid 383.176691 -272.390726)
		(end 382.90246 -272.314924)
		(width 0.088646)
		(layer "In11.Cu")
		(net "M_H_CPU0_SA_DQ<20>")
	)
	(arc
		(start 381.02286 -272.314924)
		(mid 380.835662 -272.264781)
		(end 380.648464 -272.314924)
		(width 0.088646)
		(layer "In11.Cu")
		(net "M_H_CPU0_SA_DQ<20>")
	)
	(arc
		(start 382.90246 -272.314924)
		(mid 382.715262 -272.264781)
		(end 382.528064 -272.314924)
		(width 0.088646)
		(layer "In11.Cu")
		(net "M_H_CPU0_SA_DQ<20>")
	)
	(arc
		(start 376.889264 -269.059152)
		(mid 376.61009 -269.134917)
		(end 376.329956 -269.062708)
		(width 0.088646)
		(layer "In11.Cu")
		(net "M_H_CPU0_SA_DQ<20>")
	)
	(arc
		(start 384.392932 -272.32356)
		(mid 384.116491 -272.390726)
		(end 383.84226 -272.314924)
		(width 0.088646)
		(layer "In11.Cu")
		(net "M_H_CPU0_SA_DQ<20>")
	)
	(arc
		(start 373.115332 -269.699232)
		(mid 372.838891 -269.632066)
		(end 372.56466 -269.707868)
		(width 0.088646)
		(layer "In11.Cu")
		(net "M_H_CPU0_SA_DQ<20>")
	)
	(arc
		(start 385.800092 -272.373852)
		(mid 385.762901 -272.341834)
		(end 385.72186 -272.314924)
		(width 0.088646)
		(layer "In11.Cu")
		(net "M_H_CPU0_SA_DQ<20>")
	)
	(arc
		(start 380.083314 -272.314924)
		(mid 379.879833 -272.11412)
		(end 379.800612 -271.839436)
		(width 0.088646)
		(layer "In11.Cu")
		(net "M_H_CPU0_SA_DQ<20>")
	)
	(arc
		(start 372.175532 -269.699232)
		(mid 371.931788 -269.632383)
		(end 371.68328 -269.678404)
		(width 0.088646)
		(layer "In11.Cu")
		(net "M_H_CPU0_SA_DQ<20>")
	)
	(arc
		(start 384.78206 -272.314924)
		(mid 384.594862 -272.264781)
		(end 384.407664 -272.314924)
		(width 0.088646)
		(layer "In11.Cu")
		(net "M_H_CPU0_SA_DQ<20>")
	)
	(arc
		(start 378.861066 -270.19758)
		(mid 378.813387 -270.01468)
		(end 378.682504 -269.878302)
		(width 0.088646)
		(layer "In11.Cu")
		(net "M_H_CPU0_SA_DQ<20>")
	)
	(arc
		(start 381.573532 -272.32356)
		(mid 381.297091 -272.390726)
		(end 381.02286 -272.314924)
		(width 0.088646)
		(layer "In11.Cu")
		(net "M_H_CPU0_SA_DQ<20>")
	)
	(arc
		(start 374.069864 -269.059152)
		(mid 373.961008 -269.131846)
		(end 373.8626 -269.218156)
		(width 0.088646)
		(layer "In11.Cu")
		(net "M_H_CPU0_SA_DQ<20>")
	)
	(arc
		(start 373.689372 -269.425928)
		(mid 373.666406 -269.519022)
		(end 373.620538 -269.60322)
		(width 0.088646)
		(layer "In11.Cu")
		(net "M_H_CPU0_SA_DQ<20>")
	)
	(arc
		(start 373.50446 -269.707868)
		(mid 373.317262 -269.758011)
		(end 373.130064 -269.707868)
		(width 0.088646)
		(layer "In11.Cu")
		(net "M_H_CPU0_SA_DQ<20>")
	)
	(arc
		(start 375.00941 -269.059152)
		(mid 374.726852 -269.134801)
		(end 374.44426 -269.059152)
		(width 0.088646)
		(layer "In11.Cu")
		(net "M_H_CPU0_SA_DQ<20>")
	)
	(arc
		(start 379.800612 -271.816576)
		(mid 379.748342 -271.634211)
		(end 379.613414 -271.500854)
		(width 0.088646)
		(layer "In11.Cu")
		(net "M_H_CPU0_SA_DQ<20>")
	)
	(arc
		(start 378.390912 -269.38351)
		(mid 378.343233 -269.20061)
		(end 378.21235 -269.064232)
		(width 0.088646)
		(layer "In11.Cu")
		(net "M_H_CPU0_SA_DQ<20>")
	)
	(arc
		(start 381.96266 -272.314924)
		(mid 381.775462 -272.264781)
		(end 381.588264 -272.314924)
		(width 0.088646)
		(layer "In11.Cu")
		(net "M_H_CPU0_SA_DQ<20>")
	)
	(arc
		(start 377.26366 -269.059152)
		(mid 377.076606 -269.009102)
		(end 376.889518 -269.059152)
		(width 0.088646)
		(layer "In11.Cu")
		(net "M_H_CPU0_SA_DQ<20>")
	)
	(arc
		(start 378.673614 -269.873222)
		(mid 378.470133 -269.672418)
		(end 378.390912 -269.397734)
		(width 0.088646)
		(layer "In11.Cu")
		(net "M_H_CPU0_SA_DQ<20>")
	)
	(arc
		(start 378.20346 -269.059152)
		(mid 378.016262 -269.009009)
		(end 377.829064 -269.059152)
		(width 0.088646)
		(layer "In11.Cu")
		(net "M_H_CPU0_SA_DQ<20>")
	)
	(arc
		(start 379.607318 -271.497298)
		(mid 379.404731 -271.290947)
		(end 379.330712 -271.011396)
		(width 0.088646)
		(layer "In11.Cu")
		(net "M_H_CPU0_SA_DQ<20>")
	)
	(arc
		(start 379.14326 -270.687038)
		(mid 378.940437 -270.486807)
		(end 378.861066 -270.213074)
		(width 0.088646)
		(layer "In11.Cu")
		(net "M_H_CPU0_SA_DQ<20>")
	)
	(arc
		(start 372.56466 -269.707868)
		(mid 372.377462 -269.758011)
		(end 372.190264 -269.707868)
		(width 0.088646)
		(layer "In11.Cu")
		(net "M_H_CPU0_SA_DQ<20>")
	)
	(arc
		(start 374.44426 -269.059152)
		(mid 374.257062 -269.009009)
		(end 374.069864 -269.059152)
		(width 0.088646)
		(layer "In11.Cu")
		(net "M_H_CPU0_SA_DQ<20>")
	)
	(arc
		(start 375.38406 -269.059152)
		(mid 375.197006 -269.009102)
		(end 375.009918 -269.059152)
		(width 0.088646)
		(layer "In11.Cu")
		(net "M_H_CPU0_SA_DQ<20>")
	)
	(arc
		(start 382.513332 -272.32356)
		(mid 382.236891 -272.390726)
		(end 381.96266 -272.314924)
		(width 0.088646)
		(layer "In11.Cu")
		(net "M_H_CPU0_SA_DQ<20>")
	)
	(arc
		(start 380.648464 -272.314924)
		(mid 380.371905 -272.390633)
		(end 380.093728 -272.32102)
		(width 0.088646)
		(layer "In11.Cu")
		(net "M_H_CPU0_SA_DQ<20>")
	)
	(arc
		(start 375.94921 -269.059152)
		(mid 375.666652 -269.134801)
		(end 375.38406 -269.059152)
		(width 0.088646)
		(layer "In11.Cu")
		(net "M_H_CPU0_SA_DQ<20>")
	)
	(arc
		(start 376.32386 -269.059152)
		(mid 376.136662 -269.009009)
		(end 375.949464 -269.059152)
		(width 0.088646)
		(layer "In11.Cu")
		(net "M_H_CPU0_SA_DQ<20>")
	)
	(arc
		(start 385.332732 -272.32356)
		(mid 385.056291 -272.390726)
		(end 384.78206 -272.314924)
		(width 0.088646)
		(layer "In11.Cu")
		(net "M_H_CPU0_SA_DQ<20>")
	)
	(arc
		(start 377.814332 -269.067788)
		(mid 377.537857 -269.135108)
		(end 377.26366 -269.059152)
		(width 0.088646)
		(layer "In11.Cu")
		(net "M_H_CPU0_SA_DQ<20>")
	)
	(arc
		(start 373.72163 -269.35938)
		(mid 373.699865 -269.389922)
		(end 373.689372 -269.425928)
		(width 0.088646)
		(layer "In11.Cu")
		(net "M_H_CPU0_SA_DQ<20>")
	)
	(arc
		(start 385.72186 -272.314924)
		(mid 385.534662 -272.264781)
		(end 385.347464 -272.314924)
		(width 0.088646)
		(layer "In11.Cu")
		(net "M_H_CPU0_SA_DQ<20>")
	)
	(arc
		(start 383.84226 -272.314924)
		(mid 383.655062 -272.264781)
		(end 383.467864 -272.314924)
		(width 0.088646)
		(layer "In11.Cu")
		(net "M_H_CPU0_SA_DQ<20>")
	)
	(segment
		(start 454.448672 -314.30976)
		(end 454.448672 -314.677298)
		(width 0.20066)
		(layer "F.Cu")
		(net "M_H_CPU0_SA_DQ<1>")
	)
	(segment
		(start 454.448672 -314.677298)
		(end 454.260712 -314.865258)
		(width 0.20066)
		(layer "F.Cu")
		(net "M_H_CPU0_SA_DQ<1>")
	)
	(segment
		(start 457.126594 -314.1853)
		(end 457.120244 -314.19165)
		(width 0.1016)
		(layer "F.Cu")
		(net "M_H_CPU0_SA_DQ<1>")
	)
	(segment
		(start 459.55966 -314.616846)
		(end 457.968096 -314.616846)
		(width 0.20066)
		(layer "F.Cu")
		(net "M_H_CPU0_SA_DQ<1>")
	)
	(segment
		(start 457.53655 -314.1853)
		(end 457.126594 -314.1853)
		(width 0.20066)
		(layer "F.Cu")
		(net "M_H_CPU0_SA_DQ<1>")
	)
	(segment
		(start 453.536812 -314.616592)
		(end 452.016114 -314.616592)
		(width 0.20066)
		(layer "F.Cu")
		(net "M_H_CPU0_SA_DQ<1>")
	)
	(segment
		(start 377.546362 -278.336248)
		(end 377.546616 -278.336502)
		(width 0.20066)
		(layer "F.Cu")
		(net "M_H_CPU0_SA_DQ<1>")
	)
	(segment
		(start 459.559914 -314.616592)
		(end 459.55966 -314.616846)
		(width 0.20066)
		(layer "F.Cu")
		(net "M_H_CPU0_SA_DQ<1>")
	)
	(segment
		(start 457.120244 -314.19165)
		(end 454.931526 -314.19165)
		(width 0.1016)
		(layer "F.Cu")
		(net "M_H_CPU0_SA_DQ<1>")
	)
	(segment
		(start 454.931526 -314.19165)
		(end 454.91146 -314.19165)
		(width 0.101854)
		(layer "F.Cu")
		(net "M_H_CPU0_SA_DQ<1>")
	)
	(segment
		(start 457.968096 -314.616846)
		(end 457.53655 -314.1853)
		(width 0.20066)
		(layer "F.Cu")
		(net "M_H_CPU0_SA_DQ<1>")
	)
	(segment
		(start 454.566782 -314.19165)
		(end 454.448672 -314.30976)
		(width 0.20066)
		(layer "F.Cu")
		(net "M_H_CPU0_SA_DQ<1>")
	)
	(segment
		(start 454.260712 -314.865258)
		(end 453.785478 -314.865258)
		(width 0.20066)
		(layer "F.Cu")
		(net "M_H_CPU0_SA_DQ<1>")
	)
	(segment
		(start 377.546362 -277.800562)
		(end 377.546362 -278.336248)
		(width 0.20066)
		(layer "F.Cu")
		(net "M_H_CPU0_SA_DQ<1>")
	)
	(segment
		(start 452.016114 -314.616592)
		(end 450.911214 -314.616592)
		(width 0.20066)
		(layer "F.Cu")
		(net "M_H_CPU0_SA_DQ<1>")
	)
	(segment
		(start 454.91146 -314.19165)
		(end 454.566782 -314.19165)
		(width 0.20066)
		(layer "F.Cu")
		(net "M_H_CPU0_SA_DQ<1>")
	)
	(segment
		(start 453.785478 -314.865258)
		(end 453.536812 -314.616592)
		(width 0.20066)
		(layer "F.Cu")
		(net "M_H_CPU0_SA_DQ<1>")
	)
	(segment
		(start 437.225694 -314.411614)
		(end 436.594758 -315.04255)
		(width 0.18288)
		(layer "In6.Cu")
		(net "M_H_CPU0_SA_DQ<1>")
	)
	(segment
		(start 446.662556 -313.643264)
		(end 446.006982 -314.298838)
		(width 0.18288)
		(layer "In6.Cu")
		(net "M_H_CPU0_SA_DQ<1>")
	)
	(segment
		(start 449.06819 -312.9915)
		(end 448.88531 -312.80862)
		(width 0.18288)
		(layer "In6.Cu")
		(net "M_H_CPU0_SA_DQ<1>")
	)
	(segment
		(start 445.005968 -313.618626)
		(end 444.786004 -313.398662)
		(width 0.18288)
		(layer "In6.Cu")
		(net "M_H_CPU0_SA_DQ<1>")
	)
	(segment
		(start 403.150578 -305.504088)
		(end 403.150578 -301.301912)
		(width 0.18288)
		(layer "In6.Cu")
		(net "M_H_CPU0_SA_DQ<1>")
	)
	(segment
		(start 441.718446 -313.630818)
		(end 441.158376 -314.190888)
		(width 0.18288)
		(layer "In6.Cu")
		(net "M_H_CPU0_SA_DQ<1>")
	)
	(segment
		(start 410.70022 -308.652672)
		(end 410.543756 -308.496208)
		(width 0.18288)
		(layer "In6.Cu")
		(net "M_H_CPU0_SA_DQ<1>")
	)
	(segment
		(start 445.174116 -314.298838)
		(end 445.005968 -314.13069)
		(width 0.18288)
		(layer "In6.Cu")
		(net "M_H_CPU0_SA_DQ<1>")
	)
	(segment
		(start 432.72456 -313.593226)
		(end 431.96256 -313.593226)
		(width 0.18288)
		(layer "In6.Cu")
		(net "M_H_CPU0_SA_DQ<1>")
	)
	(segment
		(start 412.383986 -309.199026)
		(end 411.874462 -309.199026)
		(width 0.18288)
		(layer "In6.Cu")
		(net "M_H_CPU0_SA_DQ<1>")
	)
	(segment
		(start 422.933876 -309.939944)
		(end 422.081198 -310.792622)
		(width 0.18288)
		(layer "In6.Cu")
		(net "M_H_CPU0_SA_DQ<1>")
	)
	(segment
		(start 444.438024 -313.398662)
		(end 444.240158 -313.596528)
		(width 0.18288)
		(layer "In6.Cu")
		(net "M_H_CPU0_SA_DQ<1>")
	)
	(segment
		(start 407.440892 -306.881276)
		(end 407.280872 -306.721256)
		(width 0.18288)
		(layer "In6.Cu")
		(net "M_H_CPU0_SA_DQ<1>")
	)
	(segment
		(start 443.086236 -314.294774)
		(end 442.42228 -313.630818)
		(width 0.18288)
		(layer "In6.Cu")
		(net "M_H_CPU0_SA_DQ<1>")
	)
	(segment
		(start 381.503428 -278.654764)
		(end 381.493014 -278.66086)
		(width 0.088646)
		(layer "In6.Cu")
		(net "M_H_CPU0_SA_DQ<1>")
	)
	(segment
		(start 387.264402 -280.385266)
		(end 387.115812 -280.385266)
		(width 0.088646)
		(layer "In6.Cu")
		(net "M_H_CPU0_SA_DQ<1>")
	)
	(segment
		(start 418.08781 -310.792622)
		(end 417.819586 -311.060846)
		(width 0.18288)
		(layer "In6.Cu")
		(net "M_H_CPU0_SA_DQ<1>")
	)
	(segment
		(start 410.797756 -307.26126)
		(end 410.571696 -307.26126)
		(width 0.18288)
		(layer "In6.Cu")
		(net "M_H_CPU0_SA_DQ<1>")
	)
	(segment
		(start 416.74669 -310.792622)
		(end 416.016694 -310.062626)
		(width 0.18288)
		(layer "In6.Cu")
		(net "M_H_CPU0_SA_DQ<1>")
	)
	(segment
		(start 435.172358 -315.04255)
		(end 434.939694 -315.275214)
		(width 0.18288)
		(layer "In6.Cu")
		(net "M_H_CPU0_SA_DQ<1>")
	)
	(segment
		(start 386.202428 -280.282396)
		(end 386.192014 -280.288492)
		(width 0.088646)
		(layer "In6.Cu")
		(net "M_H_CPU0_SA_DQ<1>")
	)
	(segment
		(start 409.827222 -307.779674)
		(end 408.768804 -306.721256)
		(width 0.18288)
		(layer "In6.Cu")
		(net "M_H_CPU0_SA_DQ<1>")
	)
	(segment
		(start 419.206426 -311.060846)
		(end 418.78123 -311.060846)
		(width 0.18288)
		(layer "In6.Cu")
		(net "M_H_CPU0_SA_DQ<1>")
	)
	(segment
		(start 387.524752 -280.645616)
		(end 387.264402 -280.385266)
		(width 0.088646)
		(layer "In6.Cu")
		(net "M_H_CPU0_SA_DQ<1>")
	)
	(segment
		(start 406.11171 -307.393594)
		(end 405.040084 -307.393594)
		(width 0.18288)
		(layer "In6.Cu")
		(net "M_H_CPU0_SA_DQ<1>")
	)
	(segment
		(start 450.911214 -314.616592)
		(end 449.937886 -313.643264)
		(width 0.18288)
		(layer "In6.Cu")
		(net "M_H_CPU0_SA_DQ<1>")
	)
	(segment
		(start 410.053282 -307.779674)
		(end 409.827222 -307.779674)
		(width 0.18288)
		(layer "In6.Cu")
		(net "M_H_CPU0_SA_DQ<1>")
	)
	(segment
		(start 413.631888 -309.351172)
		(end 413.631888 -309.125112)
		(width 0.18288)
		(layer "In6.Cu")
		(net "M_H_CPU0_SA_DQ<1>")
	)
	(segment
		(start 417.819586 -311.060846)
		(end 417.39439 -311.060846)
		(width 0.18288)
		(layer "In6.Cu")
		(net "M_H_CPU0_SA_DQ<1>")
	)
	(segment
		(start 411.328108 -308.652672)
		(end 410.70022 -308.652672)
		(width 0.18288)
		(layer "In6.Cu")
		(net "M_H_CPU0_SA_DQ<1>")
	)
	(segment
		(start 414.122362 -309.615586)
		(end 413.896302 -309.615586)
		(width 0.18288)
		(layer "In6.Cu")
		(net "M_H_CPU0_SA_DQ<1>")
	)
	(segment
		(start 438.444894 -314.411614)
		(end 437.225694 -314.411614)
		(width 0.18288)
		(layer "In6.Cu")
		(net "M_H_CPU0_SA_DQ<1>")
	)
	(segment
		(start 385.160012 -279.150318)
		(end 385.160012 -279.140412)
		(width 0.088646)
		(layer "In6.Cu")
		(net "M_H_CPU0_SA_DQ<1>")
	)
	(segment
		(start 445.005968 -314.13069)
		(end 445.005968 -313.618626)
		(width 0.18288)
		(layer "In6.Cu")
		(net "M_H_CPU0_SA_DQ<1>")
	)
	(segment
		(start 444.786004 -313.398662)
		(end 444.438024 -313.398662)
		(width 0.18288)
		(layer "In6.Cu")
		(net "M_H_CPU0_SA_DQ<1>")
	)
	(segment
		(start 431.96256 -313.593226)
		(end 431.207164 -312.83783)
		(width 0.18288)
		(layer "In6.Cu")
		(net "M_H_CPU0_SA_DQ<1>")
	)
	(segment
		(start 408.294332 -306.721256)
		(end 408.134312 -306.881276)
		(width 0.18288)
		(layer "In6.Cu")
		(net "M_H_CPU0_SA_DQ<1>")
	)
	(segment
		(start 414.377124 -309.360824)
		(end 414.122362 -309.615586)
		(width 0.18288)
		(layer "In6.Cu")
		(net "M_H_CPU0_SA_DQ<1>")
	)
	(segment
		(start 434.939694 -315.275214)
		(end 434.406548 -315.275214)
		(width 0.18288)
		(layer "In6.Cu")
		(net "M_H_CPU0_SA_DQ<1>")
	)
	(segment
		(start 422.081198 -310.792622)
		(end 419.47465 -310.792622)
		(width 0.18288)
		(layer "In6.Cu")
		(net "M_H_CPU0_SA_DQ<1>")
	)
	(segment
		(start 395.29639 -293.447724)
		(end 395.29639 -283.891228)
		(width 0.18288)
		(layer "In6.Cu")
		(net "M_H_CPU0_SA_DQ<1>")
	)
	(segment
		(start 385.817618 -280.288492)
		(end 385.808474 -280.283412)
		(width 0.088646)
		(layer "In6.Cu")
		(net "M_H_CPU0_SA_DQ<1>")
	)
	(segment
		(start 411.06217 -307.751734)
		(end 411.06217 -307.525674)
		(width 0.18288)
		(layer "In6.Cu")
		(net "M_H_CPU0_SA_DQ<1>")
	)
	(segment
		(start 448.37477 -313.460384)
		(end 448.19189 -313.643264)
		(width 0.18288)
		(layer "In6.Cu")
		(net "M_H_CPU0_SA_DQ<1>")
	)
	(segment
		(start 442.42228 -313.630818)
		(end 441.718446 -313.630818)
		(width 0.18288)
		(layer "In6.Cu")
		(net "M_H_CPU0_SA_DQ<1>")
	)
	(segment
		(start 410.543756 -308.270148)
		(end 411.06217 -307.751734)
		(width 0.18288)
		(layer "In6.Cu")
		(net "M_H_CPU0_SA_DQ<1>")
	)
	(segment
		(start 431.207164 -312.83783)
		(end 429.999394 -312.83783)
		(width 0.18288)
		(layer "In6.Cu")
		(net "M_H_CPU0_SA_DQ<1>")
	)
	(segment
		(start 444.080138 -314.294774)
		(end 443.086236 -314.294774)
		(width 0.18288)
		(layer "In6.Cu")
		(net "M_H_CPU0_SA_DQ<1>")
	)
	(segment
		(start 378.207524 -278.607266)
		(end 377.917456 -278.437086)
		(width 0.088646)
		(layer "In6.Cu")
		(net "M_H_CPU0_SA_DQ<1>")
	)
	(segment
		(start 408.134312 -306.881276)
		(end 408.134312 -307.208682)
		(width 0.18288)
		(layer "In6.Cu")
		(net "M_H_CPU0_SA_DQ<1>")
	)
	(segment
		(start 393.037822 -281.63266)
		(end 388.307326 -281.63266)
		(width 0.18288)
		(layer "In6.Cu")
		(net "M_H_CPU0_SA_DQ<1>")
	)
	(segment
		(start 429.999394 -312.83783)
		(end 428.913036 -311.751472)
		(width 0.18288)
		(layer "In6.Cu")
		(net "M_H_CPU0_SA_DQ<1>")
	)
	(segment
		(start 434.406548 -315.275214)
		(end 432.72456 -313.593226)
		(width 0.18288)
		(layer "In6.Cu")
		(net "M_H_CPU0_SA_DQ<1>")
	)
	(segment
		(start 407.974292 -307.368702)
		(end 407.600912 -307.368702)
		(width 0.18288)
		(layer "In6.Cu")
		(net "M_H_CPU0_SA_DQ<1>")
	)
	(segment
		(start 378.298964 -278.66086)
		(end 378.207524 -278.607266)
		(width 0.088646)
		(layer "In6.Cu")
		(net "M_H_CPU0_SA_DQ<1>")
	)
	(segment
		(start 413.018986 -308.564026)
		(end 412.383986 -309.199026)
		(width 0.18288)
		(layer "In6.Cu")
		(net "M_H_CPU0_SA_DQ<1>")
	)
	(segment
		(start 407.280872 -306.721256)
		(end 406.784048 -306.721256)
		(width 0.18288)
		(layer "In6.Cu")
		(net "M_H_CPU0_SA_DQ<1>")
	)
	(segment
		(start 438.66562 -314.190888)
		(end 438.444894 -314.411614)
		(width 0.18288)
		(layer "In6.Cu")
		(net "M_H_CPU0_SA_DQ<1>")
	)
	(segment
		(start 413.631888 -309.125112)
		(end 413.88665 -308.87035)
		(width 0.18288)
		(layer "In6.Cu")
		(net "M_H_CPU0_SA_DQ<1>")
	)
	(segment
		(start 406.784048 -306.721256)
		(end 406.11171 -307.393594)
		(width 0.18288)
		(layer "In6.Cu")
		(net "M_H_CPU0_SA_DQ<1>")
	)
	(segment
		(start 436.594758 -315.04255)
		(end 435.172358 -315.04255)
		(width 0.18288)
		(layer "In6.Cu")
		(net "M_H_CPU0_SA_DQ<1>")
	)
	(segment
		(start 395.29639 -283.891228)
		(end 393.037822 -281.63266)
		(width 0.18288)
		(layer "In6.Cu")
		(net "M_H_CPU0_SA_DQ<1>")
	)
	(segment
		(start 408.768804 -306.721256)
		(end 408.294332 -306.721256)
		(width 0.18288)
		(layer "In6.Cu")
		(net "M_H_CPU0_SA_DQ<1>")
	)
	(segment
		(start 428.913036 -311.751472)
		(end 427.682406 -311.751472)
		(width 0.18288)
		(layer "In6.Cu")
		(net "M_H_CPU0_SA_DQ<1>")
	)
	(segment
		(start 449.06819 -313.460384)
		(end 449.06819 -312.9915)
		(width 0.18288)
		(layer "In6.Cu")
		(net "M_H_CPU0_SA_DQ<1>")
	)
	(segment
		(start 407.440892 -307.208682)
		(end 407.440892 -306.881276)
		(width 0.18288)
		(layer "In6.Cu")
		(net "M_H_CPU0_SA_DQ<1>")
	)
	(segment
		(start 410.571696 -307.26126)
		(end 410.053282 -307.779674)
		(width 0.18288)
		(layer "In6.Cu")
		(net "M_H_CPU0_SA_DQ<1>")
	)
	(segment
		(start 378.683774 -278.654764)
		(end 378.67336 -278.66086)
		(width 0.088646)
		(layer "In6.Cu")
		(net "M_H_CPU0_SA_DQ<1>")
	)
	(segment
		(start 403.150578 -301.301912)
		(end 395.29639 -293.447724)
		(width 0.18288)
		(layer "In6.Cu")
		(net "M_H_CPU0_SA_DQ<1>")
	)
	(segment
		(start 388.307326 -281.63266)
		(end 388.00405 -281.63266)
		(width 0.088646)
		(layer "In6.Cu")
		(net "M_H_CPU0_SA_DQ<1>")
	)
	(segment
		(start 408.134312 -307.208682)
		(end 407.974292 -307.368702)
		(width 0.18288)
		(layer "In6.Cu")
		(net "M_H_CPU0_SA_DQ<1>")
	)
	(segment
		(start 418.513006 -310.792622)
		(end 418.08781 -310.792622)
		(width 0.18288)
		(layer "In6.Cu")
		(net "M_H_CPU0_SA_DQ<1>")
	)
	(segment
		(start 410.543756 -308.496208)
		(end 410.543756 -308.270148)
		(width 0.18288)
		(layer "In6.Cu")
		(net "M_H_CPU0_SA_DQ<1>")
	)
	(segment
		(start 413.896302 -309.615586)
		(end 413.631888 -309.351172)
		(width 0.18288)
		(layer "In6.Cu")
		(net "M_H_CPU0_SA_DQ<1>")
	)
	(segment
		(start 444.240158 -314.134754)
		(end 444.080138 -314.294774)
		(width 0.18288)
		(layer "In6.Cu")
		(net "M_H_CPU0_SA_DQ<1>")
	)
	(segment
		(start 446.006982 -314.298838)
		(end 445.174116 -314.298838)
		(width 0.18288)
		(layer "In6.Cu")
		(net "M_H_CPU0_SA_DQ<1>")
	)
	(segment
		(start 413.88665 -308.87035)
		(end 413.88665 -308.64429)
		(width 0.18288)
		(layer "In6.Cu")
		(net "M_H_CPU0_SA_DQ<1>")
	)
	(segment
		(start 425.870878 -309.939944)
		(end 422.933876 -309.939944)
		(width 0.18288)
		(layer "In6.Cu")
		(net "M_H_CPU0_SA_DQ<1>")
	)
	(segment
		(start 449.937886 -313.643264)
		(end 449.25107 -313.643264)
		(width 0.18288)
		(layer "In6.Cu")
		(net "M_H_CPU0_SA_DQ<1>")
	)
	(segment
		(start 427.682406 -311.751472)
		(end 425.870878 -309.939944)
		(width 0.18288)
		(layer "In6.Cu")
		(net "M_H_CPU0_SA_DQ<1>")
	)
	(segment
		(start 416.016694 -310.062626)
		(end 415.304986 -310.062626)
		(width 0.18288)
		(layer "In6.Cu")
		(net "M_H_CPU0_SA_DQ<1>")
	)
	(segment
		(start 448.88531 -312.80862)
		(end 448.55765 -312.80862)
		(width 0.18288)
		(layer "In6.Cu")
		(net "M_H_CPU0_SA_DQ<1>")
	)
	(segment
		(start 444.240158 -313.596528)
		(end 444.240158 -314.134754)
		(width 0.18288)
		(layer "In6.Cu")
		(net "M_H_CPU0_SA_DQ<1>")
	)
	(segment
		(start 417.39439 -311.060846)
		(end 417.126166 -310.792622)
		(width 0.18288)
		(layer "In6.Cu")
		(net "M_H_CPU0_SA_DQ<1>")
	)
	(segment
		(start 417.126166 -310.792622)
		(end 416.74669 -310.792622)
		(width 0.18288)
		(layer "In6.Cu")
		(net "M_H_CPU0_SA_DQ<1>")
	)
	(segment
		(start 418.78123 -311.060846)
		(end 418.513006 -310.792622)
		(width 0.18288)
		(layer "In6.Cu")
		(net "M_H_CPU0_SA_DQ<1>")
	)
	(segment
		(start 413.806386 -308.564026)
		(end 413.018986 -308.564026)
		(width 0.18288)
		(layer "In6.Cu")
		(net "M_H_CPU0_SA_DQ<1>")
	)
	(segment
		(start 419.47465 -310.792622)
		(end 419.206426 -311.060846)
		(width 0.18288)
		(layer "In6.Cu")
		(net "M_H_CPU0_SA_DQ<1>")
	)
	(segment
		(start 407.600912 -307.368702)
		(end 407.440892 -307.208682)
		(width 0.18288)
		(layer "In6.Cu")
		(net "M_H_CPU0_SA_DQ<1>")
	)
	(segment
		(start 449.25107 -313.643264)
		(end 449.06819 -313.460384)
		(width 0.18288)
		(layer "In6.Cu")
		(net "M_H_CPU0_SA_DQ<1>")
	)
	(segment
		(start 441.158376 -314.190888)
		(end 438.66562 -314.190888)
		(width 0.18288)
		(layer "In6.Cu")
		(net "M_H_CPU0_SA_DQ<1>")
	)
	(segment
		(start 411.06217 -307.525674)
		(end 410.797756 -307.26126)
		(width 0.18288)
		(layer "In6.Cu")
		(net "M_H_CPU0_SA_DQ<1>")
	)
	(segment
		(start 387.883908 -281.512518)
		(end 387.524752 -280.645616)
		(width 0.088646)
		(layer "In6.Cu")
		(net "M_H_CPU0_SA_DQ<1>")
	)
	(segment
		(start 448.37477 -312.9915)
		(end 448.37477 -313.460384)
		(width 0.18288)
		(layer "In6.Cu")
		(net "M_H_CPU0_SA_DQ<1>")
	)
	(segment
		(start 411.874462 -309.199026)
		(end 411.328108 -308.652672)
		(width 0.18288)
		(layer "In6.Cu")
		(net "M_H_CPU0_SA_DQ<1>")
	)
	(segment
		(start 385.629912 -279.964134)
		(end 385.629912 -279.954228)
		(width 0.088646)
		(layer "In6.Cu")
		(net "M_H_CPU0_SA_DQ<1>")
	)
	(segment
		(start 388.00405 -281.63266)
		(end 387.883908 -281.512518)
		(width 0.088646)
		(layer "In6.Cu")
		(net "M_H_CPU0_SA_DQ<1>")
	)
	(segment
		(start 405.040084 -307.393594)
		(end 403.150578 -305.504088)
		(width 0.18288)
		(layer "In6.Cu")
		(net "M_H_CPU0_SA_DQ<1>")
	)
	(segment
		(start 385.347464 -279.474676)
		(end 385.338574 -279.469596)
		(width 0.088646)
		(layer "In6.Cu")
		(net "M_H_CPU0_SA_DQ<1>")
	)
	(segment
		(start 414.603184 -309.360824)
		(end 414.377124 -309.360824)
		(width 0.18288)
		(layer "In6.Cu")
		(net "M_H_CPU0_SA_DQ<1>")
	)
	(segment
		(start 448.19189 -313.643264)
		(end 446.662556 -313.643264)
		(width 0.18288)
		(layer "In6.Cu")
		(net "M_H_CPU0_SA_DQ<1>")
	)
	(segment
		(start 415.304986 -310.062626)
		(end 414.603184 -309.360824)
		(width 0.18288)
		(layer "In6.Cu")
		(net "M_H_CPU0_SA_DQ<1>")
	)
	(segment
		(start 413.88665 -308.64429)
		(end 413.806386 -308.564026)
		(width 0.18288)
		(layer "In6.Cu")
		(net "M_H_CPU0_SA_DQ<1>")
	)
	(segment
		(start 448.55765 -312.80862)
		(end 448.37477 -312.9915)
		(width 0.18288)
		(layer "In6.Cu")
		(net "M_H_CPU0_SA_DQ<1>")
	)
	(arc
		(start 385.160012 -279.140412)
		(mid 385.081901 -278.863463)
		(end 384.877564 -278.66086)
		(width 0.088646)
		(layer "In6.Cu")
		(net "M_H_CPU0_SA_DQ<1>")
	)
	(arc
		(start 384.877564 -278.66086)
		(mid 384.594862 -278.585084)
		(end 384.31216 -278.66086)
		(width 0.088646)
		(layer "In6.Cu")
		(net "M_H_CPU0_SA_DQ<1>")
	)
	(arc
		(start 383.937764 -278.66086)
		(mid 383.655062 -278.585084)
		(end 383.37236 -278.66086)
		(width 0.088646)
		(layer "In6.Cu")
		(net "M_H_CPU0_SA_DQ<1>")
	)
	(arc
		(start 378.67336 -278.66086)
		(mid 378.486162 -278.711003)
		(end 378.298964 -278.66086)
		(width 0.088646)
		(layer "In6.Cu")
		(net "M_H_CPU0_SA_DQ<1>")
	)
	(arc
		(start 382.43256 -278.66086)
		(mid 382.245362 -278.711003)
		(end 382.058164 -278.66086)
		(width 0.088646)
		(layer "In6.Cu")
		(net "M_H_CPU0_SA_DQ<1>")
	)
	(arc
		(start 385.629912 -279.954228)
		(mid 385.551801 -279.677279)
		(end 385.347464 -279.474676)
		(width 0.088646)
		(layer "In6.Cu")
		(net "M_H_CPU0_SA_DQ<1>")
	)
	(arc
		(start 379.239018 -278.66086)
		(mid 378.962205 -278.58499)
		(end 378.683774 -278.654764)
		(width 0.088646)
		(layer "In6.Cu")
		(net "M_H_CPU0_SA_DQ<1>")
	)
	(arc
		(start 381.118618 -278.66086)
		(mid 380.835916 -278.585084)
		(end 380.553214 -278.66086)
		(width 0.088646)
		(layer "In6.Cu")
		(net "M_H_CPU0_SA_DQ<1>")
	)
	(arc
		(start 387.115812 -280.385266)
		(mid 386.930327 -280.360634)
		(end 386.757672 -280.288492)
		(width 0.088646)
		(layer "In6.Cu")
		(net "M_H_CPU0_SA_DQ<1>")
	)
	(arc
		(start 386.757672 -280.288492)
		(mid 386.480859 -280.212656)
		(end 386.202428 -280.282396)
		(width 0.088646)
		(layer "In6.Cu")
		(net "M_H_CPU0_SA_DQ<1>")
	)
	(arc
		(start 383.37236 -278.66086)
		(mid 383.185162 -278.711003)
		(end 382.997964 -278.66086)
		(width 0.088646)
		(layer "In6.Cu")
		(net "M_H_CPU0_SA_DQ<1>")
	)
	(arc
		(start 386.192014 -280.288492)
		(mid 386.004816 -280.338635)
		(end 385.817618 -280.288492)
		(width 0.088646)
		(layer "In6.Cu")
		(net "M_H_CPU0_SA_DQ<1>")
	)
	(arc
		(start 380.553214 -278.66086)
		(mid 380.366016 -278.711003)
		(end 380.178818 -278.66086)
		(width 0.088646)
		(layer "In6.Cu")
		(net "M_H_CPU0_SA_DQ<1>")
	)
	(arc
		(start 380.178818 -278.66086)
		(mid 379.896116 -278.585084)
		(end 379.613414 -278.66086)
		(width 0.088646)
		(layer "In6.Cu")
		(net "M_H_CPU0_SA_DQ<1>")
	)
	(arc
		(start 385.808474 -280.283412)
		(mid 385.67756 -280.147052)
		(end 385.629912 -279.964134)
		(width 0.088646)
		(layer "In6.Cu")
		(net "M_H_CPU0_SA_DQ<1>")
	)
	(arc
		(start 384.31216 -278.66086)
		(mid 384.124962 -278.711003)
		(end 383.937764 -278.66086)
		(width 0.088646)
		(layer "In6.Cu")
		(net "M_H_CPU0_SA_DQ<1>")
	)
	(arc
		(start 381.493014 -278.66086)
		(mid 381.305816 -278.711003)
		(end 381.118618 -278.66086)
		(width 0.088646)
		(layer "In6.Cu")
		(net "M_H_CPU0_SA_DQ<1>")
	)
	(arc
		(start 379.613414 -278.66086)
		(mid 379.426216 -278.711003)
		(end 379.239018 -278.66086)
		(width 0.088646)
		(layer "In6.Cu")
		(net "M_H_CPU0_SA_DQ<1>")
	)
	(arc
		(start 377.917456 -278.437086)
		(mid 377.738743 -278.362069)
		(end 377.546616 -278.336502)
		(width 0.088646)
		(layer "In6.Cu")
		(net "M_H_CPU0_SA_DQ<1>")
	)
	(arc
		(start 382.997964 -278.66086)
		(mid 382.715262 -278.585084)
		(end 382.43256 -278.66086)
		(width 0.088646)
		(layer "In6.Cu")
		(net "M_H_CPU0_SA_DQ<1>")
	)
	(arc
		(start 382.058164 -278.66086)
		(mid 381.781605 -278.585117)
		(end 381.503428 -278.654764)
		(width 0.088646)
		(layer "In6.Cu")
		(net "M_H_CPU0_SA_DQ<1>")
	)
	(arc
		(start 385.338574 -279.469596)
		(mid 385.20766 -279.333236)
		(end 385.160012 -279.150318)
		(width 0.088646)
		(layer "In6.Cu")
		(net "M_H_CPU0_SA_DQ<1>")
	)
	(segment
		(start 458.543152 -295.498774)
		(end 458.550264 -295.491662)
		(width 0.1016)
		(layer "F.Cu")
		(net "M_H_CPU0_SA_DQ<19>")
	)
	(segment
		(start 462.073752 -294.814752)
		(end 462.32572 -295.06672)
		(width 0.20066)
		(layer "F.Cu")
		(net "M_H_CPU0_SA_DQ<19>")
	)
	(segment
		(start 456.116182 -295.06672)
		(end 457.814426 -295.06672)
		(width 0.20066)
		(layer "F.Cu")
		(net "M_H_CPU0_SA_DQ<19>")
	)
	(segment
		(start 461.251554 -295.503854)
		(end 461.455516 -295.299892)
		(width 0.20066)
		(layer "F.Cu")
		(net "M_H_CPU0_SA_DQ<19>")
	)
	(segment
		(start 462.32572 -295.06672)
		(end 463.659982 -295.06672)
		(width 0.20066)
		(layer "F.Cu")
		(net "M_H_CPU0_SA_DQ<19>")
	)
	(segment
		(start 458.24648 -295.498774)
		(end 458.538326 -295.498774)
		(width 0.20066)
		(layer "F.Cu")
		(net "M_H_CPU0_SA_DQ<19>")
	)
	(segment
		(start 461.455516 -295.299892)
		(end 461.455516 -295.04894)
		(width 0.20066)
		(layer "F.Cu")
		(net "M_H_CPU0_SA_DQ<19>")
	)
	(segment
		(start 373.317516 -271.011142)
		(end 373.317262 -271.011396)
		(width 0.20066)
		(layer "F.Cu")
		(net "M_H_CPU0_SA_DQ<19>")
	)
	(segment
		(start 455.011282 -295.06672)
		(end 456.116182 -295.06672)
		(width 0.20066)
		(layer "F.Cu")
		(net "M_H_CPU0_SA_DQ<19>")
	)
	(segment
		(start 460.558134 -295.491662)
		(end 460.570326 -295.503854)
		(width 0.1016)
		(layer "F.Cu")
		(net "M_H_CPU0_SA_DQ<19>")
	)
	(segment
		(start 461.689704 -294.814752)
		(end 462.073752 -294.814752)
		(width 0.20066)
		(layer "F.Cu")
		(net "M_H_CPU0_SA_DQ<19>")
	)
	(segment
		(start 458.550264 -295.491662)
		(end 460.558134 -295.491662)
		(width 0.1016)
		(layer "F.Cu")
		(net "M_H_CPU0_SA_DQ<19>")
	)
	(segment
		(start 460.570326 -295.503854)
		(end 461.251554 -295.503854)
		(width 0.20066)
		(layer "F.Cu")
		(net "M_H_CPU0_SA_DQ<19>")
	)
	(segment
		(start 461.455516 -295.04894)
		(end 461.689704 -294.814752)
		(width 0.20066)
		(layer "F.Cu")
		(net "M_H_CPU0_SA_DQ<19>")
	)
	(segment
		(start 457.814426 -295.06672)
		(end 458.24648 -295.498774)
		(width 0.20066)
		(layer "F.Cu")
		(net "M_H_CPU0_SA_DQ<19>")
	)
	(segment
		(start 373.317516 -270.475456)
		(end 373.317516 -271.011142)
		(width 0.20066)
		(layer "F.Cu")
		(net "M_H_CPU0_SA_DQ<19>")
	)
	(segment
		(start 458.538326 -295.498774)
		(end 458.543152 -295.498774)
		(width 0.101854)
		(layer "F.Cu")
		(net "M_H_CPU0_SA_DQ<19>")
	)
	(segment
		(start 440.811666 -300.055026)
		(end 440.27471 -300.591982)
		(width 0.18288)
		(layer "In11.Cu")
		(net "M_H_CPU0_SA_DQ<19>")
	)
	(segment
		(start 435.071266 -299.90161)
		(end 431.814986 -299.90161)
		(width 0.18288)
		(layer "In11.Cu")
		(net "M_H_CPU0_SA_DQ<19>")
	)
	(segment
		(start 387.25856 -276.487382)
		(end 387.104636 -276.48662)
		(width 0.088646)
		(layer "In11.Cu")
		(net "M_H_CPU0_SA_DQ<19>")
	)
	(segment
		(start 422.204388 -300.766226)
		(end 421.52824 -301.442374)
		(width 0.18288)
		(layer "In11.Cu")
		(net "M_H_CPU0_SA_DQ<19>")
	)
	(segment
		(start 452.126096 -295.762426)
		(end 451.856094 -295.492424)
		(width 0.18288)
		(layer "In11.Cu")
		(net "M_H_CPU0_SA_DQ<19>")
	)
	(segment
		(start 419.452552 -301.655226)
		(end 417.566094 -299.768768)
		(width 0.18288)
		(layer "In11.Cu")
		(net "M_H_CPU0_SA_DQ<19>")
	)
	(segment
		(start 455.011282 -295.06672)
		(end 454.2028 -295.06672)
		(width 0.18288)
		(layer "In11.Cu")
		(net "M_H_CPU0_SA_DQ<19>")
	)
	(segment
		(start 447.677794 -296.448226)
		(end 446.687194 -296.448226)
		(width 0.18288)
		(layer "In11.Cu")
		(net "M_H_CPU0_SA_DQ<19>")
	)
	(segment
		(start 426.559472 -300.226222)
		(end 426.193458 -300.592236)
		(width 0.18288)
		(layer "In11.Cu")
		(net "M_H_CPU0_SA_DQ<19>")
	)
	(segment
		(start 374.041924 -271.319498)
		(end 373.317262 -271.011396)
		(width 0.088646)
		(layer "In11.Cu")
		(net "M_H_CPU0_SA_DQ<19>")
	)
	(segment
		(start 379.708664 -274.591272)
		(end 379.693932 -274.582636)
		(width 0.088646)
		(layer "In11.Cu")
		(net "M_H_CPU0_SA_DQ<19>")
	)
	(segment
		(start 386.837428 -276.219412)
		(end 386.063236 -276.219412)
		(width 0.088646)
		(layer "In11.Cu")
		(net "M_H_CPU0_SA_DQ<19>")
	)
	(segment
		(start 421.52824 -301.442374)
		(end 420.242746 -301.442374)
		(width 0.18288)
		(layer "In11.Cu")
		(net "M_H_CPU0_SA_DQ<19>")
	)
	(segment
		(start 386.063236 -276.219412)
		(end 384.525012 -274.681188)
		(width 0.088646)
		(layer "In11.Cu")
		(net "M_H_CPU0_SA_DQ<19>")
	)
	(segment
		(start 423.865294 -300.766226)
		(end 422.204388 -300.766226)
		(width 0.18288)
		(layer "In11.Cu")
		(net "M_H_CPU0_SA_DQ<19>")
	)
	(segment
		(start 435.230524 -299.742352)
		(end 435.071266 -299.90161)
		(width 0.18288)
		(layer "In11.Cu")
		(net "M_H_CPU0_SA_DQ<19>")
	)
	(segment
		(start 390.9949 -280.133044)
		(end 390.995154 -280.064718)
		(width 0.18288)
		(layer "In11.Cu")
		(net "M_H_CPU0_SA_DQ<19>")
	)
	(segment
		(start 438.901078 -300.77537)
		(end 437.819038 -300.77537)
		(width 0.18288)
		(layer "In11.Cu")
		(net "M_H_CPU0_SA_DQ<19>")
	)
	(segment
		(start 445.798194 -297.337226)
		(end 445.284606 -297.337226)
		(width 0.18288)
		(layer "In11.Cu")
		(net "M_H_CPU0_SA_DQ<19>")
	)
	(segment
		(start 377.83516 -272.967196)
		(end 377.829064 -272.96364)
		(width 0.088646)
		(layer "In11.Cu")
		(net "M_H_CPU0_SA_DQ<19>")
	)
	(segment
		(start 414.457642 -299.557948)
		(end 414.457642 -299.257466)
		(width 0.18288)
		(layer "In11.Cu")
		(net "M_H_CPU0_SA_DQ<19>")
	)
	(segment
		(start 454.2028 -295.06672)
		(end 453.507094 -295.762426)
		(width 0.18288)
		(layer "In11.Cu")
		(net "M_H_CPU0_SA_DQ<19>")
	)
	(segment
		(start 416.766248 -299.768768)
		(end 416.061906 -299.064426)
		(width 0.18288)
		(layer "In11.Cu")
		(net "M_H_CPU0_SA_DQ<19>")
	)
	(segment
		(start 377.641612 -272.639282)
		(end 377.641612 -272.63852)
		(width 0.088646)
		(layer "In11.Cu")
		(net "M_H_CPU0_SA_DQ<19>")
	)
	(segment
		(start 449.23456 -294.89146)
		(end 447.677794 -296.448226)
		(width 0.18288)
		(layer "In11.Cu")
		(net "M_H_CPU0_SA_DQ<19>")
	)
	(segment
		(start 450.058028 -294.89146)
		(end 449.23456 -294.89146)
		(width 0.18288)
		(layer "In11.Cu")
		(net "M_H_CPU0_SA_DQ<19>")
	)
	(segment
		(start 387.104636 -276.48662)
		(end 386.837428 -276.219412)
		(width 0.088646)
		(layer "In11.Cu")
		(net "M_H_CPU0_SA_DQ<19>")
	)
	(segment
		(start 446.687194 -296.448226)
		(end 445.798194 -297.337226)
		(width 0.18288)
		(layer "In11.Cu")
		(net "M_H_CPU0_SA_DQ<19>")
	)
	(segment
		(start 378.768864 -274.591272)
		(end 378.759974 -274.586192)
		(width 0.088646)
		(layer "In11.Cu")
		(net "M_H_CPU0_SA_DQ<19>")
	)
	(segment
		(start 414.264602 -299.064426)
		(end 412.663894 -299.064426)
		(width 0.18288)
		(layer "In11.Cu")
		(net "M_H_CPU0_SA_DQ<19>")
	)
	(segment
		(start 427.088808 -300.226222)
		(end 426.559472 -300.226222)
		(width 0.18288)
		(layer "In11.Cu")
		(net "M_H_CPU0_SA_DQ<19>")
	)
	(segment
		(start 390.995154 -280.064718)
		(end 387.43509 -276.48789)
		(width 0.18288)
		(layer "In11.Cu")
		(net "M_H_CPU0_SA_DQ<19>")
	)
	(segment
		(start 420.242746 -301.442374)
		(end 420.029894 -301.655226)
		(width 0.18288)
		(layer "In11.Cu")
		(net "M_H_CPU0_SA_DQ<19>")
	)
	(segment
		(start 375.009664 -271.335754)
		(end 374.994932 -271.327118)
		(width 0.088646)
		(layer "In11.Cu")
		(net "M_H_CPU0_SA_DQ<19>")
	)
	(segment
		(start 410.047186 -297.179746)
		(end 408.820366 -297.179746)
		(width 0.18288)
		(layer "In11.Cu")
		(net "M_H_CPU0_SA_DQ<19>")
	)
	(segment
		(start 378.299218 -273.777456)
		(end 378.290328 -273.772376)
		(width 0.088646)
		(layer "In11.Cu")
		(net "M_H_CPU0_SA_DQ<19>")
	)
	(segment
		(start 377.829064 -272.96364)
		(end 377.820174 -272.95856)
		(width 0.088646)
		(layer "In11.Cu")
		(net "M_H_CPU0_SA_DQ<19>")
	)
	(segment
		(start 387.43509 -276.48789)
		(end 387.25856 -276.487382)
		(width 0.18288)
		(layer "In11.Cu")
		(net "M_H_CPU0_SA_DQ<19>")
	)
	(segment
		(start 415.161222 -299.557948)
		(end 414.968182 -299.750988)
		(width 0.18288)
		(layer "In11.Cu")
		(net "M_H_CPU0_SA_DQ<19>")
	)
	(segment
		(start 399.283174 -288.459418)
		(end 391.093706 -280.232358)
		(width 0.18288)
		(layer "In11.Cu")
		(net "M_H_CPU0_SA_DQ<19>")
	)
	(segment
		(start 416.061906 -299.064426)
		(end 415.354262 -299.064426)
		(width 0.18288)
		(layer "In11.Cu")
		(net "M_H_CPU0_SA_DQ<19>")
	)
	(segment
		(start 381.033528 -274.585176)
		(end 381.023114 -274.591272)
		(width 0.088646)
		(layer "In11.Cu")
		(net "M_H_CPU0_SA_DQ<19>")
	)
	(segment
		(start 420.029894 -301.655226)
		(end 419.452552 -301.655226)
		(width 0.18288)
		(layer "In11.Cu")
		(net "M_H_CPU0_SA_DQ<19>")
	)
	(segment
		(start 408.727148 -297.272964)
		(end 407.750772 -297.272964)
		(width 0.18288)
		(layer "In11.Cu")
		(net "M_H_CPU0_SA_DQ<19>")
	)
	(segment
		(start 445.284606 -297.337226)
		(end 443.709806 -298.912026)
		(width 0.18288)
		(layer "In11.Cu")
		(net "M_H_CPU0_SA_DQ<19>")
	)
	(segment
		(start 412.663894 -299.064426)
		(end 410.783024 -297.180508)
		(width 0.18288)
		(layer "In11.Cu")
		(net "M_H_CPU0_SA_DQ<19>")
	)
	(segment
		(start 426.193458 -300.592236)
		(end 424.039284 -300.592236)
		(width 0.18288)
		(layer "In11.Cu")
		(net "M_H_CPU0_SA_DQ<19>")
	)
	(segment
		(start 439.084466 -300.591982)
		(end 438.901078 -300.77537)
		(width 0.18288)
		(layer "In11.Cu")
		(net "M_H_CPU0_SA_DQ<19>")
	)
	(segment
		(start 375.009918 -271.335754)
		(end 375.009664 -271.335754)
		(width 0.088646)
		(layer "In11.Cu")
		(net "M_H_CPU0_SA_DQ<19>")
	)
	(segment
		(start 407.750772 -297.272964)
		(end 406.07742 -295.599612)
		(width 0.18288)
		(layer "In11.Cu")
		(net "M_H_CPU0_SA_DQ<19>")
	)
	(segment
		(start 382.528064 -274.591272)
		(end 382.513332 -274.582636)
		(width 0.088646)
		(layer "In11.Cu")
		(net "M_H_CPU0_SA_DQ<19>")
	)
	(segment
		(start 374.069864 -271.335754)
		(end 374.041924 -271.319498)
		(width 0.088646)
		(layer "In11.Cu")
		(net "M_H_CPU0_SA_DQ<19>")
	)
	(segment
		(start 399.283174 -290.339018)
		(end 399.283174 -288.459418)
		(width 0.18288)
		(layer "In11.Cu")
		(net "M_H_CPU0_SA_DQ<19>")
	)
	(segment
		(start 376.419618 -272.14957)
		(end 376.410728 -272.14449)
		(width 0.088646)
		(layer "In11.Cu")
		(net "M_H_CPU0_SA_DQ<19>")
	)
	(segment
		(start 428.781972 -300.610016)
		(end 427.472602 -300.610016)
		(width 0.18288)
		(layer "In11.Cu")
		(net "M_H_CPU0_SA_DQ<19>")
	)
	(segment
		(start 376.808746 -272.140934)
		(end 376.794014 -272.14957)
		(width 0.088646)
		(layer "In11.Cu")
		(net "M_H_CPU0_SA_DQ<19>")
	)
	(segment
		(start 431.610262 -299.696886)
		(end 429.695102 -299.696886)
		(width 0.18288)
		(layer "In11.Cu")
		(net "M_H_CPU0_SA_DQ<19>")
	)
	(segment
		(start 450.658992 -295.492424)
		(end 450.058028 -294.89146)
		(width 0.18288)
		(layer "In11.Cu")
		(net "M_H_CPU0_SA_DQ<19>")
	)
	(segment
		(start 375.95556 -271.33931)
		(end 375.949464 -271.335754)
		(width 0.088646)
		(layer "In11.Cu")
		(net "M_H_CPU0_SA_DQ<19>")
	)
	(segment
		(start 417.566094 -299.768768)
		(end 416.766248 -299.768768)
		(width 0.18288)
		(layer "In11.Cu")
		(net "M_H_CPU0_SA_DQ<19>")
	)
	(segment
		(start 380.648718 -274.591272)
		(end 380.638304 -274.585176)
		(width 0.088646)
		(layer "In11.Cu")
		(net "M_H_CPU0_SA_DQ<19>")
	)
	(segment
		(start 442.01461 -300.055026)
		(end 440.811666 -300.055026)
		(width 0.18288)
		(layer "In11.Cu")
		(net "M_H_CPU0_SA_DQ<19>")
	)
	(segment
		(start 451.856094 -295.492424)
		(end 450.658992 -295.492424)
		(width 0.18288)
		(layer "In11.Cu")
		(net "M_H_CPU0_SA_DQ<19>")
	)
	(segment
		(start 453.507094 -295.762426)
		(end 452.126096 -295.762426)
		(width 0.18288)
		(layer "In11.Cu")
		(net "M_H_CPU0_SA_DQ<19>")
	)
	(segment
		(start 375.949464 -271.335754)
		(end 375.934732 -271.327118)
		(width 0.088646)
		(layer "In11.Cu")
		(net "M_H_CPU0_SA_DQ<19>")
	)
	(segment
		(start 437.819038 -300.77537)
		(end 436.78602 -299.742352)
		(width 0.18288)
		(layer "In11.Cu")
		(net "M_H_CPU0_SA_DQ<19>")
	)
	(segment
		(start 378.581412 -274.266914)
		(end 378.581412 -274.25142)
		(width 0.088646)
		(layer "In11.Cu")
		(net "M_H_CPU0_SA_DQ<19>")
	)
	(segment
		(start 429.695102 -299.696886)
		(end 428.781972 -300.610016)
		(width 0.18288)
		(layer "In11.Cu")
		(net "M_H_CPU0_SA_DQ<19>")
	)
	(segment
		(start 414.650682 -299.750988)
		(end 414.457642 -299.557948)
		(width 0.18288)
		(layer "In11.Cu")
		(net "M_H_CPU0_SA_DQ<19>")
	)
	(segment
		(start 410.783024 -297.180508)
		(end 410.047186 -297.179746)
		(width 0.18288)
		(layer "In11.Cu")
		(net "M_H_CPU0_SA_DQ<19>")
	)
	(segment
		(start 391.093706 -280.232358)
		(end 390.9949 -280.133044)
		(width 0.18288)
		(layer "In11.Cu")
		(net "M_H_CPU0_SA_DQ<19>")
	)
	(segment
		(start 384.407664 -274.591272)
		(end 384.392932 -274.582636)
		(width 0.088646)
		(layer "In11.Cu")
		(net "M_H_CPU0_SA_DQ<19>")
	)
	(segment
		(start 424.039284 -300.592236)
		(end 423.865294 -300.766226)
		(width 0.18288)
		(layer "In11.Cu")
		(net "M_H_CPU0_SA_DQ<19>")
	)
	(segment
		(start 427.472602 -300.610016)
		(end 427.088808 -300.226222)
		(width 0.18288)
		(layer "In11.Cu")
		(net "M_H_CPU0_SA_DQ<19>")
	)
	(segment
		(start 415.161222 -299.257466)
		(end 415.161222 -299.557948)
		(width 0.18288)
		(layer "In11.Cu")
		(net "M_H_CPU0_SA_DQ<19>")
	)
	(segment
		(start 414.968182 -299.750988)
		(end 414.650682 -299.750988)
		(width 0.18288)
		(layer "In11.Cu")
		(net "M_H_CPU0_SA_DQ<19>")
	)
	(segment
		(start 443.15761 -298.912026)
		(end 442.01461 -300.055026)
		(width 0.18288)
		(layer "In11.Cu")
		(net "M_H_CPU0_SA_DQ<19>")
	)
	(segment
		(start 408.820366 -297.179746)
		(end 408.727148 -297.272964)
		(width 0.18288)
		(layer "In11.Cu")
		(net "M_H_CPU0_SA_DQ<19>")
	)
	(segment
		(start 404.54199 -295.599612)
		(end 399.283174 -290.339018)
		(width 0.18288)
		(layer "In11.Cu")
		(net "M_H_CPU0_SA_DQ<19>")
	)
	(segment
		(start 436.78602 -299.742352)
		(end 435.230524 -299.742352)
		(width 0.18288)
		(layer "In11.Cu")
		(net "M_H_CPU0_SA_DQ<19>")
	)
	(segment
		(start 431.814986 -299.90161)
		(end 431.610262 -299.696886)
		(width 0.18288)
		(layer "In11.Cu")
		(net "M_H_CPU0_SA_DQ<19>")
	)
	(segment
		(start 414.457642 -299.257466)
		(end 414.264602 -299.064426)
		(width 0.18288)
		(layer "In11.Cu")
		(net "M_H_CPU0_SA_DQ<19>")
	)
	(segment
		(start 383.467864 -274.591272)
		(end 383.453132 -274.582636)
		(width 0.088646)
		(layer "In11.Cu")
		(net "M_H_CPU0_SA_DQ<19>")
	)
	(segment
		(start 440.27471 -300.591982)
		(end 439.084466 -300.591982)
		(width 0.18288)
		(layer "In11.Cu")
		(net "M_H_CPU0_SA_DQ<19>")
	)
	(segment
		(start 406.07742 -295.599612)
		(end 404.54199 -295.599612)
		(width 0.18288)
		(layer "In11.Cu")
		(net "M_H_CPU0_SA_DQ<19>")
	)
	(segment
		(start 443.709806 -298.912026)
		(end 443.15761 -298.912026)
		(width 0.18288)
		(layer "In11.Cu")
		(net "M_H_CPU0_SA_DQ<19>")
	)
	(segment
		(start 415.354262 -299.064426)
		(end 415.161222 -299.257466)
		(width 0.18288)
		(layer "In11.Cu")
		(net "M_H_CPU0_SA_DQ<19>")
	)
	(arc
		(start 375.38406 -271.335754)
		(mid 375.197006 -271.385804)
		(end 375.009918 -271.335754)
		(width 0.088646)
		(layer "In11.Cu")
		(net "M_H_CPU0_SA_DQ<19>")
	)
	(arc
		(start 381.023114 -274.591272)
		(mid 380.835916 -274.641415)
		(end 380.648718 -274.591272)
		(width 0.088646)
		(layer "In11.Cu")
		(net "M_H_CPU0_SA_DQ<19>")
	)
	(arc
		(start 382.513332 -274.582636)
		(mid 382.236857 -274.515316)
		(end 381.96266 -274.591272)
		(width 0.088646)
		(layer "In11.Cu")
		(net "M_H_CPU0_SA_DQ<19>")
	)
	(arc
		(start 374.994932 -271.327118)
		(mid 374.718457 -271.259798)
		(end 374.44426 -271.335754)
		(width 0.088646)
		(layer "In11.Cu")
		(net "M_H_CPU0_SA_DQ<19>")
	)
	(arc
		(start 377.820174 -272.95856)
		(mid 377.68926 -272.8222)
		(end 377.641612 -272.639282)
		(width 0.088646)
		(layer "In11.Cu")
		(net "M_H_CPU0_SA_DQ<19>")
	)
	(arc
		(start 379.693932 -274.582636)
		(mid 379.417457 -274.515316)
		(end 379.14326 -274.591272)
		(width 0.088646)
		(layer "In11.Cu")
		(net "M_H_CPU0_SA_DQ<19>")
	)
	(arc
		(start 378.581412 -274.25142)
		(mid 378.502042 -273.977686)
		(end 378.299218 -273.777456)
		(width 0.088646)
		(layer "In11.Cu")
		(net "M_H_CPU0_SA_DQ<19>")
	)
	(arc
		(start 384.392932 -274.582636)
		(mid 384.116491 -274.51547)
		(end 383.84226 -274.591272)
		(width 0.088646)
		(layer "In11.Cu")
		(net "M_H_CPU0_SA_DQ<19>")
	)
	(arc
		(start 377.359418 -272.14957)
		(mid 377.085189 -272.073645)
		(end 376.808746 -272.140934)
		(width 0.088646)
		(layer "In11.Cu")
		(net "M_H_CPU0_SA_DQ<19>")
	)
	(arc
		(start 376.232166 -271.825212)
		(mid 376.158175 -271.545646)
		(end 375.95556 -271.33931)
		(width 0.088646)
		(layer "In11.Cu")
		(net "M_H_CPU0_SA_DQ<19>")
	)
	(arc
		(start 376.794014 -272.14957)
		(mid 376.606816 -272.199713)
		(end 376.419618 -272.14957)
		(width 0.088646)
		(layer "In11.Cu")
		(net "M_H_CPU0_SA_DQ<19>")
	)
	(arc
		(start 383.453132 -274.582636)
		(mid 383.176691 -274.51547)
		(end 382.90246 -274.591272)
		(width 0.088646)
		(layer "In11.Cu")
		(net "M_H_CPU0_SA_DQ<19>")
	)
	(arc
		(start 381.588264 -274.591272)
		(mid 381.311705 -274.515529)
		(end 381.033528 -274.585176)
		(width 0.088646)
		(layer "In11.Cu")
		(net "M_H_CPU0_SA_DQ<19>")
	)
	(arc
		(start 378.759974 -274.586192)
		(mid 378.62906 -274.449832)
		(end 378.581412 -274.266914)
		(width 0.088646)
		(layer "In11.Cu")
		(net "M_H_CPU0_SA_DQ<19>")
	)
	(arc
		(start 378.111766 -273.453098)
		(mid 378.037775 -273.173532)
		(end 377.83516 -272.967196)
		(width 0.088646)
		(layer "In11.Cu")
		(net "M_H_CPU0_SA_DQ<19>")
	)
	(arc
		(start 379.14326 -274.591272)
		(mid 378.956062 -274.641415)
		(end 378.768864 -274.591272)
		(width 0.088646)
		(layer "In11.Cu")
		(net "M_H_CPU0_SA_DQ<19>")
	)
	(arc
		(start 376.410728 -272.14449)
		(mid 376.279814 -272.00813)
		(end 376.232166 -271.825212)
		(width 0.088646)
		(layer "In11.Cu")
		(net "M_H_CPU0_SA_DQ<19>")
	)
	(arc
		(start 380.638304 -274.585176)
		(mid 380.359872 -274.51533)
		(end 380.08306 -274.591272)
		(width 0.088646)
		(layer "In11.Cu")
		(net "M_H_CPU0_SA_DQ<19>")
	)
	(arc
		(start 381.96266 -274.591272)
		(mid 381.775462 -274.641415)
		(end 381.588264 -274.591272)
		(width 0.088646)
		(layer "In11.Cu")
		(net "M_H_CPU0_SA_DQ<19>")
	)
	(arc
		(start 375.934732 -271.327118)
		(mid 375.658257 -271.259798)
		(end 375.38406 -271.335754)
		(width 0.088646)
		(layer "In11.Cu")
		(net "M_H_CPU0_SA_DQ<19>")
	)
	(arc
		(start 380.08306 -274.591272)
		(mid 379.895862 -274.641415)
		(end 379.708664 -274.591272)
		(width 0.088646)
		(layer "In11.Cu")
		(net "M_H_CPU0_SA_DQ<19>")
	)
	(arc
		(start 378.290328 -273.772376)
		(mid 378.159414 -273.636016)
		(end 378.111766 -273.453098)
		(width 0.088646)
		(layer "In11.Cu")
		(net "M_H_CPU0_SA_DQ<19>")
	)
	(arc
		(start 374.44426 -271.335754)
		(mid 374.257062 -271.385897)
		(end 374.069864 -271.335754)
		(width 0.088646)
		(layer "In11.Cu")
		(net "M_H_CPU0_SA_DQ<19>")
	)
	(arc
		(start 384.525012 -274.681188)
		(mid 384.469283 -274.632388)
		(end 384.407664 -274.591272)
		(width 0.088646)
		(layer "In11.Cu")
		(net "M_H_CPU0_SA_DQ<19>")
	)
	(arc
		(start 382.90246 -274.591272)
		(mid 382.715262 -274.641415)
		(end 382.528064 -274.591272)
		(width 0.088646)
		(layer "In11.Cu")
		(net "M_H_CPU0_SA_DQ<19>")
	)
	(arc
		(start 383.84226 -274.591272)
		(mid 383.655062 -274.641415)
		(end 383.467864 -274.591272)
		(width 0.088646)
		(layer "In11.Cu")
		(net "M_H_CPU0_SA_DQ<19>")
	)
	(arc
		(start 377.641612 -272.63852)
		(mid 377.565997 -272.356256)
		(end 377.359418 -272.14957)
		(width 0.088646)
		(layer "In11.Cu")
		(net "M_H_CPU0_SA_DQ<19>")
	)
	(segment
		(start 461.455516 -296.999914)
		(end 461.455516 -296.748962)
		(width 0.20066)
		(layer "F.Cu")
		(net "M_H_CPU0_SA_DQ<18>")
	)
	(segment
		(start 461.689704 -296.514774)
		(end 462.073752 -296.514774)
		(width 0.20066)
		(layer "F.Cu")
		(net "M_H_CPU0_SA_DQ<18>")
	)
	(segment
		(start 461.455516 -296.748962)
		(end 461.689704 -296.514774)
		(width 0.20066)
		(layer "F.Cu")
		(net "M_H_CPU0_SA_DQ<18>")
	)
	(segment
		(start 457.814426 -296.766742)
		(end 458.24648 -297.198796)
		(width 0.20066)
		(layer "F.Cu")
		(net "M_H_CPU0_SA_DQ<18>")
	)
	(segment
		(start 460.570326 -297.203876)
		(end 461.251554 -297.203876)
		(width 0.20066)
		(layer "F.Cu")
		(net "M_H_CPU0_SA_DQ<18>")
	)
	(segment
		(start 458.543152 -297.198796)
		(end 458.550264 -297.191684)
		(width 0.1016)
		(layer "F.Cu")
		(net "M_H_CPU0_SA_DQ<18>")
	)
	(segment
		(start 458.538326 -297.198796)
		(end 458.543152 -297.198796)
		(width 0.101854)
		(layer "F.Cu")
		(net "M_H_CPU0_SA_DQ<18>")
	)
	(segment
		(start 458.24648 -297.198796)
		(end 458.538326 -297.198796)
		(width 0.20066)
		(layer "F.Cu")
		(net "M_H_CPU0_SA_DQ<18>")
	)
	(segment
		(start 456.116182 -296.766742)
		(end 457.814426 -296.766742)
		(width 0.20066)
		(layer "F.Cu")
		(net "M_H_CPU0_SA_DQ<18>")
	)
	(segment
		(start 372.847362 -271.289272)
		(end 372.847616 -271.825212)
		(width 0.20066)
		(layer "F.Cu")
		(net "M_H_CPU0_SA_DQ<18>")
	)
	(segment
		(start 461.251554 -297.203876)
		(end 461.455516 -296.999914)
		(width 0.20066)
		(layer "F.Cu")
		(net "M_H_CPU0_SA_DQ<18>")
	)
	(segment
		(start 462.32572 -296.766742)
		(end 463.659982 -296.766742)
		(width 0.20066)
		(layer "F.Cu")
		(net "M_H_CPU0_SA_DQ<18>")
	)
	(segment
		(start 462.073752 -296.514774)
		(end 462.32572 -296.766742)
		(width 0.20066)
		(layer "F.Cu")
		(net "M_H_CPU0_SA_DQ<18>")
	)
	(segment
		(start 458.550264 -297.191684)
		(end 460.558134 -297.191684)
		(width 0.1016)
		(layer "F.Cu")
		(net "M_H_CPU0_SA_DQ<18>")
	)
	(segment
		(start 460.558134 -297.191684)
		(end 460.570326 -297.203876)
		(width 0.1016)
		(layer "F.Cu")
		(net "M_H_CPU0_SA_DQ<18>")
	)
	(segment
		(start 455.011282 -296.766742)
		(end 456.116182 -296.766742)
		(width 0.20066)
		(layer "F.Cu")
		(net "M_H_CPU0_SA_DQ<18>")
	)
	(segment
		(start 373.600218 -272.14957)
		(end 373.599964 -272.14957)
		(width 0.088646)
		(layer "In11.Cu")
		(net "M_H_CPU0_SA_DQ<18>")
	)
	(segment
		(start 442.25464 -301.502826)
		(end 441.147708 -301.502826)
		(width 0.18288)
		(layer "In11.Cu")
		(net "M_H_CPU0_SA_DQ<18>")
	)
	(segment
		(start 373.984774 -272.143474)
		(end 373.97436 -272.14957)
		(width 0.088646)
		(layer "In11.Cu")
		(net "M_H_CPU0_SA_DQ<18>")
	)
	(segment
		(start 377.359418 -275.405088)
		(end 377.350528 -275.400008)
		(width 0.088646)
		(layer "In11.Cu")
		(net "M_H_CPU0_SA_DQ<18>")
	)
	(segment
		(start 381.503174 -275.398992)
		(end 381.49276 -275.405088)
		(width 0.088646)
		(layer "In11.Cu")
		(net "M_H_CPU0_SA_DQ<18>")
	)
	(segment
		(start 435.101746 -301.442374)
		(end 433.971446 -301.702724)
		(width 0.18288)
		(layer "In11.Cu")
		(net "M_H_CPU0_SA_DQ<18>")
	)
	(segment
		(start 404.758652 -297.272456)
		(end 398.230852 -290.744656)
		(width 0.18288)
		(layer "In11.Cu")
		(net "M_H_CPU0_SA_DQ<18>")
	)
	(segment
		(start 376.89536 -274.594828)
		(end 376.889264 -274.591272)
		(width 0.088646)
		(layer "In11.Cu")
		(net "M_H_CPU0_SA_DQ<18>")
	)
	(segment
		(start 431.670968 -301.375826)
		(end 430.342548 -301.375826)
		(width 0.18288)
		(layer "In11.Cu")
		(net "M_H_CPU0_SA_DQ<18>")
	)
	(segment
		(start 432.672236 -301.702724)
		(end 431.670968 -301.375826)
		(width 0.18288)
		(layer "In11.Cu")
		(net "M_H_CPU0_SA_DQ<18>")
	)
	(segment
		(start 420.038784 -303.208182)
		(end 419.717728 -302.887126)
		(width 0.18288)
		(layer "In11.Cu")
		(net "M_H_CPU0_SA_DQ<18>")
	)
	(segment
		(start 455.011282 -296.766742)
		(end 454.985882 -296.766742)
		(width 0.18288)
		(layer "In11.Cu")
		(net "M_H_CPU0_SA_DQ<18>")
	)
	(segment
		(start 409.270708 -299.742352)
		(end 408.534108 -299.005752)
		(width 0.18288)
		(layer "In11.Cu")
		(net "M_H_CPU0_SA_DQ<18>")
	)
	(segment
		(start 440.355482 -302.941736)
		(end 440.154822 -303.142396)
		(width 0.18288)
		(layer "In11.Cu")
		(net "M_H_CPU0_SA_DQ<18>")
	)
	(segment
		(start 375.95556 -272.967196)
		(end 375.949464 -272.96364)
		(width 0.088646)
		(layer "In11.Cu")
		(net "M_H_CPU0_SA_DQ<18>")
	)
	(segment
		(start 398.230852 -288.872422)
		(end 390.090406 -280.731976)
		(width 0.18288)
		(layer "In11.Cu")
		(net "M_H_CPU0_SA_DQ<18>")
	)
	(segment
		(start 413.782764 -301.159926)
		(end 410.851604 -300.072298)
		(width 0.18288)
		(layer "In11.Cu")
		(net "M_H_CPU0_SA_DQ<18>")
	)
	(segment
		(start 421.936164 -303.143412)
		(end 421.085518 -303.994058)
		(width 0.18288)
		(layer "In11.Cu")
		(net "M_H_CPU0_SA_DQ<18>")
	)
	(segment
		(start 437.106568 -301.855378)
		(end 436.370984 -301.442374)
		(width 0.18288)
		(layer "In11.Cu")
		(net "M_H_CPU0_SA_DQ<18>")
	)
	(segment
		(start 449.133722 -296.57421)
		(end 447.608706 -298.099226)
		(width 0.18288)
		(layer "In11.Cu")
		(net "M_H_CPU0_SA_DQ<18>")
	)
	(segment
		(start 387.570726 -277.9649)
		(end 387.192266 -277.58644)
		(width 0.088646)
		(layer "In11.Cu")
		(net "M_H_CPU0_SA_DQ<18>")
	)
	(segment
		(start 398.230852 -290.744656)
		(end 398.230852 -288.872422)
		(width 0.18288)
		(layer "In11.Cu")
		(net "M_H_CPU0_SA_DQ<18>")
	)
	(segment
		(start 376.419618 -273.777456)
		(end 376.410728 -273.772376)
		(width 0.088646)
		(layer "In11.Cu")
		(net "M_H_CPU0_SA_DQ<18>")
	)
	(segment
		(start 433.971446 -301.702724)
		(end 432.672236 -301.702724)
		(width 0.18288)
		(layer "In11.Cu")
		(net "M_H_CPU0_SA_DQ<18>")
	)
	(segment
		(start 384.472942 -275.495004)
		(end 384.054858 -275.495004)
		(width 0.088646)
		(layer "In11.Cu")
		(net "M_H_CPU0_SA_DQ<18>")
	)
	(segment
		(start 378.688346 -275.396452)
		(end 378.673614 -275.405088)
		(width 0.088646)
		(layer "In11.Cu")
		(net "M_H_CPU0_SA_DQ<18>")
	)
	(segment
		(start 447.608706 -298.099226)
		(end 446.610994 -298.099226)
		(width 0.18288)
		(layer "In11.Cu")
		(net "M_H_CPU0_SA_DQ<18>")
	)
	(segment
		(start 452.678038 -297.431714)
		(end 452.438516 -297.192192)
		(width 0.18288)
		(layer "In11.Cu")
		(net "M_H_CPU0_SA_DQ<18>")
	)
	(segment
		(start 428.028608 -302.444404)
		(end 427.065694 -302.444404)
		(width 0.18288)
		(layer "In11.Cu")
		(net "M_H_CPU0_SA_DQ<18>")
	)
	(segment
		(start 417.815014 -301.601886)
		(end 416.146234 -301.601886)
		(width 0.18288)
		(layer "In11.Cu")
		(net "M_H_CPU0_SA_DQ<18>")
	)
	(segment
		(start 387.192266 -277.58644)
		(end 387.192266 -277.303484)
		(width 0.088646)
		(layer "In11.Cu")
		(net "M_H_CPU0_SA_DQ<18>")
	)
	(segment
		(start 421.085518 -303.994058)
		(end 420.234872 -303.994058)
		(width 0.18288)
		(layer "In11.Cu")
		(net "M_H_CPU0_SA_DQ<18>")
	)
	(segment
		(start 380.563628 -275.398992)
		(end 380.553214 -275.405088)
		(width 0.088646)
		(layer "In11.Cu")
		(net "M_H_CPU0_SA_DQ<18>")
	)
	(segment
		(start 408.534108 -299.005752)
		(end 407.37536 -299.005752)
		(width 0.18288)
		(layer "In11.Cu")
		(net "M_H_CPU0_SA_DQ<18>")
	)
	(segment
		(start 374.929146 -272.140934)
		(end 374.914414 -272.14957)
		(width 0.088646)
		(layer "In11.Cu")
		(net "M_H_CPU0_SA_DQ<18>")
	)
	(segment
		(start 449.979796 -296.57421)
		(end 449.133722 -296.57421)
		(width 0.18288)
		(layer "In11.Cu")
		(net "M_H_CPU0_SA_DQ<18>")
	)
	(segment
		(start 436.370984 -301.442374)
		(end 435.101746 -301.442374)
		(width 0.18288)
		(layer "In11.Cu")
		(net "M_H_CPU0_SA_DQ<18>")
	)
	(segment
		(start 450.597778 -297.192192)
		(end 449.979796 -296.57421)
		(width 0.18288)
		(layer "In11.Cu")
		(net "M_H_CPU0_SA_DQ<18>")
	)
	(segment
		(start 372.477538 -271.882362)
		(end 372.534688 -271.825212)
		(width 0.088646)
		(layer "In11.Cu")
		(net "M_H_CPU0_SA_DQ<18>")
	)
	(segment
		(start 407.37536 -299.005752)
		(end 406.953974 -298.584366)
		(width 0.18288)
		(layer "In11.Cu")
		(net "M_H_CPU0_SA_DQ<18>")
	)
	(segment
		(start 390.090406 -280.731976)
		(end 390.090406 -280.48458)
		(width 0.18288)
		(layer "In11.Cu")
		(net "M_H_CPU0_SA_DQ<18>")
	)
	(segment
		(start 452.438516 -297.192192)
		(end 450.597778 -297.192192)
		(width 0.18288)
		(layer "In11.Cu")
		(net "M_H_CPU0_SA_DQ<18>")
	)
	(segment
		(start 410.521658 -299.742352)
		(end 409.270708 -299.742352)
		(width 0.18288)
		(layer "In11.Cu")
		(net "M_H_CPU0_SA_DQ<18>")
	)
	(segment
		(start 427.065694 -302.444404)
		(end 425.378118 -303.143412)
		(width 0.18288)
		(layer "In11.Cu")
		(net "M_H_CPU0_SA_DQ<18>")
	)
	(segment
		(start 429.824896 -301.68596)
		(end 428.028608 -302.444404)
		(width 0.18288)
		(layer "In11.Cu")
		(net "M_H_CPU0_SA_DQ<18>")
	)
	(segment
		(start 443.502542 -300.68012)
		(end 443.077346 -300.68012)
		(width 0.18288)
		(layer "In11.Cu")
		(net "M_H_CPU0_SA_DQ<18>")
	)
	(segment
		(start 379.628146 -275.396452)
		(end 379.613414 -275.405088)
		(width 0.088646)
		(layer "In11.Cu")
		(net "M_H_CPU0_SA_DQ<18>")
	)
	(segment
		(start 372.534688 -271.825212)
		(end 372.847616 -271.825212)
		(width 0.088646)
		(layer "In11.Cu")
		(net "M_H_CPU0_SA_DQ<18>")
	)
	(segment
		(start 383.387346 -275.396706)
		(end 383.372614 -275.405342)
		(width 0.088646)
		(layer "In11.Cu")
		(net "M_H_CPU0_SA_DQ<18>")
	)
	(segment
		(start 410.851604 -300.072298)
		(end 410.521658 -299.742352)
		(width 0.18288)
		(layer "In11.Cu")
		(net "M_H_CPU0_SA_DQ<18>")
	)
	(segment
		(start 375.949464 -272.96364)
		(end 375.940574 -272.95856)
		(width 0.088646)
		(layer "In11.Cu")
		(net "M_H_CPU0_SA_DQ<18>")
	)
	(segment
		(start 377.748546 -275.396452)
		(end 377.733814 -275.405088)
		(width 0.088646)
		(layer "In11.Cu")
		(net "M_H_CPU0_SA_DQ<18>")
	)
	(segment
		(start 454.32091 -297.431714)
		(end 452.678038 -297.431714)
		(width 0.18288)
		(layer "In11.Cu")
		(net "M_H_CPU0_SA_DQ<18>")
	)
	(segment
		(start 376.701812 -274.266914)
		(end 376.701812 -274.25142)
		(width 0.088646)
		(layer "In11.Cu")
		(net "M_H_CPU0_SA_DQ<18>")
	)
	(segment
		(start 438.393586 -303.142396)
		(end 437.106568 -301.855378)
		(width 0.18288)
		(layer "In11.Cu")
		(net "M_H_CPU0_SA_DQ<18>")
	)
	(segment
		(start 445.169036 -299.013626)
		(end 443.502542 -300.68012)
		(width 0.18288)
		(layer "In11.Cu")
		(net "M_H_CPU0_SA_DQ<18>")
	)
	(segment
		(start 420.038784 -303.79797)
		(end 420.038784 -303.208182)
		(width 0.18288)
		(layer "In11.Cu")
		(net "M_H_CPU0_SA_DQ<18>")
	)
	(segment
		(start 415.894774 -301.350426)
		(end 414.724342 -301.350426)
		(width 0.18288)
		(layer "In11.Cu")
		(net "M_H_CPU0_SA_DQ<18>")
	)
	(segment
		(start 406.953974 -298.584366)
		(end 406.953974 -298.224194)
		(width 0.18288)
		(layer "In11.Cu")
		(net "M_H_CPU0_SA_DQ<18>")
	)
	(segment
		(start 440.355482 -302.295052)
		(end 440.355482 -302.941736)
		(width 0.18288)
		(layer "In11.Cu")
		(net "M_H_CPU0_SA_DQ<18>")
	)
	(segment
		(start 440.154822 -303.142396)
		(end 438.393586 -303.142396)
		(width 0.18288)
		(layer "In11.Cu")
		(net "M_H_CPU0_SA_DQ<18>")
	)
	(segment
		(start 416.146234 -301.601886)
		(end 415.894774 -301.350426)
		(width 0.18288)
		(layer "In11.Cu")
		(net "M_H_CPU0_SA_DQ<18>")
	)
	(segment
		(start 385.779264 -276.801326)
		(end 384.472942 -275.495004)
		(width 0.088646)
		(layer "In11.Cu")
		(net "M_H_CPU0_SA_DQ<18>")
	)
	(segment
		(start 406.002236 -297.272456)
		(end 404.758652 -297.272456)
		(width 0.18288)
		(layer "In11.Cu")
		(net "M_H_CPU0_SA_DQ<18>")
	)
	(segment
		(start 430.342548 -301.375826)
		(end 429.824896 -301.68596)
		(width 0.18288)
		(layer "In11.Cu")
		(net "M_H_CPU0_SA_DQ<18>")
	)
	(segment
		(start 419.100254 -302.887126)
		(end 417.815014 -301.601886)
		(width 0.18288)
		(layer "In11.Cu")
		(net "M_H_CPU0_SA_DQ<18>")
	)
	(segment
		(start 443.077346 -300.68012)
		(end 442.25464 -301.502826)
		(width 0.18288)
		(layer "In11.Cu")
		(net "M_H_CPU0_SA_DQ<18>")
	)
	(segment
		(start 372.660418 -272.14957)
		(end 372.651528 -272.14449)
		(width 0.088646)
		(layer "In11.Cu")
		(net "M_H_CPU0_SA_DQ<18>")
	)
	(segment
		(start 425.378118 -303.143412)
		(end 421.936164 -303.143412)
		(width 0.18288)
		(layer "In11.Cu")
		(net "M_H_CPU0_SA_DQ<18>")
	)
	(segment
		(start 386.690108 -276.801326)
		(end 385.779264 -276.801326)
		(width 0.088646)
		(layer "In11.Cu")
		(net "M_H_CPU0_SA_DQ<18>")
	)
	(segment
		(start 376.889264 -274.591272)
		(end 376.880374 -274.586192)
		(width 0.088646)
		(layer "In11.Cu")
		(net "M_H_CPU0_SA_DQ<18>")
	)
	(segment
		(start 406.953974 -298.224194)
		(end 406.002236 -297.272456)
		(width 0.18288)
		(layer "In11.Cu")
		(net "M_H_CPU0_SA_DQ<18>")
	)
	(segment
		(start 375.762012 -272.639282)
		(end 375.762012 -272.63852)
		(width 0.088646)
		(layer "In11.Cu")
		(net "M_H_CPU0_SA_DQ<18>")
	)
	(segment
		(start 382.438402 -275.401786)
		(end 382.432814 -275.405088)
		(width 0.088646)
		(layer "In11.Cu")
		(net "M_H_CPU0_SA_DQ<18>")
	)
	(segment
		(start 373.599964 -272.14957)
		(end 373.58955 -272.143474)
		(width 0.088646)
		(layer "In11.Cu")
		(net "M_H_CPU0_SA_DQ<18>")
	)
	(segment
		(start 446.610994 -298.099226)
		(end 445.696594 -299.013626)
		(width 0.18288)
		(layer "In11.Cu")
		(net "M_H_CPU0_SA_DQ<18>")
	)
	(segment
		(start 390.090406 -280.48458)
		(end 387.570726 -277.9649)
		(width 0.18288)
		(layer "In11.Cu")
		(net "M_H_CPU0_SA_DQ<18>")
	)
	(segment
		(start 419.717728 -302.887126)
		(end 419.100254 -302.887126)
		(width 0.18288)
		(layer "In11.Cu")
		(net "M_H_CPU0_SA_DQ<18>")
	)
	(segment
		(start 441.147708 -301.502826)
		(end 440.355482 -302.295052)
		(width 0.18288)
		(layer "In11.Cu")
		(net "M_H_CPU0_SA_DQ<18>")
	)
	(segment
		(start 445.696594 -299.013626)
		(end 445.169036 -299.013626)
		(width 0.18288)
		(layer "In11.Cu")
		(net "M_H_CPU0_SA_DQ<18>")
	)
	(segment
		(start 454.985882 -296.766742)
		(end 454.32091 -297.431714)
		(width 0.18288)
		(layer "In11.Cu")
		(net "M_H_CPU0_SA_DQ<18>")
	)
	(segment
		(start 420.234872 -303.994058)
		(end 420.038784 -303.79797)
		(width 0.18288)
		(layer "In11.Cu")
		(net "M_H_CPU0_SA_DQ<18>")
	)
	(segment
		(start 387.192266 -277.303484)
		(end 386.690108 -276.801326)
		(width 0.088646)
		(layer "In11.Cu")
		(net "M_H_CPU0_SA_DQ<18>")
	)
	(segment
		(start 414.724342 -301.350426)
		(end 413.782764 -301.159926)
		(width 0.18288)
		(layer "In11.Cu")
		(net "M_H_CPU0_SA_DQ<18>")
	)
	(arc
		(start 380.178818 -275.405088)
		(mid 379.904589 -275.329163)
		(end 379.628146 -275.396452)
		(width 0.088646)
		(layer "In11.Cu")
		(net "M_H_CPU0_SA_DQ<18>")
	)
	(arc
		(start 375.940574 -272.95856)
		(mid 375.80966 -272.8222)
		(end 375.762012 -272.639282)
		(width 0.088646)
		(layer "In11.Cu")
		(net "M_H_CPU0_SA_DQ<18>")
	)
	(arc
		(start 379.239018 -275.405088)
		(mid 378.964789 -275.329163)
		(end 378.688346 -275.396452)
		(width 0.088646)
		(layer "In11.Cu")
		(net "M_H_CPU0_SA_DQ<18>")
	)
	(arc
		(start 382.058418 -275.405088)
		(mid 381.781605 -275.329252)
		(end 381.503174 -275.398992)
		(width 0.088646)
		(layer "In11.Cu")
		(net "M_H_CPU0_SA_DQ<18>")
	)
	(arc
		(start 380.553214 -275.405088)
		(mid 380.366016 -275.455231)
		(end 380.178818 -275.405088)
		(width 0.088646)
		(layer "In11.Cu")
		(net "M_H_CPU0_SA_DQ<18>")
	)
	(arc
		(start 373.97436 -272.14957)
		(mid 373.787306 -272.19962)
		(end 373.600218 -272.14957)
		(width 0.088646)
		(layer "In11.Cu")
		(net "M_H_CPU0_SA_DQ<18>")
	)
	(arc
		(start 375.762012 -272.63852)
		(mid 375.686397 -272.356256)
		(end 375.479818 -272.14957)
		(width 0.088646)
		(layer "In11.Cu")
		(net "M_H_CPU0_SA_DQ<18>")
	)
	(arc
		(start 378.299218 -275.405088)
		(mid 378.024989 -275.329163)
		(end 377.748546 -275.396452)
		(width 0.088646)
		(layer "In11.Cu")
		(net "M_H_CPU0_SA_DQ<18>")
	)
	(arc
		(start 376.410728 -273.772376)
		(mid 376.279814 -273.636016)
		(end 376.232166 -273.453098)
		(width 0.088646)
		(layer "In11.Cu")
		(net "M_H_CPU0_SA_DQ<18>")
	)
	(arc
		(start 382.998218 -275.405342)
		(mid 382.71879 -275.32945)
		(end 382.438402 -275.401786)
		(width 0.088646)
		(layer "In11.Cu")
		(net "M_H_CPU0_SA_DQ<18>")
	)
	(arc
		(start 379.613414 -275.405088)
		(mid 379.426216 -275.455231)
		(end 379.239018 -275.405088)
		(width 0.088646)
		(layer "In11.Cu")
		(net "M_H_CPU0_SA_DQ<18>")
	)
	(arc
		(start 377.171966 -275.08073)
		(mid 377.097975 -274.801164)
		(end 376.89536 -274.594828)
		(width 0.088646)
		(layer "In11.Cu")
		(net "M_H_CPU0_SA_DQ<18>")
	)
	(arc
		(start 373.58955 -272.143474)
		(mid 373.311372 -272.073782)
		(end 373.034814 -272.14957)
		(width 0.088646)
		(layer "In11.Cu")
		(net "M_H_CPU0_SA_DQ<18>")
	)
	(arc
		(start 374.914414 -272.14957)
		(mid 374.727216 -272.199713)
		(end 374.540018 -272.14957)
		(width 0.088646)
		(layer "In11.Cu")
		(net "M_H_CPU0_SA_DQ<18>")
	)
	(arc
		(start 384.054858 -275.495004)
		(mid 383.737378 -275.335427)
		(end 383.387346 -275.396706)
		(width 0.088646)
		(layer "In11.Cu")
		(net "M_H_CPU0_SA_DQ<18>")
	)
	(arc
		(start 372.651528 -272.14449)
		(mid 372.535719 -272.032561)
		(end 372.477538 -271.882362)
		(width 0.088646)
		(layer "In11.Cu")
		(net "M_H_CPU0_SA_DQ<18>")
	)
	(arc
		(start 373.034814 -272.14957)
		(mid 372.847616 -272.199713)
		(end 372.660418 -272.14957)
		(width 0.088646)
		(layer "In11.Cu")
		(net "M_H_CPU0_SA_DQ<18>")
	)
	(arc
		(start 382.432814 -275.405088)
		(mid 382.245616 -275.455231)
		(end 382.058418 -275.405088)
		(width 0.088646)
		(layer "In11.Cu")
		(net "M_H_CPU0_SA_DQ<18>")
	)
	(arc
		(start 378.673614 -275.405088)
		(mid 378.486416 -275.455231)
		(end 378.299218 -275.405088)
		(width 0.088646)
		(layer "In11.Cu")
		(net "M_H_CPU0_SA_DQ<18>")
	)
	(arc
		(start 376.701812 -274.25142)
		(mid 376.622442 -273.977686)
		(end 376.419618 -273.777456)
		(width 0.088646)
		(layer "In11.Cu")
		(net "M_H_CPU0_SA_DQ<18>")
	)
	(arc
		(start 381.49276 -275.405088)
		(mid 381.305562 -275.455231)
		(end 381.118364 -275.405088)
		(width 0.088646)
		(layer "In11.Cu")
		(net "M_H_CPU0_SA_DQ<18>")
	)
	(arc
		(start 374.540018 -272.14957)
		(mid 374.263205 -272.073734)
		(end 373.984774 -272.143474)
		(width 0.088646)
		(layer "In11.Cu")
		(net "M_H_CPU0_SA_DQ<18>")
	)
	(arc
		(start 377.350528 -275.400008)
		(mid 377.219614 -275.263648)
		(end 377.171966 -275.08073)
		(width 0.088646)
		(layer "In11.Cu")
		(net "M_H_CPU0_SA_DQ<18>")
	)
	(arc
		(start 376.232166 -273.453098)
		(mid 376.158175 -273.173532)
		(end 375.95556 -272.967196)
		(width 0.088646)
		(layer "In11.Cu")
		(net "M_H_CPU0_SA_DQ<18>")
	)
	(arc
		(start 377.733814 -275.405088)
		(mid 377.546616 -275.455231)
		(end 377.359418 -275.405088)
		(width 0.088646)
		(layer "In11.Cu")
		(net "M_H_CPU0_SA_DQ<18>")
	)
	(arc
		(start 381.118364 -275.405088)
		(mid 380.841805 -275.329379)
		(end 380.563628 -275.398992)
		(width 0.088646)
		(layer "In11.Cu")
		(net "M_H_CPU0_SA_DQ<18>")
	)
	(arc
		(start 383.372614 -275.405342)
		(mid 383.185416 -275.455485)
		(end 382.998218 -275.405342)
		(width 0.088646)
		(layer "In11.Cu")
		(net "M_H_CPU0_SA_DQ<18>")
	)
	(arc
		(start 376.880374 -274.586192)
		(mid 376.74946 -274.449832)
		(end 376.701812 -274.266914)
		(width 0.088646)
		(layer "In11.Cu")
		(net "M_H_CPU0_SA_DQ<18>")
	)
	(arc
		(start 375.479818 -272.14957)
		(mid 375.205589 -272.073645)
		(end 374.929146 -272.140934)
		(width 0.088646)
		(layer "In11.Cu")
		(net "M_H_CPU0_SA_DQ<18>")
	)
	(segment
		(start 454.566782 -295.491662)
		(end 454.448672 -295.609772)
		(width 0.20066)
		(layer "F.Cu")
		(net "M_H_CPU0_SA_DQ<17>")
	)
	(segment
		(start 457.126594 -295.485312)
		(end 457.120244 -295.491662)
		(width 0.1016)
		(layer "F.Cu")
		(net "M_H_CPU0_SA_DQ<17>")
	)
	(segment
		(start 454.91146 -295.491662)
		(end 454.566782 -295.491662)
		(width 0.20066)
		(layer "F.Cu")
		(net "M_H_CPU0_SA_DQ<17>")
	)
	(segment
		(start 454.260712 -296.16527)
		(end 453.785478 -296.16527)
		(width 0.20066)
		(layer "F.Cu")
		(net "M_H_CPU0_SA_DQ<17>")
	)
	(segment
		(start 459.559914 -295.916604)
		(end 459.55966 -295.916858)
		(width 0.20066)
		(layer "F.Cu")
		(net "M_H_CPU0_SA_DQ<17>")
	)
	(segment
		(start 454.448672 -295.609772)
		(end 454.448672 -295.97731)
		(width 0.20066)
		(layer "F.Cu")
		(net "M_H_CPU0_SA_DQ<17>")
	)
	(segment
		(start 454.931526 -295.491662)
		(end 454.91146 -295.491662)
		(width 0.101854)
		(layer "F.Cu")
		(net "M_H_CPU0_SA_DQ<17>")
	)
	(segment
		(start 454.448672 -295.97731)
		(end 454.260712 -296.16527)
		(width 0.20066)
		(layer "F.Cu")
		(net "M_H_CPU0_SA_DQ<17>")
	)
	(segment
		(start 459.55966 -295.916858)
		(end 457.968096 -295.916858)
		(width 0.20066)
		(layer "F.Cu")
		(net "M_H_CPU0_SA_DQ<17>")
	)
	(segment
		(start 453.536812 -295.916604)
		(end 452.016114 -295.916604)
		(width 0.20066)
		(layer "F.Cu")
		(net "M_H_CPU0_SA_DQ<17>")
	)
	(segment
		(start 457.53655 -295.485312)
		(end 457.126594 -295.485312)
		(width 0.20066)
		(layer "F.Cu")
		(net "M_H_CPU0_SA_DQ<17>")
	)
	(segment
		(start 452.016114 -295.916604)
		(end 450.911214 -295.916604)
		(width 0.20066)
		(layer "F.Cu")
		(net "M_H_CPU0_SA_DQ<17>")
	)
	(segment
		(start 457.968096 -295.916858)
		(end 457.53655 -295.485312)
		(width 0.20066)
		(layer "F.Cu")
		(net "M_H_CPU0_SA_DQ<17>")
	)
	(segment
		(start 453.785478 -296.16527)
		(end 453.536812 -295.916604)
		(width 0.20066)
		(layer "F.Cu")
		(net "M_H_CPU0_SA_DQ<17>")
	)
	(segment
		(start 457.120244 -295.491662)
		(end 454.931526 -295.491662)
		(width 0.1016)
		(layer "F.Cu")
		(net "M_H_CPU0_SA_DQ<17>")
	)
	(segment
		(start 371.437916 -271.011142)
		(end 371.437662 -271.011396)
		(width 0.20066)
		(layer "F.Cu")
		(net "M_H_CPU0_SA_DQ<17>")
	)
	(segment
		(start 371.437916 -270.475456)
		(end 371.437916 -271.011142)
		(width 0.20066)
		(layer "F.Cu")
		(net "M_H_CPU0_SA_DQ<17>")
	)
	(segment
		(start 398.755108 -290.536884)
		(end 398.755108 -288.677858)
		(width 0.18288)
		(layer "In11.Cu")
		(net "M_H_CPU0_SA_DQ<17>")
	)
	(segment
		(start 372.74754 -271.423892)
		(end 372.232682 -271.423892)
		(width 0.088646)
		(layer "In11.Cu")
		(net "M_H_CPU0_SA_DQ<17>")
	)
	(segment
		(start 381.118364 -274.756372)
		(end 381.10795 -274.762468)
		(width 0.088646)
		(layer "In11.Cu")
		(net "M_H_CPU0_SA_DQ<17>")
	)
	(segment
		(start 373.984774 -271.50695)
		(end 373.97436 -271.500854)
		(width 0.088646)
		(layer "In11.Cu")
		(net "M_H_CPU0_SA_DQ<17>")
	)
	(segment
		(start 450.412358 -296.00779)
		(end 449.888102 -295.483534)
		(width 0.18288)
		(layer "In11.Cu")
		(net "M_H_CPU0_SA_DQ<17>")
	)
	(segment
		(start 438.607454 -301.95139)
		(end 438.607454 -301.578264)
		(width 0.18288)
		(layer "In11.Cu")
		(net "M_H_CPU0_SA_DQ<17>")
	)
	(segment
		(start 373.97436 -271.500854)
		(end 373.973852 -271.5006)
		(width 0.088646)
		(layer "In11.Cu")
		(net "M_H_CPU0_SA_DQ<17>")
	)
	(segment
		(start 378.688346 -274.765008)
		(end 378.673614 -274.756372)
		(width 0.088646)
		(layer "In11.Cu")
		(net "M_H_CPU0_SA_DQ<17>")
	)
	(segment
		(start 373.605806 -271.497552)
		(end 373.599964 -271.500854)
		(width 0.088646)
		(layer "In11.Cu")
		(net "M_H_CPU0_SA_DQ<17>")
	)
	(segment
		(start 413.16021 -299.674026)
		(end 412.511494 -299.674026)
		(width 0.18288)
		(layer "In11.Cu")
		(net "M_H_CPU0_SA_DQ<17>")
	)
	(segment
		(start 433.244752 -300.985682)
		(end 433.244752 -300.603666)
		(width 0.18288)
		(layer "In11.Cu")
		(net "M_H_CPU0_SA_DQ<17>")
	)
	(segment
		(start 377.921266 -273.468592)
		(end 377.921266 -273.453098)
		(width 0.088646)
		(layer "In11.Cu")
		(net "M_H_CPU0_SA_DQ<17>")
	)
	(segment
		(start 390.555226 -280.477976)
		(end 390.555226 -280.282396)
		(width 0.18288)
		(layer "In11.Cu")
		(net "M_H_CPU0_SA_DQ<17>")
	)
	(segment
		(start 379.628146 -274.765008)
		(end 379.613414 -274.756372)
		(width 0.088646)
		(layer "In11.Cu")
		(net "M_H_CPU0_SA_DQ<17>")
	)
	(segment
		(start 433.244752 -300.603666)
		(end 433.051712 -300.410626)
		(width 0.18288)
		(layer "In11.Cu")
		(net "M_H_CPU0_SA_DQ<17>")
	)
	(segment
		(start 378.21235 -273.947636)
		(end 378.20346 -273.942556)
		(width 0.088646)
		(layer "In11.Cu")
		(net "M_H_CPU0_SA_DQ<17>")
	)
	(segment
		(start 450.911214 -295.916604)
		(end 450.820028 -296.00779)
		(width 0.18288)
		(layer "In11.Cu")
		(net "M_H_CPU0_SA_DQ<17>")
	)
	(segment
		(start 449.429886 -295.483534)
		(end 447.906394 -297.007026)
		(width 0.18288)
		(layer "In11.Cu")
		(net "M_H_CPU0_SA_DQ<17>")
	)
	(segment
		(start 447.906394 -297.007026)
		(end 446.966594 -297.007026)
		(width 0.18288)
		(layer "In11.Cu")
		(net "M_H_CPU0_SA_DQ<17>")
	)
	(segment
		(start 375.863104 -271.505934)
		(end 375.854214 -271.500854)
		(width 0.088646)
		(layer "In11.Cu")
		(net "M_H_CPU0_SA_DQ<17>")
	)
	(segment
		(start 433.437792 -301.178722)
		(end 433.244752 -300.985682)
		(width 0.18288)
		(layer "In11.Cu")
		(net "M_H_CPU0_SA_DQ<17>")
	)
	(segment
		(start 405.964644 -296.299128)
		(end 404.517352 -296.299128)
		(width 0.18288)
		(layer "In11.Cu")
		(net "M_H_CPU0_SA_DQ<17>")
	)
	(segment
		(start 433.051712 -300.410626)
		(end 431.815494 -300.410626)
		(width 0.18288)
		(layer "In11.Cu")
		(net "M_H_CPU0_SA_DQ<17>")
	)
	(segment
		(start 415.028634 -300.447964)
		(end 414.666176 -300.297596)
		(width 0.18288)
		(layer "In11.Cu")
		(net "M_H_CPU0_SA_DQ<17>")
	)
	(segment
		(start 404.517352 -296.299128)
		(end 398.755108 -290.536884)
		(width 0.18288)
		(layer "In11.Cu")
		(net "M_H_CPU0_SA_DQ<17>")
	)
	(segment
		(start 421.527986 -302.292004)
		(end 419.345872 -302.292004)
		(width 0.18288)
		(layer "In11.Cu")
		(net "M_H_CPU0_SA_DQ<17>")
	)
	(segment
		(start 431.815494 -300.410626)
		(end 431.586894 -300.639226)
		(width 0.18288)
		(layer "In11.Cu")
		(net "M_H_CPU0_SA_DQ<17>")
	)
	(segment
		(start 412.357062 -299.828458)
		(end 411.834838 -299.828458)
		(width 0.18288)
		(layer "In11.Cu")
		(net "M_H_CPU0_SA_DQ<17>")
	)
	(segment
		(start 417.505388 -300.45152)
		(end 416.179 -300.45152)
		(width 0.18288)
		(layer "In11.Cu")
		(net "M_H_CPU0_SA_DQ<17>")
	)
	(segment
		(start 413.858202 -300.359318)
		(end 413.65932 -299.880782)
		(width 0.18288)
		(layer "In11.Cu")
		(net "M_H_CPU0_SA_DQ<17>")
	)
	(segment
		(start 446.966594 -297.007026)
		(end 446.077594 -297.896026)
		(width 0.18288)
		(layer "In11.Cu")
		(net "M_H_CPU0_SA_DQ<17>")
	)
	(segment
		(start 425.6786 -301.655226)
		(end 425.465494 -301.44212)
		(width 0.18288)
		(layer "In11.Cu")
		(net "M_H_CPU0_SA_DQ<17>")
	)
	(segment
		(start 442.242194 -300.563026)
		(end 441.196476 -300.563026)
		(width 0.18288)
		(layer "In11.Cu")
		(net "M_H_CPU0_SA_DQ<17>")
	)
	(segment
		(start 438.41416 -301.38497)
		(end 437.560974 -301.38497)
		(width 0.18288)
		(layer "In11.Cu")
		(net "M_H_CPU0_SA_DQ<17>")
	)
	(segment
		(start 433.948332 -300.985682)
		(end 433.755292 -301.178722)
		(width 0.18288)
		(layer "In11.Cu")
		(net "M_H_CPU0_SA_DQ<17>")
	)
	(segment
		(start 429.028098 -301.35449)
		(end 427.66996 -301.35449)
		(width 0.18288)
		(layer "In11.Cu")
		(net "M_H_CPU0_SA_DQ<17>")
	)
	(segment
		(start 386.794756 -276.521926)
		(end 386.09651 -276.521926)
		(width 0.088646)
		(layer "In11.Cu")
		(net "M_H_CPU0_SA_DQ<17>")
	)
	(segment
		(start 427.66996 -301.35449)
		(end 427.370494 -301.655226)
		(width 0.18288)
		(layer "In11.Cu")
		(net "M_H_CPU0_SA_DQ<17>")
	)
	(segment
		(start 390.555226 -280.282396)
		(end 387.585966 -277.313136)
		(width 0.18288)
		(layer "In11.Cu")
		(net "M_H_CPU0_SA_DQ<17>")
	)
	(segment
		(start 376.889264 -272.314924)
		(end 376.874532 -272.32356)
		(width 0.088646)
		(layer "In11.Cu")
		(net "M_H_CPU0_SA_DQ<17>")
	)
	(segment
		(start 377.742704 -273.13382)
		(end 377.733814 -273.12874)
		(width 0.088646)
		(layer "In11.Cu")
		(net "M_H_CPU0_SA_DQ<17>")
	)
	(segment
		(start 411.834838 -299.828458)
		(end 410.04871 -298.04233)
		(width 0.18288)
		(layer "In11.Cu")
		(net "M_H_CPU0_SA_DQ<17>")
	)
	(segment
		(start 440.317382 -301.44212)
		(end 439.504074 -301.44212)
		(width 0.18288)
		(layer "In11.Cu")
		(net "M_H_CPU0_SA_DQ<17>")
	)
	(segment
		(start 443.232794 -299.572426)
		(end 442.242194 -300.563026)
		(width 0.18288)
		(layer "In11.Cu")
		(net "M_H_CPU0_SA_DQ<17>")
	)
	(segment
		(start 433.948332 -300.603666)
		(end 433.948332 -300.985682)
		(width 0.18288)
		(layer "In11.Cu")
		(net "M_H_CPU0_SA_DQ<17>")
	)
	(segment
		(start 412.511494 -299.674026)
		(end 412.357062 -299.828458)
		(width 0.18288)
		(layer "In11.Cu")
		(net "M_H_CPU0_SA_DQ<17>")
	)
	(segment
		(start 376.041666 -271.84731)
		(end 376.041666 -271.825212)
		(width 0.088646)
		(layer "In11.Cu")
		(net "M_H_CPU0_SA_DQ<17>")
	)
	(segment
		(start 431.586894 -300.639226)
		(end 429.743362 -300.639226)
		(width 0.18288)
		(layer "In11.Cu")
		(net "M_H_CPU0_SA_DQ<17>")
	)
	(segment
		(start 373.599964 -271.500854)
		(end 373.594122 -271.50441)
		(width 0.088646)
		(layer "In11.Cu")
		(net "M_H_CPU0_SA_DQ<17>")
	)
	(segment
		(start 374.929146 -271.50949)
		(end 374.914668 -271.500854)
		(width 0.088646)
		(layer "In11.Cu")
		(net "M_H_CPU0_SA_DQ<17>")
	)
	(segment
		(start 439.117994 -302.14443)
		(end 438.800494 -302.14443)
		(width 0.18288)
		(layer "In11.Cu")
		(net "M_H_CPU0_SA_DQ<17>")
	)
	(segment
		(start 407.471118 -297.805602)
		(end 405.964644 -296.299128)
		(width 0.18288)
		(layer "In11.Cu")
		(net "M_H_CPU0_SA_DQ<17>")
	)
	(segment
		(start 436.767986 -300.591982)
		(end 435.40045 -300.591982)
		(width 0.18288)
		(layer "In11.Cu")
		(net "M_H_CPU0_SA_DQ<17>")
	)
	(segment
		(start 416.179 -300.45152)
		(end 415.915094 -300.715426)
		(width 0.18288)
		(layer "In11.Cu")
		(net "M_H_CPU0_SA_DQ<17>")
	)
	(segment
		(start 439.311034 -301.95139)
		(end 439.117994 -302.14443)
		(width 0.18288)
		(layer "In11.Cu")
		(net "M_H_CPU0_SA_DQ<17>")
	)
	(segment
		(start 377.733814 -273.12874)
		(end 377.727718 -273.125184)
		(width 0.088646)
		(layer "In11.Cu")
		(net "M_H_CPU0_SA_DQ<17>")
	)
	(segment
		(start 446.077594 -297.896026)
		(end 445.467994 -297.896026)
		(width 0.18288)
		(layer "In11.Cu")
		(net "M_H_CPU0_SA_DQ<17>")
	)
	(segment
		(start 438.607454 -301.578264)
		(end 438.41416 -301.38497)
		(width 0.18288)
		(layer "In11.Cu")
		(net "M_H_CPU0_SA_DQ<17>")
	)
	(segment
		(start 383.387346 -274.765262)
		(end 383.372614 -274.756626)
		(width 0.088646)
		(layer "In11.Cu")
		(net "M_H_CPU0_SA_DQ<17>")
	)
	(segment
		(start 415.296096 -300.715426)
		(end 415.028634 -300.447964)
		(width 0.18288)
		(layer "In11.Cu")
		(net "M_H_CPU0_SA_DQ<17>")
	)
	(segment
		(start 371.473222 -271.011396)
		(end 371.437662 -271.011396)
		(width 0.088646)
		(layer "In11.Cu")
		(net "M_H_CPU0_SA_DQ<17>")
	)
	(segment
		(start 371.720364 -271.258538)
		(end 371.473222 -271.011396)
		(width 0.088646)
		(layer "In11.Cu")
		(net "M_H_CPU0_SA_DQ<17>")
	)
	(segment
		(start 435.219094 -300.410626)
		(end 434.141372 -300.410626)
		(width 0.18288)
		(layer "In11.Cu")
		(net "M_H_CPU0_SA_DQ<17>")
	)
	(segment
		(start 437.560974 -301.38497)
		(end 436.767986 -300.591982)
		(width 0.18288)
		(layer "In11.Cu")
		(net "M_H_CPU0_SA_DQ<17>")
	)
	(segment
		(start 443.791594 -299.572426)
		(end 443.232794 -299.572426)
		(width 0.18288)
		(layer "In11.Cu")
		(net "M_H_CPU0_SA_DQ<17>")
	)
	(segment
		(start 445.467994 -297.896026)
		(end 443.791594 -299.572426)
		(width 0.18288)
		(layer "In11.Cu")
		(net "M_H_CPU0_SA_DQ<17>")
	)
	(segment
		(start 408.56027 -297.805602)
		(end 407.471118 -297.805602)
		(width 0.18288)
		(layer "In11.Cu")
		(net "M_H_CPU0_SA_DQ<17>")
	)
	(segment
		(start 386.09651 -276.521926)
		(end 384.390392 -274.815808)
		(width 0.088646)
		(layer "In11.Cu")
		(net "M_H_CPU0_SA_DQ<17>")
	)
	(segment
		(start 441.196476 -300.563026)
		(end 440.317382 -301.44212)
		(width 0.18288)
		(layer "In11.Cu")
		(net "M_H_CPU0_SA_DQ<17>")
	)
	(segment
		(start 423.986452 -301.2821)
		(end 422.53789 -301.2821)
		(width 0.18288)
		(layer "In11.Cu")
		(net "M_H_CPU0_SA_DQ<17>")
	)
	(segment
		(start 425.465494 -301.44212)
		(end 424.146472 -301.44212)
		(width 0.18288)
		(layer "In11.Cu")
		(net "M_H_CPU0_SA_DQ<17>")
	)
	(segment
		(start 419.345872 -302.292004)
		(end 417.505388 -300.45152)
		(width 0.18288)
		(layer "In11.Cu")
		(net "M_H_CPU0_SA_DQ<17>")
	)
	(segment
		(start 410.04871 -298.04233)
		(end 408.796998 -298.04233)
		(width 0.18288)
		(layer "In11.Cu")
		(net "M_H_CPU0_SA_DQ<17>")
	)
	(segment
		(start 415.915094 -300.715426)
		(end 415.296096 -300.715426)
		(width 0.18288)
		(layer "In11.Cu")
		(net "M_H_CPU0_SA_DQ<17>")
	)
	(segment
		(start 387.585966 -277.313136)
		(end 386.794756 -276.521926)
		(width 0.088646)
		(layer "In11.Cu")
		(net "M_H_CPU0_SA_DQ<17>")
	)
	(segment
		(start 398.755108 -288.677858)
		(end 390.555226 -280.477976)
		(width 0.18288)
		(layer "In11.Cu")
		(net "M_H_CPU0_SA_DQ<17>")
	)
	(segment
		(start 378.673614 -274.756372)
		(end 378.667518 -274.752816)
		(width 0.088646)
		(layer "In11.Cu")
		(net "M_H_CPU0_SA_DQ<17>")
	)
	(segment
		(start 422.53789 -301.2821)
		(end 421.527986 -302.292004)
		(width 0.18288)
		(layer "In11.Cu")
		(net "M_H_CPU0_SA_DQ<17>")
	)
	(segment
		(start 414.187894 -300.496224)
		(end 413.858202 -300.359318)
		(width 0.18288)
		(layer "In11.Cu")
		(net "M_H_CPU0_SA_DQ<17>")
	)
	(segment
		(start 413.65932 -299.880782)
		(end 413.16021 -299.674026)
		(width 0.18288)
		(layer "In11.Cu")
		(net "M_H_CPU0_SA_DQ<17>")
	)
	(segment
		(start 414.666176 -300.297596)
		(end 414.187894 -300.496224)
		(width 0.18288)
		(layer "In11.Cu")
		(net "M_H_CPU0_SA_DQ<17>")
	)
	(segment
		(start 382.45288 -274.768056)
		(end 382.432814 -274.756372)
		(width 0.088646)
		(layer "In11.Cu")
		(net "M_H_CPU0_SA_DQ<17>")
	)
	(segment
		(start 450.820028 -296.00779)
		(end 450.412358 -296.00779)
		(width 0.18288)
		(layer "In11.Cu")
		(net "M_H_CPU0_SA_DQ<17>")
	)
	(segment
		(start 449.888102 -295.483534)
		(end 449.429886 -295.483534)
		(width 0.18288)
		(layer "In11.Cu")
		(net "M_H_CPU0_SA_DQ<17>")
	)
	(segment
		(start 439.311034 -301.63516)
		(end 439.311034 -301.95139)
		(width 0.18288)
		(layer "In11.Cu")
		(net "M_H_CPU0_SA_DQ<17>")
	)
	(segment
		(start 381.503174 -274.762468)
		(end 381.49276 -274.756372)
		(width 0.088646)
		(layer "In11.Cu")
		(net "M_H_CPU0_SA_DQ<17>")
	)
	(segment
		(start 438.800494 -302.14443)
		(end 438.607454 -301.95139)
		(width 0.18288)
		(layer "In11.Cu")
		(net "M_H_CPU0_SA_DQ<17>")
	)
	(segment
		(start 434.141372 -300.410626)
		(end 433.948332 -300.603666)
		(width 0.18288)
		(layer "In11.Cu")
		(net "M_H_CPU0_SA_DQ<17>")
	)
	(segment
		(start 439.504074 -301.44212)
		(end 439.311034 -301.63516)
		(width 0.18288)
		(layer "In11.Cu")
		(net "M_H_CPU0_SA_DQ<17>")
	)
	(segment
		(start 377.27255 -272.320004)
		(end 377.26366 -272.314924)
		(width 0.088646)
		(layer "In11.Cu")
		(net "M_H_CPU0_SA_DQ<17>")
	)
	(segment
		(start 427.370494 -301.655226)
		(end 425.6786 -301.655226)
		(width 0.18288)
		(layer "In11.Cu")
		(net "M_H_CPU0_SA_DQ<17>")
	)
	(segment
		(start 433.755292 -301.178722)
		(end 433.437792 -301.178722)
		(width 0.18288)
		(layer "In11.Cu")
		(net "M_H_CPU0_SA_DQ<17>")
	)
	(segment
		(start 435.40045 -300.591982)
		(end 435.219094 -300.410626)
		(width 0.18288)
		(layer "In11.Cu")
		(net "M_H_CPU0_SA_DQ<17>")
	)
	(segment
		(start 429.743362 -300.639226)
		(end 429.028098 -301.35449)
		(width 0.18288)
		(layer "In11.Cu")
		(net "M_H_CPU0_SA_DQ<17>")
	)
	(segment
		(start 408.796998 -298.04233)
		(end 408.56027 -297.805602)
		(width 0.18288)
		(layer "In11.Cu")
		(net "M_H_CPU0_SA_DQ<17>")
	)
	(segment
		(start 424.146472 -301.44212)
		(end 423.986452 -301.2821)
		(width 0.18288)
		(layer "In11.Cu")
		(net "M_H_CPU0_SA_DQ<17>")
	)
	(arc
		(start 373.594122 -271.50441)
		(mid 373.313987 -271.576693)
		(end 373.034814 -271.500854)
		(width 0.088646)
		(layer "In11.Cu")
		(net "M_H_CPU0_SA_DQ<17>")
	)
	(arc
		(start 381.10795 -274.762468)
		(mid 380.829772 -274.832191)
		(end 380.553214 -274.756372)
		(width 0.088646)
		(layer "In11.Cu")
		(net "M_H_CPU0_SA_DQ<17>")
	)
	(arc
		(start 375.854214 -271.500854)
		(mid 375.667016 -271.450711)
		(end 375.479818 -271.500854)
		(width 0.088646)
		(layer "In11.Cu")
		(net "M_H_CPU0_SA_DQ<17>")
	)
	(arc
		(start 377.26366 -272.314924)
		(mid 377.076462 -272.264781)
		(end 376.889264 -272.314924)
		(width 0.088646)
		(layer "In11.Cu")
		(net "M_H_CPU0_SA_DQ<17>")
	)
	(arc
		(start 377.921266 -273.453098)
		(mid 377.873587 -273.270198)
		(end 377.742704 -273.13382)
		(width 0.088646)
		(layer "In11.Cu")
		(net "M_H_CPU0_SA_DQ<17>")
	)
	(arc
		(start 381.49276 -274.756372)
		(mid 381.305562 -274.706229)
		(end 381.118364 -274.756372)
		(width 0.088646)
		(layer "In11.Cu")
		(net "M_H_CPU0_SA_DQ<17>")
	)
	(arc
		(start 384.390392 -274.815808)
		(mid 384.353342 -274.783662)
		(end 384.312414 -274.756626)
		(width 0.088646)
		(layer "In11.Cu")
		(net "M_H_CPU0_SA_DQ<17>")
	)
	(arc
		(start 384.312414 -274.756626)
		(mid 384.125216 -274.706483)
		(end 383.938018 -274.756626)
		(width 0.088646)
		(layer "In11.Cu")
		(net "M_H_CPU0_SA_DQ<17>")
	)
	(arc
		(start 382.058418 -274.756372)
		(mid 381.781605 -274.832242)
		(end 381.503174 -274.762468)
		(width 0.088646)
		(layer "In11.Cu")
		(net "M_H_CPU0_SA_DQ<17>")
	)
	(arc
		(start 374.540018 -271.500854)
		(mid 374.263205 -271.576724)
		(end 373.984774 -271.50695)
		(width 0.088646)
		(layer "In11.Cu")
		(net "M_H_CPU0_SA_DQ<17>")
	)
	(arc
		(start 371.79123 -271.311878)
		(mid 371.753875 -271.287761)
		(end 371.720364 -271.258538)
		(width 0.088646)
		(layer "In11.Cu")
		(net "M_H_CPU0_SA_DQ<17>")
	)
	(arc
		(start 382.432814 -274.756372)
		(mid 382.245616 -274.706229)
		(end 382.058418 -274.756372)
		(width 0.088646)
		(layer "In11.Cu")
		(net "M_H_CPU0_SA_DQ<17>")
	)
	(arc
		(start 377.451112 -272.639282)
		(mid 377.403433 -272.456382)
		(end 377.27255 -272.320004)
		(width 0.088646)
		(layer "In11.Cu")
		(net "M_H_CPU0_SA_DQ<17>")
	)
	(arc
		(start 378.20346 -273.942556)
		(mid 378.000637 -273.742325)
		(end 377.921266 -273.468592)
		(width 0.088646)
		(layer "In11.Cu")
		(net "M_H_CPU0_SA_DQ<17>")
	)
	(arc
		(start 383.372614 -274.756626)
		(mid 383.185416 -274.706483)
		(end 382.998218 -274.756626)
		(width 0.088646)
		(layer "In11.Cu")
		(net "M_H_CPU0_SA_DQ<17>")
	)
	(arc
		(start 379.613414 -274.756372)
		(mid 379.426216 -274.706229)
		(end 379.239018 -274.756372)
		(width 0.088646)
		(layer "In11.Cu")
		(net "M_H_CPU0_SA_DQ<17>")
	)
	(arc
		(start 382.998218 -274.756626)
		(mid 382.727029 -274.832373)
		(end 382.45288 -274.768056)
		(width 0.088646)
		(layer "In11.Cu")
		(net "M_H_CPU0_SA_DQ<17>")
	)
	(arc
		(start 380.553214 -274.756372)
		(mid 380.366016 -274.706229)
		(end 380.178818 -274.756372)
		(width 0.088646)
		(layer "In11.Cu")
		(net "M_H_CPU0_SA_DQ<17>")
	)
	(arc
		(start 378.390912 -274.266914)
		(mid 378.343233 -274.084014)
		(end 378.21235 -273.947636)
		(width 0.088646)
		(layer "In11.Cu")
		(net "M_H_CPU0_SA_DQ<17>")
	)
	(arc
		(start 372.232682 -271.423892)
		(mid 372.004932 -271.395555)
		(end 371.79123 -271.311878)
		(width 0.088646)
		(layer "In11.Cu")
		(net "M_H_CPU0_SA_DQ<17>")
	)
	(arc
		(start 376.874532 -272.32356)
		(mid 376.598091 -272.390726)
		(end 376.32386 -272.314924)
		(width 0.088646)
		(layer "In11.Cu")
		(net "M_H_CPU0_SA_DQ<17>")
	)
	(arc
		(start 375.479818 -271.500854)
		(mid 375.205619 -271.576689)
		(end 374.929146 -271.50949)
		(width 0.088646)
		(layer "In11.Cu")
		(net "M_H_CPU0_SA_DQ<17>")
	)
	(arc
		(start 376.32386 -272.314924)
		(mid 376.122578 -272.117437)
		(end 376.041666 -271.84731)
		(width 0.088646)
		(layer "In11.Cu")
		(net "M_H_CPU0_SA_DQ<17>")
	)
	(arc
		(start 376.041666 -271.825212)
		(mid 375.993987 -271.642312)
		(end 375.863104 -271.505934)
		(width 0.088646)
		(layer "In11.Cu")
		(net "M_H_CPU0_SA_DQ<17>")
	)
	(arc
		(start 374.914668 -271.500854)
		(mid 374.72736 -271.450711)
		(end 374.540018 -271.500854)
		(width 0.088646)
		(layer "In11.Cu")
		(net "M_H_CPU0_SA_DQ<17>")
	)
	(arc
		(start 380.178818 -274.756372)
		(mid 379.904619 -274.832207)
		(end 379.628146 -274.765008)
		(width 0.088646)
		(layer "In11.Cu")
		(net "M_H_CPU0_SA_DQ<17>")
	)
	(arc
		(start 373.034814 -271.500854)
		(mid 372.896248 -271.443433)
		(end 372.74754 -271.423892)
		(width 0.088646)
		(layer "In11.Cu")
		(net "M_H_CPU0_SA_DQ<17>")
	)
	(arc
		(start 378.667518 -274.752816)
		(mid 378.464931 -274.546465)
		(end 378.390912 -274.266914)
		(width 0.088646)
		(layer "In11.Cu")
		(net "M_H_CPU0_SA_DQ<17>")
	)
	(arc
		(start 373.973852 -271.5006)
		(mid 373.790234 -271.450757)
		(end 373.605806 -271.497552)
		(width 0.088646)
		(layer "In11.Cu")
		(net "M_H_CPU0_SA_DQ<17>")
	)
	(arc
		(start 379.239018 -274.756372)
		(mid 378.964819 -274.832207)
		(end 378.688346 -274.765008)
		(width 0.088646)
		(layer "In11.Cu")
		(net "M_H_CPU0_SA_DQ<17>")
	)
	(arc
		(start 377.727718 -273.125184)
		(mid 377.525131 -272.918833)
		(end 377.451112 -272.639282)
		(width 0.088646)
		(layer "In11.Cu")
		(net "M_H_CPU0_SA_DQ<17>")
	)
	(arc
		(start 383.938018 -274.756626)
		(mid 383.663789 -274.832551)
		(end 383.387346 -274.765262)
		(width 0.088646)
		(layer "In11.Cu")
		(net "M_H_CPU0_SA_DQ<17>")
	)
	(segment
		(start 454.95845 -297.191684)
		(end 454.91146 -297.191684)
		(width 0.101854)
		(layer "F.Cu")
		(net "M_H_CPU0_SA_DQ<16>")
	)
	(segment
		(start 454.566782 -297.191684)
		(end 454.448672 -297.309794)
		(width 0.20066)
		(layer "F.Cu")
		(net "M_H_CPU0_SA_DQ<16>")
	)
	(segment
		(start 454.260712 -297.865292)
		(end 453.785478 -297.865292)
		(width 0.20066)
		(layer "F.Cu")
		(net "M_H_CPU0_SA_DQ<16>")
	)
	(segment
		(start 457.126594 -297.185334)
		(end 457.120244 -297.191684)
		(width 0.1016)
		(layer "F.Cu")
		(net "M_H_CPU0_SA_DQ<16>")
	)
	(segment
		(start 457.120244 -297.191684)
		(end 454.95845 -297.191684)
		(width 0.1016)
		(layer "F.Cu")
		(net "M_H_CPU0_SA_DQ<16>")
	)
	(segment
		(start 454.448672 -297.677332)
		(end 454.260712 -297.865292)
		(width 0.20066)
		(layer "F.Cu")
		(net "M_H_CPU0_SA_DQ<16>")
	)
	(segment
		(start 454.448672 -297.309794)
		(end 454.448672 -297.677332)
		(width 0.20066)
		(layer "F.Cu")
		(net "M_H_CPU0_SA_DQ<16>")
	)
	(segment
		(start 459.559914 -297.616626)
		(end 459.55966 -297.61688)
		(width 0.20066)
		(layer "F.Cu")
		(net "M_H_CPU0_SA_DQ<16>")
	)
	(segment
		(start 454.91146 -297.191684)
		(end 454.566782 -297.191684)
		(width 0.20066)
		(layer "F.Cu")
		(net "M_H_CPU0_SA_DQ<16>")
	)
	(segment
		(start 459.55966 -297.61688)
		(end 457.968096 -297.61688)
		(width 0.20066)
		(layer "F.Cu")
		(net "M_H_CPU0_SA_DQ<16>")
	)
	(segment
		(start 453.536812 -297.616626)
		(end 452.016114 -297.616626)
		(width 0.20066)
		(layer "F.Cu")
		(net "M_H_CPU0_SA_DQ<16>")
	)
	(segment
		(start 452.016114 -297.616626)
		(end 450.911214 -297.616626)
		(width 0.20066)
		(layer "F.Cu")
		(net "M_H_CPU0_SA_DQ<16>")
	)
	(segment
		(start 371.907562 -271.289272)
		(end 371.907816 -271.825212)
		(width 0.20066)
		(layer "F.Cu")
		(net "M_H_CPU0_SA_DQ<16>")
	)
	(segment
		(start 457.53655 -297.185334)
		(end 457.126594 -297.185334)
		(width 0.20066)
		(layer "F.Cu")
		(net "M_H_CPU0_SA_DQ<16>")
	)
	(segment
		(start 457.968096 -297.61688)
		(end 457.53655 -297.185334)
		(width 0.20066)
		(layer "F.Cu")
		(net "M_H_CPU0_SA_DQ<16>")
	)
	(segment
		(start 453.785478 -297.865292)
		(end 453.536812 -297.616626)
		(width 0.20066)
		(layer "F.Cu")
		(net "M_H_CPU0_SA_DQ<16>")
	)
	(segment
		(start 421.167052 -304.841148)
		(end 419.813232 -304.841148)
		(width 0.18288)
		(layer "In11.Cu")
		(net "M_H_CPU0_SA_DQ<16>")
	)
	(segment
		(start 412.161736 -301.985426)
		(end 410.768546 -300.592236)
		(width 0.18288)
		(layer "In11.Cu")
		(net "M_H_CPU0_SA_DQ<16>")
	)
	(segment
		(start 443.664594 -301.325026)
		(end 443.232794 -301.325026)
		(width 0.18288)
		(layer "In11.Cu")
		(net "M_H_CPU0_SA_DQ<16>")
	)
	(segment
		(start 376.79122 -274.754848)
		(end 376.787918 -274.752816)
		(width 0.088646)
		(layer "In11.Cu")
		(net "M_H_CPU0_SA_DQ<16>")
	)
	(segment
		(start 425.906946 -303.992534)
		(end 423.830242 -303.992534)
		(width 0.18288)
		(layer "In11.Cu")
		(net "M_H_CPU0_SA_DQ<16>")
	)
	(segment
		(start 372.285768 -272.078704)
		(end 372.285768 -271.890236)
		(width 0.088646)
		(layer "In11.Cu")
		(net "M_H_CPU0_SA_DQ<16>")
	)
	(segment
		(start 422.122092 -303.886108)
		(end 421.167052 -304.841148)
		(width 0.18288)
		(layer "In11.Cu")
		(net "M_H_CPU0_SA_DQ<16>")
	)
	(segment
		(start 419.39083 -304.119026)
		(end 417.63823 -302.366426)
		(width 0.18288)
		(layer "In11.Cu")
		(net "M_H_CPU0_SA_DQ<16>")
	)
	(segment
		(start 386.892546 -277.397464)
		(end 386.525008 -277.029926)
		(width 0.088646)
		(layer "In11.Cu")
		(net "M_H_CPU0_SA_DQ<16>")
	)
	(segment
		(start 389.567166 -280.66619)
		(end 387.570726 -278.66975)
		(width 0.18288)
		(layer "In11.Cu")
		(net "M_H_CPU0_SA_DQ<16>")
	)
	(segment
		(start 426.659802 -303.239678)
		(end 425.906946 -303.992534)
		(width 0.18288)
		(layer "In11.Cu")
		(net "M_H_CPU0_SA_DQ<16>")
	)
	(segment
		(start 375.009664 -272.314924)
		(end 374.994932 -272.32356)
		(width 0.088646)
		(layer "In11.Cu")
		(net "M_H_CPU0_SA_DQ<16>")
	)
	(segment
		(start 372.220744 -271.825212)
		(end 371.907816 -271.825212)
		(width 0.088646)
		(layer "In11.Cu")
		(net "M_H_CPU0_SA_DQ<16>")
	)
	(segment
		(start 387.570726 -278.66975)
		(end 387.400546 -278.49957)
		(width 0.088646)
		(layer "In11.Cu")
		(net "M_H_CPU0_SA_DQ<16>")
	)
	(segment
		(start 440.124342 -303.992026)
		(end 438.346088 -303.992026)
		(width 0.18288)
		(layer "In11.Cu")
		(net "M_H_CPU0_SA_DQ<16>")
	)
	(segment
		(start 440.877706 -302.818038)
		(end 440.877706 -303.238662)
		(width 0.18288)
		(layer "In11.Cu")
		(net "M_H_CPU0_SA_DQ<16>")
	)
	(segment
		(start 408.183588 -299.546264)
		(end 407.064718 -299.546264)
		(width 0.18288)
		(layer "In11.Cu")
		(net "M_H_CPU0_SA_DQ<16>")
	)
	(segment
		(start 450.911214 -297.616626)
		(end 450.911214 -297.77309)
		(width 0.18288)
		(layer "In11.Cu")
		(net "M_H_CPU0_SA_DQ<16>")
	)
	(segment
		(start 450.420486 -297.928284)
		(end 450.131434 -297.639232)
		(width 0.18288)
		(layer "In11.Cu")
		(net "M_H_CPU0_SA_DQ<16>")
	)
	(segment
		(start 375.39295 -272.320004)
		(end 375.38406 -272.314924)
		(width 0.088646)
		(layer "In11.Cu")
		(net "M_H_CPU0_SA_DQ<16>")
	)
	(segment
		(start 450.911214 -297.77309)
		(end 450.85127 -297.91787)
		(width 0.18288)
		(layer "In11.Cu")
		(net "M_H_CPU0_SA_DQ<16>")
	)
	(segment
		(start 445.950594 -299.597826)
		(end 445.391794 -299.597826)
		(width 0.18288)
		(layer "In11.Cu")
		(net "M_H_CPU0_SA_DQ<16>")
	)
	(segment
		(start 419.813232 -304.841148)
		(end 419.39083 -304.418746)
		(width 0.18288)
		(layer "In11.Cu")
		(net "M_H_CPU0_SA_DQ<16>")
	)
	(segment
		(start 376.794014 -274.756372)
		(end 376.79122 -274.754848)
		(width 0.088646)
		(layer "In11.Cu")
		(net "M_H_CPU0_SA_DQ<16>")
	)
	(segment
		(start 450.598286 -298.001944)
		(end 450.420486 -297.928284)
		(width 0.18288)
		(layer "In11.Cu")
		(net "M_H_CPU0_SA_DQ<16>")
	)
	(segment
		(start 437.50357 -303.593246)
		(end 437.22798 -303.317656)
		(width 0.18288)
		(layer "In11.Cu")
		(net "M_H_CPU0_SA_DQ<16>")
	)
	(segment
		(start 450.767196 -298.001944)
		(end 450.598286 -298.001944)
		(width 0.18288)
		(layer "In11.Cu")
		(net "M_H_CPU0_SA_DQ<16>")
	)
	(segment
		(start 375.85142 -273.127216)
		(end 375.848118 -273.125184)
		(width 0.088646)
		(layer "In11.Cu")
		(net "M_H_CPU0_SA_DQ<16>")
	)
	(segment
		(start 389.567166 -280.981404)
		(end 389.567166 -280.66619)
		(width 0.18288)
		(layer "In11.Cu")
		(net "M_H_CPU0_SA_DQ<16>")
	)
	(segment
		(start 412.663894 -301.985426)
		(end 412.161736 -301.985426)
		(width 0.18288)
		(layer "In11.Cu")
		(net "M_H_CPU0_SA_DQ<16>")
	)
	(segment
		(start 383.97688 -275.686266)
		(end 383.920238 -275.629624)
		(width 0.088646)
		(layer "In11.Cu")
		(net "M_H_CPU0_SA_DQ<16>")
	)
	(segment
		(start 383.467864 -275.570442)
		(end 383.453132 -275.579078)
		(width 0.088646)
		(layer "In11.Cu")
		(net "M_H_CPU0_SA_DQ<16>")
	)
	(segment
		(start 406.385014 -298.86656)
		(end 406.385014 -298.432982)
		(width 0.18288)
		(layer "In11.Cu")
		(net "M_H_CPU0_SA_DQ<16>")
	)
	(segment
		(start 409.22956 -300.592236)
		(end 408.183588 -299.546264)
		(width 0.18288)
		(layer "In11.Cu")
		(net "M_H_CPU0_SA_DQ<16>")
	)
	(segment
		(start 379.708664 -275.570442)
		(end 379.693932 -275.579078)
		(width 0.088646)
		(layer "In11.Cu")
		(net "M_H_CPU0_SA_DQ<16>")
	)
	(segment
		(start 372.400322 -272.214086)
		(end 372.285768 -272.078704)
		(width 0.088646)
		(layer "In11.Cu")
		(net "M_H_CPU0_SA_DQ<16>")
	)
	(segment
		(start 440.877706 -303.238662)
		(end 440.124342 -303.992026)
		(width 0.18288)
		(layer "In11.Cu")
		(net "M_H_CPU0_SA_DQ<16>")
	)
	(segment
		(start 449.30314 -297.162728)
		(end 447.826384 -298.639484)
		(width 0.18288)
		(layer "In11.Cu")
		(net "M_H_CPU0_SA_DQ<16>")
	)
	(segment
		(start 380.648464 -275.570442)
		(end 380.633732 -275.579078)
		(width 0.088646)
		(layer "In11.Cu")
		(net "M_H_CPU0_SA_DQ<16>")
	)
	(segment
		(start 373.515128 -272.32102)
		(end 373.504714 -272.314924)
		(width 0.088646)
		(layer "In11.Cu")
		(net "M_H_CPU0_SA_DQ<16>")
	)
	(segment
		(start 378.768864 -275.570442)
		(end 378.754132 -275.579078)
		(width 0.088646)
		(layer "In11.Cu")
		(net "M_H_CPU0_SA_DQ<16>")
	)
	(segment
		(start 385.703064 -277.029926)
		(end 384.359404 -275.686266)
		(width 0.088646)
		(layer "In11.Cu")
		(net "M_H_CPU0_SA_DQ<16>")
	)
	(segment
		(start 377.829064 -275.570442)
		(end 377.81865 -275.576538)
		(width 0.088646)
		(layer "In11.Cu")
		(net "M_H_CPU0_SA_DQ<16>")
	)
	(segment
		(start 382.528064 -275.570442)
		(end 382.513332 -275.579078)
		(width 0.088646)
		(layer "In11.Cu")
		(net "M_H_CPU0_SA_DQ<16>")
	)
	(segment
		(start 427.320456 -302.96612)
		(end 426.659802 -303.239678)
		(width 0.18288)
		(layer "In11.Cu")
		(net "M_H_CPU0_SA_DQ<16>")
	)
	(segment
		(start 423.830242 -303.992534)
		(end 423.723816 -303.886108)
		(width 0.18288)
		(layer "In11.Cu")
		(net "M_H_CPU0_SA_DQ<16>")
	)
	(segment
		(start 386.892546 -277.75154)
		(end 386.892546 -277.397464)
		(width 0.088646)
		(layer "In11.Cu")
		(net "M_H_CPU0_SA_DQ<16>")
	)
	(segment
		(start 414.61563 -301.93107)
		(end 414.061402 -301.93107)
		(width 0.18288)
		(layer "In11.Cu")
		(net "M_H_CPU0_SA_DQ<16>")
	)
	(segment
		(start 372.56466 -272.314924)
		(end 372.400322 -272.214086)
		(width 0.088646)
		(layer "In11.Cu")
		(net "M_H_CPU0_SA_DQ<16>")
	)
	(segment
		(start 407.064718 -299.546264)
		(end 406.385014 -298.86656)
		(width 0.18288)
		(layer "In11.Cu")
		(net "M_H_CPU0_SA_DQ<16>")
	)
	(segment
		(start 414.061402 -301.93107)
		(end 413.626046 -302.366426)
		(width 0.18288)
		(layer "In11.Cu")
		(net "M_H_CPU0_SA_DQ<16>")
	)
	(segment
		(start 450.85127 -297.91787)
		(end 450.767196 -298.001944)
		(width 0.18288)
		(layer "In11.Cu")
		(net "M_H_CPU0_SA_DQ<16>")
	)
	(segment
		(start 397.702786 -289.117024)
		(end 389.567166 -280.981404)
		(width 0.18288)
		(layer "In11.Cu")
		(net "M_H_CPU0_SA_DQ<16>")
	)
	(segment
		(start 445.391794 -299.597826)
		(end 443.664594 -301.325026)
		(width 0.18288)
		(layer "In11.Cu")
		(net "M_H_CPU0_SA_DQ<16>")
	)
	(segment
		(start 404.676356 -297.930824)
		(end 397.702786 -290.957254)
		(width 0.18288)
		(layer "In11.Cu")
		(net "M_H_CPU0_SA_DQ<16>")
	)
	(segment
		(start 443.232794 -301.325026)
		(end 442.521594 -302.036226)
		(width 0.18288)
		(layer "In11.Cu")
		(net "M_H_CPU0_SA_DQ<16>")
	)
	(segment
		(start 410.768546 -300.592236)
		(end 409.22956 -300.592236)
		(width 0.18288)
		(layer "In11.Cu")
		(net "M_H_CPU0_SA_DQ<16>")
	)
	(segment
		(start 373.130318 -272.314924)
		(end 373.130064 -272.314924)
		(width 0.088646)
		(layer "In11.Cu")
		(net "M_H_CPU0_SA_DQ<16>")
	)
	(segment
		(start 376.981466 -275.100034)
		(end 376.981466 -275.08073)
		(width 0.088646)
		(layer "In11.Cu")
		(net "M_H_CPU0_SA_DQ<16>")
	)
	(segment
		(start 376.041666 -273.468592)
		(end 376.041666 -273.453098)
		(width 0.088646)
		(layer "In11.Cu")
		(net "M_H_CPU0_SA_DQ<16>")
	)
	(segment
		(start 386.525008 -277.029926)
		(end 385.703064 -277.029926)
		(width 0.088646)
		(layer "In11.Cu")
		(net "M_H_CPU0_SA_DQ<16>")
	)
	(segment
		(start 419.39083 -304.418746)
		(end 419.39083 -304.119026)
		(width 0.18288)
		(layer "In11.Cu")
		(net "M_H_CPU0_SA_DQ<16>")
	)
	(segment
		(start 447.826384 -298.639484)
		(end 446.908936 -298.639484)
		(width 0.18288)
		(layer "In11.Cu")
		(net "M_H_CPU0_SA_DQ<16>")
	)
	(segment
		(start 428.846488 -302.96612)
		(end 427.320456 -302.96612)
		(width 0.18288)
		(layer "In11.Cu")
		(net "M_H_CPU0_SA_DQ<16>")
	)
	(segment
		(start 375.863104 -273.13382)
		(end 375.854214 -273.12874)
		(width 0.088646)
		(layer "In11.Cu")
		(net "M_H_CPU0_SA_DQ<16>")
	)
	(segment
		(start 429.13808 -302.674528)
		(end 428.846488 -302.96612)
		(width 0.18288)
		(layer "In11.Cu")
		(net "M_H_CPU0_SA_DQ<16>")
	)
	(segment
		(start 415.050986 -302.366426)
		(end 414.61563 -301.93107)
		(width 0.18288)
		(layer "In11.Cu")
		(net "M_H_CPU0_SA_DQ<16>")
	)
	(segment
		(start 375.854214 -273.12874)
		(end 375.85142 -273.127216)
		(width 0.088646)
		(layer "In11.Cu")
		(net "M_H_CPU0_SA_DQ<16>")
	)
	(segment
		(start 413.044894 -302.366426)
		(end 412.663894 -301.985426)
		(width 0.18288)
		(layer "In11.Cu")
		(net "M_H_CPU0_SA_DQ<16>")
	)
	(segment
		(start 397.702786 -290.957254)
		(end 397.702786 -289.117024)
		(width 0.18288)
		(layer "In11.Cu")
		(net "M_H_CPU0_SA_DQ<16>")
	)
	(segment
		(start 437.22798 -303.317656)
		(end 437.22798 -302.873918)
		(width 0.18288)
		(layer "In11.Cu")
		(net "M_H_CPU0_SA_DQ<16>")
	)
	(segment
		(start 387.400546 -278.49957)
		(end 387.400546 -278.25954)
		(width 0.088646)
		(layer "In11.Cu")
		(net "M_H_CPU0_SA_DQ<16>")
	)
	(segment
		(start 432.015392 -302.674528)
		(end 429.13808 -302.674528)
		(width 0.18288)
		(layer "In11.Cu")
		(net "M_H_CPU0_SA_DQ<16>")
	)
	(segment
		(start 406.385014 -298.432982)
		(end 405.882856 -297.930824)
		(width 0.18288)
		(layer "In11.Cu")
		(net "M_H_CPU0_SA_DQ<16>")
	)
	(segment
		(start 437.22798 -302.873918)
		(end 436.646066 -302.292004)
		(width 0.18288)
		(layer "In11.Cu")
		(net "M_H_CPU0_SA_DQ<16>")
	)
	(segment
		(start 450.131434 -297.639232)
		(end 450.131434 -297.462194)
		(width 0.18288)
		(layer "In11.Cu")
		(net "M_H_CPU0_SA_DQ<16>")
	)
	(segment
		(start 413.626046 -302.366426)
		(end 413.044894 -302.366426)
		(width 0.18288)
		(layer "In11.Cu")
		(net "M_H_CPU0_SA_DQ<16>")
	)
	(segment
		(start 438.346088 -303.992026)
		(end 437.947308 -303.593246)
		(width 0.18288)
		(layer "In11.Cu")
		(net "M_H_CPU0_SA_DQ<16>")
	)
	(segment
		(start 417.63823 -302.366426)
		(end 415.050986 -302.366426)
		(width 0.18288)
		(layer "In11.Cu")
		(net "M_H_CPU0_SA_DQ<16>")
	)
	(segment
		(start 446.908936 -298.639484)
		(end 445.950594 -299.597826)
		(width 0.18288)
		(layer "In11.Cu")
		(net "M_H_CPU0_SA_DQ<16>")
	)
	(segment
		(start 449.831968 -297.162728)
		(end 449.30314 -297.162728)
		(width 0.18288)
		(layer "In11.Cu")
		(net "M_H_CPU0_SA_DQ<16>")
	)
	(segment
		(start 405.882856 -297.930824)
		(end 404.676356 -297.930824)
		(width 0.18288)
		(layer "In11.Cu")
		(net "M_H_CPU0_SA_DQ<16>")
	)
	(segment
		(start 387.400546 -278.25954)
		(end 386.892546 -277.75154)
		(width 0.088646)
		(layer "In11.Cu")
		(net "M_H_CPU0_SA_DQ<16>")
	)
	(segment
		(start 384.359404 -275.686266)
		(end 383.97688 -275.686266)
		(width 0.088646)
		(layer "In11.Cu")
		(net "M_H_CPU0_SA_DQ<16>")
	)
	(segment
		(start 376.33275 -273.947636)
		(end 376.32386 -273.942556)
		(width 0.088646)
		(layer "In11.Cu")
		(net "M_H_CPU0_SA_DQ<16>")
	)
	(segment
		(start 450.131434 -297.462194)
		(end 449.831968 -297.162728)
		(width 0.18288)
		(layer "In11.Cu")
		(net "M_H_CPU0_SA_DQ<16>")
	)
	(segment
		(start 432.397916 -302.292004)
		(end 432.015392 -302.674528)
		(width 0.18288)
		(layer "In11.Cu")
		(net "M_H_CPU0_SA_DQ<16>")
	)
	(segment
		(start 442.521594 -302.036226)
		(end 441.659518 -302.036226)
		(width 0.18288)
		(layer "In11.Cu")
		(net "M_H_CPU0_SA_DQ<16>")
	)
	(segment
		(start 423.723816 -303.886108)
		(end 422.122092 -303.886108)
		(width 0.18288)
		(layer "In11.Cu")
		(net "M_H_CPU0_SA_DQ<16>")
	)
	(segment
		(start 437.947308 -303.593246)
		(end 437.50357 -303.593246)
		(width 0.18288)
		(layer "In11.Cu")
		(net "M_H_CPU0_SA_DQ<16>")
	)
	(segment
		(start 441.659518 -302.036226)
		(end 440.877706 -302.818038)
		(width 0.18288)
		(layer "In11.Cu")
		(net "M_H_CPU0_SA_DQ<16>")
	)
	(segment
		(start 376.802904 -274.761452)
		(end 376.794014 -274.756372)
		(width 0.088646)
		(layer "In11.Cu")
		(net "M_H_CPU0_SA_DQ<16>")
	)
	(segment
		(start 436.646066 -302.292004)
		(end 432.397916 -302.292004)
		(width 0.18288)
		(layer "In11.Cu")
		(net "M_H_CPU0_SA_DQ<16>")
	)
	(segment
		(start 372.285768 -271.890236)
		(end 372.220744 -271.825212)
		(width 0.088646)
		(layer "In11.Cu")
		(net "M_H_CPU0_SA_DQ<16>")
	)
	(arc
		(start 380.633732 -275.579078)
		(mid 380.357291 -275.646244)
		(end 380.08306 -275.570442)
		(width 0.088646)
		(layer "In11.Cu")
		(net "M_H_CPU0_SA_DQ<16>")
	)
	(arc
		(start 380.08306 -275.570442)
		(mid 379.895862 -275.520299)
		(end 379.708664 -275.570442)
		(width 0.088646)
		(layer "In11.Cu")
		(net "M_H_CPU0_SA_DQ<16>")
	)
	(arc
		(start 376.511312 -274.266914)
		(mid 376.463633 -274.084014)
		(end 376.33275 -273.947636)
		(width 0.088646)
		(layer "In11.Cu")
		(net "M_H_CPU0_SA_DQ<16>")
	)
	(arc
		(start 376.787918 -274.752816)
		(mid 376.585331 -274.546465)
		(end 376.511312 -274.266914)
		(width 0.088646)
		(layer "In11.Cu")
		(net "M_H_CPU0_SA_DQ<16>")
	)
	(arc
		(start 374.994932 -272.32356)
		(mid 374.718491 -272.390726)
		(end 374.44426 -272.314924)
		(width 0.088646)
		(layer "In11.Cu")
		(net "M_H_CPU0_SA_DQ<16>")
	)
	(arc
		(start 381.588264 -275.570442)
		(mid 381.305562 -275.646184)
		(end 381.02286 -275.570442)
		(width 0.088646)
		(layer "In11.Cu")
		(net "M_H_CPU0_SA_DQ<16>")
	)
	(arc
		(start 374.44426 -272.314924)
		(mid 374.257062 -272.264781)
		(end 374.069864 -272.314924)
		(width 0.088646)
		(layer "In11.Cu")
		(net "M_H_CPU0_SA_DQ<16>")
	)
	(arc
		(start 373.504714 -272.314924)
		(mid 373.317516 -272.264781)
		(end 373.130318 -272.314924)
		(width 0.088646)
		(layer "In11.Cu")
		(net "M_H_CPU0_SA_DQ<16>")
	)
	(arc
		(start 373.130064 -272.314924)
		(mid 372.847362 -272.390666)
		(end 372.56466 -272.314924)
		(width 0.088646)
		(layer "In11.Cu")
		(net "M_H_CPU0_SA_DQ<16>")
	)
	(arc
		(start 383.84226 -275.570442)
		(mid 383.655062 -275.520299)
		(end 383.467864 -275.570442)
		(width 0.088646)
		(layer "In11.Cu")
		(net "M_H_CPU0_SA_DQ<16>")
	)
	(arc
		(start 378.20346 -275.570442)
		(mid 378.016262 -275.520299)
		(end 377.829064 -275.570442)
		(width 0.088646)
		(layer "In11.Cu")
		(net "M_H_CPU0_SA_DQ<16>")
	)
	(arc
		(start 375.571512 -272.639282)
		(mid 375.523833 -272.456382)
		(end 375.39295 -272.320004)
		(width 0.088646)
		(layer "In11.Cu")
		(net "M_H_CPU0_SA_DQ<16>")
	)
	(arc
		(start 381.96266 -275.570442)
		(mid 381.775462 -275.520299)
		(end 381.588264 -275.570442)
		(width 0.088646)
		(layer "In11.Cu")
		(net "M_H_CPU0_SA_DQ<16>")
	)
	(arc
		(start 381.02286 -275.570442)
		(mid 380.835662 -275.520299)
		(end 380.648464 -275.570442)
		(width 0.088646)
		(layer "In11.Cu")
		(net "M_H_CPU0_SA_DQ<16>")
	)
	(arc
		(start 383.453132 -275.579078)
		(mid 383.176657 -275.646398)
		(end 382.90246 -275.570442)
		(width 0.088646)
		(layer "In11.Cu")
		(net "M_H_CPU0_SA_DQ<16>")
	)
	(arc
		(start 383.920238 -275.629624)
		(mid 383.883188 -275.597478)
		(end 383.84226 -275.570442)
		(width 0.088646)
		(layer "In11.Cu")
		(net "M_H_CPU0_SA_DQ<16>")
	)
	(arc
		(start 375.848118 -273.125184)
		(mid 375.645531 -272.918833)
		(end 375.571512 -272.639282)
		(width 0.088646)
		(layer "In11.Cu")
		(net "M_H_CPU0_SA_DQ<16>")
	)
	(arc
		(start 376.981466 -275.08073)
		(mid 376.933787 -274.89783)
		(end 376.802904 -274.761452)
		(width 0.088646)
		(layer "In11.Cu")
		(net "M_H_CPU0_SA_DQ<16>")
	)
	(arc
		(start 379.14326 -275.570442)
		(mid 378.956062 -275.520299)
		(end 378.768864 -275.570442)
		(width 0.088646)
		(layer "In11.Cu")
		(net "M_H_CPU0_SA_DQ<16>")
	)
	(arc
		(start 379.693932 -275.579078)
		(mid 379.417491 -275.646244)
		(end 379.14326 -275.570442)
		(width 0.088646)
		(layer "In11.Cu")
		(net "M_H_CPU0_SA_DQ<16>")
	)
	(arc
		(start 377.81865 -275.576538)
		(mid 377.540472 -275.64623)
		(end 377.263914 -275.570442)
		(width 0.088646)
		(layer "In11.Cu")
		(net "M_H_CPU0_SA_DQ<16>")
	)
	(arc
		(start 376.32386 -273.942556)
		(mid 376.121037 -273.742325)
		(end 376.041666 -273.468592)
		(width 0.088646)
		(layer "In11.Cu")
		(net "M_H_CPU0_SA_DQ<16>")
	)
	(arc
		(start 374.069864 -272.314924)
		(mid 373.793305 -272.390633)
		(end 373.515128 -272.32102)
		(width 0.088646)
		(layer "In11.Cu")
		(net "M_H_CPU0_SA_DQ<16>")
	)
	(arc
		(start 377.263914 -275.570442)
		(mid 377.061824 -275.371788)
		(end 376.981466 -275.100034)
		(width 0.088646)
		(layer "In11.Cu")
		(net "M_H_CPU0_SA_DQ<16>")
	)
	(arc
		(start 382.513332 -275.579078)
		(mid 382.236891 -275.646244)
		(end 381.96266 -275.570442)
		(width 0.088646)
		(layer "In11.Cu")
		(net "M_H_CPU0_SA_DQ<16>")
	)
	(arc
		(start 382.90246 -275.570442)
		(mid 382.715262 -275.520299)
		(end 382.528064 -275.570442)
		(width 0.088646)
		(layer "In11.Cu")
		(net "M_H_CPU0_SA_DQ<16>")
	)
	(arc
		(start 378.754132 -275.579078)
		(mid 378.477691 -275.646244)
		(end 378.20346 -275.570442)
		(width 0.088646)
		(layer "In11.Cu")
		(net "M_H_CPU0_SA_DQ<16>")
	)
	(arc
		(start 375.38406 -272.314924)
		(mid 375.196862 -272.264781)
		(end 375.009664 -272.314924)
		(width 0.088646)
		(layer "In11.Cu")
		(net "M_H_CPU0_SA_DQ<16>")
	)
	(arc
		(start 376.041666 -273.453098)
		(mid 375.993987 -273.270198)
		(end 375.863104 -273.13382)
		(width 0.088646)
		(layer "In11.Cu")
		(net "M_H_CPU0_SA_DQ<16>")
	)
	(segment
		(start 460.570326 -298.903898)
		(end 461.251554 -298.903898)
		(width 0.20066)
		(layer "F.Cu")
		(net "M_H_CPU0_SA_DQ<15>")
	)
	(segment
		(start 457.814426 -298.466764)
		(end 458.24648 -298.898818)
		(width 0.20066)
		(layer "F.Cu")
		(net "M_H_CPU0_SA_DQ<15>")
	)
	(segment
		(start 372.847362 -273.452844)
		(end 372.847616 -273.453098)
		(width 0.20066)
		(layer "F.Cu")
		(net "M_H_CPU0_SA_DQ<15>")
	)
	(segment
		(start 458.550264 -298.891706)
		(end 460.558134 -298.891706)
		(width 0.1016)
		(layer "F.Cu")
		(net "M_H_CPU0_SA_DQ<15>")
	)
	(segment
		(start 461.455516 -298.448984)
		(end 461.689704 -298.214796)
		(width 0.20066)
		(layer "F.Cu")
		(net "M_H_CPU0_SA_DQ<15>")
	)
	(segment
		(start 372.847362 -272.917158)
		(end 372.847362 -273.452844)
		(width 0.20066)
		(layer "F.Cu")
		(net "M_H_CPU0_SA_DQ<15>")
	)
	(segment
		(start 458.543152 -298.898818)
		(end 458.550264 -298.891706)
		(width 0.1016)
		(layer "F.Cu")
		(net "M_H_CPU0_SA_DQ<15>")
	)
	(segment
		(start 461.251554 -298.903898)
		(end 461.455516 -298.699936)
		(width 0.20066)
		(layer "F.Cu")
		(net "M_H_CPU0_SA_DQ<15>")
	)
	(segment
		(start 456.116182 -298.466764)
		(end 457.814426 -298.466764)
		(width 0.20066)
		(layer "F.Cu")
		(net "M_H_CPU0_SA_DQ<15>")
	)
	(segment
		(start 461.455516 -298.699936)
		(end 461.455516 -298.448984)
		(width 0.20066)
		(layer "F.Cu")
		(net "M_H_CPU0_SA_DQ<15>")
	)
	(segment
		(start 458.24648 -298.898818)
		(end 458.538326 -298.898818)
		(width 0.20066)
		(layer "F.Cu")
		(net "M_H_CPU0_SA_DQ<15>")
	)
	(segment
		(start 458.538326 -298.898818)
		(end 458.543152 -298.898818)
		(width 0.101854)
		(layer "F.Cu")
		(net "M_H_CPU0_SA_DQ<15>")
	)
	(segment
		(start 462.073752 -298.214796)
		(end 462.32572 -298.466764)
		(width 0.20066)
		(layer "F.Cu")
		(net "M_H_CPU0_SA_DQ<15>")
	)
	(segment
		(start 460.558134 -298.891706)
		(end 460.570326 -298.903898)
		(width 0.1016)
		(layer "F.Cu")
		(net "M_H_CPU0_SA_DQ<15>")
	)
	(segment
		(start 461.689704 -298.214796)
		(end 462.073752 -298.214796)
		(width 0.20066)
		(layer "F.Cu")
		(net "M_H_CPU0_SA_DQ<15>")
	)
	(segment
		(start 455.011282 -298.466764)
		(end 456.116182 -298.466764)
		(width 0.20066)
		(layer "F.Cu")
		(net "M_H_CPU0_SA_DQ<15>")
	)
	(segment
		(start 462.32572 -298.466764)
		(end 463.659982 -298.466764)
		(width 0.20066)
		(layer "F.Cu")
		(net "M_H_CPU0_SA_DQ<15>")
	)
	(segment
		(start 450.591428 -298.893484)
		(end 450.287644 -298.5897)
		(width 0.18288)
		(layer "In11.Cu")
		(net "M_H_CPU0_SA_DQ<15>")
	)
	(segment
		(start 432.94046 -304.010822)
		(end 431.720752 -304.010822)
		(width 0.18288)
		(layer "In11.Cu")
		(net "M_H_CPU0_SA_DQ<15>")
	)
	(segment
		(start 453.504808 -299.876464)
		(end 453.504808 -299.089064)
		(width 0.18288)
		(layer "In11.Cu")
		(net "M_H_CPU0_SA_DQ<15>")
	)
	(segment
		(start 419.280594 -305.693318)
		(end 417.642294 -304.056034)
		(width 0.18288)
		(layer "In11.Cu")
		(net "M_H_CPU0_SA_DQ<15>")
	)
	(segment
		(start 410.169106 -303.012856)
		(end 410.040074 -303.141888)
		(width 0.18288)
		(layer "In11.Cu")
		(net "M_H_CPU0_SA_DQ<15>")
	)
	(segment
		(start 453.311768 -298.896024)
		(end 452.469758 -298.896024)
		(width 0.18288)
		(layer "In11.Cu")
		(net "M_H_CPU0_SA_DQ<15>")
	)
	(segment
		(start 384.877564 -277.032974)
		(end 384.877818 -277.032974)
		(width 0.088646)
		(layer "In11.Cu")
		(net "M_H_CPU0_SA_DQ<15>")
	)
	(segment
		(start 410.040074 -303.141888)
		(end 409.46705 -303.141888)
		(width 0.18288)
		(layer "In11.Cu")
		(net "M_H_CPU0_SA_DQ<15>")
	)
	(segment
		(start 416.308794 -303.20488)
		(end 412.638748 -303.20488)
		(width 0.18288)
		(layer "In11.Cu")
		(net "M_H_CPU0_SA_DQ<15>")
	)
	(segment
		(start 429.879252 -304.916078)
		(end 429.686212 -304.723038)
		(width 0.18288)
		(layer "In11.Cu")
		(net "M_H_CPU0_SA_DQ<15>")
	)
	(segment
		(start 433.83708 -303.801272)
		(end 433.83708 -303.321212)
		(width 0.18288)
		(layer "In11.Cu")
		(net "M_H_CPU0_SA_DQ<15>")
	)
	(segment
		(start 441.691776 -303.27092)
		(end 441.691776 -303.56048)
		(width 0.18288)
		(layer "In11.Cu")
		(net "M_H_CPU0_SA_DQ<15>")
	)
	(segment
		(start 422.19499 -305.02479)
		(end 421.526462 -305.693318)
		(width 0.18288)
		(layer "In11.Cu")
		(net "M_H_CPU0_SA_DQ<15>")
	)
	(segment
		(start 378.299218 -277.032974)
		(end 378.290328 -277.027894)
		(width 0.088646)
		(layer "In11.Cu")
		(net "M_H_CPU0_SA_DQ<15>")
	)
	(segment
		(start 404.986236 -300.99)
		(end 404.986236 -299.396658)
		(width 0.18288)
		(layer "In11.Cu")
		(net "M_H_CPU0_SA_DQ<15>")
	)
	(segment
		(start 429.686212 -304.242724)
		(end 429.493172 -304.049684)
		(width 0.18288)
		(layer "In11.Cu")
		(net "M_H_CPU0_SA_DQ<15>")
	)
	(segment
		(start 385.160012 -277.522432)
		(end 385.160012 -277.512526)
		(width 0.088646)
		(layer "In11.Cu")
		(net "M_H_CPU0_SA_DQ<15>")
	)
	(segment
		(start 447.761106 -299.874178)
		(end 447.147442 -299.874178)
		(width 0.18288)
		(layer "In11.Cu")
		(net "M_H_CPU0_SA_DQ<15>")
	)
	(segment
		(start 434.03012 -303.994312)
		(end 433.83708 -303.801272)
		(width 0.18288)
		(layer "In11.Cu")
		(net "M_H_CPU0_SA_DQ<15>")
	)
	(segment
		(start 377.83516 -276.222714)
		(end 377.829064 -276.219158)
		(width 0.088646)
		(layer "In11.Cu")
		(net "M_H_CPU0_SA_DQ<15>")
	)
	(segment
		(start 428.982632 -304.242724)
		(end 428.982632 -304.723038)
		(width 0.18288)
		(layer "In11.Cu")
		(net "M_H_CPU0_SA_DQ<15>")
	)
	(segment
		(start 454.401428 -298.896024)
		(end 454.208388 -299.089064)
		(width 0.18288)
		(layer "In11.Cu")
		(net "M_H_CPU0_SA_DQ<15>")
	)
	(segment
		(start 451.573138 -299.089064)
		(end 451.377558 -298.893484)
		(width 0.18288)
		(layer "In11.Cu")
		(net "M_H_CPU0_SA_DQ<15>")
	)
	(segment
		(start 409.46705 -303.141888)
		(end 408.892756 -302.567594)
		(width 0.18288)
		(layer "In11.Cu")
		(net "M_H_CPU0_SA_DQ<15>")
	)
	(segment
		(start 451.766178 -300.088046)
		(end 451.573138 -299.895006)
		(width 0.18288)
		(layer "In11.Cu")
		(net "M_H_CPU0_SA_DQ<15>")
	)
	(segment
		(start 412.446724 -303.012856)
		(end 410.169106 -303.012856)
		(width 0.18288)
		(layer "In11.Cu")
		(net "M_H_CPU0_SA_DQ<15>")
	)
	(segment
		(start 373.349774 -273.095212)
		(end 373.295926 -273.161252)
		(width 0.088646)
		(layer "In11.Cu")
		(net "M_H_CPU0_SA_DQ<15>")
	)
	(segment
		(start 377.829064 -276.219158)
		(end 377.81865 -276.213062)
		(width 0.088646)
		(layer "In11.Cu")
		(net "M_H_CPU0_SA_DQ<15>")
	)
	(segment
		(start 436.745126 -303.994312)
		(end 434.03012 -303.994312)
		(width 0.18288)
		(layer "In11.Cu")
		(net "M_H_CPU0_SA_DQ<15>")
	)
	(segment
		(start 440.41187 -304.840386)
		(end 438.921906 -304.840386)
		(width 0.18288)
		(layer "In11.Cu")
		(net "M_H_CPU0_SA_DQ<15>")
	)
	(segment
		(start 387.679184 -280.094944)
		(end 386.641086 -279.056846)
		(width 0.088646)
		(layer "In11.Cu")
		(net "M_H_CPU0_SA_DQ<15>")
	)
	(segment
		(start 429.686212 -304.723038)
		(end 429.686212 -304.242724)
		(width 0.18288)
		(layer "In11.Cu")
		(net "M_H_CPU0_SA_DQ<15>")
	)
	(segment
		(start 433.32654 -303.128172)
		(end 433.1335 -303.321212)
		(width 0.18288)
		(layer "In11.Cu")
		(net "M_H_CPU0_SA_DQ<15>")
	)
	(segment
		(start 385.347464 -277.84679)
		(end 385.338574 -277.84171)
		(width 0.088646)
		(layer "In11.Cu")
		(net "M_H_CPU0_SA_DQ<15>")
	)
	(segment
		(start 426.472858 -304.601626)
		(end 426.231812 -304.842672)
		(width 0.18288)
		(layer "In11.Cu")
		(net "M_H_CPU0_SA_DQ<15>")
	)
	(segment
		(start 404.986236 -299.396658)
		(end 396.896082 -291.306504)
		(width 0.18288)
		(layer "In11.Cu")
		(net "M_H_CPU0_SA_DQ<15>")
	)
	(segment
		(start 455.011282 -298.466764)
		(end 454.580498 -298.896024)
		(width 0.18288)
		(layer "In11.Cu")
		(net "M_H_CPU0_SA_DQ<15>")
	)
	(segment
		(start 427.446694 -304.601626)
		(end 426.472858 -304.601626)
		(width 0.18288)
		(layer "In11.Cu")
		(net "M_H_CPU0_SA_DQ<15>")
	)
	(segment
		(start 428.789592 -304.916078)
		(end 427.761146 -304.916078)
		(width 0.18288)
		(layer "In11.Cu")
		(net "M_H_CPU0_SA_DQ<15>")
	)
	(segment
		(start 375.479818 -273.777456)
		(end 375.470928 -273.772376)
		(width 0.088646)
		(layer "In11.Cu")
		(net "M_H_CPU0_SA_DQ<15>")
	)
	(segment
		(start 388.740142 -281.513026)
		(end 388.610602 -281.200606)
		(width 0.18288)
		(layer "In11.Cu")
		(net "M_H_CPU0_SA_DQ<15>")
	)
	(segment
		(start 438.821322 -304.94097)
		(end 437.691784 -304.94097)
		(width 0.18288)
		(layer "In11.Cu")
		(net "M_H_CPU0_SA_DQ<15>")
	)
	(segment
		(start 451.377558 -298.893484)
		(end 450.591428 -298.893484)
		(width 0.18288)
		(layer "In11.Cu")
		(net "M_H_CPU0_SA_DQ<15>")
	)
	(segment
		(start 446.331594 -300.690026)
		(end 445.691514 -300.690026)
		(width 0.18288)
		(layer "In11.Cu")
		(net "M_H_CPU0_SA_DQ<15>")
	)
	(segment
		(start 380.563374 -277.026878)
		(end 380.55296 -277.032974)
		(width 0.088646)
		(layer "In11.Cu")
		(net "M_H_CPU0_SA_DQ<15>")
	)
	(segment
		(start 408.892756 -302.567594)
		(end 408.892756 -301.401988)
		(width 0.18288)
		(layer "In11.Cu")
		(net "M_H_CPU0_SA_DQ<15>")
	)
	(segment
		(start 430.815496 -304.916078)
		(end 429.879252 -304.916078)
		(width 0.18288)
		(layer "In11.Cu")
		(net "M_H_CPU0_SA_DQ<15>")
	)
	(segment
		(start 453.504808 -299.089064)
		(end 453.311768 -298.896024)
		(width 0.18288)
		(layer "In11.Cu")
		(net "M_H_CPU0_SA_DQ<15>")
	)
	(segment
		(start 454.015348 -300.069504)
		(end 453.697848 -300.069504)
		(width 0.18288)
		(layer "In11.Cu")
		(net "M_H_CPU0_SA_DQ<15>")
	)
	(segment
		(start 396.896082 -289.668966)
		(end 388.740142 -281.513026)
		(width 0.18288)
		(layer "In11.Cu")
		(net "M_H_CPU0_SA_DQ<15>")
	)
	(segment
		(start 438.921906 -304.840386)
		(end 438.821322 -304.94097)
		(width 0.18288)
		(layer "In11.Cu")
		(net "M_H_CPU0_SA_DQ<15>")
	)
	(segment
		(start 427.761146 -304.916078)
		(end 427.446694 -304.601626)
		(width 0.18288)
		(layer "In11.Cu")
		(net "M_H_CPU0_SA_DQ<15>")
	)
	(segment
		(start 428.982632 -304.723038)
		(end 428.789592 -304.916078)
		(width 0.18288)
		(layer "In11.Cu")
		(net "M_H_CPU0_SA_DQ<15>")
	)
	(segment
		(start 386.641086 -279.056846)
		(end 386.641086 -278.678894)
		(width 0.088646)
		(layer "In11.Cu")
		(net "M_H_CPU0_SA_DQ<15>")
	)
	(segment
		(start 431.720752 -304.010822)
		(end 430.815496 -304.916078)
		(width 0.18288)
		(layer "In11.Cu")
		(net "M_H_CPU0_SA_DQ<15>")
	)
	(segment
		(start 450.287644 -298.5897)
		(end 449.773802 -298.376848)
		(width 0.18288)
		(layer "In11.Cu")
		(net "M_H_CPU0_SA_DQ<15>")
	)
	(segment
		(start 373.504714 -272.96364)
		(end 373.498618 -272.967196)
		(width 0.088646)
		(layer "In11.Cu")
		(net "M_H_CPU0_SA_DQ<15>")
	)
	(segment
		(start 373.083836 -273.453098)
		(end 372.847616 -273.453098)
		(width 0.088646)
		(layer "In11.Cu")
		(net "M_H_CPU0_SA_DQ<15>")
	)
	(segment
		(start 453.697848 -300.069504)
		(end 453.504808 -299.876464)
		(width 0.18288)
		(layer "In11.Cu")
		(net "M_H_CPU0_SA_DQ<15>")
	)
	(segment
		(start 376.702066 -275.8948)
		(end 376.702066 -275.880576)
		(width 0.088646)
		(layer "In11.Cu")
		(net "M_H_CPU0_SA_DQ<15>")
	)
	(segment
		(start 374.069864 -272.96364)
		(end 374.05945 -272.957544)
		(width 0.088646)
		(layer "In11.Cu")
		(net "M_H_CPU0_SA_DQ<15>")
	)
	(segment
		(start 408.892756 -301.401988)
		(end 408.385518 -300.89475)
		(width 0.18288)
		(layer "In11.Cu")
		(net "M_H_CPU0_SA_DQ<15>")
	)
	(segment
		(start 387.915912 -280.505916)
		(end 387.679184 -280.269188)
		(width 0.088646)
		(layer "In11.Cu")
		(net "M_H_CPU0_SA_DQ<15>")
	)
	(segment
		(start 376.889518 -276.219158)
		(end 376.880628 -276.214078)
		(width 0.088646)
		(layer "In11.Cu")
		(net "M_H_CPU0_SA_DQ<15>")
	)
	(segment
		(start 443.465458 -302.916082)
		(end 442.046614 -302.916082)
		(width 0.18288)
		(layer "In11.Cu")
		(net "M_H_CPU0_SA_DQ<15>")
	)
	(segment
		(start 383.37236 -277.032974)
		(end 383.363978 -277.0378)
		(width 0.088646)
		(layer "In11.Cu")
		(net "M_H_CPU0_SA_DQ<15>")
	)
	(segment
		(start 406.126188 -301.444152)
		(end 405.440388 -301.444152)
		(width 0.18288)
		(layer "In11.Cu")
		(net "M_H_CPU0_SA_DQ<15>")
	)
	(segment
		(start 375.01576 -272.967196)
		(end 375.009664 -272.96364)
		(width 0.088646)
		(layer "In11.Cu")
		(net "M_H_CPU0_SA_DQ<15>")
	)
	(segment
		(start 433.64404 -303.128172)
		(end 433.32654 -303.128172)
		(width 0.18288)
		(layer "In11.Cu")
		(net "M_H_CPU0_SA_DQ<15>")
	)
	(segment
		(start 433.1335 -303.321212)
		(end 433.1335 -303.817782)
		(width 0.18288)
		(layer "In11.Cu")
		(net "M_H_CPU0_SA_DQ<15>")
	)
	(segment
		(start 437.691784 -304.94097)
		(end 436.745126 -303.994312)
		(width 0.18288)
		(layer "In11.Cu")
		(net "M_H_CPU0_SA_DQ<15>")
	)
	(segment
		(start 445.691514 -300.690026)
		(end 443.465458 -302.916082)
		(width 0.18288)
		(layer "In11.Cu")
		(net "M_H_CPU0_SA_DQ<15>")
	)
	(segment
		(start 417.642294 -304.056034)
		(end 417.158678 -304.056034)
		(width 0.18288)
		(layer "In11.Cu")
		(net "M_H_CPU0_SA_DQ<15>")
	)
	(segment
		(start 449.773802 -298.376848)
		(end 449.258436 -298.376848)
		(width 0.18288)
		(layer "In11.Cu")
		(net "M_H_CPU0_SA_DQ<15>")
	)
	(segment
		(start 454.580498 -298.896024)
		(end 454.401428 -298.896024)
		(width 0.18288)
		(layer "In11.Cu")
		(net "M_H_CPU0_SA_DQ<15>")
	)
	(segment
		(start 375.762012 -274.266914)
		(end 375.762012 -274.25142)
		(width 0.088646)
		(layer "In11.Cu")
		(net "M_H_CPU0_SA_DQ<15>")
	)
	(segment
		(start 386.641086 -278.678894)
		(end 386.569712 -278.60752)
		(width 0.088646)
		(layer "In11.Cu")
		(net "M_H_CPU0_SA_DQ<15>")
	)
	(segment
		(start 449.258436 -298.376848)
		(end 447.761106 -299.874178)
		(width 0.18288)
		(layer "In11.Cu")
		(net "M_H_CPU0_SA_DQ<15>")
	)
	(segment
		(start 421.526462 -305.693318)
		(end 419.280594 -305.693318)
		(width 0.18288)
		(layer "In11.Cu")
		(net "M_H_CPU0_SA_DQ<15>")
	)
	(segment
		(start 452.469758 -298.896024)
		(end 452.276718 -299.089064)
		(width 0.18288)
		(layer "In11.Cu")
		(net "M_H_CPU0_SA_DQ<15>")
	)
	(segment
		(start 417.158678 -304.056034)
		(end 416.308794 -303.20488)
		(width 0.18288)
		(layer "In11.Cu")
		(net "M_H_CPU0_SA_DQ<15>")
	)
	(segment
		(start 375.95556 -274.594828)
		(end 375.949464 -274.591272)
		(width 0.088646)
		(layer "In11.Cu")
		(net "M_H_CPU0_SA_DQ<15>")
	)
	(segment
		(start 383.387092 -277.024338)
		(end 383.37236 -277.032974)
		(width 0.088646)
		(layer "In11.Cu")
		(net "M_H_CPU0_SA_DQ<15>")
	)
	(segment
		(start 426.231812 -304.842672)
		(end 424.024806 -304.842672)
		(width 0.18288)
		(layer "In11.Cu")
		(net "M_H_CPU0_SA_DQ<15>")
	)
	(segment
		(start 375.009664 -272.96364)
		(end 374.994932 -272.955004)
		(width 0.088646)
		(layer "In11.Cu")
		(net "M_H_CPU0_SA_DQ<15>")
	)
	(segment
		(start 386.569712 -278.60752)
		(end 386.569712 -278.31796)
		(width 0.088646)
		(layer "In11.Cu")
		(net "M_H_CPU0_SA_DQ<15>")
	)
	(segment
		(start 452.276718 -299.895006)
		(end 452.083678 -300.088046)
		(width 0.18288)
		(layer "In11.Cu")
		(net "M_H_CPU0_SA_DQ<15>")
	)
	(segment
		(start 429.493172 -304.049684)
		(end 429.175672 -304.049684)
		(width 0.18288)
		(layer "In11.Cu")
		(net "M_H_CPU0_SA_DQ<15>")
	)
	(segment
		(start 454.208388 -299.089064)
		(end 454.208388 -299.876464)
		(width 0.18288)
		(layer "In11.Cu")
		(net "M_H_CPU0_SA_DQ<15>")
	)
	(segment
		(start 412.638748 -303.20488)
		(end 412.446724 -303.012856)
		(width 0.18288)
		(layer "In11.Cu")
		(net "M_H_CPU0_SA_DQ<15>")
	)
	(segment
		(start 452.276718 -299.089064)
		(end 452.276718 -299.895006)
		(width 0.18288)
		(layer "In11.Cu")
		(net "M_H_CPU0_SA_DQ<15>")
	)
	(segment
		(start 384.322574 -277.026878)
		(end 384.31216 -277.032974)
		(width 0.088646)
		(layer "In11.Cu")
		(net "M_H_CPU0_SA_DQ<15>")
	)
	(segment
		(start 379.623828 -277.026878)
		(end 379.613414 -277.032974)
		(width 0.088646)
		(layer "In11.Cu")
		(net "M_H_CPU0_SA_DQ<15>")
	)
	(segment
		(start 388.610602 -281.200606)
		(end 387.915912 -280.505916)
		(width 0.18288)
		(layer "In11.Cu")
		(net "M_H_CPU0_SA_DQ<15>")
	)
	(segment
		(start 381.507746 -277.024338)
		(end 381.493014 -277.032974)
		(width 0.088646)
		(layer "In11.Cu")
		(net "M_H_CPU0_SA_DQ<15>")
	)
	(segment
		(start 405.440388 -301.444152)
		(end 404.986236 -300.99)
		(width 0.18288)
		(layer "In11.Cu")
		(net "M_H_CPU0_SA_DQ<15>")
	)
	(segment
		(start 387.679184 -280.269188)
		(end 387.679184 -280.094944)
		(width 0.088646)
		(layer "In11.Cu")
		(net "M_H_CPU0_SA_DQ<15>")
	)
	(segment
		(start 441.691776 -303.56048)
		(end 440.41187 -304.840386)
		(width 0.18288)
		(layer "In11.Cu")
		(net "M_H_CPU0_SA_DQ<15>")
	)
	(segment
		(start 454.208388 -299.876464)
		(end 454.015348 -300.069504)
		(width 0.18288)
		(layer "In11.Cu")
		(net "M_H_CPU0_SA_DQ<15>")
	)
	(segment
		(start 429.175672 -304.049684)
		(end 428.982632 -304.242724)
		(width 0.18288)
		(layer "In11.Cu")
		(net "M_H_CPU0_SA_DQ<15>")
	)
	(segment
		(start 447.147442 -299.874178)
		(end 446.331594 -300.690026)
		(width 0.18288)
		(layer "In11.Cu")
		(net "M_H_CPU0_SA_DQ<15>")
	)
	(segment
		(start 382.447546 -277.024338)
		(end 382.432814 -277.032974)
		(width 0.088646)
		(layer "In11.Cu")
		(net "M_H_CPU0_SA_DQ<15>")
	)
	(segment
		(start 452.083678 -300.088046)
		(end 451.766178 -300.088046)
		(width 0.18288)
		(layer "In11.Cu")
		(net "M_H_CPU0_SA_DQ<15>")
	)
	(segment
		(start 423.842688 -305.02479)
		(end 422.19499 -305.02479)
		(width 0.18288)
		(layer "In11.Cu")
		(net "M_H_CPU0_SA_DQ<15>")
	)
	(segment
		(start 433.1335 -303.817782)
		(end 432.94046 -304.010822)
		(width 0.18288)
		(layer "In11.Cu")
		(net "M_H_CPU0_SA_DQ<15>")
	)
	(segment
		(start 406.67559 -300.89475)
		(end 406.126188 -301.444152)
		(width 0.18288)
		(layer "In11.Cu")
		(net "M_H_CPU0_SA_DQ<15>")
	)
	(segment
		(start 433.83708 -303.321212)
		(end 433.64404 -303.128172)
		(width 0.18288)
		(layer "In11.Cu")
		(net "M_H_CPU0_SA_DQ<15>")
	)
	(segment
		(start 396.896082 -291.306504)
		(end 396.896082 -289.668966)
		(width 0.18288)
		(layer "In11.Cu")
		(net "M_H_CPU0_SA_DQ<15>")
	)
	(segment
		(start 408.385518 -300.89475)
		(end 406.67559 -300.89475)
		(width 0.18288)
		(layer "In11.Cu")
		(net "M_H_CPU0_SA_DQ<15>")
	)
	(segment
		(start 375.949464 -274.591272)
		(end 375.940574 -274.586192)
		(width 0.088646)
		(layer "In11.Cu")
		(net "M_H_CPU0_SA_DQ<15>")
	)
	(segment
		(start 442.046614 -302.916082)
		(end 441.691776 -303.27092)
		(width 0.18288)
		(layer "In11.Cu")
		(net "M_H_CPU0_SA_DQ<15>")
	)
	(segment
		(start 424.024806 -304.842672)
		(end 423.842688 -305.02479)
		(width 0.18288)
		(layer "In11.Cu")
		(net "M_H_CPU0_SA_DQ<15>")
	)
	(segment
		(start 376.419618 -275.405088)
		(end 376.410728 -275.400008)
		(width 0.088646)
		(layer "In11.Cu")
		(net "M_H_CPU0_SA_DQ<15>")
	)
	(segment
		(start 451.573138 -299.895006)
		(end 451.573138 -299.089064)
		(width 0.18288)
		(layer "In11.Cu")
		(net "M_H_CPU0_SA_DQ<15>")
	)
	(arc
		(start 373.498618 -272.967196)
		(mid 373.418605 -273.024701)
		(end 373.349774 -273.095212)
		(width 0.088646)
		(layer "In11.Cu")
		(net "M_H_CPU0_SA_DQ<15>")
	)
	(arc
		(start 380.178564 -277.032974)
		(mid 379.902005 -276.957231)
		(end 379.623828 -277.026878)
		(width 0.088646)
		(layer "In11.Cu")
		(net "M_H_CPU0_SA_DQ<15>")
	)
	(arc
		(start 378.290328 -277.027894)
		(mid 378.159414 -276.891534)
		(end 378.111766 -276.708616)
		(width 0.088646)
		(layer "In11.Cu")
		(net "M_H_CPU0_SA_DQ<15>")
	)
	(arc
		(start 381.493014 -277.032974)
		(mid 381.305816 -277.083117)
		(end 381.118618 -277.032974)
		(width 0.088646)
		(layer "In11.Cu")
		(net "M_H_CPU0_SA_DQ<15>")
	)
	(arc
		(start 376.410728 -275.400008)
		(mid 376.279814 -275.263648)
		(end 376.232166 -275.08073)
		(width 0.088646)
		(layer "In11.Cu")
		(net "M_H_CPU0_SA_DQ<15>")
	)
	(arc
		(start 374.994932 -272.955004)
		(mid 374.718457 -272.887684)
		(end 374.44426 -272.96364)
		(width 0.088646)
		(layer "In11.Cu")
		(net "M_H_CPU0_SA_DQ<15>")
	)
	(arc
		(start 376.880628 -276.214078)
		(mid 376.749714 -276.077718)
		(end 376.702066 -275.8948)
		(width 0.088646)
		(layer "In11.Cu")
		(net "M_H_CPU0_SA_DQ<15>")
	)
	(arc
		(start 382.432814 -277.032974)
		(mid 382.245616 -277.083117)
		(end 382.058418 -277.032974)
		(width 0.088646)
		(layer "In11.Cu")
		(net "M_H_CPU0_SA_DQ<15>")
	)
	(arc
		(start 381.118618 -277.032974)
		(mid 380.841805 -276.957104)
		(end 380.563374 -277.026878)
		(width 0.088646)
		(layer "In11.Cu")
		(net "M_H_CPU0_SA_DQ<15>")
	)
	(arc
		(start 383.937764 -277.032974)
		(mid 383.663565 -276.957139)
		(end 383.387092 -277.024338)
		(width 0.088646)
		(layer "In11.Cu")
		(net "M_H_CPU0_SA_DQ<15>")
	)
	(arc
		(start 385.160012 -277.512526)
		(mid 385.081901 -277.235577)
		(end 384.877564 -277.032974)
		(width 0.088646)
		(layer "In11.Cu")
		(net "M_H_CPU0_SA_DQ<15>")
	)
	(arc
		(start 380.55296 -277.032974)
		(mid 380.365762 -277.083117)
		(end 380.178564 -277.032974)
		(width 0.088646)
		(layer "In11.Cu")
		(net "M_H_CPU0_SA_DQ<15>")
	)
	(arc
		(start 378.111766 -276.708616)
		(mid 378.037775 -276.42905)
		(end 377.83516 -276.222714)
		(width 0.088646)
		(layer "In11.Cu")
		(net "M_H_CPU0_SA_DQ<15>")
	)
	(arc
		(start 385.72186 -277.84679)
		(mid 385.534662 -277.896933)
		(end 385.347464 -277.84679)
		(width 0.088646)
		(layer "In11.Cu")
		(net "M_H_CPU0_SA_DQ<15>")
	)
	(arc
		(start 382.998218 -277.032974)
		(mid 382.724019 -276.957139)
		(end 382.447546 -277.024338)
		(width 0.088646)
		(layer "In11.Cu")
		(net "M_H_CPU0_SA_DQ<15>")
	)
	(arc
		(start 384.877818 -277.032974)
		(mid 384.601005 -276.957104)
		(end 384.322574 -277.026878)
		(width 0.088646)
		(layer "In11.Cu")
		(net "M_H_CPU0_SA_DQ<15>")
	)
	(arc
		(start 373.295926 -273.161252)
		(mid 373.258113 -273.226392)
		(end 373.243094 -273.30019)
		(width 0.088646)
		(layer "In11.Cu")
		(net "M_H_CPU0_SA_DQ<15>")
	)
	(arc
		(start 377.81865 -276.213062)
		(mid 377.540472 -276.143339)
		(end 377.263914 -276.219158)
		(width 0.088646)
		(layer "In11.Cu")
		(net "M_H_CPU0_SA_DQ<15>")
	)
	(arc
		(start 374.05945 -272.957544)
		(mid 373.781272 -272.887821)
		(end 373.504714 -272.96364)
		(width 0.088646)
		(layer "In11.Cu")
		(net "M_H_CPU0_SA_DQ<15>")
	)
	(arc
		(start 385.338574 -277.84171)
		(mid 385.20766 -277.70535)
		(end 385.160012 -277.522432)
		(width 0.088646)
		(layer "In11.Cu")
		(net "M_H_CPU0_SA_DQ<15>")
	)
	(arc
		(start 373.24284 -273.300952)
		(mid 373.23692 -273.323319)
		(end 373.231918 -273.34591)
		(width 0.088646)
		(layer "In11.Cu")
		(net "M_H_CPU0_SA_DQ<15>")
	)
	(arc
		(start 375.940574 -274.586192)
		(mid 375.80966 -274.449832)
		(end 375.762012 -274.266914)
		(width 0.088646)
		(layer "In11.Cu")
		(net "M_H_CPU0_SA_DQ<15>")
	)
	(arc
		(start 384.31216 -277.032974)
		(mid 384.124962 -277.083117)
		(end 383.937764 -277.032974)
		(width 0.088646)
		(layer "In11.Cu")
		(net "M_H_CPU0_SA_DQ<15>")
	)
	(arc
		(start 373.231918 -273.34591)
		(mid 373.228105 -273.360159)
		(end 373.222012 -273.373596)
		(width 0.088646)
		(layer "In11.Cu")
		(net "M_H_CPU0_SA_DQ<15>")
	)
	(arc
		(start 374.44426 -272.96364)
		(mid 374.257062 -273.013783)
		(end 374.069864 -272.96364)
		(width 0.088646)
		(layer "In11.Cu")
		(net "M_H_CPU0_SA_DQ<15>")
	)
	(arc
		(start 383.363978 -277.0378)
		(mid 383.18047 -277.083078)
		(end 382.998218 -277.032974)
		(width 0.088646)
		(layer "In11.Cu")
		(net "M_H_CPU0_SA_DQ<15>")
	)
	(arc
		(start 373.243094 -273.30019)
		(mid 373.242967 -273.300571)
		(end 373.24284 -273.300952)
		(width 0.088646)
		(layer "In11.Cu")
		(net "M_H_CPU0_SA_DQ<15>")
	)
	(arc
		(start 377.263914 -276.219158)
		(mid 377.076716 -276.269301)
		(end 376.889518 -276.219158)
		(width 0.088646)
		(layer "In11.Cu")
		(net "M_H_CPU0_SA_DQ<15>")
	)
	(arc
		(start 378.673614 -277.032974)
		(mid 378.486416 -277.083117)
		(end 378.299218 -277.032974)
		(width 0.088646)
		(layer "In11.Cu")
		(net "M_H_CPU0_SA_DQ<15>")
	)
	(arc
		(start 375.470928 -273.772376)
		(mid 375.340014 -273.636016)
		(end 375.292366 -273.453098)
		(width 0.088646)
		(layer "In11.Cu")
		(net "M_H_CPU0_SA_DQ<15>")
	)
	(arc
		(start 373.222012 -273.373596)
		(mid 373.163593 -273.431908)
		(end 373.083836 -273.453098)
		(width 0.088646)
		(layer "In11.Cu")
		(net "M_H_CPU0_SA_DQ<15>")
	)
	(arc
		(start 376.702066 -275.880576)
		(mid 376.622925 -275.605953)
		(end 376.419618 -275.405088)
		(width 0.088646)
		(layer "In11.Cu")
		(net "M_H_CPU0_SA_DQ<15>")
	)
	(arc
		(start 379.239018 -277.032974)
		(mid 378.956316 -276.957198)
		(end 378.673614 -277.032974)
		(width 0.088646)
		(layer "In11.Cu")
		(net "M_H_CPU0_SA_DQ<15>")
	)
	(arc
		(start 386.569712 -278.31796)
		(mid 386.279234 -277.842241)
		(end 385.72186 -277.84679)
		(width 0.088646)
		(layer "In11.Cu")
		(net "M_H_CPU0_SA_DQ<15>")
	)
	(arc
		(start 375.762012 -274.25142)
		(mid 375.682642 -273.977686)
		(end 375.479818 -273.777456)
		(width 0.088646)
		(layer "In11.Cu")
		(net "M_H_CPU0_SA_DQ<15>")
	)
	(arc
		(start 382.058418 -277.032974)
		(mid 381.784219 -276.957139)
		(end 381.507746 -277.024338)
		(width 0.088646)
		(layer "In11.Cu")
		(net "M_H_CPU0_SA_DQ<15>")
	)
	(arc
		(start 379.613414 -277.032974)
		(mid 379.426216 -277.083117)
		(end 379.239018 -277.032974)
		(width 0.088646)
		(layer "In11.Cu")
		(net "M_H_CPU0_SA_DQ<15>")
	)
	(arc
		(start 376.232166 -275.08073)
		(mid 376.158175 -274.801164)
		(end 375.95556 -274.594828)
		(width 0.088646)
		(layer "In11.Cu")
		(net "M_H_CPU0_SA_DQ<15>")
	)
	(arc
		(start 375.292366 -273.453098)
		(mid 375.218375 -273.173532)
		(end 375.01576 -272.967196)
		(width 0.088646)
		(layer "In11.Cu")
		(net "M_H_CPU0_SA_DQ<15>")
	)
	(segment
		(start 460.558134 -300.591728)
		(end 460.570326 -300.60392)
		(width 0.1016)
		(layer "F.Cu")
		(net "M_H_CPU0_SA_DQ<14>")
	)
	(segment
		(start 458.543152 -300.59884)
		(end 458.550264 -300.591728)
		(width 0.1016)
		(layer "F.Cu")
		(net "M_H_CPU0_SA_DQ<14>")
	)
	(segment
		(start 461.455516 -300.149006)
		(end 461.689704 -299.914818)
		(width 0.20066)
		(layer "F.Cu")
		(net "M_H_CPU0_SA_DQ<14>")
	)
	(segment
		(start 373.317516 -273.730974)
		(end 373.317516 -274.26666)
		(width 0.20066)
		(layer "F.Cu")
		(net "M_H_CPU0_SA_DQ<14>")
	)
	(segment
		(start 455.011282 -300.166532)
		(end 456.115928 -300.166532)
		(width 0.20066)
		(layer "F.Cu")
		(net "M_H_CPU0_SA_DQ<14>")
	)
	(segment
		(start 461.689704 -299.914818)
		(end 462.073752 -299.914818)
		(width 0.20066)
		(layer "F.Cu")
		(net "M_H_CPU0_SA_DQ<14>")
	)
	(segment
		(start 461.455516 -300.399958)
		(end 461.455516 -300.149006)
		(width 0.20066)
		(layer "F.Cu")
		(net "M_H_CPU0_SA_DQ<14>")
	)
	(segment
		(start 456.116182 -300.166786)
		(end 457.814426 -300.166786)
		(width 0.20066)
		(layer "F.Cu")
		(net "M_H_CPU0_SA_DQ<14>")
	)
	(segment
		(start 461.251554 -300.60392)
		(end 461.455516 -300.399958)
		(width 0.20066)
		(layer "F.Cu")
		(net "M_H_CPU0_SA_DQ<14>")
	)
	(segment
		(start 458.550264 -300.591728)
		(end 460.558134 -300.591728)
		(width 0.1016)
		(layer "F.Cu")
		(net "M_H_CPU0_SA_DQ<14>")
	)
	(segment
		(start 458.538326 -300.59884)
		(end 458.543152 -300.59884)
		(width 0.101854)
		(layer "F.Cu")
		(net "M_H_CPU0_SA_DQ<14>")
	)
	(segment
		(start 457.814426 -300.166786)
		(end 458.24648 -300.59884)
		(width 0.20066)
		(layer "F.Cu")
		(net "M_H_CPU0_SA_DQ<14>")
	)
	(segment
		(start 373.317516 -274.26666)
		(end 373.317262 -274.266914)
		(width 0.20066)
		(layer "F.Cu")
		(net "M_H_CPU0_SA_DQ<14>")
	)
	(segment
		(start 456.115928 -300.166532)
		(end 456.116182 -300.166786)
		(width 0.20066)
		(layer "F.Cu")
		(net "M_H_CPU0_SA_DQ<14>")
	)
	(segment
		(start 462.073752 -299.914818)
		(end 462.32572 -300.166786)
		(width 0.20066)
		(layer "F.Cu")
		(net "M_H_CPU0_SA_DQ<14>")
	)
	(segment
		(start 462.32572 -300.166786)
		(end 463.659982 -300.166786)
		(width 0.20066)
		(layer "F.Cu")
		(net "M_H_CPU0_SA_DQ<14>")
	)
	(segment
		(start 458.24648 -300.59884)
		(end 458.538326 -300.59884)
		(width 0.20066)
		(layer "F.Cu")
		(net "M_H_CPU0_SA_DQ<14>")
	)
	(segment
		(start 460.570326 -300.60392)
		(end 461.251554 -300.60392)
		(width 0.20066)
		(layer "F.Cu")
		(net "M_H_CPU0_SA_DQ<14>")
	)
	(segment
		(start 437.136286 -306.724812)
		(end 436.103522 -305.692048)
		(width 0.18288)
		(layer "In11.Cu")
		(net "M_H_CPU0_SA_DQ<14>")
	)
	(segment
		(start 431.612294 -305.871626)
		(end 430.833022 -306.650898)
		(width 0.18288)
		(layer "In11.Cu")
		(net "M_H_CPU0_SA_DQ<14>")
	)
	(segment
		(start 452.648066 -300.623478)
		(end 452.455026 -300.816518)
		(width 0.18288)
		(layer "In11.Cu")
		(net "M_H_CPU0_SA_DQ<14>")
	)
	(segment
		(start 404.819104 -302.392588)
		(end 404.546308 -302.392588)
		(width 0.18288)
		(layer "In11.Cu")
		(net "M_H_CPU0_SA_DQ<14>")
	)
	(segment
		(start 444.278004 -304.057558)
		(end 444.510668 -304.290222)
		(width 0.18288)
		(layer "In11.Cu")
		(net "M_H_CPU0_SA_DQ<14>")
	)
	(segment
		(start 384.877564 -278.66086)
		(end 384.868674 -278.65578)
		(width 0.088646)
		(layer "In11.Cu")
		(net "M_H_CPU0_SA_DQ<14>")
	)
	(segment
		(start 404.8125 -303.121568)
		(end 405.043894 -302.890174)
		(width 0.18288)
		(layer "In11.Cu")
		(net "M_H_CPU0_SA_DQ<14>")
	)
	(segment
		(start 412.557722 -304.82794)
		(end 411.438344 -304.82794)
		(width 0.18288)
		(layer "In11.Cu")
		(net "M_H_CPU0_SA_DQ<14>")
	)
	(segment
		(start 387.13664 -280.455624)
		(end 386.556758 -279.875742)
		(width 0.088646)
		(layer "In11.Cu")
		(net "M_H_CPU0_SA_DQ<14>")
	)
	(segment
		(start 417.642294 -305.76266)
		(end 416.829494 -305.76266)
		(width 0.18288)
		(layer "In11.Cu")
		(net "M_H_CPU0_SA_DQ<14>")
	)
	(segment
		(start 445.008254 -303.792636)
		(end 444.77559 -303.559972)
		(width 0.18288)
		(layer "In11.Cu")
		(net "M_H_CPU0_SA_DQ<14>")
	)
	(segment
		(start 407.004012 -304.93843)
		(end 406.056084 -303.990502)
		(width 0.18288)
		(layer "In11.Cu")
		(net "M_H_CPU0_SA_DQ<14>")
	)
	(segment
		(start 375.949464 -276.219158)
		(end 375.940574 -276.214078)
		(width 0.088646)
		(layer "In11.Cu")
		(net "M_H_CPU0_SA_DQ<14>")
	)
	(segment
		(start 379.708664 -277.84679)
		(end 379.69825 -277.840694)
		(width 0.088646)
		(layer "In11.Cu")
		(net "M_H_CPU0_SA_DQ<14>")
	)
	(segment
		(start 375.762012 -275.8948)
		(end 375.762012 -275.872702)
		(width 0.088646)
		(layer "In11.Cu")
		(net "M_H_CPU0_SA_DQ<14>")
	)
	(segment
		(start 446.285112 -302.78832)
		(end 445.28105 -303.792636)
		(width 0.18288)
		(layer "In11.Cu")
		(net "M_H_CPU0_SA_DQ<14>")
	)
	(segment
		(start 375.95556 -276.222714)
		(end 375.949464 -276.219158)
		(width 0.088646)
		(layer "In11.Cu")
		(net "M_H_CPU0_SA_DQ<14>")
	)
	(segment
		(start 453.824594 -301.643034)
		(end 453.507094 -301.643034)
		(width 0.18288)
		(layer "In11.Cu")
		(net "M_H_CPU0_SA_DQ<14>")
	)
	(segment
		(start 447.650362 -301.574962)
		(end 447.424302 -301.574962)
		(width 0.18288)
		(layer "In11.Cu")
		(net "M_H_CPU0_SA_DQ<14>")
	)
	(segment
		(start 386.556758 -279.716738)
		(end 386.404358 -279.564338)
		(width 0.088646)
		(layer "In11.Cu")
		(net "M_H_CPU0_SA_DQ<14>")
	)
	(segment
		(start 451.751446 -301.002954)
		(end 451.751446 -300.816518)
		(width 0.18288)
		(layer "In11.Cu")
		(net "M_H_CPU0_SA_DQ<14>")
	)
	(segment
		(start 443.651894 -304.818034)
		(end 443.386972 -305.082194)
		(width 0.18288)
		(layer "In11.Cu")
		(net "M_H_CPU0_SA_DQ<14>")
	)
	(segment
		(start 439.71845 -306.542186)
		(end 439.203084 -306.02682)
		(width 0.18288)
		(layer "In11.Cu")
		(net "M_H_CPU0_SA_DQ<14>")
	)
	(segment
		(start 422.300146 -306.61991)
		(end 421.526208 -307.393848)
		(width 0.18288)
		(layer "In11.Cu")
		(net "M_H_CPU0_SA_DQ<14>")
	)
	(segment
		(start 426.876718 -306.405026)
		(end 426.406564 -306.87518)
		(width 0.18288)
		(layer "In11.Cu")
		(net "M_H_CPU0_SA_DQ<14>")
	)
	(segment
		(start 451.944486 -301.195994)
		(end 451.751446 -301.002954)
		(width 0.18288)
		(layer "In11.Cu")
		(net "M_H_CPU0_SA_DQ<14>")
	)
	(segment
		(start 375.479818 -275.405088)
		(end 375.470928 -275.400008)
		(width 0.088646)
		(layer "In11.Cu")
		(net "M_H_CPU0_SA_DQ<14>")
	)
	(segment
		(start 447.76644 -301.57928)
		(end 447.65468 -301.57928)
		(width 0.18288)
		(layer "In11.Cu")
		(net "M_H_CPU0_SA_DQ<14>")
	)
	(segment
		(start 395.838426 -290.06419)
		(end 389.076946 -283.302964)
		(width 0.18288)
		(layer "In11.Cu")
		(net "M_H_CPU0_SA_DQ<14>")
	)
	(segment
		(start 447.424302 -301.574962)
		(end 447.18224 -301.817024)
		(width 0.18288)
		(layer "In11.Cu")
		(net "M_H_CPU0_SA_DQ<14>")
	)
	(segment
		(start 409.034742 -304.51679)
		(end 408.717496 -304.51679)
		(width 0.18288)
		(layer "In11.Cu")
		(net "M_H_CPU0_SA_DQ<14>")
	)
	(segment
		(start 453.121014 -300.623478)
		(end 452.648066 -300.623478)
		(width 0.18288)
		(layer "In11.Cu")
		(net "M_H_CPU0_SA_DQ<14>")
	)
	(segment
		(start 395.838426 -291.797486)
		(end 395.838426 -290.06419)
		(width 0.18288)
		(layer "In11.Cu")
		(net "M_H_CPU0_SA_DQ<14>")
	)
	(segment
		(start 383.46761 -277.84679)
		(end 383.457196 -277.840694)
		(width 0.088646)
		(layer "In11.Cu")
		(net "M_H_CPU0_SA_DQ<14>")
	)
	(segment
		(start 410.541724 -304.6349)
		(end 410.333444 -304.84318)
		(width 0.18288)
		(layer "In11.Cu")
		(net "M_H_CPU0_SA_DQ<14>")
	)
	(segment
		(start 387.867906 -281.582622)
		(end 387.642608 -281.357324)
		(width 0.18288)
		(layer "In11.Cu")
		(net "M_H_CPU0_SA_DQ<14>")
	)
	(segment
		(start 455.011282 -300.166532)
		(end 454.55332 -300.623478)
		(width 0.18288)
		(layer "In11.Cu")
		(net "M_H_CPU0_SA_DQ<14>")
	)
	(segment
		(start 377.365514 -277.03653)
		(end 377.359418 -277.032974)
		(width 0.088646)
		(layer "In11.Cu")
		(net "M_H_CPU0_SA_DQ<14>")
	)
	(segment
		(start 386.556758 -279.875742)
		(end 386.556758 -279.716738)
		(width 0.088646)
		(layer "In11.Cu")
		(net "M_H_CPU0_SA_DQ<14>")
	)
	(segment
		(start 453.507094 -301.643034)
		(end 453.314054 -301.449994)
		(width 0.18288)
		(layer "In11.Cu")
		(net "M_H_CPU0_SA_DQ<14>")
	)
	(segment
		(start 447.18224 -301.817024)
		(end 447.18224 -302.27778)
		(width 0.18288)
		(layer "In11.Cu")
		(net "M_H_CPU0_SA_DQ<14>")
	)
	(segment
		(start 453.314054 -301.449994)
		(end 453.314054 -300.816518)
		(width 0.18288)
		(layer "In11.Cu")
		(net "M_H_CPU0_SA_DQ<14>")
	)
	(segment
		(start 436.103522 -305.692048)
		(end 435.297072 -305.692048)
		(width 0.18288)
		(layer "In11.Cu")
		(net "M_H_CPU0_SA_DQ<14>")
	)
	(segment
		(start 427.573694 -306.405026)
		(end 426.876718 -306.405026)
		(width 0.18288)
		(layer "In11.Cu")
		(net "M_H_CPU0_SA_DQ<14>")
	)
	(segment
		(start 454.017634 -300.816518)
		(end 454.017634 -301.449994)
		(width 0.18288)
		(layer "In11.Cu")
		(net "M_H_CPU0_SA_DQ<14>")
	)
	(segment
		(start 404.546308 -302.392588)
		(end 404.314914 -302.623982)
		(width 0.18288)
		(layer "In11.Cu")
		(net "M_H_CPU0_SA_DQ<14>")
	)
	(segment
		(start 373.898414 -273.822922)
		(end 373.317262 -274.266914)
		(width 0.088646)
		(layer "In11.Cu")
		(net "M_H_CPU0_SA_DQ<14>")
	)
	(segment
		(start 374.822466 -274.27555)
		(end 374.822466 -274.257008)
		(width 0.088646)
		(layer "In11.Cu")
		(net "M_H_CPU0_SA_DQ<14>")
	)
	(segment
		(start 435.117494 -305.871626)
		(end 431.612294 -305.871626)
		(width 0.18288)
		(layer "In11.Cu")
		(net "M_H_CPU0_SA_DQ<14>")
	)
	(segment
		(start 424.418506 -306.541678)
		(end 424.059858 -306.18303)
		(width 0.18288)
		(layer "In11.Cu")
		(net "M_H_CPU0_SA_DQ<14>")
	)
	(segment
		(start 411.438344 -304.82794)
		(end 411.245304 -304.6349)
		(width 0.18288)
		(layer "In11.Cu")
		(net "M_H_CPU0_SA_DQ<14>")
	)
	(segment
		(start 404.314914 -302.623982)
		(end 404.042118 -302.623982)
		(width 0.18288)
		(layer "In11.Cu")
		(net "M_H_CPU0_SA_DQ<14>")
	)
	(segment
		(start 442.925962 -305.082194)
		(end 442.623194 -304.779426)
		(width 0.18288)
		(layer "In11.Cu")
		(net "M_H_CPU0_SA_DQ<14>")
	)
	(segment
		(start 410.541724 -304.33391)
		(end 410.541724 -304.6349)
		(width 0.18288)
		(layer "In11.Cu")
		(net "M_H_CPU0_SA_DQ<14>")
	)
	(segment
		(start 411.245304 -304.6349)
		(end 411.245304 -304.33391)
		(width 0.18288)
		(layer "In11.Cu")
		(net "M_H_CPU0_SA_DQ<14>")
	)
	(segment
		(start 386.099812 -279.150318)
		(end 386.099812 -279.140412)
		(width 0.088646)
		(layer "In11.Cu")
		(net "M_H_CPU0_SA_DQ<14>")
	)
	(segment
		(start 411.052264 -304.14087)
		(end 410.734764 -304.14087)
		(width 0.18288)
		(layer "In11.Cu")
		(net "M_H_CPU0_SA_DQ<14>")
	)
	(segment
		(start 375.021856 -274.598384)
		(end 375.009664 -274.591272)
		(width 0.088646)
		(layer "In11.Cu")
		(net "M_H_CPU0_SA_DQ<14>")
	)
	(segment
		(start 447.65468 -301.57928)
		(end 447.650362 -301.574962)
		(width 0.18288)
		(layer "In11.Cu")
		(net "M_H_CPU0_SA_DQ<14>")
	)
	(segment
		(start 387.642608 -281.357324)
		(end 387.13664 -280.851356)
		(width 0.088646)
		(layer "In11.Cu")
		(net "M_H_CPU0_SA_DQ<14>")
	)
	(segment
		(start 410.333444 -304.84318)
		(end 409.361132 -304.84318)
		(width 0.18288)
		(layer "In11.Cu")
		(net "M_H_CPU0_SA_DQ<14>")
	)
	(segment
		(start 451.525386 -300.590458)
		(end 450.577204 -300.590458)
		(width 0.18288)
		(layer "In11.Cu")
		(net "M_H_CPU0_SA_DQ<14>")
	)
	(segment
		(start 408.717496 -304.51679)
		(end 408.295856 -304.93843)
		(width 0.18288)
		(layer "In11.Cu")
		(net "M_H_CPU0_SA_DQ<14>")
	)
	(segment
		(start 405.043894 -302.617378)
		(end 404.819104 -302.392588)
		(width 0.18288)
		(layer "In11.Cu")
		(net "M_H_CPU0_SA_DQ<14>")
	)
	(segment
		(start 377.829318 -277.84679)
		(end 377.820428 -277.84171)
		(width 0.088646)
		(layer "In11.Cu")
		(net "M_H_CPU0_SA_DQ<14>")
	)
	(segment
		(start 416.829494 -305.76266)
		(end 416.07486 -305.008026)
		(width 0.18288)
		(layer "In11.Cu")
		(net "M_H_CPU0_SA_DQ<14>")
	)
	(segment
		(start 411.245304 -304.33391)
		(end 411.052264 -304.14087)
		(width 0.18288)
		(layer "In11.Cu")
		(net "M_H_CPU0_SA_DQ<14>")
	)
	(segment
		(start 378.218446 -277.838154)
		(end 378.203714 -277.84679)
		(width 0.088646)
		(layer "In11.Cu")
		(net "M_H_CPU0_SA_DQ<14>")
	)
	(segment
		(start 444.255906 -304.818034)
		(end 443.651894 -304.818034)
		(width 0.18288)
		(layer "In11.Cu")
		(net "M_H_CPU0_SA_DQ<14>")
	)
	(segment
		(start 404.042118 -302.623982)
		(end 403.834092 -302.415956)
		(width 0.18288)
		(layer "In11.Cu")
		(net "M_H_CPU0_SA_DQ<14>")
	)
	(segment
		(start 419.273482 -307.393848)
		(end 417.642294 -305.76266)
		(width 0.18288)
		(layer "In11.Cu")
		(net "M_H_CPU0_SA_DQ<14>")
	)
	(segment
		(start 380.648464 -277.84679)
		(end 380.633732 -277.838154)
		(width 0.088646)
		(layer "In11.Cu")
		(net "M_H_CPU0_SA_DQ<14>")
	)
	(segment
		(start 425.49445 -306.87518)
		(end 425.160948 -306.541678)
		(width 0.18288)
		(layer "In11.Cu")
		(net "M_H_CPU0_SA_DQ<14>")
	)
	(segment
		(start 408.295856 -304.93843)
		(end 407.004012 -304.93843)
		(width 0.18288)
		(layer "In11.Cu")
		(net "M_H_CPU0_SA_DQ<14>")
	)
	(segment
		(start 403.834092 -302.415956)
		(end 403.834092 -299.793152)
		(width 0.18288)
		(layer "In11.Cu")
		(net "M_H_CPU0_SA_DQ<14>")
	)
	(segment
		(start 444.278004 -303.784762)
		(end 444.278004 -304.057558)
		(width 0.18288)
		(layer "In11.Cu")
		(net "M_H_CPU0_SA_DQ<14>")
	)
	(segment
		(start 440.654186 -306.542186)
		(end 439.71845 -306.542186)
		(width 0.18288)
		(layer "In11.Cu")
		(net "M_H_CPU0_SA_DQ<14>")
	)
	(segment
		(start 452.455026 -301.002954)
		(end 452.261986 -301.195994)
		(width 0.18288)
		(layer "In11.Cu")
		(net "M_H_CPU0_SA_DQ<14>")
	)
	(segment
		(start 441.556394 -305.207162)
		(end 441.556394 -305.639978)
		(width 0.18288)
		(layer "In11.Cu")
		(net "M_H_CPU0_SA_DQ<14>")
	)
	(segment
		(start 445.28105 -303.792636)
		(end 445.008254 -303.792636)
		(width 0.18288)
		(layer "In11.Cu")
		(net "M_H_CPU0_SA_DQ<14>")
	)
	(segment
		(start 449.331334 -300.014386)
		(end 447.76644 -301.57928)
		(width 0.18288)
		(layer "In11.Cu")
		(net "M_H_CPU0_SA_DQ<14>")
	)
	(segment
		(start 439.203084 -306.02682)
		(end 438.748678 -306.02682)
		(width 0.18288)
		(layer "In11.Cu")
		(net "M_H_CPU0_SA_DQ<14>")
	)
	(segment
		(start 384.690112 -278.336502)
		(end 384.690112 -278.31796)
		(width 0.088646)
		(layer "In11.Cu")
		(net "M_H_CPU0_SA_DQ<14>")
	)
	(segment
		(start 443.386972 -305.082194)
		(end 442.925962 -305.082194)
		(width 0.18288)
		(layer "In11.Cu")
		(net "M_H_CPU0_SA_DQ<14>")
	)
	(segment
		(start 389.076946 -283.302964)
		(end 388.229856 -282.455874)
		(width 0.18288)
		(layer "In11.Cu")
		(net "M_H_CPU0_SA_DQ<14>")
	)
	(segment
		(start 444.510668 -304.290222)
		(end 444.510668 -304.563018)
		(width 0.18288)
		(layer "In11.Cu")
		(net "M_H_CPU0_SA_DQ<14>")
	)
	(segment
		(start 376.808746 -277.024338)
		(end 376.794014 -277.032974)
		(width 0.088646)
		(layer "In11.Cu")
		(net "M_H_CPU0_SA_DQ<14>")
	)
	(segment
		(start 427.819566 -306.650898)
		(end 427.573694 -306.405026)
		(width 0.18288)
		(layer "In11.Cu")
		(net "M_H_CPU0_SA_DQ<14>")
	)
	(segment
		(start 423.250614 -306.61991)
		(end 422.300146 -306.61991)
		(width 0.18288)
		(layer "In11.Cu")
		(net "M_H_CPU0_SA_DQ<14>")
	)
	(segment
		(start 452.261986 -301.195994)
		(end 451.944486 -301.195994)
		(width 0.18288)
		(layer "In11.Cu")
		(net "M_H_CPU0_SA_DQ<14>")
	)
	(segment
		(start 384.407664 -277.84679)
		(end 384.39725 -277.840694)
		(width 0.088646)
		(layer "In11.Cu")
		(net "M_H_CPU0_SA_DQ<14>")
	)
	(segment
		(start 444.510668 -304.563018)
		(end 444.255906 -304.818034)
		(width 0.18288)
		(layer "In11.Cu")
		(net "M_H_CPU0_SA_DQ<14>")
	)
	(segment
		(start 409.361132 -304.84318)
		(end 409.034742 -304.51679)
		(width 0.18288)
		(layer "In11.Cu")
		(net "M_H_CPU0_SA_DQ<14>")
	)
	(segment
		(start 388.229856 -282.455874)
		(end 387.867906 -281.582622)
		(width 0.18288)
		(layer "In11.Cu")
		(net "M_H_CPU0_SA_DQ<14>")
	)
	(segment
		(start 376.419618 -277.032974)
		(end 376.410728 -277.027894)
		(width 0.088646)
		(layer "In11.Cu")
		(net "M_H_CPU0_SA_DQ<14>")
	)
	(segment
		(start 444.502794 -303.559972)
		(end 444.278004 -303.784762)
		(width 0.18288)
		(layer "In11.Cu")
		(net "M_H_CPU0_SA_DQ<14>")
	)
	(segment
		(start 387.13664 -280.851356)
		(end 387.13664 -280.455624)
		(width 0.088646)
		(layer "In11.Cu")
		(net "M_H_CPU0_SA_DQ<14>")
	)
	(segment
		(start 438.748678 -306.02682)
		(end 438.050686 -306.724812)
		(width 0.18288)
		(layer "In11.Cu")
		(net "M_H_CPU0_SA_DQ<14>")
	)
	(segment
		(start 452.455026 -300.816518)
		(end 452.455026 -301.002954)
		(width 0.18288)
		(layer "In11.Cu")
		(net "M_H_CPU0_SA_DQ<14>")
	)
	(segment
		(start 447.18224 -302.27778)
		(end 446.6717 -302.78832)
		(width 0.18288)
		(layer "In11.Cu")
		(net "M_H_CPU0_SA_DQ<14>")
	)
	(segment
		(start 454.017634 -301.449994)
		(end 453.824594 -301.643034)
		(width 0.18288)
		(layer "In11.Cu")
		(net "M_H_CPU0_SA_DQ<14>")
	)
	(segment
		(start 405.043894 -302.890174)
		(end 405.043894 -302.617378)
		(width 0.18288)
		(layer "In11.Cu")
		(net "M_H_CPU0_SA_DQ<14>")
	)
	(segment
		(start 441.556394 -305.639978)
		(end 440.654186 -306.542186)
		(width 0.18288)
		(layer "In11.Cu")
		(net "M_H_CPU0_SA_DQ<14>")
	)
	(segment
		(start 403.834092 -299.793152)
		(end 395.838426 -291.797486)
		(width 0.18288)
		(layer "In11.Cu")
		(net "M_H_CPU0_SA_DQ<14>")
	)
	(segment
		(start 441.98413 -304.779426)
		(end 441.556394 -305.207162)
		(width 0.18288)
		(layer "In11.Cu")
		(net "M_H_CPU0_SA_DQ<14>")
	)
	(segment
		(start 386.287264 -279.474676)
		(end 386.278374 -279.469596)
		(width 0.088646)
		(layer "In11.Cu")
		(net "M_H_CPU0_SA_DQ<14>")
	)
	(segment
		(start 444.77559 -303.559972)
		(end 444.502794 -303.559972)
		(width 0.18288)
		(layer "In11.Cu")
		(net "M_H_CPU0_SA_DQ<14>")
	)
	(segment
		(start 421.526208 -307.393848)
		(end 419.273482 -307.393848)
		(width 0.18288)
		(layer "In11.Cu")
		(net "M_H_CPU0_SA_DQ<14>")
	)
	(segment
		(start 381.588264 -277.84679)
		(end 381.573532 -277.838154)
		(width 0.088646)
		(layer "In11.Cu")
		(net "M_H_CPU0_SA_DQ<14>")
	)
	(segment
		(start 406.056084 -303.990502)
		(end 405.408638 -303.990502)
		(width 0.18288)
		(layer "In11.Cu")
		(net "M_H_CPU0_SA_DQ<14>")
	)
	(segment
		(start 423.687494 -306.18303)
		(end 423.250614 -306.61991)
		(width 0.18288)
		(layer "In11.Cu")
		(net "M_H_CPU0_SA_DQ<14>")
	)
	(segment
		(start 454.55332 -300.623478)
		(end 454.210674 -300.623478)
		(width 0.18288)
		(layer "In11.Cu")
		(net "M_H_CPU0_SA_DQ<14>")
	)
	(segment
		(start 442.623194 -304.779426)
		(end 441.98413 -304.779426)
		(width 0.18288)
		(layer "In11.Cu")
		(net "M_H_CPU0_SA_DQ<14>")
	)
	(segment
		(start 405.408638 -303.990502)
		(end 404.8125 -303.394364)
		(width 0.18288)
		(layer "In11.Cu")
		(net "M_H_CPU0_SA_DQ<14>")
	)
	(segment
		(start 412.737808 -305.008026)
		(end 412.557722 -304.82794)
		(width 0.18288)
		(layer "In11.Cu")
		(net "M_H_CPU0_SA_DQ<14>")
	)
	(segment
		(start 430.833022 -306.650898)
		(end 427.819566 -306.650898)
		(width 0.18288)
		(layer "In11.Cu")
		(net "M_H_CPU0_SA_DQ<14>")
	)
	(segment
		(start 373.974614 -273.777456)
		(end 373.898414 -273.822922)
		(width 0.088646)
		(layer "In11.Cu")
		(net "M_H_CPU0_SA_DQ<14>")
	)
	(segment
		(start 424.059858 -306.18303)
		(end 423.687494 -306.18303)
		(width 0.18288)
		(layer "In11.Cu")
		(net "M_H_CPU0_SA_DQ<14>")
	)
	(segment
		(start 416.07486 -305.008026)
		(end 412.737808 -305.008026)
		(width 0.18288)
		(layer "In11.Cu")
		(net "M_H_CPU0_SA_DQ<14>")
	)
	(segment
		(start 438.050686 -306.724812)
		(end 437.136286 -306.724812)
		(width 0.18288)
		(layer "In11.Cu")
		(net "M_H_CPU0_SA_DQ<14>")
	)
	(segment
		(start 426.406564 -306.87518)
		(end 425.49445 -306.87518)
		(width 0.18288)
		(layer "In11.Cu")
		(net "M_H_CPU0_SA_DQ<14>")
	)
	(segment
		(start 453.314054 -300.816518)
		(end 453.121014 -300.623478)
		(width 0.18288)
		(layer "In11.Cu")
		(net "M_H_CPU0_SA_DQ<14>")
	)
	(segment
		(start 404.8125 -303.394364)
		(end 404.8125 -303.121568)
		(width 0.18288)
		(layer "In11.Cu")
		(net "M_H_CPU0_SA_DQ<14>")
	)
	(segment
		(start 451.751446 -300.816518)
		(end 451.525386 -300.590458)
		(width 0.18288)
		(layer "In11.Cu")
		(net "M_H_CPU0_SA_DQ<14>")
	)
	(segment
		(start 425.160948 -306.541678)
		(end 424.418506 -306.541678)
		(width 0.18288)
		(layer "In11.Cu")
		(net "M_H_CPU0_SA_DQ<14>")
	)
	(segment
		(start 410.734764 -304.14087)
		(end 410.541724 -304.33391)
		(width 0.18288)
		(layer "In11.Cu")
		(net "M_H_CPU0_SA_DQ<14>")
	)
	(segment
		(start 450.001132 -300.014386)
		(end 449.331334 -300.014386)
		(width 0.18288)
		(layer "In11.Cu")
		(net "M_H_CPU0_SA_DQ<14>")
	)
	(segment
		(start 450.577204 -300.590458)
		(end 450.001132 -300.014386)
		(width 0.18288)
		(layer "In11.Cu")
		(net "M_H_CPU0_SA_DQ<14>")
	)
	(segment
		(start 454.210674 -300.623478)
		(end 454.017634 -300.816518)
		(width 0.18288)
		(layer "In11.Cu")
		(net "M_H_CPU0_SA_DQ<14>")
	)
	(segment
		(start 446.6717 -302.78832)
		(end 446.285112 -302.78832)
		(width 0.18288)
		(layer "In11.Cu")
		(net "M_H_CPU0_SA_DQ<14>")
	)
	(segment
		(start 435.297072 -305.692048)
		(end 435.117494 -305.871626)
		(width 0.18288)
		(layer "In11.Cu")
		(net "M_H_CPU0_SA_DQ<14>")
	)
	(arc
		(start 374.540018 -273.777456)
		(mid 374.257316 -273.70168)
		(end 373.974614 -273.777456)
		(width 0.088646)
		(layer "In11.Cu")
		(net "M_H_CPU0_SA_DQ<14>")
	)
	(arc
		(start 383.457196 -277.840694)
		(mid 383.179018 -277.771002)
		(end 382.90246 -277.84679)
		(width 0.088646)
		(layer "In11.Cu")
		(net "M_H_CPU0_SA_DQ<14>")
	)
	(arc
		(start 386.099812 -279.140412)
		(mid 386.021701 -278.863463)
		(end 385.817364 -278.66086)
		(width 0.088646)
		(layer "In11.Cu")
		(net "M_H_CPU0_SA_DQ<14>")
	)
	(arc
		(start 385.817364 -278.66086)
		(mid 385.534662 -278.585084)
		(end 385.25196 -278.66086)
		(width 0.088646)
		(layer "In11.Cu")
		(net "M_H_CPU0_SA_DQ<14>")
	)
	(arc
		(start 384.39725 -277.840694)
		(mid 384.118818 -277.77088)
		(end 383.842006 -277.84679)
		(width 0.088646)
		(layer "In11.Cu")
		(net "M_H_CPU0_SA_DQ<14>")
	)
	(arc
		(start 382.528064 -277.84679)
		(mid 382.245362 -277.771048)
		(end 381.96266 -277.84679)
		(width 0.088646)
		(layer "In11.Cu")
		(net "M_H_CPU0_SA_DQ<14>")
	)
	(arc
		(start 375.292366 -275.08073)
		(mid 375.220131 -274.804206)
		(end 375.021856 -274.598384)
		(width 0.088646)
		(layer "In11.Cu")
		(net "M_H_CPU0_SA_DQ<14>")
	)
	(arc
		(start 376.794014 -277.032974)
		(mid 376.606816 -277.083117)
		(end 376.419618 -277.032974)
		(width 0.088646)
		(layer "In11.Cu")
		(net "M_H_CPU0_SA_DQ<14>")
	)
	(arc
		(start 375.009664 -274.591272)
		(mid 374.874731 -274.457918)
		(end 374.822466 -274.27555)
		(width 0.088646)
		(layer "In11.Cu")
		(net "M_H_CPU0_SA_DQ<14>")
	)
	(arc
		(start 381.573532 -277.838154)
		(mid 381.297091 -277.770988)
		(end 381.02286 -277.84679)
		(width 0.088646)
		(layer "In11.Cu")
		(net "M_H_CPU0_SA_DQ<14>")
	)
	(arc
		(start 376.232166 -276.708616)
		(mid 376.158175 -276.42905)
		(end 375.95556 -276.222714)
		(width 0.088646)
		(layer "In11.Cu")
		(net "M_H_CPU0_SA_DQ<14>")
	)
	(arc
		(start 381.96266 -277.84679)
		(mid 381.775462 -277.896933)
		(end 381.588264 -277.84679)
		(width 0.088646)
		(layer "In11.Cu")
		(net "M_H_CPU0_SA_DQ<14>")
	)
	(arc
		(start 380.633732 -277.838154)
		(mid 380.357291 -277.770988)
		(end 380.08306 -277.84679)
		(width 0.088646)
		(layer "In11.Cu")
		(net "M_H_CPU0_SA_DQ<14>")
	)
	(arc
		(start 386.278374 -279.469596)
		(mid 386.14746 -279.333236)
		(end 386.099812 -279.150318)
		(width 0.088646)
		(layer "In11.Cu")
		(net "M_H_CPU0_SA_DQ<14>")
	)
	(arc
		(start 383.842006 -277.84679)
		(mid 383.654808 -277.896933)
		(end 383.46761 -277.84679)
		(width 0.088646)
		(layer "In11.Cu")
		(net "M_H_CPU0_SA_DQ<14>")
	)
	(arc
		(start 376.410728 -277.027894)
		(mid 376.279814 -276.891534)
		(end 376.232166 -276.708616)
		(width 0.088646)
		(layer "In11.Cu")
		(net "M_H_CPU0_SA_DQ<14>")
	)
	(arc
		(start 380.08306 -277.84679)
		(mid 379.895862 -277.896933)
		(end 379.708664 -277.84679)
		(width 0.088646)
		(layer "In11.Cu")
		(net "M_H_CPU0_SA_DQ<14>")
	)
	(arc
		(start 384.868674 -278.65578)
		(mid 384.73776 -278.51942)
		(end 384.690112 -278.336502)
		(width 0.088646)
		(layer "In11.Cu")
		(net "M_H_CPU0_SA_DQ<14>")
	)
	(arc
		(start 385.25196 -278.66086)
		(mid 385.064762 -278.711003)
		(end 384.877564 -278.66086)
		(width 0.088646)
		(layer "In11.Cu")
		(net "M_H_CPU0_SA_DQ<14>")
	)
	(arc
		(start 375.470928 -275.400008)
		(mid 375.340014 -275.263648)
		(end 375.292366 -275.08073)
		(width 0.088646)
		(layer "In11.Cu")
		(net "M_H_CPU0_SA_DQ<14>")
	)
	(arc
		(start 379.69825 -277.840694)
		(mid 379.420072 -277.771002)
		(end 379.143514 -277.84679)
		(width 0.088646)
		(layer "In11.Cu")
		(net "M_H_CPU0_SA_DQ<14>")
	)
	(arc
		(start 377.820428 -277.84171)
		(mid 377.689514 -277.70535)
		(end 377.641866 -277.522432)
		(width 0.088646)
		(layer "In11.Cu")
		(net "M_H_CPU0_SA_DQ<14>")
	)
	(arc
		(start 375.940574 -276.214078)
		(mid 375.80966 -276.077718)
		(end 375.762012 -275.8948)
		(width 0.088646)
		(layer "In11.Cu")
		(net "M_H_CPU0_SA_DQ<14>")
	)
	(arc
		(start 375.762012 -275.872702)
		(mid 375.681101 -275.602574)
		(end 375.479818 -275.405088)
		(width 0.088646)
		(layer "In11.Cu")
		(net "M_H_CPU0_SA_DQ<14>")
	)
	(arc
		(start 374.822466 -274.257008)
		(mid 374.744355 -273.980059)
		(end 374.540018 -273.777456)
		(width 0.088646)
		(layer "In11.Cu")
		(net "M_H_CPU0_SA_DQ<14>")
	)
	(arc
		(start 377.641866 -277.522432)
		(mid 377.56795 -277.24293)
		(end 377.365514 -277.03653)
		(width 0.088646)
		(layer "In11.Cu")
		(net "M_H_CPU0_SA_DQ<14>")
	)
	(arc
		(start 378.769118 -277.84679)
		(mid 378.494889 -277.770865)
		(end 378.218446 -277.838154)
		(width 0.088646)
		(layer "In11.Cu")
		(net "M_H_CPU0_SA_DQ<14>")
	)
	(arc
		(start 381.02286 -277.84679)
		(mid 380.835662 -277.896933)
		(end 380.648464 -277.84679)
		(width 0.088646)
		(layer "In11.Cu")
		(net "M_H_CPU0_SA_DQ<14>")
	)
	(arc
		(start 377.359418 -277.032974)
		(mid 377.085219 -276.957139)
		(end 376.808746 -277.024338)
		(width 0.088646)
		(layer "In11.Cu")
		(net "M_H_CPU0_SA_DQ<14>")
	)
	(arc
		(start 382.90246 -277.84679)
		(mid 382.715262 -277.896933)
		(end 382.528064 -277.84679)
		(width 0.088646)
		(layer "In11.Cu")
		(net "M_H_CPU0_SA_DQ<14>")
	)
	(arc
		(start 379.143514 -277.84679)
		(mid 378.956316 -277.896933)
		(end 378.769118 -277.84679)
		(width 0.088646)
		(layer "In11.Cu")
		(net "M_H_CPU0_SA_DQ<14>")
	)
	(arc
		(start 384.690112 -278.31796)
		(mid 384.60995 -278.045771)
		(end 384.407664 -277.84679)
		(width 0.088646)
		(layer "In11.Cu")
		(net "M_H_CPU0_SA_DQ<14>")
	)
	(arc
		(start 386.404358 -279.564338)
		(mid 386.393323 -279.553647)
		(end 386.382006 -279.543256)
		(width 0.088646)
		(layer "In11.Cu")
		(net "M_H_CPU0_SA_DQ<14>")
	)
	(arc
		(start 386.382006 -279.543256)
		(mid 386.336411 -279.506512)
		(end 386.287264 -279.474676)
		(width 0.088646)
		(layer "In11.Cu")
		(net "M_H_CPU0_SA_DQ<14>")
	)
	(arc
		(start 378.203714 -277.84679)
		(mid 378.016516 -277.896933)
		(end 377.829318 -277.84679)
		(width 0.088646)
		(layer "In11.Cu")
		(net "M_H_CPU0_SA_DQ<14>")
	)
	(segment
		(start 454.448672 -299.009816)
		(end 454.448672 -299.377354)
		(width 0.20066)
		(layer "F.Cu")
		(net "M_H_CPU0_SA_DQ<13>")
	)
	(segment
		(start 457.126594 -298.885356)
		(end 457.120244 -298.891706)
		(width 0.1016)
		(layer "F.Cu")
		(net "M_H_CPU0_SA_DQ<13>")
	)
	(segment
		(start 454.260712 -299.565314)
		(end 453.785478 -299.565314)
		(width 0.20066)
		(layer "F.Cu")
		(net "M_H_CPU0_SA_DQ<13>")
	)
	(segment
		(start 457.53655 -298.885356)
		(end 457.126594 -298.885356)
		(width 0.20066)
		(layer "F.Cu")
		(net "M_H_CPU0_SA_DQ<13>")
	)
	(segment
		(start 454.91146 -298.891706)
		(end 454.566782 -298.891706)
		(width 0.20066)
		(layer "F.Cu")
		(net "M_H_CPU0_SA_DQ<13>")
	)
	(segment
		(start 454.566782 -298.891706)
		(end 454.448672 -299.009816)
		(width 0.20066)
		(layer "F.Cu")
		(net "M_H_CPU0_SA_DQ<13>")
	)
	(segment
		(start 454.448672 -299.377354)
		(end 454.260712 -299.565314)
		(width 0.20066)
		(layer "F.Cu")
		(net "M_H_CPU0_SA_DQ<13>")
	)
	(segment
		(start 457.968096 -299.316902)
		(end 457.53655 -298.885356)
		(width 0.20066)
		(layer "F.Cu")
		(net "M_H_CPU0_SA_DQ<13>")
	)
	(segment
		(start 453.785478 -299.565314)
		(end 453.536812 -299.316648)
		(width 0.20066)
		(layer "F.Cu")
		(net "M_H_CPU0_SA_DQ<13>")
	)
	(segment
		(start 457.120244 -298.891706)
		(end 454.931526 -298.891706)
		(width 0.1016)
		(layer "F.Cu")
		(net "M_H_CPU0_SA_DQ<13>")
	)
	(segment
		(start 459.559914 -299.316648)
		(end 459.55966 -299.316902)
		(width 0.20066)
		(layer "F.Cu")
		(net "M_H_CPU0_SA_DQ<13>")
	)
	(segment
		(start 459.55966 -299.316902)
		(end 457.968096 -299.316902)
		(width 0.20066)
		(layer "F.Cu")
		(net "M_H_CPU0_SA_DQ<13>")
	)
	(segment
		(start 371.907562 -273.452844)
		(end 371.907816 -273.453098)
		(width 0.20066)
		(layer "F.Cu")
		(net "M_H_CPU0_SA_DQ<13>")
	)
	(segment
		(start 452.016114 -299.316648)
		(end 450.911214 -299.316648)
		(width 0.20066)
		(layer "F.Cu")
		(net "M_H_CPU0_SA_DQ<13>")
	)
	(segment
		(start 453.536812 -299.316648)
		(end 452.016114 -299.316648)
		(width 0.20066)
		(layer "F.Cu")
		(net "M_H_CPU0_SA_DQ<13>")
	)
	(segment
		(start 454.931526 -298.891706)
		(end 454.91146 -298.891706)
		(width 0.101854)
		(layer "F.Cu")
		(net "M_H_CPU0_SA_DQ<13>")
	)
	(segment
		(start 371.907562 -272.917158)
		(end 371.907562 -273.452844)
		(width 0.20066)
		(layer "F.Cu")
		(net "M_H_CPU0_SA_DQ<13>")
	)
	(segment
		(start 444.721742 -302.384206)
		(end 443.628272 -303.477676)
		(width 0.18288)
		(layer "In11.Cu")
		(net "M_H_CPU0_SA_DQ<13>")
	)
	(segment
		(start 408.290522 -302.618648)
		(end 407.957782 -302.285146)
		(width 0.18288)
		(layer "In11.Cu")
		(net "M_H_CPU0_SA_DQ<13>")
	)
	(segment
		(start 420.312596 -306.541678)
		(end 420.175944 -306.405026)
		(width 0.18288)
		(layer "In11.Cu")
		(net "M_H_CPU0_SA_DQ<13>")
	)
	(segment
		(start 431.205894 -305.465226)
		(end 429.923702 -305.465226)
		(width 0.18288)
		(layer "In11.Cu")
		(net "M_H_CPU0_SA_DQ<13>")
	)
	(segment
		(start 408.12085 -303.991772)
		(end 407.923238 -303.79416)
		(width 0.18288)
		(layer "In11.Cu")
		(net "M_H_CPU0_SA_DQ<13>")
	)
	(segment
		(start 436.793894 -305.648106)
		(end 436.793894 -305.025806)
		(width 0.18288)
		(layer "In11.Cu")
		(net "M_H_CPU0_SA_DQ<13>")
	)
	(segment
		(start 414.03397 -303.915064)
		(end 413.84093 -303.722024)
		(width 0.18288)
		(layer "In11.Cu")
		(net "M_H_CPU0_SA_DQ<13>")
	)
	(segment
		(start 387.632702 -280.788872)
		(end 387.401562 -280.557732)
		(width 0.088646)
		(layer "In11.Cu")
		(net "M_H_CPU0_SA_DQ<13>")
	)
	(segment
		(start 447.895218 -300.461426)
		(end 447.322194 -300.461426)
		(width 0.18288)
		(layer "In11.Cu")
		(net "M_H_CPU0_SA_DQ<13>")
	)
	(segment
		(start 410.044392 -303.991772)
		(end 408.12085 -303.991772)
		(width 0.18288)
		(layer "In11.Cu")
		(net "M_H_CPU0_SA_DQ<13>")
	)
	(segment
		(start 425.618148 -306.165504)
		(end 425.144438 -305.691794)
		(width 0.18288)
		(layer "In11.Cu")
		(net "M_H_CPU0_SA_DQ<13>")
	)
	(segment
		(start 414.93059 -303.722024)
		(end 414.73755 -303.915064)
		(width 0.18288)
		(layer "In11.Cu")
		(net "M_H_CPU0_SA_DQ<13>")
	)
	(segment
		(start 406.706324 -303.869852)
		(end 406.513284 -303.676812)
		(width 0.18288)
		(layer "In11.Cu")
		(net "M_H_CPU0_SA_DQ<13>")
	)
	(segment
		(start 447.322194 -300.461426)
		(end 446.821814 -300.961806)
		(width 0.18288)
		(layer "In11.Cu")
		(net "M_H_CPU0_SA_DQ<13>")
	)
	(segment
		(start 449.469764 -298.88688)
		(end 447.895218 -300.461426)
		(width 0.18288)
		(layer "In11.Cu")
		(net "M_H_CPU0_SA_DQ<13>")
	)
	(segment
		(start 436.953914 -305.808126)
		(end 436.793894 -305.648106)
		(width 0.18288)
		(layer "In11.Cu")
		(net "M_H_CPU0_SA_DQ<13>")
	)
	(segment
		(start 406.513284 -303.676812)
		(end 406.513284 -302.483266)
		(width 0.18288)
		(layer "In11.Cu")
		(net "M_H_CPU0_SA_DQ<13>")
	)
	(segment
		(start 404.454868 -299.695108)
		(end 396.367762 -291.608002)
		(width 0.18288)
		(layer "In11.Cu")
		(net "M_H_CPU0_SA_DQ<13>")
	)
	(segment
		(start 442.985144 -303.477676)
		(end 442.419994 -304.042826)
		(width 0.18288)
		(layer "In11.Cu")
		(net "M_H_CPU0_SA_DQ<13>")
	)
	(segment
		(start 450.85127 -299.617892)
		(end 450.754496 -299.714666)
		(width 0.18288)
		(layer "In11.Cu")
		(net "M_H_CPU0_SA_DQ<13>")
	)
	(segment
		(start 376.33275 -275.575522)
		(end 376.32386 -275.570442)
		(width 0.088646)
		(layer "In11.Cu")
		(net "M_H_CPU0_SA_DQ<13>")
	)
	(segment
		(start 432.992022 -304.542698)
		(end 432.128422 -304.542698)
		(width 0.18288)
		(layer "In11.Cu")
		(net "M_H_CPU0_SA_DQ<13>")
	)
	(segment
		(start 450.131434 -299.364654)
		(end 450.131434 -299.167296)
		(width 0.18288)
		(layer "In11.Cu")
		(net "M_H_CPU0_SA_DQ<13>")
	)
	(segment
		(start 429.220122 -306.132992)
		(end 429.027082 -305.939952)
		(width 0.18288)
		(layer "In11.Cu")
		(net "M_H_CPU0_SA_DQ<13>")
	)
	(segment
		(start 373.989346 -273.137376)
		(end 373.974614 -273.12874)
		(width 0.088646)
		(layer "In11.Cu")
		(net "M_H_CPU0_SA_DQ<13>")
	)
	(segment
		(start 417.036758 -304.672238)
		(end 416.086544 -303.722024)
		(width 0.18288)
		(layer "In11.Cu")
		(net "M_H_CPU0_SA_DQ<13>")
	)
	(segment
		(start 396.367762 -291.608002)
		(end 396.367762 -289.861752)
		(width 0.18288)
		(layer "In11.Cu")
		(net "M_H_CPU0_SA_DQ<13>")
	)
	(segment
		(start 429.730662 -305.939952)
		(end 429.537622 -306.132992)
		(width 0.18288)
		(layer "In11.Cu")
		(net "M_H_CPU0_SA_DQ<13>")
	)
	(segment
		(start 408.290522 -302.909224)
		(end 408.290522 -302.618648)
		(width 0.18288)
		(layer "In11.Cu")
		(net "M_H_CPU0_SA_DQ<13>")
	)
	(segment
		(start 384.79095 -277.203154)
		(end 384.78206 -277.198074)
		(width 0.088646)
		(layer "In11.Cu")
		(net "M_H_CPU0_SA_DQ<13>")
	)
	(segment
		(start 433.888642 -304.735738)
		(end 433.888642 -305.169824)
		(width 0.18288)
		(layer "In11.Cu")
		(net "M_H_CPU0_SA_DQ<13>")
	)
	(segment
		(start 450.911214 -299.316648)
		(end 450.911214 -299.473112)
		(width 0.18288)
		(layer "In11.Cu")
		(net "M_H_CPU0_SA_DQ<13>")
	)
	(segment
		(start 377.742704 -276.389338)
		(end 377.733814 -276.384258)
		(width 0.088646)
		(layer "In11.Cu")
		(net "M_H_CPU0_SA_DQ<13>")
	)
	(segment
		(start 439.458354 -305.51755)
		(end 437.81345 -305.51755)
		(width 0.18288)
		(layer "In11.Cu")
		(net "M_H_CPU0_SA_DQ<13>")
	)
	(segment
		(start 414.54451 -304.49774)
		(end 414.22701 -304.49774)
		(width 0.18288)
		(layer "In11.Cu")
		(net "M_H_CPU0_SA_DQ<13>")
	)
	(segment
		(start 425.144438 -305.691794)
		(end 424.57497 -305.691794)
		(width 0.18288)
		(layer "In11.Cu")
		(net "M_H_CPU0_SA_DQ<13>")
	)
	(segment
		(start 383.467864 -277.198074)
		(end 383.453132 -277.20671)
		(width 0.088646)
		(layer "In11.Cu")
		(net "M_H_CPU0_SA_DQ<13>")
	)
	(segment
		(start 426.22978 -306.165504)
		(end 425.618148 -306.165504)
		(width 0.18288)
		(layer "In11.Cu")
		(net "M_H_CPU0_SA_DQ<13>")
	)
	(segment
		(start 429.923702 -305.465226)
		(end 429.730662 -305.658266)
		(width 0.18288)
		(layer "In11.Cu")
		(net "M_H_CPU0_SA_DQ<13>")
	)
	(segment
		(start 414.73755 -304.3047)
		(end 414.54451 -304.49774)
		(width 0.18288)
		(layer "In11.Cu")
		(net "M_H_CPU0_SA_DQ<13>")
	)
	(segment
		(start 432.128422 -304.542698)
		(end 431.205894 -305.465226)
		(width 0.18288)
		(layer "In11.Cu")
		(net "M_H_CPU0_SA_DQ<13>")
	)
	(segment
		(start 429.730662 -305.658266)
		(end 429.730662 -305.939952)
		(width 0.18288)
		(layer "In11.Cu")
		(net "M_H_CPU0_SA_DQ<13>")
	)
	(segment
		(start 383.476246 -277.193248)
		(end 383.467864 -277.198074)
		(width 0.088646)
		(layer "In11.Cu")
		(net "M_H_CPU0_SA_DQ<13>")
	)
	(segment
		(start 443.628272 -303.477676)
		(end 442.985144 -303.477676)
		(width 0.18288)
		(layer "In11.Cu")
		(net "M_H_CPU0_SA_DQ<13>")
	)
	(segment
		(start 381.588264 -277.198074)
		(end 381.573532 -277.20671)
		(width 0.088646)
		(layer "In11.Cu")
		(net "M_H_CPU0_SA_DQ<13>")
	)
	(segment
		(start 433.185062 -305.169824)
		(end 433.185062 -304.735738)
		(width 0.18288)
		(layer "In11.Cu")
		(net "M_H_CPU0_SA_DQ<13>")
	)
	(segment
		(start 411.840934 -304.209958)
		(end 411.206442 -303.575466)
		(width 0.18288)
		(layer "In11.Cu")
		(net "M_H_CPU0_SA_DQ<13>")
	)
	(segment
		(start 377.921266 -276.718522)
		(end 377.921266 -276.708616)
		(width 0.088646)
		(layer "In11.Cu")
		(net "M_H_CPU0_SA_DQ<13>")
	)
	(segment
		(start 450.911214 -299.473112)
		(end 450.85127 -299.617892)
		(width 0.18288)
		(layer "In11.Cu")
		(net "M_H_CPU0_SA_DQ<13>")
	)
	(segment
		(start 419.090094 -306.405026)
		(end 417.357306 -304.672238)
		(width 0.18288)
		(layer "In11.Cu")
		(net "M_H_CPU0_SA_DQ<13>")
	)
	(segment
		(start 376.794014 -276.384258)
		(end 376.781822 -276.377146)
		(width 0.088646)
		(layer "In11.Cu")
		(net "M_H_CPU0_SA_DQ<13>")
	)
	(segment
		(start 436.610506 -304.842418)
		(end 435.400958 -304.842418)
		(width 0.18288)
		(layer "In11.Cu")
		(net "M_H_CPU0_SA_DQ<13>")
	)
	(segment
		(start 407.923238 -303.276508)
		(end 408.290522 -302.909224)
		(width 0.18288)
		(layer "In11.Cu")
		(net "M_H_CPU0_SA_DQ<13>")
	)
	(segment
		(start 421.527986 -306.541678)
		(end 420.312596 -306.541678)
		(width 0.18288)
		(layer "In11.Cu")
		(net "M_H_CPU0_SA_DQ<13>")
	)
	(segment
		(start 428.081694 -305.465226)
		(end 427.825154 -305.721766)
		(width 0.18288)
		(layer "In11.Cu")
		(net "M_H_CPU0_SA_DQ<13>")
	)
	(segment
		(start 437.522874 -305.808126)
		(end 436.953914 -305.808126)
		(width 0.18288)
		(layer "In11.Cu")
		(net "M_H_CPU0_SA_DQ<13>")
	)
	(segment
		(start 429.027082 -305.939952)
		(end 429.027082 -305.658266)
		(width 0.18288)
		(layer "In11.Cu")
		(net "M_H_CPU0_SA_DQ<13>")
	)
	(segment
		(start 375.39295 -273.947636)
		(end 375.38406 -273.942556)
		(width 0.088646)
		(layer "In11.Cu")
		(net "M_H_CPU0_SA_DQ<13>")
	)
	(segment
		(start 436.793894 -305.025806)
		(end 436.610506 -304.842418)
		(width 0.18288)
		(layer "In11.Cu")
		(net "M_H_CPU0_SA_DQ<13>")
	)
	(segment
		(start 382.528064 -277.198074)
		(end 382.513332 -277.20671)
		(width 0.088646)
		(layer "In11.Cu")
		(net "M_H_CPU0_SA_DQ<13>")
	)
	(segment
		(start 404.454868 -301.286164)
		(end 404.454868 -299.695108)
		(width 0.18288)
		(layer "In11.Cu")
		(net "M_H_CPU0_SA_DQ<13>")
	)
	(segment
		(start 414.73755 -303.915064)
		(end 414.73755 -304.3047)
		(width 0.18288)
		(layer "In11.Cu")
		(net "M_H_CPU0_SA_DQ<13>")
	)
	(segment
		(start 449.756276 -298.88688)
		(end 449.469764 -298.88688)
		(width 0.18288)
		(layer "In11.Cu")
		(net "M_H_CPU0_SA_DQ<13>")
	)
	(segment
		(start 407.023824 -303.869852)
		(end 406.706324 -303.869852)
		(width 0.18288)
		(layer "In11.Cu")
		(net "M_H_CPU0_SA_DQ<13>")
	)
	(segment
		(start 433.888642 -305.169824)
		(end 433.695602 -305.362864)
		(width 0.18288)
		(layer "In11.Cu")
		(net "M_H_CPU0_SA_DQ<13>")
	)
	(segment
		(start 411.206442 -303.575466)
		(end 410.460698 -303.575466)
		(width 0.18288)
		(layer "In11.Cu")
		(net "M_H_CPU0_SA_DQ<13>")
	)
	(segment
		(start 386.448046 -278.758142)
		(end 386.379212 -278.689308)
		(width 0.088646)
		(layer "In11.Cu")
		(net "M_H_CPU0_SA_DQ<13>")
	)
	(segment
		(start 375.854214 -274.756372)
		(end 375.85142 -274.754848)
		(width 0.088646)
		(layer "In11.Cu")
		(net "M_H_CPU0_SA_DQ<13>")
	)
	(segment
		(start 413.84093 -303.722024)
		(end 412.959296 -303.722024)
		(width 0.18288)
		(layer "In11.Cu")
		(net "M_H_CPU0_SA_DQ<13>")
	)
	(segment
		(start 412.959296 -303.722024)
		(end 412.471362 -304.209958)
		(width 0.18288)
		(layer "In11.Cu")
		(net "M_H_CPU0_SA_DQ<13>")
	)
	(segment
		(start 435.400958 -304.842418)
		(end 435.101238 -304.542698)
		(width 0.18288)
		(layer "In11.Cu")
		(net "M_H_CPU0_SA_DQ<13>")
	)
	(segment
		(start 435.101238 -304.542698)
		(end 434.081682 -304.542698)
		(width 0.18288)
		(layer "In11.Cu")
		(net "M_H_CPU0_SA_DQ<13>")
	)
	(segment
		(start 407.957782 -302.285146)
		(end 407.409904 -302.285146)
		(width 0.18288)
		(layer "In11.Cu")
		(net "M_H_CPU0_SA_DQ<13>")
	)
	(segment
		(start 450.131434 -299.167296)
		(end 449.918074 -298.953936)
		(width 0.18288)
		(layer "In11.Cu")
		(net "M_H_CPU0_SA_DQ<13>")
	)
	(segment
		(start 424.57497 -305.691794)
		(end 424.428666 -305.54549)
		(width 0.18288)
		(layer "In11.Cu")
		(net "M_H_CPU0_SA_DQ<13>")
	)
	(segment
		(start 446.821814 -300.961806)
		(end 446.821814 -301.317406)
		(width 0.18288)
		(layer "In11.Cu")
		(net "M_H_CPU0_SA_DQ<13>")
	)
	(segment
		(start 412.471362 -304.209958)
		(end 411.840934 -304.209958)
		(width 0.18288)
		(layer "In11.Cu")
		(net "M_H_CPU0_SA_DQ<13>")
	)
	(segment
		(start 387.401562 -280.170382)
		(end 386.448046 -279.216866)
		(width 0.088646)
		(layer "In11.Cu")
		(net "M_H_CPU0_SA_DQ<13>")
	)
	(segment
		(start 375.863104 -274.761452)
		(end 375.854214 -274.756372)
		(width 0.088646)
		(layer "In11.Cu")
		(net "M_H_CPU0_SA_DQ<13>")
	)
	(segment
		(start 371.919754 -273.44116)
		(end 371.907816 -273.453098)
		(width 0.088646)
		(layer "In11.Cu")
		(net "M_H_CPU0_SA_DQ<13>")
	)
	(segment
		(start 433.185062 -304.735738)
		(end 432.992022 -304.542698)
		(width 0.18288)
		(layer "In11.Cu")
		(net "M_H_CPU0_SA_DQ<13>")
	)
	(segment
		(start 384.969512 -277.540974)
		(end 384.969512 -277.522432)
		(width 0.088646)
		(layer "In11.Cu")
		(net "M_H_CPU0_SA_DQ<13>")
	)
	(segment
		(start 374.923304 -273.13382)
		(end 374.914668 -273.12874)
		(width 0.088646)
		(layer "In11.Cu")
		(net "M_H_CPU0_SA_DQ<13>")
	)
	(segment
		(start 388.481824 -281.975814)
		(end 388.24281 -281.39898)
		(width 0.18288)
		(layer "In11.Cu")
		(net "M_H_CPU0_SA_DQ<13>")
	)
	(segment
		(start 376.041666 -275.102828)
		(end 376.041666 -275.08073)
		(width 0.088646)
		(layer "In11.Cu")
		(net "M_H_CPU0_SA_DQ<13>")
	)
	(segment
		(start 417.357306 -304.672238)
		(end 417.036758 -304.672238)
		(width 0.18288)
		(layer "In11.Cu")
		(net "M_H_CPU0_SA_DQ<13>")
	)
	(segment
		(start 384.407664 -277.198074)
		(end 384.39725 -277.20417)
		(width 0.088646)
		(layer "In11.Cu")
		(net "M_H_CPU0_SA_DQ<13>")
	)
	(segment
		(start 441.94857 -304.042826)
		(end 440.299602 -305.691794)
		(width 0.18288)
		(layer "In11.Cu")
		(net "M_H_CPU0_SA_DQ<13>")
	)
	(segment
		(start 429.537622 -306.132992)
		(end 429.220122 -306.132992)
		(width 0.18288)
		(layer "In11.Cu")
		(net "M_H_CPU0_SA_DQ<13>")
	)
	(segment
		(start 440.299602 -305.691794)
		(end 439.632598 -305.691794)
		(width 0.18288)
		(layer "In11.Cu")
		(net "M_H_CPU0_SA_DQ<13>")
	)
	(segment
		(start 426.673518 -305.721766)
		(end 426.22978 -306.165504)
		(width 0.18288)
		(layer "In11.Cu")
		(net "M_H_CPU0_SA_DQ<13>")
	)
	(segment
		(start 414.22701 -304.49774)
		(end 414.03397 -304.3047)
		(width 0.18288)
		(layer "In11.Cu")
		(net "M_H_CPU0_SA_DQ<13>")
	)
	(segment
		(start 373.130064 -273.942556)
		(end 373.122444 -273.946874)
		(width 0.088646)
		(layer "In11.Cu")
		(net "M_H_CPU0_SA_DQ<13>")
	)
	(segment
		(start 379.708664 -277.198074)
		(end 379.69825 -277.20417)
		(width 0.088646)
		(layer "In11.Cu")
		(net "M_H_CPU0_SA_DQ<13>")
	)
	(segment
		(start 375.101866 -273.468592)
		(end 375.101866 -273.453098)
		(width 0.088646)
		(layer "In11.Cu")
		(net "M_H_CPU0_SA_DQ<13>")
	)
	(segment
		(start 427.825154 -305.721766)
		(end 426.673518 -305.721766)
		(width 0.18288)
		(layer "In11.Cu")
		(net "M_H_CPU0_SA_DQ<13>")
	)
	(segment
		(start 407.409904 -302.285146)
		(end 407.216864 -302.478186)
		(width 0.18288)
		(layer "In11.Cu")
		(net "M_H_CPU0_SA_DQ<13>")
	)
	(segment
		(start 420.175944 -306.405026)
		(end 419.090094 -306.405026)
		(width 0.18288)
		(layer "In11.Cu")
		(net "M_H_CPU0_SA_DQ<13>")
	)
	(segment
		(start 386.448046 -279.216866)
		(end 386.448046 -278.758142)
		(width 0.088646)
		(layer "In11.Cu")
		(net "M_H_CPU0_SA_DQ<13>")
	)
	(segment
		(start 424.428666 -305.54549)
		(end 422.524174 -305.54549)
		(width 0.18288)
		(layer "In11.Cu")
		(net "M_H_CPU0_SA_DQ<13>")
	)
	(segment
		(start 422.524174 -305.54549)
		(end 421.527986 -306.541678)
		(width 0.18288)
		(layer "In11.Cu")
		(net "M_H_CPU0_SA_DQ<13>")
	)
	(segment
		(start 449.918074 -298.953936)
		(end 449.756276 -298.88688)
		(width 0.18288)
		(layer "In11.Cu")
		(net "M_H_CPU0_SA_DQ<13>")
	)
	(segment
		(start 434.081682 -304.542698)
		(end 433.888642 -304.735738)
		(width 0.18288)
		(layer "In11.Cu")
		(net "M_H_CPU0_SA_DQ<13>")
	)
	(segment
		(start 373.600218 -273.12874)
		(end 373.59971 -273.128994)
		(width 0.088646)
		(layer "In11.Cu")
		(net "M_H_CPU0_SA_DQ<13>")
	)
	(segment
		(start 407.923238 -303.79416)
		(end 407.923238 -303.276508)
		(width 0.18288)
		(layer "In11.Cu")
		(net "M_H_CPU0_SA_DQ<13>")
	)
	(segment
		(start 387.401562 -280.557732)
		(end 387.401562 -280.170382)
		(width 0.088646)
		(layer "In11.Cu")
		(net "M_H_CPU0_SA_DQ<13>")
	)
	(segment
		(start 450.754496 -299.714666)
		(end 450.481446 -299.714666)
		(width 0.18288)
		(layer "In11.Cu")
		(net "M_H_CPU0_SA_DQ<13>")
	)
	(segment
		(start 428.834042 -305.465226)
		(end 428.081694 -305.465226)
		(width 0.18288)
		(layer "In11.Cu")
		(net "M_H_CPU0_SA_DQ<13>")
	)
	(segment
		(start 396.367762 -289.861752)
		(end 388.481824 -281.975814)
		(width 0.18288)
		(layer "In11.Cu")
		(net "M_H_CPU0_SA_DQ<13>")
	)
	(segment
		(start 446.821814 -301.317406)
		(end 445.755014 -302.384206)
		(width 0.18288)
		(layer "In11.Cu")
		(net "M_H_CPU0_SA_DQ<13>")
	)
	(segment
		(start 386.20065 -278.017224)
		(end 386.19176 -278.012144)
		(width 0.088646)
		(layer "In11.Cu")
		(net "M_H_CPU0_SA_DQ<13>")
	)
	(segment
		(start 406.513284 -302.483266)
		(end 406.320244 -302.290226)
		(width 0.18288)
		(layer "In11.Cu")
		(net "M_H_CPU0_SA_DQ<13>")
	)
	(segment
		(start 414.03397 -304.3047)
		(end 414.03397 -303.915064)
		(width 0.18288)
		(layer "In11.Cu")
		(net "M_H_CPU0_SA_DQ<13>")
	)
	(segment
		(start 433.378102 -305.362864)
		(end 433.185062 -305.169824)
		(width 0.18288)
		(layer "In11.Cu")
		(net "M_H_CPU0_SA_DQ<13>")
	)
	(segment
		(start 407.216864 -303.676812)
		(end 407.023824 -303.869852)
		(width 0.18288)
		(layer "In11.Cu")
		(net "M_H_CPU0_SA_DQ<13>")
	)
	(segment
		(start 386.379212 -278.689308)
		(end 386.379212 -278.336502)
		(width 0.088646)
		(layer "In11.Cu")
		(net "M_H_CPU0_SA_DQ<13>")
	)
	(segment
		(start 450.481446 -299.714666)
		(end 450.131434 -299.364654)
		(width 0.18288)
		(layer "In11.Cu")
		(net "M_H_CPU0_SA_DQ<13>")
	)
	(segment
		(start 407.216864 -302.478186)
		(end 407.216864 -303.676812)
		(width 0.18288)
		(layer "In11.Cu")
		(net "M_H_CPU0_SA_DQ<13>")
	)
	(segment
		(start 433.695602 -305.362864)
		(end 433.378102 -305.362864)
		(width 0.18288)
		(layer "In11.Cu")
		(net "M_H_CPU0_SA_DQ<13>")
	)
	(segment
		(start 445.755014 -302.384206)
		(end 444.721742 -302.384206)
		(width 0.18288)
		(layer "In11.Cu")
		(net "M_H_CPU0_SA_DQ<13>")
	)
	(segment
		(start 375.85142 -274.754848)
		(end 375.848118 -274.752816)
		(width 0.088646)
		(layer "In11.Cu")
		(net "M_H_CPU0_SA_DQ<13>")
	)
	(segment
		(start 405.45893 -302.290226)
		(end 404.454868 -301.286164)
		(width 0.18288)
		(layer "In11.Cu")
		(net "M_H_CPU0_SA_DQ<13>")
	)
	(segment
		(start 442.419994 -304.042826)
		(end 441.94857 -304.042826)
		(width 0.18288)
		(layer "In11.Cu")
		(net "M_H_CPU0_SA_DQ<13>")
	)
	(segment
		(start 416.086544 -303.722024)
		(end 414.93059 -303.722024)
		(width 0.18288)
		(layer "In11.Cu")
		(net "M_H_CPU0_SA_DQ<13>")
	)
	(segment
		(start 429.027082 -305.658266)
		(end 428.834042 -305.465226)
		(width 0.18288)
		(layer "In11.Cu")
		(net "M_H_CPU0_SA_DQ<13>")
	)
	(segment
		(start 372.287546 -273.44116)
		(end 371.919754 -273.44116)
		(width 0.088646)
		(layer "In11.Cu")
		(net "M_H_CPU0_SA_DQ<13>")
	)
	(segment
		(start 388.24281 -281.39898)
		(end 387.632702 -280.788872)
		(width 0.18288)
		(layer "In11.Cu")
		(net "M_H_CPU0_SA_DQ<13>")
	)
	(segment
		(start 410.460698 -303.575466)
		(end 410.044392 -303.991772)
		(width 0.18288)
		(layer "In11.Cu")
		(net "M_H_CPU0_SA_DQ<13>")
	)
	(segment
		(start 437.81345 -305.51755)
		(end 437.522874 -305.808126)
		(width 0.18288)
		(layer "In11.Cu")
		(net "M_H_CPU0_SA_DQ<13>")
	)
	(segment
		(start 406.320244 -302.290226)
		(end 405.45893 -302.290226)
		(width 0.18288)
		(layer "In11.Cu")
		(net "M_H_CPU0_SA_DQ<13>")
	)
	(segment
		(start 439.632598 -305.691794)
		(end 439.458354 -305.51755)
		(width 0.18288)
		(layer "In11.Cu")
		(net "M_H_CPU0_SA_DQ<13>")
	)
	(arc
		(start 373.122444 -273.946874)
		(mid 372.686473 -273.954962)
		(end 372.44782 -273.590004)
		(width 0.088646)
		(layer "In11.Cu")
		(net "M_H_CPU0_SA_DQ<13>")
	)
	(arc
		(start 374.540018 -273.12874)
		(mid 374.265819 -273.204575)
		(end 373.989346 -273.137376)
		(width 0.088646)
		(layer "In11.Cu")
		(net "M_H_CPU0_SA_DQ<13>")
	)
	(arc
		(start 372.44782 -273.590004)
		(mid 372.396889 -273.484152)
		(end 372.287546 -273.44116)
		(width 0.088646)
		(layer "In11.Cu")
		(net "M_H_CPU0_SA_DQ<13>")
	)
	(arc
		(start 383.453132 -277.20671)
		(mid 383.176657 -277.27403)
		(end 382.90246 -277.198074)
		(width 0.088646)
		(layer "In11.Cu")
		(net "M_H_CPU0_SA_DQ<13>")
	)
	(arc
		(start 381.96266 -277.198074)
		(mid 381.775462 -277.147931)
		(end 381.588264 -277.198074)
		(width 0.088646)
		(layer "In11.Cu")
		(net "M_H_CPU0_SA_DQ<13>")
	)
	(arc
		(start 377.733814 -276.384258)
		(mid 377.546616 -276.334115)
		(end 377.359418 -276.384258)
		(width 0.088646)
		(layer "In11.Cu")
		(net "M_H_CPU0_SA_DQ<13>")
	)
	(arc
		(start 384.39725 -277.20417)
		(mid 384.118818 -277.274016)
		(end 383.842006 -277.198074)
		(width 0.088646)
		(layer "In11.Cu")
		(net "M_H_CPU0_SA_DQ<13>")
	)
	(arc
		(start 376.041666 -275.08073)
		(mid 375.993987 -274.89783)
		(end 375.863104 -274.761452)
		(width 0.088646)
		(layer "In11.Cu")
		(net "M_H_CPU0_SA_DQ<13>")
	)
	(arc
		(start 373.412512 -273.453098)
		(mid 373.336842 -273.735662)
		(end 373.130064 -273.942556)
		(width 0.088646)
		(layer "In11.Cu")
		(net "M_H_CPU0_SA_DQ<13>")
	)
	(arc
		(start 383.842006 -277.198074)
		(mid 383.659755 -277.147963)
		(end 383.476246 -277.193248)
		(width 0.088646)
		(layer "In11.Cu")
		(net "M_H_CPU0_SA_DQ<13>")
	)
	(arc
		(start 378.769118 -277.198074)
		(mid 378.486416 -277.27385)
		(end 378.203714 -277.198074)
		(width 0.088646)
		(layer "In11.Cu")
		(net "M_H_CPU0_SA_DQ<13>")
	)
	(arc
		(start 384.78206 -277.198074)
		(mid 384.594862 -277.147931)
		(end 384.407664 -277.198074)
		(width 0.088646)
		(layer "In11.Cu")
		(net "M_H_CPU0_SA_DQ<13>")
	)
	(arc
		(start 377.359418 -276.384258)
		(mid 377.076716 -276.460034)
		(end 376.794014 -276.384258)
		(width 0.088646)
		(layer "In11.Cu")
		(net "M_H_CPU0_SA_DQ<13>")
	)
	(arc
		(start 386.379212 -278.336502)
		(mid 386.331533 -278.153602)
		(end 386.20065 -278.017224)
		(width 0.088646)
		(layer "In11.Cu")
		(net "M_H_CPU0_SA_DQ<13>")
	)
	(arc
		(start 376.511312 -275.8948)
		(mid 376.463633 -275.7119)
		(end 376.33275 -275.575522)
		(width 0.088646)
		(layer "In11.Cu")
		(net "M_H_CPU0_SA_DQ<13>")
	)
	(arc
		(start 381.573532 -277.20671)
		(mid 381.297057 -277.27403)
		(end 381.02286 -277.198074)
		(width 0.088646)
		(layer "In11.Cu")
		(net "M_H_CPU0_SA_DQ<13>")
	)
	(arc
		(start 385.817364 -278.012144)
		(mid 385.534662 -278.087886)
		(end 385.25196 -278.012144)
		(width 0.088646)
		(layer "In11.Cu")
		(net "M_H_CPU0_SA_DQ<13>")
	)
	(arc
		(start 375.848118 -274.752816)
		(mid 375.645531 -274.546465)
		(end 375.571512 -274.266914)
		(width 0.088646)
		(layer "In11.Cu")
		(net "M_H_CPU0_SA_DQ<13>")
	)
	(arc
		(start 375.101866 -273.453098)
		(mid 375.054187 -273.270198)
		(end 374.923304 -273.13382)
		(width 0.088646)
		(layer "In11.Cu")
		(net "M_H_CPU0_SA_DQ<13>")
	)
	(arc
		(start 373.59971 -273.128994)
		(mid 373.462665 -273.265954)
		(end 373.412512 -273.453098)
		(width 0.088646)
		(layer "In11.Cu")
		(net "M_H_CPU0_SA_DQ<13>")
	)
	(arc
		(start 375.38406 -273.942556)
		(mid 375.181237 -273.742325)
		(end 375.101866 -273.468592)
		(width 0.088646)
		(layer "In11.Cu")
		(net "M_H_CPU0_SA_DQ<13>")
	)
	(arc
		(start 377.921266 -276.708616)
		(mid 377.873587 -276.525716)
		(end 377.742704 -276.389338)
		(width 0.088646)
		(layer "In11.Cu")
		(net "M_H_CPU0_SA_DQ<13>")
	)
	(arc
		(start 380.08306 -277.198074)
		(mid 379.895862 -277.147931)
		(end 379.708664 -277.198074)
		(width 0.088646)
		(layer "In11.Cu")
		(net "M_H_CPU0_SA_DQ<13>")
	)
	(arc
		(start 375.571512 -274.266914)
		(mid 375.523833 -274.084014)
		(end 375.39295 -273.947636)
		(width 0.088646)
		(layer "In11.Cu")
		(net "M_H_CPU0_SA_DQ<13>")
	)
	(arc
		(start 378.203714 -277.198074)
		(mid 377.999379 -276.995469)
		(end 377.921266 -276.718522)
		(width 0.088646)
		(layer "In11.Cu")
		(net "M_H_CPU0_SA_DQ<13>")
	)
	(arc
		(start 384.969512 -277.522432)
		(mid 384.921833 -277.339532)
		(end 384.79095 -277.203154)
		(width 0.088646)
		(layer "In11.Cu")
		(net "M_H_CPU0_SA_DQ<13>")
	)
	(arc
		(start 374.914668 -273.12874)
		(mid 374.72736 -273.078597)
		(end 374.540018 -273.12874)
		(width 0.088646)
		(layer "In11.Cu")
		(net "M_H_CPU0_SA_DQ<13>")
	)
	(arc
		(start 381.02286 -277.198074)
		(mid 380.835662 -277.147931)
		(end 380.648464 -277.198074)
		(width 0.088646)
		(layer "In11.Cu")
		(net "M_H_CPU0_SA_DQ<13>")
	)
	(arc
		(start 386.19176 -278.012144)
		(mid 386.004562 -277.962001)
		(end 385.817364 -278.012144)
		(width 0.088646)
		(layer "In11.Cu")
		(net "M_H_CPU0_SA_DQ<13>")
	)
	(arc
		(start 379.69825 -277.20417)
		(mid 379.420072 -277.273893)
		(end 379.143514 -277.198074)
		(width 0.088646)
		(layer "In11.Cu")
		(net "M_H_CPU0_SA_DQ<13>")
	)
	(arc
		(start 380.648464 -277.198074)
		(mid 380.365762 -277.27385)
		(end 380.08306 -277.198074)
		(width 0.088646)
		(layer "In11.Cu")
		(net "M_H_CPU0_SA_DQ<13>")
	)
	(arc
		(start 376.781822 -276.377146)
		(mid 376.583594 -276.171298)
		(end 376.511312 -275.8948)
		(width 0.088646)
		(layer "In11.Cu")
		(net "M_H_CPU0_SA_DQ<13>")
	)
	(arc
		(start 382.90246 -277.198074)
		(mid 382.715262 -277.147931)
		(end 382.528064 -277.198074)
		(width 0.088646)
		(layer "In11.Cu")
		(net "M_H_CPU0_SA_DQ<13>")
	)
	(arc
		(start 385.25196 -278.012144)
		(mid 385.049674 -277.813163)
		(end 384.969512 -277.540974)
		(width 0.088646)
		(layer "In11.Cu")
		(net "M_H_CPU0_SA_DQ<13>")
	)
	(arc
		(start 376.32386 -275.570442)
		(mid 376.122578 -275.372955)
		(end 376.041666 -275.102828)
		(width 0.088646)
		(layer "In11.Cu")
		(net "M_H_CPU0_SA_DQ<13>")
	)
	(arc
		(start 373.974614 -273.12874)
		(mid 373.787416 -273.078597)
		(end 373.600218 -273.12874)
		(width 0.088646)
		(layer "In11.Cu")
		(net "M_H_CPU0_SA_DQ<13>")
	)
	(arc
		(start 382.513332 -277.20671)
		(mid 382.236857 -277.27403)
		(end 381.96266 -277.198074)
		(width 0.088646)
		(layer "In11.Cu")
		(net "M_H_CPU0_SA_DQ<13>")
	)
	(arc
		(start 379.143514 -277.198074)
		(mid 378.956316 -277.147931)
		(end 378.769118 -277.198074)
		(width 0.088646)
		(layer "In11.Cu")
		(net "M_H_CPU0_SA_DQ<13>")
	)
	(segment
		(start 459.55966 -301.016924)
		(end 457.968096 -301.016924)
		(width 0.20066)
		(layer "F.Cu")
		(net "M_H_CPU0_SA_DQ<12>")
	)
	(segment
		(start 454.91146 -300.591728)
		(end 454.566782 -300.591728)
		(width 0.20066)
		(layer "F.Cu")
		(net "M_H_CPU0_SA_DQ<12>")
	)
	(segment
		(start 371.437916 -274.26666)
		(end 371.437662 -274.266914)
		(width 0.20066)
		(layer "F.Cu")
		(net "M_H_CPU0_SA_DQ<12>")
	)
	(segment
		(start 454.448672 -301.077376)
		(end 454.260712 -301.265336)
		(width 0.20066)
		(layer "F.Cu")
		(net "M_H_CPU0_SA_DQ<12>")
	)
	(segment
		(start 453.536812 -301.01667)
		(end 452.016114 -301.01667)
		(width 0.20066)
		(layer "F.Cu")
		(net "M_H_CPU0_SA_DQ<12>")
	)
	(segment
		(start 454.95845 -300.591728)
		(end 454.91146 -300.591728)
		(width 0.101854)
		(layer "F.Cu")
		(net "M_H_CPU0_SA_DQ<12>")
	)
	(segment
		(start 453.785478 -301.265336)
		(end 453.536812 -301.01667)
		(width 0.20066)
		(layer "F.Cu")
		(net "M_H_CPU0_SA_DQ<12>")
	)
	(segment
		(start 457.126594 -300.585378)
		(end 457.120244 -300.591728)
		(width 0.1016)
		(layer "F.Cu")
		(net "M_H_CPU0_SA_DQ<12>")
	)
	(segment
		(start 454.448672 -300.709838)
		(end 454.448672 -301.077376)
		(width 0.20066)
		(layer "F.Cu")
		(net "M_H_CPU0_SA_DQ<12>")
	)
	(segment
		(start 459.559914 -301.01667)
		(end 459.55966 -301.016924)
		(width 0.20066)
		(layer "F.Cu")
		(net "M_H_CPU0_SA_DQ<12>")
	)
	(segment
		(start 454.566782 -300.591728)
		(end 454.448672 -300.709838)
		(width 0.20066)
		(layer "F.Cu")
		(net "M_H_CPU0_SA_DQ<12>")
	)
	(segment
		(start 457.120244 -300.591728)
		(end 454.95845 -300.591728)
		(width 0.1016)
		(layer "F.Cu")
		(net "M_H_CPU0_SA_DQ<12>")
	)
	(segment
		(start 371.437916 -273.730974)
		(end 371.437916 -274.26666)
		(width 0.20066)
		(layer "F.Cu")
		(net "M_H_CPU0_SA_DQ<12>")
	)
	(segment
		(start 454.260712 -301.265336)
		(end 453.785478 -301.265336)
		(width 0.20066)
		(layer "F.Cu")
		(net "M_H_CPU0_SA_DQ<12>")
	)
	(segment
		(start 457.968096 -301.016924)
		(end 457.53655 -300.585378)
		(width 0.20066)
		(layer "F.Cu")
		(net "M_H_CPU0_SA_DQ<12>")
	)
	(segment
		(start 457.53655 -300.585378)
		(end 457.126594 -300.585378)
		(width 0.20066)
		(layer "F.Cu")
		(net "M_H_CPU0_SA_DQ<12>")
	)
	(segment
		(start 452.016114 -301.01667)
		(end 450.911214 -301.01667)
		(width 0.20066)
		(layer "F.Cu")
		(net "M_H_CPU0_SA_DQ<12>")
	)
	(segment
		(start 420.233094 -308.241954)
		(end 420.076376 -308.085236)
		(width 0.18288)
		(layer "In11.Cu")
		(net "M_H_CPU0_SA_DQ<12>")
	)
	(segment
		(start 431.164238 -307.208682)
		(end 430.078642 -307.208682)
		(width 0.18288)
		(layer "In11.Cu")
		(net "M_H_CPU0_SA_DQ<12>")
	)
	(segment
		(start 385.909312 -279.160224)
		(end 385.909312 -279.150318)
		(width 0.088646)
		(layer "In11.Cu")
		(net "M_H_CPU0_SA_DQ<12>")
	)
	(segment
		(start 419.17747 -308.085236)
		(end 417.413694 -306.32146)
		(width 0.18288)
		(layer "In11.Cu")
		(net "M_H_CPU0_SA_DQ<12>")
	)
	(segment
		(start 429.885602 -307.78704)
		(end 429.692562 -307.98008)
		(width 0.18288)
		(layer "In11.Cu")
		(net "M_H_CPU0_SA_DQ<12>")
	)
	(segment
		(start 386.816346 -280.510996)
		(end 386.22478 -279.91943)
		(width 0.088646)
		(layer "In11.Cu")
		(net "M_H_CPU0_SA_DQ<12>")
	)
	(segment
		(start 388.678166 -283.628084)
		(end 388.678166 -283.525722)
		(width 0.18288)
		(layer "In11.Cu")
		(net "M_H_CPU0_SA_DQ<12>")
	)
	(segment
		(start 433.789074 -306.731416)
		(end 433.789074 -306.981606)
		(width 0.18288)
		(layer "In11.Cu")
		(net "M_H_CPU0_SA_DQ<12>")
	)
	(segment
		(start 429.182022 -307.78704)
		(end 429.182022 -307.401722)
		(width 0.18288)
		(layer "In11.Cu")
		(net "M_H_CPU0_SA_DQ<12>")
	)
	(segment
		(start 439.737246 -307.391816)
		(end 439.583068 -307.237638)
		(width 0.18288)
		(layer "In11.Cu")
		(net "M_H_CPU0_SA_DQ<12>")
	)
	(segment
		(start 374.070118 -273.942556)
		(end 374.061228 -273.947636)
		(width 0.088646)
		(layer "In11.Cu")
		(net "M_H_CPU0_SA_DQ<12>")
	)
	(segment
		(start 375.39295 -275.575522)
		(end 375.38406 -275.570442)
		(width 0.088646)
		(layer "In11.Cu")
		(net "M_H_CPU0_SA_DQ<12>")
	)
	(segment
		(start 383.387092 -278.02078)
		(end 383.37236 -278.012144)
		(width 0.088646)
		(layer "In11.Cu")
		(net "M_H_CPU0_SA_DQ<12>")
	)
	(segment
		(start 372.190264 -274.591272)
		(end 372.175532 -274.582636)
		(width 0.088646)
		(layer "In11.Cu")
		(net "M_H_CPU0_SA_DQ<12>")
	)
	(segment
		(start 409.357322 -305.691794)
		(end 409.164282 -305.884834)
		(width 0.18288)
		(layer "In11.Cu")
		(net "M_H_CPU0_SA_DQ<12>")
	)
	(segment
		(start 410.187902 -305.691794)
		(end 409.357322 -305.691794)
		(width 0.18288)
		(layer "In11.Cu")
		(net "M_H_CPU0_SA_DQ<12>")
	)
	(segment
		(start 379.239018 -278.012144)
		(end 379.228604 -278.01824)
		(width 0.088646)
		(layer "In11.Cu")
		(net "M_H_CPU0_SA_DQ<12>")
	)
	(segment
		(start 446.153794 -304.049938)
		(end 446.153794 -304.601626)
		(width 0.18288)
		(layer "In11.Cu")
		(net "M_H_CPU0_SA_DQ<12>")
	)
	(segment
		(start 403.326092 -302.724058)
		(end 403.326092 -300.003718)
		(width 0.18288)
		(layer "In11.Cu")
		(net "M_H_CPU0_SA_DQ<12>")
	)
	(segment
		(start 423.370756 -307.58384)
		(end 423.004742 -307.217826)
		(width 0.18288)
		(layer "In11.Cu")
		(net "M_H_CPU0_SA_DQ<12>")
	)
	(segment
		(start 423.728388 -307.58384)
		(end 423.370756 -307.58384)
		(width 0.18288)
		(layer "In11.Cu")
		(net "M_H_CPU0_SA_DQ<12>")
	)
	(segment
		(start 449.509896 -300.564804)
		(end 448.975734 -301.098966)
		(width 0.18288)
		(layer "In11.Cu")
		(net "M_H_CPU0_SA_DQ<12>")
	)
	(segment
		(start 429.885602 -307.401722)
		(end 429.885602 -307.78704)
		(width 0.18288)
		(layer "In11.Cu")
		(net "M_H_CPU0_SA_DQ<12>")
	)
	(segment
		(start 376.041666 -276.72411)
		(end 376.041666 -276.708616)
		(width 0.088646)
		(layer "In11.Cu")
		(net "M_H_CPU0_SA_DQ<12>")
	)
	(segment
		(start 426.11548 -307.803296)
		(end 425.92244 -307.996336)
		(width 0.18288)
		(layer "In11.Cu")
		(net "M_H_CPU0_SA_DQ<12>")
	)
	(segment
		(start 377.27255 -277.203154)
		(end 377.26366 -277.198074)
		(width 0.088646)
		(layer "In11.Cu")
		(net "M_H_CPU0_SA_DQ<12>")
	)
	(segment
		(start 444.967868 -304.847752)
		(end 444.223394 -305.592226)
		(width 0.18288)
		(layer "In11.Cu")
		(net "M_H_CPU0_SA_DQ<12>")
	)
	(segment
		(start 425.92244 -307.996336)
		(end 425.60494 -307.996336)
		(width 0.18288)
		(layer "In11.Cu")
		(net "M_H_CPU0_SA_DQ<12>")
	)
	(segment
		(start 422.55186 -307.217826)
		(end 421.527732 -308.241954)
		(width 0.18288)
		(layer "In11.Cu")
		(net "M_H_CPU0_SA_DQ<12>")
	)
	(segment
		(start 423.004742 -307.217826)
		(end 422.55186 -307.217826)
		(width 0.18288)
		(layer "In11.Cu")
		(net "M_H_CPU0_SA_DQ<12>")
	)
	(segment
		(start 436.930292 -307.237638)
		(end 436.23103 -306.538376)
		(width 0.18288)
		(layer "In11.Cu")
		(net "M_H_CPU0_SA_DQ<12>")
	)
	(segment
		(start 413.600646 -305.52136)
		(end 413.172656 -305.52136)
		(width 0.18288)
		(layer "In11.Cu")
		(net "M_H_CPU0_SA_DQ<12>")
	)
	(segment
		(start 425.4119 -307.803296)
		(end 425.4119 -307.589682)
		(width 0.18288)
		(layer "In11.Cu")
		(net "M_H_CPU0_SA_DQ<12>")
	)
	(segment
		(start 429.375062 -307.98008)
		(end 429.182022 -307.78704)
		(width 0.18288)
		(layer "In11.Cu")
		(net "M_H_CPU0_SA_DQ<12>")
	)
	(segment
		(start 403.326092 -300.003718)
		(end 395.23035 -291.907976)
		(width 0.18288)
		(layer "In11.Cu")
		(net "M_H_CPU0_SA_DQ<12>")
	)
	(segment
		(start 410.891482 -306.833524)
		(end 410.573982 -306.833524)
		(width 0.18288)
		(layer "In11.Cu")
		(net "M_H_CPU0_SA_DQ<12>")
	)
	(segment
		(start 387.495796 -281.85364)
		(end 387.445504 -281.803348)
		(width 0.18288)
		(layer "In11.Cu")
		(net "M_H_CPU0_SA_DQ<12>")
	)
	(segment
		(start 433.085494 -306.665122)
		(end 432.892454 -306.472082)
		(width 0.18288)
		(layer "In11.Cu")
		(net "M_H_CPU0_SA_DQ<12>")
	)
	(segment
		(start 408.460702 -306.474368)
		(end 408.460702 -305.884834)
		(width 0.18288)
		(layer "In11.Cu")
		(net "M_H_CPU0_SA_DQ<12>")
	)
	(segment
		(start 425.21124 -307.389022)
		(end 424.616118 -307.389022)
		(width 0.18288)
		(layer "In11.Cu")
		(net "M_H_CPU0_SA_DQ<12>")
	)
	(segment
		(start 411.084522 -306.640484)
		(end 410.891482 -306.833524)
		(width 0.18288)
		(layer "In11.Cu")
		(net "M_H_CPU0_SA_DQ<12>")
	)
	(segment
		(start 375.101612 -275.094954)
		(end 375.101612 -275.08073)
		(width 0.088646)
		(layer "In11.Cu")
		(net "M_H_CPU0_SA_DQ<12>")
	)
	(segment
		(start 373.130064 -274.591272)
		(end 373.115332 -274.582636)
		(width 0.088646)
		(layer "In11.Cu")
		(net "M_H_CPU0_SA_DQ<12>")
	)
	(segment
		(start 384.32105 -278.017224)
		(end 384.31216 -278.012144)
		(width 0.088646)
		(layer "In11.Cu")
		(net "M_H_CPU0_SA_DQ<12>")
	)
	(segment
		(start 439.391298 -307.237638)
		(end 439.198258 -307.430678)
		(width 0.18288)
		(layer "In11.Cu")
		(net "M_H_CPU0_SA_DQ<12>")
	)
	(segment
		(start 417.413694 -306.32146)
		(end 416.626294 -306.32146)
		(width 0.18288)
		(layer "In11.Cu")
		(net "M_H_CPU0_SA_DQ<12>")
	)
	(segment
		(start 414.497266 -305.7144)
		(end 414.497266 -305.97856)
		(width 0.18288)
		(layer "In11.Cu")
		(net "M_H_CPU0_SA_DQ<12>")
	)
	(segment
		(start 376.889264 -277.198074)
		(end 376.874532 -277.20671)
		(width 0.088646)
		(layer "In11.Cu")
		(net "M_H_CPU0_SA_DQ<12>")
	)
	(segment
		(start 433.596034 -307.174646)
		(end 433.278534 -307.174646)
		(width 0.18288)
		(layer "In11.Cu")
		(net "M_H_CPU0_SA_DQ<12>")
	)
	(segment
		(start 406.665938 -305.45024)
		(end 406.055322 -304.839624)
		(width 0.18288)
		(layer "In11.Cu")
		(net "M_H_CPU0_SA_DQ<12>")
	)
	(segment
		(start 407.663904 -305.45024)
		(end 406.665938 -305.45024)
		(width 0.18288)
		(layer "In11.Cu")
		(net "M_H_CPU0_SA_DQ<12>")
	)
	(segment
		(start 412.737046 -305.95697)
		(end 412.064454 -305.95697)
		(width 0.18288)
		(layer "In11.Cu")
		(net "M_H_CPU0_SA_DQ<12>")
	)
	(segment
		(start 439.198258 -307.785516)
		(end 439.005218 -307.978556)
		(width 0.18288)
		(layer "In11.Cu")
		(net "M_H_CPU0_SA_DQ<12>")
	)
	(segment
		(start 375.854214 -276.384258)
		(end 375.848118 -276.380702)
		(width 0.088646)
		(layer "In11.Cu")
		(net "M_H_CPU0_SA_DQ<12>")
	)
	(segment
		(start 411.277562 -305.691794)
		(end 411.084522 -305.884834)
		(width 0.18288)
		(layer "In11.Cu")
		(net "M_H_CPU0_SA_DQ<12>")
	)
	(segment
		(start 380.567946 -278.02078)
		(end 380.553214 -278.012144)
		(width 0.088646)
		(layer "In11.Cu")
		(net "M_H_CPU0_SA_DQ<12>")
	)
	(segment
		(start 395.23035 -290.180268)
		(end 388.678166 -283.628084)
		(width 0.18288)
		(layer "In11.Cu")
		(net "M_H_CPU0_SA_DQ<12>")
	)
	(segment
		(start 442.318394 -305.947826)
		(end 441.984384 -305.947826)
		(width 0.18288)
		(layer "In11.Cu")
		(net "M_H_CPU0_SA_DQ<12>")
	)
	(segment
		(start 449.860924 -300.564804)
		(end 449.509896 -300.564804)
		(width 0.18288)
		(layer "In11.Cu")
		(net "M_H_CPU0_SA_DQ<12>")
	)
	(segment
		(start 433.085494 -306.981606)
		(end 433.085494 -306.665122)
		(width 0.18288)
		(layer "In11.Cu")
		(net "M_H_CPU0_SA_DQ<12>")
	)
	(segment
		(start 425.4119 -307.589682)
		(end 425.21124 -307.389022)
		(width 0.18288)
		(layer "In11.Cu")
		(net "M_H_CPU0_SA_DQ<12>")
	)
	(segment
		(start 448.975734 -301.098966)
		(end 448.975734 -301.227998)
		(width 0.18288)
		(layer "In11.Cu")
		(net "M_H_CPU0_SA_DQ<12>")
	)
	(segment
		(start 450.911214 -301.01667)
		(end 450.31279 -301.01667)
		(width 0.18288)
		(layer "In11.Cu")
		(net "M_H_CPU0_SA_DQ<12>")
	)
	(segment
		(start 371.281198 -274.537932)
		(end 371.437662 -274.266914)
		(width 0.088646)
		(layer "In11.Cu")
		(net "M_H_CPU0_SA_DQ<12>")
	)
	(segment
		(start 441.984384 -305.947826)
		(end 440.540394 -307.391816)
		(width 0.18288)
		(layer "In11.Cu")
		(net "M_H_CPU0_SA_DQ<12>")
	)
	(segment
		(start 408.267662 -305.691794)
		(end 407.905458 -305.691794)
		(width 0.18288)
		(layer "In11.Cu")
		(net "M_H_CPU0_SA_DQ<12>")
	)
	(segment
		(start 432.892454 -306.472082)
		(end 431.900838 -306.472082)
		(width 0.18288)
		(layer "In11.Cu")
		(net "M_H_CPU0_SA_DQ<12>")
	)
	(segment
		(start 371.30228 -274.61591)
		(end 371.281198 -274.537932)
		(width 0.088646)
		(layer "In11.Cu")
		(net "M_H_CPU0_SA_DQ<12>")
	)
	(segment
		(start 429.182022 -307.401722)
		(end 428.988982 -307.208682)
		(width 0.18288)
		(layer "In11.Cu")
		(net "M_H_CPU0_SA_DQ<12>")
	)
	(segment
		(start 410.380942 -305.884834)
		(end 410.187902 -305.691794)
		(width 0.18288)
		(layer "In11.Cu")
		(net "M_H_CPU0_SA_DQ<12>")
	)
	(segment
		(start 433.789074 -306.981606)
		(end 433.596034 -307.174646)
		(width 0.18288)
		(layer "In11.Cu")
		(net "M_H_CPU0_SA_DQ<12>")
	)
	(segment
		(start 445.907668 -304.847752)
		(end 444.967868 -304.847752)
		(width 0.18288)
		(layer "In11.Cu")
		(net "M_H_CPU0_SA_DQ<12>")
	)
	(segment
		(start 408.460702 -305.884834)
		(end 408.267662 -305.691794)
		(width 0.18288)
		(layer "In11.Cu")
		(net "M_H_CPU0_SA_DQ<12>")
	)
	(segment
		(start 433.278534 -307.174646)
		(end 433.085494 -306.981606)
		(width 0.18288)
		(layer "In11.Cu")
		(net "M_H_CPU0_SA_DQ<12>")
	)
	(segment
		(start 438.494678 -307.785516)
		(end 438.494678 -307.430678)
		(width 0.18288)
		(layer "In11.Cu")
		(net "M_H_CPU0_SA_DQ<12>")
	)
	(segment
		(start 426.30852 -307.396642)
		(end 426.11548 -307.589682)
		(width 0.18288)
		(layer "In11.Cu")
		(net "M_H_CPU0_SA_DQ<12>")
	)
	(segment
		(start 413.172656 -305.52136)
		(end 412.737046 -305.95697)
		(width 0.18288)
		(layer "In11.Cu")
		(net "M_H_CPU0_SA_DQ<12>")
	)
	(segment
		(start 415.826194 -305.52136)
		(end 414.690306 -305.52136)
		(width 0.18288)
		(layer "In11.Cu")
		(net "M_H_CPU0_SA_DQ<12>")
	)
	(segment
		(start 438.301638 -307.237638)
		(end 436.930292 -307.237638)
		(width 0.18288)
		(layer "In11.Cu")
		(net "M_H_CPU0_SA_DQ<12>")
	)
	(segment
		(start 439.005218 -307.978556)
		(end 438.687718 -307.978556)
		(width 0.18288)
		(layer "In11.Cu")
		(net "M_H_CPU0_SA_DQ<12>")
	)
	(segment
		(start 450.31279 -301.01667)
		(end 449.860924 -300.564804)
		(width 0.18288)
		(layer "In11.Cu")
		(net "M_H_CPU0_SA_DQ<12>")
	)
	(segment
		(start 387.445504 -281.803348)
		(end 386.849366 -281.20721)
		(width 0.088646)
		(layer "In11.Cu")
		(net "M_H_CPU0_SA_DQ<12>")
	)
	(segment
		(start 386.849366 -281.20721)
		(end 386.849366 -280.590752)
		(width 0.088646)
		(layer "In11.Cu")
		(net "M_H_CPU0_SA_DQ<12>")
	)
	(segment
		(start 409.164282 -305.884834)
		(end 409.164282 -306.474368)
		(width 0.18288)
		(layer "In11.Cu")
		(net "M_H_CPU0_SA_DQ<12>")
	)
	(segment
		(start 384.499612 -278.346408)
		(end 384.499612 -278.336502)
		(width 0.088646)
		(layer "In11.Cu")
		(net "M_H_CPU0_SA_DQ<12>")
	)
	(segment
		(start 374.631712 -274.27682)
		(end 374.631712 -274.258278)
		(width 0.088646)
		(layer "In11.Cu")
		(net "M_H_CPU0_SA_DQ<12>")
	)
	(segment
		(start 408.653742 -306.667408)
		(end 408.460702 -306.474368)
		(width 0.18288)
		(layer "In11.Cu")
		(net "M_H_CPU0_SA_DQ<12>")
	)
	(segment
		(start 433.982114 -306.538376)
		(end 433.789074 -306.731416)
		(width 0.18288)
		(layer "In11.Cu")
		(net "M_H_CPU0_SA_DQ<12>")
	)
	(segment
		(start 438.687718 -307.978556)
		(end 438.494678 -307.785516)
		(width 0.18288)
		(layer "In11.Cu")
		(net "M_H_CPU0_SA_DQ<12>")
	)
	(segment
		(start 412.064454 -305.95697)
		(end 411.799278 -305.691794)
		(width 0.18288)
		(layer "In11.Cu")
		(net "M_H_CPU0_SA_DQ<12>")
	)
	(segment
		(start 385.73075 -278.83104)
		(end 385.72186 -278.82596)
		(width 0.088646)
		(layer "In11.Cu")
		(net "M_H_CPU0_SA_DQ<12>")
	)
	(segment
		(start 413.793686 -305.97856)
		(end 413.793686 -305.7144)
		(width 0.18288)
		(layer "In11.Cu")
		(net "M_H_CPU0_SA_DQ<12>")
	)
	(segment
		(start 386.19176 -279.839674)
		(end 386.19176 -279.692354)
		(width 0.088646)
		(layer "In11.Cu")
		(net "M_H_CPU0_SA_DQ<12>")
	)
	(segment
		(start 375.863104 -276.389338)
		(end 375.854214 -276.384258)
		(width 0.088646)
		(layer "In11.Cu")
		(net "M_H_CPU0_SA_DQ<12>")
	)
	(segment
		(start 409.164282 -306.474368)
		(end 408.971242 -306.667408)
		(width 0.18288)
		(layer "In11.Cu")
		(net "M_H_CPU0_SA_DQ<12>")
	)
	(segment
		(start 424.094402 -307.217826)
		(end 423.728388 -307.58384)
		(width 0.18288)
		(layer "In11.Cu")
		(net "M_H_CPU0_SA_DQ<12>")
	)
	(segment
		(start 414.497266 -305.97856)
		(end 414.304226 -306.1716)
		(width 0.18288)
		(layer "In11.Cu")
		(net "M_H_CPU0_SA_DQ<12>")
	)
	(segment
		(start 431.900838 -306.472082)
		(end 431.164238 -307.208682)
		(width 0.18288)
		(layer "In11.Cu")
		(net "M_H_CPU0_SA_DQ<12>")
	)
	(segment
		(start 438.494678 -307.430678)
		(end 438.301638 -307.237638)
		(width 0.18288)
		(layer "In11.Cu")
		(net "M_H_CPU0_SA_DQ<12>")
	)
	(segment
		(start 410.380942 -306.640484)
		(end 410.380942 -305.884834)
		(width 0.18288)
		(layer "In11.Cu")
		(net "M_H_CPU0_SA_DQ<12>")
	)
	(segment
		(start 448.975734 -301.227998)
		(end 446.153794 -304.049938)
		(width 0.18288)
		(layer "In11.Cu")
		(net "M_H_CPU0_SA_DQ<12>")
	)
	(segment
		(start 425.60494 -307.996336)
		(end 425.4119 -307.803296)
		(width 0.18288)
		(layer "In11.Cu")
		(net "M_H_CPU0_SA_DQ<12>")
	)
	(segment
		(start 373.882666 -274.352258)
		(end 373.715026 -274.519898)
		(width 0.088646)
		(layer "In11.Cu")
		(net "M_H_CPU0_SA_DQ<12>")
	)
	(segment
		(start 405.441658 -304.839624)
		(end 403.326092 -302.724058)
		(width 0.18288)
		(layer "In11.Cu")
		(net "M_H_CPU0_SA_DQ<12>")
	)
	(segment
		(start 424.616118 -307.389022)
		(end 424.444922 -307.217826)
		(width 0.18288)
		(layer "In11.Cu")
		(net "M_H_CPU0_SA_DQ<12>")
	)
	(segment
		(start 374.92305 -274.761452)
		(end 374.91416 -274.756372)
		(width 0.088646)
		(layer "In11.Cu")
		(net "M_H_CPU0_SA_DQ<12>")
	)
	(segment
		(start 416.626294 -306.32146)
		(end 415.826194 -305.52136)
		(width 0.18288)
		(layer "In11.Cu")
		(net "M_H_CPU0_SA_DQ<12>")
	)
	(segment
		(start 426.11548 -307.589682)
		(end 426.11548 -307.803296)
		(width 0.18288)
		(layer "In11.Cu")
		(net "M_H_CPU0_SA_DQ<12>")
	)
	(segment
		(start 427.725078 -307.396642)
		(end 426.30852 -307.396642)
		(width 0.18288)
		(layer "In11.Cu")
		(net "M_H_CPU0_SA_DQ<12>")
	)
	(segment
		(start 388.678166 -283.525722)
		(end 387.842252 -282.689808)
		(width 0.18288)
		(layer "In11.Cu")
		(net "M_H_CPU0_SA_DQ<12>")
	)
	(segment
		(start 430.078642 -307.208682)
		(end 429.885602 -307.401722)
		(width 0.18288)
		(layer "In11.Cu")
		(net "M_H_CPU0_SA_DQ<12>")
	)
	(segment
		(start 395.23035 -291.907976)
		(end 395.23035 -290.180268)
		(width 0.18288)
		(layer "In11.Cu")
		(net "M_H_CPU0_SA_DQ<12>")
	)
	(segment
		(start 411.084522 -305.884834)
		(end 411.084522 -306.640484)
		(width 0.18288)
		(layer "In11.Cu")
		(net "M_H_CPU0_SA_DQ<12>")
	)
	(segment
		(start 411.799278 -305.691794)
		(end 411.277562 -305.691794)
		(width 0.18288)
		(layer "In11.Cu")
		(net "M_H_CPU0_SA_DQ<12>")
	)
	(segment
		(start 424.444922 -307.217826)
		(end 424.094402 -307.217826)
		(width 0.18288)
		(layer "In11.Cu")
		(net "M_H_CPU0_SA_DQ<12>")
	)
	(segment
		(start 428.988982 -307.208682)
		(end 427.913038 -307.208682)
		(width 0.18288)
		(layer "In11.Cu")
		(net "M_H_CPU0_SA_DQ<12>")
	)
	(segment
		(start 442.673994 -305.592226)
		(end 442.318394 -305.947826)
		(width 0.18288)
		(layer "In11.Cu")
		(net "M_H_CPU0_SA_DQ<12>")
	)
	(segment
		(start 429.692562 -307.98008)
		(end 429.375062 -307.98008)
		(width 0.18288)
		(layer "In11.Cu")
		(net "M_H_CPU0_SA_DQ<12>")
	)
	(segment
		(start 379.628146 -278.02078)
		(end 379.613414 -278.012144)
		(width 0.088646)
		(layer "In11.Cu")
		(net "M_H_CPU0_SA_DQ<12>")
	)
	(segment
		(start 414.690306 -305.52136)
		(end 414.497266 -305.7144)
		(width 0.18288)
		(layer "In11.Cu")
		(net "M_H_CPU0_SA_DQ<12>")
	)
	(segment
		(start 414.304226 -306.1716)
		(end 413.986726 -306.1716)
		(width 0.18288)
		(layer "In11.Cu")
		(net "M_H_CPU0_SA_DQ<12>")
	)
	(segment
		(start 420.076376 -308.085236)
		(end 419.17747 -308.085236)
		(width 0.18288)
		(layer "In11.Cu")
		(net "M_H_CPU0_SA_DQ<12>")
	)
	(segment
		(start 413.986726 -306.1716)
		(end 413.793686 -305.97856)
		(width 0.18288)
		(layer "In11.Cu")
		(net "M_H_CPU0_SA_DQ<12>")
	)
	(segment
		(start 444.223394 -305.592226)
		(end 442.673994 -305.592226)
		(width 0.18288)
		(layer "In11.Cu")
		(net "M_H_CPU0_SA_DQ<12>")
	)
	(segment
		(start 408.971242 -306.667408)
		(end 408.653742 -306.667408)
		(width 0.18288)
		(layer "In11.Cu")
		(net "M_H_CPU0_SA_DQ<12>")
	)
	(segment
		(start 407.905458 -305.691794)
		(end 407.663904 -305.45024)
		(width 0.18288)
		(layer "In11.Cu")
		(net "M_H_CPU0_SA_DQ<12>")
	)
	(segment
		(start 421.527732 -308.241954)
		(end 420.233094 -308.241954)
		(width 0.18288)
		(layer "In11.Cu")
		(net "M_H_CPU0_SA_DQ<12>")
	)
	(segment
		(start 373.882666 -274.266914)
		(end 373.882666 -274.352258)
		(width 0.088646)
		(layer "In11.Cu")
		(net "M_H_CPU0_SA_DQ<12>")
	)
	(segment
		(start 413.793686 -305.7144)
		(end 413.600646 -305.52136)
		(width 0.18288)
		(layer "In11.Cu")
		(net "M_H_CPU0_SA_DQ<12>")
	)
	(segment
		(start 446.153794 -304.601626)
		(end 445.907668 -304.847752)
		(width 0.18288)
		(layer "In11.Cu")
		(net "M_H_CPU0_SA_DQ<12>")
	)
	(segment
		(start 381.503428 -278.01824)
		(end 381.493014 -278.012144)
		(width 0.088646)
		(layer "In11.Cu")
		(net "M_H_CPU0_SA_DQ<12>")
	)
	(segment
		(start 427.913038 -307.208682)
		(end 427.725078 -307.396642)
		(width 0.18288)
		(layer "In11.Cu")
		(net "M_H_CPU0_SA_DQ<12>")
	)
	(segment
		(start 439.198258 -307.430678)
		(end 439.198258 -307.785516)
		(width 0.18288)
		(layer "In11.Cu")
		(net "M_H_CPU0_SA_DQ<12>")
	)
	(segment
		(start 440.540394 -307.391816)
		(end 439.737246 -307.391816)
		(width 0.18288)
		(layer "In11.Cu")
		(net "M_H_CPU0_SA_DQ<12>")
	)
	(segment
		(start 436.23103 -306.538376)
		(end 433.982114 -306.538376)
		(width 0.18288)
		(layer "In11.Cu")
		(net "M_H_CPU0_SA_DQ<12>")
	)
	(segment
		(start 410.573982 -306.833524)
		(end 410.380942 -306.640484)
		(width 0.18288)
		(layer "In11.Cu")
		(net "M_H_CPU0_SA_DQ<12>")
	)
	(segment
		(start 378.298964 -278.012144)
		(end 378.28855 -278.01824)
		(width 0.088646)
		(layer "In11.Cu")
		(net "M_H_CPU0_SA_DQ<12>")
	)
	(segment
		(start 406.055322 -304.839624)
		(end 405.441658 -304.839624)
		(width 0.18288)
		(layer "In11.Cu")
		(net "M_H_CPU0_SA_DQ<12>")
	)
	(segment
		(start 439.583068 -307.237638)
		(end 439.391298 -307.237638)
		(width 0.18288)
		(layer "In11.Cu")
		(net "M_H_CPU0_SA_DQ<12>")
	)
	(segment
		(start 377.451112 -277.530052)
		(end 377.451112 -277.522432)
		(width 0.088646)
		(layer "In11.Cu")
		(net "M_H_CPU0_SA_DQ<12>")
	)
	(segment
		(start 387.842252 -282.689808)
		(end 387.495796 -281.85364)
		(width 0.18288)
		(layer "In11.Cu")
		(net "M_H_CPU0_SA_DQ<12>")
	)
	(arc
		(start 374.061228 -273.947636)
		(mid 373.930314 -274.083996)
		(end 373.882666 -274.266914)
		(width 0.088646)
		(layer "In11.Cu")
		(net "M_H_CPU0_SA_DQ<12>")
	)
	(arc
		(start 379.613414 -278.012144)
		(mid 379.426216 -277.962001)
		(end 379.239018 -278.012144)
		(width 0.088646)
		(layer "In11.Cu")
		(net "M_H_CPU0_SA_DQ<12>")
	)
	(arc
		(start 375.101612 -275.08073)
		(mid 375.053933 -274.89783)
		(end 374.92305 -274.761452)
		(width 0.088646)
		(layer "In11.Cu")
		(net "M_H_CPU0_SA_DQ<12>")
	)
	(arc
		(start 377.451112 -277.522432)
		(mid 377.403433 -277.339532)
		(end 377.27255 -277.203154)
		(width 0.088646)
		(layer "In11.Cu")
		(net "M_H_CPU0_SA_DQ<12>")
	)
	(arc
		(start 386.849366 -280.590752)
		(mid 386.840781 -280.547594)
		(end 386.816346 -280.510996)
		(width 0.088646)
		(layer "In11.Cu")
		(net "M_H_CPU0_SA_DQ<12>")
	)
	(arc
		(start 376.041666 -276.708616)
		(mid 375.993987 -276.525716)
		(end 375.863104 -276.389338)
		(width 0.088646)
		(layer "In11.Cu")
		(net "M_H_CPU0_SA_DQ<12>")
	)
	(arc
		(start 380.553214 -278.012144)
		(mid 380.366016 -277.962001)
		(end 380.178818 -278.012144)
		(width 0.088646)
		(layer "In11.Cu")
		(net "M_H_CPU0_SA_DQ<12>")
	)
	(arc
		(start 382.43256 -278.012144)
		(mid 382.245362 -277.962001)
		(end 382.058164 -278.012144)
		(width 0.088646)
		(layer "In11.Cu")
		(net "M_H_CPU0_SA_DQ<12>")
	)
	(arc
		(start 383.937764 -278.012144)
		(mid 383.663535 -278.088069)
		(end 383.387092 -278.02078)
		(width 0.088646)
		(layer "In11.Cu")
		(net "M_H_CPU0_SA_DQ<12>")
	)
	(arc
		(start 386.19176 -279.692354)
		(mid 386.180782 -279.648089)
		(end 386.150612 -279.613868)
		(width 0.088646)
		(layer "In11.Cu")
		(net "M_H_CPU0_SA_DQ<12>")
	)
	(arc
		(start 375.848118 -276.380702)
		(mid 375.645531 -276.174351)
		(end 375.571512 -275.8948)
		(width 0.088646)
		(layer "In11.Cu")
		(net "M_H_CPU0_SA_DQ<12>")
	)
	(arc
		(start 374.631712 -274.258278)
		(mid 374.579442 -274.075913)
		(end 374.444514 -273.942556)
		(width 0.088646)
		(layer "In11.Cu")
		(net "M_H_CPU0_SA_DQ<12>")
	)
	(arc
		(start 379.228604 -278.01824)
		(mid 378.950172 -278.088054)
		(end 378.67336 -278.012144)
		(width 0.088646)
		(layer "In11.Cu")
		(net "M_H_CPU0_SA_DQ<12>")
	)
	(arc
		(start 374.444514 -273.942556)
		(mid 374.257316 -273.892413)
		(end 374.070118 -273.942556)
		(width 0.088646)
		(layer "In11.Cu")
		(net "M_H_CPU0_SA_DQ<12>")
	)
	(arc
		(start 376.874532 -277.20671)
		(mid 376.598057 -277.27403)
		(end 376.32386 -277.198074)
		(width 0.088646)
		(layer "In11.Cu")
		(net "M_H_CPU0_SA_DQ<12>")
	)
	(arc
		(start 380.178818 -278.012144)
		(mid 379.904589 -278.088069)
		(end 379.628146 -278.02078)
		(width 0.088646)
		(layer "In11.Cu")
		(net "M_H_CPU0_SA_DQ<12>")
	)
	(arc
		(start 372.56466 -274.591272)
		(mid 372.377462 -274.641415)
		(end 372.190264 -274.591272)
		(width 0.088646)
		(layer "In11.Cu")
		(net "M_H_CPU0_SA_DQ<12>")
	)
	(arc
		(start 373.115332 -274.582636)
		(mid 372.838857 -274.515316)
		(end 372.56466 -274.591272)
		(width 0.088646)
		(layer "In11.Cu")
		(net "M_H_CPU0_SA_DQ<12>")
	)
	(arc
		(start 386.22478 -279.91943)
		(mid 386.20033 -279.882838)
		(end 386.19176 -279.839674)
		(width 0.088646)
		(layer "In11.Cu")
		(net "M_H_CPU0_SA_DQ<12>")
	)
	(arc
		(start 381.493014 -278.012144)
		(mid 381.305816 -277.962001)
		(end 381.118618 -278.012144)
		(width 0.088646)
		(layer "In11.Cu")
		(net "M_H_CPU0_SA_DQ<12>")
	)
	(arc
		(start 381.118618 -278.012144)
		(mid 380.844389 -278.088069)
		(end 380.567946 -278.02078)
		(width 0.088646)
		(layer "In11.Cu")
		(net "M_H_CPU0_SA_DQ<12>")
	)
	(arc
		(start 383.37236 -278.012144)
		(mid 383.185162 -277.962001)
		(end 382.997964 -278.012144)
		(width 0.088646)
		(layer "In11.Cu")
		(net "M_H_CPU0_SA_DQ<12>")
	)
	(arc
		(start 378.67336 -278.012144)
		(mid 378.486162 -277.962001)
		(end 378.298964 -278.012144)
		(width 0.088646)
		(layer "In11.Cu")
		(net "M_H_CPU0_SA_DQ<12>")
	)
	(arc
		(start 375.38406 -275.570442)
		(mid 375.180755 -275.369576)
		(end 375.101612 -275.094954)
		(width 0.088646)
		(layer "In11.Cu")
		(net "M_H_CPU0_SA_DQ<12>")
	)
	(arc
		(start 378.28855 -278.01824)
		(mid 378.010372 -278.087932)
		(end 377.733814 -278.012144)
		(width 0.088646)
		(layer "In11.Cu")
		(net "M_H_CPU0_SA_DQ<12>")
	)
	(arc
		(start 385.347464 -278.82596)
		(mid 385.064762 -278.901736)
		(end 384.78206 -278.82596)
		(width 0.088646)
		(layer "In11.Cu")
		(net "M_H_CPU0_SA_DQ<12>")
	)
	(arc
		(start 384.499612 -278.336502)
		(mid 384.451933 -278.153602)
		(end 384.32105 -278.017224)
		(width 0.088646)
		(layer "In11.Cu")
		(net "M_H_CPU0_SA_DQ<12>")
	)
	(arc
		(start 375.571512 -275.8948)
		(mid 375.523833 -275.7119)
		(end 375.39295 -275.575522)
		(width 0.088646)
		(layer "In11.Cu")
		(net "M_H_CPU0_SA_DQ<12>")
	)
	(arc
		(start 382.058164 -278.012144)
		(mid 381.781605 -278.087853)
		(end 381.503428 -278.01824)
		(width 0.088646)
		(layer "In11.Cu")
		(net "M_H_CPU0_SA_DQ<12>")
	)
	(arc
		(start 385.909312 -279.150318)
		(mid 385.861633 -278.967418)
		(end 385.73075 -278.83104)
		(width 0.088646)
		(layer "In11.Cu")
		(net "M_H_CPU0_SA_DQ<12>")
	)
	(arc
		(start 371.62486 -274.591272)
		(mid 371.466372 -274.640205)
		(end 371.30228 -274.61591)
		(width 0.088646)
		(layer "In11.Cu")
		(net "M_H_CPU0_SA_DQ<12>")
	)
	(arc
		(start 373.715026 -274.519898)
		(mid 373.606195 -274.545122)
		(end 373.50446 -274.591272)
		(width 0.088646)
		(layer "In11.Cu")
		(net "M_H_CPU0_SA_DQ<12>")
	)
	(arc
		(start 376.32386 -277.198074)
		(mid 376.121037 -276.997843)
		(end 376.041666 -276.72411)
		(width 0.088646)
		(layer "In11.Cu")
		(net "M_H_CPU0_SA_DQ<12>")
	)
	(arc
		(start 386.150612 -279.613868)
		(mid 385.975421 -279.416053)
		(end 385.909312 -279.160224)
		(width 0.088646)
		(layer "In11.Cu")
		(net "M_H_CPU0_SA_DQ<12>")
	)
	(arc
		(start 384.31216 -278.012144)
		(mid 384.124962 -277.962001)
		(end 383.937764 -278.012144)
		(width 0.088646)
		(layer "In11.Cu")
		(net "M_H_CPU0_SA_DQ<12>")
	)
	(arc
		(start 374.91416 -274.756372)
		(mid 374.709825 -274.553767)
		(end 374.631712 -274.27682)
		(width 0.088646)
		(layer "In11.Cu")
		(net "M_H_CPU0_SA_DQ<12>")
	)
	(arc
		(start 384.78206 -278.82596)
		(mid 384.577725 -278.623355)
		(end 384.499612 -278.346408)
		(width 0.088646)
		(layer "In11.Cu")
		(net "M_H_CPU0_SA_DQ<12>")
	)
	(arc
		(start 385.72186 -278.82596)
		(mid 385.534662 -278.775817)
		(end 385.347464 -278.82596)
		(width 0.088646)
		(layer "In11.Cu")
		(net "M_H_CPU0_SA_DQ<12>")
	)
	(arc
		(start 372.175532 -274.582636)
		(mid 371.899057 -274.515316)
		(end 371.62486 -274.591272)
		(width 0.088646)
		(layer "In11.Cu")
		(net "M_H_CPU0_SA_DQ<12>")
	)
	(arc
		(start 377.26366 -277.198074)
		(mid 377.076462 -277.147931)
		(end 376.889264 -277.198074)
		(width 0.088646)
		(layer "In11.Cu")
		(net "M_H_CPU0_SA_DQ<12>")
	)
	(arc
		(start 373.50446 -274.591272)
		(mid 373.317262 -274.641415)
		(end 373.130064 -274.591272)
		(width 0.088646)
		(layer "In11.Cu")
		(net "M_H_CPU0_SA_DQ<12>")
	)
	(arc
		(start 377.733814 -278.012144)
		(mid 377.528742 -277.808465)
		(end 377.451112 -277.530052)
		(width 0.088646)
		(layer "In11.Cu")
		(net "M_H_CPU0_SA_DQ<12>")
	)
	(arc
		(start 382.997964 -278.012144)
		(mid 382.715262 -278.087886)
		(end 382.43256 -278.012144)
		(width 0.088646)
		(layer "In11.Cu")
		(net "M_H_CPU0_SA_DQ<12>")
	)
	(segment
		(start 461.689704 -304.164746)
		(end 462.073752 -304.164746)
		(width 0.20066)
		(layer "F.Cu")
		(net "M_H_CPU0_SA_DQ<11>")
	)
	(segment
		(start 458.24648 -304.848768)
		(end 458.538326 -304.848768)
		(width 0.20066)
		(layer "F.Cu")
		(net "M_H_CPU0_SA_DQ<11>")
	)
	(segment
		(start 373.317516 -275.35886)
		(end 373.317516 -275.894546)
		(width 0.20066)
		(layer "F.Cu")
		(net "M_H_CPU0_SA_DQ<11>")
	)
	(segment
		(start 458.543152 -304.848768)
		(end 458.550264 -304.841656)
		(width 0.1016)
		(layer "F.Cu")
		(net "M_H_CPU0_SA_DQ<11>")
	)
	(segment
		(start 462.32572 -304.416714)
		(end 463.659982 -304.416714)
		(width 0.20066)
		(layer "F.Cu")
		(net "M_H_CPU0_SA_DQ<11>")
	)
	(segment
		(start 461.455516 -304.398934)
		(end 461.689704 -304.164746)
		(width 0.20066)
		(layer "F.Cu")
		(net "M_H_CPU0_SA_DQ<11>")
	)
	(segment
		(start 461.455516 -304.649886)
		(end 461.455516 -304.398934)
		(width 0.20066)
		(layer "F.Cu")
		(net "M_H_CPU0_SA_DQ<11>")
	)
	(segment
		(start 455.011282 -304.416714)
		(end 456.116182 -304.416714)
		(width 0.20066)
		(layer "F.Cu")
		(net "M_H_CPU0_SA_DQ<11>")
	)
	(segment
		(start 458.538326 -304.848768)
		(end 458.543152 -304.848768)
		(width 0.101854)
		(layer "F.Cu")
		(net "M_H_CPU0_SA_DQ<11>")
	)
	(segment
		(start 458.550264 -304.841656)
		(end 460.558134 -304.841656)
		(width 0.1016)
		(layer "F.Cu")
		(net "M_H_CPU0_SA_DQ<11>")
	)
	(segment
		(start 457.814426 -304.416714)
		(end 458.24648 -304.848768)
		(width 0.20066)
		(layer "F.Cu")
		(net "M_H_CPU0_SA_DQ<11>")
	)
	(segment
		(start 460.570326 -304.853848)
		(end 461.251554 -304.853848)
		(width 0.20066)
		(layer "F.Cu")
		(net "M_H_CPU0_SA_DQ<11>")
	)
	(segment
		(start 456.116182 -304.416714)
		(end 457.814426 -304.416714)
		(width 0.20066)
		(layer "F.Cu")
		(net "M_H_CPU0_SA_DQ<11>")
	)
	(segment
		(start 373.317516 -275.894546)
		(end 373.317262 -275.8948)
		(width 0.20066)
		(layer "F.Cu")
		(net "M_H_CPU0_SA_DQ<11>")
	)
	(segment
		(start 461.251554 -304.853848)
		(end 461.455516 -304.649886)
		(width 0.20066)
		(layer "F.Cu")
		(net "M_H_CPU0_SA_DQ<11>")
	)
	(segment
		(start 462.073752 -304.164746)
		(end 462.32572 -304.416714)
		(width 0.20066)
		(layer "F.Cu")
		(net "M_H_CPU0_SA_DQ<11>")
	)
	(segment
		(start 460.558134 -304.841656)
		(end 460.570326 -304.853848)
		(width 0.1016)
		(layer "F.Cu")
		(net "M_H_CPU0_SA_DQ<11>")
	)
	(segment
		(start 383.937764 -281.916378)
		(end 383.928874 -281.911298)
		(width 0.088646)
		(layer "In11.Cu")
		(net "M_H_CPU0_SA_DQ<11>")
	)
	(segment
		(start 440.279282 -312.49493)
		(end 439.33999 -312.49493)
		(width 0.18288)
		(layer "In11.Cu")
		(net "M_H_CPU0_SA_DQ<11>")
	)
	(segment
		(start 421.527224 -312.492898)
		(end 421.21074 -312.809382)
		(width 0.18288)
		(layer "In11.Cu")
		(net "M_H_CPU0_SA_DQ<11>")
	)
	(segment
		(start 386.287264 -284.35808)
		(end 386.278374 -284.353)
		(width 0.088646)
		(layer "In11.Cu")
		(net "M_H_CPU0_SA_DQ<11>")
	)
	(segment
		(start 435.00167 -311.126632)
		(end 431.696622 -311.126632)
		(width 0.18288)
		(layer "In11.Cu")
		(net "M_H_CPU0_SA_DQ<11>")
	)
	(segment
		(start 373.402352 -276.246336)
		(end 373.317262 -276.161246)
		(width 0.088646)
		(layer "In11.Cu")
		(net "M_H_CPU0_SA_DQ<11>")
	)
	(segment
		(start 375.949464 -279.474676)
		(end 375.934732 -279.46604)
		(width 0.088646)
		(layer "In11.Cu")
		(net "M_H_CPU0_SA_DQ<11>")
	)
	(segment
		(start 373.412766 -278.336502)
		(end 373.412766 -278.31796)
		(width 0.088646)
		(layer "In11.Cu")
		(net "M_H_CPU0_SA_DQ<11>")
	)
	(segment
		(start 387.348984 -285.736792)
		(end 386.874004 -285.261812)
		(width 0.088646)
		(layer "In11.Cu")
		(net "M_H_CPU0_SA_DQ<11>")
	)
	(segment
		(start 374.069864 -279.474676)
		(end 374.060974 -279.469596)
		(width 0.088646)
		(layer "In11.Cu")
		(net "M_H_CPU0_SA_DQ<11>")
	)
	(segment
		(start 431.696622 -311.126632)
		(end 431.351436 -310.781446)
		(width 0.18288)
		(layer "In11.Cu")
		(net "M_H_CPU0_SA_DQ<11>")
	)
	(segment
		(start 446.111376 -308.301644)
		(end 445.298576 -308.301644)
		(width 0.18288)
		(layer "In11.Cu")
		(net "M_H_CPU0_SA_DQ<11>")
	)
	(segment
		(start 421.016684 -313.343544)
		(end 419.260782 -313.343544)
		(width 0.18288)
		(layer "In11.Cu")
		(net "M_H_CPU0_SA_DQ<11>")
	)
	(segment
		(start 378.688346 -280.279856)
		(end 378.673614 -280.288492)
		(width 0.088646)
		(layer "In11.Cu")
		(net "M_H_CPU0_SA_DQ<11>")
	)
	(segment
		(start 385.347464 -282.730194)
		(end 385.338574 -282.725114)
		(width 0.088646)
		(layer "In11.Cu")
		(net "M_H_CPU0_SA_DQ<11>")
	)
	(segment
		(start 419.260782 -313.343544)
		(end 416.015678 -310.099964)
		(width 0.18288)
		(layer "In11.Cu")
		(net "M_H_CPU0_SA_DQ<11>")
	)
	(segment
		(start 385.817618 -283.544264)
		(end 385.808728 -283.539184)
		(width 0.088646)
		(layer "In11.Cu")
		(net "M_H_CPU0_SA_DQ<11>")
	)
	(segment
		(start 448.782948 -305.452272)
		(end 448.782948 -306.366672)
		(width 0.18288)
		(layer "In11.Cu")
		(net "M_H_CPU0_SA_DQ<11>")
	)
	(segment
		(start 387.456934 -285.736792)
		(end 387.348984 -285.736792)
		(width 0.088646)
		(layer "In11.Cu")
		(net "M_H_CPU0_SA_DQ<11>")
	)
	(segment
		(start 445.298576 -308.301644)
		(end 443.596776 -310.003444)
		(width 0.18288)
		(layer "In11.Cu")
		(net "M_H_CPU0_SA_DQ<11>")
	)
	(segment
		(start 425.998894 -311.743852)
		(end 425.249848 -312.492898)
		(width 0.18288)
		(layer "In11.Cu")
		(net "M_H_CPU0_SA_DQ<11>")
	)
	(segment
		(start 373.882412 -279.150318)
		(end 373.882412 -279.134824)
		(width 0.088646)
		(layer "In11.Cu")
		(net "M_H_CPU0_SA_DQ<11>")
	)
	(segment
		(start 437.765952 -311.789826)
		(end 436.767986 -310.79186)
		(width 0.18288)
		(layer "In11.Cu")
		(net "M_H_CPU0_SA_DQ<11>")
	)
	(segment
		(start 383.750312 -281.59202)
		(end 383.750312 -281.582114)
		(width 0.088646)
		(layer "In11.Cu")
		(net "M_H_CPU0_SA_DQ<11>")
	)
	(segment
		(start 435.336442 -310.79186)
		(end 435.00167 -311.126632)
		(width 0.18288)
		(layer "In11.Cu")
		(net "M_H_CPU0_SA_DQ<11>")
	)
	(segment
		(start 373.121428 -277.203154)
		(end 373.130318 -277.198074)
		(width 0.088646)
		(layer "In11.Cu")
		(net "M_H_CPU0_SA_DQ<11>")
	)
	(segment
		(start 407.62682 -310.088026)
		(end 405.615902 -310.088026)
		(width 0.18288)
		(layer "In11.Cu")
		(net "M_H_CPU0_SA_DQ<11>")
	)
	(segment
		(start 412.298388 -311.029604)
		(end 408.568398 -311.029604)
		(width 0.18288)
		(layer "In11.Cu")
		(net "M_H_CPU0_SA_DQ<11>")
	)
	(segment
		(start 413.228028 -310.099964)
		(end 412.298388 -311.029604)
		(width 0.18288)
		(layer "In11.Cu")
		(net "M_H_CPU0_SA_DQ<11>")
	)
	(segment
		(start 421.21074 -312.809382)
		(end 421.21074 -313.149488)
		(width 0.18288)
		(layer "In11.Cu")
		(net "M_H_CPU0_SA_DQ<11>")
	)
	(segment
		(start 386.569712 -284.856174)
		(end 386.569712 -284.832044)
		(width 0.088646)
		(layer "In11.Cu")
		(net "M_H_CPU0_SA_DQ<11>")
	)
	(segment
		(start 376.808746 -280.279856)
		(end 376.794014 -280.288492)
		(width 0.088646)
		(layer "In11.Cu")
		(net "M_H_CPU0_SA_DQ<11>")
	)
	(segment
		(start 401.136612 -305.608736)
		(end 401.136612 -300.902116)
		(width 0.18288)
		(layer "In11.Cu")
		(net "M_H_CPU0_SA_DQ<11>")
	)
	(segment
		(start 447.635376 -307.514244)
		(end 446.898776 -307.514244)
		(width 0.18288)
		(layer "In11.Cu")
		(net "M_H_CPU0_SA_DQ<11>")
	)
	(segment
		(start 451.853554 -304.839878)
		(end 450.692774 -304.839878)
		(width 0.18288)
		(layer "In11.Cu")
		(net "M_H_CPU0_SA_DQ<11>")
	)
	(segment
		(start 373.317262 -276.161246)
		(end 373.317262 -275.8948)
		(width 0.088646)
		(layer "In11.Cu")
		(net "M_H_CPU0_SA_DQ<11>")
	)
	(segment
		(start 436.767986 -310.79186)
		(end 435.336442 -310.79186)
		(width 0.18288)
		(layer "In11.Cu")
		(net "M_H_CPU0_SA_DQ<11>")
	)
	(segment
		(start 385.160012 -282.405836)
		(end 385.160012 -282.39593)
		(width 0.088646)
		(layer "In11.Cu")
		(net "M_H_CPU0_SA_DQ<11>")
	)
	(segment
		(start 428.697898 -311.743852)
		(end 425.998894 -311.743852)
		(width 0.18288)
		(layer "In11.Cu")
		(net "M_H_CPU0_SA_DQ<11>")
	)
	(segment
		(start 383.280412 -280.778204)
		(end 383.280412 -280.76398)
		(width 0.088646)
		(layer "In11.Cu")
		(net "M_H_CPU0_SA_DQ<11>")
	)
	(segment
		(start 401.136612 -300.902116)
		(end 392.591544 -292.357048)
		(width 0.18288)
		(layer "In11.Cu")
		(net "M_H_CPU0_SA_DQ<11>")
	)
	(segment
		(start 405.615902 -310.088026)
		(end 401.136612 -305.608736)
		(width 0.18288)
		(layer "In11.Cu")
		(net "M_H_CPU0_SA_DQ<11>")
	)
	(segment
		(start 373.130318 -277.84679)
		(end 373.121428 -277.84171)
		(width 0.088646)
		(layer "In11.Cu")
		(net "M_H_CPU0_SA_DQ<11>")
	)
	(segment
		(start 452.439278 -305.425602)
		(end 451.853554 -304.839878)
		(width 0.18288)
		(layer "In11.Cu")
		(net "M_H_CPU0_SA_DQ<11>")
	)
	(segment
		(start 376.419618 -280.288492)
		(end 376.410728 -280.283412)
		(width 0.088646)
		(layer "In11.Cu")
		(net "M_H_CPU0_SA_DQ<11>")
	)
	(segment
		(start 373.389906 -276.549612)
		(end 373.402352 -276.537166)
		(width 0.088646)
		(layer "In11.Cu")
		(net "M_H_CPU0_SA_DQ<11>")
	)
	(segment
		(start 381.507746 -280.279856)
		(end 381.493014 -280.288492)
		(width 0.088646)
		(layer "In11.Cu")
		(net "M_H_CPU0_SA_DQ<11>")
	)
	(segment
		(start 455.011282 -304.416714)
		(end 454.2028 -304.416714)
		(width 0.18288)
		(layer "In11.Cu")
		(net "M_H_CPU0_SA_DQ<11>")
	)
	(segment
		(start 387.690106 -285.969964)
		(end 387.456934 -285.736792)
		(width 0.088646)
		(layer "In11.Cu")
		(net "M_H_CPU0_SA_DQ<11>")
	)
	(segment
		(start 438.634886 -311.789826)
		(end 437.765952 -311.789826)
		(width 0.18288)
		(layer "In11.Cu")
		(net "M_H_CPU0_SA_DQ<11>")
	)
	(segment
		(start 441.169044 -312.126376)
		(end 440.279282 -312.49493)
		(width 0.18288)
		(layer "In11.Cu")
		(net "M_H_CPU0_SA_DQ<11>")
	)
	(segment
		(start 454.2028 -304.416714)
		(end 453.193912 -305.425602)
		(width 0.18288)
		(layer "In11.Cu")
		(net "M_H_CPU0_SA_DQ<11>")
	)
	(segment
		(start 446.898776 -307.514244)
		(end 446.111376 -308.301644)
		(width 0.18288)
		(layer "In11.Cu")
		(net "M_H_CPU0_SA_DQ<11>")
	)
	(segment
		(start 425.249848 -312.492898)
		(end 421.527224 -312.492898)
		(width 0.18288)
		(layer "In11.Cu")
		(net "M_H_CPU0_SA_DQ<11>")
	)
	(segment
		(start 380.563374 -280.282396)
		(end 380.55296 -280.288492)
		(width 0.088646)
		(layer "In11.Cu")
		(net "M_H_CPU0_SA_DQ<11>")
	)
	(segment
		(start 431.351436 -310.781446)
		(end 429.660304 -310.781446)
		(width 0.18288)
		(layer "In11.Cu")
		(net "M_H_CPU0_SA_DQ<11>")
	)
	(segment
		(start 386.099812 -284.033722)
		(end 386.099812 -284.018228)
		(width 0.088646)
		(layer "In11.Cu")
		(net "M_H_CPU0_SA_DQ<11>")
	)
	(segment
		(start 392.591544 -292.357048)
		(end 392.591544 -290.871402)
		(width 0.18288)
		(layer "In11.Cu")
		(net "M_H_CPU0_SA_DQ<11>")
	)
	(segment
		(start 377.748546 -280.279856)
		(end 377.733814 -280.288492)
		(width 0.088646)
		(layer "In11.Cu")
		(net "M_H_CPU0_SA_DQ<11>")
	)
	(segment
		(start 448.782948 -306.366672)
		(end 447.635376 -307.514244)
		(width 0.18288)
		(layer "In11.Cu")
		(net "M_H_CPU0_SA_DQ<11>")
	)
	(segment
		(start 392.591544 -290.871402)
		(end 387.690106 -285.969964)
		(width 0.18288)
		(layer "In11.Cu")
		(net "M_H_CPU0_SA_DQ<11>")
	)
	(segment
		(start 375.95556 -279.478232)
		(end 375.949464 -279.474676)
		(width 0.088646)
		(layer "In11.Cu")
		(net "M_H_CPU0_SA_DQ<11>")
	)
	(segment
		(start 450.692774 -304.839878)
		(end 450.511926 -304.65903)
		(width 0.18288)
		(layer "In11.Cu")
		(net "M_H_CPU0_SA_DQ<11>")
	)
	(segment
		(start 383.467864 -281.102562)
		(end 383.458974 -281.097482)
		(width 0.088646)
		(layer "In11.Cu")
		(net "M_H_CPU0_SA_DQ<11>")
	)
	(segment
		(start 453.193912 -305.425602)
		(end 452.439278 -305.425602)
		(width 0.18288)
		(layer "In11.Cu")
		(net "M_H_CPU0_SA_DQ<11>")
	)
	(segment
		(start 373.402352 -276.537166)
		(end 373.402352 -276.246336)
		(width 0.088646)
		(layer "In11.Cu")
		(net "M_H_CPU0_SA_DQ<11>")
	)
	(segment
		(start 449.57619 -304.65903)
		(end 448.782948 -305.452272)
		(width 0.18288)
		(layer "In11.Cu")
		(net "M_H_CPU0_SA_DQ<11>")
	)
	(segment
		(start 429.660304 -310.781446)
		(end 428.697898 -311.743852)
		(width 0.18288)
		(layer "In11.Cu")
		(net "M_H_CPU0_SA_DQ<11>")
	)
	(segment
		(start 408.568398 -311.029604)
		(end 407.62682 -310.088026)
		(width 0.18288)
		(layer "In11.Cu")
		(net "M_H_CPU0_SA_DQ<11>")
	)
	(segment
		(start 443.596776 -310.003444)
		(end 443.07633 -310.21909)
		(width 0.18288)
		(layer "In11.Cu")
		(net "M_H_CPU0_SA_DQ<11>")
	)
	(segment
		(start 373.600218 -278.66086)
		(end 373.591328 -278.65578)
		(width 0.088646)
		(layer "In11.Cu")
		(net "M_H_CPU0_SA_DQ<11>")
	)
	(segment
		(start 439.33999 -312.49493)
		(end 438.634886 -311.789826)
		(width 0.18288)
		(layer "In11.Cu")
		(net "M_H_CPU0_SA_DQ<11>")
	)
	(segment
		(start 385.630166 -283.219906)
		(end 385.630166 -283.205682)
		(width 0.088646)
		(layer "In11.Cu")
		(net "M_H_CPU0_SA_DQ<11>")
	)
	(segment
		(start 450.511926 -304.65903)
		(end 449.57619 -304.65903)
		(width 0.18288)
		(layer "In11.Cu")
		(net "M_H_CPU0_SA_DQ<11>")
	)
	(segment
		(start 416.015678 -310.099964)
		(end 413.228028 -310.099964)
		(width 0.18288)
		(layer "In11.Cu")
		(net "M_H_CPU0_SA_DQ<11>")
	)
	(segment
		(start 421.21074 -313.149488)
		(end 421.016684 -313.343544)
		(width 0.18288)
		(layer "In11.Cu")
		(net "M_H_CPU0_SA_DQ<11>")
	)
	(segment
		(start 443.07633 -310.21909)
		(end 441.169044 -312.126376)
		(width 0.18288)
		(layer "In11.Cu")
		(net "M_H_CPU0_SA_DQ<11>")
	)
	(segment
		(start 379.623828 -280.282396)
		(end 379.613414 -280.288492)
		(width 0.088646)
		(layer "In11.Cu")
		(net "M_H_CPU0_SA_DQ<11>")
	)
	(arc
		(start 378.299218 -280.288492)
		(mid 378.024989 -280.212567)
		(end 377.748546 -280.279856)
		(width 0.088646)
		(layer "In11.Cu")
		(net "M_H_CPU0_SA_DQ<11>")
	)
	(arc
		(start 381.118618 -280.288492)
		(mid 380.841805 -280.212656)
		(end 380.563374 -280.282396)
		(width 0.088646)
		(layer "In11.Cu")
		(net "M_H_CPU0_SA_DQ<11>")
	)
	(arc
		(start 373.121428 -277.84171)
		(mid 372.942831 -277.522432)
		(end 373.121428 -277.203154)
		(width 0.088646)
		(layer "In11.Cu")
		(net "M_H_CPU0_SA_DQ<11>")
	)
	(arc
		(start 382.99771 -280.288492)
		(mid 382.715262 -280.212877)
		(end 382.432814 -280.288492)
		(width 0.088646)
		(layer "In11.Cu")
		(net "M_H_CPU0_SA_DQ<11>")
	)
	(arc
		(start 378.673614 -280.288492)
		(mid 378.486416 -280.338635)
		(end 378.299218 -280.288492)
		(width 0.088646)
		(layer "In11.Cu")
		(net "M_H_CPU0_SA_DQ<11>")
	)
	(arc
		(start 373.412766 -278.31796)
		(mid 373.332604 -278.045771)
		(end 373.130318 -277.84679)
		(width 0.088646)
		(layer "In11.Cu")
		(net "M_H_CPU0_SA_DQ<11>")
	)
	(arc
		(start 375.38406 -279.474676)
		(mid 375.196862 -279.524819)
		(end 375.009664 -279.474676)
		(width 0.088646)
		(layer "In11.Cu")
		(net "M_H_CPU0_SA_DQ<11>")
	)
	(arc
		(start 376.410728 -280.283412)
		(mid 376.279814 -280.147052)
		(end 376.232166 -279.964134)
		(width 0.088646)
		(layer "In11.Cu")
		(net "M_H_CPU0_SA_DQ<11>")
	)
	(arc
		(start 383.928874 -281.911298)
		(mid 383.79796 -281.774938)
		(end 383.750312 -281.59202)
		(width 0.088646)
		(layer "In11.Cu")
		(net "M_H_CPU0_SA_DQ<11>")
	)
	(arc
		(start 382.432814 -280.288492)
		(mid 382.245616 -280.338635)
		(end 382.058418 -280.288492)
		(width 0.088646)
		(layer "In11.Cu")
		(net "M_H_CPU0_SA_DQ<11>")
	)
	(arc
		(start 383.750312 -281.582114)
		(mid 383.672201 -281.305165)
		(end 383.467864 -281.102562)
		(width 0.088646)
		(layer "In11.Cu")
		(net "M_H_CPU0_SA_DQ<11>")
	)
	(arc
		(start 381.493014 -280.288492)
		(mid 381.305816 -280.338635)
		(end 381.118618 -280.288492)
		(width 0.088646)
		(layer "In11.Cu")
		(net "M_H_CPU0_SA_DQ<11>")
	)
	(arc
		(start 386.874004 -285.261812)
		(mid 386.818413 -285.213003)
		(end 386.75691 -285.171896)
		(width 0.088646)
		(layer "In11.Cu")
		(net "M_H_CPU0_SA_DQ<11>")
	)
	(arc
		(start 375.009664 -279.474676)
		(mid 374.726962 -279.3989)
		(end 374.44426 -279.474676)
		(width 0.088646)
		(layer "In11.Cu")
		(net "M_H_CPU0_SA_DQ<11>")
	)
	(arc
		(start 383.458974 -281.097482)
		(mid 383.32806 -280.961122)
		(end 383.280412 -280.778204)
		(width 0.088646)
		(layer "In11.Cu")
		(net "M_H_CPU0_SA_DQ<11>")
	)
	(arc
		(start 376.232166 -279.964134)
		(mid 376.158175 -279.684568)
		(end 375.95556 -279.478232)
		(width 0.088646)
		(layer "In11.Cu")
		(net "M_H_CPU0_SA_DQ<11>")
	)
	(arc
		(start 382.058418 -280.288492)
		(mid 381.784189 -280.212567)
		(end 381.507746 -280.279856)
		(width 0.088646)
		(layer "In11.Cu")
		(net "M_H_CPU0_SA_DQ<11>")
	)
	(arc
		(start 373.591328 -278.65578)
		(mid 373.460414 -278.51942)
		(end 373.412766 -278.336502)
		(width 0.088646)
		(layer "In11.Cu")
		(net "M_H_CPU0_SA_DQ<11>")
	)
	(arc
		(start 373.130318 -277.198074)
		(mid 373.372204 -276.918748)
		(end 373.389906 -276.549612)
		(width 0.088646)
		(layer "In11.Cu")
		(net "M_H_CPU0_SA_DQ<11>")
	)
	(arc
		(start 383.280412 -280.76398)
		(mid 383.201193 -280.489295)
		(end 382.99771 -280.288492)
		(width 0.088646)
		(layer "In11.Cu")
		(net "M_H_CPU0_SA_DQ<11>")
	)
	(arc
		(start 385.808728 -283.539184)
		(mid 385.677814 -283.402824)
		(end 385.630166 -283.219906)
		(width 0.088646)
		(layer "In11.Cu")
		(net "M_H_CPU0_SA_DQ<11>")
	)
	(arc
		(start 379.613414 -280.288492)
		(mid 379.426216 -280.338635)
		(end 379.239018 -280.288492)
		(width 0.088646)
		(layer "In11.Cu")
		(net "M_H_CPU0_SA_DQ<11>")
	)
	(arc
		(start 374.44426 -279.474676)
		(mid 374.257062 -279.524819)
		(end 374.069864 -279.474676)
		(width 0.088646)
		(layer "In11.Cu")
		(net "M_H_CPU0_SA_DQ<11>")
	)
	(arc
		(start 380.55296 -280.288492)
		(mid 380.365762 -280.338635)
		(end 380.178564 -280.288492)
		(width 0.088646)
		(layer "In11.Cu")
		(net "M_H_CPU0_SA_DQ<11>")
	)
	(arc
		(start 375.934732 -279.46604)
		(mid 375.658257 -279.39872)
		(end 375.38406 -279.474676)
		(width 0.088646)
		(layer "In11.Cu")
		(net "M_H_CPU0_SA_DQ<11>")
	)
	(arc
		(start 386.75691 -285.171896)
		(mid 386.621977 -285.038542)
		(end 386.569712 -284.856174)
		(width 0.088646)
		(layer "In11.Cu")
		(net "M_H_CPU0_SA_DQ<11>")
	)
	(arc
		(start 385.630166 -283.205682)
		(mid 385.550947 -282.930997)
		(end 385.347464 -282.730194)
		(width 0.088646)
		(layer "In11.Cu")
		(net "M_H_CPU0_SA_DQ<11>")
	)
	(arc
		(start 373.882412 -279.134824)
		(mid 373.803042 -278.86109)
		(end 373.600218 -278.66086)
		(width 0.088646)
		(layer "In11.Cu")
		(net "M_H_CPU0_SA_DQ<11>")
	)
	(arc
		(start 384.31216 -281.916378)
		(mid 384.124962 -281.966521)
		(end 383.937764 -281.916378)
		(width 0.088646)
		(layer "In11.Cu")
		(net "M_H_CPU0_SA_DQ<11>")
	)
	(arc
		(start 379.239018 -280.288492)
		(mid 378.964789 -280.212567)
		(end 378.688346 -280.279856)
		(width 0.088646)
		(layer "In11.Cu")
		(net "M_H_CPU0_SA_DQ<11>")
	)
	(arc
		(start 386.099812 -284.018228)
		(mid 386.020442 -283.744494)
		(end 385.817618 -283.544264)
		(width 0.088646)
		(layer "In11.Cu")
		(net "M_H_CPU0_SA_DQ<11>")
	)
	(arc
		(start 377.359418 -280.288492)
		(mid 377.085189 -280.212567)
		(end 376.808746 -280.279856)
		(width 0.088646)
		(layer "In11.Cu")
		(net "M_H_CPU0_SA_DQ<11>")
	)
	(arc
		(start 386.569712 -284.832044)
		(mid 386.490263 -284.558248)
		(end 386.287264 -284.35808)
		(width 0.088646)
		(layer "In11.Cu")
		(net "M_H_CPU0_SA_DQ<11>")
	)
	(arc
		(start 385.160012 -282.39593)
		(mid 385.081901 -282.118981)
		(end 384.877564 -281.916378)
		(width 0.088646)
		(layer "In11.Cu")
		(net "M_H_CPU0_SA_DQ<11>")
	)
	(arc
		(start 384.877564 -281.916378)
		(mid 384.594862 -281.840602)
		(end 384.31216 -281.916378)
		(width 0.088646)
		(layer "In11.Cu")
		(net "M_H_CPU0_SA_DQ<11>")
	)
	(arc
		(start 377.733814 -280.288492)
		(mid 377.546616 -280.338635)
		(end 377.359418 -280.288492)
		(width 0.088646)
		(layer "In11.Cu")
		(net "M_H_CPU0_SA_DQ<11>")
	)
	(arc
		(start 386.278374 -284.353)
		(mid 386.14746 -284.21664)
		(end 386.099812 -284.033722)
		(width 0.088646)
		(layer "In11.Cu")
		(net "M_H_CPU0_SA_DQ<11>")
	)
	(arc
		(start 374.060974 -279.469596)
		(mid 373.93006 -279.333236)
		(end 373.882412 -279.150318)
		(width 0.088646)
		(layer "In11.Cu")
		(net "M_H_CPU0_SA_DQ<11>")
	)
	(arc
		(start 376.794014 -280.288492)
		(mid 376.606816 -280.338635)
		(end 376.419618 -280.288492)
		(width 0.088646)
		(layer "In11.Cu")
		(net "M_H_CPU0_SA_DQ<11>")
	)
	(arc
		(start 380.178564 -280.288492)
		(mid 379.902005 -280.212783)
		(end 379.623828 -280.282396)
		(width 0.088646)
		(layer "In11.Cu")
		(net "M_H_CPU0_SA_DQ<11>")
	)
	(arc
		(start 385.338574 -282.725114)
		(mid 385.20766 -282.588754)
		(end 385.160012 -282.405836)
		(width 0.088646)
		(layer "In11.Cu")
		(net "M_H_CPU0_SA_DQ<11>")
	)
	(segment
		(start 461.455516 -306.349908)
		(end 461.455516 -306.098956)
		(width 0.20066)
		(layer "F.Cu")
		(net "M_H_CPU0_SA_DQ<10>")
	)
	(segment
		(start 457.814426 -306.116736)
		(end 458.24648 -306.54879)
		(width 0.20066)
		(layer "F.Cu")
		(net "M_H_CPU0_SA_DQ<10>")
	)
	(segment
		(start 455.011282 -306.116736)
		(end 456.116182 -306.116736)
		(width 0.20066)
		(layer "F.Cu")
		(net "M_H_CPU0_SA_DQ<10>")
	)
	(segment
		(start 462.073752 -305.864768)
		(end 462.32572 -306.116736)
		(width 0.20066)
		(layer "F.Cu")
		(net "M_H_CPU0_SA_DQ<10>")
	)
	(segment
		(start 458.543152 -306.54879)
		(end 458.550264 -306.541678)
		(width 0.1016)
		(layer "F.Cu")
		(net "M_H_CPU0_SA_DQ<10>")
	)
	(segment
		(start 460.570326 -306.55387)
		(end 461.251554 -306.55387)
		(width 0.20066)
		(layer "F.Cu")
		(net "M_H_CPU0_SA_DQ<10>")
	)
	(segment
		(start 461.455516 -306.098956)
		(end 461.689704 -305.864768)
		(width 0.20066)
		(layer "F.Cu")
		(net "M_H_CPU0_SA_DQ<10>")
	)
	(segment
		(start 458.538326 -306.54879)
		(end 458.543152 -306.54879)
		(width 0.101854)
		(layer "F.Cu")
		(net "M_H_CPU0_SA_DQ<10>")
	)
	(segment
		(start 461.689704 -305.864768)
		(end 462.073752 -305.864768)
		(width 0.20066)
		(layer "F.Cu")
		(net "M_H_CPU0_SA_DQ<10>")
	)
	(segment
		(start 460.558134 -306.541678)
		(end 460.570326 -306.55387)
		(width 0.1016)
		(layer "F.Cu")
		(net "M_H_CPU0_SA_DQ<10>")
	)
	(segment
		(start 458.24648 -306.54879)
		(end 458.538326 -306.54879)
		(width 0.20066)
		(layer "F.Cu")
		(net "M_H_CPU0_SA_DQ<10>")
	)
	(segment
		(start 458.550264 -306.541678)
		(end 460.558134 -306.541678)
		(width 0.1016)
		(layer "F.Cu")
		(net "M_H_CPU0_SA_DQ<10>")
	)
	(segment
		(start 462.32572 -306.116736)
		(end 463.659982 -306.116736)
		(width 0.20066)
		(layer "F.Cu")
		(net "M_H_CPU0_SA_DQ<10>")
	)
	(segment
		(start 456.116182 -306.116736)
		(end 457.814426 -306.116736)
		(width 0.20066)
		(layer "F.Cu")
		(net "M_H_CPU0_SA_DQ<10>")
	)
	(segment
		(start 372.847362 -276.172676)
		(end 372.847616 -276.708616)
		(width 0.20066)
		(layer "F.Cu")
		(net "M_H_CPU0_SA_DQ<10>")
	)
	(segment
		(start 461.251554 -306.55387)
		(end 461.455516 -306.349908)
		(width 0.20066)
		(layer "F.Cu")
		(net "M_H_CPU0_SA_DQ<10>")
	)
	(segment
		(start 372.534688 -276.708616)
		(end 372.847616 -276.708616)
		(width 0.088646)
		(layer "In11.Cu")
		(net "M_H_CPU0_SA_DQ<10>")
	)
	(segment
		(start 442.53785 -313.529472)
		(end 440.937396 -314.192412)
		(width 0.18288)
		(layer "In11.Cu")
		(net "M_H_CPU0_SA_DQ<10>")
	)
	(segment
		(start 429.810672 -312.942986)
		(end 427.202346 -313.440826)
		(width 0.18288)
		(layer "In11.Cu")
		(net "M_H_CPU0_SA_DQ<10>")
	)
	(segment
		(start 450.1388 -307.239924)
		(end 447.620898 -309.757826)
		(width 0.18288)
		(layer "In11.Cu")
		(net "M_H_CPU0_SA_DQ<10>")
	)
	(segment
		(start 454.164446 -306.508404)
		(end 453.034908 -306.705254)
		(width 0.18288)
		(layer "In11.Cu")
		(net "M_H_CPU0_SA_DQ<10>")
	)
	(segment
		(start 447.620898 -309.757826)
		(end 447.454274 -309.757826)
		(width 0.18288)
		(layer "In11.Cu")
		(net "M_H_CPU0_SA_DQ<10>")
	)
	(segment
		(start 373.13616 -279.478232)
		(end 373.130064 -279.474676)
		(width 0.088646)
		(layer "In11.Cu")
		(net "M_H_CPU0_SA_DQ<10>")
	)
	(segment
		(start 454.692512 -306.25669)
		(end 454.164446 -306.508404)
		(width 0.18288)
		(layer "In11.Cu")
		(net "M_H_CPU0_SA_DQ<10>")
	)
	(segment
		(start 372.190264 -277.198074)
		(end 372.193058 -277.19655)
		(width 0.088646)
		(layer "In11.Cu")
		(net "M_H_CPU0_SA_DQ<10>")
	)
	(segment
		(start 385.35356 -284.361636)
		(end 385.347464 -284.35808)
		(width 0.088646)
		(layer "In11.Cu")
		(net "M_H_CPU0_SA_DQ<10>")
	)
	(segment
		(start 380.648464 -281.102562)
		(end 380.633732 -281.093926)
		(width 0.088646)
		(layer "In11.Cu")
		(net "M_H_CPU0_SA_DQ<10>")
	)
	(segment
		(start 434.80101 -312.297318)
		(end 432.298094 -312.297318)
		(width 0.18288)
		(layer "In11.Cu")
		(net "M_H_CPU0_SA_DQ<10>")
	)
	(segment
		(start 432.298094 -312.297318)
		(end 431.500026 -312.549794)
		(width 0.18288)
		(layer "In11.Cu")
		(net "M_H_CPU0_SA_DQ<10>")
	)
	(segment
		(start 442.818266 -313.342274)
		(end 442.53785 -313.529472)
		(width 0.18288)
		(layer "In11.Cu")
		(net "M_H_CPU0_SA_DQ<10>")
	)
	(segment
		(start 421.207184 -315.042804)
		(end 420.220394 -315.042804)
		(width 0.18288)
		(layer "In11.Cu")
		(net "M_H_CPU0_SA_DQ<10>")
	)
	(segment
		(start 414.702498 -312.793634)
		(end 413.531812 -312.360056)
		(width 0.18288)
		(layer "In11.Cu")
		(net "M_H_CPU0_SA_DQ<10>")
	)
	(segment
		(start 386.596636 -286.370014)
		(end 386.596636 -286.267652)
		(width 0.088646)
		(layer "In11.Cu")
		(net "M_H_CPU0_SA_DQ<10>")
	)
	(segment
		(start 435.242208 -313.165998)
		(end 435.242208 -312.7375)
		(width 0.18288)
		(layer "In11.Cu")
		(net "M_H_CPU0_SA_DQ<10>")
	)
	(segment
		(start 374.924574 -280.282396)
		(end 374.91416 -280.288492)
		(width 0.088646)
		(layer "In11.Cu")
		(net "M_H_CPU0_SA_DQ<10>")
	)
	(segment
		(start 447.454274 -309.757826)
		(end 446.213992 -310.998108)
		(width 0.18288)
		(layer "In11.Cu")
		(net "M_H_CPU0_SA_DQ<10>")
	)
	(segment
		(start 372.472966 -278.336502)
		(end 372.472966 -278.322278)
		(width 0.088646)
		(layer "In11.Cu")
		(net "M_H_CPU0_SA_DQ<10>")
	)
	(segment
		(start 384.690366 -283.219906)
		(end 384.690366 -283.212286)
		(width 0.088646)
		(layer "In11.Cu")
		(net "M_H_CPU0_SA_DQ<10>")
	)
	(segment
		(start 382.53416 -281.106118)
		(end 382.528064 -281.102562)
		(width 0.088646)
		(layer "In11.Cu")
		(net "M_H_CPU0_SA_DQ<10>")
	)
	(segment
		(start 420.220394 -315.042804)
		(end 420.040562 -315.222636)
		(width 0.18288)
		(layer "In11.Cu")
		(net "M_H_CPU0_SA_DQ<10>")
	)
	(segment
		(start 383.280666 -282.414472)
		(end 383.280666 -282.405836)
		(width 0.088646)
		(layer "In11.Cu")
		(net "M_H_CPU0_SA_DQ<10>")
	)
	(segment
		(start 414.70326 -312.79338)
		(end 414.702498 -312.793634)
		(width 0.18288)
		(layer "In11.Cu")
		(net "M_H_CPU0_SA_DQ<10>")
	)
	(segment
		(start 382.528064 -281.102562)
		(end 382.513332 -281.093926)
		(width 0.088646)
		(layer "In11.Cu")
		(net "M_H_CPU0_SA_DQ<10>")
	)
	(segment
		(start 454.996804 -306.111656)
		(end 454.692512 -306.25669)
		(width 0.18288)
		(layer "In11.Cu")
		(net "M_H_CPU0_SA_DQ<10>")
	)
	(segment
		(start 445.975486 -311.573926)
		(end 445.802004 -311.747408)
		(width 0.18288)
		(layer "In11.Cu")
		(net "M_H_CPU0_SA_DQ<10>")
	)
	(segment
		(start 437.263286 -313.343544)
		(end 435.419754 -313.343544)
		(width 0.18288)
		(layer "In11.Cu")
		(net "M_H_CPU0_SA_DQ<10>")
	)
	(segment
		(start 378.768864 -281.102562)
		(end 378.754132 -281.093926)
		(width 0.088646)
		(layer "In11.Cu")
		(net "M_H_CPU0_SA_DQ<10>")
	)
	(segment
		(start 382.810766 -281.600656)
		(end 382.810766 -281.59202)
		(width 0.088646)
		(layer "In11.Cu")
		(net "M_H_CPU0_SA_DQ<10>")
	)
	(segment
		(start 376.889264 -281.102562)
		(end 376.874532 -281.093926)
		(width 0.088646)
		(layer "In11.Cu")
		(net "M_H_CPU0_SA_DQ<10>")
	)
	(segment
		(start 384.877818 -283.544264)
		(end 384.868928 -283.539184)
		(width 0.088646)
		(layer "In11.Cu")
		(net "M_H_CPU0_SA_DQ<10>")
	)
	(segment
		(start 372.469156 -276.774148)
		(end 372.534688 -276.708616)
		(width 0.088646)
		(layer "In11.Cu")
		(net "M_H_CPU0_SA_DQ<10>")
	)
	(segment
		(start 435.419754 -313.343544)
		(end 435.242208 -313.165998)
		(width 0.18288)
		(layer "In11.Cu")
		(net "M_H_CPU0_SA_DQ<10>")
	)
	(segment
		(start 406.188164 -312.360056)
		(end 400.120612 -306.292504)
		(width 0.18288)
		(layer "In11.Cu")
		(net "M_H_CPU0_SA_DQ<10>")
	)
	(segment
		(start 372.193058 -277.19655)
		(end 372.19636 -277.194518)
		(width 0.088646)
		(layer "In11.Cu")
		(net "M_H_CPU0_SA_DQ<10>")
	)
	(segment
		(start 450.440552 -306.54244)
		(end 450.1388 -306.844192)
		(width 0.18288)
		(layer "In11.Cu")
		(net "M_H_CPU0_SA_DQ<10>")
	)
	(segment
		(start 372.942612 -279.150318)
		(end 372.942612 -279.134824)
		(width 0.088646)
		(layer "In11.Cu")
		(net "M_H_CPU0_SA_DQ<10>")
	)
	(segment
		(start 372.190264 -277.84679)
		(end 372.181374 -277.84171)
		(width 0.088646)
		(layer "In11.Cu")
		(net "M_H_CPU0_SA_DQ<10>")
	)
	(segment
		(start 438.403492 -313.10199)
		(end 437.50484 -313.10199)
		(width 0.18288)
		(layer "In11.Cu")
		(net "M_H_CPU0_SA_DQ<10>")
	)
	(segment
		(start 420.040562 -315.222636)
		(end 419.339268 -315.222636)
		(width 0.18288)
		(layer "In11.Cu")
		(net "M_H_CPU0_SA_DQ<10>")
	)
	(segment
		(start 377.829064 -281.102562)
		(end 377.814332 -281.093926)
		(width 0.088646)
		(layer "In11.Cu")
		(net "M_H_CPU0_SA_DQ<10>")
	)
	(segment
		(start 426.278294 -313.440826)
		(end 425.526454 -314.192666)
		(width 0.18288)
		(layer "In11.Cu")
		(net "M_H_CPU0_SA_DQ<10>")
	)
	(segment
		(start 386.596636 -286.267652)
		(end 386.404612 -286.075628)
		(width 0.088646)
		(layer "In11.Cu")
		(net "M_H_CPU0_SA_DQ<10>")
	)
	(segment
		(start 386.287264 -285.985712)
		(end 386.278374 -285.980632)
		(width 0.088646)
		(layer "In11.Cu")
		(net "M_H_CPU0_SA_DQ<10>")
	)
	(segment
		(start 417.492434 -313.826398)
		(end 414.70326 -312.79338)
		(width 0.18288)
		(layer "In11.Cu")
		(net "M_H_CPU0_SA_DQ<10>")
	)
	(segment
		(start 427.202346 -313.440826)
		(end 426.278294 -313.440826)
		(width 0.18288)
		(layer "In11.Cu")
		(net "M_H_CPU0_SA_DQ<10>")
	)
	(segment
		(start 413.531812 -312.360056)
		(end 406.188164 -312.360056)
		(width 0.18288)
		(layer "In11.Cu")
		(net "M_H_CPU0_SA_DQ<10>")
	)
	(segment
		(start 425.526454 -314.192666)
		(end 423.646346 -314.192666)
		(width 0.18288)
		(layer "In11.Cu")
		(net "M_H_CPU0_SA_DQ<10>")
	)
	(segment
		(start 373.600218 -280.288492)
		(end 373.591328 -280.283412)
		(width 0.088646)
		(layer "In11.Cu")
		(net "M_H_CPU0_SA_DQ<10>")
	)
	(segment
		(start 372.181374 -277.203154)
		(end 372.190264 -277.198074)
		(width 0.088646)
		(layer "In11.Cu")
		(net "M_H_CPU0_SA_DQ<10>")
	)
	(segment
		(start 423.461942 -314.37707)
		(end 421.872918 -314.37707)
		(width 0.18288)
		(layer "In11.Cu")
		(net "M_H_CPU0_SA_DQ<10>")
	)
	(segment
		(start 437.50484 -313.10199)
		(end 437.263286 -313.343544)
		(width 0.18288)
		(layer "In11.Cu")
		(net "M_H_CPU0_SA_DQ<10>")
	)
	(segment
		(start 423.646346 -314.192666)
		(end 423.461942 -314.37707)
		(width 0.18288)
		(layer "In11.Cu")
		(net "M_H_CPU0_SA_DQ<10>")
	)
	(segment
		(start 400.120612 -301.323502)
		(end 391.4394 -292.64229)
		(width 0.18288)
		(layer "In11.Cu")
		(net "M_H_CPU0_SA_DQ<10>")
	)
	(segment
		(start 383.00406 -281.919934)
		(end 382.997964 -281.916378)
		(width 0.088646)
		(layer "In11.Cu")
		(net "M_H_CPU0_SA_DQ<10>")
	)
	(segment
		(start 440.937396 -314.192412)
		(end 439.493914 -314.192412)
		(width 0.18288)
		(layer "In11.Cu")
		(net "M_H_CPU0_SA_DQ<10>")
	)
	(segment
		(start 455.011282 -306.116736)
		(end 454.996804 -306.111656)
		(width 0.18288)
		(layer "In11.Cu")
		(net "M_H_CPU0_SA_DQ<10>")
	)
	(segment
		(start 430.203864 -312.549794)
		(end 429.810672 -312.942986)
		(width 0.18288)
		(layer "In11.Cu")
		(net "M_H_CPU0_SA_DQ<10>")
	)
	(segment
		(start 373.130064 -279.474676)
		(end 373.121174 -279.469596)
		(width 0.088646)
		(layer "In11.Cu")
		(net "M_H_CPU0_SA_DQ<10>")
	)
	(segment
		(start 385.347464 -284.35808)
		(end 385.338574 -284.353)
		(width 0.088646)
		(layer "In11.Cu")
		(net "M_H_CPU0_SA_DQ<10>")
	)
	(segment
		(start 385.817618 -285.171896)
		(end 385.808728 -285.166816)
		(width 0.088646)
		(layer "In11.Cu")
		(net "M_H_CPU0_SA_DQ<10>")
	)
	(segment
		(start 375.949464 -281.102562)
		(end 375.940574 -281.097482)
		(width 0.088646)
		(layer "In11.Cu")
		(net "M_H_CPU0_SA_DQ<10>")
	)
	(segment
		(start 386.099812 -285.661354)
		(end 386.099812 -285.64586)
		(width 0.088646)
		(layer "In11.Cu")
		(net "M_H_CPU0_SA_DQ<10>")
	)
	(segment
		(start 372.660418 -278.66086)
		(end 372.651528 -278.65578)
		(width 0.088646)
		(layer "In11.Cu")
		(net "M_H_CPU0_SA_DQ<10>")
	)
	(segment
		(start 374.539764 -280.288492)
		(end 374.52935 -280.282396)
		(width 0.088646)
		(layer "In11.Cu")
		(net "M_H_CPU0_SA_DQ<10>")
	)
	(segment
		(start 439.493914 -314.192412)
		(end 438.403492 -313.10199)
		(width 0.18288)
		(layer "In11.Cu")
		(net "M_H_CPU0_SA_DQ<10>")
	)
	(segment
		(start 450.1388 -306.844192)
		(end 450.1388 -307.239924)
		(width 0.18288)
		(layer "In11.Cu")
		(net "M_H_CPU0_SA_DQ<10>")
	)
	(segment
		(start 421.872918 -314.37707)
		(end 421.207184 -315.042804)
		(width 0.18288)
		(layer "In11.Cu")
		(net "M_H_CPU0_SA_DQ<10>")
	)
	(segment
		(start 391.4394 -292.64229)
		(end 391.4394 -291.212778)
		(width 0.18288)
		(layer "In11.Cu")
		(net "M_H_CPU0_SA_DQ<10>")
	)
	(segment
		(start 379.708664 -281.102562)
		(end 379.693932 -281.093926)
		(width 0.088646)
		(layer "In11.Cu")
		(net "M_H_CPU0_SA_DQ<10>")
	)
	(segment
		(start 446.213992 -310.998108)
		(end 445.975486 -311.573926)
		(width 0.18288)
		(layer "In11.Cu")
		(net "M_H_CPU0_SA_DQ<10>")
	)
	(segment
		(start 435.242208 -312.7375)
		(end 434.80228 -312.297572)
		(width 0.18288)
		(layer "In11.Cu")
		(net "M_H_CPU0_SA_DQ<10>")
	)
	(segment
		(start 419.339268 -315.222636)
		(end 417.492434 -313.826398)
		(width 0.18288)
		(layer "In11.Cu")
		(net "M_H_CPU0_SA_DQ<10>")
	)
	(segment
		(start 431.500026 -312.549794)
		(end 430.203864 -312.549794)
		(width 0.18288)
		(layer "In11.Cu")
		(net "M_H_CPU0_SA_DQ<10>")
	)
	(segment
		(start 375.762012 -280.778204)
		(end 375.762012 -280.756106)
		(width 0.088646)
		(layer "In11.Cu")
		(net "M_H_CPU0_SA_DQ<10>")
	)
	(segment
		(start 386.943092 -286.71647)
		(end 386.596636 -286.370014)
		(width 0.088646)
		(layer "In11.Cu")
		(net "M_H_CPU0_SA_DQ<10>")
	)
	(segment
		(start 434.80228 -312.297572)
		(end 434.80101 -312.297318)
		(width 0.18288)
		(layer "In11.Cu")
		(net "M_H_CPU0_SA_DQ<10>")
	)
	(segment
		(start 453.034908 -306.705254)
		(end 451.856094 -306.54244)
		(width 0.18288)
		(layer "In11.Cu")
		(net "M_H_CPU0_SA_DQ<10>")
	)
	(segment
		(start 445.802004 -311.747408)
		(end 442.818266 -313.342274)
		(width 0.18288)
		(layer "In11.Cu")
		(net "M_H_CPU0_SA_DQ<10>")
	)
	(segment
		(start 391.4394 -291.212778)
		(end 386.943092 -286.71647)
		(width 0.18288)
		(layer "In11.Cu")
		(net "M_H_CPU0_SA_DQ<10>")
	)
	(segment
		(start 381.588264 -281.102562)
		(end 381.573532 -281.093926)
		(width 0.088646)
		(layer "In11.Cu")
		(net "M_H_CPU0_SA_DQ<10>")
	)
	(segment
		(start 451.856094 -306.54244)
		(end 450.440552 -306.54244)
		(width 0.18288)
		(layer "In11.Cu")
		(net "M_H_CPU0_SA_DQ<10>")
	)
	(segment
		(start 385.160012 -284.033722)
		(end 385.160012 -284.018228)
		(width 0.088646)
		(layer "In11.Cu")
		(net "M_H_CPU0_SA_DQ<10>")
	)
	(segment
		(start 400.120612 -306.292504)
		(end 400.120612 -301.323502)
		(width 0.18288)
		(layer "In11.Cu")
		(net "M_H_CPU0_SA_DQ<10>")
	)
	(arc
		(start 379.14326 -281.102562)
		(mid 378.956062 -281.152705)
		(end 378.768864 -281.102562)
		(width 0.088646)
		(layer "In11.Cu")
		(net "M_H_CPU0_SA_DQ<10>")
	)
	(arc
		(start 380.08306 -281.102562)
		(mid 379.895862 -281.152705)
		(end 379.708664 -281.102562)
		(width 0.088646)
		(layer "In11.Cu")
		(net "M_H_CPU0_SA_DQ<10>")
	)
	(arc
		(start 376.32386 -281.102562)
		(mid 376.136662 -281.152705)
		(end 375.949464 -281.102562)
		(width 0.088646)
		(layer "In11.Cu")
		(net "M_H_CPU0_SA_DQ<10>")
	)
	(arc
		(start 372.942612 -279.134824)
		(mid 372.863242 -278.86109)
		(end 372.660418 -278.66086)
		(width 0.088646)
		(layer "In11.Cu")
		(net "M_H_CPU0_SA_DQ<10>")
	)
	(arc
		(start 376.874532 -281.093926)
		(mid 376.598057 -281.026606)
		(end 376.32386 -281.102562)
		(width 0.088646)
		(layer "In11.Cu")
		(net "M_H_CPU0_SA_DQ<10>")
	)
	(arc
		(start 373.591328 -280.283412)
		(mid 373.460414 -280.147052)
		(end 373.412766 -279.964134)
		(width 0.088646)
		(layer "In11.Cu")
		(net "M_H_CPU0_SA_DQ<10>")
	)
	(arc
		(start 372.19636 -277.194518)
		(mid 372.381883 -277.016217)
		(end 372.469156 -276.774148)
		(width 0.088646)
		(layer "In11.Cu")
		(net "M_H_CPU0_SA_DQ<10>")
	)
	(arc
		(start 386.278374 -285.980632)
		(mid 386.14746 -285.844272)
		(end 386.099812 -285.661354)
		(width 0.088646)
		(layer "In11.Cu")
		(net "M_H_CPU0_SA_DQ<10>")
	)
	(arc
		(start 375.762012 -280.756106)
		(mid 375.681101 -280.485978)
		(end 375.479818 -280.288492)
		(width 0.088646)
		(layer "In11.Cu")
		(net "M_H_CPU0_SA_DQ<10>")
	)
	(arc
		(start 383.280666 -282.405836)
		(mid 383.206675 -282.12627)
		(end 383.00406 -281.919934)
		(width 0.088646)
		(layer "In11.Cu")
		(net "M_H_CPU0_SA_DQ<10>")
	)
	(arc
		(start 375.940574 -281.097482)
		(mid 375.80966 -280.961122)
		(end 375.762012 -280.778204)
		(width 0.088646)
		(layer "In11.Cu")
		(net "M_H_CPU0_SA_DQ<10>")
	)
	(arc
		(start 385.808728 -285.166816)
		(mid 385.677814 -285.030456)
		(end 385.630166 -284.847538)
		(width 0.088646)
		(layer "In11.Cu")
		(net "M_H_CPU0_SA_DQ<10>")
	)
	(arc
		(start 380.633732 -281.093926)
		(mid 380.357257 -281.026606)
		(end 380.08306 -281.102562)
		(width 0.088646)
		(layer "In11.Cu")
		(net "M_H_CPU0_SA_DQ<10>")
	)
	(arc
		(start 378.754132 -281.093926)
		(mid 378.477657 -281.026606)
		(end 378.20346 -281.102562)
		(width 0.088646)
		(layer "In11.Cu")
		(net "M_H_CPU0_SA_DQ<10>")
	)
	(arc
		(start 377.26366 -281.102562)
		(mid 377.076462 -281.152705)
		(end 376.889264 -281.102562)
		(width 0.088646)
		(layer "In11.Cu")
		(net "M_H_CPU0_SA_DQ<10>")
	)
	(arc
		(start 377.814332 -281.093926)
		(mid 377.537857 -281.026606)
		(end 377.26366 -281.102562)
		(width 0.088646)
		(layer "In11.Cu")
		(net "M_H_CPU0_SA_DQ<10>")
	)
	(arc
		(start 373.974614 -280.288492)
		(mid 373.787416 -280.338635)
		(end 373.600218 -280.288492)
		(width 0.088646)
		(layer "In11.Cu")
		(net "M_H_CPU0_SA_DQ<10>")
	)
	(arc
		(start 381.573532 -281.093926)
		(mid 381.297057 -281.026606)
		(end 381.02286 -281.102562)
		(width 0.088646)
		(layer "In11.Cu")
		(net "M_H_CPU0_SA_DQ<10>")
	)
	(arc
		(start 381.96266 -281.102562)
		(mid 381.775462 -281.152705)
		(end 381.588264 -281.102562)
		(width 0.088646)
		(layer "In11.Cu")
		(net "M_H_CPU0_SA_DQ<10>")
	)
	(arc
		(start 384.690366 -283.212286)
		(mid 384.612737 -282.933873)
		(end 384.407664 -282.730194)
		(width 0.088646)
		(layer "In11.Cu")
		(net "M_H_CPU0_SA_DQ<10>")
	)
	(arc
		(start 383.467864 -282.730194)
		(mid 383.332931 -282.59684)
		(end 383.280666 -282.414472)
		(width 0.088646)
		(layer "In11.Cu")
		(net "M_H_CPU0_SA_DQ<10>")
	)
	(arc
		(start 385.338574 -284.353)
		(mid 385.20766 -284.21664)
		(end 385.160012 -284.033722)
		(width 0.088646)
		(layer "In11.Cu")
		(net "M_H_CPU0_SA_DQ<10>")
	)
	(arc
		(start 373.121174 -279.469596)
		(mid 372.99026 -279.333236)
		(end 372.942612 -279.150318)
		(width 0.088646)
		(layer "In11.Cu")
		(net "M_H_CPU0_SA_DQ<10>")
	)
	(arc
		(start 374.52935 -280.282396)
		(mid 374.251172 -280.212704)
		(end 373.974614 -280.288492)
		(width 0.088646)
		(layer "In11.Cu")
		(net "M_H_CPU0_SA_DQ<10>")
	)
	(arc
		(start 386.099812 -285.64586)
		(mid 386.020442 -285.372126)
		(end 385.817618 -285.171896)
		(width 0.088646)
		(layer "In11.Cu")
		(net "M_H_CPU0_SA_DQ<10>")
	)
	(arc
		(start 382.513332 -281.093926)
		(mid 382.236857 -281.026606)
		(end 381.96266 -281.102562)
		(width 0.088646)
		(layer "In11.Cu")
		(net "M_H_CPU0_SA_DQ<10>")
	)
	(arc
		(start 372.181374 -277.84171)
		(mid 372.002777 -277.522432)
		(end 372.181374 -277.203154)
		(width 0.088646)
		(layer "In11.Cu")
		(net "M_H_CPU0_SA_DQ<10>")
	)
	(arc
		(start 384.868928 -283.539184)
		(mid 384.738014 -283.402824)
		(end 384.690366 -283.219906)
		(width 0.088646)
		(layer "In11.Cu")
		(net "M_H_CPU0_SA_DQ<10>")
	)
	(arc
		(start 385.160012 -284.018228)
		(mid 385.080642 -283.744494)
		(end 384.877818 -283.544264)
		(width 0.088646)
		(layer "In11.Cu")
		(net "M_H_CPU0_SA_DQ<10>")
	)
	(arc
		(start 386.404612 -286.075628)
		(mid 386.348883 -286.026828)
		(end 386.287264 -285.985712)
		(width 0.088646)
		(layer "In11.Cu")
		(net "M_H_CPU0_SA_DQ<10>")
	)
	(arc
		(start 374.91416 -280.288492)
		(mid 374.726962 -280.338635)
		(end 374.539764 -280.288492)
		(width 0.088646)
		(layer "In11.Cu")
		(net "M_H_CPU0_SA_DQ<10>")
	)
	(arc
		(start 375.479818 -280.288492)
		(mid 375.203005 -280.212656)
		(end 374.924574 -280.282396)
		(width 0.088646)
		(layer "In11.Cu")
		(net "M_H_CPU0_SA_DQ<10>")
	)
	(arc
		(start 385.630166 -284.847538)
		(mid 385.556175 -284.567972)
		(end 385.35356 -284.361636)
		(width 0.088646)
		(layer "In11.Cu")
		(net "M_H_CPU0_SA_DQ<10>")
	)
	(arc
		(start 372.472966 -278.322278)
		(mid 372.393747 -278.047593)
		(end 372.190264 -277.84679)
		(width 0.088646)
		(layer "In11.Cu")
		(net "M_H_CPU0_SA_DQ<10>")
	)
	(arc
		(start 382.810766 -281.59202)
		(mid 382.736775 -281.312454)
		(end 382.53416 -281.106118)
		(width 0.088646)
		(layer "In11.Cu")
		(net "M_H_CPU0_SA_DQ<10>")
	)
	(arc
		(start 381.02286 -281.102562)
		(mid 380.835662 -281.152705)
		(end 380.648464 -281.102562)
		(width 0.088646)
		(layer "In11.Cu")
		(net "M_H_CPU0_SA_DQ<10>")
	)
	(arc
		(start 382.997964 -281.916378)
		(mid 382.863031 -281.783024)
		(end 382.810766 -281.600656)
		(width 0.088646)
		(layer "In11.Cu")
		(net "M_H_CPU0_SA_DQ<10>")
	)
	(arc
		(start 384.407664 -282.730194)
		(mid 384.124962 -282.654452)
		(end 383.84226 -282.730194)
		(width 0.088646)
		(layer "In11.Cu")
		(net "M_H_CPU0_SA_DQ<10>")
	)
	(arc
		(start 379.693932 -281.093926)
		(mid 379.417457 -281.026606)
		(end 379.14326 -281.102562)
		(width 0.088646)
		(layer "In11.Cu")
		(net "M_H_CPU0_SA_DQ<10>")
	)
	(arc
		(start 383.84226 -282.730194)
		(mid 383.655062 -282.780337)
		(end 383.467864 -282.730194)
		(width 0.088646)
		(layer "In11.Cu")
		(net "M_H_CPU0_SA_DQ<10>")
	)
	(arc
		(start 378.20346 -281.102562)
		(mid 378.016262 -281.152705)
		(end 377.829064 -281.102562)
		(width 0.088646)
		(layer "In11.Cu")
		(net "M_H_CPU0_SA_DQ<10>")
	)
	(arc
		(start 372.651528 -278.65578)
		(mid 372.520614 -278.51942)
		(end 372.472966 -278.336502)
		(width 0.088646)
		(layer "In11.Cu")
		(net "M_H_CPU0_SA_DQ<10>")
	)
	(arc
		(start 373.412766 -279.964134)
		(mid 373.338775 -279.684568)
		(end 373.13616 -279.478232)
		(width 0.088646)
		(layer "In11.Cu")
		(net "M_H_CPU0_SA_DQ<10>")
	)
	(segment
		(start 379.425962 -279.96388)
		(end 379.426216 -279.964134)
		(width 0.20066)
		(layer "F.Cu")
		(net "M_H_CPU0_SA_DQ<0>")
	)
	(segment
		(start 457.53655 -315.885322)
		(end 457.126594 -315.885322)
		(width 0.20066)
		(layer "F.Cu")
		(net "M_H_CPU0_SA_DQ<0>")
	)
	(segment
		(start 454.91146 -315.891672)
		(end 454.566782 -315.891672)
		(width 0.20066)
		(layer "F.Cu")
		(net "M_H_CPU0_SA_DQ<0>")
	)
	(segment
		(start 459.559914 -316.316614)
		(end 459.55966 -316.316868)
		(width 0.20066)
		(layer "F.Cu")
		(net "M_H_CPU0_SA_DQ<0>")
	)
	(segment
		(start 459.55966 -316.316868)
		(end 457.968096 -316.316868)
		(width 0.20066)
		(layer "F.Cu")
		(net "M_H_CPU0_SA_DQ<0>")
	)
	(segment
		(start 457.126594 -315.885322)
		(end 457.120244 -315.891672)
		(width 0.1016)
		(layer "F.Cu")
		(net "M_H_CPU0_SA_DQ<0>")
	)
	(segment
		(start 452.016114 -316.316614)
		(end 450.911214 -316.316614)
		(width 0.20066)
		(layer "F.Cu")
		(net "M_H_CPU0_SA_DQ<0>")
	)
	(segment
		(start 454.95845 -315.891672)
		(end 454.91146 -315.891672)
		(width 0.101854)
		(layer "F.Cu")
		(net "M_H_CPU0_SA_DQ<0>")
	)
	(segment
		(start 454.260712 -316.56528)
		(end 453.785478 -316.56528)
		(width 0.20066)
		(layer "F.Cu")
		(net "M_H_CPU0_SA_DQ<0>")
	)
	(segment
		(start 457.968096 -316.316868)
		(end 457.53655 -315.885322)
		(width 0.20066)
		(layer "F.Cu")
		(net "M_H_CPU0_SA_DQ<0>")
	)
	(segment
		(start 454.566782 -315.891672)
		(end 454.448672 -316.009782)
		(width 0.20066)
		(layer "F.Cu")
		(net "M_H_CPU0_SA_DQ<0>")
	)
	(segment
		(start 453.536812 -316.316614)
		(end 452.016114 -316.316614)
		(width 0.20066)
		(layer "F.Cu")
		(net "M_H_CPU0_SA_DQ<0>")
	)
	(segment
		(start 379.425962 -279.428194)
		(end 379.425962 -279.96388)
		(width 0.20066)
		(layer "F.Cu")
		(net "M_H_CPU0_SA_DQ<0>")
	)
	(segment
		(start 454.448672 -316.37732)
		(end 454.260712 -316.56528)
		(width 0.20066)
		(layer "F.Cu")
		(net "M_H_CPU0_SA_DQ<0>")
	)
	(segment
		(start 454.448672 -316.009782)
		(end 454.448672 -316.37732)
		(width 0.20066)
		(layer "F.Cu")
		(net "M_H_CPU0_SA_DQ<0>")
	)
	(segment
		(start 453.785478 -316.56528)
		(end 453.536812 -316.316614)
		(width 0.20066)
		(layer "F.Cu")
		(net "M_H_CPU0_SA_DQ<0>")
	)
	(segment
		(start 457.120244 -315.891672)
		(end 454.95845 -315.891672)
		(width 0.1016)
		(layer "F.Cu")
		(net "M_H_CPU0_SA_DQ<0>")
	)
	(segment
		(start 384.79095 -280.458926)
		(end 384.78206 -280.453846)
		(width 0.088646)
		(layer "In6.Cu")
		(net "M_H_CPU0_SA_DQ<0>")
	)
	(segment
		(start 440.716416 -316.742318)
		(end 439.549286 -316.742318)
		(width 0.18288)
		(layer "In6.Cu")
		(net "M_H_CPU0_SA_DQ<0>")
	)
	(segment
		(start 431.61204 -315.820552)
		(end 430.705514 -314.914026)
		(width 0.18288)
		(layer "In6.Cu")
		(net "M_H_CPU0_SA_DQ<0>")
	)
	(segment
		(start 441.874148 -317.485268)
		(end 441.67552 -317.683896)
		(width 0.18288)
		(layer "In6.Cu")
		(net "M_H_CPU0_SA_DQ<0>")
	)
	(segment
		(start 384.969512 -280.78811)
		(end 384.969512 -280.778204)
		(width 0.088646)
		(layer "In6.Cu")
		(net "M_H_CPU0_SA_DQ<0>")
	)
	(segment
		(start 393.80287 -284.727396)
		(end 392.207496 -283.132022)
		(width 0.18288)
		(layer "In6.Cu")
		(net "M_H_CPU0_SA_DQ<0>")
	)
	(segment
		(start 428.018194 -314.914026)
		(end 427.328584 -314.224416)
		(width 0.18288)
		(layer "In6.Cu")
		(net "M_H_CPU0_SA_DQ<0>")
	)
	(segment
		(start 436.912766 -317.624714)
		(end 435.50967 -317.624714)
		(width 0.18288)
		(layer "In6.Cu")
		(net "M_H_CPU0_SA_DQ<0>")
	)
	(segment
		(start 387.4389 -283.132022)
		(end 387.359398 -283.05252)
		(width 0.18288)
		(layer "In6.Cu")
		(net "M_H_CPU0_SA_DQ<0>")
	)
	(segment
		(start 439.252106 -316.445138)
		(end 438.092342 -316.445138)
		(width 0.18288)
		(layer "In6.Cu")
		(net "M_H_CPU0_SA_DQ<0>")
	)
	(segment
		(start 418.542978 -315.119512)
		(end 418.215318 -315.119512)
		(width 0.18288)
		(layer "In6.Cu")
		(net "M_H_CPU0_SA_DQ<0>")
	)
	(segment
		(start 414.10001 -313.84494)
		(end 413.91713 -313.66206)
		(width 0.18288)
		(layer "In6.Cu")
		(net "M_H_CPU0_SA_DQ<0>")
	)
	(segment
		(start 387.13918 -282.832302)
		(end 387.13918 -281.904694)
		(width 0.088646)
		(layer "In6.Cu")
		(net "M_H_CPU0_SA_DQ<0>")
	)
	(segment
		(start 425.134786 -313.338718)
		(end 422.63314 -313.338718)
		(width 0.18288)
		(layer "In6.Cu")
		(net "M_H_CPU0_SA_DQ<0>")
	)
	(segment
		(start 450.911214 -316.316614)
		(end 450.48551 -316.742318)
		(width 0.18288)
		(layer "In6.Cu")
		(net "M_H_CPU0_SA_DQ<0>")
	)
	(segment
		(start 444.868554 -317.925958)
		(end 444.540894 -317.925958)
		(width 0.18288)
		(layer "In6.Cu")
		(net "M_H_CPU0_SA_DQ<0>")
	)
	(segment
		(start 410.955998 -310.86933)
		(end 408.575256 -310.86933)
		(width 0.18288)
		(layer "In6.Cu")
		(net "M_H_CPU0_SA_DQ<0>")
	)
	(segment
		(start 415.924492 -312.662824)
		(end 414.79343 -312.662824)
		(width 0.18288)
		(layer "In6.Cu")
		(net "M_H_CPU0_SA_DQ<0>")
	)
	(segment
		(start 417.849558 -314.192412)
		(end 417.45408 -314.192412)
		(width 0.18288)
		(layer "In6.Cu")
		(net "M_H_CPU0_SA_DQ<0>")
	)
	(segment
		(start 427.328584 -314.224416)
		(end 426.961554 -314.047886)
		(width 0.18288)
		(layer "In6.Cu")
		(net "M_H_CPU0_SA_DQ<0>")
	)
	(segment
		(start 448.713606 -316.742318)
		(end 447.774314 -315.803026)
		(width 0.18288)
		(layer "In6.Cu")
		(net "M_H_CPU0_SA_DQ<0>")
	)
	(segment
		(start 445.234314 -316.407546)
		(end 445.051434 -316.590426)
		(width 0.18288)
		(layer "In6.Cu")
		(net "M_H_CPU0_SA_DQ<0>")
	)
	(segment
		(start 379.290834 -279.615138)
		(end 379.269752 -279.693116)
		(width 0.088646)
		(layer "In6.Cu")
		(net "M_H_CPU0_SA_DQ<0>")
	)
	(segment
		(start 405.293576 -310.383936)
		(end 401.635468 -306.725828)
		(width 0.18288)
		(layer "In6.Cu")
		(net "M_H_CPU0_SA_DQ<0>")
	)
	(segment
		(start 432.423062 -315.820552)
		(end 431.61204 -315.820552)
		(width 0.18288)
		(layer "In6.Cu")
		(net "M_H_CPU0_SA_DQ<0>")
	)
	(segment
		(start 401.635468 -301.957232)
		(end 393.80287 -294.124634)
		(width 0.18288)
		(layer "In6.Cu")
		(net "M_H_CPU0_SA_DQ<0>")
	)
	(segment
		(start 425.843954 -314.047886)
		(end 425.134786 -313.338718)
		(width 0.18288)
		(layer "In6.Cu")
		(net "M_H_CPU0_SA_DQ<0>")
	)
	(segment
		(start 445.051434 -317.743078)
		(end 444.868554 -317.925958)
		(width 0.18288)
		(layer "In6.Cu")
		(net "M_H_CPU0_SA_DQ<0>")
	)
	(segment
		(start 414.79343 -312.662824)
		(end 414.61055 -312.845704)
		(width 0.18288)
		(layer "In6.Cu")
		(net "M_H_CPU0_SA_DQ<0>")
	)
	(segment
		(start 408.575256 -310.86933)
		(end 408.089862 -310.383936)
		(width 0.18288)
		(layer "In6.Cu")
		(net "M_H_CPU0_SA_DQ<0>")
	)
	(segment
		(start 421.779446 -314.192412)
		(end 418.908738 -314.192412)
		(width 0.18288)
		(layer "In6.Cu")
		(net "M_H_CPU0_SA_DQ<0>")
	)
	(segment
		(start 413.91713 -312.845704)
		(end 413.73425 -312.662824)
		(width 0.18288)
		(layer "In6.Cu")
		(net "M_H_CPU0_SA_DQ<0>")
	)
	(segment
		(start 441.153804 -317.683896)
		(end 440.925458 -317.45555)
		(width 0.18288)
		(layer "In6.Cu")
		(net "M_H_CPU0_SA_DQ<0>")
	)
	(segment
		(start 435.50967 -317.624714)
		(end 435.127146 -317.24219)
		(width 0.18288)
		(layer "In6.Cu")
		(net "M_H_CPU0_SA_DQ<0>")
	)
	(segment
		(start 380.178564 -279.639776)
		(end 380.16815 -279.645872)
		(width 0.088646)
		(layer "In6.Cu")
		(net "M_H_CPU0_SA_DQ<0>")
	)
	(segment
		(start 383.937764 -279.639776)
		(end 383.92735 -279.645872)
		(width 0.088646)
		(layer "In6.Cu")
		(net "M_H_CPU0_SA_DQ<0>")
	)
	(segment
		(start 418.032438 -314.936632)
		(end 418.032438 -314.375292)
		(width 0.18288)
		(layer "In6.Cu")
		(net "M_H_CPU0_SA_DQ<0>")
	)
	(segment
		(start 426.961554 -314.047886)
		(end 425.843954 -314.047886)
		(width 0.18288)
		(layer "In6.Cu")
		(net "M_H_CPU0_SA_DQ<0>")
	)
	(segment
		(start 418.215318 -315.119512)
		(end 418.032438 -314.936632)
		(width 0.18288)
		(layer "In6.Cu")
		(net "M_H_CPU0_SA_DQ<0>")
	)
	(segment
		(start 434.062378 -317.24219)
		(end 432.821334 -316.001146)
		(width 0.18288)
		(layer "In6.Cu")
		(net "M_H_CPU0_SA_DQ<0>")
	)
	(segment
		(start 444.358014 -316.590426)
		(end 444.175134 -316.407546)
		(width 0.18288)
		(layer "In6.Cu")
		(net "M_H_CPU0_SA_DQ<0>")
	)
	(segment
		(start 413.91713 -313.66206)
		(end 413.91713 -312.845704)
		(width 0.18288)
		(layer "In6.Cu")
		(net "M_H_CPU0_SA_DQ<0>")
	)
	(segment
		(start 445.051434 -316.590426)
		(end 445.051434 -317.743078)
		(width 0.18288)
		(layer "In6.Cu")
		(net "M_H_CPU0_SA_DQ<0>")
	)
	(segment
		(start 447.774314 -315.803026)
		(end 447.113152 -315.803026)
		(width 0.18288)
		(layer "In6.Cu")
		(net "M_H_CPU0_SA_DQ<0>")
	)
	(segment
		(start 387.359398 -283.05252)
		(end 387.13918 -282.832302)
		(width 0.088646)
		(layer "In6.Cu")
		(net "M_H_CPU0_SA_DQ<0>")
	)
	(segment
		(start 384.32105 -279.644856)
		(end 384.31216 -279.639776)
		(width 0.088646)
		(layer "In6.Cu")
		(net "M_H_CPU0_SA_DQ<0>")
	)
	(segment
		(start 379.269752 -279.693116)
		(end 379.426216 -279.964134)
		(width 0.088646)
		(layer "In6.Cu")
		(net "M_H_CPU0_SA_DQ<0>")
	)
	(segment
		(start 408.089862 -310.383936)
		(end 405.293576 -310.383936)
		(width 0.18288)
		(layer "In6.Cu")
		(net "M_H_CPU0_SA_DQ<0>")
	)
	(segment
		(start 422.63314 -313.338718)
		(end 421.779446 -314.192412)
		(width 0.18288)
		(layer "In6.Cu")
		(net "M_H_CPU0_SA_DQ<0>")
	)
	(segment
		(start 442.585348 -316.742318)
		(end 442.132212 -316.742318)
		(width 0.18288)
		(layer "In6.Cu")
		(net "M_H_CPU0_SA_DQ<0>")
	)
	(segment
		(start 412.749492 -312.662824)
		(end 410.955998 -310.86933)
		(width 0.18288)
		(layer "In6.Cu")
		(net "M_H_CPU0_SA_DQ<0>")
	)
	(segment
		(start 439.549286 -316.742318)
		(end 439.252106 -316.445138)
		(width 0.18288)
		(layer "In6.Cu")
		(net "M_H_CPU0_SA_DQ<0>")
	)
	(segment
		(start 418.725858 -314.375292)
		(end 418.725858 -314.936632)
		(width 0.18288)
		(layer "In6.Cu")
		(net "M_H_CPU0_SA_DQ<0>")
	)
	(segment
		(start 441.874148 -317.000382)
		(end 441.874148 -317.485268)
		(width 0.18288)
		(layer "In6.Cu")
		(net "M_H_CPU0_SA_DQ<0>")
	)
	(segment
		(start 430.705514 -314.914026)
		(end 428.018194 -314.914026)
		(width 0.18288)
		(layer "In6.Cu")
		(net "M_H_CPU0_SA_DQ<0>")
	)
	(segment
		(start 432.821334 -316.001146)
		(end 432.423062 -315.820552)
		(width 0.18288)
		(layer "In6.Cu")
		(net "M_H_CPU0_SA_DQ<0>")
	)
	(segment
		(start 381.118618 -279.639776)
		(end 381.108204 -279.645872)
		(width 0.088646)
		(layer "In6.Cu")
		(net "M_H_CPU0_SA_DQ<0>")
	)
	(segment
		(start 418.908738 -314.192412)
		(end 418.725858 -314.375292)
		(width 0.18288)
		(layer "In6.Cu")
		(net "M_H_CPU0_SA_DQ<0>")
	)
	(segment
		(start 444.358014 -317.743078)
		(end 444.358014 -316.590426)
		(width 0.18288)
		(layer "In6.Cu")
		(net "M_H_CPU0_SA_DQ<0>")
	)
	(segment
		(start 440.925458 -317.45555)
		(end 440.925458 -316.95136)
		(width 0.18288)
		(layer "In6.Cu")
		(net "M_H_CPU0_SA_DQ<0>")
	)
	(segment
		(start 414.42767 -313.84494)
		(end 414.10001 -313.84494)
		(width 0.18288)
		(layer "In6.Cu")
		(net "M_H_CPU0_SA_DQ<0>")
	)
	(segment
		(start 441.67552 -317.683896)
		(end 441.153804 -317.683896)
		(width 0.18288)
		(layer "In6.Cu")
		(net "M_H_CPU0_SA_DQ<0>")
	)
	(segment
		(start 384.499612 -279.982676)
		(end 384.499612 -279.964134)
		(width 0.088646)
		(layer "In6.Cu")
		(net "M_H_CPU0_SA_DQ<0>")
	)
	(segment
		(start 401.635468 -306.725828)
		(end 401.635468 -301.957232)
		(width 0.18288)
		(layer "In6.Cu")
		(net "M_H_CPU0_SA_DQ<0>")
	)
	(segment
		(start 446.508632 -316.407546)
		(end 445.234314 -316.407546)
		(width 0.18288)
		(layer "In6.Cu")
		(net "M_H_CPU0_SA_DQ<0>")
	)
	(segment
		(start 435.127146 -317.24219)
		(end 434.062378 -317.24219)
		(width 0.18288)
		(layer "In6.Cu")
		(net "M_H_CPU0_SA_DQ<0>")
	)
	(segment
		(start 450.48551 -316.742318)
		(end 448.713606 -316.742318)
		(width 0.18288)
		(layer "In6.Cu")
		(net "M_H_CPU0_SA_DQ<0>")
	)
	(segment
		(start 417.45408 -314.192412)
		(end 415.924492 -312.662824)
		(width 0.18288)
		(layer "In6.Cu")
		(net "M_H_CPU0_SA_DQ<0>")
	)
	(segment
		(start 444.175134 -316.407546)
		(end 442.92012 -316.407546)
		(width 0.18288)
		(layer "In6.Cu")
		(net "M_H_CPU0_SA_DQ<0>")
	)
	(segment
		(start 414.61055 -312.845704)
		(end 414.61055 -313.66206)
		(width 0.18288)
		(layer "In6.Cu")
		(net "M_H_CPU0_SA_DQ<0>")
	)
	(segment
		(start 392.207496 -283.132022)
		(end 387.4389 -283.132022)
		(width 0.18288)
		(layer "In6.Cu")
		(net "M_H_CPU0_SA_DQ<0>")
	)
	(segment
		(start 442.92012 -316.407546)
		(end 442.585348 -316.742318)
		(width 0.18288)
		(layer "In6.Cu")
		(net "M_H_CPU0_SA_DQ<0>")
	)
	(segment
		(start 442.132212 -316.742318)
		(end 441.874148 -317.000382)
		(width 0.18288)
		(layer "In6.Cu")
		(net "M_H_CPU0_SA_DQ<0>")
	)
	(segment
		(start 438.092342 -316.445138)
		(end 436.912766 -317.624714)
		(width 0.18288)
		(layer "In6.Cu")
		(net "M_H_CPU0_SA_DQ<0>")
	)
	(segment
		(start 418.032438 -314.375292)
		(end 417.849558 -314.192412)
		(width 0.18288)
		(layer "In6.Cu")
		(net "M_H_CPU0_SA_DQ<0>")
	)
	(segment
		(start 381.507746 -279.648412)
		(end 381.493014 -279.639776)
		(width 0.088646)
		(layer "In6.Cu")
		(net "M_H_CPU0_SA_DQ<0>")
	)
	(segment
		(start 440.925458 -316.95136)
		(end 440.716416 -316.742318)
		(width 0.18288)
		(layer "In6.Cu")
		(net "M_H_CPU0_SA_DQ<0>")
	)
	(segment
		(start 393.80287 -294.124634)
		(end 393.80287 -284.727396)
		(width 0.18288)
		(layer "In6.Cu")
		(net "M_H_CPU0_SA_DQ<0>")
	)
	(segment
		(start 413.73425 -312.662824)
		(end 412.749492 -312.662824)
		(width 0.18288)
		(layer "In6.Cu")
		(net "M_H_CPU0_SA_DQ<0>")
	)
	(segment
		(start 418.725858 -314.936632)
		(end 418.542978 -315.119512)
		(width 0.18288)
		(layer "In6.Cu")
		(net "M_H_CPU0_SA_DQ<0>")
	)
	(segment
		(start 414.61055 -313.66206)
		(end 414.42767 -313.84494)
		(width 0.18288)
		(layer "In6.Cu")
		(net "M_H_CPU0_SA_DQ<0>")
	)
	(segment
		(start 447.113152 -315.803026)
		(end 446.508632 -316.407546)
		(width 0.18288)
		(layer "In6.Cu")
		(net "M_H_CPU0_SA_DQ<0>")
	)
	(segment
		(start 444.540894 -317.925958)
		(end 444.358014 -317.743078)
		(width 0.18288)
		(layer "In6.Cu")
		(net "M_H_CPU0_SA_DQ<0>")
	)
	(arc
		(start 384.78206 -280.453846)
		(mid 384.579774 -280.254865)
		(end 384.499612 -279.982676)
		(width 0.088646)
		(layer "In6.Cu")
		(net "M_H_CPU0_SA_DQ<0>")
	)
	(arc
		(start 382.99771 -279.639776)
		(mid 382.715262 -279.715425)
		(end 382.432814 -279.639776)
		(width 0.088646)
		(layer "In6.Cu")
		(net "M_H_CPU0_SA_DQ<0>")
	)
	(arc
		(start 384.499612 -279.964134)
		(mid 384.451933 -279.781234)
		(end 384.32105 -279.644856)
		(width 0.088646)
		(layer "In6.Cu")
		(net "M_H_CPU0_SA_DQ<0>")
	)
	(arc
		(start 383.92735 -279.645872)
		(mid 383.648918 -279.715718)
		(end 383.372106 -279.639776)
		(width 0.088646)
		(layer "In6.Cu")
		(net "M_H_CPU0_SA_DQ<0>")
	)
	(arc
		(start 384.31216 -279.639776)
		(mid 384.124962 -279.589633)
		(end 383.937764 -279.639776)
		(width 0.088646)
		(layer "In6.Cu")
		(net "M_H_CPU0_SA_DQ<0>")
	)
	(arc
		(start 382.432814 -279.639776)
		(mid 382.245616 -279.589633)
		(end 382.058418 -279.639776)
		(width 0.088646)
		(layer "In6.Cu")
		(net "M_H_CPU0_SA_DQ<0>")
	)
	(arc
		(start 380.16815 -279.645872)
		(mid 379.889972 -279.715595)
		(end 379.613414 -279.639776)
		(width 0.088646)
		(layer "In6.Cu")
		(net "M_H_CPU0_SA_DQ<0>")
	)
	(arc
		(start 380.55296 -279.639776)
		(mid 380.365762 -279.589633)
		(end 380.178564 -279.639776)
		(width 0.088646)
		(layer "In6.Cu")
		(net "M_H_CPU0_SA_DQ<0>")
	)
	(arc
		(start 386.5245 -281.341576)
		(mid 386.352418 -281.330311)
		(end 386.19176 -281.267662)
		(width 0.088646)
		(layer "In6.Cu")
		(net "M_H_CPU0_SA_DQ<0>")
	)
	(arc
		(start 383.372106 -279.639776)
		(mid 383.184908 -279.589633)
		(end 382.99771 -279.639776)
		(width 0.088646)
		(layer "In6.Cu")
		(net "M_H_CPU0_SA_DQ<0>")
	)
	(arc
		(start 385.817364 -281.267662)
		(mid 385.534662 -281.343438)
		(end 385.25196 -281.267662)
		(width 0.088646)
		(layer "In6.Cu")
		(net "M_H_CPU0_SA_DQ<0>")
	)
	(arc
		(start 386.19176 -281.267662)
		(mid 386.004562 -281.217519)
		(end 385.817364 -281.267662)
		(width 0.088646)
		(layer "In6.Cu")
		(net "M_H_CPU0_SA_DQ<0>")
	)
	(arc
		(start 382.058418 -279.639776)
		(mid 381.784219 -279.715611)
		(end 381.507746 -279.648412)
		(width 0.088646)
		(layer "In6.Cu")
		(net "M_H_CPU0_SA_DQ<0>")
	)
	(arc
		(start 385.25196 -281.267662)
		(mid 385.047625 -281.065057)
		(end 384.969512 -280.78811)
		(width 0.088646)
		(layer "In6.Cu")
		(net "M_H_CPU0_SA_DQ<0>")
	)
	(arc
		(start 384.969512 -280.778204)
		(mid 384.921833 -280.595304)
		(end 384.79095 -280.458926)
		(width 0.088646)
		(layer "In6.Cu")
		(net "M_H_CPU0_SA_DQ<0>")
	)
	(arc
		(start 387.13918 -281.904694)
		(mid 386.955754 -281.487831)
		(end 386.5245 -281.341576)
		(width 0.088646)
		(layer "In6.Cu")
		(net "M_H_CPU0_SA_DQ<0>")
	)
	(arc
		(start 379.613414 -279.639776)
		(mid 379.454926 -279.590843)
		(end 379.290834 -279.615138)
		(width 0.088646)
		(layer "In6.Cu")
		(net "M_H_CPU0_SA_DQ<0>")
	)
	(arc
		(start 381.108204 -279.645872)
		(mid 380.829772 -279.715718)
		(end 380.55296 -279.639776)
		(width 0.088646)
		(layer "In6.Cu")
		(net "M_H_CPU0_SA_DQ<0>")
	)
	(arc
		(start 381.493014 -279.639776)
		(mid 381.305816 -279.589633)
		(end 381.118618 -279.639776)
		(width 0.088646)
		(layer "In6.Cu")
		(net "M_H_CPU0_SA_DQ<0>")
	)
	(segment
		(start 371.437916 -256.361184)
		(end 371.437662 -256.361438)
		(width 0.20066)
		(layer "F.Cu")
		(net "M_H_CPU0_SA_CS_N<3>")
	)
	(segment
		(start 454.935082 -267.016738)
		(end 456.116182 -267.016738)
		(width 0.20066)
		(layer "F.Cu")
		(net "M_H_CPU0_SA_CS_N<3>")
	)
	(segment
		(start 371.437916 -255.825498)
		(end 371.437916 -256.361184)
		(width 0.20066)
		(layer "F.Cu")
		(net "M_H_CPU0_SA_CS_N<3>")
	)
	(segment
		(start 446.01003 -264.712958)
		(end 443.226952 -264.712958)
		(width 0.18288)
		(layer "In11.Cu")
		(net "M_H_CPU0_SA_CS_N<3>")
	)
	(segment
		(start 381.503174 -255.865884)
		(end 381.49276 -255.87198)
		(width 0.088646)
		(layer "In11.Cu")
		(net "M_H_CPU0_SA_CS_N<3>")
	)
	(segment
		(start 419.690042 -263.898888)
		(end 416.067748 -263.898888)
		(width 0.18288)
		(layer "In11.Cu")
		(net "M_H_CPU0_SA_CS_N<3>")
	)
	(segment
		(start 406.718516 -263.172448)
		(end 405.22779 -263.172448)
		(width 0.18288)
		(layer "In11.Cu")
		(net "M_H_CPU0_SA_CS_N<3>")
	)
	(segment
		(start 451.22719 -267.443204)
		(end 450.666104 -267.443204)
		(width 0.18288)
		(layer "In11.Cu")
		(net "M_H_CPU0_SA_CS_N<3>")
	)
	(segment
		(start 441.256166 -265.037824)
		(end 441.109354 -264.891012)
		(width 0.18288)
		(layer "In11.Cu")
		(net "M_H_CPU0_SA_CS_N<3>")
	)
	(segment
		(start 385.886198 -255.978406)
		(end 385.743958 -255.836166)
		(width 0.088646)
		(layer "In11.Cu")
		(net "M_H_CPU0_SA_CS_N<3>")
	)
	(segment
		(start 375.868946 -255.863344)
		(end 375.854214 -255.87198)
		(width 0.088646)
		(layer "In11.Cu")
		(net "M_H_CPU0_SA_CS_N<3>")
	)
	(segment
		(start 437.40705 -264.040874)
		(end 435.327044 -264.040874)
		(width 0.18288)
		(layer "In11.Cu")
		(net "M_H_CPU0_SA_CS_N<3>")
	)
	(segment
		(start 398.1196 -258.25323)
		(end 397.584676 -257.718306)
		(width 0.18288)
		(layer "In11.Cu")
		(net "M_H_CPU0_SA_CS_N<3>")
	)
	(segment
		(start 371.672358 -256.653284)
		(end 371.594126 -256.632456)
		(width 0.088646)
		(layer "In11.Cu")
		(net "M_H_CPU0_SA_CS_N<3>")
	)
	(segment
		(start 435.327044 -264.040874)
		(end 435.130194 -263.844024)
		(width 0.18288)
		(layer "In11.Cu")
		(net "M_H_CPU0_SA_CS_N<3>")
	)
	(segment
		(start 454.595738 -266.380722)
		(end 452.289672 -266.380722)
		(width 0.18288)
		(layer "In11.Cu")
		(net "M_H_CPU0_SA_CS_N<3>")
	)
	(segment
		(start 426.154342 -264.891012)
		(end 424.37558 -264.891012)
		(width 0.18288)
		(layer "In11.Cu")
		(net "M_H_CPU0_SA_CS_N<3>")
	)
	(segment
		(start 389.679688 -255.978406)
		(end 388.129018 -255.978406)
		(width 0.18288)
		(layer "In11.Cu")
		(net "M_H_CPU0_SA_CS_N<3>")
	)
	(segment
		(start 379.623828 -255.865884)
		(end 379.613414 -255.87198)
		(width 0.088646)
		(layer "In11.Cu")
		(net "M_H_CPU0_SA_CS_N<3>")
	)
	(segment
		(start 400.109436 -258.25323)
		(end 398.1196 -258.25323)
		(width 0.18288)
		(layer "In11.Cu")
		(net "M_H_CPU0_SA_CS_N<3>")
	)
	(segment
		(start 419.832028 -264.040874)
		(end 419.690042 -263.898888)
		(width 0.18288)
		(layer "In11.Cu")
		(net "M_H_CPU0_SA_CS_N<3>")
	)
	(segment
		(start 449.517262 -266.73175)
		(end 448.443604 -265.658092)
		(width 0.18288)
		(layer "In11.Cu")
		(net "M_H_CPU0_SA_CS_N<3>")
	)
	(segment
		(start 409.057348 -264.070846)
		(end 407.616914 -264.070846)
		(width 0.18288)
		(layer "In11.Cu")
		(net "M_H_CPU0_SA_CS_N<3>")
	)
	(segment
		(start 430.633124 -264.61974)
		(end 427.867064 -264.61974)
		(width 0.18288)
		(layer "In11.Cu")
		(net "M_H_CPU0_SA_CS_N<3>")
	)
	(segment
		(start 373.985028 -255.865884)
		(end 373.974614 -255.87198)
		(width 0.088646)
		(layer "In11.Cu")
		(net "M_H_CPU0_SA_CS_N<3>")
	)
	(segment
		(start 377.748546 -255.863344)
		(end 377.733814 -255.87198)
		(width 0.088646)
		(layer "In11.Cu")
		(net "M_H_CPU0_SA_CS_N<3>")
	)
	(segment
		(start 454.935082 -267.016738)
		(end 454.935082 -266.720066)
		(width 0.18288)
		(layer "In11.Cu")
		(net "M_H_CPU0_SA_CS_N<3>")
	)
	(segment
		(start 435.130194 -263.844024)
		(end 434.372766 -263.844024)
		(width 0.18288)
		(layer "In11.Cu")
		(net "M_H_CPU0_SA_CS_N<3>")
	)
	(segment
		(start 405.22779 -263.172448)
		(end 405.227536 -263.172194)
		(width 0.18288)
		(layer "In11.Cu")
		(net "M_H_CPU0_SA_CS_N<3>")
	)
	(segment
		(start 446.955164 -265.658092)
		(end 446.01003 -264.712958)
		(width 0.18288)
		(layer "In11.Cu")
		(net "M_H_CPU0_SA_CS_N<3>")
	)
	(segment
		(start 421.793416 -264.040874)
		(end 419.832028 -264.040874)
		(width 0.18288)
		(layer "In11.Cu")
		(net "M_H_CPU0_SA_CS_N<3>")
	)
	(segment
		(start 449.95465 -266.73175)
		(end 449.517262 -266.73175)
		(width 0.18288)
		(layer "In11.Cu")
		(net "M_H_CPU0_SA_CS_N<3>")
	)
	(segment
		(start 426.349922 -265.086592)
		(end 426.154342 -264.891012)
		(width 0.18288)
		(layer "In11.Cu")
		(net "M_H_CPU0_SA_CS_N<3>")
	)
	(segment
		(start 371.594126 -256.632456)
		(end 371.437662 -256.361438)
		(width 0.088646)
		(layer "In11.Cu")
		(net "M_H_CPU0_SA_CS_N<3>")
	)
	(segment
		(start 421.94607 -264.193528)
		(end 421.793416 -264.040874)
		(width 0.18288)
		(layer "In11.Cu")
		(net "M_H_CPU0_SA_CS_N<3>")
	)
	(segment
		(start 372.105428 -255.865884)
		(end 372.095014 -255.87198)
		(width 0.088646)
		(layer "In11.Cu")
		(net "M_H_CPU0_SA_CS_N<3>")
	)
	(segment
		(start 438.412636 -264.157968)
		(end 437.524144 -264.157968)
		(width 0.18288)
		(layer "In11.Cu")
		(net "M_H_CPU0_SA_CS_N<3>")
	)
	(segment
		(start 448.443604 -265.658092)
		(end 446.955164 -265.658092)
		(width 0.18288)
		(layer "In11.Cu")
		(net "M_H_CPU0_SA_CS_N<3>")
	)
	(segment
		(start 388.129018 -255.978406)
		(end 385.886198 -255.978406)
		(width 0.088646)
		(layer "In11.Cu")
		(net "M_H_CPU0_SA_CS_N<3>")
	)
	(segment
		(start 416.067748 -263.898888)
		(end 415.849308 -264.117328)
		(width 0.18288)
		(layer "In11.Cu")
		(net "M_H_CPU0_SA_CS_N<3>")
	)
	(segment
		(start 434.372766 -263.844024)
		(end 433.24907 -264.96772)
		(width 0.18288)
		(layer "In11.Cu")
		(net "M_H_CPU0_SA_CS_N<3>")
	)
	(segment
		(start 454.935082 -266.720066)
		(end 454.595738 -266.380722)
		(width 0.18288)
		(layer "In11.Cu")
		(net "M_H_CPU0_SA_CS_N<3>")
	)
	(segment
		(start 437.524144 -264.157968)
		(end 437.40705 -264.040874)
		(width 0.18288)
		(layer "In11.Cu")
		(net "M_H_CPU0_SA_CS_N<3>")
	)
	(segment
		(start 450.666104 -267.443204)
		(end 449.95465 -266.73175)
		(width 0.18288)
		(layer "In11.Cu")
		(net "M_H_CPU0_SA_CS_N<3>")
	)
	(segment
		(start 378.688346 -255.863344)
		(end 378.673614 -255.87198)
		(width 0.088646)
		(layer "In11.Cu")
		(net "M_H_CPU0_SA_CS_N<3>")
	)
	(segment
		(start 391.419588 -257.718306)
		(end 389.679688 -255.978406)
		(width 0.18288)
		(layer "In11.Cu")
		(net "M_H_CPU0_SA_CS_N<3>")
	)
	(segment
		(start 424.37558 -264.891012)
		(end 423.678096 -264.193528)
		(width 0.18288)
		(layer "In11.Cu")
		(net "M_H_CPU0_SA_CS_N<3>")
	)
	(segment
		(start 412.62808 -264.117328)
		(end 412.417768 -263.907016)
		(width 0.18288)
		(layer "In11.Cu")
		(net "M_H_CPU0_SA_CS_N<3>")
	)
	(segment
		(start 412.417768 -263.907016)
		(end 409.221178 -263.907016)
		(width 0.18288)
		(layer "In11.Cu")
		(net "M_H_CPU0_SA_CS_N<3>")
	)
	(segment
		(start 452.289672 -266.380722)
		(end 451.22719 -267.443204)
		(width 0.18288)
		(layer "In11.Cu")
		(net "M_H_CPU0_SA_CS_N<3>")
	)
	(segment
		(start 439.14568 -264.891012)
		(end 438.412636 -264.157968)
		(width 0.18288)
		(layer "In11.Cu")
		(net "M_H_CPU0_SA_CS_N<3>")
	)
	(segment
		(start 430.981104 -264.96772)
		(end 430.633124 -264.61974)
		(width 0.18288)
		(layer "In11.Cu")
		(net "M_H_CPU0_SA_CS_N<3>")
	)
	(segment
		(start 373.044974 -255.865884)
		(end 373.03456 -255.87198)
		(width 0.088646)
		(layer "In11.Cu")
		(net "M_H_CPU0_SA_CS_N<3>")
	)
	(segment
		(start 382.443228 -255.865884)
		(end 382.432814 -255.87198)
		(width 0.088646)
		(layer "In11.Cu")
		(net "M_H_CPU0_SA_CS_N<3>")
	)
	(segment
		(start 415.849308 -264.117328)
		(end 412.62808 -264.117328)
		(width 0.18288)
		(layer "In11.Cu")
		(net "M_H_CPU0_SA_CS_N<3>")
	)
	(segment
		(start 442.902086 -265.037824)
		(end 441.256166 -265.037824)
		(width 0.18288)
		(layer "In11.Cu")
		(net "M_H_CPU0_SA_CS_N<3>")
	)
	(segment
		(start 441.109354 -264.891012)
		(end 439.14568 -264.891012)
		(width 0.18288)
		(layer "In11.Cu")
		(net "M_H_CPU0_SA_CS_N<3>")
	)
	(segment
		(start 384.329432 -255.86182)
		(end 384.31216 -255.87198)
		(width 0.088646)
		(layer "In11.Cu")
		(net "M_H_CPU0_SA_CS_N<3>")
	)
	(segment
		(start 433.24907 -264.96772)
		(end 430.981104 -264.96772)
		(width 0.18288)
		(layer "In11.Cu")
		(net "M_H_CPU0_SA_CS_N<3>")
	)
	(segment
		(start 405.0284 -263.172194)
		(end 400.109436 -258.25323)
		(width 0.18288)
		(layer "In11.Cu")
		(net "M_H_CPU0_SA_CS_N<3>")
	)
	(segment
		(start 409.221178 -263.907016)
		(end 409.057348 -264.070846)
		(width 0.18288)
		(layer "In11.Cu")
		(net "M_H_CPU0_SA_CS_N<3>")
	)
	(segment
		(start 397.584676 -257.718306)
		(end 391.419588 -257.718306)
		(width 0.18288)
		(layer "In11.Cu")
		(net "M_H_CPU0_SA_CS_N<3>")
	)
	(segment
		(start 427.867064 -264.61974)
		(end 427.400212 -265.086592)
		(width 0.18288)
		(layer "In11.Cu")
		(net "M_H_CPU0_SA_CS_N<3>")
	)
	(segment
		(start 372.095014 -255.87198)
		(end 372.088918 -255.875536)
		(width 0.088646)
		(layer "In11.Cu")
		(net "M_H_CPU0_SA_CS_N<3>")
	)
	(segment
		(start 443.226952 -264.712958)
		(end 442.902086 -265.037824)
		(width 0.18288)
		(layer "In11.Cu")
		(net "M_H_CPU0_SA_CS_N<3>")
	)
	(segment
		(start 427.400212 -265.086592)
		(end 426.349922 -265.086592)
		(width 0.18288)
		(layer "In11.Cu")
		(net "M_H_CPU0_SA_CS_N<3>")
	)
	(segment
		(start 374.924574 -255.865884)
		(end 374.914668 -255.87198)
		(width 0.088646)
		(layer "In11.Cu")
		(net "M_H_CPU0_SA_CS_N<3>")
	)
	(segment
		(start 407.616914 -264.070846)
		(end 406.718516 -263.172448)
		(width 0.18288)
		(layer "In11.Cu")
		(net "M_H_CPU0_SA_CS_N<3>")
	)
	(segment
		(start 405.227536 -263.172194)
		(end 405.0284 -263.172194)
		(width 0.18288)
		(layer "In11.Cu")
		(net "M_H_CPU0_SA_CS_N<3>")
	)
	(segment
		(start 423.678096 -264.193528)
		(end 421.94607 -264.193528)
		(width 0.18288)
		(layer "In11.Cu")
		(net "M_H_CPU0_SA_CS_N<3>")
	)
	(arc
		(start 373.974614 -255.87198)
		(mid 373.787416 -255.922123)
		(end 373.600218 -255.87198)
		(width 0.088646)
		(layer "In11.Cu")
		(net "M_H_CPU0_SA_CS_N<3>")
	)
	(arc
		(start 383.937764 -255.87198)
		(mid 383.655062 -255.796204)
		(end 383.37236 -255.87198)
		(width 0.088646)
		(layer "In11.Cu")
		(net "M_H_CPU0_SA_CS_N<3>")
	)
	(arc
		(start 375.854214 -255.87198)
		(mid 375.667016 -255.922123)
		(end 375.479818 -255.87198)
		(width 0.088646)
		(layer "In11.Cu")
		(net "M_H_CPU0_SA_CS_N<3>")
	)
	(arc
		(start 374.539764 -255.87198)
		(mid 374.263205 -255.796237)
		(end 373.985028 -255.865884)
		(width 0.088646)
		(layer "In11.Cu")
		(net "M_H_CPU0_SA_CS_N<3>")
	)
	(arc
		(start 378.299218 -255.87198)
		(mid 378.025019 -255.796145)
		(end 377.748546 -255.863344)
		(width 0.088646)
		(layer "In11.Cu")
		(net "M_H_CPU0_SA_CS_N<3>")
	)
	(arc
		(start 377.359418 -255.87198)
		(mid 377.076716 -255.796204)
		(end 376.794014 -255.87198)
		(width 0.088646)
		(layer "In11.Cu")
		(net "M_H_CPU0_SA_CS_N<3>")
	)
	(arc
		(start 379.239018 -255.87198)
		(mid 378.964819 -255.796145)
		(end 378.688346 -255.863344)
		(width 0.088646)
		(layer "In11.Cu")
		(net "M_H_CPU0_SA_CS_N<3>")
	)
	(arc
		(start 382.997964 -255.87198)
		(mid 382.721405 -255.796237)
		(end 382.443228 -255.865884)
		(width 0.088646)
		(layer "In11.Cu")
		(net "M_H_CPU0_SA_CS_N<3>")
	)
	(arc
		(start 380.55296 -255.87198)
		(mid 380.365762 -255.922123)
		(end 380.178564 -255.87198)
		(width 0.088646)
		(layer "In11.Cu")
		(net "M_H_CPU0_SA_CS_N<3>")
	)
	(arc
		(start 373.600218 -255.87198)
		(mid 373.323405 -255.79611)
		(end 373.044974 -255.865884)
		(width 0.088646)
		(layer "In11.Cu")
		(net "M_H_CPU0_SA_CS_N<3>")
	)
	(arc
		(start 376.419618 -255.87198)
		(mid 376.145419 -255.796145)
		(end 375.868946 -255.863344)
		(width 0.088646)
		(layer "In11.Cu")
		(net "M_H_CPU0_SA_CS_N<3>")
	)
	(arc
		(start 381.118364 -255.87198)
		(mid 380.835662 -255.796204)
		(end 380.55296 -255.87198)
		(width 0.088646)
		(layer "In11.Cu")
		(net "M_H_CPU0_SA_CS_N<3>")
	)
	(arc
		(start 384.31216 -255.87198)
		(mid 384.124962 -255.922123)
		(end 383.937764 -255.87198)
		(width 0.088646)
		(layer "In11.Cu")
		(net "M_H_CPU0_SA_CS_N<3>")
	)
	(arc
		(start 379.613414 -255.87198)
		(mid 379.426216 -255.922123)
		(end 379.239018 -255.87198)
		(width 0.088646)
		(layer "In11.Cu")
		(net "M_H_CPU0_SA_CS_N<3>")
	)
	(arc
		(start 378.673614 -255.87198)
		(mid 378.486416 -255.922123)
		(end 378.299218 -255.87198)
		(width 0.088646)
		(layer "In11.Cu")
		(net "M_H_CPU0_SA_CS_N<3>")
	)
	(arc
		(start 372.088918 -255.875536)
		(mid 371.886331 -256.081887)
		(end 371.812312 -256.361438)
		(width 0.088646)
		(layer "In11.Cu")
		(net "M_H_CPU0_SA_CS_N<3>")
	)
	(arc
		(start 371.812312 -256.361438)
		(mid 371.775452 -256.523235)
		(end 371.672358 -256.653284)
		(width 0.088646)
		(layer "In11.Cu")
		(net "M_H_CPU0_SA_CS_N<3>")
	)
	(arc
		(start 381.49276 -255.87198)
		(mid 381.305562 -255.922123)
		(end 381.118364 -255.87198)
		(width 0.088646)
		(layer "In11.Cu")
		(net "M_H_CPU0_SA_CS_N<3>")
	)
	(arc
		(start 384.877818 -255.871726)
		(mid 384.604896 -255.795823)
		(end 384.329432 -255.86182)
		(width 0.088646)
		(layer "In11.Cu")
		(net "M_H_CPU0_SA_CS_N<3>")
	)
	(arc
		(start 385.252214 -255.871726)
		(mid 385.065016 -255.921869)
		(end 384.877818 -255.871726)
		(width 0.088646)
		(layer "In11.Cu")
		(net "M_H_CPU0_SA_CS_N<3>")
	)
	(arc
		(start 376.794014 -255.87198)
		(mid 376.606816 -255.922123)
		(end 376.419618 -255.87198)
		(width 0.088646)
		(layer "In11.Cu")
		(net "M_H_CPU0_SA_CS_N<3>")
	)
	(arc
		(start 385.743958 -255.836166)
		(mid 385.49399 -255.797469)
		(end 385.252214 -255.871726)
		(width 0.088646)
		(layer "In11.Cu")
		(net "M_H_CPU0_SA_CS_N<3>")
	)
	(arc
		(start 372.660164 -255.87198)
		(mid 372.383605 -255.796237)
		(end 372.105428 -255.865884)
		(width 0.088646)
		(layer "In11.Cu")
		(net "M_H_CPU0_SA_CS_N<3>")
	)
	(arc
		(start 375.479818 -255.87198)
		(mid 375.203005 -255.79611)
		(end 374.924574 -255.865884)
		(width 0.088646)
		(layer "In11.Cu")
		(net "M_H_CPU0_SA_CS_N<3>")
	)
	(arc
		(start 377.733814 -255.87198)
		(mid 377.546616 -255.922123)
		(end 377.359418 -255.87198)
		(width 0.088646)
		(layer "In11.Cu")
		(net "M_H_CPU0_SA_CS_N<3>")
	)
	(arc
		(start 373.03456 -255.87198)
		(mid 372.847362 -255.922123)
		(end 372.660164 -255.87198)
		(width 0.088646)
		(layer "In11.Cu")
		(net "M_H_CPU0_SA_CS_N<3>")
	)
	(arc
		(start 380.178564 -255.87198)
		(mid 379.902005 -255.796237)
		(end 379.623828 -255.865884)
		(width 0.088646)
		(layer "In11.Cu")
		(net "M_H_CPU0_SA_CS_N<3>")
	)
	(arc
		(start 374.914668 -255.87198)
		(mid 374.727216 -255.92225)
		(end 374.539764 -255.87198)
		(width 0.088646)
		(layer "In11.Cu")
		(net "M_H_CPU0_SA_CS_N<3>")
	)
	(arc
		(start 383.37236 -255.87198)
		(mid 383.185162 -255.922123)
		(end 382.997964 -255.87198)
		(width 0.088646)
		(layer "In11.Cu")
		(net "M_H_CPU0_SA_CS_N<3>")
	)
	(arc
		(start 382.432814 -255.87198)
		(mid 382.245616 -255.922123)
		(end 382.058418 -255.87198)
		(width 0.088646)
		(layer "In11.Cu")
		(net "M_H_CPU0_SA_CS_N<3>")
	)
	(arc
		(start 382.058418 -255.87198)
		(mid 381.781605 -255.79611)
		(end 381.503174 -255.865884)
		(width 0.088646)
		(layer "In11.Cu")
		(net "M_H_CPU0_SA_CS_N<3>")
	)
	(segment
		(start 371.907562 -256.639314)
		(end 371.907562 -257.175)
		(width 0.20066)
		(layer "F.Cu")
		(net "M_H_CPU0_SA_CS_N<2>")
	)
	(segment
		(start 371.907562 -257.175)
		(end 371.907816 -257.175254)
		(width 0.20066)
		(layer "F.Cu")
		(net "M_H_CPU0_SA_CS_N<2>")
	)
	(segment
		(start 452.016114 -267.866622)
		(end 450.911214 -267.866622)
		(width 0.20066)
		(layer "F.Cu")
		(net "M_H_CPU0_SA_CS_N<2>")
	)
	(segment
		(start 437.64073 -264.747502)
		(end 437.49722 -264.891012)
		(width 0.18288)
		(layer "In11.Cu")
		(net "M_H_CPU0_SA_CS_N<2>")
	)
	(segment
		(start 419.89248 -264.99439)
		(end 416.44062 -264.99439)
		(width 0.18288)
		(layer "In11.Cu")
		(net "M_H_CPU0_SA_CS_N<2>")
	)
	(segment
		(start 416.079432 -264.633202)
		(end 412.53791 -264.633202)
		(width 0.18288)
		(layer "In11.Cu")
		(net "M_H_CPU0_SA_CS_N<2>")
	)
	(segment
		(start 416.44062 -264.99439)
		(end 416.079432 -264.633202)
		(width 0.18288)
		(layer "In11.Cu")
		(net "M_H_CPU0_SA_CS_N<2>")
	)
	(segment
		(start 419.993826 -264.893044)
		(end 419.89248 -264.99439)
		(width 0.18288)
		(layer "In11.Cu")
		(net "M_H_CPU0_SA_CS_N<2>")
	)
	(segment
		(start 372.190264 -256.03708)
		(end 372.181374 -256.04216)
		(width 0.088646)
		(layer "In11.Cu")
		(net "M_H_CPU0_SA_CS_N<2>")
	)
	(segment
		(start 409.046426 -264.905744)
		(end 408.776678 -264.635996)
		(width 0.18288)
		(layer "In11.Cu")
		(net "M_H_CPU0_SA_CS_N<2>")
	)
	(segment
		(start 433.559712 -265.536934)
		(end 431.182272 -265.536934)
		(width 0.18288)
		(layer "In11.Cu")
		(net "M_H_CPU0_SA_CS_N<2>")
	)
	(segment
		(start 431.182272 -265.536934)
		(end 430.845722 -265.873484)
		(width 0.18288)
		(layer "In11.Cu")
		(net "M_H_CPU0_SA_CS_N<2>")
	)
	(segment
		(start 406.83815 -264.054082)
		(end 405.22779 -264.054082)
		(width 0.18288)
		(layer "In11.Cu")
		(net "M_H_CPU0_SA_CS_N<2>")
	)
	(segment
		(start 398.09928 -258.799838)
		(end 397.363188 -258.063746)
		(width 0.18288)
		(layer "In11.Cu")
		(net "M_H_CPU0_SA_CS_N<2>")
	)
	(segment
		(start 391.276078 -258.063746)
		(end 389.582406 -256.370074)
		(width 0.18288)
		(layer "In11.Cu")
		(net "M_H_CPU0_SA_CS_N<2>")
	)
	(segment
		(start 378.768864 -256.03708)
		(end 378.754132 -256.045716)
		(width 0.088646)
		(layer "In11.Cu")
		(net "M_H_CPU0_SA_CS_N<2>")
	)
	(segment
		(start 435.036468 -265.038332)
		(end 434.058314 -265.038332)
		(width 0.18288)
		(layer "In11.Cu")
		(net "M_H_CPU0_SA_CS_N<2>")
	)
	(segment
		(start 399.6817 -258.799838)
		(end 398.09928 -258.799838)
		(width 0.18288)
		(layer "In11.Cu")
		(net "M_H_CPU0_SA_CS_N<2>")
	)
	(segment
		(start 385.347464 -256.03708)
		(end 385.332732 -256.045716)
		(width 0.088646)
		(layer "In11.Cu")
		(net "M_H_CPU0_SA_CS_N<2>")
	)
	(segment
		(start 441.517532 -265.56208)
		(end 441.338716 -265.740896)
		(width 0.18288)
		(layer "In11.Cu")
		(net "M_H_CPU0_SA_CS_N<2>")
	)
	(segment
		(start 424.384978 -265.73861)
		(end 423.388536 -264.742168)
		(width 0.18288)
		(layer "In11.Cu")
		(net "M_H_CPU0_SA_CS_N<2>")
	)
	(segment
		(start 435.183788 -264.891012)
		(end 435.036468 -265.038332)
		(width 0.18288)
		(layer "In11.Cu")
		(net "M_H_CPU0_SA_CS_N<2>")
	)
	(segment
		(start 382.528064 -256.03708)
		(end 382.513332 -256.045716)
		(width 0.088646)
		(layer "In11.Cu")
		(net "M_H_CPU0_SA_CS_N<2>")
	)
	(segment
		(start 387.193282 -256.177796)
		(end 385.742434 -256.177796)
		(width 0.088646)
		(layer "In11.Cu")
		(net "M_H_CPU0_SA_CS_N<2>")
	)
	(segment
		(start 372.002812 -256.361438)
		(end 372.002812 -256.376932)
		(width 0.088646)
		(layer "In11.Cu")
		(net "M_H_CPU0_SA_CS_N<2>")
	)
	(segment
		(start 397.363188 -258.063746)
		(end 391.276078 -258.063746)
		(width 0.18288)
		(layer "In11.Cu")
		(net "M_H_CPU0_SA_CS_N<2>")
	)
	(segment
		(start 439.235596 -265.740896)
		(end 438.242202 -264.747502)
		(width 0.18288)
		(layer "In11.Cu")
		(net "M_H_CPU0_SA_CS_N<2>")
	)
	(segment
		(start 421.916352 -264.742168)
		(end 421.765476 -264.893044)
		(width 0.18288)
		(layer "In11.Cu")
		(net "M_H_CPU0_SA_CS_N<2>")
	)
	(segment
		(start 405.227536 -264.053828)
		(end 404.93569 -264.053828)
		(width 0.18288)
		(layer "In11.Cu")
		(net "M_H_CPU0_SA_CS_N<2>")
	)
	(segment
		(start 442.961522 -265.807698)
		(end 442.715904 -265.56208)
		(width 0.18288)
		(layer "In11.Cu")
		(net "M_H_CPU0_SA_CS_N<2>")
	)
	(segment
		(start 387.38556 -256.370074)
		(end 387.193282 -256.177796)
		(width 0.088646)
		(layer "In11.Cu")
		(net "M_H_CPU0_SA_CS_N<2>")
	)
	(segment
		(start 376.889518 -256.03708)
		(end 376.879104 -256.043176)
		(width 0.088646)
		(layer "In11.Cu")
		(net "M_H_CPU0_SA_CS_N<2>")
	)
	(segment
		(start 408.776678 -264.635996)
		(end 407.420064 -264.635996)
		(width 0.18288)
		(layer "In11.Cu")
		(net "M_H_CPU0_SA_CS_N<2>")
	)
	(segment
		(start 371.751352 -256.904236)
		(end 371.907816 -257.175254)
		(width 0.088646)
		(layer "In11.Cu")
		(net "M_H_CPU0_SA_CS_N<2>")
	)
	(segment
		(start 388.129018 -256.370074)
		(end 387.38556 -256.370074)
		(width 0.088646)
		(layer "In11.Cu")
		(net "M_H_CPU0_SA_CS_N<2>")
	)
	(segment
		(start 448.644518 -266.590272)
		(end 447.033904 -266.590272)
		(width 0.18288)
		(layer "In11.Cu")
		(net "M_H_CPU0_SA_CS_N<2>")
	)
	(segment
		(start 427.789848 -265.873484)
		(end 427.654974 -265.73861)
		(width 0.18288)
		(layer "In11.Cu")
		(net "M_H_CPU0_SA_CS_N<2>")
	)
	(segment
		(start 374.069864 -256.03708)
		(end 374.055132 -256.045716)
		(width 0.088646)
		(layer "In11.Cu")
		(net "M_H_CPU0_SA_CS_N<2>")
	)
	(segment
		(start 412.53791 -264.633202)
		(end 412.265368 -264.905744)
		(width 0.18288)
		(layer "In11.Cu")
		(net "M_H_CPU0_SA_CS_N<2>")
	)
	(segment
		(start 434.058314 -265.038332)
		(end 433.559712 -265.536934)
		(width 0.18288)
		(layer "In11.Cu")
		(net "M_H_CPU0_SA_CS_N<2>")
	)
	(segment
		(start 450.911214 -267.866622)
		(end 450.360796 -267.866622)
		(width 0.18288)
		(layer "In11.Cu")
		(net "M_H_CPU0_SA_CS_N<2>")
	)
	(segment
		(start 389.582406 -256.370074)
		(end 388.129018 -256.370074)
		(width 0.18288)
		(layer "In11.Cu")
		(net "M_H_CPU0_SA_CS_N<2>")
	)
	(segment
		(start 446.25133 -265.807698)
		(end 442.961522 -265.807698)
		(width 0.18288)
		(layer "In11.Cu")
		(net "M_H_CPU0_SA_CS_N<2>")
	)
	(segment
		(start 412.265368 -264.905744)
		(end 409.046426 -264.905744)
		(width 0.18288)
		(layer "In11.Cu")
		(net "M_H_CPU0_SA_CS_N<2>")
	)
	(segment
		(start 421.765476 -264.893044)
		(end 419.993826 -264.893044)
		(width 0.18288)
		(layer "In11.Cu")
		(net "M_H_CPU0_SA_CS_N<2>")
	)
	(segment
		(start 377.829064 -256.03708)
		(end 377.81865 -256.043176)
		(width 0.088646)
		(layer "In11.Cu")
		(net "M_H_CPU0_SA_CS_N<2>")
	)
	(segment
		(start 385.742434 -256.177796)
		(end 385.551934 -255.987296)
		(width 0.088646)
		(layer "In11.Cu")
		(net "M_H_CPU0_SA_CS_N<2>")
	)
	(segment
		(start 427.654974 -265.73861)
		(end 424.384978 -265.73861)
		(width 0.18288)
		(layer "In11.Cu")
		(net "M_H_CPU0_SA_CS_N<2>")
	)
	(segment
		(start 447.033904 -266.590272)
		(end 446.25133 -265.807698)
		(width 0.18288)
		(layer "In11.Cu")
		(net "M_H_CPU0_SA_CS_N<2>")
	)
	(segment
		(start 449.22059 -267.166344)
		(end 448.644518 -266.590272)
		(width 0.18288)
		(layer "In11.Cu")
		(net "M_H_CPU0_SA_CS_N<2>")
	)
	(segment
		(start 423.388536 -264.742168)
		(end 421.916352 -264.742168)
		(width 0.18288)
		(layer "In11.Cu")
		(net "M_H_CPU0_SA_CS_N<2>")
	)
	(segment
		(start 375.949464 -256.03708)
		(end 375.934732 -256.045716)
		(width 0.088646)
		(layer "In11.Cu")
		(net "M_H_CPU0_SA_CS_N<2>")
	)
	(segment
		(start 438.242202 -264.747502)
		(end 437.64073 -264.747502)
		(width 0.18288)
		(layer "In11.Cu")
		(net "M_H_CPU0_SA_CS_N<2>")
	)
	(segment
		(start 371.775482 -256.815082)
		(end 371.751352 -256.904236)
		(width 0.088646)
		(layer "In11.Cu")
		(net "M_H_CPU0_SA_CS_N<2>")
	)
	(segment
		(start 407.420064 -264.635996)
		(end 406.83815 -264.054082)
		(width 0.18288)
		(layer "In11.Cu")
		(net "M_H_CPU0_SA_CS_N<2>")
	)
	(segment
		(start 450.360796 -267.866622)
		(end 449.971414 -267.47724)
		(width 0.18288)
		(layer "In11.Cu")
		(net "M_H_CPU0_SA_CS_N<2>")
	)
	(segment
		(start 430.845722 -265.873484)
		(end 427.789848 -265.873484)
		(width 0.18288)
		(layer "In11.Cu")
		(net "M_H_CPU0_SA_CS_N<2>")
	)
	(segment
		(start 405.22779 -264.054082)
		(end 405.227536 -264.053828)
		(width 0.18288)
		(layer "In11.Cu")
		(net "M_H_CPU0_SA_CS_N<2>")
	)
	(segment
		(start 379.708664 -256.03708)
		(end 379.693932 -256.045716)
		(width 0.088646)
		(layer "In11.Cu")
		(net "M_H_CPU0_SA_CS_N<2>")
	)
	(segment
		(start 442.715904 -265.56208)
		(end 441.517532 -265.56208)
		(width 0.18288)
		(layer "In11.Cu")
		(net "M_H_CPU0_SA_CS_N<2>")
	)
	(segment
		(start 441.338716 -265.740896)
		(end 439.235596 -265.740896)
		(width 0.18288)
		(layer "In11.Cu")
		(net "M_H_CPU0_SA_CS_N<2>")
	)
	(segment
		(start 449.971414 -267.47724)
		(end 449.22059 -267.166344)
		(width 0.18288)
		(layer "In11.Cu")
		(net "M_H_CPU0_SA_CS_N<2>")
	)
	(segment
		(start 437.49722 -264.891012)
		(end 435.183788 -264.891012)
		(width 0.18288)
		(layer "In11.Cu")
		(net "M_H_CPU0_SA_CS_N<2>")
	)
	(segment
		(start 404.93569 -264.053828)
		(end 399.6817 -258.799838)
		(width 0.18288)
		(layer "In11.Cu")
		(net "M_H_CPU0_SA_CS_N<2>")
	)
	(arc
		(start 383.467864 -256.03708)
		(mid 383.185162 -256.112856)
		(end 382.90246 -256.03708)
		(width 0.088646)
		(layer "In11.Cu")
		(net "M_H_CPU0_SA_CS_N<2>")
	)
	(arc
		(start 382.90246 -256.03708)
		(mid 382.715262 -255.986937)
		(end 382.528064 -256.03708)
		(width 0.088646)
		(layer "In11.Cu")
		(net "M_H_CPU0_SA_CS_N<2>")
	)
	(arc
		(start 385.551934 -255.987296)
		(mid 385.446123 -255.997513)
		(end 385.347464 -256.03708)
		(width 0.088646)
		(layer "In11.Cu")
		(net "M_H_CPU0_SA_CS_N<2>")
	)
	(arc
		(start 374.44426 -256.03708)
		(mid 374.257062 -255.986937)
		(end 374.069864 -256.03708)
		(width 0.088646)
		(layer "In11.Cu")
		(net "M_H_CPU0_SA_CS_N<2>")
	)
	(arc
		(start 381.588264 -256.03708)
		(mid 381.305562 -256.112856)
		(end 381.02286 -256.03708)
		(width 0.088646)
		(layer "In11.Cu")
		(net "M_H_CPU0_SA_CS_N<2>")
	)
	(arc
		(start 378.20346 -256.03708)
		(mid 378.016262 -255.986937)
		(end 377.829064 -256.03708)
		(width 0.088646)
		(layer "In11.Cu")
		(net "M_H_CPU0_SA_CS_N<2>")
	)
	(arc
		(start 378.754132 -256.045716)
		(mid 378.477657 -256.113036)
		(end 378.20346 -256.03708)
		(width 0.088646)
		(layer "In11.Cu")
		(net "M_H_CPU0_SA_CS_N<2>")
	)
	(arc
		(start 382.513332 -256.045716)
		(mid 382.236857 -256.113036)
		(end 381.96266 -256.03708)
		(width 0.088646)
		(layer "In11.Cu")
		(net "M_H_CPU0_SA_CS_N<2>")
	)
	(arc
		(start 376.32386 -256.03708)
		(mid 376.136662 -255.986937)
		(end 375.949464 -256.03708)
		(width 0.088646)
		(layer "In11.Cu")
		(net "M_H_CPU0_SA_CS_N<2>")
	)
	(arc
		(start 384.407664 -256.03708)
		(mid 384.124962 -256.112856)
		(end 383.84226 -256.03708)
		(width 0.088646)
		(layer "In11.Cu")
		(net "M_H_CPU0_SA_CS_N<2>")
	)
	(arc
		(start 379.14326 -256.03708)
		(mid 378.956062 -255.986937)
		(end 378.768864 -256.03708)
		(width 0.088646)
		(layer "In11.Cu")
		(net "M_H_CPU0_SA_CS_N<2>")
	)
	(arc
		(start 375.934732 -256.045716)
		(mid 375.658257 -256.113036)
		(end 375.38406 -256.03708)
		(width 0.088646)
		(layer "In11.Cu")
		(net "M_H_CPU0_SA_CS_N<2>")
	)
	(arc
		(start 381.96266 -256.03708)
		(mid 381.775462 -255.986937)
		(end 381.588264 -256.03708)
		(width 0.088646)
		(layer "In11.Cu")
		(net "M_H_CPU0_SA_CS_N<2>")
	)
	(arc
		(start 372.002812 -256.376932)
		(mid 371.939468 -256.622109)
		(end 371.775482 -256.815082)
		(width 0.088646)
		(layer "In11.Cu")
		(net "M_H_CPU0_SA_CS_N<2>")
	)
	(arc
		(start 384.78206 -256.03708)
		(mid 384.594862 -255.986937)
		(end 384.407664 -256.03708)
		(width 0.088646)
		(layer "In11.Cu")
		(net "M_H_CPU0_SA_CS_N<2>")
	)
	(arc
		(start 381.02286 -256.03708)
		(mid 380.835662 -255.986937)
		(end 380.648464 -256.03708)
		(width 0.088646)
		(layer "In11.Cu")
		(net "M_H_CPU0_SA_CS_N<2>")
	)
	(arc
		(start 383.84226 -256.03708)
		(mid 383.655062 -255.986937)
		(end 383.467864 -256.03708)
		(width 0.088646)
		(layer "In11.Cu")
		(net "M_H_CPU0_SA_CS_N<2>")
	)
	(arc
		(start 379.693932 -256.045716)
		(mid 379.417457 -256.113036)
		(end 379.14326 -256.03708)
		(width 0.088646)
		(layer "In11.Cu")
		(net "M_H_CPU0_SA_CS_N<2>")
	)
	(arc
		(start 385.332732 -256.045716)
		(mid 385.056291 -256.112882)
		(end 384.78206 -256.03708)
		(width 0.088646)
		(layer "In11.Cu")
		(net "M_H_CPU0_SA_CS_N<2>")
	)
	(arc
		(start 375.009664 -256.03708)
		(mid 374.726962 -256.112856)
		(end 374.44426 -256.03708)
		(width 0.088646)
		(layer "In11.Cu")
		(net "M_H_CPU0_SA_CS_N<2>")
	)
	(arc
		(start 373.130064 -256.03708)
		(mid 372.847362 -256.112856)
		(end 372.56466 -256.03708)
		(width 0.088646)
		(layer "In11.Cu")
		(net "M_H_CPU0_SA_CS_N<2>")
	)
	(arc
		(start 376.879104 -256.043176)
		(mid 376.600672 -256.113022)
		(end 376.32386 -256.03708)
		(width 0.088646)
		(layer "In11.Cu")
		(net "M_H_CPU0_SA_CS_N<2>")
	)
	(arc
		(start 372.181374 -256.04216)
		(mid 372.05046 -256.17852)
		(end 372.002812 -256.361438)
		(width 0.088646)
		(layer "In11.Cu")
		(net "M_H_CPU0_SA_CS_N<2>")
	)
	(arc
		(start 377.263914 -256.03708)
		(mid 377.076716 -255.986937)
		(end 376.889518 -256.03708)
		(width 0.088646)
		(layer "In11.Cu")
		(net "M_H_CPU0_SA_CS_N<2>")
	)
	(arc
		(start 380.648464 -256.03708)
		(mid 380.365762 -256.112856)
		(end 380.08306 -256.03708)
		(width 0.088646)
		(layer "In11.Cu")
		(net "M_H_CPU0_SA_CS_N<2>")
	)
	(arc
		(start 375.38406 -256.03708)
		(mid 375.196862 -255.986937)
		(end 375.009664 -256.03708)
		(width 0.088646)
		(layer "In11.Cu")
		(net "M_H_CPU0_SA_CS_N<2>")
	)
	(arc
		(start 377.81865 -256.043176)
		(mid 377.540472 -256.112899)
		(end 377.263914 -256.03708)
		(width 0.088646)
		(layer "In11.Cu")
		(net "M_H_CPU0_SA_CS_N<2>")
	)
	(arc
		(start 374.055132 -256.045716)
		(mid 373.778657 -256.113036)
		(end 373.50446 -256.03708)
		(width 0.088646)
		(layer "In11.Cu")
		(net "M_H_CPU0_SA_CS_N<2>")
	)
	(arc
		(start 372.56466 -256.03708)
		(mid 372.377462 -255.986937)
		(end 372.190264 -256.03708)
		(width 0.088646)
		(layer "In11.Cu")
		(net "M_H_CPU0_SA_CS_N<2>")
	)
	(arc
		(start 373.50446 -256.03708)
		(mid 373.317262 -255.986937)
		(end 373.130064 -256.03708)
		(width 0.088646)
		(layer "In11.Cu")
		(net "M_H_CPU0_SA_CS_N<2>")
	)
	(arc
		(start 380.08306 -256.03708)
		(mid 379.895862 -255.986937)
		(end 379.708664 -256.03708)
		(width 0.088646)
		(layer "In11.Cu")
		(net "M_H_CPU0_SA_CS_N<2>")
	)
	(segment
		(start 462.555082 -267.016738)
		(end 463.659982 -267.016738)
		(width 0.20066)
		(layer "F.Cu")
		(net "M_H_CPU0_SA_CS_N<1>")
	)
	(segment
		(start 373.317516 -255.825498)
		(end 373.317262 -255.825752)
		(width 0.20066)
		(layer "F.Cu")
		(net "M_H_CPU0_SA_CS_N<1>")
	)
	(segment
		(start 373.317262 -255.825752)
		(end 373.317262 -256.361438)
		(width 0.20066)
		(layer "F.Cu")
		(net "M_H_CPU0_SA_CS_N<1>")
	)
	(segment
		(start 459.482444 -267.43914)
		(end 454.694036 -267.43914)
		(width 0.18288)
		(layer "In11.Cu")
		(net "M_H_CPU0_SA_CS_N<1>")
	)
	(segment
		(start 437.164988 -265.740896)
		(end 435.378606 -265.740896)
		(width 0.18288)
		(layer "In11.Cu")
		(net "M_H_CPU0_SA_CS_N<1>")
	)
	(segment
		(start 375.009664 -256.685796)
		(end 374.994932 -256.67716)
		(width 0.088646)
		(layer "In11.Cu")
		(net "M_H_CPU0_SA_CS_N<1>")
	)
	(segment
		(start 379.708664 -256.685796)
		(end 379.693932 -256.67716)
		(width 0.088646)
		(layer "In11.Cu")
		(net "M_H_CPU0_SA_CS_N<1>")
	)
	(segment
		(start 459.624176 -267.580872)
		(end 459.482444 -267.43914)
		(width 0.18288)
		(layer "In11.Cu")
		(net "M_H_CPU0_SA_CS_N<1>")
	)
	(segment
		(start 461.990948 -267.580872)
		(end 459.624176 -267.580872)
		(width 0.18288)
		(layer "In11.Cu")
		(net "M_H_CPU0_SA_CS_N<1>")
	)
	(segment
		(start 449.470526 -268.44117)
		(end 449.098416 -268.06906)
		(width 0.18288)
		(layer "In11.Cu")
		(net "M_H_CPU0_SA_CS_N<1>")
	)
	(segment
		(start 445.959992 -266.454636)
		(end 443.063884 -266.454636)
		(width 0.18288)
		(layer "In11.Cu")
		(net "M_H_CPU0_SA_CS_N<1>")
	)
	(segment
		(start 428.075852 -266.385294)
		(end 427.866048 -266.595098)
		(width 0.18288)
		(layer "In11.Cu")
		(net "M_H_CPU0_SA_CS_N<1>")
	)
	(segment
		(start 376.889518 -256.685796)
		(end 376.879104 -256.6797)
		(width 0.088646)
		(layer "In11.Cu")
		(net "M_H_CPU0_SA_CS_N<1>")
	)
	(segment
		(start 416.124136 -265.864086)
		(end 412.609792 -265.864086)
		(width 0.18288)
		(layer "In11.Cu")
		(net "M_H_CPU0_SA_CS_N<1>")
	)
	(segment
		(start 388.129018 -256.735072)
		(end 387.345936 -256.735072)
		(width 0.088646)
		(layer "In11.Cu")
		(net "M_H_CPU0_SA_CS_N<1>")
	)
	(segment
		(start 397.185388 -258.409186)
		(end 391.132568 -258.409186)
		(width 0.18288)
		(layer "In11.Cu")
		(net "M_H_CPU0_SA_CS_N<1>")
	)
	(segment
		(start 398.085564 -259.309362)
		(end 397.185388 -258.409186)
		(width 0.18288)
		(layer "In11.Cu")
		(net "M_H_CPU0_SA_CS_N<1>")
	)
	(segment
		(start 427.866048 -266.595098)
		(end 424.250358 -266.595098)
		(width 0.18288)
		(layer "In11.Cu")
		(net "M_H_CPU0_SA_CS_N<1>")
	)
	(segment
		(start 430.735486 -266.385294)
		(end 428.075852 -266.385294)
		(width 0.18288)
		(layer "In11.Cu")
		(net "M_H_CPU0_SA_CS_N<1>")
	)
	(segment
		(start 406.368758 -264.66419)
		(end 404.780496 -264.66419)
		(width 0.18288)
		(layer "In11.Cu")
		(net "M_H_CPU0_SA_CS_N<1>")
	)
	(segment
		(start 377.829064 -256.685796)
		(end 377.81865 -256.6797)
		(width 0.088646)
		(layer "In11.Cu")
		(net "M_H_CPU0_SA_CS_N<1>")
	)
	(segment
		(start 423.399966 -265.744706)
		(end 419.936422 -265.744706)
		(width 0.18288)
		(layer "In11.Cu")
		(net "M_H_CPU0_SA_CS_N<1>")
	)
	(segment
		(start 412.609792 -265.864086)
		(end 412.320994 -265.575288)
		(width 0.18288)
		(layer "In11.Cu")
		(net "M_H_CPU0_SA_CS_N<1>")
	)
	(segment
		(start 462.555082 -267.016738)
		(end 461.990948 -267.580872)
		(width 0.18288)
		(layer "In11.Cu")
		(net "M_H_CPU0_SA_CS_N<1>")
	)
	(segment
		(start 439.333894 -266.591034)
		(end 438.624472 -265.881612)
		(width 0.18288)
		(layer "In11.Cu")
		(net "M_H_CPU0_SA_CS_N<1>")
	)
	(segment
		(start 449.098416 -268.06906)
		(end 449.098416 -267.802868)
		(width 0.18288)
		(layer "In11.Cu")
		(net "M_H_CPU0_SA_CS_N<1>")
	)
	(segment
		(start 416.407092 -265.58113)
		(end 416.124136 -265.864086)
		(width 0.18288)
		(layer "In11.Cu")
		(net "M_H_CPU0_SA_CS_N<1>")
	)
	(segment
		(start 373.744744 -256.611628)
		(end 373.456962 -256.41935)
		(width 0.088646)
		(layer "In11.Cu")
		(net "M_H_CPU0_SA_CS_N<1>")
	)
	(segment
		(start 441.01385 -266.765786)
		(end 440.839098 -266.591034)
		(width 0.18288)
		(layer "In11.Cu")
		(net "M_H_CPU0_SA_CS_N<1>")
	)
	(segment
		(start 389.458454 -256.735072)
		(end 388.129018 -256.735072)
		(width 0.18288)
		(layer "In11.Cu")
		(net "M_H_CPU0_SA_CS_N<1>")
	)
	(segment
		(start 454.508108 -267.625068)
		(end 451.988174 -267.625068)
		(width 0.18288)
		(layer "In11.Cu")
		(net "M_H_CPU0_SA_CS_N<1>")
	)
	(segment
		(start 442.752734 -266.765786)
		(end 441.01385 -266.765786)
		(width 0.18288)
		(layer "In11.Cu")
		(net "M_H_CPU0_SA_CS_N<1>")
	)
	(segment
		(start 412.320994 -265.575288)
		(end 409.523692 -265.575288)
		(width 0.18288)
		(layer "In11.Cu")
		(net "M_H_CPU0_SA_CS_N<1>")
	)
	(segment
		(start 451.988174 -267.625068)
		(end 451.319646 -268.293596)
		(width 0.18288)
		(layer "In11.Cu")
		(net "M_H_CPU0_SA_CS_N<1>")
	)
	(segment
		(start 435.200044 -265.562334)
		(end 434.295296 -265.562334)
		(width 0.18288)
		(layer "In11.Cu")
		(net "M_H_CPU0_SA_CS_N<1>")
	)
	(segment
		(start 437.305704 -265.881612)
		(end 437.164988 -265.740896)
		(width 0.18288)
		(layer "In11.Cu")
		(net "M_H_CPU0_SA_CS_N<1>")
	)
	(segment
		(start 404.780496 -264.66419)
		(end 399.425668 -259.309362)
		(width 0.18288)
		(layer "In11.Cu")
		(net "M_H_CPU0_SA_CS_N<1>")
	)
	(segment
		(start 433.267104 -266.590526)
		(end 430.940718 -266.590526)
		(width 0.18288)
		(layer "In11.Cu")
		(net "M_H_CPU0_SA_CS_N<1>")
	)
	(segment
		(start 450.60489 -268.293596)
		(end 450.457316 -268.44117)
		(width 0.18288)
		(layer "In11.Cu")
		(net "M_H_CPU0_SA_CS_N<1>")
	)
	(segment
		(start 419.772846 -265.58113)
		(end 416.407092 -265.58113)
		(width 0.18288)
		(layer "In11.Cu")
		(net "M_H_CPU0_SA_CS_N<1>")
	)
	(segment
		(start 448.74053 -267.444982)
		(end 446.950338 -267.444982)
		(width 0.18288)
		(layer "In11.Cu")
		(net "M_H_CPU0_SA_CS_N<1>")
	)
	(segment
		(start 387.345936 -256.735072)
		(end 387.227064 -256.685796)
		(width 0.088646)
		(layer "In11.Cu")
		(net "M_H_CPU0_SA_CS_N<1>")
	)
	(segment
		(start 454.694036 -267.43914)
		(end 454.508108 -267.625068)
		(width 0.18288)
		(layer "In11.Cu")
		(net "M_H_CPU0_SA_CS_N<1>")
	)
	(segment
		(start 419.936422 -265.744706)
		(end 419.772846 -265.58113)
		(width 0.18288)
		(layer "In11.Cu")
		(net "M_H_CPU0_SA_CS_N<1>")
	)
	(segment
		(start 435.378606 -265.740896)
		(end 435.200044 -265.562334)
		(width 0.18288)
		(layer "In11.Cu")
		(net "M_H_CPU0_SA_CS_N<1>")
	)
	(segment
		(start 381.588264 -256.685796)
		(end 381.573532 -256.67716)
		(width 0.088646)
		(layer "In11.Cu")
		(net "M_H_CPU0_SA_CS_N<1>")
	)
	(segment
		(start 438.624472 -265.881612)
		(end 437.305704 -265.881612)
		(width 0.18288)
		(layer "In11.Cu")
		(net "M_H_CPU0_SA_CS_N<1>")
	)
	(segment
		(start 440.839098 -266.591034)
		(end 439.333894 -266.591034)
		(width 0.18288)
		(layer "In11.Cu")
		(net "M_H_CPU0_SA_CS_N<1>")
	)
	(segment
		(start 434.295296 -265.562334)
		(end 433.267104 -266.590526)
		(width 0.18288)
		(layer "In11.Cu")
		(net "M_H_CPU0_SA_CS_N<1>")
	)
	(segment
		(start 378.768864 -256.685796)
		(end 378.754132 -256.67716)
		(width 0.088646)
		(layer "In11.Cu")
		(net "M_H_CPU0_SA_CS_N<1>")
	)
	(segment
		(start 409.1305 -265.96848)
		(end 407.673048 -265.96848)
		(width 0.18288)
		(layer "In11.Cu")
		(net "M_H_CPU0_SA_CS_N<1>")
	)
	(segment
		(start 443.063884 -266.454636)
		(end 442.752734 -266.765786)
		(width 0.18288)
		(layer "In11.Cu")
		(net "M_H_CPU0_SA_CS_N<1>")
	)
	(segment
		(start 424.250358 -266.595098)
		(end 423.399966 -265.744706)
		(width 0.18288)
		(layer "In11.Cu")
		(net "M_H_CPU0_SA_CS_N<1>")
	)
	(segment
		(start 446.950338 -267.444982)
		(end 445.959992 -266.454636)
		(width 0.18288)
		(layer "In11.Cu")
		(net "M_H_CPU0_SA_CS_N<1>")
	)
	(segment
		(start 391.132568 -258.409186)
		(end 389.458454 -256.735072)
		(width 0.18288)
		(layer "In11.Cu")
		(net "M_H_CPU0_SA_CS_N<1>")
	)
	(segment
		(start 451.319646 -268.293596)
		(end 450.60489 -268.293596)
		(width 0.18288)
		(layer "In11.Cu")
		(net "M_H_CPU0_SA_CS_N<1>")
	)
	(segment
		(start 449.098416 -267.802868)
		(end 448.74053 -267.444982)
		(width 0.18288)
		(layer "In11.Cu")
		(net "M_H_CPU0_SA_CS_N<1>")
	)
	(segment
		(start 373.456962 -256.41935)
		(end 373.317262 -256.361438)
		(width 0.088646)
		(layer "In11.Cu")
		(net "M_H_CPU0_SA_CS_N<1>")
	)
	(segment
		(start 399.425668 -259.309362)
		(end 398.085564 -259.309362)
		(width 0.18288)
		(layer "In11.Cu")
		(net "M_H_CPU0_SA_CS_N<1>")
	)
	(segment
		(start 409.523692 -265.575288)
		(end 409.1305 -265.96848)
		(width 0.18288)
		(layer "In11.Cu")
		(net "M_H_CPU0_SA_CS_N<1>")
	)
	(segment
		(start 430.940718 -266.590526)
		(end 430.735486 -266.385294)
		(width 0.18288)
		(layer "In11.Cu")
		(net "M_H_CPU0_SA_CS_N<1>")
	)
	(segment
		(start 450.457316 -268.44117)
		(end 449.470526 -268.44117)
		(width 0.18288)
		(layer "In11.Cu")
		(net "M_H_CPU0_SA_CS_N<1>")
	)
	(segment
		(start 407.673048 -265.96848)
		(end 406.368758 -264.66419)
		(width 0.18288)
		(layer "In11.Cu")
		(net "M_H_CPU0_SA_CS_N<1>")
	)
	(arc
		(start 387.227064 -256.685796)
		(mid 386.944362 -256.61002)
		(end 386.66166 -256.685796)
		(width 0.088646)
		(layer "In11.Cu")
		(net "M_H_CPU0_SA_CS_N<1>")
	)
	(arc
		(start 383.84226 -256.685796)
		(mid 383.655062 -256.735939)
		(end 383.467864 -256.685796)
		(width 0.088646)
		(layer "In11.Cu")
		(net "M_H_CPU0_SA_CS_N<1>")
	)
	(arc
		(start 384.407664 -256.685796)
		(mid 384.124962 -256.61002)
		(end 383.84226 -256.685796)
		(width 0.088646)
		(layer "In11.Cu")
		(net "M_H_CPU0_SA_CS_N<1>")
	)
	(arc
		(start 381.02286 -256.685796)
		(mid 380.835662 -256.735939)
		(end 380.648464 -256.685796)
		(width 0.088646)
		(layer "In11.Cu")
		(net "M_H_CPU0_SA_CS_N<1>")
	)
	(arc
		(start 386.66166 -256.685796)
		(mid 386.474462 -256.735939)
		(end 386.287264 -256.685796)
		(width 0.088646)
		(layer "In11.Cu")
		(net "M_H_CPU0_SA_CS_N<1>")
	)
	(arc
		(start 379.14326 -256.685796)
		(mid 378.956062 -256.735939)
		(end 378.768864 -256.685796)
		(width 0.088646)
		(layer "In11.Cu")
		(net "M_H_CPU0_SA_CS_N<1>")
	)
	(arc
		(start 377.81865 -256.6797)
		(mid 377.540472 -256.609977)
		(end 377.263914 -256.685796)
		(width 0.088646)
		(layer "In11.Cu")
		(net "M_H_CPU0_SA_CS_N<1>")
	)
	(arc
		(start 374.069864 -256.685796)
		(mid 373.912899 -256.624182)
		(end 373.744744 -256.611628)
		(width 0.088646)
		(layer "In11.Cu")
		(net "M_H_CPU0_SA_CS_N<1>")
	)
	(arc
		(start 374.44426 -256.685796)
		(mid 374.257062 -256.735939)
		(end 374.069864 -256.685796)
		(width 0.088646)
		(layer "In11.Cu")
		(net "M_H_CPU0_SA_CS_N<1>")
	)
	(arc
		(start 377.263914 -256.685796)
		(mid 377.076716 -256.735939)
		(end 376.889518 -256.685796)
		(width 0.088646)
		(layer "In11.Cu")
		(net "M_H_CPU0_SA_CS_N<1>")
	)
	(arc
		(start 384.78206 -256.685796)
		(mid 384.594862 -256.735939)
		(end 384.407664 -256.685796)
		(width 0.088646)
		(layer "In11.Cu")
		(net "M_H_CPU0_SA_CS_N<1>")
	)
	(arc
		(start 379.693932 -256.67716)
		(mid 379.417457 -256.60984)
		(end 379.14326 -256.685796)
		(width 0.088646)
		(layer "In11.Cu")
		(net "M_H_CPU0_SA_CS_N<1>")
	)
	(arc
		(start 382.528064 -256.685796)
		(mid 382.245362 -256.61002)
		(end 381.96266 -256.685796)
		(width 0.088646)
		(layer "In11.Cu")
		(net "M_H_CPU0_SA_CS_N<1>")
	)
	(arc
		(start 382.90246 -256.685796)
		(mid 382.715262 -256.735939)
		(end 382.528064 -256.685796)
		(width 0.088646)
		(layer "In11.Cu")
		(net "M_H_CPU0_SA_CS_N<1>")
	)
	(arc
		(start 386.287264 -256.685796)
		(mid 386.004562 -256.61002)
		(end 385.72186 -256.685796)
		(width 0.088646)
		(layer "In11.Cu")
		(net "M_H_CPU0_SA_CS_N<1>")
	)
	(arc
		(start 376.32386 -256.685796)
		(mid 376.136662 -256.735939)
		(end 375.949464 -256.685796)
		(width 0.088646)
		(layer "In11.Cu")
		(net "M_H_CPU0_SA_CS_N<1>")
	)
	(arc
		(start 385.347464 -256.685796)
		(mid 385.064762 -256.61002)
		(end 384.78206 -256.685796)
		(width 0.088646)
		(layer "In11.Cu")
		(net "M_H_CPU0_SA_CS_N<1>")
	)
	(arc
		(start 383.467864 -256.685796)
		(mid 383.185162 -256.61002)
		(end 382.90246 -256.685796)
		(width 0.088646)
		(layer "In11.Cu")
		(net "M_H_CPU0_SA_CS_N<1>")
	)
	(arc
		(start 381.96266 -256.685796)
		(mid 381.775462 -256.735939)
		(end 381.588264 -256.685796)
		(width 0.088646)
		(layer "In11.Cu")
		(net "M_H_CPU0_SA_CS_N<1>")
	)
	(arc
		(start 378.754132 -256.67716)
		(mid 378.477657 -256.60984)
		(end 378.20346 -256.685796)
		(width 0.088646)
		(layer "In11.Cu")
		(net "M_H_CPU0_SA_CS_N<1>")
	)
	(arc
		(start 378.20346 -256.685796)
		(mid 378.016262 -256.735939)
		(end 377.829064 -256.685796)
		(width 0.088646)
		(layer "In11.Cu")
		(net "M_H_CPU0_SA_CS_N<1>")
	)
	(arc
		(start 380.08306 -256.685796)
		(mid 379.895862 -256.735939)
		(end 379.708664 -256.685796)
		(width 0.088646)
		(layer "In11.Cu")
		(net "M_H_CPU0_SA_CS_N<1>")
	)
	(arc
		(start 374.994932 -256.67716)
		(mid 374.718457 -256.60984)
		(end 374.44426 -256.685796)
		(width 0.088646)
		(layer "In11.Cu")
		(net "M_H_CPU0_SA_CS_N<1>")
	)
	(arc
		(start 376.879104 -256.6797)
		(mid 376.600672 -256.609854)
		(end 376.32386 -256.685796)
		(width 0.088646)
		(layer "In11.Cu")
		(net "M_H_CPU0_SA_CS_N<1>")
	)
	(arc
		(start 380.648464 -256.685796)
		(mid 380.365762 -256.61002)
		(end 380.08306 -256.685796)
		(width 0.088646)
		(layer "In11.Cu")
		(net "M_H_CPU0_SA_CS_N<1>")
	)
	(arc
		(start 375.949464 -256.685796)
		(mid 375.666762 -256.61002)
		(end 375.38406 -256.685796)
		(width 0.088646)
		(layer "In11.Cu")
		(net "M_H_CPU0_SA_CS_N<1>")
	)
	(arc
		(start 381.573532 -256.67716)
		(mid 381.297057 -256.60984)
		(end 381.02286 -256.685796)
		(width 0.088646)
		(layer "In11.Cu")
		(net "M_H_CPU0_SA_CS_N<1>")
	)
	(arc
		(start 385.72186 -256.685796)
		(mid 385.534662 -256.735939)
		(end 385.347464 -256.685796)
		(width 0.088646)
		(layer "In11.Cu")
		(net "M_H_CPU0_SA_CS_N<1>")
	)
	(arc
		(start 375.38406 -256.685796)
		(mid 375.196862 -256.735939)
		(end 375.009664 -256.685796)
		(width 0.088646)
		(layer "In11.Cu")
		(net "M_H_CPU0_SA_CS_N<1>")
	)
	(segment
		(start 372.847362 -256.639314)
		(end 372.847362 -257.175254)
		(width 0.20066)
		(layer "F.Cu")
		(net "M_H_CPU0_SA_CS_N<0>")
	)
	(segment
		(start 458.455014 -267.866622)
		(end 459.559914 -267.866622)
		(width 0.20066)
		(layer "F.Cu")
		(net "M_H_CPU0_SA_CS_N<0>")
	)
	(segment
		(start 373.984774 -256.856992)
		(end 373.97436 -256.850896)
		(width 0.088646)
		(layer "In11.Cu")
		(net "M_H_CPU0_SA_CS_N<0>")
	)
	(segment
		(start 439.360564 -267.442696)
		(end 438.364122 -266.446254)
		(width 0.18288)
		(layer "In11.Cu")
		(net "M_H_CPU0_SA_CS_N<0>")
	)
	(segment
		(start 424.271948 -267.44168)
		(end 423.259758 -266.42949)
		(width 0.18288)
		(layer "In11.Cu")
		(net "M_H_CPU0_SA_CS_N<0>")
	)
	(segment
		(start 375.864374 -256.856992)
		(end 375.85396 -256.850896)
		(width 0.088646)
		(layer "In11.Cu")
		(net "M_H_CPU0_SA_CS_N<0>")
	)
	(segment
		(start 409.089098 -266.577826)
		(end 407.545794 -266.577826)
		(width 0.18288)
		(layer "In11.Cu")
		(net "M_H_CPU0_SA_CS_N<0>")
	)
	(segment
		(start 443.987682 -267.305536)
		(end 443.987682 -268.09065)
		(width 0.18288)
		(layer "In11.Cu")
		(net "M_H_CPU0_SA_CS_N<0>")
	)
	(segment
		(start 451.417944 -269.142972)
		(end 450.268086 -269.142972)
		(width 0.18288)
		(layer "In11.Cu")
		(net "M_H_CPU0_SA_CS_N<0>")
	)
	(segment
		(start 419.981126 -266.799568)
		(end 417.132516 -266.799568)
		(width 0.18288)
		(layer "In11.Cu")
		(net "M_H_CPU0_SA_CS_N<0>")
	)
	(segment
		(start 446.861946 -268.28369)
		(end 444.884302 -268.28369)
		(width 0.18288)
		(layer "In11.Cu")
		(net "M_H_CPU0_SA_CS_N<0>")
	)
	(segment
		(start 452.419466 -268.14145)
		(end 451.417944 -269.142972)
		(width 0.18288)
		(layer "In11.Cu")
		(net "M_H_CPU0_SA_CS_N<0>")
	)
	(segment
		(start 444.884302 -268.28369)
		(end 444.691262 -268.09065)
		(width 0.18288)
		(layer "In11.Cu")
		(net "M_H_CPU0_SA_CS_N<0>")
	)
	(segment
		(start 444.498222 -267.112496)
		(end 444.180722 -267.112496)
		(width 0.18288)
		(layer "In11.Cu")
		(net "M_H_CPU0_SA_CS_N<0>")
	)
	(segment
		(start 443.787022 -268.29131)
		(end 443.171072 -268.29131)
		(width 0.18288)
		(layer "In11.Cu")
		(net "M_H_CPU0_SA_CS_N<0>")
	)
	(segment
		(start 458.455014 -267.866622)
		(end 458.455014 -268.007084)
		(width 0.18288)
		(layer "In11.Cu")
		(net "M_H_CPU0_SA_CS_N<0>")
	)
	(segment
		(start 426.306996 -267.27023)
		(end 426.135546 -267.44168)
		(width 0.18288)
		(layer "In11.Cu")
		(net "M_H_CPU0_SA_CS_N<0>")
	)
	(segment
		(start 450.094604 -268.96949)
		(end 449.187316 -268.96949)
		(width 0.18288)
		(layer "In11.Cu")
		(net "M_H_CPU0_SA_CS_N<0>")
	)
	(segment
		(start 444.691262 -268.09065)
		(end 444.691262 -267.305536)
		(width 0.18288)
		(layer "In11.Cu")
		(net "M_H_CPU0_SA_CS_N<0>")
	)
	(segment
		(start 379.623828 -256.856992)
		(end 379.613414 -256.850896)
		(width 0.088646)
		(layer "In11.Cu")
		(net "M_H_CPU0_SA_CS_N<0>")
	)
	(segment
		(start 396.959582 -258.75488)
		(end 390.989312 -258.75488)
		(width 0.18288)
		(layer "In11.Cu")
		(net "M_H_CPU0_SA_CS_N<0>")
	)
	(segment
		(start 420.190168 -266.590526)
		(end 419.981126 -266.799568)
		(width 0.18288)
		(layer "In11.Cu")
		(net "M_H_CPU0_SA_CS_N<0>")
	)
	(segment
		(start 427.2915 -267.44422)
		(end 427.11751 -267.27023)
		(width 0.18288)
		(layer "In11.Cu")
		(net "M_H_CPU0_SA_CS_N<0>")
	)
	(segment
		(start 443.171072 -268.29131)
		(end 442.231272 -267.35151)
		(width 0.18288)
		(layer "In11.Cu")
		(net "M_H_CPU0_SA_CS_N<0>")
	)
	(segment
		(start 426.135546 -267.44168)
		(end 424.271948 -267.44168)
		(width 0.18288)
		(layer "In11.Cu")
		(net "M_H_CPU0_SA_CS_N<0>")
	)
	(segment
		(start 390.989312 -258.75488)
		(end 389.315452 -257.08102)
		(width 0.18288)
		(layer "In11.Cu")
		(net "M_H_CPU0_SA_CS_N<0>")
	)
	(segment
		(start 450.268086 -269.142972)
		(end 450.094604 -268.96949)
		(width 0.18288)
		(layer "In11.Cu")
		(net "M_H_CPU0_SA_CS_N<0>")
	)
	(segment
		(start 406.72512 -265.757152)
		(end 405.147018 -265.757152)
		(width 0.18288)
		(layer "In11.Cu")
		(net "M_H_CPU0_SA_CS_N<0>")
	)
	(segment
		(start 398.082008 -259.877306)
		(end 396.959582 -258.75488)
		(width 0.18288)
		(layer "In11.Cu")
		(net "M_H_CPU0_SA_CS_N<0>")
	)
	(segment
		(start 448.653662 -268.435836)
		(end 447.014092 -268.435836)
		(width 0.18288)
		(layer "In11.Cu")
		(net "M_H_CPU0_SA_CS_N<0>")
	)
	(segment
		(start 447.014092 -268.435836)
		(end 446.861946 -268.28369)
		(width 0.18288)
		(layer "In11.Cu")
		(net "M_H_CPU0_SA_CS_N<0>")
	)
	(segment
		(start 422.161462 -266.42949)
		(end 422.000426 -266.590526)
		(width 0.18288)
		(layer "In11.Cu")
		(net "M_H_CPU0_SA_CS_N<0>")
	)
	(segment
		(start 388.129018 -257.08102)
		(end 387.361684 -257.08102)
		(width 0.088646)
		(layer "In11.Cu")
		(net "M_H_CPU0_SA_CS_N<0>")
	)
	(segment
		(start 381.503428 -256.856992)
		(end 381.493014 -256.850896)
		(width 0.088646)
		(layer "In11.Cu")
		(net "M_H_CPU0_SA_CS_N<0>")
	)
	(segment
		(start 405.147018 -265.757152)
		(end 399.267172 -259.877306)
		(width 0.18288)
		(layer "In11.Cu")
		(net "M_H_CPU0_SA_CS_N<0>")
	)
	(segment
		(start 449.187316 -268.96949)
		(end 448.653662 -268.435836)
		(width 0.18288)
		(layer "In11.Cu")
		(net "M_H_CPU0_SA_CS_N<0>")
	)
	(segment
		(start 441.075572 -267.35151)
		(end 440.984386 -267.442696)
		(width 0.18288)
		(layer "In11.Cu")
		(net "M_H_CPU0_SA_CS_N<0>")
	)
	(segment
		(start 440.984386 -267.442696)
		(end 439.360564 -267.442696)
		(width 0.18288)
		(layer "In11.Cu")
		(net "M_H_CPU0_SA_CS_N<0>")
	)
	(segment
		(start 374.924828 -256.856992)
		(end 374.914668 -256.850896)
		(width 0.088646)
		(layer "In11.Cu")
		(net "M_H_CPU0_SA_CS_N<0>")
	)
	(segment
		(start 411.965902 -266.7381)
		(end 409.249372 -266.7381)
		(width 0.18288)
		(layer "In11.Cu")
		(net "M_H_CPU0_SA_CS_N<0>")
	)
	(segment
		(start 442.231272 -267.35151)
		(end 441.075572 -267.35151)
		(width 0.18288)
		(layer "In11.Cu")
		(net "M_H_CPU0_SA_CS_N<0>")
	)
	(segment
		(start 378.688346 -256.859532)
		(end 378.673614 -256.850896)
		(width 0.088646)
		(layer "In11.Cu")
		(net "M_H_CPU0_SA_CS_N<0>")
	)
	(segment
		(start 407.545794 -266.577826)
		(end 406.72512 -265.757152)
		(width 0.18288)
		(layer "In11.Cu")
		(net "M_H_CPU0_SA_CS_N<0>")
	)
	(segment
		(start 444.180722 -267.112496)
		(end 443.987682 -267.305536)
		(width 0.18288)
		(layer "In11.Cu")
		(net "M_H_CPU0_SA_CS_N<0>")
	)
	(segment
		(start 453.91451 -268.14145)
		(end 452.419466 -268.14145)
		(width 0.18288)
		(layer "In11.Cu")
		(net "M_H_CPU0_SA_CS_N<0>")
	)
	(segment
		(start 416.910774 -266.577826)
		(end 412.126176 -266.577826)
		(width 0.18288)
		(layer "In11.Cu")
		(net "M_H_CPU0_SA_CS_N<0>")
	)
	(segment
		(start 377.748546 -256.859532)
		(end 377.733814 -256.850896)
		(width 0.088646)
		(layer "In11.Cu")
		(net "M_H_CPU0_SA_CS_N<0>")
	)
	(segment
		(start 458.455014 -268.007084)
		(end 458.387196 -268.17066)
		(width 0.18288)
		(layer "In11.Cu")
		(net "M_H_CPU0_SA_CS_N<0>")
	)
	(segment
		(start 412.126176 -266.577826)
		(end 411.965902 -266.7381)
		(width 0.18288)
		(layer "In11.Cu")
		(net "M_H_CPU0_SA_CS_N<0>")
	)
	(segment
		(start 437.401462 -266.446254)
		(end 437.256682 -266.591034)
		(width 0.18288)
		(layer "In11.Cu")
		(net "M_H_CPU0_SA_CS_N<0>")
	)
	(segment
		(start 380.563374 -256.856992)
		(end 380.55296 -256.850896)
		(width 0.088646)
		(layer "In11.Cu")
		(net "M_H_CPU0_SA_CS_N<0>")
	)
	(segment
		(start 434.919882 -266.591034)
		(end 434.066696 -267.44422)
		(width 0.18288)
		(layer "In11.Cu")
		(net "M_H_CPU0_SA_CS_N<0>")
	)
	(segment
		(start 444.691262 -267.305536)
		(end 444.498222 -267.112496)
		(width 0.18288)
		(layer "In11.Cu")
		(net "M_H_CPU0_SA_CS_N<0>")
	)
	(segment
		(start 389.315452 -257.08102)
		(end 388.129018 -257.08102)
		(width 0.18288)
		(layer "In11.Cu")
		(net "M_H_CPU0_SA_CS_N<0>")
	)
	(segment
		(start 427.11751 -267.27023)
		(end 426.306996 -267.27023)
		(width 0.18288)
		(layer "In11.Cu")
		(net "M_H_CPU0_SA_CS_N<0>")
	)
	(segment
		(start 458.26172 -268.296136)
		(end 454.069196 -268.296136)
		(width 0.18288)
		(layer "In11.Cu")
		(net "M_H_CPU0_SA_CS_N<0>")
	)
	(segment
		(start 372.534688 -257.175254)
		(end 372.847362 -257.175254)
		(width 0.088646)
		(layer "In11.Cu")
		(net "M_H_CPU0_SA_CS_N<0>")
	)
	(segment
		(start 423.259758 -266.42949)
		(end 422.161462 -266.42949)
		(width 0.18288)
		(layer "In11.Cu")
		(net "M_H_CPU0_SA_CS_N<0>")
	)
	(segment
		(start 454.069196 -268.296136)
		(end 453.91451 -268.14145)
		(width 0.18288)
		(layer "In11.Cu")
		(net "M_H_CPU0_SA_CS_N<0>")
	)
	(segment
		(start 422.000426 -266.590526)
		(end 420.190168 -266.590526)
		(width 0.18288)
		(layer "In11.Cu")
		(net "M_H_CPU0_SA_CS_N<0>")
	)
	(segment
		(start 443.987682 -268.09065)
		(end 443.787022 -268.29131)
		(width 0.18288)
		(layer "In11.Cu")
		(net "M_H_CPU0_SA_CS_N<0>")
	)
	(segment
		(start 399.267172 -259.877306)
		(end 398.082008 -259.877306)
		(width 0.18288)
		(layer "In11.Cu")
		(net "M_H_CPU0_SA_CS_N<0>")
	)
	(segment
		(start 434.066696 -267.44422)
		(end 427.2915 -267.44422)
		(width 0.18288)
		(layer "In11.Cu")
		(net "M_H_CPU0_SA_CS_N<0>")
	)
	(segment
		(start 417.132516 -266.799568)
		(end 416.910774 -266.577826)
		(width 0.18288)
		(layer "In11.Cu")
		(net "M_H_CPU0_SA_CS_N<0>")
	)
	(segment
		(start 438.364122 -266.446254)
		(end 437.401462 -266.446254)
		(width 0.18288)
		(layer "In11.Cu")
		(net "M_H_CPU0_SA_CS_N<0>")
	)
	(segment
		(start 409.249372 -266.7381)
		(end 409.089098 -266.577826)
		(width 0.18288)
		(layer "In11.Cu")
		(net "M_H_CPU0_SA_CS_N<0>")
	)
	(segment
		(start 458.387196 -268.17066)
		(end 458.26172 -268.296136)
		(width 0.18288)
		(layer "In11.Cu")
		(net "M_H_CPU0_SA_CS_N<0>")
	)
	(segment
		(start 437.256682 -266.591034)
		(end 434.919882 -266.591034)
		(width 0.18288)
		(layer "In11.Cu")
		(net "M_H_CPU0_SA_CS_N<0>")
	)
	(segment
		(start 372.477538 -257.118104)
		(end 372.534688 -257.175254)
		(width 0.088646)
		(layer "In11.Cu")
		(net "M_H_CPU0_SA_CS_N<0>")
	)
	(segment
		(start 387.361684 -257.08102)
		(end 387.13156 -256.850896)
		(width 0.088646)
		(layer "In11.Cu")
		(net "M_H_CPU0_SA_CS_N<0>")
	)
	(arc
		(start 384.31216 -256.850896)
		(mid 384.124962 -256.800753)
		(end 383.937764 -256.850896)
		(width 0.088646)
		(layer "In11.Cu")
		(net "M_H_CPU0_SA_CS_N<0>")
	)
	(arc
		(start 382.058164 -256.850896)
		(mid 381.781605 -256.926639)
		(end 381.503428 -256.856992)
		(width 0.088646)
		(layer "In11.Cu")
		(net "M_H_CPU0_SA_CS_N<0>")
	)
	(arc
		(start 377.359418 -256.850896)
		(mid 377.076716 -256.926672)
		(end 376.794014 -256.850896)
		(width 0.088646)
		(layer "In11.Cu")
		(net "M_H_CPU0_SA_CS_N<0>")
	)
	(arc
		(start 383.937764 -256.850896)
		(mid 383.655062 -256.926672)
		(end 383.37236 -256.850896)
		(width 0.088646)
		(layer "In11.Cu")
		(net "M_H_CPU0_SA_CS_N<0>")
	)
	(arc
		(start 383.37236 -256.850896)
		(mid 383.185162 -256.800753)
		(end 382.997964 -256.850896)
		(width 0.088646)
		(layer "In11.Cu")
		(net "M_H_CPU0_SA_CS_N<0>")
	)
	(arc
		(start 384.877564 -256.850896)
		(mid 384.594862 -256.926672)
		(end 384.31216 -256.850896)
		(width 0.088646)
		(layer "In11.Cu")
		(net "M_H_CPU0_SA_CS_N<0>")
	)
	(arc
		(start 374.540018 -256.850896)
		(mid 374.263205 -256.926766)
		(end 373.984774 -256.856992)
		(width 0.088646)
		(layer "In11.Cu")
		(net "M_H_CPU0_SA_CS_N<0>")
	)
	(arc
		(start 379.239018 -256.850896)
		(mid 378.964819 -256.926731)
		(end 378.688346 -256.859532)
		(width 0.088646)
		(layer "In11.Cu")
		(net "M_H_CPU0_SA_CS_N<0>")
	)
	(arc
		(start 386.19176 -256.850896)
		(mid 386.004562 -256.800753)
		(end 385.817364 -256.850896)
		(width 0.088646)
		(layer "In11.Cu")
		(net "M_H_CPU0_SA_CS_N<0>")
	)
	(arc
		(start 385.25196 -256.850896)
		(mid 385.064762 -256.800753)
		(end 384.877564 -256.850896)
		(width 0.088646)
		(layer "In11.Cu")
		(net "M_H_CPU0_SA_CS_N<0>")
	)
	(arc
		(start 380.178564 -256.850896)
		(mid 379.902005 -256.926639)
		(end 379.623828 -256.856992)
		(width 0.088646)
		(layer "In11.Cu")
		(net "M_H_CPU0_SA_CS_N<0>")
	)
	(arc
		(start 385.817364 -256.850896)
		(mid 385.534662 -256.926672)
		(end 385.25196 -256.850896)
		(width 0.088646)
		(layer "In11.Cu")
		(net "M_H_CPU0_SA_CS_N<0>")
	)
	(arc
		(start 373.03456 -256.850896)
		(mid 372.847362 -256.800753)
		(end 372.660164 -256.850896)
		(width 0.088646)
		(layer "In11.Cu")
		(net "M_H_CPU0_SA_CS_N<0>")
	)
	(arc
		(start 379.613414 -256.850896)
		(mid 379.426216 -256.800753)
		(end 379.239018 -256.850896)
		(width 0.088646)
		(layer "In11.Cu")
		(net "M_H_CPU0_SA_CS_N<0>")
	)
	(arc
		(start 377.733814 -256.850896)
		(mid 377.546616 -256.800753)
		(end 377.359418 -256.850896)
		(width 0.088646)
		(layer "In11.Cu")
		(net "M_H_CPU0_SA_CS_N<0>")
	)
	(arc
		(start 386.757164 -256.850896)
		(mid 386.474462 -256.926672)
		(end 386.19176 -256.850896)
		(width 0.088646)
		(layer "In11.Cu")
		(net "M_H_CPU0_SA_CS_N<0>")
	)
	(arc
		(start 382.997964 -256.850896)
		(mid 382.715262 -256.926672)
		(end 382.43256 -256.850896)
		(width 0.088646)
		(layer "In11.Cu")
		(net "M_H_CPU0_SA_CS_N<0>")
	)
	(arc
		(start 381.118618 -256.850896)
		(mid 380.841805 -256.926766)
		(end 380.563374 -256.856992)
		(width 0.088646)
		(layer "In11.Cu")
		(net "M_H_CPU0_SA_CS_N<0>")
	)
	(arc
		(start 374.914668 -256.850896)
		(mid 374.72736 -256.800753)
		(end 374.540018 -256.850896)
		(width 0.088646)
		(layer "In11.Cu")
		(net "M_H_CPU0_SA_CS_N<0>")
	)
	(arc
		(start 373.97436 -256.850896)
		(mid 373.787162 -256.800753)
		(end 373.599964 -256.850896)
		(width 0.088646)
		(layer "In11.Cu")
		(net "M_H_CPU0_SA_CS_N<0>")
	)
	(arc
		(start 375.479564 -256.850896)
		(mid 375.203005 -256.926639)
		(end 374.924828 -256.856992)
		(width 0.088646)
		(layer "In11.Cu")
		(net "M_H_CPU0_SA_CS_N<0>")
	)
	(arc
		(start 378.673614 -256.850896)
		(mid 378.486416 -256.800753)
		(end 378.299218 -256.850896)
		(width 0.088646)
		(layer "In11.Cu")
		(net "M_H_CPU0_SA_CS_N<0>")
	)
	(arc
		(start 375.85396 -256.850896)
		(mid 375.666762 -256.800753)
		(end 375.479564 -256.850896)
		(width 0.088646)
		(layer "In11.Cu")
		(net "M_H_CPU0_SA_CS_N<0>")
	)
	(arc
		(start 376.419618 -256.850896)
		(mid 376.142805 -256.926766)
		(end 375.864374 -256.856992)
		(width 0.088646)
		(layer "In11.Cu")
		(net "M_H_CPU0_SA_CS_N<0>")
	)
	(arc
		(start 372.660164 -256.850896)
		(mid 372.538496 -256.963751)
		(end 372.477538 -257.118104)
		(width 0.088646)
		(layer "In11.Cu")
		(net "M_H_CPU0_SA_CS_N<0>")
	)
	(arc
		(start 387.13156 -256.850896)
		(mid 386.944362 -256.800753)
		(end 386.757164 -256.850896)
		(width 0.088646)
		(layer "In11.Cu")
		(net "M_H_CPU0_SA_CS_N<0>")
	)
	(arc
		(start 376.794014 -256.850896)
		(mid 376.606816 -256.800753)
		(end 376.419618 -256.850896)
		(width 0.088646)
		(layer "In11.Cu")
		(net "M_H_CPU0_SA_CS_N<0>")
	)
	(arc
		(start 378.299218 -256.850896)
		(mid 378.025019 -256.926731)
		(end 377.748546 -256.859532)
		(width 0.088646)
		(layer "In11.Cu")
		(net "M_H_CPU0_SA_CS_N<0>")
	)
	(arc
		(start 380.55296 -256.850896)
		(mid 380.365762 -256.800753)
		(end 380.178564 -256.850896)
		(width 0.088646)
		(layer "In11.Cu")
		(net "M_H_CPU0_SA_CS_N<0>")
	)
	(arc
		(start 373.599964 -256.850896)
		(mid 373.317262 -256.926672)
		(end 373.03456 -256.850896)
		(width 0.088646)
		(layer "In11.Cu")
		(net "M_H_CPU0_SA_CS_N<0>")
	)
	(arc
		(start 381.493014 -256.850896)
		(mid 381.305816 -256.800753)
		(end 381.118618 -256.850896)
		(width 0.088646)
		(layer "In11.Cu")
		(net "M_H_CPU0_SA_CS_N<0>")
	)
	(arc
		(start 382.43256 -256.850896)
		(mid 382.245362 -256.800753)
		(end 382.058164 -256.850896)
		(width 0.088646)
		(layer "In11.Cu")
		(net "M_H_CPU0_SA_CS_N<0>")
	)
	(segment
		(start 458.24648 -270.848836)
		(end 458.538326 -270.848836)
		(width 0.20066)
		(layer "F.Cu")
		(net "M_H_CPU0_SA_CB<7>")
	)
	(segment
		(start 461.455516 -270.399002)
		(end 461.689704 -270.164814)
		(width 0.20066)
		(layer "F.Cu")
		(net "M_H_CPU0_SA_CB<7>")
	)
	(segment
		(start 460.558134 -270.841724)
		(end 460.570326 -270.853916)
		(width 0.1016)
		(layer "F.Cu")
		(net "M_H_CPU0_SA_CB<7>")
	)
	(segment
		(start 458.550264 -270.841724)
		(end 460.558134 -270.841724)
		(width 0.1016)
		(layer "F.Cu")
		(net "M_H_CPU0_SA_CB<7>")
	)
	(segment
		(start 461.251554 -270.853916)
		(end 461.455516 -270.649954)
		(width 0.20066)
		(layer "F.Cu")
		(net "M_H_CPU0_SA_CB<7>")
	)
	(segment
		(start 458.543152 -270.848836)
		(end 458.550264 -270.841724)
		(width 0.1016)
		(layer "F.Cu")
		(net "M_H_CPU0_SA_CB<7>")
	)
	(segment
		(start 456.116182 -270.416782)
		(end 457.814426 -270.416782)
		(width 0.20066)
		(layer "F.Cu")
		(net "M_H_CPU0_SA_CB<7>")
	)
	(segment
		(start 461.689704 -270.164814)
		(end 462.073752 -270.164814)
		(width 0.20066)
		(layer "F.Cu")
		(net "M_H_CPU0_SA_CB<7>")
	)
	(segment
		(start 455.011282 -270.416782)
		(end 456.116182 -270.416782)
		(width 0.20066)
		(layer "F.Cu")
		(net "M_H_CPU0_SA_CB<7>")
	)
	(segment
		(start 462.32572 -270.416782)
		(end 463.659982 -270.416782)
		(width 0.20066)
		(layer "F.Cu")
		(net "M_H_CPU0_SA_CB<7>")
	)
	(segment
		(start 460.570326 -270.853916)
		(end 461.251554 -270.853916)
		(width 0.20066)
		(layer "F.Cu")
		(net "M_H_CPU0_SA_CB<7>")
	)
	(segment
		(start 462.073752 -270.164814)
		(end 462.32572 -270.416782)
		(width 0.20066)
		(layer "F.Cu")
		(net "M_H_CPU0_SA_CB<7>")
	)
	(segment
		(start 461.455516 -270.649954)
		(end 461.455516 -270.399002)
		(width 0.20066)
		(layer "F.Cu")
		(net "M_H_CPU0_SA_CB<7>")
	)
	(segment
		(start 457.814426 -270.416782)
		(end 458.24648 -270.848836)
		(width 0.20066)
		(layer "F.Cu")
		(net "M_H_CPU0_SA_CB<7>")
	)
	(segment
		(start 372.847616 -258.267454)
		(end 372.847616 -258.80314)
		(width 0.20066)
		(layer "F.Cu")
		(net "M_H_CPU0_SA_CB<7>")
	)
	(segment
		(start 458.538326 -270.848836)
		(end 458.543152 -270.848836)
		(width 0.101854)
		(layer "F.Cu")
		(net "M_H_CPU0_SA_CB<7>")
	)
	(segment
		(start 372.847362 -258.2672)
		(end 372.847616 -258.267454)
		(width 0.20066)
		(layer "F.Cu")
		(net "M_H_CPU0_SA_CB<7>")
	)
	(segment
		(start 383.852674 -258.307332)
		(end 383.84226 -258.313428)
		(width 0.088646)
		(layer "In11.Cu")
		(net "M_H_CPU0_SA_CB<7>")
	)
	(segment
		(start 414.24352 -269.053818)
		(end 413.92602 -269.053818)
		(width 0.18288)
		(layer "In11.Cu")
		(net "M_H_CPU0_SA_CB<7>")
	)
	(segment
		(start 440.628532 -270.84274)
		(end 439.524902 -270.84274)
		(width 0.18288)
		(layer "In11.Cu")
		(net "M_H_CPU0_SA_CB<7>")
	)
	(segment
		(start 431.603404 -270.119856)
		(end 430.827434 -270.895826)
		(width 0.18288)
		(layer "In11.Cu")
		(net "M_H_CPU0_SA_CB<7>")
	)
	(segment
		(start 406.045162 -269.990824)
		(end 404.490936 -269.990824)
		(width 0.18288)
		(layer "In11.Cu")
		(net "M_H_CPU0_SA_CB<7>")
	)
	(segment
		(start 413.73298 -269.71498)
		(end 413.53994 -269.90802)
		(width 0.18288)
		(layer "In11.Cu")
		(net "M_H_CPU0_SA_CB<7>")
	)
	(segment
		(start 413.92602 -269.053818)
		(end 413.73298 -269.246858)
		(width 0.18288)
		(layer "In11.Cu")
		(net "M_H_CPU0_SA_CB<7>")
	)
	(segment
		(start 437.254396 -270.962628)
		(end 436.282592 -269.990824)
		(width 0.18288)
		(layer "In11.Cu")
		(net "M_H_CPU0_SA_CB<7>")
	)
	(segment
		(start 387.040882 -259.411216)
		(end 385.994148 -258.364482)
		(width 0.088646)
		(layer "In11.Cu")
		(net "M_H_CPU0_SA_CB<7>")
	)
	(segment
		(start 452.675498 -270.840454)
		(end 450.14261 -270.840454)
		(width 0.18288)
		(layer "In11.Cu")
		(net "M_H_CPU0_SA_CB<7>")
	)
	(segment
		(start 450.105018 -270.802862)
		(end 447.181478 -270.802862)
		(width 0.18288)
		(layer "In11.Cu")
		(net "M_H_CPU0_SA_CB<7>")
	)
	(segment
		(start 435.779926 -269.991586)
		(end 435.107334 -269.991586)
		(width 0.18288)
		(layer "In11.Cu")
		(net "M_H_CPU0_SA_CB<7>")
	)
	(segment
		(start 421.469566 -269.990824)
		(end 420.690548 -269.990824)
		(width 0.18288)
		(layer "In11.Cu")
		(net "M_H_CPU0_SA_CB<7>")
	)
	(segment
		(start 420.690548 -269.990824)
		(end 420.689786 -269.991586)
		(width 0.18288)
		(layer "In11.Cu")
		(net "M_H_CPU0_SA_CB<7>")
	)
	(segment
		(start 424.763946 -270.843756)
		(end 424.763184 -270.844518)
		(width 0.18288)
		(layer "In11.Cu")
		(net "M_H_CPU0_SA_CB<7>")
	)
	(segment
		(start 388.378954 -259.411216)
		(end 387.925818 -259.411216)
		(width 0.18288)
		(layer "In11.Cu")
		(net "M_H_CPU0_SA_CB<7>")
	)
	(segment
		(start 416.428428 -270.102838)
		(end 416.23361 -269.90802)
		(width 0.18288)
		(layer "In11.Cu")
		(net "M_H_CPU0_SA_CB<7>")
	)
	(segment
		(start 443.88659 -271.653508)
		(end 442.972952 -271.653508)
		(width 0.18288)
		(layer "In11.Cu")
		(net "M_H_CPU0_SA_CB<7>")
	)
	(segment
		(start 454.190608 -271.236186)
		(end 453.07123 -271.236186)
		(width 0.18288)
		(layer "In11.Cu")
		(net "M_H_CPU0_SA_CB<7>")
	)
	(segment
		(start 434.979064 -270.119856)
		(end 431.603404 -270.119856)
		(width 0.18288)
		(layer "In11.Cu")
		(net "M_H_CPU0_SA_CB<7>")
	)
	(segment
		(start 442.784484 -271.841976)
		(end 441.627768 -271.841976)
		(width 0.18288)
		(layer "In11.Cu")
		(net "M_H_CPU0_SA_CB<7>")
	)
	(segment
		(start 411.43174 -270.114522)
		(end 411.2387 -269.921482)
		(width 0.18288)
		(layer "In11.Cu")
		(net "M_H_CPU0_SA_CB<7>")
	)
	(segment
		(start 444.07963 -271.460468)
		(end 443.88659 -271.653508)
		(width 0.18288)
		(layer "In11.Cu")
		(net "M_H_CPU0_SA_CB<7>")
	)
	(segment
		(start 453.07123 -271.236186)
		(end 452.675498 -270.840454)
		(width 0.18288)
		(layer "In11.Cu")
		(net "M_H_CPU0_SA_CB<7>")
	)
	(segment
		(start 404.490936 -269.990824)
		(end 395.549882 -261.04977)
		(width 0.18288)
		(layer "In11.Cu")
		(net "M_H_CPU0_SA_CB<7>")
	)
	(segment
		(start 423.239184 -269.885414)
		(end 421.574976 -269.885414)
		(width 0.18288)
		(layer "In11.Cu")
		(net "M_H_CPU0_SA_CB<7>")
	)
	(segment
		(start 435.780688 -269.990824)
		(end 435.779926 -269.991586)
		(width 0.18288)
		(layer "In11.Cu")
		(net "M_H_CPU0_SA_CB<7>")
	)
	(segment
		(start 441.627768 -271.841976)
		(end 440.628532 -270.84274)
		(width 0.18288)
		(layer "In11.Cu")
		(net "M_H_CPU0_SA_CB<7>")
	)
	(segment
		(start 384.797046 -258.304792)
		(end 384.782314 -258.313428)
		(width 0.088646)
		(layer "In11.Cu")
		(net "M_H_CPU0_SA_CB<7>")
	)
	(segment
		(start 378.768864 -258.313428)
		(end 378.754132 -258.304792)
		(width 0.088646)
		(layer "In11.Cu")
		(net "M_H_CPU0_SA_CB<7>")
	)
	(segment
		(start 420.689786 -269.991586)
		(end 420.286688 -269.991586)
		(width 0.18288)
		(layer "In11.Cu")
		(net "M_H_CPU0_SA_CB<7>")
	)
	(segment
		(start 410.53512 -269.921482)
		(end 410.34208 -270.114522)
		(width 0.18288)
		(layer "In11.Cu")
		(net "M_H_CPU0_SA_CB<7>")
	)
	(segment
		(start 387.925818 -259.411216)
		(end 387.040882 -259.411216)
		(width 0.088646)
		(layer "In11.Cu")
		(net "M_H_CPU0_SA_CB<7>")
	)
	(segment
		(start 381.588518 -258.313428)
		(end 381.578104 -258.307332)
		(width 0.088646)
		(layer "In11.Cu")
		(net "M_H_CPU0_SA_CB<7>")
	)
	(segment
		(start 410.53512 -269.275814)
		(end 410.53512 -269.921482)
		(width 0.18288)
		(layer "In11.Cu")
		(net "M_H_CPU0_SA_CB<7>")
	)
	(segment
		(start 414.6296 -269.90802)
		(end 414.43656 -269.71498)
		(width 0.18288)
		(layer "In11.Cu")
		(net "M_H_CPU0_SA_CB<7>")
	)
	(segment
		(start 380.648464 -258.313428)
		(end 380.63805 -258.307332)
		(width 0.088646)
		(layer "In11.Cu")
		(net "M_H_CPU0_SA_CB<7>")
	)
	(segment
		(start 427.700694 -270.895826)
		(end 427.472094 -270.667226)
		(width 0.18288)
		(layer "In11.Cu")
		(net "M_H_CPU0_SA_CB<7>")
	)
	(segment
		(start 414.43656 -269.246858)
		(end 414.24352 -269.053818)
		(width 0.18288)
		(layer "In11.Cu")
		(net "M_H_CPU0_SA_CB<7>")
	)
	(segment
		(start 412.505398 -270.114522)
		(end 411.43174 -270.114522)
		(width 0.18288)
		(layer "In11.Cu")
		(net "M_H_CPU0_SA_CB<7>")
	)
	(segment
		(start 411.2387 -269.275814)
		(end 411.04566 -269.082774)
		(width 0.18288)
		(layer "In11.Cu")
		(net "M_H_CPU0_SA_CB<7>")
	)
	(segment
		(start 424.198288 -270.844518)
		(end 423.239184 -269.885414)
		(width 0.18288)
		(layer "In11.Cu")
		(net "M_H_CPU0_SA_CB<7>")
	)
	(segment
		(start 426.385482 -270.667226)
		(end 426.208952 -270.843756)
		(width 0.18288)
		(layer "In11.Cu")
		(net "M_H_CPU0_SA_CB<7>")
	)
	(segment
		(start 411.2387 -269.921482)
		(end 411.2387 -269.275814)
		(width 0.18288)
		(layer "In11.Cu")
		(net "M_H_CPU0_SA_CB<7>")
	)
	(segment
		(start 408.261058 -269.80769)
		(end 406.228296 -269.80769)
		(width 0.18288)
		(layer "In11.Cu")
		(net "M_H_CPU0_SA_CB<7>")
	)
	(segment
		(start 444.97625 -271.653508)
		(end 444.78321 -271.460468)
		(width 0.18288)
		(layer "In11.Cu")
		(net "M_H_CPU0_SA_CB<7>")
	)
	(segment
		(start 374.069864 -258.313428)
		(end 374.05945 -258.307332)
		(width 0.088646)
		(layer "In11.Cu")
		(net "M_H_CPU0_SA_CB<7>")
	)
	(segment
		(start 408.56789 -270.114522)
		(end 408.261058 -269.80769)
		(width 0.18288)
		(layer "In11.Cu")
		(net "M_H_CPU0_SA_CB<7>")
	)
	(segment
		(start 375.949464 -258.313428)
		(end 375.93905 -258.307332)
		(width 0.088646)
		(layer "In11.Cu")
		(net "M_H_CPU0_SA_CB<7>")
	)
	(segment
		(start 444.27267 -270.633952)
		(end 444.07963 -270.826992)
		(width 0.18288)
		(layer "In11.Cu")
		(net "M_H_CPU0_SA_CB<7>")
	)
	(segment
		(start 435.107334 -269.991586)
		(end 434.979064 -270.119856)
		(width 0.18288)
		(layer "In11.Cu")
		(net "M_H_CPU0_SA_CB<7>")
	)
	(segment
		(start 444.59017 -270.633952)
		(end 444.27267 -270.633952)
		(width 0.18288)
		(layer "In11.Cu")
		(net "M_H_CPU0_SA_CB<7>")
	)
	(segment
		(start 436.282592 -269.990824)
		(end 435.780688 -269.990824)
		(width 0.18288)
		(layer "In11.Cu")
		(net "M_H_CPU0_SA_CB<7>")
	)
	(segment
		(start 412.7119 -269.90802)
		(end 412.505398 -270.114522)
		(width 0.18288)
		(layer "In11.Cu")
		(net "M_H_CPU0_SA_CB<7>")
	)
	(segment
		(start 421.574976 -269.885414)
		(end 421.469566 -269.990824)
		(width 0.18288)
		(layer "In11.Cu")
		(net "M_H_CPU0_SA_CB<7>")
	)
	(segment
		(start 395.549882 -261.04977)
		(end 390.017508 -261.04977)
		(width 0.18288)
		(layer "In11.Cu")
		(net "M_H_CPU0_SA_CB<7>")
	)
	(segment
		(start 444.78321 -270.826992)
		(end 444.59017 -270.633952)
		(width 0.18288)
		(layer "In11.Cu")
		(net "M_H_CPU0_SA_CB<7>")
	)
	(segment
		(start 413.53994 -269.90802)
		(end 412.7119 -269.90802)
		(width 0.18288)
		(layer "In11.Cu")
		(net "M_H_CPU0_SA_CB<7>")
	)
	(segment
		(start 375.009918 -258.313428)
		(end 374.999504 -258.307332)
		(width 0.088646)
		(layer "In11.Cu")
		(net "M_H_CPU0_SA_CB<7>")
	)
	(segment
		(start 439.405014 -270.962628)
		(end 437.254396 -270.962628)
		(width 0.18288)
		(layer "In11.Cu")
		(net "M_H_CPU0_SA_CB<7>")
	)
	(segment
		(start 413.73298 -269.246858)
		(end 413.73298 -269.71498)
		(width 0.18288)
		(layer "In11.Cu")
		(net "M_H_CPU0_SA_CB<7>")
	)
	(segment
		(start 439.524902 -270.84274)
		(end 439.405014 -270.962628)
		(width 0.18288)
		(layer "In11.Cu")
		(net "M_H_CPU0_SA_CB<7>")
	)
	(segment
		(start 447.181478 -270.802862)
		(end 446.330832 -271.653508)
		(width 0.18288)
		(layer "In11.Cu")
		(net "M_H_CPU0_SA_CB<7>")
	)
	(segment
		(start 373.504714 -258.313428)
		(end 373.428514 -258.35737)
		(width 0.088646)
		(layer "In11.Cu")
		(net "M_H_CPU0_SA_CB<7>")
	)
	(segment
		(start 444.07963 -270.826992)
		(end 444.07963 -271.460468)
		(width 0.18288)
		(layer "In11.Cu")
		(net "M_H_CPU0_SA_CB<7>")
	)
	(segment
		(start 420.286688 -269.991586)
		(end 420.175436 -270.102838)
		(width 0.18288)
		(layer "In11.Cu")
		(net "M_H_CPU0_SA_CB<7>")
	)
	(segment
		(start 410.72816 -269.082774)
		(end 410.53512 -269.275814)
		(width 0.18288)
		(layer "In11.Cu")
		(net "M_H_CPU0_SA_CB<7>")
	)
	(segment
		(start 426.208952 -270.843756)
		(end 424.763946 -270.843756)
		(width 0.18288)
		(layer "In11.Cu")
		(net "M_H_CPU0_SA_CB<7>")
	)
	(segment
		(start 376.889264 -258.313428)
		(end 376.874532 -258.304792)
		(width 0.088646)
		(layer "In11.Cu")
		(net "M_H_CPU0_SA_CB<7>")
	)
	(segment
		(start 430.827434 -270.895826)
		(end 427.700694 -270.895826)
		(width 0.18288)
		(layer "In11.Cu")
		(net "M_H_CPU0_SA_CB<7>")
	)
	(segment
		(start 406.228296 -269.80769)
		(end 406.045162 -269.990824)
		(width 0.18288)
		(layer "In11.Cu")
		(net "M_H_CPU0_SA_CB<7>")
	)
	(segment
		(start 444.78321 -271.460468)
		(end 444.78321 -270.826992)
		(width 0.18288)
		(layer "In11.Cu")
		(net "M_H_CPU0_SA_CB<7>")
	)
	(segment
		(start 424.763184 -270.844518)
		(end 424.198288 -270.844518)
		(width 0.18288)
		(layer "In11.Cu")
		(net "M_H_CPU0_SA_CB<7>")
	)
	(segment
		(start 420.175436 -270.102838)
		(end 416.428428 -270.102838)
		(width 0.18288)
		(layer "In11.Cu")
		(net "M_H_CPU0_SA_CB<7>")
	)
	(segment
		(start 385.994148 -258.364482)
		(end 385.534916 -258.364482)
		(width 0.088646)
		(layer "In11.Cu")
		(net "M_H_CPU0_SA_CB<7>")
	)
	(segment
		(start 410.34208 -270.114522)
		(end 408.56789 -270.114522)
		(width 0.18288)
		(layer "In11.Cu")
		(net "M_H_CPU0_SA_CB<7>")
	)
	(segment
		(start 379.708918 -258.313428)
		(end 379.698504 -258.307332)
		(width 0.088646)
		(layer "In11.Cu")
		(net "M_H_CPU0_SA_CB<7>")
	)
	(segment
		(start 411.04566 -269.082774)
		(end 410.72816 -269.082774)
		(width 0.18288)
		(layer "In11.Cu")
		(net "M_H_CPU0_SA_CB<7>")
	)
	(segment
		(start 450.14261 -270.840454)
		(end 450.105018 -270.802862)
		(width 0.18288)
		(layer "In11.Cu")
		(net "M_H_CPU0_SA_CB<7>")
	)
	(segment
		(start 455.011282 -270.416782)
		(end 454.190608 -271.236186)
		(width 0.18288)
		(layer "In11.Cu")
		(net "M_H_CPU0_SA_CB<7>")
	)
	(segment
		(start 390.017508 -261.04977)
		(end 388.378954 -259.411216)
		(width 0.18288)
		(layer "In11.Cu")
		(net "M_H_CPU0_SA_CB<7>")
	)
	(segment
		(start 446.330832 -271.653508)
		(end 444.97625 -271.653508)
		(width 0.18288)
		(layer "In11.Cu")
		(net "M_H_CPU0_SA_CB<7>")
	)
	(segment
		(start 416.23361 -269.90802)
		(end 414.6296 -269.90802)
		(width 0.18288)
		(layer "In11.Cu")
		(net "M_H_CPU0_SA_CB<7>")
	)
	(segment
		(start 382.528064 -258.313428)
		(end 382.51765 -258.307332)
		(width 0.088646)
		(layer "In11.Cu")
		(net "M_H_CPU0_SA_CB<7>")
	)
	(segment
		(start 414.43656 -269.71498)
		(end 414.43656 -269.246858)
		(width 0.18288)
		(layer "In11.Cu")
		(net "M_H_CPU0_SA_CB<7>")
	)
	(segment
		(start 442.972952 -271.653508)
		(end 442.784484 -271.841976)
		(width 0.18288)
		(layer "In11.Cu")
		(net "M_H_CPU0_SA_CB<7>")
	)
	(segment
		(start 427.472094 -270.667226)
		(end 426.385482 -270.667226)
		(width 0.18288)
		(layer "In11.Cu")
		(net "M_H_CPU0_SA_CB<7>")
	)
	(arc
		(start 381.578104 -258.307332)
		(mid 381.299672 -258.237518)
		(end 381.02286 -258.313428)
		(width 0.088646)
		(layer "In11.Cu")
		(net "M_H_CPU0_SA_CB<7>")
	)
	(arc
		(start 375.93905 -258.307332)
		(mid 375.660872 -258.23764)
		(end 375.384314 -258.313428)
		(width 0.088646)
		(layer "In11.Cu")
		(net "M_H_CPU0_SA_CB<7>")
	)
	(arc
		(start 373.428514 -258.35737)
		(mid 373.123458 -258.561219)
		(end 372.847616 -258.80314)
		(width 0.088646)
		(layer "In11.Cu")
		(net "M_H_CPU0_SA_CB<7>")
	)
	(arc
		(start 385.534916 -258.364482)
		(mid 385.437966 -258.351253)
		(end 385.347718 -258.313428)
		(width 0.088646)
		(layer "In11.Cu")
		(net "M_H_CPU0_SA_CB<7>")
	)
	(arc
		(start 380.63805 -258.307332)
		(mid 380.359872 -258.23764)
		(end 380.083314 -258.313428)
		(width 0.088646)
		(layer "In11.Cu")
		(net "M_H_CPU0_SA_CB<7>")
	)
	(arc
		(start 385.347718 -258.313428)
		(mid 385.073489 -258.237503)
		(end 384.797046 -258.304792)
		(width 0.088646)
		(layer "In11.Cu")
		(net "M_H_CPU0_SA_CB<7>")
	)
	(arc
		(start 377.829064 -258.313428)
		(mid 377.546362 -258.237686)
		(end 377.26366 -258.313428)
		(width 0.088646)
		(layer "In11.Cu")
		(net "M_H_CPU0_SA_CB<7>")
	)
	(arc
		(start 383.84226 -258.313428)
		(mid 383.655062 -258.363571)
		(end 383.467864 -258.313428)
		(width 0.088646)
		(layer "In11.Cu")
		(net "M_H_CPU0_SA_CB<7>")
	)
	(arc
		(start 380.083314 -258.313428)
		(mid 379.896116 -258.363571)
		(end 379.708918 -258.313428)
		(width 0.088646)
		(layer "In11.Cu")
		(net "M_H_CPU0_SA_CB<7>")
	)
	(arc
		(start 383.467864 -258.313428)
		(mid 383.185162 -258.237686)
		(end 382.90246 -258.313428)
		(width 0.088646)
		(layer "In11.Cu")
		(net "M_H_CPU0_SA_CB<7>")
	)
	(arc
		(start 381.962914 -258.313428)
		(mid 381.775716 -258.363571)
		(end 381.588518 -258.313428)
		(width 0.088646)
		(layer "In11.Cu")
		(net "M_H_CPU0_SA_CB<7>")
	)
	(arc
		(start 377.26366 -258.313428)
		(mid 377.076462 -258.363571)
		(end 376.889264 -258.313428)
		(width 0.088646)
		(layer "In11.Cu")
		(net "M_H_CPU0_SA_CB<7>")
	)
	(arc
		(start 376.874532 -258.304792)
		(mid 376.598091 -258.237626)
		(end 376.32386 -258.313428)
		(width 0.088646)
		(layer "In11.Cu")
		(net "M_H_CPU0_SA_CB<7>")
	)
	(arc
		(start 378.754132 -258.304792)
		(mid 378.477691 -258.237626)
		(end 378.20346 -258.313428)
		(width 0.088646)
		(layer "In11.Cu")
		(net "M_H_CPU0_SA_CB<7>")
	)
	(arc
		(start 379.14326 -258.313428)
		(mid 378.956062 -258.363571)
		(end 378.768864 -258.313428)
		(width 0.088646)
		(layer "In11.Cu")
		(net "M_H_CPU0_SA_CB<7>")
	)
	(arc
		(start 375.384314 -258.313428)
		(mid 375.197116 -258.363571)
		(end 375.009918 -258.313428)
		(width 0.088646)
		(layer "In11.Cu")
		(net "M_H_CPU0_SA_CB<7>")
	)
	(arc
		(start 374.44426 -258.313428)
		(mid 374.257062 -258.363571)
		(end 374.069864 -258.313428)
		(width 0.088646)
		(layer "In11.Cu")
		(net "M_H_CPU0_SA_CB<7>")
	)
	(arc
		(start 384.407918 -258.313428)
		(mid 384.131105 -258.237592)
		(end 383.852674 -258.307332)
		(width 0.088646)
		(layer "In11.Cu")
		(net "M_H_CPU0_SA_CB<7>")
	)
	(arc
		(start 381.02286 -258.313428)
		(mid 380.835662 -258.363571)
		(end 380.648464 -258.313428)
		(width 0.088646)
		(layer "In11.Cu")
		(net "M_H_CPU0_SA_CB<7>")
	)
	(arc
		(start 379.698504 -258.307332)
		(mid 379.420072 -258.237518)
		(end 379.14326 -258.313428)
		(width 0.088646)
		(layer "In11.Cu")
		(net "M_H_CPU0_SA_CB<7>")
	)
	(arc
		(start 374.999504 -258.307332)
		(mid 374.721072 -258.237518)
		(end 374.44426 -258.313428)
		(width 0.088646)
		(layer "In11.Cu")
		(net "M_H_CPU0_SA_CB<7>")
	)
	(arc
		(start 378.20346 -258.313428)
		(mid 378.016262 -258.363571)
		(end 377.829064 -258.313428)
		(width 0.088646)
		(layer "In11.Cu")
		(net "M_H_CPU0_SA_CB<7>")
	)
	(arc
		(start 382.51765 -258.307332)
		(mid 382.239472 -258.23764)
		(end 381.962914 -258.313428)
		(width 0.088646)
		(layer "In11.Cu")
		(net "M_H_CPU0_SA_CB<7>")
	)
	(arc
		(start 376.32386 -258.313428)
		(mid 376.136662 -258.363571)
		(end 375.949464 -258.313428)
		(width 0.088646)
		(layer "In11.Cu")
		(net "M_H_CPU0_SA_CB<7>")
	)
	(arc
		(start 374.05945 -258.307332)
		(mid 373.781272 -258.23764)
		(end 373.504714 -258.313428)
		(width 0.088646)
		(layer "In11.Cu")
		(net "M_H_CPU0_SA_CB<7>")
	)
	(arc
		(start 384.782314 -258.313428)
		(mid 384.595116 -258.363571)
		(end 384.407918 -258.313428)
		(width 0.088646)
		(layer "In11.Cu")
		(net "M_H_CPU0_SA_CB<7>")
	)
	(arc
		(start 382.90246 -258.313428)
		(mid 382.715262 -258.363571)
		(end 382.528064 -258.313428)
		(width 0.088646)
		(layer "In11.Cu")
		(net "M_H_CPU0_SA_CB<7>")
	)
	(segment
		(start 457.814426 -272.116804)
		(end 458.24648 -272.548858)
		(width 0.20066)
		(layer "F.Cu")
		(net "M_H_CPU0_SA_CB<6>")
	)
	(segment
		(start 458.538326 -272.548858)
		(end 458.543152 -272.548858)
		(width 0.101854)
		(layer "F.Cu")
		(net "M_H_CPU0_SA_CB<6>")
	)
	(segment
		(start 460.570326 -272.553938)
		(end 461.251554 -272.553938)
		(width 0.20066)
		(layer "F.Cu")
		(net "M_H_CPU0_SA_CB<6>")
	)
	(segment
		(start 461.251554 -272.553938)
		(end 461.455516 -272.349976)
		(width 0.20066)
		(layer "F.Cu")
		(net "M_H_CPU0_SA_CB<6>")
	)
	(segment
		(start 460.558134 -272.541746)
		(end 460.570326 -272.553938)
		(width 0.1016)
		(layer "F.Cu")
		(net "M_H_CPU0_SA_CB<6>")
	)
	(segment
		(start 373.317516 -259.081016)
		(end 373.317516 -259.093462)
		(width 0.20066)
		(layer "F.Cu")
		(net "M_H_CPU0_SA_CB<6>")
	)
	(segment
		(start 461.689704 -271.864836)
		(end 462.073752 -271.864836)
		(width 0.20066)
		(layer "F.Cu")
		(net "M_H_CPU0_SA_CB<6>")
	)
	(segment
		(start 462.32572 -272.116804)
		(end 463.659982 -272.116804)
		(width 0.20066)
		(layer "F.Cu")
		(net "M_H_CPU0_SA_CB<6>")
	)
	(segment
		(start 456.116182 -272.116804)
		(end 457.814426 -272.116804)
		(width 0.20066)
		(layer "F.Cu")
		(net "M_H_CPU0_SA_CB<6>")
	)
	(segment
		(start 458.543152 -272.548858)
		(end 458.550264 -272.541746)
		(width 0.1016)
		(layer "F.Cu")
		(net "M_H_CPU0_SA_CB<6>")
	)
	(segment
		(start 455.011536 -272.116804)
		(end 456.116182 -272.116804)
		(width 0.20066)
		(layer "F.Cu")
		(net "M_H_CPU0_SA_CB<6>")
	)
	(segment
		(start 461.455516 -272.099024)
		(end 461.689704 -271.864836)
		(width 0.20066)
		(layer "F.Cu")
		(net "M_H_CPU0_SA_CB<6>")
	)
	(segment
		(start 373.317516 -259.093462)
		(end 373.317262 -259.616956)
		(width 0.20066)
		(layer "F.Cu")
		(net "M_H_CPU0_SA_CB<6>")
	)
	(segment
		(start 458.24648 -272.548858)
		(end 458.538326 -272.548858)
		(width 0.20066)
		(layer "F.Cu")
		(net "M_H_CPU0_SA_CB<6>")
	)
	(segment
		(start 462.073752 -271.864836)
		(end 462.32572 -272.116804)
		(width 0.20066)
		(layer "F.Cu")
		(net "M_H_CPU0_SA_CB<6>")
	)
	(segment
		(start 461.455516 -272.349976)
		(end 461.455516 -272.099024)
		(width 0.20066)
		(layer "F.Cu")
		(net "M_H_CPU0_SA_CB<6>")
	)
	(segment
		(start 458.550264 -272.541746)
		(end 460.558134 -272.541746)
		(width 0.1016)
		(layer "F.Cu")
		(net "M_H_CPU0_SA_CB<6>")
	)
	(segment
		(start 455.011282 -272.11655)
		(end 455.011536 -272.116804)
		(width 0.20066)
		(layer "F.Cu")
		(net "M_H_CPU0_SA_CB<6>")
	)
	(segment
		(start 412.417006 -271.702276)
		(end 411.561788 -271.702276)
		(width 0.18288)
		(layer "In11.Cu")
		(net "M_H_CPU0_SA_CB<6>")
	)
	(segment
		(start 441.554362 -273.459956)
		(end 440.637168 -272.542762)
		(width 0.18288)
		(layer "In11.Cu")
		(net "M_H_CPU0_SA_CB<6>")
	)
	(segment
		(start 436.20436 -271.690846)
		(end 435.008274 -271.690846)
		(width 0.18288)
		(layer "In11.Cu")
		(net "M_H_CPU0_SA_CB<6>")
	)
	(segment
		(start 450.596508 -272.542254)
		(end 450.351652 -272.440908)
		(width 0.18288)
		(layer "In11.Cu")
		(net "M_H_CPU0_SA_CB<6>")
	)
	(segment
		(start 427.573694 -272.419826)
		(end 425.863512 -272.419826)
		(width 0.18288)
		(layer "In11.Cu")
		(net "M_H_CPU0_SA_CB<6>")
	)
	(segment
		(start 452.63816 -272.542254)
		(end 452.44512 -272.349214)
		(width 0.18288)
		(layer "In11.Cu")
		(net "M_H_CPU0_SA_CB<6>")
	)
	(segment
		(start 453.293988 -272.800826)
		(end 453.035416 -272.542254)
		(width 0.18288)
		(layer "In11.Cu")
		(net "M_H_CPU0_SA_CB<6>")
	)
	(segment
		(start 410.346906 -271.327118)
		(end 409.971748 -271.702276)
		(width 0.18288)
		(layer "In11.Cu")
		(net "M_H_CPU0_SA_CB<6>")
	)
	(segment
		(start 378.688346 -259.118862)
		(end 378.673614 -259.127498)
		(width 0.088646)
		(layer "In11.Cu")
		(net "M_H_CPU0_SA_CB<6>")
	)
	(segment
		(start 451.74154 -272.349214)
		(end 451.5485 -272.542254)
		(width 0.18288)
		(layer "In11.Cu")
		(net "M_H_CPU0_SA_CB<6>")
	)
	(segment
		(start 434.899308 -271.799812)
		(end 431.775108 -271.799812)
		(width 0.18288)
		(layer "In11.Cu")
		(net "M_H_CPU0_SA_CB<6>")
	)
	(segment
		(start 414.347152 -272.133822)
		(end 414.029652 -272.133822)
		(width 0.18288)
		(layer "In11.Cu")
		(net "M_H_CPU0_SA_CB<6>")
	)
	(segment
		(start 379.628146 -259.118862)
		(end 379.613414 -259.127498)
		(width 0.088646)
		(layer "In11.Cu")
		(net "M_H_CPU0_SA_CB<6>")
	)
	(segment
		(start 404.71725 -271.65427)
		(end 394.81633 -261.75335)
		(width 0.18288)
		(layer "In11.Cu")
		(net "M_H_CPU0_SA_CB<6>")
	)
	(segment
		(start 437.18353 -272.670016)
		(end 436.20436 -271.690846)
		(width 0.18288)
		(layer "In11.Cu")
		(net "M_H_CPU0_SA_CB<6>")
	)
	(segment
		(start 425.863512 -272.419826)
		(end 425.742354 -272.540984)
		(width 0.18288)
		(layer "In11.Cu")
		(net "M_H_CPU0_SA_CB<6>")
	)
	(segment
		(start 386.292598 -259.94487)
		(end 386.27812 -259.936234)
		(width 0.088646)
		(layer "In11.Cu")
		(net "M_H_CPU0_SA_CB<6>")
	)
	(segment
		(start 383.387092 -259.118862)
		(end 383.37236 -259.127498)
		(width 0.088646)
		(layer "In11.Cu")
		(net "M_H_CPU0_SA_CB<6>")
	)
	(segment
		(start 451.5485 -272.542254)
		(end 450.596508 -272.542254)
		(width 0.18288)
		(layer "In11.Cu")
		(net "M_H_CPU0_SA_CB<6>")
	)
	(segment
		(start 422.26738 -271.556734)
		(end 422.133268 -271.690846)
		(width 0.18288)
		(layer "In11.Cu")
		(net "M_H_CPU0_SA_CB<6>")
	)
	(segment
		(start 409.01747 -271.65427)
		(end 404.71725 -271.65427)
		(width 0.18288)
		(layer "In11.Cu")
		(net "M_H_CPU0_SA_CB<6>")
	)
	(segment
		(start 394.81633 -261.75335)
		(end 389.055864 -261.75335)
		(width 0.18288)
		(layer "In11.Cu")
		(net "M_H_CPU0_SA_CB<6>")
	)
	(segment
		(start 413.643572 -271.458182)
		(end 412.6611 -271.458182)
		(width 0.18288)
		(layer "In11.Cu")
		(net "M_H_CPU0_SA_CB<6>")
	)
	(segment
		(start 438.691274 -272.670016)
		(end 437.18353 -272.670016)
		(width 0.18288)
		(layer "In11.Cu")
		(net "M_H_CPU0_SA_CB<6>")
	)
	(segment
		(start 440.637168 -272.542762)
		(end 438.818528 -272.542762)
		(width 0.18288)
		(layer "In11.Cu")
		(net "M_H_CPU0_SA_CB<6>")
	)
	(segment
		(start 419.521894 -271.835626)
		(end 416.786822 -271.835626)
		(width 0.18288)
		(layer "In11.Cu")
		(net "M_H_CPU0_SA_CB<6>")
	)
	(segment
		(start 454.658222 -272.44294)
		(end 454.300336 -272.800826)
		(width 0.18288)
		(layer "In11.Cu")
		(net "M_H_CPU0_SA_CB<6>")
	)
	(segment
		(start 431.775108 -271.799812)
		(end 431.002694 -272.572226)
		(width 0.18288)
		(layer "In11.Cu")
		(net "M_H_CPU0_SA_CB<6>")
	)
	(segment
		(start 452.25208 -271.409922)
		(end 451.93458 -271.409922)
		(width 0.18288)
		(layer "In11.Cu")
		(net "M_H_CPU0_SA_CB<6>")
	)
	(segment
		(start 386.099558 -259.616956)
		(end 386.099558 -259.601462)
		(width 0.088646)
		(layer "In11.Cu")
		(net "M_H_CPU0_SA_CB<6>")
	)
	(segment
		(start 413.836612 -271.651222)
		(end 413.643572 -271.458182)
		(width 0.18288)
		(layer "In11.Cu")
		(net "M_H_CPU0_SA_CB<6>")
	)
	(segment
		(start 412.6611 -271.458182)
		(end 412.417006 -271.702276)
		(width 0.18288)
		(layer "In11.Cu")
		(net "M_H_CPU0_SA_CB<6>")
	)
	(segment
		(start 414.029652 -272.133822)
		(end 413.836612 -271.940782)
		(width 0.18288)
		(layer "In11.Cu")
		(net "M_H_CPU0_SA_CB<6>")
	)
	(segment
		(start 455.011282 -272.11655)
		(end 454.985882 -272.11655)
		(width 0.18288)
		(layer "In11.Cu")
		(net "M_H_CPU0_SA_CB<6>")
	)
	(segment
		(start 377.743974 -259.121402)
		(end 377.73356 -259.127498)
		(width 0.088646)
		(layer "In11.Cu")
		(net "M_H_CPU0_SA_CB<6>")
	)
	(segment
		(start 442.796676 -273.27987)
		(end 442.61659 -273.459956)
		(width 0.18288)
		(layer "In11.Cu")
		(net "M_H_CPU0_SA_CB<6>")
	)
	(segment
		(start 376.804428 -259.121402)
		(end 376.794014 -259.127498)
		(width 0.088646)
		(layer "In11.Cu")
		(net "M_H_CPU0_SA_CB<6>")
	)
	(segment
		(start 411.561788 -271.702276)
		(end 411.18663 -271.327118)
		(width 0.18288)
		(layer "In11.Cu")
		(net "M_H_CPU0_SA_CB<6>")
	)
	(segment
		(start 384.326892 -259.118862)
		(end 384.31216 -259.127498)
		(width 0.088646)
		(layer "In11.Cu")
		(net "M_H_CPU0_SA_CB<6>")
	)
	(segment
		(start 419.666674 -271.690846)
		(end 419.521894 -271.835626)
		(width 0.18288)
		(layer "In11.Cu")
		(net "M_H_CPU0_SA_CB<6>")
	)
	(segment
		(start 427.726094 -272.572226)
		(end 427.573694 -272.419826)
		(width 0.18288)
		(layer "In11.Cu")
		(net "M_H_CPU0_SA_CB<6>")
	)
	(segment
		(start 453.035416 -272.542254)
		(end 452.63816 -272.542254)
		(width 0.18288)
		(layer "In11.Cu")
		(net "M_H_CPU0_SA_CB<6>")
	)
	(segment
		(start 451.93458 -271.409922)
		(end 451.74154 -271.602962)
		(width 0.18288)
		(layer "In11.Cu")
		(net "M_H_CPU0_SA_CB<6>")
	)
	(segment
		(start 413.836612 -271.940782)
		(end 413.836612 -271.651222)
		(width 0.18288)
		(layer "In11.Cu")
		(net "M_H_CPU0_SA_CB<6>")
	)
	(segment
		(start 454.659492 -272.44294)
		(end 454.658222 -272.44294)
		(width 0.18288)
		(layer "In11.Cu")
		(net "M_H_CPU0_SA_CB<6>")
	)
	(segment
		(start 380.567946 -259.118862)
		(end 380.553214 -259.127498)
		(width 0.088646)
		(layer "In11.Cu")
		(net "M_H_CPU0_SA_CB<6>")
	)
	(segment
		(start 387.926072 -260.623558)
		(end 387.66369 -260.361176)
		(width 0.088646)
		(layer "In11.Cu")
		(net "M_H_CPU0_SA_CB<6>")
	)
	(segment
		(start 414.733232 -271.458182)
		(end 414.540192 -271.651222)
		(width 0.18288)
		(layer "In11.Cu")
		(net "M_H_CPU0_SA_CB<6>")
	)
	(segment
		(start 424.316652 -272.540984)
		(end 423.332402 -271.556734)
		(width 0.18288)
		(layer "In11.Cu")
		(net "M_H_CPU0_SA_CB<6>")
	)
	(segment
		(start 454.985882 -272.11655)
		(end 454.659492 -272.44294)
		(width 0.18288)
		(layer "In11.Cu")
		(net "M_H_CPU0_SA_CB<6>")
	)
	(segment
		(start 416.409378 -271.458182)
		(end 414.733232 -271.458182)
		(width 0.18288)
		(layer "In11.Cu")
		(net "M_H_CPU0_SA_CB<6>")
	)
	(segment
		(start 409.971748 -271.702276)
		(end 409.065476 -271.702276)
		(width 0.18288)
		(layer "In11.Cu")
		(net "M_H_CPU0_SA_CB<6>")
	)
	(segment
		(start 452.44512 -272.349214)
		(end 452.44512 -271.602962)
		(width 0.18288)
		(layer "In11.Cu")
		(net "M_H_CPU0_SA_CB<6>")
	)
	(segment
		(start 373.989346 -259.118862)
		(end 373.875808 -259.18541)
		(width 0.088646)
		(layer "In11.Cu")
		(net "M_H_CPU0_SA_CB<6>")
	)
	(segment
		(start 386.71627 -260.361176)
		(end 386.313934 -259.95884)
		(width 0.088646)
		(layer "In11.Cu")
		(net "M_H_CPU0_SA_CB<6>")
	)
	(segment
		(start 414.540192 -271.940782)
		(end 414.347152 -272.133822)
		(width 0.18288)
		(layer "In11.Cu")
		(net "M_H_CPU0_SA_CB<6>")
	)
	(segment
		(start 375.868946 -259.118862)
		(end 375.854214 -259.127498)
		(width 0.088646)
		(layer "In11.Cu")
		(net "M_H_CPU0_SA_CB<6>")
	)
	(segment
		(start 422.133268 -271.690846)
		(end 419.666674 -271.690846)
		(width 0.18288)
		(layer "In11.Cu")
		(net "M_H_CPU0_SA_CB<6>")
	)
	(segment
		(start 382.443228 -259.121402)
		(end 382.432814 -259.127498)
		(width 0.088646)
		(layer "In11.Cu")
		(net "M_H_CPU0_SA_CB<6>")
	)
	(segment
		(start 454.300336 -272.800826)
		(end 453.293988 -272.800826)
		(width 0.18288)
		(layer "In11.Cu")
		(net "M_H_CPU0_SA_CB<6>")
	)
	(segment
		(start 381.507746 -259.118862)
		(end 381.493014 -259.127498)
		(width 0.088646)
		(layer "In11.Cu")
		(net "M_H_CPU0_SA_CB<6>")
	)
	(segment
		(start 450.351652 -272.440908)
		(end 447.12255 -272.440908)
		(width 0.18288)
		(layer "In11.Cu")
		(net "M_H_CPU0_SA_CB<6>")
	)
	(segment
		(start 385.266692 -259.118862)
		(end 385.25196 -259.127498)
		(width 0.088646)
		(layer "In11.Cu")
		(net "M_H_CPU0_SA_CB<6>")
	)
	(segment
		(start 386.313934 -259.95884)
		(end 386.292598 -259.94487)
		(width 0.088646)
		(layer "In11.Cu")
		(net "M_H_CPU0_SA_CB<6>")
	)
	(segment
		(start 411.18663 -271.327118)
		(end 410.346906 -271.327118)
		(width 0.18288)
		(layer "In11.Cu")
		(net "M_H_CPU0_SA_CB<6>")
	)
	(segment
		(start 438.818528 -272.542762)
		(end 438.691274 -272.670016)
		(width 0.18288)
		(layer "In11.Cu")
		(net "M_H_CPU0_SA_CB<6>")
	)
	(segment
		(start 451.74154 -271.602962)
		(end 451.74154 -272.349214)
		(width 0.18288)
		(layer "In11.Cu")
		(net "M_H_CPU0_SA_CB<6>")
	)
	(segment
		(start 446.283588 -273.27987)
		(end 442.796676 -273.27987)
		(width 0.18288)
		(layer "In11.Cu")
		(net "M_H_CPU0_SA_CB<6>")
	)
	(segment
		(start 416.786822 -271.835626)
		(end 416.409378 -271.458182)
		(width 0.18288)
		(layer "In11.Cu")
		(net "M_H_CPU0_SA_CB<6>")
	)
	(segment
		(start 425.742354 -272.540984)
		(end 424.316652 -272.540984)
		(width 0.18288)
		(layer "In11.Cu")
		(net "M_H_CPU0_SA_CB<6>")
	)
	(segment
		(start 387.66369 -260.361176)
		(end 386.71627 -260.361176)
		(width 0.088646)
		(layer "In11.Cu")
		(net "M_H_CPU0_SA_CB<6>")
	)
	(segment
		(start 447.12255 -272.440908)
		(end 446.283588 -273.27987)
		(width 0.18288)
		(layer "In11.Cu")
		(net "M_H_CPU0_SA_CB<6>")
	)
	(segment
		(start 435.008274 -271.690846)
		(end 434.899308 -271.799812)
		(width 0.18288)
		(layer "In11.Cu")
		(net "M_H_CPU0_SA_CB<6>")
	)
	(segment
		(start 452.44512 -271.602962)
		(end 452.25208 -271.409922)
		(width 0.18288)
		(layer "In11.Cu")
		(net "M_H_CPU0_SA_CB<6>")
	)
	(segment
		(start 431.002694 -272.572226)
		(end 427.726094 -272.572226)
		(width 0.18288)
		(layer "In11.Cu")
		(net "M_H_CPU0_SA_CB<6>")
	)
	(segment
		(start 414.540192 -271.651222)
		(end 414.540192 -271.940782)
		(width 0.18288)
		(layer "In11.Cu")
		(net "M_H_CPU0_SA_CB<6>")
	)
	(segment
		(start 389.055864 -261.75335)
		(end 387.926072 -260.623558)
		(width 0.18288)
		(layer "In11.Cu")
		(net "M_H_CPU0_SA_CB<6>")
	)
	(segment
		(start 409.065476 -271.702276)
		(end 409.01747 -271.65427)
		(width 0.18288)
		(layer "In11.Cu")
		(net "M_H_CPU0_SA_CB<6>")
	)
	(segment
		(start 442.61659 -273.459956)
		(end 441.554362 -273.459956)
		(width 0.18288)
		(layer "In11.Cu")
		(net "M_H_CPU0_SA_CB<6>")
	)
	(segment
		(start 423.332402 -271.556734)
		(end 422.26738 -271.556734)
		(width 0.18288)
		(layer "In11.Cu")
		(net "M_H_CPU0_SA_CB<6>")
	)
	(segment
		(start 374.929146 -259.118862)
		(end 374.914668 -259.127498)
		(width 0.088646)
		(layer "In11.Cu")
		(net "M_H_CPU0_SA_CB<6>")
	)
	(arc
		(start 382.432814 -259.127498)
		(mid 382.245616 -259.177641)
		(end 382.058418 -259.127498)
		(width 0.088646)
		(layer "In11.Cu")
		(net "M_H_CPU0_SA_CB<6>")
	)
	(arc
		(start 382.058418 -259.127498)
		(mid 381.784219 -259.051663)
		(end 381.507746 -259.118862)
		(width 0.088646)
		(layer "In11.Cu")
		(net "M_H_CPU0_SA_CB<6>")
	)
	(arc
		(start 384.31216 -259.127498)
		(mid 384.124962 -259.177641)
		(end 383.937764 -259.127498)
		(width 0.088646)
		(layer "In11.Cu")
		(net "M_H_CPU0_SA_CB<6>")
	)
	(arc
		(start 385.25196 -259.127498)
		(mid 385.064762 -259.177641)
		(end 384.877564 -259.127498)
		(width 0.088646)
		(layer "In11.Cu")
		(net "M_H_CPU0_SA_CB<6>")
	)
	(arc
		(start 377.73356 -259.127498)
		(mid 377.546362 -259.177641)
		(end 377.359164 -259.127498)
		(width 0.088646)
		(layer "In11.Cu")
		(net "M_H_CPU0_SA_CB<6>")
	)
	(arc
		(start 374.540018 -259.127498)
		(mid 374.265819 -259.051663)
		(end 373.989346 -259.118862)
		(width 0.088646)
		(layer "In11.Cu")
		(net "M_H_CPU0_SA_CB<6>")
	)
	(arc
		(start 378.673614 -259.127498)
		(mid 378.486416 -259.177641)
		(end 378.299218 -259.127498)
		(width 0.088646)
		(layer "In11.Cu")
		(net "M_H_CPU0_SA_CB<6>")
	)
	(arc
		(start 383.937764 -259.127498)
		(mid 383.663565 -259.051663)
		(end 383.387092 -259.118862)
		(width 0.088646)
		(layer "In11.Cu")
		(net "M_H_CPU0_SA_CB<6>")
	)
	(arc
		(start 373.875808 -259.18541)
		(mid 373.582752 -259.383343)
		(end 373.317262 -259.616956)
		(width 0.088646)
		(layer "In11.Cu")
		(net "M_H_CPU0_SA_CB<6>")
	)
	(arc
		(start 381.493014 -259.127498)
		(mid 381.305816 -259.177641)
		(end 381.118618 -259.127498)
		(width 0.088646)
		(layer "In11.Cu")
		(net "M_H_CPU0_SA_CB<6>")
	)
	(arc
		(start 375.479818 -259.127498)
		(mid 375.205619 -259.051663)
		(end 374.929146 -259.118862)
		(width 0.088646)
		(layer "In11.Cu")
		(net "M_H_CPU0_SA_CB<6>")
	)
	(arc
		(start 382.997964 -259.127498)
		(mid 382.721405 -259.051755)
		(end 382.443228 -259.121402)
		(width 0.088646)
		(layer "In11.Cu")
		(net "M_H_CPU0_SA_CB<6>")
	)
	(arc
		(start 380.178818 -259.127498)
		(mid 379.904619 -259.051663)
		(end 379.628146 -259.118862)
		(width 0.088646)
		(layer "In11.Cu")
		(net "M_H_CPU0_SA_CB<6>")
	)
	(arc
		(start 377.359164 -259.127498)
		(mid 377.082605 -259.051755)
		(end 376.804428 -259.121402)
		(width 0.088646)
		(layer "In11.Cu")
		(net "M_H_CPU0_SA_CB<6>")
	)
	(arc
		(start 376.794014 -259.127498)
		(mid 376.606816 -259.177641)
		(end 376.419618 -259.127498)
		(width 0.088646)
		(layer "In11.Cu")
		(net "M_H_CPU0_SA_CB<6>")
	)
	(arc
		(start 383.37236 -259.127498)
		(mid 383.185162 -259.177641)
		(end 382.997964 -259.127498)
		(width 0.088646)
		(layer "In11.Cu")
		(net "M_H_CPU0_SA_CB<6>")
	)
	(arc
		(start 374.914668 -259.127498)
		(mid 374.72736 -259.177641)
		(end 374.540018 -259.127498)
		(width 0.088646)
		(layer "In11.Cu")
		(net "M_H_CPU0_SA_CB<6>")
	)
	(arc
		(start 386.099558 -259.601462)
		(mid 386.020188 -259.327728)
		(end 385.817364 -259.127498)
		(width 0.088646)
		(layer "In11.Cu")
		(net "M_H_CPU0_SA_CB<6>")
	)
	(arc
		(start 384.877564 -259.127498)
		(mid 384.603365 -259.051663)
		(end 384.326892 -259.118862)
		(width 0.088646)
		(layer "In11.Cu")
		(net "M_H_CPU0_SA_CB<6>")
	)
	(arc
		(start 380.553214 -259.127498)
		(mid 380.366016 -259.177641)
		(end 380.178818 -259.127498)
		(width 0.088646)
		(layer "In11.Cu")
		(net "M_H_CPU0_SA_CB<6>")
	)
	(arc
		(start 379.613414 -259.127498)
		(mid 379.426216 -259.177641)
		(end 379.239018 -259.127498)
		(width 0.088646)
		(layer "In11.Cu")
		(net "M_H_CPU0_SA_CB<6>")
	)
	(arc
		(start 386.27812 -259.936234)
		(mid 386.147206 -259.799874)
		(end 386.099558 -259.616956)
		(width 0.088646)
		(layer "In11.Cu")
		(net "M_H_CPU0_SA_CB<6>")
	)
	(arc
		(start 385.817364 -259.127498)
		(mid 385.543165 -259.051663)
		(end 385.266692 -259.118862)
		(width 0.088646)
		(layer "In11.Cu")
		(net "M_H_CPU0_SA_CB<6>")
	)
	(arc
		(start 379.239018 -259.127498)
		(mid 378.964819 -259.051663)
		(end 378.688346 -259.118862)
		(width 0.088646)
		(layer "In11.Cu")
		(net "M_H_CPU0_SA_CB<6>")
	)
	(arc
		(start 378.299218 -259.127498)
		(mid 378.022405 -259.051628)
		(end 377.743974 -259.121402)
		(width 0.088646)
		(layer "In11.Cu")
		(net "M_H_CPU0_SA_CB<6>")
	)
	(arc
		(start 375.854214 -259.127498)
		(mid 375.667016 -259.177641)
		(end 375.479818 -259.127498)
		(width 0.088646)
		(layer "In11.Cu")
		(net "M_H_CPU0_SA_CB<6>")
	)
	(arc
		(start 381.118618 -259.127498)
		(mid 380.844419 -259.051663)
		(end 380.567946 -259.118862)
		(width 0.088646)
		(layer "In11.Cu")
		(net "M_H_CPU0_SA_CB<6>")
	)
	(arc
		(start 376.419618 -259.127498)
		(mid 376.145419 -259.051663)
		(end 375.868946 -259.118862)
		(width 0.088646)
		(layer "In11.Cu")
		(net "M_H_CPU0_SA_CB<6>")
	)
	(segment
		(start 371.907562 -258.2672)
		(end 371.907816 -258.267454)
		(width 0.20066)
		(layer "F.Cu")
		(net "M_H_CPU0_SA_CB<5>")
	)
	(segment
		(start 452.016114 -271.266666)
		(end 450.911214 -271.266666)
		(width 0.20066)
		(layer "F.Cu")
		(net "M_H_CPU0_SA_CB<5>")
	)
	(segment
		(start 453.785478 -271.515332)
		(end 453.536812 -271.266666)
		(width 0.20066)
		(layer "F.Cu")
		(net "M_H_CPU0_SA_CB<5>")
	)
	(segment
		(start 454.448672 -271.327372)
		(end 454.260712 -271.515332)
		(width 0.20066)
		(layer "F.Cu")
		(net "M_H_CPU0_SA_CB<5>")
	)
	(segment
		(start 459.55966 -271.26692)
		(end 457.968096 -271.26692)
		(width 0.20066)
		(layer "F.Cu")
		(net "M_H_CPU0_SA_CB<5>")
	)
	(segment
		(start 454.931526 -270.841724)
		(end 454.91146 -270.841724)
		(width 0.101854)
		(layer "F.Cu")
		(net "M_H_CPU0_SA_CB<5>")
	)
	(segment
		(start 454.566782 -270.841724)
		(end 454.448672 -270.959834)
		(width 0.20066)
		(layer "F.Cu")
		(net "M_H_CPU0_SA_CB<5>")
	)
	(segment
		(start 457.53655 -270.835374)
		(end 457.126594 -270.835374)
		(width 0.20066)
		(layer "F.Cu")
		(net "M_H_CPU0_SA_CB<5>")
	)
	(segment
		(start 454.91146 -270.841724)
		(end 454.566782 -270.841724)
		(width 0.20066)
		(layer "F.Cu")
		(net "M_H_CPU0_SA_CB<5>")
	)
	(segment
		(start 453.536812 -271.266666)
		(end 452.016114 -271.266666)
		(width 0.20066)
		(layer "F.Cu")
		(net "M_H_CPU0_SA_CB<5>")
	)
	(segment
		(start 457.120244 -270.841724)
		(end 454.931526 -270.841724)
		(width 0.1016)
		(layer "F.Cu")
		(net "M_H_CPU0_SA_CB<5>")
	)
	(segment
		(start 459.559914 -271.266666)
		(end 459.55966 -271.26692)
		(width 0.20066)
		(layer "F.Cu")
		(net "M_H_CPU0_SA_CB<5>")
	)
	(segment
		(start 454.448672 -270.959834)
		(end 454.448672 -271.327372)
		(width 0.20066)
		(layer "F.Cu")
		(net "M_H_CPU0_SA_CB<5>")
	)
	(segment
		(start 457.126594 -270.835374)
		(end 457.120244 -270.841724)
		(width 0.1016)
		(layer "F.Cu")
		(net "M_H_CPU0_SA_CB<5>")
	)
	(segment
		(start 454.260712 -271.515332)
		(end 453.785478 -271.515332)
		(width 0.20066)
		(layer "F.Cu")
		(net "M_H_CPU0_SA_CB<5>")
	)
	(segment
		(start 371.907816 -258.267454)
		(end 371.907816 -258.80314)
		(width 0.20066)
		(layer "F.Cu")
		(net "M_H_CPU0_SA_CB<5>")
	)
	(segment
		(start 457.968096 -271.26692)
		(end 457.53655 -270.835374)
		(width 0.20066)
		(layer "F.Cu")
		(net "M_H_CPU0_SA_CB<5>")
	)
	(segment
		(start 421.520112 -271.136872)
		(end 421.224202 -270.840962)
		(width 0.18288)
		(layer "In11.Cu")
		(net "M_H_CPU0_SA_CB<5>")
	)
	(segment
		(start 433.476654 -271.289018)
		(end 433.283614 -271.095978)
		(width 0.18288)
		(layer "In11.Cu")
		(net "M_H_CPU0_SA_CB<5>")
	)
	(segment
		(start 446.05448 -272.755868)
		(end 444.949834 -272.755868)
		(width 0.18288)
		(layer "In11.Cu")
		(net "M_H_CPU0_SA_CB<5>")
	)
	(segment
		(start 413.590486 -270.922242)
		(end 412.58871 -270.922242)
		(width 0.18288)
		(layer "In11.Cu")
		(net "M_H_CPU0_SA_CB<5>")
	)
	(segment
		(start 416.853878 -270.922242)
		(end 414.680146 -270.922242)
		(width 0.18288)
		(layer "In11.Cu")
		(net "M_H_CPU0_SA_CB<5>")
	)
	(segment
		(start 408.841194 -270.794226)
		(end 408.688794 -270.946626)
		(width 0.18288)
		(layer "In11.Cu")
		(net "M_H_CPU0_SA_CB<5>")
	)
	(segment
		(start 444.563754 -272.02257)
		(end 444.246254 -272.02257)
		(width 0.18288)
		(layer "In11.Cu")
		(net "M_H_CPU0_SA_CB<5>")
	)
	(segment
		(start 389.562086 -261.40791)
		(end 388.078726 -259.92455)
		(width 0.18288)
		(layer "In11.Cu")
		(net "M_H_CPU0_SA_CB<5>")
	)
	(segment
		(start 449.147184 -271.925034)
		(end 448.954144 -271.731994)
		(width 0.18288)
		(layer "In11.Cu")
		(net "M_H_CPU0_SA_CB<5>")
	)
	(segment
		(start 444.053214 -272.562828)
		(end 443.860174 -272.755868)
		(width 0.18288)
		(layer "In11.Cu")
		(net "M_H_CPU0_SA_CB<5>")
	)
	(segment
		(start 448.250564 -271.555718)
		(end 448.250564 -271.731994)
		(width 0.18288)
		(layer "In11.Cu")
		(net "M_H_CPU0_SA_CB<5>")
	)
	(segment
		(start 428.770034 -271.403826)
		(end 428.030894 -271.403826)
		(width 0.18288)
		(layer "In11.Cu")
		(net "M_H_CPU0_SA_CB<5>")
	)
	(segment
		(start 387.925818 -259.92455)
		(end 387.268212 -259.92455)
		(width 0.088646)
		(layer "In11.Cu")
		(net "M_H_CPU0_SA_CB<5>")
	)
	(segment
		(start 426.782738 -271.911826)
		(end 426.274738 -271.403826)
		(width 0.18288)
		(layer "In11.Cu")
		(net "M_H_CPU0_SA_CB<5>")
	)
	(segment
		(start 436.199026 -270.840962)
		(end 435.440836 -270.840962)
		(width 0.18288)
		(layer "In11.Cu")
		(net "M_H_CPU0_SA_CB<5>")
	)
	(segment
		(start 380.567946 -258.487418)
		(end 380.553214 -258.478782)
		(width 0.088646)
		(layer "In11.Cu")
		(net "M_H_CPU0_SA_CB<5>")
	)
	(segment
		(start 442.321696 -272.363184)
		(end 441.239402 -272.363184)
		(width 0.18288)
		(layer "In11.Cu")
		(net "M_H_CPU0_SA_CB<5>")
	)
	(segment
		(start 435.229254 -270.62938)
		(end 434.180234 -270.62938)
		(width 0.18288)
		(layer "In11.Cu")
		(net "M_H_CPU0_SA_CB<5>")
	)
	(segment
		(start 378.688346 -258.487418)
		(end 378.673614 -258.478782)
		(width 0.088646)
		(layer "In11.Cu")
		(net "M_H_CPU0_SA_CB<5>")
	)
	(segment
		(start 423.585894 -271.022826)
		(end 422.848278 -271.022826)
		(width 0.18288)
		(layer "In11.Cu")
		(net "M_H_CPU0_SA_CB<5>")
	)
	(segment
		(start 425.634658 -271.6911)
		(end 424.254168 -271.6911)
		(width 0.18288)
		(layer "In11.Cu")
		(net "M_H_CPU0_SA_CB<5>")
	)
	(segment
		(start 418.289486 -271.324324)
		(end 418.096446 -271.131284)
		(width 0.18288)
		(layer "In11.Cu")
		(net "M_H_CPU0_SA_CB<5>")
	)
	(segment
		(start 429.156114 -272.036032)
		(end 428.963074 -271.842992)
		(width 0.18288)
		(layer "In11.Cu")
		(net "M_H_CPU0_SA_CB<5>")
	)
	(segment
		(start 428.963074 -271.596866)
		(end 428.770034 -271.403826)
		(width 0.18288)
		(layer "In11.Cu")
		(net "M_H_CPU0_SA_CB<5>")
	)
	(segment
		(start 382.433068 -258.478782)
		(end 382.432814 -258.478782)
		(width 0.088646)
		(layer "In11.Cu")
		(net "M_H_CPU0_SA_CB<5>")
	)
	(segment
		(start 448.057524 -271.925034)
		(end 446.885314 -271.925034)
		(width 0.18288)
		(layer "In11.Cu")
		(net "M_H_CPU0_SA_CB<5>")
	)
	(segment
		(start 431.26152 -271.403826)
		(end 429.859694 -271.403826)
		(width 0.18288)
		(layer "In11.Cu")
		(net "M_H_CPU0_SA_CB<5>")
	)
	(segment
		(start 448.954144 -271.555718)
		(end 448.761104 -271.362678)
		(width 0.18288)
		(layer "In11.Cu")
		(net "M_H_CPU0_SA_CB<5>")
	)
	(segment
		(start 440.57062 -271.694402)
		(end 439.418476 -271.694402)
		(width 0.18288)
		(layer "In11.Cu")
		(net "M_H_CPU0_SA_CB<5>")
	)
	(segment
		(start 428.030894 -271.403826)
		(end 427.522894 -271.911826)
		(width 0.18288)
		(layer "In11.Cu")
		(net "M_H_CPU0_SA_CB<5>")
	)
	(segment
		(start 376.804428 -258.484878)
		(end 376.794014 -258.478782)
		(width 0.088646)
		(layer "In11.Cu")
		(net "M_H_CPU0_SA_CB<5>")
	)
	(segment
		(start 419.75151 -270.631158)
		(end 418.993066 -270.631158)
		(width 0.18288)
		(layer "In11.Cu")
		(net "M_H_CPU0_SA_CB<5>")
	)
	(segment
		(start 433.987194 -271.095978)
		(end 433.794154 -271.289018)
		(width 0.18288)
		(layer "In11.Cu")
		(net "M_H_CPU0_SA_CB<5>")
	)
	(segment
		(start 422.848278 -271.022826)
		(end 422.666414 -270.840962)
		(width 0.18288)
		(layer "In11.Cu")
		(net "M_H_CPU0_SA_CB<5>")
	)
	(segment
		(start 433.283614 -270.82242)
		(end 433.090574 -270.62938)
		(width 0.18288)
		(layer "In11.Cu")
		(net "M_H_CPU0_SA_CB<5>")
	)
	(segment
		(start 448.443604 -271.362678)
		(end 448.250564 -271.555718)
		(width 0.18288)
		(layer "In11.Cu")
		(net "M_H_CPU0_SA_CB<5>")
	)
	(segment
		(start 441.239402 -272.363184)
		(end 440.57062 -271.694402)
		(width 0.18288)
		(layer "In11.Cu")
		(net "M_H_CPU0_SA_CB<5>")
	)
	(segment
		(start 414.487106 -270.729202)
		(end 414.487106 -270.484092)
		(width 0.18288)
		(layer "In11.Cu")
		(net "M_H_CPU0_SA_CB<5>")
	)
	(segment
		(start 395.189456 -261.40791)
		(end 389.562086 -261.40791)
		(width 0.18288)
		(layer "In11.Cu")
		(net "M_H_CPU0_SA_CB<5>")
	)
	(segment
		(start 433.987194 -270.82242)
		(end 433.987194 -271.095978)
		(width 0.18288)
		(layer "In11.Cu")
		(net "M_H_CPU0_SA_CB<5>")
	)
	(segment
		(start 373.046498 -259.288026)
		(end 372.76659 -259.288026)
		(width 0.088646)
		(layer "In11.Cu")
		(net "M_H_CPU0_SA_CB<5>")
	)
	(segment
		(start 426.274738 -271.403826)
		(end 425.921932 -271.403826)
		(width 0.18288)
		(layer "In11.Cu")
		(net "M_H_CPU0_SA_CB<5>")
	)
	(segment
		(start 414.680146 -270.922242)
		(end 414.487106 -270.729202)
		(width 0.18288)
		(layer "In11.Cu")
		(net "M_H_CPU0_SA_CB<5>")
	)
	(segment
		(start 428.963074 -271.842992)
		(end 428.963074 -271.596866)
		(width 0.18288)
		(layer "In11.Cu")
		(net "M_H_CPU0_SA_CB<5>")
	)
	(segment
		(start 385.89839 -258.554728)
		(end 385.534916 -258.554728)
		(width 0.088646)
		(layer "In11.Cu")
		(net "M_H_CPU0_SA_CB<5>")
	)
	(segment
		(start 422.666414 -270.840962)
		(end 422.213532 -270.840962)
		(width 0.18288)
		(layer "In11.Cu")
		(net "M_H_CPU0_SA_CB<5>")
	)
	(segment
		(start 404.727918 -270.946372)
		(end 395.189456 -261.40791)
		(width 0.18288)
		(layer "In11.Cu")
		(net "M_H_CPU0_SA_CB<5>")
	)
	(segment
		(start 414.294066 -270.291052)
		(end 413.976566 -270.291052)
		(width 0.18288)
		(layer "In11.Cu")
		(net "M_H_CPU0_SA_CB<5>")
	)
	(segment
		(start 417.903406 -270.631158)
		(end 417.144962 -270.631158)
		(width 0.18288)
		(layer "In11.Cu")
		(net "M_H_CPU0_SA_CB<5>")
	)
	(segment
		(start 388.078726 -259.92455)
		(end 387.925818 -259.92455)
		(width 0.18288)
		(layer "In11.Cu")
		(net "M_H_CPU0_SA_CB<5>")
	)
	(segment
		(start 373.989346 -258.487418)
		(end 373.974614 -258.478782)
		(width 0.088646)
		(layer "In11.Cu")
		(net "M_H_CPU0_SA_CB<5>")
	)
	(segment
		(start 432.035966 -270.62938)
		(end 431.26152 -271.403826)
		(width 0.18288)
		(layer "In11.Cu")
		(net "M_H_CPU0_SA_CB<5>")
	)
	(segment
		(start 413.976566 -270.291052)
		(end 413.783526 -270.484092)
		(width 0.18288)
		(layer "In11.Cu")
		(net "M_H_CPU0_SA_CB<5>")
	)
	(segment
		(start 419.961314 -270.840962)
		(end 419.75151 -270.631158)
		(width 0.18288)
		(layer "In11.Cu")
		(net "M_H_CPU0_SA_CB<5>")
	)
	(segment
		(start 418.606986 -271.324324)
		(end 418.289486 -271.324324)
		(width 0.18288)
		(layer "In11.Cu")
		(net "M_H_CPU0_SA_CB<5>")
	)
	(segment
		(start 444.756794 -272.21561)
		(end 444.563754 -272.02257)
		(width 0.18288)
		(layer "In11.Cu")
		(net "M_H_CPU0_SA_CB<5>")
	)
	(segment
		(start 435.440836 -270.840962)
		(end 435.229254 -270.62938)
		(width 0.18288)
		(layer "In11.Cu")
		(net "M_H_CPU0_SA_CB<5>")
	)
	(segment
		(start 442.71438 -272.755868)
		(end 442.321696 -272.363184)
		(width 0.18288)
		(layer "In11.Cu")
		(net "M_H_CPU0_SA_CB<5>")
	)
	(segment
		(start 450.911214 -271.266666)
		(end 450.252846 -271.925034)
		(width 0.18288)
		(layer "In11.Cu")
		(net "M_H_CPU0_SA_CB<5>")
	)
	(segment
		(start 404.768558 -270.946372)
		(end 404.727918 -270.946372)
		(width 0.18288)
		(layer "In11.Cu")
		(net "M_H_CPU0_SA_CB<5>")
	)
	(segment
		(start 436.8927 -271.534636)
		(end 436.199026 -270.840962)
		(width 0.18288)
		(layer "In11.Cu")
		(net "M_H_CPU0_SA_CB<5>")
	)
	(segment
		(start 444.246254 -272.02257)
		(end 444.053214 -272.21561)
		(width 0.18288)
		(layer "In11.Cu")
		(net "M_H_CPU0_SA_CB<5>")
	)
	(segment
		(start 414.487106 -270.484092)
		(end 414.294066 -270.291052)
		(width 0.18288)
		(layer "In11.Cu")
		(net "M_H_CPU0_SA_CB<5>")
	)
	(segment
		(start 433.283614 -271.095978)
		(end 433.283614 -270.82242)
		(width 0.18288)
		(layer "In11.Cu")
		(net "M_H_CPU0_SA_CB<5>")
	)
	(segment
		(start 375.868946 -258.487418)
		(end 375.854214 -258.478782)
		(width 0.088646)
		(layer "In11.Cu")
		(net "M_H_CPU0_SA_CB<5>")
	)
	(segment
		(start 418.096446 -271.131284)
		(end 418.096446 -270.824198)
		(width 0.18288)
		(layer "In11.Cu")
		(net "M_H_CPU0_SA_CB<5>")
	)
	(segment
		(start 383.938018 -258.478782)
		(end 383.937764 -258.478782)
		(width 0.088646)
		(layer "In11.Cu")
		(net "M_H_CPU0_SA_CB<5>")
	)
	(segment
		(start 443.860174 -272.755868)
		(end 442.71438 -272.755868)
		(width 0.18288)
		(layer "In11.Cu")
		(net "M_H_CPU0_SA_CB<5>")
	)
	(segment
		(start 439.25871 -271.534636)
		(end 436.8927 -271.534636)
		(width 0.18288)
		(layer "In11.Cu")
		(net "M_H_CPU0_SA_CB<5>")
	)
	(segment
		(start 413.783526 -270.484092)
		(end 413.783526 -270.729202)
		(width 0.18288)
		(layer "In11.Cu")
		(net "M_H_CPU0_SA_CB<5>")
	)
	(segment
		(start 422.213532 -270.840962)
		(end 421.917622 -271.136872)
		(width 0.18288)
		(layer "In11.Cu")
		(net "M_H_CPU0_SA_CB<5>")
	)
	(segment
		(start 408.688794 -270.946626)
		(end 404.768812 -270.946626)
		(width 0.18288)
		(layer "In11.Cu")
		(net "M_H_CPU0_SA_CB<5>")
	)
	(segment
		(start 439.418476 -271.694402)
		(end 439.25871 -271.534636)
		(width 0.18288)
		(layer "In11.Cu")
		(net "M_H_CPU0_SA_CB<5>")
	)
	(segment
		(start 450.252846 -271.925034)
		(end 449.147184 -271.925034)
		(width 0.18288)
		(layer "In11.Cu")
		(net "M_H_CPU0_SA_CB<5>")
	)
	(segment
		(start 387.268212 -259.92455)
		(end 385.89839 -258.554728)
		(width 0.088646)
		(layer "In11.Cu")
		(net "M_H_CPU0_SA_CB<5>")
	)
	(segment
		(start 448.761104 -271.362678)
		(end 448.443604 -271.362678)
		(width 0.18288)
		(layer "In11.Cu")
		(net "M_H_CPU0_SA_CB<5>")
	)
	(segment
		(start 433.794154 -271.289018)
		(end 433.476654 -271.289018)
		(width 0.18288)
		(layer "In11.Cu")
		(net "M_H_CPU0_SA_CB<5>")
	)
	(segment
		(start 413.783526 -270.729202)
		(end 413.590486 -270.922242)
		(width 0.18288)
		(layer "In11.Cu")
		(net "M_H_CPU0_SA_CB<5>")
	)
	(segment
		(start 444.949834 -272.755868)
		(end 444.756794 -272.562828)
		(width 0.18288)
		(layer "In11.Cu")
		(net "M_H_CPU0_SA_CB<5>")
	)
	(segment
		(start 427.522894 -271.911826)
		(end 426.782738 -271.911826)
		(width 0.18288)
		(layer "In11.Cu")
		(net "M_H_CPU0_SA_CB<5>")
	)
	(segment
		(start 444.053214 -272.21561)
		(end 444.053214 -272.562828)
		(width 0.18288)
		(layer "In11.Cu")
		(net "M_H_CPU0_SA_CB<5>")
	)
	(segment
		(start 444.756794 -272.562828)
		(end 444.756794 -272.21561)
		(width 0.18288)
		(layer "In11.Cu")
		(net "M_H_CPU0_SA_CB<5>")
	)
	(segment
		(start 418.096446 -270.824198)
		(end 417.903406 -270.631158)
		(width 0.18288)
		(layer "In11.Cu")
		(net "M_H_CPU0_SA_CB<5>")
	)
	(segment
		(start 429.473614 -272.036032)
		(end 429.156114 -272.036032)
		(width 0.18288)
		(layer "In11.Cu")
		(net "M_H_CPU0_SA_CB<5>")
	)
	(segment
		(start 433.090574 -270.62938)
		(end 432.035966 -270.62938)
		(width 0.18288)
		(layer "In11.Cu")
		(net "M_H_CPU0_SA_CB<5>")
	)
	(segment
		(start 448.250564 -271.731994)
		(end 448.057524 -271.925034)
		(width 0.18288)
		(layer "In11.Cu")
		(net "M_H_CPU0_SA_CB<5>")
	)
	(segment
		(start 424.254168 -271.6911)
		(end 423.585894 -271.022826)
		(width 0.18288)
		(layer "In11.Cu")
		(net "M_H_CPU0_SA_CB<5>")
	)
	(segment
		(start 429.666654 -271.596866)
		(end 429.666654 -271.842992)
		(width 0.18288)
		(layer "In11.Cu")
		(net "M_H_CPU0_SA_CB<5>")
	)
	(segment
		(start 412.460694 -270.794226)
		(end 408.841194 -270.794226)
		(width 0.18288)
		(layer "In11.Cu")
		(net "M_H_CPU0_SA_CB<5>")
	)
	(segment
		(start 377.743974 -258.484878)
		(end 377.73356 -258.478782)
		(width 0.088646)
		(layer "In11.Cu")
		(net "M_H_CPU0_SA_CB<5>")
	)
	(segment
		(start 434.180234 -270.62938)
		(end 433.987194 -270.82242)
		(width 0.18288)
		(layer "In11.Cu")
		(net "M_H_CPU0_SA_CB<5>")
	)
	(segment
		(start 421.917622 -271.136872)
		(end 421.520112 -271.136872)
		(width 0.18288)
		(layer "In11.Cu")
		(net "M_H_CPU0_SA_CB<5>")
	)
	(segment
		(start 383.37236 -258.478782)
		(end 383.372106 -258.478782)
		(width 0.088646)
		(layer "In11.Cu")
		(net "M_H_CPU0_SA_CB<5>")
	)
	(segment
		(start 373.600218 -258.478782)
		(end 373.59971 -258.479036)
		(width 0.088646)
		(layer "In11.Cu")
		(net "M_H_CPU0_SA_CB<5>")
	)
	(segment
		(start 384.877564 -258.478782)
		(end 384.862832 -258.487418)
		(width 0.088646)
		(layer "In11.Cu")
		(net "M_H_CPU0_SA_CB<5>")
	)
	(segment
		(start 448.954144 -271.731994)
		(end 448.954144 -271.555718)
		(width 0.18288)
		(layer "In11.Cu")
		(net "M_H_CPU0_SA_CB<5>")
	)
	(segment
		(start 418.800026 -271.131284)
		(end 418.606986 -271.324324)
		(width 0.18288)
		(layer "In11.Cu")
		(net "M_H_CPU0_SA_CB<5>")
	)
	(segment
		(start 425.921932 -271.403826)
		(end 425.634658 -271.6911)
		(width 0.18288)
		(layer "In11.Cu")
		(net "M_H_CPU0_SA_CB<5>")
	)
	(segment
		(start 404.768812 -270.946626)
		(end 404.768558 -270.946372)
		(width 0.18288)
		(layer "In11.Cu")
		(net "M_H_CPU0_SA_CB<5>")
	)
	(segment
		(start 373.412512 -258.80314)
		(end 373.412512 -258.922012)
		(width 0.088646)
		(layer "In11.Cu")
		(net "M_H_CPU0_SA_CB<5>")
	)
	(segment
		(start 417.144962 -270.631158)
		(end 416.853878 -270.922242)
		(width 0.18288)
		(layer "In11.Cu")
		(net "M_H_CPU0_SA_CB<5>")
	)
	(segment
		(start 446.885314 -271.925034)
		(end 446.05448 -272.755868)
		(width 0.18288)
		(layer "In11.Cu")
		(net "M_H_CPU0_SA_CB<5>")
	)
	(segment
		(start 372.128288 -259.023612)
		(end 371.907816 -258.80314)
		(width 0.088646)
		(layer "In11.Cu")
		(net "M_H_CPU0_SA_CB<5>")
	)
	(segment
		(start 429.666654 -271.842992)
		(end 429.473614 -272.036032)
		(width 0.18288)
		(layer "In11.Cu")
		(net "M_H_CPU0_SA_CB<5>")
	)
	(segment
		(start 429.859694 -271.403826)
		(end 429.666654 -271.596866)
		(width 0.18288)
		(layer "In11.Cu")
		(net "M_H_CPU0_SA_CB<5>")
	)
	(segment
		(start 418.993066 -270.631158)
		(end 418.800026 -270.824198)
		(width 0.18288)
		(layer "In11.Cu")
		(net "M_H_CPU0_SA_CB<5>")
	)
	(segment
		(start 418.800026 -270.824198)
		(end 418.800026 -271.131284)
		(width 0.18288)
		(layer "In11.Cu")
		(net "M_H_CPU0_SA_CB<5>")
	)
	(segment
		(start 421.224202 -270.840962)
		(end 419.961314 -270.840962)
		(width 0.18288)
		(layer "In11.Cu")
		(net "M_H_CPU0_SA_CB<5>")
	)
	(segment
		(start 412.58871 -270.922242)
		(end 412.460694 -270.794226)
		(width 0.18288)
		(layer "In11.Cu")
		(net "M_H_CPU0_SA_CB<5>")
	)
	(arc
		(start 383.937764 -258.478782)
		(mid 383.655062 -258.554524)
		(end 383.37236 -258.478782)
		(width 0.088646)
		(layer "In11.Cu")
		(net "M_H_CPU0_SA_CB<5>")
	)
	(arc
		(start 382.997964 -258.478782)
		(mid 382.715516 -258.554431)
		(end 382.433068 -258.478782)
		(width 0.088646)
		(layer "In11.Cu")
		(net "M_H_CPU0_SA_CB<5>")
	)
	(arc
		(start 373.412512 -258.922012)
		(mid 373.305309 -259.180823)
		(end 373.046498 -259.288026)
		(width 0.088646)
		(layer "In11.Cu")
		(net "M_H_CPU0_SA_CB<5>")
	)
	(arc
		(start 378.299218 -258.478782)
		(mid 378.022405 -258.554618)
		(end 377.743974 -258.484878)
		(width 0.088646)
		(layer "In11.Cu")
		(net "M_H_CPU0_SA_CB<5>")
	)
	(arc
		(start 375.479818 -258.478782)
		(mid 375.19726 -258.554397)
		(end 374.914668 -258.478782)
		(width 0.088646)
		(layer "In11.Cu")
		(net "M_H_CPU0_SA_CB<5>")
	)
	(arc
		(start 380.178818 -258.478782)
		(mid 379.896116 -258.554524)
		(end 379.613414 -258.478782)
		(width 0.088646)
		(layer "In11.Cu")
		(net "M_H_CPU0_SA_CB<5>")
	)
	(arc
		(start 384.862832 -258.487418)
		(mid 384.586391 -258.554584)
		(end 384.31216 -258.478782)
		(width 0.088646)
		(layer "In11.Cu")
		(net "M_H_CPU0_SA_CB<5>")
	)
	(arc
		(start 377.73356 -258.478782)
		(mid 377.546362 -258.428639)
		(end 377.359164 -258.478782)
		(width 0.088646)
		(layer "In11.Cu")
		(net "M_H_CPU0_SA_CB<5>")
	)
	(arc
		(start 380.553214 -258.478782)
		(mid 380.366016 -258.428639)
		(end 380.178818 -258.478782)
		(width 0.088646)
		(layer "In11.Cu")
		(net "M_H_CPU0_SA_CB<5>")
	)
	(arc
		(start 376.794014 -258.478782)
		(mid 376.606816 -258.428639)
		(end 376.419618 -258.478782)
		(width 0.088646)
		(layer "In11.Cu")
		(net "M_H_CPU0_SA_CB<5>")
	)
	(arc
		(start 372.76659 -259.288026)
		(mid 372.421136 -259.219311)
		(end 372.128288 -259.023612)
		(width 0.088646)
		(layer "In11.Cu")
		(net "M_H_CPU0_SA_CB<5>")
	)
	(arc
		(start 385.534916 -258.554728)
		(mid 385.388446 -258.535368)
		(end 385.25196 -258.478782)
		(width 0.088646)
		(layer "In11.Cu")
		(net "M_H_CPU0_SA_CB<5>")
	)
	(arc
		(start 379.239018 -258.478782)
		(mid 378.964789 -258.554707)
		(end 378.688346 -258.487418)
		(width 0.088646)
		(layer "In11.Cu")
		(net "M_H_CPU0_SA_CB<5>")
	)
	(arc
		(start 382.432814 -258.478782)
		(mid 382.245616 -258.428639)
		(end 382.058418 -258.478782)
		(width 0.088646)
		(layer "In11.Cu")
		(net "M_H_CPU0_SA_CB<5>")
	)
	(arc
		(start 374.540018 -258.478782)
		(mid 374.265789 -258.554707)
		(end 373.989346 -258.487418)
		(width 0.088646)
		(layer "In11.Cu")
		(net "M_H_CPU0_SA_CB<5>")
	)
	(arc
		(start 382.058418 -258.478782)
		(mid 381.775716 -258.554524)
		(end 381.493014 -258.478782)
		(width 0.088646)
		(layer "In11.Cu")
		(net "M_H_CPU0_SA_CB<5>")
	)
	(arc
		(start 385.25196 -258.478782)
		(mid 385.064762 -258.428639)
		(end 384.877564 -258.478782)
		(width 0.088646)
		(layer "In11.Cu")
		(net "M_H_CPU0_SA_CB<5>")
	)
	(arc
		(start 373.59971 -258.479036)
		(mid 373.462665 -258.615996)
		(end 373.412512 -258.80314)
		(width 0.088646)
		(layer "In11.Cu")
		(net "M_H_CPU0_SA_CB<5>")
	)
	(arc
		(start 375.854214 -258.478782)
		(mid 375.667016 -258.428639)
		(end 375.479818 -258.478782)
		(width 0.088646)
		(layer "In11.Cu")
		(net "M_H_CPU0_SA_CB<5>")
	)
	(arc
		(start 377.359164 -258.478782)
		(mid 377.082605 -258.554491)
		(end 376.804428 -258.484878)
		(width 0.088646)
		(layer "In11.Cu")
		(net "M_H_CPU0_SA_CB<5>")
	)
	(arc
		(start 379.613414 -258.478782)
		(mid 379.426216 -258.428639)
		(end 379.239018 -258.478782)
		(width 0.088646)
		(layer "In11.Cu")
		(net "M_H_CPU0_SA_CB<5>")
	)
	(arc
		(start 374.914668 -258.478782)
		(mid 374.72736 -258.428639)
		(end 374.540018 -258.478782)
		(width 0.088646)
		(layer "In11.Cu")
		(net "M_H_CPU0_SA_CB<5>")
	)
	(arc
		(start 383.372106 -258.478782)
		(mid 383.185052 -258.428732)
		(end 382.997964 -258.478782)
		(width 0.088646)
		(layer "In11.Cu")
		(net "M_H_CPU0_SA_CB<5>")
	)
	(arc
		(start 381.118618 -258.478782)
		(mid 380.844389 -258.554707)
		(end 380.567946 -258.487418)
		(width 0.088646)
		(layer "In11.Cu")
		(net "M_H_CPU0_SA_CB<5>")
	)
	(arc
		(start 378.673614 -258.478782)
		(mid 378.486416 -258.428639)
		(end 378.299218 -258.478782)
		(width 0.088646)
		(layer "In11.Cu")
		(net "M_H_CPU0_SA_CB<5>")
	)
	(arc
		(start 373.974614 -258.478782)
		(mid 373.787416 -258.428639)
		(end 373.600218 -258.478782)
		(width 0.088646)
		(layer "In11.Cu")
		(net "M_H_CPU0_SA_CB<5>")
	)
	(arc
		(start 376.419618 -258.478782)
		(mid 376.145389 -258.554707)
		(end 375.868946 -258.487418)
		(width 0.088646)
		(layer "In11.Cu")
		(net "M_H_CPU0_SA_CB<5>")
	)
	(arc
		(start 381.493014 -258.478782)
		(mid 381.305816 -258.428639)
		(end 381.118618 -258.478782)
		(width 0.088646)
		(layer "In11.Cu")
		(net "M_H_CPU0_SA_CB<5>")
	)
	(arc
		(start 384.31216 -258.478782)
		(mid 384.125106 -258.428732)
		(end 383.938018 -258.478782)
		(width 0.088646)
		(layer "In11.Cu")
		(net "M_H_CPU0_SA_CB<5>")
	)
	(segment
		(start 452.016114 -272.966688)
		(end 450.911214 -272.966688)
		(width 0.20066)
		(layer "F.Cu")
		(net "M_H_CPU0_SA_CB<4>")
	)
	(segment
		(start 459.559914 -272.966688)
		(end 459.55966 -272.966942)
		(width 0.20066)
		(layer "F.Cu")
		(net "M_H_CPU0_SA_CB<4>")
	)
	(segment
		(start 371.437916 -259.093462)
		(end 371.437662 -259.616956)
		(width 0.20066)
		(layer "F.Cu")
		(net "M_H_CPU0_SA_CB<4>")
	)
	(segment
		(start 457.53655 -272.535396)
		(end 457.126594 -272.535396)
		(width 0.20066)
		(layer "F.Cu")
		(net "M_H_CPU0_SA_CB<4>")
	)
	(segment
		(start 371.437916 -259.081016)
		(end 371.437916 -259.093462)
		(width 0.20066)
		(layer "F.Cu")
		(net "M_H_CPU0_SA_CB<4>")
	)
	(segment
		(start 457.968096 -272.966942)
		(end 457.53655 -272.535396)
		(width 0.20066)
		(layer "F.Cu")
		(net "M_H_CPU0_SA_CB<4>")
	)
	(segment
		(start 453.785478 -273.215354)
		(end 453.536812 -272.966688)
		(width 0.20066)
		(layer "F.Cu")
		(net "M_H_CPU0_SA_CB<4>")
	)
	(segment
		(start 453.536812 -272.966688)
		(end 452.016114 -272.966688)
		(width 0.20066)
		(layer "F.Cu")
		(net "M_H_CPU0_SA_CB<4>")
	)
	(segment
		(start 457.126594 -272.535396)
		(end 457.120244 -272.541746)
		(width 0.1016)
		(layer "F.Cu")
		(net "M_H_CPU0_SA_CB<4>")
	)
	(segment
		(start 454.95845 -272.541746)
		(end 454.91146 -272.541746)
		(width 0.101854)
		(layer "F.Cu")
		(net "M_H_CPU0_SA_CB<4>")
	)
	(segment
		(start 454.566782 -272.541746)
		(end 454.448672 -272.659856)
		(width 0.20066)
		(layer "F.Cu")
		(net "M_H_CPU0_SA_CB<4>")
	)
	(segment
		(start 454.260712 -273.215354)
		(end 453.785478 -273.215354)
		(width 0.20066)
		(layer "F.Cu")
		(net "M_H_CPU0_SA_CB<4>")
	)
	(segment
		(start 454.448672 -272.659856)
		(end 454.448672 -273.027394)
		(width 0.20066)
		(layer "F.Cu")
		(net "M_H_CPU0_SA_CB<4>")
	)
	(segment
		(start 459.55966 -272.966942)
		(end 457.968096 -272.966942)
		(width 0.20066)
		(layer "F.Cu")
		(net "M_H_CPU0_SA_CB<4>")
	)
	(segment
		(start 454.448672 -273.027394)
		(end 454.260712 -273.215354)
		(width 0.20066)
		(layer "F.Cu")
		(net "M_H_CPU0_SA_CB<4>")
	)
	(segment
		(start 454.91146 -272.541746)
		(end 454.566782 -272.541746)
		(width 0.20066)
		(layer "F.Cu")
		(net "M_H_CPU0_SA_CB<4>")
	)
	(segment
		(start 457.120244 -272.541746)
		(end 454.95845 -272.541746)
		(width 0.1016)
		(layer "F.Cu")
		(net "M_H_CPU0_SA_CB<4>")
	)
	(segment
		(start 383.46761 -259.292598)
		(end 383.457196 -259.298694)
		(width 0.088646)
		(layer "In11.Cu")
		(net "M_H_CPU0_SA_CB<4>")
	)
	(segment
		(start 412.784798 -272.707354)
		(end 412.613856 -272.536412)
		(width 0.18288)
		(layer "In11.Cu")
		(net "M_H_CPU0_SA_CB<4>")
	)
	(segment
		(start 375.009664 -259.292598)
		(end 374.994932 -259.301234)
		(width 0.088646)
		(layer "In11.Cu")
		(net "M_H_CPU0_SA_CB<4>")
	)
	(segment
		(start 434.908452 -272.540984)
		(end 434.754274 -272.386806)
		(width 0.18288)
		(layer "In11.Cu")
		(net "M_H_CPU0_SA_CB<4>")
	)
	(segment
		(start 434.099716 -272.386806)
		(end 433.906676 -272.579846)
		(width 0.18288)
		(layer "In11.Cu")
		(net "M_H_CPU0_SA_CB<4>")
	)
	(segment
		(start 438.135268 -273.179794)
		(end 436.778146 -273.179794)
		(width 0.18288)
		(layer "In11.Cu")
		(net "M_H_CPU0_SA_CB<4>")
	)
	(segment
		(start 414.304226 -273.65325)
		(end 413.986726 -273.65325)
		(width 0.18288)
		(layer "In11.Cu")
		(net "M_H_CPU0_SA_CB<4>")
	)
	(segment
		(start 431.297842 -273.089878)
		(end 428.09541 -273.089878)
		(width 0.18288)
		(layer "In11.Cu")
		(net "M_H_CPU0_SA_CB<4>")
	)
	(segment
		(start 416.247072 -272.355056)
		(end 415.894774 -272.707354)
		(width 0.18288)
		(layer "In11.Cu")
		(net "M_H_CPU0_SA_CB<4>")
	)
	(segment
		(start 379.708664 -259.292598)
		(end 379.693932 -259.301234)
		(width 0.088646)
		(layer "In11.Cu")
		(net "M_H_CPU0_SA_CB<4>")
	)
	(segment
		(start 386.19176 -260.106414)
		(end 386.185664 -260.102858)
		(width 0.088646)
		(layer "In11.Cu")
		(net "M_H_CPU0_SA_CB<4>")
	)
	(segment
		(start 409.330144 -272.362676)
		(end 408.517344 -272.362676)
		(width 0.18288)
		(layer "In11.Cu")
		(net "M_H_CPU0_SA_CB<4>")
	)
	(segment
		(start 386.757926 -260.672326)
		(end 386.192522 -260.106922)
		(width 0.088646)
		(layer "In11.Cu")
		(net "M_H_CPU0_SA_CB<4>")
	)
	(segment
		(start 443.816232 -274.701254)
		(end 443.542928 -274.701254)
		(width 0.18288)
		(layer "In11.Cu")
		(net "M_H_CPU0_SA_CB<4>")
	)
	(segment
		(start 413.793686 -272.900394)
		(end 413.600646 -272.707354)
		(width 0.18288)
		(layer "In11.Cu")
		(net "M_H_CPU0_SA_CB<4>")
	)
	(segment
		(start 388.68731 -262.11403)
		(end 387.926072 -261.352792)
		(width 0.18288)
		(layer "In11.Cu")
		(net "M_H_CPU0_SA_CB<4>")
	)
	(segment
		(start 420.034974 -272.355056)
		(end 418.583872 -272.355056)
		(width 0.18288)
		(layer "In11.Cu")
		(net "M_H_CPU0_SA_CB<4>")
	)
	(segment
		(start 424.279314 -273.392646)
		(end 423.856912 -272.970244)
		(width 0.18288)
		(layer "In11.Cu")
		(net "M_H_CPU0_SA_CB<4>")
	)
	(segment
		(start 418.583872 -272.355056)
		(end 418.390832 -272.548096)
		(width 0.18288)
		(layer "In11.Cu")
		(net "M_H_CPU0_SA_CB<4>")
	)
	(segment
		(start 440.887104 -274.004532)
		(end 440.273948 -273.391376)
		(width 0.18288)
		(layer "In11.Cu")
		(net "M_H_CPU0_SA_CB<4>")
	)
	(segment
		(start 446.99555 -273.39798)
		(end 446.559686 -273.833844)
		(width 0.18288)
		(layer "In11.Cu")
		(net "M_H_CPU0_SA_CB<4>")
	)
	(segment
		(start 433.203096 -272.932906)
		(end 433.203096 -272.579846)
		(width 0.18288)
		(layer "In11.Cu")
		(net "M_H_CPU0_SA_CB<4>")
	)
	(segment
		(start 385.730496 -259.297678)
		(end 385.721606 -259.292598)
		(width 0.088646)
		(layer "In11.Cu")
		(net "M_H_CPU0_SA_CB<4>")
	)
	(segment
		(start 444.009272 -273.982434)
		(end 444.009272 -274.508214)
		(width 0.18288)
		(layer "In11.Cu")
		(net "M_H_CPU0_SA_CB<4>")
	)
	(segment
		(start 446.559686 -273.833844)
		(end 446.375028 -273.833844)
		(width 0.18288)
		(layer "In11.Cu")
		(net "M_H_CPU0_SA_CB<4>")
	)
	(segment
		(start 420.220394 -272.540476)
		(end 420.034974 -272.355056)
		(width 0.18288)
		(layer "In11.Cu")
		(net "M_H_CPU0_SA_CB<4>")
	)
	(segment
		(start 414.690306 -272.707354)
		(end 414.497266 -272.900394)
		(width 0.18288)
		(layer "In11.Cu")
		(net "M_H_CPU0_SA_CB<4>")
	)
	(segment
		(start 433.203096 -272.579846)
		(end 433.010056 -272.386806)
		(width 0.18288)
		(layer "In11.Cu")
		(net "M_H_CPU0_SA_CB<4>")
	)
	(segment
		(start 372.190264 -259.941314)
		(end 371.793262 -259.712206)
		(width 0.088646)
		(layer "In11.Cu")
		(net "M_H_CPU0_SA_CB<4>")
	)
	(segment
		(start 426.81017 -273.51355)
		(end 426.689266 -273.392646)
		(width 0.18288)
		(layer "In11.Cu")
		(net "M_H_CPU0_SA_CB<4>")
	)
	(segment
		(start 421.312086 -272.540476)
		(end 420.220394 -272.540476)
		(width 0.18288)
		(layer "In11.Cu")
		(net "M_H_CPU0_SA_CB<4>")
	)
	(segment
		(start 433.906676 -272.932906)
		(end 433.713636 -273.125946)
		(width 0.18288)
		(layer "In11.Cu")
		(net "M_H_CPU0_SA_CB<4>")
	)
	(segment
		(start 441.528962 -274.004532)
		(end 440.887104 -274.004532)
		(width 0.18288)
		(layer "In11.Cu")
		(net "M_H_CPU0_SA_CB<4>")
	)
	(segment
		(start 414.497266 -273.46021)
		(end 414.304226 -273.65325)
		(width 0.18288)
		(layer "In11.Cu")
		(net "M_H_CPU0_SA_CB<4>")
	)
	(segment
		(start 413.793686 -273.46021)
		(end 413.793686 -272.900394)
		(width 0.18288)
		(layer "In11.Cu")
		(net "M_H_CPU0_SA_CB<4>")
	)
	(segment
		(start 444.712852 -273.982434)
		(end 444.519812 -273.789394)
		(width 0.18288)
		(layer "In11.Cu")
		(net "M_H_CPU0_SA_CB<4>")
	)
	(segment
		(start 444.202312 -273.789394)
		(end 444.009272 -273.982434)
		(width 0.18288)
		(layer "In11.Cu")
		(net "M_H_CPU0_SA_CB<4>")
	)
	(segment
		(start 450.911214 -272.966688)
		(end 450.592444 -272.966942)
		(width 0.18288)
		(layer "In11.Cu")
		(net "M_H_CPU0_SA_CB<4>")
	)
	(segment
		(start 373.733314 -259.63499)
		(end 373.647208 -259.794756)
		(width 0.088646)
		(layer "In11.Cu")
		(net "M_H_CPU0_SA_CB<4>")
	)
	(segment
		(start 386.192522 -260.106922)
		(end 386.19176 -260.106414)
		(width 0.088646)
		(layer "In11.Cu")
		(net "M_H_CPU0_SA_CB<4>")
	)
	(segment
		(start 444.712852 -274.576286)
		(end 444.712852 -273.982434)
		(width 0.18288)
		(layer "In11.Cu")
		(net "M_H_CPU0_SA_CB<4>")
	)
	(segment
		(start 436.778146 -273.179794)
		(end 436.139336 -272.540984)
		(width 0.18288)
		(layer "In11.Cu")
		(net "M_H_CPU0_SA_CB<4>")
	)
	(segment
		(start 449.859908 -273.39798)
		(end 446.99555 -273.39798)
		(width 0.18288)
		(layer "In11.Cu")
		(net "M_H_CPU0_SA_CB<4>")
	)
	(segment
		(start 413.986726 -273.65325)
		(end 413.793686 -273.46021)
		(width 0.18288)
		(layer "In11.Cu")
		(net "M_H_CPU0_SA_CB<4>")
	)
	(segment
		(start 387.926072 -261.352792)
		(end 387.245606 -260.672326)
		(width 0.088646)
		(layer "In11.Cu")
		(net "M_H_CPU0_SA_CB<4>")
	)
	(segment
		(start 432.000914 -272.386806)
		(end 431.297842 -273.089878)
		(width 0.18288)
		(layer "In11.Cu")
		(net "M_H_CPU0_SA_CB<4>")
	)
	(segment
		(start 443.542928 -274.701254)
		(end 443.082934 -274.24126)
		(width 0.18288)
		(layer "In11.Cu")
		(net "M_H_CPU0_SA_CB<4>")
	)
	(segment
		(start 380.648464 -259.292598)
		(end 380.633732 -259.301234)
		(width 0.088646)
		(layer "In11.Cu")
		(net "M_H_CPU0_SA_CB<4>")
	)
	(segment
		(start 409.50388 -272.536412)
		(end 409.330144 -272.362676)
		(width 0.18288)
		(layer "In11.Cu")
		(net "M_H_CPU0_SA_CB<4>")
	)
	(segment
		(start 417.687252 -273.09953)
		(end 417.687252 -272.548096)
		(width 0.18288)
		(layer "In11.Cu")
		(net "M_H_CPU0_SA_CB<4>")
	)
	(segment
		(start 412.613856 -272.536412)
		(end 409.50388 -272.536412)
		(width 0.18288)
		(layer "In11.Cu")
		(net "M_H_CPU0_SA_CB<4>")
	)
	(segment
		(start 385.34721 -259.292598)
		(end 385.332478 -259.301234)
		(width 0.088646)
		(layer "In11.Cu")
		(net "M_H_CPU0_SA_CB<4>")
	)
	(segment
		(start 433.713636 -273.125946)
		(end 433.396136 -273.125946)
		(width 0.18288)
		(layer "In11.Cu")
		(net "M_H_CPU0_SA_CB<4>")
	)
	(segment
		(start 426.689266 -273.392646)
		(end 424.279314 -273.392646)
		(width 0.18288)
		(layer "In11.Cu")
		(net "M_H_CPU0_SA_CB<4>")
	)
	(segment
		(start 384.40741 -259.292598)
		(end 384.392678 -259.301234)
		(width 0.088646)
		(layer "In11.Cu")
		(net "M_H_CPU0_SA_CB<4>")
	)
	(segment
		(start 378.768864 -259.292598)
		(end 378.754132 -259.301234)
		(width 0.088646)
		(layer "In11.Cu")
		(net "M_H_CPU0_SA_CB<4>")
	)
	(segment
		(start 373.130064 -259.941314)
		(end 373.115332 -259.932678)
		(width 0.088646)
		(layer "In11.Cu")
		(net "M_H_CPU0_SA_CB<4>")
	)
	(segment
		(start 441.76569 -274.24126)
		(end 441.528962 -274.004532)
		(width 0.18288)
		(layer "In11.Cu")
		(net "M_H_CPU0_SA_CB<4>")
	)
	(segment
		(start 421.741854 -272.970244)
		(end 421.312086 -272.540476)
		(width 0.18288)
		(layer "In11.Cu")
		(net "M_H_CPU0_SA_CB<4>")
	)
	(segment
		(start 382.528064 -259.292598)
		(end 382.513332 -259.301234)
		(width 0.088646)
		(layer "In11.Cu")
		(net "M_H_CPU0_SA_CB<4>")
	)
	(segment
		(start 418.390832 -272.548096)
		(end 418.390832 -273.09953)
		(width 0.18288)
		(layer "In11.Cu")
		(net "M_H_CPU0_SA_CB<4>")
	)
	(segment
		(start 433.906676 -272.579846)
		(end 433.906676 -272.932906)
		(width 0.18288)
		(layer "In11.Cu")
		(net "M_H_CPU0_SA_CB<4>")
	)
	(segment
		(start 417.687252 -272.548096)
		(end 417.494212 -272.355056)
		(width 0.18288)
		(layer "In11.Cu")
		(net "M_H_CPU0_SA_CB<4>")
	)
	(segment
		(start 408.33294 -272.54708)
		(end 404.891494 -272.54708)
		(width 0.18288)
		(layer "In11.Cu")
		(net "M_H_CPU0_SA_CB<4>")
	)
	(segment
		(start 394.458444 -262.11403)
		(end 388.68731 -262.11403)
		(width 0.18288)
		(layer "In11.Cu")
		(net "M_H_CPU0_SA_CB<4>")
	)
	(segment
		(start 446.375028 -273.833844)
		(end 445.439546 -274.769326)
		(width 0.18288)
		(layer "In11.Cu")
		(net "M_H_CPU0_SA_CB<4>")
	)
	(segment
		(start 450.290946 -272.966942)
		(end 449.859908 -273.39798)
		(width 0.18288)
		(layer "In11.Cu")
		(net "M_H_CPU0_SA_CB<4>")
	)
	(segment
		(start 438.34685 -273.391376)
		(end 438.135268 -273.179794)
		(width 0.18288)
		(layer "In11.Cu")
		(net "M_H_CPU0_SA_CB<4>")
	)
	(segment
		(start 373.881142 -259.437378)
		(end 373.878094 -259.440426)
		(width 0.088646)
		(layer "In11.Cu")
		(net "M_H_CPU0_SA_CB<4>")
	)
	(segment
		(start 443.082934 -274.24126)
		(end 441.76569 -274.24126)
		(width 0.18288)
		(layer "In11.Cu")
		(net "M_H_CPU0_SA_CB<4>")
	)
	(segment
		(start 434.754274 -272.386806)
		(end 434.099716 -272.386806)
		(width 0.18288)
		(layer "In11.Cu")
		(net "M_H_CPU0_SA_CB<4>")
	)
	(segment
		(start 423.856912 -272.970244)
		(end 421.741854 -272.970244)
		(width 0.18288)
		(layer "In11.Cu")
		(net "M_H_CPU0_SA_CB<4>")
	)
	(segment
		(start 428.09541 -273.089878)
		(end 427.671738 -273.51355)
		(width 0.18288)
		(layer "In11.Cu")
		(net "M_H_CPU0_SA_CB<4>")
	)
	(segment
		(start 381.588264 -259.292598)
		(end 381.573532 -259.301234)
		(width 0.088646)
		(layer "In11.Cu")
		(net "M_H_CPU0_SA_CB<4>")
	)
	(segment
		(start 414.497266 -272.900394)
		(end 414.497266 -273.46021)
		(width 0.18288)
		(layer "In11.Cu")
		(net "M_H_CPU0_SA_CB<4>")
	)
	(segment
		(start 440.273948 -273.391376)
		(end 438.34685 -273.391376)
		(width 0.18288)
		(layer "In11.Cu")
		(net "M_H_CPU0_SA_CB<4>")
	)
	(segment
		(start 375.949464 -259.292598)
		(end 375.934732 -259.301234)
		(width 0.088646)
		(layer "In11.Cu")
		(net "M_H_CPU0_SA_CB<4>")
	)
	(segment
		(start 444.905892 -274.769326)
		(end 444.712852 -274.576286)
		(width 0.18288)
		(layer "In11.Cu")
		(net "M_H_CPU0_SA_CB<4>")
	)
	(segment
		(start 436.139336 -272.540984)
		(end 434.908452 -272.540984)
		(width 0.18288)
		(layer "In11.Cu")
		(net "M_H_CPU0_SA_CB<4>")
	)
	(segment
		(start 417.880292 -273.29257)
		(end 417.687252 -273.09953)
		(width 0.18288)
		(layer "In11.Cu")
		(net "M_H_CPU0_SA_CB<4>")
	)
	(segment
		(start 413.600646 -272.707354)
		(end 412.784798 -272.707354)
		(width 0.18288)
		(layer "In11.Cu")
		(net "M_H_CPU0_SA_CB<4>")
	)
	(segment
		(start 408.517344 -272.362676)
		(end 408.33294 -272.54708)
		(width 0.18288)
		(layer "In11.Cu")
		(net "M_H_CPU0_SA_CB<4>")
	)
	(segment
		(start 373.513604 -259.936234)
		(end 373.51208 -259.936742)
		(width 0.088646)
		(layer "In11.Cu")
		(net "M_H_CPU0_SA_CB<4>")
	)
	(segment
		(start 445.439546 -274.769326)
		(end 444.905892 -274.769326)
		(width 0.18288)
		(layer "In11.Cu")
		(net "M_H_CPU0_SA_CB<4>")
	)
	(segment
		(start 415.894774 -272.707354)
		(end 414.690306 -272.707354)
		(width 0.18288)
		(layer "In11.Cu")
		(net "M_H_CPU0_SA_CB<4>")
	)
	(segment
		(start 433.010056 -272.386806)
		(end 432.000914 -272.386806)
		(width 0.18288)
		(layer "In11.Cu")
		(net "M_H_CPU0_SA_CB<4>")
	)
	(segment
		(start 444.009272 -274.508214)
		(end 443.816232 -274.701254)
		(width 0.18288)
		(layer "In11.Cu")
		(net "M_H_CPU0_SA_CB<4>")
	)
	(segment
		(start 404.891494 -272.54708)
		(end 394.458444 -262.11403)
		(width 0.18288)
		(layer "In11.Cu")
		(net "M_H_CPU0_SA_CB<4>")
	)
	(segment
		(start 418.390832 -273.09953)
		(end 418.197792 -273.29257)
		(width 0.18288)
		(layer "In11.Cu")
		(net "M_H_CPU0_SA_CB<4>")
	)
	(segment
		(start 418.197792 -273.29257)
		(end 417.880292 -273.29257)
		(width 0.18288)
		(layer "In11.Cu")
		(net "M_H_CPU0_SA_CB<4>")
	)
	(segment
		(start 376.889264 -259.292598)
		(end 376.874532 -259.301234)
		(width 0.088646)
		(layer "In11.Cu")
		(net "M_H_CPU0_SA_CB<4>")
	)
	(segment
		(start 450.592444 -272.966942)
		(end 450.290946 -272.966942)
		(width 0.18288)
		(layer "In11.Cu")
		(net "M_H_CPU0_SA_CB<4>")
	)
	(segment
		(start 444.519812 -273.789394)
		(end 444.202312 -273.789394)
		(width 0.18288)
		(layer "In11.Cu")
		(net "M_H_CPU0_SA_CB<4>")
	)
	(segment
		(start 427.671738 -273.51355)
		(end 426.81017 -273.51355)
		(width 0.18288)
		(layer "In11.Cu")
		(net "M_H_CPU0_SA_CB<4>")
	)
	(segment
		(start 433.396136 -273.125946)
		(end 433.203096 -272.932906)
		(width 0.18288)
		(layer "In11.Cu")
		(net "M_H_CPU0_SA_CB<4>")
	)
	(segment
		(start 417.494212 -272.355056)
		(end 416.247072 -272.355056)
		(width 0.18288)
		(layer "In11.Cu")
		(net "M_H_CPU0_SA_CB<4>")
	)
	(segment
		(start 387.245606 -260.672326)
		(end 386.757926 -260.672326)
		(width 0.088646)
		(layer "In11.Cu")
		(net "M_H_CPU0_SA_CB<4>")
	)
	(arc
		(start 378.754132 -259.301234)
		(mid 378.477657 -259.368554)
		(end 378.20346 -259.292598)
		(width 0.088646)
		(layer "In11.Cu")
		(net "M_H_CPU0_SA_CB<4>")
	)
	(arc
		(start 380.08306 -259.292598)
		(mid 379.895862 -259.242455)
		(end 379.708664 -259.292598)
		(width 0.088646)
		(layer "In11.Cu")
		(net "M_H_CPU0_SA_CB<4>")
	)
	(arc
		(start 377.829064 -259.292598)
		(mid 377.546362 -259.368374)
		(end 377.26366 -259.292598)
		(width 0.088646)
		(layer "In11.Cu")
		(net "M_H_CPU0_SA_CB<4>")
	)
	(arc
		(start 375.934732 -259.301234)
		(mid 375.658257 -259.368554)
		(end 375.38406 -259.292598)
		(width 0.088646)
		(layer "In11.Cu")
		(net "M_H_CPU0_SA_CB<4>")
	)
	(arc
		(start 375.38406 -259.292598)
		(mid 375.196862 -259.242455)
		(end 375.009664 -259.292598)
		(width 0.088646)
		(layer "In11.Cu")
		(net "M_H_CPU0_SA_CB<4>")
	)
	(arc
		(start 381.573532 -259.301234)
		(mid 381.297057 -259.368554)
		(end 381.02286 -259.292598)
		(width 0.088646)
		(layer "In11.Cu")
		(net "M_H_CPU0_SA_CB<4>")
	)
	(arc
		(start 383.457196 -259.298694)
		(mid 383.179018 -259.368417)
		(end 382.90246 -259.292598)
		(width 0.088646)
		(layer "In11.Cu")
		(net "M_H_CPU0_SA_CB<4>")
	)
	(arc
		(start 379.693932 -259.301234)
		(mid 379.417457 -259.368554)
		(end 379.14326 -259.292598)
		(width 0.088646)
		(layer "In11.Cu")
		(net "M_H_CPU0_SA_CB<4>")
	)
	(arc
		(start 385.332478 -259.301234)
		(mid 385.056003 -259.368554)
		(end 384.781806 -259.292598)
		(width 0.088646)
		(layer "In11.Cu")
		(net "M_H_CPU0_SA_CB<4>")
	)
	(arc
		(start 374.069864 -259.292598)
		(mid 373.970763 -259.358809)
		(end 373.881142 -259.437378)
		(width 0.088646)
		(layer "In11.Cu")
		(net "M_H_CPU0_SA_CB<4>")
	)
	(arc
		(start 374.994932 -259.301234)
		(mid 374.718457 -259.368554)
		(end 374.44426 -259.292598)
		(width 0.088646)
		(layer "In11.Cu")
		(net "M_H_CPU0_SA_CB<4>")
	)
	(arc
		(start 384.392678 -259.301234)
		(mid 384.116203 -259.368554)
		(end 383.842006 -259.292598)
		(width 0.088646)
		(layer "In11.Cu")
		(net "M_H_CPU0_SA_CB<4>")
	)
	(arc
		(start 373.878094 -259.440426)
		(mid 373.798605 -259.532426)
		(end 373.733314 -259.63499)
		(width 0.088646)
		(layer "In11.Cu")
		(net "M_H_CPU0_SA_CB<4>")
	)
	(arc
		(start 374.44426 -259.292598)
		(mid 374.257062 -259.242455)
		(end 374.069864 -259.292598)
		(width 0.088646)
		(layer "In11.Cu")
		(net "M_H_CPU0_SA_CB<4>")
	)
	(arc
		(start 384.781806 -259.292598)
		(mid 384.594608 -259.242455)
		(end 384.40741 -259.292598)
		(width 0.088646)
		(layer "In11.Cu")
		(net "M_H_CPU0_SA_CB<4>")
	)
	(arc
		(start 379.14326 -259.292598)
		(mid 378.956062 -259.242455)
		(end 378.768864 -259.292598)
		(width 0.088646)
		(layer "In11.Cu")
		(net "M_H_CPU0_SA_CB<4>")
	)
	(arc
		(start 371.793262 -259.712206)
		(mid 371.621729 -259.641185)
		(end 371.437662 -259.616956)
		(width 0.088646)
		(layer "In11.Cu")
		(net "M_H_CPU0_SA_CB<4>")
	)
	(arc
		(start 385.909058 -259.616956)
		(mid 385.861379 -259.434056)
		(end 385.730496 -259.297678)
		(width 0.088646)
		(layer "In11.Cu")
		(net "M_H_CPU0_SA_CB<4>")
	)
	(arc
		(start 382.513332 -259.301234)
		(mid 382.236857 -259.368554)
		(end 381.96266 -259.292598)
		(width 0.088646)
		(layer "In11.Cu")
		(net "M_H_CPU0_SA_CB<4>")
	)
	(arc
		(start 378.20346 -259.292598)
		(mid 378.016262 -259.242455)
		(end 377.829064 -259.292598)
		(width 0.088646)
		(layer "In11.Cu")
		(net "M_H_CPU0_SA_CB<4>")
	)
	(arc
		(start 373.647208 -259.794756)
		(mid 373.589743 -259.874311)
		(end 373.513604 -259.936234)
		(width 0.088646)
		(layer "In11.Cu")
		(net "M_H_CPU0_SA_CB<4>")
	)
	(arc
		(start 373.51208 -259.936742)
		(mid 373.321705 -259.991385)
		(end 373.130064 -259.941314)
		(width 0.088646)
		(layer "In11.Cu")
		(net "M_H_CPU0_SA_CB<4>")
	)
	(arc
		(start 383.842006 -259.292598)
		(mid 383.654808 -259.242455)
		(end 383.46761 -259.292598)
		(width 0.088646)
		(layer "In11.Cu")
		(net "M_H_CPU0_SA_CB<4>")
	)
	(arc
		(start 381.02286 -259.292598)
		(mid 380.835662 -259.242455)
		(end 380.648464 -259.292598)
		(width 0.088646)
		(layer "In11.Cu")
		(net "M_H_CPU0_SA_CB<4>")
	)
	(arc
		(start 381.96266 -259.292598)
		(mid 381.775462 -259.242455)
		(end 381.588264 -259.292598)
		(width 0.088646)
		(layer "In11.Cu")
		(net "M_H_CPU0_SA_CB<4>")
	)
	(arc
		(start 382.90246 -259.292598)
		(mid 382.715262 -259.242455)
		(end 382.528064 -259.292598)
		(width 0.088646)
		(layer "In11.Cu")
		(net "M_H_CPU0_SA_CB<4>")
	)
	(arc
		(start 376.874532 -259.301234)
		(mid 376.598057 -259.368554)
		(end 376.32386 -259.292598)
		(width 0.088646)
		(layer "In11.Cu")
		(net "M_H_CPU0_SA_CB<4>")
	)
	(arc
		(start 385.721606 -259.292598)
		(mid 385.534408 -259.242455)
		(end 385.34721 -259.292598)
		(width 0.088646)
		(layer "In11.Cu")
		(net "M_H_CPU0_SA_CB<4>")
	)
	(arc
		(start 373.115332 -259.932678)
		(mid 372.838857 -259.865358)
		(end 372.56466 -259.941314)
		(width 0.088646)
		(layer "In11.Cu")
		(net "M_H_CPU0_SA_CB<4>")
	)
	(arc
		(start 386.185664 -260.102858)
		(mid 385.983077 -259.896507)
		(end 385.909058 -259.616956)
		(width 0.088646)
		(layer "In11.Cu")
		(net "M_H_CPU0_SA_CB<4>")
	)
	(arc
		(start 372.56466 -259.941314)
		(mid 372.377462 -259.991457)
		(end 372.190264 -259.941314)
		(width 0.088646)
		(layer "In11.Cu")
		(net "M_H_CPU0_SA_CB<4>")
	)
	(arc
		(start 377.26366 -259.292598)
		(mid 377.076462 -259.242455)
		(end 376.889264 -259.292598)
		(width 0.088646)
		(layer "In11.Cu")
		(net "M_H_CPU0_SA_CB<4>")
	)
	(arc
		(start 380.633732 -259.301234)
		(mid 380.357257 -259.368554)
		(end 380.08306 -259.292598)
		(width 0.088646)
		(layer "In11.Cu")
		(net "M_H_CPU0_SA_CB<4>")
	)
	(arc
		(start 376.32386 -259.292598)
		(mid 376.136662 -259.242455)
		(end 375.949464 -259.292598)
		(width 0.088646)
		(layer "In11.Cu")
		(net "M_H_CPU0_SA_CB<4>")
	)
	(segment
		(start 458.550264 -276.791674)
		(end 460.558134 -276.791674)
		(width 0.1016)
		(layer "F.Cu")
		(net "M_H_CPU0_SA_CB<3>")
	)
	(segment
		(start 456.116182 -276.366732)
		(end 457.814426 -276.366732)
		(width 0.20066)
		(layer "F.Cu")
		(net "M_H_CPU0_SA_CB<3>")
	)
	(segment
		(start 457.814426 -276.366732)
		(end 458.24648 -276.798786)
		(width 0.20066)
		(layer "F.Cu")
		(net "M_H_CPU0_SA_CB<3>")
	)
	(segment
		(start 461.689704 -276.114764)
		(end 462.073752 -276.114764)
		(width 0.20066)
		(layer "F.Cu")
		(net "M_H_CPU0_SA_CB<3>")
	)
	(segment
		(start 373.317516 -261.244334)
		(end 373.317262 -261.244588)
		(width 0.20066)
		(layer "F.Cu")
		(net "M_H_CPU0_SA_CB<3>")
	)
	(segment
		(start 460.570326 -276.803866)
		(end 461.251554 -276.803866)
		(width 0.20066)
		(layer "F.Cu")
		(net "M_H_CPU0_SA_CB<3>")
	)
	(segment
		(start 458.543152 -276.798786)
		(end 458.550264 -276.791674)
		(width 0.1016)
		(layer "F.Cu")
		(net "M_H_CPU0_SA_CB<3>")
	)
	(segment
		(start 373.317516 -260.708902)
		(end 373.317516 -261.244334)
		(width 0.20066)
		(layer "F.Cu")
		(net "M_H_CPU0_SA_CB<3>")
	)
	(segment
		(start 462.073752 -276.114764)
		(end 462.32572 -276.366732)
		(width 0.20066)
		(layer "F.Cu")
		(net "M_H_CPU0_SA_CB<3>")
	)
	(segment
		(start 461.455516 -276.599904)
		(end 461.455516 -276.348952)
		(width 0.20066)
		(layer "F.Cu")
		(net "M_H_CPU0_SA_CB<3>")
	)
	(segment
		(start 455.011282 -276.366732)
		(end 456.116182 -276.366732)
		(width 0.20066)
		(layer "F.Cu")
		(net "M_H_CPU0_SA_CB<3>")
	)
	(segment
		(start 462.32572 -276.366732)
		(end 463.659982 -276.366732)
		(width 0.20066)
		(layer "F.Cu")
		(net "M_H_CPU0_SA_CB<3>")
	)
	(segment
		(start 373.317262 -261.244588)
		(end 373.317262 -261.244842)
		(width 0.20066)
		(layer "F.Cu")
		(net "M_H_CPU0_SA_CB<3>")
	)
	(segment
		(start 461.455516 -276.348952)
		(end 461.689704 -276.114764)
		(width 0.20066)
		(layer "F.Cu")
		(net "M_H_CPU0_SA_CB<3>")
	)
	(segment
		(start 458.538326 -276.798786)
		(end 458.543152 -276.798786)
		(width 0.101854)
		(layer "F.Cu")
		(net "M_H_CPU0_SA_CB<3>")
	)
	(segment
		(start 461.251554 -276.803866)
		(end 461.455516 -276.599904)
		(width 0.20066)
		(layer "F.Cu")
		(net "M_H_CPU0_SA_CB<3>")
	)
	(segment
		(start 458.24648 -276.798786)
		(end 458.538326 -276.798786)
		(width 0.20066)
		(layer "F.Cu")
		(net "M_H_CPU0_SA_CB<3>")
	)
	(segment
		(start 460.558134 -276.791674)
		(end 460.570326 -276.803866)
		(width 0.1016)
		(layer "F.Cu")
		(net "M_H_CPU0_SA_CB<3>")
	)
	(segment
		(start 384.690112 -262.058658)
		(end 384.690112 -262.048752)
		(width 0.088646)
		(layer "In11.Cu")
		(net "M_H_CPU0_SA_CB<3>")
	)
	(segment
		(start 451.558914 -276.793706)
		(end 450.823838 -276.793706)
		(width 0.18288)
		(layer "In11.Cu")
		(net "M_H_CPU0_SA_CB<3>")
	)
	(segment
		(start 433.329334 -277.03018)
		(end 433.136294 -277.22322)
		(width 0.18288)
		(layer "In11.Cu")
		(net "M_H_CPU0_SA_CB<3>")
	)
	(segment
		(start 404.515574 -275.345398)
		(end 393.372848 -264.202672)
		(width 0.18288)
		(layer "In11.Cu")
		(net "M_H_CPU0_SA_CB<3>")
	)
	(segment
		(start 376.889264 -261.5692)
		(end 376.874532 -261.560564)
		(width 0.088646)
		(layer "In11.Cu")
		(net "M_H_CPU0_SA_CB<3>")
	)
	(segment
		(start 378.768864 -261.5692)
		(end 378.754132 -261.560564)
		(width 0.088646)
		(layer "In11.Cu")
		(net "M_H_CPU0_SA_CB<3>")
	)
	(segment
		(start 455.011282 -276.366732)
		(end 454.728834 -276.366732)
		(width 0.18288)
		(layer "In11.Cu")
		(net "M_H_CPU0_SA_CB<3>")
	)
	(segment
		(start 428.732696 -276.798024)
		(end 427.700694 -277.830026)
		(width 0.18288)
		(layer "In11.Cu")
		(net "M_H_CPU0_SA_CB<3>")
	)
	(segment
		(start 420.692326 -277.641558)
		(end 419.901878 -277.641558)
		(width 0.18288)
		(layer "In11.Cu")
		(net "M_H_CPU0_SA_CB<3>")
	)
	(segment
		(start 386.917438 -264.019792)
		(end 386.569966 -263.67232)
		(width 0.088646)
		(layer "In11.Cu")
		(net "M_H_CPU0_SA_CB<3>")
	)
	(segment
		(start 382.528064 -261.5692)
		(end 382.513332 -261.560564)
		(width 0.088646)
		(layer "In11.Cu")
		(net "M_H_CPU0_SA_CB<3>")
	)
	(segment
		(start 388.30377 -264.202672)
		(end 388.12089 -264.019792)
		(width 0.18288)
		(layer "In11.Cu")
		(net "M_H_CPU0_SA_CB<3>")
	)
	(segment
		(start 424.704256 -278.491696)
		(end 423.889424 -278.491696)
		(width 0.18288)
		(layer "In11.Cu")
		(net "M_H_CPU0_SA_CB<3>")
	)
	(segment
		(start 446.367662 -277.632922)
		(end 442.368178 -277.632922)
		(width 0.18288)
		(layer "In11.Cu")
		(net "M_H_CPU0_SA_CB<3>")
	)
	(segment
		(start 393.372848 -264.202672)
		(end 388.30377 -264.202672)
		(width 0.18288)
		(layer "In11.Cu")
		(net "M_H_CPU0_SA_CB<3>")
	)
	(segment
		(start 433.839874 -277.636986)
		(end 433.839874 -277.22322)
		(width 0.18288)
		(layer "In11.Cu")
		(net "M_H_CPU0_SA_CB<3>")
	)
	(segment
		(start 441.91428 -277.847552)
		(end 440.362086 -278.490426)
		(width 0.18288)
		(layer "In11.Cu")
		(net "M_H_CPU0_SA_CB<3>")
	)
	(segment
		(start 447.220086 -276.780498)
		(end 446.367662 -277.632922)
		(width 0.18288)
		(layer "In11.Cu")
		(net "M_H_CPU0_SA_CB<3>")
	)
	(segment
		(start 421.821864 -277.640796)
		(end 420.693088 -277.640796)
		(width 0.18288)
		(layer "In11.Cu")
		(net "M_H_CPU0_SA_CB<3>")
	)
	(segment
		(start 412.402782 -276.941026)
		(end 412.248604 -276.786848)
		(width 0.18288)
		(layer "In11.Cu")
		(net "M_H_CPU0_SA_CB<3>")
	)
	(segment
		(start 385.732274 -263.190736)
		(end 385.72186 -263.196832)
		(width 0.088646)
		(layer "In11.Cu")
		(net "M_H_CPU0_SA_CB<3>")
	)
	(segment
		(start 417.083494 -277.742142)
		(end 416.282378 -276.941026)
		(width 0.18288)
		(layer "In11.Cu")
		(net "M_H_CPU0_SA_CB<3>")
	)
	(segment
		(start 426.456094 -277.830026)
		(end 425.795186 -278.490934)
		(width 0.18288)
		(layer "In11.Cu")
		(net "M_H_CPU0_SA_CB<3>")
	)
	(segment
		(start 410.427424 -276.077426)
		(end 409.38196 -276.077426)
		(width 0.18288)
		(layer "In11.Cu")
		(net "M_H_CPU0_SA_CB<3>")
	)
	(segment
		(start 449.237354 -275.99005)
		(end 448.446906 -276.780498)
		(width 0.18288)
		(layer "In11.Cu")
		(net "M_H_CPU0_SA_CB<3>")
	)
	(segment
		(start 439.415682 -278.490426)
		(end 439.274712 -278.631396)
		(width 0.18288)
		(layer "In11.Cu")
		(net "M_H_CPU0_SA_CB<3>")
	)
	(segment
		(start 416.282378 -276.941026)
		(end 412.402782 -276.941026)
		(width 0.18288)
		(layer "In11.Cu")
		(net "M_H_CPU0_SA_CB<3>")
	)
	(segment
		(start 434.032914 -277.830026)
		(end 433.839874 -277.636986)
		(width 0.18288)
		(layer "In11.Cu")
		(net "M_H_CPU0_SA_CB<3>")
	)
	(segment
		(start 451.830186 -277.064978)
		(end 451.558914 -276.793706)
		(width 0.18288)
		(layer "In11.Cu")
		(net "M_H_CPU0_SA_CB<3>")
	)
	(segment
		(start 406.301702 -275.345652)
		(end 406.301448 -275.345398)
		(width 0.18288)
		(layer "In11.Cu")
		(net "M_H_CPU0_SA_CB<3>")
	)
	(segment
		(start 450.822314 -276.792182)
		(end 450.68617 -276.792182)
		(width 0.18288)
		(layer "In11.Cu")
		(net "M_H_CPU0_SA_CB<3>")
	)
	(segment
		(start 454.728834 -276.366732)
		(end 454.030588 -277.064978)
		(width 0.18288)
		(layer "In11.Cu")
		(net "M_H_CPU0_SA_CB<3>")
	)
	(segment
		(start 419.901878 -277.641558)
		(end 419.801294 -277.742142)
		(width 0.18288)
		(layer "In11.Cu")
		(net "M_H_CPU0_SA_CB<3>")
	)
	(segment
		(start 431.967894 -277.830026)
		(end 430.935892 -276.798024)
		(width 0.18288)
		(layer "In11.Cu")
		(net "M_H_CPU0_SA_CB<3>")
	)
	(segment
		(start 432.943254 -277.830026)
		(end 431.967894 -277.830026)
		(width 0.18288)
		(layer "In11.Cu")
		(net "M_H_CPU0_SA_CB<3>")
	)
	(segment
		(start 433.136294 -277.22322)
		(end 433.136294 -277.636986)
		(width 0.18288)
		(layer "In11.Cu")
		(net "M_H_CPU0_SA_CB<3>")
	)
	(segment
		(start 408.650186 -275.345652)
		(end 406.301702 -275.345652)
		(width 0.18288)
		(layer "In11.Cu")
		(net "M_H_CPU0_SA_CB<3>")
	)
	(segment
		(start 424.705018 -278.490934)
		(end 424.704256 -278.491696)
		(width 0.18288)
		(layer "In11.Cu")
		(net "M_H_CPU0_SA_CB<3>")
	)
	(segment
		(start 442.368178 -277.632922)
		(end 442.153548 -277.847552)
		(width 0.18288)
		(layer "In11.Cu")
		(net "M_H_CPU0_SA_CB<3>")
	)
	(segment
		(start 434.722524 -277.640796)
		(end 434.533294 -277.830026)
		(width 0.18288)
		(layer "In11.Cu")
		(net "M_H_CPU0_SA_CB<3>")
	)
	(segment
		(start 420.693088 -277.640796)
		(end 420.692326 -277.641558)
		(width 0.18288)
		(layer "In11.Cu")
		(net "M_H_CPU0_SA_CB<3>")
	)
	(segment
		(start 387.545072 -264.019792)
		(end 386.917438 -264.019792)
		(width 0.088646)
		(layer "In11.Cu")
		(net "M_H_CPU0_SA_CB<3>")
	)
	(segment
		(start 388.12089 -264.019792)
		(end 387.545072 -264.019792)
		(width 0.18288)
		(layer "In11.Cu")
		(net "M_H_CPU0_SA_CB<3>")
	)
	(segment
		(start 384.877564 -262.383016)
		(end 384.868674 -262.377936)
		(width 0.088646)
		(layer "In11.Cu")
		(net "M_H_CPU0_SA_CB<3>")
	)
	(segment
		(start 433.136294 -277.636986)
		(end 432.943254 -277.830026)
		(width 0.18288)
		(layer "In11.Cu")
		(net "M_H_CPU0_SA_CB<3>")
	)
	(segment
		(start 448.446906 -276.780498)
		(end 447.220086 -276.780498)
		(width 0.18288)
		(layer "In11.Cu")
		(net "M_H_CPU0_SA_CB<3>")
	)
	(segment
		(start 406.301448 -275.345398)
		(end 404.515574 -275.345398)
		(width 0.18288)
		(layer "In11.Cu")
		(net "M_H_CPU0_SA_CB<3>")
	)
	(segment
		(start 375.009664 -261.5692)
		(end 374.994932 -261.560564)
		(width 0.088646)
		(layer "In11.Cu")
		(net "M_H_CPU0_SA_CB<3>")
	)
	(segment
		(start 412.248604 -276.786848)
		(end 411.136846 -276.786848)
		(width 0.18288)
		(layer "In11.Cu")
		(net "M_H_CPU0_SA_CB<3>")
	)
	(segment
		(start 430.935892 -276.798024)
		(end 428.732696 -276.798024)
		(width 0.18288)
		(layer "In11.Cu")
		(net "M_H_CPU0_SA_CB<3>")
	)
	(segment
		(start 423.889424 -278.491696)
		(end 423.738294 -278.642826)
		(width 0.18288)
		(layer "In11.Cu")
		(net "M_H_CPU0_SA_CB<3>")
	)
	(segment
		(start 425.795186 -278.490934)
		(end 424.705018 -278.490934)
		(width 0.18288)
		(layer "In11.Cu")
		(net "M_H_CPU0_SA_CB<3>")
	)
	(segment
		(start 422.823894 -278.642826)
		(end 421.821864 -277.640796)
		(width 0.18288)
		(layer "In11.Cu")
		(net "M_H_CPU0_SA_CB<3>")
	)
	(segment
		(start 454.030588 -277.064978)
		(end 451.830186 -277.064978)
		(width 0.18288)
		(layer "In11.Cu")
		(net "M_H_CPU0_SA_CB<3>")
	)
	(segment
		(start 440.362086 -278.490426)
		(end 439.415682 -278.490426)
		(width 0.18288)
		(layer "In11.Cu")
		(net "M_H_CPU0_SA_CB<3>")
	)
	(segment
		(start 439.274712 -278.631396)
		(end 438.204102 -278.631396)
		(width 0.18288)
		(layer "In11.Cu")
		(net "M_H_CPU0_SA_CB<3>")
	)
	(segment
		(start 379.708664 -261.5692)
		(end 379.693932 -261.560564)
		(width 0.088646)
		(layer "In11.Cu")
		(net "M_H_CPU0_SA_CB<3>")
	)
	(segment
		(start 385.347464 -263.196832)
		(end 385.338574 -263.191752)
		(width 0.088646)
		(layer "In11.Cu")
		(net "M_H_CPU0_SA_CB<3>")
	)
	(segment
		(start 433.646834 -277.03018)
		(end 433.329334 -277.03018)
		(width 0.18288)
		(layer "In11.Cu")
		(net "M_H_CPU0_SA_CB<3>")
	)
	(segment
		(start 433.839874 -277.22322)
		(end 433.646834 -277.03018)
		(width 0.18288)
		(layer "In11.Cu")
		(net "M_H_CPU0_SA_CB<3>")
	)
	(segment
		(start 434.533294 -277.830026)
		(end 434.032914 -277.830026)
		(width 0.18288)
		(layer "In11.Cu")
		(net "M_H_CPU0_SA_CB<3>")
	)
	(segment
		(start 423.738294 -278.642826)
		(end 422.823894 -278.642826)
		(width 0.18288)
		(layer "In11.Cu")
		(net "M_H_CPU0_SA_CB<3>")
	)
	(segment
		(start 438.204102 -278.631396)
		(end 437.684926 -278.416258)
		(width 0.18288)
		(layer "In11.Cu")
		(net "M_H_CPU0_SA_CB<3>")
	)
	(segment
		(start 449.884038 -275.99005)
		(end 449.237354 -275.99005)
		(width 0.18288)
		(layer "In11.Cu")
		(net "M_H_CPU0_SA_CB<3>")
	)
	(segment
		(start 381.588264 -261.5692)
		(end 381.573532 -261.560564)
		(width 0.088646)
		(layer "In11.Cu")
		(net "M_H_CPU0_SA_CB<3>")
	)
	(segment
		(start 442.153548 -277.847552)
		(end 441.91428 -277.847552)
		(width 0.18288)
		(layer "In11.Cu")
		(net "M_H_CPU0_SA_CB<3>")
	)
	(segment
		(start 409.38196 -276.077426)
		(end 408.650186 -275.345652)
		(width 0.18288)
		(layer "In11.Cu")
		(net "M_H_CPU0_SA_CB<3>")
	)
	(segment
		(start 450.823838 -276.793706)
		(end 450.822314 -276.792182)
		(width 0.18288)
		(layer "In11.Cu")
		(net "M_H_CPU0_SA_CB<3>")
	)
	(segment
		(start 374.069864 -261.5692)
		(end 373.672862 -261.340092)
		(width 0.088646)
		(layer "In11.Cu")
		(net "M_H_CPU0_SA_CB<3>")
	)
	(segment
		(start 427.700694 -277.830026)
		(end 426.456094 -277.830026)
		(width 0.18288)
		(layer "In11.Cu")
		(net "M_H_CPU0_SA_CB<3>")
	)
	(segment
		(start 419.801294 -277.742142)
		(end 417.083494 -277.742142)
		(width 0.18288)
		(layer "In11.Cu")
		(net "M_H_CPU0_SA_CB<3>")
	)
	(segment
		(start 377.829064 -261.5692)
		(end 377.814332 -261.560564)
		(width 0.088646)
		(layer "In11.Cu")
		(net "M_H_CPU0_SA_CB<3>")
	)
	(segment
		(start 375.949464 -261.5692)
		(end 375.934732 -261.560564)
		(width 0.088646)
		(layer "In11.Cu")
		(net "M_H_CPU0_SA_CB<3>")
	)
	(segment
		(start 385.160012 -262.872474)
		(end 385.160012 -262.862568)
		(width 0.088646)
		(layer "In11.Cu")
		(net "M_H_CPU0_SA_CB<3>")
	)
	(segment
		(start 436.909464 -277.640796)
		(end 434.722524 -277.640796)
		(width 0.18288)
		(layer "In11.Cu")
		(net "M_H_CPU0_SA_CB<3>")
	)
	(segment
		(start 450.68617 -276.792182)
		(end 449.884038 -275.99005)
		(width 0.18288)
		(layer "In11.Cu")
		(net "M_H_CPU0_SA_CB<3>")
	)
	(segment
		(start 411.136846 -276.786848)
		(end 410.427424 -276.077426)
		(width 0.18288)
		(layer "In11.Cu")
		(net "M_H_CPU0_SA_CB<3>")
	)
	(segment
		(start 437.684926 -278.416258)
		(end 436.909464 -277.640796)
		(width 0.18288)
		(layer "In11.Cu")
		(net "M_H_CPU0_SA_CB<3>")
	)
	(arc
		(start 378.20346 -261.5692)
		(mid 378.016262 -261.619343)
		(end 377.829064 -261.5692)
		(width 0.088646)
		(layer "In11.Cu")
		(net "M_H_CPU0_SA_CB<3>")
	)
	(arc
		(start 384.407664 -261.5692)
		(mid 384.124962 -261.493424)
		(end 383.84226 -261.5692)
		(width 0.088646)
		(layer "In11.Cu")
		(net "M_H_CPU0_SA_CB<3>")
	)
	(arc
		(start 381.573532 -261.560564)
		(mid 381.297057 -261.493244)
		(end 381.02286 -261.5692)
		(width 0.088646)
		(layer "In11.Cu")
		(net "M_H_CPU0_SA_CB<3>")
	)
	(arc
		(start 374.44426 -261.5692)
		(mid 374.257062 -261.619343)
		(end 374.069864 -261.5692)
		(width 0.088646)
		(layer "In11.Cu")
		(net "M_H_CPU0_SA_CB<3>")
	)
	(arc
		(start 379.693932 -261.560564)
		(mid 379.417457 -261.493244)
		(end 379.14326 -261.5692)
		(width 0.088646)
		(layer "In11.Cu")
		(net "M_H_CPU0_SA_CB<3>")
	)
	(arc
		(start 383.84226 -261.5692)
		(mid 383.655062 -261.619343)
		(end 383.467864 -261.5692)
		(width 0.088646)
		(layer "In11.Cu")
		(net "M_H_CPU0_SA_CB<3>")
	)
	(arc
		(start 374.994932 -261.560564)
		(mid 374.718457 -261.493244)
		(end 374.44426 -261.5692)
		(width 0.088646)
		(layer "In11.Cu")
		(net "M_H_CPU0_SA_CB<3>")
	)
	(arc
		(start 384.690112 -262.048752)
		(mid 384.612001 -261.771803)
		(end 384.407664 -261.5692)
		(width 0.088646)
		(layer "In11.Cu")
		(net "M_H_CPU0_SA_CB<3>")
	)
	(arc
		(start 377.26366 -261.5692)
		(mid 377.076462 -261.619343)
		(end 376.889264 -261.5692)
		(width 0.088646)
		(layer "In11.Cu")
		(net "M_H_CPU0_SA_CB<3>")
	)
	(arc
		(start 378.754132 -261.560564)
		(mid 378.477657 -261.493244)
		(end 378.20346 -261.5692)
		(width 0.088646)
		(layer "In11.Cu")
		(net "M_H_CPU0_SA_CB<3>")
	)
	(arc
		(start 382.90246 -261.5692)
		(mid 382.715262 -261.619343)
		(end 382.528064 -261.5692)
		(width 0.088646)
		(layer "In11.Cu")
		(net "M_H_CPU0_SA_CB<3>")
	)
	(arc
		(start 377.814332 -261.560564)
		(mid 377.537857 -261.493244)
		(end 377.26366 -261.5692)
		(width 0.088646)
		(layer "In11.Cu")
		(net "M_H_CPU0_SA_CB<3>")
	)
	(arc
		(start 375.38406 -261.5692)
		(mid 375.196862 -261.619343)
		(end 375.009664 -261.5692)
		(width 0.088646)
		(layer "In11.Cu")
		(net "M_H_CPU0_SA_CB<3>")
	)
	(arc
		(start 379.14326 -261.5692)
		(mid 378.956062 -261.619343)
		(end 378.768864 -261.5692)
		(width 0.088646)
		(layer "In11.Cu")
		(net "M_H_CPU0_SA_CB<3>")
	)
	(arc
		(start 373.672862 -261.340092)
		(mid 373.501329 -261.269071)
		(end 373.317262 -261.244842)
		(width 0.088646)
		(layer "In11.Cu")
		(net "M_H_CPU0_SA_CB<3>")
	)
	(arc
		(start 381.96266 -261.5692)
		(mid 381.775462 -261.619343)
		(end 381.588264 -261.5692)
		(width 0.088646)
		(layer "In11.Cu")
		(net "M_H_CPU0_SA_CB<3>")
	)
	(arc
		(start 380.08306 -261.5692)
		(mid 379.895862 -261.619343)
		(end 379.708664 -261.5692)
		(width 0.088646)
		(layer "In11.Cu")
		(net "M_H_CPU0_SA_CB<3>")
	)
	(arc
		(start 385.338574 -263.191752)
		(mid 385.20766 -263.055392)
		(end 385.160012 -262.872474)
		(width 0.088646)
		(layer "In11.Cu")
		(net "M_H_CPU0_SA_CB<3>")
	)
	(arc
		(start 380.648464 -261.5692)
		(mid 380.365762 -261.493424)
		(end 380.08306 -261.5692)
		(width 0.088646)
		(layer "In11.Cu")
		(net "M_H_CPU0_SA_CB<3>")
	)
	(arc
		(start 386.569966 -263.67232)
		(mid 386.28643 -263.196203)
		(end 385.732274 -263.190736)
		(width 0.088646)
		(layer "In11.Cu")
		(net "M_H_CPU0_SA_CB<3>")
	)
	(arc
		(start 385.160012 -262.862568)
		(mid 385.081901 -262.585619)
		(end 384.877564 -262.383016)
		(width 0.088646)
		(layer "In11.Cu")
		(net "M_H_CPU0_SA_CB<3>")
	)
	(arc
		(start 385.72186 -263.196832)
		(mid 385.534662 -263.246975)
		(end 385.347464 -263.196832)
		(width 0.088646)
		(layer "In11.Cu")
		(net "M_H_CPU0_SA_CB<3>")
	)
	(arc
		(start 384.868674 -262.377936)
		(mid 384.73776 -262.241576)
		(end 384.690112 -262.058658)
		(width 0.088646)
		(layer "In11.Cu")
		(net "M_H_CPU0_SA_CB<3>")
	)
	(arc
		(start 376.874532 -261.560564)
		(mid 376.598057 -261.493244)
		(end 376.32386 -261.5692)
		(width 0.088646)
		(layer "In11.Cu")
		(net "M_H_CPU0_SA_CB<3>")
	)
	(arc
		(start 375.934732 -261.560564)
		(mid 375.658257 -261.493244)
		(end 375.38406 -261.5692)
		(width 0.088646)
		(layer "In11.Cu")
		(net "M_H_CPU0_SA_CB<3>")
	)
	(arc
		(start 382.513332 -261.560564)
		(mid 382.236857 -261.493244)
		(end 381.96266 -261.5692)
		(width 0.088646)
		(layer "In11.Cu")
		(net "M_H_CPU0_SA_CB<3>")
	)
	(arc
		(start 376.32386 -261.5692)
		(mid 376.136662 -261.619343)
		(end 375.949464 -261.5692)
		(width 0.088646)
		(layer "In11.Cu")
		(net "M_H_CPU0_SA_CB<3>")
	)
	(arc
		(start 383.467864 -261.5692)
		(mid 383.185162 -261.493424)
		(end 382.90246 -261.5692)
		(width 0.088646)
		(layer "In11.Cu")
		(net "M_H_CPU0_SA_CB<3>")
	)
	(arc
		(start 381.02286 -261.5692)
		(mid 380.835662 -261.619343)
		(end 380.648464 -261.5692)
		(width 0.088646)
		(layer "In11.Cu")
		(net "M_H_CPU0_SA_CB<3>")
	)
	(segment
		(start 458.538326 -278.498808)
		(end 458.543152 -278.498808)
		(width 0.101854)
		(layer "F.Cu")
		(net "M_H_CPU0_SA_CB<2>")
	)
	(segment
		(start 372.847362 -261.522718)
		(end 372.847616 -261.522972)
		(width 0.20066)
		(layer "F.Cu")
		(net "M_H_CPU0_SA_CB<2>")
	)
	(segment
		(start 461.455516 -278.048974)
		(end 461.689704 -277.814786)
		(width 0.20066)
		(layer "F.Cu")
		(net "M_H_CPU0_SA_CB<2>")
	)
	(segment
		(start 461.251554 -278.503888)
		(end 461.455516 -278.299926)
		(width 0.20066)
		(layer "F.Cu")
		(net "M_H_CPU0_SA_CB<2>")
	)
	(segment
		(start 455.011282 -278.066754)
		(end 456.116182 -278.066754)
		(width 0.20066)
		(layer "F.Cu")
		(net "M_H_CPU0_SA_CB<2>")
	)
	(segment
		(start 372.847616 -261.522972)
		(end 372.847616 -262.058658)
		(width 0.20066)
		(layer "F.Cu")
		(net "M_H_CPU0_SA_CB<2>")
	)
	(segment
		(start 460.570326 -278.503888)
		(end 461.251554 -278.503888)
		(width 0.20066)
		(layer "F.Cu")
		(net "M_H_CPU0_SA_CB<2>")
	)
	(segment
		(start 461.689704 -277.814786)
		(end 462.073752 -277.814786)
		(width 0.20066)
		(layer "F.Cu")
		(net "M_H_CPU0_SA_CB<2>")
	)
	(segment
		(start 462.073752 -277.814786)
		(end 462.32572 -278.066754)
		(width 0.20066)
		(layer "F.Cu")
		(net "M_H_CPU0_SA_CB<2>")
	)
	(segment
		(start 462.32572 -278.066754)
		(end 463.659982 -278.066754)
		(width 0.20066)
		(layer "F.Cu")
		(net "M_H_CPU0_SA_CB<2>")
	)
	(segment
		(start 458.24648 -278.498808)
		(end 458.538326 -278.498808)
		(width 0.20066)
		(layer "F.Cu")
		(net "M_H_CPU0_SA_CB<2>")
	)
	(segment
		(start 456.116182 -278.066754)
		(end 457.814426 -278.066754)
		(width 0.20066)
		(layer "F.Cu")
		(net "M_H_CPU0_SA_CB<2>")
	)
	(segment
		(start 458.543152 -278.498808)
		(end 458.550264 -278.491696)
		(width 0.1016)
		(layer "F.Cu")
		(net "M_H_CPU0_SA_CB<2>")
	)
	(segment
		(start 461.455516 -278.299926)
		(end 461.455516 -278.048974)
		(width 0.20066)
		(layer "F.Cu")
		(net "M_H_CPU0_SA_CB<2>")
	)
	(segment
		(start 458.550264 -278.491696)
		(end 460.558134 -278.491696)
		(width 0.1016)
		(layer "F.Cu")
		(net "M_H_CPU0_SA_CB<2>")
	)
	(segment
		(start 457.814426 -278.066754)
		(end 458.24648 -278.498808)
		(width 0.20066)
		(layer "F.Cu")
		(net "M_H_CPU0_SA_CB<2>")
	)
	(segment
		(start 460.558134 -278.491696)
		(end 460.570326 -278.503888)
		(width 0.1016)
		(layer "F.Cu")
		(net "M_H_CPU0_SA_CB<2>")
	)
	(segment
		(start 440.536584 -280.190956)
		(end 439.047128 -280.190956)
		(width 0.18288)
		(layer "In11.Cu")
		(net "M_H_CPU0_SA_CB<2>")
	)
	(segment
		(start 380.563374 -262.37692)
		(end 380.55296 -262.383016)
		(width 0.088646)
		(layer "In11.Cu")
		(net "M_H_CPU0_SA_CB<2>")
	)
	(segment
		(start 442.637926 -279.090374)
		(end 442.221874 -279.506426)
		(width 0.18288)
		(layer "In11.Cu")
		(net "M_H_CPU0_SA_CB<2>")
	)
	(segment
		(start 409.363926 -277.552658)
		(end 408.921966 -277.110698)
		(width 0.18288)
		(layer "In11.Cu")
		(net "M_H_CPU0_SA_CB<2>")
	)
	(segment
		(start 439.047128 -280.190956)
		(end 438.907174 -280.33091)
		(width 0.18288)
		(layer "In11.Cu")
		(net "M_H_CPU0_SA_CB<2>")
	)
	(segment
		(start 440.847988 -279.879552)
		(end 440.536584 -280.190956)
		(width 0.18288)
		(layer "In11.Cu")
		(net "M_H_CPU0_SA_CB<2>")
	)
	(segment
		(start 372.534942 -262.058658)
		(end 372.847616 -262.058658)
		(width 0.088646)
		(layer "In11.Cu")
		(net "M_H_CPU0_SA_CB<2>")
	)
	(segment
		(start 434.805836 -279.340818)
		(end 434.700934 -279.44572)
		(width 0.18288)
		(layer "In11.Cu")
		(net "M_H_CPU0_SA_CB<2>")
	)
	(segment
		(start 372.660418 -262.383016)
		(end 372.651528 -262.377936)
		(width 0.088646)
		(layer "In11.Cu")
		(net "M_H_CPU0_SA_CB<2>")
	)
	(segment
		(start 384.877564 -264.010902)
		(end 384.868674 -264.005822)
		(width 0.088646)
		(layer "In11.Cu")
		(net "M_H_CPU0_SA_CB<2>")
	)
	(segment
		(start 387.545072 -265.218672)
		(end 387.146546 -265.218672)
		(width 0.088646)
		(layer "In11.Cu")
		(net "M_H_CPU0_SA_CB<2>")
	)
	(segment
		(start 441.748926 -279.506426)
		(end 440.847988 -279.879552)
		(width 0.18288)
		(layer "In11.Cu")
		(net "M_H_CPU0_SA_CB<2>")
	)
	(segment
		(start 454.985882 -278.066754)
		(end 453.760078 -279.292558)
		(width 0.18288)
		(layer "In11.Cu")
		(net "M_H_CPU0_SA_CB<2>")
	)
	(segment
		(start 437.906414 -280.33091)
		(end 436.916322 -279.340818)
		(width 0.18288)
		(layer "In11.Cu")
		(net "M_H_CPU0_SA_CB<2>")
	)
	(segment
		(start 380.178564 -262.383016)
		(end 380.16815 -262.37692)
		(width 0.088646)
		(layer "In11.Cu")
		(net "M_H_CPU0_SA_CB<2>")
	)
	(segment
		(start 450.039994 -277.911306)
		(end 449.02628 -277.911306)
		(width 0.18288)
		(layer "In11.Cu")
		(net "M_H_CPU0_SA_CB<2>")
	)
	(segment
		(start 410.120084 -277.906226)
		(end 409.363926 -277.552658)
		(width 0.18288)
		(layer "In11.Cu")
		(net "M_H_CPU0_SA_CB<2>")
	)
	(segment
		(start 449.02628 -277.911306)
		(end 448.482212 -278.455374)
		(width 0.18288)
		(layer "In11.Cu")
		(net "M_H_CPU0_SA_CB<2>")
	)
	(segment
		(start 421.822626 -279.340818)
		(end 420.068502 -279.340818)
		(width 0.18288)
		(layer "In11.Cu")
		(net "M_H_CPU0_SA_CB<2>")
	)
	(segment
		(start 424.794426 -280.191718)
		(end 424.16095 -280.191718)
		(width 0.18288)
		(layer "In11.Cu")
		(net "M_H_CPU0_SA_CB<2>")
	)
	(segment
		(start 417.039552 -279.411684)
		(end 416.270694 -278.642826)
		(width 0.18288)
		(layer "In11.Cu")
		(net "M_H_CPU0_SA_CB<2>")
	)
	(segment
		(start 412.816294 -278.642826)
		(end 412.479744 -278.306276)
		(width 0.18288)
		(layer "In11.Cu")
		(net "M_H_CPU0_SA_CB<2>")
	)
	(segment
		(start 447.062606 -278.455374)
		(end 446.427606 -279.090374)
		(width 0.18288)
		(layer "In11.Cu")
		(net "M_H_CPU0_SA_CB<2>")
	)
	(segment
		(start 375.868946 -262.37438)
		(end 375.854214 -262.383016)
		(width 0.088646)
		(layer "In11.Cu")
		(net "M_H_CPU0_SA_CB<2>")
	)
	(segment
		(start 452.35495 -278.491442)
		(end 450.62013 -278.491442)
		(width 0.18288)
		(layer "In11.Cu")
		(net "M_H_CPU0_SA_CB<2>")
	)
	(segment
		(start 425.464224 -280.190956)
		(end 424.795188 -280.190956)
		(width 0.18288)
		(layer "In11.Cu")
		(net "M_H_CPU0_SA_CB<2>")
	)
	(segment
		(start 422.808146 -280.326338)
		(end 421.822626 -279.340818)
		(width 0.18288)
		(layer "In11.Cu")
		(net "M_H_CPU0_SA_CB<2>")
	)
	(segment
		(start 431.332894 -279.227026)
		(end 427.878494 -279.227026)
		(width 0.18288)
		(layer "In11.Cu")
		(net "M_H_CPU0_SA_CB<2>")
	)
	(segment
		(start 378.688346 -262.37438)
		(end 378.673614 -262.383016)
		(width 0.088646)
		(layer "In11.Cu")
		(net "M_H_CPU0_SA_CB<2>")
	)
	(segment
		(start 412.479744 -278.306276)
		(end 411.120844 -278.306276)
		(width 0.18288)
		(layer "In11.Cu")
		(net "M_H_CPU0_SA_CB<2>")
	)
	(segment
		(start 419.997636 -279.411684)
		(end 417.039552 -279.411684)
		(width 0.18288)
		(layer "In11.Cu")
		(net "M_H_CPU0_SA_CB<2>")
	)
	(segment
		(start 372.477538 -262.116062)
		(end 372.534942 -262.058658)
		(width 0.088646)
		(layer "In11.Cu")
		(net "M_H_CPU0_SA_CB<2>")
	)
	(segment
		(start 410.720794 -277.906226)
		(end 410.120084 -277.906226)
		(width 0.18288)
		(layer "In11.Cu")
		(net "M_H_CPU0_SA_CB<2>")
	)
	(segment
		(start 436.916322 -279.340818)
		(end 434.805836 -279.340818)
		(width 0.18288)
		(layer "In11.Cu")
		(net "M_H_CPU0_SA_CB<2>")
	)
	(segment
		(start 431.551588 -279.44572)
		(end 431.332894 -279.227026)
		(width 0.18288)
		(layer "In11.Cu")
		(net "M_H_CPU0_SA_CB<2>")
	)
	(segment
		(start 408.921966 -277.110698)
		(end 404.843234 -277.110698)
		(width 0.18288)
		(layer "In11.Cu")
		(net "M_H_CPU0_SA_CB<2>")
	)
	(segment
		(start 384.220212 -262.872474)
		(end 384.220212 -262.862568)
		(width 0.088646)
		(layer "In11.Cu")
		(net "M_H_CPU0_SA_CB<2>")
	)
	(segment
		(start 453.156066 -279.292558)
		(end 452.35495 -278.491442)
		(width 0.18288)
		(layer "In11.Cu")
		(net "M_H_CPU0_SA_CB<2>")
	)
	(segment
		(start 404.843234 -277.110698)
		(end 392.951208 -265.218672)
		(width 0.18288)
		(layer "In11.Cu")
		(net "M_H_CPU0_SA_CB<2>")
	)
	(segment
		(start 453.760078 -279.292558)
		(end 453.156066 -279.292558)
		(width 0.18288)
		(layer "In11.Cu")
		(net "M_H_CPU0_SA_CB<2>")
	)
	(segment
		(start 424.795188 -280.190956)
		(end 424.794426 -280.191718)
		(width 0.18288)
		(layer "In11.Cu")
		(net "M_H_CPU0_SA_CB<2>")
	)
	(segment
		(start 424.16095 -280.191718)
		(end 424.02633 -280.326338)
		(width 0.18288)
		(layer "In11.Cu")
		(net "M_H_CPU0_SA_CB<2>")
	)
	(segment
		(start 382.443228 -262.37692)
		(end 382.432814 -262.383016)
		(width 0.088646)
		(layer "In11.Cu")
		(net "M_H_CPU0_SA_CB<2>")
	)
	(segment
		(start 427.878494 -279.227026)
		(end 427.472094 -279.633426)
		(width 0.18288)
		(layer "In11.Cu")
		(net "M_H_CPU0_SA_CB<2>")
	)
	(segment
		(start 381.507746 -262.37438)
		(end 381.493014 -262.383016)
		(width 0.088646)
		(layer "In11.Cu")
		(net "M_H_CPU0_SA_CB<2>")
	)
	(segment
		(start 416.270694 -278.642826)
		(end 412.816294 -278.642826)
		(width 0.18288)
		(layer "In11.Cu")
		(net "M_H_CPU0_SA_CB<2>")
	)
	(segment
		(start 446.427606 -279.090374)
		(end 442.637926 -279.090374)
		(width 0.18288)
		(layer "In11.Cu")
		(net "M_H_CPU0_SA_CB<2>")
	)
	(segment
		(start 377.748546 -262.37438)
		(end 377.733814 -262.383016)
		(width 0.088646)
		(layer "In11.Cu")
		(net "M_H_CPU0_SA_CB<2>")
	)
	(segment
		(start 411.120844 -278.306276)
		(end 410.720794 -277.906226)
		(width 0.18288)
		(layer "In11.Cu")
		(net "M_H_CPU0_SA_CB<2>")
	)
	(segment
		(start 376.808746 -262.37438)
		(end 376.794014 -262.383016)
		(width 0.088646)
		(layer "In11.Cu")
		(net "M_H_CPU0_SA_CB<2>")
	)
	(segment
		(start 373.599964 -262.383016)
		(end 373.58955 -262.37692)
		(width 0.088646)
		(layer "In11.Cu")
		(net "M_H_CPU0_SA_CB<2>")
	)
	(segment
		(start 438.907174 -280.33091)
		(end 437.906414 -280.33091)
		(width 0.18288)
		(layer "In11.Cu")
		(net "M_H_CPU0_SA_CB<2>")
	)
	(segment
		(start 450.62013 -278.491442)
		(end 450.039994 -277.911306)
		(width 0.18288)
		(layer "In11.Cu")
		(net "M_H_CPU0_SA_CB<2>")
	)
	(segment
		(start 448.482212 -278.455374)
		(end 447.062606 -278.455374)
		(width 0.18288)
		(layer "In11.Cu")
		(net "M_H_CPU0_SA_CB<2>")
	)
	(segment
		(start 374.929146 -262.37438)
		(end 374.914668 -262.383016)
		(width 0.088646)
		(layer "In11.Cu")
		(net "M_H_CPU0_SA_CB<2>")
	)
	(segment
		(start 420.068502 -279.340818)
		(end 419.997636 -279.411684)
		(width 0.18288)
		(layer "In11.Cu")
		(net "M_H_CPU0_SA_CB<2>")
	)
	(segment
		(start 384.690112 -263.686544)
		(end 384.690112 -263.668002)
		(width 0.088646)
		(layer "In11.Cu")
		(net "M_H_CPU0_SA_CB<2>")
	)
	(segment
		(start 387.146546 -265.218672)
		(end 386.897626 -264.969752)
		(width 0.088646)
		(layer "In11.Cu")
		(net "M_H_CPU0_SA_CB<2>")
	)
	(segment
		(start 424.02633 -280.326338)
		(end 422.808146 -280.326338)
		(width 0.18288)
		(layer "In11.Cu")
		(net "M_H_CPU0_SA_CB<2>")
	)
	(segment
		(start 455.011282 -278.066754)
		(end 454.985882 -278.066754)
		(width 0.18288)
		(layer "In11.Cu")
		(net "M_H_CPU0_SA_CB<2>")
	)
	(segment
		(start 392.951208 -265.218672)
		(end 387.545072 -265.218672)
		(width 0.18288)
		(layer "In11.Cu")
		(net "M_H_CPU0_SA_CB<2>")
	)
	(segment
		(start 373.984774 -262.37692)
		(end 373.97436 -262.383016)
		(width 0.088646)
		(layer "In11.Cu")
		(net "M_H_CPU0_SA_CB<2>")
	)
	(segment
		(start 386.81787 -264.936732)
		(end 385.989068 -264.10793)
		(width 0.088646)
		(layer "In11.Cu")
		(net "M_H_CPU0_SA_CB<2>")
	)
	(segment
		(start 434.700934 -279.44572)
		(end 431.551588 -279.44572)
		(width 0.18288)
		(layer "In11.Cu")
		(net "M_H_CPU0_SA_CB<2>")
	)
	(segment
		(start 384.407664 -263.196832)
		(end 384.398774 -263.191752)
		(width 0.088646)
		(layer "In11.Cu")
		(net "M_H_CPU0_SA_CB<2>")
	)
	(segment
		(start 442.221874 -279.506426)
		(end 441.748926 -279.506426)
		(width 0.18288)
		(layer "In11.Cu")
		(net "M_H_CPU0_SA_CB<2>")
	)
	(segment
		(start 427.472094 -279.633426)
		(end 426.021754 -279.633426)
		(width 0.18288)
		(layer "In11.Cu")
		(net "M_H_CPU0_SA_CB<2>")
	)
	(segment
		(start 426.021754 -279.633426)
		(end 425.464224 -280.190956)
		(width 0.18288)
		(layer "In11.Cu")
		(net "M_H_CPU0_SA_CB<2>")
	)
	(arc
		(start 379.239018 -262.383016)
		(mid 378.964819 -262.307181)
		(end 378.688346 -262.37438)
		(width 0.088646)
		(layer "In11.Cu")
		(net "M_H_CPU0_SA_CB<2>")
	)
	(arc
		(start 383.937764 -262.383016)
		(mid 383.655062 -262.30724)
		(end 383.37236 -262.383016)
		(width 0.088646)
		(layer "In11.Cu")
		(net "M_H_CPU0_SA_CB<2>")
	)
	(arc
		(start 385.989068 -264.10793)
		(mid 385.63698 -263.934297)
		(end 385.25196 -264.010902)
		(width 0.088646)
		(layer "In11.Cu")
		(net "M_H_CPU0_SA_CB<2>")
	)
	(arc
		(start 372.651528 -262.377936)
		(mid 372.535789 -262.266112)
		(end 372.477538 -262.116062)
		(width 0.088646)
		(layer "In11.Cu")
		(net "M_H_CPU0_SA_CB<2>")
	)
	(arc
		(start 378.299218 -262.383016)
		(mid 378.025019 -262.307181)
		(end 377.748546 -262.37438)
		(width 0.088646)
		(layer "In11.Cu")
		(net "M_H_CPU0_SA_CB<2>")
	)
	(arc
		(start 384.220212 -262.862568)
		(mid 384.142101 -262.585619)
		(end 383.937764 -262.383016)
		(width 0.088646)
		(layer "In11.Cu")
		(net "M_H_CPU0_SA_CB<2>")
	)
	(arc
		(start 378.673614 -262.383016)
		(mid 378.486416 -262.433159)
		(end 378.299218 -262.383016)
		(width 0.088646)
		(layer "In11.Cu")
		(net "M_H_CPU0_SA_CB<2>")
	)
	(arc
		(start 376.419618 -262.383016)
		(mid 376.145419 -262.307181)
		(end 375.868946 -262.37438)
		(width 0.088646)
		(layer "In11.Cu")
		(net "M_H_CPU0_SA_CB<2>")
	)
	(arc
		(start 373.58955 -262.37692)
		(mid 373.311372 -262.307197)
		(end 373.034814 -262.383016)
		(width 0.088646)
		(layer "In11.Cu")
		(net "M_H_CPU0_SA_CB<2>")
	)
	(arc
		(start 373.97436 -262.383016)
		(mid 373.787162 -262.433159)
		(end 373.599964 -262.383016)
		(width 0.088646)
		(layer "In11.Cu")
		(net "M_H_CPU0_SA_CB<2>")
	)
	(arc
		(start 380.55296 -262.383016)
		(mid 380.365762 -262.433159)
		(end 380.178564 -262.383016)
		(width 0.088646)
		(layer "In11.Cu")
		(net "M_H_CPU0_SA_CB<2>")
	)
	(arc
		(start 383.37236 -262.383016)
		(mid 383.185162 -262.433159)
		(end 382.997964 -262.383016)
		(width 0.088646)
		(layer "In11.Cu")
		(net "M_H_CPU0_SA_CB<2>")
	)
	(arc
		(start 377.733814 -262.383016)
		(mid 377.546616 -262.433159)
		(end 377.359418 -262.383016)
		(width 0.088646)
		(layer "In11.Cu")
		(net "M_H_CPU0_SA_CB<2>")
	)
	(arc
		(start 374.540018 -262.383016)
		(mid 374.263205 -262.307146)
		(end 373.984774 -262.37692)
		(width 0.088646)
		(layer "In11.Cu")
		(net "M_H_CPU0_SA_CB<2>")
	)
	(arc
		(start 373.034814 -262.383016)
		(mid 372.847616 -262.433159)
		(end 372.660418 -262.383016)
		(width 0.088646)
		(layer "In11.Cu")
		(net "M_H_CPU0_SA_CB<2>")
	)
	(arc
		(start 385.25196 -264.010902)
		(mid 385.064762 -264.061045)
		(end 384.877564 -264.010902)
		(width 0.088646)
		(layer "In11.Cu")
		(net "M_H_CPU0_SA_CB<2>")
	)
	(arc
		(start 375.854214 -262.383016)
		(mid 375.667016 -262.433159)
		(end 375.479818 -262.383016)
		(width 0.088646)
		(layer "In11.Cu")
		(net "M_H_CPU0_SA_CB<2>")
	)
	(arc
		(start 376.794014 -262.383016)
		(mid 376.606816 -262.433159)
		(end 376.419618 -262.383016)
		(width 0.088646)
		(layer "In11.Cu")
		(net "M_H_CPU0_SA_CB<2>")
	)
	(arc
		(start 374.914668 -262.383016)
		(mid 374.72736 -262.433159)
		(end 374.540018 -262.383016)
		(width 0.088646)
		(layer "In11.Cu")
		(net "M_H_CPU0_SA_CB<2>")
	)
	(arc
		(start 379.613414 -262.383016)
		(mid 379.426216 -262.433159)
		(end 379.239018 -262.383016)
		(width 0.088646)
		(layer "In11.Cu")
		(net "M_H_CPU0_SA_CB<2>")
	)
	(arc
		(start 386.897626 -264.969752)
		(mid 386.854468 -264.961167)
		(end 386.81787 -264.936732)
		(width 0.088646)
		(layer "In11.Cu")
		(net "M_H_CPU0_SA_CB<2>")
	)
	(arc
		(start 381.493014 -262.383016)
		(mid 381.305816 -262.433159)
		(end 381.118618 -262.383016)
		(width 0.088646)
		(layer "In11.Cu")
		(net "M_H_CPU0_SA_CB<2>")
	)
	(arc
		(start 384.398774 -263.191752)
		(mid 384.26786 -263.055392)
		(end 384.220212 -262.872474)
		(width 0.088646)
		(layer "In11.Cu")
		(net "M_H_CPU0_SA_CB<2>")
	)
	(arc
		(start 380.16815 -262.37692)
		(mid 379.889972 -262.307197)
		(end 379.613414 -262.383016)
		(width 0.088646)
		(layer "In11.Cu")
		(net "M_H_CPU0_SA_CB<2>")
	)
	(arc
		(start 382.058418 -262.383016)
		(mid 381.784219 -262.307181)
		(end 381.507746 -262.37438)
		(width 0.088646)
		(layer "In11.Cu")
		(net "M_H_CPU0_SA_CB<2>")
	)
	(arc
		(start 377.359418 -262.383016)
		(mid 377.085219 -262.307181)
		(end 376.808746 -262.37438)
		(width 0.088646)
		(layer "In11.Cu")
		(net "M_H_CPU0_SA_CB<2>")
	)
	(arc
		(start 384.690112 -263.668002)
		(mid 384.60995 -263.395813)
		(end 384.407664 -263.196832)
		(width 0.088646)
		(layer "In11.Cu")
		(net "M_H_CPU0_SA_CB<2>")
	)
	(arc
		(start 382.432814 -262.383016)
		(mid 382.245616 -262.433159)
		(end 382.058418 -262.383016)
		(width 0.088646)
		(layer "In11.Cu")
		(net "M_H_CPU0_SA_CB<2>")
	)
	(arc
		(start 382.997964 -262.383016)
		(mid 382.721405 -262.307273)
		(end 382.443228 -262.37692)
		(width 0.088646)
		(layer "In11.Cu")
		(net "M_H_CPU0_SA_CB<2>")
	)
	(arc
		(start 381.118618 -262.383016)
		(mid 380.841805 -262.307146)
		(end 380.563374 -262.37692)
		(width 0.088646)
		(layer "In11.Cu")
		(net "M_H_CPU0_SA_CB<2>")
	)
	(arc
		(start 375.479818 -262.383016)
		(mid 375.205619 -262.307181)
		(end 374.929146 -262.37438)
		(width 0.088646)
		(layer "In11.Cu")
		(net "M_H_CPU0_SA_CB<2>")
	)
	(arc
		(start 384.868674 -264.005822)
		(mid 384.73776 -263.869462)
		(end 384.690112 -263.686544)
		(width 0.088646)
		(layer "In11.Cu")
		(net "M_H_CPU0_SA_CB<2>")
	)
	(segment
		(start 459.55966 -277.21687)
		(end 457.968096 -277.21687)
		(width 0.20066)
		(layer "F.Cu")
		(net "M_H_CPU0_SA_CB<1>")
	)
	(segment
		(start 457.53655 -276.785324)
		(end 457.126594 -276.785324)
		(width 0.20066)
		(layer "F.Cu")
		(net "M_H_CPU0_SA_CB<1>")
	)
	(segment
		(start 454.260712 -277.465282)
		(end 453.785478 -277.465282)
		(width 0.20066)
		(layer "F.Cu")
		(net "M_H_CPU0_SA_CB<1>")
	)
	(segment
		(start 371.437662 -261.244588)
		(end 371.437662 -261.244842)
		(width 0.20066)
		(layer "F.Cu")
		(net "M_H_CPU0_SA_CB<1>")
	)
	(segment
		(start 371.437916 -261.244334)
		(end 371.437662 -261.244588)
		(width 0.20066)
		(layer "F.Cu")
		(net "M_H_CPU0_SA_CB<1>")
	)
	(segment
		(start 452.016114 -277.216616)
		(end 450.911214 -277.216616)
		(width 0.20066)
		(layer "F.Cu")
		(net "M_H_CPU0_SA_CB<1>")
	)
	(segment
		(start 454.91146 -276.791674)
		(end 454.566782 -276.791674)
		(width 0.20066)
		(layer "F.Cu")
		(net "M_H_CPU0_SA_CB<1>")
	)
	(segment
		(start 457.120244 -276.791674)
		(end 454.931526 -276.791674)
		(width 0.1016)
		(layer "F.Cu")
		(net "M_H_CPU0_SA_CB<1>")
	)
	(segment
		(start 454.448672 -277.277322)
		(end 454.260712 -277.465282)
		(width 0.20066)
		(layer "F.Cu")
		(net "M_H_CPU0_SA_CB<1>")
	)
	(segment
		(start 454.566782 -276.791674)
		(end 454.448672 -276.909784)
		(width 0.20066)
		(layer "F.Cu")
		(net "M_H_CPU0_SA_CB<1>")
	)
	(segment
		(start 453.785478 -277.465282)
		(end 453.536812 -277.216616)
		(width 0.20066)
		(layer "F.Cu")
		(net "M_H_CPU0_SA_CB<1>")
	)
	(segment
		(start 457.968096 -277.21687)
		(end 457.53655 -276.785324)
		(width 0.20066)
		(layer "F.Cu")
		(net "M_H_CPU0_SA_CB<1>")
	)
	(segment
		(start 371.437916 -260.708902)
		(end 371.437916 -261.244334)
		(width 0.20066)
		(layer "F.Cu")
		(net "M_H_CPU0_SA_CB<1>")
	)
	(segment
		(start 453.536812 -277.216616)
		(end 452.016114 -277.216616)
		(width 0.20066)
		(layer "F.Cu")
		(net "M_H_CPU0_SA_CB<1>")
	)
	(segment
		(start 459.559914 -277.216616)
		(end 459.55966 -277.21687)
		(width 0.20066)
		(layer "F.Cu")
		(net "M_H_CPU0_SA_CB<1>")
	)
	(segment
		(start 454.931526 -276.791674)
		(end 454.91146 -276.791674)
		(width 0.101854)
		(layer "F.Cu")
		(net "M_H_CPU0_SA_CB<1>")
	)
	(segment
		(start 457.126594 -276.785324)
		(end 457.120244 -276.791674)
		(width 0.1016)
		(layer "F.Cu")
		(net "M_H_CPU0_SA_CB<1>")
	)
	(segment
		(start 454.448672 -276.909784)
		(end 454.448672 -277.277322)
		(width 0.20066)
		(layer "F.Cu")
		(net "M_H_CPU0_SA_CB<1>")
	)
	(segment
		(start 412.622746 -277.452074)
		(end 412.422594 -277.652226)
		(width 0.18288)
		(layer "In11.Cu")
		(net "M_H_CPU0_SA_CB<1>")
	)
	(segment
		(start 386.379212 -263.751568)
		(end 386.379212 -263.686544)
		(width 0.088646)
		(layer "In11.Cu")
		(net "M_H_CPU0_SA_CB<1>")
	)
	(segment
		(start 393.162028 -264.710672)
		(end 387.545072 -264.710672)
		(width 0.18288)
		(layer "In11.Cu")
		(net "M_H_CPU0_SA_CB<1>")
	)
	(segment
		(start 448.146424 -277.942802)
		(end 446.838832 -277.942802)
		(width 0.18288)
		(layer "In11.Cu")
		(net "M_H_CPU0_SA_CB<1>")
	)
	(segment
		(start 435.26964 -278.490934)
		(end 435.128416 -278.34971)
		(width 0.18288)
		(layer "In11.Cu")
		(net "M_H_CPU0_SA_CB<1>")
	)
	(segment
		(start 423.281094 -279.227026)
		(end 422.842436 -279.227026)
		(width 0.18288)
		(layer "In11.Cu")
		(net "M_H_CPU0_SA_CB<1>")
	)
	(segment
		(start 425.338494 -279.341072)
		(end 424.297094 -279.341072)
		(width 0.18288)
		(layer "In11.Cu")
		(net "M_H_CPU0_SA_CB<1>")
	)
	(segment
		(start 376.808746 -261.742936)
		(end 376.794014 -261.7343)
		(width 0.088646)
		(layer "In11.Cu")
		(net "M_H_CPU0_SA_CB<1>")
	)
	(segment
		(start 429.177704 -277.311866)
		(end 428.984664 -277.504906)
		(width 0.18288)
		(layer "In11.Cu")
		(net "M_H_CPU0_SA_CB<1>")
	)
	(segment
		(start 426.316394 -278.910034)
		(end 425.338494 -279.341072)
		(width 0.18288)
		(layer "In11.Cu")
		(net "M_H_CPU0_SA_CB<1>")
	)
	(segment
		(start 416.408362 -278.031194)
		(end 415.407094 -277.576026)
		(width 0.18288)
		(layer "In11.Cu")
		(net "M_H_CPU0_SA_CB<1>")
	)
	(segment
		(start 418.058346 -278.683212)
		(end 418.058346 -278.45512)
		(width 0.18288)
		(layer "In11.Cu")
		(net "M_H_CPU0_SA_CB<1>")
	)
	(segment
		(start 375.868946 -261.742936)
		(end 375.854214 -261.7343)
		(width 0.088646)
		(layer "In11.Cu")
		(net "M_H_CPU0_SA_CB<1>")
	)
	(segment
		(start 379.623828 -261.740396)
		(end 379.613414 -261.7343)
		(width 0.088646)
		(layer "In11.Cu")
		(net "M_H_CPU0_SA_CB<1>")
	)
	(segment
		(start 427.609 -278.388826)
		(end 426.83684 -278.388826)
		(width 0.18288)
		(layer "In11.Cu")
		(net "M_H_CPU0_SA_CB<1>")
	)
	(segment
		(start 418.058346 -278.45512)
		(end 417.865306 -278.26208)
		(width 0.18288)
		(layer "In11.Cu")
		(net "M_H_CPU0_SA_CB<1>")
	)
	(segment
		(start 450.481446 -277.614634)
		(end 450.131434 -277.264622)
		(width 0.18288)
		(layer "In11.Cu")
		(net "M_H_CPU0_SA_CB<1>")
	)
	(segment
		(start 441.772294 -278.566626)
		(end 441.510928 -278.827992)
		(width 0.18288)
		(layer "In11.Cu")
		(net "M_H_CPU0_SA_CB<1>")
	)
	(segment
		(start 422.842436 -279.227026)
		(end 421.638984 -278.668988)
		(width 0.18288)
		(layer "In11.Cu")
		(net "M_H_CPU0_SA_CB<1>")
	)
	(segment
		(start 443.009782 -278.537162)
		(end 442.836046 -278.363426)
		(width 0.18288)
		(layer "In11.Cu")
		(net "M_H_CPU0_SA_CB<1>")
	)
	(segment
		(start 373.24919 -261.63905)
		(end 373.115332 -261.560564)
		(width 0.088646)
		(layer "In11.Cu")
		(net "M_H_CPU0_SA_CB<1>")
	)
	(segment
		(start 415.082736 -277.576026)
		(end 414.595056 -278.063706)
		(width 0.18288)
		(layer "In11.Cu")
		(net "M_H_CPU0_SA_CB<1>")
	)
	(segment
		(start 428.984664 -277.504906)
		(end 428.984664 -278.52243)
		(width 0.18288)
		(layer "In11.Cu")
		(net "M_H_CPU0_SA_CB<1>")
	)
	(segment
		(start 406.301448 -275.912834)
		(end 404.36419 -275.912834)
		(width 0.18288)
		(layer "In11.Cu")
		(net "M_H_CPU0_SA_CB<1>")
	)
	(segment
		(start 418.954966 -278.26208)
		(end 418.761926 -278.45512)
		(width 0.18288)
		(layer "In11.Cu")
		(net "M_H_CPU0_SA_CB<1>")
	)
	(segment
		(start 430.675034 -278.71547)
		(end 429.881284 -278.71547)
		(width 0.18288)
		(layer "In11.Cu")
		(net "M_H_CPU0_SA_CB<1>")
	)
	(segment
		(start 380.563374 -261.740396)
		(end 380.55296 -261.7343)
		(width 0.088646)
		(layer "In11.Cu")
		(net "M_H_CPU0_SA_CB<1>")
	)
	(segment
		(start 373.984774 -261.740396)
		(end 373.97436 -261.7343)
		(width 0.088646)
		(layer "In11.Cu")
		(net "M_H_CPU0_SA_CB<1>")
	)
	(segment
		(start 408.463496 -275.913088)
		(end 406.301702 -275.913088)
		(width 0.18288)
		(layer "In11.Cu")
		(net "M_H_CPU0_SA_CB<1>")
	)
	(segment
		(start 436.844186 -278.673814)
		(end 436.235094 -278.490934)
		(width 0.18288)
		(layer "In11.Cu")
		(net "M_H_CPU0_SA_CB<1>")
	)
	(segment
		(start 421.071294 -278.490934)
		(end 420.410894 -278.490934)
		(width 0.18288)
		(layer "In11.Cu")
		(net "M_H_CPU0_SA_CB<1>")
	)
	(segment
		(start 426.83684 -278.388826)
		(end 426.316394 -278.910034)
		(width 0.18288)
		(layer "In11.Cu")
		(net "M_H_CPU0_SA_CB<1>")
	)
	(segment
		(start 446.838832 -277.942802)
		(end 446.244472 -278.537162)
		(width 0.18288)
		(layer "In11.Cu")
		(net "M_H_CPU0_SA_CB<1>")
	)
	(segment
		(start 418.568886 -278.876252)
		(end 418.251386 -278.876252)
		(width 0.18288)
		(layer "In11.Cu")
		(net "M_H_CPU0_SA_CB<1>")
	)
	(segment
		(start 418.251386 -278.876252)
		(end 418.058346 -278.683212)
		(width 0.18288)
		(layer "In11.Cu")
		(net "M_H_CPU0_SA_CB<1>")
	)
	(segment
		(start 440.281568 -279.341072)
		(end 438.068974 -279.341072)
		(width 0.18288)
		(layer "In11.Cu")
		(net "M_H_CPU0_SA_CB<1>")
	)
	(segment
		(start 415.407094 -277.576026)
		(end 415.082736 -277.576026)
		(width 0.18288)
		(layer "In11.Cu")
		(net "M_H_CPU0_SA_CB<1>")
	)
	(segment
		(start 372.190264 -261.5692)
		(end 371.808756 -261.34568)
		(width 0.088646)
		(layer "In11.Cu")
		(net "M_H_CPU0_SA_CB<1>")
	)
	(segment
		(start 386.20065 -263.367266)
		(end 386.19176 -263.362186)
		(width 0.088646)
		(layer "In11.Cu")
		(net "M_H_CPU0_SA_CB<1>")
	)
	(segment
		(start 450.911214 -277.37308)
		(end 450.85127 -277.51786)
		(width 0.18288)
		(layer "In11.Cu")
		(net "M_H_CPU0_SA_CB<1>")
	)
	(segment
		(start 410.263594 -276.661626)
		(end 409.212034 -276.661626)
		(width 0.18288)
		(layer "In11.Cu")
		(net "M_H_CPU0_SA_CB<1>")
	)
	(segment
		(start 428.791624 -278.71547)
		(end 427.935644 -278.71547)
		(width 0.18288)
		(layer "In11.Cu")
		(net "M_H_CPU0_SA_CB<1>")
	)
	(segment
		(start 384.499612 -262.068564)
		(end 384.499612 -262.058658)
		(width 0.088646)
		(layer "In11.Cu")
		(net "M_H_CPU0_SA_CB<1>")
	)
	(segment
		(start 413.385508 -277.452074)
		(end 412.622746 -277.452074)
		(width 0.18288)
		(layer "In11.Cu")
		(net "M_H_CPU0_SA_CB<1>")
	)
	(segment
		(start 387.545072 -264.710672)
		(end 387.338316 -264.710672)
		(width 0.088646)
		(layer "In11.Cu")
		(net "M_H_CPU0_SA_CB<1>")
	)
	(segment
		(start 374.929146 -261.742936)
		(end 374.914668 -261.7343)
		(width 0.088646)
		(layer "In11.Cu")
		(net "M_H_CPU0_SA_CB<1>")
	)
	(segment
		(start 384.79095 -262.553196)
		(end 384.78206 -262.548116)
		(width 0.088646)
		(layer "In11.Cu")
		(net "M_H_CPU0_SA_CB<1>")
	)
	(segment
		(start 414.595056 -278.063706)
		(end 413.99714 -278.063706)
		(width 0.18288)
		(layer "In11.Cu")
		(net "M_H_CPU0_SA_CB<1>")
	)
	(segment
		(start 450.131434 -277.264622)
		(end 450.131434 -277.0251)
		(width 0.18288)
		(layer "In11.Cu")
		(net "M_H_CPU0_SA_CB<1>")
	)
	(segment
		(start 450.911214 -277.216616)
		(end 450.911214 -277.37308)
		(width 0.18288)
		(layer "In11.Cu")
		(net "M_H_CPU0_SA_CB<1>")
	)
	(segment
		(start 449.84416 -276.737826)
		(end 449.3514 -276.737826)
		(width 0.18288)
		(layer "In11.Cu")
		(net "M_H_CPU0_SA_CB<1>")
	)
	(segment
		(start 406.301702 -275.913088)
		(end 406.301448 -275.912834)
		(width 0.18288)
		(layer "In11.Cu")
		(net "M_H_CPU0_SA_CB<1>")
	)
	(segment
		(start 384.32105 -261.73938)
		(end 384.31216 -261.7343)
		(width 0.088646)
		(layer "In11.Cu")
		(net "M_H_CPU0_SA_CB<1>")
	)
	(segment
		(start 428.984664 -278.52243)
		(end 428.791624 -278.71547)
		(width 0.18288)
		(layer "In11.Cu")
		(net "M_H_CPU0_SA_CB<1>")
	)
	(segment
		(start 450.754496 -277.614634)
		(end 450.481446 -277.614634)
		(width 0.18288)
		(layer "In11.Cu")
		(net "M_H_CPU0_SA_CB<1>")
	)
	(segment
		(start 418.761926 -278.45512)
		(end 418.761926 -278.683212)
		(width 0.18288)
		(layer "In11.Cu")
		(net "M_H_CPU0_SA_CB<1>")
	)
	(segment
		(start 417.865306 -278.26208)
		(end 416.976052 -278.26208)
		(width 0.18288)
		(layer "In11.Cu")
		(net "M_H_CPU0_SA_CB<1>")
	)
	(segment
		(start 420.410894 -278.490934)
		(end 420.18204 -278.26208)
		(width 0.18288)
		(layer "In11.Cu")
		(net "M_H_CPU0_SA_CB<1>")
	)
	(segment
		(start 449.3514 -276.737826)
		(end 448.146424 -277.942802)
		(width 0.18288)
		(layer "In11.Cu")
		(net "M_H_CPU0_SA_CB<1>")
	)
	(segment
		(start 441.510928 -278.827992)
		(end 440.281568 -279.341072)
		(width 0.18288)
		(layer "In11.Cu")
		(net "M_H_CPU0_SA_CB<1>")
	)
	(segment
		(start 446.244472 -278.537162)
		(end 443.009782 -278.537162)
		(width 0.18288)
		(layer "In11.Cu")
		(net "M_H_CPU0_SA_CB<1>")
	)
	(segment
		(start 442.331094 -278.363426)
		(end 441.772294 -278.566626)
		(width 0.18288)
		(layer "In11.Cu")
		(net "M_H_CPU0_SA_CB<1>")
	)
	(segment
		(start 411.254194 -277.652226)
		(end 410.263594 -276.661626)
		(width 0.18288)
		(layer "In11.Cu")
		(net "M_H_CPU0_SA_CB<1>")
	)
	(segment
		(start 429.881284 -278.71547)
		(end 429.688244 -278.52243)
		(width 0.18288)
		(layer "In11.Cu")
		(net "M_H_CPU0_SA_CB<1>")
	)
	(segment
		(start 418.761926 -278.683212)
		(end 418.568886 -278.876252)
		(width 0.18288)
		(layer "In11.Cu")
		(net "M_H_CPU0_SA_CB<1>")
	)
	(segment
		(start 450.131434 -277.0251)
		(end 449.84416 -276.737826)
		(width 0.18288)
		(layer "In11.Cu")
		(net "M_H_CPU0_SA_CB<1>")
	)
	(segment
		(start 435.128416 -278.34971)
		(end 432.394106 -278.34971)
		(width 0.18288)
		(layer "In11.Cu")
		(net "M_H_CPU0_SA_CB<1>")
	)
	(segment
		(start 421.638984 -278.668988)
		(end 421.071294 -278.490934)
		(width 0.18288)
		(layer "In11.Cu")
		(net "M_H_CPU0_SA_CB<1>")
	)
	(segment
		(start 382.443228 -261.740396)
		(end 382.432814 -261.7343)
		(width 0.088646)
		(layer "In11.Cu")
		(net "M_H_CPU0_SA_CB<1>")
	)
	(segment
		(start 429.495204 -277.311866)
		(end 429.177704 -277.311866)
		(width 0.18288)
		(layer "In11.Cu")
		(net "M_H_CPU0_SA_CB<1>")
	)
	(segment
		(start 381.507746 -261.742936)
		(end 381.493014 -261.7343)
		(width 0.088646)
		(layer "In11.Cu")
		(net "M_H_CPU0_SA_CB<1>")
	)
	(segment
		(start 432.394106 -278.34971)
		(end 430.675034 -278.71547)
		(width 0.18288)
		(layer "In11.Cu")
		(net "M_H_CPU0_SA_CB<1>")
	)
	(segment
		(start 450.85127 -277.51786)
		(end 450.754496 -277.614634)
		(width 0.18288)
		(layer "In11.Cu")
		(net "M_H_CPU0_SA_CB<1>")
	)
	(segment
		(start 387.338316 -264.710672)
		(end 386.379212 -263.751568)
		(width 0.088646)
		(layer "In11.Cu")
		(net "M_H_CPU0_SA_CB<1>")
	)
	(segment
		(start 429.688244 -277.504906)
		(end 429.495204 -277.311866)
		(width 0.18288)
		(layer "In11.Cu")
		(net "M_H_CPU0_SA_CB<1>")
	)
	(segment
		(start 416.976052 -278.26208)
		(end 416.408362 -278.031194)
		(width 0.18288)
		(layer "In11.Cu")
		(net "M_H_CPU0_SA_CB<1>")
	)
	(segment
		(start 409.212034 -276.661626)
		(end 408.463496 -275.913088)
		(width 0.18288)
		(layer "In11.Cu")
		(net "M_H_CPU0_SA_CB<1>")
	)
	(segment
		(start 377.748546 -261.742936)
		(end 377.733814 -261.7343)
		(width 0.088646)
		(layer "In11.Cu")
		(net "M_H_CPU0_SA_CB<1>")
	)
	(segment
		(start 438.068974 -279.341072)
		(end 436.844186 -278.673814)
		(width 0.18288)
		(layer "In11.Cu")
		(net "M_H_CPU0_SA_CB<1>")
	)
	(segment
		(start 429.688244 -278.52243)
		(end 429.688244 -277.504906)
		(width 0.18288)
		(layer "In11.Cu")
		(net "M_H_CPU0_SA_CB<1>")
	)
	(segment
		(start 420.18204 -278.26208)
		(end 418.954966 -278.26208)
		(width 0.18288)
		(layer "In11.Cu")
		(net "M_H_CPU0_SA_CB<1>")
	)
	(segment
		(start 378.688346 -261.742936)
		(end 378.673614 -261.7343)
		(width 0.088646)
		(layer "In11.Cu")
		(net "M_H_CPU0_SA_CB<1>")
	)
	(segment
		(start 424.297094 -279.341072)
		(end 423.281094 -279.227026)
		(width 0.18288)
		(layer "In11.Cu")
		(net "M_H_CPU0_SA_CB<1>")
	)
	(segment
		(start 384.969512 -262.891016)
		(end 384.969512 -262.872474)
		(width 0.088646)
		(layer "In11.Cu")
		(net "M_H_CPU0_SA_CB<1>")
	)
	(segment
		(start 413.99714 -278.063706)
		(end 413.385508 -277.452074)
		(width 0.18288)
		(layer "In11.Cu")
		(net "M_H_CPU0_SA_CB<1>")
	)
	(segment
		(start 427.935644 -278.71547)
		(end 427.609 -278.388826)
		(width 0.18288)
		(layer "In11.Cu")
		(net "M_H_CPU0_SA_CB<1>")
	)
	(segment
		(start 404.36419 -275.912834)
		(end 393.162028 -264.710672)
		(width 0.18288)
		(layer "In11.Cu")
		(net "M_H_CPU0_SA_CB<1>")
	)
	(segment
		(start 442.836046 -278.363426)
		(end 442.331094 -278.363426)
		(width 0.18288)
		(layer "In11.Cu")
		(net "M_H_CPU0_SA_CB<1>")
	)
	(segment
		(start 412.422594 -277.652226)
		(end 411.254194 -277.652226)
		(width 0.18288)
		(layer "In11.Cu")
		(net "M_H_CPU0_SA_CB<1>")
	)
	(segment
		(start 436.235094 -278.490934)
		(end 435.26964 -278.490934)
		(width 0.18288)
		(layer "In11.Cu")
		(net "M_H_CPU0_SA_CB<1>")
	)
	(arc
		(start 385.25196 -263.362186)
		(mid 385.049674 -263.163205)
		(end 384.969512 -262.891016)
		(width 0.088646)
		(layer "In11.Cu")
		(net "M_H_CPU0_SA_CB<1>")
	)
	(arc
		(start 376.419618 -261.7343)
		(mid 376.145419 -261.810135)
		(end 375.868946 -261.742936)
		(width 0.088646)
		(layer "In11.Cu")
		(net "M_H_CPU0_SA_CB<1>")
	)
	(arc
		(start 373.115332 -261.560564)
		(mid 372.838857 -261.493244)
		(end 372.56466 -261.5692)
		(width 0.088646)
		(layer "In11.Cu")
		(net "M_H_CPU0_SA_CB<1>")
	)
	(arc
		(start 382.997964 -261.7343)
		(mid 382.721405 -261.810043)
		(end 382.443228 -261.740396)
		(width 0.088646)
		(layer "In11.Cu")
		(net "M_H_CPU0_SA_CB<1>")
	)
	(arc
		(start 386.19176 -263.362186)
		(mid 386.004562 -263.312043)
		(end 385.817364 -263.362186)
		(width 0.088646)
		(layer "In11.Cu")
		(net "M_H_CPU0_SA_CB<1>")
	)
	(arc
		(start 385.817364 -263.362186)
		(mid 385.534662 -263.437928)
		(end 385.25196 -263.362186)
		(width 0.088646)
		(layer "In11.Cu")
		(net "M_H_CPU0_SA_CB<1>")
	)
	(arc
		(start 377.359418 -261.7343)
		(mid 377.085219 -261.810135)
		(end 376.808746 -261.742936)
		(width 0.088646)
		(layer "In11.Cu")
		(net "M_H_CPU0_SA_CB<1>")
	)
	(arc
		(start 381.493014 -261.7343)
		(mid 381.305816 -261.684157)
		(end 381.118618 -261.7343)
		(width 0.088646)
		(layer "In11.Cu")
		(net "M_H_CPU0_SA_CB<1>")
	)
	(arc
		(start 383.37236 -261.7343)
		(mid 383.185162 -261.684157)
		(end 382.997964 -261.7343)
		(width 0.088646)
		(layer "In11.Cu")
		(net "M_H_CPU0_SA_CB<1>")
	)
	(arc
		(start 379.613414 -261.7343)
		(mid 379.426216 -261.684157)
		(end 379.239018 -261.7343)
		(width 0.088646)
		(layer "In11.Cu")
		(net "M_H_CPU0_SA_CB<1>")
	)
	(arc
		(start 380.178564 -261.7343)
		(mid 379.902005 -261.810043)
		(end 379.623828 -261.740396)
		(width 0.088646)
		(layer "In11.Cu")
		(net "M_H_CPU0_SA_CB<1>")
	)
	(arc
		(start 380.55296 -261.7343)
		(mid 380.365762 -261.684157)
		(end 380.178564 -261.7343)
		(width 0.088646)
		(layer "In11.Cu")
		(net "M_H_CPU0_SA_CB<1>")
	)
	(arc
		(start 374.914668 -261.7343)
		(mid 374.72736 -261.684157)
		(end 374.540018 -261.7343)
		(width 0.088646)
		(layer "In11.Cu")
		(net "M_H_CPU0_SA_CB<1>")
	)
	(arc
		(start 373.599964 -261.7343)
		(mid 373.418228 -261.710061)
		(end 373.24919 -261.63905)
		(width 0.088646)
		(layer "In11.Cu")
		(net "M_H_CPU0_SA_CB<1>")
	)
	(arc
		(start 382.058418 -261.7343)
		(mid 381.784219 -261.810135)
		(end 381.507746 -261.742936)
		(width 0.088646)
		(layer "In11.Cu")
		(net "M_H_CPU0_SA_CB<1>")
	)
	(arc
		(start 376.794014 -261.7343)
		(mid 376.606816 -261.684157)
		(end 376.419618 -261.7343)
		(width 0.088646)
		(layer "In11.Cu")
		(net "M_H_CPU0_SA_CB<1>")
	)
	(arc
		(start 384.969512 -262.872474)
		(mid 384.921833 -262.689574)
		(end 384.79095 -262.553196)
		(width 0.088646)
		(layer "In11.Cu")
		(net "M_H_CPU0_SA_CB<1>")
	)
	(arc
		(start 378.673614 -261.7343)
		(mid 378.486416 -261.684157)
		(end 378.299218 -261.7343)
		(width 0.088646)
		(layer "In11.Cu")
		(net "M_H_CPU0_SA_CB<1>")
	)
	(arc
		(start 383.937764 -261.7343)
		(mid 383.655062 -261.810076)
		(end 383.37236 -261.7343)
		(width 0.088646)
		(layer "In11.Cu")
		(net "M_H_CPU0_SA_CB<1>")
	)
	(arc
		(start 382.432814 -261.7343)
		(mid 382.245616 -261.684157)
		(end 382.058418 -261.7343)
		(width 0.088646)
		(layer "In11.Cu")
		(net "M_H_CPU0_SA_CB<1>")
	)
	(arc
		(start 386.379212 -263.686544)
		(mid 386.331533 -263.503644)
		(end 386.20065 -263.367266)
		(width 0.088646)
		(layer "In11.Cu")
		(net "M_H_CPU0_SA_CB<1>")
	)
	(arc
		(start 381.118618 -261.7343)
		(mid 380.841805 -261.81017)
		(end 380.563374 -261.740396)
		(width 0.088646)
		(layer "In11.Cu")
		(net "M_H_CPU0_SA_CB<1>")
	)
	(arc
		(start 378.299218 -261.7343)
		(mid 378.025019 -261.810135)
		(end 377.748546 -261.742936)
		(width 0.088646)
		(layer "In11.Cu")
		(net "M_H_CPU0_SA_CB<1>")
	)
	(arc
		(start 371.808756 -261.34568)
		(mid 371.629935 -261.270495)
		(end 371.437662 -261.244842)
		(width 0.088646)
		(layer "In11.Cu")
		(net "M_H_CPU0_SA_CB<1>")
	)
	(arc
		(start 375.479818 -261.7343)
		(mid 375.205619 -261.810135)
		(end 374.929146 -261.742936)
		(width 0.088646)
		(layer "In11.Cu")
		(net "M_H_CPU0_SA_CB<1>")
	)
	(arc
		(start 374.540018 -261.7343)
		(mid 374.263205 -261.81017)
		(end 373.984774 -261.740396)
		(width 0.088646)
		(layer "In11.Cu")
		(net "M_H_CPU0_SA_CB<1>")
	)
	(arc
		(start 373.97436 -261.7343)
		(mid 373.787162 -261.684157)
		(end 373.599964 -261.7343)
		(width 0.088646)
		(layer "In11.Cu")
		(net "M_H_CPU0_SA_CB<1>")
	)
	(arc
		(start 384.78206 -262.548116)
		(mid 384.577725 -262.345511)
		(end 384.499612 -262.068564)
		(width 0.088646)
		(layer "In11.Cu")
		(net "M_H_CPU0_SA_CB<1>")
	)
	(arc
		(start 372.56466 -261.5692)
		(mid 372.377462 -261.619343)
		(end 372.190264 -261.5692)
		(width 0.088646)
		(layer "In11.Cu")
		(net "M_H_CPU0_SA_CB<1>")
	)
	(arc
		(start 384.31216 -261.7343)
		(mid 384.124962 -261.684157)
		(end 383.937764 -261.7343)
		(width 0.088646)
		(layer "In11.Cu")
		(net "M_H_CPU0_SA_CB<1>")
	)
	(arc
		(start 384.499612 -262.058658)
		(mid 384.451933 -261.875758)
		(end 384.32105 -261.73938)
		(width 0.088646)
		(layer "In11.Cu")
		(net "M_H_CPU0_SA_CB<1>")
	)
	(arc
		(start 377.733814 -261.7343)
		(mid 377.546616 -261.684157)
		(end 377.359418 -261.7343)
		(width 0.088646)
		(layer "In11.Cu")
		(net "M_H_CPU0_SA_CB<1>")
	)
	(arc
		(start 379.239018 -261.7343)
		(mid 378.964819 -261.810135)
		(end 378.688346 -261.742936)
		(width 0.088646)
		(layer "In11.Cu")
		(net "M_H_CPU0_SA_CB<1>")
	)
	(arc
		(start 375.854214 -261.7343)
		(mid 375.667016 -261.684157)
		(end 375.479818 -261.7343)
		(width 0.088646)
		(layer "In11.Cu")
		(net "M_H_CPU0_SA_CB<1>")
	)
	(segment
		(start 457.53655 -278.485346)
		(end 457.126594 -278.485346)
		(width 0.20066)
		(layer "F.Cu")
		(net "M_H_CPU0_SA_CB<0>")
	)
	(segment
		(start 454.260712 -279.165304)
		(end 453.785478 -279.165304)
		(width 0.20066)
		(layer "F.Cu")
		(net "M_H_CPU0_SA_CB<0>")
	)
	(segment
		(start 452.016114 -278.916638)
		(end 450.911214 -278.916638)
		(width 0.20066)
		(layer "F.Cu")
		(net "M_H_CPU0_SA_CB<0>")
	)
	(segment
		(start 454.566782 -278.491696)
		(end 454.448672 -278.609806)
		(width 0.20066)
		(layer "F.Cu")
		(net "M_H_CPU0_SA_CB<0>")
	)
	(segment
		(start 454.91146 -278.491696)
		(end 454.566782 -278.491696)
		(width 0.20066)
		(layer "F.Cu")
		(net "M_H_CPU0_SA_CB<0>")
	)
	(segment
		(start 457.126594 -278.485346)
		(end 457.120244 -278.491696)
		(width 0.1016)
		(layer "F.Cu")
		(net "M_H_CPU0_SA_CB<0>")
	)
	(segment
		(start 454.448672 -278.609806)
		(end 454.448672 -278.977344)
		(width 0.20066)
		(layer "F.Cu")
		(net "M_H_CPU0_SA_CB<0>")
	)
	(segment
		(start 459.55966 -278.916892)
		(end 457.968096 -278.916892)
		(width 0.20066)
		(layer "F.Cu")
		(net "M_H_CPU0_SA_CB<0>")
	)
	(segment
		(start 453.536812 -278.916638)
		(end 452.016114 -278.916638)
		(width 0.20066)
		(layer "F.Cu")
		(net "M_H_CPU0_SA_CB<0>")
	)
	(segment
		(start 371.907816 -261.522972)
		(end 371.907816 -262.058658)
		(width 0.20066)
		(layer "F.Cu")
		(net "M_H_CPU0_SA_CB<0>")
	)
	(segment
		(start 371.907562 -261.522718)
		(end 371.907816 -261.522972)
		(width 0.20066)
		(layer "F.Cu")
		(net "M_H_CPU0_SA_CB<0>")
	)
	(segment
		(start 454.95845 -278.491696)
		(end 454.91146 -278.491696)
		(width 0.101854)
		(layer "F.Cu")
		(net "M_H_CPU0_SA_CB<0>")
	)
	(segment
		(start 457.120244 -278.491696)
		(end 454.95845 -278.491696)
		(width 0.1016)
		(layer "F.Cu")
		(net "M_H_CPU0_SA_CB<0>")
	)
	(segment
		(start 457.968096 -278.916892)
		(end 457.53655 -278.485346)
		(width 0.20066)
		(layer "F.Cu")
		(net "M_H_CPU0_SA_CB<0>")
	)
	(segment
		(start 454.448672 -278.977344)
		(end 454.260712 -279.165304)
		(width 0.20066)
		(layer "F.Cu")
		(net "M_H_CPU0_SA_CB<0>")
	)
	(segment
		(start 459.559914 -278.916638)
		(end 459.55966 -278.916892)
		(width 0.20066)
		(layer "F.Cu")
		(net "M_H_CPU0_SA_CB<0>")
	)
	(segment
		(start 453.785478 -279.165304)
		(end 453.536812 -278.916638)
		(width 0.20066)
		(layer "F.Cu")
		(net "M_H_CPU0_SA_CB<0>")
	)
	(segment
		(start 392.740388 -265.726672)
		(end 387.545072 -265.726672)
		(width 0.18288)
		(layer "In11.Cu")
		(net "M_H_CPU0_SA_CB<0>")
	)
	(segment
		(start 372.22049 -262.058658)
		(end 371.907816 -262.058658)
		(width 0.088646)
		(layer "In11.Cu")
		(net "M_H_CPU0_SA_CB<0>")
	)
	(segment
		(start 419.019482 -280.116026)
		(end 418.826442 -280.309066)
		(width 0.18288)
		(layer "In11.Cu")
		(net "M_H_CPU0_SA_CB<0>")
	)
	(segment
		(start 443.997842 -280.462736)
		(end 443.038992 -280.462736)
		(width 0.18288)
		(layer "In11.Cu")
		(net "M_H_CPU0_SA_CB<0>")
	)
	(segment
		(start 436.31485 -280.190956)
		(end 435.268624 -280.190956)
		(width 0.18288)
		(layer "In11.Cu")
		(net "M_H_CPU0_SA_CB<0>")
	)
	(segment
		(start 444.190882 -279.804114)
		(end 444.190882 -280.269696)
		(width 0.18288)
		(layer "In11.Cu")
		(net "M_H_CPU0_SA_CB<0>")
	)
	(segment
		(start 418.826442 -280.852372)
		(end 418.633402 -281.045412)
		(width 0.18288)
		(layer "In11.Cu")
		(net "M_H_CPU0_SA_CB<0>")
	)
	(segment
		(start 450.911214 -279.073102)
		(end 450.85127 -279.217882)
		(width 0.18288)
		(layer "In11.Cu")
		(net "M_H_CPU0_SA_CB<0>")
	)
	(segment
		(start 450.481446 -279.314656)
		(end 450.131434 -278.964644)
		(width 0.18288)
		(layer "In11.Cu")
		(net "M_H_CPU0_SA_CB<0>")
	)
	(segment
		(start 425.249594 -281.041094)
		(end 424.436794 -281.041094)
		(width 0.18288)
		(layer "In11.Cu")
		(net "M_H_CPU0_SA_CB<0>")
	)
	(segment
		(start 421.602408 -280.846276)
		(end 421.357806 -280.846276)
		(width 0.18288)
		(layer "In11.Cu")
		(net "M_H_CPU0_SA_CB<0>")
	)
	(segment
		(start 418.826442 -280.309066)
		(end 418.826442 -280.852372)
		(width 0.18288)
		(layer "In11.Cu")
		(net "M_H_CPU0_SA_CB<0>")
	)
	(segment
		(start 422.499028 -281.039316)
		(end 422.499028 -281.693366)
		(width 0.18288)
		(layer "In11.Cu")
		(net "M_H_CPU0_SA_CB<0>")
	)
	(segment
		(start 441.241434 -280.301446)
		(end 440.502548 -281.040332)
		(width 0.18288)
		(layer "In11.Cu")
		(net "M_H_CPU0_SA_CB<0>")
	)
	(segment
		(start 450.131434 -278.725122)
		(end 449.84162 -278.435308)
		(width 0.18288)
		(layer "In11.Cu")
		(net "M_H_CPU0_SA_CB<0>")
	)
	(segment
		(start 446.983866 -279.401016)
		(end 445.922146 -280.462736)
		(width 0.18288)
		(layer "In11.Cu")
		(net "M_H_CPU0_SA_CB<0>")
	)
	(segment
		(start 380.093728 -262.554212)
		(end 380.083314 -262.548116)
		(width 0.088646)
		(layer "In11.Cu")
		(net "M_H_CPU0_SA_CB<0>")
	)
	(segment
		(start 410.440632 -278.759666)
		(end 408.381962 -277.62454)
		(width 0.18288)
		(layer "In11.Cu")
		(net "M_H_CPU0_SA_CB<0>")
	)
	(segment
		(start 378.768864 -262.548116)
		(end 378.754132 -262.556752)
		(width 0.088646)
		(layer "In11.Cu")
		(net "M_H_CPU0_SA_CB<0>")
	)
	(segment
		(start 385.73075 -264.181336)
		(end 385.72186 -264.176256)
		(width 0.088646)
		(layer "In11.Cu")
		(net "M_H_CPU0_SA_CB<0>")
	)
	(segment
		(start 444.190882 -280.269696)
		(end 443.997842 -280.462736)
		(width 0.18288)
		(layer "In11.Cu")
		(net "M_H_CPU0_SA_CB<0>")
	)
	(segment
		(start 375.009664 -262.548116)
		(end 374.994932 -262.556752)
		(width 0.088646)
		(layer "In11.Cu")
		(net "M_H_CPU0_SA_CB<0>")
	)
	(segment
		(start 412.676594 -279.331166)
		(end 412.440374 -279.421082)
		(width 0.18288)
		(layer "In11.Cu")
		(net "M_H_CPU0_SA_CB<0>")
	)
	(segment
		(start 418.122862 -280.309066)
		(end 417.929822 -280.116026)
		(width 0.18288)
		(layer "In11.Cu")
		(net "M_H_CPU0_SA_CB<0>")
	)
	(segment
		(start 424.436794 -281.041094)
		(end 424.241976 -280.846276)
		(width 0.18288)
		(layer "In11.Cu")
		(net "M_H_CPU0_SA_CB<0>")
	)
	(segment
		(start 442.609478 -280.033222)
		(end 442.388498 -280.033222)
		(width 0.18288)
		(layer "In11.Cu")
		(net "M_H_CPU0_SA_CB<0>")
	)
	(segment
		(start 383.85115 -262.553196)
		(end 383.84226 -262.548116)
		(width 0.088646)
		(layer "In11.Cu")
		(net "M_H_CPU0_SA_CB<0>")
	)
	(segment
		(start 415.79419 -279.331166)
		(end 412.676594 -279.331166)
		(width 0.18288)
		(layer "In11.Cu")
		(net "M_H_CPU0_SA_CB<0>")
	)
	(segment
		(start 426.78604 -280.141426)
		(end 426.670724 -280.256742)
		(width 0.18288)
		(layer "In11.Cu")
		(net "M_H_CPU0_SA_CB<0>")
	)
	(segment
		(start 421.357806 -280.846276)
		(end 421.164766 -280.653236)
		(width 0.18288)
		(layer "In11.Cu")
		(net "M_H_CPU0_SA_CB<0>")
	)
	(segment
		(start 432.056794 -280.141426)
		(end 431.115724 -280.323036)
		(width 0.18288)
		(layer "In11.Cu")
		(net "M_H_CPU0_SA_CB<0>")
	)
	(segment
		(start 384.32105 -263.367266)
		(end 384.31216 -263.362186)
		(width 0.088646)
		(layer "In11.Cu")
		(net "M_H_CPU0_SA_CB<0>")
	)
	(segment
		(start 372.286022 -262.12419)
		(end 372.22049 -262.058658)
		(width 0.088646)
		(layer "In11.Cu")
		(net "M_H_CPU0_SA_CB<0>")
	)
	(segment
		(start 440.502548 -281.040332)
		(end 438.924446 -281.040332)
		(width 0.18288)
		(layer "In11.Cu")
		(net "M_H_CPU0_SA_CB<0>")
	)
	(segment
		(start 416.888676 -279.92451)
		(end 415.79419 -279.331166)
		(width 0.18288)
		(layer "In11.Cu")
		(net "M_H_CPU0_SA_CB<0>")
	)
	(segment
		(start 375.949464 -262.548116)
		(end 375.934732 -262.556752)
		(width 0.088646)
		(layer "In11.Cu")
		(net "M_H_CPU0_SA_CB<0>")
	)
	(segment
		(start 421.795448 -281.693366)
		(end 421.795448 -281.039316)
		(width 0.18288)
		(layer "In11.Cu")
		(net "M_H_CPU0_SA_CB<0>")
	)
	(segment
		(start 425.625768 -280.896314)
		(end 425.249594 -281.041094)
		(width 0.18288)
		(layer "In11.Cu")
		(net "M_H_CPU0_SA_CB<0>")
	)
	(segment
		(start 449.84162 -278.435308)
		(end 449.50253 -278.435308)
		(width 0.18288)
		(layer "In11.Cu")
		(net "M_H_CPU0_SA_CB<0>")
	)
	(segment
		(start 379.708918 -262.548116)
		(end 379.698504 -262.554212)
		(width 0.088646)
		(layer "In11.Cu")
		(net "M_H_CPU0_SA_CB<0>")
	)
	(segment
		(start 421.988488 -281.886406)
		(end 421.795448 -281.693366)
		(width 0.18288)
		(layer "In11.Cu")
		(net "M_H_CPU0_SA_CB<0>")
	)
	(segment
		(start 426.670724 -280.256742)
		(end 425.625768 -280.896314)
		(width 0.18288)
		(layer "In11.Cu")
		(net "M_H_CPU0_SA_CB<0>")
	)
	(segment
		(start 450.911214 -278.916638)
		(end 450.911214 -279.073102)
		(width 0.18288)
		(layer "In11.Cu")
		(net "M_H_CPU0_SA_CB<0>")
	)
	(segment
		(start 444.894462 -279.804114)
		(end 444.701422 -279.611074)
		(width 0.18288)
		(layer "In11.Cu")
		(net "M_H_CPU0_SA_CB<0>")
	)
	(segment
		(start 422.692068 -280.846276)
		(end 422.499028 -281.039316)
		(width 0.18288)
		(layer "In11.Cu")
		(net "M_H_CPU0_SA_CB<0>")
	)
	(segment
		(start 377.829064 -262.548116)
		(end 377.814332 -262.556752)
		(width 0.088646)
		(layer "In11.Cu")
		(net "M_H_CPU0_SA_CB<0>")
	)
	(segment
		(start 421.164766 -280.289)
		(end 421.066722 -280.190956)
		(width 0.18288)
		(layer "In11.Cu")
		(net "M_H_CPU0_SA_CB<0>")
	)
	(segment
		(start 382.528064 -262.548116)
		(end 382.513332 -262.556752)
		(width 0.088646)
		(layer "In11.Cu")
		(net "M_H_CPU0_SA_CB<0>")
	)
	(segment
		(start 417.644834 -280.116026)
		(end 416.888676 -279.92451)
		(width 0.18288)
		(layer "In11.Cu")
		(net "M_H_CPU0_SA_CB<0>")
	)
	(segment
		(start 427.728634 -280.267156)
		(end 427.179994 -280.141426)
		(width 0.18288)
		(layer "In11.Cu")
		(net "M_H_CPU0_SA_CB<0>")
	)
	(segment
		(start 435.268624 -280.190956)
		(end 435.219094 -280.141426)
		(width 0.18288)
		(layer "In11.Cu")
		(net "M_H_CPU0_SA_CB<0>")
	)
	(segment
		(start 444.383922 -279.611074)
		(end 444.190882 -279.804114)
		(width 0.18288)
		(layer "In11.Cu")
		(net "M_H_CPU0_SA_CB<0>")
	)
	(segment
		(start 404.638256 -277.62454)
		(end 392.740388 -265.726672)
		(width 0.18288)
		(layer "In11.Cu")
		(net "M_H_CPU0_SA_CB<0>")
	)
	(segment
		(start 444.701422 -279.611074)
		(end 444.383922 -279.611074)
		(width 0.18288)
		(layer "In11.Cu")
		(net "M_H_CPU0_SA_CB<0>")
	)
	(segment
		(start 387.276086 -265.726672)
		(end 385.73075 -264.181336)
		(width 0.088646)
		(layer "In11.Cu")
		(net "M_H_CPU0_SA_CB<0>")
	)
	(segment
		(start 437.056276 -280.439368)
		(end 436.31485 -280.190956)
		(width 0.18288)
		(layer "In11.Cu")
		(net "M_H_CPU0_SA_CB<0>")
	)
	(segment
		(start 422.305988 -281.886406)
		(end 421.988488 -281.886406)
		(width 0.18288)
		(layer "In11.Cu")
		(net "M_H_CPU0_SA_CB<0>")
	)
	(segment
		(start 445.922146 -280.462736)
		(end 445.087502 -280.462736)
		(width 0.18288)
		(layer "In11.Cu")
		(net "M_H_CPU0_SA_CB<0>")
	)
	(segment
		(start 450.131434 -278.964644)
		(end 450.131434 -278.725122)
		(width 0.18288)
		(layer "In11.Cu")
		(net "M_H_CPU0_SA_CB<0>")
	)
	(segment
		(start 381.588264 -262.548116)
		(end 381.573532 -262.556752)
		(width 0.088646)
		(layer "In11.Cu")
		(net "M_H_CPU0_SA_CB<0>")
	)
	(segment
		(start 417.929822 -280.116026)
		(end 417.644834 -280.116026)
		(width 0.18288)
		(layer "In11.Cu")
		(net "M_H_CPU0_SA_CB<0>")
	)
	(segment
		(start 376.889264 -262.548116)
		(end 376.874532 -262.556752)
		(width 0.088646)
		(layer "In11.Cu")
		(net "M_H_CPU0_SA_CB<0>")
	)
	(segment
		(start 450.754496 -279.314656)
		(end 450.481446 -279.314656)
		(width 0.18288)
		(layer "In11.Cu")
		(net "M_H_CPU0_SA_CB<0>")
	)
	(segment
		(start 384.499612 -263.705086)
		(end 384.499612 -263.686544)
		(width 0.088646)
		(layer "In11.Cu")
		(net "M_H_CPU0_SA_CB<0>")
	)
	(segment
		(start 431.115724 -280.323036)
		(end 429.06442 -280.401268)
		(width 0.18288)
		(layer "In11.Cu")
		(net "M_H_CPU0_SA_CB<0>")
	)
	(segment
		(start 442.388498 -280.033222)
		(end 441.241434 -280.301446)
		(width 0.18288)
		(layer "In11.Cu")
		(net "M_H_CPU0_SA_CB<0>")
	)
	(segment
		(start 373.515128 -262.554212)
		(end 373.504714 -262.548116)
		(width 0.088646)
		(layer "In11.Cu")
		(net "M_H_CPU0_SA_CB<0>")
	)
	(segment
		(start 384.029712 -262.891016)
		(end 384.029712 -262.872474)
		(width 0.088646)
		(layer "In11.Cu")
		(net "M_H_CPU0_SA_CB<0>")
	)
	(segment
		(start 421.795448 -281.039316)
		(end 421.602408 -280.846276)
		(width 0.18288)
		(layer "In11.Cu")
		(net "M_H_CPU0_SA_CB<0>")
	)
	(segment
		(start 424.241976 -280.846276)
		(end 422.692068 -280.846276)
		(width 0.18288)
		(layer "In11.Cu")
		(net "M_H_CPU0_SA_CB<0>")
	)
	(segment
		(start 418.315902 -281.045412)
		(end 418.122862 -280.852372)
		(width 0.18288)
		(layer "In11.Cu")
		(net "M_H_CPU0_SA_CB<0>")
	)
	(segment
		(start 443.038992 -280.462736)
		(end 442.609478 -280.033222)
		(width 0.18288)
		(layer "In11.Cu")
		(net "M_H_CPU0_SA_CB<0>")
	)
	(segment
		(start 437.496712 -280.879804)
		(end 437.056276 -280.439368)
		(width 0.18288)
		(layer "In11.Cu")
		(net "M_H_CPU0_SA_CB<0>")
	)
	(segment
		(start 418.633402 -281.045412)
		(end 418.315902 -281.045412)
		(width 0.18288)
		(layer "In11.Cu")
		(net "M_H_CPU0_SA_CB<0>")
	)
	(segment
		(start 449.50253 -278.435308)
		(end 448.536822 -279.401016)
		(width 0.18288)
		(layer "In11.Cu")
		(net "M_H_CPU0_SA_CB<0>")
	)
	(segment
		(start 419.636194 -280.116026)
		(end 419.019482 -280.116026)
		(width 0.18288)
		(layer "In11.Cu")
		(net "M_H_CPU0_SA_CB<0>")
	)
	(segment
		(start 435.219094 -280.141426)
		(end 432.056794 -280.141426)
		(width 0.18288)
		(layer "In11.Cu")
		(net "M_H_CPU0_SA_CB<0>")
	)
	(segment
		(start 418.122862 -280.852372)
		(end 418.122862 -280.309066)
		(width 0.18288)
		(layer "In11.Cu")
		(net "M_H_CPU0_SA_CB<0>")
	)
	(segment
		(start 445.087502 -280.462736)
		(end 444.894462 -280.269696)
		(width 0.18288)
		(layer "In11.Cu")
		(net "M_H_CPU0_SA_CB<0>")
	)
	(segment
		(start 408.381962 -277.62454)
		(end 404.638256 -277.62454)
		(width 0.18288)
		(layer "In11.Cu")
		(net "M_H_CPU0_SA_CB<0>")
	)
	(segment
		(start 438.924446 -281.040332)
		(end 438.763918 -280.879804)
		(width 0.18288)
		(layer "In11.Cu")
		(net "M_H_CPU0_SA_CB<0>")
	)
	(segment
		(start 444.894462 -280.269696)
		(end 444.894462 -279.804114)
		(width 0.18288)
		(layer "In11.Cu")
		(net "M_H_CPU0_SA_CB<0>")
	)
	(segment
		(start 421.164766 -280.653236)
		(end 421.164766 -280.289)
		(width 0.18288)
		(layer "In11.Cu")
		(net "M_H_CPU0_SA_CB<0>")
	)
	(segment
		(start 373.130318 -262.548116)
		(end 373.119904 -262.554212)
		(width 0.088646)
		(layer "In11.Cu")
		(net "M_H_CPU0_SA_CB<0>")
	)
	(segment
		(start 448.536822 -279.401016)
		(end 446.983866 -279.401016)
		(width 0.18288)
		(layer "In11.Cu")
		(net "M_H_CPU0_SA_CB<0>")
	)
	(segment
		(start 438.763918 -280.879804)
		(end 437.496712 -280.879804)
		(width 0.18288)
		(layer "In11.Cu")
		(net "M_H_CPU0_SA_CB<0>")
	)
	(segment
		(start 427.179994 -280.141426)
		(end 426.78604 -280.141426)
		(width 0.18288)
		(layer "In11.Cu")
		(net "M_H_CPU0_SA_CB<0>")
	)
	(segment
		(start 411.905196 -279.389586)
		(end 410.440632 -278.759666)
		(width 0.18288)
		(layer "In11.Cu")
		(net "M_H_CPU0_SA_CB<0>")
	)
	(segment
		(start 412.440374 -279.421082)
		(end 411.905196 -279.389586)
		(width 0.18288)
		(layer "In11.Cu")
		(net "M_H_CPU0_SA_CB<0>")
	)
	(segment
		(start 429.06442 -280.401268)
		(end 427.728634 -280.267156)
		(width 0.18288)
		(layer "In11.Cu")
		(net "M_H_CPU0_SA_CB<0>")
	)
	(segment
		(start 420.245794 -280.190956)
		(end 419.636194 -280.116026)
		(width 0.18288)
		(layer "In11.Cu")
		(net "M_H_CPU0_SA_CB<0>")
	)
	(segment
		(start 387.545072 -265.726672)
		(end 387.276086 -265.726672)
		(width 0.088646)
		(layer "In11.Cu")
		(net "M_H_CPU0_SA_CB<0>")
	)
	(segment
		(start 422.499028 -281.693366)
		(end 422.305988 -281.886406)
		(width 0.18288)
		(layer "In11.Cu")
		(net "M_H_CPU0_SA_CB<0>")
	)
	(segment
		(start 450.85127 -279.217882)
		(end 450.754496 -279.314656)
		(width 0.18288)
		(layer "In11.Cu")
		(net "M_H_CPU0_SA_CB<0>")
	)
	(segment
		(start 421.066722 -280.190956)
		(end 420.245794 -280.190956)
		(width 0.18288)
		(layer "In11.Cu")
		(net "M_H_CPU0_SA_CB<0>")
	)
	(arc
		(start 373.119904 -262.554212)
		(mid 372.841472 -262.624058)
		(end 372.56466 -262.548116)
		(width 0.088646)
		(layer "In11.Cu")
		(net "M_H_CPU0_SA_CB<0>")
	)
	(arc
		(start 382.513332 -262.556752)
		(mid 382.236857 -262.624072)
		(end 381.96266 -262.548116)
		(width 0.088646)
		(layer "In11.Cu")
		(net "M_H_CPU0_SA_CB<0>")
	)
	(arc
		(start 385.72186 -264.176256)
		(mid 385.534662 -264.126113)
		(end 385.347464 -264.176256)
		(width 0.088646)
		(layer "In11.Cu")
		(net "M_H_CPU0_SA_CB<0>")
	)
	(arc
		(start 381.573532 -262.556752)
		(mid 381.297057 -262.624072)
		(end 381.02286 -262.548116)
		(width 0.088646)
		(layer "In11.Cu")
		(net "M_H_CPU0_SA_CB<0>")
	)
	(arc
		(start 376.874532 -262.556752)
		(mid 376.598057 -262.624072)
		(end 376.32386 -262.548116)
		(width 0.088646)
		(layer "In11.Cu")
		(net "M_H_CPU0_SA_CB<0>")
	)
	(arc
		(start 372.56466 -262.548116)
		(mid 372.375147 -262.369151)
		(end 372.286022 -262.12419)
		(width 0.088646)
		(layer "In11.Cu")
		(net "M_H_CPU0_SA_CB<0>")
	)
	(arc
		(start 378.754132 -262.556752)
		(mid 378.477657 -262.624072)
		(end 378.20346 -262.548116)
		(width 0.088646)
		(layer "In11.Cu")
		(net "M_H_CPU0_SA_CB<0>")
	)
	(arc
		(start 383.467864 -262.548116)
		(mid 383.185162 -262.623892)
		(end 382.90246 -262.548116)
		(width 0.088646)
		(layer "In11.Cu")
		(net "M_H_CPU0_SA_CB<0>")
	)
	(arc
		(start 378.20346 -262.548116)
		(mid 378.016262 -262.497973)
		(end 377.829064 -262.548116)
		(width 0.088646)
		(layer "In11.Cu")
		(net "M_H_CPU0_SA_CB<0>")
	)
	(arc
		(start 384.78206 -264.176256)
		(mid 384.579774 -263.977275)
		(end 384.499612 -263.705086)
		(width 0.088646)
		(layer "In11.Cu")
		(net "M_H_CPU0_SA_CB<0>")
	)
	(arc
		(start 384.31216 -263.362186)
		(mid 384.109874 -263.163205)
		(end 384.029712 -262.891016)
		(width 0.088646)
		(layer "In11.Cu")
		(net "M_H_CPU0_SA_CB<0>")
	)
	(arc
		(start 374.994932 -262.556752)
		(mid 374.718457 -262.624072)
		(end 374.44426 -262.548116)
		(width 0.088646)
		(layer "In11.Cu")
		(net "M_H_CPU0_SA_CB<0>")
	)
	(arc
		(start 384.499612 -263.686544)
		(mid 384.451933 -263.503644)
		(end 384.32105 -263.367266)
		(width 0.088646)
		(layer "In11.Cu")
		(net "M_H_CPU0_SA_CB<0>")
	)
	(arc
		(start 384.029712 -262.872474)
		(mid 383.982033 -262.689574)
		(end 383.85115 -262.553196)
		(width 0.088646)
		(layer "In11.Cu")
		(net "M_H_CPU0_SA_CB<0>")
	)
	(arc
		(start 377.814332 -262.556752)
		(mid 377.537857 -262.624072)
		(end 377.26366 -262.548116)
		(width 0.088646)
		(layer "In11.Cu")
		(net "M_H_CPU0_SA_CB<0>")
	)
	(arc
		(start 375.934732 -262.556752)
		(mid 375.658257 -262.624072)
		(end 375.38406 -262.548116)
		(width 0.088646)
		(layer "In11.Cu")
		(net "M_H_CPU0_SA_CB<0>")
	)
	(arc
		(start 375.38406 -262.548116)
		(mid 375.196862 -262.497973)
		(end 375.009664 -262.548116)
		(width 0.088646)
		(layer "In11.Cu")
		(net "M_H_CPU0_SA_CB<0>")
	)
	(arc
		(start 374.069864 -262.548116)
		(mid 373.793305 -262.623859)
		(end 373.515128 -262.554212)
		(width 0.088646)
		(layer "In11.Cu")
		(net "M_H_CPU0_SA_CB<0>")
	)
	(arc
		(start 383.84226 -262.548116)
		(mid 383.655062 -262.497973)
		(end 383.467864 -262.548116)
		(width 0.088646)
		(layer "In11.Cu")
		(net "M_H_CPU0_SA_CB<0>")
	)
	(arc
		(start 381.02286 -262.548116)
		(mid 380.835662 -262.497973)
		(end 380.648464 -262.548116)
		(width 0.088646)
		(layer "In11.Cu")
		(net "M_H_CPU0_SA_CB<0>")
	)
	(arc
		(start 377.26366 -262.548116)
		(mid 377.076462 -262.497973)
		(end 376.889264 -262.548116)
		(width 0.088646)
		(layer "In11.Cu")
		(net "M_H_CPU0_SA_CB<0>")
	)
	(arc
		(start 380.648464 -262.548116)
		(mid 380.371905 -262.623859)
		(end 380.093728 -262.554212)
		(width 0.088646)
		(layer "In11.Cu")
		(net "M_H_CPU0_SA_CB<0>")
	)
	(arc
		(start 373.504714 -262.548116)
		(mid 373.317516 -262.497973)
		(end 373.130318 -262.548116)
		(width 0.088646)
		(layer "In11.Cu")
		(net "M_H_CPU0_SA_CB<0>")
	)
	(arc
		(start 374.44426 -262.548116)
		(mid 374.257062 -262.497973)
		(end 374.069864 -262.548116)
		(width 0.088646)
		(layer "In11.Cu")
		(net "M_H_CPU0_SA_CB<0>")
	)
	(arc
		(start 380.083314 -262.548116)
		(mid 379.896116 -262.497973)
		(end 379.708918 -262.548116)
		(width 0.088646)
		(layer "In11.Cu")
		(net "M_H_CPU0_SA_CB<0>")
	)
	(arc
		(start 379.698504 -262.554212)
		(mid 379.420072 -262.624058)
		(end 379.14326 -262.548116)
		(width 0.088646)
		(layer "In11.Cu")
		(net "M_H_CPU0_SA_CB<0>")
	)
	(arc
		(start 381.96266 -262.548116)
		(mid 381.775462 -262.497973)
		(end 381.588264 -262.548116)
		(width 0.088646)
		(layer "In11.Cu")
		(net "M_H_CPU0_SA_CB<0>")
	)
	(arc
		(start 376.32386 -262.548116)
		(mid 376.136662 -262.497973)
		(end 375.949464 -262.548116)
		(width 0.088646)
		(layer "In11.Cu")
		(net "M_H_CPU0_SA_CB<0>")
	)
	(arc
		(start 382.90246 -262.548116)
		(mid 382.715262 -262.497973)
		(end 382.528064 -262.548116)
		(width 0.088646)
		(layer "In11.Cu")
		(net "M_H_CPU0_SA_CB<0>")
	)
	(arc
		(start 385.347464 -264.176256)
		(mid 385.064762 -264.251998)
		(end 384.78206 -264.176256)
		(width 0.088646)
		(layer "In11.Cu")
		(net "M_H_CPU0_SA_CB<0>")
	)
	(arc
		(start 379.14326 -262.548116)
		(mid 378.956062 -262.497973)
		(end 378.768864 -262.548116)
		(width 0.088646)
		(layer "In11.Cu")
		(net "M_H_CPU0_SA_CB<0>")
	)
	(segment
		(start 453.575928 -260.572504)
		(end 453.901302 -260.572504)
		(width 0.20066)
		(layer "F.Cu")
		(net "M_H_CPU0_SA_CA<6>")
	)
	(segment
		(start 454.92797 -261.49173)
		(end 454.941686 -261.49173)
		(width 0.101854)
		(layer "F.Cu")
		(net "M_H_CPU0_SA_CA<6>")
	)
	(segment
		(start 371.327934 -246.900446)
		(end 371.32768 -246.900192)
		(width 0.20066)
		(layer "F.Cu")
		(net "M_H_CPU0_SA_CA<6>")
	)
	(segment
		(start 459.55966 -261.066534)
		(end 459.559914 -261.066788)
		(width 0.20066)
		(layer "F.Cu")
		(net "M_H_CPU0_SA_CA<6>")
	)
	(segment
		(start 454.820528 -261.49173)
		(end 454.92797 -261.49173)
		(width 0.20066)
		(layer "F.Cu")
		(net "M_H_CPU0_SA_CA<6>")
	)
	(segment
		(start 457.126594 -261.504176)
		(end 457.542646 -261.504176)
		(width 0.20066)
		(layer "F.Cu")
		(net "M_H_CPU0_SA_CA<6>")
	)
	(segment
		(start 457.114148 -261.49173)
		(end 457.126594 -261.504176)
		(width 0.1016)
		(layer "F.Cu")
		(net "M_H_CPU0_SA_CA<6>")
	)
	(segment
		(start 454.941686 -261.49173)
		(end 457.114148 -261.49173)
		(width 0.1016)
		(layer "F.Cu")
		(net "M_H_CPU0_SA_CA<6>")
	)
	(segment
		(start 452.016114 -261.066788)
		(end 453.081644 -261.066788)
		(width 0.20066)
		(layer "F.Cu")
		(net "M_H_CPU0_SA_CA<6>")
	)
	(segment
		(start 371.32768 -246.900192)
		(end 371.32768 -246.364506)
		(width 0.20066)
		(layer "F.Cu")
		(net "M_H_CPU0_SA_CA<6>")
	)
	(segment
		(start 453.081644 -261.066788)
		(end 453.575928 -260.572504)
		(width 0.20066)
		(layer "F.Cu")
		(net "M_H_CPU0_SA_CA<6>")
	)
	(segment
		(start 457.980288 -261.066534)
		(end 459.55966 -261.066534)
		(width 0.20066)
		(layer "F.Cu")
		(net "M_H_CPU0_SA_CA<6>")
	)
	(segment
		(start 453.901302 -260.572504)
		(end 454.820528 -261.49173)
		(width 0.20066)
		(layer "F.Cu")
		(net "M_H_CPU0_SA_CA<6>")
	)
	(segment
		(start 457.542646 -261.504176)
		(end 457.980288 -261.066534)
		(width 0.20066)
		(layer "F.Cu")
		(net "M_H_CPU0_SA_CA<6>")
	)
	(segment
		(start 450.911214 -261.066788)
		(end 452.016114 -261.066788)
		(width 0.20066)
		(layer "F.Cu")
		(net "M_H_CPU0_SA_CA<6>")
	)
	(segment
		(start 441.974478 -259.067554)
		(end 441.199016 -258.292092)
		(width 0.18288)
		(layer "In11.Cu")
		(net "M_H_CPU0_SA_CA<6>")
	)
	(segment
		(start 406.273 -257.323844)
		(end 404.77567 -257.323844)
		(width 0.18288)
		(layer "In11.Cu")
		(net "M_H_CPU0_SA_CA<6>")
	)
	(segment
		(start 371.053868 -248.48693)
		(end 371.044978 -248.48185)
		(width 0.088646)
		(layer "In11.Cu")
		(net "M_H_CPU0_SA_CA<6>")
	)
	(segment
		(start 392.430508 -255.263396)
		(end 389.9535 -252.786388)
		(width 0.18288)
		(layer "In11.Cu")
		(net "M_H_CPU0_SA_CA<6>")
	)
	(segment
		(start 371.484144 -246.093488)
		(end 371.32768 -246.364506)
		(width 0.088646)
		(layer "In11.Cu")
		(net "M_H_CPU0_SA_CA<6>")
	)
	(segment
		(start 395.799564 -255.263396)
		(end 392.430508 -255.263396)
		(width 0.18288)
		(layer "In11.Cu")
		(net "M_H_CPU0_SA_CA<6>")
	)
	(segment
		(start 450.911214 -260.94944)
		(end 450.820282 -260.729984)
		(width 0.18288)
		(layer "In11.Cu")
		(net "M_H_CPU0_SA_CA<6>")
	)
	(segment
		(start 446.682114 -258.940808)
		(end 446.555368 -259.067554)
		(width 0.18288)
		(layer "In11.Cu")
		(net "M_H_CPU0_SA_CA<6>")
	)
	(segment
		(start 371.130068 -246.682768)
		(end 371.140482 -246.688864)
		(width 0.088646)
		(layer "In11.Cu")
		(net "M_H_CPU0_SA_CA<6>")
	)
	(segment
		(start 450.911214 -261.066788)
		(end 450.911214 -260.94944)
		(width 0.18288)
		(layer "In11.Cu")
		(net "M_H_CPU0_SA_CA<6>")
	)
	(segment
		(start 371.523768 -249.300746)
		(end 371.514878 -249.295666)
		(width 0.088646)
		(layer "In11.Cu")
		(net "M_H_CPU0_SA_CA<6>")
	)
	(segment
		(start 371.514878 -246.688864)
		(end 371.523768 -246.683784)
		(width 0.088646)
		(layer "In11.Cu")
		(net "M_H_CPU0_SA_CA<6>")
	)
	(segment
		(start 408.482038 -258.085844)
		(end 406.273 -257.323844)
		(width 0.18288)
		(layer "In11.Cu")
		(net "M_H_CPU0_SA_CA<6>")
	)
	(segment
		(start 372.195344 -252.786388)
		(end 371.70233 -252.293374)
		(width 0.088646)
		(layer "In11.Cu")
		(net "M_H_CPU0_SA_CA<6>")
	)
	(segment
		(start 370.292884 -247.193816)
		(end 370.292884 -247.168416)
		(width 0.088646)
		(layer "In11.Cu")
		(net "M_H_CPU0_SA_CA<6>")
	)
	(segment
		(start 372.508526 -252.786388)
		(end 372.195344 -252.786388)
		(width 0.088646)
		(layer "In11.Cu")
		(net "M_H_CPU0_SA_CA<6>")
	)
	(segment
		(start 402.698966 -255.24714)
		(end 400.636486 -254.392176)
		(width 0.18288)
		(layer "In11.Cu")
		(net "M_H_CPU0_SA_CA<6>")
	)
	(segment
		(start 370.76253 -248.01068)
		(end 370.76253 -247.992138)
		(width 0.088646)
		(layer "In11.Cu")
		(net "M_H_CPU0_SA_CA<6>")
	)
	(segment
		(start 450.820282 -260.729984)
		(end 449.786756 -259.696458)
		(width 0.18288)
		(layer "In11.Cu")
		(net "M_H_CPU0_SA_CA<6>")
	)
	(segment
		(start 400.636486 -254.392176)
		(end 396.670784 -254.392176)
		(width 0.18288)
		(layer "In11.Cu")
		(net "M_H_CPU0_SA_CA<6>")
	)
	(segment
		(start 440.700922 -258.085844)
		(end 408.482038 -258.085844)
		(width 0.18288)
		(layer "In11.Cu")
		(net "M_H_CPU0_SA_CA<6>")
	)
	(segment
		(start 449.786756 -259.696458)
		(end 447.962528 -258.940808)
		(width 0.18288)
		(layer "In11.Cu")
		(net "M_H_CPU0_SA_CA<6>")
	)
	(segment
		(start 371.70233 -252.293374)
		(end 371.70233 -249.620024)
		(width 0.088646)
		(layer "In11.Cu")
		(net "M_H_CPU0_SA_CA<6>")
	)
	(segment
		(start 389.9535 -252.786388)
		(end 372.508526 -252.786388)
		(width 0.18288)
		(layer "In11.Cu")
		(net "M_H_CPU0_SA_CA<6>")
	)
	(segment
		(start 441.199016 -258.292092)
		(end 440.700922 -258.085844)
		(width 0.18288)
		(layer "In11.Cu")
		(net "M_H_CPU0_SA_CA<6>")
	)
	(segment
		(start 396.670784 -254.392176)
		(end 395.799564 -255.263396)
		(width 0.18288)
		(layer "In11.Cu")
		(net "M_H_CPU0_SA_CA<6>")
	)
	(segment
		(start 371.562376 -246.07266)
		(end 371.484144 -246.093488)
		(width 0.088646)
		(layer "In11.Cu")
		(net "M_H_CPU0_SA_CA<6>")
	)
	(segment
		(start 370.583968 -247.67286)
		(end 370.575078 -247.66778)
		(width 0.088646)
		(layer "In11.Cu")
		(net "M_H_CPU0_SA_CA<6>")
	)
	(segment
		(start 371.514878 -249.295666)
		(end 371.508782 -249.29211)
		(width 0.088646)
		(layer "In11.Cu")
		(net "M_H_CPU0_SA_CA<6>")
	)
	(segment
		(start 446.555368 -259.067554)
		(end 441.974478 -259.067554)
		(width 0.18288)
		(layer "In11.Cu")
		(net "M_H_CPU0_SA_CA<6>")
	)
	(segment
		(start 447.962528 -258.940808)
		(end 446.682114 -258.940808)
		(width 0.18288)
		(layer "In11.Cu")
		(net "M_H_CPU0_SA_CA<6>")
	)
	(segment
		(start 404.77567 -257.323844)
		(end 402.698966 -255.24714)
		(width 0.18288)
		(layer "In11.Cu")
		(net "M_H_CPU0_SA_CA<6>")
	)
	(arc
		(start 370.575078 -247.66778)
		(mid 370.372255 -247.467549)
		(end 370.292884 -247.193816)
		(width 0.088646)
		(layer "In11.Cu")
		(net "M_H_CPU0_SA_CA<6>")
	)
	(arc
		(start 371.70233 -246.364506)
		(mid 371.66547 -246.202709)
		(end 371.562376 -246.07266)
		(width 0.088646)
		(layer "In11.Cu")
		(net "M_H_CPU0_SA_CA<6>")
	)
	(arc
		(start 371.23243 -248.806208)
		(mid 371.184751 -248.623308)
		(end 371.053868 -248.48693)
		(width 0.088646)
		(layer "In11.Cu")
		(net "M_H_CPU0_SA_CA<6>")
	)
	(arc
		(start 370.76253 -247.992138)
		(mid 370.714851 -247.809238)
		(end 370.583968 -247.67286)
		(width 0.088646)
		(layer "In11.Cu")
		(net "M_H_CPU0_SA_CA<6>")
	)
	(arc
		(start 370.292884 -247.168416)
		(mid 370.370995 -246.891467)
		(end 370.575332 -246.688864)
		(width 0.088646)
		(layer "In11.Cu")
		(net "M_H_CPU0_SA_CA<6>")
	)
	(arc
		(start 370.575332 -246.688864)
		(mid 370.851891 -246.613121)
		(end 371.130068 -246.682768)
		(width 0.088646)
		(layer "In11.Cu")
		(net "M_H_CPU0_SA_CA<6>")
	)
	(arc
		(start 371.508782 -249.29211)
		(mid 371.306369 -249.085697)
		(end 371.23243 -248.806208)
		(width 0.088646)
		(layer "In11.Cu")
		(net "M_H_CPU0_SA_CA<6>")
	)
	(arc
		(start 371.70233 -249.620024)
		(mid 371.654651 -249.437124)
		(end 371.523768 -249.300746)
		(width 0.088646)
		(layer "In11.Cu")
		(net "M_H_CPU0_SA_CA<6>")
	)
	(arc
		(start 371.044978 -248.48185)
		(mid 370.842692 -248.282869)
		(end 370.76253 -248.01068)
		(width 0.088646)
		(layer "In11.Cu")
		(net "M_H_CPU0_SA_CA<6>")
	)
	(arc
		(start 371.523768 -246.683784)
		(mid 371.654682 -246.547424)
		(end 371.70233 -246.364506)
		(width 0.088646)
		(layer "In11.Cu")
		(net "M_H_CPU0_SA_CA<6>")
	)
	(arc
		(start 371.140482 -246.688864)
		(mid 371.32768 -246.739007)
		(end 371.514878 -246.688864)
		(width 0.088646)
		(layer "In11.Cu")
		(net "M_H_CPU0_SA_CA<6>")
	)
	(segment
		(start 462.54543 -261.916672)
		(end 463.659982 -261.916672)
		(width 0.20066)
		(layer "F.Cu")
		(net "M_H_CPU0_SA_CA<5>")
	)
	(segment
		(start 457.751942 -261.916672)
		(end 458.187552 -262.352282)
		(width 0.20066)
		(layer "F.Cu")
		(net "M_H_CPU0_SA_CA<5>")
	)
	(segment
		(start 455.011282 -261.916672)
		(end 456.116182 -261.916672)
		(width 0.20066)
		(layer "F.Cu")
		(net "M_H_CPU0_SA_CA<5>")
	)
	(segment
		(start 460.844392 -262.34898)
		(end 461.709262 -261.48411)
		(width 0.20066)
		(layer "F.Cu")
		(net "M_H_CPU0_SA_CA<5>")
	)
	(segment
		(start 460.56296 -262.341614)
		(end 460.570326 -262.34898)
		(width 0.1016)
		(layer "F.Cu")
		(net "M_H_CPU0_SA_CA<5>")
	)
	(segment
		(start 458.55382 -262.341614)
		(end 460.56296 -262.341614)
		(width 0.1016)
		(layer "F.Cu")
		(net "M_H_CPU0_SA_CA<5>")
	)
	(segment
		(start 462.112868 -261.48411)
		(end 462.54543 -261.916672)
		(width 0.20066)
		(layer "F.Cu")
		(net "M_H_CPU0_SA_CA<5>")
	)
	(segment
		(start 458.543152 -262.352282)
		(end 458.55382 -262.341614)
		(width 0.1016)
		(layer "F.Cu")
		(net "M_H_CPU0_SA_CA<5>")
	)
	(segment
		(start 458.538326 -262.352282)
		(end 458.543152 -262.352282)
		(width 0.101854)
		(layer "F.Cu")
		(net "M_H_CPU0_SA_CA<5>")
	)
	(segment
		(start 461.709262 -261.48411)
		(end 462.112868 -261.48411)
		(width 0.20066)
		(layer "F.Cu")
		(net "M_H_CPU0_SA_CA<5>")
	)
	(segment
		(start 456.116182 -261.916672)
		(end 457.751942 -261.916672)
		(width 0.20066)
		(layer "F.Cu")
		(net "M_H_CPU0_SA_CA<5>")
	)
	(segment
		(start 458.187552 -262.352282)
		(end 458.538326 -262.352282)
		(width 0.20066)
		(layer "F.Cu")
		(net "M_H_CPU0_SA_CA<5>")
	)
	(segment
		(start 372.847362 -253.919482)
		(end 372.847616 -253.919736)
		(width 0.20066)
		(layer "F.Cu")
		(net "M_H_CPU0_SA_CA<5>")
	)
	(segment
		(start 372.847362 -253.383796)
		(end 372.847362 -253.919482)
		(width 0.20066)
		(layer "F.Cu")
		(net "M_H_CPU0_SA_CA<5>")
	)
	(segment
		(start 460.570326 -262.34898)
		(end 460.844392 -262.34898)
		(width 0.20066)
		(layer "F.Cu")
		(net "M_H_CPU0_SA_CA<5>")
	)
	(segment
		(start 436.747666 -259.119878)
		(end 436.56885 -258.941062)
		(width 0.18288)
		(layer "In11.Cu")
		(net "M_H_CPU0_SA_CA<5>")
	)
	(segment
		(start 420.687246 -258.940808)
		(end 420.686484 -258.94157)
		(width 0.18288)
		(layer "In11.Cu")
		(net "M_H_CPU0_SA_CA<5>")
	)
	(segment
		(start 445.960754 -259.73913)
		(end 441.48629 -259.73913)
		(width 0.18288)
		(layer "In11.Cu")
		(net "M_H_CPU0_SA_CA<5>")
	)
	(segment
		(start 424.792648 -258.940808)
		(end 424.791886 -258.94157)
		(width 0.18288)
		(layer "In11.Cu")
		(net "M_H_CPU0_SA_CA<5>")
	)
	(segment
		(start 404.603712 -257.950462)
		(end 402.298154 -255.663954)
		(width 0.18288)
		(layer "In11.Cu")
		(net "M_H_CPU0_SA_CA<5>")
	)
	(segment
		(start 423.648378 -258.94157)
		(end 423.51325 -259.076698)
		(width 0.18288)
		(layer "In11.Cu")
		(net "M_H_CPU0_SA_CA<5>")
	)
	(segment
		(start 440.688222 -258.941062)
		(end 439.426858 -258.941062)
		(width 0.18288)
		(layer "In11.Cu")
		(net "M_H_CPU0_SA_CA<5>")
	)
	(segment
		(start 407.61285 -259.088382)
		(end 406.682956 -258.158488)
		(width 0.18288)
		(layer "In11.Cu")
		(net "M_H_CPU0_SA_CA<5>")
	)
	(segment
		(start 441.48629 -259.73913)
		(end 440.688222 -258.941062)
		(width 0.18288)
		(layer "In11.Cu")
		(net "M_H_CPU0_SA_CA<5>")
	)
	(segment
		(start 446.860422 -260.638798)
		(end 445.960754 -259.73913)
		(width 0.18288)
		(layer "In11.Cu")
		(net "M_H_CPU0_SA_CA<5>")
	)
	(segment
		(start 449.91909 -260.638798)
		(end 446.860422 -260.638798)
		(width 0.18288)
		(layer "In11.Cu")
		(net "M_H_CPU0_SA_CA<5>")
	)
	(segment
		(start 439.426858 -258.941062)
		(end 439.248042 -259.119878)
		(width 0.18288)
		(layer "In11.Cu")
		(net "M_H_CPU0_SA_CA<5>")
	)
	(segment
		(start 450.829426 -261.492492)
		(end 450.827902 -261.490968)
		(width 0.18288)
		(layer "In11.Cu")
		(net "M_H_CPU0_SA_CA<5>")
	)
	(segment
		(start 420.1287 -258.94157)
		(end 419.981888 -259.088382)
		(width 0.18288)
		(layer "In11.Cu")
		(net "M_H_CPU0_SA_CA<5>")
	)
	(segment
		(start 431.675794 -258.941062)
		(end 431.45075 -259.166106)
		(width 0.18288)
		(layer "In11.Cu")
		(net "M_H_CPU0_SA_CA<5>")
	)
	(segment
		(start 433.055522 -258.941062)
		(end 431.675794 -258.941062)
		(width 0.18288)
		(layer "In11.Cu")
		(net "M_H_CPU0_SA_CA<5>")
	)
	(segment
		(start 426.225716 -258.940808)
		(end 424.792648 -258.940808)
		(width 0.18288)
		(layer "In11.Cu")
		(net "M_H_CPU0_SA_CA<5>")
	)
	(segment
		(start 396.234158 -255.616964)
		(end 392.288776 -255.616964)
		(width 0.18288)
		(layer "In11.Cu")
		(net "M_H_CPU0_SA_CA<5>")
	)
	(segment
		(start 421.549322 -258.940808)
		(end 420.687246 -258.940808)
		(width 0.18288)
		(layer "In11.Cu")
		(net "M_H_CPU0_SA_CA<5>")
	)
	(segment
		(start 435.287166 -258.941062)
		(end 435.115462 -259.112766)
		(width 0.18288)
		(layer "In11.Cu")
		(net "M_H_CPU0_SA_CA<5>")
	)
	(segment
		(start 373.322596 -253.138686)
		(end 372.847616 -253.614174)
		(width 0.18288)
		(layer "In11.Cu")
		(net "M_H_CPU0_SA_CA<5>")
	)
	(segment
		(start 424.791886 -258.94157)
		(end 423.648378 -258.94157)
		(width 0.18288)
		(layer "In11.Cu")
		(net "M_H_CPU0_SA_CA<5>")
	)
	(segment
		(start 439.248042 -259.119878)
		(end 436.747666 -259.119878)
		(width 0.18288)
		(layer "In11.Cu")
		(net "M_H_CPU0_SA_CA<5>")
	)
	(segment
		(start 406.301702 -257.950462)
		(end 404.603712 -257.950462)
		(width 0.18288)
		(layer "In11.Cu")
		(net "M_H_CPU0_SA_CA<5>")
	)
	(segment
		(start 450.55536 -261.490968)
		(end 450.226684 -261.162292)
		(width 0.18288)
		(layer "In11.Cu")
		(net "M_H_CPU0_SA_CA<5>")
	)
	(segment
		(start 419.981888 -259.088382)
		(end 407.61285 -259.088382)
		(width 0.18288)
		(layer "In11.Cu")
		(net "M_H_CPU0_SA_CA<5>")
	)
	(segment
		(start 402.298154 -255.663954)
		(end 400.480022 -254.914146)
		(width 0.18288)
		(layer "In11.Cu")
		(net "M_H_CPU0_SA_CA<5>")
	)
	(segment
		(start 372.847616 -253.614174)
		(end 372.847616 -253.919736)
		(width 0.18288)
		(layer "In11.Cu")
		(net "M_H_CPU0_SA_CA<5>")
	)
	(segment
		(start 426.451014 -259.166106)
		(end 426.225716 -258.940808)
		(width 0.18288)
		(layer "In11.Cu")
		(net "M_H_CPU0_SA_CA<5>")
	)
	(segment
		(start 433.227226 -259.112766)
		(end 433.055522 -258.941062)
		(width 0.18288)
		(layer "In11.Cu")
		(net "M_H_CPU0_SA_CA<5>")
	)
	(segment
		(start 451.55866 -261.142226)
		(end 451.208394 -261.492492)
		(width 0.18288)
		(layer "In11.Cu")
		(net "M_H_CPU0_SA_CA<5>")
	)
	(segment
		(start 392.288776 -255.616964)
		(end 389.810498 -253.138686)
		(width 0.18288)
		(layer "In11.Cu")
		(net "M_H_CPU0_SA_CA<5>")
	)
	(segment
		(start 450.226684 -260.946392)
		(end 449.91909 -260.638798)
		(width 0.18288)
		(layer "In11.Cu")
		(net "M_H_CPU0_SA_CA<5>")
	)
	(segment
		(start 451.208394 -261.492492)
		(end 450.829426 -261.492492)
		(width 0.18288)
		(layer "In11.Cu")
		(net "M_H_CPU0_SA_CA<5>")
	)
	(segment
		(start 454.23582 -261.142226)
		(end 451.55866 -261.142226)
		(width 0.18288)
		(layer "In11.Cu")
		(net "M_H_CPU0_SA_CA<5>")
	)
	(segment
		(start 396.936976 -254.914146)
		(end 396.234158 -255.616964)
		(width 0.18288)
		(layer "In11.Cu")
		(net "M_H_CPU0_SA_CA<5>")
	)
	(segment
		(start 421.685212 -259.076698)
		(end 421.549322 -258.940808)
		(width 0.18288)
		(layer "In11.Cu")
		(net "M_H_CPU0_SA_CA<5>")
	)
	(segment
		(start 406.682956 -258.158488)
		(end 406.301702 -257.950462)
		(width 0.18288)
		(layer "In11.Cu")
		(net "M_H_CPU0_SA_CA<5>")
	)
	(segment
		(start 450.226684 -261.162292)
		(end 450.226684 -260.946392)
		(width 0.18288)
		(layer "In11.Cu")
		(net "M_H_CPU0_SA_CA<5>")
	)
	(segment
		(start 400.480022 -254.914146)
		(end 396.936976 -254.914146)
		(width 0.18288)
		(layer "In11.Cu")
		(net "M_H_CPU0_SA_CA<5>")
	)
	(segment
		(start 420.686484 -258.94157)
		(end 420.1287 -258.94157)
		(width 0.18288)
		(layer "In11.Cu")
		(net "M_H_CPU0_SA_CA<5>")
	)
	(segment
		(start 431.45075 -259.166106)
		(end 426.451014 -259.166106)
		(width 0.18288)
		(layer "In11.Cu")
		(net "M_H_CPU0_SA_CA<5>")
	)
	(segment
		(start 423.51325 -259.076698)
		(end 421.685212 -259.076698)
		(width 0.18288)
		(layer "In11.Cu")
		(net "M_H_CPU0_SA_CA<5>")
	)
	(segment
		(start 436.56885 -258.941062)
		(end 435.287166 -258.941062)
		(width 0.18288)
		(layer "In11.Cu")
		(net "M_H_CPU0_SA_CA<5>")
	)
	(segment
		(start 455.011282 -261.916672)
		(end 454.23582 -261.142226)
		(width 0.18288)
		(layer "In11.Cu")
		(net "M_H_CPU0_SA_CA<5>")
	)
	(segment
		(start 389.810498 -253.138686)
		(end 373.322596 -253.138686)
		(width 0.18288)
		(layer "In11.Cu")
		(net "M_H_CPU0_SA_CA<5>")
	)
	(segment
		(start 435.115462 -259.112766)
		(end 433.227226 -259.112766)
		(width 0.18288)
		(layer "In11.Cu")
		(net "M_H_CPU0_SA_CA<5>")
	)
	(segment
		(start 450.827902 -261.490968)
		(end 450.55536 -261.490968)
		(width 0.18288)
		(layer "In11.Cu")
		(net "M_H_CPU0_SA_CA<5>")
	)
	(segment
		(start 453.575928 -262.272526)
		(end 453.901302 -262.272526)
		(width 0.20066)
		(layer "F.Cu")
		(net "M_H_CPU0_SA_CA<4>")
	)
	(segment
		(start 454.92797 -263.191752)
		(end 454.941686 -263.191752)
		(width 0.101854)
		(layer "F.Cu")
		(net "M_H_CPU0_SA_CA<4>")
	)
	(segment
		(start 457.126594 -263.204198)
		(end 457.542646 -263.204198)
		(width 0.20066)
		(layer "F.Cu")
		(net "M_H_CPU0_SA_CA<4>")
	)
	(segment
		(start 454.820528 -263.191752)
		(end 454.92797 -263.191752)
		(width 0.20066)
		(layer "F.Cu")
		(net "M_H_CPU0_SA_CA<4>")
	)
	(segment
		(start 453.901302 -262.272526)
		(end 454.820528 -263.191752)
		(width 0.20066)
		(layer "F.Cu")
		(net "M_H_CPU0_SA_CA<4>")
	)
	(segment
		(start 457.114148 -263.191752)
		(end 457.126594 -263.204198)
		(width 0.1016)
		(layer "F.Cu")
		(net "M_H_CPU0_SA_CA<4>")
	)
	(segment
		(start 457.542646 -263.204198)
		(end 457.980288 -262.766556)
		(width 0.20066)
		(layer "F.Cu")
		(net "M_H_CPU0_SA_CA<4>")
	)
	(segment
		(start 454.941686 -263.191752)
		(end 457.114148 -263.191752)
		(width 0.1016)
		(layer "F.Cu")
		(net "M_H_CPU0_SA_CA<4>")
	)
	(segment
		(start 450.911214 -262.76681)
		(end 452.016114 -262.76681)
		(width 0.20066)
		(layer "F.Cu")
		(net "M_H_CPU0_SA_CA<4>")
	)
	(segment
		(start 371.907562 -253.919482)
		(end 371.907816 -253.919736)
		(width 0.20066)
		(layer "F.Cu")
		(net "M_H_CPU0_SA_CA<4>")
	)
	(segment
		(start 453.081644 -262.76681)
		(end 453.575928 -262.272526)
		(width 0.20066)
		(layer "F.Cu")
		(net "M_H_CPU0_SA_CA<4>")
	)
	(segment
		(start 459.55966 -262.766556)
		(end 459.559914 -262.76681)
		(width 0.20066)
		(layer "F.Cu")
		(net "M_H_CPU0_SA_CA<4>")
	)
	(segment
		(start 457.980288 -262.766556)
		(end 459.55966 -262.766556)
		(width 0.20066)
		(layer "F.Cu")
		(net "M_H_CPU0_SA_CA<4>")
	)
	(segment
		(start 371.907562 -253.383796)
		(end 371.907562 -253.919482)
		(width 0.20066)
		(layer "F.Cu")
		(net "M_H_CPU0_SA_CA<4>")
	)
	(segment
		(start 452.016114 -262.76681)
		(end 453.081644 -262.76681)
		(width 0.20066)
		(layer "F.Cu")
		(net "M_H_CPU0_SA_CA<4>")
	)
	(segment
		(start 425.543472 -260.531102)
		(end 425.168568 -260.531102)
		(width 0.18288)
		(layer "In11.Cu")
		(net "M_H_CPU0_SA_CA<4>")
	)
	(segment
		(start 446.2526 -260.809486)
		(end 442.951362 -260.809486)
		(width 0.18288)
		(layer "In11.Cu")
		(net "M_H_CPU0_SA_CA<4>")
	)
	(segment
		(start 429.596804 -259.777484)
		(end 429.279304 -259.777484)
		(width 0.18288)
		(layer "In11.Cu")
		(net "M_H_CPU0_SA_CA<4>")
	)
	(segment
		(start 421.741092 -259.61594)
		(end 421.566086 -259.790946)
		(width 0.18288)
		(layer "In11.Cu")
		(net "M_H_CPU0_SA_CA<4>")
	)
	(segment
		(start 446.961006 -261.517892)
		(end 446.2526 -260.809486)
		(width 0.18288)
		(layer "In11.Cu")
		(net "M_H_CPU0_SA_CA<4>")
	)
	(segment
		(start 373.366792 -253.83363)
		(end 373.366792 -254.201676)
		(width 0.088646)
		(layer "In11.Cu")
		(net "M_H_CPU0_SA_CA<4>")
	)
	(segment
		(start 373.255032 -254.313436)
		(end 372.360952 -254.313436)
		(width 0.088646)
		(layer "In11.Cu")
		(net "M_H_CPU0_SA_CA<4>")
	)
	(segment
		(start 429.279304 -259.777484)
		(end 429.086264 -259.970524)
		(width 0.18288)
		(layer "In11.Cu")
		(net "M_H_CPU0_SA_CA<4>")
	)
	(segment
		(start 425.736512 -260.338062)
		(end 425.543472 -260.531102)
		(width 0.18288)
		(layer "In11.Cu")
		(net "M_H_CPU0_SA_CA<4>")
	)
	(segment
		(start 400.369024 -255.432306)
		(end 397.28267 -255.432306)
		(width 0.18288)
		(layer "In11.Cu")
		(net "M_H_CPU0_SA_CA<4>")
	)
	(segment
		(start 425.168568 -260.531102)
		(end 425.05884 -260.64083)
		(width 0.18288)
		(layer "In11.Cu")
		(net "M_H_CPU0_SA_CA<4>")
	)
	(segment
		(start 431.865532 -260.641084)
		(end 431.63363 -260.872986)
		(width 0.18288)
		(layer "In11.Cu")
		(net "M_H_CPU0_SA_CA<4>")
	)
	(segment
		(start 442.582808 -260.440932)
		(end 440.800236 -260.440932)
		(width 0.18288)
		(layer "In11.Cu")
		(net "M_H_CPU0_SA_CA<4>")
	)
	(segment
		(start 428.893224 -260.872986)
		(end 427.969934 -260.872986)
		(width 0.18288)
		(layer "In11.Cu")
		(net "M_H_CPU0_SA_CA<4>")
	)
	(segment
		(start 439.658506 -260.64083)
		(end 438.653428 -259.635752)
		(width 0.18288)
		(layer "In11.Cu")
		(net "M_H_CPU0_SA_CA<4>")
	)
	(segment
		(start 429.789844 -260.679946)
		(end 429.789844 -259.970524)
		(width 0.18288)
		(layer "In11.Cu")
		(net "M_H_CPU0_SA_CA<4>")
	)
	(segment
		(start 406.762458 -258.99999)
		(end 404.886414 -258.99999)
		(width 0.18288)
		(layer "In11.Cu")
		(net "M_H_CPU0_SA_CA<4>")
	)
	(segment
		(start 434.062378 -259.790946)
		(end 433.21224 -260.641084)
		(width 0.18288)
		(layer "In11.Cu")
		(net "M_H_CPU0_SA_CA<4>")
	)
	(segment
		(start 426.440092 -259.864352)
		(end 426.247052 -259.671312)
		(width 0.18288)
		(layer "In11.Cu")
		(net "M_H_CPU0_SA_CA<4>")
	)
	(segment
		(start 407.407618 -259.64515)
		(end 406.762458 -258.99999)
		(width 0.18288)
		(layer "In11.Cu")
		(net "M_H_CPU0_SA_CA<4>")
	)
	(segment
		(start 396.752318 -255.962658)
		(end 392.135106 -255.962658)
		(width 0.18288)
		(layer "In11.Cu")
		(net "M_H_CPU0_SA_CA<4>")
	)
	(segment
		(start 429.982884 -260.872986)
		(end 429.789844 -260.679946)
		(width 0.18288)
		(layer "In11.Cu")
		(net "M_H_CPU0_SA_CA<4>")
	)
	(segment
		(start 424.429682 -260.64083)
		(end 423.404792 -259.61594)
		(width 0.18288)
		(layer "In11.Cu")
		(net "M_H_CPU0_SA_CA<4>")
	)
	(segment
		(start 429.086264 -260.679946)
		(end 428.893224 -260.872986)
		(width 0.18288)
		(layer "In11.Cu")
		(net "M_H_CPU0_SA_CA<4>")
	)
	(segment
		(start 440.800236 -260.440932)
		(end 440.600338 -260.64083)
		(width 0.18288)
		(layer "In11.Cu")
		(net "M_H_CPU0_SA_CA<4>")
	)
	(segment
		(start 421.566086 -259.790946)
		(end 420.22903 -259.790946)
		(width 0.18288)
		(layer "In11.Cu")
		(net "M_H_CPU0_SA_CA<4>")
	)
	(segment
		(start 372.360952 -254.313436)
		(end 371.967252 -253.919736)
		(width 0.088646)
		(layer "In11.Cu")
		(net "M_H_CPU0_SA_CA<4>")
	)
	(segment
		(start 431.63363 -260.872986)
		(end 429.982884 -260.872986)
		(width 0.18288)
		(layer "In11.Cu")
		(net "M_H_CPU0_SA_CA<4>")
	)
	(segment
		(start 427.969934 -260.872986)
		(end 427.62805 -260.531102)
		(width 0.18288)
		(layer "In11.Cu")
		(net "M_H_CPU0_SA_CA<4>")
	)
	(segment
		(start 420.22903 -259.790946)
		(end 420.083234 -259.64515)
		(width 0.18288)
		(layer "In11.Cu")
		(net "M_H_CPU0_SA_CA<4>")
	)
	(segment
		(start 450.434456 -262.089138)
		(end 449.095368 -262.089138)
		(width 0.18288)
		(layer "In11.Cu")
		(net "M_H_CPU0_SA_CA<4>")
	)
	(segment
		(start 420.083234 -259.64515)
		(end 407.407618 -259.64515)
		(width 0.18288)
		(layer "In11.Cu")
		(net "M_H_CPU0_SA_CA<4>")
	)
	(segment
		(start 425.929552 -259.671312)
		(end 425.736512 -259.864352)
		(width 0.18288)
		(layer "In11.Cu")
		(net "M_H_CPU0_SA_CA<4>")
	)
	(segment
		(start 389.663178 -253.49073)
		(end 373.559832 -253.49073)
		(width 0.18288)
		(layer "In11.Cu")
		(net "M_H_CPU0_SA_CA<4>")
	)
	(segment
		(start 450.911214 -262.76681)
		(end 450.911214 -262.63219)
		(width 0.18288)
		(layer "In11.Cu")
		(net "M_H_CPU0_SA_CA<4>")
	)
	(segment
		(start 401.990306 -256.103882)
		(end 400.369024 -255.432306)
		(width 0.18288)
		(layer "In11.Cu")
		(net "M_H_CPU0_SA_CA<4>")
	)
	(segment
		(start 426.633132 -260.531102)
		(end 426.440092 -260.338062)
		(width 0.18288)
		(layer "In11.Cu")
		(net "M_H_CPU0_SA_CA<4>")
	)
	(segment
		(start 426.247052 -259.671312)
		(end 425.929552 -259.671312)
		(width 0.18288)
		(layer "In11.Cu")
		(net "M_H_CPU0_SA_CA<4>")
	)
	(segment
		(start 392.135106 -255.962658)
		(end 389.663178 -253.49073)
		(width 0.18288)
		(layer "In11.Cu")
		(net "M_H_CPU0_SA_CA<4>")
	)
	(segment
		(start 433.21224 -260.641084)
		(end 431.865532 -260.641084)
		(width 0.18288)
		(layer "In11.Cu")
		(net "M_H_CPU0_SA_CA<4>")
	)
	(segment
		(start 450.911214 -262.63219)
		(end 450.864224 -262.518906)
		(width 0.18288)
		(layer "In11.Cu")
		(net "M_H_CPU0_SA_CA<4>")
	)
	(segment
		(start 397.28267 -255.432306)
		(end 396.752318 -255.962658)
		(width 0.18288)
		(layer "In11.Cu")
		(net "M_H_CPU0_SA_CA<4>")
	)
	(segment
		(start 423.404792 -259.61594)
		(end 421.741092 -259.61594)
		(width 0.18288)
		(layer "In11.Cu")
		(net "M_H_CPU0_SA_CA<4>")
	)
	(segment
		(start 429.789844 -259.970524)
		(end 429.596804 -259.777484)
		(width 0.18288)
		(layer "In11.Cu")
		(net "M_H_CPU0_SA_CA<4>")
	)
	(segment
		(start 442.951362 -260.809486)
		(end 442.582808 -260.440932)
		(width 0.18288)
		(layer "In11.Cu")
		(net "M_H_CPU0_SA_CA<4>")
	)
	(segment
		(start 404.886414 -258.99999)
		(end 401.990306 -256.103882)
		(width 0.18288)
		(layer "In11.Cu")
		(net "M_H_CPU0_SA_CA<4>")
	)
	(segment
		(start 440.600338 -260.64083)
		(end 439.658506 -260.64083)
		(width 0.18288)
		(layer "In11.Cu")
		(net "M_H_CPU0_SA_CA<4>")
	)
	(segment
		(start 436.72887 -259.635752)
		(end 436.573676 -259.790946)
		(width 0.18288)
		(layer "In11.Cu")
		(net "M_H_CPU0_SA_CA<4>")
	)
	(segment
		(start 438.653428 -259.635752)
		(end 436.72887 -259.635752)
		(width 0.18288)
		(layer "In11.Cu")
		(net "M_H_CPU0_SA_CA<4>")
	)
	(segment
		(start 450.864224 -262.518906)
		(end 450.434456 -262.089138)
		(width 0.18288)
		(layer "In11.Cu")
		(net "M_H_CPU0_SA_CA<4>")
	)
	(segment
		(start 371.967252 -253.919736)
		(end 371.907816 -253.919736)
		(width 0.088646)
		(layer "In11.Cu")
		(net "M_H_CPU0_SA_CA<4>")
	)
	(segment
		(start 425.05884 -260.64083)
		(end 424.429682 -260.64083)
		(width 0.18288)
		(layer "In11.Cu")
		(net "M_H_CPU0_SA_CA<4>")
	)
	(segment
		(start 373.366792 -254.201676)
		(end 373.255032 -254.313436)
		(width 0.088646)
		(layer "In11.Cu")
		(net "M_H_CPU0_SA_CA<4>")
	)
	(segment
		(start 429.086264 -259.970524)
		(end 429.086264 -260.679946)
		(width 0.18288)
		(layer "In11.Cu")
		(net "M_H_CPU0_SA_CA<4>")
	)
	(segment
		(start 436.573676 -259.790946)
		(end 434.062378 -259.790946)
		(width 0.18288)
		(layer "In11.Cu")
		(net "M_H_CPU0_SA_CA<4>")
	)
	(segment
		(start 373.559832 -253.49073)
		(end 373.366792 -253.68377)
		(width 0.18288)
		(layer "In11.Cu")
		(net "M_H_CPU0_SA_CA<4>")
	)
	(segment
		(start 427.62805 -260.531102)
		(end 426.633132 -260.531102)
		(width 0.18288)
		(layer "In11.Cu")
		(net "M_H_CPU0_SA_CA<4>")
	)
	(segment
		(start 448.524122 -261.517892)
		(end 446.961006 -261.517892)
		(width 0.18288)
		(layer "In11.Cu")
		(net "M_H_CPU0_SA_CA<4>")
	)
	(segment
		(start 449.095368 -262.089138)
		(end 448.524122 -261.517892)
		(width 0.18288)
		(layer "In11.Cu")
		(net "M_H_CPU0_SA_CA<4>")
	)
	(segment
		(start 426.440092 -260.338062)
		(end 426.440092 -259.864352)
		(width 0.18288)
		(layer "In11.Cu")
		(net "M_H_CPU0_SA_CA<4>")
	)
	(segment
		(start 373.366792 -253.68377)
		(end 373.366792 -253.83363)
		(width 0.18288)
		(layer "In11.Cu")
		(net "M_H_CPU0_SA_CA<4>")
	)
	(segment
		(start 425.736512 -259.864352)
		(end 425.736512 -260.338062)
		(width 0.18288)
		(layer "In11.Cu")
		(net "M_H_CPU0_SA_CA<4>")
	)
	(segment
		(start 458.538326 -264.052304)
		(end 458.543152 -264.052304)
		(width 0.101854)
		(layer "F.Cu")
		(net "M_H_CPU0_SA_CA<3>")
	)
	(segment
		(start 460.570326 -264.049002)
		(end 460.844392 -264.049002)
		(width 0.20066)
		(layer "F.Cu")
		(net "M_H_CPU0_SA_CA<3>")
	)
	(segment
		(start 460.56296 -264.041636)
		(end 460.570326 -264.049002)
		(width 0.1016)
		(layer "F.Cu")
		(net "M_H_CPU0_SA_CA<3>")
	)
	(segment
		(start 462.54543 -263.616694)
		(end 463.659982 -263.616694)
		(width 0.20066)
		(layer "F.Cu")
		(net "M_H_CPU0_SA_CA<3>")
	)
	(segment
		(start 462.112868 -263.184132)
		(end 462.54543 -263.616694)
		(width 0.20066)
		(layer "F.Cu")
		(net "M_H_CPU0_SA_CA<3>")
	)
	(segment
		(start 455.011282 -263.616694)
		(end 456.116182 -263.616694)
		(width 0.20066)
		(layer "F.Cu")
		(net "M_H_CPU0_SA_CA<3>")
	)
	(segment
		(start 457.751942 -263.616694)
		(end 458.187552 -264.052304)
		(width 0.20066)
		(layer "F.Cu")
		(net "M_H_CPU0_SA_CA<3>")
	)
	(segment
		(start 458.187552 -264.052304)
		(end 458.538326 -264.052304)
		(width 0.20066)
		(layer "F.Cu")
		(net "M_H_CPU0_SA_CA<3>")
	)
	(segment
		(start 461.709262 -263.184132)
		(end 462.112868 -263.184132)
		(width 0.20066)
		(layer "F.Cu")
		(net "M_H_CPU0_SA_CA<3>")
	)
	(segment
		(start 456.116182 -263.616694)
		(end 457.751942 -263.616694)
		(width 0.20066)
		(layer "F.Cu")
		(net "M_H_CPU0_SA_CA<3>")
	)
	(segment
		(start 373.317516 -254.197612)
		(end 373.317516 -254.733298)
		(width 0.20066)
		(layer "F.Cu")
		(net "M_H_CPU0_SA_CA<3>")
	)
	(segment
		(start 373.317516 -254.733298)
		(end 373.317262 -254.733552)
		(width 0.20066)
		(layer "F.Cu")
		(net "M_H_CPU0_SA_CA<3>")
	)
	(segment
		(start 458.55382 -264.041636)
		(end 460.56296 -264.041636)
		(width 0.1016)
		(layer "F.Cu")
		(net "M_H_CPU0_SA_CA<3>")
	)
	(segment
		(start 460.844392 -264.049002)
		(end 461.709262 -263.184132)
		(width 0.20066)
		(layer "F.Cu")
		(net "M_H_CPU0_SA_CA<3>")
	)
	(segment
		(start 458.543152 -264.052304)
		(end 458.55382 -264.041636)
		(width 0.1016)
		(layer "F.Cu")
		(net "M_H_CPU0_SA_CA<3>")
	)
	(segment
		(start 404.652988 -259.548122)
		(end 401.638516 -256.53365)
		(width 0.18288)
		(layer "In11.Cu")
		(net "M_H_CPU0_SA_CA<3>")
	)
	(segment
		(start 420.205154 -260.64083)
		(end 419.799008 -260.234684)
		(width 0.18288)
		(layer "In11.Cu")
		(net "M_H_CPU0_SA_CA<3>")
	)
	(segment
		(start 446.768474 -262.21182)
		(end 445.88049 -261.323836)
		(width 0.18288)
		(layer "In11.Cu")
		(net "M_H_CPU0_SA_CA<3>")
	)
	(segment
		(start 390.08431 -254.415798)
		(end 388.129018 -254.415798)
		(width 0.18288)
		(layer "In11.Cu")
		(net "M_H_CPU0_SA_CA<3>")
	)
	(segment
		(start 435.217316 -260.64083)
		(end 435.092094 -260.515608)
		(width 0.18288)
		(layer "In11.Cu")
		(net "M_H_CPU0_SA_CA<3>")
	)
	(segment
		(start 400.22907 -255.950212)
		(end 397.508984 -255.950212)
		(width 0.18288)
		(layer "In11.Cu")
		(net "M_H_CPU0_SA_CA<3>")
	)
	(segment
		(start 407.800302 -260.850634)
		(end 406.49779 -259.548122)
		(width 0.18288)
		(layer "In11.Cu")
		(net "M_H_CPU0_SA_CA<3>")
	)
	(segment
		(start 431.260504 -261.522718)
		(end 431.12944 -261.391654)
		(width 0.18288)
		(layer "In11.Cu")
		(net "M_H_CPU0_SA_CA<3>")
	)
	(segment
		(start 377.743974 -254.237998)
		(end 377.73356 -254.244094)
		(width 0.088646)
		(layer "In11.Cu")
		(net "M_H_CPU0_SA_CA<3>")
	)
	(segment
		(start 441.474098 -261.490968)
		(end 439.530236 -261.490968)
		(width 0.18288)
		(layer "In11.Cu")
		(net "M_H_CPU0_SA_CA<3>")
	)
	(segment
		(start 401.638516 -256.53365)
		(end 400.22907 -255.950212)
		(width 0.18288)
		(layer "In11.Cu")
		(net "M_H_CPU0_SA_CA<3>")
	)
	(segment
		(start 373.797576 -254.294132)
		(end 373.358156 -254.733552)
		(width 0.088646)
		(layer "In11.Cu")
		(net "M_H_CPU0_SA_CA<3>")
	)
	(segment
		(start 387.744716 -254.415798)
		(end 387.603492 -254.557022)
		(width 0.088646)
		(layer "In11.Cu")
		(net "M_H_CPU0_SA_CA<3>")
	)
	(segment
		(start 375.864628 -254.237998)
		(end 375.854214 -254.244094)
		(width 0.088646)
		(layer "In11.Cu")
		(net "M_H_CPU0_SA_CA<3>")
	)
	(segment
		(start 380.178818 -254.244094)
		(end 380.164086 -254.235458)
		(width 0.088646)
		(layer "In11.Cu")
		(net "M_H_CPU0_SA_CA<3>")
	)
	(segment
		(start 454.241662 -262.847074)
		(end 452.084186 -262.847074)
		(width 0.18288)
		(layer "In11.Cu")
		(net "M_H_CPU0_SA_CA<3>")
	)
	(segment
		(start 424.442636 -261.490968)
		(end 423.756328 -260.80466)
		(width 0.18288)
		(layer "In11.Cu")
		(net "M_H_CPU0_SA_CA<3>")
	)
	(segment
		(start 378.684028 -254.237998)
		(end 378.673614 -254.244094)
		(width 0.088646)
		(layer "In11.Cu")
		(net "M_H_CPU0_SA_CA<3>")
	)
	(segment
		(start 436.71871 -260.64083)
		(end 435.217316 -260.64083)
		(width 0.18288)
		(layer "In11.Cu")
		(net "M_H_CPU0_SA_CA<3>")
	)
	(segment
		(start 436.847742 -260.769862)
		(end 436.71871 -260.64083)
		(width 0.18288)
		(layer "In11.Cu")
		(net "M_H_CPU0_SA_CA<3>")
	)
	(segment
		(start 397.138906 -256.32029)
		(end 391.988802 -256.32029)
		(width 0.18288)
		(layer "In11.Cu")
		(net "M_H_CPU0_SA_CA<3>")
	)
	(segment
		(start 382.443228 -254.237998)
		(end 382.432814 -254.244094)
		(width 0.088646)
		(layer "In11.Cu")
		(net "M_H_CPU0_SA_CA<3>")
	)
	(segment
		(start 416.899852 -260.727444)
		(end 412.69158 -260.727444)
		(width 0.18288)
		(layer "In11.Cu")
		(net "M_H_CPU0_SA_CA<3>")
	)
	(segment
		(start 439.530236 -261.490968)
		(end 438.80913 -260.769862)
		(width 0.18288)
		(layer "In11.Cu")
		(net "M_H_CPU0_SA_CA<3>")
	)
	(segment
		(start 450.467476 -263.322816)
		(end 449.209414 -263.322816)
		(width 0.18288)
		(layer "In11.Cu")
		(net "M_H_CPU0_SA_CA<3>")
	)
	(segment
		(start 450.598032 -263.19226)
		(end 450.467476 -263.322816)
		(width 0.18288)
		(layer "In11.Cu")
		(net "M_H_CPU0_SA_CA<3>")
	)
	(segment
		(start 425.774358 -261.490968)
		(end 424.442636 -261.490968)
		(width 0.18288)
		(layer "In11.Cu")
		(net "M_H_CPU0_SA_CA<3>")
	)
	(segment
		(start 455.011282 -263.616694)
		(end 454.241662 -262.847074)
		(width 0.18288)
		(layer "In11.Cu")
		(net "M_H_CPU0_SA_CA<3>")
	)
	(segment
		(start 412.69158 -260.727444)
		(end 412.286704 -260.322568)
		(width 0.18288)
		(layer "In11.Cu")
		(net "M_H_CPU0_SA_CA<3>")
	)
	(segment
		(start 387.097524 -254.557022)
		(end 386.874258 -254.333756)
		(width 0.088646)
		(layer "In11.Cu")
		(net "M_H_CPU0_SA_CA<3>")
	)
	(segment
		(start 425.965366 -261.681976)
		(end 425.774358 -261.490968)
		(width 0.18288)
		(layer "In11.Cu")
		(net "M_H_CPU0_SA_CA<3>")
	)
	(segment
		(start 397.508984 -255.950212)
		(end 397.138906 -256.32029)
		(width 0.18288)
		(layer "In11.Cu")
		(net "M_H_CPU0_SA_CA<3>")
	)
	(segment
		(start 388.129018 -254.415798)
		(end 387.744716 -254.415798)
		(width 0.088646)
		(layer "In11.Cu")
		(net "M_H_CPU0_SA_CA<3>")
	)
	(segment
		(start 373.358156 -254.733552)
		(end 373.317262 -254.733552)
		(width 0.088646)
		(layer "In11.Cu")
		(net "M_H_CPU0_SA_CA<3>")
	)
	(segment
		(start 419.799008 -260.234684)
		(end 417.392612 -260.234684)
		(width 0.18288)
		(layer "In11.Cu")
		(net "M_H_CPU0_SA_CA<3>")
	)
	(segment
		(start 406.49779 -259.548122)
		(end 404.652988 -259.548122)
		(width 0.18288)
		(layer "In11.Cu")
		(net "M_H_CPU0_SA_CA<3>")
	)
	(segment
		(start 431.12944 -261.391654)
		(end 427.839124 -261.391654)
		(width 0.18288)
		(layer "In11.Cu")
		(net "M_H_CPU0_SA_CA<3>")
	)
	(segment
		(start 438.80913 -260.769862)
		(end 436.847742 -260.769862)
		(width 0.18288)
		(layer "In11.Cu")
		(net "M_H_CPU0_SA_CA<3>")
	)
	(segment
		(start 391.988802 -256.32029)
		(end 390.08431 -254.415798)
		(width 0.18288)
		(layer "In11.Cu")
		(net "M_H_CPU0_SA_CA<3>")
	)
	(segment
		(start 387.603492 -254.557022)
		(end 387.097524 -254.557022)
		(width 0.088646)
		(layer "In11.Cu")
		(net "M_H_CPU0_SA_CA<3>")
	)
	(segment
		(start 449.209414 -263.322816)
		(end 448.098418 -262.21182)
		(width 0.18288)
		(layer "In11.Cu")
		(net "M_H_CPU0_SA_CA<3>")
	)
	(segment
		(start 417.392612 -260.234684)
		(end 416.899852 -260.727444)
		(width 0.18288)
		(layer "In11.Cu")
		(net "M_H_CPU0_SA_CA<3>")
	)
	(segment
		(start 421.553894 -260.64083)
		(end 420.205154 -260.64083)
		(width 0.18288)
		(layer "In11.Cu")
		(net "M_H_CPU0_SA_CA<3>")
	)
	(segment
		(start 427.839124 -261.391654)
		(end 427.548802 -261.681976)
		(width 0.18288)
		(layer "In11.Cu")
		(net "M_H_CPU0_SA_CA<3>")
	)
	(segment
		(start 441.660788 -261.677658)
		(end 441.474098 -261.490968)
		(width 0.18288)
		(layer "In11.Cu")
		(net "M_H_CPU0_SA_CA<3>")
	)
	(segment
		(start 451.739 -263.19226)
		(end 450.598032 -263.19226)
		(width 0.18288)
		(layer "In11.Cu")
		(net "M_H_CPU0_SA_CA<3>")
	)
	(segment
		(start 445.88049 -261.323836)
		(end 442.990986 -261.323836)
		(width 0.18288)
		(layer "In11.Cu")
		(net "M_H_CPU0_SA_CA<3>")
	)
	(segment
		(start 427.548802 -261.681976)
		(end 425.965366 -261.681976)
		(width 0.18288)
		(layer "In11.Cu")
		(net "M_H_CPU0_SA_CA<3>")
	)
	(segment
		(start 374.929146 -254.235458)
		(end 374.914668 -254.244094)
		(width 0.088646)
		(layer "In11.Cu")
		(net "M_H_CPU0_SA_CA<3>")
	)
	(segment
		(start 412.286704 -260.322568)
		(end 409.602178 -260.322568)
		(width 0.18288)
		(layer "In11.Cu")
		(net "M_H_CPU0_SA_CA<3>")
	)
	(segment
		(start 433.063904 -261.522718)
		(end 431.260504 -261.522718)
		(width 0.18288)
		(layer "In11.Cu")
		(net "M_H_CPU0_SA_CA<3>")
	)
	(segment
		(start 423.756328 -260.80466)
		(end 421.717724 -260.80466)
		(width 0.18288)
		(layer "In11.Cu")
		(net "M_H_CPU0_SA_CA<3>")
	)
	(segment
		(start 409.074112 -260.850634)
		(end 407.800302 -260.850634)
		(width 0.18288)
		(layer "In11.Cu")
		(net "M_H_CPU0_SA_CA<3>")
	)
	(segment
		(start 380.553214 -254.244094)
		(end 380.55296 -254.244094)
		(width 0.088646)
		(layer "In11.Cu")
		(net "M_H_CPU0_SA_CA<3>")
	)
	(segment
		(start 442.637164 -261.677658)
		(end 441.660788 -261.677658)
		(width 0.18288)
		(layer "In11.Cu")
		(net "M_H_CPU0_SA_CA<3>")
	)
	(segment
		(start 380.1872 -254.24892)
		(end 380.178818 -254.244094)
		(width 0.088646)
		(layer "In11.Cu")
		(net "M_H_CPU0_SA_CA<3>")
	)
	(segment
		(start 434.071014 -260.515608)
		(end 433.063904 -261.522718)
		(width 0.18288)
		(layer "In11.Cu")
		(net "M_H_CPU0_SA_CA<3>")
	)
	(segment
		(start 381.507746 -254.235458)
		(end 381.493014 -254.244094)
		(width 0.088646)
		(layer "In11.Cu")
		(net "M_H_CPU0_SA_CA<3>")
	)
	(segment
		(start 435.092094 -260.515608)
		(end 434.071014 -260.515608)
		(width 0.18288)
		(layer "In11.Cu")
		(net "M_H_CPU0_SA_CA<3>")
	)
	(segment
		(start 452.084186 -262.847074)
		(end 451.739 -263.19226)
		(width 0.18288)
		(layer "In11.Cu")
		(net "M_H_CPU0_SA_CA<3>")
	)
	(segment
		(start 379.247146 -254.24892)
		(end 379.238764 -254.244094)
		(width 0.088646)
		(layer "In11.Cu")
		(net "M_H_CPU0_SA_CA<3>")
	)
	(segment
		(start 409.602178 -260.322568)
		(end 409.074112 -260.850634)
		(width 0.18288)
		(layer "In11.Cu")
		(net "M_H_CPU0_SA_CA<3>")
	)
	(segment
		(start 442.990986 -261.323836)
		(end 442.637164 -261.677658)
		(width 0.18288)
		(layer "In11.Cu")
		(net "M_H_CPU0_SA_CA<3>")
	)
	(segment
		(start 448.098418 -262.21182)
		(end 446.768474 -262.21182)
		(width 0.18288)
		(layer "In11.Cu")
		(net "M_H_CPU0_SA_CA<3>")
	)
	(segment
		(start 421.717724 -260.80466)
		(end 421.553894 -260.64083)
		(width 0.18288)
		(layer "In11.Cu")
		(net "M_H_CPU0_SA_CA<3>")
	)
	(arc
		(start 386.19176 -254.244094)
		(mid 386.004562 -254.294237)
		(end 385.817364 -254.244094)
		(width 0.088646)
		(layer "In11.Cu")
		(net "M_H_CPU0_SA_CA<3>")
	)
	(arc
		(start 384.31216 -254.244094)
		(mid 384.124962 -254.294237)
		(end 383.937764 -254.244094)
		(width 0.088646)
		(layer "In11.Cu")
		(net "M_H_CPU0_SA_CA<3>")
	)
	(arc
		(start 381.493014 -254.244094)
		(mid 381.305816 -254.294237)
		(end 381.118618 -254.244094)
		(width 0.088646)
		(layer "In11.Cu")
		(net "M_H_CPU0_SA_CA<3>")
	)
	(arc
		(start 376.419364 -254.244094)
		(mid 376.142805 -254.168351)
		(end 375.864628 -254.237998)
		(width 0.088646)
		(layer "In11.Cu")
		(net "M_H_CPU0_SA_CA<3>")
	)
	(arc
		(start 383.37236 -254.244094)
		(mid 383.185162 -254.294237)
		(end 382.997964 -254.244094)
		(width 0.088646)
		(layer "In11.Cu")
		(net "M_H_CPU0_SA_CA<3>")
	)
	(arc
		(start 377.73356 -254.244094)
		(mid 377.546362 -254.294237)
		(end 377.359164 -254.244094)
		(width 0.088646)
		(layer "In11.Cu")
		(net "M_H_CPU0_SA_CA<3>")
	)
	(arc
		(start 374.914668 -254.244094)
		(mid 374.72736 -254.294237)
		(end 374.540018 -254.244094)
		(width 0.088646)
		(layer "In11.Cu")
		(net "M_H_CPU0_SA_CA<3>")
	)
	(arc
		(start 379.613414 -254.244094)
		(mid 379.430909 -254.294332)
		(end 379.247146 -254.24892)
		(width 0.088646)
		(layer "In11.Cu")
		(net "M_H_CPU0_SA_CA<3>")
	)
	(arc
		(start 382.997964 -254.244094)
		(mid 382.721405 -254.168351)
		(end 382.443228 -254.237998)
		(width 0.088646)
		(layer "In11.Cu")
		(net "M_H_CPU0_SA_CA<3>")
	)
	(arc
		(start 384.877564 -254.244094)
		(mid 384.594862 -254.168318)
		(end 384.31216 -254.244094)
		(width 0.088646)
		(layer "In11.Cu")
		(net "M_H_CPU0_SA_CA<3>")
	)
	(arc
		(start 373.974614 -254.244094)
		(mid 373.889213 -254.280137)
		(end 373.797576 -254.294132)
		(width 0.088646)
		(layer "In11.Cu")
		(net "M_H_CPU0_SA_CA<3>")
	)
	(arc
		(start 375.479818 -254.244094)
		(mid 375.205619 -254.168259)
		(end 374.929146 -254.235458)
		(width 0.088646)
		(layer "In11.Cu")
		(net "M_H_CPU0_SA_CA<3>")
	)
	(arc
		(start 374.540018 -254.244094)
		(mid 374.257316 -254.168318)
		(end 373.974614 -254.244094)
		(width 0.088646)
		(layer "In11.Cu")
		(net "M_H_CPU0_SA_CA<3>")
	)
	(arc
		(start 386.874258 -254.333756)
		(mid 386.818653 -254.285082)
		(end 386.757164 -254.244094)
		(width 0.088646)
		(layer "In11.Cu")
		(net "M_H_CPU0_SA_CA<3>")
	)
	(arc
		(start 378.299218 -254.244094)
		(mid 378.022405 -254.168224)
		(end 377.743974 -254.237998)
		(width 0.088646)
		(layer "In11.Cu")
		(net "M_H_CPU0_SA_CA<3>")
	)
	(arc
		(start 381.118618 -254.244094)
		(mid 380.835916 -254.168318)
		(end 380.553214 -254.244094)
		(width 0.088646)
		(layer "In11.Cu")
		(net "M_H_CPU0_SA_CA<3>")
	)
	(arc
		(start 386.757164 -254.244094)
		(mid 386.474462 -254.168318)
		(end 386.19176 -254.244094)
		(width 0.088646)
		(layer "In11.Cu")
		(net "M_H_CPU0_SA_CA<3>")
	)
	(arc
		(start 380.55296 -254.244094)
		(mid 380.370709 -254.294205)
		(end 380.1872 -254.24892)
		(width 0.088646)
		(layer "In11.Cu")
		(net "M_H_CPU0_SA_CA<3>")
	)
	(arc
		(start 383.937764 -254.244094)
		(mid 383.655062 -254.168318)
		(end 383.37236 -254.244094)
		(width 0.088646)
		(layer "In11.Cu")
		(net "M_H_CPU0_SA_CA<3>")
	)
	(arc
		(start 378.673614 -254.244094)
		(mid 378.486416 -254.294237)
		(end 378.299218 -254.244094)
		(width 0.088646)
		(layer "In11.Cu")
		(net "M_H_CPU0_SA_CA<3>")
	)
	(arc
		(start 380.164086 -254.235458)
		(mid 379.887611 -254.168138)
		(end 379.613414 -254.244094)
		(width 0.088646)
		(layer "In11.Cu")
		(net "M_H_CPU0_SA_CA<3>")
	)
	(arc
		(start 382.058418 -254.244094)
		(mid 381.784219 -254.168259)
		(end 381.507746 -254.235458)
		(width 0.088646)
		(layer "In11.Cu")
		(net "M_H_CPU0_SA_CA<3>")
	)
	(arc
		(start 382.432814 -254.244094)
		(mid 382.245616 -254.294237)
		(end 382.058418 -254.244094)
		(width 0.088646)
		(layer "In11.Cu")
		(net "M_H_CPU0_SA_CA<3>")
	)
	(arc
		(start 385.817364 -254.244094)
		(mid 385.534662 -254.168318)
		(end 385.25196 -254.244094)
		(width 0.088646)
		(layer "In11.Cu")
		(net "M_H_CPU0_SA_CA<3>")
	)
	(arc
		(start 385.25196 -254.244094)
		(mid 385.064762 -254.294237)
		(end 384.877564 -254.244094)
		(width 0.088646)
		(layer "In11.Cu")
		(net "M_H_CPU0_SA_CA<3>")
	)
	(arc
		(start 379.238764 -254.244094)
		(mid 378.962205 -254.168351)
		(end 378.684028 -254.237998)
		(width 0.088646)
		(layer "In11.Cu")
		(net "M_H_CPU0_SA_CA<3>")
	)
	(arc
		(start 376.79376 -254.244094)
		(mid 376.606562 -254.294237)
		(end 376.419364 -254.244094)
		(width 0.088646)
		(layer "In11.Cu")
		(net "M_H_CPU0_SA_CA<3>")
	)
	(arc
		(start 377.359164 -254.244094)
		(mid 377.076462 -254.168318)
		(end 376.79376 -254.244094)
		(width 0.088646)
		(layer "In11.Cu")
		(net "M_H_CPU0_SA_CA<3>")
	)
	(arc
		(start 375.854214 -254.244094)
		(mid 375.667016 -254.294237)
		(end 375.479818 -254.244094)
		(width 0.088646)
		(layer "In11.Cu")
		(net "M_H_CPU0_SA_CA<3>")
	)
	(segment
		(start 450.911214 -264.466578)
		(end 452.016114 -264.466578)
		(width 0.20066)
		(layer "F.Cu")
		(net "M_H_CPU0_SA_CA<2>")
	)
	(segment
		(start 371.437916 -254.197612)
		(end 371.437662 -254.197866)
		(width 0.20066)
		(layer "F.Cu")
		(net "M_H_CPU0_SA_CA<2>")
	)
	(segment
		(start 457.114148 -264.89152)
		(end 457.126594 -264.903966)
		(width 0.1016)
		(layer "F.Cu")
		(net "M_H_CPU0_SA_CA<2>")
	)
	(segment
		(start 454.820528 -264.89152)
		(end 454.92797 -264.89152)
		(width 0.20066)
		(layer "F.Cu")
		(net "M_H_CPU0_SA_CA<2>")
	)
	(segment
		(start 457.980288 -264.466324)
		(end 459.55966 -264.466324)
		(width 0.20066)
		(layer "F.Cu")
		(net "M_H_CPU0_SA_CA<2>")
	)
	(segment
		(start 454.941686 -264.89152)
		(end 457.114148 -264.89152)
		(width 0.1016)
		(layer "F.Cu")
		(net "M_H_CPU0_SA_CA<2>")
	)
	(segment
		(start 452.016114 -264.466578)
		(end 453.081644 -264.466578)
		(width 0.20066)
		(layer "F.Cu")
		(net "M_H_CPU0_SA_CA<2>")
	)
	(segment
		(start 459.55966 -264.466324)
		(end 459.559914 -264.466578)
		(width 0.20066)
		(layer "F.Cu")
		(net "M_H_CPU0_SA_CA<2>")
	)
	(segment
		(start 371.437662 -254.197866)
		(end 371.437662 -254.733552)
		(width 0.20066)
		(layer "F.Cu")
		(net "M_H_CPU0_SA_CA<2>")
	)
	(segment
		(start 453.575928 -263.972294)
		(end 453.901302 -263.972294)
		(width 0.20066)
		(layer "F.Cu")
		(net "M_H_CPU0_SA_CA<2>")
	)
	(segment
		(start 453.081644 -264.466578)
		(end 453.575928 -263.972294)
		(width 0.20066)
		(layer "F.Cu")
		(net "M_H_CPU0_SA_CA<2>")
	)
	(segment
		(start 457.126594 -264.903966)
		(end 457.542646 -264.903966)
		(width 0.20066)
		(layer "F.Cu")
		(net "M_H_CPU0_SA_CA<2>")
	)
	(segment
		(start 454.92797 -264.89152)
		(end 454.941686 -264.89152)
		(width 0.101854)
		(layer "F.Cu")
		(net "M_H_CPU0_SA_CA<2>")
	)
	(segment
		(start 457.542646 -264.903966)
		(end 457.980288 -264.466324)
		(width 0.20066)
		(layer "F.Cu")
		(net "M_H_CPU0_SA_CA<2>")
	)
	(segment
		(start 453.901302 -263.972294)
		(end 454.820528 -264.89152)
		(width 0.20066)
		(layer "F.Cu")
		(net "M_H_CPU0_SA_CA<2>")
	)
	(segment
		(start 440.735466 -262.20166)
		(end 440.596274 -262.340852)
		(width 0.18288)
		(layer "In11.Cu")
		(net "M_H_CPU0_SA_CA<2>")
	)
	(segment
		(start 406.92197 -260.708902)
		(end 405.057356 -260.708902)
		(width 0.18288)
		(layer "In11.Cu")
		(net "M_H_CPU0_SA_CA<2>")
	)
	(segment
		(start 433.714906 -261.592568)
		(end 433.244244 -262.06323)
		(width 0.18288)
		(layer "In11.Cu")
		(net "M_H_CPU0_SA_CA<2>")
	)
	(segment
		(start 372.575328 -255.051814)
		(end 372.564914 -255.05791)
		(width 0.088646)
		(layer "In11.Cu")
		(net "M_H_CPU0_SA_CA<2>")
	)
	(segment
		(start 423.340784 -261.324598)
		(end 421.836088 -261.324598)
		(width 0.18288)
		(layer "In11.Cu")
		(net "M_H_CPU0_SA_CA<2>")
	)
	(segment
		(start 427.678342 -262.198104)
		(end 426.003212 -262.198104)
		(width 0.18288)
		(layer "In11.Cu")
		(net "M_H_CPU0_SA_CA<2>")
	)
	(segment
		(start 416.907218 -261.661148)
		(end 416.530282 -261.284212)
		(width 0.18288)
		(layer "In11.Cu")
		(net "M_H_CPU0_SA_CA<2>")
	)
	(segment
		(start 435.763162 -261.492492)
		(end 435.172612 -261.492492)
		(width 0.18288)
		(layer "In11.Cu")
		(net "M_H_CPU0_SA_CA<2>")
	)
	(segment
		(start 417.981892 -261.661148)
		(end 416.907218 -261.661148)
		(width 0.18288)
		(layer "In11.Cu")
		(net "M_H_CPU0_SA_CA<2>")
	)
	(segment
		(start 397.407384 -256.669286)
		(end 391.838434 -256.669286)
		(width 0.18288)
		(layer "In11.Cu")
		(net "M_H_CPU0_SA_CA<2>")
	)
	(segment
		(start 424.357038 -262.340852)
		(end 423.340784 -261.324598)
		(width 0.18288)
		(layer "In11.Cu")
		(net "M_H_CPU0_SA_CA<2>")
	)
	(segment
		(start 419.071552 -261.661148)
		(end 418.878512 -261.468108)
		(width 0.18288)
		(layer "In11.Cu")
		(net "M_H_CPU0_SA_CA<2>")
	)
	(segment
		(start 436.660544 -261.490968)
		(end 435.764686 -261.490968)
		(width 0.18288)
		(layer "In11.Cu")
		(net "M_H_CPU0_SA_CA<2>")
	)
	(segment
		(start 433.244244 -262.06323)
		(end 431.350674 -262.06323)
		(width 0.18288)
		(layer "In11.Cu")
		(net "M_H_CPU0_SA_CA<2>")
	)
	(segment
		(start 418.174932 -261.468108)
		(end 417.981892 -261.661148)
		(width 0.18288)
		(layer "In11.Cu")
		(net "M_H_CPU0_SA_CA<2>")
	)
	(segment
		(start 418.367972 -260.754876)
		(end 418.174932 -260.947916)
		(width 0.18288)
		(layer "In11.Cu")
		(net "M_H_CPU0_SA_CA<2>")
	)
	(segment
		(start 436.852314 -261.299198)
		(end 436.660544 -261.490968)
		(width 0.18288)
		(layer "In11.Cu")
		(net "M_H_CPU0_SA_CA<2>")
	)
	(segment
		(start 389.930894 -254.761746)
		(end 388.132574 -254.761746)
		(width 0.18288)
		(layer "In11.Cu")
		(net "M_H_CPU0_SA_CA<2>")
	)
	(segment
		(start 450.336158 -264.466578)
		(end 449.800726 -263.931146)
		(width 0.18288)
		(layer "In11.Cu")
		(net "M_H_CPU0_SA_CA<2>")
	)
	(segment
		(start 379.153674 -254.41529)
		(end 379.14326 -254.409194)
		(width 0.088646)
		(layer "In11.Cu")
		(net "M_H_CPU0_SA_CA<2>")
	)
	(segment
		(start 374.070118 -254.409194)
		(end 374.061228 -254.414274)
		(width 0.088646)
		(layer "In11.Cu")
		(net "M_H_CPU0_SA_CA<2>")
	)
	(segment
		(start 448.460876 -263.405112)
		(end 447.201544 -263.405112)
		(width 0.18288)
		(layer "In11.Cu")
		(net "M_H_CPU0_SA_CA<2>")
	)
	(segment
		(start 397.614394 -256.462276)
		(end 397.407384 -256.669286)
		(width 0.18288)
		(layer "In11.Cu")
		(net "M_H_CPU0_SA_CA<2>")
	)
	(segment
		(start 400.077686 -256.462276)
		(end 397.614394 -256.462276)
		(width 0.18288)
		(layer "In11.Cu")
		(net "M_H_CPU0_SA_CA<2>")
	)
	(segment
		(start 439.639202 -262.340852)
		(end 438.597548 -261.299198)
		(width 0.18288)
		(layer "In11.Cu")
		(net "M_H_CPU0_SA_CA<2>")
	)
	(segment
		(start 412.119826 -261.655052)
		(end 409.587954 -261.655052)
		(width 0.18288)
		(layer "In11.Cu")
		(net "M_H_CPU0_SA_CA<2>")
	)
	(segment
		(start 431.350674 -262.06323)
		(end 431.039524 -262.37438)
		(width 0.18288)
		(layer "In11.Cu")
		(net "M_H_CPU0_SA_CA<2>")
	)
	(segment
		(start 387.033008 -254.761746)
		(end 386.739638 -254.46863)
		(width 0.088646)
		(layer "In11.Cu")
		(net "M_H_CPU0_SA_CA<2>")
	)
	(segment
		(start 419.850824 -261.661148)
		(end 419.071552 -261.661148)
		(width 0.18288)
		(layer "In11.Cu")
		(net "M_H_CPU0_SA_CA<2>")
	)
	(segment
		(start 450.911214 -264.466578)
		(end 450.336158 -264.466578)
		(width 0.18288)
		(layer "In11.Cu")
		(net "M_H_CPU0_SA_CA<2>")
	)
	(segment
		(start 435.764686 -261.490968)
		(end 435.763162 -261.492492)
		(width 0.18288)
		(layer "In11.Cu")
		(net "M_H_CPU0_SA_CA<2>")
	)
	(segment
		(start 381.588264 -254.409194)
		(end 381.57785 -254.41529)
		(width 0.088646)
		(layer "In11.Cu")
		(net "M_H_CPU0_SA_CA<2>")
	)
	(segment
		(start 405.057356 -260.708902)
		(end 401.329144 -256.98069)
		(width 0.18288)
		(layer "In11.Cu")
		(net "M_H_CPU0_SA_CA<2>")
	)
	(segment
		(start 435.172612 -261.492492)
		(end 435.072536 -261.592568)
		(width 0.18288)
		(layer "In11.Cu")
		(net "M_H_CPU0_SA_CA<2>")
	)
	(segment
		(start 442.61913 -262.20166)
		(end 440.735466 -262.20166)
		(width 0.18288)
		(layer "In11.Cu")
		(net "M_H_CPU0_SA_CA<2>")
	)
	(segment
		(start 391.838434 -256.669286)
		(end 389.930894 -254.761746)
		(width 0.18288)
		(layer "In11.Cu")
		(net "M_H_CPU0_SA_CA<2>")
	)
	(segment
		(start 418.174932 -260.947916)
		(end 418.174932 -261.468108)
		(width 0.18288)
		(layer "In11.Cu")
		(net "M_H_CPU0_SA_CA<2>")
	)
	(segment
		(start 418.878512 -261.468108)
		(end 418.878512 -260.947916)
		(width 0.18288)
		(layer "In11.Cu")
		(net "M_H_CPU0_SA_CA<2>")
	)
	(segment
		(start 420.021004 -261.490968)
		(end 419.850824 -261.661148)
		(width 0.18288)
		(layer "In11.Cu")
		(net "M_H_CPU0_SA_CA<2>")
	)
	(segment
		(start 426.003212 -262.198104)
		(end 425.860464 -262.340852)
		(width 0.18288)
		(layer "In11.Cu")
		(net "M_H_CPU0_SA_CA<2>")
	)
	(segment
		(start 373.631206 -254.985012)
		(end 373.50446 -255.05791)
		(width 0.088646)
		(layer "In11.Cu")
		(net "M_H_CPU0_SA_CA<2>")
	)
	(segment
		(start 371.281198 -255.00457)
		(end 371.437662 -254.733552)
		(width 0.088646)
		(layer "In11.Cu")
		(net "M_H_CPU0_SA_CA<2>")
	)
	(segment
		(start 412.490666 -261.284212)
		(end 412.119826 -261.655052)
		(width 0.18288)
		(layer "In11.Cu")
		(net "M_H_CPU0_SA_CA<2>")
	)
	(segment
		(start 418.878512 -260.947916)
		(end 418.685472 -260.754876)
		(width 0.18288)
		(layer "In11.Cu")
		(net "M_H_CPU0_SA_CA<2>")
	)
	(segment
		(start 409.587954 -261.655052)
		(end 409.29941 -261.366508)
		(width 0.18288)
		(layer "In11.Cu")
		(net "M_H_CPU0_SA_CA<2>")
	)
	(segment
		(start 438.597548 -261.299198)
		(end 436.852314 -261.299198)
		(width 0.18288)
		(layer "In11.Cu")
		(net "M_H_CPU0_SA_CA<2>")
	)
	(segment
		(start 421.836088 -261.324598)
		(end 421.669718 -261.490968)
		(width 0.18288)
		(layer "In11.Cu")
		(net "M_H_CPU0_SA_CA<2>")
	)
	(segment
		(start 435.072536 -261.592568)
		(end 433.714906 -261.592568)
		(width 0.18288)
		(layer "In11.Cu")
		(net "M_H_CPU0_SA_CA<2>")
	)
	(segment
		(start 421.669718 -261.490968)
		(end 420.021004 -261.490968)
		(width 0.18288)
		(layer "In11.Cu")
		(net "M_H_CPU0_SA_CA<2>")
	)
	(segment
		(start 376.889264 -254.409194)
		(end 376.874532 -254.41783)
		(width 0.088646)
		(layer "In11.Cu")
		(net "M_H_CPU0_SA_CA<2>")
	)
	(segment
		(start 386.739638 -254.46863)
		(end 386.739638 -254.468376)
		(width 0.088646)
		(layer "In11.Cu")
		(net "M_H_CPU0_SA_CA<2>")
	)
	(segment
		(start 371.30228 -255.082548)
		(end 371.281198 -255.00457)
		(width 0.088646)
		(layer "In11.Cu")
		(net "M_H_CPU0_SA_CA<2>")
	)
	(segment
		(start 380.083314 -254.409194)
		(end 380.071376 -254.402336)
		(width 0.088646)
		(layer "In11.Cu")
		(net "M_H_CPU0_SA_CA<2>")
	)
	(segment
		(start 447.201544 -263.405112)
		(end 446.262252 -262.46582)
		(width 0.18288)
		(layer "In11.Cu")
		(net "M_H_CPU0_SA_CA<2>")
	)
	(segment
		(start 440.596274 -262.340852)
		(end 439.639202 -262.340852)
		(width 0.18288)
		(layer "In11.Cu")
		(net "M_H_CPU0_SA_CA<2>")
	)
	(segment
		(start 427.854618 -262.37438)
		(end 427.678342 -262.198104)
		(width 0.18288)
		(layer "In11.Cu")
		(net "M_H_CPU0_SA_CA<2>")
	)
	(segment
		(start 448.98691 -263.931146)
		(end 448.460876 -263.405112)
		(width 0.18288)
		(layer "In11.Cu")
		(net "M_H_CPU0_SA_CA<2>")
	)
	(segment
		(start 401.329144 -256.98069)
		(end 400.077686 -256.462276)
		(width 0.18288)
		(layer "In11.Cu")
		(net "M_H_CPU0_SA_CA<2>")
	)
	(segment
		(start 409.29941 -261.366508)
		(end 407.579576 -261.366508)
		(width 0.18288)
		(layer "In11.Cu")
		(net "M_H_CPU0_SA_CA<2>")
	)
	(segment
		(start 407.579576 -261.366508)
		(end 406.92197 -260.708902)
		(width 0.18288)
		(layer "In11.Cu")
		(net "M_H_CPU0_SA_CA<2>")
	)
	(segment
		(start 446.262252 -262.46582)
		(end 442.88329 -262.46582)
		(width 0.18288)
		(layer "In11.Cu")
		(net "M_H_CPU0_SA_CA<2>")
	)
	(segment
		(start 382.528064 -254.409194)
		(end 382.513332 -254.41783)
		(width 0.088646)
		(layer "In11.Cu")
		(net "M_H_CPU0_SA_CA<2>")
	)
	(segment
		(start 442.88329 -262.46582)
		(end 442.61913 -262.20166)
		(width 0.18288)
		(layer "In11.Cu")
		(net "M_H_CPU0_SA_CA<2>")
	)
	(segment
		(start 373.882666 -254.733552)
		(end 373.631206 -254.985012)
		(width 0.088646)
		(layer "In11.Cu")
		(net "M_H_CPU0_SA_CA<2>")
	)
	(segment
		(start 380.098046 -254.41783)
		(end 380.083314 -254.409194)
		(width 0.088646)
		(layer "In11.Cu")
		(net "M_H_CPU0_SA_CA<2>")
	)
	(segment
		(start 375.949464 -254.409194)
		(end 375.934732 -254.41783)
		(width 0.088646)
		(layer "In11.Cu")
		(net "M_H_CPU0_SA_CA<2>")
	)
	(segment
		(start 388.132574 -254.761746)
		(end 387.033008 -254.761746)
		(width 0.088646)
		(layer "In11.Cu")
		(net "M_H_CPU0_SA_CA<2>")
	)
	(segment
		(start 418.685472 -260.754876)
		(end 418.367972 -260.754876)
		(width 0.18288)
		(layer "In11.Cu")
		(net "M_H_CPU0_SA_CA<2>")
	)
	(segment
		(start 449.800726 -263.931146)
		(end 448.98691 -263.931146)
		(width 0.18288)
		(layer "In11.Cu")
		(net "M_H_CPU0_SA_CA<2>")
	)
	(segment
		(start 425.860464 -262.340852)
		(end 424.357038 -262.340852)
		(width 0.18288)
		(layer "In11.Cu")
		(net "M_H_CPU0_SA_CA<2>")
	)
	(segment
		(start 375.009664 -254.409194)
		(end 374.99925 -254.41529)
		(width 0.088646)
		(layer "In11.Cu")
		(net "M_H_CPU0_SA_CA<2>")
	)
	(segment
		(start 431.039524 -262.37438)
		(end 427.854618 -262.37438)
		(width 0.18288)
		(layer "In11.Cu")
		(net "M_H_CPU0_SA_CA<2>")
	)
	(segment
		(start 416.530282 -261.284212)
		(end 412.490666 -261.284212)
		(width 0.18288)
		(layer "In11.Cu")
		(net "M_H_CPU0_SA_CA<2>")
	)
	(segment
		(start 372.190518 -255.05791)
		(end 372.180104 -255.051814)
		(width 0.088646)
		(layer "In11.Cu")
		(net "M_H_CPU0_SA_CA<2>")
	)
	(segment
		(start 378.768864 -254.409194)
		(end 378.754132 -254.41783)
		(width 0.088646)
		(layer "In11.Cu")
		(net "M_H_CPU0_SA_CA<2>")
	)
	(arc
		(start 380.071376 -254.402336)
		(mid 379.889265 -254.359011)
		(end 379.708918 -254.409194)
		(width 0.088646)
		(layer "In11.Cu")
		(net "M_H_CPU0_SA_CA<2>")
	)
	(arc
		(start 376.874532 -254.41783)
		(mid 376.598057 -254.48515)
		(end 376.32386 -254.409194)
		(width 0.088646)
		(layer "In11.Cu")
		(net "M_H_CPU0_SA_CA<2>")
	)
	(arc
		(start 382.90246 -254.409194)
		(mid 382.715262 -254.359051)
		(end 382.528064 -254.409194)
		(width 0.088646)
		(layer "In11.Cu")
		(net "M_H_CPU0_SA_CA<2>")
	)
	(arc
		(start 384.78206 -254.409194)
		(mid 384.594862 -254.359051)
		(end 384.407664 -254.409194)
		(width 0.088646)
		(layer "In11.Cu")
		(net "M_H_CPU0_SA_CA<2>")
	)
	(arc
		(start 386.66166 -254.409194)
		(mid 386.474462 -254.359051)
		(end 386.287264 -254.409194)
		(width 0.088646)
		(layer "In11.Cu")
		(net "M_H_CPU0_SA_CA<2>")
	)
	(arc
		(start 385.72186 -254.409194)
		(mid 385.534662 -254.359051)
		(end 385.347464 -254.409194)
		(width 0.088646)
		(layer "In11.Cu")
		(net "M_H_CPU0_SA_CA<2>")
	)
	(arc
		(start 380.648718 -254.409194)
		(mid 380.374519 -254.485029)
		(end 380.098046 -254.41783)
		(width 0.088646)
		(layer "In11.Cu")
		(net "M_H_CPU0_SA_CA<2>")
	)
	(arc
		(start 375.934732 -254.41783)
		(mid 375.658257 -254.48515)
		(end 375.38406 -254.409194)
		(width 0.088646)
		(layer "In11.Cu")
		(net "M_H_CPU0_SA_CA<2>")
	)
	(arc
		(start 377.26366 -254.409194)
		(mid 377.076462 -254.359051)
		(end 376.889264 -254.409194)
		(width 0.088646)
		(layer "In11.Cu")
		(net "M_H_CPU0_SA_CA<2>")
	)
	(arc
		(start 379.708918 -254.409194)
		(mid 379.432105 -254.485064)
		(end 379.153674 -254.41529)
		(width 0.088646)
		(layer "In11.Cu")
		(net "M_H_CPU0_SA_CA<2>")
	)
	(arc
		(start 385.347464 -254.409194)
		(mid 385.064762 -254.48497)
		(end 384.78206 -254.409194)
		(width 0.088646)
		(layer "In11.Cu")
		(net "M_H_CPU0_SA_CA<2>")
	)
	(arc
		(start 384.407664 -254.409194)
		(mid 384.124962 -254.48497)
		(end 383.84226 -254.409194)
		(width 0.088646)
		(layer "In11.Cu")
		(net "M_H_CPU0_SA_CA<2>")
	)
	(arc
		(start 379.14326 -254.409194)
		(mid 378.956062 -254.359051)
		(end 378.768864 -254.409194)
		(width 0.088646)
		(layer "In11.Cu")
		(net "M_H_CPU0_SA_CA<2>")
	)
	(arc
		(start 374.061228 -254.414274)
		(mid 373.930314 -254.550634)
		(end 373.882666 -254.733552)
		(width 0.088646)
		(layer "In11.Cu")
		(net "M_H_CPU0_SA_CA<2>")
	)
	(arc
		(start 378.754132 -254.41783)
		(mid 378.477657 -254.48515)
		(end 378.20346 -254.409194)
		(width 0.088646)
		(layer "In11.Cu")
		(net "M_H_CPU0_SA_CA<2>")
	)
	(arc
		(start 373.130064 -255.05791)
		(mid 372.853505 -254.982201)
		(end 372.575328 -255.051814)
		(width 0.088646)
		(layer "In11.Cu")
		(net "M_H_CPU0_SA_CA<2>")
	)
	(arc
		(start 386.739638 -254.468376)
		(mid 386.702588 -254.43623)
		(end 386.66166 -254.409194)
		(width 0.088646)
		(layer "In11.Cu")
		(net "M_H_CPU0_SA_CA<2>")
	)
	(arc
		(start 381.57785 -254.41529)
		(mid 381.299672 -254.485013)
		(end 381.023114 -254.409194)
		(width 0.088646)
		(layer "In11.Cu")
		(net "M_H_CPU0_SA_CA<2>")
	)
	(arc
		(start 377.829064 -254.409194)
		(mid 377.546362 -254.48497)
		(end 377.26366 -254.409194)
		(width 0.088646)
		(layer "In11.Cu")
		(net "M_H_CPU0_SA_CA<2>")
	)
	(arc
		(start 371.62486 -255.05791)
		(mid 371.466372 -255.106843)
		(end 371.30228 -255.082548)
		(width 0.088646)
		(layer "In11.Cu")
		(net "M_H_CPU0_SA_CA<2>")
	)
	(arc
		(start 374.444514 -254.409194)
		(mid 374.257316 -254.359051)
		(end 374.070118 -254.409194)
		(width 0.088646)
		(layer "In11.Cu")
		(net "M_H_CPU0_SA_CA<2>")
	)
	(arc
		(start 383.467864 -254.409194)
		(mid 383.185162 -254.48497)
		(end 382.90246 -254.409194)
		(width 0.088646)
		(layer "In11.Cu")
		(net "M_H_CPU0_SA_CA<2>")
	)
	(arc
		(start 386.287264 -254.409194)
		(mid 386.004562 -254.48497)
		(end 385.72186 -254.409194)
		(width 0.088646)
		(layer "In11.Cu")
		(net "M_H_CPU0_SA_CA<2>")
	)
	(arc
		(start 373.50446 -255.05791)
		(mid 373.317262 -255.108053)
		(end 373.130064 -255.05791)
		(width 0.088646)
		(layer "In11.Cu")
		(net "M_H_CPU0_SA_CA<2>")
	)
	(arc
		(start 382.513332 -254.41783)
		(mid 382.236857 -254.48515)
		(end 381.96266 -254.409194)
		(width 0.088646)
		(layer "In11.Cu")
		(net "M_H_CPU0_SA_CA<2>")
	)
	(arc
		(start 383.84226 -254.409194)
		(mid 383.655062 -254.359051)
		(end 383.467864 -254.409194)
		(width 0.088646)
		(layer "In11.Cu")
		(net "M_H_CPU0_SA_CA<2>")
	)
	(arc
		(start 378.20346 -254.409194)
		(mid 378.016262 -254.359051)
		(end 377.829064 -254.409194)
		(width 0.088646)
		(layer "In11.Cu")
		(net "M_H_CPU0_SA_CA<2>")
	)
	(arc
		(start 372.180104 -255.051814)
		(mid 371.901672 -254.982)
		(end 371.62486 -255.05791)
		(width 0.088646)
		(layer "In11.Cu")
		(net "M_H_CPU0_SA_CA<2>")
	)
	(arc
		(start 375.38406 -254.409194)
		(mid 375.196862 -254.359051)
		(end 375.009664 -254.409194)
		(width 0.088646)
		(layer "In11.Cu")
		(net "M_H_CPU0_SA_CA<2>")
	)
	(arc
		(start 381.96266 -254.409194)
		(mid 381.775462 -254.359051)
		(end 381.588264 -254.409194)
		(width 0.088646)
		(layer "In11.Cu")
		(net "M_H_CPU0_SA_CA<2>")
	)
	(arc
		(start 376.32386 -254.409194)
		(mid 376.136662 -254.359051)
		(end 375.949464 -254.409194)
		(width 0.088646)
		(layer "In11.Cu")
		(net "M_H_CPU0_SA_CA<2>")
	)
	(arc
		(start 372.564914 -255.05791)
		(mid 372.377716 -255.108053)
		(end 372.190518 -255.05791)
		(width 0.088646)
		(layer "In11.Cu")
		(net "M_H_CPU0_SA_CA<2>")
	)
	(arc
		(start 381.023114 -254.409194)
		(mid 380.835916 -254.359051)
		(end 380.648718 -254.409194)
		(width 0.088646)
		(layer "In11.Cu")
		(net "M_H_CPU0_SA_CA<2>")
	)
	(arc
		(start 374.99925 -254.41529)
		(mid 374.721072 -254.485013)
		(end 374.444514 -254.409194)
		(width 0.088646)
		(layer "In11.Cu")
		(net "M_H_CPU0_SA_CA<2>")
	)
	(segment
		(start 456.116182 -265.316716)
		(end 457.751942 -265.316716)
		(width 0.20066)
		(layer "F.Cu")
		(net "M_H_CPU0_SA_CA<1>")
	)
	(segment
		(start 457.751942 -265.316716)
		(end 458.187552 -265.752326)
		(width 0.20066)
		(layer "F.Cu")
		(net "M_H_CPU0_SA_CA<1>")
	)
	(segment
		(start 458.543152 -265.752326)
		(end 458.55382 -265.741658)
		(width 0.1016)
		(layer "F.Cu")
		(net "M_H_CPU0_SA_CA<1>")
	)
	(segment
		(start 462.54543 -265.316716)
		(end 463.659982 -265.316716)
		(width 0.20066)
		(layer "F.Cu")
		(net "M_H_CPU0_SA_CA<1>")
	)
	(segment
		(start 373.787416 -255.011936)
		(end 373.787416 -255.547622)
		(width 0.20066)
		(layer "F.Cu")
		(net "M_H_CPU0_SA_CA<1>")
	)
	(segment
		(start 460.570326 -265.749024)
		(end 460.844392 -265.749024)
		(width 0.20066)
		(layer "F.Cu")
		(net "M_H_CPU0_SA_CA<1>")
	)
	(segment
		(start 460.56296 -265.741658)
		(end 460.570326 -265.749024)
		(width 0.1016)
		(layer "F.Cu")
		(net "M_H_CPU0_SA_CA<1>")
	)
	(segment
		(start 460.844392 -265.749024)
		(end 461.709262 -264.884154)
		(width 0.20066)
		(layer "F.Cu")
		(net "M_H_CPU0_SA_CA<1>")
	)
	(segment
		(start 458.187552 -265.752326)
		(end 458.538326 -265.752326)
		(width 0.20066)
		(layer "F.Cu")
		(net "M_H_CPU0_SA_CA<1>")
	)
	(segment
		(start 458.55382 -265.741658)
		(end 460.56296 -265.741658)
		(width 0.1016)
		(layer "F.Cu")
		(net "M_H_CPU0_SA_CA<1>")
	)
	(segment
		(start 458.538326 -265.752326)
		(end 458.543152 -265.752326)
		(width 0.101854)
		(layer "F.Cu")
		(net "M_H_CPU0_SA_CA<1>")
	)
	(segment
		(start 462.112868 -264.884154)
		(end 462.54543 -265.316716)
		(width 0.20066)
		(layer "F.Cu")
		(net "M_H_CPU0_SA_CA<1>")
	)
	(segment
		(start 373.787162 -255.011682)
		(end 373.787416 -255.011936)
		(width 0.20066)
		(layer "F.Cu")
		(net "M_H_CPU0_SA_CA<1>")
	)
	(segment
		(start 461.709262 -264.884154)
		(end 462.112868 -264.884154)
		(width 0.20066)
		(layer "F.Cu")
		(net "M_H_CPU0_SA_CA<1>")
	)
	(segment
		(start 455.011282 -265.316716)
		(end 456.116182 -265.316716)
		(width 0.20066)
		(layer "F.Cu")
		(net "M_H_CPU0_SA_CA<1>")
	)
	(segment
		(start 421.80891 -263.02843)
		(end 421.64635 -263.19099)
		(width 0.18288)
		(layer "In11.Cu")
		(net "M_H_CPU0_SA_CA<1>")
	)
	(segment
		(start 435.294278 -263.19099)
		(end 435.173628 -263.31164)
		(width 0.18288)
		(layer "In11.Cu")
		(net "M_H_CPU0_SA_CA<1>")
	)
	(segment
		(start 436.91048 -263.19099)
		(end 435.294278 -263.19099)
		(width 0.18288)
		(layer "In11.Cu")
		(net "M_H_CPU0_SA_CA<1>")
	)
	(segment
		(start 375.868946 -255.2319)
		(end 375.854214 -255.223264)
		(width 0.088646)
		(layer "In11.Cu")
		(net "M_H_CPU0_SA_CA<1>")
	)
	(segment
		(start 411.959298 -263.374886)
		(end 409.309062 -263.374886)
		(width 0.18288)
		(layer "In11.Cu")
		(net "M_H_CPU0_SA_CA<1>")
	)
	(segment
		(start 442.930534 -263.910826)
		(end 440.746642 -263.910826)
		(width 0.18288)
		(layer "In11.Cu")
		(net "M_H_CPU0_SA_CA<1>")
	)
	(segment
		(start 434.162708 -263.31164)
		(end 433.603146 -263.871202)
		(width 0.18288)
		(layer "In11.Cu")
		(net "M_H_CPU0_SA_CA<1>")
	)
	(segment
		(start 373.878348 -255.45669)
		(end 373.787416 -255.547622)
		(width 0.088646)
		(layer "In11.Cu")
		(net "M_H_CPU0_SA_CA<1>")
	)
	(segment
		(start 374.924574 -255.22936)
		(end 374.914668 -255.223264)
		(width 0.088646)
		(layer "In11.Cu")
		(net "M_H_CPU0_SA_CA<1>")
	)
	(segment
		(start 407.398728 -262.96366)
		(end 407.072846 -262.637778)
		(width 0.18288)
		(layer "In11.Cu")
		(net "M_H_CPU0_SA_CA<1>")
	)
	(segment
		(start 377.748546 -255.2319)
		(end 377.733814 -255.223264)
		(width 0.088646)
		(layer "In11.Cu")
		(net "M_H_CPU0_SA_CA<1>")
	)
	(segment
		(start 416.580574 -263.037828)
		(end 412.86557 -263.037828)
		(width 0.18288)
		(layer "In11.Cu")
		(net "M_H_CPU0_SA_CA<1>")
	)
	(segment
		(start 431.54092 -263.871202)
		(end 431.34788 -264.064242)
		(width 0.18288)
		(layer "In11.Cu")
		(net "M_H_CPU0_SA_CA<1>")
	)
	(segment
		(start 449.82638 -265.661648)
		(end 449.173346 -265.661648)
		(width 0.18288)
		(layer "In11.Cu")
		(net "M_H_CPU0_SA_CA<1>")
	)
	(segment
		(start 420.234618 -263.19099)
		(end 420.047928 -263.37768)
		(width 0.18288)
		(layer "In11.Cu")
		(net "M_H_CPU0_SA_CA<1>")
	)
	(segment
		(start 423.262298 -263.02843)
		(end 421.80891 -263.02843)
		(width 0.18288)
		(layer "In11.Cu")
		(net "M_H_CPU0_SA_CA<1>")
	)
	(segment
		(start 386.206746 -255.231646)
		(end 386.192014 -255.22301)
		(width 0.088646)
		(layer "In11.Cu")
		(net "M_H_CPU0_SA_CA<1>")
	)
	(segment
		(start 446.401952 -264.197084)
		(end 443.216792 -264.197084)
		(width 0.18288)
		(layer "In11.Cu")
		(net "M_H_CPU0_SA_CA<1>")
	)
	(segment
		(start 408.897836 -262.96366)
		(end 407.398728 -262.96366)
		(width 0.18288)
		(layer "In11.Cu")
		(net "M_H_CPU0_SA_CA<1>")
	)
	(segment
		(start 450.509386 -266.594844)
		(end 450.170296 -266.255754)
		(width 0.18288)
		(layer "In11.Cu")
		(net "M_H_CPU0_SA_CA<1>")
	)
	(segment
		(start 421.64635 -263.19099)
		(end 420.234618 -263.19099)
		(width 0.18288)
		(layer "In11.Cu")
		(net "M_H_CPU0_SA_CA<1>")
	)
	(segment
		(start 384.877818 -255.22301)
		(end 384.868928 -255.228344)
		(width 0.088646)
		(layer "In11.Cu")
		(net "M_H_CPU0_SA_CA<1>")
	)
	(segment
		(start 380.178818 -255.223264)
		(end 380.164086 -255.2319)
		(width 0.088646)
		(layer "In11.Cu")
		(net "M_H_CPU0_SA_CA<1>")
	)
	(segment
		(start 438.352946 -263.031478)
		(end 437.069992 -263.031478)
		(width 0.18288)
		(layer "In11.Cu")
		(net "M_H_CPU0_SA_CA<1>")
	)
	(segment
		(start 426.219874 -263.843008)
		(end 426.022008 -264.040874)
		(width 0.18288)
		(layer "In11.Cu")
		(net "M_H_CPU0_SA_CA<1>")
	)
	(segment
		(start 388.129018 -255.510284)
		(end 387.437376 -255.510284)
		(width 0.088646)
		(layer "In11.Cu")
		(net "M_H_CPU0_SA_CA<1>")
	)
	(segment
		(start 431.34788 -264.064242)
		(end 427.627542 -264.064242)
		(width 0.18288)
		(layer "In11.Cu")
		(net "M_H_CPU0_SA_CA<1>")
	)
	(segment
		(start 449.173346 -265.661648)
		(end 448.609974 -265.098276)
		(width 0.18288)
		(layer "In11.Cu")
		(net "M_H_CPU0_SA_CA<1>")
	)
	(segment
		(start 374.539764 -255.223264)
		(end 374.52935 -255.22936)
		(width 0.088646)
		(layer "In11.Cu")
		(net "M_H_CPU0_SA_CA<1>")
	)
	(segment
		(start 439.795412 -264.041128)
		(end 439.362596 -264.041128)
		(width 0.18288)
		(layer "In11.Cu")
		(net "M_H_CPU0_SA_CA<1>")
	)
	(segment
		(start 412.712408 -263.19099)
		(end 412.143194 -263.19099)
		(width 0.18288)
		(layer "In11.Cu")
		(net "M_H_CPU0_SA_CA<1>")
	)
	(segment
		(start 412.143194 -263.19099)
		(end 411.959298 -263.374886)
		(width 0.18288)
		(layer "In11.Cu")
		(net "M_H_CPU0_SA_CA<1>")
	)
	(segment
		(start 433.603146 -263.871202)
		(end 431.54092 -263.871202)
		(width 0.18288)
		(layer "In11.Cu")
		(net "M_H_CPU0_SA_CA<1>")
	)
	(segment
		(start 439.795666 -264.040874)
		(end 439.795412 -264.041128)
		(width 0.18288)
		(layer "In11.Cu")
		(net "M_H_CPU0_SA_CA<1>")
	)
	(segment
		(start 448.609974 -265.098276)
		(end 447.303144 -265.098276)
		(width 0.18288)
		(layer "In11.Cu")
		(net "M_H_CPU0_SA_CA<1>")
	)
	(segment
		(start 389.700262 -255.510284)
		(end 388.129018 -255.510284)
		(width 0.18288)
		(layer "In11.Cu")
		(net "M_H_CPU0_SA_CA<1>")
	)
	(segment
		(start 427.406308 -263.843008)
		(end 426.219874 -263.843008)
		(width 0.18288)
		(layer "In11.Cu")
		(net "M_H_CPU0_SA_CA<1>")
	)
	(segment
		(start 455.011282 -265.316716)
		(end 454.503028 -265.82497)
		(width 0.18288)
		(layer "In11.Cu")
		(net "M_H_CPU0_SA_CA<1>")
	)
	(segment
		(start 426.022008 -264.040874)
		(end 424.713146 -264.040874)
		(width 0.18288)
		(layer "In11.Cu")
		(net "M_H_CPU0_SA_CA<1>")
	)
	(segment
		(start 387.437376 -255.510284)
		(end 387.209538 -255.282446)
		(width 0.088646)
		(layer "In11.Cu")
		(net "M_H_CPU0_SA_CA<1>")
	)
	(segment
		(start 381.118364 -255.223264)
		(end 381.10795 -255.22936)
		(width 0.088646)
		(layer "In11.Cu")
		(net "M_H_CPU0_SA_CA<1>")
	)
	(segment
		(start 454.503028 -265.82497)
		(end 452.11492 -265.82497)
		(width 0.18288)
		(layer "In11.Cu")
		(net "M_H_CPU0_SA_CA<1>")
	)
	(segment
		(start 450.170296 -266.005564)
		(end 449.82638 -265.661648)
		(width 0.18288)
		(layer "In11.Cu")
		(net "M_H_CPU0_SA_CA<1>")
	)
	(segment
		(start 420.047928 -263.37768)
		(end 416.920426 -263.37768)
		(width 0.18288)
		(layer "In11.Cu")
		(net "M_H_CPU0_SA_CA<1>")
	)
	(segment
		(start 452.11492 -265.82497)
		(end 451.345046 -266.594844)
		(width 0.18288)
		(layer "In11.Cu")
		(net "M_H_CPU0_SA_CA<1>")
	)
	(segment
		(start 427.627542 -264.064242)
		(end 427.406308 -263.843008)
		(width 0.18288)
		(layer "In11.Cu")
		(net "M_H_CPU0_SA_CA<1>")
	)
	(segment
		(start 451.345046 -266.594844)
		(end 450.509386 -266.594844)
		(width 0.18288)
		(layer "In11.Cu")
		(net "M_H_CPU0_SA_CA<1>")
	)
	(segment
		(start 391.55497 -257.364992)
		(end 389.700262 -255.510284)
		(width 0.18288)
		(layer "In11.Cu")
		(net "M_H_CPU0_SA_CA<1>")
	)
	(segment
		(start 440.616594 -264.040874)
		(end 439.795666 -264.040874)
		(width 0.18288)
		(layer "In11.Cu")
		(net "M_H_CPU0_SA_CA<1>")
	)
	(segment
		(start 400.32051 -257.727704)
		(end 398.17421 -257.727704)
		(width 0.18288)
		(layer "In11.Cu")
		(net "M_H_CPU0_SA_CA<1>")
	)
	(segment
		(start 450.170296 -266.255754)
		(end 450.170296 -266.005564)
		(width 0.18288)
		(layer "In11.Cu")
		(net "M_H_CPU0_SA_CA<1>")
	)
	(segment
		(start 447.303144 -265.098276)
		(end 446.401952 -264.197084)
		(width 0.18288)
		(layer "In11.Cu")
		(net "M_H_CPU0_SA_CA<1>")
	)
	(segment
		(start 376.808746 -255.2319)
		(end 376.794014 -255.223264)
		(width 0.088646)
		(layer "In11.Cu")
		(net "M_H_CPU0_SA_CA<1>")
	)
	(segment
		(start 382.443228 -255.22936)
		(end 382.432814 -255.223264)
		(width 0.088646)
		(layer "In11.Cu")
		(net "M_H_CPU0_SA_CA<1>")
	)
	(segment
		(start 424.712892 -264.041128)
		(end 424.274996 -264.041128)
		(width 0.18288)
		(layer "In11.Cu")
		(net "M_H_CPU0_SA_CA<1>")
	)
	(segment
		(start 381.503174 -255.22936)
		(end 381.49276 -255.223264)
		(width 0.088646)
		(layer "In11.Cu")
		(net "M_H_CPU0_SA_CA<1>")
	)
	(segment
		(start 443.216792 -264.197084)
		(end 442.930534 -263.910826)
		(width 0.18288)
		(layer "In11.Cu")
		(net "M_H_CPU0_SA_CA<1>")
	)
	(segment
		(start 385.266946 -255.231646)
		(end 385.252214 -255.22301)
		(width 0.088646)
		(layer "In11.Cu")
		(net "M_H_CPU0_SA_CA<1>")
	)
	(segment
		(start 409.309062 -263.374886)
		(end 408.897836 -262.96366)
		(width 0.18288)
		(layer "In11.Cu")
		(net "M_H_CPU0_SA_CA<1>")
	)
	(segment
		(start 407.072846 -262.637778)
		(end 405.230584 -262.637778)
		(width 0.18288)
		(layer "In11.Cu")
		(net "M_H_CPU0_SA_CA<1>")
	)
	(segment
		(start 439.362596 -264.041128)
		(end 438.352946 -263.031478)
		(width 0.18288)
		(layer "In11.Cu")
		(net "M_H_CPU0_SA_CA<1>")
	)
	(segment
		(start 435.173628 -263.31164)
		(end 434.162708 -263.31164)
		(width 0.18288)
		(layer "In11.Cu")
		(net "M_H_CPU0_SA_CA<1>")
	)
	(segment
		(start 440.746642 -263.910826)
		(end 440.616594 -264.040874)
		(width 0.18288)
		(layer "In11.Cu")
		(net "M_H_CPU0_SA_CA<1>")
	)
	(segment
		(start 397.811498 -257.364992)
		(end 391.55497 -257.364992)
		(width 0.18288)
		(layer "In11.Cu")
		(net "M_H_CPU0_SA_CA<1>")
	)
	(segment
		(start 424.713146 -264.040874)
		(end 424.712892 -264.041128)
		(width 0.18288)
		(layer "In11.Cu")
		(net "M_H_CPU0_SA_CA<1>")
	)
	(segment
		(start 412.86557 -263.037828)
		(end 412.712408 -263.19099)
		(width 0.18288)
		(layer "In11.Cu")
		(net "M_H_CPU0_SA_CA<1>")
	)
	(segment
		(start 398.17421 -257.727704)
		(end 397.811498 -257.364992)
		(width 0.18288)
		(layer "In11.Cu")
		(net "M_H_CPU0_SA_CA<1>")
	)
	(segment
		(start 405.230584 -262.637778)
		(end 400.32051 -257.727704)
		(width 0.18288)
		(layer "In11.Cu")
		(net "M_H_CPU0_SA_CA<1>")
	)
	(segment
		(start 378.688346 -255.2319)
		(end 378.673614 -255.223264)
		(width 0.088646)
		(layer "In11.Cu")
		(net "M_H_CPU0_SA_CA<1>")
	)
	(segment
		(start 437.069992 -263.031478)
		(end 436.91048 -263.19099)
		(width 0.18288)
		(layer "In11.Cu")
		(net "M_H_CPU0_SA_CA<1>")
	)
	(segment
		(start 424.274996 -264.041128)
		(end 423.262298 -263.02843)
		(width 0.18288)
		(layer "In11.Cu")
		(net "M_H_CPU0_SA_CA<1>")
	)
	(segment
		(start 416.920426 -263.37768)
		(end 416.580574 -263.037828)
		(width 0.18288)
		(layer "In11.Cu")
		(net "M_H_CPU0_SA_CA<1>")
	)
	(arc
		(start 374.259094 -255.298956)
		(mid 374.053027 -255.339945)
		(end 373.878348 -255.45669)
		(width 0.088646)
		(layer "In11.Cu")
		(net "M_H_CPU0_SA_CA<1>")
	)
	(arc
		(start 385.817618 -255.22301)
		(mid 385.543419 -255.298845)
		(end 385.266946 -255.231646)
		(width 0.088646)
		(layer "In11.Cu")
		(net "M_H_CPU0_SA_CA<1>")
	)
	(arc
		(start 375.854214 -255.223264)
		(mid 375.667016 -255.173121)
		(end 375.479818 -255.223264)
		(width 0.088646)
		(layer "In11.Cu")
		(net "M_H_CPU0_SA_CA<1>")
	)
	(arc
		(start 386.757418 -255.22301)
		(mid 386.483219 -255.298845)
		(end 386.206746 -255.231646)
		(width 0.088646)
		(layer "In11.Cu")
		(net "M_H_CPU0_SA_CA<1>")
	)
	(arc
		(start 387.209538 -255.282446)
		(mid 387.172628 -255.250175)
		(end 387.131814 -255.22301)
		(width 0.088646)
		(layer "In11.Cu")
		(net "M_H_CPU0_SA_CA<1>")
	)
	(arc
		(start 381.10795 -255.22936)
		(mid 380.829772 -255.299052)
		(end 380.553214 -255.223264)
		(width 0.088646)
		(layer "In11.Cu")
		(net "M_H_CPU0_SA_CA<1>")
	)
	(arc
		(start 383.937764 -255.223264)
		(mid 383.655062 -255.299006)
		(end 383.37236 -255.223264)
		(width 0.088646)
		(layer "In11.Cu")
		(net "M_H_CPU0_SA_CA<1>")
	)
	(arc
		(start 379.239018 -255.223264)
		(mid 378.964789 -255.299189)
		(end 378.688346 -255.2319)
		(width 0.088646)
		(layer "In11.Cu")
		(net "M_H_CPU0_SA_CA<1>")
	)
	(arc
		(start 384.868928 -255.228344)
		(mid 384.589886 -255.299029)
		(end 384.31216 -255.223264)
		(width 0.088646)
		(layer "In11.Cu")
		(net "M_H_CPU0_SA_CA<1>")
	)
	(arc
		(start 384.31216 -255.223264)
		(mid 384.124962 -255.173121)
		(end 383.937764 -255.223264)
		(width 0.088646)
		(layer "In11.Cu")
		(net "M_H_CPU0_SA_CA<1>")
	)
	(arc
		(start 382.058418 -255.223264)
		(mid 381.781605 -255.2991)
		(end 381.503174 -255.22936)
		(width 0.088646)
		(layer "In11.Cu")
		(net "M_H_CPU0_SA_CA<1>")
	)
	(arc
		(start 374.52935 -255.22936)
		(mid 374.398584 -255.281097)
		(end 374.259094 -255.298956)
		(width 0.088646)
		(layer "In11.Cu")
		(net "M_H_CPU0_SA_CA<1>")
	)
	(arc
		(start 378.673614 -255.223264)
		(mid 378.486416 -255.173121)
		(end 378.299218 -255.223264)
		(width 0.088646)
		(layer "In11.Cu")
		(net "M_H_CPU0_SA_CA<1>")
	)
	(arc
		(start 380.164086 -255.2319)
		(mid 379.887645 -255.299066)
		(end 379.613414 -255.223264)
		(width 0.088646)
		(layer "In11.Cu")
		(net "M_H_CPU0_SA_CA<1>")
	)
	(arc
		(start 383.37236 -255.223264)
		(mid 383.185162 -255.173121)
		(end 382.997964 -255.223264)
		(width 0.088646)
		(layer "In11.Cu")
		(net "M_H_CPU0_SA_CA<1>")
	)
	(arc
		(start 379.613414 -255.223264)
		(mid 379.426216 -255.173121)
		(end 379.239018 -255.223264)
		(width 0.088646)
		(layer "In11.Cu")
		(net "M_H_CPU0_SA_CA<1>")
	)
	(arc
		(start 374.914668 -255.223264)
		(mid 374.727216 -255.172994)
		(end 374.539764 -255.223264)
		(width 0.088646)
		(layer "In11.Cu")
		(net "M_H_CPU0_SA_CA<1>")
	)
	(arc
		(start 382.997964 -255.223264)
		(mid 382.721405 -255.298973)
		(end 382.443228 -255.22936)
		(width 0.088646)
		(layer "In11.Cu")
		(net "M_H_CPU0_SA_CA<1>")
	)
	(arc
		(start 381.49276 -255.223264)
		(mid 381.305562 -255.173121)
		(end 381.118364 -255.223264)
		(width 0.088646)
		(layer "In11.Cu")
		(net "M_H_CPU0_SA_CA<1>")
	)
	(arc
		(start 378.299218 -255.223264)
		(mid 378.024989 -255.299189)
		(end 377.748546 -255.2319)
		(width 0.088646)
		(layer "In11.Cu")
		(net "M_H_CPU0_SA_CA<1>")
	)
	(arc
		(start 386.192014 -255.22301)
		(mid 386.004816 -255.172867)
		(end 385.817618 -255.22301)
		(width 0.088646)
		(layer "In11.Cu")
		(net "M_H_CPU0_SA_CA<1>")
	)
	(arc
		(start 377.733814 -255.223264)
		(mid 377.546616 -255.173121)
		(end 377.359418 -255.223264)
		(width 0.088646)
		(layer "In11.Cu")
		(net "M_H_CPU0_SA_CA<1>")
	)
	(arc
		(start 387.131814 -255.22301)
		(mid 386.944616 -255.172867)
		(end 386.757418 -255.22301)
		(width 0.088646)
		(layer "In11.Cu")
		(net "M_H_CPU0_SA_CA<1>")
	)
	(arc
		(start 380.553214 -255.223264)
		(mid 380.366016 -255.173121)
		(end 380.178818 -255.223264)
		(width 0.088646)
		(layer "In11.Cu")
		(net "M_H_CPU0_SA_CA<1>")
	)
	(arc
		(start 376.419618 -255.223264)
		(mid 376.145389 -255.299189)
		(end 375.868946 -255.2319)
		(width 0.088646)
		(layer "In11.Cu")
		(net "M_H_CPU0_SA_CA<1>")
	)
	(arc
		(start 375.479818 -255.223264)
		(mid 375.203005 -255.2991)
		(end 374.924574 -255.22936)
		(width 0.088646)
		(layer "In11.Cu")
		(net "M_H_CPU0_SA_CA<1>")
	)
	(arc
		(start 377.359418 -255.223264)
		(mid 377.085189 -255.299189)
		(end 376.808746 -255.2319)
		(width 0.088646)
		(layer "In11.Cu")
		(net "M_H_CPU0_SA_CA<1>")
	)
	(arc
		(start 382.432814 -255.223264)
		(mid 382.245616 -255.173121)
		(end 382.058418 -255.223264)
		(width 0.088646)
		(layer "In11.Cu")
		(net "M_H_CPU0_SA_CA<1>")
	)
	(arc
		(start 376.794014 -255.223264)
		(mid 376.606816 -255.173121)
		(end 376.419618 -255.223264)
		(width 0.088646)
		(layer "In11.Cu")
		(net "M_H_CPU0_SA_CA<1>")
	)
	(arc
		(start 385.252214 -255.22301)
		(mid 385.065016 -255.172867)
		(end 384.877818 -255.22301)
		(width 0.088646)
		(layer "In11.Cu")
		(net "M_H_CPU0_SA_CA<1>")
	)
	(segment
		(start 453.437244 -265.672316)
		(end 453.759062 -265.672316)
		(width 0.20066)
		(layer "F.Cu")
		(net "M_H_CPU0_SA_CA<0>")
	)
	(segment
		(start 454.678288 -266.591542)
		(end 454.833736 -266.591542)
		(width 0.20066)
		(layer "F.Cu")
		(net "M_H_CPU0_SA_CA<0>")
	)
	(segment
		(start 457.980288 -266.166346)
		(end 459.55966 -266.166346)
		(width 0.20066)
		(layer "F.Cu")
		(net "M_H_CPU0_SA_CA<0>")
	)
	(segment
		(start 459.55966 -266.166346)
		(end 459.559914 -266.1666)
		(width 0.20066)
		(layer "F.Cu")
		(net "M_H_CPU0_SA_CA<0>")
	)
	(segment
		(start 450.911214 -266.1666)
		(end 452.016114 -266.1666)
		(width 0.20066)
		(layer "F.Cu")
		(net "M_H_CPU0_SA_CA<0>")
	)
	(segment
		(start 457.126594 -266.603988)
		(end 457.542646 -266.603988)
		(width 0.20066)
		(layer "F.Cu")
		(net "M_H_CPU0_SA_CA<0>")
	)
	(segment
		(start 452.94296 -266.1666)
		(end 453.437244 -265.672316)
		(width 0.20066)
		(layer "F.Cu")
		(net "M_H_CPU0_SA_CA<0>")
	)
	(segment
		(start 453.759062 -265.672316)
		(end 454.678288 -266.591542)
		(width 0.20066)
		(layer "F.Cu")
		(net "M_H_CPU0_SA_CA<0>")
	)
	(segment
		(start 454.833736 -266.591542)
		(end 454.854818 -266.591542)
		(width 0.101854)
		(layer "F.Cu")
		(net "M_H_CPU0_SA_CA<0>")
	)
	(segment
		(start 457.542646 -266.603988)
		(end 457.980288 -266.166346)
		(width 0.20066)
		(layer "F.Cu")
		(net "M_H_CPU0_SA_CA<0>")
	)
	(segment
		(start 457.114148 -266.591542)
		(end 457.126594 -266.603988)
		(width 0.1016)
		(layer "F.Cu")
		(net "M_H_CPU0_SA_CA<0>")
	)
	(segment
		(start 452.016114 -266.1666)
		(end 452.94296 -266.1666)
		(width 0.20066)
		(layer "F.Cu")
		(net "M_H_CPU0_SA_CA<0>")
	)
	(segment
		(start 454.854818 -266.591542)
		(end 457.114148 -266.591542)
		(width 0.1016)
		(layer "F.Cu")
		(net "M_H_CPU0_SA_CA<0>")
	)
	(segment
		(start 370.967762 -255.547368)
		(end 370.968016 -255.547622)
		(width 0.20066)
		(layer "F.Cu")
		(net "M_H_CPU0_SA_CA<0>")
	)
	(segment
		(start 370.967762 -255.011682)
		(end 370.967762 -255.547368)
		(width 0.20066)
		(layer "F.Cu")
		(net "M_H_CPU0_SA_CA<0>")
	)
	(segment
		(start 427.595284 -263.322816)
		(end 425.987464 -263.322816)
		(width 0.18288)
		(layer "In11.Cu")
		(net "M_H_CPU0_SA_CA<0>")
	)
	(segment
		(start 416.884358 -262.18515)
		(end 416.54857 -262.520938)
		(width 0.18288)
		(layer "In11.Cu")
		(net "M_H_CPU0_SA_CA<0>")
	)
	(segment
		(start 433.926996 -262.130794)
		(end 432.71059 -263.3472)
		(width 0.18288)
		(layer "In11.Cu")
		(net "M_H_CPU0_SA_CA<0>")
	)
	(segment
		(start 409.288234 -262.36168)
		(end 407.609548 -262.36168)
		(width 0.18288)
		(layer "In11.Cu")
		(net "M_H_CPU0_SA_CA<0>")
	)
	(segment
		(start 450.911214 -266.1666)
		(end 450.911214 -266.018772)
		(width 0.18288)
		(layer "In11.Cu")
		(net "M_H_CPU0_SA_CA<0>")
	)
	(segment
		(start 421.6908 -262.512302)
		(end 421.51935 -262.340852)
		(width 0.18288)
		(layer "In11.Cu")
		(net "M_H_CPU0_SA_CA<0>")
	)
	(segment
		(start 382.528064 -255.05791)
		(end 382.513332 -255.049274)
		(width 0.088646)
		(layer "In11.Cu")
		(net "M_H_CPU0_SA_CA<0>")
	)
	(segment
		(start 423.53357 -262.512302)
		(end 421.6908 -262.512302)
		(width 0.18288)
		(layer "In11.Cu")
		(net "M_H_CPU0_SA_CA<0>")
	)
	(segment
		(start 406.62352 -261.375652)
		(end 404.705058 -261.375652)
		(width 0.18288)
		(layer "In11.Cu")
		(net "M_H_CPU0_SA_CA<0>")
	)
	(segment
		(start 376.889264 -255.05791)
		(end 376.874532 -255.049274)
		(width 0.088646)
		(layer "In11.Cu")
		(net "M_H_CPU0_SA_CA<0>")
	)
	(segment
		(start 432.71059 -263.3472)
		(end 431.985674 -263.3472)
		(width 0.18288)
		(layer "In11.Cu")
		(net "M_H_CPU0_SA_CA<0>")
	)
	(segment
		(start 448.206114 -263.938258)
		(end 446.988438 -263.938258)
		(width 0.18288)
		(layer "In11.Cu")
		(net "M_H_CPU0_SA_CA<0>")
	)
	(segment
		(start 372.660164 -255.223264)
		(end 372.64975 -255.22936)
		(width 0.088646)
		(layer "In11.Cu")
		(net "M_H_CPU0_SA_CA<0>")
	)
	(segment
		(start 380.093982 -255.051814)
		(end 380.083568 -255.05791)
		(width 0.088646)
		(layer "In11.Cu")
		(net "M_H_CPU0_SA_CA<0>")
	)
	(segment
		(start 412.201868 -262.187182)
		(end 409.462732 -262.187182)
		(width 0.18288)
		(layer "In11.Cu")
		(net "M_H_CPU0_SA_CA<0>")
	)
	(segment
		(start 388.129018 -255.147572)
		(end 387.344158 -255.147572)
		(width 0.088646)
		(layer "In11.Cu")
		(net "M_H_CPU0_SA_CA<0>")
	)
	(segment
		(start 440.5376 -263.19099)
		(end 439.299858 -263.19099)
		(width 0.18288)
		(layer "In11.Cu")
		(net "M_H_CPU0_SA_CA<0>")
	)
	(segment
		(start 450.848222 -265.866626)
		(end 450.117718 -265.136122)
		(width 0.18288)
		(layer "In11.Cu")
		(net "M_H_CPU0_SA_CA<0>")
	)
	(segment
		(start 387.227064 -255.05791)
		(end 387.212332 -255.049274)
		(width 0.088646)
		(layer "In11.Cu")
		(net "M_H_CPU0_SA_CA<0>")
	)
	(segment
		(start 385.347464 -255.05791)
		(end 385.332732 -255.049274)
		(width 0.088646)
		(layer "In11.Cu")
		(net "M_H_CPU0_SA_CA<0>")
	)
	(segment
		(start 442.789564 -263.38911)
		(end 440.73572 -263.38911)
		(width 0.18288)
		(layer "In11.Cu")
		(net "M_H_CPU0_SA_CA<0>")
	)
	(segment
		(start 398.197832 -257.014726)
		(end 391.69467 -257.014726)
		(width 0.18288)
		(layer "In11.Cu")
		(net "M_H_CPU0_SA_CA<0>")
	)
	(segment
		(start 431.608992 -262.970518)
		(end 427.947582 -262.970518)
		(width 0.18288)
		(layer "In11.Cu")
		(net "M_H_CPU0_SA_CA<0>")
	)
	(segment
		(start 371.21338 -255.252982)
		(end 371.12448 -255.276604)
		(width 0.088646)
		(layer "In11.Cu")
		(net "M_H_CPU0_SA_CA<0>")
	)
	(segment
		(start 386.287264 -255.05791)
		(end 386.272532 -255.049274)
		(width 0.088646)
		(layer "In11.Cu")
		(net "M_H_CPU0_SA_CA<0>")
	)
	(segment
		(start 449.403978 -265.136122)
		(end 448.206114 -263.938258)
		(width 0.18288)
		(layer "In11.Cu")
		(net "M_H_CPU0_SA_CA<0>")
	)
	(segment
		(start 439.299858 -263.19099)
		(end 438.624218 -262.51535)
		(width 0.18288)
		(layer "In11.Cu")
		(net "M_H_CPU0_SA_CA<0>")
	)
	(segment
		(start 389.827516 -255.147572)
		(end 388.129018 -255.147572)
		(width 0.18288)
		(layer "In11.Cu")
		(net "M_H_CPU0_SA_CA<0>")
	)
	(segment
		(start 391.69467 -257.014726)
		(end 389.827516 -255.147572)
		(width 0.18288)
		(layer "In11.Cu")
		(net "M_H_CPU0_SA_CA<0>")
	)
	(segment
		(start 379.697996 -255.051306)
		(end 379.693932 -255.049274)
		(width 0.088646)
		(layer "In11.Cu")
		(net "M_H_CPU0_SA_CA<0>")
	)
	(segment
		(start 374.454928 -255.051814)
		(end 374.444514 -255.05791)
		(width 0.088646)
		(layer "In11.Cu")
		(net "M_H_CPU0_SA_CA<0>")
	)
	(segment
		(start 416.54857 -262.520938)
		(end 412.535624 -262.520938)
		(width 0.18288)
		(layer "In11.Cu")
		(net "M_H_CPU0_SA_CA<0>")
	)
	(segment
		(start 379.709172 -255.05791)
		(end 379.697996 -255.051306)
		(width 0.088646)
		(layer "In11.Cu")
		(net "M_H_CPU0_SA_CA<0>")
	)
	(segment
		(start 420.119048 -262.18515)
		(end 416.884358 -262.18515)
		(width 0.18288)
		(layer "In11.Cu")
		(net "M_H_CPU0_SA_CA<0>")
	)
	(segment
		(start 421.51935 -262.340852)
		(end 420.27475 -262.340852)
		(width 0.18288)
		(layer "In11.Cu")
		(net "M_H_CPU0_SA_CA<0>")
	)
	(segment
		(start 446.070736 -263.020556)
		(end 443.158118 -263.020556)
		(width 0.18288)
		(layer "In11.Cu")
		(net "M_H_CPU0_SA_CA<0>")
	)
	(segment
		(start 377.829064 -255.05791)
		(end 377.814332 -255.049274)
		(width 0.088646)
		(layer "In11.Cu")
		(net "M_H_CPU0_SA_CA<0>")
	)
	(segment
		(start 374.070118 -255.05791)
		(end 373.88546 -255.05791)
		(width 0.088646)
		(layer "In11.Cu")
		(net "M_H_CPU0_SA_CA<0>")
	)
	(segment
		(start 443.158118 -263.020556)
		(end 442.789564 -263.38911)
		(width 0.18288)
		(layer "In11.Cu")
		(net "M_H_CPU0_SA_CA<0>")
	)
	(segment
		(start 438.624218 -262.51535)
		(end 436.982616 -262.51535)
		(width 0.18288)
		(layer "In11.Cu")
		(net "M_H_CPU0_SA_CA<0>")
	)
	(segment
		(start 450.911214 -266.018772)
		(end 450.848222 -265.866626)
		(width 0.18288)
		(layer "In11.Cu")
		(net "M_H_CPU0_SA_CA<0>")
	)
	(segment
		(start 400.547078 -257.217672)
		(end 398.400778 -257.217672)
		(width 0.18288)
		(layer "In11.Cu")
		(net "M_H_CPU0_SA_CA<0>")
	)
	(segment
		(start 450.117718 -265.136122)
		(end 449.403978 -265.136122)
		(width 0.18288)
		(layer "In11.Cu")
		(net "M_H_CPU0_SA_CA<0>")
	)
	(segment
		(start 427.947582 -262.970518)
		(end 427.595284 -263.322816)
		(width 0.18288)
		(layer "In11.Cu")
		(net "M_H_CPU0_SA_CA<0>")
	)
	(segment
		(start 425.855638 -263.19099)
		(end 424.212258 -263.19099)
		(width 0.18288)
		(layer "In11.Cu")
		(net "M_H_CPU0_SA_CA<0>")
	)
	(segment
		(start 440.73572 -263.38911)
		(end 440.5376 -263.19099)
		(width 0.18288)
		(layer "In11.Cu")
		(net "M_H_CPU0_SA_CA<0>")
	)
	(segment
		(start 420.27475 -262.340852)
		(end 420.119048 -262.18515)
		(width 0.18288)
		(layer "In11.Cu")
		(net "M_H_CPU0_SA_CA<0>")
	)
	(segment
		(start 378.768864 -255.05791)
		(end 378.754132 -255.049274)
		(width 0.088646)
		(layer "In11.Cu")
		(net "M_H_CPU0_SA_CA<0>")
	)
	(segment
		(start 381.033528 -255.051814)
		(end 381.023114 -255.05791)
		(width 0.088646)
		(layer "In11.Cu")
		(net "M_H_CPU0_SA_CA<0>")
	)
	(segment
		(start 371.12448 -255.276604)
		(end 370.968016 -255.547622)
		(width 0.088646)
		(layer "In11.Cu")
		(net "M_H_CPU0_SA_CA<0>")
	)
	(segment
		(start 373.044974 -255.22936)
		(end 373.03456 -255.223264)
		(width 0.088646)
		(layer "In11.Cu")
		(net "M_H_CPU0_SA_CA<0>")
	)
	(segment
		(start 446.988438 -263.938258)
		(end 446.070736 -263.020556)
		(width 0.18288)
		(layer "In11.Cu")
		(net "M_H_CPU0_SA_CA<0>")
	)
	(segment
		(start 436.808118 -262.340852)
		(end 435.499764 -262.340852)
		(width 0.18288)
		(layer "In11.Cu")
		(net "M_H_CPU0_SA_CA<0>")
	)
	(segment
		(start 424.212258 -263.19099)
		(end 423.53357 -262.512302)
		(width 0.18288)
		(layer "In11.Cu")
		(net "M_H_CPU0_SA_CA<0>")
	)
	(segment
		(start 373.88546 -255.05791)
		(end 373.600218 -255.223264)
		(width 0.088646)
		(layer "In11.Cu")
		(net "M_H_CPU0_SA_CA<0>")
	)
	(segment
		(start 425.987464 -263.322816)
		(end 425.855638 -263.19099)
		(width 0.18288)
		(layer "In11.Cu")
		(net "M_H_CPU0_SA_CA<0>")
	)
	(segment
		(start 398.400778 -257.217672)
		(end 398.197832 -257.014726)
		(width 0.18288)
		(layer "In11.Cu")
		(net "M_H_CPU0_SA_CA<0>")
	)
	(segment
		(start 412.535624 -262.520938)
		(end 412.201868 -262.187182)
		(width 0.18288)
		(layer "In11.Cu")
		(net "M_H_CPU0_SA_CA<0>")
	)
	(segment
		(start 435.499764 -262.340852)
		(end 435.289706 -262.130794)
		(width 0.18288)
		(layer "In11.Cu")
		(net "M_H_CPU0_SA_CA<0>")
	)
	(segment
		(start 436.982616 -262.51535)
		(end 436.808118 -262.340852)
		(width 0.18288)
		(layer "In11.Cu")
		(net "M_H_CPU0_SA_CA<0>")
	)
	(segment
		(start 435.289706 -262.130794)
		(end 433.926996 -262.130794)
		(width 0.18288)
		(layer "In11.Cu")
		(net "M_H_CPU0_SA_CA<0>")
	)
	(segment
		(start 375.949464 -255.05791)
		(end 375.934732 -255.049274)
		(width 0.088646)
		(layer "In11.Cu")
		(net "M_H_CPU0_SA_CA<0>")
	)
	(segment
		(start 407.609548 -262.36168)
		(end 406.62352 -261.375652)
		(width 0.18288)
		(layer "In11.Cu")
		(net "M_H_CPU0_SA_CA<0>")
	)
	(segment
		(start 431.985674 -263.3472)
		(end 431.608992 -262.970518)
		(width 0.18288)
		(layer "In11.Cu")
		(net "M_H_CPU0_SA_CA<0>")
	)
	(segment
		(start 404.705058 -261.375652)
		(end 400.547078 -257.217672)
		(width 0.18288)
		(layer "In11.Cu")
		(net "M_H_CPU0_SA_CA<0>")
	)
	(segment
		(start 409.462732 -262.187182)
		(end 409.288234 -262.36168)
		(width 0.18288)
		(layer "In11.Cu")
		(net "M_H_CPU0_SA_CA<0>")
	)
	(arc
		(start 376.874532 -255.049274)
		(mid 376.598091 -254.982108)
		(end 376.32386 -255.05791)
		(width 0.088646)
		(layer "In11.Cu")
		(net "M_H_CPU0_SA_CA<0>")
	)
	(arc
		(start 373.600218 -255.223264)
		(mid 373.323405 -255.2991)
		(end 373.044974 -255.22936)
		(width 0.088646)
		(layer "In11.Cu")
		(net "M_H_CPU0_SA_CA<0>")
	)
	(arc
		(start 375.934732 -255.049274)
		(mid 375.658291 -254.982108)
		(end 375.38406 -255.05791)
		(width 0.088646)
		(layer "In11.Cu")
		(net "M_H_CPU0_SA_CA<0>")
	)
	(arc
		(start 375.38406 -255.05791)
		(mid 375.196862 -255.108053)
		(end 375.009664 -255.05791)
		(width 0.088646)
		(layer "In11.Cu")
		(net "M_H_CPU0_SA_CA<0>")
	)
	(arc
		(start 387.344158 -255.147572)
		(mid 387.288553 -255.098898)
		(end 387.227064 -255.05791)
		(width 0.088646)
		(layer "In11.Cu")
		(net "M_H_CPU0_SA_CA<0>")
	)
	(arc
		(start 372.64975 -255.22936)
		(mid 372.371572 -255.299052)
		(end 372.095014 -255.223264)
		(width 0.088646)
		(layer "In11.Cu")
		(net "M_H_CPU0_SA_CA<0>")
	)
	(arc
		(start 378.754132 -255.049274)
		(mid 378.477691 -254.982108)
		(end 378.20346 -255.05791)
		(width 0.088646)
		(layer "In11.Cu")
		(net "M_H_CPU0_SA_CA<0>")
	)
	(arc
		(start 381.96266 -255.05791)
		(mid 381.775462 -255.108053)
		(end 381.588264 -255.05791)
		(width 0.088646)
		(layer "In11.Cu")
		(net "M_H_CPU0_SA_CA<0>")
	)
	(arc
		(start 385.332732 -255.049274)
		(mid 385.056257 -254.981954)
		(end 384.78206 -255.05791)
		(width 0.088646)
		(layer "In11.Cu")
		(net "M_H_CPU0_SA_CA<0>")
	)
	(arc
		(start 386.272532 -255.049274)
		(mid 385.996057 -254.981954)
		(end 385.72186 -255.05791)
		(width 0.088646)
		(layer "In11.Cu")
		(net "M_H_CPU0_SA_CA<0>")
	)
	(arc
		(start 384.78206 -255.05791)
		(mid 384.594862 -255.108053)
		(end 384.407664 -255.05791)
		(width 0.088646)
		(layer "In11.Cu")
		(net "M_H_CPU0_SA_CA<0>")
	)
	(arc
		(start 377.814332 -255.049274)
		(mid 377.537891 -254.982108)
		(end 377.26366 -255.05791)
		(width 0.088646)
		(layer "In11.Cu")
		(net "M_H_CPU0_SA_CA<0>")
	)
	(arc
		(start 371.720618 -255.223264)
		(mid 371.470521 -255.29829)
		(end 371.21338 -255.252982)
		(width 0.088646)
		(layer "In11.Cu")
		(net "M_H_CPU0_SA_CA<0>")
	)
	(arc
		(start 382.90246 -255.05791)
		(mid 382.715262 -255.108053)
		(end 382.528064 -255.05791)
		(width 0.088646)
		(layer "In11.Cu")
		(net "M_H_CPU0_SA_CA<0>")
	)
	(arc
		(start 377.26366 -255.05791)
		(mid 377.076462 -255.108053)
		(end 376.889264 -255.05791)
		(width 0.088646)
		(layer "In11.Cu")
		(net "M_H_CPU0_SA_CA<0>")
	)
	(arc
		(start 375.009664 -255.05791)
		(mid 374.733105 -254.982201)
		(end 374.454928 -255.051814)
		(width 0.088646)
		(layer "In11.Cu")
		(net "M_H_CPU0_SA_CA<0>")
	)
	(arc
		(start 379.693932 -255.049274)
		(mid 379.417491 -254.982108)
		(end 379.14326 -255.05791)
		(width 0.088646)
		(layer "In11.Cu")
		(net "M_H_CPU0_SA_CA<0>")
	)
	(arc
		(start 381.588264 -255.05791)
		(mid 381.311705 -254.982201)
		(end 381.033528 -255.051814)
		(width 0.088646)
		(layer "In11.Cu")
		(net "M_H_CPU0_SA_CA<0>")
	)
	(arc
		(start 376.32386 -255.05791)
		(mid 376.136662 -255.108053)
		(end 375.949464 -255.05791)
		(width 0.088646)
		(layer "In11.Cu")
		(net "M_H_CPU0_SA_CA<0>")
	)
	(arc
		(start 384.407664 -255.05791)
		(mid 384.124962 -254.982168)
		(end 383.84226 -255.05791)
		(width 0.088646)
		(layer "In11.Cu")
		(net "M_H_CPU0_SA_CA<0>")
	)
	(arc
		(start 380.648718 -255.05791)
		(mid 380.372159 -254.982201)
		(end 380.093982 -255.051814)
		(width 0.088646)
		(layer "In11.Cu")
		(net "M_H_CPU0_SA_CA<0>")
	)
	(arc
		(start 378.20346 -255.05791)
		(mid 378.016262 -255.108053)
		(end 377.829064 -255.05791)
		(width 0.088646)
		(layer "In11.Cu")
		(net "M_H_CPU0_SA_CA<0>")
	)
	(arc
		(start 381.023114 -255.05791)
		(mid 380.835916 -255.108053)
		(end 380.648718 -255.05791)
		(width 0.088646)
		(layer "In11.Cu")
		(net "M_H_CPU0_SA_CA<0>")
	)
	(arc
		(start 374.444514 -255.05791)
		(mid 374.257316 -255.108053)
		(end 374.070118 -255.05791)
		(width 0.088646)
		(layer "In11.Cu")
		(net "M_H_CPU0_SA_CA<0>")
	)
	(arc
		(start 383.84226 -255.05791)
		(mid 383.655062 -255.108053)
		(end 383.467864 -255.05791)
		(width 0.088646)
		(layer "In11.Cu")
		(net "M_H_CPU0_SA_CA<0>")
	)
	(arc
		(start 380.083568 -255.05791)
		(mid 379.89637 -255.108053)
		(end 379.709172 -255.05791)
		(width 0.088646)
		(layer "In11.Cu")
		(net "M_H_CPU0_SA_CA<0>")
	)
	(arc
		(start 379.14326 -255.05791)
		(mid 378.956062 -255.108053)
		(end 378.768864 -255.05791)
		(width 0.088646)
		(layer "In11.Cu")
		(net "M_H_CPU0_SA_CA<0>")
	)
	(arc
		(start 385.72186 -255.05791)
		(mid 385.534662 -255.108053)
		(end 385.347464 -255.05791)
		(width 0.088646)
		(layer "In11.Cu")
		(net "M_H_CPU0_SA_CA<0>")
	)
	(arc
		(start 387.212332 -255.049274)
		(mid 386.935857 -254.981954)
		(end 386.66166 -255.05791)
		(width 0.088646)
		(layer "In11.Cu")
		(net "M_H_CPU0_SA_CA<0>")
	)
	(arc
		(start 382.513332 -255.049274)
		(mid 382.236891 -254.982108)
		(end 381.96266 -255.05791)
		(width 0.088646)
		(layer "In11.Cu")
		(net "M_H_CPU0_SA_CA<0>")
	)
	(arc
		(start 372.095014 -255.223264)
		(mid 371.907816 -255.173121)
		(end 371.720618 -255.223264)
		(width 0.088646)
		(layer "In11.Cu")
		(net "M_H_CPU0_SA_CA<0>")
	)
	(arc
		(start 373.03456 -255.223264)
		(mid 372.847362 -255.173121)
		(end 372.660164 -255.223264)
		(width 0.088646)
		(layer "In11.Cu")
		(net "M_H_CPU0_SA_CA<0>")
	)
	(arc
		(start 386.66166 -255.05791)
		(mid 386.474462 -255.108053)
		(end 386.287264 -255.05791)
		(width 0.088646)
		(layer "In11.Cu")
		(net "M_H_CPU0_SA_CA<0>")
	)
	(arc
		(start 383.467864 -255.05791)
		(mid 383.185162 -254.982168)
		(end 382.90246 -255.05791)
		(width 0.088646)
		(layer "In11.Cu")
		(net "M_H_CPU0_SA_CA<0>")
	)
	(segment
		(start 455.011282 -260.21665)
		(end 456.116182 -260.21665)
		(width 0.20066)
		(layer "F.Cu")
		(net "M_H_CPU0_CLK_DP<1>")
	)
	(segment
		(start 370.85778 -247.714262)
		(end 370.858034 -247.714008)
		(width 0.20066)
		(layer "F.Cu")
		(net "M_H_CPU0_CLK_DP<1>")
	)
	(segment
		(start 370.858034 -247.714008)
		(end 370.858034 -247.178322)
		(width 0.20066)
		(layer "F.Cu")
		(net "M_H_CPU0_CLK_DP<1>")
	)
	(segment
		(start 371.23624 -247.2436)
		(end 371.170962 -247.178322)
		(width 0.088646)
		(layer "In11.Cu")
		(net "M_H_CPU0_CLK_DP<1>")
	)
	(segment
		(start 372.463822 -249.300492)
		(end 372.463568 -249.300746)
		(width 0.088646)
		(layer "In11.Cu")
		(net "M_H_CPU0_CLK_DP<1>")
	)
	(segment
		(start 454.393554 -259.950458)
		(end 452.609204 -259.438394)
		(width 0.18288)
		(layer "In11.Cu")
		(net "M_H_CPU0_CLK_DP<1>")
	)
	(segment
		(start 405.265382 -256.011934)
		(end 403.822154 -254.568452)
		(width 0.18288)
		(layer "In11.Cu")
		(net "M_H_CPU0_CLK_DP<1>")
	)
	(segment
		(start 371.523768 -247.67286)
		(end 371.514878 -247.66778)
		(width 0.088646)
		(layer "In11.Cu")
		(net "M_H_CPU0_CLK_DP<1>")
	)
	(segment
		(start 372.463568 -249.300746)
		(end 372.455694 -249.296174)
		(width 0.088646)
		(layer "In11.Cu")
		(net "M_H_CPU0_CLK_DP<1>")
	)
	(segment
		(start 372.582948 -251.298456)
		(end 372.582948 -250.753118)
		(width 0.18288)
		(layer "In11.Cu")
		(net "M_H_CPU0_CLK_DP<1>")
	)
	(segment
		(start 406.43175 -256.011934)
		(end 405.265382 -256.011934)
		(width 0.18288)
		(layer "In11.Cu")
		(net "M_H_CPU0_CLK_DP<1>")
	)
	(segment
		(start 372.642638 -250.693428)
		(end 372.642638 -249.620024)
		(width 0.088646)
		(layer "In11.Cu")
		(net "M_H_CPU0_CLK_DP<1>")
	)
	(segment
		(start 400.885914 -253.352046)
		(end 396.257018 -253.352046)
		(width 0.18288)
		(layer "In11.Cu")
		(net "M_H_CPU0_CLK_DP<1>")
	)
	(segment
		(start 382.07188 -251.75083)
		(end 373.035322 -251.75083)
		(width 0.18288)
		(layer "In11.Cu")
		(net "M_H_CPU0_CLK_DP<1>")
	)
	(segment
		(start 395.049756 -254.559308)
		(end 392.713718 -254.559308)
		(width 0.18288)
		(layer "In11.Cu")
		(net "M_H_CPU0_CLK_DP<1>")
	)
	(segment
		(start 452.609204 -259.438394)
		(end 451.106286 -257.935476)
		(width 0.18288)
		(layer "In11.Cu")
		(net "M_H_CPU0_CLK_DP<1>")
	)
	(segment
		(start 382.389126 -252.068076)
		(end 382.07188 -251.75083)
		(width 0.18288)
		(layer "In11.Cu")
		(net "M_H_CPU0_CLK_DP<1>")
	)
	(segment
		(start 372.582948 -250.753118)
		(end 372.642638 -250.693428)
		(width 0.088646)
		(layer "In11.Cu")
		(net "M_H_CPU0_CLK_DP<1>")
	)
	(segment
		(start 396.257018 -253.352046)
		(end 395.049756 -254.559308)
		(width 0.18288)
		(layer "In11.Cu")
		(net "M_H_CPU0_CLK_DP<1>")
	)
	(segment
		(start 455.011282 -260.21665)
		(end 454.74509 -259.950458)
		(width 0.18288)
		(layer "In11.Cu")
		(net "M_H_CPU0_CLK_DP<1>")
	)
	(segment
		(start 408.968702 -257.062732)
		(end 406.43175 -256.011934)
		(width 0.18288)
		(layer "In11.Cu")
		(net "M_H_CPU0_CLK_DP<1>")
	)
	(segment
		(start 454.74509 -259.950458)
		(end 454.393554 -259.950458)
		(width 0.18288)
		(layer "In11.Cu")
		(net "M_H_CPU0_CLK_DP<1>")
	)
	(segment
		(start 372.172484 -248.821702)
		(end 372.172484 -248.806208)
		(width 0.088646)
		(layer "In11.Cu")
		(net "M_H_CPU0_CLK_DP<1>")
	)
	(segment
		(start 392.713718 -254.559308)
		(end 390.222486 -252.068076)
		(width 0.18288)
		(layer "In11.Cu")
		(net "M_H_CPU0_CLK_DP<1>")
	)
	(segment
		(start 390.222486 -252.068076)
		(end 382.389126 -252.068076)
		(width 0.18288)
		(layer "In11.Cu")
		(net "M_H_CPU0_CLK_DP<1>")
	)
	(segment
		(start 373.035322 -251.75083)
		(end 372.582948 -251.298456)
		(width 0.18288)
		(layer "In11.Cu")
		(net "M_H_CPU0_CLK_DP<1>")
	)
	(segment
		(start 451.106286 -257.935476)
		(end 443.55258 -257.062732)
		(width 0.18288)
		(layer "In11.Cu")
		(net "M_H_CPU0_CLK_DP<1>")
	)
	(segment
		(start 371.170962 -247.178322)
		(end 370.858034 -247.178322)
		(width 0.088646)
		(layer "In11.Cu")
		(net "M_H_CPU0_CLK_DP<1>")
	)
	(segment
		(start 371.993922 -248.48693)
		(end 371.985032 -248.48185)
		(width 0.088646)
		(layer "In11.Cu")
		(net "M_H_CPU0_CLK_DP<1>")
	)
	(segment
		(start 443.55258 -257.062732)
		(end 408.968702 -257.062732)
		(width 0.18288)
		(layer "In11.Cu")
		(net "M_H_CPU0_CLK_DP<1>")
	)
	(segment
		(start 403.822154 -254.568452)
		(end 400.885914 -253.352046)
		(width 0.18288)
		(layer "In11.Cu")
		(net "M_H_CPU0_CLK_DP<1>")
	)
	(segment
		(start 371.70233 -248.006362)
		(end 371.70233 -247.992138)
		(width 0.088646)
		(layer "In11.Cu")
		(net "M_H_CPU0_CLK_DP<1>")
	)
	(segment
		(start 372.455694 -249.296174)
		(end 372.454678 -249.295666)
		(width 0.088646)
		(layer "In11.Cu")
		(net "M_H_CPU0_CLK_DP<1>")
	)
	(arc
		(start 372.642638 -249.620024)
		(mid 372.594894 -249.436942)
		(end 372.463822 -249.300492)
		(width 0.088646)
		(layer "In11.Cu")
		(net "M_H_CPU0_CLK_DP<1>")
	)
	(arc
		(start 371.239034 -247.264682)
		(mid 371.237538 -247.254154)
		(end 371.23624 -247.2436)
		(width 0.088646)
		(layer "In11.Cu")
		(net "M_H_CPU0_CLK_DP<1>")
	)
	(arc
		(start 371.985032 -248.48185)
		(mid 371.781551 -248.281046)
		(end 371.70233 -248.006362)
		(width 0.088646)
		(layer "In11.Cu")
		(net "M_H_CPU0_CLK_DP<1>")
	)
	(arc
		(start 372.172484 -248.806208)
		(mid 372.124805 -248.623308)
		(end 371.993922 -248.48693)
		(width 0.088646)
		(layer "In11.Cu")
		(net "M_H_CPU0_CLK_DP<1>")
	)
	(arc
		(start 371.514878 -247.66778)
		(mid 371.331216 -247.497541)
		(end 371.239034 -247.264682)
		(width 0.088646)
		(layer "In11.Cu")
		(net "M_H_CPU0_CLK_DP<1>")
	)
	(arc
		(start 371.70233 -247.992138)
		(mid 371.654651 -247.809238)
		(end 371.523768 -247.67286)
		(width 0.088646)
		(layer "In11.Cu")
		(net "M_H_CPU0_CLK_DP<1>")
	)
	(arc
		(start 372.454678 -249.295666)
		(mid 372.251855 -249.095435)
		(end 372.172484 -248.821702)
		(width 0.088646)
		(layer "In11.Cu")
		(net "M_H_CPU0_CLK_DP<1>")
	)
	(segment
		(start 372.737634 -247.714008)
		(end 372.737634 -247.178322)
		(width 0.20066)
		(layer "F.Cu")
		(net "M_H_CPU0_CLK_DP<0>")
	)
	(segment
		(start 462.555082 -260.21665)
		(end 463.659982 -260.21665)
		(width 0.20066)
		(layer "F.Cu")
		(net "M_H_CPU0_CLK_DP<0>")
	)
	(segment
		(start 372.73738 -247.714262)
		(end 372.737634 -247.714008)
		(width 0.20066)
		(layer "F.Cu")
		(net "M_H_CPU0_CLK_DP<0>")
	)
	(segment
		(start 403.955504 -253.50851)
		(end 400.863054 -252.462538)
		(width 0.18288)
		(layer "In11.Cu")
		(net "M_H_CPU0_CLK_DP<0>")
	)
	(segment
		(start 374.521984 -249.61977)
		(end 374.52173 -249.620024)
		(width 0.088646)
		(layer "In11.Cu")
		(net "M_H_CPU0_CLK_DP<0>")
	)
	(segment
		(start 393.749784 -249.29973)
		(end 392.983466 -249.453146)
		(width 0.18288)
		(layer "In11.Cu")
		(net "M_H_CPU0_CLK_DP<0>")
	)
	(segment
		(start 374.052084 -248.821702)
		(end 374.052084 -248.806208)
		(width 0.088646)
		(layer "In11.Cu")
		(net "M_H_CPU0_CLK_DP<0>")
	)
	(segment
		(start 373.11584 -247.243854)
		(end 373.050308 -247.178322)
		(width 0.088646)
		(layer "In11.Cu")
		(net "M_H_CPU0_CLK_DP<0>")
	)
	(segment
		(start 375.059194 -250.83897)
		(end 374.83415 -250.613926)
		(width 0.18288)
		(layer "In11.Cu")
		(net "M_H_CPU0_CLK_DP<0>")
	)
	(segment
		(start 374.33885 -249.298206)
		(end 374.334278 -249.295666)
		(width 0.088646)
		(layer "In11.Cu")
		(net "M_H_CPU0_CLK_DP<0>")
	)
	(segment
		(start 394.906754 -249.29973)
		(end 393.749784 -249.29973)
		(width 0.18288)
		(layer "In11.Cu")
		(net "M_H_CPU0_CLK_DP<0>")
	)
	(segment
		(start 373.873522 -248.48693)
		(end 373.864632 -248.48185)
		(width 0.088646)
		(layer "In11.Cu")
		(net "M_H_CPU0_CLK_DP<0>")
	)
	(segment
		(start 462.555082 -260.21665)
		(end 462.279746 -259.941314)
		(width 0.18288)
		(layer "In11.Cu")
		(net "M_H_CPU0_CLK_DP<0>")
	)
	(segment
		(start 400.863054 -252.462538)
		(end 398.069562 -252.462538)
		(width 0.18288)
		(layer "In11.Cu")
		(net "M_H_CPU0_CLK_DP<0>")
	)
	(segment
		(start 383.328926 -251.380498)
		(end 382.787398 -250.83897)
		(width 0.18288)
		(layer "In11.Cu")
		(net "M_H_CPU0_CLK_DP<0>")
	)
	(segment
		(start 373.395494 -247.668288)
		(end 373.394478 -247.66778)
		(width 0.088646)
		(layer "In11.Cu")
		(net "M_H_CPU0_CLK_DP<0>")
	)
	(segment
		(start 461.148938 -259.754116)
		(end 457.20635 -259.754116)
		(width 0.18288)
		(layer "In11.Cu")
		(net "M_H_CPU0_CLK_DP<0>")
	)
	(segment
		(start 409.567888 -256.076196)
		(end 406.296622 -255.060704)
		(width 0.18288)
		(layer "In11.Cu")
		(net "M_H_CPU0_CLK_DP<0>")
	)
	(segment
		(start 405.507698 -255.060704)
		(end 403.955504 -253.50851)
		(width 0.18288)
		(layer "In11.Cu")
		(net "M_H_CPU0_CLK_DP<0>")
	)
	(segment
		(start 452.938896 -257.17754)
		(end 442.524642 -256.076196)
		(width 0.18288)
		(layer "In11.Cu")
		(net "M_H_CPU0_CLK_DP<0>")
	)
	(segment
		(start 457.20635 -259.754116)
		(end 455.825352 -258.373118)
		(width 0.18288)
		(layer "In11.Cu")
		(net "M_H_CPU0_CLK_DP<0>")
	)
	(segment
		(start 374.83415 -250.52909)
		(end 374.521984 -250.216924)
		(width 0.088646)
		(layer "In11.Cu")
		(net "M_H_CPU0_CLK_DP<0>")
	)
	(segment
		(start 406.296622 -255.060704)
		(end 405.507698 -255.060704)
		(width 0.18288)
		(layer "In11.Cu")
		(net "M_H_CPU0_CLK_DP<0>")
	)
	(segment
		(start 374.340882 -249.299476)
		(end 374.33885 -249.298206)
		(width 0.088646)
		(layer "In11.Cu")
		(net "M_H_CPU0_CLK_DP<0>")
	)
	(segment
		(start 461.336136 -259.941314)
		(end 461.148938 -259.754116)
		(width 0.18288)
		(layer "In11.Cu")
		(net "M_H_CPU0_CLK_DP<0>")
	)
	(segment
		(start 442.524642 -256.076196)
		(end 409.567888 -256.076196)
		(width 0.18288)
		(layer "In11.Cu")
		(net "M_H_CPU0_CLK_DP<0>")
	)
	(segment
		(start 374.83415 -250.613926)
		(end 374.83415 -250.52909)
		(width 0.088646)
		(layer "In11.Cu")
		(net "M_H_CPU0_CLK_DP<0>")
	)
	(segment
		(start 382.787398 -250.83897)
		(end 375.059194 -250.83897)
		(width 0.18288)
		(layer "In11.Cu")
		(net "M_H_CPU0_CLK_DP<0>")
	)
	(segment
		(start 455.825352 -258.373118)
		(end 452.938896 -257.17754)
		(width 0.18288)
		(layer "In11.Cu")
		(net "M_H_CPU0_CLK_DP<0>")
	)
	(segment
		(start 462.279746 -259.941314)
		(end 461.336136 -259.941314)
		(width 0.18288)
		(layer "In11.Cu")
		(net "M_H_CPU0_CLK_DP<0>")
	)
	(segment
		(start 374.521984 -250.216924)
		(end 374.521984 -249.61977)
		(width 0.088646)
		(layer "In11.Cu")
		(net "M_H_CPU0_CLK_DP<0>")
	)
	(segment
		(start 398.069562 -252.462538)
		(end 394.906754 -249.29973)
		(width 0.18288)
		(layer "In11.Cu")
		(net "M_H_CPU0_CLK_DP<0>")
	)
	(segment
		(start 388.333488 -251.380498)
		(end 383.328926 -251.380498)
		(width 0.18288)
		(layer "In11.Cu")
		(net "M_H_CPU0_CLK_DP<0>")
	)
	(segment
		(start 374.343168 -249.300746)
		(end 374.340882 -249.299476)
		(width 0.088646)
		(layer "In11.Cu")
		(net "M_H_CPU0_CLK_DP<0>")
	)
	(segment
		(start 392.983466 -249.453146)
		(end 388.333488 -251.380498)
		(width 0.18288)
		(layer "In11.Cu")
		(net "M_H_CPU0_CLK_DP<0>")
	)
	(segment
		(start 373.58193 -247.999758)
		(end 373.58193 -247.992138)
		(width 0.088646)
		(layer "In11.Cu")
		(net "M_H_CPU0_CLK_DP<0>")
	)
	(segment
		(start 373.050308 -247.178322)
		(end 372.737634 -247.178322)
		(width 0.088646)
		(layer "In11.Cu")
		(net "M_H_CPU0_CLK_DP<0>")
	)
	(segment
		(start 373.403368 -247.67286)
		(end 373.395494 -247.668288)
		(width 0.088646)
		(layer "In11.Cu")
		(net "M_H_CPU0_CLK_DP<0>")
	)
	(arc
		(start 374.52173 -249.620024)
		(mid 374.474051 -249.437124)
		(end 374.343168 -249.300746)
		(width 0.088646)
		(layer "In11.Cu")
		(net "M_H_CPU0_CLK_DP<0>")
	)
	(arc
		(start 374.334278 -249.295666)
		(mid 374.131455 -249.095435)
		(end 374.052084 -248.821702)
		(width 0.088646)
		(layer "In11.Cu")
		(net "M_H_CPU0_CLK_DP<0>")
	)
	(arc
		(start 373.864632 -248.48185)
		(mid 373.65956 -248.278171)
		(end 373.58193 -247.999758)
		(width 0.088646)
		(layer "In11.Cu")
		(net "M_H_CPU0_CLK_DP<0>")
	)
	(arc
		(start 373.58193 -247.992138)
		(mid 373.534251 -247.809238)
		(end 373.403368 -247.67286)
		(width 0.088646)
		(layer "In11.Cu")
		(net "M_H_CPU0_CLK_DP<0>")
	)
	(arc
		(start 373.394478 -247.66778)
		(mid 373.210887 -247.497645)
		(end 373.118634 -247.264936)
		(width 0.088646)
		(layer "In11.Cu")
		(net "M_H_CPU0_CLK_DP<0>")
	)
	(arc
		(start 373.118634 -247.264936)
		(mid 373.117138 -247.254408)
		(end 373.11584 -247.243854)
		(width 0.088646)
		(layer "In11.Cu")
		(net "M_H_CPU0_CLK_DP<0>")
	)
	(arc
		(start 374.052084 -248.806208)
		(mid 374.004405 -248.623308)
		(end 373.873522 -248.48693)
		(width 0.088646)
		(layer "In11.Cu")
		(net "M_H_CPU0_CLK_DP<0>")
	)
	(segment
		(start 371.79758 -247.714262)
		(end 371.797834 -247.714008)
		(width 0.20066)
		(layer "F.Cu")
		(net "M_H_CPU0_CLK_DN<1>")
	)
	(segment
		(start 371.797834 -247.714008)
		(end 371.797834 -247.178322)
		(width 0.20066)
		(layer "F.Cu")
		(net "M_H_CPU0_CLK_DN<1>")
	)
	(segment
		(start 456.116182 -259.366766)
		(end 455.011282 -259.366766)
		(width 0.20066)
		(layer "F.Cu")
		(net "M_H_CPU0_CLK_DN<1>")
	)
	(segment
		(start 382.51765 -251.758196)
		(end 382.200404 -251.44095)
		(width 0.18288)
		(layer "In11.Cu")
		(net "M_H_CPU0_CLK_DN<1>")
	)
	(segment
		(start 403.997922 -254.305562)
		(end 400.947636 -253.042166)
		(width 0.18288)
		(layer "In11.Cu")
		(net "M_H_CPU0_CLK_DN<1>")
	)
	(segment
		(start 443.570614 -256.752852)
		(end 441.770516 -256.752852)
		(width 0.18288)
		(layer "In11.Cu")
		(net "M_H_CPU0_CLK_DN<1>")
	)
	(segment
		(start 454.437242 -259.640578)
		(end 452.771764 -259.16255)
		(width 0.18288)
		(layer "In11.Cu")
		(net "M_H_CPU0_CLK_DN<1>")
	)
	(segment
		(start 437.838596 -256.752852)
		(end 437.716676 -256.630932)
		(width 0.18288)
		(layer "In11.Cu")
		(net "M_H_CPU0_CLK_DN<1>")
	)
	(segment
		(start 400.947636 -253.042166)
		(end 396.128494 -253.042166)
		(width 0.18288)
		(layer "In11.Cu")
		(net "M_H_CPU0_CLK_DN<1>")
	)
	(segment
		(start 372.556532 -249.134122)
		(end 372.555008 -249.13336)
		(width 0.088646)
		(layer "In11.Cu")
		(net "M_H_CPU0_CLK_DN<1>")
	)
	(segment
		(start 372.362984 -248.806208)
		(end 372.362984 -248.791984)
		(width 0.088646)
		(layer "In11.Cu")
		(net "M_H_CPU0_CLK_DN<1>")
	)
	(segment
		(start 437.716676 -256.630932)
		(end 437.183276 -256.630932)
		(width 0.18288)
		(layer "In11.Cu")
		(net "M_H_CPU0_CLK_DN<1>")
	)
	(segment
		(start 451.753986 -258.144518)
		(end 451.249288 -257.63982)
		(width 0.18288)
		(layer "In11.Cu")
		(net "M_H_CPU0_CLK_DN<1>")
	)
	(segment
		(start 452.303896 -258.521962)
		(end 451.926452 -258.144518)
		(width 0.18288)
		(layer "In11.Cu")
		(net "M_H_CPU0_CLK_DN<1>")
	)
	(segment
		(start 392.842242 -254.249428)
		(end 390.35101 -251.758196)
		(width 0.18288)
		(layer "In11.Cu")
		(net "M_H_CPU0_CLK_DN<1>")
	)
	(segment
		(start 372.080282 -248.316496)
		(end 372.071392 -248.311416)
		(width 0.088646)
		(layer "In11.Cu")
		(net "M_H_CPU0_CLK_DN<1>")
	)
	(segment
		(start 371.484906 -247.178322)
		(end 371.797834 -247.178322)
		(width 0.088646)
		(layer "In11.Cu")
		(net "M_H_CPU0_CLK_DN<1>")
	)
	(segment
		(start 372.550436 -249.130566)
		(end 372.541546 -249.125486)
		(width 0.088646)
		(layer "In11.Cu")
		(net "M_H_CPU0_CLK_DN<1>")
	)
	(segment
		(start 455.00036 -259.366766)
		(end 454.726548 -259.640578)
		(width 0.18288)
		(layer "In11.Cu")
		(net "M_H_CPU0_CLK_DN<1>")
	)
	(segment
		(start 371.89283 -247.992138)
		(end 371.89283 -247.976644)
		(width 0.088646)
		(layer "In11.Cu")
		(net "M_H_CPU0_CLK_DN<1>")
	)
	(segment
		(start 439.804556 -256.630932)
		(end 439.682636 -256.752852)
		(width 0.18288)
		(layer "In11.Cu")
		(net "M_H_CPU0_CLK_DN<1>")
	)
	(segment
		(start 371.610636 -247.50268)
		(end 371.601746 -247.4976)
		(width 0.088646)
		(layer "In11.Cu")
		(net "M_H_CPU0_CLK_DN<1>")
	)
	(segment
		(start 390.35101 -251.758196)
		(end 382.51765 -251.758196)
		(width 0.18288)
		(layer "In11.Cu")
		(net "M_H_CPU0_CLK_DN<1>")
	)
	(segment
		(start 440.993276 -256.752852)
		(end 440.459876 -256.752852)
		(width 0.18288)
		(layer "In11.Cu")
		(net "M_H_CPU0_CLK_DN<1>")
	)
	(segment
		(start 372.892828 -251.169932)
		(end 372.892828 -250.753118)
		(width 0.18288)
		(layer "In11.Cu")
		(net "M_H_CPU0_CLK_DN<1>")
	)
	(segment
		(start 372.892828 -250.753118)
		(end 372.832884 -250.693174)
		(width 0.088646)
		(layer "In11.Cu")
		(net "M_H_CPU0_CLK_DN<1>")
	)
	(segment
		(start 441.770516 -256.752852)
		(end 441.648596 -256.630932)
		(width 0.18288)
		(layer "In11.Cu")
		(net "M_H_CPU0_CLK_DN<1>")
	)
	(segment
		(start 438.493916 -256.630932)
		(end 438.371996 -256.752852)
		(width 0.18288)
		(layer "In11.Cu")
		(net "M_H_CPU0_CLK_DN<1>")
	)
	(segment
		(start 373.163846 -251.44095)
		(end 372.892828 -251.169932)
		(width 0.18288)
		(layer "In11.Cu")
		(net "M_H_CPU0_CLK_DN<1>")
	)
	(segment
		(start 372.555008 -249.13336)
		(end 372.550436 -249.130566)
		(width 0.088646)
		(layer "In11.Cu")
		(net "M_H_CPU0_CLK_DN<1>")
	)
	(segment
		(start 440.459876 -256.752852)
		(end 440.337956 -256.630932)
		(width 0.18288)
		(layer "In11.Cu")
		(net "M_H_CPU0_CLK_DN<1>")
	)
	(segment
		(start 406.493472 -255.702054)
		(end 405.393906 -255.702054)
		(width 0.18288)
		(layer "In11.Cu")
		(net "M_H_CPU0_CLK_DN<1>")
	)
	(segment
		(start 437.183276 -256.630932)
		(end 437.061356 -256.752852)
		(width 0.18288)
		(layer "In11.Cu")
		(net "M_H_CPU0_CLK_DN<1>")
	)
	(segment
		(start 438.371996 -256.752852)
		(end 437.838596 -256.752852)
		(width 0.18288)
		(layer "In11.Cu")
		(net "M_H_CPU0_CLK_DN<1>")
	)
	(segment
		(start 441.115196 -256.630932)
		(end 440.993276 -256.752852)
		(width 0.18288)
		(layer "In11.Cu")
		(net "M_H_CPU0_CLK_DN<1>")
	)
	(segment
		(start 439.027316 -256.630932)
		(end 438.493916 -256.630932)
		(width 0.18288)
		(layer "In11.Cu")
		(net "M_H_CPU0_CLK_DN<1>")
	)
	(segment
		(start 440.337956 -256.630932)
		(end 439.804556 -256.630932)
		(width 0.18288)
		(layer "In11.Cu")
		(net "M_H_CPU0_CLK_DN<1>")
	)
	(segment
		(start 439.149236 -256.752852)
		(end 439.027316 -256.630932)
		(width 0.18288)
		(layer "In11.Cu")
		(net "M_H_CPU0_CLK_DN<1>")
	)
	(segment
		(start 455.011282 -259.366766)
		(end 455.00036 -259.366766)
		(width 0.18288)
		(layer "In11.Cu")
		(net "M_H_CPU0_CLK_DN<1>")
	)
	(segment
		(start 396.128494 -253.042166)
		(end 394.921232 -254.249428)
		(width 0.18288)
		(layer "In11.Cu")
		(net "M_H_CPU0_CLK_DN<1>")
	)
	(segment
		(start 439.682636 -256.752852)
		(end 439.149236 -256.752852)
		(width 0.18288)
		(layer "In11.Cu")
		(net "M_H_CPU0_CLK_DN<1>")
	)
	(segment
		(start 394.921232 -254.249428)
		(end 392.842242 -254.249428)
		(width 0.18288)
		(layer "In11.Cu")
		(net "M_H_CPU0_CLK_DN<1>")
	)
	(segment
		(start 382.200404 -251.44095)
		(end 373.163846 -251.44095)
		(width 0.18288)
		(layer "In11.Cu")
		(net "M_H_CPU0_CLK_DN<1>")
	)
	(segment
		(start 372.832884 -250.693174)
		(end 372.832884 -249.620024)
		(width 0.088646)
		(layer "In11.Cu")
		(net "M_H_CPU0_CLK_DN<1>")
	)
	(segment
		(start 454.726548 -259.640578)
		(end 454.437242 -259.640578)
		(width 0.18288)
		(layer "In11.Cu")
		(net "M_H_CPU0_CLK_DN<1>")
	)
	(segment
		(start 451.926452 -258.144518)
		(end 451.753986 -258.144518)
		(width 0.18288)
		(layer "In11.Cu")
		(net "M_H_CPU0_CLK_DN<1>")
	)
	(segment
		(start 371.427756 -247.235472)
		(end 371.484906 -247.178322)
		(width 0.088646)
		(layer "In11.Cu")
		(net "M_H_CPU0_CLK_DN<1>")
	)
	(segment
		(start 437.061356 -256.752852)
		(end 409.030424 -256.752852)
		(width 0.18288)
		(layer "In11.Cu")
		(net "M_H_CPU0_CLK_DN<1>")
	)
	(segment
		(start 441.648596 -256.630932)
		(end 441.115196 -256.630932)
		(width 0.18288)
		(layer "In11.Cu")
		(net "M_H_CPU0_CLK_DN<1>")
	)
	(segment
		(start 409.030424 -256.752852)
		(end 406.493472 -255.702054)
		(width 0.18288)
		(layer "In11.Cu")
		(net "M_H_CPU0_CLK_DN<1>")
	)
	(segment
		(start 452.771764 -259.16255)
		(end 452.303896 -258.694428)
		(width 0.18288)
		(layer "In11.Cu")
		(net "M_H_CPU0_CLK_DN<1>")
	)
	(segment
		(start 451.249288 -257.63982)
		(end 443.570614 -256.752852)
		(width 0.18288)
		(layer "In11.Cu")
		(net "M_H_CPU0_CLK_DN<1>")
	)
	(segment
		(start 452.303896 -258.694428)
		(end 452.303896 -258.521962)
		(width 0.18288)
		(layer "In11.Cu")
		(net "M_H_CPU0_CLK_DN<1>")
	)
	(segment
		(start 405.393906 -255.702054)
		(end 403.997922 -254.305562)
		(width 0.18288)
		(layer "In11.Cu")
		(net "M_H_CPU0_CLK_DN<1>")
	)
	(arc
		(start 372.071392 -248.311416)
		(mid 371.940478 -248.175056)
		(end 371.89283 -247.992138)
		(width 0.088646)
		(layer "In11.Cu")
		(net "M_H_CPU0_CLK_DN<1>")
	)
	(arc
		(start 372.832884 -249.620024)
		(mid 372.758968 -249.340522)
		(end 372.556532 -249.134122)
		(width 0.088646)
		(layer "In11.Cu")
		(net "M_H_CPU0_CLK_DN<1>")
	)
	(arc
		(start 372.362984 -248.791984)
		(mid 372.283765 -248.517299)
		(end 372.080282 -248.316496)
		(width 0.088646)
		(layer "In11.Cu")
		(net "M_H_CPU0_CLK_DN<1>")
	)
	(arc
		(start 371.89283 -247.976644)
		(mid 371.81346 -247.70291)
		(end 371.610636 -247.50268)
		(width 0.088646)
		(layer "In11.Cu")
		(net "M_H_CPU0_CLK_DN<1>")
	)
	(arc
		(start 371.601746 -247.4976)
		(mid 371.485937 -247.385671)
		(end 371.427756 -247.235472)
		(width 0.088646)
		(layer "In11.Cu")
		(net "M_H_CPU0_CLK_DN<1>")
	)
	(arc
		(start 372.541546 -249.125486)
		(mid 372.410632 -248.989126)
		(end 372.362984 -248.806208)
		(width 0.088646)
		(layer "In11.Cu")
		(net "M_H_CPU0_CLK_DN<1>")
	)
	(segment
		(start 373.67718 -247.714262)
		(end 373.677434 -247.714008)
		(width 0.20066)
		(layer "F.Cu")
		(net "M_H_CPU0_CLK_DN<0>")
	)
	(segment
		(start 373.677434 -247.714008)
		(end 373.677434 -247.178322)
		(width 0.20066)
		(layer "F.Cu")
		(net "M_H_CPU0_CLK_DN<0>")
	)
	(segment
		(start 463.659982 -259.366766)
		(end 462.555082 -259.366766)
		(width 0.20066)
		(layer "F.Cu")
		(net "M_H_CPU0_CLK_DN<0>")
	)
	(segment
		(start 373.496332 -247.506236)
		(end 373.492522 -247.50395)
		(width 0.088646)
		(layer "In11.Cu")
		(net "M_H_CPU0_CLK_DN<0>")
	)
	(segment
		(start 374.712738 -250.13793)
		(end 374.71223 -250.13793)
		(width 0.088646)
		(layer "In11.Cu")
		(net "M_H_CPU0_CLK_DN<0>")
	)
	(segment
		(start 457.334874 -259.444236)
		(end 456.00112 -258.110228)
		(width 0.18288)
		(layer "In11.Cu")
		(net "M_H_CPU0_CLK_DN<0>")
	)
	(segment
		(start 373.490744 -247.502934)
		(end 373.481346 -247.4976)
		(width 0.088646)
		(layer "In11.Cu")
		(net "M_H_CPU0_CLK_DN<0>")
	)
	(segment
		(start 388.271766 -251.070618)
		(end 383.45745 -251.070618)
		(width 0.18288)
		(layer "In11.Cu")
		(net "M_H_CPU0_CLK_DN<0>")
	)
	(segment
		(start 373.492522 -247.50395)
		(end 373.490744 -247.502934)
		(width 0.088646)
		(layer "In11.Cu")
		(net "M_H_CPU0_CLK_DN<0>")
	)
	(segment
		(start 392.769344 -249.206258)
		(end 388.271766 -251.070618)
		(width 0.18288)
		(layer "In11.Cu")
		(net "M_H_CPU0_CLK_DN<0>")
	)
	(segment
		(start 375.187718 -250.52909)
		(end 375.053352 -250.394724)
		(width 0.18288)
		(layer "In11.Cu")
		(net "M_H_CPU0_CLK_DN<0>")
	)
	(segment
		(start 375.053352 -250.394724)
		(end 374.969532 -250.394724)
		(width 0.088646)
		(layer "In11.Cu")
		(net "M_H_CPU0_CLK_DN<0>")
	)
	(segment
		(start 382.915922 -250.52909)
		(end 375.187718 -250.52909)
		(width 0.18288)
		(layer "In11.Cu")
		(net "M_H_CPU0_CLK_DN<0>")
	)
	(segment
		(start 442.541152 -255.766316)
		(end 409.615132 -255.766316)
		(width 0.18288)
		(layer "In11.Cu")
		(net "M_H_CPU0_CLK_DN<0>")
	)
	(segment
		(start 451.24497 -256.563876)
		(end 450.71411 -256.507996)
		(width 0.18288)
		(layer "In11.Cu")
		(net "M_H_CPU0_CLK_DN<0>")
	)
	(segment
		(start 458.575664 -259.322316)
		(end 458.453744 -259.444236)
		(width 0.18288)
		(layer "In11.Cu")
		(net "M_H_CPU0_CLK_DN<0>")
	)
	(segment
		(start 459.230984 -259.444236)
		(end 459.109064 -259.322316)
		(width 0.18288)
		(layer "In11.Cu")
		(net "M_H_CPU0_CLK_DN<0>")
	)
	(segment
		(start 460.419704 -259.322316)
		(end 459.886304 -259.322316)
		(width 0.18288)
		(layer "In11.Cu")
		(net "M_H_CPU0_CLK_DN<0>")
	)
	(segment
		(start 373.307356 -247.235726)
		(end 373.36476 -247.178322)
		(width 0.088646)
		(layer "In11.Cu")
		(net "M_H_CPU0_CLK_DN<0>")
	)
	(segment
		(start 462.555082 -259.366766)
		(end 462.290414 -259.631434)
		(width 0.18288)
		(layer "In11.Cu")
		(net "M_H_CPU0_CLK_DN<0>")
	)
	(segment
		(start 374.969532 -250.394724)
		(end 374.712738 -250.13793)
		(width 0.088646)
		(layer "In11.Cu")
		(net "M_H_CPU0_CLK_DN<0>")
	)
	(segment
		(start 462.290414 -259.631434)
		(end 461.46466 -259.631434)
		(width 0.18288)
		(layer "In11.Cu")
		(net "M_H_CPU0_CLK_DN<0>")
	)
	(segment
		(start 373.36476 -247.178322)
		(end 373.677434 -247.178322)
		(width 0.088646)
		(layer "In11.Cu")
		(net "M_H_CPU0_CLK_DN<0>")
	)
	(segment
		(start 406.343866 -254.750824)
		(end 405.636222 -254.750824)
		(width 0.18288)
		(layer "In11.Cu")
		(net "M_H_CPU0_CLK_DN<0>")
	)
	(segment
		(start 450.71411 -256.507996)
		(end 450.580252 -256.6162)
		(width 0.18288)
		(layer "In11.Cu")
		(net "M_H_CPU0_CLK_DN<0>")
	)
	(segment
		(start 393.68603 -248.98985)
		(end 393.677902 -248.997978)
		(width 0.18288)
		(layer "In11.Cu")
		(net "M_H_CPU0_CLK_DN<0>")
	)
	(segment
		(start 459.109064 -259.322316)
		(end 458.575664 -259.322316)
		(width 0.18288)
		(layer "In11.Cu")
		(net "M_H_CPU0_CLK_DN<0>")
	)
	(segment
		(start 459.886304 -259.322316)
		(end 459.764384 -259.444236)
		(width 0.18288)
		(layer "In11.Cu")
		(net "M_H_CPU0_CLK_DN<0>")
	)
	(segment
		(start 459.764384 -259.444236)
		(end 459.230984 -259.444236)
		(width 0.18288)
		(layer "In11.Cu")
		(net "M_H_CPU0_CLK_DN<0>")
	)
	(segment
		(start 393.677902 -248.997978)
		(end 392.892788 -249.155204)
		(width 0.18288)
		(layer "In11.Cu")
		(net "M_H_CPU0_CLK_DN<0>")
	)
	(segment
		(start 405.636222 -254.750824)
		(end 404.123652 -253.238)
		(width 0.18288)
		(layer "In11.Cu")
		(net "M_H_CPU0_CLK_DN<0>")
	)
	(segment
		(start 458.453744 -259.444236)
		(end 457.334874 -259.444236)
		(width 0.18288)
		(layer "In11.Cu")
		(net "M_H_CPU0_CLK_DN<0>")
	)
	(segment
		(start 373.960136 -248.316496)
		(end 373.951246 -248.311416)
		(width 0.088646)
		(layer "In11.Cu")
		(net "M_H_CPU0_CLK_DN<0>")
	)
	(segment
		(start 460.541624 -259.444236)
		(end 460.419704 -259.322316)
		(width 0.18288)
		(layer "In11.Cu")
		(net "M_H_CPU0_CLK_DN<0>")
	)
	(segment
		(start 374.4341 -249.133106)
		(end 374.433846 -249.132852)
		(width 0.088646)
		(layer "In11.Cu")
		(net "M_H_CPU0_CLK_DN<0>")
	)
	(segment
		(start 455.203814 -257.647948)
		(end 454.7108 -257.443732)
		(width 0.18288)
		(layer "In11.Cu")
		(net "M_H_CPU0_CLK_DN<0>")
	)
	(segment
		(start 398.198086 -252.152658)
		(end 395.035278 -248.98985)
		(width 0.18288)
		(layer "In11.Cu")
		(net "M_H_CPU0_CLK_DN<0>")
	)
	(segment
		(start 461.46466 -259.631434)
		(end 461.277462 -259.444236)
		(width 0.18288)
		(layer "In11.Cu")
		(net "M_H_CPU0_CLK_DN<0>")
	)
	(segment
		(start 461.277462 -259.444236)
		(end 460.541624 -259.444236)
		(width 0.18288)
		(layer "In11.Cu")
		(net "M_H_CPU0_CLK_DN<0>")
	)
	(segment
		(start 392.892788 -249.155204)
		(end 392.769344 -249.206258)
		(width 0.18288)
		(layer "In11.Cu")
		(net "M_H_CPU0_CLK_DN<0>")
	)
	(segment
		(start 454.551542 -257.509772)
		(end 453.016112 -256.87401)
		(width 0.18288)
		(layer "In11.Cu")
		(net "M_H_CPU0_CLK_DN<0>")
	)
	(segment
		(start 374.433846 -249.132852)
		(end 374.421146 -249.125486)
		(width 0.088646)
		(layer "In11.Cu")
		(net "M_H_CPU0_CLK_DN<0>")
	)
	(segment
		(start 455.269854 -257.80746)
		(end 455.203814 -257.647948)
		(width 0.18288)
		(layer "In11.Cu")
		(net "M_H_CPU0_CLK_DN<0>")
	)
	(segment
		(start 453.016112 -256.87401)
		(end 451.353428 -256.698242)
		(width 0.18288)
		(layer "In11.Cu")
		(net "M_H_CPU0_CLK_DN<0>")
	)
	(segment
		(start 374.71223 -250.13793)
		(end 374.71223 -249.492262)
		(width 0.088646)
		(layer "In11.Cu")
		(net "M_H_CPU0_CLK_DN<0>")
	)
	(segment
		(start 374.437656 -249.135138)
		(end 374.4341 -249.133106)
		(width 0.088646)
		(layer "In11.Cu")
		(net "M_H_CPU0_CLK_DN<0>")
	)
	(segment
		(start 409.615132 -255.766316)
		(end 406.343866 -254.750824)
		(width 0.18288)
		(layer "In11.Cu")
		(net "M_H_CPU0_CLK_DN<0>")
	)
	(segment
		(start 374.441212 -249.137424)
		(end 374.437656 -249.135138)
		(width 0.088646)
		(layer "In11.Cu")
		(net "M_H_CPU0_CLK_DN<0>")
	)
	(segment
		(start 454.7108 -257.443732)
		(end 454.551542 -257.509772)
		(width 0.18288)
		(layer "In11.Cu")
		(net "M_H_CPU0_CLK_DN<0>")
	)
	(segment
		(start 374.71223 -249.492262)
		(end 374.692672 -249.47245)
		(width 0.088646)
		(layer "In11.Cu")
		(net "M_H_CPU0_CLK_DN<0>")
	)
	(segment
		(start 450.580252 -256.6162)
		(end 442.541152 -255.766316)
		(width 0.18288)
		(layer "In11.Cu")
		(net "M_H_CPU0_CLK_DN<0>")
	)
	(segment
		(start 451.353428 -256.698242)
		(end 451.24497 -256.563876)
		(width 0.18288)
		(layer "In11.Cu")
		(net "M_H_CPU0_CLK_DN<0>")
	)
	(segment
		(start 456.00112 -258.110228)
		(end 455.269854 -257.80746)
		(width 0.18288)
		(layer "In11.Cu")
		(net "M_H_CPU0_CLK_DN<0>")
	)
	(segment
		(start 404.123652 -253.238)
		(end 400.914108 -252.152658)
		(width 0.18288)
		(layer "In11.Cu")
		(net "M_H_CPU0_CLK_DN<0>")
	)
	(segment
		(start 383.45745 -251.070618)
		(end 382.915922 -250.52909)
		(width 0.18288)
		(layer "In11.Cu")
		(net "M_H_CPU0_CLK_DN<0>")
	)
	(segment
		(start 374.242584 -248.806208)
		(end 374.242584 -248.787666)
		(width 0.088646)
		(layer "In11.Cu")
		(net "M_H_CPU0_CLK_DN<0>")
	)
	(segment
		(start 395.035278 -248.98985)
		(end 393.68603 -248.98985)
		(width 0.18288)
		(layer "In11.Cu")
		(net "M_H_CPU0_CLK_DN<0>")
	)
	(segment
		(start 400.914108 -252.152658)
		(end 398.198086 -252.152658)
		(width 0.18288)
		(layer "In11.Cu")
		(net "M_H_CPU0_CLK_DN<0>")
	)
	(arc
		(start 373.481346 -247.4976)
		(mid 373.365607 -247.385776)
		(end 373.307356 -247.235726)
		(width 0.088646)
		(layer "In11.Cu")
		(net "M_H_CPU0_CLK_DN<0>")
	)
	(arc
		(start 373.772684 -247.992138)
		(mid 373.698768 -247.712636)
		(end 373.496332 -247.506236)
		(width 0.088646)
		(layer "In11.Cu")
		(net "M_H_CPU0_CLK_DN<0>")
	)
	(arc
		(start 374.421146 -249.125486)
		(mid 374.290232 -248.989126)
		(end 374.242584 -248.806208)
		(width 0.088646)
		(layer "In11.Cu")
		(net "M_H_CPU0_CLK_DN<0>")
	)
	(arc
		(start 374.242584 -248.787666)
		(mid 374.162422 -248.515477)
		(end 373.960136 -248.316496)
		(width 0.088646)
		(layer "In11.Cu")
		(net "M_H_CPU0_CLK_DN<0>")
	)
	(arc
		(start 373.951246 -248.311416)
		(mid 373.820332 -248.175056)
		(end 373.772684 -247.992138)
		(width 0.088646)
		(layer "In11.Cu")
		(net "M_H_CPU0_CLK_DN<0>")
	)
	(arc
		(start 374.692672 -249.47245)
		(mid 374.599136 -249.280769)
		(end 374.441212 -249.137424)
		(width 0.088646)
		(layer "In11.Cu")
		(net "M_H_CPU0_CLK_DN<0>")
	)
	(segment
		(start 454.301352 -269.789656)
		(end 453.717152 -269.789656)
		(width 0.20066)
		(layer "F.Cu")
		(net "M_H_CPU0_ALERT_N")
	)
	(segment
		(start 459.55966 -269.566898)
		(end 458.685138 -269.566898)
		(width 0.20066)
		(layer "F.Cu")
		(net "M_H_CPU0_ALERT_N")
	)
	(segment
		(start 457.111862 -269.1003)
		(end 456.97521 -269.141702)
		(width 0.1016)
		(layer "F.Cu")
		(net "M_H_CPU0_ALERT_N")
	)
	(segment
		(start 454.479152 -269.433802)
		(end 454.479152 -269.611856)
		(width 0.20066)
		(layer "F.Cu")
		(net "M_H_CPU0_ALERT_N")
	)
	(segment
		(start 454.771252 -269.141702)
		(end 454.479152 -269.433802)
		(width 0.20066)
		(layer "F.Cu")
		(net "M_H_CPU0_ALERT_N")
	)
	(segment
		(start 453.590152 -269.916656)
		(end 452.896732 -269.916656)
		(width 0.20066)
		(layer "F.Cu")
		(net "M_H_CPU0_ALERT_N")
	)
	(segment
		(start 457.703682 -269.1003)
		(end 457.126594 -269.1003)
		(width 0.20066)
		(layer "F.Cu")
		(net "M_H_CPU0_ALERT_N")
	)
	(segment
		(start 458.599286 -269.65275)
		(end 458.256132 -269.65275)
		(width 0.20066)
		(layer "F.Cu")
		(net "M_H_CPU0_ALERT_N")
	)
	(segment
		(start 454.890378 -269.141702)
		(end 454.771252 -269.141702)
		(width 0.20066)
		(layer "F.Cu")
		(net "M_H_CPU0_ALERT_N")
	)
	(segment
		(start 452.896732 -269.916656)
		(end 452.54672 -269.566644)
		(width 0.20066)
		(layer "F.Cu")
		(net "M_H_CPU0_ALERT_N")
	)
	(segment
		(start 456.97521 -269.141702)
		(end 455.09942 -269.141702)
		(width 0.1016)
		(layer "F.Cu")
		(net "M_H_CPU0_ALERT_N")
	)
	(segment
		(start 458.256132 -269.65275)
		(end 457.703682 -269.1003)
		(width 0.20066)
		(layer "F.Cu")
		(net "M_H_CPU0_ALERT_N")
	)
	(segment
		(start 458.685138 -269.566898)
		(end 458.599286 -269.65275)
		(width 0.20066)
		(layer "F.Cu")
		(net "M_H_CPU0_ALERT_N")
	)
	(segment
		(start 452.54672 -269.566644)
		(end 452.016114 -269.566644)
		(width 0.20066)
		(layer "F.Cu")
		(net "M_H_CPU0_ALERT_N")
	)
	(segment
		(start 457.126594 -269.1003)
		(end 457.111862 -269.1003)
		(width 0.1016)
		(layer "F.Cu")
		(net "M_H_CPU0_ALERT_N")
	)
	(segment
		(start 454.479152 -269.611856)
		(end 454.301352 -269.789656)
		(width 0.20066)
		(layer "F.Cu")
		(net "M_H_CPU0_ALERT_N")
	)
	(segment
		(start 453.717152 -269.789656)
		(end 453.590152 -269.916656)
		(width 0.20066)
		(layer "F.Cu")
		(net "M_H_CPU0_ALERT_N")
	)
	(segment
		(start 452.016114 -269.566644)
		(end 450.911214 -269.566644)
		(width 0.20066)
		(layer "F.Cu")
		(net "M_H_CPU0_ALERT_N")
	)
	(segment
		(start 459.559914 -269.566644)
		(end 459.55966 -269.566898)
		(width 0.20066)
		(layer "F.Cu")
		(net "M_H_CPU0_ALERT_N")
	)
	(segment
		(start 455.09942 -269.141702)
		(end 454.890378 -269.141702)
		(width 0.101854)
		(layer "F.Cu")
		(net "M_H_CPU0_ALERT_N")
	)
	(segment
		(start 370.027962 -257.175)
		(end 370.028216 -257.175254)
		(width 0.20066)
		(layer "F.Cu")
		(net "M_H_CPU0_ALERT_N")
	)
	(segment
		(start 370.027962 -256.639314)
		(end 370.027962 -257.175)
		(width 0.20066)
		(layer "F.Cu")
		(net "M_H_CPU0_ALERT_N")
	)
	(via
		(at 450.911214 -269.566644)
		(size 0.4572)
		(drill 0.2032)
		(layers "F.Cu" "B.Cu")
		(net "M_H_CPU0_ALERT_N")
	)
	(via
		(at 370.028216 -257.175254)
		(size 0.4572)
		(drill 0.2032)
		(layers "F.Cu" "B.Cu")
		(net "M_H_CPU0_ALERT_N")
	)
	(segment
		(start 384.877564 -257.499612)
		(end 384.862832 -257.490976)
		(width 0.088646)
		(layer "In11.Cu")
		(net "M_H_CPU0_ALERT_N")
	)
	(segment
		(start 388.129018 -257.466338)
		(end 387.549644 -257.466338)
		(width 0.088646)
		(layer "In11.Cu")
		(net "M_H_CPU0_ALERT_N")
	)
	(segment
		(start 380.178564 -257.499612)
		(end 380.16815 -257.493516)
		(width 0.088646)
		(layer "In11.Cu")
		(net "M_H_CPU0_ALERT_N")
	)
	(segment
		(start 385.817364 -257.499612)
		(end 385.802632 -257.490976)
		(width 0.088646)
		(layer "In11.Cu")
		(net "M_H_CPU0_ALERT_N")
	)
	(segment
		(start 416.837114 -267.443712)
		(end 412.281878 -267.443712)
		(width 0.18288)
		(layer "In11.Cu")
		(net "M_H_CPU0_ALERT_N")
	)
	(segment
		(start 380.563374 -257.493516)
		(end 380.55296 -257.499612)
		(width 0.088646)
		(layer "In11.Cu")
		(net "M_H_CPU0_ALERT_N")
	)
	(segment
		(start 390.84377 -259.10032)
		(end 389.209788 -257.466338)
		(width 0.18288)
		(layer "In11.Cu")
		(net "M_H_CPU0_ALERT_N")
	)
	(segment
		(start 434.826664 -268.614906)
		(end 434.304948 -268.614906)
		(width 0.18288)
		(layer "In11.Cu")
		(net "M_H_CPU0_ALERT_N")
	)
	(segment
		(start 412.090362 -267.252196)
		(end 409.263088 -267.252196)
		(width 0.18288)
		(layer "In11.Cu")
		(net "M_H_CPU0_ALERT_N")
	)
	(segment
		(start 404.96998 -266.45362)
		(end 398.931638 -260.415278)
		(width 0.18288)
		(layer "In11.Cu")
		(net "M_H_CPU0_ALERT_N")
	)
	(segment
		(start 435.180994 -268.260576)
		(end 434.826664 -268.614906)
		(width 0.18288)
		(layer "In11.Cu")
		(net "M_H_CPU0_ALERT_N")
	)
	(segment
		(start 409.263088 -267.252196)
		(end 409.071572 -267.443712)
		(width 0.18288)
		(layer "In11.Cu")
		(net "M_H_CPU0_ALERT_N")
	)
	(segment
		(start 409.071572 -267.443712)
		(end 407.085292 -267.443712)
		(width 0.18288)
		(layer "In11.Cu")
		(net "M_H_CPU0_ALERT_N")
	)
	(segment
		(start 448.345814 -269.021306)
		(end 447.102484 -269.021306)
		(width 0.18288)
		(layer "In11.Cu")
		(net "M_H_CPU0_ALERT_N")
	)
	(segment
		(start 435.769512 -267.441172)
		(end 435.384448 -267.441172)
		(width 0.18288)
		(layer "In11.Cu")
		(net "M_H_CPU0_ALERT_N")
	)
	(segment
		(start 427.435518 -268.480286)
		(end 424.358054 -268.480286)
		(width 0.18288)
		(layer "In11.Cu")
		(net "M_H_CPU0_ALERT_N")
	)
	(segment
		(start 433.980082 -268.29004)
		(end 427.625764 -268.29004)
		(width 0.18288)
		(layer "In11.Cu")
		(net "M_H_CPU0_ALERT_N")
	)
	(segment
		(start 387.41604 -257.52171)
		(end 386.864606 -257.52171)
		(width 0.088646)
		(layer "In11.Cu")
		(net "M_H_CPU0_ALERT_N")
	)
	(segment
		(start 435.769766 -267.441426)
		(end 435.769512 -267.441172)
		(width 0.18288)
		(layer "In11.Cu")
		(net "M_H_CPU0_ALERT_N")
	)
	(segment
		(start 407.085292 -267.443712)
		(end 406.0952 -266.45362)
		(width 0.18288)
		(layer "In11.Cu")
		(net "M_H_CPU0_ALERT_N")
	)
	(segment
		(start 406.0952 -266.45362)
		(end 404.96998 -266.45362)
		(width 0.18288)
		(layer "In11.Cu")
		(net "M_H_CPU0_ALERT_N")
	)
	(segment
		(start 435.180994 -267.644626)
		(end 435.180994 -268.260576)
		(width 0.18288)
		(layer "In11.Cu")
		(net "M_H_CPU0_ALERT_N")
	)
	(segment
		(start 373.984774 -257.493516)
		(end 373.97436 -257.499612)
		(width 0.088646)
		(layer "In11.Cu")
		(net "M_H_CPU0_ALERT_N")
	)
	(segment
		(start 450.344286 -269.924022)
		(end 450.030342 -270.02867)
		(width 0.18288)
		(layer "In11.Cu")
		(net "M_H_CPU0_ALERT_N")
	)
	(segment
		(start 450.030342 -270.02867)
		(end 449.353178 -270.02867)
		(width 0.18288)
		(layer "In11.Cu")
		(net "M_H_CPU0_ALERT_N")
	)
	(segment
		(start 398.063974 -260.415278)
		(end 396.749016 -259.10032)
		(width 0.18288)
		(layer "In11.Cu")
		(net "M_H_CPU0_ALERT_N")
	)
	(segment
		(start 373.599964 -257.499612)
		(end 373.585232 -257.490976)
		(width 0.088646)
		(layer "In11.Cu")
		(net "M_H_CPU0_ALERT_N")
	)
	(segment
		(start 446.878964 -269.244826)
		(end 442.945012 -269.244826)
		(width 0.18288)
		(layer "In11.Cu")
		(net "M_H_CPU0_ALERT_N")
	)
	(segment
		(start 423.31894 -267.441172)
		(end 419.91534 -267.441172)
		(width 0.18288)
		(layer "In11.Cu")
		(net "M_H_CPU0_ALERT_N")
	)
	(segment
		(start 450.548756 -269.85595)
		(end 450.344286 -269.924022)
		(width 0.18288)
		(layer "In11.Cu")
		(net "M_H_CPU0_ALERT_N")
	)
	(segment
		(start 371.169946 -257.490976)
		(end 371.155214 -257.499612)
		(width 0.088646)
		(layer "In11.Cu")
		(net "M_H_CPU0_ALERT_N")
	)
	(segment
		(start 419.91534 -267.441172)
		(end 419.78961 -267.315442)
		(width 0.18288)
		(layer "In11.Cu")
		(net "M_H_CPU0_ALERT_N")
	)
	(segment
		(start 434.304948 -268.614906)
		(end 433.980082 -268.29004)
		(width 0.18288)
		(layer "In11.Cu")
		(net "M_H_CPU0_ALERT_N")
	)
	(segment
		(start 450.658484 -269.819374)
		(end 450.548756 -269.85595)
		(width 0.18288)
		(layer "In11.Cu")
		(net "M_H_CPU0_ALERT_N")
	)
	(segment
		(start 416.965384 -267.315442)
		(end 416.837114 -267.443712)
		(width 0.18288)
		(layer "In11.Cu")
		(net "M_H_CPU0_ALERT_N")
	)
	(segment
		(start 419.78961 -267.315442)
		(end 416.965384 -267.315442)
		(width 0.18288)
		(layer "In11.Cu")
		(net "M_H_CPU0_ALERT_N")
	)
	(segment
		(start 442.945012 -269.244826)
		(end 441.991242 -268.291056)
		(width 0.18288)
		(layer "In11.Cu")
		(net "M_H_CPU0_ALERT_N")
	)
	(segment
		(start 427.625764 -268.29004)
		(end 427.435518 -268.480286)
		(width 0.18288)
		(layer "In11.Cu")
		(net "M_H_CPU0_ALERT_N")
	)
	(segment
		(start 370.752116 -257.482848)
		(end 370.028216 -257.175254)
		(width 0.088646)
		(layer "In11.Cu")
		(net "M_H_CPU0_ALERT_N")
	)
	(segment
		(start 372.105428 -257.493516)
		(end 372.095014 -257.499612)
		(width 0.088646)
		(layer "In11.Cu")
		(net "M_H_CPU0_ALERT_N")
	)
	(segment
		(start 435.878986 -267.441426)
		(end 435.769766 -267.441426)
		(width 0.18288)
		(layer "In11.Cu")
		(net "M_H_CPU0_ALERT_N")
	)
	(segment
		(start 377.748546 -257.490976)
		(end 377.733814 -257.499612)
		(width 0.088646)
		(layer "In11.Cu")
		(net "M_H_CPU0_ALERT_N")
	)
	(segment
		(start 441.991242 -268.291056)
		(end 438.882028 -268.291056)
		(width 0.18288)
		(layer "In11.Cu")
		(net "M_H_CPU0_ALERT_N")
	)
	(segment
		(start 437.293766 -267.707364)
		(end 437.02732 -267.440918)
		(width 0.18288)
		(layer "In11.Cu")
		(net "M_H_CPU0_ALERT_N")
	)
	(segment
		(start 438.298336 -267.707364)
		(end 437.293766 -267.707364)
		(width 0.18288)
		(layer "In11.Cu")
		(net "M_H_CPU0_ALERT_N")
	)
	(segment
		(start 370.780818 -257.499612)
		(end 370.752116 -257.482848)
		(width 0.088646)
		(layer "In11.Cu")
		(net "M_H_CPU0_ALERT_N")
	)
	(segment
		(start 398.931638 -260.415278)
		(end 398.063974 -260.415278)
		(width 0.18288)
		(layer "In11.Cu")
		(net "M_H_CPU0_ALERT_N")
	)
	(segment
		(start 424.358054 -268.480286)
		(end 423.31894 -267.441172)
		(width 0.18288)
		(layer "In11.Cu")
		(net "M_H_CPU0_ALERT_N")
	)
	(segment
		(start 389.209788 -257.466338)
		(end 388.129018 -257.466338)
		(width 0.18288)
		(layer "In11.Cu")
		(net "M_H_CPU0_ALERT_N")
	)
	(segment
		(start 438.882028 -268.291056)
		(end 438.298336 -267.707364)
		(width 0.18288)
		(layer "In11.Cu")
		(net "M_H_CPU0_ALERT_N")
	)
	(segment
		(start 376.808746 -257.490976)
		(end 376.794014 -257.499612)
		(width 0.088646)
		(layer "In11.Cu")
		(net "M_H_CPU0_ALERT_N")
	)
	(segment
		(start 435.384448 -267.441172)
		(end 435.180994 -267.644626)
		(width 0.18288)
		(layer "In11.Cu")
		(net "M_H_CPU0_ALERT_N")
	)
	(segment
		(start 437.02732 -267.440918)
		(end 435.879494 -267.440918)
		(width 0.18288)
		(layer "In11.Cu")
		(net "M_H_CPU0_ALERT_N")
	)
	(segment
		(start 450.911214 -269.566644)
		(end 450.658484 -269.819374)
		(width 0.18288)
		(layer "In11.Cu")
		(net "M_H_CPU0_ALERT_N")
	)
	(segment
		(start 447.102484 -269.021306)
		(end 446.878964 -269.244826)
		(width 0.18288)
		(layer "In11.Cu")
		(net "M_H_CPU0_ALERT_N")
	)
	(segment
		(start 449.353178 -270.02867)
		(end 448.345814 -269.021306)
		(width 0.18288)
		(layer "In11.Cu")
		(net "M_H_CPU0_ALERT_N")
	)
	(segment
		(start 375.479564 -257.499612)
		(end 375.46915 -257.493516)
		(width 0.088646)
		(layer "In11.Cu")
		(net "M_H_CPU0_ALERT_N")
	)
	(segment
		(start 412.281878 -267.443712)
		(end 412.090362 -267.252196)
		(width 0.18288)
		(layer "In11.Cu")
		(net "M_H_CPU0_ALERT_N")
	)
	(segment
		(start 375.864374 -257.493516)
		(end 375.85396 -257.499612)
		(width 0.088646)
		(layer "In11.Cu")
		(net "M_H_CPU0_ALERT_N")
	)
	(segment
		(start 435.879494 -267.440918)
		(end 435.878986 -267.441426)
		(width 0.18288)
		(layer "In11.Cu")
		(net "M_H_CPU0_ALERT_N")
	)
	(segment
		(start 378.688346 -257.490976)
		(end 378.673614 -257.499612)
		(width 0.088646)
		(layer "In11.Cu")
		(net "M_H_CPU0_ALERT_N")
	)
	(segment
		(start 382.058164 -257.499612)
		(end 382.04775 -257.493516)
		(width 0.088646)
		(layer "In11.Cu")
		(net "M_H_CPU0_ALERT_N")
	)
	(segment
		(start 396.749016 -259.10032)
		(end 390.84377 -259.10032)
		(width 0.18288)
		(layer "In11.Cu")
		(net "M_H_CPU0_ALERT_N")
	)
	(arc
		(start 386.19176 -257.499612)
		(mid 386.004562 -257.549755)
		(end 385.817364 -257.499612)
		(width 0.088646)
		(layer "In11.Cu")
		(net "M_H_CPU0_ALERT_N")
	)
	(arc
		(start 383.937764 -257.499612)
		(mid 383.655062 -257.423836)
		(end 383.37236 -257.499612)
		(width 0.088646)
		(layer "In11.Cu")
		(net "M_H_CPU0_ALERT_N")
	)
	(arc
		(start 372.095014 -257.499612)
		(mid 371.907816 -257.549755)
		(end 371.720618 -257.499612)
		(width 0.088646)
		(layer "In11.Cu")
		(net "M_H_CPU0_ALERT_N")
	)
	(arc
		(start 377.359418 -257.499612)
		(mid 377.085219 -257.423777)
		(end 376.808746 -257.490976)
		(width 0.088646)
		(layer "In11.Cu")
		(net "M_H_CPU0_ALERT_N")
	)
	(arc
		(start 379.613414 -257.499612)
		(mid 379.426216 -257.549755)
		(end 379.239018 -257.499612)
		(width 0.088646)
		(layer "In11.Cu")
		(net "M_H_CPU0_ALERT_N")
	)
	(arc
		(start 384.862832 -257.490976)
		(mid 384.586357 -257.423656)
		(end 384.31216 -257.499612)
		(width 0.088646)
		(layer "In11.Cu")
		(net "M_H_CPU0_ALERT_N")
	)
	(arc
		(start 374.540018 -257.499612)
		(mid 374.263205 -257.423742)
		(end 373.984774 -257.493516)
		(width 0.088646)
		(layer "In11.Cu")
		(net "M_H_CPU0_ALERT_N")
	)
	(arc
		(start 371.155214 -257.499612)
		(mid 370.968016 -257.549755)
		(end 370.780818 -257.499612)
		(width 0.088646)
		(layer "In11.Cu")
		(net "M_H_CPU0_ALERT_N")
	)
	(arc
		(start 386.864606 -257.52171)
		(mid 386.801621 -257.513898)
		(end 386.742432 -257.490976)
		(width 0.088646)
		(layer "In11.Cu")
		(net "M_H_CPU0_ALERT_N")
	)
	(arc
		(start 381.493014 -257.499612)
		(mid 381.305816 -257.549755)
		(end 381.118618 -257.499612)
		(width 0.088646)
		(layer "In11.Cu")
		(net "M_H_CPU0_ALERT_N")
	)
	(arc
		(start 373.03456 -257.499612)
		(mid 372.847362 -257.549755)
		(end 372.660164 -257.499612)
		(width 0.088646)
		(layer "In11.Cu")
		(net "M_H_CPU0_ALERT_N")
	)
	(arc
		(start 384.31216 -257.499612)
		(mid 384.124962 -257.549755)
		(end 383.937764 -257.499612)
		(width 0.088646)
		(layer "In11.Cu")
		(net "M_H_CPU0_ALERT_N")
	)
	(arc
		(start 379.239018 -257.499612)
		(mid 378.964819 -257.423777)
		(end 378.688346 -257.490976)
		(width 0.088646)
		(layer "In11.Cu")
		(net "M_H_CPU0_ALERT_N")
	)
	(arc
		(start 383.37236 -257.499612)
		(mid 383.185162 -257.549755)
		(end 382.997964 -257.499612)
		(width 0.088646)
		(layer "In11.Cu")
		(net "M_H_CPU0_ALERT_N")
	)
	(arc
		(start 377.733814 -257.499612)
		(mid 377.546616 -257.549755)
		(end 377.359418 -257.499612)
		(width 0.088646)
		(layer "In11.Cu")
		(net "M_H_CPU0_ALERT_N")
	)
	(arc
		(start 380.16815 -257.493516)
		(mid 379.889972 -257.423793)
		(end 379.613414 -257.499612)
		(width 0.088646)
		(layer "In11.Cu")
		(net "M_H_CPU0_ALERT_N")
	)
	(arc
		(start 378.299218 -257.499612)
		(mid 378.025019 -257.423777)
		(end 377.748546 -257.490976)
		(width 0.088646)
		(layer "In11.Cu")
		(net "M_H_CPU0_ALERT_N")
	)
	(arc
		(start 382.997964 -257.499612)
		(mid 382.715262 -257.423836)
		(end 382.43256 -257.499612)
		(width 0.088646)
		(layer "In11.Cu")
		(net "M_H_CPU0_ALERT_N")
	)
	(arc
		(start 373.97436 -257.499612)
		(mid 373.787162 -257.549755)
		(end 373.599964 -257.499612)
		(width 0.088646)
		(layer "In11.Cu")
		(net "M_H_CPU0_ALERT_N")
	)
	(arc
		(start 380.55296 -257.499612)
		(mid 380.365762 -257.549755)
		(end 380.178564 -257.499612)
		(width 0.088646)
		(layer "In11.Cu")
		(net "M_H_CPU0_ALERT_N")
	)
	(arc
		(start 385.802632 -257.490976)
		(mid 385.526157 -257.423656)
		(end 385.25196 -257.499612)
		(width 0.088646)
		(layer "In11.Cu")
		(net "M_H_CPU0_ALERT_N")
	)
	(arc
		(start 378.673614 -257.499612)
		(mid 378.486416 -257.549755)
		(end 378.299218 -257.499612)
		(width 0.088646)
		(layer "In11.Cu")
		(net "M_H_CPU0_ALERT_N")
	)
	(arc
		(start 375.46915 -257.493516)
		(mid 375.191116 -257.423916)
		(end 374.914668 -257.499612)
		(width 0.088646)
		(layer "In11.Cu")
		(net "M_H_CPU0_ALERT_N")
	)
	(arc
		(start 382.04775 -257.493516)
		(mid 381.769572 -257.423793)
		(end 381.493014 -257.499612)
		(width 0.088646)
		(layer "In11.Cu")
		(net "M_H_CPU0_ALERT_N")
	)
	(arc
		(start 381.118618 -257.499612)
		(mid 380.841805 -257.423742)
		(end 380.563374 -257.493516)
		(width 0.088646)
		(layer "In11.Cu")
		(net "M_H_CPU0_ALERT_N")
	)
	(arc
		(start 371.720618 -257.499612)
		(mid 371.446419 -257.423777)
		(end 371.169946 -257.490976)
		(width 0.088646)
		(layer "In11.Cu")
		(net "M_H_CPU0_ALERT_N")
	)
	(arc
		(start 372.660164 -257.499612)
		(mid 372.383605 -257.423869)
		(end 372.105428 -257.493516)
		(width 0.088646)
		(layer "In11.Cu")
		(net "M_H_CPU0_ALERT_N")
	)
	(arc
		(start 385.25196 -257.499612)
		(mid 385.064762 -257.549755)
		(end 384.877564 -257.499612)
		(width 0.088646)
		(layer "In11.Cu")
		(net "M_H_CPU0_ALERT_N")
	)
	(arc
		(start 376.794014 -257.499612)
		(mid 376.606816 -257.549755)
		(end 376.419618 -257.499612)
		(width 0.088646)
		(layer "In11.Cu")
		(net "M_H_CPU0_ALERT_N")
	)
	(arc
		(start 387.458966 -257.50393)
		(mid 387.439271 -257.51709)
		(end 387.41604 -257.52171)
		(width 0.088646)
		(layer "In11.Cu")
		(net "M_H_CPU0_ALERT_N")
	)
	(arc
		(start 387.549644 -257.466338)
		(mid 387.500557 -257.476102)
		(end 387.458966 -257.50393)
		(width 0.088646)
		(layer "In11.Cu")
		(net "M_H_CPU0_ALERT_N")
	)
	(arc
		(start 376.419618 -257.499612)
		(mid 376.142805 -257.423742)
		(end 375.864374 -257.493516)
		(width 0.088646)
		(layer "In11.Cu")
		(net "M_H_CPU0_ALERT_N")
	)
	(arc
		(start 375.85396 -257.499612)
		(mid 375.666762 -257.549755)
		(end 375.479564 -257.499612)
		(width 0.088646)
		(layer "In11.Cu")
		(net "M_H_CPU0_ALERT_N")
	)
	(arc
		(start 382.43256 -257.499612)
		(mid 382.245362 -257.549755)
		(end 382.058164 -257.499612)
		(width 0.088646)
		(layer "In11.Cu")
		(net "M_H_CPU0_ALERT_N")
	)
	(arc
		(start 386.742432 -257.490976)
		(mid 386.465957 -257.423656)
		(end 386.19176 -257.499612)
		(width 0.088646)
		(layer "In11.Cu")
		(net "M_H_CPU0_ALERT_N")
	)
	(arc
		(start 373.585232 -257.490976)
		(mid 373.308757 -257.423656)
		(end 373.03456 -257.499612)
		(width 0.088646)
		(layer "In11.Cu")
		(net "M_H_CPU0_ALERT_N")
	)
	(arc
		(start 374.914668 -257.499612)
		(mid 374.72736 -257.549755)
		(end 374.540018 -257.499612)
		(width 0.088646)
		(layer "In11.Cu")
		(net "M_H_CPU0_ALERT_N")
	)
	(segment
		(start 188.988446 -243.216684)
		(end 187.883546 -243.216684)
		(width 0.20066)
		(layer "F.Cu")
		(net "M_G_CPU1_SB_RSP<1>")
	)
	(segment
		(start 130.546094 -253.383796)
		(end 130.546348 -253.38405)
		(width 0.20066)
		(layer "F.Cu")
		(net "M_G_CPU1_SB_RSP<1>")
	)
	(segment
		(start 130.546348 -253.38405)
		(end 130.546348 -253.919736)
		(width 0.20066)
		(layer "F.Cu")
		(net "M_G_CPU1_SB_RSP<1>")
	)
	(segment
		(start 178.794156 -246.734076)
		(end 178.535584 -246.734076)
		(width 0.18288)
		(layer "In6.Cu")
		(net "M_G_CPU1_SB_RSP<1>")
	)
	(segment
		(start 178.089052 -246.287544)
		(end 177.83048 -246.287544)
		(width 0.18288)
		(layer "In6.Cu")
		(net "M_G_CPU1_SB_RSP<1>")
	)
	(segment
		(start 177.598578 -246.778018)
		(end 178.04511 -247.22455)
		(width 0.18288)
		(layer "In6.Cu")
		(net "M_G_CPU1_SB_RSP<1>")
	)
	(segment
		(start 178.04511 -247.483122)
		(end 177.635916 -247.892316)
		(width 0.18288)
		(layer "In6.Cu")
		(net "M_G_CPU1_SB_RSP<1>")
	)
	(segment
		(start 168.981628 -247.892316)
		(end 168.020746 -248.853198)
		(width 0.18288)
		(layer "In6.Cu")
		(net "M_G_CPU1_SB_RSP<1>")
	)
	(segment
		(start 145.825718 -254.28067)
		(end 145.033746 -254.122682)
		(width 0.18288)
		(layer "In6.Cu")
		(net "M_G_CPU1_SB_RSP<1>")
	)
	(segment
		(start 147.029932 -254.28067)
		(end 145.825718 -254.28067)
		(width 0.18288)
		(layer "In6.Cu")
		(net "M_G_CPU1_SB_RSP<1>")
	)
	(segment
		(start 184.018936 -244.494304)
		(end 183.687466 -244.825774)
		(width 0.18288)
		(layer "In6.Cu")
		(net "M_G_CPU1_SB_RSP<1>")
	)
	(segment
		(start 180.763672 -246.188484)
		(end 179.339748 -246.188484)
		(width 0.18288)
		(layer "In6.Cu")
		(net "M_G_CPU1_SB_RSP<1>")
	)
	(segment
		(start 179.339748 -246.188484)
		(end 178.794156 -246.734076)
		(width 0.18288)
		(layer "In6.Cu")
		(net "M_G_CPU1_SB_RSP<1>")
	)
	(segment
		(start 181.779164 -245.562374)
		(end 181.652164 -245.689374)
		(width 0.18288)
		(layer "In6.Cu")
		(net "M_G_CPU1_SB_RSP<1>")
	)
	(segment
		(start 181.492144 -246.568976)
		(end 181.144164 -246.568976)
		(width 0.18288)
		(layer "In6.Cu")
		(net "M_G_CPU1_SB_RSP<1>")
	)
	(segment
		(start 145.033746 -254.122682)
		(end 144.560544 -253.927102)
		(width 0.18288)
		(layer "In6.Cu")
		(net "M_G_CPU1_SB_RSP<1>")
	)
	(segment
		(start 183.687466 -244.825774)
		(end 183.687466 -245.290086)
		(width 0.18288)
		(layer "In6.Cu")
		(net "M_G_CPU1_SB_RSP<1>")
	)
	(segment
		(start 160.6169 -250.503436)
		(end 156.447998 -250.503436)
		(width 0.18288)
		(layer "In6.Cu")
		(net "M_G_CPU1_SB_RSP<1>")
	)
	(segment
		(start 185.438288 -244.494304)
		(end 184.018936 -244.494304)
		(width 0.18288)
		(layer "In6.Cu")
		(net "M_G_CPU1_SB_RSP<1>")
	)
	(segment
		(start 181.144164 -246.568976)
		(end 180.763672 -246.188484)
		(width 0.18288)
		(layer "In6.Cu")
		(net "M_G_CPU1_SB_RSP<1>")
	)
	(segment
		(start 178.04511 -247.22455)
		(end 178.04511 -247.483122)
		(width 0.18288)
		(layer "In6.Cu")
		(net "M_G_CPU1_SB_RSP<1>")
	)
	(segment
		(start 165.603682 -248.853198)
		(end 164.663882 -249.792998)
		(width 0.18288)
		(layer "In6.Cu")
		(net "M_G_CPU1_SB_RSP<1>")
	)
	(segment
		(start 155.882848 -251.068586)
		(end 150.242016 -251.068586)
		(width 0.18288)
		(layer "In6.Cu")
		(net "M_G_CPU1_SB_RSP<1>")
	)
	(segment
		(start 177.83048 -246.287544)
		(end 177.598578 -246.519446)
		(width 0.18288)
		(layer "In6.Cu")
		(net "M_G_CPU1_SB_RSP<1>")
	)
	(segment
		(start 150.242016 -251.068586)
		(end 147.029932 -254.28067)
		(width 0.18288)
		(layer "In6.Cu")
		(net "M_G_CPU1_SB_RSP<1>")
	)
	(segment
		(start 168.020746 -248.853198)
		(end 165.603682 -248.853198)
		(width 0.18288)
		(layer "In6.Cu")
		(net "M_G_CPU1_SB_RSP<1>")
	)
	(segment
		(start 186.715908 -243.216684)
		(end 185.438288 -244.494304)
		(width 0.18288)
		(layer "In6.Cu")
		(net "M_G_CPU1_SB_RSP<1>")
	)
	(segment
		(start 164.663882 -249.792998)
		(end 161.327338 -249.792998)
		(width 0.18288)
		(layer "In6.Cu")
		(net "M_G_CPU1_SB_RSP<1>")
	)
	(segment
		(start 156.447998 -250.503436)
		(end 155.882848 -251.068586)
		(width 0.18288)
		(layer "In6.Cu")
		(net "M_G_CPU1_SB_RSP<1>")
	)
	(segment
		(start 177.598578 -246.519446)
		(end 177.598578 -246.778018)
		(width 0.18288)
		(layer "In6.Cu")
		(net "M_G_CPU1_SB_RSP<1>")
	)
	(segment
		(start 187.883546 -243.216684)
		(end 186.715908 -243.216684)
		(width 0.18288)
		(layer "In6.Cu")
		(net "M_G_CPU1_SB_RSP<1>")
	)
	(segment
		(start 183.415178 -245.562374)
		(end 181.779164 -245.562374)
		(width 0.18288)
		(layer "In6.Cu")
		(net "M_G_CPU1_SB_RSP<1>")
	)
	(segment
		(start 161.327338 -249.792998)
		(end 160.6169 -250.503436)
		(width 0.18288)
		(layer "In6.Cu")
		(net "M_G_CPU1_SB_RSP<1>")
	)
	(segment
		(start 130.546348 -253.130304)
		(end 130.546348 -253.919736)
		(width 0.18288)
		(layer "In6.Cu")
		(net "M_G_CPU1_SB_RSP<1>")
	)
	(segment
		(start 144.560544 -253.927102)
		(end 143.12519 -252.491748)
		(width 0.18288)
		(layer "In6.Cu")
		(net "M_G_CPU1_SB_RSP<1>")
	)
	(segment
		(start 181.652164 -245.689374)
		(end 181.652164 -246.408956)
		(width 0.18288)
		(layer "In6.Cu")
		(net "M_G_CPU1_SB_RSP<1>")
	)
	(segment
		(start 177.635916 -247.892316)
		(end 168.981628 -247.892316)
		(width 0.18288)
		(layer "In6.Cu")
		(net "M_G_CPU1_SB_RSP<1>")
	)
	(segment
		(start 131.184904 -252.491748)
		(end 130.546348 -253.130304)
		(width 0.18288)
		(layer "In6.Cu")
		(net "M_G_CPU1_SB_RSP<1>")
	)
	(segment
		(start 181.652164 -246.408956)
		(end 181.492144 -246.568976)
		(width 0.18288)
		(layer "In6.Cu")
		(net "M_G_CPU1_SB_RSP<1>")
	)
	(segment
		(start 178.535584 -246.734076)
		(end 178.089052 -246.287544)
		(width 0.18288)
		(layer "In6.Cu")
		(net "M_G_CPU1_SB_RSP<1>")
	)
	(segment
		(start 183.687466 -245.290086)
		(end 183.415178 -245.562374)
		(width 0.18288)
		(layer "In6.Cu")
		(net "M_G_CPU1_SB_RSP<1>")
	)
	(segment
		(start 143.12519 -252.491748)
		(end 131.184904 -252.491748)
		(width 0.18288)
		(layer "In6.Cu")
		(net "M_G_CPU1_SB_RSP<1>")
	)
	(segment
		(start 196.532246 -243.216684)
		(end 195.427346 -243.216684)
		(width 0.20066)
		(layer "F.Cu")
		(net "M_G_CPU1_SB_RSP<0>")
	)
	(segment
		(start 130.076448 -254.733298)
		(end 130.076194 -254.733552)
		(width 0.20066)
		(layer "F.Cu")
		(net "M_G_CPU1_SB_RSP<0>")
	)
	(segment
		(start 130.076448 -254.197612)
		(end 130.076448 -254.733298)
		(width 0.20066)
		(layer "F.Cu")
		(net "M_G_CPU1_SB_RSP<0>")
	)
	(segment
		(start 178.701446 -248.612406)
		(end 177.721514 -249.592338)
		(width 0.18288)
		(layer "In6.Cu")
		(net "M_G_CPU1_SB_RSP<0>")
	)
	(segment
		(start 131.860544 -253.517908)
		(end 131.860544 -253.94412)
		(width 0.088646)
		(layer "In6.Cu")
		(net "M_G_CPU1_SB_RSP<0>")
	)
	(segment
		(start 189.974982 -245.34241)
		(end 189.125098 -246.192294)
		(width 0.18288)
		(layer "In6.Cu")
		(net "M_G_CPU1_SB_RSP<0>")
	)
	(segment
		(start 155.317444 -253.23165)
		(end 149.727158 -253.23165)
		(width 0.18288)
		(layer "In6.Cu")
		(net "M_G_CPU1_SB_RSP<0>")
	)
	(segment
		(start 186.343798 -246.192294)
		(end 184.57926 -247.956832)
		(width 0.18288)
		(layer "In6.Cu")
		(net "M_G_CPU1_SB_RSP<0>")
	)
	(segment
		(start 131.49326 -254.309626)
		(end 130.814826 -254.309626)
		(width 0.088646)
		(layer "In6.Cu")
		(net "M_G_CPU1_SB_RSP<0>")
	)
	(segment
		(start 192.278762 -245.34241)
		(end 189.974982 -245.34241)
		(width 0.18288)
		(layer "In6.Cu")
		(net "M_G_CPU1_SB_RSP<0>")
	)
	(segment
		(start 167.10406 -250.54306)
		(end 165.34003 -252.30709)
		(width 0.18288)
		(layer "In6.Cu")
		(net "M_G_CPU1_SB_RSP<0>")
	)
	(segment
		(start 169.041318 -249.592338)
		(end 168.090596 -250.54306)
		(width 0.18288)
		(layer "In6.Cu")
		(net "M_G_CPU1_SB_RSP<0>")
	)
	(segment
		(start 147.762214 -255.196594)
		(end 145.874486 -255.196594)
		(width 0.18288)
		(layer "In6.Cu")
		(net "M_G_CPU1_SB_RSP<0>")
	)
	(segment
		(start 145.874486 -255.196594)
		(end 144.87398 -254.997712)
		(width 0.18288)
		(layer "In6.Cu")
		(net "M_G_CPU1_SB_RSP<0>")
	)
	(segment
		(start 136.263634 -253.19355)
		(end 132.184902 -253.19355)
		(width 0.088646)
		(layer "In6.Cu")
		(net "M_G_CPU1_SB_RSP<0>")
	)
	(segment
		(start 142.566898 -253.19355)
		(end 136.263634 -253.19355)
		(width 0.18288)
		(layer "In6.Cu")
		(net "M_G_CPU1_SB_RSP<0>")
	)
	(segment
		(start 179.999386 -248.92889)
		(end 179.682902 -248.612406)
		(width 0.18288)
		(layer "In6.Cu")
		(net "M_G_CPU1_SB_RSP<0>")
	)
	(segment
		(start 184.57926 -247.956832)
		(end 182.2323 -248.92889)
		(width 0.18288)
		(layer "In6.Cu")
		(net "M_G_CPU1_SB_RSP<0>")
	)
	(segment
		(start 179.682902 -248.612406)
		(end 178.701446 -248.612406)
		(width 0.18288)
		(layer "In6.Cu")
		(net "M_G_CPU1_SB_RSP<0>")
	)
	(segment
		(start 130.814826 -254.309626)
		(end 130.076194 -254.733552)
		(width 0.088646)
		(layer "In6.Cu")
		(net "M_G_CPU1_SB_RSP<0>")
	)
	(segment
		(start 168.090596 -250.54306)
		(end 167.10406 -250.54306)
		(width 0.18288)
		(layer "In6.Cu")
		(net "M_G_CPU1_SB_RSP<0>")
	)
	(segment
		(start 182.2323 -248.92889)
		(end 179.999386 -248.92889)
		(width 0.18288)
		(layer "In6.Cu")
		(net "M_G_CPU1_SB_RSP<0>")
	)
	(segment
		(start 189.125098 -246.192294)
		(end 186.343798 -246.192294)
		(width 0.18288)
		(layer "In6.Cu")
		(net "M_G_CPU1_SB_RSP<0>")
	)
	(segment
		(start 194.404488 -243.216684)
		(end 192.278762 -245.34241)
		(width 0.18288)
		(layer "In6.Cu")
		(net "M_G_CPU1_SB_RSP<0>")
	)
	(segment
		(start 195.427346 -243.216684)
		(end 194.404488 -243.216684)
		(width 0.18288)
		(layer "In6.Cu")
		(net "M_G_CPU1_SB_RSP<0>")
	)
	(segment
		(start 149.727158 -253.23165)
		(end 147.762214 -255.196594)
		(width 0.18288)
		(layer "In6.Cu")
		(net "M_G_CPU1_SB_RSP<0>")
	)
	(segment
		(start 144.015206 -254.641858)
		(end 142.566898 -253.19355)
		(width 0.18288)
		(layer "In6.Cu")
		(net "M_G_CPU1_SB_RSP<0>")
	)
	(segment
		(start 156.242004 -252.30709)
		(end 155.317444 -253.23165)
		(width 0.18288)
		(layer "In6.Cu")
		(net "M_G_CPU1_SB_RSP<0>")
	)
	(segment
		(start 132.184902 -253.19355)
		(end 131.860544 -253.517908)
		(width 0.088646)
		(layer "In6.Cu")
		(net "M_G_CPU1_SB_RSP<0>")
	)
	(segment
		(start 177.721514 -249.592338)
		(end 169.041318 -249.592338)
		(width 0.18288)
		(layer "In6.Cu")
		(net "M_G_CPU1_SB_RSP<0>")
	)
	(segment
		(start 144.87398 -254.997712)
		(end 144.015206 -254.641858)
		(width 0.18288)
		(layer "In6.Cu")
		(net "M_G_CPU1_SB_RSP<0>")
	)
	(segment
		(start 165.34003 -252.30709)
		(end 156.242004 -252.30709)
		(width 0.18288)
		(layer "In6.Cu")
		(net "M_G_CPU1_SB_RSP<0>")
	)
	(arc
		(start 131.684522 -254.258826)
		(mid 131.592205 -254.296698)
		(end 131.49326 -254.309626)
		(width 0.088646)
		(layer "In6.Cu")
		(net "M_G_CPU1_SB_RSP<0>")
	)
	(arc
		(start 131.860544 -253.94412)
		(mid 131.813547 -254.124411)
		(end 131.684522 -254.258826)
		(width 0.088646)
		(layer "In6.Cu")
		(net "M_G_CPU1_SB_RSP<0>")
	)
	(segment
		(start 191.958214 -246.616728)
		(end 193.088514 -246.616728)
		(width 0.20066)
		(layer "F.Cu")
		(net "M_G_CPU1_SB_PAR")
	)
	(segment
		(start 195.159884 -247.052338)
		(end 195.510658 -247.052338)
		(width 0.20066)
		(layer "F.Cu")
		(net "M_G_CPU1_SB_PAR")
	)
	(segment
		(start 199.517762 -246.616728)
		(end 200.632314 -246.616728)
		(width 0.20066)
		(layer "F.Cu")
		(net "M_G_CPU1_SB_PAR")
	)
	(segment
		(start 132.315966 -247.714008)
		(end 132.315966 -247.178322)
		(width 0.20066)
		(layer "F.Cu")
		(net "M_G_CPU1_SB_PAR")
	)
	(segment
		(start 197.816724 -247.049036)
		(end 198.681594 -246.184166)
		(width 0.20066)
		(layer "F.Cu")
		(net "M_G_CPU1_SB_PAR")
	)
	(segment
		(start 197.535292 -247.04167)
		(end 197.542658 -247.049036)
		(width 0.1016)
		(layer "F.Cu")
		(net "M_G_CPU1_SB_PAR")
	)
	(segment
		(start 193.088514 -246.616728)
		(end 194.724274 -246.616728)
		(width 0.20066)
		(layer "F.Cu")
		(net "M_G_CPU1_SB_PAR")
	)
	(segment
		(start 198.681594 -246.184166)
		(end 199.0852 -246.184166)
		(width 0.20066)
		(layer "F.Cu")
		(net "M_G_CPU1_SB_PAR")
	)
	(segment
		(start 199.0852 -246.184166)
		(end 199.517762 -246.616728)
		(width 0.20066)
		(layer "F.Cu")
		(net "M_G_CPU1_SB_PAR")
	)
	(segment
		(start 195.510658 -247.052338)
		(end 195.515484 -247.052338)
		(width 0.101854)
		(layer "F.Cu")
		(net "M_G_CPU1_SB_PAR")
	)
	(segment
		(start 132.315712 -247.714262)
		(end 132.315966 -247.714008)
		(width 0.20066)
		(layer "F.Cu")
		(net "M_G_CPU1_SB_PAR")
	)
	(segment
		(start 195.515484 -247.052338)
		(end 195.526152 -247.04167)
		(width 0.1016)
		(layer "F.Cu")
		(net "M_G_CPU1_SB_PAR")
	)
	(segment
		(start 197.542658 -247.049036)
		(end 197.816724 -247.049036)
		(width 0.20066)
		(layer "F.Cu")
		(net "M_G_CPU1_SB_PAR")
	)
	(segment
		(start 195.526152 -247.04167)
		(end 197.535292 -247.04167)
		(width 0.1016)
		(layer "F.Cu")
		(net "M_G_CPU1_SB_PAR")
	)
	(segment
		(start 194.724274 -246.616728)
		(end 195.159884 -247.052338)
		(width 0.20066)
		(layer "F.Cu")
		(net "M_G_CPU1_SB_PAR")
	)
	(segment
		(start 183.133492 -246.800624)
		(end 182.86349 -247.070626)
		(width 0.18288)
		(layer "In4.Cu")
		(net "M_G_CPU1_SB_PAR")
	)
	(segment
		(start 137.35558 -247.592342)
		(end 136.005062 -247.592342)
		(width 0.088646)
		(layer "In4.Cu")
		(net "M_G_CPU1_SB_PAR")
	)
	(segment
		(start 177.107596 -247.042432)
		(end 176.750726 -247.042432)
		(width 0.18288)
		(layer "In4.Cu")
		(net "M_G_CPU1_SB_PAR")
	)
	(segment
		(start 173.139608 -247.040908)
		(end 157.570424 -247.040908)
		(width 0.18288)
		(layer "In4.Cu")
		(net "M_G_CPU1_SB_PAR")
	)
	(segment
		(start 157.570424 -247.040908)
		(end 155.288742 -246.095774)
		(width 0.18288)
		(layer "In4.Cu")
		(net "M_G_CPU1_SB_PAR")
	)
	(segment
		(start 188.434726 -247.202452)
		(end 188.274706 -247.042432)
		(width 0.18288)
		(layer "In4.Cu")
		(net "M_G_CPU1_SB_PAR")
	)
	(segment
		(start 176.750726 -247.042432)
		(end 176.750472 -247.042686)
		(width 0.18288)
		(layer "In4.Cu")
		(net "M_G_CPU1_SB_PAR")
	)
	(segment
		(start 133.076696 -247.507506)
		(end 133.068314 -247.50268)
		(width 0.088646)
		(layer "In4.Cu")
		(net "M_G_CPU1_SB_PAR")
	)
	(segment
		(start 191.696848 -247.890792)
		(end 191.431926 -248.155714)
		(width 0.18288)
		(layer "In4.Cu")
		(net "M_G_CPU1_SB_PAR")
	)
	(segment
		(start 179.839366 -247.070626)
		(end 179.636166 -246.867426)
		(width 0.18288)
		(layer "In4.Cu")
		(net "M_G_CPU1_SB_PAR")
	)
	(segment
		(start 192.335912 -246.994426)
		(end 193.583306 -246.994426)
		(width 0.18288)
		(layer "In4.Cu")
		(net "M_G_CPU1_SB_PAR")
	)
	(segment
		(start 148.543518 -246.095774)
		(end 148.306028 -246.333264)
		(width 0.18288)
		(layer "In4.Cu")
		(net "M_G_CPU1_SB_PAR")
	)
	(segment
		(start 184.206134 -246.829072)
		(end 183.96458 -247.070626)
		(width 0.18288)
		(layer "In4.Cu")
		(net "M_G_CPU1_SB_PAR")
	)
	(segment
		(start 176.750472 -247.042686)
		(end 173.141386 -247.042686)
		(width 0.18288)
		(layer "In4.Cu")
		(net "M_G_CPU1_SB_PAR")
	)
	(segment
		(start 187.164472 -246.829072)
		(end 185.285634 -246.829072)
		(width 0.18288)
		(layer "In4.Cu")
		(net "M_G_CPU1_SB_PAR")
	)
	(segment
		(start 137.441178 -247.506744)
		(end 137.35558 -247.592342)
		(width 0.088646)
		(layer "In4.Cu")
		(net "M_G_CPU1_SB_PAR")
	)
	(segment
		(start 193.743326 -247.566942)
		(end 193.419476 -247.890792)
		(width 0.18288)
		(layer "In4.Cu")
		(net "M_G_CPU1_SB_PAR")
	)
	(segment
		(start 191.431926 -248.764806)
		(end 191.271906 -248.924826)
		(width 0.18288)
		(layer "In4.Cu")
		(net "M_G_CPU1_SB_PAR")
	)
	(segment
		(start 183.34101 -246.800624)
		(end 183.133492 -246.800624)
		(width 0.18288)
		(layer "In4.Cu")
		(net "M_G_CPU1_SB_PAR")
	)
	(segment
		(start 184.82437 -247.045226)
		(end 184.608216 -246.829072)
		(width 0.18288)
		(layer "In4.Cu")
		(net "M_G_CPU1_SB_PAR")
	)
	(segment
		(start 193.583306 -246.994426)
		(end 193.743326 -247.154446)
		(width 0.18288)
		(layer "In4.Cu")
		(net "M_G_CPU1_SB_PAR")
	)
	(segment
		(start 148.306028 -246.333264)
		(end 142.468092 -246.333264)
		(width 0.18288)
		(layer "In4.Cu")
		(net "M_G_CPU1_SB_PAR")
	)
	(segment
		(start 155.288742 -246.095774)
		(end 148.543518 -246.095774)
		(width 0.18288)
		(layer "In4.Cu")
		(net "M_G_CPU1_SB_PAR")
	)
	(segment
		(start 173.141386 -247.042686)
		(end 173.139608 -247.040908)
		(width 0.18288)
		(layer "In4.Cu")
		(net "M_G_CPU1_SB_PAR")
	)
	(segment
		(start 193.419476 -247.890792)
		(end 191.696848 -247.890792)
		(width 0.18288)
		(layer "In4.Cu")
		(net "M_G_CPU1_SB_PAR")
	)
	(segment
		(start 134.008368 -247.50268)
		(end 133.993636 -247.494044)
		(width 0.088646)
		(layer "In4.Cu")
		(net "M_G_CPU1_SB_PAR")
	)
	(segment
		(start 189.170056 -248.255536)
		(end 188.699902 -248.255536)
		(width 0.18288)
		(layer "In4.Cu")
		(net "M_G_CPU1_SB_PAR")
	)
	(segment
		(start 142.468092 -246.333264)
		(end 141.294612 -247.506744)
		(width 0.18288)
		(layer "In4.Cu")
		(net "M_G_CPU1_SB_PAR")
	)
	(segment
		(start 188.274706 -247.042432)
		(end 187.377832 -247.042432)
		(width 0.18288)
		(layer "In4.Cu")
		(net "M_G_CPU1_SB_PAR")
	)
	(segment
		(start 137.82675 -247.506744)
		(end 137.441178 -247.506744)
		(width 0.088646)
		(layer "In4.Cu")
		(net "M_G_CPU1_SB_PAR")
	)
	(segment
		(start 189.321186 -248.406666)
		(end 189.170056 -248.255536)
		(width 0.18288)
		(layer "In4.Cu")
		(net "M_G_CPU1_SB_PAR")
	)
	(segment
		(start 177.282602 -246.867426)
		(end 177.107596 -247.042432)
		(width 0.18288)
		(layer "In4.Cu")
		(net "M_G_CPU1_SB_PAR")
	)
	(segment
		(start 182.86349 -247.070626)
		(end 179.839366 -247.070626)
		(width 0.18288)
		(layer "In4.Cu")
		(net "M_G_CPU1_SB_PAR")
	)
	(segment
		(start 189.519306 -248.924826)
		(end 189.321186 -248.726706)
		(width 0.18288)
		(layer "In4.Cu")
		(net "M_G_CPU1_SB_PAR")
	)
	(segment
		(start 187.377832 -247.042432)
		(end 187.164472 -246.829072)
		(width 0.18288)
		(layer "In4.Cu")
		(net "M_G_CPU1_SB_PAR")
	)
	(segment
		(start 183.96458 -247.070626)
		(end 183.611012 -247.070626)
		(width 0.18288)
		(layer "In4.Cu")
		(net "M_G_CPU1_SB_PAR")
	)
	(segment
		(start 193.743326 -247.154446)
		(end 193.743326 -247.566942)
		(width 0.18288)
		(layer "In4.Cu")
		(net "M_G_CPU1_SB_PAR")
	)
	(segment
		(start 184.608216 -246.829072)
		(end 184.206134 -246.829072)
		(width 0.18288)
		(layer "In4.Cu")
		(net "M_G_CPU1_SB_PAR")
	)
	(segment
		(start 185.285634 -246.829072)
		(end 185.06948 -247.045226)
		(width 0.18288)
		(layer "In4.Cu")
		(net "M_G_CPU1_SB_PAR")
	)
	(segment
		(start 191.431926 -248.155714)
		(end 191.431926 -248.764806)
		(width 0.18288)
		(layer "In4.Cu")
		(net "M_G_CPU1_SB_PAR")
	)
	(segment
		(start 191.271906 -248.924826)
		(end 189.519306 -248.924826)
		(width 0.18288)
		(layer "In4.Cu")
		(net "M_G_CPU1_SB_PAR")
	)
	(segment
		(start 191.958214 -246.616728)
		(end 192.335912 -246.994426)
		(width 0.18288)
		(layer "In4.Cu")
		(net "M_G_CPU1_SB_PAR")
	)
	(segment
		(start 183.611012 -247.070626)
		(end 183.34101 -246.800624)
		(width 0.18288)
		(layer "In4.Cu")
		(net "M_G_CPU1_SB_PAR")
	)
	(segment
		(start 141.294612 -247.506744)
		(end 137.82675 -247.506744)
		(width 0.18288)
		(layer "In4.Cu")
		(net "M_G_CPU1_SB_PAR")
	)
	(segment
		(start 185.06948 -247.045226)
		(end 184.82437 -247.045226)
		(width 0.18288)
		(layer "In4.Cu")
		(net "M_G_CPU1_SB_PAR")
	)
	(segment
		(start 188.434726 -247.99036)
		(end 188.434726 -247.202452)
		(width 0.18288)
		(layer "In4.Cu")
		(net "M_G_CPU1_SB_PAR")
	)
	(segment
		(start 179.636166 -246.867426)
		(end 177.282602 -246.867426)
		(width 0.18288)
		(layer "In4.Cu")
		(net "M_G_CPU1_SB_PAR")
	)
	(segment
		(start 134.948168 -247.50268)
		(end 134.933436 -247.494044)
		(width 0.088646)
		(layer "In4.Cu")
		(net "M_G_CPU1_SB_PAR")
	)
	(segment
		(start 189.321186 -248.726706)
		(end 189.321186 -248.406666)
		(width 0.18288)
		(layer "In4.Cu")
		(net "M_G_CPU1_SB_PAR")
	)
	(segment
		(start 188.699902 -248.255536)
		(end 188.434726 -247.99036)
		(width 0.18288)
		(layer "In4.Cu")
		(net "M_G_CPU1_SB_PAR")
	)
	(segment
		(start 133.068314 -247.50268)
		(end 132.685282 -247.278398)
		(width 0.088646)
		(layer "In4.Cu")
		(net "M_G_CPU1_SB_PAR")
	)
	(arc
		(start 133.993636 -247.494044)
		(mid 133.717161 -247.426724)
		(end 133.442964 -247.50268)
		(width 0.088646)
		(layer "In4.Cu")
		(net "M_G_CPU1_SB_PAR")
	)
	(arc
		(start 132.685282 -247.278398)
		(mid 132.507292 -247.203736)
		(end 132.315966 -247.178322)
		(width 0.088646)
		(layer "In4.Cu")
		(net "M_G_CPU1_SB_PAR")
	)
	(arc
		(start 136.005062 -247.592342)
		(mid 135.949457 -247.543668)
		(end 135.887968 -247.50268)
		(width 0.088646)
		(layer "In4.Cu")
		(net "M_G_CPU1_SB_PAR")
	)
	(arc
		(start 135.322564 -247.50268)
		(mid 135.135366 -247.552823)
		(end 134.948168 -247.50268)
		(width 0.088646)
		(layer "In4.Cu")
		(net "M_G_CPU1_SB_PAR")
	)
	(arc
		(start 133.442964 -247.50268)
		(mid 133.260459 -247.552918)
		(end 133.076696 -247.507506)
		(width 0.088646)
		(layer "In4.Cu")
		(net "M_G_CPU1_SB_PAR")
	)
	(arc
		(start 134.382764 -247.50268)
		(mid 134.195566 -247.552823)
		(end 134.008368 -247.50268)
		(width 0.088646)
		(layer "In4.Cu")
		(net "M_G_CPU1_SB_PAR")
	)
	(arc
		(start 135.887968 -247.50268)
		(mid 135.605266 -247.426904)
		(end 135.322564 -247.50268)
		(width 0.088646)
		(layer "In4.Cu")
		(net "M_G_CPU1_SB_PAR")
	)
	(arc
		(start 134.933436 -247.494044)
		(mid 134.656961 -247.426724)
		(end 134.382764 -247.50268)
		(width 0.088646)
		(layer "In4.Cu")
		(net "M_G_CPU1_SB_PAR")
	)
	(segment
		(start 129.496566 -242.830604)
		(end 129.496566 -242.294918)
		(width 0.20066)
		(layer "F.Cu")
		(net "M_G_CPU1_SB_DQS_DP<9>")
	)
	(segment
		(start 191.899286 -238.541814)
		(end 191.935608 -238.541814)
		(width 0.101854)
		(layer "F.Cu")
		(net "M_G_CPU1_SB_DQS_DP<9>")
	)
	(segment
		(start 191.519048 -238.290608)
		(end 191.770254 -238.541814)
		(width 0.20066)
		(layer "F.Cu")
		(net "M_G_CPU1_SB_DQS_DP<9>")
	)
	(segment
		(start 190.803276 -238.290608)
		(end 191.519048 -238.290608)
		(width 0.20066)
		(layer "F.Cu")
		(net "M_G_CPU1_SB_DQS_DP<9>")
	)
	(segment
		(start 191.770254 -238.541814)
		(end 191.899286 -238.541814)
		(width 0.20066)
		(layer "F.Cu")
		(net "M_G_CPU1_SB_DQS_DP<9>")
	)
	(segment
		(start 187.883546 -238.116618)
		(end 188.988446 -238.116618)
		(width 0.20066)
		(layer "F.Cu")
		(net "M_G_CPU1_SB_DQS_DP<9>")
	)
	(segment
		(start 195.983606 -238.116618)
		(end 196.532246 -238.116618)
		(width 0.20066)
		(layer "F.Cu")
		(net "M_G_CPU1_SB_DQS_DP<9>")
	)
	(segment
		(start 195.095368 -238.245396)
		(end 195.505832 -237.834932)
		(width 0.20066)
		(layer "F.Cu")
		(net "M_G_CPU1_SB_DQS_DP<9>")
	)
	(segment
		(start 195.70192 -237.834932)
		(end 195.983606 -238.116618)
		(width 0.20066)
		(layer "F.Cu")
		(net "M_G_CPU1_SB_DQS_DP<9>")
	)
	(segment
		(start 190.388748 -237.87608)
		(end 190.803276 -238.290608)
		(width 0.20066)
		(layer "F.Cu")
		(net "M_G_CPU1_SB_DQS_DP<9>")
	)
	(segment
		(start 189.818264 -237.87608)
		(end 190.388748 -237.87608)
		(width 0.20066)
		(layer "F.Cu")
		(net "M_G_CPU1_SB_DQS_DP<9>")
	)
	(segment
		(start 189.577726 -238.116618)
		(end 189.818264 -237.87608)
		(width 0.20066)
		(layer "F.Cu")
		(net "M_G_CPU1_SB_DQS_DP<9>")
	)
	(segment
		(start 129.496312 -242.830858)
		(end 129.496566 -242.830604)
		(width 0.20066)
		(layer "F.Cu")
		(net "M_G_CPU1_SB_DQS_DP<9>")
	)
	(segment
		(start 194.306952 -238.541814)
		(end 194.428364 -238.541814)
		(width 0.20066)
		(layer "F.Cu")
		(net "M_G_CPU1_SB_DQS_DP<9>")
	)
	(segment
		(start 194.09283 -238.541814)
		(end 194.306952 -238.541814)
		(width 0.101854)
		(layer "F.Cu")
		(net "M_G_CPU1_SB_DQS_DP<9>")
	)
	(segment
		(start 194.724782 -238.245396)
		(end 195.095368 -238.245396)
		(width 0.20066)
		(layer "F.Cu")
		(net "M_G_CPU1_SB_DQS_DP<9>")
	)
	(segment
		(start 188.988446 -238.116618)
		(end 189.577726 -238.116618)
		(width 0.20066)
		(layer "F.Cu")
		(net "M_G_CPU1_SB_DQS_DP<9>")
	)
	(segment
		(start 195.505832 -237.834932)
		(end 195.70192 -237.834932)
		(width 0.20066)
		(layer "F.Cu")
		(net "M_G_CPU1_SB_DQS_DP<9>")
	)
	(segment
		(start 191.935608 -238.541814)
		(end 194.09283 -238.541814)
		(width 0.1016)
		(layer "F.Cu")
		(net "M_G_CPU1_SB_DQS_DP<9>")
	)
	(segment
		(start 194.428364 -238.541814)
		(end 194.724782 -238.245396)
		(width 0.20066)
		(layer "F.Cu")
		(net "M_G_CPU1_SB_DQS_DP<9>")
	)
	(segment
		(start 139.153646 -242.357148)
		(end 138.777218 -242.733576)
		(width 0.088646)
		(layer "In4.Cu")
		(net "M_G_CPU1_SB_DQS_DP<9>")
	)
	(segment
		(start 178.932586 -237.619286)
		(end 178.290982 -238.26089)
		(width 0.18288)
		(layer "In4.Cu")
		(net "M_G_CPU1_SB_DQS_DP<9>")
	)
	(segment
		(start 174.62881 -238.252254)
		(end 173.770036 -239.111028)
		(width 0.18288)
		(layer "In4.Cu")
		(net "M_G_CPU1_SB_DQS_DP<9>")
	)
	(segment
		(start 140.315696 -242.417092)
		(end 140.292328 -242.417092)
		(width 0.088646)
		(layer "In4.Cu")
		(net "M_G_CPU1_SB_DQS_DP<9>")
	)
	(segment
		(start 140.292328 -242.417092)
		(end 140.232384 -242.357148)
		(width 0.088646)
		(layer "In4.Cu")
		(net "M_G_CPU1_SB_DQS_DP<9>")
	)
	(segment
		(start 168.145206 -238.511334)
		(end 165.969188 -238.511334)
		(width 0.18288)
		(layer "In4.Cu")
		(net "M_G_CPU1_SB_DQS_DP<9>")
	)
	(segment
		(start 135.418068 -242.78463)
		(end 135.407654 -242.790726)
		(width 0.088646)
		(layer "In4.Cu")
		(net "M_G_CPU1_SB_DQS_DP<9>")
	)
	(segment
		(start 138.777218 -242.733576)
		(end 138.42492 -242.733576)
		(width 0.088646)
		(layer "In4.Cu")
		(net "M_G_CPU1_SB_DQS_DP<9>")
	)
	(segment
		(start 160.4772 -238.490252)
		(end 152.734264 -238.490252)
		(width 0.18288)
		(layer "In4.Cu")
		(net "M_G_CPU1_SB_DQS_DP<9>")
	)
	(segment
		(start 172.988224 -239.393984)
		(end 172.604176 -239.393984)
		(width 0.18288)
		(layer "In4.Cu")
		(net "M_G_CPU1_SB_DQS_DP<9>")
	)
	(segment
		(start 140.232384 -242.357148)
		(end 139.153646 -242.357148)
		(width 0.088646)
		(layer "In4.Cu")
		(net "M_G_CPU1_SB_DQS_DP<9>")
	)
	(segment
		(start 152.734264 -238.490252)
		(end 151.332692 -239.891824)
		(width 0.18288)
		(layer "In4.Cu")
		(net "M_G_CPU1_SB_DQS_DP<9>")
	)
	(segment
		(start 162.896296 -238.252762)
		(end 162.335972 -237.692438)
		(width 0.18288)
		(layer "In4.Cu")
		(net "M_G_CPU1_SB_DQS_DP<9>")
	)
	(segment
		(start 132.598668 -242.78463)
		(end 132.588254 -242.790726)
		(width 0.088646)
		(layer "In4.Cu")
		(net "M_G_CPU1_SB_DQS_DP<9>")
	)
	(segment
		(start 163.295584 -238.252254)
		(end 162.896296 -238.252762)
		(width 0.18288)
		(layer "In4.Cu")
		(net "M_G_CPU1_SB_DQS_DP<9>")
	)
	(segment
		(start 177.371248 -238.26089)
		(end 177.088292 -238.543846)
		(width 0.18288)
		(layer "In4.Cu")
		(net "M_G_CPU1_SB_DQS_DP<9>")
	)
	(segment
		(start 162.335972 -237.692438)
		(end 161.275014 -237.692438)
		(width 0.18288)
		(layer "In4.Cu")
		(net "M_G_CPU1_SB_DQS_DP<9>")
	)
	(segment
		(start 132.987796 -242.793266)
		(end 132.973064 -242.78463)
		(width 0.088646)
		(layer "In4.Cu")
		(net "M_G_CPU1_SB_DQS_DP<9>")
	)
	(segment
		(start 146.97456 -239.891824)
		(end 144.449292 -242.417092)
		(width 0.18288)
		(layer "In4.Cu")
		(net "M_G_CPU1_SB_DQS_DP<9>")
	)
	(segment
		(start 151.332692 -239.891824)
		(end 146.97456 -239.891824)
		(width 0.18288)
		(layer "In4.Cu")
		(net "M_G_CPU1_SB_DQS_DP<9>")
	)
	(segment
		(start 144.449292 -242.417092)
		(end 140.315696 -242.417092)
		(width 0.18288)
		(layer "In4.Cu")
		(net "M_G_CPU1_SB_DQS_DP<9>")
	)
	(segment
		(start 164.083238 -238.556292)
		(end 163.7792 -238.252254)
		(width 0.18288)
		(layer "In4.Cu")
		(net "M_G_CPU1_SB_DQS_DP<9>")
	)
	(segment
		(start 131.658614 -242.78463)
		(end 131.643882 -242.793266)
		(width 0.088646)
		(layer "In4.Cu")
		(net "M_G_CPU1_SB_DQS_DP<9>")
	)
	(segment
		(start 172.312584 -239.102392)
		(end 171.454826 -239.102392)
		(width 0.18288)
		(layer "In4.Cu")
		(net "M_G_CPU1_SB_DQS_DP<9>")
	)
	(segment
		(start 171.20235 -238.849916)
		(end 168.483788 -238.849916)
		(width 0.18288)
		(layer "In4.Cu")
		(net "M_G_CPU1_SB_DQS_DP<9>")
	)
	(segment
		(start 129.874772 -242.360704)
		(end 129.80924 -242.295172)
		(width 0.088646)
		(layer "In4.Cu")
		(net "M_G_CPU1_SB_DQS_DP<9>")
	)
	(segment
		(start 187.883546 -238.116618)
		(end 187.597288 -237.83036)
		(width 0.18288)
		(layer "In4.Cu")
		(net "M_G_CPU1_SB_DQS_DP<9>")
	)
	(segment
		(start 171.454826 -239.102392)
		(end 171.20235 -238.849916)
		(width 0.18288)
		(layer "In4.Cu")
		(net "M_G_CPU1_SB_DQS_DP<9>")
	)
	(segment
		(start 173.770036 -239.111028)
		(end 173.27118 -239.111028)
		(width 0.18288)
		(layer "In4.Cu")
		(net "M_G_CPU1_SB_DQS_DP<9>")
	)
	(segment
		(start 165.969188 -238.511334)
		(end 165.714426 -238.256572)
		(width 0.18288)
		(layer "In4.Cu")
		(net "M_G_CPU1_SB_DQS_DP<9>")
	)
	(segment
		(start 129.80924 -242.295172)
		(end 129.496566 -242.294918)
		(width 0.088646)
		(layer "In4.Cu")
		(net "M_G_CPU1_SB_DQS_DP<9>")
	)
	(segment
		(start 168.483788 -238.849916)
		(end 168.145206 -238.511334)
		(width 0.18288)
		(layer "In4.Cu")
		(net "M_G_CPU1_SB_DQS_DP<9>")
	)
	(segment
		(start 177.088292 -238.543846)
		(end 176.704244 -238.543846)
		(width 0.18288)
		(layer "In4.Cu")
		(net "M_G_CPU1_SB_DQS_DP<9>")
	)
	(segment
		(start 164.442394 -238.556292)
		(end 164.083238 -238.556292)
		(width 0.18288)
		(layer "In4.Cu")
		(net "M_G_CPU1_SB_DQS_DP<9>")
	)
	(segment
		(start 172.604176 -239.393984)
		(end 172.312584 -239.102392)
		(width 0.18288)
		(layer "In4.Cu")
		(net "M_G_CPU1_SB_DQS_DP<9>")
	)
	(segment
		(start 130.718814 -242.78463)
		(end 130.704082 -242.793266)
		(width 0.088646)
		(layer "In4.Cu")
		(net "M_G_CPU1_SB_DQS_DP<9>")
	)
	(segment
		(start 178.290982 -238.26089)
		(end 177.371248 -238.26089)
		(width 0.18288)
		(layer "In4.Cu")
		(net "M_G_CPU1_SB_DQS_DP<9>")
	)
	(segment
		(start 164.742114 -238.256572)
		(end 164.442394 -238.556292)
		(width 0.18288)
		(layer "In4.Cu")
		(net "M_G_CPU1_SB_DQS_DP<9>")
	)
	(segment
		(start 186.890406 -237.619286)
		(end 178.932586 -237.619286)
		(width 0.18288)
		(layer "In4.Cu")
		(net "M_G_CPU1_SB_DQS_DP<9>")
	)
	(segment
		(start 134.478014 -242.78463)
		(end 134.4676 -242.790726)
		(width 0.088646)
		(layer "In4.Cu")
		(net "M_G_CPU1_SB_DQS_DP<9>")
	)
	(segment
		(start 176.412652 -238.252254)
		(end 174.62881 -238.252254)
		(width 0.18288)
		(layer "In4.Cu")
		(net "M_G_CPU1_SB_DQS_DP<9>")
	)
	(segment
		(start 161.275014 -237.692438)
		(end 160.4772 -238.490252)
		(width 0.18288)
		(layer "In4.Cu")
		(net "M_G_CPU1_SB_DQS_DP<9>")
	)
	(segment
		(start 165.714426 -238.256572)
		(end 164.742114 -238.256572)
		(width 0.18288)
		(layer "In4.Cu")
		(net "M_G_CPU1_SB_DQS_DP<9>")
	)
	(segment
		(start 187.10148 -237.83036)
		(end 186.890406 -237.619286)
		(width 0.18288)
		(layer "In4.Cu")
		(net "M_G_CPU1_SB_DQS_DP<9>")
	)
	(segment
		(start 163.7792 -238.252254)
		(end 163.295584 -238.252254)
		(width 0.18288)
		(layer "In4.Cu")
		(net "M_G_CPU1_SB_DQS_DP<9>")
	)
	(segment
		(start 173.27118 -239.111028)
		(end 172.988224 -239.393984)
		(width 0.18288)
		(layer "In4.Cu")
		(net "M_G_CPU1_SB_DQS_DP<9>")
	)
	(segment
		(start 187.597288 -237.83036)
		(end 187.10148 -237.83036)
		(width 0.18288)
		(layer "In4.Cu")
		(net "M_G_CPU1_SB_DQS_DP<9>")
	)
	(segment
		(start 176.704244 -238.543846)
		(end 176.412652 -238.252254)
		(width 0.18288)
		(layer "In4.Cu")
		(net "M_G_CPU1_SB_DQS_DP<9>")
	)
	(arc
		(start 136.357868 -242.78463)
		(mid 136.075166 -242.860372)
		(end 135.792464 -242.78463)
		(width 0.088646)
		(layer "In4.Cu")
		(net "M_G_CPU1_SB_DQS_DP<9>")
	)
	(arc
		(start 133.538468 -242.78463)
		(mid 133.264269 -242.860465)
		(end 132.987796 -242.793266)
		(width 0.088646)
		(layer "In4.Cu")
		(net "M_G_CPU1_SB_DQS_DP<9>")
	)
	(arc
		(start 138.237468 -242.78463)
		(mid 137.954766 -242.860372)
		(end 137.672064 -242.78463)
		(width 0.088646)
		(layer "In4.Cu")
		(net "M_G_CPU1_SB_DQS_DP<9>")
	)
	(arc
		(start 136.732264 -242.78463)
		(mid 136.545066 -242.734487)
		(end 136.357868 -242.78463)
		(width 0.088646)
		(layer "In4.Cu")
		(net "M_G_CPU1_SB_DQS_DP<9>")
	)
	(arc
		(start 132.03301 -242.78463)
		(mid 131.845812 -242.734487)
		(end 131.658614 -242.78463)
		(width 0.088646)
		(layer "In4.Cu")
		(net "M_G_CPU1_SB_DQS_DP<9>")
	)
	(arc
		(start 135.792464 -242.78463)
		(mid 135.605266 -242.734487)
		(end 135.418068 -242.78463)
		(width 0.088646)
		(layer "In4.Cu")
		(net "M_G_CPU1_SB_DQS_DP<9>")
	)
	(arc
		(start 129.877566 -242.381786)
		(mid 129.87607 -242.371258)
		(end 129.874772 -242.360704)
		(width 0.088646)
		(layer "In4.Cu")
		(net "M_G_CPU1_SB_DQS_DP<9>")
	)
	(arc
		(start 130.704082 -242.793266)
		(mid 130.427607 -242.860586)
		(end 130.15341 -242.78463)
		(width 0.088646)
		(layer "In4.Cu")
		(net "M_G_CPU1_SB_DQS_DP<9>")
	)
	(arc
		(start 132.973064 -242.78463)
		(mid 132.785866 -242.734487)
		(end 132.598668 -242.78463)
		(width 0.088646)
		(layer "In4.Cu")
		(net "M_G_CPU1_SB_DQS_DP<9>")
	)
	(arc
		(start 137.672064 -242.78463)
		(mid 137.484866 -242.734487)
		(end 137.297668 -242.78463)
		(width 0.088646)
		(layer "In4.Cu")
		(net "M_G_CPU1_SB_DQS_DP<9>")
	)
	(arc
		(start 132.588254 -242.790726)
		(mid 132.309822 -242.860572)
		(end 132.03301 -242.78463)
		(width 0.088646)
		(layer "In4.Cu")
		(net "M_G_CPU1_SB_DQS_DP<9>")
	)
	(arc
		(start 133.912864 -242.78463)
		(mid 133.725666 -242.734487)
		(end 133.538468 -242.78463)
		(width 0.088646)
		(layer "In4.Cu")
		(net "M_G_CPU1_SB_DQS_DP<9>")
	)
	(arc
		(start 131.09321 -242.78463)
		(mid 130.906012 -242.734487)
		(end 130.718814 -242.78463)
		(width 0.088646)
		(layer "In4.Cu")
		(net "M_G_CPU1_SB_DQS_DP<9>")
	)
	(arc
		(start 137.297668 -242.78463)
		(mid 137.014966 -242.860372)
		(end 136.732264 -242.78463)
		(width 0.088646)
		(layer "In4.Cu")
		(net "M_G_CPU1_SB_DQS_DP<9>")
	)
	(arc
		(start 131.643882 -242.793266)
		(mid 131.367407 -242.860586)
		(end 131.09321 -242.78463)
		(width 0.088646)
		(layer "In4.Cu")
		(net "M_G_CPU1_SB_DQS_DP<9>")
	)
	(arc
		(start 138.42492 -242.733576)
		(mid 138.327839 -242.746772)
		(end 138.237468 -242.78463)
		(width 0.088646)
		(layer "In4.Cu")
		(net "M_G_CPU1_SB_DQS_DP<9>")
	)
	(arc
		(start 130.15341 -242.78463)
		(mid 129.969819 -242.614495)
		(end 129.877566 -242.381786)
		(width 0.088646)
		(layer "In4.Cu")
		(net "M_G_CPU1_SB_DQS_DP<9>")
	)
	(arc
		(start 135.407654 -242.790726)
		(mid 135.129222 -242.860572)
		(end 134.85241 -242.78463)
		(width 0.088646)
		(layer "In4.Cu")
		(net "M_G_CPU1_SB_DQS_DP<9>")
	)
	(arc
		(start 134.4676 -242.790726)
		(mid 134.189422 -242.860449)
		(end 133.912864 -242.78463)
		(width 0.088646)
		(layer "In4.Cu")
		(net "M_G_CPU1_SB_DQS_DP<9>")
	)
	(arc
		(start 134.85241 -242.78463)
		(mid 134.665212 -242.734487)
		(end 134.478014 -242.78463)
		(width 0.088646)
		(layer "In4.Cu")
		(net "M_G_CPU1_SB_DQS_DP<9>")
	)
	(segment
		(start 198.773034 -198.839328)
		(end 199.21855 -199.284844)
		(width 0.20066)
		(layer "F.Cu")
		(net "M_G_CPU1_SB_DQS_DP<8>")
	)
	(segment
		(start 195.510658 -198.584566)
		(end 195.515484 -198.584566)
		(width 0.101854)
		(layer "F.Cu")
		(net "M_G_CPU1_SB_DQS_DP<8>")
	)
	(segment
		(start 198.119492 -198.839328)
		(end 198.773034 -198.839328)
		(width 0.20066)
		(layer "F.Cu")
		(net "M_G_CPU1_SB_DQS_DP<8>")
	)
	(segment
		(start 195.515484 -198.584566)
		(end 195.522596 -198.591678)
		(width 0.1016)
		(layer "F.Cu")
		(net "M_G_CPU1_SB_DQS_DP<8>")
	)
	(segment
		(start 195.199508 -198.584566)
		(end 195.510658 -198.584566)
		(width 0.20066)
		(layer "F.Cu")
		(net "M_G_CPU1_SB_DQS_DP<8>")
	)
	(segment
		(start 193.933064 -199.267826)
		(end 194.237864 -199.267826)
		(width 0.20066)
		(layer "F.Cu")
		(net "M_G_CPU1_SB_DQS_DP<8>")
	)
	(segment
		(start 194.94119 -198.842884)
		(end 195.199508 -198.584566)
		(width 0.20066)
		(layer "F.Cu")
		(net "M_G_CPU1_SB_DQS_DP<8>")
	)
	(segment
		(start 197.542658 -198.584312)
		(end 197.864476 -198.584312)
		(width 0.20066)
		(layer "F.Cu")
		(net "M_G_CPU1_SB_DQS_DP<8>")
	)
	(segment
		(start 193.088514 -199.01662)
		(end 193.681858 -199.01662)
		(width 0.20066)
		(layer "F.Cu")
		(net "M_G_CPU1_SB_DQS_DP<8>")
	)
	(segment
		(start 193.681858 -199.01662)
		(end 193.933064 -199.267826)
		(width 0.20066)
		(layer "F.Cu")
		(net "M_G_CPU1_SB_DQS_DP<8>")
	)
	(segment
		(start 199.796146 -199.284844)
		(end 200.06437 -199.01662)
		(width 0.20066)
		(layer "F.Cu")
		(net "M_G_CPU1_SB_DQS_DP<8>")
	)
	(segment
		(start 200.06437 -199.01662)
		(end 200.632314 -199.01662)
		(width 0.20066)
		(layer "F.Cu")
		(net "M_G_CPU1_SB_DQS_DP<8>")
	)
	(segment
		(start 195.522596 -198.591678)
		(end 197.535292 -198.591678)
		(width 0.1016)
		(layer "F.Cu")
		(net "M_G_CPU1_SB_DQS_DP<8>")
	)
	(segment
		(start 199.21855 -199.284844)
		(end 199.796146 -199.284844)
		(width 0.20066)
		(layer "F.Cu")
		(net "M_G_CPU1_SB_DQS_DP<8>")
	)
	(segment
		(start 194.237864 -199.267826)
		(end 194.662806 -198.842884)
		(width 0.20066)
		(layer "F.Cu")
		(net "M_G_CPU1_SB_DQS_DP<8>")
	)
	(segment
		(start 197.864476 -198.584312)
		(end 198.119492 -198.839328)
		(width 0.20066)
		(layer "F.Cu")
		(net "M_G_CPU1_SB_DQS_DP<8>")
	)
	(segment
		(start 137.484866 -217.064336)
		(end 137.484866 -217.600276)
		(width 0.20066)
		(layer "F.Cu")
		(net "M_G_CPU1_SB_DQS_DP<8>")
	)
	(segment
		(start 194.662806 -198.842884)
		(end 194.94119 -198.842884)
		(width 0.20066)
		(layer "F.Cu")
		(net "M_G_CPU1_SB_DQS_DP<8>")
	)
	(segment
		(start 197.535292 -198.591678)
		(end 197.542658 -198.584312)
		(width 0.1016)
		(layer "F.Cu")
		(net "M_G_CPU1_SB_DQS_DP<8>")
	)
	(segment
		(start 191.983614 -199.01662)
		(end 193.088514 -199.01662)
		(width 0.20066)
		(layer "F.Cu")
		(net "M_G_CPU1_SB_DQS_DP<8>")
	)
	(segment
		(start 176.42967 -198.028306)
		(end 175.483012 -198.028306)
		(width 0.18288)
		(layer "In6.Cu")
		(net "M_G_CPU1_SB_DQS_DP<8>")
	)
	(segment
		(start 167.719502 -197.809866)
		(end 165.231572 -197.809866)
		(width 0.18288)
		(layer "In6.Cu")
		(net "M_G_CPU1_SB_DQS_DP<8>")
	)
	(segment
		(start 177.372518 -198.020686)
		(end 177.094388 -197.742556)
		(width 0.18288)
		(layer "In6.Cu")
		(net "M_G_CPU1_SB_DQS_DP<8>")
	)
	(segment
		(start 137.328402 -217.335354)
		(end 137.484866 -217.064336)
		(width 0.088646)
		(layer "In6.Cu")
		(net "M_G_CPU1_SB_DQS_DP<8>")
	)
	(segment
		(start 191.376808 -199.30491)
		(end 190.434214 -199.492362)
		(width 0.18288)
		(layer "In6.Cu")
		(net "M_G_CPU1_SB_DQS_DP<8>")
	)
	(segment
		(start 157.71368 -197.820026)
		(end 148.385276 -207.14843)
		(width 0.18288)
		(layer "In6.Cu")
		(net "M_G_CPU1_SB_DQS_DP<8>")
	)
	(segment
		(start 188.622686 -198.87057)
		(end 188.348874 -198.87057)
		(width 0.18288)
		(layer "In6.Cu")
		(net "M_G_CPU1_SB_DQS_DP<8>")
	)
	(segment
		(start 141.619986 -215.810084)
		(end 141.406626 -216.023444)
		(width 0.088646)
		(layer "In6.Cu")
		(net "M_G_CPU1_SB_DQS_DP<8>")
	)
	(segment
		(start 173.247304 -197.15607)
		(end 172.983652 -196.892418)
		(width 0.18288)
		(layer "In6.Cu")
		(net "M_G_CPU1_SB_DQS_DP<8>")
	)
	(segment
		(start 140.960856 -217.313002)
		(end 140.773912 -217.313002)
		(width 0.088646)
		(layer "In6.Cu")
		(net "M_G_CPU1_SB_DQS_DP<8>")
	)
	(segment
		(start 138.237468 -217.388694)
		(end 138.222736 -217.380058)
		(width 0.088646)
		(layer "In6.Cu")
		(net "M_G_CPU1_SB_DQS_DP<8>")
	)
	(segment
		(start 148.385276 -207.14843)
		(end 148.385276 -208.960466)
		(width 0.18288)
		(layer "In6.Cu")
		(net "M_G_CPU1_SB_DQS_DP<8>")
	)
	(segment
		(start 172.593508 -196.892418)
		(end 172.321728 -197.164198)
		(width 0.18288)
		(layer "In6.Cu")
		(net "M_G_CPU1_SB_DQS_DP<8>")
	)
	(segment
		(start 139.566396 -217.380058)
		(end 139.551664 -217.388694)
		(width 0.088646)
		(layer "In6.Cu")
		(net "M_G_CPU1_SB_DQS_DP<8>")
	)
	(segment
		(start 169.277792 -197.164198)
		(end 167.719502 -197.809866)
		(width 0.18288)
		(layer "In6.Cu")
		(net "M_G_CPU1_SB_DQS_DP<8>")
	)
	(segment
		(start 178.472084 -198.55942)
		(end 178.107086 -198.194168)
		(width 0.18288)
		(layer "In6.Cu")
		(net "M_G_CPU1_SB_DQS_DP<8>")
	)
	(segment
		(start 188.070744 -198.59244)
		(end 187.710572 -198.59244)
		(width 0.18288)
		(layer "In6.Cu")
		(net "M_G_CPU1_SB_DQS_DP<8>")
	)
	(segment
		(start 179.572412 -198.53402)
		(end 179.295806 -198.648828)
		(width 0.18288)
		(layer "In6.Cu")
		(net "M_G_CPU1_SB_DQS_DP<8>")
	)
	(segment
		(start 172.983652 -196.892418)
		(end 172.593508 -196.892418)
		(width 0.18288)
		(layer "In6.Cu")
		(net "M_G_CPU1_SB_DQS_DP<8>")
	)
	(segment
		(start 148.385276 -208.960466)
		(end 141.636496 -215.709246)
		(width 0.18288)
		(layer "In6.Cu")
		(net "M_G_CPU1_SB_DQS_DP<8>")
	)
	(segment
		(start 179.295806 -198.648828)
		(end 178.686714 -198.648828)
		(width 0.18288)
		(layer "In6.Cu")
		(net "M_G_CPU1_SB_DQS_DP<8>")
	)
	(segment
		(start 165.231572 -197.809866)
		(end 164.409374 -197.415658)
		(width 0.18288)
		(layer "In6.Cu")
		(net "M_G_CPU1_SB_DQS_DP<8>")
	)
	(segment
		(start 187.710572 -198.59244)
		(end 187.432442 -198.87057)
		(width 0.18288)
		(layer "In6.Cu")
		(net "M_G_CPU1_SB_DQS_DP<8>")
	)
	(segment
		(start 191.695324 -199.30491)
		(end 191.376808 -199.30491)
		(width 0.18288)
		(layer "In6.Cu")
		(net "M_G_CPU1_SB_DQS_DP<8>")
	)
	(segment
		(start 179.767992 -198.339202)
		(end 179.572412 -198.53402)
		(width 0.18288)
		(layer "In6.Cu")
		(net "M_G_CPU1_SB_DQS_DP<8>")
	)
	(segment
		(start 178.686714 -198.648828)
		(end 178.472084 -198.55942)
		(width 0.18288)
		(layer "In6.Cu")
		(net "M_G_CPU1_SB_DQS_DP<8>")
	)
	(segment
		(start 174.451264 -197.50913)
		(end 174.296578 -197.354444)
		(width 0.18288)
		(layer "In6.Cu")
		(net "M_G_CPU1_SB_DQS_DP<8>")
	)
	(segment
		(start 141.406626 -216.023444)
		(end 141.406626 -216.867232)
		(width 0.088646)
		(layer "In6.Cu")
		(net "M_G_CPU1_SB_DQS_DP<8>")
	)
	(segment
		(start 176.71542 -197.742556)
		(end 176.42967 -198.028306)
		(width 0.18288)
		(layer "In6.Cu")
		(net "M_G_CPU1_SB_DQS_DP<8>")
	)
	(segment
		(start 175.483012 -198.028306)
		(end 174.60595 -197.663562)
		(width 0.18288)
		(layer "In6.Cu")
		(net "M_G_CPU1_SB_DQS_DP<8>")
	)
	(segment
		(start 174.296578 -197.354444)
		(end 173.81982 -197.15607)
		(width 0.18288)
		(layer "In6.Cu")
		(net "M_G_CPU1_SB_DQS_DP<8>")
	)
	(segment
		(start 188.348874 -198.87057)
		(end 188.070744 -198.59244)
		(width 0.18288)
		(layer "In6.Cu")
		(net "M_G_CPU1_SB_DQS_DP<8>")
	)
	(segment
		(start 190.434214 -199.492362)
		(end 190.12789 -199.492362)
		(width 0.18288)
		(layer "In6.Cu")
		(net "M_G_CPU1_SB_DQS_DP<8>")
	)
	(segment
		(start 182.911496 -198.211948)
		(end 180.075332 -198.211948)
		(width 0.18288)
		(layer "In6.Cu")
		(net "M_G_CPU1_SB_DQS_DP<8>")
	)
	(segment
		(start 173.81982 -197.15607)
		(end 173.247304 -197.15607)
		(width 0.18288)
		(layer "In6.Cu")
		(net "M_G_CPU1_SB_DQS_DP<8>")
	)
	(segment
		(start 174.60595 -197.663562)
		(end 174.451264 -197.50913)
		(width 0.18288)
		(layer "In6.Cu")
		(net "M_G_CPU1_SB_DQS_DP<8>")
	)
	(segment
		(start 177.094388 -197.742556)
		(end 176.71542 -197.742556)
		(width 0.18288)
		(layer "In6.Cu")
		(net "M_G_CPU1_SB_DQS_DP<8>")
	)
	(segment
		(start 180.075332 -198.211948)
		(end 179.767992 -198.339202)
		(width 0.18288)
		(layer "In6.Cu")
		(net "M_G_CPU1_SB_DQS_DP<8>")
	)
	(segment
		(start 164.409374 -197.415658)
		(end 161.04997 -197.415658)
		(width 0.18288)
		(layer "In6.Cu")
		(net "M_G_CPU1_SB_DQS_DP<8>")
	)
	(segment
		(start 138.626596 -217.380058)
		(end 138.611864 -217.388694)
		(width 0.088646)
		(layer "In6.Cu")
		(net "M_G_CPU1_SB_DQS_DP<8>")
	)
	(segment
		(start 141.619986 -215.725756)
		(end 141.619986 -215.810084)
		(width 0.088646)
		(layer "In6.Cu")
		(net "M_G_CPU1_SB_DQS_DP<8>")
	)
	(segment
		(start 141.406626 -216.867232)
		(end 140.960856 -217.313002)
		(width 0.088646)
		(layer "In6.Cu")
		(net "M_G_CPU1_SB_DQS_DP<8>")
	)
	(segment
		(start 172.321728 -197.164198)
		(end 169.277792 -197.164198)
		(width 0.18288)
		(layer "In6.Cu")
		(net "M_G_CPU1_SB_DQS_DP<8>")
	)
	(segment
		(start 161.04997 -197.415658)
		(end 160.076642 -197.820026)
		(width 0.18288)
		(layer "In6.Cu")
		(net "M_G_CPU1_SB_DQS_DP<8>")
	)
	(segment
		(start 160.076642 -197.820026)
		(end 157.71368 -197.820026)
		(width 0.18288)
		(layer "In6.Cu")
		(net "M_G_CPU1_SB_DQS_DP<8>")
	)
	(segment
		(start 187.432442 -198.87057)
		(end 184.50052 -198.87057)
		(width 0.18288)
		(layer "In6.Cu")
		(net "M_G_CPU1_SB_DQS_DP<8>")
	)
	(segment
		(start 178.107086 -198.194168)
		(end 177.690526 -198.020686)
		(width 0.18288)
		(layer "In6.Cu")
		(net "M_G_CPU1_SB_DQS_DP<8>")
	)
	(segment
		(start 190.12789 -199.492362)
		(end 188.622686 -198.87057)
		(width 0.18288)
		(layer "In6.Cu")
		(net "M_G_CPU1_SB_DQS_DP<8>")
	)
	(segment
		(start 177.690526 -198.020686)
		(end 177.372518 -198.020686)
		(width 0.18288)
		(layer "In6.Cu")
		(net "M_G_CPU1_SB_DQS_DP<8>")
	)
	(segment
		(start 191.983614 -199.01662)
		(end 191.695324 -199.30491)
		(width 0.18288)
		(layer "In6.Cu")
		(net "M_G_CPU1_SB_DQS_DP<8>")
	)
	(segment
		(start 184.50052 -198.87057)
		(end 182.911496 -198.211948)
		(width 0.18288)
		(layer "In6.Cu")
		(net "M_G_CPU1_SB_DQS_DP<8>")
	)
	(segment
		(start 141.636496 -215.709246)
		(end 141.619986 -215.725756)
		(width 0.088646)
		(layer "In6.Cu")
		(net "M_G_CPU1_SB_DQS_DP<8>")
	)
	(segment
		(start 137.349484 -217.413332)
		(end 137.328402 -217.335354)
		(width 0.088646)
		(layer "In6.Cu")
		(net "M_G_CPU1_SB_DQS_DP<8>")
	)
	(arc
		(start 138.222736 -217.380058)
		(mid 137.946295 -217.312892)
		(end 137.672064 -217.388694)
		(width 0.088646)
		(layer "In6.Cu")
		(net "M_G_CPU1_SB_DQS_DP<8>")
	)
	(arc
		(start 139.177268 -217.388694)
		(mid 138.903039 -217.312769)
		(end 138.626596 -217.380058)
		(width 0.088646)
		(layer "In6.Cu")
		(net "M_G_CPU1_SB_DQS_DP<8>")
	)
	(arc
		(start 137.672064 -217.388694)
		(mid 137.513576 -217.437627)
		(end 137.349484 -217.413332)
		(width 0.088646)
		(layer "In6.Cu")
		(net "M_G_CPU1_SB_DQS_DP<8>")
	)
	(arc
		(start 140.117068 -217.388694)
		(mid 139.842839 -217.312769)
		(end 139.566396 -217.380058)
		(width 0.088646)
		(layer "In6.Cu")
		(net "M_G_CPU1_SB_DQS_DP<8>")
	)
	(arc
		(start 138.611864 -217.388694)
		(mid 138.424666 -217.438837)
		(end 138.237468 -217.388694)
		(width 0.088646)
		(layer "In6.Cu")
		(net "M_G_CPU1_SB_DQS_DP<8>")
	)
	(arc
		(start 140.773912 -217.313002)
		(mid 140.62772 -217.332297)
		(end 140.491464 -217.388694)
		(width 0.088646)
		(layer "In6.Cu")
		(net "M_G_CPU1_SB_DQS_DP<8>")
	)
	(arc
		(start 139.551664 -217.388694)
		(mid 139.364466 -217.438837)
		(end 139.177268 -217.388694)
		(width 0.088646)
		(layer "In6.Cu")
		(net "M_G_CPU1_SB_DQS_DP<8>")
	)
	(arc
		(start 140.491464 -217.388694)
		(mid 140.304266 -217.438837)
		(end 140.117068 -217.388694)
		(width 0.088646)
		(layer "In6.Cu")
		(net "M_G_CPU1_SB_DQS_DP<8>")
	)
	(segment
		(start 199.21855 -208.634838)
		(end 199.796146 -208.634838)
		(width 0.20066)
		(layer "F.Cu")
		(net "M_G_CPU1_SB_DQS_DP<7>")
	)
	(segment
		(start 191.983614 -208.366614)
		(end 193.088514 -208.366614)
		(width 0.20066)
		(layer "F.Cu")
		(net "M_G_CPU1_SB_DQS_DP<7>")
	)
	(segment
		(start 195.199508 -207.93456)
		(end 195.510658 -207.93456)
		(width 0.20066)
		(layer "F.Cu")
		(net "M_G_CPU1_SB_DQS_DP<7>")
	)
	(segment
		(start 131.375912 -232.528618)
		(end 131.376166 -232.528364)
		(width 0.20066)
		(layer "F.Cu")
		(net "M_G_CPU1_SB_DQS_DP<7>")
	)
	(segment
		(start 197.535292 -207.941672)
		(end 197.542658 -207.934306)
		(width 0.1016)
		(layer "F.Cu")
		(net "M_G_CPU1_SB_DQS_DP<7>")
	)
	(segment
		(start 195.515484 -207.93456)
		(end 195.522596 -207.941672)
		(width 0.1016)
		(layer "F.Cu")
		(net "M_G_CPU1_SB_DQS_DP<7>")
	)
	(segment
		(start 199.796146 -208.634838)
		(end 200.06437 -208.366614)
		(width 0.20066)
		(layer "F.Cu")
		(net "M_G_CPU1_SB_DQS_DP<7>")
	)
	(segment
		(start 194.237864 -208.61782)
		(end 194.662806 -208.192878)
		(width 0.20066)
		(layer "F.Cu")
		(net "M_G_CPU1_SB_DQS_DP<7>")
	)
	(segment
		(start 194.94119 -208.192878)
		(end 195.199508 -207.93456)
		(width 0.20066)
		(layer "F.Cu")
		(net "M_G_CPU1_SB_DQS_DP<7>")
	)
	(segment
		(start 193.933064 -208.61782)
		(end 194.237864 -208.61782)
		(width 0.20066)
		(layer "F.Cu")
		(net "M_G_CPU1_SB_DQS_DP<7>")
	)
	(segment
		(start 195.522596 -207.941672)
		(end 197.535292 -207.941672)
		(width 0.1016)
		(layer "F.Cu")
		(net "M_G_CPU1_SB_DQS_DP<7>")
	)
	(segment
		(start 197.864476 -207.934306)
		(end 198.119492 -208.189322)
		(width 0.20066)
		(layer "F.Cu")
		(net "M_G_CPU1_SB_DQS_DP<7>")
	)
	(segment
		(start 197.542658 -207.934306)
		(end 197.864476 -207.934306)
		(width 0.20066)
		(layer "F.Cu")
		(net "M_G_CPU1_SB_DQS_DP<7>")
	)
	(segment
		(start 200.06437 -208.366614)
		(end 200.632314 -208.366614)
		(width 0.20066)
		(layer "F.Cu")
		(net "M_G_CPU1_SB_DQS_DP<7>")
	)
	(segment
		(start 193.088514 -208.366614)
		(end 193.681858 -208.366614)
		(width 0.20066)
		(layer "F.Cu")
		(net "M_G_CPU1_SB_DQS_DP<7>")
	)
	(segment
		(start 198.773034 -208.189322)
		(end 199.21855 -208.634838)
		(width 0.20066)
		(layer "F.Cu")
		(net "M_G_CPU1_SB_DQS_DP<7>")
	)
	(segment
		(start 131.375912 -233.064304)
		(end 131.375912 -232.528618)
		(width 0.20066)
		(layer "F.Cu")
		(net "M_G_CPU1_SB_DQS_DP<7>")
	)
	(segment
		(start 194.662806 -208.192878)
		(end 194.94119 -208.192878)
		(width 0.20066)
		(layer "F.Cu")
		(net "M_G_CPU1_SB_DQS_DP<7>")
	)
	(segment
		(start 193.681858 -208.366614)
		(end 193.933064 -208.61782)
		(width 0.20066)
		(layer "F.Cu")
		(net "M_G_CPU1_SB_DQS_DP<7>")
	)
	(segment
		(start 198.119492 -208.189322)
		(end 198.773034 -208.189322)
		(width 0.20066)
		(layer "F.Cu")
		(net "M_G_CPU1_SB_DQS_DP<7>")
	)
	(segment
		(start 195.510658 -207.93456)
		(end 195.515484 -207.93456)
		(width 0.101854)
		(layer "F.Cu")
		(net "M_G_CPU1_SB_DQS_DP<7>")
	)
	(segment
		(start 157.864302 -211.42579)
		(end 142.606268 -226.683824)
		(width 0.18288)
		(layer "In4.Cu")
		(net "M_G_CPU1_SB_DQS_DP<7>")
	)
	(segment
		(start 164.340286 -211.012786)
		(end 161.167572 -211.012786)
		(width 0.18288)
		(layer "In4.Cu")
		(net "M_G_CPU1_SB_DQS_DP<7>")
	)
	(segment
		(start 131.945888 -232.47096)
		(end 131.88315 -232.533698)
		(width 0.088646)
		(layer "In4.Cu")
		(net "M_G_CPU1_SB_DQS_DP<7>")
	)
	(segment
		(start 191.002666 -208.20888)
		(end 190.553594 -208.20888)
		(width 0.18288)
		(layer "In4.Cu")
		(net "M_G_CPU1_SB_DQS_DP<7>")
	)
	(segment
		(start 160.754568 -211.42579)
		(end 157.864302 -211.42579)
		(width 0.18288)
		(layer "In4.Cu")
		(net "M_G_CPU1_SB_DQS_DP<7>")
	)
	(segment
		(start 138.59891 -228.791262)
		(end 138.598656 -228.790754)
		(width 0.088646)
		(layer "In4.Cu")
		(net "M_G_CPU1_SB_DQS_DP<7>")
	)
	(segment
		(start 132.983224 -232.03281)
		(end 132.97281 -232.038906)
		(width 0.088646)
		(layer "In4.Cu")
		(net "M_G_CPU1_SB_DQS_DP<7>")
	)
	(segment
		(start 172.989748 -210.492594)
		(end 172.584872 -210.492594)
		(width 0.18288)
		(layer "In4.Cu")
		(net "M_G_CPU1_SB_DQS_DP<7>")
	)
	(segment
		(start 191.699388 -208.62544)
		(end 191.529208 -208.62544)
		(width 0.18288)
		(layer "In4.Cu")
		(net "M_G_CPU1_SB_DQS_DP<7>")
	)
	(segment
		(start 138.799824 -228.35235)
		(end 138.799824 -228.466396)
		(width 0.088646)
		(layer "In4.Cu")
		(net "M_G_CPU1_SB_DQS_DP<7>")
	)
	(segment
		(start 132.95376 -232.050336)
		(end 132.86232 -232.102914)
		(width 0.088646)
		(layer "In4.Cu")
		(net "M_G_CPU1_SB_DQS_DP<7>")
	)
	(segment
		(start 173.24832 -210.751166)
		(end 172.989748 -210.492594)
		(width 0.18288)
		(layer "In4.Cu")
		(net "M_G_CPU1_SB_DQS_DP<7>")
	)
	(segment
		(start 191.529208 -208.62544)
		(end 191.340486 -208.5467)
		(width 0.18288)
		(layer "In4.Cu")
		(net "M_G_CPU1_SB_DQS_DP<7>")
	)
	(segment
		(start 174.204122 -210.751166)
		(end 173.24832 -210.751166)
		(width 0.18288)
		(layer "In4.Cu")
		(net "M_G_CPU1_SB_DQS_DP<7>")
	)
	(segment
		(start 190.287148 -207.942434)
		(end 189.882272 -207.942434)
		(width 0.18288)
		(layer "In4.Cu")
		(net "M_G_CPU1_SB_DQS_DP<7>")
	)
	(segment
		(start 140.772642 -226.683824)
		(end 140.749274 -226.683824)
		(width 0.088646)
		(layer "In4.Cu")
		(net "M_G_CPU1_SB_DQS_DP<7>")
	)
	(segment
		(start 176.68494 -211.342478)
		(end 176.459642 -211.567776)
		(width 0.18288)
		(layer "In4.Cu")
		(net "M_G_CPU1_SB_DQS_DP<7>")
	)
	(segment
		(start 177.089816 -211.342478)
		(end 176.68494 -211.342478)
		(width 0.18288)
		(layer "In4.Cu")
		(net "M_G_CPU1_SB_DQS_DP<7>")
	)
	(segment
		(start 182.583582 -210.025996)
		(end 182.366412 -210.116166)
		(width 0.18288)
		(layer "In4.Cu")
		(net "M_G_CPU1_SB_DQS_DP<7>")
	)
	(segment
		(start 177.348388 -211.60105)
		(end 177.089816 -211.342478)
		(width 0.18288)
		(layer "In4.Cu")
		(net "M_G_CPU1_SB_DQS_DP<7>")
	)
	(segment
		(start 188.077348 -207.942434)
		(end 187.672472 -207.942434)
		(width 0.18288)
		(layer "In4.Cu")
		(net "M_G_CPU1_SB_DQS_DP<7>")
	)
	(segment
		(start 132.971794 -232.039414)
		(end 132.95376 -232.050336)
		(width 0.088646)
		(layer "In4.Cu")
		(net "M_G_CPU1_SB_DQS_DP<7>")
	)
	(segment
		(start 136.741154 -232.033826)
		(end 136.732264 -232.038906)
		(width 0.088646)
		(layer "In4.Cu")
		(net "M_G_CPU1_SB_DQS_DP<7>")
	)
	(segment
		(start 191.958214 -208.366614)
		(end 191.699388 -208.62544)
		(width 0.18288)
		(layer "In4.Cu")
		(net "M_G_CPU1_SB_DQS_DP<7>")
	)
	(segment
		(start 137.389616 -230.890572)
		(end 137.389616 -230.900478)
		(width 0.088646)
		(layer "In4.Cu")
		(net "M_G_CPU1_SB_DQS_DP<7>")
	)
	(segment
		(start 131.3815 -232.533698)
		(end 131.376166 -232.528364)
		(width 0.088646)
		(layer "In4.Cu")
		(net "M_G_CPU1_SB_DQS_DP<7>")
	)
	(segment
		(start 138.329162 -229.26294)
		(end 138.329416 -229.272846)
		(width 0.088646)
		(layer "In4.Cu")
		(net "M_G_CPU1_SB_DQS_DP<7>")
	)
	(segment
		(start 188.317378 -208.182464)
		(end 188.077348 -207.942434)
		(width 0.18288)
		(layer "In4.Cu")
		(net "M_G_CPU1_SB_DQS_DP<7>")
	)
	(segment
		(start 189.882272 -207.942434)
		(end 189.642242 -208.182464)
		(width 0.18288)
		(layer "In4.Cu")
		(net "M_G_CPU1_SB_DQS_DP<7>")
	)
	(segment
		(start 140.689584 -226.743514)
		(end 140.40866 -226.743514)
		(width 0.088646)
		(layer "In4.Cu")
		(net "M_G_CPU1_SB_DQS_DP<7>")
	)
	(segment
		(start 132.758688 -232.130854)
		(end 132.322062 -232.130854)
		(width 0.088646)
		(layer "In4.Cu")
		(net "M_G_CPU1_SB_DQS_DP<7>")
	)
	(segment
		(start 161.167572 -211.012786)
		(end 160.754568 -211.42579)
		(width 0.18288)
		(layer "In4.Cu")
		(net "M_G_CPU1_SB_DQS_DP<7>")
	)
	(segment
		(start 187.028074 -208.19237)
		(end 186.433714 -207.946244)
		(width 0.18288)
		(layer "In4.Cu")
		(net "M_G_CPU1_SB_DQS_DP<7>")
	)
	(segment
		(start 132.97281 -232.038906)
		(end 132.971794 -232.039414)
		(width 0.088646)
		(layer "In4.Cu")
		(net "M_G_CPU1_SB_DQS_DP<7>")
	)
	(segment
		(start 172.584872 -210.492594)
		(end 172.334936 -210.74253)
		(width 0.18288)
		(layer "In4.Cu")
		(net "M_G_CPU1_SB_DQS_DP<7>")
	)
	(segment
		(start 142.606268 -226.683824)
		(end 140.772642 -226.683824)
		(width 0.18288)
		(layer "In4.Cu")
		(net "M_G_CPU1_SB_DQS_DP<7>")
	)
	(segment
		(start 168.199562 -211.406486)
		(end 164.733986 -211.406486)
		(width 0.18288)
		(layer "In4.Cu")
		(net "M_G_CPU1_SB_DQS_DP<7>")
	)
	(segment
		(start 140.40866 -226.743514)
		(end 138.799824 -228.35235)
		(width 0.088646)
		(layer "In4.Cu")
		(net "M_G_CPU1_SB_DQS_DP<7>")
	)
	(segment
		(start 172.334936 -210.74253)
		(end 171.370498 -210.74253)
		(width 0.18288)
		(layer "In4.Cu")
		(net "M_G_CPU1_SB_DQS_DP<7>")
	)
	(segment
		(start 138.150854 -229.592124)
		(end 138.141964 -229.597204)
		(width 0.088646)
		(layer "In4.Cu")
		(net "M_G_CPU1_SB_DQS_DP<7>")
	)
	(segment
		(start 186.433714 -207.946244)
		(end 184.663334 -207.946244)
		(width 0.18288)
		(layer "In4.Cu")
		(net "M_G_CPU1_SB_DQS_DP<7>")
	)
	(segment
		(start 182.366412 -210.116166)
		(end 179.662328 -210.116166)
		(width 0.18288)
		(layer "In4.Cu")
		(net "M_G_CPU1_SB_DQS_DP<7>")
	)
	(segment
		(start 178.177444 -211.60105)
		(end 177.348388 -211.60105)
		(width 0.18288)
		(layer "In4.Cu")
		(net "M_G_CPU1_SB_DQS_DP<7>")
	)
	(segment
		(start 187.672472 -207.942434)
		(end 187.422536 -208.19237)
		(width 0.18288)
		(layer "In4.Cu")
		(net "M_G_CPU1_SB_DQS_DP<7>")
	)
	(segment
		(start 140.749274 -226.683824)
		(end 140.689584 -226.743514)
		(width 0.088646)
		(layer "In4.Cu")
		(net "M_G_CPU1_SB_DQS_DP<7>")
	)
	(segment
		(start 191.983614 -208.366614)
		(end 191.958214 -208.366614)
		(width 0.18288)
		(layer "In4.Cu")
		(net "M_G_CPU1_SB_DQS_DP<7>")
	)
	(segment
		(start 131.88315 -232.533698)
		(end 131.3815 -232.533698)
		(width 0.088646)
		(layer "In4.Cu")
		(net "M_G_CPU1_SB_DQS_DP<7>")
	)
	(segment
		(start 191.340486 -208.5467)
		(end 191.002666 -208.20888)
		(width 0.18288)
		(layer "In4.Cu")
		(net "M_G_CPU1_SB_DQS_DP<7>")
	)
	(segment
		(start 190.553594 -208.20888)
		(end 190.287148 -207.942434)
		(width 0.18288)
		(layer "In4.Cu")
		(net "M_G_CPU1_SB_DQS_DP<7>")
	)
	(segment
		(start 189.642242 -208.182464)
		(end 188.317378 -208.182464)
		(width 0.18288)
		(layer "In4.Cu")
		(net "M_G_CPU1_SB_DQS_DP<7>")
	)
	(segment
		(start 132.86232 -232.102914)
		(end 132.758688 -232.130854)
		(width 0.088646)
		(layer "In4.Cu")
		(net "M_G_CPU1_SB_DQS_DP<7>")
	)
	(segment
		(start 138.612372 -228.783388)
		(end 138.59891 -228.791262)
		(width 0.088646)
		(layer "In4.Cu")
		(net "M_G_CPU1_SB_DQS_DP<7>")
	)
	(segment
		(start 168.659302 -210.946746)
		(end 168.199562 -211.406486)
		(width 0.18288)
		(layer "In4.Cu")
		(net "M_G_CPU1_SB_DQS_DP<7>")
	)
	(segment
		(start 171.166282 -210.946746)
		(end 168.659302 -210.946746)
		(width 0.18288)
		(layer "In4.Cu")
		(net "M_G_CPU1_SB_DQS_DP<7>")
	)
	(segment
		(start 176.459642 -211.567776)
		(end 175.020732 -211.567776)
		(width 0.18288)
		(layer "In4.Cu")
		(net "M_G_CPU1_SB_DQS_DP<7>")
	)
	(segment
		(start 187.422536 -208.19237)
		(end 187.028074 -208.19237)
		(width 0.18288)
		(layer "In4.Cu")
		(net "M_G_CPU1_SB_DQS_DP<7>")
	)
	(segment
		(start 164.733986 -211.406486)
		(end 164.340286 -211.012786)
		(width 0.18288)
		(layer "In4.Cu")
		(net "M_G_CPU1_SB_DQS_DP<7>")
	)
	(segment
		(start 137.211054 -231.219756)
		(end 137.202164 -231.224836)
		(width 0.088646)
		(layer "In4.Cu")
		(net "M_G_CPU1_SB_DQS_DP<7>")
	)
	(segment
		(start 137.859516 -230.076756)
		(end 137.859516 -230.086662)
		(width 0.088646)
		(layer "In4.Cu")
		(net "M_G_CPU1_SB_DQS_DP<7>")
	)
	(segment
		(start 137.680954 -230.40594)
		(end 137.672064 -230.41102)
		(width 0.088646)
		(layer "In4.Cu")
		(net "M_G_CPU1_SB_DQS_DP<7>")
	)
	(segment
		(start 179.662328 -210.116166)
		(end 178.177444 -211.60105)
		(width 0.18288)
		(layer "In4.Cu")
		(net "M_G_CPU1_SB_DQS_DP<7>")
	)
	(segment
		(start 184.663334 -207.946244)
		(end 182.583582 -210.025996)
		(width 0.18288)
		(layer "In4.Cu")
		(net "M_G_CPU1_SB_DQS_DP<7>")
	)
	(segment
		(start 171.370498 -210.74253)
		(end 171.166282 -210.946746)
		(width 0.18288)
		(layer "In4.Cu")
		(net "M_G_CPU1_SB_DQS_DP<7>")
	)
	(segment
		(start 136.919716 -231.696006)
		(end 136.919716 -231.714548)
		(width 0.088646)
		(layer "In4.Cu")
		(net "M_G_CPU1_SB_DQS_DP<7>")
	)
	(segment
		(start 175.020732 -211.567776)
		(end 174.204122 -210.751166)
		(width 0.18288)
		(layer "In4.Cu")
		(net "M_G_CPU1_SB_DQS_DP<7>")
	)
	(arc
		(start 134.478268 -232.038906)
		(mid 134.195566 -231.96313)
		(end 133.912864 -232.038906)
		(width 0.088646)
		(layer "In4.Cu")
		(net "M_G_CPU1_SB_DQS_DP<7>")
	)
	(arc
		(start 136.357868 -232.038906)
		(mid 136.075166 -231.96313)
		(end 135.792464 -232.038906)
		(width 0.088646)
		(layer "In4.Cu")
		(net "M_G_CPU1_SB_DQS_DP<7>")
	)
	(arc
		(start 132.230114 -232.154984)
		(mid 132.204892 -232.168204)
		(end 132.178806 -232.179622)
		(width 0.088646)
		(layer "In4.Cu")
		(net "M_G_CPU1_SB_DQS_DP<7>")
	)
	(arc
		(start 138.141964 -229.597204)
		(mid 137.937629 -229.799809)
		(end 137.859516 -230.076756)
		(width 0.088646)
		(layer "In4.Cu")
		(net "M_G_CPU1_SB_DQS_DP<7>")
	)
	(arc
		(start 135.792464 -232.038906)
		(mid 135.605266 -232.089049)
		(end 135.418068 -232.038906)
		(width 0.088646)
		(layer "In4.Cu")
		(net "M_G_CPU1_SB_DQS_DP<7>")
	)
	(arc
		(start 137.202164 -231.224836)
		(mid 136.999878 -231.423817)
		(end 136.919716 -231.696006)
		(width 0.088646)
		(layer "In4.Cu")
		(net "M_G_CPU1_SB_DQS_DP<7>")
	)
	(arc
		(start 132.322062 -232.130854)
		(mid 132.274532 -232.136988)
		(end 132.230114 -232.154984)
		(width 0.088646)
		(layer "In4.Cu")
		(net "M_G_CPU1_SB_DQS_DP<7>")
	)
	(arc
		(start 133.912864 -232.038906)
		(mid 133.725666 -232.089049)
		(end 133.538468 -232.038906)
		(width 0.088646)
		(layer "In4.Cu")
		(net "M_G_CPU1_SB_DQS_DP<7>")
	)
	(arc
		(start 135.418068 -232.038906)
		(mid 135.135366 -231.96313)
		(end 134.852664 -232.038906)
		(width 0.088646)
		(layer "In4.Cu")
		(net "M_G_CPU1_SB_DQS_DP<7>")
	)
	(arc
		(start 137.672064 -230.41102)
		(mid 137.467729 -230.613625)
		(end 137.389616 -230.890572)
		(width 0.088646)
		(layer "In4.Cu")
		(net "M_G_CPU1_SB_DQS_DP<7>")
	)
	(arc
		(start 138.799824 -228.466396)
		(mid 138.747657 -228.649456)
		(end 138.612372 -228.783388)
		(width 0.088646)
		(layer "In4.Cu")
		(net "M_G_CPU1_SB_DQS_DP<7>")
	)
	(arc
		(start 136.919716 -231.714548)
		(mid 136.872037 -231.897448)
		(end 136.741154 -232.033826)
		(width 0.088646)
		(layer "In4.Cu")
		(net "M_G_CPU1_SB_DQS_DP<7>")
	)
	(arc
		(start 133.538468 -232.038906)
		(mid 133.261655 -231.963036)
		(end 132.983224 -232.03281)
		(width 0.088646)
		(layer "In4.Cu")
		(net "M_G_CPU1_SB_DQS_DP<7>")
	)
	(arc
		(start 138.598656 -228.790754)
		(mid 138.403456 -228.992339)
		(end 138.329162 -229.26294)
		(width 0.088646)
		(layer "In4.Cu")
		(net "M_G_CPU1_SB_DQS_DP<7>")
	)
	(arc
		(start 138.329416 -229.272846)
		(mid 138.281737 -229.455746)
		(end 138.150854 -229.592124)
		(width 0.088646)
		(layer "In4.Cu")
		(net "M_G_CPU1_SB_DQS_DP<7>")
	)
	(arc
		(start 134.852664 -232.038906)
		(mid 134.665466 -232.089049)
		(end 134.478268 -232.038906)
		(width 0.088646)
		(layer "In4.Cu")
		(net "M_G_CPU1_SB_DQS_DP<7>")
	)
	(arc
		(start 137.389616 -230.900478)
		(mid 137.341937 -231.083378)
		(end 137.211054 -231.219756)
		(width 0.088646)
		(layer "In4.Cu")
		(net "M_G_CPU1_SB_DQS_DP<7>")
	)
	(arc
		(start 136.732264 -232.038906)
		(mid 136.545066 -232.089049)
		(end 136.357868 -232.038906)
		(width 0.088646)
		(layer "In4.Cu")
		(net "M_G_CPU1_SB_DQS_DP<7>")
	)
	(arc
		(start 132.178806 -232.179622)
		(mid 132.023473 -232.29422)
		(end 131.945888 -232.47096)
		(width 0.088646)
		(layer "In4.Cu")
		(net "M_G_CPU1_SB_DQS_DP<7>")
	)
	(arc
		(start 137.859516 -230.086662)
		(mid 137.811837 -230.269562)
		(end 137.680954 -230.40594)
		(width 0.088646)
		(layer "In4.Cu")
		(net "M_G_CPU1_SB_DQS_DP<7>")
	)
	(segment
		(start 194.237864 -217.967814)
		(end 194.662806 -217.542872)
		(width 0.20066)
		(layer "F.Cu")
		(net "M_G_CPU1_SB_DQS_DP<6>")
	)
	(segment
		(start 129.026412 -235.505752)
		(end 129.026412 -234.970066)
		(width 0.20066)
		(layer "F.Cu")
		(net "M_G_CPU1_SB_DQS_DP<6>")
	)
	(segment
		(start 199.21855 -217.984832)
		(end 199.796146 -217.984832)
		(width 0.20066)
		(layer "F.Cu")
		(net "M_G_CPU1_SB_DQS_DP<6>")
	)
	(segment
		(start 129.026666 -235.506006)
		(end 129.026412 -235.505752)
		(width 0.20066)
		(layer "F.Cu")
		(net "M_G_CPU1_SB_DQS_DP<6>")
	)
	(segment
		(start 197.535292 -217.291666)
		(end 197.542658 -217.2843)
		(width 0.1016)
		(layer "F.Cu")
		(net "M_G_CPU1_SB_DQS_DP<6>")
	)
	(segment
		(start 199.796146 -217.984832)
		(end 200.06437 -217.716608)
		(width 0.20066)
		(layer "F.Cu")
		(net "M_G_CPU1_SB_DQS_DP<6>")
	)
	(segment
		(start 197.542658 -217.2843)
		(end 197.864476 -217.2843)
		(width 0.20066)
		(layer "F.Cu")
		(net "M_G_CPU1_SB_DQS_DP<6>")
	)
	(segment
		(start 194.662806 -217.542872)
		(end 194.94119 -217.542872)
		(width 0.20066)
		(layer "F.Cu")
		(net "M_G_CPU1_SB_DQS_DP<6>")
	)
	(segment
		(start 193.681858 -217.716608)
		(end 193.933064 -217.967814)
		(width 0.20066)
		(layer "F.Cu")
		(net "M_G_CPU1_SB_DQS_DP<6>")
	)
	(segment
		(start 191.983614 -217.716608)
		(end 193.088514 -217.716608)
		(width 0.20066)
		(layer "F.Cu")
		(net "M_G_CPU1_SB_DQS_DP<6>")
	)
	(segment
		(start 195.522596 -217.291666)
		(end 197.535292 -217.291666)
		(width 0.1016)
		(layer "F.Cu")
		(net "M_G_CPU1_SB_DQS_DP<6>")
	)
	(segment
		(start 195.199508 -217.284554)
		(end 195.510658 -217.284554)
		(width 0.20066)
		(layer "F.Cu")
		(net "M_G_CPU1_SB_DQS_DP<6>")
	)
	(segment
		(start 193.933064 -217.967814)
		(end 194.237864 -217.967814)
		(width 0.20066)
		(layer "F.Cu")
		(net "M_G_CPU1_SB_DQS_DP<6>")
	)
	(segment
		(start 194.94119 -217.542872)
		(end 195.199508 -217.284554)
		(width 0.20066)
		(layer "F.Cu")
		(net "M_G_CPU1_SB_DQS_DP<6>")
	)
	(segment
		(start 195.510658 -217.284554)
		(end 195.515484 -217.284554)
		(width 0.101854)
		(layer "F.Cu")
		(net "M_G_CPU1_SB_DQS_DP<6>")
	)
	(segment
		(start 198.773034 -217.539316)
		(end 199.21855 -217.984832)
		(width 0.20066)
		(layer "F.Cu")
		(net "M_G_CPU1_SB_DQS_DP<6>")
	)
	(segment
		(start 193.088514 -217.716608)
		(end 193.681858 -217.716608)
		(width 0.20066)
		(layer "F.Cu")
		(net "M_G_CPU1_SB_DQS_DP<6>")
	)
	(segment
		(start 200.06437 -217.716608)
		(end 200.632314 -217.716608)
		(width 0.20066)
		(layer "F.Cu")
		(net "M_G_CPU1_SB_DQS_DP<6>")
	)
	(segment
		(start 198.119492 -217.539316)
		(end 198.773034 -217.539316)
		(width 0.20066)
		(layer "F.Cu")
		(net "M_G_CPU1_SB_DQS_DP<6>")
	)
	(segment
		(start 197.864476 -217.2843)
		(end 198.119492 -217.539316)
		(width 0.20066)
		(layer "F.Cu")
		(net "M_G_CPU1_SB_DQS_DP<6>")
	)
	(segment
		(start 195.515484 -217.284554)
		(end 195.522596 -217.291666)
		(width 0.1016)
		(layer "F.Cu")
		(net "M_G_CPU1_SB_DQS_DP<6>")
	)
	(segment
		(start 189.735968 -219.057728)
		(end 188.784484 -220.009212)
		(width 0.18288)
		(layer "In6.Cu")
		(net "M_G_CPU1_SB_DQS_DP<6>")
	)
	(segment
		(start 157.150308 -221.191582)
		(end 157.025848 -221.067122)
		(width 0.18288)
		(layer "In6.Cu")
		(net "M_G_CPU1_SB_DQS_DP<6>")
	)
	(segment
		(start 156.479748 -221.067122)
		(end 156.355288 -221.191582)
		(width 0.18288)
		(layer "In6.Cu")
		(net "M_G_CPU1_SB_DQS_DP<6>")
	)
	(segment
		(start 177.074068 -222.392494)
		(end 176.722024 -222.392494)
		(width 0.18288)
		(layer "In6.Cu")
		(net "M_G_CPU1_SB_DQS_DP<6>")
	)
	(segment
		(start 177.757074 -222.661226)
		(end 177.3428 -222.661226)
		(width 0.18288)
		(layer "In6.Cu")
		(net "M_G_CPU1_SB_DQS_DP<6>")
	)
	(segment
		(start 187.621418 -219.845382)
		(end 185.585354 -219.845382)
		(width 0.18288)
		(layer "In6.Cu")
		(net "M_G_CPU1_SB_DQS_DP<6>")
	)
	(segment
		(start 168.927272 -223.454214)
		(end 167.92829 -222.455232)
		(width 0.18288)
		(layer "In6.Cu")
		(net "M_G_CPU1_SB_DQS_DP<6>")
	)
	(segment
		(start 173.916594 -223.33458)
		(end 173.464982 -223.522794)
		(width 0.18288)
		(layer "In6.Cu")
		(net "M_G_CPU1_SB_DQS_DP<6>")
	)
	(segment
		(start 159.596836 -221.067122)
		(end 159.472376 -221.191582)
		(width 0.18288)
		(layer "In6.Cu")
		(net "M_G_CPU1_SB_DQS_DP<6>")
	)
	(segment
		(start 132.039106 -235.291122)
		(end 132.027422 -235.297726)
		(width 0.088646)
		(layer "In6.Cu")
		(net "M_G_CPU1_SB_DQS_DP<6>")
	)
	(segment
		(start 190.684404 -218.109292)
		(end 190.298324 -218.495372)
		(width 0.18288)
		(layer "In6.Cu")
		(net "M_G_CPU1_SB_DQS_DP<6>")
	)
	(segment
		(start 177.3428 -222.661226)
		(end 177.074068 -222.392494)
		(width 0.18288)
		(layer "In6.Cu")
		(net "M_G_CPU1_SB_DQS_DP<6>")
	)
	(segment
		(start 130.159506 -235.291122)
		(end 130.15849 -235.29163)
		(width 0.088646)
		(layer "In6.Cu")
		(net "M_G_CPU1_SB_DQS_DP<6>")
	)
	(segment
		(start 171.723558 -223.501458)
		(end 171.599098 -223.376998)
		(width 0.18288)
		(layer "In6.Cu")
		(net "M_G_CPU1_SB_DQS_DP<6>")
	)
	(segment
		(start 169.711878 -223.376998)
		(end 169.587418 -223.501458)
		(width 0.18288)
		(layer "In6.Cu")
		(net "M_G_CPU1_SB_DQS_DP<6>")
	)
	(segment
		(start 190.298324 -218.495372)
		(end 190.122302 -218.495372)
		(width 0.18288)
		(layer "In6.Cu")
		(net "M_G_CPU1_SB_DQS_DP<6>")
	)
	(segment
		(start 157.025848 -221.067122)
		(end 156.479748 -221.067122)
		(width 0.18288)
		(layer "In6.Cu")
		(net "M_G_CPU1_SB_DQS_DP<6>")
	)
	(segment
		(start 169.587418 -223.501458)
		(end 169.041318 -223.501458)
		(width 0.18288)
		(layer "In6.Cu")
		(net "M_G_CPU1_SB_DQS_DP<6>")
	)
	(segment
		(start 152.085548 -224.985326)
		(end 143.440912 -233.629962)
		(width 0.18288)
		(layer "In6.Cu")
		(net "M_G_CPU1_SB_DQS_DP<6>")
	)
	(segment
		(start 180.880766 -220.711268)
		(end 179.60975 -221.560644)
		(width 0.18288)
		(layer "In6.Cu")
		(net "M_G_CPU1_SB_DQS_DP<6>")
	)
	(segment
		(start 191.961262 -217.716608)
		(end 191.643508 -218.034362)
		(width 0.18288)
		(layer "In6.Cu")
		(net "M_G_CPU1_SB_DQS_DP<6>")
	)
	(segment
		(start 143.440912 -233.629962)
		(end 140.061696 -233.629962)
		(width 0.18288)
		(layer "In6.Cu")
		(net "M_G_CPU1_SB_DQS_DP<6>")
	)
	(segment
		(start 170.257978 -223.376998)
		(end 169.711878 -223.376998)
		(width 0.18288)
		(layer "In6.Cu")
		(net "M_G_CPU1_SB_DQS_DP<6>")
	)
	(segment
		(start 140.061696 -233.629962)
		(end 140.009372 -233.629962)
		(width 0.088646)
		(layer "In6.Cu")
		(net "M_G_CPU1_SB_DQS_DP<6>")
	)
	(segment
		(start 183.719724 -219.987368)
		(end 183.134 -220.573092)
		(width 0.18288)
		(layer "In6.Cu")
		(net "M_G_CPU1_SB_DQS_DP<6>")
	)
	(segment
		(start 137.6807 -235.289344)
		(end 137.67181 -235.294424)
		(width 0.088646)
		(layer "In6.Cu")
		(net "M_G_CPU1_SB_DQS_DP<6>")
	)
	(segment
		(start 153.98242 -223.088454)
		(end 153.59634 -223.474534)
		(width 0.18288)
		(layer "In6.Cu")
		(net "M_G_CPU1_SB_DQS_DP<6>")
	)
	(segment
		(start 139.4206 -233.996992)
		(end 138.984736 -234.317286)
		(width 0.088646)
		(layer "In6.Cu")
		(net "M_G_CPU1_SB_DQS_DP<6>")
	)
	(segment
		(start 178.026314 -222.549466)
		(end 177.757074 -222.661226)
		(width 0.18288)
		(layer "In6.Cu")
		(net "M_G_CPU1_SB_DQS_DP<6>")
	)
	(segment
		(start 183.134 -220.573092)
		(end 182.801006 -220.711268)
		(width 0.18288)
		(layer "In6.Cu")
		(net "M_G_CPU1_SB_DQS_DP<6>")
	)
	(segment
		(start 187.624212 -219.842588)
		(end 187.621418 -219.845382)
		(width 0.18288)
		(layer "In6.Cu")
		(net "M_G_CPU1_SB_DQS_DP<6>")
	)
	(segment
		(start 159.472376 -221.191582)
		(end 158.491428 -221.191582)
		(width 0.18288)
		(layer "In6.Cu")
		(net "M_G_CPU1_SB_DQS_DP<6>")
	)
	(segment
		(start 184.062878 -219.845382)
		(end 183.719724 -219.987368)
		(width 0.18288)
		(layer "In6.Cu")
		(net "M_G_CPU1_SB_DQS_DP<6>")
	)
	(segment
		(start 169.041318 -223.501458)
		(end 168.927272 -223.454214)
		(width 0.18288)
		(layer "In6.Cu")
		(net "M_G_CPU1_SB_DQS_DP<6>")
	)
	(segment
		(start 185.585354 -219.845382)
		(end 185.460894 -219.720922)
		(width 0.18288)
		(layer "In6.Cu")
		(net "M_G_CPU1_SB_DQS_DP<6>")
	)
	(segment
		(start 153.98242 -222.912432)
		(end 153.98242 -223.088454)
		(width 0.18288)
		(layer "In6.Cu")
		(net "M_G_CPU1_SB_DQS_DP<6>")
	)
	(segment
		(start 185.460894 -219.720922)
		(end 184.914794 -219.720922)
		(width 0.18288)
		(layer "In6.Cu")
		(net "M_G_CPU1_SB_DQS_DP<6>")
	)
	(segment
		(start 131.099306 -235.291122)
		(end 131.087622 -235.297726)
		(width 0.088646)
		(layer "In6.Cu")
		(net "M_G_CPU1_SB_DQS_DP<6>")
	)
	(segment
		(start 152.085548 -224.809304)
		(end 152.085548 -224.985326)
		(width 0.18288)
		(layer "In6.Cu")
		(net "M_G_CPU1_SB_DQS_DP<6>")
	)
	(segment
		(start 157.820868 -221.067122)
		(end 157.696408 -221.191582)
		(width 0.18288)
		(layer "In6.Cu")
		(net "M_G_CPU1_SB_DQS_DP<6>")
	)
	(segment
		(start 191.643508 -218.034362)
		(end 190.86576 -218.034362)
		(width 0.18288)
		(layer "In6.Cu")
		(net "M_G_CPU1_SB_DQS_DP<6>")
	)
	(segment
		(start 161.220404 -221.538546)
		(end 160.87344 -221.191582)
		(width 0.18288)
		(layer "In6.Cu")
		(net "M_G_CPU1_SB_DQS_DP<6>")
	)
	(segment
		(start 129.139188 -235.082842)
		(end 129.026412 -234.970066)
		(width 0.088646)
		(layer "In6.Cu")
		(net "M_G_CPU1_SB_DQS_DP<6>")
	)
	(segment
		(start 184.914794 -219.720922)
		(end 184.790334 -219.845382)
		(width 0.18288)
		(layer "In6.Cu")
		(net "M_G_CPU1_SB_DQS_DP<6>")
	)
	(segment
		(start 165.783006 -221.198948)
		(end 165.07206 -221.198948)
		(width 0.18288)
		(layer "In6.Cu")
		(net "M_G_CPU1_SB_DQS_DP<6>")
	)
	(segment
		(start 190.122302 -218.495372)
		(end 189.735968 -218.881706)
		(width 0.18288)
		(layer "In6.Cu")
		(net "M_G_CPU1_SB_DQS_DP<6>")
	)
	(segment
		(start 138.139678 -234.481878)
		(end 138.137646 -234.483148)
		(width 0.088646)
		(layer "In6.Cu")
		(net "M_G_CPU1_SB_DQS_DP<6>")
	)
	(segment
		(start 139.737846 -233.689652)
		(end 139.48791 -233.939334)
		(width 0.088646)
		(layer "In6.Cu")
		(net "M_G_CPU1_SB_DQS_DP<6>")
	)
	(segment
		(start 153.033984 -224.03689)
		(end 152.647904 -224.42297)
		(width 0.18288)
		(layer "In6.Cu")
		(net "M_G_CPU1_SB_DQS_DP<6>")
	)
	(segment
		(start 133.538468 -235.294424)
		(end 133.528054 -235.288328)
		(width 0.088646)
		(layer "In6.Cu")
		(net "M_G_CPU1_SB_DQS_DP<6>")
	)
	(segment
		(start 178.594512 -221.981268)
		(end 178.026314 -222.549466)
		(width 0.18288)
		(layer "In6.Cu")
		(net "M_G_CPU1_SB_DQS_DP<6>")
	)
	(segment
		(start 129.76098 -235.283756)
		(end 129.479294 -235.09986)
		(width 0.088646)
		(layer "In6.Cu")
		(net "M_G_CPU1_SB_DQS_DP<6>")
	)
	(segment
		(start 162.426396 -221.414086)
		(end 162.301936 -221.538546)
		(width 0.18288)
		(layer "In6.Cu")
		(net "M_G_CPU1_SB_DQS_DP<6>")
	)
	(segment
		(start 164.252402 -221.538546)
		(end 163.096956 -221.538546)
		(width 0.18288)
		(layer "In6.Cu")
		(net "M_G_CPU1_SB_DQS_DP<6>")
	)
	(segment
		(start 154.930856 -222.140018)
		(end 154.544776 -222.526098)
		(width 0.18288)
		(layer "In6.Cu")
		(net "M_G_CPU1_SB_DQS_DP<6>")
	)
	(segment
		(start 172.622972 -223.242378)
		(end 172.363892 -223.501458)
		(width 0.18288)
		(layer "In6.Cu")
		(net "M_G_CPU1_SB_DQS_DP<6>")
	)
	(segment
		(start 188.15304 -219.842588)
		(end 187.624212 -219.842588)
		(width 0.18288)
		(layer "In6.Cu")
		(net "M_G_CPU1_SB_DQS_DP<6>")
	)
	(segment
		(start 138.141964 -234.480608)
		(end 138.139678 -234.481878)
		(width 0.088646)
		(layer "In6.Cu")
		(net "M_G_CPU1_SB_DQS_DP<6>")
	)
	(segment
		(start 173.464982 -223.522794)
		(end 173.251876 -223.522794)
		(width 0.18288)
		(layer "In6.Cu")
		(net "M_G_CPU1_SB_DQS_DP<6>")
	)
	(segment
		(start 155.493212 -221.577662)
		(end 155.31719 -221.577662)
		(width 0.18288)
		(layer "In6.Cu")
		(net "M_G_CPU1_SB_DQS_DP<6>")
	)
	(segment
		(start 158.491428 -221.191582)
		(end 158.366968 -221.067122)
		(width 0.18288)
		(layer "In6.Cu")
		(net "M_G_CPU1_SB_DQS_DP<6>")
	)
	(segment
		(start 170.928538 -223.501458)
		(end 170.382438 -223.501458)
		(width 0.18288)
		(layer "In6.Cu")
		(net "M_G_CPU1_SB_DQS_DP<6>")
	)
	(segment
		(start 188.601858 -220.086174)
		(end 188.396626 -220.086174)
		(width 0.18288)
		(layer "In6.Cu")
		(net "M_G_CPU1_SB_DQS_DP<6>")
	)
	(segment
		(start 176.722024 -222.392494)
		(end 176.44237 -222.672148)
		(width 0.18288)
		(layer "In6.Cu")
		(net "M_G_CPU1_SB_DQS_DP<6>")
	)
	(segment
		(start 130.15849 -235.29163)
		(end 130.157728 -235.292138)
		(width 0.088646)
		(layer "In6.Cu")
		(net "M_G_CPU1_SB_DQS_DP<6>")
	)
	(segment
		(start 152.471882 -224.42297)
		(end 152.085548 -224.809304)
		(width 0.18288)
		(layer "In6.Cu")
		(net "M_G_CPU1_SB_DQS_DP<6>")
	)
	(segment
		(start 182.801006 -220.711268)
		(end 180.880766 -220.711268)
		(width 0.18288)
		(layer "In6.Cu")
		(net "M_G_CPU1_SB_DQS_DP<6>")
	)
	(segment
		(start 158.366968 -221.067122)
		(end 157.820868 -221.067122)
		(width 0.18288)
		(layer "In6.Cu")
		(net "M_G_CPU1_SB_DQS_DP<6>")
	)
	(segment
		(start 172.97146 -223.242378)
		(end 172.622972 -223.242378)
		(width 0.18288)
		(layer "In6.Cu")
		(net "M_G_CPU1_SB_DQS_DP<6>")
	)
	(segment
		(start 162.972496 -221.414086)
		(end 162.426396 -221.414086)
		(width 0.18288)
		(layer "In6.Cu")
		(net "M_G_CPU1_SB_DQS_DP<6>")
	)
	(segment
		(start 154.930856 -221.963996)
		(end 154.930856 -222.140018)
		(width 0.18288)
		(layer "In6.Cu")
		(net "M_G_CPU1_SB_DQS_DP<6>")
	)
	(segment
		(start 140.009372 -233.629962)
		(end 139.949682 -233.689652)
		(width 0.088646)
		(layer "In6.Cu")
		(net "M_G_CPU1_SB_DQS_DP<6>")
	)
	(segment
		(start 191.983614 -217.716608)
		(end 191.961262 -217.716608)
		(width 0.18288)
		(layer "In6.Cu")
		(net "M_G_CPU1_SB_DQS_DP<6>")
	)
	(segment
		(start 160.267396 -221.191582)
		(end 160.142936 -221.067122)
		(width 0.18288)
		(layer "In6.Cu")
		(net "M_G_CPU1_SB_DQS_DP<6>")
	)
	(segment
		(start 160.142936 -221.067122)
		(end 159.596836 -221.067122)
		(width 0.18288)
		(layer "In6.Cu")
		(net "M_G_CPU1_SB_DQS_DP<6>")
	)
	(segment
		(start 153.420318 -223.474534)
		(end 153.033984 -223.860868)
		(width 0.18288)
		(layer "In6.Cu")
		(net "M_G_CPU1_SB_DQS_DP<6>")
	)
	(segment
		(start 156.355288 -221.191582)
		(end 155.879292 -221.191582)
		(width 0.18288)
		(layer "In6.Cu")
		(net "M_G_CPU1_SB_DQS_DP<6>")
	)
	(segment
		(start 189.735968 -218.881706)
		(end 189.735968 -219.057728)
		(width 0.18288)
		(layer "In6.Cu")
		(net "M_G_CPU1_SB_DQS_DP<6>")
	)
	(segment
		(start 155.879292 -221.191582)
		(end 155.493212 -221.577662)
		(width 0.18288)
		(layer "In6.Cu")
		(net "M_G_CPU1_SB_DQS_DP<6>")
	)
	(segment
		(start 173.251876 -223.522794)
		(end 172.97146 -223.242378)
		(width 0.18288)
		(layer "In6.Cu")
		(net "M_G_CPU1_SB_DQS_DP<6>")
	)
	(segment
		(start 176.44237 -222.672148)
		(end 174.894748 -222.672148)
		(width 0.18288)
		(layer "In6.Cu")
		(net "M_G_CPU1_SB_DQS_DP<6>")
	)
	(segment
		(start 157.696408 -221.191582)
		(end 157.150308 -221.191582)
		(width 0.18288)
		(layer "In6.Cu")
		(net "M_G_CPU1_SB_DQS_DP<6>")
	)
	(segment
		(start 153.59634 -223.474534)
		(end 153.420318 -223.474534)
		(width 0.18288)
		(layer "In6.Cu")
		(net "M_G_CPU1_SB_DQS_DP<6>")
	)
	(segment
		(start 136.357614 -235.294424)
		(end 136.3472 -235.288328)
		(width 0.088646)
		(layer "In6.Cu")
		(net "M_G_CPU1_SB_DQS_DP<6>")
	)
	(segment
		(start 155.31719 -221.577662)
		(end 154.930856 -221.963996)
		(width 0.18288)
		(layer "In6.Cu")
		(net "M_G_CPU1_SB_DQS_DP<6>")
	)
	(segment
		(start 190.86576 -218.034362)
		(end 190.684404 -218.109292)
		(width 0.18288)
		(layer "In6.Cu")
		(net "M_G_CPU1_SB_DQS_DP<6>")
	)
	(segment
		(start 139.949682 -233.689652)
		(end 139.737846 -233.689652)
		(width 0.088646)
		(layer "In6.Cu")
		(net "M_G_CPU1_SB_DQS_DP<6>")
	)
	(segment
		(start 129.479294 -235.09986)
		(end 129.139188 -235.082842)
		(width 0.088646)
		(layer "In6.Cu")
		(net "M_G_CPU1_SB_DQS_DP<6>")
	)
	(segment
		(start 138.156696 -234.471972)
		(end 138.141964 -234.480608)
		(width 0.088646)
		(layer "In6.Cu")
		(net "M_G_CPU1_SB_DQS_DP<6>")
	)
	(segment
		(start 174.894748 -222.672148)
		(end 174.356776 -222.894398)
		(width 0.18288)
		(layer "In6.Cu")
		(net "M_G_CPU1_SB_DQS_DP<6>")
	)
	(segment
		(start 188.396626 -220.086174)
		(end 188.15304 -219.842588)
		(width 0.18288)
		(layer "In6.Cu")
		(net "M_G_CPU1_SB_DQS_DP<6>")
	)
	(segment
		(start 184.790334 -219.845382)
		(end 184.062878 -219.845382)
		(width 0.18288)
		(layer "In6.Cu")
		(net "M_G_CPU1_SB_DQS_DP<6>")
	)
	(segment
		(start 137.297414 -235.294424)
		(end 137.282682 -235.285788)
		(width 0.088646)
		(layer "In6.Cu")
		(net "M_G_CPU1_SB_DQS_DP<6>")
	)
	(segment
		(start 167.03929 -222.455232)
		(end 165.783006 -221.198948)
		(width 0.18288)
		(layer "In6.Cu")
		(net "M_G_CPU1_SB_DQS_DP<6>")
	)
	(segment
		(start 174.356776 -222.894398)
		(end 173.916594 -223.33458)
		(width 0.18288)
		(layer "In6.Cu")
		(net "M_G_CPU1_SB_DQS_DP<6>")
	)
	(segment
		(start 162.301936 -221.538546)
		(end 161.220404 -221.538546)
		(width 0.18288)
		(layer "In6.Cu")
		(net "M_G_CPU1_SB_DQS_DP<6>")
	)
	(segment
		(start 153.033984 -223.860868)
		(end 153.033984 -224.03689)
		(width 0.18288)
		(layer "In6.Cu")
		(net "M_G_CPU1_SB_DQS_DP<6>")
	)
	(segment
		(start 167.92829 -222.455232)
		(end 167.03929 -222.455232)
		(width 0.18288)
		(layer "In6.Cu")
		(net "M_G_CPU1_SB_DQS_DP<6>")
	)
	(segment
		(start 172.363892 -223.501458)
		(end 171.723558 -223.501458)
		(width 0.18288)
		(layer "In6.Cu")
		(net "M_G_CPU1_SB_DQS_DP<6>")
	)
	(segment
		(start 163.096956 -221.538546)
		(end 162.972496 -221.414086)
		(width 0.18288)
		(layer "In6.Cu")
		(net "M_G_CPU1_SB_DQS_DP<6>")
	)
	(segment
		(start 138.137646 -234.483148)
		(end 138.135868 -234.484164)
		(width 0.088646)
		(layer "In6.Cu")
		(net "M_G_CPU1_SB_DQS_DP<6>")
	)
	(segment
		(start 179.14493 -221.753176)
		(end 178.594512 -221.981268)
		(width 0.18288)
		(layer "In6.Cu")
		(net "M_G_CPU1_SB_DQS_DP<6>")
	)
	(segment
		(start 179.60975 -221.560644)
		(end 179.14493 -221.753176)
		(width 0.18288)
		(layer "In6.Cu")
		(net "M_G_CPU1_SB_DQS_DP<6>")
	)
	(segment
		(start 165.07206 -221.198948)
		(end 164.252402 -221.538546)
		(width 0.18288)
		(layer "In6.Cu")
		(net "M_G_CPU1_SB_DQS_DP<6>")
	)
	(segment
		(start 188.784484 -220.009212)
		(end 188.601858 -220.086174)
		(width 0.18288)
		(layer "In6.Cu")
		(net "M_G_CPU1_SB_DQS_DP<6>")
	)
	(segment
		(start 130.157728 -235.292138)
		(end 130.147822 -235.297726)
		(width 0.088646)
		(layer "In6.Cu")
		(net "M_G_CPU1_SB_DQS_DP<6>")
	)
	(segment
		(start 152.647904 -224.42297)
		(end 152.471882 -224.42297)
		(width 0.18288)
		(layer "In6.Cu")
		(net "M_G_CPU1_SB_DQS_DP<6>")
	)
	(segment
		(start 154.368754 -222.526098)
		(end 153.98242 -222.912432)
		(width 0.18288)
		(layer "In6.Cu")
		(net "M_G_CPU1_SB_DQS_DP<6>")
	)
	(segment
		(start 154.544776 -222.526098)
		(end 154.368754 -222.526098)
		(width 0.18288)
		(layer "In6.Cu")
		(net "M_G_CPU1_SB_DQS_DP<6>")
	)
	(segment
		(start 171.599098 -223.376998)
		(end 171.052998 -223.376998)
		(width 0.18288)
		(layer "In6.Cu")
		(net "M_G_CPU1_SB_DQS_DP<6>")
	)
	(segment
		(start 160.87344 -221.191582)
		(end 160.267396 -221.191582)
		(width 0.18288)
		(layer "In6.Cu")
		(net "M_G_CPU1_SB_DQS_DP<6>")
	)
	(segment
		(start 171.052998 -223.376998)
		(end 170.928538 -223.501458)
		(width 0.18288)
		(layer "In6.Cu")
		(net "M_G_CPU1_SB_DQS_DP<6>")
	)
	(segment
		(start 170.382438 -223.501458)
		(end 170.257978 -223.376998)
		(width 0.18288)
		(layer "In6.Cu")
		(net "M_G_CPU1_SB_DQS_DP<6>")
	)
	(arc
		(start 137.67181 -235.294424)
		(mid 137.484612 -235.344567)
		(end 137.297414 -235.294424)
		(width 0.088646)
		(layer "In6.Cu")
		(net "M_G_CPU1_SB_DQS_DP<6>")
	)
	(arc
		(start 131.658614 -235.294424)
		(mid 131.379411 -235.218784)
		(end 131.099306 -235.291122)
		(width 0.088646)
		(layer "In6.Cu")
		(net "M_G_CPU1_SB_DQS_DP<6>")
	)
	(arc
		(start 134.852664 -235.294424)
		(mid 134.665466 -235.344567)
		(end 134.478268 -235.294424)
		(width 0.088646)
		(layer "In6.Cu")
		(net "M_G_CPU1_SB_DQS_DP<6>")
	)
	(arc
		(start 132.027422 -235.297726)
		(mid 131.842567 -235.344676)
		(end 131.658614 -235.294424)
		(width 0.088646)
		(layer "In6.Cu")
		(net "M_G_CPU1_SB_DQS_DP<6>")
	)
	(arc
		(start 137.859262 -234.970066)
		(mid 137.811583 -235.152966)
		(end 137.6807 -235.289344)
		(width 0.088646)
		(layer "In6.Cu")
		(net "M_G_CPU1_SB_DQS_DP<6>")
	)
	(arc
		(start 136.73201 -235.294424)
		(mid 136.544812 -235.344567)
		(end 136.357614 -235.294424)
		(width 0.088646)
		(layer "In6.Cu")
		(net "M_G_CPU1_SB_DQS_DP<6>")
	)
	(arc
		(start 130.718814 -235.294424)
		(mid 130.439611 -235.218784)
		(end 130.159506 -235.291122)
		(width 0.088646)
		(layer "In6.Cu")
		(net "M_G_CPU1_SB_DQS_DP<6>")
	)
	(arc
		(start 134.478268 -235.294424)
		(mid 134.195566 -235.218648)
		(end 133.912864 -235.294424)
		(width 0.088646)
		(layer "In6.Cu")
		(net "M_G_CPU1_SB_DQS_DP<6>")
	)
	(arc
		(start 135.792464 -235.294424)
		(mid 135.605266 -235.344567)
		(end 135.418068 -235.294424)
		(width 0.088646)
		(layer "In6.Cu")
		(net "M_G_CPU1_SB_DQS_DP<6>")
	)
	(arc
		(start 138.984736 -234.317286)
		(mid 138.771396 -234.413893)
		(end 138.537188 -234.415838)
		(width 0.088646)
		(layer "In6.Cu")
		(net "M_G_CPU1_SB_DQS_DP<6>")
	)
	(arc
		(start 132.598414 -235.294424)
		(mid 132.319211 -235.218784)
		(end 132.039106 -235.291122)
		(width 0.088646)
		(layer "In6.Cu")
		(net "M_G_CPU1_SB_DQS_DP<6>")
	)
	(arc
		(start 130.147822 -235.297726)
		(mid 129.952453 -235.344475)
		(end 129.76098 -235.283756)
		(width 0.088646)
		(layer "In6.Cu")
		(net "M_G_CPU1_SB_DQS_DP<6>")
	)
	(arc
		(start 136.3472 -235.288328)
		(mid 136.069022 -235.218605)
		(end 135.792464 -235.294424)
		(width 0.088646)
		(layer "In6.Cu")
		(net "M_G_CPU1_SB_DQS_DP<6>")
	)
	(arc
		(start 133.528054 -235.288328)
		(mid 133.249622 -235.218482)
		(end 132.97281 -235.294424)
		(width 0.088646)
		(layer "In6.Cu")
		(net "M_G_CPU1_SB_DQS_DP<6>")
	)
	(arc
		(start 131.087622 -235.297726)
		(mid 130.902767 -235.344676)
		(end 130.718814 -235.294424)
		(width 0.088646)
		(layer "In6.Cu")
		(net "M_G_CPU1_SB_DQS_DP<6>")
	)
	(arc
		(start 135.418068 -235.294424)
		(mid 135.135366 -235.218648)
		(end 134.852664 -235.294424)
		(width 0.088646)
		(layer "In6.Cu")
		(net "M_G_CPU1_SB_DQS_DP<6>")
	)
	(arc
		(start 132.97281 -235.294424)
		(mid 132.785612 -235.344567)
		(end 132.598414 -235.294424)
		(width 0.088646)
		(layer "In6.Cu")
		(net "M_G_CPU1_SB_DQS_DP<6>")
	)
	(arc
		(start 139.48791 -233.939334)
		(mid 139.455345 -233.969435)
		(end 139.4206 -233.996992)
		(width 0.088646)
		(layer "In6.Cu")
		(net "M_G_CPU1_SB_DQS_DP<6>")
	)
	(arc
		(start 138.135868 -234.484164)
		(mid 137.933281 -234.690515)
		(end 137.859262 -234.970066)
		(width 0.088646)
		(layer "In6.Cu")
		(net "M_G_CPU1_SB_DQS_DP<6>")
	)
	(arc
		(start 138.537188 -234.415838)
		(mid 138.342036 -234.410598)
		(end 138.156696 -234.471972)
		(width 0.088646)
		(layer "In6.Cu")
		(net "M_G_CPU1_SB_DQS_DP<6>")
	)
	(arc
		(start 133.912864 -235.294424)
		(mid 133.725666 -235.344567)
		(end 133.538468 -235.294424)
		(width 0.088646)
		(layer "In6.Cu")
		(net "M_G_CPU1_SB_DQS_DP<6>")
	)
	(arc
		(start 137.282682 -235.285788)
		(mid 137.006207 -235.218468)
		(end 136.73201 -235.294424)
		(width 0.088646)
		(layer "In6.Cu")
		(net "M_G_CPU1_SB_DQS_DP<6>")
	)
	(segment
		(start 195.522596 -226.64166)
		(end 197.535292 -226.64166)
		(width 0.1016)
		(layer "F.Cu")
		(net "M_G_CPU1_SB_DQS_DP<5>")
	)
	(segment
		(start 194.94119 -226.892866)
		(end 195.199508 -226.634548)
		(width 0.20066)
		(layer "F.Cu")
		(net "M_G_CPU1_SB_DQS_DP<5>")
	)
	(segment
		(start 193.933064 -227.317808)
		(end 194.237864 -227.317808)
		(width 0.20066)
		(layer "F.Cu")
		(net "M_G_CPU1_SB_DQS_DP<5>")
	)
	(segment
		(start 193.088514 -227.066602)
		(end 193.681858 -227.066602)
		(width 0.20066)
		(layer "F.Cu")
		(net "M_G_CPU1_SB_DQS_DP<5>")
	)
	(segment
		(start 195.510658 -226.634548)
		(end 195.515484 -226.634548)
		(width 0.101854)
		(layer "F.Cu")
		(net "M_G_CPU1_SB_DQS_DP<5>")
	)
	(segment
		(start 194.237864 -227.317808)
		(end 194.662806 -226.892866)
		(width 0.20066)
		(layer "F.Cu")
		(net "M_G_CPU1_SB_DQS_DP<5>")
	)
	(segment
		(start 198.119492 -226.88931)
		(end 198.773034 -226.88931)
		(width 0.20066)
		(layer "F.Cu")
		(net "M_G_CPU1_SB_DQS_DP<5>")
	)
	(segment
		(start 197.542658 -226.634294)
		(end 197.864476 -226.634294)
		(width 0.20066)
		(layer "F.Cu")
		(net "M_G_CPU1_SB_DQS_DP<5>")
	)
	(segment
		(start 128.086866 -240.389156)
		(end 128.086612 -240.388902)
		(width 0.20066)
		(layer "F.Cu")
		(net "M_G_CPU1_SB_DQS_DP<5>")
	)
	(segment
		(start 199.796146 -227.334826)
		(end 200.06437 -227.066602)
		(width 0.20066)
		(layer "F.Cu")
		(net "M_G_CPU1_SB_DQS_DP<5>")
	)
	(segment
		(start 191.983614 -227.066602)
		(end 193.088514 -227.066602)
		(width 0.20066)
		(layer "F.Cu")
		(net "M_G_CPU1_SB_DQS_DP<5>")
	)
	(segment
		(start 197.535292 -226.64166)
		(end 197.542658 -226.634294)
		(width 0.1016)
		(layer "F.Cu")
		(net "M_G_CPU1_SB_DQS_DP<5>")
	)
	(segment
		(start 195.515484 -226.634548)
		(end 195.522596 -226.64166)
		(width 0.1016)
		(layer "F.Cu")
		(net "M_G_CPU1_SB_DQS_DP<5>")
	)
	(segment
		(start 197.864476 -226.634294)
		(end 198.119492 -226.88931)
		(width 0.20066)
		(layer "F.Cu")
		(net "M_G_CPU1_SB_DQS_DP<5>")
	)
	(segment
		(start 195.199508 -226.634548)
		(end 195.510658 -226.634548)
		(width 0.20066)
		(layer "F.Cu")
		(net "M_G_CPU1_SB_DQS_DP<5>")
	)
	(segment
		(start 200.06437 -227.066602)
		(end 200.632314 -227.066602)
		(width 0.20066)
		(layer "F.Cu")
		(net "M_G_CPU1_SB_DQS_DP<5>")
	)
	(segment
		(start 198.773034 -226.88931)
		(end 199.21855 -227.334826)
		(width 0.20066)
		(layer "F.Cu")
		(net "M_G_CPU1_SB_DQS_DP<5>")
	)
	(segment
		(start 199.21855 -227.334826)
		(end 199.796146 -227.334826)
		(width 0.20066)
		(layer "F.Cu")
		(net "M_G_CPU1_SB_DQS_DP<5>")
	)
	(segment
		(start 194.662806 -226.892866)
		(end 194.94119 -226.892866)
		(width 0.20066)
		(layer "F.Cu")
		(net "M_G_CPU1_SB_DQS_DP<5>")
	)
	(segment
		(start 193.681858 -227.066602)
		(end 193.933064 -227.317808)
		(width 0.20066)
		(layer "F.Cu")
		(net "M_G_CPU1_SB_DQS_DP<5>")
	)
	(segment
		(start 128.086612 -240.388902)
		(end 128.086612 -239.853216)
		(width 0.20066)
		(layer "F.Cu")
		(net "M_G_CPU1_SB_DQS_DP<5>")
	)
	(segment
		(start 129.183638 -239.430306)
		(end 129.02946 -239.46104)
		(width 0.088646)
		(layer "In6.Cu")
		(net "M_G_CPU1_SB_DQS_DP<5>")
	)
	(segment
		(start 174.226728 -232.020618)
		(end 173.380654 -232.866692)
		(width 0.18288)
		(layer "In6.Cu")
		(net "M_G_CPU1_SB_DQS_DP<5>")
	)
	(segment
		(start 129.02946 -239.46104)
		(end 128.979676 -239.481614)
		(width 0.088646)
		(layer "In6.Cu")
		(net "M_G_CPU1_SB_DQS_DP<5>")
	)
	(segment
		(start 160.190942 -232.252012)
		(end 159.494982 -232.252012)
		(width 0.18288)
		(layer "In6.Cu")
		(net "M_G_CPU1_SB_DQS_DP<5>")
	)
	(segment
		(start 173.246542 -232.866692)
		(end 172.972476 -232.592626)
		(width 0.18288)
		(layer "In6.Cu")
		(net "M_G_CPU1_SB_DQS_DP<5>")
	)
	(segment
		(start 134.397496 -239.355122)
		(end 134.382764 -239.363758)
		(width 0.088646)
		(layer "In6.Cu")
		(net "M_G_CPU1_SB_DQS_DP<5>")
	)
	(segment
		(start 165.227254 -232.08488)
		(end 164.558726 -231.416606)
		(width 0.18288)
		(layer "In6.Cu")
		(net "M_G_CPU1_SB_DQS_DP<5>")
	)
	(segment
		(start 158.872682 -232.874312)
		(end 158.166054 -232.874312)
		(width 0.18288)
		(layer "In6.Cu")
		(net "M_G_CPU1_SB_DQS_DP<5>")
	)
	(segment
		(start 140.359638 -238.99622)
		(end 140.038328 -238.99622)
		(width 0.088646)
		(layer "In6.Cu")
		(net "M_G_CPU1_SB_DQS_DP<5>")
	)
	(segment
		(start 187.085732 -227.180902)
		(end 186.015884 -227.180902)
		(width 0.18288)
		(layer "In6.Cu")
		(net "M_G_CPU1_SB_DQS_DP<5>")
	)
	(segment
		(start 128.839214 -239.528858)
		(end 128.83769 -239.52962)
		(width 0.088646)
		(layer "In6.Cu")
		(net "M_G_CPU1_SB_DQS_DP<5>")
	)
	(segment
		(start 179.566824 -231.401366)
		(end 178.606704 -231.401366)
		(width 0.18288)
		(layer "In6.Cu")
		(net "M_G_CPU1_SB_DQS_DP<5>")
	)
	(segment
		(start 152.362916 -232.905046)
		(end 146.331432 -238.93653)
		(width 0.18288)
		(layer "In6.Cu")
		(net "M_G_CPU1_SB_DQS_DP<5>")
	)
	(segment
		(start 177.070004 -231.742488)
		(end 176.7205 -231.742488)
		(width 0.18288)
		(layer "In6.Cu")
		(net "M_G_CPU1_SB_DQS_DP<5>")
	)
	(segment
		(start 130.638296 -239.355122)
		(end 130.623564 -239.363758)
		(width 0.088646)
		(layer "In6.Cu")
		(net "M_G_CPU1_SB_DQS_DP<5>")
	)
	(segment
		(start 136.277096 -239.355122)
		(end 136.262364 -239.363758)
		(width 0.088646)
		(layer "In6.Cu")
		(net "M_G_CPU1_SB_DQS_DP<5>")
	)
	(segment
		(start 165.665912 -232.266998)
		(end 165.227254 -232.08488)
		(width 0.18288)
		(layer "In6.Cu")
		(net "M_G_CPU1_SB_DQS_DP<5>")
	)
	(segment
		(start 140.419328 -238.93653)
		(end 140.359638 -238.99622)
		(width 0.088646)
		(layer "In6.Cu")
		(net "M_G_CPU1_SB_DQS_DP<5>")
	)
	(segment
		(start 185.47842 -227.718366)
		(end 185.04408 -227.718366)
		(width 0.18288)
		(layer "In6.Cu")
		(net "M_G_CPU1_SB_DQS_DP<5>")
	)
	(segment
		(start 181.813708 -230.476298)
		(end 180.402484 -231.887522)
		(width 0.18288)
		(layer "In6.Cu")
		(net "M_G_CPU1_SB_DQS_DP<5>")
	)
	(segment
		(start 164.558726 -231.416606)
		(end 163.18865 -231.416606)
		(width 0.18288)
		(layer "In6.Cu")
		(net "M_G_CPU1_SB_DQS_DP<5>")
	)
	(segment
		(start 128.656334 -239.796066)
		(end 128.599184 -239.853216)
		(width 0.088646)
		(layer "In6.Cu")
		(net "M_G_CPU1_SB_DQS_DP<5>")
	)
	(segment
		(start 191.073278 -227.525834)
		(end 190.084456 -227.525834)
		(width 0.18288)
		(layer "In6.Cu")
		(net "M_G_CPU1_SB_DQS_DP<5>")
	)
	(segment
		(start 157.21711 -232.905046)
		(end 152.362916 -232.905046)
		(width 0.18288)
		(layer "In6.Cu")
		(net "M_G_CPU1_SB_DQS_DP<5>")
	)
	(segment
		(start 129.683764 -239.364012)
		(end 129.583688 -239.421924)
		(width 0.088646)
		(layer "In6.Cu")
		(net "M_G_CPU1_SB_DQS_DP<5>")
	)
	(segment
		(start 183.913018 -228.18598)
		(end 183.316372 -228.782626)
		(width 0.18288)
		(layer "In6.Cu")
		(net "M_G_CPU1_SB_DQS_DP<5>")
	)
	(segment
		(start 140.038328 -238.99622)
		(end 139.746482 -239.288066)
		(width 0.088646)
		(layer "In6.Cu")
		(net "M_G_CPU1_SB_DQS_DP<5>")
	)
	(segment
		(start 139.427204 -239.288066)
		(end 139.363958 -239.288066)
		(width 0.088646)
		(layer "In6.Cu")
		(net "M_G_CPU1_SB_DQS_DP<5>")
	)
	(segment
		(start 172.621956 -232.592626)
		(end 172.3517 -232.862882)
		(width 0.18288)
		(layer "In6.Cu")
		(net "M_G_CPU1_SB_DQS_DP<5>")
	)
	(segment
		(start 157.52953 -232.592626)
		(end 157.21711 -232.905046)
		(width 0.18288)
		(layer "In6.Cu")
		(net "M_G_CPU1_SB_DQS_DP<5>")
	)
	(segment
		(start 129.583688 -239.421924)
		(end 129.552446 -239.430306)
		(width 0.088646)
		(layer "In6.Cu")
		(net "M_G_CPU1_SB_DQS_DP<5>")
	)
	(segment
		(start 139.746482 -239.288066)
		(end 139.427712 -239.288066)
		(width 0.088646)
		(layer "In6.Cu")
		(net "M_G_CPU1_SB_DQS_DP<5>")
	)
	(segment
		(start 190.084456 -227.525834)
		(end 189.425072 -227.227384)
		(width 0.18288)
		(layer "In6.Cu")
		(net "M_G_CPU1_SB_DQS_DP<5>")
	)
	(segment
		(start 181.813708 -229.316534)
		(end 181.813708 -230.476298)
		(width 0.18288)
		(layer "In6.Cu")
		(net "M_G_CPU1_SB_DQS_DP<5>")
	)
	(segment
		(start 168.931082 -232.862882)
		(end 168.335198 -232.266998)
		(width 0.18288)
		(layer "In6.Cu")
		(net "M_G_CPU1_SB_DQS_DP<5>")
	)
	(segment
		(start 128.599184 -239.853216)
		(end 128.086612 -239.853216)
		(width 0.088646)
		(layer "In6.Cu")
		(net "M_G_CPU1_SB_DQS_DP<5>")
	)
	(segment
		(start 191.713612 -227.336604)
		(end 191.531748 -227.336604)
		(width 0.18288)
		(layer "In6.Cu")
		(net "M_G_CPU1_SB_DQS_DP<5>")
	)
	(segment
		(start 188.15304 -226.642422)
		(end 187.624212 -226.642422)
		(width 0.18288)
		(layer "In6.Cu")
		(net "M_G_CPU1_SB_DQS_DP<5>")
	)
	(segment
		(start 140.442696 -238.93653)
		(end 140.419328 -238.93653)
		(width 0.088646)
		(layer "In6.Cu")
		(net "M_G_CPU1_SB_DQS_DP<5>")
	)
	(segment
		(start 185.04408 -227.718366)
		(end 183.913018 -228.18598)
		(width 0.18288)
		(layer "In6.Cu")
		(net "M_G_CPU1_SB_DQS_DP<5>")
	)
	(segment
		(start 138.156696 -239.355122)
		(end 138.141964 -239.363758)
		(width 0.088646)
		(layer "In6.Cu")
		(net "M_G_CPU1_SB_DQS_DP<5>")
	)
	(segment
		(start 178.606704 -231.401366)
		(end 177.994564 -232.013506)
		(width 0.18288)
		(layer "In6.Cu")
		(net "M_G_CPU1_SB_DQS_DP<5>")
	)
	(segment
		(start 132.517896 -239.355122)
		(end 132.503164 -239.363758)
		(width 0.088646)
		(layer "In6.Cu")
		(net "M_G_CPU1_SB_DQS_DP<5>")
	)
	(segment
		(start 172.3517 -232.862882)
		(end 168.931082 -232.862882)
		(width 0.18288)
		(layer "In6.Cu")
		(net "M_G_CPU1_SB_DQS_DP<5>")
	)
	(segment
		(start 191.531748 -227.336604)
		(end 191.073278 -227.525834)
		(width 0.18288)
		(layer "In6.Cu")
		(net "M_G_CPU1_SB_DQS_DP<5>")
	)
	(segment
		(start 130.249168 -239.363758)
		(end 130.24866 -239.364012)
		(width 0.088646)
		(layer "In6.Cu")
		(net "M_G_CPU1_SB_DQS_DP<5>")
	)
	(segment
		(start 188.620146 -226.894136)
		(end 188.404754 -226.894136)
		(width 0.18288)
		(layer "In6.Cu")
		(net "M_G_CPU1_SB_DQS_DP<5>")
	)
	(segment
		(start 158.166054 -232.874312)
		(end 157.884368 -232.592626)
		(width 0.18288)
		(layer "In6.Cu")
		(net "M_G_CPU1_SB_DQS_DP<5>")
	)
	(segment
		(start 183.316372 -228.782626)
		(end 182.347616 -228.782626)
		(width 0.18288)
		(layer "In6.Cu")
		(net "M_G_CPU1_SB_DQS_DP<5>")
	)
	(segment
		(start 176.7205 -231.742488)
		(end 176.44237 -232.020618)
		(width 0.18288)
		(layer "In6.Cu")
		(net "M_G_CPU1_SB_DQS_DP<5>")
	)
	(segment
		(start 157.884368 -232.592626)
		(end 157.52953 -232.592626)
		(width 0.18288)
		(layer "In6.Cu")
		(net "M_G_CPU1_SB_DQS_DP<5>")
	)
	(segment
		(start 180.402484 -231.887522)
		(end 180.05298 -231.887522)
		(width 0.18288)
		(layer "In6.Cu")
		(net "M_G_CPU1_SB_DQS_DP<5>")
	)
	(segment
		(start 160.692592 -232.753662)
		(end 160.190942 -232.252012)
		(width 0.18288)
		(layer "In6.Cu")
		(net "M_G_CPU1_SB_DQS_DP<5>")
	)
	(segment
		(start 173.380654 -232.866692)
		(end 173.246542 -232.866692)
		(width 0.18288)
		(layer "In6.Cu")
		(net "M_G_CPU1_SB_DQS_DP<5>")
	)
	(segment
		(start 139.427458 -239.287812)
		(end 139.427204 -239.288066)
		(width 0.088646)
		(layer "In6.Cu")
		(net "M_G_CPU1_SB_DQS_DP<5>")
	)
	(segment
		(start 180.05298 -231.887522)
		(end 179.566824 -231.401366)
		(width 0.18288)
		(layer "In6.Cu")
		(net "M_G_CPU1_SB_DQS_DP<5>")
	)
	(segment
		(start 189.425072 -227.227384)
		(end 188.620146 -226.894136)
		(width 0.18288)
		(layer "In6.Cu")
		(net "M_G_CPU1_SB_DQS_DP<5>")
	)
	(segment
		(start 168.335198 -232.266998)
		(end 165.665912 -232.266998)
		(width 0.18288)
		(layer "In6.Cu")
		(net "M_G_CPU1_SB_DQS_DP<5>")
	)
	(segment
		(start 128.83769 -239.52962)
		(end 128.830324 -239.533938)
		(width 0.088646)
		(layer "In6.Cu")
		(net "M_G_CPU1_SB_DQS_DP<5>")
	)
	(segment
		(start 177.341022 -232.013506)
		(end 177.070004 -231.742488)
		(width 0.18288)
		(layer "In6.Cu")
		(net "M_G_CPU1_SB_DQS_DP<5>")
	)
	(segment
		(start 186.015884 -227.180902)
		(end 185.47842 -227.718366)
		(width 0.18288)
		(layer "In6.Cu")
		(net "M_G_CPU1_SB_DQS_DP<5>")
	)
	(segment
		(start 177.994564 -232.013506)
		(end 177.341022 -232.013506)
		(width 0.18288)
		(layer "In6.Cu")
		(net "M_G_CPU1_SB_DQS_DP<5>")
	)
	(segment
		(start 161.851594 -232.753662)
		(end 160.692592 -232.753662)
		(width 0.18288)
		(layer "In6.Cu")
		(net "M_G_CPU1_SB_DQS_DP<5>")
	)
	(segment
		(start 187.624212 -226.642422)
		(end 187.085732 -227.180902)
		(width 0.18288)
		(layer "In6.Cu")
		(net "M_G_CPU1_SB_DQS_DP<5>")
	)
	(segment
		(start 163.18865 -231.416606)
		(end 161.851594 -232.753662)
		(width 0.18288)
		(layer "In6.Cu")
		(net "M_G_CPU1_SB_DQS_DP<5>")
	)
	(segment
		(start 172.972476 -232.592626)
		(end 172.621956 -232.592626)
		(width 0.18288)
		(layer "In6.Cu")
		(net "M_G_CPU1_SB_DQS_DP<5>")
	)
	(segment
		(start 176.44237 -232.020618)
		(end 174.226728 -232.020618)
		(width 0.18288)
		(layer "In6.Cu")
		(net "M_G_CPU1_SB_DQS_DP<5>")
	)
	(segment
		(start 137.216896 -239.355122)
		(end 137.202164 -239.363758)
		(width 0.088646)
		(layer "In6.Cu")
		(net "M_G_CPU1_SB_DQS_DP<5>")
	)
	(segment
		(start 129.552446 -239.430306)
		(end 129.183638 -239.430306)
		(width 0.088646)
		(layer "In6.Cu")
		(net "M_G_CPU1_SB_DQS_DP<5>")
	)
	(segment
		(start 182.347616 -228.782626)
		(end 181.813708 -229.316534)
		(width 0.18288)
		(layer "In6.Cu")
		(net "M_G_CPU1_SB_DQS_DP<5>")
	)
	(segment
		(start 188.404754 -226.894136)
		(end 188.15304 -226.642422)
		(width 0.18288)
		(layer "In6.Cu")
		(net "M_G_CPU1_SB_DQS_DP<5>")
	)
	(segment
		(start 159.494982 -232.252012)
		(end 158.872682 -232.874312)
		(width 0.18288)
		(layer "In6.Cu")
		(net "M_G_CPU1_SB_DQS_DP<5>")
	)
	(segment
		(start 139.427712 -239.288066)
		(end 139.427458 -239.287812)
		(width 0.088646)
		(layer "In6.Cu")
		(net "M_G_CPU1_SB_DQS_DP<5>")
	)
	(segment
		(start 146.331432 -238.93653)
		(end 140.442696 -238.93653)
		(width 0.18288)
		(layer "In6.Cu")
		(net "M_G_CPU1_SB_DQS_DP<5>")
	)
	(segment
		(start 191.983614 -227.066602)
		(end 191.713612 -227.336604)
		(width 0.18288)
		(layer "In6.Cu")
		(net "M_G_CPU1_SB_DQS_DP<5>")
	)
	(arc
		(start 132.128768 -239.363758)
		(mid 131.846066 -239.287982)
		(end 131.563364 -239.363758)
		(width 0.088646)
		(layer "In6.Cu")
		(net "M_G_CPU1_SB_DQS_DP<5>")
	)
	(arc
		(start 136.827768 -239.363758)
		(mid 136.553569 -239.287923)
		(end 136.277096 -239.355122)
		(width 0.088646)
		(layer "In6.Cu")
		(net "M_G_CPU1_SB_DQS_DP<5>")
	)
	(arc
		(start 138.141964 -239.363758)
		(mid 137.954766 -239.413901)
		(end 137.767568 -239.363758)
		(width 0.088646)
		(layer "In6.Cu")
		(net "M_G_CPU1_SB_DQS_DP<5>")
	)
	(arc
		(start 133.442964 -239.363758)
		(mid 133.255766 -239.413901)
		(end 133.068568 -239.363758)
		(width 0.088646)
		(layer "In6.Cu")
		(net "M_G_CPU1_SB_DQS_DP<5>")
	)
	(arc
		(start 135.887968 -239.363758)
		(mid 135.605266 -239.287982)
		(end 135.322564 -239.363758)
		(width 0.088646)
		(layer "In6.Cu")
		(net "M_G_CPU1_SB_DQS_DP<5>")
	)
	(arc
		(start 131.563364 -239.363758)
		(mid 131.376166 -239.413901)
		(end 131.188968 -239.363758)
		(width 0.088646)
		(layer "In6.Cu")
		(net "M_G_CPU1_SB_DQS_DP<5>")
	)
	(arc
		(start 139.081764 -239.363758)
		(mid 138.894566 -239.413901)
		(end 138.707368 -239.363758)
		(width 0.088646)
		(layer "In6.Cu")
		(net "M_G_CPU1_SB_DQS_DP<5>")
	)
	(arc
		(start 133.068568 -239.363758)
		(mid 132.794369 -239.287923)
		(end 132.517896 -239.355122)
		(width 0.088646)
		(layer "In6.Cu")
		(net "M_G_CPU1_SB_DQS_DP<5>")
	)
	(arc
		(start 138.707368 -239.363758)
		(mid 138.433169 -239.287923)
		(end 138.156696 -239.355122)
		(width 0.088646)
		(layer "In6.Cu")
		(net "M_G_CPU1_SB_DQS_DP<5>")
	)
	(arc
		(start 135.322564 -239.363758)
		(mid 135.135366 -239.413901)
		(end 134.948168 -239.363758)
		(width 0.088646)
		(layer "In6.Cu")
		(net "M_G_CPU1_SB_DQS_DP<5>")
	)
	(arc
		(start 137.202164 -239.363758)
		(mid 137.014966 -239.413901)
		(end 136.827768 -239.363758)
		(width 0.088646)
		(layer "In6.Cu")
		(net "M_G_CPU1_SB_DQS_DP<5>")
	)
	(arc
		(start 131.188968 -239.363758)
		(mid 130.914769 -239.287923)
		(end 130.638296 -239.355122)
		(width 0.088646)
		(layer "In6.Cu")
		(net "M_G_CPU1_SB_DQS_DP<5>")
	)
	(arc
		(start 137.767568 -239.363758)
		(mid 137.493369 -239.287923)
		(end 137.216896 -239.355122)
		(width 0.088646)
		(layer "In6.Cu")
		(net "M_G_CPU1_SB_DQS_DP<5>")
	)
	(arc
		(start 134.948168 -239.363758)
		(mid 134.673969 -239.287923)
		(end 134.397496 -239.355122)
		(width 0.088646)
		(layer "In6.Cu")
		(net "M_G_CPU1_SB_DQS_DP<5>")
	)
	(arc
		(start 128.979676 -239.481614)
		(mid 128.907079 -239.498206)
		(end 128.839214 -239.528858)
		(width 0.088646)
		(layer "In6.Cu")
		(net "M_G_CPU1_SB_DQS_DP<5>")
	)
	(arc
		(start 134.382764 -239.363758)
		(mid 134.195566 -239.413901)
		(end 134.008368 -239.363758)
		(width 0.088646)
		(layer "In6.Cu")
		(net "M_G_CPU1_SB_DQS_DP<5>")
	)
	(arc
		(start 128.830324 -239.533938)
		(mid 128.714515 -239.645867)
		(end 128.656334 -239.796066)
		(width 0.088646)
		(layer "In6.Cu")
		(net "M_G_CPU1_SB_DQS_DP<5>")
	)
	(arc
		(start 134.008368 -239.363758)
		(mid 133.725666 -239.287982)
		(end 133.442964 -239.363758)
		(width 0.088646)
		(layer "In6.Cu")
		(net "M_G_CPU1_SB_DQS_DP<5>")
	)
	(arc
		(start 139.363958 -239.288066)
		(mid 139.217877 -239.30734)
		(end 139.081764 -239.363758)
		(width 0.088646)
		(layer "In6.Cu")
		(net "M_G_CPU1_SB_DQS_DP<5>")
	)
	(arc
		(start 136.262364 -239.363758)
		(mid 136.075166 -239.413901)
		(end 135.887968 -239.363758)
		(width 0.088646)
		(layer "In6.Cu")
		(net "M_G_CPU1_SB_DQS_DP<5>")
	)
	(arc
		(start 130.24866 -239.364012)
		(mid 129.966212 -239.288329)
		(end 129.683764 -239.364012)
		(width 0.088646)
		(layer "In6.Cu")
		(net "M_G_CPU1_SB_DQS_DP<5>")
	)
	(arc
		(start 132.503164 -239.363758)
		(mid 132.315966 -239.413901)
		(end 132.128768 -239.363758)
		(width 0.088646)
		(layer "In6.Cu")
		(net "M_G_CPU1_SB_DQS_DP<5>")
	)
	(arc
		(start 130.623564 -239.363758)
		(mid 130.436366 -239.413901)
		(end 130.249168 -239.363758)
		(width 0.088646)
		(layer "In6.Cu")
		(net "M_G_CPU1_SB_DQS_DP<5>")
	)
	(segment
		(start 197.721474 -235.991654)
		(end 197.871842 -235.991654)
		(width 0.20066)
		(layer "F.Cu")
		(net "M_G_CPU1_SB_DQS_DP<4>")
	)
	(segment
		(start 193.933064 -236.667802)
		(end 194.237864 -236.667802)
		(width 0.20066)
		(layer "F.Cu")
		(net "M_G_CPU1_SB_DQS_DP<4>")
	)
	(segment
		(start 195.180966 -235.991654)
		(end 195.288916 -235.991654)
		(width 0.20066)
		(layer "F.Cu")
		(net "M_G_CPU1_SB_DQS_DP<4>")
	)
	(segment
		(start 195.288916 -235.991654)
		(end 195.522596 -235.991654)
		(width 0.101854)
		(layer "F.Cu")
		(net "M_G_CPU1_SB_DQS_DP<4>")
	)
	(segment
		(start 197.871842 -235.991654)
		(end 198.119492 -236.239304)
		(width 0.20066)
		(layer "F.Cu")
		(net "M_G_CPU1_SB_DQS_DP<4>")
	)
	(segment
		(start 193.088514 -236.416596)
		(end 193.681858 -236.416596)
		(width 0.20066)
		(layer "F.Cu")
		(net "M_G_CPU1_SB_DQS_DP<4>")
	)
	(segment
		(start 194.662806 -236.24286)
		(end 194.92976 -236.24286)
		(width 0.20066)
		(layer "F.Cu")
		(net "M_G_CPU1_SB_DQS_DP<4>")
	)
	(segment
		(start 194.92976 -236.24286)
		(end 195.180966 -235.991654)
		(width 0.20066)
		(layer "F.Cu")
		(net "M_G_CPU1_SB_DQS_DP<4>")
	)
	(segment
		(start 199.21855 -236.68482)
		(end 199.796146 -236.68482)
		(width 0.20066)
		(layer "F.Cu")
		(net "M_G_CPU1_SB_DQS_DP<4>")
	)
	(segment
		(start 195.522596 -235.991654)
		(end 197.535292 -235.991654)
		(width 0.1016)
		(layer "F.Cu")
		(net "M_G_CPU1_SB_DQS_DP<4>")
	)
	(segment
		(start 194.237864 -236.667802)
		(end 194.662806 -236.24286)
		(width 0.20066)
		(layer "F.Cu")
		(net "M_G_CPU1_SB_DQS_DP<4>")
	)
	(segment
		(start 200.06437 -236.416596)
		(end 200.632314 -236.416596)
		(width 0.20066)
		(layer "F.Cu")
		(net "M_G_CPU1_SB_DQS_DP<4>")
	)
	(segment
		(start 198.773034 -236.239304)
		(end 199.21855 -236.68482)
		(width 0.20066)
		(layer "F.Cu")
		(net "M_G_CPU1_SB_DQS_DP<4>")
	)
	(segment
		(start 197.535292 -235.991654)
		(end 197.721474 -235.991654)
		(width 0.101854)
		(layer "F.Cu")
		(net "M_G_CPU1_SB_DQS_DP<4>")
	)
	(segment
		(start 191.983614 -236.416596)
		(end 193.088514 -236.416596)
		(width 0.20066)
		(layer "F.Cu")
		(net "M_G_CPU1_SB_DQS_DP<4>")
	)
	(segment
		(start 193.681858 -236.416596)
		(end 193.933064 -236.667802)
		(width 0.20066)
		(layer "F.Cu")
		(net "M_G_CPU1_SB_DQS_DP<4>")
	)
	(segment
		(start 131.375912 -242.830858)
		(end 131.376166 -242.830604)
		(width 0.20066)
		(layer "F.Cu")
		(net "M_G_CPU1_SB_DQS_DP<4>")
	)
	(segment
		(start 199.796146 -236.68482)
		(end 200.06437 -236.416596)
		(width 0.20066)
		(layer "F.Cu")
		(net "M_G_CPU1_SB_DQS_DP<4>")
	)
	(segment
		(start 198.119492 -236.239304)
		(end 198.773034 -236.239304)
		(width 0.20066)
		(layer "F.Cu")
		(net "M_G_CPU1_SB_DQS_DP<4>")
	)
	(segment
		(start 131.376166 -242.830604)
		(end 131.376166 -242.294918)
		(width 0.20066)
		(layer "F.Cu")
		(net "M_G_CPU1_SB_DQS_DP<4>")
	)
	(segment
		(start 132.97281 -241.80546)
		(end 132.973064 -241.805714)
		(width 0.088646)
		(layer "In4.Cu")
		(net "M_G_CPU1_SB_DQS_DP<4>")
	)
	(segment
		(start 172.584872 -235.992416)
		(end 172.334936 -236.242352)
		(width 0.18288)
		(layer "In4.Cu")
		(net "M_G_CPU1_SB_DQS_DP<4>")
	)
	(segment
		(start 179.314602 -236.041946)
		(end 178.78679 -236.041946)
		(width 0.18288)
		(layer "In4.Cu")
		(net "M_G_CPU1_SB_DQS_DP<4>")
	)
	(segment
		(start 191.983614 -236.416596)
		(end 191.72555 -236.67466)
		(width 0.18288)
		(layer "In4.Cu")
		(net "M_G_CPU1_SB_DQS_DP<4>")
	)
	(segment
		(start 188.33592 -236.250988)
		(end 188.077348 -235.992416)
		(width 0.18288)
		(layer "In4.Cu")
		(net "M_G_CPU1_SB_DQS_DP<4>")
	)
	(segment
		(start 160.794446 -236.572806)
		(end 160.235646 -237.131606)
		(width 0.18288)
		(layer "In4.Cu")
		(net "M_G_CPU1_SB_DQS_DP<4>")
	)
	(segment
		(start 131.945888 -242.237768)
		(end 131.888738 -242.294918)
		(width 0.088646)
		(layer "In4.Cu")
		(net "M_G_CPU1_SB_DQS_DP<4>")
	)
	(segment
		(start 183.066182 -235.410248)
		(end 179.9463 -235.410248)
		(width 0.18288)
		(layer "In4.Cu")
		(net "M_G_CPU1_SB_DQS_DP<4>")
	)
	(segment
		(start 135.418068 -241.80546)
		(end 135.41756 -241.805714)
		(width 0.088646)
		(layer "In4.Cu")
		(net "M_G_CPU1_SB_DQS_DP<4>")
	)
	(segment
		(start 139.558014 -241.729514)
		(end 138.894566 -241.729514)
		(width 0.088646)
		(layer "In4.Cu")
		(net "M_G_CPU1_SB_DQS_DP<4>")
	)
	(segment
		(start 187.396374 -236.268514)
		(end 187.18276 -236.268514)
		(width 0.18288)
		(layer "In4.Cu")
		(net "M_G_CPU1_SB_DQS_DP<4>")
	)
	(segment
		(start 136.732518 -241.80546)
		(end 136.732264 -241.80546)
		(width 0.088646)
		(layer "In4.Cu")
		(net "M_G_CPU1_SB_DQS_DP<4>")
	)
	(segment
		(start 174.35576 -236.250988)
		(end 173.24832 -236.250988)
		(width 0.18288)
		(layer "In4.Cu")
		(net "M_G_CPU1_SB_DQS_DP<4>")
	)
	(segment
		(start 134.49046 -241.81308)
		(end 134.478522 -241.805968)
		(width 0.088646)
		(layer "In4.Cu")
		(net "M_G_CPU1_SB_DQS_DP<4>")
	)
	(segment
		(start 152.03551 -237.539276)
		(end 150.800816 -238.774224)
		(width 0.18288)
		(layer "In4.Cu")
		(net "M_G_CPU1_SB_DQS_DP<4>")
	)
	(segment
		(start 176.68494 -235.142532)
		(end 176.449482 -235.37799)
		(width 0.18288)
		(layer "In4.Cu")
		(net "M_G_CPU1_SB_DQS_DP<4>")
	)
	(segment
		(start 172.334936 -236.242352)
		(end 171.4754 -236.242352)
		(width 0.18288)
		(layer "In4.Cu")
		(net "M_G_CPU1_SB_DQS_DP<4>")
	)
	(segment
		(start 187.672472 -235.992416)
		(end 187.396374 -236.268514)
		(width 0.18288)
		(layer "In4.Cu")
		(net "M_G_CPU1_SB_DQS_DP<4>")
	)
	(segment
		(start 139.817094 -241.470434)
		(end 139.558014 -241.729514)
		(width 0.088646)
		(layer "In4.Cu")
		(net "M_G_CPU1_SB_DQS_DP<4>")
	)
	(segment
		(start 140.315696 -241.410744)
		(end 140.292328 -241.410744)
		(width 0.088646)
		(layer "In4.Cu")
		(net "M_G_CPU1_SB_DQS_DP<4>")
	)
	(segment
		(start 132.128768 -241.97056)
		(end 132.119878 -241.97564)
		(width 0.088646)
		(layer "In4.Cu")
		(net "M_G_CPU1_SB_DQS_DP<4>")
	)
	(segment
		(start 187.18276 -236.268514)
		(end 186.981592 -236.067346)
		(width 0.18288)
		(layer "In4.Cu")
		(net "M_G_CPU1_SB_DQS_DP<4>")
	)
	(segment
		(start 177.357278 -235.409994)
		(end 177.089816 -235.142532)
		(width 0.18288)
		(layer "In4.Cu")
		(net "M_G_CPU1_SB_DQS_DP<4>")
	)
	(segment
		(start 175.228758 -235.37799)
		(end 174.35576 -236.250988)
		(width 0.18288)
		(layer "In4.Cu")
		(net "M_G_CPU1_SB_DQS_DP<4>")
	)
	(segment
		(start 173.24832 -236.250988)
		(end 172.989748 -235.992416)
		(width 0.18288)
		(layer "In4.Cu")
		(net "M_G_CPU1_SB_DQS_DP<4>")
	)
	(segment
		(start 137.297668 -241.80546)
		(end 137.297414 -241.80546)
		(width 0.088646)
		(layer "In4.Cu")
		(net "M_G_CPU1_SB_DQS_DP<4>")
	)
	(segment
		(start 134.85749 -241.80292)
		(end 134.852156 -241.805968)
		(width 0.088646)
		(layer "In4.Cu")
		(net "M_G_CPU1_SB_DQS_DP<4>")
	)
	(segment
		(start 153.020268 -237.131606)
		(end 152.03551 -237.539276)
		(width 0.18288)
		(layer "In4.Cu")
		(net "M_G_CPU1_SB_DQS_DP<4>")
	)
	(segment
		(start 191.189102 -236.67466)
		(end 190.893954 -236.969808)
		(width 0.18288)
		(layer "In4.Cu")
		(net "M_G_CPU1_SB_DQS_DP<4>")
	)
	(segment
		(start 189.021466 -236.250988)
		(end 188.33592 -236.250988)
		(width 0.18288)
		(layer "In4.Cu")
		(net "M_G_CPU1_SB_DQS_DP<4>")
	)
	(segment
		(start 132.863336 -241.86896)
		(end 132.756656 -241.897662)
		(width 0.088646)
		(layer "In4.Cu")
		(net "M_G_CPU1_SB_DQS_DP<4>")
	)
	(segment
		(start 178.78679 -236.041946)
		(end 178.154838 -235.409994)
		(width 0.18288)
		(layer "In4.Cu")
		(net "M_G_CPU1_SB_DQS_DP<4>")
	)
	(segment
		(start 131.888738 -242.294918)
		(end 131.376166 -242.294918)
		(width 0.088646)
		(layer "In4.Cu")
		(net "M_G_CPU1_SB_DQS_DP<4>")
	)
	(segment
		(start 132.756656 -241.897662)
		(end 132.322062 -241.897662)
		(width 0.088646)
		(layer "In4.Cu")
		(net "M_G_CPU1_SB_DQS_DP<4>")
	)
	(segment
		(start 172.989748 -235.992416)
		(end 172.584872 -235.992416)
		(width 0.18288)
		(layer "In4.Cu")
		(net "M_G_CPU1_SB_DQS_DP<4>")
	)
	(segment
		(start 140.232638 -241.470434)
		(end 139.817094 -241.470434)
		(width 0.088646)
		(layer "In4.Cu")
		(net "M_G_CPU1_SB_DQS_DP<4>")
	)
	(segment
		(start 188.077348 -235.992416)
		(end 187.672472 -235.992416)
		(width 0.18288)
		(layer "In4.Cu")
		(net "M_G_CPU1_SB_DQS_DP<4>")
	)
	(segment
		(start 140.292328 -241.410744)
		(end 140.232638 -241.470434)
		(width 0.088646)
		(layer "In4.Cu")
		(net "M_G_CPU1_SB_DQS_DP<4>")
	)
	(segment
		(start 133.538468 -241.80546)
		(end 133.528054 -241.799364)
		(width 0.088646)
		(layer "In4.Cu")
		(net "M_G_CPU1_SB_DQS_DP<4>")
	)
	(segment
		(start 144.09293 -241.178334)
		(end 143.532352 -241.410744)
		(width 0.18288)
		(layer "In4.Cu")
		(net "M_G_CPU1_SB_DQS_DP<4>")
	)
	(segment
		(start 186.981592 -236.067346)
		(end 183.72328 -236.067346)
		(width 0.18288)
		(layer "In4.Cu")
		(net "M_G_CPU1_SB_DQS_DP<4>")
	)
	(segment
		(start 164.224462 -236.572806)
		(end 160.794446 -236.572806)
		(width 0.18288)
		(layer "In4.Cu")
		(net "M_G_CPU1_SB_DQS_DP<4>")
	)
	(segment
		(start 132.973064 -241.805714)
		(end 132.863336 -241.86896)
		(width 0.088646)
		(layer "In4.Cu")
		(net "M_G_CPU1_SB_DQS_DP<4>")
	)
	(segment
		(start 150.800816 -238.774224)
		(end 146.49704 -238.774224)
		(width 0.18288)
		(layer "In4.Cu")
		(net "M_G_CPU1_SB_DQS_DP<4>")
	)
	(segment
		(start 178.154838 -235.409994)
		(end 177.357278 -235.409994)
		(width 0.18288)
		(layer "In4.Cu")
		(net "M_G_CPU1_SB_DQS_DP<4>")
	)
	(segment
		(start 160.235646 -237.131606)
		(end 153.020268 -237.131606)
		(width 0.18288)
		(layer "In4.Cu")
		(net "M_G_CPU1_SB_DQS_DP<4>")
	)
	(segment
		(start 146.49704 -238.774224)
		(end 144.09293 -241.178334)
		(width 0.18288)
		(layer "In4.Cu")
		(net "M_G_CPU1_SB_DQS_DP<4>")
	)
	(segment
		(start 179.9463 -235.410248)
		(end 179.314602 -236.041946)
		(width 0.18288)
		(layer "In4.Cu")
		(net "M_G_CPU1_SB_DQS_DP<4>")
	)
	(segment
		(start 190.893954 -236.969808)
		(end 189.740286 -236.969808)
		(width 0.18288)
		(layer "In4.Cu")
		(net "M_G_CPU1_SB_DQS_DP<4>")
	)
	(segment
		(start 171.4754 -236.242352)
		(end 169.88028 -236.903006)
		(width 0.18288)
		(layer "In4.Cu")
		(net "M_G_CPU1_SB_DQS_DP<4>")
	)
	(segment
		(start 189.740286 -236.969808)
		(end 189.021466 -236.250988)
		(width 0.18288)
		(layer "In4.Cu")
		(net "M_G_CPU1_SB_DQS_DP<4>")
	)
	(segment
		(start 143.532352 -241.410744)
		(end 140.315696 -241.410744)
		(width 0.18288)
		(layer "In4.Cu")
		(net "M_G_CPU1_SB_DQS_DP<4>")
	)
	(segment
		(start 169.88028 -236.903006)
		(end 165.021768 -236.903006)
		(width 0.18288)
		(layer "In4.Cu")
		(net "M_G_CPU1_SB_DQS_DP<4>")
	)
	(segment
		(start 177.089816 -235.142532)
		(end 176.68494 -235.142532)
		(width 0.18288)
		(layer "In4.Cu")
		(net "M_G_CPU1_SB_DQS_DP<4>")
	)
	(segment
		(start 183.72328 -236.067346)
		(end 183.066182 -235.410248)
		(width 0.18288)
		(layer "In4.Cu")
		(net "M_G_CPU1_SB_DQS_DP<4>")
	)
	(segment
		(start 191.72555 -236.67466)
		(end 191.189102 -236.67466)
		(width 0.18288)
		(layer "In4.Cu")
		(net "M_G_CPU1_SB_DQS_DP<4>")
	)
	(segment
		(start 165.021768 -236.903006)
		(end 164.224462 -236.572806)
		(width 0.18288)
		(layer "In4.Cu")
		(net "M_G_CPU1_SB_DQS_DP<4>")
	)
	(segment
		(start 176.449482 -235.37799)
		(end 175.228758 -235.37799)
		(width 0.18288)
		(layer "In4.Cu")
		(net "M_G_CPU1_SB_DQS_DP<4>")
	)
	(arc
		(start 137.297414 -241.80546)
		(mid 137.014966 -241.729811)
		(end 136.732518 -241.80546)
		(width 0.088646)
		(layer "In4.Cu")
		(net "M_G_CPU1_SB_DQS_DP<4>")
	)
	(arc
		(start 138.845544 -241.731546)
		(mid 138.72464 -241.755665)
		(end 138.611864 -241.80546)
		(width 0.088646)
		(layer "In4.Cu")
		(net "M_G_CPU1_SB_DQS_DP<4>")
	)
	(arc
		(start 133.913372 -241.805714)
		(mid 133.912981 -241.805792)
		(end 133.912864 -241.80546)
		(width 0.088646)
		(layer "In4.Cu")
		(net "M_G_CPU1_SB_DQS_DP<4>")
	)
	(arc
		(start 132.322062 -241.897662)
		(mid 132.273948 -241.904018)
		(end 132.229098 -241.922554)
		(width 0.088646)
		(layer "In4.Cu")
		(net "M_G_CPU1_SB_DQS_DP<4>")
	)
	(arc
		(start 135.41756 -241.805714)
		(mid 135.1379 -241.730038)
		(end 134.85749 -241.80292)
		(width 0.088646)
		(layer "In4.Cu")
		(net "M_G_CPU1_SB_DQS_DP<4>")
	)
	(arc
		(start 134.478522 -241.805968)
		(mid 134.195993 -241.730124)
		(end 133.913372 -241.805714)
		(width 0.088646)
		(layer "In4.Cu")
		(net "M_G_CPU1_SB_DQS_DP<4>")
	)
	(arc
		(start 132.119878 -241.97564)
		(mid 132.004069 -242.087569)
		(end 131.945888 -242.237768)
		(width 0.088646)
		(layer "In4.Cu")
		(net "M_G_CPU1_SB_DQS_DP<4>")
	)
	(arc
		(start 137.672064 -241.80546)
		(mid 137.484866 -241.855603)
		(end 137.297668 -241.80546)
		(width 0.088646)
		(layer "In4.Cu")
		(net "M_G_CPU1_SB_DQS_DP<4>")
	)
	(arc
		(start 136.732264 -241.80546)
		(mid 136.545066 -241.855603)
		(end 136.357868 -241.80546)
		(width 0.088646)
		(layer "In4.Cu")
		(net "M_G_CPU1_SB_DQS_DP<4>")
	)
	(arc
		(start 133.528054 -241.799364)
		(mid 133.249622 -241.729518)
		(end 132.97281 -241.80546)
		(width 0.088646)
		(layer "In4.Cu")
		(net "M_G_CPU1_SB_DQS_DP<4>")
	)
	(arc
		(start 136.357868 -241.80546)
		(mid 136.075166 -241.729684)
		(end 135.792464 -241.80546)
		(width 0.088646)
		(layer "In4.Cu")
		(net "M_G_CPU1_SB_DQS_DP<4>")
	)
	(arc
		(start 138.894566 -241.729514)
		(mid 138.870033 -241.730002)
		(end 138.845544 -241.731546)
		(width 0.088646)
		(layer "In4.Cu")
		(net "M_G_CPU1_SB_DQS_DP<4>")
	)
	(arc
		(start 134.852156 -241.805968)
		(mid 134.672235 -241.855973)
		(end 134.49046 -241.81308)
		(width 0.088646)
		(layer "In4.Cu")
		(net "M_G_CPU1_SB_DQS_DP<4>")
	)
	(arc
		(start 132.229098 -241.922554)
		(mid 132.204393 -241.935421)
		(end 132.178806 -241.94643)
		(width 0.088646)
		(layer "In4.Cu")
		(net "M_G_CPU1_SB_DQS_DP<4>")
	)
	(arc
		(start 138.611864 -241.80546)
		(mid 138.424666 -241.855603)
		(end 138.237468 -241.80546)
		(width 0.088646)
		(layer "In4.Cu")
		(net "M_G_CPU1_SB_DQS_DP<4>")
	)
	(arc
		(start 133.912864 -241.80546)
		(mid 133.725666 -241.855603)
		(end 133.538468 -241.80546)
		(width 0.088646)
		(layer "In4.Cu")
		(net "M_G_CPU1_SB_DQS_DP<4>")
	)
	(arc
		(start 132.178806 -241.94643)
		(mid 132.153337 -241.957563)
		(end 132.128768 -241.97056)
		(width 0.088646)
		(layer "In4.Cu")
		(net "M_G_CPU1_SB_DQS_DP<4>")
	)
	(arc
		(start 135.792464 -241.80546)
		(mid 135.605266 -241.855603)
		(end 135.418068 -241.80546)
		(width 0.088646)
		(layer "In4.Cu")
		(net "M_G_CPU1_SB_DQS_DP<4>")
	)
	(arc
		(start 138.237468 -241.80546)
		(mid 137.954766 -241.729684)
		(end 137.672064 -241.80546)
		(width 0.088646)
		(layer "In4.Cu")
		(net "M_G_CPU1_SB_DQS_DP<4>")
	)
	(segment
		(start 195.505832 -200.434956)
		(end 195.70192 -200.434956)
		(width 0.20066)
		(layer "F.Cu")
		(net "M_G_CPU1_SB_DQS_DP<3>")
	)
	(segment
		(start 191.935608 -201.141838)
		(end 194.09283 -201.141838)
		(width 0.1016)
		(layer "F.Cu")
		(net "M_G_CPU1_SB_DQS_DP<3>")
	)
	(segment
		(start 137.484866 -219.228162)
		(end 137.489692 -218.697048)
		(width 0.20066)
		(layer "F.Cu")
		(net "M_G_CPU1_SB_DQS_DP<3>")
	)
	(segment
		(start 191.770254 -201.141838)
		(end 191.9097 -201.141838)
		(width 0.20066)
		(layer "F.Cu")
		(net "M_G_CPU1_SB_DQS_DP<3>")
	)
	(segment
		(start 195.095368 -200.84542)
		(end 195.505832 -200.434956)
		(width 0.20066)
		(layer "F.Cu")
		(net "M_G_CPU1_SB_DQS_DP<3>")
	)
	(segment
		(start 195.983606 -200.716642)
		(end 196.532246 -200.716642)
		(width 0.20066)
		(layer "F.Cu")
		(net "M_G_CPU1_SB_DQS_DP<3>")
	)
	(segment
		(start 188.988446 -200.716642)
		(end 189.577726 -200.716642)
		(width 0.20066)
		(layer "F.Cu")
		(net "M_G_CPU1_SB_DQS_DP<3>")
	)
	(segment
		(start 191.9097 -201.141838)
		(end 191.935608 -201.141838)
		(width 0.101854)
		(layer "F.Cu")
		(net "M_G_CPU1_SB_DQS_DP<3>")
	)
	(segment
		(start 191.519048 -200.890632)
		(end 191.770254 -201.141838)
		(width 0.20066)
		(layer "F.Cu")
		(net "M_G_CPU1_SB_DQS_DP<3>")
	)
	(segment
		(start 194.422268 -201.147934)
		(end 194.724782 -200.84542)
		(width 0.20066)
		(layer "F.Cu")
		(net "M_G_CPU1_SB_DQS_DP<3>")
	)
	(segment
		(start 189.818264 -200.476104)
		(end 190.41872 -200.476104)
		(width 0.20066)
		(layer "F.Cu")
		(net "M_G_CPU1_SB_DQS_DP<3>")
	)
	(segment
		(start 137.489692 -218.697048)
		(end 137.484866 -218.692222)
		(width 0.20066)
		(layer "F.Cu")
		(net "M_G_CPU1_SB_DQS_DP<3>")
	)
	(segment
		(start 189.577726 -200.716642)
		(end 189.818264 -200.476104)
		(width 0.20066)
		(layer "F.Cu")
		(net "M_G_CPU1_SB_DQS_DP<3>")
	)
	(segment
		(start 190.41872 -200.476104)
		(end 190.833248 -200.890632)
		(width 0.20066)
		(layer "F.Cu")
		(net "M_G_CPU1_SB_DQS_DP<3>")
	)
	(segment
		(start 187.883546 -200.716642)
		(end 188.988446 -200.716642)
		(width 0.20066)
		(layer "F.Cu")
		(net "M_G_CPU1_SB_DQS_DP<3>")
	)
	(segment
		(start 194.098926 -201.147934)
		(end 194.422268 -201.147934)
		(width 0.20066)
		(layer "F.Cu")
		(net "M_G_CPU1_SB_DQS_DP<3>")
	)
	(segment
		(start 190.833248 -200.890632)
		(end 191.519048 -200.890632)
		(width 0.20066)
		(layer "F.Cu")
		(net "M_G_CPU1_SB_DQS_DP<3>")
	)
	(segment
		(start 194.724782 -200.84542)
		(end 195.095368 -200.84542)
		(width 0.20066)
		(layer "F.Cu")
		(net "M_G_CPU1_SB_DQS_DP<3>")
	)
	(segment
		(start 195.70192 -200.434956)
		(end 195.983606 -200.716642)
		(width 0.20066)
		(layer "F.Cu")
		(net "M_G_CPU1_SB_DQS_DP<3>")
	)
	(segment
		(start 194.09283 -201.141838)
		(end 194.098926 -201.147934)
		(width 0.1016)
		(layer "F.Cu")
		(net "M_G_CPU1_SB_DQS_DP<3>")
	)
	(segment
		(start 141.243304 -218.317064)
		(end 141.24305 -218.317318)
		(width 0.088646)
		(layer "In6.Cu")
		(net "M_G_CPU1_SB_DQS_DP<3>")
	)
	(segment
		(start 179.756562 -199.996552)
		(end 178.927252 -199.996552)
		(width 0.18288)
		(layer "In6.Cu")
		(net "M_G_CPU1_SB_DQS_DP<3>")
	)
	(segment
		(start 182.813706 -200.5838)
		(end 182.203598 -199.973692)
		(width 0.18288)
		(layer "In6.Cu")
		(net "M_G_CPU1_SB_DQS_DP<3>")
	)
	(segment
		(start 169.617644 -199.148954)
		(end 168.997122 -199.769476)
		(width 0.18288)
		(layer "In6.Cu")
		(net "M_G_CPU1_SB_DQS_DP<3>")
	)
	(segment
		(start 173.973744 -199.18045)
		(end 173.256194 -199.18045)
		(width 0.18288)
		(layer "In6.Cu")
		(net "M_G_CPU1_SB_DQS_DP<3>")
	)
	(segment
		(start 142.41526 -216.521284)
		(end 142.330424 -216.521284)
		(width 0.088646)
		(layer "In6.Cu")
		(net "M_G_CPU1_SB_DQS_DP<3>")
	)
	(segment
		(start 181.20233 -200.597008)
		(end 180.357018 -200.597008)
		(width 0.18288)
		(layer "In6.Cu")
		(net "M_G_CPU1_SB_DQS_DP<3>")
	)
	(segment
		(start 149.604222 -209.332322)
		(end 142.43177 -216.504774)
		(width 0.18288)
		(layer "In6.Cu")
		(net "M_G_CPU1_SB_DQS_DP<3>")
	)
	(segment
		(start 141.684756 -217.598752)
		(end 141.684756 -218.117166)
		(width 0.088646)
		(layer "In6.Cu")
		(net "M_G_CPU1_SB_DQS_DP<3>")
	)
	(segment
		(start 172.593 -199.4408)
		(end 172.301154 -199.148954)
		(width 0.18288)
		(layer "In6.Cu")
		(net "M_G_CPU1_SB_DQS_DP<3>")
	)
	(segment
		(start 173.256194 -199.18045)
		(end 172.995844 -199.4408)
		(width 0.18288)
		(layer "In6.Cu")
		(net "M_G_CPU1_SB_DQS_DP<3>")
	)
	(segment
		(start 187.883546 -200.716642)
		(end 187.599066 -200.432162)
		(width 0.18288)
		(layer "In6.Cu")
		(net "M_G_CPU1_SB_DQS_DP<3>")
	)
	(segment
		(start 181.825646 -199.973692)
		(end 181.20233 -200.597008)
		(width 0.18288)
		(layer "In6.Cu")
		(net "M_G_CPU1_SB_DQS_DP<3>")
	)
	(segment
		(start 168.997122 -199.769476)
		(end 157.701234 -199.769476)
		(width 0.18288)
		(layer "In6.Cu")
		(net "M_G_CPU1_SB_DQS_DP<3>")
	)
	(segment
		(start 175.37938 -200.194926)
		(end 174.98822 -200.194926)
		(width 0.18288)
		(layer "In6.Cu")
		(net "M_G_CPU1_SB_DQS_DP<3>")
	)
	(segment
		(start 180.357018 -200.597008)
		(end 179.756562 -199.996552)
		(width 0.18288)
		(layer "In6.Cu")
		(net "M_G_CPU1_SB_DQS_DP<3>")
	)
	(segment
		(start 177.349658 -200.880472)
		(end 177.089308 -201.140822)
		(width 0.18288)
		(layer "In6.Cu")
		(net "M_G_CPU1_SB_DQS_DP<3>")
	)
	(segment
		(start 174.98822 -200.194926)
		(end 173.973744 -199.18045)
		(width 0.18288)
		(layer "In6.Cu")
		(net "M_G_CPU1_SB_DQS_DP<3>")
	)
	(segment
		(start 182.203598 -199.973692)
		(end 181.825646 -199.973692)
		(width 0.18288)
		(layer "In6.Cu")
		(net "M_G_CPU1_SB_DQS_DP<3>")
	)
	(segment
		(start 187.095892 -200.432162)
		(end 186.680348 -200.016618)
		(width 0.18288)
		(layer "In6.Cu")
		(net "M_G_CPU1_SB_DQS_DP<3>")
	)
	(segment
		(start 149.604222 -207.866488)
		(end 149.604222 -209.332322)
		(width 0.18288)
		(layer "In6.Cu")
		(net "M_G_CPU1_SB_DQS_DP<3>")
	)
	(segment
		(start 187.599066 -200.432162)
		(end 187.095892 -200.432162)
		(width 0.18288)
		(layer "In6.Cu")
		(net "M_G_CPU1_SB_DQS_DP<3>")
	)
	(segment
		(start 178.043332 -200.880472)
		(end 177.349658 -200.880472)
		(width 0.18288)
		(layer "In6.Cu")
		(net "M_G_CPU1_SB_DQS_DP<3>")
	)
	(segment
		(start 186.680348 -200.016618)
		(end 184.346088 -200.016618)
		(width 0.18288)
		(layer "In6.Cu")
		(net "M_G_CPU1_SB_DQS_DP<3>")
	)
	(segment
		(start 172.301154 -199.148954)
		(end 169.617644 -199.148954)
		(width 0.18288)
		(layer "In6.Cu")
		(net "M_G_CPU1_SB_DQS_DP<3>")
	)
	(segment
		(start 142.330424 -216.521284)
		(end 142.221458 -216.63025)
		(width 0.088646)
		(layer "In6.Cu")
		(net "M_G_CPU1_SB_DQS_DP<3>")
	)
	(segment
		(start 141.484858 -218.317064)
		(end 141.243304 -218.317064)
		(width 0.088646)
		(layer "In6.Cu")
		(net "M_G_CPU1_SB_DQS_DP<3>")
	)
	(segment
		(start 176.431702 -200.880472)
		(end 176.064926 -200.880472)
		(width 0.18288)
		(layer "In6.Cu")
		(net "M_G_CPU1_SB_DQS_DP<3>")
	)
	(segment
		(start 177.089308 -201.140822)
		(end 176.692052 -201.140822)
		(width 0.18288)
		(layer "In6.Cu")
		(net "M_G_CPU1_SB_DQS_DP<3>")
	)
	(segment
		(start 141.684756 -218.117166)
		(end 141.484858 -218.317064)
		(width 0.088646)
		(layer "In6.Cu")
		(net "M_G_CPU1_SB_DQS_DP<3>")
	)
	(segment
		(start 176.692052 -201.140822)
		(end 176.431702 -200.880472)
		(width 0.18288)
		(layer "In6.Cu")
		(net "M_G_CPU1_SB_DQS_DP<3>")
	)
	(segment
		(start 142.221458 -217.06205)
		(end 141.684756 -217.598752)
		(width 0.088646)
		(layer "In6.Cu")
		(net "M_G_CPU1_SB_DQS_DP<3>")
	)
	(segment
		(start 183.778906 -200.5838)
		(end 182.813706 -200.5838)
		(width 0.18288)
		(layer "In6.Cu")
		(net "M_G_CPU1_SB_DQS_DP<3>")
	)
	(segment
		(start 142.43177 -216.504774)
		(end 142.41526 -216.521284)
		(width 0.088646)
		(layer "In6.Cu")
		(net "M_G_CPU1_SB_DQS_DP<3>")
	)
	(segment
		(start 178.927252 -199.996552)
		(end 178.043332 -200.880472)
		(width 0.18288)
		(layer "In6.Cu")
		(net "M_G_CPU1_SB_DQS_DP<3>")
	)
	(segment
		(start 176.064926 -200.880472)
		(end 175.37938 -200.194926)
		(width 0.18288)
		(layer "In6.Cu")
		(net "M_G_CPU1_SB_DQS_DP<3>")
	)
	(segment
		(start 172.995844 -199.4408)
		(end 172.593 -199.4408)
		(width 0.18288)
		(layer "In6.Cu")
		(net "M_G_CPU1_SB_DQS_DP<3>")
	)
	(segment
		(start 140.506196 -218.3765)
		(end 140.491464 -218.367864)
		(width 0.088646)
		(layer "In6.Cu")
		(net "M_G_CPU1_SB_DQS_DP<3>")
	)
	(segment
		(start 137.730484 -218.397328)
		(end 137.64133 -218.421204)
		(width 0.088646)
		(layer "In6.Cu")
		(net "M_G_CPU1_SB_DQS_DP<3>")
	)
	(segment
		(start 141.056614 -218.367356)
		(end 141.056868 -218.367864)
		(width 0.088646)
		(layer "In6.Cu")
		(net "M_G_CPU1_SB_DQS_DP<3>")
	)
	(segment
		(start 142.221458 -216.63025)
		(end 142.221458 -217.06205)
		(width 0.088646)
		(layer "In6.Cu")
		(net "M_G_CPU1_SB_DQS_DP<3>")
	)
	(segment
		(start 138.626596 -218.3765)
		(end 138.611864 -218.367864)
		(width 0.088646)
		(layer "In6.Cu")
		(net "M_G_CPU1_SB_DQS_DP<3>")
	)
	(segment
		(start 138.237468 -218.367864)
		(end 138.222736 -218.3765)
		(width 0.088646)
		(layer "In6.Cu")
		(net "M_G_CPU1_SB_DQS_DP<3>")
	)
	(segment
		(start 157.701234 -199.769476)
		(end 149.604222 -207.866488)
		(width 0.18288)
		(layer "In6.Cu")
		(net "M_G_CPU1_SB_DQS_DP<3>")
	)
	(segment
		(start 184.346088 -200.016618)
		(end 183.778906 -200.5838)
		(width 0.18288)
		(layer "In6.Cu")
		(net "M_G_CPU1_SB_DQS_DP<3>")
	)
	(segment
		(start 139.566396 -218.3765)
		(end 139.551664 -218.367864)
		(width 0.088646)
		(layer "In6.Cu")
		(net "M_G_CPU1_SB_DQS_DP<3>")
	)
	(segment
		(start 137.64133 -218.421204)
		(end 137.484866 -218.692222)
		(width 0.088646)
		(layer "In6.Cu")
		(net "M_G_CPU1_SB_DQS_DP<3>")
	)
	(arc
		(start 137.75055 -218.405456)
		(mid 137.740478 -218.401489)
		(end 137.730484 -218.397328)
		(width 0.088646)
		(layer "In6.Cu")
		(net "M_G_CPU1_SB_DQS_DP<3>")
	)
	(arc
		(start 140.117068 -218.367864)
		(mid 139.842869 -218.443699)
		(end 139.566396 -218.3765)
		(width 0.088646)
		(layer "In6.Cu")
		(net "M_G_CPU1_SB_DQS_DP<3>")
	)
	(arc
		(start 139.177268 -218.367864)
		(mid 138.903069 -218.443699)
		(end 138.626596 -218.3765)
		(width 0.088646)
		(layer "In6.Cu")
		(net "M_G_CPU1_SB_DQS_DP<3>")
	)
	(arc
		(start 141.056868 -218.367864)
		(mid 140.782669 -218.443699)
		(end 140.506196 -218.3765)
		(width 0.088646)
		(layer "In6.Cu")
		(net "M_G_CPU1_SB_DQS_DP<3>")
	)
	(arc
		(start 138.611864 -218.367864)
		(mid 138.424666 -218.317721)
		(end 138.237468 -218.367864)
		(width 0.088646)
		(layer "In6.Cu")
		(net "M_G_CPU1_SB_DQS_DP<3>")
	)
	(arc
		(start 139.551664 -218.367864)
		(mid 139.364466 -218.317721)
		(end 139.177268 -218.367864)
		(width 0.088646)
		(layer "In6.Cu")
		(net "M_G_CPU1_SB_DQS_DP<3>")
	)
	(arc
		(start 141.24305 -218.317318)
		(mid 141.146528 -218.330036)
		(end 141.056614 -218.367356)
		(width 0.088646)
		(layer "In6.Cu")
		(net "M_G_CPU1_SB_DQS_DP<3>")
	)
	(arc
		(start 138.222736 -218.3765)
		(mid 137.989821 -218.442711)
		(end 137.75055 -218.405456)
		(width 0.088646)
		(layer "In6.Cu")
		(net "M_G_CPU1_SB_DQS_DP<3>")
	)
	(arc
		(start 140.491464 -218.367864)
		(mid 140.304266 -218.317721)
		(end 140.117068 -218.367864)
		(width 0.088646)
		(layer "In6.Cu")
		(net "M_G_CPU1_SB_DQS_DP<3>")
	)
	(segment
		(start 195.983606 -210.066636)
		(end 196.532246 -210.066636)
		(width 0.20066)
		(layer "F.Cu")
		(net "M_G_CPU1_SB_DQS_DP<2>")
	)
	(segment
		(start 187.883546 -210.066636)
		(end 188.988446 -210.066636)
		(width 0.20066)
		(layer "F.Cu")
		(net "M_G_CPU1_SB_DQS_DP<2>")
	)
	(segment
		(start 190.833248 -210.240626)
		(end 191.519048 -210.240626)
		(width 0.20066)
		(layer "F.Cu")
		(net "M_G_CPU1_SB_DQS_DP<2>")
	)
	(segment
		(start 194.724782 -210.195414)
		(end 195.095368 -210.195414)
		(width 0.20066)
		(layer "F.Cu")
		(net "M_G_CPU1_SB_DQS_DP<2>")
	)
	(segment
		(start 191.935608 -210.491832)
		(end 194.09283 -210.491832)
		(width 0.1016)
		(layer "F.Cu")
		(net "M_G_CPU1_SB_DQS_DP<2>")
	)
	(segment
		(start 129.496312 -232.528618)
		(end 129.496566 -232.528364)
		(width 0.20066)
		(layer "F.Cu")
		(net "M_G_CPU1_SB_DQS_DP<2>")
	)
	(segment
		(start 191.770254 -210.491832)
		(end 191.9097 -210.491832)
		(width 0.20066)
		(layer "F.Cu")
		(net "M_G_CPU1_SB_DQS_DP<2>")
	)
	(segment
		(start 194.09283 -210.491832)
		(end 194.098926 -210.497928)
		(width 0.1016)
		(layer "F.Cu")
		(net "M_G_CPU1_SB_DQS_DP<2>")
	)
	(segment
		(start 194.422268 -210.497928)
		(end 194.724782 -210.195414)
		(width 0.20066)
		(layer "F.Cu")
		(net "M_G_CPU1_SB_DQS_DP<2>")
	)
	(segment
		(start 195.095368 -210.195414)
		(end 195.505832 -209.78495)
		(width 0.20066)
		(layer "F.Cu")
		(net "M_G_CPU1_SB_DQS_DP<2>")
	)
	(segment
		(start 189.577726 -210.066636)
		(end 189.818264 -209.826098)
		(width 0.20066)
		(layer "F.Cu")
		(net "M_G_CPU1_SB_DQS_DP<2>")
	)
	(segment
		(start 195.505832 -209.78495)
		(end 195.70192 -209.78495)
		(width 0.20066)
		(layer "F.Cu")
		(net "M_G_CPU1_SB_DQS_DP<2>")
	)
	(segment
		(start 191.9097 -210.491832)
		(end 191.935608 -210.491832)
		(width 0.101854)
		(layer "F.Cu")
		(net "M_G_CPU1_SB_DQS_DP<2>")
	)
	(segment
		(start 188.988446 -210.066636)
		(end 189.577726 -210.066636)
		(width 0.20066)
		(layer "F.Cu")
		(net "M_G_CPU1_SB_DQS_DP<2>")
	)
	(segment
		(start 189.818264 -209.826098)
		(end 190.41872 -209.826098)
		(width 0.20066)
		(layer "F.Cu")
		(net "M_G_CPU1_SB_DQS_DP<2>")
	)
	(segment
		(start 190.41872 -209.826098)
		(end 190.833248 -210.240626)
		(width 0.20066)
		(layer "F.Cu")
		(net "M_G_CPU1_SB_DQS_DP<2>")
	)
	(segment
		(start 191.519048 -210.240626)
		(end 191.770254 -210.491832)
		(width 0.20066)
		(layer "F.Cu")
		(net "M_G_CPU1_SB_DQS_DP<2>")
	)
	(segment
		(start 129.496312 -233.064304)
		(end 129.496312 -232.528618)
		(width 0.20066)
		(layer "F.Cu")
		(net "M_G_CPU1_SB_DQS_DP<2>")
	)
	(segment
		(start 195.70192 -209.78495)
		(end 195.983606 -210.066636)
		(width 0.20066)
		(layer "F.Cu")
		(net "M_G_CPU1_SB_DQS_DP<2>")
	)
	(segment
		(start 194.098926 -210.497928)
		(end 194.422268 -210.497928)
		(width 0.20066)
		(layer "F.Cu")
		(net "M_G_CPU1_SB_DQS_DP<2>")
	)
	(segment
		(start 132.987796 -233.026458)
		(end 132.973064 -233.017822)
		(width 0.088646)
		(layer "In4.Cu")
		(net "M_G_CPU1_SB_DQS_DP<2>")
	)
	(segment
		(start 186.957462 -209.57159)
		(end 186.209686 -209.57159)
		(width 0.18288)
		(layer "In4.Cu")
		(net "M_G_CPU1_SB_DQS_DP<2>")
	)
	(segment
		(start 187.204096 -209.818224)
		(end 186.957462 -209.57159)
		(width 0.18288)
		(layer "In4.Cu")
		(net "M_G_CPU1_SB_DQS_DP<2>")
	)
	(segment
		(start 138.237468 -231.39019)
		(end 138.228578 -231.39527)
		(width 0.088646)
		(layer "In4.Cu")
		(net "M_G_CPU1_SB_DQS_DP<2>")
	)
	(segment
		(start 184.302654 -211.007198)
		(end 183.367426 -211.942426)
		(width 0.18288)
		(layer "In4.Cu")
		(net "M_G_CPU1_SB_DQS_DP<2>")
	)
	(segment
		(start 168.859454 -212.983572)
		(end 168.41978 -213.423246)
		(width 0.18288)
		(layer "In4.Cu")
		(net "M_G_CPU1_SB_DQS_DP<2>")
	)
	(segment
		(start 174.8663 -213.602316)
		(end 174.025052 -212.761068)
		(width 0.18288)
		(layer "In4.Cu")
		(net "M_G_CPU1_SB_DQS_DP<2>")
	)
	(segment
		(start 139.981178 -228.243638)
		(end 139.981178 -228.957124)
		(width 0.088646)
		(layer "In4.Cu")
		(net "M_G_CPU1_SB_DQS_DP<2>")
	)
	(segment
		(start 137.580116 -232.528364)
		(end 137.580116 -232.53827)
		(width 0.088646)
		(layer "In4.Cu")
		(net "M_G_CPU1_SB_DQS_DP<2>")
	)
	(segment
		(start 167.206676 -213.423246)
		(end 166.851076 -213.067646)
		(width 0.18288)
		(layer "In4.Cu")
		(net "M_G_CPU1_SB_DQS_DP<2>")
	)
	(segment
		(start 177.088292 -213.893908)
		(end 176.704244 -213.893908)
		(width 0.18288)
		(layer "In4.Cu")
		(net "M_G_CPU1_SB_DQS_DP<2>")
	)
	(segment
		(start 176.412652 -213.602316)
		(end 174.8663 -213.602316)
		(width 0.18288)
		(layer "In4.Cu")
		(net "M_G_CPU1_SB_DQS_DP<2>")
	)
	(segment
		(start 187.883546 -210.066636)
		(end 187.635134 -209.818224)
		(width 0.18288)
		(layer "In4.Cu")
		(net "M_G_CPU1_SB_DQS_DP<2>")
	)
	(segment
		(start 140.68933 -227.74148)
		(end 140.483336 -227.74148)
		(width 0.088646)
		(layer "In4.Cu")
		(net "M_G_CPU1_SB_DQS_DP<2>")
	)
	(segment
		(start 139.17168 -229.765352)
		(end 139.169648 -229.766622)
		(width 0.088646)
		(layer "In4.Cu")
		(net "M_G_CPU1_SB_DQS_DP<2>")
	)
	(segment
		(start 166.851076 -213.067646)
		(end 166.011352 -213.067646)
		(width 0.18288)
		(layer "In4.Cu")
		(net "M_G_CPU1_SB_DQS_DP<2>")
	)
	(segment
		(start 182.407306 -211.942426)
		(end 180.62956 -213.720172)
		(width 0.18288)
		(layer "In4.Cu")
		(net "M_G_CPU1_SB_DQS_DP<2>")
	)
	(segment
		(start 132.598668 -233.017822)
		(end 132.588254 -233.023918)
		(width 0.088646)
		(layer "In4.Cu")
		(net "M_G_CPU1_SB_DQS_DP<2>")
	)
	(segment
		(start 139.173712 -229.764336)
		(end 139.17168 -229.765352)
		(width 0.088646)
		(layer "In4.Cu")
		(net "M_G_CPU1_SB_DQS_DP<2>")
	)
	(segment
		(start 176.704244 -213.893908)
		(end 176.412652 -213.602316)
		(width 0.18288)
		(layer "In4.Cu")
		(net "M_G_CPU1_SB_DQS_DP<2>")
	)
	(segment
		(start 161.058352 -212.916008)
		(end 160.57626 -213.3981)
		(width 0.18288)
		(layer "In4.Cu")
		(net "M_G_CPU1_SB_DQS_DP<2>")
	)
	(segment
		(start 170.899328 -213.190328)
		(end 170.010328 -213.190328)
		(width 0.18288)
		(layer "In4.Cu")
		(net "M_G_CPU1_SB_DQS_DP<2>")
	)
	(segment
		(start 172.312584 -212.752432)
		(end 171.337224 -212.752432)
		(width 0.18288)
		(layer "In4.Cu")
		(net "M_G_CPU1_SB_DQS_DP<2>")
	)
	(segment
		(start 184.774078 -211.007198)
		(end 184.302654 -211.007198)
		(width 0.18288)
		(layer "In4.Cu")
		(net "M_G_CPU1_SB_DQS_DP<2>")
	)
	(segment
		(start 180.125116 -213.720172)
		(end 179.615084 -214.230204)
		(width 0.18288)
		(layer "In4.Cu")
		(net "M_G_CPU1_SB_DQS_DP<2>")
	)
	(segment
		(start 139.174474 -229.763828)
		(end 139.173712 -229.764336)
		(width 0.088646)
		(layer "In4.Cu")
		(net "M_G_CPU1_SB_DQS_DP<2>")
	)
	(segment
		(start 136.732264 -233.017822)
		(end 136.732772 -233.017568)
		(width 0.088646)
		(layer "In4.Cu")
		(net "M_G_CPU1_SB_DQS_DP<2>")
	)
	(segment
		(start 143.62684 -227.801424)
		(end 140.772642 -227.801424)
		(width 0.18288)
		(layer "In4.Cu")
		(net "M_G_CPU1_SB_DQS_DP<2>")
	)
	(segment
		(start 129.80924 -232.528364)
		(end 129.496566 -232.528364)
		(width 0.088646)
		(layer "In4.Cu")
		(net "M_G_CPU1_SB_DQS_DP<2>")
	)
	(segment
		(start 169.803572 -212.983572)
		(end 168.859454 -212.983572)
		(width 0.18288)
		(layer "In4.Cu")
		(net "M_G_CPU1_SB_DQS_DP<2>")
	)
	(segment
		(start 180.62956 -213.720172)
		(end 180.125116 -213.720172)
		(width 0.18288)
		(layer "In4.Cu")
		(net "M_G_CPU1_SB_DQS_DP<2>")
	)
	(segment
		(start 177.37201 -213.61019)
		(end 177.088292 -213.893908)
		(width 0.18288)
		(layer "In4.Cu")
		(net "M_G_CPU1_SB_DQS_DP<2>")
	)
	(segment
		(start 138.519916 -230.900478)
		(end 138.519916 -230.914702)
		(width 0.088646)
		(layer "In4.Cu")
		(net "M_G_CPU1_SB_DQS_DP<2>")
	)
	(segment
		(start 138.989816 -230.086662)
		(end 138.989816 -230.096568)
		(width 0.088646)
		(layer "In4.Cu")
		(net "M_G_CPU1_SB_DQS_DP<2>")
	)
	(segment
		(start 138.706606 -230.576628)
		(end 138.698478 -230.5812)
		(width 0.088646)
		(layer "In4.Cu")
		(net "M_G_CPU1_SB_DQS_DP<2>")
	)
	(segment
		(start 173.27118 -212.761068)
		(end 172.988224 -213.044024)
		(width 0.18288)
		(layer "In4.Cu")
		(net "M_G_CPU1_SB_DQS_DP<2>")
	)
	(segment
		(start 170.010328 -213.190328)
		(end 169.803572 -212.983572)
		(width 0.18288)
		(layer "In4.Cu")
		(net "M_G_CPU1_SB_DQS_DP<2>")
	)
	(segment
		(start 139.981178 -228.957124)
		(end 139.174474 -229.763828)
		(width 0.088646)
		(layer "In4.Cu")
		(net "M_G_CPU1_SB_DQS_DP<2>")
	)
	(segment
		(start 131.658614 -233.017822)
		(end 131.643882 -233.026458)
		(width 0.088646)
		(layer "In4.Cu")
		(net "M_G_CPU1_SB_DQS_DP<2>")
	)
	(segment
		(start 136.35736 -233.017568)
		(end 136.357614 -233.018076)
		(width 0.088646)
		(layer "In4.Cu")
		(net "M_G_CPU1_SB_DQS_DP<2>")
	)
	(segment
		(start 137.773664 -232.20045)
		(end 137.767568 -232.204006)
		(width 0.088646)
		(layer "In4.Cu")
		(net "M_G_CPU1_SB_DQS_DP<2>")
	)
	(segment
		(start 164.672264 -213.363556)
		(end 164.224716 -212.916008)
		(width 0.18288)
		(layer "In4.Cu")
		(net "M_G_CPU1_SB_DQS_DP<2>")
	)
	(segment
		(start 140.749274 -227.801424)
		(end 140.68933 -227.74148)
		(width 0.088646)
		(layer "In4.Cu")
		(net "M_G_CPU1_SB_DQS_DP<2>")
	)
	(segment
		(start 171.337224 -212.752432)
		(end 170.899328 -213.190328)
		(width 0.18288)
		(layer "In4.Cu")
		(net "M_G_CPU1_SB_DQS_DP<2>")
	)
	(segment
		(start 165.715442 -213.363556)
		(end 164.672264 -213.363556)
		(width 0.18288)
		(layer "In4.Cu")
		(net "M_G_CPU1_SB_DQS_DP<2>")
	)
	(segment
		(start 139.169648 -229.766622)
		(end 139.168378 -229.767384)
		(width 0.088646)
		(layer "In4.Cu")
		(net "M_G_CPU1_SB_DQS_DP<2>")
	)
	(segment
		(start 138.707368 -230.57612)
		(end 138.706606 -230.576628)
		(width 0.088646)
		(layer "In4.Cu")
		(net "M_G_CPU1_SB_DQS_DP<2>")
	)
	(segment
		(start 160.57626 -213.3981)
		(end 158.030164 -213.3981)
		(width 0.18288)
		(layer "In4.Cu")
		(net "M_G_CPU1_SB_DQS_DP<2>")
	)
	(segment
		(start 140.772642 -227.801424)
		(end 140.749274 -227.801424)
		(width 0.088646)
		(layer "In4.Cu")
		(net "M_G_CPU1_SB_DQS_DP<2>")
	)
	(segment
		(start 136.732772 -233.017568)
		(end 136.732518 -233.017568)
		(width 0.088646)
		(layer "In4.Cu")
		(net "M_G_CPU1_SB_DQS_DP<2>")
	)
	(segment
		(start 130.718814 -233.017822)
		(end 130.704082 -233.026458)
		(width 0.088646)
		(layer "In4.Cu")
		(net "M_G_CPU1_SB_DQS_DP<2>")
	)
	(segment
		(start 178.74361 -214.230204)
		(end 178.123596 -213.61019)
		(width 0.18288)
		(layer "In4.Cu")
		(net "M_G_CPU1_SB_DQS_DP<2>")
	)
	(segment
		(start 179.615084 -214.230204)
		(end 178.74361 -214.230204)
		(width 0.18288)
		(layer "In4.Cu")
		(net "M_G_CPU1_SB_DQS_DP<2>")
	)
	(segment
		(start 137.767568 -232.204006)
		(end 137.758678 -232.209086)
		(width 0.088646)
		(layer "In4.Cu")
		(net "M_G_CPU1_SB_DQS_DP<2>")
	)
	(segment
		(start 187.635134 -209.818224)
		(end 187.204096 -209.818224)
		(width 0.18288)
		(layer "In4.Cu")
		(net "M_G_CPU1_SB_DQS_DP<2>")
	)
	(segment
		(start 166.011352 -213.067646)
		(end 165.715442 -213.363556)
		(width 0.18288)
		(layer "In4.Cu")
		(net "M_G_CPU1_SB_DQS_DP<2>")
	)
	(segment
		(start 168.41978 -213.423246)
		(end 167.206676 -213.423246)
		(width 0.18288)
		(layer "In4.Cu")
		(net "M_G_CPU1_SB_DQS_DP<2>")
	)
	(segment
		(start 183.367426 -211.942426)
		(end 182.407306 -211.942426)
		(width 0.18288)
		(layer "In4.Cu")
		(net "M_G_CPU1_SB_DQS_DP<2>")
	)
	(segment
		(start 172.988224 -213.044024)
		(end 172.604176 -213.044024)
		(width 0.18288)
		(layer "In4.Cu")
		(net "M_G_CPU1_SB_DQS_DP<2>")
	)
	(segment
		(start 129.874772 -232.593896)
		(end 129.80924 -232.528364)
		(width 0.088646)
		(layer "In4.Cu")
		(net "M_G_CPU1_SB_DQS_DP<2>")
	)
	(segment
		(start 172.604176 -213.044024)
		(end 172.312584 -212.752432)
		(width 0.18288)
		(layer "In4.Cu")
		(net "M_G_CPU1_SB_DQS_DP<2>")
	)
	(segment
		(start 140.483336 -227.74148)
		(end 139.981178 -228.243638)
		(width 0.088646)
		(layer "In4.Cu")
		(net "M_G_CPU1_SB_DQS_DP<2>")
	)
	(segment
		(start 178.123596 -213.61019)
		(end 177.37201 -213.61019)
		(width 0.18288)
		(layer "In4.Cu")
		(net "M_G_CPU1_SB_DQS_DP<2>")
	)
	(segment
		(start 164.224716 -212.916008)
		(end 161.058352 -212.916008)
		(width 0.18288)
		(layer "In4.Cu")
		(net "M_G_CPU1_SB_DQS_DP<2>")
	)
	(segment
		(start 186.209686 -209.57159)
		(end 184.774078 -211.007198)
		(width 0.18288)
		(layer "In4.Cu")
		(net "M_G_CPU1_SB_DQS_DP<2>")
	)
	(segment
		(start 174.025052 -212.761068)
		(end 173.27118 -212.761068)
		(width 0.18288)
		(layer "In4.Cu")
		(net "M_G_CPU1_SB_DQS_DP<2>")
	)
	(segment
		(start 158.030164 -213.3981)
		(end 143.62684 -227.801424)
		(width 0.18288)
		(layer "In4.Cu")
		(net "M_G_CPU1_SB_DQS_DP<2>")
	)
	(arc
		(start 131.09321 -233.017822)
		(mid 130.906012 -232.967679)
		(end 130.718814 -233.017822)
		(width 0.088646)
		(layer "In4.Cu")
		(net "M_G_CPU1_SB_DQS_DP<2>")
	)
	(arc
		(start 130.15341 -233.017822)
		(mid 129.969819 -232.847687)
		(end 129.877566 -232.614978)
		(width 0.088646)
		(layer "In4.Cu")
		(net "M_G_CPU1_SB_DQS_DP<2>")
	)
	(arc
		(start 132.03301 -233.017822)
		(mid 131.845812 -232.967679)
		(end 131.658614 -233.017822)
		(width 0.088646)
		(layer "In4.Cu")
		(net "M_G_CPU1_SB_DQS_DP<2>")
	)
	(arc
		(start 133.538468 -233.017822)
		(mid 133.264269 -233.093657)
		(end 132.987796 -233.026458)
		(width 0.088646)
		(layer "In4.Cu")
		(net "M_G_CPU1_SB_DQS_DP<2>")
	)
	(arc
		(start 137.758678 -232.209086)
		(mid 137.627764 -232.345446)
		(end 137.580116 -232.528364)
		(width 0.088646)
		(layer "In4.Cu")
		(net "M_G_CPU1_SB_DQS_DP<2>")
	)
	(arc
		(start 138.050016 -231.714548)
		(mid 137.9761 -231.99405)
		(end 137.773664 -232.20045)
		(width 0.088646)
		(layer "In4.Cu")
		(net "M_G_CPU1_SB_DQS_DP<2>")
	)
	(arc
		(start 137.580116 -232.53827)
		(mid 137.502005 -232.815219)
		(end 137.297668 -233.017822)
		(width 0.088646)
		(layer "In4.Cu")
		(net "M_G_CPU1_SB_DQS_DP<2>")
	)
	(arc
		(start 136.357614 -233.018076)
		(mid 136.074993 -233.093691)
		(end 135.792464 -233.017822)
		(width 0.088646)
		(layer "In4.Cu")
		(net "M_G_CPU1_SB_DQS_DP<2>")
	)
	(arc
		(start 136.732518 -233.017568)
		(mid 136.544956 -232.967332)
		(end 136.35736 -233.017568)
		(width 0.088646)
		(layer "In4.Cu")
		(net "M_G_CPU1_SB_DQS_DP<2>")
	)
	(arc
		(start 138.698478 -230.5812)
		(mid 138.567564 -230.71756)
		(end 138.519916 -230.900478)
		(width 0.088646)
		(layer "In4.Cu")
		(net "M_G_CPU1_SB_DQS_DP<2>")
	)
	(arc
		(start 129.877566 -232.614978)
		(mid 129.87607 -232.60445)
		(end 129.874772 -232.593896)
		(width 0.088646)
		(layer "In4.Cu")
		(net "M_G_CPU1_SB_DQS_DP<2>")
	)
	(arc
		(start 137.297668 -233.017822)
		(mid 137.014966 -233.093598)
		(end 136.732264 -233.017822)
		(width 0.088646)
		(layer "In4.Cu")
		(net "M_G_CPU1_SB_DQS_DP<2>")
	)
	(arc
		(start 135.792464 -233.017822)
		(mid 135.605266 -232.967679)
		(end 135.418068 -233.017822)
		(width 0.088646)
		(layer "In4.Cu")
		(net "M_G_CPU1_SB_DQS_DP<2>")
	)
	(arc
		(start 138.519916 -230.914702)
		(mid 138.440775 -231.189325)
		(end 138.237468 -231.39019)
		(width 0.088646)
		(layer "In4.Cu")
		(net "M_G_CPU1_SB_DQS_DP<2>")
	)
	(arc
		(start 135.418068 -233.017822)
		(mid 135.135366 -233.093598)
		(end 134.852664 -233.017822)
		(width 0.088646)
		(layer "In4.Cu")
		(net "M_G_CPU1_SB_DQS_DP<2>")
	)
	(arc
		(start 138.989816 -230.096568)
		(mid 138.911705 -230.373517)
		(end 138.707368 -230.57612)
		(width 0.088646)
		(layer "In4.Cu")
		(net "M_G_CPU1_SB_DQS_DP<2>")
	)
	(arc
		(start 132.973064 -233.017822)
		(mid 132.785866 -232.967679)
		(end 132.598668 -233.017822)
		(width 0.088646)
		(layer "In4.Cu")
		(net "M_G_CPU1_SB_DQS_DP<2>")
	)
	(arc
		(start 134.852664 -233.017822)
		(mid 134.665466 -232.967679)
		(end 134.478268 -233.017822)
		(width 0.088646)
		(layer "In4.Cu")
		(net "M_G_CPU1_SB_DQS_DP<2>")
	)
	(arc
		(start 132.588254 -233.023918)
		(mid 132.309822 -233.093764)
		(end 132.03301 -233.017822)
		(width 0.088646)
		(layer "In4.Cu")
		(net "M_G_CPU1_SB_DQS_DP<2>")
	)
	(arc
		(start 131.643882 -233.026458)
		(mid 131.367407 -233.093778)
		(end 131.09321 -233.017822)
		(width 0.088646)
		(layer "In4.Cu")
		(net "M_G_CPU1_SB_DQS_DP<2>")
	)
	(arc
		(start 138.228578 -231.39527)
		(mid 138.097664 -231.53163)
		(end 138.050016 -231.714548)
		(width 0.088646)
		(layer "In4.Cu")
		(net "M_G_CPU1_SB_DQS_DP<2>")
	)
	(arc
		(start 139.168378 -229.767384)
		(mid 139.037464 -229.903744)
		(end 138.989816 -230.086662)
		(width 0.088646)
		(layer "In4.Cu")
		(net "M_G_CPU1_SB_DQS_DP<2>")
	)
	(arc
		(start 134.478268 -233.017822)
		(mid 134.195566 -233.093598)
		(end 133.912864 -233.017822)
		(width 0.088646)
		(layer "In4.Cu")
		(net "M_G_CPU1_SB_DQS_DP<2>")
	)
	(arc
		(start 130.704082 -233.026458)
		(mid 130.427607 -233.093778)
		(end 130.15341 -233.017822)
		(width 0.088646)
		(layer "In4.Cu")
		(net "M_G_CPU1_SB_DQS_DP<2>")
	)
	(arc
		(start 133.912864 -233.017822)
		(mid 133.725666 -232.967679)
		(end 133.538468 -233.017822)
		(width 0.088646)
		(layer "In4.Cu")
		(net "M_G_CPU1_SB_DQS_DP<2>")
	)
	(segment
		(start 188.988446 -219.41663)
		(end 189.577726 -219.41663)
		(width 0.20066)
		(layer "F.Cu")
		(net "M_G_CPU1_SB_DQS_DP<1>")
	)
	(segment
		(start 191.935608 -219.841826)
		(end 194.09283 -219.841826)
		(width 0.1016)
		(layer "F.Cu")
		(net "M_G_CPU1_SB_DQS_DP<1>")
	)
	(segment
		(start 189.818264 -219.176092)
		(end 190.41872 -219.176092)
		(width 0.20066)
		(layer "F.Cu")
		(net "M_G_CPU1_SB_DQS_DP<1>")
	)
	(segment
		(start 194.098926 -219.847922)
		(end 194.422268 -219.847922)
		(width 0.20066)
		(layer "F.Cu")
		(net "M_G_CPU1_SB_DQS_DP<1>")
	)
	(segment
		(start 190.41872 -219.176092)
		(end 190.833248 -219.59062)
		(width 0.20066)
		(layer "F.Cu")
		(net "M_G_CPU1_SB_DQS_DP<1>")
	)
	(segment
		(start 191.519048 -219.59062)
		(end 191.770254 -219.841826)
		(width 0.20066)
		(layer "F.Cu")
		(net "M_G_CPU1_SB_DQS_DP<1>")
	)
	(segment
		(start 191.9097 -219.841826)
		(end 191.935608 -219.841826)
		(width 0.101854)
		(layer "F.Cu")
		(net "M_G_CPU1_SB_DQS_DP<1>")
	)
	(segment
		(start 187.883546 -219.41663)
		(end 188.988446 -219.41663)
		(width 0.20066)
		(layer "F.Cu")
		(net "M_G_CPU1_SB_DQS_DP<1>")
	)
	(segment
		(start 127.146812 -235.505752)
		(end 127.146812 -234.970066)
		(width 0.20066)
		(layer "F.Cu")
		(net "M_G_CPU1_SB_DQS_DP<1>")
	)
	(segment
		(start 190.833248 -219.59062)
		(end 191.519048 -219.59062)
		(width 0.20066)
		(layer "F.Cu")
		(net "M_G_CPU1_SB_DQS_DP<1>")
	)
	(segment
		(start 127.147066 -235.506006)
		(end 127.146812 -235.505752)
		(width 0.20066)
		(layer "F.Cu")
		(net "M_G_CPU1_SB_DQS_DP<1>")
	)
	(segment
		(start 189.577726 -219.41663)
		(end 189.818264 -219.176092)
		(width 0.20066)
		(layer "F.Cu")
		(net "M_G_CPU1_SB_DQS_DP<1>")
	)
	(segment
		(start 195.095368 -219.545408)
		(end 195.505832 -219.134944)
		(width 0.20066)
		(layer "F.Cu")
		(net "M_G_CPU1_SB_DQS_DP<1>")
	)
	(segment
		(start 191.770254 -219.841826)
		(end 191.9097 -219.841826)
		(width 0.20066)
		(layer "F.Cu")
		(net "M_G_CPU1_SB_DQS_DP<1>")
	)
	(segment
		(start 194.09283 -219.841826)
		(end 194.098926 -219.847922)
		(width 0.1016)
		(layer "F.Cu")
		(net "M_G_CPU1_SB_DQS_DP<1>")
	)
	(segment
		(start 194.422268 -219.847922)
		(end 194.724782 -219.545408)
		(width 0.20066)
		(layer "F.Cu")
		(net "M_G_CPU1_SB_DQS_DP<1>")
	)
	(segment
		(start 195.70192 -219.134944)
		(end 195.983606 -219.41663)
		(width 0.20066)
		(layer "F.Cu")
		(net "M_G_CPU1_SB_DQS_DP<1>")
	)
	(segment
		(start 195.983606 -219.41663)
		(end 196.532246 -219.41663)
		(width 0.20066)
		(layer "F.Cu")
		(net "M_G_CPU1_SB_DQS_DP<1>")
	)
	(segment
		(start 194.724782 -219.545408)
		(end 195.095368 -219.545408)
		(width 0.20066)
		(layer "F.Cu")
		(net "M_G_CPU1_SB_DQS_DP<1>")
	)
	(segment
		(start 195.505832 -219.134944)
		(end 195.70192 -219.134944)
		(width 0.20066)
		(layer "F.Cu")
		(net "M_G_CPU1_SB_DQS_DP<1>")
	)
	(segment
		(start 137.30351 -234.642152)
		(end 137.298176 -234.6452)
		(width 0.088646)
		(layer "In6.Cu")
		(net "M_G_CPU1_SB_DQS_DP<1>")
	)
	(segment
		(start 140.061442 -233.131106)
		(end 140.038074 -233.131106)
		(width 0.088646)
		(layer "In6.Cu")
		(net "M_G_CPU1_SB_DQS_DP<1>")
	)
	(segment
		(start 155.672282 -220.678756)
		(end 155.49626 -220.678756)
		(width 0.18288)
		(layer "In6.Cu")
		(net "M_G_CPU1_SB_DQS_DP<1>")
	)
	(segment
		(start 173.012862 -222.39097)
		(end 172.609256 -222.39097)
		(width 0.18288)
		(layer "In6.Cu")
		(net "M_G_CPU1_SB_DQS_DP<1>")
	)
	(segment
		(start 186.98464 -219.138246)
		(end 186.719718 -218.873324)
		(width 0.18288)
		(layer "In6.Cu")
		(net "M_G_CPU1_SB_DQS_DP<1>")
	)
	(segment
		(start 126.776734 -234.912916)
		(end 126.833884 -234.970066)
		(width 0.088646)
		(layer "In6.Cu")
		(net "M_G_CPU1_SB_DQS_DP<1>")
	)
	(segment
		(start 187.605162 -219.138246)
		(end 186.98464 -219.138246)
		(width 0.18288)
		(layer "In6.Cu")
		(net "M_G_CPU1_SB_DQS_DP<1>")
	)
	(segment
		(start 140.038074 -233.131106)
		(end 139.97813 -233.071162)
		(width 0.088646)
		(layer "In6.Cu")
		(net "M_G_CPU1_SB_DQS_DP<1>")
	)
	(segment
		(start 161.23031 -220.291914)
		(end 160.668716 -219.73032)
		(width 0.18288)
		(layer "In6.Cu")
		(net "M_G_CPU1_SB_DQS_DP<1>")
	)
	(segment
		(start 174.938436 -221.285562)
		(end 174.084234 -222.139764)
		(width 0.18288)
		(layer "In6.Cu")
		(net "M_G_CPU1_SB_DQS_DP<1>")
	)
	(segment
		(start 172.342048 -222.123762)
		(end 169.836338 -222.123762)
		(width 0.18288)
		(layer "In6.Cu")
		(net "M_G_CPU1_SB_DQS_DP<1>")
	)
	(segment
		(start 156.444696 -219.73032)
		(end 156.058616 -220.1164)
		(width 0.18288)
		(layer "In6.Cu")
		(net "M_G_CPU1_SB_DQS_DP<1>")
	)
	(segment
		(start 126.95809 -234.64647)
		(end 126.950724 -234.650788)
		(width 0.088646)
		(layer "In6.Cu")
		(net "M_G_CPU1_SB_DQS_DP<1>")
	)
	(segment
		(start 176.701704 -221.540832)
		(end 176.446434 -221.285562)
		(width 0.18288)
		(layer "In6.Cu")
		(net "M_G_CPU1_SB_DQS_DP<1>")
	)
	(segment
		(start 178.812952 -220.535246)
		(end 178.084226 -221.263972)
		(width 0.18288)
		(layer "In6.Cu")
		(net "M_G_CPU1_SB_DQS_DP<1>")
	)
	(segment
		(start 183.011572 -219.816426)
		(end 179.972208 -219.816426)
		(width 0.18288)
		(layer "In6.Cu")
		(net "M_G_CPU1_SB_DQS_DP<1>")
	)
	(segment
		(start 140.581634 -233.131106)
		(end 140.061442 -233.131106)
		(width 0.18288)
		(layer "In6.Cu")
		(net "M_G_CPU1_SB_DQS_DP<1>")
	)
	(segment
		(start 156.058616 -220.1164)
		(end 156.058616 -220.292422)
		(width 0.18288)
		(layer "In6.Cu")
		(net "M_G_CPU1_SB_DQS_DP<1>")
	)
	(segment
		(start 163.867846 -218.983306)
		(end 162.559238 -220.291914)
		(width 0.18288)
		(layer "In6.Cu")
		(net "M_G_CPU1_SB_DQS_DP<1>")
	)
	(segment
		(start 187.883546 -219.41663)
		(end 187.605162 -219.138246)
		(width 0.18288)
		(layer "In6.Cu")
		(net "M_G_CPU1_SB_DQS_DP<1>")
	)
	(segment
		(start 160.668716 -219.73032)
		(end 159.199072 -219.73032)
		(width 0.18288)
		(layer "In6.Cu")
		(net "M_G_CPU1_SB_DQS_DP<1>")
	)
	(segment
		(start 179.253388 -220.535246)
		(end 178.812952 -220.535246)
		(width 0.18288)
		(layer "In6.Cu")
		(net "M_G_CPU1_SB_DQS_DP<1>")
	)
	(segment
		(start 179.972208 -219.816426)
		(end 179.253388 -220.535246)
		(width 0.18288)
		(layer "In6.Cu")
		(net "M_G_CPU1_SB_DQS_DP<1>")
	)
	(segment
		(start 174.084234 -222.139764)
		(end 173.264068 -222.139764)
		(width 0.18288)
		(layer "In6.Cu")
		(net "M_G_CPU1_SB_DQS_DP<1>")
	)
	(segment
		(start 158.528512 -219.85478)
		(end 158.404052 -219.73032)
		(width 0.18288)
		(layer "In6.Cu")
		(net "M_G_CPU1_SB_DQS_DP<1>")
	)
	(segment
		(start 176.446434 -221.285562)
		(end 174.938436 -221.285562)
		(width 0.18288)
		(layer "In6.Cu")
		(net "M_G_CPU1_SB_DQS_DP<1>")
	)
	(segment
		(start 137.297414 -234.645708)
		(end 137.282682 -234.654344)
		(width 0.088646)
		(layer "In6.Cu")
		(net "M_G_CPU1_SB_DQS_DP<1>")
	)
	(segment
		(start 132.598414 -234.645708)
		(end 132.588 -234.651804)
		(width 0.088646)
		(layer "In6.Cu")
		(net "M_G_CPU1_SB_DQS_DP<1>")
	)
	(segment
		(start 172.609256 -222.39097)
		(end 172.342048 -222.123762)
		(width 0.18288)
		(layer "In6.Cu")
		(net "M_G_CPU1_SB_DQS_DP<1>")
	)
	(segment
		(start 155.49626 -220.678756)
		(end 143.044164 -233.130852)
		(width 0.18288)
		(layer "In6.Cu")
		(net "M_G_CPU1_SB_DQS_DP<1>")
	)
	(segment
		(start 126.833884 -234.970066)
		(end 127.146812 -234.970066)
		(width 0.088646)
		(layer "In6.Cu")
		(net "M_G_CPU1_SB_DQS_DP<1>")
	)
	(segment
		(start 166.930578 -220.92031)
		(end 166.219124 -220.208856)
		(width 0.18288)
		(layer "In6.Cu")
		(net "M_G_CPU1_SB_DQS_DP<1>")
	)
	(segment
		(start 178.084226 -221.263972)
		(end 177.351182 -221.263972)
		(width 0.18288)
		(layer "In6.Cu")
		(net "M_G_CPU1_SB_DQS_DP<1>")
	)
	(segment
		(start 183.954674 -218.873324)
		(end 183.011572 -219.816426)
		(width 0.18288)
		(layer "In6.Cu")
		(net "M_G_CPU1_SB_DQS_DP<1>")
	)
	(segment
		(start 140.843254 -233.130852)
		(end 140.581634 -233.131106)
		(width 0.18288)
		(layer "In6.Cu")
		(net "M_G_CPU1_SB_DQS_DP<1>")
	)
	(segment
		(start 177.351182 -221.263972)
		(end 177.074322 -221.540832)
		(width 0.18288)
		(layer "In6.Cu")
		(net "M_G_CPU1_SB_DQS_DP<1>")
	)
	(segment
		(start 131.658868 -234.645708)
		(end 131.648454 -234.651804)
		(width 0.088646)
		(layer "In6.Cu")
		(net "M_G_CPU1_SB_DQS_DP<1>")
	)
	(segment
		(start 165.656514 -219.822268)
		(end 165.656514 -219.646246)
		(width 0.18288)
		(layer "In6.Cu")
		(net "M_G_CPU1_SB_DQS_DP<1>")
	)
	(segment
		(start 162.559238 -220.291914)
		(end 161.23031 -220.291914)
		(width 0.18288)
		(layer "In6.Cu")
		(net "M_G_CPU1_SB_DQS_DP<1>")
	)
	(segment
		(start 169.836338 -222.123762)
		(end 166.930578 -220.92031)
		(width 0.18288)
		(layer "In6.Cu")
		(net "M_G_CPU1_SB_DQS_DP<1>")
	)
	(segment
		(start 139.97813 -233.071162)
		(end 139.870688 -233.071162)
		(width 0.088646)
		(layer "In6.Cu")
		(net "M_G_CPU1_SB_DQS_DP<1>")
	)
	(segment
		(start 126.959614 -234.645708)
		(end 126.95809 -234.64647)
		(width 0.088646)
		(layer "In6.Cu")
		(net "M_G_CPU1_SB_DQS_DP<1>")
	)
	(segment
		(start 166.043102 -220.208856)
		(end 165.656514 -219.822268)
		(width 0.18288)
		(layer "In6.Cu")
		(net "M_G_CPU1_SB_DQS_DP<1>")
	)
	(segment
		(start 159.199072 -219.73032)
		(end 159.074612 -219.85478)
		(width 0.18288)
		(layer "In6.Cu")
		(net "M_G_CPU1_SB_DQS_DP<1>")
	)
	(segment
		(start 130.718814 -234.645708)
		(end 130.704082 -234.654344)
		(width 0.088646)
		(layer "In6.Cu")
		(net "M_G_CPU1_SB_DQS_DP<1>")
	)
	(segment
		(start 127.899414 -234.645708)
		(end 127.884682 -234.654344)
		(width 0.088646)
		(layer "In6.Cu")
		(net "M_G_CPU1_SB_DQS_DP<1>")
	)
	(segment
		(start 159.074612 -219.85478)
		(end 158.528512 -219.85478)
		(width 0.18288)
		(layer "In6.Cu")
		(net "M_G_CPU1_SB_DQS_DP<1>")
	)
	(segment
		(start 158.404052 -219.73032)
		(end 156.444696 -219.73032)
		(width 0.18288)
		(layer "In6.Cu")
		(net "M_G_CPU1_SB_DQS_DP<1>")
	)
	(segment
		(start 137.767568 -233.831892)
		(end 137.758678 -233.836972)
		(width 0.088646)
		(layer "In6.Cu")
		(net "M_G_CPU1_SB_DQS_DP<1>")
	)
	(segment
		(start 133.538468 -234.645708)
		(end 133.528054 -234.651804)
		(width 0.088646)
		(layer "In6.Cu")
		(net "M_G_CPU1_SB_DQS_DP<1>")
	)
	(segment
		(start 166.219124 -220.208856)
		(end 166.043102 -220.208856)
		(width 0.18288)
		(layer "In6.Cu")
		(net "M_G_CPU1_SB_DQS_DP<1>")
	)
	(segment
		(start 173.264068 -222.139764)
		(end 173.012862 -222.39097)
		(width 0.18288)
		(layer "In6.Cu")
		(net "M_G_CPU1_SB_DQS_DP<1>")
	)
	(segment
		(start 164.993574 -218.983306)
		(end 163.867846 -218.983306)
		(width 0.18288)
		(layer "In6.Cu")
		(net "M_G_CPU1_SB_DQS_DP<1>")
	)
	(segment
		(start 156.058616 -220.292422)
		(end 155.672282 -220.678756)
		(width 0.18288)
		(layer "In6.Cu")
		(net "M_G_CPU1_SB_DQS_DP<1>")
	)
	(segment
		(start 165.656514 -219.646246)
		(end 164.993574 -218.983306)
		(width 0.18288)
		(layer "In6.Cu")
		(net "M_G_CPU1_SB_DQS_DP<1>")
	)
	(segment
		(start 128.839214 -234.645708)
		(end 128.824482 -234.654344)
		(width 0.088646)
		(layer "In6.Cu")
		(net "M_G_CPU1_SB_DQS_DP<1>")
	)
	(segment
		(start 139.870688 -233.071162)
		(end 139.627864 -233.313986)
		(width 0.088646)
		(layer "In6.Cu")
		(net "M_G_CPU1_SB_DQS_DP<1>")
	)
	(segment
		(start 143.044164 -233.130852)
		(end 140.843254 -233.130852)
		(width 0.18288)
		(layer "In6.Cu")
		(net "M_G_CPU1_SB_DQS_DP<1>")
	)
	(segment
		(start 137.298176 -234.6452)
		(end 137.297414 -234.645708)
		(width 0.088646)
		(layer "In6.Cu")
		(net "M_G_CPU1_SB_DQS_DP<1>")
	)
	(segment
		(start 177.074322 -221.540832)
		(end 176.701704 -221.540832)
		(width 0.18288)
		(layer "In6.Cu")
		(net "M_G_CPU1_SB_DQS_DP<1>")
	)
	(segment
		(start 186.719718 -218.873324)
		(end 183.954674 -218.873324)
		(width 0.18288)
		(layer "In6.Cu")
		(net "M_G_CPU1_SB_DQS_DP<1>")
	)
	(segment
		(start 136.357614 -234.645708)
		(end 136.3472 -234.651804)
		(width 0.088646)
		(layer "In6.Cu")
		(net "M_G_CPU1_SB_DQS_DP<1>")
	)
	(arc
		(start 127.884682 -234.654344)
		(mid 127.608207 -234.721664)
		(end 127.33401 -234.645708)
		(width 0.088646)
		(layer "In6.Cu")
		(net "M_G_CPU1_SB_DQS_DP<1>")
	)
	(arc
		(start 137.580116 -234.15625)
		(mid 137.506125 -234.435816)
		(end 137.30351 -234.642152)
		(width 0.088646)
		(layer "In6.Cu")
		(net "M_G_CPU1_SB_DQS_DP<1>")
	)
	(arc
		(start 131.648454 -234.651804)
		(mid 131.370022 -234.72165)
		(end 131.09321 -234.645708)
		(width 0.088646)
		(layer "In6.Cu")
		(net "M_G_CPU1_SB_DQS_DP<1>")
	)
	(arc
		(start 138.68273 -233.844846)
		(mid 138.410687 -233.90732)
		(end 138.141964 -233.831892)
		(width 0.088646)
		(layer "In6.Cu")
		(net "M_G_CPU1_SB_DQS_DP<1>")
	)
	(arc
		(start 136.73201 -234.645708)
		(mid 136.544812 -234.595565)
		(end 136.357614 -234.645708)
		(width 0.088646)
		(layer "In6.Cu")
		(net "M_G_CPU1_SB_DQS_DP<1>")
	)
	(arc
		(start 128.27381 -234.645708)
		(mid 128.086612 -234.595565)
		(end 127.899414 -234.645708)
		(width 0.088646)
		(layer "In6.Cu")
		(net "M_G_CPU1_SB_DQS_DP<1>")
	)
	(arc
		(start 138.141964 -233.831892)
		(mid 137.954766 -233.781749)
		(end 137.767568 -233.831892)
		(width 0.088646)
		(layer "In6.Cu")
		(net "M_G_CPU1_SB_DQS_DP<1>")
	)
	(arc
		(start 134.852664 -234.645708)
		(mid 134.665466 -234.595565)
		(end 134.478268 -234.645708)
		(width 0.088646)
		(layer "In6.Cu")
		(net "M_G_CPU1_SB_DQS_DP<1>")
	)
	(arc
		(start 130.15341 -234.645708)
		(mid 129.966212 -234.595565)
		(end 129.779014 -234.645708)
		(width 0.088646)
		(layer "In6.Cu")
		(net "M_G_CPU1_SB_DQS_DP<1>")
	)
	(arc
		(start 132.97281 -234.645708)
		(mid 132.785612 -234.595565)
		(end 132.598414 -234.645708)
		(width 0.088646)
		(layer "In6.Cu")
		(net "M_G_CPU1_SB_DQS_DP<1>")
	)
	(arc
		(start 133.528054 -234.651804)
		(mid 133.249622 -234.72165)
		(end 132.97281 -234.645708)
		(width 0.088646)
		(layer "In6.Cu")
		(net "M_G_CPU1_SB_DQS_DP<1>")
	)
	(arc
		(start 139.627864 -233.313986)
		(mid 139.581809 -233.367113)
		(end 139.54379 -233.426254)
		(width 0.088646)
		(layer "In6.Cu")
		(net "M_G_CPU1_SB_DQS_DP<1>")
	)
	(arc
		(start 129.779014 -234.645708)
		(mid 129.496312 -234.721484)
		(end 129.21361 -234.645708)
		(width 0.088646)
		(layer "In6.Cu")
		(net "M_G_CPU1_SB_DQS_DP<1>")
	)
	(arc
		(start 135.418068 -234.645708)
		(mid 135.135366 -234.721484)
		(end 134.852664 -234.645708)
		(width 0.088646)
		(layer "In6.Cu")
		(net "M_G_CPU1_SB_DQS_DP<1>")
	)
	(arc
		(start 134.478268 -234.645708)
		(mid 134.195566 -234.721484)
		(end 133.912864 -234.645708)
		(width 0.088646)
		(layer "In6.Cu")
		(net "M_G_CPU1_SB_DQS_DP<1>")
	)
	(arc
		(start 133.912864 -234.645708)
		(mid 133.725666 -234.595565)
		(end 133.538468 -234.645708)
		(width 0.088646)
		(layer "In6.Cu")
		(net "M_G_CPU1_SB_DQS_DP<1>")
	)
	(arc
		(start 137.758678 -233.836972)
		(mid 137.627764 -233.973332)
		(end 137.580116 -234.15625)
		(width 0.088646)
		(layer "In6.Cu")
		(net "M_G_CPU1_SB_DQS_DP<1>")
	)
	(arc
		(start 132.033264 -234.645708)
		(mid 131.846066 -234.595565)
		(end 131.658868 -234.645708)
		(width 0.088646)
		(layer "In6.Cu")
		(net "M_G_CPU1_SB_DQS_DP<1>")
	)
	(arc
		(start 129.21361 -234.645708)
		(mid 129.026412 -234.595565)
		(end 128.839214 -234.645708)
		(width 0.088646)
		(layer "In6.Cu")
		(net "M_G_CPU1_SB_DQS_DP<1>")
	)
	(arc
		(start 135.792464 -234.645708)
		(mid 135.605266 -234.595565)
		(end 135.418068 -234.645708)
		(width 0.088646)
		(layer "In6.Cu")
		(net "M_G_CPU1_SB_DQS_DP<1>")
	)
	(arc
		(start 131.09321 -234.645708)
		(mid 130.906012 -234.595565)
		(end 130.718814 -234.645708)
		(width 0.088646)
		(layer "In6.Cu")
		(net "M_G_CPU1_SB_DQS_DP<1>")
	)
	(arc
		(start 136.3472 -234.651804)
		(mid 136.069022 -234.721527)
		(end 135.792464 -234.645708)
		(width 0.088646)
		(layer "In6.Cu")
		(net "M_G_CPU1_SB_DQS_DP<1>")
	)
	(arc
		(start 126.950724 -234.650788)
		(mid 126.834915 -234.762717)
		(end 126.776734 -234.912916)
		(width 0.088646)
		(layer "In6.Cu")
		(net "M_G_CPU1_SB_DQS_DP<1>")
	)
	(arc
		(start 127.33401 -234.645708)
		(mid 127.146812 -234.595565)
		(end 126.959614 -234.645708)
		(width 0.088646)
		(layer "In6.Cu")
		(net "M_G_CPU1_SB_DQS_DP<1>")
	)
	(arc
		(start 130.704082 -234.654344)
		(mid 130.427607 -234.721664)
		(end 130.15341 -234.645708)
		(width 0.088646)
		(layer "In6.Cu")
		(net "M_G_CPU1_SB_DQS_DP<1>")
	)
	(arc
		(start 139.54379 -233.426254)
		(mid 139.291811 -233.686875)
		(end 138.942064 -233.782108)
		(width 0.088646)
		(layer "In6.Cu")
		(net "M_G_CPU1_SB_DQS_DP<1>")
	)
	(arc
		(start 138.942064 -233.782108)
		(mid 138.808647 -233.797966)
		(end 138.68273 -233.844846)
		(width 0.088646)
		(layer "In6.Cu")
		(net "M_G_CPU1_SB_DQS_DP<1>")
	)
	(arc
		(start 132.588 -234.651804)
		(mid 132.309822 -234.721527)
		(end 132.033264 -234.645708)
		(width 0.088646)
		(layer "In6.Cu")
		(net "M_G_CPU1_SB_DQS_DP<1>")
	)
	(arc
		(start 137.282682 -234.654344)
		(mid 137.006207 -234.721664)
		(end 136.73201 -234.645708)
		(width 0.088646)
		(layer "In6.Cu")
		(net "M_G_CPU1_SB_DQS_DP<1>")
	)
	(arc
		(start 128.824482 -234.654344)
		(mid 128.548007 -234.721664)
		(end 128.27381 -234.645708)
		(width 0.088646)
		(layer "In6.Cu")
		(net "M_G_CPU1_SB_DQS_DP<1>")
	)
	(segment
		(start 127.146812 -240.388902)
		(end 127.146812 -239.853216)
		(width 0.20066)
		(layer "F.Cu")
		(net "M_G_CPU1_SB_DQS_DP<0>")
	)
	(segment
		(start 189.818264 -228.526086)
		(end 190.41872 -228.526086)
		(width 0.20066)
		(layer "F.Cu")
		(net "M_G_CPU1_SB_DQS_DP<0>")
	)
	(segment
		(start 191.519048 -228.940614)
		(end 191.770254 -229.19182)
		(width 0.20066)
		(layer "F.Cu")
		(net "M_G_CPU1_SB_DQS_DP<0>")
	)
	(segment
		(start 195.983606 -228.766624)
		(end 196.532246 -228.766624)
		(width 0.20066)
		(layer "F.Cu")
		(net "M_G_CPU1_SB_DQS_DP<0>")
	)
	(segment
		(start 194.422268 -229.197916)
		(end 194.724782 -228.895402)
		(width 0.20066)
		(layer "F.Cu")
		(net "M_G_CPU1_SB_DQS_DP<0>")
	)
	(segment
		(start 195.505832 -228.484938)
		(end 195.70192 -228.484938)
		(width 0.20066)
		(layer "F.Cu")
		(net "M_G_CPU1_SB_DQS_DP<0>")
	)
	(segment
		(start 194.09283 -229.19182)
		(end 194.098926 -229.197916)
		(width 0.1016)
		(layer "F.Cu")
		(net "M_G_CPU1_SB_DQS_DP<0>")
	)
	(segment
		(start 195.70192 -228.484938)
		(end 195.983606 -228.766624)
		(width 0.20066)
		(layer "F.Cu")
		(net "M_G_CPU1_SB_DQS_DP<0>")
	)
	(segment
		(start 191.935608 -229.19182)
		(end 194.09283 -229.19182)
		(width 0.1016)
		(layer "F.Cu")
		(net "M_G_CPU1_SB_DQS_DP<0>")
	)
	(segment
		(start 189.577726 -228.766624)
		(end 189.818264 -228.526086)
		(width 0.20066)
		(layer "F.Cu")
		(net "M_G_CPU1_SB_DQS_DP<0>")
	)
	(segment
		(start 190.41872 -228.526086)
		(end 190.833248 -228.940614)
		(width 0.20066)
		(layer "F.Cu")
		(net "M_G_CPU1_SB_DQS_DP<0>")
	)
	(segment
		(start 194.724782 -228.895402)
		(end 195.095368 -228.895402)
		(width 0.20066)
		(layer "F.Cu")
		(net "M_G_CPU1_SB_DQS_DP<0>")
	)
	(segment
		(start 188.988446 -228.766624)
		(end 189.577726 -228.766624)
		(width 0.20066)
		(layer "F.Cu")
		(net "M_G_CPU1_SB_DQS_DP<0>")
	)
	(segment
		(start 127.147066 -240.389156)
		(end 127.146812 -240.388902)
		(width 0.20066)
		(layer "F.Cu")
		(net "M_G_CPU1_SB_DQS_DP<0>")
	)
	(segment
		(start 191.770254 -229.19182)
		(end 191.9097 -229.19182)
		(width 0.20066)
		(layer "F.Cu")
		(net "M_G_CPU1_SB_DQS_DP<0>")
	)
	(segment
		(start 190.833248 -228.940614)
		(end 191.519048 -228.940614)
		(width 0.20066)
		(layer "F.Cu")
		(net "M_G_CPU1_SB_DQS_DP<0>")
	)
	(segment
		(start 194.098926 -229.197916)
		(end 194.422268 -229.197916)
		(width 0.20066)
		(layer "F.Cu")
		(net "M_G_CPU1_SB_DQS_DP<0>")
	)
	(segment
		(start 187.883546 -228.766624)
		(end 188.988446 -228.766624)
		(width 0.20066)
		(layer "F.Cu")
		(net "M_G_CPU1_SB_DQS_DP<0>")
	)
	(segment
		(start 191.9097 -229.19182)
		(end 191.935608 -229.19182)
		(width 0.101854)
		(layer "F.Cu")
		(net "M_G_CPU1_SB_DQS_DP<0>")
	)
	(segment
		(start 195.095368 -228.895402)
		(end 195.505832 -228.484938)
		(width 0.20066)
		(layer "F.Cu")
		(net "M_G_CPU1_SB_DQS_DP<0>")
	)
	(segment
		(start 172.973746 -235.140754)
		(end 173.247304 -234.867196)
		(width 0.18288)
		(layer "In6.Cu")
		(net "M_G_CPU1_SB_DQS_DP<0>")
	)
	(segment
		(start 165.334188 -233.951526)
		(end 165.458648 -234.075986)
		(width 0.18288)
		(layer "In6.Cu")
		(net "M_G_CPU1_SB_DQS_DP<0>")
	)
	(segment
		(start 184.38241 -229.806246)
		(end 184.98566 -229.806246)
		(width 0.18288)
		(layer "In6.Cu")
		(net "M_G_CPU1_SB_DQS_DP<0>")
	)
	(segment
		(start 176.707292 -234.29087)
		(end 177.068226 -234.29087)
		(width 0.18288)
		(layer "In6.Cu")
		(net "M_G_CPU1_SB_DQS_DP<0>")
	)
	(segment
		(start 175.16983 -234.15498)
		(end 175.71593 -234.15498)
		(width 0.18288)
		(layer "In6.Cu")
		(net "M_G_CPU1_SB_DQS_DP<0>")
	)
	(segment
		(start 175.71593 -234.15498)
		(end 175.84039 -234.03052)
		(width 0.18288)
		(layer "In6.Cu")
		(net "M_G_CPU1_SB_DQS_DP<0>")
	)
	(segment
		(start 158.904686 -234.392978)
		(end 159.029146 -234.268518)
		(width 0.18288)
		(layer "In6.Cu")
		(net "M_G_CPU1_SB_DQS_DP<0>")
	)
	(segment
		(start 156.574744 -234.392978)
		(end 157.120844 -234.392978)
		(width 0.18288)
		(layer "In6.Cu")
		(net "M_G_CPU1_SB_DQS_DP<0>")
	)
	(segment
		(start 139.364212 -240.41862)
		(end 139.66571 -240.41862)
		(width 0.088646)
		(layer "In6.Cu")
		(net "M_G_CPU1_SB_DQS_DP<0>")
	)
	(segment
		(start 181.395878 -233.532426)
		(end 181.5719 -233.532426)
		(width 0.18288)
		(layer "In6.Cu")
		(net "M_G_CPU1_SB_DQS_DP<0>")
	)
	(segment
		(start 185.934096 -229.033832)
		(end 185.934096 -228.85781)
		(width 0.18288)
		(layer "In6.Cu")
		(net "M_G_CPU1_SB_DQS_DP<0>")
	)
	(segment
		(start 185.37174 -229.420166)
		(end 185.547762 -229.420166)
		(width 0.18288)
		(layer "In6.Cu")
		(net "M_G_CPU1_SB_DQS_DP<0>")
	)
	(segment
		(start 155.62453 -234.392978)
		(end 155.74899 -234.268518)
		(width 0.18288)
		(layer "In6.Cu")
		(net "M_G_CPU1_SB_DQS_DP<0>")
	)
	(segment
		(start 155.07843 -234.392978)
		(end 155.62453 -234.392978)
		(width 0.18288)
		(layer "In6.Cu")
		(net "M_G_CPU1_SB_DQS_DP<0>")
	)
	(segment
		(start 170.471592 -234.86491)
		(end 171.017692 -234.86491)
		(width 0.18288)
		(layer "In6.Cu")
		(net "M_G_CPU1_SB_DQS_DP<0>")
	)
	(segment
		(start 164.089842 -233.336846)
		(end 164.704522 -233.951526)
		(width 0.18288)
		(layer "In6.Cu")
		(net "M_G_CPU1_SB_DQS_DP<0>")
	)
	(segment
		(start 162.144202 -234.604306)
		(end 163.411662 -233.336846)
		(width 0.18288)
		(layer "In6.Cu")
		(net "M_G_CPU1_SB_DQS_DP<0>")
	)
	(segment
		(start 175.84039 -234.03052)
		(end 176.446942 -234.03052)
		(width 0.18288)
		(layer "In6.Cu")
		(net "M_G_CPU1_SB_DQS_DP<0>")
	)
	(segment
		(start 181.958234 -233.146092)
		(end 181.958234 -232.97007)
		(width 0.18288)
		(layer "In6.Cu")
		(net "M_G_CPU1_SB_DQS_DP<0>")
	)
	(segment
		(start 185.547762 -229.420166)
		(end 185.934096 -229.033832)
		(width 0.18288)
		(layer "In6.Cu")
		(net "M_G_CPU1_SB_DQS_DP<0>")
	)
	(segment
		(start 156.450284 -234.268518)
		(end 156.574744 -234.392978)
		(width 0.18288)
		(layer "In6.Cu")
		(net "M_G_CPU1_SB_DQS_DP<0>")
	)
	(segment
		(start 178.136296 -234.02036)
		(end 178.79695 -233.359706)
		(width 0.18288)
		(layer "In6.Cu")
		(net "M_G_CPU1_SB_DQS_DP<0>")
	)
	(segment
		(start 182.574692 -232.529634)
		(end 182.961026 -232.1433)
		(width 0.18288)
		(layer "In6.Cu")
		(net "M_G_CPU1_SB_DQS_DP<0>")
	)
	(segment
		(start 177.068226 -234.29087)
		(end 177.338736 -234.02036)
		(width 0.18288)
		(layer "In6.Cu")
		(net "M_G_CPU1_SB_DQS_DP<0>")
	)
	(segment
		(start 140.419328 -240.05667)
		(end 140.442696 -240.05667)
		(width 0.088646)
		(layer "In6.Cu")
		(net "M_G_CPU1_SB_DQS_DP<0>")
	)
	(segment
		(start 153.58618 -234.392978)
		(end 154.13228 -234.392978)
		(width 0.18288)
		(layer "In6.Cu")
		(net "M_G_CPU1_SB_DQS_DP<0>")
	)
	(segment
		(start 187.61964 -228.502718)
		(end 187.883546 -228.766624)
		(width 0.18288)
		(layer "In6.Cu")
		(net "M_G_CPU1_SB_DQS_DP<0>")
	)
	(segment
		(start 178.79695 -233.359706)
		(end 179.444142 -233.359706)
		(width 0.18288)
		(layer "In6.Cu")
		(net "M_G_CPU1_SB_DQS_DP<0>")
	)
	(segment
		(start 182.961026 -232.1433)
		(end 182.961026 -231.967278)
		(width 0.18288)
		(layer "In6.Cu")
		(net "M_G_CPU1_SB_DQS_DP<0>")
	)
	(segment
		(start 175.04537 -234.03052)
		(end 175.16983 -234.15498)
		(width 0.18288)
		(layer "In6.Cu")
		(net "M_G_CPU1_SB_DQS_DP<0>")
	)
	(segment
		(start 180.002942 -233.918506)
		(end 181.009798 -233.918506)
		(width 0.18288)
		(layer "In6.Cu")
		(net "M_G_CPU1_SB_DQS_DP<0>")
	)
	(segment
		(start 183.347106 -230.84155)
		(end 184.38241 -229.806246)
		(width 0.18288)
		(layer "In6.Cu")
		(net "M_G_CPU1_SB_DQS_DP<0>")
	)
	(segment
		(start 169.801032 -234.98937)
		(end 170.347132 -234.98937)
		(width 0.18288)
		(layer "In6.Cu")
		(net "M_G_CPU1_SB_DQS_DP<0>")
	)
	(segment
		(start 181.958234 -232.97007)
		(end 182.39867 -232.529634)
		(width 0.18288)
		(layer "In6.Cu")
		(net "M_G_CPU1_SB_DQS_DP<0>")
	)
	(segment
		(start 159.029146 -234.268518)
		(end 159.849058 -234.268518)
		(width 0.18288)
		(layer "In6.Cu")
		(net "M_G_CPU1_SB_DQS_DP<0>")
	)
	(segment
		(start 176.446942 -234.03052)
		(end 176.707292 -234.29087)
		(width 0.18288)
		(layer "In6.Cu")
		(net "M_G_CPU1_SB_DQS_DP<0>")
	)
	(segment
		(start 132.50291 -240.342928)
		(end 132.513324 -240.349024)
		(width 0.088646)
		(layer "In6.Cu")
		(net "M_G_CPU1_SB_DQS_DP<0>")
	)
	(segment
		(start 136.262364 -240.342928)
		(end 136.277096 -240.351564)
		(width 0.088646)
		(layer "In6.Cu")
		(net "M_G_CPU1_SB_DQS_DP<0>")
	)
	(segment
		(start 170.347132 -234.98937)
		(end 170.471592 -234.86491)
		(width 0.18288)
		(layer "In6.Cu")
		(net "M_G_CPU1_SB_DQS_DP<0>")
	)
	(segment
		(start 172.338492 -234.86491)
		(end 172.614336 -235.140754)
		(width 0.18288)
		(layer "In6.Cu")
		(net "M_G_CPU1_SB_DQS_DP<0>")
	)
	(segment
		(start 137.202164 -240.342928)
		(end 137.216896 -240.351564)
		(width 0.088646)
		(layer "In6.Cu")
		(net "M_G_CPU1_SB_DQS_DP<0>")
	)
	(segment
		(start 158.234126 -234.268518)
		(end 158.358586 -234.392978)
		(width 0.18288)
		(layer "In6.Cu")
		(net "M_G_CPU1_SB_DQS_DP<0>")
	)
	(segment
		(start 174.460154 -234.03052)
		(end 175.04537 -234.03052)
		(width 0.18288)
		(layer "In6.Cu")
		(net "M_G_CPU1_SB_DQS_DP<0>")
	)
	(segment
		(start 181.5719 -233.532426)
		(end 181.958234 -233.146092)
		(width 0.18288)
		(layer "In6.Cu")
		(net "M_G_CPU1_SB_DQS_DP<0>")
	)
	(segment
		(start 164.704522 -233.951526)
		(end 165.334188 -233.951526)
		(width 0.18288)
		(layer "In6.Cu")
		(net "M_G_CPU1_SB_DQS_DP<0>")
	)
	(segment
		(start 184.98566 -229.806246)
		(end 185.37174 -229.420166)
		(width 0.18288)
		(layer "In6.Cu")
		(net "M_G_CPU1_SB_DQS_DP<0>")
	)
	(segment
		(start 167.449754 -234.075986)
		(end 167.574214 -233.951526)
		(width 0.18288)
		(layer "In6.Cu")
		(net "M_G_CPU1_SB_DQS_DP<0>")
	)
	(segment
		(start 154.25674 -234.268518)
		(end 154.95397 -234.268518)
		(width 0.18288)
		(layer "In6.Cu")
		(net "M_G_CPU1_SB_DQS_DP<0>")
	)
	(segment
		(start 166.004748 -234.075986)
		(end 166.129208 -233.951526)
		(width 0.18288)
		(layer "In6.Cu")
		(net "M_G_CPU1_SB_DQS_DP<0>")
	)
	(segment
		(start 169.676572 -234.86491)
		(end 169.801032 -234.98937)
		(width 0.18288)
		(layer "In6.Cu")
		(net "M_G_CPU1_SB_DQS_DP<0>")
	)
	(segment
		(start 166.779194 -233.951526)
		(end 166.903654 -234.075986)
		(width 0.18288)
		(layer "In6.Cu")
		(net "M_G_CPU1_SB_DQS_DP<0>")
	)
	(segment
		(start 140.442696 -240.05667)
		(end 147.089876 -240.05667)
		(width 0.18288)
		(layer "In6.Cu")
		(net "M_G_CPU1_SB_DQS_DP<0>")
	)
	(segment
		(start 166.129208 -233.951526)
		(end 166.779194 -233.951526)
		(width 0.18288)
		(layer "In6.Cu")
		(net "M_G_CPU1_SB_DQS_DP<0>")
	)
	(segment
		(start 154.13228 -234.392978)
		(end 154.25674 -234.268518)
		(width 0.18288)
		(layer "In6.Cu")
		(net "M_G_CPU1_SB_DQS_DP<0>")
	)
	(segment
		(start 154.95397 -234.268518)
		(end 155.07843 -234.392978)
		(width 0.18288)
		(layer "In6.Cu")
		(net "M_G_CPU1_SB_DQS_DP<0>")
	)
	(segment
		(start 173.247304 -234.867196)
		(end 173.623478 -234.867196)
		(width 0.18288)
		(layer "In6.Cu")
		(net "M_G_CPU1_SB_DQS_DP<0>")
	)
	(segment
		(start 127.804164 -240.342928)
		(end 127.818896 -240.351564)
		(width 0.088646)
		(layer "In6.Cu")
		(net "M_G_CPU1_SB_DQS_DP<0>")
	)
	(segment
		(start 183.347106 -231.581198)
		(end 183.347106 -230.84155)
		(width 0.18288)
		(layer "In6.Cu")
		(net "M_G_CPU1_SB_DQS_DP<0>")
	)
	(segment
		(start 182.961026 -231.967278)
		(end 183.347106 -231.581198)
		(width 0.18288)
		(layer "In6.Cu")
		(net "M_G_CPU1_SB_DQS_DP<0>")
	)
	(segment
		(start 129.683764 -240.342928)
		(end 129.698496 -240.351564)
		(width 0.088646)
		(layer "In6.Cu")
		(net "M_G_CPU1_SB_DQS_DP<0>")
	)
	(segment
		(start 140.087604 -239.996726)
		(end 140.359384 -239.996726)
		(width 0.088646)
		(layer "In6.Cu")
		(net "M_G_CPU1_SB_DQS_DP<0>")
	)
	(segment
		(start 168.120314 -233.951526)
		(end 169.033698 -234.86491)
		(width 0.18288)
		(layer "In6.Cu")
		(net "M_G_CPU1_SB_DQS_DP<0>")
	)
	(segment
		(start 185.934096 -228.85781)
		(end 186.451748 -228.340158)
		(width 0.18288)
		(layer "In6.Cu")
		(net "M_G_CPU1_SB_DQS_DP<0>")
	)
	(segment
		(start 163.411662 -233.336846)
		(end 164.089842 -233.336846)
		(width 0.18288)
		(layer "In6.Cu")
		(net "M_G_CPU1_SB_DQS_DP<0>")
	)
	(segment
		(start 130.623564 -240.342928)
		(end 130.638296 -240.351564)
		(width 0.088646)
		(layer "In6.Cu")
		(net "M_G_CPU1_SB_DQS_DP<0>")
	)
	(segment
		(start 171.812712 -234.86491)
		(end 172.338492 -234.86491)
		(width 0.18288)
		(layer "In6.Cu")
		(net "M_G_CPU1_SB_DQS_DP<0>")
	)
	(segment
		(start 136.26211 -240.342674)
		(end 136.262364 -240.342928)
		(width 0.088646)
		(layer "In6.Cu")
		(net "M_G_CPU1_SB_DQS_DP<0>")
	)
	(segment
		(start 171.142152 -234.98937)
		(end 171.688252 -234.98937)
		(width 0.18288)
		(layer "In6.Cu")
		(net "M_G_CPU1_SB_DQS_DP<0>")
	)
	(segment
		(start 173.623478 -234.867196)
		(end 174.460154 -234.03052)
		(width 0.18288)
		(layer "In6.Cu")
		(net "M_G_CPU1_SB_DQS_DP<0>")
	)
	(segment
		(start 182.39867 -232.529634)
		(end 182.574692 -232.529634)
		(width 0.18288)
		(layer "In6.Cu")
		(net "M_G_CPU1_SB_DQS_DP<0>")
	)
	(segment
		(start 153.46172 -234.268518)
		(end 153.58618 -234.392978)
		(width 0.18288)
		(layer "In6.Cu")
		(net "M_G_CPU1_SB_DQS_DP<0>")
	)
	(segment
		(start 134.382764 -240.342928)
		(end 134.397496 -240.351564)
		(width 0.088646)
		(layer "In6.Cu")
		(net "M_G_CPU1_SB_DQS_DP<0>")
	)
	(segment
		(start 157.245304 -234.268518)
		(end 158.234126 -234.268518)
		(width 0.18288)
		(layer "In6.Cu")
		(net "M_G_CPU1_SB_DQS_DP<0>")
	)
	(segment
		(start 187.151772 -228.502718)
		(end 187.61964 -228.502718)
		(width 0.18288)
		(layer "In6.Cu")
		(net "M_G_CPU1_SB_DQS_DP<0>")
	)
	(segment
		(start 135.887968 -240.342928)
		(end 135.888222 -240.342674)
		(width 0.088646)
		(layer "In6.Cu")
		(net "M_G_CPU1_SB_DQS_DP<0>")
	)
	(segment
		(start 177.338736 -234.02036)
		(end 178.136296 -234.02036)
		(width 0.18288)
		(layer "In6.Cu")
		(net "M_G_CPU1_SB_DQS_DP<0>")
	)
	(segment
		(start 165.458648 -234.075986)
		(end 166.004748 -234.075986)
		(width 0.18288)
		(layer "In6.Cu")
		(net "M_G_CPU1_SB_DQS_DP<0>")
	)
	(segment
		(start 157.120844 -234.392978)
		(end 157.245304 -234.268518)
		(width 0.18288)
		(layer "In6.Cu")
		(net "M_G_CPU1_SB_DQS_DP<0>")
	)
	(segment
		(start 169.033698 -234.86491)
		(end 169.676572 -234.86491)
		(width 0.18288)
		(layer "In6.Cu")
		(net "M_G_CPU1_SB_DQS_DP<0>")
	)
	(segment
		(start 158.358586 -234.392978)
		(end 158.904686 -234.392978)
		(width 0.18288)
		(layer "In6.Cu")
		(net "M_G_CPU1_SB_DQS_DP<0>")
	)
	(segment
		(start 181.009798 -233.918506)
		(end 181.395878 -233.532426)
		(width 0.18288)
		(layer "In6.Cu")
		(net "M_G_CPU1_SB_DQS_DP<0>")
	)
	(segment
		(start 179.444142 -233.359706)
		(end 180.002942 -233.918506)
		(width 0.18288)
		(layer "In6.Cu")
		(net "M_G_CPU1_SB_DQS_DP<0>")
	)
	(segment
		(start 152.878028 -234.268518)
		(end 153.46172 -234.268518)
		(width 0.18288)
		(layer "In6.Cu")
		(net "M_G_CPU1_SB_DQS_DP<0>")
	)
	(segment
		(start 166.903654 -234.075986)
		(end 167.449754 -234.075986)
		(width 0.18288)
		(layer "In6.Cu")
		(net "M_G_CPU1_SB_DQS_DP<0>")
	)
	(segment
		(start 128.743964 -240.342928)
		(end 128.758696 -240.351564)
		(width 0.088646)
		(layer "In6.Cu")
		(net "M_G_CPU1_SB_DQS_DP<0>")
	)
	(segment
		(start 147.089876 -240.05667)
		(end 152.878028 -234.268518)
		(width 0.18288)
		(layer "In6.Cu")
		(net "M_G_CPU1_SB_DQS_DP<0>")
	)
	(segment
		(start 186.451748 -228.340158)
		(end 186.989212 -228.340158)
		(width 0.18288)
		(layer "In6.Cu")
		(net "M_G_CPU1_SB_DQS_DP<0>")
	)
	(segment
		(start 159.849058 -234.268518)
		(end 161.537396 -234.604306)
		(width 0.18288)
		(layer "In6.Cu")
		(net "M_G_CPU1_SB_DQS_DP<0>")
	)
	(segment
		(start 140.359384 -239.996726)
		(end 140.419328 -240.05667)
		(width 0.088646)
		(layer "In6.Cu")
		(net "M_G_CPU1_SB_DQS_DP<0>")
	)
	(segment
		(start 172.614336 -235.140754)
		(end 172.973746 -235.140754)
		(width 0.18288)
		(layer "In6.Cu")
		(net "M_G_CPU1_SB_DQS_DP<0>")
	)
	(segment
		(start 138.141964 -240.342928)
		(end 138.156696 -240.351564)
		(width 0.088646)
		(layer "In6.Cu")
		(net "M_G_CPU1_SB_DQS_DP<0>")
	)
	(segment
		(start 155.74899 -234.268518)
		(end 156.450284 -234.268518)
		(width 0.18288)
		(layer "In6.Cu")
		(net "M_G_CPU1_SB_DQS_DP<0>")
	)
	(segment
		(start 139.66571 -240.41862)
		(end 140.087604 -239.996726)
		(width 0.088646)
		(layer "In6.Cu")
		(net "M_G_CPU1_SB_DQS_DP<0>")
	)
	(segment
		(start 186.989212 -228.340158)
		(end 187.151772 -228.502718)
		(width 0.18288)
		(layer "In6.Cu")
		(net "M_G_CPU1_SB_DQS_DP<0>")
	)
	(segment
		(start 171.017692 -234.86491)
		(end 171.142152 -234.98937)
		(width 0.18288)
		(layer "In6.Cu")
		(net "M_G_CPU1_SB_DQS_DP<0>")
	)
	(segment
		(start 161.537396 -234.604306)
		(end 162.144202 -234.604306)
		(width 0.18288)
		(layer "In6.Cu")
		(net "M_G_CPU1_SB_DQS_DP<0>")
	)
	(segment
		(start 132.1181 -240.349024)
		(end 132.128514 -240.342928)
		(width 0.088646)
		(layer "In6.Cu")
		(net "M_G_CPU1_SB_DQS_DP<0>")
	)
	(segment
		(start 167.574214 -233.951526)
		(end 168.120314 -233.951526)
		(width 0.18288)
		(layer "In6.Cu")
		(net "M_G_CPU1_SB_DQS_DP<0>")
	)
	(segment
		(start 171.688252 -234.98937)
		(end 171.812712 -234.86491)
		(width 0.18288)
		(layer "In6.Cu")
		(net "M_G_CPU1_SB_DQS_DP<0>")
	)
	(arc
		(start 138.707368 -240.342928)
		(mid 138.894566 -240.292785)
		(end 139.081764 -240.342928)
		(width 0.088646)
		(layer "In6.Cu")
		(net "M_G_CPU1_SB_DQS_DP<0>")
	)
	(arc
		(start 131.563364 -240.342928)
		(mid 131.839923 -240.418637)
		(end 132.1181 -240.349024)
		(width 0.088646)
		(layer "In6.Cu")
		(net "M_G_CPU1_SB_DQS_DP<0>")
	)
	(arc
		(start 130.249168 -240.342928)
		(mid 130.436366 -240.292785)
		(end 130.623564 -240.342928)
		(width 0.088646)
		(layer "In6.Cu")
		(net "M_G_CPU1_SB_DQS_DP<0>")
	)
	(arc
		(start 138.156696 -240.351564)
		(mid 138.433137 -240.41873)
		(end 138.707368 -240.342928)
		(width 0.088646)
		(layer "In6.Cu")
		(net "M_G_CPU1_SB_DQS_DP<0>")
	)
	(arc
		(start 134.397496 -240.351564)
		(mid 134.673937 -240.41873)
		(end 134.948168 -240.342928)
		(width 0.088646)
		(layer "In6.Cu")
		(net "M_G_CPU1_SB_DQS_DP<0>")
	)
	(arc
		(start 129.698496 -240.351564)
		(mid 129.974937 -240.41873)
		(end 130.249168 -240.342928)
		(width 0.088646)
		(layer "In6.Cu")
		(net "M_G_CPU1_SB_DQS_DP<0>")
	)
	(arc
		(start 128.758696 -240.351564)
		(mid 129.035137 -240.41873)
		(end 129.309368 -240.342928)
		(width 0.088646)
		(layer "In6.Cu")
		(net "M_G_CPU1_SB_DQS_DP<0>")
	)
	(arc
		(start 132.513324 -240.349024)
		(mid 132.791756 -240.418838)
		(end 133.068568 -240.342928)
		(width 0.088646)
		(layer "In6.Cu")
		(net "M_G_CPU1_SB_DQS_DP<0>")
	)
	(arc
		(start 127.818896 -240.351564)
		(mid 128.095337 -240.41873)
		(end 128.369568 -240.342928)
		(width 0.088646)
		(layer "In6.Cu")
		(net "M_G_CPU1_SB_DQS_DP<0>")
	)
	(arc
		(start 137.767568 -240.342928)
		(mid 137.954766 -240.292785)
		(end 138.141964 -240.342928)
		(width 0.088646)
		(layer "In6.Cu")
		(net "M_G_CPU1_SB_DQS_DP<0>")
	)
	(arc
		(start 127.146812 -239.853216)
		(mid 127.461998 -240.11618)
		(end 127.804164 -240.342928)
		(width 0.088646)
		(layer "In6.Cu")
		(net "M_G_CPU1_SB_DQS_DP<0>")
	)
	(arc
		(start 129.309368 -240.342928)
		(mid 129.496566 -240.292785)
		(end 129.683764 -240.342928)
		(width 0.088646)
		(layer "In6.Cu")
		(net "M_G_CPU1_SB_DQS_DP<0>")
	)
	(arc
		(start 134.008368 -240.342928)
		(mid 134.195566 -240.292785)
		(end 134.382764 -240.342928)
		(width 0.088646)
		(layer "In6.Cu")
		(net "M_G_CPU1_SB_DQS_DP<0>")
	)
	(arc
		(start 139.081764 -240.342928)
		(mid 139.218007 -240.399374)
		(end 139.364212 -240.41862)
		(width 0.088646)
		(layer "In6.Cu")
		(net "M_G_CPU1_SB_DQS_DP<0>")
	)
	(arc
		(start 137.216896 -240.351564)
		(mid 137.493337 -240.41873)
		(end 137.767568 -240.342928)
		(width 0.088646)
		(layer "In6.Cu")
		(net "M_G_CPU1_SB_DQS_DP<0>")
	)
	(arc
		(start 128.369568 -240.342928)
		(mid 128.556766 -240.292785)
		(end 128.743964 -240.342928)
		(width 0.088646)
		(layer "In6.Cu")
		(net "M_G_CPU1_SB_DQS_DP<0>")
	)
	(arc
		(start 132.128514 -240.342928)
		(mid 132.315712 -240.292785)
		(end 132.50291 -240.342928)
		(width 0.088646)
		(layer "In6.Cu")
		(net "M_G_CPU1_SB_DQS_DP<0>")
	)
	(arc
		(start 134.948168 -240.342928)
		(mid 135.135366 -240.292785)
		(end 135.322564 -240.342928)
		(width 0.088646)
		(layer "In6.Cu")
		(net "M_G_CPU1_SB_DQS_DP<0>")
	)
	(arc
		(start 135.888222 -240.342674)
		(mid 136.075166 -240.29259)
		(end 136.26211 -240.342674)
		(width 0.088646)
		(layer "In6.Cu")
		(net "M_G_CPU1_SB_DQS_DP<0>")
	)
	(arc
		(start 130.638296 -240.351564)
		(mid 130.914737 -240.41873)
		(end 131.188968 -240.342928)
		(width 0.088646)
		(layer "In6.Cu")
		(net "M_G_CPU1_SB_DQS_DP<0>")
	)
	(arc
		(start 135.322564 -240.342928)
		(mid 135.605266 -240.41867)
		(end 135.887968 -240.342928)
		(width 0.088646)
		(layer "In6.Cu")
		(net "M_G_CPU1_SB_DQS_DP<0>")
	)
	(arc
		(start 136.277096 -240.351564)
		(mid 136.553537 -240.41873)
		(end 136.827768 -240.342928)
		(width 0.088646)
		(layer "In6.Cu")
		(net "M_G_CPU1_SB_DQS_DP<0>")
	)
	(arc
		(start 131.188968 -240.342928)
		(mid 131.376166 -240.292785)
		(end 131.563364 -240.342928)
		(width 0.088646)
		(layer "In6.Cu")
		(net "M_G_CPU1_SB_DQS_DP<0>")
	)
	(arc
		(start 133.442964 -240.342928)
		(mid 133.725666 -240.41867)
		(end 134.008368 -240.342928)
		(width 0.088646)
		(layer "In6.Cu")
		(net "M_G_CPU1_SB_DQS_DP<0>")
	)
	(arc
		(start 133.068568 -240.342928)
		(mid 133.255766 -240.292785)
		(end 133.442964 -240.342928)
		(width 0.088646)
		(layer "In6.Cu")
		(net "M_G_CPU1_SB_DQS_DP<0>")
	)
	(arc
		(start 136.827768 -240.342928)
		(mid 137.014966 -240.292785)
		(end 137.202164 -240.342928)
		(width 0.088646)
		(layer "In6.Cu")
		(net "M_G_CPU1_SB_DQS_DP<0>")
	)
	(segment
		(start 189.818772 -237.54842)
		(end 190.524638 -237.54842)
		(width 0.20066)
		(layer "F.Cu")
		(net "M_G_CPU1_SB_DQS_DN<9>")
	)
	(segment
		(start 191.845184 -237.691676)
		(end 191.914018 -237.691676)
		(width 0.101854)
		(layer "F.Cu")
		(net "M_G_CPU1_SB_DQS_DN<9>")
	)
	(segment
		(start 195.942966 -237.266734)
		(end 196.532246 -237.266734)
		(width 0.20066)
		(layer "F.Cu")
		(net "M_G_CPU1_SB_DQS_DN<9>")
	)
	(segment
		(start 194.428364 -237.691676)
		(end 194.654424 -237.917736)
		(width 0.20066)
		(layer "F.Cu")
		(net "M_G_CPU1_SB_DQS_DN<9>")
	)
	(segment
		(start 190.939166 -237.962948)
		(end 191.490854 -237.962948)
		(width 0.20066)
		(layer "F.Cu")
		(net "M_G_CPU1_SB_DQS_DN<9>")
	)
	(segment
		(start 191.914018 -237.691676)
		(end 194.093592 -237.691676)
		(width 0.1016)
		(layer "F.Cu")
		(net "M_G_CPU1_SB_DQS_DN<9>")
	)
	(segment
		(start 194.277742 -237.691676)
		(end 194.428364 -237.691676)
		(width 0.20066)
		(layer "F.Cu")
		(net "M_G_CPU1_SB_DQS_DN<9>")
	)
	(segment
		(start 194.959478 -237.917736)
		(end 195.369942 -237.507272)
		(width 0.20066)
		(layer "F.Cu")
		(net "M_G_CPU1_SB_DQS_DN<9>")
	)
	(segment
		(start 187.883546 -237.266734)
		(end 188.988446 -237.266734)
		(width 0.20066)
		(layer "F.Cu")
		(net "M_G_CPU1_SB_DQS_DN<9>")
	)
	(segment
		(start 191.490854 -237.962948)
		(end 191.762126 -237.691676)
		(width 0.20066)
		(layer "F.Cu")
		(net "M_G_CPU1_SB_DQS_DN<9>")
	)
	(segment
		(start 195.702428 -237.507272)
		(end 195.942966 -237.266734)
		(width 0.20066)
		(layer "F.Cu")
		(net "M_G_CPU1_SB_DQS_DN<9>")
	)
	(segment
		(start 195.369942 -237.507272)
		(end 195.702428 -237.507272)
		(width 0.20066)
		(layer "F.Cu")
		(net "M_G_CPU1_SB_DQS_DN<9>")
	)
	(segment
		(start 194.093592 -237.691676)
		(end 194.277742 -237.691676)
		(width 0.101854)
		(layer "F.Cu")
		(net "M_G_CPU1_SB_DQS_DN<9>")
	)
	(segment
		(start 189.537086 -237.266734)
		(end 189.818772 -237.54842)
		(width 0.20066)
		(layer "F.Cu")
		(net "M_G_CPU1_SB_DQS_DN<9>")
	)
	(segment
		(start 190.524638 -237.54842)
		(end 190.939166 -237.962948)
		(width 0.20066)
		(layer "F.Cu")
		(net "M_G_CPU1_SB_DQS_DN<9>")
	)
	(segment
		(start 191.762126 -237.691676)
		(end 191.845184 -237.691676)
		(width 0.20066)
		(layer "F.Cu")
		(net "M_G_CPU1_SB_DQS_DN<9>")
	)
	(segment
		(start 130.436112 -242.830858)
		(end 130.436366 -242.830604)
		(width 0.20066)
		(layer "F.Cu")
		(net "M_G_CPU1_SB_DQS_DN<9>")
	)
	(segment
		(start 194.654424 -237.917736)
		(end 194.959478 -237.917736)
		(width 0.20066)
		(layer "F.Cu")
		(net "M_G_CPU1_SB_DQS_DN<9>")
	)
	(segment
		(start 188.988446 -237.266734)
		(end 189.537086 -237.266734)
		(width 0.20066)
		(layer "F.Cu")
		(net "M_G_CPU1_SB_DQS_DN<9>")
	)
	(segment
		(start 130.436366 -242.830604)
		(end 130.436366 -242.294918)
		(width 0.20066)
		(layer "F.Cu")
		(net "M_G_CPU1_SB_DQS_DN<9>")
	)
	(segment
		(start 183.009286 -237.184946)
		(end 182.463186 -237.184946)
		(width 0.18288)
		(layer "In4.Cu")
		(net "M_G_CPU1_SB_DQS_DN<9>")
	)
	(segment
		(start 140.315696 -242.107212)
		(end 140.292328 -242.107212)
		(width 0.088646)
		(layer "In4.Cu")
		(net "M_G_CPU1_SB_DQS_DN<9>")
	)
	(segment
		(start 174.500286 -237.942374)
		(end 173.641512 -238.801148)
		(width 0.18288)
		(layer "In4.Cu")
		(net "M_G_CPU1_SB_DQS_DN<9>")
	)
	(segment
		(start 173.24832 -238.801148)
		(end 172.989748 -238.542576)
		(width 0.18288)
		(layer "In4.Cu")
		(net "M_G_CPU1_SB_DQS_DN<9>")
	)
	(segment
		(start 187.01893 -237.309406)
		(end 186.47283 -237.309406)
		(width 0.18288)
		(layer "In4.Cu")
		(net "M_G_CPU1_SB_DQS_DN<9>")
	)
	(segment
		(start 176.435004 -237.942374)
		(end 174.500286 -237.942374)
		(width 0.18288)
		(layer "In4.Cu")
		(net "M_G_CPU1_SB_DQS_DN<9>")
	)
	(segment
		(start 187.230004 -237.52048)
		(end 187.01893 -237.309406)
		(width 0.18288)
		(layer "In4.Cu")
		(net "M_G_CPU1_SB_DQS_DN<9>")
	)
	(segment
		(start 173.641512 -238.801148)
		(end 173.24832 -238.801148)
		(width 0.18288)
		(layer "In4.Cu")
		(net "M_G_CPU1_SB_DQS_DN<9>")
	)
	(segment
		(start 168.27373 -238.201454)
		(end 166.097712 -238.201454)
		(width 0.18288)
		(layer "In4.Cu")
		(net "M_G_CPU1_SB_DQS_DN<9>")
	)
	(segment
		(start 164.066474 -237.677452)
		(end 163.801552 -237.942374)
		(width 0.18288)
		(layer "In4.Cu")
		(net "M_G_CPU1_SB_DQS_DN<9>")
	)
	(segment
		(start 163.801552 -237.942374)
		(end 163.024312 -237.942374)
		(width 0.18288)
		(layer "In4.Cu")
		(net "M_G_CPU1_SB_DQS_DN<9>")
	)
	(segment
		(start 172.989748 -238.542576)
		(end 172.584872 -238.542576)
		(width 0.18288)
		(layer "In4.Cu")
		(net "M_G_CPU1_SB_DQS_DN<9>")
	)
	(segment
		(start 131.562856 -242.620038)
		(end 131.550918 -242.62715)
		(width 0.088646)
		(layer "In4.Cu")
		(net "M_G_CPU1_SB_DQS_DN<9>")
	)
	(segment
		(start 185.80227 -237.184946)
		(end 185.67781 -237.309406)
		(width 0.18288)
		(layer "In4.Cu")
		(net "M_G_CPU1_SB_DQS_DN<9>")
	)
	(segment
		(start 130.623056 -242.620038)
		(end 130.611118 -242.62715)
		(width 0.088646)
		(layer "In4.Cu")
		(net "M_G_CPU1_SB_DQS_DN<9>")
	)
	(segment
		(start 184.46115 -237.184946)
		(end 184.33669 -237.309406)
		(width 0.18288)
		(layer "In4.Cu")
		(net "M_G_CPU1_SB_DQS_DN<9>")
	)
	(segment
		(start 144.320768 -242.107212)
		(end 140.315696 -242.107212)
		(width 0.18288)
		(layer "In4.Cu")
		(net "M_G_CPU1_SB_DQS_DN<9>")
	)
	(segment
		(start 182.338726 -237.309406)
		(end 178.804062 -237.309406)
		(width 0.18288)
		(layer "In4.Cu")
		(net "M_G_CPU1_SB_DQS_DN<9>")
	)
	(segment
		(start 130.066034 -242.35283)
		(end 130.123692 -242.295172)
		(width 0.088646)
		(layer "In4.Cu")
		(net "M_G_CPU1_SB_DQS_DN<9>")
	)
	(segment
		(start 186.34837 -237.184946)
		(end 185.80227 -237.184946)
		(width 0.18288)
		(layer "In4.Cu")
		(net "M_G_CPU1_SB_DQS_DN<9>")
	)
	(segment
		(start 138.698224 -242.54333)
		(end 138.42492 -242.54333)
		(width 0.088646)
		(layer "In4.Cu")
		(net "M_G_CPU1_SB_DQS_DN<9>")
	)
	(segment
		(start 185.13171 -237.309406)
		(end 185.00725 -237.184946)
		(width 0.18288)
		(layer "In4.Cu")
		(net "M_G_CPU1_SB_DQS_DN<9>")
	)
	(segment
		(start 168.612312 -238.540036)
		(end 168.27373 -238.201454)
		(width 0.18288)
		(layer "In4.Cu")
		(net "M_G_CPU1_SB_DQS_DN<9>")
	)
	(segment
		(start 166.097712 -238.201454)
		(end 165.84295 -237.946692)
		(width 0.18288)
		(layer "In4.Cu")
		(net "M_G_CPU1_SB_DQS_DN<9>")
	)
	(segment
		(start 177.089816 -237.692438)
		(end 176.68494 -237.692438)
		(width 0.18288)
		(layer "In4.Cu")
		(net "M_G_CPU1_SB_DQS_DN<9>")
	)
	(segment
		(start 140.292328 -242.107212)
		(end 140.232638 -242.166902)
		(width 0.088646)
		(layer "In4.Cu")
		(net "M_G_CPU1_SB_DQS_DN<9>")
	)
	(segment
		(start 187.6298 -237.52048)
		(end 187.230004 -237.52048)
		(width 0.18288)
		(layer "In4.Cu")
		(net "M_G_CPU1_SB_DQS_DN<9>")
	)
	(segment
		(start 132.50291 -242.620038)
		(end 132.494528 -242.625118)
		(width 0.088646)
		(layer "In4.Cu")
		(net "M_G_CPU1_SB_DQS_DN<9>")
	)
	(segment
		(start 152.60574 -238.180372)
		(end 151.204168 -239.581944)
		(width 0.18288)
		(layer "In4.Cu")
		(net "M_G_CPU1_SB_DQS_DN<9>")
	)
	(segment
		(start 182.463186 -237.184946)
		(end 182.338726 -237.309406)
		(width 0.18288)
		(layer "In4.Cu")
		(net "M_G_CPU1_SB_DQS_DN<9>")
	)
	(segment
		(start 160.348676 -238.180372)
		(end 152.60574 -238.180372)
		(width 0.18288)
		(layer "In4.Cu")
		(net "M_G_CPU1_SB_DQS_DN<9>")
	)
	(segment
		(start 162.464496 -237.382558)
		(end 161.14649 -237.382558)
		(width 0.18288)
		(layer "In4.Cu")
		(net "M_G_CPU1_SB_DQS_DN<9>")
	)
	(segment
		(start 161.14649 -237.382558)
		(end 160.348676 -238.180372)
		(width 0.18288)
		(layer "In4.Cu")
		(net "M_G_CPU1_SB_DQS_DN<9>")
	)
	(segment
		(start 171.330874 -238.540036)
		(end 168.612312 -238.540036)
		(width 0.18288)
		(layer "In4.Cu")
		(net "M_G_CPU1_SB_DQS_DN<9>")
	)
	(segment
		(start 164.710618 -237.946692)
		(end 164.441378 -237.677452)
		(width 0.18288)
		(layer "In4.Cu")
		(net "M_G_CPU1_SB_DQS_DN<9>")
	)
	(segment
		(start 135.322564 -242.619276)
		(end 135.312404 -242.62588)
		(width 0.088646)
		(layer "In4.Cu")
		(net "M_G_CPU1_SB_DQS_DN<9>")
	)
	(segment
		(start 163.024312 -237.942374)
		(end 162.464496 -237.382558)
		(width 0.18288)
		(layer "In4.Cu")
		(net "M_G_CPU1_SB_DQS_DN<9>")
	)
	(segment
		(start 185.00725 -237.184946)
		(end 184.46115 -237.184946)
		(width 0.18288)
		(layer "In4.Cu")
		(net "M_G_CPU1_SB_DQS_DN<9>")
	)
	(segment
		(start 172.334936 -238.792512)
		(end 171.58335 -238.792512)
		(width 0.18288)
		(layer "In4.Cu")
		(net "M_G_CPU1_SB_DQS_DN<9>")
	)
	(segment
		(start 140.232638 -242.166902)
		(end 139.07516 -242.166902)
		(width 0.088646)
		(layer "In4.Cu")
		(net "M_G_CPU1_SB_DQS_DN<9>")
	)
	(segment
		(start 151.204168 -239.581944)
		(end 146.846036 -239.581944)
		(width 0.18288)
		(layer "In4.Cu")
		(net "M_G_CPU1_SB_DQS_DN<9>")
	)
	(segment
		(start 184.33669 -237.309406)
		(end 183.133746 -237.309406)
		(width 0.18288)
		(layer "In4.Cu")
		(net "M_G_CPU1_SB_DQS_DN<9>")
	)
	(segment
		(start 164.441378 -237.677452)
		(end 164.066474 -237.677452)
		(width 0.18288)
		(layer "In4.Cu")
		(net "M_G_CPU1_SB_DQS_DN<9>")
	)
	(segment
		(start 146.846036 -239.581944)
		(end 144.320768 -242.107212)
		(width 0.18288)
		(layer "In4.Cu")
		(net "M_G_CPU1_SB_DQS_DN<9>")
	)
	(segment
		(start 165.84295 -237.946692)
		(end 164.710618 -237.946692)
		(width 0.18288)
		(layer "In4.Cu")
		(net "M_G_CPU1_SB_DQS_DN<9>")
	)
	(segment
		(start 130.123692 -242.295172)
		(end 130.436366 -242.294918)
		(width 0.088646)
		(layer "In4.Cu")
		(net "M_G_CPU1_SB_DQS_DN<9>")
	)
	(segment
		(start 177.348388 -237.95101)
		(end 177.089816 -237.692438)
		(width 0.18288)
		(layer "In4.Cu")
		(net "M_G_CPU1_SB_DQS_DN<9>")
	)
	(segment
		(start 171.58335 -238.792512)
		(end 171.330874 -238.540036)
		(width 0.18288)
		(layer "In4.Cu")
		(net "M_G_CPU1_SB_DQS_DN<9>")
	)
	(segment
		(start 186.47283 -237.309406)
		(end 186.34837 -237.184946)
		(width 0.18288)
		(layer "In4.Cu")
		(net "M_G_CPU1_SB_DQS_DN<9>")
	)
	(segment
		(start 176.68494 -237.692438)
		(end 176.435004 -237.942374)
		(width 0.18288)
		(layer "In4.Cu")
		(net "M_G_CPU1_SB_DQS_DN<9>")
	)
	(segment
		(start 130.06578 -242.35283)
		(end 130.066034 -242.35283)
		(width 0.088646)
		(layer "In4.Cu")
		(net "M_G_CPU1_SB_DQS_DN<9>")
	)
	(segment
		(start 139.07516 -242.166902)
		(end 139.074906 -242.166648)
		(width 0.088646)
		(layer "In4.Cu")
		(net "M_G_CPU1_SB_DQS_DN<9>")
	)
	(segment
		(start 139.074906 -242.166648)
		(end 138.698224 -242.54333)
		(width 0.088646)
		(layer "In4.Cu")
		(net "M_G_CPU1_SB_DQS_DN<9>")
	)
	(segment
		(start 178.162458 -237.95101)
		(end 177.348388 -237.95101)
		(width 0.18288)
		(layer "In4.Cu")
		(net "M_G_CPU1_SB_DQS_DN<9>")
	)
	(segment
		(start 185.67781 -237.309406)
		(end 185.13171 -237.309406)
		(width 0.18288)
		(layer "In4.Cu")
		(net "M_G_CPU1_SB_DQS_DN<9>")
	)
	(segment
		(start 134.382256 -242.620038)
		(end 134.373874 -242.625118)
		(width 0.088646)
		(layer "In4.Cu")
		(net "M_G_CPU1_SB_DQS_DN<9>")
	)
	(segment
		(start 178.804062 -237.309406)
		(end 178.162458 -237.95101)
		(width 0.18288)
		(layer "In4.Cu")
		(net "M_G_CPU1_SB_DQS_DN<9>")
	)
	(segment
		(start 183.133746 -237.309406)
		(end 183.009286 -237.184946)
		(width 0.18288)
		(layer "In4.Cu")
		(net "M_G_CPU1_SB_DQS_DN<9>")
	)
	(segment
		(start 133.08076 -242.62715)
		(end 133.068822 -242.620038)
		(width 0.088646)
		(layer "In4.Cu")
		(net "M_G_CPU1_SB_DQS_DN<9>")
	)
	(segment
		(start 172.584872 -238.542576)
		(end 172.334936 -238.792512)
		(width 0.18288)
		(layer "In4.Cu")
		(net "M_G_CPU1_SB_DQS_DN<9>")
	)
	(segment
		(start 187.883546 -237.266734)
		(end 187.6298 -237.52048)
		(width 0.18288)
		(layer "In4.Cu")
		(net "M_G_CPU1_SB_DQS_DN<9>")
	)
	(arc
		(start 137.767568 -242.619276)
		(mid 137.484866 -242.543534)
		(end 137.202164 -242.619276)
		(width 0.088646)
		(layer "In4.Cu")
		(net "M_G_CPU1_SB_DQS_DN<9>")
	)
	(arc
		(start 135.887968 -242.619276)
		(mid 135.605266 -242.543534)
		(end 135.322564 -242.619276)
		(width 0.088646)
		(layer "In4.Cu")
		(net "M_G_CPU1_SB_DQS_DN<9>")
	)
	(arc
		(start 133.068822 -242.620038)
		(mid 132.785866 -242.544067)
		(end 132.50291 -242.620038)
		(width 0.088646)
		(layer "In4.Cu")
		(net "M_G_CPU1_SB_DQS_DN<9>")
	)
	(arc
		(start 131.550918 -242.62715)
		(mid 131.368748 -242.670139)
		(end 131.18846 -242.619784)
		(width 0.088646)
		(layer "In4.Cu")
		(net "M_G_CPU1_SB_DQS_DN<9>")
	)
	(arc
		(start 136.262364 -242.619276)
		(mid 136.075166 -242.669419)
		(end 135.887968 -242.619276)
		(width 0.088646)
		(layer "In4.Cu")
		(net "M_G_CPU1_SB_DQS_DN<9>")
	)
	(arc
		(start 130.24866 -242.619784)
		(mid 130.126978 -242.507034)
		(end 130.06578 -242.35283)
		(width 0.088646)
		(layer "In4.Cu")
		(net "M_G_CPU1_SB_DQS_DN<9>")
	)
	(arc
		(start 132.12826 -242.619784)
		(mid 131.845529 -242.544101)
		(end 131.562856 -242.620038)
		(width 0.088646)
		(layer "In4.Cu")
		(net "M_G_CPU1_SB_DQS_DN<9>")
	)
	(arc
		(start 135.312404 -242.62588)
		(mid 135.129256 -242.670112)
		(end 134.94766 -242.619784)
		(width 0.088646)
		(layer "In4.Cu")
		(net "M_G_CPU1_SB_DQS_DN<9>")
	)
	(arc
		(start 136.827768 -242.619276)
		(mid 136.545066 -242.543534)
		(end 136.262364 -242.619276)
		(width 0.088646)
		(layer "In4.Cu")
		(net "M_G_CPU1_SB_DQS_DN<9>")
	)
	(arc
		(start 137.202164 -242.619276)
		(mid 137.014966 -242.669419)
		(end 136.827768 -242.619276)
		(width 0.088646)
		(layer "In4.Cu")
		(net "M_G_CPU1_SB_DQS_DN<9>")
	)
	(arc
		(start 134.373874 -242.625118)
		(mid 134.190307 -242.670055)
		(end 134.008114 -242.619784)
		(width 0.088646)
		(layer "In4.Cu")
		(net "M_G_CPU1_SB_DQS_DN<9>")
	)
	(arc
		(start 134.94766 -242.619784)
		(mid 134.664929 -242.544101)
		(end 134.382256 -242.620038)
		(width 0.088646)
		(layer "In4.Cu")
		(net "M_G_CPU1_SB_DQS_DN<9>")
	)
	(arc
		(start 133.443218 -242.619784)
		(mid 133.262931 -242.670196)
		(end 133.08076 -242.62715)
		(width 0.088646)
		(layer "In4.Cu")
		(net "M_G_CPU1_SB_DQS_DN<9>")
	)
	(arc
		(start 131.18846 -242.619784)
		(mid 130.905729 -242.544101)
		(end 130.623056 -242.620038)
		(width 0.088646)
		(layer "In4.Cu")
		(net "M_G_CPU1_SB_DQS_DN<9>")
	)
	(arc
		(start 132.494528 -242.625118)
		(mid 132.310707 -242.670176)
		(end 132.12826 -242.619784)
		(width 0.088646)
		(layer "In4.Cu")
		(net "M_G_CPU1_SB_DQS_DN<9>")
	)
	(arc
		(start 134.008114 -242.619784)
		(mid 133.725666 -242.544101)
		(end 133.443218 -242.619784)
		(width 0.088646)
		(layer "In4.Cu")
		(net "M_G_CPU1_SB_DQS_DN<9>")
	)
	(arc
		(start 138.42492 -242.54333)
		(mid 138.27845 -242.56269)
		(end 138.141964 -242.619276)
		(width 0.088646)
		(layer "In4.Cu")
		(net "M_G_CPU1_SB_DQS_DN<9>")
	)
	(arc
		(start 138.141964 -242.619276)
		(mid 137.954766 -242.669419)
		(end 137.767568 -242.619276)
		(width 0.088646)
		(layer "In4.Cu")
		(net "M_G_CPU1_SB_DQS_DN<9>")
	)
	(arc
		(start 130.611118 -242.62715)
		(mid 130.428948 -242.670139)
		(end 130.24866 -242.619784)
		(width 0.088646)
		(layer "In4.Cu")
		(net "M_G_CPU1_SB_DQS_DN<9>")
	)
	(segment
		(start 137.019538 -217.882978)
		(end 137.014966 -217.878406)
		(width 0.20066)
		(layer "F.Cu")
		(net "M_G_CPU1_SB_DQS_DN<8>")
	)
	(segment
		(start 199.874378 -199.612504)
		(end 200.128632 -199.866758)
		(width 0.20066)
		(layer "F.Cu")
		(net "M_G_CPU1_SB_DQS_DN<8>")
	)
	(segment
		(start 197.531736 -199.441816)
		(end 197.542658 -199.452738)
		(width 0.1016)
		(layer "F.Cu")
		(net "M_G_CPU1_SB_DQS_DN<8>")
	)
	(segment
		(start 193.088514 -199.866758)
		(end 193.61912 -199.866758)
		(width 0.20066)
		(layer "F.Cu")
		(net "M_G_CPU1_SB_DQS_DN<8>")
	)
	(segment
		(start 200.128632 -199.866758)
		(end 200.632314 -199.866758)
		(width 0.20066)
		(layer "F.Cu")
		(net "M_G_CPU1_SB_DQS_DN<8>")
	)
	(segment
		(start 193.61912 -199.866758)
		(end 193.890392 -199.595486)
		(width 0.20066)
		(layer "F.Cu")
		(net "M_G_CPU1_SB_DQS_DN<8>")
	)
	(segment
		(start 193.890392 -199.595486)
		(end 194.373754 -199.595486)
		(width 0.20066)
		(layer "F.Cu")
		(net "M_G_CPU1_SB_DQS_DN<8>")
	)
	(segment
		(start 191.983614 -199.866758)
		(end 193.088514 -199.866758)
		(width 0.20066)
		(layer "F.Cu")
		(net "M_G_CPU1_SB_DQS_DN<8>")
	)
	(segment
		(start 194.373754 -199.595486)
		(end 194.798696 -199.170544)
		(width 0.20066)
		(layer "F.Cu")
		(net "M_G_CPU1_SB_DQS_DN<8>")
	)
	(segment
		(start 194.921124 -199.170544)
		(end 195.198492 -199.447912)
		(width 0.20066)
		(layer "F.Cu")
		(net "M_G_CPU1_SB_DQS_DN<8>")
	)
	(segment
		(start 198.147178 -199.166988)
		(end 198.637144 -199.166988)
		(width 0.20066)
		(layer "F.Cu")
		(net "M_G_CPU1_SB_DQS_DN<8>")
	)
	(segment
		(start 195.510658 -199.447912)
		(end 195.515484 -199.447912)
		(width 0.101854)
		(layer "F.Cu")
		(net "M_G_CPU1_SB_DQS_DN<8>")
	)
	(segment
		(start 198.637144 -199.166988)
		(end 199.08266 -199.612504)
		(width 0.20066)
		(layer "F.Cu")
		(net "M_G_CPU1_SB_DQS_DN<8>")
	)
	(segment
		(start 197.542658 -199.452738)
		(end 197.861428 -199.452738)
		(width 0.20066)
		(layer "F.Cu")
		(net "M_G_CPU1_SB_DQS_DN<8>")
	)
	(segment
		(start 195.515484 -199.447912)
		(end 195.52158 -199.441816)
		(width 0.1016)
		(layer "F.Cu")
		(net "M_G_CPU1_SB_DQS_DN<8>")
	)
	(segment
		(start 137.014712 -218.414346)
		(end 137.019538 -217.882978)
		(width 0.20066)
		(layer "F.Cu")
		(net "M_G_CPU1_SB_DQS_DN<8>")
	)
	(segment
		(start 195.198492 -199.447912)
		(end 195.510658 -199.447912)
		(width 0.20066)
		(layer "F.Cu")
		(net "M_G_CPU1_SB_DQS_DN<8>")
	)
	(segment
		(start 197.861428 -199.452738)
		(end 198.147178 -199.166988)
		(width 0.20066)
		(layer "F.Cu")
		(net "M_G_CPU1_SB_DQS_DN<8>")
	)
	(segment
		(start 194.798696 -199.170544)
		(end 194.921124 -199.170544)
		(width 0.20066)
		(layer "F.Cu")
		(net "M_G_CPU1_SB_DQS_DN<8>")
	)
	(segment
		(start 199.08266 -199.612504)
		(end 199.874378 -199.612504)
		(width 0.20066)
		(layer "F.Cu")
		(net "M_G_CPU1_SB_DQS_DN<8>")
	)
	(segment
		(start 195.52158 -199.441816)
		(end 197.531736 -199.441816)
		(width 0.1016)
		(layer "F.Cu")
		(net "M_G_CPU1_SB_DQS_DN<8>")
	)
	(segment
		(start 167.781224 -198.119746)
		(end 165.16096 -198.119746)
		(width 0.18288)
		(layer "In6.Cu")
		(net "M_G_CPU1_SB_DQS_DN<8>")
	)
	(segment
		(start 141.596872 -216.946226)
		(end 141.03985 -217.503248)
		(width 0.088646)
		(layer "In6.Cu")
		(net "M_G_CPU1_SB_DQS_DN<8>")
	)
	(segment
		(start 164.338762 -197.725538)
		(end 161.111946 -197.725538)
		(width 0.18288)
		(layer "In6.Cu")
		(net "M_G_CPU1_SB_DQS_DN<8>")
	)
	(segment
		(start 187.39993 -199.18045)
		(end 184.438798 -199.18045)
		(width 0.18288)
		(layer "In6.Cu")
		(net "M_G_CPU1_SB_DQS_DN<8>")
	)
	(segment
		(start 174.430182 -197.926452)
		(end 174.12081 -197.61708)
		(width 0.18288)
		(layer "In6.Cu")
		(net "M_G_CPU1_SB_DQS_DN<8>")
	)
	(segment
		(start 148.695156 -207.276954)
		(end 148.695156 -209.08899)
		(width 0.18288)
		(layer "In6.Cu")
		(net "M_G_CPU1_SB_DQS_DN<8>")
	)
	(segment
		(start 190.066168 -199.802242)
		(end 188.560964 -199.18045)
		(width 0.18288)
		(layer "In6.Cu")
		(net "M_G_CPU1_SB_DQS_DN<8>")
	)
	(segment
		(start 191.731646 -199.61479)
		(end 191.407542 -199.61479)
		(width 0.18288)
		(layer "In6.Cu")
		(net "M_G_CPU1_SB_DQS_DN<8>")
	)
	(segment
		(start 177.10404 -198.590916)
		(end 176.706276 -198.590916)
		(width 0.18288)
		(layer "In6.Cu")
		(net "M_G_CPU1_SB_DQS_DN<8>")
	)
	(segment
		(start 148.695156 -209.08899)
		(end 141.855698 -215.928448)
		(width 0.18288)
		(layer "In6.Cu")
		(net "M_G_CPU1_SB_DQS_DN<8>")
	)
	(segment
		(start 172.977556 -197.740778)
		(end 172.612304 -197.740778)
		(width 0.18288)
		(layer "In6.Cu")
		(net "M_G_CPU1_SB_DQS_DN<8>")
	)
	(segment
		(start 137.26033 -217.583766)
		(end 137.17143 -217.607388)
		(width 0.088646)
		(layer "In6.Cu")
		(net "M_G_CPU1_SB_DQS_DN<8>")
	)
	(segment
		(start 191.983614 -199.866758)
		(end 191.731646 -199.61479)
		(width 0.18288)
		(layer "In6.Cu")
		(net "M_G_CPU1_SB_DQS_DN<8>")
	)
	(segment
		(start 140.586714 -217.554048)
		(end 140.571982 -217.562684)
		(width 0.088646)
		(layer "In6.Cu")
		(net "M_G_CPU1_SB_DQS_DN<8>")
	)
	(segment
		(start 172.345604 -197.474078)
		(end 169.339514 -197.474078)
		(width 0.18288)
		(layer "In6.Cu")
		(net "M_G_CPU1_SB_DQS_DN<8>")
	)
	(segment
		(start 177.931064 -198.456804)
		(end 177.628296 -198.330566)
		(width 0.18288)
		(layer "In6.Cu")
		(net "M_G_CPU1_SB_DQS_DN<8>")
	)
	(segment
		(start 177.628296 -198.330566)
		(end 177.36439 -198.330566)
		(width 0.18288)
		(layer "In6.Cu")
		(net "M_G_CPU1_SB_DQS_DN<8>")
	)
	(segment
		(start 180.137054 -198.521828)
		(end 179.943252 -198.602346)
		(width 0.18288)
		(layer "In6.Cu")
		(net "M_G_CPU1_SB_DQS_DN<8>")
	)
	(segment
		(start 161.111946 -197.725538)
		(end 160.138618 -198.129906)
		(width 0.18288)
		(layer "In6.Cu")
		(net "M_G_CPU1_SB_DQS_DN<8>")
	)
	(segment
		(start 165.16096 -198.119746)
		(end 164.338762 -197.725538)
		(width 0.18288)
		(layer "In6.Cu")
		(net "M_G_CPU1_SB_DQS_DN<8>")
	)
	(segment
		(start 179.357782 -198.958708)
		(end 178.624484 -198.958708)
		(width 0.18288)
		(layer "In6.Cu")
		(net "M_G_CPU1_SB_DQS_DN<8>")
	)
	(segment
		(start 179.749196 -198.796148)
		(end 179.357782 -198.958708)
		(width 0.18288)
		(layer "In6.Cu")
		(net "M_G_CPU1_SB_DQS_DN<8>")
	)
	(segment
		(start 139.646914 -217.554048)
		(end 139.632182 -217.562684)
		(width 0.088646)
		(layer "In6.Cu")
		(net "M_G_CPU1_SB_DQS_DN<8>")
	)
	(segment
		(start 141.855698 -215.928448)
		(end 141.839188 -215.944958)
		(width 0.088646)
		(layer "In6.Cu")
		(net "M_G_CPU1_SB_DQS_DN<8>")
	)
	(segment
		(start 188.560964 -199.18045)
		(end 188.338206 -199.18045)
		(width 0.18288)
		(layer "In6.Cu")
		(net "M_G_CPU1_SB_DQS_DN<8>")
	)
	(segment
		(start 184.438798 -199.18045)
		(end 182.849774 -198.521828)
		(width 0.18288)
		(layer "In6.Cu")
		(net "M_G_CPU1_SB_DQS_DN<8>")
	)
	(segment
		(start 175.421036 -198.338186)
		(end 174.430182 -197.926452)
		(width 0.18288)
		(layer "In6.Cu")
		(net "M_G_CPU1_SB_DQS_DN<8>")
	)
	(segment
		(start 177.36439 -198.330566)
		(end 177.10404 -198.590916)
		(width 0.18288)
		(layer "In6.Cu")
		(net "M_G_CPU1_SB_DQS_DN<8>")
	)
	(segment
		(start 141.03985 -217.503248)
		(end 140.773912 -217.503248)
		(width 0.088646)
		(layer "In6.Cu")
		(net "M_G_CPU1_SB_DQS_DN<8>")
	)
	(segment
		(start 174.12081 -197.61708)
		(end 173.757844 -197.46595)
		(width 0.18288)
		(layer "In6.Cu")
		(net "M_G_CPU1_SB_DQS_DN<8>")
	)
	(segment
		(start 188.338206 -199.18045)
		(end 188.077856 -199.4408)
		(width 0.18288)
		(layer "In6.Cu")
		(net "M_G_CPU1_SB_DQS_DN<8>")
	)
	(segment
		(start 137.17143 -217.607388)
		(end 137.014966 -217.878406)
		(width 0.088646)
		(layer "In6.Cu")
		(net "M_G_CPU1_SB_DQS_DN<8>")
	)
	(segment
		(start 141.596872 -216.102438)
		(end 141.596872 -216.946226)
		(width 0.088646)
		(layer "In6.Cu")
		(net "M_G_CPU1_SB_DQS_DN<8>")
	)
	(segment
		(start 141.754352 -215.944958)
		(end 141.596872 -216.102438)
		(width 0.088646)
		(layer "In6.Cu")
		(net "M_G_CPU1_SB_DQS_DN<8>")
	)
	(segment
		(start 141.839188 -215.944958)
		(end 141.754352 -215.944958)
		(width 0.088646)
		(layer "In6.Cu")
		(net "M_G_CPU1_SB_DQS_DN<8>")
	)
	(segment
		(start 157.842204 -198.129906)
		(end 148.695156 -207.276954)
		(width 0.18288)
		(layer "In6.Cu")
		(net "M_G_CPU1_SB_DQS_DN<8>")
	)
	(segment
		(start 172.612304 -197.740778)
		(end 172.345604 -197.474078)
		(width 0.18288)
		(layer "In6.Cu")
		(net "M_G_CPU1_SB_DQS_DN<8>")
	)
	(segment
		(start 176.706276 -198.590916)
		(end 176.453546 -198.338186)
		(width 0.18288)
		(layer "In6.Cu")
		(net "M_G_CPU1_SB_DQS_DN<8>")
	)
	(segment
		(start 173.757844 -197.46595)
		(end 173.252384 -197.46595)
		(width 0.18288)
		(layer "In6.Cu")
		(net "M_G_CPU1_SB_DQS_DN<8>")
	)
	(segment
		(start 173.252384 -197.46595)
		(end 172.977556 -197.740778)
		(width 0.18288)
		(layer "In6.Cu")
		(net "M_G_CPU1_SB_DQS_DN<8>")
	)
	(segment
		(start 160.138618 -198.129906)
		(end 157.842204 -198.129906)
		(width 0.18288)
		(layer "In6.Cu")
		(net "M_G_CPU1_SB_DQS_DN<8>")
	)
	(segment
		(start 188.077856 -199.4408)
		(end 187.66028 -199.4408)
		(width 0.18288)
		(layer "In6.Cu")
		(net "M_G_CPU1_SB_DQS_DN<8>")
	)
	(segment
		(start 187.66028 -199.4408)
		(end 187.39993 -199.18045)
		(width 0.18288)
		(layer "In6.Cu")
		(net "M_G_CPU1_SB_DQS_DN<8>")
	)
	(segment
		(start 190.464948 -199.802242)
		(end 190.066168 -199.802242)
		(width 0.18288)
		(layer "In6.Cu")
		(net "M_G_CPU1_SB_DQS_DN<8>")
	)
	(segment
		(start 176.453546 -198.338186)
		(end 175.421036 -198.338186)
		(width 0.18288)
		(layer "In6.Cu")
		(net "M_G_CPU1_SB_DQS_DN<8>")
	)
	(segment
		(start 191.407542 -199.61479)
		(end 190.464948 -199.802242)
		(width 0.18288)
		(layer "In6.Cu")
		(net "M_G_CPU1_SB_DQS_DN<8>")
	)
	(segment
		(start 169.339514 -197.474078)
		(end 167.781224 -198.119746)
		(width 0.18288)
		(layer "In6.Cu")
		(net "M_G_CPU1_SB_DQS_DN<8>")
	)
	(segment
		(start 179.943252 -198.602346)
		(end 179.749196 -198.796148)
		(width 0.18288)
		(layer "In6.Cu")
		(net "M_G_CPU1_SB_DQS_DN<8>")
	)
	(segment
		(start 182.849774 -198.521828)
		(end 180.137054 -198.521828)
		(width 0.18288)
		(layer "In6.Cu")
		(net "M_G_CPU1_SB_DQS_DN<8>")
	)
	(segment
		(start 178.296316 -198.822056)
		(end 177.931064 -198.456804)
		(width 0.18288)
		(layer "In6.Cu")
		(net "M_G_CPU1_SB_DQS_DN<8>")
	)
	(segment
		(start 178.624484 -198.958708)
		(end 178.296316 -198.822056)
		(width 0.18288)
		(layer "In6.Cu")
		(net "M_G_CPU1_SB_DQS_DN<8>")
	)
	(arc
		(start 138.707114 -217.554048)
		(mid 138.424666 -217.629663)
		(end 138.142218 -217.554048)
		(width 0.088646)
		(layer "In6.Cu")
		(net "M_G_CPU1_SB_DQS_DN<8>")
	)
	(arc
		(start 137.767822 -217.554048)
		(mid 137.528409 -217.62838)
		(end 137.280396 -217.591894)
		(width 0.088646)
		(layer "In6.Cu")
		(net "M_G_CPU1_SB_DQS_DN<8>")
	)
	(arc
		(start 138.142218 -217.554048)
		(mid 137.95502 -217.503905)
		(end 137.767822 -217.554048)
		(width 0.088646)
		(layer "In6.Cu")
		(net "M_G_CPU1_SB_DQS_DN<8>")
	)
	(arc
		(start 140.02131 -217.554048)
		(mid 139.834112 -217.503905)
		(end 139.646914 -217.554048)
		(width 0.088646)
		(layer "In6.Cu")
		(net "M_G_CPU1_SB_DQS_DN<8>")
	)
	(arc
		(start 137.280396 -217.591894)
		(mid 137.270324 -217.587927)
		(end 137.26033 -217.583766)
		(width 0.088646)
		(layer "In6.Cu")
		(net "M_G_CPU1_SB_DQS_DN<8>")
	)
	(arc
		(start 140.773912 -217.503248)
		(mid 140.676973 -217.516338)
		(end 140.586714 -217.554048)
		(width 0.088646)
		(layer "In6.Cu")
		(net "M_G_CPU1_SB_DQS_DN<8>")
	)
	(arc
		(start 139.08151 -217.554048)
		(mid 138.894312 -217.503905)
		(end 138.707114 -217.554048)
		(width 0.088646)
		(layer "In6.Cu")
		(net "M_G_CPU1_SB_DQS_DN<8>")
	)
	(arc
		(start 139.632182 -217.562684)
		(mid 139.355741 -217.62985)
		(end 139.08151 -217.554048)
		(width 0.088646)
		(layer "In6.Cu")
		(net "M_G_CPU1_SB_DQS_DN<8>")
	)
	(arc
		(start 140.571982 -217.562684)
		(mid 140.295541 -217.62985)
		(end 140.02131 -217.554048)
		(width 0.088646)
		(layer "In6.Cu")
		(net "M_G_CPU1_SB_DQS_DN<8>")
	)
	(segment
		(start 199.08266 -208.962498)
		(end 199.874378 -208.962498)
		(width 0.20066)
		(layer "F.Cu")
		(net "M_G_CPU1_SB_DQS_DN<7>")
	)
	(segment
		(start 197.542658 -208.802732)
		(end 197.861428 -208.802732)
		(width 0.20066)
		(layer "F.Cu")
		(net "M_G_CPU1_SB_DQS_DN<7>")
	)
	(segment
		(start 191.983614 -209.216752)
		(end 193.088514 -209.216752)
		(width 0.20066)
		(layer "F.Cu")
		(net "M_G_CPU1_SB_DQS_DN<7>")
	)
	(segment
		(start 194.373754 -208.94548)
		(end 194.798696 -208.520538)
		(width 0.20066)
		(layer "F.Cu")
		(net "M_G_CPU1_SB_DQS_DN<7>")
	)
	(segment
		(start 200.128632 -209.216752)
		(end 200.632314 -209.216752)
		(width 0.20066)
		(layer "F.Cu")
		(net "M_G_CPU1_SB_DQS_DN<7>")
	)
	(segment
		(start 194.921124 -208.520538)
		(end 195.198492 -208.797906)
		(width 0.20066)
		(layer "F.Cu")
		(net "M_G_CPU1_SB_DQS_DN<7>")
	)
	(segment
		(start 193.61912 -209.216752)
		(end 193.890392 -208.94548)
		(width 0.20066)
		(layer "F.Cu")
		(net "M_G_CPU1_SB_DQS_DN<7>")
	)
	(segment
		(start 195.515484 -208.797906)
		(end 195.52158 -208.79181)
		(width 0.1016)
		(layer "F.Cu")
		(net "M_G_CPU1_SB_DQS_DN<7>")
	)
	(segment
		(start 195.198492 -208.797906)
		(end 195.510658 -208.797906)
		(width 0.20066)
		(layer "F.Cu")
		(net "M_G_CPU1_SB_DQS_DN<7>")
	)
	(segment
		(start 197.531736 -208.79181)
		(end 197.542658 -208.802732)
		(width 0.1016)
		(layer "F.Cu")
		(net "M_G_CPU1_SB_DQS_DN<7>")
	)
	(segment
		(start 193.088514 -209.216752)
		(end 193.61912 -209.216752)
		(width 0.20066)
		(layer "F.Cu")
		(net "M_G_CPU1_SB_DQS_DN<7>")
	)
	(segment
		(start 132.315712 -232.528618)
		(end 132.315966 -232.528364)
		(width 0.20066)
		(layer "F.Cu")
		(net "M_G_CPU1_SB_DQS_DN<7>")
	)
	(segment
		(start 132.315712 -233.064304)
		(end 132.315712 -232.528618)
		(width 0.20066)
		(layer "F.Cu")
		(net "M_G_CPU1_SB_DQS_DN<7>")
	)
	(segment
		(start 195.510658 -208.797906)
		(end 195.515484 -208.797906)
		(width 0.101854)
		(layer "F.Cu")
		(net "M_G_CPU1_SB_DQS_DN<7>")
	)
	(segment
		(start 193.890392 -208.94548)
		(end 194.373754 -208.94548)
		(width 0.20066)
		(layer "F.Cu")
		(net "M_G_CPU1_SB_DQS_DN<7>")
	)
	(segment
		(start 194.798696 -208.520538)
		(end 194.921124 -208.520538)
		(width 0.20066)
		(layer "F.Cu")
		(net "M_G_CPU1_SB_DQS_DN<7>")
	)
	(segment
		(start 197.861428 -208.802732)
		(end 198.147178 -208.516982)
		(width 0.20066)
		(layer "F.Cu")
		(net "M_G_CPU1_SB_DQS_DN<7>")
	)
	(segment
		(start 195.52158 -208.79181)
		(end 197.531736 -208.79181)
		(width 0.1016)
		(layer "F.Cu")
		(net "M_G_CPU1_SB_DQS_DN<7>")
	)
	(segment
		(start 198.147178 -208.516982)
		(end 198.637144 -208.516982)
		(width 0.20066)
		(layer "F.Cu")
		(net "M_G_CPU1_SB_DQS_DN<7>")
	)
	(segment
		(start 199.874378 -208.962498)
		(end 200.128632 -209.216752)
		(width 0.20066)
		(layer "F.Cu")
		(net "M_G_CPU1_SB_DQS_DN<7>")
	)
	(segment
		(start 198.637144 -208.516982)
		(end 199.08266 -208.962498)
		(width 0.20066)
		(layer "F.Cu")
		(net "M_G_CPU1_SB_DQS_DN<7>")
	)
	(segment
		(start 190.874142 -208.51876)
		(end 190.560706 -208.51876)
		(width 0.18288)
		(layer "In4.Cu")
		(net "M_G_CPU1_SB_DQS_DN<7>")
	)
	(segment
		(start 160.883092 -211.73567)
		(end 159.333946 -211.73567)
		(width 0.18288)
		(layer "In4.Cu")
		(net "M_G_CPU1_SB_DQS_DN<7>")
	)
	(segment
		(start 178.305968 -211.91093)
		(end 177.371248 -211.91093)
		(width 0.18288)
		(layer "In4.Cu")
		(net "M_G_CPU1_SB_DQS_DN<7>")
	)
	(segment
		(start 190.560706 -208.51876)
		(end 190.285624 -208.793842)
		(width 0.18288)
		(layer "In4.Cu")
		(net "M_G_CPU1_SB_DQS_DN<7>")
	)
	(segment
		(start 138.707368 -228.948488)
		(end 138.693144 -228.956616)
		(width 0.088646)
		(layer "In4.Cu")
		(net "M_G_CPU1_SB_DQS_DN<7>")
	)
	(segment
		(start 137.110216 -231.714548)
		(end 137.110216 -231.73309)
		(width 0.088646)
		(layer "In4.Cu")
		(net "M_G_CPU1_SB_DQS_DN<7>")
	)
	(segment
		(start 186.371992 -208.256124)
		(end 184.791858 -208.256124)
		(width 0.18288)
		(layer "In4.Cu")
		(net "M_G_CPU1_SB_DQS_DN<7>")
	)
	(segment
		(start 176.388014 -211.877656)
		(end 174.892208 -211.877656)
		(width 0.18288)
		(layer "In4.Cu")
		(net "M_G_CPU1_SB_DQS_DN<7>")
	)
	(segment
		(start 166.617142 -211.840826)
		(end 166.492682 -211.716366)
		(width 0.18288)
		(layer "In4.Cu")
		(net "M_G_CPU1_SB_DQS_DN<7>")
	)
	(segment
		(start 172.312584 -211.05241)
		(end 171.499022 -211.05241)
		(width 0.18288)
		(layer "In4.Cu")
		(net "M_G_CPU1_SB_DQS_DN<7>")
	)
	(segment
		(start 133.442964 -232.20426)
		(end 133.44271 -232.204006)
		(width 0.088646)
		(layer "In4.Cu")
		(net "M_G_CPU1_SB_DQS_DN<7>")
	)
	(segment
		(start 161.296096 -211.322666)
		(end 160.883092 -211.73567)
		(width 0.18288)
		(layer "In4.Cu")
		(net "M_G_CPU1_SB_DQS_DN<7>")
	)
	(segment
		(start 136.827768 -232.20426)
		(end 136.827768 -232.204006)
		(width 0.088646)
		(layer "In4.Cu")
		(net "M_G_CPU1_SB_DQS_DN<7>")
	)
	(segment
		(start 191.676782 -208.93532)
		(end 191.467232 -208.93532)
		(width 0.18288)
		(layer "In4.Cu")
		(net "M_G_CPU1_SB_DQS_DN<7>")
	)
	(segment
		(start 189.600078 -208.492344)
		(end 188.377322 -208.492344)
		(width 0.18288)
		(layer "In4.Cu")
		(net "M_G_CPU1_SB_DQS_DN<7>")
	)
	(segment
		(start 159.333946 -211.73567)
		(end 159.209486 -211.86013)
		(width 0.18288)
		(layer "In4.Cu")
		(net "M_G_CPU1_SB_DQS_DN<7>")
	)
	(segment
		(start 165.946582 -211.716366)
		(end 165.822122 -211.840826)
		(width 0.18288)
		(layer "In4.Cu")
		(net "M_G_CPU1_SB_DQS_DN<7>")
	)
	(segment
		(start 182.76062 -210.288378)
		(end 182.428134 -210.426046)
		(width 0.18288)
		(layer "In4.Cu")
		(net "M_G_CPU1_SB_DQS_DN<7>")
	)
	(segment
		(start 188.377322 -208.492344)
		(end 188.075824 -208.793842)
		(width 0.18288)
		(layer "In4.Cu")
		(net "M_G_CPU1_SB_DQS_DN<7>")
	)
	(segment
		(start 173.27118 -211.061046)
		(end 172.988224 -211.344002)
		(width 0.18288)
		(layer "In4.Cu")
		(net "M_G_CPU1_SB_DQS_DN<7>")
	)
	(segment
		(start 138.237468 -229.762304)
		(end 138.228578 -229.767384)
		(width 0.088646)
		(layer "In4.Cu")
		(net "M_G_CPU1_SB_DQS_DN<7>")
	)
	(segment
		(start 174.075598 -211.061046)
		(end 173.27118 -211.061046)
		(width 0.18288)
		(layer "In4.Cu")
		(net "M_G_CPU1_SB_DQS_DN<7>")
	)
	(segment
		(start 169.953686 -211.256626)
		(end 168.787826 -211.256626)
		(width 0.18288)
		(layer "In4.Cu")
		(net "M_G_CPU1_SB_DQS_DN<7>")
	)
	(segment
		(start 168.787826 -211.256626)
		(end 168.328086 -211.716366)
		(width 0.18288)
		(layer "In4.Cu")
		(net "M_G_CPU1_SB_DQS_DN<7>")
	)
	(segment
		(start 170.748706 -211.256626)
		(end 170.624246 -211.381086)
		(width 0.18288)
		(layer "In4.Cu")
		(net "M_G_CPU1_SB_DQS_DN<7>")
	)
	(segment
		(start 158.663386 -211.86013)
		(end 158.538926 -211.73567)
		(width 0.18288)
		(layer "In4.Cu")
		(net "M_G_CPU1_SB_DQS_DN<7>")
	)
	(segment
		(start 179.790852 -210.426046)
		(end 178.305968 -211.91093)
		(width 0.18288)
		(layer "In4.Cu")
		(net "M_G_CPU1_SB_DQS_DN<7>")
	)
	(segment
		(start 170.624246 -211.381086)
		(end 170.078146 -211.381086)
		(width 0.18288)
		(layer "In4.Cu")
		(net "M_G_CPU1_SB_DQS_DN<7>")
	)
	(segment
		(start 183.884824 -209.163158)
		(end 183.884824 -209.33918)
		(width 0.18288)
		(layer "In4.Cu")
		(net "M_G_CPU1_SB_DQS_DN<7>")
	)
	(segment
		(start 191.16294 -208.807558)
		(end 190.874142 -208.51876)
		(width 0.18288)
		(layer "In4.Cu")
		(net "M_G_CPU1_SB_DQS_DN<7>")
	)
	(segment
		(start 177.088292 -212.193886)
		(end 176.704244 -212.193886)
		(width 0.18288)
		(layer "In4.Cu")
		(net "M_G_CPU1_SB_DQS_DN<7>")
	)
	(segment
		(start 187.400184 -208.50225)
		(end 186.966352 -208.50225)
		(width 0.18288)
		(layer "In4.Cu")
		(net "M_G_CPU1_SB_DQS_DN<7>")
	)
	(segment
		(start 163.199318 -211.322666)
		(end 163.074858 -211.447126)
		(width 0.18288)
		(layer "In4.Cu")
		(net "M_G_CPU1_SB_DQS_DN<7>")
	)
	(segment
		(start 181.11343 -210.550506)
		(end 180.98897 -210.426046)
		(width 0.18288)
		(layer "In4.Cu")
		(net "M_G_CPU1_SB_DQS_DN<7>")
	)
	(segment
		(start 137.297668 -231.39019)
		(end 137.288778 -231.39527)
		(width 0.088646)
		(layer "In4.Cu")
		(net "M_G_CPU1_SB_DQS_DN<7>")
	)
	(segment
		(start 190.285624 -208.793842)
		(end 189.901576 -208.793842)
		(width 0.18288)
		(layer "In4.Cu")
		(net "M_G_CPU1_SB_DQS_DN<7>")
	)
	(segment
		(start 182.936388 -210.111594)
		(end 182.936896 -210.112102)
		(width 0.18288)
		(layer "In4.Cu")
		(net "M_G_CPU1_SB_DQS_DN<7>")
	)
	(segment
		(start 176.704244 -212.193886)
		(end 176.388014 -211.877656)
		(width 0.18288)
		(layer "In4.Cu")
		(net "M_G_CPU1_SB_DQS_DN<7>")
	)
	(segment
		(start 183.322468 -209.725514)
		(end 182.936388 -210.111594)
		(width 0.18288)
		(layer "In4.Cu")
		(net "M_G_CPU1_SB_DQS_DN<7>")
	)
	(segment
		(start 189.901576 -208.793842)
		(end 189.600078 -208.492344)
		(width 0.18288)
		(layer "In4.Cu")
		(net "M_G_CPU1_SB_DQS_DN<7>")
	)
	(segment
		(start 172.604176 -211.344002)
		(end 172.312584 -211.05241)
		(width 0.18288)
		(layer "In4.Cu")
		(net "M_G_CPU1_SB_DQS_DN<7>")
	)
	(segment
		(start 133.068314 -232.204006)
		(end 132.935726 -232.28046)
		(width 0.088646)
		(layer "In4.Cu")
		(net "M_G_CPU1_SB_DQS_DN<7>")
	)
	(segment
		(start 158.538926 -211.73567)
		(end 157.992826 -211.73567)
		(width 0.18288)
		(layer "In4.Cu")
		(net "M_G_CPU1_SB_DQS_DN<7>")
	)
	(segment
		(start 165.822122 -211.840826)
		(end 165.276022 -211.840826)
		(width 0.18288)
		(layer "In4.Cu")
		(net "M_G_CPU1_SB_DQS_DN<7>")
	)
	(segment
		(start 191.175386 -208.813908)
		(end 191.16294 -208.807558)
		(width 0.18288)
		(layer "In4.Cu")
		(net "M_G_CPU1_SB_DQS_DN<7>")
	)
	(segment
		(start 171.294806 -211.256626)
		(end 170.748706 -211.256626)
		(width 0.18288)
		(layer "In4.Cu")
		(net "M_G_CPU1_SB_DQS_DN<7>")
	)
	(segment
		(start 134.008368 -232.204006)
		(end 133.997954 -232.210102)
		(width 0.088646)
		(layer "In4.Cu")
		(net "M_G_CPU1_SB_DQS_DN<7>")
	)
	(segment
		(start 138.519916 -229.272592)
		(end 138.519916 -229.282752)
		(width 0.088646)
		(layer "In4.Cu")
		(net "M_G_CPU1_SB_DQS_DN<7>")
	)
	(segment
		(start 172.988224 -211.344002)
		(end 172.604176 -211.344002)
		(width 0.18288)
		(layer "In4.Cu")
		(net "M_G_CPU1_SB_DQS_DN<7>")
	)
	(segment
		(start 177.371248 -211.91093)
		(end 177.088292 -212.193886)
		(width 0.18288)
		(layer "In4.Cu")
		(net "M_G_CPU1_SB_DQS_DN<7>")
	)
	(segment
		(start 164.605462 -211.716366)
		(end 164.211762 -211.322666)
		(width 0.18288)
		(layer "In4.Cu")
		(net "M_G_CPU1_SB_DQS_DN<7>")
	)
	(segment
		(start 159.209486 -211.86013)
		(end 158.663386 -211.86013)
		(width 0.18288)
		(layer "In4.Cu")
		(net "M_G_CPU1_SB_DQS_DN<7>")
	)
	(segment
		(start 165.276022 -211.840826)
		(end 165.151562 -211.716366)
		(width 0.18288)
		(layer "In4.Cu")
		(net "M_G_CPU1_SB_DQS_DN<7>")
	)
	(segment
		(start 132.783834 -232.3211)
		(end 132.390388 -232.3211)
		(width 0.088646)
		(layer "In4.Cu")
		(net "M_G_CPU1_SB_DQS_DN<7>")
	)
	(segment
		(start 182.936896 -210.112102)
		(end 182.76062 -210.288378)
		(width 0.18288)
		(layer "In4.Cu")
		(net "M_G_CPU1_SB_DQS_DN<7>")
	)
	(segment
		(start 183.884824 -209.33918)
		(end 183.49849 -209.725514)
		(width 0.18288)
		(layer "In4.Cu")
		(net "M_G_CPU1_SB_DQS_DN<7>")
	)
	(segment
		(start 132.315966 -232.395522)
		(end 132.315966 -232.528364)
		(width 0.088646)
		(layer "In4.Cu")
		(net "M_G_CPU1_SB_DQS_DN<7>")
	)
	(segment
		(start 188.075824 -208.793842)
		(end 187.691776 -208.793842)
		(width 0.18288)
		(layer "In4.Cu")
		(net "M_G_CPU1_SB_DQS_DN<7>")
	)
	(segment
		(start 171.499022 -211.05241)
		(end 171.294806 -211.256626)
		(width 0.18288)
		(layer "In4.Cu")
		(net "M_G_CPU1_SB_DQS_DN<7>")
	)
	(segment
		(start 138.050016 -230.086662)
		(end 138.050016 -230.096568)
		(width 0.088646)
		(layer "In4.Cu")
		(net "M_G_CPU1_SB_DQS_DN<7>")
	)
	(segment
		(start 164.211762 -211.322666)
		(end 163.199318 -211.322666)
		(width 0.18288)
		(layer "In4.Cu")
		(net "M_G_CPU1_SB_DQS_DN<7>")
	)
	(segment
		(start 191.467232 -208.93532)
		(end 191.175386 -208.813908)
		(width 0.18288)
		(layer "In4.Cu")
		(net "M_G_CPU1_SB_DQS_DN<7>")
	)
	(segment
		(start 140.749274 -226.993704)
		(end 140.68933 -226.93376)
		(width 0.088646)
		(layer "In4.Cu")
		(net "M_G_CPU1_SB_DQS_DN<7>")
	)
	(segment
		(start 140.772642 -226.993704)
		(end 140.749274 -226.993704)
		(width 0.088646)
		(layer "In4.Cu")
		(net "M_G_CPU1_SB_DQS_DN<7>")
	)
	(segment
		(start 170.078146 -211.381086)
		(end 169.953686 -211.256626)
		(width 0.18288)
		(layer "In4.Cu")
		(net "M_G_CPU1_SB_DQS_DN<7>")
	)
	(segment
		(start 182.428134 -210.426046)
		(end 181.78399 -210.426046)
		(width 0.18288)
		(layer "In4.Cu")
		(net "M_G_CPU1_SB_DQS_DN<7>")
	)
	(segment
		(start 184.791858 -208.256124)
		(end 183.884824 -209.163158)
		(width 0.18288)
		(layer "In4.Cu")
		(net "M_G_CPU1_SB_DQS_DN<7>")
	)
	(segment
		(start 138.99007 -228.431344)
		(end 138.99007 -228.468428)
		(width 0.088646)
		(layer "In4.Cu")
		(net "M_G_CPU1_SB_DQS_DN<7>")
	)
	(segment
		(start 167.163242 -211.840826)
		(end 166.617142 -211.840826)
		(width 0.18288)
		(layer "In4.Cu")
		(net "M_G_CPU1_SB_DQS_DN<7>")
	)
	(segment
		(start 191.958214 -209.216752)
		(end 191.676782 -208.93532)
		(width 0.18288)
		(layer "In4.Cu")
		(net "M_G_CPU1_SB_DQS_DN<7>")
	)
	(segment
		(start 166.492682 -211.716366)
		(end 165.946582 -211.716366)
		(width 0.18288)
		(layer "In4.Cu")
		(net "M_G_CPU1_SB_DQS_DN<7>")
	)
	(segment
		(start 174.892208 -211.877656)
		(end 174.075598 -211.061046)
		(width 0.18288)
		(layer "In4.Cu")
		(net "M_G_CPU1_SB_DQS_DN<7>")
	)
	(segment
		(start 180.98897 -210.426046)
		(end 179.790852 -210.426046)
		(width 0.18288)
		(layer "In4.Cu")
		(net "M_G_CPU1_SB_DQS_DN<7>")
	)
	(segment
		(start 165.151562 -211.716366)
		(end 164.605462 -211.716366)
		(width 0.18288)
		(layer "In4.Cu")
		(net "M_G_CPU1_SB_DQS_DN<7>")
	)
	(segment
		(start 137.767568 -230.57612)
		(end 137.758678 -230.5812)
		(width 0.088646)
		(layer "In4.Cu")
		(net "M_G_CPU1_SB_DQS_DN<7>")
	)
	(segment
		(start 181.65953 -210.550506)
		(end 181.11343 -210.550506)
		(width 0.18288)
		(layer "In4.Cu")
		(net "M_G_CPU1_SB_DQS_DN<7>")
	)
	(segment
		(start 137.580116 -230.900478)
		(end 137.580116 -230.91902)
		(width 0.088646)
		(layer "In4.Cu")
		(net "M_G_CPU1_SB_DQS_DN<7>")
	)
	(segment
		(start 186.966352 -208.50225)
		(end 186.371992 -208.256124)
		(width 0.18288)
		(layer "In4.Cu")
		(net "M_G_CPU1_SB_DQS_DN<7>")
	)
	(segment
		(start 162.404298 -211.322666)
		(end 161.296096 -211.322666)
		(width 0.18288)
		(layer "In4.Cu")
		(net "M_G_CPU1_SB_DQS_DN<7>")
	)
	(segment
		(start 163.074858 -211.447126)
		(end 162.528758 -211.447126)
		(width 0.18288)
		(layer "In4.Cu")
		(net "M_G_CPU1_SB_DQS_DN<7>")
	)
	(segment
		(start 140.487654 -226.93376)
		(end 138.99007 -228.431344)
		(width 0.088646)
		(layer "In4.Cu")
		(net "M_G_CPU1_SB_DQS_DN<7>")
	)
	(segment
		(start 191.983614 -209.216752)
		(end 191.958214 -209.216752)
		(width 0.18288)
		(layer "In4.Cu")
		(net "M_G_CPU1_SB_DQS_DN<7>")
	)
	(segment
		(start 168.328086 -211.716366)
		(end 167.287702 -211.716366)
		(width 0.18288)
		(layer "In4.Cu")
		(net "M_G_CPU1_SB_DQS_DN<7>")
	)
	(segment
		(start 162.528758 -211.447126)
		(end 162.404298 -211.322666)
		(width 0.18288)
		(layer "In4.Cu")
		(net "M_G_CPU1_SB_DQS_DN<7>")
	)
	(segment
		(start 140.68933 -226.93376)
		(end 140.487654 -226.93376)
		(width 0.088646)
		(layer "In4.Cu")
		(net "M_G_CPU1_SB_DQS_DN<7>")
	)
	(segment
		(start 181.78399 -210.426046)
		(end 181.65953 -210.550506)
		(width 0.18288)
		(layer "In4.Cu")
		(net "M_G_CPU1_SB_DQS_DN<7>")
	)
	(segment
		(start 183.49849 -209.725514)
		(end 183.322468 -209.725514)
		(width 0.18288)
		(layer "In4.Cu")
		(net "M_G_CPU1_SB_DQS_DN<7>")
	)
	(segment
		(start 187.691776 -208.793842)
		(end 187.400184 -208.50225)
		(width 0.18288)
		(layer "In4.Cu")
		(net "M_G_CPU1_SB_DQS_DN<7>")
	)
	(segment
		(start 142.734792 -226.993704)
		(end 140.772642 -226.993704)
		(width 0.18288)
		(layer "In4.Cu")
		(net "M_G_CPU1_SB_DQS_DN<7>")
	)
	(segment
		(start 157.992826 -211.73567)
		(end 142.734792 -226.993704)
		(width 0.18288)
		(layer "In4.Cu")
		(net "M_G_CPU1_SB_DQS_DN<7>")
	)
	(segment
		(start 167.287702 -211.716366)
		(end 167.163242 -211.840826)
		(width 0.18288)
		(layer "In4.Cu")
		(net "M_G_CPU1_SB_DQS_DN<7>")
	)
	(segment
		(start 132.935726 -232.28046)
		(end 132.783834 -232.3211)
		(width 0.088646)
		(layer "In4.Cu")
		(net "M_G_CPU1_SB_DQS_DN<7>")
	)
	(arc
		(start 136.262364 -232.204006)
		(mid 136.075166 -232.153863)
		(end 135.887968 -232.204006)
		(width 0.088646)
		(layer "In4.Cu")
		(net "M_G_CPU1_SB_DQS_DN<7>")
	)
	(arc
		(start 136.827768 -232.204006)
		(mid 136.545066 -232.279782)
		(end 136.262364 -232.204006)
		(width 0.088646)
		(layer "In4.Cu")
		(net "M_G_CPU1_SB_DQS_DN<7>")
	)
	(arc
		(start 132.390388 -232.3211)
		(mid 132.337764 -232.342898)
		(end 132.315966 -232.395522)
		(width 0.088646)
		(layer "In4.Cu")
		(net "M_G_CPU1_SB_DQS_DN<7>")
	)
	(arc
		(start 137.110216 -231.73309)
		(mid 137.030054 -232.005279)
		(end 136.827768 -232.20426)
		(width 0.088646)
		(layer "In4.Cu")
		(net "M_G_CPU1_SB_DQS_DN<7>")
	)
	(arc
		(start 135.887968 -232.204006)
		(mid 135.605266 -232.279782)
		(end 135.322564 -232.204006)
		(width 0.088646)
		(layer "In4.Cu")
		(net "M_G_CPU1_SB_DQS_DN<7>")
	)
	(arc
		(start 133.997954 -232.210102)
		(mid 133.719696 -232.27995)
		(end 133.442964 -232.20426)
		(width 0.088646)
		(layer "In4.Cu")
		(net "M_G_CPU1_SB_DQS_DN<7>")
	)
	(arc
		(start 135.322564 -232.204006)
		(mid 135.135366 -232.153863)
		(end 134.948168 -232.204006)
		(width 0.088646)
		(layer "In4.Cu")
		(net "M_G_CPU1_SB_DQS_DN<7>")
	)
	(arc
		(start 138.693144 -228.956616)
		(mid 138.566101 -229.092432)
		(end 138.519916 -229.272592)
		(width 0.088646)
		(layer "In4.Cu")
		(net "M_G_CPU1_SB_DQS_DN<7>")
	)
	(arc
		(start 138.228578 -229.767384)
		(mid 138.097664 -229.903744)
		(end 138.050016 -230.086662)
		(width 0.088646)
		(layer "In4.Cu")
		(net "M_G_CPU1_SB_DQS_DN<7>")
	)
	(arc
		(start 138.99007 -228.468428)
		(mid 138.911932 -228.745669)
		(end 138.707368 -228.948488)
		(width 0.088646)
		(layer "In4.Cu")
		(net "M_G_CPU1_SB_DQS_DN<7>")
	)
	(arc
		(start 138.050016 -230.096568)
		(mid 137.971905 -230.373517)
		(end 137.767568 -230.57612)
		(width 0.088646)
		(layer "In4.Cu")
		(net "M_G_CPU1_SB_DQS_DN<7>")
	)
	(arc
		(start 137.580116 -230.91902)
		(mid 137.499954 -231.191209)
		(end 137.297668 -231.39019)
		(width 0.088646)
		(layer "In4.Cu")
		(net "M_G_CPU1_SB_DQS_DN<7>")
	)
	(arc
		(start 137.758678 -230.5812)
		(mid 137.627764 -230.71756)
		(end 137.580116 -230.900478)
		(width 0.088646)
		(layer "In4.Cu")
		(net "M_G_CPU1_SB_DQS_DN<7>")
	)
	(arc
		(start 134.948168 -232.204006)
		(mid 134.665466 -232.279782)
		(end 134.382764 -232.204006)
		(width 0.088646)
		(layer "In4.Cu")
		(net "M_G_CPU1_SB_DQS_DN<7>")
	)
	(arc
		(start 134.382764 -232.204006)
		(mid 134.195566 -232.153863)
		(end 134.008368 -232.204006)
		(width 0.088646)
		(layer "In4.Cu")
		(net "M_G_CPU1_SB_DQS_DN<7>")
	)
	(arc
		(start 137.288778 -231.39527)
		(mid 137.157864 -231.53163)
		(end 137.110216 -231.714548)
		(width 0.088646)
		(layer "In4.Cu")
		(net "M_G_CPU1_SB_DQS_DN<7>")
	)
	(arc
		(start 138.519916 -229.282752)
		(mid 138.441805 -229.559701)
		(end 138.237468 -229.762304)
		(width 0.088646)
		(layer "In4.Cu")
		(net "M_G_CPU1_SB_DQS_DN<7>")
	)
	(arc
		(start 133.44271 -232.204006)
		(mid 133.255512 -232.153863)
		(end 133.068314 -232.204006)
		(width 0.088646)
		(layer "In4.Cu")
		(net "M_G_CPU1_SB_DQS_DN<7>")
	)
	(segment
		(start 198.637144 -217.866976)
		(end 199.08266 -218.312492)
		(width 0.20066)
		(layer "F.Cu")
		(net "M_G_CPU1_SB_DQS_DN<6>")
	)
	(segment
		(start 199.874378 -218.312492)
		(end 200.128632 -218.566746)
		(width 0.20066)
		(layer "F.Cu")
		(net "M_G_CPU1_SB_DQS_DN<6>")
	)
	(segment
		(start 198.147178 -217.866976)
		(end 198.637144 -217.866976)
		(width 0.20066)
		(layer "F.Cu")
		(net "M_G_CPU1_SB_DQS_DN<6>")
	)
	(segment
		(start 195.52158 -218.141804)
		(end 197.531736 -218.141804)
		(width 0.1016)
		(layer "F.Cu")
		(net "M_G_CPU1_SB_DQS_DN<6>")
	)
	(segment
		(start 197.542658 -218.152726)
		(end 197.861428 -218.152726)
		(width 0.20066)
		(layer "F.Cu")
		(net "M_G_CPU1_SB_DQS_DN<6>")
	)
	(segment
		(start 128.086612 -235.505752)
		(end 128.086612 -234.970066)
		(width 0.20066)
		(layer "F.Cu")
		(net "M_G_CPU1_SB_DQS_DN<6>")
	)
	(segment
		(start 128.086866 -235.506006)
		(end 128.086612 -235.505752)
		(width 0.20066)
		(layer "F.Cu")
		(net "M_G_CPU1_SB_DQS_DN<6>")
	)
	(segment
		(start 193.088514 -218.566746)
		(end 193.61912 -218.566746)
		(width 0.20066)
		(layer "F.Cu")
		(net "M_G_CPU1_SB_DQS_DN<6>")
	)
	(segment
		(start 195.515484 -218.1479)
		(end 195.52158 -218.141804)
		(width 0.1016)
		(layer "F.Cu")
		(net "M_G_CPU1_SB_DQS_DN<6>")
	)
	(segment
		(start 193.61912 -218.566746)
		(end 193.890392 -218.295474)
		(width 0.20066)
		(layer "F.Cu")
		(net "M_G_CPU1_SB_DQS_DN<6>")
	)
	(segment
		(start 194.373754 -218.295474)
		(end 194.798696 -217.870532)
		(width 0.20066)
		(layer "F.Cu")
		(net "M_G_CPU1_SB_DQS_DN<6>")
	)
	(segment
		(start 195.198492 -218.1479)
		(end 195.510658 -218.1479)
		(width 0.20066)
		(layer "F.Cu")
		(net "M_G_CPU1_SB_DQS_DN<6>")
	)
	(segment
		(start 194.921124 -217.870532)
		(end 195.198492 -218.1479)
		(width 0.20066)
		(layer "F.Cu")
		(net "M_G_CPU1_SB_DQS_DN<6>")
	)
	(segment
		(start 197.861428 -218.152726)
		(end 198.147178 -217.866976)
		(width 0.20066)
		(layer "F.Cu")
		(net "M_G_CPU1_SB_DQS_DN<6>")
	)
	(segment
		(start 199.08266 -218.312492)
		(end 199.874378 -218.312492)
		(width 0.20066)
		(layer "F.Cu")
		(net "M_G_CPU1_SB_DQS_DN<6>")
	)
	(segment
		(start 197.531736 -218.141804)
		(end 197.542658 -218.152726)
		(width 0.1016)
		(layer "F.Cu")
		(net "M_G_CPU1_SB_DQS_DN<6>")
	)
	(segment
		(start 200.128632 -218.566746)
		(end 200.632314 -218.566746)
		(width 0.20066)
		(layer "F.Cu")
		(net "M_G_CPU1_SB_DQS_DN<6>")
	)
	(segment
		(start 194.798696 -217.870532)
		(end 194.921124 -217.870532)
		(width 0.20066)
		(layer "F.Cu")
		(net "M_G_CPU1_SB_DQS_DN<6>")
	)
	(segment
		(start 193.890392 -218.295474)
		(end 194.373754 -218.295474)
		(width 0.20066)
		(layer "F.Cu")
		(net "M_G_CPU1_SB_DQS_DN<6>")
	)
	(segment
		(start 191.983614 -218.566746)
		(end 193.088514 -218.566746)
		(width 0.20066)
		(layer "F.Cu")
		(net "M_G_CPU1_SB_DQS_DN<6>")
	)
	(segment
		(start 195.510658 -218.1479)
		(end 195.515484 -218.1479)
		(width 0.101854)
		(layer "F.Cu")
		(net "M_G_CPU1_SB_DQS_DN<6>")
	)
	(segment
		(start 173.002702 -224.090738)
		(end 172.622464 -224.090738)
		(width 0.18288)
		(layer "In6.Cu")
		(net "M_G_CPU1_SB_DQS_DN<6>")
	)
	(segment
		(start 156.007816 -221.501462)
		(end 143.569436 -233.939842)
		(width 0.18288)
		(layer "In6.Cu")
		(net "M_G_CPU1_SB_DQS_DN<6>")
	)
	(segment
		(start 168.865804 -223.764348)
		(end 168.751758 -223.717104)
		(width 0.18288)
		(layer "In6.Cu")
		(net "M_G_CPU1_SB_DQS_DN<6>")
	)
	(segment
		(start 138.049762 -234.970066)
		(end 138.049762 -234.98556)
		(width 0.088646)
		(layer "In6.Cu")
		(net "M_G_CPU1_SB_DQS_DN<6>")
	)
	(segment
		(start 183.309768 -220.835982)
		(end 182.862728 -221.021148)
		(width 0.18288)
		(layer "In6.Cu")
		(net "M_G_CPU1_SB_DQS_DN<6>")
	)
	(segment
		(start 140.009626 -233.939842)
		(end 139.949682 -233.879898)
		(width 0.088646)
		(layer "In6.Cu")
		(net "M_G_CPU1_SB_DQS_DN<6>")
	)
	(segment
		(start 178.202082 -222.812356)
		(end 177.81905 -222.971106)
		(width 0.18288)
		(layer "In6.Cu")
		(net "M_G_CPU1_SB_DQS_DN<6>")
	)
	(segment
		(start 183.895492 -220.250258)
		(end 183.309768 -220.835982)
		(width 0.18288)
		(layer "In6.Cu")
		(net "M_G_CPU1_SB_DQS_DN<6>")
	)
	(segment
		(start 187.1091 -220.155262)
		(end 184.1246 -220.155262)
		(width 0.18288)
		(layer "In6.Cu")
		(net "M_G_CPU1_SB_DQS_DN<6>")
	)
	(segment
		(start 166.910766 -222.765112)
		(end 165.654482 -221.508828)
		(width 0.18288)
		(layer "In6.Cu")
		(net "M_G_CPU1_SB_DQS_DN<6>")
	)
	(segment
		(start 130.252978 -235.456984)
		(end 130.252216 -235.457492)
		(width 0.088646)
		(layer "In6.Cu")
		(net "M_G_CPU1_SB_DQS_DN<6>")
	)
	(segment
		(start 164.314124 -221.848426)
		(end 161.09188 -221.848426)
		(width 0.18288)
		(layer "In6.Cu")
		(net "M_G_CPU1_SB_DQS_DN<6>")
	)
	(segment
		(start 188.96076 -220.27134)
		(end 188.664596 -220.396054)
		(width 0.18288)
		(layer "In6.Cu")
		(net "M_G_CPU1_SB_DQS_DN<6>")
	)
	(segment
		(start 176.461674 -222.982028)
		(end 174.95647 -222.982028)
		(width 0.18288)
		(layer "In6.Cu")
		(net "M_G_CPU1_SB_DQS_DN<6>")
	)
	(segment
		(start 161.09188 -221.848426)
		(end 160.744916 -221.501462)
		(width 0.18288)
		(layer "In6.Cu")
		(net "M_G_CPU1_SB_DQS_DN<6>")
	)
	(segment
		(start 139.81684 -233.879898)
		(end 139.622276 -234.074208)
		(width 0.088646)
		(layer "In6.Cu")
		(net "M_G_CPU1_SB_DQS_DN<6>")
	)
	(segment
		(start 165.654482 -221.508828)
		(end 165.133782 -221.508828)
		(width 0.18288)
		(layer "In6.Cu")
		(net "M_G_CPU1_SB_DQS_DN<6>")
	)
	(segment
		(start 190.859918 -218.372182)
		(end 188.96076 -220.27134)
		(width 0.18288)
		(layer "In6.Cu")
		(net "M_G_CPU1_SB_DQS_DN<6>")
	)
	(segment
		(start 188.664596 -220.396054)
		(end 188.395356 -220.396054)
		(width 0.18288)
		(layer "In6.Cu")
		(net "M_G_CPU1_SB_DQS_DN<6>")
	)
	(segment
		(start 129.418334 -235.287312)
		(end 129.24155 -235.278676)
		(width 0.088646)
		(layer "In6.Cu")
		(net "M_G_CPU1_SB_DQS_DN<6>")
	)
	(segment
		(start 139.949682 -233.879898)
		(end 139.81684 -233.879898)
		(width 0.088646)
		(layer "In6.Cu")
		(net "M_G_CPU1_SB_DQS_DN<6>")
	)
	(segment
		(start 172.622464 -224.090738)
		(end 172.343064 -223.811338)
		(width 0.18288)
		(layer "In6.Cu")
		(net "M_G_CPU1_SB_DQS_DN<6>")
	)
	(segment
		(start 173.526958 -223.832674)
		(end 173.260766 -223.832674)
		(width 0.18288)
		(layer "In6.Cu")
		(net "M_G_CPU1_SB_DQS_DN<6>")
	)
	(segment
		(start 191.76111 -218.344242)
		(end 190.927482 -218.344242)
		(width 0.18288)
		(layer "In6.Cu")
		(net "M_G_CPU1_SB_DQS_DN<6>")
	)
	(segment
		(start 140.061696 -233.939842)
		(end 140.009626 -233.939842)
		(width 0.088646)
		(layer "In6.Cu")
		(net "M_G_CPU1_SB_DQS_DN<6>")
	)
	(segment
		(start 139.533122 -234.150408)
		(end 139.097512 -234.470702)
		(width 0.088646)
		(layer "In6.Cu")
		(net "M_G_CPU1_SB_DQS_DN<6>")
	)
	(segment
		(start 137.216896 -235.46816)
		(end 137.202164 -235.459524)
		(width 0.088646)
		(layer "In6.Cu")
		(net "M_G_CPU1_SB_DQS_DN<6>")
	)
	(segment
		(start 174.95647 -222.982028)
		(end 174.53229 -223.157288)
		(width 0.18288)
		(layer "In6.Cu")
		(net "M_G_CPU1_SB_DQS_DN<6>")
	)
	(segment
		(start 177.81905 -222.971106)
		(end 177.345594 -222.971106)
		(width 0.18288)
		(layer "In6.Cu")
		(net "M_G_CPU1_SB_DQS_DN<6>")
	)
	(segment
		(start 168.751758 -223.717104)
		(end 167.799766 -222.765112)
		(width 0.18288)
		(layer "In6.Cu")
		(net "M_G_CPU1_SB_DQS_DN<6>")
	)
	(segment
		(start 136.277096 -235.46816)
		(end 136.262364 -235.459524)
		(width 0.088646)
		(layer "In6.Cu")
		(net "M_G_CPU1_SB_DQS_DN<6>")
	)
	(segment
		(start 177.345594 -222.971106)
		(end 177.075846 -223.240854)
		(width 0.18288)
		(layer "In6.Cu")
		(net "M_G_CPU1_SB_DQS_DN<6>")
	)
	(segment
		(start 184.1246 -220.155262)
		(end 183.895492 -220.250258)
		(width 0.18288)
		(layer "In6.Cu")
		(net "M_G_CPU1_SB_DQS_DN<6>")
	)
	(segment
		(start 131.194556 -235.456222)
		(end 131.182872 -235.462826)
		(width 0.088646)
		(layer "In6.Cu")
		(net "M_G_CPU1_SB_DQS_DN<6>")
	)
	(segment
		(start 160.744916 -221.501462)
		(end 156.007816 -221.501462)
		(width 0.18288)
		(layer "In6.Cu")
		(net "M_G_CPU1_SB_DQS_DN<6>")
	)
	(segment
		(start 173.260766 -223.832674)
		(end 173.002702 -224.090738)
		(width 0.18288)
		(layer "In6.Cu")
		(net "M_G_CPU1_SB_DQS_DN<6>")
	)
	(segment
		(start 130.252216 -235.457492)
		(end 130.249676 -235.459016)
		(width 0.088646)
		(layer "In6.Cu")
		(net "M_G_CPU1_SB_DQS_DN<6>")
	)
	(segment
		(start 188.395356 -220.396054)
		(end 188.10224 -220.68917)
		(width 0.18288)
		(layer "In6.Cu")
		(net "M_G_CPU1_SB_DQS_DN<6>")
	)
	(segment
		(start 179.756562 -221.835472)
		(end 178.77028 -222.244158)
		(width 0.18288)
		(layer "In6.Cu")
		(net "M_G_CPU1_SB_DQS_DN<6>")
	)
	(segment
		(start 132.50291 -235.459524)
		(end 132.503164 -235.459524)
		(width 0.088646)
		(layer "In6.Cu")
		(net "M_G_CPU1_SB_DQS_DN<6>")
	)
	(segment
		(start 176.7205 -223.240854)
		(end 176.461674 -222.982028)
		(width 0.18288)
		(layer "In6.Cu")
		(net "M_G_CPU1_SB_DQS_DN<6>")
	)
	(segment
		(start 180.975 -221.021148)
		(end 179.756562 -221.835472)
		(width 0.18288)
		(layer "In6.Cu")
		(net "M_G_CPU1_SB_DQS_DN<6>")
	)
	(segment
		(start 132.134356 -235.456222)
		(end 132.122672 -235.462826)
		(width 0.088646)
		(layer "In6.Cu")
		(net "M_G_CPU1_SB_DQS_DN<6>")
	)
	(segment
		(start 172.343064 -223.811338)
		(end 168.979596 -223.811338)
		(width 0.18288)
		(layer "In6.Cu")
		(net "M_G_CPU1_SB_DQS_DN<6>")
	)
	(segment
		(start 174.53229 -223.157288)
		(end 174.091854 -223.597724)
		(width 0.18288)
		(layer "In6.Cu")
		(net "M_G_CPU1_SB_DQS_DN<6>")
	)
	(segment
		(start 182.862728 -221.021148)
		(end 180.975 -221.021148)
		(width 0.18288)
		(layer "In6.Cu")
		(net "M_G_CPU1_SB_DQS_DN<6>")
	)
	(segment
		(start 167.799766 -222.765112)
		(end 166.910766 -222.765112)
		(width 0.18288)
		(layer "In6.Cu")
		(net "M_G_CPU1_SB_DQS_DN<6>")
	)
	(segment
		(start 128.656334 -235.027216)
		(end 128.599184 -234.970066)
		(width 0.088646)
		(layer "In6.Cu")
		(net "M_G_CPU1_SB_DQS_DN<6>")
	)
	(segment
		(start 168.979596 -223.811338)
		(end 168.865804 -223.764348)
		(width 0.18288)
		(layer "In6.Cu")
		(net "M_G_CPU1_SB_DQS_DN<6>")
	)
	(segment
		(start 130.249676 -235.459016)
		(end 130.23977 -235.46435)
		(width 0.088646)
		(layer "In6.Cu")
		(net "M_G_CPU1_SB_DQS_DN<6>")
	)
	(segment
		(start 174.091854 -223.597724)
		(end 173.526958 -223.832674)
		(width 0.18288)
		(layer "In6.Cu")
		(net "M_G_CPU1_SB_DQS_DN<6>")
	)
	(segment
		(start 129.65684 -235.443014)
		(end 129.418334 -235.287312)
		(width 0.088646)
		(layer "In6.Cu")
		(net "M_G_CPU1_SB_DQS_DN<6>")
	)
	(segment
		(start 129.24155 -235.278676)
		(end 129.21361 -235.294424)
		(width 0.088646)
		(layer "In6.Cu")
		(net "M_G_CPU1_SB_DQS_DN<6>")
	)
	(segment
		(start 178.77028 -222.244158)
		(end 178.202082 -222.812356)
		(width 0.18288)
		(layer "In6.Cu")
		(net "M_G_CPU1_SB_DQS_DN<6>")
	)
	(segment
		(start 165.133782 -221.508828)
		(end 164.314124 -221.848426)
		(width 0.18288)
		(layer "In6.Cu")
		(net "M_G_CPU1_SB_DQS_DN<6>")
	)
	(segment
		(start 132.513324 -235.46562)
		(end 132.50291 -235.459524)
		(width 0.088646)
		(layer "In6.Cu")
		(net "M_G_CPU1_SB_DQS_DN<6>")
	)
	(segment
		(start 190.927482 -218.344242)
		(end 190.859918 -218.372182)
		(width 0.18288)
		(layer "In6.Cu")
		(net "M_G_CPU1_SB_DQS_DN<6>")
	)
	(segment
		(start 177.075846 -223.240854)
		(end 176.7205 -223.240854)
		(width 0.18288)
		(layer "In6.Cu")
		(net "M_G_CPU1_SB_DQS_DN<6>")
	)
	(segment
		(start 128.599184 -234.970066)
		(end 128.086612 -234.970066)
		(width 0.088646)
		(layer "In6.Cu")
		(net "M_G_CPU1_SB_DQS_DN<6>")
	)
	(segment
		(start 187.643008 -220.68917)
		(end 187.1091 -220.155262)
		(width 0.18288)
		(layer "In6.Cu")
		(net "M_G_CPU1_SB_DQS_DN<6>")
	)
	(segment
		(start 138.23569 -234.64647)
		(end 138.228324 -234.650788)
		(width 0.088646)
		(layer "In6.Cu")
		(net "M_G_CPU1_SB_DQS_DN<6>")
	)
	(segment
		(start 143.569436 -233.939842)
		(end 140.061696 -233.939842)
		(width 0.18288)
		(layer "In6.Cu")
		(net "M_G_CPU1_SB_DQS_DN<6>")
	)
	(segment
		(start 138.237214 -234.645708)
		(end 138.23569 -234.64647)
		(width 0.088646)
		(layer "In6.Cu")
		(net "M_G_CPU1_SB_DQS_DN<6>")
	)
	(segment
		(start 188.10224 -220.68917)
		(end 187.643008 -220.68917)
		(width 0.18288)
		(layer "In6.Cu")
		(net "M_G_CPU1_SB_DQS_DN<6>")
	)
	(segment
		(start 191.983614 -218.566746)
		(end 191.76111 -218.344242)
		(width 0.18288)
		(layer "In6.Cu")
		(net "M_G_CPU1_SB_DQS_DN<6>")
	)
	(arc
		(start 130.623564 -235.459524)
		(mid 130.43961 -235.409395)
		(end 130.254756 -235.456222)
		(width 0.088646)
		(layer "In6.Cu")
		(net "M_G_CPU1_SB_DQS_DN<6>")
	)
	(arc
		(start 134.008368 -235.459524)
		(mid 133.725666 -235.5353)
		(end 133.442964 -235.459524)
		(width 0.088646)
		(layer "In6.Cu")
		(net "M_G_CPU1_SB_DQS_DN<6>")
	)
	(arc
		(start 131.563364 -235.459524)
		(mid 131.37941 -235.409395)
		(end 131.194556 -235.456222)
		(width 0.088646)
		(layer "In6.Cu")
		(net "M_G_CPU1_SB_DQS_DN<6>")
	)
	(arc
		(start 131.182872 -235.462826)
		(mid 130.902767 -235.535268)
		(end 130.623564 -235.459524)
		(width 0.088646)
		(layer "In6.Cu")
		(net "M_G_CPU1_SB_DQS_DN<6>")
	)
	(arc
		(start 133.442964 -235.459524)
		(mid 133.255766 -235.409381)
		(end 133.068568 -235.459524)
		(width 0.088646)
		(layer "In6.Cu")
		(net "M_G_CPU1_SB_DQS_DN<6>")
	)
	(arc
		(start 133.068568 -235.459524)
		(mid 132.791755 -235.535394)
		(end 132.513324 -235.46562)
		(width 0.088646)
		(layer "In6.Cu")
		(net "M_G_CPU1_SB_DQS_DN<6>")
	)
	(arc
		(start 134.382764 -235.459524)
		(mid 134.195566 -235.409381)
		(end 134.008368 -235.459524)
		(width 0.088646)
		(layer "In6.Cu")
		(net "M_G_CPU1_SB_DQS_DN<6>")
	)
	(arc
		(start 129.21361 -235.294424)
		(mid 128.864505 -235.30776)
		(end 128.656334 -235.027216)
		(width 0.088646)
		(layer "In6.Cu")
		(net "M_G_CPU1_SB_DQS_DN<6>")
	)
	(arc
		(start 139.622276 -234.074208)
		(mid 139.579143 -234.113998)
		(end 139.533122 -234.150408)
		(width 0.088646)
		(layer "In6.Cu")
		(net "M_G_CPU1_SB_DQS_DN<6>")
	)
	(arc
		(start 132.503164 -235.459524)
		(mid 132.31921 -235.409395)
		(end 132.134356 -235.456222)
		(width 0.088646)
		(layer "In6.Cu")
		(net "M_G_CPU1_SB_DQS_DN<6>")
	)
	(arc
		(start 138.228324 -234.650788)
		(mid 138.09741 -234.787148)
		(end 138.049762 -234.970066)
		(width 0.088646)
		(layer "In6.Cu")
		(net "M_G_CPU1_SB_DQS_DN<6>")
	)
	(arc
		(start 135.887968 -235.459524)
		(mid 135.605266 -235.5353)
		(end 135.322564 -235.459524)
		(width 0.088646)
		(layer "In6.Cu")
		(net "M_G_CPU1_SB_DQS_DN<6>")
	)
	(arc
		(start 136.262364 -235.459524)
		(mid 136.075166 -235.409381)
		(end 135.887968 -235.459524)
		(width 0.088646)
		(layer "In6.Cu")
		(net "M_G_CPU1_SB_DQS_DN<6>")
	)
	(arc
		(start 139.097512 -234.470702)
		(mid 138.812234 -234.599869)
		(end 138.499088 -234.602274)
		(width 0.088646)
		(layer "In6.Cu")
		(net "M_G_CPU1_SB_DQS_DN<6>")
	)
	(arc
		(start 136.827768 -235.459524)
		(mid 136.553569 -235.535359)
		(end 136.277096 -235.46816)
		(width 0.088646)
		(layer "In6.Cu")
		(net "M_G_CPU1_SB_DQS_DN<6>")
	)
	(arc
		(start 138.049762 -234.98556)
		(mid 137.970392 -235.259294)
		(end 137.767568 -235.459524)
		(width 0.088646)
		(layer "In6.Cu")
		(net "M_G_CPU1_SB_DQS_DN<6>")
	)
	(arc
		(start 130.254756 -235.456222)
		(mid 130.253867 -235.456602)
		(end 130.252978 -235.456984)
		(width 0.088646)
		(layer "In6.Cu")
		(net "M_G_CPU1_SB_DQS_DN<6>")
	)
	(arc
		(start 138.499088 -234.602274)
		(mid 138.364168 -234.600005)
		(end 138.237214 -234.645708)
		(width 0.088646)
		(layer "In6.Cu")
		(net "M_G_CPU1_SB_DQS_DN<6>")
	)
	(arc
		(start 130.23977 -235.46435)
		(mid 129.945331 -235.534683)
		(end 129.65684 -235.443014)
		(width 0.088646)
		(layer "In6.Cu")
		(net "M_G_CPU1_SB_DQS_DN<6>")
	)
	(arc
		(start 134.948168 -235.459524)
		(mid 134.665466 -235.5353)
		(end 134.382764 -235.459524)
		(width 0.088646)
		(layer "In6.Cu")
		(net "M_G_CPU1_SB_DQS_DN<6>")
	)
	(arc
		(start 135.322564 -235.459524)
		(mid 135.135366 -235.409381)
		(end 134.948168 -235.459524)
		(width 0.088646)
		(layer "In6.Cu")
		(net "M_G_CPU1_SB_DQS_DN<6>")
	)
	(arc
		(start 137.202164 -235.459524)
		(mid 137.014966 -235.409381)
		(end 136.827768 -235.459524)
		(width 0.088646)
		(layer "In6.Cu")
		(net "M_G_CPU1_SB_DQS_DN<6>")
	)
	(arc
		(start 132.122672 -235.462826)
		(mid 131.842567 -235.535268)
		(end 131.563364 -235.459524)
		(width 0.088646)
		(layer "In6.Cu")
		(net "M_G_CPU1_SB_DQS_DN<6>")
	)
	(arc
		(start 137.767568 -235.459524)
		(mid 137.493369 -235.535359)
		(end 137.216896 -235.46816)
		(width 0.088646)
		(layer "In6.Cu")
		(net "M_G_CPU1_SB_DQS_DN<6>")
	)
	(segment
		(start 193.088514 -227.91674)
		(end 193.61912 -227.91674)
		(width 0.20066)
		(layer "F.Cu")
		(net "M_G_CPU1_SB_DQS_DN<5>")
	)
	(segment
		(start 199.08266 -227.662486)
		(end 199.874378 -227.662486)
		(width 0.20066)
		(layer "F.Cu")
		(net "M_G_CPU1_SB_DQS_DN<5>")
	)
	(segment
		(start 194.921124 -227.220526)
		(end 195.198492 -227.497894)
		(width 0.20066)
		(layer "F.Cu")
		(net "M_G_CPU1_SB_DQS_DN<5>")
	)
	(segment
		(start 197.861428 -227.50272)
		(end 198.147178 -227.21697)
		(width 0.20066)
		(layer "F.Cu")
		(net "M_G_CPU1_SB_DQS_DN<5>")
	)
	(segment
		(start 193.890392 -227.645468)
		(end 194.373754 -227.645468)
		(width 0.20066)
		(layer "F.Cu")
		(net "M_G_CPU1_SB_DQS_DN<5>")
	)
	(segment
		(start 195.198492 -227.497894)
		(end 195.510658 -227.497894)
		(width 0.20066)
		(layer "F.Cu")
		(net "M_G_CPU1_SB_DQS_DN<5>")
	)
	(segment
		(start 195.52158 -227.491798)
		(end 197.531736 -227.491798)
		(width 0.1016)
		(layer "F.Cu")
		(net "M_G_CPU1_SB_DQS_DN<5>")
	)
	(segment
		(start 194.798696 -227.220526)
		(end 194.921124 -227.220526)
		(width 0.20066)
		(layer "F.Cu")
		(net "M_G_CPU1_SB_DQS_DN<5>")
	)
	(segment
		(start 191.983614 -227.91674)
		(end 193.088514 -227.91674)
		(width 0.20066)
		(layer "F.Cu")
		(net "M_G_CPU1_SB_DQS_DN<5>")
	)
	(segment
		(start 193.61912 -227.91674)
		(end 193.890392 -227.645468)
		(width 0.20066)
		(layer "F.Cu")
		(net "M_G_CPU1_SB_DQS_DN<5>")
	)
	(segment
		(start 198.637144 -227.21697)
		(end 199.08266 -227.662486)
		(width 0.20066)
		(layer "F.Cu")
		(net "M_G_CPU1_SB_DQS_DN<5>")
	)
	(segment
		(start 129.026412 -240.388902)
		(end 129.026412 -239.853216)
		(width 0.20066)
		(layer "F.Cu")
		(net "M_G_CPU1_SB_DQS_DN<5>")
	)
	(segment
		(start 195.515484 -227.497894)
		(end 195.52158 -227.491798)
		(width 0.1016)
		(layer "F.Cu")
		(net "M_G_CPU1_SB_DQS_DN<5>")
	)
	(segment
		(start 129.026666 -240.389156)
		(end 129.026412 -240.388902)
		(width 0.20066)
		(layer "F.Cu")
		(net "M_G_CPU1_SB_DQS_DN<5>")
	)
	(segment
		(start 195.510658 -227.497894)
		(end 195.515484 -227.497894)
		(width 0.101854)
		(layer "F.Cu")
		(net "M_G_CPU1_SB_DQS_DN<5>")
	)
	(segment
		(start 194.373754 -227.645468)
		(end 194.798696 -227.220526)
		(width 0.20066)
		(layer "F.Cu")
		(net "M_G_CPU1_SB_DQS_DN<5>")
	)
	(segment
		(start 197.531736 -227.491798)
		(end 197.542658 -227.50272)
		(width 0.1016)
		(layer "F.Cu")
		(net "M_G_CPU1_SB_DQS_DN<5>")
	)
	(segment
		(start 199.874378 -227.662486)
		(end 200.128632 -227.91674)
		(width 0.20066)
		(layer "F.Cu")
		(net "M_G_CPU1_SB_DQS_DN<5>")
	)
	(segment
		(start 197.542658 -227.50272)
		(end 197.861428 -227.50272)
		(width 0.20066)
		(layer "F.Cu")
		(net "M_G_CPU1_SB_DQS_DN<5>")
	)
	(segment
		(start 198.147178 -227.21697)
		(end 198.637144 -227.21697)
		(width 0.20066)
		(layer "F.Cu")
		(net "M_G_CPU1_SB_DQS_DN<5>")
	)
	(segment
		(start 200.128632 -227.91674)
		(end 200.632314 -227.91674)
		(width 0.20066)
		(layer "F.Cu")
		(net "M_G_CPU1_SB_DQS_DN<5>")
	)
	(segment
		(start 178.123088 -232.323386)
		(end 177.339752 -232.323386)
		(width 0.18288)
		(layer "In6.Cu")
		(net "M_G_CPU1_SB_DQS_DN<5>")
	)
	(segment
		(start 166.182294 -232.576878)
		(end 165.603936 -232.576878)
		(width 0.18288)
		(layer "In6.Cu")
		(net "M_G_CPU1_SB_DQS_DN<5>")
	)
	(segment
		(start 149.822154 -236.060234)
		(end 149.646132 -236.060234)
		(width 0.18288)
		(layer "In6.Cu")
		(net "M_G_CPU1_SB_DQS_DN<5>")
	)
	(segment
		(start 175.696372 -232.330498)
		(end 175.571912 -232.454958)
		(width 0.18288)
		(layer "In6.Cu")
		(net "M_G_CPU1_SB_DQS_DN<5>")
	)
	(segment
		(start 137.297414 -239.528858)
		(end 137.282682 -239.537494)
		(width 0.088646)
		(layer "In6.Cu")
		(net "M_G_CPU1_SB_DQS_DN<5>")
	)
	(segment
		(start 169.473118 -233.297222)
		(end 169.348658 -233.172762)
		(width 0.18288)
		(layer "In6.Cu")
		(net "M_G_CPU1_SB_DQS_DN<5>")
	)
	(segment
		(start 150.208488 -235.6739)
		(end 149.822154 -236.060234)
		(width 0.18288)
		(layer "In6.Cu")
		(net "M_G_CPU1_SB_DQS_DN<5>")
	)
	(segment
		(start 157.280102 -233.214926)
		(end 156.029152 -233.214926)
		(width 0.18288)
		(layer "In6.Cu")
		(net "M_G_CPU1_SB_DQS_DN<5>")
	)
	(segment
		(start 191.983614 -227.91674)
		(end 191.713358 -227.646484)
		(width 0.18288)
		(layer "In6.Cu")
		(net "M_G_CPU1_SB_DQS_DN<5>")
	)
	(segment
		(start 152.49144 -233.214926)
		(end 152.10536 -233.601006)
		(width 0.18288)
		(layer "In6.Cu")
		(net "M_G_CPU1_SB_DQS_DN<5>")
	)
	(segment
		(start 140.117322 -239.186466)
		(end 139.825476 -239.478312)
		(width 0.088646)
		(layer "In6.Cu")
		(net "M_G_CPU1_SB_DQS_DN<5>")
	)
	(segment
		(start 152.10536 -233.601006)
		(end 152.10536 -233.777028)
		(width 0.18288)
		(layer "In6.Cu")
		(net "M_G_CPU1_SB_DQS_DN<5>")
	)
	(segment
		(start 155.234132 -233.214926)
		(end 154.688032 -233.214926)
		(width 0.18288)
		(layer "In6.Cu")
		(net "M_G_CPU1_SB_DQS_DN<5>")
	)
	(segment
		(start 186.144408 -227.490782)
		(end 185.606944 -228.028246)
		(width 0.18288)
		(layer "In6.Cu")
		(net "M_G_CPU1_SB_DQS_DN<5>")
	)
	(segment
		(start 131.658868 -239.528858)
		(end 131.648454 -239.534954)
		(width 0.088646)
		(layer "In6.Cu")
		(net "M_G_CPU1_SB_DQS_DN<5>")
	)
	(segment
		(start 150.77059 -235.111798)
		(end 150.594568 -235.111798)
		(width 0.18288)
		(layer "In6.Cu")
		(net "M_G_CPU1_SB_DQS_DN<5>")
	)
	(segment
		(start 136.357614 -239.528858)
		(end 136.35736 -239.528858)
		(width 0.088646)
		(layer "In6.Cu")
		(net "M_G_CPU1_SB_DQS_DN<5>")
	)
	(segment
		(start 133.538468 -239.528858)
		(end 133.528054 -239.534954)
		(width 0.088646)
		(layer "In6.Cu")
		(net "M_G_CPU1_SB_DQS_DN<5>")
	)
	(segment
		(start 163.317174 -231.726486)
		(end 162.928554 -232.115106)
		(width 0.18288)
		(layer "In6.Cu")
		(net "M_G_CPU1_SB_DQS_DN<5>")
	)
	(segment
		(start 174.355252 -232.330498)
		(end 173.509178 -233.176572)
		(width 0.18288)
		(layer "In6.Cu")
		(net "M_G_CPU1_SB_DQS_DN<5>")
	)
	(segment
		(start 155.358592 -233.339386)
		(end 155.234132 -233.214926)
		(width 0.18288)
		(layer "In6.Cu")
		(net "M_G_CPU1_SB_DQS_DN<5>")
	)
	(segment
		(start 174.901352 -232.330498)
		(end 174.355252 -232.330498)
		(width 0.18288)
		(layer "In6.Cu")
		(net "M_G_CPU1_SB_DQS_DN<5>")
	)
	(segment
		(start 184.088532 -228.44887)
		(end 183.444896 -229.092506)
		(width 0.18288)
		(layer "In6.Cu")
		(net "M_G_CPU1_SB_DQS_DN<5>")
	)
	(segment
		(start 188.100462 -227.490782)
		(end 186.144408 -227.490782)
		(width 0.18288)
		(layer "In6.Cu")
		(net "M_G_CPU1_SB_DQS_DN<5>")
	)
	(segment
		(start 165.051486 -232.347516)
		(end 164.430202 -231.726486)
		(width 0.18288)
		(layer "In6.Cu")
		(net "M_G_CPU1_SB_DQS_DN<5>")
	)
	(segment
		(start 176.721516 -232.590848)
		(end 176.461166 -232.330498)
		(width 0.18288)
		(layer "In6.Cu")
		(net "M_G_CPU1_SB_DQS_DN<5>")
	)
	(segment
		(start 177.339752 -232.323386)
		(end 177.07229 -232.590848)
		(width 0.18288)
		(layer "In6.Cu")
		(net "M_G_CPU1_SB_DQS_DN<5>")
	)
	(segment
		(start 175.571912 -232.454958)
		(end 175.025812 -232.454958)
		(width 0.18288)
		(layer "In6.Cu")
		(net "M_G_CPU1_SB_DQS_DN<5>")
	)
	(segment
		(start 130.718814 -239.528858)
		(end 130.704082 -239.537494)
		(width 0.088646)
		(layer "In6.Cu")
		(net "M_G_CPU1_SB_DQS_DN<5>")
	)
	(segment
		(start 191.713358 -227.646484)
		(end 191.59347 -227.646484)
		(width 0.18288)
		(layer "In6.Cu")
		(net "M_G_CPU1_SB_DQS_DN<5>")
	)
	(segment
		(start 173.2407 -233.176572)
		(end 172.976286 -233.440986)
		(width 0.18288)
		(layer "In6.Cu")
		(net "M_G_CPU1_SB_DQS_DN<5>")
	)
	(segment
		(start 135.418068 -239.528858)
		(end 135.407654 -239.534954)
		(width 0.088646)
		(layer "In6.Cu")
		(net "M_G_CPU1_SB_DQS_DN<5>")
	)
	(segment
		(start 139.825476 -239.478312)
		(end 139.364212 -239.478312)
		(width 0.088646)
		(layer "In6.Cu")
		(net "M_G_CPU1_SB_DQS_DN<5>")
	)
	(segment
		(start 175.025812 -232.454958)
		(end 174.901352 -232.330498)
		(width 0.18288)
		(layer "In6.Cu")
		(net "M_G_CPU1_SB_DQS_DN<5>")
	)
	(segment
		(start 170.689778 -233.172762)
		(end 170.143678 -233.172762)
		(width 0.18288)
		(layer "In6.Cu")
		(net "M_G_CPU1_SB_DQS_DN<5>")
	)
	(segment
		(start 129.779014 -239.528858)
		(end 129.657348 -239.599216)
		(width 0.088646)
		(layer "In6.Cu")
		(net "M_G_CPU1_SB_DQS_DN<5>")
	)
	(segment
		(start 151.156924 -234.725464)
		(end 150.77059 -235.111798)
		(width 0.18288)
		(layer "In6.Cu")
		(net "M_G_CPU1_SB_DQS_DN<5>")
	)
	(segment
		(start 185.606944 -228.028246)
		(end 185.105802 -228.028246)
		(width 0.18288)
		(layer "In6.Cu")
		(net "M_G_CPU1_SB_DQS_DN<5>")
	)
	(segment
		(start 176.461166 -232.330498)
		(end 175.696372 -232.330498)
		(width 0.18288)
		(layer "In6.Cu")
		(net "M_G_CPU1_SB_DQS_DN<5>")
	)
	(segment
		(start 129.026412 -239.704118)
		(end 129.026412 -239.853216)
		(width 0.088646)
		(layer "In6.Cu")
		(net "M_G_CPU1_SB_DQS_DN<5>")
	)
	(segment
		(start 166.306754 -232.701338)
		(end 166.182294 -232.576878)
		(width 0.18288)
		(layer "In6.Cu")
		(net "M_G_CPU1_SB_DQS_DN<5>")
	)
	(segment
		(start 191.135 -227.835714)
		(end 190.0174 -227.835714)
		(width 0.18288)
		(layer "In6.Cu")
		(net "M_G_CPU1_SB_DQS_DN<5>")
	)
	(segment
		(start 162.54222 -232.677462)
		(end 162.366198 -232.677462)
		(width 0.18288)
		(layer "In6.Cu")
		(net "M_G_CPU1_SB_DQS_DN<5>")
	)
	(segment
		(start 159.001206 -233.184192)
		(end 158.143448 -233.184192)
		(width 0.18288)
		(layer "In6.Cu")
		(net "M_G_CPU1_SB_DQS_DN<5>")
	)
	(segment
		(start 129.657348 -239.599216)
		(end 129.577592 -239.620552)
		(width 0.088646)
		(layer "In6.Cu")
		(net "M_G_CPU1_SB_DQS_DN<5>")
	)
	(segment
		(start 168.802558 -233.172762)
		(end 168.206674 -232.576878)
		(width 0.18288)
		(layer "In6.Cu")
		(net "M_G_CPU1_SB_DQS_DN<5>")
	)
	(segment
		(start 181.595522 -231.30891)
		(end 181.209188 -231.695244)
		(width 0.18288)
		(layer "In6.Cu")
		(net "M_G_CPU1_SB_DQS_DN<5>")
	)
	(segment
		(start 182.123588 -230.604822)
		(end 181.595522 -231.132888)
		(width 0.18288)
		(layer "In6.Cu")
		(net "M_G_CPU1_SB_DQS_DN<5>")
	)
	(segment
		(start 157.507432 -233.442256)
		(end 157.280102 -233.214926)
		(width 0.18288)
		(layer "In6.Cu")
		(net "M_G_CPU1_SB_DQS_DN<5>")
	)
	(segment
		(start 177.07229 -232.590848)
		(end 176.721516 -232.590848)
		(width 0.18288)
		(layer "In6.Cu")
		(net "M_G_CPU1_SB_DQS_DN<5>")
	)
	(segment
		(start 183.444896 -229.092506)
		(end 182.47614 -229.092506)
		(width 0.18288)
		(layer "In6.Cu")
		(net "M_G_CPU1_SB_DQS_DN<5>")
	)
	(segment
		(start 151.156924 -234.549442)
		(end 151.156924 -234.725464)
		(width 0.18288)
		(layer "In6.Cu")
		(net "M_G_CPU1_SB_DQS_DN<5>")
	)
	(segment
		(start 129.086864 -239.643666)
		(end 129.026412 -239.704118)
		(width 0.088646)
		(layer "In6.Cu")
		(net "M_G_CPU1_SB_DQS_DN<5>")
	)
	(segment
		(start 181.209188 -231.695244)
		(end 181.033166 -231.695244)
		(width 0.18288)
		(layer "In6.Cu")
		(net "M_G_CPU1_SB_DQS_DN<5>")
	)
	(segment
		(start 166.977314 -232.576878)
		(end 166.852854 -232.701338)
		(width 0.18288)
		(layer "In6.Cu")
		(net "M_G_CPU1_SB_DQS_DN<5>")
	)
	(segment
		(start 182.47614 -229.092506)
		(end 182.123588 -229.445058)
		(width 0.18288)
		(layer "In6.Cu")
		(net "M_G_CPU1_SB_DQS_DN<5>")
	)
	(segment
		(start 179.924456 -232.197402)
		(end 179.4383 -231.711246)
		(width 0.18288)
		(layer "In6.Cu")
		(net "M_G_CPU1_SB_DQS_DN<5>")
	)
	(segment
		(start 158.143448 -233.184192)
		(end 157.885384 -233.442256)
		(width 0.18288)
		(layer "In6.Cu")
		(net "M_G_CPU1_SB_DQS_DN<5>")
	)
	(segment
		(start 161.980118 -233.063542)
		(end 160.564068 -233.063542)
		(width 0.18288)
		(layer "In6.Cu")
		(net "M_G_CPU1_SB_DQS_DN<5>")
	)
	(segment
		(start 173.509178 -233.176572)
		(end 173.2407 -233.176572)
		(width 0.18288)
		(layer "In6.Cu")
		(net "M_G_CPU1_SB_DQS_DN<5>")
	)
	(segment
		(start 154.017472 -233.339386)
		(end 153.893012 -233.214926)
		(width 0.18288)
		(layer "In6.Cu")
		(net "M_G_CPU1_SB_DQS_DN<5>")
	)
	(segment
		(start 170.019218 -233.297222)
		(end 169.473118 -233.297222)
		(width 0.18288)
		(layer "In6.Cu")
		(net "M_G_CPU1_SB_DQS_DN<5>")
	)
	(segment
		(start 179.4383 -231.711246)
		(end 178.735228 -231.711246)
		(width 0.18288)
		(layer "In6.Cu")
		(net "M_G_CPU1_SB_DQS_DN<5>")
	)
	(segment
		(start 162.366198 -232.677462)
		(end 161.980118 -233.063542)
		(width 0.18288)
		(layer "In6.Cu")
		(net "M_G_CPU1_SB_DQS_DN<5>")
	)
	(segment
		(start 170.143678 -233.172762)
		(end 170.019218 -233.297222)
		(width 0.18288)
		(layer "In6.Cu")
		(net "M_G_CPU1_SB_DQS_DN<5>")
	)
	(segment
		(start 160.564068 -233.063542)
		(end 160.062418 -232.561892)
		(width 0.18288)
		(layer "In6.Cu")
		(net "M_G_CPU1_SB_DQS_DN<5>")
	)
	(segment
		(start 180.531008 -232.197402)
		(end 179.924456 -232.197402)
		(width 0.18288)
		(layer "In6.Cu")
		(net "M_G_CPU1_SB_DQS_DN<5>")
	)
	(segment
		(start 188.558424 -227.204016)
		(end 188.387228 -227.204016)
		(width 0.18288)
		(layer "In6.Cu")
		(net "M_G_CPU1_SB_DQS_DN<5>")
	)
	(segment
		(start 162.928554 -232.291128)
		(end 162.54222 -232.677462)
		(width 0.18288)
		(layer "In6.Cu")
		(net "M_G_CPU1_SB_DQS_DN<5>")
	)
	(segment
		(start 151.719026 -234.163362)
		(end 151.543004 -234.163362)
		(width 0.18288)
		(layer "In6.Cu")
		(net "M_G_CPU1_SB_DQS_DN<5>")
	)
	(segment
		(start 138.237214 -239.528858)
		(end 138.222482 -239.537494)
		(width 0.088646)
		(layer "In6.Cu")
		(net "M_G_CPU1_SB_DQS_DN<5>")
	)
	(segment
		(start 172.976286 -233.440986)
		(end 172.622464 -233.440986)
		(width 0.18288)
		(layer "In6.Cu")
		(net "M_G_CPU1_SB_DQS_DN<5>")
	)
	(segment
		(start 188.387228 -227.204016)
		(end 188.100462 -227.490782)
		(width 0.18288)
		(layer "In6.Cu")
		(net "M_G_CPU1_SB_DQS_DN<5>")
	)
	(segment
		(start 157.885384 -233.442256)
		(end 157.507432 -233.442256)
		(width 0.18288)
		(layer "In6.Cu")
		(net "M_G_CPU1_SB_DQS_DN<5>")
	)
	(segment
		(start 149.646132 -236.060234)
		(end 146.459956 -239.24641)
		(width 0.18288)
		(layer "In6.Cu")
		(net "M_G_CPU1_SB_DQS_DN<5>")
	)
	(segment
		(start 162.928554 -232.115106)
		(end 162.928554 -232.291128)
		(width 0.18288)
		(layer "In6.Cu")
		(net "M_G_CPU1_SB_DQS_DN<5>")
	)
	(segment
		(start 185.105802 -228.028246)
		(end 184.088532 -228.44887)
		(width 0.18288)
		(layer "In6.Cu")
		(net "M_G_CPU1_SB_DQS_DN<5>")
	)
	(segment
		(start 154.563572 -233.339386)
		(end 154.017472 -233.339386)
		(width 0.18288)
		(layer "In6.Cu")
		(net "M_G_CPU1_SB_DQS_DN<5>")
	)
	(segment
		(start 168.206674 -232.576878)
		(end 166.977314 -232.576878)
		(width 0.18288)
		(layer "In6.Cu")
		(net "M_G_CPU1_SB_DQS_DN<5>")
	)
	(segment
		(start 132.598414 -239.528858)
		(end 132.588 -239.534954)
		(width 0.088646)
		(layer "In6.Cu")
		(net "M_G_CPU1_SB_DQS_DN<5>")
	)
	(segment
		(start 152.10536 -233.777028)
		(end 151.719026 -234.163362)
		(width 0.18288)
		(layer "In6.Cu")
		(net "M_G_CPU1_SB_DQS_DN<5>")
	)
	(segment
		(start 146.459956 -239.24641)
		(end 140.442696 -239.24641)
		(width 0.18288)
		(layer "In6.Cu")
		(net "M_G_CPU1_SB_DQS_DN<5>")
	)
	(segment
		(start 135.792972 -239.528604)
		(end 135.792464 -239.528858)
		(width 0.088646)
		(layer "In6.Cu")
		(net "M_G_CPU1_SB_DQS_DN<5>")
	)
	(segment
		(start 178.735228 -231.711246)
		(end 178.123088 -232.323386)
		(width 0.18288)
		(layer "In6.Cu")
		(net "M_G_CPU1_SB_DQS_DN<5>")
	)
	(segment
		(start 181.595522 -231.132888)
		(end 181.595522 -231.30891)
		(width 0.18288)
		(layer "In6.Cu")
		(net "M_G_CPU1_SB_DQS_DN<5>")
	)
	(segment
		(start 172.35424 -233.172762)
		(end 171.484798 -233.172762)
		(width 0.18288)
		(layer "In6.Cu")
		(net "M_G_CPU1_SB_DQS_DN<5>")
	)
	(segment
		(start 189.301882 -227.511864)
		(end 188.558424 -227.204016)
		(width 0.18288)
		(layer "In6.Cu")
		(net "M_G_CPU1_SB_DQS_DN<5>")
	)
	(segment
		(start 182.123588 -229.445058)
		(end 182.123588 -230.604822)
		(width 0.18288)
		(layer "In6.Cu")
		(net "M_G_CPU1_SB_DQS_DN<5>")
	)
	(segment
		(start 140.419328 -239.24641)
		(end 140.359384 -239.186466)
		(width 0.088646)
		(layer "In6.Cu")
		(net "M_G_CPU1_SB_DQS_DN<5>")
	)
	(segment
		(start 153.893012 -233.214926)
		(end 152.49144 -233.214926)
		(width 0.18288)
		(layer "In6.Cu")
		(net "M_G_CPU1_SB_DQS_DN<5>")
	)
	(segment
		(start 129.577592 -239.620552)
		(end 129.202434 -239.620552)
		(width 0.088646)
		(layer "In6.Cu")
		(net "M_G_CPU1_SB_DQS_DN<5>")
	)
	(segment
		(start 154.688032 -233.214926)
		(end 154.563572 -233.339386)
		(width 0.18288)
		(layer "In6.Cu")
		(net "M_G_CPU1_SB_DQS_DN<5>")
	)
	(segment
		(start 170.814238 -233.297222)
		(end 170.689778 -233.172762)
		(width 0.18288)
		(layer "In6.Cu")
		(net "M_G_CPU1_SB_DQS_DN<5>")
	)
	(segment
		(start 134.478014 -239.528858)
		(end 134.4676 -239.534954)
		(width 0.088646)
		(layer "In6.Cu")
		(net "M_G_CPU1_SB_DQS_DN<5>")
	)
	(segment
		(start 160.062418 -232.561892)
		(end 159.623506 -232.561892)
		(width 0.18288)
		(layer "In6.Cu")
		(net "M_G_CPU1_SB_DQS_DN<5>")
	)
	(segment
		(start 151.543004 -234.163362)
		(end 151.156924 -234.549442)
		(width 0.18288)
		(layer "In6.Cu")
		(net "M_G_CPU1_SB_DQS_DN<5>")
	)
	(segment
		(start 155.904692 -233.339386)
		(end 155.358592 -233.339386)
		(width 0.18288)
		(layer "In6.Cu")
		(net "M_G_CPU1_SB_DQS_DN<5>")
	)
	(segment
		(start 191.59347 -227.646484)
		(end 191.135 -227.835714)
		(width 0.18288)
		(layer "In6.Cu")
		(net "M_G_CPU1_SB_DQS_DN<5>")
	)
	(segment
		(start 140.442696 -239.24641)
		(end 140.419328 -239.24641)
		(width 0.088646)
		(layer "In6.Cu")
		(net "M_G_CPU1_SB_DQS_DN<5>")
	)
	(segment
		(start 156.029152 -233.214926)
		(end 155.904692 -233.339386)
		(width 0.18288)
		(layer "In6.Cu")
		(net "M_G_CPU1_SB_DQS_DN<5>")
	)
	(segment
		(start 150.208488 -235.497878)
		(end 150.208488 -235.6739)
		(width 0.18288)
		(layer "In6.Cu")
		(net "M_G_CPU1_SB_DQS_DN<5>")
	)
	(segment
		(start 169.348658 -233.172762)
		(end 168.802558 -233.172762)
		(width 0.18288)
		(layer "In6.Cu")
		(net "M_G_CPU1_SB_DQS_DN<5>")
	)
	(segment
		(start 171.360338 -233.297222)
		(end 170.814238 -233.297222)
		(width 0.18288)
		(layer "In6.Cu")
		(net "M_G_CPU1_SB_DQS_DN<5>")
	)
	(segment
		(start 129.202434 -239.620552)
		(end 129.086864 -239.643666)
		(width 0.088646)
		(layer "In6.Cu")
		(net "M_G_CPU1_SB_DQS_DN<5>")
	)
	(segment
		(start 171.484798 -233.172762)
		(end 171.360338 -233.297222)
		(width 0.18288)
		(layer "In6.Cu")
		(net "M_G_CPU1_SB_DQS_DN<5>")
	)
	(segment
		(start 172.622464 -233.440986)
		(end 172.35424 -233.172762)
		(width 0.18288)
		(layer "In6.Cu")
		(net "M_G_CPU1_SB_DQS_DN<5>")
	)
	(segment
		(start 150.594568 -235.111798)
		(end 150.208488 -235.497878)
		(width 0.18288)
		(layer "In6.Cu")
		(net "M_G_CPU1_SB_DQS_DN<5>")
	)
	(segment
		(start 159.623506 -232.561892)
		(end 159.001206 -233.184192)
		(width 0.18288)
		(layer "In6.Cu")
		(net "M_G_CPU1_SB_DQS_DN<5>")
	)
	(segment
		(start 190.0174 -227.835714)
		(end 189.301882 -227.511864)
		(width 0.18288)
		(layer "In6.Cu")
		(net "M_G_CPU1_SB_DQS_DN<5>")
	)
	(segment
		(start 165.603936 -232.576878)
		(end 165.051486 -232.347516)
		(width 0.18288)
		(layer "In6.Cu")
		(net "M_G_CPU1_SB_DQS_DN<5>")
	)
	(segment
		(start 140.359384 -239.186466)
		(end 140.117322 -239.186466)
		(width 0.088646)
		(layer "In6.Cu")
		(net "M_G_CPU1_SB_DQS_DN<5>")
	)
	(segment
		(start 164.430202 -231.726486)
		(end 163.317174 -231.726486)
		(width 0.18288)
		(layer "In6.Cu")
		(net "M_G_CPU1_SB_DQS_DN<5>")
	)
	(segment
		(start 181.033166 -231.695244)
		(end 180.531008 -232.197402)
		(width 0.18288)
		(layer "In6.Cu")
		(net "M_G_CPU1_SB_DQS_DN<5>")
	)
	(segment
		(start 166.852854 -232.701338)
		(end 166.306754 -232.701338)
		(width 0.18288)
		(layer "In6.Cu")
		(net "M_G_CPU1_SB_DQS_DN<5>")
	)
	(arc
		(start 130.15341 -239.528858)
		(mid 129.966212 -239.478715)
		(end 129.779014 -239.528858)
		(width 0.088646)
		(layer "In6.Cu")
		(net "M_G_CPU1_SB_DQS_DN<5>")
	)
	(arc
		(start 138.222482 -239.537494)
		(mid 137.946007 -239.604814)
		(end 137.67181 -239.528858)
		(width 0.088646)
		(layer "In6.Cu")
		(net "M_G_CPU1_SB_DQS_DN<5>")
	)
	(arc
		(start 132.97281 -239.528858)
		(mid 132.785612 -239.478715)
		(end 132.598414 -239.528858)
		(width 0.088646)
		(layer "In6.Cu")
		(net "M_G_CPU1_SB_DQS_DN<5>")
	)
	(arc
		(start 139.364212 -239.478312)
		(mid 139.259011 -239.493449)
		(end 139.162282 -239.537494)
		(width 0.088646)
		(layer "In6.Cu")
		(net "M_G_CPU1_SB_DQS_DN<5>")
	)
	(arc
		(start 137.282682 -239.537494)
		(mid 137.006207 -239.604814)
		(end 136.73201 -239.528858)
		(width 0.088646)
		(layer "In6.Cu")
		(net "M_G_CPU1_SB_DQS_DN<5>")
	)
	(arc
		(start 135.407654 -239.534954)
		(mid 135.129222 -239.6048)
		(end 134.85241 -239.528858)
		(width 0.088646)
		(layer "In6.Cu")
		(net "M_G_CPU1_SB_DQS_DN<5>")
	)
	(arc
		(start 131.648454 -239.534954)
		(mid 131.370022 -239.6048)
		(end 131.09321 -239.528858)
		(width 0.088646)
		(layer "In6.Cu")
		(net "M_G_CPU1_SB_DQS_DN<5>")
	)
	(arc
		(start 137.67181 -239.528858)
		(mid 137.484612 -239.478715)
		(end 137.297414 -239.528858)
		(width 0.088646)
		(layer "In6.Cu")
		(net "M_G_CPU1_SB_DQS_DN<5>")
	)
	(arc
		(start 132.588 -239.534954)
		(mid 132.309822 -239.604677)
		(end 132.033264 -239.528858)
		(width 0.088646)
		(layer "In6.Cu")
		(net "M_G_CPU1_SB_DQS_DN<5>")
	)
	(arc
		(start 136.35736 -239.528858)
		(mid 136.075137 -239.604253)
		(end 135.792972 -239.528604)
		(width 0.088646)
		(layer "In6.Cu")
		(net "M_G_CPU1_SB_DQS_DN<5>")
	)
	(arc
		(start 133.912864 -239.528858)
		(mid 133.725666 -239.478715)
		(end 133.538468 -239.528858)
		(width 0.088646)
		(layer "In6.Cu")
		(net "M_G_CPU1_SB_DQS_DN<5>")
	)
	(arc
		(start 136.73201 -239.528858)
		(mid 136.544812 -239.478715)
		(end 136.357614 -239.528858)
		(width 0.088646)
		(layer "In6.Cu")
		(net "M_G_CPU1_SB_DQS_DN<5>")
	)
	(arc
		(start 138.61161 -239.528858)
		(mid 138.424412 -239.478715)
		(end 138.237214 -239.528858)
		(width 0.088646)
		(layer "In6.Cu")
		(net "M_G_CPU1_SB_DQS_DN<5>")
	)
	(arc
		(start 134.85241 -239.528858)
		(mid 134.665212 -239.478715)
		(end 134.478014 -239.528858)
		(width 0.088646)
		(layer "In6.Cu")
		(net "M_G_CPU1_SB_DQS_DN<5>")
	)
	(arc
		(start 130.704082 -239.537494)
		(mid 130.427607 -239.604814)
		(end 130.15341 -239.528858)
		(width 0.088646)
		(layer "In6.Cu")
		(net "M_G_CPU1_SB_DQS_DN<5>")
	)
	(arc
		(start 134.4676 -239.534954)
		(mid 134.189422 -239.604677)
		(end 133.912864 -239.528858)
		(width 0.088646)
		(layer "In6.Cu")
		(net "M_G_CPU1_SB_DQS_DN<5>")
	)
	(arc
		(start 135.792464 -239.528858)
		(mid 135.605266 -239.478715)
		(end 135.418068 -239.528858)
		(width 0.088646)
		(layer "In6.Cu")
		(net "M_G_CPU1_SB_DQS_DN<5>")
	)
	(arc
		(start 133.528054 -239.534954)
		(mid 133.249622 -239.6048)
		(end 132.97281 -239.528858)
		(width 0.088646)
		(layer "In6.Cu")
		(net "M_G_CPU1_SB_DQS_DN<5>")
	)
	(arc
		(start 131.09321 -239.528858)
		(mid 130.906012 -239.478715)
		(end 130.718814 -239.528858)
		(width 0.088646)
		(layer "In6.Cu")
		(net "M_G_CPU1_SB_DQS_DN<5>")
	)
	(arc
		(start 139.162282 -239.537494)
		(mid 138.885807 -239.604814)
		(end 138.61161 -239.528858)
		(width 0.088646)
		(layer "In6.Cu")
		(net "M_G_CPU1_SB_DQS_DN<5>")
	)
	(arc
		(start 132.033264 -239.528858)
		(mid 131.846066 -239.478715)
		(end 131.658868 -239.528858)
		(width 0.088646)
		(layer "In6.Cu")
		(net "M_G_CPU1_SB_DQS_DN<5>")
	)
	(segment
		(start 195.198492 -236.841792)
		(end 195.343018 -236.841792)
		(width 0.20066)
		(layer "F.Cu")
		(net "M_G_CPU1_SB_DQS_DN<4>")
	)
	(segment
		(start 132.315712 -242.830858)
		(end 132.315966 -242.830604)
		(width 0.20066)
		(layer "F.Cu")
		(net "M_G_CPU1_SB_DQS_DN<4>")
	)
	(segment
		(start 197.87235 -236.841792)
		(end 198.147178 -236.566964)
		(width 0.20066)
		(layer "F.Cu")
		(net "M_G_CPU1_SB_DQS_DN<4>")
	)
	(segment
		(start 195.343018 -236.841792)
		(end 195.52158 -236.841792)
		(width 0.101854)
		(layer "F.Cu")
		(net "M_G_CPU1_SB_DQS_DN<4>")
	)
	(segment
		(start 132.315966 -242.830604)
		(end 132.315966 -242.294918)
		(width 0.20066)
		(layer "F.Cu")
		(net "M_G_CPU1_SB_DQS_DN<4>")
	)
	(segment
		(start 193.61912 -237.266734)
		(end 193.890392 -236.995462)
		(width 0.20066)
		(layer "F.Cu")
		(net "M_G_CPU1_SB_DQS_DN<4>")
	)
	(segment
		(start 199.08266 -237.01248)
		(end 199.874378 -237.01248)
		(width 0.20066)
		(layer "F.Cu")
		(net "M_G_CPU1_SB_DQS_DN<4>")
	)
	(segment
		(start 194.798696 -236.57052)
		(end 194.92722 -236.57052)
		(width 0.20066)
		(layer "F.Cu")
		(net "M_G_CPU1_SB_DQS_DN<4>")
	)
	(segment
		(start 194.92722 -236.57052)
		(end 195.198492 -236.841792)
		(width 0.20066)
		(layer "F.Cu")
		(net "M_G_CPU1_SB_DQS_DN<4>")
	)
	(segment
		(start 197.750684 -236.841792)
		(end 197.87235 -236.841792)
		(width 0.20066)
		(layer "F.Cu")
		(net "M_G_CPU1_SB_DQS_DN<4>")
	)
	(segment
		(start 197.531736 -236.841792)
		(end 197.750684 -236.841792)
		(width 0.101854)
		(layer "F.Cu")
		(net "M_G_CPU1_SB_DQS_DN<4>")
	)
	(segment
		(start 191.983614 -237.266734)
		(end 193.088514 -237.266734)
		(width 0.20066)
		(layer "F.Cu")
		(net "M_G_CPU1_SB_DQS_DN<4>")
	)
	(segment
		(start 198.147178 -236.566964)
		(end 198.637144 -236.566964)
		(width 0.20066)
		(layer "F.Cu")
		(net "M_G_CPU1_SB_DQS_DN<4>")
	)
	(segment
		(start 193.088514 -237.266734)
		(end 193.61912 -237.266734)
		(width 0.20066)
		(layer "F.Cu")
		(net "M_G_CPU1_SB_DQS_DN<4>")
	)
	(segment
		(start 200.128632 -237.266734)
		(end 200.632314 -237.266734)
		(width 0.20066)
		(layer "F.Cu")
		(net "M_G_CPU1_SB_DQS_DN<4>")
	)
	(segment
		(start 199.874378 -237.01248)
		(end 200.128632 -237.266734)
		(width 0.20066)
		(layer "F.Cu")
		(net "M_G_CPU1_SB_DQS_DN<4>")
	)
	(segment
		(start 195.52158 -236.841792)
		(end 197.531736 -236.841792)
		(width 0.1016)
		(layer "F.Cu")
		(net "M_G_CPU1_SB_DQS_DN<4>")
	)
	(segment
		(start 193.890392 -236.995462)
		(end 194.373754 -236.995462)
		(width 0.20066)
		(layer "F.Cu")
		(net "M_G_CPU1_SB_DQS_DN<4>")
	)
	(segment
		(start 198.637144 -236.566964)
		(end 199.08266 -237.01248)
		(width 0.20066)
		(layer "F.Cu")
		(net "M_G_CPU1_SB_DQS_DN<4>")
	)
	(segment
		(start 194.373754 -236.995462)
		(end 194.798696 -236.57052)
		(width 0.20066)
		(layer "F.Cu")
		(net "M_G_CPU1_SB_DQS_DN<4>")
	)
	(segment
		(start 188.35878 -236.560868)
		(end 188.075824 -236.843824)
		(width 0.18288)
		(layer "In4.Cu")
		(net "M_G_CPU1_SB_DQS_DN<4>")
	)
	(segment
		(start 152.211278 -237.802166)
		(end 150.92934 -239.084104)
		(width 0.18288)
		(layer "In4.Cu")
		(net "M_G_CPU1_SB_DQS_DN<4>")
	)
	(segment
		(start 162.94608 -237.007146)
		(end 162.82162 -236.882686)
		(width 0.18288)
		(layer "In4.Cu")
		(net "M_G_CPU1_SB_DQS_DN<4>")
	)
	(segment
		(start 155.67025 -237.565946)
		(end 155.12415 -237.565946)
		(width 0.18288)
		(layer "In4.Cu")
		(net "M_G_CPU1_SB_DQS_DN<4>")
	)
	(segment
		(start 154.99969 -237.441486)
		(end 154.45359 -237.441486)
		(width 0.18288)
		(layer "In4.Cu")
		(net "M_G_CPU1_SB_DQS_DN<4>")
	)
	(segment
		(start 167.3606 -237.212886)
		(end 166.8145 -237.212886)
		(width 0.18288)
		(layer "In4.Cu")
		(net "M_G_CPU1_SB_DQS_DN<4>")
	)
	(segment
		(start 157.68193 -237.441486)
		(end 157.13583 -237.441486)
		(width 0.18288)
		(layer "In4.Cu")
		(net "M_G_CPU1_SB_DQS_DN<4>")
	)
	(segment
		(start 153.08199 -237.441486)
		(end 152.211278 -237.802166)
		(width 0.18288)
		(layer "In4.Cu")
		(net "M_G_CPU1_SB_DQS_DN<4>")
	)
	(segment
		(start 189.611762 -237.279688)
		(end 188.892942 -236.560868)
		(width 0.18288)
		(layer "In4.Cu")
		(net "M_G_CPU1_SB_DQS_DN<4>")
	)
	(segment
		(start 154.45359 -237.441486)
		(end 154.32913 -237.565946)
		(width 0.18288)
		(layer "In4.Cu")
		(net "M_G_CPU1_SB_DQS_DN<4>")
	)
	(segment
		(start 178.658266 -236.351826)
		(end 178.026314 -235.719874)
		(width 0.18288)
		(layer "In4.Cu")
		(net "M_G_CPU1_SB_DQS_DN<4>")
	)
	(segment
		(start 180.074824 -235.720128)
		(end 179.443126 -236.351826)
		(width 0.18288)
		(layer "In4.Cu")
		(net "M_G_CPU1_SB_DQS_DN<4>")
	)
	(segment
		(start 155.12415 -237.565946)
		(end 154.99969 -237.441486)
		(width 0.18288)
		(layer "In4.Cu")
		(net "M_G_CPU1_SB_DQS_DN<4>")
	)
	(segment
		(start 159.69361 -237.565946)
		(end 159.14751 -237.565946)
		(width 0.18288)
		(layer "In4.Cu")
		(net "M_G_CPU1_SB_DQS_DN<4>")
	)
	(segment
		(start 139.637008 -241.91976)
		(end 138.894566 -241.91976)
		(width 0.088646)
		(layer "In4.Cu")
		(net "M_G_CPU1_SB_DQS_DN<4>")
	)
	(segment
		(start 182.937658 -235.720128)
		(end 180.074824 -235.720128)
		(width 0.18288)
		(layer "In4.Cu")
		(net "M_G_CPU1_SB_DQS_DN<4>")
	)
	(segment
		(start 164.16274 -236.882686)
		(end 163.61664 -236.882686)
		(width 0.18288)
		(layer "In4.Cu")
		(net "M_G_CPU1_SB_DQS_DN<4>")
	)
	(segment
		(start 187.691776 -236.843824)
		(end 187.426346 -236.578394)
		(width 0.18288)
		(layer "In4.Cu")
		(net "M_G_CPU1_SB_DQS_DN<4>")
	)
	(segment
		(start 191.317626 -236.98454)
		(end 191.022478 -237.279688)
		(width 0.18288)
		(layer "In4.Cu")
		(net "M_G_CPU1_SB_DQS_DN<4>")
	)
	(segment
		(start 176.704244 -235.99394)
		(end 176.398174 -235.68787)
		(width 0.18288)
		(layer "In4.Cu")
		(net "M_G_CPU1_SB_DQS_DN<4>")
	)
	(segment
		(start 140.292328 -241.720624)
		(end 140.232384 -241.66068)
		(width 0.088646)
		(layer "In4.Cu")
		(net "M_G_CPU1_SB_DQS_DN<4>")
	)
	(segment
		(start 157.13583 -237.441486)
		(end 157.01137 -237.565946)
		(width 0.18288)
		(layer "In4.Cu")
		(net "M_G_CPU1_SB_DQS_DN<4>")
	)
	(segment
		(start 146.625564 -239.084104)
		(end 144.268698 -241.441224)
		(width 0.18288)
		(layer "In4.Cu")
		(net "M_G_CPU1_SB_DQS_DN<4>")
	)
	(segment
		(start 166.14394 -237.337346)
		(end 166.01948 -237.212886)
		(width 0.18288)
		(layer "In4.Cu")
		(net "M_G_CPU1_SB_DQS_DN<4>")
	)
	(segment
		(start 163.49218 -237.007146)
		(end 162.94608 -237.007146)
		(width 0.18288)
		(layer "In4.Cu")
		(net "M_G_CPU1_SB_DQS_DN<4>")
	)
	(segment
		(start 136.827514 -241.970306)
		(end 136.827768 -241.97056)
		(width 0.088646)
		(layer "In4.Cu")
		(net "M_G_CPU1_SB_DQS_DN<4>")
	)
	(segment
		(start 153.78303 -237.565946)
		(end 153.65857 -237.441486)
		(width 0.18288)
		(layer "In4.Cu")
		(net "M_G_CPU1_SB_DQS_DN<4>")
	)
	(segment
		(start 140.315696 -241.720624)
		(end 140.292328 -241.720624)
		(width 0.088646)
		(layer "In4.Cu")
		(net "M_G_CPU1_SB_DQS_DN<4>")
	)
	(segment
		(start 177.088292 -235.99394)
		(end 176.704244 -235.99394)
		(width 0.18288)
		(layer "In4.Cu")
		(net "M_G_CPU1_SB_DQS_DN<4>")
	)
	(segment
		(start 159.02305 -237.441486)
		(end 158.47695 -237.441486)
		(width 0.18288)
		(layer "In4.Cu")
		(net "M_G_CPU1_SB_DQS_DN<4>")
	)
	(segment
		(start 159.14751 -237.565946)
		(end 159.02305 -237.441486)
		(width 0.18288)
		(layer "In4.Cu")
		(net "M_G_CPU1_SB_DQS_DN<4>")
	)
	(segment
		(start 168.03116 -237.337346)
		(end 167.48506 -237.337346)
		(width 0.18288)
		(layer "In4.Cu")
		(net "M_G_CPU1_SB_DQS_DN<4>")
	)
	(segment
		(start 183.594756 -236.377226)
		(end 182.937658 -235.720128)
		(width 0.18288)
		(layer "In4.Cu")
		(net "M_G_CPU1_SB_DQS_DN<4>")
	)
	(segment
		(start 160.36417 -237.441486)
		(end 159.81807 -237.441486)
		(width 0.18288)
		(layer "In4.Cu")
		(net "M_G_CPU1_SB_DQS_DN<4>")
	)
	(segment
		(start 150.92934 -239.084104)
		(end 146.625564 -239.084104)
		(width 0.18288)
		(layer "In4.Cu")
		(net "M_G_CPU1_SB_DQS_DN<4>")
	)
	(segment
		(start 144.268698 -241.441224)
		(end 143.594074 -241.720624)
		(width 0.18288)
		(layer "In4.Cu")
		(net "M_G_CPU1_SB_DQS_DN<4>")
	)
	(segment
		(start 143.594074 -241.720624)
		(end 140.315696 -241.720624)
		(width 0.18288)
		(layer "In4.Cu")
		(net "M_G_CPU1_SB_DQS_DN<4>")
	)
	(segment
		(start 176.398174 -235.68787)
		(end 175.357282 -235.68787)
		(width 0.18288)
		(layer "In4.Cu")
		(net "M_G_CPU1_SB_DQS_DN<4>")
	)
	(segment
		(start 188.075824 -236.843824)
		(end 187.691776 -236.843824)
		(width 0.18288)
		(layer "In4.Cu")
		(net "M_G_CPU1_SB_DQS_DN<4>")
	)
	(segment
		(start 163.61664 -236.882686)
		(end 163.49218 -237.007146)
		(width 0.18288)
		(layer "In4.Cu")
		(net "M_G_CPU1_SB_DQS_DN<4>")
	)
	(segment
		(start 169.942002 -237.212886)
		(end 168.15562 -237.212886)
		(width 0.18288)
		(layer "In4.Cu")
		(net "M_G_CPU1_SB_DQS_DN<4>")
	)
	(segment
		(start 173.27118 -236.560868)
		(end 172.988224 -236.843824)
		(width 0.18288)
		(layer "In4.Cu")
		(net "M_G_CPU1_SB_DQS_DN<4>")
	)
	(segment
		(start 191.70142 -236.98454)
		(end 191.317626 -236.98454)
		(width 0.18288)
		(layer "In4.Cu")
		(net "M_G_CPU1_SB_DQS_DN<4>")
	)
	(segment
		(start 132.327904 -242.145566)
		(end 132.315966 -242.294918)
		(width 0.088646)
		(layer "In4.Cu")
		(net "M_G_CPU1_SB_DQS_DN<4>")
	)
	(segment
		(start 166.01948 -237.212886)
		(end 164.960046 -237.212886)
		(width 0.18288)
		(layer "In4.Cu")
		(net "M_G_CPU1_SB_DQS_DN<4>")
	)
	(segment
		(start 162.82162 -236.882686)
		(end 160.92297 -236.882686)
		(width 0.18288)
		(layer "In4.Cu")
		(net "M_G_CPU1_SB_DQS_DN<4>")
	)
	(segment
		(start 191.983614 -237.266734)
		(end 191.70142 -236.98454)
		(width 0.18288)
		(layer "In4.Cu")
		(net "M_G_CPU1_SB_DQS_DN<4>")
	)
	(segment
		(start 133.068568 -241.97056)
		(end 133.068314 -241.97056)
		(width 0.088646)
		(layer "In4.Cu")
		(net "M_G_CPU1_SB_DQS_DN<4>")
	)
	(segment
		(start 157.80639 -237.565946)
		(end 157.68193 -237.441486)
		(width 0.18288)
		(layer "In4.Cu")
		(net "M_G_CPU1_SB_DQS_DN<4>")
	)
	(segment
		(start 187.426346 -236.578394)
		(end 187.054236 -236.578394)
		(width 0.18288)
		(layer "In4.Cu")
		(net "M_G_CPU1_SB_DQS_DN<4>")
	)
	(segment
		(start 132.781802 -242.087908)
		(end 132.390388 -242.087908)
		(width 0.088646)
		(layer "In4.Cu")
		(net "M_G_CPU1_SB_DQS_DN<4>")
	)
	(segment
		(start 167.48506 -237.337346)
		(end 167.3606 -237.212886)
		(width 0.18288)
		(layer "In4.Cu")
		(net "M_G_CPU1_SB_DQS_DN<4>")
	)
	(segment
		(start 177.362358 -235.719874)
		(end 177.088292 -235.99394)
		(width 0.18288)
		(layer "In4.Cu")
		(net "M_G_CPU1_SB_DQS_DN<4>")
	)
	(segment
		(start 137.202164 -241.97056)
		(end 137.202418 -241.970306)
		(width 0.088646)
		(layer "In4.Cu")
		(net "M_G_CPU1_SB_DQS_DN<4>")
	)
	(segment
		(start 175.357282 -235.68787)
		(end 174.484284 -236.560868)
		(width 0.18288)
		(layer "In4.Cu")
		(net "M_G_CPU1_SB_DQS_DN<4>")
	)
	(segment
		(start 164.960046 -237.212886)
		(end 164.16274 -236.882686)
		(width 0.18288)
		(layer "In4.Cu")
		(net "M_G_CPU1_SB_DQS_DN<4>")
	)
	(segment
		(start 156.34081 -237.441486)
		(end 155.79471 -237.441486)
		(width 0.18288)
		(layer "In4.Cu")
		(net "M_G_CPU1_SB_DQS_DN<4>")
	)
	(segment
		(start 188.892942 -236.560868)
		(end 188.35878 -236.560868)
		(width 0.18288)
		(layer "In4.Cu")
		(net "M_G_CPU1_SB_DQS_DN<4>")
	)
	(segment
		(start 168.15562 -237.212886)
		(end 168.03116 -237.337346)
		(width 0.18288)
		(layer "In4.Cu")
		(net "M_G_CPU1_SB_DQS_DN<4>")
	)
	(segment
		(start 172.988224 -236.843824)
		(end 172.604176 -236.843824)
		(width 0.18288)
		(layer "In4.Cu")
		(net "M_G_CPU1_SB_DQS_DN<4>")
	)
	(segment
		(start 171.537122 -236.552232)
		(end 169.942002 -237.212886)
		(width 0.18288)
		(layer "In4.Cu")
		(net "M_G_CPU1_SB_DQS_DN<4>")
	)
	(segment
		(start 166.69004 -237.337346)
		(end 166.14394 -237.337346)
		(width 0.18288)
		(layer "In4.Cu")
		(net "M_G_CPU1_SB_DQS_DN<4>")
	)
	(segment
		(start 172.312584 -236.552232)
		(end 171.537122 -236.552232)
		(width 0.18288)
		(layer "In4.Cu")
		(net "M_G_CPU1_SB_DQS_DN<4>")
	)
	(segment
		(start 186.853068 -236.377226)
		(end 183.594756 -236.377226)
		(width 0.18288)
		(layer "In4.Cu")
		(net "M_G_CPU1_SB_DQS_DN<4>")
	)
	(segment
		(start 156.46527 -237.565946)
		(end 156.34081 -237.441486)
		(width 0.18288)
		(layer "In4.Cu")
		(net "M_G_CPU1_SB_DQS_DN<4>")
	)
	(segment
		(start 158.35249 -237.565946)
		(end 157.80639 -237.565946)
		(width 0.18288)
		(layer "In4.Cu")
		(net "M_G_CPU1_SB_DQS_DN<4>")
	)
	(segment
		(start 139.896088 -241.66068)
		(end 139.637008 -241.91976)
		(width 0.088646)
		(layer "In4.Cu")
		(net "M_G_CPU1_SB_DQS_DN<4>")
	)
	(segment
		(start 179.443126 -236.351826)
		(end 178.658266 -236.351826)
		(width 0.18288)
		(layer "In4.Cu")
		(net "M_G_CPU1_SB_DQS_DN<4>")
	)
	(segment
		(start 174.484284 -236.560868)
		(end 173.27118 -236.560868)
		(width 0.18288)
		(layer "In4.Cu")
		(net "M_G_CPU1_SB_DQS_DN<4>")
	)
	(segment
		(start 134.397496 -241.979196)
		(end 134.382764 -241.97056)
		(width 0.088646)
		(layer "In4.Cu")
		(net "M_G_CPU1_SB_DQS_DN<4>")
	)
	(segment
		(start 155.79471 -237.441486)
		(end 155.67025 -237.565946)
		(width 0.18288)
		(layer "In4.Cu")
		(net "M_G_CPU1_SB_DQS_DN<4>")
	)
	(segment
		(start 140.232384 -241.66068)
		(end 139.896088 -241.66068)
		(width 0.088646)
		(layer "In4.Cu")
		(net "M_G_CPU1_SB_DQS_DN<4>")
	)
	(segment
		(start 133.068314 -241.97056)
		(end 132.936742 -242.046506)
		(width 0.088646)
		(layer "In4.Cu")
		(net "M_G_CPU1_SB_DQS_DN<4>")
	)
	(segment
		(start 158.47695 -237.441486)
		(end 158.35249 -237.565946)
		(width 0.18288)
		(layer "In4.Cu")
		(net "M_G_CPU1_SB_DQS_DN<4>")
	)
	(segment
		(start 132.936742 -242.046506)
		(end 132.781802 -242.087908)
		(width 0.088646)
		(layer "In4.Cu")
		(net "M_G_CPU1_SB_DQS_DN<4>")
	)
	(segment
		(start 178.026314 -235.719874)
		(end 177.362358 -235.719874)
		(width 0.18288)
		(layer "In4.Cu")
		(net "M_G_CPU1_SB_DQS_DN<4>")
	)
	(segment
		(start 172.604176 -236.843824)
		(end 172.312584 -236.552232)
		(width 0.18288)
		(layer "In4.Cu")
		(net "M_G_CPU1_SB_DQS_DN<4>")
	)
	(segment
		(start 154.32913 -237.565946)
		(end 153.78303 -237.565946)
		(width 0.18288)
		(layer "In4.Cu")
		(net "M_G_CPU1_SB_DQS_DN<4>")
	)
	(segment
		(start 134.952486 -241.96802)
		(end 134.948168 -241.97056)
		(width 0.088646)
		(layer "In4.Cu")
		(net "M_G_CPU1_SB_DQS_DN<4>")
	)
	(segment
		(start 187.054236 -236.578394)
		(end 186.853068 -236.377226)
		(width 0.18288)
		(layer "In4.Cu")
		(net "M_G_CPU1_SB_DQS_DN<4>")
	)
	(segment
		(start 166.8145 -237.212886)
		(end 166.69004 -237.337346)
		(width 0.18288)
		(layer "In4.Cu")
		(net "M_G_CPU1_SB_DQS_DN<4>")
	)
	(segment
		(start 160.92297 -236.882686)
		(end 160.36417 -237.441486)
		(width 0.18288)
		(layer "In4.Cu")
		(net "M_G_CPU1_SB_DQS_DN<4>")
	)
	(segment
		(start 159.81807 -237.441486)
		(end 159.69361 -237.565946)
		(width 0.18288)
		(layer "In4.Cu")
		(net "M_G_CPU1_SB_DQS_DN<4>")
	)
	(segment
		(start 153.65857 -237.441486)
		(end 153.08199 -237.441486)
		(width 0.18288)
		(layer "In4.Cu")
		(net "M_G_CPU1_SB_DQS_DN<4>")
	)
	(segment
		(start 191.022478 -237.279688)
		(end 189.611762 -237.279688)
		(width 0.18288)
		(layer "In4.Cu")
		(net "M_G_CPU1_SB_DQS_DN<4>")
	)
	(segment
		(start 157.01137 -237.565946)
		(end 156.46527 -237.565946)
		(width 0.18288)
		(layer "In4.Cu")
		(net "M_G_CPU1_SB_DQS_DN<4>")
	)
	(arc
		(start 136.827768 -241.97056)
		(mid 136.545066 -242.046336)
		(end 136.262364 -241.97056)
		(width 0.088646)
		(layer "In4.Cu")
		(net "M_G_CPU1_SB_DQS_DN<4>")
	)
	(arc
		(start 132.390388 -242.087908)
		(mid 132.347861 -242.104521)
		(end 132.327904 -242.145566)
		(width 0.088646)
		(layer "In4.Cu")
		(net "M_G_CPU1_SB_DQS_DN<4>")
	)
	(arc
		(start 137.767568 -241.97056)
		(mid 137.484866 -242.046336)
		(end 137.202164 -241.97056)
		(width 0.088646)
		(layer "In4.Cu")
		(net "M_G_CPU1_SB_DQS_DN<4>")
	)
	(arc
		(start 134.382764 -241.97056)
		(mid 134.195566 -241.920417)
		(end 134.008368 -241.97056)
		(width 0.088646)
		(layer "In4.Cu")
		(net "M_G_CPU1_SB_DQS_DN<4>")
	)
	(arc
		(start 138.141964 -241.97056)
		(mid 137.954766 -241.920417)
		(end 137.767568 -241.97056)
		(width 0.088646)
		(layer "In4.Cu")
		(net "M_G_CPU1_SB_DQS_DN<4>")
	)
	(arc
		(start 138.894566 -241.91976)
		(mid 138.878548 -241.920178)
		(end 138.862562 -241.921284)
		(width 0.088646)
		(layer "In4.Cu")
		(net "M_G_CPU1_SB_DQS_DN<4>")
	)
	(arc
		(start 133.442964 -241.97056)
		(mid 133.255766 -241.920417)
		(end 133.068568 -241.97056)
		(width 0.088646)
		(layer "In4.Cu")
		(net "M_G_CPU1_SB_DQS_DN<4>")
	)
	(arc
		(start 138.862562 -241.921284)
		(mid 138.782247 -241.937371)
		(end 138.707368 -241.97056)
		(width 0.088646)
		(layer "In4.Cu")
		(net "M_G_CPU1_SB_DQS_DN<4>")
	)
	(arc
		(start 135.322564 -241.97056)
		(mid 135.13787 -241.920459)
		(end 134.952486 -241.96802)
		(width 0.088646)
		(layer "In4.Cu")
		(net "M_G_CPU1_SB_DQS_DN<4>")
	)
	(arc
		(start 137.202418 -241.970306)
		(mid 137.014966 -241.92007)
		(end 136.827514 -241.970306)
		(width 0.088646)
		(layer "In4.Cu")
		(net "M_G_CPU1_SB_DQS_DN<4>")
	)
	(arc
		(start 138.707368 -241.97056)
		(mid 138.424666 -242.046336)
		(end 138.141964 -241.97056)
		(width 0.088646)
		(layer "In4.Cu")
		(net "M_G_CPU1_SB_DQS_DN<4>")
	)
	(arc
		(start 134.008368 -241.97056)
		(mid 133.725666 -242.046336)
		(end 133.442964 -241.97056)
		(width 0.088646)
		(layer "In4.Cu")
		(net "M_G_CPU1_SB_DQS_DN<4>")
	)
	(arc
		(start 134.948168 -241.97056)
		(mid 134.673969 -242.046395)
		(end 134.397496 -241.979196)
		(width 0.088646)
		(layer "In4.Cu")
		(net "M_G_CPU1_SB_DQS_DN<4>")
	)
	(arc
		(start 136.262364 -241.97056)
		(mid 136.075166 -241.920417)
		(end 135.887968 -241.97056)
		(width 0.088646)
		(layer "In4.Cu")
		(net "M_G_CPU1_SB_DQS_DN<4>")
	)
	(arc
		(start 135.887968 -241.97056)
		(mid 135.605266 -242.046336)
		(end 135.322564 -241.97056)
		(width 0.088646)
		(layer "In4.Cu")
		(net "M_G_CPU1_SB_DQS_DN<4>")
	)
	(segment
		(start 194.093592 -200.2917)
		(end 194.098926 -200.286366)
		(width 0.1016)
		(layer "F.Cu")
		(net "M_G_CPU1_SB_DQS_DN<3>")
	)
	(segment
		(start 189.537086 -199.866758)
		(end 189.818772 -200.148444)
		(width 0.20066)
		(layer "F.Cu")
		(net "M_G_CPU1_SB_DQS_DN<3>")
	)
	(segment
		(start 194.959478 -200.51776)
		(end 195.369942 -200.107296)
		(width 0.20066)
		(layer "F.Cu")
		(net "M_G_CPU1_SB_DQS_DN<3>")
	)
	(segment
		(start 191.490854 -200.562972)
		(end 191.762126 -200.2917)
		(width 0.20066)
		(layer "F.Cu")
		(net "M_G_CPU1_SB_DQS_DN<3>")
	)
	(segment
		(start 190.969138 -200.562972)
		(end 191.490854 -200.562972)
		(width 0.20066)
		(layer "F.Cu")
		(net "M_G_CPU1_SB_DQS_DN<3>")
	)
	(segment
		(start 137.954766 -218.414346)
		(end 137.954766 -217.87866)
		(width 0.20066)
		(layer "F.Cu")
		(net "M_G_CPU1_SB_DQS_DN<3>")
	)
	(segment
		(start 194.098926 -200.286366)
		(end 194.42303 -200.286366)
		(width 0.20066)
		(layer "F.Cu")
		(net "M_G_CPU1_SB_DQS_DN<3>")
	)
	(segment
		(start 194.42303 -200.286366)
		(end 194.654424 -200.51776)
		(width 0.20066)
		(layer "F.Cu")
		(net "M_G_CPU1_SB_DQS_DN<3>")
	)
	(segment
		(start 195.942966 -199.866758)
		(end 196.532246 -199.866758)
		(width 0.20066)
		(layer "F.Cu")
		(net "M_G_CPU1_SB_DQS_DN<3>")
	)
	(segment
		(start 190.55461 -200.148444)
		(end 190.969138 -200.562972)
		(width 0.20066)
		(layer "F.Cu")
		(net "M_G_CPU1_SB_DQS_DN<3>")
	)
	(segment
		(start 194.654424 -200.51776)
		(end 194.959478 -200.51776)
		(width 0.20066)
		(layer "F.Cu")
		(net "M_G_CPU1_SB_DQS_DN<3>")
	)
	(segment
		(start 188.988446 -199.866758)
		(end 189.537086 -199.866758)
		(width 0.20066)
		(layer "F.Cu")
		(net "M_G_CPU1_SB_DQS_DN<3>")
	)
	(segment
		(start 195.369942 -200.107296)
		(end 195.702428 -200.107296)
		(width 0.20066)
		(layer "F.Cu")
		(net "M_G_CPU1_SB_DQS_DN<3>")
	)
	(segment
		(start 191.9097 -200.2917)
		(end 191.914018 -200.2917)
		(width 0.101854)
		(layer "F.Cu")
		(net "M_G_CPU1_SB_DQS_DN<3>")
	)
	(segment
		(start 191.914018 -200.2917)
		(end 194.093592 -200.2917)
		(width 0.1016)
		(layer "F.Cu")
		(net "M_G_CPU1_SB_DQS_DN<3>")
	)
	(segment
		(start 195.702428 -200.107296)
		(end 195.942966 -199.866758)
		(width 0.20066)
		(layer "F.Cu")
		(net "M_G_CPU1_SB_DQS_DN<3>")
	)
	(segment
		(start 137.954766 -217.87866)
		(end 137.95502 -217.878406)
		(width 0.20066)
		(layer "F.Cu")
		(net "M_G_CPU1_SB_DQS_DN<3>")
	)
	(segment
		(start 191.762126 -200.2917)
		(end 191.9097 -200.2917)
		(width 0.20066)
		(layer "F.Cu")
		(net "M_G_CPU1_SB_DQS_DN<3>")
	)
	(segment
		(start 189.818772 -200.148444)
		(end 190.55461 -200.148444)
		(width 0.20066)
		(layer "F.Cu")
		(net "M_G_CPU1_SB_DQS_DN<3>")
	)
	(segment
		(start 187.883546 -199.866758)
		(end 188.988446 -199.866758)
		(width 0.20066)
		(layer "F.Cu")
		(net "M_G_CPU1_SB_DQS_DN<3>")
	)
	(segment
		(start 187.883546 -199.866758)
		(end 187.628022 -200.122282)
		(width 0.18288)
		(layer "In6.Cu")
		(net "M_G_CPU1_SB_DQS_DN<3>")
	)
	(segment
		(start 139.646914 -218.202764)
		(end 139.632182 -218.194128)
		(width 0.088646)
		(layer "In6.Cu")
		(net "M_G_CPU1_SB_DQS_DN<3>")
	)
	(segment
		(start 176.44237 -200.570592)
		(end 176.19345 -200.570592)
		(width 0.18288)
		(layer "In6.Cu")
		(net "M_G_CPU1_SB_DQS_DN<3>")
	)
	(segment
		(start 179.885086 -199.686672)
		(end 178.798728 -199.686672)
		(width 0.18288)
		(layer "In6.Cu")
		(net "M_G_CPU1_SB_DQS_DN<3>")
	)
	(segment
		(start 178.798728 -199.686672)
		(end 177.914808 -200.570592)
		(width 0.18288)
		(layer "In6.Cu")
		(net "M_G_CPU1_SB_DQS_DN<3>")
	)
	(segment
		(start 142.031212 -216.551256)
		(end 142.031212 -216.983056)
		(width 0.088646)
		(layer "In6.Cu")
		(net "M_G_CPU1_SB_DQS_DN<3>")
	)
	(segment
		(start 172.609256 -198.59244)
		(end 172.362622 -198.839074)
		(width 0.18288)
		(layer "In6.Cu")
		(net "M_G_CPU1_SB_DQS_DN<3>")
	)
	(segment
		(start 137.819638 -218.227402)
		(end 137.798556 -218.149424)
		(width 0.088646)
		(layer "In6.Cu")
		(net "M_G_CPU1_SB_DQS_DN<3>")
	)
	(segment
		(start 180.485542 -200.287128)
		(end 179.885086 -199.686672)
		(width 0.18288)
		(layer "In6.Cu")
		(net "M_G_CPU1_SB_DQS_DN<3>")
	)
	(segment
		(start 141.49451 -218.038172)
		(end 141.405864 -218.126818)
		(width 0.088646)
		(layer "In6.Cu")
		(net "M_G_CPU1_SB_DQS_DN<3>")
	)
	(segment
		(start 182.332122 -199.663812)
		(end 181.697122 -199.663812)
		(width 0.18288)
		(layer "In6.Cu")
		(net "M_G_CPU1_SB_DQS_DN<3>")
	)
	(segment
		(start 175.116744 -199.885046)
		(end 174.102268 -198.87057)
		(width 0.18288)
		(layer "In6.Cu")
		(net "M_G_CPU1_SB_DQS_DN<3>")
	)
	(segment
		(start 141.405864 -218.126818)
		(end 141.24305 -218.126818)
		(width 0.088646)
		(layer "In6.Cu")
		(net "M_G_CPU1_SB_DQS_DN<3>")
	)
	(segment
		(start 142.196058 -216.38641)
		(end 142.031212 -216.551256)
		(width 0.088646)
		(layer "In6.Cu")
		(net "M_G_CPU1_SB_DQS_DN<3>")
	)
	(segment
		(start 157.57271 -199.459596)
		(end 149.294342 -207.737964)
		(width 0.18288)
		(layer "In6.Cu")
		(net "M_G_CPU1_SB_DQS_DN<3>")
	)
	(segment
		(start 142.031212 -216.983056)
		(end 141.49451 -217.519758)
		(width 0.088646)
		(layer "In6.Cu")
		(net "M_G_CPU1_SB_DQS_DN<3>")
	)
	(segment
		(start 177.371502 -200.570592)
		(end 177.093372 -200.292462)
		(width 0.18288)
		(layer "In6.Cu")
		(net "M_G_CPU1_SB_DQS_DN<3>")
	)
	(segment
		(start 169.48912 -198.839074)
		(end 168.868598 -199.459596)
		(width 0.18288)
		(layer "In6.Cu")
		(net "M_G_CPU1_SB_DQS_DN<3>")
	)
	(segment
		(start 187.224416 -200.122282)
		(end 186.808872 -199.706738)
		(width 0.18288)
		(layer "In6.Cu")
		(net "M_G_CPU1_SB_DQS_DN<3>")
	)
	(segment
		(start 141.49451 -217.519758)
		(end 141.49451 -218.038172)
		(width 0.088646)
		(layer "In6.Cu")
		(net "M_G_CPU1_SB_DQS_DN<3>")
	)
	(segment
		(start 173.263814 -198.87057)
		(end 172.985684 -198.59244)
		(width 0.18288)
		(layer "In6.Cu")
		(net "M_G_CPU1_SB_DQS_DN<3>")
	)
	(segment
		(start 187.628022 -200.122282)
		(end 187.224416 -200.122282)
		(width 0.18288)
		(layer "In6.Cu")
		(net "M_G_CPU1_SB_DQS_DN<3>")
	)
	(segment
		(start 181.073806 -200.287128)
		(end 180.485542 -200.287128)
		(width 0.18288)
		(layer "In6.Cu")
		(net "M_G_CPU1_SB_DQS_DN<3>")
	)
	(segment
		(start 140.586714 -218.202764)
		(end 140.571982 -218.194128)
		(width 0.088646)
		(layer "In6.Cu")
		(net "M_G_CPU1_SB_DQS_DN<3>")
	)
	(segment
		(start 177.914808 -200.570592)
		(end 177.371502 -200.570592)
		(width 0.18288)
		(layer "In6.Cu")
		(net "M_G_CPU1_SB_DQS_DN<3>")
	)
	(segment
		(start 172.985684 -198.59244)
		(end 172.609256 -198.59244)
		(width 0.18288)
		(layer "In6.Cu")
		(net "M_G_CPU1_SB_DQS_DN<3>")
	)
	(segment
		(start 183.650382 -200.27392)
		(end 182.94223 -200.27392)
		(width 0.18288)
		(layer "In6.Cu")
		(net "M_G_CPU1_SB_DQS_DN<3>")
	)
	(segment
		(start 168.868598 -199.459596)
		(end 157.57271 -199.459596)
		(width 0.18288)
		(layer "In6.Cu")
		(net "M_G_CPU1_SB_DQS_DN<3>")
	)
	(segment
		(start 176.19345 -200.570592)
		(end 175.507904 -199.885046)
		(width 0.18288)
		(layer "In6.Cu")
		(net "M_G_CPU1_SB_DQS_DN<3>")
	)
	(segment
		(start 174.102268 -198.87057)
		(end 173.263814 -198.87057)
		(width 0.18288)
		(layer "In6.Cu")
		(net "M_G_CPU1_SB_DQS_DN<3>")
	)
	(segment
		(start 186.808872 -199.706738)
		(end 184.217564 -199.706738)
		(width 0.18288)
		(layer "In6.Cu")
		(net "M_G_CPU1_SB_DQS_DN<3>")
	)
	(segment
		(start 177.093372 -200.292462)
		(end 176.7205 -200.292462)
		(width 0.18288)
		(layer "In6.Cu")
		(net "M_G_CPU1_SB_DQS_DN<3>")
	)
	(segment
		(start 172.362622 -198.839074)
		(end 169.48912 -198.839074)
		(width 0.18288)
		(layer "In6.Cu")
		(net "M_G_CPU1_SB_DQS_DN<3>")
	)
	(segment
		(start 181.697122 -199.663812)
		(end 181.073806 -200.287128)
		(width 0.18288)
		(layer "In6.Cu")
		(net "M_G_CPU1_SB_DQS_DN<3>")
	)
	(segment
		(start 142.212568 -216.285572)
		(end 142.196058 -216.302082)
		(width 0.088646)
		(layer "In6.Cu")
		(net "M_G_CPU1_SB_DQS_DN<3>")
	)
	(segment
		(start 175.507904 -199.885046)
		(end 175.116744 -199.885046)
		(width 0.18288)
		(layer "In6.Cu")
		(net "M_G_CPU1_SB_DQS_DN<3>")
	)
	(segment
		(start 149.294342 -209.203798)
		(end 142.212568 -216.285572)
		(width 0.18288)
		(layer "In6.Cu")
		(net "M_G_CPU1_SB_DQS_DN<3>")
	)
	(segment
		(start 149.294342 -207.737964)
		(end 149.294342 -209.203798)
		(width 0.18288)
		(layer "In6.Cu")
		(net "M_G_CPU1_SB_DQS_DN<3>")
	)
	(segment
		(start 184.217564 -199.706738)
		(end 183.650382 -200.27392)
		(width 0.18288)
		(layer "In6.Cu")
		(net "M_G_CPU1_SB_DQS_DN<3>")
	)
	(segment
		(start 142.196058 -216.302082)
		(end 142.196058 -216.38641)
		(width 0.088646)
		(layer "In6.Cu")
		(net "M_G_CPU1_SB_DQS_DN<3>")
	)
	(segment
		(start 176.7205 -200.292462)
		(end 176.44237 -200.570592)
		(width 0.18288)
		(layer "In6.Cu")
		(net "M_G_CPU1_SB_DQS_DN<3>")
	)
	(segment
		(start 137.798556 -218.149424)
		(end 137.95502 -217.878406)
		(width 0.088646)
		(layer "In6.Cu")
		(net "M_G_CPU1_SB_DQS_DN<3>")
	)
	(segment
		(start 182.94223 -200.27392)
		(end 182.332122 -199.663812)
		(width 0.18288)
		(layer "In6.Cu")
		(net "M_G_CPU1_SB_DQS_DN<3>")
	)
	(arc
		(start 138.142218 -218.202764)
		(mid 137.98373 -218.251697)
		(end 137.819638 -218.227402)
		(width 0.088646)
		(layer "In6.Cu")
		(net "M_G_CPU1_SB_DQS_DN<3>")
	)
	(arc
		(start 139.08151 -218.202764)
		(mid 138.894312 -218.252907)
		(end 138.707114 -218.202764)
		(width 0.088646)
		(layer "In6.Cu")
		(net "M_G_CPU1_SB_DQS_DN<3>")
	)
	(arc
		(start 140.955522 -218.205812)
		(mid 140.77073 -218.252795)
		(end 140.586714 -218.202764)
		(width 0.088646)
		(layer "In6.Cu")
		(net "M_G_CPU1_SB_DQS_DN<3>")
	)
	(arc
		(start 141.24305 -218.126818)
		(mid 141.093953 -218.146915)
		(end 140.955522 -218.205812)
		(width 0.088646)
		(layer "In6.Cu")
		(net "M_G_CPU1_SB_DQS_DN<3>")
	)
	(arc
		(start 140.02131 -218.202764)
		(mid 139.834112 -218.252907)
		(end 139.646914 -218.202764)
		(width 0.088646)
		(layer "In6.Cu")
		(net "M_G_CPU1_SB_DQS_DN<3>")
	)
	(arc
		(start 138.707114 -218.202764)
		(mid 138.424666 -218.127115)
		(end 138.142218 -218.202764)
		(width 0.088646)
		(layer "In6.Cu")
		(net "M_G_CPU1_SB_DQS_DN<3>")
	)
	(arc
		(start 140.571982 -218.194128)
		(mid 140.295507 -218.126808)
		(end 140.02131 -218.202764)
		(width 0.088646)
		(layer "In6.Cu")
		(net "M_G_CPU1_SB_DQS_DN<3>")
	)
	(arc
		(start 139.632182 -218.194128)
		(mid 139.355707 -218.126808)
		(end 139.08151 -218.202764)
		(width 0.088646)
		(layer "In6.Cu")
		(net "M_G_CPU1_SB_DQS_DN<3>")
	)
	(segment
		(start 130.436112 -233.064304)
		(end 130.436112 -232.528618)
		(width 0.20066)
		(layer "F.Cu")
		(net "M_G_CPU1_SB_DQS_DN<2>")
	)
	(segment
		(start 190.55461 -209.498438)
		(end 190.969138 -209.912966)
		(width 0.20066)
		(layer "F.Cu")
		(net "M_G_CPU1_SB_DQS_DN<2>")
	)
	(segment
		(start 194.959478 -209.867754)
		(end 195.369942 -209.45729)
		(width 0.20066)
		(layer "F.Cu")
		(net "M_G_CPU1_SB_DQS_DN<2>")
	)
	(segment
		(start 195.369942 -209.45729)
		(end 195.702428 -209.45729)
		(width 0.20066)
		(layer "F.Cu")
		(net "M_G_CPU1_SB_DQS_DN<2>")
	)
	(segment
		(start 189.537086 -209.216752)
		(end 189.818772 -209.498438)
		(width 0.20066)
		(layer "F.Cu")
		(net "M_G_CPU1_SB_DQS_DN<2>")
	)
	(segment
		(start 189.818772 -209.498438)
		(end 190.55461 -209.498438)
		(width 0.20066)
		(layer "F.Cu")
		(net "M_G_CPU1_SB_DQS_DN<2>")
	)
	(segment
		(start 188.988446 -209.216752)
		(end 189.537086 -209.216752)
		(width 0.20066)
		(layer "F.Cu")
		(net "M_G_CPU1_SB_DQS_DN<2>")
	)
	(segment
		(start 195.942966 -209.216752)
		(end 196.532246 -209.216752)
		(width 0.20066)
		(layer "F.Cu")
		(net "M_G_CPU1_SB_DQS_DN<2>")
	)
	(segment
		(start 194.654424 -209.867754)
		(end 194.959478 -209.867754)
		(width 0.20066)
		(layer "F.Cu")
		(net "M_G_CPU1_SB_DQS_DN<2>")
	)
	(segment
		(start 191.914018 -209.641694)
		(end 194.093592 -209.641694)
		(width 0.1016)
		(layer "F.Cu")
		(net "M_G_CPU1_SB_DQS_DN<2>")
	)
	(segment
		(start 194.098926 -209.63636)
		(end 194.42303 -209.63636)
		(width 0.20066)
		(layer "F.Cu")
		(net "M_G_CPU1_SB_DQS_DN<2>")
	)
	(segment
		(start 130.436112 -232.528618)
		(end 130.436366 -232.528364)
		(width 0.20066)
		(layer "F.Cu")
		(net "M_G_CPU1_SB_DQS_DN<2>")
	)
	(segment
		(start 194.42303 -209.63636)
		(end 194.654424 -209.867754)
		(width 0.20066)
		(layer "F.Cu")
		(net "M_G_CPU1_SB_DQS_DN<2>")
	)
	(segment
		(start 194.093592 -209.641694)
		(end 194.098926 -209.63636)
		(width 0.1016)
		(layer "F.Cu")
		(net "M_G_CPU1_SB_DQS_DN<2>")
	)
	(segment
		(start 190.969138 -209.912966)
		(end 191.490854 -209.912966)
		(width 0.20066)
		(layer "F.Cu")
		(net "M_G_CPU1_SB_DQS_DN<2>")
	)
	(segment
		(start 191.9097 -209.641694)
		(end 191.914018 -209.641694)
		(width 0.101854)
		(layer "F.Cu")
		(net "M_G_CPU1_SB_DQS_DN<2>")
	)
	(segment
		(start 191.490854 -209.912966)
		(end 191.762126 -209.641694)
		(width 0.20066)
		(layer "F.Cu")
		(net "M_G_CPU1_SB_DQS_DN<2>")
	)
	(segment
		(start 187.883546 -209.216752)
		(end 188.988446 -209.216752)
		(width 0.20066)
		(layer "F.Cu")
		(net "M_G_CPU1_SB_DQS_DN<2>")
	)
	(segment
		(start 191.762126 -209.641694)
		(end 191.9097 -209.641694)
		(width 0.20066)
		(layer "F.Cu")
		(net "M_G_CPU1_SB_DQS_DN<2>")
	)
	(segment
		(start 195.702428 -209.45729)
		(end 195.942966 -209.216752)
		(width 0.20066)
		(layer "F.Cu")
		(net "M_G_CPU1_SB_DQS_DN<2>")
	)
	(segment
		(start 186.081162 -209.26171)
		(end 185.695082 -209.64779)
		(width 0.18288)
		(layer "In4.Cu")
		(net "M_G_CPU1_SB_DQS_DN<2>")
	)
	(segment
		(start 177.089816 -213.0425)
		(end 176.68494 -213.0425)
		(width 0.18288)
		(layer "In4.Cu")
		(net "M_G_CPU1_SB_DQS_DN<2>")
	)
	(segment
		(start 138.1506 -231.219756)
		(end 138.14171 -231.224836)
		(width 0.088646)
		(layer "In4.Cu")
		(net "M_G_CPU1_SB_DQS_DN<2>")
	)
	(segment
		(start 133.068314 -232.852722)
		(end 133.0579 -232.846626)
		(width 0.088646)
		(layer "In4.Cu")
		(net "M_G_CPU1_SB_DQS_DN<2>")
	)
	(segment
		(start 172.334936 -212.442552)
		(end 171.2087 -212.442552)
		(width 0.18288)
		(layer "In4.Cu")
		(net "M_G_CPU1_SB_DQS_DN<2>")
	)
	(segment
		(start 177.347626 -213.30031)
		(end 177.089816 -213.0425)
		(width 0.18288)
		(layer "In4.Cu")
		(net "M_G_CPU1_SB_DQS_DN<2>")
	)
	(segment
		(start 180.501036 -213.410292)
		(end 179.996592 -213.410292)
		(width 0.18288)
		(layer "In4.Cu")
		(net "M_G_CPU1_SB_DQS_DN<2>")
	)
	(segment
		(start 130.638296 -232.844086)
		(end 130.623564 -232.852722)
		(width 0.088646)
		(layer "In4.Cu")
		(net "M_G_CPU1_SB_DQS_DN<2>")
	)
	(segment
		(start 178.25212 -213.30031)
		(end 177.347626 -213.30031)
		(width 0.18288)
		(layer "In4.Cu")
		(net "M_G_CPU1_SB_DQS_DN<2>")
	)
	(segment
		(start 185.132726 -210.034124)
		(end 185.132726 -210.210146)
		(width 0.18288)
		(layer "In4.Cu")
		(net "M_G_CPU1_SB_DQS_DN<2>")
	)
	(segment
		(start 184.17413 -210.697318)
		(end 183.238902 -211.632546)
		(width 0.18288)
		(layer "In4.Cu")
		(net "M_G_CPU1_SB_DQS_DN<2>")
	)
	(segment
		(start 179.996592 -213.410292)
		(end 179.48656 -213.920324)
		(width 0.18288)
		(layer "In4.Cu")
		(net "M_G_CPU1_SB_DQS_DN<2>")
	)
	(segment
		(start 182.278782 -211.632546)
		(end 181.661562 -212.249766)
		(width 0.18288)
		(layer "In4.Cu")
		(net "M_G_CPU1_SB_DQS_DN<2>")
	)
	(segment
		(start 159.24276 -213.08822)
		(end 159.1183 -212.96376)
		(width 0.18288)
		(layer "In4.Cu")
		(net "M_G_CPU1_SB_DQS_DN<2>")
	)
	(segment
		(start 173.24832 -212.451188)
		(end 172.989748 -212.192616)
		(width 0.18288)
		(layer "In4.Cu")
		(net "M_G_CPU1_SB_DQS_DN<2>")
	)
	(segment
		(start 143.498316 -227.491544)
		(end 140.772642 -227.491544)
		(width 0.18288)
		(layer "In4.Cu")
		(net "M_G_CPU1_SB_DQS_DN<2>")
	)
	(segment
		(start 185.132726 -210.210146)
		(end 184.645554 -210.697318)
		(width 0.18288)
		(layer "In4.Cu")
		(net "M_G_CPU1_SB_DQS_DN<2>")
	)
	(segment
		(start 158.5722 -212.96376)
		(end 158.44774 -213.08822)
		(width 0.18288)
		(layer "In4.Cu")
		(net "M_G_CPU1_SB_DQS_DN<2>")
	)
	(segment
		(start 158.44774 -213.08822)
		(end 157.90164 -213.08822)
		(width 0.18288)
		(layer "In4.Cu")
		(net "M_G_CPU1_SB_DQS_DN<2>")
	)
	(segment
		(start 137.6807 -232.033826)
		(end 137.672826 -232.038398)
		(width 0.088646)
		(layer "In4.Cu")
		(net "M_G_CPU1_SB_DQS_DN<2>")
	)
	(segment
		(start 178.872134 -213.920324)
		(end 178.25212 -213.30031)
		(width 0.18288)
		(layer "In4.Cu")
		(net "M_G_CPU1_SB_DQS_DN<2>")
	)
	(segment
		(start 181.098952 -212.636354)
		(end 181.098952 -212.812376)
		(width 0.18288)
		(layer "In4.Cu")
		(net "M_G_CPU1_SB_DQS_DN<2>")
	)
	(segment
		(start 170.138852 -212.880448)
		(end 169.932096 -212.673692)
		(width 0.18288)
		(layer "In4.Cu")
		(net "M_G_CPU1_SB_DQS_DN<2>")
	)
	(segment
		(start 170.770804 -212.880448)
		(end 170.138852 -212.880448)
		(width 0.18288)
		(layer "In4.Cu")
		(net "M_G_CPU1_SB_DQS_DN<2>")
	)
	(segment
		(start 131.578096 -232.844086)
		(end 131.563364 -232.852722)
		(width 0.088646)
		(layer "In4.Cu")
		(net "M_G_CPU1_SB_DQS_DN<2>")
	)
	(segment
		(start 187.883546 -209.216752)
		(end 187.591954 -209.508344)
		(width 0.18288)
		(layer "In4.Cu")
		(net "M_G_CPU1_SB_DQS_DN<2>")
	)
	(segment
		(start 140.749274 -227.491544)
		(end 140.689584 -227.551234)
		(width 0.088646)
		(layer "In4.Cu")
		(net "M_G_CPU1_SB_DQS_DN<2>")
	)
	(segment
		(start 160.929828 -212.606128)
		(end 160.447736 -213.08822)
		(width 0.18288)
		(layer "In4.Cu")
		(net "M_G_CPU1_SB_DQS_DN<2>")
	)
	(segment
		(start 140.689584 -227.551234)
		(end 140.404342 -227.551234)
		(width 0.088646)
		(layer "In4.Cu")
		(net "M_G_CPU1_SB_DQS_DN<2>")
	)
	(segment
		(start 176.435004 -213.292436)
		(end 174.994824 -213.292436)
		(width 0.18288)
		(layer "In4.Cu")
		(net "M_G_CPU1_SB_DQS_DN<2>")
	)
	(segment
		(start 160.447736 -213.08822)
		(end 159.24276 -213.08822)
		(width 0.18288)
		(layer "In4.Cu")
		(net "M_G_CPU1_SB_DQS_DN<2>")
	)
	(segment
		(start 183.238902 -211.632546)
		(end 182.278782 -211.632546)
		(width 0.18288)
		(layer "In4.Cu")
		(net "M_G_CPU1_SB_DQS_DN<2>")
	)
	(segment
		(start 171.2087 -212.442552)
		(end 170.770804 -212.880448)
		(width 0.18288)
		(layer "In4.Cu")
		(net "M_G_CPU1_SB_DQS_DN<2>")
	)
	(segment
		(start 168.73093 -212.673692)
		(end 168.291256 -213.113366)
		(width 0.18288)
		(layer "In4.Cu")
		(net "M_G_CPU1_SB_DQS_DN<2>")
	)
	(segment
		(start 187.085986 -209.26171)
		(end 186.081162 -209.26171)
		(width 0.18288)
		(layer "In4.Cu")
		(net "M_G_CPU1_SB_DQS_DN<2>")
	)
	(segment
		(start 130.066288 -232.585768)
		(end 130.123692 -232.528364)
		(width 0.088646)
		(layer "In4.Cu")
		(net "M_G_CPU1_SB_DQS_DN<2>")
	)
	(segment
		(start 174.153576 -212.451188)
		(end 173.24832 -212.451188)
		(width 0.18288)
		(layer "In4.Cu")
		(net "M_G_CPU1_SB_DQS_DN<2>")
	)
	(segment
		(start 169.932096 -212.673692)
		(end 168.73093 -212.673692)
		(width 0.18288)
		(layer "In4.Cu")
		(net "M_G_CPU1_SB_DQS_DN<2>")
	)
	(segment
		(start 157.90164 -213.08822)
		(end 143.498316 -227.491544)
		(width 0.18288)
		(layer "In4.Cu")
		(net "M_G_CPU1_SB_DQS_DN<2>")
	)
	(segment
		(start 179.48656 -213.920324)
		(end 178.872134 -213.920324)
		(width 0.18288)
		(layer "In4.Cu")
		(net "M_G_CPU1_SB_DQS_DN<2>")
	)
	(segment
		(start 174.994824 -213.292436)
		(end 174.153576 -212.451188)
		(width 0.18288)
		(layer "In4.Cu")
		(net "M_G_CPU1_SB_DQS_DN<2>")
	)
	(segment
		(start 172.989748 -212.192616)
		(end 172.584872 -212.192616)
		(width 0.18288)
		(layer "In4.Cu")
		(net "M_G_CPU1_SB_DQS_DN<2>")
	)
	(segment
		(start 138.799316 -230.076756)
		(end 138.799316 -230.086662)
		(width 0.088646)
		(layer "In4.Cu")
		(net "M_G_CPU1_SB_DQS_DN<2>")
	)
	(segment
		(start 137.672826 -232.038398)
		(end 137.67181 -232.038906)
		(width 0.088646)
		(layer "In4.Cu")
		(net "M_G_CPU1_SB_DQS_DN<2>")
	)
	(segment
		(start 159.1183 -212.96376)
		(end 158.5722 -212.96376)
		(width 0.18288)
		(layer "In4.Cu")
		(net "M_G_CPU1_SB_DQS_DN<2>")
	)
	(segment
		(start 138.611864 -230.41102)
		(end 138.599672 -230.418132)
		(width 0.088646)
		(layer "In4.Cu")
		(net "M_G_CPU1_SB_DQS_DN<2>")
	)
	(segment
		(start 134.008368 -232.852722)
		(end 133.997954 -232.846626)
		(width 0.088646)
		(layer "In4.Cu")
		(net "M_G_CPU1_SB_DQS_DN<2>")
	)
	(segment
		(start 137.389616 -232.51287)
		(end 137.389616 -232.528364)
		(width 0.088646)
		(layer "In4.Cu")
		(net "M_G_CPU1_SB_DQS_DN<2>")
	)
	(segment
		(start 164.800788 -213.053676)
		(end 164.35324 -212.606128)
		(width 0.18288)
		(layer "In4.Cu")
		(net "M_G_CPU1_SB_DQS_DN<2>")
	)
	(segment
		(start 176.68494 -213.0425)
		(end 176.435004 -213.292436)
		(width 0.18288)
		(layer "In4.Cu")
		(net "M_G_CPU1_SB_DQS_DN<2>")
	)
	(segment
		(start 167.3352 -213.113366)
		(end 166.9796 -212.757766)
		(width 0.18288)
		(layer "In4.Cu")
		(net "M_G_CPU1_SB_DQS_DN<2>")
	)
	(segment
		(start 185.51906 -209.64779)
		(end 185.132726 -210.034124)
		(width 0.18288)
		(layer "In4.Cu")
		(net "M_G_CPU1_SB_DQS_DN<2>")
	)
	(segment
		(start 166.9796 -212.757766)
		(end 165.882828 -212.757766)
		(width 0.18288)
		(layer "In4.Cu")
		(net "M_G_CPU1_SB_DQS_DN<2>")
	)
	(segment
		(start 164.35324 -212.606128)
		(end 160.929828 -212.606128)
		(width 0.18288)
		(layer "In4.Cu")
		(net "M_G_CPU1_SB_DQS_DN<2>")
	)
	(segment
		(start 181.661562 -212.249766)
		(end 181.48554 -212.249766)
		(width 0.18288)
		(layer "In4.Cu")
		(net "M_G_CPU1_SB_DQS_DN<2>")
	)
	(segment
		(start 137.859262 -231.700324)
		(end 137.859262 -231.714548)
		(width 0.088646)
		(layer "In4.Cu")
		(net "M_G_CPU1_SB_DQS_DN<2>")
	)
	(segment
		(start 130.249168 -232.852722)
		(end 130.240278 -232.847642)
		(width 0.088646)
		(layer "In4.Cu")
		(net "M_G_CPU1_SB_DQS_DN<2>")
	)
	(segment
		(start 181.098952 -212.812376)
		(end 180.501036 -213.410292)
		(width 0.18288)
		(layer "In4.Cu")
		(net "M_G_CPU1_SB_DQS_DN<2>")
	)
	(segment
		(start 181.48554 -212.249766)
		(end 181.098952 -212.636354)
		(width 0.18288)
		(layer "In4.Cu")
		(net "M_G_CPU1_SB_DQS_DN<2>")
	)
	(segment
		(start 137.211054 -232.847642)
		(end 137.202164 -232.852722)
		(width 0.088646)
		(layer "In4.Cu")
		(net "M_G_CPU1_SB_DQS_DN<2>")
	)
	(segment
		(start 187.591954 -209.508344)
		(end 187.33262 -209.508344)
		(width 0.18288)
		(layer "In4.Cu")
		(net "M_G_CPU1_SB_DQS_DN<2>")
	)
	(segment
		(start 139.790932 -228.164644)
		(end 139.790932 -228.87813)
		(width 0.088646)
		(layer "In4.Cu")
		(net "M_G_CPU1_SB_DQS_DN<2>")
	)
	(segment
		(start 138.620754 -230.40594)
		(end 138.611864 -230.41102)
		(width 0.088646)
		(layer "In4.Cu")
		(net "M_G_CPU1_SB_DQS_DN<2>")
	)
	(segment
		(start 165.586918 -213.053676)
		(end 164.800788 -213.053676)
		(width 0.18288)
		(layer "In4.Cu")
		(net "M_G_CPU1_SB_DQS_DN<2>")
	)
	(segment
		(start 165.882828 -212.757766)
		(end 165.586918 -213.053676)
		(width 0.18288)
		(layer "In4.Cu")
		(net "M_G_CPU1_SB_DQS_DN<2>")
	)
	(segment
		(start 184.645554 -210.697318)
		(end 184.17413 -210.697318)
		(width 0.18288)
		(layer "In4.Cu")
		(net "M_G_CPU1_SB_DQS_DN<2>")
	)
	(segment
		(start 168.291256 -213.113366)
		(end 167.3352 -213.113366)
		(width 0.18288)
		(layer "In4.Cu")
		(net "M_G_CPU1_SB_DQS_DN<2>")
	)
	(segment
		(start 140.404342 -227.551234)
		(end 139.790932 -228.164644)
		(width 0.088646)
		(layer "In4.Cu")
		(net "M_G_CPU1_SB_DQS_DN<2>")
	)
	(segment
		(start 139.790932 -228.87813)
		(end 139.055602 -229.61346)
		(width 0.088646)
		(layer "In4.Cu")
		(net "M_G_CPU1_SB_DQS_DN<2>")
	)
	(segment
		(start 140.772642 -227.491544)
		(end 140.749274 -227.491544)
		(width 0.088646)
		(layer "In4.Cu")
		(net "M_G_CPU1_SB_DQS_DN<2>")
	)
	(segment
		(start 130.123692 -232.528364)
		(end 130.436366 -232.528364)
		(width 0.088646)
		(layer "In4.Cu")
		(net "M_G_CPU1_SB_DQS_DN<2>")
	)
	(segment
		(start 172.584872 -212.192616)
		(end 172.334936 -212.442552)
		(width 0.18288)
		(layer "In4.Cu")
		(net "M_G_CPU1_SB_DQS_DN<2>")
	)
	(segment
		(start 187.33262 -209.508344)
		(end 187.085986 -209.26171)
		(width 0.18288)
		(layer "In4.Cu")
		(net "M_G_CPU1_SB_DQS_DN<2>")
	)
	(segment
		(start 185.695082 -209.64779)
		(end 185.51906 -209.64779)
		(width 0.18288)
		(layer "In4.Cu")
		(net "M_G_CPU1_SB_DQS_DN<2>")
	)
	(arc
		(start 136.827768 -232.852722)
		(mid 136.545066 -232.776946)
		(end 136.262364 -232.852722)
		(width 0.088646)
		(layer "In4.Cu")
		(net "M_G_CPU1_SB_DQS_DN<2>")
	)
	(arc
		(start 134.948168 -232.852722)
		(mid 134.665466 -232.776946)
		(end 134.382764 -232.852722)
		(width 0.088646)
		(layer "In4.Cu")
		(net "M_G_CPU1_SB_DQS_DN<2>")
	)
	(arc
		(start 130.623564 -232.852722)
		(mid 130.436366 -232.902865)
		(end 130.249168 -232.852722)
		(width 0.088646)
		(layer "In4.Cu")
		(net "M_G_CPU1_SB_DQS_DN<2>")
	)
	(arc
		(start 138.799316 -230.086662)
		(mid 138.751637 -230.269562)
		(end 138.620754 -230.40594)
		(width 0.088646)
		(layer "In4.Cu")
		(net "M_G_CPU1_SB_DQS_DN<2>")
	)
	(arc
		(start 131.563364 -232.852722)
		(mid 131.376166 -232.902865)
		(end 131.188968 -232.852722)
		(width 0.088646)
		(layer "In4.Cu")
		(net "M_G_CPU1_SB_DQS_DN<2>")
	)
	(arc
		(start 134.382764 -232.852722)
		(mid 134.195566 -232.902865)
		(end 134.008368 -232.852722)
		(width 0.088646)
		(layer "In4.Cu")
		(net "M_G_CPU1_SB_DQS_DN<2>")
	)
	(arc
		(start 136.262364 -232.852722)
		(mid 136.075166 -232.902865)
		(end 135.887968 -232.852722)
		(width 0.088646)
		(layer "In4.Cu")
		(net "M_G_CPU1_SB_DQS_DN<2>")
	)
	(arc
		(start 133.0579 -232.846626)
		(mid 132.779722 -232.776903)
		(end 132.503164 -232.852722)
		(width 0.088646)
		(layer "In4.Cu")
		(net "M_G_CPU1_SB_DQS_DN<2>")
	)
	(arc
		(start 138.599672 -230.418132)
		(mid 138.401444 -230.62398)
		(end 138.329162 -230.900478)
		(width 0.088646)
		(layer "In4.Cu")
		(net "M_G_CPU1_SB_DQS_DN<2>")
	)
	(arc
		(start 135.887968 -232.852722)
		(mid 135.605266 -232.776946)
		(end 135.322564 -232.852722)
		(width 0.088646)
		(layer "In4.Cu")
		(net "M_G_CPU1_SB_DQS_DN<2>")
	)
	(arc
		(start 132.128768 -232.852722)
		(mid 131.854569 -232.776887)
		(end 131.578096 -232.844086)
		(width 0.088646)
		(layer "In4.Cu")
		(net "M_G_CPU1_SB_DQS_DN<2>")
	)
	(arc
		(start 133.997954 -232.846626)
		(mid 133.719522 -232.77678)
		(end 133.44271 -232.852722)
		(width 0.088646)
		(layer "In4.Cu")
		(net "M_G_CPU1_SB_DQS_DN<2>")
	)
	(arc
		(start 132.503164 -232.852722)
		(mid 132.315966 -232.902865)
		(end 132.128768 -232.852722)
		(width 0.088646)
		(layer "In4.Cu")
		(net "M_G_CPU1_SB_DQS_DN<2>")
	)
	(arc
		(start 137.67181 -232.038906)
		(mid 137.468987 -232.239137)
		(end 137.389616 -232.51287)
		(width 0.088646)
		(layer "In4.Cu")
		(net "M_G_CPU1_SB_DQS_DN<2>")
	)
	(arc
		(start 139.055602 -229.61346)
		(mid 138.869836 -229.81324)
		(end 138.799316 -230.076756)
		(width 0.088646)
		(layer "In4.Cu")
		(net "M_G_CPU1_SB_DQS_DN<2>")
	)
	(arc
		(start 131.188968 -232.852722)
		(mid 130.914769 -232.776887)
		(end 130.638296 -232.844086)
		(width 0.088646)
		(layer "In4.Cu")
		(net "M_G_CPU1_SB_DQS_DN<2>")
	)
	(arc
		(start 130.240278 -232.847642)
		(mid 130.124539 -232.735818)
		(end 130.066288 -232.585768)
		(width 0.088646)
		(layer "In4.Cu")
		(net "M_G_CPU1_SB_DQS_DN<2>")
	)
	(arc
		(start 137.389616 -232.528364)
		(mid 137.341937 -232.711264)
		(end 137.211054 -232.847642)
		(width 0.088646)
		(layer "In4.Cu")
		(net "M_G_CPU1_SB_DQS_DN<2>")
	)
	(arc
		(start 133.44271 -232.852722)
		(mid 133.255512 -232.902865)
		(end 133.068314 -232.852722)
		(width 0.088646)
		(layer "In4.Cu")
		(net "M_G_CPU1_SB_DQS_DN<2>")
	)
	(arc
		(start 137.859262 -231.714548)
		(mid 137.811583 -231.897448)
		(end 137.6807 -232.033826)
		(width 0.088646)
		(layer "In4.Cu")
		(net "M_G_CPU1_SB_DQS_DN<2>")
	)
	(arc
		(start 137.202164 -232.852722)
		(mid 137.014966 -232.902865)
		(end 136.827768 -232.852722)
		(width 0.088646)
		(layer "In4.Cu")
		(net "M_G_CPU1_SB_DQS_DN<2>")
	)
	(arc
		(start 138.329162 -230.900478)
		(mid 138.281483 -231.083378)
		(end 138.1506 -231.219756)
		(width 0.088646)
		(layer "In4.Cu")
		(net "M_G_CPU1_SB_DQS_DN<2>")
	)
	(arc
		(start 138.14171 -231.224836)
		(mid 137.938405 -231.425702)
		(end 137.859262 -231.700324)
		(width 0.088646)
		(layer "In4.Cu")
		(net "M_G_CPU1_SB_DQS_DN<2>")
	)
	(arc
		(start 135.322564 -232.852722)
		(mid 135.135366 -232.902865)
		(end 134.948168 -232.852722)
		(width 0.088646)
		(layer "In4.Cu")
		(net "M_G_CPU1_SB_DQS_DN<2>")
	)
	(segment
		(start 194.654424 -219.217748)
		(end 194.959478 -219.217748)
		(width 0.20066)
		(layer "F.Cu")
		(net "M_G_CPU1_SB_DQS_DN<1>")
	)
	(segment
		(start 189.818772 -218.848432)
		(end 190.55461 -218.848432)
		(width 0.20066)
		(layer "F.Cu")
		(net "M_G_CPU1_SB_DQS_DN<1>")
	)
	(segment
		(start 194.42303 -218.986354)
		(end 194.654424 -219.217748)
		(width 0.20066)
		(layer "F.Cu")
		(net "M_G_CPU1_SB_DQS_DN<1>")
	)
	(segment
		(start 191.9097 -218.991688)
		(end 191.914018 -218.991688)
		(width 0.101854)
		(layer "F.Cu")
		(net "M_G_CPU1_SB_DQS_DN<1>")
	)
	(segment
		(start 187.883546 -218.566746)
		(end 188.988446 -218.566746)
		(width 0.20066)
		(layer "F.Cu")
		(net "M_G_CPU1_SB_DQS_DN<1>")
	)
	(segment
		(start 190.969138 -219.26296)
		(end 191.490854 -219.26296)
		(width 0.20066)
		(layer "F.Cu")
		(net "M_G_CPU1_SB_DQS_DN<1>")
	)
	(segment
		(start 194.093592 -218.991688)
		(end 194.098926 -218.986354)
		(width 0.1016)
		(layer "F.Cu")
		(net "M_G_CPU1_SB_DQS_DN<1>")
	)
	(segment
		(start 194.098926 -218.986354)
		(end 194.42303 -218.986354)
		(width 0.20066)
		(layer "F.Cu")
		(net "M_G_CPU1_SB_DQS_DN<1>")
	)
	(segment
		(start 191.762126 -218.991688)
		(end 191.9097 -218.991688)
		(width 0.20066)
		(layer "F.Cu")
		(net "M_G_CPU1_SB_DQS_DN<1>")
	)
	(segment
		(start 191.490854 -219.26296)
		(end 191.762126 -218.991688)
		(width 0.20066)
		(layer "F.Cu")
		(net "M_G_CPU1_SB_DQS_DN<1>")
	)
	(segment
		(start 189.537086 -218.566746)
		(end 189.818772 -218.848432)
		(width 0.20066)
		(layer "F.Cu")
		(net "M_G_CPU1_SB_DQS_DN<1>")
	)
	(segment
		(start 126.207266 -235.506006)
		(end 126.207012 -235.505752)
		(width 0.20066)
		(layer "F.Cu")
		(net "M_G_CPU1_SB_DQS_DN<1>")
	)
	(segment
		(start 188.988446 -218.566746)
		(end 189.537086 -218.566746)
		(width 0.20066)
		(layer "F.Cu")
		(net "M_G_CPU1_SB_DQS_DN<1>")
	)
	(segment
		(start 194.959478 -219.217748)
		(end 195.369942 -218.807284)
		(width 0.20066)
		(layer "F.Cu")
		(net "M_G_CPU1_SB_DQS_DN<1>")
	)
	(segment
		(start 126.207012 -235.505752)
		(end 126.207012 -234.970066)
		(width 0.20066)
		(layer "F.Cu")
		(net "M_G_CPU1_SB_DQS_DN<1>")
	)
	(segment
		(start 195.942966 -218.566746)
		(end 196.532246 -218.566746)
		(width 0.20066)
		(layer "F.Cu")
		(net "M_G_CPU1_SB_DQS_DN<1>")
	)
	(segment
		(start 195.702428 -218.807284)
		(end 195.942966 -218.566746)
		(width 0.20066)
		(layer "F.Cu")
		(net "M_G_CPU1_SB_DQS_DN<1>")
	)
	(segment
		(start 191.914018 -218.991688)
		(end 194.093592 -218.991688)
		(width 0.1016)
		(layer "F.Cu")
		(net "M_G_CPU1_SB_DQS_DN<1>")
	)
	(segment
		(start 195.369942 -218.807284)
		(end 195.702428 -218.807284)
		(width 0.20066)
		(layer "F.Cu")
		(net "M_G_CPU1_SB_DQS_DN<1>")
	)
	(segment
		(start 190.55461 -218.848432)
		(end 190.969138 -219.26296)
		(width 0.20066)
		(layer "F.Cu")
		(net "M_G_CPU1_SB_DQS_DN<1>")
	)
	(segment
		(start 126.863602 -234.481116)
		(end 126.858268 -234.484164)
		(width 0.088646)
		(layer "In6.Cu")
		(net "M_G_CPU1_SB_DQS_DN<1>")
	)
	(segment
		(start 132.517896 -234.471972)
		(end 132.503164 -234.480608)
		(width 0.088646)
		(layer "In6.Cu")
		(net "M_G_CPU1_SB_DQS_DN<1>")
	)
	(segment
		(start 136.277096 -234.471972)
		(end 136.262364 -234.480608)
		(width 0.088646)
		(layer "In6.Cu")
		(net "M_G_CPU1_SB_DQS_DN<1>")
	)
	(segment
		(start 163.739322 -218.673426)
		(end 162.430714 -219.982034)
		(width 0.18288)
		(layer "In6.Cu")
		(net "M_G_CPU1_SB_DQS_DN<1>")
	)
	(segment
		(start 137.203688 -234.479846)
		(end 137.202164 -234.480608)
		(width 0.088646)
		(layer "In6.Cu")
		(net "M_G_CPU1_SB_DQS_DN<1>")
	)
	(segment
		(start 187.113164 -218.828366)
		(end 186.848242 -218.563444)
		(width 0.18288)
		(layer "In6.Cu")
		(net "M_G_CPU1_SB_DQS_DN<1>")
	)
	(segment
		(start 140.038074 -232.821226)
		(end 139.978384 -232.880916)
		(width 0.088646)
		(layer "In6.Cu")
		(net "M_G_CPU1_SB_DQS_DN<1>")
	)
	(segment
		(start 173.95571 -221.829884)
		(end 173.270926 -221.829884)
		(width 0.18288)
		(layer "In6.Cu")
		(net "M_G_CPU1_SB_DQS_DN<1>")
	)
	(segment
		(start 172.609764 -221.54261)
		(end 172.338492 -221.813882)
		(width 0.18288)
		(layer "In6.Cu")
		(net "M_G_CPU1_SB_DQS_DN<1>")
	)
	(segment
		(start 126.879096 -234.471972)
		(end 126.864364 -234.480608)
		(width 0.088646)
		(layer "In6.Cu")
		(net "M_G_CPU1_SB_DQS_DN<1>")
	)
	(segment
		(start 130.638296 -234.471972)
		(end 130.623564 -234.480608)
		(width 0.088646)
		(layer "In6.Cu")
		(net "M_G_CPU1_SB_DQS_DN<1>")
	)
	(segment
		(start 137.389616 -234.137708)
		(end 137.389616 -234.15625)
		(width 0.088646)
		(layer "In6.Cu")
		(net "M_G_CPU1_SB_DQS_DN<1>")
	)
	(segment
		(start 127.818896 -234.471972)
		(end 127.804164 -234.480608)
		(width 0.088646)
		(layer "In6.Cu")
		(net "M_G_CPU1_SB_DQS_DN<1>")
	)
	(segment
		(start 140.843 -232.820972)
		(end 140.58138 -232.821226)
		(width 0.18288)
		(layer "In6.Cu")
		(net "M_G_CPU1_SB_DQS_DN<1>")
	)
	(segment
		(start 165.122098 -218.673426)
		(end 163.739322 -218.673426)
		(width 0.18288)
		(layer "In6.Cu")
		(net "M_G_CPU1_SB_DQS_DN<1>")
	)
	(segment
		(start 126.585472 -234.904534)
		(end 126.51994 -234.970066)
		(width 0.088646)
		(layer "In6.Cu")
		(net "M_G_CPU1_SB_DQS_DN<1>")
	)
	(segment
		(start 129.693924 -234.474512)
		(end 129.68351 -234.480608)
		(width 0.088646)
		(layer "In6.Cu")
		(net "M_G_CPU1_SB_DQS_DN<1>")
	)
	(segment
		(start 178.684428 -220.225366)
		(end 177.955702 -220.954092)
		(width 0.18288)
		(layer "In6.Cu")
		(net "M_G_CPU1_SB_DQS_DN<1>")
	)
	(segment
		(start 187.883546 -218.566746)
		(end 187.621926 -218.828366)
		(width 0.18288)
		(layer "In6.Cu")
		(net "M_G_CPU1_SB_DQS_DN<1>")
	)
	(segment
		(start 176.722024 -220.692472)
		(end 176.438814 -220.975682)
		(width 0.18288)
		(layer "In6.Cu")
		(net "M_G_CPU1_SB_DQS_DN<1>")
	)
	(segment
		(start 183.82615 -218.563444)
		(end 182.883048 -219.506546)
		(width 0.18288)
		(layer "In6.Cu")
		(net "M_G_CPU1_SB_DQS_DN<1>")
	)
	(segment
		(start 177.955702 -220.954092)
		(end 177.3301 -220.954092)
		(width 0.18288)
		(layer "In6.Cu")
		(net "M_G_CPU1_SB_DQS_DN<1>")
	)
	(segment
		(start 128.754378 -234.474512)
		(end 128.743964 -234.480608)
		(width 0.088646)
		(layer "In6.Cu")
		(net "M_G_CPU1_SB_DQS_DN<1>")
	)
	(segment
		(start 139.791694 -232.880916)
		(end 139.493244 -233.179366)
		(width 0.088646)
		(layer "In6.Cu")
		(net "M_G_CPU1_SB_DQS_DN<1>")
	)
	(segment
		(start 140.58138 -232.821226)
		(end 140.061442 -232.821226)
		(width 0.18288)
		(layer "In6.Cu")
		(net "M_G_CPU1_SB_DQS_DN<1>")
	)
	(segment
		(start 139.978384 -232.880916)
		(end 139.791694 -232.880916)
		(width 0.088646)
		(layer "In6.Cu")
		(net "M_G_CPU1_SB_DQS_DN<1>")
	)
	(segment
		(start 172.983652 -221.54261)
		(end 172.609764 -221.54261)
		(width 0.18288)
		(layer "In6.Cu")
		(net "M_G_CPU1_SB_DQS_DN<1>")
	)
	(segment
		(start 142.91564 -232.820972)
		(end 140.843 -232.820972)
		(width 0.18288)
		(layer "In6.Cu")
		(net "M_G_CPU1_SB_DQS_DN<1>")
	)
	(segment
		(start 187.621926 -218.828366)
		(end 187.113164 -218.828366)
		(width 0.18288)
		(layer "In6.Cu")
		(net "M_G_CPU1_SB_DQS_DN<1>")
	)
	(segment
		(start 174.809912 -220.975682)
		(end 173.95571 -221.829884)
		(width 0.18288)
		(layer "In6.Cu")
		(net "M_G_CPU1_SB_DQS_DN<1>")
	)
	(segment
		(start 182.883048 -219.506546)
		(end 179.843684 -219.506546)
		(width 0.18288)
		(layer "In6.Cu")
		(net "M_G_CPU1_SB_DQS_DN<1>")
	)
	(segment
		(start 162.430714 -219.982034)
		(end 161.358834 -219.982034)
		(width 0.18288)
		(layer "In6.Cu")
		(net "M_G_CPU1_SB_DQS_DN<1>")
	)
	(segment
		(start 160.79724 -219.42044)
		(end 156.316172 -219.42044)
		(width 0.18288)
		(layer "In6.Cu")
		(net "M_G_CPU1_SB_DQS_DN<1>")
	)
	(segment
		(start 161.358834 -219.982034)
		(end 160.79724 -219.42044)
		(width 0.18288)
		(layer "In6.Cu")
		(net "M_G_CPU1_SB_DQS_DN<1>")
	)
	(segment
		(start 169.89806 -221.813882)
		(end 167.106346 -220.65742)
		(width 0.18288)
		(layer "In6.Cu")
		(net "M_G_CPU1_SB_DQS_DN<1>")
	)
	(segment
		(start 137.211054 -234.475528)
		(end 137.203688 -234.479846)
		(width 0.088646)
		(layer "In6.Cu")
		(net "M_G_CPU1_SB_DQS_DN<1>")
	)
	(segment
		(start 167.106346 -220.65742)
		(end 165.122098 -218.673426)
		(width 0.18288)
		(layer "In6.Cu")
		(net "M_G_CPU1_SB_DQS_DN<1>")
	)
	(segment
		(start 176.438814 -220.975682)
		(end 174.809912 -220.975682)
		(width 0.18288)
		(layer "In6.Cu")
		(net "M_G_CPU1_SB_DQS_DN<1>")
	)
	(segment
		(start 172.338492 -221.813882)
		(end 169.89806 -221.813882)
		(width 0.18288)
		(layer "In6.Cu")
		(net "M_G_CPU1_SB_DQS_DN<1>")
	)
	(segment
		(start 179.124864 -220.225366)
		(end 178.684428 -220.225366)
		(width 0.18288)
		(layer "In6.Cu")
		(net "M_G_CPU1_SB_DQS_DN<1>")
	)
	(segment
		(start 156.316172 -219.42044)
		(end 142.91564 -232.820972)
		(width 0.18288)
		(layer "In6.Cu")
		(net "M_G_CPU1_SB_DQS_DN<1>")
	)
	(segment
		(start 179.843684 -219.506546)
		(end 179.124864 -220.225366)
		(width 0.18288)
		(layer "In6.Cu")
		(net "M_G_CPU1_SB_DQS_DN<1>")
	)
	(segment
		(start 126.864364 -234.480608)
		(end 126.863602 -234.481116)
		(width 0.088646)
		(layer "In6.Cu")
		(net "M_G_CPU1_SB_DQS_DN<1>")
	)
	(segment
		(start 177.3301 -220.954092)
		(end 177.06848 -220.692472)
		(width 0.18288)
		(layer "In6.Cu")
		(net "M_G_CPU1_SB_DQS_DN<1>")
	)
	(segment
		(start 140.061442 -232.821226)
		(end 140.038074 -232.821226)
		(width 0.088646)
		(layer "In6.Cu")
		(net "M_G_CPU1_SB_DQS_DN<1>")
	)
	(segment
		(start 173.270926 -221.829884)
		(end 172.983652 -221.54261)
		(width 0.18288)
		(layer "In6.Cu")
		(net "M_G_CPU1_SB_DQS_DN<1>")
	)
	(segment
		(start 177.06848 -220.692472)
		(end 176.722024 -220.692472)
		(width 0.18288)
		(layer "In6.Cu")
		(net "M_G_CPU1_SB_DQS_DN<1>")
	)
	(segment
		(start 126.51994 -234.970066)
		(end 126.207012 -234.970066)
		(width 0.088646)
		(layer "In6.Cu")
		(net "M_G_CPU1_SB_DQS_DN<1>")
	)
	(segment
		(start 186.848242 -218.563444)
		(end 183.82615 -218.563444)
		(width 0.18288)
		(layer "In6.Cu")
		(net "M_G_CPU1_SB_DQS_DN<1>")
	)
	(arc
		(start 129.68351 -234.480608)
		(mid 129.496312 -234.530751)
		(end 129.309114 -234.480608)
		(width 0.088646)
		(layer "In6.Cu")
		(net "M_G_CPU1_SB_DQS_DN<1>")
	)
	(arc
		(start 137.202164 -234.480608)
		(mid 137.014966 -234.530751)
		(end 136.827768 -234.480608)
		(width 0.088646)
		(layer "In6.Cu")
		(net "M_G_CPU1_SB_DQS_DN<1>")
	)
	(arc
		(start 131.188968 -234.480608)
		(mid 130.914769 -234.404773)
		(end 130.638296 -234.471972)
		(width 0.088646)
		(layer "In6.Cu")
		(net "M_G_CPU1_SB_DQS_DN<1>")
	)
	(arc
		(start 135.887968 -234.480608)
		(mid 135.605266 -234.404832)
		(end 135.322564 -234.480608)
		(width 0.088646)
		(layer "In6.Cu")
		(net "M_G_CPU1_SB_DQS_DN<1>")
	)
	(arc
		(start 132.128768 -234.480608)
		(mid 131.846066 -234.404832)
		(end 131.563364 -234.480608)
		(width 0.088646)
		(layer "In6.Cu")
		(net "M_G_CPU1_SB_DQS_DN<1>")
	)
	(arc
		(start 133.442964 -234.480608)
		(mid 133.255766 -234.530751)
		(end 133.068568 -234.480608)
		(width 0.088646)
		(layer "In6.Cu")
		(net "M_G_CPU1_SB_DQS_DN<1>")
	)
	(arc
		(start 128.743964 -234.480608)
		(mid 128.556766 -234.530751)
		(end 128.369568 -234.480608)
		(width 0.088646)
		(layer "In6.Cu")
		(net "M_G_CPU1_SB_DQS_DN<1>")
	)
	(arc
		(start 139.376912 -233.334814)
		(mid 139.194942 -233.523089)
		(end 138.942318 -233.591862)
		(width 0.088646)
		(layer "In6.Cu")
		(net "M_G_CPU1_SB_DQS_DN<1>")
	)
	(arc
		(start 128.369568 -234.480608)
		(mid 128.095369 -234.404773)
		(end 127.818896 -234.471972)
		(width 0.088646)
		(layer "In6.Cu")
		(net "M_G_CPU1_SB_DQS_DN<1>")
	)
	(arc
		(start 127.804164 -234.480608)
		(mid 127.616966 -234.530751)
		(end 127.429768 -234.480608)
		(width 0.088646)
		(layer "In6.Cu")
		(net "M_G_CPU1_SB_DQS_DN<1>")
	)
	(arc
		(start 138.595608 -233.675682)
		(mid 138.415372 -233.716702)
		(end 138.237468 -233.666538)
		(width 0.088646)
		(layer "In6.Cu")
		(net "M_G_CPU1_SB_DQS_DN<1>")
	)
	(arc
		(start 135.322564 -234.480608)
		(mid 135.135366 -234.530751)
		(end 134.948168 -234.480608)
		(width 0.088646)
		(layer "In6.Cu")
		(net "M_G_CPU1_SB_DQS_DN<1>")
	)
	(arc
		(start 136.827768 -234.480608)
		(mid 136.553569 -234.404773)
		(end 136.277096 -234.471972)
		(width 0.088646)
		(layer "In6.Cu")
		(net "M_G_CPU1_SB_DQS_DN<1>")
	)
	(arc
		(start 126.858268 -234.484164)
		(mid 126.672745 -234.662465)
		(end 126.585472 -234.904534)
		(width 0.088646)
		(layer "In6.Cu")
		(net "M_G_CPU1_SB_DQS_DN<1>")
	)
	(arc
		(start 137.389616 -234.15625)
		(mid 137.341937 -234.33915)
		(end 137.211054 -234.475528)
		(width 0.088646)
		(layer "In6.Cu")
		(net "M_G_CPU1_SB_DQS_DN<1>")
	)
	(arc
		(start 134.948168 -234.480608)
		(mid 134.665466 -234.404832)
		(end 134.382764 -234.480608)
		(width 0.088646)
		(layer "In6.Cu")
		(net "M_G_CPU1_SB_DQS_DN<1>")
	)
	(arc
		(start 131.563364 -234.480608)
		(mid 131.376166 -234.530751)
		(end 131.188968 -234.480608)
		(width 0.088646)
		(layer "In6.Cu")
		(net "M_G_CPU1_SB_DQS_DN<1>")
	)
	(arc
		(start 130.623564 -234.480608)
		(mid 130.436366 -234.530751)
		(end 130.249168 -234.480608)
		(width 0.088646)
		(layer "In6.Cu")
		(net "M_G_CPU1_SB_DQS_DN<1>")
	)
	(arc
		(start 138.942318 -233.591862)
		(mid 138.763935 -233.612987)
		(end 138.595608 -233.675682)
		(width 0.088646)
		(layer "In6.Cu")
		(net "M_G_CPU1_SB_DQS_DN<1>")
	)
	(arc
		(start 137.672064 -233.666538)
		(mid 137.469778 -233.865519)
		(end 137.389616 -234.137708)
		(width 0.088646)
		(layer "In6.Cu")
		(net "M_G_CPU1_SB_DQS_DN<1>")
	)
	(arc
		(start 134.008368 -234.480608)
		(mid 133.725666 -234.404832)
		(end 133.442964 -234.480608)
		(width 0.088646)
		(layer "In6.Cu")
		(net "M_G_CPU1_SB_DQS_DN<1>")
	)
	(arc
		(start 130.249168 -234.480608)
		(mid 129.972355 -234.404738)
		(end 129.693924 -234.474512)
		(width 0.088646)
		(layer "In6.Cu")
		(net "M_G_CPU1_SB_DQS_DN<1>")
	)
	(arc
		(start 133.068568 -234.480608)
		(mid 132.794369 -234.404773)
		(end 132.517896 -234.471972)
		(width 0.088646)
		(layer "In6.Cu")
		(net "M_G_CPU1_SB_DQS_DN<1>")
	)
	(arc
		(start 129.309114 -234.480608)
		(mid 129.032555 -234.404865)
		(end 128.754378 -234.474512)
		(width 0.088646)
		(layer "In6.Cu")
		(net "M_G_CPU1_SB_DQS_DN<1>")
	)
	(arc
		(start 138.237468 -233.666538)
		(mid 137.954766 -233.590796)
		(end 137.672064 -233.666538)
		(width 0.088646)
		(layer "In6.Cu")
		(net "M_G_CPU1_SB_DQS_DN<1>")
	)
	(arc
		(start 134.382764 -234.480608)
		(mid 134.195566 -234.530751)
		(end 134.008368 -234.480608)
		(width 0.088646)
		(layer "In6.Cu")
		(net "M_G_CPU1_SB_DQS_DN<1>")
	)
	(arc
		(start 127.429768 -234.480608)
		(mid 127.155569 -234.404773)
		(end 126.879096 -234.471972)
		(width 0.088646)
		(layer "In6.Cu")
		(net "M_G_CPU1_SB_DQS_DN<1>")
	)
	(arc
		(start 139.493244 -233.179366)
		(mid 139.429528 -233.252938)
		(end 139.376912 -233.334814)
		(width 0.088646)
		(layer "In6.Cu")
		(net "M_G_CPU1_SB_DQS_DN<1>")
	)
	(arc
		(start 132.503164 -234.480608)
		(mid 132.315966 -234.530751)
		(end 132.128768 -234.480608)
		(width 0.088646)
		(layer "In6.Cu")
		(net "M_G_CPU1_SB_DQS_DN<1>")
	)
	(arc
		(start 136.262364 -234.480608)
		(mid 136.075166 -234.530751)
		(end 135.887968 -234.480608)
		(width 0.088646)
		(layer "In6.Cu")
		(net "M_G_CPU1_SB_DQS_DN<1>")
	)
	(segment
		(start 195.702428 -228.157278)
		(end 195.942966 -227.91674)
		(width 0.20066)
		(layer "F.Cu")
		(net "M_G_CPU1_SB_DQS_DN<0>")
	)
	(segment
		(start 189.818772 -228.198426)
		(end 190.55461 -228.198426)
		(width 0.20066)
		(layer "F.Cu")
		(net "M_G_CPU1_SB_DQS_DN<0>")
	)
	(segment
		(start 194.959478 -228.567742)
		(end 195.369942 -228.157278)
		(width 0.20066)
		(layer "F.Cu")
		(net "M_G_CPU1_SB_DQS_DN<0>")
	)
	(segment
		(start 195.369942 -228.157278)
		(end 195.702428 -228.157278)
		(width 0.20066)
		(layer "F.Cu")
		(net "M_G_CPU1_SB_DQS_DN<0>")
	)
	(segment
		(start 187.883546 -227.91674)
		(end 188.988446 -227.91674)
		(width 0.20066)
		(layer "F.Cu")
		(net "M_G_CPU1_SB_DQS_DN<0>")
	)
	(segment
		(start 190.969138 -228.612954)
		(end 191.490854 -228.612954)
		(width 0.20066)
		(layer "F.Cu")
		(net "M_G_CPU1_SB_DQS_DN<0>")
	)
	(segment
		(start 195.942966 -227.91674)
		(end 196.532246 -227.91674)
		(width 0.20066)
		(layer "F.Cu")
		(net "M_G_CPU1_SB_DQS_DN<0>")
	)
	(segment
		(start 126.207266 -240.389156)
		(end 126.207012 -240.388902)
		(width 0.20066)
		(layer "F.Cu")
		(net "M_G_CPU1_SB_DQS_DN<0>")
	)
	(segment
		(start 194.654424 -228.567742)
		(end 194.959478 -228.567742)
		(width 0.20066)
		(layer "F.Cu")
		(net "M_G_CPU1_SB_DQS_DN<0>")
	)
	(segment
		(start 191.9097 -228.341682)
		(end 191.914018 -228.341682)
		(width 0.101854)
		(layer "F.Cu")
		(net "M_G_CPU1_SB_DQS_DN<0>")
	)
	(segment
		(start 188.988446 -227.91674)
		(end 189.537086 -227.91674)
		(width 0.20066)
		(layer "F.Cu")
		(net "M_G_CPU1_SB_DQS_DN<0>")
	)
	(segment
		(start 194.093592 -228.341682)
		(end 194.098926 -228.336348)
		(width 0.1016)
		(layer "F.Cu")
		(net "M_G_CPU1_SB_DQS_DN<0>")
	)
	(segment
		(start 191.762126 -228.341682)
		(end 191.9097 -228.341682)
		(width 0.20066)
		(layer "F.Cu")
		(net "M_G_CPU1_SB_DQS_DN<0>")
	)
	(segment
		(start 126.207012 -240.388902)
		(end 126.207012 -239.853216)
		(width 0.20066)
		(layer "F.Cu")
		(net "M_G_CPU1_SB_DQS_DN<0>")
	)
	(segment
		(start 191.490854 -228.612954)
		(end 191.762126 -228.341682)
		(width 0.20066)
		(layer "F.Cu")
		(net "M_G_CPU1_SB_DQS_DN<0>")
	)
	(segment
		(start 190.55461 -228.198426)
		(end 190.969138 -228.612954)
		(width 0.20066)
		(layer "F.Cu")
		(net "M_G_CPU1_SB_DQS_DN<0>")
	)
	(segment
		(start 194.098926 -228.336348)
		(end 194.42303 -228.336348)
		(width 0.20066)
		(layer "F.Cu")
		(net "M_G_CPU1_SB_DQS_DN<0>")
	)
	(segment
		(start 194.42303 -228.336348)
		(end 194.654424 -228.567742)
		(width 0.20066)
		(layer "F.Cu")
		(net "M_G_CPU1_SB_DQS_DN<0>")
	)
	(segment
		(start 189.537086 -227.91674)
		(end 189.818772 -228.198426)
		(width 0.20066)
		(layer "F.Cu")
		(net "M_G_CPU1_SB_DQS_DN<0>")
	)
	(segment
		(start 191.914018 -228.341682)
		(end 194.093592 -228.341682)
		(width 0.1016)
		(layer "F.Cu")
		(net "M_G_CPU1_SB_DQS_DN<0>")
	)
	(segment
		(start 126.934722 -239.543844)
		(end 126.95809 -239.52962)
		(width 0.088646)
		(layer "In6.Cu")
		(net "M_G_CPU1_SB_DQS_DN<0>")
	)
	(segment
		(start 177.089308 -233.44251)
		(end 177.357278 -233.71048)
		(width 0.18288)
		(layer "In6.Cu")
		(net "M_G_CPU1_SB_DQS_DN<0>")
	)
	(segment
		(start 126.95809 -239.52962)
		(end 126.959614 -239.528858)
		(width 0.088646)
		(layer "In6.Cu")
		(net "M_G_CPU1_SB_DQS_DN<0>")
	)
	(segment
		(start 126.207012 -239.853216)
		(end 126.719584 -239.853216)
		(width 0.088646)
		(layer "In6.Cu")
		(net "M_G_CPU1_SB_DQS_DN<0>")
	)
	(segment
		(start 132.033264 -240.177574)
		(end 132.043678 -240.171478)
		(width 0.088646)
		(layer "In6.Cu")
		(net "M_G_CPU1_SB_DQS_DN<0>")
	)
	(segment
		(start 178.668426 -233.049826)
		(end 179.572666 -233.049826)
		(width 0.18288)
		(layer "In6.Cu")
		(net "M_G_CPU1_SB_DQS_DN<0>")
	)
	(segment
		(start 134.4676 -240.171478)
		(end 134.478014 -240.177574)
		(width 0.088646)
		(layer "In6.Cu")
		(net "M_G_CPU1_SB_DQS_DN<0>")
	)
	(segment
		(start 180.881274 -233.608626)
		(end 183.037226 -231.452674)
		(width 0.18288)
		(layer "In6.Cu")
		(net "M_G_CPU1_SB_DQS_DN<0>")
	)
	(segment
		(start 126.776734 -239.796066)
		(end 126.779528 -239.777524)
		(width 0.088646)
		(layer "In6.Cu")
		(net "M_G_CPU1_SB_DQS_DN<0>")
	)
	(segment
		(start 173.235874 -234.557316)
		(end 173.494954 -234.557316)
		(width 0.18288)
		(layer "In6.Cu")
		(net "M_G_CPU1_SB_DQS_DN<0>")
	)
	(segment
		(start 146.961352 -239.74679)
		(end 152.749504 -233.958638)
		(width 0.18288)
		(layer "In6.Cu")
		(net "M_G_CPU1_SB_DQS_DN<0>")
	)
	(segment
		(start 164.833046 -233.641646)
		(end 168.248838 -233.641646)
		(width 0.18288)
		(layer "In6.Cu")
		(net "M_G_CPU1_SB_DQS_DN<0>")
	)
	(segment
		(start 130.704082 -240.168938)
		(end 130.718814 -240.177574)
		(width 0.088646)
		(layer "In6.Cu")
		(net "M_G_CPU1_SB_DQS_DN<0>")
	)
	(segment
		(start 172.970952 -234.292394)
		(end 173.235874 -234.557316)
		(width 0.18288)
		(layer "In6.Cu")
		(net "M_G_CPU1_SB_DQS_DN<0>")
	)
	(segment
		(start 176.422558 -233.72064)
		(end 176.700688 -233.44251)
		(width 0.18288)
		(layer "In6.Cu")
		(net "M_G_CPU1_SB_DQS_DN<0>")
	)
	(segment
		(start 179.572666 -233.049826)
		(end 180.131466 -233.608626)
		(width 0.18288)
		(layer "In6.Cu")
		(net "M_G_CPU1_SB_DQS_DN<0>")
	)
	(segment
		(start 128.824482 -240.168938)
		(end 128.839214 -240.177574)
		(width 0.088646)
		(layer "In6.Cu")
		(net "M_G_CPU1_SB_DQS_DN<0>")
	)
	(segment
		(start 137.282682 -240.168938)
		(end 137.297414 -240.177574)
		(width 0.088646)
		(layer "In6.Cu")
		(net "M_G_CPU1_SB_DQS_DN<0>")
	)
	(segment
		(start 176.700688 -233.44251)
		(end 177.089308 -233.44251)
		(width 0.18288)
		(layer "In6.Cu")
		(net "M_G_CPU1_SB_DQS_DN<0>")
	)
	(segment
		(start 139.586716 -240.228374)
		(end 140.00861 -239.80648)
		(width 0.088646)
		(layer "In6.Cu")
		(net "M_G_CPU1_SB_DQS_DN<0>")
	)
	(segment
		(start 183.037226 -231.452674)
		(end 183.037226 -230.713026)
		(width 0.18288)
		(layer "In6.Cu")
		(net "M_G_CPU1_SB_DQS_DN<0>")
	)
	(segment
		(start 184.253886 -229.496366)
		(end 184.857136 -229.496366)
		(width 0.18288)
		(layer "In6.Cu")
		(net "M_G_CPU1_SB_DQS_DN<0>")
	)
	(segment
		(start 138.222482 -240.168938)
		(end 138.237214 -240.177574)
		(width 0.088646)
		(layer "In6.Cu")
		(net "M_G_CPU1_SB_DQS_DN<0>")
	)
	(segment
		(start 186.323224 -228.030278)
		(end 187.117736 -228.030278)
		(width 0.18288)
		(layer "In6.Cu")
		(net "M_G_CPU1_SB_DQS_DN<0>")
	)
	(segment
		(start 173.494954 -234.557316)
		(end 174.33163 -233.72064)
		(width 0.18288)
		(layer "In6.Cu")
		(net "M_G_CPU1_SB_DQS_DN<0>")
	)
	(segment
		(start 187.607448 -228.192838)
		(end 187.883546 -227.91674)
		(width 0.18288)
		(layer "In6.Cu")
		(net "M_G_CPU1_SB_DQS_DN<0>")
	)
	(segment
		(start 139.162282 -240.168938)
		(end 139.177014 -240.177574)
		(width 0.088646)
		(layer "In6.Cu")
		(net "M_G_CPU1_SB_DQS_DN<0>")
	)
	(segment
		(start 164.218366 -233.026966)
		(end 164.833046 -233.641646)
		(width 0.18288)
		(layer "In6.Cu")
		(net "M_G_CPU1_SB_DQS_DN<0>")
	)
	(segment
		(start 177.357278 -233.71048)
		(end 178.007772 -233.71048)
		(width 0.18288)
		(layer "In6.Cu")
		(net "M_G_CPU1_SB_DQS_DN<0>")
	)
	(segment
		(start 134.85241 -240.177574)
		(end 134.852918 -240.177828)
		(width 0.088646)
		(layer "In6.Cu")
		(net "M_G_CPU1_SB_DQS_DN<0>")
	)
	(segment
		(start 163.283138 -233.026966)
		(end 164.218366 -233.026966)
		(width 0.18288)
		(layer "In6.Cu")
		(net "M_G_CPU1_SB_DQS_DN<0>")
	)
	(segment
		(start 140.359638 -239.80648)
		(end 140.419328 -239.74679)
		(width 0.088646)
		(layer "In6.Cu")
		(net "M_G_CPU1_SB_DQS_DN<0>")
	)
	(segment
		(start 174.33163 -233.72064)
		(end 176.422558 -233.72064)
		(width 0.18288)
		(layer "In6.Cu")
		(net "M_G_CPU1_SB_DQS_DN<0>")
	)
	(segment
		(start 180.131466 -233.608626)
		(end 180.881274 -233.608626)
		(width 0.18288)
		(layer "In6.Cu")
		(net "M_G_CPU1_SB_DQS_DN<0>")
	)
	(segment
		(start 162.015678 -234.294426)
		(end 163.283138 -233.026966)
		(width 0.18288)
		(layer "In6.Cu")
		(net "M_G_CPU1_SB_DQS_DN<0>")
	)
	(segment
		(start 161.56813 -234.294426)
		(end 162.015678 -234.294426)
		(width 0.18288)
		(layer "In6.Cu")
		(net "M_G_CPU1_SB_DQS_DN<0>")
	)
	(segment
		(start 169.162222 -234.55503)
		(end 172.359828 -234.55503)
		(width 0.18288)
		(layer "In6.Cu")
		(net "M_G_CPU1_SB_DQS_DN<0>")
	)
	(segment
		(start 187.280296 -228.192838)
		(end 187.607448 -228.192838)
		(width 0.18288)
		(layer "In6.Cu")
		(net "M_G_CPU1_SB_DQS_DN<0>")
	)
	(segment
		(start 159.879792 -233.958638)
		(end 161.56813 -234.294426)
		(width 0.18288)
		(layer "In6.Cu")
		(net "M_G_CPU1_SB_DQS_DN<0>")
	)
	(segment
		(start 168.248838 -233.641646)
		(end 169.162222 -234.55503)
		(width 0.18288)
		(layer "In6.Cu")
		(net "M_G_CPU1_SB_DQS_DN<0>")
	)
	(segment
		(start 129.764282 -240.168938)
		(end 129.779014 -240.177574)
		(width 0.088646)
		(layer "In6.Cu")
		(net "M_G_CPU1_SB_DQS_DN<0>")
	)
	(segment
		(start 152.749504 -233.958638)
		(end 159.879792 -233.958638)
		(width 0.18288)
		(layer "In6.Cu")
		(net "M_G_CPU1_SB_DQS_DN<0>")
	)
	(segment
		(start 136.35736 -240.177574)
		(end 136.357614 -240.177574)
		(width 0.088646)
		(layer "In6.Cu")
		(net "M_G_CPU1_SB_DQS_DN<0>")
	)
	(segment
		(start 183.037226 -230.713026)
		(end 184.253886 -229.496366)
		(width 0.18288)
		(layer "In6.Cu")
		(net "M_G_CPU1_SB_DQS_DN<0>")
	)
	(segment
		(start 131.648454 -240.171478)
		(end 131.658868 -240.177574)
		(width 0.088646)
		(layer "In6.Cu")
		(net "M_G_CPU1_SB_DQS_DN<0>")
	)
	(segment
		(start 126.719584 -239.853216)
		(end 126.776734 -239.796066)
		(width 0.088646)
		(layer "In6.Cu")
		(net "M_G_CPU1_SB_DQS_DN<0>")
	)
	(segment
		(start 133.528054 -240.171478)
		(end 133.538468 -240.177574)
		(width 0.088646)
		(layer "In6.Cu")
		(net "M_G_CPU1_SB_DQS_DN<0>")
	)
	(segment
		(start 139.364212 -240.228374)
		(end 139.586716 -240.228374)
		(width 0.088646)
		(layer "In6.Cu")
		(net "M_G_CPU1_SB_DQS_DN<0>")
	)
	(segment
		(start 187.117736 -228.030278)
		(end 187.280296 -228.192838)
		(width 0.18288)
		(layer "In6.Cu")
		(net "M_G_CPU1_SB_DQS_DN<0>")
	)
	(segment
		(start 127.55372 -239.694974)
		(end 127.658622 -239.799876)
		(width 0.088646)
		(layer "In6.Cu")
		(net "M_G_CPU1_SB_DQS_DN<0>")
	)
	(segment
		(start 172.359828 -234.55503)
		(end 172.622464 -234.292394)
		(width 0.18288)
		(layer "In6.Cu")
		(net "M_G_CPU1_SB_DQS_DN<0>")
	)
	(segment
		(start 140.00861 -239.80648)
		(end 140.359638 -239.80648)
		(width 0.088646)
		(layer "In6.Cu")
		(net "M_G_CPU1_SB_DQS_DN<0>")
	)
	(segment
		(start 178.007772 -233.71048)
		(end 178.668426 -233.049826)
		(width 0.18288)
		(layer "In6.Cu")
		(net "M_G_CPU1_SB_DQS_DN<0>")
	)
	(segment
		(start 184.857136 -229.496366)
		(end 186.323224 -228.030278)
		(width 0.18288)
		(layer "In6.Cu")
		(net "M_G_CPU1_SB_DQS_DN<0>")
	)
	(segment
		(start 172.622464 -234.292394)
		(end 172.970952 -234.292394)
		(width 0.18288)
		(layer "In6.Cu")
		(net "M_G_CPU1_SB_DQS_DN<0>")
	)
	(segment
		(start 140.442696 -239.74679)
		(end 146.961352 -239.74679)
		(width 0.18288)
		(layer "In6.Cu")
		(net "M_G_CPU1_SB_DQS_DN<0>")
	)
	(segment
		(start 127.33401 -239.528858)
		(end 127.3429 -239.533938)
		(width 0.088646)
		(layer "In6.Cu")
		(net "M_G_CPU1_SB_DQS_DN<0>")
	)
	(segment
		(start 140.419328 -239.74679)
		(end 140.442696 -239.74679)
		(width 0.088646)
		(layer "In6.Cu")
		(net "M_G_CPU1_SB_DQS_DN<0>")
	)
	(arc
		(start 136.73201 -240.177574)
		(mid 137.006239 -240.101649)
		(end 137.282682 -240.168938)
		(width 0.088646)
		(layer "In6.Cu")
		(net "M_G_CPU1_SB_DQS_DN<0>")
	)
	(arc
		(start 132.97281 -240.177574)
		(mid 133.249623 -240.101738)
		(end 133.528054 -240.171478)
		(width 0.088646)
		(layer "In6.Cu")
		(net "M_G_CPU1_SB_DQS_DN<0>")
	)
	(arc
		(start 130.718814 -240.177574)
		(mid 130.906012 -240.227717)
		(end 131.09321 -240.177574)
		(width 0.088646)
		(layer "In6.Cu")
		(net "M_G_CPU1_SB_DQS_DN<0>")
	)
	(arc
		(start 126.959614 -239.528858)
		(mid 127.146812 -239.478715)
		(end 127.33401 -239.528858)
		(width 0.088646)
		(layer "In6.Cu")
		(net "M_G_CPU1_SB_DQS_DN<0>")
	)
	(arc
		(start 138.61161 -240.177574)
		(mid 138.885839 -240.101649)
		(end 139.162282 -240.168938)
		(width 0.088646)
		(layer "In6.Cu")
		(net "M_G_CPU1_SB_DQS_DN<0>")
	)
	(arc
		(start 130.15341 -240.177574)
		(mid 130.427639 -240.101649)
		(end 130.704082 -240.168938)
		(width 0.088646)
		(layer "In6.Cu")
		(net "M_G_CPU1_SB_DQS_DN<0>")
	)
	(arc
		(start 135.417814 -240.177828)
		(mid 135.602083 -240.228051)
		(end 135.78713 -240.180876)
		(width 0.088646)
		(layer "In6.Cu")
		(net "M_G_CPU1_SB_DQS_DN<0>")
	)
	(arc
		(start 126.779528 -239.777524)
		(mid 126.831377 -239.643572)
		(end 126.934722 -239.543844)
		(width 0.088646)
		(layer "In6.Cu")
		(net "M_G_CPU1_SB_DQS_DN<0>")
	)
	(arc
		(start 127.658622 -239.799876)
		(mid 127.696622 -239.852073)
		(end 127.716788 -239.913414)
		(width 0.088646)
		(layer "In6.Cu")
		(net "M_G_CPU1_SB_DQS_DN<0>")
	)
	(arc
		(start 133.912864 -240.177574)
		(mid 134.189423 -240.101865)
		(end 134.4676 -240.171478)
		(width 0.088646)
		(layer "In6.Cu")
		(net "M_G_CPU1_SB_DQS_DN<0>")
	)
	(arc
		(start 137.297414 -240.177574)
		(mid 137.484612 -240.227717)
		(end 137.67181 -240.177574)
		(width 0.088646)
		(layer "In6.Cu")
		(net "M_G_CPU1_SB_DQS_DN<0>")
	)
	(arc
		(start 138.237214 -240.177574)
		(mid 138.424412 -240.227717)
		(end 138.61161 -240.177574)
		(width 0.088646)
		(layer "In6.Cu")
		(net "M_G_CPU1_SB_DQS_DN<0>")
	)
	(arc
		(start 127.3429 -239.533938)
		(mid 127.453687 -239.607418)
		(end 127.55372 -239.694974)
		(width 0.088646)
		(layer "In6.Cu")
		(net "M_G_CPU1_SB_DQS_DN<0>")
	)
	(arc
		(start 134.852918 -240.177828)
		(mid 135.135366 -240.102179)
		(end 135.417814 -240.177828)
		(width 0.088646)
		(layer "In6.Cu")
		(net "M_G_CPU1_SB_DQS_DN<0>")
	)
	(arc
		(start 133.538468 -240.177574)
		(mid 133.725666 -240.227717)
		(end 133.912864 -240.177574)
		(width 0.088646)
		(layer "In6.Cu")
		(net "M_G_CPU1_SB_DQS_DN<0>")
	)
	(arc
		(start 131.658868 -240.177574)
		(mid 131.846066 -240.227717)
		(end 132.033264 -240.177574)
		(width 0.088646)
		(layer "In6.Cu")
		(net "M_G_CPU1_SB_DQS_DN<0>")
	)
	(arc
		(start 127.716788 -239.913414)
		(mid 127.926 -240.191738)
		(end 128.27381 -240.177574)
		(width 0.088646)
		(layer "In6.Cu")
		(net "M_G_CPU1_SB_DQS_DN<0>")
	)
	(arc
		(start 131.09321 -240.177574)
		(mid 131.370023 -240.101738)
		(end 131.648454 -240.171478)
		(width 0.088646)
		(layer "In6.Cu")
		(net "M_G_CPU1_SB_DQS_DN<0>")
	)
	(arc
		(start 136.357614 -240.177574)
		(mid 136.544812 -240.227717)
		(end 136.73201 -240.177574)
		(width 0.088646)
		(layer "In6.Cu")
		(net "M_G_CPU1_SB_DQS_DN<0>")
	)
	(arc
		(start 132.043678 -240.171478)
		(mid 132.321856 -240.101786)
		(end 132.598414 -240.177574)
		(width 0.088646)
		(layer "In6.Cu")
		(net "M_G_CPU1_SB_DQS_DN<0>")
	)
	(arc
		(start 135.78713 -240.180876)
		(mid 136.071811 -240.101894)
		(end 136.35736 -240.177574)
		(width 0.088646)
		(layer "In6.Cu")
		(net "M_G_CPU1_SB_DQS_DN<0>")
	)
	(arc
		(start 128.839214 -240.177574)
		(mid 129.026412 -240.227717)
		(end 129.21361 -240.177574)
		(width 0.088646)
		(layer "In6.Cu")
		(net "M_G_CPU1_SB_DQS_DN<0>")
	)
	(arc
		(start 128.27381 -240.177574)
		(mid 128.548039 -240.101649)
		(end 128.824482 -240.168938)
		(width 0.088646)
		(layer "In6.Cu")
		(net "M_G_CPU1_SB_DQS_DN<0>")
	)
	(arc
		(start 129.779014 -240.177574)
		(mid 129.966212 -240.227717)
		(end 130.15341 -240.177574)
		(width 0.088646)
		(layer "In6.Cu")
		(net "M_G_CPU1_SB_DQS_DN<0>")
	)
	(arc
		(start 137.67181 -240.177574)
		(mid 137.946039 -240.101649)
		(end 138.222482 -240.168938)
		(width 0.088646)
		(layer "In6.Cu")
		(net "M_G_CPU1_SB_DQS_DN<0>")
	)
	(arc
		(start 134.478014 -240.177574)
		(mid 134.665212 -240.227717)
		(end 134.85241 -240.177574)
		(width 0.088646)
		(layer "In6.Cu")
		(net "M_G_CPU1_SB_DQS_DN<0>")
	)
	(arc
		(start 132.598414 -240.177574)
		(mid 132.785612 -240.227717)
		(end 132.97281 -240.177574)
		(width 0.088646)
		(layer "In6.Cu")
		(net "M_G_CPU1_SB_DQS_DN<0>")
	)
	(arc
		(start 139.177014 -240.177574)
		(mid 139.26727 -240.215296)
		(end 139.364212 -240.228374)
		(width 0.088646)
		(layer "In6.Cu")
		(net "M_G_CPU1_SB_DQS_DN<0>")
	)
	(arc
		(start 129.21361 -240.177574)
		(mid 129.487839 -240.101649)
		(end 129.764282 -240.168938)
		(width 0.088646)
		(layer "In6.Cu")
		(net "M_G_CPU1_SB_DQS_DN<0>")
	)
	(segment
		(start 194.508882 -220.68536)
		(end 194.098926 -220.68536)
		(width 0.20066)
		(layer "F.Cu")
		(net "M_G_CPU1_SB_DQ<9>")
	)
	(segment
		(start 191.539114 -220.69171)
		(end 191.421004 -220.80982)
		(width 0.20066)
		(layer "F.Cu")
		(net "M_G_CPU1_SB_DQ<9>")
	)
	(segment
		(start 126.677166 -236.319568)
		(end 126.677166 -235.783882)
		(width 0.20066)
		(layer "F.Cu")
		(net "M_G_CPU1_SB_DQ<9>")
	)
	(segment
		(start 191.883792 -220.69171)
		(end 191.539114 -220.69171)
		(width 0.20066)
		(layer "F.Cu")
		(net "M_G_CPU1_SB_DQ<9>")
	)
	(segment
		(start 191.421004 -221.177358)
		(end 191.233044 -221.365318)
		(width 0.20066)
		(layer "F.Cu")
		(net "M_G_CPU1_SB_DQ<9>")
	)
	(segment
		(start 196.531992 -221.116906)
		(end 194.940428 -221.116906)
		(width 0.20066)
		(layer "F.Cu")
		(net "M_G_CPU1_SB_DQ<9>")
	)
	(segment
		(start 188.988446 -221.116652)
		(end 187.883546 -221.116652)
		(width 0.20066)
		(layer "F.Cu")
		(net "M_G_CPU1_SB_DQ<9>")
	)
	(segment
		(start 191.421004 -220.80982)
		(end 191.421004 -221.177358)
		(width 0.20066)
		(layer "F.Cu")
		(net "M_G_CPU1_SB_DQ<9>")
	)
	(segment
		(start 190.509144 -221.116652)
		(end 188.988446 -221.116652)
		(width 0.20066)
		(layer "F.Cu")
		(net "M_G_CPU1_SB_DQ<9>")
	)
	(segment
		(start 191.903858 -220.69171)
		(end 191.883792 -220.69171)
		(width 0.101854)
		(layer "F.Cu")
		(net "M_G_CPU1_SB_DQ<9>")
	)
	(segment
		(start 126.676912 -236.319822)
		(end 126.677166 -236.319568)
		(width 0.20066)
		(layer "F.Cu")
		(net "M_G_CPU1_SB_DQ<9>")
	)
	(segment
		(start 191.233044 -221.365318)
		(end 190.75781 -221.365318)
		(width 0.20066)
		(layer "F.Cu")
		(net "M_G_CPU1_SB_DQ<9>")
	)
	(segment
		(start 190.75781 -221.365318)
		(end 190.509144 -221.116652)
		(width 0.20066)
		(layer "F.Cu")
		(net "M_G_CPU1_SB_DQ<9>")
	)
	(segment
		(start 196.532246 -221.116652)
		(end 196.531992 -221.116906)
		(width 0.20066)
		(layer "F.Cu")
		(net "M_G_CPU1_SB_DQ<9>")
	)
	(segment
		(start 194.098926 -220.68536)
		(end 194.092576 -220.69171)
		(width 0.1016)
		(layer "F.Cu")
		(net "M_G_CPU1_SB_DQ<9>")
	)
	(segment
		(start 194.092576 -220.69171)
		(end 191.903858 -220.69171)
		(width 0.1016)
		(layer "F.Cu")
		(net "M_G_CPU1_SB_DQ<9>")
	)
	(segment
		(start 194.940428 -221.116906)
		(end 194.508882 -220.68536)
		(width 0.20066)
		(layer "F.Cu")
		(net "M_G_CPU1_SB_DQ<9>")
	)
	(segment
		(start 172.3644 -224.9424)
		(end 172.017182 -225.289618)
		(width 0.18288)
		(layer "In6.Cu")
		(net "M_G_CPU1_SB_DQ<9>")
	)
	(segment
		(start 167.390826 -224.236026)
		(end 166.917116 -223.762316)
		(width 0.18288)
		(layer "In6.Cu")
		(net "M_G_CPU1_SB_DQ<9>")
	)
	(segment
		(start 187.309252 -221.116652)
		(end 186.847226 -220.654626)
		(width 0.18288)
		(layer "In6.Cu")
		(net "M_G_CPU1_SB_DQ<9>")
	)
	(segment
		(start 165.062408 -223.232472)
		(end 164.689028 -223.232472)
		(width 0.18288)
		(layer "In6.Cu")
		(net "M_G_CPU1_SB_DQ<9>")
	)
	(segment
		(start 165.550596 -222.395796)
		(end 165.382448 -222.395796)
		(width 0.18288)
		(layer "In6.Cu")
		(net "M_G_CPU1_SB_DQ<9>")
	)
	(segment
		(start 187.883546 -221.116652)
		(end 187.309252 -221.116652)
		(width 0.18288)
		(layer "In6.Cu")
		(net "M_G_CPU1_SB_DQ<9>")
	)
	(segment
		(start 164.529008 -222.574358)
		(end 164.346128 -222.391478)
		(width 0.18288)
		(layer "In6.Cu")
		(net "M_G_CPU1_SB_DQ<9>")
	)
	(segment
		(start 159.653224 -222.391478)
		(end 159.287718 -222.025972)
		(width 0.18288)
		(layer "In6.Cu")
		(net "M_G_CPU1_SB_DQ<9>")
	)
	(segment
		(start 168.279826 -224.236026)
		(end 167.390826 -224.236026)
		(width 0.18288)
		(layer "In6.Cu")
		(net "M_G_CPU1_SB_DQ<9>")
	)
	(segment
		(start 165.222428 -222.555816)
		(end 165.222428 -223.072452)
		(width 0.18288)
		(layer "In6.Cu")
		(net "M_G_CPU1_SB_DQ<9>")
	)
	(segment
		(start 180.622194 -222.458026)
		(end 180.192426 -222.458026)
		(width 0.18288)
		(layer "In6.Cu")
		(net "M_G_CPU1_SB_DQ<9>")
	)
	(segment
		(start 139.739116 -234.561634)
		(end 139.739116 -235.151168)
		(width 0.088646)
		(layer "In6.Cu")
		(net "M_G_CPU1_SB_DQ<9>")
	)
	(segment
		(start 170.880532 -224.556574)
		(end 170.697652 -224.373694)
		(width 0.18288)
		(layer "In6.Cu")
		(net "M_G_CPU1_SB_DQ<9>")
	)
	(segment
		(start 164.689028 -223.232472)
		(end 164.529008 -223.072452)
		(width 0.18288)
		(layer "In6.Cu")
		(net "M_G_CPU1_SB_DQ<9>")
	)
	(segment
		(start 158.56585 -222.025972)
		(end 158.160212 -222.43161)
		(width 0.18288)
		(layer "In6.Cu")
		(net "M_G_CPU1_SB_DQ<9>")
	)
	(segment
		(start 186.847226 -220.654626)
		(end 184.231026 -220.654626)
		(width 0.18288)
		(layer "In6.Cu")
		(net "M_G_CPU1_SB_DQ<9>")
	)
	(segment
		(start 165.95471 -224.272602)
		(end 165.690296 -224.008188)
		(width 0.18288)
		(layer "In6.Cu")
		(net "M_G_CPU1_SB_DQ<9>")
	)
	(segment
		(start 170.187112 -224.556574)
		(end 170.187112 -225.106738)
		(width 0.18288)
		(layer "In6.Cu")
		(net "M_G_CPU1_SB_DQ<9>")
	)
	(segment
		(start 159.287718 -222.025972)
		(end 158.56585 -222.025972)
		(width 0.18288)
		(layer "In6.Cu")
		(net "M_G_CPU1_SB_DQ<9>")
	)
	(segment
		(start 172.017182 -225.289618)
		(end 171.063412 -225.289618)
		(width 0.18288)
		(layer "In6.Cu")
		(net "M_G_CPU1_SB_DQ<9>")
	)
	(segment
		(start 165.690296 -223.782128)
		(end 166.200582 -223.271842)
		(width 0.18288)
		(layer "In6.Cu")
		(net "M_G_CPU1_SB_DQ<9>")
	)
	(segment
		(start 143.77797 -234.439714)
		(end 140.061696 -234.439714)
		(width 0.18288)
		(layer "In6.Cu")
		(net "M_G_CPU1_SB_DQ<9>")
	)
	(segment
		(start 132.513324 -236.102144)
		(end 132.50291 -236.10824)
		(width 0.088646)
		(layer "In6.Cu")
		(net "M_G_CPU1_SB_DQ<9>")
	)
	(segment
		(start 170.187112 -225.106738)
		(end 170.004232 -225.289618)
		(width 0.18288)
		(layer "In6.Cu")
		(net "M_G_CPU1_SB_DQ<9>")
	)
	(segment
		(start 173.568106 -224.9424)
		(end 172.3644 -224.9424)
		(width 0.18288)
		(layer "In6.Cu")
		(net "M_G_CPU1_SB_DQ<9>")
	)
	(segment
		(start 139.545314 -235.34497)
		(end 139.364212 -235.34497)
		(width 0.088646)
		(layer "In6.Cu")
		(net "M_G_CPU1_SB_DQ<9>")
	)
	(segment
		(start 131.573778 -236.102144)
		(end 131.563364 -236.10824)
		(width 0.088646)
		(layer "In6.Cu")
		(net "M_G_CPU1_SB_DQ<9>")
	)
	(segment
		(start 169.333418 -225.289618)
		(end 168.279826 -224.236026)
		(width 0.18288)
		(layer "In6.Cu")
		(net "M_G_CPU1_SB_DQ<9>")
	)
	(segment
		(start 139.739116 -235.151168)
		(end 139.545314 -235.34497)
		(width 0.088646)
		(layer "In6.Cu")
		(net "M_G_CPU1_SB_DQ<9>")
	)
	(segment
		(start 165.690296 -224.008188)
		(end 165.690296 -223.782128)
		(width 0.18288)
		(layer "In6.Cu")
		(net "M_G_CPU1_SB_DQ<9>")
	)
	(segment
		(start 158.160212 -222.43161)
		(end 155.786074 -222.43161)
		(width 0.18288)
		(layer "In6.Cu")
		(net "M_G_CPU1_SB_DQ<9>")
	)
	(segment
		(start 155.786074 -222.43161)
		(end 143.77797 -234.439714)
		(width 0.18288)
		(layer "In6.Cu")
		(net "M_G_CPU1_SB_DQ<9>")
	)
	(segment
		(start 166.691056 -223.762316)
		(end 166.18077 -224.272602)
		(width 0.18288)
		(layer "In6.Cu")
		(net "M_G_CPU1_SB_DQ<9>")
	)
	(segment
		(start 128.862074 -235.528104)
		(end 128.743964 -235.459524)
		(width 0.088646)
		(layer "In6.Cu")
		(net "M_G_CPU1_SB_DQ<9>")
	)
	(segment
		(start 183.340502 -221.54515)
		(end 181.53507 -221.54515)
		(width 0.18288)
		(layer "In6.Cu")
		(net "M_G_CPU1_SB_DQ<9>")
	)
	(segment
		(start 166.917116 -223.762316)
		(end 166.691056 -223.762316)
		(width 0.18288)
		(layer "In6.Cu")
		(net "M_G_CPU1_SB_DQ<9>")
	)
	(segment
		(start 166.18077 -224.272602)
		(end 165.95471 -224.272602)
		(width 0.18288)
		(layer "In6.Cu")
		(net "M_G_CPU1_SB_DQ<9>")
	)
	(segment
		(start 165.222428 -223.072452)
		(end 165.062408 -223.232472)
		(width 0.18288)
		(layer "In6.Cu")
		(net "M_G_CPU1_SB_DQ<9>")
	)
	(segment
		(start 128.158748 -235.406692)
		(end 127.58801 -235.406692)
		(width 0.088646)
		(layer "In6.Cu")
		(net "M_G_CPU1_SB_DQ<9>")
	)
	(segment
		(start 181.53507 -221.54515)
		(end 180.622194 -222.458026)
		(width 0.18288)
		(layer "In6.Cu")
		(net "M_G_CPU1_SB_DQ<9>")
	)
	(segment
		(start 184.231026 -220.654626)
		(end 183.340502 -221.54515)
		(width 0.18288)
		(layer "In6.Cu")
		(net "M_G_CPU1_SB_DQ<9>")
	)
	(segment
		(start 138.329416 -235.768388)
		(end 138.329416 -235.783882)
		(width 0.088646)
		(layer "In6.Cu")
		(net "M_G_CPU1_SB_DQ<9>")
	)
	(segment
		(start 170.697652 -224.373694)
		(end 170.369992 -224.373694)
		(width 0.18288)
		(layer "In6.Cu")
		(net "M_G_CPU1_SB_DQ<9>")
	)
	(segment
		(start 129.309368 -236.10824)
		(end 129.313686 -236.111034)
		(width 0.088646)
		(layer "In6.Cu")
		(net "M_G_CPU1_SB_DQ<9>")
	)
	(segment
		(start 139.861036 -234.439714)
		(end 139.739116 -234.561634)
		(width 0.088646)
		(layer "In6.Cu")
		(net "M_G_CPU1_SB_DQ<9>")
	)
	(segment
		(start 177.38979 -224.092262)
		(end 174.418244 -224.092262)
		(width 0.18288)
		(layer "In6.Cu")
		(net "M_G_CPU1_SB_DQ<9>")
	)
	(segment
		(start 130.638296 -236.099604)
		(end 130.623564 -236.10824)
		(width 0.088646)
		(layer "In6.Cu")
		(net "M_G_CPU1_SB_DQ<9>")
	)
	(segment
		(start 164.529008 -223.072452)
		(end 164.529008 -222.574358)
		(width 0.18288)
		(layer "In6.Cu")
		(net "M_G_CPU1_SB_DQ<9>")
	)
	(segment
		(start 166.200582 -223.045782)
		(end 165.550596 -222.395796)
		(width 0.18288)
		(layer "In6.Cu")
		(net "M_G_CPU1_SB_DQ<9>")
	)
	(segment
		(start 136.277096 -236.099604)
		(end 136.262364 -236.10824)
		(width 0.088646)
		(layer "In6.Cu")
		(net "M_G_CPU1_SB_DQ<9>")
	)
	(segment
		(start 129.698496 -236.099604)
		(end 129.683764 -236.10824)
		(width 0.088646)
		(layer "In6.Cu")
		(net "M_G_CPU1_SB_DQ<9>")
	)
	(segment
		(start 129.110486 -235.957364)
		(end 129.063496 -235.910374)
		(width 0.088646)
		(layer "In6.Cu")
		(net "M_G_CPU1_SB_DQ<9>")
	)
	(segment
		(start 128.559306 -235.409486)
		(end 128.158748 -235.406692)
		(width 0.088646)
		(layer "In6.Cu")
		(net "M_G_CPU1_SB_DQ<9>")
	)
	(segment
		(start 135.337296 -236.099604)
		(end 135.322564 -236.10824)
		(width 0.088646)
		(layer "In6.Cu")
		(net "M_G_CPU1_SB_DQ<9>")
	)
	(segment
		(start 180.192426 -222.458026)
		(end 179.201826 -223.448626)
		(width 0.18288)
		(layer "In6.Cu")
		(net "M_G_CPU1_SB_DQ<9>")
	)
	(segment
		(start 170.004232 -225.289618)
		(end 169.333418 -225.289618)
		(width 0.18288)
		(layer "In6.Cu")
		(net "M_G_CPU1_SB_DQ<9>")
	)
	(segment
		(start 171.063412 -225.289618)
		(end 170.880532 -225.106738)
		(width 0.18288)
		(layer "In6.Cu")
		(net "M_G_CPU1_SB_DQ<9>")
	)
	(segment
		(start 170.880532 -225.106738)
		(end 170.880532 -224.556574)
		(width 0.18288)
		(layer "In6.Cu")
		(net "M_G_CPU1_SB_DQ<9>")
	)
	(segment
		(start 137.216896 -236.099604)
		(end 137.202164 -236.10824)
		(width 0.088646)
		(layer "In6.Cu")
		(net "M_G_CPU1_SB_DQ<9>")
	)
	(segment
		(start 139.177014 -235.294424)
		(end 139.162282 -235.285788)
		(width 0.088646)
		(layer "In6.Cu")
		(net "M_G_CPU1_SB_DQ<9>")
	)
	(segment
		(start 128.93421 -235.599478)
		(end 128.862074 -235.528104)
		(width 0.088646)
		(layer "In6.Cu")
		(net "M_G_CPU1_SB_DQ<9>")
	)
	(segment
		(start 140.061696 -234.439714)
		(end 139.861036 -234.439714)
		(width 0.088646)
		(layer "In6.Cu")
		(net "M_G_CPU1_SB_DQ<9>")
	)
	(segment
		(start 179.201826 -223.448626)
		(end 178.033426 -223.448626)
		(width 0.18288)
		(layer "In6.Cu")
		(net "M_G_CPU1_SB_DQ<9>")
	)
	(segment
		(start 170.369992 -224.373694)
		(end 170.187112 -224.556574)
		(width 0.18288)
		(layer "In6.Cu")
		(net "M_G_CPU1_SB_DQ<9>")
	)
	(segment
		(start 174.418244 -224.092262)
		(end 173.568106 -224.9424)
		(width 0.18288)
		(layer "In6.Cu")
		(net "M_G_CPU1_SB_DQ<9>")
	)
	(segment
		(start 166.200582 -223.271842)
		(end 166.200582 -223.045782)
		(width 0.18288)
		(layer "In6.Cu")
		(net "M_G_CPU1_SB_DQ<9>")
	)
	(segment
		(start 164.346128 -222.391478)
		(end 159.653224 -222.391478)
		(width 0.18288)
		(layer "In6.Cu")
		(net "M_G_CPU1_SB_DQ<9>")
	)
	(segment
		(start 178.033426 -223.448626)
		(end 177.38979 -224.092262)
		(width 0.18288)
		(layer "In6.Cu")
		(net "M_G_CPU1_SB_DQ<9>")
	)
	(segment
		(start 165.382448 -222.395796)
		(end 165.222428 -222.555816)
		(width 0.18288)
		(layer "In6.Cu")
		(net "M_G_CPU1_SB_DQ<9>")
	)
	(arc
		(start 135.322564 -236.10824)
		(mid 135.135366 -236.158383)
		(end 134.948168 -236.10824)
		(width 0.088646)
		(layer "In6.Cu")
		(net "M_G_CPU1_SB_DQ<9>")
	)
	(arc
		(start 129.683764 -236.10824)
		(mid 129.496566 -236.158383)
		(end 129.309368 -236.10824)
		(width 0.088646)
		(layer "In6.Cu")
		(net "M_G_CPU1_SB_DQ<9>")
	)
	(arc
		(start 139.364212 -235.34497)
		(mid 139.267289 -235.332012)
		(end 139.177014 -235.294424)
		(width 0.088646)
		(layer "In6.Cu")
		(net "M_G_CPU1_SB_DQ<9>")
	)
	(arc
		(start 134.948168 -236.10824)
		(mid 134.665466 -236.032498)
		(end 134.382764 -236.10824)
		(width 0.088646)
		(layer "In6.Cu")
		(net "M_G_CPU1_SB_DQ<9>")
	)
	(arc
		(start 134.382764 -236.10824)
		(mid 134.195566 -236.158383)
		(end 134.008368 -236.10824)
		(width 0.088646)
		(layer "In6.Cu")
		(net "M_G_CPU1_SB_DQ<9>")
	)
	(arc
		(start 131.188968 -236.10824)
		(mid 130.914739 -236.032315)
		(end 130.638296 -236.099604)
		(width 0.088646)
		(layer "In6.Cu")
		(net "M_G_CPU1_SB_DQ<9>")
	)
	(arc
		(start 132.50291 -236.10824)
		(mid 132.315712 -236.158383)
		(end 132.128514 -236.10824)
		(width 0.088646)
		(layer "In6.Cu")
		(net "M_G_CPU1_SB_DQ<9>")
	)
	(arc
		(start 130.249168 -236.10824)
		(mid 129.974939 -236.032315)
		(end 129.698496 -236.099604)
		(width 0.088646)
		(layer "In6.Cu")
		(net "M_G_CPU1_SB_DQ<9>")
	)
	(arc
		(start 136.262364 -236.10824)
		(mid 136.075166 -236.158383)
		(end 135.887968 -236.10824)
		(width 0.088646)
		(layer "In6.Cu")
		(net "M_G_CPU1_SB_DQ<9>")
	)
	(arc
		(start 136.827768 -236.10824)
		(mid 136.553539 -236.032315)
		(end 136.277096 -236.099604)
		(width 0.088646)
		(layer "In6.Cu")
		(net "M_G_CPU1_SB_DQ<9>")
	)
	(arc
		(start 137.767568 -236.10824)
		(mid 137.493339 -236.032315)
		(end 137.216896 -236.099604)
		(width 0.088646)
		(layer "In6.Cu")
		(net "M_G_CPU1_SB_DQ<9>")
	)
	(arc
		(start 129.313686 -236.111034)
		(mid 129.206783 -236.041211)
		(end 129.110486 -235.957364)
		(width 0.088646)
		(layer "In6.Cu")
		(net "M_G_CPU1_SB_DQ<9>")
	)
	(arc
		(start 134.008368 -236.10824)
		(mid 133.725666 -236.032498)
		(end 133.442964 -236.10824)
		(width 0.088646)
		(layer "In6.Cu")
		(net "M_G_CPU1_SB_DQ<9>")
	)
	(arc
		(start 133.068568 -236.10824)
		(mid 132.791755 -236.032404)
		(end 132.513324 -236.102144)
		(width 0.088646)
		(layer "In6.Cu")
		(net "M_G_CPU1_SB_DQ<9>")
	)
	(arc
		(start 137.202164 -236.10824)
		(mid 137.014966 -236.158383)
		(end 136.827768 -236.10824)
		(width 0.088646)
		(layer "In6.Cu")
		(net "M_G_CPU1_SB_DQ<9>")
	)
	(arc
		(start 128.743964 -235.459524)
		(mid 128.654883 -235.422525)
		(end 128.559306 -235.409486)
		(width 0.088646)
		(layer "In6.Cu")
		(net "M_G_CPU1_SB_DQ<9>")
	)
	(arc
		(start 138.329416 -235.783882)
		(mid 138.142117 -236.108323)
		(end 137.767568 -236.10824)
		(width 0.088646)
		(layer "In6.Cu")
		(net "M_G_CPU1_SB_DQ<9>")
	)
	(arc
		(start 138.61161 -235.294424)
		(mid 138.408787 -235.494655)
		(end 138.329416 -235.768388)
		(width 0.088646)
		(layer "In6.Cu")
		(net "M_G_CPU1_SB_DQ<9>")
	)
	(arc
		(start 127.58801 -235.406692)
		(mid 127.095086 -235.504723)
		(end 126.677166 -235.783882)
		(width 0.088646)
		(layer "In6.Cu")
		(net "M_G_CPU1_SB_DQ<9>")
	)
	(arc
		(start 129.063496 -235.910374)
		(mid 129.010313 -235.83078)
		(end 128.991614 -235.736892)
		(width 0.088646)
		(layer "In6.Cu")
		(net "M_G_CPU1_SB_DQ<9>")
	)
	(arc
		(start 130.623564 -236.10824)
		(mid 130.436366 -236.158383)
		(end 130.249168 -236.10824)
		(width 0.088646)
		(layer "In6.Cu")
		(net "M_G_CPU1_SB_DQ<9>")
	)
	(arc
		(start 139.162282 -235.285788)
		(mid 138.885807 -235.218468)
		(end 138.61161 -235.294424)
		(width 0.088646)
		(layer "In6.Cu")
		(net "M_G_CPU1_SB_DQ<9>")
	)
	(arc
		(start 133.442964 -236.10824)
		(mid 133.255766 -236.158383)
		(end 133.068568 -236.10824)
		(width 0.088646)
		(layer "In6.Cu")
		(net "M_G_CPU1_SB_DQ<9>")
	)
	(arc
		(start 135.887968 -236.10824)
		(mid 135.613739 -236.032315)
		(end 135.337296 -236.099604)
		(width 0.088646)
		(layer "In6.Cu")
		(net "M_G_CPU1_SB_DQ<9>")
	)
	(arc
		(start 131.563364 -236.10824)
		(mid 131.376166 -236.158383)
		(end 131.188968 -236.10824)
		(width 0.088646)
		(layer "In6.Cu")
		(net "M_G_CPU1_SB_DQ<9>")
	)
	(arc
		(start 128.991614 -235.736892)
		(mid 128.976641 -235.662449)
		(end 128.93421 -235.599478)
		(width 0.088646)
		(layer "In6.Cu")
		(net "M_G_CPU1_SB_DQ<9>")
	)
	(arc
		(start 132.128514 -236.10824)
		(mid 131.851955 -236.032531)
		(end 131.573778 -236.102144)
		(width 0.088646)
		(layer "In6.Cu")
		(net "M_G_CPU1_SB_DQ<9>")
	)
	(segment
		(start 128.086866 -237.133892)
		(end 128.086612 -237.133638)
		(width 0.20066)
		(layer "F.Cu")
		(net "M_G_CPU1_SB_DQ<8>")
	)
	(segment
		(start 191.233044 -223.06534)
		(end 190.75781 -223.06534)
		(width 0.20066)
		(layer "F.Cu")
		(net "M_G_CPU1_SB_DQ<8>")
	)
	(segment
		(start 191.421004 -222.509842)
		(end 191.421004 -222.87738)
		(width 0.20066)
		(layer "F.Cu")
		(net "M_G_CPU1_SB_DQ<8>")
	)
	(segment
		(start 190.75781 -223.06534)
		(end 190.509144 -222.816674)
		(width 0.20066)
		(layer "F.Cu")
		(net "M_G_CPU1_SB_DQ<8>")
	)
	(segment
		(start 191.421004 -222.87738)
		(end 191.233044 -223.06534)
		(width 0.20066)
		(layer "F.Cu")
		(net "M_G_CPU1_SB_DQ<8>")
	)
	(segment
		(start 196.532246 -222.816674)
		(end 196.531992 -222.816928)
		(width 0.20066)
		(layer "F.Cu")
		(net "M_G_CPU1_SB_DQ<8>")
	)
	(segment
		(start 191.539114 -222.391732)
		(end 191.421004 -222.509842)
		(width 0.20066)
		(layer "F.Cu")
		(net "M_G_CPU1_SB_DQ<8>")
	)
	(segment
		(start 188.988446 -222.816674)
		(end 187.883546 -222.816674)
		(width 0.20066)
		(layer "F.Cu")
		(net "M_G_CPU1_SB_DQ<8>")
	)
	(segment
		(start 190.509144 -222.816674)
		(end 188.988446 -222.816674)
		(width 0.20066)
		(layer "F.Cu")
		(net "M_G_CPU1_SB_DQ<8>")
	)
	(segment
		(start 191.930782 -222.391732)
		(end 191.883792 -222.391732)
		(width 0.101854)
		(layer "F.Cu")
		(net "M_G_CPU1_SB_DQ<8>")
	)
	(segment
		(start 194.092576 -222.391732)
		(end 191.930782 -222.391732)
		(width 0.1016)
		(layer "F.Cu")
		(net "M_G_CPU1_SB_DQ<8>")
	)
	(segment
		(start 196.531992 -222.816928)
		(end 194.940428 -222.816928)
		(width 0.20066)
		(layer "F.Cu")
		(net "M_G_CPU1_SB_DQ<8>")
	)
	(segment
		(start 191.883792 -222.391732)
		(end 191.539114 -222.391732)
		(width 0.20066)
		(layer "F.Cu")
		(net "M_G_CPU1_SB_DQ<8>")
	)
	(segment
		(start 194.098926 -222.385382)
		(end 194.092576 -222.391732)
		(width 0.1016)
		(layer "F.Cu")
		(net "M_G_CPU1_SB_DQ<8>")
	)
	(segment
		(start 194.508882 -222.385382)
		(end 194.098926 -222.385382)
		(width 0.20066)
		(layer "F.Cu")
		(net "M_G_CPU1_SB_DQ<8>")
	)
	(segment
		(start 194.940428 -222.816928)
		(end 194.508882 -222.385382)
		(width 0.20066)
		(layer "F.Cu")
		(net "M_G_CPU1_SB_DQ<8>")
	)
	(segment
		(start 128.086612 -237.133638)
		(end 128.086612 -236.597952)
		(width 0.20066)
		(layer "F.Cu")
		(net "M_G_CPU1_SB_DQ<8>")
	)
	(segment
		(start 134.008368 -237.08741)
		(end 133.997954 -237.093506)
		(width 0.088646)
		(layer "In6.Cu")
		(net "M_G_CPU1_SB_DQ<8>")
	)
	(segment
		(start 159.352234 -224.941892)
		(end 159.35198 -224.942146)
		(width 0.18288)
		(layer "In6.Cu")
		(net "M_G_CPU1_SB_DQ<8>")
	)
	(segment
		(start 132.513578 -237.093506)
		(end 132.503164 -237.08741)
		(width 0.088646)
		(layer "In6.Cu")
		(net "M_G_CPU1_SB_DQ<8>")
	)
	(segment
		(start 178.18862 -225.709226)
		(end 177.255678 -226.642168)
		(width 0.18288)
		(layer "In6.Cu")
		(net "M_G_CPU1_SB_DQ<8>")
	)
	(segment
		(start 180.192426 -224.845626)
		(end 179.328826 -225.709226)
		(width 0.18288)
		(layer "In6.Cu")
		(net "M_G_CPU1_SB_DQ<8>")
	)
	(segment
		(start 138.989562 -236.597952)
		(end 138.989562 -236.613446)
		(width 0.088646)
		(layer "In6.Cu")
		(net "M_G_CPU1_SB_DQ<8>")
	)
	(segment
		(start 130.638296 -237.096046)
		(end 130.623564 -237.08741)
		(width 0.088646)
		(layer "In6.Cu")
		(net "M_G_CPU1_SB_DQ<8>")
	)
	(segment
		(start 155.52293 -224.941892)
		(end 144.52219 -235.942632)
		(width 0.18288)
		(layer "In6.Cu")
		(net "M_G_CPU1_SB_DQ<8>")
	)
	(segment
		(start 161.017712 -226.737672)
		(end 160.644332 -226.737672)
		(width 0.18288)
		(layer "In6.Cu")
		(net "M_G_CPU1_SB_DQ<8>")
	)
	(segment
		(start 162.178492 -224.941892)
		(end 161.337752 -224.941892)
		(width 0.18288)
		(layer "In6.Cu")
		(net "M_G_CPU1_SB_DQ<8>")
	)
	(segment
		(start 179.328826 -225.709226)
		(end 178.18862 -225.709226)
		(width 0.18288)
		(layer "In6.Cu")
		(net "M_G_CPU1_SB_DQ<8>")
	)
	(segment
		(start 180.642514 -224.845626)
		(end 180.192426 -224.845626)
		(width 0.18288)
		(layer "In6.Cu")
		(net "M_G_CPU1_SB_DQ<8>")
	)
	(segment
		(start 131.578096 -237.096046)
		(end 131.563364 -237.08741)
		(width 0.088646)
		(layer "In6.Cu")
		(net "M_G_CPU1_SB_DQ<8>")
	)
	(segment
		(start 139.908026 -235.942632)
		(end 139.627864 -236.222794)
		(width 0.088646)
		(layer "In6.Cu")
		(net "M_G_CPU1_SB_DQ<8>")
	)
	(segment
		(start 136.277096 -237.096046)
		(end 136.262364 -237.08741)
		(width 0.088646)
		(layer "In6.Cu")
		(net "M_G_CPU1_SB_DQ<8>")
	)
	(segment
		(start 135.337296 -237.096046)
		(end 135.322564 -237.08741)
		(width 0.088646)
		(layer "In6.Cu")
		(net "M_G_CPU1_SB_DQ<8>")
	)
	(segment
		(start 161.337752 -224.941892)
		(end 161.177732 -225.101912)
		(width 0.18288)
		(layer "In6.Cu")
		(net "M_G_CPU1_SB_DQ<8>")
	)
	(segment
		(start 183.113426 -224.134426)
		(end 181.353714 -224.134426)
		(width 0.18288)
		(layer "In6.Cu")
		(net "M_G_CPU1_SB_DQ<8>")
	)
	(segment
		(start 138.156696 -237.096046)
		(end 138.141964 -237.08741)
		(width 0.088646)
		(layer "In6.Cu")
		(net "M_G_CPU1_SB_DQ<8>")
	)
	(segment
		(start 167.902636 -226.602036)
		(end 165.01999 -226.602036)
		(width 0.18288)
		(layer "In6.Cu")
		(net "M_G_CPU1_SB_DQ<8>")
	)
	(segment
		(start 174.662084 -226.642168)
		(end 173.811946 -227.492306)
		(width 0.18288)
		(layer "In6.Cu")
		(net "M_G_CPU1_SB_DQ<8>")
	)
	(segment
		(start 144.52219 -235.942632)
		(end 140.222478 -235.942632)
		(width 0.18288)
		(layer "In6.Cu")
		(net "M_G_CPU1_SB_DQ<8>")
	)
	(segment
		(start 177.255678 -226.642168)
		(end 174.662084 -226.642168)
		(width 0.18288)
		(layer "In6.Cu")
		(net "M_G_CPU1_SB_DQ<8>")
	)
	(segment
		(start 158.263336 -224.942146)
		(end 157.80512 -224.942146)
		(width 0.18288)
		(layer "In6.Cu")
		(net "M_G_CPU1_SB_DQ<8>")
	)
	(segment
		(start 128.743964 -237.08741)
		(end 128.66624 -237.042452)
		(width 0.088646)
		(layer "In6.Cu")
		(net "M_G_CPU1_SB_DQ<8>")
	)
	(segment
		(start 187.883546 -222.816674)
		(end 187.430918 -223.269302)
		(width 0.18288)
		(layer "In6.Cu")
		(net "M_G_CPU1_SB_DQ<8>")
	)
	(segment
		(start 139.627864 -236.222794)
		(end 139.364212 -236.222794)
		(width 0.088646)
		(layer "In6.Cu")
		(net "M_G_CPU1_SB_DQ<8>")
	)
	(segment
		(start 159.276796 -224.942146)
		(end 159.116776 -225.102166)
		(width 0.18288)
		(layer "In6.Cu")
		(net "M_G_CPU1_SB_DQ<8>")
	)
	(segment
		(start 157.80512 -224.942146)
		(end 157.804866 -224.941892)
		(width 0.18288)
		(layer "In6.Cu")
		(net "M_G_CPU1_SB_DQ<8>")
	)
	(segment
		(start 158.423356 -225.102166)
		(end 158.263336 -224.942146)
		(width 0.18288)
		(layer "In6.Cu")
		(net "M_G_CPU1_SB_DQ<8>")
	)
	(segment
		(start 158.583376 -226.839272)
		(end 158.423356 -226.679252)
		(width 0.18288)
		(layer "In6.Cu")
		(net "M_G_CPU1_SB_DQ<8>")
	)
	(segment
		(start 160.644332 -226.737672)
		(end 160.484312 -226.577652)
		(width 0.18288)
		(layer "In6.Cu")
		(net "M_G_CPU1_SB_DQ<8>")
	)
	(segment
		(start 161.177732 -226.577652)
		(end 161.017712 -226.737672)
		(width 0.18288)
		(layer "In6.Cu")
		(net "M_G_CPU1_SB_DQ<8>")
	)
	(segment
		(start 160.324292 -224.941892)
		(end 159.352234 -224.941892)
		(width 0.18288)
		(layer "In6.Cu")
		(net "M_G_CPU1_SB_DQ<8>")
	)
	(segment
		(start 168.792906 -227.492306)
		(end 167.902636 -226.602036)
		(width 0.18288)
		(layer "In6.Cu")
		(net "M_G_CPU1_SB_DQ<8>")
	)
	(segment
		(start 162.805872 -225.569272)
		(end 162.178492 -224.941892)
		(width 0.18288)
		(layer "In6.Cu")
		(net "M_G_CPU1_SB_DQ<8>")
	)
	(segment
		(start 157.804866 -224.941892)
		(end 155.52293 -224.941892)
		(width 0.18288)
		(layer "In6.Cu")
		(net "M_G_CPU1_SB_DQ<8>")
	)
	(segment
		(start 165.01999 -226.602036)
		(end 163.987226 -225.569272)
		(width 0.18288)
		(layer "In6.Cu")
		(net "M_G_CPU1_SB_DQ<8>")
	)
	(segment
		(start 187.430918 -223.269302)
		(end 183.97855 -223.269302)
		(width 0.18288)
		(layer "In6.Cu")
		(net "M_G_CPU1_SB_DQ<8>")
	)
	(segment
		(start 159.35198 -224.942146)
		(end 159.276796 -224.942146)
		(width 0.18288)
		(layer "In6.Cu")
		(net "M_G_CPU1_SB_DQ<8>")
	)
	(segment
		(start 163.987226 -225.569272)
		(end 162.805872 -225.569272)
		(width 0.18288)
		(layer "In6.Cu")
		(net "M_G_CPU1_SB_DQ<8>")
	)
	(segment
		(start 173.811946 -227.492306)
		(end 168.792906 -227.492306)
		(width 0.18288)
		(layer "In6.Cu")
		(net "M_G_CPU1_SB_DQ<8>")
	)
	(segment
		(start 161.177732 -225.101912)
		(end 161.177732 -226.577652)
		(width 0.18288)
		(layer "In6.Cu")
		(net "M_G_CPU1_SB_DQ<8>")
	)
	(segment
		(start 159.116776 -226.679252)
		(end 158.956756 -226.839272)
		(width 0.18288)
		(layer "In6.Cu")
		(net "M_G_CPU1_SB_DQ<8>")
	)
	(segment
		(start 159.116776 -225.102166)
		(end 159.116776 -226.679252)
		(width 0.18288)
		(layer "In6.Cu")
		(net "M_G_CPU1_SB_DQ<8>")
	)
	(segment
		(start 160.484312 -226.577652)
		(end 160.484312 -225.101912)
		(width 0.18288)
		(layer "In6.Cu")
		(net "M_G_CPU1_SB_DQ<8>")
	)
	(segment
		(start 181.353714 -224.134426)
		(end 180.642514 -224.845626)
		(width 0.18288)
		(layer "In6.Cu")
		(net "M_G_CPU1_SB_DQ<8>")
	)
	(segment
		(start 140.222478 -235.942632)
		(end 139.908026 -235.942632)
		(width 0.088646)
		(layer "In6.Cu")
		(net "M_G_CPU1_SB_DQ<8>")
	)
	(segment
		(start 139.177014 -236.273594)
		(end 139.168124 -236.278674)
		(width 0.088646)
		(layer "In6.Cu")
		(net "M_G_CPU1_SB_DQ<8>")
	)
	(segment
		(start 129.698496 -237.096046)
		(end 129.683764 -237.08741)
		(width 0.088646)
		(layer "In6.Cu")
		(net "M_G_CPU1_SB_DQ<8>")
	)
	(segment
		(start 183.97855 -223.269302)
		(end 183.113426 -224.134426)
		(width 0.18288)
		(layer "In6.Cu")
		(net "M_G_CPU1_SB_DQ<8>")
	)
	(segment
		(start 160.484312 -225.101912)
		(end 160.324292 -224.941892)
		(width 0.18288)
		(layer "In6.Cu")
		(net "M_G_CPU1_SB_DQ<8>")
	)
	(segment
		(start 158.423356 -226.679252)
		(end 158.423356 -225.102166)
		(width 0.18288)
		(layer "In6.Cu")
		(net "M_G_CPU1_SB_DQ<8>")
	)
	(segment
		(start 158.956756 -226.839272)
		(end 158.583376 -226.839272)
		(width 0.18288)
		(layer "In6.Cu")
		(net "M_G_CPU1_SB_DQ<8>")
	)
	(segment
		(start 137.216896 -237.096046)
		(end 137.202164 -237.08741)
		(width 0.088646)
		(layer "In6.Cu")
		(net "M_G_CPU1_SB_DQ<8>")
	)
	(arc
		(start 139.364212 -236.222794)
		(mid 139.267273 -236.235884)
		(end 139.177014 -236.273594)
		(width 0.088646)
		(layer "In6.Cu")
		(net "M_G_CPU1_SB_DQ<8>")
	)
	(arc
		(start 135.322564 -237.08741)
		(mid 135.135366 -237.037233)
		(end 134.948168 -237.08741)
		(width 0.088646)
		(layer "In6.Cu")
		(net "M_G_CPU1_SB_DQ<8>")
	)
	(arc
		(start 130.249168 -237.08741)
		(mid 129.974969 -237.163245)
		(end 129.698496 -237.096046)
		(width 0.088646)
		(layer "In6.Cu")
		(net "M_G_CPU1_SB_DQ<8>")
	)
	(arc
		(start 128.66624 -237.042452)
		(mid 128.361841 -236.839222)
		(end 128.086612 -236.597952)
		(width 0.088646)
		(layer "In6.Cu")
		(net "M_G_CPU1_SB_DQ<8>")
	)
	(arc
		(start 129.309368 -237.08741)
		(mid 129.026666 -237.163186)
		(end 128.743964 -237.08741)
		(width 0.088646)
		(layer "In6.Cu")
		(net "M_G_CPU1_SB_DQ<8>")
	)
	(arc
		(start 137.202164 -237.08741)
		(mid 137.014966 -237.037233)
		(end 136.827768 -237.08741)
		(width 0.088646)
		(layer "In6.Cu")
		(net "M_G_CPU1_SB_DQ<8>")
	)
	(arc
		(start 134.382764 -237.08741)
		(mid 134.195566 -237.037233)
		(end 134.008368 -237.08741)
		(width 0.088646)
		(layer "In6.Cu")
		(net "M_G_CPU1_SB_DQ<8>")
	)
	(arc
		(start 134.948168 -237.08741)
		(mid 134.665466 -237.163186)
		(end 134.382764 -237.08741)
		(width 0.088646)
		(layer "In6.Cu")
		(net "M_G_CPU1_SB_DQ<8>")
	)
	(arc
		(start 132.503164 -237.08741)
		(mid 132.315966 -237.037233)
		(end 132.128768 -237.08741)
		(width 0.088646)
		(layer "In6.Cu")
		(net "M_G_CPU1_SB_DQ<8>")
	)
	(arc
		(start 138.141964 -237.08741)
		(mid 137.954766 -237.037233)
		(end 137.767568 -237.08741)
		(width 0.088646)
		(layer "In6.Cu")
		(net "M_G_CPU1_SB_DQ<8>")
	)
	(arc
		(start 129.683764 -237.08741)
		(mid 129.496566 -237.037233)
		(end 129.309368 -237.08741)
		(width 0.088646)
		(layer "In6.Cu")
		(net "M_G_CPU1_SB_DQ<8>")
	)
	(arc
		(start 131.563364 -237.08741)
		(mid 131.376166 -237.037233)
		(end 131.188968 -237.08741)
		(width 0.088646)
		(layer "In6.Cu")
		(net "M_G_CPU1_SB_DQ<8>")
	)
	(arc
		(start 133.068314 -237.08741)
		(mid 132.791755 -237.163153)
		(end 132.513578 -237.093506)
		(width 0.088646)
		(layer "In6.Cu")
		(net "M_G_CPU1_SB_DQ<8>")
	)
	(arc
		(start 135.887968 -237.08741)
		(mid 135.613769 -237.163245)
		(end 135.337296 -237.096046)
		(width 0.088646)
		(layer "In6.Cu")
		(net "M_G_CPU1_SB_DQ<8>")
	)
	(arc
		(start 138.989562 -236.613446)
		(mid 138.910192 -236.88718)
		(end 138.707368 -237.08741)
		(width 0.088646)
		(layer "In6.Cu")
		(net "M_G_CPU1_SB_DQ<8>")
	)
	(arc
		(start 130.623564 -237.08741)
		(mid 130.436366 -237.037233)
		(end 130.249168 -237.08741)
		(width 0.088646)
		(layer "In6.Cu")
		(net "M_G_CPU1_SB_DQ<8>")
	)
	(arc
		(start 136.827768 -237.08741)
		(mid 136.553569 -237.163245)
		(end 136.277096 -237.096046)
		(width 0.088646)
		(layer "In6.Cu")
		(net "M_G_CPU1_SB_DQ<8>")
	)
	(arc
		(start 139.168124 -236.278674)
		(mid 139.03721 -236.415034)
		(end 138.989562 -236.597952)
		(width 0.088646)
		(layer "In6.Cu")
		(net "M_G_CPU1_SB_DQ<8>")
	)
	(arc
		(start 132.128768 -237.08741)
		(mid 131.854569 -237.163245)
		(end 131.578096 -237.096046)
		(width 0.088646)
		(layer "In6.Cu")
		(net "M_G_CPU1_SB_DQ<8>")
	)
	(arc
		(start 136.262364 -237.08741)
		(mid 136.075166 -237.037233)
		(end 135.887968 -237.08741)
		(width 0.088646)
		(layer "In6.Cu")
		(net "M_G_CPU1_SB_DQ<8>")
	)
	(arc
		(start 138.707368 -237.08741)
		(mid 138.433169 -237.163245)
		(end 138.156696 -237.096046)
		(width 0.088646)
		(layer "In6.Cu")
		(net "M_G_CPU1_SB_DQ<8>")
	)
	(arc
		(start 133.44271 -237.08741)
		(mid 133.255512 -237.037233)
		(end 133.068314 -237.08741)
		(width 0.088646)
		(layer "In6.Cu")
		(net "M_G_CPU1_SB_DQ<8>")
	)
	(arc
		(start 133.997954 -237.093506)
		(mid 133.719522 -237.163352)
		(end 133.44271 -237.08741)
		(width 0.088646)
		(layer "In6.Cu")
		(net "M_G_CPU1_SB_DQ<8>")
	)
	(arc
		(start 137.767568 -237.08741)
		(mid 137.493369 -237.163245)
		(end 137.216896 -237.096046)
		(width 0.088646)
		(layer "In6.Cu")
		(net "M_G_CPU1_SB_DQ<8>")
	)
	(arc
		(start 131.188968 -237.08741)
		(mid 130.914769 -237.163245)
		(end 130.638296 -237.096046)
		(width 0.088646)
		(layer "In6.Cu")
		(net "M_G_CPU1_SB_DQ<8>")
	)
	(segment
		(start 199.298052 -223.666558)
		(end 200.632314 -223.666558)
		(width 0.20066)
		(layer "F.Cu")
		(net "M_G_CPU1_SB_DQ<7>")
	)
	(segment
		(start 198.223886 -224.103692)
		(end 198.427848 -223.89973)
		(width 0.20066)
		(layer "F.Cu")
		(net "M_G_CPU1_SB_DQ<7>")
	)
	(segment
		(start 193.088514 -223.666558)
		(end 194.786758 -223.666558)
		(width 0.20066)
		(layer "F.Cu")
		(net "M_G_CPU1_SB_DQ<7>")
	)
	(segment
		(start 198.427848 -223.648778)
		(end 198.662036 -223.41459)
		(width 0.20066)
		(layer "F.Cu")
		(net "M_G_CPU1_SB_DQ<7>")
	)
	(segment
		(start 191.983614 -223.666558)
		(end 193.088514 -223.666558)
		(width 0.20066)
		(layer "F.Cu")
		(net "M_G_CPU1_SB_DQ<7>")
	)
	(segment
		(start 197.542658 -224.103692)
		(end 198.223886 -224.103692)
		(width 0.20066)
		(layer "F.Cu")
		(net "M_G_CPU1_SB_DQ<7>")
	)
	(segment
		(start 195.515484 -224.098612)
		(end 195.522596 -224.0915)
		(width 0.1016)
		(layer "F.Cu")
		(net "M_G_CPU1_SB_DQ<7>")
	)
	(segment
		(start 195.218812 -224.098612)
		(end 195.510658 -224.098612)
		(width 0.20066)
		(layer "F.Cu")
		(net "M_G_CPU1_SB_DQ<7>")
	)
	(segment
		(start 199.046084 -223.41459)
		(end 199.298052 -223.666558)
		(width 0.20066)
		(layer "F.Cu")
		(net "M_G_CPU1_SB_DQ<7>")
	)
	(segment
		(start 194.786758 -223.666558)
		(end 195.218812 -224.098612)
		(width 0.20066)
		(layer "F.Cu")
		(net "M_G_CPU1_SB_DQ<7>")
	)
	(segment
		(start 197.530466 -224.0915)
		(end 197.542658 -224.103692)
		(width 0.1016)
		(layer "F.Cu")
		(net "M_G_CPU1_SB_DQ<7>")
	)
	(segment
		(start 128.086866 -238.761524)
		(end 128.086612 -238.76127)
		(width 0.20066)
		(layer "F.Cu")
		(net "M_G_CPU1_SB_DQ<7>")
	)
	(segment
		(start 198.427848 -223.89973)
		(end 198.427848 -223.648778)
		(width 0.20066)
		(layer "F.Cu")
		(net "M_G_CPU1_SB_DQ<7>")
	)
	(segment
		(start 195.510658 -224.098612)
		(end 195.515484 -224.098612)
		(width 0.101854)
		(layer "F.Cu")
		(net "M_G_CPU1_SB_DQ<7>")
	)
	(segment
		(start 198.662036 -223.41459)
		(end 199.046084 -223.41459)
		(width 0.20066)
		(layer "F.Cu")
		(net "M_G_CPU1_SB_DQ<7>")
	)
	(segment
		(start 195.522596 -224.0915)
		(end 197.530466 -224.0915)
		(width 0.1016)
		(layer "F.Cu")
		(net "M_G_CPU1_SB_DQ<7>")
	)
	(segment
		(start 128.086612 -238.76127)
		(end 128.086612 -238.225584)
		(width 0.20066)
		(layer "F.Cu")
		(net "M_G_CPU1_SB_DQ<7>")
	)
	(segment
		(start 170.014392 -229.316026)
		(end 168.606978 -229.316026)
		(width 0.18288)
		(layer "In6.Cu")
		(net "M_G_CPU1_SB_DQ<7>")
	)
	(segment
		(start 140.222478 -236.745526)
		(end 140.090906 -236.745526)
		(width 0.088646)
		(layer "In6.Cu")
		(net "M_G_CPU1_SB_DQ<7>")
	)
	(segment
		(start 171.073572 -229.316026)
		(end 170.890692 -229.133146)
		(width 0.18288)
		(layer "In6.Cu")
		(net "M_G_CPU1_SB_DQ<7>")
	)
	(segment
		(start 140.090906 -236.745526)
		(end 139.159742 -237.67669)
		(width 0.088646)
		(layer "In6.Cu")
		(net "M_G_CPU1_SB_DQ<7>")
	)
	(segment
		(start 185.221626 -225.125026)
		(end 183.596026 -225.125026)
		(width 0.18288)
		(layer "In6.Cu")
		(net "M_G_CPU1_SB_DQ<7>")
	)
	(segment
		(start 158.22168 -229.192074)
		(end 157.326838 -229.192074)
		(width 0.18288)
		(layer "In6.Cu")
		(net "M_G_CPU1_SB_DQ<7>")
	)
	(segment
		(start 130.248914 -237.736126)
		(end 130.243072 -237.73257)
		(width 0.088646)
		(layer "In6.Cu")
		(net "M_G_CPU1_SB_DQ<7>")
	)
	(segment
		(start 170.707812 -228.373686)
		(end 170.380152 -228.373686)
		(width 0.18288)
		(layer "In6.Cu")
		(net "M_G_CPU1_SB_DQ<7>")
	)
	(segment
		(start 170.890692 -229.133146)
		(end 170.890692 -228.556566)
		(width 0.18288)
		(layer "In6.Cu")
		(net "M_G_CPU1_SB_DQ<7>")
	)
	(segment
		(start 144.846548 -236.745526)
		(end 140.222478 -236.745526)
		(width 0.18288)
		(layer "In6.Cu")
		(net "M_G_CPU1_SB_DQ<7>")
	)
	(segment
		(start 159.754316 -228.342444)
		(end 159.07131 -228.342444)
		(width 0.18288)
		(layer "In6.Cu")
		(net "M_G_CPU1_SB_DQ<7>")
	)
	(segment
		(start 191.983614 -223.666558)
		(end 191.55791 -224.092262)
		(width 0.18288)
		(layer "In6.Cu")
		(net "M_G_CPU1_SB_DQ<7>")
	)
	(segment
		(start 167.383968 -228.093016)
		(end 163.223956 -228.093016)
		(width 0.18288)
		(layer "In6.Cu")
		(net "M_G_CPU1_SB_DQ<7>")
	)
	(segment
		(start 160.630616 -228.159564)
		(end 160.630616 -227.736146)
		(width 0.18288)
		(layer "In6.Cu")
		(net "M_G_CPU1_SB_DQ<7>")
	)
	(segment
		(start 186.25439 -224.092262)
		(end 185.221626 -225.125026)
		(width 0.18288)
		(layer "In6.Cu")
		(net "M_G_CPU1_SB_DQ<7>")
	)
	(segment
		(start 180.611018 -225.810826)
		(end 178.0794 -228.342444)
		(width 0.18288)
		(layer "In6.Cu")
		(net "M_G_CPU1_SB_DQ<7>")
	)
	(segment
		(start 170.890692 -228.556566)
		(end 170.707812 -228.373686)
		(width 0.18288)
		(layer "In6.Cu")
		(net "M_G_CPU1_SB_DQ<7>")
	)
	(segment
		(start 159.937196 -227.736146)
		(end 159.937196 -228.159564)
		(width 0.18288)
		(layer "In6.Cu")
		(net "M_G_CPU1_SB_DQ<7>")
	)
	(segment
		(start 152.586182 -229.005892)
		(end 144.846548 -236.745526)
		(width 0.18288)
		(layer "In6.Cu")
		(net "M_G_CPU1_SB_DQ<7>")
	)
	(segment
		(start 128.743964 -237.736126)
		(end 128.663954 -237.782354)
		(width 0.088646)
		(layer "In6.Cu")
		(net "M_G_CPU1_SB_DQ<7>")
	)
	(segment
		(start 172.289724 -229.192328)
		(end 172.166026 -229.316026)
		(width 0.18288)
		(layer "In6.Cu")
		(net "M_G_CPU1_SB_DQ<7>")
	)
	(segment
		(start 159.07131 -228.342444)
		(end 158.22168 -229.192074)
		(width 0.18288)
		(layer "In6.Cu")
		(net "M_G_CPU1_SB_DQ<7>")
	)
	(segment
		(start 129.314956 -237.739428)
		(end 129.309114 -237.736126)
		(width 0.088646)
		(layer "In6.Cu")
		(net "M_G_CPU1_SB_DQ<7>")
	)
	(segment
		(start 131.188714 -237.736126)
		(end 131.182872 -237.73257)
		(width 0.088646)
		(layer "In6.Cu")
		(net "M_G_CPU1_SB_DQ<7>")
	)
	(segment
		(start 163.223956 -228.093016)
		(end 162.974528 -228.342444)
		(width 0.18288)
		(layer "In6.Cu")
		(net "M_G_CPU1_SB_DQ<7>")
	)
	(segment
		(start 160.120076 -227.553266)
		(end 159.937196 -227.736146)
		(width 0.18288)
		(layer "In6.Cu")
		(net "M_G_CPU1_SB_DQ<7>")
	)
	(segment
		(start 191.55791 -224.092262)
		(end 186.25439 -224.092262)
		(width 0.18288)
		(layer "In6.Cu")
		(net "M_G_CPU1_SB_DQ<7>")
	)
	(segment
		(start 170.197272 -229.133146)
		(end 170.014392 -229.316026)
		(width 0.18288)
		(layer "In6.Cu")
		(net "M_G_CPU1_SB_DQ<7>")
	)
	(segment
		(start 159.937196 -228.159564)
		(end 159.754316 -228.342444)
		(width 0.18288)
		(layer "In6.Cu")
		(net "M_G_CPU1_SB_DQ<7>")
	)
	(segment
		(start 157.326838 -229.192074)
		(end 157.140656 -229.005892)
		(width 0.18288)
		(layer "In6.Cu")
		(net "M_G_CPU1_SB_DQ<7>")
	)
	(segment
		(start 129.309114 -237.736126)
		(end 129.303272 -237.73257)
		(width 0.088646)
		(layer "In6.Cu")
		(net "M_G_CPU1_SB_DQ<7>")
	)
	(segment
		(start 178.0794 -228.342444)
		(end 174.333662 -228.342444)
		(width 0.18288)
		(layer "In6.Cu")
		(net "M_G_CPU1_SB_DQ<7>")
	)
	(segment
		(start 130.254756 -237.739428)
		(end 130.248914 -237.736126)
		(width 0.088646)
		(layer "In6.Cu")
		(net "M_G_CPU1_SB_DQ<7>")
	)
	(segment
		(start 131.194556 -237.739428)
		(end 131.188714 -237.736126)
		(width 0.088646)
		(layer "In6.Cu")
		(net "M_G_CPU1_SB_DQ<7>")
	)
	(segment
		(start 182.910226 -225.810826)
		(end 180.611018 -225.810826)
		(width 0.18288)
		(layer "In6.Cu")
		(net "M_G_CPU1_SB_DQ<7>")
	)
	(segment
		(start 183.596026 -225.125026)
		(end 182.910226 -225.810826)
		(width 0.18288)
		(layer "In6.Cu")
		(net "M_G_CPU1_SB_DQ<7>")
	)
	(segment
		(start 157.140656 -229.005892)
		(end 152.586182 -229.005892)
		(width 0.18288)
		(layer "In6.Cu")
		(net "M_G_CPU1_SB_DQ<7>")
	)
	(segment
		(start 134.382764 -237.735872)
		(end 134.382764 -237.736126)
		(width 0.088646)
		(layer "In6.Cu")
		(net "M_G_CPU1_SB_DQ<7>")
	)
	(segment
		(start 160.630616 -227.736146)
		(end 160.447736 -227.553266)
		(width 0.18288)
		(layer "In6.Cu")
		(net "M_G_CPU1_SB_DQ<7>")
	)
	(segment
		(start 162.974528 -228.342444)
		(end 160.813496 -228.342444)
		(width 0.18288)
		(layer "In6.Cu")
		(net "M_G_CPU1_SB_DQ<7>")
	)
	(segment
		(start 174.333662 -228.342444)
		(end 173.483778 -229.192328)
		(width 0.18288)
		(layer "In6.Cu")
		(net "M_G_CPU1_SB_DQ<7>")
	)
	(segment
		(start 160.447736 -227.553266)
		(end 160.120076 -227.553266)
		(width 0.18288)
		(layer "In6.Cu")
		(net "M_G_CPU1_SB_DQ<7>")
	)
	(segment
		(start 134.008114 -237.736126)
		(end 134.004558 -237.73384)
		(width 0.088646)
		(layer "In6.Cu")
		(net "M_G_CPU1_SB_DQ<7>")
	)
	(segment
		(start 168.606978 -229.316026)
		(end 167.383968 -228.093016)
		(width 0.18288)
		(layer "In6.Cu")
		(net "M_G_CPU1_SB_DQ<7>")
	)
	(segment
		(start 172.166026 -229.316026)
		(end 171.073572 -229.316026)
		(width 0.18288)
		(layer "In6.Cu")
		(net "M_G_CPU1_SB_DQ<7>")
	)
	(segment
		(start 160.813496 -228.342444)
		(end 160.630616 -228.159564)
		(width 0.18288)
		(layer "In6.Cu")
		(net "M_G_CPU1_SB_DQ<7>")
	)
	(segment
		(start 170.197272 -228.556566)
		(end 170.197272 -229.133146)
		(width 0.18288)
		(layer "In6.Cu")
		(net "M_G_CPU1_SB_DQ<7>")
	)
	(segment
		(start 133.068314 -237.736126)
		(end 133.062472 -237.73257)
		(width 0.088646)
		(layer "In6.Cu")
		(net "M_G_CPU1_SB_DQ<7>")
	)
	(segment
		(start 132.134356 -237.739428)
		(end 132.128514 -237.736126)
		(width 0.088646)
		(layer "In6.Cu")
		(net "M_G_CPU1_SB_DQ<7>")
	)
	(segment
		(start 170.380152 -228.373686)
		(end 170.197272 -228.556566)
		(width 0.18288)
		(layer "In6.Cu")
		(net "M_G_CPU1_SB_DQ<7>")
	)
	(segment
		(start 133.074156 -237.739428)
		(end 133.068314 -237.736126)
		(width 0.088646)
		(layer "In6.Cu")
		(net "M_G_CPU1_SB_DQ<7>")
	)
	(segment
		(start 132.128514 -237.736126)
		(end 132.122672 -237.73257)
		(width 0.088646)
		(layer "In6.Cu")
		(net "M_G_CPU1_SB_DQ<7>")
	)
	(segment
		(start 173.483778 -229.192328)
		(end 172.289724 -229.192328)
		(width 0.18288)
		(layer "In6.Cu")
		(net "M_G_CPU1_SB_DQ<7>")
	)
	(arc
		(start 139.081764 -237.735872)
		(mid 138.894566 -237.786015)
		(end 138.707368 -237.735872)
		(width 0.088646)
		(layer "In6.Cu")
		(net "M_G_CPU1_SB_DQ<7>")
	)
	(arc
		(start 134.382764 -237.736126)
		(mid 134.195456 -237.786269)
		(end 134.008114 -237.736126)
		(width 0.088646)
		(layer "In6.Cu")
		(net "M_G_CPU1_SB_DQ<7>")
	)
	(arc
		(start 130.243072 -237.73257)
		(mid 129.962937 -237.660287)
		(end 129.683764 -237.736126)
		(width 0.088646)
		(layer "In6.Cu")
		(net "M_G_CPU1_SB_DQ<7>")
	)
	(arc
		(start 134.004558 -237.73384)
		(mid 133.723445 -237.660263)
		(end 133.442964 -237.736126)
		(width 0.088646)
		(layer "In6.Cu")
		(net "M_G_CPU1_SB_DQ<7>")
	)
	(arc
		(start 135.887968 -237.735872)
		(mid 135.605266 -237.66013)
		(end 135.322564 -237.735872)
		(width 0.088646)
		(layer "In6.Cu")
		(net "M_G_CPU1_SB_DQ<7>")
	)
	(arc
		(start 128.663954 -237.782354)
		(mid 128.36079 -237.985089)
		(end 128.086612 -238.225584)
		(width 0.088646)
		(layer "In6.Cu")
		(net "M_G_CPU1_SB_DQ<7>")
	)
	(arc
		(start 129.303272 -237.73257)
		(mid 129.023137 -237.660287)
		(end 128.743964 -237.736126)
		(width 0.088646)
		(layer "In6.Cu")
		(net "M_G_CPU1_SB_DQ<7>")
	)
	(arc
		(start 136.827768 -237.735872)
		(mid 136.545066 -237.66013)
		(end 136.262364 -237.735872)
		(width 0.088646)
		(layer "In6.Cu")
		(net "M_G_CPU1_SB_DQ<7>")
	)
	(arc
		(start 130.623564 -237.736126)
		(mid 130.43961 -237.786255)
		(end 130.254756 -237.739428)
		(width 0.088646)
		(layer "In6.Cu")
		(net "M_G_CPU1_SB_DQ<7>")
	)
	(arc
		(start 137.202164 -237.735872)
		(mid 137.014966 -237.786015)
		(end 136.827768 -237.735872)
		(width 0.088646)
		(layer "In6.Cu")
		(net "M_G_CPU1_SB_DQ<7>")
	)
	(arc
		(start 132.503164 -237.736126)
		(mid 132.31921 -237.786255)
		(end 132.134356 -237.739428)
		(width 0.088646)
		(layer "In6.Cu")
		(net "M_G_CPU1_SB_DQ<7>")
	)
	(arc
		(start 136.262364 -237.735872)
		(mid 136.075166 -237.786015)
		(end 135.887968 -237.735872)
		(width 0.088646)
		(layer "In6.Cu")
		(net "M_G_CPU1_SB_DQ<7>")
	)
	(arc
		(start 131.182872 -237.73257)
		(mid 130.902737 -237.660287)
		(end 130.623564 -237.736126)
		(width 0.088646)
		(layer "In6.Cu")
		(net "M_G_CPU1_SB_DQ<7>")
	)
	(arc
		(start 133.062472 -237.73257)
		(mid 132.782337 -237.660287)
		(end 132.503164 -237.736126)
		(width 0.088646)
		(layer "In6.Cu")
		(net "M_G_CPU1_SB_DQ<7>")
	)
	(arc
		(start 132.122672 -237.73257)
		(mid 131.842537 -237.660287)
		(end 131.563364 -237.736126)
		(width 0.088646)
		(layer "In6.Cu")
		(net "M_G_CPU1_SB_DQ<7>")
	)
	(arc
		(start 139.159742 -237.67669)
		(mid 139.122692 -237.708836)
		(end 139.081764 -237.735872)
		(width 0.088646)
		(layer "In6.Cu")
		(net "M_G_CPU1_SB_DQ<7>")
	)
	(arc
		(start 129.683764 -237.736126)
		(mid 129.49981 -237.786255)
		(end 129.314956 -237.739428)
		(width 0.088646)
		(layer "In6.Cu")
		(net "M_G_CPU1_SB_DQ<7>")
	)
	(arc
		(start 137.767568 -237.735872)
		(mid 137.484866 -237.66013)
		(end 137.202164 -237.735872)
		(width 0.088646)
		(layer "In6.Cu")
		(net "M_G_CPU1_SB_DQ<7>")
	)
	(arc
		(start 134.948168 -237.735872)
		(mid 134.665466 -237.66013)
		(end 134.382764 -237.735872)
		(width 0.088646)
		(layer "In6.Cu")
		(net "M_G_CPU1_SB_DQ<7>")
	)
	(arc
		(start 138.707368 -237.735872)
		(mid 138.424666 -237.66013)
		(end 138.141964 -237.735872)
		(width 0.088646)
		(layer "In6.Cu")
		(net "M_G_CPU1_SB_DQ<7>")
	)
	(arc
		(start 131.563364 -237.736126)
		(mid 131.37941 -237.786255)
		(end 131.194556 -237.739428)
		(width 0.088646)
		(layer "In6.Cu")
		(net "M_G_CPU1_SB_DQ<7>")
	)
	(arc
		(start 135.322564 -237.735872)
		(mid 135.135366 -237.786015)
		(end 134.948168 -237.735872)
		(width 0.088646)
		(layer "In6.Cu")
		(net "M_G_CPU1_SB_DQ<7>")
	)
	(arc
		(start 138.141964 -237.735872)
		(mid 137.954766 -237.786015)
		(end 137.767568 -237.735872)
		(width 0.088646)
		(layer "In6.Cu")
		(net "M_G_CPU1_SB_DQ<7>")
	)
	(arc
		(start 133.442964 -237.736126)
		(mid 133.25901 -237.786255)
		(end 133.074156 -237.739428)
		(width 0.088646)
		(layer "In6.Cu")
		(net "M_G_CPU1_SB_DQ<7>")
	)
	(segment
		(start 193.088514 -225.36658)
		(end 194.786758 -225.36658)
		(width 0.20066)
		(layer "F.Cu")
		(net "M_G_CPU1_SB_DQ<6>")
	)
	(segment
		(start 198.427848 -225.3488)
		(end 198.662036 -225.114612)
		(width 0.20066)
		(layer "F.Cu")
		(net "M_G_CPU1_SB_DQ<6>")
	)
	(segment
		(start 128.556766 -239.575086)
		(end 128.556766 -239.0394)
		(width 0.20066)
		(layer "F.Cu")
		(net "M_G_CPU1_SB_DQ<6>")
	)
	(segment
		(start 195.218812 -225.798634)
		(end 195.510658 -225.798634)
		(width 0.20066)
		(layer "F.Cu")
		(net "M_G_CPU1_SB_DQ<6>")
	)
	(segment
		(start 197.542658 -225.803714)
		(end 198.223886 -225.803714)
		(width 0.20066)
		(layer "F.Cu")
		(net "M_G_CPU1_SB_DQ<6>")
	)
	(segment
		(start 198.662036 -225.114612)
		(end 199.046084 -225.114612)
		(width 0.20066)
		(layer "F.Cu")
		(net "M_G_CPU1_SB_DQ<6>")
	)
	(segment
		(start 128.556512 -239.57534)
		(end 128.556766 -239.575086)
		(width 0.20066)
		(layer "F.Cu")
		(net "M_G_CPU1_SB_DQ<6>")
	)
	(segment
		(start 198.223886 -225.803714)
		(end 198.427848 -225.599752)
		(width 0.20066)
		(layer "F.Cu")
		(net "M_G_CPU1_SB_DQ<6>")
	)
	(segment
		(start 198.427848 -225.599752)
		(end 198.427848 -225.3488)
		(width 0.20066)
		(layer "F.Cu")
		(net "M_G_CPU1_SB_DQ<6>")
	)
	(segment
		(start 195.515484 -225.798634)
		(end 195.522596 -225.791522)
		(width 0.1016)
		(layer "F.Cu")
		(net "M_G_CPU1_SB_DQ<6>")
	)
	(segment
		(start 195.510658 -225.798634)
		(end 195.515484 -225.798634)
		(width 0.101854)
		(layer "F.Cu")
		(net "M_G_CPU1_SB_DQ<6>")
	)
	(segment
		(start 199.046084 -225.114612)
		(end 199.298052 -225.36658)
		(width 0.20066)
		(layer "F.Cu")
		(net "M_G_CPU1_SB_DQ<6>")
	)
	(segment
		(start 194.786758 -225.36658)
		(end 195.218812 -225.798634)
		(width 0.20066)
		(layer "F.Cu")
		(net "M_G_CPU1_SB_DQ<6>")
	)
	(segment
		(start 197.530466 -225.791522)
		(end 197.542658 -225.803714)
		(width 0.1016)
		(layer "F.Cu")
		(net "M_G_CPU1_SB_DQ<6>")
	)
	(segment
		(start 191.983614 -225.36658)
		(end 193.088514 -225.36658)
		(width 0.20066)
		(layer "F.Cu")
		(net "M_G_CPU1_SB_DQ<6>")
	)
	(segment
		(start 199.298052 -225.36658)
		(end 200.632314 -225.36658)
		(width 0.20066)
		(layer "F.Cu")
		(net "M_G_CPU1_SB_DQ<6>")
	)
	(segment
		(start 195.522596 -225.791522)
		(end 197.530466 -225.791522)
		(width 0.1016)
		(layer "F.Cu")
		(net "M_G_CPU1_SB_DQ<6>")
	)
	(segment
		(start 177.931826 -230.042212)
		(end 176.226978 -230.042212)
		(width 0.18288)
		(layer "In6.Cu")
		(net "M_G_CPU1_SB_DQ<6>")
	)
	(segment
		(start 173.486572 -230.892096)
		(end 167.05961 -230.892096)
		(width 0.18288)
		(layer "In6.Cu")
		(net "M_G_CPU1_SB_DQ<6>")
	)
	(segment
		(start 129.22123 -238.545624)
		(end 129.109978 -238.611156)
		(width 0.088646)
		(layer "In6.Cu")
		(net "M_G_CPU1_SB_DQ<6>")
	)
	(segment
		(start 191.561974 -224.94494)
		(end 189.917324 -224.94494)
		(width 0.18288)
		(layer "In6.Cu")
		(net "M_G_CPU1_SB_DQ<6>")
	)
	(segment
		(start 161.201354 -230.042212)
		(end 160.85693 -230.386636)
		(width 0.18288)
		(layer "In6.Cu")
		(net "M_G_CPU1_SB_DQ<6>")
	)
	(segment
		(start 180.515514 -228.618034)
		(end 180.256942 -228.618034)
		(width 0.18288)
		(layer "In6.Cu")
		(net "M_G_CPU1_SB_DQ<6>")
	)
	(segment
		(start 140.442696 -237.891574)
		(end 140.11783 -237.891574)
		(width 0.088646)
		(layer "In6.Cu")
		(net "M_G_CPU1_SB_DQ<6>")
	)
	(segment
		(start 156.002736 -230.64724)
		(end 155.819856 -230.83012)
		(width 0.18288)
		(layer "In6.Cu")
		(net "M_G_CPU1_SB_DQ<6>")
	)
	(segment
		(start 186.403742 -225.79203)
		(end 186.029346 -226.166426)
		(width 0.18288)
		(layer "In6.Cu")
		(net "M_G_CPU1_SB_DQ<6>")
	)
	(segment
		(start 181.131464 -228.253036)
		(end 181.131464 -228.511608)
		(width 0.18288)
		(layer "In6.Cu")
		(net "M_G_CPU1_SB_DQ<6>")
	)
	(segment
		(start 189.070234 -225.79203)
		(end 186.403742 -225.79203)
		(width 0.18288)
		(layer "In6.Cu")
		(net "M_G_CPU1_SB_DQ<6>")
	)
	(segment
		(start 139.443206 -238.566198)
		(end 139.237466 -238.566198)
		(width 0.088646)
		(layer "In6.Cu")
		(net "M_G_CPU1_SB_DQ<6>")
	)
	(segment
		(start 159.04464 -230.042212)
		(end 158.51124 -230.575612)
		(width 0.18288)
		(layer "In6.Cu")
		(net "M_G_CPU1_SB_DQ<6>")
	)
	(segment
		(start 155.636976 -231.230932)
		(end 155.309316 -231.230932)
		(width 0.18288)
		(layer "In6.Cu")
		(net "M_G_CPU1_SB_DQ<6>")
	)
	(segment
		(start 158.210504 -230.891588)
		(end 157.438344 -230.891588)
		(width 0.18288)
		(layer "In6.Cu")
		(net "M_G_CPU1_SB_DQ<6>")
	)
	(segment
		(start 155.819856 -231.048052)
		(end 155.636976 -231.230932)
		(width 0.18288)
		(layer "In6.Cu")
		(net "M_G_CPU1_SB_DQ<6>")
	)
	(segment
		(start 158.51124 -230.590852)
		(end 158.210504 -230.891588)
		(width 0.18288)
		(layer "In6.Cu")
		(net "M_G_CPU1_SB_DQ<6>")
	)
	(segment
		(start 166.48176 -230.314246)
		(end 165.028626 -230.314246)
		(width 0.18288)
		(layer "In6.Cu")
		(net "M_G_CPU1_SB_DQ<6>")
	)
	(segment
		(start 133.912864 -238.549942)
		(end 133.910324 -238.551466)
		(width 0.088646)
		(layer "In6.Cu")
		(net "M_G_CPU1_SB_DQ<6>")
	)
	(segment
		(start 154.943556 -230.64724)
		(end 154.615896 -230.64724)
		(width 0.18288)
		(layer "In6.Cu")
		(net "M_G_CPU1_SB_DQ<6>")
	)
	(segment
		(start 181.005988 -228.12756)
		(end 181.131464 -228.253036)
		(width 0.18288)
		(layer "In6.Cu")
		(net "M_G_CPU1_SB_DQ<6>")
	)
	(segment
		(start 185.589418 -226.166426)
		(end 185.081418 -226.674426)
		(width 0.18288)
		(layer "In6.Cu")
		(net "M_G_CPU1_SB_DQ<6>")
	)
	(segment
		(start 132.033264 -238.549942)
		(end 132.028692 -238.552736)
		(width 0.088646)
		(layer "In6.Cu")
		(net "M_G_CPU1_SB_DQ<6>")
	)
	(segment
		(start 183.79186 -226.674426)
		(end 182.85206 -227.614226)
		(width 0.18288)
		(layer "In6.Cu")
		(net "M_G_CPU1_SB_DQ<6>")
	)
	(segment
		(start 182.85206 -227.614226)
		(end 181.26075 -227.614226)
		(width 0.18288)
		(layer "In6.Cu")
		(net "M_G_CPU1_SB_DQ<6>")
	)
	(segment
		(start 160.85693 -230.386636)
		(end 160.507934 -230.386636)
		(width 0.18288)
		(layer "In6.Cu")
		(net "M_G_CPU1_SB_DQ<6>")
	)
	(segment
		(start 178.45405 -229.519988)
		(end 177.931826 -230.042212)
		(width 0.18288)
		(layer "In6.Cu")
		(net "M_G_CPU1_SB_DQ<6>")
	)
	(segment
		(start 158.51124 -230.575612)
		(end 158.51124 -230.590852)
		(width 0.18288)
		(layer "In6.Cu")
		(net "M_G_CPU1_SB_DQ<6>")
	)
	(segment
		(start 132.04063 -238.545624)
		(end 132.033264 -238.549942)
		(width 0.088646)
		(layer "In6.Cu")
		(net "M_G_CPU1_SB_DQ<6>")
	)
	(segment
		(start 140.11783 -237.891574)
		(end 139.443206 -238.566198)
		(width 0.088646)
		(layer "In6.Cu")
		(net "M_G_CPU1_SB_DQ<6>")
	)
	(segment
		(start 163.5887 -230.042212)
		(end 161.201354 -230.042212)
		(width 0.18288)
		(layer "In6.Cu")
		(net "M_G_CPU1_SB_DQ<6>")
	)
	(segment
		(start 163.71443 -229.916482)
		(end 163.5887 -230.042212)
		(width 0.18288)
		(layer "In6.Cu")
		(net "M_G_CPU1_SB_DQ<6>")
	)
	(segment
		(start 181.131464 -228.511608)
		(end 180.899562 -228.74351)
		(width 0.18288)
		(layer "In6.Cu")
		(net "M_G_CPU1_SB_DQ<6>")
	)
	(segment
		(start 175.883824 -230.385366)
		(end 175.533558 -230.385366)
		(width 0.18288)
		(layer "In6.Cu")
		(net "M_G_CPU1_SB_DQ<6>")
	)
	(segment
		(start 191.983614 -225.36658)
		(end 191.561974 -224.94494)
		(width 0.18288)
		(layer "In6.Cu")
		(net "M_G_CPU1_SB_DQ<6>")
	)
	(segment
		(start 160.507934 -230.386636)
		(end 160.16351 -230.042212)
		(width 0.18288)
		(layer "In6.Cu")
		(net "M_G_CPU1_SB_DQ<6>")
	)
	(segment
		(start 180.256942 -228.618034)
		(end 179.354988 -229.519988)
		(width 0.18288)
		(layer "In6.Cu")
		(net "M_G_CPU1_SB_DQ<6>")
	)
	(segment
		(start 153.556716 -230.64724)
		(end 152.565862 -230.64724)
		(width 0.18288)
		(layer "In6.Cu")
		(net "M_G_CPU1_SB_DQ<6>")
	)
	(segment
		(start 154.433016 -230.83012)
		(end 154.433016 -231.048052)
		(width 0.18288)
		(layer "In6.Cu")
		(net "M_G_CPU1_SB_DQ<6>")
	)
	(segment
		(start 167.05961 -230.892096)
		(end 166.48176 -230.314246)
		(width 0.18288)
		(layer "In6.Cu")
		(net "M_G_CPU1_SB_DQ<6>")
	)
	(segment
		(start 155.126436 -230.83012)
		(end 154.943556 -230.64724)
		(width 0.18288)
		(layer "In6.Cu")
		(net "M_G_CPU1_SB_DQ<6>")
	)
	(segment
		(start 165.028626 -230.314246)
		(end 164.630862 -229.916482)
		(width 0.18288)
		(layer "In6.Cu")
		(net "M_G_CPU1_SB_DQ<6>")
	)
	(segment
		(start 155.126436 -231.048052)
		(end 155.126436 -230.83012)
		(width 0.18288)
		(layer "In6.Cu")
		(net "M_G_CPU1_SB_DQ<6>")
	)
	(segment
		(start 157.193996 -230.64724)
		(end 156.002736 -230.64724)
		(width 0.18288)
		(layer "In6.Cu")
		(net "M_G_CPU1_SB_DQ<6>")
	)
	(segment
		(start 131.10083 -238.545624)
		(end 131.093464 -238.549942)
		(width 0.088646)
		(layer "In6.Cu")
		(net "M_G_CPU1_SB_DQ<6>")
	)
	(segment
		(start 157.438344 -230.891588)
		(end 157.193996 -230.64724)
		(width 0.18288)
		(layer "In6.Cu")
		(net "M_G_CPU1_SB_DQ<6>")
	)
	(segment
		(start 189.917324 -224.94494)
		(end 189.070234 -225.79203)
		(width 0.18288)
		(layer "In6.Cu")
		(net "M_G_CPU1_SB_DQ<6>")
	)
	(segment
		(start 132.98043 -238.545624)
		(end 132.973064 -238.549942)
		(width 0.088646)
		(layer "In6.Cu")
		(net "M_G_CPU1_SB_DQ<6>")
	)
	(segment
		(start 152.565862 -230.64724)
		(end 145.321528 -237.891574)
		(width 0.18288)
		(layer "In6.Cu")
		(net "M_G_CPU1_SB_DQ<6>")
	)
	(segment
		(start 181.005988 -227.868988)
		(end 181.005988 -228.12756)
		(width 0.18288)
		(layer "In6.Cu")
		(net "M_G_CPU1_SB_DQ<6>")
	)
	(segment
		(start 180.899562 -228.74351)
		(end 180.64099 -228.74351)
		(width 0.18288)
		(layer "In6.Cu")
		(net "M_G_CPU1_SB_DQ<6>")
	)
	(segment
		(start 128.55702 -239.039146)
		(end 128.556766 -239.0394)
		(width 0.088646)
		(layer "In6.Cu")
		(net "M_G_CPU1_SB_DQ<6>")
	)
	(segment
		(start 175.533558 -230.385366)
		(end 175.190404 -230.042212)
		(width 0.18288)
		(layer "In6.Cu")
		(net "M_G_CPU1_SB_DQ<6>")
	)
	(segment
		(start 180.64099 -228.74351)
		(end 180.515514 -228.618034)
		(width 0.18288)
		(layer "In6.Cu")
		(net "M_G_CPU1_SB_DQ<6>")
	)
	(segment
		(start 176.226978 -230.042212)
		(end 175.883824 -230.385366)
		(width 0.18288)
		(layer "In6.Cu")
		(net "M_G_CPU1_SB_DQ<6>")
	)
	(segment
		(start 132.973064 -238.549942)
		(end 132.968492 -238.552736)
		(width 0.088646)
		(layer "In6.Cu")
		(net "M_G_CPU1_SB_DQ<6>")
	)
	(segment
		(start 175.190404 -230.042212)
		(end 174.336456 -230.042212)
		(width 0.18288)
		(layer "In6.Cu")
		(net "M_G_CPU1_SB_DQ<6>")
	)
	(segment
		(start 186.029346 -226.166426)
		(end 185.589418 -226.166426)
		(width 0.18288)
		(layer "In6.Cu")
		(net "M_G_CPU1_SB_DQ<6>")
	)
	(segment
		(start 153.739596 -231.048052)
		(end 153.739596 -230.83012)
		(width 0.18288)
		(layer "In6.Cu")
		(net "M_G_CPU1_SB_DQ<6>")
	)
	(segment
		(start 131.093464 -238.549942)
		(end 131.088892 -238.552736)
		(width 0.088646)
		(layer "In6.Cu")
		(net "M_G_CPU1_SB_DQ<6>")
	)
	(segment
		(start 155.819856 -230.83012)
		(end 155.819856 -231.048052)
		(width 0.18288)
		(layer "In6.Cu")
		(net "M_G_CPU1_SB_DQ<6>")
	)
	(segment
		(start 130.16103 -238.545624)
		(end 130.153664 -238.549942)
		(width 0.088646)
		(layer "In6.Cu")
		(net "M_G_CPU1_SB_DQ<6>")
	)
	(segment
		(start 153.739596 -230.83012)
		(end 153.556716 -230.64724)
		(width 0.18288)
		(layer "In6.Cu")
		(net "M_G_CPU1_SB_DQ<6>")
	)
	(segment
		(start 179.354988 -229.519988)
		(end 178.45405 -229.519988)
		(width 0.18288)
		(layer "In6.Cu")
		(net "M_G_CPU1_SB_DQ<6>")
	)
	(segment
		(start 174.336456 -230.042212)
		(end 173.486572 -230.892096)
		(width 0.18288)
		(layer "In6.Cu")
		(net "M_G_CPU1_SB_DQ<6>")
	)
	(segment
		(start 153.922476 -231.230932)
		(end 153.739596 -231.048052)
		(width 0.18288)
		(layer "In6.Cu")
		(net "M_G_CPU1_SB_DQ<6>")
	)
	(segment
		(start 154.433016 -231.048052)
		(end 154.250136 -231.230932)
		(width 0.18288)
		(layer "In6.Cu")
		(net "M_G_CPU1_SB_DQ<6>")
	)
	(segment
		(start 130.153664 -238.549942)
		(end 130.149092 -238.552736)
		(width 0.088646)
		(layer "In6.Cu")
		(net "M_G_CPU1_SB_DQ<6>")
	)
	(segment
		(start 160.16351 -230.042212)
		(end 159.04464 -230.042212)
		(width 0.18288)
		(layer "In6.Cu")
		(net "M_G_CPU1_SB_DQ<6>")
	)
	(segment
		(start 154.615896 -230.64724)
		(end 154.433016 -230.83012)
		(width 0.18288)
		(layer "In6.Cu")
		(net "M_G_CPU1_SB_DQ<6>")
	)
	(segment
		(start 145.321528 -237.891574)
		(end 140.442696 -237.891574)
		(width 0.18288)
		(layer "In6.Cu")
		(net "M_G_CPU1_SB_DQ<6>")
	)
	(segment
		(start 134.478268 -238.549942)
		(end 134.478014 -238.549942)
		(width 0.088646)
		(layer "In6.Cu")
		(net "M_G_CPU1_SB_DQ<6>")
	)
	(segment
		(start 154.250136 -231.230932)
		(end 153.922476 -231.230932)
		(width 0.18288)
		(layer "In6.Cu")
		(net "M_G_CPU1_SB_DQ<6>")
	)
	(segment
		(start 181.26075 -227.614226)
		(end 181.005988 -227.868988)
		(width 0.18288)
		(layer "In6.Cu")
		(net "M_G_CPU1_SB_DQ<6>")
	)
	(segment
		(start 185.081418 -226.674426)
		(end 183.79186 -226.674426)
		(width 0.18288)
		(layer "In6.Cu")
		(net "M_G_CPU1_SB_DQ<6>")
	)
	(segment
		(start 155.309316 -231.230932)
		(end 155.126436 -231.048052)
		(width 0.18288)
		(layer "In6.Cu")
		(net "M_G_CPU1_SB_DQ<6>")
	)
	(segment
		(start 164.630862 -229.916482)
		(end 163.71443 -229.916482)
		(width 0.18288)
		(layer "In6.Cu")
		(net "M_G_CPU1_SB_DQ<6>")
	)
	(arc
		(start 132.968492 -238.552736)
		(mid 132.783078 -238.600248)
		(end 132.598414 -238.549942)
		(width 0.088646)
		(layer "In6.Cu")
		(net "M_G_CPU1_SB_DQ<6>")
	)
	(arc
		(start 131.088892 -238.552736)
		(mid 130.903478 -238.600248)
		(end 130.718814 -238.549942)
		(width 0.088646)
		(layer "In6.Cu")
		(net "M_G_CPU1_SB_DQ<6>")
	)
	(arc
		(start 137.672064 -238.549942)
		(mid 137.484866 -238.600085)
		(end 137.297668 -238.549942)
		(width 0.088646)
		(layer "In6.Cu")
		(net "M_G_CPU1_SB_DQ<6>")
	)
	(arc
		(start 133.538214 -238.549942)
		(mid 133.259891 -238.474183)
		(end 132.98043 -238.545624)
		(width 0.088646)
		(layer "In6.Cu")
		(net "M_G_CPU1_SB_DQ<6>")
	)
	(arc
		(start 139.237466 -238.566198)
		(mid 139.206284 -238.562072)
		(end 139.177268 -238.549942)
		(width 0.088646)
		(layer "In6.Cu")
		(net "M_G_CPU1_SB_DQ<6>")
	)
	(arc
		(start 130.149092 -238.552736)
		(mid 129.963678 -238.600248)
		(end 129.779014 -238.549942)
		(width 0.088646)
		(layer "In6.Cu")
		(net "M_G_CPU1_SB_DQ<6>")
	)
	(arc
		(start 136.357868 -238.549942)
		(mid 136.075166 -238.474166)
		(end 135.792464 -238.549942)
		(width 0.088646)
		(layer "In6.Cu")
		(net "M_G_CPU1_SB_DQ<6>")
	)
	(arc
		(start 129.779014 -238.549942)
		(mid 129.500691 -238.474183)
		(end 129.22123 -238.545624)
		(width 0.088646)
		(layer "In6.Cu")
		(net "M_G_CPU1_SB_DQ<6>")
	)
	(arc
		(start 135.792464 -238.549942)
		(mid 135.605266 -238.600085)
		(end 135.418068 -238.549942)
		(width 0.088646)
		(layer "In6.Cu")
		(net "M_G_CPU1_SB_DQ<6>")
	)
	(arc
		(start 131.658614 -238.549942)
		(mid 131.380291 -238.474183)
		(end 131.10083 -238.545624)
		(width 0.088646)
		(layer "In6.Cu")
		(net "M_G_CPU1_SB_DQ<6>")
	)
	(arc
		(start 132.028692 -238.552736)
		(mid 131.843278 -238.600248)
		(end 131.658614 -238.549942)
		(width 0.088646)
		(layer "In6.Cu")
		(net "M_G_CPU1_SB_DQ<6>")
	)
	(arc
		(start 132.598414 -238.549942)
		(mid 132.320091 -238.474183)
		(end 132.04063 -238.545624)
		(width 0.088646)
		(layer "In6.Cu")
		(net "M_G_CPU1_SB_DQ<6>")
	)
	(arc
		(start 134.478014 -238.549942)
		(mid 134.195456 -238.474293)
		(end 133.912864 -238.549942)
		(width 0.088646)
		(layer "In6.Cu")
		(net "M_G_CPU1_SB_DQ<6>")
	)
	(arc
		(start 139.177268 -238.549942)
		(mid 138.894566 -238.474166)
		(end 138.611864 -238.549942)
		(width 0.088646)
		(layer "In6.Cu")
		(net "M_G_CPU1_SB_DQ<6>")
	)
	(arc
		(start 138.237468 -238.549942)
		(mid 137.954766 -238.474166)
		(end 137.672064 -238.549942)
		(width 0.088646)
		(layer "In6.Cu")
		(net "M_G_CPU1_SB_DQ<6>")
	)
	(arc
		(start 138.611864 -238.549942)
		(mid 138.424666 -238.600085)
		(end 138.237468 -238.549942)
		(width 0.088646)
		(layer "In6.Cu")
		(net "M_G_CPU1_SB_DQ<6>")
	)
	(arc
		(start 129.109978 -238.611156)
		(mid 128.819954 -238.80765)
		(end 128.55702 -239.039146)
		(width 0.088646)
		(layer "In6.Cu")
		(net "M_G_CPU1_SB_DQ<6>")
	)
	(arc
		(start 130.718814 -238.549942)
		(mid 130.440491 -238.474183)
		(end 130.16103 -238.545624)
		(width 0.088646)
		(layer "In6.Cu")
		(net "M_G_CPU1_SB_DQ<6>")
	)
	(arc
		(start 133.910324 -238.551466)
		(mid 133.724075 -238.600144)
		(end 133.538214 -238.549942)
		(width 0.088646)
		(layer "In6.Cu")
		(net "M_G_CPU1_SB_DQ<6>")
	)
	(arc
		(start 136.732264 -238.549942)
		(mid 136.545066 -238.600085)
		(end 136.357868 -238.549942)
		(width 0.088646)
		(layer "In6.Cu")
		(net "M_G_CPU1_SB_DQ<6>")
	)
	(arc
		(start 134.852664 -238.549942)
		(mid 134.665466 -238.600085)
		(end 134.478268 -238.549942)
		(width 0.088646)
		(layer "In6.Cu")
		(net "M_G_CPU1_SB_DQ<6>")
	)
	(arc
		(start 135.418068 -238.549942)
		(mid 135.135366 -238.474166)
		(end 134.852664 -238.549942)
		(width 0.088646)
		(layer "In6.Cu")
		(net "M_G_CPU1_SB_DQ<6>")
	)
	(arc
		(start 137.297668 -238.549942)
		(mid 137.014966 -238.474166)
		(end 136.732264 -238.549942)
		(width 0.088646)
		(layer "In6.Cu")
		(net "M_G_CPU1_SB_DQ<6>")
	)
	(segment
		(start 190.75781 -224.765362)
		(end 190.509144 -224.516696)
		(width 0.20066)
		(layer "F.Cu")
		(net "M_G_CPU1_SB_DQ<5>")
	)
	(segment
		(start 194.508882 -224.085404)
		(end 194.098926 -224.085404)
		(width 0.20066)
		(layer "F.Cu")
		(net "M_G_CPU1_SB_DQ<5>")
	)
	(segment
		(start 196.531992 -224.51695)
		(end 194.940428 -224.51695)
		(width 0.20066)
		(layer "F.Cu")
		(net "M_G_CPU1_SB_DQ<5>")
	)
	(segment
		(start 127.146812 -238.76127)
		(end 127.146812 -238.225584)
		(width 0.20066)
		(layer "F.Cu")
		(net "M_G_CPU1_SB_DQ<5>")
	)
	(segment
		(start 190.509144 -224.516696)
		(end 188.988446 -224.516696)
		(width 0.20066)
		(layer "F.Cu")
		(net "M_G_CPU1_SB_DQ<5>")
	)
	(segment
		(start 194.940428 -224.51695)
		(end 194.508882 -224.085404)
		(width 0.20066)
		(layer "F.Cu")
		(net "M_G_CPU1_SB_DQ<5>")
	)
	(segment
		(start 194.092576 -224.091754)
		(end 191.903858 -224.091754)
		(width 0.1016)
		(layer "F.Cu")
		(net "M_G_CPU1_SB_DQ<5>")
	)
	(segment
		(start 194.098926 -224.085404)
		(end 194.092576 -224.091754)
		(width 0.1016)
		(layer "F.Cu")
		(net "M_G_CPU1_SB_DQ<5>")
	)
	(segment
		(start 191.233044 -224.765362)
		(end 190.75781 -224.765362)
		(width 0.20066)
		(layer "F.Cu")
		(net "M_G_CPU1_SB_DQ<5>")
	)
	(segment
		(start 191.903858 -224.091754)
		(end 191.883792 -224.091754)
		(width 0.101854)
		(layer "F.Cu")
		(net "M_G_CPU1_SB_DQ<5>")
	)
	(segment
		(start 191.421004 -224.209864)
		(end 191.421004 -224.577402)
		(width 0.20066)
		(layer "F.Cu")
		(net "M_G_CPU1_SB_DQ<5>")
	)
	(segment
		(start 191.883792 -224.091754)
		(end 191.539114 -224.091754)
		(width 0.20066)
		(layer "F.Cu")
		(net "M_G_CPU1_SB_DQ<5>")
	)
	(segment
		(start 191.421004 -224.577402)
		(end 191.233044 -224.765362)
		(width 0.20066)
		(layer "F.Cu")
		(net "M_G_CPU1_SB_DQ<5>")
	)
	(segment
		(start 127.147066 -238.761524)
		(end 127.146812 -238.76127)
		(width 0.20066)
		(layer "F.Cu")
		(net "M_G_CPU1_SB_DQ<5>")
	)
	(segment
		(start 188.988446 -224.516696)
		(end 187.883546 -224.516696)
		(width 0.20066)
		(layer "F.Cu")
		(net "M_G_CPU1_SB_DQ<5>")
	)
	(segment
		(start 191.539114 -224.091754)
		(end 191.421004 -224.209864)
		(width 0.20066)
		(layer "F.Cu")
		(net "M_G_CPU1_SB_DQ<5>")
	)
	(segment
		(start 196.532246 -224.516696)
		(end 196.531992 -224.51695)
		(width 0.20066)
		(layer "F.Cu")
		(net "M_G_CPU1_SB_DQ<5>")
	)
	(segment
		(start 171.06138 -229.874826)
		(end 170.8785 -230.057706)
		(width 0.18288)
		(layer "In6.Cu")
		(net "M_G_CPU1_SB_DQ<5>")
	)
	(segment
		(start 154.048968 -229.858824)
		(end 153.866088 -230.041704)
		(width 0.18288)
		(layer "In6.Cu")
		(net "M_G_CPU1_SB_DQ<5>")
	)
	(segment
		(start 130.159506 -237.904528)
		(end 130.153664 -237.900972)
		(width 0.088646)
		(layer "In6.Cu")
		(net "M_G_CPU1_SB_DQ<5>")
	)
	(segment
		(start 168.77411 -229.874826)
		(end 168.449244 -230.199692)
		(width 0.18288)
		(layer "In6.Cu")
		(net "M_G_CPU1_SB_DQ<5>")
	)
	(segment
		(start 128.652016 -238.222028)
		(end 128.652016 -238.225584)
		(width 0.088646)
		(layer "In6.Cu")
		(net "M_G_CPU1_SB_DQ<5>")
	)
	(segment
		(start 175.772318 -229.480872)
		(end 175.48352 -229.192074)
		(width 0.18288)
		(layer "In6.Cu")
		(net "M_G_CPU1_SB_DQ<5>")
	)
	(segment
		(start 187.30468 -225.070162)
		(end 186.06389 -225.070162)
		(width 0.18288)
		(layer "In6.Cu")
		(net "M_G_CPU1_SB_DQ<5>")
	)
	(segment
		(start 130.153664 -237.900972)
		(end 130.147822 -237.89767)
		(width 0.088646)
		(layer "In6.Cu")
		(net "M_G_CPU1_SB_DQ<5>")
	)
	(segment
		(start 165.147244 -228.633528)
		(end 164.375592 -229.40518)
		(width 0.18288)
		(layer "In6.Cu")
		(net "M_G_CPU1_SB_DQ<5>")
	)
	(segment
		(start 140.003022 -237.374684)
		(end 139.566396 -237.81131)
		(width 0.088646)
		(layer "In6.Cu")
		(net "M_G_CPU1_SB_DQ<5>")
	)
	(segment
		(start 166.835582 -229.606348)
		(end 167.335962 -229.105968)
		(width 0.18288)
		(layer "In6.Cu")
		(net "M_G_CPU1_SB_DQ<5>")
	)
	(segment
		(start 133.912864 -237.900972)
		(end 133.908546 -237.898432)
		(width 0.088646)
		(layer "In6.Cu")
		(net "M_G_CPU1_SB_DQ<5>")
	)
	(segment
		(start 161.99993 -229.192074)
		(end 159.031178 -229.192074)
		(width 0.18288)
		(layer "In6.Cu")
		(net "M_G_CPU1_SB_DQ<5>")
	)
	(segment
		(start 155.435808 -229.858824)
		(end 155.252928 -230.041704)
		(width 0.18288)
		(layer "In6.Cu")
		(net "M_G_CPU1_SB_DQ<5>")
	)
	(segment
		(start 170.18508 -230.210106)
		(end 170.18508 -230.057706)
		(width 0.18288)
		(layer "In6.Cu")
		(net "M_G_CPU1_SB_DQ<5>")
	)
	(segment
		(start 164.375592 -229.40518)
		(end 163.623752 -229.40518)
		(width 0.18288)
		(layer "In6.Cu")
		(net "M_G_CPU1_SB_DQ<5>")
	)
	(segment
		(start 140.442696 -237.374684)
		(end 140.003022 -237.374684)
		(width 0.088646)
		(layer "In6.Cu")
		(net "M_G_CPU1_SB_DQ<5>")
	)
	(segment
		(start 163.463732 -229.24516)
		(end 163.463732 -229.005892)
		(width 0.18288)
		(layer "In6.Cu")
		(net "M_G_CPU1_SB_DQ<5>")
	)
	(segment
		(start 154.559508 -229.52202)
		(end 154.231848 -229.52202)
		(width 0.18288)
		(layer "In6.Cu")
		(net "M_G_CPU1_SB_DQ<5>")
	)
	(segment
		(start 166.345108 -229.115874)
		(end 166.119048 -229.115874)
		(width 0.18288)
		(layer "In6.Cu")
		(net "M_G_CPU1_SB_DQ<5>")
	)
	(segment
		(start 167.202866 -230.199692)
		(end 166.835582 -229.832408)
		(width 0.18288)
		(layer "In6.Cu")
		(net "M_G_CPU1_SB_DQ<5>")
	)
	(segment
		(start 145.107406 -237.374684)
		(end 140.442696 -237.374684)
		(width 0.18288)
		(layer "In6.Cu")
		(net "M_G_CPU1_SB_DQ<5>")
	)
	(segment
		(start 162.213036 -229.40518)
		(end 161.99993 -229.192074)
		(width 0.18288)
		(layer "In6.Cu")
		(net "M_G_CPU1_SB_DQ<5>")
	)
	(segment
		(start 155.252928 -230.041704)
		(end 154.925268 -230.041704)
		(width 0.18288)
		(layer "In6.Cu")
		(net "M_G_CPU1_SB_DQ<5>")
	)
	(segment
		(start 153.866088 -230.041704)
		(end 152.440386 -230.041704)
		(width 0.18288)
		(layer "In6.Cu")
		(net "M_G_CPU1_SB_DQ<5>")
	)
	(segment
		(start 179.29606 -227.880672)
		(end 177.984658 -229.192074)
		(width 0.18288)
		(layer "In6.Cu")
		(net "M_G_CPU1_SB_DQ<5>")
	)
	(segment
		(start 131.093464 -237.900972)
		(end 131.087622 -237.89767)
		(width 0.088646)
		(layer "In6.Cu")
		(net "M_G_CPU1_SB_DQ<5>")
	)
	(segment
		(start 163.303712 -228.845872)
		(end 162.930332 -228.845872)
		(width 0.18288)
		(layer "In6.Cu")
		(net "M_G_CPU1_SB_DQ<5>")
	)
	(segment
		(start 167.335962 -229.105968)
		(end 167.335962 -228.879908)
		(width 0.18288)
		(layer "In6.Cu")
		(net "M_G_CPU1_SB_DQ<5>")
	)
	(segment
		(start 132.039106 -237.904528)
		(end 132.033264 -237.900972)
		(width 0.088646)
		(layer "In6.Cu")
		(net "M_G_CPU1_SB_DQ<5>")
	)
	(segment
		(start 152.440386 -230.041704)
		(end 145.107406 -237.374684)
		(width 0.18288)
		(layer "In6.Cu")
		(net "M_G_CPU1_SB_DQ<5>")
	)
	(segment
		(start 181.678326 -226.439222)
		(end 180.236876 -227.880672)
		(width 0.18288)
		(layer "In6.Cu")
		(net "M_G_CPU1_SB_DQ<5>")
	)
	(segment
		(start 176.465738 -229.192074)
		(end 176.17694 -229.480872)
		(width 0.18288)
		(layer "In6.Cu")
		(net "M_G_CPU1_SB_DQ<5>")
	)
	(segment
		(start 162.610292 -229.40518)
		(end 162.213036 -229.40518)
		(width 0.18288)
		(layer "In6.Cu")
		(net "M_G_CPU1_SB_DQ<5>")
	)
	(segment
		(start 166.845488 -228.615494)
		(end 166.345108 -229.115874)
		(width 0.18288)
		(layer "In6.Cu")
		(net "M_G_CPU1_SB_DQ<5>")
	)
	(segment
		(start 175.48352 -229.192074)
		(end 174.398178 -229.192074)
		(width 0.18288)
		(layer "In6.Cu")
		(net "M_G_CPU1_SB_DQ<5>")
	)
	(segment
		(start 177.984658 -229.192074)
		(end 176.465738 -229.192074)
		(width 0.18288)
		(layer "In6.Cu")
		(net "M_G_CPU1_SB_DQ<5>")
	)
	(segment
		(start 185.450226 -225.683826)
		(end 183.773826 -225.683826)
		(width 0.18288)
		(layer "In6.Cu")
		(net "M_G_CPU1_SB_DQ<5>")
	)
	(segment
		(start 132.978906 -237.904528)
		(end 132.973064 -237.900972)
		(width 0.088646)
		(layer "In6.Cu")
		(net "M_G_CPU1_SB_DQ<5>")
	)
	(segment
		(start 176.17694 -229.480872)
		(end 175.772318 -229.480872)
		(width 0.18288)
		(layer "In6.Cu")
		(net "M_G_CPU1_SB_DQ<5>")
	)
	(segment
		(start 154.925268 -230.041704)
		(end 154.742388 -229.858824)
		(width 0.18288)
		(layer "In6.Cu")
		(net "M_G_CPU1_SB_DQ<5>")
	)
	(segment
		(start 186.06389 -225.070162)
		(end 185.450226 -225.683826)
		(width 0.18288)
		(layer "In6.Cu")
		(net "M_G_CPU1_SB_DQ<5>")
	)
	(segment
		(start 167.335962 -228.879908)
		(end 167.071548 -228.615494)
		(width 0.18288)
		(layer "In6.Cu")
		(net "M_G_CPU1_SB_DQ<5>")
	)
	(segment
		(start 128.358138 -238.673132)
		(end 128.047242 -238.673132)
		(width 0.088646)
		(layer "In6.Cu")
		(net "M_G_CPU1_SB_DQ<5>")
	)
	(segment
		(start 173.548294 -230.041958)
		(end 171.977558 -230.041958)
		(width 0.18288)
		(layer "In6.Cu")
		(net "M_G_CPU1_SB_DQ<5>")
	)
	(segment
		(start 154.742388 -229.858824)
		(end 154.742388 -229.7049)
		(width 0.18288)
		(layer "In6.Cu")
		(net "M_G_CPU1_SB_DQ<5>")
	)
	(segment
		(start 156.312108 -230.041704)
		(end 156.129228 -229.858824)
		(width 0.18288)
		(layer "In6.Cu")
		(net "M_G_CPU1_SB_DQ<5>")
	)
	(segment
		(start 162.770312 -229.005892)
		(end 162.770312 -229.24516)
		(width 0.18288)
		(layer "In6.Cu")
		(net "M_G_CPU1_SB_DQ<5>")
	)
	(segment
		(start 170.8785 -230.057706)
		(end 170.8785 -230.210106)
		(width 0.18288)
		(layer "In6.Cu")
		(net "M_G_CPU1_SB_DQ<5>")
	)
	(segment
		(start 155.946348 -229.52202)
		(end 155.618688 -229.52202)
		(width 0.18288)
		(layer "In6.Cu")
		(net "M_G_CPU1_SB_DQ<5>")
	)
	(segment
		(start 170.69562 -230.392986)
		(end 170.36796 -230.392986)
		(width 0.18288)
		(layer "In6.Cu")
		(net "M_G_CPU1_SB_DQ<5>")
	)
	(segment
		(start 168.449244 -230.199692)
		(end 167.202866 -230.199692)
		(width 0.18288)
		(layer "In6.Cu")
		(net "M_G_CPU1_SB_DQ<5>")
	)
	(segment
		(start 183.01843 -226.439222)
		(end 181.678326 -226.439222)
		(width 0.18288)
		(layer "In6.Cu")
		(net "M_G_CPU1_SB_DQ<5>")
	)
	(segment
		(start 170.0022 -229.874826)
		(end 168.77411 -229.874826)
		(width 0.18288)
		(layer "In6.Cu")
		(net "M_G_CPU1_SB_DQ<5>")
	)
	(segment
		(start 139.566396 -237.81131)
		(end 139.294362 -237.81131)
		(width 0.088646)
		(layer "In6.Cu")
		(net "M_G_CPU1_SB_DQ<5>")
	)
	(segment
		(start 170.18508 -230.057706)
		(end 170.0022 -229.874826)
		(width 0.18288)
		(layer "In6.Cu")
		(net "M_G_CPU1_SB_DQ<5>")
	)
	(segment
		(start 163.623752 -229.40518)
		(end 163.463732 -229.24516)
		(width 0.18288)
		(layer "In6.Cu")
		(net "M_G_CPU1_SB_DQ<5>")
	)
	(segment
		(start 166.119048 -229.115874)
		(end 165.636702 -228.633528)
		(width 0.18288)
		(layer "In6.Cu")
		(net "M_G_CPU1_SB_DQ<5>")
	)
	(segment
		(start 158.181548 -230.041704)
		(end 156.312108 -230.041704)
		(width 0.18288)
		(layer "In6.Cu")
		(net "M_G_CPU1_SB_DQ<5>")
	)
	(segment
		(start 167.071548 -228.615494)
		(end 166.845488 -228.615494)
		(width 0.18288)
		(layer "In6.Cu")
		(net "M_G_CPU1_SB_DQ<5>")
	)
	(segment
		(start 162.770312 -229.24516)
		(end 162.610292 -229.40518)
		(width 0.18288)
		(layer "In6.Cu")
		(net "M_G_CPU1_SB_DQ<5>")
	)
	(segment
		(start 170.36796 -230.392986)
		(end 170.18508 -230.210106)
		(width 0.18288)
		(layer "In6.Cu")
		(net "M_G_CPU1_SB_DQ<5>")
	)
	(segment
		(start 165.636702 -228.633528)
		(end 165.147244 -228.633528)
		(width 0.18288)
		(layer "In6.Cu")
		(net "M_G_CPU1_SB_DQ<5>")
	)
	(segment
		(start 156.129228 -229.858824)
		(end 156.129228 -229.7049)
		(width 0.18288)
		(layer "In6.Cu")
		(net "M_G_CPU1_SB_DQ<5>")
	)
	(segment
		(start 154.231848 -229.52202)
		(end 154.048968 -229.7049)
		(width 0.18288)
		(layer "In6.Cu")
		(net "M_G_CPU1_SB_DQ<5>")
	)
	(segment
		(start 180.236876 -227.880672)
		(end 179.29606 -227.880672)
		(width 0.18288)
		(layer "In6.Cu")
		(net "M_G_CPU1_SB_DQ<5>")
	)
	(segment
		(start 159.031178 -229.192074)
		(end 158.181548 -230.041704)
		(width 0.18288)
		(layer "In6.Cu")
		(net "M_G_CPU1_SB_DQ<5>")
	)
	(segment
		(start 129.213864 -237.900972)
		(end 129.208022 -237.89767)
		(width 0.088646)
		(layer "In6.Cu")
		(net "M_G_CPU1_SB_DQ<5>")
	)
	(segment
		(start 163.463732 -229.005892)
		(end 163.303712 -228.845872)
		(width 0.18288)
		(layer "In6.Cu")
		(net "M_G_CPU1_SB_DQ<5>")
	)
	(segment
		(start 183.773826 -225.683826)
		(end 183.01843 -226.439222)
		(width 0.18288)
		(layer "In6.Cu")
		(net "M_G_CPU1_SB_DQ<5>")
	)
	(segment
		(start 155.435808 -229.7049)
		(end 155.435808 -229.858824)
		(width 0.18288)
		(layer "In6.Cu")
		(net "M_G_CPU1_SB_DQ<5>")
	)
	(segment
		(start 187.858146 -224.516696)
		(end 187.30468 -225.070162)
		(width 0.18288)
		(layer "In6.Cu")
		(net "M_G_CPU1_SB_DQ<5>")
	)
	(segment
		(start 156.129228 -229.7049)
		(end 155.946348 -229.52202)
		(width 0.18288)
		(layer "In6.Cu")
		(net "M_G_CPU1_SB_DQ<5>")
	)
	(segment
		(start 187.883546 -224.516696)
		(end 187.858146 -224.516696)
		(width 0.18288)
		(layer "In6.Cu")
		(net "M_G_CPU1_SB_DQ<5>")
	)
	(segment
		(start 127.146812 -238.225838)
		(end 127.146812 -238.225584)
		(width 0.088646)
		(layer "In6.Cu")
		(net "M_G_CPU1_SB_DQ<5>")
	)
	(segment
		(start 166.835582 -229.832408)
		(end 166.835582 -229.606348)
		(width 0.18288)
		(layer "In6.Cu")
		(net "M_G_CPU1_SB_DQ<5>")
	)
	(segment
		(start 154.048968 -229.7049)
		(end 154.048968 -229.858824)
		(width 0.18288)
		(layer "In6.Cu")
		(net "M_G_CPU1_SB_DQ<5>")
	)
	(segment
		(start 162.930332 -228.845872)
		(end 162.770312 -229.005892)
		(width 0.18288)
		(layer "In6.Cu")
		(net "M_G_CPU1_SB_DQ<5>")
	)
	(segment
		(start 155.618688 -229.52202)
		(end 155.435808 -229.7049)
		(width 0.18288)
		(layer "In6.Cu")
		(net "M_G_CPU1_SB_DQ<5>")
	)
	(segment
		(start 134.478268 -237.901226)
		(end 134.478014 -237.900972)
		(width 0.088646)
		(layer "In6.Cu")
		(net "M_G_CPU1_SB_DQ<5>")
	)
	(segment
		(start 132.033264 -237.900972)
		(end 132.027422 -237.89767)
		(width 0.088646)
		(layer "In6.Cu")
		(net "M_G_CPU1_SB_DQ<5>")
	)
	(segment
		(start 132.973064 -237.900972)
		(end 132.967222 -237.89767)
		(width 0.088646)
		(layer "In6.Cu")
		(net "M_G_CPU1_SB_DQ<5>")
	)
	(segment
		(start 126.990602 -238.496602)
		(end 127.146812 -238.225838)
		(width 0.088646)
		(layer "In6.Cu")
		(net "M_G_CPU1_SB_DQ<5>")
	)
	(segment
		(start 171.977558 -230.041958)
		(end 171.810426 -229.874826)
		(width 0.18288)
		(layer "In6.Cu")
		(net "M_G_CPU1_SB_DQ<5>")
	)
	(segment
		(start 128.621028 -238.410242)
		(end 128.358138 -238.673132)
		(width 0.088646)
		(layer "In6.Cu")
		(net "M_G_CPU1_SB_DQ<5>")
	)
	(segment
		(start 154.742388 -229.7049)
		(end 154.559508 -229.52202)
		(width 0.18288)
		(layer "In6.Cu")
		(net "M_G_CPU1_SB_DQ<5>")
	)
	(segment
		(start 170.8785 -230.210106)
		(end 170.69562 -230.392986)
		(width 0.18288)
		(layer "In6.Cu")
		(net "M_G_CPU1_SB_DQ<5>")
	)
	(segment
		(start 127.34925 -238.541306)
		(end 127.329692 -238.552736)
		(width 0.088646)
		(layer "In6.Cu")
		(net "M_G_CPU1_SB_DQ<5>")
	)
	(segment
		(start 131.099306 -237.904528)
		(end 131.093464 -237.900972)
		(width 0.088646)
		(layer "In6.Cu")
		(net "M_G_CPU1_SB_DQ<5>")
	)
	(segment
		(start 174.398178 -229.192074)
		(end 173.548294 -230.041958)
		(width 0.18288)
		(layer "In6.Cu")
		(net "M_G_CPU1_SB_DQ<5>")
	)
	(segment
		(start 171.810426 -229.874826)
		(end 171.06138 -229.874826)
		(width 0.18288)
		(layer "In6.Cu")
		(net "M_G_CPU1_SB_DQ<5>")
	)
	(segment
		(start 129.219706 -237.904528)
		(end 129.213864 -237.900972)
		(width 0.088646)
		(layer "In6.Cu")
		(net "M_G_CPU1_SB_DQ<5>")
	)
	(segment
		(start 127.020066 -238.577882)
		(end 126.990602 -238.496602)
		(width 0.088646)
		(layer "In6.Cu")
		(net "M_G_CPU1_SB_DQ<5>")
	)
	(arc
		(start 139.294362 -237.81131)
		(mid 138.968379 -237.972072)
		(end 138.611864 -237.901226)
		(width 0.088646)
		(layer "In6.Cu")
		(net "M_G_CPU1_SB_DQ<5>")
	)
	(arc
		(start 134.478014 -237.900972)
		(mid 134.195456 -237.976621)
		(end 133.912864 -237.900972)
		(width 0.088646)
		(layer "In6.Cu")
		(net "M_G_CPU1_SB_DQ<5>")
	)
	(arc
		(start 128.839214 -237.900972)
		(mid 128.703017 -238.036657)
		(end 128.652016 -238.222028)
		(width 0.088646)
		(layer "In6.Cu")
		(net "M_G_CPU1_SB_DQ<5>")
	)
	(arc
		(start 135.792464 -237.901226)
		(mid 135.605266 -237.851083)
		(end 135.418068 -237.901226)
		(width 0.088646)
		(layer "In6.Cu")
		(net "M_G_CPU1_SB_DQ<5>")
	)
	(arc
		(start 130.147822 -237.89767)
		(mid 129.962967 -237.850752)
		(end 129.779014 -237.900972)
		(width 0.088646)
		(layer "In6.Cu")
		(net "M_G_CPU1_SB_DQ<5>")
	)
	(arc
		(start 134.852664 -237.901226)
		(mid 134.665466 -237.851083)
		(end 134.478268 -237.901226)
		(width 0.088646)
		(layer "In6.Cu")
		(net "M_G_CPU1_SB_DQ<5>")
	)
	(arc
		(start 135.418068 -237.901226)
		(mid 135.135366 -237.976968)
		(end 134.852664 -237.901226)
		(width 0.088646)
		(layer "In6.Cu")
		(net "M_G_CPU1_SB_DQ<5>")
	)
	(arc
		(start 128.047242 -238.673132)
		(mid 127.721551 -238.48387)
		(end 127.34925 -238.541306)
		(width 0.088646)
		(layer "In6.Cu")
		(net "M_G_CPU1_SB_DQ<5>")
	)
	(arc
		(start 130.718814 -237.900972)
		(mid 130.43964 -237.976737)
		(end 130.159506 -237.904528)
		(width 0.088646)
		(layer "In6.Cu")
		(net "M_G_CPU1_SB_DQ<5>")
	)
	(arc
		(start 137.297668 -237.901226)
		(mid 137.014966 -237.976968)
		(end 136.732264 -237.901226)
		(width 0.088646)
		(layer "In6.Cu")
		(net "M_G_CPU1_SB_DQ<5>")
	)
	(arc
		(start 128.652016 -238.225584)
		(mid 128.644208 -238.319202)
		(end 128.621028 -238.410242)
		(width 0.088646)
		(layer "In6.Cu")
		(net "M_G_CPU1_SB_DQ<5>")
	)
	(arc
		(start 132.967222 -237.89767)
		(mid 132.782367 -237.850752)
		(end 132.598414 -237.900972)
		(width 0.088646)
		(layer "In6.Cu")
		(net "M_G_CPU1_SB_DQ<5>")
	)
	(arc
		(start 136.732264 -237.901226)
		(mid 136.545066 -237.851083)
		(end 136.357868 -237.901226)
		(width 0.088646)
		(layer "In6.Cu")
		(net "M_G_CPU1_SB_DQ<5>")
	)
	(arc
		(start 131.087622 -237.89767)
		(mid 130.902767 -237.850752)
		(end 130.718814 -237.900972)
		(width 0.088646)
		(layer "In6.Cu")
		(net "M_G_CPU1_SB_DQ<5>")
	)
	(arc
		(start 129.779014 -237.900972)
		(mid 129.49984 -237.976737)
		(end 129.219706 -237.904528)
		(width 0.088646)
		(layer "In6.Cu")
		(net "M_G_CPU1_SB_DQ<5>")
	)
	(arc
		(start 138.237468 -237.901226)
		(mid 137.954766 -237.976968)
		(end 137.672064 -237.901226)
		(width 0.088646)
		(layer "In6.Cu")
		(net "M_G_CPU1_SB_DQ<5>")
	)
	(arc
		(start 132.027422 -237.89767)
		(mid 131.842567 -237.850752)
		(end 131.658614 -237.900972)
		(width 0.088646)
		(layer "In6.Cu")
		(net "M_G_CPU1_SB_DQ<5>")
	)
	(arc
		(start 138.611864 -237.901226)
		(mid 138.424666 -237.851083)
		(end 138.237468 -237.901226)
		(width 0.088646)
		(layer "In6.Cu")
		(net "M_G_CPU1_SB_DQ<5>")
	)
	(arc
		(start 137.672064 -237.901226)
		(mid 137.484866 -237.851083)
		(end 137.297668 -237.901226)
		(width 0.088646)
		(layer "In6.Cu")
		(net "M_G_CPU1_SB_DQ<5>")
	)
	(arc
		(start 136.357868 -237.901226)
		(mid 136.075166 -237.976968)
		(end 135.792464 -237.901226)
		(width 0.088646)
		(layer "In6.Cu")
		(net "M_G_CPU1_SB_DQ<5>")
	)
	(arc
		(start 132.598414 -237.900972)
		(mid 132.31924 -237.976737)
		(end 132.039106 -237.904528)
		(width 0.088646)
		(layer "In6.Cu")
		(net "M_G_CPU1_SB_DQ<5>")
	)
	(arc
		(start 133.538214 -237.900972)
		(mid 133.25904 -237.976737)
		(end 132.978906 -237.904528)
		(width 0.088646)
		(layer "In6.Cu")
		(net "M_G_CPU1_SB_DQ<5>")
	)
	(arc
		(start 129.208022 -237.89767)
		(mid 129.023167 -237.850752)
		(end 128.839214 -237.900972)
		(width 0.088646)
		(layer "In6.Cu")
		(net "M_G_CPU1_SB_DQ<5>")
	)
	(arc
		(start 133.908546 -237.898432)
		(mid 133.723051 -237.850795)
		(end 133.538214 -237.900972)
		(width 0.088646)
		(layer "In6.Cu")
		(net "M_G_CPU1_SB_DQ<5>")
	)
	(arc
		(start 131.658614 -237.900972)
		(mid 131.37944 -237.976737)
		(end 131.099306 -237.904528)
		(width 0.088646)
		(layer "In6.Cu")
		(net "M_G_CPU1_SB_DQ<5>")
	)
	(arc
		(start 127.329692 -238.552736)
		(mid 127.177759 -238.600891)
		(end 127.020066 -238.577882)
		(width 0.088646)
		(layer "In6.Cu")
		(net "M_G_CPU1_SB_DQ<5>")
	)
	(segment
		(start 194.940428 -226.216972)
		(end 194.508882 -225.785426)
		(width 0.20066)
		(layer "F.Cu")
		(net "M_G_CPU1_SB_DQ<4>")
	)
	(segment
		(start 191.883792 -225.791776)
		(end 191.539114 -225.791776)
		(width 0.20066)
		(layer "F.Cu")
		(net "M_G_CPU1_SB_DQ<4>")
	)
	(segment
		(start 126.676912 -239.57534)
		(end 126.677166 -239.575086)
		(width 0.20066)
		(layer "F.Cu")
		(net "M_G_CPU1_SB_DQ<4>")
	)
	(segment
		(start 188.988446 -226.216718)
		(end 187.883546 -226.216718)
		(width 0.20066)
		(layer "F.Cu")
		(net "M_G_CPU1_SB_DQ<4>")
	)
	(segment
		(start 191.421004 -226.277424)
		(end 191.233044 -226.465384)
		(width 0.20066)
		(layer "F.Cu")
		(net "M_G_CPU1_SB_DQ<4>")
	)
	(segment
		(start 194.098926 -225.785426)
		(end 194.092576 -225.791776)
		(width 0.1016)
		(layer "F.Cu")
		(net "M_G_CPU1_SB_DQ<4>")
	)
	(segment
		(start 191.539114 -225.791776)
		(end 191.421004 -225.909886)
		(width 0.20066)
		(layer "F.Cu")
		(net "M_G_CPU1_SB_DQ<4>")
	)
	(segment
		(start 196.531992 -226.216972)
		(end 194.940428 -226.216972)
		(width 0.20066)
		(layer "F.Cu")
		(net "M_G_CPU1_SB_DQ<4>")
	)
	(segment
		(start 190.509144 -226.216718)
		(end 188.988446 -226.216718)
		(width 0.20066)
		(layer "F.Cu")
		(net "M_G_CPU1_SB_DQ<4>")
	)
	(segment
		(start 196.532246 -226.216718)
		(end 196.531992 -226.216972)
		(width 0.20066)
		(layer "F.Cu")
		(net "M_G_CPU1_SB_DQ<4>")
	)
	(segment
		(start 194.092576 -225.791776)
		(end 191.930782 -225.791776)
		(width 0.1016)
		(layer "F.Cu")
		(net "M_G_CPU1_SB_DQ<4>")
	)
	(segment
		(start 194.508882 -225.785426)
		(end 194.098926 -225.785426)
		(width 0.20066)
		(layer "F.Cu")
		(net "M_G_CPU1_SB_DQ<4>")
	)
	(segment
		(start 191.233044 -226.465384)
		(end 190.75781 -226.465384)
		(width 0.20066)
		(layer "F.Cu")
		(net "M_G_CPU1_SB_DQ<4>")
	)
	(segment
		(start 191.421004 -225.909886)
		(end 191.421004 -226.277424)
		(width 0.20066)
		(layer "F.Cu")
		(net "M_G_CPU1_SB_DQ<4>")
	)
	(segment
		(start 190.75781 -226.465384)
		(end 190.509144 -226.216718)
		(width 0.20066)
		(layer "F.Cu")
		(net "M_G_CPU1_SB_DQ<4>")
	)
	(segment
		(start 126.677166 -239.575086)
		(end 126.677166 -239.0394)
		(width 0.20066)
		(layer "F.Cu")
		(net "M_G_CPU1_SB_DQ<4>")
	)
	(segment
		(start 191.930782 -225.791776)
		(end 191.883792 -225.791776)
		(width 0.101854)
		(layer "F.Cu")
		(net "M_G_CPU1_SB_DQ<4>")
	)
	(segment
		(start 155.441142 -231.74198)
		(end 155.258262 -231.92486)
		(width 0.18288)
		(layer "In6.Cu")
		(net "M_G_CPU1_SB_DQ<4>")
	)
	(segment
		(start 127.427482 -238.716312)
		(end 127.42672 -238.71682)
		(width 0.088646)
		(layer "In6.Cu")
		(net "M_G_CPU1_SB_DQ<4>")
	)
	(segment
		(start 126.930658 -238.748062)
		(end 126.833376 -238.768382)
		(width 0.088646)
		(layer "In6.Cu")
		(net "M_G_CPU1_SB_DQ<4>")
	)
	(segment
		(start 169.881296 -231.738932)
		(end 166.991792 -231.738932)
		(width 0.18288)
		(layer "In6.Cu")
		(net "M_G_CPU1_SB_DQ<4>")
	)
	(segment
		(start 132.128514 -238.715042)
		(end 132.121148 -238.71936)
		(width 0.088646)
		(layer "In6.Cu")
		(net "M_G_CPU1_SB_DQ<4>")
	)
	(segment
		(start 178.006502 -230.89235)
		(end 174.348902 -230.89235)
		(width 0.18288)
		(layer "In6.Cu")
		(net "M_G_CPU1_SB_DQ<4>")
	)
	(segment
		(start 153.871422 -232.21569)
		(end 153.688542 -232.39857)
		(width 0.18288)
		(layer "In6.Cu")
		(net "M_G_CPU1_SB_DQ<4>")
	)
	(segment
		(start 129.309114 -238.715042)
		(end 129.305558 -238.717074)
		(width 0.088646)
		(layer "In6.Cu")
		(net "M_G_CPU1_SB_DQ<4>")
	)
	(segment
		(start 156.134562 -232.39857)
		(end 155.951682 -232.21569)
		(width 0.18288)
		(layer "In6.Cu")
		(net "M_G_CPU1_SB_DQ<4>")
	)
	(segment
		(start 178.871626 -230.027226)
		(end 178.006502 -230.89235)
		(width 0.18288)
		(layer "In6.Cu")
		(net "M_G_CPU1_SB_DQ<4>")
	)
	(segment
		(start 155.768802 -231.74198)
		(end 155.441142 -231.74198)
		(width 0.18288)
		(layer "In6.Cu")
		(net "M_G_CPU1_SB_DQ<4>")
	)
	(segment
		(start 171.143676 -231.541828)
		(end 170.766232 -231.919272)
		(width 0.18288)
		(layer "In6.Cu")
		(net "M_G_CPU1_SB_DQ<4>")
	)
	(segment
		(start 158.068264 -231.74198)
		(end 156.827982 -231.74198)
		(width 0.18288)
		(layer "In6.Cu")
		(net "M_G_CPU1_SB_DQ<4>")
	)
	(segment
		(start 185.303922 -227.174298)
		(end 184.010554 -227.174298)
		(width 0.18288)
		(layer "In6.Cu")
		(net "M_G_CPU1_SB_DQ<4>")
	)
	(segment
		(start 128.098804 -239.312704)
		(end 127.991362 -239.205262)
		(width 0.088646)
		(layer "In6.Cu")
		(net "M_G_CPU1_SB_DQ<4>")
	)
	(segment
		(start 129.165096 -238.84001)
		(end 128.915922 -239.166908)
		(width 0.088646)
		(layer "In6.Cu")
		(net "M_G_CPU1_SB_DQ<4>")
	)
	(segment
		(start 140.013436 -238.397034)
		(end 139.654026 -238.756444)
		(width 0.088646)
		(layer "In6.Cu")
		(net "M_G_CPU1_SB_DQ<4>")
	)
	(segment
		(start 154.564842 -232.21569)
		(end 154.564842 -231.92486)
		(width 0.18288)
		(layer "In6.Cu")
		(net "M_G_CPU1_SB_DQ<4>")
	)
	(segment
		(start 184.010554 -227.174298)
		(end 183.068214 -228.116638)
		(width 0.18288)
		(layer "In6.Cu")
		(net "M_G_CPU1_SB_DQ<4>")
	)
	(segment
		(start 156.645102 -231.92486)
		(end 156.645102 -232.21569)
		(width 0.18288)
		(layer "In6.Cu")
		(net "M_G_CPU1_SB_DQ<4>")
	)
	(segment
		(start 130.253486 -238.712248)
		(end 130.248914 -238.715042)
		(width 0.088646)
		(layer "In6.Cu")
		(net "M_G_CPU1_SB_DQ<4>")
	)
	(segment
		(start 153.360882 -232.39857)
		(end 153.178002 -232.21569)
		(width 0.18288)
		(layer "In6.Cu")
		(net "M_G_CPU1_SB_DQ<4>")
	)
	(segment
		(start 160.601406 -231.749092)
		(end 160.601406 -231.05237)
		(width 0.18288)
		(layer "In6.Cu")
		(net "M_G_CPU1_SB_DQ<4>")
	)
	(segment
		(start 161.294826 -231.05237)
		(end 161.294826 -231.749092)
		(width 0.18288)
		(layer "In6.Cu")
		(net "M_G_CPU1_SB_DQ<4>")
	)
	(segment
		(start 140.442696 -238.397034)
		(end 140.013436 -238.397034)
		(width 0.088646)
		(layer "In6.Cu")
		(net "M_G_CPU1_SB_DQ<4>")
	)
	(segment
		(start 128.340866 -239.346994)
		(end 128.098804 -239.312704)
		(width 0.088646)
		(layer "In6.Cu")
		(net "M_G_CPU1_SB_DQ<4>")
	)
	(segment
		(start 133.068314 -238.715042)
		(end 133.060948 -238.71936)
		(width 0.088646)
		(layer "In6.Cu")
		(net "M_G_CPU1_SB_DQ<4>")
	)
	(segment
		(start 160.761426 -231.909112)
		(end 160.601406 -231.749092)
		(width 0.18288)
		(layer "In6.Cu")
		(net "M_G_CPU1_SB_DQ<4>")
	)
	(segment
		(start 162.418268 -230.5812)
		(end 162.107118 -230.89235)
		(width 0.18288)
		(layer "In6.Cu")
		(net "M_G_CPU1_SB_DQ<4>")
	)
	(segment
		(start 156.827982 -231.74198)
		(end 156.645102 -231.92486)
		(width 0.18288)
		(layer "In6.Cu")
		(net "M_G_CPU1_SB_DQ<4>")
	)
	(segment
		(start 172.153834 -231.742234)
		(end 171.953428 -231.541828)
		(width 0.18288)
		(layer "In6.Cu")
		(net "M_G_CPU1_SB_DQ<4>")
	)
	(segment
		(start 126.677166 -239.039146)
		(end 126.677166 -239.0394)
		(width 0.088646)
		(layer "In6.Cu")
		(net "M_G_CPU1_SB_DQ<4>")
	)
	(segment
		(start 132.133086 -238.712248)
		(end 132.128514 -238.715042)
		(width 0.088646)
		(layer "In6.Cu")
		(net "M_G_CPU1_SB_DQ<4>")
	)
	(segment
		(start 174.348902 -230.89235)
		(end 173.499018 -231.742234)
		(width 0.18288)
		(layer "In6.Cu")
		(net "M_G_CPU1_SB_DQ<4>")
	)
	(segment
		(start 128.369568 -239.363758)
		(end 128.340866 -239.346994)
		(width 0.088646)
		(layer "In6.Cu")
		(net "M_G_CPU1_SB_DQ<4>")
	)
	(segment
		(start 155.951682 -231.92486)
		(end 155.768802 -231.74198)
		(width 0.18288)
		(layer "In6.Cu")
		(net "M_G_CPU1_SB_DQ<4>")
	)
	(segment
		(start 126.833376 -238.768382)
		(end 126.677166 -239.039146)
		(width 0.088646)
		(layer "In6.Cu")
		(net "M_G_CPU1_SB_DQ<4>")
	)
	(segment
		(start 170.766232 -231.919272)
		(end 170.061636 -231.919272)
		(width 0.18288)
		(layer "In6.Cu")
		(net "M_G_CPU1_SB_DQ<4>")
	)
	(segment
		(start 127.991362 -239.205262)
		(end 127.991362 -239.0394)
		(width 0.088646)
		(layer "In6.Cu")
		(net "M_G_CPU1_SB_DQ<4>")
	)
	(segment
		(start 186.874912 -226.67214)
		(end 185.80608 -226.67214)
		(width 0.18288)
		(layer "In6.Cu")
		(net "M_G_CPU1_SB_DQ<4>")
	)
	(segment
		(start 162.107118 -230.89235)
		(end 161.454846 -230.89235)
		(width 0.18288)
		(layer "In6.Cu")
		(net "M_G_CPU1_SB_DQ<4>")
	)
	(segment
		(start 166.143686 -230.890826)
		(end 163.838128 -230.890826)
		(width 0.18288)
		(layer "In6.Cu")
		(net "M_G_CPU1_SB_DQ<4>")
	)
	(segment
		(start 173.499018 -231.742234)
		(end 172.153834 -231.742234)
		(width 0.18288)
		(layer "In6.Cu")
		(net "M_G_CPU1_SB_DQ<4>")
	)
	(segment
		(start 161.294826 -231.749092)
		(end 161.134806 -231.909112)
		(width 0.18288)
		(layer "In6.Cu")
		(net "M_G_CPU1_SB_DQ<4>")
	)
	(segment
		(start 130.248914 -238.715042)
		(end 130.241548 -238.71936)
		(width 0.088646)
		(layer "In6.Cu")
		(net "M_G_CPU1_SB_DQ<4>")
	)
	(segment
		(start 171.953428 -231.541828)
		(end 171.143676 -231.541828)
		(width 0.18288)
		(layer "In6.Cu")
		(net "M_G_CPU1_SB_DQ<4>")
	)
	(segment
		(start 153.178002 -231.92486)
		(end 152.995122 -231.74198)
		(width 0.18288)
		(layer "In6.Cu")
		(net "M_G_CPU1_SB_DQ<4>")
	)
	(segment
		(start 155.258262 -232.21569)
		(end 155.075382 -232.39857)
		(width 0.18288)
		(layer "In6.Cu")
		(net "M_G_CPU1_SB_DQ<4>")
	)
	(segment
		(start 179.878482 -230.297482)
		(end 179.608226 -230.027226)
		(width 0.18288)
		(layer "In6.Cu")
		(net "M_G_CPU1_SB_DQ<4>")
	)
	(segment
		(start 183.068214 -228.116638)
		(end 182.243222 -228.116638)
		(width 0.18288)
		(layer "In6.Cu")
		(net "M_G_CPU1_SB_DQ<4>")
	)
	(segment
		(start 187.883546 -226.216718)
		(end 187.330334 -226.216718)
		(width 0.18288)
		(layer "In6.Cu")
		(net "M_G_CPU1_SB_DQ<4>")
	)
	(segment
		(start 187.330334 -226.216718)
		(end 186.874912 -226.67214)
		(width 0.18288)
		(layer "In6.Cu")
		(net "M_G_CPU1_SB_DQ<4>")
	)
	(segment
		(start 155.075382 -232.39857)
		(end 154.747722 -232.39857)
		(width 0.18288)
		(layer "In6.Cu")
		(net "M_G_CPU1_SB_DQ<4>")
	)
	(segment
		(start 129.23139 -238.773716)
		(end 129.165096 -238.84001)
		(width 0.088646)
		(layer "In6.Cu")
		(net "M_G_CPU1_SB_DQ<4>")
	)
	(segment
		(start 153.871422 -231.92486)
		(end 153.871422 -232.21569)
		(width 0.18288)
		(layer "In6.Cu")
		(net "M_G_CPU1_SB_DQ<4>")
	)
	(segment
		(start 133.072886 -238.712248)
		(end 133.068314 -238.715042)
		(width 0.088646)
		(layer "In6.Cu")
		(net "M_G_CPU1_SB_DQ<4>")
	)
	(segment
		(start 134.008114 -238.715042)
		(end 134.002526 -238.718344)
		(width 0.088646)
		(layer "In6.Cu")
		(net "M_G_CPU1_SB_DQ<4>")
	)
	(segment
		(start 154.054302 -231.74198)
		(end 153.871422 -231.92486)
		(width 0.18288)
		(layer "In6.Cu")
		(net "M_G_CPU1_SB_DQ<4>")
	)
	(segment
		(start 155.258262 -231.92486)
		(end 155.258262 -232.21569)
		(width 0.18288)
		(layer "In6.Cu")
		(net "M_G_CPU1_SB_DQ<4>")
	)
	(segment
		(start 180.852826 -230.078026)
		(end 180.63337 -230.297482)
		(width 0.18288)
		(layer "In6.Cu")
		(net "M_G_CPU1_SB_DQ<4>")
	)
	(segment
		(start 158.917894 -230.89235)
		(end 158.068264 -231.74198)
		(width 0.18288)
		(layer "In6.Cu")
		(net "M_G_CPU1_SB_DQ<4>")
	)
	(segment
		(start 155.951682 -232.21569)
		(end 155.951682 -231.92486)
		(width 0.18288)
		(layer "In6.Cu")
		(net "M_G_CPU1_SB_DQ<4>")
	)
	(segment
		(start 145.56994 -238.397034)
		(end 140.442696 -238.397034)
		(width 0.18288)
		(layer "In6.Cu")
		(net "M_G_CPU1_SB_DQ<4>")
	)
	(segment
		(start 170.061636 -231.919272)
		(end 169.881296 -231.738932)
		(width 0.18288)
		(layer "In6.Cu")
		(net "M_G_CPU1_SB_DQ<4>")
	)
	(segment
		(start 179.608226 -230.027226)
		(end 178.871626 -230.027226)
		(width 0.18288)
		(layer "In6.Cu")
		(net "M_G_CPU1_SB_DQ<4>")
	)
	(segment
		(start 152.995122 -231.74198)
		(end 152.224994 -231.74198)
		(width 0.18288)
		(layer "In6.Cu")
		(net "M_G_CPU1_SB_DQ<4>")
	)
	(segment
		(start 156.462222 -232.39857)
		(end 156.134562 -232.39857)
		(width 0.18288)
		(layer "In6.Cu")
		(net "M_G_CPU1_SB_DQ<4>")
	)
	(segment
		(start 152.224994 -231.74198)
		(end 145.56994 -238.397034)
		(width 0.18288)
		(layer "In6.Cu")
		(net "M_G_CPU1_SB_DQ<4>")
	)
	(segment
		(start 161.134806 -231.909112)
		(end 160.761426 -231.909112)
		(width 0.18288)
		(layer "In6.Cu")
		(net "M_G_CPU1_SB_DQ<4>")
	)
	(segment
		(start 154.381962 -231.74198)
		(end 154.054302 -231.74198)
		(width 0.18288)
		(layer "In6.Cu")
		(net "M_G_CPU1_SB_DQ<4>")
	)
	(segment
		(start 182.243222 -228.116638)
		(end 180.852826 -229.507034)
		(width 0.18288)
		(layer "In6.Cu")
		(net "M_G_CPU1_SB_DQ<4>")
	)
	(segment
		(start 163.838128 -230.890826)
		(end 163.528502 -230.5812)
		(width 0.18288)
		(layer "In6.Cu")
		(net "M_G_CPU1_SB_DQ<4>")
	)
	(segment
		(start 160.441386 -230.89235)
		(end 158.917894 -230.89235)
		(width 0.18288)
		(layer "In6.Cu")
		(net "M_G_CPU1_SB_DQ<4>")
	)
	(segment
		(start 131.188714 -238.715042)
		(end 131.181348 -238.71936)
		(width 0.088646)
		(layer "In6.Cu")
		(net "M_G_CPU1_SB_DQ<4>")
	)
	(segment
		(start 180.852826 -229.507034)
		(end 180.852826 -230.078026)
		(width 0.18288)
		(layer "In6.Cu")
		(net "M_G_CPU1_SB_DQ<4>")
	)
	(segment
		(start 154.747722 -232.39857)
		(end 154.564842 -232.21569)
		(width 0.18288)
		(layer "In6.Cu")
		(net "M_G_CPU1_SB_DQ<4>")
	)
	(segment
		(start 161.454846 -230.89235)
		(end 161.294826 -231.05237)
		(width 0.18288)
		(layer "In6.Cu")
		(net "M_G_CPU1_SB_DQ<4>")
	)
	(segment
		(start 180.63337 -230.297482)
		(end 179.878482 -230.297482)
		(width 0.18288)
		(layer "In6.Cu")
		(net "M_G_CPU1_SB_DQ<4>")
	)
	(segment
		(start 154.564842 -231.92486)
		(end 154.381962 -231.74198)
		(width 0.18288)
		(layer "In6.Cu")
		(net "M_G_CPU1_SB_DQ<4>")
	)
	(segment
		(start 185.80608 -226.67214)
		(end 185.303922 -227.174298)
		(width 0.18288)
		(layer "In6.Cu")
		(net "M_G_CPU1_SB_DQ<4>")
	)
	(segment
		(start 139.654026 -238.756444)
		(end 139.198096 -238.756444)
		(width 0.088646)
		(layer "In6.Cu")
		(net "M_G_CPU1_SB_DQ<4>")
	)
	(segment
		(start 163.528502 -230.5812)
		(end 162.418268 -230.5812)
		(width 0.18288)
		(layer "In6.Cu")
		(net "M_G_CPU1_SB_DQ<4>")
	)
	(segment
		(start 160.601406 -231.05237)
		(end 160.441386 -230.89235)
		(width 0.18288)
		(layer "In6.Cu")
		(net "M_G_CPU1_SB_DQ<4>")
	)
	(segment
		(start 156.645102 -232.21569)
		(end 156.462222 -232.39857)
		(width 0.18288)
		(layer "In6.Cu")
		(net "M_G_CPU1_SB_DQ<4>")
	)
	(segment
		(start 129.313686 -238.712248)
		(end 129.309114 -238.715042)
		(width 0.088646)
		(layer "In6.Cu")
		(net "M_G_CPU1_SB_DQ<4>")
	)
	(segment
		(start 153.688542 -232.39857)
		(end 153.360882 -232.39857)
		(width 0.18288)
		(layer "In6.Cu")
		(net "M_G_CPU1_SB_DQ<4>")
	)
	(segment
		(start 131.193286 -238.712248)
		(end 131.188714 -238.715042)
		(width 0.088646)
		(layer "In6.Cu")
		(net "M_G_CPU1_SB_DQ<4>")
	)
	(segment
		(start 166.991792 -231.738932)
		(end 166.143686 -230.890826)
		(width 0.18288)
		(layer "In6.Cu")
		(net "M_G_CPU1_SB_DQ<4>")
	)
	(segment
		(start 153.178002 -232.21569)
		(end 153.178002 -231.92486)
		(width 0.18288)
		(layer "In6.Cu")
		(net "M_G_CPU1_SB_DQ<4>")
	)
	(arc
		(start 136.262364 -238.715042)
		(mid 136.075166 -238.664899)
		(end 135.887968 -238.715042)
		(width 0.088646)
		(layer "In6.Cu")
		(net "M_G_CPU1_SB_DQ<4>")
	)
	(arc
		(start 127.42672 -238.71682)
		(mid 127.182444 -238.791999)
		(end 126.930658 -238.748062)
		(width 0.088646)
		(layer "In6.Cu")
		(net "M_G_CPU1_SB_DQ<4>")
	)
	(arc
		(start 139.17422 -238.753396)
		(mid 139.126711 -238.737308)
		(end 139.081764 -238.715042)
		(width 0.088646)
		(layer "In6.Cu")
		(net "M_G_CPU1_SB_DQ<4>")
	)
	(arc
		(start 131.181348 -238.71936)
		(mid 130.901887 -238.790797)
		(end 130.623564 -238.715042)
		(width 0.088646)
		(layer "In6.Cu")
		(net "M_G_CPU1_SB_DQ<4>")
	)
	(arc
		(start 134.948168 -238.715042)
		(mid 134.665466 -238.790818)
		(end 134.382764 -238.715042)
		(width 0.088646)
		(layer "In6.Cu")
		(net "M_G_CPU1_SB_DQ<4>")
	)
	(arc
		(start 133.442964 -238.715042)
		(mid 133.2583 -238.664782)
		(end 133.072886 -238.712248)
		(width 0.088646)
		(layer "In6.Cu")
		(net "M_G_CPU1_SB_DQ<4>")
	)
	(arc
		(start 139.081764 -238.715042)
		(mid 138.894566 -238.664899)
		(end 138.707368 -238.715042)
		(width 0.088646)
		(layer "In6.Cu")
		(net "M_G_CPU1_SB_DQ<4>")
	)
	(arc
		(start 137.202164 -238.715042)
		(mid 137.014966 -238.664899)
		(end 136.827768 -238.715042)
		(width 0.088646)
		(layer "In6.Cu")
		(net "M_G_CPU1_SB_DQ<4>")
	)
	(arc
		(start 131.563364 -238.715042)
		(mid 131.3787 -238.664782)
		(end 131.193286 -238.712248)
		(width 0.088646)
		(layer "In6.Cu")
		(net "M_G_CPU1_SB_DQ<4>")
	)
	(arc
		(start 128.915922 -239.166908)
		(mid 128.846287 -239.279605)
		(end 128.743964 -239.363758)
		(width 0.088646)
		(layer "In6.Cu")
		(net "M_G_CPU1_SB_DQ<4>")
	)
	(arc
		(start 133.060948 -238.71936)
		(mid 132.781487 -238.790797)
		(end 132.503164 -238.715042)
		(width 0.088646)
		(layer "In6.Cu")
		(net "M_G_CPU1_SB_DQ<4>")
	)
	(arc
		(start 132.503164 -238.715042)
		(mid 132.3185 -238.664782)
		(end 132.133086 -238.712248)
		(width 0.088646)
		(layer "In6.Cu")
		(net "M_G_CPU1_SB_DQ<4>")
	)
	(arc
		(start 139.198096 -238.756444)
		(mid 139.186063 -238.755671)
		(end 139.17422 -238.753396)
		(width 0.088646)
		(layer "In6.Cu")
		(net "M_G_CPU1_SB_DQ<4>")
	)
	(arc
		(start 130.623564 -238.715042)
		(mid 130.4389 -238.664782)
		(end 130.253486 -238.712248)
		(width 0.088646)
		(layer "In6.Cu")
		(net "M_G_CPU1_SB_DQ<4>")
	)
	(arc
		(start 134.002526 -238.718344)
		(mid 133.722311 -238.790785)
		(end 133.442964 -238.715042)
		(width 0.088646)
		(layer "In6.Cu")
		(net "M_G_CPU1_SB_DQ<4>")
	)
	(arc
		(start 127.991362 -239.0394)
		(mid 127.803057 -238.714527)
		(end 127.427482 -238.716312)
		(width 0.088646)
		(layer "In6.Cu")
		(net "M_G_CPU1_SB_DQ<4>")
	)
	(arc
		(start 132.121148 -238.71936)
		(mid 131.841687 -238.790797)
		(end 131.563364 -238.715042)
		(width 0.088646)
		(layer "In6.Cu")
		(net "M_G_CPU1_SB_DQ<4>")
	)
	(arc
		(start 138.141964 -238.715042)
		(mid 137.954766 -238.664899)
		(end 137.767568 -238.715042)
		(width 0.088646)
		(layer "In6.Cu")
		(net "M_G_CPU1_SB_DQ<4>")
	)
	(arc
		(start 137.767568 -238.715042)
		(mid 137.484866 -238.790818)
		(end 137.202164 -238.715042)
		(width 0.088646)
		(layer "In6.Cu")
		(net "M_G_CPU1_SB_DQ<4>")
	)
	(arc
		(start 138.707368 -238.715042)
		(mid 138.424666 -238.790818)
		(end 138.141964 -238.715042)
		(width 0.088646)
		(layer "In6.Cu")
		(net "M_G_CPU1_SB_DQ<4>")
	)
	(arc
		(start 135.322564 -238.715042)
		(mid 135.135366 -238.664899)
		(end 134.948168 -238.715042)
		(width 0.088646)
		(layer "In6.Cu")
		(net "M_G_CPU1_SB_DQ<4>")
	)
	(arc
		(start 129.305558 -238.717074)
		(mid 129.26659 -238.742928)
		(end 129.23139 -238.773716)
		(width 0.088646)
		(layer "In6.Cu")
		(net "M_G_CPU1_SB_DQ<4>")
	)
	(arc
		(start 135.887968 -238.715042)
		(mid 135.605266 -238.790818)
		(end 135.322564 -238.715042)
		(width 0.088646)
		(layer "In6.Cu")
		(net "M_G_CPU1_SB_DQ<4>")
	)
	(arc
		(start 128.743964 -239.363758)
		(mid 128.556766 -239.413901)
		(end 128.369568 -239.363758)
		(width 0.088646)
		(layer "In6.Cu")
		(net "M_G_CPU1_SB_DQ<4>")
	)
	(arc
		(start 136.827768 -238.715042)
		(mid 136.545066 -238.790818)
		(end 136.262364 -238.715042)
		(width 0.088646)
		(layer "In6.Cu")
		(net "M_G_CPU1_SB_DQ<4>")
	)
	(arc
		(start 134.382764 -238.715042)
		(mid 134.195456 -238.664899)
		(end 134.008114 -238.715042)
		(width 0.088646)
		(layer "In6.Cu")
		(net "M_G_CPU1_SB_DQ<4>")
	)
	(arc
		(start 129.683764 -238.715042)
		(mid 129.4991 -238.664782)
		(end 129.313686 -238.712248)
		(width 0.088646)
		(layer "In6.Cu")
		(net "M_G_CPU1_SB_DQ<4>")
	)
	(arc
		(start 130.241548 -238.71936)
		(mid 129.962087 -238.790797)
		(end 129.683764 -238.715042)
		(width 0.088646)
		(layer "In6.Cu")
		(net "M_G_CPU1_SB_DQ<4>")
	)
	(segment
		(start 128.556766 -241.202972)
		(end 128.556766 -240.667286)
		(width 0.20066)
		(layer "F.Cu")
		(net "M_G_CPU1_SB_DQ<3>")
	)
	(segment
		(start 195.522596 -230.041704)
		(end 197.530466 -230.041704)
		(width 0.1016)
		(layer "F.Cu")
		(net "M_G_CPU1_SB_DQ<3>")
	)
	(segment
		(start 198.662036 -229.364794)
		(end 199.046084 -229.364794)
		(width 0.20066)
		(layer "F.Cu")
		(net "M_G_CPU1_SB_DQ<3>")
	)
	(segment
		(start 198.427848 -229.598982)
		(end 198.662036 -229.364794)
		(width 0.20066)
		(layer "F.Cu")
		(net "M_G_CPU1_SB_DQ<3>")
	)
	(segment
		(start 199.046084 -229.364794)
		(end 199.298052 -229.616762)
		(width 0.20066)
		(layer "F.Cu")
		(net "M_G_CPU1_SB_DQ<3>")
	)
	(segment
		(start 197.530466 -230.041704)
		(end 197.542658 -230.053896)
		(width 0.1016)
		(layer "F.Cu")
		(net "M_G_CPU1_SB_DQ<3>")
	)
	(segment
		(start 195.510658 -230.048816)
		(end 195.515484 -230.048816)
		(width 0.101854)
		(layer "F.Cu")
		(net "M_G_CPU1_SB_DQ<3>")
	)
	(segment
		(start 195.515484 -230.048816)
		(end 195.522596 -230.041704)
		(width 0.1016)
		(layer "F.Cu")
		(net "M_G_CPU1_SB_DQ<3>")
	)
	(segment
		(start 128.556512 -241.203226)
		(end 128.556766 -241.202972)
		(width 0.20066)
		(layer "F.Cu")
		(net "M_G_CPU1_SB_DQ<3>")
	)
	(segment
		(start 198.427848 -229.849934)
		(end 198.427848 -229.598982)
		(width 0.20066)
		(layer "F.Cu")
		(net "M_G_CPU1_SB_DQ<3>")
	)
	(segment
		(start 193.088514 -229.616762)
		(end 194.786758 -229.616762)
		(width 0.20066)
		(layer "F.Cu")
		(net "M_G_CPU1_SB_DQ<3>")
	)
	(segment
		(start 199.298052 -229.616762)
		(end 200.632314 -229.616762)
		(width 0.20066)
		(layer "F.Cu")
		(net "M_G_CPU1_SB_DQ<3>")
	)
	(segment
		(start 197.542658 -230.053896)
		(end 198.223886 -230.053896)
		(width 0.20066)
		(layer "F.Cu")
		(net "M_G_CPU1_SB_DQ<3>")
	)
	(segment
		(start 191.983614 -229.616762)
		(end 193.088514 -229.616762)
		(width 0.20066)
		(layer "F.Cu")
		(net "M_G_CPU1_SB_DQ<3>")
	)
	(segment
		(start 194.786758 -229.616762)
		(end 195.218812 -230.048816)
		(width 0.20066)
		(layer "F.Cu")
		(net "M_G_CPU1_SB_DQ<3>")
	)
	(segment
		(start 195.218812 -230.048816)
		(end 195.510658 -230.048816)
		(width 0.20066)
		(layer "F.Cu")
		(net "M_G_CPU1_SB_DQ<3>")
	)
	(segment
		(start 198.223886 -230.053896)
		(end 198.427848 -229.849934)
		(width 0.20066)
		(layer "F.Cu")
		(net "M_G_CPU1_SB_DQ<3>")
	)
	(segment
		(start 173.665134 -235.992416)
		(end 171.572174 -235.992416)
		(width 0.18288)
		(layer "In6.Cu")
		(net "M_G_CPU1_SB_DQ<3>")
	)
	(segment
		(start 153.073862 -235.183172)
		(end 147.699222 -240.557812)
		(width 0.18288)
		(layer "In6.Cu")
		(net "M_G_CPU1_SB_DQ<3>")
	)
	(segment
		(start 174.516288 -235.141262)
		(end 173.665134 -235.992416)
		(width 0.18288)
		(layer "In6.Cu")
		(net "M_G_CPU1_SB_DQ<3>")
	)
	(segment
		(start 139.906756 -240.81613)
		(end 139.280646 -240.81613)
		(width 0.088646)
		(layer "In6.Cu")
		(net "M_G_CPU1_SB_DQ<3>")
	)
	(segment
		(start 180.97119 -235.141262)
		(end 174.516288 -235.141262)
		(width 0.18288)
		(layer "In6.Cu")
		(net "M_G_CPU1_SB_DQ<3>")
	)
	(segment
		(start 182.497222 -233.710226)
		(end 182.402226 -233.710226)
		(width 0.18288)
		(layer "In6.Cu")
		(net "M_G_CPU1_SB_DQ<3>")
	)
	(segment
		(start 160.507426 -235.183426)
		(end 157.80512 -235.183426)
		(width 0.18288)
		(layer "In6.Cu")
		(net "M_G_CPU1_SB_DQ<3>")
	)
	(segment
		(start 130.638296 -240.983008)
		(end 130.623564 -240.991644)
		(width 0.088646)
		(layer "In6.Cu")
		(net "M_G_CPU1_SB_DQ<3>")
	)
	(segment
		(start 165.012116 -235.217716)
		(end 164.698426 -234.904026)
		(width 0.18288)
		(layer "In6.Cu")
		(net "M_G_CPU1_SB_DQ<3>")
	)
	(segment
		(start 171.572174 -235.992416)
		(end 171.271184 -235.691426)
		(width 0.18288)
		(layer "In6.Cu")
		(net "M_G_CPU1_SB_DQ<3>")
	)
	(segment
		(start 191.415162 -229.616762)
		(end 190.990728 -229.192328)
		(width 0.18288)
		(layer "In6.Cu")
		(net "M_G_CPU1_SB_DQ<3>")
	)
	(segment
		(start 128.369568 -240.991644)
		(end 128.360678 -240.986564)
		(width 0.088646)
		(layer "In6.Cu")
		(net "M_G_CPU1_SB_DQ<3>")
	)
	(segment
		(start 170.561508 -235.691426)
		(end 170.200828 -236.052106)
		(width 0.18288)
		(layer "In6.Cu")
		(net "M_G_CPU1_SB_DQ<3>")
	)
	(segment
		(start 183.951626 -231.830626)
		(end 183.951626 -232.255822)
		(width 0.18288)
		(layer "In6.Cu")
		(net "M_G_CPU1_SB_DQ<3>")
	)
	(segment
		(start 170.200828 -236.052106)
		(end 168.590214 -236.052106)
		(width 0.18288)
		(layer "In6.Cu")
		(net "M_G_CPU1_SB_DQ<3>")
	)
	(segment
		(start 139.280646 -240.81613)
		(end 139.081764 -240.991644)
		(width 0.088646)
		(layer "In6.Cu")
		(net "M_G_CPU1_SB_DQ<3>")
	)
	(segment
		(start 129.698496 -240.983008)
		(end 129.683764 -240.991644)
		(width 0.088646)
		(layer "In6.Cu")
		(net "M_G_CPU1_SB_DQ<3>")
	)
	(segment
		(start 186.237626 -229.544626)
		(end 185.815732 -229.96652)
		(width 0.18288)
		(layer "In6.Cu")
		(net "M_G_CPU1_SB_DQ<3>")
	)
	(segment
		(start 140.165074 -240.557812)
		(end 139.906756 -240.81613)
		(width 0.088646)
		(layer "In6.Cu")
		(net "M_G_CPU1_SB_DQ<3>")
	)
	(segment
		(start 185.099198 -230.683054)
		(end 183.951626 -231.830626)
		(width 0.18288)
		(layer "In6.Cu")
		(net "M_G_CPU1_SB_DQ<3>")
	)
	(segment
		(start 186.084972 -230.68788)
		(end 185.820558 -230.952294)
		(width 0.18288)
		(layer "In6.Cu")
		(net "M_G_CPU1_SB_DQ<3>")
	)
	(segment
		(start 132.513324 -240.985548)
		(end 132.50291 -240.991644)
		(width 0.088646)
		(layer "In6.Cu")
		(net "M_G_CPU1_SB_DQ<3>")
	)
	(segment
		(start 128.244092 -240.667286)
		(end 128.556766 -240.667286)
		(width 0.088646)
		(layer "In6.Cu")
		(net "M_G_CPU1_SB_DQ<3>")
	)
	(segment
		(start 166.974012 -235.400596)
		(end 166.974012 -235.817156)
		(width 0.18288)
		(layer "In6.Cu")
		(net "M_G_CPU1_SB_DQ<3>")
	)
	(segment
		(start 185.325258 -230.683054)
		(end 185.099198 -230.683054)
		(width 0.18288)
		(layer "In6.Cu")
		(net "M_G_CPU1_SB_DQ<3>")
	)
	(segment
		(start 166.280592 -235.817156)
		(end 166.280592 -235.400596)
		(width 0.18288)
		(layer "In6.Cu")
		(net "M_G_CPU1_SB_DQ<3>")
	)
	(segment
		(start 128.186688 -240.72469)
		(end 128.244092 -240.667286)
		(width 0.088646)
		(layer "In6.Cu")
		(net "M_G_CPU1_SB_DQ<3>")
	)
	(segment
		(start 191.983614 -229.616762)
		(end 191.415162 -229.616762)
		(width 0.18288)
		(layer "In6.Cu")
		(net "M_G_CPU1_SB_DQ<3>")
	)
	(segment
		(start 186.084972 -230.46182)
		(end 186.084972 -230.68788)
		(width 0.18288)
		(layer "In6.Cu")
		(net "M_G_CPU1_SB_DQ<3>")
	)
	(segment
		(start 147.699222 -240.557812)
		(end 140.442696 -240.557812)
		(width 0.18288)
		(layer "In6.Cu")
		(net "M_G_CPU1_SB_DQ<3>")
	)
	(segment
		(start 168.590214 -236.052106)
		(end 167.755824 -235.217716)
		(width 0.18288)
		(layer "In6.Cu")
		(net "M_G_CPU1_SB_DQ<3>")
	)
	(segment
		(start 167.156892 -235.217716)
		(end 166.974012 -235.400596)
		(width 0.18288)
		(layer "In6.Cu")
		(net "M_G_CPU1_SB_DQ<3>")
	)
	(segment
		(start 185.594498 -230.952294)
		(end 185.325258 -230.683054)
		(width 0.18288)
		(layer "In6.Cu")
		(net "M_G_CPU1_SB_DQ<3>")
	)
	(segment
		(start 166.097712 -235.217716)
		(end 165.012116 -235.217716)
		(width 0.18288)
		(layer "In6.Cu")
		(net "M_G_CPU1_SB_DQ<3>")
	)
	(segment
		(start 183.951626 -232.255822)
		(end 182.497222 -233.710226)
		(width 0.18288)
		(layer "In6.Cu")
		(net "M_G_CPU1_SB_DQ<3>")
	)
	(segment
		(start 134.397496 -240.983008)
		(end 134.382764 -240.991644)
		(width 0.088646)
		(layer "In6.Cu")
		(net "M_G_CPU1_SB_DQ<3>")
	)
	(segment
		(start 131.573778 -240.985548)
		(end 131.563364 -240.991644)
		(width 0.088646)
		(layer "In6.Cu")
		(net "M_G_CPU1_SB_DQ<3>")
	)
	(segment
		(start 162.172142 -236.047026)
		(end 161.371026 -236.047026)
		(width 0.18288)
		(layer "In6.Cu")
		(net "M_G_CPU1_SB_DQ<3>")
	)
	(segment
		(start 167.755824 -235.217716)
		(end 167.156892 -235.217716)
		(width 0.18288)
		(layer "In6.Cu")
		(net "M_G_CPU1_SB_DQ<3>")
	)
	(segment
		(start 164.698426 -234.904026)
		(end 163.315142 -234.904026)
		(width 0.18288)
		(layer "In6.Cu")
		(net "M_G_CPU1_SB_DQ<3>")
	)
	(segment
		(start 171.271184 -235.691426)
		(end 170.561508 -235.691426)
		(width 0.18288)
		(layer "In6.Cu")
		(net "M_G_CPU1_SB_DQ<3>")
	)
	(segment
		(start 185.815732 -229.96652)
		(end 185.815732 -230.19258)
		(width 0.18288)
		(layer "In6.Cu")
		(net "M_G_CPU1_SB_DQ<3>")
	)
	(segment
		(start 161.371026 -236.047026)
		(end 160.507426 -235.183426)
		(width 0.18288)
		(layer "In6.Cu")
		(net "M_G_CPU1_SB_DQ<3>")
	)
	(segment
		(start 185.820558 -230.952294)
		(end 185.594498 -230.952294)
		(width 0.18288)
		(layer "In6.Cu")
		(net "M_G_CPU1_SB_DQ<3>")
	)
	(segment
		(start 190.990728 -229.192328)
		(end 187.152026 -229.192328)
		(width 0.18288)
		(layer "In6.Cu")
		(net "M_G_CPU1_SB_DQ<3>")
	)
	(segment
		(start 185.815732 -230.19258)
		(end 186.084972 -230.46182)
		(width 0.18288)
		(layer "In6.Cu")
		(net "M_G_CPU1_SB_DQ<3>")
	)
	(segment
		(start 140.442696 -240.557812)
		(end 140.165074 -240.557812)
		(width 0.088646)
		(layer "In6.Cu")
		(net "M_G_CPU1_SB_DQ<3>")
	)
	(segment
		(start 187.152026 -229.192328)
		(end 186.799728 -229.544626)
		(width 0.18288)
		(layer "In6.Cu")
		(net "M_G_CPU1_SB_DQ<3>")
	)
	(segment
		(start 166.463472 -236.000036)
		(end 166.280592 -235.817156)
		(width 0.18288)
		(layer "In6.Cu")
		(net "M_G_CPU1_SB_DQ<3>")
	)
	(segment
		(start 163.315142 -234.904026)
		(end 162.172142 -236.047026)
		(width 0.18288)
		(layer "In6.Cu")
		(net "M_G_CPU1_SB_DQ<3>")
	)
	(segment
		(start 157.80512 -235.183426)
		(end 157.804866 -235.183172)
		(width 0.18288)
		(layer "In6.Cu")
		(net "M_G_CPU1_SB_DQ<3>")
	)
	(segment
		(start 166.280592 -235.400596)
		(end 166.097712 -235.217716)
		(width 0.18288)
		(layer "In6.Cu")
		(net "M_G_CPU1_SB_DQ<3>")
	)
	(segment
		(start 186.799728 -229.544626)
		(end 186.237626 -229.544626)
		(width 0.18288)
		(layer "In6.Cu")
		(net "M_G_CPU1_SB_DQ<3>")
	)
	(segment
		(start 157.804866 -235.183172)
		(end 153.073862 -235.183172)
		(width 0.18288)
		(layer "In6.Cu")
		(net "M_G_CPU1_SB_DQ<3>")
	)
	(segment
		(start 166.974012 -235.817156)
		(end 166.791132 -236.000036)
		(width 0.18288)
		(layer "In6.Cu")
		(net "M_G_CPU1_SB_DQ<3>")
	)
	(segment
		(start 182.402226 -233.710226)
		(end 180.97119 -235.141262)
		(width 0.18288)
		(layer "In6.Cu")
		(net "M_G_CPU1_SB_DQ<3>")
	)
	(segment
		(start 166.791132 -236.000036)
		(end 166.463472 -236.000036)
		(width 0.18288)
		(layer "In6.Cu")
		(net "M_G_CPU1_SB_DQ<3>")
	)
	(arc
		(start 138.141964 -240.991644)
		(mid 137.954766 -241.041787)
		(end 137.767568 -240.991644)
		(width 0.088646)
		(layer "In6.Cu")
		(net "M_G_CPU1_SB_DQ<3>")
	)
	(arc
		(start 135.322564 -240.991644)
		(mid 135.135366 -241.041787)
		(end 134.948168 -240.991644)
		(width 0.088646)
		(layer "In6.Cu")
		(net "M_G_CPU1_SB_DQ<3>")
	)
	(arc
		(start 133.442964 -240.991644)
		(mid 133.255766 -241.041787)
		(end 133.068568 -240.991644)
		(width 0.088646)
		(layer "In6.Cu")
		(net "M_G_CPU1_SB_DQ<3>")
	)
	(arc
		(start 138.707368 -240.991644)
		(mid 138.424666 -240.915868)
		(end 138.141964 -240.991644)
		(width 0.088646)
		(layer "In6.Cu")
		(net "M_G_CPU1_SB_DQ<3>")
	)
	(arc
		(start 136.827768 -240.991644)
		(mid 136.545066 -240.915868)
		(end 136.262364 -240.991644)
		(width 0.088646)
		(layer "In6.Cu")
		(net "M_G_CPU1_SB_DQ<3>")
	)
	(arc
		(start 132.50291 -240.991644)
		(mid 132.315712 -241.041787)
		(end 132.128514 -240.991644)
		(width 0.088646)
		(layer "In6.Cu")
		(net "M_G_CPU1_SB_DQ<3>")
	)
	(arc
		(start 137.202164 -240.991644)
		(mid 137.014966 -241.041787)
		(end 136.827768 -240.991644)
		(width 0.088646)
		(layer "In6.Cu")
		(net "M_G_CPU1_SB_DQ<3>")
	)
	(arc
		(start 134.948168 -240.991644)
		(mid 134.673969 -240.915809)
		(end 134.397496 -240.983008)
		(width 0.088646)
		(layer "In6.Cu")
		(net "M_G_CPU1_SB_DQ<3>")
	)
	(arc
		(start 134.382764 -240.991644)
		(mid 134.195566 -241.041787)
		(end 134.008368 -240.991644)
		(width 0.088646)
		(layer "In6.Cu")
		(net "M_G_CPU1_SB_DQ<3>")
	)
	(arc
		(start 128.743964 -240.991644)
		(mid 128.556766 -241.041787)
		(end 128.369568 -240.991644)
		(width 0.088646)
		(layer "In6.Cu")
		(net "M_G_CPU1_SB_DQ<3>")
	)
	(arc
		(start 129.683764 -240.991644)
		(mid 129.496566 -241.041787)
		(end 129.309368 -240.991644)
		(width 0.088646)
		(layer "In6.Cu")
		(net "M_G_CPU1_SB_DQ<3>")
	)
	(arc
		(start 133.068568 -240.991644)
		(mid 132.791755 -240.915774)
		(end 132.513324 -240.985548)
		(width 0.088646)
		(layer "In6.Cu")
		(net "M_G_CPU1_SB_DQ<3>")
	)
	(arc
		(start 131.563364 -240.991644)
		(mid 131.376166 -241.041787)
		(end 131.188968 -240.991644)
		(width 0.088646)
		(layer "In6.Cu")
		(net "M_G_CPU1_SB_DQ<3>")
	)
	(arc
		(start 132.128514 -240.991644)
		(mid 131.851955 -240.915901)
		(end 131.573778 -240.985548)
		(width 0.088646)
		(layer "In6.Cu")
		(net "M_G_CPU1_SB_DQ<3>")
	)
	(arc
		(start 137.767568 -240.991644)
		(mid 137.484866 -240.915868)
		(end 137.202164 -240.991644)
		(width 0.088646)
		(layer "In6.Cu")
		(net "M_G_CPU1_SB_DQ<3>")
	)
	(arc
		(start 136.262364 -240.991644)
		(mid 136.075166 -241.041787)
		(end 135.887968 -240.991644)
		(width 0.088646)
		(layer "In6.Cu")
		(net "M_G_CPU1_SB_DQ<3>")
	)
	(arc
		(start 129.309368 -240.991644)
		(mid 129.026666 -240.915868)
		(end 128.743964 -240.991644)
		(width 0.088646)
		(layer "In6.Cu")
		(net "M_G_CPU1_SB_DQ<3>")
	)
	(arc
		(start 131.188968 -240.991644)
		(mid 130.914769 -240.915809)
		(end 130.638296 -240.983008)
		(width 0.088646)
		(layer "In6.Cu")
		(net "M_G_CPU1_SB_DQ<3>")
	)
	(arc
		(start 128.360678 -240.986564)
		(mid 128.244939 -240.87474)
		(end 128.186688 -240.72469)
		(width 0.088646)
		(layer "In6.Cu")
		(net "M_G_CPU1_SB_DQ<3>")
	)
	(arc
		(start 134.008368 -240.991644)
		(mid 133.725666 -240.915868)
		(end 133.442964 -240.991644)
		(width 0.088646)
		(layer "In6.Cu")
		(net "M_G_CPU1_SB_DQ<3>")
	)
	(arc
		(start 130.623564 -240.991644)
		(mid 130.436366 -241.041787)
		(end 130.249168 -240.991644)
		(width 0.088646)
		(layer "In6.Cu")
		(net "M_G_CPU1_SB_DQ<3>")
	)
	(arc
		(start 130.249168 -240.991644)
		(mid 129.974969 -240.915809)
		(end 129.698496 -240.983008)
		(width 0.088646)
		(layer "In6.Cu")
		(net "M_G_CPU1_SB_DQ<3>")
	)
	(arc
		(start 139.081764 -240.991644)
		(mid 138.894566 -241.041787)
		(end 138.707368 -240.991644)
		(width 0.088646)
		(layer "In6.Cu")
		(net "M_G_CPU1_SB_DQ<3>")
	)
	(arc
		(start 135.887968 -240.991644)
		(mid 135.605266 -240.915868)
		(end 135.322564 -240.991644)
		(width 0.088646)
		(layer "In6.Cu")
		(net "M_G_CPU1_SB_DQ<3>")
	)
	(segment
		(start 198.223886 -196.05371)
		(end 198.427848 -195.849748)
		(width 0.20066)
		(layer "F.Cu")
		(net "M_G_CPU1_SB_DQ<31>")
	)
	(segment
		(start 193.088514 -195.616576)
		(end 194.786758 -195.616576)
		(width 0.20066)
		(layer "F.Cu")
		(net "M_G_CPU1_SB_DQ<31>")
	)
	(segment
		(start 198.427848 -195.849748)
		(end 198.427848 -195.598796)
		(width 0.20066)
		(layer "F.Cu")
		(net "M_G_CPU1_SB_DQ<31>")
	)
	(segment
		(start 194.786758 -195.616576)
		(end 195.218812 -196.04863)
		(width 0.20066)
		(layer "F.Cu")
		(net "M_G_CPU1_SB_DQ<31>")
	)
	(segment
		(start 195.515484 -196.04863)
		(end 195.522596 -196.041518)
		(width 0.1016)
		(layer "F.Cu")
		(net "M_G_CPU1_SB_DQ<31>")
	)
	(segment
		(start 198.427848 -195.598796)
		(end 198.662036 -195.364608)
		(width 0.20066)
		(layer "F.Cu")
		(net "M_G_CPU1_SB_DQ<31>")
	)
	(segment
		(start 197.530466 -196.041518)
		(end 197.542658 -196.05371)
		(width 0.1016)
		(layer "F.Cu")
		(net "M_G_CPU1_SB_DQ<31>")
	)
	(segment
		(start 197.542658 -196.05371)
		(end 198.223886 -196.05371)
		(width 0.20066)
		(layer "F.Cu")
		(net "M_G_CPU1_SB_DQ<31>")
	)
	(segment
		(start 137.014966 -216.786206)
		(end 137.014966 -216.25052)
		(width 0.20066)
		(layer "F.Cu")
		(net "M_G_CPU1_SB_DQ<31>")
	)
	(segment
		(start 199.046084 -195.364608)
		(end 199.298052 -195.616576)
		(width 0.20066)
		(layer "F.Cu")
		(net "M_G_CPU1_SB_DQ<31>")
	)
	(segment
		(start 191.983614 -195.616576)
		(end 193.088514 -195.616576)
		(width 0.20066)
		(layer "F.Cu")
		(net "M_G_CPU1_SB_DQ<31>")
	)
	(segment
		(start 195.510658 -196.04863)
		(end 195.515484 -196.04863)
		(width 0.101854)
		(layer "F.Cu")
		(net "M_G_CPU1_SB_DQ<31>")
	)
	(segment
		(start 195.522596 -196.041518)
		(end 197.530466 -196.041518)
		(width 0.1016)
		(layer "F.Cu")
		(net "M_G_CPU1_SB_DQ<31>")
	)
	(segment
		(start 199.298052 -195.616576)
		(end 200.632314 -195.616576)
		(width 0.20066)
		(layer "F.Cu")
		(net "M_G_CPU1_SB_DQ<31>")
	)
	(segment
		(start 137.014712 -216.78646)
		(end 137.014966 -216.786206)
		(width 0.20066)
		(layer "F.Cu")
		(net "M_G_CPU1_SB_DQ<31>")
	)
	(segment
		(start 195.218812 -196.04863)
		(end 195.510658 -196.04863)
		(width 0.20066)
		(layer "F.Cu")
		(net "M_G_CPU1_SB_DQ<31>")
	)
	(segment
		(start 198.662036 -195.364608)
		(end 199.046084 -195.364608)
		(width 0.20066)
		(layer "F.Cu")
		(net "M_G_CPU1_SB_DQ<31>")
	)
	(segment
		(start 186.354212 -193.756788)
		(end 182.393844 -193.749676)
		(width 0.18288)
		(layer "In6.Cu")
		(net "M_G_CPU1_SB_DQ<31>")
	)
	(segment
		(start 190.6143 -195.049394)
		(end 186.354212 -193.756788)
		(width 0.18288)
		(layer "In6.Cu")
		(net "M_G_CPU1_SB_DQ<31>")
	)
	(segment
		(start 146.25193 -205.749906)
		(end 146.25193 -208.108042)
		(width 0.18288)
		(layer "In6.Cu")
		(net "M_G_CPU1_SB_DQ<31>")
	)
	(segment
		(start 137.642346 -215.775032)
		(end 137.015728 -216.24925)
		(width 0.088646)
		(layer "In6.Cu")
		(net "M_G_CPU1_SB_DQ<31>")
	)
	(segment
		(start 182.210202 -194.14871)
		(end 182.20944 -194.497198)
		(width 0.18288)
		(layer "In6.Cu")
		(net "M_G_CPU1_SB_DQ<31>")
	)
	(segment
		(start 181.51602 -194.49542)
		(end 181.516782 -194.14871)
		(width 0.18288)
		(layer "In6.Cu")
		(net "M_G_CPU1_SB_DQ<31>")
	)
	(segment
		(start 139.177776 -215.760554)
		(end 139.167362 -215.754458)
		(width 0.088646)
		(layer "In6.Cu")
		(net "M_G_CPU1_SB_DQ<31>")
	)
	(segment
		(start 157.73908 -194.262756)
		(end 146.25193 -205.749906)
		(width 0.18288)
		(layer "In6.Cu")
		(net "M_G_CPU1_SB_DQ<31>")
	)
	(segment
		(start 182.393844 -193.749676)
		(end 182.21071 -193.932302)
		(width 0.18288)
		(layer "In6.Cu")
		(net "M_G_CPU1_SB_DQ<31>")
	)
	(segment
		(start 137.672064 -215.758014)
		(end 137.642346 -215.775032)
		(width 0.088646)
		(layer "In6.Cu")
		(net "M_G_CPU1_SB_DQ<31>")
	)
	(segment
		(start 137.014966 -216.250012)
		(end 137.014966 -216.25052)
		(width 0.088646)
		(layer "In6.Cu")
		(net "M_G_CPU1_SB_DQ<31>")
	)
	(segment
		(start 181.51729 -193.930524)
		(end 181.334918 -193.747644)
		(width 0.18288)
		(layer "In6.Cu")
		(net "M_G_CPU1_SB_DQ<31>")
	)
	(segment
		(start 182.02656 -194.67957)
		(end 181.698646 -194.678554)
		(width 0.18288)
		(layer "In6.Cu")
		(net "M_G_CPU1_SB_DQ<31>")
	)
	(segment
		(start 162.290506 -194.262756)
		(end 157.73908 -194.262756)
		(width 0.18288)
		(layer "In6.Cu")
		(net "M_G_CPU1_SB_DQ<31>")
	)
	(segment
		(start 181.698646 -194.678554)
		(end 181.51602 -194.49542)
		(width 0.18288)
		(layer "In6.Cu")
		(net "M_G_CPU1_SB_DQ<31>")
	)
	(segment
		(start 139.186158 -215.76538)
		(end 139.177776 -215.760554)
		(width 0.088646)
		(layer "In6.Cu")
		(net "M_G_CPU1_SB_DQ<31>")
	)
	(segment
		(start 191.983614 -195.616576)
		(end 190.6143 -195.049394)
		(width 0.18288)
		(layer "In6.Cu")
		(net "M_G_CPU1_SB_DQ<31>")
	)
	(segment
		(start 137.672318 -215.758014)
		(end 137.672064 -215.758014)
		(width 0.088646)
		(layer "In6.Cu")
		(net "M_G_CPU1_SB_DQ<31>")
	)
	(segment
		(start 162.839908 -193.713354)
		(end 162.290506 -194.262756)
		(width 0.18288)
		(layer "In6.Cu")
		(net "M_G_CPU1_SB_DQ<31>")
	)
	(segment
		(start 138.24204 -215.760554)
		(end 138.237722 -215.758014)
		(width 0.088646)
		(layer "In6.Cu")
		(net "M_G_CPU1_SB_DQ<31>")
	)
	(segment
		(start 137.015728 -216.24925)
		(end 137.014966 -216.250012)
		(width 0.088646)
		(layer "In6.Cu")
		(net "M_G_CPU1_SB_DQ<31>")
	)
	(segment
		(start 181.516782 -194.14871)
		(end 181.51729 -193.930524)
		(width 0.18288)
		(layer "In6.Cu")
		(net "M_G_CPU1_SB_DQ<31>")
	)
	(segment
		(start 182.20944 -194.497198)
		(end 182.02656 -194.67957)
		(width 0.18288)
		(layer "In6.Cu")
		(net "M_G_CPU1_SB_DQ<31>")
	)
	(segment
		(start 182.21071 -193.932302)
		(end 182.210202 -194.14871)
		(width 0.18288)
		(layer "In6.Cu")
		(net "M_G_CPU1_SB_DQ<31>")
	)
	(segment
		(start 181.334918 -193.747644)
		(end 162.839908 -193.713354)
		(width 0.18288)
		(layer "In6.Cu")
		(net "M_G_CPU1_SB_DQ<31>")
	)
	(segment
		(start 140.029438 -215.490044)
		(end 139.834874 -215.684608)
		(width 0.088646)
		(layer "In6.Cu")
		(net "M_G_CPU1_SB_DQ<31>")
	)
	(segment
		(start 140.029438 -214.330534)
		(end 140.029438 -215.490044)
		(width 0.088646)
		(layer "In6.Cu")
		(net "M_G_CPU1_SB_DQ<31>")
	)
	(segment
		(start 140.143484 -214.216488)
		(end 140.029438 -214.330534)
		(width 0.088646)
		(layer "In6.Cu")
		(net "M_G_CPU1_SB_DQ<31>")
	)
	(segment
		(start 146.25193 -208.108042)
		(end 140.143484 -214.216488)
		(width 0.18288)
		(layer "In6.Cu")
		(net "M_G_CPU1_SB_DQ<31>")
	)
	(arc
		(start 138.237722 -215.758014)
		(mid 137.95502 -215.682204)
		(end 137.672318 -215.758014)
		(width 0.088646)
		(layer "In6.Cu")
		(net "M_G_CPU1_SB_DQ<31>")
	)
	(arc
		(start 139.551918 -215.760554)
		(mid 139.369667 -215.810733)
		(end 139.186158 -215.76538)
		(width 0.088646)
		(layer "In6.Cu")
		(net "M_G_CPU1_SB_DQ<31>")
	)
	(arc
		(start 139.167362 -215.754458)
		(mid 138.88893 -215.684581)
		(end 138.612118 -215.760554)
		(width 0.088646)
		(layer "In6.Cu")
		(net "M_G_CPU1_SB_DQ<31>")
	)
	(arc
		(start 139.834874 -215.684608)
		(mid 139.688387 -215.703923)
		(end 139.551918 -215.760554)
		(width 0.088646)
		(layer "In6.Cu")
		(net "M_G_CPU1_SB_DQ<31>")
	)
	(arc
		(start 138.612118 -215.760554)
		(mid 138.427096 -215.810099)
		(end 138.24204 -215.760554)
		(width 0.088646)
		(layer "In6.Cu")
		(net "M_G_CPU1_SB_DQ<31>")
	)
	(segment
		(start 195.218812 -197.748652)
		(end 195.510658 -197.748652)
		(width 0.20066)
		(layer "F.Cu")
		(net "M_G_CPU1_SB_DQ<30>")
	)
	(segment
		(start 199.046084 -197.06463)
		(end 199.298052 -197.316598)
		(width 0.20066)
		(layer "F.Cu")
		(net "M_G_CPU1_SB_DQ<30>")
	)
	(segment
		(start 199.298052 -197.316598)
		(end 200.632314 -197.316598)
		(width 0.20066)
		(layer "F.Cu")
		(net "M_G_CPU1_SB_DQ<30>")
	)
	(segment
		(start 195.515484 -197.748652)
		(end 195.522596 -197.74154)
		(width 0.1016)
		(layer "F.Cu")
		(net "M_G_CPU1_SB_DQ<30>")
	)
	(segment
		(start 193.088514 -197.316598)
		(end 194.786758 -197.316598)
		(width 0.20066)
		(layer "F.Cu")
		(net "M_G_CPU1_SB_DQ<30>")
	)
	(segment
		(start 137.954766 -216.25052)
		(end 137.954766 -216.78646)
		(width 0.20066)
		(layer "F.Cu")
		(net "M_G_CPU1_SB_DQ<30>")
	)
	(segment
		(start 194.786758 -197.316598)
		(end 195.218812 -197.748652)
		(width 0.20066)
		(layer "F.Cu")
		(net "M_G_CPU1_SB_DQ<30>")
	)
	(segment
		(start 198.427848 -197.298818)
		(end 198.662036 -197.06463)
		(width 0.20066)
		(layer "F.Cu")
		(net "M_G_CPU1_SB_DQ<30>")
	)
	(segment
		(start 195.522596 -197.74154)
		(end 197.530466 -197.74154)
		(width 0.1016)
		(layer "F.Cu")
		(net "M_G_CPU1_SB_DQ<30>")
	)
	(segment
		(start 195.510658 -197.748652)
		(end 195.515484 -197.748652)
		(width 0.101854)
		(layer "F.Cu")
		(net "M_G_CPU1_SB_DQ<30>")
	)
	(segment
		(start 197.542658 -197.753732)
		(end 198.223886 -197.753732)
		(width 0.20066)
		(layer "F.Cu")
		(net "M_G_CPU1_SB_DQ<30>")
	)
	(segment
		(start 198.223886 -197.753732)
		(end 198.427848 -197.54977)
		(width 0.20066)
		(layer "F.Cu")
		(net "M_G_CPU1_SB_DQ<30>")
	)
	(segment
		(start 198.662036 -197.06463)
		(end 199.046084 -197.06463)
		(width 0.20066)
		(layer "F.Cu")
		(net "M_G_CPU1_SB_DQ<30>")
	)
	(segment
		(start 191.983614 -197.316598)
		(end 193.088514 -197.316598)
		(width 0.20066)
		(layer "F.Cu")
		(net "M_G_CPU1_SB_DQ<30>")
	)
	(segment
		(start 197.530466 -197.74154)
		(end 197.542658 -197.753732)
		(width 0.1016)
		(layer "F.Cu")
		(net "M_G_CPU1_SB_DQ<30>")
	)
	(segment
		(start 198.427848 -197.54977)
		(end 198.427848 -197.298818)
		(width 0.20066)
		(layer "F.Cu")
		(net "M_G_CPU1_SB_DQ<30>")
	)
	(segment
		(start 183.354218 -196.04228)
		(end 176.33188 -196.04228)
		(width 0.18288)
		(layer "In6.Cu")
		(net "M_G_CPU1_SB_DQ<30>")
	)
	(segment
		(start 163.298886 -195.350892)
		(end 163.298886 -195.780406)
		(width 0.18288)
		(layer "In6.Cu")
		(net "M_G_CPU1_SB_DQ<30>")
	)
	(segment
		(start 167.621458 -196.143626)
		(end 166.967662 -196.143626)
		(width 0.18288)
		(layer "In6.Cu")
		(net "M_G_CPU1_SB_DQ<30>")
	)
	(segment
		(start 161.007044 -196.050408)
		(end 157.486096 -196.050408)
		(width 0.18288)
		(layer "In6.Cu")
		(net "M_G_CPU1_SB_DQ<30>")
	)
	(segment
		(start 165.908482 -196.143626)
		(end 164.800026 -196.143626)
		(width 0.18288)
		(layer "In6.Cu")
		(net "M_G_CPU1_SB_DQ<30>")
	)
	(segment
		(start 164.596826 -195.940426)
		(end 164.152326 -195.940426)
		(width 0.18288)
		(layer "In6.Cu")
		(net "M_G_CPU1_SB_DQ<30>")
	)
	(segment
		(start 191.97447 -197.321424)
		(end 190.557912 -196.892672)
		(width 0.18288)
		(layer "In6.Cu")
		(net "M_G_CPU1_SB_DQ<30>")
	)
	(segment
		(start 163.992306 -195.350892)
		(end 163.832286 -195.190872)
		(width 0.18288)
		(layer "In6.Cu")
		(net "M_G_CPU1_SB_DQ<30>")
	)
	(segment
		(start 164.152326 -195.940426)
		(end 163.992306 -195.780406)
		(width 0.18288)
		(layer "In6.Cu")
		(net "M_G_CPU1_SB_DQ<30>")
	)
	(segment
		(start 140.877036 -214.95004)
		(end 140.705078 -215.121998)
		(width 0.088646)
		(layer "In6.Cu")
		(net "M_G_CPU1_SB_DQ<30>")
	)
	(segment
		(start 184.20461 -196.892672)
		(end 183.354218 -196.04228)
		(width 0.18288)
		(layer "In6.Cu")
		(net "M_G_CPU1_SB_DQ<30>")
	)
	(segment
		(start 163.832286 -195.190872)
		(end 163.458906 -195.190872)
		(width 0.18288)
		(layer "In6.Cu")
		(net "M_G_CPU1_SB_DQ<30>")
	)
	(segment
		(start 163.458906 -195.190872)
		(end 163.298886 -195.350892)
		(width 0.18288)
		(layer "In6.Cu")
		(net "M_G_CPU1_SB_DQ<30>")
	)
	(segment
		(start 166.784782 -195.471796)
		(end 166.601902 -195.288916)
		(width 0.18288)
		(layer "In6.Cu")
		(net "M_G_CPU1_SB_DQ<30>")
	)
	(segment
		(start 140.021818 -216.574116)
		(end 140.00988 -216.581228)
		(width 0.088646)
		(layer "In6.Cu")
		(net "M_G_CPU1_SB_DQ<30>")
	)
	(segment
		(start 161.117026 -195.940426)
		(end 161.007044 -196.050408)
		(width 0.18288)
		(layer "In6.Cu")
		(net "M_G_CPU1_SB_DQ<30>")
	)
	(segment
		(start 166.784782 -195.960746)
		(end 166.784782 -195.471796)
		(width 0.18288)
		(layer "In6.Cu")
		(net "M_G_CPU1_SB_DQ<30>")
	)
	(segment
		(start 166.091362 -195.960746)
		(end 165.908482 -196.143626)
		(width 0.18288)
		(layer "In6.Cu")
		(net "M_G_CPU1_SB_DQ<30>")
	)
	(segment
		(start 166.967662 -196.143626)
		(end 166.784782 -195.960746)
		(width 0.18288)
		(layer "In6.Cu")
		(net "M_G_CPU1_SB_DQ<30>")
	)
	(segment
		(start 168.054274 -195.71081)
		(end 167.621458 -196.143626)
		(width 0.18288)
		(layer "In6.Cu")
		(net "M_G_CPU1_SB_DQ<30>")
	)
	(segment
		(start 176.33188 -196.04228)
		(end 175.481996 -195.192396)
		(width 0.18288)
		(layer "In6.Cu")
		(net "M_G_CPU1_SB_DQ<30>")
	)
	(segment
		(start 140.705078 -216.097612)
		(end 140.304012 -216.498678)
		(width 0.088646)
		(layer "In6.Cu")
		(net "M_G_CPU1_SB_DQ<30>")
	)
	(segment
		(start 138.679682 -216.55786)
		(end 137.958576 -216.25433)
		(width 0.088646)
		(layer "In6.Cu")
		(net "M_G_CPU1_SB_DQ<30>")
	)
	(segment
		(start 166.274242 -195.288916)
		(end 166.091362 -195.471796)
		(width 0.18288)
		(layer "In6.Cu")
		(net "M_G_CPU1_SB_DQ<30>")
	)
	(segment
		(start 166.091362 -195.471796)
		(end 166.091362 -195.960746)
		(width 0.18288)
		(layer "In6.Cu")
		(net "M_G_CPU1_SB_DQ<30>")
	)
	(segment
		(start 163.298886 -195.780406)
		(end 163.138866 -195.940426)
		(width 0.18288)
		(layer "In6.Cu")
		(net "M_G_CPU1_SB_DQ<30>")
	)
	(segment
		(start 137.958576 -216.25433)
		(end 137.954766 -216.25052)
		(width 0.088646)
		(layer "In6.Cu")
		(net "M_G_CPU1_SB_DQ<30>")
	)
	(segment
		(start 163.992306 -195.780406)
		(end 163.992306 -195.350892)
		(width 0.18288)
		(layer "In6.Cu")
		(net "M_G_CPU1_SB_DQ<30>")
	)
	(segment
		(start 157.486096 -196.050408)
		(end 147.31619 -206.245206)
		(width 0.18288)
		(layer "In6.Cu")
		(net "M_G_CPU1_SB_DQ<30>")
	)
	(segment
		(start 163.138866 -195.940426)
		(end 161.117026 -195.940426)
		(width 0.18288)
		(layer "In6.Cu")
		(net "M_G_CPU1_SB_DQ<30>")
	)
	(segment
		(start 139.082018 -216.57437)
		(end 139.07008 -216.581228)
		(width 0.088646)
		(layer "In6.Cu")
		(net "M_G_CPU1_SB_DQ<30>")
	)
	(segment
		(start 172.025056 -195.192396)
		(end 171.861226 -195.356226)
		(width 0.18288)
		(layer "In6.Cu")
		(net "M_G_CPU1_SB_DQ<30>")
	)
	(segment
		(start 169.237406 -195.356226)
		(end 168.054274 -195.71081)
		(width 0.18288)
		(layer "In6.Cu")
		(net "M_G_CPU1_SB_DQ<30>")
	)
	(segment
		(start 190.557912 -196.892672)
		(end 184.20461 -196.892672)
		(width 0.18288)
		(layer "In6.Cu")
		(net "M_G_CPU1_SB_DQ<30>")
	)
	(segment
		(start 175.481996 -195.192396)
		(end 172.025056 -195.192396)
		(width 0.18288)
		(layer "In6.Cu")
		(net "M_G_CPU1_SB_DQ<30>")
	)
	(segment
		(start 166.601902 -195.288916)
		(end 166.274242 -195.288916)
		(width 0.18288)
		(layer "In6.Cu")
		(net "M_G_CPU1_SB_DQ<30>")
	)
	(segment
		(start 164.800026 -196.143626)
		(end 164.596826 -195.940426)
		(width 0.18288)
		(layer "In6.Cu")
		(net "M_G_CPU1_SB_DQ<30>")
	)
	(segment
		(start 191.983614 -197.316598)
		(end 191.97447 -197.321424)
		(width 0.18288)
		(layer "In6.Cu")
		(net "M_G_CPU1_SB_DQ<30>")
	)
	(segment
		(start 147.318984 -208.493868)
		(end 140.877036 -214.95004)
		(width 0.18288)
		(layer "In6.Cu")
		(net "M_G_CPU1_SB_DQ<30>")
	)
	(segment
		(start 171.861226 -195.356226)
		(end 169.237406 -195.356226)
		(width 0.18288)
		(layer "In6.Cu")
		(net "M_G_CPU1_SB_DQ<30>")
	)
	(segment
		(start 147.31619 -206.245206)
		(end 147.318984 -208.493868)
		(width 0.18288)
		(layer "In6.Cu")
		(net "M_G_CPU1_SB_DQ<30>")
	)
	(segment
		(start 138.707622 -216.57437)
		(end 138.679682 -216.55786)
		(width 0.088646)
		(layer "In6.Cu")
		(net "M_G_CPU1_SB_DQ<30>")
	)
	(segment
		(start 140.705078 -215.121998)
		(end 140.705078 -216.097612)
		(width 0.088646)
		(layer "In6.Cu")
		(net "M_G_CPU1_SB_DQ<30>")
	)
	(segment
		(start 139.09675 -216.565734)
		(end 139.082018 -216.57437)
		(width 0.088646)
		(layer "In6.Cu")
		(net "M_G_CPU1_SB_DQ<30>")
	)
	(arc
		(start 139.07008 -216.581228)
		(mid 138.887969 -216.624523)
		(end 138.707622 -216.57437)
		(width 0.088646)
		(layer "In6.Cu")
		(net "M_G_CPU1_SB_DQ<30>")
	)
	(arc
		(start 140.304012 -216.498678)
		(mid 140.157958 -216.517859)
		(end 140.021818 -216.574116)
		(width 0.088646)
		(layer "In6.Cu")
		(net "M_G_CPU1_SB_DQ<30>")
	)
	(arc
		(start 140.00988 -216.581228)
		(mid 139.827769 -216.624523)
		(end 139.647422 -216.57437)
		(width 0.088646)
		(layer "In6.Cu")
		(net "M_G_CPU1_SB_DQ<30>")
	)
	(arc
		(start 139.647422 -216.57437)
		(mid 139.373193 -216.498479)
		(end 139.09675 -216.565734)
		(width 0.088646)
		(layer "In6.Cu")
		(net "M_G_CPU1_SB_DQ<30>")
	)
	(segment
		(start 128.086866 -242.017042)
		(end 128.086612 -242.016788)
		(width 0.20066)
		(layer "F.Cu")
		(net "M_G_CPU1_SB_DQ<2>")
	)
	(segment
		(start 194.786758 -231.316784)
		(end 195.218812 -231.748838)
		(width 0.20066)
		(layer "F.Cu")
		(net "M_G_CPU1_SB_DQ<2>")
	)
	(segment
		(start 195.522596 -231.741726)
		(end 197.530466 -231.741726)
		(width 0.1016)
		(layer "F.Cu")
		(net "M_G_CPU1_SB_DQ<2>")
	)
	(segment
		(start 198.223886 -231.753918)
		(end 198.427848 -231.549956)
		(width 0.20066)
		(layer "F.Cu")
		(net "M_G_CPU1_SB_DQ<2>")
	)
	(segment
		(start 128.086612 -242.016788)
		(end 128.086612 -241.481102)
		(width 0.20066)
		(layer "F.Cu")
		(net "M_G_CPU1_SB_DQ<2>")
	)
	(segment
		(start 199.046084 -231.064816)
		(end 199.298052 -231.316784)
		(width 0.20066)
		(layer "F.Cu")
		(net "M_G_CPU1_SB_DQ<2>")
	)
	(segment
		(start 198.427848 -231.299004)
		(end 198.662036 -231.064816)
		(width 0.20066)
		(layer "F.Cu")
		(net "M_G_CPU1_SB_DQ<2>")
	)
	(segment
		(start 193.088514 -231.316784)
		(end 194.786758 -231.316784)
		(width 0.20066)
		(layer "F.Cu")
		(net "M_G_CPU1_SB_DQ<2>")
	)
	(segment
		(start 195.218812 -231.748838)
		(end 195.510658 -231.748838)
		(width 0.20066)
		(layer "F.Cu")
		(net "M_G_CPU1_SB_DQ<2>")
	)
	(segment
		(start 197.530466 -231.741726)
		(end 197.542658 -231.753918)
		(width 0.1016)
		(layer "F.Cu")
		(net "M_G_CPU1_SB_DQ<2>")
	)
	(segment
		(start 195.510658 -231.748838)
		(end 195.515484 -231.748838)
		(width 0.101854)
		(layer "F.Cu")
		(net "M_G_CPU1_SB_DQ<2>")
	)
	(segment
		(start 198.662036 -231.064816)
		(end 199.046084 -231.064816)
		(width 0.20066)
		(layer "F.Cu")
		(net "M_G_CPU1_SB_DQ<2>")
	)
	(segment
		(start 197.542658 -231.753918)
		(end 198.223886 -231.753918)
		(width 0.20066)
		(layer "F.Cu")
		(net "M_G_CPU1_SB_DQ<2>")
	)
	(segment
		(start 191.983614 -231.316784)
		(end 193.088514 -231.316784)
		(width 0.20066)
		(layer "F.Cu")
		(net "M_G_CPU1_SB_DQ<2>")
	)
	(segment
		(start 195.515484 -231.748838)
		(end 195.522596 -231.741726)
		(width 0.1016)
		(layer "F.Cu")
		(net "M_G_CPU1_SB_DQ<2>")
	)
	(segment
		(start 199.298052 -231.316784)
		(end 200.632314 -231.316784)
		(width 0.20066)
		(layer "F.Cu")
		(net "M_G_CPU1_SB_DQ<2>")
	)
	(segment
		(start 198.427848 -231.549956)
		(end 198.427848 -231.299004)
		(width 0.20066)
		(layer "F.Cu")
		(net "M_G_CPU1_SB_DQ<2>")
	)
	(segment
		(start 188.488066 -231.559354)
		(end 188.305186 -231.742234)
		(width 0.18288)
		(layer "In6.Cu")
		(net "M_G_CPU1_SB_DQ<2>")
	)
	(segment
		(start 186.453018 -231.742234)
		(end 185.780426 -232.414826)
		(width 0.18288)
		(layer "In6.Cu")
		(net "M_G_CPU1_SB_DQ<2>")
	)
	(segment
		(start 191.057784 -231.316784)
		(end 190.632334 -231.742234)
		(width 0.18288)
		(layer "In6.Cu")
		(net "M_G_CPU1_SB_DQ<2>")
	)
	(segment
		(start 189.181486 -231.559354)
		(end 189.181486 -231.23271)
		(width 0.18288)
		(layer "In6.Cu")
		(net "M_G_CPU1_SB_DQ<2>")
	)
	(segment
		(start 135.418068 -241.80546)
		(end 135.407654 -241.799364)
		(width 0.088646)
		(layer "In6.Cu")
		(net "M_G_CPU1_SB_DQ<2>")
	)
	(segment
		(start 158.542228 -237.063026)
		(end 152.996646 -237.063026)
		(width 0.18288)
		(layer "In6.Cu")
		(net "M_G_CPU1_SB_DQ<2>")
	)
	(segment
		(start 159.555688 -237.063026)
		(end 159.395668 -236.903006)
		(width 0.18288)
		(layer "In6.Cu")
		(net "M_G_CPU1_SB_DQ<2>")
	)
	(segment
		(start 148.501862 -241.55781)
		(end 140.442696 -241.55781)
		(width 0.18288)
		(layer "In6.Cu")
		(net "M_G_CPU1_SB_DQ<2>")
	)
	(segment
		(start 170.69181 -238.238538)
		(end 170.36415 -238.238538)
		(width 0.18288)
		(layer "In6.Cu")
		(net "M_G_CPU1_SB_DQ<2>")
	)
	(segment
		(start 139.336018 -241.94008)
		(end 139.224258 -241.82832)
		(width 0.088646)
		(layer "In6.Cu")
		(net "M_G_CPU1_SB_DQ<2>")
	)
	(segment
		(start 171.05757 -237.444026)
		(end 170.87469 -237.626906)
		(width 0.18288)
		(layer "In6.Cu")
		(net "M_G_CPU1_SB_DQ<2>")
	)
	(segment
		(start 190.632334 -231.742234)
		(end 189.364366 -231.742234)
		(width 0.18288)
		(layer "In6.Cu")
		(net "M_G_CPU1_SB_DQ<2>")
	)
	(segment
		(start 158.702248 -236.903006)
		(end 158.542228 -237.063026)
		(width 0.18288)
		(layer "In6.Cu")
		(net "M_G_CPU1_SB_DQ<2>")
	)
	(segment
		(start 170.18127 -237.626906)
		(end 169.99839 -237.444026)
		(width 0.18288)
		(layer "In6.Cu")
		(net "M_G_CPU1_SB_DQ<2>")
	)
	(segment
		(start 159.395668 -236.371892)
		(end 159.235648 -236.211872)
		(width 0.18288)
		(layer "In6.Cu")
		(net "M_G_CPU1_SB_DQ<2>")
	)
	(segment
		(start 170.36415 -238.238538)
		(end 170.18127 -238.055658)
		(width 0.18288)
		(layer "In6.Cu")
		(net "M_G_CPU1_SB_DQ<2>")
	)
	(segment
		(start 177.587148 -236.83849)
		(end 174.408338 -236.83849)
		(width 0.18288)
		(layer "In6.Cu")
		(net "M_G_CPU1_SB_DQ<2>")
	)
	(segment
		(start 185.780426 -233.14787)
		(end 183.021224 -235.907072)
		(width 0.18288)
		(layer "In6.Cu")
		(net "M_G_CPU1_SB_DQ<2>")
	)
	(segment
		(start 140.442696 -241.55781)
		(end 140.19149 -241.55781)
		(width 0.088646)
		(layer "In6.Cu")
		(net "M_G_CPU1_SB_DQ<2>")
	)
	(segment
		(start 177.760884 -237.012226)
		(end 177.587148 -236.83849)
		(width 0.18288)
		(layer "In6.Cu")
		(net "M_G_CPU1_SB_DQ<2>")
	)
	(segment
		(start 172.24502 -237.691422)
		(end 171.997624 -237.444026)
		(width 0.18288)
		(layer "In6.Cu")
		(net "M_G_CPU1_SB_DQ<2>")
	)
	(segment
		(start 188.670946 -231.04983)
		(end 188.488066 -231.23271)
		(width 0.18288)
		(layer "In6.Cu")
		(net "M_G_CPU1_SB_DQ<2>")
	)
	(segment
		(start 173.555406 -237.691422)
		(end 172.24502 -237.691422)
		(width 0.18288)
		(layer "In6.Cu")
		(net "M_G_CPU1_SB_DQ<2>")
	)
	(segment
		(start 130.718814 -241.80546)
		(end 130.704082 -241.796824)
		(width 0.088646)
		(layer "In6.Cu")
		(net "M_G_CPU1_SB_DQ<2>")
	)
	(segment
		(start 188.998606 -231.04983)
		(end 188.670946 -231.04983)
		(width 0.18288)
		(layer "In6.Cu")
		(net "M_G_CPU1_SB_DQ<2>")
	)
	(segment
		(start 189.364366 -231.742234)
		(end 189.181486 -231.559354)
		(width 0.18288)
		(layer "In6.Cu")
		(net "M_G_CPU1_SB_DQ<2>")
	)
	(segment
		(start 189.181486 -231.23271)
		(end 188.998606 -231.04983)
		(width 0.18288)
		(layer "In6.Cu")
		(net "M_G_CPU1_SB_DQ<2>")
	)
	(segment
		(start 174.408338 -236.83849)
		(end 173.555406 -237.691422)
		(width 0.18288)
		(layer "In6.Cu")
		(net "M_G_CPU1_SB_DQ<2>")
	)
	(segment
		(start 159.395668 -236.903006)
		(end 159.395668 -236.371892)
		(width 0.18288)
		(layer "In6.Cu")
		(net "M_G_CPU1_SB_DQ<2>")
	)
	(segment
		(start 127.899414 -241.80546)
		(end 127.890524 -241.80038)
		(width 0.088646)
		(layer "In6.Cu")
		(net "M_G_CPU1_SB_DQ<2>")
	)
	(segment
		(start 152.996646 -237.063026)
		(end 148.501862 -241.55781)
		(width 0.18288)
		(layer "In6.Cu")
		(net "M_G_CPU1_SB_DQ<2>")
	)
	(segment
		(start 170.87469 -237.626906)
		(end 170.87469 -238.055658)
		(width 0.18288)
		(layer "In6.Cu")
		(net "M_G_CPU1_SB_DQ<2>")
	)
	(segment
		(start 127.716534 -241.538506)
		(end 127.773938 -241.481102)
		(width 0.088646)
		(layer "In6.Cu")
		(net "M_G_CPU1_SB_DQ<2>")
	)
	(segment
		(start 181.90718 -235.907072)
		(end 180.802026 -237.012226)
		(width 0.18288)
		(layer "In6.Cu")
		(net "M_G_CPU1_SB_DQ<2>")
	)
	(segment
		(start 169.99839 -237.444026)
		(end 165.560502 -237.444026)
		(width 0.18288)
		(layer "In6.Cu")
		(net "M_G_CPU1_SB_DQ<2>")
	)
	(segment
		(start 140.19149 -241.55781)
		(end 139.80922 -241.94008)
		(width 0.088646)
		(layer "In6.Cu")
		(net "M_G_CPU1_SB_DQ<2>")
	)
	(segment
		(start 133.538468 -241.80546)
		(end 133.528054 -241.799364)
		(width 0.088646)
		(layer "In6.Cu")
		(net "M_G_CPU1_SB_DQ<2>")
	)
	(segment
		(start 158.862268 -236.211872)
		(end 158.702248 -236.371892)
		(width 0.18288)
		(layer "In6.Cu")
		(net "M_G_CPU1_SB_DQ<2>")
	)
	(segment
		(start 134.478014 -241.80546)
		(end 134.4676 -241.799364)
		(width 0.088646)
		(layer "In6.Cu")
		(net "M_G_CPU1_SB_DQ<2>")
	)
	(segment
		(start 129.779014 -241.80546)
		(end 129.7686 -241.799364)
		(width 0.088646)
		(layer "In6.Cu")
		(net "M_G_CPU1_SB_DQ<2>")
	)
	(segment
		(start 165.560502 -237.444026)
		(end 165.179502 -237.063026)
		(width 0.18288)
		(layer "In6.Cu")
		(net "M_G_CPU1_SB_DQ<2>")
	)
	(segment
		(start 188.305186 -231.742234)
		(end 186.453018 -231.742234)
		(width 0.18288)
		(layer "In6.Cu")
		(net "M_G_CPU1_SB_DQ<2>")
	)
	(segment
		(start 191.983614 -231.316784)
		(end 191.057784 -231.316784)
		(width 0.18288)
		(layer "In6.Cu")
		(net "M_G_CPU1_SB_DQ<2>")
	)
	(segment
		(start 139.80922 -241.94008)
		(end 139.336018 -241.94008)
		(width 0.088646)
		(layer "In6.Cu")
		(net "M_G_CPU1_SB_DQ<2>")
	)
	(segment
		(start 188.488066 -231.23271)
		(end 188.488066 -231.559354)
		(width 0.18288)
		(layer "In6.Cu")
		(net "M_G_CPU1_SB_DQ<2>")
	)
	(segment
		(start 183.021224 -235.907072)
		(end 181.90718 -235.907072)
		(width 0.18288)
		(layer "In6.Cu")
		(net "M_G_CPU1_SB_DQ<2>")
	)
	(segment
		(start 131.658614 -241.80546)
		(end 131.643882 -241.796824)
		(width 0.088646)
		(layer "In6.Cu")
		(net "M_G_CPU1_SB_DQ<2>")
	)
	(segment
		(start 185.780426 -232.414826)
		(end 185.780426 -233.14787)
		(width 0.18288)
		(layer "In6.Cu")
		(net "M_G_CPU1_SB_DQ<2>")
	)
	(segment
		(start 170.87469 -238.055658)
		(end 170.69181 -238.238538)
		(width 0.18288)
		(layer "In6.Cu")
		(net "M_G_CPU1_SB_DQ<2>")
	)
	(segment
		(start 165.179502 -237.063026)
		(end 159.555688 -237.063026)
		(width 0.18288)
		(layer "In6.Cu")
		(net "M_G_CPU1_SB_DQ<2>")
	)
	(segment
		(start 170.18127 -238.055658)
		(end 170.18127 -237.626906)
		(width 0.18288)
		(layer "In6.Cu")
		(net "M_G_CPU1_SB_DQ<2>")
	)
	(segment
		(start 127.773938 -241.481102)
		(end 128.086612 -241.481102)
		(width 0.088646)
		(layer "In6.Cu")
		(net "M_G_CPU1_SB_DQ<2>")
	)
	(segment
		(start 132.598414 -241.80546)
		(end 132.583682 -241.796824)
		(width 0.088646)
		(layer "In6.Cu")
		(net "M_G_CPU1_SB_DQ<2>")
	)
	(segment
		(start 180.802026 -237.012226)
		(end 177.760884 -237.012226)
		(width 0.18288)
		(layer "In6.Cu")
		(net "M_G_CPU1_SB_DQ<2>")
	)
	(segment
		(start 158.702248 -236.371892)
		(end 158.702248 -236.903006)
		(width 0.18288)
		(layer "In6.Cu")
		(net "M_G_CPU1_SB_DQ<2>")
	)
	(segment
		(start 159.235648 -236.211872)
		(end 158.862268 -236.211872)
		(width 0.18288)
		(layer "In6.Cu")
		(net "M_G_CPU1_SB_DQ<2>")
	)
	(segment
		(start 171.997624 -237.444026)
		(end 171.05757 -237.444026)
		(width 0.18288)
		(layer "In6.Cu")
		(net "M_G_CPU1_SB_DQ<2>")
	)
	(segment
		(start 128.839468 -241.80546)
		(end 128.829054 -241.799364)
		(width 0.088646)
		(layer "In6.Cu")
		(net "M_G_CPU1_SB_DQ<2>")
	)
	(arc
		(start 137.297668 -241.80546)
		(mid 137.014966 -241.729684)
		(end 136.732264 -241.80546)
		(width 0.088646)
		(layer "In6.Cu")
		(net "M_G_CPU1_SB_DQ<2>")
	)
	(arc
		(start 132.583682 -241.796824)
		(mid 132.307207 -241.729504)
		(end 132.03301 -241.80546)
		(width 0.088646)
		(layer "In6.Cu")
		(net "M_G_CPU1_SB_DQ<2>")
	)
	(arc
		(start 134.4676 -241.799364)
		(mid 134.189422 -241.729641)
		(end 133.912864 -241.80546)
		(width 0.088646)
		(layer "In6.Cu")
		(net "M_G_CPU1_SB_DQ<2>")
	)
	(arc
		(start 131.643882 -241.796824)
		(mid 131.367407 -241.729504)
		(end 131.09321 -241.80546)
		(width 0.088646)
		(layer "In6.Cu")
		(net "M_G_CPU1_SB_DQ<2>")
	)
	(arc
		(start 130.704082 -241.796824)
		(mid 130.427607 -241.729504)
		(end 130.15341 -241.80546)
		(width 0.088646)
		(layer "In6.Cu")
		(net "M_G_CPU1_SB_DQ<2>")
	)
	(arc
		(start 130.15341 -241.80546)
		(mid 129.966212 -241.855603)
		(end 129.779014 -241.80546)
		(width 0.088646)
		(layer "In6.Cu")
		(net "M_G_CPU1_SB_DQ<2>")
	)
	(arc
		(start 127.890524 -241.80038)
		(mid 127.774785 -241.688556)
		(end 127.716534 -241.538506)
		(width 0.088646)
		(layer "In6.Cu")
		(net "M_G_CPU1_SB_DQ<2>")
	)
	(arc
		(start 133.528054 -241.799364)
		(mid 133.249622 -241.729518)
		(end 132.97281 -241.80546)
		(width 0.088646)
		(layer "In6.Cu")
		(net "M_G_CPU1_SB_DQ<2>")
	)
	(arc
		(start 138.237468 -241.80546)
		(mid 137.954766 -241.729684)
		(end 137.672064 -241.80546)
		(width 0.088646)
		(layer "In6.Cu")
		(net "M_G_CPU1_SB_DQ<2>")
	)
	(arc
		(start 128.829054 -241.799364)
		(mid 128.550622 -241.729518)
		(end 128.27381 -241.80546)
		(width 0.088646)
		(layer "In6.Cu")
		(net "M_G_CPU1_SB_DQ<2>")
	)
	(arc
		(start 136.357868 -241.80546)
		(mid 136.075166 -241.729684)
		(end 135.792464 -241.80546)
		(width 0.088646)
		(layer "In6.Cu")
		(net "M_G_CPU1_SB_DQ<2>")
	)
	(arc
		(start 135.792464 -241.80546)
		(mid 135.605266 -241.855603)
		(end 135.418068 -241.80546)
		(width 0.088646)
		(layer "In6.Cu")
		(net "M_G_CPU1_SB_DQ<2>")
	)
	(arc
		(start 136.732264 -241.80546)
		(mid 136.545066 -241.855603)
		(end 136.357868 -241.80546)
		(width 0.088646)
		(layer "In6.Cu")
		(net "M_G_CPU1_SB_DQ<2>")
	)
	(arc
		(start 131.09321 -241.80546)
		(mid 130.906012 -241.855603)
		(end 130.718814 -241.80546)
		(width 0.088646)
		(layer "In6.Cu")
		(net "M_G_CPU1_SB_DQ<2>")
	)
	(arc
		(start 139.224258 -241.82832)
		(mid 139.200363 -241.817712)
		(end 139.177268 -241.80546)
		(width 0.088646)
		(layer "In6.Cu")
		(net "M_G_CPU1_SB_DQ<2>")
	)
	(arc
		(start 134.85241 -241.80546)
		(mid 134.665212 -241.855603)
		(end 134.478014 -241.80546)
		(width 0.088646)
		(layer "In6.Cu")
		(net "M_G_CPU1_SB_DQ<2>")
	)
	(arc
		(start 132.03301 -241.80546)
		(mid 131.845812 -241.855603)
		(end 131.658614 -241.80546)
		(width 0.088646)
		(layer "In6.Cu")
		(net "M_G_CPU1_SB_DQ<2>")
	)
	(arc
		(start 133.912864 -241.80546)
		(mid 133.725666 -241.855603)
		(end 133.538468 -241.80546)
		(width 0.088646)
		(layer "In6.Cu")
		(net "M_G_CPU1_SB_DQ<2>")
	)
	(arc
		(start 135.407654 -241.799364)
		(mid 135.129222 -241.729518)
		(end 134.85241 -241.80546)
		(width 0.088646)
		(layer "In6.Cu")
		(net "M_G_CPU1_SB_DQ<2>")
	)
	(arc
		(start 132.97281 -241.80546)
		(mid 132.785612 -241.855603)
		(end 132.598414 -241.80546)
		(width 0.088646)
		(layer "In6.Cu")
		(net "M_G_CPU1_SB_DQ<2>")
	)
	(arc
		(start 138.611864 -241.80546)
		(mid 138.424666 -241.855603)
		(end 138.237468 -241.80546)
		(width 0.088646)
		(layer "In6.Cu")
		(net "M_G_CPU1_SB_DQ<2>")
	)
	(arc
		(start 129.213864 -241.80546)
		(mid 129.026666 -241.855603)
		(end 128.839468 -241.80546)
		(width 0.088646)
		(layer "In6.Cu")
		(net "M_G_CPU1_SB_DQ<2>")
	)
	(arc
		(start 137.672064 -241.80546)
		(mid 137.484866 -241.855603)
		(end 137.297668 -241.80546)
		(width 0.088646)
		(layer "In6.Cu")
		(net "M_G_CPU1_SB_DQ<2>")
	)
	(arc
		(start 129.7686 -241.799364)
		(mid 129.490422 -241.729641)
		(end 129.213864 -241.80546)
		(width 0.088646)
		(layer "In6.Cu")
		(net "M_G_CPU1_SB_DQ<2>")
	)
	(arc
		(start 128.27381 -241.80546)
		(mid 128.086612 -241.855603)
		(end 127.899414 -241.80546)
		(width 0.088646)
		(layer "In6.Cu")
		(net "M_G_CPU1_SB_DQ<2>")
	)
	(arc
		(start 139.177268 -241.80546)
		(mid 138.894566 -241.729684)
		(end 138.611864 -241.80546)
		(width 0.088646)
		(layer "In6.Cu")
		(net "M_G_CPU1_SB_DQ<2>")
	)
	(segment
		(start 135.605266 -217.600276)
		(end 135.605266 -217.064336)
		(width 0.20066)
		(layer "F.Cu")
		(net "M_G_CPU1_SB_DQ<29>")
	)
	(segment
		(start 191.233044 -196.71538)
		(end 190.75781 -196.71538)
		(width 0.20066)
		(layer "F.Cu")
		(net "M_G_CPU1_SB_DQ<29>")
	)
	(segment
		(start 191.539114 -196.041772)
		(end 191.421004 -196.159882)
		(width 0.20066)
		(layer "F.Cu")
		(net "M_G_CPU1_SB_DQ<29>")
	)
	(segment
		(start 196.532246 -196.466714)
		(end 196.531992 -196.466968)
		(width 0.20066)
		(layer "F.Cu")
		(net "M_G_CPU1_SB_DQ<29>")
	)
	(segment
		(start 190.509144 -196.466714)
		(end 188.988446 -196.466714)
		(width 0.20066)
		(layer "F.Cu")
		(net "M_G_CPU1_SB_DQ<29>")
	)
	(segment
		(start 188.988446 -196.466714)
		(end 187.883546 -196.466714)
		(width 0.20066)
		(layer "F.Cu")
		(net "M_G_CPU1_SB_DQ<29>")
	)
	(segment
		(start 194.098926 -196.035422)
		(end 194.092576 -196.041772)
		(width 0.1016)
		(layer "F.Cu")
		(net "M_G_CPU1_SB_DQ<29>")
	)
	(segment
		(start 194.508882 -196.035422)
		(end 194.098926 -196.035422)
		(width 0.20066)
		(layer "F.Cu")
		(net "M_G_CPU1_SB_DQ<29>")
	)
	(segment
		(start 196.531992 -196.466968)
		(end 194.940428 -196.466968)
		(width 0.20066)
		(layer "F.Cu")
		(net "M_G_CPU1_SB_DQ<29>")
	)
	(segment
		(start 191.883792 -196.041772)
		(end 191.539114 -196.041772)
		(width 0.20066)
		(layer "F.Cu")
		(net "M_G_CPU1_SB_DQ<29>")
	)
	(segment
		(start 191.903858 -196.041772)
		(end 191.883792 -196.041772)
		(width 0.101854)
		(layer "F.Cu")
		(net "M_G_CPU1_SB_DQ<29>")
	)
	(segment
		(start 191.421004 -196.52742)
		(end 191.233044 -196.71538)
		(width 0.20066)
		(layer "F.Cu")
		(net "M_G_CPU1_SB_DQ<29>")
	)
	(segment
		(start 190.75781 -196.71538)
		(end 190.509144 -196.466714)
		(width 0.20066)
		(layer "F.Cu")
		(net "M_G_CPU1_SB_DQ<29>")
	)
	(segment
		(start 191.421004 -196.159882)
		(end 191.421004 -196.52742)
		(width 0.20066)
		(layer "F.Cu")
		(net "M_G_CPU1_SB_DQ<29>")
	)
	(segment
		(start 194.940428 -196.466968)
		(end 194.508882 -196.035422)
		(width 0.20066)
		(layer "F.Cu")
		(net "M_G_CPU1_SB_DQ<29>")
	)
	(segment
		(start 194.092576 -196.041772)
		(end 191.903858 -196.041772)
		(width 0.1016)
		(layer "F.Cu")
		(net "M_G_CPU1_SB_DQ<29>")
	)
	(segment
		(start 170.837352 -194.482466)
		(end 170.837352 -194.662806)
		(width 0.18288)
		(layer "In6.Cu")
		(net "M_G_CPU1_SB_DQ<29>")
	)
	(segment
		(start 137.263124 -216.539572)
		(end 137.202164 -216.574878)
		(width 0.088646)
		(layer "In6.Cu")
		(net "M_G_CPU1_SB_DQ<29>")
	)
	(segment
		(start 146.756882 -205.950566)
		(end 146.756882 -208.339182)
		(width 0.18288)
		(layer "In6.Cu")
		(net "M_G_CPU1_SB_DQ<29>")
	)
	(segment
		(start 170.143932 -194.482466)
		(end 169.961052 -194.299586)
		(width 0.18288)
		(layer "In6.Cu")
		(net "M_G_CPU1_SB_DQ<29>")
	)
	(segment
		(start 167.238934 -195.170552)
		(end 167.056054 -194.987672)
		(width 0.18288)
		(layer "In6.Cu")
		(net "M_G_CPU1_SB_DQ<29>")
	)
	(segment
		(start 139.932918 -215.875108)
		(end 139.834874 -215.875108)
		(width 0.088646)
		(layer "In6.Cu")
		(net "M_G_CPU1_SB_DQ<29>")
	)
	(segment
		(start 163.415726 -194.299586)
		(end 162.380676 -195.334636)
		(width 0.18288)
		(layer "In6.Cu")
		(net "M_G_CPU1_SB_DQ<29>")
	)
	(segment
		(start 140.51153 -214.584534)
		(end 140.357098 -214.738966)
		(width 0.088646)
		(layer "In6.Cu")
		(net "M_G_CPU1_SB_DQ<29>")
	)
	(segment
		(start 135.76173 -217.335354)
		(end 135.605266 -217.064336)
		(width 0.088646)
		(layer "In6.Cu")
		(net "M_G_CPU1_SB_DQ<29>")
	)
	(segment
		(start 139.082018 -215.925908)
		(end 139.073636 -215.921082)
		(width 0.088646)
		(layer "In6.Cu")
		(net "M_G_CPU1_SB_DQ<29>")
	)
	(segment
		(start 170.326812 -194.845686)
		(end 170.143932 -194.662806)
		(width 0.18288)
		(layer "In6.Cu")
		(net "M_G_CPU1_SB_DQ<29>")
	)
	(segment
		(start 160.29813 -195.305426)
		(end 160.291526 -195.305426)
		(width 0.18288)
		(layer "In6.Cu")
		(net "M_G_CPU1_SB_DQ<29>")
	)
	(segment
		(start 167.056054 -194.482466)
		(end 166.873174 -194.299586)
		(width 0.18288)
		(layer "In6.Cu")
		(net "M_G_CPU1_SB_DQ<29>")
	)
	(segment
		(start 160.114996 -195.128896)
		(end 157.578552 -195.128896)
		(width 0.18288)
		(layer "In6.Cu")
		(net "M_G_CPU1_SB_DQ<29>")
	)
	(segment
		(start 138.146282 -215.925908)
		(end 138.141964 -215.923368)
		(width 0.088646)
		(layer "In6.Cu")
		(net "M_G_CPU1_SB_DQ<29>")
	)
	(segment
		(start 167.749474 -194.987672)
		(end 167.566594 -195.170552)
		(width 0.18288)
		(layer "In6.Cu")
		(net "M_G_CPU1_SB_DQ<29>")
	)
	(segment
		(start 135.839962 -217.356182)
		(end 135.76173 -217.335354)
		(width 0.088646)
		(layer "In6.Cu")
		(net "M_G_CPU1_SB_DQ<29>")
	)
	(segment
		(start 139.092432 -215.932004)
		(end 139.082018 -215.925908)
		(width 0.088646)
		(layer "In6.Cu")
		(net "M_G_CPU1_SB_DQ<29>")
	)
	(segment
		(start 187.883546 -196.466714)
		(end 186.609228 -195.192396)
		(width 0.18288)
		(layer "In6.Cu")
		(net "M_G_CPU1_SB_DQ<29>")
	)
	(segment
		(start 176.446942 -195.192396)
		(end 175.554132 -194.299586)
		(width 0.18288)
		(layer "In6.Cu")
		(net "M_G_CPU1_SB_DQ<29>")
	)
	(segment
		(start 186.609228 -195.192396)
		(end 176.446942 -195.192396)
		(width 0.18288)
		(layer "In6.Cu")
		(net "M_G_CPU1_SB_DQ<29>")
	)
	(segment
		(start 137.76833 -215.923368)
		(end 137.76706 -215.923876)
		(width 0.088646)
		(layer "In6.Cu")
		(net "M_G_CPU1_SB_DQ<29>")
	)
	(segment
		(start 169.961052 -194.299586)
		(end 167.932354 -194.299586)
		(width 0.18288)
		(layer "In6.Cu")
		(net "M_G_CPU1_SB_DQ<29>")
	)
	(segment
		(start 167.566594 -195.170552)
		(end 167.238934 -195.170552)
		(width 0.18288)
		(layer "In6.Cu")
		(net "M_G_CPU1_SB_DQ<29>")
	)
	(segment
		(start 170.654472 -194.845686)
		(end 170.326812 -194.845686)
		(width 0.18288)
		(layer "In6.Cu")
		(net "M_G_CPU1_SB_DQ<29>")
	)
	(segment
		(start 167.749474 -194.482466)
		(end 167.749474 -194.987672)
		(width 0.18288)
		(layer "In6.Cu")
		(net "M_G_CPU1_SB_DQ<29>")
	)
	(segment
		(start 175.554132 -194.299586)
		(end 171.020232 -194.299586)
		(width 0.18288)
		(layer "In6.Cu")
		(net "M_G_CPU1_SB_DQ<29>")
	)
	(segment
		(start 157.578552 -195.128896)
		(end 146.756882 -205.950566)
		(width 0.18288)
		(layer "In6.Cu")
		(net "M_G_CPU1_SB_DQ<29>")
	)
	(segment
		(start 137.562336 -216.292938)
		(end 137.489438 -216.36609)
		(width 0.088646)
		(layer "In6.Cu")
		(net "M_G_CPU1_SB_DQ<29>")
	)
	(segment
		(start 137.58037 -216.247218)
		(end 137.58037 -216.249758)
		(width 0.088646)
		(layer "In6.Cu")
		(net "M_G_CPU1_SB_DQ<29>")
	)
	(segment
		(start 171.020232 -194.299586)
		(end 170.837352 -194.482466)
		(width 0.18288)
		(layer "In6.Cu")
		(net "M_G_CPU1_SB_DQ<29>")
	)
	(segment
		(start 160.32734 -195.334636)
		(end 160.29813 -195.305426)
		(width 0.18288)
		(layer "In6.Cu")
		(net "M_G_CPU1_SB_DQ<29>")
	)
	(segment
		(start 166.873174 -194.299586)
		(end 163.415726 -194.299586)
		(width 0.18288)
		(layer "In6.Cu")
		(net "M_G_CPU1_SB_DQ<29>")
	)
	(segment
		(start 170.837352 -194.662806)
		(end 170.654472 -194.845686)
		(width 0.18288)
		(layer "In6.Cu")
		(net "M_G_CPU1_SB_DQ<29>")
	)
	(segment
		(start 162.380676 -195.334636)
		(end 160.32734 -195.334636)
		(width 0.18288)
		(layer "In6.Cu")
		(net "M_G_CPU1_SB_DQ<29>")
	)
	(segment
		(start 140.357098 -214.738966)
		(end 140.357098 -215.450928)
		(width 0.088646)
		(layer "In6.Cu")
		(net "M_G_CPU1_SB_DQ<29>")
	)
	(segment
		(start 167.932354 -194.299586)
		(end 167.749474 -194.482466)
		(width 0.18288)
		(layer "In6.Cu")
		(net "M_G_CPU1_SB_DQ<29>")
	)
	(segment
		(start 140.357098 -215.450928)
		(end 139.932918 -215.875108)
		(width 0.088646)
		(layer "In6.Cu")
		(net "M_G_CPU1_SB_DQ<29>")
	)
	(segment
		(start 167.056054 -194.987672)
		(end 167.056054 -194.482466)
		(width 0.18288)
		(layer "In6.Cu")
		(net "M_G_CPU1_SB_DQ<29>")
	)
	(segment
		(start 135.979916 -217.05443)
		(end 135.979916 -217.064336)
		(width 0.088646)
		(layer "In6.Cu")
		(net "M_G_CPU1_SB_DQ<29>")
	)
	(segment
		(start 170.143932 -194.662806)
		(end 170.143932 -194.482466)
		(width 0.18288)
		(layer "In6.Cu")
		(net "M_G_CPU1_SB_DQ<29>")
	)
	(segment
		(start 160.291526 -195.305426)
		(end 160.114996 -195.128896)
		(width 0.18288)
		(layer "In6.Cu")
		(net "M_G_CPU1_SB_DQ<29>")
	)
	(segment
		(start 146.756882 -208.339182)
		(end 140.51153 -214.584534)
		(width 0.18288)
		(layer "In6.Cu")
		(net "M_G_CPU1_SB_DQ<29>")
	)
	(arc
		(start 139.834874 -215.875108)
		(mid 139.737919 -215.888152)
		(end 139.647676 -215.925908)
		(width 0.088646)
		(layer "In6.Cu")
		(net "M_G_CPU1_SB_DQ<29>")
	)
	(arc
		(start 137.202164 -216.574878)
		(mid 137.014966 -216.625021)
		(end 136.827768 -216.574878)
		(width 0.088646)
		(layer "In6.Cu")
		(net "M_G_CPU1_SB_DQ<29>")
	)
	(arc
		(start 136.262364 -216.574878)
		(mid 136.058029 -216.777483)
		(end 135.979916 -217.05443)
		(width 0.088646)
		(layer "In6.Cu")
		(net "M_G_CPU1_SB_DQ<29>")
	)
	(arc
		(start 139.647676 -215.925908)
		(mid 139.370863 -216.001812)
		(end 139.092432 -215.932004)
		(width 0.088646)
		(layer "In6.Cu")
		(net "M_G_CPU1_SB_DQ<29>")
	)
	(arc
		(start 137.76706 -215.923876)
		(mid 137.630403 -216.060537)
		(end 137.58037 -216.247218)
		(width 0.088646)
		(layer "In6.Cu")
		(net "M_G_CPU1_SB_DQ<29>")
	)
	(arc
		(start 135.979916 -217.064336)
		(mid 135.943056 -217.226133)
		(end 135.839962 -217.356182)
		(width 0.088646)
		(layer "In6.Cu")
		(net "M_G_CPU1_SB_DQ<29>")
	)
	(arc
		(start 138.141964 -215.923368)
		(mid 137.955164 -215.873343)
		(end 137.76833 -215.923368)
		(width 0.088646)
		(layer "In6.Cu")
		(net "M_G_CPU1_SB_DQ<29>")
	)
	(arc
		(start 138.707876 -215.925908)
		(mid 138.427096 -216.001179)
		(end 138.146282 -215.925908)
		(width 0.088646)
		(layer "In6.Cu")
		(net "M_G_CPU1_SB_DQ<29>")
	)
	(arc
		(start 136.827768 -216.574878)
		(mid 136.545066 -216.499102)
		(end 136.262364 -216.574878)
		(width 0.088646)
		(layer "In6.Cu")
		(net "M_G_CPU1_SB_DQ<29>")
	)
	(arc
		(start 137.58037 -216.249758)
		(mid 137.575628 -216.27313)
		(end 137.562336 -216.292938)
		(width 0.088646)
		(layer "In6.Cu")
		(net "M_G_CPU1_SB_DQ<29>")
	)
	(arc
		(start 137.489438 -216.36609)
		(mid 137.381974 -216.460259)
		(end 137.263124 -216.539572)
		(width 0.088646)
		(layer "In6.Cu")
		(net "M_G_CPU1_SB_DQ<29>")
	)
	(arc
		(start 139.073636 -215.921082)
		(mid 138.890128 -215.875742)
		(end 138.707876 -215.925908)
		(width 0.088646)
		(layer "In6.Cu")
		(net "M_G_CPU1_SB_DQ<29>")
	)
	(segment
		(start 191.930782 -197.741794)
		(end 191.883792 -197.741794)
		(width 0.101854)
		(layer "F.Cu")
		(net "M_G_CPU1_SB_DQ<28>")
	)
	(segment
		(start 194.508882 -197.735444)
		(end 194.098926 -197.735444)
		(width 0.20066)
		(layer "F.Cu")
		(net "M_G_CPU1_SB_DQ<28>")
	)
	(segment
		(start 188.988446 -198.166736)
		(end 187.883546 -198.166736)
		(width 0.20066)
		(layer "F.Cu")
		(net "M_G_CPU1_SB_DQ<28>")
	)
	(segment
		(start 196.531992 -198.16699)
		(end 194.940428 -198.16699)
		(width 0.20066)
		(layer "F.Cu")
		(net "M_G_CPU1_SB_DQ<28>")
	)
	(segment
		(start 190.509144 -198.166736)
		(end 188.988446 -198.166736)
		(width 0.20066)
		(layer "F.Cu")
		(net "M_G_CPU1_SB_DQ<28>")
	)
	(segment
		(start 136.075166 -217.878406)
		(end 136.075166 -218.414346)
		(width 0.20066)
		(layer "F.Cu")
		(net "M_G_CPU1_SB_DQ<28>")
	)
	(segment
		(start 194.098926 -197.735444)
		(end 194.092576 -197.741794)
		(width 0.1016)
		(layer "F.Cu")
		(net "M_G_CPU1_SB_DQ<28>")
	)
	(segment
		(start 191.883792 -197.741794)
		(end 191.539114 -197.741794)
		(width 0.20066)
		(layer "F.Cu")
		(net "M_G_CPU1_SB_DQ<28>")
	)
	(segment
		(start 191.539114 -197.741794)
		(end 191.421004 -197.859904)
		(width 0.20066)
		(layer "F.Cu")
		(net "M_G_CPU1_SB_DQ<28>")
	)
	(segment
		(start 194.940428 -198.16699)
		(end 194.508882 -197.735444)
		(width 0.20066)
		(layer "F.Cu")
		(net "M_G_CPU1_SB_DQ<28>")
	)
	(segment
		(start 190.75781 -198.415402)
		(end 190.509144 -198.166736)
		(width 0.20066)
		(layer "F.Cu")
		(net "M_G_CPU1_SB_DQ<28>")
	)
	(segment
		(start 191.233044 -198.415402)
		(end 190.75781 -198.415402)
		(width 0.20066)
		(layer "F.Cu")
		(net "M_G_CPU1_SB_DQ<28>")
	)
	(segment
		(start 191.421004 -198.227442)
		(end 191.233044 -198.415402)
		(width 0.20066)
		(layer "F.Cu")
		(net "M_G_CPU1_SB_DQ<28>")
	)
	(segment
		(start 194.092576 -197.741794)
		(end 191.930782 -197.741794)
		(width 0.1016)
		(layer "F.Cu")
		(net "M_G_CPU1_SB_DQ<28>")
	)
	(segment
		(start 196.532246 -198.166736)
		(end 196.531992 -198.16699)
		(width 0.20066)
		(layer "F.Cu")
		(net "M_G_CPU1_SB_DQ<28>")
	)
	(segment
		(start 191.421004 -197.859904)
		(end 191.421004 -198.227442)
		(width 0.20066)
		(layer "F.Cu")
		(net "M_G_CPU1_SB_DQ<28>")
	)
	(segment
		(start 160.297114 -196.568314)
		(end 159.37738 -196.568314)
		(width 0.18288)
		(layer "In6.Cu")
		(net "M_G_CPU1_SB_DQ<28>")
	)
	(segment
		(start 170.854624 -196.097906)
		(end 170.854624 -196.466714)
		(width 0.18288)
		(layer "In6.Cu")
		(net "M_G_CPU1_SB_DQ<28>")
	)
	(segment
		(start 164.708586 -196.641466)
		(end 164.444426 -196.905626)
		(width 0.18288)
		(layer "In6.Cu")
		(net "M_G_CPU1_SB_DQ<28>")
	)
	(segment
		(start 165.859714 -196.641466)
		(end 164.708586 -196.641466)
		(width 0.18288)
		(layer "In6.Cu")
		(net "M_G_CPU1_SB_DQ<28>")
	)
	(segment
		(start 164.444426 -196.905626)
		(end 160.634426 -196.905626)
		(width 0.18288)
		(layer "In6.Cu")
		(net "M_G_CPU1_SB_DQ<28>")
	)
	(segment
		(start 141.037818 -216.062814)
		(end 140.411454 -216.689178)
		(width 0.088646)
		(layer "In6.Cu")
		(net "M_G_CPU1_SB_DQ<28>")
	)
	(segment
		(start 187.883546 -198.166736)
		(end 187.257436 -197.540626)
		(width 0.18288)
		(layer "In6.Cu")
		(net "M_G_CPU1_SB_DQ<28>")
	)
	(segment
		(start 147.845018 -208.74482)
		(end 141.25829 -215.331548)
		(width 0.18288)
		(layer "In6.Cu")
		(net "M_G_CPU1_SB_DQ<28>")
	)
	(segment
		(start 158.50108 -196.751194)
		(end 158.3182 -196.568314)
		(width 0.18288)
		(layer "In6.Cu")
		(net "M_G_CPU1_SB_DQ<28>")
	)
	(segment
		(start 147.845018 -206.436976)
		(end 147.845018 -208.74482)
		(width 0.18288)
		(layer "In6.Cu")
		(net "M_G_CPU1_SB_DQ<28>")
	)
	(segment
		(start 170.161204 -196.466714)
		(end 170.161204 -196.097906)
		(width 0.18288)
		(layer "In6.Cu")
		(net "M_G_CPU1_SB_DQ<28>")
	)
	(segment
		(start 166.553134 -197.279006)
		(end 166.225474 -197.279006)
		(width 0.18288)
		(layer "In6.Cu")
		(net "M_G_CPU1_SB_DQ<28>")
	)
	(segment
		(start 171.98848 -196.04228)
		(end 171.861226 -195.915026)
		(width 0.18288)
		(layer "In6.Cu")
		(net "M_G_CPU1_SB_DQ<28>")
	)
	(segment
		(start 139.18946 -216.732866)
		(end 139.177522 -216.739724)
		(width 0.088646)
		(layer "In6.Cu")
		(net "M_G_CPU1_SB_DQ<28>")
	)
	(segment
		(start 140.411454 -216.689178)
		(end 140.304266 -216.689178)
		(width 0.088646)
		(layer "In6.Cu")
		(net "M_G_CPU1_SB_DQ<28>")
	)
	(segment
		(start 159.1945 -196.751194)
		(end 159.1945 -197.125844)
		(width 0.18288)
		(layer "In6.Cu")
		(net "M_G_CPU1_SB_DQ<28>")
	)
	(segment
		(start 160.634426 -196.905626)
		(end 160.297114 -196.568314)
		(width 0.18288)
		(layer "In6.Cu")
		(net "M_G_CPU1_SB_DQ<28>")
	)
	(segment
		(start 139.177522 -216.739724)
		(end 139.16279 -216.74836)
		(width 0.088646)
		(layer "In6.Cu")
		(net "M_G_CPU1_SB_DQ<28>")
	)
	(segment
		(start 169.126662 -195.915026)
		(end 168.400222 -196.641466)
		(width 0.18288)
		(layer "In6.Cu")
		(net "M_G_CPU1_SB_DQ<28>")
	)
	(segment
		(start 166.736014 -196.824346)
		(end 166.736014 -197.096126)
		(width 0.18288)
		(layer "In6.Cu")
		(net "M_G_CPU1_SB_DQ<28>")
	)
	(segment
		(start 158.3182 -196.568314)
		(end 157.71368 -196.568314)
		(width 0.18288)
		(layer "In6.Cu")
		(net "M_G_CPU1_SB_DQ<28>")
	)
	(segment
		(start 166.042594 -196.824346)
		(end 165.859714 -196.641466)
		(width 0.18288)
		(layer "In6.Cu")
		(net "M_G_CPU1_SB_DQ<28>")
	)
	(segment
		(start 159.37738 -196.568314)
		(end 159.1945 -196.751194)
		(width 0.18288)
		(layer "In6.Cu")
		(net "M_G_CPU1_SB_DQ<28>")
	)
	(segment
		(start 141.037818 -215.55202)
		(end 141.037818 -216.062814)
		(width 0.088646)
		(layer "In6.Cu")
		(net "M_G_CPU1_SB_DQ<28>")
	)
	(segment
		(start 168.400222 -196.641466)
		(end 166.918894 -196.641466)
		(width 0.18288)
		(layer "In6.Cu")
		(net "M_G_CPU1_SB_DQ<28>")
	)
	(segment
		(start 187.257436 -197.540626)
		(end 184.0611 -197.540626)
		(width 0.18288)
		(layer "In6.Cu")
		(net "M_G_CPU1_SB_DQ<28>")
	)
	(segment
		(start 171.861226 -195.915026)
		(end 171.037504 -195.915026)
		(width 0.18288)
		(layer "In6.Cu")
		(net "M_G_CPU1_SB_DQ<28>")
	)
	(segment
		(start 175.18888 -196.04228)
		(end 171.98848 -196.04228)
		(width 0.18288)
		(layer "In6.Cu")
		(net "M_G_CPU1_SB_DQ<28>")
	)
	(segment
		(start 166.042594 -197.096126)
		(end 166.042594 -196.824346)
		(width 0.18288)
		(layer "In6.Cu")
		(net "M_G_CPU1_SB_DQ<28>")
	)
	(segment
		(start 166.225474 -197.279006)
		(end 166.042594 -197.096126)
		(width 0.18288)
		(layer "In6.Cu")
		(net "M_G_CPU1_SB_DQ<28>")
	)
	(segment
		(start 166.918894 -196.641466)
		(end 166.736014 -196.824346)
		(width 0.18288)
		(layer "In6.Cu")
		(net "M_G_CPU1_SB_DQ<28>")
	)
	(segment
		(start 137.548874 -216.68867)
		(end 137.489184 -216.68867)
		(width 0.088646)
		(layer "In6.Cu")
		(net "M_G_CPU1_SB_DQ<28>")
	)
	(segment
		(start 135.918702 -217.607388)
		(end 136.075166 -217.878406)
		(width 0.088646)
		(layer "In6.Cu")
		(net "M_G_CPU1_SB_DQ<28>")
	)
	(segment
		(start 157.71368 -196.568314)
		(end 147.845018 -206.436976)
		(width 0.18288)
		(layer "In6.Cu")
		(net "M_G_CPU1_SB_DQ<28>")
	)
	(segment
		(start 135.942832 -217.518234)
		(end 135.918702 -217.607388)
		(width 0.088646)
		(layer "In6.Cu")
		(net "M_G_CPU1_SB_DQ<28>")
	)
	(segment
		(start 170.344084 -196.649594)
		(end 170.161204 -196.466714)
		(width 0.18288)
		(layer "In6.Cu")
		(net "M_G_CPU1_SB_DQ<28>")
	)
	(segment
		(start 136.170416 -217.064336)
		(end 136.170416 -217.082878)
		(width 0.088646)
		(layer "In6.Cu")
		(net "M_G_CPU1_SB_DQ<28>")
	)
	(segment
		(start 166.736014 -197.096126)
		(end 166.553134 -197.279006)
		(width 0.18288)
		(layer "In6.Cu")
		(net "M_G_CPU1_SB_DQ<28>")
	)
	(segment
		(start 170.854624 -196.466714)
		(end 170.671744 -196.649594)
		(width 0.18288)
		(layer "In6.Cu")
		(net "M_G_CPU1_SB_DQ<28>")
	)
	(segment
		(start 183.412892 -196.892418)
		(end 176.039018 -196.892418)
		(width 0.18288)
		(layer "In6.Cu")
		(net "M_G_CPU1_SB_DQ<28>")
	)
	(segment
		(start 170.671744 -196.649594)
		(end 170.344084 -196.649594)
		(width 0.18288)
		(layer "In6.Cu")
		(net "M_G_CPU1_SB_DQ<28>")
	)
	(segment
		(start 171.037504 -195.915026)
		(end 170.854624 -196.097906)
		(width 0.18288)
		(layer "In6.Cu")
		(net "M_G_CPU1_SB_DQ<28>")
	)
	(segment
		(start 158.68396 -197.308724)
		(end 158.50108 -197.125844)
		(width 0.18288)
		(layer "In6.Cu")
		(net "M_G_CPU1_SB_DQ<28>")
	)
	(segment
		(start 170.161204 -196.097906)
		(end 169.978324 -195.915026)
		(width 0.18288)
		(layer "In6.Cu")
		(net "M_G_CPU1_SB_DQ<28>")
	)
	(segment
		(start 159.1945 -197.125844)
		(end 159.01162 -197.308724)
		(width 0.18288)
		(layer "In6.Cu")
		(net "M_G_CPU1_SB_DQ<28>")
	)
	(segment
		(start 169.978324 -195.915026)
		(end 169.126662 -195.915026)
		(width 0.18288)
		(layer "In6.Cu")
		(net "M_G_CPU1_SB_DQ<28>")
	)
	(segment
		(start 184.0611 -197.540626)
		(end 183.412892 -196.892418)
		(width 0.18288)
		(layer "In6.Cu")
		(net "M_G_CPU1_SB_DQ<28>")
	)
	(segment
		(start 138.24585 -216.734898)
		(end 138.237468 -216.739724)
		(width 0.088646)
		(layer "In6.Cu")
		(net "M_G_CPU1_SB_DQ<28>")
	)
	(segment
		(start 159.01162 -197.308724)
		(end 158.68396 -197.308724)
		(width 0.18288)
		(layer "In6.Cu")
		(net "M_G_CPU1_SB_DQ<28>")
	)
	(segment
		(start 136.357868 -216.739978)
		(end 136.348978 -216.745058)
		(width 0.088646)
		(layer "In6.Cu")
		(net "M_G_CPU1_SB_DQ<28>")
	)
	(segment
		(start 176.039018 -196.892418)
		(end 175.18888 -196.04228)
		(width 0.18288)
		(layer "In6.Cu")
		(net "M_G_CPU1_SB_DQ<28>")
	)
	(segment
		(start 141.25829 -215.331548)
		(end 141.037818 -215.55202)
		(width 0.088646)
		(layer "In6.Cu")
		(net "M_G_CPU1_SB_DQ<28>")
	)
	(segment
		(start 158.50108 -197.125844)
		(end 158.50108 -196.751194)
		(width 0.18288)
		(layer "In6.Cu")
		(net "M_G_CPU1_SB_DQ<28>")
	)
	(arc
		(start 138.237468 -216.739724)
		(mid 137.954766 -216.815432)
		(end 137.672064 -216.739724)
		(width 0.088646)
		(layer "In6.Cu")
		(net "M_G_CPU1_SB_DQ<28>")
	)
	(arc
		(start 140.10259 -216.74836)
		(mid 139.826149 -216.815496)
		(end 139.551918 -216.739724)
		(width 0.088646)
		(layer "In6.Cu")
		(net "M_G_CPU1_SB_DQ<28>")
	)
	(arc
		(start 139.551918 -216.739724)
		(mid 139.371571 -216.689555)
		(end 139.18946 -216.732866)
		(width 0.088646)
		(layer "In6.Cu")
		(net "M_G_CPU1_SB_DQ<28>")
	)
	(arc
		(start 137.489184 -216.68867)
		(mid 137.390055 -216.701729)
		(end 137.297668 -216.739978)
		(width 0.088646)
		(layer "In6.Cu")
		(net "M_G_CPU1_SB_DQ<28>")
	)
	(arc
		(start 136.170416 -217.082878)
		(mid 136.106367 -217.326558)
		(end 135.942832 -217.518234)
		(width 0.088646)
		(layer "In6.Cu")
		(net "M_G_CPU1_SB_DQ<28>")
	)
	(arc
		(start 140.304266 -216.689178)
		(mid 140.199197 -216.70435)
		(end 140.10259 -216.74836)
		(width 0.088646)
		(layer "In6.Cu")
		(net "M_G_CPU1_SB_DQ<28>")
	)
	(arc
		(start 136.732264 -216.739978)
		(mid 136.545066 -216.689835)
		(end 136.357868 -216.739978)
		(width 0.088646)
		(layer "In6.Cu")
		(net "M_G_CPU1_SB_DQ<28>")
	)
	(arc
		(start 138.612118 -216.739724)
		(mid 138.429613 -216.68952)
		(end 138.24585 -216.734898)
		(width 0.088646)
		(layer "In6.Cu")
		(net "M_G_CPU1_SB_DQ<28>")
	)
	(arc
		(start 136.348978 -216.745058)
		(mid 136.218064 -216.881418)
		(end 136.170416 -217.064336)
		(width 0.088646)
		(layer "In6.Cu")
		(net "M_G_CPU1_SB_DQ<28>")
	)
	(arc
		(start 137.672064 -216.739724)
		(mid 137.615544 -216.701959)
		(end 137.548874 -216.68867)
		(width 0.088646)
		(layer "In6.Cu")
		(net "M_G_CPU1_SB_DQ<28>")
	)
	(arc
		(start 139.16279 -216.74836)
		(mid 138.886349 -216.815496)
		(end 138.612118 -216.739724)
		(width 0.088646)
		(layer "In6.Cu")
		(net "M_G_CPU1_SB_DQ<28>")
	)
	(arc
		(start 137.297668 -216.739978)
		(mid 137.014966 -216.815754)
		(end 136.732264 -216.739978)
		(width 0.088646)
		(layer "In6.Cu")
		(net "M_G_CPU1_SB_DQ<28>")
	)
	(segment
		(start 191.983614 -201.56678)
		(end 193.088514 -201.56678)
		(width 0.20066)
		(layer "F.Cu")
		(net "M_G_CPU1_SB_DQ<27>")
	)
	(segment
		(start 198.662036 -201.314812)
		(end 199.046084 -201.314812)
		(width 0.20066)
		(layer "F.Cu")
		(net "M_G_CPU1_SB_DQ<27>")
	)
	(segment
		(start 197.530466 -201.991722)
		(end 197.542658 -202.003914)
		(width 0.1016)
		(layer "F.Cu")
		(net "M_G_CPU1_SB_DQ<27>")
	)
	(segment
		(start 194.786758 -201.56678)
		(end 195.218812 -201.998834)
		(width 0.20066)
		(layer "F.Cu")
		(net "M_G_CPU1_SB_DQ<27>")
	)
	(segment
		(start 199.298052 -201.56678)
		(end 200.632314 -201.56678)
		(width 0.20066)
		(layer "F.Cu")
		(net "M_G_CPU1_SB_DQ<27>")
	)
	(segment
		(start 198.427848 -201.549)
		(end 198.662036 -201.314812)
		(width 0.20066)
		(layer "F.Cu")
		(net "M_G_CPU1_SB_DQ<27>")
	)
	(segment
		(start 195.510658 -201.998834)
		(end 195.515484 -201.998834)
		(width 0.101854)
		(layer "F.Cu")
		(net "M_G_CPU1_SB_DQ<27>")
	)
	(segment
		(start 199.046084 -201.314812)
		(end 199.298052 -201.56678)
		(width 0.20066)
		(layer "F.Cu")
		(net "M_G_CPU1_SB_DQ<27>")
	)
	(segment
		(start 195.218812 -201.998834)
		(end 195.510658 -201.998834)
		(width 0.20066)
		(layer "F.Cu")
		(net "M_G_CPU1_SB_DQ<27>")
	)
	(segment
		(start 195.522596 -201.991722)
		(end 197.530466 -201.991722)
		(width 0.1016)
		(layer "F.Cu")
		(net "M_G_CPU1_SB_DQ<27>")
	)
	(segment
		(start 197.542658 -202.003914)
		(end 198.223886 -202.003914)
		(width 0.20066)
		(layer "F.Cu")
		(net "M_G_CPU1_SB_DQ<27>")
	)
	(segment
		(start 195.515484 -201.998834)
		(end 195.522596 -201.991722)
		(width 0.1016)
		(layer "F.Cu")
		(net "M_G_CPU1_SB_DQ<27>")
	)
	(segment
		(start 198.223886 -202.003914)
		(end 198.427848 -201.799952)
		(width 0.20066)
		(layer "F.Cu")
		(net "M_G_CPU1_SB_DQ<27>")
	)
	(segment
		(start 138.894312 -220.041978)
		(end 138.894312 -219.506038)
		(width 0.20066)
		(layer "F.Cu")
		(net "M_G_CPU1_SB_DQ<27>")
	)
	(segment
		(start 198.427848 -201.799952)
		(end 198.427848 -201.549)
		(width 0.20066)
		(layer "F.Cu")
		(net "M_G_CPU1_SB_DQ<27>")
	)
	(segment
		(start 193.088514 -201.56678)
		(end 194.786758 -201.56678)
		(width 0.20066)
		(layer "F.Cu")
		(net "M_G_CPU1_SB_DQ<27>")
	)
	(segment
		(start 170.803062 -200.220072)
		(end 170.429682 -200.220072)
		(width 0.18288)
		(layer "In6.Cu")
		(net "M_G_CPU1_SB_DQ<27>")
	)
	(segment
		(start 191.557656 -201.140822)
		(end 178.703986 -201.140822)
		(width 0.18288)
		(layer "In6.Cu")
		(net "M_G_CPU1_SB_DQ<27>")
	)
	(segment
		(start 174.510954 -201.142346)
		(end 174.350934 -200.982326)
		(width 0.18288)
		(layer "In6.Cu")
		(net "M_G_CPU1_SB_DQ<27>")
	)
	(segment
		(start 142.430754 -217.240612)
		(end 141.934946 -217.73642)
		(width 0.088646)
		(layer "In6.Cu")
		(net "M_G_CPU1_SB_DQ<27>")
	)
	(segment
		(start 162.890454 -200.53808)
		(end 162.730434 -200.6981)
		(width 0.18288)
		(layer "In6.Cu")
		(net "M_G_CPU1_SB_DQ<27>")
	)
	(segment
		(start 170.963082 -200.380092)
		(end 170.803062 -200.220072)
		(width 0.18288)
		(layer "In6.Cu")
		(net "M_G_CPU1_SB_DQ<27>")
	)
	(segment
		(start 170.269662 -200.380092)
		(end 170.269662 -200.982326)
		(width 0.18288)
		(layer "In6.Cu")
		(net "M_G_CPU1_SB_DQ<27>")
	)
	(segment
		(start 141.934946 -217.73642)
		(end 141.934946 -218.7194)
		(width 0.088646)
		(layer "In6.Cu")
		(net "M_G_CPU1_SB_DQ<27>")
	)
	(segment
		(start 139.521438 -219.033852)
		(end 138.894312 -219.506038)
		(width 0.088646)
		(layer "In6.Cu")
		(net "M_G_CPU1_SB_DQ<27>")
	)
	(segment
		(start 174.350934 -200.982326)
		(end 174.350934 -200.405492)
		(width 0.18288)
		(layer "In6.Cu")
		(net "M_G_CPU1_SB_DQ<27>")
	)
	(segment
		(start 164.576506 -201.142346)
		(end 164.419026 -201.299826)
		(width 0.18288)
		(layer "In6.Cu")
		(net "M_G_CPU1_SB_DQ<27>")
	)
	(segment
		(start 176.338484 -201.992484)
		(end 175.488346 -201.142346)
		(width 0.18288)
		(layer "In6.Cu")
		(net "M_G_CPU1_SB_DQ<27>")
	)
	(segment
		(start 150.131272 -208.309464)
		(end 150.131272 -209.540094)
		(width 0.18288)
		(layer "In6.Cu")
		(net "M_G_CPU1_SB_DQ<27>")
	)
	(segment
		(start 140.506196 -219.007944)
		(end 140.491464 -219.01658)
		(width 0.088646)
		(layer "In6.Cu")
		(net "M_G_CPU1_SB_DQ<27>")
	)
	(segment
		(start 139.566396 -219.007944)
		(end 139.521438 -219.033852)
		(width 0.088646)
		(layer "In6.Cu")
		(net "M_G_CPU1_SB_DQ<27>")
	)
	(segment
		(start 174.350934 -200.405492)
		(end 174.190914 -200.245472)
		(width 0.18288)
		(layer "In6.Cu")
		(net "M_G_CPU1_SB_DQ<27>")
	)
	(segment
		(start 171.123102 -201.142346)
		(end 170.963082 -200.982326)
		(width 0.18288)
		(layer "In6.Cu")
		(net "M_G_CPU1_SB_DQ<27>")
	)
	(segment
		(start 173.657514 -200.405492)
		(end 173.657514 -200.982326)
		(width 0.18288)
		(layer "In6.Cu")
		(net "M_G_CPU1_SB_DQ<27>")
	)
	(segment
		(start 175.488346 -201.142346)
		(end 174.510954 -201.142346)
		(width 0.18288)
		(layer "In6.Cu")
		(net "M_G_CPU1_SB_DQ<27>")
	)
	(segment
		(start 173.657514 -200.982326)
		(end 173.497494 -201.142346)
		(width 0.18288)
		(layer "In6.Cu")
		(net "M_G_CPU1_SB_DQ<27>")
	)
	(segment
		(start 161.740342 -201.299826)
		(end 160.749234 -200.308718)
		(width 0.18288)
		(layer "In6.Cu")
		(net "M_G_CPU1_SB_DQ<27>")
	)
	(segment
		(start 163.423854 -200.6981)
		(end 163.263834 -200.53808)
		(width 0.18288)
		(layer "In6.Cu")
		(net "M_G_CPU1_SB_DQ<27>")
	)
	(segment
		(start 162.730434 -201.139806)
		(end 162.570414 -201.299826)
		(width 0.18288)
		(layer "In6.Cu")
		(net "M_G_CPU1_SB_DQ<27>")
	)
	(segment
		(start 174.190914 -200.245472)
		(end 173.817534 -200.245472)
		(width 0.18288)
		(layer "In6.Cu")
		(net "M_G_CPU1_SB_DQ<27>")
	)
	(segment
		(start 170.963082 -200.982326)
		(end 170.963082 -200.380092)
		(width 0.18288)
		(layer "In6.Cu")
		(net "M_G_CPU1_SB_DQ<27>")
	)
	(segment
		(start 173.497494 -201.142346)
		(end 171.123102 -201.142346)
		(width 0.18288)
		(layer "In6.Cu")
		(net "M_G_CPU1_SB_DQ<27>")
	)
	(segment
		(start 170.109642 -201.142346)
		(end 164.576506 -201.142346)
		(width 0.18288)
		(layer "In6.Cu")
		(net "M_G_CPU1_SB_DQ<27>")
	)
	(segment
		(start 164.419026 -201.299826)
		(end 163.583874 -201.299826)
		(width 0.18288)
		(layer "In6.Cu")
		(net "M_G_CPU1_SB_DQ<27>")
	)
	(segment
		(start 162.730434 -200.6981)
		(end 162.730434 -201.139806)
		(width 0.18288)
		(layer "In6.Cu")
		(net "M_G_CPU1_SB_DQ<27>")
	)
	(segment
		(start 158.132018 -200.308718)
		(end 150.131272 -208.309464)
		(width 0.18288)
		(layer "In6.Cu")
		(net "M_G_CPU1_SB_DQ<27>")
	)
	(segment
		(start 163.583874 -201.299826)
		(end 163.423854 -201.139806)
		(width 0.18288)
		(layer "In6.Cu")
		(net "M_G_CPU1_SB_DQ<27>")
	)
	(segment
		(start 141.934946 -218.7194)
		(end 141.713458 -218.940888)
		(width 0.088646)
		(layer "In6.Cu")
		(net "M_G_CPU1_SB_DQ<27>")
	)
	(segment
		(start 178.703986 -201.140822)
		(end 177.852324 -201.992484)
		(width 0.18288)
		(layer "In6.Cu")
		(net "M_G_CPU1_SB_DQ<27>")
	)
	(segment
		(start 150.131272 -209.540094)
		(end 142.430754 -217.240612)
		(width 0.18288)
		(layer "In6.Cu")
		(net "M_G_CPU1_SB_DQ<27>")
	)
	(segment
		(start 170.269662 -200.982326)
		(end 170.109642 -201.142346)
		(width 0.18288)
		(layer "In6.Cu")
		(net "M_G_CPU1_SB_DQ<27>")
	)
	(segment
		(start 162.570414 -201.299826)
		(end 161.740342 -201.299826)
		(width 0.18288)
		(layer "In6.Cu")
		(net "M_G_CPU1_SB_DQ<27>")
	)
	(segment
		(start 170.429682 -200.220072)
		(end 170.269662 -200.380092)
		(width 0.18288)
		(layer "In6.Cu")
		(net "M_G_CPU1_SB_DQ<27>")
	)
	(segment
		(start 191.983614 -201.56678)
		(end 191.557656 -201.140822)
		(width 0.18288)
		(layer "In6.Cu")
		(net "M_G_CPU1_SB_DQ<27>")
	)
	(segment
		(start 177.852324 -201.992484)
		(end 176.338484 -201.992484)
		(width 0.18288)
		(layer "In6.Cu")
		(net "M_G_CPU1_SB_DQ<27>")
	)
	(segment
		(start 160.749234 -200.308718)
		(end 158.132018 -200.308718)
		(width 0.18288)
		(layer "In6.Cu")
		(net "M_G_CPU1_SB_DQ<27>")
	)
	(segment
		(start 173.817534 -200.245472)
		(end 173.657514 -200.405492)
		(width 0.18288)
		(layer "In6.Cu")
		(net "M_G_CPU1_SB_DQ<27>")
	)
	(segment
		(start 163.263834 -200.53808)
		(end 162.890454 -200.53808)
		(width 0.18288)
		(layer "In6.Cu")
		(net "M_G_CPU1_SB_DQ<27>")
	)
	(segment
		(start 163.423854 -201.139806)
		(end 163.423854 -200.6981)
		(width 0.18288)
		(layer "In6.Cu")
		(net "M_G_CPU1_SB_DQ<27>")
	)
	(arc
		(start 140.491464 -219.01658)
		(mid 140.304266 -219.066723)
		(end 140.117068 -219.01658)
		(width 0.088646)
		(layer "In6.Cu")
		(net "M_G_CPU1_SB_DQ<27>")
	)
	(arc
		(start 141.056868 -219.01658)
		(mid 140.782669 -218.940745)
		(end 140.506196 -219.007944)
		(width 0.088646)
		(layer "In6.Cu")
		(net "M_G_CPU1_SB_DQ<27>")
	)
	(arc
		(start 141.713458 -218.940888)
		(mid 141.695289 -218.941107)
		(end 141.677136 -218.941904)
		(width 0.088646)
		(layer "In6.Cu")
		(net "M_G_CPU1_SB_DQ<27>")
	)
	(arc
		(start 140.117068 -219.01658)
		(mid 139.842869 -218.940745)
		(end 139.566396 -219.007944)
		(width 0.088646)
		(layer "In6.Cu")
		(net "M_G_CPU1_SB_DQ<27>")
	)
	(arc
		(start 141.431264 -219.01658)
		(mid 141.244066 -219.066723)
		(end 141.056868 -219.01658)
		(width 0.088646)
		(layer "In6.Cu")
		(net "M_G_CPU1_SB_DQ<27>")
	)
	(arc
		(start 141.677136 -218.941904)
		(mid 141.549908 -218.965102)
		(end 141.431264 -219.01658)
		(width 0.088646)
		(layer "In6.Cu")
		(net "M_G_CPU1_SB_DQ<27>")
	)
	(segment
		(start 195.510658 -203.698856)
		(end 195.515484 -203.698856)
		(width 0.101854)
		(layer "F.Cu")
		(net "M_G_CPU1_SB_DQ<26>")
	)
	(segment
		(start 199.298052 -203.266802)
		(end 200.632314 -203.266802)
		(width 0.20066)
		(layer "F.Cu")
		(net "M_G_CPU1_SB_DQ<26>")
	)
	(segment
		(start 191.983614 -203.266802)
		(end 193.088514 -203.266802)
		(width 0.20066)
		(layer "F.Cu")
		(net "M_G_CPU1_SB_DQ<26>")
	)
	(segment
		(start 137.954766 -220.041978)
		(end 137.954766 -219.506292)
		(width 0.20066)
		(layer "F.Cu")
		(net "M_G_CPU1_SB_DQ<26>")
	)
	(segment
		(start 198.427848 -203.499974)
		(end 198.427848 -203.249022)
		(width 0.20066)
		(layer "F.Cu")
		(net "M_G_CPU1_SB_DQ<26>")
	)
	(segment
		(start 198.662036 -203.014834)
		(end 199.046084 -203.014834)
		(width 0.20066)
		(layer "F.Cu")
		(net "M_G_CPU1_SB_DQ<26>")
	)
	(segment
		(start 195.218812 -203.698856)
		(end 195.510658 -203.698856)
		(width 0.20066)
		(layer "F.Cu")
		(net "M_G_CPU1_SB_DQ<26>")
	)
	(segment
		(start 195.515484 -203.698856)
		(end 195.522596 -203.691744)
		(width 0.1016)
		(layer "F.Cu")
		(net "M_G_CPU1_SB_DQ<26>")
	)
	(segment
		(start 195.522596 -203.691744)
		(end 197.530466 -203.691744)
		(width 0.1016)
		(layer "F.Cu")
		(net "M_G_CPU1_SB_DQ<26>")
	)
	(segment
		(start 193.088514 -203.266802)
		(end 194.786758 -203.266802)
		(width 0.20066)
		(layer "F.Cu")
		(net "M_G_CPU1_SB_DQ<26>")
	)
	(segment
		(start 198.223886 -203.703936)
		(end 198.427848 -203.499974)
		(width 0.20066)
		(layer "F.Cu")
		(net "M_G_CPU1_SB_DQ<26>")
	)
	(segment
		(start 137.954766 -219.506292)
		(end 137.954512 -219.506038)
		(width 0.20066)
		(layer "F.Cu")
		(net "M_G_CPU1_SB_DQ<26>")
	)
	(segment
		(start 197.530466 -203.691744)
		(end 197.542658 -203.703936)
		(width 0.1016)
		(layer "F.Cu")
		(net "M_G_CPU1_SB_DQ<26>")
	)
	(segment
		(start 199.046084 -203.014834)
		(end 199.298052 -203.266802)
		(width 0.20066)
		(layer "F.Cu")
		(net "M_G_CPU1_SB_DQ<26>")
	)
	(segment
		(start 198.427848 -203.249022)
		(end 198.662036 -203.014834)
		(width 0.20066)
		(layer "F.Cu")
		(net "M_G_CPU1_SB_DQ<26>")
	)
	(segment
		(start 194.786758 -203.266802)
		(end 195.218812 -203.698856)
		(width 0.20066)
		(layer "F.Cu")
		(net "M_G_CPU1_SB_DQ<26>")
	)
	(segment
		(start 197.542658 -203.703936)
		(end 198.223886 -203.703936)
		(width 0.20066)
		(layer "F.Cu")
		(net "M_G_CPU1_SB_DQ<26>")
	)
	(segment
		(start 166.596314 -203.289408)
		(end 166.222934 -203.289408)
		(width 0.18288)
		(layer "In6.Cu")
		(net "M_G_CPU1_SB_DQ<26>")
	)
	(segment
		(start 162.76701 -202.90282)
		(end 162.58413 -203.0857)
		(width 0.18288)
		(layer "In6.Cu")
		(net "M_G_CPU1_SB_DQ<26>")
	)
	(segment
		(start 166.062914 -202.869546)
		(end 165.902894 -202.709526)
		(width 0.18288)
		(layer "In6.Cu")
		(net "M_G_CPU1_SB_DQ<26>")
	)
	(segment
		(start 171.995084 -202.842368)
		(end 171.785026 -203.052426)
		(width 0.18288)
		(layer "In6.Cu")
		(net "M_G_CPU1_SB_DQ<26>")
	)
	(segment
		(start 165.902894 -202.709526)
		(end 164.812726 -202.709526)
		(width 0.18288)
		(layer "In6.Cu")
		(net "M_G_CPU1_SB_DQ<26>")
	)
	(segment
		(start 163.46043 -202.90282)
		(end 163.46043 -202.553824)
		(width 0.18288)
		(layer "In6.Cu")
		(net "M_G_CPU1_SB_DQ<26>")
	)
	(segment
		(start 162.94989 -202.370944)
		(end 162.76701 -202.553824)
		(width 0.18288)
		(layer "In6.Cu")
		(net "M_G_CPU1_SB_DQ<26>")
	)
	(segment
		(start 142.350998 -218.762072)
		(end 142.350998 -218.939364)
		(width 0.088646)
		(layer "In6.Cu")
		(net "M_G_CPU1_SB_DQ<26>")
	)
	(segment
		(start 177.906426 -203.692506)
		(end 176.235106 -203.692506)
		(width 0.18288)
		(layer "In6.Cu")
		(net "M_G_CPU1_SB_DQ<26>")
	)
	(segment
		(start 158.726632 -202.759056)
		(end 158.543752 -202.576176)
		(width 0.18288)
		(layer "In6.Cu")
		(net "M_G_CPU1_SB_DQ<26>")
	)
	(segment
		(start 138.050016 -220.319854)
		(end 138.050016 -220.286326)
		(width 0.088646)
		(layer "In6.Cu")
		(net "M_G_CPU1_SB_DQ<26>")
	)
	(segment
		(start 151.171402 -209.941668)
		(end 142.521686 -218.591384)
		(width 0.18288)
		(layer "In6.Cu")
		(net "M_G_CPU1_SB_DQ<26>")
	)
	(segment
		(start 161.7345 -203.0857)
		(end 161.224976 -202.576176)
		(width 0.18288)
		(layer "In6.Cu")
		(net "M_G_CPU1_SB_DQ<26>")
	)
	(segment
		(start 168.914826 -203.052426)
		(end 168.571926 -202.709526)
		(width 0.18288)
		(layer "In6.Cu")
		(net "M_G_CPU1_SB_DQ<26>")
	)
	(segment
		(start 166.222934 -203.289408)
		(end 166.062914 -203.129388)
		(width 0.18288)
		(layer "In6.Cu")
		(net "M_G_CPU1_SB_DQ<26>")
	)
	(segment
		(start 162.76701 -202.553824)
		(end 162.76701 -202.90282)
		(width 0.18288)
		(layer "In6.Cu")
		(net "M_G_CPU1_SB_DQ<26>")
	)
	(segment
		(start 176.235106 -203.692506)
		(end 175.384968 -202.842368)
		(width 0.18288)
		(layer "In6.Cu")
		(net "M_G_CPU1_SB_DQ<26>")
	)
	(segment
		(start 163.46043 -202.553824)
		(end 163.27755 -202.370944)
		(width 0.18288)
		(layer "In6.Cu")
		(net "M_G_CPU1_SB_DQ<26>")
	)
	(segment
		(start 166.756334 -203.129388)
		(end 166.596314 -203.289408)
		(width 0.18288)
		(layer "In6.Cu")
		(net "M_G_CPU1_SB_DQ<26>")
	)
	(segment
		(start 158.543752 -202.576176)
		(end 157.78607 -202.576176)
		(width 0.18288)
		(layer "In6.Cu")
		(net "M_G_CPU1_SB_DQ<26>")
	)
	(segment
		(start 138.237468 -220.644212)
		(end 138.228578 -220.639132)
		(width 0.088646)
		(layer "In6.Cu")
		(net "M_G_CPU1_SB_DQ<26>")
	)
	(segment
		(start 189.306962 -202.84059)
		(end 178.758342 -202.84059)
		(width 0.18288)
		(layer "In6.Cu")
		(net "M_G_CPU1_SB_DQ<26>")
	)
	(segment
		(start 162.58413 -203.0857)
		(end 161.7345 -203.0857)
		(width 0.18288)
		(layer "In6.Cu")
		(net "M_G_CPU1_SB_DQ<26>")
	)
	(segment
		(start 168.571926 -202.709526)
		(end 166.916354 -202.709526)
		(width 0.18288)
		(layer "In6.Cu")
		(net "M_G_CPU1_SB_DQ<26>")
	)
	(segment
		(start 163.27755 -202.370944)
		(end 162.94989 -202.370944)
		(width 0.18288)
		(layer "In6.Cu")
		(net "M_G_CPU1_SB_DQ<26>")
	)
	(segment
		(start 164.812726 -202.709526)
		(end 164.436552 -203.0857)
		(width 0.18288)
		(layer "In6.Cu")
		(net "M_G_CPU1_SB_DQ<26>")
	)
	(segment
		(start 142.521686 -218.591384)
		(end 142.350998 -218.762072)
		(width 0.088646)
		(layer "In6.Cu")
		(net "M_G_CPU1_SB_DQ<26>")
	)
	(segment
		(start 159.420052 -202.759056)
		(end 159.420052 -203.048362)
		(width 0.18288)
		(layer "In6.Cu")
		(net "M_G_CPU1_SB_DQ<26>")
	)
	(segment
		(start 159.237172 -203.231242)
		(end 158.909512 -203.231242)
		(width 0.18288)
		(layer "In6.Cu")
		(net "M_G_CPU1_SB_DQ<26>")
	)
	(segment
		(start 171.785026 -203.052426)
		(end 168.914826 -203.052426)
		(width 0.18288)
		(layer "In6.Cu")
		(net "M_G_CPU1_SB_DQ<26>")
	)
	(segment
		(start 163.64331 -203.0857)
		(end 163.46043 -202.90282)
		(width 0.18288)
		(layer "In6.Cu")
		(net "M_G_CPU1_SB_DQ<26>")
	)
	(segment
		(start 158.726632 -203.048362)
		(end 158.726632 -202.759056)
		(width 0.18288)
		(layer "In6.Cu")
		(net "M_G_CPU1_SB_DQ<26>")
	)
	(segment
		(start 141.591284 -219.699078)
		(end 141.455394 -219.699078)
		(width 0.088646)
		(layer "In6.Cu")
		(net "M_G_CPU1_SB_DQ<26>")
	)
	(segment
		(start 166.916354 -202.709526)
		(end 166.756334 -202.869546)
		(width 0.18288)
		(layer "In6.Cu")
		(net "M_G_CPU1_SB_DQ<26>")
	)
	(segment
		(start 141.455394 -219.699078)
		(end 140.569442 -220.58503)
		(width 0.088646)
		(layer "In6.Cu")
		(net "M_G_CPU1_SB_DQ<26>")
	)
	(segment
		(start 178.758342 -202.84059)
		(end 177.906426 -203.692506)
		(width 0.18288)
		(layer "In6.Cu")
		(net "M_G_CPU1_SB_DQ<26>")
	)
	(segment
		(start 151.171402 -209.190844)
		(end 151.171402 -209.941668)
		(width 0.18288)
		(layer "In6.Cu")
		(net "M_G_CPU1_SB_DQ<26>")
	)
	(segment
		(start 191.983614 -203.004674)
		(end 191.742568 -202.763628)
		(width 0.18288)
		(layer "In6.Cu")
		(net "M_G_CPU1_SB_DQ<26>")
	)
	(segment
		(start 159.602932 -202.576176)
		(end 159.420052 -202.759056)
		(width 0.18288)
		(layer "In6.Cu")
		(net "M_G_CPU1_SB_DQ<26>")
	)
	(segment
		(start 161.224976 -202.576176)
		(end 159.602932 -202.576176)
		(width 0.18288)
		(layer "In6.Cu")
		(net "M_G_CPU1_SB_DQ<26>")
	)
	(segment
		(start 166.756334 -202.869546)
		(end 166.756334 -203.129388)
		(width 0.18288)
		(layer "In6.Cu")
		(net "M_G_CPU1_SB_DQ<26>")
	)
	(segment
		(start 191.983614 -203.266802)
		(end 191.983614 -203.004674)
		(width 0.18288)
		(layer "In6.Cu")
		(net "M_G_CPU1_SB_DQ<26>")
	)
	(segment
		(start 142.350998 -218.939364)
		(end 141.591284 -219.699078)
		(width 0.088646)
		(layer "In6.Cu")
		(net "M_G_CPU1_SB_DQ<26>")
	)
	(segment
		(start 157.78607 -202.576176)
		(end 151.171402 -209.190844)
		(width 0.18288)
		(layer "In6.Cu")
		(net "M_G_CPU1_SB_DQ<26>")
	)
	(segment
		(start 189.383924 -202.763628)
		(end 189.306962 -202.84059)
		(width 0.18288)
		(layer "In6.Cu")
		(net "M_G_CPU1_SB_DQ<26>")
	)
	(segment
		(start 191.742568 -202.763628)
		(end 189.383924 -202.763628)
		(width 0.18288)
		(layer "In6.Cu")
		(net "M_G_CPU1_SB_DQ<26>")
	)
	(segment
		(start 138.050016 -220.286326)
		(end 137.954512 -219.506038)
		(width 0.088646)
		(layer "In6.Cu")
		(net "M_G_CPU1_SB_DQ<26>")
	)
	(segment
		(start 159.420052 -203.048362)
		(end 159.237172 -203.231242)
		(width 0.18288)
		(layer "In6.Cu")
		(net "M_G_CPU1_SB_DQ<26>")
	)
	(segment
		(start 158.909512 -203.231242)
		(end 158.726632 -203.048362)
		(width 0.18288)
		(layer "In6.Cu")
		(net "M_G_CPU1_SB_DQ<26>")
	)
	(segment
		(start 175.384968 -202.842368)
		(end 171.995084 -202.842368)
		(width 0.18288)
		(layer "In6.Cu")
		(net "M_G_CPU1_SB_DQ<26>")
	)
	(segment
		(start 166.062914 -203.129388)
		(end 166.062914 -202.869546)
		(width 0.18288)
		(layer "In6.Cu")
		(net "M_G_CPU1_SB_DQ<26>")
	)
	(segment
		(start 164.436552 -203.0857)
		(end 163.64331 -203.0857)
		(width 0.18288)
		(layer "In6.Cu")
		(net "M_G_CPU1_SB_DQ<26>")
	)
	(arc
		(start 138.228578 -220.639132)
		(mid 138.097664 -220.502772)
		(end 138.050016 -220.319854)
		(width 0.088646)
		(layer "In6.Cu")
		(net "M_G_CPU1_SB_DQ<26>")
	)
	(arc
		(start 139.177268 -220.644212)
		(mid 138.894566 -220.56847)
		(end 138.611864 -220.644212)
		(width 0.088646)
		(layer "In6.Cu")
		(net "M_G_CPU1_SB_DQ<26>")
	)
	(arc
		(start 140.491464 -220.644212)
		(mid 140.304266 -220.694355)
		(end 140.117068 -220.644212)
		(width 0.088646)
		(layer "In6.Cu")
		(net "M_G_CPU1_SB_DQ<26>")
	)
	(arc
		(start 140.569442 -220.58503)
		(mid 140.532392 -220.617176)
		(end 140.491464 -220.644212)
		(width 0.088646)
		(layer "In6.Cu")
		(net "M_G_CPU1_SB_DQ<26>")
	)
	(arc
		(start 138.611864 -220.644212)
		(mid 138.424666 -220.694355)
		(end 138.237468 -220.644212)
		(width 0.088646)
		(layer "In6.Cu")
		(net "M_G_CPU1_SB_DQ<26>")
	)
	(arc
		(start 139.551664 -220.644212)
		(mid 139.364466 -220.694355)
		(end 139.177268 -220.644212)
		(width 0.088646)
		(layer "In6.Cu")
		(net "M_G_CPU1_SB_DQ<26>")
	)
	(arc
		(start 140.117068 -220.644212)
		(mid 139.834366 -220.56847)
		(end 139.551664 -220.644212)
		(width 0.088646)
		(layer "In6.Cu")
		(net "M_G_CPU1_SB_DQ<26>")
	)
	(segment
		(start 194.092576 -201.991722)
		(end 191.903858 -201.991722)
		(width 0.1016)
		(layer "F.Cu")
		(net "M_G_CPU1_SB_DQ<25>")
	)
	(segment
		(start 196.531992 -202.416918)
		(end 194.940428 -202.416918)
		(width 0.20066)
		(layer "F.Cu")
		(net "M_G_CPU1_SB_DQ<25>")
	)
	(segment
		(start 191.233044 -202.66533)
		(end 190.75781 -202.66533)
		(width 0.20066)
		(layer "F.Cu")
		(net "M_G_CPU1_SB_DQ<25>")
	)
	(segment
		(start 194.508882 -201.985372)
		(end 194.098926 -201.985372)
		(width 0.20066)
		(layer "F.Cu")
		(net "M_G_CPU1_SB_DQ<25>")
	)
	(segment
		(start 196.532246 -202.416664)
		(end 196.531992 -202.416918)
		(width 0.20066)
		(layer "F.Cu")
		(net "M_G_CPU1_SB_DQ<25>")
	)
	(segment
		(start 191.883792 -201.991722)
		(end 191.539114 -201.991722)
		(width 0.20066)
		(layer "F.Cu")
		(net "M_G_CPU1_SB_DQ<25>")
	)
	(segment
		(start 191.421004 -202.47737)
		(end 191.233044 -202.66533)
		(width 0.20066)
		(layer "F.Cu")
		(net "M_G_CPU1_SB_DQ<25>")
	)
	(segment
		(start 194.940428 -202.416918)
		(end 194.508882 -201.985372)
		(width 0.20066)
		(layer "F.Cu")
		(net "M_G_CPU1_SB_DQ<25>")
	)
	(segment
		(start 191.539114 -201.991722)
		(end 191.421004 -202.109832)
		(width 0.20066)
		(layer "F.Cu")
		(net "M_G_CPU1_SB_DQ<25>")
	)
	(segment
		(start 190.75781 -202.66533)
		(end 190.509144 -202.416664)
		(width 0.20066)
		(layer "F.Cu")
		(net "M_G_CPU1_SB_DQ<25>")
	)
	(segment
		(start 194.098926 -201.985372)
		(end 194.092576 -201.991722)
		(width 0.1016)
		(layer "F.Cu")
		(net "M_G_CPU1_SB_DQ<25>")
	)
	(segment
		(start 188.988446 -202.416664)
		(end 187.883546 -202.416664)
		(width 0.20066)
		(layer "F.Cu")
		(net "M_G_CPU1_SB_DQ<25>")
	)
	(segment
		(start 191.421004 -202.109832)
		(end 191.421004 -202.47737)
		(width 0.20066)
		(layer "F.Cu")
		(net "M_G_CPU1_SB_DQ<25>")
	)
	(segment
		(start 135.135112 -220.041978)
		(end 135.135366 -220.041724)
		(width 0.20066)
		(layer "F.Cu")
		(net "M_G_CPU1_SB_DQ<25>")
	)
	(segment
		(start 191.903858 -201.991722)
		(end 191.883792 -201.991722)
		(width 0.101854)
		(layer "F.Cu")
		(net "M_G_CPU1_SB_DQ<25>")
	)
	(segment
		(start 135.135366 -220.041724)
		(end 135.135366 -219.506038)
		(width 0.20066)
		(layer "F.Cu")
		(net "M_G_CPU1_SB_DQ<25>")
	)
	(segment
		(start 190.509144 -202.416664)
		(end 188.988446 -202.416664)
		(width 0.20066)
		(layer "F.Cu")
		(net "M_G_CPU1_SB_DQ<25>")
	)
	(segment
		(start 161.320226 -202.036426)
		(end 159.439102 -202.036426)
		(width 0.18288)
		(layer "In6.Cu")
		(net "M_G_CPU1_SB_DQ<25>")
	)
	(segment
		(start 173.497748 -201.99223)
		(end 172.04563 -201.99223)
		(width 0.18288)
		(layer "In6.Cu")
		(net "M_G_CPU1_SB_DQ<25>")
	)
	(segment
		(start 173.80839 -202.302872)
		(end 173.497748 -201.99223)
		(width 0.18288)
		(layer "In6.Cu")
		(net "M_G_CPU1_SB_DQ<25>")
	)
	(segment
		(start 166.650162 -201.642472)
		(end 166.276782 -201.642472)
		(width 0.18288)
		(layer "In6.Cu")
		(net "M_G_CPU1_SB_DQ<25>")
	)
	(segment
		(start 166.276782 -201.642472)
		(end 166.116762 -201.802492)
		(width 0.18288)
		(layer "In6.Cu")
		(net "M_G_CPU1_SB_DQ<25>")
	)
	(segment
		(start 171.912026 -201.858626)
		(end 170.901868 -201.858626)
		(width 0.18288)
		(layer "In6.Cu")
		(net "M_G_CPU1_SB_DQ<25>")
	)
	(segment
		(start 166.970202 -202.188826)
		(end 166.810182 -202.028806)
		(width 0.18288)
		(layer "In6.Cu")
		(net "M_G_CPU1_SB_DQ<25>")
	)
	(segment
		(start 142.13205 -218.266772)
		(end 142.13205 -218.811094)
		(width 0.088646)
		(layer "In6.Cu")
		(net "M_G_CPU1_SB_DQ<25>")
	)
	(segment
		(start 168.610026 -202.188826)
		(end 166.970202 -202.188826)
		(width 0.18288)
		(layer "In6.Cu")
		(net "M_G_CPU1_SB_DQ<25>")
	)
	(segment
		(start 139.459462 -219.506292)
		(end 139.459462 -219.506546)
		(width 0.088646)
		(layer "In6.Cu")
		(net "M_G_CPU1_SB_DQ<25>")
	)
	(segment
		(start 150.666196 -209.732626)
		(end 142.418562 -217.98026)
		(width 0.18288)
		(layer "In6.Cu")
		(net "M_G_CPU1_SB_DQ<25>")
	)
	(segment
		(start 135.860028 -219.197936)
		(end 135.135366 -219.506038)
		(width 0.088646)
		(layer "In6.Cu")
		(net "M_G_CPU1_SB_DQ<25>")
	)
	(segment
		(start 138.612626 -219.995496)
		(end 138.611864 -219.995242)
		(width 0.088646)
		(layer "In6.Cu")
		(net "M_G_CPU1_SB_DQ<25>")
	)
	(segment
		(start 174.50181 -201.99223)
		(end 174.191168 -202.302872)
		(width 0.18288)
		(layer "In6.Cu")
		(net "M_G_CPU1_SB_DQ<25>")
	)
	(segment
		(start 166.810182 -201.802492)
		(end 166.650162 -201.642472)
		(width 0.18288)
		(layer "In6.Cu")
		(net "M_G_CPU1_SB_DQ<25>")
	)
	(segment
		(start 172.04563 -201.99223)
		(end 171.912026 -201.858626)
		(width 0.18288)
		(layer "In6.Cu")
		(net "M_G_CPU1_SB_DQ<25>")
	)
	(segment
		(start 166.116762 -202.028806)
		(end 165.956742 -202.188826)
		(width 0.18288)
		(layer "In6.Cu")
		(net "M_G_CPU1_SB_DQ<25>")
	)
	(segment
		(start 158.425642 -202.036426)
		(end 157.408626 -202.036426)
		(width 0.18288)
		(layer "In6.Cu")
		(net "M_G_CPU1_SB_DQ<25>")
	)
	(segment
		(start 169.842688 -201.858626)
		(end 168.940226 -201.858626)
		(width 0.18288)
		(layer "In6.Cu")
		(net "M_G_CPU1_SB_DQ<25>")
	)
	(segment
		(start 150.666196 -208.778856)
		(end 150.666196 -209.732626)
		(width 0.18288)
		(layer "In6.Cu")
		(net "M_G_CPU1_SB_DQ<25>")
	)
	(segment
		(start 164.800026 -202.188826)
		(end 164.444426 -201.833226)
		(width 0.18288)
		(layer "In6.Cu")
		(net "M_G_CPU1_SB_DQ<25>")
	)
	(segment
		(start 141.811248 -219.131896)
		(end 141.71295 -219.131388)
		(width 0.088646)
		(layer "In6.Cu")
		(net "M_G_CPU1_SB_DQ<25>")
	)
	(segment
		(start 159.279082 -200.97369)
		(end 159.119062 -200.81367)
		(width 0.18288)
		(layer "In6.Cu")
		(net "M_G_CPU1_SB_DQ<25>")
	)
	(segment
		(start 170.208448 -202.54214)
		(end 170.025568 -202.35926)
		(width 0.18288)
		(layer "In6.Cu")
		(net "M_G_CPU1_SB_DQ<25>")
	)
	(segment
		(start 158.745682 -200.81367)
		(end 158.585662 -200.97369)
		(width 0.18288)
		(layer "In6.Cu")
		(net "M_G_CPU1_SB_DQ<25>")
	)
	(segment
		(start 178.699922 -201.99477)
		(end 177.852324 -202.842368)
		(width 0.18288)
		(layer "In6.Cu")
		(net "M_G_CPU1_SB_DQ<25>")
	)
	(segment
		(start 165.956742 -202.188826)
		(end 164.800026 -202.188826)
		(width 0.18288)
		(layer "In6.Cu")
		(net "M_G_CPU1_SB_DQ<25>")
	)
	(segment
		(start 159.439102 -202.036426)
		(end 159.279082 -201.876406)
		(width 0.18288)
		(layer "In6.Cu")
		(net "M_G_CPU1_SB_DQ<25>")
	)
	(segment
		(start 140.586714 -219.18168)
		(end 140.571982 -219.190316)
		(width 0.088646)
		(layer "In6.Cu")
		(net "M_G_CPU1_SB_DQ<25>")
	)
	(segment
		(start 187.461652 -201.99477)
		(end 178.699922 -201.99477)
		(width 0.18288)
		(layer "In6.Cu")
		(net "M_G_CPU1_SB_DQ<25>")
	)
	(segment
		(start 187.883546 -202.416664)
		(end 187.461652 -201.99477)
		(width 0.18288)
		(layer "In6.Cu")
		(net "M_G_CPU1_SB_DQ<25>")
	)
	(segment
		(start 138.141964 -219.181934)
		(end 138.14171 -219.18168)
		(width 0.088646)
		(layer "In6.Cu")
		(net "M_G_CPU1_SB_DQ<25>")
	)
	(segment
		(start 166.810182 -202.028806)
		(end 166.810182 -201.802492)
		(width 0.18288)
		(layer "In6.Cu")
		(net "M_G_CPU1_SB_DQ<25>")
	)
	(segment
		(start 170.536108 -202.54214)
		(end 170.208448 -202.54214)
		(width 0.18288)
		(layer "In6.Cu")
		(net "M_G_CPU1_SB_DQ<25>")
	)
	(segment
		(start 175.39843 -201.99223)
		(end 174.50181 -201.99223)
		(width 0.18288)
		(layer "In6.Cu")
		(net "M_G_CPU1_SB_DQ<25>")
	)
	(segment
		(start 166.116762 -201.802492)
		(end 166.116762 -202.028806)
		(width 0.18288)
		(layer "In6.Cu")
		(net "M_G_CPU1_SB_DQ<25>")
	)
	(segment
		(start 158.585662 -200.97369)
		(end 158.585662 -201.876406)
		(width 0.18288)
		(layer "In6.Cu")
		(net "M_G_CPU1_SB_DQ<25>")
	)
	(segment
		(start 157.408626 -202.036426)
		(end 150.666196 -208.778856)
		(width 0.18288)
		(layer "In6.Cu")
		(net "M_G_CPU1_SB_DQ<25>")
	)
	(segment
		(start 170.025568 -202.041506)
		(end 169.842688 -201.858626)
		(width 0.18288)
		(layer "In6.Cu")
		(net "M_G_CPU1_SB_DQ<25>")
	)
	(segment
		(start 177.852324 -202.842368)
		(end 176.248568 -202.842368)
		(width 0.18288)
		(layer "In6.Cu")
		(net "M_G_CPU1_SB_DQ<25>")
	)
	(segment
		(start 142.418562 -217.98026)
		(end 142.13205 -218.266772)
		(width 0.088646)
		(layer "In6.Cu")
		(net "M_G_CPU1_SB_DQ<25>")
	)
	(segment
		(start 159.279082 -201.876406)
		(end 159.279082 -200.97369)
		(width 0.18288)
		(layer "In6.Cu")
		(net "M_G_CPU1_SB_DQ<25>")
	)
	(segment
		(start 176.248568 -202.842368)
		(end 175.39843 -201.99223)
		(width 0.18288)
		(layer "In6.Cu")
		(net "M_G_CPU1_SB_DQ<25>")
	)
	(segment
		(start 135.887968 -219.18168)
		(end 135.860028 -219.197936)
		(width 0.088646)
		(layer "In6.Cu")
		(net "M_G_CPU1_SB_DQ<25>")
	)
	(segment
		(start 168.940226 -201.858626)
		(end 168.610026 -202.188826)
		(width 0.18288)
		(layer "In6.Cu")
		(net "M_G_CPU1_SB_DQ<25>")
	)
	(segment
		(start 158.585662 -201.876406)
		(end 158.425642 -202.036426)
		(width 0.18288)
		(layer "In6.Cu")
		(net "M_G_CPU1_SB_DQ<25>")
	)
	(segment
		(start 142.13205 -218.811094)
		(end 141.811248 -219.131896)
		(width 0.088646)
		(layer "In6.Cu")
		(net "M_G_CPU1_SB_DQ<25>")
	)
	(segment
		(start 174.191168 -202.302872)
		(end 173.80839 -202.302872)
		(width 0.18288)
		(layer "In6.Cu")
		(net "M_G_CPU1_SB_DQ<25>")
	)
	(segment
		(start 170.025568 -202.35926)
		(end 170.025568 -202.041506)
		(width 0.18288)
		(layer "In6.Cu")
		(net "M_G_CPU1_SB_DQ<25>")
	)
	(segment
		(start 170.718988 -202.041506)
		(end 170.718988 -202.35926)
		(width 0.18288)
		(layer "In6.Cu")
		(net "M_G_CPU1_SB_DQ<25>")
	)
	(segment
		(start 137.767314 -219.18168)
		(end 137.752582 -219.190316)
		(width 0.088646)
		(layer "In6.Cu")
		(net "M_G_CPU1_SB_DQ<25>")
	)
	(segment
		(start 159.119062 -200.81367)
		(end 158.745682 -200.81367)
		(width 0.18288)
		(layer "In6.Cu")
		(net "M_G_CPU1_SB_DQ<25>")
	)
	(segment
		(start 141.526514 -219.18168)
		(end 141.511782 -219.190316)
		(width 0.088646)
		(layer "In6.Cu")
		(net "M_G_CPU1_SB_DQ<25>")
	)
	(segment
		(start 161.523426 -201.833226)
		(end 161.320226 -202.036426)
		(width 0.18288)
		(layer "In6.Cu")
		(net "M_G_CPU1_SB_DQ<25>")
	)
	(segment
		(start 136.827514 -219.18168)
		(end 136.8171 -219.187776)
		(width 0.088646)
		(layer "In6.Cu")
		(net "M_G_CPU1_SB_DQ<25>")
	)
	(segment
		(start 170.901868 -201.858626)
		(end 170.718988 -202.041506)
		(width 0.18288)
		(layer "In6.Cu")
		(net "M_G_CPU1_SB_DQ<25>")
	)
	(segment
		(start 170.718988 -202.35926)
		(end 170.536108 -202.54214)
		(width 0.18288)
		(layer "In6.Cu")
		(net "M_G_CPU1_SB_DQ<25>")
	)
	(segment
		(start 164.444426 -201.833226)
		(end 161.523426 -201.833226)
		(width 0.18288)
		(layer "In6.Cu")
		(net "M_G_CPU1_SB_DQ<25>")
	)
	(arc
		(start 140.571982 -219.190316)
		(mid 140.295507 -219.257636)
		(end 140.02131 -219.18168)
		(width 0.088646)
		(layer "In6.Cu")
		(net "M_G_CPU1_SB_DQ<25>")
	)
	(arc
		(start 138.611864 -219.995242)
		(mid 138.40492 -219.788532)
		(end 138.329162 -219.506038)
		(width 0.088646)
		(layer "In6.Cu")
		(net "M_G_CPU1_SB_DQ<25>")
	)
	(arc
		(start 139.646914 -219.18168)
		(mid 139.50973 -219.318882)
		(end 139.459462 -219.506292)
		(width 0.088646)
		(layer "In6.Cu")
		(net "M_G_CPU1_SB_DQ<25>")
	)
	(arc
		(start 137.752582 -219.190316)
		(mid 137.476107 -219.257636)
		(end 137.20191 -219.18168)
		(width 0.088646)
		(layer "In6.Cu")
		(net "M_G_CPU1_SB_DQ<25>")
	)
	(arc
		(start 140.02131 -219.18168)
		(mid 139.834112 -219.131537)
		(end 139.646914 -219.18168)
		(width 0.088646)
		(layer "In6.Cu")
		(net "M_G_CPU1_SB_DQ<25>")
	)
	(arc
		(start 141.511782 -219.190316)
		(mid 141.235307 -219.257636)
		(end 140.96111 -219.18168)
		(width 0.088646)
		(layer "In6.Cu")
		(net "M_G_CPU1_SB_DQ<25>")
	)
	(arc
		(start 138.329162 -219.506038)
		(mid 138.278998 -219.3189)
		(end 138.141964 -219.181934)
		(width 0.088646)
		(layer "In6.Cu")
		(net "M_G_CPU1_SB_DQ<25>")
	)
	(arc
		(start 136.262364 -219.18168)
		(mid 136.075166 -219.131503)
		(end 135.887968 -219.18168)
		(width 0.088646)
		(layer "In6.Cu")
		(net "M_G_CPU1_SB_DQ<25>")
	)
	(arc
		(start 138.14171 -219.18168)
		(mid 137.954512 -219.131537)
		(end 137.767314 -219.18168)
		(width 0.088646)
		(layer "In6.Cu")
		(net "M_G_CPU1_SB_DQ<25>")
	)
	(arc
		(start 141.71295 -219.131388)
		(mid 141.616432 -219.144305)
		(end 141.526514 -219.18168)
		(width 0.088646)
		(layer "In6.Cu")
		(net "M_G_CPU1_SB_DQ<25>")
	)
	(arc
		(start 139.459462 -219.506546)
		(mid 139.177179 -219.995518)
		(end 138.612626 -219.995496)
		(width 0.088646)
		(layer "In6.Cu")
		(net "M_G_CPU1_SB_DQ<25>")
	)
	(arc
		(start 137.20191 -219.18168)
		(mid 137.014712 -219.131537)
		(end 136.827514 -219.18168)
		(width 0.088646)
		(layer "In6.Cu")
		(net "M_G_CPU1_SB_DQ<25>")
	)
	(arc
		(start 136.8171 -219.187776)
		(mid 136.538922 -219.257499)
		(end 136.262364 -219.18168)
		(width 0.088646)
		(layer "In6.Cu")
		(net "M_G_CPU1_SB_DQ<25>")
	)
	(arc
		(start 140.96111 -219.18168)
		(mid 140.773912 -219.131537)
		(end 140.586714 -219.18168)
		(width 0.088646)
		(layer "In6.Cu")
		(net "M_G_CPU1_SB_DQ<25>")
	)
	(segment
		(start 196.531992 -204.11694)
		(end 194.940428 -204.11694)
		(width 0.20066)
		(layer "F.Cu")
		(net "M_G_CPU1_SB_DQ<24>")
	)
	(segment
		(start 191.539114 -203.691744)
		(end 191.421004 -203.809854)
		(width 0.20066)
		(layer "F.Cu")
		(net "M_G_CPU1_SB_DQ<24>")
	)
	(segment
		(start 191.883792 -203.691744)
		(end 191.539114 -203.691744)
		(width 0.20066)
		(layer "F.Cu")
		(net "M_G_CPU1_SB_DQ<24>")
	)
	(segment
		(start 194.940428 -204.11694)
		(end 194.508882 -203.685394)
		(width 0.20066)
		(layer "F.Cu")
		(net "M_G_CPU1_SB_DQ<24>")
	)
	(segment
		(start 191.233044 -204.365352)
		(end 190.75781 -204.365352)
		(width 0.20066)
		(layer "F.Cu")
		(net "M_G_CPU1_SB_DQ<24>")
	)
	(segment
		(start 136.075166 -220.041978)
		(end 136.075166 -219.506038)
		(width 0.20066)
		(layer "F.Cu")
		(net "M_G_CPU1_SB_DQ<24>")
	)
	(segment
		(start 191.930782 -203.691744)
		(end 191.883792 -203.691744)
		(width 0.101854)
		(layer "F.Cu")
		(net "M_G_CPU1_SB_DQ<24>")
	)
	(segment
		(start 194.098926 -203.685394)
		(end 194.092576 -203.691744)
		(width 0.1016)
		(layer "F.Cu")
		(net "M_G_CPU1_SB_DQ<24>")
	)
	(segment
		(start 190.509144 -204.116686)
		(end 188.988446 -204.116686)
		(width 0.20066)
		(layer "F.Cu")
		(net "M_G_CPU1_SB_DQ<24>")
	)
	(segment
		(start 188.988446 -204.116686)
		(end 187.883546 -204.116686)
		(width 0.20066)
		(layer "F.Cu")
		(net "M_G_CPU1_SB_DQ<24>")
	)
	(segment
		(start 190.75781 -204.365352)
		(end 190.509144 -204.116686)
		(width 0.20066)
		(layer "F.Cu")
		(net "M_G_CPU1_SB_DQ<24>")
	)
	(segment
		(start 196.532246 -204.116686)
		(end 196.531992 -204.11694)
		(width 0.20066)
		(layer "F.Cu")
		(net "M_G_CPU1_SB_DQ<24>")
	)
	(segment
		(start 191.421004 -204.177392)
		(end 191.233044 -204.365352)
		(width 0.20066)
		(layer "F.Cu")
		(net "M_G_CPU1_SB_DQ<24>")
	)
	(segment
		(start 191.421004 -203.809854)
		(end 191.421004 -204.177392)
		(width 0.20066)
		(layer "F.Cu")
		(net "M_G_CPU1_SB_DQ<24>")
	)
	(segment
		(start 194.508882 -203.685394)
		(end 194.098926 -203.685394)
		(width 0.20066)
		(layer "F.Cu")
		(net "M_G_CPU1_SB_DQ<24>")
	)
	(segment
		(start 194.092576 -203.691744)
		(end 191.930782 -203.691744)
		(width 0.1016)
		(layer "F.Cu")
		(net "M_G_CPU1_SB_DQ<24>")
	)
	(segment
		(start 170.795442 -203.875132)
		(end 170.795442 -204.259434)
		(width 0.18288)
		(layer "In6.Cu")
		(net "M_G_CPU1_SB_DQ<24>")
	)
	(segment
		(start 164.724334 -203.586334)
		(end 163.531804 -203.586334)
		(width 0.18288)
		(layer "In6.Cu")
		(net "M_G_CPU1_SB_DQ<24>")
	)
	(segment
		(start 163.531804 -203.586334)
		(end 163.348924 -203.769214)
		(width 0.18288)
		(layer "In6.Cu")
		(net "M_G_CPU1_SB_DQ<24>")
	)
	(segment
		(start 173.599856 -203.692252)
		(end 170.978322 -203.692252)
		(width 0.18288)
		(layer "In6.Cu")
		(net "M_G_CPU1_SB_DQ<24>")
	)
	(segment
		(start 180.079142 -204.183742)
		(end 179.552092 -203.656692)
		(width 0.18288)
		(layer "In6.Cu")
		(net "M_G_CPU1_SB_DQ<24>")
	)
	(segment
		(start 151.680418 -209.390234)
		(end 151.680418 -210.141058)
		(width 0.18288)
		(layer "In6.Cu")
		(net "M_G_CPU1_SB_DQ<24>")
	)
	(segment
		(start 170.102022 -203.875132)
		(end 169.919142 -203.692252)
		(width 0.18288)
		(layer "In6.Cu")
		(net "M_G_CPU1_SB_DQ<24>")
	)
	(segment
		(start 173.965616 -204.38237)
		(end 173.782736 -204.19949)
		(width 0.18288)
		(layer "In6.Cu")
		(net "M_G_CPU1_SB_DQ<24>")
	)
	(segment
		(start 136.732264 -219.995496)
		(end 136.703562 -219.97924)
		(width 0.088646)
		(layer "In6.Cu")
		(net "M_G_CPU1_SB_DQ<24>")
	)
	(segment
		(start 174.476156 -204.19949)
		(end 174.293276 -204.38237)
		(width 0.18288)
		(layer "In6.Cu")
		(net "M_G_CPU1_SB_DQ<24>")
	)
	(segment
		(start 159.217614 -203.792836)
		(end 159.034734 -203.975716)
		(width 0.18288)
		(layer "In6.Cu")
		(net "M_G_CPU1_SB_DQ<24>")
	)
	(segment
		(start 159.034734 -204.404722)
		(end 158.851854 -204.587602)
		(width 0.18288)
		(layer "In6.Cu")
		(net "M_G_CPU1_SB_DQ<24>")
	)
	(segment
		(start 170.284902 -204.442314)
		(end 170.102022 -204.259434)
		(width 0.18288)
		(layer "In6.Cu")
		(net "M_G_CPU1_SB_DQ<24>")
	)
	(segment
		(start 159.034734 -203.975716)
		(end 159.034734 -204.404722)
		(width 0.18288)
		(layer "In6.Cu")
		(net "M_G_CPU1_SB_DQ<24>")
	)
	(segment
		(start 163.348924 -204.225144)
		(end 163.166044 -204.408024)
		(width 0.18288)
		(layer "In6.Cu")
		(net "M_G_CPU1_SB_DQ<24>")
	)
	(segment
		(start 165.130226 -203.992226)
		(end 164.724334 -203.586334)
		(width 0.18288)
		(layer "In6.Cu")
		(net "M_G_CPU1_SB_DQ<24>")
	)
	(segment
		(start 163.348924 -203.769214)
		(end 163.348924 -204.225144)
		(width 0.18288)
		(layer "In6.Cu")
		(net "M_G_CPU1_SB_DQ<24>")
	)
	(segment
		(start 178.033426 -204.54239)
		(end 176.11979 -204.54239)
		(width 0.18288)
		(layer "In6.Cu")
		(net "M_G_CPU1_SB_DQ<24>")
	)
	(segment
		(start 162.655504 -203.769214)
		(end 162.472624 -203.586334)
		(width 0.18288)
		(layer "In6.Cu")
		(net "M_G_CPU1_SB_DQ<24>")
	)
	(segment
		(start 160.960816 -203.792836)
		(end 159.217614 -203.792836)
		(width 0.18288)
		(layer "In6.Cu")
		(net "M_G_CPU1_SB_DQ<24>")
	)
	(segment
		(start 170.612562 -204.442314)
		(end 170.284902 -204.442314)
		(width 0.18288)
		(layer "In6.Cu")
		(net "M_G_CPU1_SB_DQ<24>")
	)
	(segment
		(start 174.476156 -203.875132)
		(end 174.476156 -204.19949)
		(width 0.18288)
		(layer "In6.Cu")
		(net "M_G_CPU1_SB_DQ<24>")
	)
	(segment
		(start 183.102504 -203.518516)
		(end 182.920132 -203.518516)
		(width 0.18288)
		(layer "In6.Cu")
		(net "M_G_CPU1_SB_DQ<24>")
	)
	(segment
		(start 142.398242 -219.423234)
		(end 142.398242 -219.424758)
		(width 0.088646)
		(layer "In6.Cu")
		(net "M_G_CPU1_SB_DQ<24>")
	)
	(segment
		(start 151.680418 -210.141058)
		(end 142.398242 -219.423234)
		(width 0.18288)
		(layer "In6.Cu")
		(net "M_G_CPU1_SB_DQ<24>")
	)
	(segment
		(start 170.978322 -203.692252)
		(end 170.795442 -203.875132)
		(width 0.18288)
		(layer "In6.Cu")
		(net "M_G_CPU1_SB_DQ<24>")
	)
	(segment
		(start 183.955944 -203.678536)
		(end 183.955944 -204.19949)
		(width 0.18288)
		(layer "In6.Cu")
		(net "M_G_CPU1_SB_DQ<24>")
	)
	(segment
		(start 173.782736 -204.19949)
		(end 173.782736 -203.875132)
		(width 0.18288)
		(layer "In6.Cu")
		(net "M_G_CPU1_SB_DQ<24>")
	)
	(segment
		(start 183.262524 -204.19949)
		(end 183.262524 -203.678536)
		(width 0.18288)
		(layer "In6.Cu")
		(net "M_G_CPU1_SB_DQ<24>")
	)
	(segment
		(start 158.341314 -204.404722)
		(end 158.341314 -203.975716)
		(width 0.18288)
		(layer "In6.Cu")
		(net "M_G_CPU1_SB_DQ<24>")
	)
	(segment
		(start 170.102022 -204.259434)
		(end 170.102022 -203.875132)
		(width 0.18288)
		(layer "In6.Cu")
		(net "M_G_CPU1_SB_DQ<24>")
	)
	(segment
		(start 169.919142 -203.692252)
		(end 168.9354 -203.692252)
		(width 0.18288)
		(layer "In6.Cu")
		(net "M_G_CPU1_SB_DQ<24>")
	)
	(segment
		(start 183.955944 -204.19949)
		(end 183.795924 -204.35951)
		(width 0.18288)
		(layer "In6.Cu")
		(net "M_G_CPU1_SB_DQ<24>")
	)
	(segment
		(start 136.919716 -220.320362)
		(end 136.919716 -220.319854)
		(width 0.088646)
		(layer "In6.Cu")
		(net "M_G_CPU1_SB_DQ<24>")
	)
	(segment
		(start 182.254906 -204.183742)
		(end 180.079142 -204.183742)
		(width 0.18288)
		(layer "In6.Cu")
		(net "M_G_CPU1_SB_DQ<24>")
	)
	(segment
		(start 170.795442 -204.259434)
		(end 170.612562 -204.442314)
		(width 0.18288)
		(layer "In6.Cu")
		(net "M_G_CPU1_SB_DQ<24>")
	)
	(segment
		(start 183.795924 -204.35951)
		(end 183.422544 -204.35951)
		(width 0.18288)
		(layer "In6.Cu")
		(net "M_G_CPU1_SB_DQ<24>")
	)
	(segment
		(start 173.782736 -203.875132)
		(end 173.599856 -203.692252)
		(width 0.18288)
		(layer "In6.Cu")
		(net "M_G_CPU1_SB_DQ<24>")
	)
	(segment
		(start 174.659036 -203.692252)
		(end 174.476156 -203.875132)
		(width 0.18288)
		(layer "In6.Cu")
		(net "M_G_CPU1_SB_DQ<24>")
	)
	(segment
		(start 158.341314 -203.975716)
		(end 158.158434 -203.792836)
		(width 0.18288)
		(layer "In6.Cu")
		(net "M_G_CPU1_SB_DQ<24>")
	)
	(segment
		(start 136.741154 -220.000576)
		(end 136.732264 -219.995496)
		(width 0.088646)
		(layer "In6.Cu")
		(net "M_G_CPU1_SB_DQ<24>")
	)
	(segment
		(start 158.158434 -203.792836)
		(end 157.277816 -203.792836)
		(width 0.18288)
		(layer "In6.Cu")
		(net "M_G_CPU1_SB_DQ<24>")
	)
	(segment
		(start 162.472624 -203.586334)
		(end 161.167318 -203.586334)
		(width 0.18288)
		(layer "In6.Cu")
		(net "M_G_CPU1_SB_DQ<24>")
	)
	(segment
		(start 163.166044 -204.408024)
		(end 162.838384 -204.408024)
		(width 0.18288)
		(layer "In6.Cu")
		(net "M_G_CPU1_SB_DQ<24>")
	)
	(segment
		(start 141.240002 -220.18371)
		(end 140.704062 -220.71965)
		(width 0.088646)
		(layer "In6.Cu")
		(net "M_G_CPU1_SB_DQ<24>")
	)
	(segment
		(start 183.422544 -204.35951)
		(end 183.262524 -204.19949)
		(width 0.18288)
		(layer "In6.Cu")
		(net "M_G_CPU1_SB_DQ<24>")
	)
	(segment
		(start 162.838384 -204.408024)
		(end 162.655504 -204.225144)
		(width 0.18288)
		(layer "In6.Cu")
		(net "M_G_CPU1_SB_DQ<24>")
	)
	(segment
		(start 157.277816 -203.792836)
		(end 151.680418 -209.390234)
		(width 0.18288)
		(layer "In6.Cu")
		(net "M_G_CPU1_SB_DQ<24>")
	)
	(segment
		(start 183.262524 -203.678536)
		(end 183.102504 -203.518516)
		(width 0.18288)
		(layer "In6.Cu")
		(net "M_G_CPU1_SB_DQ<24>")
	)
	(segment
		(start 158.851854 -204.587602)
		(end 158.524194 -204.587602)
		(width 0.18288)
		(layer "In6.Cu")
		(net "M_G_CPU1_SB_DQ<24>")
	)
	(segment
		(start 174.293276 -204.38237)
		(end 173.965616 -204.38237)
		(width 0.18288)
		(layer "In6.Cu")
		(net "M_G_CPU1_SB_DQ<24>")
	)
	(segment
		(start 179.552092 -203.656692)
		(end 178.919124 -203.656692)
		(width 0.18288)
		(layer "In6.Cu")
		(net "M_G_CPU1_SB_DQ<24>")
	)
	(segment
		(start 136.703562 -219.97924)
		(end 136.075166 -219.506038)
		(width 0.088646)
		(layer "In6.Cu")
		(net "M_G_CPU1_SB_DQ<24>")
	)
	(segment
		(start 141.63929 -220.18371)
		(end 141.240002 -220.18371)
		(width 0.088646)
		(layer "In6.Cu")
		(net "M_G_CPU1_SB_DQ<24>")
	)
	(segment
		(start 187.285376 -203.518516)
		(end 184.115964 -203.518516)
		(width 0.18288)
		(layer "In6.Cu")
		(net "M_G_CPU1_SB_DQ<24>")
	)
	(segment
		(start 168.635426 -203.992226)
		(end 165.130226 -203.992226)
		(width 0.18288)
		(layer "In6.Cu")
		(net "M_G_CPU1_SB_DQ<24>")
	)
	(segment
		(start 176.11979 -204.54239)
		(end 175.269652 -203.692252)
		(width 0.18288)
		(layer "In6.Cu")
		(net "M_G_CPU1_SB_DQ<24>")
	)
	(segment
		(start 184.115964 -203.518516)
		(end 183.955944 -203.678536)
		(width 0.18288)
		(layer "In6.Cu")
		(net "M_G_CPU1_SB_DQ<24>")
	)
	(segment
		(start 162.655504 -204.225144)
		(end 162.655504 -203.769214)
		(width 0.18288)
		(layer "In6.Cu")
		(net "M_G_CPU1_SB_DQ<24>")
	)
	(segment
		(start 187.883546 -204.116686)
		(end 187.285376 -203.518516)
		(width 0.18288)
		(layer "In6.Cu")
		(net "M_G_CPU1_SB_DQ<24>")
	)
	(segment
		(start 158.524194 -204.587602)
		(end 158.341314 -204.404722)
		(width 0.18288)
		(layer "In6.Cu")
		(net "M_G_CPU1_SB_DQ<24>")
	)
	(segment
		(start 161.167318 -203.586334)
		(end 160.960816 -203.792836)
		(width 0.18288)
		(layer "In6.Cu")
		(net "M_G_CPU1_SB_DQ<24>")
	)
	(segment
		(start 182.920132 -203.518516)
		(end 182.254906 -204.183742)
		(width 0.18288)
		(layer "In6.Cu")
		(net "M_G_CPU1_SB_DQ<24>")
	)
	(segment
		(start 175.269652 -203.692252)
		(end 174.659036 -203.692252)
		(width 0.18288)
		(layer "In6.Cu")
		(net "M_G_CPU1_SB_DQ<24>")
	)
	(segment
		(start 142.398242 -219.424758)
		(end 141.63929 -220.18371)
		(width 0.088646)
		(layer "In6.Cu")
		(net "M_G_CPU1_SB_DQ<24>")
	)
	(segment
		(start 168.9354 -203.692252)
		(end 168.635426 -203.992226)
		(width 0.18288)
		(layer "In6.Cu")
		(net "M_G_CPU1_SB_DQ<24>")
	)
	(segment
		(start 178.919124 -203.656692)
		(end 178.033426 -204.54239)
		(width 0.18288)
		(layer "In6.Cu")
		(net "M_G_CPU1_SB_DQ<24>")
	)
	(arc
		(start 138.707368 -220.809566)
		(mid 138.424666 -220.885308)
		(end 138.141964 -220.809566)
		(width 0.088646)
		(layer "In6.Cu")
		(net "M_G_CPU1_SB_DQ<24>")
	)
	(arc
		(start 139.081764 -220.809566)
		(mid 138.894566 -220.759423)
		(end 138.707368 -220.809566)
		(width 0.088646)
		(layer "In6.Cu")
		(net "M_G_CPU1_SB_DQ<24>")
	)
	(arc
		(start 137.202164 -220.809566)
		(mid 136.995404 -220.602803)
		(end 136.919716 -220.320362)
		(width 0.088646)
		(layer "In6.Cu")
		(net "M_G_CPU1_SB_DQ<24>")
	)
	(arc
		(start 138.141964 -220.809566)
		(mid 137.954766 -220.759423)
		(end 137.767568 -220.809566)
		(width 0.088646)
		(layer "In6.Cu")
		(net "M_G_CPU1_SB_DQ<24>")
	)
	(arc
		(start 140.021564 -220.809566)
		(mid 139.834366 -220.759423)
		(end 139.647168 -220.809566)
		(width 0.088646)
		(layer "In6.Cu")
		(net "M_G_CPU1_SB_DQ<24>")
	)
	(arc
		(start 139.647168 -220.809566)
		(mid 139.364466 -220.885308)
		(end 139.081764 -220.809566)
		(width 0.088646)
		(layer "In6.Cu")
		(net "M_G_CPU1_SB_DQ<24>")
	)
	(arc
		(start 136.919716 -220.319854)
		(mid 136.872037 -220.136954)
		(end 136.741154 -220.000576)
		(width 0.088646)
		(layer "In6.Cu")
		(net "M_G_CPU1_SB_DQ<24>")
	)
	(arc
		(start 140.704062 -220.71965)
		(mid 140.378079 -220.880412)
		(end 140.021564 -220.809566)
		(width 0.088646)
		(layer "In6.Cu")
		(net "M_G_CPU1_SB_DQ<24>")
	)
	(arc
		(start 137.767568 -220.809566)
		(mid 137.484866 -220.885308)
		(end 137.202164 -220.809566)
		(width 0.088646)
		(layer "In6.Cu")
		(net "M_G_CPU1_SB_DQ<24>")
	)
	(segment
		(start 195.515484 -205.398624)
		(end 195.522596 -205.391512)
		(width 0.1016)
		(layer "F.Cu")
		(net "M_G_CPU1_SB_DQ<23>")
	)
	(segment
		(start 193.088514 -204.96657)
		(end 194.786758 -204.96657)
		(width 0.20066)
		(layer "F.Cu")
		(net "M_G_CPU1_SB_DQ<23>")
	)
	(segment
		(start 198.427848 -204.94879)
		(end 198.662036 -204.714602)
		(width 0.20066)
		(layer "F.Cu")
		(net "M_G_CPU1_SB_DQ<23>")
	)
	(segment
		(start 199.298052 -204.96657)
		(end 200.632314 -204.96657)
		(width 0.20066)
		(layer "F.Cu")
		(net "M_G_CPU1_SB_DQ<23>")
	)
	(segment
		(start 131.375912 -230.900732)
		(end 131.376166 -230.900478)
		(width 0.20066)
		(layer "F.Cu")
		(net "M_G_CPU1_SB_DQ<23>")
	)
	(segment
		(start 197.530466 -205.391512)
		(end 197.542658 -205.403704)
		(width 0.1016)
		(layer "F.Cu")
		(net "M_G_CPU1_SB_DQ<23>")
	)
	(segment
		(start 195.218812 -205.398624)
		(end 195.510658 -205.398624)
		(width 0.20066)
		(layer "F.Cu")
		(net "M_G_CPU1_SB_DQ<23>")
	)
	(segment
		(start 199.046084 -204.714602)
		(end 199.298052 -204.96657)
		(width 0.20066)
		(layer "F.Cu")
		(net "M_G_CPU1_SB_DQ<23>")
	)
	(segment
		(start 198.662036 -204.714602)
		(end 199.046084 -204.714602)
		(width 0.20066)
		(layer "F.Cu")
		(net "M_G_CPU1_SB_DQ<23>")
	)
	(segment
		(start 191.983614 -204.96657)
		(end 193.088514 -204.96657)
		(width 0.20066)
		(layer "F.Cu")
		(net "M_G_CPU1_SB_DQ<23>")
	)
	(segment
		(start 131.375912 -231.436418)
		(end 131.375912 -230.900732)
		(width 0.20066)
		(layer "F.Cu")
		(net "M_G_CPU1_SB_DQ<23>")
	)
	(segment
		(start 195.522596 -205.391512)
		(end 197.530466 -205.391512)
		(width 0.1016)
		(layer "F.Cu")
		(net "M_G_CPU1_SB_DQ<23>")
	)
	(segment
		(start 198.223886 -205.403704)
		(end 198.427848 -205.199742)
		(width 0.20066)
		(layer "F.Cu")
		(net "M_G_CPU1_SB_DQ<23>")
	)
	(segment
		(start 195.510658 -205.398624)
		(end 195.515484 -205.398624)
		(width 0.101854)
		(layer "F.Cu")
		(net "M_G_CPU1_SB_DQ<23>")
	)
	(segment
		(start 194.786758 -204.96657)
		(end 195.218812 -205.398624)
		(width 0.20066)
		(layer "F.Cu")
		(net "M_G_CPU1_SB_DQ<23>")
	)
	(segment
		(start 197.542658 -205.403704)
		(end 198.223886 -205.403704)
		(width 0.20066)
		(layer "F.Cu")
		(net "M_G_CPU1_SB_DQ<23>")
	)
	(segment
		(start 198.427848 -205.199742)
		(end 198.427848 -204.94879)
		(width 0.20066)
		(layer "F.Cu")
		(net "M_G_CPU1_SB_DQ<23>")
	)
	(segment
		(start 175.337978 -206.243682)
		(end 173.806104 -206.243682)
		(width 0.18288)
		(layer "In4.Cu")
		(net "M_G_CPU1_SB_DQ<23>")
	)
	(segment
		(start 173.806104 -206.243682)
		(end 173.637194 -206.412592)
		(width 0.18288)
		(layer "In4.Cu")
		(net "M_G_CPU1_SB_DQ<23>")
	)
	(segment
		(start 135.792464 -230.41102)
		(end 135.788146 -230.41356)
		(width 0.088646)
		(layer "In4.Cu")
		(net "M_G_CPU1_SB_DQ<23>")
	)
	(segment
		(start 182.282592 -204.54366)
		(end 181.00421 -205.067662)
		(width 0.18288)
		(layer "In4.Cu")
		(net "M_G_CPU1_SB_DQ<23>")
	)
	(segment
		(start 191.983614 -204.96657)
		(end 190.847218 -204.485748)
		(width 0.18288)
		(layer "In4.Cu")
		(net "M_G_CPU1_SB_DQ<23>")
	)
	(segment
		(start 190.847218 -204.485748)
		(end 189.766702 -204.485748)
		(width 0.18288)
		(layer "In4.Cu")
		(net "M_G_CPU1_SB_DQ<23>")
	)
	(segment
		(start 141.882876 -224.590356)
		(end 140.772642 -224.590356)
		(width 0.18288)
		(layer "In4.Cu")
		(net "M_G_CPU1_SB_DQ<23>")
	)
	(segment
		(start 159.160972 -207.850994)
		(end 159.152336 -207.85963)
		(width 0.18288)
		(layer "In4.Cu")
		(net "M_G_CPU1_SB_DQ<23>")
	)
	(segment
		(start 140.772642 -224.590356)
		(end 140.164566 -224.590356)
		(width 0.088646)
		(layer "In4.Cu")
		(net "M_G_CPU1_SB_DQ<23>")
	)
	(segment
		(start 136.741154 -228.778308)
		(end 136.732264 -228.783388)
		(width 0.088646)
		(layer "In4.Cu")
		(net "M_G_CPU1_SB_DQ<23>")
	)
	(segment
		(start 138.329416 -225.998786)
		(end 138.329416 -226.017328)
		(width 0.088646)
		(layer "In4.Cu")
		(net "M_G_CPU1_SB_DQ<23>")
	)
	(segment
		(start 156.814012 -207.85963)
		(end 155.420822 -209.25282)
		(width 0.18288)
		(layer "In4.Cu")
		(net "M_G_CPU1_SB_DQ<23>")
	)
	(segment
		(start 159.152336 -207.85963)
		(end 156.814012 -207.85963)
		(width 0.18288)
		(layer "In4.Cu")
		(net "M_G_CPU1_SB_DQ<23>")
	)
	(segment
		(start 172.321474 -206.534004)
		(end 171.073318 -206.534004)
		(width 0.18288)
		(layer "In4.Cu")
		(net "M_G_CPU1_SB_DQ<23>")
	)
	(segment
		(start 139.302998 -225.451924)
		(end 138.894566 -225.451924)
		(width 0.088646)
		(layer "In4.Cu")
		(net "M_G_CPU1_SB_DQ<23>")
	)
	(segment
		(start 164.987986 -207.252316)
		(end 164.201602 -206.977996)
		(width 0.18288)
		(layer "In4.Cu")
		(net "M_G_CPU1_SB_DQ<23>")
	)
	(segment
		(start 181.00421 -205.067662)
		(end 178.978306 -207.093566)
		(width 0.18288)
		(layer "In4.Cu")
		(net "M_G_CPU1_SB_DQ<23>")
	)
	(segment
		(start 164.201602 -206.977996)
		(end 163.732972 -206.985616)
		(width 0.18288)
		(layer "In4.Cu")
		(net "M_G_CPU1_SB_DQ<23>")
	)
	(segment
		(start 166.670482 -207.014826)
		(end 165.663626 -207.014826)
		(width 0.18288)
		(layer "In4.Cu")
		(net "M_G_CPU1_SB_DQ<23>")
	)
	(segment
		(start 171.073318 -206.534004)
		(end 170.579542 -207.02778)
		(width 0.18288)
		(layer "In4.Cu")
		(net "M_G_CPU1_SB_DQ<23>")
	)
	(segment
		(start 137.389616 -227.635054)
		(end 137.389616 -227.64496)
		(width 0.088646)
		(layer "In4.Cu")
		(net "M_G_CPU1_SB_DQ<23>")
	)
	(segment
		(start 132.039106 -230.407718)
		(end 132.033264 -230.41102)
		(width 0.088646)
		(layer "In4.Cu")
		(net "M_G_CPU1_SB_DQ<23>")
	)
	(segment
		(start 131.896612 -230.497888)
		(end 131.376166 -230.900478)
		(width 0.088646)
		(layer "In4.Cu")
		(net "M_G_CPU1_SB_DQ<23>")
	)
	(segment
		(start 172.611796 -206.243682)
		(end 172.321474 -206.534004)
		(width 0.18288)
		(layer "In4.Cu")
		(net "M_G_CPU1_SB_DQ<23>")
	)
	(segment
		(start 137.2108 -227.964238)
		(end 137.20191 -227.969318)
		(width 0.088646)
		(layer "In4.Cu")
		(net "M_G_CPU1_SB_DQ<23>")
	)
	(segment
		(start 170.579542 -207.02778)
		(end 168.7195 -207.02778)
		(width 0.18288)
		(layer "In4.Cu")
		(net "M_G_CPU1_SB_DQ<23>")
	)
	(segment
		(start 168.7195 -207.02778)
		(end 168.371774 -207.375506)
		(width 0.18288)
		(layer "In4.Cu")
		(net "M_G_CPU1_SB_DQ<23>")
	)
	(segment
		(start 165.663626 -207.014826)
		(end 165.426136 -207.252316)
		(width 0.18288)
		(layer "In4.Cu")
		(net "M_G_CPU1_SB_DQ<23>")
	)
	(segment
		(start 163.732972 -206.985616)
		(end 161.51225 -206.985616)
		(width 0.18288)
		(layer "In4.Cu")
		(net "M_G_CPU1_SB_DQ<23>")
	)
	(segment
		(start 134.852664 -230.41102)
		(end 134.848854 -230.413306)
		(width 0.088646)
		(layer "In4.Cu")
		(net "M_G_CPU1_SB_DQ<23>")
	)
	(segment
		(start 133.912864 -230.41102)
		(end 133.908546 -230.41356)
		(width 0.088646)
		(layer "In4.Cu")
		(net "M_G_CPU1_SB_DQ<23>")
	)
	(segment
		(start 172.978572 -206.243682)
		(end 172.611796 -206.243682)
		(width 0.18288)
		(layer "In4.Cu")
		(net "M_G_CPU1_SB_DQ<23>")
	)
	(segment
		(start 173.637194 -206.412592)
		(end 173.147482 -206.412592)
		(width 0.18288)
		(layer "In4.Cu")
		(net "M_G_CPU1_SB_DQ<23>")
	)
	(segment
		(start 189.70879 -204.54366)
		(end 182.282592 -204.54366)
		(width 0.18288)
		(layer "In4.Cu")
		(net "M_G_CPU1_SB_DQ<23>")
	)
	(segment
		(start 178.978306 -207.093566)
		(end 176.407826 -207.093566)
		(width 0.18288)
		(layer "In4.Cu")
		(net "M_G_CPU1_SB_DQ<23>")
	)
	(segment
		(start 165.426136 -207.252316)
		(end 164.987986 -207.252316)
		(width 0.18288)
		(layer "In4.Cu")
		(net "M_G_CPU1_SB_DQ<23>")
	)
	(segment
		(start 136.919208 -228.443536)
		(end 136.919462 -228.45903)
		(width 0.088646)
		(layer "In4.Cu")
		(net "M_G_CPU1_SB_DQ<23>")
	)
	(segment
		(start 161.51225 -206.985616)
		(end 159.770826 -207.850994)
		(width 0.18288)
		(layer "In4.Cu")
		(net "M_G_CPU1_SB_DQ<23>")
	)
	(segment
		(start 167.031162 -207.375506)
		(end 166.670482 -207.014826)
		(width 0.18288)
		(layer "In4.Cu")
		(net "M_G_CPU1_SB_DQ<23>")
	)
	(segment
		(start 137.859516 -226.821238)
		(end 137.859516 -226.831144)
		(width 0.088646)
		(layer "In4.Cu")
		(net "M_G_CPU1_SB_DQ<23>")
	)
	(segment
		(start 175.847756 -206.533496)
		(end 175.337978 -206.243682)
		(width 0.18288)
		(layer "In4.Cu")
		(net "M_G_CPU1_SB_DQ<23>")
	)
	(segment
		(start 135.979916 -230.076756)
		(end 135.979916 -230.086662)
		(width 0.088646)
		(layer "In4.Cu")
		(net "M_G_CPU1_SB_DQ<23>")
	)
	(segment
		(start 189.766702 -204.485748)
		(end 189.70879 -204.54366)
		(width 0.18288)
		(layer "In4.Cu")
		(net "M_G_CPU1_SB_DQ<23>")
	)
	(segment
		(start 173.147482 -206.412592)
		(end 172.978572 -206.243682)
		(width 0.18288)
		(layer "In4.Cu")
		(net "M_G_CPU1_SB_DQ<23>")
	)
	(segment
		(start 132.033264 -230.41102)
		(end 131.970272 -230.448104)
		(width 0.088646)
		(layer "In4.Cu")
		(net "M_G_CPU1_SB_DQ<23>")
	)
	(segment
		(start 140.164566 -224.590356)
		(end 139.302998 -225.451924)
		(width 0.088646)
		(layer "In4.Cu")
		(net "M_G_CPU1_SB_DQ<23>")
	)
	(segment
		(start 154.148282 -212.324696)
		(end 141.882876 -224.590356)
		(width 0.18288)
		(layer "In4.Cu")
		(net "M_G_CPU1_SB_DQ<23>")
	)
	(segment
		(start 136.732264 -228.783388)
		(end 136.726168 -228.786944)
		(width 0.088646)
		(layer "In4.Cu")
		(net "M_G_CPU1_SB_DQ<23>")
	)
	(segment
		(start 136.449562 -229.272846)
		(end 136.449562 -229.281482)
		(width 0.088646)
		(layer "In4.Cu")
		(net "M_G_CPU1_SB_DQ<23>")
	)
	(segment
		(start 137.680954 -227.150422)
		(end 137.672064 -227.155502)
		(width 0.088646)
		(layer "In4.Cu")
		(net "M_G_CPU1_SB_DQ<23>")
	)
	(segment
		(start 155.420822 -209.25282)
		(end 154.148282 -212.324696)
		(width 0.18288)
		(layer "In4.Cu")
		(net "M_G_CPU1_SB_DQ<23>")
	)
	(segment
		(start 138.150854 -226.336606)
		(end 138.141964 -226.341686)
		(width 0.088646)
		(layer "In4.Cu")
		(net "M_G_CPU1_SB_DQ<23>")
	)
	(segment
		(start 159.770826 -207.850994)
		(end 159.160972 -207.850994)
		(width 0.18288)
		(layer "In4.Cu")
		(net "M_G_CPU1_SB_DQ<23>")
	)
	(segment
		(start 176.407826 -207.093566)
		(end 175.847756 -206.533496)
		(width 0.18288)
		(layer "In4.Cu")
		(net "M_G_CPU1_SB_DQ<23>")
	)
	(segment
		(start 132.978906 -230.407718)
		(end 132.967222 -230.414322)
		(width 0.088646)
		(layer "In4.Cu")
		(net "M_G_CPU1_SB_DQ<23>")
	)
	(segment
		(start 137.389616 -227.64496)
		(end 137.389362 -227.64496)
		(width 0.088646)
		(layer "In4.Cu")
		(net "M_G_CPU1_SB_DQ<23>")
	)
	(segment
		(start 168.371774 -207.375506)
		(end 167.031162 -207.375506)
		(width 0.18288)
		(layer "In4.Cu")
		(net "M_G_CPU1_SB_DQ<23>")
	)
	(segment
		(start 134.858506 -230.407718)
		(end 134.852664 -230.41102)
		(width 0.088646)
		(layer "In4.Cu")
		(net "M_G_CPU1_SB_DQ<23>")
	)
	(segment
		(start 135.801354 -230.40594)
		(end 135.792464 -230.41102)
		(width 0.088646)
		(layer "In4.Cu")
		(net "M_G_CPU1_SB_DQ<23>")
	)
	(segment
		(start 136.919462 -228.45903)
		(end 136.919716 -228.45903)
		(width 0.088646)
		(layer "In4.Cu")
		(net "M_G_CPU1_SB_DQ<23>")
	)
	(arc
		(start 138.141964 -226.341686)
		(mid 137.937629 -226.544291)
		(end 137.859516 -226.821238)
		(width 0.088646)
		(layer "In4.Cu")
		(net "M_G_CPU1_SB_DQ<23>")
	)
	(arc
		(start 133.538214 -230.41102)
		(mid 133.259011 -230.33538)
		(end 132.978906 -230.407718)
		(width 0.088646)
		(layer "In4.Cu")
		(net "M_G_CPU1_SB_DQ<23>")
	)
	(arc
		(start 137.389362 -227.64496)
		(mid 137.341683 -227.82786)
		(end 137.2108 -227.964238)
		(width 0.088646)
		(layer "In4.Cu")
		(net "M_G_CPU1_SB_DQ<23>")
	)
	(arc
		(start 135.417814 -230.41102)
		(mid 135.138611 -230.33538)
		(end 134.858506 -230.407718)
		(width 0.088646)
		(layer "In4.Cu")
		(net "M_G_CPU1_SB_DQ<23>")
	)
	(arc
		(start 138.894566 -225.451924)
		(mid 138.501375 -225.611025)
		(end 138.329416 -225.998786)
		(width 0.088646)
		(layer "In4.Cu")
		(net "M_G_CPU1_SB_DQ<23>")
	)
	(arc
		(start 132.598414 -230.41102)
		(mid 132.319211 -230.33538)
		(end 132.039106 -230.407718)
		(width 0.088646)
		(layer "In4.Cu")
		(net "M_G_CPU1_SB_DQ<23>")
	)
	(arc
		(start 136.919716 -228.45903)
		(mid 136.872037 -228.64193)
		(end 136.741154 -228.778308)
		(width 0.088646)
		(layer "In4.Cu")
		(net "M_G_CPU1_SB_DQ<23>")
	)
	(arc
		(start 136.449562 -229.281482)
		(mid 136.397292 -229.463847)
		(end 136.262364 -229.597204)
		(width 0.088646)
		(layer "In4.Cu")
		(net "M_G_CPU1_SB_DQ<23>")
	)
	(arc
		(start 136.726168 -228.786944)
		(mid 136.523581 -228.993295)
		(end 136.449562 -229.272846)
		(width 0.088646)
		(layer "In4.Cu")
		(net "M_G_CPU1_SB_DQ<23>")
	)
	(arc
		(start 135.979916 -230.086662)
		(mid 135.932237 -230.269562)
		(end 135.801354 -230.40594)
		(width 0.088646)
		(layer "In4.Cu")
		(net "M_G_CPU1_SB_DQ<23>")
	)
	(arc
		(start 137.859516 -226.831144)
		(mid 137.811837 -227.014044)
		(end 137.680954 -227.150422)
		(width 0.088646)
		(layer "In4.Cu")
		(net "M_G_CPU1_SB_DQ<23>")
	)
	(arc
		(start 137.20191 -227.969318)
		(mid 136.998667 -228.169544)
		(end 136.919208 -228.443536)
		(width 0.088646)
		(layer "In4.Cu")
		(net "M_G_CPU1_SB_DQ<23>")
	)
	(arc
		(start 133.908546 -230.41356)
		(mid 133.723051 -230.461229)
		(end 133.538214 -230.41102)
		(width 0.088646)
		(layer "In4.Cu")
		(net "M_G_CPU1_SB_DQ<23>")
	)
	(arc
		(start 134.848854 -230.413306)
		(mid 134.663135 -230.461258)
		(end 134.478014 -230.41102)
		(width 0.088646)
		(layer "In4.Cu")
		(net "M_G_CPU1_SB_DQ<23>")
	)
	(arc
		(start 131.970272 -230.448104)
		(mid 131.932661 -230.471841)
		(end 131.896612 -230.497888)
		(width 0.088646)
		(layer "In4.Cu")
		(net "M_G_CPU1_SB_DQ<23>")
	)
	(arc
		(start 138.329416 -226.017328)
		(mid 138.281737 -226.200228)
		(end 138.150854 -226.336606)
		(width 0.088646)
		(layer "In4.Cu")
		(net "M_G_CPU1_SB_DQ<23>")
	)
	(arc
		(start 136.262364 -229.597204)
		(mid 136.058029 -229.799809)
		(end 135.979916 -230.076756)
		(width 0.088646)
		(layer "In4.Cu")
		(net "M_G_CPU1_SB_DQ<23>")
	)
	(arc
		(start 137.672064 -227.155502)
		(mid 137.467729 -227.358107)
		(end 137.389616 -227.635054)
		(width 0.088646)
		(layer "In4.Cu")
		(net "M_G_CPU1_SB_DQ<23>")
	)
	(arc
		(start 134.478014 -230.41102)
		(mid 134.195456 -230.335371)
		(end 133.912864 -230.41102)
		(width 0.088646)
		(layer "In4.Cu")
		(net "M_G_CPU1_SB_DQ<23>")
	)
	(arc
		(start 135.788146 -230.41356)
		(mid 135.602651 -230.461229)
		(end 135.417814 -230.41102)
		(width 0.088646)
		(layer "In4.Cu")
		(net "M_G_CPU1_SB_DQ<23>")
	)
	(arc
		(start 132.967222 -230.414322)
		(mid 132.782367 -230.461272)
		(end 132.598414 -230.41102)
		(width 0.088646)
		(layer "In4.Cu")
		(net "M_G_CPU1_SB_DQ<23>")
	)
	(segment
		(start 195.218812 -207.098646)
		(end 195.510658 -207.098646)
		(width 0.20066)
		(layer "F.Cu")
		(net "M_G_CPU1_SB_DQ<22>")
	)
	(segment
		(start 198.427848 -206.648812)
		(end 198.662036 -206.414624)
		(width 0.20066)
		(layer "F.Cu")
		(net "M_G_CPU1_SB_DQ<22>")
	)
	(segment
		(start 195.522596 -207.091534)
		(end 197.530466 -207.091534)
		(width 0.1016)
		(layer "F.Cu")
		(net "M_G_CPU1_SB_DQ<22>")
	)
	(segment
		(start 131.846066 -232.250488)
		(end 131.845812 -232.250234)
		(width 0.20066)
		(layer "F.Cu")
		(net "M_G_CPU1_SB_DQ<22>")
	)
	(segment
		(start 195.510658 -207.098646)
		(end 195.515484 -207.098646)
		(width 0.101854)
		(layer "F.Cu")
		(net "M_G_CPU1_SB_DQ<22>")
	)
	(segment
		(start 193.088514 -206.666592)
		(end 194.786758 -206.666592)
		(width 0.20066)
		(layer "F.Cu")
		(net "M_G_CPU1_SB_DQ<22>")
	)
	(segment
		(start 197.530466 -207.091534)
		(end 197.542658 -207.103726)
		(width 0.1016)
		(layer "F.Cu")
		(net "M_G_CPU1_SB_DQ<22>")
	)
	(segment
		(start 195.515484 -207.098646)
		(end 195.522596 -207.091534)
		(width 0.1016)
		(layer "F.Cu")
		(net "M_G_CPU1_SB_DQ<22>")
	)
	(segment
		(start 197.542658 -207.103726)
		(end 198.223886 -207.103726)
		(width 0.20066)
		(layer "F.Cu")
		(net "M_G_CPU1_SB_DQ<22>")
	)
	(segment
		(start 191.983614 -206.666592)
		(end 193.088514 -206.666592)
		(width 0.20066)
		(layer "F.Cu")
		(net "M_G_CPU1_SB_DQ<22>")
	)
	(segment
		(start 199.046084 -206.414624)
		(end 199.298052 -206.666592)
		(width 0.20066)
		(layer "F.Cu")
		(net "M_G_CPU1_SB_DQ<22>")
	)
	(segment
		(start 194.786758 -206.666592)
		(end 195.218812 -207.098646)
		(width 0.20066)
		(layer "F.Cu")
		(net "M_G_CPU1_SB_DQ<22>")
	)
	(segment
		(start 198.427848 -206.899764)
		(end 198.427848 -206.648812)
		(width 0.20066)
		(layer "F.Cu")
		(net "M_G_CPU1_SB_DQ<22>")
	)
	(segment
		(start 131.845812 -232.250234)
		(end 131.845812 -231.714548)
		(width 0.20066)
		(layer "F.Cu")
		(net "M_G_CPU1_SB_DQ<22>")
	)
	(segment
		(start 198.662036 -206.414624)
		(end 199.046084 -206.414624)
		(width 0.20066)
		(layer "F.Cu")
		(net "M_G_CPU1_SB_DQ<22>")
	)
	(segment
		(start 199.298052 -206.666592)
		(end 200.632314 -206.666592)
		(width 0.20066)
		(layer "F.Cu")
		(net "M_G_CPU1_SB_DQ<22>")
	)
	(segment
		(start 198.223886 -207.103726)
		(end 198.427848 -206.899764)
		(width 0.20066)
		(layer "F.Cu")
		(net "M_G_CPU1_SB_DQ<22>")
	)
	(segment
		(start 132.137658 -231.461818)
		(end 131.845812 -231.714548)
		(width 0.088646)
		(layer "In4.Cu")
		(net "M_G_CPU1_SB_DQ<22>")
	)
	(segment
		(start 133.068314 -231.22509)
		(end 133.060948 -231.220772)
		(width 0.088646)
		(layer "In4.Cu")
		(net "M_G_CPU1_SB_DQ<22>")
	)
	(segment
		(start 164.433758 -208.843626)
		(end 163.692078 -209.585306)
		(width 0.18288)
		(layer "In4.Cu")
		(net "M_G_CPU1_SB_DQ<22>")
	)
	(segment
		(start 180.649626 -208.691226)
		(end 180.446426 -208.894426)
		(width 0.18288)
		(layer "In4.Cu")
		(net "M_G_CPU1_SB_DQ<22>")
	)
	(segment
		(start 140.04925 -226.395026)
		(end 139.045696 -226.395026)
		(width 0.088646)
		(layer "In4.Cu")
		(net "M_G_CPU1_SB_DQ<22>")
	)
	(segment
		(start 140.772642 -225.6282)
		(end 140.636752 -225.6282)
		(width 0.088646)
		(layer "In4.Cu")
		(net "M_G_CPU1_SB_DQ<22>")
	)
	(segment
		(start 137.2108 -229.592124)
		(end 137.20191 -229.597204)
		(width 0.088646)
		(layer "In4.Cu")
		(net "M_G_CPU1_SB_DQ<22>")
	)
	(segment
		(start 175.53305 -207.94345)
		(end 172.151802 -207.94345)
		(width 0.18288)
		(layer "In4.Cu")
		(net "M_G_CPU1_SB_DQ<22>")
	)
	(segment
		(start 180.446426 -208.894426)
		(end 178.274726 -208.894426)
		(width 0.18288)
		(layer "In4.Cu")
		(net "M_G_CPU1_SB_DQ<22>")
	)
	(segment
		(start 137.680954 -228.778308)
		(end 137.672064 -228.783388)
		(width 0.088646)
		(layer "In4.Cu")
		(net "M_G_CPU1_SB_DQ<22>")
	)
	(segment
		(start 140.636752 -225.6282)
		(end 140.343636 -225.921316)
		(width 0.088646)
		(layer "In4.Cu")
		(net "M_G_CPU1_SB_DQ<22>")
	)
	(segment
		(start 136.271254 -231.219756)
		(end 136.262364 -231.224836)
		(width 0.088646)
		(layer "In4.Cu")
		(net "M_G_CPU1_SB_DQ<22>")
	)
	(segment
		(start 136.449816 -230.890572)
		(end 136.449816 -230.900478)
		(width 0.088646)
		(layer "In4.Cu")
		(net "M_G_CPU1_SB_DQ<22>")
	)
	(segment
		(start 142.253208 -225.6282)
		(end 140.772642 -225.6282)
		(width 0.18288)
		(layer "In4.Cu")
		(net "M_G_CPU1_SB_DQ<22>")
	)
	(segment
		(start 178.274726 -208.894426)
		(end 177.525426 -209.643726)
		(width 0.18288)
		(layer "In4.Cu")
		(net "M_G_CPU1_SB_DQ<22>")
	)
	(segment
		(start 176.362614 -209.643726)
		(end 176.133252 -209.414364)
		(width 0.18288)
		(layer "In4.Cu")
		(net "M_G_CPU1_SB_DQ<22>")
	)
	(segment
		(start 171.250356 -208.844896)
		(end 170.564556 -208.844896)
		(width 0.18288)
		(layer "In4.Cu")
		(net "M_G_CPU1_SB_DQ<22>")
	)
	(segment
		(start 138.329162 -227.64496)
		(end 138.329162 -227.653596)
		(width 0.088646)
		(layer "In4.Cu")
		(net "M_G_CPU1_SB_DQ<22>")
	)
	(segment
		(start 135.887714 -231.22509)
		(end 135.882126 -231.221788)
		(width 0.088646)
		(layer "In4.Cu")
		(net "M_G_CPU1_SB_DQ<22>")
	)
	(segment
		(start 133.072886 -231.22763)
		(end 133.068314 -231.22509)
		(width 0.088646)
		(layer "In4.Cu")
		(net "M_G_CPU1_SB_DQ<22>")
	)
	(segment
		(start 183.90997 -206.243682)
		(end 181.462426 -208.691226)
		(width 0.18288)
		(layer "In4.Cu")
		(net "M_G_CPU1_SB_DQ<22>")
	)
	(segment
		(start 134.008114 -231.22509)
		(end 134.002526 -231.221788)
		(width 0.088646)
		(layer "In4.Cu")
		(net "M_G_CPU1_SB_DQ<22>")
	)
	(segment
		(start 191.560704 -206.243682)
		(end 183.90997 -206.243682)
		(width 0.18288)
		(layer "In4.Cu")
		(net "M_G_CPU1_SB_DQ<22>")
	)
	(segment
		(start 134.952486 -231.22763)
		(end 134.947914 -231.22509)
		(width 0.088646)
		(layer "In4.Cu")
		(net "M_G_CPU1_SB_DQ<22>")
	)
	(segment
		(start 135.887968 -231.224836)
		(end 135.887714 -231.22509)
		(width 0.088646)
		(layer "In4.Cu")
		(net "M_G_CPU1_SB_DQ<22>")
	)
	(segment
		(start 157.337252 -209.585306)
		(end 155.964636 -210.957922)
		(width 0.18288)
		(layer "In4.Cu")
		(net "M_G_CPU1_SB_DQ<22>")
	)
	(segment
		(start 136.919716 -230.071168)
		(end 136.919716 -230.086662)
		(width 0.088646)
		(layer "In4.Cu")
		(net "M_G_CPU1_SB_DQ<22>")
	)
	(segment
		(start 137.859516 -228.440488)
		(end 137.859516 -228.45903)
		(width 0.088646)
		(layer "In4.Cu")
		(net "M_G_CPU1_SB_DQ<22>")
	)
	(segment
		(start 138.799062 -226.64166)
		(end 138.799062 -226.83978)
		(width 0.088646)
		(layer "In4.Cu")
		(net "M_G_CPU1_SB_DQ<22>")
	)
	(segment
		(start 136.741154 -230.40594)
		(end 136.732264 -230.41102)
		(width 0.088646)
		(layer "In4.Cu")
		(net "M_G_CPU1_SB_DQ<22>")
	)
	(segment
		(start 138.611864 -227.155502)
		(end 138.605768 -227.159058)
		(width 0.088646)
		(layer "In4.Cu")
		(net "M_G_CPU1_SB_DQ<22>")
	)
	(segment
		(start 140.343636 -225.921316)
		(end 140.343636 -226.10064)
		(width 0.088646)
		(layer "In4.Cu")
		(net "M_G_CPU1_SB_DQ<22>")
	)
	(segment
		(start 134.947914 -231.22509)
		(end 134.943342 -231.222296)
		(width 0.088646)
		(layer "In4.Cu")
		(net "M_G_CPU1_SB_DQ<22>")
	)
	(segment
		(start 155.286456 -212.594952)
		(end 142.253208 -225.6282)
		(width 0.18288)
		(layer "In4.Cu")
		(net "M_G_CPU1_SB_DQ<22>")
	)
	(segment
		(start 168.448482 -208.551018)
		(end 168.155874 -208.843626)
		(width 0.18288)
		(layer "In4.Cu")
		(net "M_G_CPU1_SB_DQ<22>")
	)
	(segment
		(start 139.045696 -226.395026)
		(end 138.799062 -226.64166)
		(width 0.088646)
		(layer "In4.Cu")
		(net "M_G_CPU1_SB_DQ<22>")
	)
	(segment
		(start 177.525426 -209.643726)
		(end 176.362614 -209.643726)
		(width 0.18288)
		(layer "In4.Cu")
		(net "M_G_CPU1_SB_DQ<22>")
	)
	(segment
		(start 170.564556 -208.844896)
		(end 170.270678 -208.551018)
		(width 0.18288)
		(layer "In4.Cu")
		(net "M_G_CPU1_SB_DQ<22>")
	)
	(segment
		(start 140.343636 -226.10064)
		(end 140.04925 -226.395026)
		(width 0.088646)
		(layer "In4.Cu")
		(net "M_G_CPU1_SB_DQ<22>")
	)
	(segment
		(start 132.503164 -231.22509)
		(end 132.424932 -231.270048)
		(width 0.088646)
		(layer "In4.Cu")
		(net "M_G_CPU1_SB_DQ<22>")
	)
	(segment
		(start 155.964636 -210.957922)
		(end 155.286456 -212.594952)
		(width 0.18288)
		(layer "In4.Cu")
		(net "M_G_CPU1_SB_DQ<22>")
	)
	(segment
		(start 176.133252 -209.414364)
		(end 176.133252 -208.543652)
		(width 0.18288)
		(layer "In4.Cu")
		(net "M_G_CPU1_SB_DQ<22>")
	)
	(segment
		(start 170.270678 -208.551018)
		(end 168.448482 -208.551018)
		(width 0.18288)
		(layer "In4.Cu")
		(net "M_G_CPU1_SB_DQ<22>")
	)
	(segment
		(start 172.151802 -207.94345)
		(end 171.250356 -208.844896)
		(width 0.18288)
		(layer "In4.Cu")
		(net "M_G_CPU1_SB_DQ<22>")
	)
	(segment
		(start 191.983614 -206.666592)
		(end 191.560704 -206.243682)
		(width 0.18288)
		(layer "In4.Cu")
		(net "M_G_CPU1_SB_DQ<22>")
	)
	(segment
		(start 181.462426 -208.691226)
		(end 180.649626 -208.691226)
		(width 0.18288)
		(layer "In4.Cu")
		(net "M_G_CPU1_SB_DQ<22>")
	)
	(segment
		(start 176.133252 -208.543652)
		(end 175.53305 -207.94345)
		(width 0.18288)
		(layer "In4.Cu")
		(net "M_G_CPU1_SB_DQ<22>")
	)
	(segment
		(start 137.672064 -228.783388)
		(end 137.659872 -228.7905)
		(width 0.088646)
		(layer "In4.Cu")
		(net "M_G_CPU1_SB_DQ<22>")
	)
	(segment
		(start 168.155874 -208.843626)
		(end 164.433758 -208.843626)
		(width 0.18288)
		(layer "In4.Cu")
		(net "M_G_CPU1_SB_DQ<22>")
	)
	(segment
		(start 163.692078 -209.585306)
		(end 157.337252 -209.585306)
		(width 0.18288)
		(layer "In4.Cu")
		(net "M_G_CPU1_SB_DQ<22>")
	)
	(arc
		(start 138.605768 -227.159058)
		(mid 138.403181 -227.365409)
		(end 138.329162 -227.64496)
		(width 0.088646)
		(layer "In4.Cu")
		(net "M_G_CPU1_SB_DQ<22>")
	)
	(arc
		(start 134.002526 -231.221788)
		(mid 133.722311 -231.149347)
		(end 133.442964 -231.22509)
		(width 0.088646)
		(layer "In4.Cu")
		(net "M_G_CPU1_SB_DQ<22>")
	)
	(arc
		(start 135.882126 -231.221788)
		(mid 135.601911 -231.149347)
		(end 135.322564 -231.22509)
		(width 0.088646)
		(layer "In4.Cu")
		(net "M_G_CPU1_SB_DQ<22>")
	)
	(arc
		(start 136.919716 -230.086662)
		(mid 136.872037 -230.269562)
		(end 136.741154 -230.40594)
		(width 0.088646)
		(layer "In4.Cu")
		(net "M_G_CPU1_SB_DQ<22>")
	)
	(arc
		(start 136.449816 -230.900478)
		(mid 136.402137 -231.083378)
		(end 136.271254 -231.219756)
		(width 0.088646)
		(layer "In4.Cu")
		(net "M_G_CPU1_SB_DQ<22>")
	)
	(arc
		(start 136.732264 -230.41102)
		(mid 136.527929 -230.613625)
		(end 136.449816 -230.890572)
		(width 0.088646)
		(layer "In4.Cu")
		(net "M_G_CPU1_SB_DQ<22>")
	)
	(arc
		(start 134.943342 -231.222296)
		(mid 134.662678 -231.149288)
		(end 134.382764 -231.22509)
		(width 0.088646)
		(layer "In4.Cu")
		(net "M_G_CPU1_SB_DQ<22>")
	)
	(arc
		(start 137.389362 -229.272846)
		(mid 137.341683 -229.455746)
		(end 137.2108 -229.592124)
		(width 0.088646)
		(layer "In4.Cu")
		(net "M_G_CPU1_SB_DQ<22>")
	)
	(arc
		(start 137.659872 -228.7905)
		(mid 137.461644 -228.996348)
		(end 137.389362 -229.272846)
		(width 0.088646)
		(layer "In4.Cu")
		(net "M_G_CPU1_SB_DQ<22>")
	)
	(arc
		(start 134.382764 -231.22509)
		(mid 134.195456 -231.275199)
		(end 134.008114 -231.22509)
		(width 0.088646)
		(layer "In4.Cu")
		(net "M_G_CPU1_SB_DQ<22>")
	)
	(arc
		(start 133.442964 -231.22509)
		(mid 133.25827 -231.275191)
		(end 133.072886 -231.22763)
		(width 0.088646)
		(layer "In4.Cu")
		(net "M_G_CPU1_SB_DQ<22>")
	)
	(arc
		(start 137.20191 -229.597204)
		(mid 136.999087 -229.797435)
		(end 136.919716 -230.071168)
		(width 0.088646)
		(layer "In4.Cu")
		(net "M_G_CPU1_SB_DQ<22>")
	)
	(arc
		(start 138.799062 -226.83978)
		(mid 138.746792 -227.022145)
		(end 138.611864 -227.155502)
		(width 0.088646)
		(layer "In4.Cu")
		(net "M_G_CPU1_SB_DQ<22>")
	)
	(arc
		(start 135.322564 -231.22509)
		(mid 135.13787 -231.275191)
		(end 134.952486 -231.22763)
		(width 0.088646)
		(layer "In4.Cu")
		(net "M_G_CPU1_SB_DQ<22>")
	)
	(arc
		(start 132.175758 -231.431338)
		(mid 132.156387 -231.446177)
		(end 132.137658 -231.461818)
		(width 0.088646)
		(layer "In4.Cu")
		(net "M_G_CPU1_SB_DQ<22>")
	)
	(arc
		(start 133.060948 -231.220772)
		(mid 132.781487 -231.149335)
		(end 132.503164 -231.22509)
		(width 0.088646)
		(layer "In4.Cu")
		(net "M_G_CPU1_SB_DQ<22>")
	)
	(arc
		(start 132.424932 -231.270048)
		(mid 132.298169 -231.347331)
		(end 132.175758 -231.431338)
		(width 0.088646)
		(layer "In4.Cu")
		(net "M_G_CPU1_SB_DQ<22>")
	)
	(arc
		(start 137.859516 -228.45903)
		(mid 137.811837 -228.64193)
		(end 137.680954 -228.778308)
		(width 0.088646)
		(layer "In4.Cu")
		(net "M_G_CPU1_SB_DQ<22>")
	)
	(arc
		(start 138.141964 -227.969318)
		(mid 137.939678 -228.168299)
		(end 137.859516 -228.440488)
		(width 0.088646)
		(layer "In4.Cu")
		(net "M_G_CPU1_SB_DQ<22>")
	)
	(arc
		(start 136.262364 -231.224836)
		(mid 136.075166 -231.274979)
		(end 135.887968 -231.224836)
		(width 0.088646)
		(layer "In4.Cu")
		(net "M_G_CPU1_SB_DQ<22>")
	)
	(arc
		(start 138.329162 -227.653596)
		(mid 138.276892 -227.835961)
		(end 138.141964 -227.969318)
		(width 0.088646)
		(layer "In4.Cu")
		(net "M_G_CPU1_SB_DQ<22>")
	)
	(segment
		(start 194.508882 -205.385416)
		(end 194.098926 -205.385416)
		(width 0.20066)
		(layer "F.Cu")
		(net "M_G_CPU1_SB_DQ<21>")
	)
	(segment
		(start 190.75781 -206.065374)
		(end 190.509144 -205.816708)
		(width 0.20066)
		(layer "F.Cu")
		(net "M_G_CPU1_SB_DQ<21>")
	)
	(segment
		(start 194.098926 -205.385416)
		(end 194.092576 -205.391766)
		(width 0.1016)
		(layer "F.Cu")
		(net "M_G_CPU1_SB_DQ<21>")
	)
	(segment
		(start 194.092576 -205.391766)
		(end 191.903858 -205.391766)
		(width 0.1016)
		(layer "F.Cu")
		(net "M_G_CPU1_SB_DQ<21>")
	)
	(segment
		(start 191.883792 -205.391766)
		(end 191.539114 -205.391766)
		(width 0.20066)
		(layer "F.Cu")
		(net "M_G_CPU1_SB_DQ<21>")
	)
	(segment
		(start 130.436112 -230.900732)
		(end 130.436366 -230.900478)
		(width 0.20066)
		(layer "F.Cu")
		(net "M_G_CPU1_SB_DQ<21>")
	)
	(segment
		(start 188.988446 -205.816708)
		(end 187.883546 -205.816708)
		(width 0.20066)
		(layer "F.Cu")
		(net "M_G_CPU1_SB_DQ<21>")
	)
	(segment
		(start 191.539114 -205.391766)
		(end 191.421004 -205.509876)
		(width 0.20066)
		(layer "F.Cu")
		(net "M_G_CPU1_SB_DQ<21>")
	)
	(segment
		(start 194.940428 -205.816962)
		(end 194.508882 -205.385416)
		(width 0.20066)
		(layer "F.Cu")
		(net "M_G_CPU1_SB_DQ<21>")
	)
	(segment
		(start 191.421004 -205.877414)
		(end 191.233044 -206.065374)
		(width 0.20066)
		(layer "F.Cu")
		(net "M_G_CPU1_SB_DQ<21>")
	)
	(segment
		(start 190.509144 -205.816708)
		(end 188.988446 -205.816708)
		(width 0.20066)
		(layer "F.Cu")
		(net "M_G_CPU1_SB_DQ<21>")
	)
	(segment
		(start 196.532246 -205.816708)
		(end 196.531992 -205.816962)
		(width 0.20066)
		(layer "F.Cu")
		(net "M_G_CPU1_SB_DQ<21>")
	)
	(segment
		(start 191.421004 -205.509876)
		(end 191.421004 -205.877414)
		(width 0.20066)
		(layer "F.Cu")
		(net "M_G_CPU1_SB_DQ<21>")
	)
	(segment
		(start 191.233044 -206.065374)
		(end 190.75781 -206.065374)
		(width 0.20066)
		(layer "F.Cu")
		(net "M_G_CPU1_SB_DQ<21>")
	)
	(segment
		(start 196.531992 -205.816962)
		(end 194.940428 -205.816962)
		(width 0.20066)
		(layer "F.Cu")
		(net "M_G_CPU1_SB_DQ<21>")
	)
	(segment
		(start 191.903858 -205.391766)
		(end 191.883792 -205.391766)
		(width 0.101854)
		(layer "F.Cu")
		(net "M_G_CPU1_SB_DQ<21>")
	)
	(segment
		(start 130.436112 -231.436418)
		(end 130.436112 -230.900732)
		(width 0.20066)
		(layer "F.Cu")
		(net "M_G_CPU1_SB_DQ<21>")
	)
	(segment
		(start 182.148226 -206.354426)
		(end 181.488842 -206.354426)
		(width 0.18288)
		(layer "In4.Cu")
		(net "M_G_CPU1_SB_DQ<21>")
	)
	(segment
		(start 136.357868 -229.762304)
		(end 136.348978 -229.767384)
		(width 0.088646)
		(layer "In4.Cu")
		(net "M_G_CPU1_SB_DQ<21>")
	)
	(segment
		(start 138.050016 -226.831144)
		(end 138.050016 -226.84105)
		(width 0.088646)
		(layer "In4.Cu")
		(net "M_G_CPU1_SB_DQ<21>")
	)
	(segment
		(start 136.640316 -229.26421)
		(end 136.640316 -229.282752)
		(width 0.088646)
		(layer "In4.Cu")
		(net "M_G_CPU1_SB_DQ<21>")
	)
	(segment
		(start 163.0426 -208.80705)
		(end 163.0426 -208.21904)
		(width 0.18288)
		(layer "In4.Cu")
		(net "M_G_CPU1_SB_DQ<21>")
	)
	(segment
		(start 181.488842 -206.354426)
		(end 179.902104 -207.941164)
		(width 0.18288)
		(layer "In4.Cu")
		(net "M_G_CPU1_SB_DQ<21>")
	)
	(segment
		(start 174.934626 -207.370426)
		(end 174.657766 -207.093566)
		(width 0.18288)
		(layer "In4.Cu")
		(net "M_G_CPU1_SB_DQ<21>")
	)
	(segment
		(start 176.241964 -207.941164)
		(end 175.671226 -207.370426)
		(width 0.18288)
		(layer "In4.Cu")
		(net "M_G_CPU1_SB_DQ<21>")
	)
	(segment
		(start 138.237468 -226.506786)
		(end 138.228578 -226.511866)
		(width 0.088646)
		(layer "In4.Cu")
		(net "M_G_CPU1_SB_DQ<21>")
	)
	(segment
		(start 135.887968 -230.57612)
		(end 135.884158 -230.578152)
		(width 0.088646)
		(layer "In4.Cu")
		(net "M_G_CPU1_SB_DQ<21>")
	)
	(segment
		(start 133.074156 -230.572818)
		(end 133.062472 -230.579422)
		(width 0.088646)
		(layer "In4.Cu")
		(net "M_G_CPU1_SB_DQ<21>")
	)
	(segment
		(start 161.83864 -208.98993)
		(end 161.65576 -208.80705)
		(width 0.18288)
		(layer "In4.Cu")
		(net "M_G_CPU1_SB_DQ<21>")
	)
	(segment
		(start 163.0426 -208.21904)
		(end 162.85972 -208.03616)
		(width 0.18288)
		(layer "In4.Cu")
		(net "M_G_CPU1_SB_DQ<21>")
	)
	(segment
		(start 183.875426 -205.363826)
		(end 183.40705 -205.832202)
		(width 0.18288)
		(layer "In4.Cu")
		(net "M_G_CPU1_SB_DQ<21>")
	)
	(segment
		(start 182.67045 -205.832202)
		(end 182.148226 -206.354426)
		(width 0.18288)
		(layer "In4.Cu")
		(net "M_G_CPU1_SB_DQ<21>")
	)
	(segment
		(start 137.109962 -228.458776)
		(end 137.110216 -228.45903)
		(width 0.088646)
		(layer "In4.Cu")
		(net "M_G_CPU1_SB_DQ<21>")
	)
	(segment
		(start 179.902104 -207.941164)
		(end 176.241964 -207.941164)
		(width 0.18288)
		(layer "In4.Cu")
		(net "M_G_CPU1_SB_DQ<21>")
	)
	(segment
		(start 155.659074 -210.13166)
		(end 154.67838 -212.49894)
		(width 0.18288)
		(layer "In4.Cu")
		(net "M_G_CPU1_SB_DQ<21>")
	)
	(segment
		(start 137.767568 -227.320602)
		(end 137.758678 -227.325682)
		(width 0.088646)
		(layer "In4.Cu")
		(net "M_G_CPU1_SB_DQ<21>")
	)
	(segment
		(start 187.430664 -205.363826)
		(end 183.875426 -205.363826)
		(width 0.18288)
		(layer "In4.Cu")
		(net "M_G_CPU1_SB_DQ<21>")
	)
	(segment
		(start 160.993074 -208.03616)
		(end 160.14065 -208.888584)
		(width 0.18288)
		(layer "In4.Cu")
		(net "M_G_CPU1_SB_DQ<21>")
	)
	(segment
		(start 168.804082 -208.047082)
		(end 168.649142 -207.892142)
		(width 0.18288)
		(layer "In4.Cu")
		(net "M_G_CPU1_SB_DQ<21>")
	)
	(segment
		(start 162.1663 -208.98993)
		(end 161.83864 -208.98993)
		(width 0.18288)
		(layer "In4.Cu")
		(net "M_G_CPU1_SB_DQ<21>")
	)
	(segment
		(start 163.73602 -208.80705)
		(end 163.55314 -208.98993)
		(width 0.18288)
		(layer "In4.Cu")
		(net "M_G_CPU1_SB_DQ<21>")
	)
	(segment
		(start 161.65576 -208.21904)
		(end 161.47288 -208.03616)
		(width 0.18288)
		(layer "In4.Cu")
		(net "M_G_CPU1_SB_DQ<21>")
	)
	(segment
		(start 157.785816 -208.888584)
		(end 157.785562 -208.88833)
		(width 0.18288)
		(layer "In4.Cu")
		(net "M_G_CPU1_SB_DQ<21>")
	)
	(segment
		(start 154.67838 -212.49894)
		(end 142.089124 -225.088196)
		(width 0.18288)
		(layer "In4.Cu")
		(net "M_G_CPU1_SB_DQ<21>")
	)
	(segment
		(start 183.40705 -205.832202)
		(end 182.67045 -205.832202)
		(width 0.18288)
		(layer "In4.Cu")
		(net "M_G_CPU1_SB_DQ<21>")
	)
	(segment
		(start 160.14065 -208.888584)
		(end 157.785816 -208.888584)
		(width 0.18288)
		(layer "In4.Cu")
		(net "M_G_CPU1_SB_DQ<21>")
	)
	(segment
		(start 140.772642 -225.088196)
		(end 139.946126 -225.088196)
		(width 0.088646)
		(layer "In4.Cu")
		(net "M_G_CPU1_SB_DQ<21>")
	)
	(segment
		(start 137.313162 -228.12502)
		(end 137.29716 -228.134418)
		(width 0.088646)
		(layer "In4.Cu")
		(net "M_G_CPU1_SB_DQ<21>")
	)
	(segment
		(start 163.55314 -208.98993)
		(end 163.22548 -208.98993)
		(width 0.18288)
		(layer "In4.Cu")
		(net "M_G_CPU1_SB_DQ<21>")
	)
	(segment
		(start 163.73602 -208.21904)
		(end 163.73602 -208.80705)
		(width 0.18288)
		(layer "In4.Cu")
		(net "M_G_CPU1_SB_DQ<21>")
	)
	(segment
		(start 157.785562 -208.88833)
		(end 156.902404 -208.88833)
		(width 0.18288)
		(layer "In4.Cu")
		(net "M_G_CPU1_SB_DQ<21>")
	)
	(segment
		(start 174.657766 -207.093566)
		(end 171.338494 -207.093566)
		(width 0.18288)
		(layer "In4.Cu")
		(net "M_G_CPU1_SB_DQ<21>")
	)
	(segment
		(start 168.649142 -207.892142)
		(end 164.539168 -207.892142)
		(width 0.18288)
		(layer "In4.Cu")
		(net "M_G_CPU1_SB_DQ<21>")
	)
	(segment
		(start 139.392152 -225.64217)
		(end 138.894566 -225.64217)
		(width 0.088646)
		(layer "In4.Cu")
		(net "M_G_CPU1_SB_DQ<21>")
	)
	(segment
		(start 162.34918 -208.21904)
		(end 162.34918 -208.80705)
		(width 0.18288)
		(layer "In4.Cu")
		(net "M_G_CPU1_SB_DQ<21>")
	)
	(segment
		(start 162.53206 -208.03616)
		(end 162.34918 -208.21904)
		(width 0.18288)
		(layer "In4.Cu")
		(net "M_G_CPU1_SB_DQ<21>")
	)
	(segment
		(start 187.883546 -205.816708)
		(end 187.430664 -205.363826)
		(width 0.18288)
		(layer "In4.Cu")
		(net "M_G_CPU1_SB_DQ<21>")
	)
	(segment
		(start 164.539168 -207.892142)
		(end 164.39515 -208.03616)
		(width 0.18288)
		(layer "In4.Cu")
		(net "M_G_CPU1_SB_DQ<21>")
	)
	(segment
		(start 134.008114 -230.57612)
		(end 134.004558 -230.578152)
		(width 0.088646)
		(layer "In4.Cu")
		(net "M_G_CPU1_SB_DQ<21>")
	)
	(segment
		(start 131.213352 -231.329484)
		(end 130.436366 -230.900478)
		(width 0.088646)
		(layer "In4.Cu")
		(net "M_G_CPU1_SB_DQ<21>")
	)
	(segment
		(start 171.338494 -207.093566)
		(end 170.384978 -208.047082)
		(width 0.18288)
		(layer "In4.Cu")
		(net "M_G_CPU1_SB_DQ<21>")
	)
	(segment
		(start 162.85972 -208.03616)
		(end 162.53206 -208.03616)
		(width 0.18288)
		(layer "In4.Cu")
		(net "M_G_CPU1_SB_DQ<21>")
	)
	(segment
		(start 162.34918 -208.80705)
		(end 162.1663 -208.98993)
		(width 0.18288)
		(layer "In4.Cu")
		(net "M_G_CPU1_SB_DQ<21>")
	)
	(segment
		(start 142.089124 -225.088196)
		(end 140.772642 -225.088196)
		(width 0.18288)
		(layer "In4.Cu")
		(net "M_G_CPU1_SB_DQ<21>")
	)
	(segment
		(start 138.519916 -226.017328)
		(end 138.519916 -226.027234)
		(width 0.088646)
		(layer "In4.Cu")
		(net "M_G_CPU1_SB_DQ<21>")
	)
	(segment
		(start 137.109962 -228.45014)
		(end 137.109962 -228.458776)
		(width 0.088646)
		(layer "In4.Cu")
		(net "M_G_CPU1_SB_DQ<21>")
	)
	(segment
		(start 139.946126 -225.088196)
		(end 139.392152 -225.64217)
		(width 0.088646)
		(layer "In4.Cu")
		(net "M_G_CPU1_SB_DQ<21>")
	)
	(segment
		(start 136.83361 -228.944932)
		(end 136.827514 -228.948488)
		(width 0.088646)
		(layer "In4.Cu")
		(net "M_G_CPU1_SB_DQ<21>")
	)
	(segment
		(start 175.671226 -207.370426)
		(end 174.934626 -207.370426)
		(width 0.18288)
		(layer "In4.Cu")
		(net "M_G_CPU1_SB_DQ<21>")
	)
	(segment
		(start 161.65576 -208.80705)
		(end 161.65576 -208.21904)
		(width 0.18288)
		(layer "In4.Cu")
		(net "M_G_CPU1_SB_DQ<21>")
	)
	(segment
		(start 164.39515 -208.03616)
		(end 163.9189 -208.03616)
		(width 0.18288)
		(layer "In4.Cu")
		(net "M_G_CPU1_SB_DQ<21>")
	)
	(segment
		(start 163.22548 -208.98993)
		(end 163.0426 -208.80705)
		(width 0.18288)
		(layer "In4.Cu")
		(net "M_G_CPU1_SB_DQ<21>")
	)
	(segment
		(start 163.9189 -208.03616)
		(end 163.73602 -208.21904)
		(width 0.18288)
		(layer "In4.Cu")
		(net "M_G_CPU1_SB_DQ<21>")
	)
	(segment
		(start 136.170416 -230.086662)
		(end 136.170416 -230.096568)
		(width 0.088646)
		(layer "In4.Cu")
		(net "M_G_CPU1_SB_DQ<21>")
	)
	(segment
		(start 156.902404 -208.88833)
		(end 155.659074 -210.13166)
		(width 0.18288)
		(layer "In4.Cu")
		(net "M_G_CPU1_SB_DQ<21>")
	)
	(segment
		(start 161.47288 -208.03616)
		(end 160.993074 -208.03616)
		(width 0.18288)
		(layer "In4.Cu")
		(net "M_G_CPU1_SB_DQ<21>")
	)
	(segment
		(start 134.953756 -230.572818)
		(end 134.943342 -230.57866)
		(width 0.088646)
		(layer "In4.Cu")
		(net "M_G_CPU1_SB_DQ<21>")
	)
	(segment
		(start 170.384978 -208.047082)
		(end 168.804082 -208.047082)
		(width 0.18288)
		(layer "In4.Cu")
		(net "M_G_CPU1_SB_DQ<21>")
	)
	(arc
		(start 138.519916 -226.027234)
		(mid 138.441805 -226.304183)
		(end 138.237468 -226.506786)
		(width 0.088646)
		(layer "In4.Cu")
		(net "M_G_CPU1_SB_DQ<21>")
	)
	(arc
		(start 133.442964 -230.57612)
		(mid 133.25901 -230.525991)
		(end 133.074156 -230.572818)
		(width 0.088646)
		(layer "In4.Cu")
		(net "M_G_CPU1_SB_DQ<21>")
	)
	(arc
		(start 134.943342 -230.57866)
		(mid 134.662707 -230.651828)
		(end 134.382764 -230.57612)
		(width 0.088646)
		(layer "In4.Cu")
		(net "M_G_CPU1_SB_DQ<21>")
	)
	(arc
		(start 137.29716 -228.134418)
		(mid 137.162227 -228.267772)
		(end 137.109962 -228.45014)
		(width 0.088646)
		(layer "In4.Cu")
		(net "M_G_CPU1_SB_DQ<21>")
	)
	(arc
		(start 132.503164 -230.57612)
		(mid 132.128467 -230.576001)
		(end 131.941062 -230.900478)
		(width 0.088646)
		(layer "In4.Cu")
		(net "M_G_CPU1_SB_DQ<21>")
	)
	(arc
		(start 135.322564 -230.57612)
		(mid 135.13861 -230.525991)
		(end 134.953756 -230.572818)
		(width 0.088646)
		(layer "In4.Cu")
		(net "M_G_CPU1_SB_DQ<21>")
	)
	(arc
		(start 137.580116 -227.64496)
		(mid 137.508891 -227.91961)
		(end 137.313162 -228.12502)
		(width 0.088646)
		(layer "In4.Cu")
		(net "M_G_CPU1_SB_DQ<21>")
	)
	(arc
		(start 136.640316 -229.282752)
		(mid 136.562205 -229.559701)
		(end 136.357868 -229.762304)
		(width 0.088646)
		(layer "In4.Cu")
		(net "M_G_CPU1_SB_DQ<21>")
	)
	(arc
		(start 137.110216 -228.45903)
		(mid 137.036225 -228.738596)
		(end 136.83361 -228.944932)
		(width 0.088646)
		(layer "In4.Cu")
		(net "M_G_CPU1_SB_DQ<21>")
	)
	(arc
		(start 137.758678 -227.325682)
		(mid 137.627764 -227.462042)
		(end 137.580116 -227.64496)
		(width 0.088646)
		(layer "In4.Cu")
		(net "M_G_CPU1_SB_DQ<21>")
	)
	(arc
		(start 136.170416 -230.096568)
		(mid 136.092305 -230.373517)
		(end 135.887968 -230.57612)
		(width 0.088646)
		(layer "In4.Cu")
		(net "M_G_CPU1_SB_DQ<21>")
	)
	(arc
		(start 136.827514 -228.948488)
		(mid 136.692581 -229.081842)
		(end 136.640316 -229.26421)
		(width 0.088646)
		(layer "In4.Cu")
		(net "M_G_CPU1_SB_DQ<21>")
	)
	(arc
		(start 138.228578 -226.511866)
		(mid 138.097664 -226.648226)
		(end 138.050016 -226.831144)
		(width 0.088646)
		(layer "In4.Cu")
		(net "M_G_CPU1_SB_DQ<21>")
	)
	(arc
		(start 134.004558 -230.578152)
		(mid 133.723474 -230.651889)
		(end 133.442964 -230.57612)
		(width 0.088646)
		(layer "In4.Cu")
		(net "M_G_CPU1_SB_DQ<21>")
	)
	(arc
		(start 138.050016 -226.84105)
		(mid 137.971905 -227.117999)
		(end 137.767568 -227.320602)
		(width 0.088646)
		(layer "In4.Cu")
		(net "M_G_CPU1_SB_DQ<21>")
	)
	(arc
		(start 138.894566 -225.64217)
		(mid 138.792643 -225.656506)
		(end 138.698478 -225.69805)
		(width 0.088646)
		(layer "In4.Cu")
		(net "M_G_CPU1_SB_DQ<21>")
	)
	(arc
		(start 133.062472 -230.579422)
		(mid 132.782367 -230.651864)
		(end 132.503164 -230.57612)
		(width 0.088646)
		(layer "In4.Cu")
		(net "M_G_CPU1_SB_DQ<21>")
	)
	(arc
		(start 131.941062 -230.900478)
		(mid 131.699736 -231.322959)
		(end 131.213352 -231.329484)
		(width 0.088646)
		(layer "In4.Cu")
		(net "M_G_CPU1_SB_DQ<21>")
	)
	(arc
		(start 138.698478 -225.69805)
		(mid 138.567564 -225.83441)
		(end 138.519916 -226.017328)
		(width 0.088646)
		(layer "In4.Cu")
		(net "M_G_CPU1_SB_DQ<21>")
	)
	(arc
		(start 134.382764 -230.57612)
		(mid 134.195456 -230.525977)
		(end 134.008114 -230.57612)
		(width 0.088646)
		(layer "In4.Cu")
		(net "M_G_CPU1_SB_DQ<21>")
	)
	(arc
		(start 135.884158 -230.578152)
		(mid 135.603074 -230.651889)
		(end 135.322564 -230.57612)
		(width 0.088646)
		(layer "In4.Cu")
		(net "M_G_CPU1_SB_DQ<21>")
	)
	(arc
		(start 136.348978 -229.767384)
		(mid 136.218064 -229.903744)
		(end 136.170416 -230.086662)
		(width 0.088646)
		(layer "In4.Cu")
		(net "M_G_CPU1_SB_DQ<21>")
	)
	(segment
		(start 190.75781 -207.765396)
		(end 190.509144 -207.51673)
		(width 0.20066)
		(layer "F.Cu")
		(net "M_G_CPU1_SB_DQ<20>")
	)
	(segment
		(start 194.508882 -207.085438)
		(end 194.098926 -207.085438)
		(width 0.20066)
		(layer "F.Cu")
		(net "M_G_CPU1_SB_DQ<20>")
	)
	(segment
		(start 194.098926 -207.085438)
		(end 194.092576 -207.091788)
		(width 0.1016)
		(layer "F.Cu")
		(net "M_G_CPU1_SB_DQ<20>")
	)
	(segment
		(start 191.421004 -207.209898)
		(end 191.421004 -207.577436)
		(width 0.20066)
		(layer "F.Cu")
		(net "M_G_CPU1_SB_DQ<20>")
	)
	(segment
		(start 191.421004 -207.577436)
		(end 191.233044 -207.765396)
		(width 0.20066)
		(layer "F.Cu")
		(net "M_G_CPU1_SB_DQ<20>")
	)
	(segment
		(start 190.509144 -207.51673)
		(end 188.988446 -207.51673)
		(width 0.20066)
		(layer "F.Cu")
		(net "M_G_CPU1_SB_DQ<20>")
	)
	(segment
		(start 194.092576 -207.091788)
		(end 191.930782 -207.091788)
		(width 0.1016)
		(layer "F.Cu")
		(net "M_G_CPU1_SB_DQ<20>")
	)
	(segment
		(start 196.531992 -207.516984)
		(end 194.940428 -207.516984)
		(width 0.20066)
		(layer "F.Cu")
		(net "M_G_CPU1_SB_DQ<20>")
	)
	(segment
		(start 191.930782 -207.091788)
		(end 191.883792 -207.091788)
		(width 0.101854)
		(layer "F.Cu")
		(net "M_G_CPU1_SB_DQ<20>")
	)
	(segment
		(start 196.532246 -207.51673)
		(end 196.531992 -207.516984)
		(width 0.20066)
		(layer "F.Cu")
		(net "M_G_CPU1_SB_DQ<20>")
	)
	(segment
		(start 129.966466 -232.250488)
		(end 129.966212 -232.250234)
		(width 0.20066)
		(layer "F.Cu")
		(net "M_G_CPU1_SB_DQ<20>")
	)
	(segment
		(start 191.539114 -207.091788)
		(end 191.421004 -207.209898)
		(width 0.20066)
		(layer "F.Cu")
		(net "M_G_CPU1_SB_DQ<20>")
	)
	(segment
		(start 129.966212 -232.250234)
		(end 129.966212 -231.714548)
		(width 0.20066)
		(layer "F.Cu")
		(net "M_G_CPU1_SB_DQ<20>")
	)
	(segment
		(start 191.233044 -207.765396)
		(end 190.75781 -207.765396)
		(width 0.20066)
		(layer "F.Cu")
		(net "M_G_CPU1_SB_DQ<20>")
	)
	(segment
		(start 188.988446 -207.51673)
		(end 187.883546 -207.51673)
		(width 0.20066)
		(layer "F.Cu")
		(net "M_G_CPU1_SB_DQ<20>")
	)
	(segment
		(start 191.883792 -207.091788)
		(end 191.539114 -207.091788)
		(width 0.20066)
		(layer "F.Cu")
		(net "M_G_CPU1_SB_DQ<20>")
	)
	(segment
		(start 194.940428 -207.516984)
		(end 194.508882 -207.085438)
		(width 0.20066)
		(layer "F.Cu")
		(net "M_G_CPU1_SB_DQ<20>")
	)
	(segment
		(start 135.792464 -231.39019)
		(end 135.792464 -231.389936)
		(width 0.088646)
		(layer "In4.Cu")
		(net "M_G_CPU1_SB_DQ<20>")
	)
	(segment
		(start 187.278518 -206.913226)
		(end 184.053226 -206.913226)
		(width 0.18288)
		(layer "In4.Cu")
		(net "M_G_CPU1_SB_DQ<20>")
	)
	(segment
		(start 176.40681 -210.49361)
		(end 174.706788 -208.793588)
		(width 0.18288)
		(layer "In4.Cu")
		(net "M_G_CPU1_SB_DQ<20>")
	)
	(segment
		(start 158.42234 -210.443826)
		(end 157.452822 -210.443826)
		(width 0.18288)
		(layer "In4.Cu")
		(net "M_G_CPU1_SB_DQ<20>")
	)
	(segment
		(start 183.443626 -208.335626)
		(end 182.199026 -209.580226)
		(width 0.18288)
		(layer "In4.Cu")
		(net "M_G_CPU1_SB_DQ<20>")
	)
	(segment
		(start 138.237468 -228.134672)
		(end 138.228578 -228.139752)
		(width 0.088646)
		(layer "In4.Cu")
		(net "M_G_CPU1_SB_DQ<20>")
	)
	(segment
		(start 187.883546 -207.51673)
		(end 187.278518 -206.913226)
		(width 0.18288)
		(layer "In4.Cu")
		(net "M_G_CPU1_SB_DQ<20>")
	)
	(segment
		(start 166.347902 -210.651852)
		(end 166.020242 -210.651852)
		(width 0.18288)
		(layer "In4.Cu")
		(net "M_G_CPU1_SB_DQ<20>")
	)
	(segment
		(start 138.519916 -227.636324)
		(end 138.519916 -227.663502)
		(width 0.088646)
		(layer "In4.Cu")
		(net "M_G_CPU1_SB_DQ<20>")
	)
	(segment
		(start 136.640316 -230.900478)
		(end 136.640316 -230.91902)
		(width 0.088646)
		(layer "In4.Cu")
		(net "M_G_CPU1_SB_DQ<20>")
	)
	(segment
		(start 159.09036 -210.720686)
		(end 158.6992 -210.720686)
		(width 0.18288)
		(layer "In4.Cu")
		(net "M_G_CPU1_SB_DQ<20>")
	)
	(segment
		(start 156.689298 -211.20735)
		(end 156.201872 -212.383878)
		(width 0.18288)
		(layer "In4.Cu")
		(net "M_G_CPU1_SB_DQ<20>")
	)
	(segment
		(start 171.302426 -209.554826)
		(end 166.713662 -209.554826)
		(width 0.18288)
		(layer "In4.Cu")
		(net "M_G_CPU1_SB_DQ<20>")
	)
	(segment
		(start 131.093464 -232.038906)
		(end 131.087622 -232.042208)
		(width 0.088646)
		(layer "In4.Cu")
		(net "M_G_CPU1_SB_DQ<20>")
	)
	(segment
		(start 184.053226 -206.913226)
		(end 183.443626 -207.522826)
		(width 0.18288)
		(layer "In4.Cu")
		(net "M_G_CPU1_SB_DQ<20>")
	)
	(segment
		(start 132.3213 -231.819196)
		(end 132.263896 -231.8766)
		(width 0.088646)
		(layer "In4.Cu")
		(net "M_G_CPU1_SB_DQ<20>")
	)
	(segment
		(start 166.713662 -209.554826)
		(end 166.530782 -209.737706)
		(width 0.18288)
		(layer "In4.Cu")
		(net "M_G_CPU1_SB_DQ<20>")
	)
	(segment
		(start 160.645602 -210.502246)
		(end 160.587182 -210.443826)
		(width 0.18288)
		(layer "In4.Cu")
		(net "M_G_CPU1_SB_DQ<20>")
	)
	(segment
		(start 131.099306 -232.03535)
		(end 131.093464 -232.038906)
		(width 0.088646)
		(layer "In4.Cu")
		(net "M_G_CPU1_SB_DQ<20>")
	)
	(segment
		(start 135.792464 -231.389936)
		(end 135.789924 -231.388412)
		(width 0.088646)
		(layer "In4.Cu")
		(net "M_G_CPU1_SB_DQ<20>")
	)
	(segment
		(start 137.767568 -228.948488)
		(end 137.758678 -228.953568)
		(width 0.088646)
		(layer "In4.Cu")
		(net "M_G_CPU1_SB_DQ<20>")
	)
	(segment
		(start 133.912864 -231.389936)
		(end 133.910324 -231.388412)
		(width 0.088646)
		(layer "In4.Cu")
		(net "M_G_CPU1_SB_DQ<20>")
	)
	(segment
		(start 156.201872 -212.383878)
		(end 148.623528 -219.962222)
		(width 0.18288)
		(layer "In4.Cu")
		(net "M_G_CPU1_SB_DQ<20>")
	)
	(segment
		(start 158.6992 -210.720686)
		(end 158.42234 -210.443826)
		(width 0.18288)
		(layer "In4.Cu")
		(net "M_G_CPU1_SB_DQ<20>")
	)
	(segment
		(start 179.786026 -209.402426)
		(end 178.79441 -209.402426)
		(width 0.18288)
		(layer "In4.Cu")
		(net "M_G_CPU1_SB_DQ<20>")
	)
	(segment
		(start 132.598414 -231.389936)
		(end 132.50926 -231.441498)
		(width 0.088646)
		(layer "In4.Cu")
		(net "M_G_CPU1_SB_DQ<20>")
	)
	(segment
		(start 166.530782 -209.737706)
		(end 166.530782 -210.468972)
		(width 0.18288)
		(layer "In4.Cu")
		(net "M_G_CPU1_SB_DQ<20>")
	)
	(segment
		(start 140.602462 -226.12604)
		(end 140.135356 -226.593146)
		(width 0.088646)
		(layer "In4.Cu")
		(net "M_G_CPU1_SB_DQ<20>")
	)
	(segment
		(start 132.973064 -231.389936)
		(end 132.968492 -231.387396)
		(width 0.088646)
		(layer "In4.Cu")
		(net "M_G_CPU1_SB_DQ<20>")
	)
	(segment
		(start 132.110226 -231.994456)
		(end 132.027422 -232.042208)
		(width 0.088646)
		(layer "In4.Cu")
		(net "M_G_CPU1_SB_DQ<20>")
	)
	(segment
		(start 138.050016 -228.45903)
		(end 138.050016 -228.468936)
		(width 0.088646)
		(layer "In4.Cu")
		(net "M_G_CPU1_SB_DQ<20>")
	)
	(segment
		(start 137.110216 -230.086662)
		(end 137.110216 -230.096568)
		(width 0.088646)
		(layer "In4.Cu")
		(net "M_G_CPU1_SB_DQ<20>")
	)
	(segment
		(start 138.989562 -226.7204)
		(end 138.989562 -226.83089)
		(width 0.088646)
		(layer "In4.Cu")
		(net "M_G_CPU1_SB_DQ<20>")
	)
	(segment
		(start 164.309806 -210.502246)
		(end 160.645602 -210.502246)
		(width 0.18288)
		(layer "In4.Cu")
		(net "M_G_CPU1_SB_DQ<20>")
	)
	(segment
		(start 136.827768 -230.57612)
		(end 136.818878 -230.5812)
		(width 0.088646)
		(layer "In4.Cu")
		(net "M_G_CPU1_SB_DQ<20>")
	)
	(segment
		(start 140.772642 -226.12604)
		(end 140.602462 -226.12604)
		(width 0.088646)
		(layer "In4.Cu")
		(net "M_G_CPU1_SB_DQ<20>")
	)
	(segment
		(start 139.116816 -226.593146)
		(end 138.989562 -226.7204)
		(width 0.088646)
		(layer "In4.Cu")
		(net "M_G_CPU1_SB_DQ<20>")
	)
	(segment
		(start 165.257226 -209.554826)
		(end 164.309806 -210.502246)
		(width 0.18288)
		(layer "In4.Cu")
		(net "M_G_CPU1_SB_DQ<20>")
	)
	(segment
		(start 130.660648 -232.01376)
		(end 129.966212 -231.714548)
		(width 0.088646)
		(layer "In4.Cu")
		(net "M_G_CPU1_SB_DQ<20>")
	)
	(segment
		(start 159.36722 -210.443826)
		(end 159.09036 -210.720686)
		(width 0.18288)
		(layer "In4.Cu")
		(net "M_G_CPU1_SB_DQ<20>")
	)
	(segment
		(start 140.135356 -226.593146)
		(end 139.116816 -226.593146)
		(width 0.088646)
		(layer "In4.Cu")
		(net "M_G_CPU1_SB_DQ<20>")
	)
	(segment
		(start 148.623528 -219.962222)
		(end 148.623528 -219.961968)
		(width 0.18288)
		(layer "In4.Cu")
		(net "M_G_CPU1_SB_DQ<20>")
	)
	(segment
		(start 138.989562 -226.83089)
		(end 138.989816 -226.846384)
		(width 0.088646)
		(layer "In4.Cu")
		(net "M_G_CPU1_SB_DQ<20>")
	)
	(segment
		(start 165.654482 -209.554826)
		(end 165.257226 -209.554826)
		(width 0.18288)
		(layer "In4.Cu")
		(net "M_G_CPU1_SB_DQ<20>")
	)
	(segment
		(start 132.98043 -231.394254)
		(end 132.973064 -231.389936)
		(width 0.088646)
		(layer "In4.Cu")
		(net "M_G_CPU1_SB_DQ<20>")
	)
	(segment
		(start 182.199026 -209.580226)
		(end 179.963826 -209.580226)
		(width 0.18288)
		(layer "In4.Cu")
		(net "M_G_CPU1_SB_DQ<20>")
	)
	(segment
		(start 172.063664 -208.793588)
		(end 171.302426 -209.554826)
		(width 0.18288)
		(layer "In4.Cu")
		(net "M_G_CPU1_SB_DQ<20>")
	)
	(segment
		(start 183.443626 -207.522826)
		(end 183.443626 -208.335626)
		(width 0.18288)
		(layer "In4.Cu")
		(net "M_G_CPU1_SB_DQ<20>")
	)
	(segment
		(start 137.303764 -229.758748)
		(end 137.297668 -229.762304)
		(width 0.088646)
		(layer "In4.Cu")
		(net "M_G_CPU1_SB_DQ<20>")
	)
	(segment
		(start 177.703226 -210.49361)
		(end 176.40681 -210.49361)
		(width 0.18288)
		(layer "In4.Cu")
		(net "M_G_CPU1_SB_DQ<20>")
	)
	(segment
		(start 165.837362 -210.468972)
		(end 165.837362 -209.737706)
		(width 0.18288)
		(layer "In4.Cu")
		(net "M_G_CPU1_SB_DQ<20>")
	)
	(segment
		(start 134.852664 -231.389936)
		(end 134.848854 -231.387904)
		(width 0.088646)
		(layer "In4.Cu")
		(net "M_G_CPU1_SB_DQ<20>")
	)
	(segment
		(start 178.79441 -209.402426)
		(end 177.703226 -210.49361)
		(width 0.18288)
		(layer "In4.Cu")
		(net "M_G_CPU1_SB_DQ<20>")
	)
	(segment
		(start 179.963826 -209.580226)
		(end 179.786026 -209.402426)
		(width 0.18288)
		(layer "In4.Cu")
		(net "M_G_CPU1_SB_DQ<20>")
	)
	(segment
		(start 157.452822 -210.443826)
		(end 156.689298 -211.20735)
		(width 0.18288)
		(layer "In4.Cu")
		(net "M_G_CPU1_SB_DQ<20>")
	)
	(segment
		(start 142.459456 -226.12604)
		(end 140.772642 -226.12604)
		(width 0.18288)
		(layer "In4.Cu")
		(net "M_G_CPU1_SB_DQ<20>")
	)
	(segment
		(start 166.020242 -210.651852)
		(end 165.837362 -210.468972)
		(width 0.18288)
		(layer "In4.Cu")
		(net "M_G_CPU1_SB_DQ<20>")
	)
	(segment
		(start 165.837362 -209.737706)
		(end 165.654482 -209.554826)
		(width 0.18288)
		(layer "In4.Cu")
		(net "M_G_CPU1_SB_DQ<20>")
	)
	(segment
		(start 137.297668 -229.762304)
		(end 137.288778 -229.767384)
		(width 0.088646)
		(layer "In4.Cu")
		(net "M_G_CPU1_SB_DQ<20>")
	)
	(segment
		(start 174.706788 -208.793588)
		(end 172.063664 -208.793588)
		(width 0.18288)
		(layer "In4.Cu")
		(net "M_G_CPU1_SB_DQ<20>")
	)
	(segment
		(start 134.86003 -231.394254)
		(end 134.852664 -231.389936)
		(width 0.088646)
		(layer "In4.Cu")
		(net "M_G_CPU1_SB_DQ<20>")
	)
	(segment
		(start 166.530782 -210.468972)
		(end 166.347902 -210.651852)
		(width 0.18288)
		(layer "In4.Cu")
		(net "M_G_CPU1_SB_DQ<20>")
	)
	(segment
		(start 148.623528 -219.961968)
		(end 142.459456 -226.12604)
		(width 0.18288)
		(layer "In4.Cu")
		(net "M_G_CPU1_SB_DQ<20>")
	)
	(segment
		(start 160.587182 -210.443826)
		(end 159.36722 -210.443826)
		(width 0.18288)
		(layer "In4.Cu")
		(net "M_G_CPU1_SB_DQ<20>")
	)
	(arc
		(start 132.263896 -231.8766)
		(mid 132.190931 -231.940575)
		(end 132.110226 -231.994456)
		(width 0.088646)
		(layer "In4.Cu")
		(net "M_G_CPU1_SB_DQ<20>")
	)
	(arc
		(start 138.989816 -226.846384)
		(mid 138.910278 -227.120329)
		(end 138.707114 -227.320602)
		(width 0.088646)
		(layer "In4.Cu")
		(net "M_G_CPU1_SB_DQ<20>")
	)
	(arc
		(start 131.658614 -232.038906)
		(mid 131.37944 -231.963141)
		(end 131.099306 -232.03535)
		(width 0.088646)
		(layer "In4.Cu")
		(net "M_G_CPU1_SB_DQ<20>")
	)
	(arc
		(start 137.580116 -229.272846)
		(mid 137.5062 -229.552348)
		(end 137.303764 -229.758748)
		(width 0.088646)
		(layer "In4.Cu")
		(net "M_G_CPU1_SB_DQ<20>")
	)
	(arc
		(start 134.848854 -231.387904)
		(mid 134.663164 -231.339826)
		(end 134.478014 -231.389936)
		(width 0.088646)
		(layer "In4.Cu")
		(net "M_G_CPU1_SB_DQ<20>")
	)
	(arc
		(start 132.968492 -231.387396)
		(mid 132.783107 -231.339758)
		(end 132.598414 -231.389936)
		(width 0.088646)
		(layer "In4.Cu")
		(net "M_G_CPU1_SB_DQ<20>")
	)
	(arc
		(start 137.288778 -229.767384)
		(mid 137.157864 -229.903744)
		(end 137.110216 -230.086662)
		(width 0.088646)
		(layer "In4.Cu")
		(net "M_G_CPU1_SB_DQ<20>")
	)
	(arc
		(start 136.818878 -230.5812)
		(mid 136.687964 -230.71756)
		(end 136.640316 -230.900478)
		(width 0.088646)
		(layer "In4.Cu")
		(net "M_G_CPU1_SB_DQ<20>")
	)
	(arc
		(start 138.707114 -227.320602)
		(mid 138.572181 -227.453956)
		(end 138.519916 -227.636324)
		(width 0.088646)
		(layer "In4.Cu")
		(net "M_G_CPU1_SB_DQ<20>")
	)
	(arc
		(start 130.74142 -232.051098)
		(mid 130.701258 -232.031944)
		(end 130.660648 -232.01376)
		(width 0.088646)
		(layer "In4.Cu")
		(net "M_G_CPU1_SB_DQ<20>")
	)
	(arc
		(start 132.50926 -231.441498)
		(mid 132.427462 -231.523303)
		(end 132.3975 -231.635046)
		(width 0.088646)
		(layer "In4.Cu")
		(net "M_G_CPU1_SB_DQ<20>")
	)
	(arc
		(start 132.3975 -231.635046)
		(mid 132.377697 -231.734692)
		(end 132.3213 -231.819196)
		(width 0.088646)
		(layer "In4.Cu")
		(net "M_G_CPU1_SB_DQ<20>")
	)
	(arc
		(start 138.228578 -228.139752)
		(mid 138.097664 -228.276112)
		(end 138.050016 -228.45903)
		(width 0.088646)
		(layer "In4.Cu")
		(net "M_G_CPU1_SB_DQ<20>")
	)
	(arc
		(start 137.758678 -228.953568)
		(mid 137.627764 -229.089928)
		(end 137.580116 -229.272846)
		(width 0.088646)
		(layer "In4.Cu")
		(net "M_G_CPU1_SB_DQ<20>")
	)
	(arc
		(start 136.640316 -230.91902)
		(mid 136.560154 -231.191209)
		(end 136.357868 -231.39019)
		(width 0.088646)
		(layer "In4.Cu")
		(net "M_G_CPU1_SB_DQ<20>")
	)
	(arc
		(start 131.087622 -232.042208)
		(mid 130.915612 -232.089049)
		(end 130.74142 -232.051098)
		(width 0.088646)
		(layer "In4.Cu")
		(net "M_G_CPU1_SB_DQ<20>")
	)
	(arc
		(start 132.027422 -232.042208)
		(mid 131.842567 -232.089158)
		(end 131.658614 -232.038906)
		(width 0.088646)
		(layer "In4.Cu")
		(net "M_G_CPU1_SB_DQ<20>")
	)
	(arc
		(start 135.417814 -231.389936)
		(mid 135.139491 -231.465695)
		(end 134.86003 -231.394254)
		(width 0.088646)
		(layer "In4.Cu")
		(net "M_G_CPU1_SB_DQ<20>")
	)
	(arc
		(start 133.910324 -231.388412)
		(mid 133.724075 -231.339767)
		(end 133.538214 -231.389936)
		(width 0.088646)
		(layer "In4.Cu")
		(net "M_G_CPU1_SB_DQ<20>")
	)
	(arc
		(start 138.519916 -227.663502)
		(mid 138.439754 -227.935691)
		(end 138.237468 -228.134672)
		(width 0.088646)
		(layer "In4.Cu")
		(net "M_G_CPU1_SB_DQ<20>")
	)
	(arc
		(start 134.478014 -231.389936)
		(mid 134.195456 -231.465585)
		(end 133.912864 -231.389936)
		(width 0.088646)
		(layer "In4.Cu")
		(net "M_G_CPU1_SB_DQ<20>")
	)
	(arc
		(start 133.538214 -231.389936)
		(mid 133.259891 -231.465695)
		(end 132.98043 -231.394254)
		(width 0.088646)
		(layer "In4.Cu")
		(net "M_G_CPU1_SB_DQ<20>")
	)
	(arc
		(start 135.789924 -231.388412)
		(mid 135.603675 -231.339767)
		(end 135.417814 -231.389936)
		(width 0.088646)
		(layer "In4.Cu")
		(net "M_G_CPU1_SB_DQ<20>")
	)
	(arc
		(start 138.050016 -228.468936)
		(mid 137.971905 -228.745885)
		(end 137.767568 -228.948488)
		(width 0.088646)
		(layer "In4.Cu")
		(net "M_G_CPU1_SB_DQ<20>")
	)
	(arc
		(start 137.110216 -230.096568)
		(mid 137.032105 -230.373517)
		(end 136.827768 -230.57612)
		(width 0.088646)
		(layer "In4.Cu")
		(net "M_G_CPU1_SB_DQ<20>")
	)
	(arc
		(start 136.357868 -231.39019)
		(mid 136.075166 -231.465932)
		(end 135.792464 -231.39019)
		(width 0.088646)
		(layer "In4.Cu")
		(net "M_G_CPU1_SB_DQ<20>")
	)
	(segment
		(start 194.508882 -230.035354)
		(end 194.098926 -230.035354)
		(width 0.20066)
		(layer "F.Cu")
		(net "M_G_CPU1_SB_DQ<1>")
	)
	(segment
		(start 196.532246 -230.466646)
		(end 196.531992 -230.4669)
		(width 0.20066)
		(layer "F.Cu")
		(net "M_G_CPU1_SB_DQ<1>")
	)
	(segment
		(start 126.676912 -241.203226)
		(end 126.677166 -241.202972)
		(width 0.20066)
		(layer "F.Cu")
		(net "M_G_CPU1_SB_DQ<1>")
	)
	(segment
		(start 190.509144 -230.466646)
		(end 188.988446 -230.466646)
		(width 0.20066)
		(layer "F.Cu")
		(net "M_G_CPU1_SB_DQ<1>")
	)
	(segment
		(start 191.421004 -230.159814)
		(end 191.421004 -230.527352)
		(width 0.20066)
		(layer "F.Cu")
		(net "M_G_CPU1_SB_DQ<1>")
	)
	(segment
		(start 191.883792 -230.041704)
		(end 191.539114 -230.041704)
		(width 0.20066)
		(layer "F.Cu")
		(net "M_G_CPU1_SB_DQ<1>")
	)
	(segment
		(start 126.677166 -241.202972)
		(end 126.677166 -240.667286)
		(width 0.20066)
		(layer "F.Cu")
		(net "M_G_CPU1_SB_DQ<1>")
	)
	(segment
		(start 191.539114 -230.041704)
		(end 191.421004 -230.159814)
		(width 0.20066)
		(layer "F.Cu")
		(net "M_G_CPU1_SB_DQ<1>")
	)
	(segment
		(start 194.098926 -230.035354)
		(end 194.092576 -230.041704)
		(width 0.1016)
		(layer "F.Cu")
		(net "M_G_CPU1_SB_DQ<1>")
	)
	(segment
		(start 194.940428 -230.4669)
		(end 194.508882 -230.035354)
		(width 0.20066)
		(layer "F.Cu")
		(net "M_G_CPU1_SB_DQ<1>")
	)
	(segment
		(start 191.903858 -230.041704)
		(end 191.883792 -230.041704)
		(width 0.101854)
		(layer "F.Cu")
		(net "M_G_CPU1_SB_DQ<1>")
	)
	(segment
		(start 188.988446 -230.466646)
		(end 187.883546 -230.466646)
		(width 0.20066)
		(layer "F.Cu")
		(net "M_G_CPU1_SB_DQ<1>")
	)
	(segment
		(start 191.233044 -230.715312)
		(end 190.75781 -230.715312)
		(width 0.20066)
		(layer "F.Cu")
		(net "M_G_CPU1_SB_DQ<1>")
	)
	(segment
		(start 196.531992 -230.4669)
		(end 194.940428 -230.4669)
		(width 0.20066)
		(layer "F.Cu")
		(net "M_G_CPU1_SB_DQ<1>")
	)
	(segment
		(start 190.75781 -230.715312)
		(end 190.509144 -230.466646)
		(width 0.20066)
		(layer "F.Cu")
		(net "M_G_CPU1_SB_DQ<1>")
	)
	(segment
		(start 194.092576 -230.041704)
		(end 191.903858 -230.041704)
		(width 0.1016)
		(layer "F.Cu")
		(net "M_G_CPU1_SB_DQ<1>")
	)
	(segment
		(start 191.421004 -230.527352)
		(end 191.233044 -230.715312)
		(width 0.20066)
		(layer "F.Cu")
		(net "M_G_CPU1_SB_DQ<1>")
	)
	(segment
		(start 139.662916 -241.60988)
		(end 139.31138 -241.60988)
		(width 0.088646)
		(layer "In6.Cu")
		(net "M_G_CPU1_SB_DQ<1>")
	)
	(segment
		(start 154.984704 -236.389672)
		(end 154.824684 -236.229652)
		(width 0.18288)
		(layer "In6.Cu")
		(net "M_G_CPU1_SB_DQ<1>")
	)
	(segment
		(start 155.518104 -235.863892)
		(end 155.518104 -236.229652)
		(width 0.18288)
		(layer "In6.Cu")
		(net "M_G_CPU1_SB_DQ<1>")
	)
	(segment
		(start 140.212826 -241.05997)
		(end 139.662916 -241.60988)
		(width 0.088646)
		(layer "In6.Cu")
		(net "M_G_CPU1_SB_DQ<1>")
	)
	(segment
		(start 170.08475 -236.936026)
		(end 169.58183 -236.936026)
		(width 0.18288)
		(layer "In6.Cu")
		(net "M_G_CPU1_SB_DQ<1>")
	)
	(segment
		(start 183.958738 -233.85907)
		(end 183.791098 -234.02671)
		(width 0.18288)
		(layer "In6.Cu")
		(net "M_G_CPU1_SB_DQ<1>")
	)
	(segment
		(start 184.641744 -232.840276)
		(end 184.141872 -232.840276)
		(width 0.18288)
		(layer "In6.Cu")
		(net "M_G_CPU1_SB_DQ<1>")
	)
	(segment
		(start 155.518104 -236.229652)
		(end 155.358084 -236.389672)
		(width 0.18288)
		(layer "In6.Cu")
		(net "M_G_CPU1_SB_DQ<1>")
	)
	(segment
		(start 185.071766 -231.422702)
		(end 184.839864 -231.654604)
		(width 0.18288)
		(layer "In6.Cu")
		(net "M_G_CPU1_SB_DQ<1>")
	)
	(segment
		(start 187.883546 -230.466646)
		(end 187.408566 -230.941626)
		(width 0.18288)
		(layer "In6.Cu")
		(net "M_G_CPU1_SB_DQ<1>")
	)
	(segment
		(start 138.98118 -241.27968)
		(end 138.7348 -241.27968)
		(width 0.088646)
		(layer "In6.Cu")
		(net "M_G_CPU1_SB_DQ<1>")
	)
	(segment
		(start 173.548294 -236.842046)
		(end 171.3357 -236.842046)
		(width 0.18288)
		(layer "In6.Cu")
		(net "M_G_CPU1_SB_DQ<1>")
	)
	(segment
		(start 128.037336 -241.03965)
		(end 127.948944 -241.045492)
		(width 0.088646)
		(layer "In6.Cu")
		(net "M_G_CPU1_SB_DQ<1>")
	)
	(segment
		(start 183.108092 -233.861356)
		(end 182.884318 -234.08513)
		(width 0.18288)
		(layer "In6.Cu")
		(net "M_G_CPU1_SB_DQ<1>")
	)
	(segment
		(start 168.702228 -236.568488)
		(end 168.33469 -236.936026)
		(width 0.18288)
		(layer "In6.Cu")
		(net "M_G_CPU1_SB_DQ<1>")
	)
	(segment
		(start 179.317904 -236.479588)
		(end 178.46929 -236.479588)
		(width 0.18288)
		(layer "In6.Cu")
		(net "M_G_CPU1_SB_DQ<1>")
	)
	(segment
		(start 169.214292 -236.568488)
		(end 168.702228 -236.568488)
		(width 0.18288)
		(layer "In6.Cu")
		(net "M_G_CPU1_SB_DQ<1>")
	)
	(segment
		(start 179.979066 -235.818426)
		(end 179.317904 -236.479588)
		(width 0.18288)
		(layer "In6.Cu")
		(net "M_G_CPU1_SB_DQ<1>")
	)
	(segment
		(start 139.31138 -241.60988)
		(end 138.98118 -241.27968)
		(width 0.088646)
		(layer "In6.Cu")
		(net "M_G_CPU1_SB_DQ<1>")
	)
	(segment
		(start 176.03216 -235.63961)
		(end 174.75073 -235.63961)
		(width 0.18288)
		(layer "In6.Cu")
		(net "M_G_CPU1_SB_DQ<1>")
	)
	(segment
		(start 185.565542 -231.657906)
		(end 185.330338 -231.422702)
		(width 0.18288)
		(layer "In6.Cu")
		(net "M_G_CPU1_SB_DQ<1>")
	)
	(segment
		(start 154.664664 -235.703872)
		(end 153.50871 -235.703872)
		(width 0.18288)
		(layer "In6.Cu")
		(net "M_G_CPU1_SB_DQ<1>")
	)
	(segment
		(start 128.839468 -241.156744)
		(end 128.829054 -241.16284)
		(width 0.088646)
		(layer "In6.Cu")
		(net "M_G_CPU1_SB_DQ<1>")
	)
	(segment
		(start 165.137846 -235.912406)
		(end 164.49421 -235.912406)
		(width 0.18288)
		(layer "In6.Cu")
		(net "M_G_CPU1_SB_DQ<1>")
	)
	(segment
		(start 161.167826 -236.555026)
		(end 160.316672 -235.703872)
		(width 0.18288)
		(layer "In6.Cu")
		(net "M_G_CPU1_SB_DQ<1>")
	)
	(segment
		(start 135.418068 -241.156744)
		(end 135.407654 -241.16284)
		(width 0.088646)
		(layer "In6.Cu")
		(net "M_G_CPU1_SB_DQ<1>")
	)
	(segment
		(start 185.330338 -231.422702)
		(end 185.071766 -231.422702)
		(width 0.18288)
		(layer "In6.Cu")
		(net "M_G_CPU1_SB_DQ<1>")
	)
	(segment
		(start 171.3357 -236.842046)
		(end 171.062142 -236.568488)
		(width 0.18288)
		(layer "In6.Cu")
		(net "M_G_CPU1_SB_DQ<1>")
	)
	(segment
		(start 170.452288 -236.568488)
		(end 170.08475 -236.936026)
		(width 0.18288)
		(layer "In6.Cu")
		(net "M_G_CPU1_SB_DQ<1>")
	)
	(segment
		(start 148.152612 -241.05997)
		(end 140.442696 -241.05997)
		(width 0.18288)
		(layer "In6.Cu")
		(net "M_G_CPU1_SB_DQ<1>")
	)
	(segment
		(start 134.478014 -241.156744)
		(end 134.4676 -241.16284)
		(width 0.088646)
		(layer "In6.Cu")
		(net "M_G_CPU1_SB_DQ<1>")
	)
	(segment
		(start 182.795926 -235.297726)
		(end 181.525926 -235.297726)
		(width 0.18288)
		(layer "In6.Cu")
		(net "M_G_CPU1_SB_DQ<1>")
	)
	(segment
		(start 183.14797 -234.686602)
		(end 183.14797 -234.945682)
		(width 0.18288)
		(layer "In6.Cu")
		(net "M_G_CPU1_SB_DQ<1>")
	)
	(segment
		(start 181.005226 -235.818426)
		(end 179.979066 -235.818426)
		(width 0.18288)
		(layer "In6.Cu")
		(net "M_G_CPU1_SB_DQ<1>")
	)
	(segment
		(start 127.948944 -241.045492)
		(end 127.590296 -241.045492)
		(width 0.088646)
		(layer "In6.Cu")
		(net "M_G_CPU1_SB_DQ<1>")
	)
	(segment
		(start 154.824684 -235.863892)
		(end 154.664664 -235.703872)
		(width 0.18288)
		(layer "In6.Cu")
		(net "M_G_CPU1_SB_DQ<1>")
	)
	(segment
		(start 166.161466 -236.936026)
		(end 165.137846 -235.912406)
		(width 0.18288)
		(layer "In6.Cu")
		(net "M_G_CPU1_SB_DQ<1>")
	)
	(segment
		(start 183.14797 -234.945682)
		(end 182.795926 -235.297726)
		(width 0.18288)
		(layer "In6.Cu")
		(net "M_G_CPU1_SB_DQ<1>")
	)
	(segment
		(start 182.884318 -234.08513)
		(end 182.884318 -234.42295)
		(width 0.18288)
		(layer "In6.Cu")
		(net "M_G_CPU1_SB_DQ<1>")
	)
	(segment
		(start 185.824114 -231.657906)
		(end 185.565542 -231.657906)
		(width 0.18288)
		(layer "In6.Cu")
		(net "M_G_CPU1_SB_DQ<1>")
	)
	(segment
		(start 155.358084 -236.389672)
		(end 154.984704 -236.389672)
		(width 0.18288)
		(layer "In6.Cu")
		(net "M_G_CPU1_SB_DQ<1>")
	)
	(segment
		(start 178.46929 -236.479588)
		(end 177.98161 -235.991908)
		(width 0.18288)
		(layer "In6.Cu")
		(net "M_G_CPU1_SB_DQ<1>")
	)
	(segment
		(start 183.958738 -233.02341)
		(end 183.958738 -233.85907)
		(width 0.18288)
		(layer "In6.Cu")
		(net "M_G_CPU1_SB_DQ<1>")
	)
	(segment
		(start 138.7348 -241.27968)
		(end 138.611864 -241.156744)
		(width 0.088646)
		(layer "In6.Cu")
		(net "M_G_CPU1_SB_DQ<1>")
	)
	(segment
		(start 160.316672 -235.703872)
		(end 157.064964 -235.703872)
		(width 0.18288)
		(layer "In6.Cu")
		(net "M_G_CPU1_SB_DQ<1>")
	)
	(segment
		(start 185.075068 -232.406952)
		(end 184.641744 -232.840276)
		(width 0.18288)
		(layer "In6.Cu")
		(net "M_G_CPU1_SB_DQ<1>")
	)
	(segment
		(start 153.50871 -235.703872)
		(end 148.152612 -241.05997)
		(width 0.18288)
		(layer "In6.Cu")
		(net "M_G_CPU1_SB_DQ<1>")
	)
	(segment
		(start 128.164082 -241.07394)
		(end 128.037336 -241.03965)
		(width 0.088646)
		(layer "In6.Cu")
		(net "M_G_CPU1_SB_DQ<1>")
	)
	(segment
		(start 154.824684 -236.229652)
		(end 154.824684 -235.863892)
		(width 0.18288)
		(layer "In6.Cu")
		(net "M_G_CPU1_SB_DQ<1>")
	)
	(segment
		(start 184.141872 -232.840276)
		(end 183.958738 -233.02341)
		(width 0.18288)
		(layer "In6.Cu")
		(net "M_G_CPU1_SB_DQ<1>")
	)
	(segment
		(start 131.658614 -241.156744)
		(end 131.643882 -241.16538)
		(width 0.088646)
		(layer "In6.Cu")
		(net "M_G_CPU1_SB_DQ<1>")
	)
	(segment
		(start 156.051504 -235.703872)
		(end 155.678124 -235.703872)
		(width 0.18288)
		(layer "In6.Cu")
		(net "M_G_CPU1_SB_DQ<1>")
	)
	(segment
		(start 186.540394 -230.941626)
		(end 185.824114 -231.657906)
		(width 0.18288)
		(layer "In6.Cu")
		(net "M_G_CPU1_SB_DQ<1>")
	)
	(segment
		(start 130.718814 -241.156744)
		(end 130.704082 -241.16538)
		(width 0.088646)
		(layer "In6.Cu")
		(net "M_G_CPU1_SB_DQ<1>")
	)
	(segment
		(start 181.525926 -235.297726)
		(end 181.005226 -235.818426)
		(width 0.18288)
		(layer "In6.Cu")
		(net "M_G_CPU1_SB_DQ<1>")
	)
	(segment
		(start 156.371544 -236.389672)
		(end 156.211524 -236.229652)
		(width 0.18288)
		(layer "In6.Cu")
		(net "M_G_CPU1_SB_DQ<1>")
	)
	(segment
		(start 156.744924 -236.389672)
		(end 156.371544 -236.389672)
		(width 0.18288)
		(layer "In6.Cu")
		(net "M_G_CPU1_SB_DQ<1>")
	)
	(segment
		(start 183.366664 -233.861356)
		(end 183.108092 -233.861356)
		(width 0.18288)
		(layer "In6.Cu")
		(net "M_G_CPU1_SB_DQ<1>")
	)
	(segment
		(start 171.062142 -236.568488)
		(end 170.452288 -236.568488)
		(width 0.18288)
		(layer "In6.Cu")
		(net "M_G_CPU1_SB_DQ<1>")
	)
	(segment
		(start 182.884318 -234.42295)
		(end 183.14797 -234.686602)
		(width 0.18288)
		(layer "In6.Cu")
		(net "M_G_CPU1_SB_DQ<1>")
	)
	(segment
		(start 177.98161 -235.991908)
		(end 176.384458 -235.991908)
		(width 0.18288)
		(layer "In6.Cu")
		(net "M_G_CPU1_SB_DQ<1>")
	)
	(segment
		(start 187.408566 -230.941626)
		(end 186.540394 -230.941626)
		(width 0.18288)
		(layer "In6.Cu")
		(net "M_G_CPU1_SB_DQ<1>")
	)
	(segment
		(start 184.839864 -231.654604)
		(end 184.839864 -231.913176)
		(width 0.18288)
		(layer "In6.Cu")
		(net "M_G_CPU1_SB_DQ<1>")
	)
	(segment
		(start 183.791098 -234.02671)
		(end 183.532018 -234.02671)
		(width 0.18288)
		(layer "In6.Cu")
		(net "M_G_CPU1_SB_DQ<1>")
	)
	(segment
		(start 140.442696 -241.05997)
		(end 140.212826 -241.05997)
		(width 0.088646)
		(layer "In6.Cu")
		(net "M_G_CPU1_SB_DQ<1>")
	)
	(segment
		(start 156.211524 -236.229652)
		(end 156.211524 -235.863892)
		(width 0.18288)
		(layer "In6.Cu")
		(net "M_G_CPU1_SB_DQ<1>")
	)
	(segment
		(start 185.075068 -232.14838)
		(end 185.075068 -232.406952)
		(width 0.18288)
		(layer "In6.Cu")
		(net "M_G_CPU1_SB_DQ<1>")
	)
	(segment
		(start 157.064964 -235.703872)
		(end 156.904944 -235.863892)
		(width 0.18288)
		(layer "In6.Cu")
		(net "M_G_CPU1_SB_DQ<1>")
	)
	(segment
		(start 174.75073 -235.63961)
		(end 173.548294 -236.842046)
		(width 0.18288)
		(layer "In6.Cu")
		(net "M_G_CPU1_SB_DQ<1>")
	)
	(segment
		(start 176.384458 -235.991908)
		(end 176.03216 -235.63961)
		(width 0.18288)
		(layer "In6.Cu")
		(net "M_G_CPU1_SB_DQ<1>")
	)
	(segment
		(start 156.904944 -235.863892)
		(end 156.904944 -236.229652)
		(width 0.18288)
		(layer "In6.Cu")
		(net "M_G_CPU1_SB_DQ<1>")
	)
	(segment
		(start 156.211524 -235.863892)
		(end 156.051504 -235.703872)
		(width 0.18288)
		(layer "In6.Cu")
		(net "M_G_CPU1_SB_DQ<1>")
	)
	(segment
		(start 133.538468 -241.156744)
		(end 133.528054 -241.16284)
		(width 0.088646)
		(layer "In6.Cu")
		(net "M_G_CPU1_SB_DQ<1>")
	)
	(segment
		(start 163.85159 -236.555026)
		(end 161.167826 -236.555026)
		(width 0.18288)
		(layer "In6.Cu")
		(net "M_G_CPU1_SB_DQ<1>")
	)
	(segment
		(start 156.904944 -236.229652)
		(end 156.744924 -236.389672)
		(width 0.18288)
		(layer "In6.Cu")
		(net "M_G_CPU1_SB_DQ<1>")
	)
	(segment
		(start 155.678124 -235.703872)
		(end 155.518104 -235.863892)
		(width 0.18288)
		(layer "In6.Cu")
		(net "M_G_CPU1_SB_DQ<1>")
	)
	(segment
		(start 168.33469 -236.936026)
		(end 166.161466 -236.936026)
		(width 0.18288)
		(layer "In6.Cu")
		(net "M_G_CPU1_SB_DQ<1>")
	)
	(segment
		(start 129.779014 -241.156744)
		(end 129.7686 -241.16284)
		(width 0.088646)
		(layer "In6.Cu")
		(net "M_G_CPU1_SB_DQ<1>")
	)
	(segment
		(start 183.532018 -234.02671)
		(end 183.366664 -233.861356)
		(width 0.18288)
		(layer "In6.Cu")
		(net "M_G_CPU1_SB_DQ<1>")
	)
	(segment
		(start 169.58183 -236.936026)
		(end 169.214292 -236.568488)
		(width 0.18288)
		(layer "In6.Cu")
		(net "M_G_CPU1_SB_DQ<1>")
	)
	(segment
		(start 164.49421 -235.912406)
		(end 163.85159 -236.555026)
		(width 0.18288)
		(layer "In6.Cu")
		(net "M_G_CPU1_SB_DQ<1>")
	)
	(segment
		(start 184.839864 -231.913176)
		(end 185.075068 -232.14838)
		(width 0.18288)
		(layer "In6.Cu")
		(net "M_G_CPU1_SB_DQ<1>")
	)
	(arc
		(start 137.672064 -241.156744)
		(mid 137.484866 -241.106601)
		(end 137.297668 -241.156744)
		(width 0.088646)
		(layer "In6.Cu")
		(net "M_G_CPU1_SB_DQ<1>")
	)
	(arc
		(start 132.598414 -241.156744)
		(mid 132.315712 -241.23252)
		(end 132.03301 -241.156744)
		(width 0.088646)
		(layer "In6.Cu")
		(net "M_G_CPU1_SB_DQ<1>")
	)
	(arc
		(start 138.611864 -241.156744)
		(mid 138.424666 -241.106601)
		(end 138.237468 -241.156744)
		(width 0.088646)
		(layer "In6.Cu")
		(net "M_G_CPU1_SB_DQ<1>")
	)
	(arc
		(start 132.97281 -241.156744)
		(mid 132.785612 -241.106601)
		(end 132.598414 -241.156744)
		(width 0.088646)
		(layer "In6.Cu")
		(net "M_G_CPU1_SB_DQ<1>")
	)
	(arc
		(start 131.09321 -241.156744)
		(mid 130.906012 -241.106601)
		(end 130.718814 -241.156744)
		(width 0.088646)
		(layer "In6.Cu")
		(net "M_G_CPU1_SB_DQ<1>")
	)
	(arc
		(start 134.85241 -241.156744)
		(mid 134.665212 -241.106601)
		(end 134.478014 -241.156744)
		(width 0.088646)
		(layer "In6.Cu")
		(net "M_G_CPU1_SB_DQ<1>")
	)
	(arc
		(start 135.407654 -241.16284)
		(mid 135.129222 -241.232686)
		(end 134.85241 -241.156744)
		(width 0.088646)
		(layer "In6.Cu")
		(net "M_G_CPU1_SB_DQ<1>")
	)
	(arc
		(start 136.357868 -241.156744)
		(mid 136.075166 -241.23252)
		(end 135.792464 -241.156744)
		(width 0.088646)
		(layer "In6.Cu")
		(net "M_G_CPU1_SB_DQ<1>")
	)
	(arc
		(start 135.792464 -241.156744)
		(mid 135.605266 -241.106601)
		(end 135.418068 -241.156744)
		(width 0.088646)
		(layer "In6.Cu")
		(net "M_G_CPU1_SB_DQ<1>")
	)
	(arc
		(start 128.829054 -241.16284)
		(mid 128.550622 -241.232686)
		(end 128.27381 -241.156744)
		(width 0.088646)
		(layer "In6.Cu")
		(net "M_G_CPU1_SB_DQ<1>")
	)
	(arc
		(start 129.7686 -241.16284)
		(mid 129.490422 -241.232563)
		(end 129.213864 -241.156744)
		(width 0.088646)
		(layer "In6.Cu")
		(net "M_G_CPU1_SB_DQ<1>")
	)
	(arc
		(start 132.03301 -241.156744)
		(mid 131.845812 -241.106601)
		(end 131.658614 -241.156744)
		(width 0.088646)
		(layer "In6.Cu")
		(net "M_G_CPU1_SB_DQ<1>")
	)
	(arc
		(start 127.590296 -241.045492)
		(mid 127.096123 -240.947195)
		(end 126.677166 -240.667286)
		(width 0.088646)
		(layer "In6.Cu")
		(net "M_G_CPU1_SB_DQ<1>")
	)
	(arc
		(start 137.297668 -241.156744)
		(mid 137.014966 -241.23252)
		(end 136.732264 -241.156744)
		(width 0.088646)
		(layer "In6.Cu")
		(net "M_G_CPU1_SB_DQ<1>")
	)
	(arc
		(start 136.732264 -241.156744)
		(mid 136.545066 -241.106601)
		(end 136.357868 -241.156744)
		(width 0.088646)
		(layer "In6.Cu")
		(net "M_G_CPU1_SB_DQ<1>")
	)
	(arc
		(start 134.4676 -241.16284)
		(mid 134.189422 -241.232563)
		(end 133.912864 -241.156744)
		(width 0.088646)
		(layer "In6.Cu")
		(net "M_G_CPU1_SB_DQ<1>")
	)
	(arc
		(start 133.912864 -241.156744)
		(mid 133.725666 -241.106601)
		(end 133.538468 -241.156744)
		(width 0.088646)
		(layer "In6.Cu")
		(net "M_G_CPU1_SB_DQ<1>")
	)
	(arc
		(start 138.237468 -241.156744)
		(mid 137.954766 -241.23252)
		(end 137.672064 -241.156744)
		(width 0.088646)
		(layer "In6.Cu")
		(net "M_G_CPU1_SB_DQ<1>")
	)
	(arc
		(start 130.15341 -241.156744)
		(mid 129.966212 -241.106601)
		(end 129.779014 -241.156744)
		(width 0.088646)
		(layer "In6.Cu")
		(net "M_G_CPU1_SB_DQ<1>")
	)
	(arc
		(start 131.643882 -241.16538)
		(mid 131.367407 -241.2327)
		(end 131.09321 -241.156744)
		(width 0.088646)
		(layer "In6.Cu")
		(net "M_G_CPU1_SB_DQ<1>")
	)
	(arc
		(start 130.704082 -241.16538)
		(mid 130.427607 -241.2327)
		(end 130.15341 -241.156744)
		(width 0.088646)
		(layer "In6.Cu")
		(net "M_G_CPU1_SB_DQ<1>")
	)
	(arc
		(start 128.27381 -241.156744)
		(mid 128.216429 -241.118679)
		(end 128.164082 -241.07394)
		(width 0.088646)
		(layer "In6.Cu")
		(net "M_G_CPU1_SB_DQ<1>")
	)
	(arc
		(start 133.528054 -241.16284)
		(mid 133.249622 -241.232686)
		(end 132.97281 -241.156744)
		(width 0.088646)
		(layer "In6.Cu")
		(net "M_G_CPU1_SB_DQ<1>")
	)
	(arc
		(start 129.213864 -241.156744)
		(mid 129.026666 -241.106601)
		(end 128.839468 -241.156744)
		(width 0.088646)
		(layer "In6.Cu")
		(net "M_G_CPU1_SB_DQ<1>")
	)
	(segment
		(start 195.522596 -211.341716)
		(end 197.530466 -211.341716)
		(width 0.1016)
		(layer "F.Cu")
		(net "M_G_CPU1_SB_DQ<19>")
	)
	(segment
		(start 197.530466 -211.341716)
		(end 197.542658 -211.353908)
		(width 0.1016)
		(layer "F.Cu")
		(net "M_G_CPU1_SB_DQ<19>")
	)
	(segment
		(start 197.542658 -211.353908)
		(end 198.223886 -211.353908)
		(width 0.20066)
		(layer "F.Cu")
		(net "M_G_CPU1_SB_DQ<19>")
	)
	(segment
		(start 198.662036 -210.664806)
		(end 199.046084 -210.664806)
		(width 0.20066)
		(layer "F.Cu")
		(net "M_G_CPU1_SB_DQ<19>")
	)
	(segment
		(start 198.427848 -210.898994)
		(end 198.662036 -210.664806)
		(width 0.20066)
		(layer "F.Cu")
		(net "M_G_CPU1_SB_DQ<19>")
	)
	(segment
		(start 199.046084 -210.664806)
		(end 199.298052 -210.916774)
		(width 0.20066)
		(layer "F.Cu")
		(net "M_G_CPU1_SB_DQ<19>")
	)
	(segment
		(start 191.983614 -210.916774)
		(end 193.088514 -210.916774)
		(width 0.20066)
		(layer "F.Cu")
		(net "M_G_CPU1_SB_DQ<19>")
	)
	(segment
		(start 199.298052 -210.916774)
		(end 200.632314 -210.916774)
		(width 0.20066)
		(layer "F.Cu")
		(net "M_G_CPU1_SB_DQ<19>")
	)
	(segment
		(start 195.515484 -211.348828)
		(end 195.522596 -211.341716)
		(width 0.1016)
		(layer "F.Cu")
		(net "M_G_CPU1_SB_DQ<19>")
	)
	(segment
		(start 198.427848 -211.149946)
		(end 198.427848 -210.898994)
		(width 0.20066)
		(layer "F.Cu")
		(net "M_G_CPU1_SB_DQ<19>")
	)
	(segment
		(start 194.786758 -210.916774)
		(end 195.218812 -211.348828)
		(width 0.20066)
		(layer "F.Cu")
		(net "M_G_CPU1_SB_DQ<19>")
	)
	(segment
		(start 195.218812 -211.348828)
		(end 195.510658 -211.348828)
		(width 0.20066)
		(layer "F.Cu")
		(net "M_G_CPU1_SB_DQ<19>")
	)
	(segment
		(start 131.846066 -233.87812)
		(end 131.845812 -233.877866)
		(width 0.20066)
		(layer "F.Cu")
		(net "M_G_CPU1_SB_DQ<19>")
	)
	(segment
		(start 193.088514 -210.916774)
		(end 194.786758 -210.916774)
		(width 0.20066)
		(layer "F.Cu")
		(net "M_G_CPU1_SB_DQ<19>")
	)
	(segment
		(start 198.223886 -211.353908)
		(end 198.427848 -211.149946)
		(width 0.20066)
		(layer "F.Cu")
		(net "M_G_CPU1_SB_DQ<19>")
	)
	(segment
		(start 195.510658 -211.348828)
		(end 195.515484 -211.348828)
		(width 0.101854)
		(layer "F.Cu")
		(net "M_G_CPU1_SB_DQ<19>")
	)
	(segment
		(start 131.845812 -233.877866)
		(end 131.845812 -233.34218)
		(width 0.20066)
		(layer "F.Cu")
		(net "M_G_CPU1_SB_DQ<19>")
	)
	(segment
		(start 168.851326 -214.774526)
		(end 166.782242 -214.774526)
		(width 0.18288)
		(layer "In4.Cu")
		(net "M_G_CPU1_SB_DQ<19>")
	)
	(segment
		(start 137.680954 -233.661458)
		(end 137.672064 -233.666538)
		(width 0.088646)
		(layer "In4.Cu")
		(net "M_G_CPU1_SB_DQ<19>")
	)
	(segment
		(start 178.846226 -215.727026)
		(end 177.862738 -214.743538)
		(width 0.18288)
		(layer "In4.Cu")
		(net "M_G_CPU1_SB_DQ<19>")
	)
	(segment
		(start 164.876226 -214.609426)
		(end 163.437316 -214.609426)
		(width 0.18288)
		(layer "In4.Cu")
		(net "M_G_CPU1_SB_DQ<19>")
	)
	(segment
		(start 132.598414 -233.666792)
		(end 132.201666 -233.43743)
		(width 0.088646)
		(layer "In4.Cu")
		(net "M_G_CPU1_SB_DQ<19>")
	)
	(segment
		(start 169.582084 -214.043768)
		(end 168.851326 -214.774526)
		(width 0.18288)
		(layer "In4.Cu")
		(net "M_G_CPU1_SB_DQ<19>")
	)
	(segment
		(start 134.86003 -233.662474)
		(end 134.852664 -233.666792)
		(width 0.088646)
		(layer "In4.Cu")
		(net "M_G_CPU1_SB_DQ<19>")
	)
	(segment
		(start 163.437316 -214.609426)
		(end 163.254436 -214.426546)
		(width 0.18288)
		(layer "In4.Cu")
		(net "M_G_CPU1_SB_DQ<19>")
	)
	(segment
		(start 171.549568 -214.043768)
		(end 169.582084 -214.043768)
		(width 0.18288)
		(layer "In4.Cu")
		(net "M_G_CPU1_SB_DQ<19>")
	)
	(segment
		(start 166.672514 -214.664798)
		(end 165.90391 -214.664798)
		(width 0.18288)
		(layer "In4.Cu")
		(net "M_G_CPU1_SB_DQ<19>")
	)
	(segment
		(start 181.691026 -213.872826)
		(end 179.836826 -215.727026)
		(width 0.18288)
		(layer "In4.Cu")
		(net "M_G_CPU1_SB_DQ<19>")
	)
	(segment
		(start 160.609026 -214.609426)
		(end 160.355026 -214.863426)
		(width 0.18288)
		(layer "In4.Cu")
		(net "M_G_CPU1_SB_DQ<19>")
	)
	(segment
		(start 135.792464 -233.666538)
		(end 135.789924 -233.668316)
		(width 0.088646)
		(layer "In4.Cu")
		(net "M_G_CPU1_SB_DQ<19>")
	)
	(segment
		(start 139.739116 -229.910386)
		(end 139.739116 -230.086662)
		(width 0.088646)
		(layer "In4.Cu")
		(net "M_G_CPU1_SB_DQ<19>")
	)
	(segment
		(start 133.912864 -233.666792)
		(end 133.910324 -233.668316)
		(width 0.088646)
		(layer "In4.Cu")
		(net "M_G_CPU1_SB_DQ<19>")
	)
	(segment
		(start 162.743896 -213.710266)
		(end 162.561016 -213.893146)
		(width 0.18288)
		(layer "In4.Cu")
		(net "M_G_CPU1_SB_DQ<19>")
	)
	(segment
		(start 163.254436 -214.426546)
		(end 163.254436 -213.893146)
		(width 0.18288)
		(layer "In4.Cu")
		(net "M_G_CPU1_SB_DQ<19>")
	)
	(segment
		(start 139.269216 -230.890572)
		(end 139.269216 -230.900478)
		(width 0.088646)
		(layer "In4.Cu")
		(net "M_G_CPU1_SB_DQ<19>")
	)
	(segment
		(start 139.551918 -230.410766)
		(end 139.551664 -230.41102)
		(width 0.088646)
		(layer "In4.Cu")
		(net "M_G_CPU1_SB_DQ<19>")
	)
	(segment
		(start 131.846066 -233.34218)
		(end 131.845812 -233.34218)
		(width 0.088646)
		(layer "In4.Cu")
		(net "M_G_CPU1_SB_DQ<19>")
	)
	(segment
		(start 140.517372 -229.726998)
		(end 139.922504 -229.726998)
		(width 0.18288)
		(layer "In4.Cu")
		(net "M_G_CPU1_SB_DQ<19>")
	)
	(segment
		(start 189.38367 -210.316826)
		(end 189.206886 -210.49361)
		(width 0.18288)
		(layer "In4.Cu")
		(net "M_G_CPU1_SB_DQ<19>")
	)
	(segment
		(start 183.850026 -212.298026)
		(end 182.275226 -213.872826)
		(width 0.18288)
		(layer "In4.Cu")
		(net "M_G_CPU1_SB_DQ<19>")
	)
	(segment
		(start 172.249338 -214.743538)
		(end 171.549568 -214.043768)
		(width 0.18288)
		(layer "In4.Cu")
		(net "M_G_CPU1_SB_DQ<19>")
	)
	(segment
		(start 132.98043 -233.662474)
		(end 132.973064 -233.666792)
		(width 0.088646)
		(layer "In4.Cu")
		(net "M_G_CPU1_SB_DQ<19>")
	)
	(segment
		(start 162.561016 -214.426546)
		(end 162.378136 -214.609426)
		(width 0.18288)
		(layer "In4.Cu")
		(net "M_G_CPU1_SB_DQ<19>")
	)
	(segment
		(start 163.254436 -213.893146)
		(end 163.071556 -213.710266)
		(width 0.18288)
		(layer "In4.Cu")
		(net "M_G_CPU1_SB_DQ<19>")
	)
	(segment
		(start 189.206886 -210.49361)
		(end 187.153042 -210.49361)
		(width 0.18288)
		(layer "In4.Cu")
		(net "M_G_CPU1_SB_DQ<19>")
	)
	(segment
		(start 144.601946 -228.299264)
		(end 141.945106 -228.299264)
		(width 0.18288)
		(layer "In4.Cu")
		(net "M_G_CPU1_SB_DQ<19>")
	)
	(segment
		(start 139.888722 -229.76078)
		(end 139.739116 -229.910386)
		(width 0.088646)
		(layer "In4.Cu")
		(net "M_G_CPU1_SB_DQ<19>")
	)
	(segment
		(start 163.071556 -213.710266)
		(end 162.743896 -213.710266)
		(width 0.18288)
		(layer "In4.Cu")
		(net "M_G_CPU1_SB_DQ<19>")
	)
	(segment
		(start 160.355026 -214.863426)
		(end 158.037784 -214.863426)
		(width 0.18288)
		(layer "In4.Cu")
		(net "M_G_CPU1_SB_DQ<19>")
	)
	(segment
		(start 134.852664 -233.666792)
		(end 134.848854 -233.668824)
		(width 0.088646)
		(layer "In4.Cu")
		(net "M_G_CPU1_SB_DQ<19>")
	)
	(segment
		(start 138.329416 -232.518458)
		(end 138.329416 -232.528364)
		(width 0.088646)
		(layer "In4.Cu")
		(net "M_G_CPU1_SB_DQ<19>")
	)
	(segment
		(start 162.561016 -213.893146)
		(end 162.561016 -214.426546)
		(width 0.18288)
		(layer "In4.Cu")
		(net "M_G_CPU1_SB_DQ<19>")
	)
	(segment
		(start 141.945106 -228.299264)
		(end 140.517372 -229.726998)
		(width 0.18288)
		(layer "In4.Cu")
		(net "M_G_CPU1_SB_DQ<19>")
	)
	(segment
		(start 138.150854 -232.847642)
		(end 138.141964 -232.852722)
		(width 0.088646)
		(layer "In4.Cu")
		(net "M_G_CPU1_SB_DQ<19>")
	)
	(segment
		(start 165.90391 -214.664798)
		(end 165.794182 -214.774526)
		(width 0.18288)
		(layer "In4.Cu")
		(net "M_G_CPU1_SB_DQ<19>")
	)
	(segment
		(start 177.862738 -214.743538)
		(end 172.249338 -214.743538)
		(width 0.18288)
		(layer "In4.Cu")
		(net "M_G_CPU1_SB_DQ<19>")
	)
	(segment
		(start 179.836826 -215.727026)
		(end 178.846226 -215.727026)
		(width 0.18288)
		(layer "In4.Cu")
		(net "M_G_CPU1_SB_DQ<19>")
	)
	(segment
		(start 138.620754 -232.033826)
		(end 138.611864 -232.038906)
		(width 0.088646)
		(layer "In4.Cu")
		(net "M_G_CPU1_SB_DQ<19>")
	)
	(segment
		(start 191.983614 -210.916774)
		(end 191.383666 -210.316826)
		(width 0.18288)
		(layer "In4.Cu")
		(net "M_G_CPU1_SB_DQ<19>")
	)
	(segment
		(start 132.973064 -233.666792)
		(end 132.968492 -233.669332)
		(width 0.088646)
		(layer "In4.Cu")
		(net "M_G_CPU1_SB_DQ<19>")
	)
	(segment
		(start 166.782242 -214.774526)
		(end 166.672514 -214.664798)
		(width 0.18288)
		(layer "In4.Cu")
		(net "M_G_CPU1_SB_DQ<19>")
	)
	(segment
		(start 139.922504 -229.726998)
		(end 139.888722 -229.76078)
		(width 0.18288)
		(layer "In4.Cu")
		(net "M_G_CPU1_SB_DQ<19>")
	)
	(segment
		(start 191.383666 -210.316826)
		(end 189.38367 -210.316826)
		(width 0.18288)
		(layer "In4.Cu")
		(net "M_G_CPU1_SB_DQ<19>")
	)
	(segment
		(start 158.037784 -214.863426)
		(end 144.601946 -228.299264)
		(width 0.18288)
		(layer "In4.Cu")
		(net "M_G_CPU1_SB_DQ<19>")
	)
	(segment
		(start 137.859516 -233.332274)
		(end 137.859516 -233.34218)
		(width 0.088646)
		(layer "In4.Cu")
		(net "M_G_CPU1_SB_DQ<19>")
	)
	(segment
		(start 162.378136 -214.609426)
		(end 160.609026 -214.609426)
		(width 0.18288)
		(layer "In4.Cu")
		(net "M_G_CPU1_SB_DQ<19>")
	)
	(segment
		(start 187.153042 -210.49361)
		(end 185.348626 -212.298026)
		(width 0.18288)
		(layer "In4.Cu")
		(net "M_G_CPU1_SB_DQ<19>")
	)
	(segment
		(start 165.041326 -214.774526)
		(end 164.876226 -214.609426)
		(width 0.18288)
		(layer "In4.Cu")
		(net "M_G_CPU1_SB_DQ<19>")
	)
	(segment
		(start 185.348626 -212.298026)
		(end 183.850026 -212.298026)
		(width 0.18288)
		(layer "In4.Cu")
		(net "M_G_CPU1_SB_DQ<19>")
	)
	(segment
		(start 165.794182 -214.774526)
		(end 165.041326 -214.774526)
		(width 0.18288)
		(layer "In4.Cu")
		(net "M_G_CPU1_SB_DQ<19>")
	)
	(segment
		(start 138.799316 -231.696006)
		(end 138.799316 -231.714548)
		(width 0.088646)
		(layer "In4.Cu")
		(net "M_G_CPU1_SB_DQ<19>")
	)
	(segment
		(start 139.090654 -231.219756)
		(end 139.081764 -231.224836)
		(width 0.088646)
		(layer "In4.Cu")
		(net "M_G_CPU1_SB_DQ<19>")
	)
	(segment
		(start 182.275226 -213.872826)
		(end 181.691026 -213.872826)
		(width 0.18288)
		(layer "In4.Cu")
		(net "M_G_CPU1_SB_DQ<19>")
	)
	(arc
		(start 138.141964 -232.852722)
		(mid 137.937629 -233.055327)
		(end 137.859516 -233.332274)
		(width 0.088646)
		(layer "In4.Cu")
		(net "M_G_CPU1_SB_DQ<19>")
	)
	(arc
		(start 139.739116 -230.086662)
		(mid 139.688952 -230.2738)
		(end 139.551918 -230.410766)
		(width 0.088646)
		(layer "In4.Cu")
		(net "M_G_CPU1_SB_DQ<19>")
	)
	(arc
		(start 135.417814 -233.666792)
		(mid 135.139491 -233.591033)
		(end 134.86003 -233.662474)
		(width 0.088646)
		(layer "In4.Cu")
		(net "M_G_CPU1_SB_DQ<19>")
	)
	(arc
		(start 136.357868 -233.666538)
		(mid 136.075166 -233.590796)
		(end 135.792464 -233.666538)
		(width 0.088646)
		(layer "In4.Cu")
		(net "M_G_CPU1_SB_DQ<19>")
	)
	(arc
		(start 137.859516 -233.34218)
		(mid 137.811837 -233.52508)
		(end 137.680954 -233.661458)
		(width 0.088646)
		(layer "In4.Cu")
		(net "M_G_CPU1_SB_DQ<19>")
	)
	(arc
		(start 132.968492 -233.669332)
		(mid 132.783107 -233.71697)
		(end 132.598414 -233.666792)
		(width 0.088646)
		(layer "In4.Cu")
		(net "M_G_CPU1_SB_DQ<19>")
	)
	(arc
		(start 133.538214 -233.666792)
		(mid 133.259891 -233.591033)
		(end 132.98043 -233.662474)
		(width 0.088646)
		(layer "In4.Cu")
		(net "M_G_CPU1_SB_DQ<19>")
	)
	(arc
		(start 138.329416 -232.528364)
		(mid 138.281737 -232.711264)
		(end 138.150854 -232.847642)
		(width 0.088646)
		(layer "In4.Cu")
		(net "M_G_CPU1_SB_DQ<19>")
	)
	(arc
		(start 138.611864 -232.038906)
		(mid 138.407529 -232.241511)
		(end 138.329416 -232.518458)
		(width 0.088646)
		(layer "In4.Cu")
		(net "M_G_CPU1_SB_DQ<19>")
	)
	(arc
		(start 134.478014 -233.666792)
		(mid 134.195456 -233.591143)
		(end 133.912864 -233.666792)
		(width 0.088646)
		(layer "In4.Cu")
		(net "M_G_CPU1_SB_DQ<19>")
	)
	(arc
		(start 137.672064 -233.666538)
		(mid 137.484866 -233.716681)
		(end 137.297668 -233.666538)
		(width 0.088646)
		(layer "In4.Cu")
		(net "M_G_CPU1_SB_DQ<19>")
	)
	(arc
		(start 139.269216 -230.900478)
		(mid 139.221537 -231.083378)
		(end 139.090654 -231.219756)
		(width 0.088646)
		(layer "In4.Cu")
		(net "M_G_CPU1_SB_DQ<19>")
	)
	(arc
		(start 135.789924 -233.668316)
		(mid 135.603675 -233.716961)
		(end 135.417814 -233.666792)
		(width 0.088646)
		(layer "In4.Cu")
		(net "M_G_CPU1_SB_DQ<19>")
	)
	(arc
		(start 139.551664 -230.41102)
		(mid 139.347329 -230.613625)
		(end 139.269216 -230.890572)
		(width 0.088646)
		(layer "In4.Cu")
		(net "M_G_CPU1_SB_DQ<19>")
	)
	(arc
		(start 139.081764 -231.224836)
		(mid 138.879478 -231.423817)
		(end 138.799316 -231.696006)
		(width 0.088646)
		(layer "In4.Cu")
		(net "M_G_CPU1_SB_DQ<19>")
	)
	(arc
		(start 132.201666 -233.43743)
		(mid 132.030138 -233.366384)
		(end 131.846066 -233.34218)
		(width 0.088646)
		(layer "In4.Cu")
		(net "M_G_CPU1_SB_DQ<19>")
	)
	(arc
		(start 136.732264 -233.666538)
		(mid 136.545066 -233.716681)
		(end 136.357868 -233.666538)
		(width 0.088646)
		(layer "In4.Cu")
		(net "M_G_CPU1_SB_DQ<19>")
	)
	(arc
		(start 138.799316 -231.714548)
		(mid 138.751637 -231.897448)
		(end 138.620754 -232.033826)
		(width 0.088646)
		(layer "In4.Cu")
		(net "M_G_CPU1_SB_DQ<19>")
	)
	(arc
		(start 137.297668 -233.666538)
		(mid 137.014966 -233.590796)
		(end 136.732264 -233.666538)
		(width 0.088646)
		(layer "In4.Cu")
		(net "M_G_CPU1_SB_DQ<19>")
	)
	(arc
		(start 134.848854 -233.668824)
		(mid 134.663164 -233.716902)
		(end 134.478014 -233.666792)
		(width 0.088646)
		(layer "In4.Cu")
		(net "M_G_CPU1_SB_DQ<19>")
	)
	(arc
		(start 133.910324 -233.668316)
		(mid 133.724075 -233.716961)
		(end 133.538214 -233.666792)
		(width 0.088646)
		(layer "In4.Cu")
		(net "M_G_CPU1_SB_DQ<19>")
	)
	(segment
		(start 198.427848 -212.849968)
		(end 198.427848 -212.599016)
		(width 0.20066)
		(layer "F.Cu")
		(net "M_G_CPU1_SB_DQ<18>")
	)
	(segment
		(start 197.530466 -213.041738)
		(end 197.542658 -213.05393)
		(width 0.1016)
		(layer "F.Cu")
		(net "M_G_CPU1_SB_DQ<18>")
	)
	(segment
		(start 198.662036 -212.364828)
		(end 199.046084 -212.364828)
		(width 0.20066)
		(layer "F.Cu")
		(net "M_G_CPU1_SB_DQ<18>")
	)
	(segment
		(start 131.376166 -234.691936)
		(end 131.376166 -234.15625)
		(width 0.20066)
		(layer "F.Cu")
		(net "M_G_CPU1_SB_DQ<18>")
	)
	(segment
		(start 195.522596 -213.041738)
		(end 197.530466 -213.041738)
		(width 0.1016)
		(layer "F.Cu")
		(net "M_G_CPU1_SB_DQ<18>")
	)
	(segment
		(start 198.223886 -213.05393)
		(end 198.427848 -212.849968)
		(width 0.20066)
		(layer "F.Cu")
		(net "M_G_CPU1_SB_DQ<18>")
	)
	(segment
		(start 199.046084 -212.364828)
		(end 199.298052 -212.616796)
		(width 0.20066)
		(layer "F.Cu")
		(net "M_G_CPU1_SB_DQ<18>")
	)
	(segment
		(start 195.218812 -213.04885)
		(end 195.510658 -213.04885)
		(width 0.20066)
		(layer "F.Cu")
		(net "M_G_CPU1_SB_DQ<18>")
	)
	(segment
		(start 195.515484 -213.04885)
		(end 195.522596 -213.041738)
		(width 0.1016)
		(layer "F.Cu")
		(net "M_G_CPU1_SB_DQ<18>")
	)
	(segment
		(start 191.983614 -212.616796)
		(end 193.088514 -212.616796)
		(width 0.20066)
		(layer "F.Cu")
		(net "M_G_CPU1_SB_DQ<18>")
	)
	(segment
		(start 194.786758 -212.616796)
		(end 195.218812 -213.04885)
		(width 0.20066)
		(layer "F.Cu")
		(net "M_G_CPU1_SB_DQ<18>")
	)
	(segment
		(start 199.298052 -212.616796)
		(end 200.632314 -212.616796)
		(width 0.20066)
		(layer "F.Cu")
		(net "M_G_CPU1_SB_DQ<18>")
	)
	(segment
		(start 131.375912 -234.69219)
		(end 131.376166 -234.691936)
		(width 0.20066)
		(layer "F.Cu")
		(net "M_G_CPU1_SB_DQ<18>")
	)
	(segment
		(start 198.427848 -212.599016)
		(end 198.662036 -212.364828)
		(width 0.20066)
		(layer "F.Cu")
		(net "M_G_CPU1_SB_DQ<18>")
	)
	(segment
		(start 197.542658 -213.05393)
		(end 198.223886 -213.05393)
		(width 0.20066)
		(layer "F.Cu")
		(net "M_G_CPU1_SB_DQ<18>")
	)
	(segment
		(start 193.088514 -212.616796)
		(end 194.786758 -212.616796)
		(width 0.20066)
		(layer "F.Cu")
		(net "M_G_CPU1_SB_DQ<18>")
	)
	(segment
		(start 195.510658 -213.04885)
		(end 195.515484 -213.04885)
		(width 0.101854)
		(layer "F.Cu")
		(net "M_G_CPU1_SB_DQ<18>")
	)
	(segment
		(start 139.739116 -231.62514)
		(end 139.739116 -231.714548)
		(width 0.088646)
		(layer "In4.Cu")
		(net "M_G_CPU1_SB_DQ<18>")
	)
	(segment
		(start 180.040026 -217.124026)
		(end 179.709826 -217.454226)
		(width 0.18288)
		(layer "In4.Cu")
		(net "M_G_CPU1_SB_DQ<18>")
	)
	(segment
		(start 178.637692 -217.454226)
		(end 177.627026 -216.44356)
		(width 0.18288)
		(layer "In4.Cu")
		(net "M_G_CPU1_SB_DQ<18>")
	)
	(segment
		(start 158.490158 -217.230706)
		(end 158.307278 -217.047826)
		(width 0.18288)
		(layer "In4.Cu")
		(net "M_G_CPU1_SB_DQ<18>")
	)
	(segment
		(start 140.301726 -231.06253)
		(end 139.739116 -231.62514)
		(width 0.088646)
		(layer "In4.Cu")
		(net "M_G_CPU1_SB_DQ<18>")
	)
	(segment
		(start 158.673038 -217.688414)
		(end 158.490158 -217.505534)
		(width 0.18288)
		(layer "In4.Cu")
		(net "M_G_CPU1_SB_DQ<18>")
	)
	(segment
		(start 189.400434 -213.04377)
		(end 187.464954 -213.04377)
		(width 0.18288)
		(layer "In4.Cu")
		(net "M_G_CPU1_SB_DQ<18>")
	)
	(segment
		(start 179.709826 -217.454226)
		(end 178.637692 -217.454226)
		(width 0.18288)
		(layer "In4.Cu")
		(net "M_G_CPU1_SB_DQ<18>")
	)
	(segment
		(start 131.188968 -234.480608)
		(end 131.180078 -234.475528)
		(width 0.088646)
		(layer "In4.Cu")
		(net "M_G_CPU1_SB_DQ<18>")
	)
	(segment
		(start 174.92726 -216.659714)
		(end 174.711106 -216.44356)
		(width 0.18288)
		(layer "In4.Cu")
		(net "M_G_CPU1_SB_DQ<18>")
	)
	(segment
		(start 176.024032 -216.44102)
		(end 175.805338 -216.659714)
		(width 0.18288)
		(layer "In4.Cu")
		(net "M_G_CPU1_SB_DQ<18>")
	)
	(segment
		(start 184.891426 -213.771226)
		(end 183.138826 -215.523826)
		(width 0.18288)
		(layer "In4.Cu")
		(net "M_G_CPU1_SB_DQ<18>")
	)
	(segment
		(start 171.560744 -216.44356)
		(end 171.34332 -216.660984)
		(width 0.18288)
		(layer "In4.Cu")
		(net "M_G_CPU1_SB_DQ<18>")
	)
	(segment
		(start 176.771046 -216.44356)
		(end 176.771046 -216.44102)
		(width 0.18288)
		(layer "In4.Cu")
		(net "M_G_CPU1_SB_DQ<18>")
	)
	(segment
		(start 159.000698 -217.688414)
		(end 158.673038 -217.688414)
		(width 0.18288)
		(layer "In4.Cu")
		(net "M_G_CPU1_SB_DQ<18>")
	)
	(segment
		(start 186.847226 -213.949026)
		(end 186.415426 -213.949026)
		(width 0.18288)
		(layer "In4.Cu")
		(net "M_G_CPU1_SB_DQ<18>")
	)
	(segment
		(start 187.253626 -213.255098)
		(end 187.253626 -213.542626)
		(width 0.18288)
		(layer "In4.Cu")
		(net "M_G_CPU1_SB_DQ<18>")
	)
	(segment
		(start 139.090654 -232.847642)
		(end 139.081764 -232.852722)
		(width 0.088646)
		(layer "In4.Cu")
		(net "M_G_CPU1_SB_DQ<18>")
	)
	(segment
		(start 138.329416 -234.137708)
		(end 138.329416 -234.15625)
		(width 0.088646)
		(layer "In4.Cu")
		(net "M_G_CPU1_SB_DQ<18>")
	)
	(segment
		(start 138.799316 -233.332274)
		(end 138.799316 -233.34218)
		(width 0.088646)
		(layer "In4.Cu")
		(net "M_G_CPU1_SB_DQ<18>")
	)
	(segment
		(start 164.935916 -216.650316)
		(end 164.673026 -216.387426)
		(width 0.18288)
		(layer "In4.Cu")
		(net "M_G_CPU1_SB_DQ<18>")
	)
	(segment
		(start 180.725826 -217.124026)
		(end 180.040026 -217.124026)
		(width 0.18288)
		(layer "In4.Cu")
		(net "M_G_CPU1_SB_DQ<18>")
	)
	(segment
		(start 131.006088 -234.213654)
		(end 131.063492 -234.15625)
		(width 0.088646)
		(layer "In4.Cu")
		(net "M_G_CPU1_SB_DQ<18>")
	)
	(segment
		(start 186.237626 -213.771226)
		(end 184.891426 -213.771226)
		(width 0.18288)
		(layer "In4.Cu")
		(net "M_G_CPU1_SB_DQ<18>")
	)
	(segment
		(start 139.269216 -232.518458)
		(end 139.269216 -232.528364)
		(width 0.088646)
		(layer "In4.Cu")
		(net "M_G_CPU1_SB_DQ<18>")
	)
	(segment
		(start 138.150854 -234.475528)
		(end 138.141964 -234.480608)
		(width 0.088646)
		(layer "In4.Cu")
		(net "M_G_CPU1_SB_DQ<18>")
	)
	(segment
		(start 168.940226 -216.362026)
		(end 168.651936 -216.650316)
		(width 0.18288)
		(layer "In4.Cu")
		(net "M_G_CPU1_SB_DQ<18>")
	)
	(segment
		(start 170.522646 -216.660984)
		(end 170.223688 -216.362026)
		(width 0.18288)
		(layer "In4.Cu")
		(net "M_G_CPU1_SB_DQ<18>")
	)
	(segment
		(start 159.183578 -217.505534)
		(end 159.000698 -217.688414)
		(width 0.18288)
		(layer "In4.Cu")
		(net "M_G_CPU1_SB_DQ<18>")
	)
	(segment
		(start 191.362584 -213.237826)
		(end 189.59449 -213.237826)
		(width 0.18288)
		(layer "In4.Cu")
		(net "M_G_CPU1_SB_DQ<18>")
	)
	(segment
		(start 136.277096 -234.471972)
		(end 136.262364 -234.480608)
		(width 0.088646)
		(layer "In4.Cu")
		(net "M_G_CPU1_SB_DQ<18>")
	)
	(segment
		(start 132.517896 -234.471972)
		(end 132.503164 -234.480608)
		(width 0.088646)
		(layer "In4.Cu")
		(net "M_G_CPU1_SB_DQ<18>")
	)
	(segment
		(start 177.627026 -216.44356)
		(end 176.771046 -216.44356)
		(width 0.18288)
		(layer "In4.Cu")
		(net "M_G_CPU1_SB_DQ<18>")
	)
	(segment
		(start 183.138826 -215.523826)
		(end 182.326026 -215.523826)
		(width 0.18288)
		(layer "In4.Cu")
		(net "M_G_CPU1_SB_DQ<18>")
	)
	(segment
		(start 187.464954 -213.04377)
		(end 187.253626 -213.255098)
		(width 0.18288)
		(layer "In4.Cu")
		(net "M_G_CPU1_SB_DQ<18>")
	)
	(segment
		(start 189.59449 -213.237826)
		(end 189.400434 -213.04377)
		(width 0.18288)
		(layer "In4.Cu")
		(net "M_G_CPU1_SB_DQ<18>")
	)
	(segment
		(start 142.357602 -229.294944)
		(end 140.60297 -231.049576)
		(width 0.18288)
		(layer "In4.Cu")
		(net "M_G_CPU1_SB_DQ<18>")
	)
	(segment
		(start 140.31468 -231.049576)
		(end 140.301726 -231.06253)
		(width 0.18288)
		(layer "In4.Cu")
		(net "M_G_CPU1_SB_DQ<18>")
	)
	(segment
		(start 174.711106 -216.44356)
		(end 171.560744 -216.44356)
		(width 0.18288)
		(layer "In4.Cu")
		(net "M_G_CPU1_SB_DQ<18>")
	)
	(segment
		(start 182.326026 -215.523826)
		(end 180.725826 -217.124026)
		(width 0.18288)
		(layer "In4.Cu")
		(net "M_G_CPU1_SB_DQ<18>")
	)
	(segment
		(start 191.983614 -212.616796)
		(end 191.362584 -213.237826)
		(width 0.18288)
		(layer "In4.Cu")
		(net "M_G_CPU1_SB_DQ<18>")
	)
	(segment
		(start 187.253626 -213.542626)
		(end 186.847226 -213.949026)
		(width 0.18288)
		(layer "In4.Cu")
		(net "M_G_CPU1_SB_DQ<18>")
	)
	(segment
		(start 161.009838 -216.387426)
		(end 160.349438 -217.047826)
		(width 0.18288)
		(layer "In4.Cu")
		(net "M_G_CPU1_SB_DQ<18>")
	)
	(segment
		(start 131.063492 -234.15625)
		(end 131.376166 -234.15625)
		(width 0.088646)
		(layer "In4.Cu")
		(net "M_G_CPU1_SB_DQ<18>")
	)
	(segment
		(start 159.183578 -217.230706)
		(end 159.183578 -217.505534)
		(width 0.18288)
		(layer "In4.Cu")
		(net "M_G_CPU1_SB_DQ<18>")
	)
	(segment
		(start 168.651936 -216.650316)
		(end 164.935916 -216.650316)
		(width 0.18288)
		(layer "In4.Cu")
		(net "M_G_CPU1_SB_DQ<18>")
	)
	(segment
		(start 158.490158 -217.505534)
		(end 158.490158 -217.230706)
		(width 0.18288)
		(layer "In4.Cu")
		(net "M_G_CPU1_SB_DQ<18>")
	)
	(segment
		(start 138.620754 -233.661458)
		(end 138.611864 -233.666538)
		(width 0.088646)
		(layer "In4.Cu")
		(net "M_G_CPU1_SB_DQ<18>")
	)
	(segment
		(start 157.566868 -217.047826)
		(end 145.31975 -229.294944)
		(width 0.18288)
		(layer "In4.Cu")
		(net "M_G_CPU1_SB_DQ<18>")
	)
	(segment
		(start 158.307278 -217.047826)
		(end 157.566868 -217.047826)
		(width 0.18288)
		(layer "In4.Cu")
		(net "M_G_CPU1_SB_DQ<18>")
	)
	(segment
		(start 175.805338 -216.659714)
		(end 174.92726 -216.659714)
		(width 0.18288)
		(layer "In4.Cu")
		(net "M_G_CPU1_SB_DQ<18>")
	)
	(segment
		(start 160.349438 -217.047826)
		(end 159.366458 -217.047826)
		(width 0.18288)
		(layer "In4.Cu")
		(net "M_G_CPU1_SB_DQ<18>")
	)
	(segment
		(start 171.34332 -216.660984)
		(end 170.522646 -216.660984)
		(width 0.18288)
		(layer "In4.Cu")
		(net "M_G_CPU1_SB_DQ<18>")
	)
	(segment
		(start 145.31975 -229.294944)
		(end 142.357602 -229.294944)
		(width 0.18288)
		(layer "In4.Cu")
		(net "M_G_CPU1_SB_DQ<18>")
	)
	(segment
		(start 186.415426 -213.949026)
		(end 186.237626 -213.771226)
		(width 0.18288)
		(layer "In4.Cu")
		(net "M_G_CPU1_SB_DQ<18>")
	)
	(segment
		(start 137.216896 -234.471972)
		(end 137.202164 -234.480608)
		(width 0.088646)
		(layer "In4.Cu")
		(net "M_G_CPU1_SB_DQ<18>")
	)
	(segment
		(start 140.60297 -231.049576)
		(end 140.31468 -231.049576)
		(width 0.18288)
		(layer "In4.Cu")
		(net "M_G_CPU1_SB_DQ<18>")
	)
	(segment
		(start 176.771046 -216.44102)
		(end 176.024032 -216.44102)
		(width 0.18288)
		(layer "In4.Cu")
		(net "M_G_CPU1_SB_DQ<18>")
	)
	(segment
		(start 159.366458 -217.047826)
		(end 159.183578 -217.230706)
		(width 0.18288)
		(layer "In4.Cu")
		(net "M_G_CPU1_SB_DQ<18>")
	)
	(segment
		(start 139.560554 -232.033826)
		(end 139.551664 -232.038906)
		(width 0.088646)
		(layer "In4.Cu")
		(net "M_G_CPU1_SB_DQ<18>")
	)
	(segment
		(start 170.223688 -216.362026)
		(end 168.940226 -216.362026)
		(width 0.18288)
		(layer "In4.Cu")
		(net "M_G_CPU1_SB_DQ<18>")
	)
	(segment
		(start 164.673026 -216.387426)
		(end 161.009838 -216.387426)
		(width 0.18288)
		(layer "In4.Cu")
		(net "M_G_CPU1_SB_DQ<18>")
	)
	(arc
		(start 139.269216 -232.528364)
		(mid 139.221537 -232.711264)
		(end 139.090654 -232.847642)
		(width 0.088646)
		(layer "In4.Cu")
		(net "M_G_CPU1_SB_DQ<18>")
	)
	(arc
		(start 131.563364 -234.480608)
		(mid 131.376166 -234.530751)
		(end 131.188968 -234.480608)
		(width 0.088646)
		(layer "In4.Cu")
		(net "M_G_CPU1_SB_DQ<18>")
	)
	(arc
		(start 139.739116 -231.714548)
		(mid 139.691437 -231.897448)
		(end 139.560554 -232.033826)
		(width 0.088646)
		(layer "In4.Cu")
		(net "M_G_CPU1_SB_DQ<18>")
	)
	(arc
		(start 134.382764 -234.480608)
		(mid 134.195566 -234.530751)
		(end 134.008368 -234.480608)
		(width 0.088646)
		(layer "In4.Cu")
		(net "M_G_CPU1_SB_DQ<18>")
	)
	(arc
		(start 139.081764 -232.852722)
		(mid 138.877429 -233.055327)
		(end 138.799316 -233.332274)
		(width 0.088646)
		(layer "In4.Cu")
		(net "M_G_CPU1_SB_DQ<18>")
	)
	(arc
		(start 138.329416 -234.15625)
		(mid 138.281737 -234.33915)
		(end 138.150854 -234.475528)
		(width 0.088646)
		(layer "In4.Cu")
		(net "M_G_CPU1_SB_DQ<18>")
	)
	(arc
		(start 137.767568 -234.480608)
		(mid 137.493369 -234.404773)
		(end 137.216896 -234.471972)
		(width 0.088646)
		(layer "In4.Cu")
		(net "M_G_CPU1_SB_DQ<18>")
	)
	(arc
		(start 137.202164 -234.480608)
		(mid 137.014966 -234.530751)
		(end 136.827768 -234.480608)
		(width 0.088646)
		(layer "In4.Cu")
		(net "M_G_CPU1_SB_DQ<18>")
	)
	(arc
		(start 138.141964 -234.480608)
		(mid 137.954766 -234.530751)
		(end 137.767568 -234.480608)
		(width 0.088646)
		(layer "In4.Cu")
		(net "M_G_CPU1_SB_DQ<18>")
	)
	(arc
		(start 132.503164 -234.480608)
		(mid 132.315966 -234.530751)
		(end 132.128768 -234.480608)
		(width 0.088646)
		(layer "In4.Cu")
		(net "M_G_CPU1_SB_DQ<18>")
	)
	(arc
		(start 134.008368 -234.480608)
		(mid 133.725666 -234.404832)
		(end 133.442964 -234.480608)
		(width 0.088646)
		(layer "In4.Cu")
		(net "M_G_CPU1_SB_DQ<18>")
	)
	(arc
		(start 136.262364 -234.480608)
		(mid 136.075166 -234.530751)
		(end 135.887968 -234.480608)
		(width 0.088646)
		(layer "In4.Cu")
		(net "M_G_CPU1_SB_DQ<18>")
	)
	(arc
		(start 132.128768 -234.480608)
		(mid 131.846066 -234.404832)
		(end 131.563364 -234.480608)
		(width 0.088646)
		(layer "In4.Cu")
		(net "M_G_CPU1_SB_DQ<18>")
	)
	(arc
		(start 135.887968 -234.480608)
		(mid 135.605266 -234.404832)
		(end 135.322564 -234.480608)
		(width 0.088646)
		(layer "In4.Cu")
		(net "M_G_CPU1_SB_DQ<18>")
	)
	(arc
		(start 131.180078 -234.475528)
		(mid 131.064339 -234.363704)
		(end 131.006088 -234.213654)
		(width 0.088646)
		(layer "In4.Cu")
		(net "M_G_CPU1_SB_DQ<18>")
	)
	(arc
		(start 136.827768 -234.480608)
		(mid 136.553569 -234.404773)
		(end 136.277096 -234.471972)
		(width 0.088646)
		(layer "In4.Cu")
		(net "M_G_CPU1_SB_DQ<18>")
	)
	(arc
		(start 138.611864 -233.666538)
		(mid 138.409578 -233.865519)
		(end 138.329416 -234.137708)
		(width 0.088646)
		(layer "In4.Cu")
		(net "M_G_CPU1_SB_DQ<18>")
	)
	(arc
		(start 134.948168 -234.480608)
		(mid 134.665466 -234.404832)
		(end 134.382764 -234.480608)
		(width 0.088646)
		(layer "In4.Cu")
		(net "M_G_CPU1_SB_DQ<18>")
	)
	(arc
		(start 139.551664 -232.038906)
		(mid 139.347329 -232.241511)
		(end 139.269216 -232.518458)
		(width 0.088646)
		(layer "In4.Cu")
		(net "M_G_CPU1_SB_DQ<18>")
	)
	(arc
		(start 135.322564 -234.480608)
		(mid 135.135366 -234.530751)
		(end 134.948168 -234.480608)
		(width 0.088646)
		(layer "In4.Cu")
		(net "M_G_CPU1_SB_DQ<18>")
	)
	(arc
		(start 133.068568 -234.480608)
		(mid 132.794369 -234.404773)
		(end 132.517896 -234.471972)
		(width 0.088646)
		(layer "In4.Cu")
		(net "M_G_CPU1_SB_DQ<18>")
	)
	(arc
		(start 133.442964 -234.480608)
		(mid 133.255766 -234.530751)
		(end 133.068568 -234.480608)
		(width 0.088646)
		(layer "In4.Cu")
		(net "M_G_CPU1_SB_DQ<18>")
	)
	(arc
		(start 138.799316 -233.34218)
		(mid 138.751637 -233.52508)
		(end 138.620754 -233.661458)
		(width 0.088646)
		(layer "In4.Cu")
		(net "M_G_CPU1_SB_DQ<18>")
	)
	(segment
		(start 191.903858 -211.341716)
		(end 191.883792 -211.341716)
		(width 0.101854)
		(layer "F.Cu")
		(net "M_G_CPU1_SB_DQ<17>")
	)
	(segment
		(start 190.75781 -212.015324)
		(end 190.509144 -211.766658)
		(width 0.20066)
		(layer "F.Cu")
		(net "M_G_CPU1_SB_DQ<17>")
	)
	(segment
		(start 191.539114 -211.341716)
		(end 191.421004 -211.459826)
		(width 0.20066)
		(layer "F.Cu")
		(net "M_G_CPU1_SB_DQ<17>")
	)
	(segment
		(start 190.509144 -211.766658)
		(end 188.988446 -211.766658)
		(width 0.20066)
		(layer "F.Cu")
		(net "M_G_CPU1_SB_DQ<17>")
	)
	(segment
		(start 194.098926 -211.335366)
		(end 194.092576 -211.341716)
		(width 0.1016)
		(layer "F.Cu")
		(net "M_G_CPU1_SB_DQ<17>")
	)
	(segment
		(start 196.532246 -211.766658)
		(end 196.531992 -211.766912)
		(width 0.20066)
		(layer "F.Cu")
		(net "M_G_CPU1_SB_DQ<17>")
	)
	(segment
		(start 194.508882 -211.335366)
		(end 194.098926 -211.335366)
		(width 0.20066)
		(layer "F.Cu")
		(net "M_G_CPU1_SB_DQ<17>")
	)
	(segment
		(start 191.233044 -212.015324)
		(end 190.75781 -212.015324)
		(width 0.20066)
		(layer "F.Cu")
		(net "M_G_CPU1_SB_DQ<17>")
	)
	(segment
		(start 194.092576 -211.341716)
		(end 191.903858 -211.341716)
		(width 0.1016)
		(layer "F.Cu")
		(net "M_G_CPU1_SB_DQ<17>")
	)
	(segment
		(start 129.966212 -233.877866)
		(end 129.966212 -233.34218)
		(width 0.20066)
		(layer "F.Cu")
		(net "M_G_CPU1_SB_DQ<17>")
	)
	(segment
		(start 194.940428 -211.766912)
		(end 194.508882 -211.335366)
		(width 0.20066)
		(layer "F.Cu")
		(net "M_G_CPU1_SB_DQ<17>")
	)
	(segment
		(start 191.421004 -211.459826)
		(end 191.421004 -211.827364)
		(width 0.20066)
		(layer "F.Cu")
		(net "M_G_CPU1_SB_DQ<17>")
	)
	(segment
		(start 191.421004 -211.827364)
		(end 191.233044 -212.015324)
		(width 0.20066)
		(layer "F.Cu")
		(net "M_G_CPU1_SB_DQ<17>")
	)
	(segment
		(start 191.883792 -211.341716)
		(end 191.539114 -211.341716)
		(width 0.20066)
		(layer "F.Cu")
		(net "M_G_CPU1_SB_DQ<17>")
	)
	(segment
		(start 188.988446 -211.766658)
		(end 187.883546 -211.766658)
		(width 0.20066)
		(layer "F.Cu")
		(net "M_G_CPU1_SB_DQ<17>")
	)
	(segment
		(start 129.966466 -233.87812)
		(end 129.966212 -233.877866)
		(width 0.20066)
		(layer "F.Cu")
		(net "M_G_CPU1_SB_DQ<17>")
	)
	(segment
		(start 196.531992 -211.766912)
		(end 194.940428 -211.766912)
		(width 0.20066)
		(layer "F.Cu")
		(net "M_G_CPU1_SB_DQ<17>")
	)
	(segment
		(start 131.193286 -233.829098)
		(end 131.188714 -233.831638)
		(width 0.088646)
		(layer "In4.Cu")
		(net "M_G_CPU1_SB_DQ<17>")
	)
	(segment
		(start 158.109666 -215.549226)
		(end 157.926786 -215.732106)
		(width 0.18288)
		(layer "In4.Cu")
		(net "M_G_CPU1_SB_DQ<17>")
	)
	(segment
		(start 170.644058 -214.710264)
		(end 170.224958 -214.710264)
		(width 0.18288)
		(layer "In4.Cu")
		(net "M_G_CPU1_SB_DQ<17>")
	)
	(segment
		(start 174.394876 -215.885522)
		(end 173.576488 -215.885522)
		(width 0.18288)
		(layer "In4.Cu")
		(net "M_G_CPU1_SB_DQ<17>")
	)
	(segment
		(start 161.260028 -215.549226)
		(end 159.735774 -215.549226)
		(width 0.18288)
		(layer "In4.Cu")
		(net "M_G_CPU1_SB_DQ<17>")
	)
	(segment
		(start 176.401222 -215.593422)
		(end 176.120806 -215.313006)
		(width 0.18288)
		(layer "In4.Cu")
		(net "M_G_CPU1_SB_DQ<17>")
	)
	(segment
		(start 187.32754 -211.766658)
		(end 187.050426 -212.043772)
		(width 0.18288)
		(layer "In4.Cu")
		(net "M_G_CPU1_SB_DQ<17>")
	)
	(segment
		(start 158.859474 -215.732106)
		(end 158.676594 -215.549226)
		(width 0.18288)
		(layer "In4.Cu")
		(net "M_G_CPU1_SB_DQ<17>")
	)
	(segment
		(start 138.519916 -232.528364)
		(end 138.519916 -232.53827)
		(width 0.088646)
		(layer "In4.Cu")
		(net "M_G_CPU1_SB_DQ<17>")
	)
	(segment
		(start 187.883546 -211.766658)
		(end 187.32754 -211.766658)
		(width 0.18288)
		(layer "In4.Cu")
		(net "M_G_CPU1_SB_DQ<17>")
	)
	(segment
		(start 130.623564 -233.831638)
		(end 130.550158 -233.789474)
		(width 0.088646)
		(layer "In4.Cu")
		(net "M_G_CPU1_SB_DQ<17>")
	)
	(segment
		(start 182.85968 -214.964772)
		(end 181.589426 -214.964772)
		(width 0.18288)
		(layer "In4.Cu")
		(net "M_G_CPU1_SB_DQ<17>")
	)
	(segment
		(start 166.086536 -215.523826)
		(end 165.842696 -215.279986)
		(width 0.18288)
		(layer "In4.Cu")
		(net "M_G_CPU1_SB_DQ<17>")
	)
	(segment
		(start 187.050426 -212.043772)
		(end 187.050426 -212.614256)
		(width 0.18288)
		(layer "In4.Cu")
		(net "M_G_CPU1_SB_DQ<17>")
	)
	(segment
		(start 157.40634 -216.504266)
		(end 145.113502 -228.797104)
		(width 0.18288)
		(layer "In4.Cu")
		(net "M_G_CPU1_SB_DQ<17>")
	)
	(segment
		(start 183.977026 -212.983826)
		(end 183.621426 -213.339426)
		(width 0.18288)
		(layer "In4.Cu")
		(net "M_G_CPU1_SB_DQ<17>")
	)
	(segment
		(start 161.535872 -215.82507)
		(end 161.260028 -215.549226)
		(width 0.18288)
		(layer "In4.Cu")
		(net "M_G_CPU1_SB_DQ<17>")
	)
	(segment
		(start 139.459716 -230.900478)
		(end 139.459716 -230.91902)
		(width 0.088646)
		(layer "In4.Cu")
		(net "M_G_CPU1_SB_DQ<17>")
	)
	(segment
		(start 180.967126 -216.08161)
		(end 180.45811 -216.590626)
		(width 0.18288)
		(layer "In4.Cu")
		(net "M_G_CPU1_SB_DQ<17>")
	)
	(segment
		(start 170.81881 -214.885016)
		(end 170.644058 -214.710264)
		(width 0.18288)
		(layer "In4.Cu")
		(net "M_G_CPU1_SB_DQ<17>")
	)
	(segment
		(start 157.766766 -216.504266)
		(end 157.40634 -216.504266)
		(width 0.18288)
		(layer "In4.Cu")
		(net "M_G_CPU1_SB_DQ<17>")
	)
	(segment
		(start 133.068314 -233.831638)
		(end 133.060948 -233.835956)
		(width 0.088646)
		(layer "In4.Cu")
		(net "M_G_CPU1_SB_DQ<17>")
	)
	(segment
		(start 183.621426 -213.339426)
		(end 183.621426 -214.203026)
		(width 0.18288)
		(layer "In4.Cu")
		(net "M_G_CPU1_SB_DQ<17>")
	)
	(segment
		(start 132.133086 -233.829098)
		(end 132.128514 -233.831638)
		(width 0.088646)
		(layer "In4.Cu")
		(net "M_G_CPU1_SB_DQ<17>")
	)
	(segment
		(start 135.887968 -233.831892)
		(end 135.882126 -233.83494)
		(width 0.088646)
		(layer "In4.Cu")
		(net "M_G_CPU1_SB_DQ<17>")
	)
	(segment
		(start 170.064938 -215.386412)
		(end 169.775124 -215.676226)
		(width 0.18288)
		(layer "In4.Cu")
		(net "M_G_CPU1_SB_DQ<17>")
	)
	(segment
		(start 142.151354 -228.797104)
		(end 140.66774 -230.280718)
		(width 0.18288)
		(layer "In4.Cu")
		(net "M_G_CPU1_SB_DQ<17>")
	)
	(segment
		(start 159.042354 -216.381076)
		(end 158.859474 -216.198196)
		(width 0.18288)
		(layer "In4.Cu")
		(net "M_G_CPU1_SB_DQ<17>")
	)
	(segment
		(start 187.050426 -212.614256)
		(end 186.680856 -212.983826)
		(width 0.18288)
		(layer "In4.Cu")
		(net "M_G_CPU1_SB_DQ<17>")
	)
	(segment
		(start 170.224958 -214.710264)
		(end 170.064938 -214.870284)
		(width 0.18288)
		(layer "In4.Cu")
		(net "M_G_CPU1_SB_DQ<17>")
	)
	(segment
		(start 134.952486 -233.829098)
		(end 134.947914 -233.831638)
		(width 0.088646)
		(layer "In4.Cu")
		(net "M_G_CPU1_SB_DQ<17>")
	)
	(segment
		(start 171.095416 -215.593422)
		(end 170.81881 -215.316816)
		(width 0.18288)
		(layer "In4.Cu")
		(net "M_G_CPU1_SB_DQ<17>")
	)
	(segment
		(start 170.064938 -214.870284)
		(end 170.064938 -215.386412)
		(width 0.18288)
		(layer "In4.Cu")
		(net "M_G_CPU1_SB_DQ<17>")
	)
	(segment
		(start 138.050016 -233.34218)
		(end 138.050016 -233.352086)
		(width 0.088646)
		(layer "In4.Cu")
		(net "M_G_CPU1_SB_DQ<17>")
	)
	(segment
		(start 179.786026 -216.590626)
		(end 179.481226 -216.285826)
		(width 0.18288)
		(layer "In4.Cu")
		(net "M_G_CPU1_SB_DQ<17>")
	)
	(segment
		(start 131.188714 -233.831638)
		(end 131.181348 -233.835956)
		(width 0.088646)
		(layer "In4.Cu")
		(net "M_G_CPU1_SB_DQ<17>")
	)
	(segment
		(start 159.735774 -215.549226)
		(end 159.552894 -215.732106)
		(width 0.18288)
		(layer "In4.Cu")
		(net "M_G_CPU1_SB_DQ<17>")
	)
	(segment
		(start 173.576488 -215.885522)
		(end 173.284388 -215.593422)
		(width 0.18288)
		(layer "In4.Cu")
		(net "M_G_CPU1_SB_DQ<17>")
	)
	(segment
		(start 170.81881 -215.316816)
		(end 170.81881 -214.885016)
		(width 0.18288)
		(layer "In4.Cu")
		(net "M_G_CPU1_SB_DQ<17>")
	)
	(segment
		(start 164.90823 -215.593422)
		(end 162.478466 -215.593422)
		(width 0.18288)
		(layer "In4.Cu")
		(net "M_G_CPU1_SB_DQ<17>")
	)
	(segment
		(start 159.552894 -216.198196)
		(end 159.370014 -216.381076)
		(width 0.18288)
		(layer "In4.Cu")
		(net "M_G_CPU1_SB_DQ<17>")
	)
	(segment
		(start 165.842696 -215.279986)
		(end 165.221666 -215.279986)
		(width 0.18288)
		(layer "In4.Cu")
		(net "M_G_CPU1_SB_DQ<17>")
	)
	(segment
		(start 138.989816 -231.714548)
		(end 138.989816 -231.724454)
		(width 0.088646)
		(layer "In4.Cu")
		(net "M_G_CPU1_SB_DQ<17>")
	)
	(segment
		(start 140.408914 -230.280718)
		(end 140.040106 -230.280718)
		(width 0.088646)
		(layer "In4.Cu")
		(net "M_G_CPU1_SB_DQ<17>")
	)
	(segment
		(start 157.926786 -216.344246)
		(end 157.766766 -216.504266)
		(width 0.18288)
		(layer "In4.Cu")
		(net "M_G_CPU1_SB_DQ<17>")
	)
	(segment
		(start 178.287426 -216.285826)
		(end 177.595022 -215.593422)
		(width 0.18288)
		(layer "In4.Cu")
		(net "M_G_CPU1_SB_DQ<17>")
	)
	(segment
		(start 137.767568 -233.831638)
		(end 137.767568 -233.831892)
		(width 0.088646)
		(layer "In4.Cu")
		(net "M_G_CPU1_SB_DQ<17>")
	)
	(segment
		(start 140.66774 -230.280718)
		(end 140.408914 -230.280718)
		(width 0.18288)
		(layer "In4.Cu")
		(net "M_G_CPU1_SB_DQ<17>")
	)
	(segment
		(start 157.926786 -215.732106)
		(end 157.926786 -216.344246)
		(width 0.18288)
		(layer "In4.Cu")
		(net "M_G_CPU1_SB_DQ<17>")
	)
	(segment
		(start 139.177268 -231.39019)
		(end 139.168378 -231.39527)
		(width 0.088646)
		(layer "In4.Cu")
		(net "M_G_CPU1_SB_DQ<17>")
	)
	(segment
		(start 158.676594 -215.549226)
		(end 158.109666 -215.549226)
		(width 0.18288)
		(layer "In4.Cu")
		(net "M_G_CPU1_SB_DQ<17>")
	)
	(segment
		(start 183.621426 -214.203026)
		(end 182.85968 -214.964772)
		(width 0.18288)
		(layer "In4.Cu")
		(net "M_G_CPU1_SB_DQ<17>")
	)
	(segment
		(start 159.370014 -216.381076)
		(end 159.042354 -216.381076)
		(width 0.18288)
		(layer "In4.Cu")
		(net "M_G_CPU1_SB_DQ<17>")
	)
	(segment
		(start 159.552894 -215.732106)
		(end 159.552894 -216.198196)
		(width 0.18288)
		(layer "In4.Cu")
		(net "M_G_CPU1_SB_DQ<17>")
	)
	(segment
		(start 180.967126 -215.587072)
		(end 180.967126 -216.08161)
		(width 0.18288)
		(layer "In4.Cu")
		(net "M_G_CPU1_SB_DQ<17>")
	)
	(segment
		(start 186.680856 -212.983826)
		(end 183.977026 -212.983826)
		(width 0.18288)
		(layer "In4.Cu")
		(net "M_G_CPU1_SB_DQ<17>")
	)
	(segment
		(start 169.775124 -215.676226)
		(end 167.924226 -215.676226)
		(width 0.18288)
		(layer "In4.Cu")
		(net "M_G_CPU1_SB_DQ<17>")
	)
	(segment
		(start 138.237468 -233.017822)
		(end 138.228578 -233.022902)
		(width 0.088646)
		(layer "In4.Cu")
		(net "M_G_CPU1_SB_DQ<17>")
	)
	(segment
		(start 134.008114 -233.831638)
		(end 134.002526 -233.83494)
		(width 0.088646)
		(layer "In4.Cu")
		(net "M_G_CPU1_SB_DQ<17>")
	)
	(segment
		(start 176.120806 -215.313006)
		(end 174.967392 -215.313006)
		(width 0.18288)
		(layer "In4.Cu")
		(net "M_G_CPU1_SB_DQ<17>")
	)
	(segment
		(start 181.589426 -214.964772)
		(end 180.967126 -215.587072)
		(width 0.18288)
		(layer "In4.Cu")
		(net "M_G_CPU1_SB_DQ<17>")
	)
	(segment
		(start 165.221666 -215.279986)
		(end 164.90823 -215.593422)
		(width 0.18288)
		(layer "In4.Cu")
		(net "M_G_CPU1_SB_DQ<17>")
	)
	(segment
		(start 180.45811 -216.590626)
		(end 179.786026 -216.590626)
		(width 0.18288)
		(layer "In4.Cu")
		(net "M_G_CPU1_SB_DQ<17>")
	)
	(segment
		(start 167.924226 -215.676226)
		(end 167.771826 -215.523826)
		(width 0.18288)
		(layer "In4.Cu")
		(net "M_G_CPU1_SB_DQ<17>")
	)
	(segment
		(start 134.947914 -233.831638)
		(end 134.943342 -233.834432)
		(width 0.088646)
		(layer "In4.Cu")
		(net "M_G_CPU1_SB_DQ<17>")
	)
	(segment
		(start 173.284388 -215.593422)
		(end 171.095416 -215.593422)
		(width 0.18288)
		(layer "In4.Cu")
		(net "M_G_CPU1_SB_DQ<17>")
	)
	(segment
		(start 162.246818 -215.82507)
		(end 161.535872 -215.82507)
		(width 0.18288)
		(layer "In4.Cu")
		(net "M_G_CPU1_SB_DQ<17>")
	)
	(segment
		(start 177.595022 -215.593422)
		(end 176.401222 -215.593422)
		(width 0.18288)
		(layer "In4.Cu")
		(net "M_G_CPU1_SB_DQ<17>")
	)
	(segment
		(start 140.040106 -230.280718)
		(end 139.99845 -230.322374)
		(width 0.088646)
		(layer "In4.Cu")
		(net "M_G_CPU1_SB_DQ<17>")
	)
	(segment
		(start 174.967392 -215.313006)
		(end 174.394876 -215.885522)
		(width 0.18288)
		(layer "In4.Cu")
		(net "M_G_CPU1_SB_DQ<17>")
	)
	(segment
		(start 167.771826 -215.523826)
		(end 166.086536 -215.523826)
		(width 0.18288)
		(layer "In4.Cu")
		(net "M_G_CPU1_SB_DQ<17>")
	)
	(segment
		(start 138.707368 -232.204006)
		(end 138.698478 -232.209086)
		(width 0.088646)
		(layer "In4.Cu")
		(net "M_G_CPU1_SB_DQ<17>")
	)
	(segment
		(start 162.478466 -215.593422)
		(end 162.246818 -215.82507)
		(width 0.18288)
		(layer "In4.Cu")
		(net "M_G_CPU1_SB_DQ<17>")
	)
	(segment
		(start 158.859474 -216.198196)
		(end 158.859474 -215.732106)
		(width 0.18288)
		(layer "In4.Cu")
		(net "M_G_CPU1_SB_DQ<17>")
	)
	(segment
		(start 145.113502 -228.797104)
		(end 142.151354 -228.797104)
		(width 0.18288)
		(layer "In4.Cu")
		(net "M_G_CPU1_SB_DQ<17>")
	)
	(segment
		(start 132.128514 -233.831638)
		(end 132.121148 -233.835956)
		(width 0.088646)
		(layer "In4.Cu")
		(net "M_G_CPU1_SB_DQ<17>")
	)
	(segment
		(start 133.072886 -233.829098)
		(end 133.068314 -233.831638)
		(width 0.088646)
		(layer "In4.Cu")
		(net "M_G_CPU1_SB_DQ<17>")
	)
	(segment
		(start 179.481226 -216.285826)
		(end 178.287426 -216.285826)
		(width 0.18288)
		(layer "In4.Cu")
		(net "M_G_CPU1_SB_DQ<17>")
	)
	(arc
		(start 139.459716 -230.91902)
		(mid 139.379554 -231.191209)
		(end 139.177268 -231.39019)
		(width 0.088646)
		(layer "In4.Cu")
		(net "M_G_CPU1_SB_DQ<17>")
	)
	(arc
		(start 131.181348 -233.835956)
		(mid 130.901887 -233.907393)
		(end 130.623564 -233.831638)
		(width 0.088646)
		(layer "In4.Cu")
		(net "M_G_CPU1_SB_DQ<17>")
	)
	(arc
		(start 134.002526 -233.83494)
		(mid 133.722311 -233.907381)
		(end 133.442964 -233.831638)
		(width 0.088646)
		(layer "In4.Cu")
		(net "M_G_CPU1_SB_DQ<17>")
	)
	(arc
		(start 137.202164 -233.831892)
		(mid 137.014966 -233.781749)
		(end 136.827768 -233.831892)
		(width 0.088646)
		(layer "In4.Cu")
		(net "M_G_CPU1_SB_DQ<17>")
	)
	(arc
		(start 134.382764 -233.831638)
		(mid 134.195456 -233.781529)
		(end 134.008114 -233.831638)
		(width 0.088646)
		(layer "In4.Cu")
		(net "M_G_CPU1_SB_DQ<17>")
	)
	(arc
		(start 132.503164 -233.831638)
		(mid 132.31847 -233.781537)
		(end 132.133086 -233.829098)
		(width 0.088646)
		(layer "In4.Cu")
		(net "M_G_CPU1_SB_DQ<17>")
	)
	(arc
		(start 137.767568 -233.831892)
		(mid 137.484866 -233.907634)
		(end 137.202164 -233.831892)
		(width 0.088646)
		(layer "In4.Cu")
		(net "M_G_CPU1_SB_DQ<17>")
	)
	(arc
		(start 138.050016 -233.352086)
		(mid 137.971905 -233.629035)
		(end 137.767568 -233.831638)
		(width 0.088646)
		(layer "In4.Cu")
		(net "M_G_CPU1_SB_DQ<17>")
	)
	(arc
		(start 136.262364 -233.831892)
		(mid 136.075166 -233.781749)
		(end 135.887968 -233.831892)
		(width 0.088646)
		(layer "In4.Cu")
		(net "M_G_CPU1_SB_DQ<17>")
	)
	(arc
		(start 139.638278 -230.5812)
		(mid 139.507364 -230.71756)
		(end 139.459716 -230.900478)
		(width 0.088646)
		(layer "In4.Cu")
		(net "M_G_CPU1_SB_DQ<17>")
	)
	(arc
		(start 133.060948 -233.835956)
		(mid 132.781487 -233.907393)
		(end 132.503164 -233.831638)
		(width 0.088646)
		(layer "In4.Cu")
		(net "M_G_CPU1_SB_DQ<17>")
	)
	(arc
		(start 135.322564 -233.831638)
		(mid 135.13787 -233.781537)
		(end 134.952486 -233.829098)
		(width 0.088646)
		(layer "In4.Cu")
		(net "M_G_CPU1_SB_DQ<17>")
	)
	(arc
		(start 134.943342 -233.834432)
		(mid 134.662678 -233.90744)
		(end 134.382764 -233.831638)
		(width 0.088646)
		(layer "In4.Cu")
		(net "M_G_CPU1_SB_DQ<17>")
	)
	(arc
		(start 130.550158 -233.789474)
		(mid 130.243409 -233.585119)
		(end 129.966212 -233.34218)
		(width 0.088646)
		(layer "In4.Cu")
		(net "M_G_CPU1_SB_DQ<17>")
	)
	(arc
		(start 138.989816 -231.724454)
		(mid 138.911705 -232.001403)
		(end 138.707368 -232.204006)
		(width 0.088646)
		(layer "In4.Cu")
		(net "M_G_CPU1_SB_DQ<17>")
	)
	(arc
		(start 138.698478 -232.209086)
		(mid 138.567564 -232.345446)
		(end 138.519916 -232.528364)
		(width 0.088646)
		(layer "In4.Cu")
		(net "M_G_CPU1_SB_DQ<17>")
	)
	(arc
		(start 132.121148 -233.835956)
		(mid 131.841687 -233.907393)
		(end 131.563364 -233.831638)
		(width 0.088646)
		(layer "In4.Cu")
		(net "M_G_CPU1_SB_DQ<17>")
	)
	(arc
		(start 138.519916 -232.53827)
		(mid 138.441805 -232.815219)
		(end 138.237468 -233.017822)
		(width 0.088646)
		(layer "In4.Cu")
		(net "M_G_CPU1_SB_DQ<17>")
	)
	(arc
		(start 139.99845 -230.322374)
		(mid 139.826023 -230.462444)
		(end 139.638278 -230.5812)
		(width 0.088646)
		(layer "In4.Cu")
		(net "M_G_CPU1_SB_DQ<17>")
	)
	(arc
		(start 139.168378 -231.39527)
		(mid 139.037464 -231.53163)
		(end 138.989816 -231.714548)
		(width 0.088646)
		(layer "In4.Cu")
		(net "M_G_CPU1_SB_DQ<17>")
	)
	(arc
		(start 136.827768 -233.831892)
		(mid 136.545066 -233.907634)
		(end 136.262364 -233.831892)
		(width 0.088646)
		(layer "In4.Cu")
		(net "M_G_CPU1_SB_DQ<17>")
	)
	(arc
		(start 135.882126 -233.83494)
		(mid 135.601911 -233.907381)
		(end 135.322564 -233.831638)
		(width 0.088646)
		(layer "In4.Cu")
		(net "M_G_CPU1_SB_DQ<17>")
	)
	(arc
		(start 131.563364 -233.831638)
		(mid 131.37867 -233.781537)
		(end 131.193286 -233.829098)
		(width 0.088646)
		(layer "In4.Cu")
		(net "M_G_CPU1_SB_DQ<17>")
	)
	(arc
		(start 138.228578 -233.022902)
		(mid 138.097664 -233.159262)
		(end 138.050016 -233.34218)
		(width 0.088646)
		(layer "In4.Cu")
		(net "M_G_CPU1_SB_DQ<17>")
	)
	(arc
		(start 133.442964 -233.831638)
		(mid 133.25827 -233.781537)
		(end 133.072886 -233.829098)
		(width 0.088646)
		(layer "In4.Cu")
		(net "M_G_CPU1_SB_DQ<17>")
	)
	(segment
		(start 188.988446 -213.46668)
		(end 187.883546 -213.46668)
		(width 0.20066)
		(layer "F.Cu")
		(net "M_G_CPU1_SB_DQ<16>")
	)
	(segment
		(start 196.532246 -213.46668)
		(end 196.531992 -213.466934)
		(width 0.20066)
		(layer "F.Cu")
		(net "M_G_CPU1_SB_DQ<16>")
	)
	(segment
		(start 191.421004 -213.159848)
		(end 191.421004 -213.527386)
		(width 0.20066)
		(layer "F.Cu")
		(net "M_G_CPU1_SB_DQ<16>")
	)
	(segment
		(start 190.75781 -213.715346)
		(end 190.509144 -213.46668)
		(width 0.20066)
		(layer "F.Cu")
		(net "M_G_CPU1_SB_DQ<16>")
	)
	(segment
		(start 196.531992 -213.466934)
		(end 194.940428 -213.466934)
		(width 0.20066)
		(layer "F.Cu")
		(net "M_G_CPU1_SB_DQ<16>")
	)
	(segment
		(start 130.436112 -234.69219)
		(end 130.436366 -234.691936)
		(width 0.20066)
		(layer "F.Cu")
		(net "M_G_CPU1_SB_DQ<16>")
	)
	(segment
		(start 191.539114 -213.041738)
		(end 191.421004 -213.159848)
		(width 0.20066)
		(layer "F.Cu")
		(net "M_G_CPU1_SB_DQ<16>")
	)
	(segment
		(start 191.930782 -213.041738)
		(end 191.883792 -213.041738)
		(width 0.101854)
		(layer "F.Cu")
		(net "M_G_CPU1_SB_DQ<16>")
	)
	(segment
		(start 191.883792 -213.041738)
		(end 191.539114 -213.041738)
		(width 0.20066)
		(layer "F.Cu")
		(net "M_G_CPU1_SB_DQ<16>")
	)
	(segment
		(start 194.092576 -213.041738)
		(end 191.930782 -213.041738)
		(width 0.1016)
		(layer "F.Cu")
		(net "M_G_CPU1_SB_DQ<16>")
	)
	(segment
		(start 194.508882 -213.035388)
		(end 194.098926 -213.035388)
		(width 0.20066)
		(layer "F.Cu")
		(net "M_G_CPU1_SB_DQ<16>")
	)
	(segment
		(start 190.509144 -213.46668)
		(end 188.988446 -213.46668)
		(width 0.20066)
		(layer "F.Cu")
		(net "M_G_CPU1_SB_DQ<16>")
	)
	(segment
		(start 130.436366 -234.691936)
		(end 130.436366 -234.15625)
		(width 0.20066)
		(layer "F.Cu")
		(net "M_G_CPU1_SB_DQ<16>")
	)
	(segment
		(start 191.421004 -213.527386)
		(end 191.233044 -213.715346)
		(width 0.20066)
		(layer "F.Cu")
		(net "M_G_CPU1_SB_DQ<16>")
	)
	(segment
		(start 191.233044 -213.715346)
		(end 190.75781 -213.715346)
		(width 0.20066)
		(layer "F.Cu")
		(net "M_G_CPU1_SB_DQ<16>")
	)
	(segment
		(start 194.098926 -213.035388)
		(end 194.092576 -213.041738)
		(width 0.1016)
		(layer "F.Cu")
		(net "M_G_CPU1_SB_DQ<16>")
	)
	(segment
		(start 194.940428 -213.466934)
		(end 194.508882 -213.035388)
		(width 0.20066)
		(layer "F.Cu")
		(net "M_G_CPU1_SB_DQ<16>")
	)
	(segment
		(start 185.788808 -214.39632)
		(end 185.461148 -214.39632)
		(width 0.18288)
		(layer "In4.Cu")
		(net "M_G_CPU1_SB_DQ<16>")
	)
	(segment
		(start 186.154568 -216.235026)
		(end 185.971688 -216.052146)
		(width 0.18288)
		(layer "In4.Cu")
		(net "M_G_CPU1_SB_DQ<16>")
	)
	(segment
		(start 171.357036 -218.307412)
		(end 170.37431 -218.307412)
		(width 0.18288)
		(layer "In4.Cu")
		(net "M_G_CPU1_SB_DQ<16>")
	)
	(segment
		(start 133.538468 -234.645708)
		(end 133.528054 -234.651804)
		(width 0.088646)
		(layer "In4.Cu")
		(net "M_G_CPU1_SB_DQ<16>")
	)
	(segment
		(start 187.883546 -213.46668)
		(end 187.883546 -213.71941)
		(width 0.18288)
		(layer "In4.Cu")
		(net "M_G_CPU1_SB_DQ<16>")
	)
	(segment
		(start 185.971688 -214.5792)
		(end 185.788808 -214.39632)
		(width 0.18288)
		(layer "In4.Cu")
		(net "M_G_CPU1_SB_DQ<16>")
	)
	(segment
		(start 138.237214 -234.645708)
		(end 138.222482 -234.654344)
		(width 0.088646)
		(layer "In4.Cu")
		(net "M_G_CPU1_SB_DQ<16>")
	)
	(segment
		(start 180.157628 -218.606624)
		(end 179.054506 -218.606624)
		(width 0.18288)
		(layer "In4.Cu")
		(net "M_G_CPU1_SB_DQ<16>")
	)
	(segment
		(start 185.095388 -216.235026)
		(end 184.535826 -216.235026)
		(width 0.18288)
		(layer "In4.Cu")
		(net "M_G_CPU1_SB_DQ<16>")
	)
	(segment
		(start 137.297414 -234.645708)
		(end 137.282682 -234.654344)
		(width 0.088646)
		(layer "In4.Cu")
		(net "M_G_CPU1_SB_DQ<16>")
	)
	(segment
		(start 140.578078 -231.77881)
		(end 140.433298 -231.77881)
		(width 0.088646)
		(layer "In4.Cu")
		(net "M_G_CPU1_SB_DQ<16>")
	)
	(segment
		(start 183.545226 -216.006426)
		(end 182.072026 -217.479626)
		(width 0.18288)
		(layer "In4.Cu")
		(net "M_G_CPU1_SB_DQ<16>")
	)
	(segment
		(start 140.433298 -231.77881)
		(end 140.324078 -231.66959)
		(width 0.088646)
		(layer "In4.Cu")
		(net "M_G_CPU1_SB_DQ<16>")
	)
	(segment
		(start 162.16757 -217.292682)
		(end 161.091626 -218.368626)
		(width 0.18288)
		(layer "In4.Cu")
		(net "M_G_CPU1_SB_DQ<16>")
	)
	(segment
		(start 140.798042 -231.558846)
		(end 140.578078 -231.77881)
		(width 0.088646)
		(layer "In4.Cu")
		(net "M_G_CPU1_SB_DQ<16>")
	)
	(segment
		(start 139.647168 -232.204006)
		(end 139.638278 -232.209086)
		(width 0.088646)
		(layer "In4.Cu")
		(net "M_G_CPU1_SB_DQ<16>")
	)
	(segment
		(start 177.741326 -217.293444)
		(end 172.371004 -217.293444)
		(width 0.18288)
		(layer "In4.Cu")
		(net "M_G_CPU1_SB_DQ<16>")
	)
	(segment
		(start 179.054506 -218.606624)
		(end 177.741326 -217.293444)
		(width 0.18288)
		(layer "In4.Cu")
		(net "M_G_CPU1_SB_DQ<16>")
	)
	(segment
		(start 169.35958 -217.292682)
		(end 162.16757 -217.292682)
		(width 0.18288)
		(layer "In4.Cu")
		(net "M_G_CPU1_SB_DQ<16>")
	)
	(segment
		(start 184.535826 -216.235026)
		(end 184.307226 -216.006426)
		(width 0.18288)
		(layer "In4.Cu")
		(net "M_G_CPU1_SB_DQ<16>")
	)
	(segment
		(start 184.307226 -216.006426)
		(end 183.545226 -216.006426)
		(width 0.18288)
		(layer "In4.Cu")
		(net "M_G_CPU1_SB_DQ<16>")
	)
	(segment
		(start 170.37431 -218.307412)
		(end 169.35958 -217.292682)
		(width 0.18288)
		(layer "In4.Cu")
		(net "M_G_CPU1_SB_DQ<16>")
	)
	(segment
		(start 139.459716 -232.528364)
		(end 139.459716 -232.53827)
		(width 0.088646)
		(layer "In4.Cu")
		(net "M_G_CPU1_SB_DQ<16>")
	)
	(segment
		(start 136.357614 -234.645708)
		(end 136.3472 -234.651804)
		(width 0.088646)
		(layer "In4.Cu")
		(net "M_G_CPU1_SB_DQ<16>")
	)
	(segment
		(start 138.989816 -233.34218)
		(end 138.989816 -233.360722)
		(width 0.088646)
		(layer "In4.Cu")
		(net "M_G_CPU1_SB_DQ<16>")
	)
	(segment
		(start 187.883546 -213.71941)
		(end 187.303918 -214.299038)
		(width 0.18288)
		(layer "In4.Cu")
		(net "M_G_CPU1_SB_DQ<16>")
	)
	(segment
		(start 161.091626 -218.368626)
		(end 157.05963 -218.368626)
		(width 0.18288)
		(layer "In4.Cu")
		(net "M_G_CPU1_SB_DQ<16>")
	)
	(segment
		(start 145.635472 -229.792784)
		(end 142.564104 -229.792784)
		(width 0.18288)
		(layer "In4.Cu")
		(net "M_G_CPU1_SB_DQ<16>")
	)
	(segment
		(start 138.707368 -233.831892)
		(end 138.698478 -233.836972)
		(width 0.088646)
		(layer "In4.Cu")
		(net "M_G_CPU1_SB_DQ<16>")
	)
	(segment
		(start 185.278268 -216.052146)
		(end 185.095388 -216.235026)
		(width 0.18288)
		(layer "In4.Cu")
		(net "M_G_CPU1_SB_DQ<16>")
	)
	(segment
		(start 185.461148 -214.39632)
		(end 185.278268 -214.5792)
		(width 0.18288)
		(layer "In4.Cu")
		(net "M_G_CPU1_SB_DQ<16>")
	)
	(segment
		(start 142.564104 -229.792784)
		(end 140.798042 -231.558846)
		(width 0.18288)
		(layer "In4.Cu")
		(net "M_G_CPU1_SB_DQ<16>")
	)
	(segment
		(start 185.278268 -214.5792)
		(end 185.278268 -216.052146)
		(width 0.18288)
		(layer "In4.Cu")
		(net "M_G_CPU1_SB_DQ<16>")
	)
	(segment
		(start 130.74904 -234.15625)
		(end 130.436366 -234.15625)
		(width 0.088646)
		(layer "In4.Cu")
		(net "M_G_CPU1_SB_DQ<16>")
	)
	(segment
		(start 140.077698 -231.66959)
		(end 139.941808 -231.80548)
		(width 0.088646)
		(layer "In4.Cu")
		(net "M_G_CPU1_SB_DQ<16>")
	)
	(segment
		(start 130.814572 -234.221782)
		(end 130.74904 -234.15625)
		(width 0.088646)
		(layer "In4.Cu")
		(net "M_G_CPU1_SB_DQ<16>")
	)
	(segment
		(start 132.598414 -234.645708)
		(end 132.588 -234.651804)
		(width 0.088646)
		(layer "In4.Cu")
		(net "M_G_CPU1_SB_DQ<16>")
	)
	(segment
		(start 157.05963 -218.368626)
		(end 145.635472 -229.792784)
		(width 0.18288)
		(layer "In4.Cu")
		(net "M_G_CPU1_SB_DQ<16>")
	)
	(segment
		(start 140.324078 -231.66959)
		(end 140.077698 -231.66959)
		(width 0.088646)
		(layer "In4.Cu")
		(net "M_G_CPU1_SB_DQ<16>")
	)
	(segment
		(start 187.303918 -214.299038)
		(end 187.303918 -216.075006)
		(width 0.18288)
		(layer "In4.Cu")
		(net "M_G_CPU1_SB_DQ<16>")
	)
	(segment
		(start 185.971688 -216.052146)
		(end 185.971688 -214.5792)
		(width 0.18288)
		(layer "In4.Cu")
		(net "M_G_CPU1_SB_DQ<16>")
	)
	(segment
		(start 181.284626 -217.479626)
		(end 180.157628 -218.606624)
		(width 0.18288)
		(layer "In4.Cu")
		(net "M_G_CPU1_SB_DQ<16>")
	)
	(segment
		(start 139.177268 -233.017822)
		(end 139.168378 -233.022902)
		(width 0.088646)
		(layer "In4.Cu")
		(net "M_G_CPU1_SB_DQ<16>")
	)
	(segment
		(start 187.303918 -216.075006)
		(end 187.143898 -216.235026)
		(width 0.18288)
		(layer "In4.Cu")
		(net "M_G_CPU1_SB_DQ<16>")
	)
	(segment
		(start 138.24331 -234.642152)
		(end 138.237214 -234.645708)
		(width 0.088646)
		(layer "In4.Cu")
		(net "M_G_CPU1_SB_DQ<16>")
	)
	(segment
		(start 187.143898 -216.235026)
		(end 186.154568 -216.235026)
		(width 0.18288)
		(layer "In4.Cu")
		(net "M_G_CPU1_SB_DQ<16>")
	)
	(segment
		(start 182.072026 -217.479626)
		(end 181.284626 -217.479626)
		(width 0.18288)
		(layer "In4.Cu")
		(net "M_G_CPU1_SB_DQ<16>")
	)
	(segment
		(start 131.658868 -234.645708)
		(end 131.648454 -234.651804)
		(width 0.088646)
		(layer "In4.Cu")
		(net "M_G_CPU1_SB_DQ<16>")
	)
	(segment
		(start 172.371004 -217.293444)
		(end 171.357036 -218.307412)
		(width 0.18288)
		(layer "In4.Cu")
		(net "M_G_CPU1_SB_DQ<16>")
	)
	(arc
		(start 135.792464 -234.645708)
		(mid 135.605266 -234.595565)
		(end 135.418068 -234.645708)
		(width 0.088646)
		(layer "In4.Cu")
		(net "M_G_CPU1_SB_DQ<16>")
	)
	(arc
		(start 136.73201 -234.645708)
		(mid 136.544812 -234.595565)
		(end 136.357614 -234.645708)
		(width 0.088646)
		(layer "In4.Cu")
		(net "M_G_CPU1_SB_DQ<16>")
	)
	(arc
		(start 138.989816 -233.360722)
		(mid 138.909654 -233.632911)
		(end 138.707368 -233.831892)
		(width 0.088646)
		(layer "In4.Cu")
		(net "M_G_CPU1_SB_DQ<16>")
	)
	(arc
		(start 137.67181 -234.645708)
		(mid 137.484612 -234.595565)
		(end 137.297414 -234.645708)
		(width 0.088646)
		(layer "In4.Cu")
		(net "M_G_CPU1_SB_DQ<16>")
	)
	(arc
		(start 132.033264 -234.645708)
		(mid 131.846066 -234.595565)
		(end 131.658868 -234.645708)
		(width 0.088646)
		(layer "In4.Cu")
		(net "M_G_CPU1_SB_DQ<16>")
	)
	(arc
		(start 133.528054 -234.651804)
		(mid 133.249622 -234.72165)
		(end 132.97281 -234.645708)
		(width 0.088646)
		(layer "In4.Cu")
		(net "M_G_CPU1_SB_DQ<16>")
	)
	(arc
		(start 139.910566 -231.859836)
		(mid 139.813211 -232.058222)
		(end 139.647168 -232.204006)
		(width 0.088646)
		(layer "In4.Cu")
		(net "M_G_CPU1_SB_DQ<16>")
	)
	(arc
		(start 137.282682 -234.654344)
		(mid 137.006207 -234.721664)
		(end 136.73201 -234.645708)
		(width 0.088646)
		(layer "In4.Cu")
		(net "M_G_CPU1_SB_DQ<16>")
	)
	(arc
		(start 135.418068 -234.645708)
		(mid 135.135366 -234.721484)
		(end 134.852664 -234.645708)
		(width 0.088646)
		(layer "In4.Cu")
		(net "M_G_CPU1_SB_DQ<16>")
	)
	(arc
		(start 131.09321 -234.645708)
		(mid 130.903697 -234.466743)
		(end 130.814572 -234.221782)
		(width 0.088646)
		(layer "In4.Cu")
		(net "M_G_CPU1_SB_DQ<16>")
	)
	(arc
		(start 134.478268 -234.645708)
		(mid 134.195566 -234.721484)
		(end 133.912864 -234.645708)
		(width 0.088646)
		(layer "In4.Cu")
		(net "M_G_CPU1_SB_DQ<16>")
	)
	(arc
		(start 132.588 -234.651804)
		(mid 132.309822 -234.721527)
		(end 132.033264 -234.645708)
		(width 0.088646)
		(layer "In4.Cu")
		(net "M_G_CPU1_SB_DQ<16>")
	)
	(arc
		(start 139.638278 -232.209086)
		(mid 139.507364 -232.345446)
		(end 139.459716 -232.528364)
		(width 0.088646)
		(layer "In4.Cu")
		(net "M_G_CPU1_SB_DQ<16>")
	)
	(arc
		(start 139.941808 -231.80548)
		(mid 139.922604 -231.830598)
		(end 139.910566 -231.859836)
		(width 0.088646)
		(layer "In4.Cu")
		(net "M_G_CPU1_SB_DQ<16>")
	)
	(arc
		(start 136.3472 -234.651804)
		(mid 136.069022 -234.721527)
		(end 135.792464 -234.645708)
		(width 0.088646)
		(layer "In4.Cu")
		(net "M_G_CPU1_SB_DQ<16>")
	)
	(arc
		(start 138.519916 -234.15625)
		(mid 138.445925 -234.435816)
		(end 138.24331 -234.642152)
		(width 0.088646)
		(layer "In4.Cu")
		(net "M_G_CPU1_SB_DQ<16>")
	)
	(arc
		(start 134.852664 -234.645708)
		(mid 134.665466 -234.595565)
		(end 134.478268 -234.645708)
		(width 0.088646)
		(layer "In4.Cu")
		(net "M_G_CPU1_SB_DQ<16>")
	)
	(arc
		(start 132.97281 -234.645708)
		(mid 132.785612 -234.595565)
		(end 132.598414 -234.645708)
		(width 0.088646)
		(layer "In4.Cu")
		(net "M_G_CPU1_SB_DQ<16>")
	)
	(arc
		(start 139.459716 -232.53827)
		(mid 139.381605 -232.815219)
		(end 139.177268 -233.017822)
		(width 0.088646)
		(layer "In4.Cu")
		(net "M_G_CPU1_SB_DQ<16>")
	)
	(arc
		(start 138.222482 -234.654344)
		(mid 137.946007 -234.721664)
		(end 137.67181 -234.645708)
		(width 0.088646)
		(layer "In4.Cu")
		(net "M_G_CPU1_SB_DQ<16>")
	)
	(arc
		(start 133.912864 -234.645708)
		(mid 133.725666 -234.595565)
		(end 133.538468 -234.645708)
		(width 0.088646)
		(layer "In4.Cu")
		(net "M_G_CPU1_SB_DQ<16>")
	)
	(arc
		(start 131.648454 -234.651804)
		(mid 131.370022 -234.72165)
		(end 131.09321 -234.645708)
		(width 0.088646)
		(layer "In4.Cu")
		(net "M_G_CPU1_SB_DQ<16>")
	)
	(arc
		(start 138.698478 -233.836972)
		(mid 138.567564 -233.973332)
		(end 138.519916 -234.15625)
		(width 0.088646)
		(layer "In4.Cu")
		(net "M_G_CPU1_SB_DQ<16>")
	)
	(arc
		(start 139.168378 -233.022902)
		(mid 139.037464 -233.159262)
		(end 138.989816 -233.34218)
		(width 0.088646)
		(layer "In4.Cu")
		(net "M_G_CPU1_SB_DQ<16>")
	)
	(segment
		(start 193.088514 -214.316564)
		(end 194.786758 -214.316564)
		(width 0.20066)
		(layer "F.Cu")
		(net "M_G_CPU1_SB_DQ<15>")
	)
	(segment
		(start 194.786758 -214.316564)
		(end 195.218812 -214.748618)
		(width 0.20066)
		(layer "F.Cu")
		(net "M_G_CPU1_SB_DQ<15>")
	)
	(segment
		(start 197.542658 -214.753698)
		(end 198.223886 -214.753698)
		(width 0.20066)
		(layer "F.Cu")
		(net "M_G_CPU1_SB_DQ<15>")
	)
	(segment
		(start 198.662036 -214.064596)
		(end 199.046084 -214.064596)
		(width 0.20066)
		(layer "F.Cu")
		(net "M_G_CPU1_SB_DQ<15>")
	)
	(segment
		(start 195.218812 -214.748618)
		(end 195.510658 -214.748618)
		(width 0.20066)
		(layer "F.Cu")
		(net "M_G_CPU1_SB_DQ<15>")
	)
	(segment
		(start 191.983614 -214.316564)
		(end 193.088514 -214.316564)
		(width 0.20066)
		(layer "F.Cu")
		(net "M_G_CPU1_SB_DQ<15>")
	)
	(segment
		(start 198.427848 -214.549736)
		(end 198.427848 -214.298784)
		(width 0.20066)
		(layer "F.Cu")
		(net "M_G_CPU1_SB_DQ<15>")
	)
	(segment
		(start 195.515484 -214.748618)
		(end 195.522596 -214.741506)
		(width 0.1016)
		(layer "F.Cu")
		(net "M_G_CPU1_SB_DQ<15>")
	)
	(segment
		(start 128.086612 -233.877866)
		(end 128.086612 -233.34218)
		(width 0.20066)
		(layer "F.Cu")
		(net "M_G_CPU1_SB_DQ<15>")
	)
	(segment
		(start 199.298052 -214.316564)
		(end 200.632314 -214.316564)
		(width 0.20066)
		(layer "F.Cu")
		(net "M_G_CPU1_SB_DQ<15>")
	)
	(segment
		(start 197.530466 -214.741506)
		(end 197.542658 -214.753698)
		(width 0.1016)
		(layer "F.Cu")
		(net "M_G_CPU1_SB_DQ<15>")
	)
	(segment
		(start 198.223886 -214.753698)
		(end 198.427848 -214.549736)
		(width 0.20066)
		(layer "F.Cu")
		(net "M_G_CPU1_SB_DQ<15>")
	)
	(segment
		(start 195.522596 -214.741506)
		(end 197.530466 -214.741506)
		(width 0.1016)
		(layer "F.Cu")
		(net "M_G_CPU1_SB_DQ<15>")
	)
	(segment
		(start 198.427848 -214.298784)
		(end 198.662036 -214.064596)
		(width 0.20066)
		(layer "F.Cu")
		(net "M_G_CPU1_SB_DQ<15>")
	)
	(segment
		(start 199.046084 -214.064596)
		(end 199.298052 -214.316564)
		(width 0.20066)
		(layer "F.Cu")
		(net "M_G_CPU1_SB_DQ<15>")
	)
	(segment
		(start 195.510658 -214.748618)
		(end 195.515484 -214.748618)
		(width 0.101854)
		(layer "F.Cu")
		(net "M_G_CPU1_SB_DQ<15>")
	)
	(segment
		(start 128.086866 -233.87812)
		(end 128.086612 -233.877866)
		(width 0.20066)
		(layer "F.Cu")
		(net "M_G_CPU1_SB_DQ<15>")
	)
	(segment
		(start 183.823864 -216.442036)
		(end 183.04002 -216.743026)
		(width 0.18288)
		(layer "In6.Cu")
		(net "M_G_CPU1_SB_DQ<15>")
	)
	(segment
		(start 127.773938 -233.34218)
		(end 128.086612 -233.34218)
		(width 0.088646)
		(layer "In6.Cu")
		(net "M_G_CPU1_SB_DQ<15>")
	)
	(segment
		(start 161.408872 -217.492072)
		(end 161.025586 -217.108786)
		(width 0.18288)
		(layer "In6.Cu")
		(net "M_G_CPU1_SB_DQ<15>")
	)
	(segment
		(start 173.364144 -218.99499)
		(end 172.27042 -218.99499)
		(width 0.18288)
		(layer "In6.Cu")
		(net "M_G_CPU1_SB_DQ<15>")
	)
	(segment
		(start 139.740386 -231.563164)
		(end 139.740386 -231.875584)
		(width 0.088646)
		(layer "In6.Cu")
		(net "M_G_CPU1_SB_DQ<15>")
	)
	(segment
		(start 130.718814 -233.017822)
		(end 130.704082 -233.026458)
		(width 0.088646)
		(layer "In6.Cu")
		(net "M_G_CPU1_SB_DQ<15>")
	)
	(segment
		(start 183.04002 -216.743026)
		(end 182.072026 -216.743026)
		(width 0.18288)
		(layer "In6.Cu")
		(net "M_G_CPU1_SB_DQ<15>")
	)
	(segment
		(start 164.640514 -216.387426)
		(end 163.109402 -216.387426)
		(width 0.18288)
		(layer "In6.Cu")
		(net "M_G_CPU1_SB_DQ<15>")
	)
	(segment
		(start 174.039784 -218.31935)
		(end 173.364144 -218.99499)
		(width 0.18288)
		(layer "In6.Cu")
		(net "M_G_CPU1_SB_DQ<15>")
	)
	(segment
		(start 182.072026 -216.743026)
		(end 181.310026 -217.225626)
		(width 0.18288)
		(layer "In6.Cu")
		(net "M_G_CPU1_SB_DQ<15>")
	)
	(segment
		(start 175.507142 -218.31935)
		(end 174.039784 -218.31935)
		(width 0.18288)
		(layer "In6.Cu")
		(net "M_G_CPU1_SB_DQ<15>")
	)
	(segment
		(start 136.640316 -232.528364)
		(end 136.640316 -232.53827)
		(width 0.088646)
		(layer "In6.Cu")
		(net "M_G_CPU1_SB_DQ<15>")
	)
	(segment
		(start 168.676066 -217.792808)
		(end 167.58539 -216.702132)
		(width 0.18288)
		(layer "In6.Cu")
		(net "M_G_CPU1_SB_DQ<15>")
	)
	(segment
		(start 190.917068 -214.935562)
		(end 188.320426 -216.442036)
		(width 0.18288)
		(layer "In6.Cu")
		(net "M_G_CPU1_SB_DQ<15>")
	)
	(segment
		(start 158.453582 -217.108786)
		(end 156.324808 -217.108786)
		(width 0.18288)
		(layer "In6.Cu")
		(net "M_G_CPU1_SB_DQ<15>")
	)
	(segment
		(start 158.819342 -217.659204)
		(end 158.636462 -217.476324)
		(width 0.18288)
		(layer "In6.Cu")
		(net "M_G_CPU1_SB_DQ<15>")
	)
	(segment
		(start 159.512762 -217.108786)
		(end 159.329882 -217.291666)
		(width 0.18288)
		(layer "In6.Cu")
		(net "M_G_CPU1_SB_DQ<15>")
	)
	(segment
		(start 159.329882 -217.476324)
		(end 159.147002 -217.659204)
		(width 0.18288)
		(layer "In6.Cu")
		(net "M_G_CPU1_SB_DQ<15>")
	)
	(segment
		(start 172.27042 -218.99499)
		(end 172.108622 -218.833192)
		(width 0.18288)
		(layer "In6.Cu")
		(net "M_G_CPU1_SB_DQ<15>")
	)
	(segment
		(start 127.716534 -233.284776)
		(end 127.773938 -233.34218)
		(width 0.088646)
		(layer "In6.Cu")
		(net "M_G_CPU1_SB_DQ<15>")
	)
	(segment
		(start 127.899414 -233.017822)
		(end 127.890524 -233.022902)
		(width 0.088646)
		(layer "In6.Cu")
		(net "M_G_CPU1_SB_DQ<15>")
	)
	(segment
		(start 140.021818 -231.281732)
		(end 139.740386 -231.563164)
		(width 0.088646)
		(layer "In6.Cu")
		(net "M_G_CPU1_SB_DQ<15>")
	)
	(segment
		(start 132.598668 -233.017822)
		(end 132.588254 -233.023918)
		(width 0.088646)
		(layer "In6.Cu")
		(net "M_G_CPU1_SB_DQ<15>")
	)
	(segment
		(start 180.116226 -217.225626)
		(end 179.379626 -217.962226)
		(width 0.18288)
		(layer "In6.Cu")
		(net "M_G_CPU1_SB_DQ<15>")
	)
	(segment
		(start 131.658614 -233.017822)
		(end 131.643882 -233.026458)
		(width 0.088646)
		(layer "In6.Cu")
		(net "M_G_CPU1_SB_DQ<15>")
	)
	(segment
		(start 159.147002 -217.659204)
		(end 158.819342 -217.659204)
		(width 0.18288)
		(layer "In6.Cu")
		(net "M_G_CPU1_SB_DQ<15>")
	)
	(segment
		(start 177.632868 -217.962226)
		(end 177.453544 -218.14155)
		(width 0.18288)
		(layer "In6.Cu")
		(net "M_G_CPU1_SB_DQ<15>")
	)
	(segment
		(start 162.004756 -217.492072)
		(end 161.408872 -217.492072)
		(width 0.18288)
		(layer "In6.Cu")
		(net "M_G_CPU1_SB_DQ<15>")
	)
	(segment
		(start 172.108622 -218.833192)
		(end 168.676066 -217.792808)
		(width 0.18288)
		(layer "In6.Cu")
		(net "M_G_CPU1_SB_DQ<15>")
	)
	(segment
		(start 163.109402 -216.387426)
		(end 162.004756 -217.492072)
		(width 0.18288)
		(layer "In6.Cu")
		(net "M_G_CPU1_SB_DQ<15>")
	)
	(segment
		(start 158.636462 -217.476324)
		(end 158.636462 -217.291666)
		(width 0.18288)
		(layer "In6.Cu")
		(net "M_G_CPU1_SB_DQ<15>")
	)
	(segment
		(start 164.95522 -216.702132)
		(end 164.640514 -216.387426)
		(width 0.18288)
		(layer "In6.Cu")
		(net "M_G_CPU1_SB_DQ<15>")
	)
	(segment
		(start 140.174218 -231.281732)
		(end 140.021818 -231.281732)
		(width 0.088646)
		(layer "In6.Cu")
		(net "M_G_CPU1_SB_DQ<15>")
	)
	(segment
		(start 132.987796 -233.026458)
		(end 132.973064 -233.017822)
		(width 0.088646)
		(layer "In6.Cu")
		(net "M_G_CPU1_SB_DQ<15>")
	)
	(segment
		(start 191.364616 -214.935562)
		(end 190.917068 -214.935562)
		(width 0.18288)
		(layer "In6.Cu")
		(net "M_G_CPU1_SB_DQ<15>")
	)
	(segment
		(start 136.827768 -232.204006)
		(end 136.818878 -232.209086)
		(width 0.088646)
		(layer "In6.Cu")
		(net "M_G_CPU1_SB_DQ<15>")
	)
	(segment
		(start 156.324808 -217.108786)
		(end 142.151862 -231.281732)
		(width 0.18288)
		(layer "In6.Cu")
		(net "M_G_CPU1_SB_DQ<15>")
	)
	(segment
		(start 142.151862 -231.281732)
		(end 140.174218 -231.281732)
		(width 0.18288)
		(layer "In6.Cu")
		(net "M_G_CPU1_SB_DQ<15>")
	)
	(segment
		(start 159.329882 -217.291666)
		(end 159.329882 -217.476324)
		(width 0.18288)
		(layer "In6.Cu")
		(net "M_G_CPU1_SB_DQ<15>")
	)
	(segment
		(start 128.839214 -233.017822)
		(end 128.824482 -233.026458)
		(width 0.088646)
		(layer "In6.Cu")
		(net "M_G_CPU1_SB_DQ<15>")
	)
	(segment
		(start 158.636462 -217.291666)
		(end 158.453582 -217.108786)
		(width 0.18288)
		(layer "In6.Cu")
		(net "M_G_CPU1_SB_DQ<15>")
	)
	(segment
		(start 129.779014 -233.017822)
		(end 129.764282 -233.026458)
		(width 0.088646)
		(layer "In6.Cu")
		(net "M_G_CPU1_SB_DQ<15>")
	)
	(segment
		(start 188.320426 -216.442036)
		(end 183.823864 -216.442036)
		(width 0.18288)
		(layer "In6.Cu")
		(net "M_G_CPU1_SB_DQ<15>")
	)
	(segment
		(start 175.684942 -218.14155)
		(end 175.507142 -218.31935)
		(width 0.18288)
		(layer "In6.Cu")
		(net "M_G_CPU1_SB_DQ<15>")
	)
	(segment
		(start 139.740386 -231.875584)
		(end 139.461748 -232.154222)
		(width 0.088646)
		(layer "In6.Cu")
		(net "M_G_CPU1_SB_DQ<15>")
	)
	(segment
		(start 181.310026 -217.225626)
		(end 180.116226 -217.225626)
		(width 0.18288)
		(layer "In6.Cu")
		(net "M_G_CPU1_SB_DQ<15>")
	)
	(segment
		(start 139.461748 -232.154222)
		(end 138.908536 -232.154222)
		(width 0.088646)
		(layer "In6.Cu")
		(net "M_G_CPU1_SB_DQ<15>")
	)
	(segment
		(start 161.025586 -217.108786)
		(end 159.512762 -217.108786)
		(width 0.18288)
		(layer "In6.Cu")
		(net "M_G_CPU1_SB_DQ<15>")
	)
	(segment
		(start 167.58539 -216.702132)
		(end 164.95522 -216.702132)
		(width 0.18288)
		(layer "In6.Cu")
		(net "M_G_CPU1_SB_DQ<15>")
	)
	(segment
		(start 177.453544 -218.14155)
		(end 175.684942 -218.14155)
		(width 0.18288)
		(layer "In6.Cu")
		(net "M_G_CPU1_SB_DQ<15>")
	)
	(segment
		(start 191.983614 -214.316564)
		(end 191.364616 -214.935562)
		(width 0.18288)
		(layer "In6.Cu")
		(net "M_G_CPU1_SB_DQ<15>")
	)
	(segment
		(start 179.379626 -217.962226)
		(end 177.632868 -217.962226)
		(width 0.18288)
		(layer "In6.Cu")
		(net "M_G_CPU1_SB_DQ<15>")
	)
	(arc
		(start 128.824482 -233.026458)
		(mid 128.548007 -233.093778)
		(end 128.27381 -233.017822)
		(width 0.088646)
		(layer "In6.Cu")
		(net "M_G_CPU1_SB_DQ<15>")
	)
	(arc
		(start 129.21361 -233.017822)
		(mid 129.026412 -232.967679)
		(end 128.839214 -233.017822)
		(width 0.088646)
		(layer "In6.Cu")
		(net "M_G_CPU1_SB_DQ<15>")
	)
	(arc
		(start 132.588254 -233.023918)
		(mid 132.309822 -233.093764)
		(end 132.03301 -233.017822)
		(width 0.088646)
		(layer "In6.Cu")
		(net "M_G_CPU1_SB_DQ<15>")
	)
	(arc
		(start 133.538468 -233.017822)
		(mid 133.264269 -233.093657)
		(end 132.987796 -233.026458)
		(width 0.088646)
		(layer "In6.Cu")
		(net "M_G_CPU1_SB_DQ<15>")
	)
	(arc
		(start 135.792464 -233.017822)
		(mid 135.605266 -232.967679)
		(end 135.418068 -233.017822)
		(width 0.088646)
		(layer "In6.Cu")
		(net "M_G_CPU1_SB_DQ<15>")
	)
	(arc
		(start 132.973064 -233.017822)
		(mid 132.785866 -232.967679)
		(end 132.598668 -233.017822)
		(width 0.088646)
		(layer "In6.Cu")
		(net "M_G_CPU1_SB_DQ<15>")
	)
	(arc
		(start 136.357868 -233.017822)
		(mid 136.075166 -233.093598)
		(end 135.792464 -233.017822)
		(width 0.088646)
		(layer "In6.Cu")
		(net "M_G_CPU1_SB_DQ<15>")
	)
	(arc
		(start 130.15341 -233.017822)
		(mid 129.966212 -232.967679)
		(end 129.779014 -233.017822)
		(width 0.088646)
		(layer "In6.Cu")
		(net "M_G_CPU1_SB_DQ<15>")
	)
	(arc
		(start 127.890524 -233.022902)
		(mid 127.774785 -233.134726)
		(end 127.716534 -233.284776)
		(width 0.088646)
		(layer "In6.Cu")
		(net "M_G_CPU1_SB_DQ<15>")
	)
	(arc
		(start 138.908536 -232.154222)
		(mid 138.804432 -232.1649)
		(end 138.707368 -232.204006)
		(width 0.088646)
		(layer "In6.Cu")
		(net "M_G_CPU1_SB_DQ<15>")
	)
	(arc
		(start 134.478268 -233.017822)
		(mid 134.195566 -233.093598)
		(end 133.912864 -233.017822)
		(width 0.088646)
		(layer "In6.Cu")
		(net "M_G_CPU1_SB_DQ<15>")
	)
	(arc
		(start 128.27381 -233.017822)
		(mid 128.086612 -232.967679)
		(end 127.899414 -233.017822)
		(width 0.088646)
		(layer "In6.Cu")
		(net "M_G_CPU1_SB_DQ<15>")
	)
	(arc
		(start 134.852664 -233.017822)
		(mid 134.665466 -232.967679)
		(end 134.478268 -233.017822)
		(width 0.088646)
		(layer "In6.Cu")
		(net "M_G_CPU1_SB_DQ<15>")
	)
	(arc
		(start 136.818878 -232.209086)
		(mid 136.687964 -232.345446)
		(end 136.640316 -232.528364)
		(width 0.088646)
		(layer "In6.Cu")
		(net "M_G_CPU1_SB_DQ<15>")
	)
	(arc
		(start 135.418068 -233.017822)
		(mid 135.135366 -233.093598)
		(end 134.852664 -233.017822)
		(width 0.088646)
		(layer "In6.Cu")
		(net "M_G_CPU1_SB_DQ<15>")
	)
	(arc
		(start 129.764282 -233.026458)
		(mid 129.487807 -233.093778)
		(end 129.21361 -233.017822)
		(width 0.088646)
		(layer "In6.Cu")
		(net "M_G_CPU1_SB_DQ<15>")
	)
	(arc
		(start 137.202164 -232.204006)
		(mid 137.014966 -232.153863)
		(end 136.827768 -232.204006)
		(width 0.088646)
		(layer "In6.Cu")
		(net "M_G_CPU1_SB_DQ<15>")
	)
	(arc
		(start 138.707368 -232.204006)
		(mid 138.424666 -232.279782)
		(end 138.141964 -232.204006)
		(width 0.088646)
		(layer "In6.Cu")
		(net "M_G_CPU1_SB_DQ<15>")
	)
	(arc
		(start 131.643882 -233.026458)
		(mid 131.367407 -233.093778)
		(end 131.09321 -233.017822)
		(width 0.088646)
		(layer "In6.Cu")
		(net "M_G_CPU1_SB_DQ<15>")
	)
	(arc
		(start 138.141964 -232.204006)
		(mid 137.954766 -232.153863)
		(end 137.767568 -232.204006)
		(width 0.088646)
		(layer "In6.Cu")
		(net "M_G_CPU1_SB_DQ<15>")
	)
	(arc
		(start 130.704082 -233.026458)
		(mid 130.427607 -233.093778)
		(end 130.15341 -233.017822)
		(width 0.088646)
		(layer "In6.Cu")
		(net "M_G_CPU1_SB_DQ<15>")
	)
	(arc
		(start 133.912864 -233.017822)
		(mid 133.725666 -232.967679)
		(end 133.538468 -233.017822)
		(width 0.088646)
		(layer "In6.Cu")
		(net "M_G_CPU1_SB_DQ<15>")
	)
	(arc
		(start 137.767568 -232.204006)
		(mid 137.484866 -232.279782)
		(end 137.202164 -232.204006)
		(width 0.088646)
		(layer "In6.Cu")
		(net "M_G_CPU1_SB_DQ<15>")
	)
	(arc
		(start 131.09321 -233.017822)
		(mid 130.906012 -232.967679)
		(end 130.718814 -233.017822)
		(width 0.088646)
		(layer "In6.Cu")
		(net "M_G_CPU1_SB_DQ<15>")
	)
	(arc
		(start 136.640316 -232.53827)
		(mid 136.562205 -232.815219)
		(end 136.357868 -233.017822)
		(width 0.088646)
		(layer "In6.Cu")
		(net "M_G_CPU1_SB_DQ<15>")
	)
	(arc
		(start 132.03301 -233.017822)
		(mid 131.845812 -232.967679)
		(end 131.658614 -233.017822)
		(width 0.088646)
		(layer "In6.Cu")
		(net "M_G_CPU1_SB_DQ<15>")
	)
	(segment
		(start 198.662036 -215.764618)
		(end 199.046084 -215.764618)
		(width 0.20066)
		(layer "F.Cu")
		(net "M_G_CPU1_SB_DQ<14>")
	)
	(segment
		(start 199.298052 -216.016586)
		(end 200.632314 -216.016586)
		(width 0.20066)
		(layer "F.Cu")
		(net "M_G_CPU1_SB_DQ<14>")
	)
	(segment
		(start 195.218812 -216.44864)
		(end 195.510658 -216.44864)
		(width 0.20066)
		(layer "F.Cu")
		(net "M_G_CPU1_SB_DQ<14>")
	)
	(segment
		(start 197.542658 -216.45372)
		(end 198.223886 -216.45372)
		(width 0.20066)
		(layer "F.Cu")
		(net "M_G_CPU1_SB_DQ<14>")
	)
	(segment
		(start 191.983614 -216.016586)
		(end 193.088514 -216.016586)
		(width 0.20066)
		(layer "F.Cu")
		(net "M_G_CPU1_SB_DQ<14>")
	)
	(segment
		(start 198.427848 -215.998806)
		(end 198.662036 -215.764618)
		(width 0.20066)
		(layer "F.Cu")
		(net "M_G_CPU1_SB_DQ<14>")
	)
	(segment
		(start 195.515484 -216.44864)
		(end 195.522596 -216.441528)
		(width 0.1016)
		(layer "F.Cu")
		(net "M_G_CPU1_SB_DQ<14>")
	)
	(segment
		(start 193.088514 -216.016586)
		(end 194.786758 -216.016586)
		(width 0.20066)
		(layer "F.Cu")
		(net "M_G_CPU1_SB_DQ<14>")
	)
	(segment
		(start 128.556512 -234.69219)
		(end 128.556766 -234.691936)
		(width 0.20066)
		(layer "F.Cu")
		(net "M_G_CPU1_SB_DQ<14>")
	)
	(segment
		(start 198.223886 -216.45372)
		(end 198.427848 -216.249758)
		(width 0.20066)
		(layer "F.Cu")
		(net "M_G_CPU1_SB_DQ<14>")
	)
	(segment
		(start 195.522596 -216.441528)
		(end 197.530466 -216.441528)
		(width 0.1016)
		(layer "F.Cu")
		(net "M_G_CPU1_SB_DQ<14>")
	)
	(segment
		(start 195.510658 -216.44864)
		(end 195.515484 -216.44864)
		(width 0.101854)
		(layer "F.Cu")
		(net "M_G_CPU1_SB_DQ<14>")
	)
	(segment
		(start 199.046084 -215.764618)
		(end 199.298052 -216.016586)
		(width 0.20066)
		(layer "F.Cu")
		(net "M_G_CPU1_SB_DQ<14>")
	)
	(segment
		(start 194.786758 -216.016586)
		(end 195.218812 -216.44864)
		(width 0.20066)
		(layer "F.Cu")
		(net "M_G_CPU1_SB_DQ<14>")
	)
	(segment
		(start 198.427848 -216.249758)
		(end 198.427848 -215.998806)
		(width 0.20066)
		(layer "F.Cu")
		(net "M_G_CPU1_SB_DQ<14>")
	)
	(segment
		(start 128.556766 -234.691936)
		(end 128.556766 -234.15625)
		(width 0.20066)
		(layer "F.Cu")
		(net "M_G_CPU1_SB_DQ<14>")
	)
	(segment
		(start 197.530466 -216.441528)
		(end 197.542658 -216.45372)
		(width 0.1016)
		(layer "F.Cu")
		(net "M_G_CPU1_SB_DQ<14>")
	)
	(segment
		(start 130.253486 -233.829098)
		(end 130.248914 -233.831638)
		(width 0.088646)
		(layer "In6.Cu")
		(net "M_G_CPU1_SB_DQ<14>")
	)
	(segment
		(start 173.498764 -220.693488)
		(end 168.852088 -220.693488)
		(width 0.18288)
		(layer "In6.Cu")
		(net "M_G_CPU1_SB_DQ<14>")
	)
	(segment
		(start 129.313686 -233.829098)
		(end 128.91262 -234.060746)
		(width 0.088646)
		(layer "In6.Cu")
		(net "M_G_CPU1_SB_DQ<14>")
	)
	(segment
		(start 161.244534 -218.673426)
		(end 161.014918 -218.903042)
		(width 0.18288)
		(layer "In6.Cu")
		(net "M_G_CPU1_SB_DQ<14>")
	)
	(segment
		(start 178.812444 -218.986608)
		(end 177.957988 -219.841064)
		(width 0.18288)
		(layer "In6.Cu")
		(net "M_G_CPU1_SB_DQ<14>")
	)
	(segment
		(start 167.308022 -219.407994)
		(end 167.065452 -219.650564)
		(width 0.18288)
		(layer "In6.Cu")
		(net "M_G_CPU1_SB_DQ<14>")
	)
	(segment
		(start 166.574978 -219.418662)
		(end 166.574978 -219.16009)
		(width 0.18288)
		(layer "In6.Cu")
		(net "M_G_CPU1_SB_DQ<14>")
	)
	(segment
		(start 160.346898 -218.673426)
		(end 156.304488 -218.673426)
		(width 0.18288)
		(layer "In6.Cu")
		(net "M_G_CPU1_SB_DQ<14>")
	)
	(segment
		(start 142.589504 -232.29189)
		(end 140.174218 -232.29189)
		(width 0.18288)
		(layer "In6.Cu")
		(net "M_G_CPU1_SB_DQ<14>")
	)
	(segment
		(start 166.574978 -219.16009)
		(end 166.817548 -218.91752)
		(width 0.18288)
		(layer "In6.Cu")
		(net "M_G_CPU1_SB_DQ<14>")
	)
	(segment
		(start 168.852088 -220.693488)
		(end 167.566594 -219.407994)
		(width 0.18288)
		(layer "In6.Cu")
		(net "M_G_CPU1_SB_DQ<14>")
	)
	(segment
		(start 166.324026 -218.165426)
		(end 163.199826 -218.165426)
		(width 0.18288)
		(layer "In6.Cu")
		(net "M_G_CPU1_SB_DQ<14>")
	)
	(segment
		(start 167.065452 -219.650564)
		(end 166.80688 -219.650564)
		(width 0.18288)
		(layer "In6.Cu")
		(net "M_G_CPU1_SB_DQ<14>")
	)
	(segment
		(start 130.248914 -233.831638)
		(end 130.241548 -233.835956)
		(width 0.088646)
		(layer "In6.Cu")
		(net "M_G_CPU1_SB_DQ<14>")
	)
	(segment
		(start 189.003178 -218.142058)
		(end 187.33262 -218.142058)
		(width 0.18288)
		(layer "In6.Cu")
		(net "M_G_CPU1_SB_DQ<14>")
	)
	(segment
		(start 191.12865 -216.016586)
		(end 189.003178 -218.142058)
		(width 0.18288)
		(layer "In6.Cu")
		(net "M_G_CPU1_SB_DQ<14>")
	)
	(segment
		(start 139.945364 -232.29189)
		(end 139.33805 -232.899204)
		(width 0.088646)
		(layer "In6.Cu")
		(net "M_G_CPU1_SB_DQ<14>")
	)
	(segment
		(start 156.304488 -218.673426)
		(end 142.75435 -232.223564)
		(width 0.18288)
		(layer "In6.Cu")
		(net "M_G_CPU1_SB_DQ<14>")
	)
	(segment
		(start 131.193286 -233.829098)
		(end 131.181348 -233.835956)
		(width 0.088646)
		(layer "In6.Cu")
		(net "M_G_CPU1_SB_DQ<14>")
	)
	(segment
		(start 174.351188 -219.841064)
		(end 173.498764 -220.693488)
		(width 0.18288)
		(layer "In6.Cu")
		(net "M_G_CPU1_SB_DQ<14>")
	)
	(segment
		(start 167.566594 -219.407994)
		(end 167.308022 -219.407994)
		(width 0.18288)
		(layer "In6.Cu")
		(net "M_G_CPU1_SB_DQ<14>")
	)
	(segment
		(start 182.470044 -218.986608)
		(end 178.812444 -218.986608)
		(width 0.18288)
		(layer "In6.Cu")
		(net "M_G_CPU1_SB_DQ<14>")
	)
	(segment
		(start 191.983614 -216.016586)
		(end 191.12865 -216.016586)
		(width 0.18288)
		(layer "In6.Cu")
		(net "M_G_CPU1_SB_DQ<14>")
	)
	(segment
		(start 163.199826 -218.165426)
		(end 162.691826 -218.673426)
		(width 0.18288)
		(layer "In6.Cu")
		(net "M_G_CPU1_SB_DQ<14>")
	)
	(segment
		(start 160.576514 -218.903042)
		(end 160.346898 -218.673426)
		(width 0.18288)
		(layer "In6.Cu")
		(net "M_G_CPU1_SB_DQ<14>")
	)
	(segment
		(start 161.014918 -218.903042)
		(end 160.576514 -218.903042)
		(width 0.18288)
		(layer "In6.Cu")
		(net "M_G_CPU1_SB_DQ<14>")
	)
	(segment
		(start 140.174218 -232.29189)
		(end 139.945364 -232.29189)
		(width 0.088646)
		(layer "In6.Cu")
		(net "M_G_CPU1_SB_DQ<14>")
	)
	(segment
		(start 166.80688 -219.650564)
		(end 166.574978 -219.418662)
		(width 0.18288)
		(layer "In6.Cu")
		(net "M_G_CPU1_SB_DQ<14>")
	)
	(segment
		(start 166.817548 -218.658948)
		(end 166.324026 -218.165426)
		(width 0.18288)
		(layer "In6.Cu")
		(net "M_G_CPU1_SB_DQ<14>")
	)
	(segment
		(start 132.128768 -233.831892)
		(end 132.121148 -233.835956)
		(width 0.088646)
		(layer "In6.Cu")
		(net "M_G_CPU1_SB_DQ<14>")
	)
	(segment
		(start 162.691826 -218.673426)
		(end 161.244534 -218.673426)
		(width 0.18288)
		(layer "In6.Cu")
		(net "M_G_CPU1_SB_DQ<14>")
	)
	(segment
		(start 183.555386 -217.901266)
		(end 182.470044 -218.986608)
		(width 0.18288)
		(layer "In6.Cu")
		(net "M_G_CPU1_SB_DQ<14>")
	)
	(segment
		(start 166.817548 -218.91752)
		(end 166.817548 -218.658948)
		(width 0.18288)
		(layer "In6.Cu")
		(net "M_G_CPU1_SB_DQ<14>")
	)
	(segment
		(start 137.110216 -233.34218)
		(end 137.110216 -233.360722)
		(width 0.088646)
		(layer "In6.Cu")
		(net "M_G_CPU1_SB_DQ<14>")
	)
	(segment
		(start 187.091828 -217.901266)
		(end 183.555386 -217.901266)
		(width 0.18288)
		(layer "In6.Cu")
		(net "M_G_CPU1_SB_DQ<14>")
	)
	(segment
		(start 187.33262 -218.142058)
		(end 187.091828 -217.901266)
		(width 0.18288)
		(layer "In6.Cu")
		(net "M_G_CPU1_SB_DQ<14>")
	)
	(segment
		(start 137.297668 -233.017822)
		(end 137.288778 -233.022902)
		(width 0.088646)
		(layer "In6.Cu")
		(net "M_G_CPU1_SB_DQ<14>")
	)
	(segment
		(start 177.957988 -219.841064)
		(end 174.351188 -219.841064)
		(width 0.18288)
		(layer "In6.Cu")
		(net "M_G_CPU1_SB_DQ<14>")
	)
	(arc
		(start 129.683764 -233.831638)
		(mid 129.49907 -233.781537)
		(end 129.313686 -233.829098)
		(width 0.088646)
		(layer "In6.Cu")
		(net "M_G_CPU1_SB_DQ<14>")
	)
	(arc
		(start 137.288778 -233.022902)
		(mid 137.157864 -233.159262)
		(end 137.110216 -233.34218)
		(width 0.088646)
		(layer "In6.Cu")
		(net "M_G_CPU1_SB_DQ<14>")
	)
	(arc
		(start 139.130532 -233.042206)
		(mid 138.868238 -233.093065)
		(end 138.611864 -233.017822)
		(width 0.088646)
		(layer "In6.Cu")
		(net "M_G_CPU1_SB_DQ<14>")
	)
	(arc
		(start 138.611864 -233.017822)
		(mid 138.424666 -232.967679)
		(end 138.237468 -233.017822)
		(width 0.088646)
		(layer "In6.Cu")
		(net "M_G_CPU1_SB_DQ<14>")
	)
	(arc
		(start 139.33805 -232.899204)
		(mid 139.242429 -232.979004)
		(end 139.134088 -233.040428)
		(width 0.088646)
		(layer "In6.Cu")
		(net "M_G_CPU1_SB_DQ<14>")
	)
	(arc
		(start 139.134088 -233.040428)
		(mid 139.132309 -233.041314)
		(end 139.130532 -233.042206)
		(width 0.088646)
		(layer "In6.Cu")
		(net "M_G_CPU1_SB_DQ<14>")
	)
	(arc
		(start 134.948168 -233.831892)
		(mid 134.665466 -233.907634)
		(end 134.382764 -233.831892)
		(width 0.088646)
		(layer "In6.Cu")
		(net "M_G_CPU1_SB_DQ<14>")
	)
	(arc
		(start 142.75435 -232.223564)
		(mid 142.678732 -232.274153)
		(end 142.589504 -232.29189)
		(width 0.18288)
		(layer "In6.Cu")
		(net "M_G_CPU1_SB_DQ<14>")
	)
	(arc
		(start 136.262364 -233.831892)
		(mid 136.075166 -233.781749)
		(end 135.887968 -233.831892)
		(width 0.088646)
		(layer "In6.Cu")
		(net "M_G_CPU1_SB_DQ<14>")
	)
	(arc
		(start 136.827768 -233.831892)
		(mid 136.545066 -233.907634)
		(end 136.262364 -233.831892)
		(width 0.088646)
		(layer "In6.Cu")
		(net "M_G_CPU1_SB_DQ<14>")
	)
	(arc
		(start 137.110216 -233.360722)
		(mid 137.030054 -233.632911)
		(end 136.827768 -233.831892)
		(width 0.088646)
		(layer "In6.Cu")
		(net "M_G_CPU1_SB_DQ<14>")
	)
	(arc
		(start 134.382764 -233.831892)
		(mid 134.195566 -233.781749)
		(end 134.008368 -233.831892)
		(width 0.088646)
		(layer "In6.Cu")
		(net "M_G_CPU1_SB_DQ<14>")
	)
	(arc
		(start 130.623564 -233.831638)
		(mid 130.43887 -233.781537)
		(end 130.253486 -233.829098)
		(width 0.088646)
		(layer "In6.Cu")
		(net "M_G_CPU1_SB_DQ<14>")
	)
	(arc
		(start 132.121148 -233.835956)
		(mid 131.841687 -233.907393)
		(end 131.563364 -233.831638)
		(width 0.088646)
		(layer "In6.Cu")
		(net "M_G_CPU1_SB_DQ<14>")
	)
	(arc
		(start 128.91262 -234.060746)
		(mid 128.740989 -234.131973)
		(end 128.556766 -234.15625)
		(width 0.088646)
		(layer "In6.Cu")
		(net "M_G_CPU1_SB_DQ<14>")
	)
	(arc
		(start 132.503164 -233.831892)
		(mid 132.315966 -233.781749)
		(end 132.128768 -233.831892)
		(width 0.088646)
		(layer "In6.Cu")
		(net "M_G_CPU1_SB_DQ<14>")
	)
	(arc
		(start 135.322564 -233.831892)
		(mid 135.135366 -233.781749)
		(end 134.948168 -233.831892)
		(width 0.088646)
		(layer "In6.Cu")
		(net "M_G_CPU1_SB_DQ<14>")
	)
	(arc
		(start 138.237468 -233.017822)
		(mid 137.954766 -233.093598)
		(end 137.672064 -233.017822)
		(width 0.088646)
		(layer "In6.Cu")
		(net "M_G_CPU1_SB_DQ<14>")
	)
	(arc
		(start 131.563364 -233.831638)
		(mid 131.37867 -233.781537)
		(end 131.193286 -233.829098)
		(width 0.088646)
		(layer "In6.Cu")
		(net "M_G_CPU1_SB_DQ<14>")
	)
	(arc
		(start 130.241548 -233.835956)
		(mid 129.962087 -233.907393)
		(end 129.683764 -233.831638)
		(width 0.088646)
		(layer "In6.Cu")
		(net "M_G_CPU1_SB_DQ<14>")
	)
	(arc
		(start 131.181348 -233.835956)
		(mid 130.901887 -233.907393)
		(end 130.623564 -233.831638)
		(width 0.088646)
		(layer "In6.Cu")
		(net "M_G_CPU1_SB_DQ<14>")
	)
	(arc
		(start 137.672064 -233.017822)
		(mid 137.484866 -232.967679)
		(end 137.297668 -233.017822)
		(width 0.088646)
		(layer "In6.Cu")
		(net "M_G_CPU1_SB_DQ<14>")
	)
	(arc
		(start 134.008368 -233.831892)
		(mid 133.725666 -233.907634)
		(end 133.442964 -233.831892)
		(width 0.088646)
		(layer "In6.Cu")
		(net "M_G_CPU1_SB_DQ<14>")
	)
	(arc
		(start 133.442964 -233.831892)
		(mid 133.255766 -233.781749)
		(end 133.068568 -233.831892)
		(width 0.088646)
		(layer "In6.Cu")
		(net "M_G_CPU1_SB_DQ<14>")
	)
	(arc
		(start 135.887968 -233.831892)
		(mid 135.605266 -233.907634)
		(end 135.322564 -233.831892)
		(width 0.088646)
		(layer "In6.Cu")
		(net "M_G_CPU1_SB_DQ<14>")
	)
	(arc
		(start 133.068568 -233.831892)
		(mid 132.785866 -233.907634)
		(end 132.503164 -233.831892)
		(width 0.088646)
		(layer "In6.Cu")
		(net "M_G_CPU1_SB_DQ<14>")
	)
	(segment
		(start 127.146812 -233.877866)
		(end 127.146812 -233.34218)
		(width 0.20066)
		(layer "F.Cu")
		(net "M_G_CPU1_SB_DQ<13>")
	)
	(segment
		(start 190.75781 -215.415368)
		(end 190.509144 -215.166702)
		(width 0.20066)
		(layer "F.Cu")
		(net "M_G_CPU1_SB_DQ<13>")
	)
	(segment
		(start 190.509144 -215.166702)
		(end 188.988446 -215.166702)
		(width 0.20066)
		(layer "F.Cu")
		(net "M_G_CPU1_SB_DQ<13>")
	)
	(segment
		(start 127.147066 -233.87812)
		(end 127.146812 -233.877866)
		(width 0.20066)
		(layer "F.Cu")
		(net "M_G_CPU1_SB_DQ<13>")
	)
	(segment
		(start 191.233044 -215.415368)
		(end 190.75781 -215.415368)
		(width 0.20066)
		(layer "F.Cu")
		(net "M_G_CPU1_SB_DQ<13>")
	)
	(segment
		(start 188.988446 -215.166702)
		(end 187.883546 -215.166702)
		(width 0.20066)
		(layer "F.Cu")
		(net "M_G_CPU1_SB_DQ<13>")
	)
	(segment
		(start 191.539114 -214.74176)
		(end 191.421004 -214.85987)
		(width 0.20066)
		(layer "F.Cu")
		(net "M_G_CPU1_SB_DQ<13>")
	)
	(segment
		(start 194.098926 -214.73541)
		(end 194.092576 -214.74176)
		(width 0.1016)
		(layer "F.Cu")
		(net "M_G_CPU1_SB_DQ<13>")
	)
	(segment
		(start 196.531992 -215.166956)
		(end 194.940428 -215.166956)
		(width 0.20066)
		(layer "F.Cu")
		(net "M_G_CPU1_SB_DQ<13>")
	)
	(segment
		(start 191.421004 -214.85987)
		(end 191.421004 -215.227408)
		(width 0.20066)
		(layer "F.Cu")
		(net "M_G_CPU1_SB_DQ<13>")
	)
	(segment
		(start 191.421004 -215.227408)
		(end 191.233044 -215.415368)
		(width 0.20066)
		(layer "F.Cu")
		(net "M_G_CPU1_SB_DQ<13>")
	)
	(segment
		(start 194.508882 -214.73541)
		(end 194.098926 -214.73541)
		(width 0.20066)
		(layer "F.Cu")
		(net "M_G_CPU1_SB_DQ<13>")
	)
	(segment
		(start 194.092576 -214.74176)
		(end 191.903858 -214.74176)
		(width 0.1016)
		(layer "F.Cu")
		(net "M_G_CPU1_SB_DQ<13>")
	)
	(segment
		(start 194.940428 -215.166956)
		(end 194.508882 -214.73541)
		(width 0.20066)
		(layer "F.Cu")
		(net "M_G_CPU1_SB_DQ<13>")
	)
	(segment
		(start 191.903858 -214.74176)
		(end 191.883792 -214.74176)
		(width 0.101854)
		(layer "F.Cu")
		(net "M_G_CPU1_SB_DQ<13>")
	)
	(segment
		(start 196.532246 -215.166702)
		(end 196.531992 -215.166956)
		(width 0.20066)
		(layer "F.Cu")
		(net "M_G_CPU1_SB_DQ<13>")
	)
	(segment
		(start 191.883792 -214.74176)
		(end 191.539114 -214.74176)
		(width 0.20066)
		(layer "F.Cu")
		(net "M_G_CPU1_SB_DQ<13>")
	)
	(segment
		(start 179.252626 -217.378026)
		(end 178.656234 -217.378026)
		(width 0.18288)
		(layer "In6.Cu")
		(net "M_G_CPU1_SB_DQ<13>")
	)
	(segment
		(start 177.798984 -216.62771)
		(end 177.131726 -217.294968)
		(width 0.18288)
		(layer "In6.Cu")
		(net "M_G_CPU1_SB_DQ<13>")
	)
	(segment
		(start 130.638296 -232.844086)
		(end 130.623564 -232.852722)
		(width 0.088646)
		(layer "In6.Cu")
		(net "M_G_CPU1_SB_DQ<13>")
	)
	(segment
		(start 179.938426 -216.692226)
		(end 179.252626 -217.378026)
		(width 0.18288)
		(layer "In6.Cu")
		(net "M_G_CPU1_SB_DQ<13>")
	)
	(segment
		(start 169.733214 -216.03081)
		(end 168.40581 -216.03081)
		(width 0.18288)
		(layer "In6.Cu")
		(net "M_G_CPU1_SB_DQ<13>")
	)
	(segment
		(start 164.667692 -215.473026)
		(end 164.439092 -215.701626)
		(width 0.18288)
		(layer "In6.Cu")
		(net "M_G_CPU1_SB_DQ<13>")
	)
	(segment
		(start 182.389526 -215.485726)
		(end 181.183026 -216.692226)
		(width 0.18288)
		(layer "In6.Cu")
		(net "M_G_CPU1_SB_DQ<13>")
	)
	(segment
		(start 141.963902 -230.749094)
		(end 140.061442 -230.749094)
		(width 0.18288)
		(layer "In6.Cu")
		(net "M_G_CPU1_SB_DQ<13>")
	)
	(segment
		(start 159.098996 -216.11717)
		(end 158.771336 -216.11717)
		(width 0.18288)
		(layer "In6.Cu")
		(net "M_G_CPU1_SB_DQ<13>")
	)
	(segment
		(start 140.061442 -230.749094)
		(end 139.684252 -230.749094)
		(width 0.088646)
		(layer "In6.Cu")
		(net "M_G_CPU1_SB_DQ<13>")
	)
	(segment
		(start 127.804164 -232.852722)
		(end 127.798068 -232.856278)
		(width 0.088646)
		(layer "In6.Cu")
		(net "M_G_CPU1_SB_DQ<13>")
	)
	(segment
		(start 175.167544 -216.96807)
		(end 174.373286 -216.96807)
		(width 0.18288)
		(layer "In6.Cu")
		(net "M_G_CPU1_SB_DQ<13>")
	)
	(segment
		(start 178.496214 -216.81059)
		(end 178.313334 -216.62771)
		(width 0.18288)
		(layer "In6.Cu")
		(net "M_G_CPU1_SB_DQ<13>")
	)
	(segment
		(start 159.281876 -216.30005)
		(end 159.098996 -216.11717)
		(width 0.18288)
		(layer "In6.Cu")
		(net "M_G_CPU1_SB_DQ<13>")
	)
	(segment
		(start 158.588456 -216.30005)
		(end 158.588456 -216.425272)
		(width 0.18288)
		(layer "In6.Cu")
		(net "M_G_CPU1_SB_DQ<13>")
	)
	(segment
		(start 174.373286 -216.96807)
		(end 173.197266 -218.14409)
		(width 0.18288)
		(layer "In6.Cu")
		(net "M_G_CPU1_SB_DQ<13>")
	)
	(segment
		(start 131.578096 -232.844086)
		(end 131.563364 -232.852722)
		(width 0.088646)
		(layer "In6.Cu")
		(net "M_G_CPU1_SB_DQ<13>")
	)
	(segment
		(start 166.412926 -215.854026)
		(end 166.031926 -215.473026)
		(width 0.18288)
		(layer "In6.Cu")
		(net "M_G_CPU1_SB_DQ<13>")
	)
	(segment
		(start 166.031926 -215.473026)
		(end 164.667692 -215.473026)
		(width 0.18288)
		(layer "In6.Cu")
		(net "M_G_CPU1_SB_DQ<13>")
	)
	(segment
		(start 166.819326 -215.854026)
		(end 166.412926 -215.854026)
		(width 0.18288)
		(layer "In6.Cu")
		(net "M_G_CPU1_SB_DQ<13>")
	)
	(segment
		(start 175.494442 -217.294968)
		(end 175.167544 -216.96807)
		(width 0.18288)
		(layer "In6.Cu")
		(net "M_G_CPU1_SB_DQ<13>")
	)
	(segment
		(start 187.883546 -215.166702)
		(end 187.246006 -215.804242)
		(width 0.18288)
		(layer "In6.Cu")
		(net "M_G_CPU1_SB_DQ<13>")
	)
	(segment
		(start 159.281876 -216.425272)
		(end 159.281876 -216.30005)
		(width 0.18288)
		(layer "In6.Cu")
		(net "M_G_CPU1_SB_DQ<13>")
	)
	(segment
		(start 127.525272 -233.276394)
		(end 127.459486 -233.34218)
		(width 0.088646)
		(layer "In6.Cu")
		(net "M_G_CPU1_SB_DQ<13>")
	)
	(segment
		(start 158.405576 -216.608152)
		(end 156.104844 -216.608152)
		(width 0.18288)
		(layer "In6.Cu")
		(net "M_G_CPU1_SB_DQ<13>")
	)
	(segment
		(start 178.313334 -216.62771)
		(end 177.798984 -216.62771)
		(width 0.18288)
		(layer "In6.Cu")
		(net "M_G_CPU1_SB_DQ<13>")
	)
	(segment
		(start 177.131726 -217.294968)
		(end 175.494442 -217.294968)
		(width 0.18288)
		(layer "In6.Cu")
		(net "M_G_CPU1_SB_DQ<13>")
	)
	(segment
		(start 178.496214 -217.218006)
		(end 178.496214 -216.81059)
		(width 0.18288)
		(layer "In6.Cu")
		(net "M_G_CPU1_SB_DQ<13>")
	)
	(segment
		(start 167.848026 -215.473026)
		(end 167.200326 -215.473026)
		(width 0.18288)
		(layer "In6.Cu")
		(net "M_G_CPU1_SB_DQ<13>")
	)
	(segment
		(start 127.459486 -233.34218)
		(end 127.146812 -233.34218)
		(width 0.088646)
		(layer "In6.Cu")
		(net "M_G_CPU1_SB_DQ<13>")
	)
	(segment
		(start 181.183026 -216.692226)
		(end 179.938426 -216.692226)
		(width 0.18288)
		(layer "In6.Cu")
		(net "M_G_CPU1_SB_DQ<13>")
	)
	(segment
		(start 158.588456 -216.425272)
		(end 158.405576 -216.608152)
		(width 0.18288)
		(layer "In6.Cu")
		(net "M_G_CPU1_SB_DQ<13>")
	)
	(segment
		(start 129.698496 -232.844086)
		(end 129.683764 -232.852722)
		(width 0.088646)
		(layer "In6.Cu")
		(net "M_G_CPU1_SB_DQ<13>")
	)
	(segment
		(start 170.046396 -216.602564)
		(end 170.046396 -216.343992)
		(width 0.18288)
		(layer "In6.Cu")
		(net "M_G_CPU1_SB_DQ<13>")
	)
	(segment
		(start 170.53687 -217.093038)
		(end 170.065954 -217.563954)
		(width 0.18288)
		(layer "In6.Cu")
		(net "M_G_CPU1_SB_DQ<13>")
	)
	(segment
		(start 167.200326 -215.473026)
		(end 166.819326 -215.854026)
		(width 0.18288)
		(layer "In6.Cu")
		(net "M_G_CPU1_SB_DQ<13>")
	)
	(segment
		(start 187.246006 -215.804242)
		(end 184.049162 -215.804242)
		(width 0.18288)
		(layer "In6.Cu")
		(net "M_G_CPU1_SB_DQ<13>")
	)
	(segment
		(start 168.40581 -216.03081)
		(end 167.848026 -215.473026)
		(width 0.18288)
		(layer "In6.Cu")
		(net "M_G_CPU1_SB_DQ<13>")
	)
	(segment
		(start 178.656234 -217.378026)
		(end 178.496214 -217.218006)
		(width 0.18288)
		(layer "In6.Cu")
		(net "M_G_CPU1_SB_DQ<13>")
	)
	(segment
		(start 127.818896 -232.844086)
		(end 127.804164 -232.852722)
		(width 0.088646)
		(layer "In6.Cu")
		(net "M_G_CPU1_SB_DQ<13>")
	)
	(segment
		(start 139.684252 -230.749094)
		(end 138.98118 -231.452166)
		(width 0.088646)
		(layer "In6.Cu")
		(net "M_G_CPU1_SB_DQ<13>")
	)
	(segment
		(start 184.049162 -215.804242)
		(end 183.730646 -215.485726)
		(width 0.18288)
		(layer "In6.Cu")
		(net "M_G_CPU1_SB_DQ<13>")
	)
	(segment
		(start 136.449816 -232.518458)
		(end 136.449816 -232.528364)
		(width 0.088646)
		(layer "In6.Cu")
		(net "M_G_CPU1_SB_DQ<13>")
	)
	(segment
		(start 169.57548 -217.07348)
		(end 170.046396 -216.602564)
		(width 0.18288)
		(layer "In6.Cu")
		(net "M_G_CPU1_SB_DQ<13>")
	)
	(segment
		(start 133.068314 -232.852722)
		(end 133.0579 -232.846626)
		(width 0.088646)
		(layer "In6.Cu")
		(net "M_G_CPU1_SB_DQ<13>")
	)
	(segment
		(start 169.807382 -217.563954)
		(end 169.57548 -217.332052)
		(width 0.18288)
		(layer "In6.Cu")
		(net "M_G_CPU1_SB_DQ<13>")
	)
	(segment
		(start 171.846494 -218.14409)
		(end 170.795442 -217.093038)
		(width 0.18288)
		(layer "In6.Cu")
		(net "M_G_CPU1_SB_DQ<13>")
	)
	(segment
		(start 159.464756 -216.608152)
		(end 159.281876 -216.425272)
		(width 0.18288)
		(layer "In6.Cu")
		(net "M_G_CPU1_SB_DQ<13>")
	)
	(segment
		(start 161.303462 -216.608152)
		(end 159.464756 -216.608152)
		(width 0.18288)
		(layer "In6.Cu")
		(net "M_G_CPU1_SB_DQ<13>")
	)
	(segment
		(start 173.197266 -218.14409)
		(end 171.846494 -218.14409)
		(width 0.18288)
		(layer "In6.Cu")
		(net "M_G_CPU1_SB_DQ<13>")
	)
	(segment
		(start 158.771336 -216.11717)
		(end 158.588456 -216.30005)
		(width 0.18288)
		(layer "In6.Cu")
		(net "M_G_CPU1_SB_DQ<13>")
	)
	(segment
		(start 170.795442 -217.093038)
		(end 170.53687 -217.093038)
		(width 0.18288)
		(layer "In6.Cu")
		(net "M_G_CPU1_SB_DQ<13>")
	)
	(segment
		(start 136.271254 -232.847642)
		(end 136.262364 -232.852722)
		(width 0.088646)
		(layer "In6.Cu")
		(net "M_G_CPU1_SB_DQ<13>")
	)
	(segment
		(start 134.008368 -232.852722)
		(end 133.997954 -232.846626)
		(width 0.088646)
		(layer "In6.Cu")
		(net "M_G_CPU1_SB_DQ<13>")
	)
	(segment
		(start 164.439092 -215.701626)
		(end 162.209988 -215.701626)
		(width 0.18288)
		(layer "In6.Cu")
		(net "M_G_CPU1_SB_DQ<13>")
	)
	(segment
		(start 156.104844 -216.608152)
		(end 141.963902 -230.749094)
		(width 0.18288)
		(layer "In6.Cu")
		(net "M_G_CPU1_SB_DQ<13>")
	)
	(segment
		(start 183.730646 -215.485726)
		(end 182.389526 -215.485726)
		(width 0.18288)
		(layer "In6.Cu")
		(net "M_G_CPU1_SB_DQ<13>")
	)
	(segment
		(start 169.57548 -217.332052)
		(end 169.57548 -217.07348)
		(width 0.18288)
		(layer "In6.Cu")
		(net "M_G_CPU1_SB_DQ<13>")
	)
	(segment
		(start 170.046396 -216.343992)
		(end 169.733214 -216.03081)
		(width 0.18288)
		(layer "In6.Cu")
		(net "M_G_CPU1_SB_DQ<13>")
	)
	(segment
		(start 170.065954 -217.563954)
		(end 169.807382 -217.563954)
		(width 0.18288)
		(layer "In6.Cu")
		(net "M_G_CPU1_SB_DQ<13>")
	)
	(segment
		(start 162.209988 -215.701626)
		(end 161.303462 -216.608152)
		(width 0.18288)
		(layer "In6.Cu")
		(net "M_G_CPU1_SB_DQ<13>")
	)
	(segment
		(start 128.758696 -232.844086)
		(end 128.743964 -232.852722)
		(width 0.088646)
		(layer "In6.Cu")
		(net "M_G_CPU1_SB_DQ<13>")
	)
	(arc
		(start 128.743964 -232.852722)
		(mid 128.556766 -232.902865)
		(end 128.369568 -232.852722)
		(width 0.088646)
		(layer "In6.Cu")
		(net "M_G_CPU1_SB_DQ<13>")
	)
	(arc
		(start 133.44271 -232.852722)
		(mid 133.255512 -232.902865)
		(end 133.068314 -232.852722)
		(width 0.088646)
		(layer "In6.Cu")
		(net "M_G_CPU1_SB_DQ<13>")
	)
	(arc
		(start 134.948168 -232.852722)
		(mid 134.665466 -232.776946)
		(end 134.382764 -232.852722)
		(width 0.088646)
		(layer "In6.Cu")
		(net "M_G_CPU1_SB_DQ<13>")
	)
	(arc
		(start 137.672064 -232.038906)
		(mid 137.484866 -232.089049)
		(end 137.297668 -232.038906)
		(width 0.088646)
		(layer "In6.Cu")
		(net "M_G_CPU1_SB_DQ<13>")
	)
	(arc
		(start 132.503164 -232.852722)
		(mid 132.315966 -232.902865)
		(end 132.128768 -232.852722)
		(width 0.088646)
		(layer "In6.Cu")
		(net "M_G_CPU1_SB_DQ<13>")
	)
	(arc
		(start 127.798068 -232.856278)
		(mid 127.612613 -233.034473)
		(end 127.525272 -233.276394)
		(width 0.088646)
		(layer "In6.Cu")
		(net "M_G_CPU1_SB_DQ<13>")
	)
	(arc
		(start 136.262364 -232.852722)
		(mid 136.075166 -232.902865)
		(end 135.887968 -232.852722)
		(width 0.088646)
		(layer "In6.Cu")
		(net "M_G_CPU1_SB_DQ<13>")
	)
	(arc
		(start 128.369568 -232.852722)
		(mid 128.095369 -232.776887)
		(end 127.818896 -232.844086)
		(width 0.088646)
		(layer "In6.Cu")
		(net "M_G_CPU1_SB_DQ<13>")
	)
	(arc
		(start 130.249168 -232.852722)
		(mid 129.974969 -232.776887)
		(end 129.698496 -232.844086)
		(width 0.088646)
		(layer "In6.Cu")
		(net "M_G_CPU1_SB_DQ<13>")
	)
	(arc
		(start 138.757406 -231.979978)
		(mid 138.682584 -232.004374)
		(end 138.611864 -232.038906)
		(width 0.088646)
		(layer "In6.Cu")
		(net "M_G_CPU1_SB_DQ<13>")
	)
	(arc
		(start 138.965178 -231.645714)
		(mid 138.929114 -231.855034)
		(end 138.757406 -231.979978)
		(width 0.088646)
		(layer "In6.Cu")
		(net "M_G_CPU1_SB_DQ<13>")
	)
	(arc
		(start 136.449816 -232.528364)
		(mid 136.402137 -232.711264)
		(end 136.271254 -232.847642)
		(width 0.088646)
		(layer "In6.Cu")
		(net "M_G_CPU1_SB_DQ<13>")
	)
	(arc
		(start 137.297668 -232.038906)
		(mid 137.014966 -231.96313)
		(end 136.732264 -232.038906)
		(width 0.088646)
		(layer "In6.Cu")
		(net "M_G_CPU1_SB_DQ<13>")
	)
	(arc
		(start 132.128768 -232.852722)
		(mid 131.854569 -232.776887)
		(end 131.578096 -232.844086)
		(width 0.088646)
		(layer "In6.Cu")
		(net "M_G_CPU1_SB_DQ<13>")
	)
	(arc
		(start 138.611864 -232.038906)
		(mid 138.424666 -232.089049)
		(end 138.237468 -232.038906)
		(width 0.088646)
		(layer "In6.Cu")
		(net "M_G_CPU1_SB_DQ<13>")
	)
	(arc
		(start 133.0579 -232.846626)
		(mid 132.779722 -232.776903)
		(end 132.503164 -232.852722)
		(width 0.088646)
		(layer "In6.Cu")
		(net "M_G_CPU1_SB_DQ<13>")
	)
	(arc
		(start 130.623564 -232.852722)
		(mid 130.436366 -232.902865)
		(end 130.249168 -232.852722)
		(width 0.088646)
		(layer "In6.Cu")
		(net "M_G_CPU1_SB_DQ<13>")
	)
	(arc
		(start 138.949684 -231.535478)
		(mid 138.955386 -231.590884)
		(end 138.965178 -231.645714)
		(width 0.088646)
		(layer "In6.Cu")
		(net "M_G_CPU1_SB_DQ<13>")
	)
	(arc
		(start 135.887968 -232.852722)
		(mid 135.605266 -232.776946)
		(end 135.322564 -232.852722)
		(width 0.088646)
		(layer "In6.Cu")
		(net "M_G_CPU1_SB_DQ<13>")
	)
	(arc
		(start 129.683764 -232.852722)
		(mid 129.496566 -232.902865)
		(end 129.309368 -232.852722)
		(width 0.088646)
		(layer "In6.Cu")
		(net "M_G_CPU1_SB_DQ<13>")
	)
	(arc
		(start 129.309368 -232.852722)
		(mid 129.035169 -232.776887)
		(end 128.758696 -232.844086)
		(width 0.088646)
		(layer "In6.Cu")
		(net "M_G_CPU1_SB_DQ<13>")
	)
	(arc
		(start 131.563364 -232.852722)
		(mid 131.376166 -232.902865)
		(end 131.188968 -232.852722)
		(width 0.088646)
		(layer "In6.Cu")
		(net "M_G_CPU1_SB_DQ<13>")
	)
	(arc
		(start 138.98118 -231.452166)
		(mid 138.9564 -231.490405)
		(end 138.949684 -231.535478)
		(width 0.088646)
		(layer "In6.Cu")
		(net "M_G_CPU1_SB_DQ<13>")
	)
	(arc
		(start 136.732264 -232.038906)
		(mid 136.527929 -232.241511)
		(end 136.449816 -232.518458)
		(width 0.088646)
		(layer "In6.Cu")
		(net "M_G_CPU1_SB_DQ<13>")
	)
	(arc
		(start 133.997954 -232.846626)
		(mid 133.719522 -232.77678)
		(end 133.44271 -232.852722)
		(width 0.088646)
		(layer "In6.Cu")
		(net "M_G_CPU1_SB_DQ<13>")
	)
	(arc
		(start 131.188968 -232.852722)
		(mid 130.914769 -232.776887)
		(end 130.638296 -232.844086)
		(width 0.088646)
		(layer "In6.Cu")
		(net "M_G_CPU1_SB_DQ<13>")
	)
	(arc
		(start 134.382764 -232.852722)
		(mid 134.195566 -232.902865)
		(end 134.008368 -232.852722)
		(width 0.088646)
		(layer "In6.Cu")
		(net "M_G_CPU1_SB_DQ<13>")
	)
	(arc
		(start 138.237468 -232.038906)
		(mid 137.954766 -231.96313)
		(end 137.672064 -232.038906)
		(width 0.088646)
		(layer "In6.Cu")
		(net "M_G_CPU1_SB_DQ<13>")
	)
	(arc
		(start 135.322564 -232.852722)
		(mid 135.135366 -232.902865)
		(end 134.948168 -232.852722)
		(width 0.088646)
		(layer "In6.Cu")
		(net "M_G_CPU1_SB_DQ<13>")
	)
	(segment
		(start 194.092576 -216.441782)
		(end 191.930782 -216.441782)
		(width 0.1016)
		(layer "F.Cu")
		(net "M_G_CPU1_SB_DQ<12>")
	)
	(segment
		(start 191.883792 -216.441782)
		(end 191.539114 -216.441782)
		(width 0.20066)
		(layer "F.Cu")
		(net "M_G_CPU1_SB_DQ<12>")
	)
	(segment
		(start 191.539114 -216.441782)
		(end 191.421004 -216.559892)
		(width 0.20066)
		(layer "F.Cu")
		(net "M_G_CPU1_SB_DQ<12>")
	)
	(segment
		(start 194.940428 -216.866978)
		(end 194.508882 -216.435432)
		(width 0.20066)
		(layer "F.Cu")
		(net "M_G_CPU1_SB_DQ<12>")
	)
	(segment
		(start 191.233044 -217.11539)
		(end 190.75781 -217.11539)
		(width 0.20066)
		(layer "F.Cu")
		(net "M_G_CPU1_SB_DQ<12>")
	)
	(segment
		(start 126.676912 -234.69219)
		(end 126.677166 -234.691936)
		(width 0.20066)
		(layer "F.Cu")
		(net "M_G_CPU1_SB_DQ<12>")
	)
	(segment
		(start 194.098926 -216.435432)
		(end 194.092576 -216.441782)
		(width 0.1016)
		(layer "F.Cu")
		(net "M_G_CPU1_SB_DQ<12>")
	)
	(segment
		(start 191.421004 -216.92743)
		(end 191.233044 -217.11539)
		(width 0.20066)
		(layer "F.Cu")
		(net "M_G_CPU1_SB_DQ<12>")
	)
	(segment
		(start 190.75781 -217.11539)
		(end 190.509144 -216.866724)
		(width 0.20066)
		(layer "F.Cu")
		(net "M_G_CPU1_SB_DQ<12>")
	)
	(segment
		(start 196.531992 -216.866978)
		(end 194.940428 -216.866978)
		(width 0.20066)
		(layer "F.Cu")
		(net "M_G_CPU1_SB_DQ<12>")
	)
	(segment
		(start 191.421004 -216.559892)
		(end 191.421004 -216.92743)
		(width 0.20066)
		(layer "F.Cu")
		(net "M_G_CPU1_SB_DQ<12>")
	)
	(segment
		(start 194.508882 -216.435432)
		(end 194.098926 -216.435432)
		(width 0.20066)
		(layer "F.Cu")
		(net "M_G_CPU1_SB_DQ<12>")
	)
	(segment
		(start 190.509144 -216.866724)
		(end 188.988446 -216.866724)
		(width 0.20066)
		(layer "F.Cu")
		(net "M_G_CPU1_SB_DQ<12>")
	)
	(segment
		(start 196.532246 -216.866724)
		(end 196.531992 -216.866978)
		(width 0.20066)
		(layer "F.Cu")
		(net "M_G_CPU1_SB_DQ<12>")
	)
	(segment
		(start 126.677166 -234.691936)
		(end 126.677166 -234.15625)
		(width 0.20066)
		(layer "F.Cu")
		(net "M_G_CPU1_SB_DQ<12>")
	)
	(segment
		(start 188.988446 -216.866724)
		(end 187.883546 -216.866724)
		(width 0.20066)
		(layer "F.Cu")
		(net "M_G_CPU1_SB_DQ<12>")
	)
	(segment
		(start 191.930782 -216.441782)
		(end 191.883792 -216.441782)
		(width 0.101854)
		(layer "F.Cu")
		(net "M_G_CPU1_SB_DQ<12>")
	)
	(segment
		(start 167.902128 -218.704668)
		(end 167.676068 -218.704668)
		(width 0.18288)
		(layer "In6.Cu")
		(net "M_G_CPU1_SB_DQ<12>")
	)
	(segment
		(start 168.978072 -220.006672)
		(end 168.392602 -219.421202)
		(width 0.18288)
		(layer "In6.Cu")
		(net "M_G_CPU1_SB_DQ<12>")
	)
	(segment
		(start 170.975528 -219.016072)
		(end 170.602148 -219.016072)
		(width 0.18288)
		(layer "In6.Cu")
		(net "M_G_CPU1_SB_DQ<12>")
	)
	(segment
		(start 162.932872 -217.292174)
		(end 162.064954 -218.160092)
		(width 0.18288)
		(layer "In6.Cu")
		(net "M_G_CPU1_SB_DQ<12>")
	)
	(segment
		(start 140.174218 -231.779572)
		(end 140.040868 -231.779572)
		(width 0.088646)
		(layer "In6.Cu")
		(net "M_G_CPU1_SB_DQ<12>")
	)
	(segment
		(start 131.658614 -233.666538)
		(end 131.643882 -233.657902)
		(width 0.088646)
		(layer "In6.Cu")
		(net "M_G_CPU1_SB_DQ<12>")
	)
	(segment
		(start 139.930378 -231.890062)
		(end 139.930378 -231.994964)
		(width 0.088646)
		(layer "In6.Cu")
		(net "M_G_CPU1_SB_DQ<12>")
	)
	(segment
		(start 136.741154 -233.661458)
		(end 136.732264 -233.666538)
		(width 0.088646)
		(layer "In6.Cu")
		(net "M_G_CPU1_SB_DQ<12>")
	)
	(segment
		(start 127.306324 -233.682286)
		(end 126.677166 -234.15625)
		(width 0.088646)
		(layer "In6.Cu")
		(net "M_G_CPU1_SB_DQ<12>")
	)
	(segment
		(start 139.930378 -231.994964)
		(end 139.364466 -232.560876)
		(width 0.088646)
		(layer "In6.Cu")
		(net "M_G_CPU1_SB_DQ<12>")
	)
	(segment
		(start 186.089036 -217.297508)
		(end 185.801 -217.009472)
		(width 0.18288)
		(layer "In6.Cu")
		(net "M_G_CPU1_SB_DQ<12>")
	)
	(segment
		(start 175.731932 -218.992196)
		(end 175.316388 -218.992196)
		(width 0.18288)
		(layer "In6.Cu")
		(net "M_G_CPU1_SB_DQ<12>")
	)
	(segment
		(start 170.602148 -219.016072)
		(end 170.442128 -219.176092)
		(width 0.18288)
		(layer "In6.Cu")
		(net "M_G_CPU1_SB_DQ<12>")
	)
	(segment
		(start 170.442128 -219.176092)
		(end 170.442128 -219.668852)
		(width 0.18288)
		(layer "In6.Cu")
		(net "M_G_CPU1_SB_DQ<12>")
	)
	(segment
		(start 168.324022 -218.282774)
		(end 167.902128 -218.704668)
		(width 0.18288)
		(layer "In6.Cu")
		(net "M_G_CPU1_SB_DQ<12>")
	)
	(segment
		(start 166.263574 -217.292174)
		(end 162.932872 -217.292174)
		(width 0.18288)
		(layer "In6.Cu")
		(net "M_G_CPU1_SB_DQ<12>")
	)
	(segment
		(start 170.282108 -219.828872)
		(end 169.613326 -219.828872)
		(width 0.18288)
		(layer "In6.Cu")
		(net "M_G_CPU1_SB_DQ<12>")
	)
	(segment
		(start 127.33401 -233.666538)
		(end 127.306324 -233.682286)
		(width 0.088646)
		(layer "In6.Cu")
		(net "M_G_CPU1_SB_DQ<12>")
	)
	(segment
		(start 130.718814 -233.666538)
		(end 130.704082 -233.657902)
		(width 0.088646)
		(layer "In6.Cu")
		(net "M_G_CPU1_SB_DQ<12>")
	)
	(segment
		(start 182.256938 -217.294714)
		(end 181.089554 -218.462098)
		(width 0.18288)
		(layer "In6.Cu")
		(net "M_G_CPU1_SB_DQ<12>")
	)
	(segment
		(start 127.899414 -233.666538)
		(end 127.884682 -233.657902)
		(width 0.088646)
		(layer "In6.Cu")
		(net "M_G_CPU1_SB_DQ<12>")
	)
	(segment
		(start 185.801 -217.009472)
		(end 185.395616 -217.009472)
		(width 0.18288)
		(layer "In6.Cu")
		(net "M_G_CPU1_SB_DQ<12>")
	)
	(segment
		(start 175.038512 -219.270072)
		(end 174.622968 -219.270072)
		(width 0.18288)
		(layer "In6.Cu")
		(net "M_G_CPU1_SB_DQ<12>")
	)
	(segment
		(start 174.622968 -219.270072)
		(end 174.345092 -218.992196)
		(width 0.18288)
		(layer "In6.Cu")
		(net "M_G_CPU1_SB_DQ<12>")
	)
	(segment
		(start 128.839214 -233.666538)
		(end 128.824482 -233.657902)
		(width 0.088646)
		(layer "In6.Cu")
		(net "M_G_CPU1_SB_DQ<12>")
	)
	(segment
		(start 174.345092 -218.992196)
		(end 174.122588 -218.992196)
		(width 0.18288)
		(layer "In6.Cu")
		(net "M_G_CPU1_SB_DQ<12>")
	)
	(segment
		(start 178.157124 -218.462098)
		(end 177.627026 -218.992196)
		(width 0.18288)
		(layer "In6.Cu")
		(net "M_G_CPU1_SB_DQ<12>")
	)
	(segment
		(start 171.135548 -219.668852)
		(end 171.135548 -219.176092)
		(width 0.18288)
		(layer "In6.Cu")
		(net "M_G_CPU1_SB_DQ<12>")
	)
	(segment
		(start 187.452762 -217.297508)
		(end 186.089036 -217.297508)
		(width 0.18288)
		(layer "In6.Cu")
		(net "M_G_CPU1_SB_DQ<12>")
	)
	(segment
		(start 167.676068 -218.704668)
		(end 166.263574 -217.292174)
		(width 0.18288)
		(layer "In6.Cu")
		(net "M_G_CPU1_SB_DQ<12>")
	)
	(segment
		(start 185.395616 -217.009472)
		(end 185.110374 -217.294714)
		(width 0.18288)
		(layer "In6.Cu")
		(net "M_G_CPU1_SB_DQ<12>")
	)
	(segment
		(start 177.627026 -218.992196)
		(end 176.703228 -218.992196)
		(width 0.18288)
		(layer "In6.Cu")
		(net "M_G_CPU1_SB_DQ<12>")
	)
	(segment
		(start 139.364466 -232.560876)
		(end 139.150852 -232.790746)
		(width 0.088646)
		(layer "In6.Cu")
		(net "M_G_CPU1_SB_DQ<12>")
	)
	(segment
		(start 176.425352 -219.270072)
		(end 176.009808 -219.270072)
		(width 0.18288)
		(layer "In6.Cu")
		(net "M_G_CPU1_SB_DQ<12>")
	)
	(segment
		(start 132.598668 -233.666538)
		(end 132.588254 -233.660442)
		(width 0.088646)
		(layer "In6.Cu")
		(net "M_G_CPU1_SB_DQ<12>")
	)
	(segment
		(start 171.135548 -219.176092)
		(end 170.975528 -219.016072)
		(width 0.18288)
		(layer "In6.Cu")
		(net "M_G_CPU1_SB_DQ<12>")
	)
	(segment
		(start 168.392602 -219.195142)
		(end 168.814496 -218.773248)
		(width 0.18288)
		(layer "In6.Cu")
		(net "M_G_CPU1_SB_DQ<12>")
	)
	(segment
		(start 156.028898 -218.160092)
		(end 142.409418 -231.779572)
		(width 0.18288)
		(layer "In6.Cu")
		(net "M_G_CPU1_SB_DQ<12>")
	)
	(segment
		(start 185.110374 -217.294714)
		(end 182.256938 -217.294714)
		(width 0.18288)
		(layer "In6.Cu")
		(net "M_G_CPU1_SB_DQ<12>")
	)
	(segment
		(start 162.064954 -218.160092)
		(end 156.028898 -218.160092)
		(width 0.18288)
		(layer "In6.Cu")
		(net "M_G_CPU1_SB_DQ<12>")
	)
	(segment
		(start 142.409418 -231.779572)
		(end 140.174218 -231.779572)
		(width 0.18288)
		(layer "In6.Cu")
		(net "M_G_CPU1_SB_DQ<12>")
	)
	(segment
		(start 176.009808 -219.270072)
		(end 175.731932 -218.992196)
		(width 0.18288)
		(layer "In6.Cu")
		(net "M_G_CPU1_SB_DQ<12>")
	)
	(segment
		(start 168.814496 -218.773248)
		(end 168.814496 -218.547188)
		(width 0.18288)
		(layer "In6.Cu")
		(net "M_G_CPU1_SB_DQ<12>")
	)
	(segment
		(start 181.089554 -218.462098)
		(end 178.157124 -218.462098)
		(width 0.18288)
		(layer "In6.Cu")
		(net "M_G_CPU1_SB_DQ<12>")
	)
	(segment
		(start 168.814496 -218.547188)
		(end 168.550082 -218.282774)
		(width 0.18288)
		(layer "In6.Cu")
		(net "M_G_CPU1_SB_DQ<12>")
	)
	(segment
		(start 168.550082 -218.282774)
		(end 168.324022 -218.282774)
		(width 0.18288)
		(layer "In6.Cu")
		(net "M_G_CPU1_SB_DQ<12>")
	)
	(segment
		(start 136.919716 -233.332274)
		(end 136.919716 -233.34218)
		(width 0.088646)
		(layer "In6.Cu")
		(net "M_G_CPU1_SB_DQ<12>")
	)
	(segment
		(start 174.122588 -218.992196)
		(end 173.27245 -219.842334)
		(width 0.18288)
		(layer "In6.Cu")
		(net "M_G_CPU1_SB_DQ<12>")
	)
	(segment
		(start 168.392602 -219.421202)
		(end 168.392602 -219.195142)
		(width 0.18288)
		(layer "In6.Cu")
		(net "M_G_CPU1_SB_DQ<12>")
	)
	(segment
		(start 169.435526 -220.006672)
		(end 168.978072 -220.006672)
		(width 0.18288)
		(layer "In6.Cu")
		(net "M_G_CPU1_SB_DQ<12>")
	)
	(segment
		(start 187.883546 -216.866724)
		(end 187.452762 -217.297508)
		(width 0.18288)
		(layer "In6.Cu")
		(net "M_G_CPU1_SB_DQ<12>")
	)
	(segment
		(start 169.613326 -219.828872)
		(end 169.435526 -220.006672)
		(width 0.18288)
		(layer "In6.Cu")
		(net "M_G_CPU1_SB_DQ<12>")
	)
	(segment
		(start 170.442128 -219.668852)
		(end 170.282108 -219.828872)
		(width 0.18288)
		(layer "In6.Cu")
		(net "M_G_CPU1_SB_DQ<12>")
	)
	(segment
		(start 140.040868 -231.779572)
		(end 139.930378 -231.890062)
		(width 0.088646)
		(layer "In6.Cu")
		(net "M_G_CPU1_SB_DQ<12>")
	)
	(segment
		(start 171.30903 -219.842334)
		(end 171.135548 -219.668852)
		(width 0.18288)
		(layer "In6.Cu")
		(net "M_G_CPU1_SB_DQ<12>")
	)
	(segment
		(start 176.703228 -218.992196)
		(end 176.425352 -219.270072)
		(width 0.18288)
		(layer "In6.Cu")
		(net "M_G_CPU1_SB_DQ<12>")
	)
	(segment
		(start 175.316388 -218.992196)
		(end 175.038512 -219.270072)
		(width 0.18288)
		(layer "In6.Cu")
		(net "M_G_CPU1_SB_DQ<12>")
	)
	(segment
		(start 173.27245 -219.842334)
		(end 171.30903 -219.842334)
		(width 0.18288)
		(layer "In6.Cu")
		(net "M_G_CPU1_SB_DQ<12>")
	)
	(arc
		(start 135.418068 -233.666538)
		(mid 135.135366 -233.590796)
		(end 134.852664 -233.666538)
		(width 0.088646)
		(layer "In6.Cu")
		(net "M_G_CPU1_SB_DQ<12>")
	)
	(arc
		(start 128.824482 -233.657902)
		(mid 128.548041 -233.590736)
		(end 128.27381 -233.666538)
		(width 0.088646)
		(layer "In6.Cu")
		(net "M_G_CPU1_SB_DQ<12>")
	)
	(arc
		(start 137.202164 -232.852722)
		(mid 136.997829 -233.055327)
		(end 136.919716 -233.332274)
		(width 0.088646)
		(layer "In6.Cu")
		(net "M_G_CPU1_SB_DQ<12>")
	)
	(arc
		(start 138.141964 -232.852722)
		(mid 137.954766 -232.902865)
		(end 137.767568 -232.852722)
		(width 0.088646)
		(layer "In6.Cu")
		(net "M_G_CPU1_SB_DQ<12>")
	)
	(arc
		(start 127.884682 -233.657902)
		(mid 127.608241 -233.590736)
		(end 127.33401 -233.666538)
		(width 0.088646)
		(layer "In6.Cu")
		(net "M_G_CPU1_SB_DQ<12>")
	)
	(arc
		(start 136.357868 -233.666538)
		(mid 136.075166 -233.590796)
		(end 135.792464 -233.666538)
		(width 0.088646)
		(layer "In6.Cu")
		(net "M_G_CPU1_SB_DQ<12>")
	)
	(arc
		(start 138.879834 -232.90276)
		(mid 138.79055 -232.888249)
		(end 138.707368 -232.852722)
		(width 0.088646)
		(layer "In6.Cu")
		(net "M_G_CPU1_SB_DQ<12>")
	)
	(arc
		(start 132.973064 -233.666538)
		(mid 132.785866 -233.716681)
		(end 132.598668 -233.666538)
		(width 0.088646)
		(layer "In6.Cu")
		(net "M_G_CPU1_SB_DQ<12>")
	)
	(arc
		(start 133.912864 -233.666538)
		(mid 133.725666 -233.716681)
		(end 133.538468 -233.666538)
		(width 0.088646)
		(layer "In6.Cu")
		(net "M_G_CPU1_SB_DQ<12>")
	)
	(arc
		(start 131.643882 -233.657902)
		(mid 131.367441 -233.590736)
		(end 131.09321 -233.666538)
		(width 0.088646)
		(layer "In6.Cu")
		(net "M_G_CPU1_SB_DQ<12>")
	)
	(arc
		(start 130.15341 -233.666538)
		(mid 129.966212 -233.716681)
		(end 129.779014 -233.666538)
		(width 0.088646)
		(layer "In6.Cu")
		(net "M_G_CPU1_SB_DQ<12>")
	)
	(arc
		(start 135.792464 -233.666538)
		(mid 135.605266 -233.716681)
		(end 135.418068 -233.666538)
		(width 0.088646)
		(layer "In6.Cu")
		(net "M_G_CPU1_SB_DQ<12>")
	)
	(arc
		(start 133.538468 -233.666538)
		(mid 133.255766 -233.590796)
		(end 132.973064 -233.666538)
		(width 0.088646)
		(layer "In6.Cu")
		(net "M_G_CPU1_SB_DQ<12>")
	)
	(arc
		(start 129.21361 -233.666538)
		(mid 129.026412 -233.716681)
		(end 128.839214 -233.666538)
		(width 0.088646)
		(layer "In6.Cu")
		(net "M_G_CPU1_SB_DQ<12>")
	)
	(arc
		(start 128.27381 -233.666538)
		(mid 128.086612 -233.716681)
		(end 127.899414 -233.666538)
		(width 0.088646)
		(layer "In6.Cu")
		(net "M_G_CPU1_SB_DQ<12>")
	)
	(arc
		(start 130.704082 -233.657902)
		(mid 130.427641 -233.590736)
		(end 130.15341 -233.666538)
		(width 0.088646)
		(layer "In6.Cu")
		(net "M_G_CPU1_SB_DQ<12>")
	)
	(arc
		(start 136.732264 -233.666538)
		(mid 136.545066 -233.716681)
		(end 136.357868 -233.666538)
		(width 0.088646)
		(layer "In6.Cu")
		(net "M_G_CPU1_SB_DQ<12>")
	)
	(arc
		(start 129.779014 -233.666538)
		(mid 129.496312 -233.590796)
		(end 129.21361 -233.666538)
		(width 0.088646)
		(layer "In6.Cu")
		(net "M_G_CPU1_SB_DQ<12>")
	)
	(arc
		(start 131.09321 -233.666538)
		(mid 130.906012 -233.716681)
		(end 130.718814 -233.666538)
		(width 0.088646)
		(layer "In6.Cu")
		(net "M_G_CPU1_SB_DQ<12>")
	)
	(arc
		(start 134.478268 -233.666538)
		(mid 134.195566 -233.590796)
		(end 133.912864 -233.666538)
		(width 0.088646)
		(layer "In6.Cu")
		(net "M_G_CPU1_SB_DQ<12>")
	)
	(arc
		(start 136.919716 -233.34218)
		(mid 136.872037 -233.52508)
		(end 136.741154 -233.661458)
		(width 0.088646)
		(layer "In6.Cu")
		(net "M_G_CPU1_SB_DQ<12>")
	)
	(arc
		(start 139.150852 -232.790746)
		(mid 139.027583 -232.876335)
		(end 138.879834 -232.90276)
		(width 0.088646)
		(layer "In6.Cu")
		(net "M_G_CPU1_SB_DQ<12>")
	)
	(arc
		(start 132.03301 -233.666538)
		(mid 131.845812 -233.716681)
		(end 131.658614 -233.666538)
		(width 0.088646)
		(layer "In6.Cu")
		(net "M_G_CPU1_SB_DQ<12>")
	)
	(arc
		(start 138.707368 -232.852722)
		(mid 138.424666 -232.776946)
		(end 138.141964 -232.852722)
		(width 0.088646)
		(layer "In6.Cu")
		(net "M_G_CPU1_SB_DQ<12>")
	)
	(arc
		(start 137.767568 -232.852722)
		(mid 137.484866 -232.776946)
		(end 137.202164 -232.852722)
		(width 0.088646)
		(layer "In6.Cu")
		(net "M_G_CPU1_SB_DQ<12>")
	)
	(arc
		(start 132.588254 -233.660442)
		(mid 132.309822 -233.590628)
		(end 132.03301 -233.666538)
		(width 0.088646)
		(layer "In6.Cu")
		(net "M_G_CPU1_SB_DQ<12>")
	)
	(arc
		(start 134.852664 -233.666538)
		(mid 134.665466 -233.716681)
		(end 134.478268 -233.666538)
		(width 0.088646)
		(layer "In6.Cu")
		(net "M_G_CPU1_SB_DQ<12>")
	)
	(segment
		(start 197.542658 -220.703902)
		(end 198.223886 -220.703902)
		(width 0.20066)
		(layer "F.Cu")
		(net "M_G_CPU1_SB_DQ<11>")
	)
	(segment
		(start 198.662036 -220.0148)
		(end 199.046084 -220.0148)
		(width 0.20066)
		(layer "F.Cu")
		(net "M_G_CPU1_SB_DQ<11>")
	)
	(segment
		(start 198.427848 -220.49994)
		(end 198.427848 -220.248988)
		(width 0.20066)
		(layer "F.Cu")
		(net "M_G_CPU1_SB_DQ<11>")
	)
	(segment
		(start 198.427848 -220.248988)
		(end 198.662036 -220.0148)
		(width 0.20066)
		(layer "F.Cu")
		(net "M_G_CPU1_SB_DQ<11>")
	)
	(segment
		(start 128.556766 -236.319568)
		(end 128.556766 -235.783882)
		(width 0.20066)
		(layer "F.Cu")
		(net "M_G_CPU1_SB_DQ<11>")
	)
	(segment
		(start 195.522596 -220.69171)
		(end 197.530466 -220.69171)
		(width 0.1016)
		(layer "F.Cu")
		(net "M_G_CPU1_SB_DQ<11>")
	)
	(segment
		(start 128.556512 -236.319822)
		(end 128.556766 -236.319568)
		(width 0.20066)
		(layer "F.Cu")
		(net "M_G_CPU1_SB_DQ<11>")
	)
	(segment
		(start 199.298052 -220.266768)
		(end 200.632314 -220.266768)
		(width 0.20066)
		(layer "F.Cu")
		(net "M_G_CPU1_SB_DQ<11>")
	)
	(segment
		(start 191.983614 -220.266768)
		(end 193.088514 -220.266768)
		(width 0.20066)
		(layer "F.Cu")
		(net "M_G_CPU1_SB_DQ<11>")
	)
	(segment
		(start 197.530466 -220.69171)
		(end 197.542658 -220.703902)
		(width 0.1016)
		(layer "F.Cu")
		(net "M_G_CPU1_SB_DQ<11>")
	)
	(segment
		(start 195.218812 -220.698822)
		(end 195.510658 -220.698822)
		(width 0.20066)
		(layer "F.Cu")
		(net "M_G_CPU1_SB_DQ<11>")
	)
	(segment
		(start 195.510658 -220.698822)
		(end 195.515484 -220.698822)
		(width 0.101854)
		(layer "F.Cu")
		(net "M_G_CPU1_SB_DQ<11>")
	)
	(segment
		(start 198.223886 -220.703902)
		(end 198.427848 -220.49994)
		(width 0.20066)
		(layer "F.Cu")
		(net "M_G_CPU1_SB_DQ<11>")
	)
	(segment
		(start 193.088514 -220.266768)
		(end 194.786758 -220.266768)
		(width 0.20066)
		(layer "F.Cu")
		(net "M_G_CPU1_SB_DQ<11>")
	)
	(segment
		(start 199.046084 -220.0148)
		(end 199.298052 -220.266768)
		(width 0.20066)
		(layer "F.Cu")
		(net "M_G_CPU1_SB_DQ<11>")
	)
	(segment
		(start 195.515484 -220.698822)
		(end 195.522596 -220.69171)
		(width 0.1016)
		(layer "F.Cu")
		(net "M_G_CPU1_SB_DQ<11>")
	)
	(segment
		(start 194.786758 -220.266768)
		(end 195.218812 -220.698822)
		(width 0.20066)
		(layer "F.Cu")
		(net "M_G_CPU1_SB_DQ<11>")
	)
	(segment
		(start 180.815234 -222.991426)
		(end 180.370226 -222.991426)
		(width 0.18288)
		(layer "In6.Cu")
		(net "M_G_CPU1_SB_DQ<11>")
	)
	(segment
		(start 185.378598 -221.18701)
		(end 185.195718 -221.36989)
		(width 0.18288)
		(layer "In6.Cu")
		(net "M_G_CPU1_SB_DQ<11>")
	)
	(segment
		(start 186.072018 -221.881446)
		(end 185.889138 -221.698566)
		(width 0.18288)
		(layer "In6.Cu")
		(net "M_G_CPU1_SB_DQ<11>")
	)
	(segment
		(start 159.080962 -223.600264)
		(end 158.732982 -223.600264)
		(width 0.18288)
		(layer "In6.Cu")
		(net "M_G_CPU1_SB_DQ<11>")
	)
	(segment
		(start 185.889138 -221.698566)
		(end 185.889138 -221.36989)
		(width 0.18288)
		(layer "In6.Cu")
		(net "M_G_CPU1_SB_DQ<11>")
	)
	(segment
		(start 140.222478 -234.939332)
		(end 140.030708 -234.939332)
		(width 0.088646)
		(layer "In6.Cu")
		(net "M_G_CPU1_SB_DQ<11>")
	)
	(segment
		(start 185.889138 -221.36989)
		(end 185.706258 -221.18701)
		(width 0.18288)
		(layer "In6.Cu")
		(net "M_G_CPU1_SB_DQ<11>")
	)
	(segment
		(start 135.417814 -236.273594)
		(end 135.4074 -236.27969)
		(width 0.088646)
		(layer "In6.Cu")
		(net "M_G_CPU1_SB_DQ<11>")
	)
	(segment
		(start 139.929616 -235.040424)
		(end 139.929616 -235.231178)
		(width 0.088646)
		(layer "In6.Cu")
		(net "M_G_CPU1_SB_DQ<11>")
	)
	(segment
		(start 168.92143 -225.79203)
		(end 167.901366 -224.771966)
		(width 0.18288)
		(layer "In6.Cu")
		(net "M_G_CPU1_SB_DQ<11>")
	)
	(segment
		(start 159.266636 -223.126046)
		(end 159.266636 -223.41459)
		(width 0.18288)
		(layer "In6.Cu")
		(net "M_G_CPU1_SB_DQ<11>")
	)
	(segment
		(start 129.213864 -236.273594)
		(end 129.22123 -236.277658)
		(width 0.088646)
		(layer "In6.Cu")
		(net "M_G_CPU1_SB_DQ<11>")
	)
	(segment
		(start 128.55702 -235.784136)
		(end 128.556766 -235.783882)
		(width 0.088646)
		(layer "In6.Cu")
		(net "M_G_CPU1_SB_DQ<11>")
	)
	(segment
		(start 166.702994 -224.954846)
		(end 166.702994 -225.3869)
		(width 0.18288)
		(layer "In6.Cu")
		(net "M_G_CPU1_SB_DQ<11>")
	)
	(segment
		(start 179.379626 -223.982026)
		(end 178.328828 -223.982026)
		(width 0.18288)
		(layer "In6.Cu")
		(net "M_G_CPU1_SB_DQ<11>")
	)
	(segment
		(start 140.030708 -234.939332)
		(end 139.929616 -235.040424)
		(width 0.088646)
		(layer "In6.Cu")
		(net "M_G_CPU1_SB_DQ<11>")
	)
	(segment
		(start 185.012838 -221.881446)
		(end 183.778906 -221.881446)
		(width 0.18288)
		(layer "In6.Cu")
		(net "M_G_CPU1_SB_DQ<11>")
	)
	(segment
		(start 130.718814 -236.273594)
		(end 130.704082 -236.28223)
		(width 0.088646)
		(layer "In6.Cu")
		(net "M_G_CPU1_SB_DQ<11>")
	)
	(segment
		(start 166.520114 -225.56978)
		(end 166.192454 -225.56978)
		(width 0.18288)
		(layer "In6.Cu")
		(net "M_G_CPU1_SB_DQ<11>")
	)
	(segment
		(start 129.22123 -236.277658)
		(end 129.115058 -236.215428)
		(width 0.088646)
		(layer "In6.Cu")
		(net "M_G_CPU1_SB_DQ<11>")
	)
	(segment
		(start 163.476178 -223.24187)
		(end 161.29127 -223.24187)
		(width 0.18288)
		(layer "In6.Cu")
		(net "M_G_CPU1_SB_DQ<11>")
	)
	(segment
		(start 166.192454 -225.56978)
		(end 166.009574 -225.3869)
		(width 0.18288)
		(layer "In6.Cu")
		(net "M_G_CPU1_SB_DQ<11>")
	)
	(segment
		(start 158.562548 -223.126046)
		(end 158.402528 -222.966026)
		(width 0.18288)
		(layer "In6.Cu")
		(net "M_G_CPU1_SB_DQ<11>")
	)
	(segment
		(start 158.402528 -222.966026)
		(end 155.975558 -222.966026)
		(width 0.18288)
		(layer "In6.Cu")
		(net "M_G_CPU1_SB_DQ<11>")
	)
	(segment
		(start 138.237214 -236.273594)
		(end 138.222482 -236.28223)
		(width 0.088646)
		(layer "In6.Cu")
		(net "M_G_CPU1_SB_DQ<11>")
	)
	(segment
		(start 139.929616 -235.231178)
		(end 139.625578 -235.535216)
		(width 0.088646)
		(layer "In6.Cu")
		(net "M_G_CPU1_SB_DQ<11>")
	)
	(segment
		(start 165.006274 -224.771966)
		(end 163.476178 -223.24187)
		(width 0.18288)
		(layer "In6.Cu")
		(net "M_G_CPU1_SB_DQ<11>")
	)
	(segment
		(start 133.538468 -236.273594)
		(end 133.528054 -236.27969)
		(width 0.088646)
		(layer "In6.Cu")
		(net "M_G_CPU1_SB_DQ<11>")
	)
	(segment
		(start 129.779014 -236.273594)
		(end 129.7686 -236.27969)
		(width 0.088646)
		(layer "In6.Cu")
		(net "M_G_CPU1_SB_DQ<11>")
	)
	(segment
		(start 187.37199 -221.881446)
		(end 186.072018 -221.881446)
		(width 0.18288)
		(layer "In6.Cu")
		(net "M_G_CPU1_SB_DQ<11>")
	)
	(segment
		(start 185.195718 -221.36989)
		(end 185.195718 -221.698566)
		(width 0.18288)
		(layer "In6.Cu")
		(net "M_G_CPU1_SB_DQ<11>")
	)
	(segment
		(start 167.901366 -224.771966)
		(end 166.885874 -224.771966)
		(width 0.18288)
		(layer "In6.Cu")
		(net "M_G_CPU1_SB_DQ<11>")
	)
	(segment
		(start 136.357614 -236.273594)
		(end 136.342882 -236.28223)
		(width 0.088646)
		(layer "In6.Cu")
		(net "M_G_CPU1_SB_DQ<11>")
	)
	(segment
		(start 165.826694 -224.771966)
		(end 165.006274 -224.771966)
		(width 0.18288)
		(layer "In6.Cu")
		(net "M_G_CPU1_SB_DQ<11>")
	)
	(segment
		(start 161.015426 -222.966026)
		(end 159.426656 -222.966026)
		(width 0.18288)
		(layer "In6.Cu")
		(net "M_G_CPU1_SB_DQ<11>")
	)
	(segment
		(start 174.27956 -224.941892)
		(end 173.429422 -225.79203)
		(width 0.18288)
		(layer "In6.Cu")
		(net "M_G_CPU1_SB_DQ<11>")
	)
	(segment
		(start 159.426656 -222.966026)
		(end 159.266636 -223.126046)
		(width 0.18288)
		(layer "In6.Cu")
		(net "M_G_CPU1_SB_DQ<11>")
	)
	(segment
		(start 185.195718 -221.698566)
		(end 185.012838 -221.881446)
		(width 0.18288)
		(layer "In6.Cu")
		(net "M_G_CPU1_SB_DQ<11>")
	)
	(segment
		(start 190.70828 -221.542102)
		(end 187.711334 -221.542102)
		(width 0.18288)
		(layer "In6.Cu")
		(net "M_G_CPU1_SB_DQ<11>")
	)
	(segment
		(start 144.002252 -234.939332)
		(end 140.222478 -234.939332)
		(width 0.18288)
		(layer "In6.Cu")
		(net "M_G_CPU1_SB_DQ<11>")
	)
	(segment
		(start 173.429422 -225.79203)
		(end 168.92143 -225.79203)
		(width 0.18288)
		(layer "In6.Cu")
		(net "M_G_CPU1_SB_DQ<11>")
	)
	(segment
		(start 138.707368 -235.459524)
		(end 138.698478 -235.464604)
		(width 0.088646)
		(layer "In6.Cu")
		(net "M_G_CPU1_SB_DQ<11>")
	)
	(segment
		(start 166.009574 -224.954846)
		(end 165.826694 -224.771966)
		(width 0.18288)
		(layer "In6.Cu")
		(net "M_G_CPU1_SB_DQ<11>")
	)
	(segment
		(start 137.297414 -236.273594)
		(end 137.282682 -236.28223)
		(width 0.088646)
		(layer "In6.Cu")
		(net "M_G_CPU1_SB_DQ<11>")
	)
	(segment
		(start 155.975558 -222.966026)
		(end 144.002252 -234.939332)
		(width 0.18288)
		(layer "In6.Cu")
		(net "M_G_CPU1_SB_DQ<11>")
	)
	(segment
		(start 183.778906 -221.881446)
		(end 183.088026 -222.572326)
		(width 0.18288)
		(layer "In6.Cu")
		(net "M_G_CPU1_SB_DQ<11>")
	)
	(segment
		(start 191.983614 -220.266768)
		(end 190.70828 -221.542102)
		(width 0.18288)
		(layer "In6.Cu")
		(net "M_G_CPU1_SB_DQ<11>")
	)
	(segment
		(start 131.658614 -236.273594)
		(end 131.643882 -236.28223)
		(width 0.088646)
		(layer "In6.Cu")
		(net "M_G_CPU1_SB_DQ<11>")
	)
	(segment
		(start 139.625578 -235.535216)
		(end 139.364212 -235.535216)
		(width 0.088646)
		(layer "In6.Cu")
		(net "M_G_CPU1_SB_DQ<11>")
	)
	(segment
		(start 185.706258 -221.18701)
		(end 185.378598 -221.18701)
		(width 0.18288)
		(layer "In6.Cu")
		(net "M_G_CPU1_SB_DQ<11>")
	)
	(segment
		(start 159.266636 -223.41459)
		(end 159.080962 -223.600264)
		(width 0.18288)
		(layer "In6.Cu")
		(net "M_G_CPU1_SB_DQ<11>")
	)
	(segment
		(start 178.328828 -223.982026)
		(end 177.368962 -224.941892)
		(width 0.18288)
		(layer "In6.Cu")
		(net "M_G_CPU1_SB_DQ<11>")
	)
	(segment
		(start 166.885874 -224.771966)
		(end 166.702994 -224.954846)
		(width 0.18288)
		(layer "In6.Cu")
		(net "M_G_CPU1_SB_DQ<11>")
	)
	(segment
		(start 166.009574 -225.3869)
		(end 166.009574 -224.954846)
		(width 0.18288)
		(layer "In6.Cu")
		(net "M_G_CPU1_SB_DQ<11>")
	)
	(segment
		(start 161.29127 -223.24187)
		(end 161.015426 -222.966026)
		(width 0.18288)
		(layer "In6.Cu")
		(net "M_G_CPU1_SB_DQ<11>")
	)
	(segment
		(start 138.519916 -235.783882)
		(end 138.519916 -235.798106)
		(width 0.088646)
		(layer "In6.Cu")
		(net "M_G_CPU1_SB_DQ<11>")
	)
	(segment
		(start 177.368962 -224.941892)
		(end 174.27956 -224.941892)
		(width 0.18288)
		(layer "In6.Cu")
		(net "M_G_CPU1_SB_DQ<11>")
	)
	(segment
		(start 180.370226 -222.991426)
		(end 179.379626 -223.982026)
		(width 0.18288)
		(layer "In6.Cu")
		(net "M_G_CPU1_SB_DQ<11>")
	)
	(segment
		(start 187.711334 -221.542102)
		(end 187.37199 -221.881446)
		(width 0.18288)
		(layer "In6.Cu")
		(net "M_G_CPU1_SB_DQ<11>")
	)
	(segment
		(start 166.702994 -225.3869)
		(end 166.520114 -225.56978)
		(width 0.18288)
		(layer "In6.Cu")
		(net "M_G_CPU1_SB_DQ<11>")
	)
	(segment
		(start 158.562548 -223.42983)
		(end 158.562548 -223.126046)
		(width 0.18288)
		(layer "In6.Cu")
		(net "M_G_CPU1_SB_DQ<11>")
	)
	(segment
		(start 181.234334 -222.572326)
		(end 180.815234 -222.991426)
		(width 0.18288)
		(layer "In6.Cu")
		(net "M_G_CPU1_SB_DQ<11>")
	)
	(segment
		(start 158.732982 -223.600264)
		(end 158.562548 -223.42983)
		(width 0.18288)
		(layer "In6.Cu")
		(net "M_G_CPU1_SB_DQ<11>")
	)
	(segment
		(start 183.088026 -222.572326)
		(end 181.234334 -222.572326)
		(width 0.18288)
		(layer "In6.Cu")
		(net "M_G_CPU1_SB_DQ<11>")
	)
	(arc
		(start 137.282682 -236.28223)
		(mid 137.006241 -236.349396)
		(end 136.73201 -236.273594)
		(width 0.088646)
		(layer "In6.Cu")
		(net "M_G_CPU1_SB_DQ<11>")
	)
	(arc
		(start 138.519916 -235.798106)
		(mid 138.440697 -236.072791)
		(end 138.237214 -236.273594)
		(width 0.088646)
		(layer "In6.Cu")
		(net "M_G_CPU1_SB_DQ<11>")
	)
	(arc
		(start 139.081764 -235.459524)
		(mid 138.894566 -235.409381)
		(end 138.707368 -235.459524)
		(width 0.088646)
		(layer "In6.Cu")
		(net "M_G_CPU1_SB_DQ<11>")
	)
	(arc
		(start 139.364212 -235.535216)
		(mid 139.218004 -235.515967)
		(end 139.081764 -235.459524)
		(width 0.088646)
		(layer "In6.Cu")
		(net "M_G_CPU1_SB_DQ<11>")
	)
	(arc
		(start 135.79221 -236.273594)
		(mid 135.605012 -236.223451)
		(end 135.417814 -236.273594)
		(width 0.088646)
		(layer "In6.Cu")
		(net "M_G_CPU1_SB_DQ<11>")
	)
	(arc
		(start 132.598414 -236.273594)
		(mid 132.315712 -236.349336)
		(end 132.03301 -236.273594)
		(width 0.088646)
		(layer "In6.Cu")
		(net "M_G_CPU1_SB_DQ<11>")
	)
	(arc
		(start 129.7686 -236.27969)
		(mid 129.490422 -236.349382)
		(end 129.213864 -236.273594)
		(width 0.088646)
		(layer "In6.Cu")
		(net "M_G_CPU1_SB_DQ<11>")
	)
	(arc
		(start 131.643882 -236.28223)
		(mid 131.367441 -236.349396)
		(end 131.09321 -236.273594)
		(width 0.088646)
		(layer "In6.Cu")
		(net "M_G_CPU1_SB_DQ<11>")
	)
	(arc
		(start 136.342882 -236.28223)
		(mid 136.066441 -236.349396)
		(end 135.79221 -236.273594)
		(width 0.088646)
		(layer "In6.Cu")
		(net "M_G_CPU1_SB_DQ<11>")
	)
	(arc
		(start 130.15341 -236.273594)
		(mid 129.966212 -236.223451)
		(end 129.779014 -236.273594)
		(width 0.088646)
		(layer "In6.Cu")
		(net "M_G_CPU1_SB_DQ<11>")
	)
	(arc
		(start 132.97281 -236.273594)
		(mid 132.785612 -236.223451)
		(end 132.598414 -236.273594)
		(width 0.088646)
		(layer "In6.Cu")
		(net "M_G_CPU1_SB_DQ<11>")
	)
	(arc
		(start 130.704082 -236.28223)
		(mid 130.427641 -236.349396)
		(end 130.15341 -236.273594)
		(width 0.088646)
		(layer "In6.Cu")
		(net "M_G_CPU1_SB_DQ<11>")
	)
	(arc
		(start 133.912864 -236.273594)
		(mid 133.725666 -236.223451)
		(end 133.538468 -236.273594)
		(width 0.088646)
		(layer "In6.Cu")
		(net "M_G_CPU1_SB_DQ<11>")
	)
	(arc
		(start 135.4074 -236.27969)
		(mid 135.129222 -236.349382)
		(end 134.852664 -236.273594)
		(width 0.088646)
		(layer "In6.Cu")
		(net "M_G_CPU1_SB_DQ<11>")
	)
	(arc
		(start 131.09321 -236.273594)
		(mid 130.906012 -236.223451)
		(end 130.718814 -236.273594)
		(width 0.088646)
		(layer "In6.Cu")
		(net "M_G_CPU1_SB_DQ<11>")
	)
	(arc
		(start 134.852664 -236.273594)
		(mid 134.665466 -236.223451)
		(end 134.478268 -236.273594)
		(width 0.088646)
		(layer "In6.Cu")
		(net "M_G_CPU1_SB_DQ<11>")
	)
	(arc
		(start 134.478268 -236.273594)
		(mid 134.195566 -236.349336)
		(end 133.912864 -236.273594)
		(width 0.088646)
		(layer "In6.Cu")
		(net "M_G_CPU1_SB_DQ<11>")
	)
	(arc
		(start 129.115058 -236.215428)
		(mid 128.822275 -236.017591)
		(end 128.55702 -235.784136)
		(width 0.088646)
		(layer "In6.Cu")
		(net "M_G_CPU1_SB_DQ<11>")
	)
	(arc
		(start 138.698478 -235.464604)
		(mid 138.567564 -235.600964)
		(end 138.519916 -235.783882)
		(width 0.088646)
		(layer "In6.Cu")
		(net "M_G_CPU1_SB_DQ<11>")
	)
	(arc
		(start 137.67181 -236.273594)
		(mid 137.484612 -236.223451)
		(end 137.297414 -236.273594)
		(width 0.088646)
		(layer "In6.Cu")
		(net "M_G_CPU1_SB_DQ<11>")
	)
	(arc
		(start 132.03301 -236.273594)
		(mid 131.845812 -236.223451)
		(end 131.658614 -236.273594)
		(width 0.088646)
		(layer "In6.Cu")
		(net "M_G_CPU1_SB_DQ<11>")
	)
	(arc
		(start 133.528054 -236.27969)
		(mid 133.249622 -236.349504)
		(end 132.97281 -236.273594)
		(width 0.088646)
		(layer "In6.Cu")
		(net "M_G_CPU1_SB_DQ<11>")
	)
	(arc
		(start 138.222482 -236.28223)
		(mid 137.946041 -236.349396)
		(end 137.67181 -236.273594)
		(width 0.088646)
		(layer "In6.Cu")
		(net "M_G_CPU1_SB_DQ<11>")
	)
	(arc
		(start 136.73201 -236.273594)
		(mid 136.544812 -236.223451)
		(end 136.357614 -236.273594)
		(width 0.088646)
		(layer "In6.Cu")
		(net "M_G_CPU1_SB_DQ<11>")
	)
	(segment
		(start 199.046084 -221.714822)
		(end 199.298052 -221.96679)
		(width 0.20066)
		(layer "F.Cu")
		(net "M_G_CPU1_SB_DQ<10>")
	)
	(segment
		(start 198.662036 -221.714822)
		(end 199.046084 -221.714822)
		(width 0.20066)
		(layer "F.Cu")
		(net "M_G_CPU1_SB_DQ<10>")
	)
	(segment
		(start 195.522596 -222.391732)
		(end 197.530466 -222.391732)
		(width 0.1016)
		(layer "F.Cu")
		(net "M_G_CPU1_SB_DQ<10>")
	)
	(segment
		(start 198.223886 -222.403924)
		(end 198.427848 -222.199962)
		(width 0.20066)
		(layer "F.Cu")
		(net "M_G_CPU1_SB_DQ<10>")
	)
	(segment
		(start 199.298052 -221.96679)
		(end 200.632314 -221.96679)
		(width 0.20066)
		(layer "F.Cu")
		(net "M_G_CPU1_SB_DQ<10>")
	)
	(segment
		(start 197.530466 -222.391732)
		(end 197.542658 -222.403924)
		(width 0.1016)
		(layer "F.Cu")
		(net "M_G_CPU1_SB_DQ<10>")
	)
	(segment
		(start 198.427848 -222.199962)
		(end 198.427848 -221.94901)
		(width 0.20066)
		(layer "F.Cu")
		(net "M_G_CPU1_SB_DQ<10>")
	)
	(segment
		(start 195.515484 -222.398844)
		(end 195.522596 -222.391732)
		(width 0.1016)
		(layer "F.Cu")
		(net "M_G_CPU1_SB_DQ<10>")
	)
	(segment
		(start 127.147066 -237.133892)
		(end 127.146812 -237.133638)
		(width 0.20066)
		(layer "F.Cu")
		(net "M_G_CPU1_SB_DQ<10>")
	)
	(segment
		(start 193.088514 -221.96679)
		(end 194.786758 -221.96679)
		(width 0.20066)
		(layer "F.Cu")
		(net "M_G_CPU1_SB_DQ<10>")
	)
	(segment
		(start 197.542658 -222.403924)
		(end 198.223886 -222.403924)
		(width 0.20066)
		(layer "F.Cu")
		(net "M_G_CPU1_SB_DQ<10>")
	)
	(segment
		(start 191.983614 -221.96679)
		(end 193.088514 -221.96679)
		(width 0.20066)
		(layer "F.Cu")
		(net "M_G_CPU1_SB_DQ<10>")
	)
	(segment
		(start 127.146812 -237.133638)
		(end 127.146812 -236.597952)
		(width 0.20066)
		(layer "F.Cu")
		(net "M_G_CPU1_SB_DQ<10>")
	)
	(segment
		(start 198.427848 -221.94901)
		(end 198.662036 -221.714822)
		(width 0.20066)
		(layer "F.Cu")
		(net "M_G_CPU1_SB_DQ<10>")
	)
	(segment
		(start 195.218812 -222.398844)
		(end 195.510658 -222.398844)
		(width 0.20066)
		(layer "F.Cu")
		(net "M_G_CPU1_SB_DQ<10>")
	)
	(segment
		(start 194.786758 -221.96679)
		(end 195.218812 -222.398844)
		(width 0.20066)
		(layer "F.Cu")
		(net "M_G_CPU1_SB_DQ<10>")
	)
	(segment
		(start 195.510658 -222.398844)
		(end 195.515484 -222.398844)
		(width 0.101854)
		(layer "F.Cu")
		(net "M_G_CPU1_SB_DQ<10>")
	)
	(segment
		(start 137.297414 -236.922056)
		(end 137.282682 -236.91342)
		(width 0.088646)
		(layer "In6.Cu")
		(net "M_G_CPU1_SB_DQ<10>")
	)
	(segment
		(start 170.069256 -226.526852)
		(end 170.069256 -226.539806)
		(width 0.18288)
		(layer "In6.Cu")
		(net "M_G_CPU1_SB_DQ<10>")
	)
	(segment
		(start 171.033186 -226.366832)
		(end 170.229276 -226.366832)
		(width 0.18288)
		(layer "In6.Cu")
		(net "M_G_CPU1_SB_DQ<10>")
	)
	(segment
		(start 169.909236 -226.699826)
		(end 168.864026 -226.699826)
		(width 0.18288)
		(layer "In6.Cu")
		(net "M_G_CPU1_SB_DQ<10>")
	)
	(segment
		(start 171.308522 -226.642168)
		(end 171.033186 -226.366832)
		(width 0.18288)
		(layer "In6.Cu")
		(net "M_G_CPU1_SB_DQ<10>")
	)
	(segment
		(start 136.357614 -236.922056)
		(end 136.342882 -236.91342)
		(width 0.088646)
		(layer "In6.Cu")
		(net "M_G_CPU1_SB_DQ<10>")
	)
	(segment
		(start 128.839468 -236.922056)
		(end 128.825244 -236.913928)
		(width 0.088646)
		(layer "In6.Cu")
		(net "M_G_CPU1_SB_DQ<10>")
	)
	(segment
		(start 163.12007 -224.985072)
		(end 162.226752 -224.091754)
		(width 0.18288)
		(layer "In6.Cu")
		(net "M_G_CPU1_SB_DQ<10>")
	)
	(segment
		(start 132.598414 -236.922056)
		(end 132.583682 -236.91342)
		(width 0.088646)
		(layer "In6.Cu")
		(net "M_G_CPU1_SB_DQ<10>")
	)
	(segment
		(start 170.069256 -226.539806)
		(end 169.909236 -226.699826)
		(width 0.18288)
		(layer "In6.Cu")
		(net "M_G_CPU1_SB_DQ<10>")
	)
	(segment
		(start 138.625834 -236.913928)
		(end 138.61161 -236.922056)
		(width 0.088646)
		(layer "In6.Cu")
		(net "M_G_CPU1_SB_DQ<10>")
	)
	(segment
		(start 160.53308 -224.4217)
		(end 158.525972 -224.4217)
		(width 0.18288)
		(layer "In6.Cu")
		(net "M_G_CPU1_SB_DQ<10>")
	)
	(segment
		(start 168.864026 -226.699826)
		(end 168.26103 -226.09683)
		(width 0.18288)
		(layer "In6.Cu")
		(net "M_G_CPU1_SB_DQ<10>")
	)
	(segment
		(start 138.799062 -236.583728)
		(end 138.799062 -236.597952)
		(width 0.088646)
		(layer "In6.Cu")
		(net "M_G_CPU1_SB_DQ<10>")
	)
	(segment
		(start 130.718814 -236.922056)
		(end 130.704082 -236.91342)
		(width 0.088646)
		(layer "In6.Cu")
		(net "M_G_CPU1_SB_DQ<10>")
	)
	(segment
		(start 177.315368 -225.79203)
		(end 174.33671 -225.79203)
		(width 0.18288)
		(layer "In6.Cu")
		(net "M_G_CPU1_SB_DQ<10>")
	)
	(segment
		(start 140.000736 -235.439204)
		(end 139.412472 -236.027468)
		(width 0.088646)
		(layer "In6.Cu")
		(net "M_G_CPU1_SB_DQ<10>")
	)
	(segment
		(start 135.417814 -236.922056)
		(end 135.4074 -236.91596)
		(width 0.088646)
		(layer "In6.Cu")
		(net "M_G_CPU1_SB_DQ<10>")
	)
	(segment
		(start 155.640532 -224.091754)
		(end 144.293082 -235.439204)
		(width 0.18288)
		(layer "In6.Cu")
		(net "M_G_CPU1_SB_DQ<10>")
	)
	(segment
		(start 158.196026 -224.091754)
		(end 155.640532 -224.091754)
		(width 0.18288)
		(layer "In6.Cu")
		(net "M_G_CPU1_SB_DQ<10>")
	)
	(segment
		(start 140.222478 -235.439204)
		(end 140.000736 -235.439204)
		(width 0.088646)
		(layer "In6.Cu")
		(net "M_G_CPU1_SB_DQ<10>")
	)
	(segment
		(start 129.779014 -236.922056)
		(end 129.7686 -236.91596)
		(width 0.088646)
		(layer "In6.Cu")
		(net "M_G_CPU1_SB_DQ<10>")
	)
	(segment
		(start 128.652016 -236.597952)
		(end 128.652016 -236.53242)
		(width 0.088646)
		(layer "In6.Cu")
		(net "M_G_CPU1_SB_DQ<10>")
	)
	(segment
		(start 188.816996 -222.39224)
		(end 184.119012 -222.39224)
		(width 0.18288)
		(layer "In6.Cu")
		(net "M_G_CPU1_SB_DQ<10>")
	)
	(segment
		(start 180.335682 -224.312226)
		(end 180.014626 -224.312226)
		(width 0.18288)
		(layer "In6.Cu")
		(net "M_G_CPU1_SB_DQ<10>")
	)
	(segment
		(start 174.33671 -225.79203)
		(end 173.486572 -226.642168)
		(width 0.18288)
		(layer "In6.Cu")
		(net "M_G_CPU1_SB_DQ<10>")
	)
	(segment
		(start 181.504082 -223.143826)
		(end 180.335682 -224.312226)
		(width 0.18288)
		(layer "In6.Cu")
		(net "M_G_CPU1_SB_DQ<10>")
	)
	(segment
		(start 184.119012 -222.39224)
		(end 183.367426 -223.143826)
		(width 0.18288)
		(layer "In6.Cu")
		(net "M_G_CPU1_SB_DQ<10>")
	)
	(segment
		(start 131.658614 -236.922056)
		(end 131.643882 -236.91342)
		(width 0.088646)
		(layer "In6.Cu")
		(net "M_G_CPU1_SB_DQ<10>")
	)
	(segment
		(start 165.272974 -226.09683)
		(end 164.161216 -224.985072)
		(width 0.18288)
		(layer "In6.Cu")
		(net "M_G_CPU1_SB_DQ<10>")
	)
	(segment
		(start 168.26103 -226.09683)
		(end 165.272974 -226.09683)
		(width 0.18288)
		(layer "In6.Cu")
		(net "M_G_CPU1_SB_DQ<10>")
	)
	(segment
		(start 179.201826 -225.125026)
		(end 177.982372 -225.125026)
		(width 0.18288)
		(layer "In6.Cu")
		(net "M_G_CPU1_SB_DQ<10>")
	)
	(segment
		(start 170.229276 -226.366832)
		(end 170.069256 -226.526852)
		(width 0.18288)
		(layer "In6.Cu")
		(net "M_G_CPU1_SB_DQ<10>")
	)
	(segment
		(start 132.983224 -236.91596)
		(end 132.97281 -236.922056)
		(width 0.088646)
		(layer "In6.Cu")
		(net "M_G_CPU1_SB_DQ<10>")
	)
	(segment
		(start 139.412472 -236.027468)
		(end 139.364212 -236.027468)
		(width 0.088646)
		(layer "In6.Cu")
		(net "M_G_CPU1_SB_DQ<10>")
	)
	(segment
		(start 190.894462 -223.055942)
		(end 189.480698 -223.055942)
		(width 0.18288)
		(layer "In6.Cu")
		(net "M_G_CPU1_SB_DQ<10>")
	)
	(segment
		(start 158.525972 -224.4217)
		(end 158.196026 -224.091754)
		(width 0.18288)
		(layer "In6.Cu")
		(net "M_G_CPU1_SB_DQ<10>")
	)
	(segment
		(start 138.237214 -236.922056)
		(end 138.222482 -236.91342)
		(width 0.088646)
		(layer "In6.Cu")
		(net "M_G_CPU1_SB_DQ<10>")
	)
	(segment
		(start 128.652016 -236.53242)
		(end 128.450594 -236.330998)
		(width 0.088646)
		(layer "In6.Cu")
		(net "M_G_CPU1_SB_DQ<10>")
	)
	(segment
		(start 189.480698 -223.055942)
		(end 188.816996 -222.39224)
		(width 0.18288)
		(layer "In6.Cu")
		(net "M_G_CPU1_SB_DQ<10>")
	)
	(segment
		(start 162.226752 -224.091754)
		(end 160.863026 -224.091754)
		(width 0.18288)
		(layer "In6.Cu")
		(net "M_G_CPU1_SB_DQ<10>")
	)
	(segment
		(start 177.982372 -225.125026)
		(end 177.315368 -225.79203)
		(width 0.18288)
		(layer "In6.Cu")
		(net "M_G_CPU1_SB_DQ<10>")
	)
	(segment
		(start 180.014626 -224.312226)
		(end 179.201826 -225.125026)
		(width 0.18288)
		(layer "In6.Cu")
		(net "M_G_CPU1_SB_DQ<10>")
	)
	(segment
		(start 183.367426 -223.143826)
		(end 181.504082 -223.143826)
		(width 0.18288)
		(layer "In6.Cu")
		(net "M_G_CPU1_SB_DQ<10>")
	)
	(segment
		(start 160.863026 -224.091754)
		(end 160.53308 -224.4217)
		(width 0.18288)
		(layer "In6.Cu")
		(net "M_G_CPU1_SB_DQ<10>")
	)
	(segment
		(start 173.486572 -226.642168)
		(end 171.308522 -226.642168)
		(width 0.18288)
		(layer "In6.Cu")
		(net "M_G_CPU1_SB_DQ<10>")
	)
	(segment
		(start 164.161216 -224.985072)
		(end 163.12007 -224.985072)
		(width 0.18288)
		(layer "In6.Cu")
		(net "M_G_CPU1_SB_DQ<10>")
	)
	(segment
		(start 139.364212 -236.027468)
		(end 139.309348 -236.035088)
		(width 0.088646)
		(layer "In6.Cu")
		(net "M_G_CPU1_SB_DQ<10>")
	)
	(segment
		(start 127.481076 -236.315504)
		(end 127.146812 -236.597952)
		(width 0.088646)
		(layer "In6.Cu")
		(net "M_G_CPU1_SB_DQ<10>")
	)
	(segment
		(start 191.983614 -221.96679)
		(end 190.894462 -223.055942)
		(width 0.18288)
		(layer "In6.Cu")
		(net "M_G_CPU1_SB_DQ<10>")
	)
	(segment
		(start 144.293082 -235.439204)
		(end 140.222478 -235.439204)
		(width 0.18288)
		(layer "In6.Cu")
		(net "M_G_CPU1_SB_DQ<10>")
	)
	(arc
		(start 132.03301 -236.922056)
		(mid 131.845812 -236.972233)
		(end 131.658614 -236.922056)
		(width 0.088646)
		(layer "In6.Cu")
		(net "M_G_CPU1_SB_DQ<10>")
	)
	(arc
		(start 131.09321 -236.922056)
		(mid 130.906012 -236.972233)
		(end 130.718814 -236.922056)
		(width 0.088646)
		(layer "In6.Cu")
		(net "M_G_CPU1_SB_DQ<10>")
	)
	(arc
		(start 133.538468 -236.922056)
		(mid 133.261655 -236.846186)
		(end 132.983224 -236.91596)
		(width 0.088646)
		(layer "In6.Cu")
		(net "M_G_CPU1_SB_DQ<10>")
	)
	(arc
		(start 132.97281 -236.922056)
		(mid 132.785612 -236.972233)
		(end 132.598414 -236.922056)
		(width 0.088646)
		(layer "In6.Cu")
		(net "M_G_CPU1_SB_DQ<10>")
	)
	(arc
		(start 129.7686 -236.91596)
		(mid 129.490422 -236.846237)
		(end 129.213864 -236.922056)
		(width 0.088646)
		(layer "In6.Cu")
		(net "M_G_CPU1_SB_DQ<10>")
	)
	(arc
		(start 138.799062 -236.597952)
		(mid 138.752923 -236.778137)
		(end 138.625834 -236.913928)
		(width 0.088646)
		(layer "In6.Cu")
		(net "M_G_CPU1_SB_DQ<10>")
	)
	(arc
		(start 128.450594 -236.330998)
		(mid 127.968971 -236.126905)
		(end 127.481076 -236.315504)
		(width 0.088646)
		(layer "In6.Cu")
		(net "M_G_CPU1_SB_DQ<10>")
	)
	(arc
		(start 138.222482 -236.91342)
		(mid 137.946007 -236.8461)
		(end 137.67181 -236.922056)
		(width 0.088646)
		(layer "In6.Cu")
		(net "M_G_CPU1_SB_DQ<10>")
	)
	(arc
		(start 136.73201 -236.922056)
		(mid 136.544812 -236.972233)
		(end 136.357614 -236.922056)
		(width 0.088646)
		(layer "In6.Cu")
		(net "M_G_CPU1_SB_DQ<10>")
	)
	(arc
		(start 137.67181 -236.922056)
		(mid 137.484612 -236.972233)
		(end 137.297414 -236.922056)
		(width 0.088646)
		(layer "In6.Cu")
		(net "M_G_CPU1_SB_DQ<10>")
	)
	(arc
		(start 134.852664 -236.922056)
		(mid 134.665466 -236.972233)
		(end 134.478268 -236.922056)
		(width 0.088646)
		(layer "In6.Cu")
		(net "M_G_CPU1_SB_DQ<10>")
	)
	(arc
		(start 138.61161 -236.922056)
		(mid 138.424412 -236.972233)
		(end 138.237214 -236.922056)
		(width 0.088646)
		(layer "In6.Cu")
		(net "M_G_CPU1_SB_DQ<10>")
	)
	(arc
		(start 136.342882 -236.91342)
		(mid 136.066407 -236.8461)
		(end 135.79221 -236.922056)
		(width 0.088646)
		(layer "In6.Cu")
		(net "M_G_CPU1_SB_DQ<10>")
	)
	(arc
		(start 135.4074 -236.91596)
		(mid 135.129222 -236.846237)
		(end 134.852664 -236.922056)
		(width 0.088646)
		(layer "In6.Cu")
		(net "M_G_CPU1_SB_DQ<10>")
	)
	(arc
		(start 132.583682 -236.91342)
		(mid 132.307207 -236.8461)
		(end 132.03301 -236.922056)
		(width 0.088646)
		(layer "In6.Cu")
		(net "M_G_CPU1_SB_DQ<10>")
	)
	(arc
		(start 139.081764 -236.10824)
		(mid 138.878283 -236.309044)
		(end 138.799062 -236.583728)
		(width 0.088646)
		(layer "In6.Cu")
		(net "M_G_CPU1_SB_DQ<10>")
	)
	(arc
		(start 131.643882 -236.91342)
		(mid 131.367407 -236.8461)
		(end 131.09321 -236.922056)
		(width 0.088646)
		(layer "In6.Cu")
		(net "M_G_CPU1_SB_DQ<10>")
	)
	(arc
		(start 139.309348 -236.035088)
		(mid 139.191652 -236.059513)
		(end 139.081764 -236.10824)
		(width 0.088646)
		(layer "In6.Cu")
		(net "M_G_CPU1_SB_DQ<10>")
	)
	(arc
		(start 129.213864 -236.922056)
		(mid 129.026666 -236.972233)
		(end 128.839468 -236.922056)
		(width 0.088646)
		(layer "In6.Cu")
		(net "M_G_CPU1_SB_DQ<10>")
	)
	(arc
		(start 128.825244 -236.913928)
		(mid 128.698201 -236.778112)
		(end 128.652016 -236.597952)
		(width 0.088646)
		(layer "In6.Cu")
		(net "M_G_CPU1_SB_DQ<10>")
	)
	(arc
		(start 130.704082 -236.91342)
		(mid 130.427607 -236.8461)
		(end 130.15341 -236.922056)
		(width 0.088646)
		(layer "In6.Cu")
		(net "M_G_CPU1_SB_DQ<10>")
	)
	(arc
		(start 135.79221 -236.922056)
		(mid 135.605012 -236.972233)
		(end 135.417814 -236.922056)
		(width 0.088646)
		(layer "In6.Cu")
		(net "M_G_CPU1_SB_DQ<10>")
	)
	(arc
		(start 134.478268 -236.922056)
		(mid 134.195566 -236.84628)
		(end 133.912864 -236.922056)
		(width 0.088646)
		(layer "In6.Cu")
		(net "M_G_CPU1_SB_DQ<10>")
	)
	(arc
		(start 137.282682 -236.91342)
		(mid 137.006207 -236.8461)
		(end 136.73201 -236.922056)
		(width 0.088646)
		(layer "In6.Cu")
		(net "M_G_CPU1_SB_DQ<10>")
	)
	(arc
		(start 133.912864 -236.922056)
		(mid 133.725666 -236.972233)
		(end 133.538468 -236.922056)
		(width 0.088646)
		(layer "In6.Cu")
		(net "M_G_CPU1_SB_DQ<10>")
	)
	(arc
		(start 130.15341 -236.922056)
		(mid 129.966212 -236.972233)
		(end 129.779014 -236.922056)
		(width 0.088646)
		(layer "In6.Cu")
		(net "M_G_CPU1_SB_DQ<10>")
	)
	(segment
		(start 127.147066 -242.017042)
		(end 127.146812 -242.016788)
		(width 0.20066)
		(layer "F.Cu")
		(net "M_G_CPU1_SB_DQ<0>")
	)
	(segment
		(start 194.092576 -231.741726)
		(end 191.930782 -231.741726)
		(width 0.1016)
		(layer "F.Cu")
		(net "M_G_CPU1_SB_DQ<0>")
	)
	(segment
		(start 194.508882 -231.735376)
		(end 194.098926 -231.735376)
		(width 0.20066)
		(layer "F.Cu")
		(net "M_G_CPU1_SB_DQ<0>")
	)
	(segment
		(start 191.883792 -231.741726)
		(end 191.539114 -231.741726)
		(width 0.20066)
		(layer "F.Cu")
		(net "M_G_CPU1_SB_DQ<0>")
	)
	(segment
		(start 196.531992 -232.166922)
		(end 194.940428 -232.166922)
		(width 0.20066)
		(layer "F.Cu")
		(net "M_G_CPU1_SB_DQ<0>")
	)
	(segment
		(start 127.146812 -242.016788)
		(end 127.146812 -241.481102)
		(width 0.20066)
		(layer "F.Cu")
		(net "M_G_CPU1_SB_DQ<0>")
	)
	(segment
		(start 190.509144 -232.166668)
		(end 188.988446 -232.166668)
		(width 0.20066)
		(layer "F.Cu")
		(net "M_G_CPU1_SB_DQ<0>")
	)
	(segment
		(start 188.988446 -232.166668)
		(end 187.883546 -232.166668)
		(width 0.20066)
		(layer "F.Cu")
		(net "M_G_CPU1_SB_DQ<0>")
	)
	(segment
		(start 191.421004 -232.227374)
		(end 191.233044 -232.415334)
		(width 0.20066)
		(layer "F.Cu")
		(net "M_G_CPU1_SB_DQ<0>")
	)
	(segment
		(start 196.532246 -232.166668)
		(end 196.531992 -232.166922)
		(width 0.20066)
		(layer "F.Cu")
		(net "M_G_CPU1_SB_DQ<0>")
	)
	(segment
		(start 191.930782 -231.741726)
		(end 191.883792 -231.741726)
		(width 0.101854)
		(layer "F.Cu")
		(net "M_G_CPU1_SB_DQ<0>")
	)
	(segment
		(start 194.098926 -231.735376)
		(end 194.092576 -231.741726)
		(width 0.1016)
		(layer "F.Cu")
		(net "M_G_CPU1_SB_DQ<0>")
	)
	(segment
		(start 191.233044 -232.415334)
		(end 190.75781 -232.415334)
		(width 0.20066)
		(layer "F.Cu")
		(net "M_G_CPU1_SB_DQ<0>")
	)
	(segment
		(start 194.940428 -232.166922)
		(end 194.508882 -231.735376)
		(width 0.20066)
		(layer "F.Cu")
		(net "M_G_CPU1_SB_DQ<0>")
	)
	(segment
		(start 191.421004 -231.859836)
		(end 191.421004 -232.227374)
		(width 0.20066)
		(layer "F.Cu")
		(net "M_G_CPU1_SB_DQ<0>")
	)
	(segment
		(start 190.75781 -232.415334)
		(end 190.509144 -232.166668)
		(width 0.20066)
		(layer "F.Cu")
		(net "M_G_CPU1_SB_DQ<0>")
	)
	(segment
		(start 191.539114 -231.741726)
		(end 191.421004 -231.859836)
		(width 0.20066)
		(layer "F.Cu")
		(net "M_G_CPU1_SB_DQ<0>")
	)
	(segment
		(start 185.54827 -235.311442)
		(end 185.32221 -235.311442)
		(width 0.18288)
		(layer "In6.Cu")
		(net "M_G_CPU1_SB_DQ<0>")
	)
	(segment
		(start 168.234106 -238.058706)
		(end 165.362382 -238.058706)
		(width 0.18288)
		(layer "In6.Cu")
		(net "M_G_CPU1_SB_DQ<0>")
	)
	(segment
		(start 185.949082 -237.78083)
		(end 184.530238 -236.361986)
		(width 0.18288)
		(layer "In6.Cu")
		(net "M_G_CPU1_SB_DQ<0>")
	)
	(segment
		(start 185.32221 -235.311442)
		(end 185.020712 -235.61294)
		(width 0.18288)
		(layer "In6.Cu")
		(net "M_G_CPU1_SB_DQ<0>")
	)
	(segment
		(start 184.271666 -236.361986)
		(end 183.968136 -236.665516)
		(width 0.18288)
		(layer "In6.Cu")
		(net "M_G_CPU1_SB_DQ<0>")
	)
	(segment
		(start 140.442696 -242.05565)
		(end 140.292836 -242.05565)
		(width 0.088646)
		(layer "In6.Cu")
		(net "M_G_CPU1_SB_DQ<0>")
	)
	(segment
		(start 183.968136 -236.924088)
		(end 184.254902 -237.210854)
		(width 0.18288)
		(layer "In6.Cu")
		(net "M_G_CPU1_SB_DQ<0>")
	)
	(segment
		(start 186.980322 -233.069892)
		(end 186.59856 -233.069892)
		(width 0.18288)
		(layer "In6.Cu")
		(net "M_G_CPU1_SB_DQ<0>")
	)
	(segment
		(start 171.955206 -238.771684)
		(end 168.947084 -238.771684)
		(width 0.18288)
		(layer "In6.Cu")
		(net "M_G_CPU1_SB_DQ<0>")
	)
	(segment
		(start 184.530238 -236.361986)
		(end 184.271666 -236.361986)
		(width 0.18288)
		(layer "In6.Cu")
		(net "M_G_CPU1_SB_DQ<0>")
	)
	(segment
		(start 139.35583 -242.244626)
		(end 139.081764 -241.97056)
		(width 0.088646)
		(layer "In6.Cu")
		(net "M_G_CPU1_SB_DQ<0>")
	)
	(segment
		(start 140.443204 -242.056158)
		(end 140.442696 -242.05565)
		(width 0.18288)
		(layer "In6.Cu")
		(net "M_G_CPU1_SB_DQ<0>")
	)
	(segment
		(start 183.477662 -237.414562)
		(end 183.21909 -237.414562)
		(width 0.18288)
		(layer "In6.Cu")
		(net "M_G_CPU1_SB_DQ<0>")
	)
	(segment
		(start 186.429396 -237.559088)
		(end 186.207654 -237.78083)
		(width 0.18288)
		(layer "In6.Cu")
		(net "M_G_CPU1_SB_DQ<0>")
	)
	(segment
		(start 187.883546 -232.166668)
		(end 186.980322 -233.069892)
		(width 0.18288)
		(layer "In6.Cu")
		(net "M_G_CPU1_SB_DQ<0>")
	)
	(segment
		(start 127.459486 -241.481102)
		(end 127.146812 -241.481102)
		(width 0.088646)
		(layer "In6.Cu")
		(net "M_G_CPU1_SB_DQ<0>")
	)
	(segment
		(start 131.578096 -241.979196)
		(end 131.563364 -241.97056)
		(width 0.088646)
		(layer "In6.Cu")
		(net "M_G_CPU1_SB_DQ<0>")
	)
	(segment
		(start 155.210764 -238.59109)
		(end 152.225248 -238.59109)
		(width 0.18288)
		(layer "In6.Cu")
		(net "M_G_CPU1_SB_DQ<0>")
	)
	(segment
		(start 165.362382 -238.058706)
		(end 164.884608 -237.580932)
		(width 0.18288)
		(layer "In6.Cu")
		(net "M_G_CPU1_SB_DQ<0>")
	)
	(segment
		(start 127.804164 -241.97056)
		(end 127.798068 -241.967004)
		(width 0.088646)
		(layer "In6.Cu")
		(net "M_G_CPU1_SB_DQ<0>")
	)
	(segment
		(start 152.225248 -238.59109)
		(end 148.76018 -242.056158)
		(width 0.18288)
		(layer "In6.Cu")
		(net "M_G_CPU1_SB_DQ<0>")
	)
	(segment
		(start 184.023 -237.701328)
		(end 183.764428 -237.701328)
		(width 0.18288)
		(layer "In6.Cu")
		(net "M_G_CPU1_SB_DQ<0>")
	)
	(segment
		(start 127.525272 -241.546888)
		(end 127.459486 -241.481102)
		(width 0.088646)
		(layer "In6.Cu")
		(net "M_G_CPU1_SB_DQ<0>")
	)
	(segment
		(start 164.884608 -237.580932)
		(end 156.220922 -237.580932)
		(width 0.18288)
		(layer "In6.Cu")
		(net "M_G_CPU1_SB_DQ<0>")
	)
	(segment
		(start 184.254902 -237.469426)
		(end 184.023 -237.701328)
		(width 0.18288)
		(layer "In6.Cu")
		(net "M_G_CPU1_SB_DQ<0>")
	)
	(segment
		(start 168.947084 -238.771684)
		(end 168.234106 -238.058706)
		(width 0.18288)
		(layer "In6.Cu")
		(net "M_G_CPU1_SB_DQ<0>")
	)
	(segment
		(start 172.1866 -238.54029)
		(end 171.955206 -238.771684)
		(width 0.18288)
		(layer "In6.Cu")
		(net "M_G_CPU1_SB_DQ<0>")
	)
	(segment
		(start 183.21909 -237.414562)
		(end 182.941722 -237.69193)
		(width 0.18288)
		(layer "In6.Cu")
		(net "M_G_CPU1_SB_DQ<0>")
	)
	(segment
		(start 186.02071 -233.647742)
		(end 186.02071 -234.314238)
		(width 0.18288)
		(layer "In6.Cu")
		(net "M_G_CPU1_SB_DQ<0>")
	)
	(segment
		(start 132.517896 -241.979196)
		(end 132.503164 -241.97056)
		(width 0.088646)
		(layer "In6.Cu")
		(net "M_G_CPU1_SB_DQ<0>")
	)
	(segment
		(start 175.124618 -237.69193)
		(end 174.276258 -238.54029)
		(width 0.18288)
		(layer "In6.Cu")
		(net "M_G_CPU1_SB_DQ<0>")
	)
	(segment
		(start 186.529218 -235.076238)
		(end 186.034172 -235.571284)
		(width 0.18288)
		(layer "In6.Cu")
		(net "M_G_CPU1_SB_DQ<0>")
	)
	(segment
		(start 185.020712 -235.61294)
		(end 185.020712 -235.871512)
		(width 0.18288)
		(layer "In6.Cu")
		(net "M_G_CPU1_SB_DQ<0>")
	)
	(segment
		(start 174.276258 -238.54029)
		(end 172.1866 -238.54029)
		(width 0.18288)
		(layer "In6.Cu")
		(net "M_G_CPU1_SB_DQ<0>")
	)
	(segment
		(start 140.292836 -242.05565)
		(end 140.10386 -242.244626)
		(width 0.088646)
		(layer "In6.Cu")
		(net "M_G_CPU1_SB_DQ<0>")
	)
	(segment
		(start 130.638296 -241.979196)
		(end 130.623564 -241.97056)
		(width 0.088646)
		(layer "In6.Cu")
		(net "M_G_CPU1_SB_DQ<0>")
	)
	(segment
		(start 186.529218 -234.822746)
		(end 186.529218 -235.076238)
		(width 0.18288)
		(layer "In6.Cu")
		(net "M_G_CPU1_SB_DQ<0>")
	)
	(segment
		(start 186.207654 -237.78083)
		(end 185.949082 -237.78083)
		(width 0.18288)
		(layer "In6.Cu")
		(net "M_G_CPU1_SB_DQ<0>")
	)
	(segment
		(start 127.818896 -241.979196)
		(end 127.804164 -241.97056)
		(width 0.088646)
		(layer "In6.Cu")
		(net "M_G_CPU1_SB_DQ<0>")
	)
	(segment
		(start 185.808112 -235.571284)
		(end 185.54827 -235.311442)
		(width 0.18288)
		(layer "In6.Cu")
		(net "M_G_CPU1_SB_DQ<0>")
	)
	(segment
		(start 186.59856 -233.069892)
		(end 186.02071 -233.647742)
		(width 0.18288)
		(layer "In6.Cu")
		(net "M_G_CPU1_SB_DQ<0>")
	)
	(segment
		(start 129.698496 -241.979196)
		(end 129.683764 -241.97056)
		(width 0.088646)
		(layer "In6.Cu")
		(net "M_G_CPU1_SB_DQ<0>")
	)
	(segment
		(start 184.254902 -237.210854)
		(end 184.254902 -237.469426)
		(width 0.18288)
		(layer "In6.Cu")
		(net "M_G_CPU1_SB_DQ<0>")
	)
	(segment
		(start 185.020712 -235.871512)
		(end 186.429396 -237.280196)
		(width 0.18288)
		(layer "In6.Cu")
		(net "M_G_CPU1_SB_DQ<0>")
	)
	(segment
		(start 140.10386 -242.244626)
		(end 139.35583 -242.244626)
		(width 0.088646)
		(layer "In6.Cu")
		(net "M_G_CPU1_SB_DQ<0>")
	)
	(segment
		(start 186.02071 -234.314238)
		(end 186.529218 -234.822746)
		(width 0.18288)
		(layer "In6.Cu")
		(net "M_G_CPU1_SB_DQ<0>")
	)
	(segment
		(start 183.764428 -237.701328)
		(end 183.477662 -237.414562)
		(width 0.18288)
		(layer "In6.Cu")
		(net "M_G_CPU1_SB_DQ<0>")
	)
	(segment
		(start 186.429396 -237.280196)
		(end 186.429396 -237.559088)
		(width 0.18288)
		(layer "In6.Cu")
		(net "M_G_CPU1_SB_DQ<0>")
	)
	(segment
		(start 156.220922 -237.580932)
		(end 155.210764 -238.59109)
		(width 0.18288)
		(layer "In6.Cu")
		(net "M_G_CPU1_SB_DQ<0>")
	)
	(segment
		(start 186.034172 -235.571284)
		(end 185.808112 -235.571284)
		(width 0.18288)
		(layer "In6.Cu")
		(net "M_G_CPU1_SB_DQ<0>")
	)
	(segment
		(start 134.397496 -241.979196)
		(end 134.382764 -241.97056)
		(width 0.088646)
		(layer "In6.Cu")
		(net "M_G_CPU1_SB_DQ<0>")
	)
	(segment
		(start 182.941722 -237.69193)
		(end 175.124618 -237.69193)
		(width 0.18288)
		(layer "In6.Cu")
		(net "M_G_CPU1_SB_DQ<0>")
	)
	(segment
		(start 148.76018 -242.056158)
		(end 140.443204 -242.056158)
		(width 0.18288)
		(layer "In6.Cu")
		(net "M_G_CPU1_SB_DQ<0>")
	)
	(segment
		(start 183.968136 -236.665516)
		(end 183.968136 -236.924088)
		(width 0.18288)
		(layer "In6.Cu")
		(net "M_G_CPU1_SB_DQ<0>")
	)
	(arc
		(start 135.887968 -241.97056)
		(mid 135.605266 -242.046336)
		(end 135.322564 -241.97056)
		(width 0.088646)
		(layer "In6.Cu")
		(net "M_G_CPU1_SB_DQ<0>")
	)
	(arc
		(start 130.249168 -241.97056)
		(mid 129.974969 -242.046395)
		(end 129.698496 -241.979196)
		(width 0.088646)
		(layer "In6.Cu")
		(net "M_G_CPU1_SB_DQ<0>")
	)
	(arc
		(start 131.563364 -241.97056)
		(mid 131.376166 -241.920417)
		(end 131.188968 -241.97056)
		(width 0.088646)
		(layer "In6.Cu")
		(net "M_G_CPU1_SB_DQ<0>")
	)
	(arc
		(start 129.683764 -241.97056)
		(mid 129.496566 -241.920417)
		(end 129.309368 -241.97056)
		(width 0.088646)
		(layer "In6.Cu")
		(net "M_G_CPU1_SB_DQ<0>")
	)
	(arc
		(start 136.827768 -241.97056)
		(mid 136.545066 -242.046336)
		(end 136.262364 -241.97056)
		(width 0.088646)
		(layer "In6.Cu")
		(net "M_G_CPU1_SB_DQ<0>")
	)
	(arc
		(start 133.068568 -241.97056)
		(mid 132.794369 -242.046395)
		(end 132.517896 -241.979196)
		(width 0.088646)
		(layer "In6.Cu")
		(net "M_G_CPU1_SB_DQ<0>")
	)
	(arc
		(start 129.309368 -241.97056)
		(mid 129.026666 -242.046336)
		(end 128.743964 -241.97056)
		(width 0.088646)
		(layer "In6.Cu")
		(net "M_G_CPU1_SB_DQ<0>")
	)
	(arc
		(start 134.008368 -241.97056)
		(mid 133.725666 -242.046336)
		(end 133.442964 -241.97056)
		(width 0.088646)
		(layer "In6.Cu")
		(net "M_G_CPU1_SB_DQ<0>")
	)
	(arc
		(start 132.128768 -241.97056)
		(mid 131.854569 -242.046395)
		(end 131.578096 -241.979196)
		(width 0.088646)
		(layer "In6.Cu")
		(net "M_G_CPU1_SB_DQ<0>")
	)
	(arc
		(start 134.948168 -241.97056)
		(mid 134.673969 -242.046395)
		(end 134.397496 -241.979196)
		(width 0.088646)
		(layer "In6.Cu")
		(net "M_G_CPU1_SB_DQ<0>")
	)
	(arc
		(start 128.369568 -241.97056)
		(mid 128.095369 -242.046395)
		(end 127.818896 -241.979196)
		(width 0.088646)
		(layer "In6.Cu")
		(net "M_G_CPU1_SB_DQ<0>")
	)
	(arc
		(start 130.623564 -241.97056)
		(mid 130.436366 -241.920417)
		(end 130.249168 -241.97056)
		(width 0.088646)
		(layer "In6.Cu")
		(net "M_G_CPU1_SB_DQ<0>")
	)
	(arc
		(start 136.262364 -241.97056)
		(mid 136.075166 -241.920417)
		(end 135.887968 -241.97056)
		(width 0.088646)
		(layer "In6.Cu")
		(net "M_G_CPU1_SB_DQ<0>")
	)
	(arc
		(start 134.382764 -241.97056)
		(mid 134.195566 -241.920417)
		(end 134.008368 -241.97056)
		(width 0.088646)
		(layer "In6.Cu")
		(net "M_G_CPU1_SB_DQ<0>")
	)
	(arc
		(start 138.707368 -241.97056)
		(mid 138.424666 -242.046336)
		(end 138.141964 -241.97056)
		(width 0.088646)
		(layer "In6.Cu")
		(net "M_G_CPU1_SB_DQ<0>")
	)
	(arc
		(start 131.188968 -241.97056)
		(mid 130.914769 -242.046395)
		(end 130.638296 -241.979196)
		(width 0.088646)
		(layer "In6.Cu")
		(net "M_G_CPU1_SB_DQ<0>")
	)
	(arc
		(start 128.743964 -241.97056)
		(mid 128.556766 -241.920417)
		(end 128.369568 -241.97056)
		(width 0.088646)
		(layer "In6.Cu")
		(net "M_G_CPU1_SB_DQ<0>")
	)
	(arc
		(start 127.798068 -241.967004)
		(mid 127.612613 -241.788809)
		(end 127.525272 -241.546888)
		(width 0.088646)
		(layer "In6.Cu")
		(net "M_G_CPU1_SB_DQ<0>")
	)
	(arc
		(start 137.202164 -241.97056)
		(mid 137.014966 -241.920417)
		(end 136.827768 -241.97056)
		(width 0.088646)
		(layer "In6.Cu")
		(net "M_G_CPU1_SB_DQ<0>")
	)
	(arc
		(start 138.141964 -241.97056)
		(mid 137.954766 -241.920417)
		(end 137.767568 -241.97056)
		(width 0.088646)
		(layer "In6.Cu")
		(net "M_G_CPU1_SB_DQ<0>")
	)
	(arc
		(start 137.767568 -241.97056)
		(mid 137.484866 -242.046336)
		(end 137.202164 -241.97056)
		(width 0.088646)
		(layer "In6.Cu")
		(net "M_G_CPU1_SB_DQ<0>")
	)
	(arc
		(start 132.503164 -241.97056)
		(mid 132.315966 -241.920417)
		(end 132.128768 -241.97056)
		(width 0.088646)
		(layer "In6.Cu")
		(net "M_G_CPU1_SB_DQ<0>")
	)
	(arc
		(start 139.081764 -241.97056)
		(mid 138.894566 -241.920417)
		(end 138.707368 -241.97056)
		(width 0.088646)
		(layer "In6.Cu")
		(net "M_G_CPU1_SB_DQ<0>")
	)
	(arc
		(start 133.442964 -241.97056)
		(mid 133.255766 -241.920417)
		(end 133.068568 -241.97056)
		(width 0.088646)
		(layer "In6.Cu")
		(net "M_G_CPU1_SB_DQ<0>")
	)
	(arc
		(start 135.322564 -241.97056)
		(mid 135.135366 -241.920417)
		(end 134.948168 -241.97056)
		(width 0.088646)
		(layer "In6.Cu")
		(net "M_G_CPU1_SB_DQ<0>")
	)
	(segment
		(start 193.088514 -244.916706)
		(end 191.983614 -244.916706)
		(width 0.20066)
		(layer "F.Cu")
		(net "M_G_CPU1_SB_CS_N<3>")
	)
	(segment
		(start 130.436112 -246.08663)
		(end 130.436366 -246.086376)
		(width 0.20066)
		(layer "F.Cu")
		(net "M_G_CPU1_SB_CS_N<3>")
	)
	(segment
		(start 130.436366 -246.086376)
		(end 130.436366 -245.55069)
		(width 0.20066)
		(layer "F.Cu")
		(net "M_G_CPU1_SB_CS_N<3>")
	)
	(segment
		(start 175.415956 -244.491002)
		(end 174.716948 -244.491002)
		(width 0.18288)
		(layer "In4.Cu")
		(net "M_G_CPU1_SB_CS_N<3>")
	)
	(segment
		(start 191.983614 -244.652546)
		(end 191.823594 -244.492526)
		(width 0.18288)
		(layer "In4.Cu")
		(net "M_G_CPU1_SB_CS_N<3>")
	)
	(segment
		(start 176.08042 -244.835426)
		(end 175.76038 -244.835426)
		(width 0.18288)
		(layer "In4.Cu")
		(net "M_G_CPU1_SB_CS_N<3>")
	)
	(segment
		(start 175.76038 -244.835426)
		(end 175.415956 -244.491002)
		(width 0.18288)
		(layer "In4.Cu")
		(net "M_G_CPU1_SB_CS_N<3>")
	)
	(segment
		(start 138.080242 -245.774972)
		(end 137.826496 -245.774972)
		(width 0.18288)
		(layer "In4.Cu")
		(net "M_G_CPU1_SB_CS_N<3>")
	)
	(segment
		(start 136.65073 -245.774972)
		(end 136.474708 -245.950994)
		(width 0.088646)
		(layer "In4.Cu")
		(net "M_G_CPU1_SB_CS_N<3>")
	)
	(segment
		(start 174.413672 -244.187726)
		(end 173.321726 -244.187726)
		(width 0.18288)
		(layer "In4.Cu")
		(net "M_G_CPU1_SB_CS_N<3>")
	)
	(segment
		(start 171.338748 -244.492526)
		(end 171.275248 -244.556026)
		(width 0.18288)
		(layer "In4.Cu")
		(net "M_G_CPU1_SB_CS_N<3>")
	)
	(segment
		(start 190.618618 -243.948458)
		(end 190.618618 -244.320314)
		(width 0.18288)
		(layer "In4.Cu")
		(net "M_G_CPU1_SB_CS_N<3>")
	)
	(segment
		(start 137.826496 -245.774972)
		(end 136.65073 -245.774972)
		(width 0.088646)
		(layer "In4.Cu")
		(net "M_G_CPU1_SB_CS_N<3>")
	)
	(segment
		(start 176.542192 -244.49278)
		(end 176.423066 -244.49278)
		(width 0.18288)
		(layer "In4.Cu")
		(net "M_G_CPU1_SB_CS_N<3>")
	)
	(segment
		(start 166.997126 -243.768626)
		(end 166.412926 -244.352826)
		(width 0.18288)
		(layer "In4.Cu")
		(net "M_G_CPU1_SB_CS_N<3>")
	)
	(segment
		(start 155.830016 -244.494304)
		(end 155.722066 -244.602254)
		(width 0.18288)
		(layer "In4.Cu")
		(net "M_G_CPU1_SB_CS_N<3>")
	)
	(segment
		(start 171.275248 -244.556026)
		(end 168.703752 -244.556026)
		(width 0.18288)
		(layer "In4.Cu")
		(net "M_G_CPU1_SB_CS_N<3>")
	)
	(segment
		(start 179.354226 -244.657626)
		(end 177.652426 -244.657626)
		(width 0.18288)
		(layer "In4.Cu")
		(net "M_G_CPU1_SB_CS_N<3>")
	)
	(segment
		(start 191.341756 -243.931186)
		(end 191.181736 -243.771166)
		(width 0.18288)
		(layer "In4.Cu")
		(net "M_G_CPU1_SB_CS_N<3>")
	)
	(segment
		(start 180.687726 -244.327426)
		(end 180.522626 -244.492526)
		(width 0.18288)
		(layer "In4.Cu")
		(net "M_G_CPU1_SB_CS_N<3>")
	)
	(segment
		(start 177.487326 -244.492526)
		(end 176.542446 -244.492526)
		(width 0.18288)
		(layer "In4.Cu")
		(net "M_G_CPU1_SB_CS_N<3>")
	)
	(segment
		(start 148.15439 -244.602254)
		(end 147.42922 -245.327424)
		(width 0.18288)
		(layer "In4.Cu")
		(net "M_G_CPU1_SB_CS_N<3>")
	)
	(segment
		(start 191.341756 -244.332506)
		(end 191.341756 -243.931186)
		(width 0.18288)
		(layer "In4.Cu")
		(net "M_G_CPU1_SB_CS_N<3>")
	)
	(segment
		(start 166.412926 -244.352826)
		(end 165.671246 -244.352826)
		(width 0.18288)
		(layer "In4.Cu")
		(net "M_G_CPU1_SB_CS_N<3>")
	)
	(segment
		(start 132.987796 -246.048784)
		(end 132.954776 -246.02948)
		(width 0.088646)
		(layer "In4.Cu")
		(net "M_G_CPU1_SB_CS_N<3>")
	)
	(segment
		(start 173.016926 -244.492526)
		(end 171.338748 -244.492526)
		(width 0.18288)
		(layer "In4.Cu")
		(net "M_G_CPU1_SB_CS_N<3>")
	)
	(segment
		(start 176.542446 -244.492526)
		(end 176.542192 -244.49278)
		(width 0.18288)
		(layer "In4.Cu")
		(net "M_G_CPU1_SB_CS_N<3>")
	)
	(segment
		(start 132.039106 -246.043704)
		(end 132.037836 -246.042942)
		(width 0.088646)
		(layer "In4.Cu")
		(net "M_G_CPU1_SB_CS_N<3>")
	)
	(segment
		(start 173.321726 -244.187726)
		(end 173.016926 -244.492526)
		(width 0.18288)
		(layer "In4.Cu")
		(net "M_G_CPU1_SB_CS_N<3>")
	)
	(segment
		(start 130.81889 -245.79199)
		(end 130.436366 -245.55069)
		(width 0.088646)
		(layer "In4.Cu")
		(net "M_G_CPU1_SB_CS_N<3>")
	)
	(segment
		(start 176.423066 -244.49278)
		(end 176.08042 -244.835426)
		(width 0.18288)
		(layer "In4.Cu")
		(net "M_G_CPU1_SB_CS_N<3>")
	)
	(segment
		(start 180.522626 -244.492526)
		(end 179.519326 -244.492526)
		(width 0.18288)
		(layer "In4.Cu")
		(net "M_G_CPU1_SB_CS_N<3>")
	)
	(segment
		(start 190.618618 -244.320314)
		(end 190.448438 -244.490494)
		(width 0.18288)
		(layer "In4.Cu")
		(net "M_G_CPU1_SB_CS_N<3>")
	)
	(segment
		(start 190.448438 -244.490494)
		(end 183.530494 -244.490494)
		(width 0.18288)
		(layer "In4.Cu")
		(net "M_G_CPU1_SB_CS_N<3>")
	)
	(segment
		(start 131.106926 -246.04853)
		(end 131.105402 -246.047006)
		(width 0.088646)
		(layer "In4.Cu")
		(net "M_G_CPU1_SB_CS_N<3>")
	)
	(segment
		(start 174.716948 -244.491002)
		(end 174.413672 -244.187726)
		(width 0.18288)
		(layer "In4.Cu")
		(net "M_G_CPU1_SB_CS_N<3>")
	)
	(segment
		(start 190.79591 -243.771166)
		(end 190.618618 -243.948458)
		(width 0.18288)
		(layer "In4.Cu")
		(net "M_G_CPU1_SB_CS_N<3>")
	)
	(segment
		(start 139.366752 -246.0498)
		(end 138.35507 -246.0498)
		(width 0.18288)
		(layer "In4.Cu")
		(net "M_G_CPU1_SB_CS_N<3>")
	)
	(segment
		(start 167.916352 -243.768626)
		(end 166.997126 -243.768626)
		(width 0.18288)
		(layer "In4.Cu")
		(net "M_G_CPU1_SB_CS_N<3>")
	)
	(segment
		(start 183.367426 -244.327426)
		(end 180.687726 -244.327426)
		(width 0.18288)
		(layer "In4.Cu")
		(net "M_G_CPU1_SB_CS_N<3>")
	)
	(segment
		(start 131.034282 -245.993412)
		(end 130.888232 -245.847362)
		(width 0.088646)
		(layer "In4.Cu")
		(net "M_G_CPU1_SB_CS_N<3>")
	)
	(segment
		(start 141.111986 -245.327424)
		(end 139.366752 -246.0498)
		(width 0.18288)
		(layer "In4.Cu")
		(net "M_G_CPU1_SB_CS_N<3>")
	)
	(segment
		(start 177.652426 -244.657626)
		(end 177.487326 -244.492526)
		(width 0.18288)
		(layer "In4.Cu")
		(net "M_G_CPU1_SB_CS_N<3>")
	)
	(segment
		(start 165.671246 -244.352826)
		(end 165.529768 -244.494304)
		(width 0.18288)
		(layer "In4.Cu")
		(net "M_G_CPU1_SB_CS_N<3>")
	)
	(segment
		(start 155.722066 -244.602254)
		(end 148.15439 -244.602254)
		(width 0.18288)
		(layer "In4.Cu")
		(net "M_G_CPU1_SB_CS_N<3>")
	)
	(segment
		(start 191.983614 -244.916706)
		(end 191.983614 -244.652546)
		(width 0.18288)
		(layer "In4.Cu")
		(net "M_G_CPU1_SB_CS_N<3>")
	)
	(segment
		(start 132.037836 -246.042942)
		(end 131.96824 -246.00154)
		(width 0.088646)
		(layer "In4.Cu")
		(net "M_G_CPU1_SB_CS_N<3>")
	)
	(segment
		(start 168.703752 -244.556026)
		(end 167.916352 -243.768626)
		(width 0.18288)
		(layer "In4.Cu")
		(net "M_G_CPU1_SB_CS_N<3>")
	)
	(segment
		(start 191.823594 -244.492526)
		(end 191.501776 -244.492526)
		(width 0.18288)
		(layer "In4.Cu")
		(net "M_G_CPU1_SB_CS_N<3>")
	)
	(segment
		(start 191.501776 -244.492526)
		(end 191.341756 -244.332506)
		(width 0.18288)
		(layer "In4.Cu")
		(net "M_G_CPU1_SB_CS_N<3>")
	)
	(segment
		(start 165.529768 -244.494304)
		(end 155.830016 -244.494304)
		(width 0.18288)
		(layer "In4.Cu")
		(net "M_G_CPU1_SB_CS_N<3>")
	)
	(segment
		(start 183.530494 -244.490494)
		(end 183.367426 -244.327426)
		(width 0.18288)
		(layer "In4.Cu")
		(net "M_G_CPU1_SB_CS_N<3>")
	)
	(segment
		(start 191.181736 -243.771166)
		(end 190.79591 -243.771166)
		(width 0.18288)
		(layer "In4.Cu")
		(net "M_G_CPU1_SB_CS_N<3>")
	)
	(segment
		(start 138.35507 -246.0498)
		(end 138.080242 -245.774972)
		(width 0.18288)
		(layer "In4.Cu")
		(net "M_G_CPU1_SB_CS_N<3>")
	)
	(segment
		(start 147.42922 -245.327424)
		(end 141.111986 -245.327424)
		(width 0.18288)
		(layer "In4.Cu")
		(net "M_G_CPU1_SB_CS_N<3>")
	)
	(segment
		(start 132.597906 -246.039894)
		(end 132.582158 -246.049038)
		(width 0.088646)
		(layer "In4.Cu")
		(net "M_G_CPU1_SB_CS_N<3>")
	)
	(segment
		(start 179.519326 -244.492526)
		(end 179.354226 -244.657626)
		(width 0.18288)
		(layer "In4.Cu")
		(net "M_G_CPU1_SB_CS_N<3>")
	)
	(arc
		(start 132.817108 -245.990872)
		(mid 132.8166 -245.990871)
		(end 132.816092 -245.990872)
		(width 0.088646)
		(layer "In4.Cu")
		(net "M_G_CPU1_SB_CS_N<3>")
	)
	(arc
		(start 131.23037 -246.130318)
		(mid 131.190267 -246.110848)
		(end 131.154424 -246.084344)
		(width 0.088646)
		(layer "In4.Cu")
		(net "M_G_CPU1_SB_CS_N<3>")
	)
	(arc
		(start 130.888232 -245.847362)
		(mid 130.855098 -245.817753)
		(end 130.81889 -245.79199)
		(width 0.088646)
		(layer "In4.Cu")
		(net "M_G_CPU1_SB_CS_N<3>")
	)
	(arc
		(start 133.538468 -246.040148)
		(mid 133.264269 -246.115983)
		(end 132.987796 -246.048784)
		(width 0.088646)
		(layer "In4.Cu")
		(net "M_G_CPU1_SB_CS_N<3>")
	)
	(arc
		(start 131.105402 -246.047006)
		(mid 131.067919 -246.02276)
		(end 131.034282 -245.993412)
		(width 0.088646)
		(layer "In4.Cu")
		(net "M_G_CPU1_SB_CS_N<3>")
	)
	(arc
		(start 132.582158 -246.049038)
		(mid 132.578496 -246.051109)
		(end 132.574792 -246.053102)
		(width 0.088646)
		(layer "In4.Cu")
		(net "M_G_CPU1_SB_CS_N<3>")
	)
	(arc
		(start 132.804916 -245.990364)
		(mid 132.728126 -245.994356)
		(end 132.653786 -246.013986)
		(width 0.088646)
		(layer "In4.Cu")
		(net "M_G_CPU1_SB_CS_N<3>")
	)
	(arc
		(start 135.418068 -246.040148)
		(mid 135.135366 -246.115924)
		(end 134.852664 -246.040148)
		(width 0.088646)
		(layer "In4.Cu")
		(net "M_G_CPU1_SB_CS_N<3>")
	)
	(arc
		(start 132.816092 -245.990872)
		(mid 132.813806 -245.990738)
		(end 132.81152 -245.990618)
		(width 0.088646)
		(layer "In4.Cu")
		(net "M_G_CPU1_SB_CS_N<3>")
	)
	(arc
		(start 136.421876 -245.997222)
		(mid 136.390604 -246.019777)
		(end 136.357868 -246.040148)
		(width 0.088646)
		(layer "In4.Cu")
		(net "M_G_CPU1_SB_CS_N<3>")
	)
	(arc
		(start 134.852664 -246.040148)
		(mid 134.665466 -245.990005)
		(end 134.478268 -246.040148)
		(width 0.088646)
		(layer "In4.Cu")
		(net "M_G_CPU1_SB_CS_N<3>")
	)
	(arc
		(start 132.574792 -246.053102)
		(mid 132.313784 -246.1162)
		(end 132.053076 -246.051832)
		(width 0.088646)
		(layer "In4.Cu")
		(net "M_G_CPU1_SB_CS_N<3>")
	)
	(arc
		(start 131.96824 -246.00154)
		(mid 131.928358 -245.981567)
		(end 131.885944 -245.967758)
		(width 0.088646)
		(layer "In4.Cu")
		(net "M_G_CPU1_SB_CS_N<3>")
	)
	(arc
		(start 133.912864 -246.040148)
		(mid 133.725666 -245.990005)
		(end 133.538468 -246.040148)
		(width 0.088646)
		(layer "In4.Cu")
		(net "M_G_CPU1_SB_CS_N<3>")
	)
	(arc
		(start 131.576826 -246.054626)
		(mid 131.414704 -246.143302)
		(end 131.23037 -246.130318)
		(width 0.088646)
		(layer "In4.Cu")
		(net "M_G_CPU1_SB_CS_N<3>")
	)
	(arc
		(start 132.053076 -246.051832)
		(mid 132.046029 -246.047875)
		(end 132.039106 -246.043704)
		(width 0.088646)
		(layer "In4.Cu")
		(net "M_G_CPU1_SB_CS_N<3>")
	)
	(arc
		(start 132.954776 -246.02948)
		(mid 132.887794 -246.003579)
		(end 132.817108 -245.990872)
		(width 0.088646)
		(layer "In4.Cu")
		(net "M_G_CPU1_SB_CS_N<3>")
	)
	(arc
		(start 136.474708 -245.950994)
		(mid 136.44901 -245.974928)
		(end 136.421876 -245.997222)
		(width 0.088646)
		(layer "In4.Cu")
		(net "M_G_CPU1_SB_CS_N<3>")
	)
	(arc
		(start 131.154424 -246.084344)
		(mid 131.131384 -246.065497)
		(end 131.106926 -246.04853)
		(width 0.088646)
		(layer "In4.Cu")
		(net "M_G_CPU1_SB_CS_N<3>")
	)
	(arc
		(start 131.885944 -245.967758)
		(mid 131.72002 -245.970763)
		(end 131.576826 -246.054626)
		(width 0.088646)
		(layer "In4.Cu")
		(net "M_G_CPU1_SB_CS_N<3>")
	)
	(arc
		(start 135.792464 -246.040148)
		(mid 135.605266 -245.990005)
		(end 135.418068 -246.040148)
		(width 0.088646)
		(layer "In4.Cu")
		(net "M_G_CPU1_SB_CS_N<3>")
	)
	(arc
		(start 134.478268 -246.040148)
		(mid 134.195566 -246.115924)
		(end 133.912864 -246.040148)
		(width 0.088646)
		(layer "In4.Cu")
		(net "M_G_CPU1_SB_CS_N<3>")
	)
	(arc
		(start 132.81152 -245.990618)
		(mid 132.80822 -245.990434)
		(end 132.804916 -245.990364)
		(width 0.088646)
		(layer "In4.Cu")
		(net "M_G_CPU1_SB_CS_N<3>")
	)
	(arc
		(start 132.653786 -246.013986)
		(mid 132.646945 -246.016573)
		(end 132.64007 -246.019066)
		(width 0.088646)
		(layer "In4.Cu")
		(net "M_G_CPU1_SB_CS_N<3>")
	)
	(arc
		(start 132.64007 -246.019066)
		(mid 132.618664 -246.028824)
		(end 132.597906 -246.039894)
		(width 0.088646)
		(layer "In4.Cu")
		(net "M_G_CPU1_SB_CS_N<3>")
	)
	(arc
		(start 136.357868 -246.040148)
		(mid 136.075166 -246.115924)
		(end 135.792464 -246.040148)
		(width 0.088646)
		(layer "In4.Cu")
		(net "M_G_CPU1_SB_CS_N<3>")
	)
	(segment
		(start 129.966466 -246.900446)
		(end 129.966212 -246.900192)
		(width 0.20066)
		(layer "F.Cu")
		(net "M_G_CPU1_SB_CS_N<2>")
	)
	(segment
		(start 129.966212 -246.900192)
		(end 129.966212 -246.364506)
		(width 0.20066)
		(layer "F.Cu")
		(net "M_G_CPU1_SB_CS_N<2>")
	)
	(segment
		(start 187.883546 -245.76659)
		(end 188.988446 -245.76659)
		(width 0.20066)
		(layer "F.Cu")
		(net "M_G_CPU1_SB_CS_N<2>")
	)
	(segment
		(start 185.901584 -245.620794)
		(end 185.533538 -245.620794)
		(width 0.18288)
		(layer "In4.Cu")
		(net "M_G_CPU1_SB_CS_N<2>")
	)
	(segment
		(start 166.702232 -245.855236)
		(end 166.702232 -245.636796)
		(width 0.18288)
		(layer "In4.Cu")
		(net "M_G_CPU1_SB_CS_N<2>")
	)
	(segment
		(start 167.422322 -245.855236)
		(end 167.262302 -246.015256)
		(width 0.18288)
		(layer "In4.Cu")
		(net "M_G_CPU1_SB_CS_N<2>")
	)
	(segment
		(start 166.163244 -245.445026)
		(end 165.636702 -245.971568)
		(width 0.18288)
		(layer "In4.Cu")
		(net "M_G_CPU1_SB_CS_N<2>")
	)
	(segment
		(start 134.008368 -246.853964)
		(end 133.997954 -246.86006)
		(width 0.088646)
		(layer "In4.Cu")
		(net "M_G_CPU1_SB_CS_N<2>")
	)
	(segment
		(start 155.535122 -245.597934)
		(end 148.566886 -245.597934)
		(width 0.18288)
		(layer "In4.Cu")
		(net "M_G_CPU1_SB_CS_N<2>")
	)
	(segment
		(start 170.064684 -245.833646)
		(end 170.064684 -246.303546)
		(width 0.18288)
		(layer "In4.Cu")
		(net "M_G_CPU1_SB_CS_N<2>")
	)
	(segment
		(start 134.939532 -246.85879)
		(end 134.9375 -246.86006)
		(width 0.088646)
		(layer "In4.Cu")
		(net "M_G_CPU1_SB_CS_N<2>")
	)
	(segment
		(start 170.758104 -245.833646)
		(end 170.575224 -245.650766)
		(width 0.18288)
		(layer "In4.Cu")
		(net "M_G_CPU1_SB_CS_N<2>")
	)
	(segment
		(start 178.731672 -246.359426)
		(end 178.548792 -246.176546)
		(width 0.18288)
		(layer "In4.Cu")
		(net "M_G_CPU1_SB_CS_N<2>")
	)
	(segment
		(start 185.361834 -246.126508)
		(end 185.201814 -246.286528)
		(width 0.18288)
		(layer "In4.Cu")
		(net "M_G_CPU1_SB_CS_N<2>")
	)
	(segment
		(start 167.262302 -246.015256)
		(end 166.862252 -246.015256)
		(width 0.18288)
		(layer "In4.Cu")
		(net "M_G_CPU1_SB_CS_N<2>")
	)
	(segment
		(start 130.594862 -246.837708)
		(end 129.966212 -246.364506)
		(width 0.088646)
		(layer "In4.Cu")
		(net "M_G_CPU1_SB_CS_N<2>")
	)
	(segment
		(start 163.493196 -246.34063)
		(end 163.286186 -246.13362)
		(width 0.18288)
		(layer "In4.Cu")
		(net "M_G_CPU1_SB_CS_N<2>")
	)
	(segment
		(start 137.826496 -247.087644)
		(end 137.642854 -247.087644)
		(width 0.088646)
		(layer "In4.Cu")
		(net "M_G_CPU1_SB_CS_N<2>")
	)
	(segment
		(start 166.862252 -246.015256)
		(end 166.702232 -245.855236)
		(width 0.18288)
		(layer "In4.Cu")
		(net "M_G_CPU1_SB_CS_N<2>")
	)
	(segment
		(start 177.855372 -245.863872)
		(end 177.855372 -246.176546)
		(width 0.18288)
		(layer "In4.Cu")
		(net "M_G_CPU1_SB_CS_N<2>")
	)
	(segment
		(start 169.073576 -246.130826)
		(end 168.344342 -246.130826)
		(width 0.18288)
		(layer "In4.Cu")
		(net "M_G_CPU1_SB_CS_N<2>")
	)
	(segment
		(start 185.201814 -246.286528)
		(end 182.905908 -246.286528)
		(width 0.18288)
		(layer "In4.Cu")
		(net "M_G_CPU1_SB_CS_N<2>")
	)
	(segment
		(start 133.068314 -246.853964)
		(end 132.986018 -246.902224)
		(width 0.088646)
		(layer "In4.Cu")
		(net "M_G_CPU1_SB_CS_N<2>")
	)
	(segment
		(start 181.778656 -246.19204)
		(end 181.778656 -246.391176)
		(width 0.18288)
		(layer "In4.Cu")
		(net "M_G_CPU1_SB_CS_N<2>")
	)
	(segment
		(start 162.729164 -245.826534)
		(end 162.54603 -246.009668)
		(width 0.18288)
		(layer "In4.Cu")
		(net "M_G_CPU1_SB_CS_N<2>")
	)
	(segment
		(start 167.422322 -245.605046)
		(end 167.422322 -245.855236)
		(width 0.18288)
		(layer "In4.Cu")
		(net "M_G_CPU1_SB_CS_N<2>")
	)
	(segment
		(start 169.881804 -246.486426)
		(end 169.429176 -246.486426)
		(width 0.18288)
		(layer "In4.Cu")
		(net "M_G_CPU1_SB_CS_N<2>")
	)
	(segment
		(start 130.623564 -246.853964)
		(end 130.594862 -246.837708)
		(width 0.088646)
		(layer "In4.Cu")
		(net "M_G_CPU1_SB_CS_N<2>")
	)
	(segment
		(start 162.54603 -246.009668)
		(end 162.54603 -246.123206)
		(width 0.18288)
		(layer "In4.Cu")
		(net "M_G_CPU1_SB_CS_N<2>")
	)
	(segment
		(start 168.024302 -245.445026)
		(end 167.582342 -245.445026)
		(width 0.18288)
		(layer "In4.Cu")
		(net "M_G_CPU1_SB_CS_N<2>")
	)
	(segment
		(start 169.429176 -246.486426)
		(end 169.073576 -246.130826)
		(width 0.18288)
		(layer "In4.Cu")
		(net "M_G_CPU1_SB_CS_N<2>")
	)
	(segment
		(start 164.497766 -246.099584)
		(end 164.497766 -246.158766)
		(width 0.18288)
		(layer "In4.Cu")
		(net "M_G_CPU1_SB_CS_N<2>")
	)
	(segment
		(start 173.22038 -246.192802)
		(end 173.220126 -246.192548)
		(width 0.18288)
		(layer "In4.Cu")
		(net "M_G_CPU1_SB_CS_N<2>")
	)
	(segment
		(start 148.566886 -245.597934)
		(end 148.166836 -245.997984)
		(width 0.18288)
		(layer "In4.Cu")
		(net "M_G_CPU1_SB_CS_N<2>")
	)
	(segment
		(start 131.188714 -246.853964)
		(end 131.18846 -246.853964)
		(width 0.088646)
		(layer "In4.Cu")
		(net "M_G_CPU1_SB_CS_N<2>")
	)
	(segment
		(start 166.510462 -245.445026)
		(end 166.163244 -245.445026)
		(width 0.18288)
		(layer "In4.Cu")
		(net "M_G_CPU1_SB_CS_N<2>")
	)
	(segment
		(start 148.166836 -245.997984)
		(end 141.288008 -245.997984)
		(width 0.18288)
		(layer "In4.Cu")
		(net "M_G_CPU1_SB_CS_N<2>")
	)
	(segment
		(start 178.038252 -245.680992)
		(end 177.855372 -245.863872)
		(width 0.18288)
		(layer "In4.Cu")
		(net "M_G_CPU1_SB_CS_N<2>")
	)
	(segment
		(start 164.315902 -246.34063)
		(end 163.493196 -246.34063)
		(width 0.18288)
		(layer "In4.Cu")
		(net "M_G_CPU1_SB_CS_N<2>")
	)
	(segment
		(start 164.625782 -245.971568)
		(end 164.497766 -246.099584)
		(width 0.18288)
		(layer "In4.Cu")
		(net "M_G_CPU1_SB_CS_N<2>")
	)
	(segment
		(start 178.365912 -245.680992)
		(end 178.038252 -245.680992)
		(width 0.18288)
		(layer "In4.Cu")
		(net "M_G_CPU1_SB_CS_N<2>")
	)
	(segment
		(start 187.883546 -245.76659)
		(end 187.363608 -246.286528)
		(width 0.18288)
		(layer "In4.Cu")
		(net "M_G_CPU1_SB_CS_N<2>")
	)
	(segment
		(start 181.270656 -246.551196)
		(end 180.910992 -246.191532)
		(width 0.18288)
		(layer "In4.Cu")
		(net "M_G_CPU1_SB_CS_N<2>")
	)
	(segment
		(start 132.128768 -246.853964)
		(end 132.128514 -246.853964)
		(width 0.088646)
		(layer "In4.Cu")
		(net "M_G_CPU1_SB_CS_N<2>")
	)
	(segment
		(start 179.39512 -246.191532)
		(end 179.227226 -246.359426)
		(width 0.18288)
		(layer "In4.Cu")
		(net "M_G_CPU1_SB_CS_N<2>")
	)
	(segment
		(start 178.548792 -245.863872)
		(end 178.365912 -245.680992)
		(width 0.18288)
		(layer "In4.Cu")
		(net "M_G_CPU1_SB_CS_N<2>")
	)
	(segment
		(start 162.54603 -246.123206)
		(end 162.38601 -246.283226)
		(width 0.18288)
		(layer "In4.Cu")
		(net "M_G_CPU1_SB_CS_N<2>")
	)
	(segment
		(start 134.948168 -246.853964)
		(end 134.939532 -246.85879)
		(width 0.088646)
		(layer "In4.Cu")
		(net "M_G_CPU1_SB_CS_N<2>")
	)
	(segment
		(start 181.618636 -246.551196)
		(end 181.270656 -246.551196)
		(width 0.18288)
		(layer "In4.Cu")
		(net "M_G_CPU1_SB_CS_N<2>")
	)
	(segment
		(start 165.636702 -245.971568)
		(end 164.625782 -245.971568)
		(width 0.18288)
		(layer "In4.Cu")
		(net "M_G_CPU1_SB_CS_N<2>")
	)
	(segment
		(start 162.38601 -246.283226)
		(end 160.316926 -246.283226)
		(width 0.18288)
		(layer "In4.Cu")
		(net "M_G_CPU1_SB_CS_N<2>")
	)
	(segment
		(start 164.497766 -246.158766)
		(end 164.315902 -246.34063)
		(width 0.18288)
		(layer "In4.Cu")
		(net "M_G_CPU1_SB_CS_N<2>")
	)
	(segment
		(start 177.105056 -246.192802)
		(end 173.22038 -246.192802)
		(width 0.18288)
		(layer "In4.Cu")
		(net "M_G_CPU1_SB_CS_N<2>")
	)
	(segment
		(start 177.855372 -246.176546)
		(end 177.672492 -246.359426)
		(width 0.18288)
		(layer "In4.Cu")
		(net "M_G_CPU1_SB_CS_N<2>")
	)
	(segment
		(start 182.905908 -246.286528)
		(end 182.6514 -246.03202)
		(width 0.18288)
		(layer "In4.Cu")
		(net "M_G_CPU1_SB_CS_N<2>")
	)
	(segment
		(start 168.344342 -246.130826)
		(end 168.184322 -245.970806)
		(width 0.18288)
		(layer "In4.Cu")
		(net "M_G_CPU1_SB_CS_N<2>")
	)
	(segment
		(start 160.316926 -246.283226)
		(end 160.111186 -246.077486)
		(width 0.18288)
		(layer "In4.Cu")
		(net "M_G_CPU1_SB_CS_N<2>")
	)
	(segment
		(start 167.582342 -245.445026)
		(end 167.422322 -245.605046)
		(width 0.18288)
		(layer "In4.Cu")
		(net "M_G_CPU1_SB_CS_N<2>")
	)
	(segment
		(start 132.508244 -246.856758)
		(end 132.507482 -246.856504)
		(width 0.088646)
		(layer "In4.Cu")
		(net "M_G_CPU1_SB_CS_N<2>")
	)
	(segment
		(start 177.672492 -246.359426)
		(end 177.27168 -246.359426)
		(width 0.18288)
		(layer "In4.Cu")
		(net "M_G_CPU1_SB_CS_N<2>")
	)
	(segment
		(start 180.910992 -246.191532)
		(end 179.39512 -246.191532)
		(width 0.18288)
		(layer "In4.Cu")
		(net "M_G_CPU1_SB_CS_N<2>")
	)
	(segment
		(start 187.363608 -246.286528)
		(end 186.221624 -246.286528)
		(width 0.18288)
		(layer "In4.Cu")
		(net "M_G_CPU1_SB_CS_N<2>")
	)
	(segment
		(start 163.286186 -246.13362)
		(end 163.286186 -245.986554)
		(width 0.18288)
		(layer "In4.Cu")
		(net "M_G_CPU1_SB_CS_N<2>")
	)
	(segment
		(start 168.184322 -245.970806)
		(end 168.184322 -245.605046)
		(width 0.18288)
		(layer "In4.Cu")
		(net "M_G_CPU1_SB_CS_N<2>")
	)
	(segment
		(start 156.693108 -246.077486)
		(end 155.535122 -245.597934)
		(width 0.18288)
		(layer "In4.Cu")
		(net "M_G_CPU1_SB_CS_N<2>")
	)
	(segment
		(start 170.247564 -245.650766)
		(end 170.064684 -245.833646)
		(width 0.18288)
		(layer "In4.Cu")
		(net "M_G_CPU1_SB_CS_N<2>")
	)
	(segment
		(start 137.642854 -247.087644)
		(end 137.484866 -246.929656)
		(width 0.088646)
		(layer "In4.Cu")
		(net "M_G_CPU1_SB_CS_N<2>")
	)
	(segment
		(start 139.64539 -246.67845)
		(end 139.236196 -247.087644)
		(width 0.18288)
		(layer "In4.Cu")
		(net "M_G_CPU1_SB_CS_N<2>")
	)
	(segment
		(start 141.288008 -245.997984)
		(end 139.64539 -246.67845)
		(width 0.18288)
		(layer "In4.Cu")
		(net "M_G_CPU1_SB_CS_N<2>")
	)
	(segment
		(start 186.221624 -246.286528)
		(end 186.061604 -246.126508)
		(width 0.18288)
		(layer "In4.Cu")
		(net "M_G_CPU1_SB_CS_N<2>")
	)
	(segment
		(start 182.6514 -246.03202)
		(end 181.938676 -246.03202)
		(width 0.18288)
		(layer "In4.Cu")
		(net "M_G_CPU1_SB_CS_N<2>")
	)
	(segment
		(start 168.184322 -245.605046)
		(end 168.024302 -245.445026)
		(width 0.18288)
		(layer "In4.Cu")
		(net "M_G_CPU1_SB_CS_N<2>")
	)
	(segment
		(start 170.064684 -246.303546)
		(end 169.881804 -246.486426)
		(width 0.18288)
		(layer "In4.Cu")
		(net "M_G_CPU1_SB_CS_N<2>")
	)
	(segment
		(start 181.938676 -246.03202)
		(end 181.778656 -246.19204)
		(width 0.18288)
		(layer "In4.Cu")
		(net "M_G_CPU1_SB_CS_N<2>")
	)
	(segment
		(start 186.061604 -245.780814)
		(end 185.901584 -245.620794)
		(width 0.18288)
		(layer "In4.Cu")
		(net "M_G_CPU1_SB_CS_N<2>")
	)
	(segment
		(start 170.758104 -246.303546)
		(end 170.758104 -245.833646)
		(width 0.18288)
		(layer "In4.Cu")
		(net "M_G_CPU1_SB_CS_N<2>")
	)
	(segment
		(start 163.126166 -245.826534)
		(end 162.729164 -245.826534)
		(width 0.18288)
		(layer "In4.Cu")
		(net "M_G_CPU1_SB_CS_N<2>")
	)
	(segment
		(start 170.575224 -245.650766)
		(end 170.247564 -245.650766)
		(width 0.18288)
		(layer "In4.Cu")
		(net "M_G_CPU1_SB_CS_N<2>")
	)
	(segment
		(start 171.734226 -246.486426)
		(end 170.940984 -246.486426)
		(width 0.18288)
		(layer "In4.Cu")
		(net "M_G_CPU1_SB_CS_N<2>")
	)
	(segment
		(start 186.061604 -246.126508)
		(end 186.061604 -245.780814)
		(width 0.18288)
		(layer "In4.Cu")
		(net "M_G_CPU1_SB_CS_N<2>")
	)
	(segment
		(start 178.548792 -246.176546)
		(end 178.548792 -245.863872)
		(width 0.18288)
		(layer "In4.Cu")
		(net "M_G_CPU1_SB_CS_N<2>")
	)
	(segment
		(start 139.236196 -247.087644)
		(end 137.826496 -247.087644)
		(width 0.18288)
		(layer "In4.Cu")
		(net "M_G_CPU1_SB_CS_N<2>")
	)
	(segment
		(start 185.361834 -245.792498)
		(end 185.361834 -246.126508)
		(width 0.18288)
		(layer "In4.Cu")
		(net "M_G_CPU1_SB_CS_N<2>")
	)
	(segment
		(start 163.286186 -245.986554)
		(end 163.126166 -245.826534)
		(width 0.18288)
		(layer "In4.Cu")
		(net "M_G_CPU1_SB_CS_N<2>")
	)
	(segment
		(start 179.227226 -246.359426)
		(end 178.731672 -246.359426)
		(width 0.18288)
		(layer "In4.Cu")
		(net "M_G_CPU1_SB_CS_N<2>")
	)
	(segment
		(start 172.028104 -246.192548)
		(end 171.734226 -246.486426)
		(width 0.18288)
		(layer "In4.Cu")
		(net "M_G_CPU1_SB_CS_N<2>")
	)
	(segment
		(start 185.533538 -245.620794)
		(end 185.361834 -245.792498)
		(width 0.18288)
		(layer "In4.Cu")
		(net "M_G_CPU1_SB_CS_N<2>")
	)
	(segment
		(start 177.27168 -246.359426)
		(end 177.105056 -246.192802)
		(width 0.18288)
		(layer "In4.Cu")
		(net "M_G_CPU1_SB_CS_N<2>")
	)
	(segment
		(start 166.702232 -245.636796)
		(end 166.510462 -245.445026)
		(width 0.18288)
		(layer "In4.Cu")
		(net "M_G_CPU1_SB_CS_N<2>")
	)
	(segment
		(start 160.111186 -246.077486)
		(end 156.693108 -246.077486)
		(width 0.18288)
		(layer "In4.Cu")
		(net "M_G_CPU1_SB_CS_N<2>")
	)
	(segment
		(start 132.128514 -246.853964)
		(end 132.113782 -246.8626)
		(width 0.088646)
		(layer "In4.Cu")
		(net "M_G_CPU1_SB_CS_N<2>")
	)
	(segment
		(start 170.940984 -246.486426)
		(end 170.758104 -246.303546)
		(width 0.18288)
		(layer "In4.Cu")
		(net "M_G_CPU1_SB_CS_N<2>")
	)
	(segment
		(start 181.778656 -246.391176)
		(end 181.618636 -246.551196)
		(width 0.18288)
		(layer "In4.Cu")
		(net "M_G_CPU1_SB_CS_N<2>")
	)
	(segment
		(start 173.220126 -246.192548)
		(end 172.028104 -246.192548)
		(width 0.18288)
		(layer "In4.Cu")
		(net "M_G_CPU1_SB_CS_N<2>")
	)
	(arc
		(start 133.44271 -246.853964)
		(mid 133.255512 -246.803821)
		(end 133.068314 -246.853964)
		(width 0.088646)
		(layer "In4.Cu")
		(net "M_G_CPU1_SB_CS_N<2>")
	)
	(arc
		(start 132.986018 -246.902224)
		(mid 132.786939 -246.955387)
		(end 132.588762 -246.898922)
		(width 0.088646)
		(layer "In4.Cu")
		(net "M_G_CPU1_SB_CS_N<2>")
	)
	(arc
		(start 132.507482 -246.856504)
		(mid 132.318471 -246.803837)
		(end 132.128768 -246.853964)
		(width 0.088646)
		(layer "In4.Cu")
		(net "M_G_CPU1_SB_CS_N<2>")
	)
	(arc
		(start 134.382764 -246.853964)
		(mid 134.195566 -246.803821)
		(end 134.008368 -246.853964)
		(width 0.088646)
		(layer "In4.Cu")
		(net "M_G_CPU1_SB_CS_N<2>")
	)
	(arc
		(start 137.202164 -246.853964)
		(mid 137.014966 -246.803821)
		(end 136.827768 -246.853964)
		(width 0.088646)
		(layer "In4.Cu")
		(net "M_G_CPU1_SB_CS_N<2>")
	)
	(arc
		(start 131.56311 -246.853964)
		(mid 131.375912 -246.803821)
		(end 131.188714 -246.853964)
		(width 0.088646)
		(layer "In4.Cu")
		(net "M_G_CPU1_SB_CS_N<2>")
	)
	(arc
		(start 132.549138 -246.87784)
		(mid 132.528477 -246.867715)
		(end 132.508244 -246.856758)
		(width 0.088646)
		(layer "In4.Cu")
		(net "M_G_CPU1_SB_CS_N<2>")
	)
	(arc
		(start 133.997954 -246.86006)
		(mid 133.719522 -246.929906)
		(end 133.44271 -246.853964)
		(width 0.088646)
		(layer "In4.Cu")
		(net "M_G_CPU1_SB_CS_N<2>")
	)
	(arc
		(start 136.827768 -246.853964)
		(mid 136.545066 -246.92974)
		(end 136.262364 -246.853964)
		(width 0.088646)
		(layer "In4.Cu")
		(net "M_G_CPU1_SB_CS_N<2>")
	)
	(arc
		(start 136.262364 -246.853964)
		(mid 136.075166 -246.803821)
		(end 135.887968 -246.853964)
		(width 0.088646)
		(layer "In4.Cu")
		(net "M_G_CPU1_SB_CS_N<2>")
	)
	(arc
		(start 135.887968 -246.853964)
		(mid 135.605266 -246.929706)
		(end 135.322564 -246.853964)
		(width 0.088646)
		(layer "In4.Cu")
		(net "M_G_CPU1_SB_CS_N<2>")
	)
	(arc
		(start 137.484866 -246.929656)
		(mid 137.338522 -246.910448)
		(end 137.202164 -246.853964)
		(width 0.088646)
		(layer "In4.Cu")
		(net "M_G_CPU1_SB_CS_N<2>")
	)
	(arc
		(start 135.322564 -246.853964)
		(mid 135.135366 -246.803821)
		(end 134.948168 -246.853964)
		(width 0.088646)
		(layer "In4.Cu")
		(net "M_G_CPU1_SB_CS_N<2>")
	)
	(arc
		(start 132.588762 -246.898922)
		(mid 132.569254 -246.887809)
		(end 132.549138 -246.87784)
		(width 0.088646)
		(layer "In4.Cu")
		(net "M_G_CPU1_SB_CS_N<2>")
	)
	(arc
		(start 131.18846 -246.853964)
		(mid 130.906012 -246.929647)
		(end 130.623564 -246.853964)
		(width 0.088646)
		(layer "In4.Cu")
		(net "M_G_CPU1_SB_CS_N<2>")
	)
	(arc
		(start 134.9375 -246.86006)
		(mid 134.659322 -246.929783)
		(end 134.382764 -246.853964)
		(width 0.088646)
		(layer "In4.Cu")
		(net "M_G_CPU1_SB_CS_N<2>")
	)
	(arc
		(start 132.113782 -246.8626)
		(mid 131.837307 -246.92992)
		(end 131.56311 -246.853964)
		(width 0.088646)
		(layer "In4.Cu")
		(net "M_G_CPU1_SB_CS_N<2>")
	)
	(segment
		(start 199.527414 -244.916706)
		(end 200.632314 -244.916706)
		(width 0.20066)
		(layer "F.Cu")
		(net "M_G_CPU1_SB_CS_N<1>")
	)
	(segment
		(start 131.376166 -246.086376)
		(end 131.376166 -245.55069)
		(width 0.20066)
		(layer "F.Cu")
		(net "M_G_CPU1_SB_CS_N<1>")
	)
	(segment
		(start 131.375912 -246.08663)
		(end 131.376166 -246.086376)
		(width 0.20066)
		(layer "F.Cu")
		(net "M_G_CPU1_SB_CS_N<1>")
	)
	(segment
		(start 132.50291 -245.875048)
		(end 132.487416 -245.883938)
		(width 0.088646)
		(layer "In4.Cu")
		(net "M_G_CPU1_SB_CS_N<1>")
	)
	(segment
		(start 170.33113 -243.642642)
		(end 168.699942 -243.642642)
		(width 0.18288)
		(layer "In4.Cu")
		(net "M_G_CPU1_SB_CS_N<1>")
	)
	(segment
		(start 186.189874 -243.642388)
		(end 186.006994 -243.459508)
		(width 0.18288)
		(layer "In4.Cu")
		(net "M_G_CPU1_SB_CS_N<1>")
	)
	(segment
		(start 185.124344 -243.189252)
		(end 185.124344 -243.482368)
		(width 0.18288)
		(layer "In4.Cu")
		(net "M_G_CPU1_SB_CS_N<1>")
	)
	(segment
		(start 146.86534 -244.992144)
		(end 140.910056 -244.992144)
		(width 0.18288)
		(layer "In4.Cu")
		(net "M_G_CPU1_SB_CS_N<1>")
	)
	(segment
		(start 185.124344 -243.482368)
		(end 184.964324 -243.642388)
		(width 0.18288)
		(layer "In4.Cu")
		(net "M_G_CPU1_SB_CS_N<1>")
	)
	(segment
		(start 179.252626 -243.413026)
		(end 177.372772 -243.413026)
		(width 0.18288)
		(layer "In4.Cu")
		(net "M_G_CPU1_SB_CS_N<1>")
	)
	(segment
		(start 147.766278 -244.091206)
		(end 146.86534 -244.992144)
		(width 0.18288)
		(layer "In4.Cu")
		(net "M_G_CPU1_SB_CS_N<1>")
	)
	(segment
		(start 185.846974 -243.029232)
		(end 185.284364 -243.029232)
		(width 0.18288)
		(layer "In4.Cu")
		(net "M_G_CPU1_SB_CS_N<1>")
	)
	(segment
		(start 133.068314 -245.875048)
		(end 133.053582 -245.866412)
		(width 0.088646)
		(layer "In4.Cu")
		(net "M_G_CPU1_SB_CS_N<1>")
	)
	(segment
		(start 134.939532 -245.870222)
		(end 134.9375 -245.868952)
		(width 0.088646)
		(layer "In4.Cu")
		(net "M_G_CPU1_SB_CS_N<1>")
	)
	(segment
		(start 166.23411 -243.642642)
		(end 159.42564 -243.642642)
		(width 0.18288)
		(layer "In4.Cu")
		(net "M_G_CPU1_SB_CS_N<1>")
	)
	(segment
		(start 186.006994 -243.459508)
		(end 186.006994 -243.189252)
		(width 0.18288)
		(layer "In4.Cu")
		(net "M_G_CPU1_SB_CS_N<1>")
	)
	(segment
		(start 177.14341 -243.642388)
		(end 170.331384 -243.642388)
		(width 0.18288)
		(layer "In4.Cu")
		(net "M_G_CPU1_SB_CS_N<1>")
	)
	(segment
		(start 139.281916 -245.711726)
		(end 138.564874 -245.711726)
		(width 0.18288)
		(layer "In4.Cu")
		(net "M_G_CPU1_SB_CS_N<1>")
	)
	(segment
		(start 190.58763 -242.78844)
		(end 189.733682 -243.642388)
		(width 0.18288)
		(layer "In4.Cu")
		(net "M_G_CPU1_SB_CS_N<1>")
	)
	(segment
		(start 137.826496 -245.406418)
		(end 136.74979 -245.406418)
		(width 0.088646)
		(layer "In4.Cu")
		(net "M_G_CPU1_SB_CS_N<1>")
	)
	(segment
		(start 140.833856 -245.068344)
		(end 139.281916 -245.711726)
		(width 0.18288)
		(layer "In4.Cu")
		(net "M_G_CPU1_SB_CS_N<1>")
	)
	(segment
		(start 189.733682 -243.642388)
		(end 186.189874 -243.642388)
		(width 0.18288)
		(layer "In4.Cu")
		(net "M_G_CPU1_SB_CS_N<1>")
	)
	(segment
		(start 159.425386 -243.642388)
		(end 155.894532 -243.642388)
		(width 0.18288)
		(layer "In4.Cu")
		(net "M_G_CPU1_SB_CS_N<1>")
	)
	(segment
		(start 140.910056 -244.992144)
		(end 140.833856 -245.068344)
		(width 0.18288)
		(layer "In4.Cu")
		(net "M_G_CPU1_SB_CS_N<1>")
	)
	(segment
		(start 155.894532 -243.642388)
		(end 155.445714 -244.091206)
		(width 0.18288)
		(layer "In4.Cu")
		(net "M_G_CPU1_SB_CS_N<1>")
	)
	(segment
		(start 184.964324 -243.642388)
		(end 179.481988 -243.642388)
		(width 0.18288)
		(layer "In4.Cu")
		(net "M_G_CPU1_SB_CS_N<1>")
	)
	(segment
		(start 193.906648 -244.489478)
		(end 192.20561 -242.78844)
		(width 0.18288)
		(layer "In4.Cu")
		(net "M_G_CPU1_SB_CS_N<1>")
	)
	(segment
		(start 132.14096 -245.882668)
		(end 131.761992 -245.656862)
		(width 0.088646)
		(layer "In4.Cu")
		(net "M_G_CPU1_SB_CS_N<1>")
	)
	(segment
		(start 199.527414 -244.916706)
		(end 199.100186 -244.489478)
		(width 0.18288)
		(layer "In4.Cu")
		(net "M_G_CPU1_SB_CS_N<1>")
	)
	(segment
		(start 185.284364 -243.029232)
		(end 185.124344 -243.189252)
		(width 0.18288)
		(layer "In4.Cu")
		(net "M_G_CPU1_SB_CS_N<1>")
	)
	(segment
		(start 136.74979 -245.406418)
		(end 136.340342 -245.815866)
		(width 0.088646)
		(layer "In4.Cu")
		(net "M_G_CPU1_SB_CS_N<1>")
	)
	(segment
		(start 179.481988 -243.642388)
		(end 179.252626 -243.413026)
		(width 0.18288)
		(layer "In4.Cu")
		(net "M_G_CPU1_SB_CS_N<1>")
	)
	(segment
		(start 155.445714 -244.091206)
		(end 147.766278 -244.091206)
		(width 0.18288)
		(layer "In4.Cu")
		(net "M_G_CPU1_SB_CS_N<1>")
	)
	(segment
		(start 133.08076 -245.882668)
		(end 133.068822 -245.875556)
		(width 0.088646)
		(layer "In4.Cu")
		(net "M_G_CPU1_SB_CS_N<1>")
	)
	(segment
		(start 134.948168 -245.875048)
		(end 134.939532 -245.870222)
		(width 0.088646)
		(layer "In4.Cu")
		(net "M_G_CPU1_SB_CS_N<1>")
	)
	(segment
		(start 192.20561 -242.78844)
		(end 190.58763 -242.78844)
		(width 0.18288)
		(layer "In4.Cu")
		(net "M_G_CPU1_SB_CS_N<1>")
	)
	(segment
		(start 133.442964 -245.875048)
		(end 133.442964 -245.875302)
		(width 0.088646)
		(layer "In4.Cu")
		(net "M_G_CPU1_SB_CS_N<1>")
	)
	(segment
		(start 199.100186 -244.489478)
		(end 193.906648 -244.489478)
		(width 0.18288)
		(layer "In4.Cu")
		(net "M_G_CPU1_SB_CS_N<1>")
	)
	(segment
		(start 168.699942 -243.642642)
		(end 168.165526 -243.108226)
		(width 0.18288)
		(layer "In4.Cu")
		(net "M_G_CPU1_SB_CS_N<1>")
	)
	(segment
		(start 168.165526 -243.108226)
		(end 166.768526 -243.108226)
		(width 0.18288)
		(layer "In4.Cu")
		(net "M_G_CPU1_SB_CS_N<1>")
	)
	(segment
		(start 186.006994 -243.189252)
		(end 185.846974 -243.029232)
		(width 0.18288)
		(layer "In4.Cu")
		(net "M_G_CPU1_SB_CS_N<1>")
	)
	(segment
		(start 170.331384 -243.642388)
		(end 170.33113 -243.642642)
		(width 0.18288)
		(layer "In4.Cu")
		(net "M_G_CPU1_SB_CS_N<1>")
	)
	(segment
		(start 177.372772 -243.413026)
		(end 177.14341 -243.642388)
		(width 0.18288)
		(layer "In4.Cu")
		(net "M_G_CPU1_SB_CS_N<1>")
	)
	(segment
		(start 166.768526 -243.108226)
		(end 166.23411 -243.642642)
		(width 0.18288)
		(layer "In4.Cu")
		(net "M_G_CPU1_SB_CS_N<1>")
	)
	(segment
		(start 138.259566 -245.406418)
		(end 137.826496 -245.406418)
		(width 0.18288)
		(layer "In4.Cu")
		(net "M_G_CPU1_SB_CS_N<1>")
	)
	(segment
		(start 159.42564 -243.642642)
		(end 159.425386 -243.642388)
		(width 0.18288)
		(layer "In4.Cu")
		(net "M_G_CPU1_SB_CS_N<1>")
	)
	(segment
		(start 138.564874 -245.711726)
		(end 138.259566 -245.406418)
		(width 0.18288)
		(layer "In4.Cu")
		(net "M_G_CPU1_SB_CS_N<1>")
	)
	(arc
		(start 132.487416 -245.883938)
		(mid 132.314038 -245.925686)
		(end 132.14096 -245.882668)
		(width 0.088646)
		(layer "In4.Cu")
		(net "M_G_CPU1_SB_CS_N<1>")
	)
	(arc
		(start 136.262364 -245.875048)
		(mid 136.075166 -245.925191)
		(end 135.887968 -245.875048)
		(width 0.088646)
		(layer "In4.Cu")
		(net "M_G_CPU1_SB_CS_N<1>")
	)
	(arc
		(start 135.322564 -245.875048)
		(mid 135.135366 -245.925191)
		(end 134.948168 -245.875048)
		(width 0.088646)
		(layer "In4.Cu")
		(net "M_G_CPU1_SB_CS_N<1>")
	)
	(arc
		(start 131.761992 -245.656862)
		(mid 131.576255 -245.577691)
		(end 131.376166 -245.55069)
		(width 0.088646)
		(layer "In4.Cu")
		(net "M_G_CPU1_SB_CS_N<1>")
	)
	(arc
		(start 133.068822 -245.875556)
		(mid 133.068568 -245.875302)
		(end 133.068314 -245.875048)
		(width 0.088646)
		(layer "In4.Cu")
		(net "M_G_CPU1_SB_CS_N<1>")
	)
	(arc
		(start 135.887968 -245.875048)
		(mid 135.605266 -245.799272)
		(end 135.322564 -245.875048)
		(width 0.088646)
		(layer "In4.Cu")
		(net "M_G_CPU1_SB_CS_N<1>")
	)
	(arc
		(start 133.053582 -245.866412)
		(mid 132.777107 -245.799092)
		(end 132.50291 -245.875048)
		(width 0.088646)
		(layer "In4.Cu")
		(net "M_G_CPU1_SB_CS_N<1>")
	)
	(arc
		(start 134.008368 -245.875048)
		(mid 133.725666 -245.799272)
		(end 133.442964 -245.875048)
		(width 0.088646)
		(layer "In4.Cu")
		(net "M_G_CPU1_SB_CS_N<1>")
	)
	(arc
		(start 136.340342 -245.815866)
		(mid 136.303292 -245.848012)
		(end 136.262364 -245.875048)
		(width 0.088646)
		(layer "In4.Cu")
		(net "M_G_CPU1_SB_CS_N<1>")
	)
	(arc
		(start 134.9375 -245.868952)
		(mid 134.659322 -245.799229)
		(end 134.382764 -245.875048)
		(width 0.088646)
		(layer "In4.Cu")
		(net "M_G_CPU1_SB_CS_N<1>")
	)
	(arc
		(start 134.382764 -245.875048)
		(mid 134.195566 -245.925191)
		(end 134.008368 -245.875048)
		(width 0.088646)
		(layer "In4.Cu")
		(net "M_G_CPU1_SB_CS_N<1>")
	)
	(arc
		(start 133.442964 -245.875302)
		(mid 133.262819 -245.925589)
		(end 133.08076 -245.882668)
		(width 0.088646)
		(layer "In4.Cu")
		(net "M_G_CPU1_SB_CS_N<1>")
	)
	(segment
		(start 131.845812 -246.900192)
		(end 131.845812 -246.364506)
		(width 0.20066)
		(layer "F.Cu")
		(net "M_G_CPU1_SB_CS_N<0>")
	)
	(segment
		(start 195.427346 -245.76659)
		(end 196.532246 -245.76659)
		(width 0.20066)
		(layer "F.Cu")
		(net "M_G_CPU1_SB_CS_N<0>")
	)
	(segment
		(start 131.846066 -246.900446)
		(end 131.845812 -246.900192)
		(width 0.20066)
		(layer "F.Cu")
		(net "M_G_CPU1_SB_CS_N<0>")
	)
	(segment
		(start 193.192146 -244.91569)
		(end 192.827656 -244.91569)
		(width 0.18288)
		(layer "In4.Cu")
		(net "M_G_CPU1_SB_CS_N<0>")
	)
	(segment
		(start 188.457586 -245.331234)
		(end 188.289438 -245.331234)
		(width 0.18288)
		(layer "In4.Cu")
		(net "M_G_CPU1_SB_CS_N<0>")
	)
	(segment
		(start 190.605664 -245.54053)
		(end 190.445644 -245.38051)
		(width 0.18288)
		(layer "In4.Cu")
		(net "M_G_CPU1_SB_CS_N<0>")
	)
	(segment
		(start 188.617606 -245.491254)
		(end 188.457586 -245.331234)
		(width 0.18288)
		(layer "In4.Cu")
		(net "M_G_CPU1_SB_CS_N<0>")
	)
	(segment
		(start 148.360638 -245.100094)
		(end 147.798028 -245.662704)
		(width 0.18288)
		(layer "In4.Cu")
		(net "M_G_CPU1_SB_CS_N<0>")
	)
	(segment
		(start 167.809926 -244.454426)
		(end 167.124126 -244.454426)
		(width 0.18288)
		(layer "In4.Cu")
		(net "M_G_CPU1_SB_CS_N<0>")
	)
	(segment
		(start 185.107326 -245.338346)
		(end 179.628546 -245.338346)
		(width 0.18288)
		(layer "In4.Cu")
		(net "M_G_CPU1_SB_CS_N<0>")
	)
	(segment
		(start 159.231838 -245.361206)
		(end 159.231838 -245.189502)
		(width 0.18288)
		(layer "In4.Cu")
		(net "M_G_CPU1_SB_CS_N<0>")
	)
	(segment
		(start 132.598414 -246.688864)
		(end 132.569966 -246.672354)
		(width 0.088646)
		(layer "In4.Cu")
		(net "M_G_CPU1_SB_CS_N<0>")
	)
	(segment
		(start 139.09167 -246.73941)
		(end 137.826496 -246.73941)
		(width 0.18288)
		(layer "In4.Cu")
		(net "M_G_CPU1_SB_CS_N<0>")
	)
	(segment
		(start 166.692326 -244.886226)
		(end 165.955726 -244.886226)
		(width 0.18288)
		(layer "In4.Cu")
		(net "M_G_CPU1_SB_CS_N<0>")
	)
	(segment
		(start 188.278262 -245.34241)
		(end 187.433966 -245.34241)
		(width 0.18288)
		(layer "In4.Cu")
		(net "M_G_CPU1_SB_CS_N<0>")
	)
	(segment
		(start 188.617606 -246.569738)
		(end 188.617606 -245.491254)
		(width 0.18288)
		(layer "In4.Cu")
		(net "M_G_CPU1_SB_CS_N<0>")
	)
	(segment
		(start 187.433966 -245.34241)
		(end 187.206382 -245.114826)
		(width 0.18288)
		(layer "In4.Cu")
		(net "M_G_CPU1_SB_CS_N<0>")
	)
	(segment
		(start 173.00321 -245.34241)
		(end 171.38015 -245.34241)
		(width 0.18288)
		(layer "In4.Cu")
		(net "M_G_CPU1_SB_CS_N<0>")
	)
	(segment
		(start 131.846066 -246.364506)
		(end 131.845812 -246.364506)
		(width 0.088646)
		(layer "In4.Cu")
		(net "M_G_CPU1_SB_CS_N<0>")
	)
	(segment
		(start 167.124126 -244.454426)
		(end 166.692326 -244.886226)
		(width 0.18288)
		(layer "In4.Cu")
		(net "M_G_CPU1_SB_CS_N<0>")
	)
	(segment
		(start 190.605664 -246.529352)
		(end 190.605664 -245.54053)
		(width 0.18288)
		(layer "In4.Cu")
		(net "M_G_CPU1_SB_CS_N<0>")
	)
	(segment
		(start 158.698438 -245.029482)
		(end 158.538418 -245.189502)
		(width 0.18288)
		(layer "In4.Cu")
		(net "M_G_CPU1_SB_CS_N<0>")
	)
	(segment
		(start 195.427346 -245.76659)
		(end 194.96532 -246.228616)
		(width 0.18288)
		(layer "In4.Cu")
		(net "M_G_CPU1_SB_CS_N<0>")
	)
	(segment
		(start 176.179226 -245.564406)
		(end 175.6791 -245.564406)
		(width 0.18288)
		(layer "In4.Cu")
		(net "M_G_CPU1_SB_CS_N<0>")
	)
	(segment
		(start 159.071818 -245.029482)
		(end 158.698438 -245.029482)
		(width 0.18288)
		(layer "In4.Cu")
		(net "M_G_CPU1_SB_CS_N<0>")
	)
	(segment
		(start 160.418526 -245.165626)
		(end 160.062926 -245.521226)
		(width 0.18288)
		(layer "In4.Cu")
		(net "M_G_CPU1_SB_CS_N<0>")
	)
	(segment
		(start 188.777626 -246.729758)
		(end 188.617606 -246.569738)
		(width 0.18288)
		(layer "In4.Cu")
		(net "M_G_CPU1_SB_CS_N<0>")
	)
	(segment
		(start 189.471046 -245.38051)
		(end 189.311026 -245.54053)
		(width 0.18288)
		(layer "In4.Cu")
		(net "M_G_CPU1_SB_CS_N<0>")
	)
	(segment
		(start 188.289438 -245.331234)
		(end 188.278262 -245.34241)
		(width 0.18288)
		(layer "In4.Cu")
		(net "M_G_CPU1_SB_CS_N<0>")
	)
	(segment
		(start 175.457358 -245.342664)
		(end 173.003464 -245.342664)
		(width 0.18288)
		(layer "In4.Cu")
		(net "M_G_CPU1_SB_CS_N<0>")
	)
	(segment
		(start 132.987796 -246.680228)
		(end 132.973064 -246.688864)
		(width 0.088646)
		(layer "In4.Cu")
		(net "M_G_CPU1_SB_CS_N<0>")
	)
	(segment
		(start 168.597326 -245.241826)
		(end 167.809926 -244.454426)
		(width 0.18288)
		(layer "In4.Cu")
		(net "M_G_CPU1_SB_CS_N<0>")
	)
	(segment
		(start 177.271426 -245.165626)
		(end 177.094642 -245.34241)
		(width 0.18288)
		(layer "In4.Cu")
		(net "M_G_CPU1_SB_CS_N<0>")
	)
	(segment
		(start 158.378398 -245.386352)
		(end 156.489654 -245.386352)
		(width 0.18288)
		(layer "In4.Cu")
		(net "M_G_CPU1_SB_CS_N<0>")
	)
	(segment
		(start 190.445644 -245.38051)
		(end 189.471046 -245.38051)
		(width 0.18288)
		(layer "In4.Cu")
		(net "M_G_CPU1_SB_CS_N<0>")
	)
	(segment
		(start 193.352166 -245.07571)
		(end 193.192146 -244.91569)
		(width 0.18288)
		(layer "In4.Cu")
		(net "M_G_CPU1_SB_CS_N<0>")
	)
	(segment
		(start 171.172886 -245.135146)
		(end 169.824146 -245.135146)
		(width 0.18288)
		(layer "In4.Cu")
		(net "M_G_CPU1_SB_CS_N<0>")
	)
	(segment
		(start 194.96532 -246.228616)
		(end 193.548254 -246.228616)
		(width 0.18288)
		(layer "In4.Cu")
		(net "M_G_CPU1_SB_CS_N<0>")
	)
	(segment
		(start 159.391858 -245.521226)
		(end 159.231838 -245.361206)
		(width 0.18288)
		(layer "In4.Cu")
		(net "M_G_CPU1_SB_CS_N<0>")
	)
	(segment
		(start 141.1986 -245.662704)
		(end 139.440158 -246.390922)
		(width 0.18288)
		(layer "In4.Cu")
		(net "M_G_CPU1_SB_CS_N<0>")
	)
	(segment
		(start 132.569966 -246.672354)
		(end 131.846066 -246.364506)
		(width 0.088646)
		(layer "In4.Cu")
		(net "M_G_CPU1_SB_CS_N<0>")
	)
	(segment
		(start 192.398396 -245.34495)
		(end 191.475614 -245.34495)
		(width 0.18288)
		(layer "In4.Cu")
		(net "M_G_CPU1_SB_CS_N<0>")
	)
	(segment
		(start 147.798028 -245.662704)
		(end 141.1986 -245.662704)
		(width 0.18288)
		(layer "In4.Cu")
		(net "M_G_CPU1_SB_CS_N<0>")
	)
	(segment
		(start 165.460172 -245.38178)
		(end 164.80028 -245.38178)
		(width 0.18288)
		(layer "In4.Cu")
		(net "M_G_CPU1_SB_CS_N<0>")
	)
	(segment
		(start 158.538418 -245.226332)
		(end 158.378398 -245.386352)
		(width 0.18288)
		(layer "In4.Cu")
		(net "M_G_CPU1_SB_CS_N<0>")
	)
	(segment
		(start 185.330846 -245.114826)
		(end 185.107326 -245.338346)
		(width 0.18288)
		(layer "In4.Cu")
		(net "M_G_CPU1_SB_CS_N<0>")
	)
	(segment
		(start 191.299084 -245.52148)
		(end 191.299084 -246.529352)
		(width 0.18288)
		(layer "In4.Cu")
		(net "M_G_CPU1_SB_CS_N<0>")
	)
	(segment
		(start 177.094642 -245.34241)
		(end 176.401222 -245.34241)
		(width 0.18288)
		(layer "In4.Cu")
		(net "M_G_CPU1_SB_CS_N<0>")
	)
	(segment
		(start 169.824146 -245.135146)
		(end 169.717466 -245.241826)
		(width 0.18288)
		(layer "In4.Cu")
		(net "M_G_CPU1_SB_CS_N<0>")
	)
	(segment
		(start 155.798774 -245.100094)
		(end 148.360638 -245.100094)
		(width 0.18288)
		(layer "In4.Cu")
		(net "M_G_CPU1_SB_CS_N<0>")
	)
	(segment
		(start 193.548254 -246.228616)
		(end 193.352166 -246.032528)
		(width 0.18288)
		(layer "In4.Cu")
		(net "M_G_CPU1_SB_CS_N<0>")
	)
	(segment
		(start 191.299084 -246.529352)
		(end 191.139064 -246.689372)
		(width 0.18288)
		(layer "In4.Cu")
		(net "M_G_CPU1_SB_CS_N<0>")
	)
	(segment
		(start 165.955726 -244.886226)
		(end 165.460172 -245.38178)
		(width 0.18288)
		(layer "In4.Cu")
		(net "M_G_CPU1_SB_CS_N<0>")
	)
	(segment
		(start 139.440158 -246.390922)
		(end 139.09167 -246.73941)
		(width 0.18288)
		(layer "In4.Cu")
		(net "M_G_CPU1_SB_CS_N<0>")
	)
	(segment
		(start 189.311026 -245.54053)
		(end 189.311026 -246.569738)
		(width 0.18288)
		(layer "In4.Cu")
		(net "M_G_CPU1_SB_CS_N<0>")
	)
	(segment
		(start 175.6791 -245.564406)
		(end 175.457358 -245.342664)
		(width 0.18288)
		(layer "In4.Cu")
		(net "M_G_CPU1_SB_CS_N<0>")
	)
	(segment
		(start 191.475614 -245.34495)
		(end 191.299084 -245.52148)
		(width 0.18288)
		(layer "In4.Cu")
		(net "M_G_CPU1_SB_CS_N<0>")
	)
	(segment
		(start 160.062926 -245.521226)
		(end 159.391858 -245.521226)
		(width 0.18288)
		(layer "In4.Cu")
		(net "M_G_CPU1_SB_CS_N<0>")
	)
	(segment
		(start 171.38015 -245.34241)
		(end 171.172886 -245.135146)
		(width 0.18288)
		(layer "In4.Cu")
		(net "M_G_CPU1_SB_CS_N<0>")
	)
	(segment
		(start 192.827656 -244.91569)
		(end 192.398396 -245.34495)
		(width 0.18288)
		(layer "In4.Cu")
		(net "M_G_CPU1_SB_CS_N<0>")
	)
	(segment
		(start 156.489654 -245.386352)
		(end 155.798774 -245.100094)
		(width 0.18288)
		(layer "In4.Cu")
		(net "M_G_CPU1_SB_CS_N<0>")
	)
	(segment
		(start 132.973064 -246.688864)
		(end 132.97281 -246.688864)
		(width 0.088646)
		(layer "In4.Cu")
		(net "M_G_CPU1_SB_CS_N<0>")
	)
	(segment
		(start 164.80028 -245.38178)
		(end 164.584126 -245.165626)
		(width 0.18288)
		(layer "In4.Cu")
		(net "M_G_CPU1_SB_CS_N<0>")
	)
	(segment
		(start 159.231838 -245.189502)
		(end 159.071818 -245.029482)
		(width 0.18288)
		(layer "In4.Cu")
		(net "M_G_CPU1_SB_CS_N<0>")
	)
	(segment
		(start 191.139064 -246.689372)
		(end 190.765684 -246.689372)
		(width 0.18288)
		(layer "In4.Cu")
		(net "M_G_CPU1_SB_CS_N<0>")
	)
	(segment
		(start 169.717466 -245.241826)
		(end 168.597326 -245.241826)
		(width 0.18288)
		(layer "In4.Cu")
		(net "M_G_CPU1_SB_CS_N<0>")
	)
	(segment
		(start 179.628546 -245.338346)
		(end 179.455826 -245.165626)
		(width 0.18288)
		(layer "In4.Cu")
		(net "M_G_CPU1_SB_CS_N<0>")
	)
	(segment
		(start 190.765684 -246.689372)
		(end 190.605664 -246.529352)
		(width 0.18288)
		(layer "In4.Cu")
		(net "M_G_CPU1_SB_CS_N<0>")
	)
	(segment
		(start 193.352166 -246.032528)
		(end 193.352166 -245.07571)
		(width 0.18288)
		(layer "In4.Cu")
		(net "M_G_CPU1_SB_CS_N<0>")
	)
	(segment
		(start 158.538418 -245.189502)
		(end 158.538418 -245.226332)
		(width 0.18288)
		(layer "In4.Cu")
		(net "M_G_CPU1_SB_CS_N<0>")
	)
	(segment
		(start 179.455826 -245.165626)
		(end 177.271426 -245.165626)
		(width 0.18288)
		(layer "In4.Cu")
		(net "M_G_CPU1_SB_CS_N<0>")
	)
	(segment
		(start 164.584126 -245.165626)
		(end 160.418526 -245.165626)
		(width 0.18288)
		(layer "In4.Cu")
		(net "M_G_CPU1_SB_CS_N<0>")
	)
	(segment
		(start 189.151006 -246.729758)
		(end 188.777626 -246.729758)
		(width 0.18288)
		(layer "In4.Cu")
		(net "M_G_CPU1_SB_CS_N<0>")
	)
	(segment
		(start 137.826496 -246.73941)
		(end 137.484866 -246.73941)
		(width 0.088646)
		(layer "In4.Cu")
		(net "M_G_CPU1_SB_CS_N<0>")
	)
	(segment
		(start 189.311026 -246.569738)
		(end 189.151006 -246.729758)
		(width 0.18288)
		(layer "In4.Cu")
		(net "M_G_CPU1_SB_CS_N<0>")
	)
	(segment
		(start 173.003464 -245.342664)
		(end 173.00321 -245.34241)
		(width 0.18288)
		(layer "In4.Cu")
		(net "M_G_CPU1_SB_CS_N<0>")
	)
	(segment
		(start 187.206382 -245.114826)
		(end 185.330846 -245.114826)
		(width 0.18288)
		(layer "In4.Cu")
		(net "M_G_CPU1_SB_CS_N<0>")
	)
	(segment
		(start 176.401222 -245.34241)
		(end 176.179226 -245.564406)
		(width 0.18288)
		(layer "In4.Cu")
		(net "M_G_CPU1_SB_CS_N<0>")
	)
	(arc
		(start 135.418068 -246.688864)
		(mid 135.135366 -246.613088)
		(end 134.852664 -246.688864)
		(width 0.088646)
		(layer "In4.Cu")
		(net "M_G_CPU1_SB_CS_N<0>")
	)
	(arc
		(start 135.792464 -246.688864)
		(mid 135.605266 -246.739007)
		(end 135.418068 -246.688864)
		(width 0.088646)
		(layer "In4.Cu")
		(net "M_G_CPU1_SB_CS_N<0>")
	)
	(arc
		(start 137.484866 -246.73941)
		(mid 137.387943 -246.726452)
		(end 137.297668 -246.688864)
		(width 0.088646)
		(layer "In4.Cu")
		(net "M_G_CPU1_SB_CS_N<0>")
	)
	(arc
		(start 136.732264 -246.688864)
		(mid 136.545066 -246.739007)
		(end 136.357868 -246.688864)
		(width 0.088646)
		(layer "In4.Cu")
		(net "M_G_CPU1_SB_CS_N<0>")
	)
	(arc
		(start 133.538468 -246.688864)
		(mid 133.264269 -246.613029)
		(end 132.987796 -246.680228)
		(width 0.088646)
		(layer "In4.Cu")
		(net "M_G_CPU1_SB_CS_N<0>")
	)
	(arc
		(start 137.297668 -246.688864)
		(mid 137.014966 -246.613088)
		(end 136.732264 -246.688864)
		(width 0.088646)
		(layer "In4.Cu")
		(net "M_G_CPU1_SB_CS_N<0>")
	)
	(arc
		(start 136.357868 -246.688864)
		(mid 136.075166 -246.613088)
		(end 135.792464 -246.688864)
		(width 0.088646)
		(layer "In4.Cu")
		(net "M_G_CPU1_SB_CS_N<0>")
	)
	(arc
		(start 134.478268 -246.688864)
		(mid 134.195566 -246.613088)
		(end 133.912864 -246.688864)
		(width 0.088646)
		(layer "In4.Cu")
		(net "M_G_CPU1_SB_CS_N<0>")
	)
	(arc
		(start 133.912864 -246.688864)
		(mid 133.725666 -246.739007)
		(end 133.538468 -246.688864)
		(width 0.088646)
		(layer "In4.Cu")
		(net "M_G_CPU1_SB_CS_N<0>")
	)
	(arc
		(start 132.97281 -246.688864)
		(mid 132.785612 -246.739041)
		(end 132.598414 -246.688864)
		(width 0.088646)
		(layer "In4.Cu")
		(net "M_G_CPU1_SB_CS_N<0>")
	)
	(arc
		(start 134.852664 -246.688864)
		(mid 134.665466 -246.739007)
		(end 134.478268 -246.688864)
		(width 0.088646)
		(layer "In4.Cu")
		(net "M_G_CPU1_SB_CS_N<0>")
	)
	(segment
		(start 198.427848 -239.191038)
		(end 198.427848 -238.893858)
		(width 0.20066)
		(layer "F.Cu")
		(net "M_G_CPU1_SB_CB<7>")
	)
	(segment
		(start 198.628508 -238.693198)
		(end 199.024494 -238.693198)
		(width 0.20066)
		(layer "F.Cu")
		(net "M_G_CPU1_SB_CB<7>")
	)
	(segment
		(start 131.846066 -243.644928)
		(end 131.845812 -243.644674)
		(width 0.20066)
		(layer "F.Cu")
		(net "M_G_CPU1_SB_CB<7>")
	)
	(segment
		(start 191.983614 -238.966756)
		(end 193.088514 -238.966756)
		(width 0.20066)
		(layer "F.Cu")
		(net "M_G_CPU1_SB_CB<7>")
	)
	(segment
		(start 198.227188 -239.391698)
		(end 198.427848 -239.191038)
		(width 0.20066)
		(layer "F.Cu")
		(net "M_G_CPU1_SB_CB<7>")
	)
	(segment
		(start 195.343018 -239.391698)
		(end 195.522596 -239.391698)
		(width 0.101854)
		(layer "F.Cu")
		(net "M_G_CPU1_SB_CB<7>")
	)
	(segment
		(start 131.845812 -243.644674)
		(end 131.845812 -243.108988)
		(width 0.20066)
		(layer "F.Cu")
		(net "M_G_CPU1_SB_CB<7>")
	)
	(segment
		(start 197.530466 -239.391698)
		(end 197.834504 -239.391698)
		(width 0.101854)
		(layer "F.Cu")
		(net "M_G_CPU1_SB_CB<7>")
	)
	(segment
		(start 193.088514 -238.966756)
		(end 194.79387 -238.966756)
		(width 0.20066)
		(layer "F.Cu")
		(net "M_G_CPU1_SB_CB<7>")
	)
	(segment
		(start 195.218812 -239.391698)
		(end 195.343018 -239.391698)
		(width 0.20066)
		(layer "F.Cu")
		(net "M_G_CPU1_SB_CB<7>")
	)
	(segment
		(start 198.427848 -238.893858)
		(end 198.628508 -238.693198)
		(width 0.20066)
		(layer "F.Cu")
		(net "M_G_CPU1_SB_CB<7>")
	)
	(segment
		(start 197.834504 -239.391698)
		(end 198.227188 -239.391698)
		(width 0.20066)
		(layer "F.Cu")
		(net "M_G_CPU1_SB_CB<7>")
	)
	(segment
		(start 195.522596 -239.391698)
		(end 197.530466 -239.391698)
		(width 0.1016)
		(layer "F.Cu")
		(net "M_G_CPU1_SB_CB<7>")
	)
	(segment
		(start 194.79387 -238.966756)
		(end 195.218812 -239.391698)
		(width 0.20066)
		(layer "F.Cu")
		(net "M_G_CPU1_SB_CB<7>")
	)
	(segment
		(start 199.298052 -238.966756)
		(end 200.632314 -238.966756)
		(width 0.20066)
		(layer "F.Cu")
		(net "M_G_CPU1_SB_CB<7>")
	)
	(segment
		(start 199.024494 -238.693198)
		(end 199.298052 -238.966756)
		(width 0.20066)
		(layer "F.Cu")
		(net "M_G_CPU1_SB_CB<7>")
	)
	(segment
		(start 171.40174 -240.3094)
		(end 170.466766 -239.374426)
		(width 0.18288)
		(layer "In4.Cu")
		(net "M_G_CPU1_SB_CB<7>")
	)
	(segment
		(start 178.001676 -239.393476)
		(end 176.617122 -239.393476)
		(width 0.18288)
		(layer "In4.Cu")
		(net "M_G_CPU1_SB_CB<7>")
	)
	(segment
		(start 134.852664 -243.433346)
		(end 134.848854 -243.435632)
		(width 0.088646)
		(layer "In4.Cu")
		(net "M_G_CPU1_SB_CB<7>")
	)
	(segment
		(start 166.7637 -239.668812)
		(end 166.31285 -239.217962)
		(width 0.18288)
		(layer "In4.Cu")
		(net "M_G_CPU1_SB_CB<7>")
	)
	(segment
		(start 164.733986 -239.613186)
		(end 164.495226 -239.374426)
		(width 0.18288)
		(layer "In4.Cu")
		(net "M_G_CPU1_SB_CB<7>")
	)
	(segment
		(start 138.57478 -243.483892)
		(end 137.484866 -243.483892)
		(width 0.088646)
		(layer "In4.Cu")
		(net "M_G_CPU1_SB_CB<7>")
	)
	(segment
		(start 190.21806 -239.39246)
		(end 187.39866 -239.39246)
		(width 0.18288)
		(layer "In4.Cu")
		(net "M_G_CPU1_SB_CB<7>")
	)
	(segment
		(start 168.927526 -239.374426)
		(end 168.63314 -239.668812)
		(width 0.18288)
		(layer "In4.Cu")
		(net "M_G_CPU1_SB_CB<7>")
	)
	(segment
		(start 161.740088 -239.249712)
		(end 161.580068 -239.089692)
		(width 0.18288)
		(layer "In4.Cu")
		(net "M_G_CPU1_SB_CB<7>")
	)
	(segment
		(start 160.583626 -239.392714)
		(end 160.336738 -239.392714)
		(width 0.18288)
		(layer "In4.Cu")
		(net "M_G_CPU1_SB_CB<7>")
	)
	(segment
		(start 162.433508 -238.779812)
		(end 162.273488 -238.939832)
		(width 0.18288)
		(layer "In4.Cu")
		(net "M_G_CPU1_SB_CB<7>")
	)
	(segment
		(start 191.983614 -238.966756)
		(end 191.185038 -239.765332)
		(width 0.18288)
		(layer "In4.Cu")
		(net "M_G_CPU1_SB_CB<7>")
	)
	(segment
		(start 151.614378 -240.389664)
		(end 147.186904 -240.389664)
		(width 0.18288)
		(layer "In4.Cu")
		(net "M_G_CPU1_SB_CB<7>")
	)
	(segment
		(start 161.580068 -239.089692)
		(end 161.580068 -238.939832)
		(width 0.18288)
		(layer "In4.Cu")
		(net "M_G_CPU1_SB_CB<7>")
	)
	(segment
		(start 191.185038 -239.765332)
		(end 190.590932 -239.765332)
		(width 0.18288)
		(layer "In4.Cu")
		(net "M_G_CPU1_SB_CB<7>")
	)
	(segment
		(start 162.806888 -238.779812)
		(end 162.433508 -238.779812)
		(width 0.18288)
		(layer "In4.Cu")
		(net "M_G_CPU1_SB_CB<7>")
	)
	(segment
		(start 186.669426 -238.663226)
		(end 183.735726 -238.663226)
		(width 0.18288)
		(layer "In4.Cu")
		(net "M_G_CPU1_SB_CB<7>")
	)
	(segment
		(start 165.608254 -239.526826)
		(end 165.2524 -239.526826)
		(width 0.18288)
		(layer "In4.Cu")
		(net "M_G_CPU1_SB_CB<7>")
	)
	(segment
		(start 170.466766 -239.374426)
		(end 168.927526 -239.374426)
		(width 0.18288)
		(layer "In4.Cu")
		(net "M_G_CPU1_SB_CB<7>")
	)
	(segment
		(start 135.792464 -243.433346)
		(end 135.788146 -243.435886)
		(width 0.088646)
		(layer "In4.Cu")
		(net "M_G_CPU1_SB_CB<7>")
	)
	(segment
		(start 160.886648 -239.089692)
		(end 160.583626 -239.392714)
		(width 0.18288)
		(layer "In4.Cu")
		(net "M_G_CPU1_SB_CB<7>")
	)
	(segment
		(start 176.617122 -239.393476)
		(end 176.509172 -239.501426)
		(width 0.18288)
		(layer "In4.Cu")
		(net "M_G_CPU1_SB_CB<7>")
	)
	(segment
		(start 178.630326 -238.764826)
		(end 178.001676 -239.393476)
		(width 0.18288)
		(layer "In4.Cu")
		(net "M_G_CPU1_SB_CB<7>")
	)
	(segment
		(start 173.888654 -240.242598)
		(end 172.8724 -240.242598)
		(width 0.18288)
		(layer "In4.Cu")
		(net "M_G_CPU1_SB_CB<7>")
	)
	(segment
		(start 187.39866 -239.39246)
		(end 186.669426 -238.663226)
		(width 0.18288)
		(layer "In4.Cu")
		(net "M_G_CPU1_SB_CB<7>")
	)
	(segment
		(start 174.629826 -239.501426)
		(end 173.888654 -240.242598)
		(width 0.18288)
		(layer "In4.Cu")
		(net "M_G_CPU1_SB_CB<7>")
	)
	(segment
		(start 172.1231 -240.242344)
		(end 172.056044 -240.3094)
		(width 0.18288)
		(layer "In4.Cu")
		(net "M_G_CPU1_SB_CB<7>")
	)
	(segment
		(start 176.509172 -239.501426)
		(end 174.629826 -239.501426)
		(width 0.18288)
		(layer "In4.Cu")
		(net "M_G_CPU1_SB_CB<7>")
	)
	(segment
		(start 165.2524 -239.526826)
		(end 165.16604 -239.613186)
		(width 0.18288)
		(layer "In4.Cu")
		(net "M_G_CPU1_SB_CB<7>")
	)
	(segment
		(start 162.113468 -239.249712)
		(end 161.740088 -239.249712)
		(width 0.18288)
		(layer "In4.Cu")
		(net "M_G_CPU1_SB_CB<7>")
	)
	(segment
		(start 166.31285 -239.217962)
		(end 165.917118 -239.217962)
		(width 0.18288)
		(layer "In4.Cu")
		(net "M_G_CPU1_SB_CB<7>")
	)
	(segment
		(start 140.315696 -242.907566)
		(end 139.151106 -242.907566)
		(width 0.088646)
		(layer "In4.Cu")
		(net "M_G_CPU1_SB_CB<7>")
	)
	(segment
		(start 172.056044 -240.3094)
		(end 171.40174 -240.3094)
		(width 0.18288)
		(layer "In4.Cu")
		(net "M_G_CPU1_SB_CB<7>")
	)
	(segment
		(start 160.336738 -239.392714)
		(end 160.177226 -239.552226)
		(width 0.18288)
		(layer "In4.Cu")
		(net "M_G_CPU1_SB_CB<7>")
	)
	(segment
		(start 165.16604 -239.613186)
		(end 164.733986 -239.613186)
		(width 0.18288)
		(layer "In4.Cu")
		(net "M_G_CPU1_SB_CB<7>")
	)
	(segment
		(start 162.273488 -238.939832)
		(end 162.273488 -239.089692)
		(width 0.18288)
		(layer "In4.Cu")
		(net "M_G_CPU1_SB_CB<7>")
	)
	(segment
		(start 180.027326 -238.485426)
		(end 179.747926 -238.764826)
		(width 0.18288)
		(layer "In4.Cu")
		(net "M_G_CPU1_SB_CB<7>")
	)
	(segment
		(start 161.580068 -238.939832)
		(end 161.420048 -238.779812)
		(width 0.18288)
		(layer "In4.Cu")
		(net "M_G_CPU1_SB_CB<7>")
	)
	(segment
		(start 179.747926 -238.764826)
		(end 178.630326 -238.764826)
		(width 0.18288)
		(layer "In4.Cu")
		(net "M_G_CPU1_SB_CB<7>")
	)
	(segment
		(start 159.593026 -239.425226)
		(end 157.785816 -239.425226)
		(width 0.18288)
		(layer "In4.Cu")
		(net "M_G_CPU1_SB_CB<7>")
	)
	(segment
		(start 161.420048 -238.779812)
		(end 161.046668 -238.779812)
		(width 0.18288)
		(layer "In4.Cu")
		(net "M_G_CPU1_SB_CB<7>")
	)
	(segment
		(start 163.351972 -239.249712)
		(end 163.126928 -239.249712)
		(width 0.18288)
		(layer "In4.Cu")
		(net "M_G_CPU1_SB_CB<7>")
	)
	(segment
		(start 163.126928 -239.249712)
		(end 162.966908 -239.089692)
		(width 0.18288)
		(layer "In4.Cu")
		(net "M_G_CPU1_SB_CB<7>")
	)
	(segment
		(start 162.966908 -239.089692)
		(end 162.966908 -238.939832)
		(width 0.18288)
		(layer "In4.Cu")
		(net "M_G_CPU1_SB_CB<7>")
	)
	(segment
		(start 132.978906 -243.430044)
		(end 132.967222 -243.436648)
		(width 0.088646)
		(layer "In4.Cu")
		(net "M_G_CPU1_SB_CB<7>")
	)
	(segment
		(start 163.476686 -239.374426)
		(end 163.351972 -239.249712)
		(width 0.18288)
		(layer "In4.Cu")
		(net "M_G_CPU1_SB_CB<7>")
	)
	(segment
		(start 132.598414 -243.433346)
		(end 132.201412 -243.204238)
		(width 0.088646)
		(layer "In4.Cu")
		(net "M_G_CPU1_SB_CB<7>")
	)
	(segment
		(start 160.886648 -238.939832)
		(end 160.886648 -239.089692)
		(width 0.18288)
		(layer "In4.Cu")
		(net "M_G_CPU1_SB_CB<7>")
	)
	(segment
		(start 131.846066 -243.108988)
		(end 131.845812 -243.108988)
		(width 0.088646)
		(layer "In4.Cu")
		(net "M_G_CPU1_SB_CB<7>")
	)
	(segment
		(start 183.557926 -238.485426)
		(end 180.027326 -238.485426)
		(width 0.18288)
		(layer "In4.Cu")
		(net "M_G_CPU1_SB_CB<7>")
	)
	(segment
		(start 172.872146 -240.242344)
		(end 172.1231 -240.242344)
		(width 0.18288)
		(layer "In4.Cu")
		(net "M_G_CPU1_SB_CB<7>")
	)
	(segment
		(start 172.8724 -240.242598)
		(end 172.872146 -240.242344)
		(width 0.18288)
		(layer "In4.Cu")
		(net "M_G_CPU1_SB_CB<7>")
	)
	(segment
		(start 183.735726 -238.663226)
		(end 183.557926 -238.485426)
		(width 0.18288)
		(layer "In4.Cu")
		(net "M_G_CPU1_SB_CB<7>")
	)
	(segment
		(start 160.177226 -239.552226)
		(end 159.720026 -239.552226)
		(width 0.18288)
		(layer "In4.Cu")
		(net "M_G_CPU1_SB_CB<7>")
	)
	(segment
		(start 159.720026 -239.552226)
		(end 159.593026 -239.425226)
		(width 0.18288)
		(layer "In4.Cu")
		(net "M_G_CPU1_SB_CB<7>")
	)
	(segment
		(start 139.151106 -242.907566)
		(end 138.57478 -243.483892)
		(width 0.088646)
		(layer "In4.Cu")
		(net "M_G_CPU1_SB_CB<7>")
	)
	(segment
		(start 157.785562 -239.424972)
		(end 152.57907 -239.424972)
		(width 0.18288)
		(layer "In4.Cu")
		(net "M_G_CPU1_SB_CB<7>")
	)
	(segment
		(start 162.273488 -239.089692)
		(end 162.113468 -239.249712)
		(width 0.18288)
		(layer "In4.Cu")
		(net "M_G_CPU1_SB_CB<7>")
	)
	(segment
		(start 147.186904 -240.389664)
		(end 144.669002 -242.907566)
		(width 0.18288)
		(layer "In4.Cu")
		(net "M_G_CPU1_SB_CB<7>")
	)
	(segment
		(start 134.858506 -243.430044)
		(end 134.852664 -243.433346)
		(width 0.088646)
		(layer "In4.Cu")
		(net "M_G_CPU1_SB_CB<7>")
	)
	(segment
		(start 165.917118 -239.217962)
		(end 165.608254 -239.526826)
		(width 0.18288)
		(layer "In4.Cu")
		(net "M_G_CPU1_SB_CB<7>")
	)
	(segment
		(start 164.495226 -239.374426)
		(end 163.476686 -239.374426)
		(width 0.18288)
		(layer "In4.Cu")
		(net "M_G_CPU1_SB_CB<7>")
	)
	(segment
		(start 133.912864 -243.433346)
		(end 133.908546 -243.435886)
		(width 0.088646)
		(layer "In4.Cu")
		(net "M_G_CPU1_SB_CB<7>")
	)
	(segment
		(start 157.785816 -239.425226)
		(end 157.785562 -239.424972)
		(width 0.18288)
		(layer "In4.Cu")
		(net "M_G_CPU1_SB_CB<7>")
	)
	(segment
		(start 161.046668 -238.779812)
		(end 160.886648 -238.939832)
		(width 0.18288)
		(layer "In4.Cu")
		(net "M_G_CPU1_SB_CB<7>")
	)
	(segment
		(start 162.966908 -238.939832)
		(end 162.806888 -238.779812)
		(width 0.18288)
		(layer "In4.Cu")
		(net "M_G_CPU1_SB_CB<7>")
	)
	(segment
		(start 168.63314 -239.668812)
		(end 166.7637 -239.668812)
		(width 0.18288)
		(layer "In4.Cu")
		(net "M_G_CPU1_SB_CB<7>")
	)
	(segment
		(start 152.57907 -239.424972)
		(end 151.614378 -240.389664)
		(width 0.18288)
		(layer "In4.Cu")
		(net "M_G_CPU1_SB_CB<7>")
	)
	(segment
		(start 190.590932 -239.765332)
		(end 190.21806 -239.39246)
		(width 0.18288)
		(layer "In4.Cu")
		(net "M_G_CPU1_SB_CB<7>")
	)
	(segment
		(start 144.669002 -242.907566)
		(end 140.315696 -242.907566)
		(width 0.18288)
		(layer "In4.Cu")
		(net "M_G_CPU1_SB_CB<7>")
	)
	(arc
		(start 132.201412 -243.204238)
		(mid 132.030006 -243.133225)
		(end 131.846066 -243.108988)
		(width 0.088646)
		(layer "In4.Cu")
		(net "M_G_CPU1_SB_CB<7>")
	)
	(arc
		(start 133.908546 -243.435886)
		(mid 133.723051 -243.483555)
		(end 133.538214 -243.433346)
		(width 0.088646)
		(layer "In4.Cu")
		(net "M_G_CPU1_SB_CB<7>")
	)
	(arc
		(start 134.848854 -243.435632)
		(mid 134.663135 -243.483584)
		(end 134.478014 -243.433346)
		(width 0.088646)
		(layer "In4.Cu")
		(net "M_G_CPU1_SB_CB<7>")
	)
	(arc
		(start 135.417814 -243.433346)
		(mid 135.138611 -243.357706)
		(end 134.858506 -243.430044)
		(width 0.088646)
		(layer "In4.Cu")
		(net "M_G_CPU1_SB_CB<7>")
	)
	(arc
		(start 137.297668 -243.433346)
		(mid 137.014966 -243.35757)
		(end 136.732264 -243.433346)
		(width 0.088646)
		(layer "In4.Cu")
		(net "M_G_CPU1_SB_CB<7>")
	)
	(arc
		(start 133.538214 -243.433346)
		(mid 133.259011 -243.357706)
		(end 132.978906 -243.430044)
		(width 0.088646)
		(layer "In4.Cu")
		(net "M_G_CPU1_SB_CB<7>")
	)
	(arc
		(start 136.732264 -243.433346)
		(mid 136.545066 -243.483489)
		(end 136.357868 -243.433346)
		(width 0.088646)
		(layer "In4.Cu")
		(net "M_G_CPU1_SB_CB<7>")
	)
	(arc
		(start 134.478014 -243.433346)
		(mid 134.195456 -243.357697)
		(end 133.912864 -243.433346)
		(width 0.088646)
		(layer "In4.Cu")
		(net "M_G_CPU1_SB_CB<7>")
	)
	(arc
		(start 132.967222 -243.436648)
		(mid 132.782367 -243.483598)
		(end 132.598414 -243.433346)
		(width 0.088646)
		(layer "In4.Cu")
		(net "M_G_CPU1_SB_CB<7>")
	)
	(arc
		(start 136.357868 -243.433346)
		(mid 136.075166 -243.35757)
		(end 135.792464 -243.433346)
		(width 0.088646)
		(layer "In4.Cu")
		(net "M_G_CPU1_SB_CB<7>")
	)
	(arc
		(start 137.484866 -243.483892)
		(mid 137.387938 -243.470941)
		(end 137.297668 -243.433346)
		(width 0.088646)
		(layer "In4.Cu")
		(net "M_G_CPU1_SB_CB<7>")
	)
	(arc
		(start 135.788146 -243.435886)
		(mid 135.602651 -243.483555)
		(end 135.417814 -243.433346)
		(width 0.088646)
		(layer "In4.Cu")
		(net "M_G_CPU1_SB_CB<7>")
	)
	(segment
		(start 197.834504 -241.09172)
		(end 198.227188 -241.09172)
		(width 0.20066)
		(layer "F.Cu")
		(net "M_G_CPU1_SB_CB<6>")
	)
	(segment
		(start 191.983614 -240.666778)
		(end 193.088514 -240.666778)
		(width 0.20066)
		(layer "F.Cu")
		(net "M_G_CPU1_SB_CB<6>")
	)
	(segment
		(start 193.088514 -240.666778)
		(end 194.685158 -240.666778)
		(width 0.20066)
		(layer "F.Cu")
		(net "M_G_CPU1_SB_CB<6>")
	)
	(segment
		(start 194.685158 -240.666778)
		(end 195.1101 -241.09172)
		(width 0.20066)
		(layer "F.Cu")
		(net "M_G_CPU1_SB_CB<6>")
	)
	(segment
		(start 198.628508 -240.371884)
		(end 199.003158 -240.371884)
		(width 0.20066)
		(layer "F.Cu")
		(net "M_G_CPU1_SB_CB<6>")
	)
	(segment
		(start 131.376166 -244.45849)
		(end 131.376166 -243.922804)
		(width 0.20066)
		(layer "F.Cu")
		(net "M_G_CPU1_SB_CB<6>")
	)
	(segment
		(start 198.427848 -240.572544)
		(end 198.628508 -240.371884)
		(width 0.20066)
		(layer "F.Cu")
		(net "M_G_CPU1_SB_CB<6>")
	)
	(segment
		(start 195.522596 -241.09172)
		(end 197.48881 -241.09172)
		(width 0.1016)
		(layer "F.Cu")
		(net "M_G_CPU1_SB_CB<6>")
	)
	(segment
		(start 198.227188 -241.09172)
		(end 198.427848 -240.89106)
		(width 0.20066)
		(layer "F.Cu")
		(net "M_G_CPU1_SB_CB<6>")
	)
	(segment
		(start 199.298052 -240.666778)
		(end 200.632314 -240.666778)
		(width 0.20066)
		(layer "F.Cu")
		(net "M_G_CPU1_SB_CB<6>")
	)
	(segment
		(start 131.375912 -244.458744)
		(end 131.376166 -244.45849)
		(width 0.20066)
		(layer "F.Cu")
		(net "M_G_CPU1_SB_CB<6>")
	)
	(segment
		(start 199.003158 -240.371884)
		(end 199.298052 -240.666778)
		(width 0.20066)
		(layer "F.Cu")
		(net "M_G_CPU1_SB_CB<6>")
	)
	(segment
		(start 195.1101 -241.09172)
		(end 195.343018 -241.09172)
		(width 0.20066)
		(layer "F.Cu")
		(net "M_G_CPU1_SB_CB<6>")
	)
	(segment
		(start 195.343018 -241.09172)
		(end 195.522596 -241.09172)
		(width 0.101854)
		(layer "F.Cu")
		(net "M_G_CPU1_SB_CB<6>")
	)
	(segment
		(start 198.427848 -240.89106)
		(end 198.427848 -240.572544)
		(width 0.20066)
		(layer "F.Cu")
		(net "M_G_CPU1_SB_CB<6>")
	)
	(segment
		(start 197.48881 -241.09172)
		(end 197.834504 -241.09172)
		(width 0.101854)
		(layer "F.Cu")
		(net "M_G_CPU1_SB_CB<6>")
	)
	(segment
		(start 191.294766 -241.355626)
		(end 190.098426 -241.355626)
		(width 0.18288)
		(layer "In4.Cu")
		(net "M_G_CPU1_SB_CB<6>")
	)
	(segment
		(start 154.80792 -241.944906)
		(end 154.62504 -242.127786)
		(width 0.18288)
		(layer "In4.Cu")
		(net "M_G_CPU1_SB_CB<6>")
	)
	(segment
		(start 158.9151 -241.385344)
		(end 156.37764 -241.385344)
		(width 0.18288)
		(layer "In4.Cu")
		(net "M_G_CPU1_SB_CB<6>")
	)
	(segment
		(start 155.68422 -242.127786)
		(end 155.50134 -241.944906)
		(width 0.18288)
		(layer "In4.Cu")
		(net "M_G_CPU1_SB_CB<6>")
	)
	(segment
		(start 156.19476 -241.568224)
		(end 156.19476 -241.944906)
		(width 0.18288)
		(layer "In4.Cu")
		(net "M_G_CPU1_SB_CB<6>")
	)
	(segment
		(start 131.005834 -243.980208)
		(end 131.063238 -243.922804)
		(width 0.088646)
		(layer "In4.Cu")
		(net "M_G_CPU1_SB_CB<6>")
	)
	(segment
		(start 168.193212 -240.89614)
		(end 167.911526 -241.177826)
		(width 0.18288)
		(layer "In4.Cu")
		(net "M_G_CPU1_SB_CB<6>")
	)
	(segment
		(start 140.285216 -243.690648)
		(end 140.27658 -243.699284)
		(width 0.088646)
		(layer "In4.Cu")
		(net "M_G_CPU1_SB_CB<6>")
	)
	(segment
		(start 191.983614 -240.666778)
		(end 191.294766 -241.355626)
		(width 0.18288)
		(layer "In4.Cu")
		(net "M_G_CPU1_SB_CB<6>")
	)
	(segment
		(start 164.393626 -241.177826)
		(end 164.058092 -240.842292)
		(width 0.18288)
		(layer "In4.Cu")
		(net "M_G_CPU1_SB_CB<6>")
	)
	(segment
		(start 140.27658 -243.699284)
		(end 139.119356 -243.699284)
		(width 0.088646)
		(layer "In4.Cu")
		(net "M_G_CPU1_SB_CB<6>")
	)
	(segment
		(start 154.1145 -241.568224)
		(end 153.93162 -241.385344)
		(width 0.18288)
		(layer "In4.Cu")
		(net "M_G_CPU1_SB_CB<6>")
	)
	(segment
		(start 132.133086 -244.249956)
		(end 132.128514 -244.247416)
		(width 0.088646)
		(layer "In4.Cu")
		(net "M_G_CPU1_SB_CB<6>")
	)
	(segment
		(start 131.063238 -243.922804)
		(end 131.376166 -243.922804)
		(width 0.088646)
		(layer "In4.Cu")
		(net "M_G_CPU1_SB_CB<6>")
	)
	(segment
		(start 155.50134 -241.568224)
		(end 155.31846 -241.385344)
		(width 0.18288)
		(layer "In4.Cu")
		(net "M_G_CPU1_SB_CB<6>")
	)
	(segment
		(start 156.19476 -241.944906)
		(end 156.01188 -242.127786)
		(width 0.18288)
		(layer "In4.Cu")
		(net "M_G_CPU1_SB_CB<6>")
	)
	(segment
		(start 154.1145 -241.944906)
		(end 154.1145 -241.568224)
		(width 0.18288)
		(layer "In4.Cu")
		(net "M_G_CPU1_SB_CB<6>")
	)
	(segment
		(start 173.893226 -241.94262)
		(end 171.14012 -241.94262)
		(width 0.18288)
		(layer "In4.Cu")
		(net "M_G_CPU1_SB_CB<6>")
	)
	(segment
		(start 185.767726 -240.466626)
		(end 184.091326 -240.466626)
		(width 0.18288)
		(layer "In4.Cu")
		(net "M_G_CPU1_SB_CB<6>")
	)
	(segment
		(start 159.224218 -241.076226)
		(end 158.9151 -241.385344)
		(width 0.18288)
		(layer "In4.Cu")
		(net "M_G_CPU1_SB_CB<6>")
	)
	(segment
		(start 145.626582 -243.690648)
		(end 140.315696 -243.690648)
		(width 0.18288)
		(layer "In4.Cu")
		(net "M_G_CPU1_SB_CB<6>")
	)
	(segment
		(start 174.743364 -241.092482)
		(end 173.893226 -241.94262)
		(width 0.18288)
		(layer "In4.Cu")
		(net "M_G_CPU1_SB_CB<6>")
	)
	(segment
		(start 179.620926 -240.212626)
		(end 178.74107 -241.092482)
		(width 0.18288)
		(layer "In4.Cu")
		(net "M_G_CPU1_SB_CB<6>")
	)
	(segment
		(start 139.119356 -243.699284)
		(end 138.64717 -244.17147)
		(width 0.088646)
		(layer "In4.Cu")
		(net "M_G_CPU1_SB_CB<6>")
	)
	(segment
		(start 183.837326 -240.212626)
		(end 179.620926 -240.212626)
		(width 0.18288)
		(layer "In4.Cu")
		(net "M_G_CPU1_SB_CB<6>")
	)
	(segment
		(start 147.931886 -241.385344)
		(end 145.626582 -243.690648)
		(width 0.18288)
		(layer "In4.Cu")
		(net "M_G_CPU1_SB_CB<6>")
	)
	(segment
		(start 155.31846 -241.385344)
		(end 154.9908 -241.385344)
		(width 0.18288)
		(layer "In4.Cu")
		(net "M_G_CPU1_SB_CB<6>")
	)
	(segment
		(start 154.29738 -242.127786)
		(end 154.1145 -241.944906)
		(width 0.18288)
		(layer "In4.Cu")
		(net "M_G_CPU1_SB_CB<6>")
	)
	(segment
		(start 154.9908 -241.385344)
		(end 154.80792 -241.568224)
		(width 0.18288)
		(layer "In4.Cu")
		(net "M_G_CPU1_SB_CB<6>")
	)
	(segment
		(start 186.392566 -241.091466)
		(end 185.767726 -240.466626)
		(width 0.18288)
		(layer "In4.Cu")
		(net "M_G_CPU1_SB_CB<6>")
	)
	(segment
		(start 188.048138 -241.09299)
		(end 188.046614 -241.091466)
		(width 0.18288)
		(layer "In4.Cu")
		(net "M_G_CPU1_SB_CB<6>")
	)
	(segment
		(start 131.193286 -244.249956)
		(end 131.188714 -244.247416)
		(width 0.088646)
		(layer "In4.Cu")
		(net "M_G_CPU1_SB_CB<6>")
	)
	(segment
		(start 135.886444 -244.2464)
		(end 135.882126 -244.24386)
		(width 0.088646)
		(layer "In4.Cu")
		(net "M_G_CPU1_SB_CB<6>")
	)
	(segment
		(start 164.058092 -240.842292)
		(end 161.606992 -240.842292)
		(width 0.18288)
		(layer "In4.Cu")
		(net "M_G_CPU1_SB_CB<6>")
	)
	(segment
		(start 178.74107 -241.092482)
		(end 174.743364 -241.092482)
		(width 0.18288)
		(layer "In4.Cu")
		(net "M_G_CPU1_SB_CB<6>")
	)
	(segment
		(start 131.188714 -244.247416)
		(end 131.185158 -244.24513)
		(width 0.088646)
		(layer "In4.Cu")
		(net "M_G_CPU1_SB_CB<6>")
	)
	(segment
		(start 134.947914 -244.247416)
		(end 134.943342 -244.244622)
		(width 0.088646)
		(layer "In4.Cu")
		(net "M_G_CPU1_SB_CB<6>")
	)
	(segment
		(start 156.01188 -242.127786)
		(end 155.68422 -242.127786)
		(width 0.18288)
		(layer "In4.Cu")
		(net "M_G_CPU1_SB_CB<6>")
	)
	(segment
		(start 134.008114 -244.247416)
		(end 134.002526 -244.24386)
		(width 0.088646)
		(layer "In4.Cu")
		(net "M_G_CPU1_SB_CB<6>")
	)
	(segment
		(start 133.072886 -244.249956)
		(end 133.068314 -244.247416)
		(width 0.088646)
		(layer "In4.Cu")
		(net "M_G_CPU1_SB_CB<6>")
	)
	(segment
		(start 138.64717 -244.17147)
		(end 138.424666 -244.17147)
		(width 0.088646)
		(layer "In4.Cu")
		(net "M_G_CPU1_SB_CB<6>")
	)
	(segment
		(start 167.911526 -241.177826)
		(end 164.393626 -241.177826)
		(width 0.18288)
		(layer "In4.Cu")
		(net "M_G_CPU1_SB_CB<6>")
	)
	(segment
		(start 161.24301 -241.206274)
		(end 159.748474 -241.206274)
		(width 0.18288)
		(layer "In4.Cu")
		(net "M_G_CPU1_SB_CB<6>")
	)
	(segment
		(start 171.14012 -241.94262)
		(end 170.09364 -240.89614)
		(width 0.18288)
		(layer "In4.Cu")
		(net "M_G_CPU1_SB_CB<6>")
	)
	(segment
		(start 161.606992 -240.842292)
		(end 161.24301 -241.206274)
		(width 0.18288)
		(layer "In4.Cu")
		(net "M_G_CPU1_SB_CB<6>")
	)
	(segment
		(start 133.068314 -244.247416)
		(end 133.060948 -244.243098)
		(width 0.088646)
		(layer "In4.Cu")
		(net "M_G_CPU1_SB_CB<6>")
	)
	(segment
		(start 189.83579 -241.09299)
		(end 188.048138 -241.09299)
		(width 0.18288)
		(layer "In4.Cu")
		(net "M_G_CPU1_SB_CB<6>")
	)
	(segment
		(start 140.315696 -243.690648)
		(end 140.285216 -243.690648)
		(width 0.088646)
		(layer "In4.Cu")
		(net "M_G_CPU1_SB_CB<6>")
	)
	(segment
		(start 159.618426 -241.076226)
		(end 159.224218 -241.076226)
		(width 0.18288)
		(layer "In4.Cu")
		(net "M_G_CPU1_SB_CB<6>")
	)
	(segment
		(start 153.93162 -241.385344)
		(end 147.931886 -241.385344)
		(width 0.18288)
		(layer "In4.Cu")
		(net "M_G_CPU1_SB_CB<6>")
	)
	(segment
		(start 170.09364 -240.89614)
		(end 168.193212 -240.89614)
		(width 0.18288)
		(layer "In4.Cu")
		(net "M_G_CPU1_SB_CB<6>")
	)
	(segment
		(start 159.748474 -241.206274)
		(end 159.618426 -241.076226)
		(width 0.18288)
		(layer "In4.Cu")
		(net "M_G_CPU1_SB_CB<6>")
	)
	(segment
		(start 190.098426 -241.355626)
		(end 189.83579 -241.09299)
		(width 0.18288)
		(layer "In4.Cu")
		(net "M_G_CPU1_SB_CB<6>")
	)
	(segment
		(start 184.091326 -240.466626)
		(end 183.837326 -240.212626)
		(width 0.18288)
		(layer "In4.Cu")
		(net "M_G_CPU1_SB_CB<6>")
	)
	(segment
		(start 132.128514 -244.247416)
		(end 132.121148 -244.243098)
		(width 0.088646)
		(layer "In4.Cu")
		(net "M_G_CPU1_SB_CB<6>")
	)
	(segment
		(start 156.37764 -241.385344)
		(end 156.19476 -241.568224)
		(width 0.18288)
		(layer "In4.Cu")
		(net "M_G_CPU1_SB_CB<6>")
	)
	(segment
		(start 154.62504 -242.127786)
		(end 154.29738 -242.127786)
		(width 0.18288)
		(layer "In4.Cu")
		(net "M_G_CPU1_SB_CB<6>")
	)
	(segment
		(start 134.952486 -244.249956)
		(end 134.947914 -244.247416)
		(width 0.088646)
		(layer "In4.Cu")
		(net "M_G_CPU1_SB_CB<6>")
	)
	(segment
		(start 155.50134 -241.944906)
		(end 155.50134 -241.568224)
		(width 0.18288)
		(layer "In4.Cu")
		(net "M_G_CPU1_SB_CB<6>")
	)
	(segment
		(start 154.80792 -241.568224)
		(end 154.80792 -241.944906)
		(width 0.18288)
		(layer "In4.Cu")
		(net "M_G_CPU1_SB_CB<6>")
	)
	(segment
		(start 135.887968 -244.247162)
		(end 135.886444 -244.2464)
		(width 0.088646)
		(layer "In4.Cu")
		(net "M_G_CPU1_SB_CB<6>")
	)
	(segment
		(start 188.046614 -241.091466)
		(end 186.392566 -241.091466)
		(width 0.18288)
		(layer "In4.Cu")
		(net "M_G_CPU1_SB_CB<6>")
	)
	(arc
		(start 135.322564 -244.247416)
		(mid 135.13787 -244.297517)
		(end 134.952486 -244.249956)
		(width 0.088646)
		(layer "In4.Cu")
		(net "M_G_CPU1_SB_CB<6>")
	)
	(arc
		(start 136.827768 -244.247162)
		(mid 136.545066 -244.171386)
		(end 136.262364 -244.247162)
		(width 0.088646)
		(layer "In4.Cu")
		(net "M_G_CPU1_SB_CB<6>")
	)
	(arc
		(start 134.943342 -244.244622)
		(mid 134.662678 -244.171581)
		(end 134.382764 -244.247416)
		(width 0.088646)
		(layer "In4.Cu")
		(net "M_G_CPU1_SB_CB<6>")
	)
	(arc
		(start 137.202164 -244.247162)
		(mid 137.014966 -244.297305)
		(end 136.827768 -244.247162)
		(width 0.088646)
		(layer "In4.Cu")
		(net "M_G_CPU1_SB_CB<6>")
	)
	(arc
		(start 131.563364 -244.247416)
		(mid 131.37867 -244.297517)
		(end 131.193286 -244.249956)
		(width 0.088646)
		(layer "In4.Cu")
		(net "M_G_CPU1_SB_CB<6>")
	)
	(arc
		(start 131.185158 -244.24513)
		(mid 131.065769 -244.132786)
		(end 131.005834 -243.980208)
		(width 0.088646)
		(layer "In4.Cu")
		(net "M_G_CPU1_SB_CB<6>")
	)
	(arc
		(start 134.382764 -244.247416)
		(mid 134.195456 -244.297525)
		(end 134.008114 -244.247416)
		(width 0.088646)
		(layer "In4.Cu")
		(net "M_G_CPU1_SB_CB<6>")
	)
	(arc
		(start 133.060948 -244.243098)
		(mid 132.781487 -244.171629)
		(end 132.503164 -244.247416)
		(width 0.088646)
		(layer "In4.Cu")
		(net "M_G_CPU1_SB_CB<6>")
	)
	(arc
		(start 133.442964 -244.247416)
		(mid 133.25827 -244.297517)
		(end 133.072886 -244.249956)
		(width 0.088646)
		(layer "In4.Cu")
		(net "M_G_CPU1_SB_CB<6>")
	)
	(arc
		(start 132.503164 -244.247416)
		(mid 132.31847 -244.297517)
		(end 132.133086 -244.249956)
		(width 0.088646)
		(layer "In4.Cu")
		(net "M_G_CPU1_SB_CB<6>")
	)
	(arc
		(start 138.141964 -244.247162)
		(mid 137.954766 -244.297339)
		(end 137.767568 -244.247162)
		(width 0.088646)
		(layer "In4.Cu")
		(net "M_G_CPU1_SB_CB<6>")
	)
	(arc
		(start 136.262364 -244.247162)
		(mid 136.075166 -244.297305)
		(end 135.887968 -244.247162)
		(width 0.088646)
		(layer "In4.Cu")
		(net "M_G_CPU1_SB_CB<6>")
	)
	(arc
		(start 137.767568 -244.247162)
		(mid 137.484866 -244.171386)
		(end 137.202164 -244.247162)
		(width 0.088646)
		(layer "In4.Cu")
		(net "M_G_CPU1_SB_CB<6>")
	)
	(arc
		(start 132.121148 -244.243098)
		(mid 131.841687 -244.171629)
		(end 131.563364 -244.247416)
		(width 0.088646)
		(layer "In4.Cu")
		(net "M_G_CPU1_SB_CB<6>")
	)
	(arc
		(start 135.882126 -244.24386)
		(mid 135.601881 -244.171545)
		(end 135.322564 -244.247416)
		(width 0.088646)
		(layer "In4.Cu")
		(net "M_G_CPU1_SB_CB<6>")
	)
	(arc
		(start 134.002526 -244.24386)
		(mid 133.722281 -244.171545)
		(end 133.442964 -244.247416)
		(width 0.088646)
		(layer "In4.Cu")
		(net "M_G_CPU1_SB_CB<6>")
	)
	(arc
		(start 138.424666 -244.17147)
		(mid 138.278322 -244.190678)
		(end 138.141964 -244.247162)
		(width 0.088646)
		(layer "In4.Cu")
		(net "M_G_CPU1_SB_CB<6>")
	)
	(segment
		(start 191.421004 -239.509808)
		(end 191.421004 -239.877346)
		(width 0.20066)
		(layer "F.Cu")
		(net "M_G_CPU1_SB_CB<5>")
	)
	(segment
		(start 196.532246 -239.81664)
		(end 196.531992 -239.816894)
		(width 0.20066)
		(layer "F.Cu")
		(net "M_G_CPU1_SB_CB<5>")
	)
	(segment
		(start 191.786256 -239.391698)
		(end 191.539114 -239.391698)
		(width 0.20066)
		(layer "F.Cu")
		(net "M_G_CPU1_SB_CB<5>")
	)
	(segment
		(start 191.421004 -239.877346)
		(end 191.233044 -240.065306)
		(width 0.20066)
		(layer "F.Cu")
		(net "M_G_CPU1_SB_CB<5>")
	)
	(segment
		(start 194.277742 -239.391698)
		(end 194.241166 -239.391698)
		(width 0.101854)
		(layer "F.Cu")
		(net "M_G_CPU1_SB_CB<5>")
	)
	(segment
		(start 194.901312 -239.816894)
		(end 194.476116 -239.391698)
		(width 0.20066)
		(layer "F.Cu")
		(net "M_G_CPU1_SB_CB<5>")
	)
	(segment
		(start 190.75781 -240.065306)
		(end 190.509144 -239.81664)
		(width 0.20066)
		(layer "F.Cu")
		(net "M_G_CPU1_SB_CB<5>")
	)
	(segment
		(start 194.241166 -239.391698)
		(end 191.930782 -239.391698)
		(width 0.1016)
		(layer "F.Cu")
		(net "M_G_CPU1_SB_CB<5>")
	)
	(segment
		(start 129.966212 -243.644674)
		(end 129.966212 -243.108988)
		(width 0.20066)
		(layer "F.Cu")
		(net "M_G_CPU1_SB_CB<5>")
	)
	(segment
		(start 196.531992 -239.816894)
		(end 194.901312 -239.816894)
		(width 0.20066)
		(layer "F.Cu")
		(net "M_G_CPU1_SB_CB<5>")
	)
	(segment
		(start 191.539114 -239.391698)
		(end 191.421004 -239.509808)
		(width 0.20066)
		(layer "F.Cu")
		(net "M_G_CPU1_SB_CB<5>")
	)
	(segment
		(start 191.930782 -239.391698)
		(end 191.786256 -239.391698)
		(width 0.101854)
		(layer "F.Cu")
		(net "M_G_CPU1_SB_CB<5>")
	)
	(segment
		(start 194.476116 -239.391698)
		(end 194.277742 -239.391698)
		(width 0.20066)
		(layer "F.Cu")
		(net "M_G_CPU1_SB_CB<5>")
	)
	(segment
		(start 191.233044 -240.065306)
		(end 190.75781 -240.065306)
		(width 0.20066)
		(layer "F.Cu")
		(net "M_G_CPU1_SB_CB<5>")
	)
	(segment
		(start 190.509144 -239.81664)
		(end 188.988446 -239.81664)
		(width 0.20066)
		(layer "F.Cu")
		(net "M_G_CPU1_SB_CB<5>")
	)
	(segment
		(start 188.988446 -239.81664)
		(end 187.883546 -239.81664)
		(width 0.20066)
		(layer "F.Cu")
		(net "M_G_CPU1_SB_CB<5>")
	)
	(segment
		(start 129.966466 -243.644928)
		(end 129.966212 -243.644674)
		(width 0.20066)
		(layer "F.Cu")
		(net "M_G_CPU1_SB_CB<5>")
	)
	(segment
		(start 163.142422 -240.156746)
		(end 163.142422 -239.902238)
		(width 0.18288)
		(layer "In4.Cu")
		(net "M_G_CPU1_SB_CB<5>")
	)
	(segment
		(start 178.858926 -239.349026)
		(end 178.579526 -239.628426)
		(width 0.18288)
		(layer "In4.Cu")
		(net "M_G_CPU1_SB_CB<5>")
	)
	(segment
		(start 151.869902 -240.887504)
		(end 147.725638 -240.887504)
		(width 0.18288)
		(layer "In4.Cu")
		(net "M_G_CPU1_SB_CB<5>")
	)
	(segment
		(start 181.774338 -239.51057)
		(end 181.774338 -239.166908)
		(width 0.18288)
		(layer "In4.Cu")
		(net "M_G_CPU1_SB_CB<5>")
	)
	(segment
		(start 161.263838 -240.339626)
		(end 161.035238 -240.111026)
		(width 0.18288)
		(layer "In4.Cu")
		(net "M_G_CPU1_SB_CB<5>")
	)
	(segment
		(start 185.643774 -239.371632)
		(end 185.298334 -239.228884)
		(width 0.18288)
		(layer "In4.Cu")
		(net "M_G_CPU1_SB_CB<5>")
	)
	(segment
		(start 171.238926 -240.923826)
		(end 170.603926 -240.288826)
		(width 0.18288)
		(layer "In4.Cu")
		(net "M_G_CPU1_SB_CB<5>")
	)
	(segment
		(start 181.957218 -239.69345)
		(end 181.774338 -239.51057)
		(width 0.18288)
		(layer "In4.Cu")
		(net "M_G_CPU1_SB_CB<5>")
	)
	(segment
		(start 135.887714 -243.598446)
		(end 135.884158 -243.600478)
		(width 0.088646)
		(layer "In4.Cu")
		(net "M_G_CPU1_SB_CB<5>")
	)
	(segment
		(start 187.883546 -239.81664)
		(end 187.28436 -240.415826)
		(width 0.18288)
		(layer "In4.Cu")
		(net "M_G_CPU1_SB_CB<5>")
	)
	(segment
		(start 158.12643 -240.111026)
		(end 157.785816 -240.111026)
		(width 0.18288)
		(layer "In4.Cu")
		(net "M_G_CPU1_SB_CB<5>")
	)
	(segment
		(start 155.575254 -240.110772)
		(end 155.392374 -240.293652)
		(width 0.18288)
		(layer "In4.Cu")
		(net "M_G_CPU1_SB_CB<5>")
	)
	(segment
		(start 165.555168 -240.187226)
		(end 164.622226 -240.187226)
		(width 0.18288)
		(layer "In4.Cu")
		(net "M_G_CPU1_SB_CB<5>")
	)
	(segment
		(start 167.975026 -240.187226)
		(end 166.568628 -240.187226)
		(width 0.18288)
		(layer "In4.Cu")
		(net "M_G_CPU1_SB_CB<5>")
	)
	(segment
		(start 155.902914 -240.110772)
		(end 155.575254 -240.110772)
		(width 0.18288)
		(layer "In4.Cu")
		(net "M_G_CPU1_SB_CB<5>")
	)
	(segment
		(start 139.004548 -243.323364)
		(end 138.653774 -243.674138)
		(width 0.088646)
		(layer "In4.Cu")
		(net "M_G_CPU1_SB_CB<5>")
	)
	(segment
		(start 181.774338 -239.166908)
		(end 181.591458 -238.984028)
		(width 0.18288)
		(layer "In4.Cu")
		(net "M_G_CPU1_SB_CB<5>")
	)
	(segment
		(start 152.646634 -240.110772)
		(end 151.869902 -240.887504)
		(width 0.18288)
		(layer "In4.Cu")
		(net "M_G_CPU1_SB_CB<5>")
	)
	(segment
		(start 185.687462 -239.685068)
		(end 185.730388 -239.581182)
		(width 0.18288)
		(layer "In4.Cu")
		(net "M_G_CPU1_SB_CB<5>")
	)
	(segment
		(start 175.672242 -240.124742)
		(end 174.899066 -240.124742)
		(width 0.18288)
		(layer "In4.Cu")
		(net "M_G_CPU1_SB_CB<5>")
	)
	(segment
		(start 181.080918 -239.51057)
		(end 180.898038 -239.69345)
		(width 0.18288)
		(layer "In4.Cu")
		(net "M_G_CPU1_SB_CB<5>")
	)
	(segment
		(start 177.347372 -240.441226)
		(end 177.147728 -240.241582)
		(width 0.18288)
		(layer "In4.Cu")
		(net "M_G_CPU1_SB_CB<5>")
	)
	(segment
		(start 156.268674 -240.723928)
		(end 156.085794 -240.541048)
		(width 0.18288)
		(layer "In4.Cu")
		(net "M_G_CPU1_SB_CB<5>")
	)
	(segment
		(start 158.97987 -240.510568)
		(end 158.81985 -240.670588)
		(width 0.18288)
		(layer "In4.Cu")
		(net "M_G_CPU1_SB_CB<5>")
	)
	(segment
		(start 185.089546 -239.315244)
		(end 185.046366 -239.419384)
		(width 0.18288)
		(layer "In4.Cu")
		(net "M_G_CPU1_SB_CB<5>")
	)
	(segment
		(start 132.134356 -243.595144)
		(end 132.122672 -243.601748)
		(width 0.088646)
		(layer "In4.Cu")
		(net "M_G_CPU1_SB_CB<5>")
	)
	(segment
		(start 185.046366 -239.419384)
		(end 184.837832 -239.505998)
		(width 0.18288)
		(layer "In4.Cu")
		(net "M_G_CPU1_SB_CB<5>")
	)
	(segment
		(start 181.591458 -238.984028)
		(end 181.263798 -238.984028)
		(width 0.18288)
		(layer "In4.Cu")
		(net "M_G_CPU1_SB_CB<5>")
	)
	(segment
		(start 185.730388 -239.581182)
		(end 185.643774 -239.371632)
		(width 0.18288)
		(layer "In4.Cu")
		(net "M_G_CPU1_SB_CB<5>")
	)
	(segment
		(start 164.469826 -240.339626)
		(end 163.325302 -240.339626)
		(width 0.18288)
		(layer "In4.Cu")
		(net "M_G_CPU1_SB_CB<5>")
	)
	(segment
		(start 145.289778 -243.323364)
		(end 140.315696 -243.323364)
		(width 0.18288)
		(layer "In4.Cu")
		(net "M_G_CPU1_SB_CB<5>")
	)
	(segment
		(start 130.623564 -243.598446)
		(end 130.543554 -243.552218)
		(width 0.088646)
		(layer "In4.Cu")
		(net "M_G_CPU1_SB_CB<5>")
	)
	(segment
		(start 165.715188 -240.347246)
		(end 165.555168 -240.187226)
		(width 0.18288)
		(layer "In4.Cu")
		(net "M_G_CPU1_SB_CB<5>")
	)
	(segment
		(start 172.013626 -240.923826)
		(end 171.238926 -240.923826)
		(width 0.18288)
		(layer "In4.Cu")
		(net "M_G_CPU1_SB_CB<5>")
	)
	(segment
		(start 186.591194 -240.415826)
		(end 186.277758 -240.10239)
		(width 0.18288)
		(layer "In4.Cu")
		(net "M_G_CPU1_SB_CB<5>")
	)
	(segment
		(start 178.579526 -239.628426)
		(end 178.579526 -239.857026)
		(width 0.18288)
		(layer "In4.Cu")
		(net "M_G_CPU1_SB_CB<5>")
	)
	(segment
		(start 184.152286 -239.222026)
		(end 183.811926 -239.222026)
		(width 0.18288)
		(layer "In4.Cu")
		(net "M_G_CPU1_SB_CB<5>")
	)
	(segment
		(start 157.785816 -240.111026)
		(end 157.785562 -240.110772)
		(width 0.18288)
		(layer "In4.Cu")
		(net "M_G_CPU1_SB_CB<5>")
	)
	(segment
		(start 177.995326 -240.441226)
		(end 177.347372 -240.441226)
		(width 0.18288)
		(layer "In4.Cu")
		(net "M_G_CPU1_SB_CB<5>")
	)
	(segment
		(start 134.008114 -243.598446)
		(end 134.004558 -243.600478)
		(width 0.088646)
		(layer "In4.Cu")
		(net "M_G_CPU1_SB_CB<5>")
	)
	(segment
		(start 154.516074 -240.110772)
		(end 152.646634 -240.110772)
		(width 0.18288)
		(layer "In4.Cu")
		(net "M_G_CPU1_SB_CB<5>")
	)
	(segment
		(start 168.076626 -240.288826)
		(end 167.975026 -240.187226)
		(width 0.18288)
		(layer "In4.Cu")
		(net "M_G_CPU1_SB_CB<5>")
	)
	(segment
		(start 173.931326 -241.092482)
		(end 172.182282 -241.092482)
		(width 0.18288)
		(layer "In4.Cu")
		(net "M_G_CPU1_SB_CB<5>")
	)
	(segment
		(start 181.263798 -238.984028)
		(end 181.080918 -239.166908)
		(width 0.18288)
		(layer "In4.Cu")
		(net "M_G_CPU1_SB_CB<5>")
	)
	(segment
		(start 162.449002 -240.156746)
		(end 162.266122 -240.339626)
		(width 0.18288)
		(layer "In4.Cu")
		(net "M_G_CPU1_SB_CB<5>")
	)
	(segment
		(start 180.898038 -239.69345)
		(end 180.04155 -239.69345)
		(width 0.18288)
		(layer "In4.Cu")
		(net "M_G_CPU1_SB_CB<5>")
	)
	(segment
		(start 179.697126 -239.349026)
		(end 178.858926 -239.349026)
		(width 0.18288)
		(layer "In4.Cu")
		(net "M_G_CPU1_SB_CB<5>")
	)
	(segment
		(start 163.325302 -240.339626)
		(end 163.142422 -240.156746)
		(width 0.18288)
		(layer "In4.Cu")
		(net "M_G_CPU1_SB_CB<5>")
	)
	(segment
		(start 185.298334 -239.228884)
		(end 185.089546 -239.315244)
		(width 0.18288)
		(layer "In4.Cu")
		(net "M_G_CPU1_SB_CB<5>")
	)
	(segment
		(start 166.408608 -240.375694)
		(end 166.248588 -240.535714)
		(width 0.18288)
		(layer "In4.Cu")
		(net "M_G_CPU1_SB_CB<5>")
	)
	(segment
		(start 162.959542 -239.719358)
		(end 162.631882 -239.719358)
		(width 0.18288)
		(layer "In4.Cu")
		(net "M_G_CPU1_SB_CB<5>")
	)
	(segment
		(start 180.04155 -239.69345)
		(end 179.697126 -239.349026)
		(width 0.18288)
		(layer "In4.Cu")
		(net "M_G_CPU1_SB_CB<5>")
	)
	(segment
		(start 155.392374 -240.541048)
		(end 155.209494 -240.723928)
		(width 0.18288)
		(layer "In4.Cu")
		(net "M_G_CPU1_SB_CB<5>")
	)
	(segment
		(start 133.074156 -243.595144)
		(end 133.062472 -243.601748)
		(width 0.088646)
		(layer "In4.Cu")
		(net "M_G_CPU1_SB_CB<5>")
	)
	(segment
		(start 156.085794 -240.293652)
		(end 155.902914 -240.110772)
		(width 0.18288)
		(layer "In4.Cu")
		(net "M_G_CPU1_SB_CB<5>")
	)
	(segment
		(start 177.147728 -240.241582)
		(end 175.789082 -240.241582)
		(width 0.18288)
		(layer "In4.Cu")
		(net "M_G_CPU1_SB_CB<5>")
	)
	(segment
		(start 134.953756 -243.595144)
		(end 134.943342 -243.600986)
		(width 0.088646)
		(layer "In4.Cu")
		(net "M_G_CPU1_SB_CB<5>")
	)
	(segment
		(start 131.194556 -243.595144)
		(end 131.182872 -243.601748)
		(width 0.088646)
		(layer "In4.Cu")
		(net "M_G_CPU1_SB_CB<5>")
	)
	(segment
		(start 166.248588 -240.535714)
		(end 165.875208 -240.535714)
		(width 0.18288)
		(layer "In4.Cu")
		(net "M_G_CPU1_SB_CB<5>")
	)
	(segment
		(start 164.622226 -240.187226)
		(end 164.469826 -240.339626)
		(width 0.18288)
		(layer "In4.Cu")
		(net "M_G_CPU1_SB_CB<5>")
	)
	(segment
		(start 186.277758 -240.10239)
		(end 185.773822 -239.893602)
		(width 0.18288)
		(layer "In4.Cu")
		(net "M_G_CPU1_SB_CB<5>")
	)
	(segment
		(start 163.142422 -239.902238)
		(end 162.959542 -239.719358)
		(width 0.18288)
		(layer "In4.Cu")
		(net "M_G_CPU1_SB_CB<5>")
	)
	(segment
		(start 156.779214 -240.541048)
		(end 156.596334 -240.723928)
		(width 0.18288)
		(layer "In4.Cu")
		(net "M_G_CPU1_SB_CB<5>")
	)
	(segment
		(start 156.962094 -240.110772)
		(end 156.779214 -240.293652)
		(width 0.18288)
		(layer "In4.Cu")
		(net "M_G_CPU1_SB_CB<5>")
	)
	(segment
		(start 162.449002 -239.902238)
		(end 162.449002 -240.156746)
		(width 0.18288)
		(layer "In4.Cu")
		(net "M_G_CPU1_SB_CB<5>")
	)
	(segment
		(start 159.13989 -240.111026)
		(end 158.97987 -240.271046)
		(width 0.18288)
		(layer "In4.Cu")
		(net "M_G_CPU1_SB_CB<5>")
	)
	(segment
		(start 156.596334 -240.723928)
		(end 156.268674 -240.723928)
		(width 0.18288)
		(layer "In4.Cu")
		(net "M_G_CPU1_SB_CB<5>")
	)
	(segment
		(start 158.81985 -240.670588)
		(end 158.44647 -240.670588)
		(width 0.18288)
		(layer "In4.Cu")
		(net "M_G_CPU1_SB_CB<5>")
	)
	(segment
		(start 166.568628 -240.187226)
		(end 166.408608 -240.347246)
		(width 0.18288)
		(layer "In4.Cu")
		(net "M_G_CPU1_SB_CB<5>")
	)
	(segment
		(start 175.789082 -240.241582)
		(end 175.672242 -240.124742)
		(width 0.18288)
		(layer "In4.Cu")
		(net "M_G_CPU1_SB_CB<5>")
	)
	(segment
		(start 178.579526 -239.857026)
		(end 177.995326 -240.441226)
		(width 0.18288)
		(layer "In4.Cu")
		(net "M_G_CPU1_SB_CB<5>")
	)
	(segment
		(start 140.315696 -243.323364)
		(end 139.004548 -243.323364)
		(width 0.088646)
		(layer "In4.Cu")
		(net "M_G_CPU1_SB_CB<5>")
	)
	(segment
		(start 154.698954 -240.293652)
		(end 154.516074 -240.110772)
		(width 0.18288)
		(layer "In4.Cu")
		(net "M_G_CPU1_SB_CB<5>")
	)
	(segment
		(start 183.340502 -239.69345)
		(end 181.957218 -239.69345)
		(width 0.18288)
		(layer "In4.Cu")
		(net "M_G_CPU1_SB_CB<5>")
	)
	(segment
		(start 181.080918 -239.166908)
		(end 181.080918 -239.51057)
		(width 0.18288)
		(layer "In4.Cu")
		(net "M_G_CPU1_SB_CB<5>")
	)
	(segment
		(start 158.44647 -240.670588)
		(end 158.28645 -240.510568)
		(width 0.18288)
		(layer "In4.Cu")
		(net "M_G_CPU1_SB_CB<5>")
	)
	(segment
		(start 165.715188 -240.375694)
		(end 165.715188 -240.347246)
		(width 0.18288)
		(layer "In4.Cu")
		(net "M_G_CPU1_SB_CB<5>")
	)
	(segment
		(start 158.28645 -240.271046)
		(end 158.12643 -240.111026)
		(width 0.18288)
		(layer "In4.Cu")
		(net "M_G_CPU1_SB_CB<5>")
	)
	(segment
		(start 157.785562 -240.110772)
		(end 156.962094 -240.110772)
		(width 0.18288)
		(layer "In4.Cu")
		(net "M_G_CPU1_SB_CB<5>")
	)
	(segment
		(start 161.035238 -240.111026)
		(end 159.13989 -240.111026)
		(width 0.18288)
		(layer "In4.Cu")
		(net "M_G_CPU1_SB_CB<5>")
	)
	(segment
		(start 154.698954 -240.541048)
		(end 154.698954 -240.293652)
		(width 0.18288)
		(layer "In4.Cu")
		(net "M_G_CPU1_SB_CB<5>")
	)
	(segment
		(start 158.28645 -240.510568)
		(end 158.28645 -240.271046)
		(width 0.18288)
		(layer "In4.Cu")
		(net "M_G_CPU1_SB_CB<5>")
	)
	(segment
		(start 147.725638 -240.887504)
		(end 145.289778 -243.323364)
		(width 0.18288)
		(layer "In4.Cu")
		(net "M_G_CPU1_SB_CB<5>")
	)
	(segment
		(start 185.773822 -239.893602)
		(end 185.687462 -239.685068)
		(width 0.18288)
		(layer "In4.Cu")
		(net "M_G_CPU1_SB_CB<5>")
	)
	(segment
		(start 156.085794 -240.541048)
		(end 156.085794 -240.293652)
		(width 0.18288)
		(layer "In4.Cu")
		(net "M_G_CPU1_SB_CB<5>")
	)
	(segment
		(start 138.653774 -243.674138)
		(end 137.484866 -243.674138)
		(width 0.088646)
		(layer "In4.Cu")
		(net "M_G_CPU1_SB_CB<5>")
	)
	(segment
		(start 170.603926 -240.288826)
		(end 168.076626 -240.288826)
		(width 0.18288)
		(layer "In4.Cu")
		(net "M_G_CPU1_SB_CB<5>")
	)
	(segment
		(start 158.97987 -240.271046)
		(end 158.97987 -240.510568)
		(width 0.18288)
		(layer "In4.Cu")
		(net "M_G_CPU1_SB_CB<5>")
	)
	(segment
		(start 165.875208 -240.535714)
		(end 165.715188 -240.375694)
		(width 0.18288)
		(layer "In4.Cu")
		(net "M_G_CPU1_SB_CB<5>")
	)
	(segment
		(start 155.209494 -240.723928)
		(end 154.881834 -240.723928)
		(width 0.18288)
		(layer "In4.Cu")
		(net "M_G_CPU1_SB_CB<5>")
	)
	(segment
		(start 162.631882 -239.719358)
		(end 162.449002 -239.902238)
		(width 0.18288)
		(layer "In4.Cu")
		(net "M_G_CPU1_SB_CB<5>")
	)
	(segment
		(start 162.266122 -240.339626)
		(end 161.263838 -240.339626)
		(width 0.18288)
		(layer "In4.Cu")
		(net "M_G_CPU1_SB_CB<5>")
	)
	(segment
		(start 156.779214 -240.293652)
		(end 156.779214 -240.541048)
		(width 0.18288)
		(layer "In4.Cu")
		(net "M_G_CPU1_SB_CB<5>")
	)
	(segment
		(start 187.28436 -240.415826)
		(end 186.591194 -240.415826)
		(width 0.18288)
		(layer "In4.Cu")
		(net "M_G_CPU1_SB_CB<5>")
	)
	(segment
		(start 135.887968 -243.598446)
		(end 135.887714 -243.598446)
		(width 0.088646)
		(layer "In4.Cu")
		(net "M_G_CPU1_SB_CB<5>")
	)
	(segment
		(start 166.408608 -240.347246)
		(end 166.408608 -240.375694)
		(width 0.18288)
		(layer "In4.Cu")
		(net "M_G_CPU1_SB_CB<5>")
	)
	(segment
		(start 183.811926 -239.222026)
		(end 183.340502 -239.69345)
		(width 0.18288)
		(layer "In4.Cu")
		(net "M_G_CPU1_SB_CB<5>")
	)
	(segment
		(start 154.881834 -240.723928)
		(end 154.698954 -240.541048)
		(width 0.18288)
		(layer "In4.Cu")
		(net "M_G_CPU1_SB_CB<5>")
	)
	(segment
		(start 184.837832 -239.505998)
		(end 184.152286 -239.222026)
		(width 0.18288)
		(layer "In4.Cu")
		(net "M_G_CPU1_SB_CB<5>")
	)
	(segment
		(start 172.182282 -241.092482)
		(end 172.013626 -240.923826)
		(width 0.18288)
		(layer "In4.Cu")
		(net "M_G_CPU1_SB_CB<5>")
	)
	(segment
		(start 174.899066 -240.124742)
		(end 173.931326 -241.092482)
		(width 0.18288)
		(layer "In4.Cu")
		(net "M_G_CPU1_SB_CB<5>")
	)
	(segment
		(start 155.392374 -240.293652)
		(end 155.392374 -240.541048)
		(width 0.18288)
		(layer "In4.Cu")
		(net "M_G_CPU1_SB_CB<5>")
	)
	(arc
		(start 133.062472 -243.601748)
		(mid 132.782367 -243.67419)
		(end 132.503164 -243.598446)
		(width 0.088646)
		(layer "In4.Cu")
		(net "M_G_CPU1_SB_CB<5>")
	)
	(arc
		(start 132.122672 -243.601748)
		(mid 131.842567 -243.67419)
		(end 131.563364 -243.598446)
		(width 0.088646)
		(layer "In4.Cu")
		(net "M_G_CPU1_SB_CB<5>")
	)
	(arc
		(start 137.484866 -243.674138)
		(mid 137.338543 -243.654876)
		(end 137.202164 -243.598446)
		(width 0.088646)
		(layer "In4.Cu")
		(net "M_G_CPU1_SB_CB<5>")
	)
	(arc
		(start 137.202164 -243.598446)
		(mid 137.014966 -243.548303)
		(end 136.827768 -243.598446)
		(width 0.088646)
		(layer "In4.Cu")
		(net "M_G_CPU1_SB_CB<5>")
	)
	(arc
		(start 134.943342 -243.600986)
		(mid 134.662707 -243.674154)
		(end 134.382764 -243.598446)
		(width 0.088646)
		(layer "In4.Cu")
		(net "M_G_CPU1_SB_CB<5>")
	)
	(arc
		(start 131.563364 -243.598446)
		(mid 131.37941 -243.548317)
		(end 131.194556 -243.595144)
		(width 0.088646)
		(layer "In4.Cu")
		(net "M_G_CPU1_SB_CB<5>")
	)
	(arc
		(start 135.884158 -243.600478)
		(mid 135.603074 -243.674215)
		(end 135.322564 -243.598446)
		(width 0.088646)
		(layer "In4.Cu")
		(net "M_G_CPU1_SB_CB<5>")
	)
	(arc
		(start 131.182872 -243.601748)
		(mid 130.902767 -243.67419)
		(end 130.623564 -243.598446)
		(width 0.088646)
		(layer "In4.Cu")
		(net "M_G_CPU1_SB_CB<5>")
	)
	(arc
		(start 136.827768 -243.598446)
		(mid 136.545066 -243.674222)
		(end 136.262364 -243.598446)
		(width 0.088646)
		(layer "In4.Cu")
		(net "M_G_CPU1_SB_CB<5>")
	)
	(arc
		(start 136.262364 -243.598446)
		(mid 136.075166 -243.548303)
		(end 135.887968 -243.598446)
		(width 0.088646)
		(layer "In4.Cu")
		(net "M_G_CPU1_SB_CB<5>")
	)
	(arc
		(start 133.442964 -243.598446)
		(mid 133.25901 -243.548317)
		(end 133.074156 -243.595144)
		(width 0.088646)
		(layer "In4.Cu")
		(net "M_G_CPU1_SB_CB<5>")
	)
	(arc
		(start 134.004558 -243.600478)
		(mid 133.723474 -243.674215)
		(end 133.442964 -243.598446)
		(width 0.088646)
		(layer "In4.Cu")
		(net "M_G_CPU1_SB_CB<5>")
	)
	(arc
		(start 135.322564 -243.598446)
		(mid 135.13861 -243.548317)
		(end 134.953756 -243.595144)
		(width 0.088646)
		(layer "In4.Cu")
		(net "M_G_CPU1_SB_CB<5>")
	)
	(arc
		(start 132.503164 -243.598446)
		(mid 132.31921 -243.548317)
		(end 132.134356 -243.595144)
		(width 0.088646)
		(layer "In4.Cu")
		(net "M_G_CPU1_SB_CB<5>")
	)
	(arc
		(start 134.382764 -243.598446)
		(mid 134.195456 -243.548303)
		(end 134.008114 -243.598446)
		(width 0.088646)
		(layer "In4.Cu")
		(net "M_G_CPU1_SB_CB<5>")
	)
	(arc
		(start 130.543554 -243.552218)
		(mid 130.241655 -243.347834)
		(end 129.966212 -243.108988)
		(width 0.088646)
		(layer "In4.Cu")
		(net "M_G_CPU1_SB_CB<5>")
	)
	(segment
		(start 188.988446 -241.516662)
		(end 187.883546 -241.516662)
		(width 0.20066)
		(layer "F.Cu")
		(net "M_G_CPU1_SB_CB<4>")
	)
	(segment
		(start 191.786256 -241.09172)
		(end 191.539114 -241.09172)
		(width 0.20066)
		(layer "F.Cu")
		(net "M_G_CPU1_SB_CB<4>")
	)
	(segment
		(start 196.531992 -241.516916)
		(end 194.901312 -241.516916)
		(width 0.20066)
		(layer "F.Cu")
		(net "M_G_CPU1_SB_CB<4>")
	)
	(segment
		(start 194.241166 -241.09172)
		(end 191.930782 -241.09172)
		(width 0.1016)
		(layer "F.Cu")
		(net "M_G_CPU1_SB_CB<4>")
	)
	(segment
		(start 191.421004 -241.577368)
		(end 191.233044 -241.765328)
		(width 0.20066)
		(layer "F.Cu")
		(net "M_G_CPU1_SB_CB<4>")
	)
	(segment
		(start 191.930782 -241.09172)
		(end 191.786256 -241.09172)
		(width 0.101854)
		(layer "F.Cu")
		(net "M_G_CPU1_SB_CB<4>")
	)
	(segment
		(start 191.421004 -241.20983)
		(end 191.421004 -241.577368)
		(width 0.20066)
		(layer "F.Cu")
		(net "M_G_CPU1_SB_CB<4>")
	)
	(segment
		(start 130.436366 -244.45849)
		(end 130.436366 -243.922804)
		(width 0.20066)
		(layer "F.Cu")
		(net "M_G_CPU1_SB_CB<4>")
	)
	(segment
		(start 194.277742 -241.09172)
		(end 194.241166 -241.09172)
		(width 0.101854)
		(layer "F.Cu")
		(net "M_G_CPU1_SB_CB<4>")
	)
	(segment
		(start 196.532246 -241.516662)
		(end 196.531992 -241.516916)
		(width 0.20066)
		(layer "F.Cu")
		(net "M_G_CPU1_SB_CB<4>")
	)
	(segment
		(start 194.476116 -241.09172)
		(end 194.277742 -241.09172)
		(width 0.20066)
		(layer "F.Cu")
		(net "M_G_CPU1_SB_CB<4>")
	)
	(segment
		(start 191.233044 -241.765328)
		(end 190.75781 -241.765328)
		(width 0.20066)
		(layer "F.Cu")
		(net "M_G_CPU1_SB_CB<4>")
	)
	(segment
		(start 130.436112 -244.458744)
		(end 130.436366 -244.45849)
		(width 0.20066)
		(layer "F.Cu")
		(net "M_G_CPU1_SB_CB<4>")
	)
	(segment
		(start 191.539114 -241.09172)
		(end 191.421004 -241.20983)
		(width 0.20066)
		(layer "F.Cu")
		(net "M_G_CPU1_SB_CB<4>")
	)
	(segment
		(start 190.75781 -241.765328)
		(end 190.509144 -241.516662)
		(width 0.20066)
		(layer "F.Cu")
		(net "M_G_CPU1_SB_CB<4>")
	)
	(segment
		(start 194.901312 -241.516916)
		(end 194.476116 -241.09172)
		(width 0.20066)
		(layer "F.Cu")
		(net "M_G_CPU1_SB_CB<4>")
	)
	(segment
		(start 190.509144 -241.516662)
		(end 188.988446 -241.516662)
		(width 0.20066)
		(layer "F.Cu")
		(net "M_G_CPU1_SB_CB<4>")
	)
	(segment
		(start 174.95901 -241.623088)
		(end 174.081186 -242.500912)
		(width 0.18288)
		(layer "In4.Cu")
		(net "M_G_CPU1_SB_CB<4>")
	)
	(segment
		(start 165.229286 -241.688366)
		(end 164.850826 -242.066826)
		(width 0.18288)
		(layer "In4.Cu")
		(net "M_G_CPU1_SB_CB<4>")
	)
	(segment
		(start 132.033264 -244.412262)
		(end 132.028692 -244.409722)
		(width 0.088646)
		(layer "In4.Cu")
		(net "M_G_CPU1_SB_CB<4>")
	)
	(segment
		(start 164.123116 -242.066826)
		(end 163.940236 -242.249706)
		(width 0.18288)
		(layer "In4.Cu")
		(net "M_G_CPU1_SB_CB<4>")
	)
	(segment
		(start 134.86003 -244.41658)
		(end 134.852664 -244.412262)
		(width 0.088646)
		(layer "In4.Cu")
		(net "M_G_CPU1_SB_CB<4>")
	)
	(segment
		(start 181.933088 -242.509548)
		(end 181.773068 -242.669568)
		(width 0.18288)
		(layer "In4.Cu")
		(net "M_G_CPU1_SB_CB<4>")
	)
	(segment
		(start 177.306732 -241.94262)
		(end 176.60112 -241.94262)
		(width 0.18288)
		(layer "In4.Cu")
		(net "M_G_CPU1_SB_CB<4>")
	)
	(segment
		(start 164.850826 -242.066826)
		(end 164.123116 -242.066826)
		(width 0.18288)
		(layer "In4.Cu")
		(net "M_G_CPU1_SB_CB<4>")
	)
	(segment
		(start 172.267626 -242.498626)
		(end 170.372532 -242.498626)
		(width 0.18288)
		(layer "In4.Cu")
		(net "M_G_CPU1_SB_CB<4>")
	)
	(segment
		(start 133.912864 -244.412262)
		(end 133.910324 -244.410738)
		(width 0.088646)
		(layer "In4.Cu")
		(net "M_G_CPU1_SB_CB<4>")
	)
	(segment
		(start 181.052978 -241.327432)
		(end 179.99202 -241.327432)
		(width 0.18288)
		(layer "In4.Cu")
		(net "M_G_CPU1_SB_CB<4>")
	)
	(segment
		(start 181.212998 -242.486434)
		(end 181.212998 -241.487452)
		(width 0.18288)
		(layer "In4.Cu")
		(net "M_G_CPU1_SB_CB<4>")
	)
	(segment
		(start 162.098736 -241.943636)
		(end 161.3662 -241.943636)
		(width 0.18288)
		(layer "In4.Cu")
		(net "M_G_CPU1_SB_CB<4>")
	)
	(segment
		(start 156.187394 -242.697508)
		(end 147.353274 -242.697508)
		(width 0.18288)
		(layer "In4.Cu")
		(net "M_G_CPU1_SB_CB<4>")
	)
	(segment
		(start 161.3662 -241.943636)
		(end 161.305748 -241.883184)
		(width 0.18288)
		(layer "In4.Cu")
		(net "M_G_CPU1_SB_CB<4>")
	)
	(segment
		(start 163.246816 -242.51031)
		(end 163.246816 -242.249706)
		(width 0.18288)
		(layer "In4.Cu")
		(net "M_G_CPU1_SB_CB<4>")
	)
	(segment
		(start 163.757356 -242.69319)
		(end 163.429696 -242.69319)
		(width 0.18288)
		(layer "In4.Cu")
		(net "M_G_CPU1_SB_CB<4>")
	)
	(segment
		(start 184.013348 -241.050826)
		(end 183.7944 -241.269774)
		(width 0.18288)
		(layer "In4.Cu")
		(net "M_G_CPU1_SB_CB<4>")
	)
	(segment
		(start 169.816526 -241.94262)
		(end 168.23182 -241.94262)
		(width 0.18288)
		(layer "In4.Cu")
		(net "M_G_CPU1_SB_CB<4>")
	)
	(segment
		(start 183.212486 -242.14328)
		(end 183.052466 -241.98326)
		(width 0.18288)
		(layer "In4.Cu")
		(net "M_G_CPU1_SB_CB<4>")
	)
	(segment
		(start 183.052466 -241.426746)
		(end 182.892446 -241.266726)
		(width 0.18288)
		(layer "In4.Cu")
		(net "M_G_CPU1_SB_CB<4>")
	)
	(segment
		(start 130.876802 -244.18798)
		(end 130.436366 -243.922804)
		(width 0.088646)
		(layer "In4.Cu")
		(net "M_G_CPU1_SB_CB<4>")
	)
	(segment
		(start 132.04063 -244.41658)
		(end 132.033264 -244.412262)
		(width 0.088646)
		(layer "In4.Cu")
		(net "M_G_CPU1_SB_CB<4>")
	)
	(segment
		(start 157.001718 -241.883184)
		(end 156.187394 -242.697508)
		(width 0.18288)
		(layer "In4.Cu")
		(net "M_G_CPU1_SB_CB<4>")
	)
	(segment
		(start 163.429696 -242.69319)
		(end 163.246816 -242.51031)
		(width 0.18288)
		(layer "In4.Cu")
		(net "M_G_CPU1_SB_CB<4>")
	)
	(segment
		(start 183.052466 -241.98326)
		(end 183.052466 -241.426746)
		(width 0.18288)
		(layer "In4.Cu")
		(net "M_G_CPU1_SB_CB<4>")
	)
	(segment
		(start 173.319694 -242.500912)
		(end 173.028102 -242.792504)
		(width 0.18288)
		(layer "In4.Cu")
		(net "M_G_CPU1_SB_CB<4>")
	)
	(segment
		(start 163.063936 -242.066826)
		(end 162.221926 -242.066826)
		(width 0.18288)
		(layer "In4.Cu")
		(net "M_G_CPU1_SB_CB<4>")
	)
	(segment
		(start 134.852664 -244.412262)
		(end 134.848854 -244.41023)
		(width 0.088646)
		(layer "In4.Cu")
		(net "M_G_CPU1_SB_CB<4>")
	)
	(segment
		(start 187.883546 -241.516662)
		(end 187.249308 -242.1509)
		(width 0.18288)
		(layer "In4.Cu")
		(net "M_G_CPU1_SB_CB<4>")
	)
	(segment
		(start 181.773068 -242.669568)
		(end 181.396132 -242.669568)
		(width 0.18288)
		(layer "In4.Cu")
		(net "M_G_CPU1_SB_CB<4>")
	)
	(segment
		(start 138.726164 -244.361716)
		(end 138.424666 -244.361716)
		(width 0.088646)
		(layer "In4.Cu")
		(net "M_G_CPU1_SB_CB<4>")
	)
	(segment
		(start 181.212998 -241.487452)
		(end 181.052978 -241.327432)
		(width 0.18288)
		(layer "In4.Cu")
		(net "M_G_CPU1_SB_CB<4>")
	)
	(segment
		(start 146.003518 -244.047264)
		(end 140.315696 -244.047264)
		(width 0.18288)
		(layer "In4.Cu")
		(net "M_G_CPU1_SB_CB<4>")
	)
	(segment
		(start 172.561504 -242.792504)
		(end 172.267626 -242.498626)
		(width 0.18288)
		(layer "In4.Cu")
		(net "M_G_CPU1_SB_CB<4>")
	)
	(segment
		(start 140.29944 -244.047264)
		(end 140.288264 -244.036088)
		(width 0.088646)
		(layer "In4.Cu")
		(net "M_G_CPU1_SB_CB<4>")
	)
	(segment
		(start 176.60112 -241.94262)
		(end 176.281588 -241.623088)
		(width 0.18288)
		(layer "In4.Cu")
		(net "M_G_CPU1_SB_CB<4>")
	)
	(segment
		(start 181.933088 -241.426746)
		(end 181.933088 -242.509548)
		(width 0.18288)
		(layer "In4.Cu")
		(net "M_G_CPU1_SB_CB<4>")
	)
	(segment
		(start 161.305748 -241.883184)
		(end 157.001718 -241.883184)
		(width 0.18288)
		(layer "In4.Cu")
		(net "M_G_CPU1_SB_CB<4>")
	)
	(segment
		(start 132.973064 -244.412262)
		(end 132.968492 -244.409722)
		(width 0.088646)
		(layer "In4.Cu")
		(net "M_G_CPU1_SB_CB<4>")
	)
	(segment
		(start 147.353274 -242.697508)
		(end 146.003518 -244.047264)
		(width 0.18288)
		(layer "In4.Cu")
		(net "M_G_CPU1_SB_CB<4>")
	)
	(segment
		(start 163.940236 -242.249706)
		(end 163.940236 -242.51031)
		(width 0.18288)
		(layer "In4.Cu")
		(net "M_G_CPU1_SB_CB<4>")
	)
	(segment
		(start 183.611266 -242.14328)
		(end 183.212486 -242.14328)
		(width 0.18288)
		(layer "In4.Cu")
		(net "M_G_CPU1_SB_CB<4>")
	)
	(segment
		(start 132.98043 -244.41658)
		(end 132.973064 -244.412262)
		(width 0.088646)
		(layer "In4.Cu")
		(net "M_G_CPU1_SB_CB<4>")
	)
	(segment
		(start 176.281588 -241.623088)
		(end 174.95901 -241.623088)
		(width 0.18288)
		(layer "In4.Cu")
		(net "M_G_CPU1_SB_CB<4>")
	)
	(segment
		(start 177.666396 -242.302284)
		(end 177.306732 -241.94262)
		(width 0.18288)
		(layer "In4.Cu")
		(net "M_G_CPU1_SB_CB<4>")
	)
	(segment
		(start 168.23182 -241.94262)
		(end 167.977566 -241.688366)
		(width 0.18288)
		(layer "In4.Cu")
		(net "M_G_CPU1_SB_CB<4>")
	)
	(segment
		(start 174.081186 -242.500912)
		(end 173.319694 -242.500912)
		(width 0.18288)
		(layer "In4.Cu")
		(net "M_G_CPU1_SB_CB<4>")
	)
	(segment
		(start 135.792464 -244.412262)
		(end 135.789924 -244.410738)
		(width 0.088646)
		(layer "In4.Cu")
		(net "M_G_CPU1_SB_CB<4>")
	)
	(segment
		(start 163.940236 -242.51031)
		(end 163.757356 -242.69319)
		(width 0.18288)
		(layer "In4.Cu")
		(net "M_G_CPU1_SB_CB<4>")
	)
	(segment
		(start 170.372532 -242.498626)
		(end 169.816526 -241.94262)
		(width 0.18288)
		(layer "In4.Cu")
		(net "M_G_CPU1_SB_CB<4>")
	)
	(segment
		(start 179.99202 -241.327432)
		(end 179.017168 -242.302284)
		(width 0.18288)
		(layer "In4.Cu")
		(net "M_G_CPU1_SB_CB<4>")
	)
	(segment
		(start 163.246816 -242.249706)
		(end 163.063936 -242.066826)
		(width 0.18288)
		(layer "In4.Cu")
		(net "M_G_CPU1_SB_CB<4>")
	)
	(segment
		(start 186.39282 -242.1509)
		(end 185.292746 -241.050826)
		(width 0.18288)
		(layer "In4.Cu")
		(net "M_G_CPU1_SB_CB<4>")
	)
	(segment
		(start 179.017168 -242.302284)
		(end 177.666396 -242.302284)
		(width 0.18288)
		(layer "In4.Cu")
		(net "M_G_CPU1_SB_CB<4>")
	)
	(segment
		(start 181.396132 -242.669568)
		(end 181.212998 -242.486434)
		(width 0.18288)
		(layer "In4.Cu")
		(net "M_G_CPU1_SB_CB<4>")
	)
	(segment
		(start 173.028102 -242.792504)
		(end 172.561504 -242.792504)
		(width 0.18288)
		(layer "In4.Cu")
		(net "M_G_CPU1_SB_CB<4>")
	)
	(segment
		(start 167.977566 -241.688366)
		(end 165.229286 -241.688366)
		(width 0.18288)
		(layer "In4.Cu")
		(net "M_G_CPU1_SB_CB<4>")
	)
	(segment
		(start 140.288264 -244.036088)
		(end 139.051792 -244.036088)
		(width 0.088646)
		(layer "In4.Cu")
		(net "M_G_CPU1_SB_CB<4>")
	)
	(segment
		(start 162.221926 -242.066826)
		(end 162.098736 -241.943636)
		(width 0.18288)
		(layer "In4.Cu")
		(net "M_G_CPU1_SB_CB<4>")
	)
	(segment
		(start 182.892446 -241.266726)
		(end 182.093108 -241.266726)
		(width 0.18288)
		(layer "In4.Cu")
		(net "M_G_CPU1_SB_CB<4>")
	)
	(segment
		(start 140.315696 -244.047264)
		(end 140.29944 -244.047264)
		(width 0.088646)
		(layer "In4.Cu")
		(net "M_G_CPU1_SB_CB<4>")
	)
	(segment
		(start 139.051792 -244.036088)
		(end 138.726164 -244.361716)
		(width 0.088646)
		(layer "In4.Cu")
		(net "M_G_CPU1_SB_CB<4>")
	)
	(segment
		(start 182.093108 -241.266726)
		(end 181.933088 -241.426746)
		(width 0.18288)
		(layer "In4.Cu")
		(net "M_G_CPU1_SB_CB<4>")
	)
	(segment
		(start 183.7944 -241.960146)
		(end 183.611266 -242.14328)
		(width 0.18288)
		(layer "In4.Cu")
		(net "M_G_CPU1_SB_CB<4>")
	)
	(segment
		(start 185.292746 -241.050826)
		(end 184.013348 -241.050826)
		(width 0.18288)
		(layer "In4.Cu")
		(net "M_G_CPU1_SB_CB<4>")
	)
	(segment
		(start 183.7944 -241.269774)
		(end 183.7944 -241.960146)
		(width 0.18288)
		(layer "In4.Cu")
		(net "M_G_CPU1_SB_CB<4>")
	)
	(segment
		(start 187.249308 -242.1509)
		(end 186.39282 -242.1509)
		(width 0.18288)
		(layer "In4.Cu")
		(net "M_G_CPU1_SB_CB<4>")
	)
	(arc
		(start 131.658614 -244.412262)
		(mid 131.220072 -244.46613)
		(end 130.876802 -244.18798)
		(width 0.088646)
		(layer "In4.Cu")
		(net "M_G_CPU1_SB_CB<4>")
	)
	(arc
		(start 132.028692 -244.409722)
		(mid 131.843307 -244.362084)
		(end 131.658614 -244.412262)
		(width 0.088646)
		(layer "In4.Cu")
		(net "M_G_CPU1_SB_CB<4>")
	)
	(arc
		(start 134.478014 -244.412262)
		(mid 134.195456 -244.487911)
		(end 133.912864 -244.412262)
		(width 0.088646)
		(layer "In4.Cu")
		(net "M_G_CPU1_SB_CB<4>")
	)
	(arc
		(start 133.910324 -244.410738)
		(mid 133.724075 -244.362093)
		(end 133.538214 -244.412262)
		(width 0.088646)
		(layer "In4.Cu")
		(net "M_G_CPU1_SB_CB<4>")
	)
	(arc
		(start 136.357868 -244.412262)
		(mid 136.075166 -244.488038)
		(end 135.792464 -244.412262)
		(width 0.088646)
		(layer "In4.Cu")
		(net "M_G_CPU1_SB_CB<4>")
	)
	(arc
		(start 133.538214 -244.412262)
		(mid 133.259891 -244.488021)
		(end 132.98043 -244.41658)
		(width 0.088646)
		(layer "In4.Cu")
		(net "M_G_CPU1_SB_CB<4>")
	)
	(arc
		(start 137.672064 -244.412262)
		(mid 137.484866 -244.362119)
		(end 137.297668 -244.412262)
		(width 0.088646)
		(layer "In4.Cu")
		(net "M_G_CPU1_SB_CB<4>")
	)
	(arc
		(start 138.424666 -244.361716)
		(mid 138.327743 -244.374674)
		(end 138.237468 -244.412262)
		(width 0.088646)
		(layer "In4.Cu")
		(net "M_G_CPU1_SB_CB<4>")
	)
	(arc
		(start 136.732264 -244.412262)
		(mid 136.545066 -244.362119)
		(end 136.357868 -244.412262)
		(width 0.088646)
		(layer "In4.Cu")
		(net "M_G_CPU1_SB_CB<4>")
	)
	(arc
		(start 138.237468 -244.412262)
		(mid 137.954766 -244.488004)
		(end 137.672064 -244.412262)
		(width 0.088646)
		(layer "In4.Cu")
		(net "M_G_CPU1_SB_CB<4>")
	)
	(arc
		(start 137.297668 -244.412262)
		(mid 137.014966 -244.488038)
		(end 136.732264 -244.412262)
		(width 0.088646)
		(layer "In4.Cu")
		(net "M_G_CPU1_SB_CB<4>")
	)
	(arc
		(start 135.789924 -244.410738)
		(mid 135.603675 -244.362093)
		(end 135.417814 -244.412262)
		(width 0.088646)
		(layer "In4.Cu")
		(net "M_G_CPU1_SB_CB<4>")
	)
	(arc
		(start 132.598414 -244.412262)
		(mid 132.320091 -244.488021)
		(end 132.04063 -244.41658)
		(width 0.088646)
		(layer "In4.Cu")
		(net "M_G_CPU1_SB_CB<4>")
	)
	(arc
		(start 134.848854 -244.41023)
		(mid 134.663164 -244.362152)
		(end 134.478014 -244.412262)
		(width 0.088646)
		(layer "In4.Cu")
		(net "M_G_CPU1_SB_CB<4>")
	)
	(arc
		(start 135.417814 -244.412262)
		(mid 135.139491 -244.488021)
		(end 134.86003 -244.41658)
		(width 0.088646)
		(layer "In4.Cu")
		(net "M_G_CPU1_SB_CB<4>")
	)
	(arc
		(start 132.968492 -244.409722)
		(mid 132.783107 -244.362084)
		(end 132.598414 -244.412262)
		(width 0.088646)
		(layer "In4.Cu")
		(net "M_G_CPU1_SB_CB<4>")
	)
	(segment
		(start 198.427848 -233.241088)
		(end 198.427848 -232.943908)
		(width 0.20066)
		(layer "F.Cu")
		(net "M_G_CPU1_SB_CB<3>")
	)
	(segment
		(start 198.427848 -232.943908)
		(end 198.628508 -232.743248)
		(width 0.20066)
		(layer "F.Cu")
		(net "M_G_CPU1_SB_CB<3>")
	)
	(segment
		(start 195.343018 -233.441748)
		(end 195.522596 -233.441748)
		(width 0.101854)
		(layer "F.Cu")
		(net "M_G_CPU1_SB_CB<3>")
	)
	(segment
		(start 195.218812 -233.441748)
		(end 195.343018 -233.441748)
		(width 0.20066)
		(layer "F.Cu")
		(net "M_G_CPU1_SB_CB<3>")
	)
	(segment
		(start 197.530466 -233.441748)
		(end 197.834504 -233.441748)
		(width 0.101854)
		(layer "F.Cu")
		(net "M_G_CPU1_SB_CB<3>")
	)
	(segment
		(start 197.834504 -233.441748)
		(end 198.227188 -233.441748)
		(width 0.20066)
		(layer "F.Cu")
		(net "M_G_CPU1_SB_CB<3>")
	)
	(segment
		(start 199.024494 -232.743248)
		(end 199.298052 -233.016806)
		(width 0.20066)
		(layer "F.Cu")
		(net "M_G_CPU1_SB_CB<3>")
	)
	(segment
		(start 199.298052 -233.016806)
		(end 200.632314 -233.016806)
		(width 0.20066)
		(layer "F.Cu")
		(net "M_G_CPU1_SB_CB<3>")
	)
	(segment
		(start 198.227188 -233.441748)
		(end 198.427848 -233.241088)
		(width 0.20066)
		(layer "F.Cu")
		(net "M_G_CPU1_SB_CB<3>")
	)
	(segment
		(start 194.79387 -233.016806)
		(end 195.218812 -233.441748)
		(width 0.20066)
		(layer "F.Cu")
		(net "M_G_CPU1_SB_CB<3>")
	)
	(segment
		(start 131.375912 -241.203226)
		(end 131.376166 -241.202972)
		(width 0.20066)
		(layer "F.Cu")
		(net "M_G_CPU1_SB_CB<3>")
	)
	(segment
		(start 193.088514 -233.016806)
		(end 194.79387 -233.016806)
		(width 0.20066)
		(layer "F.Cu")
		(net "M_G_CPU1_SB_CB<3>")
	)
	(segment
		(start 195.522596 -233.441748)
		(end 197.530466 -233.441748)
		(width 0.1016)
		(layer "F.Cu")
		(net "M_G_CPU1_SB_CB<3>")
	)
	(segment
		(start 191.983614 -233.016806)
		(end 193.088514 -233.016806)
		(width 0.20066)
		(layer "F.Cu")
		(net "M_G_CPU1_SB_CB<3>")
	)
	(segment
		(start 198.628508 -232.743248)
		(end 199.024494 -232.743248)
		(width 0.20066)
		(layer "F.Cu")
		(net "M_G_CPU1_SB_CB<3>")
	)
	(segment
		(start 131.376166 -241.202972)
		(end 131.376166 -240.667286)
		(width 0.20066)
		(layer "F.Cu")
		(net "M_G_CPU1_SB_CB<3>")
	)
	(segment
		(start 174.30496 -231.742234)
		(end 173.45279 -232.594404)
		(width 0.18288)
		(layer "In4.Cu")
		(net "M_G_CPU1_SB_CB<3>")
	)
	(segment
		(start 131.37642 -240.667032)
		(end 131.376166 -240.667286)
		(width 0.088646)
		(layer "In4.Cu")
		(net "M_G_CPU1_SB_CB<3>")
	)
	(segment
		(start 132.973064 -240.177828)
		(end 132.967222 -240.18113)
		(width 0.088646)
		(layer "In4.Cu")
		(net "M_G_CPU1_SB_CB<3>")
	)
	(segment
		(start 189.404244 -232.59161)
		(end 186.38901 -232.59161)
		(width 0.18288)
		(layer "In4.Cu")
		(net "M_G_CPU1_SB_CB<3>")
	)
	(segment
		(start 184.86882 -232.437432)
		(end 184.599326 -232.706926)
		(width 0.18288)
		(layer "In4.Cu")
		(net "M_G_CPU1_SB_CB<3>")
	)
	(segment
		(start 162.326066 -232.893362)
		(end 162.326066 -233.247692)
		(width 0.18288)
		(layer "In4.Cu")
		(net "M_G_CPU1_SB_CB<3>")
	)
	(segment
		(start 191.537336 -232.867962)
		(end 190.327026 -232.440226)
		(width 0.18288)
		(layer "In4.Cu")
		(net "M_G_CPU1_SB_CB<3>")
	)
	(segment
		(start 136.357614 -240.177574)
		(end 136.357614 -240.177828)
		(width 0.088646)
		(layer "In4.Cu")
		(net "M_G_CPU1_SB_CB<3>")
	)
	(segment
		(start 134.852664 -240.177828)
		(end 134.848854 -240.17986)
		(width 0.088646)
		(layer "In4.Cu")
		(net "M_G_CPU1_SB_CB<3>")
	)
	(segment
		(start 164.960046 -233.430572)
		(end 163.202366 -233.430572)
		(width 0.18288)
		(layer "In4.Cu")
		(net "M_G_CPU1_SB_CB<3>")
	)
	(segment
		(start 140.315696 -239.30483)
		(end 140.202412 -239.30483)
		(width 0.088646)
		(layer "In4.Cu")
		(net "M_G_CPU1_SB_CB<3>")
	)
	(segment
		(start 178.820318 -231.742234)
		(end 174.30496 -231.742234)
		(width 0.18288)
		(layer "In4.Cu")
		(net "M_G_CPU1_SB_CB<3>")
	)
	(segment
		(start 173.45279 -232.594404)
		(end 172.522642 -232.594404)
		(width 0.18288)
		(layer "In4.Cu")
		(net "M_G_CPU1_SB_CB<3>")
	)
	(segment
		(start 132.978906 -240.174272)
		(end 132.973064 -240.177828)
		(width 0.088646)
		(layer "In4.Cu")
		(net "M_G_CPU1_SB_CB<3>")
	)
	(segment
		(start 135.792464 -240.177828)
		(end 135.788146 -240.180368)
		(width 0.088646)
		(layer "In4.Cu")
		(net "M_G_CPU1_SB_CB<3>")
	)
	(segment
		(start 179.696872 -231.550972)
		(end 179.01158 -231.550972)
		(width 0.18288)
		(layer "In4.Cu")
		(net "M_G_CPU1_SB_CB<3>")
	)
	(segment
		(start 183.248554 -231.830626)
		(end 179.976526 -231.830626)
		(width 0.18288)
		(layer "In4.Cu")
		(net "M_G_CPU1_SB_CB<3>")
	)
	(segment
		(start 153.069544 -233.68889)
		(end 149.97557 -236.782864)
		(width 0.18288)
		(layer "In4.Cu")
		(net "M_G_CPU1_SB_CB<3>")
	)
	(segment
		(start 133.912864 -240.177828)
		(end 133.908546 -240.180368)
		(width 0.088646)
		(layer "In4.Cu")
		(net "M_G_CPU1_SB_CB<3>")
	)
	(segment
		(start 184.599326 -232.706926)
		(end 184.124854 -232.706926)
		(width 0.18288)
		(layer "In4.Cu")
		(net "M_G_CPU1_SB_CB<3>")
	)
	(segment
		(start 191.983614 -233.016806)
		(end 191.537336 -232.867962)
		(width 0.18288)
		(layer "In4.Cu")
		(net "M_G_CPU1_SB_CB<3>")
	)
	(segment
		(start 165.058852 -233.529378)
		(end 164.960046 -233.430572)
		(width 0.18288)
		(layer "In4.Cu")
		(net "M_G_CPU1_SB_CB<3>")
	)
	(segment
		(start 149.97557 -236.782864)
		(end 145.50898 -236.782864)
		(width 0.18288)
		(layer "In4.Cu")
		(net "M_G_CPU1_SB_CB<3>")
	)
	(segment
		(start 163.202366 -233.430572)
		(end 163.019486 -233.247692)
		(width 0.18288)
		(layer "In4.Cu")
		(net "M_G_CPU1_SB_CB<3>")
	)
	(segment
		(start 160.427162 -233.68889)
		(end 153.069544 -233.68889)
		(width 0.18288)
		(layer "In4.Cu")
		(net "M_G_CPU1_SB_CB<3>")
	)
	(segment
		(start 145.50898 -236.782864)
		(end 142.987014 -239.30483)
		(width 0.18288)
		(layer "In4.Cu")
		(net "M_G_CPU1_SB_CB<3>")
	)
	(segment
		(start 162.143186 -233.430572)
		(end 160.68548 -233.430572)
		(width 0.18288)
		(layer "In4.Cu")
		(net "M_G_CPU1_SB_CB<3>")
	)
	(segment
		(start 172.522642 -232.594404)
		(end 172.183044 -232.934002)
		(width 0.18288)
		(layer "In4.Cu")
		(net "M_G_CPU1_SB_CB<3>")
	)
	(segment
		(start 142.987014 -239.30483)
		(end 140.315696 -239.30483)
		(width 0.18288)
		(layer "In4.Cu")
		(net "M_G_CPU1_SB_CB<3>")
	)
	(segment
		(start 169.259758 -232.934002)
		(end 168.664382 -233.529378)
		(width 0.18288)
		(layer "In4.Cu")
		(net "M_G_CPU1_SB_CB<3>")
	)
	(segment
		(start 134.858506 -240.174272)
		(end 134.852664 -240.177828)
		(width 0.088646)
		(layer "In4.Cu")
		(net "M_G_CPU1_SB_CB<3>")
	)
	(segment
		(start 162.508946 -232.710482)
		(end 162.326066 -232.893362)
		(width 0.18288)
		(layer "In4.Cu")
		(net "M_G_CPU1_SB_CB<3>")
	)
	(segment
		(start 189.555628 -232.440226)
		(end 189.404244 -232.59161)
		(width 0.18288)
		(layer "In4.Cu")
		(net "M_G_CPU1_SB_CB<3>")
	)
	(segment
		(start 179.01158 -231.550972)
		(end 178.820318 -231.742234)
		(width 0.18288)
		(layer "In4.Cu")
		(net "M_G_CPU1_SB_CB<3>")
	)
	(segment
		(start 184.124854 -232.706926)
		(end 183.248554 -231.830626)
		(width 0.18288)
		(layer "In4.Cu")
		(net "M_G_CPU1_SB_CB<3>")
	)
	(segment
		(start 137.297414 -240.177574)
		(end 137.282682 -240.168938)
		(width 0.088646)
		(layer "In4.Cu")
		(net "M_G_CPU1_SB_CB<3>")
	)
	(segment
		(start 139.580874 -240.185702)
		(end 139.450572 -240.217706)
		(width 0.088646)
		(layer "In4.Cu")
		(net "M_G_CPU1_SB_CB<3>")
	)
	(segment
		(start 139.853416 -239.653826)
		(end 139.853416 -239.91316)
		(width 0.088646)
		(layer "In4.Cu")
		(net "M_G_CPU1_SB_CB<3>")
	)
	(segment
		(start 139.177014 -240.177574)
		(end 139.162282 -240.168938)
		(width 0.088646)
		(layer "In4.Cu")
		(net "M_G_CPU1_SB_CB<3>")
	)
	(segment
		(start 162.326066 -233.247692)
		(end 162.143186 -233.430572)
		(width 0.18288)
		(layer "In4.Cu")
		(net "M_G_CPU1_SB_CB<3>")
	)
	(segment
		(start 139.853416 -239.91316)
		(end 139.580874 -240.185702)
		(width 0.088646)
		(layer "In4.Cu")
		(net "M_G_CPU1_SB_CB<3>")
	)
	(segment
		(start 138.237214 -240.177574)
		(end 138.222482 -240.168938)
		(width 0.088646)
		(layer "In4.Cu")
		(net "M_G_CPU1_SB_CB<3>")
	)
	(segment
		(start 186.234832 -232.437432)
		(end 184.86882 -232.437432)
		(width 0.18288)
		(layer "In4.Cu")
		(net "M_G_CPU1_SB_CB<3>")
	)
	(segment
		(start 186.38901 -232.59161)
		(end 186.234832 -232.437432)
		(width 0.18288)
		(layer "In4.Cu")
		(net "M_G_CPU1_SB_CB<3>")
	)
	(segment
		(start 140.202412 -239.30483)
		(end 139.853416 -239.653826)
		(width 0.088646)
		(layer "In4.Cu")
		(net "M_G_CPU1_SB_CB<3>")
	)
	(segment
		(start 163.019486 -233.247692)
		(end 163.019486 -232.893362)
		(width 0.18288)
		(layer "In4.Cu")
		(net "M_G_CPU1_SB_CB<3>")
	)
	(segment
		(start 190.327026 -232.440226)
		(end 189.555628 -232.440226)
		(width 0.18288)
		(layer "In4.Cu")
		(net "M_G_CPU1_SB_CB<3>")
	)
	(segment
		(start 132.039106 -240.174272)
		(end 131.934458 -240.23574)
		(width 0.088646)
		(layer "In4.Cu")
		(net "M_G_CPU1_SB_CB<3>")
	)
	(segment
		(start 168.664382 -233.529378)
		(end 165.058852 -233.529378)
		(width 0.18288)
		(layer "In4.Cu")
		(net "M_G_CPU1_SB_CB<3>")
	)
	(segment
		(start 160.68548 -233.430572)
		(end 160.427162 -233.68889)
		(width 0.18288)
		(layer "In4.Cu")
		(net "M_G_CPU1_SB_CB<3>")
	)
	(segment
		(start 162.836606 -232.710482)
		(end 162.508946 -232.710482)
		(width 0.18288)
		(layer "In4.Cu")
		(net "M_G_CPU1_SB_CB<3>")
	)
	(segment
		(start 163.019486 -232.893362)
		(end 162.836606 -232.710482)
		(width 0.18288)
		(layer "In4.Cu")
		(net "M_G_CPU1_SB_CB<3>")
	)
	(segment
		(start 179.976526 -231.830626)
		(end 179.696872 -231.550972)
		(width 0.18288)
		(layer "In4.Cu")
		(net "M_G_CPU1_SB_CB<3>")
	)
	(segment
		(start 172.183044 -232.934002)
		(end 169.259758 -232.934002)
		(width 0.18288)
		(layer "In4.Cu")
		(net "M_G_CPU1_SB_CB<3>")
	)
	(arc
		(start 133.538214 -240.177828)
		(mid 133.25904 -240.102063)
		(end 132.978906 -240.174272)
		(width 0.088646)
		(layer "In4.Cu")
		(net "M_G_CPU1_SB_CB<3>")
	)
	(arc
		(start 135.417814 -240.177828)
		(mid 135.13864 -240.102063)
		(end 134.858506 -240.174272)
		(width 0.088646)
		(layer "In4.Cu")
		(net "M_G_CPU1_SB_CB<3>")
	)
	(arc
		(start 134.848854 -240.17986)
		(mid 134.663164 -240.227938)
		(end 134.478014 -240.177828)
		(width 0.088646)
		(layer "In4.Cu")
		(net "M_G_CPU1_SB_CB<3>")
	)
	(arc
		(start 136.357614 -240.177828)
		(mid 136.075056 -240.102179)
		(end 135.792464 -240.177828)
		(width 0.088646)
		(layer "In4.Cu")
		(net "M_G_CPU1_SB_CB<3>")
	)
	(arc
		(start 139.162282 -240.168938)
		(mid 138.885841 -240.101772)
		(end 138.61161 -240.177574)
		(width 0.088646)
		(layer "In4.Cu")
		(net "M_G_CPU1_SB_CB<3>")
	)
	(arc
		(start 131.934458 -240.23574)
		(mid 131.641675 -240.433577)
		(end 131.37642 -240.667032)
		(width 0.088646)
		(layer "In4.Cu")
		(net "M_G_CPU1_SB_CB<3>")
	)
	(arc
		(start 135.788146 -240.180368)
		(mid 135.602651 -240.228037)
		(end 135.417814 -240.177828)
		(width 0.088646)
		(layer "In4.Cu")
		(net "M_G_CPU1_SB_CB<3>")
	)
	(arc
		(start 132.967222 -240.18113)
		(mid 132.782367 -240.22808)
		(end 132.598414 -240.177828)
		(width 0.088646)
		(layer "In4.Cu")
		(net "M_G_CPU1_SB_CB<3>")
	)
	(arc
		(start 139.450572 -240.217706)
		(mid 139.309941 -240.223845)
		(end 139.177014 -240.177574)
		(width 0.088646)
		(layer "In4.Cu")
		(net "M_G_CPU1_SB_CB<3>")
	)
	(arc
		(start 137.282682 -240.168938)
		(mid 137.006241 -240.101772)
		(end 136.73201 -240.177574)
		(width 0.088646)
		(layer "In4.Cu")
		(net "M_G_CPU1_SB_CB<3>")
	)
	(arc
		(start 138.61161 -240.177574)
		(mid 138.424412 -240.227717)
		(end 138.237214 -240.177574)
		(width 0.088646)
		(layer "In4.Cu")
		(net "M_G_CPU1_SB_CB<3>")
	)
	(arc
		(start 137.67181 -240.177574)
		(mid 137.484612 -240.227717)
		(end 137.297414 -240.177574)
		(width 0.088646)
		(layer "In4.Cu")
		(net "M_G_CPU1_SB_CB<3>")
	)
	(arc
		(start 133.908546 -240.180368)
		(mid 133.723051 -240.228037)
		(end 133.538214 -240.177828)
		(width 0.088646)
		(layer "In4.Cu")
		(net "M_G_CPU1_SB_CB<3>")
	)
	(arc
		(start 132.598414 -240.177828)
		(mid 132.31924 -240.102063)
		(end 132.039106 -240.174272)
		(width 0.088646)
		(layer "In4.Cu")
		(net "M_G_CPU1_SB_CB<3>")
	)
	(arc
		(start 134.478014 -240.177828)
		(mid 134.195456 -240.102179)
		(end 133.912864 -240.177828)
		(width 0.088646)
		(layer "In4.Cu")
		(net "M_G_CPU1_SB_CB<3>")
	)
	(arc
		(start 136.73201 -240.177574)
		(mid 136.544812 -240.227717)
		(end 136.357614 -240.177574)
		(width 0.088646)
		(layer "In4.Cu")
		(net "M_G_CPU1_SB_CB<3>")
	)
	(arc
		(start 138.222482 -240.168938)
		(mid 137.946041 -240.101772)
		(end 137.67181 -240.177574)
		(width 0.088646)
		(layer "In4.Cu")
		(net "M_G_CPU1_SB_CB<3>")
	)
	(segment
		(start 195.522596 -235.141516)
		(end 197.48881 -235.141516)
		(width 0.1016)
		(layer "F.Cu")
		(net "M_G_CPU1_SB_CB<2>")
	)
	(segment
		(start 198.628508 -234.42168)
		(end 199.003158 -234.42168)
		(width 0.20066)
		(layer "F.Cu")
		(net "M_G_CPU1_SB_CB<2>")
	)
	(segment
		(start 131.845812 -242.016788)
		(end 131.845812 -241.481102)
		(width 0.20066)
		(layer "F.Cu")
		(net "M_G_CPU1_SB_CB<2>")
	)
	(segment
		(start 198.427848 -234.62234)
		(end 198.628508 -234.42168)
		(width 0.20066)
		(layer "F.Cu")
		(net "M_G_CPU1_SB_CB<2>")
	)
	(segment
		(start 131.846066 -242.017042)
		(end 131.845812 -242.016788)
		(width 0.20066)
		(layer "F.Cu")
		(net "M_G_CPU1_SB_CB<2>")
	)
	(segment
		(start 193.088514 -234.716574)
		(end 194.685158 -234.716574)
		(width 0.20066)
		(layer "F.Cu")
		(net "M_G_CPU1_SB_CB<2>")
	)
	(segment
		(start 195.1101 -235.141516)
		(end 195.343018 -235.141516)
		(width 0.20066)
		(layer "F.Cu")
		(net "M_G_CPU1_SB_CB<2>")
	)
	(segment
		(start 199.298052 -234.716574)
		(end 200.632314 -234.716574)
		(width 0.20066)
		(layer "F.Cu")
		(net "M_G_CPU1_SB_CB<2>")
	)
	(segment
		(start 199.003158 -234.42168)
		(end 199.298052 -234.716574)
		(width 0.20066)
		(layer "F.Cu")
		(net "M_G_CPU1_SB_CB<2>")
	)
	(segment
		(start 191.983614 -234.716574)
		(end 193.088514 -234.716574)
		(width 0.20066)
		(layer "F.Cu")
		(net "M_G_CPU1_SB_CB<2>")
	)
	(segment
		(start 198.427848 -234.940856)
		(end 198.427848 -234.62234)
		(width 0.20066)
		(layer "F.Cu")
		(net "M_G_CPU1_SB_CB<2>")
	)
	(segment
		(start 195.343018 -235.141516)
		(end 195.522596 -235.141516)
		(width 0.101854)
		(layer "F.Cu")
		(net "M_G_CPU1_SB_CB<2>")
	)
	(segment
		(start 197.48881 -235.141516)
		(end 197.834504 -235.141516)
		(width 0.101854)
		(layer "F.Cu")
		(net "M_G_CPU1_SB_CB<2>")
	)
	(segment
		(start 197.834504 -235.141516)
		(end 198.227188 -235.141516)
		(width 0.20066)
		(layer "F.Cu")
		(net "M_G_CPU1_SB_CB<2>")
	)
	(segment
		(start 198.227188 -235.141516)
		(end 198.427848 -234.940856)
		(width 0.20066)
		(layer "F.Cu")
		(net "M_G_CPU1_SB_CB<2>")
	)
	(segment
		(start 194.685158 -234.716574)
		(end 195.1101 -235.141516)
		(width 0.20066)
		(layer "F.Cu")
		(net "M_G_CPU1_SB_CB<2>")
	)
	(segment
		(start 186.097418 -234.291632)
		(end 185.993024 -234.396026)
		(width 0.18288)
		(layer "In4.Cu")
		(net "M_G_CPU1_SB_CB<2>")
	)
	(segment
		(start 191.983614 -234.716574)
		(end 190.989204 -233.722164)
		(width 0.18288)
		(layer "In4.Cu")
		(net "M_G_CPU1_SB_CB<2>")
	)
	(segment
		(start 179.697126 -233.278426)
		(end 179.003198 -233.278426)
		(width 0.18288)
		(layer "In4.Cu")
		(net "M_G_CPU1_SB_CB<2>")
	)
	(segment
		(start 157.785562 -235.233972)
		(end 152.932638 -235.233972)
		(width 0.18288)
		(layer "In4.Cu")
		(net "M_G_CPU1_SB_CB<2>")
	)
	(segment
		(start 140.069824 -240.30051)
		(end 139.746736 -240.623598)
		(width 0.088646)
		(layer "In4.Cu")
		(net "M_G_CPU1_SB_CB<2>")
	)
	(segment
		(start 145.921476 -237.778544)
		(end 143.39951 -240.30051)
		(width 0.18288)
		(layer "In4.Cu")
		(net "M_G_CPU1_SB_CB<2>")
	)
	(segment
		(start 173.603158 -234.292394)
		(end 170.725338 -234.292394)
		(width 0.18288)
		(layer "In4.Cu")
		(net "M_G_CPU1_SB_CB<2>")
	)
	(segment
		(start 158.655512 -235.051346)
		(end 158.472632 -235.234226)
		(width 0.18288)
		(layer "In4.Cu")
		(net "M_G_CPU1_SB_CB<2>")
	)
	(segment
		(start 174.453042 -233.44251)
		(end 173.603158 -234.292394)
		(width 0.18288)
		(layer "In4.Cu")
		(net "M_G_CPU1_SB_CB<2>")
	)
	(segment
		(start 158.838392 -234.69727)
		(end 158.655512 -234.88015)
		(width 0.18288)
		(layer "In4.Cu")
		(net "M_G_CPU1_SB_CB<2>")
	)
	(segment
		(start 168.364916 -235.174536)
		(end 165.054534 -235.174536)
		(width 0.18288)
		(layer "In4.Cu")
		(net "M_G_CPU1_SB_CB<2>")
	)
	(segment
		(start 179.003198 -233.278426)
		(end 178.5112 -233.770424)
		(width 0.18288)
		(layer "In4.Cu")
		(net "M_G_CPU1_SB_CB<2>")
	)
	(segment
		(start 190.989204 -233.722164)
		(end 190.416688 -233.722164)
		(width 0.18288)
		(layer "In4.Cu")
		(net "M_G_CPU1_SB_CB<2>")
	)
	(segment
		(start 138.608562 -240.915952)
		(end 138.424412 -240.915952)
		(width 0.088646)
		(layer "In4.Cu")
		(net "M_G_CPU1_SB_CB<2>")
	)
	(segment
		(start 183.814974 -234.396026)
		(end 182.925974 -233.507026)
		(width 0.18288)
		(layer "In4.Cu")
		(net "M_G_CPU1_SB_CB<2>")
	)
	(segment
		(start 132.503164 -240.991644)
		(end 132.423154 -241.037872)
		(width 0.088646)
		(layer "In4.Cu")
		(net "M_G_CPU1_SB_CB<2>")
	)
	(segment
		(start 158.655512 -234.88015)
		(end 158.655512 -235.051346)
		(width 0.18288)
		(layer "In4.Cu")
		(net "M_G_CPU1_SB_CB<2>")
	)
	(segment
		(start 178.5112 -233.770424)
		(end 177.847244 -233.770424)
		(width 0.18288)
		(layer "In4.Cu")
		(net "M_G_CPU1_SB_CB<2>")
	)
	(segment
		(start 159.531812 -235.234226)
		(end 159.348932 -235.051346)
		(width 0.18288)
		(layer "In4.Cu")
		(net "M_G_CPU1_SB_CB<2>")
	)
	(segment
		(start 159.166052 -234.69727)
		(end 158.838392 -234.69727)
		(width 0.18288)
		(layer "In4.Cu")
		(net "M_G_CPU1_SB_CB<2>")
	)
	(segment
		(start 139.746736 -240.623598)
		(end 139.170156 -240.623598)
		(width 0.088646)
		(layer "In4.Cu")
		(net "M_G_CPU1_SB_CB<2>")
	)
	(segment
		(start 159.348932 -235.051346)
		(end 159.348932 -234.88015)
		(width 0.18288)
		(layer "In4.Cu")
		(net "M_G_CPU1_SB_CB<2>")
	)
	(segment
		(start 177.51933 -233.44251)
		(end 174.453042 -233.44251)
		(width 0.18288)
		(layer "In4.Cu")
		(net "M_G_CPU1_SB_CB<2>")
	)
	(segment
		(start 134.953756 -240.994946)
		(end 134.943342 -240.989104)
		(width 0.088646)
		(layer "In4.Cu")
		(net "M_G_CPU1_SB_CB<2>")
	)
	(segment
		(start 158.472632 -235.234226)
		(end 157.785816 -235.234226)
		(width 0.18288)
		(layer "In4.Cu")
		(net "M_G_CPU1_SB_CB<2>")
	)
	(segment
		(start 188.022992 -234.292648)
		(end 188.021976 -234.291632)
		(width 0.18288)
		(layer "In4.Cu")
		(net "M_G_CPU1_SB_CB<2>")
	)
	(segment
		(start 182.925974 -233.507026)
		(end 179.925726 -233.507026)
		(width 0.18288)
		(layer "In4.Cu")
		(net "M_G_CPU1_SB_CB<2>")
	)
	(segment
		(start 165.054534 -235.174536)
		(end 164.749226 -234.869228)
		(width 0.18288)
		(layer "In4.Cu")
		(net "M_G_CPU1_SB_CB<2>")
	)
	(segment
		(start 139.170156 -240.623598)
		(end 138.854434 -240.757964)
		(width 0.088646)
		(layer "In4.Cu")
		(net "M_G_CPU1_SB_CB<2>")
	)
	(segment
		(start 170.20286 -234.814872)
		(end 168.72458 -234.814872)
		(width 0.18288)
		(layer "In4.Cu")
		(net "M_G_CPU1_SB_CB<2>")
	)
	(segment
		(start 157.785816 -235.234226)
		(end 157.785562 -235.233972)
		(width 0.18288)
		(layer "In4.Cu")
		(net "M_G_CPU1_SB_CB<2>")
	)
	(segment
		(start 138.854434 -240.757964)
		(end 138.608562 -240.915952)
		(width 0.088646)
		(layer "In4.Cu")
		(net "M_G_CPU1_SB_CB<2>")
	)
	(segment
		(start 177.847244 -233.770424)
		(end 177.51933 -233.44251)
		(width 0.18288)
		(layer "In4.Cu")
		(net "M_G_CPU1_SB_CB<2>")
	)
	(segment
		(start 159.348932 -234.88015)
		(end 159.166052 -234.69727)
		(width 0.18288)
		(layer "In4.Cu")
		(net "M_G_CPU1_SB_CB<2>")
	)
	(segment
		(start 170.725338 -234.292394)
		(end 170.20286 -234.814872)
		(width 0.18288)
		(layer "In4.Cu")
		(net "M_G_CPU1_SB_CB<2>")
	)
	(segment
		(start 161.558224 -234.869228)
		(end 161.193226 -235.234226)
		(width 0.18288)
		(layer "In4.Cu")
		(net "M_G_CPU1_SB_CB<2>")
	)
	(segment
		(start 188.021976 -234.291632)
		(end 186.097418 -234.291632)
		(width 0.18288)
		(layer "In4.Cu")
		(net "M_G_CPU1_SB_CB<2>")
	)
	(segment
		(start 134.008114 -240.991644)
		(end 134.004558 -240.989612)
		(width 0.088646)
		(layer "In4.Cu")
		(net "M_G_CPU1_SB_CB<2>")
	)
	(segment
		(start 150.388066 -237.778544)
		(end 145.921476 -237.778544)
		(width 0.18288)
		(layer "In4.Cu")
		(net "M_G_CPU1_SB_CB<2>")
	)
	(segment
		(start 133.074156 -240.994946)
		(end 133.062472 -240.988342)
		(width 0.088646)
		(layer "In4.Cu")
		(net "M_G_CPU1_SB_CB<2>")
	)
	(segment
		(start 140.315696 -240.30051)
		(end 140.069824 -240.30051)
		(width 0.088646)
		(layer "In4.Cu")
		(net "M_G_CPU1_SB_CB<2>")
	)
	(segment
		(start 161.193226 -235.234226)
		(end 159.531812 -235.234226)
		(width 0.18288)
		(layer "In4.Cu")
		(net "M_G_CPU1_SB_CB<2>")
	)
	(segment
		(start 135.887968 -240.991644)
		(end 135.884158 -240.989612)
		(width 0.088646)
		(layer "In4.Cu")
		(net "M_G_CPU1_SB_CB<2>")
	)
	(segment
		(start 189.846204 -234.292648)
		(end 188.022992 -234.292648)
		(width 0.18288)
		(layer "In4.Cu")
		(net "M_G_CPU1_SB_CB<2>")
	)
	(segment
		(start 179.925726 -233.507026)
		(end 179.697126 -233.278426)
		(width 0.18288)
		(layer "In4.Cu")
		(net "M_G_CPU1_SB_CB<2>")
	)
	(segment
		(start 152.932638 -235.233972)
		(end 150.388066 -237.778544)
		(width 0.18288)
		(layer "In4.Cu")
		(net "M_G_CPU1_SB_CB<2>")
	)
	(segment
		(start 143.39951 -240.30051)
		(end 140.315696 -240.30051)
		(width 0.18288)
		(layer "In4.Cu")
		(net "M_G_CPU1_SB_CB<2>")
	)
	(segment
		(start 185.993024 -234.396026)
		(end 183.814974 -234.396026)
		(width 0.18288)
		(layer "In4.Cu")
		(net "M_G_CPU1_SB_CB<2>")
	)
	(segment
		(start 168.72458 -234.814872)
		(end 168.364916 -235.174536)
		(width 0.18288)
		(layer "In4.Cu")
		(net "M_G_CPU1_SB_CB<2>")
	)
	(segment
		(start 190.416688 -233.722164)
		(end 189.846204 -234.292648)
		(width 0.18288)
		(layer "In4.Cu")
		(net "M_G_CPU1_SB_CB<2>")
	)
	(segment
		(start 164.749226 -234.869228)
		(end 161.558224 -234.869228)
		(width 0.18288)
		(layer "In4.Cu")
		(net "M_G_CPU1_SB_CB<2>")
	)
	(arc
		(start 137.202164 -240.991644)
		(mid 137.014966 -241.041787)
		(end 136.827768 -240.991644)
		(width 0.088646)
		(layer "In4.Cu")
		(net "M_G_CPU1_SB_CB<2>")
	)
	(arc
		(start 137.767568 -240.991644)
		(mid 137.484866 -240.915868)
		(end 137.202164 -240.991644)
		(width 0.088646)
		(layer "In4.Cu")
		(net "M_G_CPU1_SB_CB<2>")
	)
	(arc
		(start 133.062472 -240.988342)
		(mid 132.782367 -240.9159)
		(end 132.503164 -240.991644)
		(width 0.088646)
		(layer "In4.Cu")
		(net "M_G_CPU1_SB_CB<2>")
	)
	(arc
		(start 135.884158 -240.989612)
		(mid 135.603074 -240.915875)
		(end 135.322564 -240.991644)
		(width 0.088646)
		(layer "In4.Cu")
		(net "M_G_CPU1_SB_CB<2>")
	)
	(arc
		(start 138.141964 -240.991644)
		(mid 137.954766 -241.041787)
		(end 137.767568 -240.991644)
		(width 0.088646)
		(layer "In4.Cu")
		(net "M_G_CPU1_SB_CB<2>")
	)
	(arc
		(start 135.322564 -240.991644)
		(mid 135.13861 -241.041773)
		(end 134.953756 -240.994946)
		(width 0.088646)
		(layer "In4.Cu")
		(net "M_G_CPU1_SB_CB<2>")
	)
	(arc
		(start 136.262364 -240.991644)
		(mid 136.075166 -241.041787)
		(end 135.887968 -240.991644)
		(width 0.088646)
		(layer "In4.Cu")
		(net "M_G_CPU1_SB_CB<2>")
	)
	(arc
		(start 138.424412 -240.915952)
		(mid 138.278199 -240.935193)
		(end 138.141964 -240.991644)
		(width 0.088646)
		(layer "In4.Cu")
		(net "M_G_CPU1_SB_CB<2>")
	)
	(arc
		(start 134.943342 -240.989104)
		(mid 134.662707 -240.915936)
		(end 134.382764 -240.991644)
		(width 0.088646)
		(layer "In4.Cu")
		(net "M_G_CPU1_SB_CB<2>")
	)
	(arc
		(start 133.442964 -240.991644)
		(mid 133.25901 -241.041773)
		(end 133.074156 -240.994946)
		(width 0.088646)
		(layer "In4.Cu")
		(net "M_G_CPU1_SB_CB<2>")
	)
	(arc
		(start 134.382764 -240.991644)
		(mid 134.195456 -241.041787)
		(end 134.008114 -240.991644)
		(width 0.088646)
		(layer "In4.Cu")
		(net "M_G_CPU1_SB_CB<2>")
	)
	(arc
		(start 136.827768 -240.991644)
		(mid 136.545066 -240.915868)
		(end 136.262364 -240.991644)
		(width 0.088646)
		(layer "In4.Cu")
		(net "M_G_CPU1_SB_CB<2>")
	)
	(arc
		(start 132.423154 -241.037872)
		(mid 132.11999 -241.240607)
		(end 131.845812 -241.481102)
		(width 0.088646)
		(layer "In4.Cu")
		(net "M_G_CPU1_SB_CB<2>")
	)
	(arc
		(start 134.004558 -240.989612)
		(mid 133.723474 -240.915875)
		(end 133.442964 -240.991644)
		(width 0.088646)
		(layer "In4.Cu")
		(net "M_G_CPU1_SB_CB<2>")
	)
	(segment
		(start 196.531992 -233.866944)
		(end 194.901312 -233.866944)
		(width 0.20066)
		(layer "F.Cu")
		(net "M_G_CPU1_SB_CB<1>")
	)
	(segment
		(start 194.476116 -233.441748)
		(end 194.277742 -233.441748)
		(width 0.20066)
		(layer "F.Cu")
		(net "M_G_CPU1_SB_CB<1>")
	)
	(segment
		(start 191.786256 -233.441748)
		(end 191.539114 -233.441748)
		(width 0.20066)
		(layer "F.Cu")
		(net "M_G_CPU1_SB_CB<1>")
	)
	(segment
		(start 191.421004 -233.927396)
		(end 191.233044 -234.115356)
		(width 0.20066)
		(layer "F.Cu")
		(net "M_G_CPU1_SB_CB<1>")
	)
	(segment
		(start 130.436366 -241.202972)
		(end 130.436366 -240.667286)
		(width 0.20066)
		(layer "F.Cu")
		(net "M_G_CPU1_SB_CB<1>")
	)
	(segment
		(start 191.930782 -233.441748)
		(end 191.786256 -233.441748)
		(width 0.101854)
		(layer "F.Cu")
		(net "M_G_CPU1_SB_CB<1>")
	)
	(segment
		(start 191.233044 -234.115356)
		(end 190.75781 -234.115356)
		(width 0.20066)
		(layer "F.Cu")
		(net "M_G_CPU1_SB_CB<1>")
	)
	(segment
		(start 130.436112 -241.203226)
		(end 130.436366 -241.202972)
		(width 0.20066)
		(layer "F.Cu")
		(net "M_G_CPU1_SB_CB<1>")
	)
	(segment
		(start 188.988446 -233.86669)
		(end 187.883546 -233.86669)
		(width 0.20066)
		(layer "F.Cu")
		(net "M_G_CPU1_SB_CB<1>")
	)
	(segment
		(start 190.509144 -233.86669)
		(end 188.988446 -233.86669)
		(width 0.20066)
		(layer "F.Cu")
		(net "M_G_CPU1_SB_CB<1>")
	)
	(segment
		(start 191.539114 -233.441748)
		(end 191.421004 -233.559858)
		(width 0.20066)
		(layer "F.Cu")
		(net "M_G_CPU1_SB_CB<1>")
	)
	(segment
		(start 191.421004 -233.559858)
		(end 191.421004 -233.927396)
		(width 0.20066)
		(layer "F.Cu")
		(net "M_G_CPU1_SB_CB<1>")
	)
	(segment
		(start 194.277742 -233.441748)
		(end 194.241166 -233.441748)
		(width 0.101854)
		(layer "F.Cu")
		(net "M_G_CPU1_SB_CB<1>")
	)
	(segment
		(start 196.532246 -233.86669)
		(end 196.531992 -233.866944)
		(width 0.20066)
		(layer "F.Cu")
		(net "M_G_CPU1_SB_CB<1>")
	)
	(segment
		(start 194.241166 -233.441748)
		(end 191.930782 -233.441748)
		(width 0.1016)
		(layer "F.Cu")
		(net "M_G_CPU1_SB_CB<1>")
	)
	(segment
		(start 194.901312 -233.866944)
		(end 194.476116 -233.441748)
		(width 0.20066)
		(layer "F.Cu")
		(net "M_G_CPU1_SB_CB<1>")
	)
	(segment
		(start 190.75781 -234.115356)
		(end 190.509144 -233.86669)
		(width 0.20066)
		(layer "F.Cu")
		(net "M_G_CPU1_SB_CB<1>")
	)
	(segment
		(start 154.587194 -234.375706)
		(end 154.404314 -234.192826)
		(width 0.18288)
		(layer "In4.Cu")
		(net "M_G_CPU1_SB_CB<1>")
	)
	(segment
		(start 164.444426 -234.370626)
		(end 160.939226 -234.370626)
		(width 0.18288)
		(layer "In4.Cu")
		(net "M_G_CPU1_SB_CB<1>")
	)
	(segment
		(start 153.269696 -234.192826)
		(end 150.181818 -237.280704)
		(width 0.18288)
		(layer "In4.Cu")
		(net "M_G_CPU1_SB_CB<1>")
	)
	(segment
		(start 160.939226 -234.370626)
		(end 160.761426 -234.192826)
		(width 0.18288)
		(layer "In4.Cu")
		(net "M_G_CPU1_SB_CB<1>")
	)
	(segment
		(start 132.128514 -240.342928)
		(end 132.123434 -240.345722)
		(width 0.088646)
		(layer "In4.Cu")
		(net "M_G_CPU1_SB_CB<1>")
	)
	(segment
		(start 134.953756 -240.339372)
		(end 134.947914 -240.342928)
		(width 0.088646)
		(layer "In4.Cu")
		(net "M_G_CPU1_SB_CB<1>")
	)
	(segment
		(start 168.45534 -234.19943)
		(end 167.094154 -234.19943)
		(width 0.18288)
		(layer "In4.Cu")
		(net "M_G_CPU1_SB_CB<1>")
	)
	(segment
		(start 187.452508 -233.435652)
		(end 185.904124 -233.435652)
		(width 0.18288)
		(layer "In4.Cu")
		(net "M_G_CPU1_SB_CB<1>")
	)
	(segment
		(start 187.883546 -233.86669)
		(end 187.452508 -233.435652)
		(width 0.18288)
		(layer "In4.Cu")
		(net "M_G_CPU1_SB_CB<1>")
	)
	(segment
		(start 165.904926 -234.269026)
		(end 165.466776 -234.269026)
		(width 0.18288)
		(layer "In4.Cu")
		(net "M_G_CPU1_SB_CB<1>")
	)
	(segment
		(start 181.298342 -232.594658)
		(end 181.138322 -232.434638)
		(width 0.18288)
		(layer "In4.Cu")
		(net "M_G_CPU1_SB_CB<1>")
	)
	(segment
		(start 178.268884 -233.085132)
		(end 177.895504 -233.085132)
		(width 0.18288)
		(layer "In4.Cu")
		(net "M_G_CPU1_SB_CB<1>")
	)
	(segment
		(start 155.280614 -234.54868)
		(end 155.097734 -234.73156)
		(width 0.18288)
		(layer "In4.Cu")
		(net "M_G_CPU1_SB_CB<1>")
	)
	(segment
		(start 136.277096 -240.351564)
		(end 136.262364 -240.342928)
		(width 0.088646)
		(layer "In4.Cu")
		(net "M_G_CPU1_SB_CB<1>")
	)
	(segment
		(start 178.588924 -232.648252)
		(end 178.428904 -232.808272)
		(width 0.18288)
		(layer "In4.Cu")
		(net "M_G_CPU1_SB_CB<1>")
	)
	(segment
		(start 154.770074 -234.73156)
		(end 154.587194 -234.54868)
		(width 0.18288)
		(layer "In4.Cu")
		(net "M_G_CPU1_SB_CB<1>")
	)
	(segment
		(start 155.463494 -234.192826)
		(end 155.280614 -234.375706)
		(width 0.18288)
		(layer "In4.Cu")
		(net "M_G_CPU1_SB_CB<1>")
	)
	(segment
		(start 143.193262 -239.80267)
		(end 140.315696 -239.80267)
		(width 0.18288)
		(layer "In4.Cu")
		(net "M_G_CPU1_SB_CB<1>")
	)
	(segment
		(start 167.094154 -234.19943)
		(end 166.638732 -234.654852)
		(width 0.18288)
		(layer "In4.Cu")
		(net "M_G_CPU1_SB_CB<1>")
	)
	(segment
		(start 140.315696 -239.80267)
		(end 140.273278 -239.80267)
		(width 0.088646)
		(layer "In4.Cu")
		(net "M_G_CPU1_SB_CB<1>")
	)
	(segment
		(start 155.280614 -234.375706)
		(end 155.280614 -234.54868)
		(width 0.18288)
		(layer "In4.Cu")
		(net "M_G_CPU1_SB_CB<1>")
	)
	(segment
		(start 177.735484 -232.752138)
		(end 177.575464 -232.592118)
		(width 0.18288)
		(layer "In4.Cu")
		(net "M_G_CPU1_SB_CB<1>")
	)
	(segment
		(start 130.43662 -240.66754)
		(end 130.436366 -240.667286)
		(width 0.088646)
		(layer "In4.Cu")
		(net "M_G_CPU1_SB_CB<1>")
	)
	(segment
		(start 174.436786 -232.592118)
		(end 173.589188 -233.439716)
		(width 0.18288)
		(layer "In4.Cu")
		(net "M_G_CPU1_SB_CB<1>")
	)
	(segment
		(start 131.941062 -240.667286)
		(end 131.941062 -240.673636)
		(width 0.088646)
		(layer "In4.Cu")
		(net "M_G_CPU1_SB_CB<1>")
	)
	(segment
		(start 178.428904 -232.925112)
		(end 178.268884 -233.085132)
		(width 0.18288)
		(layer "In4.Cu")
		(net "M_G_CPU1_SB_CB<1>")
	)
	(segment
		(start 160.761426 -234.192826)
		(end 156.850334 -234.192826)
		(width 0.18288)
		(layer "In4.Cu")
		(net "M_G_CPU1_SB_CB<1>")
	)
	(segment
		(start 183.403748 -233.24058)
		(end 183.403748 -232.872026)
		(width 0.18288)
		(layer "In4.Cu")
		(net "M_G_CPU1_SB_CB<1>")
	)
	(segment
		(start 181.138322 -232.434638)
		(end 180.109114 -232.434638)
		(width 0.18288)
		(layer "In4.Cu")
		(net "M_G_CPU1_SB_CB<1>")
	)
	(segment
		(start 155.791154 -234.192826)
		(end 155.463494 -234.192826)
		(width 0.18288)
		(layer "In4.Cu")
		(net "M_G_CPU1_SB_CB<1>")
	)
	(segment
		(start 165.466776 -234.269026)
		(end 165.275006 -234.077256)
		(width 0.18288)
		(layer "In4.Cu")
		(net "M_G_CPU1_SB_CB<1>")
	)
	(segment
		(start 166.290752 -234.654852)
		(end 165.904926 -234.269026)
		(width 0.18288)
		(layer "In4.Cu")
		(net "M_G_CPU1_SB_CB<1>")
	)
	(segment
		(start 170.468036 -233.439716)
		(end 169.611548 -234.296204)
		(width 0.18288)
		(layer "In4.Cu")
		(net "M_G_CPU1_SB_CB<1>")
	)
	(segment
		(start 145.715228 -237.280704)
		(end 143.193262 -239.80267)
		(width 0.18288)
		(layer "In4.Cu")
		(net "M_G_CPU1_SB_CB<1>")
	)
	(segment
		(start 179.21986 -232.648252)
		(end 178.588924 -232.648252)
		(width 0.18288)
		(layer "In4.Cu")
		(net "M_G_CPU1_SB_CB<1>")
	)
	(segment
		(start 137.216896 -240.351564)
		(end 137.202164 -240.342928)
		(width 0.088646)
		(layer "In4.Cu")
		(net "M_G_CPU1_SB_CB<1>")
	)
	(segment
		(start 156.850334 -234.192826)
		(end 156.667454 -234.375706)
		(width 0.18288)
		(layer "In4.Cu")
		(net "M_G_CPU1_SB_CB<1>")
	)
	(segment
		(start 185.904124 -233.435652)
		(end 185.744104 -233.275632)
		(width 0.18288)
		(layer "In4.Cu")
		(net "M_G_CPU1_SB_CB<1>")
	)
	(segment
		(start 185.050684 -233.095292)
		(end 185.050684 -233.275632)
		(width 0.18288)
		(layer "In4.Cu")
		(net "M_G_CPU1_SB_CB<1>")
	)
	(segment
		(start 131.099306 -241.160046)
		(end 131.093464 -241.156744)
		(width 0.088646)
		(layer "In4.Cu")
		(net "M_G_CPU1_SB_CB<1>")
	)
	(segment
		(start 155.097734 -234.73156)
		(end 154.770074 -234.73156)
		(width 0.18288)
		(layer "In4.Cu")
		(net "M_G_CPU1_SB_CB<1>")
	)
	(segment
		(start 156.667454 -234.54868)
		(end 156.484574 -234.73156)
		(width 0.18288)
		(layer "In4.Cu")
		(net "M_G_CPU1_SB_CB<1>")
	)
	(segment
		(start 156.156914 -234.73156)
		(end 155.974034 -234.54868)
		(width 0.18288)
		(layer "In4.Cu")
		(net "M_G_CPU1_SB_CB<1>")
	)
	(segment
		(start 138.156696 -240.351564)
		(end 138.141964 -240.342928)
		(width 0.088646)
		(layer "In4.Cu")
		(net "M_G_CPU1_SB_CB<1>")
	)
	(segment
		(start 178.428904 -232.808272)
		(end 178.428904 -232.925112)
		(width 0.18288)
		(layer "In4.Cu")
		(net "M_G_CPU1_SB_CB<1>")
	)
	(segment
		(start 139.659868 -240.41608)
		(end 139.419838 -240.41608)
		(width 0.088646)
		(layer "In4.Cu")
		(net "M_G_CPU1_SB_CB<1>")
	)
	(segment
		(start 140.273278 -239.80267)
		(end 139.659868 -240.41608)
		(width 0.088646)
		(layer "In4.Cu")
		(net "M_G_CPU1_SB_CB<1>")
	)
	(segment
		(start 139.096496 -240.351564)
		(end 139.081764 -240.342928)
		(width 0.088646)
		(layer "In4.Cu")
		(net "M_G_CPU1_SB_CB<1>")
	)
	(segment
		(start 183.55056 -233.387392)
		(end 183.403748 -233.24058)
		(width 0.18288)
		(layer "In4.Cu")
		(net "M_G_CPU1_SB_CB<1>")
	)
	(segment
		(start 185.210704 -232.935272)
		(end 185.050684 -233.095292)
		(width 0.18288)
		(layer "In4.Cu")
		(net "M_G_CPU1_SB_CB<1>")
	)
	(segment
		(start 182.96636 -232.434638)
		(end 182.151782 -232.434638)
		(width 0.18288)
		(layer "In4.Cu")
		(net "M_G_CPU1_SB_CB<1>")
	)
	(segment
		(start 133.074156 -240.339372)
		(end 133.068314 -240.342928)
		(width 0.088646)
		(layer "In4.Cu")
		(net "M_G_CPU1_SB_CB<1>")
	)
	(segment
		(start 185.584084 -232.935272)
		(end 185.210704 -232.935272)
		(width 0.18288)
		(layer "In4.Cu")
		(net "M_G_CPU1_SB_CB<1>")
	)
	(segment
		(start 169.611548 -234.296204)
		(end 168.552114 -234.296204)
		(width 0.18288)
		(layer "In4.Cu")
		(net "M_G_CPU1_SB_CB<1>")
	)
	(segment
		(start 155.974034 -234.375706)
		(end 155.791154 -234.192826)
		(width 0.18288)
		(layer "In4.Cu")
		(net "M_G_CPU1_SB_CB<1>")
	)
	(segment
		(start 181.991762 -232.769918)
		(end 181.831742 -232.929938)
		(width 0.18288)
		(layer "In4.Cu")
		(net "M_G_CPU1_SB_CB<1>")
	)
	(segment
		(start 185.050684 -233.275632)
		(end 184.890664 -233.435652)
		(width 0.18288)
		(layer "In4.Cu")
		(net "M_G_CPU1_SB_CB<1>")
	)
	(segment
		(start 154.587194 -234.54868)
		(end 154.587194 -234.375706)
		(width 0.18288)
		(layer "In4.Cu")
		(net "M_G_CPU1_SB_CB<1>")
	)
	(segment
		(start 155.974034 -234.54868)
		(end 155.974034 -234.375706)
		(width 0.18288)
		(layer "In4.Cu")
		(net "M_G_CPU1_SB_CB<1>")
	)
	(segment
		(start 132.134356 -240.339372)
		(end 132.128514 -240.342928)
		(width 0.088646)
		(layer "In4.Cu")
		(net "M_G_CPU1_SB_CB<1>")
	)
	(segment
		(start 156.484574 -234.73156)
		(end 156.156914 -234.73156)
		(width 0.18288)
		(layer "In4.Cu")
		(net "M_G_CPU1_SB_CB<1>")
	)
	(segment
		(start 156.667454 -234.375706)
		(end 156.667454 -234.54868)
		(width 0.18288)
		(layer "In4.Cu")
		(net "M_G_CPU1_SB_CB<1>")
	)
	(segment
		(start 177.575464 -232.592118)
		(end 174.436786 -232.592118)
		(width 0.18288)
		(layer "In4.Cu")
		(net "M_G_CPU1_SB_CB<1>")
	)
	(segment
		(start 181.458362 -232.929938)
		(end 181.298342 -232.769918)
		(width 0.18288)
		(layer "In4.Cu")
		(net "M_G_CPU1_SB_CB<1>")
	)
	(segment
		(start 134.008114 -240.342928)
		(end 134.004558 -240.34496)
		(width 0.088646)
		(layer "In4.Cu")
		(net "M_G_CPU1_SB_CB<1>")
	)
	(segment
		(start 133.068314 -240.342928)
		(end 133.062472 -240.34623)
		(width 0.088646)
		(layer "In4.Cu")
		(net "M_G_CPU1_SB_CB<1>")
	)
	(segment
		(start 181.831742 -232.929938)
		(end 181.458362 -232.929938)
		(width 0.18288)
		(layer "In4.Cu")
		(net "M_G_CPU1_SB_CB<1>")
	)
	(segment
		(start 182.151782 -232.434638)
		(end 181.991762 -232.594658)
		(width 0.18288)
		(layer "In4.Cu")
		(net "M_G_CPU1_SB_CB<1>")
	)
	(segment
		(start 164.737796 -234.077256)
		(end 164.444426 -234.370626)
		(width 0.18288)
		(layer "In4.Cu")
		(net "M_G_CPU1_SB_CB<1>")
	)
	(segment
		(start 168.552114 -234.296204)
		(end 168.45534 -234.19943)
		(width 0.18288)
		(layer "In4.Cu")
		(net "M_G_CPU1_SB_CB<1>")
	)
	(segment
		(start 183.403748 -232.872026)
		(end 182.96636 -232.434638)
		(width 0.18288)
		(layer "In4.Cu")
		(net "M_G_CPU1_SB_CB<1>")
	)
	(segment
		(start 184.62117 -233.387392)
		(end 183.55056 -233.387392)
		(width 0.18288)
		(layer "In4.Cu")
		(net "M_G_CPU1_SB_CB<1>")
	)
	(segment
		(start 184.890664 -233.435652)
		(end 184.66943 -233.435652)
		(width 0.18288)
		(layer "In4.Cu")
		(net "M_G_CPU1_SB_CB<1>")
	)
	(segment
		(start 173.589188 -233.439716)
		(end 170.468036 -233.439716)
		(width 0.18288)
		(layer "In4.Cu")
		(net "M_G_CPU1_SB_CB<1>")
	)
	(segment
		(start 181.991762 -232.594658)
		(end 181.991762 -232.769918)
		(width 0.18288)
		(layer "In4.Cu")
		(net "M_G_CPU1_SB_CB<1>")
	)
	(segment
		(start 185.744104 -233.095292)
		(end 185.584084 -232.935272)
		(width 0.18288)
		(layer "In4.Cu")
		(net "M_G_CPU1_SB_CB<1>")
	)
	(segment
		(start 150.181818 -237.280704)
		(end 145.715228 -237.280704)
		(width 0.18288)
		(layer "In4.Cu")
		(net "M_G_CPU1_SB_CB<1>")
	)
	(segment
		(start 134.947914 -240.342928)
		(end 134.943342 -240.345468)
		(width 0.088646)
		(layer "In4.Cu")
		(net "M_G_CPU1_SB_CB<1>")
	)
	(segment
		(start 179.316634 -232.745026)
		(end 179.21986 -232.648252)
		(width 0.18288)
		(layer "In4.Cu")
		(net "M_G_CPU1_SB_CB<1>")
	)
	(segment
		(start 135.887714 -240.342928)
		(end 135.884158 -240.34496)
		(width 0.088646)
		(layer "In4.Cu")
		(net "M_G_CPU1_SB_CB<1>")
	)
	(segment
		(start 181.298342 -232.769918)
		(end 181.298342 -232.594658)
		(width 0.18288)
		(layer "In4.Cu")
		(net "M_G_CPU1_SB_CB<1>")
	)
	(segment
		(start 165.275006 -234.077256)
		(end 164.737796 -234.077256)
		(width 0.18288)
		(layer "In4.Cu")
		(net "M_G_CPU1_SB_CB<1>")
	)
	(segment
		(start 131.093464 -241.156744)
		(end 130.989578 -241.09553)
		(width 0.088646)
		(layer "In4.Cu")
		(net "M_G_CPU1_SB_CB<1>")
	)
	(segment
		(start 177.895504 -233.085132)
		(end 177.735484 -232.925112)
		(width 0.18288)
		(layer "In4.Cu")
		(net "M_G_CPU1_SB_CB<1>")
	)
	(segment
		(start 184.66943 -233.435652)
		(end 184.62117 -233.387392)
		(width 0.18288)
		(layer "In4.Cu")
		(net "M_G_CPU1_SB_CB<1>")
	)
	(segment
		(start 154.404314 -234.192826)
		(end 153.269696 -234.192826)
		(width 0.18288)
		(layer "In4.Cu")
		(net "M_G_CPU1_SB_CB<1>")
	)
	(segment
		(start 185.744104 -233.275632)
		(end 185.744104 -233.095292)
		(width 0.18288)
		(layer "In4.Cu")
		(net "M_G_CPU1_SB_CB<1>")
	)
	(segment
		(start 179.798726 -232.745026)
		(end 179.316634 -232.745026)
		(width 0.18288)
		(layer "In4.Cu")
		(net "M_G_CPU1_SB_CB<1>")
	)
	(segment
		(start 180.109114 -232.434638)
		(end 179.798726 -232.745026)
		(width 0.18288)
		(layer "In4.Cu")
		(net "M_G_CPU1_SB_CB<1>")
	)
	(segment
		(start 177.735484 -232.925112)
		(end 177.735484 -232.752138)
		(width 0.18288)
		(layer "In4.Cu")
		(net "M_G_CPU1_SB_CB<1>")
	)
	(segment
		(start 166.638732 -234.654852)
		(end 166.290752 -234.654852)
		(width 0.18288)
		(layer "In4.Cu")
		(net "M_G_CPU1_SB_CB<1>")
	)
	(arc
		(start 137.767568 -240.342928)
		(mid 137.493339 -240.418853)
		(end 137.216896 -240.351564)
		(width 0.088646)
		(layer "In4.Cu")
		(net "M_G_CPU1_SB_CB<1>")
	)
	(arc
		(start 138.141964 -240.342928)
		(mid 137.954766 -240.292785)
		(end 137.767568 -240.342928)
		(width 0.088646)
		(layer "In4.Cu")
		(net "M_G_CPU1_SB_CB<1>")
	)
	(arc
		(start 136.262364 -240.342928)
		(mid 136.075056 -240.292785)
		(end 135.887714 -240.342928)
		(width 0.088646)
		(layer "In4.Cu")
		(net "M_G_CPU1_SB_CB<1>")
	)
	(arc
		(start 132.123434 -240.345722)
		(mid 131.989818 -240.482442)
		(end 131.941062 -240.667286)
		(width 0.088646)
		(layer "In4.Cu")
		(net "M_G_CPU1_SB_CB<1>")
	)
	(arc
		(start 131.941062 -240.673636)
		(mid 131.863807 -240.952582)
		(end 131.658614 -241.156744)
		(width 0.088646)
		(layer "In4.Cu")
		(net "M_G_CPU1_SB_CB<1>")
	)
	(arc
		(start 138.707368 -240.342928)
		(mid 138.433139 -240.418853)
		(end 138.156696 -240.351564)
		(width 0.088646)
		(layer "In4.Cu")
		(net "M_G_CPU1_SB_CB<1>")
	)
	(arc
		(start 135.322564 -240.342674)
		(mid 135.13861 -240.292579)
		(end 134.953756 -240.339372)
		(width 0.088646)
		(layer "In4.Cu")
		(net "M_G_CPU1_SB_CB<1>")
	)
	(arc
		(start 132.503164 -240.342674)
		(mid 132.31921 -240.292579)
		(end 132.134356 -240.339372)
		(width 0.088646)
		(layer "In4.Cu")
		(net "M_G_CPU1_SB_CB<1>")
	)
	(arc
		(start 139.081764 -240.342928)
		(mid 138.894566 -240.292785)
		(end 138.707368 -240.342928)
		(width 0.088646)
		(layer "In4.Cu")
		(net "M_G_CPU1_SB_CB<1>")
	)
	(arc
		(start 131.658614 -241.156744)
		(mid 131.379411 -241.232384)
		(end 131.099306 -241.160046)
		(width 0.088646)
		(layer "In4.Cu")
		(net "M_G_CPU1_SB_CB<1>")
	)
	(arc
		(start 134.382764 -240.342928)
		(mid 134.195456 -240.292785)
		(end 134.008114 -240.342928)
		(width 0.088646)
		(layer "In4.Cu")
		(net "M_G_CPU1_SB_CB<1>")
	)
	(arc
		(start 134.004558 -240.34496)
		(mid 133.723445 -240.418537)
		(end 133.442964 -240.342674)
		(width 0.088646)
		(layer "In4.Cu")
		(net "M_G_CPU1_SB_CB<1>")
	)
	(arc
		(start 135.884158 -240.34496)
		(mid 135.603045 -240.418537)
		(end 135.322564 -240.342674)
		(width 0.088646)
		(layer "In4.Cu")
		(net "M_G_CPU1_SB_CB<1>")
	)
	(arc
		(start 139.419838 -240.41608)
		(mid 139.253354 -240.407928)
		(end 139.096496 -240.351564)
		(width 0.088646)
		(layer "In4.Cu")
		(net "M_G_CPU1_SB_CB<1>")
	)
	(arc
		(start 133.062472 -240.34623)
		(mid 132.782337 -240.418546)
		(end 132.503164 -240.342674)
		(width 0.088646)
		(layer "In4.Cu")
		(net "M_G_CPU1_SB_CB<1>")
	)
	(arc
		(start 134.943342 -240.345468)
		(mid 134.662707 -240.418636)
		(end 134.382764 -240.342928)
		(width 0.088646)
		(layer "In4.Cu")
		(net "M_G_CPU1_SB_CB<1>")
	)
	(arc
		(start 130.989578 -241.09553)
		(mid 130.699554 -240.899036)
		(end 130.43662 -240.66754)
		(width 0.088646)
		(layer "In4.Cu")
		(net "M_G_CPU1_SB_CB<1>")
	)
	(arc
		(start 133.442964 -240.342674)
		(mid 133.25901 -240.292579)
		(end 133.074156 -240.339372)
		(width 0.088646)
		(layer "In4.Cu")
		(net "M_G_CPU1_SB_CB<1>")
	)
	(arc
		(start 137.202164 -240.342928)
		(mid 137.014966 -240.292785)
		(end 136.827768 -240.342928)
		(width 0.088646)
		(layer "In4.Cu")
		(net "M_G_CPU1_SB_CB<1>")
	)
	(arc
		(start 136.827768 -240.342928)
		(mid 136.553539 -240.418853)
		(end 136.277096 -240.351564)
		(width 0.088646)
		(layer "In4.Cu")
		(net "M_G_CPU1_SB_CB<1>")
	)
	(segment
		(start 194.901312 -235.566966)
		(end 194.476116 -235.14177)
		(width 0.20066)
		(layer "F.Cu")
		(net "M_G_CPU1_SB_CB<0>")
	)
	(segment
		(start 191.539114 -235.14177)
		(end 191.421004 -235.25988)
		(width 0.20066)
		(layer "F.Cu")
		(net "M_G_CPU1_SB_CB<0>")
	)
	(segment
		(start 194.277742 -235.14177)
		(end 194.241166 -235.14177)
		(width 0.101854)
		(layer "F.Cu")
		(net "M_G_CPU1_SB_CB<0>")
	)
	(segment
		(start 191.421004 -235.25988)
		(end 191.421004 -235.627418)
		(width 0.20066)
		(layer "F.Cu")
		(net "M_G_CPU1_SB_CB<0>")
	)
	(segment
		(start 188.988446 -235.566712)
		(end 187.883546 -235.566712)
		(width 0.20066)
		(layer "F.Cu")
		(net "M_G_CPU1_SB_CB<0>")
	)
	(segment
		(start 196.532246 -235.566712)
		(end 196.531992 -235.566966)
		(width 0.20066)
		(layer "F.Cu")
		(net "M_G_CPU1_SB_CB<0>")
	)
	(segment
		(start 129.966466 -242.017042)
		(end 129.966212 -242.016788)
		(width 0.20066)
		(layer "F.Cu")
		(net "M_G_CPU1_SB_CB<0>")
	)
	(segment
		(start 190.509144 -235.566712)
		(end 188.988446 -235.566712)
		(width 0.20066)
		(layer "F.Cu")
		(net "M_G_CPU1_SB_CB<0>")
	)
	(segment
		(start 194.476116 -235.14177)
		(end 194.277742 -235.14177)
		(width 0.20066)
		(layer "F.Cu")
		(net "M_G_CPU1_SB_CB<0>")
	)
	(segment
		(start 191.786256 -235.14177)
		(end 191.539114 -235.14177)
		(width 0.20066)
		(layer "F.Cu")
		(net "M_G_CPU1_SB_CB<0>")
	)
	(segment
		(start 191.421004 -235.627418)
		(end 191.233044 -235.815378)
		(width 0.20066)
		(layer "F.Cu")
		(net "M_G_CPU1_SB_CB<0>")
	)
	(segment
		(start 190.75781 -235.815378)
		(end 190.509144 -235.566712)
		(width 0.20066)
		(layer "F.Cu")
		(net "M_G_CPU1_SB_CB<0>")
	)
	(segment
		(start 191.233044 -235.815378)
		(end 190.75781 -235.815378)
		(width 0.20066)
		(layer "F.Cu")
		(net "M_G_CPU1_SB_CB<0>")
	)
	(segment
		(start 191.930782 -235.14177)
		(end 191.786256 -235.14177)
		(width 0.101854)
		(layer "F.Cu")
		(net "M_G_CPU1_SB_CB<0>")
	)
	(segment
		(start 196.531992 -235.566966)
		(end 194.901312 -235.566966)
		(width 0.20066)
		(layer "F.Cu")
		(net "M_G_CPU1_SB_CB<0>")
	)
	(segment
		(start 194.241166 -235.14177)
		(end 191.930782 -235.14177)
		(width 0.1016)
		(layer "F.Cu")
		(net "M_G_CPU1_SB_CB<0>")
	)
	(segment
		(start 129.966212 -242.016788)
		(end 129.966212 -241.481102)
		(width 0.20066)
		(layer "F.Cu")
		(net "M_G_CPU1_SB_CB<0>")
	)
	(segment
		(start 181.593744 -234.460542)
		(end 180.98262 -234.460542)
		(width 0.18288)
		(layer "In4.Cu")
		(net "M_G_CPU1_SB_CB<0>")
	)
	(segment
		(start 184.830212 -235.325412)
		(end 184.612026 -235.107226)
		(width 0.18288)
		(layer "In4.Cu")
		(net "M_G_CPU1_SB_CB<0>")
	)
	(segment
		(start 163.256722 -235.889546)
		(end 163.256722 -235.555536)
		(width 0.18288)
		(layer "In4.Cu")
		(net "M_G_CPU1_SB_CB<0>")
	)
	(segment
		(start 181.81066 -234.243626)
		(end 181.593744 -234.460542)
		(width 0.18288)
		(layer "In4.Cu")
		(net "M_G_CPU1_SB_CB<0>")
	)
	(segment
		(start 166.728902 -235.865924)
		(end 166.728902 -236.212888)
		(width 0.18288)
		(layer "In4.Cu")
		(net "M_G_CPU1_SB_CB<0>")
	)
	(segment
		(start 169.930064 -235.793534)
		(end 169.350944 -236.372654)
		(width 0.18288)
		(layer "In4.Cu")
		(net "M_G_CPU1_SB_CB<0>")
	)
	(segment
		(start 186.121548 -235.325412)
		(end 184.830212 -235.325412)
		(width 0.18288)
		(layer "In4.Cu")
		(net "M_G_CPU1_SB_CB<0>")
	)
	(segment
		(start 129.966466 -241.481102)
		(end 129.966212 -241.481102)
		(width 0.088646)
		(layer "In4.Cu")
		(net "M_G_CPU1_SB_CB<0>")
	)
	(segment
		(start 187.858146 -235.566712)
		(end 187.37326 -235.081826)
		(width 0.18288)
		(layer "In4.Cu")
		(net "M_G_CPU1_SB_CB<0>")
	)
	(segment
		(start 187.883546 -235.566712)
		(end 187.858146 -235.566712)
		(width 0.18288)
		(layer "In4.Cu")
		(net "M_G_CPU1_SB_CB<0>")
	)
	(segment
		(start 173.667674 -235.142278)
		(end 171.026074 -235.142278)
		(width 0.18288)
		(layer "In4.Cu")
		(net "M_G_CPU1_SB_CB<0>")
	)
	(segment
		(start 183.77281 -235.107226)
		(end 182.90921 -234.243626)
		(width 0.18288)
		(layer "In4.Cu")
		(net "M_G_CPU1_SB_CB<0>")
	)
	(segment
		(start 186.365134 -235.081826)
		(end 186.121548 -235.325412)
		(width 0.18288)
		(layer "In4.Cu")
		(net "M_G_CPU1_SB_CB<0>")
	)
	(segment
		(start 168.841928 -236.372654)
		(end 168.152318 -235.683044)
		(width 0.18288)
		(layer "In4.Cu")
		(net "M_G_CPU1_SB_CB<0>")
	)
	(segment
		(start 166.035482 -235.865924)
		(end 165.852602 -235.683044)
		(width 0.18288)
		(layer "In4.Cu")
		(net "M_G_CPU1_SB_CB<0>")
	)
	(segment
		(start 135.792464 -241.156744)
		(end 135.788146 -241.154204)
		(width 0.088646)
		(layer "In4.Cu")
		(net "M_G_CPU1_SB_CB<0>")
	)
	(segment
		(start 168.152318 -235.683044)
		(end 166.911782 -235.683044)
		(width 0.18288)
		(layer "In4.Cu")
		(net "M_G_CPU1_SB_CB<0>")
	)
	(segment
		(start 132.978906 -241.160046)
		(end 132.967222 -241.153442)
		(width 0.088646)
		(layer "In4.Cu")
		(net "M_G_CPU1_SB_CB<0>")
	)
	(segment
		(start 150.594314 -238.276384)
		(end 146.127724 -238.276384)
		(width 0.18288)
		(layer "In4.Cu")
		(net "M_G_CPU1_SB_CB<0>")
	)
	(segment
		(start 163.439602 -236.072426)
		(end 163.256722 -235.889546)
		(width 0.18288)
		(layer "In4.Cu")
		(net "M_G_CPU1_SB_CB<0>")
	)
	(segment
		(start 164.783008 -235.683044)
		(end 164.393626 -236.072426)
		(width 0.18288)
		(layer "In4.Cu")
		(net "M_G_CPU1_SB_CB<0>")
	)
	(segment
		(start 179.276248 -234.94746)
		(end 179.093368 -235.13034)
		(width 0.18288)
		(layer "In4.Cu")
		(net "M_G_CPU1_SB_CB<0>")
	)
	(segment
		(start 146.127724 -238.276384)
		(end 143.58112 -240.822988)
		(width 0.18288)
		(layer "In4.Cu")
		(net "M_G_CPU1_SB_CB<0>")
	)
	(segment
		(start 163.073842 -235.372656)
		(end 162.746182 -235.372656)
		(width 0.18288)
		(layer "In4.Cu")
		(net "M_G_CPU1_SB_CB<0>")
	)
	(segment
		(start 134.858506 -241.160046)
		(end 134.852664 -241.156744)
		(width 0.088646)
		(layer "In4.Cu")
		(net "M_G_CPU1_SB_CB<0>")
	)
	(segment
		(start 139.244832 -240.822988)
		(end 138.937238 -240.950496)
		(width 0.088646)
		(layer "In4.Cu")
		(net "M_G_CPU1_SB_CB<0>")
	)
	(segment
		(start 178.582828 -234.475274)
		(end 178.399948 -234.292394)
		(width 0.18288)
		(layer "In4.Cu")
		(net "M_G_CPU1_SB_CB<0>")
	)
	(segment
		(start 179.459128 -234.292394)
		(end 179.276248 -234.475274)
		(width 0.18288)
		(layer "In4.Cu")
		(net "M_G_CPU1_SB_CB<0>")
	)
	(segment
		(start 160.913826 -236.072426)
		(end 160.710626 -235.869226)
		(width 0.18288)
		(layer "In4.Cu")
		(net "M_G_CPU1_SB_CB<0>")
	)
	(segment
		(start 162.380422 -236.072426)
		(end 160.913826 -236.072426)
		(width 0.18288)
		(layer "In4.Cu")
		(net "M_G_CPU1_SB_CB<0>")
	)
	(segment
		(start 180.814472 -234.292394)
		(end 179.459128 -234.292394)
		(width 0.18288)
		(layer "In4.Cu")
		(net "M_G_CPU1_SB_CB<0>")
	)
	(segment
		(start 178.582828 -234.94746)
		(end 178.582828 -234.475274)
		(width 0.18288)
		(layer "In4.Cu")
		(net "M_G_CPU1_SB_CB<0>")
	)
	(segment
		(start 162.563302 -235.889546)
		(end 162.380422 -236.072426)
		(width 0.18288)
		(layer "In4.Cu")
		(net "M_G_CPU1_SB_CB<0>")
	)
	(segment
		(start 160.710626 -235.869226)
		(end 153.001472 -235.869226)
		(width 0.18288)
		(layer "In4.Cu")
		(net "M_G_CPU1_SB_CB<0>")
	)
	(segment
		(start 138.781536 -241.106198)
		(end 138.424666 -241.106198)
		(width 0.088646)
		(layer "In4.Cu")
		(net "M_G_CPU1_SB_CB<0>")
	)
	(segment
		(start 164.393626 -236.072426)
		(end 163.439602 -236.072426)
		(width 0.18288)
		(layer "In4.Cu")
		(net "M_G_CPU1_SB_CB<0>")
	)
	(segment
		(start 132.033264 -241.80546)
		(end 132.028692 -241.808254)
		(width 0.088646)
		(layer "In4.Cu")
		(net "M_G_CPU1_SB_CB<0>")
	)
	(segment
		(start 132.514594 -241.221006)
		(end 132.395468 -241.340132)
		(width 0.088646)
		(layer "In4.Cu")
		(net "M_G_CPU1_SB_CB<0>")
	)
	(segment
		(start 171.026074 -235.142278)
		(end 170.374818 -235.793534)
		(width 0.18288)
		(layer "In4.Cu")
		(net "M_G_CPU1_SB_CB<0>")
	)
	(segment
		(start 175.747426 -234.167426)
		(end 174.642526 -234.167426)
		(width 0.18288)
		(layer "In4.Cu")
		(net "M_G_CPU1_SB_CB<0>")
	)
	(segment
		(start 138.937238 -240.950496)
		(end 138.781536 -241.106198)
		(width 0.088646)
		(layer "In4.Cu")
		(net "M_G_CPU1_SB_CB<0>")
	)
	(segment
		(start 178.399948 -234.292394)
		(end 175.872394 -234.292394)
		(width 0.18288)
		(layer "In4.Cu")
		(net "M_G_CPU1_SB_CB<0>")
	)
	(segment
		(start 153.001472 -235.869226)
		(end 150.594314 -238.276384)
		(width 0.18288)
		(layer "In4.Cu")
		(net "M_G_CPU1_SB_CB<0>")
	)
	(segment
		(start 131.093464 -241.80546)
		(end 131.088892 -241.808254)
		(width 0.088646)
		(layer "In4.Cu")
		(net "M_G_CPU1_SB_CB<0>")
	)
	(segment
		(start 166.035482 -236.212888)
		(end 166.035482 -235.865924)
		(width 0.18288)
		(layer "In4.Cu")
		(net "M_G_CPU1_SB_CB<0>")
	)
	(segment
		(start 133.912864 -241.156744)
		(end 133.908546 -241.154204)
		(width 0.088646)
		(layer "In4.Cu")
		(net "M_G_CPU1_SB_CB<0>")
	)
	(segment
		(start 187.37326 -235.081826)
		(end 186.365134 -235.081826)
		(width 0.18288)
		(layer "In4.Cu")
		(net "M_G_CPU1_SB_CB<0>")
	)
	(segment
		(start 166.546022 -236.395768)
		(end 166.218362 -236.395768)
		(width 0.18288)
		(layer "In4.Cu")
		(net "M_G_CPU1_SB_CB<0>")
	)
	(segment
		(start 166.728902 -236.212888)
		(end 166.546022 -236.395768)
		(width 0.18288)
		(layer "In4.Cu")
		(net "M_G_CPU1_SB_CB<0>")
	)
	(segment
		(start 162.746182 -235.372656)
		(end 162.563302 -235.555536)
		(width 0.18288)
		(layer "In4.Cu")
		(net "M_G_CPU1_SB_CB<0>")
	)
	(segment
		(start 132.073142 -241.782346)
		(end 132.033264 -241.80546)
		(width 0.088646)
		(layer "In4.Cu")
		(net "M_G_CPU1_SB_CB<0>")
	)
	(segment
		(start 184.612026 -235.107226)
		(end 183.77281 -235.107226)
		(width 0.18288)
		(layer "In4.Cu")
		(net "M_G_CPU1_SB_CB<0>")
	)
	(segment
		(start 170.374818 -235.793534)
		(end 169.930064 -235.793534)
		(width 0.18288)
		(layer "In4.Cu")
		(net "M_G_CPU1_SB_CB<0>")
	)
	(segment
		(start 132.292344 -241.537236)
		(end 132.258308 -241.619786)
		(width 0.088646)
		(layer "In4.Cu")
		(net "M_G_CPU1_SB_CB<0>")
	)
	(segment
		(start 163.256722 -235.555536)
		(end 163.073842 -235.372656)
		(width 0.18288)
		(layer "In4.Cu")
		(net "M_G_CPU1_SB_CB<0>")
	)
	(segment
		(start 178.765708 -235.13034)
		(end 178.582828 -234.94746)
		(width 0.18288)
		(layer "In4.Cu")
		(net "M_G_CPU1_SB_CB<0>")
	)
	(segment
		(start 165.852602 -235.683044)
		(end 164.783008 -235.683044)
		(width 0.18288)
		(layer "In4.Cu")
		(net "M_G_CPU1_SB_CB<0>")
	)
	(segment
		(start 182.90921 -234.243626)
		(end 181.81066 -234.243626)
		(width 0.18288)
		(layer "In4.Cu")
		(net "M_G_CPU1_SB_CB<0>")
	)
	(segment
		(start 166.911782 -235.683044)
		(end 166.728902 -235.865924)
		(width 0.18288)
		(layer "In4.Cu")
		(net "M_G_CPU1_SB_CB<0>")
	)
	(segment
		(start 169.350944 -236.372654)
		(end 168.841928 -236.372654)
		(width 0.18288)
		(layer "In4.Cu")
		(net "M_G_CPU1_SB_CB<0>")
	)
	(segment
		(start 179.093368 -235.13034)
		(end 178.765708 -235.13034)
		(width 0.18288)
		(layer "In4.Cu")
		(net "M_G_CPU1_SB_CB<0>")
	)
	(segment
		(start 162.563302 -235.555536)
		(end 162.563302 -235.889546)
		(width 0.18288)
		(layer "In4.Cu")
		(net "M_G_CPU1_SB_CB<0>")
	)
	(segment
		(start 131.10083 -241.801396)
		(end 131.093464 -241.80546)
		(width 0.088646)
		(layer "In4.Cu")
		(net "M_G_CPU1_SB_CB<0>")
	)
	(segment
		(start 166.218362 -236.395768)
		(end 166.035482 -236.212888)
		(width 0.18288)
		(layer "In4.Cu")
		(net "M_G_CPU1_SB_CB<0>")
	)
	(segment
		(start 174.642526 -234.167426)
		(end 173.667674 -235.142278)
		(width 0.18288)
		(layer "In4.Cu")
		(net "M_G_CPU1_SB_CB<0>")
	)
	(segment
		(start 130.718814 -241.80546)
		(end 130.321812 -241.576352)
		(width 0.088646)
		(layer "In4.Cu")
		(net "M_G_CPU1_SB_CB<0>")
	)
	(segment
		(start 179.276248 -234.475274)
		(end 179.276248 -234.94746)
		(width 0.18288)
		(layer "In4.Cu")
		(net "M_G_CPU1_SB_CB<0>")
	)
	(segment
		(start 180.98262 -234.460542)
		(end 180.814472 -234.292394)
		(width 0.18288)
		(layer "In4.Cu")
		(net "M_G_CPU1_SB_CB<0>")
	)
	(segment
		(start 134.852664 -241.156744)
		(end 134.848854 -241.154458)
		(width 0.088646)
		(layer "In4.Cu")
		(net "M_G_CPU1_SB_CB<0>")
	)
	(segment
		(start 140.29182 -240.822988)
		(end 139.244832 -240.822988)
		(width 0.088646)
		(layer "In4.Cu")
		(net "M_G_CPU1_SB_CB<0>")
	)
	(segment
		(start 175.872394 -234.292394)
		(end 175.747426 -234.167426)
		(width 0.18288)
		(layer "In4.Cu")
		(net "M_G_CPU1_SB_CB<0>")
	)
	(segment
		(start 143.58112 -240.822988)
		(end 140.29182 -240.822988)
		(width 0.18288)
		(layer "In4.Cu")
		(net "M_G_CPU1_SB_CB<0>")
	)
	(arc
		(start 130.321812 -241.576352)
		(mid 130.150406 -241.505339)
		(end 129.966466 -241.481102)
		(width 0.088646)
		(layer "In4.Cu")
		(net "M_G_CPU1_SB_CB<0>")
	)
	(arc
		(start 138.237468 -241.156744)
		(mid 137.954766 -241.23252)
		(end 137.672064 -241.156744)
		(width 0.088646)
		(layer "In4.Cu")
		(net "M_G_CPU1_SB_CB<0>")
	)
	(arc
		(start 132.258308 -241.619786)
		(mid 132.236199 -241.658772)
		(end 132.205222 -241.69116)
		(width 0.088646)
		(layer "In4.Cu")
		(net "M_G_CPU1_SB_CB<0>")
	)
	(arc
		(start 137.297668 -241.156744)
		(mid 137.014966 -241.23252)
		(end 136.732264 -241.156744)
		(width 0.088646)
		(layer "In4.Cu")
		(net "M_G_CPU1_SB_CB<0>")
	)
	(arc
		(start 131.647438 -241.800634)
		(mid 131.374066 -241.746742)
		(end 131.10083 -241.801396)
		(width 0.088646)
		(layer "In4.Cu")
		(net "M_G_CPU1_SB_CB<0>")
	)
	(arc
		(start 138.424666 -241.106198)
		(mid 138.327743 -241.119156)
		(end 138.237468 -241.156744)
		(width 0.088646)
		(layer "In4.Cu")
		(net "M_G_CPU1_SB_CB<0>")
	)
	(arc
		(start 133.908546 -241.154204)
		(mid 133.723051 -241.106535)
		(end 133.538214 -241.156744)
		(width 0.088646)
		(layer "In4.Cu")
		(net "M_G_CPU1_SB_CB<0>")
	)
	(arc
		(start 132.205222 -241.69116)
		(mid 132.14102 -241.739416)
		(end 132.073142 -241.782346)
		(width 0.088646)
		(layer "In4.Cu")
		(net "M_G_CPU1_SB_CB<0>")
	)
	(arc
		(start 136.732264 -241.156744)
		(mid 136.545066 -241.106601)
		(end 136.357868 -241.156744)
		(width 0.088646)
		(layer "In4.Cu")
		(net "M_G_CPU1_SB_CB<0>")
	)
	(arc
		(start 135.417814 -241.156744)
		(mid 135.138611 -241.232384)
		(end 134.858506 -241.160046)
		(width 0.088646)
		(layer "In4.Cu")
		(net "M_G_CPU1_SB_CB<0>")
	)
	(arc
		(start 132.028692 -241.808254)
		(mid 131.847546 -241.855773)
		(end 131.66598 -241.809778)
		(width 0.088646)
		(layer "In4.Cu")
		(net "M_G_CPU1_SB_CB<0>")
	)
	(arc
		(start 134.478014 -241.156744)
		(mid 134.195456 -241.232393)
		(end 133.912864 -241.156744)
		(width 0.088646)
		(layer "In4.Cu")
		(net "M_G_CPU1_SB_CB<0>")
	)
	(arc
		(start 133.538214 -241.156744)
		(mid 133.259011 -241.232384)
		(end 132.978906 -241.160046)
		(width 0.088646)
		(layer "In4.Cu")
		(net "M_G_CPU1_SB_CB<0>")
	)
	(arc
		(start 132.395468 -241.340132)
		(mid 132.353318 -241.392978)
		(end 132.324094 -241.453924)
		(width 0.088646)
		(layer "In4.Cu")
		(net "M_G_CPU1_SB_CB<0>")
	)
	(arc
		(start 134.848854 -241.154458)
		(mid 134.663135 -241.106506)
		(end 134.478014 -241.156744)
		(width 0.088646)
		(layer "In4.Cu")
		(net "M_G_CPU1_SB_CB<0>")
	)
	(arc
		(start 131.66598 -241.809778)
		(mid 131.656835 -241.80495)
		(end 131.647438 -241.800634)
		(width 0.088646)
		(layer "In4.Cu")
		(net "M_G_CPU1_SB_CB<0>")
	)
	(arc
		(start 136.357868 -241.156744)
		(mid 136.075166 -241.23252)
		(end 135.792464 -241.156744)
		(width 0.088646)
		(layer "In4.Cu")
		(net "M_G_CPU1_SB_CB<0>")
	)
	(arc
		(start 132.324094 -241.453924)
		(mid 132.308824 -241.49581)
		(end 132.292344 -241.537236)
		(width 0.088646)
		(layer "In4.Cu")
		(net "M_G_CPU1_SB_CB<0>")
	)
	(arc
		(start 131.088892 -241.808254)
		(mid 130.903478 -241.855766)
		(end 130.718814 -241.80546)
		(width 0.088646)
		(layer "In4.Cu")
		(net "M_G_CPU1_SB_CB<0>")
	)
	(arc
		(start 135.788146 -241.154204)
		(mid 135.602651 -241.106535)
		(end 135.417814 -241.156744)
		(width 0.088646)
		(layer "In4.Cu")
		(net "M_G_CPU1_SB_CB<0>")
	)
	(arc
		(start 132.967222 -241.153442)
		(mid 132.782367 -241.106492)
		(end 132.598414 -241.156744)
		(width 0.088646)
		(layer "In4.Cu")
		(net "M_G_CPU1_SB_CB<0>")
	)
	(arc
		(start 137.672064 -241.156744)
		(mid 137.484866 -241.106601)
		(end 137.297668 -241.156744)
		(width 0.088646)
		(layer "In4.Cu")
		(net "M_G_CPU1_SB_CB<0>")
	)
	(arc
		(start 132.598414 -241.156744)
		(mid 132.554392 -241.186121)
		(end 132.514594 -241.221006)
		(width 0.088646)
		(layer "In4.Cu")
		(net "M_G_CPU1_SB_CB<0>")
	)
	(segment
		(start 187.883546 -247.466612)
		(end 188.988446 -247.466612)
		(width 0.20066)
		(layer "F.Cu")
		(net "M_G_CPU1_SB_CA<6>")
	)
	(segment
		(start 194.95262 -247.466358)
		(end 196.531992 -247.466358)
		(width 0.20066)
		(layer "F.Cu")
		(net "M_G_CPU1_SB_CA<6>")
	)
	(segment
		(start 190.053976 -247.466612)
		(end 190.54826 -246.972328)
		(width 0.20066)
		(layer "F.Cu")
		(net "M_G_CPU1_SB_CA<6>")
	)
	(segment
		(start 191.79286 -247.891554)
		(end 191.900302 -247.891554)
		(width 0.20066)
		(layer "F.Cu")
		(net "M_G_CPU1_SB_CA<6>")
	)
	(segment
		(start 191.900302 -247.891554)
		(end 191.914018 -247.891554)
		(width 0.101854)
		(layer "F.Cu")
		(net "M_G_CPU1_SB_CA<6>")
	)
	(segment
		(start 196.531992 -247.466358)
		(end 196.532246 -247.466612)
		(width 0.20066)
		(layer "F.Cu")
		(net "M_G_CPU1_SB_CA<6>")
	)
	(segment
		(start 188.988446 -247.466612)
		(end 190.053976 -247.466612)
		(width 0.20066)
		(layer "F.Cu")
		(net "M_G_CPU1_SB_CA<6>")
	)
	(segment
		(start 190.54826 -246.972328)
		(end 190.873634 -246.972328)
		(width 0.20066)
		(layer "F.Cu")
		(net "M_G_CPU1_SB_CA<6>")
	)
	(segment
		(start 190.873634 -246.972328)
		(end 191.79286 -247.891554)
		(width 0.20066)
		(layer "F.Cu")
		(net "M_G_CPU1_SB_CA<6>")
	)
	(segment
		(start 129.496312 -247.714262)
		(end 129.496566 -247.714008)
		(width 0.20066)
		(layer "F.Cu")
		(net "M_G_CPU1_SB_CA<6>")
	)
	(segment
		(start 194.514978 -247.904)
		(end 194.95262 -247.466358)
		(width 0.20066)
		(layer "F.Cu")
		(net "M_G_CPU1_SB_CA<6>")
	)
	(segment
		(start 191.914018 -247.891554)
		(end 194.08648 -247.891554)
		(width 0.1016)
		(layer "F.Cu")
		(net "M_G_CPU1_SB_CA<6>")
	)
	(segment
		(start 194.098926 -247.904)
		(end 194.514978 -247.904)
		(width 0.20066)
		(layer "F.Cu")
		(net "M_G_CPU1_SB_CA<6>")
	)
	(segment
		(start 129.496566 -247.714008)
		(end 129.496566 -247.178322)
		(width 0.20066)
		(layer "F.Cu")
		(net "M_G_CPU1_SB_CA<6>")
	)
	(segment
		(start 194.08648 -247.891554)
		(end 194.098926 -247.904)
		(width 0.1016)
		(layer "F.Cu")
		(net "M_G_CPU1_SB_CA<6>")
	)
	(segment
		(start 178.48707 -247.575832)
		(end 178.30419 -247.392952)
		(width 0.18288)
		(layer "In4.Cu")
		(net "M_G_CPU1_SB_CA<6>")
	)
	(segment
		(start 137.82675 -247.844564)
		(end 137.432034 -247.844564)
		(width 0.088646)
		(layer "In4.Cu")
		(net "M_G_CPU1_SB_CA<6>")
	)
	(segment
		(start 141.431264 -247.844564)
		(end 137.82675 -247.844564)
		(width 0.18288)
		(layer "In4.Cu")
		(net "M_G_CPU1_SB_CA<6>")
	)
	(segment
		(start 178.30419 -247.392952)
		(end 177.97653 -247.392952)
		(width 0.18288)
		(layer "In4.Cu")
		(net "M_G_CPU1_SB_CA<6>")
	)
	(segment
		(start 185.912506 -247.41378)
		(end 185.463434 -247.41378)
		(width 0.18288)
		(layer "In4.Cu")
		(net "M_G_CPU1_SB_CA<6>")
	)
	(segment
		(start 185.303414 -248.074942)
		(end 185.19013 -248.188226)
		(width 0.18288)
		(layer "In4.Cu")
		(net "M_G_CPU1_SB_CA<6>")
	)
	(segment
		(start 142.607284 -246.668544)
		(end 141.431264 -247.844564)
		(width 0.18288)
		(layer "In4.Cu")
		(net "M_G_CPU1_SB_CA<6>")
	)
	(segment
		(start 185.19013 -248.188226)
		(end 183.075834 -248.188226)
		(width 0.18288)
		(layer "In4.Cu")
		(net "M_G_CPU1_SB_CA<6>")
	)
	(segment
		(start 181.185312 -248.40311)
		(end 181.002432 -248.22023)
		(width 0.18288)
		(layer "In4.Cu")
		(net "M_G_CPU1_SB_CA<6>")
	)
	(segment
		(start 181.512972 -248.40311)
		(end 181.185312 -248.40311)
		(width 0.18288)
		(layer "In4.Cu")
		(net "M_G_CPU1_SB_CA<6>")
	)
	(segment
		(start 148.44522 -246.668544)
		(end 142.607284 -246.668544)
		(width 0.18288)
		(layer "In4.Cu")
		(net "M_G_CPU1_SB_CA<6>")
	)
	(segment
		(start 185.463434 -247.41378)
		(end 185.303414 -247.5738)
		(width 0.18288)
		(layer "In4.Cu")
		(net "M_G_CPU1_SB_CA<6>")
	)
	(segment
		(start 175.462946 -247.731026)
		(end 173.296326 -247.731026)
		(width 0.18288)
		(layer "In4.Cu")
		(net "M_G_CPU1_SB_CA<6>")
	)
	(segment
		(start 186.809126 -248.50598)
		(end 186.667394 -248.647712)
		(width 0.18288)
		(layer "In4.Cu")
		(net "M_G_CPU1_SB_CA<6>")
	)
	(segment
		(start 157.973776 -247.89257)
		(end 154.837892 -246.593614)
		(width 0.18288)
		(layer "In4.Cu")
		(net "M_G_CPU1_SB_CA<6>")
	)
	(segment
		(start 177.385726 -248.112026)
		(end 177.16627 -247.89257)
		(width 0.18288)
		(layer "In4.Cu")
		(net "M_G_CPU1_SB_CA<6>")
	)
	(segment
		(start 177.79365 -247.929146)
		(end 177.61077 -248.112026)
		(width 0.18288)
		(layer "In4.Cu")
		(net "M_G_CPU1_SB_CA<6>")
	)
	(segment
		(start 177.61077 -248.112026)
		(end 177.385726 -248.112026)
		(width 0.18288)
		(layer "In4.Cu")
		(net "M_G_CPU1_SB_CA<6>")
	)
	(segment
		(start 179.62626 -247.590564)
		(end 179.104798 -248.112026)
		(width 0.18288)
		(layer "In4.Cu")
		(net "M_G_CPU1_SB_CA<6>")
	)
	(segment
		(start 176.326546 -248.114566)
		(end 175.846486 -248.114566)
		(width 0.18288)
		(layer "In4.Cu")
		(net "M_G_CPU1_SB_CA<6>")
	)
	(segment
		(start 130.15341 -247.66778)
		(end 130.075178 -247.622568)
		(width 0.088646)
		(layer "In4.Cu")
		(net "M_G_CPU1_SB_CA<6>")
	)
	(segment
		(start 133.92785 -247.676416)
		(end 133.913118 -247.66778)
		(width 0.088646)
		(layer "In4.Cu")
		(net "M_G_CPU1_SB_CA<6>")
	)
	(segment
		(start 132.598668 -247.66778)
		(end 132.588254 -247.673876)
		(width 0.088646)
		(layer "In4.Cu")
		(net "M_G_CPU1_SB_CA<6>")
	)
	(segment
		(start 182.478172 -247.590564)
		(end 181.878732 -247.590564)
		(width 0.18288)
		(layer "In4.Cu")
		(net "M_G_CPU1_SB_CA<6>")
	)
	(segment
		(start 183.075834 -248.188226)
		(end 182.478172 -247.590564)
		(width 0.18288)
		(layer "In4.Cu")
		(net "M_G_CPU1_SB_CA<6>")
	)
	(segment
		(start 132.987796 -247.676416)
		(end 132.973064 -247.66778)
		(width 0.088646)
		(layer "In4.Cu")
		(net "M_G_CPU1_SB_CA<6>")
	)
	(segment
		(start 187.883546 -247.736106)
		(end 187.71616 -247.903492)
		(width 0.18288)
		(layer "In4.Cu")
		(net "M_G_CPU1_SB_CA<6>")
	)
	(segment
		(start 180.819552 -247.590564)
		(end 179.62626 -247.590564)
		(width 0.18288)
		(layer "In4.Cu")
		(net "M_G_CPU1_SB_CA<6>")
	)
	(segment
		(start 187.71616 -247.903492)
		(end 186.99226 -247.903492)
		(width 0.18288)
		(layer "In4.Cu")
		(net "M_G_CPU1_SB_CA<6>")
	)
	(segment
		(start 137.432034 -247.844564)
		(end 137.378694 -247.791224)
		(width 0.088646)
		(layer "In4.Cu")
		(net "M_G_CPU1_SB_CA<6>")
	)
	(segment
		(start 134.863332 -247.673876)
		(end 134.852918 -247.66778)
		(width 0.088646)
		(layer "In4.Cu")
		(net "M_G_CPU1_SB_CA<6>")
	)
	(segment
		(start 177.16627 -247.89257)
		(end 176.548542 -247.89257)
		(width 0.18288)
		(layer "In4.Cu")
		(net "M_G_CPU1_SB_CA<6>")
	)
	(segment
		(start 135.949944 -247.791224)
		(end 135.87857 -247.735344)
		(width 0.088646)
		(layer "In4.Cu")
		(net "M_G_CPU1_SB_CA<6>")
	)
	(segment
		(start 176.548542 -247.89257)
		(end 176.326546 -248.114566)
		(width 0.18288)
		(layer "In4.Cu")
		(net "M_G_CPU1_SB_CA<6>")
	)
	(segment
		(start 137.378694 -247.791224)
		(end 135.949944 -247.791224)
		(width 0.088646)
		(layer "In4.Cu")
		(net "M_G_CPU1_SB_CA<6>")
	)
	(segment
		(start 187.883546 -247.466612)
		(end 187.883546 -247.736106)
		(width 0.18288)
		(layer "In4.Cu")
		(net "M_G_CPU1_SB_CA<6>")
	)
	(segment
		(start 173.296326 -247.731026)
		(end 173.134782 -247.89257)
		(width 0.18288)
		(layer "In4.Cu")
		(net "M_G_CPU1_SB_CA<6>")
	)
	(segment
		(start 186.072526 -248.469404)
		(end 186.072526 -247.5738)
		(width 0.18288)
		(layer "In4.Cu")
		(net "M_G_CPU1_SB_CA<6>")
	)
	(segment
		(start 186.809126 -248.086626)
		(end 186.809126 -248.50598)
		(width 0.18288)
		(layer "In4.Cu")
		(net "M_G_CPU1_SB_CA<6>")
	)
	(segment
		(start 154.837892 -246.593614)
		(end 148.52015 -246.593614)
		(width 0.18288)
		(layer "In4.Cu")
		(net "M_G_CPU1_SB_CA<6>")
	)
	(segment
		(start 186.250834 -248.647712)
		(end 186.072526 -248.469404)
		(width 0.18288)
		(layer "In4.Cu")
		(net "M_G_CPU1_SB_CA<6>")
	)
	(segment
		(start 181.695852 -248.22023)
		(end 181.512972 -248.40311)
		(width 0.18288)
		(layer "In4.Cu")
		(net "M_G_CPU1_SB_CA<6>")
	)
	(segment
		(start 148.52015 -246.593614)
		(end 148.44522 -246.668544)
		(width 0.18288)
		(layer "In4.Cu")
		(net "M_G_CPU1_SB_CA<6>")
	)
	(segment
		(start 178.48707 -247.929146)
		(end 178.48707 -247.575832)
		(width 0.18288)
		(layer "In4.Cu")
		(net "M_G_CPU1_SB_CA<6>")
	)
	(segment
		(start 175.846486 -248.114566)
		(end 175.462946 -247.731026)
		(width 0.18288)
		(layer "In4.Cu")
		(net "M_G_CPU1_SB_CA<6>")
	)
	(segment
		(start 135.870442 -247.727216)
		(end 135.870442 -247.726962)
		(width 0.088646)
		(layer "In4.Cu")
		(net "M_G_CPU1_SB_CA<6>")
	)
	(segment
		(start 133.913118 -247.66778)
		(end 133.904736 -247.662954)
		(width 0.088646)
		(layer "In4.Cu")
		(net "M_G_CPU1_SB_CA<6>")
	)
	(segment
		(start 186.99226 -247.903492)
		(end 186.809126 -248.086626)
		(width 0.18288)
		(layer "In4.Cu")
		(net "M_G_CPU1_SB_CA<6>")
	)
	(segment
		(start 135.87857 -247.735344)
		(end 135.870442 -247.727216)
		(width 0.088646)
		(layer "In4.Cu")
		(net "M_G_CPU1_SB_CA<6>")
	)
	(segment
		(start 177.97653 -247.392952)
		(end 177.79365 -247.575832)
		(width 0.18288)
		(layer "In4.Cu")
		(net "M_G_CPU1_SB_CA<6>")
	)
	(segment
		(start 178.66995 -248.112026)
		(end 178.48707 -247.929146)
		(width 0.18288)
		(layer "In4.Cu")
		(net "M_G_CPU1_SB_CA<6>")
	)
	(segment
		(start 181.002432 -248.22023)
		(end 181.002432 -247.773444)
		(width 0.18288)
		(layer "In4.Cu")
		(net "M_G_CPU1_SB_CA<6>")
	)
	(segment
		(start 179.104798 -248.112026)
		(end 178.66995 -248.112026)
		(width 0.18288)
		(layer "In4.Cu")
		(net "M_G_CPU1_SB_CA<6>")
	)
	(segment
		(start 186.072526 -247.5738)
		(end 185.912506 -247.41378)
		(width 0.18288)
		(layer "In4.Cu")
		(net "M_G_CPU1_SB_CA<6>")
	)
	(segment
		(start 130.719068 -247.66778)
		(end 130.708654 -247.673876)
		(width 0.088646)
		(layer "In4.Cu")
		(net "M_G_CPU1_SB_CA<6>")
	)
	(segment
		(start 181.878732 -247.590564)
		(end 181.695852 -247.773444)
		(width 0.18288)
		(layer "In4.Cu")
		(net "M_G_CPU1_SB_CA<6>")
	)
	(segment
		(start 181.695852 -247.773444)
		(end 181.695852 -248.22023)
		(width 0.18288)
		(layer "In4.Cu")
		(net "M_G_CPU1_SB_CA<6>")
	)
	(segment
		(start 131.103878 -247.673876)
		(end 131.093464 -247.66778)
		(width 0.088646)
		(layer "In4.Cu")
		(net "M_G_CPU1_SB_CA<6>")
	)
	(segment
		(start 181.002432 -247.773444)
		(end 180.819552 -247.590564)
		(width 0.18288)
		(layer "In4.Cu")
		(net "M_G_CPU1_SB_CA<6>")
	)
	(segment
		(start 173.134782 -247.89257)
		(end 157.973776 -247.89257)
		(width 0.18288)
		(layer "In4.Cu")
		(net "M_G_CPU1_SB_CA<6>")
	)
	(segment
		(start 177.79365 -247.575832)
		(end 177.79365 -247.929146)
		(width 0.18288)
		(layer "In4.Cu")
		(net "M_G_CPU1_SB_CA<6>")
	)
	(segment
		(start 186.667394 -248.647712)
		(end 186.250834 -248.647712)
		(width 0.18288)
		(layer "In4.Cu")
		(net "M_G_CPU1_SB_CA<6>")
	)
	(segment
		(start 185.303414 -247.5738)
		(end 185.303414 -248.074942)
		(width 0.18288)
		(layer "In4.Cu")
		(net "M_G_CPU1_SB_CA<6>")
	)
	(arc
		(start 133.904736 -247.662954)
		(mid 133.720974 -247.617554)
		(end 133.538468 -247.66778)
		(width 0.088646)
		(layer "In4.Cu")
		(net "M_G_CPU1_SB_CA<6>")
	)
	(arc
		(start 132.03301 -247.66778)
		(mid 131.845812 -247.617637)
		(end 131.658614 -247.66778)
		(width 0.088646)
		(layer "In4.Cu")
		(net "M_G_CPU1_SB_CA<6>")
	)
	(arc
		(start 132.973064 -247.66778)
		(mid 132.785866 -247.617637)
		(end 132.598668 -247.66778)
		(width 0.088646)
		(layer "In4.Cu")
		(net "M_G_CPU1_SB_CA<6>")
	)
	(arc
		(start 133.538468 -247.66778)
		(mid 133.264269 -247.743615)
		(end 132.987796 -247.676416)
		(width 0.088646)
		(layer "In4.Cu")
		(net "M_G_CPU1_SB_CA<6>")
	)
	(arc
		(start 135.418068 -247.66778)
		(mid 135.141509 -247.743523)
		(end 134.863332 -247.673876)
		(width 0.088646)
		(layer "In4.Cu")
		(net "M_G_CPU1_SB_CA<6>")
	)
	(arc
		(start 135.870442 -247.726962)
		(mid 135.833392 -247.694816)
		(end 135.792464 -247.66778)
		(width 0.088646)
		(layer "In4.Cu")
		(net "M_G_CPU1_SB_CA<6>")
	)
	(arc
		(start 134.852918 -247.66778)
		(mid 134.66572 -247.617637)
		(end 134.478522 -247.66778)
		(width 0.088646)
		(layer "In4.Cu")
		(net "M_G_CPU1_SB_CA<6>")
	)
	(arc
		(start 130.708654 -247.673876)
		(mid 130.430222 -247.743722)
		(end 130.15341 -247.66778)
		(width 0.088646)
		(layer "In4.Cu")
		(net "M_G_CPU1_SB_CA<6>")
	)
	(arc
		(start 131.658614 -247.66778)
		(mid 131.382055 -247.743523)
		(end 131.103878 -247.673876)
		(width 0.088646)
		(layer "In4.Cu")
		(net "M_G_CPU1_SB_CA<6>")
	)
	(arc
		(start 131.093464 -247.66778)
		(mid 130.906266 -247.617637)
		(end 130.719068 -247.66778)
		(width 0.088646)
		(layer "In4.Cu")
		(net "M_G_CPU1_SB_CA<6>")
	)
	(arc
		(start 130.075178 -247.622568)
		(mid 129.771338 -247.419374)
		(end 129.496566 -247.178322)
		(width 0.088646)
		(layer "In4.Cu")
		(net "M_G_CPU1_SB_CA<6>")
	)
	(arc
		(start 132.588254 -247.673876)
		(mid 132.309822 -247.743722)
		(end 132.03301 -247.66778)
		(width 0.088646)
		(layer "In4.Cu")
		(net "M_G_CPU1_SB_CA<6>")
	)
	(arc
		(start 134.478522 -247.66778)
		(mid 134.204323 -247.743615)
		(end 133.92785 -247.676416)
		(width 0.088646)
		(layer "In4.Cu")
		(net "M_G_CPU1_SB_CA<6>")
	)
	(arc
		(start 135.792464 -247.66778)
		(mid 135.605266 -247.617637)
		(end 135.418068 -247.66778)
		(width 0.088646)
		(layer "In4.Cu")
		(net "M_G_CPU1_SB_CA<6>")
	)
	(segment
		(start 199.0852 -247.884188)
		(end 199.517762 -248.31675)
		(width 0.20066)
		(layer "F.Cu")
		(net "M_G_CPU1_SB_CA<5>")
	)
	(segment
		(start 193.088514 -248.31675)
		(end 194.724274 -248.31675)
		(width 0.20066)
		(layer "F.Cu")
		(net "M_G_CPU1_SB_CA<5>")
	)
	(segment
		(start 194.724274 -248.31675)
		(end 195.159884 -248.75236)
		(width 0.20066)
		(layer "F.Cu")
		(net "M_G_CPU1_SB_CA<5>")
	)
	(segment
		(start 198.681594 -247.884188)
		(end 199.0852 -247.884188)
		(width 0.20066)
		(layer "F.Cu")
		(net "M_G_CPU1_SB_CA<5>")
	)
	(segment
		(start 195.159884 -248.75236)
		(end 195.510658 -248.75236)
		(width 0.20066)
		(layer "F.Cu")
		(net "M_G_CPU1_SB_CA<5>")
	)
	(segment
		(start 195.510658 -248.75236)
		(end 195.515484 -248.75236)
		(width 0.101854)
		(layer "F.Cu")
		(net "M_G_CPU1_SB_CA<5>")
	)
	(segment
		(start 131.846066 -248.528078)
		(end 131.846066 -247.992392)
		(width 0.20066)
		(layer "F.Cu")
		(net "M_G_CPU1_SB_CA<5>")
	)
	(segment
		(start 131.846066 -247.992392)
		(end 131.845812 -247.992138)
		(width 0.20066)
		(layer "F.Cu")
		(net "M_G_CPU1_SB_CA<5>")
	)
	(segment
		(start 195.515484 -248.75236)
		(end 195.526152 -248.741692)
		(width 0.1016)
		(layer "F.Cu")
		(net "M_G_CPU1_SB_CA<5>")
	)
	(segment
		(start 197.542658 -248.749058)
		(end 197.816724 -248.749058)
		(width 0.20066)
		(layer "F.Cu")
		(net "M_G_CPU1_SB_CA<5>")
	)
	(segment
		(start 197.535292 -248.741692)
		(end 197.542658 -248.749058)
		(width 0.1016)
		(layer "F.Cu")
		(net "M_G_CPU1_SB_CA<5>")
	)
	(segment
		(start 197.816724 -248.749058)
		(end 198.681594 -247.884188)
		(width 0.20066)
		(layer "F.Cu")
		(net "M_G_CPU1_SB_CA<5>")
	)
	(segment
		(start 195.526152 -248.741692)
		(end 197.535292 -248.741692)
		(width 0.1016)
		(layer "F.Cu")
		(net "M_G_CPU1_SB_CA<5>")
	)
	(segment
		(start 191.983614 -248.31675)
		(end 193.088514 -248.31675)
		(width 0.20066)
		(layer "F.Cu")
		(net "M_G_CPU1_SB_CA<5>")
	)
	(segment
		(start 199.517762 -248.31675)
		(end 200.632314 -248.31675)
		(width 0.20066)
		(layer "F.Cu")
		(net "M_G_CPU1_SB_CA<5>")
	)
	(segment
		(start 157.570678 -248.742454)
		(end 153.584656 -247.091454)
		(width 0.18288)
		(layer "In4.Cu")
		(net "M_G_CPU1_SB_CA<5>")
	)
	(segment
		(start 193.519552 -249.590814)
		(end 189.35192 -249.590814)
		(width 0.18288)
		(layer "In4.Cu")
		(net "M_G_CPU1_SB_CA<5>")
	)
	(segment
		(start 137.82675 -248.216928)
		(end 137.800334 -248.216928)
		(width 0.088646)
		(layer "In4.Cu")
		(net "M_G_CPU1_SB_CA<5>")
	)
	(segment
		(start 149.556978 -247.091454)
		(end 149.469348 -247.003824)
		(width 0.18288)
		(layer "In4.Cu")
		(net "M_G_CPU1_SB_CA<5>")
	)
	(segment
		(start 134.478522 -248.316496)
		(end 134.478268 -248.316496)
		(width 0.088646)
		(layer "In4.Cu")
		(net "M_G_CPU1_SB_CA<5>")
	)
	(segment
		(start 175.499522 -248.74093)
		(end 175.341026 -248.899426)
		(width 0.18288)
		(layer "In4.Cu")
		(net "M_G_CPU1_SB_CA<5>")
	)
	(segment
		(start 173.165262 -248.742708)
		(end 172.928026 -248.742708)
		(width 0.18288)
		(layer "In4.Cu")
		(net "M_G_CPU1_SB_CA<5>")
	)
	(segment
		(start 157.785816 -248.742708)
		(end 157.785562 -248.742454)
		(width 0.18288)
		(layer "In4.Cu")
		(net "M_G_CPU1_SB_CA<5>")
	)
	(segment
		(start 185.373772 -248.696226)
		(end 183.522874 -248.696226)
		(width 0.18288)
		(layer "In4.Cu")
		(net "M_G_CPU1_SB_CA<5>")
	)
	(segment
		(start 187.093098 -249.3899)
		(end 186.841384 -249.641614)
		(width 0.18288)
		(layer "In4.Cu")
		(net "M_G_CPU1_SB_CA<5>")
	)
	(segment
		(start 188.236098 -248.74093)
		(end 187.491624 -248.74093)
		(width 0.18288)
		(layer "In4.Cu")
		(net "M_G_CPU1_SB_CA<5>")
	)
	(segment
		(start 183.29529 -248.92381)
		(end 180.03901 -248.92381)
		(width 0.18288)
		(layer "In4.Cu")
		(net "M_G_CPU1_SB_CA<5>")
	)
	(segment
		(start 177.746152 -248.648982)
		(end 177.652426 -248.742708)
		(width 0.18288)
		(layer "In4.Cu")
		(net "M_G_CPU1_SB_CA<5>")
	)
	(segment
		(start 187.093098 -249.139456)
		(end 187.093098 -249.3899)
		(width 0.18288)
		(layer "In4.Cu")
		(net "M_G_CPU1_SB_CA<5>")
	)
	(segment
		(start 191.983614 -248.31675)
		(end 192.23609 -248.569226)
		(width 0.18288)
		(layer "In4.Cu")
		(net "M_G_CPU1_SB_CA<5>")
	)
	(segment
		(start 193.711576 -248.748042)
		(end 193.711576 -249.39879)
		(width 0.18288)
		(layer "In4.Cu")
		(net "M_G_CPU1_SB_CA<5>")
	)
	(segment
		(start 172.926248 -248.74093)
		(end 172.635926 -248.74093)
		(width 0.18288)
		(layer "In4.Cu")
		(net "M_G_CPU1_SB_CA<5>")
	)
	(segment
		(start 179.764182 -248.648982)
		(end 177.746152 -248.648982)
		(width 0.18288)
		(layer "In4.Cu")
		(net "M_G_CPU1_SB_CA<5>")
	)
	(segment
		(start 192.23609 -248.569226)
		(end 193.53276 -248.569226)
		(width 0.18288)
		(layer "In4.Cu")
		(net "M_G_CPU1_SB_CA<5>")
	)
	(segment
		(start 177.093626 -248.742708)
		(end 177.091848 -248.74093)
		(width 0.18288)
		(layer "In4.Cu")
		(net "M_G_CPU1_SB_CA<5>")
	)
	(segment
		(start 137.800334 -248.216928)
		(end 137.796524 -248.213118)
		(width 0.088646)
		(layer "In4.Cu")
		(net "M_G_CPU1_SB_CA<5>")
	)
	(segment
		(start 188.623194 -249.865134)
		(end 188.440314 -249.682254)
		(width 0.18288)
		(layer "In4.Cu")
		(net "M_G_CPU1_SB_CA<5>")
	)
	(segment
		(start 132.598668 -248.316496)
		(end 132.213096 -248.091452)
		(width 0.088646)
		(layer "In4.Cu")
		(net "M_G_CPU1_SB_CA<5>")
	)
	(segment
		(start 189.0776 -249.865134)
		(end 188.623194 -249.865134)
		(width 0.18288)
		(layer "In4.Cu")
		(net "M_G_CPU1_SB_CA<5>")
	)
	(segment
		(start 137.796524 -248.213118)
		(end 136.178544 -248.213118)
		(width 0.088646)
		(layer "In4.Cu")
		(net "M_G_CPU1_SB_CA<5>")
	)
	(segment
		(start 180.03901 -248.92381)
		(end 179.764182 -248.648982)
		(width 0.18288)
		(layer "In4.Cu")
		(net "M_G_CPU1_SB_CA<5>")
	)
	(segment
		(start 177.652426 -248.742708)
		(end 177.093626 -248.742708)
		(width 0.18288)
		(layer "In4.Cu")
		(net "M_G_CPU1_SB_CA<5>")
	)
	(segment
		(start 189.35192 -249.590814)
		(end 189.0776 -249.865134)
		(width 0.18288)
		(layer "In4.Cu")
		(net "M_G_CPU1_SB_CA<5>")
	)
	(segment
		(start 188.440314 -249.682254)
		(end 188.440314 -248.945146)
		(width 0.18288)
		(layer "In4.Cu")
		(net "M_G_CPU1_SB_CA<5>")
	)
	(segment
		(start 172.928026 -248.742708)
		(end 172.926248 -248.74093)
		(width 0.18288)
		(layer "In4.Cu")
		(net "M_G_CPU1_SB_CA<5>")
	)
	(segment
		(start 193.53276 -248.569226)
		(end 193.711576 -248.748042)
		(width 0.18288)
		(layer "In4.Cu")
		(net "M_G_CPU1_SB_CA<5>")
	)
	(segment
		(start 172.635926 -248.74093)
		(end 172.634148 -248.742708)
		(width 0.18288)
		(layer "In4.Cu")
		(net "M_G_CPU1_SB_CA<5>")
	)
	(segment
		(start 173.32198 -248.899426)
		(end 173.165262 -248.742708)
		(width 0.18288)
		(layer "In4.Cu")
		(net "M_G_CPU1_SB_CA<5>")
	)
	(segment
		(start 186.31916 -249.641614)
		(end 185.373772 -248.696226)
		(width 0.18288)
		(layer "In4.Cu")
		(net "M_G_CPU1_SB_CA<5>")
	)
	(segment
		(start 157.785562 -248.742454)
		(end 157.570678 -248.742454)
		(width 0.18288)
		(layer "In4.Cu")
		(net "M_G_CPU1_SB_CA<5>")
	)
	(segment
		(start 153.584656 -247.091454)
		(end 149.556978 -247.091454)
		(width 0.18288)
		(layer "In4.Cu")
		(net "M_G_CPU1_SB_CA<5>")
	)
	(segment
		(start 186.841384 -249.641614)
		(end 186.31916 -249.641614)
		(width 0.18288)
		(layer "In4.Cu")
		(net "M_G_CPU1_SB_CA<5>")
	)
	(segment
		(start 183.522874 -248.696226)
		(end 183.29529 -248.92381)
		(width 0.18288)
		(layer "In4.Cu")
		(net "M_G_CPU1_SB_CA<5>")
	)
	(segment
		(start 142.746476 -247.003824)
		(end 141.533372 -248.216928)
		(width 0.18288)
		(layer "In4.Cu")
		(net "M_G_CPU1_SB_CA<5>")
	)
	(segment
		(start 132.213096 -248.091452)
		(end 131.845812 -247.992138)
		(width 0.088646)
		(layer "In4.Cu")
		(net "M_G_CPU1_SB_CA<5>")
	)
	(segment
		(start 141.533372 -248.216928)
		(end 137.82675 -248.216928)
		(width 0.18288)
		(layer "In4.Cu")
		(net "M_G_CPU1_SB_CA<5>")
	)
	(segment
		(start 177.091848 -248.74093)
		(end 175.499522 -248.74093)
		(width 0.18288)
		(layer "In4.Cu")
		(net "M_G_CPU1_SB_CA<5>")
	)
	(segment
		(start 193.711576 -249.39879)
		(end 193.519552 -249.590814)
		(width 0.18288)
		(layer "In4.Cu")
		(net "M_G_CPU1_SB_CA<5>")
	)
	(segment
		(start 149.469348 -247.003824)
		(end 142.746476 -247.003824)
		(width 0.18288)
		(layer "In4.Cu")
		(net "M_G_CPU1_SB_CA<5>")
	)
	(segment
		(start 175.341026 -248.899426)
		(end 173.32198 -248.899426)
		(width 0.18288)
		(layer "In4.Cu")
		(net "M_G_CPU1_SB_CA<5>")
	)
	(segment
		(start 188.440314 -248.945146)
		(end 188.236098 -248.74093)
		(width 0.18288)
		(layer "In4.Cu")
		(net "M_G_CPU1_SB_CA<5>")
	)
	(segment
		(start 187.491624 -248.74093)
		(end 187.093098 -249.139456)
		(width 0.18288)
		(layer "In4.Cu")
		(net "M_G_CPU1_SB_CA<5>")
	)
	(segment
		(start 135.418068 -248.316496)
		(end 135.407654 -248.3104)
		(width 0.088646)
		(layer "In4.Cu")
		(net "M_G_CPU1_SB_CA<5>")
	)
	(segment
		(start 172.634148 -248.742708)
		(end 157.785816 -248.742708)
		(width 0.18288)
		(layer "In4.Cu")
		(net "M_G_CPU1_SB_CA<5>")
	)
	(arc
		(start 134.478268 -248.316496)
		(mid 134.195566 -248.240754)
		(end 133.912864 -248.316496)
		(width 0.088646)
		(layer "In4.Cu")
		(net "M_G_CPU1_SB_CA<5>")
	)
	(arc
		(start 134.852918 -248.316496)
		(mid 134.66572 -248.366639)
		(end 134.478522 -248.316496)
		(width 0.088646)
		(layer "In4.Cu")
		(net "M_G_CPU1_SB_CA<5>")
	)
	(arc
		(start 135.407654 -248.3104)
		(mid 135.129476 -248.240708)
		(end 134.852918 -248.316496)
		(width 0.088646)
		(layer "In4.Cu")
		(net "M_G_CPU1_SB_CA<5>")
	)
	(arc
		(start 136.178544 -248.213118)
		(mid 135.978712 -248.239424)
		(end 135.792464 -248.316496)
		(width 0.088646)
		(layer "In4.Cu")
		(net "M_G_CPU1_SB_CA<5>")
	)
	(arc
		(start 133.538468 -248.316496)
		(mid 133.255766 -248.240754)
		(end 132.973064 -248.316496)
		(width 0.088646)
		(layer "In4.Cu")
		(net "M_G_CPU1_SB_CA<5>")
	)
	(arc
		(start 132.973064 -248.316496)
		(mid 132.785866 -248.366639)
		(end 132.598668 -248.316496)
		(width 0.088646)
		(layer "In4.Cu")
		(net "M_G_CPU1_SB_CA<5>")
	)
	(arc
		(start 135.792464 -248.316496)
		(mid 135.605266 -248.366639)
		(end 135.418068 -248.316496)
		(width 0.088646)
		(layer "In4.Cu")
		(net "M_G_CPU1_SB_CA<5>")
	)
	(arc
		(start 133.912864 -248.316496)
		(mid 133.725666 -248.366639)
		(end 133.538468 -248.316496)
		(width 0.088646)
		(layer "In4.Cu")
		(net "M_G_CPU1_SB_CA<5>")
	)
	(segment
		(start 129.966466 -248.528078)
		(end 129.966466 -247.992392)
		(width 0.20066)
		(layer "F.Cu")
		(net "M_G_CPU1_SB_CA<4>")
	)
	(segment
		(start 191.900302 -249.591576)
		(end 191.914018 -249.591576)
		(width 0.101854)
		(layer "F.Cu")
		(net "M_G_CPU1_SB_CA<4>")
	)
	(segment
		(start 187.883546 -249.166634)
		(end 188.988446 -249.166634)
		(width 0.20066)
		(layer "F.Cu")
		(net "M_G_CPU1_SB_CA<4>")
	)
	(segment
		(start 194.098926 -249.604022)
		(end 194.514978 -249.604022)
		(width 0.20066)
		(layer "F.Cu")
		(net "M_G_CPU1_SB_CA<4>")
	)
	(segment
		(start 194.08648 -249.591576)
		(end 194.098926 -249.604022)
		(width 0.1016)
		(layer "F.Cu")
		(net "M_G_CPU1_SB_CA<4>")
	)
	(segment
		(start 194.95262 -249.16638)
		(end 196.531992 -249.16638)
		(width 0.20066)
		(layer "F.Cu")
		(net "M_G_CPU1_SB_CA<4>")
	)
	(segment
		(start 129.966466 -247.992392)
		(end 129.966212 -247.992138)
		(width 0.20066)
		(layer "F.Cu")
		(net "M_G_CPU1_SB_CA<4>")
	)
	(segment
		(start 194.514978 -249.604022)
		(end 194.95262 -249.16638)
		(width 0.20066)
		(layer "F.Cu")
		(net "M_G_CPU1_SB_CA<4>")
	)
	(segment
		(start 188.988446 -249.166634)
		(end 190.053976 -249.166634)
		(width 0.20066)
		(layer "F.Cu")
		(net "M_G_CPU1_SB_CA<4>")
	)
	(segment
		(start 190.54826 -248.67235)
		(end 190.873634 -248.67235)
		(width 0.20066)
		(layer "F.Cu")
		(net "M_G_CPU1_SB_CA<4>")
	)
	(segment
		(start 190.873634 -248.67235)
		(end 191.79286 -249.591576)
		(width 0.20066)
		(layer "F.Cu")
		(net "M_G_CPU1_SB_CA<4>")
	)
	(segment
		(start 191.914018 -249.591576)
		(end 194.08648 -249.591576)
		(width 0.1016)
		(layer "F.Cu")
		(net "M_G_CPU1_SB_CA<4>")
	)
	(segment
		(start 196.531992 -249.16638)
		(end 196.532246 -249.166634)
		(width 0.20066)
		(layer "F.Cu")
		(net "M_G_CPU1_SB_CA<4>")
	)
	(segment
		(start 190.053976 -249.166634)
		(end 190.54826 -248.67235)
		(width 0.20066)
		(layer "F.Cu")
		(net "M_G_CPU1_SB_CA<4>")
	)
	(segment
		(start 191.79286 -249.591576)
		(end 191.900302 -249.591576)
		(width 0.20066)
		(layer "F.Cu")
		(net "M_G_CPU1_SB_CA<4>")
	)
	(segment
		(start 132.503164 -248.48185)
		(end 132.359654 -248.399046)
		(width 0.088646)
		(layer "In4.Cu")
		(net "M_G_CPU1_SB_CA<4>")
	)
	(segment
		(start 135.333232 -248.487946)
		(end 135.322818 -248.48185)
		(width 0.088646)
		(layer "In4.Cu")
		(net "M_G_CPU1_SB_CA<4>")
	)
	(segment
		(start 187.58916 -249.605546)
		(end 186.76366 -250.431046)
		(width 0.18288)
		(layer "In4.Cu")
		(net "M_G_CPU1_SB_CA<4>")
	)
	(segment
		(start 131.141216 -248.399046)
		(end 131.141216 -248.3993)
		(width 0.088646)
		(layer "In4.Cu")
		(net "M_G_CPU1_SB_CA<4>")
	)
	(segment
		(start 149.101048 -247.339612)
		(end 142.884906 -247.339612)
		(width 0.18288)
		(layer "In4.Cu")
		(net "M_G_CPU1_SB_CA<4>")
	)
	(segment
		(start 182.014876 -249.45594)
		(end 181.831996 -249.63882)
		(width 0.18288)
		(layer "In4.Cu")
		(net "M_G_CPU1_SB_CA<4>")
	)
	(segment
		(start 138.99642 -248.556526)
		(end 137.82675 -248.556526)
		(width 0.18288)
		(layer "In4.Cu")
		(net "M_G_CPU1_SB_CA<4>")
	)
	(segment
		(start 181.831996 -250.27001)
		(end 181.649116 -250.45289)
		(width 0.18288)
		(layer "In4.Cu")
		(net "M_G_CPU1_SB_CA<4>")
	)
	(segment
		(start 178.021488 -249.775472)
		(end 177.838608 -249.592592)
		(width 0.18288)
		(layer "In4.Cu")
		(net "M_G_CPU1_SB_CA<4>")
	)
	(segment
		(start 131.611116 -248.3993)
		(end 131.610354 -248.399046)
		(width 0.088646)
		(layer "In4.Cu")
		(net "M_G_CPU1_SB_CA<4>")
	)
	(segment
		(start 178.714908 -249.775472)
		(end 178.714908 -250.55068)
		(width 0.18288)
		(layer "In4.Cu")
		(net "M_G_CPU1_SB_CA<4>")
	)
	(segment
		(start 153.58364 -247.930924)
		(end 149.69236 -247.930924)
		(width 0.18288)
		(layer "In4.Cu")
		(net "M_G_CPU1_SB_CA<4>")
	)
	(segment
		(start 179.413154 -249.592592)
		(end 178.897788 -249.592592)
		(width 0.18288)
		(layer "In4.Cu")
		(net "M_G_CPU1_SB_CA<4>")
	)
	(segment
		(start 173.169326 -249.592592)
		(end 172.17136 -249.592592)
		(width 0.18288)
		(layer "In4.Cu")
		(net "M_G_CPU1_SB_CA<4>")
	)
	(segment
		(start 180.955696 -249.45594)
		(end 179.549806 -249.45594)
		(width 0.18288)
		(layer "In4.Cu")
		(net "M_G_CPU1_SB_CA<4>")
	)
	(segment
		(start 157.785816 -249.407426)
		(end 157.785562 -249.407172)
		(width 0.18288)
		(layer "In4.Cu")
		(net "M_G_CPU1_SB_CA<4>")
	)
	(segment
		(start 175.671226 -249.432826)
		(end 173.329092 -249.432826)
		(width 0.18288)
		(layer "In4.Cu")
		(net "M_G_CPU1_SB_CA<4>")
	)
	(segment
		(start 179.549806 -249.45594)
		(end 179.413154 -249.592592)
		(width 0.18288)
		(layer "In4.Cu")
		(net "M_G_CPU1_SB_CA<4>")
	)
	(segment
		(start 177.838608 -249.592592)
		(end 175.830992 -249.592592)
		(width 0.18288)
		(layer "In4.Cu")
		(net "M_G_CPU1_SB_CA<4>")
	)
	(segment
		(start 149.69236 -247.930924)
		(end 149.101048 -247.339612)
		(width 0.18288)
		(layer "In4.Cu")
		(net "M_G_CPU1_SB_CA<4>")
	)
	(segment
		(start 187.58916 -249.46102)
		(end 187.58916 -249.605546)
		(width 0.18288)
		(layer "In4.Cu")
		(net "M_G_CPU1_SB_CA<4>")
	)
	(segment
		(start 137.295382 -248.419112)
		(end 136.120632 -248.419112)
		(width 0.088646)
		(layer "In4.Cu")
		(net "M_G_CPU1_SB_CA<4>")
	)
	(segment
		(start 183.056022 -249.451622)
		(end 182.07863 -249.451622)
		(width 0.18288)
		(layer "In4.Cu")
		(net "M_G_CPU1_SB_CA<4>")
	)
	(segment
		(start 178.021488 -250.55068)
		(end 178.021488 -249.775472)
		(width 0.18288)
		(layer "In4.Cu")
		(net "M_G_CPU1_SB_CA<4>")
	)
	(segment
		(start 181.649116 -250.45289)
		(end 181.321456 -250.45289)
		(width 0.18288)
		(layer "In4.Cu")
		(net "M_G_CPU1_SB_CA<4>")
	)
	(segment
		(start 181.321456 -250.45289)
		(end 181.138576 -250.27001)
		(width 0.18288)
		(layer "In4.Cu")
		(net "M_G_CPU1_SB_CA<4>")
	)
	(segment
		(start 178.897788 -249.592592)
		(end 178.714908 -249.775472)
		(width 0.18288)
		(layer "In4.Cu")
		(net "M_G_CPU1_SB_CA<4>")
	)
	(segment
		(start 137.82675 -248.556526)
		(end 137.432796 -248.556526)
		(width 0.088646)
		(layer "In4.Cu")
		(net "M_G_CPU1_SB_CA<4>")
	)
	(segment
		(start 178.204368 -250.73356)
		(end 178.021488 -250.55068)
		(width 0.18288)
		(layer "In4.Cu")
		(net "M_G_CPU1_SB_CA<4>")
	)
	(segment
		(start 181.138576 -249.63882)
		(end 180.955696 -249.45594)
		(width 0.18288)
		(layer "In4.Cu")
		(net "M_G_CPU1_SB_CA<4>")
	)
	(segment
		(start 164.736272 -249.39498)
		(end 164.393626 -249.737626)
		(width 0.18288)
		(layer "In4.Cu")
		(net "M_G_CPU1_SB_CA<4>")
	)
	(segment
		(start 173.329092 -249.432826)
		(end 173.169326 -249.592592)
		(width 0.18288)
		(layer "In4.Cu")
		(net "M_G_CPU1_SB_CA<4>")
	)
	(segment
		(start 132.080762 -248.399046)
		(end 132.081016 -248.3993)
		(width 0.088646)
		(layer "In4.Cu")
		(net "M_G_CPU1_SB_CA<4>")
	)
	(segment
		(start 164.393626 -249.737626)
		(end 161.18586 -249.737626)
		(width 0.18288)
		(layer "In4.Cu")
		(net "M_G_CPU1_SB_CA<4>")
	)
	(segment
		(start 181.831996 -249.63882)
		(end 181.831996 -250.27001)
		(width 0.18288)
		(layer "In4.Cu")
		(net "M_G_CPU1_SB_CA<4>")
	)
	(segment
		(start 178.532028 -250.73356)
		(end 178.204368 -250.73356)
		(width 0.18288)
		(layer "In4.Cu")
		(net "M_G_CPU1_SB_CA<4>")
	)
	(segment
		(start 142.884906 -247.339612)
		(end 141.097 -249.127518)
		(width 0.18288)
		(layer "In4.Cu")
		(net "M_G_CPU1_SB_CA<4>")
	)
	(segment
		(start 187.883546 -249.166634)
		(end 187.58916 -249.46102)
		(width 0.18288)
		(layer "In4.Cu")
		(net "M_G_CPU1_SB_CA<4>")
	)
	(segment
		(start 139.567412 -249.127518)
		(end 138.99642 -248.556526)
		(width 0.18288)
		(layer "In4.Cu")
		(net "M_G_CPU1_SB_CA<4>")
	)
	(segment
		(start 141.097 -249.127518)
		(end 139.567412 -249.127518)
		(width 0.18288)
		(layer "In4.Cu")
		(net "M_G_CPU1_SB_CA<4>")
	)
	(segment
		(start 131.624578 -248.407174)
		(end 131.611116 -248.3993)
		(width 0.088646)
		(layer "In4.Cu")
		(net "M_G_CPU1_SB_CA<4>")
	)
	(segment
		(start 185.597546 -250.431046)
		(end 184.929526 -249.763026)
		(width 0.18288)
		(layer "In4.Cu")
		(net "M_G_CPU1_SB_CA<4>")
	)
	(segment
		(start 175.830992 -249.592592)
		(end 175.671226 -249.432826)
		(width 0.18288)
		(layer "In4.Cu")
		(net "M_G_CPU1_SB_CA<4>")
	)
	(segment
		(start 183.367426 -249.763026)
		(end 183.056022 -249.451622)
		(width 0.18288)
		(layer "In4.Cu")
		(net "M_G_CPU1_SB_CA<4>")
	)
	(segment
		(start 134.948422 -248.48185)
		(end 134.938008 -248.487946)
		(width 0.088646)
		(layer "In4.Cu")
		(net "M_G_CPU1_SB_CA<4>")
	)
	(segment
		(start 157.785562 -249.407172)
		(end 157.147514 -249.407172)
		(width 0.18288)
		(layer "In4.Cu")
		(net "M_G_CPU1_SB_CA<4>")
	)
	(segment
		(start 130.671316 -248.3993)
		(end 130.671316 -248.399046)
		(width 0.088646)
		(layer "In4.Cu")
		(net "M_G_CPU1_SB_CA<4>")
	)
	(segment
		(start 168.39438 -249.39498)
		(end 164.736272 -249.39498)
		(width 0.18288)
		(layer "In4.Cu")
		(net "M_G_CPU1_SB_CA<4>")
	)
	(segment
		(start 178.714908 -250.55068)
		(end 178.532028 -250.73356)
		(width 0.18288)
		(layer "In4.Cu")
		(net "M_G_CPU1_SB_CA<4>")
	)
	(segment
		(start 186.76366 -250.431046)
		(end 185.597546 -250.431046)
		(width 0.18288)
		(layer "In4.Cu")
		(net "M_G_CPU1_SB_CA<4>")
	)
	(segment
		(start 182.07863 -249.451622)
		(end 182.074312 -249.45594)
		(width 0.18288)
		(layer "In4.Cu")
		(net "M_G_CPU1_SB_CA<4>")
	)
	(segment
		(start 130.671316 -248.399046)
		(end 129.966212 -247.992138)
		(width 0.088646)
		(layer "In4.Cu")
		(net "M_G_CPU1_SB_CA<4>")
	)
	(segment
		(start 168.864026 -249.864626)
		(end 168.39438 -249.39498)
		(width 0.18288)
		(layer "In4.Cu")
		(net "M_G_CPU1_SB_CA<4>")
	)
	(segment
		(start 182.074312 -249.45594)
		(end 182.014876 -249.45594)
		(width 0.18288)
		(layer "In4.Cu")
		(net "M_G_CPU1_SB_CA<4>")
	)
	(segment
		(start 161.18586 -249.737626)
		(end 160.85566 -249.407426)
		(width 0.18288)
		(layer "In4.Cu")
		(net "M_G_CPU1_SB_CA<4>")
	)
	(segment
		(start 157.147514 -249.407172)
		(end 153.58364 -247.930924)
		(width 0.18288)
		(layer "In4.Cu")
		(net "M_G_CPU1_SB_CA<4>")
	)
	(segment
		(start 184.929526 -249.763026)
		(end 183.367426 -249.763026)
		(width 0.18288)
		(layer "In4.Cu")
		(net "M_G_CPU1_SB_CA<4>")
	)
	(segment
		(start 137.432796 -248.556526)
		(end 137.295382 -248.419112)
		(width 0.088646)
		(layer "In4.Cu")
		(net "M_G_CPU1_SB_CA<4>")
	)
	(segment
		(start 160.85566 -249.407426)
		(end 157.785816 -249.407426)
		(width 0.18288)
		(layer "In4.Cu")
		(net "M_G_CPU1_SB_CA<4>")
	)
	(segment
		(start 171.899326 -249.864626)
		(end 168.864026 -249.864626)
		(width 0.18288)
		(layer "In4.Cu")
		(net "M_G_CPU1_SB_CA<4>")
	)
	(segment
		(start 181.138576 -250.27001)
		(end 181.138576 -249.63882)
		(width 0.18288)
		(layer "In4.Cu")
		(net "M_G_CPU1_SB_CA<4>")
	)
	(segment
		(start 172.17136 -249.592592)
		(end 171.899326 -249.864626)
		(width 0.18288)
		(layer "In4.Cu")
		(net "M_G_CPU1_SB_CA<4>")
	)
	(arc
		(start 134.938008 -248.487946)
		(mid 134.659576 -248.55776)
		(end 134.382764 -248.48185)
		(width 0.088646)
		(layer "In4.Cu")
		(net "M_G_CPU1_SB_CA<4>")
	)
	(arc
		(start 132.359654 -248.399046)
		(mid 132.220208 -248.361685)
		(end 132.080762 -248.399046)
		(width 0.088646)
		(layer "In4.Cu")
		(net "M_G_CPU1_SB_CA<4>")
	)
	(arc
		(start 132.081016 -248.3993)
		(mid 131.853829 -248.462284)
		(end 131.624578 -248.407174)
		(width 0.088646)
		(layer "In4.Cu")
		(net "M_G_CPU1_SB_CA<4>")
	)
	(arc
		(start 134.382764 -248.48185)
		(mid 134.195566 -248.431707)
		(end 134.008368 -248.48185)
		(width 0.088646)
		(layer "In4.Cu")
		(net "M_G_CPU1_SB_CA<4>")
	)
	(arc
		(start 131.610354 -248.399046)
		(mid 131.375768 -248.336145)
		(end 131.141216 -248.399046)
		(width 0.088646)
		(layer "In4.Cu")
		(net "M_G_CPU1_SB_CA<4>")
	)
	(arc
		(start 136.120632 -248.419112)
		(mid 136.000145 -248.435072)
		(end 135.887968 -248.48185)
		(width 0.088646)
		(layer "In4.Cu")
		(net "M_G_CPU1_SB_CA<4>")
	)
	(arc
		(start 135.322818 -248.48185)
		(mid 135.13562 -248.431707)
		(end 134.948422 -248.48185)
		(width 0.088646)
		(layer "In4.Cu")
		(net "M_G_CPU1_SB_CA<4>")
	)
	(arc
		(start 135.887968 -248.48185)
		(mid 135.611409 -248.557559)
		(end 135.333232 -248.487946)
		(width 0.088646)
		(layer "In4.Cu")
		(net "M_G_CPU1_SB_CA<4>")
	)
	(arc
		(start 131.141216 -248.3993)
		(mid 130.906266 -248.462226)
		(end 130.671316 -248.3993)
		(width 0.088646)
		(layer "In4.Cu")
		(net "M_G_CPU1_SB_CA<4>")
	)
	(arc
		(start 134.008368 -248.48185)
		(mid 133.725666 -248.557592)
		(end 133.442964 -248.48185)
		(width 0.088646)
		(layer "In4.Cu")
		(net "M_G_CPU1_SB_CA<4>")
	)
	(arc
		(start 133.068568 -248.48185)
		(mid 132.785866 -248.557592)
		(end 132.503164 -248.48185)
		(width 0.088646)
		(layer "In4.Cu")
		(net "M_G_CPU1_SB_CA<4>")
	)
	(arc
		(start 133.442964 -248.48185)
		(mid 133.255766 -248.431707)
		(end 133.068568 -248.48185)
		(width 0.088646)
		(layer "In4.Cu")
		(net "M_G_CPU1_SB_CA<4>")
	)
	(segment
		(start 199.517762 -250.016772)
		(end 200.632314 -250.016772)
		(width 0.20066)
		(layer "F.Cu")
		(net "M_G_CPU1_SB_CA<3>")
	)
	(segment
		(start 195.159884 -250.452382)
		(end 195.510658 -250.452382)
		(width 0.20066)
		(layer "F.Cu")
		(net "M_G_CPU1_SB_CA<3>")
	)
	(segment
		(start 195.526152 -250.441714)
		(end 197.535292 -250.441714)
		(width 0.1016)
		(layer "F.Cu")
		(net "M_G_CPU1_SB_CA<3>")
	)
	(segment
		(start 193.088514 -250.016772)
		(end 194.724274 -250.016772)
		(width 0.20066)
		(layer "F.Cu")
		(net "M_G_CPU1_SB_CA<3>")
	)
	(segment
		(start 195.510658 -250.452382)
		(end 195.515484 -250.452382)
		(width 0.101854)
		(layer "F.Cu")
		(net "M_G_CPU1_SB_CA<3>")
	)
	(segment
		(start 197.816724 -250.44908)
		(end 198.681594 -249.58421)
		(width 0.20066)
		(layer "F.Cu")
		(net "M_G_CPU1_SB_CA<3>")
	)
	(segment
		(start 195.515484 -250.452382)
		(end 195.526152 -250.441714)
		(width 0.1016)
		(layer "F.Cu")
		(net "M_G_CPU1_SB_CA<3>")
	)
	(segment
		(start 131.375912 -249.342148)
		(end 131.376166 -249.341894)
		(width 0.20066)
		(layer "F.Cu")
		(net "M_G_CPU1_SB_CA<3>")
	)
	(segment
		(start 131.376166 -249.341894)
		(end 131.376166 -248.806208)
		(width 0.20066)
		(layer "F.Cu")
		(net "M_G_CPU1_SB_CA<3>")
	)
	(segment
		(start 197.535292 -250.441714)
		(end 197.542658 -250.44908)
		(width 0.1016)
		(layer "F.Cu")
		(net "M_G_CPU1_SB_CA<3>")
	)
	(segment
		(start 194.724274 -250.016772)
		(end 195.159884 -250.452382)
		(width 0.20066)
		(layer "F.Cu")
		(net "M_G_CPU1_SB_CA<3>")
	)
	(segment
		(start 191.983614 -250.016772)
		(end 193.088514 -250.016772)
		(width 0.20066)
		(layer "F.Cu")
		(net "M_G_CPU1_SB_CA<3>")
	)
	(segment
		(start 199.0852 -249.58421)
		(end 199.517762 -250.016772)
		(width 0.20066)
		(layer "F.Cu")
		(net "M_G_CPU1_SB_CA<3>")
	)
	(segment
		(start 197.542658 -250.44908)
		(end 197.816724 -250.44908)
		(width 0.20066)
		(layer "F.Cu")
		(net "M_G_CPU1_SB_CA<3>")
	)
	(segment
		(start 198.681594 -249.58421)
		(end 199.0852 -249.58421)
		(width 0.20066)
		(layer "F.Cu")
		(net "M_G_CPU1_SB_CA<3>")
	)
	(segment
		(start 137.21461 -249.181112)
		(end 137.014966 -249.181112)
		(width 0.088646)
		(layer "In4.Cu")
		(net "M_G_CPU1_SB_CA<3>")
	)
	(segment
		(start 136.536684 -249.05462)
		(end 136.226804 -249.05462)
		(width 0.088646)
		(layer "In4.Cu")
		(net "M_G_CPU1_SB_CA<3>")
	)
	(segment
		(start 187.465462 -250.44019)
		(end 187.202826 -250.702826)
		(width 0.18288)
		(layer "In4.Cu")
		(net "M_G_CPU1_SB_CA<3>")
	)
	(segment
		(start 143.047466 -247.6754)
		(end 141.260068 -249.462798)
		(width 0.18288)
		(layer "In4.Cu")
		(net "M_G_CPU1_SB_CA<3>")
	)
	(segment
		(start 153.065226 -248.624852)
		(end 149.6568 -248.624852)
		(width 0.18288)
		(layer "In4.Cu")
		(net "M_G_CPU1_SB_CA<3>")
	)
	(segment
		(start 182.211726 -250.626626)
		(end 181.809136 -251.029216)
		(width 0.18288)
		(layer "In4.Cu")
		(net "M_G_CPU1_SB_CA<3>")
	)
	(segment
		(start 183.33847 -250.626626)
		(end 182.211726 -250.626626)
		(width 0.18288)
		(layer "In4.Cu")
		(net "M_G_CPU1_SB_CA<3>")
	)
	(segment
		(start 187.202826 -250.982226)
		(end 186.847226 -251.337826)
		(width 0.18288)
		(layer "In4.Cu")
		(net "M_G_CPU1_SB_CA<3>")
	)
	(segment
		(start 183.69407 -250.271026)
		(end 183.33847 -250.626626)
		(width 0.18288)
		(layer "In4.Cu")
		(net "M_G_CPU1_SB_CA<3>")
	)
	(segment
		(start 187.202826 -250.702826)
		(end 187.202826 -250.982226)
		(width 0.18288)
		(layer "In4.Cu")
		(net "M_G_CPU1_SB_CA<3>")
	)
	(segment
		(start 141.260068 -249.462798)
		(end 139.428474 -249.462798)
		(width 0.18288)
		(layer "In4.Cu")
		(net "M_G_CPU1_SB_CA<3>")
	)
	(segment
		(start 181.809136 -251.029216)
		(end 180.335936 -251.029216)
		(width 0.18288)
		(layer "In4.Cu")
		(net "M_G_CPU1_SB_CA<3>")
	)
	(segment
		(start 148.707348 -247.6754)
		(end 143.047466 -247.6754)
		(width 0.18288)
		(layer "In4.Cu")
		(net "M_G_CPU1_SB_CA<3>")
	)
	(segment
		(start 137.82675 -249.035316)
		(end 137.360406 -249.035316)
		(width 0.088646)
		(layer "In4.Cu")
		(net "M_G_CPU1_SB_CA<3>")
	)
	(segment
		(start 139.000992 -249.035316)
		(end 137.82675 -249.035316)
		(width 0.18288)
		(layer "In4.Cu")
		(net "M_G_CPU1_SB_CA<3>")
	)
	(segment
		(start 180.335936 -251.029216)
		(end 179.951126 -251.414026)
		(width 0.18288)
		(layer "In4.Cu")
		(net "M_G_CPU1_SB_CA<3>")
	)
	(segment
		(start 131.006088 -248.863358)
		(end 131.063238 -248.806208)
		(width 0.088646)
		(layer "In4.Cu")
		(net "M_G_CPU1_SB_CA<3>")
	)
	(segment
		(start 184.675526 -250.271026)
		(end 183.69407 -250.271026)
		(width 0.18288)
		(layer "In4.Cu")
		(net "M_G_CPU1_SB_CA<3>")
	)
	(segment
		(start 185.742326 -251.337826)
		(end 184.675526 -250.271026)
		(width 0.18288)
		(layer "In4.Cu")
		(net "M_G_CPU1_SB_CA<3>")
	)
	(segment
		(start 178.122326 -251.414026)
		(end 177.15103 -250.44273)
		(width 0.18288)
		(layer "In4.Cu")
		(net "M_G_CPU1_SB_CA<3>")
	)
	(segment
		(start 131.063238 -248.806208)
		(end 131.376166 -248.806208)
		(width 0.088646)
		(layer "In4.Cu")
		(net "M_G_CPU1_SB_CA<3>")
	)
	(segment
		(start 191.983614 -250.016772)
		(end 191.560196 -250.44019)
		(width 0.18288)
		(layer "In4.Cu")
		(net "M_G_CPU1_SB_CA<3>")
	)
	(segment
		(start 149.6568 -248.624852)
		(end 148.707348 -247.6754)
		(width 0.18288)
		(layer "In4.Cu")
		(net "M_G_CPU1_SB_CA<3>")
	)
	(segment
		(start 135.34263 -249.497596)
		(end 135.065262 -249.220228)
		(width 0.088646)
		(layer "In4.Cu")
		(net "M_G_CPU1_SB_CA<3>")
	)
	(segment
		(start 177.15103 -250.44273)
		(end 157.454092 -250.44273)
		(width 0.18288)
		(layer "In4.Cu")
		(net "M_G_CPU1_SB_CA<3>")
	)
	(segment
		(start 179.951126 -251.414026)
		(end 178.122326 -251.414026)
		(width 0.18288)
		(layer "In4.Cu")
		(net "M_G_CPU1_SB_CA<3>")
	)
	(segment
		(start 135.783828 -249.497596)
		(end 135.34263 -249.497596)
		(width 0.088646)
		(layer "In4.Cu")
		(net "M_G_CPU1_SB_CA<3>")
	)
	(segment
		(start 137.360406 -249.035316)
		(end 137.21461 -249.181112)
		(width 0.088646)
		(layer "In4.Cu")
		(net "M_G_CPU1_SB_CA<3>")
	)
	(segment
		(start 131.188968 -249.130566)
		(end 131.180078 -249.125486)
		(width 0.088646)
		(layer "In4.Cu")
		(net "M_G_CPU1_SB_CA<3>")
	)
	(segment
		(start 186.847226 -251.337826)
		(end 185.742326 -251.337826)
		(width 0.18288)
		(layer "In4.Cu")
		(net "M_G_CPU1_SB_CA<3>")
	)
	(segment
		(start 191.560196 -250.44019)
		(end 187.465462 -250.44019)
		(width 0.18288)
		(layer "In4.Cu")
		(net "M_G_CPU1_SB_CA<3>")
	)
	(segment
		(start 139.428474 -249.462798)
		(end 139.000992 -249.035316)
		(width 0.18288)
		(layer "In4.Cu")
		(net "M_G_CPU1_SB_CA<3>")
	)
	(segment
		(start 157.454092 -250.44273)
		(end 153.065226 -248.624852)
		(width 0.18288)
		(layer "In4.Cu")
		(net "M_G_CPU1_SB_CA<3>")
	)
	(segment
		(start 136.226804 -249.05462)
		(end 135.783828 -249.497596)
		(width 0.088646)
		(layer "In4.Cu")
		(net "M_G_CPU1_SB_CA<3>")
	)
	(arc
		(start 134.008368 -249.130566)
		(mid 133.725666 -249.05479)
		(end 133.442964 -249.130566)
		(width 0.088646)
		(layer "In4.Cu")
		(net "M_G_CPU1_SB_CA<3>")
	)
	(arc
		(start 131.563364 -249.130566)
		(mid 131.376166 -249.180709)
		(end 131.188968 -249.130566)
		(width 0.088646)
		(layer "In4.Cu")
		(net "M_G_CPU1_SB_CA<3>")
	)
	(arc
		(start 132.128768 -249.130566)
		(mid 131.846066 -249.05479)
		(end 131.563364 -249.130566)
		(width 0.088646)
		(layer "In4.Cu")
		(net "M_G_CPU1_SB_CA<3>")
	)
	(arc
		(start 132.503164 -249.130566)
		(mid 132.315966 -249.180709)
		(end 132.128768 -249.130566)
		(width 0.088646)
		(layer "In4.Cu")
		(net "M_G_CPU1_SB_CA<3>")
	)
	(arc
		(start 135.065262 -249.220228)
		(mid 135.009657 -249.171554)
		(end 134.948168 -249.130566)
		(width 0.088646)
		(layer "In4.Cu")
		(net "M_G_CPU1_SB_CA<3>")
	)
	(arc
		(start 131.180078 -249.125486)
		(mid 131.064269 -249.013557)
		(end 131.006088 -248.863358)
		(width 0.088646)
		(layer "In4.Cu")
		(net "M_G_CPU1_SB_CA<3>")
	)
	(arc
		(start 134.382764 -249.130566)
		(mid 134.195566 -249.180709)
		(end 134.008368 -249.130566)
		(width 0.088646)
		(layer "In4.Cu")
		(net "M_G_CPU1_SB_CA<3>")
	)
	(arc
		(start 133.442964 -249.130566)
		(mid 133.255766 -249.180709)
		(end 133.068568 -249.130566)
		(width 0.088646)
		(layer "In4.Cu")
		(net "M_G_CPU1_SB_CA<3>")
	)
	(arc
		(start 133.068568 -249.130566)
		(mid 132.785866 -249.05479)
		(end 132.503164 -249.130566)
		(width 0.088646)
		(layer "In4.Cu")
		(net "M_G_CPU1_SB_CA<3>")
	)
	(arc
		(start 136.813036 -249.12193)
		(mid 136.679162 -249.07061)
		(end 136.536684 -249.05462)
		(width 0.088646)
		(layer "In4.Cu")
		(net "M_G_CPU1_SB_CA<3>")
	)
	(arc
		(start 134.948168 -249.130566)
		(mid 134.665466 -249.05479)
		(end 134.382764 -249.130566)
		(width 0.088646)
		(layer "In4.Cu")
		(net "M_G_CPU1_SB_CA<3>")
	)
	(arc
		(start 137.014966 -249.181112)
		(mid 136.909765 -249.165975)
		(end 136.813036 -249.12193)
		(width 0.088646)
		(layer "In4.Cu")
		(net "M_G_CPU1_SB_CA<3>")
	)
	(segment
		(start 130.436366 -249.341894)
		(end 130.436366 -248.806208)
		(width 0.20066)
		(layer "F.Cu")
		(net "M_G_CPU1_SB_CA<2>")
	)
	(segment
		(start 190.873634 -250.372372)
		(end 191.79286 -251.291598)
		(width 0.20066)
		(layer "F.Cu")
		(net "M_G_CPU1_SB_CA<2>")
	)
	(segment
		(start 188.988446 -250.866656)
		(end 190.053976 -250.866656)
		(width 0.20066)
		(layer "F.Cu")
		(net "M_G_CPU1_SB_CA<2>")
	)
	(segment
		(start 196.531992 -250.866402)
		(end 196.532246 -250.866656)
		(width 0.20066)
		(layer "F.Cu")
		(net "M_G_CPU1_SB_CA<2>")
	)
	(segment
		(start 190.54826 -250.372372)
		(end 190.873634 -250.372372)
		(width 0.20066)
		(layer "F.Cu")
		(net "M_G_CPU1_SB_CA<2>")
	)
	(segment
		(start 191.900302 -251.291598)
		(end 191.914018 -251.291598)
		(width 0.101854)
		(layer "F.Cu")
		(net "M_G_CPU1_SB_CA<2>")
	)
	(segment
		(start 130.436112 -249.342148)
		(end 130.436366 -249.341894)
		(width 0.20066)
		(layer "F.Cu")
		(net "M_G_CPU1_SB_CA<2>")
	)
	(segment
		(start 194.08648 -251.291598)
		(end 194.098926 -251.304044)
		(width 0.1016)
		(layer "F.Cu")
		(net "M_G_CPU1_SB_CA<2>")
	)
	(segment
		(start 191.79286 -251.291598)
		(end 191.900302 -251.291598)
		(width 0.20066)
		(layer "F.Cu")
		(net "M_G_CPU1_SB_CA<2>")
	)
	(segment
		(start 187.883546 -250.866656)
		(end 188.988446 -250.866656)
		(width 0.20066)
		(layer "F.Cu")
		(net "M_G_CPU1_SB_CA<2>")
	)
	(segment
		(start 194.95262 -250.866402)
		(end 196.531992 -250.866402)
		(width 0.20066)
		(layer "F.Cu")
		(net "M_G_CPU1_SB_CA<2>")
	)
	(segment
		(start 191.914018 -251.291598)
		(end 194.08648 -251.291598)
		(width 0.1016)
		(layer "F.Cu")
		(net "M_G_CPU1_SB_CA<2>")
	)
	(segment
		(start 190.053976 -250.866656)
		(end 190.54826 -250.372372)
		(width 0.20066)
		(layer "F.Cu")
		(net "M_G_CPU1_SB_CA<2>")
	)
	(segment
		(start 194.098926 -251.304044)
		(end 194.514978 -251.304044)
		(width 0.20066)
		(layer "F.Cu")
		(net "M_G_CPU1_SB_CA<2>")
	)
	(segment
		(start 194.514978 -251.304044)
		(end 194.95262 -250.866402)
		(width 0.20066)
		(layer "F.Cu")
		(net "M_G_CPU1_SB_CA<2>")
	)
	(segment
		(start 169.067226 -251.673106)
		(end 168.884346 -251.490226)
		(width 0.18288)
		(layer "In4.Cu")
		(net "M_G_CPU1_SB_CA<2>")
	)
	(segment
		(start 169.760646 -251.673106)
		(end 169.760646 -251.86513)
		(width 0.18288)
		(layer "In4.Cu")
		(net "M_G_CPU1_SB_CA<2>")
	)
	(segment
		(start 170.454066 -251.86513)
		(end 170.454066 -251.673106)
		(width 0.18288)
		(layer "In4.Cu")
		(net "M_G_CPU1_SB_CA<2>")
	)
	(segment
		(start 169.760646 -251.86513)
		(end 169.577766 -252.04801)
		(width 0.18288)
		(layer "In4.Cu")
		(net "M_G_CPU1_SB_CA<2>")
	)
	(segment
		(start 181.28615 -252.288802)
		(end 180.912262 -252.288802)
		(width 0.18288)
		(layer "In4.Cu")
		(net "M_G_CPU1_SB_CA<2>")
	)
	(segment
		(start 143.291306 -248.01068)
		(end 141.449552 -249.852434)
		(width 0.18288)
		(layer "In4.Cu")
		(net "M_G_CPU1_SB_CA<2>")
	)
	(segment
		(start 160.84296 -251.464826)
		(end 160.60928 -251.231146)
		(width 0.18288)
		(layer "In4.Cu")
		(net "M_G_CPU1_SB_CA<2>")
	)
	(segment
		(start 130.749294 -248.806208)
		(end 130.436366 -248.806208)
		(width 0.088646)
		(layer "In4.Cu")
		(net "M_G_CPU1_SB_CA<2>")
	)
	(segment
		(start 136.540494 -249.245374)
		(end 136.319514 -249.245374)
		(width 0.088646)
		(layer "In4.Cu")
		(net "M_G_CPU1_SB_CA<2>")
	)
	(segment
		(start 153.152602 -249.253502)
		(end 149.57044 -249.253502)
		(width 0.18288)
		(layer "In4.Cu")
		(net "M_G_CPU1_SB_CA<2>")
	)
	(segment
		(start 169.943526 -251.490226)
		(end 169.760646 -251.673106)
		(width 0.18288)
		(layer "In4.Cu")
		(net "M_G_CPU1_SB_CA<2>")
	)
	(segment
		(start 180.035962 -252.884686)
		(end 180.035962 -252.471682)
		(width 0.18288)
		(layer "In4.Cu")
		(net "M_G_CPU1_SB_CA<2>")
	)
	(segment
		(start 172.393864 -251.490226)
		(end 171.330366 -251.490226)
		(width 0.18288)
		(layer "In4.Cu")
		(net "M_G_CPU1_SB_CA<2>")
	)
	(segment
		(start 179.342542 -252.884686)
		(end 179.159662 -253.067566)
		(width 0.18288)
		(layer "In4.Cu")
		(net "M_G_CPU1_SB_CA<2>")
	)
	(segment
		(start 139.15771 -249.852434)
		(end 138.677142 -249.371866)
		(width 0.18288)
		(layer "In4.Cu")
		(net "M_G_CPU1_SB_CA<2>")
	)
	(segment
		(start 148.327618 -248.01068)
		(end 143.291306 -248.01068)
		(width 0.18288)
		(layer "In4.Cu")
		(net "M_G_CPU1_SB_CA<2>")
	)
	(segment
		(start 180.035962 -252.471682)
		(end 179.853082 -252.288802)
		(width 0.18288)
		(layer "In4.Cu")
		(net "M_G_CPU1_SB_CA<2>")
	)
	(segment
		(start 171.330366 -251.490226)
		(end 171.147486 -251.673106)
		(width 0.18288)
		(layer "In4.Cu")
		(net "M_G_CPU1_SB_CA<2>")
	)
	(segment
		(start 178.260502 -252.288802)
		(end 177.264314 -251.292614)
		(width 0.18288)
		(layer "In4.Cu")
		(net "M_G_CPU1_SB_CA<2>")
	)
	(segment
		(start 137.560304 -249.371866)
		(end 137.559796 -249.371358)
		(width 0.088646)
		(layer "In4.Cu")
		(net "M_G_CPU1_SB_CA<2>")
	)
	(segment
		(start 180.912262 -252.288802)
		(end 180.729382 -252.471682)
		(width 0.18288)
		(layer "In4.Cu")
		(net "M_G_CPU1_SB_CA<2>")
	)
	(segment
		(start 179.159662 -253.067566)
		(end 178.832002 -253.067566)
		(width 0.18288)
		(layer "In4.Cu")
		(net "M_G_CPU1_SB_CA<2>")
	)
	(segment
		(start 135.263636 -249.687842)
		(end 134.930642 -249.354848)
		(width 0.088646)
		(layer "In4.Cu")
		(net "M_G_CPU1_SB_CA<2>")
	)
	(segment
		(start 171.147486 -251.673106)
		(end 171.147486 -251.86513)
		(width 0.18288)
		(layer "In4.Cu")
		(net "M_G_CPU1_SB_CA<2>")
	)
	(segment
		(start 180.218842 -253.067566)
		(end 180.035962 -252.884686)
		(width 0.18288)
		(layer "In4.Cu")
		(net "M_G_CPU1_SB_CA<2>")
	)
	(segment
		(start 180.729382 -252.471682)
		(end 180.729382 -252.884686)
		(width 0.18288)
		(layer "In4.Cu")
		(net "M_G_CPU1_SB_CA<2>")
	)
	(segment
		(start 178.466242 -252.288802)
		(end 178.260502 -252.288802)
		(width 0.18288)
		(layer "In4.Cu")
		(net "M_G_CPU1_SB_CA<2>")
	)
	(segment
		(start 178.832002 -253.067566)
		(end 178.649122 -252.884686)
		(width 0.18288)
		(layer "In4.Cu")
		(net "M_G_CPU1_SB_CA<2>")
	)
	(segment
		(start 160.60928 -251.231146)
		(end 157.926786 -251.231146)
		(width 0.18288)
		(layer "In4.Cu")
		(net "M_G_CPU1_SB_CA<2>")
	)
	(segment
		(start 177.264314 -251.292614)
		(end 172.591476 -251.292614)
		(width 0.18288)
		(layer "In4.Cu")
		(net "M_G_CPU1_SB_CA<2>")
	)
	(segment
		(start 187.883546 -250.866656)
		(end 187.883546 -251.115576)
		(width 0.18288)
		(layer "In4.Cu")
		(net "M_G_CPU1_SB_CA<2>")
	)
	(segment
		(start 141.449552 -249.852434)
		(end 139.15771 -249.852434)
		(width 0.18288)
		(layer "In4.Cu")
		(net "M_G_CPU1_SB_CA<2>")
	)
	(segment
		(start 149.57044 -249.253502)
		(end 148.327618 -248.01068)
		(width 0.18288)
		(layer "In4.Cu")
		(net "M_G_CPU1_SB_CA<2>")
	)
	(segment
		(start 137.559796 -249.371358)
		(end 137.014458 -249.371358)
		(width 0.088646)
		(layer "In4.Cu")
		(net "M_G_CPU1_SB_CA<2>")
	)
	(segment
		(start 137.82675 -249.371866)
		(end 137.560304 -249.371866)
		(width 0.088646)
		(layer "In4.Cu")
		(net "M_G_CPU1_SB_CA<2>")
	)
	(segment
		(start 178.649122 -252.471682)
		(end 178.466242 -252.288802)
		(width 0.18288)
		(layer "In4.Cu")
		(net "M_G_CPU1_SB_CA<2>")
	)
	(segment
		(start 131.658868 -249.295666)
		(end 131.648454 -249.301762)
		(width 0.088646)
		(layer "In4.Cu")
		(net "M_G_CPU1_SB_CA<2>")
	)
	(segment
		(start 164.645848 -251.464826)
		(end 160.84296 -251.464826)
		(width 0.18288)
		(layer "In4.Cu")
		(net "M_G_CPU1_SB_CA<2>")
	)
	(segment
		(start 182.782972 -251.236226)
		(end 182.338726 -251.236226)
		(width 0.18288)
		(layer "In4.Cu")
		(net "M_G_CPU1_SB_CA<2>")
	)
	(segment
		(start 179.525422 -252.288802)
		(end 179.342542 -252.471682)
		(width 0.18288)
		(layer "In4.Cu")
		(net "M_G_CPU1_SB_CA<2>")
	)
	(segment
		(start 170.454066 -251.673106)
		(end 170.271186 -251.490226)
		(width 0.18288)
		(layer "In4.Cu")
		(net "M_G_CPU1_SB_CA<2>")
	)
	(segment
		(start 185.653426 -251.972826)
		(end 185.189876 -251.509276)
		(width 0.18288)
		(layer "In4.Cu")
		(net "M_G_CPU1_SB_CA<2>")
	)
	(segment
		(start 180.546502 -253.067566)
		(end 180.218842 -253.067566)
		(width 0.18288)
		(layer "In4.Cu")
		(net "M_G_CPU1_SB_CA<2>")
	)
	(segment
		(start 135.877046 -249.687842)
		(end 135.263636 -249.687842)
		(width 0.088646)
		(layer "In4.Cu")
		(net "M_G_CPU1_SB_CA<2>")
	)
	(segment
		(start 172.591476 -251.292614)
		(end 172.393864 -251.490226)
		(width 0.18288)
		(layer "In4.Cu")
		(net "M_G_CPU1_SB_CA<2>")
	)
	(segment
		(start 178.649122 -252.884686)
		(end 178.649122 -252.471682)
		(width 0.18288)
		(layer "In4.Cu")
		(net "M_G_CPU1_SB_CA<2>")
	)
	(segment
		(start 164.849048 -251.261626)
		(end 164.645848 -251.464826)
		(width 0.18288)
		(layer "In4.Cu")
		(net "M_G_CPU1_SB_CA<2>")
	)
	(segment
		(start 183.056022 -251.509276)
		(end 182.782972 -251.236226)
		(width 0.18288)
		(layer "In4.Cu")
		(net "M_G_CPU1_SB_CA<2>")
	)
	(segment
		(start 170.271186 -251.490226)
		(end 169.943526 -251.490226)
		(width 0.18288)
		(layer "In4.Cu")
		(net "M_G_CPU1_SB_CA<2>")
	)
	(segment
		(start 185.189876 -251.509276)
		(end 183.056022 -251.509276)
		(width 0.18288)
		(layer "In4.Cu")
		(net "M_G_CPU1_SB_CA<2>")
	)
	(segment
		(start 168.884346 -251.490226)
		(end 167.908224 -251.490226)
		(width 0.18288)
		(layer "In4.Cu")
		(net "M_G_CPU1_SB_CA<2>")
	)
	(segment
		(start 169.067226 -251.86513)
		(end 169.067226 -251.673106)
		(width 0.18288)
		(layer "In4.Cu")
		(net "M_G_CPU1_SB_CA<2>")
	)
	(segment
		(start 187.026296 -251.972826)
		(end 185.653426 -251.972826)
		(width 0.18288)
		(layer "In4.Cu")
		(net "M_G_CPU1_SB_CA<2>")
	)
	(segment
		(start 167.908224 -251.490226)
		(end 167.679624 -251.261626)
		(width 0.18288)
		(layer "In4.Cu")
		(net "M_G_CPU1_SB_CA<2>")
	)
	(segment
		(start 170.964606 -252.04801)
		(end 170.636946 -252.04801)
		(width 0.18288)
		(layer "In4.Cu")
		(net "M_G_CPU1_SB_CA<2>")
	)
	(segment
		(start 187.883546 -251.115576)
		(end 187.026296 -251.972826)
		(width 0.18288)
		(layer "In4.Cu")
		(net "M_G_CPU1_SB_CA<2>")
	)
	(segment
		(start 179.853082 -252.288802)
		(end 179.525422 -252.288802)
		(width 0.18288)
		(layer "In4.Cu")
		(net "M_G_CPU1_SB_CA<2>")
	)
	(segment
		(start 136.319514 -249.245374)
		(end 135.877046 -249.687842)
		(width 0.088646)
		(layer "In4.Cu")
		(net "M_G_CPU1_SB_CA<2>")
	)
	(segment
		(start 157.926786 -251.231146)
		(end 153.152602 -249.253502)
		(width 0.18288)
		(layer "In4.Cu")
		(net "M_G_CPU1_SB_CA<2>")
	)
	(segment
		(start 179.342542 -252.471682)
		(end 179.342542 -252.884686)
		(width 0.18288)
		(layer "In4.Cu")
		(net "M_G_CPU1_SB_CA<2>")
	)
	(segment
		(start 171.147486 -251.86513)
		(end 170.964606 -252.04801)
		(width 0.18288)
		(layer "In4.Cu")
		(net "M_G_CPU1_SB_CA<2>")
	)
	(segment
		(start 169.577766 -252.04801)
		(end 169.250106 -252.04801)
		(width 0.18288)
		(layer "In4.Cu")
		(net "M_G_CPU1_SB_CA<2>")
	)
	(segment
		(start 130.814572 -248.871486)
		(end 130.749294 -248.806208)
		(width 0.088646)
		(layer "In4.Cu")
		(net "M_G_CPU1_SB_CA<2>")
	)
	(segment
		(start 180.729382 -252.884686)
		(end 180.546502 -253.067566)
		(width 0.18288)
		(layer "In4.Cu")
		(net "M_G_CPU1_SB_CA<2>")
	)
	(segment
		(start 167.679624 -251.261626)
		(end 164.849048 -251.261626)
		(width 0.18288)
		(layer "In4.Cu")
		(net "M_G_CPU1_SB_CA<2>")
	)
	(segment
		(start 138.677142 -249.371866)
		(end 137.82675 -249.371866)
		(width 0.18288)
		(layer "In4.Cu")
		(net "M_G_CPU1_SB_CA<2>")
	)
	(segment
		(start 170.636946 -252.04801)
		(end 170.454066 -251.86513)
		(width 0.18288)
		(layer "In4.Cu")
		(net "M_G_CPU1_SB_CA<2>")
	)
	(segment
		(start 182.338726 -251.236226)
		(end 181.28615 -252.288802)
		(width 0.18288)
		(layer "In4.Cu")
		(net "M_G_CPU1_SB_CA<2>")
	)
	(segment
		(start 169.250106 -252.04801)
		(end 169.067226 -251.86513)
		(width 0.18288)
		(layer "In4.Cu")
		(net "M_G_CPU1_SB_CA<2>")
	)
	(arc
		(start 134.930642 -249.354848)
		(mid 134.893592 -249.322702)
		(end 134.852664 -249.295666)
		(width 0.088646)
		(layer "In4.Cu")
		(net "M_G_CPU1_SB_CA<2>")
	)
	(arc
		(start 133.538468 -249.295666)
		(mid 133.255766 -249.371442)
		(end 132.973064 -249.295666)
		(width 0.088646)
		(layer "In4.Cu")
		(net "M_G_CPU1_SB_CA<2>")
	)
	(arc
		(start 131.09321 -249.295666)
		(mid 130.903627 -249.116596)
		(end 130.814572 -248.871486)
		(width 0.088646)
		(layer "In4.Cu")
		(net "M_G_CPU1_SB_CA<2>")
	)
	(arc
		(start 137.014458 -249.371358)
		(mid 136.863838 -249.350786)
		(end 136.724136 -249.29084)
		(width 0.088646)
		(layer "In4.Cu")
		(net "M_G_CPU1_SB_CA<2>")
	)
	(arc
		(start 133.912864 -249.295666)
		(mid 133.725666 -249.245523)
		(end 133.538468 -249.295666)
		(width 0.088646)
		(layer "In4.Cu")
		(net "M_G_CPU1_SB_CA<2>")
	)
	(arc
		(start 131.648454 -249.301762)
		(mid 131.370022 -249.371608)
		(end 131.09321 -249.295666)
		(width 0.088646)
		(layer "In4.Cu")
		(net "M_G_CPU1_SB_CA<2>")
	)
	(arc
		(start 134.852664 -249.295666)
		(mid 134.665466 -249.245523)
		(end 134.478268 -249.295666)
		(width 0.088646)
		(layer "In4.Cu")
		(net "M_G_CPU1_SB_CA<2>")
	)
	(arc
		(start 134.478268 -249.295666)
		(mid 134.195566 -249.371442)
		(end 133.912864 -249.295666)
		(width 0.088646)
		(layer "In4.Cu")
		(net "M_G_CPU1_SB_CA<2>")
	)
	(arc
		(start 136.724136 -249.29084)
		(mid 136.635228 -249.256357)
		(end 136.540494 -249.245374)
		(width 0.088646)
		(layer "In4.Cu")
		(net "M_G_CPU1_SB_CA<2>")
	)
	(arc
		(start 132.598668 -249.295666)
		(mid 132.315966 -249.371442)
		(end 132.033264 -249.295666)
		(width 0.088646)
		(layer "In4.Cu")
		(net "M_G_CPU1_SB_CA<2>")
	)
	(arc
		(start 132.033264 -249.295666)
		(mid 131.846066 -249.245523)
		(end 131.658868 -249.295666)
		(width 0.088646)
		(layer "In4.Cu")
		(net "M_G_CPU1_SB_CA<2>")
	)
	(arc
		(start 132.973064 -249.295666)
		(mid 132.785866 -249.245523)
		(end 132.598668 -249.295666)
		(width 0.088646)
		(layer "In4.Cu")
		(net "M_G_CPU1_SB_CA<2>")
	)
	(segment
		(start 195.510658 -252.152404)
		(end 195.515484 -252.152404)
		(width 0.101854)
		(layer "F.Cu")
		(net "M_G_CPU1_SB_CA<1>")
	)
	(segment
		(start 195.515484 -252.152404)
		(end 195.526152 -252.141736)
		(width 0.1016)
		(layer "F.Cu")
		(net "M_G_CPU1_SB_CA<1>")
	)
	(segment
		(start 198.681594 -251.284232)
		(end 199.0852 -251.284232)
		(width 0.20066)
		(layer "F.Cu")
		(net "M_G_CPU1_SB_CA<1>")
	)
	(segment
		(start 191.983614 -251.716794)
		(end 193.088514 -251.716794)
		(width 0.20066)
		(layer "F.Cu")
		(net "M_G_CPU1_SB_CA<1>")
	)
	(segment
		(start 193.088514 -251.716794)
		(end 194.724274 -251.716794)
		(width 0.20066)
		(layer "F.Cu")
		(net "M_G_CPU1_SB_CA<1>")
	)
	(segment
		(start 128.556512 -249.342148)
		(end 128.556512 -248.806462)
		(width 0.20066)
		(layer "F.Cu")
		(net "M_G_CPU1_SB_CA<1>")
	)
	(segment
		(start 199.0852 -251.284232)
		(end 199.517762 -251.716794)
		(width 0.20066)
		(layer "F.Cu")
		(net "M_G_CPU1_SB_CA<1>")
	)
	(segment
		(start 197.535292 -252.141736)
		(end 197.542658 -252.149102)
		(width 0.1016)
		(layer "F.Cu")
		(net "M_G_CPU1_SB_CA<1>")
	)
	(segment
		(start 197.542658 -252.149102)
		(end 197.816724 -252.149102)
		(width 0.20066)
		(layer "F.Cu")
		(net "M_G_CPU1_SB_CA<1>")
	)
	(segment
		(start 199.517762 -251.716794)
		(end 200.632314 -251.716794)
		(width 0.20066)
		(layer "F.Cu")
		(net "M_G_CPU1_SB_CA<1>")
	)
	(segment
		(start 197.816724 -252.149102)
		(end 198.681594 -251.284232)
		(width 0.20066)
		(layer "F.Cu")
		(net "M_G_CPU1_SB_CA<1>")
	)
	(segment
		(start 195.159884 -252.152404)
		(end 195.510658 -252.152404)
		(width 0.20066)
		(layer "F.Cu")
		(net "M_G_CPU1_SB_CA<1>")
	)
	(segment
		(start 194.724274 -251.716794)
		(end 195.159884 -252.152404)
		(width 0.20066)
		(layer "F.Cu")
		(net "M_G_CPU1_SB_CA<1>")
	)
	(segment
		(start 128.556512 -248.806462)
		(end 128.556766 -248.806208)
		(width 0.20066)
		(layer "F.Cu")
		(net "M_G_CPU1_SB_CA<1>")
	)
	(segment
		(start 195.526152 -252.141736)
		(end 197.535292 -252.141736)
		(width 0.1016)
		(layer "F.Cu")
		(net "M_G_CPU1_SB_CA<1>")
	)
	(segment
		(start 191.234568 -252.46584)
		(end 188.619892 -252.46584)
		(width 0.18288)
		(layer "In4.Cu")
		(net "M_G_CPU1_SB_CA<1>")
	)
	(segment
		(start 143.542258 -248.34596)
		(end 141.659102 -250.229116)
		(width 0.18288)
		(layer "In4.Cu")
		(net "M_G_CPU1_SB_CA<1>")
	)
	(segment
		(start 160.355534 -251.985018)
		(end 160.084516 -252.256036)
		(width 0.18288)
		(layer "In4.Cu")
		(net "M_G_CPU1_SB_CA<1>")
	)
	(segment
		(start 185.297826 -252.480826)
		(end 184.84215 -252.02515)
		(width 0.18288)
		(layer "In4.Cu")
		(net "M_G_CPU1_SB_CA<1>")
	)
	(segment
		(start 161.319464 -251.985018)
		(end 160.355534 -251.985018)
		(width 0.18288)
		(layer "In4.Cu")
		(net "M_G_CPU1_SB_CA<1>")
	)
	(segment
		(start 153.105866 -249.823732)
		(end 149.414484 -249.823732)
		(width 0.18288)
		(layer "In4.Cu")
		(net "M_G_CPU1_SB_CA<1>")
	)
	(segment
		(start 187.282582 -252.480826)
		(end 185.297826 -252.480826)
		(width 0.18288)
		(layer "In4.Cu")
		(net "M_G_CPU1_SB_CA<1>")
	)
	(segment
		(start 176.693576 -252.142498)
		(end 176.693322 -252.142752)
		(width 0.18288)
		(layer "In4.Cu")
		(net "M_G_CPU1_SB_CA<1>")
	)
	(segment
		(start 177.174398 -252.142752)
		(end 177.045366 -252.142752)
		(width 0.18288)
		(layer "In4.Cu")
		(net "M_G_CPU1_SB_CA<1>")
	)
	(segment
		(start 172.663866 -252.142498)
		(end 172.663612 -252.142752)
		(width 0.18288)
		(layer "In4.Cu")
		(net "M_G_CPU1_SB_CA<1>")
	)
	(segment
		(start 171.950126 -252.557026)
		(end 161.891472 -252.557026)
		(width 0.18288)
		(layer "In4.Cu")
		(net "M_G_CPU1_SB_CA<1>")
	)
	(segment
		(start 182.338726 -252.353826)
		(end 181.119526 -253.573026)
		(width 0.18288)
		(layer "In4.Cu")
		(net "M_G_CPU1_SB_CA<1>")
	)
	(segment
		(start 178.604672 -253.573026)
		(end 177.174398 -252.142752)
		(width 0.18288)
		(layer "In4.Cu")
		(net "M_G_CPU1_SB_CA<1>")
	)
	(segment
		(start 172.3644 -252.142752)
		(end 171.950126 -252.557026)
		(width 0.18288)
		(layer "In4.Cu")
		(net "M_G_CPU1_SB_CA<1>")
	)
	(segment
		(start 141.659102 -250.229116)
		(end 138.899392 -250.229116)
		(width 0.18288)
		(layer "In4.Cu")
		(net "M_G_CPU1_SB_CA<1>")
	)
	(segment
		(start 129.31521 -249.134122)
		(end 128.927606 -248.906792)
		(width 0.088646)
		(layer "In4.Cu")
		(net "M_G_CPU1_SB_CA<1>")
	)
	(segment
		(start 181.119526 -253.573026)
		(end 178.604672 -253.573026)
		(width 0.18288)
		(layer "In4.Cu")
		(net "M_G_CPU1_SB_CA<1>")
	)
	(segment
		(start 183.265318 -252.353826)
		(end 182.338726 -252.353826)
		(width 0.18288)
		(layer "In4.Cu")
		(net "M_G_CPU1_SB_CA<1>")
	)
	(segment
		(start 156.538676 -251.245624)
		(end 153.105866 -249.823732)
		(width 0.18288)
		(layer "In4.Cu")
		(net "M_G_CPU1_SB_CA<1>")
	)
	(segment
		(start 160.084516 -252.256036)
		(end 157.549088 -252.256036)
		(width 0.18288)
		(layer "In4.Cu")
		(net "M_G_CPU1_SB_CA<1>")
	)
	(segment
		(start 184.84215 -252.02515)
		(end 183.593994 -252.02515)
		(width 0.18288)
		(layer "In4.Cu")
		(net "M_G_CPU1_SB_CA<1>")
	)
	(segment
		(start 188.295026 -252.140974)
		(end 187.622434 -252.140974)
		(width 0.18288)
		(layer "In4.Cu")
		(net "M_G_CPU1_SB_CA<1>")
	)
	(segment
		(start 147.936712 -248.34596)
		(end 143.542258 -248.34596)
		(width 0.18288)
		(layer "In4.Cu")
		(net "M_G_CPU1_SB_CA<1>")
	)
	(segment
		(start 157.549088 -252.256036)
		(end 156.538676 -251.245624)
		(width 0.18288)
		(layer "In4.Cu")
		(net "M_G_CPU1_SB_CA<1>")
	)
	(segment
		(start 191.983614 -251.716794)
		(end 191.234568 -252.46584)
		(width 0.18288)
		(layer "In4.Cu")
		(net "M_G_CPU1_SB_CA<1>")
	)
	(segment
		(start 183.593994 -252.02515)
		(end 183.265318 -252.353826)
		(width 0.18288)
		(layer "In4.Cu")
		(net "M_G_CPU1_SB_CA<1>")
	)
	(segment
		(start 173.580552 -252.142752)
		(end 173.580298 -252.142498)
		(width 0.18288)
		(layer "In4.Cu")
		(net "M_G_CPU1_SB_CA<1>")
	)
	(segment
		(start 129.69621 -249.97664)
		(end 129.591816 -249.872246)
		(width 0.088646)
		(layer "In4.Cu")
		(net "M_G_CPU1_SB_CA<1>")
	)
	(segment
		(start 137.940796 -249.724926)
		(end 137.56259 -250.103132)
		(width 0.18288)
		(layer "In4.Cu")
		(net "M_G_CPU1_SB_CA<1>")
	)
	(segment
		(start 137.56259 -250.103132)
		(end 129.822702 -250.103132)
		(width 0.18288)
		(layer "In4.Cu")
		(net "M_G_CPU1_SB_CA<1>")
	)
	(segment
		(start 187.622434 -252.140974)
		(end 187.282582 -252.480826)
		(width 0.18288)
		(layer "In4.Cu")
		(net "M_G_CPU1_SB_CA<1>")
	)
	(segment
		(start 188.619892 -252.46584)
		(end 188.295026 -252.140974)
		(width 0.18288)
		(layer "In4.Cu")
		(net "M_G_CPU1_SB_CA<1>")
	)
	(segment
		(start 173.580298 -252.142498)
		(end 172.663866 -252.142498)
		(width 0.18288)
		(layer "In4.Cu")
		(net "M_G_CPU1_SB_CA<1>")
	)
	(segment
		(start 138.899392 -250.229116)
		(end 138.395202 -249.724926)
		(width 0.18288)
		(layer "In4.Cu")
		(net "M_G_CPU1_SB_CA<1>")
	)
	(segment
		(start 177.045112 -252.142498)
		(end 176.693576 -252.142498)
		(width 0.18288)
		(layer "In4.Cu")
		(net "M_G_CPU1_SB_CA<1>")
	)
	(segment
		(start 172.663612 -252.142752)
		(end 172.3644 -252.142752)
		(width 0.18288)
		(layer "In4.Cu")
		(net "M_G_CPU1_SB_CA<1>")
	)
	(segment
		(start 129.591816 -249.872246)
		(end 129.591816 -249.620024)
		(width 0.088646)
		(layer "In4.Cu")
		(net "M_G_CPU1_SB_CA<1>")
	)
	(segment
		(start 129.822702 -250.103132)
		(end 129.69621 -249.97664)
		(width 0.18288)
		(layer "In4.Cu")
		(net "M_G_CPU1_SB_CA<1>")
	)
	(segment
		(start 176.693322 -252.142752)
		(end 173.580552 -252.142752)
		(width 0.18288)
		(layer "In4.Cu")
		(net "M_G_CPU1_SB_CA<1>")
	)
	(segment
		(start 161.891472 -252.557026)
		(end 161.319464 -251.985018)
		(width 0.18288)
		(layer "In4.Cu")
		(net "M_G_CPU1_SB_CA<1>")
	)
	(segment
		(start 138.395202 -249.724926)
		(end 137.940796 -249.724926)
		(width 0.18288)
		(layer "In4.Cu")
		(net "M_G_CPU1_SB_CA<1>")
	)
	(segment
		(start 177.045366 -252.142752)
		(end 177.045112 -252.142498)
		(width 0.18288)
		(layer "In4.Cu")
		(net "M_G_CPU1_SB_CA<1>")
	)
	(segment
		(start 149.414484 -249.823732)
		(end 147.936712 -248.34596)
		(width 0.18288)
		(layer "In4.Cu")
		(net "M_G_CPU1_SB_CA<1>")
	)
	(arc
		(start 129.591816 -249.620024)
		(mid 129.517825 -249.340458)
		(end 129.31521 -249.134122)
		(width 0.088646)
		(layer "In4.Cu")
		(net "M_G_CPU1_SB_CA<1>")
	)
	(arc
		(start 128.927606 -248.906792)
		(mid 128.748887 -248.83179)
		(end 128.556766 -248.806208)
		(width 0.088646)
		(layer "In4.Cu")
		(net "M_G_CPU1_SB_CA<1>")
	)
	(segment
		(start 195.431156 -252.566678)
		(end 196.532246 -252.566678)
		(width 0.20066)
		(layer "F.Cu")
		(net "M_G_CPU1_SB_CA<0>")
	)
	(segment
		(start 188.988446 -252.566678)
		(end 190.210694 -252.566678)
		(width 0.20066)
		(layer "F.Cu")
		(net "M_G_CPU1_SB_CA<0>")
	)
	(segment
		(start 191.06134 -252.262132)
		(end 191.978788 -253.17958)
		(width 0.20066)
		(layer "F.Cu")
		(net "M_G_CPU1_SB_CA<0>")
	)
	(segment
		(start 187.883546 -252.566678)
		(end 188.988446 -252.566678)
		(width 0.20066)
		(layer "F.Cu")
		(net "M_G_CPU1_SB_CA<0>")
	)
	(segment
		(start 190.51524 -252.262132)
		(end 191.06134 -252.262132)
		(width 0.20066)
		(layer "F.Cu")
		(net "M_G_CPU1_SB_CA<0>")
	)
	(segment
		(start 191.978788 -253.17958)
		(end 194.818254 -253.17958)
		(width 0.20066)
		(layer "F.Cu")
		(net "M_G_CPU1_SB_CA<0>")
	)
	(segment
		(start 194.818254 -253.17958)
		(end 195.431156 -252.566678)
		(width 0.20066)
		(layer "F.Cu")
		(net "M_G_CPU1_SB_CA<0>")
	)
	(segment
		(start 128.086866 -248.528078)
		(end 128.086612 -248.527824)
		(width 0.20066)
		(layer "F.Cu")
		(net "M_G_CPU1_SB_CA<0>")
	)
	(segment
		(start 128.086612 -248.527824)
		(end 128.086612 -247.992138)
		(width 0.20066)
		(layer "F.Cu")
		(net "M_G_CPU1_SB_CA<0>")
	)
	(segment
		(start 190.210694 -252.566678)
		(end 190.51524 -252.262132)
		(width 0.20066)
		(layer "F.Cu")
		(net "M_G_CPU1_SB_CA<0>")
	)
	(segment
		(start 183.113426 -252.912626)
		(end 182.541926 -252.912626)
		(width 0.18288)
		(layer "In4.Cu")
		(net "M_G_CPU1_SB_CA<0>")
	)
	(segment
		(start 141.958568 -250.63069)
		(end 129.582672 -250.63069)
		(width 0.18288)
		(layer "In4.Cu")
		(net "M_G_CPU1_SB_CA<0>")
	)
	(segment
		(start 163.74872 -253.58217)
		(end 162.730942 -253.58217)
		(width 0.18288)
		(layer "In4.Cu")
		(net "M_G_CPU1_SB_CA<0>")
	)
	(segment
		(start 129.354834 -249.827288)
		(end 129.401316 -249.780806)
		(width 0.088646)
		(layer "In4.Cu")
		(net "M_G_CPU1_SB_CA<0>")
	)
	(segment
		(start 147.557744 -248.68124)
		(end 143.908018 -248.68124)
		(width 0.18288)
		(layer "In4.Cu")
		(net "M_G_CPU1_SB_CA<0>")
	)
	(segment
		(start 187.677552 -253.154688)
		(end 183.355488 -253.154688)
		(width 0.18288)
		(layer "In4.Cu")
		(net "M_G_CPU1_SB_CA<0>")
	)
	(segment
		(start 181.297326 -254.157226)
		(end 178.046126 -254.157226)
		(width 0.18288)
		(layer "In4.Cu")
		(net "M_G_CPU1_SB_CA<0>")
	)
	(segment
		(start 162.254692 -253.10592)
		(end 160.583372 -253.10592)
		(width 0.18288)
		(layer "In4.Cu")
		(net "M_G_CPU1_SB_CA<0>")
	)
	(segment
		(start 129.21234 -249.294396)
		(end 129.143252 -249.25401)
		(width 0.088646)
		(layer "In4.Cu")
		(net "M_G_CPU1_SB_CA<0>")
	)
	(segment
		(start 128.086866 -248.367296)
		(end 128.086612 -248.367042)
		(width 0.088646)
		(layer "In4.Cu")
		(net "M_G_CPU1_SB_CA<0>")
	)
	(segment
		(start 156.228542 -251.673868)
		(end 153.244042 -250.43765)
		(width 0.18288)
		(layer "In4.Cu")
		(net "M_G_CPU1_SB_CA<0>")
	)
	(segment
		(start 128.086612 -248.367042)
		(end 128.086612 -247.992138)
		(width 0.088646)
		(layer "In4.Cu")
		(net "M_G_CPU1_SB_CA<0>")
	)
	(segment
		(start 187.883546 -252.948694)
		(end 187.677552 -253.154688)
		(width 0.18288)
		(layer "In4.Cu")
		(net "M_G_CPU1_SB_CA<0>")
	)
	(segment
		(start 129.582672 -250.63069)
		(end 129.354834 -250.402852)
		(width 0.18288)
		(layer "In4.Cu")
		(net "M_G_CPU1_SB_CA<0>")
	)
	(segment
		(start 164.699188 -253.214378)
		(end 164.116512 -253.214378)
		(width 0.18288)
		(layer "In4.Cu")
		(net "M_G_CPU1_SB_CA<0>")
	)
	(segment
		(start 166.982648 -253.10592)
		(end 166.506398 -253.58217)
		(width 0.18288)
		(layer "In4.Cu")
		(net "M_G_CPU1_SB_CA<0>")
	)
	(segment
		(start 129.354834 -250.402852)
		(end 129.354834 -250.050046)
		(width 0.18288)
		(layer "In4.Cu")
		(net "M_G_CPU1_SB_CA<0>")
	)
	(segment
		(start 157.3403 -252.785626)
		(end 156.228542 -251.673868)
		(width 0.18288)
		(layer "In4.Cu")
		(net "M_G_CPU1_SB_CA<0>")
	)
	(segment
		(start 128.706626 -249.331226)
		(end 128.376426 -249.331226)
		(width 0.088646)
		(layer "In4.Cu")
		(net "M_G_CPU1_SB_CA<0>")
	)
	(segment
		(start 166.506398 -253.58217)
		(end 165.06698 -253.58217)
		(width 0.18288)
		(layer "In4.Cu")
		(net "M_G_CPU1_SB_CA<0>")
	)
	(segment
		(start 160.263078 -252.785626)
		(end 157.3403 -252.785626)
		(width 0.18288)
		(layer "In4.Cu")
		(net "M_G_CPU1_SB_CA<0>")
	)
	(segment
		(start 178.046126 -254.157226)
		(end 176.99482 -253.10592)
		(width 0.18288)
		(layer "In4.Cu")
		(net "M_G_CPU1_SB_CA<0>")
	)
	(segment
		(start 128.086866 -249.041666)
		(end 128.086866 -248.367296)
		(width 0.088646)
		(layer "In4.Cu")
		(net "M_G_CPU1_SB_CA<0>")
	)
	(segment
		(start 143.908018 -248.68124)
		(end 141.958568 -250.63069)
		(width 0.18288)
		(layer "In4.Cu")
		(net "M_G_CPU1_SB_CA<0>")
	)
	(segment
		(start 165.06698 -253.58217)
		(end 164.699188 -253.214378)
		(width 0.18288)
		(layer "In4.Cu")
		(net "M_G_CPU1_SB_CA<0>")
	)
	(segment
		(start 149.314154 -250.43765)
		(end 147.557744 -248.68124)
		(width 0.18288)
		(layer "In4.Cu")
		(net "M_G_CPU1_SB_CA<0>")
	)
	(segment
		(start 187.883546 -252.566678)
		(end 187.883546 -252.948694)
		(width 0.18288)
		(layer "In4.Cu")
		(net "M_G_CPU1_SB_CA<0>")
	)
	(segment
		(start 129.354834 -250.050046)
		(end 129.354834 -249.827288)
		(width 0.088646)
		(layer "In4.Cu")
		(net "M_G_CPU1_SB_CA<0>")
	)
	(segment
		(start 153.244042 -250.43765)
		(end 149.314154 -250.43765)
		(width 0.18288)
		(layer "In4.Cu")
		(net "M_G_CPU1_SB_CA<0>")
	)
	(segment
		(start 129.401316 -249.780806)
		(end 129.401316 -249.624596)
		(width 0.088646)
		(layer "In4.Cu")
		(net "M_G_CPU1_SB_CA<0>")
	)
	(segment
		(start 183.355488 -253.154688)
		(end 183.113426 -252.912626)
		(width 0.18288)
		(layer "In4.Cu")
		(net "M_G_CPU1_SB_CA<0>")
	)
	(segment
		(start 128.376426 -249.331226)
		(end 128.086866 -249.041666)
		(width 0.088646)
		(layer "In4.Cu")
		(net "M_G_CPU1_SB_CA<0>")
	)
	(segment
		(start 164.116512 -253.214378)
		(end 163.74872 -253.58217)
		(width 0.18288)
		(layer "In4.Cu")
		(net "M_G_CPU1_SB_CA<0>")
	)
	(segment
		(start 162.730942 -253.58217)
		(end 162.254692 -253.10592)
		(width 0.18288)
		(layer "In4.Cu")
		(net "M_G_CPU1_SB_CA<0>")
	)
	(segment
		(start 160.583372 -253.10592)
		(end 160.263078 -252.785626)
		(width 0.18288)
		(layer "In4.Cu")
		(net "M_G_CPU1_SB_CA<0>")
	)
	(segment
		(start 176.99482 -253.10592)
		(end 166.982648 -253.10592)
		(width 0.18288)
		(layer "In4.Cu")
		(net "M_G_CPU1_SB_CA<0>")
	)
	(segment
		(start 182.541926 -252.912626)
		(end 181.297326 -254.157226)
		(width 0.18288)
		(layer "In4.Cu")
		(net "M_G_CPU1_SB_CA<0>")
	)
	(arc
		(start 129.283968 -249.347736)
		(mid 129.249679 -249.319019)
		(end 129.21234 -249.294396)
		(width 0.088646)
		(layer "In4.Cu")
		(net "M_G_CPU1_SB_CA<0>")
	)
	(arc
		(start 129.401316 -249.624596)
		(mid 129.398873 -249.579993)
		(end 129.39141 -249.53595)
		(width 0.088646)
		(layer "In4.Cu")
		(net "M_G_CPU1_SB_CA<0>")
	)
	(arc
		(start 129.39141 -249.53595)
		(mid 129.351629 -249.433879)
		(end 129.283968 -249.347736)
		(width 0.088646)
		(layer "In4.Cu")
		(net "M_G_CPU1_SB_CA<0>")
	)
	(arc
		(start 129.05994 -249.222514)
		(mid 128.869744 -249.232917)
		(end 128.706626 -249.331226)
		(width 0.088646)
		(layer "In4.Cu")
		(net "M_G_CPU1_SB_CA<0>")
	)
	(arc
		(start 129.143252 -249.25401)
		(mid 129.102938 -249.234714)
		(end 129.05994 -249.222514)
		(width 0.088646)
		(layer "In4.Cu")
		(net "M_G_CPU1_SB_CA<0>")
	)
	(segment
		(start 187.883546 -244.066568)
		(end 188.988446 -244.066568)
		(width 0.20066)
		(layer "F.Cu")
		(net "M_G_CPU1_SA_RSP<1>")
	)
	(segment
		(start 131.485894 -253.383796)
		(end 131.485894 -253.919736)
		(width 0.20066)
		(layer "F.Cu")
		(net "M_G_CPU1_SA_RSP<1>")
	)
	(segment
		(start 157.184344 -251.087382)
		(end 157.064456 -251.20727)
		(width 0.18288)
		(layer "In6.Cu")
		(net "M_G_CPU1_SA_RSP<1>")
	)
	(segment
		(start 165.23589 -250.68403)
		(end 164.641022 -250.68403)
		(width 0.18288)
		(layer "In6.Cu")
		(net "M_G_CPU1_SA_RSP<1>")
	)
	(segment
		(start 162.534346 -251.393198)
		(end 162.534346 -250.549664)
		(width 0.18288)
		(layer "In6.Cu")
		(net "M_G_CPU1_SA_RSP<1>")
	)
	(segment
		(start 159.158686 -251.247402)
		(end 159.158686 -251.609606)
		(width 0.18288)
		(layer "In6.Cu")
		(net "M_G_CPU1_SA_RSP<1>")
	)
	(segment
		(start 183.448706 -247.714262)
		(end 179.918106 -247.714262)
		(width 0.18288)
		(layer "In6.Cu")
		(net "M_G_CPU1_SA_RSP<1>")
	)
	(segment
		(start 162.361372 -250.37669)
		(end 161.569146 -250.37669)
		(width 0.18288)
		(layer "In6.Cu")
		(net "M_G_CPU1_SA_RSP<1>")
	)
	(segment
		(start 157.064456 -251.20727)
		(end 157.064456 -251.621798)
		(width 0.18288)
		(layer "In6.Cu")
		(net "M_G_CPU1_SA_RSP<1>")
	)
	(segment
		(start 164.333682 -250.37669)
		(end 163.43376 -250.37669)
		(width 0.18288)
		(layer "In6.Cu")
		(net "M_G_CPU1_SA_RSP<1>")
	)
	(segment
		(start 186.258962 -244.904006)
		(end 183.448706 -247.714262)
		(width 0.18288)
		(layer "In6.Cu")
		(net "M_G_CPU1_SA_RSP<1>")
	)
	(segment
		(start 158.235396 -251.087382)
		(end 157.184344 -251.087382)
		(width 0.18288)
		(layer "In6.Cu")
		(net "M_G_CPU1_SA_RSP<1>")
	)
	(segment
		(start 162.694366 -251.553218)
		(end 162.534346 -251.393198)
		(width 0.18288)
		(layer "In6.Cu")
		(net "M_G_CPU1_SA_RSP<1>")
	)
	(segment
		(start 163.27374 -250.53671)
		(end 163.27374 -251.393198)
		(width 0.18288)
		(layer "In6.Cu")
		(net "M_G_CPU1_SA_RSP<1>")
	)
	(segment
		(start 158.555436 -251.769626)
		(end 158.395416 -251.609606)
		(width 0.18288)
		(layer "In6.Cu")
		(net "M_G_CPU1_SA_RSP<1>")
	)
	(segment
		(start 160.858454 -251.087382)
		(end 159.318706 -251.087382)
		(width 0.18288)
		(layer "In6.Cu")
		(net "M_G_CPU1_SA_RSP<1>")
	)
	(segment
		(start 158.998666 -251.769626)
		(end 158.555436 -251.769626)
		(width 0.18288)
		(layer "In6.Cu")
		(net "M_G_CPU1_SA_RSP<1>")
	)
	(segment
		(start 163.11372 -251.553218)
		(end 162.694366 -251.553218)
		(width 0.18288)
		(layer "In6.Cu")
		(net "M_G_CPU1_SA_RSP<1>")
	)
	(segment
		(start 168.98493 -248.660666)
		(end 168.208706 -249.43689)
		(width 0.18288)
		(layer "In6.Cu")
		(net "M_G_CPU1_SA_RSP<1>")
	)
	(segment
		(start 162.534346 -250.549664)
		(end 162.361372 -250.37669)
		(width 0.18288)
		(layer "In6.Cu")
		(net "M_G_CPU1_SA_RSP<1>")
	)
	(segment
		(start 187.883546 -244.066568)
		(end 187.046108 -244.904006)
		(width 0.18288)
		(layer "In6.Cu")
		(net "M_G_CPU1_SA_RSP<1>")
	)
	(segment
		(start 163.43376 -250.37669)
		(end 163.27374 -250.53671)
		(width 0.18288)
		(layer "In6.Cu")
		(net "M_G_CPU1_SA_RSP<1>")
	)
	(segment
		(start 158.395416 -251.609606)
		(end 158.395416 -251.247402)
		(width 0.18288)
		(layer "In6.Cu")
		(net "M_G_CPU1_SA_RSP<1>")
	)
	(segment
		(start 131.250944 -253.684786)
		(end 131.485894 -253.919736)
		(width 0.18288)
		(layer "In6.Cu")
		(net "M_G_CPU1_SA_RSP<1>")
	)
	(segment
		(start 147.418044 -254.70485)
		(end 145.772632 -254.70485)
		(width 0.18288)
		(layer "In6.Cu")
		(net "M_G_CPU1_SA_RSP<1>")
	)
	(segment
		(start 144.274794 -254.261366)
		(end 142.840456 -252.827028)
		(width 0.18288)
		(layer "In6.Cu")
		(net "M_G_CPU1_SA_RSP<1>")
	)
	(segment
		(start 158.395416 -251.247402)
		(end 158.235396 -251.087382)
		(width 0.18288)
		(layer "In6.Cu")
		(net "M_G_CPU1_SA_RSP<1>")
	)
	(segment
		(start 178.477926 -247.967246)
		(end 177.702972 -248.7422)
		(width 0.18288)
		(layer "In6.Cu")
		(net "M_G_CPU1_SA_RSP<1>")
	)
	(segment
		(start 145.772632 -254.70485)
		(end 144.950688 -254.541528)
		(width 0.18288)
		(layer "In6.Cu")
		(net "M_G_CPU1_SA_RSP<1>")
	)
	(segment
		(start 131.70281 -252.827028)
		(end 131.250944 -253.278894)
		(width 0.18288)
		(layer "In6.Cu")
		(net "M_G_CPU1_SA_RSP<1>")
	)
	(segment
		(start 159.318706 -251.087382)
		(end 159.158686 -251.247402)
		(width 0.18288)
		(layer "In6.Cu")
		(net "M_G_CPU1_SA_RSP<1>")
	)
	(segment
		(start 163.27374 -251.393198)
		(end 163.11372 -251.553218)
		(width 0.18288)
		(layer "In6.Cu")
		(net "M_G_CPU1_SA_RSP<1>")
	)
	(segment
		(start 168.208706 -249.43689)
		(end 166.48303 -249.43689)
		(width 0.18288)
		(layer "In6.Cu")
		(net "M_G_CPU1_SA_RSP<1>")
	)
	(segment
		(start 156.026612 -251.781818)
		(end 155.663646 -252.144784)
		(width 0.18288)
		(layer "In6.Cu")
		(net "M_G_CPU1_SA_RSP<1>")
	)
	(segment
		(start 161.569146 -250.37669)
		(end 160.858454 -251.087382)
		(width 0.18288)
		(layer "In6.Cu")
		(net "M_G_CPU1_SA_RSP<1>")
	)
	(segment
		(start 149.97811 -252.144784)
		(end 147.418044 -254.70485)
		(width 0.18288)
		(layer "In6.Cu")
		(net "M_G_CPU1_SA_RSP<1>")
	)
	(segment
		(start 142.840456 -252.827028)
		(end 131.70281 -252.827028)
		(width 0.18288)
		(layer "In6.Cu")
		(net "M_G_CPU1_SA_RSP<1>")
	)
	(segment
		(start 164.641022 -250.68403)
		(end 164.333682 -250.37669)
		(width 0.18288)
		(layer "In6.Cu")
		(net "M_G_CPU1_SA_RSP<1>")
	)
	(segment
		(start 177.702972 -248.7422)
		(end 169.85107 -248.7422)
		(width 0.18288)
		(layer "In6.Cu")
		(net "M_G_CPU1_SA_RSP<1>")
	)
	(segment
		(start 179.918106 -247.714262)
		(end 179.665122 -247.967246)
		(width 0.18288)
		(layer "In6.Cu")
		(net "M_G_CPU1_SA_RSP<1>")
	)
	(segment
		(start 131.250944 -253.278894)
		(end 131.250944 -253.684786)
		(width 0.18288)
		(layer "In6.Cu")
		(net "M_G_CPU1_SA_RSP<1>")
	)
	(segment
		(start 187.046108 -244.904006)
		(end 186.258962 -244.904006)
		(width 0.18288)
		(layer "In6.Cu")
		(net "M_G_CPU1_SA_RSP<1>")
	)
	(segment
		(start 156.904436 -251.781818)
		(end 156.026612 -251.781818)
		(width 0.18288)
		(layer "In6.Cu")
		(net "M_G_CPU1_SA_RSP<1>")
	)
	(segment
		(start 179.665122 -247.967246)
		(end 178.477926 -247.967246)
		(width 0.18288)
		(layer "In6.Cu")
		(net "M_G_CPU1_SA_RSP<1>")
	)
	(segment
		(start 169.85107 -248.7422)
		(end 169.769536 -248.660666)
		(width 0.18288)
		(layer "In6.Cu")
		(net "M_G_CPU1_SA_RSP<1>")
	)
	(segment
		(start 144.950688 -254.541528)
		(end 144.274794 -254.261366)
		(width 0.18288)
		(layer "In6.Cu")
		(net "M_G_CPU1_SA_RSP<1>")
	)
	(segment
		(start 157.064456 -251.621798)
		(end 156.904436 -251.781818)
		(width 0.18288)
		(layer "In6.Cu")
		(net "M_G_CPU1_SA_RSP<1>")
	)
	(segment
		(start 166.48303 -249.43689)
		(end 165.23589 -250.68403)
		(width 0.18288)
		(layer "In6.Cu")
		(net "M_G_CPU1_SA_RSP<1>")
	)
	(segment
		(start 169.769536 -248.660666)
		(end 168.98493 -248.660666)
		(width 0.18288)
		(layer "In6.Cu")
		(net "M_G_CPU1_SA_RSP<1>")
	)
	(segment
		(start 155.663646 -252.144784)
		(end 149.97811 -252.144784)
		(width 0.18288)
		(layer "In6.Cu")
		(net "M_G_CPU1_SA_RSP<1>")
	)
	(segment
		(start 159.158686 -251.609606)
		(end 158.998666 -251.769626)
		(width 0.18288)
		(layer "In6.Cu")
		(net "M_G_CPU1_SA_RSP<1>")
	)
	(segment
		(start 131.956048 -254.197612)
		(end 131.956048 -254.733298)
		(width 0.20066)
		(layer "F.Cu")
		(net "M_G_CPU1_SA_RSP<0>")
	)
	(segment
		(start 131.956048 -254.733298)
		(end 131.956302 -254.733552)
		(width 0.20066)
		(layer "F.Cu")
		(net "M_G_CPU1_SA_RSP<0>")
	)
	(segment
		(start 195.427346 -244.066568)
		(end 196.532246 -244.066568)
		(width 0.20066)
		(layer "F.Cu")
		(net "M_G_CPU1_SA_RSP<0>")
	)
	(segment
		(start 148.260562 -255.65354)
		(end 145.83537 -255.65354)
		(width 0.18288)
		(layer "In6.Cu")
		(net "M_G_CPU1_SA_RSP<0>")
	)
	(segment
		(start 145.83537 -255.65354)
		(end 144.70507 -255.42875)
		(width 0.18288)
		(layer "In6.Cu")
		(net "M_G_CPU1_SA_RSP<0>")
	)
	(segment
		(start 181.087776 -250.46305)
		(end 181.087776 -249.6312)
		(width 0.18288)
		(layer "In6.Cu")
		(net "M_G_CPU1_SA_RSP<0>")
	)
	(segment
		(start 137.334498 -253.51359)
		(end 135.884158 -253.51359)
		(width 0.088646)
		(layer "In6.Cu")
		(net "M_G_CPU1_SA_RSP<0>")
	)
	(segment
		(start 181.781196 -249.6312)
		(end 181.781196 -250.46305)
		(width 0.18288)
		(layer "In6.Cu")
		(net "M_G_CPU1_SA_RSP<0>")
	)
	(segment
		(start 181.781196 -250.46305)
		(end 181.598316 -250.64593)
		(width 0.18288)
		(layer "In6.Cu")
		(net "M_G_CPU1_SA_RSP<0>")
	)
	(segment
		(start 167.37711 -251.12599)
		(end 165.489128 -253.013972)
		(width 0.18288)
		(layer "In6.Cu")
		(net "M_G_CPU1_SA_RSP<0>")
	)
	(segment
		(start 135.884158 -253.51359)
		(end 135.774938 -253.40437)
		(width 0.088646)
		(layer "In6.Cu")
		(net "M_G_CPU1_SA_RSP<0>")
	)
	(segment
		(start 137.683748 -253.57201)
		(end 137.392918 -253.57201)
		(width 0.088646)
		(layer "In6.Cu")
		(net "M_G_CPU1_SA_RSP<0>")
	)
	(segment
		(start 132.626608 -254.374396)
		(end 132.315458 -254.374396)
		(width 0.088646)
		(layer "In6.Cu")
		(net "M_G_CPU1_SA_RSP<0>")
	)
	(segment
		(start 179.885848 -249.44832)
		(end 178.891946 -250.442222)
		(width 0.18288)
		(layer "In6.Cu")
		(net "M_G_CPU1_SA_RSP<0>")
	)
	(segment
		(start 132.315458 -254.374396)
		(end 131.956302 -254.733552)
		(width 0.088646)
		(layer "In6.Cu")
		(net "M_G_CPU1_SA_RSP<0>")
	)
	(segment
		(start 135.774938 -253.40437)
		(end 133.331458 -253.40437)
		(width 0.088646)
		(layer "In6.Cu")
		(net "M_G_CPU1_SA_RSP<0>")
	)
	(segment
		(start 195.401946 -244.066568)
		(end 195.138294 -244.33022)
		(width 0.18288)
		(layer "In6.Cu")
		(net "M_G_CPU1_SA_RSP<0>")
	)
	(segment
		(start 178.891946 -250.442222)
		(end 168.98747 -250.442222)
		(width 0.18288)
		(layer "In6.Cu")
		(net "M_G_CPU1_SA_RSP<0>")
	)
	(segment
		(start 182.337456 -249.44832)
		(end 181.964076 -249.44832)
		(width 0.18288)
		(layer "In6.Cu")
		(net "M_G_CPU1_SA_RSP<0>")
	)
	(segment
		(start 168.303702 -251.12599)
		(end 167.37711 -251.12599)
		(width 0.18288)
		(layer "In6.Cu")
		(net "M_G_CPU1_SA_RSP<0>")
	)
	(segment
		(start 133.331458 -253.40437)
		(end 132.895848 -253.83998)
		(width 0.088646)
		(layer "In6.Cu")
		(net "M_G_CPU1_SA_RSP<0>")
	)
	(segment
		(start 142.296642 -253.57201)
		(end 137.683748 -253.57201)
		(width 0.18288)
		(layer "In6.Cu")
		(net "M_G_CPU1_SA_RSP<0>")
	)
	(segment
		(start 180.904896 -249.44832)
		(end 179.885848 -249.44832)
		(width 0.18288)
		(layer "In6.Cu")
		(net "M_G_CPU1_SA_RSP<0>")
	)
	(segment
		(start 132.895848 -254.105156)
		(end 132.626608 -254.374396)
		(width 0.088646)
		(layer "In6.Cu")
		(net "M_G_CPU1_SA_RSP<0>")
	)
	(segment
		(start 181.270656 -250.64593)
		(end 181.087776 -250.46305)
		(width 0.18288)
		(layer "In6.Cu")
		(net "M_G_CPU1_SA_RSP<0>")
	)
	(segment
		(start 155.567634 -254.102362)
		(end 149.81174 -254.102362)
		(width 0.18288)
		(layer "In6.Cu")
		(net "M_G_CPU1_SA_RSP<0>")
	)
	(segment
		(start 143.763238 -255.038606)
		(end 142.296642 -253.57201)
		(width 0.18288)
		(layer "In6.Cu")
		(net "M_G_CPU1_SA_RSP<0>")
	)
	(segment
		(start 132.895848 -253.83998)
		(end 132.895848 -254.105156)
		(width 0.088646)
		(layer "In6.Cu")
		(net "M_G_CPU1_SA_RSP<0>")
	)
	(segment
		(start 185.17489 -248.273062)
		(end 182.337456 -249.44832)
		(width 0.18288)
		(layer "In6.Cu")
		(net "M_G_CPU1_SA_RSP<0>")
	)
	(segment
		(start 181.964076 -249.44832)
		(end 181.781196 -249.6312)
		(width 0.18288)
		(layer "In6.Cu")
		(net "M_G_CPU1_SA_RSP<0>")
	)
	(segment
		(start 149.81174 -254.102362)
		(end 148.260562 -255.65354)
		(width 0.18288)
		(layer "In6.Cu")
		(net "M_G_CPU1_SA_RSP<0>")
	)
	(segment
		(start 168.98747 -250.442222)
		(end 168.303702 -251.12599)
		(width 0.18288)
		(layer "In6.Cu")
		(net "M_G_CPU1_SA_RSP<0>")
	)
	(segment
		(start 181.598316 -250.64593)
		(end 181.270656 -250.64593)
		(width 0.18288)
		(layer "In6.Cu")
		(net "M_G_CPU1_SA_RSP<0>")
	)
	(segment
		(start 137.392918 -253.57201)
		(end 137.334498 -253.51359)
		(width 0.088646)
		(layer "In6.Cu")
		(net "M_G_CPU1_SA_RSP<0>")
	)
	(segment
		(start 190.362332 -247.042178)
		(end 186.405774 -247.042178)
		(width 0.18288)
		(layer "In6.Cu")
		(net "M_G_CPU1_SA_RSP<0>")
	)
	(segment
		(start 186.405774 -247.042178)
		(end 185.17489 -248.273062)
		(width 0.18288)
		(layer "In6.Cu")
		(net "M_G_CPU1_SA_RSP<0>")
	)
	(segment
		(start 144.70507 -255.42875)
		(end 143.763238 -255.038606)
		(width 0.18288)
		(layer "In6.Cu")
		(net "M_G_CPU1_SA_RSP<0>")
	)
	(segment
		(start 165.489128 -253.013972)
		(end 156.656024 -253.013972)
		(width 0.18288)
		(layer "In6.Cu")
		(net "M_G_CPU1_SA_RSP<0>")
	)
	(segment
		(start 192.221866 -246.192294)
		(end 191.655446 -246.192294)
		(width 0.18288)
		(layer "In6.Cu")
		(net "M_G_CPU1_SA_RSP<0>")
	)
	(segment
		(start 195.427346 -244.066568)
		(end 195.401946 -244.066568)
		(width 0.18288)
		(layer "In6.Cu")
		(net "M_G_CPU1_SA_RSP<0>")
	)
	(segment
		(start 195.138294 -244.33022)
		(end 192.221866 -246.192294)
		(width 0.18288)
		(layer "In6.Cu")
		(net "M_G_CPU1_SA_RSP<0>")
	)
	(segment
		(start 156.656024 -253.013972)
		(end 155.567634 -254.102362)
		(width 0.18288)
		(layer "In6.Cu")
		(net "M_G_CPU1_SA_RSP<0>")
	)
	(segment
		(start 191.655446 -246.192294)
		(end 190.362332 -247.042178)
		(width 0.18288)
		(layer "In6.Cu")
		(net "M_G_CPU1_SA_RSP<0>")
	)
	(segment
		(start 181.087776 -249.6312)
		(end 180.904896 -249.44832)
		(width 0.18288)
		(layer "In6.Cu")
		(net "M_G_CPU1_SA_RSP<0>")
	)
	(segment
		(start 189.876176 -259.366766)
		(end 190.768478 -258.474464)
		(width 0.20066)
		(layer "F.Cu")
		(net "M_G_CPU1_SA_PAR")
	)
	(segment
		(start 191.144906 -258.474464)
		(end 191.612266 -258.941824)
		(width 0.20066)
		(layer "F.Cu")
		(net "M_G_CPU1_SA_PAR")
	)
	(segment
		(start 191.891158 -258.941824)
		(end 191.911478 -258.941824)
		(width 0.101854)
		(layer "F.Cu")
		(net "M_G_CPU1_SA_PAR")
	)
	(segment
		(start 194.653408 -258.95427)
		(end 195.065904 -259.366766)
		(width 0.20066)
		(layer "F.Cu")
		(net "M_G_CPU1_SA_PAR")
	)
	(segment
		(start 188.988446 -259.366766)
		(end 189.876176 -259.366766)
		(width 0.20066)
		(layer "F.Cu")
		(net "M_G_CPU1_SA_PAR")
	)
	(segment
		(start 127.146812 -248.527824)
		(end 127.146812 -247.992138)
		(width 0.20066)
		(layer "F.Cu")
		(net "M_G_CPU1_SA_PAR")
	)
	(segment
		(start 127.147066 -248.528078)
		(end 127.146812 -248.527824)
		(width 0.20066)
		(layer "F.Cu")
		(net "M_G_CPU1_SA_PAR")
	)
	(segment
		(start 194.08648 -258.941824)
		(end 194.098926 -258.95427)
		(width 0.1016)
		(layer "F.Cu")
		(net "M_G_CPU1_SA_PAR")
	)
	(segment
		(start 194.098926 -258.95427)
		(end 194.653408 -258.95427)
		(width 0.20066)
		(layer "F.Cu")
		(net "M_G_CPU1_SA_PAR")
	)
	(segment
		(start 190.768478 -258.474464)
		(end 191.144906 -258.474464)
		(width 0.20066)
		(layer "F.Cu")
		(net "M_G_CPU1_SA_PAR")
	)
	(segment
		(start 191.612266 -258.941824)
		(end 191.891158 -258.941824)
		(width 0.20066)
		(layer "F.Cu")
		(net "M_G_CPU1_SA_PAR")
	)
	(segment
		(start 195.065904 -259.366766)
		(end 196.532246 -259.366766)
		(width 0.20066)
		(layer "F.Cu")
		(net "M_G_CPU1_SA_PAR")
	)
	(segment
		(start 191.911478 -258.941824)
		(end 194.08648 -258.941824)
		(width 0.1016)
		(layer "F.Cu")
		(net "M_G_CPU1_SA_PAR")
	)
	(segment
		(start 187.883546 -259.366766)
		(end 188.988446 -259.366766)
		(width 0.20066)
		(layer "F.Cu")
		(net "M_G_CPU1_SA_PAR")
	)
	(segment
		(start 142.114778 -252.398022)
		(end 127.226314 -252.398022)
		(width 0.18288)
		(layer "In4.Cu")
		(net "M_G_CPU1_SA_PAR")
	)
	(segment
		(start 125.907546 -250.110244)
		(end 125.832616 -250.035314)
		(width 0.088646)
		(layer "In4.Cu")
		(net "M_G_CPU1_SA_PAR")
	)
	(segment
		(start 127.146812 -248.367042)
		(end 127.146812 -247.992138)
		(width 0.088646)
		(layer "In4.Cu")
		(net "M_G_CPU1_SA_PAR")
	)
	(segment
		(start 146.534632 -254.896112)
		(end 145.405094 -254.896112)
		(width 0.18288)
		(layer "In4.Cu")
		(net "M_G_CPU1_SA_PAR")
	)
	(segment
		(start 187.266326 -259.159756)
		(end 187.266326 -258.38531)
		(width 0.18288)
		(layer "In4.Cu")
		(net "M_G_CPU1_SA_PAR")
	)
	(segment
		(start 126.116588 -249.239786)
		(end 126.621794 -249.239786)
		(width 0.088646)
		(layer "In4.Cu")
		(net "M_G_CPU1_SA_PAR")
	)
	(segment
		(start 125.907546 -250.320048)
		(end 125.907546 -250.110244)
		(width 0.088646)
		(layer "In4.Cu")
		(net "M_G_CPU1_SA_PAR")
	)
	(segment
		(start 127.147066 -248.367296)
		(end 127.146812 -248.367042)
		(width 0.088646)
		(layer "In4.Cu")
		(net "M_G_CPU1_SA_PAR")
	)
	(segment
		(start 159.332676 -256.758186)
		(end 156.39288 -255.54051)
		(width 0.18288)
		(layer "In4.Cu")
		(net "M_G_CPU1_SA_PAR")
	)
	(segment
		(start 187.883546 -259.366766)
		(end 187.473336 -259.366766)
		(width 0.18288)
		(layer "In4.Cu")
		(net "M_G_CPU1_SA_PAR")
	)
	(segment
		(start 148.98243 -253.365254)
		(end 148.09978 -254.247904)
		(width 0.18288)
		(layer "In4.Cu")
		(net "M_G_CPU1_SA_PAR")
	)
	(segment
		(start 187.393072 -259.333492)
		(end 187.2996 -259.24002)
		(width 0.18288)
		(layer "In4.Cu")
		(net "M_G_CPU1_SA_PAR")
	)
	(segment
		(start 154.217624 -253.365254)
		(end 148.98243 -253.365254)
		(width 0.18288)
		(layer "In4.Cu")
		(net "M_G_CPU1_SA_PAR")
	)
	(segment
		(start 187.219082 -258.271518)
		(end 186.479434 -257.53187)
		(width 0.18288)
		(layer "In4.Cu")
		(net "M_G_CPU1_SA_PAR")
	)
	(segment
		(start 125.832616 -250.035314)
		(end 125.832616 -249.611388)
		(width 0.088646)
		(layer "In4.Cu")
		(net "M_G_CPU1_SA_PAR")
	)
	(segment
		(start 156.39288 -255.54051)
		(end 154.217624 -253.365254)
		(width 0.18288)
		(layer "In4.Cu")
		(net "M_G_CPU1_SA_PAR")
	)
	(segment
		(start 125.907546 -251.079254)
		(end 125.907546 -250.320048)
		(width 0.18288)
		(layer "In4.Cu")
		(net "M_G_CPU1_SA_PAR")
	)
	(segment
		(start 148.09978 -254.247904)
		(end 146.534632 -254.896112)
		(width 0.18288)
		(layer "In4.Cu")
		(net "M_G_CPU1_SA_PAR")
	)
	(segment
		(start 127.226314 -252.398022)
		(end 125.907546 -251.079254)
		(width 0.18288)
		(layer "In4.Cu")
		(net "M_G_CPU1_SA_PAR")
	)
	(segment
		(start 145.405094 -254.896112)
		(end 144.052544 -254.335788)
		(width 0.18288)
		(layer "In4.Cu")
		(net "M_G_CPU1_SA_PAR")
	)
	(segment
		(start 144.052544 -254.335788)
		(end 142.114778 -252.398022)
		(width 0.18288)
		(layer "In4.Cu")
		(net "M_G_CPU1_SA_PAR")
	)
	(segment
		(start 127.147066 -248.793762)
		(end 127.147066 -248.367296)
		(width 0.088646)
		(layer "In4.Cu")
		(net "M_G_CPU1_SA_PAR")
	)
	(segment
		(start 126.019814 -249.295666)
		(end 126.116588 -249.239786)
		(width 0.088646)
		(layer "In4.Cu")
		(net "M_G_CPU1_SA_PAR")
	)
	(segment
		(start 186.365642 -257.484626)
		(end 162.984434 -257.484626)
		(width 0.18288)
		(layer "In4.Cu")
		(net "M_G_CPU1_SA_PAR")
	)
	(segment
		(start 162.984434 -257.484626)
		(end 159.332676 -256.758186)
		(width 0.18288)
		(layer "In4.Cu")
		(net "M_G_CPU1_SA_PAR")
	)
	(arc
		(start 187.266326 -258.38531)
		(mid 187.254068 -258.323684)
		(end 187.219082 -258.271518)
		(width 0.18288)
		(layer "In4.Cu")
		(net "M_G_CPU1_SA_PAR")
	)
	(arc
		(start 126.621794 -249.239786)
		(mid 126.844191 -249.195548)
		(end 127.032766 -249.069606)
		(width 0.088646)
		(layer "In4.Cu")
		(net "M_G_CPU1_SA_PAR")
	)
	(arc
		(start 186.479434 -257.53187)
		(mid 186.427226 -257.496986)
		(end 186.365642 -257.484626)
		(width 0.18288)
		(layer "In4.Cu")
		(net "M_G_CPU1_SA_PAR")
	)
	(arc
		(start 125.832616 -249.611388)
		(mid 125.884886 -249.429023)
		(end 126.019814 -249.295666)
		(width 0.088646)
		(layer "In4.Cu")
		(net "M_G_CPU1_SA_PAR")
	)
	(arc
		(start 187.2996 -259.24002)
		(mid 187.27494 -259.203209)
		(end 187.266326 -259.159756)
		(width 0.18288)
		(layer "In4.Cu")
		(net "M_G_CPU1_SA_PAR")
	)
	(arc
		(start 187.473336 -259.366766)
		(mid 187.429901 -259.358108)
		(end 187.393072 -259.333492)
		(width 0.18288)
		(layer "In4.Cu")
		(net "M_G_CPU1_SA_PAR")
	)
	(arc
		(start 127.032766 -249.069606)
		(mid 127.11733 -248.943048)
		(end 127.147066 -248.793762)
		(width 0.088646)
		(layer "In4.Cu")
		(net "M_G_CPU1_SA_PAR")
	)
	(segment
		(start 199.796146 -274.084796)
		(end 200.06437 -273.816572)
		(width 0.20066)
		(layer "F.Cu")
		(net "M_G_CPU1_SA_DQS_DP<9>")
	)
	(segment
		(start 128.196848 -262.87222)
		(end 128.196594 -262.872474)
		(width 0.20066)
		(layer "F.Cu")
		(net "M_G_CPU1_SA_DQS_DP<9>")
	)
	(segment
		(start 200.06437 -273.816572)
		(end 200.632314 -273.816572)
		(width 0.20066)
		(layer "F.Cu")
		(net "M_G_CPU1_SA_DQS_DP<9>")
	)
	(segment
		(start 195.288916 -273.39163)
		(end 195.522596 -273.39163)
		(width 0.101854)
		(layer "F.Cu")
		(net "M_G_CPU1_SA_DQS_DP<9>")
	)
	(segment
		(start 193.088514 -273.816572)
		(end 193.681858 -273.816572)
		(width 0.20066)
		(layer "F.Cu")
		(net "M_G_CPU1_SA_DQS_DP<9>")
	)
	(segment
		(start 191.983614 -273.816572)
		(end 193.088514 -273.816572)
		(width 0.20066)
		(layer "F.Cu")
		(net "M_G_CPU1_SA_DQS_DP<9>")
	)
	(segment
		(start 195.180966 -273.39163)
		(end 195.288916 -273.39163)
		(width 0.20066)
		(layer "F.Cu")
		(net "M_G_CPU1_SA_DQS_DP<9>")
	)
	(segment
		(start 199.21855 -274.084796)
		(end 199.796146 -274.084796)
		(width 0.20066)
		(layer "F.Cu")
		(net "M_G_CPU1_SA_DQS_DP<9>")
	)
	(segment
		(start 128.196848 -262.336534)
		(end 128.196848 -262.87222)
		(width 0.20066)
		(layer "F.Cu")
		(net "M_G_CPU1_SA_DQS_DP<9>")
	)
	(segment
		(start 193.933064 -274.067778)
		(end 194.237864 -274.067778)
		(width 0.20066)
		(layer "F.Cu")
		(net "M_G_CPU1_SA_DQS_DP<9>")
	)
	(segment
		(start 193.681858 -273.816572)
		(end 193.933064 -274.067778)
		(width 0.20066)
		(layer "F.Cu")
		(net "M_G_CPU1_SA_DQS_DP<9>")
	)
	(segment
		(start 197.871842 -273.39163)
		(end 198.119492 -273.63928)
		(width 0.20066)
		(layer "F.Cu")
		(net "M_G_CPU1_SA_DQS_DP<9>")
	)
	(segment
		(start 197.535292 -273.39163)
		(end 197.721474 -273.39163)
		(width 0.101854)
		(layer "F.Cu")
		(net "M_G_CPU1_SA_DQS_DP<9>")
	)
	(segment
		(start 194.237864 -274.067778)
		(end 194.662806 -273.642836)
		(width 0.20066)
		(layer "F.Cu")
		(net "M_G_CPU1_SA_DQS_DP<9>")
	)
	(segment
		(start 195.522596 -273.39163)
		(end 197.535292 -273.39163)
		(width 0.1016)
		(layer "F.Cu")
		(net "M_G_CPU1_SA_DQS_DP<9>")
	)
	(segment
		(start 197.721474 -273.39163)
		(end 197.871842 -273.39163)
		(width 0.20066)
		(layer "F.Cu")
		(net "M_G_CPU1_SA_DQS_DP<9>")
	)
	(segment
		(start 194.662806 -273.642836)
		(end 194.92976 -273.642836)
		(width 0.20066)
		(layer "F.Cu")
		(net "M_G_CPU1_SA_DQS_DP<9>")
	)
	(segment
		(start 194.92976 -273.642836)
		(end 195.180966 -273.39163)
		(width 0.20066)
		(layer "F.Cu")
		(net "M_G_CPU1_SA_DQS_DP<9>")
	)
	(segment
		(start 198.773034 -273.63928)
		(end 199.21855 -274.084796)
		(width 0.20066)
		(layer "F.Cu")
		(net "M_G_CPU1_SA_DQS_DP<9>")
	)
	(segment
		(start 198.119492 -273.63928)
		(end 198.773034 -273.63928)
		(width 0.20066)
		(layer "F.Cu")
		(net "M_G_CPU1_SA_DQS_DP<9>")
	)
	(segment
		(start 129.139442 -262.480298)
		(end 129.089658 -262.500872)
		(width 0.088646)
		(layer "In6.Cu")
		(net "M_G_CPU1_SA_DQS_DP<9>")
	)
	(segment
		(start 128.709166 -262.872474)
		(end 128.196594 -262.872474)
		(width 0.088646)
		(layer "In6.Cu")
		(net "M_G_CPU1_SA_DQS_DP<9>")
	)
	(segment
		(start 128.947672 -262.548878)
		(end 128.940306 -262.553196)
		(width 0.088646)
		(layer "In6.Cu")
		(net "M_G_CPU1_SA_DQS_DP<9>")
	)
	(segment
		(start 142.902432 -261.528306)
		(end 140.900404 -261.528306)
		(width 0.18288)
		(layer "In6.Cu")
		(net "M_G_CPU1_SA_DQS_DP<9>")
	)
	(segment
		(start 140.900404 -261.528306)
		(end 140.877036 -261.528306)
		(width 0.088646)
		(layer "In6.Cu")
		(net "M_G_CPU1_SA_DQS_DP<9>")
	)
	(segment
		(start 129.159254 -262.476488)
		(end 129.139442 -262.480298)
		(width 0.088646)
		(layer "In6.Cu")
		(net "M_G_CPU1_SA_DQS_DP<9>")
	)
	(segment
		(start 161.026856 -263.4742)
		(end 160.43656 -262.883904)
		(width 0.18288)
		(layer "In6.Cu")
		(net "M_G_CPU1_SA_DQS_DP<9>")
	)
	(segment
		(start 188.359288 -273.666966)
		(end 188.08573 -273.393408)
		(width 0.18288)
		(layer "In6.Cu")
		(net "M_G_CPU1_SA_DQS_DP<9>")
	)
	(segment
		(start 140.47216 -261.587996)
		(end 140.377418 -261.493254)
		(width 0.088646)
		(layer "In6.Cu")
		(net "M_G_CPU1_SA_DQS_DP<9>")
	)
	(segment
		(start 191.983614 -273.816572)
		(end 191.702944 -274.097242)
		(width 0.18288)
		(layer "In6.Cu")
		(net "M_G_CPU1_SA_DQS_DP<9>")
	)
	(segment
		(start 130.748278 -262.37438)
		(end 130.733546 -262.383016)
		(width 0.088646)
		(layer "In6.Cu")
		(net "M_G_CPU1_SA_DQS_DP<9>")
	)
	(segment
		(start 173.313598 -263.440418)
		(end 173.06544 -263.19226)
		(width 0.18288)
		(layer "In6.Cu")
		(net "M_G_CPU1_SA_DQS_DP<9>")
	)
	(segment
		(start 164.108638 -263.4742)
		(end 161.026856 -263.4742)
		(width 0.18288)
		(layer "In6.Cu")
		(net "M_G_CPU1_SA_DQS_DP<9>")
	)
	(segment
		(start 172.536612 -263.19226)
		(end 172.24502 -263.483852)
		(width 0.18288)
		(layer "In6.Cu")
		(net "M_G_CPU1_SA_DQS_DP<9>")
	)
	(segment
		(start 138.817096 -262.383016)
		(end 138.802364 -262.37438)
		(width 0.088646)
		(layer "In6.Cu")
		(net "M_G_CPU1_SA_DQS_DP<9>")
	)
	(segment
		(start 185.345578 -272.598896)
		(end 184.297066 -272.037048)
		(width 0.18288)
		(layer "In6.Cu")
		(net "M_G_CPU1_SA_DQS_DP<9>")
	)
	(segment
		(start 167.892984 -262.868918)
		(end 164.71392 -262.868918)
		(width 0.18288)
		(layer "In6.Cu")
		(net "M_G_CPU1_SA_DQS_DP<9>")
	)
	(segment
		(start 139.200382 -262.377936)
		(end 139.191492 -262.383016)
		(width 0.088646)
		(layer "In6.Cu")
		(net "M_G_CPU1_SA_DQS_DP<9>")
	)
	(segment
		(start 189.947296 -273.085052)
		(end 188.54293 -273.666966)
		(width 0.18288)
		(layer "In6.Cu")
		(net "M_G_CPU1_SA_DQS_DP<9>")
	)
	(segment
		(start 164.71392 -262.868918)
		(end 164.108638 -263.4742)
		(width 0.18288)
		(layer "In6.Cu")
		(net "M_G_CPU1_SA_DQS_DP<9>")
	)
	(segment
		(start 190.431928 -273.085052)
		(end 189.947296 -273.085052)
		(width 0.18288)
		(layer "In6.Cu")
		(net "M_G_CPU1_SA_DQS_DP<9>")
	)
	(segment
		(start 157.217364 -262.883904)
		(end 156.316172 -261.982712)
		(width 0.18288)
		(layer "In6.Cu")
		(net "M_G_CPU1_SA_DQS_DP<9>")
	)
	(segment
		(start 182.78475 -264.459466)
		(end 179.747672 -264.459466)
		(width 0.18288)
		(layer "In6.Cu")
		(net "M_G_CPU1_SA_DQS_DP<9>")
	)
	(segment
		(start 145.186654 -261.982712)
		(end 142.902432 -261.528306)
		(width 0.18288)
		(layer "In6.Cu")
		(net "M_G_CPU1_SA_DQS_DP<9>")
	)
	(segment
		(start 140.377418 -261.493254)
		(end 139.944094 -261.493254)
		(width 0.088646)
		(layer "In6.Cu")
		(net "M_G_CPU1_SA_DQS_DP<9>")
	)
	(segment
		(start 176.37887 -264.299954)
		(end 174.8917 -264.299954)
		(width 0.18288)
		(layer "In6.Cu")
		(net "M_G_CPU1_SA_DQS_DP<9>")
	)
	(segment
		(start 132.623306 -262.37692)
		(end 132.612892 -262.383016)
		(width 0.088646)
		(layer "In6.Cu")
		(net "M_G_CPU1_SA_DQS_DP<9>")
	)
	(segment
		(start 179.24526 -264.961878)
		(end 178.900836 -264.961878)
		(width 0.18288)
		(layer "In6.Cu")
		(net "M_G_CPU1_SA_DQS_DP<9>")
	)
	(segment
		(start 134.50316 -262.37692)
		(end 134.492746 -262.383016)
		(width 0.088646)
		(layer "In6.Cu")
		(net "M_G_CPU1_SA_DQS_DP<9>")
	)
	(segment
		(start 183.950102 -271.457928)
		(end 183.950102 -265.624818)
		(width 0.18288)
		(layer "In6.Cu")
		(net "M_G_CPU1_SA_DQS_DP<9>")
	)
	(segment
		(start 183.950102 -265.624818)
		(end 182.78475 -264.459466)
		(width 0.18288)
		(layer "In6.Cu")
		(net "M_G_CPU1_SA_DQS_DP<9>")
	)
	(segment
		(start 178.900836 -264.961878)
		(end 178.27498 -264.336022)
		(width 0.18288)
		(layer "In6.Cu")
		(net "M_G_CPU1_SA_DQS_DP<9>")
	)
	(segment
		(start 160.43656 -262.883904)
		(end 157.217364 -262.883904)
		(width 0.18288)
		(layer "In6.Cu")
		(net "M_G_CPU1_SA_DQS_DP<9>")
	)
	(segment
		(start 130.366262 -262.386826)
		(end 130.35915 -262.383016)
		(width 0.088646)
		(layer "In6.Cu")
		(net "M_G_CPU1_SA_DQS_DP<9>")
	)
	(segment
		(start 136.937496 -262.383016)
		(end 136.937242 -262.382762)
		(width 0.088646)
		(layer "In6.Cu")
		(net "M_G_CPU1_SA_DQS_DP<9>")
	)
	(segment
		(start 191.702944 -274.097242)
		(end 191.444118 -274.097242)
		(width 0.18288)
		(layer "In6.Cu")
		(net "M_G_CPU1_SA_DQS_DP<9>")
	)
	(segment
		(start 140.877036 -261.528306)
		(end 140.817346 -261.587996)
		(width 0.088646)
		(layer "In6.Cu")
		(net "M_G_CPU1_SA_DQS_DP<9>")
	)
	(segment
		(start 129.532634 -262.476488)
		(end 129.159254 -262.476488)
		(width 0.088646)
		(layer "In6.Cu")
		(net "M_G_CPU1_SA_DQS_DP<9>")
	)
	(segment
		(start 177.459386 -264.336022)
		(end 177.165508 -264.042144)
		(width 0.18288)
		(layer "In6.Cu")
		(net "M_G_CPU1_SA_DQS_DP<9>")
	)
	(segment
		(start 186.131708 -273.384518)
		(end 185.345578 -272.598896)
		(width 0.18288)
		(layer "In6.Cu")
		(net "M_G_CPU1_SA_DQS_DP<9>")
	)
	(segment
		(start 140.817346 -261.587996)
		(end 140.47216 -261.587996)
		(width 0.088646)
		(layer "In6.Cu")
		(net "M_G_CPU1_SA_DQS_DP<9>")
	)
	(segment
		(start 191.444118 -274.097242)
		(end 190.431928 -273.085052)
		(width 0.18288)
		(layer "In6.Cu")
		(net "M_G_CPU1_SA_DQS_DP<9>")
	)
	(segment
		(start 188.08573 -273.393408)
		(end 187.62345 -273.393408)
		(width 0.18288)
		(layer "In6.Cu")
		(net "M_G_CPU1_SA_DQS_DP<9>")
	)
	(segment
		(start 173.06544 -263.19226)
		(end 172.536612 -263.19226)
		(width 0.18288)
		(layer "In6.Cu")
		(net "M_G_CPU1_SA_DQS_DP<9>")
	)
	(segment
		(start 129.701798 -262.436864)
		(end 129.532634 -262.476488)
		(width 0.088646)
		(layer "In6.Cu")
		(net "M_G_CPU1_SA_DQS_DP<9>")
	)
	(segment
		(start 129.808478 -262.37438)
		(end 129.701798 -262.436864)
		(width 0.088646)
		(layer "In6.Cu")
		(net "M_G_CPU1_SA_DQS_DP<9>")
	)
	(segment
		(start 186.874404 -273.693636)
		(end 186.131708 -273.384518)
		(width 0.18288)
		(layer "In6.Cu")
		(net "M_G_CPU1_SA_DQS_DP<9>")
	)
	(segment
		(start 172.24502 -263.483852)
		(end 168.507918 -263.483852)
		(width 0.18288)
		(layer "In6.Cu")
		(net "M_G_CPU1_SA_DQS_DP<9>")
	)
	(segment
		(start 184.067704 -271.65427)
		(end 183.950102 -271.457928)
		(width 0.18288)
		(layer "In6.Cu")
		(net "M_G_CPU1_SA_DQS_DP<9>")
	)
	(segment
		(start 133.567678 -262.37438)
		(end 133.552946 -262.383016)
		(width 0.088646)
		(layer "In6.Cu")
		(net "M_G_CPU1_SA_DQS_DP<9>")
	)
	(segment
		(start 178.27498 -264.336022)
		(end 177.459386 -264.336022)
		(width 0.18288)
		(layer "In6.Cu")
		(net "M_G_CPU1_SA_DQS_DP<9>")
	)
	(segment
		(start 168.507918 -263.483852)
		(end 167.892984 -262.868918)
		(width 0.18288)
		(layer "In6.Cu")
		(net "M_G_CPU1_SA_DQS_DP<9>")
	)
	(segment
		(start 188.54293 -273.666966)
		(end 188.359288 -273.666966)
		(width 0.18288)
		(layer "In6.Cu")
		(net "M_G_CPU1_SA_DQS_DP<9>")
	)
	(segment
		(start 176.63668 -264.042144)
		(end 176.37887 -264.299954)
		(width 0.18288)
		(layer "In6.Cu")
		(net "M_G_CPU1_SA_DQS_DP<9>")
	)
	(segment
		(start 179.747672 -264.459466)
		(end 179.24526 -264.961878)
		(width 0.18288)
		(layer "In6.Cu")
		(net "M_G_CPU1_SA_DQS_DP<9>")
	)
	(segment
		(start 135.997188 -262.38327)
		(end 135.997442 -262.382762)
		(width 0.088646)
		(layer "In6.Cu")
		(net "M_G_CPU1_SA_DQS_DP<9>")
	)
	(segment
		(start 132.238496 -262.383016)
		(end 132.228082 -262.37692)
		(width 0.088646)
		(layer "In6.Cu")
		(net "M_G_CPU1_SA_DQS_DP<9>")
	)
	(segment
		(start 128.766316 -262.815324)
		(end 128.709166 -262.872474)
		(width 0.088646)
		(layer "In6.Cu")
		(net "M_G_CPU1_SA_DQS_DP<9>")
	)
	(segment
		(start 187.62345 -273.393408)
		(end 187.323222 -273.693636)
		(width 0.18288)
		(layer "In6.Cu")
		(net "M_G_CPU1_SA_DQS_DP<9>")
	)
	(segment
		(start 187.323222 -273.693636)
		(end 186.874404 -273.693636)
		(width 0.18288)
		(layer "In6.Cu")
		(net "M_G_CPU1_SA_DQS_DP<9>")
	)
	(segment
		(start 139.37869 -262.048752)
		(end 139.378944 -262.058658)
		(width 0.088646)
		(layer "In6.Cu")
		(net "M_G_CPU1_SA_DQS_DP<9>")
	)
	(segment
		(start 184.297066 -272.037048)
		(end 184.067704 -271.65427)
		(width 0.18288)
		(layer "In6.Cu")
		(net "M_G_CPU1_SA_DQS_DP<9>")
	)
	(segment
		(start 128.949196 -262.548116)
		(end 128.947672 -262.548878)
		(width 0.088646)
		(layer "In6.Cu")
		(net "M_G_CPU1_SA_DQS_DP<9>")
	)
	(segment
		(start 136.372092 -262.383016)
		(end 136.372346 -262.38327)
		(width 0.088646)
		(layer "In6.Cu")
		(net "M_G_CPU1_SA_DQS_DP<9>")
	)
	(segment
		(start 174.032164 -263.440418)
		(end 173.313598 -263.440418)
		(width 0.18288)
		(layer "In6.Cu")
		(net "M_G_CPU1_SA_DQS_DP<9>")
	)
	(segment
		(start 177.165508 -264.042144)
		(end 176.63668 -264.042144)
		(width 0.18288)
		(layer "In6.Cu")
		(net "M_G_CPU1_SA_DQS_DP<9>")
	)
	(segment
		(start 156.316172 -261.982712)
		(end 145.186654 -261.982712)
		(width 0.18288)
		(layer "In6.Cu")
		(net "M_G_CPU1_SA_DQS_DP<9>")
	)
	(segment
		(start 174.8917 -264.299954)
		(end 174.032164 -263.440418)
		(width 0.18288)
		(layer "In6.Cu")
		(net "M_G_CPU1_SA_DQS_DP<9>")
	)
	(arc
		(start 130.733546 -262.383016)
		(mid 130.550413 -262.433013)
		(end 130.366262 -262.386826)
		(width 0.088646)
		(layer "In6.Cu")
		(net "M_G_CPU1_SA_DQS_DP<9>")
	)
	(arc
		(start 134.11835 -262.383016)
		(mid 133.844151 -262.307181)
		(end 133.567678 -262.37438)
		(width 0.088646)
		(layer "In6.Cu")
		(net "M_G_CPU1_SA_DQS_DP<9>")
	)
	(arc
		(start 132.612892 -262.383016)
		(mid 132.425694 -262.433159)
		(end 132.238496 -262.383016)
		(width 0.088646)
		(layer "In6.Cu")
		(net "M_G_CPU1_SA_DQS_DP<9>")
	)
	(arc
		(start 135.057896 -262.383016)
		(mid 134.781337 -262.307273)
		(end 134.50316 -262.37692)
		(width 0.088646)
		(layer "In6.Cu")
		(net "M_G_CPU1_SA_DQS_DP<9>")
	)
	(arc
		(start 137.311892 -262.383016)
		(mid 137.124694 -262.433159)
		(end 136.937496 -262.383016)
		(width 0.088646)
		(layer "In6.Cu")
		(net "M_G_CPU1_SA_DQS_DP<9>")
	)
	(arc
		(start 136.937242 -262.382762)
		(mid 136.654621 -262.307147)
		(end 136.372092 -262.383016)
		(width 0.088646)
		(layer "In6.Cu")
		(net "M_G_CPU1_SA_DQS_DP<9>")
	)
	(arc
		(start 138.802364 -262.37438)
		(mid 138.525889 -262.30706)
		(end 138.251692 -262.383016)
		(width 0.088646)
		(layer "In6.Cu")
		(net "M_G_CPU1_SA_DQS_DP<9>")
	)
	(arc
		(start 134.492746 -262.383016)
		(mid 134.305548 -262.433159)
		(end 134.11835 -262.383016)
		(width 0.088646)
		(layer "In6.Cu")
		(net "M_G_CPU1_SA_DQS_DP<9>")
	)
	(arc
		(start 139.378944 -262.058658)
		(mid 139.331265 -262.241558)
		(end 139.200382 -262.377936)
		(width 0.088646)
		(layer "In6.Cu")
		(net "M_G_CPU1_SA_DQS_DP<9>")
	)
	(arc
		(start 135.997442 -262.382762)
		(mid 135.714821 -262.307147)
		(end 135.432292 -262.383016)
		(width 0.088646)
		(layer "In6.Cu")
		(net "M_G_CPU1_SA_DQS_DP<9>")
	)
	(arc
		(start 129.089658 -262.500872)
		(mid 129.017061 -262.517464)
		(end 128.949196 -262.548116)
		(width 0.088646)
		(layer "In6.Cu")
		(net "M_G_CPU1_SA_DQS_DP<9>")
	)
	(arc
		(start 131.673346 -262.383016)
		(mid 131.486148 -262.433159)
		(end 131.29895 -262.383016)
		(width 0.088646)
		(layer "In6.Cu")
		(net "M_G_CPU1_SA_DQS_DP<9>")
	)
	(arc
		(start 136.372346 -262.38327)
		(mid 136.184784 -262.433506)
		(end 135.997188 -262.38327)
		(width 0.088646)
		(layer "In6.Cu")
		(net "M_G_CPU1_SA_DQS_DP<9>")
	)
	(arc
		(start 130.35915 -262.383016)
		(mid 130.084951 -262.307181)
		(end 129.808478 -262.37438)
		(width 0.088646)
		(layer "In6.Cu")
		(net "M_G_CPU1_SA_DQS_DP<9>")
	)
	(arc
		(start 137.877296 -262.383016)
		(mid 137.594594 -262.30724)
		(end 137.311892 -262.383016)
		(width 0.088646)
		(layer "In6.Cu")
		(net "M_G_CPU1_SA_DQS_DP<9>")
	)
	(arc
		(start 135.432292 -262.383016)
		(mid 135.245094 -262.433159)
		(end 135.057896 -262.383016)
		(width 0.088646)
		(layer "In6.Cu")
		(net "M_G_CPU1_SA_DQS_DP<9>")
	)
	(arc
		(start 133.17855 -262.383016)
		(mid 132.901737 -262.307146)
		(end 132.623306 -262.37692)
		(width 0.088646)
		(layer "In6.Cu")
		(net "M_G_CPU1_SA_DQS_DP<9>")
	)
	(arc
		(start 133.552946 -262.383016)
		(mid 133.365748 -262.433159)
		(end 133.17855 -262.383016)
		(width 0.088646)
		(layer "In6.Cu")
		(net "M_G_CPU1_SA_DQS_DP<9>")
	)
	(arc
		(start 128.940306 -262.553196)
		(mid 128.824497 -262.665125)
		(end 128.766316 -262.815324)
		(width 0.088646)
		(layer "In6.Cu")
		(net "M_G_CPU1_SA_DQS_DP<9>")
	)
	(arc
		(start 131.29895 -262.383016)
		(mid 131.024751 -262.307181)
		(end 130.748278 -262.37438)
		(width 0.088646)
		(layer "In6.Cu")
		(net "M_G_CPU1_SA_DQS_DP<9>")
	)
	(arc
		(start 139.64031 -261.581646)
		(mid 139.450711 -261.782265)
		(end 139.37869 -262.048752)
		(width 0.088646)
		(layer "In6.Cu")
		(net "M_G_CPU1_SA_DQS_DP<9>")
	)
	(arc
		(start 138.251692 -262.383016)
		(mid 138.064494 -262.433159)
		(end 137.877296 -262.383016)
		(width 0.088646)
		(layer "In6.Cu")
		(net "M_G_CPU1_SA_DQS_DP<9>")
	)
	(arc
		(start 139.661392 -261.568946)
		(mid 139.650783 -261.575183)
		(end 139.64031 -261.581646)
		(width 0.088646)
		(layer "In6.Cu")
		(net "M_G_CPU1_SA_DQS_DP<9>")
	)
	(arc
		(start 139.944094 -261.493254)
		(mid 139.79775 -261.512462)
		(end 139.661392 -261.568946)
		(width 0.088646)
		(layer "In6.Cu")
		(net "M_G_CPU1_SA_DQS_DP<9>")
	)
	(arc
		(start 132.228082 -262.37692)
		(mid 131.949904 -262.307197)
		(end 131.673346 -262.383016)
		(width 0.088646)
		(layer "In6.Cu")
		(net "M_G_CPU1_SA_DQS_DP<9>")
	)
	(arc
		(start 139.191492 -262.383016)
		(mid 139.004294 -262.433159)
		(end 138.817096 -262.383016)
		(width 0.088646)
		(layer "In6.Cu")
		(net "M_G_CPU1_SA_DQS_DP<9>")
	)
	(segment
		(start 199.796146 -283.43479)
		(end 200.06437 -283.166566)
		(width 0.20066)
		(layer "F.Cu")
		(net "M_G_CPU1_SA_DQS_DP<8>")
	)
	(segment
		(start 193.681858 -283.166566)
		(end 193.933064 -283.417772)
		(width 0.20066)
		(layer "F.Cu")
		(net "M_G_CPU1_SA_DQS_DP<8>")
	)
	(segment
		(start 195.510658 -282.734512)
		(end 195.515484 -282.734512)
		(width 0.101854)
		(layer "F.Cu")
		(net "M_G_CPU1_SA_DQS_DP<8>")
	)
	(segment
		(start 193.933064 -283.417772)
		(end 194.237864 -283.417772)
		(width 0.20066)
		(layer "F.Cu")
		(net "M_G_CPU1_SA_DQS_DP<8>")
	)
	(segment
		(start 198.119492 -282.989274)
		(end 198.773034 -282.989274)
		(width 0.20066)
		(layer "F.Cu")
		(net "M_G_CPU1_SA_DQS_DP<8>")
	)
	(segment
		(start 200.06437 -283.166566)
		(end 200.632314 -283.166566)
		(width 0.20066)
		(layer "F.Cu")
		(net "M_G_CPU1_SA_DQS_DP<8>")
	)
	(segment
		(start 193.088514 -283.166566)
		(end 193.681858 -283.166566)
		(width 0.20066)
		(layer "F.Cu")
		(net "M_G_CPU1_SA_DQS_DP<8>")
	)
	(segment
		(start 194.237864 -283.417772)
		(end 194.662806 -282.99283)
		(width 0.20066)
		(layer "F.Cu")
		(net "M_G_CPU1_SA_DQS_DP<8>")
	)
	(segment
		(start 194.94119 -282.99283)
		(end 195.199508 -282.734512)
		(width 0.20066)
		(layer "F.Cu")
		(net "M_G_CPU1_SA_DQS_DP<8>")
	)
	(segment
		(start 128.196594 -267.220192)
		(end 128.196594 -267.755878)
		(width 0.20066)
		(layer "F.Cu")
		(net "M_G_CPU1_SA_DQS_DP<8>")
	)
	(segment
		(start 199.21855 -283.43479)
		(end 199.796146 -283.43479)
		(width 0.20066)
		(layer "F.Cu")
		(net "M_G_CPU1_SA_DQS_DP<8>")
	)
	(segment
		(start 195.522596 -282.741624)
		(end 197.535292 -282.741624)
		(width 0.1016)
		(layer "F.Cu")
		(net "M_G_CPU1_SA_DQS_DP<8>")
	)
	(segment
		(start 195.199508 -282.734512)
		(end 195.510658 -282.734512)
		(width 0.20066)
		(layer "F.Cu")
		(net "M_G_CPU1_SA_DQS_DP<8>")
	)
	(segment
		(start 194.662806 -282.99283)
		(end 194.94119 -282.99283)
		(width 0.20066)
		(layer "F.Cu")
		(net "M_G_CPU1_SA_DQS_DP<8>")
	)
	(segment
		(start 198.773034 -282.989274)
		(end 199.21855 -283.43479)
		(width 0.20066)
		(layer "F.Cu")
		(net "M_G_CPU1_SA_DQS_DP<8>")
	)
	(segment
		(start 191.983614 -283.166566)
		(end 193.088514 -283.166566)
		(width 0.20066)
		(layer "F.Cu")
		(net "M_G_CPU1_SA_DQS_DP<8>")
	)
	(segment
		(start 197.864476 -282.734258)
		(end 198.119492 -282.989274)
		(width 0.20066)
		(layer "F.Cu")
		(net "M_G_CPU1_SA_DQS_DP<8>")
	)
	(segment
		(start 197.542658 -282.734258)
		(end 197.864476 -282.734258)
		(width 0.20066)
		(layer "F.Cu")
		(net "M_G_CPU1_SA_DQS_DP<8>")
	)
	(segment
		(start 195.515484 -282.734512)
		(end 195.522596 -282.741624)
		(width 0.1016)
		(layer "F.Cu")
		(net "M_G_CPU1_SA_DQS_DP<8>")
	)
	(segment
		(start 197.535292 -282.741624)
		(end 197.542658 -282.734258)
		(width 0.1016)
		(layer "F.Cu")
		(net "M_G_CPU1_SA_DQS_DP<8>")
	)
	(segment
		(start 128.196848 -267.219938)
		(end 128.196594 -267.220192)
		(width 0.20066)
		(layer "F.Cu")
		(net "M_G_CPU1_SA_DQS_DP<8>")
	)
	(segment
		(start 174.297848 -278.480774)
		(end 173.75632 -277.939246)
		(width 0.18288)
		(layer "In6.Cu")
		(net "M_G_CPU1_SA_DQS_DP<8>")
	)
	(segment
		(start 171.122594 -277.384256)
		(end 171.122594 -276.431502)
		(width 0.18288)
		(layer "In6.Cu")
		(net "M_G_CPU1_SA_DQS_DP<8>")
	)
	(segment
		(start 180.010054 -282.249626)
		(end 179.518564 -282.741116)
		(width 0.18288)
		(layer "In6.Cu")
		(net "M_G_CPU1_SA_DQS_DP<8>")
	)
	(segment
		(start 128.709166 -267.755878)
		(end 128.196594 -267.755878)
		(width 0.088646)
		(layer "In6.Cu")
		(net "M_G_CPU1_SA_DQS_DP<8>")
	)
	(segment
		(start 131.673092 -267.266928)
		(end 131.66471 -267.272008)
		(width 0.088646)
		(layer "In6.Cu")
		(net "M_G_CPU1_SA_DQS_DP<8>")
	)
	(segment
		(start 191.72047 -283.42971)
		(end 190.740284 -283.42971)
		(width 0.18288)
		(layer "In6.Cu")
		(net "M_G_CPU1_SA_DQS_DP<8>")
	)
	(segment
		(start 174.872396 -278.480774)
		(end 174.297848 -278.480774)
		(width 0.18288)
		(layer "In6.Cu")
		(net "M_G_CPU1_SA_DQS_DP<8>")
	)
	(segment
		(start 177.413666 -282.140406)
		(end 177.165508 -281.892248)
		(width 0.18288)
		(layer "In6.Cu")
		(net "M_G_CPU1_SA_DQS_DP<8>")
	)
	(segment
		(start 129.474976 -267.359892)
		(end 129.159254 -267.359892)
		(width 0.088646)
		(layer "In6.Cu")
		(net "M_G_CPU1_SA_DQS_DP<8>")
	)
	(segment
		(start 129.139442 -267.363702)
		(end 129.089658 -267.384276)
		(width 0.088646)
		(layer "In6.Cu")
		(net "M_G_CPU1_SA_DQS_DP<8>")
	)
	(segment
		(start 157.494224 -274.339558)
		(end 151.157178 -268.002512)
		(width 0.18288)
		(layer "In6.Cu")
		(net "M_G_CPU1_SA_DQS_DP<8>")
	)
	(segment
		(start 190.740284 -283.42971)
		(end 190.292228 -283.877766)
		(width 0.18288)
		(layer "In6.Cu")
		(net "M_G_CPU1_SA_DQS_DP<8>")
	)
	(segment
		(start 173.002448 -277.64232)
		(end 172.536612 -277.64232)
		(width 0.18288)
		(layer "In6.Cu")
		(net "M_G_CPU1_SA_DQS_DP<8>")
	)
	(segment
		(start 128.947672 -267.432282)
		(end 128.940306 -267.4366)
		(width 0.088646)
		(layer "In6.Cu")
		(net "M_G_CPU1_SA_DQS_DP<8>")
	)
	(segment
		(start 171.681648 -277.94331)
		(end 171.122594 -277.384256)
		(width 0.18288)
		(layer "In6.Cu")
		(net "M_G_CPU1_SA_DQS_DP<8>")
	)
	(segment
		(start 130.733038 -267.266928)
		(end 130.7211 -267.27404)
		(width 0.088646)
		(layer "In6.Cu")
		(net "M_G_CPU1_SA_DQS_DP<8>")
	)
	(segment
		(start 138.816842 -267.266928)
		(end 138.801602 -267.258038)
		(width 0.088646)
		(layer "In6.Cu")
		(net "M_G_CPU1_SA_DQS_DP<8>")
	)
	(segment
		(start 188.401198 -282.990544)
		(end 188.15304 -282.742386)
		(width 0.18288)
		(layer "In6.Cu")
		(net "M_G_CPU1_SA_DQS_DP<8>")
	)
	(segment
		(start 136.949688 -267.273786)
		(end 136.93775 -267.266928)
		(width 0.088646)
		(layer "In6.Cu")
		(net "M_G_CPU1_SA_DQS_DP<8>")
	)
	(segment
		(start 183.987948 -282.99029)
		(end 183.247284 -282.249626)
		(width 0.18288)
		(layer "In6.Cu")
		(net "M_G_CPU1_SA_DQS_DP<8>")
	)
	(segment
		(start 168.767252 -274.36318)
		(end 168.74363 -274.339558)
		(width 0.18288)
		(layer "In6.Cu")
		(net "M_G_CPU1_SA_DQS_DP<8>")
	)
	(segment
		(start 173.299374 -277.939246)
		(end 173.002448 -277.64232)
		(width 0.18288)
		(layer "In6.Cu")
		(net "M_G_CPU1_SA_DQS_DP<8>")
	)
	(segment
		(start 177.165508 -281.892248)
		(end 176.63668 -281.892248)
		(width 0.18288)
		(layer "In6.Cu")
		(net "M_G_CPU1_SA_DQS_DP<8>")
	)
	(segment
		(start 178.298094 -282.140406)
		(end 177.413666 -282.140406)
		(width 0.18288)
		(layer "In6.Cu")
		(net "M_G_CPU1_SA_DQS_DP<8>")
	)
	(segment
		(start 169.257472 -274.566126)
		(end 168.767252 -274.36318)
		(width 0.18288)
		(layer "In6.Cu")
		(net "M_G_CPU1_SA_DQS_DP<8>")
	)
	(segment
		(start 135.432038 -267.266928)
		(end 135.4201 -267.273786)
		(width 0.088646)
		(layer "In6.Cu")
		(net "M_G_CPU1_SA_DQS_DP<8>")
	)
	(segment
		(start 168.74363 -274.339558)
		(end 157.494224 -274.339558)
		(width 0.18288)
		(layer "In6.Cu")
		(net "M_G_CPU1_SA_DQS_DP<8>")
	)
	(segment
		(start 142.262098 -267.471398)
		(end 140.595604 -267.471398)
		(width 0.18288)
		(layer "In6.Cu")
		(net "M_G_CPU1_SA_DQS_DP<8>")
	)
	(segment
		(start 129.159254 -267.359892)
		(end 129.139442 -267.363702)
		(width 0.088646)
		(layer "In6.Cu")
		(net "M_G_CPU1_SA_DQS_DP<8>")
	)
	(segment
		(start 171.122594 -276.431502)
		(end 169.257472 -274.566126)
		(width 0.18288)
		(layer "In6.Cu")
		(net "M_G_CPU1_SA_DQS_DP<8>")
	)
	(segment
		(start 129.756408 -267.28674)
		(end 129.720086 -267.31087)
		(width 0.088646)
		(layer "In6.Cu")
		(net "M_G_CPU1_SA_DQS_DP<8>")
	)
	(segment
		(start 187.640468 -282.742386)
		(end 187.392564 -282.99029)
		(width 0.18288)
		(layer "In6.Cu")
		(net "M_G_CPU1_SA_DQS_DP<8>")
	)
	(segment
		(start 172.536612 -277.64232)
		(end 172.235622 -277.94331)
		(width 0.18288)
		(layer "In6.Cu")
		(net "M_G_CPU1_SA_DQS_DP<8>")
	)
	(segment
		(start 191.983614 -283.166566)
		(end 191.72047 -283.42971)
		(width 0.18288)
		(layer "In6.Cu")
		(net "M_G_CPU1_SA_DQS_DP<8>")
	)
	(segment
		(start 134.491984 -267.267182)
		(end 134.480808 -267.273532)
		(width 0.088646)
		(layer "In6.Cu")
		(net "M_G_CPU1_SA_DQS_DP<8>")
	)
	(segment
		(start 140.572236 -267.471398)
		(end 140.512546 -267.531088)
		(width 0.088646)
		(layer "In6.Cu")
		(net "M_G_CPU1_SA_DQS_DP<8>")
	)
	(segment
		(start 129.720086 -267.31087)
		(end 129.474976 -267.359892)
		(width 0.088646)
		(layer "In6.Cu")
		(net "M_G_CPU1_SA_DQS_DP<8>")
	)
	(segment
		(start 132.247386 -267.271754)
		(end 132.239004 -267.266928)
		(width 0.088646)
		(layer "In6.Cu")
		(net "M_G_CPU1_SA_DQS_DP<8>")
	)
	(segment
		(start 144.931892 -268.002512)
		(end 142.262098 -267.471398)
		(width 0.18288)
		(layer "In6.Cu")
		(net "M_G_CPU1_SA_DQS_DP<8>")
	)
	(segment
		(start 140.104114 -267.316966)
		(end 139.942824 -267.316966)
		(width 0.088646)
		(layer "In6.Cu")
		(net "M_G_CPU1_SA_DQS_DP<8>")
	)
	(segment
		(start 134.493 -267.266674)
		(end 134.491984 -267.267182)
		(width 0.088646)
		(layer "In6.Cu")
		(net "M_G_CPU1_SA_DQS_DP<8>")
	)
	(segment
		(start 175.983392 -282.066238)
		(end 175.983392 -279.59177)
		(width 0.18288)
		(layer "In6.Cu")
		(net "M_G_CPU1_SA_DQS_DP<8>")
	)
	(segment
		(start 140.595604 -267.471398)
		(end 140.572236 -267.471398)
		(width 0.088646)
		(layer "In6.Cu")
		(net "M_G_CPU1_SA_DQS_DP<8>")
	)
	(segment
		(start 138.825478 -267.271754)
		(end 138.816842 -267.266928)
		(width 0.088646)
		(layer "In6.Cu")
		(net "M_G_CPU1_SA_DQS_DP<8>")
	)
	(segment
		(start 172.235622 -277.94331)
		(end 171.681648 -277.94331)
		(width 0.18288)
		(layer "In6.Cu")
		(net "M_G_CPU1_SA_DQS_DP<8>")
	)
	(segment
		(start 176.63668 -281.892248)
		(end 176.33569 -282.193238)
		(width 0.18288)
		(layer "In6.Cu")
		(net "M_G_CPU1_SA_DQS_DP<8>")
	)
	(segment
		(start 190.292228 -283.877766)
		(end 189.785752 -283.877766)
		(width 0.18288)
		(layer "In6.Cu")
		(net "M_G_CPU1_SA_DQS_DP<8>")
	)
	(segment
		(start 189.785752 -283.877766)
		(end 188.89853 -282.990544)
		(width 0.18288)
		(layer "In6.Cu")
		(net "M_G_CPU1_SA_DQS_DP<8>")
	)
	(segment
		(start 140.318236 -267.531088)
		(end 140.104114 -267.316966)
		(width 0.088646)
		(layer "In6.Cu")
		(net "M_G_CPU1_SA_DQS_DP<8>")
	)
	(segment
		(start 187.392564 -282.99029)
		(end 183.987948 -282.99029)
		(width 0.18288)
		(layer "In6.Cu")
		(net "M_G_CPU1_SA_DQS_DP<8>")
	)
	(segment
		(start 183.247284 -282.249626)
		(end 180.010054 -282.249626)
		(width 0.18288)
		(layer "In6.Cu")
		(net "M_G_CPU1_SA_DQS_DP<8>")
	)
	(segment
		(start 137.877042 -267.266928)
		(end 137.866374 -267.260578)
		(width 0.088646)
		(layer "In6.Cu")
		(net "M_G_CPU1_SA_DQS_DP<8>")
	)
	(segment
		(start 128.949196 -267.43152)
		(end 128.947672 -267.432282)
		(width 0.088646)
		(layer "In6.Cu")
		(net "M_G_CPU1_SA_DQS_DP<8>")
	)
	(segment
		(start 140.512546 -267.531088)
		(end 140.318236 -267.531088)
		(width 0.088646)
		(layer "In6.Cu")
		(net "M_G_CPU1_SA_DQS_DP<8>")
	)
	(segment
		(start 133.552438 -267.266928)
		(end 133.5405 -267.27404)
		(width 0.088646)
		(layer "In6.Cu")
		(net "M_G_CPU1_SA_DQS_DP<8>")
	)
	(segment
		(start 128.766316 -267.698728)
		(end 128.709166 -267.755878)
		(width 0.088646)
		(layer "In6.Cu")
		(net "M_G_CPU1_SA_DQS_DP<8>")
	)
	(segment
		(start 173.75632 -277.939246)
		(end 173.299374 -277.939246)
		(width 0.18288)
		(layer "In6.Cu")
		(net "M_G_CPU1_SA_DQS_DP<8>")
	)
	(segment
		(start 179.518564 -282.741116)
		(end 178.898804 -282.741116)
		(width 0.18288)
		(layer "In6.Cu")
		(net "M_G_CPU1_SA_DQS_DP<8>")
	)
	(segment
		(start 151.157178 -268.002512)
		(end 144.931892 -268.002512)
		(width 0.18288)
		(layer "In6.Cu")
		(net "M_G_CPU1_SA_DQS_DP<8>")
	)
	(segment
		(start 188.89853 -282.990544)
		(end 188.401198 -282.990544)
		(width 0.18288)
		(layer "In6.Cu")
		(net "M_G_CPU1_SA_DQS_DP<8>")
	)
	(segment
		(start 137.889234 -267.273786)
		(end 137.877042 -267.266928)
		(width 0.088646)
		(layer "In6.Cu")
		(net "M_G_CPU1_SA_DQS_DP<8>")
	)
	(segment
		(start 188.15304 -282.742386)
		(end 187.640468 -282.742386)
		(width 0.18288)
		(layer "In6.Cu")
		(net "M_G_CPU1_SA_DQS_DP<8>")
	)
	(segment
		(start 176.110392 -282.193238)
		(end 175.983392 -282.066238)
		(width 0.18288)
		(layer "In6.Cu")
		(net "M_G_CPU1_SA_DQS_DP<8>")
	)
	(segment
		(start 175.983392 -279.59177)
		(end 174.872396 -278.480774)
		(width 0.18288)
		(layer "In6.Cu")
		(net "M_G_CPU1_SA_DQS_DP<8>")
	)
	(segment
		(start 178.898804 -282.741116)
		(end 178.298094 -282.140406)
		(width 0.18288)
		(layer "In6.Cu")
		(net "M_G_CPU1_SA_DQS_DP<8>")
	)
	(segment
		(start 176.33569 -282.193238)
		(end 176.110392 -282.193238)
		(width 0.18288)
		(layer "In6.Cu")
		(net "M_G_CPU1_SA_DQS_DP<8>")
	)
	(segment
		(start 129.79654 -267.26515)
		(end 129.756408 -267.28674)
		(width 0.088646)
		(layer "In6.Cu")
		(net "M_G_CPU1_SA_DQS_DP<8>")
	)
	(arc
		(start 136.93775 -267.266928)
		(mid 136.655221 -267.191084)
		(end 136.3726 -267.266674)
		(width 0.088646)
		(layer "In6.Cu")
		(net "M_G_CPU1_SA_DQS_DP<8>")
	)
	(arc
		(start 132.239004 -267.266928)
		(mid 131.956048 -267.190957)
		(end 131.673092 -267.266928)
		(width 0.088646)
		(layer "In6.Cu")
		(net "M_G_CPU1_SA_DQS_DP<8>")
	)
	(arc
		(start 134.480808 -267.273532)
		(mid 134.298443 -267.316946)
		(end 134.117842 -267.266674)
		(width 0.088646)
		(layer "In6.Cu")
		(net "M_G_CPU1_SA_DQS_DP<8>")
	)
	(arc
		(start 135.057642 -267.266674)
		(mid 134.775338 -267.191118)
		(end 134.493 -267.266674)
		(width 0.088646)
		(layer "In6.Cu")
		(net "M_G_CPU1_SA_DQS_DP<8>")
	)
	(arc
		(start 139.755372 -267.266674)
		(mid 139.473178 -267.191118)
		(end 139.190984 -267.266674)
		(width 0.088646)
		(layer "In6.Cu")
		(net "M_G_CPU1_SA_DQS_DP<8>")
	)
	(arc
		(start 135.997188 -267.266674)
		(mid 135.714566 -267.190991)
		(end 135.432038 -267.266928)
		(width 0.088646)
		(layer "In6.Cu")
		(net "M_G_CPU1_SA_DQS_DP<8>")
	)
	(arc
		(start 132.613146 -267.266674)
		(mid 132.430924 -267.316874)
		(end 132.247386 -267.271754)
		(width 0.088646)
		(layer "In6.Cu")
		(net "M_G_CPU1_SA_DQS_DP<8>")
	)
	(arc
		(start 139.942824 -267.316966)
		(mid 139.845785 -267.304172)
		(end 139.755372 -267.266674)
		(width 0.088646)
		(layer "In6.Cu")
		(net "M_G_CPU1_SA_DQS_DP<8>")
	)
	(arc
		(start 129.089658 -267.384276)
		(mid 129.017061 -267.400868)
		(end 128.949196 -267.43152)
		(width 0.088646)
		(layer "In6.Cu")
		(net "M_G_CPU1_SA_DQS_DP<8>")
	)
	(arc
		(start 131.298442 -267.266674)
		(mid 131.015711 -267.190991)
		(end 130.733038 -267.266928)
		(width 0.088646)
		(layer "In6.Cu")
		(net "M_G_CPU1_SA_DQS_DP<8>")
	)
	(arc
		(start 136.3726 -267.266674)
		(mid 136.184894 -267.317003)
		(end 135.997188 -267.266674)
		(width 0.088646)
		(layer "In6.Cu")
		(net "M_G_CPU1_SA_DQS_DP<8>")
	)
	(arc
		(start 131.66471 -267.272008)
		(mid 131.480889 -267.317066)
		(end 131.298442 -267.266674)
		(width 0.088646)
		(layer "In6.Cu")
		(net "M_G_CPU1_SA_DQS_DP<8>")
	)
	(arc
		(start 133.5405 -267.27404)
		(mid 133.35833 -267.317029)
		(end 133.178042 -267.266674)
		(width 0.088646)
		(layer "In6.Cu")
		(net "M_G_CPU1_SA_DQS_DP<8>")
	)
	(arc
		(start 137.866374 -267.260578)
		(mid 137.58845 -267.190946)
		(end 137.312146 -267.266674)
		(width 0.088646)
		(layer "In6.Cu")
		(net "M_G_CPU1_SA_DQS_DP<8>")
	)
	(arc
		(start 128.940306 -267.4366)
		(mid 128.824497 -267.548529)
		(end 128.766316 -267.698728)
		(width 0.088646)
		(layer "In6.Cu")
		(net "M_G_CPU1_SA_DQS_DP<8>")
	)
	(arc
		(start 134.117842 -267.266674)
		(mid 133.835111 -267.190991)
		(end 133.552438 -267.266928)
		(width 0.088646)
		(layer "In6.Cu")
		(net "M_G_CPU1_SA_DQS_DP<8>")
	)
	(arc
		(start 139.190984 -267.266674)
		(mid 139.008905 -267.316714)
		(end 138.825478 -267.271754)
		(width 0.088646)
		(layer "In6.Cu")
		(net "M_G_CPU1_SA_DQS_DP<8>")
	)
	(arc
		(start 135.4201 -267.273786)
		(mid 135.237959 -267.316899)
		(end 135.057642 -267.266674)
		(width 0.088646)
		(layer "In6.Cu")
		(net "M_G_CPU1_SA_DQS_DP<8>")
	)
	(arc
		(start 130.7211 -267.27404)
		(mid 130.53893 -267.317029)
		(end 130.358642 -267.266674)
		(width 0.088646)
		(layer "In6.Cu")
		(net "M_G_CPU1_SA_DQS_DP<8>")
	)
	(arc
		(start 133.178042 -267.266674)
		(mid 132.895594 -267.190991)
		(end 132.613146 -267.266674)
		(width 0.088646)
		(layer "In6.Cu")
		(net "M_G_CPU1_SA_DQS_DP<8>")
	)
	(arc
		(start 130.358642 -267.266674)
		(mid 130.077785 -267.190993)
		(end 129.79654 -267.26515)
		(width 0.088646)
		(layer "In6.Cu")
		(net "M_G_CPU1_SA_DQS_DP<8>")
	)
	(arc
		(start 137.312146 -267.266674)
		(mid 137.131829 -267.31693)
		(end 136.949688 -267.273786)
		(width 0.088646)
		(layer "In6.Cu")
		(net "M_G_CPU1_SA_DQS_DP<8>")
	)
	(arc
		(start 138.801602 -267.258038)
		(mid 138.525525 -267.19093)
		(end 138.251692 -267.266674)
		(width 0.088646)
		(layer "In6.Cu")
		(net "M_G_CPU1_SA_DQS_DP<8>")
	)
	(arc
		(start 138.251692 -267.266674)
		(mid 138.071375 -267.31693)
		(end 137.889234 -267.273786)
		(width 0.088646)
		(layer "In6.Cu")
		(net "M_G_CPU1_SA_DQS_DP<8>")
	)
	(segment
		(start 194.237864 -292.767766)
		(end 194.662806 -292.342824)
		(width 0.20066)
		(layer "F.Cu")
		(net "M_G_CPU1_SA_DQS_DP<7>")
	)
	(segment
		(start 198.119492 -292.339268)
		(end 198.773034 -292.339268)
		(width 0.20066)
		(layer "F.Cu")
		(net "M_G_CPU1_SA_DQS_DP<7>")
	)
	(segment
		(start 195.199254 -292.08476)
		(end 195.510658 -292.08476)
		(width 0.20066)
		(layer "F.Cu")
		(net "M_G_CPU1_SA_DQS_DP<7>")
	)
	(segment
		(start 193.682112 -292.516814)
		(end 193.933064 -292.767766)
		(width 0.20066)
		(layer "F.Cu")
		(net "M_G_CPU1_SA_DQS_DP<7>")
	)
	(segment
		(start 197.542658 -292.084506)
		(end 197.86473 -292.084506)
		(width 0.20066)
		(layer "F.Cu")
		(net "M_G_CPU1_SA_DQS_DP<7>")
	)
	(segment
		(start 198.773034 -292.339268)
		(end 199.21855 -292.784784)
		(width 0.20066)
		(layer "F.Cu")
		(net "M_G_CPU1_SA_DQS_DP<7>")
	)
	(segment
		(start 191.983614 -292.51656)
		(end 191.983868 -292.516814)
		(width 0.20066)
		(layer "F.Cu")
		(net "M_G_CPU1_SA_DQS_DP<7>")
	)
	(segment
		(start 200.064116 -292.516814)
		(end 200.632314 -292.516814)
		(width 0.20066)
		(layer "F.Cu")
		(net "M_G_CPU1_SA_DQS_DP<7>")
	)
	(segment
		(start 195.515484 -292.08476)
		(end 195.522596 -292.091872)
		(width 0.1016)
		(layer "F.Cu")
		(net "M_G_CPU1_SA_DQS_DP<7>")
	)
	(segment
		(start 197.535292 -292.091872)
		(end 197.542658 -292.084506)
		(width 0.1016)
		(layer "F.Cu")
		(net "M_G_CPU1_SA_DQS_DP<7>")
	)
	(segment
		(start 191.983868 -292.516814)
		(end 193.088514 -292.516814)
		(width 0.20066)
		(layer "F.Cu")
		(net "M_G_CPU1_SA_DQS_DP<7>")
	)
	(segment
		(start 193.088514 -292.516814)
		(end 193.682112 -292.516814)
		(width 0.20066)
		(layer "F.Cu")
		(net "M_G_CPU1_SA_DQS_DP<7>")
	)
	(segment
		(start 199.796146 -292.784784)
		(end 200.064116 -292.516814)
		(width 0.20066)
		(layer "F.Cu")
		(net "M_G_CPU1_SA_DQS_DP<7>")
	)
	(segment
		(start 197.86473 -292.084506)
		(end 198.119492 -292.339268)
		(width 0.20066)
		(layer "F.Cu")
		(net "M_G_CPU1_SA_DQS_DP<7>")
	)
	(segment
		(start 131.485894 -265.313922)
		(end 131.486148 -265.314176)
		(width 0.20066)
		(layer "F.Cu")
		(net "M_G_CPU1_SA_DQS_DP<7>")
	)
	(segment
		(start 194.94119 -292.342824)
		(end 195.199254 -292.08476)
		(width 0.20066)
		(layer "F.Cu")
		(net "M_G_CPU1_SA_DQS_DP<7>")
	)
	(segment
		(start 199.21855 -292.784784)
		(end 199.796146 -292.784784)
		(width 0.20066)
		(layer "F.Cu")
		(net "M_G_CPU1_SA_DQS_DP<7>")
	)
	(segment
		(start 195.510658 -292.08476)
		(end 195.515484 -292.08476)
		(width 0.101854)
		(layer "F.Cu")
		(net "M_G_CPU1_SA_DQS_DP<7>")
	)
	(segment
		(start 193.933064 -292.767766)
		(end 194.237864 -292.767766)
		(width 0.20066)
		(layer "F.Cu")
		(net "M_G_CPU1_SA_DQS_DP<7>")
	)
	(segment
		(start 195.522596 -292.091872)
		(end 197.535292 -292.091872)
		(width 0.1016)
		(layer "F.Cu")
		(net "M_G_CPU1_SA_DQS_DP<7>")
	)
	(segment
		(start 131.485894 -264.778236)
		(end 131.485894 -265.313922)
		(width 0.20066)
		(layer "F.Cu")
		(net "M_G_CPU1_SA_DQS_DP<7>")
	)
	(segment
		(start 194.662806 -292.342824)
		(end 194.94119 -292.342824)
		(width 0.20066)
		(layer "F.Cu")
		(net "M_G_CPU1_SA_DQS_DP<7>")
	)
	(segment
		(start 161.837624 -284.39364)
		(end 161.46018 -284.494478)
		(width 0.18288)
		(layer "In4.Cu")
		(net "M_G_CPU1_SA_DQS_DP<7>")
	)
	(segment
		(start 180.090064 -291.709602)
		(end 179.634896 -292.16477)
		(width 0.18288)
		(layer "In4.Cu")
		(net "M_G_CPU1_SA_DQS_DP<7>")
	)
	(segment
		(start 191.983614 -292.51656)
		(end 191.724788 -292.775386)
		(width 0.18288)
		(layer "In4.Cu")
		(net "M_G_CPU1_SA_DQS_DP<7>")
	)
	(segment
		(start 186.939682 -292.093396)
		(end 183.554878 -292.093396)
		(width 0.18288)
		(layer "In4.Cu")
		(net "M_G_CPU1_SA_DQS_DP<7>")
	)
	(segment
		(start 134.02818 -264.821416)
		(end 134.022592 -264.824718)
		(width 0.088646)
		(layer "In4.Cu")
		(net "M_G_CPU1_SA_DQS_DP<7>")
	)
	(segment
		(start 178.196494 -291.504878)
		(end 177.352706 -291.504878)
		(width 0.18288)
		(layer "In4.Cu")
		(net "M_G_CPU1_SA_DQS_DP<7>")
	)
	(segment
		(start 132.973318 -264.888218)
		(end 132.866638 -264.91692)
		(width 0.088646)
		(layer "In4.Cu")
		(net "M_G_CPU1_SA_DQS_DP<7>")
	)
	(segment
		(start 172.584872 -292.092634)
		(end 172.334936 -292.34257)
		(width 0.18288)
		(layer "In4.Cu")
		(net "M_G_CPU1_SA_DQS_DP<7>")
	)
	(segment
		(start 191.724788 -292.775386)
		(end 191.475868 -292.775386)
		(width 0.18288)
		(layer "In4.Cu")
		(net "M_G_CPU1_SA_DQS_DP<7>")
	)
	(segment
		(start 169.532808 -290.929568)
		(end 168.909746 -290.929568)
		(width 0.18288)
		(layer "In4.Cu")
		(net "M_G_CPU1_SA_DQS_DP<7>")
	)
	(segment
		(start 187.672472 -292.092634)
		(end 187.399676 -292.36543)
		(width 0.18288)
		(layer "In4.Cu")
		(net "M_G_CPU1_SA_DQS_DP<7>")
	)
	(segment
		(start 176.437036 -291.496242)
		(end 175.511714 -291.496242)
		(width 0.18288)
		(layer "In4.Cu")
		(net "M_G_CPU1_SA_DQS_DP<7>")
	)
	(segment
		(start 133.083046 -264.824972)
		(end 132.973318 -264.888218)
		(width 0.088646)
		(layer "In4.Cu")
		(net "M_G_CPU1_SA_DQS_DP<7>")
	)
	(segment
		(start 132.866638 -264.91692)
		(end 132.432044 -264.91692)
		(width 0.088646)
		(layer "In4.Cu")
		(net "M_G_CPU1_SA_DQS_DP<7>")
	)
	(segment
		(start 140.668248 -264.92708)
		(end 138.665204 -264.92708)
		(width 0.18288)
		(layer "In4.Cu")
		(net "M_G_CPU1_SA_DQS_DP<7>")
	)
	(segment
		(start 138.665204 -264.92708)
		(end 138.641836 -264.92708)
		(width 0.088646)
		(layer "In4.Cu")
		(net "M_G_CPU1_SA_DQS_DP<7>")
	)
	(segment
		(start 168.909746 -290.929568)
		(end 168.269158 -290.28898)
		(width 0.18288)
		(layer "In4.Cu")
		(net "M_G_CPU1_SA_DQS_DP<7>")
	)
	(segment
		(start 177.090324 -291.242496)
		(end 176.690782 -291.242496)
		(width 0.18288)
		(layer "In4.Cu")
		(net "M_G_CPU1_SA_DQS_DP<7>")
	)
	(segment
		(start 175.511714 -291.496242)
		(end 173.447202 -292.351206)
		(width 0.18288)
		(layer "In4.Cu")
		(net "M_G_CPU1_SA_DQS_DP<7>")
	)
	(segment
		(start 183.171084 -291.709602)
		(end 180.090064 -291.709602)
		(width 0.18288)
		(layer "In4.Cu")
		(net "M_G_CPU1_SA_DQS_DP<7>")
	)
	(segment
		(start 168.269158 -290.28898)
		(end 167.334946 -289.901884)
		(width 0.18288)
		(layer "In4.Cu")
		(net "M_G_CPU1_SA_DQS_DP<7>")
	)
	(segment
		(start 167.334946 -289.901884)
		(end 166.430198 -288.997136)
		(width 0.18288)
		(layer "In4.Cu")
		(net "M_G_CPU1_SA_DQS_DP<7>")
	)
	(segment
		(start 161.152078 -284.119066)
		(end 161.152078 -282.988766)
		(width 0.18288)
		(layer "In4.Cu")
		(net "M_G_CPU1_SA_DQS_DP<7>")
	)
	(segment
		(start 189.23254 -292.944804)
		(end 188.661802 -292.374066)
		(width 0.18288)
		(layer "In4.Cu")
		(net "M_G_CPU1_SA_DQS_DP<7>")
	)
	(segment
		(start 142.997936 -267.256768)
		(end 140.668248 -264.92708)
		(width 0.18288)
		(layer "In4.Cu")
		(net "M_G_CPU1_SA_DQS_DP<7>")
	)
	(segment
		(start 166.430198 -288.997136)
		(end 166.429944 -288.997136)
		(width 0.18288)
		(layer "In4.Cu")
		(net "M_G_CPU1_SA_DQS_DP<7>")
	)
	(segment
		(start 173.24832 -292.351206)
		(end 172.989748 -292.092634)
		(width 0.18288)
		(layer "In4.Cu")
		(net "M_G_CPU1_SA_DQS_DP<7>")
	)
	(segment
		(start 163.853876 -287.027366)
		(end 163.55568 -286.72917)
		(width 0.18288)
		(layer "In4.Cu")
		(net "M_G_CPU1_SA_DQS_DP<7>")
	)
	(segment
		(start 162.268662 -284.895036)
		(end 162.188398 -284.596078)
		(width 0.18288)
		(layer "In4.Cu")
		(net "M_G_CPU1_SA_DQS_DP<7>")
	)
	(segment
		(start 163.55568 -286.140144)
		(end 162.367722 -284.952186)
		(width 0.18288)
		(layer "In4.Cu")
		(net "M_G_CPU1_SA_DQS_DP<7>")
	)
	(segment
		(start 161.340292 -284.444948)
		(end 161.152078 -284.119066)
		(width 0.18288)
		(layer "In4.Cu")
		(net "M_G_CPU1_SA_DQS_DP<7>")
	)
	(segment
		(start 164.460174 -287.027366)
		(end 163.853876 -287.027366)
		(width 0.18288)
		(layer "In4.Cu")
		(net "M_G_CPU1_SA_DQS_DP<7>")
	)
	(segment
		(start 172.334936 -292.34257)
		(end 170.94581 -292.34257)
		(width 0.18288)
		(layer "In4.Cu")
		(net "M_G_CPU1_SA_DQS_DP<7>")
	)
	(segment
		(start 132.23875 -264.989818)
		(end 132.22986 -264.994898)
		(width 0.088646)
		(layer "In4.Cu")
		(net "M_G_CPU1_SA_DQS_DP<7>")
	)
	(segment
		(start 163.55568 -286.72917)
		(end 163.55568 -286.140144)
		(width 0.18288)
		(layer "In4.Cu")
		(net "M_G_CPU1_SA_DQS_DP<7>")
	)
	(segment
		(start 162.367722 -284.952186)
		(end 162.268662 -284.895036)
		(width 0.18288)
		(layer "In4.Cu")
		(net "M_G_CPU1_SA_DQS_DP<7>")
	)
	(segment
		(start 160.357058 -282.193746)
		(end 157.723586 -282.193746)
		(width 0.18288)
		(layer "In4.Cu")
		(net "M_G_CPU1_SA_DQS_DP<7>")
	)
	(segment
		(start 137.694924 -264.987024)
		(end 137.40638 -264.824464)
		(width 0.088646)
		(layer "In4.Cu")
		(net "M_G_CPU1_SA_DQS_DP<7>")
	)
	(segment
		(start 161.152078 -282.988766)
		(end 160.357058 -282.193746)
		(width 0.18288)
		(layer "In4.Cu")
		(net "M_G_CPU1_SA_DQS_DP<7>")
	)
	(segment
		(start 154.877262 -276.439122)
		(end 146.359372 -267.921232)
		(width 0.18288)
		(layer "In4.Cu")
		(net "M_G_CPU1_SA_DQS_DP<7>")
	)
	(segment
		(start 161.46018 -284.494478)
		(end 161.340292 -284.444948)
		(width 0.18288)
		(layer "In4.Cu")
		(net "M_G_CPU1_SA_DQS_DP<7>")
	)
	(segment
		(start 187.211716 -292.36543)
		(end 186.939682 -292.093396)
		(width 0.18288)
		(layer "In4.Cu")
		(net "M_G_CPU1_SA_DQS_DP<7>")
	)
	(segment
		(start 136.467596 -264.824718)
		(end 136.452864 -264.816082)
		(width 0.088646)
		(layer "In4.Cu")
		(net "M_G_CPU1_SA_DQS_DP<7>")
	)
	(segment
		(start 131.99872 -265.314176)
		(end 131.486148 -265.314176)
		(width 0.088646)
		(layer "In4.Cu")
		(net "M_G_CPU1_SA_DQS_DP<7>")
	)
	(segment
		(start 146.359372 -267.921232)
		(end 144.6022 -267.921232)
		(width 0.18288)
		(layer "In4.Cu")
		(net "M_G_CPU1_SA_DQS_DP<7>")
	)
	(segment
		(start 179.634896 -292.16477)
		(end 178.856386 -292.16477)
		(width 0.18288)
		(layer "In4.Cu")
		(net "M_G_CPU1_SA_DQS_DP<7>")
	)
	(segment
		(start 143.063722 -267.283946)
		(end 142.997936 -267.256768)
		(width 0.18288)
		(layer "In4.Cu")
		(net "M_G_CPU1_SA_DQS_DP<7>")
	)
	(segment
		(start 136.842754 -264.824972)
		(end 136.841992 -264.824718)
		(width 0.088646)
		(layer "In4.Cu")
		(net "M_G_CPU1_SA_DQS_DP<7>")
	)
	(segment
		(start 138.641836 -264.92708)
		(end 138.581892 -264.987024)
		(width 0.088646)
		(layer "In4.Cu")
		(net "M_G_CPU1_SA_DQS_DP<7>")
	)
	(segment
		(start 144.6022 -267.921232)
		(end 143.063722 -267.283946)
		(width 0.18288)
		(layer "In4.Cu")
		(net "M_G_CPU1_SA_DQS_DP<7>")
	)
	(segment
		(start 172.989748 -292.092634)
		(end 172.584872 -292.092634)
		(width 0.18288)
		(layer "In4.Cu")
		(net "M_G_CPU1_SA_DQS_DP<7>")
	)
	(segment
		(start 166.429944 -288.997136)
		(end 164.460174 -287.027366)
		(width 0.18288)
		(layer "In4.Cu")
		(net "M_G_CPU1_SA_DQS_DP<7>")
	)
	(segment
		(start 191.475868 -292.775386)
		(end 191.066928 -292.944804)
		(width 0.18288)
		(layer "In4.Cu")
		(net "M_G_CPU1_SA_DQS_DP<7>")
	)
	(segment
		(start 156.933646 -281.403806)
		(end 154.877262 -276.439122)
		(width 0.18288)
		(layer "In4.Cu")
		(net "M_G_CPU1_SA_DQS_DP<7>")
	)
	(segment
		(start 188.35878 -292.374066)
		(end 188.077348 -292.092634)
		(width 0.18288)
		(layer "In4.Cu")
		(net "M_G_CPU1_SA_DQS_DP<7>")
	)
	(segment
		(start 157.723586 -282.193746)
		(end 156.933646 -281.403806)
		(width 0.18288)
		(layer "In4.Cu")
		(net "M_G_CPU1_SA_DQS_DP<7>")
	)
	(segment
		(start 183.554878 -292.093396)
		(end 183.171084 -291.709602)
		(width 0.18288)
		(layer "In4.Cu")
		(net "M_G_CPU1_SA_DQS_DP<7>")
	)
	(segment
		(start 188.661802 -292.374066)
		(end 188.35878 -292.374066)
		(width 0.18288)
		(layer "In4.Cu")
		(net "M_G_CPU1_SA_DQS_DP<7>")
	)
	(segment
		(start 191.066928 -292.944804)
		(end 189.23254 -292.944804)
		(width 0.18288)
		(layer "In4.Cu")
		(net "M_G_CPU1_SA_DQS_DP<7>")
	)
	(segment
		(start 170.94581 -292.34257)
		(end 169.532808 -290.929568)
		(width 0.18288)
		(layer "In4.Cu")
		(net "M_G_CPU1_SA_DQS_DP<7>")
	)
	(segment
		(start 162.188398 -284.596078)
		(end 161.837624 -284.39364)
		(width 0.18288)
		(layer "In4.Cu")
		(net "M_G_CPU1_SA_DQS_DP<7>")
	)
	(segment
		(start 178.856386 -292.16477)
		(end 178.196494 -291.504878)
		(width 0.18288)
		(layer "In4.Cu")
		(net "M_G_CPU1_SA_DQS_DP<7>")
	)
	(segment
		(start 187.399676 -292.36543)
		(end 187.211716 -292.36543)
		(width 0.18288)
		(layer "In4.Cu")
		(net "M_G_CPU1_SA_DQS_DP<7>")
	)
	(segment
		(start 134.02945 -264.820654)
		(end 134.02818 -264.821416)
		(width 0.088646)
		(layer "In4.Cu")
		(net "M_G_CPU1_SA_DQS_DP<7>")
	)
	(segment
		(start 138.581892 -264.987024)
		(end 137.694924 -264.987024)
		(width 0.088646)
		(layer "In4.Cu")
		(net "M_G_CPU1_SA_DQS_DP<7>")
	)
	(segment
		(start 135.527796 -264.824718)
		(end 135.513064 -264.816082)
		(width 0.088646)
		(layer "In4.Cu")
		(net "M_G_CPU1_SA_DQS_DP<7>")
	)
	(segment
		(start 132.05587 -265.257026)
		(end 131.99872 -265.314176)
		(width 0.088646)
		(layer "In4.Cu")
		(net "M_G_CPU1_SA_DQS_DP<7>")
	)
	(segment
		(start 176.690782 -291.242496)
		(end 176.437036 -291.496242)
		(width 0.18288)
		(layer "In4.Cu")
		(net "M_G_CPU1_SA_DQS_DP<7>")
	)
	(segment
		(start 188.077348 -292.092634)
		(end 187.672472 -292.092634)
		(width 0.18288)
		(layer "In4.Cu")
		(net "M_G_CPU1_SA_DQS_DP<7>")
	)
	(segment
		(start 173.447202 -292.351206)
		(end 173.24832 -292.351206)
		(width 0.18288)
		(layer "In4.Cu")
		(net "M_G_CPU1_SA_DQS_DP<7>")
	)
	(segment
		(start 177.352706 -291.504878)
		(end 177.090324 -291.242496)
		(width 0.18288)
		(layer "In4.Cu")
		(net "M_G_CPU1_SA_DQS_DP<7>")
	)
	(segment
		(start 133.648196 -264.824718)
		(end 133.648196 -264.824972)
		(width 0.088646)
		(layer "In4.Cu")
		(net "M_G_CPU1_SA_DQS_DP<7>")
	)
	(arc
		(start 132.288788 -264.965688)
		(mid 132.263319 -264.976821)
		(end 132.23875 -264.989818)
		(width 0.088646)
		(layer "In4.Cu")
		(net "M_G_CPU1_SA_DQS_DP<7>")
	)
	(arc
		(start 135.513064 -264.816082)
		(mid 135.236589 -264.748762)
		(end 134.962392 -264.824718)
		(width 0.088646)
		(layer "In4.Cu")
		(net "M_G_CPU1_SA_DQS_DP<7>")
	)
	(arc
		(start 135.902192 -264.824718)
		(mid 135.714994 -264.874861)
		(end 135.527796 -264.824718)
		(width 0.088646)
		(layer "In4.Cu")
		(net "M_G_CPU1_SA_DQS_DP<7>")
	)
	(arc
		(start 134.962392 -264.824718)
		(mid 134.775194 -264.874861)
		(end 134.587996 -264.824718)
		(width 0.088646)
		(layer "In4.Cu")
		(net "M_G_CPU1_SA_DQS_DP<7>")
	)
	(arc
		(start 137.40638 -264.824464)
		(mid 137.124491 -264.749356)
		(end 136.842754 -264.824972)
		(width 0.088646)
		(layer "In4.Cu")
		(net "M_G_CPU1_SA_DQS_DP<7>")
	)
	(arc
		(start 132.22986 -264.994898)
		(mid 132.114051 -265.106827)
		(end 132.05587 -265.257026)
		(width 0.088646)
		(layer "In4.Cu")
		(net "M_G_CPU1_SA_DQS_DP<7>")
	)
	(arc
		(start 132.432044 -264.91692)
		(mid 132.38393 -264.923276)
		(end 132.33908 -264.941812)
		(width 0.088646)
		(layer "In4.Cu")
		(net "M_G_CPU1_SA_DQS_DP<7>")
	)
	(arc
		(start 136.452864 -264.816082)
		(mid 136.176389 -264.748762)
		(end 135.902192 -264.824718)
		(width 0.088646)
		(layer "In4.Cu")
		(net "M_G_CPU1_SA_DQS_DP<7>")
	)
	(arc
		(start 133.648196 -264.824972)
		(mid 133.365638 -264.749289)
		(end 133.083046 -264.824972)
		(width 0.088646)
		(layer "In4.Cu")
		(net "M_G_CPU1_SA_DQS_DP<7>")
	)
	(arc
		(start 134.587996 -264.824718)
		(mid 134.309673 -264.748959)
		(end 134.030212 -264.8204)
		(width 0.088646)
		(layer "In4.Cu")
		(net "M_G_CPU1_SA_DQS_DP<7>")
	)
	(arc
		(start 136.841992 -264.824718)
		(mid 136.654794 -264.874861)
		(end 136.467596 -264.824718)
		(width 0.088646)
		(layer "In4.Cu")
		(net "M_G_CPU1_SA_DQS_DP<7>")
	)
	(arc
		(start 132.33908 -264.941812)
		(mid 132.314375 -264.954679)
		(end 132.288788 -264.965688)
		(width 0.088646)
		(layer "In4.Cu")
		(net "M_G_CPU1_SA_DQS_DP<7>")
	)
	(arc
		(start 134.030212 -264.8204)
		(mid 134.029805 -264.820455)
		(end 134.02945 -264.820654)
		(width 0.088646)
		(layer "In4.Cu")
		(net "M_G_CPU1_SA_DQS_DP<7>")
	)
	(arc
		(start 134.022592 -264.824718)
		(mid 133.835394 -264.874861)
		(end 133.648196 -264.824718)
		(width 0.088646)
		(layer "In4.Cu")
		(net "M_G_CPU1_SA_DQS_DP<7>")
	)
	(segment
		(start 194.94119 -301.692818)
		(end 195.199254 -301.434754)
		(width 0.20066)
		(layer "F.Cu")
		(net "M_G_CPU1_SA_DQS_DP<6>")
	)
	(segment
		(start 197.535292 -301.441866)
		(end 197.542658 -301.4345)
		(width 0.1016)
		(layer "F.Cu")
		(net "M_G_CPU1_SA_DQS_DP<6>")
	)
	(segment
		(start 195.522596 -301.441866)
		(end 197.535292 -301.441866)
		(width 0.1016)
		(layer "F.Cu")
		(net "M_G_CPU1_SA_DQS_DP<6>")
	)
	(segment
		(start 199.21855 -302.134778)
		(end 199.796146 -302.134778)
		(width 0.20066)
		(layer "F.Cu")
		(net "M_G_CPU1_SA_DQS_DP<6>")
	)
	(segment
		(start 193.933064 -302.11776)
		(end 194.237864 -302.11776)
		(width 0.20066)
		(layer "F.Cu")
		(net "M_G_CPU1_SA_DQS_DP<6>")
	)
	(segment
		(start 197.542658 -301.4345)
		(end 197.86473 -301.4345)
		(width 0.20066)
		(layer "F.Cu")
		(net "M_G_CPU1_SA_DQS_DP<6>")
	)
	(segment
		(start 128.196848 -272.103342)
		(end 128.196594 -272.639282)
		(width 0.20066)
		(layer "F.Cu")
		(net "M_G_CPU1_SA_DQS_DP<6>")
	)
	(segment
		(start 195.199254 -301.434754)
		(end 195.510658 -301.434754)
		(width 0.20066)
		(layer "F.Cu")
		(net "M_G_CPU1_SA_DQS_DP<6>")
	)
	(segment
		(start 198.119492 -301.689262)
		(end 198.773034 -301.689262)
		(width 0.20066)
		(layer "F.Cu")
		(net "M_G_CPU1_SA_DQS_DP<6>")
	)
	(segment
		(start 195.510658 -301.434754)
		(end 195.515484 -301.434754)
		(width 0.101854)
		(layer "F.Cu")
		(net "M_G_CPU1_SA_DQS_DP<6>")
	)
	(segment
		(start 197.86473 -301.4345)
		(end 198.119492 -301.689262)
		(width 0.20066)
		(layer "F.Cu")
		(net "M_G_CPU1_SA_DQS_DP<6>")
	)
	(segment
		(start 194.237864 -302.11776)
		(end 194.662806 -301.692818)
		(width 0.20066)
		(layer "F.Cu")
		(net "M_G_CPU1_SA_DQS_DP<6>")
	)
	(segment
		(start 193.088514 -301.866808)
		(end 193.682112 -301.866808)
		(width 0.20066)
		(layer "F.Cu")
		(net "M_G_CPU1_SA_DQS_DP<6>")
	)
	(segment
		(start 191.941704 -301.866808)
		(end 193.088514 -301.866808)
		(width 0.20066)
		(layer "F.Cu")
		(net "M_G_CPU1_SA_DQS_DP<6>")
	)
	(segment
		(start 200.064116 -301.866808)
		(end 200.632314 -301.866808)
		(width 0.20066)
		(layer "F.Cu")
		(net "M_G_CPU1_SA_DQS_DP<6>")
	)
	(segment
		(start 198.773034 -301.689262)
		(end 199.21855 -302.134778)
		(width 0.20066)
		(layer "F.Cu")
		(net "M_G_CPU1_SA_DQS_DP<6>")
	)
	(segment
		(start 194.662806 -301.692818)
		(end 194.94119 -301.692818)
		(width 0.20066)
		(layer "F.Cu")
		(net "M_G_CPU1_SA_DQS_DP<6>")
	)
	(segment
		(start 199.796146 -302.134778)
		(end 200.064116 -301.866808)
		(width 0.20066)
		(layer "F.Cu")
		(net "M_G_CPU1_SA_DQS_DP<6>")
	)
	(segment
		(start 195.515484 -301.434754)
		(end 195.522596 -301.441866)
		(width 0.1016)
		(layer "F.Cu")
		(net "M_G_CPU1_SA_DQS_DP<6>")
	)
	(segment
		(start 193.682112 -301.866808)
		(end 193.933064 -302.11776)
		(width 0.20066)
		(layer "F.Cu")
		(net "M_G_CPU1_SA_DQS_DP<6>")
	)
	(segment
		(start 128.709166 -272.639282)
		(end 128.196594 -272.639282)
		(width 0.088646)
		(layer "In6.Cu")
		(net "M_G_CPU1_SA_DQS_DP<6>")
	)
	(segment
		(start 177.165508 -295.492678)
		(end 176.983644 -295.492678)
		(width 0.18288)
		(layer "In6.Cu")
		(net "M_G_CPU1_SA_DQS_DP<6>")
	)
	(segment
		(start 166.251128 -292.333426)
		(end 165.720776 -292.333426)
		(width 0.18288)
		(layer "In6.Cu")
		(net "M_G_CPU1_SA_DQS_DP<6>")
	)
	(segment
		(start 129.295398 -272.219674)
		(end 129.29489 -272.219674)
		(width 0.088646)
		(layer "In6.Cu")
		(net "M_G_CPU1_SA_DQS_DP<6>")
	)
	(segment
		(start 172.666406 -294.640762)
		(end 172.664374 -294.642794)
		(width 0.18288)
		(layer "In6.Cu")
		(net "M_G_CPU1_SA_DQS_DP<6>")
	)
	(segment
		(start 190.891414 -302.290734)
		(end 189.703456 -302.290734)
		(width 0.18288)
		(layer "In6.Cu")
		(net "M_G_CPU1_SA_DQS_DP<6>")
	)
	(segment
		(start 157.82417 -291.529008)
		(end 155.016962 -288.7218)
		(width 0.18288)
		(layer "In6.Cu")
		(net "M_G_CPU1_SA_DQS_DP<6>")
	)
	(segment
		(start 129.275332 -272.220182)
		(end 129.159254 -272.243042)
		(width 0.088646)
		(layer "In6.Cu")
		(net "M_G_CPU1_SA_DQS_DP<6>")
	)
	(segment
		(start 191.941704 -301.866808)
		(end 191.714374 -302.094138)
		(width 0.18288)
		(layer "In6.Cu")
		(net "M_G_CPU1_SA_DQS_DP<6>")
	)
	(segment
		(start 134.507478 -272.140934)
		(end 134.492746 -272.14957)
		(width 0.088646)
		(layer "In6.Cu")
		(net "M_G_CPU1_SA_DQS_DP<6>")
	)
	(segment
		(start 176.763426 -295.4909)
		(end 176.761648 -295.492678)
		(width 0.18288)
		(layer "In6.Cu")
		(net "M_G_CPU1_SA_DQS_DP<6>")
	)
	(segment
		(start 182.524654 -299.174154)
		(end 180.851556 -297.501056)
		(width 0.18288)
		(layer "In6.Cu")
		(net "M_G_CPU1_SA_DQS_DP<6>")
	)
	(segment
		(start 132.623306 -272.143474)
		(end 132.612892 -272.14957)
		(width 0.088646)
		(layer "In6.Cu")
		(net "M_G_CPU1_SA_DQS_DP<6>")
	)
	(segment
		(start 155.016962 -288.7218)
		(end 155.016962 -280.643838)
		(width 0.18288)
		(layer "In6.Cu")
		(net "M_G_CPU1_SA_DQS_DP<6>")
	)
	(segment
		(start 187.35548 -301.710852)
		(end 186.33821 -301.710852)
		(width 0.18288)
		(layer "In6.Cu")
		(net "M_G_CPU1_SA_DQS_DP<6>")
	)
	(segment
		(start 179.290726 -296.349166)
		(end 178.842924 -296.349166)
		(width 0.18288)
		(layer "In6.Cu")
		(net "M_G_CPU1_SA_DQS_DP<6>")
	)
	(segment
		(start 140.572236 -273.537426)
		(end 140.512546 -273.597116)
		(width 0.088646)
		(layer "In6.Cu")
		(net "M_G_CPU1_SA_DQS_DP<6>")
	)
	(segment
		(start 174.86249 -295.759632)
		(end 174.004224 -294.901366)
		(width 0.18288)
		(layer "In6.Cu")
		(net "M_G_CPU1_SA_DQS_DP<6>")
	)
	(segment
		(start 178.842924 -296.349166)
		(end 178.231546 -295.737788)
		(width 0.18288)
		(layer "In6.Cu")
		(net "M_G_CPU1_SA_DQS_DP<6>")
	)
	(segment
		(start 187.624212 -301.44212)
		(end 187.35548 -301.710852)
		(width 0.18288)
		(layer "In6.Cu")
		(net "M_G_CPU1_SA_DQS_DP<6>")
	)
	(segment
		(start 180.851556 -297.501056)
		(end 180.442616 -297.501056)
		(width 0.18288)
		(layer "In6.Cu")
		(net "M_G_CPU1_SA_DQS_DP<6>")
	)
	(segment
		(start 172.879258 -294.642794)
		(end 172.877226 -294.640762)
		(width 0.18288)
		(layer "In6.Cu")
		(net "M_G_CPU1_SA_DQS_DP<6>")
	)
	(segment
		(start 189.107826 -301.695104)
		(end 188.406024 -301.695104)
		(width 0.18288)
		(layer "In6.Cu")
		(net "M_G_CPU1_SA_DQS_DP<6>")
	)
	(segment
		(start 183.496712 -299.174154)
		(end 182.524654 -299.174154)
		(width 0.18288)
		(layer "In6.Cu")
		(net "M_G_CPU1_SA_DQS_DP<6>")
	)
	(segment
		(start 159.55264 -291.529008)
		(end 157.82417 -291.529008)
		(width 0.18288)
		(layer "In6.Cu")
		(net "M_G_CPU1_SA_DQS_DP<6>")
	)
	(segment
		(start 176.63668 -295.492678)
		(end 176.369726 -295.759632)
		(width 0.18288)
		(layer "In6.Cu")
		(net "M_G_CPU1_SA_DQS_DP<6>")
	)
	(segment
		(start 191.08801 -302.094138)
		(end 190.891414 -302.290734)
		(width 0.18288)
		(layer "In6.Cu")
		(net "M_G_CPU1_SA_DQS_DP<6>")
	)
	(segment
		(start 161.528506 -292.348158)
		(end 159.55264 -291.529008)
		(width 0.18288)
		(layer "In6.Cu")
		(net "M_G_CPU1_SA_DQS_DP<6>")
	)
	(segment
		(start 129.159254 -272.243042)
		(end 129.139442 -272.247106)
		(width 0.088646)
		(layer "In6.Cu")
		(net "M_G_CPU1_SA_DQS_DP<6>")
	)
	(segment
		(start 129.794 -272.150078)
		(end 129.676398 -272.217642)
		(width 0.088646)
		(layer "In6.Cu")
		(net "M_G_CPU1_SA_DQS_DP<6>")
	)
	(segment
		(start 180.442616 -297.501056)
		(end 179.290726 -296.349166)
		(width 0.18288)
		(layer "In6.Cu")
		(net "M_G_CPU1_SA_DQS_DP<6>")
	)
	(segment
		(start 129.276094 -272.219928)
		(end 129.275332 -272.220182)
		(width 0.088646)
		(layer "In6.Cu")
		(net "M_G_CPU1_SA_DQS_DP<6>")
	)
	(segment
		(start 140.595604 -273.537426)
		(end 140.572236 -273.537426)
		(width 0.088646)
		(layer "In6.Cu")
		(net "M_G_CPU1_SA_DQS_DP<6>")
	)
	(segment
		(start 164.962586 -292.081712)
		(end 164.69614 -292.348158)
		(width 0.18288)
		(layer "In6.Cu")
		(net "M_G_CPU1_SA_DQS_DP<6>")
	)
	(segment
		(start 138.25474 -272.148046)
		(end 138.251946 -272.14957)
		(width 0.088646)
		(layer "In6.Cu")
		(net "M_G_CPU1_SA_DQS_DP<6>")
	)
	(segment
		(start 172.536612 -294.642794)
		(end 172.256196 -294.92321)
		(width 0.18288)
		(layer "In6.Cu")
		(net "M_G_CPU1_SA_DQS_DP<6>")
	)
	(segment
		(start 184.253124 -299.930566)
		(end 183.496712 -299.174154)
		(width 0.18288)
		(layer "In6.Cu")
		(net "M_G_CPU1_SA_DQS_DP<6>")
	)
	(segment
		(start 178.231546 -295.737788)
		(end 177.410618 -295.737788)
		(width 0.18288)
		(layer "In6.Cu")
		(net "M_G_CPU1_SA_DQS_DP<6>")
	)
	(segment
		(start 129.638552 -272.216372)
		(end 129.630678 -272.216372)
		(width 0.088646)
		(layer "In6.Cu")
		(net "M_G_CPU1_SA_DQS_DP<6>")
	)
	(segment
		(start 129.630678 -272.216372)
		(end 129.295398 -272.219674)
		(width 0.088646)
		(layer "In6.Cu")
		(net "M_G_CPU1_SA_DQS_DP<6>")
	)
	(segment
		(start 148.31822 -273.945096)
		(end 142.259558 -273.945096)
		(width 0.18288)
		(layer "In6.Cu")
		(net "M_G_CPU1_SA_DQS_DP<6>")
	)
	(segment
		(start 138.268964 -272.139918)
		(end 138.25474 -272.148046)
		(width 0.088646)
		(layer "In6.Cu")
		(net "M_G_CPU1_SA_DQS_DP<6>")
	)
	(segment
		(start 173.06544 -294.642794)
		(end 172.879258 -294.642794)
		(width 0.18288)
		(layer "In6.Cu")
		(net "M_G_CPU1_SA_DQS_DP<6>")
	)
	(segment
		(start 176.369726 -295.759632)
		(end 174.86249 -295.759632)
		(width 0.18288)
		(layer "In6.Cu")
		(net "M_G_CPU1_SA_DQS_DP<6>")
	)
	(segment
		(start 129.29489 -272.219674)
		(end 129.276094 -272.219928)
		(width 0.088646)
		(layer "In6.Cu")
		(net "M_G_CPU1_SA_DQS_DP<6>")
	)
	(segment
		(start 128.947672 -272.315686)
		(end 128.940306 -272.320004)
		(width 0.088646)
		(layer "In6.Cu")
		(net "M_G_CPU1_SA_DQS_DP<6>")
	)
	(segment
		(start 155.016962 -280.643838)
		(end 148.31822 -273.945096)
		(width 0.18288)
		(layer "In6.Cu")
		(net "M_G_CPU1_SA_DQS_DP<6>")
	)
	(segment
		(start 184.557924 -299.930566)
		(end 184.253124 -299.930566)
		(width 0.18288)
		(layer "In6.Cu")
		(net "M_G_CPU1_SA_DQS_DP<6>")
	)
	(segment
		(start 129.139442 -272.247106)
		(end 129.089658 -272.26768)
		(width 0.088646)
		(layer "In6.Cu")
		(net "M_G_CPU1_SA_DQS_DP<6>")
	)
	(segment
		(start 172.877226 -294.640762)
		(end 172.666406 -294.640762)
		(width 0.18288)
		(layer "In6.Cu")
		(net "M_G_CPU1_SA_DQS_DP<6>")
	)
	(segment
		(start 188.406024 -301.695104)
		(end 188.15304 -301.44212)
		(width 0.18288)
		(layer "In6.Cu")
		(net "M_G_CPU1_SA_DQS_DP<6>")
	)
	(segment
		(start 189.703456 -302.290734)
		(end 189.107826 -301.695104)
		(width 0.18288)
		(layer "In6.Cu")
		(net "M_G_CPU1_SA_DQS_DP<6>")
	)
	(segment
		(start 191.714374 -302.094138)
		(end 191.08801 -302.094138)
		(width 0.18288)
		(layer "In6.Cu")
		(net "M_G_CPU1_SA_DQS_DP<6>")
	)
	(segment
		(start 188.15304 -301.44212)
		(end 187.624212 -301.44212)
		(width 0.18288)
		(layer "In6.Cu")
		(net "M_G_CPU1_SA_DQS_DP<6>")
	)
	(segment
		(start 130.748278 -272.140934)
		(end 130.733546 -272.14957)
		(width 0.088646)
		(layer "In6.Cu")
		(net "M_G_CPU1_SA_DQS_DP<6>")
	)
	(segment
		(start 176.761648 -295.492678)
		(end 176.63668 -295.492678)
		(width 0.18288)
		(layer "In6.Cu")
		(net "M_G_CPU1_SA_DQS_DP<6>")
	)
	(segment
		(start 128.949196 -272.314924)
		(end 128.947672 -272.315686)
		(width 0.088646)
		(layer "In6.Cu")
		(net "M_G_CPU1_SA_DQS_DP<6>")
	)
	(segment
		(start 132.238496 -272.14957)
		(end 132.228082 -272.143474)
		(width 0.088646)
		(layer "In6.Cu")
		(net "M_G_CPU1_SA_DQS_DP<6>")
	)
	(segment
		(start 140.252196 -273.597116)
		(end 138.887454 -272.232374)
		(width 0.088646)
		(layer "In6.Cu")
		(net "M_G_CPU1_SA_DQS_DP<6>")
	)
	(segment
		(start 135.447278 -272.140934)
		(end 135.432546 -272.14957)
		(width 0.088646)
		(layer "In6.Cu")
		(net "M_G_CPU1_SA_DQS_DP<6>")
	)
	(segment
		(start 129.676398 -272.217642)
		(end 129.638552 -272.216372)
		(width 0.088646)
		(layer "In6.Cu")
		(net "M_G_CPU1_SA_DQS_DP<6>")
	)
	(segment
		(start 136.387078 -272.140934)
		(end 136.372346 -272.14957)
		(width 0.088646)
		(layer "In6.Cu")
		(net "M_G_CPU1_SA_DQS_DP<6>")
	)
	(segment
		(start 173.324012 -294.901366)
		(end 173.06544 -294.642794)
		(width 0.18288)
		(layer "In6.Cu")
		(net "M_G_CPU1_SA_DQS_DP<6>")
	)
	(segment
		(start 172.664374 -294.642794)
		(end 172.536612 -294.642794)
		(width 0.18288)
		(layer "In6.Cu")
		(net "M_G_CPU1_SA_DQS_DP<6>")
	)
	(segment
		(start 177.410618 -295.737788)
		(end 177.165508 -295.492678)
		(width 0.18288)
		(layer "In6.Cu")
		(net "M_G_CPU1_SA_DQS_DP<6>")
	)
	(segment
		(start 174.004224 -294.901366)
		(end 173.324012 -294.901366)
		(width 0.18288)
		(layer "In6.Cu")
		(net "M_G_CPU1_SA_DQS_DP<6>")
	)
	(segment
		(start 186.33821 -301.710852)
		(end 184.557924 -299.930566)
		(width 0.18288)
		(layer "In6.Cu")
		(net "M_G_CPU1_SA_DQS_DP<6>")
	)
	(segment
		(start 172.256196 -294.92321)
		(end 168.840912 -294.92321)
		(width 0.18288)
		(layer "In6.Cu")
		(net "M_G_CPU1_SA_DQS_DP<6>")
	)
	(segment
		(start 176.983644 -295.492678)
		(end 176.981866 -295.4909)
		(width 0.18288)
		(layer "In6.Cu")
		(net "M_G_CPU1_SA_DQS_DP<6>")
	)
	(segment
		(start 165.469062 -292.081712)
		(end 164.962586 -292.081712)
		(width 0.18288)
		(layer "In6.Cu")
		(net "M_G_CPU1_SA_DQS_DP<6>")
	)
	(segment
		(start 165.720776 -292.333426)
		(end 165.469062 -292.081712)
		(width 0.18288)
		(layer "In6.Cu")
		(net "M_G_CPU1_SA_DQS_DP<6>")
	)
	(segment
		(start 140.512546 -273.597116)
		(end 140.252196 -273.597116)
		(width 0.088646)
		(layer "In6.Cu")
		(net "M_G_CPU1_SA_DQS_DP<6>")
	)
	(segment
		(start 133.567678 -272.140934)
		(end 133.552946 -272.14957)
		(width 0.088646)
		(layer "In6.Cu")
		(net "M_G_CPU1_SA_DQS_DP<6>")
	)
	(segment
		(start 137.326878 -272.140934)
		(end 137.312146 -272.14957)
		(width 0.088646)
		(layer "In6.Cu")
		(net "M_G_CPU1_SA_DQS_DP<6>")
	)
	(segment
		(start 142.259558 -273.945096)
		(end 141.275308 -273.537426)
		(width 0.18288)
		(layer "In6.Cu")
		(net "M_G_CPU1_SA_DQS_DP<6>")
	)
	(segment
		(start 176.981866 -295.4909)
		(end 176.763426 -295.4909)
		(width 0.18288)
		(layer "In6.Cu")
		(net "M_G_CPU1_SA_DQS_DP<6>")
	)
	(segment
		(start 128.766316 -272.582132)
		(end 128.709166 -272.639282)
		(width 0.088646)
		(layer "In6.Cu")
		(net "M_G_CPU1_SA_DQS_DP<6>")
	)
	(segment
		(start 168.840912 -294.92321)
		(end 166.251128 -292.333426)
		(width 0.18288)
		(layer "In6.Cu")
		(net "M_G_CPU1_SA_DQS_DP<6>")
	)
	(segment
		(start 164.69614 -292.348158)
		(end 161.528506 -292.348158)
		(width 0.18288)
		(layer "In6.Cu")
		(net "M_G_CPU1_SA_DQS_DP<6>")
	)
	(segment
		(start 141.275308 -273.537426)
		(end 140.595604 -273.537426)
		(width 0.18288)
		(layer "In6.Cu")
		(net "M_G_CPU1_SA_DQS_DP<6>")
	)
	(arc
		(start 130.733546 -272.14957)
		(mid 130.546348 -272.199713)
		(end 130.35915 -272.14957)
		(width 0.088646)
		(layer "In6.Cu")
		(net "M_G_CPU1_SA_DQS_DP<6>")
	)
	(arc
		(start 136.372346 -272.14957)
		(mid 136.185148 -272.199713)
		(end 135.99795 -272.14957)
		(width 0.088646)
		(layer "In6.Cu")
		(net "M_G_CPU1_SA_DQS_DP<6>")
	)
	(arc
		(start 138.251946 -272.14957)
		(mid 138.064748 -272.199713)
		(end 137.87755 -272.14957)
		(width 0.088646)
		(layer "In6.Cu")
		(net "M_G_CPU1_SA_DQS_DP<6>")
	)
	(arc
		(start 129.089658 -272.26768)
		(mid 129.017061 -272.284272)
		(end 128.949196 -272.314924)
		(width 0.088646)
		(layer "In6.Cu")
		(net "M_G_CPU1_SA_DQS_DP<6>")
	)
	(arc
		(start 136.93775 -272.14957)
		(mid 136.663521 -272.073645)
		(end 136.387078 -272.140934)
		(width 0.088646)
		(layer "In6.Cu")
		(net "M_G_CPU1_SA_DQS_DP<6>")
	)
	(arc
		(start 137.87755 -272.14957)
		(mid 137.603321 -272.073645)
		(end 137.326878 -272.140934)
		(width 0.088646)
		(layer "In6.Cu")
		(net "M_G_CPU1_SA_DQS_DP<6>")
	)
	(arc
		(start 132.228082 -272.143474)
		(mid 131.949904 -272.073782)
		(end 131.673346 -272.14957)
		(width 0.088646)
		(layer "In6.Cu")
		(net "M_G_CPU1_SA_DQS_DP<6>")
	)
	(arc
		(start 135.99795 -272.14957)
		(mid 135.723721 -272.073645)
		(end 135.447278 -272.140934)
		(width 0.088646)
		(layer "In6.Cu")
		(net "M_G_CPU1_SA_DQS_DP<6>")
	)
	(arc
		(start 130.358388 -272.150078)
		(mid 130.076194 -272.074522)
		(end 129.794 -272.150078)
		(width 0.088646)
		(layer "In6.Cu")
		(net "M_G_CPU1_SA_DQS_DP<6>")
	)
	(arc
		(start 135.432546 -272.14957)
		(mid 135.245348 -272.199713)
		(end 135.05815 -272.14957)
		(width 0.088646)
		(layer "In6.Cu")
		(net "M_G_CPU1_SA_DQS_DP<6>")
	)
	(arc
		(start 131.673346 -272.14957)
		(mid 131.486148 -272.199713)
		(end 131.29895 -272.14957)
		(width 0.088646)
		(layer "In6.Cu")
		(net "M_G_CPU1_SA_DQS_DP<6>")
	)
	(arc
		(start 137.312146 -272.14957)
		(mid 137.124948 -272.199713)
		(end 136.93775 -272.14957)
		(width 0.088646)
		(layer "In6.Cu")
		(net "M_G_CPU1_SA_DQS_DP<6>")
	)
	(arc
		(start 134.492746 -272.14957)
		(mid 134.305548 -272.199713)
		(end 134.11835 -272.14957)
		(width 0.088646)
		(layer "In6.Cu")
		(net "M_G_CPU1_SA_DQS_DP<6>")
	)
	(arc
		(start 131.29895 -272.14957)
		(mid 131.024721 -272.073645)
		(end 130.748278 -272.140934)
		(width 0.088646)
		(layer "In6.Cu")
		(net "M_G_CPU1_SA_DQS_DP<6>")
	)
	(arc
		(start 134.11835 -272.14957)
		(mid 133.844121 -272.073645)
		(end 133.567678 -272.140934)
		(width 0.088646)
		(layer "In6.Cu")
		(net "M_G_CPU1_SA_DQS_DP<6>")
	)
	(arc
		(start 133.17855 -272.14957)
		(mid 132.901737 -272.073734)
		(end 132.623306 -272.143474)
		(width 0.088646)
		(layer "In6.Cu")
		(net "M_G_CPU1_SA_DQS_DP<6>")
	)
	(arc
		(start 132.612892 -272.14957)
		(mid 132.425694 -272.199713)
		(end 132.238496 -272.14957)
		(width 0.088646)
		(layer "In6.Cu")
		(net "M_G_CPU1_SA_DQS_DP<6>")
	)
	(arc
		(start 133.552946 -272.14957)
		(mid 133.365748 -272.199713)
		(end 133.17855 -272.14957)
		(width 0.088646)
		(layer "In6.Cu")
		(net "M_G_CPU1_SA_DQS_DP<6>")
	)
	(arc
		(start 138.887454 -272.232374)
		(mid 138.593467 -272.084214)
		(end 138.268964 -272.139918)
		(width 0.088646)
		(layer "In6.Cu")
		(net "M_G_CPU1_SA_DQS_DP<6>")
	)
	(arc
		(start 130.35915 -272.14957)
		(mid 130.358769 -272.149824)
		(end 130.358388 -272.150078)
		(width 0.088646)
		(layer "In6.Cu")
		(net "M_G_CPU1_SA_DQS_DP<6>")
	)
	(arc
		(start 135.05815 -272.14957)
		(mid 134.783921 -272.073645)
		(end 134.507478 -272.140934)
		(width 0.088646)
		(layer "In6.Cu")
		(net "M_G_CPU1_SA_DQS_DP<6>")
	)
	(arc
		(start 128.940306 -272.320004)
		(mid 128.824497 -272.431933)
		(end 128.766316 -272.582132)
		(width 0.088646)
		(layer "In6.Cu")
		(net "M_G_CPU1_SA_DQS_DP<6>")
	)
	(segment
		(start 194.662806 -311.042812)
		(end 194.94119 -311.042812)
		(width 0.20066)
		(layer "F.Cu")
		(net "M_G_CPU1_SA_DQS_DP<5>")
	)
	(segment
		(start 193.088514 -311.216802)
		(end 193.682112 -311.216802)
		(width 0.20066)
		(layer "F.Cu")
		(net "M_G_CPU1_SA_DQS_DP<5>")
	)
	(segment
		(start 197.86473 -310.784494)
		(end 198.119492 -311.039256)
		(width 0.20066)
		(layer "F.Cu")
		(net "M_G_CPU1_SA_DQS_DP<5>")
	)
	(segment
		(start 191.983614 -311.216548)
		(end 191.983868 -311.216802)
		(width 0.20066)
		(layer "F.Cu")
		(net "M_G_CPU1_SA_DQS_DP<5>")
	)
	(segment
		(start 194.237864 -311.467754)
		(end 194.662806 -311.042812)
		(width 0.20066)
		(layer "F.Cu")
		(net "M_G_CPU1_SA_DQS_DP<5>")
	)
	(segment
		(start 191.983868 -311.216802)
		(end 193.088514 -311.216802)
		(width 0.20066)
		(layer "F.Cu")
		(net "M_G_CPU1_SA_DQS_DP<5>")
	)
	(segment
		(start 194.94119 -311.042812)
		(end 195.199254 -310.784748)
		(width 0.20066)
		(layer "F.Cu")
		(net "M_G_CPU1_SA_DQS_DP<5>")
	)
	(segment
		(start 195.515484 -310.784748)
		(end 195.522596 -310.79186)
		(width 0.1016)
		(layer "F.Cu")
		(net "M_G_CPU1_SA_DQS_DP<5>")
	)
	(segment
		(start 195.510658 -310.784748)
		(end 195.515484 -310.784748)
		(width 0.101854)
		(layer "F.Cu")
		(net "M_G_CPU1_SA_DQS_DP<5>")
	)
	(segment
		(start 131.485894 -274.54479)
		(end 131.486148 -274.545044)
		(width 0.20066)
		(layer "F.Cu")
		(net "M_G_CPU1_SA_DQS_DP<5>")
	)
	(segment
		(start 198.119492 -311.039256)
		(end 198.773034 -311.039256)
		(width 0.20066)
		(layer "F.Cu")
		(net "M_G_CPU1_SA_DQS_DP<5>")
	)
	(segment
		(start 195.199254 -310.784748)
		(end 195.510658 -310.784748)
		(width 0.20066)
		(layer "F.Cu")
		(net "M_G_CPU1_SA_DQS_DP<5>")
	)
	(segment
		(start 193.682112 -311.216802)
		(end 193.933064 -311.467754)
		(width 0.20066)
		(layer "F.Cu")
		(net "M_G_CPU1_SA_DQS_DP<5>")
	)
	(segment
		(start 198.773034 -311.039256)
		(end 199.21855 -311.484772)
		(width 0.20066)
		(layer "F.Cu")
		(net "M_G_CPU1_SA_DQS_DP<5>")
	)
	(segment
		(start 195.522596 -310.79186)
		(end 197.535292 -310.79186)
		(width 0.1016)
		(layer "F.Cu")
		(net "M_G_CPU1_SA_DQS_DP<5>")
	)
	(segment
		(start 199.796146 -311.484772)
		(end 200.064116 -311.216802)
		(width 0.20066)
		(layer "F.Cu")
		(net "M_G_CPU1_SA_DQS_DP<5>")
	)
	(segment
		(start 199.21855 -311.484772)
		(end 199.796146 -311.484772)
		(width 0.20066)
		(layer "F.Cu")
		(net "M_G_CPU1_SA_DQS_DP<5>")
	)
	(segment
		(start 200.064116 -311.216802)
		(end 200.632314 -311.216802)
		(width 0.20066)
		(layer "F.Cu")
		(net "M_G_CPU1_SA_DQS_DP<5>")
	)
	(segment
		(start 197.535292 -310.79186)
		(end 197.542658 -310.784494)
		(width 0.1016)
		(layer "F.Cu")
		(net "M_G_CPU1_SA_DQS_DP<5>")
	)
	(segment
		(start 197.542658 -310.784494)
		(end 197.86473 -310.784494)
		(width 0.20066)
		(layer "F.Cu")
		(net "M_G_CPU1_SA_DQS_DP<5>")
	)
	(segment
		(start 193.933064 -311.467754)
		(end 194.237864 -311.467754)
		(width 0.20066)
		(layer "F.Cu")
		(net "M_G_CPU1_SA_DQS_DP<5>")
	)
	(segment
		(start 131.486148 -274.545044)
		(end 131.486148 -275.08073)
		(width 0.20066)
		(layer "F.Cu")
		(net "M_G_CPU1_SA_DQS_DP<5>")
	)
	(segment
		(start 143.238728 -282.519882)
		(end 142.405862 -280.508964)
		(width 0.18288)
		(layer "In4.Cu")
		(net "M_G_CPU1_SA_DQS_DP<5>")
	)
	(segment
		(start 168.642284 -311.982866)
		(end 168.39057 -311.982866)
		(width 0.18288)
		(layer "In4.Cu")
		(net "M_G_CPU1_SA_DQS_DP<5>")
	)
	(segment
		(start 137.877296 -277.032974)
		(end 137.868406 -277.027894)
		(width 0.088646)
		(layer "In4.Cu")
		(net "M_G_CPU1_SA_DQS_DP<5>")
	)
	(segment
		(start 132.05587 -275.02358)
		(end 131.99872 -275.08073)
		(width 0.088646)
		(layer "In4.Cu")
		(net "M_G_CPU1_SA_DQS_DP<5>")
	)
	(segment
		(start 158.193994 -307.660294)
		(end 157.926278 -307.392578)
		(width 0.18288)
		(layer "In4.Cu")
		(net "M_G_CPU1_SA_DQS_DP<5>")
	)
	(segment
		(start 188.127894 -310.792622)
		(end 188.032898 -310.792622)
		(width 0.18288)
		(layer "In4.Cu")
		(net "M_G_CPU1_SA_DQS_DP<5>")
	)
	(segment
		(start 134.9629 -274.59178)
		(end 134.962392 -274.591272)
		(width 0.088646)
		(layer "In4.Cu")
		(net "M_G_CPU1_SA_DQS_DP<5>")
	)
	(segment
		(start 157.474666 -307.392578)
		(end 157.24251 -307.62448)
		(width 0.18288)
		(layer "In4.Cu")
		(net "M_G_CPU1_SA_DQS_DP<5>")
	)
	(segment
		(start 165.573964 -311.04332)
		(end 165.255702 -310.725058)
		(width 0.18288)
		(layer "In4.Cu")
		(net "M_G_CPU1_SA_DQS_DP<5>")
	)
	(segment
		(start 131.99872 -275.08073)
		(end 131.486148 -275.08073)
		(width 0.088646)
		(layer "In4.Cu")
		(net "M_G_CPU1_SA_DQS_DP<5>")
	)
	(segment
		(start 148.917914 -296.23004)
		(end 143.238728 -282.519882)
		(width 0.18288)
		(layer "In4.Cu")
		(net "M_G_CPU1_SA_DQS_DP<5>")
	)
	(segment
		(start 177.376836 -312.763662)
		(end 177.10531 -312.492136)
		(width 0.18288)
		(layer "In4.Cu")
		(net "M_G_CPU1_SA_DQS_DP<5>")
	)
	(segment
		(start 181.36235 -311.92597)
		(end 178.64074 -311.92597)
		(width 0.18288)
		(layer "In4.Cu")
		(net "M_G_CPU1_SA_DQS_DP<5>")
	)
	(segment
		(start 132.842 -274.705826)
		(end 132.426964 -274.705826)
		(width 0.088646)
		(layer "In4.Cu")
		(net "M_G_CPU1_SA_DQS_DP<5>")
	)
	(segment
		(start 188.393324 -311.058052)
		(end 188.127894 -310.792622)
		(width 0.18288)
		(layer "In4.Cu")
		(net "M_G_CPU1_SA_DQS_DP<5>")
	)
	(segment
		(start 178.64074 -311.92597)
		(end 177.803048 -312.763662)
		(width 0.18288)
		(layer "In4.Cu")
		(net "M_G_CPU1_SA_DQS_DP<5>")
	)
	(segment
		(start 191.448436 -311.456832)
		(end 191.007492 -311.639458)
		(width 0.18288)
		(layer "In4.Cu")
		(net "M_G_CPU1_SA_DQS_DP<5>")
	)
	(segment
		(start 135.99795 -275.405342)
		(end 135.98906 -275.400262)
		(width 0.088646)
		(layer "In4.Cu")
		(net "M_G_CPU1_SA_DQS_DP<5>")
	)
	(segment
		(start 132.23875 -274.756372)
		(end 132.22986 -274.761452)
		(width 0.088646)
		(layer "In4.Cu")
		(net "M_G_CPU1_SA_DQS_DP<5>")
	)
	(segment
		(start 140.689838 -278.79294)
		(end 140.673328 -278.77643)
		(width 0.088646)
		(layer "In4.Cu")
		(net "M_G_CPU1_SA_DQS_DP<5>")
	)
	(segment
		(start 191.983614 -311.216548)
		(end 191.74333 -311.456832)
		(width 0.18288)
		(layer "In4.Cu")
		(net "M_G_CPU1_SA_DQS_DP<5>")
	)
	(segment
		(start 135.810498 -275.080984)
		(end 135.810498 -275.06676)
		(width 0.088646)
		(layer "In4.Cu")
		(net "M_G_CPU1_SA_DQS_DP<5>")
	)
	(segment
		(start 187.681108 -310.792368)
		(end 187.680854 -310.792622)
		(width 0.18288)
		(layer "In4.Cu")
		(net "M_G_CPU1_SA_DQS_DP<5>")
	)
	(segment
		(start 188.032898 -310.792622)
		(end 188.032644 -310.792368)
		(width 0.18288)
		(layer "In4.Cu")
		(net "M_G_CPU1_SA_DQS_DP<5>")
	)
	(segment
		(start 177.10531 -312.492136)
		(end 176.673764 -312.492136)
		(width 0.18288)
		(layer "In4.Cu")
		(net "M_G_CPU1_SA_DQS_DP<5>")
	)
	(segment
		(start 176.37252 -312.79338)
		(end 175.36922 -312.79338)
		(width 0.18288)
		(layer "In4.Cu")
		(net "M_G_CPU1_SA_DQS_DP<5>")
	)
	(segment
		(start 166.122096 -311.04332)
		(end 165.573964 -311.04332)
		(width 0.18288)
		(layer "In4.Cu")
		(net "M_G_CPU1_SA_DQS_DP<5>")
	)
	(segment
		(start 137.219944 -275.8948)
		(end 137.219944 -275.879306)
		(width 0.088646)
		(layer "In4.Cu")
		(net "M_G_CPU1_SA_DQS_DP<5>")
	)
	(segment
		(start 132.944362 -274.671282)
		(end 132.842 -274.705826)
		(width 0.088646)
		(layer "In4.Cu")
		(net "M_G_CPU1_SA_DQS_DP<5>")
	)
	(segment
		(start 157.926278 -307.392578)
		(end 157.474666 -307.392578)
		(width 0.18288)
		(layer "In4.Cu")
		(net "M_G_CPU1_SA_DQS_DP<5>")
	)
	(segment
		(start 138.771122 -276.958552)
		(end 138.56589 -276.958552)
		(width 0.088646)
		(layer "In4.Cu")
		(net "M_G_CPU1_SA_DQS_DP<5>")
	)
	(segment
		(start 176.673764 -312.492136)
		(end 176.37252 -312.79338)
		(width 0.18288)
		(layer "In4.Cu")
		(net "M_G_CPU1_SA_DQS_DP<5>")
	)
	(segment
		(start 164.564314 -311.024016)
		(end 164.179504 -311.024016)
		(width 0.18288)
		(layer "In4.Cu")
		(net "M_G_CPU1_SA_DQS_DP<5>")
	)
	(segment
		(start 136.387078 -275.396706)
		(end 136.372346 -275.405342)
		(width 0.088646)
		(layer "In4.Cu")
		(net "M_G_CPU1_SA_DQS_DP<5>")
	)
	(segment
		(start 170.073828 -312.417714)
		(end 168.642284 -311.982866)
		(width 0.18288)
		(layer "In4.Cu")
		(net "M_G_CPU1_SA_DQS_DP<5>")
	)
	(segment
		(start 138.251946 -277.033228)
		(end 138.251692 -277.032974)
		(width 0.088646)
		(layer "In4.Cu")
		(net "M_G_CPU1_SA_DQS_DP<5>")
	)
	(segment
		(start 137.689844 -276.708616)
		(end 137.689844 -276.69871)
		(width 0.088646)
		(layer "In4.Cu")
		(net "M_G_CPU1_SA_DQS_DP<5>")
	)
	(segment
		(start 170.832018 -312.92419)
		(end 170.073828 -312.417714)
		(width 0.18288)
		(layer "In4.Cu")
		(net "M_G_CPU1_SA_DQS_DP<5>")
	)
	(segment
		(start 171.869354 -313.617356)
		(end 170.832018 -312.92419)
		(width 0.18288)
		(layer "In4.Cu")
		(net "M_G_CPU1_SA_DQS_DP<5>")
	)
	(segment
		(start 133.648196 -274.591272)
		(end 133.64845 -274.59178)
		(width 0.088646)
		(layer "In4.Cu")
		(net "M_G_CPU1_SA_DQS_DP<5>")
	)
	(segment
		(start 139.817348 -278.004778)
		(end 138.771122 -276.958552)
		(width 0.088646)
		(layer "In4.Cu")
		(net "M_G_CPU1_SA_DQS_DP<5>")
	)
	(segment
		(start 188.598302 -311.058052)
		(end 188.393324 -311.058052)
		(width 0.18288)
		(layer "In4.Cu")
		(net "M_G_CPU1_SA_DQS_DP<5>")
	)
	(segment
		(start 164.179504 -311.024016)
		(end 163.180014 -310.024272)
		(width 0.18288)
		(layer "In4.Cu")
		(net "M_G_CPU1_SA_DQS_DP<5>")
	)
	(segment
		(start 187.36183 -311.094628)
		(end 186.32678 -311.094628)
		(width 0.18288)
		(layer "In4.Cu")
		(net "M_G_CPU1_SA_DQS_DP<5>")
	)
	(segment
		(start 190.00089 -311.639458)
		(end 188.598302 -311.058052)
		(width 0.18288)
		(layer "In4.Cu")
		(net "M_G_CPU1_SA_DQS_DP<5>")
	)
	(segment
		(start 134.587996 -274.591272)
		(end 134.573264 -274.582636)
		(width 0.088646)
		(layer "In4.Cu")
		(net "M_G_CPU1_SA_DQS_DP<5>")
	)
	(segment
		(start 164.863272 -310.725058)
		(end 164.564314 -311.024016)
		(width 0.18288)
		(layer "In4.Cu")
		(net "M_G_CPU1_SA_DQS_DP<5>")
	)
	(segment
		(start 140.673328 -278.77643)
		(end 140.588492 -278.77643)
		(width 0.088646)
		(layer "In4.Cu")
		(net "M_G_CPU1_SA_DQS_DP<5>")
	)
	(segment
		(start 156.737558 -307.62448)
		(end 156.11856 -307.005482)
		(width 0.18288)
		(layer "In4.Cu")
		(net "M_G_CPU1_SA_DQS_DP<5>")
	)
	(segment
		(start 175.36922 -312.79338)
		(end 173.429422 -313.600592)
		(width 0.18288)
		(layer "In4.Cu")
		(net "M_G_CPU1_SA_DQS_DP<5>")
	)
	(segment
		(start 161.281872 -309.238142)
		(end 161.281872 -309.237888)
		(width 0.18288)
		(layer "In4.Cu")
		(net "M_G_CPU1_SA_DQS_DP<5>")
	)
	(segment
		(start 172.602144 -313.342274)
		(end 172.327062 -313.617356)
		(width 0.18288)
		(layer "In4.Cu")
		(net "M_G_CPU1_SA_DQS_DP<5>")
	)
	(segment
		(start 187.680854 -310.792622)
		(end 187.663836 -310.792622)
		(width 0.18288)
		(layer "In4.Cu")
		(net "M_G_CPU1_SA_DQS_DP<5>")
	)
	(segment
		(start 187.663836 -310.792622)
		(end 187.36183 -311.094628)
		(width 0.18288)
		(layer "In4.Cu")
		(net "M_G_CPU1_SA_DQS_DP<5>")
	)
	(segment
		(start 140.588492 -278.77643)
		(end 139.817348 -278.005286)
		(width 0.088646)
		(layer "In4.Cu")
		(net "M_G_CPU1_SA_DQS_DP<5>")
	)
	(segment
		(start 172.995082 -313.342274)
		(end 172.602144 -313.342274)
		(width 0.18288)
		(layer "In4.Cu")
		(net "M_G_CPU1_SA_DQS_DP<5>")
	)
	(segment
		(start 184.251092 -311.350406)
		(end 181.36235 -311.92597)
		(width 0.18288)
		(layer "In4.Cu")
		(net "M_G_CPU1_SA_DQS_DP<5>")
	)
	(segment
		(start 186.32678 -311.094628)
		(end 185.040778 -311.350406)
		(width 0.18288)
		(layer "In4.Cu")
		(net "M_G_CPU1_SA_DQS_DP<5>")
	)
	(segment
		(start 158.580074 -307.660294)
		(end 158.193994 -307.660294)
		(width 0.18288)
		(layer "In4.Cu")
		(net "M_G_CPU1_SA_DQS_DP<5>")
	)
	(segment
		(start 159.36341 -308.443376)
		(end 158.580074 -307.660294)
		(width 0.18288)
		(layer "In4.Cu")
		(net "M_G_CPU1_SA_DQS_DP<5>")
	)
	(segment
		(start 133.0833 -274.591526)
		(end 132.944362 -274.671282)
		(width 0.088646)
		(layer "In4.Cu")
		(net "M_G_CPU1_SA_DQS_DP<5>")
	)
	(segment
		(start 161.281872 -309.237888)
		(end 159.36341 -308.443376)
		(width 0.18288)
		(layer "In4.Cu")
		(net "M_G_CPU1_SA_DQS_DP<5>")
	)
	(segment
		(start 173.2534 -313.600592)
		(end 172.995082 -313.342274)
		(width 0.18288)
		(layer "In4.Cu")
		(net "M_G_CPU1_SA_DQS_DP<5>")
	)
	(segment
		(start 157.24251 -307.62448)
		(end 156.737558 -307.62448)
		(width 0.18288)
		(layer "In4.Cu")
		(net "M_G_CPU1_SA_DQS_DP<5>")
	)
	(segment
		(start 135.527796 -274.591272)
		(end 135.527288 -274.591526)
		(width 0.088646)
		(layer "In4.Cu")
		(net "M_G_CPU1_SA_DQS_DP<5>")
	)
	(segment
		(start 191.74333 -311.456832)
		(end 191.448436 -311.456832)
		(width 0.18288)
		(layer "In4.Cu")
		(net "M_G_CPU1_SA_DQS_DP<5>")
	)
	(segment
		(start 137.407396 -276.219158)
		(end 137.398506 -276.214078)
		(width 0.088646)
		(layer "In4.Cu")
		(net "M_G_CPU1_SA_DQS_DP<5>")
	)
	(segment
		(start 173.429422 -313.600592)
		(end 173.2534 -313.600592)
		(width 0.18288)
		(layer "In4.Cu")
		(net "M_G_CPU1_SA_DQS_DP<5>")
	)
	(segment
		(start 177.803048 -312.763662)
		(end 177.376836 -312.763662)
		(width 0.18288)
		(layer "In4.Cu")
		(net "M_G_CPU1_SA_DQS_DP<5>")
	)
	(segment
		(start 191.007492 -311.639458)
		(end 190.00089 -311.639458)
		(width 0.18288)
		(layer "In4.Cu")
		(net "M_G_CPU1_SA_DQS_DP<5>")
	)
	(segment
		(start 168.39057 -311.982866)
		(end 167.748458 -311.716928)
		(width 0.18288)
		(layer "In4.Cu")
		(net "M_G_CPU1_SA_DQS_DP<5>")
	)
	(segment
		(start 172.327062 -313.617356)
		(end 171.869354 -313.617356)
		(width 0.18288)
		(layer "In4.Cu")
		(net "M_G_CPU1_SA_DQS_DP<5>")
	)
	(segment
		(start 156.11856 -307.005482)
		(end 148.917914 -296.23004)
		(width 0.18288)
		(layer "In4.Cu")
		(net "M_G_CPU1_SA_DQS_DP<5>")
	)
	(segment
		(start 163.180014 -310.024272)
		(end 161.281872 -309.238142)
		(width 0.18288)
		(layer "In4.Cu")
		(net "M_G_CPU1_SA_DQS_DP<5>")
	)
	(segment
		(start 167.748458 -311.716928)
		(end 166.122096 -311.04332)
		(width 0.18288)
		(layer "In4.Cu")
		(net "M_G_CPU1_SA_DQS_DP<5>")
	)
	(segment
		(start 188.032644 -310.792368)
		(end 187.681108 -310.792368)
		(width 0.18288)
		(layer "In4.Cu")
		(net "M_G_CPU1_SA_DQS_DP<5>")
	)
	(segment
		(start 142.405862 -280.508964)
		(end 140.689838 -278.79294)
		(width 0.18288)
		(layer "In4.Cu")
		(net "M_G_CPU1_SA_DQS_DP<5>")
	)
	(segment
		(start 185.040778 -311.350406)
		(end 184.251092 -311.350406)
		(width 0.18288)
		(layer "In4.Cu")
		(net "M_G_CPU1_SA_DQS_DP<5>")
	)
	(segment
		(start 139.817348 -278.005286)
		(end 139.817348 -278.004778)
		(width 0.088646)
		(layer "In4.Cu")
		(net "M_G_CPU1_SA_DQS_DP<5>")
	)
	(segment
		(start 165.255702 -310.725058)
		(end 164.863272 -310.725058)
		(width 0.18288)
		(layer "In4.Cu")
		(net "M_G_CPU1_SA_DQS_DP<5>")
	)
	(arc
		(start 137.398506 -276.214078)
		(mid 137.267592 -276.077718)
		(end 137.219944 -275.8948)
		(width 0.088646)
		(layer "In4.Cu")
		(net "M_G_CPU1_SA_DQS_DP<5>")
	)
	(arc
		(start 137.689844 -276.69871)
		(mid 137.611733 -276.421761)
		(end 137.407396 -276.219158)
		(width 0.088646)
		(layer "In4.Cu")
		(net "M_G_CPU1_SA_DQS_DP<5>")
	)
	(arc
		(start 132.426964 -274.705826)
		(mid 132.357556 -274.712412)
		(end 132.290566 -274.731734)
		(width 0.088646)
		(layer "In4.Cu")
		(net "M_G_CPU1_SA_DQS_DP<5>")
	)
	(arc
		(start 132.288788 -274.732242)
		(mid 132.263319 -274.743375)
		(end 132.23875 -274.756372)
		(width 0.088646)
		(layer "In4.Cu")
		(net "M_G_CPU1_SA_DQS_DP<5>")
	)
	(arc
		(start 136.372346 -275.405342)
		(mid 136.185148 -275.455485)
		(end 135.99795 -275.405342)
		(width 0.088646)
		(layer "In4.Cu")
		(net "M_G_CPU1_SA_DQS_DP<5>")
	)
	(arc
		(start 134.601458 -274.598638)
		(mid 134.594689 -274.595025)
		(end 134.587996 -274.591272)
		(width 0.088646)
		(layer "In4.Cu")
		(net "M_G_CPU1_SA_DQS_DP<5>")
	)
	(arc
		(start 138.56589 -276.958552)
		(mid 138.403468 -276.972984)
		(end 138.251946 -277.033228)
		(width 0.088646)
		(layer "In4.Cu")
		(net "M_G_CPU1_SA_DQS_DP<5>")
	)
	(arc
		(start 136.93775 -275.405342)
		(mid 136.663551 -275.329507)
		(end 136.387078 -275.396706)
		(width 0.088646)
		(layer "In4.Cu")
		(net "M_G_CPU1_SA_DQS_DP<5>")
	)
	(arc
		(start 134.573264 -274.582636)
		(mid 134.296789 -274.515316)
		(end 134.022592 -274.591272)
		(width 0.088646)
		(layer "In4.Cu")
		(net "M_G_CPU1_SA_DQS_DP<5>")
	)
	(arc
		(start 137.868406 -277.027894)
		(mid 137.737492 -276.891534)
		(end 137.689844 -276.708616)
		(width 0.088646)
		(layer "In4.Cu")
		(net "M_G_CPU1_SA_DQS_DP<5>")
	)
	(arc
		(start 135.527288 -274.591526)
		(mid 135.245065 -274.516131)
		(end 134.9629 -274.59178)
		(width 0.088646)
		(layer "In4.Cu")
		(net "M_G_CPU1_SA_DQS_DP<5>")
	)
	(arc
		(start 134.962392 -274.591272)
		(mid 134.782867 -274.641337)
		(end 134.601458 -274.598638)
		(width 0.088646)
		(layer "In4.Cu")
		(net "M_G_CPU1_SA_DQS_DP<5>")
	)
	(arc
		(start 138.251692 -277.032974)
		(mid 138.064494 -277.083117)
		(end 137.877296 -277.032974)
		(width 0.088646)
		(layer "In4.Cu")
		(net "M_G_CPU1_SA_DQS_DP<5>")
	)
	(arc
		(start 135.98906 -275.400262)
		(mid 135.858146 -275.263902)
		(end 135.810498 -275.080984)
		(width 0.088646)
		(layer "In4.Cu")
		(net "M_G_CPU1_SA_DQS_DP<5>")
	)
	(arc
		(start 137.219944 -275.879306)
		(mid 137.140574 -275.605572)
		(end 136.93775 -275.405342)
		(width 0.088646)
		(layer "In4.Cu")
		(net "M_G_CPU1_SA_DQS_DP<5>")
	)
	(arc
		(start 134.022592 -274.591272)
		(mid 133.835394 -274.641415)
		(end 133.648196 -274.591272)
		(width 0.088646)
		(layer "In4.Cu")
		(net "M_G_CPU1_SA_DQS_DP<5>")
	)
	(arc
		(start 132.290566 -274.731734)
		(mid 132.289677 -274.731989)
		(end 132.288788 -274.732242)
		(width 0.088646)
		(layer "In4.Cu")
		(net "M_G_CPU1_SA_DQS_DP<5>")
	)
	(arc
		(start 135.810498 -275.06676)
		(mid 135.731279 -274.792075)
		(end 135.527796 -274.591272)
		(width 0.088646)
		(layer "In4.Cu")
		(net "M_G_CPU1_SA_DQS_DP<5>")
	)
	(arc
		(start 132.22986 -274.761452)
		(mid 132.114051 -274.873381)
		(end 132.05587 -275.02358)
		(width 0.088646)
		(layer "In4.Cu")
		(net "M_G_CPU1_SA_DQS_DP<5>")
	)
	(arc
		(start 133.64845 -274.59178)
		(mid 133.365921 -274.515936)
		(end 133.0833 -274.591526)
		(width 0.088646)
		(layer "In4.Cu")
		(net "M_G_CPU1_SA_DQS_DP<5>")
	)
	(segment
		(start 191.899286 -275.94179)
		(end 191.935608 -275.94179)
		(width 0.101854)
		(layer "F.Cu")
		(net "M_G_CPU1_SA_DQS_DP<4>")
	)
	(segment
		(start 194.724782 -275.645372)
		(end 195.095368 -275.645372)
		(width 0.20066)
		(layer "F.Cu")
		(net "M_G_CPU1_SA_DQS_DP<4>")
	)
	(segment
		(start 195.70192 -275.234908)
		(end 195.983606 -275.516594)
		(width 0.20066)
		(layer "F.Cu")
		(net "M_G_CPU1_SA_DQS_DP<4>")
	)
	(segment
		(start 126.317248 -262.87222)
		(end 126.316994 -262.872474)
		(width 0.20066)
		(layer "F.Cu")
		(net "M_G_CPU1_SA_DQS_DP<4>")
	)
	(segment
		(start 191.935608 -275.94179)
		(end 194.09283 -275.94179)
		(width 0.1016)
		(layer "F.Cu")
		(net "M_G_CPU1_SA_DQS_DP<4>")
	)
	(segment
		(start 194.09283 -275.94179)
		(end 194.306952 -275.94179)
		(width 0.101854)
		(layer "F.Cu")
		(net "M_G_CPU1_SA_DQS_DP<4>")
	)
	(segment
		(start 194.306952 -275.94179)
		(end 194.428364 -275.94179)
		(width 0.20066)
		(layer "F.Cu")
		(net "M_G_CPU1_SA_DQS_DP<4>")
	)
	(segment
		(start 191.770254 -275.94179)
		(end 191.899286 -275.94179)
		(width 0.20066)
		(layer "F.Cu")
		(net "M_G_CPU1_SA_DQS_DP<4>")
	)
	(segment
		(start 191.519048 -275.690584)
		(end 191.770254 -275.94179)
		(width 0.20066)
		(layer "F.Cu")
		(net "M_G_CPU1_SA_DQS_DP<4>")
	)
	(segment
		(start 188.988446 -275.516594)
		(end 189.577726 -275.516594)
		(width 0.20066)
		(layer "F.Cu")
		(net "M_G_CPU1_SA_DQS_DP<4>")
	)
	(segment
		(start 195.095368 -275.645372)
		(end 195.505832 -275.234908)
		(width 0.20066)
		(layer "F.Cu")
		(net "M_G_CPU1_SA_DQS_DP<4>")
	)
	(segment
		(start 190.257938 -275.276056)
		(end 190.672466 -275.690584)
		(width 0.20066)
		(layer "F.Cu")
		(net "M_G_CPU1_SA_DQS_DP<4>")
	)
	(segment
		(start 194.428364 -275.94179)
		(end 194.724782 -275.645372)
		(width 0.20066)
		(layer "F.Cu")
		(net "M_G_CPU1_SA_DQS_DP<4>")
	)
	(segment
		(start 187.883546 -275.516594)
		(end 188.988446 -275.516594)
		(width 0.20066)
		(layer "F.Cu")
		(net "M_G_CPU1_SA_DQS_DP<4>")
	)
	(segment
		(start 126.317248 -262.336534)
		(end 126.317248 -262.87222)
		(width 0.20066)
		(layer "F.Cu")
		(net "M_G_CPU1_SA_DQS_DP<4>")
	)
	(segment
		(start 189.818264 -275.276056)
		(end 190.257938 -275.276056)
		(width 0.20066)
		(layer "F.Cu")
		(net "M_G_CPU1_SA_DQS_DP<4>")
	)
	(segment
		(start 195.505832 -275.234908)
		(end 195.70192 -275.234908)
		(width 0.20066)
		(layer "F.Cu")
		(net "M_G_CPU1_SA_DQS_DP<4>")
	)
	(segment
		(start 190.672466 -275.690584)
		(end 191.519048 -275.690584)
		(width 0.20066)
		(layer "F.Cu")
		(net "M_G_CPU1_SA_DQS_DP<4>")
	)
	(segment
		(start 195.983606 -275.516594)
		(end 196.532246 -275.516594)
		(width 0.20066)
		(layer "F.Cu")
		(net "M_G_CPU1_SA_DQS_DP<4>")
	)
	(segment
		(start 189.577726 -275.516594)
		(end 189.818264 -275.276056)
		(width 0.20066)
		(layer "F.Cu")
		(net "M_G_CPU1_SA_DQS_DP<4>")
	)
	(segment
		(start 179.498752 -266.922758)
		(end 178.558444 -266.922758)
		(width 0.18288)
		(layer "In6.Cu")
		(net "M_G_CPU1_SA_DQS_DP<4>")
	)
	(segment
		(start 176.642268 -266.59078)
		(end 176.381664 -266.330176)
		(width 0.18288)
		(layer "In6.Cu")
		(net "M_G_CPU1_SA_DQS_DP<4>")
	)
	(segment
		(start 138.817096 -263.362186)
		(end 138.802364 -263.370822)
		(width 0.088646)
		(layer "In6.Cu")
		(net "M_G_CPU1_SA_DQS_DP<4>")
	)
	(segment
		(start 139.192254 -263.361678)
		(end 139.192 -263.361678)
		(width 0.088646)
		(layer "In6.Cu")
		(net "M_G_CPU1_SA_DQS_DP<4>")
	)
	(segment
		(start 160.04667 -264.605516)
		(end 157.245558 -264.605516)
		(width 0.18288)
		(layer "In6.Cu")
		(net "M_G_CPU1_SA_DQS_DP<4>")
	)
	(segment
		(start 182.170578 -272.932144)
		(end 181.80431 -272.565876)
		(width 0.18288)
		(layer "In6.Cu")
		(net "M_G_CPU1_SA_DQS_DP<4>")
	)
	(segment
		(start 184.854596 -273.932142)
		(end 184.061862 -273.932142)
		(width 0.18288)
		(layer "In6.Cu")
		(net "M_G_CPU1_SA_DQS_DP<4>")
	)
	(segment
		(start 181.80431 -272.565876)
		(end 181.80431 -267.82776)
		(width 0.18288)
		(layer "In6.Cu")
		(net "M_G_CPU1_SA_DQS_DP<4>")
	)
	(segment
		(start 180.391308 -266.414758)
		(end 180.006752 -266.414758)
		(width 0.18288)
		(layer "In6.Cu")
		(net "M_G_CPU1_SA_DQS_DP<4>")
	)
	(segment
		(start 172.566838 -265.740896)
		(end 172.285152 -265.45921)
		(width 0.18288)
		(layer "In6.Cu")
		(net "M_G_CPU1_SA_DQS_DP<4>")
	)
	(segment
		(start 142.808706 -262.652256)
		(end 140.595604 -262.652256)
		(width 0.18288)
		(layer "In6.Cu")
		(net "M_G_CPU1_SA_DQS_DP<4>")
	)
	(segment
		(start 139.192 -263.361678)
		(end 139.191492 -263.362186)
		(width 0.088646)
		(layer "In6.Cu")
		(net "M_G_CPU1_SA_DQS_DP<4>")
	)
	(segment
		(start 127.928878 -263.370822)
		(end 127.914146 -263.362186)
		(width 0.088646)
		(layer "In6.Cu")
		(net "M_G_CPU1_SA_DQS_DP<4>")
	)
	(segment
		(start 134.50316 -263.368282)
		(end 134.492746 -263.362186)
		(width 0.088646)
		(layer "In6.Cu")
		(net "M_G_CPU1_SA_DQS_DP<4>")
	)
	(segment
		(start 164.391086 -265.340846)
		(end 160.782 -265.340846)
		(width 0.18288)
		(layer "In6.Cu")
		(net "M_G_CPU1_SA_DQS_DP<4>")
	)
	(segment
		(start 126.6952 -262.938006)
		(end 126.629668 -262.872474)
		(width 0.088646)
		(layer "In6.Cu")
		(net "M_G_CPU1_SA_DQS_DP<4>")
	)
	(segment
		(start 135.997696 -263.362186)
		(end 135.997188 -263.361678)
		(width 0.088646)
		(layer "In6.Cu")
		(net "M_G_CPU1_SA_DQS_DP<4>")
	)
	(segment
		(start 187.593732 -275.22805)
		(end 187.090304 -275.22805)
		(width 0.18288)
		(layer "In6.Cu")
		(net "M_G_CPU1_SA_DQS_DP<4>")
	)
	(segment
		(start 128.86436 -263.368282)
		(end 128.853946 -263.362186)
		(width 0.088646)
		(layer "In6.Cu")
		(net "M_G_CPU1_SA_DQS_DP<4>")
	)
	(segment
		(start 174.769526 -266.330176)
		(end 173.88967 -265.45032)
		(width 0.18288)
		(layer "In6.Cu")
		(net "M_G_CPU1_SA_DQS_DP<4>")
	)
	(segment
		(start 177.1142 -266.59078)
		(end 176.642268 -266.59078)
		(width 0.18288)
		(layer "In6.Cu")
		(net "M_G_CPU1_SA_DQS_DP<4>")
	)
	(segment
		(start 167.383968 -264.65276)
		(end 165.079172 -264.65276)
		(width 0.18288)
		(layer "In6.Cu")
		(net "M_G_CPU1_SA_DQS_DP<4>")
	)
	(segment
		(start 173.020736 -265.740896)
		(end 172.566838 -265.740896)
		(width 0.18288)
		(layer "In6.Cu")
		(net "M_G_CPU1_SA_DQS_DP<4>")
	)
	(segment
		(start 155.776168 -263.136126)
		(end 145.240502 -263.136126)
		(width 0.18288)
		(layer "In6.Cu")
		(net "M_G_CPU1_SA_DQS_DP<4>")
	)
	(segment
		(start 126.629668 -262.872474)
		(end 126.316994 -262.872474)
		(width 0.088646)
		(layer "In6.Cu")
		(net "M_G_CPU1_SA_DQS_DP<4>")
	)
	(segment
		(start 183.061864 -272.932144)
		(end 182.170578 -272.932144)
		(width 0.18288)
		(layer "In6.Cu")
		(net "M_G_CPU1_SA_DQS_DP<4>")
	)
	(segment
		(start 130.748278 -263.370822)
		(end 130.733546 -263.362186)
		(width 0.088646)
		(layer "In6.Cu")
		(net "M_G_CPU1_SA_DQS_DP<4>")
	)
	(segment
		(start 185.897012 -274.974558)
		(end 184.854596 -273.932142)
		(width 0.18288)
		(layer "In6.Cu")
		(net "M_G_CPU1_SA_DQS_DP<4>")
	)
	(segment
		(start 140.254228 -262.71474)
		(end 140.125958 -263.024112)
		(width 0.088646)
		(layer "In6.Cu")
		(net "M_G_CPU1_SA_DQS_DP<4>")
	)
	(segment
		(start 177.93589 -266.300204)
		(end 177.404776 -266.300204)
		(width 0.18288)
		(layer "In6.Cu")
		(net "M_G_CPU1_SA_DQS_DP<4>")
	)
	(segment
		(start 135.4328 -263.361678)
		(end 135.432292 -263.362186)
		(width 0.088646)
		(layer "In6.Cu")
		(net "M_G_CPU1_SA_DQS_DP<4>")
	)
	(segment
		(start 187.883546 -275.516594)
		(end 187.593732 -275.22805)
		(width 0.18288)
		(layer "In6.Cu")
		(net "M_G_CPU1_SA_DQS_DP<4>")
	)
	(segment
		(start 169.331132 -265.45921)
		(end 167.383968 -264.65276)
		(width 0.18288)
		(layer "In6.Cu")
		(net "M_G_CPU1_SA_DQS_DP<4>")
	)
	(segment
		(start 173.88967 -265.45032)
		(end 173.311312 -265.45032)
		(width 0.18288)
		(layer "In6.Cu")
		(net "M_G_CPU1_SA_DQS_DP<4>")
	)
	(segment
		(start 140.595604 -262.652256)
		(end 140.572236 -262.652256)
		(width 0.088646)
		(layer "In6.Cu")
		(net "M_G_CPU1_SA_DQS_DP<4>")
	)
	(segment
		(start 140.376656 -262.592312)
		(end 140.254228 -262.71474)
		(width 0.088646)
		(layer "In6.Cu")
		(net "M_G_CPU1_SA_DQS_DP<4>")
	)
	(segment
		(start 181.80431 -267.82776)
		(end 180.391308 -266.414758)
		(width 0.18288)
		(layer "In6.Cu")
		(net "M_G_CPU1_SA_DQS_DP<4>")
	)
	(segment
		(start 140.572236 -262.652256)
		(end 140.512292 -262.592312)
		(width 0.088646)
		(layer "In6.Cu")
		(net "M_G_CPU1_SA_DQS_DP<4>")
	)
	(segment
		(start 177.404776 -266.300204)
		(end 177.1142 -266.59078)
		(width 0.18288)
		(layer "In6.Cu")
		(net "M_G_CPU1_SA_DQS_DP<4>")
	)
	(segment
		(start 187.090304 -275.22805)
		(end 186.836812 -274.974558)
		(width 0.18288)
		(layer "In6.Cu")
		(net "M_G_CPU1_SA_DQS_DP<4>")
	)
	(segment
		(start 160.782 -265.340846)
		(end 160.04667 -264.605516)
		(width 0.18288)
		(layer "In6.Cu")
		(net "M_G_CPU1_SA_DQS_DP<4>")
	)
	(segment
		(start 173.311312 -265.45032)
		(end 173.020736 -265.740896)
		(width 0.18288)
		(layer "In6.Cu")
		(net "M_G_CPU1_SA_DQS_DP<4>")
	)
	(segment
		(start 157.245558 -264.605516)
		(end 155.776168 -263.136126)
		(width 0.18288)
		(layer "In6.Cu")
		(net "M_G_CPU1_SA_DQS_DP<4>")
	)
	(segment
		(start 186.836812 -274.974558)
		(end 185.897012 -274.974558)
		(width 0.18288)
		(layer "In6.Cu")
		(net "M_G_CPU1_SA_DQS_DP<4>")
	)
	(segment
		(start 176.381664 -266.330176)
		(end 174.769526 -266.330176)
		(width 0.18288)
		(layer "In6.Cu")
		(net "M_G_CPU1_SA_DQS_DP<4>")
	)
	(segment
		(start 132.627878 -263.370822)
		(end 132.613146 -263.362186)
		(width 0.088646)
		(layer "In6.Cu")
		(net "M_G_CPU1_SA_DQS_DP<4>")
	)
	(segment
		(start 133.567678 -263.370822)
		(end 133.552946 -263.362186)
		(width 0.088646)
		(layer "In6.Cu")
		(net "M_G_CPU1_SA_DQS_DP<4>")
	)
	(segment
		(start 180.006752 -266.414758)
		(end 179.498752 -266.922758)
		(width 0.18288)
		(layer "In6.Cu")
		(net "M_G_CPU1_SA_DQS_DP<4>")
	)
	(segment
		(start 140.125958 -263.024112)
		(end 139.896088 -263.253982)
		(width 0.088646)
		(layer "In6.Cu")
		(net "M_G_CPU1_SA_DQS_DP<4>")
	)
	(segment
		(start 172.285152 -265.45921)
		(end 169.331132 -265.45921)
		(width 0.18288)
		(layer "In6.Cu")
		(net "M_G_CPU1_SA_DQS_DP<4>")
	)
	(segment
		(start 165.079172 -264.65276)
		(end 164.391086 -265.340846)
		(width 0.18288)
		(layer "In6.Cu")
		(net "M_G_CPU1_SA_DQS_DP<4>")
	)
	(segment
		(start 145.240502 -263.136126)
		(end 142.808706 -262.652256)
		(width 0.18288)
		(layer "In6.Cu")
		(net "M_G_CPU1_SA_DQS_DP<4>")
	)
	(segment
		(start 129.803906 -263.368282)
		(end 129.793492 -263.362186)
		(width 0.088646)
		(layer "In6.Cu")
		(net "M_G_CPU1_SA_DQS_DP<4>")
	)
	(segment
		(start 178.558444 -266.922758)
		(end 177.93589 -266.300204)
		(width 0.18288)
		(layer "In6.Cu")
		(net "M_G_CPU1_SA_DQS_DP<4>")
	)
	(segment
		(start 140.512292 -262.592312)
		(end 140.376656 -262.592312)
		(width 0.088646)
		(layer "In6.Cu")
		(net "M_G_CPU1_SA_DQS_DP<4>")
	)
	(segment
		(start 184.061862 -273.932142)
		(end 183.061864 -272.932144)
		(width 0.18288)
		(layer "In6.Cu")
		(net "M_G_CPU1_SA_DQS_DP<4>")
	)
	(arc
		(start 138.802364 -263.370822)
		(mid 138.525923 -263.437988)
		(end 138.251692 -263.362186)
		(width 0.088646)
		(layer "In6.Cu")
		(net "M_G_CPU1_SA_DQS_DP<4>")
	)
	(arc
		(start 128.853946 -263.362186)
		(mid 128.666748 -263.312043)
		(end 128.47955 -263.362186)
		(width 0.088646)
		(layer "In6.Cu")
		(net "M_G_CPU1_SA_DQS_DP<4>")
	)
	(arc
		(start 136.372092 -263.362186)
		(mid 136.184894 -263.312043)
		(end 135.997696 -263.362186)
		(width 0.088646)
		(layer "In6.Cu")
		(net "M_G_CPU1_SA_DQS_DP<4>")
	)
	(arc
		(start 129.419096 -263.362186)
		(mid 129.142537 -263.437895)
		(end 128.86436 -263.368282)
		(width 0.088646)
		(layer "In6.Cu")
		(net "M_G_CPU1_SA_DQS_DP<4>")
	)
	(arc
		(start 133.17855 -263.362186)
		(mid 132.904321 -263.438111)
		(end 132.627878 -263.370822)
		(width 0.088646)
		(layer "In6.Cu")
		(net "M_G_CPU1_SA_DQS_DP<4>")
	)
	(arc
		(start 131.673346 -263.362186)
		(mid 131.486148 -263.312043)
		(end 131.29895 -263.362186)
		(width 0.088646)
		(layer "In6.Cu")
		(net "M_G_CPU1_SA_DQS_DP<4>")
	)
	(arc
		(start 134.11835 -263.362186)
		(mid 133.844121 -263.438111)
		(end 133.567678 -263.370822)
		(width 0.088646)
		(layer "In6.Cu")
		(net "M_G_CPU1_SA_DQS_DP<4>")
	)
	(arc
		(start 127.914146 -263.362186)
		(mid 127.726948 -263.312043)
		(end 127.53975 -263.362186)
		(width 0.088646)
		(layer "In6.Cu")
		(net "M_G_CPU1_SA_DQS_DP<4>")
	)
	(arc
		(start 135.057896 -263.362186)
		(mid 134.781337 -263.437895)
		(end 134.50316 -263.368282)
		(width 0.088646)
		(layer "In6.Cu")
		(net "M_G_CPU1_SA_DQS_DP<4>")
	)
	(arc
		(start 132.23875 -263.362186)
		(mid 131.956048 -263.437928)
		(end 131.673346 -263.362186)
		(width 0.088646)
		(layer "In6.Cu")
		(net "M_G_CPU1_SA_DQS_DP<4>")
	)
	(arc
		(start 131.29895 -263.362186)
		(mid 131.024721 -263.438111)
		(end 130.748278 -263.370822)
		(width 0.088646)
		(layer "In6.Cu")
		(net "M_G_CPU1_SA_DQS_DP<4>")
	)
	(arc
		(start 130.35915 -263.362186)
		(mid 130.082337 -263.438022)
		(end 129.803906 -263.368282)
		(width 0.088646)
		(layer "In6.Cu")
		(net "M_G_CPU1_SA_DQS_DP<4>")
	)
	(arc
		(start 137.311892 -263.362186)
		(mid 137.124694 -263.312043)
		(end 136.937496 -263.362186)
		(width 0.088646)
		(layer "In6.Cu")
		(net "M_G_CPU1_SA_DQS_DP<4>")
	)
	(arc
		(start 127.53975 -263.362186)
		(mid 127.012548 -263.382598)
		(end 126.697994 -262.959088)
		(width 0.088646)
		(layer "In6.Cu")
		(net "M_G_CPU1_SA_DQS_DP<4>")
	)
	(arc
		(start 136.937496 -263.362186)
		(mid 136.654794 -263.437928)
		(end 136.372092 -263.362186)
		(width 0.088646)
		(layer "In6.Cu")
		(net "M_G_CPU1_SA_DQS_DP<4>")
	)
	(arc
		(start 138.251692 -263.362186)
		(mid 138.064494 -263.312043)
		(end 137.877296 -263.362186)
		(width 0.088646)
		(layer "In6.Cu")
		(net "M_G_CPU1_SA_DQS_DP<4>")
	)
	(arc
		(start 126.697994 -262.959088)
		(mid 126.696498 -262.94856)
		(end 126.6952 -262.938006)
		(width 0.088646)
		(layer "In6.Cu")
		(net "M_G_CPU1_SA_DQS_DP<4>")
	)
	(arc
		(start 133.552946 -263.362186)
		(mid 133.365748 -263.312043)
		(end 133.17855 -263.362186)
		(width 0.088646)
		(layer "In6.Cu")
		(net "M_G_CPU1_SA_DQS_DP<4>")
	)
	(arc
		(start 135.997188 -263.361678)
		(mid 135.714994 -263.437234)
		(end 135.4328 -263.361678)
		(width 0.088646)
		(layer "In6.Cu")
		(net "M_G_CPU1_SA_DQS_DP<4>")
	)
	(arc
		(start 137.877296 -263.362186)
		(mid 137.594594 -263.437928)
		(end 137.311892 -263.362186)
		(width 0.088646)
		(layer "In6.Cu")
		(net "M_G_CPU1_SA_DQS_DP<4>")
	)
	(arc
		(start 139.896088 -263.253982)
		(mid 139.841979 -263.302795)
		(end 139.783058 -263.345676)
		(width 0.088646)
		(layer "In6.Cu")
		(net "M_G_CPU1_SA_DQS_DP<4>")
	)
	(arc
		(start 132.613146 -263.362186)
		(mid 132.425948 -263.312043)
		(end 132.23875 -263.362186)
		(width 0.088646)
		(layer "In6.Cu")
		(net "M_G_CPU1_SA_DQS_DP<4>")
	)
	(arc
		(start 139.191492 -263.362186)
		(mid 139.004294 -263.312043)
		(end 138.817096 -263.362186)
		(width 0.088646)
		(layer "In6.Cu")
		(net "M_G_CPU1_SA_DQS_DP<4>")
	)
	(arc
		(start 135.432292 -263.362186)
		(mid 135.245094 -263.312043)
		(end 135.057896 -263.362186)
		(width 0.088646)
		(layer "In6.Cu")
		(net "M_G_CPU1_SA_DQS_DP<4>")
	)
	(arc
		(start 128.47955 -263.362186)
		(mid 128.205321 -263.438111)
		(end 127.928878 -263.370822)
		(width 0.088646)
		(layer "In6.Cu")
		(net "M_G_CPU1_SA_DQS_DP<4>")
	)
	(arc
		(start 129.793492 -263.362186)
		(mid 129.606294 -263.312043)
		(end 129.419096 -263.362186)
		(width 0.088646)
		(layer "In6.Cu")
		(net "M_G_CPU1_SA_DQS_DP<4>")
	)
	(arc
		(start 134.492746 -263.362186)
		(mid 134.305548 -263.312043)
		(end 134.11835 -263.362186)
		(width 0.088646)
		(layer "In6.Cu")
		(net "M_G_CPU1_SA_DQS_DP<4>")
	)
	(arc
		(start 130.733546 -263.362186)
		(mid 130.546348 -263.312043)
		(end 130.35915 -263.362186)
		(width 0.088646)
		(layer "In6.Cu")
		(net "M_G_CPU1_SA_DQS_DP<4>")
	)
	(arc
		(start 139.783058 -263.345676)
		(mid 139.770211 -263.35385)
		(end 139.75715 -263.361678)
		(width 0.088646)
		(layer "In6.Cu")
		(net "M_G_CPU1_SA_DQS_DP<4>")
	)
	(arc
		(start 139.75715 -263.361678)
		(mid 139.474702 -263.437361)
		(end 139.192254 -263.361678)
		(width 0.088646)
		(layer "In6.Cu")
		(net "M_G_CPU1_SA_DQS_DP<4>")
	)
	(segment
		(start 191.9097 -285.291784)
		(end 191.935608 -285.291784)
		(width 0.101854)
		(layer "F.Cu")
		(net "M_G_CPU1_SA_DQS_DP<3>")
	)
	(segment
		(start 188.988446 -284.866588)
		(end 189.577726 -284.866588)
		(width 0.20066)
		(layer "F.Cu")
		(net "M_G_CPU1_SA_DQS_DP<3>")
	)
	(segment
		(start 194.422268 -285.29788)
		(end 194.724782 -284.995366)
		(width 0.20066)
		(layer "F.Cu")
		(net "M_G_CPU1_SA_DQS_DP<3>")
	)
	(segment
		(start 191.770254 -285.291784)
		(end 191.9097 -285.291784)
		(width 0.20066)
		(layer "F.Cu")
		(net "M_G_CPU1_SA_DQS_DP<3>")
	)
	(segment
		(start 126.317248 -267.219938)
		(end 126.316994 -267.220192)
		(width 0.20066)
		(layer "F.Cu")
		(net "M_G_CPU1_SA_DQS_DP<3>")
	)
	(segment
		(start 195.70192 -284.584902)
		(end 195.983606 -284.866588)
		(width 0.20066)
		(layer "F.Cu")
		(net "M_G_CPU1_SA_DQS_DP<3>")
	)
	(segment
		(start 195.095368 -284.995366)
		(end 195.505832 -284.584902)
		(width 0.20066)
		(layer "F.Cu")
		(net "M_G_CPU1_SA_DQS_DP<3>")
	)
	(segment
		(start 191.519048 -285.040578)
		(end 191.770254 -285.291784)
		(width 0.20066)
		(layer "F.Cu")
		(net "M_G_CPU1_SA_DQS_DP<3>")
	)
	(segment
		(start 195.983606 -284.866588)
		(end 196.532246 -284.866588)
		(width 0.20066)
		(layer "F.Cu")
		(net "M_G_CPU1_SA_DQS_DP<3>")
	)
	(segment
		(start 189.818264 -284.62605)
		(end 190.41872 -284.62605)
		(width 0.20066)
		(layer "F.Cu")
		(net "M_G_CPU1_SA_DQS_DP<3>")
	)
	(segment
		(start 194.09283 -285.291784)
		(end 194.098926 -285.29788)
		(width 0.1016)
		(layer "F.Cu")
		(net "M_G_CPU1_SA_DQS_DP<3>")
	)
	(segment
		(start 194.098926 -285.29788)
		(end 194.422268 -285.29788)
		(width 0.20066)
		(layer "F.Cu")
		(net "M_G_CPU1_SA_DQS_DP<3>")
	)
	(segment
		(start 195.505832 -284.584902)
		(end 195.70192 -284.584902)
		(width 0.20066)
		(layer "F.Cu")
		(net "M_G_CPU1_SA_DQS_DP<3>")
	)
	(segment
		(start 187.883546 -284.866588)
		(end 188.988446 -284.866588)
		(width 0.20066)
		(layer "F.Cu")
		(net "M_G_CPU1_SA_DQS_DP<3>")
	)
	(segment
		(start 190.833248 -285.040578)
		(end 191.519048 -285.040578)
		(width 0.20066)
		(layer "F.Cu")
		(net "M_G_CPU1_SA_DQS_DP<3>")
	)
	(segment
		(start 189.577726 -284.866588)
		(end 189.818264 -284.62605)
		(width 0.20066)
		(layer "F.Cu")
		(net "M_G_CPU1_SA_DQS_DP<3>")
	)
	(segment
		(start 126.316994 -267.220192)
		(end 126.316994 -267.755878)
		(width 0.20066)
		(layer "F.Cu")
		(net "M_G_CPU1_SA_DQS_DP<3>")
	)
	(segment
		(start 190.41872 -284.62605)
		(end 190.833248 -285.040578)
		(width 0.20066)
		(layer "F.Cu")
		(net "M_G_CPU1_SA_DQS_DP<3>")
	)
	(segment
		(start 194.724782 -284.995366)
		(end 195.095368 -284.995366)
		(width 0.20066)
		(layer "F.Cu")
		(net "M_G_CPU1_SA_DQS_DP<3>")
	)
	(segment
		(start 191.935608 -285.291784)
		(end 194.09283 -285.291784)
		(width 0.1016)
		(layer "F.Cu")
		(net "M_G_CPU1_SA_DQS_DP<3>")
	)
	(segment
		(start 174.140622 -283.46654)
		(end 174.140622 -280.354532)
		(width 0.18288)
		(layer "In6.Cu")
		(net "M_G_CPU1_SA_DQS_DP<3>")
	)
	(segment
		(start 140.184886 -268.535658)
		(end 139.923774 -268.274546)
		(width 0.088646)
		(layer "In6.Cu")
		(net "M_G_CPU1_SA_DQS_DP<3>")
	)
	(segment
		(start 173.686724 -279.900634)
		(end 173.303184 -279.900634)
		(width 0.18288)
		(layer "In6.Cu")
		(net "M_G_CPU1_SA_DQS_DP<3>")
	)
	(segment
		(start 171.329604 -279.902412)
		(end 169.637456 -278.210264)
		(width 0.18288)
		(layer "In6.Cu")
		(net "M_G_CPU1_SA_DQS_DP<3>")
	)
	(segment
		(start 128.868678 -268.253972)
		(end 128.853946 -268.245336)
		(width 0.088646)
		(layer "In6.Cu")
		(net "M_G_CPU1_SA_DQS_DP<3>")
	)
	(segment
		(start 128.47955 -268.245336)
		(end 128.479296 -268.245336)
		(width 0.088646)
		(layer "In6.Cu")
		(net "M_G_CPU1_SA_DQS_DP<3>")
	)
	(segment
		(start 187.62472 -284.607762)
		(end 187.208668 -284.607762)
		(width 0.18288)
		(layer "In6.Cu")
		(net "M_G_CPU1_SA_DQS_DP<3>")
	)
	(segment
		(start 160.551368 -275.917152)
		(end 157.490414 -275.917152)
		(width 0.18288)
		(layer "In6.Cu")
		(net "M_G_CPU1_SA_DQS_DP<3>")
	)
	(segment
		(start 178.767232 -284.400498)
		(end 178.167284 -285.000446)
		(width 0.18288)
		(layer "In6.Cu")
		(net "M_G_CPU1_SA_DQS_DP<3>")
	)
	(segment
		(start 161.777934 -276.425152)
		(end 160.551368 -275.917152)
		(width 0.18288)
		(layer "In6.Cu")
		(net "M_G_CPU1_SA_DQS_DP<3>")
	)
	(segment
		(start 137.88898 -268.238478)
		(end 137.877042 -268.245336)
		(width 0.088646)
		(layer "In6.Cu")
		(net "M_G_CPU1_SA_DQS_DP<3>")
	)
	(segment
		(start 127.476504 -268.061694)
		(end 127.443992 -268.080236)
		(width 0.088646)
		(layer "In6.Cu")
		(net "M_G_CPU1_SA_DQS_DP<3>")
	)
	(segment
		(start 176.602644 -285.290768)
		(end 176.33696 -285.025084)
		(width 0.18288)
		(layer "In6.Cu")
		(net "M_G_CPU1_SA_DQS_DP<3>")
	)
	(segment
		(start 157.490414 -275.917152)
		(end 150.693374 -269.120112)
		(width 0.18288)
		(layer "In6.Cu")
		(net "M_G_CPU1_SA_DQS_DP<3>")
	)
	(segment
		(start 176.33696 -285.025084)
		(end 175.699166 -285.025084)
		(width 0.18288)
		(layer "In6.Cu")
		(net "M_G_CPU1_SA_DQS_DP<3>")
	)
	(segment
		(start 126.829566 -267.755878)
		(end 126.316994 -267.755878)
		(width 0.088646)
		(layer "In6.Cu")
		(net "M_G_CPU1_SA_DQS_DP<3>")
	)
	(segment
		(start 129.808478 -268.253972)
		(end 129.793746 -268.245336)
		(width 0.088646)
		(layer "In6.Cu")
		(net "M_G_CPU1_SA_DQS_DP<3>")
	)
	(segment
		(start 168.476676 -277.729188)
		(end 167.893746 -277.146766)
		(width 0.18288)
		(layer "In6.Cu")
		(net "M_G_CPU1_SA_DQS_DP<3>")
	)
	(segment
		(start 177.403252 -285.000446)
		(end 177.11293 -285.290768)
		(width 0.18288)
		(layer "In6.Cu")
		(net "M_G_CPU1_SA_DQS_DP<3>")
	)
	(segment
		(start 139.923774 -268.274546)
		(end 139.745466 -268.251432)
		(width 0.088646)
		(layer "In6.Cu")
		(net "M_G_CPU1_SA_DQS_DP<3>")
	)
	(segment
		(start 187.001404 -284.400498)
		(end 178.767232 -284.400498)
		(width 0.18288)
		(layer "In6.Cu")
		(net "M_G_CPU1_SA_DQS_DP<3>")
	)
	(segment
		(start 137.877042 -268.245336)
		(end 137.86231 -268.253972)
		(width 0.088646)
		(layer "In6.Cu")
		(net "M_G_CPU1_SA_DQS_DP<3>")
	)
	(segment
		(start 140.595604 -268.595602)
		(end 140.572236 -268.595602)
		(width 0.088646)
		(layer "In6.Cu")
		(net "M_G_CPU1_SA_DQS_DP<3>")
	)
	(segment
		(start 127.678434 -268.085316)
		(end 127.657606 -268.070584)
		(width 0.088646)
		(layer "In6.Cu")
		(net "M_G_CPU1_SA_DQS_DP<3>")
	)
	(segment
		(start 172.214032 -279.902412)
		(end 171.329604 -279.902412)
		(width 0.18288)
		(layer "In6.Cu")
		(net "M_G_CPU1_SA_DQS_DP<3>")
	)
	(segment
		(start 126.886716 -267.813028)
		(end 126.829566 -267.755878)
		(width 0.088646)
		(layer "In6.Cu")
		(net "M_G_CPU1_SA_DQS_DP<3>")
	)
	(segment
		(start 134.507478 -268.253972)
		(end 134.492746 -268.245336)
		(width 0.088646)
		(layer "In6.Cu")
		(net "M_G_CPU1_SA_DQS_DP<3>")
	)
	(segment
		(start 163.89604 -276.425152)
		(end 161.777934 -276.425152)
		(width 0.18288)
		(layer "In6.Cu")
		(net "M_G_CPU1_SA_DQS_DP<3>")
	)
	(segment
		(start 187.883546 -284.866588)
		(end 187.62472 -284.607762)
		(width 0.18288)
		(layer "In6.Cu")
		(net "M_G_CPU1_SA_DQS_DP<3>")
	)
	(segment
		(start 172.502576 -280.190956)
		(end 172.214032 -279.902412)
		(width 0.18288)
		(layer "In6.Cu")
		(net "M_G_CPU1_SA_DQS_DP<3>")
	)
	(segment
		(start 177.11293 -285.290768)
		(end 176.602644 -285.290768)
		(width 0.18288)
		(layer "In6.Cu")
		(net "M_G_CPU1_SA_DQS_DP<3>")
	)
	(segment
		(start 130.748278 -268.253972)
		(end 130.733546 -268.245336)
		(width 0.088646)
		(layer "In6.Cu")
		(net "M_G_CPU1_SA_DQS_DP<3>")
	)
	(segment
		(start 175.699166 -285.025084)
		(end 174.140622 -283.46654)
		(width 0.18288)
		(layer "In6.Cu")
		(net "M_G_CPU1_SA_DQS_DP<3>")
	)
	(segment
		(start 127.069596 -268.080236)
		(end 127.068072 -268.079474)
		(width 0.088646)
		(layer "In6.Cu")
		(net "M_G_CPU1_SA_DQS_DP<3>")
	)
	(segment
		(start 187.208668 -284.607762)
		(end 187.001404 -284.400498)
		(width 0.18288)
		(layer "In6.Cu")
		(net "M_G_CPU1_SA_DQS_DP<3>")
	)
	(segment
		(start 173.012862 -280.190956)
		(end 172.502576 -280.190956)
		(width 0.18288)
		(layer "In6.Cu")
		(net "M_G_CPU1_SA_DQS_DP<3>")
	)
	(segment
		(start 142.183358 -268.595602)
		(end 140.595604 -268.595602)
		(width 0.18288)
		(layer "In6.Cu")
		(net "M_G_CPU1_SA_DQS_DP<3>")
	)
	(segment
		(start 136.937242 -268.245336)
		(end 136.926828 -268.251432)
		(width 0.088646)
		(layer "In6.Cu")
		(net "M_G_CPU1_SA_DQS_DP<3>")
	)
	(segment
		(start 127.686816 -268.087602)
		(end 127.678434 -268.085316)
		(width 0.088646)
		(layer "In6.Cu")
		(net "M_G_CPU1_SA_DQS_DP<3>")
	)
	(segment
		(start 140.572236 -268.595602)
		(end 140.512292 -268.535658)
		(width 0.088646)
		(layer "In6.Cu")
		(net "M_G_CPU1_SA_DQS_DP<3>")
	)
	(segment
		(start 138.82497 -268.24051)
		(end 138.798554 -268.25575)
		(width 0.088646)
		(layer "In6.Cu")
		(net "M_G_CPU1_SA_DQS_DP<3>")
	)
	(segment
		(start 127.657606 -268.070584)
		(end 127.476504 -268.061694)
		(width 0.088646)
		(layer "In6.Cu")
		(net "M_G_CPU1_SA_DQS_DP<3>")
	)
	(segment
		(start 127.068072 -268.079474)
		(end 127.060706 -268.075156)
		(width 0.088646)
		(layer "In6.Cu")
		(net "M_G_CPU1_SA_DQS_DP<3>")
	)
	(segment
		(start 173.303184 -279.900634)
		(end 173.012862 -280.190956)
		(width 0.18288)
		(layer "In6.Cu")
		(net "M_G_CPU1_SA_DQS_DP<3>")
	)
	(segment
		(start 133.567678 -268.253972)
		(end 133.552946 -268.245336)
		(width 0.088646)
		(layer "In6.Cu")
		(net "M_G_CPU1_SA_DQS_DP<3>")
	)
	(segment
		(start 178.167284 -285.000446)
		(end 177.403252 -285.000446)
		(width 0.18288)
		(layer "In6.Cu")
		(net "M_G_CPU1_SA_DQS_DP<3>")
	)
	(segment
		(start 135.44296 -268.251432)
		(end 135.432546 -268.245336)
		(width 0.088646)
		(layer "In6.Cu")
		(net "M_G_CPU1_SA_DQS_DP<3>")
	)
	(segment
		(start 167.893746 -277.146766)
		(end 164.617654 -277.146766)
		(width 0.18288)
		(layer "In6.Cu")
		(net "M_G_CPU1_SA_DQS_DP<3>")
	)
	(segment
		(start 164.617654 -277.146766)
		(end 163.89604 -276.425152)
		(width 0.18288)
		(layer "In6.Cu")
		(net "M_G_CPU1_SA_DQS_DP<3>")
	)
	(segment
		(start 174.140622 -280.354532)
		(end 173.686724 -279.900634)
		(width 0.18288)
		(layer "In6.Cu")
		(net "M_G_CPU1_SA_DQS_DP<3>")
	)
	(segment
		(start 150.693374 -269.120112)
		(end 144.819116 -269.120112)
		(width 0.18288)
		(layer "In6.Cu")
		(net "M_G_CPU1_SA_DQS_DP<3>")
	)
	(segment
		(start 127.87122 -268.21765)
		(end 127.686816 -268.087602)
		(width 0.088646)
		(layer "In6.Cu")
		(net "M_G_CPU1_SA_DQS_DP<3>")
	)
	(segment
		(start 132.627878 -268.253972)
		(end 132.613146 -268.245336)
		(width 0.088646)
		(layer "In6.Cu")
		(net "M_G_CPU1_SA_DQS_DP<3>")
	)
	(segment
		(start 144.819116 -269.120112)
		(end 142.183358 -268.595602)
		(width 0.18288)
		(layer "In6.Cu")
		(net "M_G_CPU1_SA_DQS_DP<3>")
	)
	(segment
		(start 140.512292 -268.535658)
		(end 140.184886 -268.535658)
		(width 0.088646)
		(layer "In6.Cu")
		(net "M_G_CPU1_SA_DQS_DP<3>")
	)
	(segment
		(start 169.637456 -278.210264)
		(end 168.476676 -277.729188)
		(width 0.18288)
		(layer "In6.Cu")
		(net "M_G_CPU1_SA_DQS_DP<3>")
	)
	(arc
		(start 128.479296 -268.245336)
		(mid 128.1712 -268.32047)
		(end 127.87122 -268.21765)
		(width 0.088646)
		(layer "In6.Cu")
		(net "M_G_CPU1_SA_DQS_DP<3>")
	)
	(arc
		(start 131.29895 -268.245336)
		(mid 131.024751 -268.321171)
		(end 130.748278 -268.253972)
		(width 0.088646)
		(layer "In6.Cu")
		(net "M_G_CPU1_SA_DQS_DP<3>")
	)
	(arc
		(start 135.05815 -268.245336)
		(mid 134.783951 -268.321171)
		(end 134.507478 -268.253972)
		(width 0.088646)
		(layer "In6.Cu")
		(net "M_G_CPU1_SA_DQS_DP<3>")
	)
	(arc
		(start 130.35915 -268.245336)
		(mid 130.084951 -268.321171)
		(end 129.808478 -268.253972)
		(width 0.088646)
		(layer "In6.Cu")
		(net "M_G_CPU1_SA_DQS_DP<3>")
	)
	(arc
		(start 134.11835 -268.245336)
		(mid 133.844151 -268.321171)
		(end 133.567678 -268.253972)
		(width 0.088646)
		(layer "In6.Cu")
		(net "M_G_CPU1_SA_DQS_DP<3>")
	)
	(arc
		(start 127.443992 -268.080236)
		(mid 127.256794 -268.130379)
		(end 127.069596 -268.080236)
		(width 0.088646)
		(layer "In6.Cu")
		(net "M_G_CPU1_SA_DQS_DP<3>")
	)
	(arc
		(start 133.552946 -268.245336)
		(mid 133.365748 -268.195193)
		(end 133.17855 -268.245336)
		(width 0.088646)
		(layer "In6.Cu")
		(net "M_G_CPU1_SA_DQS_DP<3>")
	)
	(arc
		(start 129.41935 -268.245336)
		(mid 129.145151 -268.321171)
		(end 128.868678 -268.253972)
		(width 0.088646)
		(layer "In6.Cu")
		(net "M_G_CPU1_SA_DQS_DP<3>")
	)
	(arc
		(start 139.745466 -268.251432)
		(mid 139.467288 -268.321155)
		(end 139.19073 -268.245336)
		(width 0.088646)
		(layer "In6.Cu")
		(net "M_G_CPU1_SA_DQS_DP<3>")
	)
	(arc
		(start 137.86231 -268.253972)
		(mid 137.585835 -268.321292)
		(end 137.311638 -268.245336)
		(width 0.088646)
		(layer "In6.Cu")
		(net "M_G_CPU1_SA_DQS_DP<3>")
	)
	(arc
		(start 127.060706 -268.075156)
		(mid 126.944897 -267.963227)
		(end 126.886716 -267.813028)
		(width 0.088646)
		(layer "In6.Cu")
		(net "M_G_CPU1_SA_DQS_DP<3>")
	)
	(arc
		(start 135.432546 -268.245336)
		(mid 135.245348 -268.195193)
		(end 135.05815 -268.245336)
		(width 0.088646)
		(layer "In6.Cu")
		(net "M_G_CPU1_SA_DQS_DP<3>")
	)
	(arc
		(start 128.512316 -268.228572)
		(mid 128.495726 -268.236549)
		(end 128.47955 -268.245336)
		(width 0.088646)
		(layer "In6.Cu")
		(net "M_G_CPU1_SA_DQS_DP<3>")
	)
	(arc
		(start 132.23875 -268.245336)
		(mid 131.956048 -268.321112)
		(end 131.673346 -268.245336)
		(width 0.088646)
		(layer "In6.Cu")
		(net "M_G_CPU1_SA_DQS_DP<3>")
	)
	(arc
		(start 134.492746 -268.245336)
		(mid 134.305548 -268.195193)
		(end 134.11835 -268.245336)
		(width 0.088646)
		(layer "In6.Cu")
		(net "M_G_CPU1_SA_DQS_DP<3>")
	)
	(arc
		(start 132.613146 -268.245336)
		(mid 132.425948 -268.195193)
		(end 132.23875 -268.245336)
		(width 0.088646)
		(layer "In6.Cu")
		(net "M_G_CPU1_SA_DQS_DP<3>")
	)
	(arc
		(start 131.673346 -268.245336)
		(mid 131.486148 -268.195193)
		(end 131.29895 -268.245336)
		(width 0.088646)
		(layer "In6.Cu")
		(net "M_G_CPU1_SA_DQS_DP<3>")
	)
	(arc
		(start 137.311638 -268.245336)
		(mid 137.12444 -268.195193)
		(end 136.937242 -268.245336)
		(width 0.088646)
		(layer "In6.Cu")
		(net "M_G_CPU1_SA_DQS_DP<3>")
	)
	(arc
		(start 139.19073 -268.245336)
		(mid 139.008479 -268.195225)
		(end 138.82497 -268.24051)
		(width 0.088646)
		(layer "In6.Cu")
		(net "M_G_CPU1_SA_DQS_DP<3>")
	)
	(arc
		(start 135.997696 -268.245336)
		(mid 135.721137 -268.321079)
		(end 135.44296 -268.251432)
		(width 0.088646)
		(layer "In6.Cu")
		(net "M_G_CPU1_SA_DQS_DP<3>")
	)
	(arc
		(start 136.926828 -268.251432)
		(mid 136.64865 -268.321155)
		(end 136.372092 -268.245336)
		(width 0.088646)
		(layer "In6.Cu")
		(net "M_G_CPU1_SA_DQS_DP<3>")
	)
	(arc
		(start 130.733546 -268.245336)
		(mid 130.546348 -268.195193)
		(end 130.35915 -268.245336)
		(width 0.088646)
		(layer "In6.Cu")
		(net "M_G_CPU1_SA_DQS_DP<3>")
	)
	(arc
		(start 138.798554 -268.25575)
		(mid 138.52365 -268.321154)
		(end 138.251438 -268.245336)
		(width 0.088646)
		(layer "In6.Cu")
		(net "M_G_CPU1_SA_DQS_DP<3>")
	)
	(arc
		(start 128.853946 -268.245336)
		(mid 128.685152 -268.195645)
		(end 128.512316 -268.228572)
		(width 0.088646)
		(layer "In6.Cu")
		(net "M_G_CPU1_SA_DQS_DP<3>")
	)
	(arc
		(start 129.793746 -268.245336)
		(mid 129.606548 -268.195193)
		(end 129.41935 -268.245336)
		(width 0.088646)
		(layer "In6.Cu")
		(net "M_G_CPU1_SA_DQS_DP<3>")
	)
	(arc
		(start 133.17855 -268.245336)
		(mid 132.904351 -268.321171)
		(end 132.627878 -268.253972)
		(width 0.088646)
		(layer "In6.Cu")
		(net "M_G_CPU1_SA_DQS_DP<3>")
	)
	(arc
		(start 138.251438 -268.245336)
		(mid 138.071091 -268.195133)
		(end 137.88898 -268.238478)
		(width 0.088646)
		(layer "In6.Cu")
		(net "M_G_CPU1_SA_DQS_DP<3>")
	)
	(arc
		(start 136.372092 -268.245336)
		(mid 136.184894 -268.195193)
		(end 135.997696 -268.245336)
		(width 0.088646)
		(layer "In6.Cu")
		(net "M_G_CPU1_SA_DQS_DP<3>")
	)
	(segment
		(start 191.935608 -294.641778)
		(end 194.09283 -294.641778)
		(width 0.1016)
		(layer "F.Cu")
		(net "M_G_CPU1_SA_DQS_DP<2>")
	)
	(segment
		(start 130.546094 -264.778236)
		(end 130.546094 -265.313922)
		(width 0.20066)
		(layer "F.Cu")
		(net "M_G_CPU1_SA_DQS_DP<2>")
	)
	(segment
		(start 130.546094 -265.313922)
		(end 130.546348 -265.314176)
		(width 0.20066)
		(layer "F.Cu")
		(net "M_G_CPU1_SA_DQS_DP<2>")
	)
	(segment
		(start 189.577726 -294.216582)
		(end 189.818264 -293.976044)
		(width 0.20066)
		(layer "F.Cu")
		(net "M_G_CPU1_SA_DQS_DP<2>")
	)
	(segment
		(start 195.70192 -293.934896)
		(end 195.983606 -294.216582)
		(width 0.20066)
		(layer "F.Cu")
		(net "M_G_CPU1_SA_DQS_DP<2>")
	)
	(segment
		(start 190.41872 -293.976044)
		(end 190.833248 -294.390572)
		(width 0.20066)
		(layer "F.Cu")
		(net "M_G_CPU1_SA_DQS_DP<2>")
	)
	(segment
		(start 191.9097 -294.641778)
		(end 191.935608 -294.641778)
		(width 0.101854)
		(layer "F.Cu")
		(net "M_G_CPU1_SA_DQS_DP<2>")
	)
	(segment
		(start 194.422268 -294.647874)
		(end 194.724782 -294.34536)
		(width 0.20066)
		(layer "F.Cu")
		(net "M_G_CPU1_SA_DQS_DP<2>")
	)
	(segment
		(start 190.833248 -294.390572)
		(end 191.519048 -294.390572)
		(width 0.20066)
		(layer "F.Cu")
		(net "M_G_CPU1_SA_DQS_DP<2>")
	)
	(segment
		(start 189.818264 -293.976044)
		(end 190.41872 -293.976044)
		(width 0.20066)
		(layer "F.Cu")
		(net "M_G_CPU1_SA_DQS_DP<2>")
	)
	(segment
		(start 187.883546 -294.216582)
		(end 188.988446 -294.216582)
		(width 0.20066)
		(layer "F.Cu")
		(net "M_G_CPU1_SA_DQS_DP<2>")
	)
	(segment
		(start 194.09283 -294.641778)
		(end 194.098926 -294.647874)
		(width 0.1016)
		(layer "F.Cu")
		(net "M_G_CPU1_SA_DQS_DP<2>")
	)
	(segment
		(start 191.519048 -294.390572)
		(end 191.770254 -294.641778)
		(width 0.20066)
		(layer "F.Cu")
		(net "M_G_CPU1_SA_DQS_DP<2>")
	)
	(segment
		(start 195.983606 -294.216582)
		(end 196.532246 -294.216582)
		(width 0.20066)
		(layer "F.Cu")
		(net "M_G_CPU1_SA_DQS_DP<2>")
	)
	(segment
		(start 191.770254 -294.641778)
		(end 191.9097 -294.641778)
		(width 0.20066)
		(layer "F.Cu")
		(net "M_G_CPU1_SA_DQS_DP<2>")
	)
	(segment
		(start 195.505832 -293.934896)
		(end 195.70192 -293.934896)
		(width 0.20066)
		(layer "F.Cu")
		(net "M_G_CPU1_SA_DQS_DP<2>")
	)
	(segment
		(start 188.988446 -294.216582)
		(end 189.577726 -294.216582)
		(width 0.20066)
		(layer "F.Cu")
		(net "M_G_CPU1_SA_DQS_DP<2>")
	)
	(segment
		(start 194.724782 -294.34536)
		(end 195.095368 -294.34536)
		(width 0.20066)
		(layer "F.Cu")
		(net "M_G_CPU1_SA_DQS_DP<2>")
	)
	(segment
		(start 195.095368 -294.34536)
		(end 195.505832 -293.934896)
		(width 0.20066)
		(layer "F.Cu")
		(net "M_G_CPU1_SA_DQS_DP<2>")
	)
	(segment
		(start 194.098926 -294.647874)
		(end 194.422268 -294.647874)
		(width 0.20066)
		(layer "F.Cu")
		(net "M_G_CPU1_SA_DQS_DP<2>")
	)
	(segment
		(start 179.914296 -293.562278)
		(end 179.368196 -293.562278)
		(width 0.18288)
		(layer "In4.Cu")
		(net "M_G_CPU1_SA_DQS_DP<2>")
	)
	(segment
		(start 164.253672 -289.333686)
		(end 164.09543 -289.333686)
		(width 0.18288)
		(layer "In4.Cu")
		(net "M_G_CPU1_SA_DQS_DP<2>")
	)
	(segment
		(start 181.379876 -293.437818)
		(end 181.255416 -293.562278)
		(width 0.18288)
		(layer "In4.Cu")
		(net "M_G_CPU1_SA_DQS_DP<2>")
	)
	(segment
		(start 172.902626 -295.492678)
		(end 172.900848 -295.4909)
		(width 0.18288)
		(layer "In4.Cu")
		(net "M_G_CPU1_SA_DQS_DP<2>")
	)
	(segment
		(start 131.109466 -265.749786)
		(end 131.07543 -265.70686)
		(width 0.088646)
		(layer "In4.Cu")
		(net "M_G_CPU1_SA_DQS_DP<2>")
	)
	(segment
		(start 172.140372 -295.063926)
		(end 171.420028 -294.920416)
		(width 0.18288)
		(layer "In4.Cu")
		(net "M_G_CPU1_SA_DQS_DP<2>")
	)
	(segment
		(start 157.732984 -283.950918)
		(end 157.166564 -283.950918)
		(width 0.18288)
		(layer "In4.Cu")
		(net "M_G_CPU1_SA_DQS_DP<2>")
	)
	(segment
		(start 131.203192 -265.803888)
		(end 131.109466 -265.749786)
		(width 0.088646)
		(layer "In4.Cu")
		(net "M_G_CPU1_SA_DQS_DP<2>")
	)
	(segment
		(start 130.757676 -265.314176)
		(end 130.546348 -265.314176)
		(width 0.088646)
		(layer "In4.Cu")
		(net "M_G_CPU1_SA_DQS_DP<2>")
	)
	(segment
		(start 163.306252 -288.544508)
		(end 163.306252 -288.277554)
		(width 0.18288)
		(layer "In4.Cu")
		(net "M_G_CPU1_SA_DQS_DP<2>")
	)
	(segment
		(start 183.391556 -293.562278)
		(end 183.267096 -293.437818)
		(width 0.18288)
		(layer "In4.Cu")
		(net "M_G_CPU1_SA_DQS_DP<2>")
	)
	(segment
		(start 183.937656 -293.562278)
		(end 183.391556 -293.562278)
		(width 0.18288)
		(layer "In4.Cu")
		(net "M_G_CPU1_SA_DQS_DP<2>")
	)
	(segment
		(start 175.682656 -294.480488)
		(end 175.136556 -294.480488)
		(width 0.18288)
		(layer "In4.Cu")
		(net "M_G_CPU1_SA_DQS_DP<2>")
	)
	(segment
		(start 182.720996 -293.437818)
		(end 182.596536 -293.562278)
		(width 0.18288)
		(layer "In4.Cu")
		(net "M_G_CPU1_SA_DQS_DP<2>")
	)
	(segment
		(start 166.606728 -291.349176)
		(end 166.220394 -290.962842)
		(width 0.18288)
		(layer "In4.Cu")
		(net "M_G_CPU1_SA_DQS_DP<2>")
	)
	(segment
		(start 131.07543 -265.70686)
		(end 130.760216 -265.312144)
		(width 0.088646)
		(layer "In4.Cu")
		(net "M_G_CPU1_SA_DQS_DP<2>")
	)
	(segment
		(start 173.618906 -295.20261)
		(end 173.297342 -295.20261)
		(width 0.18288)
		(layer "In4.Cu")
		(net "M_G_CPU1_SA_DQS_DP<2>")
	)
	(segment
		(start 170.965622 -294.537384)
		(end 170.965622 -294.13962)
		(width 0.18288)
		(layer "In4.Cu")
		(net "M_G_CPU1_SA_DQS_DP<2>")
	)
	(segment
		(start 178.697636 -293.437818)
		(end 177.777902 -294.357552)
		(width 0.18288)
		(layer "In4.Cu")
		(net "M_G_CPU1_SA_DQS_DP<2>")
	)
	(segment
		(start 172.900848 -295.4909)
		(end 172.650404 -295.4909)
		(width 0.18288)
		(layer "In4.Cu")
		(net "M_G_CPU1_SA_DQS_DP<2>")
	)
	(segment
		(start 136.467596 -265.803888)
		(end 136.452864 -265.812524)
		(width 0.088646)
		(layer "In4.Cu")
		(net "M_G_CPU1_SA_DQS_DP<2>")
	)
	(segment
		(start 156.47162 -283.22397)
		(end 153.826718 -276.969982)
		(width 0.18288)
		(layer "In4.Cu")
		(net "M_G_CPU1_SA_DQS_DP<2>")
	)
	(segment
		(start 161.873946 -286.158432)
		(end 161.281618 -286.158432)
		(width 0.18288)
		(layer "In4.Cu")
		(net "M_G_CPU1_SA_DQS_DP<2>")
	)
	(segment
		(start 169.864024 -293.214044)
		(end 169.864024 -293.038022)
		(width 0.18288)
		(layer "In4.Cu")
		(net "M_G_CPU1_SA_DQS_DP<2>")
	)
	(segment
		(start 175.136556 -294.480488)
		(end 175.012096 -294.356028)
		(width 0.18288)
		(layer "In4.Cu")
		(net "M_G_CPU1_SA_DQS_DP<2>")
	)
	(segment
		(start 181.255416 -293.562278)
		(end 180.709316 -293.562278)
		(width 0.18288)
		(layer "In4.Cu")
		(net "M_G_CPU1_SA_DQS_DP<2>")
	)
	(segment
		(start 159.074104 -283.950918)
		(end 158.528004 -283.950918)
		(width 0.18288)
		(layer "In4.Cu")
		(net "M_G_CPU1_SA_DQS_DP<2>")
	)
	(segment
		(start 169.296588 -292.470586)
		(end 168.532302 -292.470586)
		(width 0.18288)
		(layer "In4.Cu")
		(net "M_G_CPU1_SA_DQS_DP<2>")
	)
	(segment
		(start 135.527796 -265.803888)
		(end 135.516112 -265.810746)
		(width 0.088646)
		(layer "In4.Cu")
		(net "M_G_CPU1_SA_DQS_DP<2>")
	)
	(segment
		(start 145.895568 -269.038832)
		(end 144.358868 -269.038832)
		(width 0.18288)
		(layer "In4.Cu")
		(net "M_G_CPU1_SA_DQS_DP<2>")
	)
	(segment
		(start 159.585914 -284.63875)
		(end 159.585914 -284.462728)
		(width 0.18288)
		(layer "In4.Cu")
		(net "M_G_CPU1_SA_DQS_DP<2>")
	)
	(segment
		(start 170.250612 -293.600632)
		(end 169.864024 -293.214044)
		(width 0.18288)
		(layer "In4.Cu")
		(net "M_G_CPU1_SA_DQS_DP<2>")
	)
	(segment
		(start 176.409096 -294.356028)
		(end 175.807116 -294.356028)
		(width 0.18288)
		(layer "In4.Cu")
		(net "M_G_CPU1_SA_DQS_DP<2>")
	)
	(segment
		(start 164.09543 -289.333686)
		(end 163.306252 -288.544508)
		(width 0.18288)
		(layer "In4.Cu")
		(net "M_G_CPU1_SA_DQS_DP<2>")
	)
	(segment
		(start 153.826718 -276.969982)
		(end 145.895568 -269.038832)
		(width 0.18288)
		(layer "In4.Cu")
		(net "M_G_CPU1_SA_DQS_DP<2>")
	)
	(segment
		(start 167.953182 -291.891466)
		(end 167.325294 -291.891466)
		(width 0.18288)
		(layer "In4.Cu")
		(net "M_G_CPU1_SA_DQS_DP<2>")
	)
	(segment
		(start 186.843416 -293.695374)
		(end 186.396884 -293.695374)
		(width 0.18288)
		(layer "In4.Cu")
		(net "M_G_CPU1_SA_DQS_DP<2>")
	)
	(segment
		(start 182.050436 -293.562278)
		(end 181.925976 -293.437818)
		(width 0.18288)
		(layer "In4.Cu")
		(net "M_G_CPU1_SA_DQS_DP<2>")
	)
	(segment
		(start 168.532302 -292.470586)
		(end 167.953182 -291.891466)
		(width 0.18288)
		(layer "In4.Cu")
		(net "M_G_CPU1_SA_DQS_DP<2>")
	)
	(segment
		(start 132.142992 -265.803634)
		(end 132.142992 -265.803888)
		(width 0.088646)
		(layer "In4.Cu")
		(net "M_G_CPU1_SA_DQS_DP<2>")
	)
	(segment
		(start 171.420028 -294.920416)
		(end 171.299378 -294.870886)
		(width 0.18288)
		(layer "In4.Cu")
		(net "M_G_CPU1_SA_DQS_DP<2>")
	)
	(segment
		(start 167.325294 -291.891466)
		(end 166.78275 -291.349176)
		(width 0.18288)
		(layer "In4.Cu")
		(net "M_G_CPU1_SA_DQS_DP<2>")
	)
	(segment
		(start 165.117272 -290.197286)
		(end 164.253672 -289.333686)
		(width 0.18288)
		(layer "In4.Cu")
		(net "M_G_CPU1_SA_DQS_DP<2>")
	)
	(segment
		(start 182.596536 -293.562278)
		(end 182.050436 -293.562278)
		(width 0.18288)
		(layer "In4.Cu")
		(net "M_G_CPU1_SA_DQS_DP<2>")
	)
	(segment
		(start 181.925976 -293.437818)
		(end 181.379876 -293.437818)
		(width 0.18288)
		(layer "In4.Cu")
		(net "M_G_CPU1_SA_DQS_DP<2>")
	)
	(segment
		(start 186.139328 -293.437818)
		(end 185.403236 -293.437818)
		(width 0.18288)
		(layer "In4.Cu")
		(net "M_G_CPU1_SA_DQS_DP<2>")
	)
	(segment
		(start 140.800074 -266.43076)
		(end 140.254482 -265.885168)
		(width 0.18288)
		(layer "In4.Cu")
		(net "M_G_CPU1_SA_DQS_DP<2>")
	)
	(segment
		(start 179.243736 -293.437818)
		(end 178.697636 -293.437818)
		(width 0.18288)
		(layer "In4.Cu")
		(net "M_G_CPU1_SA_DQS_DP<2>")
	)
	(segment
		(start 176.695354 -294.642286)
		(end 176.409096 -294.356028)
		(width 0.18288)
		(layer "In4.Cu")
		(net "M_G_CPU1_SA_DQS_DP<2>")
	)
	(segment
		(start 187.61329 -293.946326)
		(end 187.094368 -293.946326)
		(width 0.18288)
		(layer "In4.Cu")
		(net "M_G_CPU1_SA_DQS_DP<2>")
	)
	(segment
		(start 138.641836 -265.885168)
		(end 138.581892 -265.825224)
		(width 0.088646)
		(layer "In4.Cu")
		(net "M_G_CPU1_SA_DQS_DP<2>")
	)
	(segment
		(start 175.012096 -294.356028)
		(end 174.465996 -294.356028)
		(width 0.18288)
		(layer "In4.Cu")
		(net "M_G_CPU1_SA_DQS_DP<2>")
	)
	(segment
		(start 169.864024 -293.038022)
		(end 169.296588 -292.470586)
		(width 0.18288)
		(layer "In4.Cu")
		(net "M_G_CPU1_SA_DQS_DP<2>")
	)
	(segment
		(start 132.708396 -265.803634)
		(end 132.693664 -265.81227)
		(width 0.088646)
		(layer "In4.Cu")
		(net "M_G_CPU1_SA_DQS_DP<2>")
	)
	(segment
		(start 130.760216 -265.312144)
		(end 130.757676 -265.314176)
		(width 0.088646)
		(layer "In4.Cu")
		(net "M_G_CPU1_SA_DQS_DP<2>")
	)
	(segment
		(start 156.471366 -283.22397)
		(end 156.47162 -283.22397)
		(width 0.18288)
		(layer "In4.Cu")
		(net "M_G_CPU1_SA_DQS_DP<2>")
	)
	(segment
		(start 157.857444 -284.075378)
		(end 157.732984 -283.950918)
		(width 0.18288)
		(layer "In4.Cu")
		(net "M_G_CPU1_SA_DQS_DP<2>")
	)
	(segment
		(start 171.299378 -294.870886)
		(end 170.965622 -294.537384)
		(width 0.18288)
		(layer "In4.Cu")
		(net "M_G_CPU1_SA_DQS_DP<2>")
	)
	(segment
		(start 180.584856 -293.437818)
		(end 180.038756 -293.437818)
		(width 0.18288)
		(layer "In4.Cu")
		(net "M_G_CPU1_SA_DQS_DP<2>")
	)
	(segment
		(start 185.278776 -293.562278)
		(end 184.732676 -293.562278)
		(width 0.18288)
		(layer "In4.Cu")
		(net "M_G_CPU1_SA_DQS_DP<2>")
	)
	(segment
		(start 173.297342 -295.20261)
		(end 173.007274 -295.492678)
		(width 0.18288)
		(layer "In4.Cu")
		(net "M_G_CPU1_SA_DQS_DP<2>")
	)
	(segment
		(start 165.63086 -290.197286)
		(end 165.117272 -290.197286)
		(width 0.18288)
		(layer "In4.Cu")
		(net "M_G_CPU1_SA_DQS_DP<2>")
	)
	(segment
		(start 175.807116 -294.356028)
		(end 175.682656 -294.480488)
		(width 0.18288)
		(layer "In4.Cu")
		(net "M_G_CPU1_SA_DQS_DP<2>")
	)
	(segment
		(start 162.279076 -287.250378)
		(end 162.279076 -286.563562)
		(width 0.18288)
		(layer "In4.Cu")
		(net "M_G_CPU1_SA_DQS_DP<2>")
	)
	(segment
		(start 161.281618 -286.158432)
		(end 160.148524 -285.025338)
		(width 0.18288)
		(layer "In4.Cu")
		(net "M_G_CPU1_SA_DQS_DP<2>")
	)
	(segment
		(start 138.665204 -265.885168)
		(end 138.641836 -265.885168)
		(width 0.088646)
		(layer "In4.Cu")
		(net "M_G_CPU1_SA_DQS_DP<2>")
	)
	(segment
		(start 180.038756 -293.437818)
		(end 179.914296 -293.562278)
		(width 0.18288)
		(layer "In4.Cu")
		(net "M_G_CPU1_SA_DQS_DP<2>")
	)
	(segment
		(start 170.965622 -294.13962)
		(end 170.426634 -293.600632)
		(width 0.18288)
		(layer "In4.Cu")
		(net "M_G_CPU1_SA_DQS_DP<2>")
	)
	(segment
		(start 159.972502 -285.025338)
		(end 159.585914 -284.63875)
		(width 0.18288)
		(layer "In4.Cu")
		(net "M_G_CPU1_SA_DQS_DP<2>")
	)
	(segment
		(start 172.648626 -295.492678)
		(end 172.569124 -295.492678)
		(width 0.18288)
		(layer "In4.Cu")
		(net "M_G_CPU1_SA_DQS_DP<2>")
	)
	(segment
		(start 158.528004 -283.950918)
		(end 158.403544 -284.075378)
		(width 0.18288)
		(layer "In4.Cu")
		(net "M_G_CPU1_SA_DQS_DP<2>")
	)
	(segment
		(start 138.581892 -265.825224)
		(end 137.616438 -265.825224)
		(width 0.088646)
		(layer "In4.Cu")
		(net "M_G_CPU1_SA_DQS_DP<2>")
	)
	(segment
		(start 166.78275 -291.349176)
		(end 166.606728 -291.349176)
		(width 0.18288)
		(layer "In4.Cu")
		(net "M_G_CPU1_SA_DQS_DP<2>")
	)
	(segment
		(start 177.088292 -294.642286)
		(end 176.695354 -294.642286)
		(width 0.18288)
		(layer "In4.Cu")
		(net "M_G_CPU1_SA_DQS_DP<2>")
	)
	(segment
		(start 157.166564 -283.950918)
		(end 156.495242 -283.27985)
		(width 0.18288)
		(layer "In4.Cu")
		(net "M_G_CPU1_SA_DQS_DP<2>")
	)
	(segment
		(start 186.396884 -293.695374)
		(end 186.139328 -293.437818)
		(width 0.18288)
		(layer "In4.Cu")
		(net "M_G_CPU1_SA_DQS_DP<2>")
	)
	(segment
		(start 184.732676 -293.562278)
		(end 184.608216 -293.437818)
		(width 0.18288)
		(layer "In4.Cu")
		(net "M_G_CPU1_SA_DQS_DP<2>")
	)
	(segment
		(start 163.306252 -288.277554)
		(end 162.279076 -287.250378)
		(width 0.18288)
		(layer "In4.Cu")
		(net "M_G_CPU1_SA_DQS_DP<2>")
	)
	(segment
		(start 158.403544 -284.075378)
		(end 157.857444 -284.075378)
		(width 0.18288)
		(layer "In4.Cu")
		(net "M_G_CPU1_SA_DQS_DP<2>")
	)
	(segment
		(start 177.777902 -294.357552)
		(end 177.373026 -294.357552)
		(width 0.18288)
		(layer "In4.Cu")
		(net "M_G_CPU1_SA_DQS_DP<2>")
	)
	(segment
		(start 160.148524 -285.025338)
		(end 159.972502 -285.025338)
		(width 0.18288)
		(layer "In4.Cu")
		(net "M_G_CPU1_SA_DQS_DP<2>")
	)
	(segment
		(start 179.368196 -293.562278)
		(end 179.243736 -293.437818)
		(width 0.18288)
		(layer "In4.Cu")
		(net "M_G_CPU1_SA_DQS_DP<2>")
	)
	(segment
		(start 144.358868 -269.038832)
		(end 143.021558 -268.484858)
		(width 0.18288)
		(layer "In4.Cu")
		(net "M_G_CPU1_SA_DQS_DP<2>")
	)
	(segment
		(start 185.403236 -293.437818)
		(end 185.278776 -293.562278)
		(width 0.18288)
		(layer "In4.Cu")
		(net "M_G_CPU1_SA_DQS_DP<2>")
	)
	(segment
		(start 134.587996 -265.803634)
		(end 134.573264 -265.81227)
		(width 0.088646)
		(layer "In4.Cu")
		(net "M_G_CPU1_SA_DQS_DP<2>")
	)
	(segment
		(start 142.735554 -268.366494)
		(end 140.800074 -266.43076)
		(width 0.18288)
		(layer "In4.Cu")
		(net "M_G_CPU1_SA_DQS_DP<2>")
	)
	(segment
		(start 166.220394 -290.962842)
		(end 166.220394 -290.78682)
		(width 0.18288)
		(layer "In4.Cu")
		(net "M_G_CPU1_SA_DQS_DP<2>")
	)
	(segment
		(start 183.267096 -293.437818)
		(end 182.720996 -293.437818)
		(width 0.18288)
		(layer "In4.Cu")
		(net "M_G_CPU1_SA_DQS_DP<2>")
	)
	(segment
		(start 135.516112 -265.810746)
		(end 135.513064 -265.81227)
		(width 0.088646)
		(layer "In4.Cu")
		(net "M_G_CPU1_SA_DQS_DP<2>")
	)
	(segment
		(start 180.709316 -293.562278)
		(end 180.584856 -293.437818)
		(width 0.18288)
		(layer "In4.Cu")
		(net "M_G_CPU1_SA_DQS_DP<2>")
	)
	(segment
		(start 159.585914 -284.462728)
		(end 159.074104 -283.950918)
		(width 0.18288)
		(layer "In4.Cu")
		(net "M_G_CPU1_SA_DQS_DP<2>")
	)
	(segment
		(start 172.569124 -295.492678)
		(end 172.140372 -295.063926)
		(width 0.18288)
		(layer "In4.Cu")
		(net "M_G_CPU1_SA_DQS_DP<2>")
	)
	(segment
		(start 140.254482 -265.885168)
		(end 138.665204 -265.885168)
		(width 0.18288)
		(layer "In4.Cu")
		(net "M_G_CPU1_SA_DQS_DP<2>")
	)
	(segment
		(start 166.220394 -290.78682)
		(end 165.63086 -290.197286)
		(width 0.18288)
		(layer "In4.Cu")
		(net "M_G_CPU1_SA_DQS_DP<2>")
	)
	(segment
		(start 131.768596 -265.803888)
		(end 131.753864 -265.812524)
		(width 0.088646)
		(layer "In4.Cu")
		(net "M_G_CPU1_SA_DQS_DP<2>")
	)
	(segment
		(start 174.465996 -294.356028)
		(end 173.618906 -295.20261)
		(width 0.18288)
		(layer "In4.Cu")
		(net "M_G_CPU1_SA_DQS_DP<2>")
	)
	(segment
		(start 172.650404 -295.4909)
		(end 172.648626 -295.492678)
		(width 0.18288)
		(layer "In4.Cu")
		(net "M_G_CPU1_SA_DQS_DP<2>")
	)
	(segment
		(start 187.094368 -293.946326)
		(end 186.843416 -293.695374)
		(width 0.18288)
		(layer "In4.Cu")
		(net "M_G_CPU1_SA_DQS_DP<2>")
	)
	(segment
		(start 187.883546 -294.216582)
		(end 187.61329 -293.946326)
		(width 0.18288)
		(layer "In4.Cu")
		(net "M_G_CPU1_SA_DQS_DP<2>")
	)
	(segment
		(start 177.373026 -294.357552)
		(end 177.088292 -294.642286)
		(width 0.18288)
		(layer "In4.Cu")
		(net "M_G_CPU1_SA_DQS_DP<2>")
	)
	(segment
		(start 173.007274 -295.492678)
		(end 172.902626 -295.492678)
		(width 0.18288)
		(layer "In4.Cu")
		(net "M_G_CPU1_SA_DQS_DP<2>")
	)
	(segment
		(start 184.062116 -293.437818)
		(end 183.937656 -293.562278)
		(width 0.18288)
		(layer "In4.Cu")
		(net "M_G_CPU1_SA_DQS_DP<2>")
	)
	(segment
		(start 170.426634 -293.600632)
		(end 170.250612 -293.600632)
		(width 0.18288)
		(layer "In4.Cu")
		(net "M_G_CPU1_SA_DQS_DP<2>")
	)
	(segment
		(start 184.608216 -293.437818)
		(end 184.062116 -293.437818)
		(width 0.18288)
		(layer "In4.Cu")
		(net "M_G_CPU1_SA_DQS_DP<2>")
	)
	(segment
		(start 156.495242 -283.27985)
		(end 156.471366 -283.22397)
		(width 0.18288)
		(layer "In4.Cu")
		(net "M_G_CPU1_SA_DQS_DP<2>")
	)
	(segment
		(start 162.279076 -286.563562)
		(end 161.873946 -286.158432)
		(width 0.18288)
		(layer "In4.Cu")
		(net "M_G_CPU1_SA_DQS_DP<2>")
	)
	(segment
		(start 143.021558 -268.484858)
		(end 142.735554 -268.366494)
		(width 0.18288)
		(layer "In4.Cu")
		(net "M_G_CPU1_SA_DQS_DP<2>")
	)
	(arc
		(start 134.022592 -265.803634)
		(mid 133.835394 -265.753491)
		(end 133.648196 -265.803634)
		(width 0.088646)
		(layer "In4.Cu")
		(net "M_G_CPU1_SA_DQS_DP<2>")
	)
	(arc
		(start 136.842754 -265.80338)
		(mid 136.842373 -265.803634)
		(end 136.841992 -265.803888)
		(width 0.088646)
		(layer "In4.Cu")
		(net "M_G_CPU1_SA_DQS_DP<2>")
	)
	(arc
		(start 135.513064 -265.81227)
		(mid 135.236589 -265.87959)
		(end 134.962392 -265.803634)
		(width 0.088646)
		(layer "In4.Cu")
		(net "M_G_CPU1_SA_DQS_DP<2>")
	)
	(arc
		(start 132.693664 -265.81227)
		(mid 132.417189 -265.87959)
		(end 132.142992 -265.803634)
		(width 0.088646)
		(layer "In4.Cu")
		(net "M_G_CPU1_SA_DQS_DP<2>")
	)
	(arc
		(start 135.902192 -265.803888)
		(mid 135.714994 -265.753745)
		(end 135.527796 -265.803888)
		(width 0.088646)
		(layer "In4.Cu")
		(net "M_G_CPU1_SA_DQS_DP<2>")
	)
	(arc
		(start 136.841992 -265.803888)
		(mid 136.654794 -265.753745)
		(end 136.467596 -265.803888)
		(width 0.088646)
		(layer "In4.Cu")
		(net "M_G_CPU1_SA_DQS_DP<2>")
	)
	(arc
		(start 133.648196 -265.803634)
		(mid 133.365494 -265.87941)
		(end 133.082792 -265.803634)
		(width 0.088646)
		(layer "In4.Cu")
		(net "M_G_CPU1_SA_DQS_DP<2>")
	)
	(arc
		(start 133.082792 -265.803634)
		(mid 132.895594 -265.753491)
		(end 132.708396 -265.803634)
		(width 0.088646)
		(layer "In4.Cu")
		(net "M_G_CPU1_SA_DQS_DP<2>")
	)
	(arc
		(start 134.962392 -265.803634)
		(mid 134.775194 -265.753491)
		(end 134.587996 -265.803634)
		(width 0.088646)
		(layer "In4.Cu")
		(net "M_G_CPU1_SA_DQS_DP<2>")
	)
	(arc
		(start 136.452864 -265.812524)
		(mid 136.176423 -265.87969)
		(end 135.902192 -265.803888)
		(width 0.088646)
		(layer "In4.Cu")
		(net "M_G_CPU1_SA_DQS_DP<2>")
	)
	(arc
		(start 134.573264 -265.81227)
		(mid 134.296789 -265.87959)
		(end 134.022592 -265.803634)
		(width 0.088646)
		(layer "In4.Cu")
		(net "M_G_CPU1_SA_DQS_DP<2>")
	)
	(arc
		(start 137.24763 -265.865864)
		(mid 137.039325 -265.87263)
		(end 136.842754 -265.80338)
		(width 0.088646)
		(layer "In4.Cu")
		(net "M_G_CPU1_SA_DQS_DP<2>")
	)
	(arc
		(start 137.616438 -265.825224)
		(mid 137.430922 -265.835453)
		(end 137.24763 -265.865864)
		(width 0.088646)
		(layer "In4.Cu")
		(net "M_G_CPU1_SA_DQS_DP<2>")
	)
	(arc
		(start 131.753864 -265.812524)
		(mid 131.477423 -265.87969)
		(end 131.203192 -265.803888)
		(width 0.088646)
		(layer "In4.Cu")
		(net "M_G_CPU1_SA_DQS_DP<2>")
	)
	(arc
		(start 132.142992 -265.803888)
		(mid 131.955794 -265.753745)
		(end 131.768596 -265.803888)
		(width 0.088646)
		(layer "In4.Cu")
		(net "M_G_CPU1_SA_DQS_DP<2>")
	)
	(segment
		(start 194.098926 -303.997868)
		(end 194.422268 -303.997868)
		(width 0.20066)
		(layer "F.Cu")
		(net "M_G_CPU1_SA_DQS_DP<1>")
	)
	(segment
		(start 190.41872 -303.326038)
		(end 190.833248 -303.740566)
		(width 0.20066)
		(layer "F.Cu")
		(net "M_G_CPU1_SA_DQS_DP<1>")
	)
	(segment
		(start 194.09283 -303.991772)
		(end 194.098926 -303.997868)
		(width 0.1016)
		(layer "F.Cu")
		(net "M_G_CPU1_SA_DQS_DP<1>")
	)
	(segment
		(start 127.257048 -272.103342)
		(end 127.256794 -272.639282)
		(width 0.20066)
		(layer "F.Cu")
		(net "M_G_CPU1_SA_DQS_DP<1>")
	)
	(segment
		(start 188.988446 -303.566576)
		(end 189.577726 -303.566576)
		(width 0.20066)
		(layer "F.Cu")
		(net "M_G_CPU1_SA_DQS_DP<1>")
	)
	(segment
		(start 189.818264 -303.326038)
		(end 190.41872 -303.326038)
		(width 0.20066)
		(layer "F.Cu")
		(net "M_G_CPU1_SA_DQS_DP<1>")
	)
	(segment
		(start 191.519048 -303.740566)
		(end 191.770254 -303.991772)
		(width 0.20066)
		(layer "F.Cu")
		(net "M_G_CPU1_SA_DQS_DP<1>")
	)
	(segment
		(start 195.505832 -303.28489)
		(end 195.70192 -303.28489)
		(width 0.20066)
		(layer "F.Cu")
		(net "M_G_CPU1_SA_DQS_DP<1>")
	)
	(segment
		(start 190.833248 -303.740566)
		(end 191.519048 -303.740566)
		(width 0.20066)
		(layer "F.Cu")
		(net "M_G_CPU1_SA_DQS_DP<1>")
	)
	(segment
		(start 194.422268 -303.997868)
		(end 194.724782 -303.695354)
		(width 0.20066)
		(layer "F.Cu")
		(net "M_G_CPU1_SA_DQS_DP<1>")
	)
	(segment
		(start 189.577726 -303.566576)
		(end 189.818264 -303.326038)
		(width 0.20066)
		(layer "F.Cu")
		(net "M_G_CPU1_SA_DQS_DP<1>")
	)
	(segment
		(start 194.724782 -303.695354)
		(end 195.095368 -303.695354)
		(width 0.20066)
		(layer "F.Cu")
		(net "M_G_CPU1_SA_DQS_DP<1>")
	)
	(segment
		(start 191.935608 -303.991772)
		(end 194.09283 -303.991772)
		(width 0.1016)
		(layer "F.Cu")
		(net "M_G_CPU1_SA_DQS_DP<1>")
	)
	(segment
		(start 195.095368 -303.695354)
		(end 195.505832 -303.28489)
		(width 0.20066)
		(layer "F.Cu")
		(net "M_G_CPU1_SA_DQS_DP<1>")
	)
	(segment
		(start 195.983606 -303.566576)
		(end 196.532246 -303.566576)
		(width 0.20066)
		(layer "F.Cu")
		(net "M_G_CPU1_SA_DQS_DP<1>")
	)
	(segment
		(start 191.770254 -303.991772)
		(end 191.9097 -303.991772)
		(width 0.20066)
		(layer "F.Cu")
		(net "M_G_CPU1_SA_DQS_DP<1>")
	)
	(segment
		(start 191.9097 -303.991772)
		(end 191.935608 -303.991772)
		(width 0.101854)
		(layer "F.Cu")
		(net "M_G_CPU1_SA_DQS_DP<1>")
	)
	(segment
		(start 195.70192 -303.28489)
		(end 195.983606 -303.566576)
		(width 0.20066)
		(layer "F.Cu")
		(net "M_G_CPU1_SA_DQS_DP<1>")
	)
	(segment
		(start 187.883546 -303.566576)
		(end 188.988446 -303.566576)
		(width 0.20066)
		(layer "F.Cu")
		(net "M_G_CPU1_SA_DQS_DP<1>")
	)
	(segment
		(start 169.222166 -296.93235)
		(end 168.676066 -296.93235)
		(width 0.18288)
		(layer "In6.Cu")
		(net "M_G_CPU1_SA_DQS_DP<1>")
	)
	(segment
		(start 170.902884 -296.93235)
		(end 170.017186 -296.93235)
		(width 0.18288)
		(layer "In6.Cu")
		(net "M_G_CPU1_SA_DQS_DP<1>")
	)
	(segment
		(start 170.017186 -296.93235)
		(end 169.892726 -297.05681)
		(width 0.18288)
		(layer "In6.Cu")
		(net "M_G_CPU1_SA_DQS_DP<1>")
	)
	(segment
		(start 132.627878 -273.137376)
		(end 132.613146 -273.12874)
		(width 0.088646)
		(layer "In6.Cu")
		(net "M_G_CPU1_SA_DQS_DP<1>")
	)
	(segment
		(start 155.233878 -291.088318)
		(end 154.847798 -290.702238)
		(width 0.18288)
		(layer "In6.Cu")
		(net "M_G_CPU1_SA_DQS_DP<1>")
	)
	(segment
		(start 156.182314 -292.212776)
		(end 156.182314 -292.036754)
		(width 0.18288)
		(layer "In6.Cu")
		(net "M_G_CPU1_SA_DQS_DP<1>")
	)
	(segment
		(start 158.626556 -293.257732)
		(end 158.502096 -293.382192)
		(width 0.18288)
		(layer "In6.Cu")
		(net "M_G_CPU1_SA_DQS_DP<1>")
	)
	(segment
		(start 187.883546 -303.566576)
		(end 187.611004 -303.294034)
		(width 0.18288)
		(layer "In6.Cu")
		(net "M_G_CPU1_SA_DQS_DP<1>")
	)
	(segment
		(start 127.653288 -272.803874)
		(end 127.591058 -272.687796)
		(width 0.088646)
		(layer "In6.Cu")
		(net "M_G_CPU1_SA_DQS_DP<1>")
	)
	(segment
		(start 165.6969 -294.337486)
		(end 164.556948 -294.337486)
		(width 0.18288)
		(layer "In6.Cu")
		(net "M_G_CPU1_SA_DQS_DP<1>")
	)
	(segment
		(start 163.79317 -294.690546)
		(end 163.476686 -294.374062)
		(width 0.18288)
		(layer "In6.Cu")
		(net "M_G_CPU1_SA_DQS_DP<1>")
	)
	(segment
		(start 166.75227 -295.392856)
		(end 166.576248 -295.392856)
		(width 0.18288)
		(layer "In6.Cu")
		(net "M_G_CPU1_SA_DQS_DP<1>")
	)
	(segment
		(start 127.542544 -272.639282)
		(end 127.256794 -272.639282)
		(width 0.088646)
		(layer "In6.Cu")
		(net "M_G_CPU1_SA_DQS_DP<1>")
	)
	(segment
		(start 156.568648 -292.59911)
		(end 156.182314 -292.212776)
		(width 0.18288)
		(layer "In6.Cu")
		(net "M_G_CPU1_SA_DQS_DP<1>")
	)
	(segment
		(start 127.928878 -273.137376)
		(end 127.914146 -273.12874)
		(width 0.088646)
		(layer "In6.Cu")
		(net "M_G_CPU1_SA_DQS_DP<1>")
	)
	(segment
		(start 169.892726 -297.05681)
		(end 169.346626 -297.05681)
		(width 0.18288)
		(layer "In6.Cu")
		(net "M_G_CPU1_SA_DQS_DP<1>")
	)
	(segment
		(start 178.549554 -298.30903)
		(end 178.549554 -298.133008)
		(width 0.18288)
		(layer "In6.Cu")
		(net "M_G_CPU1_SA_DQS_DP<1>")
	)
	(segment
		(start 140.595604 -274.685252)
		(end 140.572236 -274.685252)
		(width 0.088646)
		(layer "In6.Cu")
		(net "M_G_CPU1_SA_DQS_DP<1>")
	)
	(segment
		(start 159.967676 -293.257732)
		(end 159.843216 -293.382192)
		(width 0.18288)
		(layer "In6.Cu")
		(net "M_G_CPU1_SA_DQS_DP<1>")
	)
	(segment
		(start 158.502096 -293.382192)
		(end 157.955996 -293.382192)
		(width 0.18288)
		(layer "In6.Cu")
		(net "M_G_CPU1_SA_DQS_DP<1>")
	)
	(segment
		(start 154.285442 -290.139882)
		(end 153.899362 -289.753802)
		(width 0.18288)
		(layer "In6.Cu")
		(net "M_G_CPU1_SA_DQS_DP<1>")
	)
	(segment
		(start 171.697904 -296.93235)
		(end 171.573444 -297.05681)
		(width 0.18288)
		(layer "In6.Cu")
		(net "M_G_CPU1_SA_DQS_DP<1>")
	)
	(segment
		(start 180.66258 -299.341286)
		(end 179.757832 -299.341286)
		(width 0.18288)
		(layer "In6.Cu")
		(net "M_G_CPU1_SA_DQS_DP<1>")
	)
	(segment
		(start 135.44296 -273.134836)
		(end 135.432546 -273.12874)
		(width 0.088646)
		(layer "In6.Cu")
		(net "M_G_CPU1_SA_DQS_DP<1>")
	)
	(segment
		(start 140.572236 -274.685252)
		(end 140.512292 -274.625308)
		(width 0.088646)
		(layer "In6.Cu")
		(net "M_G_CPU1_SA_DQS_DP<1>")
	)
	(segment
		(start 179.11191 -298.695364)
		(end 178.935888 -298.695364)
		(width 0.18288)
		(layer "In6.Cu")
		(net "M_G_CPU1_SA_DQS_DP<1>")
	)
	(segment
		(start 167.583612 -295.839896)
		(end 167.19931 -295.839896)
		(width 0.18288)
		(layer "In6.Cu")
		(net "M_G_CPU1_SA_DQS_DP<1>")
	)
	(segment
		(start 187.611004 -303.294034)
		(end 187.127642 -303.294034)
		(width 0.18288)
		(layer "In6.Cu")
		(net "M_G_CPU1_SA_DQS_DP<1>")
	)
	(segment
		(start 154.671776 -290.702238)
		(end 154.285442 -290.315904)
		(width 0.18288)
		(layer "In6.Cu")
		(net "M_G_CPU1_SA_DQS_DP<1>")
	)
	(segment
		(start 181.545992 -300.40072)
		(end 181.159404 -300.014132)
		(width 0.18288)
		(layer "In6.Cu")
		(net "M_G_CPU1_SA_DQS_DP<1>")
	)
	(segment
		(start 178.935888 -298.695364)
		(end 178.549554 -298.30903)
		(width 0.18288)
		(layer "In6.Cu")
		(net "M_G_CPU1_SA_DQS_DP<1>")
	)
	(segment
		(start 181.159404 -300.014132)
		(end 181.159404 -299.83811)
		(width 0.18288)
		(layer "In6.Cu")
		(net "M_G_CPU1_SA_DQS_DP<1>")
	)
	(segment
		(start 153.899362 -281.107134)
		(end 147.854924 -275.062696)
		(width 0.18288)
		(layer "In6.Cu")
		(net "M_G_CPU1_SA_DQS_DP<1>")
	)
	(segment
		(start 156.182314 -292.036754)
		(end 155.796234 -291.650674)
		(width 0.18288)
		(layer "In6.Cu")
		(net "M_G_CPU1_SA_DQS_DP<1>")
	)
	(segment
		(start 173.842934 -296.9006)
		(end 173.303184 -296.9006)
		(width 0.18288)
		(layer "In6.Cu")
		(net "M_G_CPU1_SA_DQS_DP<1>")
	)
	(segment
		(start 166.18966 -295.006268)
		(end 166.18966 -294.830246)
		(width 0.18288)
		(layer "In6.Cu")
		(net "M_G_CPU1_SA_DQS_DP<1>")
	)
	(segment
		(start 178.549554 -298.133008)
		(end 178.163474 -297.746928)
		(width 0.18288)
		(layer "In6.Cu")
		(net "M_G_CPU1_SA_DQS_DP<1>")
	)
	(segment
		(start 142.036038 -275.062696)
		(end 141.12494 -274.685252)
		(width 0.18288)
		(layer "In6.Cu")
		(net "M_G_CPU1_SA_DQS_DP<1>")
	)
	(segment
		(start 162.798252 -294.374062)
		(end 162.449256 -294.025066)
		(width 0.18288)
		(layer "In6.Cu")
		(net "M_G_CPU1_SA_DQS_DP<1>")
	)
	(segment
		(start 171.027344 -297.05681)
		(end 170.902884 -296.93235)
		(width 0.18288)
		(layer "In6.Cu")
		(net "M_G_CPU1_SA_DQS_DP<1>")
	)
	(segment
		(start 177.406808 -297.746928)
		(end 177.11293 -298.040806)
		(width 0.18288)
		(layer "In6.Cu")
		(net "M_G_CPU1_SA_DQS_DP<1>")
	)
	(segment
		(start 164.203888 -294.690546)
		(end 163.79317 -294.690546)
		(width 0.18288)
		(layer "In6.Cu")
		(net "M_G_CPU1_SA_DQS_DP<1>")
	)
	(segment
		(start 171.573444 -297.05681)
		(end 171.027344 -297.05681)
		(width 0.18288)
		(layer "In6.Cu")
		(net "M_G_CPU1_SA_DQS_DP<1>")
	)
	(segment
		(start 178.163474 -297.746928)
		(end 177.406808 -297.746928)
		(width 0.18288)
		(layer "In6.Cu")
		(net "M_G_CPU1_SA_DQS_DP<1>")
	)
	(segment
		(start 154.285442 -290.315904)
		(end 154.285442 -290.139882)
		(width 0.18288)
		(layer "In6.Cu")
		(net "M_G_CPU1_SA_DQS_DP<1>")
	)
	(segment
		(start 138.88212 -273.204432)
		(end 138.533632 -273.204432)
		(width 0.088646)
		(layer "In6.Cu")
		(net "M_G_CPU1_SA_DQS_DP<1>")
	)
	(segment
		(start 182.23738 -300.916086)
		(end 181.722014 -300.40072)
		(width 0.18288)
		(layer "In6.Cu")
		(net "M_G_CPU1_SA_DQS_DP<1>")
	)
	(segment
		(start 187.127642 -303.294034)
		(end 186.79287 -302.959262)
		(width 0.18288)
		(layer "In6.Cu")
		(net "M_G_CPU1_SA_DQS_DP<1>")
	)
	(segment
		(start 127.913384 -273.128232)
		(end 127.90805 -273.125184)
		(width 0.088646)
		(layer "In6.Cu")
		(net "M_G_CPU1_SA_DQS_DP<1>")
	)
	(segment
		(start 134.507478 -273.137376)
		(end 134.492746 -273.12874)
		(width 0.088646)
		(layer "In6.Cu")
		(net "M_G_CPU1_SA_DQS_DP<1>")
	)
	(segment
		(start 172.244004 -296.93235)
		(end 171.697904 -296.93235)
		(width 0.18288)
		(layer "In6.Cu")
		(net "M_G_CPU1_SA_DQS_DP<1>")
	)
	(segment
		(start 162.449256 -294.025066)
		(end 160.599374 -293.257732)
		(width 0.18288)
		(layer "In6.Cu")
		(net "M_G_CPU1_SA_DQS_DP<1>")
	)
	(segment
		(start 140.512292 -274.625308)
		(end 140.302996 -274.625308)
		(width 0.088646)
		(layer "In6.Cu")
		(net "M_G_CPU1_SA_DQS_DP<1>")
	)
	(segment
		(start 186.79287 -302.959262)
		(end 185.338212 -302.959262)
		(width 0.18288)
		(layer "In6.Cu")
		(net "M_G_CPU1_SA_DQS_DP<1>")
	)
	(segment
		(start 185.338212 -302.959262)
		(end 183.295036 -300.916086)
		(width 0.18288)
		(layer "In6.Cu")
		(net "M_G_CPU1_SA_DQS_DP<1>")
	)
	(segment
		(start 153.899362 -289.753802)
		(end 153.899362 -281.107134)
		(width 0.18288)
		(layer "In6.Cu")
		(net "M_G_CPU1_SA_DQS_DP<1>")
	)
	(segment
		(start 181.722014 -300.40072)
		(end 181.545992 -300.40072)
		(width 0.18288)
		(layer "In6.Cu")
		(net "M_G_CPU1_SA_DQS_DP<1>")
	)
	(segment
		(start 166.576248 -295.392856)
		(end 166.18966 -295.006268)
		(width 0.18288)
		(layer "In6.Cu")
		(net "M_G_CPU1_SA_DQS_DP<1>")
	)
	(segment
		(start 141.12494 -274.685252)
		(end 140.595604 -274.685252)
		(width 0.18288)
		(layer "In6.Cu")
		(net "M_G_CPU1_SA_DQS_DP<1>")
	)
	(segment
		(start 127.914146 -273.12874)
		(end 127.913384 -273.128232)
		(width 0.088646)
		(layer "In6.Cu")
		(net "M_G_CPU1_SA_DQS_DP<1>")
	)
	(segment
		(start 159.843216 -293.382192)
		(end 159.297116 -293.382192)
		(width 0.18288)
		(layer "In6.Cu")
		(net "M_G_CPU1_SA_DQS_DP<1>")
	)
	(segment
		(start 156.74467 -292.59911)
		(end 156.568648 -292.59911)
		(width 0.18288)
		(layer "In6.Cu")
		(net "M_G_CPU1_SA_DQS_DP<1>")
	)
	(segment
		(start 173.012862 -297.190922)
		(end 172.502576 -297.190922)
		(width 0.18288)
		(layer "In6.Cu")
		(net "M_G_CPU1_SA_DQS_DP<1>")
	)
	(segment
		(start 159.172656 -293.257732)
		(end 158.626556 -293.257732)
		(width 0.18288)
		(layer "In6.Cu")
		(net "M_G_CPU1_SA_DQS_DP<1>")
	)
	(segment
		(start 133.567678 -273.137376)
		(end 133.552946 -273.12874)
		(width 0.088646)
		(layer "In6.Cu")
		(net "M_G_CPU1_SA_DQS_DP<1>")
	)
	(segment
		(start 155.620212 -291.650674)
		(end 155.233878 -291.26434)
		(width 0.18288)
		(layer "In6.Cu")
		(net "M_G_CPU1_SA_DQS_DP<1>")
	)
	(segment
		(start 173.303184 -296.9006)
		(end 173.012862 -297.190922)
		(width 0.18288)
		(layer "In6.Cu")
		(net "M_G_CPU1_SA_DQS_DP<1>")
	)
	(segment
		(start 157.955996 -293.382192)
		(end 157.831536 -293.257732)
		(width 0.18288)
		(layer "In6.Cu")
		(net "M_G_CPU1_SA_DQS_DP<1>")
	)
	(segment
		(start 172.502576 -297.190922)
		(end 172.244004 -296.93235)
		(width 0.18288)
		(layer "In6.Cu")
		(net "M_G_CPU1_SA_DQS_DP<1>")
	)
	(segment
		(start 177.11293 -298.040806)
		(end 176.602644 -298.040806)
		(width 0.18288)
		(layer "In6.Cu")
		(net "M_G_CPU1_SA_DQS_DP<1>")
	)
	(segment
		(start 157.403292 -293.257732)
		(end 156.74467 -292.59911)
		(width 0.18288)
		(layer "In6.Cu")
		(net "M_G_CPU1_SA_DQS_DP<1>")
	)
	(segment
		(start 155.796234 -291.650674)
		(end 155.620212 -291.650674)
		(width 0.18288)
		(layer "In6.Cu")
		(net "M_G_CPU1_SA_DQS_DP<1>")
	)
	(segment
		(start 166.18966 -294.830246)
		(end 165.6969 -294.337486)
		(width 0.18288)
		(layer "In6.Cu")
		(net "M_G_CPU1_SA_DQS_DP<1>")
	)
	(segment
		(start 140.302996 -274.625308)
		(end 138.88212 -273.204432)
		(width 0.088646)
		(layer "In6.Cu")
		(net "M_G_CPU1_SA_DQS_DP<1>")
	)
	(segment
		(start 154.847798 -290.702238)
		(end 154.671776 -290.702238)
		(width 0.18288)
		(layer "In6.Cu")
		(net "M_G_CPU1_SA_DQS_DP<1>")
	)
	(segment
		(start 163.476686 -294.374062)
		(end 162.798252 -294.374062)
		(width 0.18288)
		(layer "In6.Cu")
		(net "M_G_CPU1_SA_DQS_DP<1>")
	)
	(segment
		(start 159.297116 -293.382192)
		(end 159.172656 -293.257732)
		(width 0.18288)
		(layer "In6.Cu")
		(net "M_G_CPU1_SA_DQS_DP<1>")
	)
	(segment
		(start 176.342294 -297.780456)
		(end 174.72279 -297.780456)
		(width 0.18288)
		(layer "In6.Cu")
		(net "M_G_CPU1_SA_DQS_DP<1>")
	)
	(segment
		(start 176.602644 -298.040806)
		(end 176.342294 -297.780456)
		(width 0.18288)
		(layer "In6.Cu")
		(net "M_G_CPU1_SA_DQS_DP<1>")
	)
	(segment
		(start 179.757832 -299.341286)
		(end 179.11191 -298.695364)
		(width 0.18288)
		(layer "In6.Cu")
		(net "M_G_CPU1_SA_DQS_DP<1>")
	)
	(segment
		(start 157.831536 -293.257732)
		(end 157.403292 -293.257732)
		(width 0.18288)
		(layer "In6.Cu")
		(net "M_G_CPU1_SA_DQS_DP<1>")
	)
	(segment
		(start 147.854924 -275.062696)
		(end 142.036038 -275.062696)
		(width 0.18288)
		(layer "In6.Cu")
		(net "M_G_CPU1_SA_DQS_DP<1>")
	)
	(segment
		(start 167.19931 -295.839896)
		(end 166.75227 -295.392856)
		(width 0.18288)
		(layer "In6.Cu")
		(net "M_G_CPU1_SA_DQS_DP<1>")
	)
	(segment
		(start 164.556948 -294.337486)
		(end 164.203888 -294.690546)
		(width 0.18288)
		(layer "In6.Cu")
		(net "M_G_CPU1_SA_DQS_DP<1>")
	)
	(segment
		(start 169.346626 -297.05681)
		(end 169.222166 -296.93235)
		(width 0.18288)
		(layer "In6.Cu")
		(net "M_G_CPU1_SA_DQS_DP<1>")
	)
	(segment
		(start 130.748278 -273.137376)
		(end 130.733546 -273.12874)
		(width 0.088646)
		(layer "In6.Cu")
		(net "M_G_CPU1_SA_DQS_DP<1>")
	)
	(segment
		(start 174.72279 -297.780456)
		(end 173.842934 -296.9006)
		(width 0.18288)
		(layer "In6.Cu")
		(net "M_G_CPU1_SA_DQS_DP<1>")
	)
	(segment
		(start 160.599374 -293.257732)
		(end 159.967676 -293.257732)
		(width 0.18288)
		(layer "In6.Cu")
		(net "M_G_CPU1_SA_DQS_DP<1>")
	)
	(segment
		(start 127.591058 -272.687796)
		(end 127.542544 -272.639282)
		(width 0.088646)
		(layer "In6.Cu")
		(net "M_G_CPU1_SA_DQS_DP<1>")
	)
	(segment
		(start 127.71755 -272.939256)
		(end 127.682498 -272.880328)
		(width 0.088646)
		(layer "In6.Cu")
		(net "M_G_CPU1_SA_DQS_DP<1>")
	)
	(segment
		(start 129.808478 -273.137376)
		(end 129.793746 -273.12874)
		(width 0.088646)
		(layer "In6.Cu")
		(net "M_G_CPU1_SA_DQS_DP<1>")
	)
	(segment
		(start 183.295036 -300.916086)
		(end 182.23738 -300.916086)
		(width 0.18288)
		(layer "In6.Cu")
		(net "M_G_CPU1_SA_DQS_DP<1>")
	)
	(segment
		(start 128.868678 -273.137376)
		(end 128.853946 -273.12874)
		(width 0.088646)
		(layer "In6.Cu")
		(net "M_G_CPU1_SA_DQS_DP<1>")
	)
	(segment
		(start 168.676066 -296.93235)
		(end 167.583612 -295.839896)
		(width 0.18288)
		(layer "In6.Cu")
		(net "M_G_CPU1_SA_DQS_DP<1>")
	)
	(segment
		(start 155.233878 -291.26434)
		(end 155.233878 -291.088318)
		(width 0.18288)
		(layer "In6.Cu")
		(net "M_G_CPU1_SA_DQS_DP<1>")
	)
	(segment
		(start 181.159404 -299.83811)
		(end 180.66258 -299.341286)
		(width 0.18288)
		(layer "In6.Cu")
		(net "M_G_CPU1_SA_DQS_DP<1>")
	)
	(segment
		(start 137.885424 -273.123914)
		(end 137.866628 -273.134836)
		(width 0.088646)
		(layer "In6.Cu")
		(net "M_G_CPU1_SA_DQS_DP<1>")
	)
	(arc
		(start 134.11835 -273.12874)
		(mid 133.844151 -273.204575)
		(end 133.567678 -273.137376)
		(width 0.088646)
		(layer "In6.Cu")
		(net "M_G_CPU1_SA_DQS_DP<1>")
	)
	(arc
		(start 138.533632 -273.204432)
		(mid 138.38744 -273.185137)
		(end 138.251184 -273.12874)
		(width 0.088646)
		(layer "In6.Cu")
		(net "M_G_CPU1_SA_DQS_DP<1>")
	)
	(arc
		(start 135.05815 -273.12874)
		(mid 134.783951 -273.204575)
		(end 134.507478 -273.137376)
		(width 0.088646)
		(layer "In6.Cu")
		(net "M_G_CPU1_SA_DQS_DP<1>")
	)
	(arc
		(start 132.23875 -273.12874)
		(mid 131.956048 -273.204516)
		(end 131.673346 -273.12874)
		(width 0.088646)
		(layer "In6.Cu")
		(net "M_G_CPU1_SA_DQS_DP<1>")
	)
	(arc
		(start 135.997696 -273.12874)
		(mid 135.721137 -273.204483)
		(end 135.44296 -273.134836)
		(width 0.088646)
		(layer "In6.Cu")
		(net "M_G_CPU1_SA_DQS_DP<1>")
	)
	(arc
		(start 132.613146 -273.12874)
		(mid 132.425948 -273.078597)
		(end 132.23875 -273.12874)
		(width 0.088646)
		(layer "In6.Cu")
		(net "M_G_CPU1_SA_DQS_DP<1>")
	)
	(arc
		(start 137.866628 -273.134836)
		(mid 137.58845 -273.204559)
		(end 137.311892 -273.12874)
		(width 0.088646)
		(layer "In6.Cu")
		(net "M_G_CPU1_SA_DQS_DP<1>")
	)
	(arc
		(start 131.673346 -273.12874)
		(mid 131.486148 -273.078597)
		(end 131.29895 -273.12874)
		(width 0.088646)
		(layer "In6.Cu")
		(net "M_G_CPU1_SA_DQS_DP<1>")
	)
	(arc
		(start 127.901192 -273.120866)
		(mid 127.798847 -273.040703)
		(end 127.71755 -272.939256)
		(width 0.088646)
		(layer "In6.Cu")
		(net "M_G_CPU1_SA_DQS_DP<1>")
	)
	(arc
		(start 128.47955 -273.12874)
		(mid 128.205351 -273.204575)
		(end 127.928878 -273.137376)
		(width 0.088646)
		(layer "In6.Cu")
		(net "M_G_CPU1_SA_DQS_DP<1>")
	)
	(arc
		(start 129.41935 -273.12874)
		(mid 129.145151 -273.204575)
		(end 128.868678 -273.137376)
		(width 0.088646)
		(layer "In6.Cu")
		(net "M_G_CPU1_SA_DQS_DP<1>")
	)
	(arc
		(start 127.682498 -272.880328)
		(mid 127.664613 -272.843353)
		(end 127.653288 -272.803874)
		(width 0.088646)
		(layer "In6.Cu")
		(net "M_G_CPU1_SA_DQS_DP<1>")
	)
	(arc
		(start 130.733546 -273.12874)
		(mid 130.546348 -273.078597)
		(end 130.35915 -273.12874)
		(width 0.088646)
		(layer "In6.Cu")
		(net "M_G_CPU1_SA_DQS_DP<1>")
	)
	(arc
		(start 130.35915 -273.12874)
		(mid 130.084951 -273.204575)
		(end 129.808478 -273.137376)
		(width 0.088646)
		(layer "In6.Cu")
		(net "M_G_CPU1_SA_DQS_DP<1>")
	)
	(arc
		(start 131.29895 -273.12874)
		(mid 131.024751 -273.204575)
		(end 130.748278 -273.137376)
		(width 0.088646)
		(layer "In6.Cu")
		(net "M_G_CPU1_SA_DQS_DP<1>")
	)
	(arc
		(start 135.432546 -273.12874)
		(mid 135.245348 -273.078597)
		(end 135.05815 -273.12874)
		(width 0.088646)
		(layer "In6.Cu")
		(net "M_G_CPU1_SA_DQS_DP<1>")
	)
	(arc
		(start 138.251184 -273.12874)
		(mid 138.068933 -273.078629)
		(end 137.885424 -273.123914)
		(width 0.088646)
		(layer "In6.Cu")
		(net "M_G_CPU1_SA_DQS_DP<1>")
	)
	(arc
		(start 136.937496 -273.12874)
		(mid 136.654794 -273.204516)
		(end 136.372092 -273.12874)
		(width 0.088646)
		(layer "In6.Cu")
		(net "M_G_CPU1_SA_DQS_DP<1>")
	)
	(arc
		(start 129.793746 -273.12874)
		(mid 129.606548 -273.078597)
		(end 129.41935 -273.12874)
		(width 0.088646)
		(layer "In6.Cu")
		(net "M_G_CPU1_SA_DQS_DP<1>")
	)
	(arc
		(start 133.17855 -273.12874)
		(mid 132.904351 -273.204575)
		(end 132.627878 -273.137376)
		(width 0.088646)
		(layer "In6.Cu")
		(net "M_G_CPU1_SA_DQS_DP<1>")
	)
	(arc
		(start 127.90805 -273.125184)
		(mid 127.904613 -273.123037)
		(end 127.901192 -273.120866)
		(width 0.088646)
		(layer "In6.Cu")
		(net "M_G_CPU1_SA_DQS_DP<1>")
	)
	(arc
		(start 134.492746 -273.12874)
		(mid 134.305548 -273.078597)
		(end 134.11835 -273.12874)
		(width 0.088646)
		(layer "In6.Cu")
		(net "M_G_CPU1_SA_DQS_DP<1>")
	)
	(arc
		(start 137.311892 -273.12874)
		(mid 137.124694 -273.078597)
		(end 136.937496 -273.12874)
		(width 0.088646)
		(layer "In6.Cu")
		(net "M_G_CPU1_SA_DQS_DP<1>")
	)
	(arc
		(start 136.372092 -273.12874)
		(mid 136.184894 -273.078597)
		(end 135.997696 -273.12874)
		(width 0.088646)
		(layer "In6.Cu")
		(net "M_G_CPU1_SA_DQS_DP<1>")
	)
	(arc
		(start 133.552946 -273.12874)
		(mid 133.365748 -273.078597)
		(end 133.17855 -273.12874)
		(width 0.088646)
		(layer "In6.Cu")
		(net "M_G_CPU1_SA_DQS_DP<1>")
	)
	(arc
		(start 128.853946 -273.12874)
		(mid 128.666748 -273.078597)
		(end 128.47955 -273.12874)
		(width 0.088646)
		(layer "In6.Cu")
		(net "M_G_CPU1_SA_DQS_DP<1>")
	)
	(segment
		(start 191.770254 -313.341766)
		(end 191.9097 -313.341766)
		(width 0.20066)
		(layer "F.Cu")
		(net "M_G_CPU1_SA_DQS_DP<0>")
	)
	(segment
		(start 129.606548 -274.545044)
		(end 129.606548 -275.08073)
		(width 0.20066)
		(layer "F.Cu")
		(net "M_G_CPU1_SA_DQS_DP<0>")
	)
	(segment
		(start 189.577726 -312.91657)
		(end 189.818264 -312.676032)
		(width 0.20066)
		(layer "F.Cu")
		(net "M_G_CPU1_SA_DQS_DP<0>")
	)
	(segment
		(start 195.505832 -312.634884)
		(end 195.70192 -312.634884)
		(width 0.20066)
		(layer "F.Cu")
		(net "M_G_CPU1_SA_DQS_DP<0>")
	)
	(segment
		(start 190.41872 -312.676032)
		(end 190.833248 -313.09056)
		(width 0.20066)
		(layer "F.Cu")
		(net "M_G_CPU1_SA_DQS_DP<0>")
	)
	(segment
		(start 190.833248 -313.09056)
		(end 191.519048 -313.09056)
		(width 0.20066)
		(layer "F.Cu")
		(net "M_G_CPU1_SA_DQS_DP<0>")
	)
	(segment
		(start 195.70192 -312.634884)
		(end 195.983606 -312.91657)
		(width 0.20066)
		(layer "F.Cu")
		(net "M_G_CPU1_SA_DQS_DP<0>")
	)
	(segment
		(start 188.988446 -312.91657)
		(end 189.577726 -312.91657)
		(width 0.20066)
		(layer "F.Cu")
		(net "M_G_CPU1_SA_DQS_DP<0>")
	)
	(segment
		(start 187.883546 -312.91657)
		(end 188.988446 -312.91657)
		(width 0.20066)
		(layer "F.Cu")
		(net "M_G_CPU1_SA_DQS_DP<0>")
	)
	(segment
		(start 194.422268 -313.347862)
		(end 194.724782 -313.045348)
		(width 0.20066)
		(layer "F.Cu")
		(net "M_G_CPU1_SA_DQS_DP<0>")
	)
	(segment
		(start 194.09283 -313.341766)
		(end 194.098926 -313.347862)
		(width 0.1016)
		(layer "F.Cu")
		(net "M_G_CPU1_SA_DQS_DP<0>")
	)
	(segment
		(start 195.095368 -313.045348)
		(end 195.505832 -312.634884)
		(width 0.20066)
		(layer "F.Cu")
		(net "M_G_CPU1_SA_DQS_DP<0>")
	)
	(segment
		(start 191.9097 -313.341766)
		(end 191.935608 -313.341766)
		(width 0.101854)
		(layer "F.Cu")
		(net "M_G_CPU1_SA_DQS_DP<0>")
	)
	(segment
		(start 129.606294 -274.54479)
		(end 129.606548 -274.545044)
		(width 0.20066)
		(layer "F.Cu")
		(net "M_G_CPU1_SA_DQS_DP<0>")
	)
	(segment
		(start 191.935608 -313.341766)
		(end 194.09283 -313.341766)
		(width 0.1016)
		(layer "F.Cu")
		(net "M_G_CPU1_SA_DQS_DP<0>")
	)
	(segment
		(start 195.983606 -312.91657)
		(end 196.532246 -312.91657)
		(width 0.20066)
		(layer "F.Cu")
		(net "M_G_CPU1_SA_DQS_DP<0>")
	)
	(segment
		(start 194.724782 -313.045348)
		(end 195.095368 -313.045348)
		(width 0.20066)
		(layer "F.Cu")
		(net "M_G_CPU1_SA_DQS_DP<0>")
	)
	(segment
		(start 191.519048 -313.09056)
		(end 191.770254 -313.341766)
		(width 0.20066)
		(layer "F.Cu")
		(net "M_G_CPU1_SA_DQS_DP<0>")
	)
	(segment
		(start 194.098926 -313.347862)
		(end 194.422268 -313.347862)
		(width 0.20066)
		(layer "F.Cu")
		(net "M_G_CPU1_SA_DQS_DP<0>")
	)
	(segment
		(start 189.818264 -312.676032)
		(end 190.41872 -312.676032)
		(width 0.20066)
		(layer "F.Cu")
		(net "M_G_CPU1_SA_DQS_DP<0>")
	)
	(segment
		(start 184.347866 -312.478166)
		(end 182.263288 -313.341512)
		(width 0.18288)
		(layer "In4.Cu")
		(net "M_G_CPU1_SA_DQS_DP<0>")
	)
	(segment
		(start 179.986686 -313.341512)
		(end 179.430172 -313.898026)
		(width 0.18288)
		(layer "In4.Cu")
		(net "M_G_CPU1_SA_DQS_DP<0>")
	)
	(segment
		(start 169.487342 -313.753246)
		(end 168.402 -313.753246)
		(width 0.18288)
		(layer "In4.Cu")
		(net "M_G_CPU1_SA_DQS_DP<0>")
	)
	(segment
		(start 164.64788 -312.432446)
		(end 163.359846 -312.432446)
		(width 0.18288)
		(layer "In4.Cu")
		(net "M_G_CPU1_SA_DQS_DP<0>")
	)
	(segment
		(start 171.356274 -315.622178)
		(end 169.487342 -313.753246)
		(width 0.18288)
		(layer "In4.Cu")
		(net "M_G_CPU1_SA_DQS_DP<0>")
	)
	(segment
		(start 168.402 -313.753246)
		(end 167.908478 -313.259724)
		(width 0.18288)
		(layer "In4.Cu")
		(net "M_G_CPU1_SA_DQS_DP<0>")
	)
	(segment
		(start 161.498534 -311.426606)
		(end 160.642554 -310.570626)
		(width 0.18288)
		(layer "In4.Cu")
		(net "M_G_CPU1_SA_DQS_DP<0>")
	)
	(segment
		(start 136.559544 -276.718522)
		(end 136.559544 -276.708616)
		(width 0.088646)
		(layer "In4.Cu")
		(net "M_G_CPU1_SA_DQS_DP<0>")
	)
	(segment
		(start 148.166074 -297.36923)
		(end 142.372842 -283.385768)
		(width 0.18288)
		(layer "In4.Cu")
		(net "M_G_CPU1_SA_DQS_DP<0>")
	)
	(segment
		(start 187.022486 -312.478166)
		(end 184.347866 -312.478166)
		(width 0.18288)
		(layer "In4.Cu")
		(net "M_G_CPU1_SA_DQS_DP<0>")
	)
	(segment
		(start 166.644574 -313.259724)
		(end 164.64788 -312.432446)
		(width 0.18288)
		(layer "In4.Cu")
		(net "M_G_CPU1_SA_DQS_DP<0>")
	)
	(segment
		(start 172.601128 -315.891926)
		(end 172.33138 -315.622178)
		(width 0.18288)
		(layer "In4.Cu")
		(net "M_G_CPU1_SA_DQS_DP<0>")
	)
	(segment
		(start 142.32382 -283.267404)
		(end 142.323566 -283.266896)
		(width 0.18288)
		(layer "In4.Cu")
		(net "M_G_CPU1_SA_DQS_DP<0>")
	)
	(segment
		(start 162.354006 -311.426606)
		(end 161.498534 -311.426606)
		(width 0.18288)
		(layer "In4.Cu")
		(net "M_G_CPU1_SA_DQS_DP<0>")
	)
	(segment
		(start 177.987452 -314.771278)
		(end 177.358294 -314.771278)
		(width 0.18288)
		(layer "In4.Cu")
		(net "M_G_CPU1_SA_DQS_DP<0>")
	)
	(segment
		(start 176.412398 -314.76569)
		(end 175.05934 -314.76569)
		(width 0.18288)
		(layer "In4.Cu")
		(net "M_G_CPU1_SA_DQS_DP<0>")
	)
	(segment
		(start 131.768596 -275.570442)
		(end 131.753864 -275.579078)
		(width 0.088646)
		(layer "In4.Cu")
		(net "M_G_CPU1_SA_DQS_DP<0>")
	)
	(segment
		(start 173.281848 -315.60389)
		(end 172.993812 -315.891926)
		(width 0.18288)
		(layer "In4.Cu")
		(net "M_G_CPU1_SA_DQS_DP<0>")
	)
	(segment
		(start 187.607702 -312.640726)
		(end 187.185046 -312.640726)
		(width 0.18288)
		(layer "In4.Cu")
		(net "M_G_CPU1_SA_DQS_DP<0>")
	)
	(segment
		(start 136.380982 -276.389338)
		(end 136.372092 -276.384258)
		(width 0.088646)
		(layer "In4.Cu")
		(net "M_G_CPU1_SA_DQS_DP<0>")
	)
	(segment
		(start 158.035244 -309.071772)
		(end 156.433266 -309.071772)
		(width 0.18288)
		(layer "In4.Cu")
		(net "M_G_CPU1_SA_DQS_DP<0>")
	)
	(segment
		(start 187.883546 -312.91657)
		(end 187.607702 -312.640726)
		(width 0.18288)
		(layer "In4.Cu")
		(net "M_G_CPU1_SA_DQS_DP<0>")
	)
	(segment
		(start 176.688496 -315.041788)
		(end 176.412398 -314.76569)
		(width 0.18288)
		(layer "In4.Cu")
		(net "M_G_CPU1_SA_DQS_DP<0>")
	)
	(segment
		(start 138.260582 -278.017224)
		(end 138.251692 -278.012144)
		(width 0.088646)
		(layer "In4.Cu")
		(net "M_G_CPU1_SA_DQS_DP<0>")
	)
	(segment
		(start 142.372842 -283.385768)
		(end 142.32382 -283.267404)
		(width 0.18288)
		(layer "In4.Cu")
		(net "M_G_CPU1_SA_DQS_DP<0>")
	)
	(segment
		(start 130.828796 -275.570442)
		(end 130.814064 -275.579078)
		(width 0.088646)
		(layer "In4.Cu")
		(net "M_G_CPU1_SA_DQS_DP<0>")
	)
	(segment
		(start 135.428228 -276.381718)
		(end 135.42645 -276.380702)
		(width 0.088646)
		(layer "In4.Cu")
		(net "M_G_CPU1_SA_DQS_DP<0>")
	)
	(segment
		(start 139.441428 -278.901906)
		(end 139.00404 -278.901906)
		(width 0.088646)
		(layer "In4.Cu")
		(net "M_G_CPU1_SA_DQS_DP<0>")
	)
	(segment
		(start 177.358294 -314.771278)
		(end 177.087784 -315.041788)
		(width 0.18288)
		(layer "In4.Cu")
		(net "M_G_CPU1_SA_DQS_DP<0>")
	)
	(segment
		(start 160.642554 -310.570626)
		(end 159.534098 -310.570626)
		(width 0.18288)
		(layer "In4.Cu")
		(net "M_G_CPU1_SA_DQS_DP<0>")
	)
	(segment
		(start 156.433266 -309.071772)
		(end 155.084018 -307.722524)
		(width 0.18288)
		(layer "In4.Cu")
		(net "M_G_CPU1_SA_DQS_DP<0>")
	)
	(segment
		(start 137.029444 -277.540974)
		(end 137.029444 -277.522432)
		(width 0.088646)
		(layer "In4.Cu")
		(net "M_G_CPU1_SA_DQS_DP<0>")
	)
	(segment
		(start 172.993812 -315.891926)
		(end 172.601128 -315.891926)
		(width 0.18288)
		(layer "In4.Cu")
		(net "M_G_CPU1_SA_DQS_DP<0>")
	)
	(segment
		(start 129.9845 -275.145754)
		(end 129.919476 -275.08073)
		(width 0.088646)
		(layer "In4.Cu")
		(net "M_G_CPU1_SA_DQS_DP<0>")
	)
	(segment
		(start 163.359846 -312.432446)
		(end 162.354006 -311.426606)
		(width 0.18288)
		(layer "In4.Cu")
		(net "M_G_CPU1_SA_DQS_DP<0>")
	)
	(segment
		(start 178.860704 -313.898026)
		(end 177.987452 -314.771278)
		(width 0.18288)
		(layer "In4.Cu")
		(net "M_G_CPU1_SA_DQS_DP<0>")
	)
	(segment
		(start 139.923012 -279.38349)
		(end 139.441428 -278.901906)
		(width 0.088646)
		(layer "In4.Cu")
		(net "M_G_CPU1_SA_DQS_DP<0>")
	)
	(segment
		(start 167.908478 -313.259724)
		(end 166.644574 -313.259724)
		(width 0.18288)
		(layer "In4.Cu")
		(net "M_G_CPU1_SA_DQS_DP<0>")
	)
	(segment
		(start 172.33138 -315.622178)
		(end 171.356274 -315.622178)
		(width 0.18288)
		(layer "In4.Cu")
		(net "M_G_CPU1_SA_DQS_DP<0>")
	)
	(segment
		(start 139.939522 -279.484836)
		(end 139.923012 -279.468326)
		(width 0.088646)
		(layer "In4.Cu")
		(net "M_G_CPU1_SA_DQS_DP<0>")
	)
	(segment
		(start 174.22114 -315.60389)
		(end 173.281848 -315.60389)
		(width 0.18288)
		(layer "In4.Cu")
		(net "M_G_CPU1_SA_DQS_DP<0>")
	)
	(segment
		(start 141.334236 -280.878788)
		(end 139.939522 -279.484836)
		(width 0.18288)
		(layer "In4.Cu")
		(net "M_G_CPU1_SA_DQS_DP<0>")
	)
	(segment
		(start 187.185046 -312.640726)
		(end 187.022486 -312.478166)
		(width 0.18288)
		(layer "In4.Cu")
		(net "M_G_CPU1_SA_DQS_DP<0>")
	)
	(segment
		(start 159.534098 -310.570626)
		(end 158.035244 -309.071772)
		(width 0.18288)
		(layer "In4.Cu")
		(net "M_G_CPU1_SA_DQS_DP<0>")
	)
	(segment
		(start 129.919476 -275.08073)
		(end 129.606548 -275.08073)
		(width 0.088646)
		(layer "In4.Cu")
		(net "M_G_CPU1_SA_DQS_DP<0>")
	)
	(segment
		(start 132.708396 -275.570442)
		(end 132.693664 -275.579078)
		(width 0.088646)
		(layer "In4.Cu")
		(net "M_G_CPU1_SA_DQS_DP<0>")
	)
	(segment
		(start 177.087784 -315.041788)
		(end 176.688496 -315.041788)
		(width 0.18288)
		(layer "In4.Cu")
		(net "M_G_CPU1_SA_DQS_DP<0>")
	)
	(segment
		(start 142.323566 -283.266896)
		(end 141.334236 -280.878788)
		(width 0.18288)
		(layer "In4.Cu")
		(net "M_G_CPU1_SA_DQS_DP<0>")
	)
	(segment
		(start 136.850882 -277.203154)
		(end 136.841992 -277.198074)
		(width 0.088646)
		(layer "In4.Cu")
		(net "M_G_CPU1_SA_DQS_DP<0>")
	)
	(segment
		(start 175.05934 -314.76569)
		(end 174.22114 -315.60389)
		(width 0.18288)
		(layer "In4.Cu")
		(net "M_G_CPU1_SA_DQS_DP<0>")
	)
	(segment
		(start 135.44296 -276.390354)
		(end 135.428228 -276.381718)
		(width 0.088646)
		(layer "In4.Cu")
		(net "M_G_CPU1_SA_DQS_DP<0>")
	)
	(segment
		(start 179.430172 -313.898026)
		(end 178.860704 -313.898026)
		(width 0.18288)
		(layer "In4.Cu")
		(net "M_G_CPU1_SA_DQS_DP<0>")
	)
	(segment
		(start 139.923012 -279.468326)
		(end 139.923012 -279.38349)
		(width 0.088646)
		(layer "In4.Cu")
		(net "M_G_CPU1_SA_DQS_DP<0>")
	)
	(segment
		(start 138.439144 -278.351996)
		(end 138.439144 -278.336502)
		(width 0.088646)
		(layer "In4.Cu")
		(net "M_G_CPU1_SA_DQS_DP<0>")
	)
	(segment
		(start 155.084018 -307.722524)
		(end 148.166074 -297.36923)
		(width 0.18288)
		(layer "In4.Cu")
		(net "M_G_CPU1_SA_DQS_DP<0>")
	)
	(segment
		(start 182.263288 -313.341512)
		(end 179.986686 -313.341512)
		(width 0.18288)
		(layer "In4.Cu")
		(net "M_G_CPU1_SA_DQS_DP<0>")
	)
	(segment
		(start 134.587996 -275.570442)
		(end 134.573264 -275.579078)
		(width 0.088646)
		(layer "In4.Cu")
		(net "M_G_CPU1_SA_DQS_DP<0>")
	)
	(arc
		(start 130.814064 -275.579078)
		(mid 130.294089 -275.587082)
		(end 129.987294 -275.16709)
		(width 0.088646)
		(layer "In4.Cu")
		(net "M_G_CPU1_SA_DQS_DP<0>")
	)
	(arc
		(start 129.987294 -275.16709)
		(mid 129.985796 -275.156435)
		(end 129.9845 -275.145754)
		(width 0.088646)
		(layer "In4.Cu")
		(net "M_G_CPU1_SA_DQS_DP<0>")
	)
	(arc
		(start 136.841992 -277.198074)
		(mid 136.637657 -276.995469)
		(end 136.559544 -276.718522)
		(width 0.088646)
		(layer "In4.Cu")
		(net "M_G_CPU1_SA_DQS_DP<0>")
	)
	(arc
		(start 131.753864 -275.579078)
		(mid 131.477423 -275.646244)
		(end 131.203192 -275.570442)
		(width 0.088646)
		(layer "In4.Cu")
		(net "M_G_CPU1_SA_DQS_DP<0>")
	)
	(arc
		(start 139.00404 -278.901906)
		(mid 138.609918 -278.741656)
		(end 138.439144 -278.351996)
		(width 0.088646)
		(layer "In4.Cu")
		(net "M_G_CPU1_SA_DQS_DP<0>")
	)
	(arc
		(start 132.693664 -275.579078)
		(mid 132.417223 -275.646244)
		(end 132.142992 -275.570442)
		(width 0.088646)
		(layer "In4.Cu")
		(net "M_G_CPU1_SA_DQS_DP<0>")
	)
	(arc
		(start 135.149844 -275.8948)
		(mid 134.962545 -275.570359)
		(end 134.587996 -275.570442)
		(width 0.088646)
		(layer "In4.Cu")
		(net "M_G_CPU1_SA_DQS_DP<0>")
	)
	(arc
		(start 137.029444 -277.522432)
		(mid 136.981765 -277.339532)
		(end 136.850882 -277.203154)
		(width 0.088646)
		(layer "In4.Cu")
		(net "M_G_CPU1_SA_DQS_DP<0>")
	)
	(arc
		(start 134.022592 -275.570442)
		(mid 133.835394 -275.520299)
		(end 133.648196 -275.570442)
		(width 0.088646)
		(layer "In4.Cu")
		(net "M_G_CPU1_SA_DQS_DP<0>")
	)
	(arc
		(start 137.877296 -278.012144)
		(mid 137.594594 -278.087886)
		(end 137.311892 -278.012144)
		(width 0.088646)
		(layer "In4.Cu")
		(net "M_G_CPU1_SA_DQS_DP<0>")
	)
	(arc
		(start 131.203192 -275.570442)
		(mid 131.015994 -275.520299)
		(end 130.828796 -275.570442)
		(width 0.088646)
		(layer "In4.Cu")
		(net "M_G_CPU1_SA_DQS_DP<0>")
	)
	(arc
		(start 132.142992 -275.570442)
		(mid 131.955794 -275.520299)
		(end 131.768596 -275.570442)
		(width 0.088646)
		(layer "In4.Cu")
		(net "M_G_CPU1_SA_DQS_DP<0>")
	)
	(arc
		(start 138.251692 -278.012144)
		(mid 138.064494 -277.962001)
		(end 137.877296 -278.012144)
		(width 0.088646)
		(layer "In4.Cu")
		(net "M_G_CPU1_SA_DQS_DP<0>")
	)
	(arc
		(start 136.559544 -276.708616)
		(mid 136.511865 -276.525716)
		(end 136.380982 -276.389338)
		(width 0.088646)
		(layer "In4.Cu")
		(net "M_G_CPU1_SA_DQS_DP<0>")
	)
	(arc
		(start 137.311892 -278.012144)
		(mid 137.109606 -277.813163)
		(end 137.029444 -277.540974)
		(width 0.088646)
		(layer "In4.Cu")
		(net "M_G_CPU1_SA_DQS_DP<0>")
	)
	(arc
		(start 134.573264 -275.579078)
		(mid 134.296823 -275.646244)
		(end 134.022592 -275.570442)
		(width 0.088646)
		(layer "In4.Cu")
		(net "M_G_CPU1_SA_DQS_DP<0>")
	)
	(arc
		(start 138.439144 -278.336502)
		(mid 138.391465 -278.153602)
		(end 138.260582 -278.017224)
		(width 0.088646)
		(layer "In4.Cu")
		(net "M_G_CPU1_SA_DQS_DP<0>")
	)
	(arc
		(start 133.648196 -275.570442)
		(mid 133.365494 -275.646184)
		(end 133.082792 -275.570442)
		(width 0.088646)
		(layer "In4.Cu")
		(net "M_G_CPU1_SA_DQS_DP<0>")
	)
	(arc
		(start 135.997696 -276.384258)
		(mid 135.721137 -276.460001)
		(end 135.44296 -276.390354)
		(width 0.088646)
		(layer "In4.Cu")
		(net "M_G_CPU1_SA_DQS_DP<0>")
	)
	(arc
		(start 135.42645 -276.380702)
		(mid 135.223863 -276.174351)
		(end 135.149844 -275.8948)
		(width 0.088646)
		(layer "In4.Cu")
		(net "M_G_CPU1_SA_DQS_DP<0>")
	)
	(arc
		(start 136.372092 -276.384258)
		(mid 136.184894 -276.334115)
		(end 135.997696 -276.384258)
		(width 0.088646)
		(layer "In4.Cu")
		(net "M_G_CPU1_SA_DQS_DP<0>")
	)
	(arc
		(start 133.082792 -275.570442)
		(mid 132.895594 -275.520299)
		(end 132.708396 -275.570442)
		(width 0.088646)
		(layer "In4.Cu")
		(net "M_G_CPU1_SA_DQS_DP<0>")
	)
	(segment
		(start 194.373754 -274.395438)
		(end 194.798696 -273.970496)
		(width 0.20066)
		(layer "F.Cu")
		(net "M_G_CPU1_SA_DQS_DN<9>")
	)
	(segment
		(start 195.343018 -274.241768)
		(end 195.52158 -274.241768)
		(width 0.101854)
		(layer "F.Cu")
		(net "M_G_CPU1_SA_DQS_DN<9>")
	)
	(segment
		(start 193.890392 -274.395438)
		(end 194.373754 -274.395438)
		(width 0.20066)
		(layer "F.Cu")
		(net "M_G_CPU1_SA_DQS_DN<9>")
	)
	(segment
		(start 197.87235 -274.241768)
		(end 198.147178 -273.96694)
		(width 0.20066)
		(layer "F.Cu")
		(net "M_G_CPU1_SA_DQS_DN<9>")
	)
	(segment
		(start 194.798696 -273.970496)
		(end 194.92722 -273.970496)
		(width 0.20066)
		(layer "F.Cu")
		(net "M_G_CPU1_SA_DQS_DN<9>")
	)
	(segment
		(start 191.983614 -274.66671)
		(end 193.088514 -274.66671)
		(width 0.20066)
		(layer "F.Cu")
		(net "M_G_CPU1_SA_DQS_DN<9>")
	)
	(segment
		(start 197.750684 -274.241768)
		(end 197.87235 -274.241768)
		(width 0.20066)
		(layer "F.Cu")
		(net "M_G_CPU1_SA_DQS_DN<9>")
	)
	(segment
		(start 193.61912 -274.66671)
		(end 193.890392 -274.395438)
		(width 0.20066)
		(layer "F.Cu")
		(net "M_G_CPU1_SA_DQS_DN<9>")
	)
	(segment
		(start 198.637144 -273.96694)
		(end 199.08266 -274.412456)
		(width 0.20066)
		(layer "F.Cu")
		(net "M_G_CPU1_SA_DQS_DN<9>")
	)
	(segment
		(start 129.136648 -262.87222)
		(end 129.136394 -262.872474)
		(width 0.20066)
		(layer "F.Cu")
		(net "M_G_CPU1_SA_DQS_DN<9>")
	)
	(segment
		(start 195.52158 -274.241768)
		(end 197.531736 -274.241768)
		(width 0.1016)
		(layer "F.Cu")
		(net "M_G_CPU1_SA_DQS_DN<9>")
	)
	(segment
		(start 199.874378 -274.412456)
		(end 200.128632 -274.66671)
		(width 0.20066)
		(layer "F.Cu")
		(net "M_G_CPU1_SA_DQS_DN<9>")
	)
	(segment
		(start 200.128632 -274.66671)
		(end 200.632314 -274.66671)
		(width 0.20066)
		(layer "F.Cu")
		(net "M_G_CPU1_SA_DQS_DN<9>")
	)
	(segment
		(start 194.92722 -273.970496)
		(end 195.198492 -274.241768)
		(width 0.20066)
		(layer "F.Cu")
		(net "M_G_CPU1_SA_DQS_DN<9>")
	)
	(segment
		(start 199.08266 -274.412456)
		(end 199.874378 -274.412456)
		(width 0.20066)
		(layer "F.Cu")
		(net "M_G_CPU1_SA_DQS_DN<9>")
	)
	(segment
		(start 198.147178 -273.96694)
		(end 198.637144 -273.96694)
		(width 0.20066)
		(layer "F.Cu")
		(net "M_G_CPU1_SA_DQS_DN<9>")
	)
	(segment
		(start 129.136648 -262.336534)
		(end 129.136648 -262.87222)
		(width 0.20066)
		(layer "F.Cu")
		(net "M_G_CPU1_SA_DQS_DN<9>")
	)
	(segment
		(start 193.088514 -274.66671)
		(end 193.61912 -274.66671)
		(width 0.20066)
		(layer "F.Cu")
		(net "M_G_CPU1_SA_DQS_DN<9>")
	)
	(segment
		(start 197.531736 -274.241768)
		(end 197.750684 -274.241768)
		(width 0.101854)
		(layer "F.Cu")
		(net "M_G_CPU1_SA_DQS_DN<9>")
	)
	(segment
		(start 195.198492 -274.241768)
		(end 195.343018 -274.241768)
		(width 0.20066)
		(layer "F.Cu")
		(net "M_G_CPU1_SA_DQS_DN<9>")
	)
	(segment
		(start 145.15592 -262.292592)
		(end 142.871698 -261.838186)
		(width 0.18288)
		(layer "In6.Cu")
		(net "M_G_CPU1_SA_DQS_DN<9>")
	)
	(segment
		(start 160.308036 -263.193784)
		(end 159.166306 -263.193784)
		(width 0.18288)
		(layer "In6.Cu")
		(net "M_G_CPU1_SA_DQS_DN<9>")
	)
	(segment
		(start 183.640222 -271.54378)
		(end 183.640222 -269.629382)
		(width 0.18288)
		(layer "In6.Cu")
		(net "M_G_CPU1_SA_DQS_DN<9>")
	)
	(segment
		(start 181.699916 -264.893806)
		(end 181.153816 -264.893806)
		(width 0.18288)
		(layer "In6.Cu")
		(net "M_G_CPU1_SA_DQS_DN<9>")
	)
	(segment
		(start 167.76446 -263.178798)
		(end 166.620698 -263.178798)
		(width 0.18288)
		(layer "In6.Cu")
		(net "M_G_CPU1_SA_DQS_DN<9>")
	)
	(segment
		(start 188.100716 -274.240752)
		(end 187.589922 -274.240752)
		(width 0.18288)
		(layer "In6.Cu")
		(net "M_G_CPU1_SA_DQS_DN<9>")
	)
	(segment
		(start 130.828796 -262.548116)
		(end 130.814064 -262.556752)
		(width 0.088646)
		(layer "In6.Cu")
		(net "M_G_CPU1_SA_DQS_DN<9>")
	)
	(segment
		(start 183.640222 -269.629382)
		(end 183.515762 -269.504922)
		(width 0.18288)
		(layer "In6.Cu")
		(net "M_G_CPU1_SA_DQS_DN<9>")
	)
	(segment
		(start 140.393166 -261.778242)
		(end 140.298424 -261.6835)
		(width 0.088646)
		(layer "In6.Cu")
		(net "M_G_CPU1_SA_DQS_DN<9>")
	)
	(segment
		(start 139.569444 -262.058404)
		(end 139.569444 -262.074152)
		(width 0.088646)
		(layer "In6.Cu")
		(net "M_G_CPU1_SA_DQS_DN<9>")
	)
	(segment
		(start 162.896042 -263.78408)
		(end 162.349942 -263.78408)
		(width 0.18288)
		(layer "In6.Cu")
		(net "M_G_CPU1_SA_DQS_DN<9>")
	)
	(segment
		(start 186.812428 -274.003516)
		(end 185.95594 -273.647408)
		(width 0.18288)
		(layer "In6.Cu")
		(net "M_G_CPU1_SA_DQS_DN<9>")
	)
	(segment
		(start 130.263646 -262.54837)
		(end 130.263392 -262.548116)
		(width 0.088646)
		(layer "In6.Cu")
		(net "M_G_CPU1_SA_DQS_DN<9>")
	)
	(segment
		(start 140.877036 -261.838186)
		(end 140.817092 -261.778242)
		(width 0.088646)
		(layer "In6.Cu")
		(net "M_G_CPU1_SA_DQS_DN<9>")
	)
	(segment
		(start 178.146456 -264.645902)
		(end 177.410364 -264.645902)
		(width 0.18288)
		(layer "In6.Cu")
		(net "M_G_CPU1_SA_DQS_DN<9>")
	)
	(segment
		(start 129.193036 -262.666734)
		(end 129.136394 -262.723376)
		(width 0.088646)
		(layer "In6.Cu")
		(net "M_G_CPU1_SA_DQS_DN<9>")
	)
	(segment
		(start 181.029356 -264.769346)
		(end 179.876196 -264.769346)
		(width 0.18288)
		(layer "In6.Cu")
		(net "M_G_CPU1_SA_DQS_DN<9>")
	)
	(segment
		(start 187.352686 -274.003516)
		(end 186.812428 -274.003516)
		(width 0.18288)
		(layer "In6.Cu")
		(net "M_G_CPU1_SA_DQS_DN<9>")
	)
	(segment
		(start 159.166306 -263.193784)
		(end 159.041846 -263.318244)
		(width 0.18288)
		(layer "In6.Cu")
		(net "M_G_CPU1_SA_DQS_DN<9>")
	)
	(segment
		(start 129.554732 -262.666734)
		(end 129.193036 -262.666734)
		(width 0.088646)
		(layer "In6.Cu")
		(net "M_G_CPU1_SA_DQS_DN<9>")
	)
	(segment
		(start 164.842444 -263.178798)
		(end 164.237162 -263.78408)
		(width 0.18288)
		(layer "In6.Cu")
		(net "M_G_CPU1_SA_DQS_DN<9>")
	)
	(segment
		(start 134.587996 -262.548116)
		(end 134.573264 -262.556752)
		(width 0.088646)
		(layer "In6.Cu")
		(net "M_G_CPU1_SA_DQS_DN<9>")
	)
	(segment
		(start 183.515762 -269.504922)
		(end 183.515762 -268.958822)
		(width 0.18288)
		(layer "In6.Cu")
		(net "M_G_CPU1_SA_DQS_DN<9>")
	)
	(segment
		(start 185.95594 -273.647408)
		(end 185.158634 -272.85061)
		(width 0.18288)
		(layer "In6.Cu")
		(net "M_G_CPU1_SA_DQS_DN<9>")
	)
	(segment
		(start 129.773172 -262.61568)
		(end 129.554732 -262.666734)
		(width 0.088646)
		(layer "In6.Cu")
		(net "M_G_CPU1_SA_DQS_DN<9>")
	)
	(segment
		(start 131.76885 -262.548116)
		(end 131.758436 -262.554212)
		(width 0.088646)
		(layer "In6.Cu")
		(net "M_G_CPU1_SA_DQS_DN<9>")
	)
	(segment
		(start 132.15366 -262.554212)
		(end 132.143246 -262.548116)
		(width 0.088646)
		(layer "In6.Cu")
		(net "M_G_CPU1_SA_DQS_DN<9>")
	)
	(segment
		(start 156.187648 -262.292592)
		(end 145.15592 -262.292592)
		(width 0.18288)
		(layer "In6.Cu")
		(net "M_G_CPU1_SA_DQS_DN<9>")
	)
	(segment
		(start 160.898332 -263.78408)
		(end 160.308036 -263.193784)
		(width 0.18288)
		(layer "In6.Cu")
		(net "M_G_CPU1_SA_DQS_DN<9>")
	)
	(segment
		(start 188.604652 -273.976846)
		(end 188.364622 -273.976846)
		(width 0.18288)
		(layer "In6.Cu")
		(net "M_G_CPU1_SA_DQS_DN<9>")
	)
	(segment
		(start 170.12412 -263.918192)
		(end 169.99966 -263.793732)
		(width 0.18288)
		(layer "In6.Cu")
		(net "M_G_CPU1_SA_DQS_DN<9>")
	)
	(segment
		(start 133.648196 -262.548116)
		(end 133.633464 -262.556752)
		(width 0.088646)
		(layer "In6.Cu")
		(net "M_G_CPU1_SA_DQS_DN<9>")
	)
	(segment
		(start 139.756896 -261.7343)
		(end 139.742672 -261.742428)
		(width 0.088646)
		(layer "In6.Cu")
		(net "M_G_CPU1_SA_DQS_DN<9>")
	)
	(segment
		(start 170.67022 -263.918192)
		(end 170.12412 -263.918192)
		(width 0.18288)
		(layer "In6.Cu")
		(net "M_G_CPU1_SA_DQS_DN<9>")
	)
	(segment
		(start 183.640222 -268.288262)
		(end 183.515762 -268.163802)
		(width 0.18288)
		(layer "In6.Cu")
		(net "M_G_CPU1_SA_DQS_DN<9>")
	)
	(segment
		(start 163.566602 -263.90854)
		(end 163.020502 -263.90854)
		(width 0.18288)
		(layer "In6.Cu")
		(net "M_G_CPU1_SA_DQS_DN<9>")
	)
	(segment
		(start 157.08884 -263.193784)
		(end 156.187648 -262.292592)
		(width 0.18288)
		(layer "In6.Cu")
		(net "M_G_CPU1_SA_DQS_DN<9>")
	)
	(segment
		(start 176.685956 -264.883138)
		(end 176.661572 -264.883138)
		(width 0.18288)
		(layer "In6.Cu")
		(net "M_G_CPU1_SA_DQS_DN<9>")
	)
	(segment
		(start 172.542708 -264.040874)
		(end 172.295566 -263.793732)
		(width 0.18288)
		(layer "In6.Cu")
		(net "M_G_CPU1_SA_DQS_DN<9>")
	)
	(segment
		(start 166.620698 -263.178798)
		(end 166.496238 -263.303258)
		(width 0.18288)
		(layer "In6.Cu")
		(net "M_G_CPU1_SA_DQS_DN<9>")
	)
	(segment
		(start 190.303404 -273.394932)
		(end 190.009018 -273.394932)
		(width 0.18288)
		(layer "In6.Cu")
		(net "M_G_CPU1_SA_DQS_DN<9>")
	)
	(segment
		(start 188.364622 -273.976846)
		(end 188.100716 -274.240752)
		(width 0.18288)
		(layer "In6.Cu")
		(net "M_G_CPU1_SA_DQS_DN<9>")
	)
	(segment
		(start 183.515762 -266.276582)
		(end 183.640222 -266.152122)
		(width 0.18288)
		(layer "In6.Cu")
		(net "M_G_CPU1_SA_DQS_DN<9>")
	)
	(segment
		(start 162.349942 -263.78408)
		(end 162.225482 -263.90854)
		(width 0.18288)
		(layer "In6.Cu")
		(net "M_G_CPU1_SA_DQS_DN<9>")
	)
	(segment
		(start 163.691062 -263.78408)
		(end 163.566602 -263.90854)
		(width 0.18288)
		(layer "In6.Cu")
		(net "M_G_CPU1_SA_DQS_DN<9>")
	)
	(segment
		(start 176.693576 -264.890758)
		(end 176.685956 -264.883138)
		(width 0.18288)
		(layer "In6.Cu")
		(net "M_G_CPU1_SA_DQS_DN<9>")
	)
	(segment
		(start 129.88798 -262.548624)
		(end 129.773172 -262.61568)
		(width 0.088646)
		(layer "In6.Cu")
		(net "M_G_CPU1_SA_DQS_DN<9>")
	)
	(segment
		(start 158.495746 -263.318244)
		(end 158.371286 -263.193784)
		(width 0.18288)
		(layer "In6.Cu")
		(net "M_G_CPU1_SA_DQS_DN<9>")
	)
	(segment
		(start 187.589922 -274.240752)
		(end 187.352686 -274.003516)
		(width 0.18288)
		(layer "In6.Cu")
		(net "M_G_CPU1_SA_DQS_DN<9>")
	)
	(segment
		(start 184.07507 -272.269966)
		(end 183.706262 -271.65427)
		(width 0.18288)
		(layer "In6.Cu")
		(net "M_G_CPU1_SA_DQS_DN<9>")
	)
	(segment
		(start 191.724026 -274.407122)
		(end 191.315594 -274.407122)
		(width 0.18288)
		(layer "In6.Cu")
		(net "M_G_CPU1_SA_DQS_DN<9>")
	)
	(segment
		(start 165.825678 -263.178798)
		(end 164.842444 -263.178798)
		(width 0.18288)
		(layer "In6.Cu")
		(net "M_G_CPU1_SA_DQS_DN<9>")
	)
	(segment
		(start 183.640222 -267.493242)
		(end 183.640222 -266.947142)
		(width 0.18288)
		(layer "In6.Cu")
		(net "M_G_CPU1_SA_DQS_DN<9>")
	)
	(segment
		(start 142.871698 -261.838186)
		(end 140.900404 -261.838186)
		(width 0.18288)
		(layer "In6.Cu")
		(net "M_G_CPU1_SA_DQS_DN<9>")
	)
	(segment
		(start 178.772312 -265.271758)
		(end 178.146456 -264.645902)
		(width 0.18288)
		(layer "In6.Cu")
		(net "M_G_CPU1_SA_DQS_DN<9>")
	)
	(segment
		(start 166.496238 -263.303258)
		(end 165.950138 -263.303258)
		(width 0.18288)
		(layer "In6.Cu")
		(net "M_G_CPU1_SA_DQS_DN<9>")
	)
	(segment
		(start 181.824376 -264.769346)
		(end 181.699916 -264.893806)
		(width 0.18288)
		(layer "In6.Cu")
		(net "M_G_CPU1_SA_DQS_DN<9>")
	)
	(segment
		(start 183.640222 -266.152122)
		(end 183.640222 -265.753342)
		(width 0.18288)
		(layer "In6.Cu")
		(net "M_G_CPU1_SA_DQS_DN<9>")
	)
	(segment
		(start 173.90364 -263.750298)
		(end 173.324266 -263.750298)
		(width 0.18288)
		(layer "In6.Cu")
		(net "M_G_CPU1_SA_DQS_DN<9>")
	)
	(segment
		(start 183.640222 -265.753342)
		(end 182.656226 -264.769346)
		(width 0.18288)
		(layer "In6.Cu")
		(net "M_G_CPU1_SA_DQS_DN<9>")
	)
	(segment
		(start 176.661572 -264.883138)
		(end 176.388268 -264.609834)
		(width 0.18288)
		(layer "In6.Cu")
		(net "M_G_CPU1_SA_DQS_DN<9>")
	)
	(segment
		(start 173.324266 -263.750298)
		(end 173.03369 -264.040874)
		(width 0.18288)
		(layer "In6.Cu")
		(net "M_G_CPU1_SA_DQS_DN<9>")
	)
	(segment
		(start 185.158634 -272.85061)
		(end 184.07507 -272.269966)
		(width 0.18288)
		(layer "In6.Cu")
		(net "M_G_CPU1_SA_DQS_DN<9>")
	)
	(segment
		(start 177.410364 -264.645902)
		(end 177.165508 -264.890758)
		(width 0.18288)
		(layer "In6.Cu")
		(net "M_G_CPU1_SA_DQS_DN<9>")
	)
	(segment
		(start 161.554922 -263.78408)
		(end 160.898332 -263.78408)
		(width 0.18288)
		(layer "In6.Cu")
		(net "M_G_CPU1_SA_DQS_DN<9>")
	)
	(segment
		(start 177.165508 -264.890758)
		(end 176.693576 -264.890758)
		(width 0.18288)
		(layer "In6.Cu")
		(net "M_G_CPU1_SA_DQS_DN<9>")
	)
	(segment
		(start 183.515762 -268.958822)
		(end 183.640222 -268.834362)
		(width 0.18288)
		(layer "In6.Cu")
		(net "M_G_CPU1_SA_DQS_DN<9>")
	)
	(segment
		(start 164.237162 -263.78408)
		(end 163.691062 -263.78408)
		(width 0.18288)
		(layer "In6.Cu")
		(net "M_G_CPU1_SA_DQS_DN<9>")
	)
	(segment
		(start 183.640222 -268.834362)
		(end 183.640222 -268.288262)
		(width 0.18288)
		(layer "In6.Cu")
		(net "M_G_CPU1_SA_DQS_DN<9>")
	)
	(segment
		(start 165.950138 -263.303258)
		(end 165.825678 -263.178798)
		(width 0.18288)
		(layer "In6.Cu")
		(net "M_G_CPU1_SA_DQS_DN<9>")
	)
	(segment
		(start 190.009018 -273.394932)
		(end 188.604652 -273.976846)
		(width 0.18288)
		(layer "In6.Cu")
		(net "M_G_CPU1_SA_DQS_DN<9>")
	)
	(segment
		(start 137.792206 -262.554212)
		(end 137.781792 -262.548116)
		(width 0.088646)
		(layer "In6.Cu")
		(net "M_G_CPU1_SA_DQS_DN<9>")
	)
	(segment
		(start 181.153816 -264.893806)
		(end 181.029356 -264.769346)
		(width 0.18288)
		(layer "In6.Cu")
		(net "M_G_CPU1_SA_DQS_DN<9>")
	)
	(segment
		(start 183.515762 -268.163802)
		(end 183.515762 -267.617702)
		(width 0.18288)
		(layer "In6.Cu")
		(net "M_G_CPU1_SA_DQS_DN<9>")
	)
	(segment
		(start 140.817092 -261.778242)
		(end 140.393166 -261.778242)
		(width 0.088646)
		(layer "In6.Cu")
		(net "M_G_CPU1_SA_DQS_DN<9>")
	)
	(segment
		(start 174.763176 -264.609834)
		(end 173.90364 -263.750298)
		(width 0.18288)
		(layer "In6.Cu")
		(net "M_G_CPU1_SA_DQS_DN<9>")
	)
	(segment
		(start 162.225482 -263.90854)
		(end 161.679382 -263.90854)
		(width 0.18288)
		(layer "In6.Cu")
		(net "M_G_CPU1_SA_DQS_DN<9>")
	)
	(segment
		(start 183.515762 -267.617702)
		(end 183.640222 -267.493242)
		(width 0.18288)
		(layer "In6.Cu")
		(net "M_G_CPU1_SA_DQS_DN<9>")
	)
	(segment
		(start 172.295566 -263.793732)
		(end 170.79468 -263.793732)
		(width 0.18288)
		(layer "In6.Cu")
		(net "M_G_CPU1_SA_DQS_DN<9>")
	)
	(segment
		(start 161.679382 -263.90854)
		(end 161.554922 -263.78408)
		(width 0.18288)
		(layer "In6.Cu")
		(net "M_G_CPU1_SA_DQS_DN<9>")
	)
	(segment
		(start 129.888996 -262.548116)
		(end 129.88798 -262.548624)
		(width 0.088646)
		(layer "In6.Cu")
		(net "M_G_CPU1_SA_DQS_DN<9>")
	)
	(segment
		(start 140.900404 -261.838186)
		(end 140.877036 -261.838186)
		(width 0.088646)
		(layer "In6.Cu")
		(net "M_G_CPU1_SA_DQS_DN<9>")
	)
	(segment
		(start 173.03369 -264.040874)
		(end 172.542708 -264.040874)
		(width 0.18288)
		(layer "In6.Cu")
		(net "M_G_CPU1_SA_DQS_DN<9>")
	)
	(segment
		(start 159.041846 -263.318244)
		(end 158.495746 -263.318244)
		(width 0.18288)
		(layer "In6.Cu")
		(net "M_G_CPU1_SA_DQS_DN<9>")
	)
	(segment
		(start 176.388268 -264.609834)
		(end 174.763176 -264.609834)
		(width 0.18288)
		(layer "In6.Cu")
		(net "M_G_CPU1_SA_DQS_DN<9>")
	)
	(segment
		(start 183.640222 -266.947142)
		(end 183.515762 -266.822682)
		(width 0.18288)
		(layer "In6.Cu")
		(net "M_G_CPU1_SA_DQS_DN<9>")
	)
	(segment
		(start 158.371286 -263.193784)
		(end 157.08884 -263.193784)
		(width 0.18288)
		(layer "In6.Cu")
		(net "M_G_CPU1_SA_DQS_DN<9>")
	)
	(segment
		(start 170.79468 -263.793732)
		(end 170.67022 -263.918192)
		(width 0.18288)
		(layer "In6.Cu")
		(net "M_G_CPU1_SA_DQS_DN<9>")
	)
	(segment
		(start 163.020502 -263.90854)
		(end 162.896042 -263.78408)
		(width 0.18288)
		(layer "In6.Cu")
		(net "M_G_CPU1_SA_DQS_DN<9>")
	)
	(segment
		(start 183.515762 -266.822682)
		(end 183.515762 -266.276582)
		(width 0.18288)
		(layer "In6.Cu")
		(net "M_G_CPU1_SA_DQS_DN<9>")
	)
	(segment
		(start 129.136394 -262.723376)
		(end 129.136394 -262.872474)
		(width 0.088646)
		(layer "In6.Cu")
		(net "M_G_CPU1_SA_DQS_DN<9>")
	)
	(segment
		(start 138.736578 -262.556752)
		(end 138.721846 -262.548116)
		(width 0.088646)
		(layer "In6.Cu")
		(net "M_G_CPU1_SA_DQS_DN<9>")
	)
	(segment
		(start 169.99966 -263.793732)
		(end 168.379394 -263.793732)
		(width 0.18288)
		(layer "In6.Cu")
		(net "M_G_CPU1_SA_DQS_DN<9>")
	)
	(segment
		(start 179.373784 -265.271758)
		(end 178.772312 -265.271758)
		(width 0.18288)
		(layer "In6.Cu")
		(net "M_G_CPU1_SA_DQS_DN<9>")
	)
	(segment
		(start 191.983614 -274.66671)
		(end 191.724026 -274.407122)
		(width 0.18288)
		(layer "In6.Cu")
		(net "M_G_CPU1_SA_DQS_DN<9>")
	)
	(segment
		(start 191.315594 -274.407122)
		(end 190.303404 -273.394932)
		(width 0.18288)
		(layer "In6.Cu")
		(net "M_G_CPU1_SA_DQS_DN<9>")
	)
	(segment
		(start 140.298424 -261.6835)
		(end 139.944094 -261.6835)
		(width 0.088646)
		(layer "In6.Cu")
		(net "M_G_CPU1_SA_DQS_DN<9>")
	)
	(segment
		(start 168.379394 -263.793732)
		(end 167.76446 -263.178798)
		(width 0.18288)
		(layer "In6.Cu")
		(net "M_G_CPU1_SA_DQS_DN<9>")
	)
	(segment
		(start 179.876196 -264.769346)
		(end 179.373784 -265.271758)
		(width 0.18288)
		(layer "In6.Cu")
		(net "M_G_CPU1_SA_DQS_DN<9>")
	)
	(segment
		(start 183.706262 -271.65427)
		(end 183.640222 -271.54378)
		(width 0.18288)
		(layer "In6.Cu")
		(net "M_G_CPU1_SA_DQS_DN<9>")
	)
	(segment
		(start 182.656226 -264.769346)
		(end 181.824376 -264.769346)
		(width 0.18288)
		(layer "In6.Cu")
		(net "M_G_CPU1_SA_DQS_DN<9>")
	)
	(arc
		(start 133.633464 -262.556752)
		(mid 133.356989 -262.624072)
		(end 133.082792 -262.548116)
		(width 0.088646)
		(layer "In6.Cu")
		(net "M_G_CPU1_SA_DQS_DN<9>")
	)
	(arc
		(start 135.527796 -262.548116)
		(mid 135.245094 -262.623892)
		(end 134.962392 -262.548116)
		(width 0.088646)
		(layer "In6.Cu")
		(net "M_G_CPU1_SA_DQS_DN<9>")
	)
	(arc
		(start 138.34745 -262.548116)
		(mid 138.070637 -262.623986)
		(end 137.792206 -262.554212)
		(width 0.088646)
		(layer "In6.Cu")
		(net "M_G_CPU1_SA_DQS_DN<9>")
	)
	(arc
		(start 134.022592 -262.548116)
		(mid 133.835394 -262.497973)
		(end 133.648196 -262.548116)
		(width 0.088646)
		(layer "In6.Cu")
		(net "M_G_CPU1_SA_DQS_DN<9>")
	)
	(arc
		(start 133.082792 -262.548116)
		(mid 132.895594 -262.497973)
		(end 132.708396 -262.548116)
		(width 0.088646)
		(layer "In6.Cu")
		(net "M_G_CPU1_SA_DQS_DN<9>")
	)
	(arc
		(start 137.407396 -262.548116)
		(mid 137.124694 -262.623892)
		(end 136.841992 -262.548116)
		(width 0.088646)
		(layer "In6.Cu")
		(net "M_G_CPU1_SA_DQS_DN<9>")
	)
	(arc
		(start 135.902192 -262.548116)
		(mid 135.714994 -262.497973)
		(end 135.527796 -262.548116)
		(width 0.088646)
		(layer "In6.Cu")
		(net "M_G_CPU1_SA_DQS_DN<9>")
	)
	(arc
		(start 132.708396 -262.548116)
		(mid 132.431837 -262.623859)
		(end 132.15366 -262.554212)
		(width 0.088646)
		(layer "In6.Cu")
		(net "M_G_CPU1_SA_DQS_DN<9>")
	)
	(arc
		(start 134.573264 -262.556752)
		(mid 134.296789 -262.624072)
		(end 134.022592 -262.548116)
		(width 0.088646)
		(layer "In6.Cu")
		(net "M_G_CPU1_SA_DQS_DN<9>")
	)
	(arc
		(start 131.203192 -262.548116)
		(mid 131.015994 -262.497973)
		(end 130.828796 -262.548116)
		(width 0.088646)
		(layer "In6.Cu")
		(net "M_G_CPU1_SA_DQS_DN<9>")
	)
	(arc
		(start 132.143246 -262.548116)
		(mid 131.956048 -262.497973)
		(end 131.76885 -262.548116)
		(width 0.088646)
		(layer "In6.Cu")
		(net "M_G_CPU1_SA_DQS_DN<9>")
	)
	(arc
		(start 136.467596 -262.548116)
		(mid 136.184894 -262.623892)
		(end 135.902192 -262.548116)
		(width 0.088646)
		(layer "In6.Cu")
		(net "M_G_CPU1_SA_DQS_DN<9>")
	)
	(arc
		(start 130.814064 -262.556752)
		(mid 130.537762 -262.624074)
		(end 130.263646 -262.54837)
		(width 0.088646)
		(layer "In6.Cu")
		(net "M_G_CPU1_SA_DQS_DN<9>")
	)
	(arc
		(start 138.721846 -262.548116)
		(mid 138.534648 -262.497973)
		(end 138.34745 -262.548116)
		(width 0.088646)
		(layer "In6.Cu")
		(net "M_G_CPU1_SA_DQS_DN<9>")
	)
	(arc
		(start 130.263392 -262.548116)
		(mid 130.076194 -262.497973)
		(end 129.888996 -262.548116)
		(width 0.088646)
		(layer "In6.Cu")
		(net "M_G_CPU1_SA_DQS_DN<9>")
	)
	(arc
		(start 139.28725 -262.548116)
		(mid 139.013051 -262.623951)
		(end 138.736578 -262.556752)
		(width 0.088646)
		(layer "In6.Cu")
		(net "M_G_CPU1_SA_DQS_DN<9>")
	)
	(arc
		(start 139.742672 -261.742428)
		(mid 139.615629 -261.878244)
		(end 139.569444 -262.058404)
		(width 0.088646)
		(layer "In6.Cu")
		(net "M_G_CPU1_SA_DQS_DN<9>")
	)
	(arc
		(start 131.758436 -262.554212)
		(mid 131.480004 -262.624058)
		(end 131.203192 -262.548116)
		(width 0.088646)
		(layer "In6.Cu")
		(net "M_G_CPU1_SA_DQS_DN<9>")
	)
	(arc
		(start 137.781792 -262.548116)
		(mid 137.594594 -262.497973)
		(end 137.407396 -262.548116)
		(width 0.088646)
		(layer "In6.Cu")
		(net "M_G_CPU1_SA_DQS_DN<9>")
	)
	(arc
		(start 139.569444 -262.074152)
		(mid 139.490074 -262.347886)
		(end 139.28725 -262.548116)
		(width 0.088646)
		(layer "In6.Cu")
		(net "M_G_CPU1_SA_DQS_DN<9>")
	)
	(arc
		(start 136.841992 -262.548116)
		(mid 136.654794 -262.497973)
		(end 136.467596 -262.548116)
		(width 0.088646)
		(layer "In6.Cu")
		(net "M_G_CPU1_SA_DQS_DN<9>")
	)
	(arc
		(start 134.962392 -262.548116)
		(mid 134.775194 -262.497973)
		(end 134.587996 -262.548116)
		(width 0.088646)
		(layer "In6.Cu")
		(net "M_G_CPU1_SA_DQS_DN<9>")
	)
	(arc
		(start 139.944094 -261.6835)
		(mid 139.84716 -261.696598)
		(end 139.756896 -261.7343)
		(width 0.088646)
		(layer "In6.Cu")
		(net "M_G_CPU1_SA_DQS_DN<9>")
	)
	(segment
		(start 191.983614 -284.016704)
		(end 193.088514 -284.016704)
		(width 0.20066)
		(layer "F.Cu")
		(net "M_G_CPU1_SA_DQS_DN<8>")
	)
	(segment
		(start 193.61912 -284.016704)
		(end 193.890392 -283.745432)
		(width 0.20066)
		(layer "F.Cu")
		(net "M_G_CPU1_SA_DQS_DN<8>")
	)
	(segment
		(start 129.136648 -267.219938)
		(end 129.136394 -267.220192)
		(width 0.20066)
		(layer "F.Cu")
		(net "M_G_CPU1_SA_DQS_DN<8>")
	)
	(segment
		(start 197.861428 -283.602684)
		(end 198.147178 -283.316934)
		(width 0.20066)
		(layer "F.Cu")
		(net "M_G_CPU1_SA_DQS_DN<8>")
	)
	(segment
		(start 129.136394 -267.220192)
		(end 129.136394 -267.755878)
		(width 0.20066)
		(layer "F.Cu")
		(net "M_G_CPU1_SA_DQS_DN<8>")
	)
	(segment
		(start 197.542658 -283.602684)
		(end 197.861428 -283.602684)
		(width 0.20066)
		(layer "F.Cu")
		(net "M_G_CPU1_SA_DQS_DN<8>")
	)
	(segment
		(start 195.198492 -283.597858)
		(end 195.510658 -283.597858)
		(width 0.20066)
		(layer "F.Cu")
		(net "M_G_CPU1_SA_DQS_DN<8>")
	)
	(segment
		(start 195.52158 -283.591762)
		(end 197.531736 -283.591762)
		(width 0.1016)
		(layer "F.Cu")
		(net "M_G_CPU1_SA_DQS_DN<8>")
	)
	(segment
		(start 194.373754 -283.745432)
		(end 194.798696 -283.32049)
		(width 0.20066)
		(layer "F.Cu")
		(net "M_G_CPU1_SA_DQS_DN<8>")
	)
	(segment
		(start 193.890392 -283.745432)
		(end 194.373754 -283.745432)
		(width 0.20066)
		(layer "F.Cu")
		(net "M_G_CPU1_SA_DQS_DN<8>")
	)
	(segment
		(start 199.874378 -283.76245)
		(end 200.128632 -284.016704)
		(width 0.20066)
		(layer "F.Cu")
		(net "M_G_CPU1_SA_DQS_DN<8>")
	)
	(segment
		(start 199.08266 -283.76245)
		(end 199.874378 -283.76245)
		(width 0.20066)
		(layer "F.Cu")
		(net "M_G_CPU1_SA_DQS_DN<8>")
	)
	(segment
		(start 194.798696 -283.32049)
		(end 194.921124 -283.32049)
		(width 0.20066)
		(layer "F.Cu")
		(net "M_G_CPU1_SA_DQS_DN<8>")
	)
	(segment
		(start 197.531736 -283.591762)
		(end 197.542658 -283.602684)
		(width 0.1016)
		(layer "F.Cu")
		(net "M_G_CPU1_SA_DQS_DN<8>")
	)
	(segment
		(start 195.515484 -283.597858)
		(end 195.52158 -283.591762)
		(width 0.1016)
		(layer "F.Cu")
		(net "M_G_CPU1_SA_DQS_DN<8>")
	)
	(segment
		(start 195.510658 -283.597858)
		(end 195.515484 -283.597858)
		(width 0.101854)
		(layer "F.Cu")
		(net "M_G_CPU1_SA_DQS_DN<8>")
	)
	(segment
		(start 198.637144 -283.316934)
		(end 199.08266 -283.76245)
		(width 0.20066)
		(layer "F.Cu")
		(net "M_G_CPU1_SA_DQS_DN<8>")
	)
	(segment
		(start 193.088514 -284.016704)
		(end 193.61912 -284.016704)
		(width 0.20066)
		(layer "F.Cu")
		(net "M_G_CPU1_SA_DQS_DN<8>")
	)
	(segment
		(start 200.128632 -284.016704)
		(end 200.632314 -284.016704)
		(width 0.20066)
		(layer "F.Cu")
		(net "M_G_CPU1_SA_DQS_DN<8>")
	)
	(segment
		(start 194.921124 -283.32049)
		(end 195.198492 -283.597858)
		(width 0.20066)
		(layer "F.Cu")
		(net "M_G_CPU1_SA_DQS_DN<8>")
	)
	(segment
		(start 198.147178 -283.316934)
		(end 198.637144 -283.316934)
		(width 0.20066)
		(layer "F.Cu")
		(net "M_G_CPU1_SA_DQS_DN<8>")
	)
	(segment
		(start 191.7065 -283.73959)
		(end 190.868808 -283.73959)
		(width 0.18288)
		(layer "In6.Cu")
		(net "M_G_CPU1_SA_DQS_DN<8>")
	)
	(segment
		(start 188.101478 -283.58973)
		(end 187.656724 -283.58973)
		(width 0.18288)
		(layer "In6.Cu")
		(net "M_G_CPU1_SA_DQS_DN<8>")
	)
	(segment
		(start 177.11293 -282.740608)
		(end 176.602644 -282.740608)
		(width 0.18288)
		(layer "In6.Cu")
		(net "M_G_CPU1_SA_DQS_DN<8>")
	)
	(segment
		(start 188.770006 -283.300424)
		(end 188.390784 -283.300424)
		(width 0.18288)
		(layer "In6.Cu")
		(net "M_G_CPU1_SA_DQS_DN<8>")
	)
	(segment
		(start 178.16957 -282.450286)
		(end 177.403252 -282.450286)
		(width 0.18288)
		(layer "In6.Cu")
		(net "M_G_CPU1_SA_DQS_DN<8>")
	)
	(segment
		(start 181.230524 -282.559506)
		(end 180.138578 -282.559506)
		(width 0.18288)
		(layer "In6.Cu")
		(net "M_G_CPU1_SA_DQS_DN<8>")
	)
	(segment
		(start 176.365154 -282.503118)
		(end 175.981868 -282.503118)
		(width 0.18288)
		(layer "In6.Cu")
		(net "M_G_CPU1_SA_DQS_DN<8>")
	)
	(segment
		(start 164.510466 -274.773898)
		(end 164.386006 -274.649438)
		(width 0.18288)
		(layer "In6.Cu")
		(net "M_G_CPU1_SA_DQS_DN<8>")
	)
	(segment
		(start 170.414188 -276.1615)
		(end 170.238166 -276.1615)
		(width 0.18288)
		(layer "In6.Cu")
		(net "M_G_CPU1_SA_DQS_DN<8>")
	)
	(segment
		(start 162.779964 -274.649438)
		(end 162.655504 -274.773898)
		(width 0.18288)
		(layer "In6.Cu")
		(net "M_G_CPU1_SA_DQS_DN<8>")
	)
	(segment
		(start 160.14446 -274.773898)
		(end 160.02 -274.649438)
		(width 0.18288)
		(layer "In6.Cu")
		(net "M_G_CPU1_SA_DQS_DN<8>")
	)
	(segment
		(start 190.420752 -284.187646)
		(end 189.657228 -284.187646)
		(width 0.18288)
		(layer "In6.Cu")
		(net "M_G_CPU1_SA_DQS_DN<8>")
	)
	(segment
		(start 167.97782 -274.773898)
		(end 167.43172 -274.773898)
		(width 0.18288)
		(layer "In6.Cu")
		(net "M_G_CPU1_SA_DQS_DN<8>")
	)
	(segment
		(start 142.231364 -267.781278)
		(end 140.595604 -267.781278)
		(width 0.18288)
		(layer "In6.Cu")
		(net "M_G_CPU1_SA_DQS_DN<8>")
	)
	(segment
		(start 174.743872 -278.790654)
		(end 174.169324 -278.790654)
		(width 0.18288)
		(layer "In6.Cu")
		(net "M_G_CPU1_SA_DQS_DN<8>")
	)
	(segment
		(start 136.856724 -267.440156)
		(end 136.841992 -267.43152)
		(width 0.088646)
		(layer "In6.Cu")
		(net "M_G_CPU1_SA_DQS_DN<8>")
	)
	(segment
		(start 140.512292 -267.721334)
		(end 140.239242 -267.721334)
		(width 0.088646)
		(layer "In6.Cu")
		(net "M_G_CPU1_SA_DQS_DN<8>")
	)
	(segment
		(start 164.386006 -274.649438)
		(end 162.779964 -274.649438)
		(width 0.18288)
		(layer "In6.Cu")
		(net "M_G_CPU1_SA_DQS_DN<8>")
	)
	(segment
		(start 179.647088 -283.050996)
		(end 178.77028 -283.050996)
		(width 0.18288)
		(layer "In6.Cu")
		(net "M_G_CPU1_SA_DQS_DN<8>")
	)
	(segment
		(start 160.69056 -274.773898)
		(end 160.14446 -274.773898)
		(width 0.18288)
		(layer "In6.Cu")
		(net "M_G_CPU1_SA_DQS_DN<8>")
	)
	(segment
		(start 187.367164 -283.30017)
		(end 183.859424 -283.30017)
		(width 0.18288)
		(layer "In6.Cu")
		(net "M_G_CPU1_SA_DQS_DN<8>")
	)
	(segment
		(start 175.673512 -281.108404)
		(end 175.549052 -280.983944)
		(width 0.18288)
		(layer "In6.Cu")
		(net "M_G_CPU1_SA_DQS_DN<8>")
	)
	(segment
		(start 158.342838 -274.649438)
		(end 157.3657 -274.649438)
		(width 0.18288)
		(layer "In6.Cu")
		(net "M_G_CPU1_SA_DQS_DN<8>")
	)
	(segment
		(start 159.013398 -274.773898)
		(end 158.467298 -274.773898)
		(width 0.18288)
		(layer "In6.Cu")
		(net "M_G_CPU1_SA_DQS_DN<8>")
	)
	(segment
		(start 169.851578 -275.59889)
		(end 169.081704 -274.829016)
		(width 0.18288)
		(layer "In6.Cu")
		(net "M_G_CPU1_SA_DQS_DN<8>")
	)
	(segment
		(start 175.673512 -282.194762)
		(end 175.673512 -281.108404)
		(width 0.18288)
		(layer "In6.Cu")
		(net "M_G_CPU1_SA_DQS_DN<8>")
	)
	(segment
		(start 169.081704 -274.829016)
		(end 168.64838 -274.649438)
		(width 0.18288)
		(layer "In6.Cu")
		(net "M_G_CPU1_SA_DQS_DN<8>")
	)
	(segment
		(start 183.11876 -282.559506)
		(end 182.025544 -282.559506)
		(width 0.18288)
		(layer "In6.Cu")
		(net "M_G_CPU1_SA_DQS_DN<8>")
	)
	(segment
		(start 175.673512 -280.313384)
		(end 175.673512 -279.720294)
		(width 0.18288)
		(layer "In6.Cu")
		(net "M_G_CPU1_SA_DQS_DN<8>")
	)
	(segment
		(start 180.138578 -282.559506)
		(end 179.647088 -283.050996)
		(width 0.18288)
		(layer "In6.Cu")
		(net "M_G_CPU1_SA_DQS_DN<8>")
	)
	(segment
		(start 173.254416 -278.249126)
		(end 173.012862 -278.49068)
		(width 0.18288)
		(layer "In6.Cu")
		(net "M_G_CPU1_SA_DQS_DN<8>")
	)
	(segment
		(start 160.02 -274.649438)
		(end 159.137858 -274.649438)
		(width 0.18288)
		(layer "In6.Cu")
		(net "M_G_CPU1_SA_DQS_DN<8>")
	)
	(segment
		(start 165.181026 -274.649438)
		(end 165.056566 -274.773898)
		(width 0.18288)
		(layer "In6.Cu")
		(net "M_G_CPU1_SA_DQS_DN<8>")
	)
	(segment
		(start 175.981868 -282.503118)
		(end 175.673512 -282.194762)
		(width 0.18288)
		(layer "In6.Cu")
		(net "M_G_CPU1_SA_DQS_DN<8>")
	)
	(segment
		(start 140.595604 -267.781278)
		(end 140.572236 -267.781278)
		(width 0.088646)
		(layer "In6.Cu")
		(net "M_G_CPU1_SA_DQS_DN<8>")
	)
	(segment
		(start 178.77028 -283.050996)
		(end 178.16957 -282.450286)
		(width 0.18288)
		(layer "In6.Cu")
		(net "M_G_CPU1_SA_DQS_DN<8>")
	)
	(segment
		(start 187.656724 -283.58973)
		(end 187.367164 -283.30017)
		(width 0.18288)
		(layer "In6.Cu")
		(net "M_G_CPU1_SA_DQS_DN<8>")
	)
	(segment
		(start 134.587996 -267.43152)
		(end 134.573264 -267.440156)
		(width 0.088646)
		(layer "In6.Cu")
		(net "M_G_CPU1_SA_DQS_DN<8>")
	)
	(segment
		(start 190.868808 -283.73959)
		(end 190.420752 -284.187646)
		(width 0.18288)
		(layer "In6.Cu")
		(net "M_G_CPU1_SA_DQS_DN<8>")
	)
	(segment
		(start 131.76885 -267.43152)
		(end 131.758436 -267.437616)
		(width 0.088646)
		(layer "In6.Cu")
		(net "M_G_CPU1_SA_DQS_DN<8>")
	)
	(segment
		(start 175.549052 -280.983944)
		(end 175.549052 -280.437844)
		(width 0.18288)
		(layer "In6.Cu")
		(net "M_G_CPU1_SA_DQS_DN<8>")
	)
	(segment
		(start 129.843784 -267.457174)
		(end 129.794254 -267.490194)
		(width 0.088646)
		(layer "In6.Cu")
		(net "M_G_CPU1_SA_DQS_DN<8>")
	)
	(segment
		(start 173.627796 -278.249126)
		(end 173.254416 -278.249126)
		(width 0.18288)
		(layer "In6.Cu")
		(net "M_G_CPU1_SA_DQS_DN<8>")
	)
	(segment
		(start 172.502576 -278.49068)
		(end 172.265086 -278.25319)
		(width 0.18288)
		(layer "In6.Cu")
		(net "M_G_CPU1_SA_DQS_DN<8>")
	)
	(segment
		(start 170.238166 -276.1615)
		(end 169.851578 -275.774912)
		(width 0.18288)
		(layer "In6.Cu")
		(net "M_G_CPU1_SA_DQS_DN<8>")
	)
	(segment
		(start 170.812714 -277.51278)
		(end 170.812714 -276.560026)
		(width 0.18288)
		(layer "In6.Cu")
		(net "M_G_CPU1_SA_DQS_DN<8>")
	)
	(segment
		(start 170.812714 -276.560026)
		(end 170.414188 -276.1615)
		(width 0.18288)
		(layer "In6.Cu")
		(net "M_G_CPU1_SA_DQS_DN<8>")
	)
	(segment
		(start 168.64838 -274.649438)
		(end 168.10228 -274.649438)
		(width 0.18288)
		(layer "In6.Cu")
		(net "M_G_CPU1_SA_DQS_DN<8>")
	)
	(segment
		(start 160.81502 -274.649438)
		(end 160.69056 -274.773898)
		(width 0.18288)
		(layer "In6.Cu")
		(net "M_G_CPU1_SA_DQS_DN<8>")
	)
	(segment
		(start 175.549052 -280.437844)
		(end 175.673512 -280.313384)
		(width 0.18288)
		(layer "In6.Cu")
		(net "M_G_CPU1_SA_DQS_DN<8>")
	)
	(segment
		(start 144.901158 -268.312392)
		(end 142.231364 -267.781278)
		(width 0.18288)
		(layer "In6.Cu")
		(net "M_G_CPU1_SA_DQS_DN<8>")
	)
	(segment
		(start 188.390784 -283.300424)
		(end 188.101478 -283.58973)
		(width 0.18288)
		(layer "In6.Cu")
		(net "M_G_CPU1_SA_DQS_DN<8>")
	)
	(segment
		(start 165.851586 -274.773898)
		(end 165.727126 -274.649438)
		(width 0.18288)
		(layer "In6.Cu")
		(net "M_G_CPU1_SA_DQS_DN<8>")
	)
	(segment
		(start 183.859424 -283.30017)
		(end 183.11876 -282.559506)
		(width 0.18288)
		(layer "In6.Cu")
		(net "M_G_CPU1_SA_DQS_DN<8>")
	)
	(segment
		(start 161.984944 -274.649438)
		(end 160.81502 -274.649438)
		(width 0.18288)
		(layer "In6.Cu")
		(net "M_G_CPU1_SA_DQS_DN<8>")
	)
	(segment
		(start 165.727126 -274.649438)
		(end 165.181026 -274.649438)
		(width 0.18288)
		(layer "In6.Cu")
		(net "M_G_CPU1_SA_DQS_DN<8>")
	)
	(segment
		(start 140.239242 -267.721334)
		(end 140.02512 -267.507212)
		(width 0.088646)
		(layer "In6.Cu")
		(net "M_G_CPU1_SA_DQS_DN<8>")
	)
	(segment
		(start 169.851578 -275.774912)
		(end 169.851578 -275.59889)
		(width 0.18288)
		(layer "In6.Cu")
		(net "M_G_CPU1_SA_DQS_DN<8>")
	)
	(segment
		(start 176.602644 -282.740608)
		(end 176.365154 -282.503118)
		(width 0.18288)
		(layer "In6.Cu")
		(net "M_G_CPU1_SA_DQS_DN<8>")
	)
	(segment
		(start 137.79627 -267.440156)
		(end 137.781538 -267.43152)
		(width 0.088646)
		(layer "In6.Cu")
		(net "M_G_CPU1_SA_DQS_DN<8>")
	)
	(segment
		(start 175.673512 -279.720294)
		(end 174.743872 -278.790654)
		(width 0.18288)
		(layer "In6.Cu")
		(net "M_G_CPU1_SA_DQS_DN<8>")
	)
	(segment
		(start 181.901084 -282.683966)
		(end 181.354984 -282.683966)
		(width 0.18288)
		(layer "In6.Cu")
		(net "M_G_CPU1_SA_DQS_DN<8>")
	)
	(segment
		(start 166.397686 -274.773898)
		(end 165.851586 -274.773898)
		(width 0.18288)
		(layer "In6.Cu")
		(net "M_G_CPU1_SA_DQS_DN<8>")
	)
	(segment
		(start 177.403252 -282.450286)
		(end 177.11293 -282.740608)
		(width 0.18288)
		(layer "In6.Cu")
		(net "M_G_CPU1_SA_DQS_DN<8>")
	)
	(segment
		(start 172.265086 -278.25319)
		(end 171.553124 -278.25319)
		(width 0.18288)
		(layer "In6.Cu")
		(net "M_G_CPU1_SA_DQS_DN<8>")
	)
	(segment
		(start 140.572236 -267.781278)
		(end 140.512292 -267.721334)
		(width 0.088646)
		(layer "In6.Cu")
		(net "M_G_CPU1_SA_DQS_DN<8>")
	)
	(segment
		(start 191.983614 -284.016704)
		(end 191.7065 -283.73959)
		(width 0.18288)
		(layer "In6.Cu")
		(net "M_G_CPU1_SA_DQS_DN<8>")
	)
	(segment
		(start 140.02512 -267.507212)
		(end 139.942824 -267.507212)
		(width 0.088646)
		(layer "In6.Cu")
		(net "M_G_CPU1_SA_DQS_DN<8>")
	)
	(segment
		(start 162.109404 -274.773898)
		(end 161.984944 -274.649438)
		(width 0.18288)
		(layer "In6.Cu")
		(net "M_G_CPU1_SA_DQS_DN<8>")
	)
	(segment
		(start 174.169324 -278.790654)
		(end 173.627796 -278.249126)
		(width 0.18288)
		(layer "In6.Cu")
		(net "M_G_CPU1_SA_DQS_DN<8>")
	)
	(segment
		(start 138.731752 -267.437616)
		(end 138.7094 -267.424662)
		(width 0.088646)
		(layer "In6.Cu")
		(net "M_G_CPU1_SA_DQS_DN<8>")
	)
	(segment
		(start 151.028654 -268.312392)
		(end 144.901158 -268.312392)
		(width 0.18288)
		(layer "In6.Cu")
		(net "M_G_CPU1_SA_DQS_DN<8>")
	)
	(segment
		(start 157.3657 -274.649438)
		(end 151.028654 -268.312392)
		(width 0.18288)
		(layer "In6.Cu")
		(net "M_G_CPU1_SA_DQS_DN<8>")
	)
	(segment
		(start 167.30726 -274.649438)
		(end 166.522146 -274.649438)
		(width 0.18288)
		(layer "In6.Cu")
		(net "M_G_CPU1_SA_DQS_DN<8>")
	)
	(segment
		(start 165.056566 -274.773898)
		(end 164.510466 -274.773898)
		(width 0.18288)
		(layer "In6.Cu")
		(net "M_G_CPU1_SA_DQS_DN<8>")
	)
	(segment
		(start 181.354984 -282.683966)
		(end 181.230524 -282.559506)
		(width 0.18288)
		(layer "In6.Cu")
		(net "M_G_CPU1_SA_DQS_DN<8>")
	)
	(segment
		(start 129.854198 -267.450316)
		(end 129.843784 -267.457174)
		(width 0.088646)
		(layer "In6.Cu")
		(net "M_G_CPU1_SA_DQS_DN<8>")
	)
	(segment
		(start 168.10228 -274.649438)
		(end 167.97782 -274.773898)
		(width 0.18288)
		(layer "In6.Cu")
		(net "M_G_CPU1_SA_DQS_DN<8>")
	)
	(segment
		(start 133.648196 -267.43152)
		(end 133.633464 -267.440156)
		(width 0.088646)
		(layer "In6.Cu")
		(net "M_G_CPU1_SA_DQS_DN<8>")
	)
	(segment
		(start 166.522146 -274.649438)
		(end 166.397686 -274.773898)
		(width 0.18288)
		(layer "In6.Cu")
		(net "M_G_CPU1_SA_DQS_DN<8>")
	)
	(segment
		(start 130.828796 -267.43152)
		(end 130.814064 -267.440156)
		(width 0.088646)
		(layer "In6.Cu")
		(net "M_G_CPU1_SA_DQS_DN<8>")
	)
	(segment
		(start 129.193036 -267.550138)
		(end 129.136394 -267.60678)
		(width 0.088646)
		(layer "In6.Cu")
		(net "M_G_CPU1_SA_DQS_DN<8>")
	)
	(segment
		(start 129.794254 -267.490194)
		(end 129.493772 -267.550138)
		(width 0.088646)
		(layer "In6.Cu")
		(net "M_G_CPU1_SA_DQS_DN<8>")
	)
	(segment
		(start 135.527796 -267.43152)
		(end 135.513064 -267.440156)
		(width 0.088646)
		(layer "In6.Cu")
		(net "M_G_CPU1_SA_DQS_DN<8>")
	)
	(segment
		(start 162.655504 -274.773898)
		(end 162.109404 -274.773898)
		(width 0.18288)
		(layer "In6.Cu")
		(net "M_G_CPU1_SA_DQS_DN<8>")
	)
	(segment
		(start 158.467298 -274.773898)
		(end 158.342838 -274.649438)
		(width 0.18288)
		(layer "In6.Cu")
		(net "M_G_CPU1_SA_DQS_DN<8>")
	)
	(segment
		(start 173.012862 -278.49068)
		(end 172.502576 -278.49068)
		(width 0.18288)
		(layer "In6.Cu")
		(net "M_G_CPU1_SA_DQS_DN<8>")
	)
	(segment
		(start 137.781538 -267.43152)
		(end 137.773156 -267.426694)
		(width 0.088646)
		(layer "In6.Cu")
		(net "M_G_CPU1_SA_DQS_DN<8>")
	)
	(segment
		(start 129.888996 -267.43152)
		(end 129.854198 -267.450316)
		(width 0.088646)
		(layer "In6.Cu")
		(net "M_G_CPU1_SA_DQS_DN<8>")
	)
	(segment
		(start 171.553124 -278.25319)
		(end 170.812714 -277.51278)
		(width 0.18288)
		(layer "In6.Cu")
		(net "M_G_CPU1_SA_DQS_DN<8>")
	)
	(segment
		(start 129.493772 -267.550138)
		(end 129.193036 -267.550138)
		(width 0.088646)
		(layer "In6.Cu")
		(net "M_G_CPU1_SA_DQS_DN<8>")
	)
	(segment
		(start 167.43172 -274.773898)
		(end 167.30726 -274.649438)
		(width 0.18288)
		(layer "In6.Cu")
		(net "M_G_CPU1_SA_DQS_DN<8>")
	)
	(segment
		(start 182.025544 -282.559506)
		(end 181.901084 -282.683966)
		(width 0.18288)
		(layer "In6.Cu")
		(net "M_G_CPU1_SA_DQS_DN<8>")
	)
	(segment
		(start 132.15366 -267.437616)
		(end 132.143246 -267.43152)
		(width 0.088646)
		(layer "In6.Cu")
		(net "M_G_CPU1_SA_DQS_DN<8>")
	)
	(segment
		(start 189.657228 -284.187646)
		(end 188.770006 -283.300424)
		(width 0.18288)
		(layer "In6.Cu")
		(net "M_G_CPU1_SA_DQS_DN<8>")
	)
	(segment
		(start 159.137858 -274.649438)
		(end 159.013398 -274.773898)
		(width 0.18288)
		(layer "In6.Cu")
		(net "M_G_CPU1_SA_DQS_DN<8>")
	)
	(segment
		(start 129.136394 -267.60678)
		(end 129.136394 -267.755878)
		(width 0.088646)
		(layer "In6.Cu")
		(net "M_G_CPU1_SA_DQS_DN<8>")
	)
	(arc
		(start 136.467596 -267.43152)
		(mid 136.184894 -267.507262)
		(end 135.902192 -267.43152)
		(width 0.088646)
		(layer "In6.Cu")
		(net "M_G_CPU1_SA_DQS_DN<8>")
	)
	(arc
		(start 130.814064 -267.440156)
		(mid 130.537589 -267.507476)
		(end 130.263392 -267.43152)
		(width 0.088646)
		(layer "In6.Cu")
		(net "M_G_CPU1_SA_DQS_DN<8>")
	)
	(arc
		(start 137.773156 -267.426694)
		(mid 137.589648 -267.381416)
		(end 137.407396 -267.43152)
		(width 0.088646)
		(layer "In6.Cu")
		(net "M_G_CPU1_SA_DQS_DN<8>")
	)
	(arc
		(start 134.573264 -267.440156)
		(mid 134.296789 -267.507476)
		(end 134.022592 -267.43152)
		(width 0.088646)
		(layer "In6.Cu")
		(net "M_G_CPU1_SA_DQS_DN<8>")
	)
	(arc
		(start 130.263392 -267.43152)
		(mid 130.076194 -267.381377)
		(end 129.888996 -267.43152)
		(width 0.088646)
		(layer "In6.Cu")
		(net "M_G_CPU1_SA_DQS_DN<8>")
	)
	(arc
		(start 138.7094 -267.424662)
		(mid 138.527289 -267.381337)
		(end 138.346942 -267.43152)
		(width 0.088646)
		(layer "In6.Cu")
		(net "M_G_CPU1_SA_DQS_DN<8>")
	)
	(arc
		(start 131.203192 -267.43152)
		(mid 131.015994 -267.381377)
		(end 130.828796 -267.43152)
		(width 0.088646)
		(layer "In6.Cu")
		(net "M_G_CPU1_SA_DQS_DN<8>")
	)
	(arc
		(start 135.513064 -267.440156)
		(mid 135.236623 -267.507322)
		(end 134.962392 -267.43152)
		(width 0.088646)
		(layer "In6.Cu")
		(net "M_G_CPU1_SA_DQS_DN<8>")
	)
	(arc
		(start 133.082792 -267.43152)
		(mid 132.895594 -267.381377)
		(end 132.708396 -267.43152)
		(width 0.088646)
		(layer "In6.Cu")
		(net "M_G_CPU1_SA_DQS_DN<8>")
	)
	(arc
		(start 134.022592 -267.43152)
		(mid 133.835394 -267.381377)
		(end 133.648196 -267.43152)
		(width 0.088646)
		(layer "In6.Cu")
		(net "M_G_CPU1_SA_DQS_DN<8>")
	)
	(arc
		(start 133.633464 -267.440156)
		(mid 133.356989 -267.507476)
		(end 133.082792 -267.43152)
		(width 0.088646)
		(layer "In6.Cu")
		(net "M_G_CPU1_SA_DQS_DN<8>")
	)
	(arc
		(start 132.143246 -267.43152)
		(mid 131.956048 -267.381377)
		(end 131.76885 -267.43152)
		(width 0.088646)
		(layer "In6.Cu")
		(net "M_G_CPU1_SA_DQS_DN<8>")
	)
	(arc
		(start 139.28598 -267.43152)
		(mid 139.009675 -267.507102)
		(end 138.731752 -267.437616)
		(width 0.088646)
		(layer "In6.Cu")
		(net "M_G_CPU1_SA_DQS_DN<8>")
	)
	(arc
		(start 137.407396 -267.43152)
		(mid 137.133167 -267.507445)
		(end 136.856724 -267.440156)
		(width 0.088646)
		(layer "In6.Cu")
		(net "M_G_CPU1_SA_DQS_DN<8>")
	)
	(arc
		(start 139.660376 -267.43152)
		(mid 139.473178 -267.381377)
		(end 139.28598 -267.43152)
		(width 0.088646)
		(layer "In6.Cu")
		(net "M_G_CPU1_SA_DQS_DN<8>")
	)
	(arc
		(start 138.346942 -267.43152)
		(mid 138.072713 -267.507445)
		(end 137.79627 -267.440156)
		(width 0.088646)
		(layer "In6.Cu")
		(net "M_G_CPU1_SA_DQS_DN<8>")
	)
	(arc
		(start 136.841992 -267.43152)
		(mid 136.654794 -267.381377)
		(end 136.467596 -267.43152)
		(width 0.088646)
		(layer "In6.Cu")
		(net "M_G_CPU1_SA_DQS_DN<8>")
	)
	(arc
		(start 135.902192 -267.43152)
		(mid 135.714994 -267.381377)
		(end 135.527796 -267.43152)
		(width 0.088646)
		(layer "In6.Cu")
		(net "M_G_CPU1_SA_DQS_DN<8>")
	)
	(arc
		(start 131.758436 -267.437616)
		(mid 131.480004 -267.507462)
		(end 131.203192 -267.43152)
		(width 0.088646)
		(layer "In6.Cu")
		(net "M_G_CPU1_SA_DQS_DN<8>")
	)
	(arc
		(start 132.708396 -267.43152)
		(mid 132.431837 -267.507263)
		(end 132.15366 -267.437616)
		(width 0.088646)
		(layer "In6.Cu")
		(net "M_G_CPU1_SA_DQS_DN<8>")
	)
	(arc
		(start 134.962392 -267.43152)
		(mid 134.775194 -267.381377)
		(end 134.587996 -267.43152)
		(width 0.088646)
		(layer "In6.Cu")
		(net "M_G_CPU1_SA_DQS_DN<8>")
	)
	(arc
		(start 139.942824 -267.507212)
		(mid 139.796616 -267.487963)
		(end 139.660376 -267.43152)
		(width 0.088646)
		(layer "In6.Cu")
		(net "M_G_CPU1_SA_DQS_DN<8>")
	)
	(segment
		(start 195.52158 -292.941756)
		(end 197.531736 -292.941756)
		(width 0.1016)
		(layer "F.Cu")
		(net "M_G_CPU1_SA_DQS_DN<7>")
	)
	(segment
		(start 132.425694 -264.778236)
		(end 132.425694 -265.313922)
		(width 0.20066)
		(layer "F.Cu")
		(net "M_G_CPU1_SA_DQS_DN<7>")
	)
	(segment
		(start 193.088514 -293.366698)
		(end 193.61912 -293.366698)
		(width 0.20066)
		(layer "F.Cu")
		(net "M_G_CPU1_SA_DQS_DN<7>")
	)
	(segment
		(start 194.921124 -292.670484)
		(end 195.198492 -292.947852)
		(width 0.20066)
		(layer "F.Cu")
		(net "M_G_CPU1_SA_DQS_DN<7>")
	)
	(segment
		(start 194.798696 -292.670484)
		(end 194.921124 -292.670484)
		(width 0.20066)
		(layer "F.Cu")
		(net "M_G_CPU1_SA_DQS_DN<7>")
	)
	(segment
		(start 199.08266 -293.112444)
		(end 199.874378 -293.112444)
		(width 0.20066)
		(layer "F.Cu")
		(net "M_G_CPU1_SA_DQS_DN<7>")
	)
	(segment
		(start 198.637144 -292.666928)
		(end 199.08266 -293.112444)
		(width 0.20066)
		(layer "F.Cu")
		(net "M_G_CPU1_SA_DQS_DN<7>")
	)
	(segment
		(start 197.542658 -292.952678)
		(end 197.861428 -292.952678)
		(width 0.20066)
		(layer "F.Cu")
		(net "M_G_CPU1_SA_DQS_DN<7>")
	)
	(segment
		(start 195.515484 -292.947852)
		(end 195.52158 -292.941756)
		(width 0.1016)
		(layer "F.Cu")
		(net "M_G_CPU1_SA_DQS_DN<7>")
	)
	(segment
		(start 197.861428 -292.952678)
		(end 198.147178 -292.666928)
		(width 0.20066)
		(layer "F.Cu")
		(net "M_G_CPU1_SA_DQS_DN<7>")
	)
	(segment
		(start 197.531736 -292.941756)
		(end 197.542658 -292.952678)
		(width 0.1016)
		(layer "F.Cu")
		(net "M_G_CPU1_SA_DQS_DN<7>")
	)
	(segment
		(start 193.890392 -293.095426)
		(end 194.373754 -293.095426)
		(width 0.20066)
		(layer "F.Cu")
		(net "M_G_CPU1_SA_DQS_DN<7>")
	)
	(segment
		(start 194.373754 -293.095426)
		(end 194.798696 -292.670484)
		(width 0.20066)
		(layer "F.Cu")
		(net "M_G_CPU1_SA_DQS_DN<7>")
	)
	(segment
		(start 199.874378 -293.112444)
		(end 200.128632 -293.366698)
		(width 0.20066)
		(layer "F.Cu")
		(net "M_G_CPU1_SA_DQS_DN<7>")
	)
	(segment
		(start 191.983614 -293.366698)
		(end 193.088514 -293.366698)
		(width 0.20066)
		(layer "F.Cu")
		(net "M_G_CPU1_SA_DQS_DN<7>")
	)
	(segment
		(start 193.61912 -293.366698)
		(end 193.890392 -293.095426)
		(width 0.20066)
		(layer "F.Cu")
		(net "M_G_CPU1_SA_DQS_DN<7>")
	)
	(segment
		(start 132.425694 -265.313922)
		(end 132.425948 -265.314176)
		(width 0.20066)
		(layer "F.Cu")
		(net "M_G_CPU1_SA_DQS_DN<7>")
	)
	(segment
		(start 195.510658 -292.947852)
		(end 195.515484 -292.947852)
		(width 0.101854)
		(layer "F.Cu")
		(net "M_G_CPU1_SA_DQS_DN<7>")
	)
	(segment
		(start 198.147178 -292.666928)
		(end 198.637144 -292.666928)
		(width 0.20066)
		(layer "F.Cu")
		(net "M_G_CPU1_SA_DQS_DN<7>")
	)
	(segment
		(start 200.128632 -293.366698)
		(end 200.632314 -293.366698)
		(width 0.20066)
		(layer "F.Cu")
		(net "M_G_CPU1_SA_DQS_DN<7>")
	)
	(segment
		(start 195.198492 -292.947852)
		(end 195.510658 -292.947852)
		(width 0.20066)
		(layer "F.Cu")
		(net "M_G_CPU1_SA_DQS_DN<7>")
	)
	(segment
		(start 137.644886 -265.17727)
		(end 137.312908 -264.99058)
		(width 0.088646)
		(layer "In4.Cu")
		(net "M_G_CPU1_SA_DQS_DN<7>")
	)
	(segment
		(start 189.774576 -293.379144)
		(end 189.650116 -293.254684)
		(width 0.18288)
		(layer "In4.Cu")
		(net "M_G_CPU1_SA_DQS_DN<7>")
	)
	(segment
		(start 134.507478 -264.998454)
		(end 134.492746 -264.989818)
		(width 0.088646)
		(layer "In4.Cu")
		(net "M_G_CPU1_SA_DQS_DN<7>")
	)
	(segment
		(start 177.387504 -291.814758)
		(end 177.375058 -291.827204)
		(width 0.18288)
		(layer "In4.Cu")
		(net "M_G_CPU1_SA_DQS_DN<7>")
	)
	(segment
		(start 173.27118 -292.661086)
		(end 172.988224 -292.944042)
		(width 0.18288)
		(layer "In4.Cu")
		(net "M_G_CPU1_SA_DQS_DN<7>")
	)
	(segment
		(start 154.614118 -276.614382)
		(end 146.230848 -268.231112)
		(width 0.18288)
		(layer "In4.Cu")
		(net "M_G_CPU1_SA_DQS_DN<7>")
	)
	(segment
		(start 186.204098 -292.403276)
		(end 186.079638 -292.527736)
		(width 0.18288)
		(layer "In4.Cu")
		(net "M_G_CPU1_SA_DQS_DN<7>")
	)
	(segment
		(start 177.375058 -291.827204)
		(end 177.37074 -291.827204)
		(width 0.18288)
		(layer "In4.Cu")
		(net "M_G_CPU1_SA_DQS_DN<7>")
	)
	(segment
		(start 164.33165 -287.337246)
		(end 163.725352 -287.337246)
		(width 0.18288)
		(layer "In4.Cu")
		(net "M_G_CPU1_SA_DQS_DN<7>")
	)
	(segment
		(start 191.12865 -293.254684)
		(end 190.445136 -293.254684)
		(width 0.18288)
		(layer "In4.Cu")
		(net "M_G_CPU1_SA_DQS_DN<7>")
	)
	(segment
		(start 191.53759 -293.085266)
		(end 191.12865 -293.254684)
		(width 0.18288)
		(layer "In4.Cu")
		(net "M_G_CPU1_SA_DQS_DN<7>")
	)
	(segment
		(start 159.682434 -282.503626)
		(end 159.557974 -282.628086)
		(width 0.18288)
		(layer "In4.Cu")
		(net "M_G_CPU1_SA_DQS_DN<7>")
	)
	(segment
		(start 185.533538 -292.527736)
		(end 185.409078 -292.403276)
		(width 0.18288)
		(layer "In4.Cu")
		(net "M_G_CPU1_SA_DQS_DN<7>")
	)
	(segment
		(start 133.563106 -264.995914)
		(end 133.552692 -264.989818)
		(width 0.088646)
		(layer "In4.Cu")
		(net "M_G_CPU1_SA_DQS_DN<7>")
	)
	(segment
		(start 134.122668 -264.987024)
		(end 134.11835 -264.989818)
		(width 0.088646)
		(layer "In4.Cu")
		(net "M_G_CPU1_SA_DQS_DN<7>")
	)
	(segment
		(start 170.817286 -292.65245)
		(end 169.404284 -291.239448)
		(width 0.18288)
		(layer "In4.Cu")
		(net "M_G_CPU1_SA_DQS_DN<7>")
	)
	(segment
		(start 159.557974 -282.628086)
		(end 159.011874 -282.628086)
		(width 0.18288)
		(layer "In4.Cu")
		(net "M_G_CPU1_SA_DQS_DN<7>")
	)
	(segment
		(start 191.702182 -293.085266)
		(end 191.53759 -293.085266)
		(width 0.18288)
		(layer "In4.Cu")
		(net "M_G_CPU1_SA_DQS_DN<7>")
	)
	(segment
		(start 186.811158 -292.403276)
		(end 186.204098 -292.403276)
		(width 0.18288)
		(layer "In4.Cu")
		(net "M_G_CPU1_SA_DQS_DN<7>")
	)
	(segment
		(start 169.404284 -291.239448)
		(end 168.781222 -291.239448)
		(width 0.18288)
		(layer "In4.Cu")
		(net "M_G_CPU1_SA_DQS_DN<7>")
	)
	(segment
		(start 166.773098 -289.778694)
		(end 166.597076 -289.778694)
		(width 0.18288)
		(layer "In4.Cu")
		(net "M_G_CPU1_SA_DQS_DN<7>")
	)
	(segment
		(start 178.727862 -292.47465)
		(end 178.06797 -291.814758)
		(width 0.18288)
		(layer "In4.Cu")
		(net "M_G_CPU1_SA_DQS_DN<7>")
	)
	(segment
		(start 181.619906 -292.019482)
		(end 180.218588 -292.019482)
		(width 0.18288)
		(layer "In4.Cu")
		(net "M_G_CPU1_SA_DQS_DN<7>")
	)
	(segment
		(start 177.37074 -291.827204)
		(end 177.105564 -292.09238)
		(width 0.18288)
		(layer "In4.Cu")
		(net "M_G_CPU1_SA_DQS_DN<7>")
	)
	(segment
		(start 172.312584 -292.65245)
		(end 170.817286 -292.65245)
		(width 0.18288)
		(layer "In4.Cu")
		(net "M_G_CPU1_SA_DQS_DN<7>")
	)
	(segment
		(start 172.604176 -292.944042)
		(end 172.312584 -292.65245)
		(width 0.18288)
		(layer "In4.Cu")
		(net "M_G_CPU1_SA_DQS_DN<7>")
	)
	(segment
		(start 163.2458 -286.268668)
		(end 162.193732 -285.216854)
		(width 0.18288)
		(layer "In4.Cu")
		(net "M_G_CPU1_SA_DQS_DN<7>")
	)
	(segment
		(start 166.597076 -289.778694)
		(end 166.210742 -289.39236)
		(width 0.18288)
		(layer "In4.Cu")
		(net "M_G_CPU1_SA_DQS_DN<7>")
	)
	(segment
		(start 161.761424 -285.332678)
		(end 161.428684 -285.140654)
		(width 0.18288)
		(layer "In4.Cu")
		(net "M_G_CPU1_SA_DQS_DN<7>")
	)
	(segment
		(start 166.210742 -289.216338)
		(end 165.4937 -288.499296)
		(width 0.18288)
		(layer "In4.Cu")
		(net "M_G_CPU1_SA_DQS_DN<7>")
	)
	(segment
		(start 146.230848 -268.231112)
		(end 144.540478 -268.231112)
		(width 0.18288)
		(layer "In4.Cu")
		(net "M_G_CPU1_SA_DQS_DN<7>")
	)
	(segment
		(start 184.096914 -292.527736)
		(end 183.972454 -292.403276)
		(width 0.18288)
		(layer "In4.Cu")
		(net "M_G_CPU1_SA_DQS_DN<7>")
	)
	(segment
		(start 135.447278 -264.998454)
		(end 135.432546 -264.989818)
		(width 0.088646)
		(layer "In4.Cu")
		(net "M_G_CPU1_SA_DQS_DN<7>")
	)
	(segment
		(start 154.614372 -276.61489)
		(end 154.614118 -276.614382)
		(width 0.18288)
		(layer "In4.Cu")
		(net "M_G_CPU1_SA_DQS_DN<7>")
	)
	(segment
		(start 173.509178 -292.661086)
		(end 173.27118 -292.661086)
		(width 0.18288)
		(layer "In4.Cu")
		(net "M_G_CPU1_SA_DQS_DN<7>")
	)
	(segment
		(start 133.046724 -265.065764)
		(end 132.891784 -265.107166)
		(width 0.088646)
		(layer "In4.Cu")
		(net "M_G_CPU1_SA_DQS_DN<7>")
	)
	(segment
		(start 190.320676 -293.379144)
		(end 189.774576 -293.379144)
		(width 0.18288)
		(layer "In4.Cu")
		(net "M_G_CPU1_SA_DQS_DN<7>")
	)
	(segment
		(start 176.690782 -292.09238)
		(end 176.404524 -291.806122)
		(width 0.18288)
		(layer "In4.Cu")
		(net "M_G_CPU1_SA_DQS_DN<7>")
	)
	(segment
		(start 160.842198 -284.202378)
		(end 160.842198 -283.11729)
		(width 0.18288)
		(layer "In4.Cu")
		(net "M_G_CPU1_SA_DQS_DN<7>")
	)
	(segment
		(start 160.842198 -283.11729)
		(end 160.228534 -282.503626)
		(width 0.18288)
		(layer "In4.Cu")
		(net "M_G_CPU1_SA_DQS_DN<7>")
	)
	(segment
		(start 182.414926 -292.019482)
		(end 182.290466 -292.143942)
		(width 0.18288)
		(layer "In4.Cu")
		(net "M_G_CPU1_SA_DQS_DN<7>")
	)
	(segment
		(start 136.387078 -264.998454)
		(end 136.372346 -264.989818)
		(width 0.088646)
		(layer "In4.Cu")
		(net "M_G_CPU1_SA_DQS_DN<7>")
	)
	(segment
		(start 184.643014 -292.527736)
		(end 184.096914 -292.527736)
		(width 0.18288)
		(layer "In4.Cu")
		(net "M_G_CPU1_SA_DQS_DN<7>")
	)
	(segment
		(start 158.887414 -282.503626)
		(end 157.595062 -282.503626)
		(width 0.18288)
		(layer "In4.Cu")
		(net "M_G_CPU1_SA_DQS_DN<7>")
	)
	(segment
		(start 161.330894 -284.776418)
		(end 161.124646 -284.691328)
		(width 0.18288)
		(layer "In4.Cu")
		(net "M_G_CPU1_SA_DQS_DN<7>")
	)
	(segment
		(start 186.079638 -292.527736)
		(end 185.533538 -292.527736)
		(width 0.18288)
		(layer "In4.Cu")
		(net "M_G_CPU1_SA_DQS_DN<7>")
	)
	(segment
		(start 191.983614 -293.366698)
		(end 191.702182 -293.085266)
		(width 0.18288)
		(layer "In4.Cu")
		(net "M_G_CPU1_SA_DQS_DN<7>")
	)
	(segment
		(start 185.409078 -292.403276)
		(end 184.767474 -292.403276)
		(width 0.18288)
		(layer "In4.Cu")
		(net "M_G_CPU1_SA_DQS_DN<7>")
	)
	(segment
		(start 177.105564 -292.09238)
		(end 176.690782 -292.09238)
		(width 0.18288)
		(layer "In4.Cu")
		(net "M_G_CPU1_SA_DQS_DN<7>")
	)
	(segment
		(start 166.210742 -289.39236)
		(end 166.210742 -289.216338)
		(width 0.18288)
		(layer "In4.Cu")
		(net "M_G_CPU1_SA_DQS_DN<7>")
	)
	(segment
		(start 183.972454 -292.403276)
		(end 183.426354 -292.403276)
		(width 0.18288)
		(layer "In4.Cu")
		(net "M_G_CPU1_SA_DQS_DN<7>")
	)
	(segment
		(start 174.176182 -292.519608)
		(end 174.013622 -292.452298)
		(width 0.18288)
		(layer "In4.Cu")
		(net "M_G_CPU1_SA_DQS_DN<7>")
	)
	(segment
		(start 137.312908 -264.99058)
		(end 137.311384 -264.989564)
		(width 0.088646)
		(layer "In4.Cu")
		(net "M_G_CPU1_SA_DQS_DN<7>")
	)
	(segment
		(start 184.767474 -292.403276)
		(end 184.643014 -292.527736)
		(width 0.18288)
		(layer "In4.Cu")
		(net "M_G_CPU1_SA_DQS_DN<7>")
	)
	(segment
		(start 163.725352 -287.337246)
		(end 163.2458 -286.857694)
		(width 0.18288)
		(layer "In4.Cu")
		(net "M_G_CPU1_SA_DQS_DN<7>")
	)
	(segment
		(start 187.083192 -292.67531)
		(end 186.811158 -292.403276)
		(width 0.18288)
		(layer "In4.Cu")
		(net "M_G_CPU1_SA_DQS_DN<7>")
	)
	(segment
		(start 178.06797 -291.814758)
		(end 177.387504 -291.814758)
		(width 0.18288)
		(layer "In4.Cu")
		(net "M_G_CPU1_SA_DQS_DN<7>")
	)
	(segment
		(start 164.93109 -288.112708)
		(end 164.93109 -287.936686)
		(width 0.18288)
		(layer "In4.Cu")
		(net "M_G_CPU1_SA_DQS_DN<7>")
	)
	(segment
		(start 187.691776 -292.944042)
		(end 187.423044 -292.67531)
		(width 0.18288)
		(layer "In4.Cu")
		(net "M_G_CPU1_SA_DQS_DN<7>")
	)
	(segment
		(start 133.178296 -264.989818)
		(end 133.046724 -265.065764)
		(width 0.088646)
		(layer "In4.Cu")
		(net "M_G_CPU1_SA_DQS_DN<7>")
	)
	(segment
		(start 168.09339 -290.55187)
		(end 167.159178 -290.164774)
		(width 0.18288)
		(layer "In4.Cu")
		(net "M_G_CPU1_SA_DQS_DN<7>")
	)
	(segment
		(start 188.533278 -292.683946)
		(end 188.33592 -292.683946)
		(width 0.18288)
		(layer "In4.Cu")
		(net "M_G_CPU1_SA_DQS_DN<7>")
	)
	(segment
		(start 188.33592 -292.683946)
		(end 188.075824 -292.944042)
		(width 0.18288)
		(layer "In4.Cu")
		(net "M_G_CPU1_SA_DQS_DN<7>")
	)
	(segment
		(start 183.426354 -292.403276)
		(end 183.04256 -292.019482)
		(width 0.18288)
		(layer "In4.Cu")
		(net "M_G_CPU1_SA_DQS_DN<7>")
	)
	(segment
		(start 144.540478 -268.231112)
		(end 143.054578 -267.615924)
		(width 0.18288)
		(layer "In4.Cu")
		(net "M_G_CPU1_SA_DQS_DN<7>")
	)
	(segment
		(start 179.76342 -292.47465)
		(end 178.727862 -292.47465)
		(width 0.18288)
		(layer "In4.Cu")
		(net "M_G_CPU1_SA_DQS_DN<7>")
	)
	(segment
		(start 165.317678 -288.499296)
		(end 164.93109 -288.112708)
		(width 0.18288)
		(layer "In4.Cu")
		(net "M_G_CPU1_SA_DQS_DN<7>")
	)
	(segment
		(start 161.428684 -285.140654)
		(end 161.330894 -284.776418)
		(width 0.18288)
		(layer "In4.Cu")
		(net "M_G_CPU1_SA_DQS_DN<7>")
	)
	(segment
		(start 143.054578 -267.615924)
		(end 142.822676 -267.519912)
		(width 0.18288)
		(layer "In4.Cu")
		(net "M_G_CPU1_SA_DQS_DN<7>")
	)
	(segment
		(start 174.013622 -292.452298)
		(end 173.509178 -292.661086)
		(width 0.18288)
		(layer "In4.Cu")
		(net "M_G_CPU1_SA_DQS_DN<7>")
	)
	(segment
		(start 176.404524 -291.806122)
		(end 175.573436 -291.806122)
		(width 0.18288)
		(layer "In4.Cu")
		(net "M_G_CPU1_SA_DQS_DN<7>")
	)
	(segment
		(start 138.582146 -265.17727)
		(end 137.644886 -265.17727)
		(width 0.088646)
		(layer "In4.Cu")
		(net "M_G_CPU1_SA_DQS_DN<7>")
	)
	(segment
		(start 189.650116 -293.254684)
		(end 189.104016 -293.254684)
		(width 0.18288)
		(layer "In4.Cu")
		(net "M_G_CPU1_SA_DQS_DN<7>")
	)
	(segment
		(start 132.891784 -265.107166)
		(end 132.50037 -265.107166)
		(width 0.088646)
		(layer "In4.Cu")
		(net "M_G_CPU1_SA_DQS_DN<7>")
	)
	(segment
		(start 168.781222 -291.239448)
		(end 168.09339 -290.55187)
		(width 0.18288)
		(layer "In4.Cu")
		(net "M_G_CPU1_SA_DQS_DN<7>")
	)
	(segment
		(start 161.124646 -284.691328)
		(end 160.842198 -284.202378)
		(width 0.18288)
		(layer "In4.Cu")
		(net "M_G_CPU1_SA_DQS_DN<7>")
	)
	(segment
		(start 138.641836 -265.23696)
		(end 138.582146 -265.17727)
		(width 0.088646)
		(layer "In4.Cu")
		(net "M_G_CPU1_SA_DQS_DN<7>")
	)
	(segment
		(start 181.744366 -292.143942)
		(end 181.619906 -292.019482)
		(width 0.18288)
		(layer "In4.Cu")
		(net "M_G_CPU1_SA_DQS_DN<7>")
	)
	(segment
		(start 174.748444 -292.147752)
		(end 174.68088 -292.310566)
		(width 0.18288)
		(layer "In4.Cu")
		(net "M_G_CPU1_SA_DQS_DN<7>")
	)
	(segment
		(start 167.159178 -290.164774)
		(end 166.773098 -289.778694)
		(width 0.18288)
		(layer "In4.Cu")
		(net "M_G_CPU1_SA_DQS_DN<7>")
	)
	(segment
		(start 159.011874 -282.628086)
		(end 158.887414 -282.503626)
		(width 0.18288)
		(layer "In4.Cu")
		(net "M_G_CPU1_SA_DQS_DN<7>")
	)
	(segment
		(start 140.539724 -265.23696)
		(end 138.665204 -265.23696)
		(width 0.18288)
		(layer "In4.Cu")
		(net "M_G_CPU1_SA_DQS_DN<7>")
	)
	(segment
		(start 172.988224 -292.944042)
		(end 172.604176 -292.944042)
		(width 0.18288)
		(layer "In4.Cu")
		(net "M_G_CPU1_SA_DQS_DN<7>")
	)
	(segment
		(start 188.075824 -292.944042)
		(end 187.691776 -292.944042)
		(width 0.18288)
		(layer "In4.Cu")
		(net "M_G_CPU1_SA_DQS_DN<7>")
	)
	(segment
		(start 174.68088 -292.310566)
		(end 174.176182 -292.519608)
		(width 0.18288)
		(layer "In4.Cu")
		(net "M_G_CPU1_SA_DQS_DN<7>")
	)
	(segment
		(start 175.573436 -291.806122)
		(end 174.748444 -292.147752)
		(width 0.18288)
		(layer "In4.Cu")
		(net "M_G_CPU1_SA_DQS_DN<7>")
	)
	(segment
		(start 160.228534 -282.503626)
		(end 159.682434 -282.503626)
		(width 0.18288)
		(layer "In4.Cu")
		(net "M_G_CPU1_SA_DQS_DN<7>")
	)
	(segment
		(start 183.04256 -292.019482)
		(end 182.414926 -292.019482)
		(width 0.18288)
		(layer "In4.Cu")
		(net "M_G_CPU1_SA_DQS_DN<7>")
	)
	(segment
		(start 156.670756 -281.579574)
		(end 154.614372 -276.61489)
		(width 0.18288)
		(layer "In4.Cu")
		(net "M_G_CPU1_SA_DQS_DN<7>")
	)
	(segment
		(start 189.104016 -293.254684)
		(end 188.533278 -292.683946)
		(width 0.18288)
		(layer "In4.Cu")
		(net "M_G_CPU1_SA_DQS_DN<7>")
	)
	(segment
		(start 164.93109 -287.936686)
		(end 164.33165 -287.337246)
		(width 0.18288)
		(layer "In4.Cu")
		(net "M_G_CPU1_SA_DQS_DN<7>")
	)
	(segment
		(start 157.595062 -282.503626)
		(end 156.670756 -281.579574)
		(width 0.18288)
		(layer "In4.Cu")
		(net "M_G_CPU1_SA_DQS_DN<7>")
	)
	(segment
		(start 142.822676 -267.519912)
		(end 140.539724 -265.23696)
		(width 0.18288)
		(layer "In4.Cu")
		(net "M_G_CPU1_SA_DQS_DN<7>")
	)
	(segment
		(start 163.2458 -286.857694)
		(end 163.2458 -286.268668)
		(width 0.18288)
		(layer "In4.Cu")
		(net "M_G_CPU1_SA_DQS_DN<7>")
	)
	(segment
		(start 132.437886 -265.164824)
		(end 132.425948 -265.314176)
		(width 0.088646)
		(layer "In4.Cu")
		(net "M_G_CPU1_SA_DQS_DN<7>")
	)
	(segment
		(start 182.290466 -292.143942)
		(end 181.744366 -292.143942)
		(width 0.18288)
		(layer "In4.Cu")
		(net "M_G_CPU1_SA_DQS_DN<7>")
	)
	(segment
		(start 190.445136 -293.254684)
		(end 190.320676 -293.379144)
		(width 0.18288)
		(layer "In4.Cu")
		(net "M_G_CPU1_SA_DQS_DN<7>")
	)
	(segment
		(start 138.665204 -265.23696)
		(end 138.641836 -265.23696)
		(width 0.088646)
		(layer "In4.Cu")
		(net "M_G_CPU1_SA_DQS_DN<7>")
	)
	(segment
		(start 187.423044 -292.67531)
		(end 187.083192 -292.67531)
		(width 0.18288)
		(layer "In4.Cu")
		(net "M_G_CPU1_SA_DQS_DN<7>")
	)
	(segment
		(start 165.4937 -288.499296)
		(end 165.317678 -288.499296)
		(width 0.18288)
		(layer "In4.Cu")
		(net "M_G_CPU1_SA_DQS_DN<7>")
	)
	(segment
		(start 180.218588 -292.019482)
		(end 179.76342 -292.47465)
		(width 0.18288)
		(layer "In4.Cu")
		(net "M_G_CPU1_SA_DQS_DN<7>")
	)
	(segment
		(start 162.193732 -285.216854)
		(end 161.761424 -285.332678)
		(width 0.18288)
		(layer "In4.Cu")
		(net "M_G_CPU1_SA_DQS_DN<7>")
	)
	(arc
		(start 134.492746 -264.989818)
		(mid 134.308082 -264.939558)
		(end 134.122668 -264.987024)
		(width 0.088646)
		(layer "In4.Cu")
		(net "M_G_CPU1_SA_DQS_DN<7>")
	)
	(arc
		(start 133.552692 -264.989818)
		(mid 133.365494 -264.939675)
		(end 133.178296 -264.989818)
		(width 0.088646)
		(layer "In4.Cu")
		(net "M_G_CPU1_SA_DQS_DN<7>")
	)
	(arc
		(start 134.11835 -264.989818)
		(mid 133.841537 -265.065688)
		(end 133.563106 -264.995914)
		(width 0.088646)
		(layer "In4.Cu")
		(net "M_G_CPU1_SA_DQS_DN<7>")
	)
	(arc
		(start 135.99795 -264.989818)
		(mid 135.723751 -265.065653)
		(end 135.447278 -264.998454)
		(width 0.088646)
		(layer "In4.Cu")
		(net "M_G_CPU1_SA_DQS_DN<7>")
	)
	(arc
		(start 135.432546 -264.989818)
		(mid 135.245348 -264.939675)
		(end 135.05815 -264.989818)
		(width 0.088646)
		(layer "In4.Cu")
		(net "M_G_CPU1_SA_DQS_DN<7>")
	)
	(arc
		(start 136.372346 -264.989818)
		(mid 136.185148 -264.939675)
		(end 135.99795 -264.989818)
		(width 0.088646)
		(layer "In4.Cu")
		(net "M_G_CPU1_SA_DQS_DN<7>")
	)
	(arc
		(start 135.05815 -264.989818)
		(mid 134.783951 -265.065653)
		(end 134.507478 -264.998454)
		(width 0.088646)
		(layer "In4.Cu")
		(net "M_G_CPU1_SA_DQS_DN<7>")
	)
	(arc
		(start 136.93775 -264.989818)
		(mid 136.663551 -265.065653)
		(end 136.387078 -264.998454)
		(width 0.088646)
		(layer "In4.Cu")
		(net "M_G_CPU1_SA_DQS_DN<7>")
	)
	(arc
		(start 137.311384 -264.989564)
		(mid 137.124521 -264.939708)
		(end 136.93775 -264.989818)
		(width 0.088646)
		(layer "In4.Cu")
		(net "M_G_CPU1_SA_DQS_DN<7>")
	)
	(arc
		(start 132.50037 -265.107166)
		(mid 132.457843 -265.123779)
		(end 132.437886 -265.164824)
		(width 0.088646)
		(layer "In4.Cu")
		(net "M_G_CPU1_SA_DQS_DN<7>")
	)
	(segment
		(start 200.128632 -302.716692)
		(end 200.632314 -302.716692)
		(width 0.20066)
		(layer "F.Cu")
		(net "M_G_CPU1_SA_DQS_DN<6>")
	)
	(segment
		(start 193.088514 -302.716692)
		(end 193.61912 -302.716692)
		(width 0.20066)
		(layer "F.Cu")
		(net "M_G_CPU1_SA_DQS_DN<6>")
	)
	(segment
		(start 197.542658 -302.302672)
		(end 197.861428 -302.302672)
		(width 0.20066)
		(layer "F.Cu")
		(net "M_G_CPU1_SA_DQS_DN<6>")
	)
	(segment
		(start 129.136648 -272.103342)
		(end 129.136394 -272.639282)
		(width 0.20066)
		(layer "F.Cu")
		(net "M_G_CPU1_SA_DQS_DN<6>")
	)
	(segment
		(start 197.861428 -302.302672)
		(end 198.147178 -302.016922)
		(width 0.20066)
		(layer "F.Cu")
		(net "M_G_CPU1_SA_DQS_DN<6>")
	)
	(segment
		(start 195.515484 -302.297846)
		(end 195.52158 -302.29175)
		(width 0.1016)
		(layer "F.Cu")
		(net "M_G_CPU1_SA_DQS_DN<6>")
	)
	(segment
		(start 198.637144 -302.016922)
		(end 199.08266 -302.462438)
		(width 0.20066)
		(layer "F.Cu")
		(net "M_G_CPU1_SA_DQS_DN<6>")
	)
	(segment
		(start 193.890392 -302.44542)
		(end 194.373754 -302.44542)
		(width 0.20066)
		(layer "F.Cu")
		(net "M_G_CPU1_SA_DQS_DN<6>")
	)
	(segment
		(start 195.198492 -302.297846)
		(end 195.510658 -302.297846)
		(width 0.20066)
		(layer "F.Cu")
		(net "M_G_CPU1_SA_DQS_DN<6>")
	)
	(segment
		(start 191.983614 -302.716692)
		(end 193.088514 -302.716692)
		(width 0.20066)
		(layer "F.Cu")
		(net "M_G_CPU1_SA_DQS_DN<6>")
	)
	(segment
		(start 194.798696 -302.020478)
		(end 194.921124 -302.020478)
		(width 0.20066)
		(layer "F.Cu")
		(net "M_G_CPU1_SA_DQS_DN<6>")
	)
	(segment
		(start 194.373754 -302.44542)
		(end 194.798696 -302.020478)
		(width 0.20066)
		(layer "F.Cu")
		(net "M_G_CPU1_SA_DQS_DN<6>")
	)
	(segment
		(start 195.52158 -302.29175)
		(end 197.531736 -302.29175)
		(width 0.1016)
		(layer "F.Cu")
		(net "M_G_CPU1_SA_DQS_DN<6>")
	)
	(segment
		(start 195.510658 -302.297846)
		(end 195.515484 -302.297846)
		(width 0.101854)
		(layer "F.Cu")
		(net "M_G_CPU1_SA_DQS_DN<6>")
	)
	(segment
		(start 199.874378 -302.462438)
		(end 200.128632 -302.716692)
		(width 0.20066)
		(layer "F.Cu")
		(net "M_G_CPU1_SA_DQS_DN<6>")
	)
	(segment
		(start 197.531736 -302.29175)
		(end 197.542658 -302.302672)
		(width 0.1016)
		(layer "F.Cu")
		(net "M_G_CPU1_SA_DQS_DN<6>")
	)
	(segment
		(start 198.147178 -302.016922)
		(end 198.637144 -302.016922)
		(width 0.20066)
		(layer "F.Cu")
		(net "M_G_CPU1_SA_DQS_DN<6>")
	)
	(segment
		(start 194.921124 -302.020478)
		(end 195.198492 -302.297846)
		(width 0.20066)
		(layer "F.Cu")
		(net "M_G_CPU1_SA_DQS_DN<6>")
	)
	(segment
		(start 193.61912 -302.716692)
		(end 193.890392 -302.44542)
		(width 0.20066)
		(layer "F.Cu")
		(net "M_G_CPU1_SA_DQS_DN<6>")
	)
	(segment
		(start 199.08266 -302.462438)
		(end 199.874378 -302.462438)
		(width 0.20066)
		(layer "F.Cu")
		(net "M_G_CPU1_SA_DQS_DN<6>")
	)
	(segment
		(start 180.314092 -297.810936)
		(end 179.162202 -296.659046)
		(width 0.18288)
		(layer "In6.Cu")
		(net "M_G_CPU1_SA_DQS_DN<6>")
	)
	(segment
		(start 174.733966 -296.069512)
		(end 173.8757 -295.211246)
		(width 0.18288)
		(layer "In6.Cu")
		(net "M_G_CPU1_SA_DQS_DN<6>")
	)
	(segment
		(start 177.4063 -296.047668)
		(end 177.11293 -296.341038)
		(width 0.18288)
		(layer "In6.Cu")
		(net "M_G_CPU1_SA_DQS_DN<6>")
	)
	(segment
		(start 163.480496 -292.782498)
		(end 163.356036 -292.658038)
		(width 0.18288)
		(layer "In6.Cu")
		(net "M_G_CPU1_SA_DQS_DN<6>")
	)
	(segment
		(start 157.695646 -291.838888)
		(end 156.603954 -290.747196)
		(width 0.18288)
		(layer "In6.Cu")
		(net "M_G_CPU1_SA_DQS_DN<6>")
	)
	(segment
		(start 137.407396 -272.314924)
		(end 137.392664 -272.32356)
		(width 0.088646)
		(layer "In6.Cu")
		(net "M_G_CPU1_SA_DQS_DN<6>")
	)
	(segment
		(start 138.348974 -272.3134)
		(end 138.347958 -272.313908)
		(width 0.088646)
		(layer "In6.Cu")
		(net "M_G_CPU1_SA_DQS_DN<6>")
	)
	(segment
		(start 141.213586 -273.847306)
		(end 140.595604 -273.847306)
		(width 0.18288)
		(layer "In6.Cu")
		(net "M_G_CPU1_SA_DQS_DN<6>")
	)
	(segment
		(start 138.347196 -272.314924)
		(end 138.332464 -272.32356)
		(width 0.088646)
		(layer "In6.Cu")
		(net "M_G_CPU1_SA_DQS_DN<6>")
	)
	(segment
		(start 182.39613 -299.484034)
		(end 180.723032 -297.810936)
		(width 0.18288)
		(layer "In6.Cu")
		(net "M_G_CPU1_SA_DQS_DN<6>")
	)
	(segment
		(start 129.63271 -272.406618)
		(end 129.632456 -272.407126)
		(width 0.088646)
		(layer "In6.Cu")
		(net "M_G_CPU1_SA_DQS_DN<6>")
	)
	(segment
		(start 129.296668 -272.410174)
		(end 129.196592 -272.43024)
		(width 0.088646)
		(layer "In6.Cu")
		(net "M_G_CPU1_SA_DQS_DN<6>")
	)
	(segment
		(start 158.976568 -291.963348)
		(end 158.430468 -291.963348)
		(width 0.18288)
		(layer "In6.Cu")
		(net "M_G_CPU1_SA_DQS_DN<6>")
	)
	(segment
		(start 180.723032 -297.810936)
		(end 180.314092 -297.810936)
		(width 0.18288)
		(layer "In6.Cu")
		(net "M_G_CPU1_SA_DQS_DN<6>")
	)
	(segment
		(start 159.101028 -291.838888)
		(end 158.976568 -291.963348)
		(width 0.18288)
		(layer "In6.Cu")
		(net "M_G_CPU1_SA_DQS_DN<6>")
	)
	(segment
		(start 161.466784 -292.658038)
		(end 159.490918 -291.838888)
		(width 0.18288)
		(layer "In6.Cu")
		(net "M_G_CPU1_SA_DQS_DN<6>")
	)
	(segment
		(start 148.189696 -274.254976)
		(end 142.197836 -274.254976)
		(width 0.18288)
		(layer "In6.Cu")
		(net "M_G_CPU1_SA_DQS_DN<6>")
	)
	(segment
		(start 187.6298 -302.290734)
		(end 187.359798 -302.020732)
		(width 0.18288)
		(layer "In6.Cu")
		(net "M_G_CPU1_SA_DQS_DN<6>")
	)
	(segment
		(start 166.895018 -293.591742)
		(end 166.508684 -293.205408)
		(width 0.18288)
		(layer "In6.Cu")
		(net "M_G_CPU1_SA_DQS_DN<6>")
	)
	(segment
		(start 166.508684 -293.029386)
		(end 166.122604 -292.643306)
		(width 0.18288)
		(layer "In6.Cu")
		(net "M_G_CPU1_SA_DQS_DN<6>")
	)
	(segment
		(start 170.786044 -295.35755)
		(end 170.661584 -295.23309)
		(width 0.18288)
		(layer "In6.Cu")
		(net "M_G_CPU1_SA_DQS_DN<6>")
	)
	(segment
		(start 169.320464 -295.23309)
		(end 168.712388 -295.23309)
		(width 0.18288)
		(layer "In6.Cu")
		(net "M_G_CPU1_SA_DQS_DN<6>")
	)
	(segment
		(start 183.368188 -299.484034)
		(end 182.39613 -299.484034)
		(width 0.18288)
		(layer "In6.Cu")
		(net "M_G_CPU1_SA_DQS_DN<6>")
	)
	(segment
		(start 129.632456 -272.407126)
		(end 129.297176 -272.410174)
		(width 0.088646)
		(layer "In6.Cu")
		(net "M_G_CPU1_SA_DQS_DN<6>")
	)
	(segment
		(start 177.11293 -296.341038)
		(end 176.602644 -296.341038)
		(width 0.18288)
		(layer "In6.Cu")
		(net "M_G_CPU1_SA_DQS_DN<6>")
	)
	(segment
		(start 166.508684 -293.205408)
		(end 166.508684 -293.029386)
		(width 0.18288)
		(layer "In6.Cu")
		(net "M_G_CPU1_SA_DQS_DN<6>")
	)
	(segment
		(start 173.8757 -295.211246)
		(end 173.29277 -295.211246)
		(width 0.18288)
		(layer "In6.Cu")
		(net "M_G_CPU1_SA_DQS_DN<6>")
	)
	(segment
		(start 134.587996 -272.314924)
		(end 134.573264 -272.32356)
		(width 0.088646)
		(layer "In6.Cu")
		(net "M_G_CPU1_SA_DQS_DN<6>")
	)
	(segment
		(start 191.019938 -302.600614)
		(end 189.574932 -302.600614)
		(width 0.18288)
		(layer "In6.Cu")
		(net "M_G_CPU1_SA_DQS_DN<6>")
	)
	(segment
		(start 130.828796 -272.314924)
		(end 130.814064 -272.32356)
		(width 0.088646)
		(layer "In6.Cu")
		(net "M_G_CPU1_SA_DQS_DN<6>")
	)
	(segment
		(start 133.648196 -272.314924)
		(end 133.633464 -272.32356)
		(width 0.088646)
		(layer "In6.Cu")
		(net "M_G_CPU1_SA_DQS_DN<6>")
	)
	(segment
		(start 166.122604 -292.643306)
		(end 165.723062 -292.643306)
		(width 0.18288)
		(layer "In6.Cu")
		(net "M_G_CPU1_SA_DQS_DN<6>")
	)
	(segment
		(start 129.72415 -272.40992)
		(end 129.63271 -272.406618)
		(width 0.088646)
		(layer "In6.Cu")
		(net "M_G_CPU1_SA_DQS_DN<6>")
	)
	(segment
		(start 184.4294 -300.240446)
		(end 184.1246 -300.240446)
		(width 0.18288)
		(layer "In6.Cu")
		(net "M_G_CPU1_SA_DQS_DN<6>")
	)
	(segment
		(start 131.76885 -272.314924)
		(end 131.758436 -272.32102)
		(width 0.088646)
		(layer "In6.Cu")
		(net "M_G_CPU1_SA_DQS_DN<6>")
	)
	(segment
		(start 154.707082 -288.850324)
		(end 154.707082 -280.772362)
		(width 0.18288)
		(layer "In6.Cu")
		(net "M_G_CPU1_SA_DQS_DN<6>")
	)
	(segment
		(start 163.356036 -292.658038)
		(end 162.809936 -292.658038)
		(width 0.18288)
		(layer "In6.Cu")
		(net "M_G_CPU1_SA_DQS_DN<6>")
	)
	(segment
		(start 154.707082 -280.772362)
		(end 148.189696 -274.254976)
		(width 0.18288)
		(layer "In6.Cu")
		(net "M_G_CPU1_SA_DQS_DN<6>")
	)
	(segment
		(start 156.041598 -290.360862)
		(end 156.041598 -290.18484)
		(width 0.18288)
		(layer "In6.Cu")
		(net "M_G_CPU1_SA_DQS_DN<6>")
	)
	(segment
		(start 188.383418 -302.004984)
		(end 188.097668 -302.290734)
		(width 0.18288)
		(layer "In6.Cu")
		(net "M_G_CPU1_SA_DQS_DN<6>")
	)
	(segment
		(start 191.216534 -302.404018)
		(end 191.019938 -302.600614)
		(width 0.18288)
		(layer "In6.Cu")
		(net "M_G_CPU1_SA_DQS_DN<6>")
	)
	(segment
		(start 176.602644 -296.341038)
		(end 176.331118 -296.069512)
		(width 0.18288)
		(layer "In6.Cu")
		(net "M_G_CPU1_SA_DQS_DN<6>")
	)
	(segment
		(start 142.197836 -274.254976)
		(end 141.213586 -273.847306)
		(width 0.18288)
		(layer "In6.Cu")
		(net "M_G_CPU1_SA_DQS_DN<6>")
	)
	(segment
		(start 129.136394 -272.490184)
		(end 129.136394 -272.639282)
		(width 0.088646)
		(layer "In6.Cu")
		(net "M_G_CPU1_SA_DQS_DN<6>")
	)
	(segment
		(start 167.843454 -294.540178)
		(end 167.45712 -294.153844)
		(width 0.18288)
		(layer "In6.Cu")
		(net "M_G_CPU1_SA_DQS_DN<6>")
	)
	(segment
		(start 172.244512 -295.23309)
		(end 171.456604 -295.23309)
		(width 0.18288)
		(layer "In6.Cu")
		(net "M_G_CPU1_SA_DQS_DN<6>")
	)
	(segment
		(start 162.139376 -292.782498)
		(end 162.014916 -292.658038)
		(width 0.18288)
		(layer "In6.Cu")
		(net "M_G_CPU1_SA_DQS_DN<6>")
	)
	(segment
		(start 173.012862 -295.491154)
		(end 172.502576 -295.491154)
		(width 0.18288)
		(layer "In6.Cu")
		(net "M_G_CPU1_SA_DQS_DN<6>")
	)
	(segment
		(start 188.979302 -302.004984)
		(end 188.383418 -302.004984)
		(width 0.18288)
		(layer "In6.Cu")
		(net "M_G_CPU1_SA_DQS_DN<6>")
	)
	(segment
		(start 156.603954 -290.747196)
		(end 156.427932 -290.747196)
		(width 0.18288)
		(layer "In6.Cu")
		(net "M_G_CPU1_SA_DQS_DN<6>")
	)
	(segment
		(start 129.196592 -272.429986)
		(end 129.136394 -272.490184)
		(width 0.088646)
		(layer "In6.Cu")
		(net "M_G_CPU1_SA_DQS_DN<6>")
	)
	(segment
		(start 178.103022 -296.047668)
		(end 177.4063 -296.047668)
		(width 0.18288)
		(layer "In6.Cu")
		(net "M_G_CPU1_SA_DQS_DN<6>")
	)
	(segment
		(start 186.209686 -302.020732)
		(end 184.4294 -300.240446)
		(width 0.18288)
		(layer "In6.Cu")
		(net "M_G_CPU1_SA_DQS_DN<6>")
	)
	(segment
		(start 159.490918 -291.838888)
		(end 159.101028 -291.838888)
		(width 0.18288)
		(layer "In6.Cu")
		(net "M_G_CPU1_SA_DQS_DN<6>")
	)
	(segment
		(start 169.444924 -295.35755)
		(end 169.320464 -295.23309)
		(width 0.18288)
		(layer "In6.Cu")
		(net "M_G_CPU1_SA_DQS_DN<6>")
	)
	(segment
		(start 129.888996 -272.314924)
		(end 129.72415 -272.40992)
		(width 0.088646)
		(layer "In6.Cu")
		(net "M_G_CPU1_SA_DQS_DN<6>")
	)
	(segment
		(start 191.983614 -302.716692)
		(end 191.67094 -302.404018)
		(width 0.18288)
		(layer "In6.Cu")
		(net "M_G_CPU1_SA_DQS_DN<6>")
	)
	(segment
		(start 173.29277 -295.211246)
		(end 173.012862 -295.491154)
		(width 0.18288)
		(layer "In6.Cu")
		(net "M_G_CPU1_SA_DQS_DN<6>")
	)
	(segment
		(start 164.151056 -292.658038)
		(end 164.026596 -292.782498)
		(width 0.18288)
		(layer "In6.Cu")
		(net "M_G_CPU1_SA_DQS_DN<6>")
	)
	(segment
		(start 155.479496 -289.79876)
		(end 155.093162 -289.412426)
		(width 0.18288)
		(layer "In6.Cu")
		(net "M_G_CPU1_SA_DQS_DN<6>")
	)
	(segment
		(start 165.41877 -292.947598)
		(end 164.986716 -292.947598)
		(width 0.18288)
		(layer "In6.Cu")
		(net "M_G_CPU1_SA_DQS_DN<6>")
	)
	(segment
		(start 178.7144 -296.659046)
		(end 178.103022 -296.047668)
		(width 0.18288)
		(layer "In6.Cu")
		(net "M_G_CPU1_SA_DQS_DN<6>")
	)
	(segment
		(start 171.332144 -295.35755)
		(end 170.786044 -295.35755)
		(width 0.18288)
		(layer "In6.Cu")
		(net "M_G_CPU1_SA_DQS_DN<6>")
	)
	(segment
		(start 172.502576 -295.491154)
		(end 172.244512 -295.23309)
		(width 0.18288)
		(layer "In6.Cu")
		(net "M_G_CPU1_SA_DQS_DN<6>")
	)
	(segment
		(start 164.697156 -292.658038)
		(end 164.151056 -292.658038)
		(width 0.18288)
		(layer "In6.Cu")
		(net "M_G_CPU1_SA_DQS_DN<6>")
	)
	(segment
		(start 162.809936 -292.658038)
		(end 162.685476 -292.782498)
		(width 0.18288)
		(layer "In6.Cu")
		(net "M_G_CPU1_SA_DQS_DN<6>")
	)
	(segment
		(start 135.527796 -272.314924)
		(end 135.513064 -272.32356)
		(width 0.088646)
		(layer "In6.Cu")
		(net "M_G_CPU1_SA_DQS_DN<6>")
	)
	(segment
		(start 162.014916 -292.658038)
		(end 161.466784 -292.658038)
		(width 0.18288)
		(layer "In6.Cu")
		(net "M_G_CPU1_SA_DQS_DN<6>")
	)
	(segment
		(start 167.45712 -293.977822)
		(end 167.07104 -293.591742)
		(width 0.18288)
		(layer "In6.Cu")
		(net "M_G_CPU1_SA_DQS_DN<6>")
	)
	(segment
		(start 164.986716 -292.947598)
		(end 164.697156 -292.658038)
		(width 0.18288)
		(layer "In6.Cu")
		(net "M_G_CPU1_SA_DQS_DN<6>")
	)
	(segment
		(start 191.67094 -302.404018)
		(end 191.216534 -302.404018)
		(width 0.18288)
		(layer "In6.Cu")
		(net "M_G_CPU1_SA_DQS_DN<6>")
	)
	(segment
		(start 168.712388 -295.23309)
		(end 168.019476 -294.540178)
		(width 0.18288)
		(layer "In6.Cu")
		(net "M_G_CPU1_SA_DQS_DN<6>")
	)
	(segment
		(start 156.041598 -290.18484)
		(end 155.655518 -289.79876)
		(width 0.18288)
		(layer "In6.Cu")
		(net "M_G_CPU1_SA_DQS_DN<6>")
	)
	(segment
		(start 167.07104 -293.591742)
		(end 166.895018 -293.591742)
		(width 0.18288)
		(layer "In6.Cu")
		(net "M_G_CPU1_SA_DQS_DN<6>")
	)
	(segment
		(start 189.574932 -302.600614)
		(end 188.979302 -302.004984)
		(width 0.18288)
		(layer "In6.Cu")
		(net "M_G_CPU1_SA_DQS_DN<6>")
	)
	(segment
		(start 129.297176 -272.410174)
		(end 129.296668 -272.410174)
		(width 0.088646)
		(layer "In6.Cu")
		(net "M_G_CPU1_SA_DQS_DN<6>")
	)
	(segment
		(start 155.655518 -289.79876)
		(end 155.479496 -289.79876)
		(width 0.18288)
		(layer "In6.Cu")
		(net "M_G_CPU1_SA_DQS_DN<6>")
	)
	(segment
		(start 162.685476 -292.782498)
		(end 162.139376 -292.782498)
		(width 0.18288)
		(layer "In6.Cu")
		(net "M_G_CPU1_SA_DQS_DN<6>")
	)
	(segment
		(start 188.097668 -302.290734)
		(end 187.6298 -302.290734)
		(width 0.18288)
		(layer "In6.Cu")
		(net "M_G_CPU1_SA_DQS_DN<6>")
	)
	(segment
		(start 187.359798 -302.020732)
		(end 186.209686 -302.020732)
		(width 0.18288)
		(layer "In6.Cu")
		(net "M_G_CPU1_SA_DQS_DN<6>")
	)
	(segment
		(start 140.595604 -273.847306)
		(end 140.572236 -273.847306)
		(width 0.088646)
		(layer "In6.Cu")
		(net "M_G_CPU1_SA_DQS_DN<6>")
	)
	(segment
		(start 170.661584 -295.23309)
		(end 170.115484 -295.23309)
		(width 0.18288)
		(layer "In6.Cu")
		(net "M_G_CPU1_SA_DQS_DN<6>")
	)
	(segment
		(start 168.019476 -294.540178)
		(end 167.843454 -294.540178)
		(width 0.18288)
		(layer "In6.Cu")
		(net "M_G_CPU1_SA_DQS_DN<6>")
	)
	(segment
		(start 158.430468 -291.963348)
		(end 158.306008 -291.838888)
		(width 0.18288)
		(layer "In6.Cu")
		(net "M_G_CPU1_SA_DQS_DN<6>")
	)
	(segment
		(start 164.026596 -292.782498)
		(end 163.480496 -292.782498)
		(width 0.18288)
		(layer "In6.Cu")
		(net "M_G_CPU1_SA_DQS_DN<6>")
	)
	(segment
		(start 136.467596 -272.314924)
		(end 136.452864 -272.32356)
		(width 0.088646)
		(layer "In6.Cu")
		(net "M_G_CPU1_SA_DQS_DN<6>")
	)
	(segment
		(start 130.263646 -272.315178)
		(end 130.263392 -272.314924)
		(width 0.088646)
		(layer "In6.Cu")
		(net "M_G_CPU1_SA_DQS_DN<6>")
	)
	(segment
		(start 171.456604 -295.23309)
		(end 171.332144 -295.35755)
		(width 0.18288)
		(layer "In6.Cu")
		(net "M_G_CPU1_SA_DQS_DN<6>")
	)
	(segment
		(start 167.45712 -294.153844)
		(end 167.45712 -293.977822)
		(width 0.18288)
		(layer "In6.Cu")
		(net "M_G_CPU1_SA_DQS_DN<6>")
	)
	(segment
		(start 170.115484 -295.23309)
		(end 169.991024 -295.35755)
		(width 0.18288)
		(layer "In6.Cu")
		(net "M_G_CPU1_SA_DQS_DN<6>")
	)
	(segment
		(start 165.723062 -292.643306)
		(end 165.41877 -292.947598)
		(width 0.18288)
		(layer "In6.Cu")
		(net "M_G_CPU1_SA_DQS_DN<6>")
	)
	(segment
		(start 129.196592 -272.43024)
		(end 129.196592 -272.429986)
		(width 0.088646)
		(layer "In6.Cu")
		(net "M_G_CPU1_SA_DQS_DN<6>")
	)
	(segment
		(start 140.572236 -273.847306)
		(end 140.512292 -273.787362)
		(width 0.088646)
		(layer "In6.Cu")
		(net "M_G_CPU1_SA_DQS_DN<6>")
	)
	(segment
		(start 169.991024 -295.35755)
		(end 169.444924 -295.35755)
		(width 0.18288)
		(layer "In6.Cu")
		(net "M_G_CPU1_SA_DQS_DN<6>")
	)
	(segment
		(start 155.093162 -289.412426)
		(end 155.093162 -289.236404)
		(width 0.18288)
		(layer "In6.Cu")
		(net "M_G_CPU1_SA_DQS_DN<6>")
	)
	(segment
		(start 158.306008 -291.838888)
		(end 157.695646 -291.838888)
		(width 0.18288)
		(layer "In6.Cu")
		(net "M_G_CPU1_SA_DQS_DN<6>")
	)
	(segment
		(start 138.360658 -272.306796)
		(end 138.348974 -272.3134)
		(width 0.088646)
		(layer "In6.Cu")
		(net "M_G_CPU1_SA_DQS_DN<6>")
	)
	(segment
		(start 140.173202 -273.787362)
		(end 138.752834 -272.366994)
		(width 0.088646)
		(layer "In6.Cu")
		(net "M_G_CPU1_SA_DQS_DN<6>")
	)
	(segment
		(start 155.093162 -289.236404)
		(end 154.707082 -288.850324)
		(width 0.18288)
		(layer "In6.Cu")
		(net "M_G_CPU1_SA_DQS_DN<6>")
	)
	(segment
		(start 184.1246 -300.240446)
		(end 183.368188 -299.484034)
		(width 0.18288)
		(layer "In6.Cu")
		(net "M_G_CPU1_SA_DQS_DN<6>")
	)
	(segment
		(start 156.427932 -290.747196)
		(end 156.041598 -290.360862)
		(width 0.18288)
		(layer "In6.Cu")
		(net "M_G_CPU1_SA_DQS_DN<6>")
	)
	(segment
		(start 132.15366 -272.32102)
		(end 132.143246 -272.314924)
		(width 0.088646)
		(layer "In6.Cu")
		(net "M_G_CPU1_SA_DQS_DN<6>")
	)
	(segment
		(start 176.331118 -296.069512)
		(end 174.733966 -296.069512)
		(width 0.18288)
		(layer "In6.Cu")
		(net "M_G_CPU1_SA_DQS_DN<6>")
	)
	(segment
		(start 179.162202 -296.659046)
		(end 178.7144 -296.659046)
		(width 0.18288)
		(layer "In6.Cu")
		(net "M_G_CPU1_SA_DQS_DN<6>")
	)
	(segment
		(start 140.512292 -273.787362)
		(end 140.173202 -273.787362)
		(width 0.088646)
		(layer "In6.Cu")
		(net "M_G_CPU1_SA_DQS_DN<6>")
	)
	(arc
		(start 134.962392 -272.314924)
		(mid 134.775194 -272.264781)
		(end 134.587996 -272.314924)
		(width 0.088646)
		(layer "In6.Cu")
		(net "M_G_CPU1_SA_DQS_DN<6>")
	)
	(arc
		(start 138.332464 -272.32356)
		(mid 138.056023 -272.390726)
		(end 137.781792 -272.314924)
		(width 0.088646)
		(layer "In6.Cu")
		(net "M_G_CPU1_SA_DQS_DN<6>")
	)
	(arc
		(start 135.902192 -272.314924)
		(mid 135.714994 -272.264781)
		(end 135.527796 -272.314924)
		(width 0.088646)
		(layer "In6.Cu")
		(net "M_G_CPU1_SA_DQS_DN<6>")
	)
	(arc
		(start 134.022592 -272.314924)
		(mid 133.835394 -272.264781)
		(end 133.648196 -272.314924)
		(width 0.088646)
		(layer "In6.Cu")
		(net "M_G_CPU1_SA_DQS_DN<6>")
	)
	(arc
		(start 133.633464 -272.32356)
		(mid 133.357023 -272.390726)
		(end 133.082792 -272.314924)
		(width 0.088646)
		(layer "In6.Cu")
		(net "M_G_CPU1_SA_DQS_DN<6>")
	)
	(arc
		(start 136.452864 -272.32356)
		(mid 136.176423 -272.390726)
		(end 135.902192 -272.314924)
		(width 0.088646)
		(layer "In6.Cu")
		(net "M_G_CPU1_SA_DQS_DN<6>")
	)
	(arc
		(start 134.573264 -272.32356)
		(mid 134.296823 -272.390726)
		(end 134.022592 -272.314924)
		(width 0.088646)
		(layer "In6.Cu")
		(net "M_G_CPU1_SA_DQS_DN<6>")
	)
	(arc
		(start 138.347958 -272.313908)
		(mid 138.347577 -272.314416)
		(end 138.347196 -272.314924)
		(width 0.088646)
		(layer "In6.Cu")
		(net "M_G_CPU1_SA_DQS_DN<6>")
	)
	(arc
		(start 138.752834 -272.366994)
		(mid 138.566616 -272.272772)
		(end 138.360658 -272.306796)
		(width 0.088646)
		(layer "In6.Cu")
		(net "M_G_CPU1_SA_DQS_DN<6>")
	)
	(arc
		(start 130.814064 -272.32356)
		(mid 130.537762 -272.390852)
		(end 130.263646 -272.315178)
		(width 0.088646)
		(layer "In6.Cu")
		(net "M_G_CPU1_SA_DQS_DN<6>")
	)
	(arc
		(start 132.708396 -272.314924)
		(mid 132.431837 -272.390633)
		(end 132.15366 -272.32102)
		(width 0.088646)
		(layer "In6.Cu")
		(net "M_G_CPU1_SA_DQS_DN<6>")
	)
	(arc
		(start 133.082792 -272.314924)
		(mid 132.895594 -272.264781)
		(end 132.708396 -272.314924)
		(width 0.088646)
		(layer "In6.Cu")
		(net "M_G_CPU1_SA_DQS_DN<6>")
	)
	(arc
		(start 136.841992 -272.314924)
		(mid 136.654794 -272.264781)
		(end 136.467596 -272.314924)
		(width 0.088646)
		(layer "In6.Cu")
		(net "M_G_CPU1_SA_DQS_DN<6>")
	)
	(arc
		(start 137.392664 -272.32356)
		(mid 137.116223 -272.390726)
		(end 136.841992 -272.314924)
		(width 0.088646)
		(layer "In6.Cu")
		(net "M_G_CPU1_SA_DQS_DN<6>")
	)
	(arc
		(start 131.203192 -272.314924)
		(mid 131.015994 -272.264781)
		(end 130.828796 -272.314924)
		(width 0.088646)
		(layer "In6.Cu")
		(net "M_G_CPU1_SA_DQS_DN<6>")
	)
	(arc
		(start 132.143246 -272.314924)
		(mid 131.956048 -272.264781)
		(end 131.76885 -272.314924)
		(width 0.088646)
		(layer "In6.Cu")
		(net "M_G_CPU1_SA_DQS_DN<6>")
	)
	(arc
		(start 135.513064 -272.32356)
		(mid 135.236623 -272.390726)
		(end 134.962392 -272.314924)
		(width 0.088646)
		(layer "In6.Cu")
		(net "M_G_CPU1_SA_DQS_DN<6>")
	)
	(arc
		(start 130.263392 -272.314924)
		(mid 130.076194 -272.264781)
		(end 129.888996 -272.314924)
		(width 0.088646)
		(layer "In6.Cu")
		(net "M_G_CPU1_SA_DQS_DN<6>")
	)
	(arc
		(start 131.758436 -272.32102)
		(mid 131.480004 -272.390834)
		(end 131.203192 -272.314924)
		(width 0.088646)
		(layer "In6.Cu")
		(net "M_G_CPU1_SA_DQS_DN<6>")
	)
	(arc
		(start 137.781792 -272.314924)
		(mid 137.594594 -272.264781)
		(end 137.407396 -272.314924)
		(width 0.088646)
		(layer "In6.Cu")
		(net "M_G_CPU1_SA_DQS_DN<6>")
	)
	(segment
		(start 191.983614 -312.066686)
		(end 193.088514 -312.066686)
		(width 0.20066)
		(layer "F.Cu")
		(net "M_G_CPU1_SA_DQS_DN<5>")
	)
	(segment
		(start 197.861428 -311.652666)
		(end 198.147178 -311.366916)
		(width 0.20066)
		(layer "F.Cu")
		(net "M_G_CPU1_SA_DQS_DN<5>")
	)
	(segment
		(start 195.515484 -311.64784)
		(end 195.52158 -311.641744)
		(width 0.1016)
		(layer "F.Cu")
		(net "M_G_CPU1_SA_DQS_DN<5>")
	)
	(segment
		(start 195.52158 -311.641744)
		(end 197.531736 -311.641744)
		(width 0.1016)
		(layer "F.Cu")
		(net "M_G_CPU1_SA_DQS_DN<5>")
	)
	(segment
		(start 194.921124 -311.370472)
		(end 195.198492 -311.64784)
		(width 0.20066)
		(layer "F.Cu")
		(net "M_G_CPU1_SA_DQS_DN<5>")
	)
	(segment
		(start 194.798696 -311.370472)
		(end 194.921124 -311.370472)
		(width 0.20066)
		(layer "F.Cu")
		(net "M_G_CPU1_SA_DQS_DN<5>")
	)
	(segment
		(start 195.198492 -311.64784)
		(end 195.510658 -311.64784)
		(width 0.20066)
		(layer "F.Cu")
		(net "M_G_CPU1_SA_DQS_DN<5>")
	)
	(segment
		(start 132.425948 -274.545044)
		(end 132.425948 -275.08073)
		(width 0.20066)
		(layer "F.Cu")
		(net "M_G_CPU1_SA_DQS_DN<5>")
	)
	(segment
		(start 198.637144 -311.366916)
		(end 199.08266 -311.812432)
		(width 0.20066)
		(layer "F.Cu")
		(net "M_G_CPU1_SA_DQS_DN<5>")
	)
	(segment
		(start 199.08266 -311.812432)
		(end 199.874378 -311.812432)
		(width 0.20066)
		(layer "F.Cu")
		(net "M_G_CPU1_SA_DQS_DN<5>")
	)
	(segment
		(start 198.147178 -311.366916)
		(end 198.637144 -311.366916)
		(width 0.20066)
		(layer "F.Cu")
		(net "M_G_CPU1_SA_DQS_DN<5>")
	)
	(segment
		(start 193.61912 -312.066686)
		(end 193.890392 -311.795414)
		(width 0.20066)
		(layer "F.Cu")
		(net "M_G_CPU1_SA_DQS_DN<5>")
	)
	(segment
		(start 199.874378 -311.812432)
		(end 200.128632 -312.066686)
		(width 0.20066)
		(layer "F.Cu")
		(net "M_G_CPU1_SA_DQS_DN<5>")
	)
	(segment
		(start 195.510658 -311.64784)
		(end 195.515484 -311.64784)
		(width 0.101854)
		(layer "F.Cu")
		(net "M_G_CPU1_SA_DQS_DN<5>")
	)
	(segment
		(start 194.373754 -311.795414)
		(end 194.798696 -311.370472)
		(width 0.20066)
		(layer "F.Cu")
		(net "M_G_CPU1_SA_DQS_DN<5>")
	)
	(segment
		(start 193.890392 -311.795414)
		(end 194.373754 -311.795414)
		(width 0.20066)
		(layer "F.Cu")
		(net "M_G_CPU1_SA_DQS_DN<5>")
	)
	(segment
		(start 200.128632 -312.066686)
		(end 200.632314 -312.066686)
		(width 0.20066)
		(layer "F.Cu")
		(net "M_G_CPU1_SA_DQS_DN<5>")
	)
	(segment
		(start 197.542658 -311.652666)
		(end 197.861428 -311.652666)
		(width 0.20066)
		(layer "F.Cu")
		(net "M_G_CPU1_SA_DQS_DN<5>")
	)
	(segment
		(start 132.425694 -274.54479)
		(end 132.425948 -274.545044)
		(width 0.20066)
		(layer "F.Cu")
		(net "M_G_CPU1_SA_DQS_DN<5>")
	)
	(segment
		(start 193.088514 -312.066686)
		(end 193.61912 -312.066686)
		(width 0.20066)
		(layer "F.Cu")
		(net "M_G_CPU1_SA_DQS_DN<5>")
	)
	(segment
		(start 197.531736 -311.641744)
		(end 197.542658 -311.652666)
		(width 0.1016)
		(layer "F.Cu")
		(net "M_G_CPU1_SA_DQS_DN<5>")
	)
	(segment
		(start 153.273252 -303.305972)
		(end 153.273252 -303.305464)
		(width 0.18288)
		(layer "In4.Cu")
		(net "M_G_CPU1_SA_DQS_DN<5>")
	)
	(segment
		(start 161.832544 -309.936642)
		(end 161.76498 -309.773828)
		(width 0.18288)
		(layer "In4.Cu")
		(net "M_G_CPU1_SA_DQS_DN<5>")
	)
	(segment
		(start 166.895018 -311.698894)
		(end 166.060374 -311.3532)
		(width 0.18288)
		(layer "In4.Cu")
		(net "M_G_CPU1_SA_DQS_DN<5>")
	)
	(segment
		(start 163.004246 -310.287162)
		(end 162.499802 -310.078374)
		(width 0.18288)
		(layer "In4.Cu")
		(net "M_G_CPU1_SA_DQS_DN<5>")
	)
	(segment
		(start 142.136622 -280.678128)
		(end 140.470636 -279.012142)
		(width 0.18288)
		(layer "In4.Cu")
		(net "M_G_CPU1_SA_DQS_DN<5>")
	)
	(segment
		(start 177.931572 -313.073542)
		(end 177.362358 -313.073542)
		(width 0.18288)
		(layer "In4.Cu")
		(net "M_G_CPU1_SA_DQS_DN<5>")
	)
	(segment
		(start 162.337242 -310.145684)
		(end 161.832544 -309.936642)
		(width 0.18288)
		(layer "In4.Cu")
		(net "M_G_CPU1_SA_DQS_DN<5>")
	)
	(segment
		(start 172.595032 -314.191904)
		(end 172.330364 -313.927236)
		(width 0.18288)
		(layer "In4.Cu")
		(net "M_G_CPU1_SA_DQS_DN<5>")
	)
	(segment
		(start 172.330364 -313.927236)
		(end 171.77512 -313.927236)
		(width 0.18288)
		(layer "In4.Cu")
		(net "M_G_CPU1_SA_DQS_DN<5>")
	)
	(segment
		(start 185.071512 -311.660286)
		(end 184.281826 -311.660286)
		(width 0.18288)
		(layer "In4.Cu")
		(net "M_G_CPU1_SA_DQS_DN<5>")
	)
	(segment
		(start 188.087762 -311.64276)
		(end 188.048392 -311.64276)
		(width 0.18288)
		(layer "In4.Cu")
		(net "M_G_CPU1_SA_DQS_DN<5>")
	)
	(segment
		(start 181.393084 -312.23585)
		(end 180.110384 -312.23585)
		(width 0.18288)
		(layer "In4.Cu")
		(net "M_G_CPU1_SA_DQS_DN<5>")
	)
	(segment
		(start 164.881814 -311.64657)
		(end 164.56914 -311.333896)
		(width 0.18288)
		(layer "In4.Cu")
		(net "M_G_CPU1_SA_DQS_DN<5>")
	)
	(segment
		(start 135.619998 -275.096478)
		(end 135.619998 -275.080984)
		(width 0.088646)
		(layer "In4.Cu")
		(net "M_G_CPU1_SA_DQS_DN<5>")
	)
	(segment
		(start 157.561026 -308.24297)
		(end 157.481524 -308.24297)
		(width 0.18288)
		(layer "In4.Cu")
		(net "M_G_CPU1_SA_DQS_DN<5>")
	)
	(segment
		(start 164.56914 -311.333896)
		(end 164.05098 -311.333896)
		(width 0.18288)
		(layer "In4.Cu")
		(net "M_G_CPU1_SA_DQS_DN<5>")
	)
	(segment
		(start 136.467596 -275.570442)
		(end 136.452864 -275.579078)
		(width 0.088646)
		(layer "In4.Cu")
		(net "M_G_CPU1_SA_DQS_DN<5>")
	)
	(segment
		(start 137.320782 -276.389338)
		(end 137.311892 -276.384258)
		(width 0.088646)
		(layer "In4.Cu")
		(net "M_G_CPU1_SA_DQS_DN<5>")
	)
	(segment
		(start 137.499344 -276.718522)
		(end 137.499344 -276.708616)
		(width 0.088646)
		(layer "In4.Cu")
		(net "M_G_CPU1_SA_DQS_DN<5>")
	)
	(segment
		(start 133.563106 -274.762468)
		(end 133.552692 -274.756372)
		(width 0.088646)
		(layer "In4.Cu")
		(net "M_G_CPU1_SA_DQS_DN<5>")
	)
	(segment
		(start 165.282626 -311.64657)
		(end 164.881814 -311.64657)
		(width 0.18288)
		(layer "In4.Cu")
		(net "M_G_CPU1_SA_DQS_DN<5>")
	)
	(segment
		(start 187.404756 -311.404508)
		(end 186.357514 -311.404508)
		(width 0.18288)
		(layer "In4.Cu")
		(net "M_G_CPU1_SA_DQS_DN<5>")
	)
	(segment
		(start 142.142972 -280.684732)
		(end 142.136622 -280.678128)
		(width 0.18288)
		(layer "In4.Cu")
		(net "M_G_CPU1_SA_DQS_DN<5>")
	)
	(segment
		(start 157.172914 -307.93436)
		(end 156.609034 -307.93436)
		(width 0.18288)
		(layer "In4.Cu")
		(net "M_G_CPU1_SA_DQS_DN<5>")
	)
	(segment
		(start 184.281826 -311.660286)
		(end 182.70855 -311.973722)
		(width 0.18288)
		(layer "In4.Cu")
		(net "M_G_CPU1_SA_DQS_DN<5>")
	)
	(segment
		(start 143.001492 -282.757118)
		(end 142.142972 -280.684732)
		(width 0.18288)
		(layer "In4.Cu")
		(net "M_G_CPU1_SA_DQS_DN<5>")
	)
	(segment
		(start 135.441436 -274.761706)
		(end 135.432546 -274.756626)
		(width 0.088646)
		(layer "In4.Cu")
		(net "M_G_CPU1_SA_DQS_DN<5>")
	)
	(segment
		(start 153.273252 -303.305464)
		(end 148.643086 -296.376852)
		(width 0.18288)
		(layer "In4.Cu")
		(net "M_G_CPU1_SA_DQS_DN<5>")
	)
	(segment
		(start 191.983614 -312.066686)
		(end 191.68364 -311.766712)
		(width 0.18288)
		(layer "In4.Cu")
		(net "M_G_CPU1_SA_DQS_DN<5>")
	)
	(segment
		(start 187.642754 -311.642506)
		(end 187.404756 -311.404508)
		(width 0.18288)
		(layer "In4.Cu")
		(net "M_G_CPU1_SA_DQS_DN<5>")
	)
	(segment
		(start 154.123136 -304.577496)
		(end 153.715212 -303.967134)
		(width 0.18288)
		(layer "In4.Cu")
		(net "M_G_CPU1_SA_DQS_DN<5>")
	)
	(segment
		(start 188.048138 -311.642506)
		(end 187.642754 -311.642506)
		(width 0.18288)
		(layer "In4.Cu")
		(net "M_G_CPU1_SA_DQS_DN<5>")
	)
	(segment
		(start 154.088846 -304.749962)
		(end 154.123136 -304.577496)
		(width 0.18288)
		(layer "In4.Cu")
		(net "M_G_CPU1_SA_DQS_DN<5>")
	)
	(segment
		(start 154.392376 -305.204368)
		(end 154.088846 -304.749962)
		(width 0.18288)
		(layer "In4.Cu")
		(net "M_G_CPU1_SA_DQS_DN<5>")
	)
	(segment
		(start 157.481524 -308.24297)
		(end 157.172914 -307.93436)
		(width 0.18288)
		(layer "In4.Cu")
		(net "M_G_CPU1_SA_DQS_DN<5>")
	)
	(segment
		(start 153.542746 -303.932844)
		(end 153.238962 -303.478438)
		(width 0.18288)
		(layer "In4.Cu")
		(net "M_G_CPU1_SA_DQS_DN<5>")
	)
	(segment
		(start 189.939168 -311.949338)
		(end 188.53658 -311.367932)
		(width 0.18288)
		(layer "In4.Cu")
		(net "M_G_CPU1_SA_DQS_DN<5>")
	)
	(segment
		(start 167.62984 -312.00344)
		(end 167.46728 -312.07075)
		(width 0.18288)
		(layer "In4.Cu")
		(net "M_G_CPU1_SA_DQS_DN<5>")
	)
	(segment
		(start 169.939716 -312.700924)
		(end 168.596056 -312.292746)
		(width 0.18288)
		(layer "In4.Cu")
		(net "M_G_CPU1_SA_DQS_DN<5>")
	)
	(segment
		(start 171.321222 -313.62396)
		(end 171.148502 -313.65825)
		(width 0.18288)
		(layer "In4.Cu")
		(net "M_G_CPU1_SA_DQS_DN<5>")
	)
	(segment
		(start 157.815026 -308.24297)
		(end 157.813248 -308.241192)
		(width 0.18288)
		(layer "In4.Cu")
		(net "M_G_CPU1_SA_DQS_DN<5>")
	)
	(segment
		(start 177.09388 -313.341766)
		(end 176.636172 -313.341766)
		(width 0.18288)
		(layer "In4.Cu")
		(net "M_G_CPU1_SA_DQS_DN<5>")
	)
	(segment
		(start 157.562804 -308.241192)
		(end 157.561026 -308.24297)
		(width 0.18288)
		(layer "In4.Cu")
		(net "M_G_CPU1_SA_DQS_DN<5>")
	)
	(segment
		(start 171.148502 -313.65825)
		(end 170.69435 -313.354466)
		(width 0.18288)
		(layer "In4.Cu")
		(net "M_G_CPU1_SA_DQS_DN<5>")
	)
	(segment
		(start 191.68364 -311.766712)
		(end 191.510158 -311.766712)
		(width 0.18288)
		(layer "In4.Cu")
		(net "M_G_CPU1_SA_DQS_DN<5>")
	)
	(segment
		(start 153.238962 -303.478438)
		(end 153.273252 -303.305972)
		(width 0.18288)
		(layer "In4.Cu")
		(net "M_G_CPU1_SA_DQS_DN<5>")
	)
	(segment
		(start 180.110384 -312.23585)
		(end 179.985924 -312.36031)
		(width 0.18288)
		(layer "In4.Cu")
		(net "M_G_CPU1_SA_DQS_DN<5>")
	)
	(segment
		(start 161.76498 -309.773828)
		(end 161.163254 -309.524654)
		(width 0.18288)
		(layer "In4.Cu")
		(net "M_G_CPU1_SA_DQS_DN<5>")
	)
	(segment
		(start 170.69435 -313.354466)
		(end 170.66006 -313.182254)
		(width 0.18288)
		(layer "In4.Cu")
		(net "M_G_CPU1_SA_DQS_DN<5>")
	)
	(segment
		(start 181.928516 -312.12917)
		(end 181.393084 -312.23585)
		(width 0.18288)
		(layer "In4.Cu")
		(net "M_G_CPU1_SA_DQS_DN<5>")
	)
	(segment
		(start 172.990002 -314.191904)
		(end 172.595032 -314.191904)
		(width 0.18288)
		(layer "In4.Cu")
		(net "M_G_CPU1_SA_DQS_DN<5>")
	)
	(segment
		(start 134.512812 -274.768056)
		(end 134.492746 -274.756372)
		(width 0.088646)
		(layer "In4.Cu")
		(net "M_G_CPU1_SA_DQS_DN<5>")
	)
	(segment
		(start 140.454126 -278.911304)
		(end 139.627102 -278.08428)
		(width 0.088646)
		(layer "In4.Cu")
		(net "M_G_CPU1_SA_DQS_DN<5>")
	)
	(segment
		(start 176.636172 -313.341766)
		(end 176.397666 -313.10326)
		(width 0.18288)
		(layer "In4.Cu")
		(net "M_G_CPU1_SA_DQS_DN<5>")
	)
	(segment
		(start 148.643086 -296.376852)
		(end 143.001492 -282.757118)
		(width 0.18288)
		(layer "In4.Cu")
		(net "M_G_CPU1_SA_DQS_DN<5>")
	)
	(segment
		(start 139.627102 -278.083772)
		(end 138.692128 -277.148798)
		(width 0.088646)
		(layer "In4.Cu")
		(net "M_G_CPU1_SA_DQS_DN<5>")
	)
	(segment
		(start 188.53658 -311.367932)
		(end 188.36259 -311.367932)
		(width 0.18288)
		(layer "In4.Cu")
		(net "M_G_CPU1_SA_DQS_DN<5>")
	)
	(segment
		(start 173.491398 -313.910472)
		(end 173.271434 -313.910472)
		(width 0.18288)
		(layer "In4.Cu")
		(net "M_G_CPU1_SA_DQS_DN<5>")
	)
	(segment
		(start 179.439824 -312.36031)
		(end 179.315364 -312.23585)
		(width 0.18288)
		(layer "In4.Cu")
		(net "M_G_CPU1_SA_DQS_DN<5>")
	)
	(segment
		(start 177.362358 -313.073542)
		(end 177.09388 -313.341766)
		(width 0.18288)
		(layer "In4.Cu")
		(net "M_G_CPU1_SA_DQS_DN<5>")
	)
	(segment
		(start 182.61076 -312.12028)
		(end 182.07482 -312.22696)
		(width 0.18288)
		(layer "In4.Cu")
		(net "M_G_CPU1_SA_DQS_DN<5>")
	)
	(segment
		(start 179.315364 -312.23585)
		(end 178.769264 -312.23585)
		(width 0.18288)
		(layer "In4.Cu")
		(net "M_G_CPU1_SA_DQS_DN<5>")
	)
	(segment
		(start 173.271434 -313.910472)
		(end 172.990002 -314.191904)
		(width 0.18288)
		(layer "In4.Cu")
		(net "M_G_CPU1_SA_DQS_DN<5>")
	)
	(segment
		(start 182.70855 -311.973722)
		(end 182.61076 -312.12028)
		(width 0.18288)
		(layer "In4.Cu")
		(net "M_G_CPU1_SA_DQS_DN<5>")
	)
	(segment
		(start 155.877768 -307.203094)
		(end 154.565096 -305.238658)
		(width 0.18288)
		(layer "In4.Cu")
		(net "M_G_CPU1_SA_DQS_DN<5>")
	)
	(segment
		(start 166.060374 -311.3532)
		(end 165.575996 -311.3532)
		(width 0.18288)
		(layer "In4.Cu")
		(net "M_G_CPU1_SA_DQS_DN<5>")
	)
	(segment
		(start 182.07482 -312.22696)
		(end 181.928516 -312.12917)
		(width 0.18288)
		(layer "In4.Cu")
		(net "M_G_CPU1_SA_DQS_DN<5>")
	)
	(segment
		(start 171.77512 -313.927236)
		(end 171.321222 -313.62396)
		(width 0.18288)
		(layer "In4.Cu")
		(net "M_G_CPU1_SA_DQS_DN<5>")
	)
	(segment
		(start 160.495742 -309.382922)
		(end 160.428432 -309.220108)
		(width 0.18288)
		(layer "In4.Cu")
		(net "M_G_CPU1_SA_DQS_DN<5>")
	)
	(segment
		(start 191.510158 -311.766712)
		(end 191.069214 -311.949338)
		(width 0.18288)
		(layer "In4.Cu")
		(net "M_G_CPU1_SA_DQS_DN<5>")
	)
	(segment
		(start 132.623814 -274.896072)
		(end 132.601462 -274.905216)
		(width 0.088646)
		(layer "In4.Cu")
		(net "M_G_CPU1_SA_DQS_DN<5>")
	)
	(segment
		(start 156.609034 -307.93436)
		(end 155.877768 -307.203094)
		(width 0.18288)
		(layer "In4.Cu")
		(net "M_G_CPU1_SA_DQS_DN<5>")
	)
	(segment
		(start 133.552692 -274.756372)
		(end 133.55066 -274.755102)
		(width 0.088646)
		(layer "In4.Cu")
		(net "M_G_CPU1_SA_DQS_DN<5>")
	)
	(segment
		(start 161.163254 -309.524654)
		(end 161.000694 -309.591964)
		(width 0.18288)
		(layer "In4.Cu")
		(net "M_G_CPU1_SA_DQS_DN<5>")
	)
	(segment
		(start 170.66006 -313.182254)
		(end 169.939716 -312.700924)
		(width 0.18288)
		(layer "In4.Cu")
		(net "M_G_CPU1_SA_DQS_DN<5>")
	)
	(segment
		(start 138.560302 -277.148798)
		(end 138.555222 -277.148544)
		(width 0.088646)
		(layer "In4.Cu")
		(net "M_G_CPU1_SA_DQS_DN<5>")
	)
	(segment
		(start 168.596056 -312.292746)
		(end 168.328848 -312.292746)
		(width 0.18288)
		(layer "In4.Cu")
		(net "M_G_CPU1_SA_DQS_DN<5>")
	)
	(segment
		(start 166.962582 -311.861708)
		(end 166.895018 -311.698894)
		(width 0.18288)
		(layer "In4.Cu")
		(net "M_G_CPU1_SA_DQS_DN<5>")
	)
	(segment
		(start 139.627102 -278.08428)
		(end 139.627102 -278.083772)
		(width 0.088646)
		(layer "In4.Cu")
		(net "M_G_CPU1_SA_DQS_DN<5>")
	)
	(segment
		(start 175.431196 -313.10326)
		(end 173.491398 -313.910472)
		(width 0.18288)
		(layer "In4.Cu")
		(net "M_G_CPU1_SA_DQS_DN<5>")
	)
	(segment
		(start 161.000694 -309.591964)
		(end 160.495742 -309.382922)
		(width 0.18288)
		(layer "In4.Cu")
		(net "M_G_CPU1_SA_DQS_DN<5>")
	)
	(segment
		(start 132.873242 -274.896072)
		(end 132.623814 -274.896072)
		(width 0.088646)
		(layer "In4.Cu")
		(net "M_G_CPU1_SA_DQS_DN<5>")
	)
	(segment
		(start 167.46728 -312.07075)
		(end 166.962582 -311.861708)
		(width 0.18288)
		(layer "In4.Cu")
		(net "M_G_CPU1_SA_DQS_DN<5>")
	)
	(segment
		(start 132.601462 -274.905216)
		(end 132.425948 -275.08073)
		(width 0.088646)
		(layer "In4.Cu")
		(net "M_G_CPU1_SA_DQS_DN<5>")
	)
	(segment
		(start 160.428432 -309.220108)
		(end 159.187642 -308.706266)
		(width 0.18288)
		(layer "In4.Cu")
		(net "M_G_CPU1_SA_DQS_DN<5>")
	)
	(segment
		(start 186.357514 -311.404508)
		(end 185.071512 -311.660286)
		(width 0.18288)
		(layer "In4.Cu")
		(net "M_G_CPU1_SA_DQS_DN<5>")
	)
	(segment
		(start 136.850882 -275.575522)
		(end 136.841992 -275.570442)
		(width 0.088646)
		(layer "In4.Cu")
		(net "M_G_CPU1_SA_DQS_DN<5>")
	)
	(segment
		(start 178.769264 -312.23585)
		(end 177.931572 -313.073542)
		(width 0.18288)
		(layer "In4.Cu")
		(net "M_G_CPU1_SA_DQS_DN<5>")
	)
	(segment
		(start 140.470636 -279.012142)
		(end 140.454126 -278.995632)
		(width 0.088646)
		(layer "In4.Cu")
		(net "M_G_CPU1_SA_DQS_DN<5>")
	)
	(segment
		(start 133.178296 -274.756372)
		(end 133.023102 -274.845526)
		(width 0.088646)
		(layer "In4.Cu")
		(net "M_G_CPU1_SA_DQS_DN<5>")
	)
	(segment
		(start 158.19247 -307.970174)
		(end 157.919674 -308.24297)
		(width 0.18288)
		(layer "In4.Cu")
		(net "M_G_CPU1_SA_DQS_DN<5>")
	)
	(segment
		(start 138.692128 -277.148798)
		(end 138.560302 -277.148798)
		(width 0.088646)
		(layer "In4.Cu")
		(net "M_G_CPU1_SA_DQS_DN<5>")
	)
	(segment
		(start 133.023102 -274.845526)
		(end 132.873242 -274.896072)
		(width 0.088646)
		(layer "In4.Cu")
		(net "M_G_CPU1_SA_DQS_DN<5>")
	)
	(segment
		(start 188.36259 -311.367932)
		(end 188.087762 -311.64276)
		(width 0.18288)
		(layer "In4.Cu")
		(net "M_G_CPU1_SA_DQS_DN<5>")
	)
	(segment
		(start 154.565096 -305.238658)
		(end 154.392376 -305.204368)
		(width 0.18288)
		(layer "In4.Cu")
		(net "M_G_CPU1_SA_DQS_DN<5>")
	)
	(segment
		(start 137.029444 -275.904706)
		(end 137.029444 -275.8948)
		(width 0.088646)
		(layer "In4.Cu")
		(net "M_G_CPU1_SA_DQS_DN<5>")
	)
	(segment
		(start 159.187642 -308.706266)
		(end 158.45155 -307.970174)
		(width 0.18288)
		(layer "In4.Cu")
		(net "M_G_CPU1_SA_DQS_DN<5>")
	)
	(segment
		(start 138.346942 -277.198074)
		(end 138.347196 -277.198074)
		(width 0.088646)
		(layer "In4.Cu")
		(net "M_G_CPU1_SA_DQS_DN<5>")
	)
	(segment
		(start 157.919674 -308.24297)
		(end 157.815026 -308.24297)
		(width 0.18288)
		(layer "In4.Cu")
		(net "M_G_CPU1_SA_DQS_DN<5>")
	)
	(segment
		(start 140.454126 -278.995632)
		(end 140.454126 -278.911304)
		(width 0.088646)
		(layer "In4.Cu")
		(net "M_G_CPU1_SA_DQS_DN<5>")
	)
	(segment
		(start 168.328848 -312.292746)
		(end 167.62984 -312.00344)
		(width 0.18288)
		(layer "In4.Cu")
		(net "M_G_CPU1_SA_DQS_DN<5>")
	)
	(segment
		(start 157.813248 -308.241192)
		(end 157.562804 -308.241192)
		(width 0.18288)
		(layer "In4.Cu")
		(net "M_G_CPU1_SA_DQS_DN<5>")
	)
	(segment
		(start 179.985924 -312.36031)
		(end 179.439824 -312.36031)
		(width 0.18288)
		(layer "In4.Cu")
		(net "M_G_CPU1_SA_DQS_DN<5>")
	)
	(segment
		(start 191.069214 -311.949338)
		(end 189.939168 -311.949338)
		(width 0.18288)
		(layer "In4.Cu")
		(net "M_G_CPU1_SA_DQS_DN<5>")
	)
	(segment
		(start 162.499802 -310.078374)
		(end 162.337242 -310.145684)
		(width 0.18288)
		(layer "In4.Cu")
		(net "M_G_CPU1_SA_DQS_DN<5>")
	)
	(segment
		(start 176.397666 -313.10326)
		(end 175.431196 -313.10326)
		(width 0.18288)
		(layer "In4.Cu")
		(net "M_G_CPU1_SA_DQS_DN<5>")
	)
	(segment
		(start 158.45155 -307.970174)
		(end 158.19247 -307.970174)
		(width 0.18288)
		(layer "In4.Cu")
		(net "M_G_CPU1_SA_DQS_DN<5>")
	)
	(segment
		(start 165.575996 -311.3532)
		(end 165.282626 -311.64657)
		(width 0.18288)
		(layer "In4.Cu")
		(net "M_G_CPU1_SA_DQS_DN<5>")
	)
	(segment
		(start 164.05098 -311.333896)
		(end 163.004246 -310.287162)
		(width 0.18288)
		(layer "In4.Cu")
		(net "M_G_CPU1_SA_DQS_DN<5>")
	)
	(segment
		(start 188.048392 -311.64276)
		(end 188.048138 -311.642506)
		(width 0.18288)
		(layer "In4.Cu")
		(net "M_G_CPU1_SA_DQS_DN<5>")
	)
	(segment
		(start 153.715212 -303.967134)
		(end 153.542746 -303.932844)
		(width 0.18288)
		(layer "In4.Cu")
		(net "M_G_CPU1_SA_DQS_DN<5>")
	)
	(arc
		(start 134.492746 -274.756372)
		(mid 134.305548 -274.706229)
		(end 134.11835 -274.756372)
		(width 0.088646)
		(layer "In4.Cu")
		(net "M_G_CPU1_SA_DQS_DN<5>")
	)
	(arc
		(start 137.781792 -277.198074)
		(mid 137.577457 -276.995469)
		(end 137.499344 -276.718522)
		(width 0.088646)
		(layer "In4.Cu")
		(net "M_G_CPU1_SA_DQS_DN<5>")
	)
	(arc
		(start 136.452864 -275.579078)
		(mid 136.176389 -275.646398)
		(end 135.902192 -275.570442)
		(width 0.088646)
		(layer "In4.Cu")
		(net "M_G_CPU1_SA_DQS_DN<5>")
	)
	(arc
		(start 135.902192 -275.570442)
		(mid 135.699369 -275.370211)
		(end 135.619998 -275.096478)
		(width 0.088646)
		(layer "In4.Cu")
		(net "M_G_CPU1_SA_DQS_DN<5>")
	)
	(arc
		(start 135.619998 -275.080984)
		(mid 135.572319 -274.898084)
		(end 135.441436 -274.761706)
		(width 0.088646)
		(layer "In4.Cu")
		(net "M_G_CPU1_SA_DQS_DN<5>")
	)
	(arc
		(start 135.05815 -274.756626)
		(mid 134.786961 -274.832373)
		(end 134.512812 -274.768056)
		(width 0.088646)
		(layer "In4.Cu")
		(net "M_G_CPU1_SA_DQS_DN<5>")
	)
	(arc
		(start 138.555222 -277.148544)
		(mid 138.447471 -277.158117)
		(end 138.346942 -277.198074)
		(width 0.088646)
		(layer "In4.Cu")
		(net "M_G_CPU1_SA_DQS_DN<5>")
	)
	(arc
		(start 134.11835 -274.756372)
		(mid 133.841537 -274.832242)
		(end 133.563106 -274.762468)
		(width 0.088646)
		(layer "In4.Cu")
		(net "M_G_CPU1_SA_DQS_DN<5>")
	)
	(arc
		(start 138.347196 -277.198074)
		(mid 138.064494 -277.27385)
		(end 137.781792 -277.198074)
		(width 0.088646)
		(layer "In4.Cu")
		(net "M_G_CPU1_SA_DQS_DN<5>")
	)
	(arc
		(start 137.029444 -275.8948)
		(mid 136.981765 -275.7119)
		(end 136.850882 -275.575522)
		(width 0.088646)
		(layer "In4.Cu")
		(net "M_G_CPU1_SA_DQS_DN<5>")
	)
	(arc
		(start 135.432546 -274.756626)
		(mid 135.245348 -274.706483)
		(end 135.05815 -274.756626)
		(width 0.088646)
		(layer "In4.Cu")
		(net "M_G_CPU1_SA_DQS_DN<5>")
	)
	(arc
		(start 133.55066 -274.755102)
		(mid 133.364297 -274.706139)
		(end 133.178296 -274.756372)
		(width 0.088646)
		(layer "In4.Cu")
		(net "M_G_CPU1_SA_DQS_DN<5>")
	)
	(arc
		(start 136.841992 -275.570442)
		(mid 136.654794 -275.520299)
		(end 136.467596 -275.570442)
		(width 0.088646)
		(layer "In4.Cu")
		(net "M_G_CPU1_SA_DQS_DN<5>")
	)
	(arc
		(start 137.499344 -276.708616)
		(mid 137.451665 -276.525716)
		(end 137.320782 -276.389338)
		(width 0.088646)
		(layer "In4.Cu")
		(net "M_G_CPU1_SA_DQS_DN<5>")
	)
	(arc
		(start 137.311892 -276.384258)
		(mid 137.107557 -276.181653)
		(end 137.029444 -275.904706)
		(width 0.088646)
		(layer "In4.Cu")
		(net "M_G_CPU1_SA_DQS_DN<5>")
	)
	(segment
		(start 195.702428 -274.907248)
		(end 195.942966 -274.66671)
		(width 0.20066)
		(layer "F.Cu")
		(net "M_G_CPU1_SA_DQS_DN<4>")
	)
	(segment
		(start 191.490854 -275.362924)
		(end 191.762126 -275.091652)
		(width 0.20066)
		(layer "F.Cu")
		(net "M_G_CPU1_SA_DQS_DN<4>")
	)
	(segment
		(start 191.845184 -275.091652)
		(end 191.914018 -275.091652)
		(width 0.101854)
		(layer "F.Cu")
		(net "M_G_CPU1_SA_DQS_DN<4>")
	)
	(segment
		(start 188.988446 -274.66671)
		(end 189.537086 -274.66671)
		(width 0.20066)
		(layer "F.Cu")
		(net "M_G_CPU1_SA_DQS_DN<4>")
	)
	(segment
		(start 194.093592 -275.091652)
		(end 194.277742 -275.091652)
		(width 0.101854)
		(layer "F.Cu")
		(net "M_G_CPU1_SA_DQS_DN<4>")
	)
	(segment
		(start 189.818772 -274.948396)
		(end 190.393828 -274.948396)
		(width 0.20066)
		(layer "F.Cu")
		(net "M_G_CPU1_SA_DQS_DN<4>")
	)
	(segment
		(start 194.428364 -275.091652)
		(end 194.654424 -275.317712)
		(width 0.20066)
		(layer "F.Cu")
		(net "M_G_CPU1_SA_DQS_DN<4>")
	)
	(segment
		(start 127.257048 -262.87222)
		(end 127.256794 -262.872474)
		(width 0.20066)
		(layer "F.Cu")
		(net "M_G_CPU1_SA_DQS_DN<4>")
	)
	(segment
		(start 195.942966 -274.66671)
		(end 196.532246 -274.66671)
		(width 0.20066)
		(layer "F.Cu")
		(net "M_G_CPU1_SA_DQS_DN<4>")
	)
	(segment
		(start 189.537086 -274.66671)
		(end 189.818772 -274.948396)
		(width 0.20066)
		(layer "F.Cu")
		(net "M_G_CPU1_SA_DQS_DN<4>")
	)
	(segment
		(start 190.808356 -275.362924)
		(end 191.490854 -275.362924)
		(width 0.20066)
		(layer "F.Cu")
		(net "M_G_CPU1_SA_DQS_DN<4>")
	)
	(segment
		(start 195.369942 -274.907248)
		(end 195.702428 -274.907248)
		(width 0.20066)
		(layer "F.Cu")
		(net "M_G_CPU1_SA_DQS_DN<4>")
	)
	(segment
		(start 194.277742 -275.091652)
		(end 194.428364 -275.091652)
		(width 0.20066)
		(layer "F.Cu")
		(net "M_G_CPU1_SA_DQS_DN<4>")
	)
	(segment
		(start 191.914018 -275.091652)
		(end 194.093592 -275.091652)
		(width 0.1016)
		(layer "F.Cu")
		(net "M_G_CPU1_SA_DQS_DN<4>")
	)
	(segment
		(start 194.959478 -275.317712)
		(end 195.369942 -274.907248)
		(width 0.20066)
		(layer "F.Cu")
		(net "M_G_CPU1_SA_DQS_DN<4>")
	)
	(segment
		(start 187.883546 -274.66671)
		(end 188.988446 -274.66671)
		(width 0.20066)
		(layer "F.Cu")
		(net "M_G_CPU1_SA_DQS_DN<4>")
	)
	(segment
		(start 127.257048 -262.336534)
		(end 127.257048 -262.87222)
		(width 0.20066)
		(layer "F.Cu")
		(net "M_G_CPU1_SA_DQS_DN<4>")
	)
	(segment
		(start 190.393828 -274.948396)
		(end 190.808356 -275.362924)
		(width 0.20066)
		(layer "F.Cu")
		(net "M_G_CPU1_SA_DQS_DN<4>")
	)
	(segment
		(start 191.762126 -275.091652)
		(end 191.845184 -275.091652)
		(width 0.20066)
		(layer "F.Cu")
		(net "M_G_CPU1_SA_DQS_DN<4>")
	)
	(segment
		(start 194.654424 -275.317712)
		(end 194.959478 -275.317712)
		(width 0.20066)
		(layer "F.Cu")
		(net "M_G_CPU1_SA_DQS_DN<4>")
	)
	(segment
		(start 182.23865 -271.178528)
		(end 182.11419 -271.054068)
		(width 0.18288)
		(layer "In6.Cu")
		(net "M_G_CPU1_SA_DQS_DN<4>")
	)
	(segment
		(start 186.965336 -274.664678)
		(end 186.025536 -274.664678)
		(width 0.18288)
		(layer "In6.Cu")
		(net "M_G_CPU1_SA_DQS_DN<4>")
	)
	(segment
		(start 140.297662 -262.402066)
		(end 140.092684 -262.60679)
		(width 0.088646)
		(layer "In6.Cu")
		(net "M_G_CPU1_SA_DQS_DN<4>")
	)
	(segment
		(start 178.686968 -266.612878)
		(end 178.064414 -265.990324)
		(width 0.18288)
		(layer "In6.Cu")
		(net "M_G_CPU1_SA_DQS_DN<4>")
	)
	(segment
		(start 179.878228 -266.104878)
		(end 179.370228 -266.612878)
		(width 0.18288)
		(layer "In6.Cu")
		(net "M_G_CPU1_SA_DQS_DN<4>")
	)
	(segment
		(start 138.736578 -263.188196)
		(end 138.721846 -263.196832)
		(width 0.088646)
		(layer "In6.Cu")
		(net "M_G_CPU1_SA_DQS_DN<4>")
	)
	(segment
		(start 187.883546 -274.66671)
		(end 187.63107 -274.91817)
		(width 0.18288)
		(layer "In6.Cu")
		(net "M_G_CPU1_SA_DQS_DN<4>")
	)
	(segment
		(start 182.11419 -271.054068)
		(end 182.11419 -270.135096)
		(width 0.18288)
		(layer "In6.Cu")
		(net "M_G_CPU1_SA_DQS_DN<4>")
	)
	(segment
		(start 131.76885 -263.196832)
		(end 131.758436 -263.190736)
		(width 0.088646)
		(layer "In6.Cu")
		(net "M_G_CPU1_SA_DQS_DN<4>")
	)
	(segment
		(start 128.949196 -263.196832)
		(end 128.934464 -263.188196)
		(width 0.088646)
		(layer "In6.Cu")
		(net "M_G_CPU1_SA_DQS_DN<4>")
	)
	(segment
		(start 182.11419 -269.340076)
		(end 182.11419 -267.699236)
		(width 0.18288)
		(layer "In6.Cu")
		(net "M_G_CPU1_SA_DQS_DN<4>")
	)
	(segment
		(start 155.904692 -262.826246)
		(end 145.271236 -262.826246)
		(width 0.18288)
		(layer "In6.Cu")
		(net "M_G_CPU1_SA_DQS_DN<4>")
	)
	(segment
		(start 134.587996 -263.196832)
		(end 134.573264 -263.188196)
		(width 0.088646)
		(layer "In6.Cu")
		(net "M_G_CPU1_SA_DQS_DN<4>")
	)
	(segment
		(start 174.018194 -265.14044)
		(end 173.313598 -265.14044)
		(width 0.18288)
		(layer "In6.Cu")
		(net "M_G_CPU1_SA_DQS_DN<4>")
	)
	(segment
		(start 172.279564 -265.14933)
		(end 169.392854 -265.14933)
		(width 0.18288)
		(layer "In6.Cu")
		(net "M_G_CPU1_SA_DQS_DN<4>")
	)
	(segment
		(start 176.35855 -266.020296)
		(end 174.89805 -266.020296)
		(width 0.18288)
		(layer "In6.Cu")
		(net "M_G_CPU1_SA_DQS_DN<4>")
	)
	(segment
		(start 182.11419 -271.849088)
		(end 182.23865 -271.724628)
		(width 0.18288)
		(layer "In6.Cu")
		(net "M_G_CPU1_SA_DQS_DN<4>")
	)
	(segment
		(start 140.572236 -262.342376)
		(end 140.512546 -262.402066)
		(width 0.088646)
		(layer "In6.Cu")
		(net "M_G_CPU1_SA_DQS_DN<4>")
	)
	(segment
		(start 187.218828 -274.91817)
		(end 186.965336 -274.664678)
		(width 0.18288)
		(layer "In6.Cu")
		(net "M_G_CPU1_SA_DQS_DN<4>")
	)
	(segment
		(start 182.23865 -271.724628)
		(end 182.23865 -271.178528)
		(width 0.18288)
		(layer "In6.Cu")
		(net "M_G_CPU1_SA_DQS_DN<4>")
	)
	(segment
		(start 139.964414 -262.916162)
		(end 139.761468 -263.119362)
		(width 0.088646)
		(layer "In6.Cu")
		(net "M_G_CPU1_SA_DQS_DN<4>")
	)
	(segment
		(start 139.761468 -263.119362)
		(end 139.761214 -263.119362)
		(width 0.088646)
		(layer "In6.Cu")
		(net "M_G_CPU1_SA_DQS_DN<4>")
	)
	(segment
		(start 139.679172 -263.186164)
		(end 139.678918 -263.186164)
		(width 0.088646)
		(layer "In6.Cu")
		(net "M_G_CPU1_SA_DQS_DN<4>")
	)
	(segment
		(start 178.064414 -265.990324)
		(end 177.413666 -265.990324)
		(width 0.18288)
		(layer "In6.Cu")
		(net "M_G_CPU1_SA_DQS_DN<4>")
	)
	(segment
		(start 172.536612 -264.892282)
		(end 172.279564 -265.14933)
		(width 0.18288)
		(layer "In6.Cu")
		(net "M_G_CPU1_SA_DQS_DN<4>")
	)
	(segment
		(start 142.83944 -262.342376)
		(end 140.595604 -262.342376)
		(width 0.18288)
		(layer "In6.Cu")
		(net "M_G_CPU1_SA_DQS_DN<4>")
	)
	(segment
		(start 128.009396 -263.196832)
		(end 127.994664 -263.188196)
		(width 0.088646)
		(layer "In6.Cu")
		(net "M_G_CPU1_SA_DQS_DN<4>")
	)
	(segment
		(start 179.370228 -266.612878)
		(end 178.686968 -266.612878)
		(width 0.18288)
		(layer "In6.Cu")
		(net "M_G_CPU1_SA_DQS_DN<4>")
	)
	(segment
		(start 174.89805 -266.020296)
		(end 174.018194 -265.14044)
		(width 0.18288)
		(layer "In6.Cu")
		(net "M_G_CPU1_SA_DQS_DN<4>")
	)
	(segment
		(start 140.512546 -262.402066)
		(end 140.297662 -262.402066)
		(width 0.088646)
		(layer "In6.Cu")
		(net "M_G_CPU1_SA_DQS_DN<4>")
	)
	(segment
		(start 182.23865 -270.010636)
		(end 182.23865 -269.464536)
		(width 0.18288)
		(layer "In6.Cu")
		(net "M_G_CPU1_SA_DQS_DN<4>")
	)
	(segment
		(start 164.262562 -265.030966)
		(end 160.910524 -265.030966)
		(width 0.18288)
		(layer "In6.Cu")
		(net "M_G_CPU1_SA_DQS_DN<4>")
	)
	(segment
		(start 181.004972 -266.590018)
		(end 180.519832 -266.104878)
		(width 0.18288)
		(layer "In6.Cu")
		(net "M_G_CPU1_SA_DQS_DN<4>")
	)
	(segment
		(start 160.910524 -265.030966)
		(end 160.175194 -264.295636)
		(width 0.18288)
		(layer "In6.Cu")
		(net "M_G_CPU1_SA_DQS_DN<4>")
	)
	(segment
		(start 132.708396 -263.196832)
		(end 132.697982 -263.190736)
		(width 0.088646)
		(layer "In6.Cu")
		(net "M_G_CPU1_SA_DQS_DN<4>")
	)
	(segment
		(start 182.299102 -272.622264)
		(end 182.11419 -272.437352)
		(width 0.18288)
		(layer "In6.Cu")
		(net "M_G_CPU1_SA_DQS_DN<4>")
	)
	(segment
		(start 145.271236 -262.826246)
		(end 142.83944 -262.342376)
		(width 0.18288)
		(layer "In6.Cu")
		(net "M_G_CPU1_SA_DQS_DN<4>")
	)
	(segment
		(start 164.950648 -264.34288)
		(end 164.262562 -265.030966)
		(width 0.18288)
		(layer "In6.Cu")
		(net "M_G_CPU1_SA_DQS_DN<4>")
	)
	(segment
		(start 187.63107 -274.91817)
		(end 187.218828 -274.91817)
		(width 0.18288)
		(layer "In6.Cu")
		(net "M_G_CPU1_SA_DQS_DN<4>")
	)
	(segment
		(start 183.190388 -272.622264)
		(end 182.299102 -272.622264)
		(width 0.18288)
		(layer "In6.Cu")
		(net "M_G_CPU1_SA_DQS_DN<4>")
	)
	(segment
		(start 173.313598 -265.14044)
		(end 173.06544 -264.892282)
		(width 0.18288)
		(layer "In6.Cu")
		(net "M_G_CPU1_SA_DQS_DN<4>")
	)
	(segment
		(start 177.413666 -265.990324)
		(end 177.165508 -265.742166)
		(width 0.18288)
		(layer "In6.Cu")
		(net "M_G_CPU1_SA_DQS_DN<4>")
	)
	(segment
		(start 184.190386 -273.622262)
		(end 183.190388 -272.622264)
		(width 0.18288)
		(layer "In6.Cu")
		(net "M_G_CPU1_SA_DQS_DN<4>")
	)
	(segment
		(start 182.23865 -269.464536)
		(end 182.11419 -269.340076)
		(width 0.18288)
		(layer "In6.Cu")
		(net "M_G_CPU1_SA_DQS_DN<4>")
	)
	(segment
		(start 180.519832 -266.104878)
		(end 179.878228 -266.104878)
		(width 0.18288)
		(layer "In6.Cu")
		(net "M_G_CPU1_SA_DQS_DN<4>")
	)
	(segment
		(start 167.44569 -264.34288)
		(end 164.950648 -264.34288)
		(width 0.18288)
		(layer "In6.Cu")
		(net "M_G_CPU1_SA_DQS_DN<4>")
	)
	(segment
		(start 173.06544 -264.892282)
		(end 172.536612 -264.892282)
		(width 0.18288)
		(layer "In6.Cu")
		(net "M_G_CPU1_SA_DQS_DN<4>")
	)
	(segment
		(start 130.828796 -263.196832)
		(end 130.814064 -263.188196)
		(width 0.088646)
		(layer "In6.Cu")
		(net "M_G_CPU1_SA_DQS_DN<4>")
	)
	(segment
		(start 140.595604 -262.342376)
		(end 140.572236 -262.342376)
		(width 0.088646)
		(layer "In6.Cu")
		(net "M_G_CPU1_SA_DQS_DN<4>")
	)
	(segment
		(start 126.886716 -262.929878)
		(end 126.94412 -262.872474)
		(width 0.088646)
		(layer "In6.Cu")
		(net "M_G_CPU1_SA_DQS_DN<4>")
	)
	(segment
		(start 157.374082 -264.295636)
		(end 155.904692 -262.826246)
		(width 0.18288)
		(layer "In6.Cu")
		(net "M_G_CPU1_SA_DQS_DN<4>")
	)
	(segment
		(start 133.648196 -263.196832)
		(end 133.633464 -263.188196)
		(width 0.088646)
		(layer "In6.Cu")
		(net "M_G_CPU1_SA_DQS_DN<4>")
	)
	(segment
		(start 137.792206 -263.190736)
		(end 137.781792 -263.196832)
		(width 0.088646)
		(layer "In6.Cu")
		(net "M_G_CPU1_SA_DQS_DN<4>")
	)
	(segment
		(start 184.98312 -273.622262)
		(end 184.190386 -273.622262)
		(width 0.18288)
		(layer "In6.Cu")
		(net "M_G_CPU1_SA_DQS_DN<4>")
	)
	(segment
		(start 177.165508 -265.742166)
		(end 176.63668 -265.742166)
		(width 0.18288)
		(layer "In6.Cu")
		(net "M_G_CPU1_SA_DQS_DN<4>")
	)
	(segment
		(start 140.092684 -262.60679)
		(end 139.964414 -262.916162)
		(width 0.088646)
		(layer "In6.Cu")
		(net "M_G_CPU1_SA_DQS_DN<4>")
	)
	(segment
		(start 181.567582 -266.976606)
		(end 181.180994 -266.590018)
		(width 0.18288)
		(layer "In6.Cu")
		(net "M_G_CPU1_SA_DQS_DN<4>")
	)
	(segment
		(start 182.11419 -267.699236)
		(end 181.567582 -267.152628)
		(width 0.18288)
		(layer "In6.Cu")
		(net "M_G_CPU1_SA_DQS_DN<4>")
	)
	(segment
		(start 181.567582 -267.152628)
		(end 181.567582 -266.976606)
		(width 0.18288)
		(layer "In6.Cu")
		(net "M_G_CPU1_SA_DQS_DN<4>")
	)
	(segment
		(start 126.94412 -262.872474)
		(end 127.256794 -262.872474)
		(width 0.088646)
		(layer "In6.Cu")
		(net "M_G_CPU1_SA_DQS_DN<4>")
	)
	(segment
		(start 186.025536 -274.664678)
		(end 184.98312 -273.622262)
		(width 0.18288)
		(layer "In6.Cu")
		(net "M_G_CPU1_SA_DQS_DN<4>")
	)
	(segment
		(start 176.63668 -265.742166)
		(end 176.35855 -266.020296)
		(width 0.18288)
		(layer "In6.Cu")
		(net "M_G_CPU1_SA_DQS_DN<4>")
	)
	(segment
		(start 181.180994 -266.590018)
		(end 181.004972 -266.590018)
		(width 0.18288)
		(layer "In6.Cu")
		(net "M_G_CPU1_SA_DQS_DN<4>")
	)
	(segment
		(start 160.175194 -264.295636)
		(end 157.374082 -264.295636)
		(width 0.18288)
		(layer "In6.Cu")
		(net "M_G_CPU1_SA_DQS_DN<4>")
	)
	(segment
		(start 169.392854 -265.14933)
		(end 167.44569 -264.34288)
		(width 0.18288)
		(layer "In6.Cu")
		(net "M_G_CPU1_SA_DQS_DN<4>")
	)
	(segment
		(start 182.11419 -270.135096)
		(end 182.23865 -270.010636)
		(width 0.18288)
		(layer "In6.Cu")
		(net "M_G_CPU1_SA_DQS_DN<4>")
	)
	(segment
		(start 182.11419 -272.437352)
		(end 182.11419 -271.849088)
		(width 0.18288)
		(layer "In6.Cu")
		(net "M_G_CPU1_SA_DQS_DN<4>")
	)
	(arc
		(start 138.34745 -263.196832)
		(mid 138.070637 -263.120996)
		(end 137.792206 -263.190736)
		(width 0.088646)
		(layer "In6.Cu")
		(net "M_G_CPU1_SA_DQS_DN<4>")
	)
	(arc
		(start 128.383792 -263.196832)
		(mid 128.196594 -263.246975)
		(end 128.009396 -263.196832)
		(width 0.088646)
		(layer "In6.Cu")
		(net "M_G_CPU1_SA_DQS_DN<4>")
	)
	(arc
		(start 136.841992 -263.196832)
		(mid 136.654794 -263.246975)
		(end 136.467596 -263.196832)
		(width 0.088646)
		(layer "In6.Cu")
		(net "M_G_CPU1_SA_DQS_DN<4>")
	)
	(arc
		(start 135.527796 -263.196832)
		(mid 135.245094 -263.12109)
		(end 134.962392 -263.196832)
		(width 0.088646)
		(layer "In6.Cu")
		(net "M_G_CPU1_SA_DQS_DN<4>")
	)
	(arc
		(start 133.082792 -263.196832)
		(mid 132.895594 -263.246975)
		(end 132.708396 -263.196832)
		(width 0.088646)
		(layer "In6.Cu")
		(net "M_G_CPU1_SA_DQS_DN<4>")
	)
	(arc
		(start 127.443992 -263.196832)
		(mid 127.095 -263.210222)
		(end 126.886716 -262.929878)
		(width 0.088646)
		(layer "In6.Cu")
		(net "M_G_CPU1_SA_DQS_DN<4>")
	)
	(arc
		(start 131.203192 -263.196832)
		(mid 131.015994 -263.246975)
		(end 130.828796 -263.196832)
		(width 0.088646)
		(layer "In6.Cu")
		(net "M_G_CPU1_SA_DQS_DN<4>")
	)
	(arc
		(start 134.962392 -263.196832)
		(mid 134.775194 -263.246975)
		(end 134.587996 -263.196832)
		(width 0.088646)
		(layer "In6.Cu")
		(net "M_G_CPU1_SA_DQS_DN<4>")
	)
	(arc
		(start 128.934464 -263.188196)
		(mid 128.658023 -263.12103)
		(end 128.383792 -263.196832)
		(width 0.088646)
		(layer "In6.Cu")
		(net "M_G_CPU1_SA_DQS_DN<4>")
	)
	(arc
		(start 138.721846 -263.196832)
		(mid 138.534648 -263.246975)
		(end 138.34745 -263.196832)
		(width 0.088646)
		(layer "In6.Cu")
		(net "M_G_CPU1_SA_DQS_DN<4>")
	)
	(arc
		(start 135.902192 -263.196832)
		(mid 135.714994 -263.246975)
		(end 135.527796 -263.196832)
		(width 0.088646)
		(layer "In6.Cu")
		(net "M_G_CPU1_SA_DQS_DN<4>")
	)
	(arc
		(start 132.697982 -263.190736)
		(mid 132.419804 -263.121044)
		(end 132.143246 -263.196832)
		(width 0.088646)
		(layer "In6.Cu")
		(net "M_G_CPU1_SA_DQS_DN<4>")
	)
	(arc
		(start 137.781792 -263.196832)
		(mid 137.594594 -263.246975)
		(end 137.407396 -263.196832)
		(width 0.088646)
		(layer "In6.Cu")
		(net "M_G_CPU1_SA_DQS_DN<4>")
	)
	(arc
		(start 139.678918 -263.186164)
		(mid 139.670356 -263.191617)
		(end 139.661646 -263.196832)
		(width 0.088646)
		(layer "In6.Cu")
		(net "M_G_CPU1_SA_DQS_DN<4>")
	)
	(arc
		(start 139.28725 -263.196832)
		(mid 139.013021 -263.120907)
		(end 138.736578 -263.188196)
		(width 0.088646)
		(layer "In6.Cu")
		(net "M_G_CPU1_SA_DQS_DN<4>")
	)
	(arc
		(start 130.263392 -263.196832)
		(mid 130.076194 -263.246975)
		(end 129.888996 -263.196832)
		(width 0.088646)
		(layer "In6.Cu")
		(net "M_G_CPU1_SA_DQS_DN<4>")
	)
	(arc
		(start 139.761214 -263.119362)
		(mid 139.721944 -263.154913)
		(end 139.679172 -263.186164)
		(width 0.088646)
		(layer "In6.Cu")
		(net "M_G_CPU1_SA_DQS_DN<4>")
	)
	(arc
		(start 131.758436 -263.190736)
		(mid 131.480004 -263.120922)
		(end 131.203192 -263.196832)
		(width 0.088646)
		(layer "In6.Cu")
		(net "M_G_CPU1_SA_DQS_DN<4>")
	)
	(arc
		(start 134.573264 -263.188196)
		(mid 134.296823 -263.12103)
		(end 134.022592 -263.196832)
		(width 0.088646)
		(layer "In6.Cu")
		(net "M_G_CPU1_SA_DQS_DN<4>")
	)
	(arc
		(start 132.143246 -263.196832)
		(mid 131.956048 -263.246975)
		(end 131.76885 -263.196832)
		(width 0.088646)
		(layer "In6.Cu")
		(net "M_G_CPU1_SA_DQS_DN<4>")
	)
	(arc
		(start 134.022592 -263.196832)
		(mid 133.835394 -263.246975)
		(end 133.648196 -263.196832)
		(width 0.088646)
		(layer "In6.Cu")
		(net "M_G_CPU1_SA_DQS_DN<4>")
	)
	(arc
		(start 129.888996 -263.196832)
		(mid 129.606294 -263.12109)
		(end 129.323592 -263.196832)
		(width 0.088646)
		(layer "In6.Cu")
		(net "M_G_CPU1_SA_DQS_DN<4>")
	)
	(arc
		(start 130.814064 -263.188196)
		(mid 130.537623 -263.12103)
		(end 130.263392 -263.196832)
		(width 0.088646)
		(layer "In6.Cu")
		(net "M_G_CPU1_SA_DQS_DN<4>")
	)
	(arc
		(start 139.661646 -263.196832)
		(mid 139.474448 -263.246975)
		(end 139.28725 -263.196832)
		(width 0.088646)
		(layer "In6.Cu")
		(net "M_G_CPU1_SA_DQS_DN<4>")
	)
	(arc
		(start 133.633464 -263.188196)
		(mid 133.357023 -263.12103)
		(end 133.082792 -263.196832)
		(width 0.088646)
		(layer "In6.Cu")
		(net "M_G_CPU1_SA_DQS_DN<4>")
	)
	(arc
		(start 127.994664 -263.188196)
		(mid 127.718223 -263.12103)
		(end 127.443992 -263.196832)
		(width 0.088646)
		(layer "In6.Cu")
		(net "M_G_CPU1_SA_DQS_DN<4>")
	)
	(arc
		(start 136.467596 -263.196832)
		(mid 136.184894 -263.12109)
		(end 135.902192 -263.196832)
		(width 0.088646)
		(layer "In6.Cu")
		(net "M_G_CPU1_SA_DQS_DN<4>")
	)
	(arc
		(start 137.407396 -263.196832)
		(mid 137.124694 -263.12109)
		(end 136.841992 -263.196832)
		(width 0.088646)
		(layer "In6.Cu")
		(net "M_G_CPU1_SA_DQS_DN<4>")
	)
	(arc
		(start 129.323592 -263.196832)
		(mid 129.136394 -263.246975)
		(end 128.949196 -263.196832)
		(width 0.088646)
		(layer "In6.Cu")
		(net "M_G_CPU1_SA_DQS_DN<4>")
	)
	(segment
		(start 190.969138 -284.712918)
		(end 191.490854 -284.712918)
		(width 0.20066)
		(layer "F.Cu")
		(net "M_G_CPU1_SA_DQS_DN<3>")
	)
	(segment
		(start 191.9097 -284.441646)
		(end 191.914018 -284.441646)
		(width 0.101854)
		(layer "F.Cu")
		(net "M_G_CPU1_SA_DQS_DN<3>")
	)
	(segment
		(start 195.702428 -284.257242)
		(end 195.942966 -284.016704)
		(width 0.20066)
		(layer "F.Cu")
		(net "M_G_CPU1_SA_DQS_DN<3>")
	)
	(segment
		(start 127.257048 -267.219938)
		(end 127.256794 -267.220192)
		(width 0.20066)
		(layer "F.Cu")
		(net "M_G_CPU1_SA_DQS_DN<3>")
	)
	(segment
		(start 187.883546 -284.016704)
		(end 188.988446 -284.016704)
		(width 0.20066)
		(layer "F.Cu")
		(net "M_G_CPU1_SA_DQS_DN<3>")
	)
	(segment
		(start 195.369942 -284.257242)
		(end 195.702428 -284.257242)
		(width 0.20066)
		(layer "F.Cu")
		(net "M_G_CPU1_SA_DQS_DN<3>")
	)
	(segment
		(start 127.256794 -267.220192)
		(end 127.256794 -267.755878)
		(width 0.20066)
		(layer "F.Cu")
		(net "M_G_CPU1_SA_DQS_DN<3>")
	)
	(segment
		(start 190.55461 -284.29839)
		(end 190.969138 -284.712918)
		(width 0.20066)
		(layer "F.Cu")
		(net "M_G_CPU1_SA_DQS_DN<3>")
	)
	(segment
		(start 188.988446 -284.016704)
		(end 189.537086 -284.016704)
		(width 0.20066)
		(layer "F.Cu")
		(net "M_G_CPU1_SA_DQS_DN<3>")
	)
	(segment
		(start 194.959478 -284.667706)
		(end 195.369942 -284.257242)
		(width 0.20066)
		(layer "F.Cu")
		(net "M_G_CPU1_SA_DQS_DN<3>")
	)
	(segment
		(start 189.537086 -284.016704)
		(end 189.818772 -284.29839)
		(width 0.20066)
		(layer "F.Cu")
		(net "M_G_CPU1_SA_DQS_DN<3>")
	)
	(segment
		(start 191.762126 -284.441646)
		(end 191.9097 -284.441646)
		(width 0.20066)
		(layer "F.Cu")
		(net "M_G_CPU1_SA_DQS_DN<3>")
	)
	(segment
		(start 194.098926 -284.436312)
		(end 194.42303 -284.436312)
		(width 0.20066)
		(layer "F.Cu")
		(net "M_G_CPU1_SA_DQS_DN<3>")
	)
	(segment
		(start 191.914018 -284.441646)
		(end 194.093592 -284.441646)
		(width 0.1016)
		(layer "F.Cu")
		(net "M_G_CPU1_SA_DQS_DN<3>")
	)
	(segment
		(start 194.093592 -284.441646)
		(end 194.098926 -284.436312)
		(width 0.1016)
		(layer "F.Cu")
		(net "M_G_CPU1_SA_DQS_DN<3>")
	)
	(segment
		(start 194.42303 -284.436312)
		(end 194.654424 -284.667706)
		(width 0.20066)
		(layer "F.Cu")
		(net "M_G_CPU1_SA_DQS_DN<3>")
	)
	(segment
		(start 191.490854 -284.712918)
		(end 191.762126 -284.441646)
		(width 0.20066)
		(layer "F.Cu")
		(net "M_G_CPU1_SA_DQS_DN<3>")
	)
	(segment
		(start 189.818772 -284.29839)
		(end 190.55461 -284.29839)
		(width 0.20066)
		(layer "F.Cu")
		(net "M_G_CPU1_SA_DQS_DN<3>")
	)
	(segment
		(start 195.942966 -284.016704)
		(end 196.532246 -284.016704)
		(width 0.20066)
		(layer "F.Cu")
		(net "M_G_CPU1_SA_DQS_DN<3>")
	)
	(segment
		(start 194.654424 -284.667706)
		(end 194.959478 -284.667706)
		(width 0.20066)
		(layer "F.Cu")
		(net "M_G_CPU1_SA_DQS_DN<3>")
	)
	(segment
		(start 181.889908 -283.966158)
		(end 181.765448 -284.090618)
		(width 0.18288)
		(layer "In6.Cu")
		(net "M_G_CPU1_SA_DQS_DN<3>")
	)
	(segment
		(start 171.458128 -279.592532)
		(end 171.007532 -279.141936)
		(width 0.18288)
		(layer "In6.Cu")
		(net "M_G_CPU1_SA_DQS_DN<3>")
	)
	(segment
		(start 171.007532 -278.965914)
		(end 170.620944 -278.579326)
		(width 0.18288)
		(layer "In6.Cu")
		(net "M_G_CPU1_SA_DQS_DN<3>")
	)
	(segment
		(start 181.219348 -284.090618)
		(end 181.094888 -283.966158)
		(width 0.18288)
		(layer "In6.Cu")
		(net "M_G_CPU1_SA_DQS_DN<3>")
	)
	(segment
		(start 169.813224 -277.947374)
		(end 168.65219 -277.466298)
		(width 0.18288)
		(layer "In6.Cu")
		(net "M_G_CPU1_SA_DQS_DN<3>")
	)
	(segment
		(start 158.176468 -275.607272)
		(end 157.618938 -275.607272)
		(width 0.18288)
		(layer "In6.Cu")
		(net "M_G_CPU1_SA_DQS_DN<3>")
	)
	(segment
		(start 127.542544 -267.755878)
		(end 127.256794 -267.755878)
		(width 0.088646)
		(layer "In6.Cu")
		(net "M_G_CPU1_SA_DQS_DN<3>")
	)
	(segment
		(start 128.3843 -268.080236)
		(end 128.3843 -268.08049)
		(width 0.088646)
		(layer "In6.Cu")
		(net "M_G_CPU1_SA_DQS_DN<3>")
	)
	(segment
		(start 187.129928 -284.090618)
		(end 186.583828 -284.090618)
		(width 0.18288)
		(layer "In6.Cu")
		(net "M_G_CPU1_SA_DQS_DN<3>")
	)
	(segment
		(start 127.980948 -268.062202)
		(end 127.769366 -267.912596)
		(width 0.088646)
		(layer "In6.Cu")
		(net "M_G_CPU1_SA_DQS_DN<3>")
	)
	(segment
		(start 186.459368 -283.966158)
		(end 185.913268 -283.966158)
		(width 0.18288)
		(layer "In6.Cu")
		(net "M_G_CPU1_SA_DQS_DN<3>")
	)
	(segment
		(start 130.828796 -268.080236)
		(end 130.814064 -268.0716)
		(width 0.088646)
		(layer "In6.Cu")
		(net "M_G_CPU1_SA_DQS_DN<3>")
	)
	(segment
		(start 172.536612 -279.342596)
		(end 172.286676 -279.592532)
		(width 0.18288)
		(layer "In6.Cu")
		(net "M_G_CPU1_SA_DQS_DN<3>")
	)
	(segment
		(start 157.618938 -275.607272)
		(end 150.821898 -268.810232)
		(width 0.18288)
		(layer "In6.Cu")
		(net "M_G_CPU1_SA_DQS_DN<3>")
	)
	(segment
		(start 129.888996 -268.080236)
		(end 129.874264 -268.0716)
		(width 0.088646)
		(layer "In6.Cu")
		(net "M_G_CPU1_SA_DQS_DN<3>")
	)
	(segment
		(start 135.527796 -268.080236)
		(end 135.513064 -268.0716)
		(width 0.088646)
		(layer "In6.Cu")
		(net "M_G_CPU1_SA_DQS_DN<3>")
	)
	(segment
		(start 174.450502 -280.226008)
		(end 173.815248 -279.590754)
		(width 0.18288)
		(layer "In6.Cu")
		(net "M_G_CPU1_SA_DQS_DN<3>")
	)
	(segment
		(start 128.94183 -268.075918)
		(end 128.94183 -268.076172)
		(width 0.088646)
		(layer "In6.Cu")
		(net "M_G_CPU1_SA_DQS_DN<3>")
	)
	(segment
		(start 173.06544 -279.342596)
		(end 172.536612 -279.342596)
		(width 0.18288)
		(layer "In6.Cu")
		(net "M_G_CPU1_SA_DQS_DN<3>")
	)
	(segment
		(start 127.769366 -267.912596)
		(end 127.760984 -267.910564)
		(width 0.088646)
		(layer "In6.Cu")
		(net "M_G_CPU1_SA_DQS_DN<3>")
	)
	(segment
		(start 140.595604 -268.285722)
		(end 140.572236 -268.285722)
		(width 0.088646)
		(layer "In6.Cu")
		(net "M_G_CPU1_SA_DQS_DN<3>")
	)
	(segment
		(start 160.61309 -275.607272)
		(end 158.971488 -275.607272)
		(width 0.18288)
		(layer "In6.Cu")
		(net "M_G_CPU1_SA_DQS_DN<3>")
	)
	(segment
		(start 171.007532 -279.141936)
		(end 171.007532 -278.965914)
		(width 0.18288)
		(layer "In6.Cu")
		(net "M_G_CPU1_SA_DQS_DN<3>")
	)
	(segment
		(start 164.024564 -276.115272)
		(end 163.266882 -276.115272)
		(width 0.18288)
		(layer "In6.Cu")
		(net "M_G_CPU1_SA_DQS_DN<3>")
	)
	(segment
		(start 138.73607 -268.0716)
		(end 138.7094 -268.087094)
		(width 0.088646)
		(layer "In6.Cu")
		(net "M_G_CPU1_SA_DQS_DN<3>")
	)
	(segment
		(start 133.648196 -268.080236)
		(end 133.633464 -268.0716)
		(width 0.088646)
		(layer "In6.Cu")
		(net "M_G_CPU1_SA_DQS_DN<3>")
	)
	(segment
		(start 174.574962 -282.612846)
		(end 174.574962 -282.066746)
		(width 0.18288)
		(layer "In6.Cu")
		(net "M_G_CPU1_SA_DQS_DN<3>")
	)
	(segment
		(start 136.856724 -268.0716)
		(end 136.841992 -268.080236)
		(width 0.088646)
		(layer "In6.Cu")
		(net "M_G_CPU1_SA_DQS_DN<3>")
	)
	(segment
		(start 162.471862 -276.115272)
		(end 161.839656 -276.115272)
		(width 0.18288)
		(layer "In6.Cu")
		(net "M_G_CPU1_SA_DQS_DN<3>")
	)
	(segment
		(start 175.82769 -284.715204)
		(end 174.450502 -283.338016)
		(width 0.18288)
		(layer "In6.Cu")
		(net "M_G_CPU1_SA_DQS_DN<3>")
	)
	(segment
		(start 174.450502 -281.942286)
		(end 174.450502 -280.226008)
		(width 0.18288)
		(layer "In6.Cu")
		(net "M_G_CPU1_SA_DQS_DN<3>")
	)
	(segment
		(start 187.602368 -284.297882)
		(end 187.337192 -284.297882)
		(width 0.18288)
		(layer "In6.Cu")
		(net "M_G_CPU1_SA_DQS_DN<3>")
	)
	(segment
		(start 140.012674 -268.093952)
		(end 139.708382 -268.054582)
		(width 0.088646)
		(layer "In6.Cu")
		(net "M_G_CPU1_SA_DQS_DN<3>")
	)
	(segment
		(start 181.094888 -283.966158)
		(end 180.548788 -283.966158)
		(width 0.18288)
		(layer "In6.Cu")
		(net "M_G_CPU1_SA_DQS_DN<3>")
	)
	(segment
		(start 163.142422 -275.990812)
		(end 162.596322 -275.990812)
		(width 0.18288)
		(layer "In6.Cu")
		(net "M_G_CPU1_SA_DQS_DN<3>")
	)
	(segment
		(start 174.450502 -283.338016)
		(end 174.450502 -282.737306)
		(width 0.18288)
		(layer "In6.Cu")
		(net "M_G_CPU1_SA_DQS_DN<3>")
	)
	(segment
		(start 176.63668 -284.442408)
		(end 176.363884 -284.715204)
		(width 0.18288)
		(layer "In6.Cu")
		(net "M_G_CPU1_SA_DQS_DN<3>")
	)
	(segment
		(start 174.450502 -282.737306)
		(end 174.574962 -282.612846)
		(width 0.18288)
		(layer "In6.Cu")
		(net "M_G_CPU1_SA_DQS_DN<3>")
	)
	(segment
		(start 183.231028 -283.966158)
		(end 183.106568 -284.090618)
		(width 0.18288)
		(layer "In6.Cu")
		(net "M_G_CPU1_SA_DQS_DN<3>")
	)
	(segment
		(start 163.266882 -276.115272)
		(end 163.142422 -275.990812)
		(width 0.18288)
		(layer "In6.Cu")
		(net "M_G_CPU1_SA_DQS_DN<3>")
	)
	(segment
		(start 170.445176 -278.579326)
		(end 169.813224 -277.947374)
		(width 0.18288)
		(layer "In6.Cu")
		(net "M_G_CPU1_SA_DQS_DN<3>")
	)
	(segment
		(start 137.79627 -268.0716)
		(end 137.781538 -268.080236)
		(width 0.088646)
		(layer "In6.Cu")
		(net "M_G_CPU1_SA_DQS_DN<3>")
	)
	(segment
		(start 182.560468 -284.090618)
		(end 182.436008 -283.966158)
		(width 0.18288)
		(layer "In6.Cu")
		(net "M_G_CPU1_SA_DQS_DN<3>")
	)
	(segment
		(start 168.65219 -277.466298)
		(end 168.02227 -276.836886)
		(width 0.18288)
		(layer "In6.Cu")
		(net "M_G_CPU1_SA_DQS_DN<3>")
	)
	(segment
		(start 131.76885 -268.080236)
		(end 131.758436 -268.07414)
		(width 0.088646)
		(layer "In6.Cu")
		(net "M_G_CPU1_SA_DQS_DN<3>")
	)
	(segment
		(start 172.286676 -279.592532)
		(end 171.458128 -279.592532)
		(width 0.18288)
		(layer "In6.Cu")
		(net "M_G_CPU1_SA_DQS_DN<3>")
	)
	(segment
		(start 140.512546 -268.345412)
		(end 140.26388 -268.345412)
		(width 0.088646)
		(layer "In6.Cu")
		(net "M_G_CPU1_SA_DQS_DN<3>")
	)
	(segment
		(start 134.587996 -268.080236)
		(end 134.573264 -268.0716)
		(width 0.088646)
		(layer "In6.Cu")
		(net "M_G_CPU1_SA_DQS_DN<3>")
	)
	(segment
		(start 183.106568 -284.090618)
		(end 182.560468 -284.090618)
		(width 0.18288)
		(layer "In6.Cu")
		(net "M_G_CPU1_SA_DQS_DN<3>")
	)
	(segment
		(start 184.447688 -284.090618)
		(end 183.901588 -284.090618)
		(width 0.18288)
		(layer "In6.Cu")
		(net "M_G_CPU1_SA_DQS_DN<3>")
	)
	(segment
		(start 168.02227 -276.836886)
		(end 167.337486 -276.836886)
		(width 0.18288)
		(layer "In6.Cu")
		(net "M_G_CPU1_SA_DQS_DN<3>")
	)
	(segment
		(start 183.777128 -283.966158)
		(end 183.231028 -283.966158)
		(width 0.18288)
		(layer "In6.Cu")
		(net "M_G_CPU1_SA_DQS_DN<3>")
	)
	(segment
		(start 140.26388 -268.345412)
		(end 140.012674 -268.093952)
		(width 0.088646)
		(layer "In6.Cu")
		(net "M_G_CPU1_SA_DQS_DN<3>")
	)
	(segment
		(start 176.363884 -284.715204)
		(end 175.82769 -284.715204)
		(width 0.18288)
		(layer "In6.Cu")
		(net "M_G_CPU1_SA_DQS_DN<3>")
	)
	(segment
		(start 128.43383 -268.05509)
		(end 128.428242 -268.05509)
		(width 0.088646)
		(layer "In6.Cu")
		(net "M_G_CPU1_SA_DQS_DN<3>")
	)
	(segment
		(start 158.971488 -275.607272)
		(end 158.847028 -275.482812)
		(width 0.18288)
		(layer "In6.Cu")
		(net "M_G_CPU1_SA_DQS_DN<3>")
	)
	(segment
		(start 173.313598 -279.590754)
		(end 173.06544 -279.342596)
		(width 0.18288)
		(layer "In6.Cu")
		(net "M_G_CPU1_SA_DQS_DN<3>")
	)
	(segment
		(start 164.746178 -276.836886)
		(end 164.024564 -276.115272)
		(width 0.18288)
		(layer "In6.Cu")
		(net "M_G_CPU1_SA_DQS_DN<3>")
	)
	(segment
		(start 142.214092 -268.285722)
		(end 140.595604 -268.285722)
		(width 0.18288)
		(layer "In6.Cu")
		(net "M_G_CPU1_SA_DQS_DN<3>")
	)
	(segment
		(start 137.781538 -268.080236)
		(end 137.773156 -268.085062)
		(width 0.088646)
		(layer "In6.Cu")
		(net "M_G_CPU1_SA_DQS_DN<3>")
	)
	(segment
		(start 181.765448 -284.090618)
		(end 181.219348 -284.090618)
		(width 0.18288)
		(layer "In6.Cu")
		(net "M_G_CPU1_SA_DQS_DN<3>")
	)
	(segment
		(start 132.708396 -268.080236)
		(end 132.697982 -268.07414)
		(width 0.088646)
		(layer "In6.Cu")
		(net "M_G_CPU1_SA_DQS_DN<3>")
	)
	(segment
		(start 127.760984 -267.910564)
		(end 127.542544 -267.755878)
		(width 0.088646)
		(layer "In6.Cu")
		(net "M_G_CPU1_SA_DQS_DN<3>")
	)
	(segment
		(start 174.574962 -282.066746)
		(end 174.450502 -281.942286)
		(width 0.18288)
		(layer "In6.Cu")
		(net "M_G_CPU1_SA_DQS_DN<3>")
	)
	(segment
		(start 187.883546 -284.016704)
		(end 187.602368 -284.297882)
		(width 0.18288)
		(layer "In6.Cu")
		(net "M_G_CPU1_SA_DQS_DN<3>")
	)
	(segment
		(start 180.424328 -284.090618)
		(end 178.638708 -284.090618)
		(width 0.18288)
		(layer "In6.Cu")
		(net "M_G_CPU1_SA_DQS_DN<3>")
	)
	(segment
		(start 185.242708 -284.090618)
		(end 185.118248 -283.966158)
		(width 0.18288)
		(layer "In6.Cu")
		(net "M_G_CPU1_SA_DQS_DN<3>")
	)
	(segment
		(start 185.913268 -283.966158)
		(end 185.788808 -284.090618)
		(width 0.18288)
		(layer "In6.Cu")
		(net "M_G_CPU1_SA_DQS_DN<3>")
	)
	(segment
		(start 150.821898 -268.810232)
		(end 144.84985 -268.810232)
		(width 0.18288)
		(layer "In6.Cu")
		(net "M_G_CPU1_SA_DQS_DN<3>")
	)
	(segment
		(start 173.815248 -279.590754)
		(end 173.313598 -279.590754)
		(width 0.18288)
		(layer "In6.Cu")
		(net "M_G_CPU1_SA_DQS_DN<3>")
	)
	(segment
		(start 178.03876 -284.690566)
		(end 177.413666 -284.690566)
		(width 0.18288)
		(layer "In6.Cu")
		(net "M_G_CPU1_SA_DQS_DN<3>")
	)
	(segment
		(start 139.708382 -268.054582)
		(end 139.654026 -268.084554)
		(width 0.088646)
		(layer "In6.Cu")
		(net "M_G_CPU1_SA_DQS_DN<3>")
	)
	(segment
		(start 158.300928 -275.482812)
		(end 158.176468 -275.607272)
		(width 0.18288)
		(layer "In6.Cu")
		(net "M_G_CPU1_SA_DQS_DN<3>")
	)
	(segment
		(start 185.118248 -283.966158)
		(end 184.572148 -283.966158)
		(width 0.18288)
		(layer "In6.Cu")
		(net "M_G_CPU1_SA_DQS_DN<3>")
	)
	(segment
		(start 177.413666 -284.690566)
		(end 177.165508 -284.442408)
		(width 0.18288)
		(layer "In6.Cu")
		(net "M_G_CPU1_SA_DQS_DN<3>")
	)
	(segment
		(start 166.542466 -276.836886)
		(end 164.746178 -276.836886)
		(width 0.18288)
		(layer "In6.Cu")
		(net "M_G_CPU1_SA_DQS_DN<3>")
	)
	(segment
		(start 167.213026 -276.712426)
		(end 166.666926 -276.712426)
		(width 0.18288)
		(layer "In6.Cu")
		(net "M_G_CPU1_SA_DQS_DN<3>")
	)
	(segment
		(start 140.572236 -268.285722)
		(end 140.512546 -268.345412)
		(width 0.088646)
		(layer "In6.Cu")
		(net "M_G_CPU1_SA_DQS_DN<3>")
	)
	(segment
		(start 187.337192 -284.297882)
		(end 187.129928 -284.090618)
		(width 0.18288)
		(layer "In6.Cu")
		(net "M_G_CPU1_SA_DQS_DN<3>")
	)
	(segment
		(start 183.901588 -284.090618)
		(end 183.777128 -283.966158)
		(width 0.18288)
		(layer "In6.Cu")
		(net "M_G_CPU1_SA_DQS_DN<3>")
	)
	(segment
		(start 162.596322 -275.990812)
		(end 162.471862 -276.115272)
		(width 0.18288)
		(layer "In6.Cu")
		(net "M_G_CPU1_SA_DQS_DN<3>")
	)
	(segment
		(start 185.788808 -284.090618)
		(end 185.242708 -284.090618)
		(width 0.18288)
		(layer "In6.Cu")
		(net "M_G_CPU1_SA_DQS_DN<3>")
	)
	(segment
		(start 180.548788 -283.966158)
		(end 180.424328 -284.090618)
		(width 0.18288)
		(layer "In6.Cu")
		(net "M_G_CPU1_SA_DQS_DN<3>")
	)
	(segment
		(start 167.337486 -276.836886)
		(end 167.213026 -276.712426)
		(width 0.18288)
		(layer "In6.Cu")
		(net "M_G_CPU1_SA_DQS_DN<3>")
	)
	(segment
		(start 170.620944 -278.579326)
		(end 170.445176 -278.579326)
		(width 0.18288)
		(layer "In6.Cu")
		(net "M_G_CPU1_SA_DQS_DN<3>")
	)
	(segment
		(start 158.847028 -275.482812)
		(end 158.300928 -275.482812)
		(width 0.18288)
		(layer "In6.Cu")
		(net "M_G_CPU1_SA_DQS_DN<3>")
	)
	(segment
		(start 178.638708 -284.090618)
		(end 178.03876 -284.690566)
		(width 0.18288)
		(layer "In6.Cu")
		(net "M_G_CPU1_SA_DQS_DN<3>")
	)
	(segment
		(start 161.839656 -276.115272)
		(end 160.61309 -275.607272)
		(width 0.18288)
		(layer "In6.Cu")
		(net "M_G_CPU1_SA_DQS_DN<3>")
	)
	(segment
		(start 144.84985 -268.810232)
		(end 142.214092 -268.285722)
		(width 0.18288)
		(layer "In6.Cu")
		(net "M_G_CPU1_SA_DQS_DN<3>")
	)
	(segment
		(start 184.572148 -283.966158)
		(end 184.447688 -284.090618)
		(width 0.18288)
		(layer "In6.Cu")
		(net "M_G_CPU1_SA_DQS_DN<3>")
	)
	(segment
		(start 128.949196 -268.080236)
		(end 128.94183 -268.075918)
		(width 0.088646)
		(layer "In6.Cu")
		(net "M_G_CPU1_SA_DQS_DN<3>")
	)
	(segment
		(start 177.165508 -284.442408)
		(end 176.63668 -284.442408)
		(width 0.18288)
		(layer "In6.Cu")
		(net "M_G_CPU1_SA_DQS_DN<3>")
	)
	(segment
		(start 128.428242 -268.05509)
		(end 128.3843 -268.080236)
		(width 0.088646)
		(layer "In6.Cu")
		(net "M_G_CPU1_SA_DQS_DN<3>")
	)
	(segment
		(start 166.666926 -276.712426)
		(end 166.542466 -276.836886)
		(width 0.18288)
		(layer "In6.Cu")
		(net "M_G_CPU1_SA_DQS_DN<3>")
	)
	(segment
		(start 182.436008 -283.966158)
		(end 181.889908 -283.966158)
		(width 0.18288)
		(layer "In6.Cu")
		(net "M_G_CPU1_SA_DQS_DN<3>")
	)
	(segment
		(start 186.583828 -284.090618)
		(end 186.459368 -283.966158)
		(width 0.18288)
		(layer "In6.Cu")
		(net "M_G_CPU1_SA_DQS_DN<3>")
	)
	(arc
		(start 139.285726 -268.08049)
		(mid 139.012065 -268.004752)
		(end 138.73607 -268.0716)
		(width 0.088646)
		(layer "In6.Cu")
		(net "M_G_CPU1_SA_DQS_DN<3>")
	)
	(arc
		(start 133.082792 -268.080236)
		(mid 132.895594 -268.130379)
		(end 132.708396 -268.080236)
		(width 0.088646)
		(layer "In6.Cu")
		(net "M_G_CPU1_SA_DQS_DN<3>")
	)
	(arc
		(start 137.407396 -268.080236)
		(mid 137.133197 -268.004401)
		(end 136.856724 -268.0716)
		(width 0.088646)
		(layer "In6.Cu")
		(net "M_G_CPU1_SA_DQS_DN<3>")
	)
	(arc
		(start 136.467596 -268.080236)
		(mid 136.184894 -268.00446)
		(end 135.902192 -268.080236)
		(width 0.088646)
		(layer "In6.Cu")
		(net "M_G_CPU1_SA_DQS_DN<3>")
	)
	(arc
		(start 129.323592 -268.080236)
		(mid 129.136394 -268.130379)
		(end 128.949196 -268.080236)
		(width 0.088646)
		(layer "In6.Cu")
		(net "M_G_CPU1_SA_DQS_DN<3>")
	)
	(arc
		(start 135.902192 -268.080236)
		(mid 135.714994 -268.130379)
		(end 135.527796 -268.080236)
		(width 0.088646)
		(layer "In6.Cu")
		(net "M_G_CPU1_SA_DQS_DN<3>")
	)
	(arc
		(start 134.573264 -268.0716)
		(mid 134.296789 -268.00428)
		(end 134.022592 -268.080236)
		(width 0.088646)
		(layer "In6.Cu")
		(net "M_G_CPU1_SA_DQS_DN<3>")
	)
	(arc
		(start 128.94183 -268.076172)
		(mid 128.690344 -268.005292)
		(end 128.43383 -268.05509)
		(width 0.088646)
		(layer "In6.Cu")
		(net "M_G_CPU1_SA_DQS_DN<3>")
	)
	(arc
		(start 128.3843 -268.08049)
		(mid 128.179937 -268.130412)
		(end 127.980948 -268.062202)
		(width 0.088646)
		(layer "In6.Cu")
		(net "M_G_CPU1_SA_DQS_DN<3>")
	)
	(arc
		(start 132.697982 -268.07414)
		(mid 132.419804 -268.004417)
		(end 132.143246 -268.080236)
		(width 0.088646)
		(layer "In6.Cu")
		(net "M_G_CPU1_SA_DQS_DN<3>")
	)
	(arc
		(start 138.7094 -268.087094)
		(mid 138.527289 -268.130419)
		(end 138.346942 -268.080236)
		(width 0.088646)
		(layer "In6.Cu")
		(net "M_G_CPU1_SA_DQS_DN<3>")
	)
	(arc
		(start 131.758436 -268.07414)
		(mid 131.480004 -268.004294)
		(end 131.203192 -268.080236)
		(width 0.088646)
		(layer "In6.Cu")
		(net "M_G_CPU1_SA_DQS_DN<3>")
	)
	(arc
		(start 134.962392 -268.080236)
		(mid 134.775194 -268.130379)
		(end 134.587996 -268.080236)
		(width 0.088646)
		(layer "In6.Cu")
		(net "M_G_CPU1_SA_DQS_DN<3>")
	)
	(arc
		(start 137.773156 -268.085062)
		(mid 137.589648 -268.13034)
		(end 137.407396 -268.080236)
		(width 0.088646)
		(layer "In6.Cu")
		(net "M_G_CPU1_SA_DQS_DN<3>")
	)
	(arc
		(start 130.263392 -268.080236)
		(mid 130.076194 -268.130379)
		(end 129.888996 -268.080236)
		(width 0.088646)
		(layer "In6.Cu")
		(net "M_G_CPU1_SA_DQS_DN<3>")
	)
	(arc
		(start 136.841992 -268.080236)
		(mid 136.654794 -268.130379)
		(end 136.467596 -268.080236)
		(width 0.088646)
		(layer "In6.Cu")
		(net "M_G_CPU1_SA_DQS_DN<3>")
	)
	(arc
		(start 133.633464 -268.0716)
		(mid 133.356989 -268.00428)
		(end 133.082792 -268.080236)
		(width 0.088646)
		(layer "In6.Cu")
		(net "M_G_CPU1_SA_DQS_DN<3>")
	)
	(arc
		(start 129.874264 -268.0716)
		(mid 129.597789 -268.00428)
		(end 129.323592 -268.080236)
		(width 0.088646)
		(layer "In6.Cu")
		(net "M_G_CPU1_SA_DQS_DN<3>")
	)
	(arc
		(start 135.513064 -268.0716)
		(mid 135.236589 -268.00428)
		(end 134.962392 -268.080236)
		(width 0.088646)
		(layer "In6.Cu")
		(net "M_G_CPU1_SA_DQS_DN<3>")
	)
	(arc
		(start 131.203192 -268.080236)
		(mid 131.015994 -268.130379)
		(end 130.828796 -268.080236)
		(width 0.088646)
		(layer "In6.Cu")
		(net "M_G_CPU1_SA_DQS_DN<3>")
	)
	(arc
		(start 138.346942 -268.080236)
		(mid 138.072743 -268.004401)
		(end 137.79627 -268.0716)
		(width 0.088646)
		(layer "In6.Cu")
		(net "M_G_CPU1_SA_DQS_DN<3>")
	)
	(arc
		(start 139.654026 -268.084554)
		(mid 139.469336 -268.130878)
		(end 139.285726 -268.08049)
		(width 0.088646)
		(layer "In6.Cu")
		(net "M_G_CPU1_SA_DQS_DN<3>")
	)
	(arc
		(start 130.814064 -268.0716)
		(mid 130.537589 -268.00428)
		(end 130.263392 -268.080236)
		(width 0.088646)
		(layer "In6.Cu")
		(net "M_G_CPU1_SA_DQS_DN<3>")
	)
	(arc
		(start 132.143246 -268.080236)
		(mid 131.956048 -268.130379)
		(end 131.76885 -268.080236)
		(width 0.088646)
		(layer "In6.Cu")
		(net "M_G_CPU1_SA_DQS_DN<3>")
	)
	(arc
		(start 134.022592 -268.080236)
		(mid 133.835394 -268.130379)
		(end 133.648196 -268.080236)
		(width 0.088646)
		(layer "In6.Cu")
		(net "M_G_CPU1_SA_DQS_DN<3>")
	)
	(segment
		(start 191.914018 -293.79164)
		(end 194.093592 -293.79164)
		(width 0.1016)
		(layer "F.Cu")
		(net "M_G_CPU1_SA_DQS_DN<2>")
	)
	(segment
		(start 190.55461 -293.648384)
		(end 190.969138 -294.062912)
		(width 0.20066)
		(layer "F.Cu")
		(net "M_G_CPU1_SA_DQS_DN<2>")
	)
	(segment
		(start 191.762126 -293.79164)
		(end 191.9097 -293.79164)
		(width 0.20066)
		(layer "F.Cu")
		(net "M_G_CPU1_SA_DQS_DN<2>")
	)
	(segment
		(start 190.969138 -294.062912)
		(end 191.490854 -294.062912)
		(width 0.20066)
		(layer "F.Cu")
		(net "M_G_CPU1_SA_DQS_DN<2>")
	)
	(segment
		(start 189.818772 -293.648384)
		(end 190.55461 -293.648384)
		(width 0.20066)
		(layer "F.Cu")
		(net "M_G_CPU1_SA_DQS_DN<2>")
	)
	(segment
		(start 188.988446 -293.366698)
		(end 189.537086 -293.366698)
		(width 0.20066)
		(layer "F.Cu")
		(net "M_G_CPU1_SA_DQS_DN<2>")
	)
	(segment
		(start 194.098926 -293.786306)
		(end 194.42303 -293.786306)
		(width 0.20066)
		(layer "F.Cu")
		(net "M_G_CPU1_SA_DQS_DN<2>")
	)
	(segment
		(start 129.606294 -265.313922)
		(end 129.606548 -265.314176)
		(width 0.20066)
		(layer "F.Cu")
		(net "M_G_CPU1_SA_DQS_DN<2>")
	)
	(segment
		(start 194.093592 -293.79164)
		(end 194.098926 -293.786306)
		(width 0.1016)
		(layer "F.Cu")
		(net "M_G_CPU1_SA_DQS_DN<2>")
	)
	(segment
		(start 191.490854 -294.062912)
		(end 191.762126 -293.79164)
		(width 0.20066)
		(layer "F.Cu")
		(net "M_G_CPU1_SA_DQS_DN<2>")
	)
	(segment
		(start 195.942966 -293.366698)
		(end 196.532246 -293.366698)
		(width 0.20066)
		(layer "F.Cu")
		(net "M_G_CPU1_SA_DQS_DN<2>")
	)
	(segment
		(start 194.959478 -294.0177)
		(end 195.369942 -293.607236)
		(width 0.20066)
		(layer "F.Cu")
		(net "M_G_CPU1_SA_DQS_DN<2>")
	)
	(segment
		(start 191.9097 -293.79164)
		(end 191.914018 -293.79164)
		(width 0.101854)
		(layer "F.Cu")
		(net "M_G_CPU1_SA_DQS_DN<2>")
	)
	(segment
		(start 187.883546 -293.366698)
		(end 188.988446 -293.366698)
		(width 0.20066)
		(layer "F.Cu")
		(net "M_G_CPU1_SA_DQS_DN<2>")
	)
	(segment
		(start 194.654424 -294.0177)
		(end 194.959478 -294.0177)
		(width 0.20066)
		(layer "F.Cu")
		(net "M_G_CPU1_SA_DQS_DN<2>")
	)
	(segment
		(start 195.369942 -293.607236)
		(end 195.702428 -293.607236)
		(width 0.20066)
		(layer "F.Cu")
		(net "M_G_CPU1_SA_DQS_DN<2>")
	)
	(segment
		(start 129.606294 -264.778236)
		(end 129.606294 -265.313922)
		(width 0.20066)
		(layer "F.Cu")
		(net "M_G_CPU1_SA_DQS_DN<2>")
	)
	(segment
		(start 194.42303 -293.786306)
		(end 194.654424 -294.0177)
		(width 0.20066)
		(layer "F.Cu")
		(net "M_G_CPU1_SA_DQS_DN<2>")
	)
	(segment
		(start 189.537086 -293.366698)
		(end 189.818772 -293.648384)
		(width 0.20066)
		(layer "F.Cu")
		(net "M_G_CPU1_SA_DQS_DN<2>")
	)
	(segment
		(start 195.702428 -293.607236)
		(end 195.942966 -293.366698)
		(width 0.20066)
		(layer "F.Cu")
		(net "M_G_CPU1_SA_DQS_DN<2>")
	)
	(segment
		(start 163.616132 -288.415984)
		(end 163.616132 -288.14903)
		(width 0.18288)
		(layer "In4.Cu")
		(net "M_G_CPU1_SA_DQS_DN<2>")
	)
	(segment
		(start 172.189394 -294.757602)
		(end 171.510198 -294.62222)
		(width 0.18288)
		(layer "In4.Cu")
		(net "M_G_CPU1_SA_DQS_DN<2>")
	)
	(segment
		(start 162.588956 -286.435038)
		(end 162.00247 -285.848552)
		(width 0.18288)
		(layer "In4.Cu")
		(net "M_G_CPU1_SA_DQS_DN<2>")
	)
	(segment
		(start 163.616132 -288.14903)
		(end 162.588956 -287.121854)
		(width 0.18288)
		(layer "In4.Cu")
		(net "M_G_CPU1_SA_DQS_DN<2>")
	)
	(segment
		(start 168.660826 -292.160706)
		(end 168.081706 -291.581586)
		(width 0.18288)
		(layer "In4.Cu")
		(net "M_G_CPU1_SA_DQS_DN<2>")
	)
	(segment
		(start 187.222892 -293.636446)
		(end 186.97194 -293.385494)
		(width 0.18288)
		(layer "In4.Cu")
		(net "M_G_CPU1_SA_DQS_DN<2>")
	)
	(segment
		(start 169.425112 -292.160706)
		(end 168.660826 -292.160706)
		(width 0.18288)
		(layer "In4.Cu")
		(net "M_G_CPU1_SA_DQS_DN<2>")
	)
	(segment
		(start 135.447278 -265.629898)
		(end 135.432546 -265.638534)
		(width 0.088646)
		(layer "In4.Cu")
		(net "M_G_CPU1_SA_DQS_DN<2>")
	)
	(segment
		(start 173.264322 -294.89273)
		(end 173.013878 -294.642286)
		(width 0.18288)
		(layer "In4.Cu")
		(net "M_G_CPU1_SA_DQS_DN<2>")
	)
	(segment
		(start 171.474384 -294.607488)
		(end 171.275502 -294.40886)
		(width 0.18288)
		(layer "In4.Cu")
		(net "M_G_CPU1_SA_DQS_DN<2>")
	)
	(segment
		(start 164.382196 -289.023806)
		(end 164.223954 -289.023806)
		(width 0.18288)
		(layer "In4.Cu")
		(net "M_G_CPU1_SA_DQS_DN<2>")
	)
	(segment
		(start 146.024092 -268.728952)
		(end 144.42059 -268.728952)
		(width 0.18288)
		(layer "In4.Cu")
		(net "M_G_CPU1_SA_DQS_DN<2>")
	)
	(segment
		(start 176.70145 -293.792402)
		(end 176.447704 -294.046148)
		(width 0.18288)
		(layer "In4.Cu")
		(net "M_G_CPU1_SA_DQS_DN<2>")
	)
	(segment
		(start 130.934968 -265.225784)
		(end 130.935222 -265.22553)
		(width 0.088646)
		(layer "In4.Cu")
		(net "M_G_CPU1_SA_DQS_DN<2>")
	)
	(segment
		(start 187.883546 -293.366698)
		(end 187.613798 -293.636446)
		(width 0.18288)
		(layer "In4.Cu")
		(net "M_G_CPU1_SA_DQS_DN<2>")
	)
	(segment
		(start 165.759384 -289.887406)
		(end 165.245796 -289.887406)
		(width 0.18288)
		(layer "In4.Cu")
		(net "M_G_CPU1_SA_DQS_DN<2>")
	)
	(segment
		(start 172.44695 -294.757602)
		(end 172.189394 -294.757602)
		(width 0.18288)
		(layer "In4.Cu")
		(net "M_G_CPU1_SA_DQS_DN<2>")
	)
	(segment
		(start 130.718814 -264.981436)
		(end 130.718052 -264.980928)
		(width 0.088646)
		(layer "In4.Cu")
		(net "M_G_CPU1_SA_DQS_DN<2>")
	)
	(segment
		(start 144.42059 -268.728952)
		(end 143.021558 -268.149324)
		(width 0.18288)
		(layer "In4.Cu")
		(net "M_G_CPU1_SA_DQS_DN<2>")
	)
	(segment
		(start 131.29895 -265.638534)
		(end 131.234942 -265.601704)
		(width 0.088646)
		(layer "In4.Cu")
		(net "M_G_CPU1_SA_DQS_DN<2>")
	)
	(segment
		(start 178.569112 -293.127938)
		(end 177.649378 -294.047672)
		(width 0.18288)
		(layer "In4.Cu")
		(net "M_G_CPU1_SA_DQS_DN<2>")
	)
	(segment
		(start 134.507478 -265.629898)
		(end 134.492746 -265.638534)
		(width 0.088646)
		(layer "In4.Cu")
		(net "M_G_CPU1_SA_DQS_DN<2>")
	)
	(segment
		(start 162.00247 -285.848552)
		(end 161.410142 -285.848552)
		(width 0.18288)
		(layer "In4.Cu")
		(net "M_G_CPU1_SA_DQS_DN<2>")
	)
	(segment
		(start 131.234942 -265.601704)
		(end 130.934968 -265.225784)
		(width 0.088646)
		(layer "In4.Cu")
		(net "M_G_CPU1_SA_DQS_DN<2>")
	)
	(segment
		(start 156.783532 -283.129482)
		(end 156.757116 -283.10332)
		(width 0.18288)
		(layer "In4.Cu")
		(net "M_G_CPU1_SA_DQS_DN<2>")
	)
	(segment
		(start 161.410142 -285.848552)
		(end 159.202628 -283.641038)
		(width 0.18288)
		(layer "In4.Cu")
		(net "M_G_CPU1_SA_DQS_DN<2>")
	)
	(segment
		(start 154.088846 -276.793452)
		(end 146.024092 -268.728952)
		(width 0.18288)
		(layer "In4.Cu")
		(net "M_G_CPU1_SA_DQS_DN<2>")
	)
	(segment
		(start 140.383006 -265.575288)
		(end 138.665204 -265.575288)
		(width 0.18288)
		(layer "In4.Cu")
		(net "M_G_CPU1_SA_DQS_DN<2>")
	)
	(segment
		(start 186.267852 -293.127938)
		(end 178.569112 -293.127938)
		(width 0.18288)
		(layer "In4.Cu")
		(net "M_G_CPU1_SA_DQS_DN<2>")
	)
	(segment
		(start 143.021558 -268.149324)
		(end 142.911322 -268.103604)
		(width 0.18288)
		(layer "In4.Cu")
		(net "M_G_CPU1_SA_DQS_DN<2>")
	)
	(segment
		(start 130.889502 -265.157966)
		(end 130.872484 -265.128248)
		(width 0.088646)
		(layer "In4.Cu")
		(net "M_G_CPU1_SA_DQS_DN<2>")
	)
	(segment
		(start 165.245796 -289.887406)
		(end 164.382196 -289.023806)
		(width 0.18288)
		(layer "In4.Cu")
		(net "M_G_CPU1_SA_DQS_DN<2>")
	)
	(segment
		(start 171.275502 -294.40886)
		(end 171.275502 -294.011096)
		(width 0.18288)
		(layer "In4.Cu")
		(net "M_G_CPU1_SA_DQS_DN<2>")
	)
	(segment
		(start 171.275502 -294.011096)
		(end 169.425112 -292.160706)
		(width 0.18288)
		(layer "In4.Cu")
		(net "M_G_CPU1_SA_DQS_DN<2>")
	)
	(segment
		(start 173.490382 -294.89273)
		(end 173.264322 -294.89273)
		(width 0.18288)
		(layer "In4.Cu")
		(net "M_G_CPU1_SA_DQS_DN<2>")
	)
	(segment
		(start 142.911322 -268.103604)
		(end 140.383006 -265.575288)
		(width 0.18288)
		(layer "In4.Cu")
		(net "M_G_CPU1_SA_DQS_DN<2>")
	)
	(segment
		(start 156.757116 -283.10332)
		(end 154.088846 -276.793452)
		(width 0.18288)
		(layer "In4.Cu")
		(net "M_G_CPU1_SA_DQS_DN<2>")
	)
	(segment
		(start 173.013878 -294.642286)
		(end 172.562266 -294.642286)
		(width 0.18288)
		(layer "In4.Cu")
		(net "M_G_CPU1_SA_DQS_DN<2>")
	)
	(segment
		(start 164.223954 -289.023806)
		(end 163.616132 -288.415984)
		(width 0.18288)
		(layer "In4.Cu")
		(net "M_G_CPU1_SA_DQS_DN<2>")
	)
	(segment
		(start 131.688078 -265.629898)
		(end 131.673346 -265.638534)
		(width 0.088646)
		(layer "In4.Cu")
		(net "M_G_CPU1_SA_DQS_DN<2>")
	)
	(segment
		(start 187.613798 -293.636446)
		(end 187.222892 -293.636446)
		(width 0.18288)
		(layer "In4.Cu")
		(net "M_G_CPU1_SA_DQS_DN<2>")
	)
	(segment
		(start 162.588956 -287.121854)
		(end 162.588956 -286.435038)
		(width 0.18288)
		(layer "In4.Cu")
		(net "M_G_CPU1_SA_DQS_DN<2>")
	)
	(segment
		(start 177.352706 -294.047672)
		(end 177.097436 -293.792402)
		(width 0.18288)
		(layer "In4.Cu")
		(net "M_G_CPU1_SA_DQS_DN<2>")
	)
	(segment
		(start 177.649378 -294.047672)
		(end 177.352706 -294.047672)
		(width 0.18288)
		(layer "In4.Cu")
		(net "M_G_CPU1_SA_DQS_DN<2>")
	)
	(segment
		(start 130.17627 -265.257026)
		(end 130.11912 -265.314176)
		(width 0.088646)
		(layer "In4.Cu")
		(net "M_G_CPU1_SA_DQS_DN<2>")
	)
	(segment
		(start 138.641836 -265.575288)
		(end 138.582146 -265.634978)
		(width 0.088646)
		(layer "In4.Cu")
		(net "M_G_CPU1_SA_DQS_DN<2>")
	)
	(segment
		(start 136.387078 -265.629898)
		(end 136.372346 -265.638534)
		(width 0.088646)
		(layer "In4.Cu")
		(net "M_G_CPU1_SA_DQS_DN<2>")
	)
	(segment
		(start 174.337472 -294.046148)
		(end 173.490382 -294.89273)
		(width 0.18288)
		(layer "In4.Cu")
		(net "M_G_CPU1_SA_DQS_DN<2>")
	)
	(segment
		(start 138.582146 -265.634978)
		(end 137.616184 -265.634978)
		(width 0.088646)
		(layer "In4.Cu")
		(net "M_G_CPU1_SA_DQS_DN<2>")
	)
	(segment
		(start 186.97194 -293.385494)
		(end 186.525408 -293.385494)
		(width 0.18288)
		(layer "In4.Cu")
		(net "M_G_CPU1_SA_DQS_DN<2>")
	)
	(segment
		(start 133.563106 -265.632438)
		(end 133.552692 -265.638534)
		(width 0.088646)
		(layer "In4.Cu")
		(net "M_G_CPU1_SA_DQS_DN<2>")
	)
	(segment
		(start 167.453818 -291.581586)
		(end 165.759384 -289.887406)
		(width 0.18288)
		(layer "In4.Cu")
		(net "M_G_CPU1_SA_DQS_DN<2>")
	)
	(segment
		(start 132.62356 -265.632438)
		(end 132.613146 -265.638534)
		(width 0.088646)
		(layer "In4.Cu")
		(net "M_G_CPU1_SA_DQS_DN<2>")
	)
	(segment
		(start 186.525408 -293.385494)
		(end 186.267852 -293.127938)
		(width 0.18288)
		(layer "In4.Cu")
		(net "M_G_CPU1_SA_DQS_DN<2>")
	)
	(segment
		(start 168.081706 -291.581586)
		(end 167.453818 -291.581586)
		(width 0.18288)
		(layer "In4.Cu")
		(net "M_G_CPU1_SA_DQS_DN<2>")
	)
	(segment
		(start 177.097436 -293.792402)
		(end 176.70145 -293.792402)
		(width 0.18288)
		(layer "In4.Cu")
		(net "M_G_CPU1_SA_DQS_DN<2>")
	)
	(segment
		(start 138.665204 -265.575288)
		(end 138.641836 -265.575288)
		(width 0.088646)
		(layer "In4.Cu")
		(net "M_G_CPU1_SA_DQS_DN<2>")
	)
	(segment
		(start 159.202628 -283.641038)
		(end 157.295088 -283.641038)
		(width 0.18288)
		(layer "In4.Cu")
		(net "M_G_CPU1_SA_DQS_DN<2>")
	)
	(segment
		(start 157.295088 -283.641038)
		(end 156.783532 -283.129482)
		(width 0.18288)
		(layer "In4.Cu")
		(net "M_G_CPU1_SA_DQS_DN<2>")
	)
	(segment
		(start 176.447704 -294.046148)
		(end 174.337472 -294.046148)
		(width 0.18288)
		(layer "In4.Cu")
		(net "M_G_CPU1_SA_DQS_DN<2>")
	)
	(segment
		(start 172.562266 -294.642286)
		(end 172.44695 -294.757602)
		(width 0.18288)
		(layer "In4.Cu")
		(net "M_G_CPU1_SA_DQS_DN<2>")
	)
	(segment
		(start 171.510198 -294.62222)
		(end 171.474384 -294.607488)
		(width 0.18288)
		(layer "In4.Cu")
		(net "M_G_CPU1_SA_DQS_DN<2>")
	)
	(segment
		(start 130.11912 -265.314176)
		(end 129.606548 -265.314176)
		(width 0.088646)
		(layer "In4.Cu")
		(net "M_G_CPU1_SA_DQS_DN<2>")
	)
	(arc
		(start 136.93775 -265.638534)
		(mid 136.663521 -265.562609)
		(end 136.387078 -265.629898)
		(width 0.088646)
		(layer "In4.Cu")
		(net "M_G_CPU1_SA_DQS_DN<2>")
	)
	(arc
		(start 130.935222 -265.22553)
		(mid 130.91102 -265.192655)
		(end 130.889502 -265.157966)
		(width 0.088646)
		(layer "In4.Cu")
		(net "M_G_CPU1_SA_DQS_DN<2>")
	)
	(arc
		(start 131.673346 -265.638534)
		(mid 131.486148 -265.688677)
		(end 131.29895 -265.638534)
		(width 0.088646)
		(layer "In4.Cu")
		(net "M_G_CPU1_SA_DQS_DN<2>")
	)
	(arc
		(start 130.718052 -264.980928)
		(mid 130.376498 -264.980239)
		(end 130.17627 -265.257026)
		(width 0.088646)
		(layer "In4.Cu")
		(net "M_G_CPU1_SA_DQS_DN<2>")
	)
	(arc
		(start 134.492746 -265.638534)
		(mid 134.305548 -265.688677)
		(end 134.11835 -265.638534)
		(width 0.088646)
		(layer "In4.Cu")
		(net "M_G_CPU1_SA_DQS_DN<2>")
	)
	(arc
		(start 135.05815 -265.638534)
		(mid 134.783951 -265.562699)
		(end 134.507478 -265.629898)
		(width 0.088646)
		(layer "In4.Cu")
		(net "M_G_CPU1_SA_DQS_DN<2>")
	)
	(arc
		(start 137.206482 -265.679936)
		(mid 137.068218 -265.6845)
		(end 136.93775 -265.638534)
		(width 0.088646)
		(layer "In4.Cu")
		(net "M_G_CPU1_SA_DQS_DN<2>")
	)
	(arc
		(start 136.372346 -265.638534)
		(mid 136.185148 -265.688677)
		(end 135.99795 -265.638534)
		(width 0.088646)
		(layer "In4.Cu")
		(net "M_G_CPU1_SA_DQS_DN<2>")
	)
	(arc
		(start 135.432546 -265.638534)
		(mid 135.245348 -265.688677)
		(end 135.05815 -265.638534)
		(width 0.088646)
		(layer "In4.Cu")
		(net "M_G_CPU1_SA_DQS_DN<2>")
	)
	(arc
		(start 130.872484 -265.128248)
		(mid 130.806305 -265.043688)
		(end 130.718814 -264.981436)
		(width 0.088646)
		(layer "In4.Cu")
		(net "M_G_CPU1_SA_DQS_DN<2>")
	)
	(arc
		(start 132.613146 -265.638534)
		(mid 132.425948 -265.688677)
		(end 132.23875 -265.638534)
		(width 0.088646)
		(layer "In4.Cu")
		(net "M_G_CPU1_SA_DQS_DN<2>")
	)
	(arc
		(start 133.552692 -265.638534)
		(mid 133.365494 -265.688677)
		(end 133.178296 -265.638534)
		(width 0.088646)
		(layer "In4.Cu")
		(net "M_G_CPU1_SA_DQS_DN<2>")
	)
	(arc
		(start 134.11835 -265.638534)
		(mid 133.841537 -265.562664)
		(end 133.563106 -265.632438)
		(width 0.088646)
		(layer "In4.Cu")
		(net "M_G_CPU1_SA_DQS_DN<2>")
	)
	(arc
		(start 137.616184 -265.634978)
		(mid 137.410105 -265.646264)
		(end 137.206482 -265.679936)
		(width 0.088646)
		(layer "In4.Cu")
		(net "M_G_CPU1_SA_DQS_DN<2>")
	)
	(arc
		(start 132.23875 -265.638534)
		(mid 131.964521 -265.562609)
		(end 131.688078 -265.629898)
		(width 0.088646)
		(layer "In4.Cu")
		(net "M_G_CPU1_SA_DQS_DN<2>")
	)
	(arc
		(start 135.99795 -265.638534)
		(mid 135.723721 -265.562609)
		(end 135.447278 -265.629898)
		(width 0.088646)
		(layer "In4.Cu")
		(net "M_G_CPU1_SA_DQS_DN<2>")
	)
	(arc
		(start 133.178296 -265.638534)
		(mid 132.901737 -265.562791)
		(end 132.62356 -265.632438)
		(width 0.088646)
		(layer "In4.Cu")
		(net "M_G_CPU1_SA_DQS_DN<2>")
	)
	(segment
		(start 189.537086 -302.716692)
		(end 189.818772 -302.998378)
		(width 0.20066)
		(layer "F.Cu")
		(net "M_G_CPU1_SA_DQS_DN<1>")
	)
	(segment
		(start 187.883546 -302.716692)
		(end 188.988446 -302.716692)
		(width 0.20066)
		(layer "F.Cu")
		(net "M_G_CPU1_SA_DQS_DN<1>")
	)
	(segment
		(start 194.959478 -303.367694)
		(end 195.369942 -302.95723)
		(width 0.20066)
		(layer "F.Cu")
		(net "M_G_CPU1_SA_DQS_DN<1>")
	)
	(segment
		(start 191.490854 -303.412906)
		(end 191.762126 -303.141634)
		(width 0.20066)
		(layer "F.Cu")
		(net "M_G_CPU1_SA_DQS_DN<1>")
	)
	(segment
		(start 191.762126 -303.141634)
		(end 191.9097 -303.141634)
		(width 0.20066)
		(layer "F.Cu")
		(net "M_G_CPU1_SA_DQS_DN<1>")
	)
	(segment
		(start 194.654424 -303.367694)
		(end 194.959478 -303.367694)
		(width 0.20066)
		(layer "F.Cu")
		(net "M_G_CPU1_SA_DQS_DN<1>")
	)
	(segment
		(start 191.914018 -303.141634)
		(end 194.093592 -303.141634)
		(width 0.1016)
		(layer "F.Cu")
		(net "M_G_CPU1_SA_DQS_DN<1>")
	)
	(segment
		(start 194.093592 -303.141634)
		(end 194.098926 -303.1363)
		(width 0.1016)
		(layer "F.Cu")
		(net "M_G_CPU1_SA_DQS_DN<1>")
	)
	(segment
		(start 195.369942 -302.95723)
		(end 195.702428 -302.95723)
		(width 0.20066)
		(layer "F.Cu")
		(net "M_G_CPU1_SA_DQS_DN<1>")
	)
	(segment
		(start 189.818772 -302.998378)
		(end 190.55461 -302.998378)
		(width 0.20066)
		(layer "F.Cu")
		(net "M_G_CPU1_SA_DQS_DN<1>")
	)
	(segment
		(start 194.42303 -303.1363)
		(end 194.654424 -303.367694)
		(width 0.20066)
		(layer "F.Cu")
		(net "M_G_CPU1_SA_DQS_DN<1>")
	)
	(segment
		(start 188.988446 -302.716692)
		(end 189.537086 -302.716692)
		(width 0.20066)
		(layer "F.Cu")
		(net "M_G_CPU1_SA_DQS_DN<1>")
	)
	(segment
		(start 194.098926 -303.1363)
		(end 194.42303 -303.1363)
		(width 0.20066)
		(layer "F.Cu")
		(net "M_G_CPU1_SA_DQS_DN<1>")
	)
	(segment
		(start 190.969138 -303.412906)
		(end 191.490854 -303.412906)
		(width 0.20066)
		(layer "F.Cu")
		(net "M_G_CPU1_SA_DQS_DN<1>")
	)
	(segment
		(start 195.942966 -302.716692)
		(end 196.532246 -302.716692)
		(width 0.20066)
		(layer "F.Cu")
		(net "M_G_CPU1_SA_DQS_DN<1>")
	)
	(segment
		(start 191.9097 -303.141634)
		(end 191.914018 -303.141634)
		(width 0.101854)
		(layer "F.Cu")
		(net "M_G_CPU1_SA_DQS_DN<1>")
	)
	(segment
		(start 190.55461 -302.998378)
		(end 190.969138 -303.412906)
		(width 0.20066)
		(layer "F.Cu")
		(net "M_G_CPU1_SA_DQS_DN<1>")
	)
	(segment
		(start 126.317248 -272.103342)
		(end 126.316994 -272.639282)
		(width 0.20066)
		(layer "F.Cu")
		(net "M_G_CPU1_SA_DQS_DN<1>")
	)
	(segment
		(start 195.702428 -302.95723)
		(end 195.942966 -302.716692)
		(width 0.20066)
		(layer "F.Cu")
		(net "M_G_CPU1_SA_DQS_DN<1>")
	)
	(segment
		(start 177.41011 -297.437048)
		(end 177.165508 -297.192446)
		(width 0.18288)
		(layer "In6.Cu")
		(net "M_G_CPU1_SA_DQS_DN<1>")
	)
	(segment
		(start 140.595604 -274.375372)
		(end 140.572236 -274.375372)
		(width 0.088646)
		(layer "In6.Cu")
		(net "M_G_CPU1_SA_DQS_DN<1>")
	)
	(segment
		(start 179.886356 -299.031406)
		(end 178.291998 -297.437048)
		(width 0.18288)
		(layer "In6.Cu")
		(net "M_G_CPU1_SA_DQS_DN<1>")
	)
	(segment
		(start 173.06544 -296.342562)
		(end 172.536612 -296.342562)
		(width 0.18288)
		(layer "In6.Cu")
		(net "M_G_CPU1_SA_DQS_DN<1>")
	)
	(segment
		(start 183.42356 -300.606206)
		(end 182.365904 -300.606206)
		(width 0.18288)
		(layer "In6.Cu")
		(net "M_G_CPU1_SA_DQS_DN<1>")
	)
	(segment
		(start 128.007872 -272.962878)
		(end 128.004316 -272.960846)
		(width 0.088646)
		(layer "In6.Cu")
		(net "M_G_CPU1_SA_DQS_DN<1>")
	)
	(segment
		(start 157.531816 -292.947852)
		(end 154.209242 -289.625278)
		(width 0.18288)
		(layer "In6.Cu")
		(net "M_G_CPU1_SA_DQS_DN<1>")
	)
	(segment
		(start 174.851314 -297.470576)
		(end 173.971458 -296.59072)
		(width 0.18288)
		(layer "In6.Cu")
		(net "M_G_CPU1_SA_DQS_DN<1>")
	)
	(segment
		(start 142.09776 -274.752816)
		(end 141.186662 -274.375372)
		(width 0.18288)
		(layer "In6.Cu")
		(net "M_G_CPU1_SA_DQS_DN<1>")
	)
	(segment
		(start 162.926776 -294.064182)
		(end 162.625024 -293.762176)
		(width 0.18288)
		(layer "In6.Cu")
		(net "M_G_CPU1_SA_DQS_DN<1>")
	)
	(segment
		(start 126.829566 -272.639282)
		(end 126.316994 -272.639282)
		(width 0.088646)
		(layer "In6.Cu")
		(net "M_G_CPU1_SA_DQS_DN<1>")
	)
	(segment
		(start 163.505642 -294.064182)
		(end 162.926776 -294.064182)
		(width 0.18288)
		(layer "In6.Cu")
		(net "M_G_CPU1_SA_DQS_DN<1>")
	)
	(segment
		(start 160.661096 -292.947852)
		(end 157.531816 -292.947852)
		(width 0.18288)
		(layer "In6.Cu")
		(net "M_G_CPU1_SA_DQS_DN<1>")
	)
	(segment
		(start 141.186662 -274.375372)
		(end 140.595604 -274.375372)
		(width 0.18288)
		(layer "In6.Cu")
		(net "M_G_CPU1_SA_DQS_DN<1>")
	)
	(segment
		(start 176.35855 -297.470576)
		(end 174.851314 -297.470576)
		(width 0.18288)
		(layer "In6.Cu")
		(net "M_G_CPU1_SA_DQS_DN<1>")
	)
	(segment
		(start 165.825424 -294.027606)
		(end 164.541454 -294.027606)
		(width 0.18288)
		(layer "In6.Cu")
		(net "M_G_CPU1_SA_DQS_DN<1>")
	)
	(segment
		(start 138.961114 -273.014186)
		(end 138.533886 -273.014186)
		(width 0.088646)
		(layer "In6.Cu")
		(net "M_G_CPU1_SA_DQS_DN<1>")
	)
	(segment
		(start 182.365904 -300.606206)
		(end 180.791104 -299.031406)
		(width 0.18288)
		(layer "In6.Cu")
		(net "M_G_CPU1_SA_DQS_DN<1>")
	)
	(segment
		(start 134.587996 -272.96364)
		(end 134.573264 -272.955004)
		(width 0.088646)
		(layer "In6.Cu")
		(net "M_G_CPU1_SA_DQS_DN<1>")
	)
	(segment
		(start 137.791952 -272.957544)
		(end 137.773156 -272.968466)
		(width 0.088646)
		(layer "In6.Cu")
		(net "M_G_CPU1_SA_DQS_DN<1>")
	)
	(segment
		(start 172.256704 -296.62247)
		(end 168.80459 -296.62247)
		(width 0.18288)
		(layer "In6.Cu")
		(net "M_G_CPU1_SA_DQS_DN<1>")
	)
	(segment
		(start 130.828796 -272.96364)
		(end 130.814064 -272.955004)
		(width 0.088646)
		(layer "In6.Cu")
		(net "M_G_CPU1_SA_DQS_DN<1>")
	)
	(segment
		(start 173.971458 -296.59072)
		(end 173.313598 -296.59072)
		(width 0.18288)
		(layer "In6.Cu")
		(net "M_G_CPU1_SA_DQS_DN<1>")
	)
	(segment
		(start 164.254434 -293.740586)
		(end 163.829238 -293.740586)
		(width 0.18288)
		(layer "In6.Cu")
		(net "M_G_CPU1_SA_DQS_DN<1>")
	)
	(segment
		(start 162.625024 -293.762176)
		(end 160.661096 -292.947852)
		(width 0.18288)
		(layer "In6.Cu")
		(net "M_G_CPU1_SA_DQS_DN<1>")
	)
	(segment
		(start 167.327834 -295.530016)
		(end 165.825424 -294.027606)
		(width 0.18288)
		(layer "In6.Cu")
		(net "M_G_CPU1_SA_DQS_DN<1>")
	)
	(segment
		(start 154.209242 -280.97861)
		(end 147.983448 -274.752816)
		(width 0.18288)
		(layer "In6.Cu")
		(net "M_G_CPU1_SA_DQS_DN<1>")
	)
	(segment
		(start 128.949196 -272.96364)
		(end 128.934464 -272.955004)
		(width 0.088646)
		(layer "In6.Cu")
		(net "M_G_CPU1_SA_DQS_DN<1>")
	)
	(segment
		(start 140.512546 -274.435062)
		(end 140.38199 -274.435062)
		(width 0.088646)
		(layer "In6.Cu")
		(net "M_G_CPU1_SA_DQS_DN<1>")
	)
	(segment
		(start 127.815594 -272.693892)
		(end 127.75819 -272.581116)
		(width 0.088646)
		(layer "In6.Cu")
		(net "M_G_CPU1_SA_DQS_DN<1>")
	)
	(segment
		(start 128.004316 -272.960846)
		(end 128.004316 -272.960592)
		(width 0.088646)
		(layer "In6.Cu")
		(net "M_G_CPU1_SA_DQS_DN<1>")
	)
	(segment
		(start 167.712136 -295.530016)
		(end 167.327834 -295.530016)
		(width 0.18288)
		(layer "In6.Cu")
		(net "M_G_CPU1_SA_DQS_DN<1>")
	)
	(segment
		(start 178.291998 -297.437048)
		(end 177.41011 -297.437048)
		(width 0.18288)
		(layer "In6.Cu")
		(net "M_G_CPU1_SA_DQS_DN<1>")
	)
	(segment
		(start 132.708396 -272.96364)
		(end 132.697982 -272.957544)
		(width 0.088646)
		(layer "In6.Cu")
		(net "M_G_CPU1_SA_DQS_DN<1>")
	)
	(segment
		(start 127.743712 -272.56105)
		(end 127.663702 -272.48104)
		(width 0.088646)
		(layer "In6.Cu")
		(net "M_G_CPU1_SA_DQS_DN<1>")
	)
	(segment
		(start 140.572236 -274.375372)
		(end 140.512546 -274.435062)
		(width 0.088646)
		(layer "In6.Cu")
		(net "M_G_CPU1_SA_DQS_DN<1>")
	)
	(segment
		(start 186.921394 -302.649382)
		(end 185.466736 -302.649382)
		(width 0.18288)
		(layer "In6.Cu")
		(net "M_G_CPU1_SA_DQS_DN<1>")
	)
	(segment
		(start 173.313598 -296.59072)
		(end 173.06544 -296.342562)
		(width 0.18288)
		(layer "In6.Cu")
		(net "M_G_CPU1_SA_DQS_DN<1>")
	)
	(segment
		(start 176.63668 -297.192446)
		(end 176.35855 -297.470576)
		(width 0.18288)
		(layer "In6.Cu")
		(net "M_G_CPU1_SA_DQS_DN<1>")
	)
	(segment
		(start 127.068072 -272.315686)
		(end 127.060706 -272.320004)
		(width 0.088646)
		(layer "In6.Cu")
		(net "M_G_CPU1_SA_DQS_DN<1>")
	)
	(segment
		(start 129.888996 -272.96364)
		(end 129.874264 -272.955004)
		(width 0.088646)
		(layer "In6.Cu")
		(net "M_G_CPU1_SA_DQS_DN<1>")
	)
	(segment
		(start 187.256166 -302.984154)
		(end 186.921394 -302.649382)
		(width 0.18288)
		(layer "In6.Cu")
		(net "M_G_CPU1_SA_DQS_DN<1>")
	)
	(segment
		(start 138.34618 -272.963894)
		(end 138.346434 -272.963894)
		(width 0.088646)
		(layer "In6.Cu")
		(net "M_G_CPU1_SA_DQS_DN<1>")
	)
	(segment
		(start 172.536612 -296.342562)
		(end 172.256704 -296.62247)
		(width 0.18288)
		(layer "In6.Cu")
		(net "M_G_CPU1_SA_DQS_DN<1>")
	)
	(segment
		(start 140.38199 -274.435062)
		(end 138.961114 -273.014186)
		(width 0.088646)
		(layer "In6.Cu")
		(net "M_G_CPU1_SA_DQS_DN<1>")
	)
	(segment
		(start 127.452882 -272.320004)
		(end 127.443992 -272.314924)
		(width 0.088646)
		(layer "In6.Cu")
		(net "M_G_CPU1_SA_DQS_DN<1>")
	)
	(segment
		(start 128.009396 -272.96364)
		(end 128.007872 -272.962878)
		(width 0.088646)
		(layer "In6.Cu")
		(net "M_G_CPU1_SA_DQS_DN<1>")
	)
	(segment
		(start 177.165508 -297.192446)
		(end 176.63668 -297.192446)
		(width 0.18288)
		(layer "In6.Cu")
		(net "M_G_CPU1_SA_DQS_DN<1>")
	)
	(segment
		(start 127.069596 -272.314924)
		(end 127.068072 -272.315686)
		(width 0.088646)
		(layer "In6.Cu")
		(net "M_G_CPU1_SA_DQS_DN<1>")
	)
	(segment
		(start 135.527796 -272.96364)
		(end 135.513064 -272.955004)
		(width 0.088646)
		(layer "In6.Cu")
		(net "M_G_CPU1_SA_DQS_DN<1>")
	)
	(segment
		(start 185.466736 -302.649382)
		(end 183.42356 -300.606206)
		(width 0.18288)
		(layer "In6.Cu")
		(net "M_G_CPU1_SA_DQS_DN<1>")
	)
	(segment
		(start 180.791104 -299.031406)
		(end 179.886356 -299.031406)
		(width 0.18288)
		(layer "In6.Cu")
		(net "M_G_CPU1_SA_DQS_DN<1>")
	)
	(segment
		(start 164.541454 -294.027606)
		(end 164.254434 -293.740586)
		(width 0.18288)
		(layer "In6.Cu")
		(net "M_G_CPU1_SA_DQS_DN<1>")
	)
	(segment
		(start 126.886716 -272.582132)
		(end 126.829566 -272.639282)
		(width 0.088646)
		(layer "In6.Cu")
		(net "M_G_CPU1_SA_DQS_DN<1>")
	)
	(segment
		(start 131.76885 -272.96364)
		(end 131.758436 -272.957544)
		(width 0.088646)
		(layer "In6.Cu")
		(net "M_G_CPU1_SA_DQS_DN<1>")
	)
	(segment
		(start 163.829238 -293.740586)
		(end 163.505642 -294.064182)
		(width 0.18288)
		(layer "In6.Cu")
		(net "M_G_CPU1_SA_DQS_DN<1>")
	)
	(segment
		(start 168.80459 -296.62247)
		(end 167.712136 -295.530016)
		(width 0.18288)
		(layer "In6.Cu")
		(net "M_G_CPU1_SA_DQS_DN<1>")
	)
	(segment
		(start 187.883546 -302.716692)
		(end 187.616084 -302.984154)
		(width 0.18288)
		(layer "In6.Cu")
		(net "M_G_CPU1_SA_DQS_DN<1>")
	)
	(segment
		(start 147.983448 -274.752816)
		(end 142.09776 -274.752816)
		(width 0.18288)
		(layer "In6.Cu")
		(net "M_G_CPU1_SA_DQS_DN<1>")
	)
	(segment
		(start 187.616084 -302.984154)
		(end 187.256166 -302.984154)
		(width 0.18288)
		(layer "In6.Cu")
		(net "M_G_CPU1_SA_DQS_DN<1>")
	)
	(segment
		(start 138.346434 -272.963894)
		(end 138.346688 -272.96364)
		(width 0.088646)
		(layer "In6.Cu")
		(net "M_G_CPU1_SA_DQS_DN<1>")
	)
	(segment
		(start 154.209242 -289.625278)
		(end 154.209242 -280.97861)
		(width 0.18288)
		(layer "In6.Cu")
		(net "M_G_CPU1_SA_DQS_DN<1>")
	)
	(segment
		(start 133.648196 -272.96364)
		(end 133.633464 -272.955004)
		(width 0.088646)
		(layer "In6.Cu")
		(net "M_G_CPU1_SA_DQS_DN<1>")
	)
	(arc
		(start 134.962392 -272.96364)
		(mid 134.775194 -273.013783)
		(end 134.587996 -272.96364)
		(width 0.088646)
		(layer "In6.Cu")
		(net "M_G_CPU1_SA_DQS_DN<1>")
	)
	(arc
		(start 138.533886 -273.014186)
		(mid 138.436728 -273.001387)
		(end 138.34618 -272.963894)
		(width 0.088646)
		(layer "In6.Cu")
		(net "M_G_CPU1_SA_DQS_DN<1>")
	)
	(arc
		(start 134.022592 -272.96364)
		(mid 133.835394 -273.013783)
		(end 133.648196 -272.96364)
		(width 0.088646)
		(layer "In6.Cu")
		(net "M_G_CPU1_SA_DQS_DN<1>")
	)
	(arc
		(start 134.573264 -272.955004)
		(mid 134.296789 -272.887684)
		(end 134.022592 -272.96364)
		(width 0.088646)
		(layer "In6.Cu")
		(net "M_G_CPU1_SA_DQS_DN<1>")
	)
	(arc
		(start 136.841992 -272.96364)
		(mid 136.654794 -273.013783)
		(end 136.467596 -272.96364)
		(width 0.088646)
		(layer "In6.Cu")
		(net "M_G_CPU1_SA_DQS_DN<1>")
	)
	(arc
		(start 130.263392 -272.96364)
		(mid 130.076194 -273.013783)
		(end 129.888996 -272.96364)
		(width 0.088646)
		(layer "In6.Cu")
		(net "M_G_CPU1_SA_DQS_DN<1>")
	)
	(arc
		(start 131.203192 -272.96364)
		(mid 131.015994 -273.013783)
		(end 130.828796 -272.96364)
		(width 0.088646)
		(layer "In6.Cu")
		(net "M_G_CPU1_SA_DQS_DN<1>")
	)
	(arc
		(start 137.407396 -272.96364)
		(mid 137.124694 -272.887864)
		(end 136.841992 -272.96364)
		(width 0.088646)
		(layer "In6.Cu")
		(net "M_G_CPU1_SA_DQS_DN<1>")
	)
	(arc
		(start 128.934464 -272.955004)
		(mid 128.657989 -272.887684)
		(end 128.383792 -272.96364)
		(width 0.088646)
		(layer "In6.Cu")
		(net "M_G_CPU1_SA_DQS_DN<1>")
	)
	(arc
		(start 128.004316 -272.960592)
		(mid 128.003299 -272.959959)
		(end 128.002284 -272.959322)
		(width 0.088646)
		(layer "In6.Cu")
		(net "M_G_CPU1_SA_DQS_DN<1>")
	)
	(arc
		(start 136.467596 -272.96364)
		(mid 136.184894 -272.887864)
		(end 135.902192 -272.96364)
		(width 0.088646)
		(layer "In6.Cu")
		(net "M_G_CPU1_SA_DQS_DN<1>")
	)
	(arc
		(start 135.902192 -272.96364)
		(mid 135.714994 -273.013783)
		(end 135.527796 -272.96364)
		(width 0.088646)
		(layer "In6.Cu")
		(net "M_G_CPU1_SA_DQS_DN<1>")
	)
	(arc
		(start 131.758436 -272.957544)
		(mid 131.480004 -272.887698)
		(end 131.203192 -272.96364)
		(width 0.088646)
		(layer "In6.Cu")
		(net "M_G_CPU1_SA_DQS_DN<1>")
	)
	(arc
		(start 127.060706 -272.320004)
		(mid 126.944897 -272.431933)
		(end 126.886716 -272.582132)
		(width 0.088646)
		(layer "In6.Cu")
		(net "M_G_CPU1_SA_DQS_DN<1>")
	)
	(arc
		(start 127.663702 -272.48104)
		(mid 127.563655 -272.393502)
		(end 127.452882 -272.320004)
		(width 0.088646)
		(layer "In6.Cu")
		(net "M_G_CPU1_SA_DQS_DN<1>")
	)
	(arc
		(start 128.383792 -272.96364)
		(mid 128.196594 -273.013783)
		(end 128.009396 -272.96364)
		(width 0.088646)
		(layer "In6.Cu")
		(net "M_G_CPU1_SA_DQS_DN<1>")
	)
	(arc
		(start 130.814064 -272.955004)
		(mid 130.537589 -272.887684)
		(end 130.263392 -272.96364)
		(width 0.088646)
		(layer "In6.Cu")
		(net "M_G_CPU1_SA_DQS_DN<1>")
	)
	(arc
		(start 138.346688 -272.96364)
		(mid 138.070129 -272.887897)
		(end 137.791952 -272.957544)
		(width 0.088646)
		(layer "In6.Cu")
		(net "M_G_CPU1_SA_DQS_DN<1>")
	)
	(arc
		(start 129.323592 -272.96364)
		(mid 129.136394 -273.013783)
		(end 128.949196 -272.96364)
		(width 0.088646)
		(layer "In6.Cu")
		(net "M_G_CPU1_SA_DQS_DN<1>")
	)
	(arc
		(start 133.082792 -272.96364)
		(mid 132.895594 -273.013783)
		(end 132.708396 -272.96364)
		(width 0.088646)
		(layer "In6.Cu")
		(net "M_G_CPU1_SA_DQS_DN<1>")
	)
	(arc
		(start 128.002284 -272.959322)
		(mid 127.901731 -272.870432)
		(end 127.838962 -272.751804)
		(width 0.088646)
		(layer "In6.Cu")
		(net "M_G_CPU1_SA_DQS_DN<1>")
	)
	(arc
		(start 132.697982 -272.957544)
		(mid 132.419804 -272.887821)
		(end 132.143246 -272.96364)
		(width 0.088646)
		(layer "In6.Cu")
		(net "M_G_CPU1_SA_DQS_DN<1>")
	)
	(arc
		(start 127.838962 -272.751804)
		(mid 127.828498 -272.722355)
		(end 127.815594 -272.693892)
		(width 0.088646)
		(layer "In6.Cu")
		(net "M_G_CPU1_SA_DQS_DN<1>")
	)
	(arc
		(start 133.633464 -272.955004)
		(mid 133.356989 -272.887684)
		(end 133.082792 -272.96364)
		(width 0.088646)
		(layer "In6.Cu")
		(net "M_G_CPU1_SA_DQS_DN<1>")
	)
	(arc
		(start 137.773156 -272.968466)
		(mid 137.589648 -273.013744)
		(end 137.407396 -272.96364)
		(width 0.088646)
		(layer "In6.Cu")
		(net "M_G_CPU1_SA_DQS_DN<1>")
	)
	(arc
		(start 127.75819 -272.581116)
		(mid 127.751738 -272.570516)
		(end 127.743712 -272.56105)
		(width 0.088646)
		(layer "In6.Cu")
		(net "M_G_CPU1_SA_DQS_DN<1>")
	)
	(arc
		(start 135.513064 -272.955004)
		(mid 135.236589 -272.887684)
		(end 134.962392 -272.96364)
		(width 0.088646)
		(layer "In6.Cu")
		(net "M_G_CPU1_SA_DQS_DN<1>")
	)
	(arc
		(start 129.874264 -272.955004)
		(mid 129.597789 -272.887684)
		(end 129.323592 -272.96364)
		(width 0.088646)
		(layer "In6.Cu")
		(net "M_G_CPU1_SA_DQS_DN<1>")
	)
	(arc
		(start 127.443992 -272.314924)
		(mid 127.256794 -272.264781)
		(end 127.069596 -272.314924)
		(width 0.088646)
		(layer "In6.Cu")
		(net "M_G_CPU1_SA_DQS_DN<1>")
	)
	(arc
		(start 132.143246 -272.96364)
		(mid 131.956048 -273.013783)
		(end 131.76885 -272.96364)
		(width 0.088646)
		(layer "In6.Cu")
		(net "M_G_CPU1_SA_DQS_DN<1>")
	)
	(segment
		(start 195.369942 -312.307224)
		(end 195.702428 -312.307224)
		(width 0.20066)
		(layer "F.Cu")
		(net "M_G_CPU1_SA_DQS_DN<0>")
	)
	(segment
		(start 191.762126 -312.491628)
		(end 191.9097 -312.491628)
		(width 0.20066)
		(layer "F.Cu")
		(net "M_G_CPU1_SA_DQS_DN<0>")
	)
	(segment
		(start 189.818772 -312.348372)
		(end 190.55461 -312.348372)
		(width 0.20066)
		(layer "F.Cu")
		(net "M_G_CPU1_SA_DQS_DN<0>")
	)
	(segment
		(start 194.42303 -312.486294)
		(end 194.654424 -312.717688)
		(width 0.20066)
		(layer "F.Cu")
		(net "M_G_CPU1_SA_DQS_DN<0>")
	)
	(segment
		(start 190.55461 -312.348372)
		(end 190.969138 -312.7629)
		(width 0.20066)
		(layer "F.Cu")
		(net "M_G_CPU1_SA_DQS_DN<0>")
	)
	(segment
		(start 194.098926 -312.486294)
		(end 194.42303 -312.486294)
		(width 0.20066)
		(layer "F.Cu")
		(net "M_G_CPU1_SA_DQS_DN<0>")
	)
	(segment
		(start 194.093592 -312.491628)
		(end 194.098926 -312.486294)
		(width 0.1016)
		(layer "F.Cu")
		(net "M_G_CPU1_SA_DQS_DN<0>")
	)
	(segment
		(start 194.654424 -312.717688)
		(end 194.959478 -312.717688)
		(width 0.20066)
		(layer "F.Cu")
		(net "M_G_CPU1_SA_DQS_DN<0>")
	)
	(segment
		(start 195.942966 -312.066686)
		(end 196.532246 -312.066686)
		(width 0.20066)
		(layer "F.Cu")
		(net "M_G_CPU1_SA_DQS_DN<0>")
	)
	(segment
		(start 195.702428 -312.307224)
		(end 195.942966 -312.066686)
		(width 0.20066)
		(layer "F.Cu")
		(net "M_G_CPU1_SA_DQS_DN<0>")
	)
	(segment
		(start 187.883546 -312.066686)
		(end 188.988446 -312.066686)
		(width 0.20066)
		(layer "F.Cu")
		(net "M_G_CPU1_SA_DQS_DN<0>")
	)
	(segment
		(start 190.969138 -312.7629)
		(end 191.490854 -312.7629)
		(width 0.20066)
		(layer "F.Cu")
		(net "M_G_CPU1_SA_DQS_DN<0>")
	)
	(segment
		(start 191.490854 -312.7629)
		(end 191.762126 -312.491628)
		(width 0.20066)
		(layer "F.Cu")
		(net "M_G_CPU1_SA_DQS_DN<0>")
	)
	(segment
		(start 130.546348 -274.545044)
		(end 130.546348 -275.08073)
		(width 0.20066)
		(layer "F.Cu")
		(net "M_G_CPU1_SA_DQS_DN<0>")
	)
	(segment
		(start 189.537086 -312.066686)
		(end 189.818772 -312.348372)
		(width 0.20066)
		(layer "F.Cu")
		(net "M_G_CPU1_SA_DQS_DN<0>")
	)
	(segment
		(start 130.546094 -274.54479)
		(end 130.546348 -274.545044)
		(width 0.20066)
		(layer "F.Cu")
		(net "M_G_CPU1_SA_DQS_DN<0>")
	)
	(segment
		(start 191.9097 -312.491628)
		(end 191.914018 -312.491628)
		(width 0.101854)
		(layer "F.Cu")
		(net "M_G_CPU1_SA_DQS_DN<0>")
	)
	(segment
		(start 188.988446 -312.066686)
		(end 189.537086 -312.066686)
		(width 0.20066)
		(layer "F.Cu")
		(net "M_G_CPU1_SA_DQS_DN<0>")
	)
	(segment
		(start 194.959478 -312.717688)
		(end 195.369942 -312.307224)
		(width 0.20066)
		(layer "F.Cu")
		(net "M_G_CPU1_SA_DQS_DN<0>")
	)
	(segment
		(start 191.914018 -312.491628)
		(end 194.093592 -312.491628)
		(width 0.1016)
		(layer "F.Cu")
		(net "M_G_CPU1_SA_DQS_DN<0>")
	)
	(segment
		(start 170.451272 -314.278772)
		(end 169.615866 -313.443366)
		(width 0.18288)
		(layer "In4.Cu")
		(net "M_G_CPU1_SA_DQS_DN<0>")
	)
	(segment
		(start 187.619386 -312.330846)
		(end 187.31357 -312.330846)
		(width 0.18288)
		(layer "In4.Cu")
		(net "M_G_CPU1_SA_DQS_DN<0>")
	)
	(segment
		(start 135.526272 -276.218396)
		(end 135.518906 -276.214078)
		(width 0.088646)
		(layer "In4.Cu")
		(net "M_G_CPU1_SA_DQS_DN<0>")
	)
	(segment
		(start 166.16934 -312.72734)
		(end 166.101776 -312.564526)
		(width 0.18288)
		(layer "In4.Cu")
		(net "M_G_CPU1_SA_DQS_DN<0>")
	)
	(segment
		(start 132.62356 -275.398992)
		(end 132.613146 -275.405088)
		(width 0.088646)
		(layer "In4.Cu")
		(net "M_G_CPU1_SA_DQS_DN<0>")
	)
	(segment
		(start 159.276542 -309.698644)
		(end 158.890208 -309.31231)
		(width 0.18288)
		(layer "In4.Cu")
		(net "M_G_CPU1_SA_DQS_DN<0>")
	)
	(segment
		(start 171.013882 -314.841382)
		(end 171.013882 -314.66536)
		(width 0.18288)
		(layer "In4.Cu")
		(net "M_G_CPU1_SA_DQS_DN<0>")
	)
	(segment
		(start 130.35915 -275.405088)
		(end 130.35026 -275.400008)
		(width 0.088646)
		(layer "In4.Cu")
		(net "M_G_CPU1_SA_DQS_DN<0>")
	)
	(segment
		(start 168.037002 -312.949844)
		(end 166.706296 -312.949844)
		(width 0.18288)
		(layer "In4.Cu")
		(net "M_G_CPU1_SA_DQS_DN<0>")
	)
	(segment
		(start 170.627294 -314.278772)
		(end 170.451272 -314.278772)
		(width 0.18288)
		(layer "In4.Cu")
		(net "M_G_CPU1_SA_DQS_DN<0>")
	)
	(segment
		(start 172.991018 -315.042296)
		(end 172.601636 -315.042296)
		(width 0.18288)
		(layer "In4.Cu")
		(net "M_G_CPU1_SA_DQS_DN<0>")
	)
	(segment
		(start 139.520422 -278.71166)
		(end 139.004294 -278.71166)
		(width 0.088646)
		(layer "In4.Cu")
		(net "M_G_CPU1_SA_DQS_DN<0>")
	)
	(segment
		(start 171.013882 -314.66536)
		(end 170.627294 -314.278772)
		(width 0.18288)
		(layer "In4.Cu")
		(net "M_G_CPU1_SA_DQS_DN<0>")
	)
	(segment
		(start 156.56179 -308.761892)
		(end 155.32481 -307.524912)
		(width 0.18288)
		(layer "In4.Cu")
		(net "M_G_CPU1_SA_DQS_DN<0>")
	)
	(segment
		(start 178.73218 -313.588146)
		(end 177.858928 -314.461398)
		(width 0.18288)
		(layer "In4.Cu")
		(net "M_G_CPU1_SA_DQS_DN<0>")
	)
	(segment
		(start 176.6951 -314.192158)
		(end 176.431448 -314.45581)
		(width 0.18288)
		(layer "In4.Cu")
		(net "M_G_CPU1_SA_DQS_DN<0>")
	)
	(segment
		(start 131.688078 -275.396452)
		(end 131.673346 -275.405088)
		(width 0.088646)
		(layer "In4.Cu")
		(net "M_G_CPU1_SA_DQS_DN<0>")
	)
	(segment
		(start 159.276542 -309.874666)
		(end 159.276542 -309.698644)
		(width 0.18288)
		(layer "In4.Cu")
		(net "M_G_CPU1_SA_DQS_DN<0>")
	)
	(segment
		(start 136.937496 -277.032974)
		(end 136.928606 -277.027894)
		(width 0.088646)
		(layer "In4.Cu")
		(net "M_G_CPU1_SA_DQS_DN<0>")
	)
	(segment
		(start 163.48837 -312.122566)
		(end 162.48253 -311.116726)
		(width 0.18288)
		(layer "In4.Cu")
		(net "M_G_CPU1_SA_DQS_DN<0>")
	)
	(segment
		(start 173.242732 -315.29401)
		(end 172.991018 -315.042296)
		(width 0.18288)
		(layer "In4.Cu")
		(net "M_G_CPU1_SA_DQS_DN<0>")
	)
	(segment
		(start 166.101776 -312.564526)
		(end 165.597078 -312.355484)
		(width 0.18288)
		(layer "In4.Cu")
		(net "M_G_CPU1_SA_DQS_DN<0>")
	)
	(segment
		(start 187.883546 -312.066686)
		(end 187.619386 -312.330846)
		(width 0.18288)
		(layer "In4.Cu")
		(net "M_G_CPU1_SA_DQS_DN<0>")
	)
	(segment
		(start 177.357786 -314.461398)
		(end 177.088546 -314.192158)
		(width 0.18288)
		(layer "In4.Cu")
		(net "M_G_CPU1_SA_DQS_DN<0>")
	)
	(segment
		(start 176.431448 -314.45581)
		(end 174.930816 -314.45581)
		(width 0.18288)
		(layer "In4.Cu")
		(net "M_G_CPU1_SA_DQS_DN<0>")
	)
	(segment
		(start 165.434518 -312.422794)
		(end 164.709602 -312.122566)
		(width 0.18288)
		(layer "In4.Cu")
		(net "M_G_CPU1_SA_DQS_DN<0>")
	)
	(segment
		(start 161.627058 -311.116726)
		(end 160.771078 -310.260746)
		(width 0.18288)
		(layer "In4.Cu")
		(net "M_G_CPU1_SA_DQS_DN<0>")
	)
	(segment
		(start 140.158724 -279.265634)
		(end 140.142214 -279.249124)
		(width 0.088646)
		(layer "In4.Cu")
		(net "M_G_CPU1_SA_DQS_DN<0>")
	)
	(segment
		(start 162.48253 -311.116726)
		(end 161.627058 -311.116726)
		(width 0.18288)
		(layer "In4.Cu")
		(net "M_G_CPU1_SA_DQS_DN<0>")
	)
	(segment
		(start 141.596872 -280.702766)
		(end 140.158724 -279.265634)
		(width 0.18288)
		(layer "In4.Cu")
		(net "M_G_CPU1_SA_DQS_DN<0>")
	)
	(segment
		(start 187.31357 -312.330846)
		(end 187.15101 -312.168286)
		(width 0.18288)
		(layer "In4.Cu")
		(net "M_G_CPU1_SA_DQS_DN<0>")
	)
	(segment
		(start 179.858162 -313.031632)
		(end 179.301648 -313.588146)
		(width 0.18288)
		(layer "In4.Cu")
		(net "M_G_CPU1_SA_DQS_DN<0>")
	)
	(segment
		(start 172.331634 -315.312298)
		(end 171.484798 -315.312298)
		(width 0.18288)
		(layer "In4.Cu")
		(net "M_G_CPU1_SA_DQS_DN<0>")
	)
	(segment
		(start 174.092616 -315.29401)
		(end 173.242732 -315.29401)
		(width 0.18288)
		(layer "In4.Cu")
		(net "M_G_CPU1_SA_DQS_DN<0>")
	)
	(segment
		(start 142.610078 -283.148532)
		(end 141.596872 -280.702766)
		(width 0.18288)
		(layer "In4.Cu")
		(net "M_G_CPU1_SA_DQS_DN<0>")
	)
	(segment
		(start 160.771078 -310.260746)
		(end 159.662622 -310.260746)
		(width 0.18288)
		(layer "In4.Cu")
		(net "M_G_CPU1_SA_DQS_DN<0>")
	)
	(segment
		(start 148.440902 -297.222418)
		(end 142.610078 -283.148532)
		(width 0.18288)
		(layer "In4.Cu")
		(net "M_G_CPU1_SA_DQS_DN<0>")
	)
	(segment
		(start 138.62939 -278.346916)
		(end 138.629644 -278.346662)
		(width 0.088646)
		(layer "In4.Cu")
		(net "M_G_CPU1_SA_DQS_DN<0>")
	)
	(segment
		(start 130.17627 -275.13788)
		(end 130.23342 -275.08073)
		(width 0.088646)
		(layer "In4.Cu")
		(net "M_G_CPU1_SA_DQS_DN<0>")
	)
	(segment
		(start 164.709602 -312.122566)
		(end 163.48837 -312.122566)
		(width 0.18288)
		(layer "In4.Cu")
		(net "M_G_CPU1_SA_DQS_DN<0>")
	)
	(segment
		(start 133.563106 -275.398992)
		(end 133.552692 -275.405088)
		(width 0.088646)
		(layer "In4.Cu")
		(net "M_G_CPU1_SA_DQS_DN<0>")
	)
	(segment
		(start 177.858928 -314.461398)
		(end 177.357786 -314.461398)
		(width 0.18288)
		(layer "In4.Cu")
		(net "M_G_CPU1_SA_DQS_DN<0>")
	)
	(segment
		(start 138.629644 -278.336502)
		(end 138.629644 -278.31796)
		(width 0.088646)
		(layer "In4.Cu")
		(net "M_G_CPU1_SA_DQS_DN<0>")
	)
	(segment
		(start 159.662622 -310.260746)
		(end 159.276542 -309.874666)
		(width 0.18288)
		(layer "In4.Cu")
		(net "M_G_CPU1_SA_DQS_DN<0>")
	)
	(segment
		(start 134.498334 -275.401786)
		(end 134.492746 -275.405088)
		(width 0.088646)
		(layer "In4.Cu")
		(net "M_G_CPU1_SA_DQS_DN<0>")
	)
	(segment
		(start 179.301648 -313.588146)
		(end 178.73218 -313.588146)
		(width 0.18288)
		(layer "In4.Cu")
		(net "M_G_CPU1_SA_DQS_DN<0>")
	)
	(segment
		(start 172.601636 -315.042296)
		(end 172.331634 -315.312298)
		(width 0.18288)
		(layer "In4.Cu")
		(net "M_G_CPU1_SA_DQS_DN<0>")
	)
	(segment
		(start 155.32481 -307.524912)
		(end 148.440902 -297.222418)
		(width 0.18288)
		(layer "In4.Cu")
		(net "M_G_CPU1_SA_DQS_DN<0>")
	)
	(segment
		(start 137.407396 -277.84679)
		(end 137.398506 -277.84171)
		(width 0.088646)
		(layer "In4.Cu")
		(net "M_G_CPU1_SA_DQS_DN<0>")
	)
	(segment
		(start 171.484798 -315.312298)
		(end 171.013882 -314.841382)
		(width 0.18288)
		(layer "In4.Cu")
		(net "M_G_CPU1_SA_DQS_DN<0>")
	)
	(segment
		(start 180.977032 -312.907172)
		(end 180.852572 -313.031632)
		(width 0.18288)
		(layer "In4.Cu")
		(net "M_G_CPU1_SA_DQS_DN<0>")
	)
	(segment
		(start 169.615866 -313.443366)
		(end 168.530524 -313.443366)
		(width 0.18288)
		(layer "In4.Cu")
		(net "M_G_CPU1_SA_DQS_DN<0>")
	)
	(segment
		(start 130.23342 -275.08073)
		(end 130.546348 -275.08073)
		(width 0.088646)
		(layer "In4.Cu")
		(net "M_G_CPU1_SA_DQS_DN<0>")
	)
	(segment
		(start 136.750044 -276.708616)
		(end 136.750044 -276.69871)
		(width 0.088646)
		(layer "In4.Cu")
		(net "M_G_CPU1_SA_DQS_DN<0>")
	)
	(segment
		(start 168.530524 -313.443366)
		(end 168.037002 -312.949844)
		(width 0.18288)
		(layer "In4.Cu")
		(net "M_G_CPU1_SA_DQS_DN<0>")
	)
	(segment
		(start 135.340344 -275.8948)
		(end 135.340344 -275.879306)
		(width 0.088646)
		(layer "In4.Cu")
		(net "M_G_CPU1_SA_DQS_DN<0>")
	)
	(segment
		(start 180.852572 -313.031632)
		(end 179.858162 -313.031632)
		(width 0.18288)
		(layer "In4.Cu")
		(net "M_G_CPU1_SA_DQS_DN<0>")
	)
	(segment
		(start 130.748278 -275.396452)
		(end 130.733546 -275.405088)
		(width 0.088646)
		(layer "In4.Cu")
		(net "M_G_CPU1_SA_DQS_DN<0>")
	)
	(segment
		(start 158.714186 -309.31231)
		(end 158.163768 -308.761892)
		(width 0.18288)
		(layer "In4.Cu")
		(net "M_G_CPU1_SA_DQS_DN<0>")
	)
	(segment
		(start 181.523132 -312.907172)
		(end 180.977032 -312.907172)
		(width 0.18288)
		(layer "In4.Cu")
		(net "M_G_CPU1_SA_DQS_DN<0>")
	)
	(segment
		(start 187.15101 -312.168286)
		(end 184.286144 -312.168286)
		(width 0.18288)
		(layer "In4.Cu")
		(net "M_G_CPU1_SA_DQS_DN<0>")
	)
	(segment
		(start 165.597078 -312.355484)
		(end 165.434518 -312.422794)
		(width 0.18288)
		(layer "In4.Cu")
		(net "M_G_CPU1_SA_DQS_DN<0>")
	)
	(segment
		(start 177.088546 -314.192158)
		(end 176.6951 -314.192158)
		(width 0.18288)
		(layer "In4.Cu")
		(net "M_G_CPU1_SA_DQS_DN<0>")
	)
	(segment
		(start 182.201566 -313.031632)
		(end 181.647592 -313.031632)
		(width 0.18288)
		(layer "In4.Cu")
		(net "M_G_CPU1_SA_DQS_DN<0>")
	)
	(segment
		(start 140.142214 -279.249124)
		(end 140.057886 -279.249124)
		(width 0.088646)
		(layer "In4.Cu")
		(net "M_G_CPU1_SA_DQS_DN<0>")
	)
	(segment
		(start 158.890208 -309.31231)
		(end 158.714186 -309.31231)
		(width 0.18288)
		(layer "In4.Cu")
		(net "M_G_CPU1_SA_DQS_DN<0>")
	)
	(segment
		(start 184.286144 -312.168286)
		(end 182.201566 -313.031632)
		(width 0.18288)
		(layer "In4.Cu")
		(net "M_G_CPU1_SA_DQS_DN<0>")
	)
	(segment
		(start 135.527796 -276.219158)
		(end 135.526272 -276.218396)
		(width 0.088646)
		(layer "In4.Cu")
		(net "M_G_CPU1_SA_DQS_DN<0>")
	)
	(segment
		(start 166.706296 -312.949844)
		(end 166.16934 -312.72734)
		(width 0.18288)
		(layer "In4.Cu")
		(net "M_G_CPU1_SA_DQS_DN<0>")
	)
	(segment
		(start 137.219944 -277.522432)
		(end 137.219944 -277.512526)
		(width 0.088646)
		(layer "In4.Cu")
		(net "M_G_CPU1_SA_DQS_DN<0>")
	)
	(segment
		(start 174.930816 -314.45581)
		(end 174.092616 -315.29401)
		(width 0.18288)
		(layer "In4.Cu")
		(net "M_G_CPU1_SA_DQS_DN<0>")
	)
	(segment
		(start 158.163768 -308.761892)
		(end 156.56179 -308.761892)
		(width 0.18288)
		(layer "In4.Cu")
		(net "M_G_CPU1_SA_DQS_DN<0>")
	)
	(segment
		(start 181.647592 -313.031632)
		(end 181.523132 -312.907172)
		(width 0.18288)
		(layer "In4.Cu")
		(net "M_G_CPU1_SA_DQS_DN<0>")
	)
	(segment
		(start 140.057886 -279.249124)
		(end 139.520422 -278.71166)
		(width 0.088646)
		(layer "In4.Cu")
		(net "M_G_CPU1_SA_DQS_DN<0>")
	)
	(arc
		(start 136.750044 -276.69871)
		(mid 136.671933 -276.421761)
		(end 136.467596 -276.219158)
		(width 0.088646)
		(layer "In4.Cu")
		(net "M_G_CPU1_SA_DQS_DN<0>")
	)
	(arc
		(start 135.340344 -275.879306)
		(mid 135.260974 -275.605572)
		(end 135.05815 -275.405342)
		(width 0.088646)
		(layer "In4.Cu")
		(net "M_G_CPU1_SA_DQS_DN<0>")
	)
	(arc
		(start 137.398506 -277.84171)
		(mid 137.267592 -277.70535)
		(end 137.219944 -277.522432)
		(width 0.088646)
		(layer "In4.Cu")
		(net "M_G_CPU1_SA_DQS_DN<0>")
	)
	(arc
		(start 137.781792 -277.84679)
		(mid 137.594594 -277.896933)
		(end 137.407396 -277.84679)
		(width 0.088646)
		(layer "In4.Cu")
		(net "M_G_CPU1_SA_DQS_DN<0>")
	)
	(arc
		(start 139.004294 -278.71166)
		(mid 138.742726 -278.605437)
		(end 138.62939 -278.346916)
		(width 0.088646)
		(layer "In4.Cu")
		(net "M_G_CPU1_SA_DQS_DN<0>")
	)
	(arc
		(start 138.629644 -278.31796)
		(mid 138.549482 -278.045771)
		(end 138.347196 -277.84679)
		(width 0.088646)
		(layer "In4.Cu")
		(net "M_G_CPU1_SA_DQS_DN<0>")
	)
	(arc
		(start 137.219944 -277.512526)
		(mid 137.141833 -277.235577)
		(end 136.937496 -277.032974)
		(width 0.088646)
		(layer "In4.Cu")
		(net "M_G_CPU1_SA_DQS_DN<0>")
	)
	(arc
		(start 136.467596 -276.219158)
		(mid 136.184894 -276.143382)
		(end 135.902192 -276.219158)
		(width 0.088646)
		(layer "In4.Cu")
		(net "M_G_CPU1_SA_DQS_DN<0>")
	)
	(arc
		(start 135.902192 -276.219158)
		(mid 135.714994 -276.269301)
		(end 135.527796 -276.219158)
		(width 0.088646)
		(layer "In4.Cu")
		(net "M_G_CPU1_SA_DQS_DN<0>")
	)
	(arc
		(start 135.05815 -275.405342)
		(mid 134.778722 -275.32945)
		(end 134.498334 -275.401786)
		(width 0.088646)
		(layer "In4.Cu")
		(net "M_G_CPU1_SA_DQS_DN<0>")
	)
	(arc
		(start 136.928606 -277.027894)
		(mid 136.797692 -276.891534)
		(end 136.750044 -276.708616)
		(width 0.088646)
		(layer "In4.Cu")
		(net "M_G_CPU1_SA_DQS_DN<0>")
	)
	(arc
		(start 135.518906 -276.214078)
		(mid 135.387992 -276.077718)
		(end 135.340344 -275.8948)
		(width 0.088646)
		(layer "In4.Cu")
		(net "M_G_CPU1_SA_DQS_DN<0>")
	)
	(arc
		(start 138.347196 -277.84679)
		(mid 138.064494 -277.771048)
		(end 137.781792 -277.84679)
		(width 0.088646)
		(layer "In4.Cu")
		(net "M_G_CPU1_SA_DQS_DN<0>")
	)
	(arc
		(start 134.492746 -275.405088)
		(mid 134.305548 -275.455231)
		(end 134.11835 -275.405088)
		(width 0.088646)
		(layer "In4.Cu")
		(net "M_G_CPU1_SA_DQS_DN<0>")
	)
	(arc
		(start 133.178296 -275.405088)
		(mid 132.901737 -275.329379)
		(end 132.62356 -275.398992)
		(width 0.088646)
		(layer "In4.Cu")
		(net "M_G_CPU1_SA_DQS_DN<0>")
	)
	(arc
		(start 130.733546 -275.405088)
		(mid 130.546348 -275.455231)
		(end 130.35915 -275.405088)
		(width 0.088646)
		(layer "In4.Cu")
		(net "M_G_CPU1_SA_DQS_DN<0>")
	)
	(arc
		(start 131.29895 -275.405088)
		(mid 131.024721 -275.329163)
		(end 130.748278 -275.396452)
		(width 0.088646)
		(layer "In4.Cu")
		(net "M_G_CPU1_SA_DQS_DN<0>")
	)
	(arc
		(start 133.552692 -275.405088)
		(mid 133.365494 -275.455231)
		(end 133.178296 -275.405088)
		(width 0.088646)
		(layer "In4.Cu")
		(net "M_G_CPU1_SA_DQS_DN<0>")
	)
	(arc
		(start 132.23875 -275.405088)
		(mid 131.964521 -275.329163)
		(end 131.688078 -275.396452)
		(width 0.088646)
		(layer "In4.Cu")
		(net "M_G_CPU1_SA_DQS_DN<0>")
	)
	(arc
		(start 134.11835 -275.405088)
		(mid 133.841537 -275.329252)
		(end 133.563106 -275.398992)
		(width 0.088646)
		(layer "In4.Cu")
		(net "M_G_CPU1_SA_DQS_DN<0>")
	)
	(arc
		(start 131.673346 -275.405088)
		(mid 131.486148 -275.455231)
		(end 131.29895 -275.405088)
		(width 0.088646)
		(layer "In4.Cu")
		(net "M_G_CPU1_SA_DQS_DN<0>")
	)
	(arc
		(start 138.629644 -278.346662)
		(mid 138.62961 -278.341582)
		(end 138.629644 -278.336502)
		(width 0.088646)
		(layer "In4.Cu")
		(net "M_G_CPU1_SA_DQS_DN<0>")
	)
	(arc
		(start 130.35026 -275.400008)
		(mid 130.234451 -275.288079)
		(end 130.17627 -275.13788)
		(width 0.088646)
		(layer "In4.Cu")
		(net "M_G_CPU1_SA_DQS_DN<0>")
	)
	(arc
		(start 132.613146 -275.405088)
		(mid 132.425948 -275.455231)
		(end 132.23875 -275.405088)
		(width 0.088646)
		(layer "In4.Cu")
		(net "M_G_CPU1_SA_DQS_DN<0>")
	)
	(segment
		(start 194.098926 -304.835306)
		(end 194.092576 -304.841656)
		(width 0.1016)
		(layer "F.Cu")
		(net "M_G_CPU1_SA_DQ<9>")
	)
	(segment
		(start 126.786894 -272.917158)
		(end 126.786894 -273.452844)
		(width 0.20066)
		(layer "F.Cu")
		(net "M_G_CPU1_SA_DQ<9>")
	)
	(segment
		(start 194.940428 -305.266852)
		(end 194.508882 -304.835306)
		(width 0.20066)
		(layer "F.Cu")
		(net "M_G_CPU1_SA_DQ<9>")
	)
	(segment
		(start 190.509144 -305.266598)
		(end 188.988446 -305.266598)
		(width 0.20066)
		(layer "F.Cu")
		(net "M_G_CPU1_SA_DQ<9>")
	)
	(segment
		(start 190.75781 -305.515264)
		(end 190.509144 -305.266598)
		(width 0.20066)
		(layer "F.Cu")
		(net "M_G_CPU1_SA_DQ<9>")
	)
	(segment
		(start 191.903858 -304.841656)
		(end 191.883792 -304.841656)
		(width 0.101854)
		(layer "F.Cu")
		(net "M_G_CPU1_SA_DQ<9>")
	)
	(segment
		(start 194.508882 -304.835306)
		(end 194.098926 -304.835306)
		(width 0.20066)
		(layer "F.Cu")
		(net "M_G_CPU1_SA_DQ<9>")
	)
	(segment
		(start 191.233044 -305.515264)
		(end 190.75781 -305.515264)
		(width 0.20066)
		(layer "F.Cu")
		(net "M_G_CPU1_SA_DQ<9>")
	)
	(segment
		(start 188.988446 -305.266598)
		(end 187.883546 -305.266598)
		(width 0.20066)
		(layer "F.Cu")
		(net "M_G_CPU1_SA_DQ<9>")
	)
	(segment
		(start 191.421004 -305.327304)
		(end 191.233044 -305.515264)
		(width 0.20066)
		(layer "F.Cu")
		(net "M_G_CPU1_SA_DQ<9>")
	)
	(segment
		(start 196.532246 -305.266598)
		(end 196.531992 -305.266852)
		(width 0.20066)
		(layer "F.Cu")
		(net "M_G_CPU1_SA_DQ<9>")
	)
	(segment
		(start 191.539114 -304.841656)
		(end 191.421004 -304.959766)
		(width 0.20066)
		(layer "F.Cu")
		(net "M_G_CPU1_SA_DQ<9>")
	)
	(segment
		(start 191.421004 -304.959766)
		(end 191.421004 -305.327304)
		(width 0.20066)
		(layer "F.Cu")
		(net "M_G_CPU1_SA_DQ<9>")
	)
	(segment
		(start 126.786894 -273.452844)
		(end 126.787148 -273.453098)
		(width 0.20066)
		(layer "F.Cu")
		(net "M_G_CPU1_SA_DQ<9>")
	)
	(segment
		(start 194.092576 -304.841656)
		(end 191.903858 -304.841656)
		(width 0.1016)
		(layer "F.Cu")
		(net "M_G_CPU1_SA_DQ<9>")
	)
	(segment
		(start 196.531992 -305.266852)
		(end 194.940428 -305.266852)
		(width 0.20066)
		(layer "F.Cu")
		(net "M_G_CPU1_SA_DQ<9>")
	)
	(segment
		(start 191.883792 -304.841656)
		(end 191.539114 -304.841656)
		(width 0.20066)
		(layer "F.Cu")
		(net "M_G_CPU1_SA_DQ<9>")
	)
	(segment
		(start 180.807106 -301.325026)
		(end 180.103526 -301.325026)
		(width 0.18288)
		(layer "In6.Cu")
		(net "M_G_CPU1_SA_DQ<9>")
	)
	(segment
		(start 162.31489 -295.463722)
		(end 161.24428 -295.463722)
		(width 0.18288)
		(layer "In6.Cu")
		(net "M_G_CPU1_SA_DQ<9>")
	)
	(segment
		(start 183.431434 -303.21758)
		(end 183.172862 -303.21758)
		(width 0.18288)
		(layer "In6.Cu")
		(net "M_G_CPU1_SA_DQ<9>")
	)
	(segment
		(start 182.682388 -302.468534)
		(end 182.516526 -302.302672)
		(width 0.18288)
		(layer "In6.Cu")
		(net "M_G_CPU1_SA_DQ<9>")
	)
	(segment
		(start 128.949196 -273.942556)
		(end 128.904492 -273.968464)
		(width 0.088646)
		(layer "In6.Cu")
		(net "M_G_CPU1_SA_DQ<9>")
	)
	(segment
		(start 176.465738 -299.742098)
		(end 176.156112 -299.432472)
		(width 0.18288)
		(layer "In6.Cu")
		(net "M_G_CPU1_SA_DQ<9>")
	)
	(segment
		(start 140.208762 -275.687536)
		(end 140.004038 -275.482812)
		(width 0.18288)
		(layer "In6.Cu")
		(net "M_G_CPU1_SA_DQ<9>")
	)
	(segment
		(start 161.24428 -295.463722)
		(end 160.356042 -294.575484)
		(width 0.18288)
		(layer "In6.Cu")
		(net "M_G_CPU1_SA_DQ<9>")
	)
	(segment
		(start 166.566088 -297.62958)
		(end 166.281608 -297.3451)
		(width 0.18288)
		(layer "In6.Cu")
		(net "M_G_CPU1_SA_DQ<9>")
	)
	(segment
		(start 159.032448 -295.135046)
		(end 158.659068 -295.135046)
		(width 0.18288)
		(layer "In6.Cu")
		(net "M_G_CPU1_SA_DQ<9>")
	)
	(segment
		(start 176.156112 -299.432472)
		(end 175.772318 -299.432472)
		(width 0.18288)
		(layer "In6.Cu")
		(net "M_G_CPU1_SA_DQ<9>")
	)
	(segment
		(start 171.886626 -298.734226)
		(end 170.995086 -298.734226)
		(width 0.18288)
		(layer "In6.Cu")
		(net "M_G_CPU1_SA_DQ<9>")
	)
	(segment
		(start 128.28397 -273.836892)
		(end 127.713486 -273.836892)
		(width 0.088646)
		(layer "In6.Cu")
		(net "M_G_CPU1_SA_DQ<9>")
	)
	(segment
		(start 178.088798 -299.742098)
		(end 176.465738 -299.742098)
		(width 0.18288)
		(layer "In6.Cu")
		(net "M_G_CPU1_SA_DQ<9>")
	)
	(segment
		(start 170.675046 -299.407072)
		(end 170.301666 -299.407072)
		(width 0.18288)
		(layer "In6.Cu")
		(net "M_G_CPU1_SA_DQ<9>")
	)
	(segment
		(start 168.737026 -298.734226)
		(end 168.000426 -297.997626)
		(width 0.18288)
		(layer "In6.Cu")
		(net "M_G_CPU1_SA_DQ<9>")
	)
	(segment
		(start 178.761644 -300.414944)
		(end 178.088798 -299.742098)
		(width 0.18288)
		(layer "In6.Cu")
		(net "M_G_CPU1_SA_DQ<9>")
	)
	(segment
		(start 138.967464 -273.89201)
		(end 138.534394 -273.89201)
		(width 0.088646)
		(layer "In6.Cu")
		(net "M_G_CPU1_SA_DQ<9>")
	)
	(segment
		(start 139.894818 -275.373592)
		(end 139.894818 -274.819364)
		(width 0.088646)
		(layer "In6.Cu")
		(net "M_G_CPU1_SA_DQ<9>")
	)
	(segment
		(start 159.192468 -294.975026)
		(end 159.032448 -295.135046)
		(width 0.18288)
		(layer "In6.Cu")
		(net "M_G_CPU1_SA_DQ<9>")
	)
	(segment
		(start 170.141646 -298.894246)
		(end 169.981626 -298.734226)
		(width 0.18288)
		(layer "In6.Cu")
		(net "M_G_CPU1_SA_DQ<9>")
	)
	(segment
		(start 160.356042 -294.575484)
		(end 159.352488 -294.575484)
		(width 0.18288)
		(layer "In6.Cu")
		(net "M_G_CPU1_SA_DQ<9>")
	)
	(segment
		(start 147.442174 -276.058376)
		(end 141.837664 -276.058376)
		(width 0.18288)
		(layer "In6.Cu")
		(net "M_G_CPU1_SA_DQ<9>")
	)
	(segment
		(start 170.835066 -298.894246)
		(end 170.835066 -299.247052)
		(width 0.18288)
		(layer "In6.Cu")
		(net "M_G_CPU1_SA_DQ<9>")
	)
	(segment
		(start 163.946078 -296.65549)
		(end 163.723828 -296.43324)
		(width 0.18288)
		(layer "In6.Cu")
		(net "M_G_CPU1_SA_DQ<9>")
	)
	(segment
		(start 134.587996 -273.942556)
		(end 134.573264 -273.951192)
		(width 0.088646)
		(layer "In6.Cu")
		(net "M_G_CPU1_SA_DQ<9>")
	)
	(segment
		(start 180.103526 -301.325026)
		(end 179.193444 -300.414944)
		(width 0.18288)
		(layer "In6.Cu")
		(net "M_G_CPU1_SA_DQ<9>")
	)
	(segment
		(start 152.903682 -290.344606)
		(end 152.903682 -281.521154)
		(width 0.18288)
		(layer "In6.Cu")
		(net "M_G_CPU1_SA_DQ<9>")
	)
	(segment
		(start 158.499048 -294.735504)
		(end 158.339028 -294.575484)
		(width 0.18288)
		(layer "In6.Cu")
		(net "M_G_CPU1_SA_DQ<9>")
	)
	(segment
		(start 130.269488 -273.946112)
		(end 130.263646 -273.942556)
		(width 0.088646)
		(layer "In6.Cu")
		(net "M_G_CPU1_SA_DQ<9>")
	)
	(segment
		(start 168.000426 -297.997626)
		(end 167.346122 -297.997626)
		(width 0.18288)
		(layer "In6.Cu")
		(net "M_G_CPU1_SA_DQ<9>")
	)
	(segment
		(start 157.13456 -294.575484)
		(end 152.903682 -290.344606)
		(width 0.18288)
		(layer "In6.Cu")
		(net "M_G_CPU1_SA_DQ<9>")
	)
	(segment
		(start 174.643542 -299.742098)
		(end 173.793658 -298.892214)
		(width 0.18288)
		(layer "In6.Cu")
		(net "M_G_CPU1_SA_DQ<9>")
	)
	(segment
		(start 128.451102 -273.908774)
		(end 128.44653 -273.904202)
		(width 0.088646)
		(layer "In6.Cu")
		(net "M_G_CPU1_SA_DQ<9>")
	)
	(segment
		(start 141.837664 -276.058376)
		(end 140.942314 -275.687536)
		(width 0.18288)
		(layer "In6.Cu")
		(net "M_G_CPU1_SA_DQ<9>")
	)
	(segment
		(start 159.352488 -294.575484)
		(end 159.192468 -294.735504)
		(width 0.18288)
		(layer "In6.Cu")
		(net "M_G_CPU1_SA_DQ<9>")
	)
	(segment
		(start 167.346122 -297.997626)
		(end 166.978076 -297.62958)
		(width 0.18288)
		(layer "In6.Cu")
		(net "M_G_CPU1_SA_DQ<9>")
	)
	(segment
		(start 187.883546 -305.266598)
		(end 187.422028 -304.80508)
		(width 0.18288)
		(layer "In6.Cu")
		(net "M_G_CPU1_SA_DQ<9>")
	)
	(segment
		(start 129.329688 -273.946112)
		(end 129.323846 -273.942556)
		(width 0.088646)
		(layer "In6.Cu")
		(net "M_G_CPU1_SA_DQ<9>")
	)
	(segment
		(start 182.519574 -302.890174)
		(end 182.682388 -302.727106)
		(width 0.18288)
		(layer "In6.Cu")
		(net "M_G_CPU1_SA_DQ<9>")
	)
	(segment
		(start 135.527796 -273.942556)
		(end 135.513064 -273.951192)
		(width 0.088646)
		(layer "In6.Cu")
		(net "M_G_CPU1_SA_DQ<9>")
	)
	(segment
		(start 183.172862 -303.21758)
		(end 183.009794 -303.380648)
		(width 0.18288)
		(layer "In6.Cu")
		(net "M_G_CPU1_SA_DQ<9>")
	)
	(segment
		(start 163.284408 -296.43324)
		(end 162.31489 -295.463722)
		(width 0.18288)
		(layer "In6.Cu")
		(net "M_G_CPU1_SA_DQ<9>")
	)
	(segment
		(start 159.192468 -294.735504)
		(end 159.192468 -294.975026)
		(width 0.18288)
		(layer "In6.Cu")
		(net "M_G_CPU1_SA_DQ<9>")
	)
	(segment
		(start 172.044614 -298.892214)
		(end 171.886626 -298.734226)
		(width 0.18288)
		(layer "In6.Cu")
		(net "M_G_CPU1_SA_DQ<9>")
	)
	(segment
		(start 158.659068 -295.135046)
		(end 158.499048 -294.975026)
		(width 0.18288)
		(layer "In6.Cu")
		(net "M_G_CPU1_SA_DQ<9>")
	)
	(segment
		(start 184.33288 -304.119026)
		(end 183.431434 -303.21758)
		(width 0.18288)
		(layer "In6.Cu")
		(net "M_G_CPU1_SA_DQ<9>")
	)
	(segment
		(start 133.648196 -273.942556)
		(end 133.637782 -273.948652)
		(width 0.088646)
		(layer "In6.Cu")
		(net "M_G_CPU1_SA_DQ<9>")
	)
	(segment
		(start 158.339028 -294.575484)
		(end 157.13456 -294.575484)
		(width 0.18288)
		(layer "In6.Cu")
		(net "M_G_CPU1_SA_DQ<9>")
	)
	(segment
		(start 179.193444 -300.414944)
		(end 178.761644 -300.414944)
		(width 0.18288)
		(layer "In6.Cu")
		(net "M_G_CPU1_SA_DQ<9>")
	)
	(segment
		(start 140.942314 -275.687536)
		(end 140.208762 -275.687536)
		(width 0.18288)
		(layer "In6.Cu")
		(net "M_G_CPU1_SA_DQ<9>")
	)
	(segment
		(start 175.772318 -299.432472)
		(end 175.462692 -299.742098)
		(width 0.18288)
		(layer "In6.Cu")
		(net "M_G_CPU1_SA_DQ<9>")
	)
	(segment
		(start 170.141646 -299.247052)
		(end 170.141646 -298.894246)
		(width 0.18288)
		(layer "In6.Cu")
		(net "M_G_CPU1_SA_DQ<9>")
	)
	(segment
		(start 166.281608 -297.3451)
		(end 166.281608 -296.933112)
		(width 0.18288)
		(layer "In6.Cu")
		(net "M_G_CPU1_SA_DQ<9>")
	)
	(segment
		(start 164.326062 -296.65549)
		(end 163.946078 -296.65549)
		(width 0.18288)
		(layer "In6.Cu")
		(net "M_G_CPU1_SA_DQ<9>")
	)
	(segment
		(start 185.513472 -304.119026)
		(end 184.33288 -304.119026)
		(width 0.18288)
		(layer "In6.Cu")
		(net "M_G_CPU1_SA_DQ<9>")
	)
	(segment
		(start 182.751476 -303.380648)
		(end 182.519574 -303.148746)
		(width 0.18288)
		(layer "In6.Cu")
		(net "M_G_CPU1_SA_DQ<9>")
	)
	(segment
		(start 152.903682 -281.521154)
		(end 147.442174 -276.058376)
		(width 0.18288)
		(layer "In6.Cu")
		(net "M_G_CPU1_SA_DQ<9>")
	)
	(segment
		(start 158.499048 -294.975026)
		(end 158.499048 -294.735504)
		(width 0.18288)
		(layer "In6.Cu")
		(net "M_G_CPU1_SA_DQ<9>")
	)
	(segment
		(start 175.462692 -299.742098)
		(end 174.643542 -299.742098)
		(width 0.18288)
		(layer "In6.Cu")
		(net "M_G_CPU1_SA_DQ<9>")
	)
	(segment
		(start 131.768596 -273.942556)
		(end 131.753864 -273.951192)
		(width 0.088646)
		(layer "In6.Cu")
		(net "M_G_CPU1_SA_DQ<9>")
	)
	(segment
		(start 130.263646 -273.942556)
		(end 130.257804 -273.939254)
		(width 0.088646)
		(layer "In6.Cu")
		(net "M_G_CPU1_SA_DQ<9>")
	)
	(segment
		(start 182.519574 -303.148746)
		(end 182.519574 -302.890174)
		(width 0.18288)
		(layer "In6.Cu")
		(net "M_G_CPU1_SA_DQ<9>")
	)
	(segment
		(start 182.516526 -302.302672)
		(end 181.784752 -302.302672)
		(width 0.18288)
		(layer "In6.Cu")
		(net "M_G_CPU1_SA_DQ<9>")
	)
	(segment
		(start 164.639498 -296.342054)
		(end 164.326062 -296.65549)
		(width 0.18288)
		(layer "In6.Cu")
		(net "M_G_CPU1_SA_DQ<9>")
	)
	(segment
		(start 187.422028 -304.80508)
		(end 186.199526 -304.80508)
		(width 0.18288)
		(layer "In6.Cu")
		(net "M_G_CPU1_SA_DQ<9>")
	)
	(segment
		(start 129.323846 -273.942556)
		(end 129.318004 -273.939254)
		(width 0.088646)
		(layer "In6.Cu")
		(net "M_G_CPU1_SA_DQ<9>")
	)
	(segment
		(start 163.723828 -296.43324)
		(end 163.284408 -296.43324)
		(width 0.18288)
		(layer "In6.Cu")
		(net "M_G_CPU1_SA_DQ<9>")
	)
	(segment
		(start 170.995086 -298.734226)
		(end 170.835066 -298.894246)
		(width 0.18288)
		(layer "In6.Cu")
		(net "M_G_CPU1_SA_DQ<9>")
	)
	(segment
		(start 166.978076 -297.62958)
		(end 166.566088 -297.62958)
		(width 0.18288)
		(layer "In6.Cu")
		(net "M_G_CPU1_SA_DQ<9>")
	)
	(segment
		(start 169.981626 -298.734226)
		(end 168.737026 -298.734226)
		(width 0.18288)
		(layer "In6.Cu")
		(net "M_G_CPU1_SA_DQ<9>")
	)
	(segment
		(start 186.199526 -304.80508)
		(end 185.513472 -304.119026)
		(width 0.18288)
		(layer "In6.Cu")
		(net "M_G_CPU1_SA_DQ<9>")
	)
	(segment
		(start 132.70865 -273.942556)
		(end 132.698236 -273.948652)
		(width 0.088646)
		(layer "In6.Cu")
		(net "M_G_CPU1_SA_DQ<9>")
	)
	(segment
		(start 182.682388 -302.727106)
		(end 182.682388 -302.468534)
		(width 0.18288)
		(layer "In6.Cu")
		(net "M_G_CPU1_SA_DQ<9>")
	)
	(segment
		(start 170.835066 -299.247052)
		(end 170.675046 -299.407072)
		(width 0.18288)
		(layer "In6.Cu")
		(net "M_G_CPU1_SA_DQ<9>")
	)
	(segment
		(start 170.301666 -299.407072)
		(end 170.141646 -299.247052)
		(width 0.18288)
		(layer "In6.Cu")
		(net "M_G_CPU1_SA_DQ<9>")
	)
	(segment
		(start 181.784752 -302.302672)
		(end 180.807106 -301.325026)
		(width 0.18288)
		(layer "In6.Cu")
		(net "M_G_CPU1_SA_DQ<9>")
	)
	(segment
		(start 165.69055 -296.342054)
		(end 164.639498 -296.342054)
		(width 0.18288)
		(layer "In6.Cu")
		(net "M_G_CPU1_SA_DQ<9>")
	)
	(segment
		(start 173.793658 -298.892214)
		(end 172.044614 -298.892214)
		(width 0.18288)
		(layer "In6.Cu")
		(net "M_G_CPU1_SA_DQ<9>")
	)
	(segment
		(start 139.894818 -274.819364)
		(end 138.967464 -273.89201)
		(width 0.088646)
		(layer "In6.Cu")
		(net "M_G_CPU1_SA_DQ<9>")
	)
	(segment
		(start 183.009794 -303.380648)
		(end 182.751476 -303.380648)
		(width 0.18288)
		(layer "In6.Cu")
		(net "M_G_CPU1_SA_DQ<9>")
	)
	(segment
		(start 140.004038 -275.482812)
		(end 139.894818 -275.373592)
		(width 0.088646)
		(layer "In6.Cu")
		(net "M_G_CPU1_SA_DQ<9>")
	)
	(segment
		(start 166.281608 -296.933112)
		(end 165.69055 -296.342054)
		(width 0.18288)
		(layer "In6.Cu")
		(net "M_G_CPU1_SA_DQ<9>")
	)
	(arc
		(start 134.022592 -273.942556)
		(mid 133.835394 -273.892413)
		(end 133.648196 -273.942556)
		(width 0.088646)
		(layer "In6.Cu")
		(net "M_G_CPU1_SA_DQ<9>")
	)
	(arc
		(start 134.962392 -273.942556)
		(mid 134.775194 -273.892413)
		(end 134.587996 -273.942556)
		(width 0.088646)
		(layer "In6.Cu")
		(net "M_G_CPU1_SA_DQ<9>")
	)
	(arc
		(start 130.257804 -273.939254)
		(mid 130.072949 -273.892304)
		(end 129.888996 -273.942556)
		(width 0.088646)
		(layer "In6.Cu")
		(net "M_G_CPU1_SA_DQ<9>")
	)
	(arc
		(start 127.713486 -273.836892)
		(mid 127.212134 -273.737149)
		(end 126.787148 -273.453098)
		(width 0.088646)
		(layer "In6.Cu")
		(net "M_G_CPU1_SA_DQ<9>")
	)
	(arc
		(start 129.318004 -273.939254)
		(mid 129.133149 -273.892304)
		(end 128.949196 -273.942556)
		(width 0.088646)
		(layer "In6.Cu")
		(net "M_G_CPU1_SA_DQ<9>")
	)
	(arc
		(start 132.698236 -273.948652)
		(mid 132.419804 -274.018498)
		(end 132.142992 -273.942556)
		(width 0.088646)
		(layer "In6.Cu")
		(net "M_G_CPU1_SA_DQ<9>")
	)
	(arc
		(start 129.888996 -273.942556)
		(mid 129.609822 -274.018321)
		(end 129.329688 -273.946112)
		(width 0.088646)
		(layer "In6.Cu")
		(net "M_G_CPU1_SA_DQ<9>")
	)
	(arc
		(start 135.902192 -273.942556)
		(mid 135.714994 -273.892413)
		(end 135.527796 -273.942556)
		(width 0.088646)
		(layer "In6.Cu")
		(net "M_G_CPU1_SA_DQ<9>")
	)
	(arc
		(start 136.467596 -273.942556)
		(mid 136.184894 -274.018332)
		(end 135.902192 -273.942556)
		(width 0.088646)
		(layer "In6.Cu")
		(net "M_G_CPU1_SA_DQ<9>")
	)
	(arc
		(start 131.753864 -273.951192)
		(mid 131.477389 -274.018512)
		(end 131.203192 -273.942556)
		(width 0.088646)
		(layer "In6.Cu")
		(net "M_G_CPU1_SA_DQ<9>")
	)
	(arc
		(start 134.573264 -273.951192)
		(mid 134.296789 -274.018512)
		(end 134.022592 -273.942556)
		(width 0.088646)
		(layer "In6.Cu")
		(net "M_G_CPU1_SA_DQ<9>")
	)
	(arc
		(start 136.841992 -273.942556)
		(mid 136.654794 -273.892413)
		(end 136.467596 -273.942556)
		(width 0.088646)
		(layer "In6.Cu")
		(net "M_G_CPU1_SA_DQ<9>")
	)
	(arc
		(start 138.347196 -273.942556)
		(mid 138.064494 -274.018332)
		(end 137.781792 -273.942556)
		(width 0.088646)
		(layer "In6.Cu")
		(net "M_G_CPU1_SA_DQ<9>")
	)
	(arc
		(start 128.904492 -273.968464)
		(mid 128.667695 -274.015536)
		(end 128.451102 -273.908774)
		(width 0.088646)
		(layer "In6.Cu")
		(net "M_G_CPU1_SA_DQ<9>")
	)
	(arc
		(start 135.513064 -273.951192)
		(mid 135.236589 -274.018512)
		(end 134.962392 -273.942556)
		(width 0.088646)
		(layer "In6.Cu")
		(net "M_G_CPU1_SA_DQ<9>")
	)
	(arc
		(start 138.534394 -273.89201)
		(mid 138.437466 -273.904961)
		(end 138.347196 -273.942556)
		(width 0.088646)
		(layer "In6.Cu")
		(net "M_G_CPU1_SA_DQ<9>")
	)
	(arc
		(start 132.142992 -273.942556)
		(mid 131.955794 -273.892413)
		(end 131.768596 -273.942556)
		(width 0.088646)
		(layer "In6.Cu")
		(net "M_G_CPU1_SA_DQ<9>")
	)
	(arc
		(start 130.828796 -273.942556)
		(mid 130.549622 -274.018321)
		(end 130.269488 -273.946112)
		(width 0.088646)
		(layer "In6.Cu")
		(net "M_G_CPU1_SA_DQ<9>")
	)
	(arc
		(start 137.407396 -273.942556)
		(mid 137.124694 -274.018332)
		(end 136.841992 -273.942556)
		(width 0.088646)
		(layer "In6.Cu")
		(net "M_G_CPU1_SA_DQ<9>")
	)
	(arc
		(start 128.44653 -273.904202)
		(mid 128.371947 -273.854367)
		(end 128.28397 -273.836892)
		(width 0.088646)
		(layer "In6.Cu")
		(net "M_G_CPU1_SA_DQ<9>")
	)
	(arc
		(start 137.781792 -273.942556)
		(mid 137.594594 -273.892413)
		(end 137.407396 -273.942556)
		(width 0.088646)
		(layer "In6.Cu")
		(net "M_G_CPU1_SA_DQ<9>")
	)
	(arc
		(start 133.637782 -273.948652)
		(mid 133.359604 -274.018375)
		(end 133.083046 -273.942556)
		(width 0.088646)
		(layer "In6.Cu")
		(net "M_G_CPU1_SA_DQ<9>")
	)
	(arc
		(start 133.083046 -273.942556)
		(mid 132.895848 -273.892413)
		(end 132.70865 -273.942556)
		(width 0.088646)
		(layer "In6.Cu")
		(net "M_G_CPU1_SA_DQ<9>")
	)
	(arc
		(start 131.203192 -273.942556)
		(mid 131.015994 -273.892413)
		(end 130.828796 -273.942556)
		(width 0.088646)
		(layer "In6.Cu")
		(net "M_G_CPU1_SA_DQ<9>")
	)
	(segment
		(start 190.75781 -307.215286)
		(end 190.509144 -306.96662)
		(width 0.20066)
		(layer "F.Cu")
		(net "M_G_CPU1_SA_DQ<8>")
	)
	(segment
		(start 190.509144 -306.96662)
		(end 188.988446 -306.96662)
		(width 0.20066)
		(layer "F.Cu")
		(net "M_G_CPU1_SA_DQ<8>")
	)
	(segment
		(start 127.257048 -274.26666)
		(end 127.256794 -274.266914)
		(width 0.20066)
		(layer "F.Cu")
		(net "M_G_CPU1_SA_DQ<8>")
	)
	(segment
		(start 196.532246 -306.96662)
		(end 196.531992 -306.966874)
		(width 0.20066)
		(layer "F.Cu")
		(net "M_G_CPU1_SA_DQ<8>")
	)
	(segment
		(start 191.539114 -306.541678)
		(end 191.421004 -306.659788)
		(width 0.20066)
		(layer "F.Cu")
		(net "M_G_CPU1_SA_DQ<8>")
	)
	(segment
		(start 191.421004 -306.659788)
		(end 191.421004 -307.027326)
		(width 0.20066)
		(layer "F.Cu")
		(net "M_G_CPU1_SA_DQ<8>")
	)
	(segment
		(start 191.421004 -307.027326)
		(end 191.233044 -307.215286)
		(width 0.20066)
		(layer "F.Cu")
		(net "M_G_CPU1_SA_DQ<8>")
	)
	(segment
		(start 127.257048 -273.730974)
		(end 127.257048 -274.26666)
		(width 0.20066)
		(layer "F.Cu")
		(net "M_G_CPU1_SA_DQ<8>")
	)
	(segment
		(start 196.531992 -306.966874)
		(end 194.940428 -306.966874)
		(width 0.20066)
		(layer "F.Cu")
		(net "M_G_CPU1_SA_DQ<8>")
	)
	(segment
		(start 191.930782 -306.541678)
		(end 191.883792 -306.541678)
		(width 0.101854)
		(layer "F.Cu")
		(net "M_G_CPU1_SA_DQ<8>")
	)
	(segment
		(start 188.988446 -306.96662)
		(end 187.883546 -306.96662)
		(width 0.20066)
		(layer "F.Cu")
		(net "M_G_CPU1_SA_DQ<8>")
	)
	(segment
		(start 194.508882 -306.535328)
		(end 194.098926 -306.535328)
		(width 0.20066)
		(layer "F.Cu")
		(net "M_G_CPU1_SA_DQ<8>")
	)
	(segment
		(start 191.883792 -306.541678)
		(end 191.539114 -306.541678)
		(width 0.20066)
		(layer "F.Cu")
		(net "M_G_CPU1_SA_DQ<8>")
	)
	(segment
		(start 194.092576 -306.541678)
		(end 191.930782 -306.541678)
		(width 0.1016)
		(layer "F.Cu")
		(net "M_G_CPU1_SA_DQ<8>")
	)
	(segment
		(start 194.940428 -306.966874)
		(end 194.508882 -306.535328)
		(width 0.20066)
		(layer "F.Cu")
		(net "M_G_CPU1_SA_DQ<8>")
	)
	(segment
		(start 194.098926 -306.535328)
		(end 194.092576 -306.541678)
		(width 0.1016)
		(layer "F.Cu")
		(net "M_G_CPU1_SA_DQ<8>")
	)
	(segment
		(start 191.233044 -307.215286)
		(end 190.75781 -307.215286)
		(width 0.20066)
		(layer "F.Cu")
		(net "M_G_CPU1_SA_DQ<8>")
	)
	(segment
		(start 169.036238 -300.59249)
		(end 168.092374 -299.648626)
		(width 0.18288)
		(layer "In6.Cu")
		(net "M_G_CPU1_SA_DQ<8>")
	)
	(segment
		(start 164.542978 -298.200826)
		(end 164.542978 -298.4627)
		(width 0.18288)
		(layer "In6.Cu")
		(net "M_G_CPU1_SA_DQ<8>")
	)
	(segment
		(start 167.089074 -299.648626)
		(end 165.481254 -298.040806)
		(width 0.18288)
		(layer "In6.Cu")
		(net "M_G_CPU1_SA_DQ<8>")
	)
	(segment
		(start 139.788138 -276.725888)
		(end 139.788138 -276.405594)
		(width 0.088646)
		(layer "In6.Cu")
		(net "M_G_CPU1_SA_DQ<8>")
	)
	(segment
		(start 183.85028 -305.280568)
		(end 183.552338 -304.982626)
		(width 0.18288)
		(layer "In6.Cu")
		(net "M_G_CPU1_SA_DQ<8>")
	)
	(segment
		(start 164.702998 -298.040806)
		(end 164.542978 -298.200826)
		(width 0.18288)
		(layer "In6.Cu")
		(net "M_G_CPU1_SA_DQ<8>")
	)
	(segment
		(start 181.768496 -304.688748)
		(end 181.488842 -304.409094)
		(width 0.18288)
		(layer "In6.Cu")
		(net "M_G_CPU1_SA_DQ<8>")
	)
	(segment
		(start 133.563106 -274.762468)
		(end 133.552692 -274.756372)
		(width 0.088646)
		(layer "In6.Cu")
		(net "M_G_CPU1_SA_DQ<8>")
	)
	(segment
		(start 187.33135 -306.414424)
		(end 184.984136 -306.414424)
		(width 0.18288)
		(layer "In6.Cu")
		(net "M_G_CPU1_SA_DQ<8>")
	)
	(segment
		(start 176.113186 -302.14824)
		(end 175.739806 -302.14824)
		(width 0.18288)
		(layer "In6.Cu")
		(net "M_G_CPU1_SA_DQ<8>")
	)
	(segment
		(start 171.050966 -301.330106)
		(end 170.890946 -301.490126)
		(width 0.18288)
		(layer "In6.Cu")
		(net "M_G_CPU1_SA_DQ<8>")
	)
	(segment
		(start 170.357546 -300.75251)
		(end 170.197526 -300.59249)
		(width 0.18288)
		(layer "In6.Cu")
		(net "M_G_CPU1_SA_DQ<8>")
	)
	(segment
		(start 174.348902 -301.442374)
		(end 173.499018 -300.59249)
		(width 0.18288)
		(layer "In6.Cu")
		(net "M_G_CPU1_SA_DQ<8>")
	)
	(segment
		(start 127.569468 -274.266914)
		(end 127.256794 -274.266914)
		(width 0.088646)
		(layer "In6.Cu")
		(net "M_G_CPU1_SA_DQ<8>")
	)
	(segment
		(start 180.997606 -303.722278)
		(end 180.764942 -303.954942)
		(width 0.18288)
		(layer "In6.Cu")
		(net "M_G_CPU1_SA_DQ<8>")
	)
	(segment
		(start 184.233566 -306.136802)
		(end 183.974994 -306.136802)
		(width 0.18288)
		(layer "In6.Cu")
		(net "M_G_CPU1_SA_DQ<8>")
	)
	(segment
		(start 170.197526 -300.59249)
		(end 169.036238 -300.59249)
		(width 0.18288)
		(layer "In6.Cu")
		(net "M_G_CPU1_SA_DQ<8>")
	)
	(segment
		(start 180.274468 -303.690528)
		(end 180.274468 -303.464468)
		(width 0.18288)
		(layer "In6.Cu")
		(net "M_G_CPU1_SA_DQ<8>")
	)
	(segment
		(start 127.914146 -274.756372)
		(end 127.90805 -274.752816)
		(width 0.088646)
		(layer "In6.Cu")
		(net "M_G_CPU1_SA_DQ<8>")
	)
	(segment
		(start 127.928878 -274.765008)
		(end 127.914146 -274.756372)
		(width 0.088646)
		(layer "In6.Cu")
		(net "M_G_CPU1_SA_DQ<8>")
	)
	(segment
		(start 181.488842 -303.987454)
		(end 181.223666 -303.722278)
		(width 0.18288)
		(layer "In6.Cu")
		(net "M_G_CPU1_SA_DQ<8>")
	)
	(segment
		(start 170.357546 -301.330106)
		(end 170.357546 -300.75251)
		(width 0.18288)
		(layer "In6.Cu")
		(net "M_G_CPU1_SA_DQ<8>")
	)
	(segment
		(start 180.274468 -303.464468)
		(end 180.507132 -303.231804)
		(width 0.18288)
		(layer "In6.Cu")
		(net "M_G_CPU1_SA_DQ<8>")
	)
	(segment
		(start 163.689538 -298.040806)
		(end 163.339526 -298.040806)
		(width 0.18288)
		(layer "In6.Cu")
		(net "M_G_CPU1_SA_DQ<8>")
	)
	(segment
		(start 127.635254 -274.3327)
		(end 127.569468 -274.266914)
		(width 0.088646)
		(layer "In6.Cu")
		(net "M_G_CPU1_SA_DQ<8>")
	)
	(segment
		(start 180.338222 -302.836834)
		(end 178.49215 -302.836834)
		(width 0.18288)
		(layer "In6.Cu")
		(net "M_G_CPU1_SA_DQ<8>")
	)
	(segment
		(start 139.877292 -276.815042)
		(end 139.788138 -276.725888)
		(width 0.088646)
		(layer "In6.Cu")
		(net "M_G_CPU1_SA_DQ<8>")
	)
	(segment
		(start 173.499018 -300.59249)
		(end 171.210986 -300.59249)
		(width 0.18288)
		(layer "In6.Cu")
		(net "M_G_CPU1_SA_DQ<8>")
	)
	(segment
		(start 183.743092 -305.646328)
		(end 183.85028 -305.53914)
		(width 0.18288)
		(layer "In6.Cu")
		(net "M_G_CPU1_SA_DQ<8>")
	)
	(segment
		(start 147.028408 -277.054056)
		(end 141.63929 -277.054056)
		(width 0.18288)
		(layer "In6.Cu")
		(net "M_G_CPU1_SA_DQ<8>")
	)
	(segment
		(start 163.849558 -298.4627)
		(end 163.849558 -298.200826)
		(width 0.18288)
		(layer "In6.Cu")
		(net "M_G_CPU1_SA_DQ<8>")
	)
	(segment
		(start 133.178296 -274.756372)
		(end 133.167882 -274.762468)
		(width 0.088646)
		(layer "In6.Cu")
		(net "M_G_CPU1_SA_DQ<8>")
	)
	(segment
		(start 160.17875 -296.212006)
		(end 157.362906 -296.212006)
		(width 0.18288)
		(layer "In6.Cu")
		(net "M_G_CPU1_SA_DQ<8>")
	)
	(segment
		(start 170.890946 -301.490126)
		(end 170.517566 -301.490126)
		(width 0.18288)
		(layer "In6.Cu")
		(net "M_G_CPU1_SA_DQ<8>")
	)
	(segment
		(start 164.542978 -298.4627)
		(end 164.382958 -298.62272)
		(width 0.18288)
		(layer "In6.Cu")
		(net "M_G_CPU1_SA_DQ<8>")
	)
	(segment
		(start 176.433226 -301.442374)
		(end 176.273206 -301.602394)
		(width 0.18288)
		(layer "In6.Cu")
		(net "M_G_CPU1_SA_DQ<8>")
	)
	(segment
		(start 171.210986 -300.59249)
		(end 171.050966 -300.75251)
		(width 0.18288)
		(layer "In6.Cu")
		(net "M_G_CPU1_SA_DQ<8>")
	)
	(segment
		(start 163.849558 -298.200826)
		(end 163.689538 -298.040806)
		(width 0.18288)
		(layer "In6.Cu")
		(net "M_G_CPU1_SA_DQ<8>")
	)
	(segment
		(start 180.507132 -303.231804)
		(end 180.507132 -303.005744)
		(width 0.18288)
		(layer "In6.Cu")
		(net "M_G_CPU1_SA_DQ<8>")
	)
	(segment
		(start 139.338558 -275.386546)
		(end 139.412726 -275.207476)
		(width 0.088646)
		(layer "In6.Cu")
		(net "M_G_CPU1_SA_DQ<8>")
	)
	(segment
		(start 183.552338 -304.982626)
		(end 182.484014 -304.982626)
		(width 0.18288)
		(layer "In6.Cu")
		(net "M_G_CPU1_SA_DQ<8>")
	)
	(segment
		(start 175.579786 -301.98822)
		(end 175.579786 -301.602394)
		(width 0.18288)
		(layer "In6.Cu")
		(net "M_G_CPU1_SA_DQ<8>")
	)
	(segment
		(start 164.382958 -298.62272)
		(end 164.009578 -298.62272)
		(width 0.18288)
		(layer "In6.Cu")
		(net "M_G_CPU1_SA_DQ<8>")
	)
	(segment
		(start 180.764942 -303.954942)
		(end 180.538882 -303.954942)
		(width 0.18288)
		(layer "In6.Cu")
		(net "M_G_CPU1_SA_DQ<8>")
	)
	(segment
		(start 135.447278 -274.765262)
		(end 135.432546 -274.756626)
		(width 0.088646)
		(layer "In6.Cu")
		(net "M_G_CPU1_SA_DQ<8>")
	)
	(segment
		(start 175.419766 -301.442374)
		(end 174.348902 -301.442374)
		(width 0.18288)
		(layer "In6.Cu")
		(net "M_G_CPU1_SA_DQ<8>")
	)
	(segment
		(start 180.507132 -303.005744)
		(end 180.338222 -302.836834)
		(width 0.18288)
		(layer "In6.Cu")
		(net "M_G_CPU1_SA_DQ<8>")
	)
	(segment
		(start 180.538882 -303.954942)
		(end 180.274468 -303.690528)
		(width 0.18288)
		(layer "In6.Cu")
		(net "M_G_CPU1_SA_DQ<8>")
	)
	(segment
		(start 178.49215 -302.836834)
		(end 177.09769 -301.442374)
		(width 0.18288)
		(layer "In6.Cu")
		(net "M_G_CPU1_SA_DQ<8>")
	)
	(segment
		(start 187.883546 -306.96662)
		(end 187.33135 -306.414424)
		(width 0.18288)
		(layer "In6.Cu")
		(net "M_G_CPU1_SA_DQ<8>")
	)
	(segment
		(start 151.908002 -290.757102)
		(end 151.908002 -281.93365)
		(width 0.18288)
		(layer "In6.Cu")
		(net "M_G_CPU1_SA_DQ<8>")
	)
	(segment
		(start 184.599326 -306.029614)
		(end 184.340754 -306.029614)
		(width 0.18288)
		(layer "In6.Cu")
		(net "M_G_CPU1_SA_DQ<8>")
	)
	(segment
		(start 176.273206 -301.602394)
		(end 176.273206 -301.98822)
		(width 0.18288)
		(layer "In6.Cu")
		(net "M_G_CPU1_SA_DQ<8>")
	)
	(segment
		(start 139.412726 -275.207476)
		(end 139.412726 -274.955762)
		(width 0.088646)
		(layer "In6.Cu")
		(net "M_G_CPU1_SA_DQ<8>")
	)
	(segment
		(start 139.338558 -275.956014)
		(end 139.338558 -275.386546)
		(width 0.088646)
		(layer "In6.Cu")
		(net "M_G_CPU1_SA_DQ<8>")
	)
	(segment
		(start 140.367258 -276.815042)
		(end 139.877292 -276.815042)
		(width 0.088646)
		(layer "In6.Cu")
		(net "M_G_CPU1_SA_DQ<8>")
	)
	(segment
		(start 137.326878 -274.765262)
		(end 137.312146 -274.756626)
		(width 0.088646)
		(layer "In6.Cu")
		(net "M_G_CPU1_SA_DQ<8>")
	)
	(segment
		(start 129.808478 -274.765008)
		(end 129.793746 -274.756372)
		(width 0.088646)
		(layer "In6.Cu")
		(net "M_G_CPU1_SA_DQ<8>")
	)
	(segment
		(start 130.748278 -274.765008)
		(end 130.733546 -274.756372)
		(width 0.088646)
		(layer "In6.Cu")
		(net "M_G_CPU1_SA_DQ<8>")
	)
	(segment
		(start 136.387078 -274.765262)
		(end 136.372346 -274.756626)
		(width 0.088646)
		(layer "In6.Cu")
		(net "M_G_CPU1_SA_DQ<8>")
	)
	(segment
		(start 182.484014 -304.982626)
		(end 182.190136 -304.688748)
		(width 0.18288)
		(layer "In6.Cu")
		(net "M_G_CPU1_SA_DQ<8>")
	)
	(segment
		(start 182.190136 -304.688748)
		(end 181.768496 -304.688748)
		(width 0.18288)
		(layer "In6.Cu")
		(net "M_G_CPU1_SA_DQ<8>")
	)
	(segment
		(start 176.273206 -301.98822)
		(end 176.113186 -302.14824)
		(width 0.18288)
		(layer "In6.Cu")
		(net "M_G_CPU1_SA_DQ<8>")
	)
	(segment
		(start 141.062202 -276.815042)
		(end 140.367258 -276.815042)
		(width 0.18288)
		(layer "In6.Cu")
		(net "M_G_CPU1_SA_DQ<8>")
	)
	(segment
		(start 139.412726 -274.955762)
		(end 139.162536 -274.705572)
		(width 0.088646)
		(layer "In6.Cu")
		(net "M_G_CPU1_SA_DQ<8>")
	)
	(segment
		(start 163.339526 -298.040806)
		(end 162.217354 -296.918634)
		(width 0.18288)
		(layer "In6.Cu")
		(net "M_G_CPU1_SA_DQ<8>")
	)
	(segment
		(start 164.009578 -298.62272)
		(end 163.849558 -298.4627)
		(width 0.18288)
		(layer "In6.Cu")
		(net "M_G_CPU1_SA_DQ<8>")
	)
	(segment
		(start 175.739806 -302.14824)
		(end 175.579786 -301.98822)
		(width 0.18288)
		(layer "In6.Cu")
		(net "M_G_CPU1_SA_DQ<8>")
	)
	(segment
		(start 175.579786 -301.602394)
		(end 175.419766 -301.442374)
		(width 0.18288)
		(layer "In6.Cu")
		(net "M_G_CPU1_SA_DQ<8>")
	)
	(segment
		(start 139.162536 -274.705572)
		(end 138.065002 -274.705572)
		(width 0.088646)
		(layer "In6.Cu")
		(net "M_G_CPU1_SA_DQ<8>")
	)
	(segment
		(start 157.362906 -296.212006)
		(end 151.908002 -290.757102)
		(width 0.18288)
		(layer "In6.Cu")
		(net "M_G_CPU1_SA_DQ<8>")
	)
	(segment
		(start 184.340754 -306.029614)
		(end 184.233566 -306.136802)
		(width 0.18288)
		(layer "In6.Cu")
		(net "M_G_CPU1_SA_DQ<8>")
	)
	(segment
		(start 184.984136 -306.414424)
		(end 184.599326 -306.029614)
		(width 0.18288)
		(layer "In6.Cu")
		(net "M_G_CPU1_SA_DQ<8>")
	)
	(segment
		(start 162.217354 -296.918634)
		(end 160.885378 -296.918634)
		(width 0.18288)
		(layer "In6.Cu")
		(net "M_G_CPU1_SA_DQ<8>")
	)
	(segment
		(start 183.85028 -305.53914)
		(end 183.85028 -305.280568)
		(width 0.18288)
		(layer "In6.Cu")
		(net "M_G_CPU1_SA_DQ<8>")
	)
	(segment
		(start 160.885378 -296.918634)
		(end 160.17875 -296.212006)
		(width 0.18288)
		(layer "In6.Cu")
		(net "M_G_CPU1_SA_DQ<8>")
	)
	(segment
		(start 183.743092 -305.9049)
		(end 183.743092 -305.646328)
		(width 0.18288)
		(layer "In6.Cu")
		(net "M_G_CPU1_SA_DQ<8>")
	)
	(segment
		(start 181.223666 -303.722278)
		(end 180.997606 -303.722278)
		(width 0.18288)
		(layer "In6.Cu")
		(net "M_G_CPU1_SA_DQ<8>")
	)
	(segment
		(start 128.868678 -274.765008)
		(end 128.853946 -274.756372)
		(width 0.088646)
		(layer "In6.Cu")
		(net "M_G_CPU1_SA_DQ<8>")
	)
	(segment
		(start 141.63929 -277.054056)
		(end 141.062202 -276.815042)
		(width 0.18288)
		(layer "In6.Cu")
		(net "M_G_CPU1_SA_DQ<8>")
	)
	(segment
		(start 177.09769 -301.442374)
		(end 176.433226 -301.442374)
		(width 0.18288)
		(layer "In6.Cu")
		(net "M_G_CPU1_SA_DQ<8>")
	)
	(segment
		(start 131.688078 -274.765008)
		(end 131.673346 -274.756372)
		(width 0.088646)
		(layer "In6.Cu")
		(net "M_G_CPU1_SA_DQ<8>")
	)
	(segment
		(start 151.908002 -281.93365)
		(end 147.028408 -277.054056)
		(width 0.18288)
		(layer "In6.Cu")
		(net "M_G_CPU1_SA_DQ<8>")
	)
	(segment
		(start 170.517566 -301.490126)
		(end 170.357546 -301.330106)
		(width 0.18288)
		(layer "In6.Cu")
		(net "M_G_CPU1_SA_DQ<8>")
	)
	(segment
		(start 183.974994 -306.136802)
		(end 183.743092 -305.9049)
		(width 0.18288)
		(layer "In6.Cu")
		(net "M_G_CPU1_SA_DQ<8>")
	)
	(segment
		(start 165.481254 -298.040806)
		(end 164.702998 -298.040806)
		(width 0.18288)
		(layer "In6.Cu")
		(net "M_G_CPU1_SA_DQ<8>")
	)
	(segment
		(start 168.092374 -299.648626)
		(end 167.089074 -299.648626)
		(width 0.18288)
		(layer "In6.Cu")
		(net "M_G_CPU1_SA_DQ<8>")
	)
	(segment
		(start 139.788138 -276.405594)
		(end 139.338558 -275.956014)
		(width 0.088646)
		(layer "In6.Cu")
		(net "M_G_CPU1_SA_DQ<8>")
	)
	(segment
		(start 181.488842 -304.409094)
		(end 181.488842 -303.987454)
		(width 0.18288)
		(layer "In6.Cu")
		(net "M_G_CPU1_SA_DQ<8>")
	)
	(segment
		(start 171.050966 -300.75251)
		(end 171.050966 -301.330106)
		(width 0.18288)
		(layer "In6.Cu")
		(net "M_G_CPU1_SA_DQ<8>")
	)
	(segment
		(start 134.512812 -274.768056)
		(end 134.492746 -274.756372)
		(width 0.088646)
		(layer "In6.Cu")
		(net "M_G_CPU1_SA_DQ<8>")
	)
	(arc
		(start 129.41935 -274.756372)
		(mid 129.145151 -274.832207)
		(end 128.868678 -274.765008)
		(width 0.088646)
		(layer "In6.Cu")
		(net "M_G_CPU1_SA_DQ<8>")
	)
	(arc
		(start 133.167882 -274.762468)
		(mid 132.889704 -274.832191)
		(end 132.613146 -274.756372)
		(width 0.088646)
		(layer "In6.Cu")
		(net "M_G_CPU1_SA_DQ<8>")
	)
	(arc
		(start 135.99795 -274.756626)
		(mid 135.723721 -274.832551)
		(end 135.447278 -274.765262)
		(width 0.088646)
		(layer "In6.Cu")
		(net "M_G_CPU1_SA_DQ<8>")
	)
	(arc
		(start 129.793746 -274.756372)
		(mid 129.606548 -274.706229)
		(end 129.41935 -274.756372)
		(width 0.088646)
		(layer "In6.Cu")
		(net "M_G_CPU1_SA_DQ<8>")
	)
	(arc
		(start 127.90805 -274.752816)
		(mid 127.722595 -274.574621)
		(end 127.635254 -274.3327)
		(width 0.088646)
		(layer "In6.Cu")
		(net "M_G_CPU1_SA_DQ<8>")
	)
	(arc
		(start 131.29895 -274.756372)
		(mid 131.024751 -274.832207)
		(end 130.748278 -274.765008)
		(width 0.088646)
		(layer "In6.Cu")
		(net "M_G_CPU1_SA_DQ<8>")
	)
	(arc
		(start 130.35915 -274.756372)
		(mid 130.084951 -274.832207)
		(end 129.808478 -274.765008)
		(width 0.088646)
		(layer "In6.Cu")
		(net "M_G_CPU1_SA_DQ<8>")
	)
	(arc
		(start 130.733546 -274.756372)
		(mid 130.546348 -274.706229)
		(end 130.35915 -274.756372)
		(width 0.088646)
		(layer "In6.Cu")
		(net "M_G_CPU1_SA_DQ<8>")
	)
	(arc
		(start 137.87755 -274.756626)
		(mid 137.603321 -274.832551)
		(end 137.326878 -274.765262)
		(width 0.088646)
		(layer "In6.Cu")
		(net "M_G_CPU1_SA_DQ<8>")
	)
	(arc
		(start 135.05815 -274.756626)
		(mid 134.786961 -274.832373)
		(end 134.512812 -274.768056)
		(width 0.088646)
		(layer "In6.Cu")
		(net "M_G_CPU1_SA_DQ<8>")
	)
	(arc
		(start 134.492746 -274.756372)
		(mid 134.305548 -274.706229)
		(end 134.11835 -274.756372)
		(width 0.088646)
		(layer "In6.Cu")
		(net "M_G_CPU1_SA_DQ<8>")
	)
	(arc
		(start 137.312146 -274.756626)
		(mid 137.124948 -274.706483)
		(end 136.93775 -274.756626)
		(width 0.088646)
		(layer "In6.Cu")
		(net "M_G_CPU1_SA_DQ<8>")
	)
	(arc
		(start 132.23875 -274.756372)
		(mid 131.964551 -274.832207)
		(end 131.688078 -274.765008)
		(width 0.088646)
		(layer "In6.Cu")
		(net "M_G_CPU1_SA_DQ<8>")
	)
	(arc
		(start 131.673346 -274.756372)
		(mid 131.486148 -274.706229)
		(end 131.29895 -274.756372)
		(width 0.088646)
		(layer "In6.Cu")
		(net "M_G_CPU1_SA_DQ<8>")
	)
	(arc
		(start 133.552692 -274.756372)
		(mid 133.365494 -274.706229)
		(end 133.178296 -274.756372)
		(width 0.088646)
		(layer "In6.Cu")
		(net "M_G_CPU1_SA_DQ<8>")
	)
	(arc
		(start 136.372346 -274.756626)
		(mid 136.185148 -274.706483)
		(end 135.99795 -274.756626)
		(width 0.088646)
		(layer "In6.Cu")
		(net "M_G_CPU1_SA_DQ<8>")
	)
	(arc
		(start 128.853946 -274.756372)
		(mid 128.666748 -274.706229)
		(end 128.47955 -274.756372)
		(width 0.088646)
		(layer "In6.Cu")
		(net "M_G_CPU1_SA_DQ<8>")
	)
	(arc
		(start 134.11835 -274.756372)
		(mid 133.841537 -274.832242)
		(end 133.563106 -274.762468)
		(width 0.088646)
		(layer "In6.Cu")
		(net "M_G_CPU1_SA_DQ<8>")
	)
	(arc
		(start 135.432546 -274.756626)
		(mid 135.245348 -274.706483)
		(end 135.05815 -274.756626)
		(width 0.088646)
		(layer "In6.Cu")
		(net "M_G_CPU1_SA_DQ<8>")
	)
	(arc
		(start 128.47955 -274.756372)
		(mid 128.205351 -274.832207)
		(end 127.928878 -274.765008)
		(width 0.088646)
		(layer "In6.Cu")
		(net "M_G_CPU1_SA_DQ<8>")
	)
	(arc
		(start 132.613146 -274.756372)
		(mid 132.425948 -274.706229)
		(end 132.23875 -274.756372)
		(width 0.088646)
		(layer "In6.Cu")
		(net "M_G_CPU1_SA_DQ<8>")
	)
	(arc
		(start 138.065002 -274.705572)
		(mid 137.967916 -274.71876)
		(end 137.87755 -274.756626)
		(width 0.088646)
		(layer "In6.Cu")
		(net "M_G_CPU1_SA_DQ<8>")
	)
	(arc
		(start 136.93775 -274.756626)
		(mid 136.663521 -274.832551)
		(end 136.387078 -274.765262)
		(width 0.088646)
		(layer "In6.Cu")
		(net "M_G_CPU1_SA_DQ<8>")
	)
	(segment
		(start 198.662036 -307.56479)
		(end 199.046084 -307.56479)
		(width 0.20066)
		(layer "F.Cu")
		(net "M_G_CPU1_SA_DQ<7>")
	)
	(segment
		(start 198.427848 -307.798978)
		(end 198.662036 -307.56479)
		(width 0.20066)
		(layer "F.Cu")
		(net "M_G_CPU1_SA_DQ<7>")
	)
	(segment
		(start 195.515484 -308.248812)
		(end 195.522596 -308.2417)
		(width 0.1016)
		(layer "F.Cu")
		(net "M_G_CPU1_SA_DQ<7>")
	)
	(segment
		(start 198.223886 -308.253892)
		(end 198.427848 -308.04993)
		(width 0.20066)
		(layer "F.Cu")
		(net "M_G_CPU1_SA_DQ<7>")
	)
	(segment
		(start 194.786758 -307.816758)
		(end 195.218812 -308.248812)
		(width 0.20066)
		(layer "F.Cu")
		(net "M_G_CPU1_SA_DQ<7>")
	)
	(segment
		(start 199.298052 -307.816758)
		(end 200.632314 -307.816758)
		(width 0.20066)
		(layer "F.Cu")
		(net "M_G_CPU1_SA_DQ<7>")
	)
	(segment
		(start 131.485894 -273.452844)
		(end 131.486148 -273.453098)
		(width 0.20066)
		(layer "F.Cu")
		(net "M_G_CPU1_SA_DQ<7>")
	)
	(segment
		(start 197.542658 -308.253892)
		(end 198.223886 -308.253892)
		(width 0.20066)
		(layer "F.Cu")
		(net "M_G_CPU1_SA_DQ<7>")
	)
	(segment
		(start 195.218812 -308.248812)
		(end 195.510658 -308.248812)
		(width 0.20066)
		(layer "F.Cu")
		(net "M_G_CPU1_SA_DQ<7>")
	)
	(segment
		(start 199.046084 -307.56479)
		(end 199.298052 -307.816758)
		(width 0.20066)
		(layer "F.Cu")
		(net "M_G_CPU1_SA_DQ<7>")
	)
	(segment
		(start 195.510658 -308.248812)
		(end 195.515484 -308.248812)
		(width 0.101854)
		(layer "F.Cu")
		(net "M_G_CPU1_SA_DQ<7>")
	)
	(segment
		(start 197.530466 -308.2417)
		(end 197.542658 -308.253892)
		(width 0.1016)
		(layer "F.Cu")
		(net "M_G_CPU1_SA_DQ<7>")
	)
	(segment
		(start 131.485894 -272.917158)
		(end 131.485894 -273.452844)
		(width 0.20066)
		(layer "F.Cu")
		(net "M_G_CPU1_SA_DQ<7>")
	)
	(segment
		(start 195.522596 -308.2417)
		(end 197.530466 -308.2417)
		(width 0.1016)
		(layer "F.Cu")
		(net "M_G_CPU1_SA_DQ<7>")
	)
	(segment
		(start 193.088514 -307.816758)
		(end 194.786758 -307.816758)
		(width 0.20066)
		(layer "F.Cu")
		(net "M_G_CPU1_SA_DQ<7>")
	)
	(segment
		(start 198.427848 -308.04993)
		(end 198.427848 -307.798978)
		(width 0.20066)
		(layer "F.Cu")
		(net "M_G_CPU1_SA_DQ<7>")
	)
	(segment
		(start 191.983614 -307.816758)
		(end 193.088514 -307.816758)
		(width 0.20066)
		(layer "F.Cu")
		(net "M_G_CPU1_SA_DQ<7>")
	)
	(segment
		(start 176.62906 -307.390038)
		(end 175.150272 -308.868826)
		(width 0.18288)
		(layer "In4.Cu")
		(net "M_G_CPU1_SA_DQ<7>")
	)
	(segment
		(start 190.554356 -307.040026)
		(end 190.095378 -307.040026)
		(width 0.18288)
		(layer "In4.Cu")
		(net "M_G_CPU1_SA_DQ<7>")
	)
	(segment
		(start 131.682236 -273.772376)
		(end 131.673346 -273.777456)
		(width 0.088646)
		(layer "In4.Cu")
		(net "M_G_CPU1_SA_DQ<7>")
	)
	(segment
		(start 155.205684 -301.915068)
		(end 150.866602 -295.41978)
		(width 0.18288)
		(layer "In4.Cu")
		(net "M_G_CPU1_SA_DQ<7>")
	)
	(segment
		(start 164.327586 -307.545486)
		(end 163.852606 -307.545486)
		(width 0.18288)
		(layer "In4.Cu")
		(net "M_G_CPU1_SA_DQ<7>")
	)
	(segment
		(start 133.648196 -272.96364)
		(end 133.633464 -272.955004)
		(width 0.088646)
		(layer "In4.Cu")
		(net "M_G_CPU1_SA_DQ<7>")
	)
	(segment
		(start 135.527796 -272.96364)
		(end 135.513064 -272.955004)
		(width 0.088646)
		(layer "In4.Cu")
		(net "M_G_CPU1_SA_DQ<7>")
	)
	(segment
		(start 166.438326 -308.259226)
		(end 165.495986 -307.316886)
		(width 0.18288)
		(layer "In4.Cu")
		(net "M_G_CPU1_SA_DQ<7>")
	)
	(segment
		(start 172.611034 -308.242716)
		(end 171.567094 -309.286656)
		(width 0.18288)
		(layer "In4.Cu")
		(net "M_G_CPU1_SA_DQ<7>")
	)
	(segment
		(start 134.587996 -272.96364)
		(end 134.573264 -272.955004)
		(width 0.088646)
		(layer "In4.Cu")
		(net "M_G_CPU1_SA_DQ<7>")
	)
	(segment
		(start 138.159744 -274.266914)
		(end 138.159744 -274.257008)
		(width 0.088646)
		(layer "In4.Cu")
		(net "M_G_CPU1_SA_DQ<7>")
	)
	(segment
		(start 167.939466 -308.259226)
		(end 166.438326 -308.259226)
		(width 0.18288)
		(layer "In4.Cu")
		(net "M_G_CPU1_SA_DQ<7>")
	)
	(segment
		(start 162.179762 -305.692302)
		(end 161.255202 -305.692302)
		(width 0.18288)
		(layer "In4.Cu")
		(net "M_G_CPU1_SA_DQ<7>")
	)
	(segment
		(start 163.339526 -307.032406)
		(end 163.339526 -306.852066)
		(width 0.18288)
		(layer "In4.Cu")
		(net "M_G_CPU1_SA_DQ<7>")
	)
	(segment
		(start 136.937496 -273.777456)
		(end 136.928606 -273.772376)
		(width 0.088646)
		(layer "In4.Cu")
		(net "M_G_CPU1_SA_DQ<7>")
	)
	(segment
		(start 191.983614 -307.816758)
		(end 190.974726 -307.816758)
		(width 0.18288)
		(layer "In4.Cu")
		(net "M_G_CPU1_SA_DQ<7>")
	)
	(segment
		(start 164.556186 -307.316886)
		(end 164.327586 -307.545486)
		(width 0.18288)
		(layer "In4.Cu")
		(net "M_G_CPU1_SA_DQ<7>")
	)
	(segment
		(start 138.629898 -275.080984)
		(end 138.629898 -275.06676)
		(width 0.088646)
		(layer "In4.Cu")
		(net "M_G_CPU1_SA_DQ<7>")
	)
	(segment
		(start 150.866602 -295.41978)
		(end 144.886426 -280.981404)
		(width 0.18288)
		(layer "In4.Cu")
		(net "M_G_CPU1_SA_DQ<7>")
	)
	(segment
		(start 190.974726 -307.816758)
		(end 190.846964 -307.688996)
		(width 0.18288)
		(layer "In4.Cu")
		(net "M_G_CPU1_SA_DQ<7>")
	)
	(segment
		(start 163.852606 -307.545486)
		(end 163.339526 -307.032406)
		(width 0.18288)
		(layer "In4.Cu")
		(net "M_G_CPU1_SA_DQ<7>")
	)
	(segment
		(start 157.28188 -303.991264)
		(end 155.205684 -301.915068)
		(width 0.18288)
		(layer "In4.Cu")
		(net "M_G_CPU1_SA_DQ<7>")
	)
	(segment
		(start 171.567094 -309.286656)
		(end 168.966896 -309.286656)
		(width 0.18288)
		(layer "In4.Cu")
		(net "M_G_CPU1_SA_DQ<7>")
	)
	(segment
		(start 131.173474 -273.453098)
		(end 131.486148 -273.453098)
		(width 0.088646)
		(layer "In4.Cu")
		(net "M_G_CPU1_SA_DQ<7>")
	)
	(segment
		(start 131.29895 -273.777456)
		(end 131.29006 -273.772376)
		(width 0.088646)
		(layer "In4.Cu")
		(net "M_G_CPU1_SA_DQ<7>")
	)
	(segment
		(start 177.830988 -307.715158)
		(end 177.505868 -307.390038)
		(width 0.18288)
		(layer "In4.Cu")
		(net "M_G_CPU1_SA_DQ<7>")
	)
	(segment
		(start 183.281066 -308.310026)
		(end 180.15077 -308.310026)
		(width 0.18288)
		(layer "In4.Cu")
		(net "M_G_CPU1_SA_DQ<7>")
	)
	(segment
		(start 174.095664 -308.242716)
		(end 172.611034 -308.242716)
		(width 0.18288)
		(layer "In4.Cu")
		(net "M_G_CPU1_SA_DQ<7>")
	)
	(segment
		(start 175.150272 -308.868826)
		(end 174.721774 -308.868826)
		(width 0.18288)
		(layer "In4.Cu")
		(net "M_G_CPU1_SA_DQ<7>")
	)
	(segment
		(start 136.750044 -273.453098)
		(end 136.750044 -273.443192)
		(width 0.088646)
		(layer "In4.Cu")
		(net "M_G_CPU1_SA_DQ<7>")
	)
	(segment
		(start 138.347196 -274.591272)
		(end 138.338306 -274.586192)
		(width 0.088646)
		(layer "In4.Cu")
		(net "M_G_CPU1_SA_DQ<7>")
	)
	(segment
		(start 177.505868 -307.390038)
		(end 176.62906 -307.390038)
		(width 0.18288)
		(layer "In4.Cu")
		(net "M_G_CPU1_SA_DQ<7>")
	)
	(segment
		(start 189.74562 -307.389784)
		(end 184.201308 -307.389784)
		(width 0.18288)
		(layer "In4.Cu")
		(net "M_G_CPU1_SA_DQ<7>")
	)
	(segment
		(start 144.886426 -280.981404)
		(end 139.582652 -275.67763)
		(width 0.18288)
		(layer "In4.Cu")
		(net "M_G_CPU1_SA_DQ<7>")
	)
	(segment
		(start 184.201308 -307.389784)
		(end 183.281066 -308.310026)
		(width 0.18288)
		(layer "In4.Cu")
		(net "M_G_CPU1_SA_DQ<7>")
	)
	(segment
		(start 139.582652 -275.67763)
		(end 139.361164 -275.456142)
		(width 0.088646)
		(layer "In4.Cu")
		(net "M_G_CPU1_SA_DQ<7>")
	)
	(segment
		(start 131.11607 -273.510502)
		(end 131.173474 -273.453098)
		(width 0.088646)
		(layer "In4.Cu")
		(net "M_G_CPU1_SA_DQ<7>")
	)
	(segment
		(start 190.846964 -307.332634)
		(end 190.554356 -307.040026)
		(width 0.18288)
		(layer "In4.Cu")
		(net "M_G_CPU1_SA_DQ<7>")
	)
	(segment
		(start 163.339526 -306.852066)
		(end 162.179762 -305.692302)
		(width 0.18288)
		(layer "In4.Cu")
		(net "M_G_CPU1_SA_DQ<7>")
	)
	(segment
		(start 179.238402 -307.397658)
		(end 178.723544 -307.397658)
		(width 0.18288)
		(layer "In4.Cu")
		(net "M_G_CPU1_SA_DQ<7>")
	)
	(segment
		(start 190.846964 -307.688996)
		(end 190.846964 -307.332634)
		(width 0.18288)
		(layer "In4.Cu")
		(net "M_G_CPU1_SA_DQ<7>")
	)
	(segment
		(start 158.828486 -303.991264)
		(end 157.28188 -303.991264)
		(width 0.18288)
		(layer "In4.Cu")
		(net "M_G_CPU1_SA_DQ<7>")
	)
	(segment
		(start 178.723544 -307.397658)
		(end 178.406044 -307.715158)
		(width 0.18288)
		(layer "In4.Cu")
		(net "M_G_CPU1_SA_DQ<7>")
	)
	(segment
		(start 139.361164 -275.456142)
		(end 139.004548 -275.456142)
		(width 0.088646)
		(layer "In4.Cu")
		(net "M_G_CPU1_SA_DQ<7>")
	)
	(segment
		(start 131.860798 -273.443192)
		(end 131.860798 -273.453098)
		(width 0.088646)
		(layer "In4.Cu")
		(net "M_G_CPU1_SA_DQ<7>")
	)
	(segment
		(start 190.095378 -307.040026)
		(end 189.74562 -307.389784)
		(width 0.18288)
		(layer "In4.Cu")
		(net "M_G_CPU1_SA_DQ<7>")
	)
	(segment
		(start 180.15077 -308.310026)
		(end 179.238402 -307.397658)
		(width 0.18288)
		(layer "In4.Cu")
		(net "M_G_CPU1_SA_DQ<7>")
	)
	(segment
		(start 178.406044 -307.715158)
		(end 177.830988 -307.715158)
		(width 0.18288)
		(layer "In4.Cu")
		(net "M_G_CPU1_SA_DQ<7>")
	)
	(segment
		(start 168.966896 -309.286656)
		(end 167.939466 -308.259226)
		(width 0.18288)
		(layer "In4.Cu")
		(net "M_G_CPU1_SA_DQ<7>")
	)
	(segment
		(start 159.730948 -304.893726)
		(end 158.828486 -303.991264)
		(width 0.18288)
		(layer "In4.Cu")
		(net "M_G_CPU1_SA_DQ<7>")
	)
	(segment
		(start 161.255202 -305.692302)
		(end 160.456626 -304.893726)
		(width 0.18288)
		(layer "In4.Cu")
		(net "M_G_CPU1_SA_DQ<7>")
	)
	(segment
		(start 160.456626 -304.893726)
		(end 159.730948 -304.893726)
		(width 0.18288)
		(layer "In4.Cu")
		(net "M_G_CPU1_SA_DQ<7>")
	)
	(segment
		(start 165.495986 -307.316886)
		(end 164.556186 -307.316886)
		(width 0.18288)
		(layer "In4.Cu")
		(net "M_G_CPU1_SA_DQ<7>")
	)
	(segment
		(start 132.708396 -272.96364)
		(end 132.697982 -272.957544)
		(width 0.088646)
		(layer "In4.Cu")
		(net "M_G_CPU1_SA_DQ<7>")
	)
	(segment
		(start 174.721774 -308.868826)
		(end 174.095664 -308.242716)
		(width 0.18288)
		(layer "In4.Cu")
		(net "M_G_CPU1_SA_DQ<7>")
	)
	(arc
		(start 139.004548 -275.456142)
		(mid 138.902625 -275.441806)
		(end 138.80846 -275.400262)
		(width 0.088646)
		(layer "In4.Cu")
		(net "M_G_CPU1_SA_DQ<7>")
	)
	(arc
		(start 135.513064 -272.955004)
		(mid 135.236589 -272.887684)
		(end 134.962392 -272.96364)
		(width 0.088646)
		(layer "In4.Cu")
		(net "M_G_CPU1_SA_DQ<7>")
	)
	(arc
		(start 132.143246 -272.96364)
		(mid 131.938911 -273.166245)
		(end 131.860798 -273.443192)
		(width 0.088646)
		(layer "In4.Cu")
		(net "M_G_CPU1_SA_DQ<7>")
	)
	(arc
		(start 136.928606 -273.772376)
		(mid 136.797692 -273.636016)
		(end 136.750044 -273.453098)
		(width 0.088646)
		(layer "In4.Cu")
		(net "M_G_CPU1_SA_DQ<7>")
	)
	(arc
		(start 133.082792 -272.96364)
		(mid 132.895594 -273.013783)
		(end 132.708396 -272.96364)
		(width 0.088646)
		(layer "In4.Cu")
		(net "M_G_CPU1_SA_DQ<7>")
	)
	(arc
		(start 134.962392 -272.96364)
		(mid 134.775194 -273.013783)
		(end 134.587996 -272.96364)
		(width 0.088646)
		(layer "In4.Cu")
		(net "M_G_CPU1_SA_DQ<7>")
	)
	(arc
		(start 131.29006 -273.772376)
		(mid 131.174321 -273.660552)
		(end 131.11607 -273.510502)
		(width 0.088646)
		(layer "In4.Cu")
		(net "M_G_CPU1_SA_DQ<7>")
	)
	(arc
		(start 138.159744 -274.257008)
		(mid 138.081633 -273.980059)
		(end 137.877296 -273.777456)
		(width 0.088646)
		(layer "In4.Cu")
		(net "M_G_CPU1_SA_DQ<7>")
	)
	(arc
		(start 136.467596 -272.96364)
		(mid 136.184894 -272.887864)
		(end 135.902192 -272.96364)
		(width 0.088646)
		(layer "In4.Cu")
		(net "M_G_CPU1_SA_DQ<7>")
	)
	(arc
		(start 137.877296 -273.777456)
		(mid 137.594594 -273.70168)
		(end 137.311892 -273.777456)
		(width 0.088646)
		(layer "In4.Cu")
		(net "M_G_CPU1_SA_DQ<7>")
	)
	(arc
		(start 138.629898 -275.06676)
		(mid 138.550679 -274.792075)
		(end 138.347196 -274.591272)
		(width 0.088646)
		(layer "In4.Cu")
		(net "M_G_CPU1_SA_DQ<7>")
	)
	(arc
		(start 132.697982 -272.957544)
		(mid 132.419804 -272.887821)
		(end 132.143246 -272.96364)
		(width 0.088646)
		(layer "In4.Cu")
		(net "M_G_CPU1_SA_DQ<7>")
	)
	(arc
		(start 138.80846 -275.400262)
		(mid 138.677546 -275.263902)
		(end 138.629898 -275.080984)
		(width 0.088646)
		(layer "In4.Cu")
		(net "M_G_CPU1_SA_DQ<7>")
	)
	(arc
		(start 131.860798 -273.453098)
		(mid 131.813119 -273.635998)
		(end 131.682236 -273.772376)
		(width 0.088646)
		(layer "In4.Cu")
		(net "M_G_CPU1_SA_DQ<7>")
	)
	(arc
		(start 133.633464 -272.955004)
		(mid 133.356989 -272.887684)
		(end 133.082792 -272.96364)
		(width 0.088646)
		(layer "In4.Cu")
		(net "M_G_CPU1_SA_DQ<7>")
	)
	(arc
		(start 134.022592 -272.96364)
		(mid 133.835394 -273.013783)
		(end 133.648196 -272.96364)
		(width 0.088646)
		(layer "In4.Cu")
		(net "M_G_CPU1_SA_DQ<7>")
	)
	(arc
		(start 137.311892 -273.777456)
		(mid 137.124694 -273.827599)
		(end 136.937496 -273.777456)
		(width 0.088646)
		(layer "In4.Cu")
		(net "M_G_CPU1_SA_DQ<7>")
	)
	(arc
		(start 138.338306 -274.586192)
		(mid 138.207392 -274.449832)
		(end 138.159744 -274.266914)
		(width 0.088646)
		(layer "In4.Cu")
		(net "M_G_CPU1_SA_DQ<7>")
	)
	(arc
		(start 135.902192 -272.96364)
		(mid 135.714994 -273.013783)
		(end 135.527796 -272.96364)
		(width 0.088646)
		(layer "In4.Cu")
		(net "M_G_CPU1_SA_DQ<7>")
	)
	(arc
		(start 136.750044 -273.443192)
		(mid 136.671933 -273.166243)
		(end 136.467596 -272.96364)
		(width 0.088646)
		(layer "In4.Cu")
		(net "M_G_CPU1_SA_DQ<7>")
	)
	(arc
		(start 131.673346 -273.777456)
		(mid 131.486148 -273.827599)
		(end 131.29895 -273.777456)
		(width 0.088646)
		(layer "In4.Cu")
		(net "M_G_CPU1_SA_DQ<7>")
	)
	(arc
		(start 134.573264 -272.955004)
		(mid 134.296789 -272.887684)
		(end 134.022592 -272.96364)
		(width 0.088646)
		(layer "In4.Cu")
		(net "M_G_CPU1_SA_DQ<7>")
	)
	(segment
		(start 198.662036 -309.264812)
		(end 199.046084 -309.264812)
		(width 0.20066)
		(layer "F.Cu")
		(net "M_G_CPU1_SA_DQ<6>")
	)
	(segment
		(start 198.223886 -309.953914)
		(end 198.427848 -309.749952)
		(width 0.20066)
		(layer "F.Cu")
		(net "M_G_CPU1_SA_DQ<6>")
	)
	(segment
		(start 131.956048 -274.26666)
		(end 131.955794 -274.266914)
		(width 0.20066)
		(layer "F.Cu")
		(net "M_G_CPU1_SA_DQ<6>")
	)
	(segment
		(start 193.088514 -309.51678)
		(end 194.786758 -309.51678)
		(width 0.20066)
		(layer "F.Cu")
		(net "M_G_CPU1_SA_DQ<6>")
	)
	(segment
		(start 191.983868 -309.51678)
		(end 193.088514 -309.51678)
		(width 0.20066)
		(layer "F.Cu")
		(net "M_G_CPU1_SA_DQ<6>")
	)
	(segment
		(start 191.983614 -309.516526)
		(end 191.983868 -309.51678)
		(width 0.20066)
		(layer "F.Cu")
		(net "M_G_CPU1_SA_DQ<6>")
	)
	(segment
		(start 197.542658 -309.953914)
		(end 198.223886 -309.953914)
		(width 0.20066)
		(layer "F.Cu")
		(net "M_G_CPU1_SA_DQ<6>")
	)
	(segment
		(start 199.046084 -309.264812)
		(end 199.298052 -309.51678)
		(width 0.20066)
		(layer "F.Cu")
		(net "M_G_CPU1_SA_DQ<6>")
	)
	(segment
		(start 195.515484 -309.948834)
		(end 195.522596 -309.941722)
		(width 0.1016)
		(layer "F.Cu")
		(net "M_G_CPU1_SA_DQ<6>")
	)
	(segment
		(start 195.522596 -309.941722)
		(end 197.530466 -309.941722)
		(width 0.1016)
		(layer "F.Cu")
		(net "M_G_CPU1_SA_DQ<6>")
	)
	(segment
		(start 198.427848 -309.499)
		(end 198.662036 -309.264812)
		(width 0.20066)
		(layer "F.Cu")
		(net "M_G_CPU1_SA_DQ<6>")
	)
	(segment
		(start 195.218812 -309.948834)
		(end 195.510658 -309.948834)
		(width 0.20066)
		(layer "F.Cu")
		(net "M_G_CPU1_SA_DQ<6>")
	)
	(segment
		(start 195.510658 -309.948834)
		(end 195.515484 -309.948834)
		(width 0.101854)
		(layer "F.Cu")
		(net "M_G_CPU1_SA_DQ<6>")
	)
	(segment
		(start 131.956048 -273.730974)
		(end 131.956048 -274.26666)
		(width 0.20066)
		(layer "F.Cu")
		(net "M_G_CPU1_SA_DQ<6>")
	)
	(segment
		(start 199.298052 -309.51678)
		(end 200.632314 -309.51678)
		(width 0.20066)
		(layer "F.Cu")
		(net "M_G_CPU1_SA_DQ<6>")
	)
	(segment
		(start 197.530466 -309.941722)
		(end 197.542658 -309.953914)
		(width 0.1016)
		(layer "F.Cu")
		(net "M_G_CPU1_SA_DQ<6>")
	)
	(segment
		(start 198.427848 -309.749952)
		(end 198.427848 -309.499)
		(width 0.20066)
		(layer "F.Cu")
		(net "M_G_CPU1_SA_DQ<6>")
	)
	(segment
		(start 194.786758 -309.51678)
		(end 195.218812 -309.948834)
		(width 0.20066)
		(layer "F.Cu")
		(net "M_G_CPU1_SA_DQ<6>")
	)
	(segment
		(start 139.29868 -276.40407)
		(end 138.508994 -276.268434)
		(width 0.088646)
		(layer "In4.Cu")
		(net "M_G_CPU1_SA_DQ<6>")
	)
	(segment
		(start 157.399482 -305.69408)
		(end 155.129484 -303.636934)
		(width 0.18288)
		(layer "In4.Cu")
		(net "M_G_CPU1_SA_DQ<6>")
	)
	(segment
		(start 168.845484 -310.793384)
		(end 168.089326 -310.037226)
		(width 0.18288)
		(layer "In4.Cu")
		(net "M_G_CPU1_SA_DQ<6>")
	)
	(segment
		(start 183.115204 -310.258206)
		(end 182.884572 -310.027574)
		(width 0.18288)
		(layer "In4.Cu")
		(net "M_G_CPU1_SA_DQ<6>")
	)
	(segment
		(start 171.997116 -310.788558)
		(end 171.848272 -310.937402)
		(width 0.18288)
		(layer "In4.Cu")
		(net "M_G_CPU1_SA_DQ<6>")
	)
	(segment
		(start 175.697388 -310.788558)
		(end 171.997116 -310.788558)
		(width 0.18288)
		(layer "In4.Cu")
		(net "M_G_CPU1_SA_DQ<6>")
	)
	(segment
		(start 191.3509 -308.883812)
		(end 189.806072 -308.883812)
		(width 0.18288)
		(layer "In4.Cu")
		(net "M_G_CPU1_SA_DQ<6>")
	)
	(segment
		(start 170.305984 -310.937402)
		(end 170.161966 -310.793384)
		(width 0.18288)
		(layer "In4.Cu")
		(net "M_G_CPU1_SA_DQ<6>")
	)
	(segment
		(start 159.745934 -306.633626)
		(end 158.806388 -305.69408)
		(width 0.18288)
		(layer "In4.Cu")
		(net "M_G_CPU1_SA_DQ<6>")
	)
	(segment
		(start 139.844526 -276.949916)
		(end 139.29868 -276.40407)
		(width 0.088646)
		(layer "In4.Cu")
		(net "M_G_CPU1_SA_DQ<6>")
	)
	(segment
		(start 181.604412 -310.027574)
		(end 181.194964 -310.027574)
		(width 0.18288)
		(layer "In4.Cu")
		(net "M_G_CPU1_SA_DQ<6>")
	)
	(segment
		(start 161.520886 -307.469286)
		(end 160.685226 -306.633626)
		(width 0.18288)
		(layer "In4.Cu")
		(net "M_G_CPU1_SA_DQ<6>")
	)
	(segment
		(start 168.089326 -310.037226)
		(end 167.289734 -310.037226)
		(width 0.18288)
		(layer "In4.Cu")
		(net "M_G_CPU1_SA_DQ<6>")
	)
	(segment
		(start 189.217808 -309.274464)
		(end 189.217808 -310.214772)
		(width 0.18288)
		(layer "In4.Cu")
		(net "M_G_CPU1_SA_DQ<6>")
	)
	(segment
		(start 188.707268 -310.397652)
		(end 188.524388 -310.214772)
		(width 0.18288)
		(layer "In4.Cu")
		(net "M_G_CPU1_SA_DQ<6>")
	)
	(segment
		(start 164.472366 -309.259986)
		(end 163.842446 -309.259986)
		(width 0.18288)
		(layer "In4.Cu")
		(net "M_G_CPU1_SA_DQ<6>")
	)
	(segment
		(start 180.471318 -310.17464)
		(end 180.239416 -309.942738)
		(width 0.18288)
		(layer "In4.Cu")
		(net "M_G_CPU1_SA_DQ<6>")
	)
	(segment
		(start 184.322212 -309.832756)
		(end 183.896762 -310.258206)
		(width 0.18288)
		(layer "In4.Cu")
		(net "M_G_CPU1_SA_DQ<6>")
	)
	(segment
		(start 133.178296 -273.777456)
		(end 133.172454 -273.774154)
		(width 0.088646)
		(layer "In4.Cu")
		(net "M_G_CPU1_SA_DQ<6>")
	)
	(segment
		(start 144.032732 -281.725878)
		(end 143.617442 -280.722832)
		(width 0.18288)
		(layer "In4.Cu")
		(net "M_G_CPU1_SA_DQ<6>")
	)
	(segment
		(start 188.524388 -309.274464)
		(end 188.341508 -309.091584)
		(width 0.18288)
		(layer "In4.Cu")
		(net "M_G_CPU1_SA_DQ<6>")
	)
	(segment
		(start 135.057896 -273.777456)
		(end 135.052054 -273.774154)
		(width 0.088646)
		(layer "In4.Cu")
		(net "M_G_CPU1_SA_DQ<6>")
	)
	(segment
		(start 188.341508 -309.091584)
		(end 187.25642 -309.091584)
		(width 0.18288)
		(layer "In4.Cu")
		(net "M_G_CPU1_SA_DQ<6>")
	)
	(segment
		(start 187.25642 -309.091584)
		(end 187.037218 -309.310786)
		(width 0.18288)
		(layer "In4.Cu")
		(net "M_G_CPU1_SA_DQ<6>")
	)
	(segment
		(start 167.289734 -310.037226)
		(end 166.654734 -309.402226)
		(width 0.18288)
		(layer "In4.Cu")
		(net "M_G_CPU1_SA_DQ<6>")
	)
	(segment
		(start 162.051746 -307.469286)
		(end 161.520886 -307.469286)
		(width 0.18288)
		(layer "In4.Cu")
		(net "M_G_CPU1_SA_DQ<6>")
	)
	(segment
		(start 134.118096 -273.777456)
		(end 134.112254 -273.774154)
		(width 0.088646)
		(layer "In4.Cu")
		(net "M_G_CPU1_SA_DQ<6>")
	)
	(segment
		(start 170.161966 -310.793384)
		(end 168.845484 -310.793384)
		(width 0.18288)
		(layer "In4.Cu")
		(net "M_G_CPU1_SA_DQ<6>")
	)
	(segment
		(start 137.407396 -274.591272)
		(end 137.392664 -274.582636)
		(width 0.088646)
		(layer "In4.Cu")
		(net "M_G_CPU1_SA_DQ<6>")
	)
	(segment
		(start 165.371526 -308.828186)
		(end 164.904166 -308.828186)
		(width 0.18288)
		(layer "In4.Cu")
		(net "M_G_CPU1_SA_DQ<6>")
	)
	(segment
		(start 189.034928 -310.397652)
		(end 188.707268 -310.397652)
		(width 0.18288)
		(layer "In4.Cu")
		(net "M_G_CPU1_SA_DQ<6>")
	)
	(segment
		(start 133.184138 -273.781012)
		(end 133.178296 -273.777456)
		(width 0.088646)
		(layer "In4.Cu")
		(net "M_G_CPU1_SA_DQ<6>")
	)
	(segment
		(start 176.543208 -309.942738)
		(end 175.697388 -310.788558)
		(width 0.18288)
		(layer "In4.Cu")
		(net "M_G_CPU1_SA_DQ<6>")
	)
	(segment
		(start 191.983614 -309.516526)
		(end 191.3509 -308.883812)
		(width 0.18288)
		(layer "In4.Cu")
		(net "M_G_CPU1_SA_DQ<6>")
	)
	(segment
		(start 182.475124 -310.027574)
		(end 182.244492 -310.258206)
		(width 0.18288)
		(layer "In4.Cu")
		(net "M_G_CPU1_SA_DQ<6>")
	)
	(segment
		(start 183.896762 -310.258206)
		(end 183.115204 -310.258206)
		(width 0.18288)
		(layer "In4.Cu")
		(net "M_G_CPU1_SA_DQ<6>")
	)
	(segment
		(start 181.047898 -310.17464)
		(end 180.471318 -310.17464)
		(width 0.18288)
		(layer "In4.Cu")
		(net "M_G_CPU1_SA_DQ<6>")
	)
	(segment
		(start 164.904166 -308.828186)
		(end 164.472366 -309.259986)
		(width 0.18288)
		(layer "In4.Cu")
		(net "M_G_CPU1_SA_DQ<6>")
	)
	(segment
		(start 185.70321 -309.310786)
		(end 185.18124 -309.832756)
		(width 0.18288)
		(layer "In4.Cu")
		(net "M_G_CPU1_SA_DQ<6>")
	)
	(segment
		(start 136.280144 -274.266914)
		(end 136.280144 -274.257008)
		(width 0.088646)
		(layer "In4.Cu")
		(net "M_G_CPU1_SA_DQ<6>")
	)
	(segment
		(start 158.806388 -305.69408)
		(end 157.399482 -305.69408)
		(width 0.18288)
		(layer "In4.Cu")
		(net "M_G_CPU1_SA_DQ<6>")
	)
	(segment
		(start 138.159744 -275.8948)
		(end 138.159744 -275.879306)
		(width 0.088646)
		(layer "In4.Cu")
		(net "M_G_CPU1_SA_DQ<6>")
	)
	(segment
		(start 138.347196 -276.219158)
		(end 138.338306 -276.214078)
		(width 0.088646)
		(layer "In4.Cu")
		(net "M_G_CPU1_SA_DQ<6>")
	)
	(segment
		(start 180.239416 -309.942738)
		(end 176.543208 -309.942738)
		(width 0.18288)
		(layer "In4.Cu")
		(net "M_G_CPU1_SA_DQ<6>")
	)
	(segment
		(start 182.884572 -310.027574)
		(end 182.475124 -310.027574)
		(width 0.18288)
		(layer "In4.Cu")
		(net "M_G_CPU1_SA_DQ<6>")
	)
	(segment
		(start 143.617442 -280.722832)
		(end 139.844526 -276.949916)
		(width 0.18288)
		(layer "In4.Cu")
		(net "M_G_CPU1_SA_DQ<6>")
	)
	(segment
		(start 189.5983 -309.091584)
		(end 189.400688 -309.091584)
		(width 0.18288)
		(layer "In4.Cu")
		(net "M_G_CPU1_SA_DQ<6>")
	)
	(segment
		(start 189.217808 -310.214772)
		(end 189.034928 -310.397652)
		(width 0.18288)
		(layer "In4.Cu")
		(net "M_G_CPU1_SA_DQ<6>")
	)
	(segment
		(start 187.037218 -309.310786)
		(end 185.70321 -309.310786)
		(width 0.18288)
		(layer "In4.Cu")
		(net "M_G_CPU1_SA_DQ<6>")
	)
	(segment
		(start 165.945566 -309.402226)
		(end 165.371526 -308.828186)
		(width 0.18288)
		(layer "In4.Cu")
		(net "M_G_CPU1_SA_DQ<6>")
	)
	(segment
		(start 181.194964 -310.027574)
		(end 181.047898 -310.17464)
		(width 0.18288)
		(layer "In4.Cu")
		(net "M_G_CPU1_SA_DQ<6>")
	)
	(segment
		(start 136.467596 -274.591272)
		(end 136.458706 -274.586192)
		(width 0.088646)
		(layer "In4.Cu")
		(net "M_G_CPU1_SA_DQ<6>")
	)
	(segment
		(start 166.654734 -309.402226)
		(end 165.945566 -309.402226)
		(width 0.18288)
		(layer "In4.Cu")
		(net "M_G_CPU1_SA_DQ<6>")
	)
	(segment
		(start 188.524388 -310.214772)
		(end 188.524388 -309.274464)
		(width 0.18288)
		(layer "In4.Cu")
		(net "M_G_CPU1_SA_DQ<6>")
	)
	(segment
		(start 160.685226 -306.633626)
		(end 159.745934 -306.633626)
		(width 0.18288)
		(layer "In4.Cu")
		(net "M_G_CPU1_SA_DQ<6>")
	)
	(segment
		(start 137.87755 -275.405342)
		(end 137.86866 -275.400262)
		(width 0.088646)
		(layer "In4.Cu")
		(net "M_G_CPU1_SA_DQ<6>")
	)
	(segment
		(start 155.129484 -303.636934)
		(end 149.800818 -295.662604)
		(width 0.18288)
		(layer "In4.Cu")
		(net "M_G_CPU1_SA_DQ<6>")
	)
	(segment
		(start 135.061706 -273.779742)
		(end 135.057896 -273.777456)
		(width 0.088646)
		(layer "In4.Cu")
		(net "M_G_CPU1_SA_DQ<6>")
	)
	(segment
		(start 137.690098 -275.080984)
		(end 137.690098 -275.06676)
		(width 0.088646)
		(layer "In4.Cu")
		(net "M_G_CPU1_SA_DQ<6>")
	)
	(segment
		(start 185.18124 -309.832756)
		(end 184.322212 -309.832756)
		(width 0.18288)
		(layer "In4.Cu")
		(net "M_G_CPU1_SA_DQ<6>")
	)
	(segment
		(start 163.842446 -309.259986)
		(end 162.051746 -307.469286)
		(width 0.18288)
		(layer "In4.Cu")
		(net "M_G_CPU1_SA_DQ<6>")
	)
	(segment
		(start 189.400688 -309.091584)
		(end 189.217808 -309.274464)
		(width 0.18288)
		(layer "In4.Cu")
		(net "M_G_CPU1_SA_DQ<6>")
	)
	(segment
		(start 132.613146 -273.77771)
		(end 132.53466 -273.822922)
		(width 0.088646)
		(layer "In4.Cu")
		(net "M_G_CPU1_SA_DQ<6>")
	)
	(segment
		(start 149.800818 -295.662604)
		(end 144.032732 -281.725878)
		(width 0.18288)
		(layer "In4.Cu")
		(net "M_G_CPU1_SA_DQ<6>")
	)
	(segment
		(start 182.244492 -310.258206)
		(end 181.835044 -310.258206)
		(width 0.18288)
		(layer "In4.Cu")
		(net "M_G_CPU1_SA_DQ<6>")
	)
	(segment
		(start 181.835044 -310.258206)
		(end 181.604412 -310.027574)
		(width 0.18288)
		(layer "In4.Cu")
		(net "M_G_CPU1_SA_DQ<6>")
	)
	(segment
		(start 189.806072 -308.883812)
		(end 189.5983 -309.091584)
		(width 0.18288)
		(layer "In4.Cu")
		(net "M_G_CPU1_SA_DQ<6>")
	)
	(segment
		(start 171.848272 -310.937402)
		(end 170.305984 -310.937402)
		(width 0.18288)
		(layer "In4.Cu")
		(net "M_G_CPU1_SA_DQ<6>")
	)
	(segment
		(start 134.123938 -273.781012)
		(end 134.118096 -273.777456)
		(width 0.088646)
		(layer "In4.Cu")
		(net "M_G_CPU1_SA_DQ<6>")
	)
	(arc
		(start 136.280144 -274.257008)
		(mid 136.202033 -273.980059)
		(end 135.997696 -273.777456)
		(width 0.088646)
		(layer "In4.Cu")
		(net "M_G_CPU1_SA_DQ<6>")
	)
	(arc
		(start 135.052054 -273.774154)
		(mid 134.771919 -273.701838)
		(end 134.492746 -273.77771)
		(width 0.088646)
		(layer "In4.Cu")
		(net "M_G_CPU1_SA_DQ<6>")
	)
	(arc
		(start 137.86866 -275.400262)
		(mid 137.737746 -275.263902)
		(end 137.690098 -275.080984)
		(width 0.088646)
		(layer "In4.Cu")
		(net "M_G_CPU1_SA_DQ<6>")
	)
	(arc
		(start 137.392664 -274.582636)
		(mid 137.116223 -274.51547)
		(end 136.841992 -274.591272)
		(width 0.088646)
		(layer "In4.Cu")
		(net "M_G_CPU1_SA_DQ<6>")
	)
	(arc
		(start 138.338306 -276.214078)
		(mid 138.207392 -276.077718)
		(end 138.159744 -275.8948)
		(width 0.088646)
		(layer "In4.Cu")
		(net "M_G_CPU1_SA_DQ<6>")
	)
	(arc
		(start 136.841992 -274.591272)
		(mid 136.654794 -274.641415)
		(end 136.467596 -274.591272)
		(width 0.088646)
		(layer "In4.Cu")
		(net "M_G_CPU1_SA_DQ<6>")
	)
	(arc
		(start 133.172454 -273.774154)
		(mid 132.892319 -273.701838)
		(end 132.613146 -273.77771)
		(width 0.088646)
		(layer "In4.Cu")
		(net "M_G_CPU1_SA_DQ<6>")
	)
	(arc
		(start 137.690098 -275.06676)
		(mid 137.610879 -274.792075)
		(end 137.407396 -274.591272)
		(width 0.088646)
		(layer "In4.Cu")
		(net "M_G_CPU1_SA_DQ<6>")
	)
	(arc
		(start 134.492746 -273.77771)
		(mid 134.308792 -273.827805)
		(end 134.123938 -273.781012)
		(width 0.088646)
		(layer "In4.Cu")
		(net "M_G_CPU1_SA_DQ<6>")
	)
	(arc
		(start 134.112254 -273.774154)
		(mid 133.832119 -273.701838)
		(end 133.552946 -273.77771)
		(width 0.088646)
		(layer "In4.Cu")
		(net "M_G_CPU1_SA_DQ<6>")
	)
	(arc
		(start 132.53466 -273.822922)
		(mid 132.230594 -274.02584)
		(end 131.955794 -274.266914)
		(width 0.088646)
		(layer "In4.Cu")
		(net "M_G_CPU1_SA_DQ<6>")
	)
	(arc
		(start 135.997696 -273.777456)
		(mid 135.715138 -273.701807)
		(end 135.432546 -273.777456)
		(width 0.088646)
		(layer "In4.Cu")
		(net "M_G_CPU1_SA_DQ<6>")
	)
	(arc
		(start 133.552946 -273.77771)
		(mid 133.368992 -273.827805)
		(end 133.184138 -273.781012)
		(width 0.088646)
		(layer "In4.Cu")
		(net "M_G_CPU1_SA_DQ<6>")
	)
	(arc
		(start 138.159744 -275.879306)
		(mid 138.080374 -275.605572)
		(end 137.87755 -275.405342)
		(width 0.088646)
		(layer "In4.Cu")
		(net "M_G_CPU1_SA_DQ<6>")
	)
	(arc
		(start 136.458706 -274.586192)
		(mid 136.327792 -274.449832)
		(end 136.280144 -274.266914)
		(width 0.088646)
		(layer "In4.Cu")
		(net "M_G_CPU1_SA_DQ<6>")
	)
	(arc
		(start 138.508994 -276.268434)
		(mid 138.425278 -276.253047)
		(end 138.347196 -276.219158)
		(width 0.088646)
		(layer "In4.Cu")
		(net "M_G_CPU1_SA_DQ<6>")
	)
	(arc
		(start 135.432546 -273.777456)
		(mid 135.247425 -273.827719)
		(end 135.061706 -273.779742)
		(width 0.088646)
		(layer "In4.Cu")
		(net "M_G_CPU1_SA_DQ<6>")
	)
	(segment
		(start 130.546094 -273.452844)
		(end 130.546348 -273.453098)
		(width 0.20066)
		(layer "F.Cu")
		(net "M_G_CPU1_SA_DQ<5>")
	)
	(segment
		(start 191.883792 -308.2417)
		(end 191.539114 -308.2417)
		(width 0.20066)
		(layer "F.Cu")
		(net "M_G_CPU1_SA_DQ<5>")
	)
	(segment
		(start 191.421004 -308.35981)
		(end 191.421004 -308.727348)
		(width 0.20066)
		(layer "F.Cu")
		(net "M_G_CPU1_SA_DQ<5>")
	)
	(segment
		(start 194.940428 -308.666896)
		(end 194.508882 -308.23535)
		(width 0.20066)
		(layer "F.Cu")
		(net "M_G_CPU1_SA_DQ<5>")
	)
	(segment
		(start 194.508882 -308.23535)
		(end 194.098926 -308.23535)
		(width 0.20066)
		(layer "F.Cu")
		(net "M_G_CPU1_SA_DQ<5>")
	)
	(segment
		(start 190.509144 -308.666642)
		(end 188.988446 -308.666642)
		(width 0.20066)
		(layer "F.Cu")
		(net "M_G_CPU1_SA_DQ<5>")
	)
	(segment
		(start 190.75781 -308.915308)
		(end 190.509144 -308.666642)
		(width 0.20066)
		(layer "F.Cu")
		(net "M_G_CPU1_SA_DQ<5>")
	)
	(segment
		(start 130.546094 -272.917158)
		(end 130.546094 -273.452844)
		(width 0.20066)
		(layer "F.Cu")
		(net "M_G_CPU1_SA_DQ<5>")
	)
	(segment
		(start 191.539114 -308.2417)
		(end 191.421004 -308.35981)
		(width 0.20066)
		(layer "F.Cu")
		(net "M_G_CPU1_SA_DQ<5>")
	)
	(segment
		(start 196.532246 -308.666642)
		(end 196.531992 -308.666896)
		(width 0.20066)
		(layer "F.Cu")
		(net "M_G_CPU1_SA_DQ<5>")
	)
	(segment
		(start 191.421004 -308.727348)
		(end 191.233044 -308.915308)
		(width 0.20066)
		(layer "F.Cu")
		(net "M_G_CPU1_SA_DQ<5>")
	)
	(segment
		(start 194.092576 -308.2417)
		(end 191.903858 -308.2417)
		(width 0.1016)
		(layer "F.Cu")
		(net "M_G_CPU1_SA_DQ<5>")
	)
	(segment
		(start 188.988446 -308.666642)
		(end 187.883546 -308.666642)
		(width 0.20066)
		(layer "F.Cu")
		(net "M_G_CPU1_SA_DQ<5>")
	)
	(segment
		(start 196.531992 -308.666896)
		(end 194.940428 -308.666896)
		(width 0.20066)
		(layer "F.Cu")
		(net "M_G_CPU1_SA_DQ<5>")
	)
	(segment
		(start 191.903858 -308.2417)
		(end 191.883792 -308.2417)
		(width 0.101854)
		(layer "F.Cu")
		(net "M_G_CPU1_SA_DQ<5>")
	)
	(segment
		(start 191.233044 -308.915308)
		(end 190.75781 -308.915308)
		(width 0.20066)
		(layer "F.Cu")
		(net "M_G_CPU1_SA_DQ<5>")
	)
	(segment
		(start 194.098926 -308.23535)
		(end 194.092576 -308.2417)
		(width 0.1016)
		(layer "F.Cu")
		(net "M_G_CPU1_SA_DQ<5>")
	)
	(segment
		(start 137.790682 -273.947636)
		(end 137.781792 -273.942556)
		(width 0.088646)
		(layer "In4.Cu")
		(net "M_G_CPU1_SA_DQ<5>")
	)
	(segment
		(start 158.94558 -304.842672)
		(end 157.40888 -304.842672)
		(width 0.18288)
		(layer "In4.Cu")
		(net "M_G_CPU1_SA_DQ<5>")
	)
	(segment
		(start 136.559544 -273.463004)
		(end 136.559544 -273.453098)
		(width 0.088646)
		(layer "In4.Cu")
		(net "M_G_CPU1_SA_DQ<5>")
	)
	(segment
		(start 164.386006 -308.116986)
		(end 163.588446 -308.116986)
		(width 0.18288)
		(layer "In4.Cu")
		(net "M_G_CPU1_SA_DQ<5>")
	)
	(segment
		(start 130.924554 -273.51863)
		(end 130.859022 -273.453098)
		(width 0.088646)
		(layer "In4.Cu")
		(net "M_G_CPU1_SA_DQ<5>")
	)
	(segment
		(start 183.072532 -309.032656)
		(end 182.92572 -308.885844)
		(width 0.18288)
		(layer "In4.Cu")
		(net "M_G_CPU1_SA_DQ<5>")
	)
	(segment
		(start 131.774692 -273.939)
		(end 131.768596 -273.942556)
		(width 0.088646)
		(layer "In4.Cu")
		(net "M_G_CPU1_SA_DQ<5>")
	)
	(segment
		(start 138.84529 -275.72081)
		(end 138.618976 -275.494496)
		(width 0.088646)
		(layer "In4.Cu")
		(net "M_G_CPU1_SA_DQ<5>")
	)
	(segment
		(start 178.00955 -308.239922)
		(end 176.603152 -308.239922)
		(width 0.18288)
		(layer "In4.Cu")
		(net "M_G_CPU1_SA_DQ<5>")
	)
	(segment
		(start 165.663626 -308.327806)
		(end 164.596826 -308.327806)
		(width 0.18288)
		(layer "In4.Cu")
		(net "M_G_CPU1_SA_DQ<5>")
	)
	(segment
		(start 159.583374 -305.480466)
		(end 158.94558 -304.842672)
		(width 0.18288)
		(layer "In4.Cu")
		(net "M_G_CPU1_SA_DQ<5>")
	)
	(segment
		(start 163.588446 -308.116986)
		(end 162.709606 -307.238146)
		(width 0.18288)
		(layer "In4.Cu")
		(net "M_G_CPU1_SA_DQ<5>")
	)
	(segment
		(start 173.531022 -309.095648)
		(end 173.531022 -309.761128)
		(width 0.18288)
		(layer "In4.Cu")
		(net "M_G_CPU1_SA_DQ<5>")
	)
	(segment
		(start 160.240726 -305.480466)
		(end 159.583374 -305.480466)
		(width 0.18288)
		(layer "In4.Cu")
		(net "M_G_CPU1_SA_DQ<5>")
	)
	(segment
		(start 187.346082 -308.154578)
		(end 185.231786 -308.154578)
		(width 0.18288)
		(layer "In4.Cu")
		(net "M_G_CPU1_SA_DQ<5>")
	)
	(segment
		(start 170.479212 -310.368696)
		(end 169.969942 -309.859426)
		(width 0.18288)
		(layer "In4.Cu")
		(net "M_G_CPU1_SA_DQ<5>")
	)
	(segment
		(start 157.40888 -304.842672)
		(end 155.211272 -302.850804)
		(width 0.18288)
		(layer "In4.Cu")
		(net "M_G_CPU1_SA_DQ<5>")
	)
	(segment
		(start 184.990232 -309.021226)
		(end 184.863232 -309.148226)
		(width 0.18288)
		(layer "In4.Cu")
		(net "M_G_CPU1_SA_DQ<5>")
	)
	(segment
		(start 183.072532 -309.37962)
		(end 183.072532 -309.032656)
		(width 0.18288)
		(layer "In4.Cu")
		(net "M_G_CPU1_SA_DQ<5>")
	)
	(segment
		(start 164.596826 -308.327806)
		(end 164.386006 -308.116986)
		(width 0.18288)
		(layer "In4.Cu")
		(net "M_G_CPU1_SA_DQ<5>")
	)
	(segment
		(start 185.231786 -308.154578)
		(end 184.990232 -308.396132)
		(width 0.18288)
		(layer "In4.Cu")
		(net "M_G_CPU1_SA_DQ<5>")
	)
	(segment
		(start 174.224442 -309.761128)
		(end 174.224442 -309.095648)
		(width 0.18288)
		(layer "In4.Cu")
		(net "M_G_CPU1_SA_DQ<5>")
	)
	(segment
		(start 184.094374 -309.148226)
		(end 183.732424 -309.510176)
		(width 0.18288)
		(layer "In4.Cu")
		(net "M_G_CPU1_SA_DQ<5>")
	)
	(segment
		(start 139.342622 -275.91766)
		(end 139.145772 -275.72081)
		(width 0.088646)
		(layer "In4.Cu")
		(net "M_G_CPU1_SA_DQ<5>")
	)
	(segment
		(start 162.709606 -307.238146)
		(end 162.709606 -307.03266)
		(width 0.18288)
		(layer "In4.Cu")
		(net "M_G_CPU1_SA_DQ<5>")
	)
	(segment
		(start 131.768596 -273.942556)
		(end 131.753864 -273.951192)
		(width 0.088646)
		(layer "In4.Cu")
		(net "M_G_CPU1_SA_DQ<5>")
	)
	(segment
		(start 166.169086 -308.833266)
		(end 165.663626 -308.327806)
		(width 0.18288)
		(layer "In4.Cu")
		(net "M_G_CPU1_SA_DQ<5>")
	)
	(segment
		(start 132.23875 -273.12874)
		(end 132.22986 -273.13382)
		(width 0.088646)
		(layer "In4.Cu")
		(net "M_G_CPU1_SA_DQ<5>")
	)
	(segment
		(start 144.256252 -280.83129)
		(end 139.342622 -275.91766)
		(width 0.18288)
		(layer "In4.Cu")
		(net "M_G_CPU1_SA_DQ<5>")
	)
	(segment
		(start 179.949348 -308.885844)
		(end 179.580286 -309.254906)
		(width 0.18288)
		(layer "In4.Cu")
		(net "M_G_CPU1_SA_DQ<5>")
	)
	(segment
		(start 168.825926 -309.859426)
		(end 167.799766 -308.833266)
		(width 0.18288)
		(layer "In4.Cu")
		(net "M_G_CPU1_SA_DQ<5>")
	)
	(segment
		(start 183.203088 -309.510176)
		(end 183.072532 -309.37962)
		(width 0.18288)
		(layer "In4.Cu")
		(net "M_G_CPU1_SA_DQ<5>")
	)
	(segment
		(start 162.219386 -306.54244)
		(end 161.3027 -306.54244)
		(width 0.18288)
		(layer "In4.Cu")
		(net "M_G_CPU1_SA_DQ<5>")
	)
	(segment
		(start 175.440594 -309.944008)
		(end 174.407322 -309.944008)
		(width 0.18288)
		(layer "In4.Cu")
		(net "M_G_CPU1_SA_DQ<5>")
	)
	(segment
		(start 184.863232 -309.148226)
		(end 184.094374 -309.148226)
		(width 0.18288)
		(layer "In4.Cu")
		(net "M_G_CPU1_SA_DQ<5>")
	)
	(segment
		(start 174.407322 -309.944008)
		(end 174.224442 -309.761128)
		(width 0.18288)
		(layer "In4.Cu")
		(net "M_G_CPU1_SA_DQ<5>")
	)
	(segment
		(start 184.990232 -308.396132)
		(end 184.990232 -309.021226)
		(width 0.18288)
		(layer "In4.Cu")
		(net "M_G_CPU1_SA_DQ<5>")
	)
	(segment
		(start 139.145772 -275.72081)
		(end 138.84529 -275.72081)
		(width 0.088646)
		(layer "In4.Cu")
		(net "M_G_CPU1_SA_DQ<5>")
	)
	(segment
		(start 136.380982 -273.13382)
		(end 136.372092 -273.12874)
		(width 0.088646)
		(layer "In4.Cu")
		(net "M_G_CPU1_SA_DQ<5>")
	)
	(segment
		(start 178.22418 -308.454552)
		(end 178.00955 -308.239922)
		(width 0.18288)
		(layer "In4.Cu")
		(net "M_G_CPU1_SA_DQ<5>")
	)
	(segment
		(start 162.709606 -307.03266)
		(end 162.219386 -306.54244)
		(width 0.18288)
		(layer "In4.Cu")
		(net "M_G_CPU1_SA_DQ<5>")
	)
	(segment
		(start 144.452848 -281.305762)
		(end 144.256252 -280.83129)
		(width 0.18288)
		(layer "In4.Cu")
		(net "M_G_CPU1_SA_DQ<5>")
	)
	(segment
		(start 173.713902 -308.912768)
		(end 173.531022 -309.095648)
		(width 0.18288)
		(layer "In4.Cu")
		(net "M_G_CPU1_SA_DQ<5>")
	)
	(segment
		(start 161.3027 -306.54244)
		(end 160.240726 -305.480466)
		(width 0.18288)
		(layer "In4.Cu")
		(net "M_G_CPU1_SA_DQ<5>")
	)
	(segment
		(start 133.567678 -273.137376)
		(end 133.552946 -273.12874)
		(width 0.088646)
		(layer "In4.Cu")
		(net "M_G_CPU1_SA_DQ<5>")
	)
	(segment
		(start 178.069748 -308.835044)
		(end 178.22418 -308.680612)
		(width 0.18288)
		(layer "In4.Cu")
		(net "M_G_CPU1_SA_DQ<5>")
	)
	(segment
		(start 174.041562 -308.912768)
		(end 173.713902 -308.912768)
		(width 0.18288)
		(layer "In4.Cu")
		(net "M_G_CPU1_SA_DQ<5>")
	)
	(segment
		(start 150.386034 -295.629076)
		(end 144.452848 -281.305762)
		(width 0.18288)
		(layer "In4.Cu")
		(net "M_G_CPU1_SA_DQ<5>")
	)
	(segment
		(start 183.732424 -309.510176)
		(end 183.203088 -309.510176)
		(width 0.18288)
		(layer "In4.Cu")
		(net "M_G_CPU1_SA_DQ<5>")
	)
	(segment
		(start 182.92572 -308.885844)
		(end 179.949348 -308.885844)
		(width 0.18288)
		(layer "In4.Cu")
		(net "M_G_CPU1_SA_DQ<5>")
	)
	(segment
		(start 130.859022 -273.453098)
		(end 130.546348 -273.453098)
		(width 0.088646)
		(layer "In4.Cu")
		(net "M_G_CPU1_SA_DQ<5>")
	)
	(segment
		(start 138.260836 -274.761706)
		(end 138.251946 -274.756626)
		(width 0.088646)
		(layer "In4.Cu")
		(net "M_G_CPU1_SA_DQ<5>")
	)
	(segment
		(start 135.44296 -273.134836)
		(end 135.432546 -273.12874)
		(width 0.088646)
		(layer "In4.Cu")
		(net "M_G_CPU1_SA_DQ<5>")
	)
	(segment
		(start 173.531022 -309.761128)
		(end 173.348142 -309.944008)
		(width 0.18288)
		(layer "In4.Cu")
		(net "M_G_CPU1_SA_DQ<5>")
	)
	(segment
		(start 169.969942 -309.859426)
		(end 168.825926 -309.859426)
		(width 0.18288)
		(layer "In4.Cu")
		(net "M_G_CPU1_SA_DQ<5>")
	)
	(segment
		(start 173.348142 -309.944008)
		(end 171.529248 -309.944008)
		(width 0.18288)
		(layer "In4.Cu")
		(net "M_G_CPU1_SA_DQ<5>")
	)
	(segment
		(start 176.26965 -308.573424)
		(end 176.26965 -309.114952)
		(width 0.18288)
		(layer "In4.Cu")
		(net "M_G_CPU1_SA_DQ<5>")
	)
	(segment
		(start 134.507478 -273.137376)
		(end 134.492746 -273.12874)
		(width 0.088646)
		(layer "In4.Cu")
		(net "M_G_CPU1_SA_DQ<5>")
	)
	(segment
		(start 138.439398 -275.096478)
		(end 138.439398 -275.080984)
		(width 0.088646)
		(layer "In4.Cu")
		(net "M_G_CPU1_SA_DQ<5>")
	)
	(segment
		(start 187.883546 -308.666642)
		(end 187.858146 -308.666642)
		(width 0.18288)
		(layer "In4.Cu")
		(net "M_G_CPU1_SA_DQ<5>")
	)
	(segment
		(start 137.969244 -274.281138)
		(end 137.969244 -274.266914)
		(width 0.088646)
		(layer "In4.Cu")
		(net "M_G_CPU1_SA_DQ<5>")
	)
	(segment
		(start 187.858146 -308.666642)
		(end 187.346082 -308.154578)
		(width 0.18288)
		(layer "In4.Cu")
		(net "M_G_CPU1_SA_DQ<5>")
	)
	(segment
		(start 171.529248 -309.944008)
		(end 171.10456 -310.368696)
		(width 0.18288)
		(layer "In4.Cu")
		(net "M_G_CPU1_SA_DQ<5>")
	)
	(segment
		(start 176.26965 -309.114952)
		(end 175.440594 -309.944008)
		(width 0.18288)
		(layer "In4.Cu")
		(net "M_G_CPU1_SA_DQ<5>")
	)
	(segment
		(start 167.799766 -308.833266)
		(end 166.169086 -308.833266)
		(width 0.18288)
		(layer "In4.Cu")
		(net "M_G_CPU1_SA_DQ<5>")
	)
	(segment
		(start 155.211272 -302.850804)
		(end 150.386034 -295.629076)
		(width 0.18288)
		(layer "In4.Cu")
		(net "M_G_CPU1_SA_DQ<5>")
	)
	(segment
		(start 178.26355 -309.254906)
		(end 178.069748 -309.061104)
		(width 0.18288)
		(layer "In4.Cu")
		(net "M_G_CPU1_SA_DQ<5>")
	)
	(segment
		(start 171.10456 -310.368696)
		(end 170.479212 -310.368696)
		(width 0.18288)
		(layer "In4.Cu")
		(net "M_G_CPU1_SA_DQ<5>")
	)
	(segment
		(start 176.603152 -308.239922)
		(end 176.26965 -308.573424)
		(width 0.18288)
		(layer "In4.Cu")
		(net "M_G_CPU1_SA_DQ<5>")
	)
	(segment
		(start 132.627878 -273.137376)
		(end 132.613146 -273.12874)
		(width 0.088646)
		(layer "In4.Cu")
		(net "M_G_CPU1_SA_DQ<5>")
	)
	(segment
		(start 179.580286 -309.254906)
		(end 178.26355 -309.254906)
		(width 0.18288)
		(layer "In4.Cu")
		(net "M_G_CPU1_SA_DQ<5>")
	)
	(segment
		(start 174.224442 -309.095648)
		(end 174.041562 -308.912768)
		(width 0.18288)
		(layer "In4.Cu")
		(net "M_G_CPU1_SA_DQ<5>")
	)
	(segment
		(start 178.22418 -308.680612)
		(end 178.22418 -308.454552)
		(width 0.18288)
		(layer "In4.Cu")
		(net "M_G_CPU1_SA_DQ<5>")
	)
	(segment
		(start 178.069748 -309.061104)
		(end 178.069748 -308.835044)
		(width 0.18288)
		(layer "In4.Cu")
		(net "M_G_CPU1_SA_DQ<5>")
	)
	(arc
		(start 134.11835 -273.12874)
		(mid 133.844151 -273.204575)
		(end 133.567678 -273.137376)
		(width 0.088646)
		(layer "In4.Cu")
		(net "M_G_CPU1_SA_DQ<5>")
	)
	(arc
		(start 137.969244 -274.266914)
		(mid 137.921565 -274.084014)
		(end 137.790682 -273.947636)
		(width 0.088646)
		(layer "In4.Cu")
		(net "M_G_CPU1_SA_DQ<5>")
	)
	(arc
		(start 135.432546 -273.12874)
		(mid 135.245348 -273.078597)
		(end 135.05815 -273.12874)
		(width 0.088646)
		(layer "In4.Cu")
		(net "M_G_CPU1_SA_DQ<5>")
	)
	(arc
		(start 131.203192 -273.942556)
		(mid 131.013679 -273.763591)
		(end 130.924554 -273.51863)
		(width 0.088646)
		(layer "In4.Cu")
		(net "M_G_CPU1_SA_DQ<5>")
	)
	(arc
		(start 136.559544 -273.453098)
		(mid 136.511865 -273.270198)
		(end 136.380982 -273.13382)
		(width 0.088646)
		(layer "In4.Cu")
		(net "M_G_CPU1_SA_DQ<5>")
	)
	(arc
		(start 137.407396 -273.942556)
		(mid 137.124694 -274.018332)
		(end 136.841992 -273.942556)
		(width 0.088646)
		(layer "In4.Cu")
		(net "M_G_CPU1_SA_DQ<5>")
	)
	(arc
		(start 138.251946 -274.756626)
		(mid 138.048465 -274.555822)
		(end 137.969244 -274.281138)
		(width 0.088646)
		(layer "In4.Cu")
		(net "M_G_CPU1_SA_DQ<5>")
	)
	(arc
		(start 137.781792 -273.942556)
		(mid 137.594594 -273.892413)
		(end 137.407396 -273.942556)
		(width 0.088646)
		(layer "In4.Cu")
		(net "M_G_CPU1_SA_DQ<5>")
	)
	(arc
		(start 132.613146 -273.12874)
		(mid 132.425948 -273.078597)
		(end 132.23875 -273.12874)
		(width 0.088646)
		(layer "In4.Cu")
		(net "M_G_CPU1_SA_DQ<5>")
	)
	(arc
		(start 136.372092 -273.12874)
		(mid 136.184894 -273.078597)
		(end 135.997696 -273.12874)
		(width 0.088646)
		(layer "In4.Cu")
		(net "M_G_CPU1_SA_DQ<5>")
	)
	(arc
		(start 132.051298 -273.453098)
		(mid 131.977307 -273.732664)
		(end 131.774692 -273.939)
		(width 0.088646)
		(layer "In4.Cu")
		(net "M_G_CPU1_SA_DQ<5>")
	)
	(arc
		(start 132.22986 -273.13382)
		(mid 132.098946 -273.27018)
		(end 132.051298 -273.453098)
		(width 0.088646)
		(layer "In4.Cu")
		(net "M_G_CPU1_SA_DQ<5>")
	)
	(arc
		(start 138.618976 -275.494496)
		(mid 138.489201 -275.313526)
		(end 138.439398 -275.096478)
		(width 0.088646)
		(layer "In4.Cu")
		(net "M_G_CPU1_SA_DQ<5>")
	)
	(arc
		(start 135.05815 -273.12874)
		(mid 134.783951 -273.204575)
		(end 134.507478 -273.137376)
		(width 0.088646)
		(layer "In4.Cu")
		(net "M_G_CPU1_SA_DQ<5>")
	)
	(arc
		(start 138.439398 -275.080984)
		(mid 138.391719 -274.898084)
		(end 138.260836 -274.761706)
		(width 0.088646)
		(layer "In4.Cu")
		(net "M_G_CPU1_SA_DQ<5>")
	)
	(arc
		(start 133.552946 -273.12874)
		(mid 133.365748 -273.078597)
		(end 133.17855 -273.12874)
		(width 0.088646)
		(layer "In4.Cu")
		(net "M_G_CPU1_SA_DQ<5>")
	)
	(arc
		(start 136.841992 -273.942556)
		(mid 136.637657 -273.739951)
		(end 136.559544 -273.463004)
		(width 0.088646)
		(layer "In4.Cu")
		(net "M_G_CPU1_SA_DQ<5>")
	)
	(arc
		(start 134.492746 -273.12874)
		(mid 134.305548 -273.078597)
		(end 134.11835 -273.12874)
		(width 0.088646)
		(layer "In4.Cu")
		(net "M_G_CPU1_SA_DQ<5>")
	)
	(arc
		(start 133.17855 -273.12874)
		(mid 132.904351 -273.204575)
		(end 132.627878 -273.137376)
		(width 0.088646)
		(layer "In4.Cu")
		(net "M_G_CPU1_SA_DQ<5>")
	)
	(arc
		(start 135.997696 -273.12874)
		(mid 135.721137 -273.204483)
		(end 135.44296 -273.134836)
		(width 0.088646)
		(layer "In4.Cu")
		(net "M_G_CPU1_SA_DQ<5>")
	)
	(arc
		(start 131.753864 -273.951192)
		(mid 131.477389 -274.018512)
		(end 131.203192 -273.942556)
		(width 0.088646)
		(layer "In4.Cu")
		(net "M_G_CPU1_SA_DQ<5>")
	)
	(segment
		(start 191.421004 -310.42737)
		(end 191.233044 -310.61533)
		(width 0.20066)
		(layer "F.Cu")
		(net "M_G_CPU1_SA_DQ<4>")
	)
	(segment
		(start 194.940428 -310.366918)
		(end 194.508882 -309.935372)
		(width 0.20066)
		(layer "F.Cu")
		(net "M_G_CPU1_SA_DQ<4>")
	)
	(segment
		(start 190.509144 -310.366664)
		(end 188.988446 -310.366664)
		(width 0.20066)
		(layer "F.Cu")
		(net "M_G_CPU1_SA_DQ<4>")
	)
	(segment
		(start 188.988446 -310.366664)
		(end 187.883546 -310.366664)
		(width 0.20066)
		(layer "F.Cu")
		(net "M_G_CPU1_SA_DQ<4>")
	)
	(segment
		(start 130.076448 -274.26666)
		(end 130.076194 -274.266914)
		(width 0.20066)
		(layer "F.Cu")
		(net "M_G_CPU1_SA_DQ<4>")
	)
	(segment
		(start 191.883792 -309.941722)
		(end 191.539114 -309.941722)
		(width 0.20066)
		(layer "F.Cu")
		(net "M_G_CPU1_SA_DQ<4>")
	)
	(segment
		(start 190.75781 -310.61533)
		(end 190.509144 -310.366664)
		(width 0.20066)
		(layer "F.Cu")
		(net "M_G_CPU1_SA_DQ<4>")
	)
	(segment
		(start 194.508882 -309.935372)
		(end 194.098926 -309.935372)
		(width 0.20066)
		(layer "F.Cu")
		(net "M_G_CPU1_SA_DQ<4>")
	)
	(segment
		(start 191.539114 -309.941722)
		(end 191.421004 -310.059832)
		(width 0.20066)
		(layer "F.Cu")
		(net "M_G_CPU1_SA_DQ<4>")
	)
	(segment
		(start 191.930782 -309.941722)
		(end 191.883792 -309.941722)
		(width 0.101854)
		(layer "F.Cu")
		(net "M_G_CPU1_SA_DQ<4>")
	)
	(segment
		(start 196.532246 -310.366664)
		(end 196.531992 -310.366918)
		(width 0.20066)
		(layer "F.Cu")
		(net "M_G_CPU1_SA_DQ<4>")
	)
	(segment
		(start 196.531992 -310.366918)
		(end 194.940428 -310.366918)
		(width 0.20066)
		(layer "F.Cu")
		(net "M_G_CPU1_SA_DQ<4>")
	)
	(segment
		(start 130.076448 -273.730974)
		(end 130.076448 -274.26666)
		(width 0.20066)
		(layer "F.Cu")
		(net "M_G_CPU1_SA_DQ<4>")
	)
	(segment
		(start 194.092576 -309.941722)
		(end 191.930782 -309.941722)
		(width 0.1016)
		(layer "F.Cu")
		(net "M_G_CPU1_SA_DQ<4>")
	)
	(segment
		(start 191.421004 -310.059832)
		(end 191.421004 -310.42737)
		(width 0.20066)
		(layer "F.Cu")
		(net "M_G_CPU1_SA_DQ<4>")
	)
	(segment
		(start 194.098926 -309.935372)
		(end 194.092576 -309.941722)
		(width 0.1016)
		(layer "F.Cu")
		(net "M_G_CPU1_SA_DQ<4>")
	)
	(segment
		(start 191.233044 -310.61533)
		(end 190.75781 -310.61533)
		(width 0.20066)
		(layer "F.Cu")
		(net "M_G_CPU1_SA_DQ<4>")
	)
	(segment
		(start 181.722776 -310.962802)
		(end 181.722776 -311.189624)
		(width 0.18288)
		(layer "In4.Cu")
		(net "M_G_CPU1_SA_DQ<4>")
	)
	(segment
		(start 134.967218 -273.94535)
		(end 134.962646 -273.942556)
		(width 0.088646)
		(layer "In4.Cu")
		(net "M_G_CPU1_SA_DQ<4>")
	)
	(segment
		(start 165.228778 -309.940452)
		(end 163.816792 -309.940452)
		(width 0.18288)
		(layer "In4.Cu")
		(net "M_G_CPU1_SA_DQ<4>")
	)
	(segment
		(start 178.413918 -311.347612)
		(end 177.855118 -310.788812)
		(width 0.18288)
		(layer "In4.Cu")
		(net "M_G_CPU1_SA_DQ<4>")
	)
	(segment
		(start 170.316906 -311.641236)
		(end 170.097196 -311.421526)
		(width 0.18288)
		(layer "In4.Cu")
		(net "M_G_CPU1_SA_DQ<4>")
	)
	(segment
		(start 131.203446 -274.591526)
		(end 131.198874 -274.594066)
		(width 0.088646)
		(layer "In4.Cu")
		(net "M_G_CPU1_SA_DQ<4>")
	)
	(segment
		(start 167.981376 -310.665876)
		(end 167.203628 -310.665876)
		(width 0.18288)
		(layer "In4.Cu")
		(net "M_G_CPU1_SA_DQ<4>")
	)
	(segment
		(start 171.45127 -312.489596)
		(end 171.26839 -312.306716)
		(width 0.18288)
		(layer "In4.Cu")
		(net "M_G_CPU1_SA_DQ<4>")
	)
	(segment
		(start 159.426148 -307.15204)
		(end 158.816294 -306.542186)
		(width 0.18288)
		(layer "In4.Cu")
		(net "M_G_CPU1_SA_DQ<4>")
	)
	(segment
		(start 137.321036 -274.761706)
		(end 137.312146 -274.756626)
		(width 0.088646)
		(layer "In4.Cu")
		(net "M_G_CPU1_SA_DQ<4>")
	)
	(segment
		(start 162.887406 -309.300118)
		(end 162.477958 -308.89067)
		(width 0.18288)
		(layer "In4.Cu")
		(net "M_G_CPU1_SA_DQ<4>")
	)
	(segment
		(start 181.539896 -311.372504)
		(end 181.212236 -311.372504)
		(width 0.18288)
		(layer "In4.Cu")
		(net "M_G_CPU1_SA_DQ<4>")
	)
	(segment
		(start 135.902192 -273.942556)
		(end 135.902446 -273.942556)
		(width 0.088646)
		(layer "In4.Cu")
		(net "M_G_CPU1_SA_DQ<4>")
	)
	(segment
		(start 177.855118 -310.788812)
		(end 176.54778 -310.788812)
		(width 0.18288)
		(layer "In4.Cu")
		(net "M_G_CPU1_SA_DQ<4>")
	)
	(segment
		(start 139.039854 -276.63394)
		(end 138.40841 -276.445726)
		(width 0.088646)
		(layer "In4.Cu")
		(net "M_G_CPU1_SA_DQ<4>")
	)
	(segment
		(start 186.971686 -309.869586)
		(end 186.073034 -309.869586)
		(width 0.18288)
		(layer "In4.Cu")
		(net "M_G_CPU1_SA_DQ<4>")
	)
	(segment
		(start 181.212236 -311.372504)
		(end 181.029356 -311.189624)
		(width 0.18288)
		(layer "In4.Cu")
		(net "M_G_CPU1_SA_DQ<4>")
	)
	(segment
		(start 176.54778 -310.788812)
		(end 176.081436 -311.255156)
		(width 0.18288)
		(layer "In4.Cu")
		(net "M_G_CPU1_SA_DQ<4>")
	)
	(segment
		(start 166.680896 -310.143144)
		(end 166.454582 -310.143144)
		(width 0.18288)
		(layer "In4.Cu")
		(net "M_G_CPU1_SA_DQ<4>")
	)
	(segment
		(start 131.210812 -274.587208)
		(end 131.203446 -274.591526)
		(width 0.088646)
		(layer "In4.Cu")
		(net "M_G_CPU1_SA_DQ<4>")
	)
	(segment
		(start 174.327312 -311.641236)
		(end 174.144432 -311.824116)
		(width 0.18288)
		(layer "In4.Cu")
		(net "M_G_CPU1_SA_DQ<4>")
	)
	(segment
		(start 176.081436 -311.458356)
		(end 175.898556 -311.641236)
		(width 0.18288)
		(layer "In4.Cu")
		(net "M_G_CPU1_SA_DQ<4>")
	)
	(segment
		(start 179.37734 -311.347612)
		(end 178.413918 -311.347612)
		(width 0.18288)
		(layer "In4.Cu")
		(net "M_G_CPU1_SA_DQ<4>")
	)
	(segment
		(start 173.961552 -312.810906)
		(end 173.633892 -312.810906)
		(width 0.18288)
		(layer "In4.Cu")
		(net "M_G_CPU1_SA_DQ<4>")
	)
	(segment
		(start 163.176458 -309.300118)
		(end 162.887406 -309.300118)
		(width 0.18288)
		(layer "In4.Cu")
		(net "M_G_CPU1_SA_DQ<4>")
	)
	(segment
		(start 132.209286 -274.554696)
		(end 132.138674 -274.594066)
		(width 0.088646)
		(layer "In4.Cu")
		(net "M_G_CPU1_SA_DQ<4>")
	)
	(segment
		(start 181.029356 -311.189624)
		(end 181.029356 -310.962802)
		(width 0.18288)
		(layer "In4.Cu")
		(net "M_G_CPU1_SA_DQ<4>")
	)
	(segment
		(start 162.477958 -308.89067)
		(end 162.477958 -308.601618)
		(width 0.18288)
		(layer "In4.Cu")
		(net "M_G_CPU1_SA_DQ<4>")
	)
	(segment
		(start 186.073034 -309.869586)
		(end 185.115962 -310.826658)
		(width 0.18288)
		(layer "In4.Cu")
		(net "M_G_CPU1_SA_DQ<4>")
	)
	(segment
		(start 154.94762 -304.284634)
		(end 149.296374 -295.827958)
		(width 0.18288)
		(layer "In4.Cu")
		(net "M_G_CPU1_SA_DQ<4>")
	)
	(segment
		(start 181.905656 -310.779922)
		(end 181.722776 -310.962802)
		(width 0.18288)
		(layer "In4.Cu")
		(net "M_G_CPU1_SA_DQ<4>")
	)
	(segment
		(start 130.828796 -274.591526)
		(end 130.432302 -274.362418)
		(width 0.088646)
		(layer "In4.Cu")
		(net "M_G_CPU1_SA_DQ<4>")
	)
	(segment
		(start 168.737026 -311.421526)
		(end 167.981376 -310.665876)
		(width 0.18288)
		(layer "In4.Cu")
		(net "M_G_CPU1_SA_DQ<4>")
	)
	(segment
		(start 173.633892 -312.810906)
		(end 173.451012 -312.628026)
		(width 0.18288)
		(layer "In4.Cu")
		(net "M_G_CPU1_SA_DQ<4>")
	)
	(segment
		(start 134.022846 -273.942556)
		(end 134.017004 -273.939254)
		(width 0.088646)
		(layer "In4.Cu")
		(net "M_G_CPU1_SA_DQ<4>")
	)
	(segment
		(start 171.77893 -312.489596)
		(end 171.45127 -312.489596)
		(width 0.18288)
		(layer "In4.Cu")
		(net "M_G_CPU1_SA_DQ<4>")
	)
	(segment
		(start 174.144432 -311.824116)
		(end 174.144432 -312.628026)
		(width 0.18288)
		(layer "In4.Cu")
		(net "M_G_CPU1_SA_DQ<4>")
	)
	(segment
		(start 181.722776 -311.189624)
		(end 181.539896 -311.372504)
		(width 0.18288)
		(layer "In4.Cu")
		(net "M_G_CPU1_SA_DQ<4>")
	)
	(segment
		(start 158.816294 -306.542186)
		(end 157.439106 -306.542186)
		(width 0.18288)
		(layer "In4.Cu")
		(net "M_G_CPU1_SA_DQ<4>")
	)
	(segment
		(start 135.911082 -273.947636)
		(end 135.902192 -273.942556)
		(width 0.088646)
		(layer "In4.Cu")
		(net "M_G_CPU1_SA_DQ<4>")
	)
	(segment
		(start 173.268132 -311.641236)
		(end 172.14469 -311.641236)
		(width 0.18288)
		(layer "In4.Cu")
		(net "M_G_CPU1_SA_DQ<4>")
	)
	(segment
		(start 137.790682 -275.575522)
		(end 137.781792 -275.570442)
		(width 0.088646)
		(layer "In4.Cu")
		(net "M_G_CPU1_SA_DQ<4>")
	)
	(segment
		(start 166.454582 -310.143144)
		(end 166.0779 -310.519826)
		(width 0.18288)
		(layer "In4.Cu")
		(net "M_G_CPU1_SA_DQ<4>")
	)
	(segment
		(start 185.115962 -310.826658)
		(end 183.52897 -310.826658)
		(width 0.18288)
		(layer "In4.Cu")
		(net "M_G_CPU1_SA_DQ<4>")
	)
	(segment
		(start 165.808152 -310.519826)
		(end 165.228778 -309.940452)
		(width 0.18288)
		(layer "In4.Cu")
		(net "M_G_CPU1_SA_DQ<4>")
	)
	(segment
		(start 179.976526 -310.748426)
		(end 179.37734 -311.347612)
		(width 0.18288)
		(layer "In4.Cu")
		(net "M_G_CPU1_SA_DQ<4>")
	)
	(segment
		(start 180.81498 -310.748426)
		(end 179.976526 -310.748426)
		(width 0.18288)
		(layer "In4.Cu")
		(net "M_G_CPU1_SA_DQ<4>")
	)
	(segment
		(start 162.080956 -308.204616)
		(end 161.428684 -308.204616)
		(width 0.18288)
		(layer "In4.Cu")
		(net "M_G_CPU1_SA_DQ<4>")
	)
	(segment
		(start 167.203628 -310.665876)
		(end 166.680896 -310.143144)
		(width 0.18288)
		(layer "In4.Cu")
		(net "M_G_CPU1_SA_DQ<4>")
	)
	(segment
		(start 171.26839 -312.306716)
		(end 171.26839 -311.824116)
		(width 0.18288)
		(layer "In4.Cu")
		(net "M_G_CPU1_SA_DQ<4>")
	)
	(segment
		(start 162.477958 -308.601618)
		(end 162.080956 -308.204616)
		(width 0.18288)
		(layer "In4.Cu")
		(net "M_G_CPU1_SA_DQ<4>")
	)
	(segment
		(start 133.088888 -273.946112)
		(end 133.083046 -273.942556)
		(width 0.088646)
		(layer "In4.Cu")
		(net "M_G_CPU1_SA_DQ<4>")
	)
	(segment
		(start 143.624046 -282.134564)
		(end 142.975838 -280.569924)
		(width 0.18288)
		(layer "In4.Cu")
		(net "M_G_CPU1_SA_DQ<4>")
	)
	(segment
		(start 163.816792 -309.940452)
		(end 163.176458 -309.300118)
		(width 0.18288)
		(layer "In4.Cu")
		(net "M_G_CPU1_SA_DQ<4>")
	)
	(segment
		(start 133.083046 -273.942556)
		(end 133.077204 -273.939254)
		(width 0.088646)
		(layer "In4.Cu")
		(net "M_G_CPU1_SA_DQ<4>")
	)
	(segment
		(start 134.028688 -273.946112)
		(end 134.022846 -273.942556)
		(width 0.088646)
		(layer "In4.Cu")
		(net "M_G_CPU1_SA_DQ<4>")
	)
	(segment
		(start 137.499598 -275.096478)
		(end 137.499598 -275.080984)
		(width 0.088646)
		(layer "In4.Cu")
		(net "M_G_CPU1_SA_DQ<4>")
	)
	(segment
		(start 171.08551 -311.641236)
		(end 170.316906 -311.641236)
		(width 0.18288)
		(layer "In4.Cu")
		(net "M_G_CPU1_SA_DQ<4>")
	)
	(segment
		(start 137.969244 -275.904706)
		(end 137.969244 -275.8948)
		(width 0.088646)
		(layer "In4.Cu")
		(net "M_G_CPU1_SA_DQ<4>")
	)
	(segment
		(start 183.482234 -310.779922)
		(end 181.905656 -310.779922)
		(width 0.18288)
		(layer "In4.Cu")
		(net "M_G_CPU1_SA_DQ<4>")
	)
	(segment
		(start 183.52897 -310.826658)
		(end 183.482234 -310.779922)
		(width 0.18288)
		(layer "In4.Cu")
		(net "M_G_CPU1_SA_DQ<4>")
	)
	(segment
		(start 160.376108 -307.15204)
		(end 159.426148 -307.15204)
		(width 0.18288)
		(layer "In4.Cu")
		(net "M_G_CPU1_SA_DQ<4>")
	)
	(segment
		(start 172.14469 -311.641236)
		(end 171.96181 -311.824116)
		(width 0.18288)
		(layer "In4.Cu")
		(net "M_G_CPU1_SA_DQ<4>")
	)
	(segment
		(start 176.081436 -311.255156)
		(end 176.081436 -311.458356)
		(width 0.18288)
		(layer "In4.Cu")
		(net "M_G_CPU1_SA_DQ<4>")
	)
	(segment
		(start 132.576062 -274.068286)
		(end 132.330444 -274.447762)
		(width 0.088646)
		(layer "In4.Cu")
		(net "M_G_CPU1_SA_DQ<4>")
	)
	(segment
		(start 136.387078 -274.765262)
		(end 136.372346 -274.756626)
		(width 0.088646)
		(layer "In4.Cu")
		(net "M_G_CPU1_SA_DQ<4>")
	)
	(segment
		(start 171.26839 -311.824116)
		(end 171.08551 -311.641236)
		(width 0.18288)
		(layer "In4.Cu")
		(net "M_G_CPU1_SA_DQ<4>")
	)
	(segment
		(start 171.96181 -311.824116)
		(end 171.96181 -312.306716)
		(width 0.18288)
		(layer "In4.Cu")
		(net "M_G_CPU1_SA_DQ<4>")
	)
	(segment
		(start 173.451012 -311.824116)
		(end 173.268132 -311.641236)
		(width 0.18288)
		(layer "In4.Cu")
		(net "M_G_CPU1_SA_DQ<4>")
	)
	(segment
		(start 173.451012 -312.628026)
		(end 173.451012 -311.824116)
		(width 0.18288)
		(layer "In4.Cu")
		(net "M_G_CPU1_SA_DQ<4>")
	)
	(segment
		(start 174.144432 -312.628026)
		(end 173.961552 -312.810906)
		(width 0.18288)
		(layer "In4.Cu")
		(net "M_G_CPU1_SA_DQ<4>")
	)
	(segment
		(start 134.962646 -273.942556)
		(end 134.956804 -273.939254)
		(width 0.088646)
		(layer "In4.Cu")
		(net "M_G_CPU1_SA_DQ<4>")
	)
	(segment
		(start 166.0779 -310.519826)
		(end 165.808152 -310.519826)
		(width 0.18288)
		(layer "In4.Cu")
		(net "M_G_CPU1_SA_DQ<4>")
	)
	(segment
		(start 170.097196 -311.421526)
		(end 168.737026 -311.421526)
		(width 0.18288)
		(layer "In4.Cu")
		(net "M_G_CPU1_SA_DQ<4>")
	)
	(segment
		(start 136.089644 -274.281138)
		(end 136.089644 -274.266914)
		(width 0.088646)
		(layer "In4.Cu")
		(net "M_G_CPU1_SA_DQ<4>")
	)
	(segment
		(start 187.38469 -309.869078)
		(end 186.971686 -309.869586)
		(width 0.18288)
		(layer "In4.Cu")
		(net "M_G_CPU1_SA_DQ<4>")
	)
	(segment
		(start 157.439106 -306.542186)
		(end 154.94762 -304.284634)
		(width 0.18288)
		(layer "In4.Cu")
		(net "M_G_CPU1_SA_DQ<4>")
	)
	(segment
		(start 139.600178 -277.194264)
		(end 139.039854 -276.63394)
		(width 0.088646)
		(layer "In4.Cu")
		(net "M_G_CPU1_SA_DQ<4>")
	)
	(segment
		(start 142.975838 -280.569924)
		(end 139.600178 -277.194264)
		(width 0.18288)
		(layer "In4.Cu")
		(net "M_G_CPU1_SA_DQ<4>")
	)
	(segment
		(start 149.296374 -295.827958)
		(end 143.624046 -282.134564)
		(width 0.18288)
		(layer "In4.Cu")
		(net "M_G_CPU1_SA_DQ<4>")
	)
	(segment
		(start 181.029356 -310.962802)
		(end 180.81498 -310.748426)
		(width 0.18288)
		(layer "In4.Cu")
		(net "M_G_CPU1_SA_DQ<4>")
	)
	(segment
		(start 161.428684 -308.204616)
		(end 160.376108 -307.15204)
		(width 0.18288)
		(layer "In4.Cu")
		(net "M_G_CPU1_SA_DQ<4>")
	)
	(segment
		(start 175.898556 -311.641236)
		(end 174.327312 -311.641236)
		(width 0.18288)
		(layer "In4.Cu")
		(net "M_G_CPU1_SA_DQ<4>")
	)
	(segment
		(start 171.96181 -312.306716)
		(end 171.77893 -312.489596)
		(width 0.18288)
		(layer "In4.Cu")
		(net "M_G_CPU1_SA_DQ<4>")
	)
	(segment
		(start 187.883546 -310.366664)
		(end 187.38469 -309.869078)
		(width 0.18288)
		(layer "In4.Cu")
		(net "M_G_CPU1_SA_DQ<4>")
	)
	(arc
		(start 131.768596 -274.591526)
		(mid 131.490273 -274.515733)
		(end 131.210812 -274.587208)
		(width 0.088646)
		(layer "In4.Cu")
		(net "M_G_CPU1_SA_DQ<4>")
	)
	(arc
		(start 137.312146 -274.756626)
		(mid 137.124948 -274.706483)
		(end 136.93775 -274.756626)
		(width 0.088646)
		(layer "In4.Cu")
		(net "M_G_CPU1_SA_DQ<4>")
	)
	(arc
		(start 133.077204 -273.939254)
		(mid 132.892349 -273.892304)
		(end 132.708396 -273.942556)
		(width 0.088646)
		(layer "In4.Cu")
		(net "M_G_CPU1_SA_DQ<4>")
	)
	(arc
		(start 136.372346 -274.756626)
		(mid 136.168865 -274.555822)
		(end 136.089644 -274.281138)
		(width 0.088646)
		(layer "In4.Cu")
		(net "M_G_CPU1_SA_DQ<4>")
	)
	(arc
		(start 136.93775 -274.756626)
		(mid 136.663521 -274.832551)
		(end 136.387078 -274.765262)
		(width 0.088646)
		(layer "In4.Cu")
		(net "M_G_CPU1_SA_DQ<4>")
	)
	(arc
		(start 137.781792 -275.570442)
		(mid 137.578969 -275.370211)
		(end 137.499598 -275.096478)
		(width 0.088646)
		(layer "In4.Cu")
		(net "M_G_CPU1_SA_DQ<4>")
	)
	(arc
		(start 138.40841 -276.445726)
		(mid 138.327753 -276.420853)
		(end 138.251692 -276.384258)
		(width 0.088646)
		(layer "In4.Cu")
		(net "M_G_CPU1_SA_DQ<4>")
	)
	(arc
		(start 137.499598 -275.080984)
		(mid 137.451919 -274.898084)
		(end 137.321036 -274.761706)
		(width 0.088646)
		(layer "In4.Cu")
		(net "M_G_CPU1_SA_DQ<4>")
	)
	(arc
		(start 133.648196 -273.942556)
		(mid 133.369022 -274.018321)
		(end 133.088888 -273.946112)
		(width 0.088646)
		(layer "In4.Cu")
		(net "M_G_CPU1_SA_DQ<4>")
	)
	(arc
		(start 132.708396 -273.942556)
		(mid 132.634764 -273.997564)
		(end 132.576062 -274.068286)
		(width 0.088646)
		(layer "In4.Cu")
		(net "M_G_CPU1_SA_DQ<4>")
	)
	(arc
		(start 136.089644 -274.266914)
		(mid 136.041965 -274.084014)
		(end 135.911082 -273.947636)
		(width 0.088646)
		(layer "In4.Cu")
		(net "M_G_CPU1_SA_DQ<4>")
	)
	(arc
		(start 134.956804 -273.939254)
		(mid 134.771949 -273.892304)
		(end 134.587996 -273.942556)
		(width 0.088646)
		(layer "In4.Cu")
		(net "M_G_CPU1_SA_DQ<4>")
	)
	(arc
		(start 134.017004 -273.939254)
		(mid 133.832149 -273.892304)
		(end 133.648196 -273.942556)
		(width 0.088646)
		(layer "In4.Cu")
		(net "M_G_CPU1_SA_DQ<4>")
	)
	(arc
		(start 135.527796 -273.942556)
		(mid 135.247882 -274.018325)
		(end 134.967218 -273.94535)
		(width 0.088646)
		(layer "In4.Cu")
		(net "M_G_CPU1_SA_DQ<4>")
	)
	(arc
		(start 138.251692 -276.384258)
		(mid 138.047357 -276.181653)
		(end 137.969244 -275.904706)
		(width 0.088646)
		(layer "In4.Cu")
		(net "M_G_CPU1_SA_DQ<4>")
	)
	(arc
		(start 132.290566 -274.493228)
		(mid 132.252036 -274.52675)
		(end 132.209286 -274.554696)
		(width 0.088646)
		(layer "In4.Cu")
		(net "M_G_CPU1_SA_DQ<4>")
	)
	(arc
		(start 131.198874 -274.594066)
		(mid 131.013489 -274.641704)
		(end 130.828796 -274.591526)
		(width 0.088646)
		(layer "In4.Cu")
		(net "M_G_CPU1_SA_DQ<4>")
	)
	(arc
		(start 130.432302 -274.362418)
		(mid 130.260535 -274.291234)
		(end 130.076194 -274.266914)
		(width 0.088646)
		(layer "In4.Cu")
		(net "M_G_CPU1_SA_DQ<4>")
	)
	(arc
		(start 134.587996 -273.942556)
		(mid 134.308822 -274.018321)
		(end 134.028688 -273.946112)
		(width 0.088646)
		(layer "In4.Cu")
		(net "M_G_CPU1_SA_DQ<4>")
	)
	(arc
		(start 137.969244 -275.8948)
		(mid 137.921565 -275.7119)
		(end 137.790682 -275.575522)
		(width 0.088646)
		(layer "In4.Cu")
		(net "M_G_CPU1_SA_DQ<4>")
	)
	(arc
		(start 132.138674 -274.594066)
		(mid 131.953289 -274.641704)
		(end 131.768596 -274.591526)
		(width 0.088646)
		(layer "In4.Cu")
		(net "M_G_CPU1_SA_DQ<4>")
	)
	(arc
		(start 135.902446 -273.942556)
		(mid 135.715138 -273.892413)
		(end 135.527796 -273.942556)
		(width 0.088646)
		(layer "In4.Cu")
		(net "M_G_CPU1_SA_DQ<4>")
	)
	(arc
		(start 132.330444 -274.447762)
		(mid 132.311228 -274.471129)
		(end 132.290566 -274.493228)
		(width 0.088646)
		(layer "In4.Cu")
		(net "M_G_CPU1_SA_DQ<4>")
	)
	(segment
		(start 194.786758 -313.766708)
		(end 195.218812 -314.198762)
		(width 0.20066)
		(layer "F.Cu")
		(net "M_G_CPU1_SA_DQ<3>")
	)
	(segment
		(start 193.088514 -313.766708)
		(end 194.786758 -313.766708)
		(width 0.20066)
		(layer "F.Cu")
		(net "M_G_CPU1_SA_DQ<3>")
	)
	(segment
		(start 199.046084 -313.51474)
		(end 199.298052 -313.766708)
		(width 0.20066)
		(layer "F.Cu")
		(net "M_G_CPU1_SA_DQ<3>")
	)
	(segment
		(start 198.662036 -313.51474)
		(end 199.046084 -313.51474)
		(width 0.20066)
		(layer "F.Cu")
		(net "M_G_CPU1_SA_DQ<3>")
	)
	(segment
		(start 195.218812 -314.198762)
		(end 195.510658 -314.198762)
		(width 0.20066)
		(layer "F.Cu")
		(net "M_G_CPU1_SA_DQ<3>")
	)
	(segment
		(start 198.427848 -313.99988)
		(end 198.427848 -313.748928)
		(width 0.20066)
		(layer "F.Cu")
		(net "M_G_CPU1_SA_DQ<3>")
	)
	(segment
		(start 195.515484 -314.198762)
		(end 195.522596 -314.19165)
		(width 0.1016)
		(layer "F.Cu")
		(net "M_G_CPU1_SA_DQ<3>")
	)
	(segment
		(start 198.223886 -314.203842)
		(end 198.427848 -313.99988)
		(width 0.20066)
		(layer "F.Cu")
		(net "M_G_CPU1_SA_DQ<3>")
	)
	(segment
		(start 199.298052 -313.766708)
		(end 200.632314 -313.766708)
		(width 0.20066)
		(layer "F.Cu")
		(net "M_G_CPU1_SA_DQ<3>")
	)
	(segment
		(start 191.983614 -313.766708)
		(end 193.088514 -313.766708)
		(width 0.20066)
		(layer "F.Cu")
		(net "M_G_CPU1_SA_DQ<3>")
	)
	(segment
		(start 131.956048 -275.894546)
		(end 131.955794 -275.8948)
		(width 0.20066)
		(layer "F.Cu")
		(net "M_G_CPU1_SA_DQ<3>")
	)
	(segment
		(start 195.510658 -314.198762)
		(end 195.515484 -314.198762)
		(width 0.101854)
		(layer "F.Cu")
		(net "M_G_CPU1_SA_DQ<3>")
	)
	(segment
		(start 197.542658 -314.203842)
		(end 198.223886 -314.203842)
		(width 0.20066)
		(layer "F.Cu")
		(net "M_G_CPU1_SA_DQ<3>")
	)
	(segment
		(start 197.530466 -314.19165)
		(end 197.542658 -314.203842)
		(width 0.1016)
		(layer "F.Cu")
		(net "M_G_CPU1_SA_DQ<3>")
	)
	(segment
		(start 195.522596 -314.19165)
		(end 197.530466 -314.19165)
		(width 0.1016)
		(layer "F.Cu")
		(net "M_G_CPU1_SA_DQ<3>")
	)
	(segment
		(start 198.427848 -313.748928)
		(end 198.662036 -313.51474)
		(width 0.20066)
		(layer "F.Cu")
		(net "M_G_CPU1_SA_DQ<3>")
	)
	(segment
		(start 131.956048 -275.35886)
		(end 131.956048 -275.894546)
		(width 0.20066)
		(layer "F.Cu")
		(net "M_G_CPU1_SA_DQ<3>")
	)
	(segment
		(start 139.676886 -279.746964)
		(end 139.301728 -279.371806)
		(width 0.088646)
		(layer "In4.Cu")
		(net "M_G_CPU1_SA_DQ<3>")
	)
	(segment
		(start 183.532526 -313.567826)
		(end 182.694326 -314.406026)
		(width 0.18288)
		(layer "In4.Cu")
		(net "M_G_CPU1_SA_DQ<3>")
	)
	(segment
		(start 140.768578 -280.838656)
		(end 139.676886 -279.746964)
		(width 0.18288)
		(layer "In4.Cu")
		(net "M_G_CPU1_SA_DQ<3>")
	)
	(segment
		(start 187.39866 -314.192412)
		(end 186.774074 -313.567826)
		(width 0.18288)
		(layer "In4.Cu")
		(net "M_G_CPU1_SA_DQ<3>")
	)
	(segment
		(start 164.730938 -313.319414)
		(end 164.571426 -313.478926)
		(width 0.18288)
		(layer "In4.Cu")
		(net "M_G_CPU1_SA_DQ<3>")
	)
	(segment
		(start 175.899826 -316.222126)
		(end 174.020226 -316.222126)
		(width 0.18288)
		(layer "In4.Cu")
		(net "M_G_CPU1_SA_DQ<3>")
	)
	(segment
		(start 169.079926 -315.269626)
		(end 168.140126 -314.329826)
		(width 0.18288)
		(layer "In4.Cu")
		(net "M_G_CPU1_SA_DQ<3>")
	)
	(segment
		(start 191.28105 -314.469272)
		(end 189.77864 -314.469272)
		(width 0.18288)
		(layer "In4.Cu")
		(net "M_G_CPU1_SA_DQ<3>")
	)
	(segment
		(start 174.020226 -316.222126)
		(end 173.500288 -316.742064)
		(width 0.18288)
		(layer "In4.Cu")
		(net "M_G_CPU1_SA_DQ<3>")
	)
	(segment
		(start 139.301728 -279.371806)
		(end 138.615674 -279.371806)
		(width 0.088646)
		(layer "In4.Cu")
		(net "M_G_CPU1_SA_DQ<3>")
	)
	(segment
		(start 161.188146 -312.351674)
		(end 160.55975 -311.723278)
		(width 0.18288)
		(layer "In4.Cu")
		(net "M_G_CPU1_SA_DQ<3>")
	)
	(segment
		(start 132.32638 -276.017482)
		(end 131.971796 -275.922486)
		(width 0.088646)
		(layer "In4.Cu")
		(net "M_G_CPU1_SA_DQ<3>")
	)
	(segment
		(start 171.239688 -316.742064)
		(end 169.76725 -315.269626)
		(width 0.18288)
		(layer "In4.Cu")
		(net "M_G_CPU1_SA_DQ<3>")
	)
	(segment
		(start 177.600356 -315.89218)
		(end 176.229772 -315.89218)
		(width 0.18288)
		(layer "In4.Cu")
		(net "M_G_CPU1_SA_DQ<3>")
	)
	(segment
		(start 135.05815 -277.032974)
		(end 135.04926 -277.027894)
		(width 0.088646)
		(layer "In4.Cu")
		(net "M_G_CPU1_SA_DQ<3>")
	)
	(segment
		(start 165.402514 -313.319414)
		(end 164.730938 -313.319414)
		(width 0.18288)
		(layer "In4.Cu")
		(net "M_G_CPU1_SA_DQ<3>")
	)
	(segment
		(start 131.971796 -275.922486)
		(end 131.955794 -275.8948)
		(width 0.088646)
		(layer "In4.Cu")
		(net "M_G_CPU1_SA_DQ<3>")
	)
	(segment
		(start 166.76116 -313.758072)
		(end 165.841172 -313.758072)
		(width 0.18288)
		(layer "In4.Cu")
		(net "M_G_CPU1_SA_DQ<3>")
	)
	(segment
		(start 176.229772 -315.89218)
		(end 175.899826 -316.222126)
		(width 0.18288)
		(layer "In4.Cu")
		(net "M_G_CPU1_SA_DQ<3>")
	)
	(segment
		(start 167.332914 -314.329826)
		(end 166.76116 -313.758072)
		(width 0.18288)
		(layer "In4.Cu")
		(net "M_G_CPU1_SA_DQ<3>")
	)
	(segment
		(start 158.09087 -310.11241)
		(end 156.754068 -310.11241)
		(width 0.18288)
		(layer "In4.Cu")
		(net "M_G_CPU1_SA_DQ<3>")
	)
	(segment
		(start 136.750044 -278.336502)
		(end 136.750044 -278.31796)
		(width 0.088646)
		(layer "In4.Cu")
		(net "M_G_CPU1_SA_DQ<3>")
	)
	(segment
		(start 191.983614 -313.766708)
		(end 191.28105 -314.469272)
		(width 0.18288)
		(layer "In4.Cu")
		(net "M_G_CPU1_SA_DQ<3>")
	)
	(segment
		(start 134.594092 -276.222714)
		(end 134.587996 -276.219158)
		(width 0.088646)
		(layer "In4.Cu")
		(net "M_G_CPU1_SA_DQ<3>")
	)
	(segment
		(start 178.34991 -315.142626)
		(end 177.600356 -315.89218)
		(width 0.18288)
		(layer "In4.Cu")
		(net "M_G_CPU1_SA_DQ<3>")
	)
	(segment
		(start 141.984476 -283.774134)
		(end 140.768578 -280.838656)
		(width 0.18288)
		(layer "In4.Cu")
		(net "M_G_CPU1_SA_DQ<3>")
	)
	(segment
		(start 168.140126 -314.329826)
		(end 167.332914 -314.329826)
		(width 0.18288)
		(layer "In4.Cu")
		(net "M_G_CPU1_SA_DQ<3>")
	)
	(segment
		(start 169.76725 -315.269626)
		(end 169.079926 -315.269626)
		(width 0.18288)
		(layer "In4.Cu")
		(net "M_G_CPU1_SA_DQ<3>")
	)
	(segment
		(start 133.648196 -276.219158)
		(end 133.633464 -276.210522)
		(width 0.088646)
		(layer "In4.Cu")
		(net "M_G_CPU1_SA_DQ<3>")
	)
	(segment
		(start 179.265326 -315.142626)
		(end 178.34991 -315.142626)
		(width 0.18288)
		(layer "In4.Cu")
		(net "M_G_CPU1_SA_DQ<3>")
	)
	(segment
		(start 136.467596 -277.84679)
		(end 136.458706 -277.84171)
		(width 0.088646)
		(layer "In4.Cu")
		(net "M_G_CPU1_SA_DQ<3>")
	)
	(segment
		(start 159.701738 -311.723278)
		(end 158.09087 -310.11241)
		(width 0.18288)
		(layer "In4.Cu")
		(net "M_G_CPU1_SA_DQ<3>")
	)
	(segment
		(start 138.615674 -279.371806)
		(end 137.99439 -278.750522)
		(width 0.088646)
		(layer "In4.Cu")
		(net "M_G_CPU1_SA_DQ<3>")
	)
	(segment
		(start 189.77864 -314.469272)
		(end 189.50178 -314.192412)
		(width 0.18288)
		(layer "In4.Cu")
		(net "M_G_CPU1_SA_DQ<3>")
	)
	(segment
		(start 163.631626 -313.478926)
		(end 162.504374 -312.351674)
		(width 0.18288)
		(layer "In4.Cu")
		(net "M_G_CPU1_SA_DQ<3>")
	)
	(segment
		(start 154.591258 -307.9496)
		(end 147.769326 -297.739816)
		(width 0.18288)
		(layer "In4.Cu")
		(net "M_G_CPU1_SA_DQ<3>")
	)
	(segment
		(start 165.841172 -313.758072)
		(end 165.402514 -313.319414)
		(width 0.18288)
		(layer "In4.Cu")
		(net "M_G_CPU1_SA_DQ<3>")
	)
	(segment
		(start 164.571426 -313.478926)
		(end 163.631626 -313.478926)
		(width 0.18288)
		(layer "In4.Cu")
		(net "M_G_CPU1_SA_DQ<3>")
	)
	(segment
		(start 136.280144 -277.522432)
		(end 136.280144 -277.512526)
		(width 0.088646)
		(layer "In4.Cu")
		(net "M_G_CPU1_SA_DQ<3>")
	)
	(segment
		(start 180.001926 -314.406026)
		(end 179.265326 -315.142626)
		(width 0.18288)
		(layer "In4.Cu")
		(net "M_G_CPU1_SA_DQ<3>")
	)
	(segment
		(start 135.44296 -277.026878)
		(end 135.432546 -277.032974)
		(width 0.088646)
		(layer "In4.Cu")
		(net "M_G_CPU1_SA_DQ<3>")
	)
	(segment
		(start 156.754068 -310.11241)
		(end 154.591258 -307.9496)
		(width 0.18288)
		(layer "In4.Cu")
		(net "M_G_CPU1_SA_DQ<3>")
	)
	(segment
		(start 189.50178 -314.192412)
		(end 187.39866 -314.192412)
		(width 0.18288)
		(layer "In4.Cu")
		(net "M_G_CPU1_SA_DQ<3>")
	)
	(segment
		(start 136.937496 -278.66086)
		(end 136.928606 -278.65578)
		(width 0.088646)
		(layer "In4.Cu")
		(net "M_G_CPU1_SA_DQ<3>")
	)
	(segment
		(start 147.769326 -297.739816)
		(end 141.984476 -283.774134)
		(width 0.18288)
		(layer "In4.Cu")
		(net "M_G_CPU1_SA_DQ<3>")
	)
	(segment
		(start 182.694326 -314.406026)
		(end 180.001926 -314.406026)
		(width 0.18288)
		(layer "In4.Cu")
		(net "M_G_CPU1_SA_DQ<3>")
	)
	(segment
		(start 162.504374 -312.351674)
		(end 161.188146 -312.351674)
		(width 0.18288)
		(layer "In4.Cu")
		(net "M_G_CPU1_SA_DQ<3>")
	)
	(segment
		(start 186.774074 -313.567826)
		(end 183.532526 -313.567826)
		(width 0.18288)
		(layer "In4.Cu")
		(net "M_G_CPU1_SA_DQ<3>")
	)
	(segment
		(start 173.500288 -316.742064)
		(end 171.239688 -316.742064)
		(width 0.18288)
		(layer "In4.Cu")
		(net "M_G_CPU1_SA_DQ<3>")
	)
	(segment
		(start 160.55975 -311.723278)
		(end 159.701738 -311.723278)
		(width 0.18288)
		(layer "In4.Cu")
		(net "M_G_CPU1_SA_DQ<3>")
	)
	(segment
		(start 132.708396 -276.219158)
		(end 132.442966 -276.065996)
		(width 0.088646)
		(layer "In4.Cu")
		(net "M_G_CPU1_SA_DQ<3>")
	)
	(segment
		(start 134.587996 -276.219158)
		(end 134.573264 -276.210522)
		(width 0.088646)
		(layer "In4.Cu")
		(net "M_G_CPU1_SA_DQ<3>")
	)
	(arc
		(start 134.870698 -276.708616)
		(mid 134.796707 -276.42905)
		(end 134.594092 -276.222714)
		(width 0.088646)
		(layer "In4.Cu")
		(net "M_G_CPU1_SA_DQ<3>")
	)
	(arc
		(start 136.280144 -277.512526)
		(mid 136.202033 -277.235577)
		(end 135.997696 -277.032974)
		(width 0.088646)
		(layer "In4.Cu")
		(net "M_G_CPU1_SA_DQ<3>")
	)
	(arc
		(start 135.432546 -277.032974)
		(mid 135.245348 -277.083117)
		(end 135.05815 -277.032974)
		(width 0.088646)
		(layer "In4.Cu")
		(net "M_G_CPU1_SA_DQ<3>")
	)
	(arc
		(start 134.022592 -276.219158)
		(mid 133.835394 -276.269301)
		(end 133.648196 -276.219158)
		(width 0.088646)
		(layer "In4.Cu")
		(net "M_G_CPU1_SA_DQ<3>")
	)
	(arc
		(start 133.633464 -276.210522)
		(mid 133.356989 -276.143202)
		(end 133.082792 -276.219158)
		(width 0.088646)
		(layer "In4.Cu")
		(net "M_G_CPU1_SA_DQ<3>")
	)
	(arc
		(start 135.997696 -277.032974)
		(mid 135.721137 -276.957231)
		(end 135.44296 -277.026878)
		(width 0.088646)
		(layer "In4.Cu")
		(net "M_G_CPU1_SA_DQ<3>")
	)
	(arc
		(start 136.928606 -278.65578)
		(mid 136.797692 -278.51942)
		(end 136.750044 -278.336502)
		(width 0.088646)
		(layer "In4.Cu")
		(net "M_G_CPU1_SA_DQ<3>")
	)
	(arc
		(start 137.877296 -278.66086)
		(mid 137.594594 -278.585084)
		(end 137.311892 -278.66086)
		(width 0.088646)
		(layer "In4.Cu")
		(net "M_G_CPU1_SA_DQ<3>")
	)
	(arc
		(start 137.311892 -278.66086)
		(mid 137.124694 -278.711003)
		(end 136.937496 -278.66086)
		(width 0.088646)
		(layer "In4.Cu")
		(net "M_G_CPU1_SA_DQ<3>")
	)
	(arc
		(start 137.99439 -278.750522)
		(mid 137.938785 -278.701848)
		(end 137.877296 -278.66086)
		(width 0.088646)
		(layer "In4.Cu")
		(net "M_G_CPU1_SA_DQ<3>")
	)
	(arc
		(start 136.458706 -277.84171)
		(mid 136.327792 -277.70535)
		(end 136.280144 -277.522432)
		(width 0.088646)
		(layer "In4.Cu")
		(net "M_G_CPU1_SA_DQ<3>")
	)
	(arc
		(start 135.04926 -277.027894)
		(mid 134.918346 -276.891534)
		(end 134.870698 -276.708616)
		(width 0.088646)
		(layer "In4.Cu")
		(net "M_G_CPU1_SA_DQ<3>")
	)
	(arc
		(start 133.082792 -276.219158)
		(mid 132.895594 -276.269301)
		(end 132.708396 -276.219158)
		(width 0.088646)
		(layer "In4.Cu")
		(net "M_G_CPU1_SA_DQ<3>")
	)
	(arc
		(start 136.750044 -278.31796)
		(mid 136.669882 -278.045771)
		(end 136.467596 -277.84679)
		(width 0.088646)
		(layer "In4.Cu")
		(net "M_G_CPU1_SA_DQ<3>")
	)
	(arc
		(start 134.573264 -276.210522)
		(mid 134.296789 -276.143202)
		(end 134.022592 -276.219158)
		(width 0.088646)
		(layer "In4.Cu")
		(net "M_G_CPU1_SA_DQ<3>")
	)
	(arc
		(start 132.442966 -276.065996)
		(mid 132.386263 -276.037919)
		(end 132.32638 -276.017482)
		(width 0.088646)
		(layer "In4.Cu")
		(net "M_G_CPU1_SA_DQ<3>")
	)
	(segment
		(start 197.542658 -280.20391)
		(end 198.223886 -280.20391)
		(width 0.20066)
		(layer "F.Cu")
		(net "M_G_CPU1_SA_DQ<31>")
	)
	(segment
		(start 195.515484 -280.19883)
		(end 195.522596 -280.191718)
		(width 0.1016)
		(layer "F.Cu")
		(net "M_G_CPU1_SA_DQ<31>")
	)
	(segment
		(start 195.218812 -280.19883)
		(end 195.510658 -280.19883)
		(width 0.20066)
		(layer "F.Cu")
		(net "M_G_CPU1_SA_DQ<31>")
	)
	(segment
		(start 194.786758 -279.766776)
		(end 195.218812 -280.19883)
		(width 0.20066)
		(layer "F.Cu")
		(net "M_G_CPU1_SA_DQ<31>")
	)
	(segment
		(start 191.983614 -279.766776)
		(end 193.088514 -279.766776)
		(width 0.20066)
		(layer "F.Cu")
		(net "M_G_CPU1_SA_DQ<31>")
	)
	(segment
		(start 198.427848 -279.748996)
		(end 198.662036 -279.514808)
		(width 0.20066)
		(layer "F.Cu")
		(net "M_G_CPU1_SA_DQ<31>")
	)
	(segment
		(start 195.522596 -280.191718)
		(end 197.530466 -280.191718)
		(width 0.1016)
		(layer "F.Cu")
		(net "M_G_CPU1_SA_DQ<31>")
	)
	(segment
		(start 198.427848 -279.999948)
		(end 198.427848 -279.748996)
		(width 0.20066)
		(layer "F.Cu")
		(net "M_G_CPU1_SA_DQ<31>")
	)
	(segment
		(start 197.530466 -280.191718)
		(end 197.542658 -280.20391)
		(width 0.1016)
		(layer "F.Cu")
		(net "M_G_CPU1_SA_DQ<31>")
	)
	(segment
		(start 195.510658 -280.19883)
		(end 195.515484 -280.19883)
		(width 0.101854)
		(layer "F.Cu")
		(net "M_G_CPU1_SA_DQ<31>")
	)
	(segment
		(start 128.196848 -266.127992)
		(end 128.196594 -266.128246)
		(width 0.20066)
		(layer "F.Cu")
		(net "M_G_CPU1_SA_DQ<31>")
	)
	(segment
		(start 198.223886 -280.20391)
		(end 198.427848 -279.999948)
		(width 0.20066)
		(layer "F.Cu")
		(net "M_G_CPU1_SA_DQ<31>")
	)
	(segment
		(start 198.662036 -279.514808)
		(end 199.046084 -279.514808)
		(width 0.20066)
		(layer "F.Cu")
		(net "M_G_CPU1_SA_DQ<31>")
	)
	(segment
		(start 193.088514 -279.766776)
		(end 194.786758 -279.766776)
		(width 0.20066)
		(layer "F.Cu")
		(net "M_G_CPU1_SA_DQ<31>")
	)
	(segment
		(start 128.196848 -265.592306)
		(end 128.196848 -266.127992)
		(width 0.20066)
		(layer "F.Cu")
		(net "M_G_CPU1_SA_DQ<31>")
	)
	(segment
		(start 199.298052 -279.766776)
		(end 200.632314 -279.766776)
		(width 0.20066)
		(layer "F.Cu")
		(net "M_G_CPU1_SA_DQ<31>")
	)
	(segment
		(start 199.046084 -279.514808)
		(end 199.298052 -279.766776)
		(width 0.20066)
		(layer "F.Cu")
		(net "M_G_CPU1_SA_DQ<31>")
	)
	(segment
		(start 189.399926 -279.557226)
		(end 189.185042 -279.342342)
		(width 0.18288)
		(layer "In6.Cu")
		(net "M_G_CPU1_SA_DQ<31>")
	)
	(segment
		(start 178.659536 -277.342854)
		(end 177.259742 -275.94306)
		(width 0.18288)
		(layer "In6.Cu")
		(net "M_G_CPU1_SA_DQ<31>")
	)
	(segment
		(start 167.974518 -270.686276)
		(end 167.65016 -271.010634)
		(width 0.18288)
		(layer "In6.Cu")
		(net "M_G_CPU1_SA_DQ<31>")
	)
	(segment
		(start 190.619126 -280.319226)
		(end 189.59576 -280.319226)
		(width 0.18288)
		(layer "In6.Cu")
		(net "M_G_CPU1_SA_DQ<31>")
	)
	(segment
		(start 178.659536 -277.541228)
		(end 178.659536 -277.342854)
		(width 0.18288)
		(layer "In6.Cu")
		(net "M_G_CPU1_SA_DQ<31>")
	)
	(segment
		(start 190.796926 -280.141426)
		(end 190.619126 -280.319226)
		(width 0.18288)
		(layer "In6.Cu")
		(net "M_G_CPU1_SA_DQ<31>")
	)
	(segment
		(start 131.298696 -265.638788)
		(end 131.292854 -265.635232)
		(width 0.088646)
		(layer "In6.Cu")
		(net "M_G_CPU1_SA_DQ<31>")
	)
	(segment
		(start 135.447278 -265.629898)
		(end 135.432546 -265.638534)
		(width 0.088646)
		(layer "In6.Cu")
		(net "M_G_CPU1_SA_DQ<31>")
	)
	(segment
		(start 140.30452 -265.46556)
		(end 140.131546 -265.638534)
		(width 0.088646)
		(layer "In6.Cu")
		(net "M_G_CPU1_SA_DQ<31>")
	)
	(segment
		(start 176.377092 -275.709634)
		(end 176.377092 -272.052796)
		(width 0.18288)
		(layer "In6.Cu")
		(net "M_G_CPU1_SA_DQ<31>")
	)
	(segment
		(start 129.424938 -265.64209)
		(end 129.419096 -265.638788)
		(width 0.088646)
		(layer "In6.Cu")
		(net "M_G_CPU1_SA_DQ<31>")
	)
	(segment
		(start 189.399926 -280.123392)
		(end 189.399926 -279.557226)
		(width 0.18288)
		(layer "In6.Cu")
		(net "M_G_CPU1_SA_DQ<31>")
	)
	(segment
		(start 160.447228 -270.85671)
		(end 157.090618 -270.85671)
		(width 0.18288)
		(layer "In6.Cu")
		(net "M_G_CPU1_SA_DQ<31>")
	)
	(segment
		(start 134.118096 -265.638788)
		(end 134.112254 -265.635232)
		(width 0.088646)
		(layer "In6.Cu")
		(net "M_G_CPU1_SA_DQ<31>")
	)
	(segment
		(start 140.595604 -265.46556)
		(end 140.30452 -265.46556)
		(width 0.088646)
		(layer "In6.Cu")
		(net "M_G_CPU1_SA_DQ<31>")
	)
	(segment
		(start 190.796926 -279.285446)
		(end 190.796926 -280.141426)
		(width 0.18288)
		(layer "In6.Cu")
		(net "M_G_CPU1_SA_DQ<31>")
	)
	(segment
		(start 134.123938 -265.64209)
		(end 134.118096 -265.638788)
		(width 0.088646)
		(layer "In6.Cu")
		(net "M_G_CPU1_SA_DQ<31>")
	)
	(segment
		(start 135.05815 -265.638534)
		(end 135.052054 -265.635232)
		(width 0.088646)
		(layer "In6.Cu")
		(net "M_G_CPU1_SA_DQ<31>")
	)
	(segment
		(start 157.090618 -270.85671)
		(end 152.21839 -265.984482)
		(width 0.18288)
		(layer "In6.Cu")
		(net "M_G_CPU1_SA_DQ<31>")
	)
	(segment
		(start 190.956946 -279.125426)
		(end 190.796926 -279.285446)
		(width 0.18288)
		(layer "In6.Cu")
		(net "M_G_CPU1_SA_DQ<31>")
	)
	(segment
		(start 161.075878 -270.22806)
		(end 160.447228 -270.85671)
		(width 0.18288)
		(layer "In6.Cu")
		(net "M_G_CPU1_SA_DQ<31>")
	)
	(segment
		(start 132.238496 -265.638788)
		(end 132.232654 -265.635232)
		(width 0.088646)
		(layer "In6.Cu")
		(net "M_G_CPU1_SA_DQ<31>")
	)
	(segment
		(start 189.185042 -279.342342)
		(end 187.708286 -279.342342)
		(width 0.18288)
		(layer "In6.Cu")
		(net "M_G_CPU1_SA_DQ<31>")
	)
	(segment
		(start 189.59576 -280.319226)
		(end 189.399926 -280.123392)
		(width 0.18288)
		(layer "In6.Cu")
		(net "M_G_CPU1_SA_DQ<31>")
	)
	(segment
		(start 191.342264 -279.125426)
		(end 190.956946 -279.125426)
		(width 0.18288)
		(layer "In6.Cu")
		(net "M_G_CPU1_SA_DQ<31>")
	)
	(segment
		(start 177.259742 -275.94306)
		(end 176.610518 -275.94306)
		(width 0.18288)
		(layer "In6.Cu")
		(net "M_G_CPU1_SA_DQ<31>")
	)
	(segment
		(start 130.358896 -265.638788)
		(end 130.353054 -265.635232)
		(width 0.088646)
		(layer "In6.Cu")
		(net "M_G_CPU1_SA_DQ<31>")
	)
	(segment
		(start 176.610518 -275.94306)
		(end 176.377092 -275.709634)
		(width 0.18288)
		(layer "In6.Cu")
		(net "M_G_CPU1_SA_DQ<31>")
	)
	(segment
		(start 169.807382 -270.686276)
		(end 167.974518 -270.686276)
		(width 0.18288)
		(layer "In6.Cu")
		(net "M_G_CPU1_SA_DQ<31>")
	)
	(segment
		(start 184.154826 -279.582626)
		(end 183.247538 -278.675338)
		(width 0.18288)
		(layer "In6.Cu")
		(net "M_G_CPU1_SA_DQ<31>")
	)
	(segment
		(start 176.377092 -272.052796)
		(end 176.015142 -271.690846)
		(width 0.18288)
		(layer "In6.Cu")
		(net "M_G_CPU1_SA_DQ<31>")
	)
	(segment
		(start 129.419096 -265.638788)
		(end 129.413254 -265.635232)
		(width 0.088646)
		(layer "In6.Cu")
		(net "M_G_CPU1_SA_DQ<31>")
	)
	(segment
		(start 131.304538 -265.64209)
		(end 131.298696 -265.638788)
		(width 0.088646)
		(layer "In6.Cu")
		(net "M_G_CPU1_SA_DQ<31>")
	)
	(segment
		(start 139.206478 -265.629898)
		(end 139.191746 -265.638534)
		(width 0.088646)
		(layer "In6.Cu")
		(net "M_G_CPU1_SA_DQ<31>")
	)
	(segment
		(start 176.015142 -271.690846)
		(end 170.811952 -271.690846)
		(width 0.18288)
		(layer "In6.Cu")
		(net "M_G_CPU1_SA_DQ<31>")
	)
	(segment
		(start 137.326878 -265.629898)
		(end 137.312146 -265.638534)
		(width 0.088646)
		(layer "In6.Cu")
		(net "M_G_CPU1_SA_DQ<31>")
	)
	(segment
		(start 164.17544 -270.22806)
		(end 161.075878 -270.22806)
		(width 0.18288)
		(layer "In6.Cu")
		(net "M_G_CPU1_SA_DQ<31>")
	)
	(segment
		(start 170.811952 -271.690846)
		(end 169.807382 -270.686276)
		(width 0.18288)
		(layer "In6.Cu")
		(net "M_G_CPU1_SA_DQ<31>")
	)
	(segment
		(start 136.387078 -265.629898)
		(end 136.372346 -265.638534)
		(width 0.088646)
		(layer "In6.Cu")
		(net "M_G_CPU1_SA_DQ<31>")
	)
	(segment
		(start 133.184138 -265.64209)
		(end 133.178296 -265.638788)
		(width 0.088646)
		(layer "In6.Cu")
		(net "M_G_CPU1_SA_DQ<31>")
	)
	(segment
		(start 152.21839 -265.984482)
		(end 144.997424 -265.984482)
		(width 0.18288)
		(layer "In6.Cu")
		(net "M_G_CPU1_SA_DQ<31>")
	)
	(segment
		(start 138.266678 -265.629898)
		(end 138.251946 -265.638534)
		(width 0.088646)
		(layer "In6.Cu")
		(net "M_G_CPU1_SA_DQ<31>")
	)
	(segment
		(start 183.247538 -278.675338)
		(end 179.793646 -278.675338)
		(width 0.18288)
		(layer "In6.Cu")
		(net "M_G_CPU1_SA_DQ<31>")
	)
	(segment
		(start 179.793646 -278.675338)
		(end 178.659536 -277.541228)
		(width 0.18288)
		(layer "In6.Cu")
		(net "M_G_CPU1_SA_DQ<31>")
	)
	(segment
		(start 191.983614 -279.766776)
		(end 191.342264 -279.125426)
		(width 0.18288)
		(layer "In6.Cu")
		(net "M_G_CPU1_SA_DQ<31>")
	)
	(segment
		(start 187.468002 -279.582626)
		(end 184.154826 -279.582626)
		(width 0.18288)
		(layer "In6.Cu")
		(net "M_G_CPU1_SA_DQ<31>")
	)
	(segment
		(start 130.364738 -265.64209)
		(end 130.358896 -265.638788)
		(width 0.088646)
		(layer "In6.Cu")
		(net "M_G_CPU1_SA_DQ<31>")
	)
	(segment
		(start 128.853946 -265.638788)
		(end 128.775968 -265.683746)
		(width 0.088646)
		(layer "In6.Cu")
		(net "M_G_CPU1_SA_DQ<31>")
	)
	(segment
		(start 164.958014 -271.010634)
		(end 164.17544 -270.22806)
		(width 0.18288)
		(layer "In6.Cu")
		(net "M_G_CPU1_SA_DQ<31>")
	)
	(segment
		(start 142.388082 -265.46556)
		(end 140.595604 -265.46556)
		(width 0.18288)
		(layer "In6.Cu")
		(net "M_G_CPU1_SA_DQ<31>")
	)
	(segment
		(start 187.708286 -279.342342)
		(end 187.468002 -279.582626)
		(width 0.18288)
		(layer "In6.Cu")
		(net "M_G_CPU1_SA_DQ<31>")
	)
	(segment
		(start 132.244338 -265.64209)
		(end 132.238496 -265.638788)
		(width 0.088646)
		(layer "In6.Cu")
		(net "M_G_CPU1_SA_DQ<31>")
	)
	(segment
		(start 144.997424 -265.984482)
		(end 142.388082 -265.46556)
		(width 0.18288)
		(layer "In6.Cu")
		(net "M_G_CPU1_SA_DQ<31>")
	)
	(segment
		(start 128.197102 -266.127738)
		(end 128.196594 -266.128246)
		(width 0.088646)
		(layer "In6.Cu")
		(net "M_G_CPU1_SA_DQ<31>")
	)
	(segment
		(start 133.178296 -265.638788)
		(end 133.172454 -265.635232)
		(width 0.088646)
		(layer "In6.Cu")
		(net "M_G_CPU1_SA_DQ<31>")
	)
	(segment
		(start 167.65016 -271.010634)
		(end 164.958014 -271.010634)
		(width 0.18288)
		(layer "In6.Cu")
		(net "M_G_CPU1_SA_DQ<31>")
	)
	(arc
		(start 140.131546 -265.638534)
		(mid 139.944348 -265.688677)
		(end 139.75715 -265.638534)
		(width 0.088646)
		(layer "In6.Cu")
		(net "M_G_CPU1_SA_DQ<31>")
	)
	(arc
		(start 139.75715 -265.638534)
		(mid 139.482921 -265.562609)
		(end 139.206478 -265.629898)
		(width 0.088646)
		(layer "In6.Cu")
		(net "M_G_CPU1_SA_DQ<31>")
	)
	(arc
		(start 135.432546 -265.638534)
		(mid 135.245348 -265.688677)
		(end 135.05815 -265.638534)
		(width 0.088646)
		(layer "In6.Cu")
		(net "M_G_CPU1_SA_DQ<31>")
	)
	(arc
		(start 130.353054 -265.635232)
		(mid 130.072919 -265.562949)
		(end 129.793746 -265.638788)
		(width 0.088646)
		(layer "In6.Cu")
		(net "M_G_CPU1_SA_DQ<31>")
	)
	(arc
		(start 128.775968 -265.683746)
		(mid 128.471902 -265.886664)
		(end 128.197102 -266.127738)
		(width 0.088646)
		(layer "In6.Cu")
		(net "M_G_CPU1_SA_DQ<31>")
	)
	(arc
		(start 134.492746 -265.638788)
		(mid 134.308792 -265.688883)
		(end 134.123938 -265.64209)
		(width 0.088646)
		(layer "In6.Cu")
		(net "M_G_CPU1_SA_DQ<31>")
	)
	(arc
		(start 137.312146 -265.638534)
		(mid 137.124948 -265.688677)
		(end 136.93775 -265.638534)
		(width 0.088646)
		(layer "In6.Cu")
		(net "M_G_CPU1_SA_DQ<31>")
	)
	(arc
		(start 135.99795 -265.638534)
		(mid 135.723721 -265.562609)
		(end 135.447278 -265.629898)
		(width 0.088646)
		(layer "In6.Cu")
		(net "M_G_CPU1_SA_DQ<31>")
	)
	(arc
		(start 138.251946 -265.638534)
		(mid 138.064748 -265.688677)
		(end 137.87755 -265.638534)
		(width 0.088646)
		(layer "In6.Cu")
		(net "M_G_CPU1_SA_DQ<31>")
	)
	(arc
		(start 132.232654 -265.635232)
		(mid 131.952519 -265.562949)
		(end 131.673346 -265.638788)
		(width 0.088646)
		(layer "In6.Cu")
		(net "M_G_CPU1_SA_DQ<31>")
	)
	(arc
		(start 136.372346 -265.638534)
		(mid 136.185148 -265.688677)
		(end 135.99795 -265.638534)
		(width 0.088646)
		(layer "In6.Cu")
		(net "M_G_CPU1_SA_DQ<31>")
	)
	(arc
		(start 134.112254 -265.635232)
		(mid 133.832119 -265.562949)
		(end 133.552946 -265.638788)
		(width 0.088646)
		(layer "In6.Cu")
		(net "M_G_CPU1_SA_DQ<31>")
	)
	(arc
		(start 139.191746 -265.638534)
		(mid 139.004548 -265.688677)
		(end 138.81735 -265.638534)
		(width 0.088646)
		(layer "In6.Cu")
		(net "M_G_CPU1_SA_DQ<31>")
	)
	(arc
		(start 135.052054 -265.635232)
		(mid 134.771919 -265.562949)
		(end 134.492746 -265.638788)
		(width 0.088646)
		(layer "In6.Cu")
		(net "M_G_CPU1_SA_DQ<31>")
	)
	(arc
		(start 132.613146 -265.638788)
		(mid 132.429192 -265.688883)
		(end 132.244338 -265.64209)
		(width 0.088646)
		(layer "In6.Cu")
		(net "M_G_CPU1_SA_DQ<31>")
	)
	(arc
		(start 136.93775 -265.638534)
		(mid 136.663521 -265.562609)
		(end 136.387078 -265.629898)
		(width 0.088646)
		(layer "In6.Cu")
		(net "M_G_CPU1_SA_DQ<31>")
	)
	(arc
		(start 138.81735 -265.638534)
		(mid 138.543121 -265.562609)
		(end 138.266678 -265.629898)
		(width 0.088646)
		(layer "In6.Cu")
		(net "M_G_CPU1_SA_DQ<31>")
	)
	(arc
		(start 133.172454 -265.635232)
		(mid 132.892319 -265.562949)
		(end 132.613146 -265.638788)
		(width 0.088646)
		(layer "In6.Cu")
		(net "M_G_CPU1_SA_DQ<31>")
	)
	(arc
		(start 130.733546 -265.638788)
		(mid 130.549592 -265.688883)
		(end 130.364738 -265.64209)
		(width 0.088646)
		(layer "In6.Cu")
		(net "M_G_CPU1_SA_DQ<31>")
	)
	(arc
		(start 131.292854 -265.635232)
		(mid 131.012719 -265.562949)
		(end 130.733546 -265.638788)
		(width 0.088646)
		(layer "In6.Cu")
		(net "M_G_CPU1_SA_DQ<31>")
	)
	(arc
		(start 131.673346 -265.638788)
		(mid 131.489392 -265.688883)
		(end 131.304538 -265.64209)
		(width 0.088646)
		(layer "In6.Cu")
		(net "M_G_CPU1_SA_DQ<31>")
	)
	(arc
		(start 129.413254 -265.635232)
		(mid 129.133119 -265.562949)
		(end 128.853946 -265.638788)
		(width 0.088646)
		(layer "In6.Cu")
		(net "M_G_CPU1_SA_DQ<31>")
	)
	(arc
		(start 133.552946 -265.638788)
		(mid 133.368992 -265.688883)
		(end 133.184138 -265.64209)
		(width 0.088646)
		(layer "In6.Cu")
		(net "M_G_CPU1_SA_DQ<31>")
	)
	(arc
		(start 129.793746 -265.638788)
		(mid 129.609792 -265.688883)
		(end 129.424938 -265.64209)
		(width 0.088646)
		(layer "In6.Cu")
		(net "M_G_CPU1_SA_DQ<31>")
	)
	(arc
		(start 137.87755 -265.638534)
		(mid 137.603321 -265.562609)
		(end 137.326878 -265.629898)
		(width 0.088646)
		(layer "In6.Cu")
		(net "M_G_CPU1_SA_DQ<31>")
	)
	(segment
		(start 197.530466 -281.89174)
		(end 197.542658 -281.903932)
		(width 0.1016)
		(layer "F.Cu")
		(net "M_G_CPU1_SA_DQ<30>")
	)
	(segment
		(start 128.666494 -266.405868)
		(end 128.666494 -266.941554)
		(width 0.20066)
		(layer "F.Cu")
		(net "M_G_CPU1_SA_DQ<30>")
	)
	(segment
		(start 195.522596 -281.89174)
		(end 197.530466 -281.89174)
		(width 0.1016)
		(layer "F.Cu")
		(net "M_G_CPU1_SA_DQ<30>")
	)
	(segment
		(start 194.786758 -281.466798)
		(end 195.218812 -281.898852)
		(width 0.20066)
		(layer "F.Cu")
		(net "M_G_CPU1_SA_DQ<30>")
	)
	(segment
		(start 195.515484 -281.898852)
		(end 195.522596 -281.89174)
		(width 0.1016)
		(layer "F.Cu")
		(net "M_G_CPU1_SA_DQ<30>")
	)
	(segment
		(start 198.427848 -281.449018)
		(end 198.662036 -281.21483)
		(width 0.20066)
		(layer "F.Cu")
		(net "M_G_CPU1_SA_DQ<30>")
	)
	(segment
		(start 198.662036 -281.21483)
		(end 199.046084 -281.21483)
		(width 0.20066)
		(layer "F.Cu")
		(net "M_G_CPU1_SA_DQ<30>")
	)
	(segment
		(start 197.542658 -281.903932)
		(end 198.223886 -281.903932)
		(width 0.20066)
		(layer "F.Cu")
		(net "M_G_CPU1_SA_DQ<30>")
	)
	(segment
		(start 199.298052 -281.466798)
		(end 200.632314 -281.466798)
		(width 0.20066)
		(layer "F.Cu")
		(net "M_G_CPU1_SA_DQ<30>")
	)
	(segment
		(start 199.046084 -281.21483)
		(end 199.298052 -281.466798)
		(width 0.20066)
		(layer "F.Cu")
		(net "M_G_CPU1_SA_DQ<30>")
	)
	(segment
		(start 193.088514 -281.466798)
		(end 194.786758 -281.466798)
		(width 0.20066)
		(layer "F.Cu")
		(net "M_G_CPU1_SA_DQ<30>")
	)
	(segment
		(start 198.223886 -281.903932)
		(end 198.427848 -281.69997)
		(width 0.20066)
		(layer "F.Cu")
		(net "M_G_CPU1_SA_DQ<30>")
	)
	(segment
		(start 195.218812 -281.898852)
		(end 195.510658 -281.898852)
		(width 0.20066)
		(layer "F.Cu")
		(net "M_G_CPU1_SA_DQ<30>")
	)
	(segment
		(start 195.510658 -281.898852)
		(end 195.515484 -281.898852)
		(width 0.101854)
		(layer "F.Cu")
		(net "M_G_CPU1_SA_DQ<30>")
	)
	(segment
		(start 191.941704 -281.466798)
		(end 193.088514 -281.466798)
		(width 0.20066)
		(layer "F.Cu")
		(net "M_G_CPU1_SA_DQ<30>")
	)
	(segment
		(start 128.666494 -266.941554)
		(end 128.666748 -266.941808)
		(width 0.20066)
		(layer "F.Cu")
		(net "M_G_CPU1_SA_DQ<30>")
	)
	(segment
		(start 198.427848 -281.69997)
		(end 198.427848 -281.449018)
		(width 0.20066)
		(layer "F.Cu")
		(net "M_G_CPU1_SA_DQ<30>")
	)
	(segment
		(start 190.837566 -281.466544)
		(end 190.746126 -281.375104)
		(width 0.18288)
		(layer "In6.Cu")
		(net "M_G_CPU1_SA_DQ<30>")
	)
	(segment
		(start 172.424344 -273.392392)
		(end 172.17771 -273.639026)
		(width 0.18288)
		(layer "In6.Cu")
		(net "M_G_CPU1_SA_DQ<30>")
	)
	(segment
		(start 177.692304 -278.081232)
		(end 177.254408 -277.643336)
		(width 0.18288)
		(layer "In6.Cu")
		(net "M_G_CPU1_SA_DQ<30>")
	)
	(segment
		(start 189.612016 -281.086306)
		(end 189.612016 -281.701748)
		(width 0.18288)
		(layer "In6.Cu")
		(net "M_G_CPU1_SA_DQ<30>")
	)
	(segment
		(start 189.429136 -281.884628)
		(end 189.101476 -281.884628)
		(width 0.18288)
		(layer "In6.Cu")
		(net "M_G_CPU1_SA_DQ<30>")
	)
	(segment
		(start 185.45937 -280.639774)
		(end 185.27649 -280.822654)
		(width 0.18288)
		(layer "In6.Cu")
		(net "M_G_CPU1_SA_DQ<30>")
	)
	(segment
		(start 185.96991 -280.999946)
		(end 185.96991 -280.822654)
		(width 0.18288)
		(layer "In6.Cu")
		(net "M_G_CPU1_SA_DQ<30>")
	)
	(segment
		(start 186.15279 -281.182826)
		(end 185.96991 -280.999946)
		(width 0.18288)
		(layer "In6.Cu")
		(net "M_G_CPU1_SA_DQ<30>")
	)
	(segment
		(start 187.317888 -281.042364)
		(end 187.177426 -281.182826)
		(width 0.18288)
		(layer "In6.Cu")
		(net "M_G_CPU1_SA_DQ<30>")
	)
	(segment
		(start 190.568326 -280.903426)
		(end 189.794896 -280.903426)
		(width 0.18288)
		(layer "In6.Cu")
		(net "M_G_CPU1_SA_DQ<30>")
	)
	(segment
		(start 181.950614 -280.446226)
		(end 181.767734 -280.263346)
		(width 0.18288)
		(layer "In6.Cu")
		(net "M_G_CPU1_SA_DQ<30>")
	)
	(segment
		(start 191.94145 -281.466544)
		(end 190.837566 -281.466544)
		(width 0.18288)
		(layer "In6.Cu")
		(net "M_G_CPU1_SA_DQ<30>")
	)
	(segment
		(start 185.96991 -280.822654)
		(end 185.78703 -280.639774)
		(width 0.18288)
		(layer "In6.Cu")
		(net "M_G_CPU1_SA_DQ<30>")
	)
	(segment
		(start 177.254408 -277.643336)
		(end 176.345596 -277.643336)
		(width 0.18288)
		(layer "In6.Cu")
		(net "M_G_CPU1_SA_DQ<30>")
	)
	(segment
		(start 167.866568 -272.659094)
		(end 165.015418 -272.659094)
		(width 0.18288)
		(layer "In6.Cu")
		(net "M_G_CPU1_SA_DQ<30>")
	)
	(segment
		(start 189.794896 -280.903426)
		(end 189.612016 -281.086306)
		(width 0.18288)
		(layer "In6.Cu")
		(net "M_G_CPU1_SA_DQ<30>")
	)
	(segment
		(start 190.746126 -281.081226)
		(end 190.568326 -280.903426)
		(width 0.18288)
		(layer "In6.Cu")
		(net "M_G_CPU1_SA_DQ<30>")
	)
	(segment
		(start 170.991022 -273.639026)
		(end 169.699178 -272.347182)
		(width 0.18288)
		(layer "In6.Cu")
		(net "M_G_CPU1_SA_DQ<30>")
	)
	(segment
		(start 185.27649 -280.999946)
		(end 185.09361 -281.182826)
		(width 0.18288)
		(layer "In6.Cu")
		(net "M_G_CPU1_SA_DQ<30>")
	)
	(segment
		(start 177.692304 -279.04821)
		(end 177.692304 -278.081232)
		(width 0.18288)
		(layer "In6.Cu")
		(net "M_G_CPU1_SA_DQ<30>")
	)
	(segment
		(start 131.209288 -266.449048)
		(end 131.203446 -266.452604)
		(width 0.088646)
		(layer "In6.Cu")
		(net "M_G_CPU1_SA_DQ<30>")
	)
	(segment
		(start 175.663352 -276.961092)
		(end 174.7774 -276.961092)
		(width 0.18288)
		(layer "In6.Cu")
		(net "M_G_CPU1_SA_DQ<30>")
	)
	(segment
		(start 137.791952 -266.446254)
		(end 137.781538 -266.45235)
		(width 0.088646)
		(layer "In6.Cu")
		(net "M_G_CPU1_SA_DQ<30>")
	)
	(segment
		(start 151.693372 -267.006832)
		(end 145.032222 -267.006832)
		(width 0.18288)
		(layer "In6.Cu")
		(net "M_G_CPU1_SA_DQ<30>")
	)
	(segment
		(start 145.032222 -267.006832)
		(end 142.33779 -266.470892)
		(width 0.18288)
		(layer "In6.Cu")
		(net "M_G_CPU1_SA_DQ<30>")
	)
	(segment
		(start 133.088888 -266.449048)
		(end 133.083046 -266.452604)
		(width 0.088646)
		(layer "In6.Cu")
		(net "M_G_CPU1_SA_DQ<30>")
	)
	(segment
		(start 181.074314 -280.263346)
		(end 180.891434 -280.446226)
		(width 0.18288)
		(layer "In6.Cu")
		(net "M_G_CPU1_SA_DQ<30>")
	)
	(segment
		(start 188.307472 -280.903426)
		(end 188.168534 -281.042364)
		(width 0.18288)
		(layer "In6.Cu")
		(net "M_G_CPU1_SA_DQ<30>")
	)
	(segment
		(start 132.143246 -266.452604)
		(end 132.137404 -266.455906)
		(width 0.088646)
		(layer "In6.Cu")
		(net "M_G_CPU1_SA_DQ<30>")
	)
	(segment
		(start 180.891434 -280.446226)
		(end 179.923694 -280.446226)
		(width 0.18288)
		(layer "In6.Cu")
		(net "M_G_CPU1_SA_DQ<30>")
	)
	(segment
		(start 189.101476 -281.884628)
		(end 188.918596 -281.701748)
		(width 0.18288)
		(layer "In6.Cu")
		(net "M_G_CPU1_SA_DQ<30>")
	)
	(segment
		(start 140.595604 -266.470892)
		(end 140.3477 -266.470892)
		(width 0.088646)
		(layer "In6.Cu")
		(net "M_G_CPU1_SA_DQ<30>")
	)
	(segment
		(start 179.923694 -280.446226)
		(end 179.506118 -280.02865)
		(width 0.18288)
		(layer "In6.Cu")
		(net "M_G_CPU1_SA_DQ<30>")
	)
	(segment
		(start 157.339284 -272.652744)
		(end 151.693372 -267.006832)
		(width 0.18288)
		(layer "In6.Cu")
		(net "M_G_CPU1_SA_DQ<30>")
	)
	(segment
		(start 187.177426 -281.182826)
		(end 186.15279 -281.182826)
		(width 0.18288)
		(layer "In6.Cu")
		(net "M_G_CPU1_SA_DQ<30>")
	)
	(segment
		(start 188.918596 -281.086306)
		(end 188.735716 -280.903426)
		(width 0.18288)
		(layer "In6.Cu")
		(net "M_G_CPU1_SA_DQ<30>")
	)
	(segment
		(start 138.731498 -266.446254)
		(end 138.721084 -266.45235)
		(width 0.088646)
		(layer "In6.Cu")
		(net "M_G_CPU1_SA_DQ<30>")
	)
	(segment
		(start 161.279586 -272.423636)
		(end 161.050478 -272.652744)
		(width 0.18288)
		(layer "In6.Cu")
		(net "M_G_CPU1_SA_DQ<30>")
	)
	(segment
		(start 133.083046 -266.452604)
		(end 133.077204 -266.455906)
		(width 0.088646)
		(layer "In6.Cu")
		(net "M_G_CPU1_SA_DQ<30>")
	)
	(segment
		(start 161.050478 -272.652744)
		(end 157.339284 -272.652744)
		(width 0.18288)
		(layer "In6.Cu")
		(net "M_G_CPU1_SA_DQ<30>")
	)
	(segment
		(start 174.535592 -274.237704)
		(end 173.69028 -273.392392)
		(width 0.18288)
		(layer "In6.Cu")
		(net "M_G_CPU1_SA_DQ<30>")
	)
	(segment
		(start 181.257194 -279.790398)
		(end 181.074314 -279.973278)
		(width 0.18288)
		(layer "In6.Cu")
		(net "M_G_CPU1_SA_DQ<30>")
	)
	(segment
		(start 181.074314 -279.973278)
		(end 181.074314 -280.263346)
		(width 0.18288)
		(layer "In6.Cu")
		(net "M_G_CPU1_SA_DQ<30>")
	)
	(segment
		(start 136.852406 -266.446254)
		(end 136.841992 -266.45235)
		(width 0.088646)
		(layer "In6.Cu")
		(net "M_G_CPU1_SA_DQ<30>")
	)
	(segment
		(start 174.7774 -276.961092)
		(end 174.535592 -276.719284)
		(width 0.18288)
		(layer "In6.Cu")
		(net "M_G_CPU1_SA_DQ<30>")
	)
	(segment
		(start 181.584854 -279.790398)
		(end 181.257194 -279.790398)
		(width 0.18288)
		(layer "In6.Cu")
		(net "M_G_CPU1_SA_DQ<30>")
	)
	(segment
		(start 179.506118 -280.02865)
		(end 178.672744 -280.02865)
		(width 0.18288)
		(layer "In6.Cu")
		(net "M_G_CPU1_SA_DQ<30>")
	)
	(segment
		(start 130.263646 -266.452604)
		(end 130.257804 -266.455906)
		(width 0.088646)
		(layer "In6.Cu")
		(net "M_G_CPU1_SA_DQ<30>")
	)
	(segment
		(start 189.612016 -281.701748)
		(end 189.429136 -281.884628)
		(width 0.18288)
		(layer "In6.Cu")
		(net "M_G_CPU1_SA_DQ<30>")
	)
	(segment
		(start 188.168534 -281.042364)
		(end 187.317888 -281.042364)
		(width 0.18288)
		(layer "In6.Cu")
		(net "M_G_CPU1_SA_DQ<30>")
	)
	(segment
		(start 131.203446 -266.452604)
		(end 131.197604 -266.455906)
		(width 0.088646)
		(layer "In6.Cu")
		(net "M_G_CPU1_SA_DQ<30>")
	)
	(segment
		(start 185.27649 -280.822654)
		(end 185.27649 -280.999946)
		(width 0.18288)
		(layer "In6.Cu")
		(net "M_G_CPU1_SA_DQ<30>")
	)
	(segment
		(start 140.293344 -266.462764)
		(end 140.227304 -266.44219)
		(width 0.088646)
		(layer "In6.Cu")
		(net "M_G_CPU1_SA_DQ<30>")
	)
	(segment
		(start 164.77996 -272.423636)
		(end 161.279586 -272.423636)
		(width 0.18288)
		(layer "In6.Cu")
		(net "M_G_CPU1_SA_DQ<30>")
	)
	(segment
		(start 184.11317 -281.182826)
		(end 183.37657 -280.446226)
		(width 0.18288)
		(layer "In6.Cu")
		(net "M_G_CPU1_SA_DQ<30>")
	)
	(segment
		(start 169.699178 -272.347182)
		(end 168.17848 -272.347182)
		(width 0.18288)
		(layer "In6.Cu")
		(net "M_G_CPU1_SA_DQ<30>")
	)
	(segment
		(start 174.535592 -276.719284)
		(end 174.535592 -274.237704)
		(width 0.18288)
		(layer "In6.Cu")
		(net "M_G_CPU1_SA_DQ<30>")
	)
	(segment
		(start 142.33779 -266.470892)
		(end 140.595604 -266.470892)
		(width 0.18288)
		(layer "In6.Cu")
		(net "M_G_CPU1_SA_DQ<30>")
	)
	(segment
		(start 183.37657 -280.446226)
		(end 181.950614 -280.446226)
		(width 0.18288)
		(layer "In6.Cu")
		(net "M_G_CPU1_SA_DQ<30>")
	)
	(segment
		(start 185.78703 -280.639774)
		(end 185.45937 -280.639774)
		(width 0.18288)
		(layer "In6.Cu")
		(net "M_G_CPU1_SA_DQ<30>")
	)
	(segment
		(start 168.17848 -272.347182)
		(end 167.866568 -272.659094)
		(width 0.18288)
		(layer "In6.Cu")
		(net "M_G_CPU1_SA_DQ<30>")
	)
	(segment
		(start 134.962392 -266.45235)
		(end 134.956804 -266.455906)
		(width 0.088646)
		(layer "In6.Cu")
		(net "M_G_CPU1_SA_DQ<30>")
	)
	(segment
		(start 185.09361 -281.182826)
		(end 184.11317 -281.182826)
		(width 0.18288)
		(layer "In6.Cu")
		(net "M_G_CPU1_SA_DQ<30>")
	)
	(segment
		(start 178.672744 -280.02865)
		(end 177.692304 -279.04821)
		(width 0.18288)
		(layer "In6.Cu")
		(net "M_G_CPU1_SA_DQ<30>")
	)
	(segment
		(start 134.028688 -266.449048)
		(end 134.022846 -266.452604)
		(width 0.088646)
		(layer "In6.Cu")
		(net "M_G_CPU1_SA_DQ<30>")
	)
	(segment
		(start 188.735716 -280.903426)
		(end 188.307472 -280.903426)
		(width 0.18288)
		(layer "In6.Cu")
		(net "M_G_CPU1_SA_DQ<30>")
	)
	(segment
		(start 172.17771 -273.639026)
		(end 170.991022 -273.639026)
		(width 0.18288)
		(layer "In6.Cu")
		(net "M_G_CPU1_SA_DQ<30>")
	)
	(segment
		(start 191.941704 -281.466798)
		(end 191.94145 -281.466544)
		(width 0.18288)
		(layer "In6.Cu")
		(net "M_G_CPU1_SA_DQ<30>")
	)
	(segment
		(start 181.767734 -280.263346)
		(end 181.767734 -279.973278)
		(width 0.18288)
		(layer "In6.Cu")
		(net "M_G_CPU1_SA_DQ<30>")
	)
	(segment
		(start 181.767734 -279.973278)
		(end 181.584854 -279.790398)
		(width 0.18288)
		(layer "In6.Cu")
		(net "M_G_CPU1_SA_DQ<30>")
	)
	(segment
		(start 165.015418 -272.659094)
		(end 164.77996 -272.423636)
		(width 0.18288)
		(layer "In6.Cu")
		(net "M_G_CPU1_SA_DQ<30>")
	)
	(segment
		(start 173.69028 -273.392392)
		(end 172.424344 -273.392392)
		(width 0.18288)
		(layer "In6.Cu")
		(net "M_G_CPU1_SA_DQ<30>")
	)
	(segment
		(start 130.269488 -266.449048)
		(end 130.263646 -266.452604)
		(width 0.088646)
		(layer "In6.Cu")
		(net "M_G_CPU1_SA_DQ<30>")
	)
	(segment
		(start 190.746126 -281.375104)
		(end 190.746126 -281.081226)
		(width 0.18288)
		(layer "In6.Cu")
		(net "M_G_CPU1_SA_DQ<30>")
	)
	(segment
		(start 135.527796 -266.45235)
		(end 135.513064 -266.443714)
		(width 0.088646)
		(layer "In6.Cu")
		(net "M_G_CPU1_SA_DQ<30>")
	)
	(segment
		(start 188.918596 -281.701748)
		(end 188.918596 -281.086306)
		(width 0.18288)
		(layer "In6.Cu")
		(net "M_G_CPU1_SA_DQ<30>")
	)
	(segment
		(start 176.345596 -277.643336)
		(end 175.663352 -276.961092)
		(width 0.18288)
		(layer "In6.Cu")
		(net "M_G_CPU1_SA_DQ<30>")
	)
	(segment
		(start 134.022846 -266.452604)
		(end 134.017004 -266.455906)
		(width 0.088646)
		(layer "In6.Cu")
		(net "M_G_CPU1_SA_DQ<30>")
	)
	(segment
		(start 132.149088 -266.449048)
		(end 132.143246 -266.452604)
		(width 0.088646)
		(layer "In6.Cu")
		(net "M_G_CPU1_SA_DQ<30>")
	)
	(segment
		(start 129.329688 -266.449048)
		(end 129.280666 -266.476734)
		(width 0.088646)
		(layer "In6.Cu")
		(net "M_G_CPU1_SA_DQ<30>")
	)
	(arc
		(start 139.238482 -266.427458)
		(mid 138.982773 -266.376833)
		(end 138.731498 -266.446254)
		(width 0.088646)
		(layer "In6.Cu")
		(net "M_G_CPU1_SA_DQ<30>")
	)
	(arc
		(start 134.017004 -266.455906)
		(mid 133.832149 -266.502856)
		(end 133.648196 -266.452604)
		(width 0.088646)
		(layer "In6.Cu")
		(net "M_G_CPU1_SA_DQ<30>")
	)
	(arc
		(start 137.407142 -266.45235)
		(mid 137.130583 -266.376607)
		(end 136.852406 -266.446254)
		(width 0.088646)
		(layer "In6.Cu")
		(net "M_G_CPU1_SA_DQ<30>")
	)
	(arc
		(start 138.721084 -266.45235)
		(mid 138.533886 -266.502527)
		(end 138.346688 -266.45235)
		(width 0.088646)
		(layer "In6.Cu")
		(net "M_G_CPU1_SA_DQ<30>")
	)
	(arc
		(start 138.346688 -266.45235)
		(mid 138.070129 -266.376607)
		(end 137.791952 -266.446254)
		(width 0.088646)
		(layer "In6.Cu")
		(net "M_G_CPU1_SA_DQ<30>")
	)
	(arc
		(start 129.888996 -266.452604)
		(mid 129.609822 -266.376805)
		(end 129.329688 -266.449048)
		(width 0.088646)
		(layer "In6.Cu")
		(net "M_G_CPU1_SA_DQ<30>")
	)
	(arc
		(start 136.467596 -266.45235)
		(mid 136.184894 -266.376574)
		(end 135.902192 -266.45235)
		(width 0.088646)
		(layer "In6.Cu")
		(net "M_G_CPU1_SA_DQ<30>")
	)
	(arc
		(start 133.077204 -266.455906)
		(mid 132.892349 -266.502856)
		(end 132.708396 -266.452604)
		(width 0.088646)
		(layer "In6.Cu")
		(net "M_G_CPU1_SA_DQ<30>")
	)
	(arc
		(start 136.841992 -266.45235)
		(mid 136.654794 -266.502527)
		(end 136.467596 -266.45235)
		(width 0.088646)
		(layer "In6.Cu")
		(net "M_G_CPU1_SA_DQ<30>")
	)
	(arc
		(start 135.902192 -266.45235)
		(mid 135.714994 -266.502527)
		(end 135.527796 -266.45235)
		(width 0.088646)
		(layer "In6.Cu")
		(net "M_G_CPU1_SA_DQ<30>")
	)
	(arc
		(start 134.956804 -266.455906)
		(mid 134.771949 -266.502856)
		(end 134.587996 -266.452604)
		(width 0.088646)
		(layer "In6.Cu")
		(net "M_G_CPU1_SA_DQ<30>")
	)
	(arc
		(start 140.3477 -266.470892)
		(mid 140.320219 -266.46886)
		(end 140.293344 -266.462764)
		(width 0.088646)
		(layer "In6.Cu")
		(net "M_G_CPU1_SA_DQ<30>")
	)
	(arc
		(start 132.137404 -266.455906)
		(mid 131.952549 -266.502856)
		(end 131.768596 -266.452604)
		(width 0.088646)
		(layer "In6.Cu")
		(net "M_G_CPU1_SA_DQ<30>")
	)
	(arc
		(start 137.781538 -266.45235)
		(mid 137.59434 -266.502527)
		(end 137.407142 -266.45235)
		(width 0.088646)
		(layer "In6.Cu")
		(net "M_G_CPU1_SA_DQ<30>")
	)
	(arc
		(start 130.257804 -266.455906)
		(mid 130.072949 -266.502856)
		(end 129.888996 -266.452604)
		(width 0.088646)
		(layer "In6.Cu")
		(net "M_G_CPU1_SA_DQ<30>")
	)
	(arc
		(start 132.708396 -266.452604)
		(mid 132.429222 -266.376805)
		(end 132.149088 -266.449048)
		(width 0.088646)
		(layer "In6.Cu")
		(net "M_G_CPU1_SA_DQ<30>")
	)
	(arc
		(start 133.648196 -266.452604)
		(mid 133.369022 -266.376805)
		(end 133.088888 -266.449048)
		(width 0.088646)
		(layer "In6.Cu")
		(net "M_G_CPU1_SA_DQ<30>")
	)
	(arc
		(start 140.227304 -266.44219)
		(mid 140.185168 -266.428233)
		(end 140.143484 -266.41298)
		(width 0.088646)
		(layer "In6.Cu")
		(net "M_G_CPU1_SA_DQ<30>")
	)
	(arc
		(start 131.197604 -266.455906)
		(mid 131.012749 -266.502856)
		(end 130.828796 -266.452604)
		(width 0.088646)
		(layer "In6.Cu")
		(net "M_G_CPU1_SA_DQ<30>")
	)
	(arc
		(start 140.143484 -266.41298)
		(mid 139.924234 -266.376578)
		(end 139.707874 -266.427458)
		(width 0.088646)
		(layer "In6.Cu")
		(net "M_G_CPU1_SA_DQ<30>")
	)
	(arc
		(start 139.707874 -266.427458)
		(mid 139.473178 -266.478519)
		(end 139.238482 -266.427458)
		(width 0.088646)
		(layer "In6.Cu")
		(net "M_G_CPU1_SA_DQ<30>")
	)
	(arc
		(start 130.828796 -266.452604)
		(mid 130.549622 -266.376805)
		(end 130.269488 -266.449048)
		(width 0.088646)
		(layer "In6.Cu")
		(net "M_G_CPU1_SA_DQ<30>")
	)
	(arc
		(start 135.513064 -266.443714)
		(mid 135.236589 -266.376394)
		(end 134.962392 -266.45235)
		(width 0.088646)
		(layer "In6.Cu")
		(net "M_G_CPU1_SA_DQ<30>")
	)
	(arc
		(start 134.587996 -266.452604)
		(mid 134.308822 -266.376805)
		(end 134.028688 -266.449048)
		(width 0.088646)
		(layer "In6.Cu")
		(net "M_G_CPU1_SA_DQ<30>")
	)
	(arc
		(start 129.280666 -266.476734)
		(mid 128.95808 -266.688643)
		(end 128.666748 -266.941808)
		(width 0.088646)
		(layer "In6.Cu")
		(net "M_G_CPU1_SA_DQ<30>")
	)
	(arc
		(start 131.768596 -266.452604)
		(mid 131.489422 -266.376805)
		(end 131.209288 -266.449048)
		(width 0.088646)
		(layer "In6.Cu")
		(net "M_G_CPU1_SA_DQ<30>")
	)
	(segment
		(start 198.427848 -315.699902)
		(end 198.427848 -315.44895)
		(width 0.20066)
		(layer "F.Cu")
		(net "M_G_CPU1_SA_DQ<2>")
	)
	(segment
		(start 195.515484 -315.898784)
		(end 195.522596 -315.891672)
		(width 0.1016)
		(layer "F.Cu")
		(net "M_G_CPU1_SA_DQ<2>")
	)
	(segment
		(start 193.088514 -315.46673)
		(end 194.786758 -315.46673)
		(width 0.20066)
		(layer "F.Cu")
		(net "M_G_CPU1_SA_DQ<2>")
	)
	(segment
		(start 131.485894 -276.172676)
		(end 131.486148 -276.708616)
		(width 0.20066)
		(layer "F.Cu")
		(net "M_G_CPU1_SA_DQ<2>")
	)
	(segment
		(start 198.662036 -315.214762)
		(end 199.046084 -315.214762)
		(width 0.20066)
		(layer "F.Cu")
		(net "M_G_CPU1_SA_DQ<2>")
	)
	(segment
		(start 195.522596 -315.891672)
		(end 197.530466 -315.891672)
		(width 0.1016)
		(layer "F.Cu")
		(net "M_G_CPU1_SA_DQ<2>")
	)
	(segment
		(start 198.427848 -315.44895)
		(end 198.662036 -315.214762)
		(width 0.20066)
		(layer "F.Cu")
		(net "M_G_CPU1_SA_DQ<2>")
	)
	(segment
		(start 197.542658 -315.903864)
		(end 198.223886 -315.903864)
		(width 0.20066)
		(layer "F.Cu")
		(net "M_G_CPU1_SA_DQ<2>")
	)
	(segment
		(start 199.046084 -315.214762)
		(end 199.298052 -315.46673)
		(width 0.20066)
		(layer "F.Cu")
		(net "M_G_CPU1_SA_DQ<2>")
	)
	(segment
		(start 194.786758 -315.46673)
		(end 195.218812 -315.898784)
		(width 0.20066)
		(layer "F.Cu")
		(net "M_G_CPU1_SA_DQ<2>")
	)
	(segment
		(start 198.223886 -315.903864)
		(end 198.427848 -315.699902)
		(width 0.20066)
		(layer "F.Cu")
		(net "M_G_CPU1_SA_DQ<2>")
	)
	(segment
		(start 195.218812 -315.898784)
		(end 195.510658 -315.898784)
		(width 0.20066)
		(layer "F.Cu")
		(net "M_G_CPU1_SA_DQ<2>")
	)
	(segment
		(start 199.298052 -315.46673)
		(end 200.632314 -315.46673)
		(width 0.20066)
		(layer "F.Cu")
		(net "M_G_CPU1_SA_DQ<2>")
	)
	(segment
		(start 197.530466 -315.891672)
		(end 197.542658 -315.903864)
		(width 0.1016)
		(layer "F.Cu")
		(net "M_G_CPU1_SA_DQ<2>")
	)
	(segment
		(start 195.510658 -315.898784)
		(end 195.515484 -315.898784)
		(width 0.101854)
		(layer "F.Cu")
		(net "M_G_CPU1_SA_DQ<2>")
	)
	(segment
		(start 191.983614 -315.46673)
		(end 193.088514 -315.46673)
		(width 0.20066)
		(layer "F.Cu")
		(net "M_G_CPU1_SA_DQ<2>")
	)
	(segment
		(start 141.171676 -283.584142)
		(end 140.20292 -281.245818)
		(width 0.18288)
		(layer "In4.Cu")
		(net "M_G_CPU1_SA_DQ<2>")
	)
	(segment
		(start 162.579558 -314.101226)
		(end 161.266886 -314.101226)
		(width 0.18288)
		(layer "In4.Cu")
		(net "M_G_CPU1_SA_DQ<2>")
	)
	(segment
		(start 134.587996 -277.84679)
		(end 134.579106 -277.84171)
		(width 0.088646)
		(layer "In4.Cu")
		(net "M_G_CPU1_SA_DQ<2>")
	)
	(segment
		(start 185.513726 -315.218826)
		(end 183.481726 -315.218826)
		(width 0.18288)
		(layer "In4.Cu")
		(net "M_G_CPU1_SA_DQ<2>")
	)
	(segment
		(start 186.186318 -315.891418)
		(end 185.513726 -315.218826)
		(width 0.18288)
		(layer "In4.Cu")
		(net "M_G_CPU1_SA_DQ<2>")
	)
	(segment
		(start 159.316166 -313.113928)
		(end 158.223712 -312.021474)
		(width 0.18288)
		(layer "In4.Cu")
		(net "M_G_CPU1_SA_DQ<2>")
	)
	(segment
		(start 134.400544 -277.522432)
		(end 134.400544 -277.506938)
		(width 0.088646)
		(layer "In4.Cu")
		(net "M_G_CPU1_SA_DQ<2>")
	)
	(segment
		(start 157.202632 -312.021474)
		(end 153.849578 -308.66842)
		(width 0.18288)
		(layer "In4.Cu")
		(net "M_G_CPU1_SA_DQ<2>")
	)
	(segment
		(start 131.11607 -276.76602)
		(end 131.173474 -276.708616)
		(width 0.088646)
		(layer "In4.Cu")
		(net "M_G_CPU1_SA_DQ<2>")
	)
	(segment
		(start 174.19955 -317.592202)
		(end 173.550326 -318.241426)
		(width 0.18288)
		(layer "In4.Cu")
		(net "M_G_CPU1_SA_DQ<2>")
	)
	(segment
		(start 183.481726 -315.218826)
		(end 182.651146 -316.049406)
		(width 0.18288)
		(layer "In4.Cu")
		(net "M_G_CPU1_SA_DQ<2>")
	)
	(segment
		(start 135.340344 -279.150318)
		(end 135.340344 -279.140412)
		(width 0.088646)
		(layer "In4.Cu")
		(net "M_G_CPU1_SA_DQ<2>")
	)
	(segment
		(start 163.517072 -315.03874)
		(end 162.579558 -314.101226)
		(width 0.18288)
		(layer "In4.Cu")
		(net "M_G_CPU1_SA_DQ<2>")
	)
	(segment
		(start 191.983614 -315.46673)
		(end 191.02832 -315.891418)
		(width 0.18288)
		(layer "In4.Cu")
		(net "M_G_CPU1_SA_DQ<2>")
	)
	(segment
		(start 140.20292 -281.245818)
		(end 139.67333 -280.716228)
		(width 0.18288)
		(layer "In4.Cu")
		(net "M_G_CPU1_SA_DQ<2>")
	)
	(segment
		(start 131.68376 -277.026878)
		(end 131.673346 -277.032974)
		(width 0.088646)
		(layer "In4.Cu")
		(net "M_G_CPU1_SA_DQ<2>")
	)
	(segment
		(start 166.257732 -315.03874)
		(end 163.517072 -315.03874)
		(width 0.18288)
		(layer "In4.Cu")
		(net "M_G_CPU1_SA_DQ<2>")
	)
	(segment
		(start 138.947652 -279.99055)
		(end 138.1887 -279.99055)
		(width 0.088646)
		(layer "In4.Cu")
		(net "M_G_CPU1_SA_DQ<2>")
	)
	(segment
		(start 134.870444 -278.336502)
		(end 134.870444 -278.31796)
		(width 0.088646)
		(layer "In4.Cu")
		(net "M_G_CPU1_SA_DQ<2>")
	)
	(segment
		(start 191.02832 -315.891418)
		(end 186.186318 -315.891418)
		(width 0.18288)
		(layer "In4.Cu")
		(net "M_G_CPU1_SA_DQ<2>")
	)
	(segment
		(start 169.663364 -316.74308)
		(end 168.92778 -316.74308)
		(width 0.18288)
		(layer "In4.Cu")
		(net "M_G_CPU1_SA_DQ<2>")
	)
	(segment
		(start 133.567678 -277.024338)
		(end 133.552946 -277.032974)
		(width 0.088646)
		(layer "In4.Cu")
		(net "M_G_CPU1_SA_DQ<2>")
	)
	(segment
		(start 171.16171 -318.241426)
		(end 169.663364 -316.74308)
		(width 0.18288)
		(layer "In4.Cu")
		(net "M_G_CPU1_SA_DQ<2>")
	)
	(segment
		(start 131.29895 -277.032974)
		(end 131.29006 -277.027894)
		(width 0.088646)
		(layer "In4.Cu")
		(net "M_G_CPU1_SA_DQ<2>")
	)
	(segment
		(start 180.01869 -317.786766)
		(end 179.824126 -317.592202)
		(width 0.18288)
		(layer "In4.Cu")
		(net "M_G_CPU1_SA_DQ<2>")
	)
	(segment
		(start 153.849578 -308.66842)
		(end 146.897344 -298.263564)
		(width 0.18288)
		(layer "In4.Cu")
		(net "M_G_CPU1_SA_DQ<2>")
	)
	(segment
		(start 135.057896 -278.66086)
		(end 135.049006 -278.65578)
		(width 0.088646)
		(layer "In4.Cu")
		(net "M_G_CPU1_SA_DQ<2>")
	)
	(segment
		(start 158.223712 -312.021474)
		(end 157.202632 -312.021474)
		(width 0.18288)
		(layer "In4.Cu")
		(net "M_G_CPU1_SA_DQ<2>")
	)
	(segment
		(start 132.623306 -277.026878)
		(end 132.612892 -277.032974)
		(width 0.088646)
		(layer "In4.Cu")
		(net "M_G_CPU1_SA_DQ<2>")
	)
	(segment
		(start 167.225218 -316.006226)
		(end 166.257732 -315.03874)
		(width 0.18288)
		(layer "In4.Cu")
		(net "M_G_CPU1_SA_DQ<2>")
	)
	(segment
		(start 141.171676 -284.441392)
		(end 141.171676 -283.584142)
		(width 0.18288)
		(layer "In4.Cu")
		(net "M_G_CPU1_SA_DQ<2>")
	)
	(segment
		(start 168.92778 -316.74308)
		(end 168.190926 -316.006226)
		(width 0.18288)
		(layer "In4.Cu")
		(net "M_G_CPU1_SA_DQ<2>")
	)
	(segment
		(start 182.651146 -316.049406)
		(end 182.153306 -316.049406)
		(width 0.18288)
		(layer "In4.Cu")
		(net "M_G_CPU1_SA_DQ<2>")
	)
	(segment
		(start 182.153306 -316.049406)
		(end 180.415946 -317.786766)
		(width 0.18288)
		(layer "In4.Cu")
		(net "M_G_CPU1_SA_DQ<2>")
	)
	(segment
		(start 173.550326 -318.241426)
		(end 171.16171 -318.241426)
		(width 0.18288)
		(layer "In4.Cu")
		(net "M_G_CPU1_SA_DQ<2>")
	)
	(segment
		(start 131.173474 -276.708616)
		(end 131.486148 -276.708616)
		(width 0.088646)
		(layer "In4.Cu")
		(net "M_G_CPU1_SA_DQ<2>")
	)
	(segment
		(start 135.527796 -279.474676)
		(end 135.518906 -279.469596)
		(width 0.088646)
		(layer "In4.Cu")
		(net "M_G_CPU1_SA_DQ<2>")
	)
	(segment
		(start 160.279588 -313.113928)
		(end 159.316166 -313.113928)
		(width 0.18288)
		(layer "In4.Cu")
		(net "M_G_CPU1_SA_DQ<2>")
	)
	(segment
		(start 138.1887 -279.99055)
		(end 137.723626 -279.525476)
		(width 0.088646)
		(layer "In4.Cu")
		(net "M_G_CPU1_SA_DQ<2>")
	)
	(segment
		(start 180.415946 -317.786766)
		(end 180.01869 -317.786766)
		(width 0.18288)
		(layer "In4.Cu")
		(net "M_G_CPU1_SA_DQ<2>")
	)
	(segment
		(start 161.266886 -314.101226)
		(end 160.279588 -313.113928)
		(width 0.18288)
		(layer "In4.Cu")
		(net "M_G_CPU1_SA_DQ<2>")
	)
	(segment
		(start 137.723626 -279.525476)
		(end 137.594848 -279.525476)
		(width 0.088646)
		(layer "In4.Cu")
		(net "M_G_CPU1_SA_DQ<2>")
	)
	(segment
		(start 179.824126 -317.592202)
		(end 174.19955 -317.592202)
		(width 0.18288)
		(layer "In4.Cu")
		(net "M_G_CPU1_SA_DQ<2>")
	)
	(segment
		(start 146.897344 -298.263564)
		(end 141.171676 -284.441392)
		(width 0.18288)
		(layer "In4.Cu")
		(net "M_G_CPU1_SA_DQ<2>")
	)
	(segment
		(start 168.190926 -316.006226)
		(end 167.225218 -316.006226)
		(width 0.18288)
		(layer "In4.Cu")
		(net "M_G_CPU1_SA_DQ<2>")
	)
	(segment
		(start 139.67333 -280.716228)
		(end 138.947652 -279.99055)
		(width 0.088646)
		(layer "In4.Cu")
		(net "M_G_CPU1_SA_DQ<2>")
	)
	(arc
		(start 134.11835 -277.032974)
		(mid 133.844151 -276.957139)
		(end 133.567678 -277.024338)
		(width 0.088646)
		(layer "In4.Cu")
		(net "M_G_CPU1_SA_DQ<2>")
	)
	(arc
		(start 134.400544 -277.506938)
		(mid 134.321174 -277.233204)
		(end 134.11835 -277.032974)
		(width 0.088646)
		(layer "In4.Cu")
		(net "M_G_CPU1_SA_DQ<2>")
	)
	(arc
		(start 131.29006 -277.027894)
		(mid 131.174321 -276.91607)
		(end 131.11607 -276.76602)
		(width 0.088646)
		(layer "In4.Cu")
		(net "M_G_CPU1_SA_DQ<2>")
	)
	(arc
		(start 136.467596 -279.474676)
		(mid 136.184894 -279.3989)
		(end 135.902192 -279.474676)
		(width 0.088646)
		(layer "In4.Cu")
		(net "M_G_CPU1_SA_DQ<2>")
	)
	(arc
		(start 135.518906 -279.469596)
		(mid 135.387992 -279.333236)
		(end 135.340344 -279.150318)
		(width 0.088646)
		(layer "In4.Cu")
		(net "M_G_CPU1_SA_DQ<2>")
	)
	(arc
		(start 133.17855 -277.032974)
		(mid 132.901737 -276.957104)
		(end 132.623306 -277.026878)
		(width 0.088646)
		(layer "In4.Cu")
		(net "M_G_CPU1_SA_DQ<2>")
	)
	(arc
		(start 135.049006 -278.65578)
		(mid 134.918092 -278.51942)
		(end 134.870444 -278.336502)
		(width 0.088646)
		(layer "In4.Cu")
		(net "M_G_CPU1_SA_DQ<2>")
	)
	(arc
		(start 134.870444 -278.31796)
		(mid 134.790282 -278.045771)
		(end 134.587996 -277.84679)
		(width 0.088646)
		(layer "In4.Cu")
		(net "M_G_CPU1_SA_DQ<2>")
	)
	(arc
		(start 135.902192 -279.474676)
		(mid 135.714994 -279.524819)
		(end 135.527796 -279.474676)
		(width 0.088646)
		(layer "In4.Cu")
		(net "M_G_CPU1_SA_DQ<2>")
	)
	(arc
		(start 133.552946 -277.032974)
		(mid 133.365748 -277.083117)
		(end 133.17855 -277.032974)
		(width 0.088646)
		(layer "In4.Cu")
		(net "M_G_CPU1_SA_DQ<2>")
	)
	(arc
		(start 132.612892 -277.032974)
		(mid 132.425694 -277.083117)
		(end 132.238496 -277.032974)
		(width 0.088646)
		(layer "In4.Cu")
		(net "M_G_CPU1_SA_DQ<2>")
	)
	(arc
		(start 137.594848 -279.525476)
		(mid 137.497778 -279.512419)
		(end 137.407396 -279.474676)
		(width 0.088646)
		(layer "In4.Cu")
		(net "M_G_CPU1_SA_DQ<2>")
	)
	(arc
		(start 137.407396 -279.474676)
		(mid 137.124694 -279.3989)
		(end 136.841992 -279.474676)
		(width 0.088646)
		(layer "In4.Cu")
		(net "M_G_CPU1_SA_DQ<2>")
	)
	(arc
		(start 131.673346 -277.032974)
		(mid 131.486148 -277.083117)
		(end 131.29895 -277.032974)
		(width 0.088646)
		(layer "In4.Cu")
		(net "M_G_CPU1_SA_DQ<2>")
	)
	(arc
		(start 132.238496 -277.032974)
		(mid 131.961937 -276.957231)
		(end 131.68376 -277.026878)
		(width 0.088646)
		(layer "In4.Cu")
		(net "M_G_CPU1_SA_DQ<2>")
	)
	(arc
		(start 134.579106 -277.84171)
		(mid 134.448192 -277.70535)
		(end 134.400544 -277.522432)
		(width 0.088646)
		(layer "In4.Cu")
		(net "M_G_CPU1_SA_DQ<2>")
	)
	(arc
		(start 135.340344 -279.140412)
		(mid 135.262233 -278.863463)
		(end 135.057896 -278.66086)
		(width 0.088646)
		(layer "In4.Cu")
		(net "M_G_CPU1_SA_DQ<2>")
	)
	(arc
		(start 136.841992 -279.474676)
		(mid 136.654794 -279.524819)
		(end 136.467596 -279.474676)
		(width 0.088646)
		(layer "In4.Cu")
		(net "M_G_CPU1_SA_DQ<2>")
	)
	(segment
		(start 191.421004 -280.677366)
		(end 191.233044 -280.865326)
		(width 0.20066)
		(layer "F.Cu")
		(net "M_G_CPU1_SA_DQ<29>")
	)
	(segment
		(start 194.508882 -280.185368)
		(end 194.098926 -280.185368)
		(width 0.20066)
		(layer "F.Cu")
		(net "M_G_CPU1_SA_DQ<29>")
	)
	(segment
		(start 191.539114 -280.191718)
		(end 191.421004 -280.309828)
		(width 0.20066)
		(layer "F.Cu")
		(net "M_G_CPU1_SA_DQ<29>")
	)
	(segment
		(start 190.509144 -280.61666)
		(end 188.988446 -280.61666)
		(width 0.20066)
		(layer "F.Cu")
		(net "M_G_CPU1_SA_DQ<29>")
	)
	(segment
		(start 194.098926 -280.185368)
		(end 194.092576 -280.191718)
		(width 0.1016)
		(layer "F.Cu")
		(net "M_G_CPU1_SA_DQ<29>")
	)
	(segment
		(start 190.75781 -280.865326)
		(end 190.509144 -280.61666)
		(width 0.20066)
		(layer "F.Cu")
		(net "M_G_CPU1_SA_DQ<29>")
	)
	(segment
		(start 194.940428 -280.616914)
		(end 194.508882 -280.185368)
		(width 0.20066)
		(layer "F.Cu")
		(net "M_G_CPU1_SA_DQ<29>")
	)
	(segment
		(start 127.257048 -265.592306)
		(end 127.257048 -266.127992)
		(width 0.20066)
		(layer "F.Cu")
		(net "M_G_CPU1_SA_DQ<29>")
	)
	(segment
		(start 191.903858 -280.191718)
		(end 191.883792 -280.191718)
		(width 0.101854)
		(layer "F.Cu")
		(net "M_G_CPU1_SA_DQ<29>")
	)
	(segment
		(start 191.233044 -280.865326)
		(end 190.75781 -280.865326)
		(width 0.20066)
		(layer "F.Cu")
		(net "M_G_CPU1_SA_DQ<29>")
	)
	(segment
		(start 191.883792 -280.191718)
		(end 191.539114 -280.191718)
		(width 0.20066)
		(layer "F.Cu")
		(net "M_G_CPU1_SA_DQ<29>")
	)
	(segment
		(start 127.257048 -266.127992)
		(end 127.256794 -266.128246)
		(width 0.20066)
		(layer "F.Cu")
		(net "M_G_CPU1_SA_DQ<29>")
	)
	(segment
		(start 194.092576 -280.191718)
		(end 191.903858 -280.191718)
		(width 0.1016)
		(layer "F.Cu")
		(net "M_G_CPU1_SA_DQ<29>")
	)
	(segment
		(start 191.421004 -280.309828)
		(end 191.421004 -280.677366)
		(width 0.20066)
		(layer "F.Cu")
		(net "M_G_CPU1_SA_DQ<29>")
	)
	(segment
		(start 196.532246 -280.61666)
		(end 196.531992 -280.616914)
		(width 0.20066)
		(layer "F.Cu")
		(net "M_G_CPU1_SA_DQ<29>")
	)
	(segment
		(start 188.988446 -280.61666)
		(end 187.883546 -280.61666)
		(width 0.20066)
		(layer "F.Cu")
		(net "M_G_CPU1_SA_DQ<29>")
	)
	(segment
		(start 196.531992 -280.616914)
		(end 194.940428 -280.616914)
		(width 0.20066)
		(layer "F.Cu")
		(net "M_G_CPU1_SA_DQ<29>")
	)
	(segment
		(start 160.439862 -271.379696)
		(end 158.518606 -271.379696)
		(width 0.18288)
		(layer "In6.Cu")
		(net "M_G_CPU1_SA_DQ<29>")
	)
	(segment
		(start 162.408616 -271.805146)
		(end 160.865312 -271.805146)
		(width 0.18288)
		(layer "In6.Cu")
		(net "M_G_CPU1_SA_DQ<29>")
	)
	(segment
		(start 175.282352 -274.617942)
		(end 175.122332 -274.457922)
		(width 0.18288)
		(layer "In6.Cu")
		(net "M_G_CPU1_SA_DQ<29>")
	)
	(segment
		(start 171.78782 -272.229072)
		(end 171.407836 -272.229072)
		(width 0.18288)
		(layer "In6.Cu")
		(net "M_G_CPU1_SA_DQ<29>")
	)
	(segment
		(start 175.69307 -276.004782)
		(end 175.248316 -276.004782)
		(width 0.18288)
		(layer "In6.Cu")
		(net "M_G_CPU1_SA_DQ<29>")
	)
	(segment
		(start 129.888996 -265.803634)
		(end 129.878582 -265.80973)
		(width 0.088646)
		(layer "In6.Cu")
		(net "M_G_CPU1_SA_DQ<29>")
	)
	(segment
		(start 175.69307 -274.617942)
		(end 175.282352 -274.617942)
		(width 0.18288)
		(layer "In6.Cu")
		(net "M_G_CPU1_SA_DQ<29>")
	)
	(segment
		(start 160.865312 -271.805146)
		(end 160.439862 -271.379696)
		(width 0.18288)
		(layer "In6.Cu")
		(net "M_G_CPU1_SA_DQ<29>")
	)
	(segment
		(start 130.263646 -265.803634)
		(end 130.257804 -265.800332)
		(width 0.088646)
		(layer "In6.Cu")
		(net "M_G_CPU1_SA_DQ<29>")
	)
	(segment
		(start 173.69028 -272.229072)
		(end 173.376844 -272.542508)
		(width 0.18288)
		(layer "In6.Cu")
		(net "M_G_CPU1_SA_DQ<29>")
	)
	(segment
		(start 162.591496 -271.622266)
		(end 162.408616 -271.805146)
		(width 0.18288)
		(layer "In6.Cu")
		(net "M_G_CPU1_SA_DQ<29>")
	)
	(segment
		(start 134.962392 -265.803888)
		(end 134.962646 -265.803634)
		(width 0.088646)
		(layer "In6.Cu")
		(net "M_G_CPU1_SA_DQ<29>")
	)
	(segment
		(start 164.544248 -271.653508)
		(end 164.39261 -271.805146)
		(width 0.18288)
		(layer "In6.Cu")
		(net "M_G_CPU1_SA_DQ<29>")
	)
	(segment
		(start 140.316458 -265.966956)
		(end 140.242544 -265.893042)
		(width 0.088646)
		(layer "In6.Cu")
		(net "M_G_CPU1_SA_DQ<29>")
	)
	(segment
		(start 131.209288 -265.80719)
		(end 131.203446 -265.803634)
		(width 0.088646)
		(layer "In6.Cu")
		(net "M_G_CPU1_SA_DQ<29>")
	)
	(segment
		(start 178.231292 -277.807674)
		(end 177.214276 -276.790658)
		(width 0.18288)
		(layer "In6.Cu")
		(net "M_G_CPU1_SA_DQ<29>")
	)
	(segment
		(start 178.231292 -278.8158)
		(end 178.231292 -277.807674)
		(width 0.18288)
		(layer "In6.Cu")
		(net "M_G_CPU1_SA_DQ<29>")
	)
	(segment
		(start 177.214276 -276.790658)
		(end 176.478946 -276.790658)
		(width 0.18288)
		(layer "In6.Cu")
		(net "M_G_CPU1_SA_DQ<29>")
	)
	(segment
		(start 175.088296 -275.471382)
		(end 175.248316 -275.311362)
		(width 0.18288)
		(layer "In6.Cu")
		(net "M_G_CPU1_SA_DQ<29>")
	)
	(segment
		(start 169.15638 -271.842484)
		(end 168.967404 -271.653508)
		(width 0.18288)
		(layer "In6.Cu")
		(net "M_G_CPU1_SA_DQ<29>")
	)
	(segment
		(start 174.3837 -272.542508)
		(end 174.070264 -272.229072)
		(width 0.18288)
		(layer "In6.Cu")
		(net "M_G_CPU1_SA_DQ<29>")
	)
	(segment
		(start 157.112716 -271.640808)
		(end 151.964898 -266.49299)
		(width 0.18288)
		(layer "In6.Cu")
		(net "M_G_CPU1_SA_DQ<29>")
	)
	(segment
		(start 175.248316 -275.311362)
		(end 175.69307 -275.311362)
		(width 0.18288)
		(layer "In6.Cu")
		(net "M_G_CPU1_SA_DQ<29>")
	)
	(segment
		(start 133.083046 -265.803634)
		(end 133.077204 -265.800332)
		(width 0.088646)
		(layer "In6.Cu")
		(net "M_G_CPU1_SA_DQ<29>")
	)
	(segment
		(start 137.407396 -265.803888)
		(end 137.392664 -265.812524)
		(width 0.088646)
		(layer "In6.Cu")
		(net "M_G_CPU1_SA_DQ<29>")
	)
	(segment
		(start 170.038268 -271.842484)
		(end 169.15638 -271.842484)
		(width 0.18288)
		(layer "In6.Cu")
		(net "M_G_CPU1_SA_DQ<29>")
	)
	(segment
		(start 127.914146 -266.61745)
		(end 127.88392 -266.600178)
		(width 0.088646)
		(layer "In6.Cu")
		(net "M_G_CPU1_SA_DQ<29>")
	)
	(segment
		(start 134.962646 -265.803634)
		(end 134.956804 -265.800332)
		(width 0.088646)
		(layer "In6.Cu")
		(net "M_G_CPU1_SA_DQ<29>")
	)
	(segment
		(start 132.143246 -265.803634)
		(end 132.137404 -265.800332)
		(width 0.088646)
		(layer "In6.Cu")
		(net "M_G_CPU1_SA_DQ<29>")
	)
	(segment
		(start 134.028688 -265.80719)
		(end 134.022846 -265.803634)
		(width 0.088646)
		(layer "In6.Cu")
		(net "M_G_CPU1_SA_DQ<29>")
	)
	(segment
		(start 175.85309 -274.777962)
		(end 175.69307 -274.617942)
		(width 0.18288)
		(layer "In6.Cu")
		(net "M_G_CPU1_SA_DQ<29>")
	)
	(segment
		(start 158.518606 -271.379696)
		(end 158.257494 -271.640808)
		(width 0.18288)
		(layer "In6.Cu")
		(net "M_G_CPU1_SA_DQ<29>")
	)
	(segment
		(start 175.85309 -273.165062)
		(end 175.230536 -272.542508)
		(width 0.18288)
		(layer "In6.Cu")
		(net "M_G_CPU1_SA_DQ<29>")
	)
	(segment
		(start 164.39261 -271.805146)
		(end 163.467796 -271.805146)
		(width 0.18288)
		(layer "In6.Cu")
		(net "M_G_CPU1_SA_DQ<29>")
	)
	(segment
		(start 139.286996 -265.803888)
		(end 139.272264 -265.812524)
		(width 0.088646)
		(layer "In6.Cu")
		(net "M_G_CPU1_SA_DQ<29>")
	)
	(segment
		(start 136.467596 -265.803888)
		(end 136.452864 -265.812524)
		(width 0.088646)
		(layer "In6.Cu")
		(net "M_G_CPU1_SA_DQ<29>")
	)
	(segment
		(start 162.591496 -270.940276)
		(end 162.591496 -271.622266)
		(width 0.18288)
		(layer "In6.Cu")
		(net "M_G_CPU1_SA_DQ<29>")
	)
	(segment
		(start 171.407836 -272.229072)
		(end 171.0944 -272.542508)
		(width 0.18288)
		(layer "In6.Cu")
		(net "M_G_CPU1_SA_DQ<29>")
	)
	(segment
		(start 170.738292 -272.542508)
		(end 170.038268 -271.842484)
		(width 0.18288)
		(layer "In6.Cu")
		(net "M_G_CPU1_SA_DQ<29>")
	)
	(segment
		(start 183.062626 -279.277826)
		(end 179.564538 -279.277826)
		(width 0.18288)
		(layer "In6.Cu")
		(net "M_G_CPU1_SA_DQ<29>")
	)
	(segment
		(start 158.257494 -271.640808)
		(end 157.112716 -271.640808)
		(width 0.18288)
		(layer "In6.Cu")
		(net "M_G_CPU1_SA_DQ<29>")
	)
	(segment
		(start 163.467796 -271.805146)
		(end 163.284916 -271.622266)
		(width 0.18288)
		(layer "In6.Cu")
		(net "M_G_CPU1_SA_DQ<29>")
	)
	(segment
		(start 133.088888 -265.80719)
		(end 133.083046 -265.803634)
		(width 0.088646)
		(layer "In6.Cu")
		(net "M_G_CPU1_SA_DQ<29>")
	)
	(segment
		(start 175.230536 -272.542508)
		(end 174.3837 -272.542508)
		(width 0.18288)
		(layer "In6.Cu")
		(net "M_G_CPU1_SA_DQ<29>")
	)
	(segment
		(start 174.070264 -272.229072)
		(end 173.69028 -272.229072)
		(width 0.18288)
		(layer "In6.Cu")
		(net "M_G_CPU1_SA_DQ<29>")
	)
	(segment
		(start 127.88392 -266.600178)
		(end 127.256794 -266.128246)
		(width 0.088646)
		(layer "In6.Cu")
		(net "M_G_CPU1_SA_DQ<29>")
	)
	(segment
		(start 132.149088 -265.80719)
		(end 132.143246 -265.803634)
		(width 0.088646)
		(layer "In6.Cu")
		(net "M_G_CPU1_SA_DQ<29>")
	)
	(segment
		(start 131.203446 -265.803634)
		(end 131.197604 -265.800332)
		(width 0.088646)
		(layer "In6.Cu")
		(net "M_G_CPU1_SA_DQ<29>")
	)
	(segment
		(start 130.269488 -265.80719)
		(end 130.263646 -265.803634)
		(width 0.088646)
		(layer "In6.Cu")
		(net "M_G_CPU1_SA_DQ<29>")
	)
	(segment
		(start 142.356332 -265.966956)
		(end 140.595604 -265.966956)
		(width 0.18288)
		(layer "In6.Cu")
		(net "M_G_CPU1_SA_DQ<29>")
	)
	(segment
		(start 176.478946 -276.790658)
		(end 175.69307 -276.004782)
		(width 0.18288)
		(layer "In6.Cu")
		(net "M_G_CPU1_SA_DQ<29>")
	)
	(segment
		(start 151.964898 -266.49299)
		(end 145.001488 -266.49299)
		(width 0.18288)
		(layer "In6.Cu")
		(net "M_G_CPU1_SA_DQ<29>")
	)
	(segment
		(start 179.362354 -279.48001)
		(end 178.895502 -279.48001)
		(width 0.18288)
		(layer "In6.Cu")
		(net "M_G_CPU1_SA_DQ<29>")
	)
	(segment
		(start 135.527796 -265.803888)
		(end 135.513064 -265.812524)
		(width 0.088646)
		(layer "In6.Cu")
		(net "M_G_CPU1_SA_DQ<29>")
	)
	(segment
		(start 187.381642 -280.114756)
		(end 183.899556 -280.114756)
		(width 0.18288)
		(layer "In6.Cu")
		(net "M_G_CPU1_SA_DQ<29>")
	)
	(segment
		(start 175.122332 -274.084542)
		(end 175.282352 -273.924522)
		(width 0.18288)
		(layer "In6.Cu")
		(net "M_G_CPU1_SA_DQ<29>")
	)
	(segment
		(start 179.564538 -279.277826)
		(end 179.362354 -279.48001)
		(width 0.18288)
		(layer "In6.Cu")
		(net "M_G_CPU1_SA_DQ<29>")
	)
	(segment
		(start 172.101256 -272.542508)
		(end 171.78782 -272.229072)
		(width 0.18288)
		(layer "In6.Cu")
		(net "M_G_CPU1_SA_DQ<29>")
	)
	(segment
		(start 134.022846 -265.803634)
		(end 134.017004 -265.800332)
		(width 0.088646)
		(layer "In6.Cu")
		(net "M_G_CPU1_SA_DQ<29>")
	)
	(segment
		(start 128.485646 -266.613894)
		(end 128.47955 -266.61745)
		(width 0.088646)
		(layer "In6.Cu")
		(net "M_G_CPU1_SA_DQ<29>")
	)
	(segment
		(start 171.0944 -272.542508)
		(end 170.738292 -272.542508)
		(width 0.18288)
		(layer "In6.Cu")
		(net "M_G_CPU1_SA_DQ<29>")
	)
	(segment
		(start 178.895502 -279.48001)
		(end 178.231292 -278.8158)
		(width 0.18288)
		(layer "In6.Cu")
		(net "M_G_CPU1_SA_DQ<29>")
	)
	(segment
		(start 162.774376 -270.757396)
		(end 162.591496 -270.940276)
		(width 0.18288)
		(layer "In6.Cu")
		(net "M_G_CPU1_SA_DQ<29>")
	)
	(segment
		(start 175.248316 -276.004782)
		(end 175.088296 -275.844762)
		(width 0.18288)
		(layer "In6.Cu")
		(net "M_G_CPU1_SA_DQ<29>")
	)
	(segment
		(start 187.883546 -280.61666)
		(end 187.381642 -280.114756)
		(width 0.18288)
		(layer "In6.Cu")
		(net "M_G_CPU1_SA_DQ<29>")
	)
	(segment
		(start 163.284916 -271.622266)
		(end 163.284916 -270.940276)
		(width 0.18288)
		(layer "In6.Cu")
		(net "M_G_CPU1_SA_DQ<29>")
	)
	(segment
		(start 175.69307 -273.924522)
		(end 175.85309 -273.764502)
		(width 0.18288)
		(layer "In6.Cu")
		(net "M_G_CPU1_SA_DQ<29>")
	)
	(segment
		(start 175.69307 -275.311362)
		(end 175.85309 -275.151342)
		(width 0.18288)
		(layer "In6.Cu")
		(net "M_G_CPU1_SA_DQ<29>")
	)
	(segment
		(start 145.001488 -266.49299)
		(end 142.356332 -265.966956)
		(width 0.18288)
		(layer "In6.Cu")
		(net "M_G_CPU1_SA_DQ<29>")
	)
	(segment
		(start 175.282352 -273.924522)
		(end 175.69307 -273.924522)
		(width 0.18288)
		(layer "In6.Cu")
		(net "M_G_CPU1_SA_DQ<29>")
	)
	(segment
		(start 183.899556 -280.114756)
		(end 183.062626 -279.277826)
		(width 0.18288)
		(layer "In6.Cu")
		(net "M_G_CPU1_SA_DQ<29>")
	)
	(segment
		(start 127.928878 -266.626086)
		(end 127.914146 -266.61745)
		(width 0.088646)
		(layer "In6.Cu")
		(net "M_G_CPU1_SA_DQ<29>")
	)
	(segment
		(start 163.102036 -270.757396)
		(end 162.774376 -270.757396)
		(width 0.18288)
		(layer "In6.Cu")
		(net "M_G_CPU1_SA_DQ<29>")
	)
	(segment
		(start 163.284916 -270.940276)
		(end 163.102036 -270.757396)
		(width 0.18288)
		(layer "In6.Cu")
		(net "M_G_CPU1_SA_DQ<29>")
	)
	(segment
		(start 175.85309 -275.151342)
		(end 175.85309 -274.777962)
		(width 0.18288)
		(layer "In6.Cu")
		(net "M_G_CPU1_SA_DQ<29>")
	)
	(segment
		(start 140.595604 -265.966956)
		(end 140.316458 -265.966956)
		(width 0.088646)
		(layer "In6.Cu")
		(net "M_G_CPU1_SA_DQ<29>")
	)
	(segment
		(start 138.347196 -265.803888)
		(end 138.332464 -265.812524)
		(width 0.088646)
		(layer "In6.Cu")
		(net "M_G_CPU1_SA_DQ<29>")
	)
	(segment
		(start 175.85309 -273.764502)
		(end 175.85309 -273.165062)
		(width 0.18288)
		(layer "In6.Cu")
		(net "M_G_CPU1_SA_DQ<29>")
	)
	(segment
		(start 175.088296 -275.844762)
		(end 175.088296 -275.471382)
		(width 0.18288)
		(layer "In6.Cu")
		(net "M_G_CPU1_SA_DQ<29>")
	)
	(segment
		(start 175.122332 -274.457922)
		(end 175.122332 -274.084542)
		(width 0.18288)
		(layer "In6.Cu")
		(net "M_G_CPU1_SA_DQ<29>")
	)
	(segment
		(start 168.967404 -271.653508)
		(end 164.544248 -271.653508)
		(width 0.18288)
		(layer "In6.Cu")
		(net "M_G_CPU1_SA_DQ<29>")
	)
	(segment
		(start 173.376844 -272.542508)
		(end 172.101256 -272.542508)
		(width 0.18288)
		(layer "In6.Cu")
		(net "M_G_CPU1_SA_DQ<29>")
	)
	(segment
		(start 140.242544 -265.893042)
		(end 139.993624 -265.893042)
		(width 0.088646)
		(layer "In6.Cu")
		(net "M_G_CPU1_SA_DQ<29>")
	)
	(arc
		(start 133.077204 -265.800332)
		(mid 132.892349 -265.753382)
		(end 132.708396 -265.803634)
		(width 0.088646)
		(layer "In6.Cu")
		(net "M_G_CPU1_SA_DQ<29>")
	)
	(arc
		(start 131.768596 -265.803634)
		(mid 131.489422 -265.879399)
		(end 131.209288 -265.80719)
		(width 0.088646)
		(layer "In6.Cu")
		(net "M_G_CPU1_SA_DQ<29>")
	)
	(arc
		(start 135.902192 -265.803888)
		(mid 135.714994 -265.753745)
		(end 135.527796 -265.803888)
		(width 0.088646)
		(layer "In6.Cu")
		(net "M_G_CPU1_SA_DQ<29>")
	)
	(arc
		(start 129.323846 -265.803634)
		(mid 128.949371 -265.80368)
		(end 128.761998 -266.127992)
		(width 0.088646)
		(layer "In6.Cu")
		(net "M_G_CPU1_SA_DQ<29>")
	)
	(arc
		(start 138.721592 -265.803888)
		(mid 138.534394 -265.753745)
		(end 138.347196 -265.803888)
		(width 0.088646)
		(layer "In6.Cu")
		(net "M_G_CPU1_SA_DQ<29>")
	)
	(arc
		(start 139.661392 -265.803888)
		(mid 139.474194 -265.753745)
		(end 139.286996 -265.803888)
		(width 0.088646)
		(layer "In6.Cu")
		(net "M_G_CPU1_SA_DQ<29>")
	)
	(arc
		(start 134.956804 -265.800332)
		(mid 134.771949 -265.753382)
		(end 134.587996 -265.803634)
		(width 0.088646)
		(layer "In6.Cu")
		(net "M_G_CPU1_SA_DQ<29>")
	)
	(arc
		(start 134.017004 -265.800332)
		(mid 133.832149 -265.753382)
		(end 133.648196 -265.803634)
		(width 0.088646)
		(layer "In6.Cu")
		(net "M_G_CPU1_SA_DQ<29>")
	)
	(arc
		(start 135.513064 -265.812524)
		(mid 135.236623 -265.87969)
		(end 134.962392 -265.803888)
		(width 0.088646)
		(layer "In6.Cu")
		(net "M_G_CPU1_SA_DQ<29>")
	)
	(arc
		(start 138.332464 -265.812524)
		(mid 138.056023 -265.87969)
		(end 137.781792 -265.803888)
		(width 0.088646)
		(layer "In6.Cu")
		(net "M_G_CPU1_SA_DQ<29>")
	)
	(arc
		(start 133.648196 -265.803634)
		(mid 133.369022 -265.879399)
		(end 133.088888 -265.80719)
		(width 0.088646)
		(layer "In6.Cu")
		(net "M_G_CPU1_SA_DQ<29>")
	)
	(arc
		(start 128.47955 -266.61745)
		(mid 128.205351 -266.693285)
		(end 127.928878 -266.626086)
		(width 0.088646)
		(layer "In6.Cu")
		(net "M_G_CPU1_SA_DQ<29>")
	)
	(arc
		(start 136.841992 -265.803888)
		(mid 136.654794 -265.753745)
		(end 136.467596 -265.803888)
		(width 0.088646)
		(layer "In6.Cu")
		(net "M_G_CPU1_SA_DQ<29>")
	)
	(arc
		(start 137.392664 -265.812524)
		(mid 137.116223 -265.87969)
		(end 136.841992 -265.803888)
		(width 0.088646)
		(layer "In6.Cu")
		(net "M_G_CPU1_SA_DQ<29>")
	)
	(arc
		(start 134.587996 -265.803634)
		(mid 134.308822 -265.879399)
		(end 134.028688 -265.80719)
		(width 0.088646)
		(layer "In6.Cu")
		(net "M_G_CPU1_SA_DQ<29>")
	)
	(arc
		(start 131.197604 -265.800332)
		(mid 131.012749 -265.753382)
		(end 130.828796 -265.803634)
		(width 0.088646)
		(layer "In6.Cu")
		(net "M_G_CPU1_SA_DQ<29>")
	)
	(arc
		(start 139.272264 -265.812524)
		(mid 138.995823 -265.87969)
		(end 138.721592 -265.803888)
		(width 0.088646)
		(layer "In6.Cu")
		(net "M_G_CPU1_SA_DQ<29>")
	)
	(arc
		(start 128.761998 -266.127992)
		(mid 128.688082 -266.407494)
		(end 128.485646 -266.613894)
		(width 0.088646)
		(layer "In6.Cu")
		(net "M_G_CPU1_SA_DQ<29>")
	)
	(arc
		(start 129.878582 -265.80973)
		(mid 129.600404 -265.879453)
		(end 129.323846 -265.803634)
		(width 0.088646)
		(layer "In6.Cu")
		(net "M_G_CPU1_SA_DQ<29>")
	)
	(arc
		(start 132.137404 -265.800332)
		(mid 131.952549 -265.753382)
		(end 131.768596 -265.803634)
		(width 0.088646)
		(layer "In6.Cu")
		(net "M_G_CPU1_SA_DQ<29>")
	)
	(arc
		(start 132.708396 -265.803634)
		(mid 132.429222 -265.879399)
		(end 132.149088 -265.80719)
		(width 0.088646)
		(layer "In6.Cu")
		(net "M_G_CPU1_SA_DQ<29>")
	)
	(arc
		(start 139.993624 -265.893042)
		(mid 139.821625 -265.870377)
		(end 139.661392 -265.803888)
		(width 0.088646)
		(layer "In6.Cu")
		(net "M_G_CPU1_SA_DQ<29>")
	)
	(arc
		(start 137.781792 -265.803888)
		(mid 137.594594 -265.753745)
		(end 137.407396 -265.803888)
		(width 0.088646)
		(layer "In6.Cu")
		(net "M_G_CPU1_SA_DQ<29>")
	)
	(arc
		(start 130.828796 -265.803634)
		(mid 130.549622 -265.879399)
		(end 130.269488 -265.80719)
		(width 0.088646)
		(layer "In6.Cu")
		(net "M_G_CPU1_SA_DQ<29>")
	)
	(arc
		(start 136.452864 -265.812524)
		(mid 136.176423 -265.87969)
		(end 135.902192 -265.803888)
		(width 0.088646)
		(layer "In6.Cu")
		(net "M_G_CPU1_SA_DQ<29>")
	)
	(arc
		(start 130.257804 -265.800332)
		(mid 130.072949 -265.753382)
		(end 129.888996 -265.803634)
		(width 0.088646)
		(layer "In6.Cu")
		(net "M_G_CPU1_SA_DQ<29>")
	)
	(segment
		(start 191.539114 -281.89174)
		(end 191.421004 -282.00985)
		(width 0.20066)
		(layer "F.Cu")
		(net "M_G_CPU1_SA_DQ<28>")
	)
	(segment
		(start 194.940428 -282.316936)
		(end 194.508882 -281.88539)
		(width 0.20066)
		(layer "F.Cu")
		(net "M_G_CPU1_SA_DQ<28>")
	)
	(segment
		(start 190.509144 -282.316682)
		(end 188.988446 -282.316682)
		(width 0.20066)
		(layer "F.Cu")
		(net "M_G_CPU1_SA_DQ<28>")
	)
	(segment
		(start 194.092576 -281.89174)
		(end 191.930782 -281.89174)
		(width 0.1016)
		(layer "F.Cu")
		(net "M_G_CPU1_SA_DQ<28>")
	)
	(segment
		(start 126.786894 -266.941554)
		(end 126.787148 -266.941808)
		(width 0.20066)
		(layer "F.Cu")
		(net "M_G_CPU1_SA_DQ<28>")
	)
	(segment
		(start 126.786894 -266.405868)
		(end 126.786894 -266.941554)
		(width 0.20066)
		(layer "F.Cu")
		(net "M_G_CPU1_SA_DQ<28>")
	)
	(segment
		(start 196.532246 -282.316682)
		(end 196.531992 -282.316936)
		(width 0.20066)
		(layer "F.Cu")
		(net "M_G_CPU1_SA_DQ<28>")
	)
	(segment
		(start 191.421004 -282.377388)
		(end 191.233044 -282.565348)
		(width 0.20066)
		(layer "F.Cu")
		(net "M_G_CPU1_SA_DQ<28>")
	)
	(segment
		(start 196.531992 -282.316936)
		(end 194.940428 -282.316936)
		(width 0.20066)
		(layer "F.Cu")
		(net "M_G_CPU1_SA_DQ<28>")
	)
	(segment
		(start 190.75781 -282.565348)
		(end 190.509144 -282.316682)
		(width 0.20066)
		(layer "F.Cu")
		(net "M_G_CPU1_SA_DQ<28>")
	)
	(segment
		(start 194.098926 -281.88539)
		(end 194.092576 -281.89174)
		(width 0.1016)
		(layer "F.Cu")
		(net "M_G_CPU1_SA_DQ<28>")
	)
	(segment
		(start 191.233044 -282.565348)
		(end 190.75781 -282.565348)
		(width 0.20066)
		(layer "F.Cu")
		(net "M_G_CPU1_SA_DQ<28>")
	)
	(segment
		(start 191.930782 -281.89174)
		(end 191.775842 -281.89174)
		(width 0.101854)
		(layer "F.Cu")
		(net "M_G_CPU1_SA_DQ<28>")
	)
	(segment
		(start 191.421004 -282.00985)
		(end 191.421004 -282.377388)
		(width 0.20066)
		(layer "F.Cu")
		(net "M_G_CPU1_SA_DQ<28>")
	)
	(segment
		(start 191.775842 -281.89174)
		(end 191.539114 -281.89174)
		(width 0.20066)
		(layer "F.Cu")
		(net "M_G_CPU1_SA_DQ<28>")
	)
	(segment
		(start 194.508882 -281.88539)
		(end 194.098926 -281.88539)
		(width 0.20066)
		(layer "F.Cu")
		(net "M_G_CPU1_SA_DQ<28>")
	)
	(segment
		(start 188.988446 -282.316682)
		(end 187.883546 -282.316682)
		(width 0.20066)
		(layer "F.Cu")
		(net "M_G_CPU1_SA_DQ<28>")
	)
	(segment
		(start 159.376872 -273.218402)
		(end 159.193992 -273.401282)
		(width 0.18288)
		(layer "In6.Cu")
		(net "M_G_CPU1_SA_DQ<28>")
	)
	(segment
		(start 168.874186 -273.332448)
		(end 167.300402 -273.332448)
		(width 0.18288)
		(layer "In6.Cu")
		(net "M_G_CPU1_SA_DQ<28>")
	)
	(segment
		(start 131.298696 -266.61745)
		(end 131.292854 -266.621006)
		(width 0.088646)
		(layer "In6.Cu")
		(net "M_G_CPU1_SA_DQ<28>")
	)
	(segment
		(start 139.75588 -266.617704)
		(end 139.745466 -266.6238)
		(width 0.088646)
		(layer "In6.Cu")
		(net "M_G_CPU1_SA_DQ<28>")
	)
	(segment
		(start 159.193992 -273.401282)
		(end 159.193992 -273.633438)
		(width 0.18288)
		(layer "In6.Cu")
		(net "M_G_CPU1_SA_DQ<28>")
	)
	(segment
		(start 151.364442 -267.504672)
		(end 144.982438 -267.504672)
		(width 0.18288)
		(layer "In6.Cu")
		(net "M_G_CPU1_SA_DQ<28>")
	)
	(segment
		(start 162.412426 -273.574256)
		(end 161.199576 -273.574256)
		(width 0.18288)
		(layer "In6.Cu")
		(net "M_G_CPU1_SA_DQ<28>")
	)
	(segment
		(start 171.68114 -275.057616)
		(end 171.35348 -275.057616)
		(width 0.18288)
		(layer "In6.Cu")
		(net "M_G_CPU1_SA_DQ<28>")
	)
	(segment
		(start 179.50434 -281.221942)
		(end 178.980846 -281.221942)
		(width 0.18288)
		(layer "In6.Cu")
		(net "M_G_CPU1_SA_DQ<28>")
	)
	(segment
		(start 177.78349 -280.283158)
		(end 177.78349 -280.024586)
		(width 0.18288)
		(layer "In6.Cu")
		(net "M_G_CPU1_SA_DQ<28>")
	)
	(segment
		(start 132.238496 -266.61745)
		(end 132.232654 -266.621006)
		(width 0.088646)
		(layer "In6.Cu")
		(net "M_G_CPU1_SA_DQ<28>")
	)
	(segment
		(start 162.778186 -272.922238)
		(end 162.595306 -273.105118)
		(width 0.18288)
		(layer "In6.Cu")
		(net "M_G_CPU1_SA_DQ<28>")
	)
	(segment
		(start 173.998382 -275.325078)
		(end 173.998382 -274.665694)
		(width 0.18288)
		(layer "In6.Cu")
		(net "M_G_CPU1_SA_DQ<28>")
	)
	(segment
		(start 159.011112 -273.816318)
		(end 158.683452 -273.816318)
		(width 0.18288)
		(layer "In6.Cu")
		(net "M_G_CPU1_SA_DQ<28>")
	)
	(segment
		(start 173.998382 -277.106888)
		(end 173.998382 -276.384258)
		(width 0.18288)
		(layer "In6.Cu")
		(net "M_G_CPU1_SA_DQ<28>")
	)
	(segment
		(start 127.512064 -267.24991)
		(end 126.787148 -266.941808)
		(width 0.088646)
		(layer "In6.Cu")
		(net "M_G_CPU1_SA_DQ<28>")
	)
	(segment
		(start 158.683452 -273.816318)
		(end 158.500572 -273.633438)
		(width 0.18288)
		(layer "In6.Cu")
		(net "M_G_CPU1_SA_DQ<28>")
	)
	(segment
		(start 163.288726 -273.105118)
		(end 163.105846 -272.922238)
		(width 0.18288)
		(layer "In6.Cu")
		(net "M_G_CPU1_SA_DQ<28>")
	)
	(segment
		(start 127.53975 -267.266166)
		(end 127.512064 -267.24991)
		(width 0.088646)
		(layer "In6.Cu")
		(net "M_G_CPU1_SA_DQ<28>")
	)
	(segment
		(start 174.457106 -277.565612)
		(end 173.998382 -277.106888)
		(width 0.18288)
		(layer "In6.Cu")
		(net "M_G_CPU1_SA_DQ<28>")
	)
	(segment
		(start 178.273964 -280.773632)
		(end 177.891186 -281.15641)
		(width 0.18288)
		(layer "In6.Cu")
		(net "M_G_CPU1_SA_DQ<28>")
	)
	(segment
		(start 177.632614 -281.15641)
		(end 177.400712 -280.924508)
		(width 0.18288)
		(layer "In6.Cu")
		(net "M_G_CPU1_SA_DQ<28>")
	)
	(segment
		(start 134.118096 -266.61745)
		(end 134.112254 -266.621006)
		(width 0.088646)
		(layer "In6.Cu")
		(net "M_G_CPU1_SA_DQ<28>")
	)
	(segment
		(start 127.928878 -267.25753)
		(end 127.914146 -267.266166)
		(width 0.088646)
		(layer "In6.Cu")
		(net "M_G_CPU1_SA_DQ<28>")
	)
	(segment
		(start 162.595306 -273.391376)
		(end 162.412426 -273.574256)
		(width 0.18288)
		(layer "In6.Cu")
		(net "M_G_CPU1_SA_DQ<28>")
	)
	(segment
		(start 138.816334 -266.617704)
		(end 138.80592 -266.6238)
		(width 0.088646)
		(layer "In6.Cu")
		(net "M_G_CPU1_SA_DQ<28>")
	)
	(segment
		(start 178.532536 -280.773632)
		(end 178.273964 -280.773632)
		(width 0.18288)
		(layer "In6.Cu")
		(net "M_G_CPU1_SA_DQ<28>")
	)
	(segment
		(start 134.123938 -266.614148)
		(end 134.118096 -266.61745)
		(width 0.088646)
		(layer "In6.Cu")
		(net "M_G_CPU1_SA_DQ<28>")
	)
	(segment
		(start 158.317692 -273.218402)
		(end 157.115764 -273.218402)
		(width 0.18288)
		(layer "In6.Cu")
		(net "M_G_CPU1_SA_DQ<28>")
	)
	(segment
		(start 133.184138 -266.614148)
		(end 133.178296 -266.61745)
		(width 0.088646)
		(layer "In6.Cu")
		(net "M_G_CPU1_SA_DQ<28>")
	)
	(segment
		(start 164.80155 -273.332448)
		(end 164.559742 -273.574256)
		(width 0.18288)
		(layer "In6.Cu")
		(net "M_G_CPU1_SA_DQ<28>")
	)
	(segment
		(start 164.559742 -273.574256)
		(end 163.471606 -273.574256)
		(width 0.18288)
		(layer "In6.Cu")
		(net "M_G_CPU1_SA_DQ<28>")
	)
	(segment
		(start 173.998382 -274.665694)
		(end 173.575218 -274.24253)
		(width 0.18288)
		(layer "In6.Cu")
		(net "M_G_CPU1_SA_DQ<28>")
	)
	(segment
		(start 177.78349 -280.024586)
		(end 177.100484 -279.34158)
		(width 0.18288)
		(layer "In6.Cu")
		(net "M_G_CPU1_SA_DQ<28>")
	)
	(segment
		(start 177.100484 -279.34158)
		(end 176.585372 -279.34158)
		(width 0.18288)
		(layer "In6.Cu")
		(net "M_G_CPU1_SA_DQ<28>")
	)
	(segment
		(start 178.980846 -281.221942)
		(end 178.532536 -280.773632)
		(width 0.18288)
		(layer "In6.Cu")
		(net "M_G_CPU1_SA_DQ<28>")
	)
	(segment
		(start 163.105846 -272.922238)
		(end 162.778186 -272.922238)
		(width 0.18288)
		(layer "In6.Cu")
		(net "M_G_CPU1_SA_DQ<28>")
	)
	(segment
		(start 160.843722 -273.218402)
		(end 159.376872 -273.218402)
		(width 0.18288)
		(layer "In6.Cu")
		(net "M_G_CPU1_SA_DQ<28>")
	)
	(segment
		(start 132.244338 -266.614148)
		(end 132.238496 -266.61745)
		(width 0.088646)
		(layer "In6.Cu")
		(net "M_G_CPU1_SA_DQ<28>")
	)
	(segment
		(start 183.764682 -281.732482)
		(end 183.063388 -281.031188)
		(width 0.18288)
		(layer "In6.Cu")
		(net "M_G_CPU1_SA_DQ<28>")
	)
	(segment
		(start 136.937242 -266.617704)
		(end 136.926828 -266.6238)
		(width 0.088646)
		(layer "In6.Cu")
		(net "M_G_CPU1_SA_DQ<28>")
	)
	(segment
		(start 130.364738 -266.614148)
		(end 130.358896 -266.61745)
		(width 0.088646)
		(layer "In6.Cu")
		(net "M_G_CPU1_SA_DQ<28>")
	)
	(segment
		(start 170.98772 -274.24253)
		(end 169.784268 -274.24253)
		(width 0.18288)
		(layer "In6.Cu")
		(net "M_G_CPU1_SA_DQ<28>")
	)
	(segment
		(start 173.252384 -276.018498)
		(end 173.252384 -275.690838)
		(width 0.18288)
		(layer "In6.Cu")
		(net "M_G_CPU1_SA_DQ<28>")
	)
	(segment
		(start 167.300402 -273.332448)
		(end 166.914322 -273.718528)
		(width 0.18288)
		(layer "In6.Cu")
		(net "M_G_CPU1_SA_DQ<28>")
	)
	(segment
		(start 142.302992 -266.97178)
		(end 140.595604 -266.97178)
		(width 0.18288)
		(layer "In6.Cu")
		(net "M_G_CPU1_SA_DQ<28>")
	)
	(segment
		(start 158.500572 -273.401282)
		(end 158.317692 -273.218402)
		(width 0.18288)
		(layer "In6.Cu")
		(net "M_G_CPU1_SA_DQ<28>")
	)
	(segment
		(start 172.0469 -274.24253)
		(end 171.86402 -274.42541)
		(width 0.18288)
		(layer "In6.Cu")
		(net "M_G_CPU1_SA_DQ<28>")
	)
	(segment
		(start 162.595306 -273.105118)
		(end 162.595306 -273.391376)
		(width 0.18288)
		(layer "In6.Cu")
		(net "M_G_CPU1_SA_DQ<28>")
	)
	(segment
		(start 133.178296 -266.61745)
		(end 133.172454 -266.621006)
		(width 0.088646)
		(layer "In6.Cu")
		(net "M_G_CPU1_SA_DQ<28>")
	)
	(segment
		(start 176.585372 -279.34158)
		(end 176.368456 -279.124664)
		(width 0.18288)
		(layer "In6.Cu")
		(net "M_G_CPU1_SA_DQ<28>")
	)
	(segment
		(start 157.115764 -273.218402)
		(end 151.364442 -267.504672)
		(width 0.18288)
		(layer "In6.Cu")
		(net "M_G_CPU1_SA_DQ<28>")
	)
	(segment
		(start 177.891186 -281.15641)
		(end 177.632614 -281.15641)
		(width 0.18288)
		(layer "In6.Cu")
		(net "M_G_CPU1_SA_DQ<28>")
	)
	(segment
		(start 173.815502 -276.201378)
		(end 173.435264 -276.201378)
		(width 0.18288)
		(layer "In6.Cu")
		(net "M_G_CPU1_SA_DQ<28>")
	)
	(segment
		(start 137.876788 -266.617704)
		(end 137.866374 -266.6238)
		(width 0.088646)
		(layer "In6.Cu")
		(net "M_G_CPU1_SA_DQ<28>")
	)
	(segment
		(start 163.471606 -273.574256)
		(end 163.288726 -273.391376)
		(width 0.18288)
		(layer "In6.Cu")
		(net "M_G_CPU1_SA_DQ<28>")
	)
	(segment
		(start 158.500572 -273.633438)
		(end 158.500572 -273.401282)
		(width 0.18288)
		(layer "In6.Cu")
		(net "M_G_CPU1_SA_DQ<28>")
	)
	(segment
		(start 165.478206 -273.332448)
		(end 164.80155 -273.332448)
		(width 0.18288)
		(layer "In6.Cu")
		(net "M_G_CPU1_SA_DQ<28>")
	)
	(segment
		(start 165.864286 -273.718528)
		(end 165.478206 -273.332448)
		(width 0.18288)
		(layer "In6.Cu")
		(net "M_G_CPU1_SA_DQ<28>")
	)
	(segment
		(start 183.063388 -281.031188)
		(end 179.695094 -281.031188)
		(width 0.18288)
		(layer "In6.Cu")
		(net "M_G_CPU1_SA_DQ<28>")
	)
	(segment
		(start 187.641738 -282.074874)
		(end 187.233814 -282.074874)
		(width 0.18288)
		(layer "In6.Cu")
		(net "M_G_CPU1_SA_DQ<28>")
	)
	(segment
		(start 171.1706 -274.42541)
		(end 170.98772 -274.24253)
		(width 0.18288)
		(layer "In6.Cu")
		(net "M_G_CPU1_SA_DQ<28>")
	)
	(segment
		(start 159.193992 -273.633438)
		(end 159.011112 -273.816318)
		(width 0.18288)
		(layer "In6.Cu")
		(net "M_G_CPU1_SA_DQ<28>")
	)
	(segment
		(start 175.42256 -277.565612)
		(end 174.457106 -277.565612)
		(width 0.18288)
		(layer "In6.Cu")
		(net "M_G_CPU1_SA_DQ<28>")
	)
	(segment
		(start 173.998382 -276.384258)
		(end 173.815502 -276.201378)
		(width 0.18288)
		(layer "In6.Cu")
		(net "M_G_CPU1_SA_DQ<28>")
	)
	(segment
		(start 177.400712 -280.665936)
		(end 177.78349 -280.283158)
		(width 0.18288)
		(layer "In6.Cu")
		(net "M_G_CPU1_SA_DQ<28>")
	)
	(segment
		(start 140.359892 -266.97178)
		(end 140.000228 -266.612116)
		(width 0.088646)
		(layer "In6.Cu")
		(net "M_G_CPU1_SA_DQ<28>")
	)
	(segment
		(start 166.914322 -273.718528)
		(end 165.864286 -273.718528)
		(width 0.18288)
		(layer "In6.Cu")
		(net "M_G_CPU1_SA_DQ<28>")
	)
	(segment
		(start 177.400712 -280.924508)
		(end 177.400712 -280.665936)
		(width 0.18288)
		(layer "In6.Cu")
		(net "M_G_CPU1_SA_DQ<28>")
	)
	(segment
		(start 187.233814 -282.074874)
		(end 186.891422 -281.732482)
		(width 0.18288)
		(layer "In6.Cu")
		(net "M_G_CPU1_SA_DQ<28>")
	)
	(segment
		(start 161.199576 -273.574256)
		(end 160.843722 -273.218402)
		(width 0.18288)
		(layer "In6.Cu")
		(net "M_G_CPU1_SA_DQ<28>")
	)
	(segment
		(start 169.784268 -274.24253)
		(end 168.874186 -273.332448)
		(width 0.18288)
		(layer "In6.Cu")
		(net "M_G_CPU1_SA_DQ<28>")
	)
	(segment
		(start 173.435264 -276.201378)
		(end 173.252384 -276.018498)
		(width 0.18288)
		(layer "In6.Cu")
		(net "M_G_CPU1_SA_DQ<28>")
	)
	(segment
		(start 130.358896 -266.61745)
		(end 130.353054 -266.621006)
		(width 0.088646)
		(layer "In6.Cu")
		(net "M_G_CPU1_SA_DQ<28>")
	)
	(segment
		(start 176.368456 -279.124664)
		(end 176.368456 -278.511508)
		(width 0.18288)
		(layer "In6.Cu")
		(net "M_G_CPU1_SA_DQ<28>")
	)
	(segment
		(start 140.595604 -266.97178)
		(end 140.359892 -266.97178)
		(width 0.088646)
		(layer "In6.Cu")
		(net "M_G_CPU1_SA_DQ<28>")
	)
	(segment
		(start 135.05815 -266.617704)
		(end 135.052054 -266.621006)
		(width 0.088646)
		(layer "In6.Cu")
		(net "M_G_CPU1_SA_DQ<28>")
	)
	(segment
		(start 173.575218 -274.24253)
		(end 172.0469 -274.24253)
		(width 0.18288)
		(layer "In6.Cu")
		(net "M_G_CPU1_SA_DQ<28>")
	)
	(segment
		(start 144.982438 -267.504672)
		(end 142.302992 -266.97178)
		(width 0.18288)
		(layer "In6.Cu")
		(net "M_G_CPU1_SA_DQ<28>")
	)
	(segment
		(start 131.304538 -266.614148)
		(end 131.298696 -266.61745)
		(width 0.088646)
		(layer "In6.Cu")
		(net "M_G_CPU1_SA_DQ<28>")
	)
	(segment
		(start 171.86402 -274.874736)
		(end 171.68114 -275.057616)
		(width 0.18288)
		(layer "In6.Cu")
		(net "M_G_CPU1_SA_DQ<28>")
	)
	(segment
		(start 173.252384 -275.690838)
		(end 173.435264 -275.507958)
		(width 0.18288)
		(layer "In6.Cu")
		(net "M_G_CPU1_SA_DQ<28>")
	)
	(segment
		(start 163.288726 -273.391376)
		(end 163.288726 -273.105118)
		(width 0.18288)
		(layer "In6.Cu")
		(net "M_G_CPU1_SA_DQ<28>")
	)
	(segment
		(start 179.695094 -281.031188)
		(end 179.50434 -281.221942)
		(width 0.18288)
		(layer "In6.Cu")
		(net "M_G_CPU1_SA_DQ<28>")
	)
	(segment
		(start 171.35348 -275.057616)
		(end 171.1706 -274.874736)
		(width 0.18288)
		(layer "In6.Cu")
		(net "M_G_CPU1_SA_DQ<28>")
	)
	(segment
		(start 171.86402 -274.42541)
		(end 171.86402 -274.874736)
		(width 0.18288)
		(layer "In6.Cu")
		(net "M_G_CPU1_SA_DQ<28>")
	)
	(segment
		(start 173.815502 -275.507958)
		(end 173.998382 -275.325078)
		(width 0.18288)
		(layer "In6.Cu")
		(net "M_G_CPU1_SA_DQ<28>")
	)
	(segment
		(start 173.435264 -275.507958)
		(end 173.815502 -275.507958)
		(width 0.18288)
		(layer "In6.Cu")
		(net "M_G_CPU1_SA_DQ<28>")
	)
	(segment
		(start 186.891422 -281.732482)
		(end 183.764682 -281.732482)
		(width 0.18288)
		(layer "In6.Cu")
		(net "M_G_CPU1_SA_DQ<28>")
	)
	(segment
		(start 176.368456 -278.511508)
		(end 175.42256 -277.565612)
		(width 0.18288)
		(layer "In6.Cu")
		(net "M_G_CPU1_SA_DQ<28>")
	)
	(segment
		(start 135.44296 -266.6238)
		(end 135.432546 -266.617704)
		(width 0.088646)
		(layer "In6.Cu")
		(net "M_G_CPU1_SA_DQ<28>")
	)
	(segment
		(start 187.883546 -282.316682)
		(end 187.641738 -282.074874)
		(width 0.18288)
		(layer "In6.Cu")
		(net "M_G_CPU1_SA_DQ<28>")
	)
	(segment
		(start 171.1706 -274.874736)
		(end 171.1706 -274.42541)
		(width 0.18288)
		(layer "In6.Cu")
		(net "M_G_CPU1_SA_DQ<28>")
	)
	(arc
		(start 127.914146 -267.266166)
		(mid 127.726948 -267.316309)
		(end 127.53975 -267.266166)
		(width 0.088646)
		(layer "In6.Cu")
		(net "M_G_CPU1_SA_DQ<28>")
	)
	(arc
		(start 129.793746 -266.61745)
		(mid 129.602308 -266.567201)
		(end 129.411984 -266.621514)
		(width 0.088646)
		(layer "In6.Cu")
		(net "M_G_CPU1_SA_DQ<28>")
	)
	(arc
		(start 139.745466 -266.6238)
		(mid 139.467288 -266.693523)
		(end 139.19073 -266.617704)
		(width 0.088646)
		(layer "In6.Cu")
		(net "M_G_CPU1_SA_DQ<28>")
	)
	(arc
		(start 131.673346 -266.61745)
		(mid 131.489392 -266.567321)
		(end 131.304538 -266.614148)
		(width 0.088646)
		(layer "In6.Cu")
		(net "M_G_CPU1_SA_DQ<28>")
	)
	(arc
		(start 132.232654 -266.621006)
		(mid 131.952519 -266.693322)
		(end 131.673346 -266.61745)
		(width 0.088646)
		(layer "In6.Cu")
		(net "M_G_CPU1_SA_DQ<28>")
	)
	(arc
		(start 135.432546 -266.617704)
		(mid 135.245348 -266.567527)
		(end 135.05815 -266.617704)
		(width 0.088646)
		(layer "In6.Cu")
		(net "M_G_CPU1_SA_DQ<28>")
	)
	(arc
		(start 129.254504 -266.813538)
		(mid 129.22285 -266.885618)
		(end 129.182114 -266.952984)
		(width 0.088646)
		(layer "In6.Cu")
		(net "M_G_CPU1_SA_DQ<28>")
	)
	(arc
		(start 140.000228 -266.612116)
		(mid 139.96297 -266.586614)
		(end 139.918948 -266.576556)
		(width 0.088646)
		(layer "In6.Cu")
		(net "M_G_CPU1_SA_DQ<28>")
	)
	(arc
		(start 135.052054 -266.621006)
		(mid 134.771919 -266.693322)
		(end 134.492746 -266.61745)
		(width 0.088646)
		(layer "In6.Cu")
		(net "M_G_CPU1_SA_DQ<28>")
	)
	(arc
		(start 133.172454 -266.621006)
		(mid 132.892319 -266.693322)
		(end 132.613146 -266.61745)
		(width 0.088646)
		(layer "In6.Cu")
		(net "M_G_CPU1_SA_DQ<28>")
	)
	(arc
		(start 128.853946 -267.266166)
		(mid 128.666748 -267.316309)
		(end 128.47955 -267.266166)
		(width 0.088646)
		(layer "In6.Cu")
		(net "M_G_CPU1_SA_DQ<28>")
	)
	(arc
		(start 135.997696 -266.617704)
		(mid 135.721137 -266.693447)
		(end 135.44296 -266.6238)
		(width 0.088646)
		(layer "In6.Cu")
		(net "M_G_CPU1_SA_DQ<28>")
	)
	(arc
		(start 128.47955 -267.266166)
		(mid 128.205321 -267.190241)
		(end 127.928878 -267.25753)
		(width 0.088646)
		(layer "In6.Cu")
		(net "M_G_CPU1_SA_DQ<28>")
	)
	(arc
		(start 138.80592 -266.6238)
		(mid 138.527742 -266.693523)
		(end 138.251184 -266.617704)
		(width 0.088646)
		(layer "In6.Cu")
		(net "M_G_CPU1_SA_DQ<28>")
	)
	(arc
		(start 129.411984 -266.621514)
		(mid 129.316892 -266.704109)
		(end 129.254504 -266.813538)
		(width 0.088646)
		(layer "In6.Cu")
		(net "M_G_CPU1_SA_DQ<28>")
	)
	(arc
		(start 134.492746 -266.61745)
		(mid 134.308792 -266.567321)
		(end 134.123938 -266.614148)
		(width 0.088646)
		(layer "In6.Cu")
		(net "M_G_CPU1_SA_DQ<28>")
	)
	(arc
		(start 137.311638 -266.617704)
		(mid 137.12444 -266.567527)
		(end 136.937242 -266.617704)
		(width 0.088646)
		(layer "In6.Cu")
		(net "M_G_CPU1_SA_DQ<28>")
	)
	(arc
		(start 132.613146 -266.61745)
		(mid 132.429192 -266.567321)
		(end 132.244338 -266.614148)
		(width 0.088646)
		(layer "In6.Cu")
		(net "M_G_CPU1_SA_DQ<28>")
	)
	(arc
		(start 138.251184 -266.617704)
		(mid 138.063986 -266.567527)
		(end 137.876788 -266.617704)
		(width 0.088646)
		(layer "In6.Cu")
		(net "M_G_CPU1_SA_DQ<28>")
	)
	(arc
		(start 134.112254 -266.621006)
		(mid 133.832119 -266.693322)
		(end 133.552946 -266.61745)
		(width 0.088646)
		(layer "In6.Cu")
		(net "M_G_CPU1_SA_DQ<28>")
	)
	(arc
		(start 131.292854 -266.621006)
		(mid 131.012719 -266.693322)
		(end 130.733546 -266.61745)
		(width 0.088646)
		(layer "In6.Cu")
		(net "M_G_CPU1_SA_DQ<28>")
	)
	(arc
		(start 136.926828 -266.6238)
		(mid 136.64865 -266.693523)
		(end 136.372092 -266.617704)
		(width 0.088646)
		(layer "In6.Cu")
		(net "M_G_CPU1_SA_DQ<28>")
	)
	(arc
		(start 136.372092 -266.617704)
		(mid 136.184894 -266.567527)
		(end 135.997696 -266.617704)
		(width 0.088646)
		(layer "In6.Cu")
		(net "M_G_CPU1_SA_DQ<28>")
	)
	(arc
		(start 129.182114 -266.952984)
		(mid 129.144029 -267.043875)
		(end 129.077466 -267.11656)
		(width 0.088646)
		(layer "In6.Cu")
		(net "M_G_CPU1_SA_DQ<28>")
	)
	(arc
		(start 133.552946 -266.61745)
		(mid 133.368992 -266.567321)
		(end 133.184138 -266.614148)
		(width 0.088646)
		(layer "In6.Cu")
		(net "M_G_CPU1_SA_DQ<28>")
	)
	(arc
		(start 139.19073 -266.617704)
		(mid 139.003532 -266.567527)
		(end 138.816334 -266.617704)
		(width 0.088646)
		(layer "In6.Cu")
		(net "M_G_CPU1_SA_DQ<28>")
	)
	(arc
		(start 137.866374 -266.6238)
		(mid 137.588196 -266.693523)
		(end 137.311638 -266.617704)
		(width 0.088646)
		(layer "In6.Cu")
		(net "M_G_CPU1_SA_DQ<28>")
	)
	(arc
		(start 130.733546 -266.61745)
		(mid 130.549592 -266.567321)
		(end 130.364738 -266.614148)
		(width 0.088646)
		(layer "In6.Cu")
		(net "M_G_CPU1_SA_DQ<28>")
	)
	(arc
		(start 130.353054 -266.621006)
		(mid 130.072919 -266.693322)
		(end 129.793746 -266.61745)
		(width 0.088646)
		(layer "In6.Cu")
		(net "M_G_CPU1_SA_DQ<28>")
	)
	(arc
		(start 129.077466 -267.11656)
		(mid 128.968194 -267.19508)
		(end 128.853946 -267.266166)
		(width 0.088646)
		(layer "In6.Cu")
		(net "M_G_CPU1_SA_DQ<28>")
	)
	(arc
		(start 139.918948 -266.576556)
		(mid 139.834544 -266.58574)
		(end 139.75588 -266.617704)
		(width 0.088646)
		(layer "In6.Cu")
		(net "M_G_CPU1_SA_DQ<28>")
	)
	(segment
		(start 198.662036 -285.464758)
		(end 199.046084 -285.464758)
		(width 0.20066)
		(layer "F.Cu")
		(net "M_G_CPU1_SA_DQ<27>")
	)
	(segment
		(start 197.542658 -286.15386)
		(end 198.223886 -286.15386)
		(width 0.20066)
		(layer "F.Cu")
		(net "M_G_CPU1_SA_DQ<27>")
	)
	(segment
		(start 199.046084 -285.464758)
		(end 199.298052 -285.716726)
		(width 0.20066)
		(layer "F.Cu")
		(net "M_G_CPU1_SA_DQ<27>")
	)
	(segment
		(start 194.786758 -285.716726)
		(end 195.218812 -286.14878)
		(width 0.20066)
		(layer "F.Cu")
		(net "M_G_CPU1_SA_DQ<27>")
	)
	(segment
		(start 198.427848 -285.698946)
		(end 198.662036 -285.464758)
		(width 0.20066)
		(layer "F.Cu")
		(net "M_G_CPU1_SA_DQ<27>")
	)
	(segment
		(start 195.510658 -286.14878)
		(end 195.515484 -286.14878)
		(width 0.101854)
		(layer "F.Cu")
		(net "M_G_CPU1_SA_DQ<27>")
	)
	(segment
		(start 198.223886 -286.15386)
		(end 198.427848 -285.949898)
		(width 0.20066)
		(layer "F.Cu")
		(net "M_G_CPU1_SA_DQ<27>")
	)
	(segment
		(start 197.530466 -286.141668)
		(end 197.542658 -286.15386)
		(width 0.1016)
		(layer "F.Cu")
		(net "M_G_CPU1_SA_DQ<27>")
	)
	(segment
		(start 195.515484 -286.14878)
		(end 195.522596 -286.141668)
		(width 0.1016)
		(layer "F.Cu")
		(net "M_G_CPU1_SA_DQ<27>")
	)
	(segment
		(start 195.522596 -286.141668)
		(end 197.530466 -286.141668)
		(width 0.1016)
		(layer "F.Cu")
		(net "M_G_CPU1_SA_DQ<27>")
	)
	(segment
		(start 193.088514 -285.716726)
		(end 194.786758 -285.716726)
		(width 0.20066)
		(layer "F.Cu")
		(net "M_G_CPU1_SA_DQ<27>")
	)
	(segment
		(start 195.218812 -286.14878)
		(end 195.510658 -286.14878)
		(width 0.20066)
		(layer "F.Cu")
		(net "M_G_CPU1_SA_DQ<27>")
	)
	(segment
		(start 199.298052 -285.716726)
		(end 200.632314 -285.716726)
		(width 0.20066)
		(layer "F.Cu")
		(net "M_G_CPU1_SA_DQ<27>")
	)
	(segment
		(start 198.427848 -285.949898)
		(end 198.427848 -285.698946)
		(width 0.20066)
		(layer "F.Cu")
		(net "M_G_CPU1_SA_DQ<27>")
	)
	(segment
		(start 128.666748 -268.034008)
		(end 128.666748 -268.569694)
		(width 0.20066)
		(layer "F.Cu")
		(net "M_G_CPU1_SA_DQ<27>")
	)
	(segment
		(start 128.666494 -268.033754)
		(end 128.666748 -268.034008)
		(width 0.20066)
		(layer "F.Cu")
		(net "M_G_CPU1_SA_DQ<27>")
	)
	(segment
		(start 191.983614 -285.716726)
		(end 193.088514 -285.716726)
		(width 0.20066)
		(layer "F.Cu")
		(net "M_G_CPU1_SA_DQ<27>")
	)
	(segment
		(start 170.771566 -280.063194)
		(end 170.539664 -279.831292)
		(width 0.18288)
		(layer "In6.Cu")
		(net "M_G_CPU1_SA_DQ<27>")
	)
	(segment
		(start 188.94933 -285.292292)
		(end 186.979814 -285.292292)
		(width 0.18288)
		(layer "In6.Cu")
		(net "M_G_CPU1_SA_DQ<27>")
	)
	(segment
		(start 136.937242 -268.894052)
		(end 136.926828 -268.887956)
		(width 0.088646)
		(layer "In6.Cu")
		(net "M_G_CPU1_SA_DQ<27>")
	)
	(segment
		(start 185.05551 -285.406592)
		(end 184.178956 -285.406592)
		(width 0.18288)
		(layer "In6.Cu")
		(net "M_G_CPU1_SA_DQ<27>")
	)
	(segment
		(start 180.53177 -286.141922)
		(end 179.583334 -286.141922)
		(width 0.18288)
		(layer "In6.Cu")
		(net "M_G_CPU1_SA_DQ<27>")
	)
	(segment
		(start 170.481498 -280.611834)
		(end 170.771566 -280.321766)
		(width 0.18288)
		(layer "In6.Cu")
		(net "M_G_CPU1_SA_DQ<27>")
	)
	(segment
		(start 157.576012 -276.848824)
		(end 150.346918 -269.61973)
		(width 0.18288)
		(layer "In6.Cu")
		(net "M_G_CPU1_SA_DQ<27>")
	)
	(segment
		(start 181.441344 -285.232348)
		(end 180.53177 -286.141922)
		(width 0.18288)
		(layer "In6.Cu")
		(net "M_G_CPU1_SA_DQ<27>")
	)
	(segment
		(start 161.403284 -277.6728)
		(end 160.579308 -276.848824)
		(width 0.18288)
		(layer "In6.Cu")
		(net "M_G_CPU1_SA_DQ<27>")
	)
	(segment
		(start 150.346918 -269.61973)
		(end 144.732502 -269.61973)
		(width 0.18288)
		(layer "In6.Cu")
		(net "M_G_CPU1_SA_DQ<27>")
	)
	(segment
		(start 184.178956 -285.406592)
		(end 184.004712 -285.232348)
		(width 0.18288)
		(layer "In6.Cu")
		(net "M_G_CPU1_SA_DQ<27>")
	)
	(segment
		(start 170.281092 -279.831292)
		(end 169.991024 -280.12136)
		(width 0.18288)
		(layer "In6.Cu")
		(net "M_G_CPU1_SA_DQ<27>")
	)
	(segment
		(start 160.579308 -276.848824)
		(end 157.576012 -276.848824)
		(width 0.18288)
		(layer "In6.Cu")
		(net "M_G_CPU1_SA_DQ<27>")
	)
	(segment
		(start 129.390648 -268.877288)
		(end 128.666748 -268.569694)
		(width 0.088646)
		(layer "In6.Cu")
		(net "M_G_CPU1_SA_DQ<27>")
	)
	(segment
		(start 137.322052 -268.887956)
		(end 137.311638 -268.894052)
		(width 0.088646)
		(layer "In6.Cu")
		(net "M_G_CPU1_SA_DQ<27>")
	)
	(segment
		(start 186.979814 -285.292292)
		(end 186.738514 -285.533592)
		(width 0.18288)
		(layer "In6.Cu")
		(net "M_G_CPU1_SA_DQ<27>")
	)
	(segment
		(start 131.688078 -268.885416)
		(end 131.673346 -268.894052)
		(width 0.088646)
		(layer "In6.Cu")
		(net "M_G_CPU1_SA_DQ<27>")
	)
	(segment
		(start 144.732502 -269.61973)
		(end 142.1003 -269.096236)
		(width 0.18288)
		(layer "In6.Cu")
		(net "M_G_CPU1_SA_DQ<27>")
	)
	(segment
		(start 184.004712 -285.232348)
		(end 181.441344 -285.232348)
		(width 0.18288)
		(layer "In6.Cu")
		(net "M_G_CPU1_SA_DQ<27>")
	)
	(segment
		(start 186.738514 -285.533592)
		(end 186.223148 -285.533592)
		(width 0.18288)
		(layer "In6.Cu")
		(net "M_G_CPU1_SA_DQ<27>")
	)
	(segment
		(start 178.524154 -286.141922)
		(end 176.083468 -286.141922)
		(width 0.18288)
		(layer "In6.Cu")
		(net "M_G_CPU1_SA_DQ<27>")
	)
	(segment
		(start 176.083468 -286.141922)
		(end 173.5709 -283.629354)
		(width 0.18288)
		(layer "In6.Cu")
		(net "M_G_CPU1_SA_DQ<27>")
	)
	(segment
		(start 140.186156 -269.096236)
		(end 140.017754 -268.979396)
		(width 0.088646)
		(layer "In6.Cu")
		(net "M_G_CPU1_SA_DQ<27>")
	)
	(segment
		(start 178.707034 -285.506668)
		(end 178.707034 -285.959042)
		(width 0.18288)
		(layer "In6.Cu")
		(net "M_G_CPU1_SA_DQ<27>")
	)
	(segment
		(start 164.255196 -277.6728)
		(end 161.403284 -277.6728)
		(width 0.18288)
		(layer "In6.Cu")
		(net "M_G_CPU1_SA_DQ<27>")
	)
	(segment
		(start 190.05677 -286.399732)
		(end 188.94933 -285.292292)
		(width 0.18288)
		(layer "In6.Cu")
		(net "M_G_CPU1_SA_DQ<27>")
	)
	(segment
		(start 191.983614 -285.716726)
		(end 191.300608 -286.399732)
		(width 0.18288)
		(layer "In6.Cu")
		(net "M_G_CPU1_SA_DQ<27>")
	)
	(segment
		(start 134.507478 -268.885416)
		(end 134.492746 -268.894052)
		(width 0.088646)
		(layer "In6.Cu")
		(net "M_G_CPU1_SA_DQ<27>")
	)
	(segment
		(start 191.300608 -286.399732)
		(end 190.05677 -286.399732)
		(width 0.18288)
		(layer "In6.Cu")
		(net "M_G_CPU1_SA_DQ<27>")
	)
	(segment
		(start 170.898566 -281.287474)
		(end 170.481498 -280.870406)
		(width 0.18288)
		(layer "In6.Cu")
		(net "M_G_CPU1_SA_DQ<27>")
	)
	(segment
		(start 178.707034 -285.959042)
		(end 178.524154 -286.141922)
		(width 0.18288)
		(layer "In6.Cu")
		(net "M_G_CPU1_SA_DQ<27>")
	)
	(segment
		(start 129.41935 -268.894052)
		(end 129.390648 -268.877288)
		(width 0.088646)
		(layer "In6.Cu")
		(net "M_G_CPU1_SA_DQ<27>")
	)
	(segment
		(start 185.812176 -285.12262)
		(end 185.339482 -285.12262)
		(width 0.18288)
		(layer "In6.Cu")
		(net "M_G_CPU1_SA_DQ<27>")
	)
	(segment
		(start 169.732452 -280.12136)
		(end 168.119298 -278.508206)
		(width 0.18288)
		(layer "In6.Cu")
		(net "M_G_CPU1_SA_DQ<27>")
	)
	(segment
		(start 172.305726 -281.89301)
		(end 171.70019 -281.287474)
		(width 0.18288)
		(layer "In6.Cu")
		(net "M_G_CPU1_SA_DQ<27>")
	)
	(segment
		(start 170.481498 -280.870406)
		(end 170.481498 -280.611834)
		(width 0.18288)
		(layer "In6.Cu")
		(net "M_G_CPU1_SA_DQ<27>")
	)
	(segment
		(start 138.261598 -268.887956)
		(end 138.251184 -268.894052)
		(width 0.088646)
		(layer "In6.Cu")
		(net "M_G_CPU1_SA_DQ<27>")
	)
	(segment
		(start 173.5709 -283.629354)
		(end 173.5709 -282.280106)
		(width 0.18288)
		(layer "In6.Cu")
		(net "M_G_CPU1_SA_DQ<27>")
	)
	(segment
		(start 133.567678 -268.885416)
		(end 133.552946 -268.894052)
		(width 0.088646)
		(layer "In6.Cu")
		(net "M_G_CPU1_SA_DQ<27>")
	)
	(segment
		(start 178.889914 -285.323788)
		(end 178.707034 -285.506668)
		(width 0.18288)
		(layer "In6.Cu")
		(net "M_G_CPU1_SA_DQ<27>")
	)
	(segment
		(start 173.5709 -282.280106)
		(end 173.183804 -281.89301)
		(width 0.18288)
		(layer "In6.Cu")
		(net "M_G_CPU1_SA_DQ<27>")
	)
	(segment
		(start 179.583334 -286.141922)
		(end 179.400454 -285.959042)
		(width 0.18288)
		(layer "In6.Cu")
		(net "M_G_CPU1_SA_DQ<27>")
	)
	(segment
		(start 179.217574 -285.323788)
		(end 178.889914 -285.323788)
		(width 0.18288)
		(layer "In6.Cu")
		(net "M_G_CPU1_SA_DQ<27>")
	)
	(segment
		(start 140.595604 -269.096236)
		(end 140.186156 -269.096236)
		(width 0.088646)
		(layer "In6.Cu")
		(net "M_G_CPU1_SA_DQ<27>")
	)
	(segment
		(start 179.400454 -285.506668)
		(end 179.217574 -285.323788)
		(width 0.18288)
		(layer "In6.Cu")
		(net "M_G_CPU1_SA_DQ<27>")
	)
	(segment
		(start 170.539664 -279.831292)
		(end 170.281092 -279.831292)
		(width 0.18288)
		(layer "In6.Cu")
		(net "M_G_CPU1_SA_DQ<27>")
	)
	(segment
		(start 135.44296 -268.887956)
		(end 135.432546 -268.894052)
		(width 0.088646)
		(layer "In6.Cu")
		(net "M_G_CPU1_SA_DQ<27>")
	)
	(segment
		(start 169.991024 -280.12136)
		(end 169.732452 -280.12136)
		(width 0.18288)
		(layer "In6.Cu")
		(net "M_G_CPU1_SA_DQ<27>")
	)
	(segment
		(start 185.339482 -285.12262)
		(end 185.05551 -285.406592)
		(width 0.18288)
		(layer "In6.Cu")
		(net "M_G_CPU1_SA_DQ<27>")
	)
	(segment
		(start 186.223148 -285.533592)
		(end 185.812176 -285.12262)
		(width 0.18288)
		(layer "In6.Cu")
		(net "M_G_CPU1_SA_DQ<27>")
	)
	(segment
		(start 168.119298 -278.508206)
		(end 165.090602 -278.508206)
		(width 0.18288)
		(layer "In6.Cu")
		(net "M_G_CPU1_SA_DQ<27>")
	)
	(segment
		(start 179.400454 -285.959042)
		(end 179.400454 -285.506668)
		(width 0.18288)
		(layer "In6.Cu")
		(net "M_G_CPU1_SA_DQ<27>")
	)
	(segment
		(start 130.748278 -268.885416)
		(end 130.733546 -268.894052)
		(width 0.088646)
		(layer "In6.Cu")
		(net "M_G_CPU1_SA_DQ<27>")
	)
	(segment
		(start 173.183804 -281.89301)
		(end 172.305726 -281.89301)
		(width 0.18288)
		(layer "In6.Cu")
		(net "M_G_CPU1_SA_DQ<27>")
	)
	(segment
		(start 139.201144 -268.887956)
		(end 139.19073 -268.894052)
		(width 0.088646)
		(layer "In6.Cu")
		(net "M_G_CPU1_SA_DQ<27>")
	)
	(segment
		(start 171.70019 -281.287474)
		(end 170.898566 -281.287474)
		(width 0.18288)
		(layer "In6.Cu")
		(net "M_G_CPU1_SA_DQ<27>")
	)
	(segment
		(start 165.090602 -278.508206)
		(end 164.255196 -277.6728)
		(width 0.18288)
		(layer "In6.Cu")
		(net "M_G_CPU1_SA_DQ<27>")
	)
	(segment
		(start 142.1003 -269.096236)
		(end 140.595604 -269.096236)
		(width 0.18288)
		(layer "In6.Cu")
		(net "M_G_CPU1_SA_DQ<27>")
	)
	(segment
		(start 129.808478 -268.885416)
		(end 129.793746 -268.894052)
		(width 0.088646)
		(layer "In6.Cu")
		(net "M_G_CPU1_SA_DQ<27>")
	)
	(segment
		(start 170.771566 -280.321766)
		(end 170.771566 -280.063194)
		(width 0.18288)
		(layer "In6.Cu")
		(net "M_G_CPU1_SA_DQ<27>")
	)
	(arc
		(start 138.816334 -268.894052)
		(mid 138.539775 -268.818309)
		(end 138.261598 -268.887956)
		(width 0.088646)
		(layer "In6.Cu")
		(net "M_G_CPU1_SA_DQ<27>")
	)
	(arc
		(start 134.11835 -268.894052)
		(mid 133.844151 -268.818217)
		(end 133.567678 -268.885416)
		(width 0.088646)
		(layer "In6.Cu")
		(net "M_G_CPU1_SA_DQ<27>")
	)
	(arc
		(start 139.929616 -268.967458)
		(mid 139.840403 -268.936304)
		(end 139.75588 -268.894052)
		(width 0.088646)
		(layer "In6.Cu")
		(net "M_G_CPU1_SA_DQ<27>")
	)
	(arc
		(start 136.372092 -268.894052)
		(mid 136.184894 -268.944195)
		(end 135.997696 -268.894052)
		(width 0.088646)
		(layer "In6.Cu")
		(net "M_G_CPU1_SA_DQ<27>")
	)
	(arc
		(start 132.23875 -268.894052)
		(mid 131.964551 -268.818217)
		(end 131.688078 -268.885416)
		(width 0.088646)
		(layer "In6.Cu")
		(net "M_G_CPU1_SA_DQ<27>")
	)
	(arc
		(start 139.75588 -268.894052)
		(mid 139.479321 -268.818309)
		(end 139.201144 -268.887956)
		(width 0.088646)
		(layer "In6.Cu")
		(net "M_G_CPU1_SA_DQ<27>")
	)
	(arc
		(start 130.733546 -268.894052)
		(mid 130.546348 -268.944195)
		(end 130.35915 -268.894052)
		(width 0.088646)
		(layer "In6.Cu")
		(net "M_G_CPU1_SA_DQ<27>")
	)
	(arc
		(start 137.311638 -268.894052)
		(mid 137.12444 -268.944195)
		(end 136.937242 -268.894052)
		(width 0.088646)
		(layer "In6.Cu")
		(net "M_G_CPU1_SA_DQ<27>")
	)
	(arc
		(start 139.19073 -268.894052)
		(mid 139.003532 -268.944195)
		(end 138.816334 -268.894052)
		(width 0.088646)
		(layer "In6.Cu")
		(net "M_G_CPU1_SA_DQ<27>")
	)
	(arc
		(start 135.432546 -268.894052)
		(mid 135.245348 -268.944195)
		(end 135.05815 -268.894052)
		(width 0.088646)
		(layer "In6.Cu")
		(net "M_G_CPU1_SA_DQ<27>")
	)
	(arc
		(start 133.552946 -268.894052)
		(mid 133.365748 -268.944195)
		(end 133.17855 -268.894052)
		(width 0.088646)
		(layer "In6.Cu")
		(net "M_G_CPU1_SA_DQ<27>")
	)
	(arc
		(start 136.926828 -268.887956)
		(mid 136.64865 -268.818233)
		(end 136.372092 -268.894052)
		(width 0.088646)
		(layer "In6.Cu")
		(net "M_G_CPU1_SA_DQ<27>")
	)
	(arc
		(start 132.613146 -268.894052)
		(mid 132.425948 -268.944195)
		(end 132.23875 -268.894052)
		(width 0.088646)
		(layer "In6.Cu")
		(net "M_G_CPU1_SA_DQ<27>")
	)
	(arc
		(start 134.492746 -268.894052)
		(mid 134.305548 -268.944195)
		(end 134.11835 -268.894052)
		(width 0.088646)
		(layer "In6.Cu")
		(net "M_G_CPU1_SA_DQ<27>")
	)
	(arc
		(start 138.251184 -268.894052)
		(mid 138.063986 -268.944195)
		(end 137.876788 -268.894052)
		(width 0.088646)
		(layer "In6.Cu")
		(net "M_G_CPU1_SA_DQ<27>")
	)
	(arc
		(start 137.876788 -268.894052)
		(mid 137.600229 -268.818309)
		(end 137.322052 -268.887956)
		(width 0.088646)
		(layer "In6.Cu")
		(net "M_G_CPU1_SA_DQ<27>")
	)
	(arc
		(start 135.05815 -268.894052)
		(mid 134.783951 -268.818217)
		(end 134.507478 -268.885416)
		(width 0.088646)
		(layer "In6.Cu")
		(net "M_G_CPU1_SA_DQ<27>")
	)
	(arc
		(start 129.793746 -268.894052)
		(mid 129.606548 -268.944195)
		(end 129.41935 -268.894052)
		(width 0.088646)
		(layer "In6.Cu")
		(net "M_G_CPU1_SA_DQ<27>")
	)
	(arc
		(start 133.17855 -268.894052)
		(mid 132.895848 -268.818276)
		(end 132.613146 -268.894052)
		(width 0.088646)
		(layer "In6.Cu")
		(net "M_G_CPU1_SA_DQ<27>")
	)
	(arc
		(start 140.017754 -268.979396)
		(mid 139.973279 -268.976429)
		(end 139.929616 -268.967458)
		(width 0.088646)
		(layer "In6.Cu")
		(net "M_G_CPU1_SA_DQ<27>")
	)
	(arc
		(start 130.35915 -268.894052)
		(mid 130.084951 -268.818217)
		(end 129.808478 -268.885416)
		(width 0.088646)
		(layer "In6.Cu")
		(net "M_G_CPU1_SA_DQ<27>")
	)
	(arc
		(start 131.673346 -268.894052)
		(mid 131.486148 -268.944195)
		(end 131.29895 -268.894052)
		(width 0.088646)
		(layer "In6.Cu")
		(net "M_G_CPU1_SA_DQ<27>")
	)
	(arc
		(start 131.29895 -268.894052)
		(mid 131.024751 -268.818217)
		(end 130.748278 -268.885416)
		(width 0.088646)
		(layer "In6.Cu")
		(net "M_G_CPU1_SA_DQ<27>")
	)
	(arc
		(start 135.997696 -268.894052)
		(mid 135.721137 -268.818309)
		(end 135.44296 -268.887956)
		(width 0.088646)
		(layer "In6.Cu")
		(net "M_G_CPU1_SA_DQ<27>")
	)
	(segment
		(start 195.218812 -287.848802)
		(end 195.510658 -287.848802)
		(width 0.20066)
		(layer "F.Cu")
		(net "M_G_CPU1_SA_DQ<26>")
	)
	(segment
		(start 197.530466 -287.84169)
		(end 197.542658 -287.853882)
		(width 0.1016)
		(layer "F.Cu")
		(net "M_G_CPU1_SA_DQ<26>")
	)
	(segment
		(start 198.427848 -287.64992)
		(end 198.427848 -287.398968)
		(width 0.20066)
		(layer "F.Cu")
		(net "M_G_CPU1_SA_DQ<26>")
	)
	(segment
		(start 199.046084 -287.16478)
		(end 199.298052 -287.416748)
		(width 0.20066)
		(layer "F.Cu")
		(net "M_G_CPU1_SA_DQ<26>")
	)
	(segment
		(start 197.542658 -287.853882)
		(end 198.223886 -287.853882)
		(width 0.20066)
		(layer "F.Cu")
		(net "M_G_CPU1_SA_DQ<26>")
	)
	(segment
		(start 195.522596 -287.84169)
		(end 197.530466 -287.84169)
		(width 0.1016)
		(layer "F.Cu")
		(net "M_G_CPU1_SA_DQ<26>")
	)
	(segment
		(start 193.088514 -287.416748)
		(end 194.786758 -287.416748)
		(width 0.20066)
		(layer "F.Cu")
		(net "M_G_CPU1_SA_DQ<26>")
	)
	(segment
		(start 191.983614 -287.416748)
		(end 193.088514 -287.416748)
		(width 0.20066)
		(layer "F.Cu")
		(net "M_G_CPU1_SA_DQ<26>")
	)
	(segment
		(start 128.196848 -269.383256)
		(end 128.196594 -269.38351)
		(width 0.20066)
		(layer "F.Cu")
		(net "M_G_CPU1_SA_DQ<26>")
	)
	(segment
		(start 199.298052 -287.416748)
		(end 200.632314 -287.416748)
		(width 0.20066)
		(layer "F.Cu")
		(net "M_G_CPU1_SA_DQ<26>")
	)
	(segment
		(start 198.427848 -287.398968)
		(end 198.662036 -287.16478)
		(width 0.20066)
		(layer "F.Cu")
		(net "M_G_CPU1_SA_DQ<26>")
	)
	(segment
		(start 195.510658 -287.848802)
		(end 195.515484 -287.848802)
		(width 0.101854)
		(layer "F.Cu")
		(net "M_G_CPU1_SA_DQ<26>")
	)
	(segment
		(start 128.196848 -268.84757)
		(end 128.196848 -269.383256)
		(width 0.20066)
		(layer "F.Cu")
		(net "M_G_CPU1_SA_DQ<26>")
	)
	(segment
		(start 198.223886 -287.853882)
		(end 198.427848 -287.64992)
		(width 0.20066)
		(layer "F.Cu")
		(net "M_G_CPU1_SA_DQ<26>")
	)
	(segment
		(start 198.662036 -287.16478)
		(end 199.046084 -287.16478)
		(width 0.20066)
		(layer "F.Cu")
		(net "M_G_CPU1_SA_DQ<26>")
	)
	(segment
		(start 195.515484 -287.848802)
		(end 195.522596 -287.84169)
		(width 0.1016)
		(layer "F.Cu")
		(net "M_G_CPU1_SA_DQ<26>")
	)
	(segment
		(start 194.786758 -287.416748)
		(end 195.218812 -287.848802)
		(width 0.20066)
		(layer "F.Cu")
		(net "M_G_CPU1_SA_DQ<26>")
	)
	(segment
		(start 181.103016 -287.739328)
		(end 181.103016 -287.880806)
		(width 0.18288)
		(layer "In6.Cu")
		(net "M_G_CPU1_SA_DQ<26>")
	)
	(segment
		(start 161.581338 -279.50541)
		(end 160.614106 -278.538178)
		(width 0.18288)
		(layer "In6.Cu")
		(net "M_G_CPU1_SA_DQ<26>")
	)
	(segment
		(start 158.569914 -278.355298)
		(end 158.387034 -278.538178)
		(width 0.18288)
		(layer "In6.Cu")
		(net "M_G_CPU1_SA_DQ<26>")
	)
	(segment
		(start 160.614106 -278.538178)
		(end 159.446214 -278.538178)
		(width 0.18288)
		(layer "In6.Cu")
		(net "M_G_CPU1_SA_DQ<26>")
	)
	(segment
		(start 171.029376 -285.534862)
		(end 171.029376 -283.834586)
		(width 0.18288)
		(layer "In6.Cu")
		(net "M_G_CPU1_SA_DQ<26>")
	)
	(segment
		(start 174.657004 -287.843722)
		(end 173.912022 -287.09874)
		(width 0.18288)
		(layer "In6.Cu")
		(net "M_G_CPU1_SA_DQ<26>")
	)
	(segment
		(start 173.912022 -287.09874)
		(end 173.912022 -286.806132)
		(width 0.18288)
		(layer "In6.Cu")
		(net "M_G_CPU1_SA_DQ<26>")
	)
	(segment
		(start 157.553406 -278.538178)
		(end 149.675088 -270.65986)
		(width 0.18288)
		(layer "In6.Cu")
		(net "M_G_CPU1_SA_DQ<26>")
	)
	(segment
		(start 159.080454 -277.847552)
		(end 158.752794 -277.847552)
		(width 0.18288)
		(layer "In6.Cu")
		(net "M_G_CPU1_SA_DQ<26>")
	)
	(segment
		(start 159.263334 -278.355298)
		(end 159.263334 -278.030432)
		(width 0.18288)
		(layer "In6.Cu")
		(net "M_G_CPU1_SA_DQ<26>")
	)
	(segment
		(start 140.595604 -270.123412)
		(end 140.330682 -270.123412)
		(width 0.088646)
		(layer "In6.Cu")
		(net "M_G_CPU1_SA_DQ<26>")
	)
	(segment
		(start 131.768596 -269.707868)
		(end 131.753864 -269.699232)
		(width 0.088646)
		(layer "In6.Cu")
		(net "M_G_CPU1_SA_DQ<26>")
	)
	(segment
		(start 177.203608 -287.843722)
		(end 174.657004 -287.843722)
		(width 0.18288)
		(layer "In6.Cu")
		(net "M_G_CPU1_SA_DQ<26>")
	)
	(segment
		(start 137.407396 -269.707868)
		(end 137.392664 -269.699232)
		(width 0.088646)
		(layer "In6.Cu")
		(net "M_G_CPU1_SA_DQ<26>")
	)
	(segment
		(start 129.888996 -269.707868)
		(end 129.874264 -269.699232)
		(width 0.088646)
		(layer "In6.Cu")
		(net "M_G_CPU1_SA_DQ<26>")
	)
	(segment
		(start 158.387034 -278.538178)
		(end 157.553406 -278.538178)
		(width 0.18288)
		(layer "In6.Cu")
		(net "M_G_CPU1_SA_DQ<26>")
	)
	(segment
		(start 167.599614 -280.481278)
		(end 165.319202 -280.481278)
		(width 0.18288)
		(layer "In6.Cu")
		(net "M_G_CPU1_SA_DQ<26>")
	)
	(segment
		(start 132.70865 -269.707868)
		(end 132.698236 -269.701772)
		(width 0.088646)
		(layer "In6.Cu")
		(net "M_G_CPU1_SA_DQ<26>")
	)
	(segment
		(start 139.965938 -269.758668)
		(end 139.474448 -269.758668)
		(width 0.088646)
		(layer "In6.Cu")
		(net "M_G_CPU1_SA_DQ<26>")
	)
	(segment
		(start 170.06189 -282.8671)
		(end 169.081958 -282.8671)
		(width 0.18288)
		(layer "In6.Cu")
		(net "M_G_CPU1_SA_DQ<26>")
	)
	(segment
		(start 177.370486 -287.676844)
		(end 177.203608 -287.843722)
		(width 0.18288)
		(layer "In6.Cu")
		(net "M_G_CPU1_SA_DQ<26>")
	)
	(segment
		(start 163.367466 -279.50541)
		(end 163.097464 -279.235408)
		(width 0.18288)
		(layer "In6.Cu")
		(net "M_G_CPU1_SA_DQ<26>")
	)
	(segment
		(start 159.263334 -278.030432)
		(end 159.080454 -277.847552)
		(width 0.18288)
		(layer "In6.Cu")
		(net "M_G_CPU1_SA_DQ<26>")
	)
	(segment
		(start 138.347196 -269.707868)
		(end 138.332464 -269.699232)
		(width 0.088646)
		(layer "In6.Cu")
		(net "M_G_CPU1_SA_DQ<26>")
	)
	(segment
		(start 159.446214 -278.538178)
		(end 159.263334 -278.355298)
		(width 0.18288)
		(layer "In6.Cu")
		(net "M_G_CPU1_SA_DQ<26>")
	)
	(segment
		(start 190.51651 -286.992314)
		(end 184.136284 -286.992314)
		(width 0.18288)
		(layer "In6.Cu")
		(net "M_G_CPU1_SA_DQ<26>")
	)
	(segment
		(start 173.912022 -286.806132)
		(end 173.246288 -286.140398)
		(width 0.18288)
		(layer "In6.Cu")
		(net "M_G_CPU1_SA_DQ<26>")
	)
	(segment
		(start 181.796436 -287.880806)
		(end 181.796436 -287.739328)
		(width 0.18288)
		(layer "In6.Cu")
		(net "M_G_CPU1_SA_DQ<26>")
	)
	(segment
		(start 183.087772 -288.040826)
		(end 181.956456 -288.040826)
		(width 0.18288)
		(layer "In6.Cu")
		(net "M_G_CPU1_SA_DQ<26>")
	)
	(segment
		(start 168.30548 -282.090622)
		(end 168.30548 -281.187144)
		(width 0.18288)
		(layer "In6.Cu")
		(net "M_G_CPU1_SA_DQ<26>")
	)
	(segment
		(start 135.527796 -269.707868)
		(end 135.513064 -269.699232)
		(width 0.088646)
		(layer "In6.Cu")
		(net "M_G_CPU1_SA_DQ<26>")
	)
	(segment
		(start 184.136284 -286.992314)
		(end 183.087772 -288.040826)
		(width 0.18288)
		(layer "In6.Cu")
		(net "M_G_CPU1_SA_DQ<26>")
	)
	(segment
		(start 181.796436 -287.739328)
		(end 181.636416 -287.579308)
		(width 0.18288)
		(layer "In6.Cu")
		(net "M_G_CPU1_SA_DQ<26>")
	)
	(segment
		(start 149.675088 -270.65986)
		(end 144.810226 -270.65986)
		(width 0.18288)
		(layer "In6.Cu")
		(net "M_G_CPU1_SA_DQ<26>")
	)
	(segment
		(start 179.82819 -288.040826)
		(end 179.464208 -287.676844)
		(width 0.18288)
		(layer "In6.Cu")
		(net "M_G_CPU1_SA_DQ<26>")
	)
	(segment
		(start 168.30548 -281.187144)
		(end 167.599614 -280.481278)
		(width 0.18288)
		(layer "In6.Cu")
		(net "M_G_CPU1_SA_DQ<26>")
	)
	(segment
		(start 165.319202 -280.481278)
		(end 164.343334 -279.50541)
		(width 0.18288)
		(layer "In6.Cu")
		(net "M_G_CPU1_SA_DQ<26>")
	)
	(segment
		(start 181.103016 -287.880806)
		(end 180.942996 -288.040826)
		(width 0.18288)
		(layer "In6.Cu")
		(net "M_G_CPU1_SA_DQ<26>")
	)
	(segment
		(start 171.029376 -283.834586)
		(end 170.06189 -282.8671)
		(width 0.18288)
		(layer "In6.Cu")
		(net "M_G_CPU1_SA_DQ<26>")
	)
	(segment
		(start 128.919986 -269.69085)
		(end 128.196594 -269.38351)
		(width 0.088646)
		(layer "In6.Cu")
		(net "M_G_CPU1_SA_DQ<26>")
	)
	(segment
		(start 158.752794 -277.847552)
		(end 158.569914 -278.030432)
		(width 0.18288)
		(layer "In6.Cu")
		(net "M_G_CPU1_SA_DQ<26>")
	)
	(segment
		(start 173.246288 -286.140398)
		(end 171.634912 -286.140398)
		(width 0.18288)
		(layer "In6.Cu")
		(net "M_G_CPU1_SA_DQ<26>")
	)
	(segment
		(start 142.113 -270.123412)
		(end 140.595604 -270.123412)
		(width 0.18288)
		(layer "In6.Cu")
		(net "M_G_CPU1_SA_DQ<26>")
	)
	(segment
		(start 140.330682 -270.123412)
		(end 139.965938 -269.758668)
		(width 0.088646)
		(layer "In6.Cu")
		(net "M_G_CPU1_SA_DQ<26>")
	)
	(segment
		(start 181.956456 -288.040826)
		(end 181.796436 -287.880806)
		(width 0.18288)
		(layer "In6.Cu")
		(net "M_G_CPU1_SA_DQ<26>")
	)
	(segment
		(start 181.263036 -287.579308)
		(end 181.103016 -287.739328)
		(width 0.18288)
		(layer "In6.Cu")
		(net "M_G_CPU1_SA_DQ<26>")
	)
	(segment
		(start 128.949196 -269.707868)
		(end 128.919986 -269.69085)
		(width 0.088646)
		(layer "In6.Cu")
		(net "M_G_CPU1_SA_DQ<26>")
	)
	(segment
		(start 180.942996 -288.040826)
		(end 179.82819 -288.040826)
		(width 0.18288)
		(layer "In6.Cu")
		(net "M_G_CPU1_SA_DQ<26>")
	)
	(segment
		(start 163.097464 -279.235408)
		(end 162.699446 -279.235408)
		(width 0.18288)
		(layer "In6.Cu")
		(net "M_G_CPU1_SA_DQ<26>")
	)
	(segment
		(start 130.828796 -269.707868)
		(end 130.814064 -269.699232)
		(width 0.088646)
		(layer "In6.Cu")
		(net "M_G_CPU1_SA_DQ<26>")
	)
	(segment
		(start 133.09346 -269.701772)
		(end 133.083046 -269.707868)
		(width 0.088646)
		(layer "In6.Cu")
		(net "M_G_CPU1_SA_DQ<26>")
	)
	(segment
		(start 162.429444 -279.50541)
		(end 161.581338 -279.50541)
		(width 0.18288)
		(layer "In6.Cu")
		(net "M_G_CPU1_SA_DQ<26>")
	)
	(segment
		(start 136.467596 -269.707868)
		(end 136.452864 -269.699232)
		(width 0.088646)
		(layer "In6.Cu")
		(net "M_G_CPU1_SA_DQ<26>")
	)
	(segment
		(start 162.699446 -279.235408)
		(end 162.429444 -279.50541)
		(width 0.18288)
		(layer "In6.Cu")
		(net "M_G_CPU1_SA_DQ<26>")
	)
	(segment
		(start 191.983614 -287.416748)
		(end 191.637666 -287.316672)
		(width 0.18288)
		(layer "In6.Cu")
		(net "M_G_CPU1_SA_DQ<26>")
	)
	(segment
		(start 158.569914 -278.030432)
		(end 158.569914 -278.355298)
		(width 0.18288)
		(layer "In6.Cu")
		(net "M_G_CPU1_SA_DQ<26>")
	)
	(segment
		(start 144.810226 -270.65986)
		(end 142.113 -270.123412)
		(width 0.18288)
		(layer "In6.Cu")
		(net "M_G_CPU1_SA_DQ<26>")
	)
	(segment
		(start 134.587996 -269.707868)
		(end 134.573264 -269.699232)
		(width 0.088646)
		(layer "In6.Cu")
		(net "M_G_CPU1_SA_DQ<26>")
	)
	(segment
		(start 179.464208 -287.676844)
		(end 177.370486 -287.676844)
		(width 0.18288)
		(layer "In6.Cu")
		(net "M_G_CPU1_SA_DQ<26>")
	)
	(segment
		(start 191.637666 -287.316672)
		(end 190.51651 -286.992314)
		(width 0.18288)
		(layer "In6.Cu")
		(net "M_G_CPU1_SA_DQ<26>")
	)
	(segment
		(start 164.343334 -279.50541)
		(end 163.367466 -279.50541)
		(width 0.18288)
		(layer "In6.Cu")
		(net "M_G_CPU1_SA_DQ<26>")
	)
	(segment
		(start 139.286996 -269.707868)
		(end 139.272264 -269.699232)
		(width 0.088646)
		(layer "In6.Cu")
		(net "M_G_CPU1_SA_DQ<26>")
	)
	(segment
		(start 169.081958 -282.8671)
		(end 168.30548 -282.090622)
		(width 0.18288)
		(layer "In6.Cu")
		(net "M_G_CPU1_SA_DQ<26>")
	)
	(segment
		(start 171.634912 -286.140398)
		(end 171.029376 -285.534862)
		(width 0.18288)
		(layer "In6.Cu")
		(net "M_G_CPU1_SA_DQ<26>")
	)
	(segment
		(start 181.636416 -287.579308)
		(end 181.263036 -287.579308)
		(width 0.18288)
		(layer "In6.Cu")
		(net "M_G_CPU1_SA_DQ<26>")
	)
	(arc
		(start 131.753864 -269.699232)
		(mid 131.477423 -269.632066)
		(end 131.203192 -269.707868)
		(width 0.088646)
		(layer "In6.Cu")
		(net "M_G_CPU1_SA_DQ<26>")
	)
	(arc
		(start 133.648196 -269.707868)
		(mid 133.371637 -269.632159)
		(end 133.09346 -269.701772)
		(width 0.088646)
		(layer "In6.Cu")
		(net "M_G_CPU1_SA_DQ<26>")
	)
	(arc
		(start 135.513064 -269.699232)
		(mid 135.236623 -269.632066)
		(end 134.962392 -269.707868)
		(width 0.088646)
		(layer "In6.Cu")
		(net "M_G_CPU1_SA_DQ<26>")
	)
	(arc
		(start 132.142992 -269.707868)
		(mid 131.955794 -269.758011)
		(end 131.768596 -269.707868)
		(width 0.088646)
		(layer "In6.Cu")
		(net "M_G_CPU1_SA_DQ<26>")
	)
	(arc
		(start 134.022592 -269.707868)
		(mid 133.835394 -269.758011)
		(end 133.648196 -269.707868)
		(width 0.088646)
		(layer "In6.Cu")
		(net "M_G_CPU1_SA_DQ<26>")
	)
	(arc
		(start 132.698236 -269.701772)
		(mid 132.419804 -269.631958)
		(end 132.142992 -269.707868)
		(width 0.088646)
		(layer "In6.Cu")
		(net "M_G_CPU1_SA_DQ<26>")
	)
	(arc
		(start 138.332464 -269.699232)
		(mid 138.056023 -269.632066)
		(end 137.781792 -269.707868)
		(width 0.088646)
		(layer "In6.Cu")
		(net "M_G_CPU1_SA_DQ<26>")
	)
	(arc
		(start 130.263392 -269.707868)
		(mid 130.076194 -269.758011)
		(end 129.888996 -269.707868)
		(width 0.088646)
		(layer "In6.Cu")
		(net "M_G_CPU1_SA_DQ<26>")
	)
	(arc
		(start 136.452864 -269.699232)
		(mid 136.176423 -269.632066)
		(end 135.902192 -269.707868)
		(width 0.088646)
		(layer "In6.Cu")
		(net "M_G_CPU1_SA_DQ<26>")
	)
	(arc
		(start 138.721592 -269.707868)
		(mid 138.534394 -269.758011)
		(end 138.347196 -269.707868)
		(width 0.088646)
		(layer "In6.Cu")
		(net "M_G_CPU1_SA_DQ<26>")
	)
	(arc
		(start 131.203192 -269.707868)
		(mid 131.015994 -269.758011)
		(end 130.828796 -269.707868)
		(width 0.088646)
		(layer "In6.Cu")
		(net "M_G_CPU1_SA_DQ<26>")
	)
	(arc
		(start 129.323592 -269.707868)
		(mid 129.136394 -269.758011)
		(end 128.949196 -269.707868)
		(width 0.088646)
		(layer "In6.Cu")
		(net "M_G_CPU1_SA_DQ<26>")
	)
	(arc
		(start 137.781792 -269.707868)
		(mid 137.594594 -269.758011)
		(end 137.407396 -269.707868)
		(width 0.088646)
		(layer "In6.Cu")
		(net "M_G_CPU1_SA_DQ<26>")
	)
	(arc
		(start 137.392664 -269.699232)
		(mid 137.116223 -269.632066)
		(end 136.841992 -269.707868)
		(width 0.088646)
		(layer "In6.Cu")
		(net "M_G_CPU1_SA_DQ<26>")
	)
	(arc
		(start 134.962392 -269.707868)
		(mid 134.775194 -269.758011)
		(end 134.587996 -269.707868)
		(width 0.088646)
		(layer "In6.Cu")
		(net "M_G_CPU1_SA_DQ<26>")
	)
	(arc
		(start 129.874264 -269.699232)
		(mid 129.597823 -269.632066)
		(end 129.323592 -269.707868)
		(width 0.088646)
		(layer "In6.Cu")
		(net "M_G_CPU1_SA_DQ<26>")
	)
	(arc
		(start 134.573264 -269.699232)
		(mid 134.296823 -269.632066)
		(end 134.022592 -269.707868)
		(width 0.088646)
		(layer "In6.Cu")
		(net "M_G_CPU1_SA_DQ<26>")
	)
	(arc
		(start 135.902192 -269.707868)
		(mid 135.714994 -269.758011)
		(end 135.527796 -269.707868)
		(width 0.088646)
		(layer "In6.Cu")
		(net "M_G_CPU1_SA_DQ<26>")
	)
	(arc
		(start 133.083046 -269.707868)
		(mid 132.895848 -269.758011)
		(end 132.70865 -269.707868)
		(width 0.088646)
		(layer "In6.Cu")
		(net "M_G_CPU1_SA_DQ<26>")
	)
	(arc
		(start 139.474448 -269.758668)
		(mid 139.377373 -269.745619)
		(end 139.286996 -269.707868)
		(width 0.088646)
		(layer "In6.Cu")
		(net "M_G_CPU1_SA_DQ<26>")
	)
	(arc
		(start 136.841992 -269.707868)
		(mid 136.654794 -269.758011)
		(end 136.467596 -269.707868)
		(width 0.088646)
		(layer "In6.Cu")
		(net "M_G_CPU1_SA_DQ<26>")
	)
	(arc
		(start 130.814064 -269.699232)
		(mid 130.537623 -269.632066)
		(end 130.263392 -269.707868)
		(width 0.088646)
		(layer "In6.Cu")
		(net "M_G_CPU1_SA_DQ<26>")
	)
	(arc
		(start 139.272264 -269.699232)
		(mid 138.995823 -269.632066)
		(end 138.721592 -269.707868)
		(width 0.088646)
		(layer "In6.Cu")
		(net "M_G_CPU1_SA_DQ<26>")
	)
	(segment
		(start 190.75781 -286.815276)
		(end 190.509144 -286.56661)
		(width 0.20066)
		(layer "F.Cu")
		(net "M_G_CPU1_SA_DQ<25>")
	)
	(segment
		(start 188.988446 -286.56661)
		(end 187.883546 -286.56661)
		(width 0.20066)
		(layer "F.Cu")
		(net "M_G_CPU1_SA_DQ<25>")
	)
	(segment
		(start 191.903858 -286.141668)
		(end 191.883792 -286.141668)
		(width 0.101854)
		(layer "F.Cu")
		(net "M_G_CPU1_SA_DQ<25>")
	)
	(segment
		(start 191.421004 -286.259778)
		(end 191.421004 -286.627316)
		(width 0.20066)
		(layer "F.Cu")
		(net "M_G_CPU1_SA_DQ<25>")
	)
	(segment
		(start 196.532246 -286.56661)
		(end 196.531992 -286.566864)
		(width 0.20066)
		(layer "F.Cu")
		(net "M_G_CPU1_SA_DQ<25>")
	)
	(segment
		(start 196.531992 -286.566864)
		(end 194.940428 -286.566864)
		(width 0.20066)
		(layer "F.Cu")
		(net "M_G_CPU1_SA_DQ<25>")
	)
	(segment
		(start 194.098926 -286.135318)
		(end 194.092576 -286.141668)
		(width 0.1016)
		(layer "F.Cu")
		(net "M_G_CPU1_SA_DQ<25>")
	)
	(segment
		(start 194.092576 -286.141668)
		(end 191.903858 -286.141668)
		(width 0.1016)
		(layer "F.Cu")
		(net "M_G_CPU1_SA_DQ<25>")
	)
	(segment
		(start 190.509144 -286.56661)
		(end 188.988446 -286.56661)
		(width 0.20066)
		(layer "F.Cu")
		(net "M_G_CPU1_SA_DQ<25>")
	)
	(segment
		(start 191.883792 -286.141668)
		(end 191.539114 -286.141668)
		(width 0.20066)
		(layer "F.Cu")
		(net "M_G_CPU1_SA_DQ<25>")
	)
	(segment
		(start 194.508882 -286.135318)
		(end 194.098926 -286.135318)
		(width 0.20066)
		(layer "F.Cu")
		(net "M_G_CPU1_SA_DQ<25>")
	)
	(segment
		(start 194.940428 -286.566864)
		(end 194.508882 -286.135318)
		(width 0.20066)
		(layer "F.Cu")
		(net "M_G_CPU1_SA_DQ<25>")
	)
	(segment
		(start 191.233044 -286.815276)
		(end 190.75781 -286.815276)
		(width 0.20066)
		(layer "F.Cu")
		(net "M_G_CPU1_SA_DQ<25>")
	)
	(segment
		(start 126.786894 -268.56944)
		(end 126.787148 -268.569694)
		(width 0.20066)
		(layer "F.Cu")
		(net "M_G_CPU1_SA_DQ<25>")
	)
	(segment
		(start 191.539114 -286.141668)
		(end 191.421004 -286.259778)
		(width 0.20066)
		(layer "F.Cu")
		(net "M_G_CPU1_SA_DQ<25>")
	)
	(segment
		(start 126.786894 -268.033754)
		(end 126.786894 -268.56944)
		(width 0.20066)
		(layer "F.Cu")
		(net "M_G_CPU1_SA_DQ<25>")
	)
	(segment
		(start 191.421004 -286.627316)
		(end 191.233044 -286.815276)
		(width 0.20066)
		(layer "F.Cu")
		(net "M_G_CPU1_SA_DQ<25>")
	)
	(segment
		(start 165.755574 -279.02154)
		(end 164.893244 -279.02154)
		(width 0.18288)
		(layer "In6.Cu")
		(net "M_G_CPU1_SA_DQ<25>")
	)
	(segment
		(start 182.252874 -286.29102)
		(end 182.092854 -286.45104)
		(width 0.18288)
		(layer "In6.Cu")
		(net "M_G_CPU1_SA_DQ<25>")
	)
	(segment
		(start 132.143246 -269.059152)
		(end 132.137404 -269.05585)
		(width 0.088646)
		(layer "In6.Cu")
		(net "M_G_CPU1_SA_DQ<25>")
	)
	(segment
		(start 174.312834 -285.924498)
		(end 174.53229 -285.705042)
		(width 0.18288)
		(layer "In6.Cu")
		(net "M_G_CPU1_SA_DQ<25>")
	)
	(segment
		(start 142.127986 -269.61719)
		(end 140.595604 -269.61719)
		(width 0.18288)
		(layer "In6.Cu")
		(net "M_G_CPU1_SA_DQ<25>")
	)
	(segment
		(start 163.48202 -278.431244)
		(end 163.222178 -278.171402)
		(width 0.18288)
		(layer "In6.Cu")
		(net "M_G_CPU1_SA_DQ<25>")
	)
	(segment
		(start 183.853582 -286.29102)
		(end 183.639714 -286.29102)
		(width 0.18288)
		(layer "In6.Cu")
		(net "M_G_CPU1_SA_DQ<25>")
	)
	(segment
		(start 140.362432 -269.61719)
		(end 140.2334 -269.488158)
		(width 0.088646)
		(layer "In6.Cu")
		(net "M_G_CPU1_SA_DQ<25>")
	)
	(segment
		(start 184.232296 -285.912306)
		(end 183.853582 -286.29102)
		(width 0.18288)
		(layer "In6.Cu")
		(net "M_G_CPU1_SA_DQ<25>")
	)
	(segment
		(start 183.479694 -286.45104)
		(end 183.479694 -286.851852)
		(width 0.18288)
		(layer "In6.Cu")
		(net "M_G_CPU1_SA_DQ<25>")
	)
	(segment
		(start 173.454822 -285.292546)
		(end 172.564044 -285.292546)
		(width 0.18288)
		(layer "In6.Cu")
		(net "M_G_CPU1_SA_DQ<25>")
	)
	(segment
		(start 179.839366 -286.855916)
		(end 179.530248 -287.165034)
		(width 0.18288)
		(layer "In6.Cu")
		(net "M_G_CPU1_SA_DQ<25>")
	)
	(segment
		(start 130.269488 -269.062708)
		(end 130.263646 -269.059152)
		(width 0.088646)
		(layer "In6.Cu")
		(net "M_G_CPU1_SA_DQ<25>")
	)
	(segment
		(start 174.53229 -285.478982)
		(end 174.267876 -285.214568)
		(width 0.18288)
		(layer "In6.Cu")
		(net "M_G_CPU1_SA_DQ<25>")
	)
	(segment
		(start 163.222178 -278.171402)
		(end 162.812222 -278.171402)
		(width 0.18288)
		(layer "In6.Cu")
		(net "M_G_CPU1_SA_DQ<25>")
	)
	(segment
		(start 131.209288 -269.062708)
		(end 131.203446 -269.059152)
		(width 0.088646)
		(layer "In6.Cu")
		(net "M_G_CPU1_SA_DQ<25>")
	)
	(segment
		(start 166.121334 -279.63495)
		(end 165.938454 -279.45207)
		(width 0.18288)
		(layer "In6.Cu")
		(net "M_G_CPU1_SA_DQ<25>")
	)
	(segment
		(start 171.595034 -282.979876)
		(end 171.368974 -282.979876)
		(width 0.18288)
		(layer "In6.Cu")
		(net "M_G_CPU1_SA_DQ<25>")
	)
	(segment
		(start 182.092854 -286.851852)
		(end 181.932834 -287.011872)
		(width 0.18288)
		(layer "In6.Cu")
		(net "M_G_CPU1_SA_DQ<25>")
	)
	(segment
		(start 164.893244 -279.02154)
		(end 164.302948 -278.431244)
		(width 0.18288)
		(layer "In6.Cu")
		(net "M_G_CPU1_SA_DQ<25>")
	)
	(segment
		(start 173.5963 -285.434024)
		(end 173.454822 -285.292546)
		(width 0.18288)
		(layer "In6.Cu")
		(net "M_G_CPU1_SA_DQ<25>")
	)
	(segment
		(start 186.318398 -286.04972)
		(end 185.968132 -286.399986)
		(width 0.18288)
		(layer "In6.Cu")
		(net "M_G_CPU1_SA_DQ<25>")
	)
	(segment
		(start 185.968132 -286.399986)
		(end 185.45683 -286.399986)
		(width 0.18288)
		(layer "In6.Cu")
		(net "M_G_CPU1_SA_DQ<25>")
	)
	(segment
		(start 174.267876 -285.214568)
		(end 174.041816 -285.214568)
		(width 0.18288)
		(layer "In6.Cu")
		(net "M_G_CPU1_SA_DQ<25>")
	)
	(segment
		(start 166.631874 -279.45207)
		(end 166.448994 -279.63495)
		(width 0.18288)
		(layer "In6.Cu")
		(net "M_G_CPU1_SA_DQ<25>")
	)
	(segment
		(start 170.866054 -282.041092)
		(end 170.593512 -281.76855)
		(width 0.18288)
		(layer "In6.Cu")
		(net "M_G_CPU1_SA_DQ<25>")
	)
	(segment
		(start 167.385238 -279.02154)
		(end 166.814754 -279.02154)
		(width 0.18288)
		(layer "In6.Cu")
		(net "M_G_CPU1_SA_DQ<25>")
	)
	(segment
		(start 181.932834 -287.011872)
		(end 181.559454 -287.011872)
		(width 0.18288)
		(layer "In6.Cu")
		(net "M_G_CPU1_SA_DQ<25>")
	)
	(segment
		(start 140.595604 -269.61719)
		(end 140.362432 -269.61719)
		(width 0.088646)
		(layer "In6.Cu")
		(net "M_G_CPU1_SA_DQ<25>")
	)
	(segment
		(start 182.946294 -287.011872)
		(end 182.786274 -286.851852)
		(width 0.18288)
		(layer "In6.Cu")
		(net "M_G_CPU1_SA_DQ<25>")
	)
	(segment
		(start 128.39573 -269.0622)
		(end 128.391666 -269.059914)
		(width 0.088646)
		(layer "In6.Cu")
		(net "M_G_CPU1_SA_DQ<25>")
	)
	(segment
		(start 135.527796 -269.059152)
		(end 135.513064 -269.067788)
		(width 0.088646)
		(layer "In6.Cu")
		(net "M_G_CPU1_SA_DQ<25>")
	)
	(segment
		(start 130.263646 -269.059152)
		(end 130.257804 -269.05585)
		(width 0.088646)
		(layer "In6.Cu")
		(net "M_G_CPU1_SA_DQ<25>")
	)
	(segment
		(start 177.353722 -286.99206)
		(end 175.154336 -286.99206)
		(width 0.18288)
		(layer "In6.Cu")
		(net "M_G_CPU1_SA_DQ<25>")
	)
	(segment
		(start 184.96915 -285.912306)
		(end 184.232296 -285.912306)
		(width 0.18288)
		(layer "In6.Cu")
		(net "M_G_CPU1_SA_DQ<25>")
	)
	(segment
		(start 183.319674 -287.011872)
		(end 182.946294 -287.011872)
		(width 0.18288)
		(layer "In6.Cu")
		(net "M_G_CPU1_SA_DQ<25>")
	)
	(segment
		(start 144.693132 -270.127476)
		(end 142.127986 -269.61719)
		(width 0.18288)
		(layer "In6.Cu")
		(net "M_G_CPU1_SA_DQ<25>")
	)
	(segment
		(start 157.354778 -277.34895)
		(end 150.133304 -270.127476)
		(width 0.18288)
		(layer "In6.Cu")
		(net "M_G_CPU1_SA_DQ<25>")
	)
	(segment
		(start 150.133304 -270.127476)
		(end 144.693132 -270.127476)
		(width 0.18288)
		(layer "In6.Cu")
		(net "M_G_CPU1_SA_DQ<25>")
	)
	(segment
		(start 182.786274 -286.45104)
		(end 182.626254 -286.29102)
		(width 0.18288)
		(layer "In6.Cu")
		(net "M_G_CPU1_SA_DQ<25>")
	)
	(segment
		(start 134.587996 -269.059152)
		(end 134.573264 -269.067788)
		(width 0.088646)
		(layer "In6.Cu")
		(net "M_G_CPU1_SA_DQ<25>")
	)
	(segment
		(start 172.318172 -283.237432)
		(end 172.318172 -283.011372)
		(width 0.18288)
		(layer "In6.Cu")
		(net "M_G_CPU1_SA_DQ<25>")
	)
	(segment
		(start 174.53229 -285.705042)
		(end 174.53229 -285.478982)
		(width 0.18288)
		(layer "In6.Cu")
		(net "M_G_CPU1_SA_DQ<25>")
	)
	(segment
		(start 183.479694 -286.851852)
		(end 183.319674 -287.011872)
		(width 0.18288)
		(layer "In6.Cu")
		(net "M_G_CPU1_SA_DQ<25>")
	)
	(segment
		(start 174.312834 -286.150558)
		(end 174.312834 -285.924498)
		(width 0.18288)
		(layer "In6.Cu")
		(net "M_G_CPU1_SA_DQ<25>")
	)
	(segment
		(start 165.938454 -279.45207)
		(end 165.938454 -279.20442)
		(width 0.18288)
		(layer "In6.Cu")
		(net "M_G_CPU1_SA_DQ<25>")
	)
	(segment
		(start 185.45683 -286.399986)
		(end 184.96915 -285.912306)
		(width 0.18288)
		(layer "In6.Cu")
		(net "M_G_CPU1_SA_DQ<25>")
	)
	(segment
		(start 181.239414 -286.29102)
		(end 181.155086 -286.29102)
		(width 0.18288)
		(layer "In6.Cu")
		(net "M_G_CPU1_SA_DQ<25>")
	)
	(segment
		(start 161.431986 -278.431244)
		(end 160.349692 -277.34895)
		(width 0.18288)
		(layer "In6.Cu")
		(net "M_G_CPU1_SA_DQ<25>")
	)
	(segment
		(start 132.149088 -269.062708)
		(end 132.143246 -269.059152)
		(width 0.088646)
		(layer "In6.Cu")
		(net "M_G_CPU1_SA_DQ<25>")
	)
	(segment
		(start 165.938454 -279.20442)
		(end 165.755574 -279.02154)
		(width 0.18288)
		(layer "In6.Cu")
		(net "M_G_CPU1_SA_DQ<25>")
	)
	(segment
		(start 166.631874 -279.20442)
		(end 166.631874 -279.45207)
		(width 0.18288)
		(layer "In6.Cu")
		(net "M_G_CPU1_SA_DQ<25>")
	)
	(segment
		(start 168.22547 -280.390346)
		(end 168.22547 -279.861772)
		(width 0.18288)
		(layer "In6.Cu")
		(net "M_G_CPU1_SA_DQ<25>")
	)
	(segment
		(start 133.648196 -269.059152)
		(end 133.637782 -269.065248)
		(width 0.088646)
		(layer "In6.Cu")
		(net "M_G_CPU1_SA_DQ<25>")
	)
	(segment
		(start 182.092854 -286.45104)
		(end 182.092854 -286.851852)
		(width 0.18288)
		(layer "In6.Cu")
		(net "M_G_CPU1_SA_DQ<25>")
	)
	(segment
		(start 180.59019 -286.855916)
		(end 179.839366 -286.855916)
		(width 0.18288)
		(layer "In6.Cu")
		(net "M_G_CPU1_SA_DQ<25>")
	)
	(segment
		(start 181.399434 -286.45104)
		(end 181.239414 -286.29102)
		(width 0.18288)
		(layer "In6.Cu")
		(net "M_G_CPU1_SA_DQ<25>")
	)
	(segment
		(start 169.867326 -281.478228)
		(end 169.313352 -281.478228)
		(width 0.18288)
		(layer "In6.Cu")
		(net "M_G_CPU1_SA_DQ<25>")
	)
	(segment
		(start 183.639714 -286.29102)
		(end 183.479694 -286.45104)
		(width 0.18288)
		(layer "In6.Cu")
		(net "M_G_CPU1_SA_DQ<25>")
	)
	(segment
		(start 131.203446 -269.059152)
		(end 131.197604 -269.05585)
		(width 0.088646)
		(layer "In6.Cu")
		(net "M_G_CPU1_SA_DQ<25>")
	)
	(segment
		(start 181.155086 -286.29102)
		(end 180.59019 -286.855916)
		(width 0.18288)
		(layer "In6.Cu")
		(net "M_G_CPU1_SA_DQ<25>")
	)
	(segment
		(start 166.814754 -279.02154)
		(end 166.631874 -279.20442)
		(width 0.18288)
		(layer "In6.Cu")
		(net "M_G_CPU1_SA_DQ<25>")
	)
	(segment
		(start 187.366656 -286.04972)
		(end 186.318398 -286.04972)
		(width 0.18288)
		(layer "In6.Cu")
		(net "M_G_CPU1_SA_DQ<25>")
	)
	(segment
		(start 182.786274 -286.851852)
		(end 182.786274 -286.45104)
		(width 0.18288)
		(layer "In6.Cu")
		(net "M_G_CPU1_SA_DQ<25>")
	)
	(segment
		(start 133.083046 -269.059152)
		(end 133.077204 -269.05585)
		(width 0.088646)
		(layer "In6.Cu")
		(net "M_G_CPU1_SA_DQ<25>")
	)
	(segment
		(start 164.302948 -278.431244)
		(end 163.48202 -278.431244)
		(width 0.18288)
		(layer "In6.Cu")
		(net "M_G_CPU1_SA_DQ<25>")
	)
	(segment
		(start 162.812222 -278.171402)
		(end 162.55238 -278.431244)
		(width 0.18288)
		(layer "In6.Cu")
		(net "M_G_CPU1_SA_DQ<25>")
	)
	(segment
		(start 172.564044 -285.292546)
		(end 172.343064 -285.071566)
		(width 0.18288)
		(layer "In6.Cu")
		(net "M_G_CPU1_SA_DQ<25>")
	)
	(segment
		(start 172.085508 -283.69641)
		(end 172.085508 -283.47035)
		(width 0.18288)
		(layer "In6.Cu")
		(net "M_G_CPU1_SA_DQ<25>")
	)
	(segment
		(start 181.399434 -286.851852)
		(end 181.399434 -286.45104)
		(width 0.18288)
		(layer "In6.Cu")
		(net "M_G_CPU1_SA_DQ<25>")
	)
	(segment
		(start 169.313352 -281.478228)
		(end 168.22547 -280.390346)
		(width 0.18288)
		(layer "In6.Cu")
		(net "M_G_CPU1_SA_DQ<25>")
	)
	(segment
		(start 170.866054 -282.476956)
		(end 170.866054 -282.041092)
		(width 0.18288)
		(layer "In6.Cu")
		(net "M_G_CPU1_SA_DQ<25>")
	)
	(segment
		(start 173.82236 -285.434024)
		(end 173.5963 -285.434024)
		(width 0.18288)
		(layer "In6.Cu")
		(net "M_G_CPU1_SA_DQ<25>")
	)
	(segment
		(start 170.593512 -281.76855)
		(end 170.157648 -281.76855)
		(width 0.18288)
		(layer "In6.Cu")
		(net "M_G_CPU1_SA_DQ<25>")
	)
	(segment
		(start 168.22547 -279.861772)
		(end 167.385238 -279.02154)
		(width 0.18288)
		(layer "In6.Cu")
		(net "M_G_CPU1_SA_DQ<25>")
	)
	(segment
		(start 171.827698 -282.746958)
		(end 171.595034 -282.979876)
		(width 0.18288)
		(layer "In6.Cu")
		(net "M_G_CPU1_SA_DQ<25>")
	)
	(segment
		(start 171.368974 -282.979876)
		(end 170.866054 -282.476956)
		(width 0.18288)
		(layer "In6.Cu")
		(net "M_G_CPU1_SA_DQ<25>")
	)
	(segment
		(start 128.129538 -268.960092)
		(end 127.729488 -268.960092)
		(width 0.088646)
		(layer "In6.Cu")
		(net "M_G_CPU1_SA_DQ<25>")
	)
	(segment
		(start 139.28598 -269.059152)
		(end 139.275566 -269.065248)
		(width 0.088646)
		(layer "In6.Cu")
		(net "M_G_CPU1_SA_DQ<25>")
	)
	(segment
		(start 129.323846 -269.059152)
		(end 129.318004 -269.05585)
		(width 0.088646)
		(layer "In6.Cu")
		(net "M_G_CPU1_SA_DQ<25>")
	)
	(segment
		(start 181.559454 -287.011872)
		(end 181.399434 -286.851852)
		(width 0.18288)
		(layer "In6.Cu")
		(net "M_G_CPU1_SA_DQ<25>")
	)
	(segment
		(start 179.530248 -287.165034)
		(end 177.526696 -287.165034)
		(width 0.18288)
		(layer "In6.Cu")
		(net "M_G_CPU1_SA_DQ<25>")
	)
	(segment
		(start 139.987528 -269.386304)
		(end 139.660376 -269.059152)
		(width 0.088646)
		(layer "In6.Cu")
		(net "M_G_CPU1_SA_DQ<25>")
	)
	(segment
		(start 172.343064 -285.071566)
		(end 172.343064 -283.953966)
		(width 0.18288)
		(layer "In6.Cu")
		(net "M_G_CPU1_SA_DQ<25>")
	)
	(segment
		(start 172.085508 -283.47035)
		(end 172.318172 -283.237432)
		(width 0.18288)
		(layer "In6.Cu")
		(net "M_G_CPU1_SA_DQ<25>")
	)
	(segment
		(start 172.318172 -283.011372)
		(end 172.053758 -282.746958)
		(width 0.18288)
		(layer "In6.Cu")
		(net "M_G_CPU1_SA_DQ<25>")
	)
	(segment
		(start 160.349692 -277.34895)
		(end 157.354778 -277.34895)
		(width 0.18288)
		(layer "In6.Cu")
		(net "M_G_CPU1_SA_DQ<25>")
	)
	(segment
		(start 177.526696 -287.165034)
		(end 177.353722 -286.99206)
		(width 0.18288)
		(layer "In6.Cu")
		(net "M_G_CPU1_SA_DQ<25>")
	)
	(segment
		(start 175.154336 -286.99206)
		(end 174.312834 -286.150558)
		(width 0.18288)
		(layer "In6.Cu")
		(net "M_G_CPU1_SA_DQ<25>")
	)
	(segment
		(start 129.329688 -269.062708)
		(end 129.323846 -269.059152)
		(width 0.088646)
		(layer "In6.Cu")
		(net "M_G_CPU1_SA_DQ<25>")
	)
	(segment
		(start 162.55238 -278.431244)
		(end 161.431986 -278.431244)
		(width 0.18288)
		(layer "In6.Cu")
		(net "M_G_CPU1_SA_DQ<25>")
	)
	(segment
		(start 166.448994 -279.63495)
		(end 166.121334 -279.63495)
		(width 0.18288)
		(layer "In6.Cu")
		(net "M_G_CPU1_SA_DQ<25>")
	)
	(segment
		(start 174.041816 -285.214568)
		(end 173.82236 -285.434024)
		(width 0.18288)
		(layer "In6.Cu")
		(net "M_G_CPU1_SA_DQ<25>")
	)
	(segment
		(start 138.346434 -269.059152)
		(end 138.33602 -269.065248)
		(width 0.088646)
		(layer "In6.Cu")
		(net "M_G_CPU1_SA_DQ<25>")
	)
	(segment
		(start 182.626254 -286.29102)
		(end 182.252874 -286.29102)
		(width 0.18288)
		(layer "In6.Cu")
		(net "M_G_CPU1_SA_DQ<25>")
	)
	(segment
		(start 172.053758 -282.746958)
		(end 171.827698 -282.746958)
		(width 0.18288)
		(layer "In6.Cu")
		(net "M_G_CPU1_SA_DQ<25>")
	)
	(segment
		(start 170.157648 -281.76855)
		(end 169.867326 -281.478228)
		(width 0.18288)
		(layer "In6.Cu")
		(net "M_G_CPU1_SA_DQ<25>")
	)
	(segment
		(start 140.2334 -269.488158)
		(end 139.987528 -269.386304)
		(width 0.088646)
		(layer "In6.Cu")
		(net "M_G_CPU1_SA_DQ<25>")
	)
	(segment
		(start 187.883546 -286.56661)
		(end 187.366656 -286.04972)
		(width 0.18288)
		(layer "In6.Cu")
		(net "M_G_CPU1_SA_DQ<25>")
	)
	(segment
		(start 172.343064 -283.953966)
		(end 172.085508 -283.69641)
		(width 0.18288)
		(layer "In6.Cu")
		(net "M_G_CPU1_SA_DQ<25>")
	)
	(arc
		(start 136.467596 -269.059152)
		(mid 136.184894 -269.134928)
		(end 135.902192 -269.059152)
		(width 0.088646)
		(layer "In6.Cu")
		(net "M_G_CPU1_SA_DQ<25>")
	)
	(arc
		(start 139.660376 -269.059152)
		(mid 139.473178 -269.009009)
		(end 139.28598 -269.059152)
		(width 0.088646)
		(layer "In6.Cu")
		(net "M_G_CPU1_SA_DQ<25>")
	)
	(arc
		(start 127.729488 -268.960092)
		(mid 127.219485 -268.858628)
		(end 126.787148 -268.569694)
		(width 0.088646)
		(layer "In6.Cu")
		(net "M_G_CPU1_SA_DQ<25>")
	)
	(arc
		(start 131.768596 -269.059152)
		(mid 131.489422 -269.134917)
		(end 131.209288 -269.062708)
		(width 0.088646)
		(layer "In6.Cu")
		(net "M_G_CPU1_SA_DQ<25>")
	)
	(arc
		(start 133.077204 -269.05585)
		(mid 132.892349 -269.0089)
		(end 132.708396 -269.059152)
		(width 0.088646)
		(layer "In6.Cu")
		(net "M_G_CPU1_SA_DQ<25>")
	)
	(arc
		(start 132.137404 -269.05585)
		(mid 131.952549 -269.0089)
		(end 131.768596 -269.059152)
		(width 0.088646)
		(layer "In6.Cu")
		(net "M_G_CPU1_SA_DQ<25>")
	)
	(arc
		(start 129.888996 -269.059152)
		(mid 129.609822 -269.134917)
		(end 129.329688 -269.062708)
		(width 0.088646)
		(layer "In6.Cu")
		(net "M_G_CPU1_SA_DQ<25>")
	)
	(arc
		(start 137.406888 -269.059152)
		(mid 137.12444 -269.134801)
		(end 136.841992 -269.059152)
		(width 0.088646)
		(layer "In6.Cu")
		(net "M_G_CPU1_SA_DQ<25>")
	)
	(arc
		(start 138.72083 -269.059152)
		(mid 138.533632 -269.009009)
		(end 138.346434 -269.059152)
		(width 0.088646)
		(layer "In6.Cu")
		(net "M_G_CPU1_SA_DQ<25>")
	)
	(arc
		(start 139.275566 -269.065248)
		(mid 138.997388 -269.134971)
		(end 138.72083 -269.059152)
		(width 0.088646)
		(layer "In6.Cu")
		(net "M_G_CPU1_SA_DQ<25>")
	)
	(arc
		(start 129.318004 -269.05585)
		(mid 129.133149 -269.0089)
		(end 128.949196 -269.059152)
		(width 0.088646)
		(layer "In6.Cu")
		(net "M_G_CPU1_SA_DQ<25>")
	)
	(arc
		(start 133.637782 -269.065248)
		(mid 133.359604 -269.134971)
		(end 133.083046 -269.059152)
		(width 0.088646)
		(layer "In6.Cu")
		(net "M_G_CPU1_SA_DQ<25>")
	)
	(arc
		(start 128.260602 -268.990318)
		(mid 128.196791 -268.967758)
		(end 128.129538 -268.960092)
		(width 0.088646)
		(layer "In6.Cu")
		(net "M_G_CPU1_SA_DQ<25>")
	)
	(arc
		(start 137.781284 -269.059152)
		(mid 137.594086 -269.009009)
		(end 137.406888 -269.059152)
		(width 0.088646)
		(layer "In6.Cu")
		(net "M_G_CPU1_SA_DQ<25>")
	)
	(arc
		(start 134.962392 -269.059152)
		(mid 134.775194 -269.009009)
		(end 134.587996 -269.059152)
		(width 0.088646)
		(layer "In6.Cu")
		(net "M_G_CPU1_SA_DQ<25>")
	)
	(arc
		(start 138.33602 -269.065248)
		(mid 138.057842 -269.134971)
		(end 137.781284 -269.059152)
		(width 0.088646)
		(layer "In6.Cu")
		(net "M_G_CPU1_SA_DQ<25>")
	)
	(arc
		(start 128.949196 -269.059152)
		(mid 128.672868 -269.134051)
		(end 128.39573 -269.0622)
		(width 0.088646)
		(layer "In6.Cu")
		(net "M_G_CPU1_SA_DQ<25>")
	)
	(arc
		(start 130.257804 -269.05585)
		(mid 130.072949 -269.0089)
		(end 129.888996 -269.059152)
		(width 0.088646)
		(layer "In6.Cu")
		(net "M_G_CPU1_SA_DQ<25>")
	)
	(arc
		(start 134.022592 -269.059152)
		(mid 133.835394 -269.009009)
		(end 133.648196 -269.059152)
		(width 0.088646)
		(layer "In6.Cu")
		(net "M_G_CPU1_SA_DQ<25>")
	)
	(arc
		(start 134.573264 -269.067788)
		(mid 134.296789 -269.135108)
		(end 134.022592 -269.059152)
		(width 0.088646)
		(layer "In6.Cu")
		(net "M_G_CPU1_SA_DQ<25>")
	)
	(arc
		(start 135.902192 -269.059152)
		(mid 135.714994 -269.009009)
		(end 135.527796 -269.059152)
		(width 0.088646)
		(layer "In6.Cu")
		(net "M_G_CPU1_SA_DQ<25>")
	)
	(arc
		(start 135.513064 -269.067788)
		(mid 135.236589 -269.135108)
		(end 134.962392 -269.059152)
		(width 0.088646)
		(layer "In6.Cu")
		(net "M_G_CPU1_SA_DQ<25>")
	)
	(arc
		(start 132.708396 -269.059152)
		(mid 132.429222 -269.134917)
		(end 132.149088 -269.062708)
		(width 0.088646)
		(layer "In6.Cu")
		(net "M_G_CPU1_SA_DQ<25>")
	)
	(arc
		(start 136.841992 -269.059152)
		(mid 136.654794 -269.009009)
		(end 136.467596 -269.059152)
		(width 0.088646)
		(layer "In6.Cu")
		(net "M_G_CPU1_SA_DQ<25>")
	)
	(arc
		(start 131.197604 -269.05585)
		(mid 131.012749 -269.0089)
		(end 130.828796 -269.059152)
		(width 0.088646)
		(layer "In6.Cu")
		(net "M_G_CPU1_SA_DQ<25>")
	)
	(arc
		(start 130.828796 -269.059152)
		(mid 130.549622 -269.134917)
		(end 130.269488 -269.062708)
		(width 0.088646)
		(layer "In6.Cu")
		(net "M_G_CPU1_SA_DQ<25>")
	)
	(arc
		(start 128.391666 -269.059914)
		(mid 128.326563 -269.024309)
		(end 128.260602 -268.990318)
		(width 0.088646)
		(layer "In6.Cu")
		(net "M_G_CPU1_SA_DQ<25>")
	)
	(segment
		(start 194.940428 -288.266886)
		(end 194.508882 -287.83534)
		(width 0.20066)
		(layer "F.Cu")
		(net "M_G_CPU1_SA_DQ<24>")
	)
	(segment
		(start 191.233044 -288.515298)
		(end 190.75781 -288.515298)
		(width 0.20066)
		(layer "F.Cu")
		(net "M_G_CPU1_SA_DQ<24>")
	)
	(segment
		(start 191.421004 -287.9598)
		(end 191.421004 -288.327338)
		(width 0.20066)
		(layer "F.Cu")
		(net "M_G_CPU1_SA_DQ<24>")
	)
	(segment
		(start 127.257048 -269.383256)
		(end 127.256794 -269.38351)
		(width 0.20066)
		(layer "F.Cu")
		(net "M_G_CPU1_SA_DQ<24>")
	)
	(segment
		(start 196.531992 -288.266886)
		(end 194.940428 -288.266886)
		(width 0.20066)
		(layer "F.Cu")
		(net "M_G_CPU1_SA_DQ<24>")
	)
	(segment
		(start 194.092576 -287.84169)
		(end 191.930782 -287.84169)
		(width 0.1016)
		(layer "F.Cu")
		(net "M_G_CPU1_SA_DQ<24>")
	)
	(segment
		(start 191.539114 -287.84169)
		(end 191.421004 -287.9598)
		(width 0.20066)
		(layer "F.Cu")
		(net "M_G_CPU1_SA_DQ<24>")
	)
	(segment
		(start 194.508882 -287.83534)
		(end 194.098926 -287.83534)
		(width 0.20066)
		(layer "F.Cu")
		(net "M_G_CPU1_SA_DQ<24>")
	)
	(segment
		(start 194.098926 -287.83534)
		(end 194.092576 -287.84169)
		(width 0.1016)
		(layer "F.Cu")
		(net "M_G_CPU1_SA_DQ<24>")
	)
	(segment
		(start 188.988446 -288.266632)
		(end 187.883546 -288.266632)
		(width 0.20066)
		(layer "F.Cu")
		(net "M_G_CPU1_SA_DQ<24>")
	)
	(segment
		(start 191.883792 -287.84169)
		(end 191.539114 -287.84169)
		(width 0.20066)
		(layer "F.Cu")
		(net "M_G_CPU1_SA_DQ<24>")
	)
	(segment
		(start 196.532246 -288.266632)
		(end 196.531992 -288.266886)
		(width 0.20066)
		(layer "F.Cu")
		(net "M_G_CPU1_SA_DQ<24>")
	)
	(segment
		(start 190.509144 -288.266632)
		(end 188.988446 -288.266632)
		(width 0.20066)
		(layer "F.Cu")
		(net "M_G_CPU1_SA_DQ<24>")
	)
	(segment
		(start 190.75781 -288.515298)
		(end 190.509144 -288.266632)
		(width 0.20066)
		(layer "F.Cu")
		(net "M_G_CPU1_SA_DQ<24>")
	)
	(segment
		(start 191.421004 -288.327338)
		(end 191.233044 -288.515298)
		(width 0.20066)
		(layer "F.Cu")
		(net "M_G_CPU1_SA_DQ<24>")
	)
	(segment
		(start 191.930782 -287.84169)
		(end 191.883792 -287.84169)
		(width 0.101854)
		(layer "F.Cu")
		(net "M_G_CPU1_SA_DQ<24>")
	)
	(segment
		(start 127.257048 -268.84757)
		(end 127.257048 -269.383256)
		(width 0.20066)
		(layer "F.Cu")
		(net "M_G_CPU1_SA_DQ<24>")
	)
	(segment
		(start 162.954462 -281.282394)
		(end 162.626802 -281.282394)
		(width 0.18288)
		(layer "In6.Cu")
		(net "M_G_CPU1_SA_DQ<24>")
	)
	(segment
		(start 168.581832 -283.438346)
		(end 166.169594 -281.026108)
		(width 0.18288)
		(layer "In6.Cu")
		(net "M_G_CPU1_SA_DQ<24>")
	)
	(segment
		(start 164.137848 -280.103834)
		(end 163.320222 -280.103834)
		(width 0.18288)
		(layer "In6.Cu")
		(net "M_G_CPU1_SA_DQ<24>")
	)
	(segment
		(start 160.33496 -279.213818)
		(end 159.46374 -279.213818)
		(width 0.18288)
		(layer "In6.Cu")
		(net "M_G_CPU1_SA_DQ<24>")
	)
	(segment
		(start 130.748278 -269.881858)
		(end 130.733546 -269.873222)
		(width 0.088646)
		(layer "In6.Cu")
		(net "M_G_CPU1_SA_DQ<24>")
	)
	(segment
		(start 170.399202 -284.110176)
		(end 169.727372 -283.438346)
		(width 0.18288)
		(layer "In6.Cu")
		(net "M_G_CPU1_SA_DQ<24>")
	)
	(segment
		(start 133.178296 -269.873222)
		(end 133.167882 -269.879318)
		(width 0.088646)
		(layer "In6.Cu")
		(net "M_G_CPU1_SA_DQ<24>")
	)
	(segment
		(start 129.808478 -269.881858)
		(end 129.793746 -269.873222)
		(width 0.088646)
		(layer "In6.Cu")
		(net "M_G_CPU1_SA_DQ<24>")
	)
	(segment
		(start 170.822366 -286.993838)
		(end 170.399202 -286.570674)
		(width 0.18288)
		(layer "In6.Cu")
		(net "M_G_CPU1_SA_DQ<24>")
	)
	(segment
		(start 127.928878 -269.881858)
		(end 127.914146 -269.873222)
		(width 0.088646)
		(layer "In6.Cu")
		(net "M_G_CPU1_SA_DQ<24>")
	)
	(segment
		(start 133.563106 -269.879318)
		(end 133.552692 -269.873222)
		(width 0.088646)
		(layer "In6.Cu")
		(net "M_G_CPU1_SA_DQ<24>")
	)
	(segment
		(start 159.28086 -280.286968)
		(end 159.09798 -280.469848)
		(width 0.18288)
		(layer "In6.Cu")
		(net "M_G_CPU1_SA_DQ<24>")
	)
	(segment
		(start 162.443922 -280.286714)
		(end 162.261042 -280.103834)
		(width 0.18288)
		(layer "In6.Cu")
		(net "M_G_CPU1_SA_DQ<24>")
	)
	(segment
		(start 161.224976 -280.103834)
		(end 160.33496 -279.213818)
		(width 0.18288)
		(layer "In6.Cu")
		(net "M_G_CPU1_SA_DQ<24>")
	)
	(segment
		(start 128.868678 -269.881858)
		(end 128.853946 -269.873222)
		(width 0.088646)
		(layer "In6.Cu")
		(net "M_G_CPU1_SA_DQ<24>")
	)
	(segment
		(start 158.58744 -279.396698)
		(end 158.40456 -279.213818)
		(width 0.18288)
		(layer "In6.Cu")
		(net "M_G_CPU1_SA_DQ<24>")
	)
	(segment
		(start 127.914146 -269.873222)
		(end 127.88519 -269.856712)
		(width 0.088646)
		(layer "In6.Cu")
		(net "M_G_CPU1_SA_DQ<24>")
	)
	(segment
		(start 187.883546 -288.266632)
		(end 187.380626 -287.763712)
		(width 0.18288)
		(layer "In6.Cu")
		(net "M_G_CPU1_SA_DQ<24>")
	)
	(segment
		(start 141.8209 -270.625316)
		(end 140.595604 -270.625316)
		(width 0.18288)
		(layer "In6.Cu")
		(net "M_G_CPU1_SA_DQ<24>")
	)
	(segment
		(start 162.261042 -280.103834)
		(end 161.224976 -280.103834)
		(width 0.18288)
		(layer "In6.Cu")
		(net "M_G_CPU1_SA_DQ<24>")
	)
	(segment
		(start 140.395706 -270.625316)
		(end 140.062966 -270.403066)
		(width 0.088646)
		(layer "In6.Cu")
		(net "M_G_CPU1_SA_DQ<24>")
	)
	(segment
		(start 162.626802 -281.282394)
		(end 162.443922 -281.099514)
		(width 0.18288)
		(layer "In6.Cu")
		(net "M_G_CPU1_SA_DQ<24>")
	)
	(segment
		(start 135.447278 -269.881858)
		(end 135.432546 -269.873222)
		(width 0.088646)
		(layer "In6.Cu")
		(net "M_G_CPU1_SA_DQ<24>")
	)
	(segment
		(start 137.326878 -269.881858)
		(end 137.312146 -269.873222)
		(width 0.088646)
		(layer "In6.Cu")
		(net "M_G_CPU1_SA_DQ<24>")
	)
	(segment
		(start 173.081696 -286.993838)
		(end 170.822366 -286.993838)
		(width 0.18288)
		(layer "In6.Cu")
		(net "M_G_CPU1_SA_DQ<24>")
	)
	(segment
		(start 170.399202 -286.570674)
		(end 170.399202 -284.110176)
		(width 0.18288)
		(layer "In6.Cu")
		(net "M_G_CPU1_SA_DQ<24>")
	)
	(segment
		(start 139.820396 -269.948914)
		(end 139.474194 -269.948914)
		(width 0.088646)
		(layer "In6.Cu")
		(net "M_G_CPU1_SA_DQ<24>")
	)
	(segment
		(start 158.77032 -280.469848)
		(end 158.58744 -280.286968)
		(width 0.18288)
		(layer "In6.Cu")
		(net "M_G_CPU1_SA_DQ<24>")
	)
	(segment
		(start 165.060122 -281.026108)
		(end 164.137848 -280.103834)
		(width 0.18288)
		(layer "In6.Cu")
		(net "M_G_CPU1_SA_DQ<24>")
	)
	(segment
		(start 174.7774 -288.689542)
		(end 173.081696 -286.993838)
		(width 0.18288)
		(layer "In6.Cu")
		(net "M_G_CPU1_SA_DQ<24>")
	)
	(segment
		(start 163.320222 -280.103834)
		(end 163.137342 -280.286714)
		(width 0.18288)
		(layer "In6.Cu")
		(net "M_G_CPU1_SA_DQ<24>")
	)
	(segment
		(start 140.062966 -270.403066)
		(end 139.91336 -270.041878)
		(width 0.088646)
		(layer "In6.Cu")
		(net "M_G_CPU1_SA_DQ<24>")
	)
	(segment
		(start 131.688078 -269.881858)
		(end 131.673346 -269.873222)
		(width 0.088646)
		(layer "In6.Cu")
		(net "M_G_CPU1_SA_DQ<24>")
	)
	(segment
		(start 138.266678 -269.881858)
		(end 138.251946 -269.873222)
		(width 0.088646)
		(layer "In6.Cu")
		(net "M_G_CPU1_SA_DQ<24>")
	)
	(segment
		(start 127.88519 -269.856712)
		(end 127.256794 -269.38351)
		(width 0.088646)
		(layer "In6.Cu")
		(net "M_G_CPU1_SA_DQ<24>")
	)
	(segment
		(start 166.169594 -281.026108)
		(end 165.060122 -281.026108)
		(width 0.18288)
		(layer "In6.Cu")
		(net "M_G_CPU1_SA_DQ<24>")
	)
	(segment
		(start 134.507478 -269.881858)
		(end 134.492746 -269.873222)
		(width 0.088646)
		(layer "In6.Cu")
		(net "M_G_CPU1_SA_DQ<24>")
	)
	(segment
		(start 183.22671 -288.689542)
		(end 174.7774 -288.689542)
		(width 0.18288)
		(layer "In6.Cu")
		(net "M_G_CPU1_SA_DQ<24>")
	)
	(segment
		(start 169.727372 -283.438346)
		(end 168.581832 -283.438346)
		(width 0.18288)
		(layer "In6.Cu")
		(net "M_G_CPU1_SA_DQ<24>")
	)
	(segment
		(start 163.137342 -281.099514)
		(end 162.954462 -281.282394)
		(width 0.18288)
		(layer "In6.Cu")
		(net "M_G_CPU1_SA_DQ<24>")
	)
	(segment
		(start 162.443922 -281.099514)
		(end 162.443922 -280.286714)
		(width 0.18288)
		(layer "In6.Cu")
		(net "M_G_CPU1_SA_DQ<24>")
	)
	(segment
		(start 159.09798 -280.469848)
		(end 158.77032 -280.469848)
		(width 0.18288)
		(layer "In6.Cu")
		(net "M_G_CPU1_SA_DQ<24>")
	)
	(segment
		(start 159.46374 -279.213818)
		(end 159.28086 -279.396698)
		(width 0.18288)
		(layer "In6.Cu")
		(net "M_G_CPU1_SA_DQ<24>")
	)
	(segment
		(start 140.595604 -270.625316)
		(end 140.395706 -270.625316)
		(width 0.088646)
		(layer "In6.Cu")
		(net "M_G_CPU1_SA_DQ<24>")
	)
	(segment
		(start 158.58744 -280.286968)
		(end 158.58744 -279.396698)
		(width 0.18288)
		(layer "In6.Cu")
		(net "M_G_CPU1_SA_DQ<24>")
	)
	(segment
		(start 136.387078 -269.881858)
		(end 136.372346 -269.873222)
		(width 0.088646)
		(layer "In6.Cu")
		(net "M_G_CPU1_SA_DQ<24>")
	)
	(segment
		(start 144.51584 -271.161256)
		(end 141.8209 -270.625316)
		(width 0.18288)
		(layer "In6.Cu")
		(net "M_G_CPU1_SA_DQ<24>")
	)
	(segment
		(start 187.380626 -287.763712)
		(end 184.15254 -287.763712)
		(width 0.18288)
		(layer "In6.Cu")
		(net "M_G_CPU1_SA_DQ<24>")
	)
	(segment
		(start 157.524958 -279.213818)
		(end 149.472396 -271.161256)
		(width 0.18288)
		(layer "In6.Cu")
		(net "M_G_CPU1_SA_DQ<24>")
	)
	(segment
		(start 159.28086 -279.396698)
		(end 159.28086 -280.286968)
		(width 0.18288)
		(layer "In6.Cu")
		(net "M_G_CPU1_SA_DQ<24>")
	)
	(segment
		(start 139.91336 -270.041878)
		(end 139.820396 -269.948914)
		(width 0.088646)
		(layer "In6.Cu")
		(net "M_G_CPU1_SA_DQ<24>")
	)
	(segment
		(start 184.15254 -287.763712)
		(end 183.22671 -288.689542)
		(width 0.18288)
		(layer "In6.Cu")
		(net "M_G_CPU1_SA_DQ<24>")
	)
	(segment
		(start 158.40456 -279.213818)
		(end 157.524958 -279.213818)
		(width 0.18288)
		(layer "In6.Cu")
		(net "M_G_CPU1_SA_DQ<24>")
	)
	(segment
		(start 163.137342 -280.286714)
		(end 163.137342 -281.099514)
		(width 0.18288)
		(layer "In6.Cu")
		(net "M_G_CPU1_SA_DQ<24>")
	)
	(segment
		(start 149.472396 -271.161256)
		(end 144.51584 -271.161256)
		(width 0.18288)
		(layer "In6.Cu")
		(net "M_G_CPU1_SA_DQ<24>")
	)
	(arc
		(start 130.35915 -269.873222)
		(mid 130.084921 -269.949147)
		(end 129.808478 -269.881858)
		(width 0.088646)
		(layer "In6.Cu")
		(net "M_G_CPU1_SA_DQ<24>")
	)
	(arc
		(start 136.372346 -269.873222)
		(mid 136.185148 -269.823079)
		(end 135.99795 -269.873222)
		(width 0.088646)
		(layer "In6.Cu")
		(net "M_G_CPU1_SA_DQ<24>")
	)
	(arc
		(start 135.05815 -269.873222)
		(mid 134.783921 -269.949147)
		(end 134.507478 -269.881858)
		(width 0.088646)
		(layer "In6.Cu")
		(net "M_G_CPU1_SA_DQ<24>")
	)
	(arc
		(start 138.251946 -269.873222)
		(mid 138.064748 -269.823079)
		(end 137.87755 -269.873222)
		(width 0.088646)
		(layer "In6.Cu")
		(net "M_G_CPU1_SA_DQ<24>")
	)
	(arc
		(start 133.167882 -269.879318)
		(mid 132.889704 -269.94901)
		(end 132.613146 -269.873222)
		(width 0.088646)
		(layer "In6.Cu")
		(net "M_G_CPU1_SA_DQ<24>")
	)
	(arc
		(start 131.673346 -269.873222)
		(mid 131.486148 -269.823079)
		(end 131.29895 -269.873222)
		(width 0.088646)
		(layer "In6.Cu")
		(net "M_G_CPU1_SA_DQ<24>")
	)
	(arc
		(start 134.11835 -269.873222)
		(mid 133.841537 -269.949058)
		(end 133.563106 -269.879318)
		(width 0.088646)
		(layer "In6.Cu")
		(net "M_G_CPU1_SA_DQ<24>")
	)
	(arc
		(start 128.853946 -269.873222)
		(mid 128.666748 -269.823079)
		(end 128.47955 -269.873222)
		(width 0.088646)
		(layer "In6.Cu")
		(net "M_G_CPU1_SA_DQ<24>")
	)
	(arc
		(start 135.432546 -269.873222)
		(mid 135.245348 -269.823079)
		(end 135.05815 -269.873222)
		(width 0.088646)
		(layer "In6.Cu")
		(net "M_G_CPU1_SA_DQ<24>")
	)
	(arc
		(start 136.93775 -269.873222)
		(mid 136.663521 -269.949147)
		(end 136.387078 -269.881858)
		(width 0.088646)
		(layer "In6.Cu")
		(net "M_G_CPU1_SA_DQ<24>")
	)
	(arc
		(start 139.474194 -269.948914)
		(mid 139.327998 -269.929627)
		(end 139.191746 -269.873222)
		(width 0.088646)
		(layer "In6.Cu")
		(net "M_G_CPU1_SA_DQ<24>")
	)
	(arc
		(start 131.29895 -269.873222)
		(mid 131.024721 -269.949147)
		(end 130.748278 -269.881858)
		(width 0.088646)
		(layer "In6.Cu")
		(net "M_G_CPU1_SA_DQ<24>")
	)
	(arc
		(start 135.99795 -269.873222)
		(mid 135.723721 -269.949147)
		(end 135.447278 -269.881858)
		(width 0.088646)
		(layer "In6.Cu")
		(net "M_G_CPU1_SA_DQ<24>")
	)
	(arc
		(start 133.552692 -269.873222)
		(mid 133.365494 -269.823079)
		(end 133.178296 -269.873222)
		(width 0.088646)
		(layer "In6.Cu")
		(net "M_G_CPU1_SA_DQ<24>")
	)
	(arc
		(start 129.41935 -269.873222)
		(mid 129.145121 -269.949147)
		(end 128.868678 -269.881858)
		(width 0.088646)
		(layer "In6.Cu")
		(net "M_G_CPU1_SA_DQ<24>")
	)
	(arc
		(start 129.793746 -269.873222)
		(mid 129.606548 -269.823079)
		(end 129.41935 -269.873222)
		(width 0.088646)
		(layer "In6.Cu")
		(net "M_G_CPU1_SA_DQ<24>")
	)
	(arc
		(start 137.312146 -269.873222)
		(mid 137.124948 -269.823079)
		(end 136.93775 -269.873222)
		(width 0.088646)
		(layer "In6.Cu")
		(net "M_G_CPU1_SA_DQ<24>")
	)
	(arc
		(start 130.733546 -269.873222)
		(mid 130.546348 -269.823079)
		(end 130.35915 -269.873222)
		(width 0.088646)
		(layer "In6.Cu")
		(net "M_G_CPU1_SA_DQ<24>")
	)
	(arc
		(start 137.87755 -269.873222)
		(mid 137.603321 -269.949147)
		(end 137.326878 -269.881858)
		(width 0.088646)
		(layer "In6.Cu")
		(net "M_G_CPU1_SA_DQ<24>")
	)
	(arc
		(start 138.81735 -269.873222)
		(mid 138.543121 -269.949147)
		(end 138.266678 -269.881858)
		(width 0.088646)
		(layer "In6.Cu")
		(net "M_G_CPU1_SA_DQ<24>")
	)
	(arc
		(start 132.23875 -269.873222)
		(mid 131.964521 -269.949147)
		(end 131.688078 -269.881858)
		(width 0.088646)
		(layer "In6.Cu")
		(net "M_G_CPU1_SA_DQ<24>")
	)
	(arc
		(start 139.191746 -269.873222)
		(mid 139.004548 -269.823079)
		(end 138.81735 -269.873222)
		(width 0.088646)
		(layer "In6.Cu")
		(net "M_G_CPU1_SA_DQ<24>")
	)
	(arc
		(start 132.613146 -269.873222)
		(mid 132.425948 -269.823079)
		(end 132.23875 -269.873222)
		(width 0.088646)
		(layer "In6.Cu")
		(net "M_G_CPU1_SA_DQ<24>")
	)
	(arc
		(start 128.47955 -269.873222)
		(mid 128.205321 -269.949147)
		(end 127.928878 -269.881858)
		(width 0.088646)
		(layer "In6.Cu")
		(net "M_G_CPU1_SA_DQ<24>")
	)
	(arc
		(start 134.492746 -269.873222)
		(mid 134.305548 -269.823079)
		(end 134.11835 -269.873222)
		(width 0.088646)
		(layer "In6.Cu")
		(net "M_G_CPU1_SA_DQ<24>")
	)
	(segment
		(start 193.088514 -289.11677)
		(end 194.786758 -289.11677)
		(width 0.20066)
		(layer "F.Cu")
		(net "M_G_CPU1_SA_DQ<23>")
	)
	(segment
		(start 194.786758 -289.11677)
		(end 195.218812 -289.548824)
		(width 0.20066)
		(layer "F.Cu")
		(net "M_G_CPU1_SA_DQ<23>")
	)
	(segment
		(start 195.510658 -289.548824)
		(end 195.515484 -289.548824)
		(width 0.101854)
		(layer "F.Cu")
		(net "M_G_CPU1_SA_DQ<23>")
	)
	(segment
		(start 195.522596 -289.541712)
		(end 197.530466 -289.541712)
		(width 0.1016)
		(layer "F.Cu")
		(net "M_G_CPU1_SA_DQ<23>")
	)
	(segment
		(start 197.542658 -289.553904)
		(end 198.223886 -289.553904)
		(width 0.20066)
		(layer "F.Cu")
		(net "M_G_CPU1_SA_DQ<23>")
	)
	(segment
		(start 198.427848 -289.349942)
		(end 198.427848 -289.09899)
		(width 0.20066)
		(layer "F.Cu")
		(net "M_G_CPU1_SA_DQ<23>")
	)
	(segment
		(start 195.218812 -289.548824)
		(end 195.510658 -289.548824)
		(width 0.20066)
		(layer "F.Cu")
		(net "M_G_CPU1_SA_DQ<23>")
	)
	(segment
		(start 131.485894 -263.150604)
		(end 131.485894 -263.68629)
		(width 0.20066)
		(layer "F.Cu")
		(net "M_G_CPU1_SA_DQ<23>")
	)
	(segment
		(start 197.530466 -289.541712)
		(end 197.542658 -289.553904)
		(width 0.1016)
		(layer "F.Cu")
		(net "M_G_CPU1_SA_DQ<23>")
	)
	(segment
		(start 191.983614 -289.11677)
		(end 193.088514 -289.11677)
		(width 0.20066)
		(layer "F.Cu")
		(net "M_G_CPU1_SA_DQ<23>")
	)
	(segment
		(start 199.298052 -289.11677)
		(end 200.632314 -289.11677)
		(width 0.20066)
		(layer "F.Cu")
		(net "M_G_CPU1_SA_DQ<23>")
	)
	(segment
		(start 199.046084 -288.864802)
		(end 199.298052 -289.11677)
		(width 0.20066)
		(layer "F.Cu")
		(net "M_G_CPU1_SA_DQ<23>")
	)
	(segment
		(start 198.427848 -289.09899)
		(end 198.662036 -288.864802)
		(width 0.20066)
		(layer "F.Cu")
		(net "M_G_CPU1_SA_DQ<23>")
	)
	(segment
		(start 131.485894 -263.68629)
		(end 131.486148 -263.686544)
		(width 0.20066)
		(layer "F.Cu")
		(net "M_G_CPU1_SA_DQ<23>")
	)
	(segment
		(start 195.515484 -289.548824)
		(end 195.522596 -289.541712)
		(width 0.1016)
		(layer "F.Cu")
		(net "M_G_CPU1_SA_DQ<23>")
	)
	(segment
		(start 198.662036 -288.864802)
		(end 199.046084 -288.864802)
		(width 0.20066)
		(layer "F.Cu")
		(net "M_G_CPU1_SA_DQ<23>")
	)
	(segment
		(start 198.223886 -289.553904)
		(end 198.427848 -289.349942)
		(width 0.20066)
		(layer "F.Cu")
		(net "M_G_CPU1_SA_DQ<23>")
	)
	(segment
		(start 169.269664 -287.719008)
		(end 167.72763 -286.176974)
		(width 0.18288)
		(layer "In4.Cu")
		(net "M_G_CPU1_SA_DQ<23>")
	)
	(segment
		(start 137.887456 -263.244584)
		(end 137.63625 -263.244584)
		(width 0.088646)
		(layer "In4.Cu")
		(net "M_G_CPU1_SA_DQ<23>")
	)
	(segment
		(start 134.962646 -263.196832)
		(end 134.956804 -263.200388)
		(width 0.088646)
		(layer "In4.Cu")
		(net "M_G_CPU1_SA_DQ<23>")
	)
	(segment
		(start 138.173968 -263.531096)
		(end 137.887456 -263.244584)
		(width 0.088646)
		(layer "In4.Cu")
		(net "M_G_CPU1_SA_DQ<23>")
	)
	(segment
		(start 191.983614 -289.11677)
		(end 191.637158 -289.463226)
		(width 0.18288)
		(layer "In4.Cu")
		(net "M_G_CPU1_SA_DQ<23>")
	)
	(segment
		(start 187.202826 -288.08426)
		(end 186.886088 -287.767522)
		(width 0.18288)
		(layer "In4.Cu")
		(net "M_G_CPU1_SA_DQ<23>")
	)
	(segment
		(start 189.265306 -289.150806)
		(end 189.105286 -289.310826)
		(width 0.18288)
		(layer "In4.Cu")
		(net "M_G_CPU1_SA_DQ<23>")
	)
	(segment
		(start 191.152526 -289.463226)
		(end 190.956184 -289.266884)
		(width 0.18288)
		(layer "In4.Cu")
		(net "M_G_CPU1_SA_DQ<23>")
	)
	(segment
		(start 163.415726 -279.760426)
		(end 163.009326 -279.354026)
		(width 0.18288)
		(layer "In4.Cu")
		(net "M_G_CPU1_SA_DQ<23>")
	)
	(segment
		(start 161.256726 -279.354026)
		(end 160.970976 -279.068276)
		(width 0.18288)
		(layer "In4.Cu")
		(net "M_G_CPU1_SA_DQ<23>")
	)
	(segment
		(start 164.076126 -279.760426)
		(end 163.415726 -279.760426)
		(width 0.18288)
		(layer "In4.Cu")
		(net "M_G_CPU1_SA_DQ<23>")
	)
	(segment
		(start 181.898798 -287.77057)
		(end 181.898798 -287.623504)
		(width 0.18288)
		(layer "In4.Cu")
		(net "M_G_CPU1_SA_DQ<23>")
	)
	(segment
		(start 134.967218 -263.194292)
		(end 134.962646 -263.196832)
		(width 0.088646)
		(layer "In4.Cu")
		(net "M_G_CPU1_SA_DQ<23>")
	)
	(segment
		(start 178.985926 -287.67659)
		(end 178.820318 -287.842198)
		(width 0.18288)
		(layer "In4.Cu")
		(net "M_G_CPU1_SA_DQ<23>")
	)
	(segment
		(start 157.553406 -277.094188)
		(end 156.98978 -275.735034)
		(width 0.18288)
		(layer "In4.Cu")
		(net "M_G_CPU1_SA_DQ<23>")
	)
	(segment
		(start 190.956184 -289.266884)
		(end 190.956184 -288.76244)
		(width 0.18288)
		(layer "In4.Cu")
		(net "M_G_CPU1_SA_DQ<23>")
	)
	(segment
		(start 188.533786 -288.851594)
		(end 188.373766 -288.691574)
		(width 0.18288)
		(layer "In4.Cu")
		(net "M_G_CPU1_SA_DQ<23>")
	)
	(segment
		(start 188.533786 -289.150806)
		(end 188.533786 -288.851594)
		(width 0.18288)
		(layer "In4.Cu")
		(net "M_G_CPU1_SA_DQ<23>")
	)
	(segment
		(start 181.087776 -287.623504)
		(end 181.087776 -287.77057)
		(width 0.18288)
		(layer "In4.Cu")
		(net "M_G_CPU1_SA_DQ<23>")
	)
	(segment
		(start 190.956184 -288.76244)
		(end 190.713106 -288.519362)
		(width 0.18288)
		(layer "In4.Cu")
		(net "M_G_CPU1_SA_DQ<23>")
	)
	(segment
		(start 189.265306 -288.866072)
		(end 189.265306 -289.150806)
		(width 0.18288)
		(layer "In4.Cu")
		(net "M_G_CPU1_SA_DQ<23>")
	)
	(segment
		(start 183.833262 -287.93059)
		(end 182.058818 -287.93059)
		(width 0.18288)
		(layer "In4.Cu")
		(net "M_G_CPU1_SA_DQ<23>")
	)
	(segment
		(start 187.503054 -288.691574)
		(end 187.202826 -288.391346)
		(width 0.18288)
		(layer "In4.Cu")
		(net "M_G_CPU1_SA_DQ<23>")
	)
	(segment
		(start 160.970976 -279.068276)
		(end 160.970976 -277.764494)
		(width 0.18288)
		(layer "In4.Cu")
		(net "M_G_CPU1_SA_DQ<23>")
	)
	(segment
		(start 167.33139 -286.176974)
		(end 166.768526 -285.61411)
		(width 0.18288)
		(layer "In4.Cu")
		(net "M_G_CPU1_SA_DQ<23>")
	)
	(segment
		(start 171.10075 -288.868104)
		(end 169.951654 -287.719008)
		(width 0.18288)
		(layer "In4.Cu")
		(net "M_G_CPU1_SA_DQ<23>")
	)
	(segment
		(start 160.810956 -277.604474)
		(end 158.317692 -277.604474)
		(width 0.18288)
		(layer "In4.Cu")
		(net "M_G_CPU1_SA_DQ<23>")
	)
	(segment
		(start 142.799308 -265.016488)
		(end 141.313916 -263.531096)
		(width 0.18288)
		(layer "In4.Cu")
		(net "M_G_CPU1_SA_DQ<23>")
	)
	(segment
		(start 133.088888 -263.19353)
		(end 133.083046 -263.196832)
		(width 0.088646)
		(layer "In4.Cu")
		(net "M_G_CPU1_SA_DQ<23>")
	)
	(segment
		(start 132.149088 -263.19353)
		(end 132.143246 -263.196832)
		(width 0.088646)
		(layer "In4.Cu")
		(net "M_G_CPU1_SA_DQ<23>")
	)
	(segment
		(start 187.202826 -288.391346)
		(end 187.202826 -288.08426)
		(width 0.18288)
		(layer "In4.Cu")
		(net "M_G_CPU1_SA_DQ<23>")
	)
	(segment
		(start 132.143246 -263.196832)
		(end 132.141214 -263.198102)
		(width 0.088646)
		(layer "In4.Cu")
		(net "M_G_CPU1_SA_DQ<23>")
	)
	(segment
		(start 163.009326 -279.354026)
		(end 161.256726 -279.354026)
		(width 0.18288)
		(layer "In4.Cu")
		(net "M_G_CPU1_SA_DQ<23>")
	)
	(segment
		(start 176.558194 -287.964626)
		(end 174.024036 -287.964626)
		(width 0.18288)
		(layer "In4.Cu")
		(net "M_G_CPU1_SA_DQ<23>")
	)
	(segment
		(start 147.184618 -265.929872)
		(end 145.004536 -265.929872)
		(width 0.18288)
		(layer "In4.Cu")
		(net "M_G_CPU1_SA_DQ<23>")
	)
	(segment
		(start 173.296326 -288.692336)
		(end 172.71111 -288.692336)
		(width 0.18288)
		(layer "In4.Cu")
		(net "M_G_CPU1_SA_DQ<23>")
	)
	(segment
		(start 179.722526 -287.67659)
		(end 178.985926 -287.67659)
		(width 0.18288)
		(layer "In4.Cu")
		(net "M_G_CPU1_SA_DQ<23>")
	)
	(segment
		(start 164.53866 -283.10078)
		(end 164.53866 -280.22296)
		(width 0.18288)
		(layer "In4.Cu")
		(net "M_G_CPU1_SA_DQ<23>")
	)
	(segment
		(start 166.768526 -285.61411)
		(end 166.768526 -285.330646)
		(width 0.18288)
		(layer "In4.Cu")
		(net "M_G_CPU1_SA_DQ<23>")
	)
	(segment
		(start 179.976526 -287.93059)
		(end 179.722526 -287.67659)
		(width 0.18288)
		(layer "In4.Cu")
		(net "M_G_CPU1_SA_DQ<23>")
	)
	(segment
		(start 135.906002 -263.1948)
		(end 135.902446 -263.196832)
		(width 0.088646)
		(layer "In4.Cu")
		(net "M_G_CPU1_SA_DQ<23>")
	)
	(segment
		(start 181.898798 -287.623504)
		(end 181.738778 -287.463484)
		(width 0.18288)
		(layer "In4.Cu")
		(net "M_G_CPU1_SA_DQ<23>")
	)
	(segment
		(start 158.317692 -277.604474)
		(end 157.553406 -277.094188)
		(width 0.18288)
		(layer "In4.Cu")
		(net "M_G_CPU1_SA_DQ<23>")
	)
	(segment
		(start 176.680622 -287.842198)
		(end 176.558194 -287.964626)
		(width 0.18288)
		(layer "In4.Cu")
		(net "M_G_CPU1_SA_DQ<23>")
	)
	(segment
		(start 134.022846 -263.196832)
		(end 134.017004 -263.200388)
		(width 0.088646)
		(layer "In4.Cu")
		(net "M_G_CPU1_SA_DQ<23>")
	)
	(segment
		(start 143.176498 -265.172698)
		(end 142.799308 -265.016488)
		(width 0.18288)
		(layer "In4.Cu")
		(net "M_G_CPU1_SA_DQ<23>")
	)
	(segment
		(start 191.637158 -289.463226)
		(end 191.152526 -289.463226)
		(width 0.18288)
		(layer "In4.Cu")
		(net "M_G_CPU1_SA_DQ<23>")
	)
	(segment
		(start 178.820318 -287.842198)
		(end 176.680622 -287.842198)
		(width 0.18288)
		(layer "In4.Cu")
		(net "M_G_CPU1_SA_DQ<23>")
	)
	(segment
		(start 180.927756 -287.93059)
		(end 179.976526 -287.93059)
		(width 0.18288)
		(layer "In4.Cu")
		(net "M_G_CPU1_SA_DQ<23>")
	)
	(segment
		(start 138.665204 -263.531096)
		(end 138.173968 -263.531096)
		(width 0.088646)
		(layer "In4.Cu")
		(net "M_G_CPU1_SA_DQ<23>")
	)
	(segment
		(start 186.886088 -287.767522)
		(end 183.99633 -287.767522)
		(width 0.18288)
		(layer "In4.Cu")
		(net "M_G_CPU1_SA_DQ<23>")
	)
	(segment
		(start 166.768526 -285.330646)
		(end 164.53866 -283.10078)
		(width 0.18288)
		(layer "In4.Cu")
		(net "M_G_CPU1_SA_DQ<23>")
	)
	(segment
		(start 172.71111 -288.692336)
		(end 172.285914 -288.868104)
		(width 0.18288)
		(layer "In4.Cu")
		(net "M_G_CPU1_SA_DQ<23>")
	)
	(segment
		(start 182.058818 -287.93059)
		(end 181.898798 -287.77057)
		(width 0.18288)
		(layer "In4.Cu")
		(net "M_G_CPU1_SA_DQ<23>")
	)
	(segment
		(start 181.738778 -287.463484)
		(end 181.247796 -287.463484)
		(width 0.18288)
		(layer "In4.Cu")
		(net "M_G_CPU1_SA_DQ<23>")
	)
	(segment
		(start 172.285914 -288.868104)
		(end 171.10075 -288.868104)
		(width 0.18288)
		(layer "In4.Cu")
		(net "M_G_CPU1_SA_DQ<23>")
	)
	(segment
		(start 188.373766 -288.691574)
		(end 187.503054 -288.691574)
		(width 0.18288)
		(layer "In4.Cu")
		(net "M_G_CPU1_SA_DQ<23>")
	)
	(segment
		(start 167.72763 -286.176974)
		(end 167.33139 -286.176974)
		(width 0.18288)
		(layer "In4.Cu")
		(net "M_G_CPU1_SA_DQ<23>")
	)
	(segment
		(start 174.024036 -287.964626)
		(end 173.296326 -288.692336)
		(width 0.18288)
		(layer "In4.Cu")
		(net "M_G_CPU1_SA_DQ<23>")
	)
	(segment
		(start 181.087776 -287.77057)
		(end 180.927756 -287.93059)
		(width 0.18288)
		(layer "In4.Cu")
		(net "M_G_CPU1_SA_DQ<23>")
	)
	(segment
		(start 136.467596 -263.196832)
		(end 136.467596 -263.197086)
		(width 0.088646)
		(layer "In4.Cu")
		(net "M_G_CPU1_SA_DQ<23>")
	)
	(segment
		(start 145.004536 -265.929872)
		(end 143.176498 -265.172698)
		(width 0.18288)
		(layer "In4.Cu")
		(net "M_G_CPU1_SA_DQ<23>")
	)
	(segment
		(start 160.970976 -277.764494)
		(end 160.810956 -277.604474)
		(width 0.18288)
		(layer "In4.Cu")
		(net "M_G_CPU1_SA_DQ<23>")
	)
	(segment
		(start 190.713106 -288.519362)
		(end 189.612016 -288.519362)
		(width 0.18288)
		(layer "In4.Cu")
		(net "M_G_CPU1_SA_DQ<23>")
	)
	(segment
		(start 189.612016 -288.519362)
		(end 189.265306 -288.866072)
		(width 0.18288)
		(layer "In4.Cu")
		(net "M_G_CPU1_SA_DQ<23>")
	)
	(segment
		(start 164.53866 -280.22296)
		(end 164.076126 -279.760426)
		(width 0.18288)
		(layer "In4.Cu")
		(net "M_G_CPU1_SA_DQ<23>")
	)
	(segment
		(start 189.105286 -289.310826)
		(end 188.693806 -289.310826)
		(width 0.18288)
		(layer "In4.Cu")
		(net "M_G_CPU1_SA_DQ<23>")
	)
	(segment
		(start 188.693806 -289.310826)
		(end 188.533786 -289.150806)
		(width 0.18288)
		(layer "In4.Cu")
		(net "M_G_CPU1_SA_DQ<23>")
	)
	(segment
		(start 134.028688 -263.19353)
		(end 134.022846 -263.196832)
		(width 0.088646)
		(layer "In4.Cu")
		(net "M_G_CPU1_SA_DQ<23>")
	)
	(segment
		(start 169.951654 -287.719008)
		(end 169.269664 -287.719008)
		(width 0.18288)
		(layer "In4.Cu")
		(net "M_G_CPU1_SA_DQ<23>")
	)
	(segment
		(start 183.99633 -287.767522)
		(end 183.833262 -287.93059)
		(width 0.18288)
		(layer "In4.Cu")
		(net "M_G_CPU1_SA_DQ<23>")
	)
	(segment
		(start 181.247796 -287.463484)
		(end 181.087776 -287.623504)
		(width 0.18288)
		(layer "In4.Cu")
		(net "M_G_CPU1_SA_DQ<23>")
	)
	(segment
		(start 133.083046 -263.196832)
		(end 133.077204 -263.200388)
		(width 0.088646)
		(layer "In4.Cu")
		(net "M_G_CPU1_SA_DQ<23>")
	)
	(segment
		(start 141.313916 -263.531096)
		(end 138.665204 -263.531096)
		(width 0.18288)
		(layer "In4.Cu")
		(net "M_G_CPU1_SA_DQ<23>")
	)
	(segment
		(start 156.98978 -275.735034)
		(end 147.184618 -265.929872)
		(width 0.18288)
		(layer "In4.Cu")
		(net "M_G_CPU1_SA_DQ<23>")
	)
	(arc
		(start 132.708396 -263.197086)
		(mid 132.429222 -263.121287)
		(end 132.149088 -263.19353)
		(width 0.088646)
		(layer "In4.Cu")
		(net "M_G_CPU1_SA_DQ<23>")
	)
	(arc
		(start 137.63625 -263.244584)
		(mid 137.518013 -263.238993)
		(end 137.407396 -263.196832)
		(width 0.088646)
		(layer "In4.Cu")
		(net "M_G_CPU1_SA_DQ<23>")
	)
	(arc
		(start 134.956804 -263.200388)
		(mid 134.771949 -263.247306)
		(end 134.587996 -263.197086)
		(width 0.088646)
		(layer "In4.Cu")
		(net "M_G_CPU1_SA_DQ<23>")
	)
	(arc
		(start 132.141214 -263.198102)
		(mid 131.803649 -263.428869)
		(end 131.486148 -263.686544)
		(width 0.088646)
		(layer "In4.Cu")
		(net "M_G_CPU1_SA_DQ<23>")
	)
	(arc
		(start 136.841992 -263.196832)
		(mid 136.654794 -263.246975)
		(end 136.467596 -263.196832)
		(width 0.088646)
		(layer "In4.Cu")
		(net "M_G_CPU1_SA_DQ<23>")
	)
	(arc
		(start 134.017004 -263.200388)
		(mid 133.832149 -263.247306)
		(end 133.648196 -263.197086)
		(width 0.088646)
		(layer "In4.Cu")
		(net "M_G_CPU1_SA_DQ<23>")
	)
	(arc
		(start 133.077204 -263.200388)
		(mid 132.892349 -263.247306)
		(end 132.708396 -263.197086)
		(width 0.088646)
		(layer "In4.Cu")
		(net "M_G_CPU1_SA_DQ<23>")
	)
	(arc
		(start 133.648196 -263.197086)
		(mid 133.369022 -263.121287)
		(end 133.088888 -263.19353)
		(width 0.088646)
		(layer "In4.Cu")
		(net "M_G_CPU1_SA_DQ<23>")
	)
	(arc
		(start 137.407396 -263.196832)
		(mid 137.124694 -263.12109)
		(end 136.841992 -263.196832)
		(width 0.088646)
		(layer "In4.Cu")
		(net "M_G_CPU1_SA_DQ<23>")
	)
	(arc
		(start 136.467596 -263.197086)
		(mid 136.187115 -263.121314)
		(end 135.906002 -263.1948)
		(width 0.088646)
		(layer "In4.Cu")
		(net "M_G_CPU1_SA_DQ<23>")
	)
	(arc
		(start 134.587996 -263.197086)
		(mid 134.308822 -263.121287)
		(end 134.028688 -263.19353)
		(width 0.088646)
		(layer "In4.Cu")
		(net "M_G_CPU1_SA_DQ<23>")
	)
	(arc
		(start 135.527796 -263.196832)
		(mid 135.247852 -263.121188)
		(end 134.967218 -263.194292)
		(width 0.088646)
		(layer "In4.Cu")
		(net "M_G_CPU1_SA_DQ<23>")
	)
	(arc
		(start 135.902446 -263.196832)
		(mid 135.715138 -263.246975)
		(end 135.527796 -263.196832)
		(width 0.088646)
		(layer "In4.Cu")
		(net "M_G_CPU1_SA_DQ<23>")
	)
	(segment
		(start 131.956048 -263.96442)
		(end 131.956048 -264.500106)
		(width 0.20066)
		(layer "F.Cu")
		(net "M_G_CPU1_SA_DQ<22>")
	)
	(segment
		(start 198.427848 -291.049964)
		(end 198.427848 -290.799012)
		(width 0.20066)
		(layer "F.Cu")
		(net "M_G_CPU1_SA_DQ<22>")
	)
	(segment
		(start 197.542658 -291.253926)
		(end 198.223886 -291.253926)
		(width 0.20066)
		(layer "F.Cu")
		(net "M_G_CPU1_SA_DQ<22>")
	)
	(segment
		(start 191.983868 -290.816792)
		(end 193.088514 -290.816792)
		(width 0.20066)
		(layer "F.Cu")
		(net "M_G_CPU1_SA_DQ<22>")
	)
	(segment
		(start 199.298052 -290.816792)
		(end 200.632314 -290.816792)
		(width 0.20066)
		(layer "F.Cu")
		(net "M_G_CPU1_SA_DQ<22>")
	)
	(segment
		(start 194.786758 -290.816792)
		(end 195.218812 -291.248846)
		(width 0.20066)
		(layer "F.Cu")
		(net "M_G_CPU1_SA_DQ<22>")
	)
	(segment
		(start 199.046084 -290.564824)
		(end 199.298052 -290.816792)
		(width 0.20066)
		(layer "F.Cu")
		(net "M_G_CPU1_SA_DQ<22>")
	)
	(segment
		(start 198.427848 -290.799012)
		(end 198.662036 -290.564824)
		(width 0.20066)
		(layer "F.Cu")
		(net "M_G_CPU1_SA_DQ<22>")
	)
	(segment
		(start 195.218812 -291.248846)
		(end 195.510658 -291.248846)
		(width 0.20066)
		(layer "F.Cu")
		(net "M_G_CPU1_SA_DQ<22>")
	)
	(segment
		(start 198.662036 -290.564824)
		(end 199.046084 -290.564824)
		(width 0.20066)
		(layer "F.Cu")
		(net "M_G_CPU1_SA_DQ<22>")
	)
	(segment
		(start 198.223886 -291.253926)
		(end 198.427848 -291.049964)
		(width 0.20066)
		(layer "F.Cu")
		(net "M_G_CPU1_SA_DQ<22>")
	)
	(segment
		(start 191.983614 -290.816538)
		(end 191.983868 -290.816792)
		(width 0.20066)
		(layer "F.Cu")
		(net "M_G_CPU1_SA_DQ<22>")
	)
	(segment
		(start 195.515484 -291.248846)
		(end 195.522596 -291.241734)
		(width 0.1016)
		(layer "F.Cu")
		(net "M_G_CPU1_SA_DQ<22>")
	)
	(segment
		(start 131.956048 -264.500106)
		(end 131.955794 -264.50036)
		(width 0.20066)
		(layer "F.Cu")
		(net "M_G_CPU1_SA_DQ<22>")
	)
	(segment
		(start 195.522596 -291.241734)
		(end 197.530466 -291.241734)
		(width 0.1016)
		(layer "F.Cu")
		(net "M_G_CPU1_SA_DQ<22>")
	)
	(segment
		(start 193.088514 -290.816792)
		(end 194.786758 -290.816792)
		(width 0.20066)
		(layer "F.Cu")
		(net "M_G_CPU1_SA_DQ<22>")
	)
	(segment
		(start 195.510658 -291.248846)
		(end 195.515484 -291.248846)
		(width 0.101854)
		(layer "F.Cu")
		(net "M_G_CPU1_SA_DQ<22>")
	)
	(segment
		(start 197.530466 -291.241734)
		(end 197.542658 -291.253926)
		(width 0.1016)
		(layer "F.Cu")
		(net "M_G_CPU1_SA_DQ<22>")
	)
	(segment
		(start 162.300666 -281.081226)
		(end 161.078926 -281.081226)
		(width 0.18288)
		(layer "In4.Cu")
		(net "M_G_CPU1_SA_DQ<22>")
	)
	(segment
		(start 160.342326 -280.344626)
		(end 158.96717 -280.344626)
		(width 0.18288)
		(layer "In4.Cu")
		(net "M_G_CPU1_SA_DQ<22>")
	)
	(segment
		(start 179.925726 -289.60699)
		(end 179.740052 -289.421316)
		(width 0.18288)
		(layer "In4.Cu")
		(net "M_G_CPU1_SA_DQ<22>")
	)
	(segment
		(start 133.178296 -264.010902)
		(end 133.172454 -264.007346)
		(width 0.088646)
		(layer "In4.Cu")
		(net "M_G_CPU1_SA_DQ<22>")
	)
	(segment
		(start 181.095904 -289.907472)
		(end 180.795422 -289.60699)
		(width 0.18288)
		(layer "In4.Cu")
		(net "M_G_CPU1_SA_DQ<22>")
	)
	(segment
		(start 188.51499 -290.392612)
		(end 188.022992 -290.392612)
		(width 0.18288)
		(layer "In4.Cu")
		(net "M_G_CPU1_SA_DQ<22>")
	)
	(segment
		(start 189.429644 -290.565586)
		(end 189.429644 -291.274754)
		(width 0.18288)
		(layer "In4.Cu")
		(net "M_G_CPU1_SA_DQ<22>")
	)
	(segment
		(start 189.429644 -291.274754)
		(end 189.269624 -291.434774)
		(width 0.18288)
		(layer "In4.Cu")
		(net "M_G_CPU1_SA_DQ<22>")
	)
	(segment
		(start 166.405052 -286.953198)
		(end 165.562026 -286.110172)
		(width 0.18288)
		(layer "In4.Cu")
		(net "M_G_CPU1_SA_DQ<22>")
	)
	(segment
		(start 188.67501 -290.552632)
		(end 188.51499 -290.392612)
		(width 0.18288)
		(layer "In4.Cu")
		(net "M_G_CPU1_SA_DQ<22>")
	)
	(segment
		(start 161.078926 -281.081226)
		(end 160.342326 -280.344626)
		(width 0.18288)
		(layer "In4.Cu")
		(net "M_G_CPU1_SA_DQ<22>")
	)
	(segment
		(start 182.915306 -289.60699)
		(end 181.789324 -289.60699)
		(width 0.18288)
		(layer "In4.Cu")
		(net "M_G_CPU1_SA_DQ<22>")
	)
	(segment
		(start 179.740052 -289.421316)
		(end 178.891184 -289.421316)
		(width 0.18288)
		(layer "In4.Cu")
		(net "M_G_CPU1_SA_DQ<22>")
	)
	(segment
		(start 162.928046 -281.708606)
		(end 162.300666 -281.081226)
		(width 0.18288)
		(layer "In4.Cu")
		(net "M_G_CPU1_SA_DQ<22>")
	)
	(segment
		(start 191.983614 -290.816538)
		(end 191.422528 -290.255452)
		(width 0.18288)
		(layer "In4.Cu")
		(net "M_G_CPU1_SA_DQ<22>")
	)
	(segment
		(start 177.145188 -289.542474)
		(end 175.299878 -289.542474)
		(width 0.18288)
		(layer "In4.Cu")
		(net "M_G_CPU1_SA_DQ<22>")
	)
	(segment
		(start 187.126626 -290.52139)
		(end 186.31281 -290.52139)
		(width 0.18288)
		(layer "In4.Cu")
		(net "M_G_CPU1_SA_DQ<22>")
	)
	(segment
		(start 164.224208 -284.430978)
		(end 164.00907 -284.430978)
		(width 0.18288)
		(layer "In4.Cu")
		(net "M_G_CPU1_SA_DQ<22>")
	)
	(segment
		(start 157.411928 -279.246838)
		(end 157.120336 -279.05202)
		(width 0.18288)
		(layer "In4.Cu")
		(net "M_G_CPU1_SA_DQ<22>")
	)
	(segment
		(start 157.120336 -279.05202)
		(end 155.863544 -276.016974)
		(width 0.18288)
		(layer "In4.Cu")
		(net "M_G_CPU1_SA_DQ<22>")
	)
	(segment
		(start 138.665204 -264.215626)
		(end 138.108182 -264.215626)
		(width 0.088646)
		(layer "In4.Cu")
		(net "M_G_CPU1_SA_DQ<22>")
	)
	(segment
		(start 146.772122 -266.925552)
		(end 144.805908 -266.925552)
		(width 0.18288)
		(layer "In4.Cu")
		(net "M_G_CPU1_SA_DQ<22>")
	)
	(segment
		(start 134.123938 -264.014204)
		(end 134.118096 -264.010902)
		(width 0.088646)
		(layer "In4.Cu")
		(net "M_G_CPU1_SA_DQ<22>")
	)
	(segment
		(start 186.31281 -290.52139)
		(end 185.890916 -290.099496)
		(width 0.18288)
		(layer "In4.Cu")
		(net "M_G_CPU1_SA_DQ<22>")
	)
	(segment
		(start 166.810182 -287.852358)
		(end 166.405052 -287.447228)
		(width 0.18288)
		(layer "In4.Cu")
		(net "M_G_CPU1_SA_DQ<22>")
	)
	(segment
		(start 184.93232 -290.49599)
		(end 183.804306 -290.49599)
		(width 0.18288)
		(layer "In4.Cu")
		(net "M_G_CPU1_SA_DQ<22>")
	)
	(segment
		(start 180.795422 -289.60699)
		(end 179.925726 -289.60699)
		(width 0.18288)
		(layer "In4.Cu")
		(net "M_G_CPU1_SA_DQ<22>")
	)
	(segment
		(start 173.423326 -290.392358)
		(end 172.189394 -290.392358)
		(width 0.18288)
		(layer "In4.Cu")
		(net "M_G_CPU1_SA_DQ<22>")
	)
	(segment
		(start 166.405052 -287.447228)
		(end 166.405052 -286.953198)
		(width 0.18288)
		(layer "In4.Cu")
		(net "M_G_CPU1_SA_DQ<22>")
	)
	(segment
		(start 187.25642 -290.391596)
		(end 187.126626 -290.52139)
		(width 0.18288)
		(layer "In4.Cu")
		(net "M_G_CPU1_SA_DQ<22>")
	)
	(segment
		(start 175.299878 -289.542474)
		(end 175.175926 -289.666426)
		(width 0.18288)
		(layer "In4.Cu")
		(net "M_G_CPU1_SA_DQ<22>")
	)
	(segment
		(start 188.021976 -290.391596)
		(end 187.25642 -290.391596)
		(width 0.18288)
		(layer "In4.Cu")
		(net "M_G_CPU1_SA_DQ<22>")
	)
	(segment
		(start 183.804306 -290.49599)
		(end 182.915306 -289.60699)
		(width 0.18288)
		(layer "In4.Cu")
		(net "M_G_CPU1_SA_DQ<22>")
	)
	(segment
		(start 188.67501 -291.274754)
		(end 188.67501 -290.552632)
		(width 0.18288)
		(layer "In4.Cu")
		(net "M_G_CPU1_SA_DQ<22>")
	)
	(segment
		(start 191.422528 -290.255452)
		(end 189.739778 -290.255452)
		(width 0.18288)
		(layer "In4.Cu")
		(net "M_G_CPU1_SA_DQ<22>")
	)
	(segment
		(start 169.972736 -289.910012)
		(end 169.562272 -289.499548)
		(width 0.18288)
		(layer "In4.Cu")
		(net "M_G_CPU1_SA_DQ<22>")
	)
	(segment
		(start 132.613146 -264.010902)
		(end 132.53466 -264.056114)
		(width 0.088646)
		(layer "In4.Cu")
		(net "M_G_CPU1_SA_DQ<22>")
	)
	(segment
		(start 155.863544 -276.016974)
		(end 146.772122 -266.925552)
		(width 0.18288)
		(layer "In4.Cu")
		(net "M_G_CPU1_SA_DQ<22>")
	)
	(segment
		(start 134.50316 -264.004806)
		(end 134.492746 -264.010902)
		(width 0.088646)
		(layer "In4.Cu")
		(net "M_G_CPU1_SA_DQ<22>")
	)
	(segment
		(start 174.149258 -289.666426)
		(end 173.423326 -290.392358)
		(width 0.18288)
		(layer "In4.Cu")
		(net "M_G_CPU1_SA_DQ<22>")
	)
	(segment
		(start 178.487324 -289.825176)
		(end 177.42789 -289.825176)
		(width 0.18288)
		(layer "In4.Cu")
		(net "M_G_CPU1_SA_DQ<22>")
	)
	(segment
		(start 188.022992 -290.392612)
		(end 188.021976 -290.391596)
		(width 0.18288)
		(layer "In4.Cu")
		(net "M_G_CPU1_SA_DQ<22>")
	)
	(segment
		(start 170.875452 -289.910012)
		(end 169.972736 -289.910012)
		(width 0.18288)
		(layer "In4.Cu")
		(net "M_G_CPU1_SA_DQ<22>")
	)
	(segment
		(start 178.891184 -289.421316)
		(end 178.487324 -289.825176)
		(width 0.18288)
		(layer "In4.Cu")
		(net "M_G_CPU1_SA_DQ<22>")
	)
	(segment
		(start 157.869382 -279.246838)
		(end 157.411928 -279.246838)
		(width 0.18288)
		(layer "In4.Cu")
		(net "M_G_CPU1_SA_DQ<22>")
	)
	(segment
		(start 158.96717 -280.344626)
		(end 157.869382 -279.246838)
		(width 0.18288)
		(layer "In4.Cu")
		(net "M_G_CPU1_SA_DQ<22>")
	)
	(segment
		(start 172.189394 -290.392358)
		(end 172.07611 -290.505642)
		(width 0.18288)
		(layer "In4.Cu")
		(net "M_G_CPU1_SA_DQ<22>")
	)
	(segment
		(start 165.562026 -285.541212)
		(end 164.776912 -284.756098)
		(width 0.18288)
		(layer "In4.Cu")
		(net "M_G_CPU1_SA_DQ<22>")
	)
	(segment
		(start 143.063722 -266.203938)
		(end 142.907258 -266.139168)
		(width 0.18288)
		(layer "In4.Cu")
		(net "M_G_CPU1_SA_DQ<22>")
	)
	(segment
		(start 165.562026 -286.110172)
		(end 165.562026 -285.541212)
		(width 0.18288)
		(layer "In4.Cu")
		(net "M_G_CPU1_SA_DQ<22>")
	)
	(segment
		(start 189.739778 -290.255452)
		(end 189.429644 -290.565586)
		(width 0.18288)
		(layer "In4.Cu")
		(net "M_G_CPU1_SA_DQ<22>")
	)
	(segment
		(start 138.108182 -264.215626)
		(end 137.827512 -263.934956)
		(width 0.088646)
		(layer "In4.Cu")
		(net "M_G_CPU1_SA_DQ<22>")
	)
	(segment
		(start 185.328814 -290.099496)
		(end 184.93232 -290.49599)
		(width 0.18288)
		(layer "In4.Cu")
		(net "M_G_CPU1_SA_DQ<22>")
	)
	(segment
		(start 188.83503 -291.434774)
		(end 188.67501 -291.274754)
		(width 0.18288)
		(layer "In4.Cu")
		(net "M_G_CPU1_SA_DQ<22>")
	)
	(segment
		(start 140.983716 -264.215626)
		(end 138.665204 -264.215626)
		(width 0.18288)
		(layer "In4.Cu")
		(net "M_G_CPU1_SA_DQ<22>")
	)
	(segment
		(start 134.118096 -264.010902)
		(end 134.112254 -264.007346)
		(width 0.088646)
		(layer "In4.Cu")
		(net "M_G_CPU1_SA_DQ<22>")
	)
	(segment
		(start 189.269624 -291.434774)
		(end 188.83503 -291.434774)
		(width 0.18288)
		(layer "In4.Cu")
		(net "M_G_CPU1_SA_DQ<22>")
	)
	(segment
		(start 185.890916 -290.099496)
		(end 185.328814 -290.099496)
		(width 0.18288)
		(layer "In4.Cu")
		(net "M_G_CPU1_SA_DQ<22>")
	)
	(segment
		(start 164.549328 -284.756098)
		(end 164.224208 -284.430978)
		(width 0.18288)
		(layer "In4.Cu")
		(net "M_G_CPU1_SA_DQ<22>")
	)
	(segment
		(start 137.827512 -263.934956)
		(end 137.594848 -263.934956)
		(width 0.088646)
		(layer "In4.Cu")
		(net "M_G_CPU1_SA_DQ<22>")
	)
	(segment
		(start 172.07611 -290.505642)
		(end 171.471082 -290.505642)
		(width 0.18288)
		(layer "In4.Cu")
		(net "M_G_CPU1_SA_DQ<22>")
	)
	(segment
		(start 164.00907 -284.430978)
		(end 162.928046 -283.349954)
		(width 0.18288)
		(layer "In4.Cu")
		(net "M_G_CPU1_SA_DQ<22>")
	)
	(segment
		(start 142.907258 -266.139168)
		(end 140.983716 -264.215626)
		(width 0.18288)
		(layer "In4.Cu")
		(net "M_G_CPU1_SA_DQ<22>")
	)
	(segment
		(start 181.789324 -289.60699)
		(end 181.488842 -289.907472)
		(width 0.18288)
		(layer "In4.Cu")
		(net "M_G_CPU1_SA_DQ<22>")
	)
	(segment
		(start 181.488842 -289.907472)
		(end 181.095904 -289.907472)
		(width 0.18288)
		(layer "In4.Cu")
		(net "M_G_CPU1_SA_DQ<22>")
	)
	(segment
		(start 164.776912 -284.756098)
		(end 164.549328 -284.756098)
		(width 0.18288)
		(layer "In4.Cu")
		(net "M_G_CPU1_SA_DQ<22>")
	)
	(segment
		(start 171.471082 -290.505642)
		(end 170.875452 -289.910012)
		(width 0.18288)
		(layer "In4.Cu")
		(net "M_G_CPU1_SA_DQ<22>")
	)
	(segment
		(start 133.184138 -264.014204)
		(end 133.178296 -264.010902)
		(width 0.088646)
		(layer "In4.Cu")
		(net "M_G_CPU1_SA_DQ<22>")
	)
	(segment
		(start 169.562272 -289.499548)
		(end 169.145204 -289.499548)
		(width 0.18288)
		(layer "In4.Cu")
		(net "M_G_CPU1_SA_DQ<22>")
	)
	(segment
		(start 167.498014 -287.852358)
		(end 166.810182 -287.852358)
		(width 0.18288)
		(layer "In4.Cu")
		(net "M_G_CPU1_SA_DQ<22>")
	)
	(segment
		(start 169.145204 -289.499548)
		(end 167.498014 -287.852358)
		(width 0.18288)
		(layer "In4.Cu")
		(net "M_G_CPU1_SA_DQ<22>")
	)
	(segment
		(start 177.42789 -289.825176)
		(end 177.145188 -289.542474)
		(width 0.18288)
		(layer "In4.Cu")
		(net "M_G_CPU1_SA_DQ<22>")
	)
	(segment
		(start 162.928046 -283.349954)
		(end 162.928046 -281.708606)
		(width 0.18288)
		(layer "In4.Cu")
		(net "M_G_CPU1_SA_DQ<22>")
	)
	(segment
		(start 175.175926 -289.666426)
		(end 174.149258 -289.666426)
		(width 0.18288)
		(layer "In4.Cu")
		(net "M_G_CPU1_SA_DQ<22>")
	)
	(segment
		(start 144.805908 -266.925552)
		(end 143.063722 -266.203938)
		(width 0.18288)
		(layer "In4.Cu")
		(net "M_G_CPU1_SA_DQ<22>")
	)
	(arc
		(start 137.311892 -264.010902)
		(mid 137.124694 -264.061045)
		(end 136.937496 -264.010902)
		(width 0.088646)
		(layer "In4.Cu")
		(net "M_G_CPU1_SA_DQ<22>")
	)
	(arc
		(start 136.372092 -264.010902)
		(mid 136.184894 -264.061045)
		(end 135.997696 -264.010902)
		(width 0.088646)
		(layer "In4.Cu")
		(net "M_G_CPU1_SA_DQ<22>")
	)
	(arc
		(start 136.937496 -264.010902)
		(mid 136.654794 -263.935126)
		(end 136.372092 -264.010902)
		(width 0.088646)
		(layer "In4.Cu")
		(net "M_G_CPU1_SA_DQ<22>")
	)
	(arc
		(start 134.112254 -264.007346)
		(mid 133.832119 -263.935063)
		(end 133.552946 -264.010902)
		(width 0.088646)
		(layer "In4.Cu")
		(net "M_G_CPU1_SA_DQ<22>")
	)
	(arc
		(start 133.552946 -264.010902)
		(mid 133.368992 -264.061031)
		(end 133.184138 -264.014204)
		(width 0.088646)
		(layer "In4.Cu")
		(net "M_G_CPU1_SA_DQ<22>")
	)
	(arc
		(start 133.172454 -264.007346)
		(mid 132.892319 -263.935063)
		(end 132.613146 -264.010902)
		(width 0.088646)
		(layer "In4.Cu")
		(net "M_G_CPU1_SA_DQ<22>")
	)
	(arc
		(start 132.53466 -264.056114)
		(mid 132.230562 -264.259127)
		(end 131.955794 -264.50036)
		(width 0.088646)
		(layer "In4.Cu")
		(net "M_G_CPU1_SA_DQ<22>")
	)
	(arc
		(start 137.594848 -263.934956)
		(mid 137.448361 -263.954271)
		(end 137.311892 -264.010902)
		(width 0.088646)
		(layer "In4.Cu")
		(net "M_G_CPU1_SA_DQ<22>")
	)
	(arc
		(start 135.057896 -264.010902)
		(mid 134.781337 -263.935159)
		(end 134.50316 -264.004806)
		(width 0.088646)
		(layer "In4.Cu")
		(net "M_G_CPU1_SA_DQ<22>")
	)
	(arc
		(start 135.997696 -264.010902)
		(mid 135.714994 -263.935126)
		(end 135.432292 -264.010902)
		(width 0.088646)
		(layer "In4.Cu")
		(net "M_G_CPU1_SA_DQ<22>")
	)
	(arc
		(start 134.492746 -264.010902)
		(mid 134.308792 -264.061031)
		(end 134.123938 -264.014204)
		(width 0.088646)
		(layer "In4.Cu")
		(net "M_G_CPU1_SA_DQ<22>")
	)
	(arc
		(start 135.432292 -264.010902)
		(mid 135.245094 -264.061045)
		(end 135.057896 -264.010902)
		(width 0.088646)
		(layer "In4.Cu")
		(net "M_G_CPU1_SA_DQ<22>")
	)
	(segment
		(start 130.546094 -263.68629)
		(end 130.546348 -263.686544)
		(width 0.20066)
		(layer "F.Cu")
		(net "M_G_CPU1_SA_DQ<21>")
	)
	(segment
		(start 194.508882 -289.535362)
		(end 194.098926 -289.535362)
		(width 0.20066)
		(layer "F.Cu")
		(net "M_G_CPU1_SA_DQ<21>")
	)
	(segment
		(start 190.75781 -290.21532)
		(end 190.509144 -289.966654)
		(width 0.20066)
		(layer "F.Cu")
		(net "M_G_CPU1_SA_DQ<21>")
	)
	(segment
		(start 191.903858 -289.541712)
		(end 191.883792 -289.541712)
		(width 0.101854)
		(layer "F.Cu")
		(net "M_G_CPU1_SA_DQ<21>")
	)
	(segment
		(start 188.988446 -289.966654)
		(end 187.883546 -289.966654)
		(width 0.20066)
		(layer "F.Cu")
		(net "M_G_CPU1_SA_DQ<21>")
	)
	(segment
		(start 194.940428 -289.966908)
		(end 194.508882 -289.535362)
		(width 0.20066)
		(layer "F.Cu")
		(net "M_G_CPU1_SA_DQ<21>")
	)
	(segment
		(start 190.509144 -289.966654)
		(end 188.988446 -289.966654)
		(width 0.20066)
		(layer "F.Cu")
		(net "M_G_CPU1_SA_DQ<21>")
	)
	(segment
		(start 191.421004 -290.02736)
		(end 191.233044 -290.21532)
		(width 0.20066)
		(layer "F.Cu")
		(net "M_G_CPU1_SA_DQ<21>")
	)
	(segment
		(start 191.539114 -289.541712)
		(end 191.421004 -289.659822)
		(width 0.20066)
		(layer "F.Cu")
		(net "M_G_CPU1_SA_DQ<21>")
	)
	(segment
		(start 191.421004 -289.659822)
		(end 191.421004 -290.02736)
		(width 0.20066)
		(layer "F.Cu")
		(net "M_G_CPU1_SA_DQ<21>")
	)
	(segment
		(start 194.098926 -289.535362)
		(end 194.092576 -289.541712)
		(width 0.1016)
		(layer "F.Cu")
		(net "M_G_CPU1_SA_DQ<21>")
	)
	(segment
		(start 196.531992 -289.966908)
		(end 194.940428 -289.966908)
		(width 0.20066)
		(layer "F.Cu")
		(net "M_G_CPU1_SA_DQ<21>")
	)
	(segment
		(start 130.546094 -263.150604)
		(end 130.546094 -263.68629)
		(width 0.20066)
		(layer "F.Cu")
		(net "M_G_CPU1_SA_DQ<21>")
	)
	(segment
		(start 191.883792 -289.541712)
		(end 191.539114 -289.541712)
		(width 0.20066)
		(layer "F.Cu")
		(net "M_G_CPU1_SA_DQ<21>")
	)
	(segment
		(start 196.532246 -289.966654)
		(end 196.531992 -289.966908)
		(width 0.20066)
		(layer "F.Cu")
		(net "M_G_CPU1_SA_DQ<21>")
	)
	(segment
		(start 194.092576 -289.541712)
		(end 191.903858 -289.541712)
		(width 0.1016)
		(layer "F.Cu")
		(net "M_G_CPU1_SA_DQ<21>")
	)
	(segment
		(start 191.233044 -290.21532)
		(end 190.75781 -290.21532)
		(width 0.20066)
		(layer "F.Cu")
		(net "M_G_CPU1_SA_DQ<21>")
	)
	(segment
		(start 167.575992 -286.731202)
		(end 166.996364 -286.731202)
		(width 0.18288)
		(layer "In4.Cu")
		(net "M_G_CPU1_SA_DQ<21>")
	)
	(segment
		(start 164.262562 -283.85389)
		(end 163.517326 -283.108654)
		(width 0.18288)
		(layer "In4.Cu")
		(net "M_G_CPU1_SA_DQ<21>")
	)
	(segment
		(start 131.326382 -264.117582)
		(end 131.141978 -263.933178)
		(width 0.088646)
		(layer "In4.Cu")
		(net "M_G_CPU1_SA_DQ<21>")
	)
	(segment
		(start 184.909206 -289.183064)
		(end 184.63768 -289.45459)
		(width 0.18288)
		(layer "In4.Cu")
		(net "M_G_CPU1_SA_DQ<21>")
	)
	(segment
		(start 163.517326 -282.058364)
		(end 163.677346 -281.898344)
		(width 0.18288)
		(layer "In4.Cu")
		(net "M_G_CPU1_SA_DQ<21>")
	)
	(segment
		(start 179.728368 -288.915348)
		(end 179.043584 -288.915348)
		(width 0.18288)
		(layer "In4.Cu")
		(net "M_G_CPU1_SA_DQ<21>")
	)
	(segment
		(start 177.408078 -288.692082)
		(end 176.559718 -288.692082)
		(width 0.18288)
		(layer "In4.Cu")
		(net "M_G_CPU1_SA_DQ<21>")
	)
	(segment
		(start 179.043584 -288.915348)
		(end 178.820318 -288.692082)
		(width 0.18288)
		(layer "In4.Cu")
		(net "M_G_CPU1_SA_DQ<21>")
	)
	(segment
		(start 181.064916 -288.853118)
		(end 180.904896 -288.693098)
		(width 0.18288)
		(layer "In4.Cu")
		(net "M_G_CPU1_SA_DQ<21>")
	)
	(segment
		(start 169.295064 -288.937954)
		(end 168.30548 -287.94837)
		(width 0.18288)
		(layer "In4.Cu")
		(net "M_G_CPU1_SA_DQ<21>")
	)
	(segment
		(start 176.239678 -289.031172)
		(end 175.891698 -289.031172)
		(width 0.18288)
		(layer "In4.Cu")
		(net "M_G_CPU1_SA_DQ<21>")
	)
	(segment
		(start 175.571658 -288.578544)
		(end 174.234856 -288.578544)
		(width 0.18288)
		(layer "In4.Cu")
		(net "M_G_CPU1_SA_DQ<21>")
	)
	(segment
		(start 138.574526 -263.87171)
		(end 138.574272 -263.871964)
		(width 0.088646)
		(layer "In4.Cu")
		(net "M_G_CPU1_SA_DQ<21>")
	)
	(segment
		(start 183.368442 -288.66719)
		(end 181.988206 -288.66719)
		(width 0.18288)
		(layer "In4.Cu")
		(net "M_G_CPU1_SA_DQ<21>")
	)
	(segment
		(start 185.069226 -288.280348)
		(end 184.909206 -288.440368)
		(width 0.18288)
		(layer "In4.Cu")
		(net "M_G_CPU1_SA_DQ<21>")
	)
	(segment
		(start 178.820318 -288.692082)
		(end 178.552856 -288.692082)
		(width 0.18288)
		(layer "In4.Cu")
		(net "M_G_CPU1_SA_DQ<21>")
	)
	(segment
		(start 161.023046 -280.166826)
		(end 160.443926 -279.587706)
		(width 0.18288)
		(layer "In4.Cu")
		(net "M_G_CPU1_SA_DQ<21>")
	)
	(segment
		(start 132.238496 -263.361932)
		(end 132.233416 -263.36498)
		(width 0.088646)
		(layer "In4.Cu")
		(net "M_G_CPU1_SA_DQ<21>")
	)
	(segment
		(start 180.904896 -288.693098)
		(end 179.950618 -288.693098)
		(width 0.18288)
		(layer "In4.Cu")
		(net "M_G_CPU1_SA_DQ<21>")
	)
	(segment
		(start 181.828186 -288.92881)
		(end 181.668166 -289.08883)
		(width 0.18288)
		(layer "In4.Cu")
		(net "M_G_CPU1_SA_DQ<21>")
	)
	(segment
		(start 136.372092 -263.362186)
		(end 136.372346 -263.361932)
		(width 0.088646)
		(layer "In4.Cu")
		(net "M_G_CPU1_SA_DQ<21>")
	)
	(segment
		(start 138.214354 -263.871964)
		(end 137.780268 -263.437878)
		(width 0.088646)
		(layer "In4.Cu")
		(net "M_G_CPU1_SA_DQ<21>")
	)
	(segment
		(start 160.443926 -279.178766)
		(end 159.909256 -278.644096)
		(width 0.18288)
		(layer "In4.Cu")
		(net "M_G_CPU1_SA_DQ<21>")
	)
	(segment
		(start 187.36691 -289.450018)
		(end 185.813192 -289.450018)
		(width 0.18288)
		(layer "In4.Cu")
		(net "M_G_CPU1_SA_DQ<21>")
	)
	(segment
		(start 181.988206 -288.66719)
		(end 181.828186 -288.82721)
		(width 0.18288)
		(layer "In4.Cu")
		(net "M_G_CPU1_SA_DQ<21>")
	)
	(segment
		(start 170.36415 -288.937954)
		(end 169.295064 -288.937954)
		(width 0.18288)
		(layer "In4.Cu")
		(net "M_G_CPU1_SA_DQ<21>")
	)
	(segment
		(start 184.909206 -288.440368)
		(end 184.909206 -289.183064)
		(width 0.18288)
		(layer "In4.Cu")
		(net "M_G_CPU1_SA_DQ<21>")
	)
	(segment
		(start 157.541722 -278.644096)
		(end 157.455108 -278.557482)
		(width 0.18288)
		(layer "In4.Cu")
		(net "M_G_CPU1_SA_DQ<21>")
	)
	(segment
		(start 178.126898 -289.302952)
		(end 177.782474 -289.302952)
		(width 0.18288)
		(layer "In4.Cu")
		(net "M_G_CPU1_SA_DQ<21>")
	)
	(segment
		(start 157.455108 -278.557482)
		(end 156.285946 -275.735288)
		(width 0.18288)
		(layer "In4.Cu")
		(net "M_G_CPU1_SA_DQ<21>")
	)
	(segment
		(start 177.782474 -289.302952)
		(end 177.599594 -289.120072)
		(width 0.18288)
		(layer "In4.Cu")
		(net "M_G_CPU1_SA_DQ<21>")
	)
	(segment
		(start 181.224936 -289.08883)
		(end 181.064916 -288.92881)
		(width 0.18288)
		(layer "In4.Cu")
		(net "M_G_CPU1_SA_DQ<21>")
	)
	(segment
		(start 175.891698 -289.031172)
		(end 175.731678 -288.871152)
		(width 0.18288)
		(layer "In4.Cu")
		(net "M_G_CPU1_SA_DQ<21>")
	)
	(segment
		(start 179.950618 -288.693098)
		(end 179.728368 -288.915348)
		(width 0.18288)
		(layer "In4.Cu")
		(net "M_G_CPU1_SA_DQ<21>")
	)
	(segment
		(start 171.21886 -289.542474)
		(end 171.08043 -289.404044)
		(width 0.18288)
		(layer "In4.Cu")
		(net "M_G_CPU1_SA_DQ<21>")
	)
	(segment
		(start 171.08043 -289.404044)
		(end 170.83024 -289.404044)
		(width 0.18288)
		(layer "In4.Cu")
		(net "M_G_CPU1_SA_DQ<21>")
	)
	(segment
		(start 166.255446 -285.990284)
		(end 166.255446 -285.525718)
		(width 0.18288)
		(layer "In4.Cu")
		(net "M_G_CPU1_SA_DQ<21>")
	)
	(segment
		(start 184.63768 -289.45459)
		(end 183.862726 -289.45459)
		(width 0.18288)
		(layer "In4.Cu")
		(net "M_G_CPU1_SA_DQ<21>")
	)
	(segment
		(start 163.677346 -281.898344)
		(end 163.677346 -281.230324)
		(width 0.18288)
		(layer "In4.Cu")
		(net "M_G_CPU1_SA_DQ<21>")
	)
	(segment
		(start 134.118096 -263.361932)
		(end 134.112254 -263.365488)
		(width 0.088646)
		(layer "In4.Cu")
		(net "M_G_CPU1_SA_DQ<21>")
	)
	(segment
		(start 170.83024 -289.404044)
		(end 170.36415 -288.937954)
		(width 0.18288)
		(layer "In4.Cu")
		(net "M_G_CPU1_SA_DQ<21>")
	)
	(segment
		(start 134.123938 -263.35863)
		(end 134.118096 -263.361932)
		(width 0.088646)
		(layer "In4.Cu")
		(net "M_G_CPU1_SA_DQ<21>")
	)
	(segment
		(start 176.399698 -288.852102)
		(end 176.399698 -288.871152)
		(width 0.18288)
		(layer "In4.Cu")
		(net "M_G_CPU1_SA_DQ<21>")
	)
	(segment
		(start 174.234856 -288.578544)
		(end 173.270926 -289.542474)
		(width 0.18288)
		(layer "In4.Cu")
		(net "M_G_CPU1_SA_DQ<21>")
	)
	(segment
		(start 178.314096 -289.115754)
		(end 178.126898 -289.302952)
		(width 0.18288)
		(layer "In4.Cu")
		(net "M_G_CPU1_SA_DQ<21>")
	)
	(segment
		(start 178.552856 -288.692082)
		(end 178.314096 -288.930842)
		(width 0.18288)
		(layer "In4.Cu")
		(net "M_G_CPU1_SA_DQ<21>")
	)
	(segment
		(start 181.064916 -288.92881)
		(end 181.064916 -288.853118)
		(width 0.18288)
		(layer "In4.Cu")
		(net "M_G_CPU1_SA_DQ<21>")
	)
	(segment
		(start 177.599594 -289.120072)
		(end 177.599594 -288.883598)
		(width 0.18288)
		(layer "In4.Cu")
		(net "M_G_CPU1_SA_DQ<21>")
	)
	(segment
		(start 183.862726 -289.45459)
		(end 183.595772 -289.187636)
		(width 0.18288)
		(layer "In4.Cu")
		(net "M_G_CPU1_SA_DQ<21>")
	)
	(segment
		(start 156.285946 -275.735288)
		(end 146.97837 -266.427712)
		(width 0.18288)
		(layer "In4.Cu")
		(net "M_G_CPU1_SA_DQ<21>")
	)
	(segment
		(start 181.828186 -288.82721)
		(end 181.828186 -288.92881)
		(width 0.18288)
		(layer "In4.Cu")
		(net "M_G_CPU1_SA_DQ<21>")
	)
	(segment
		(start 168.30548 -287.46069)
		(end 167.575992 -286.731202)
		(width 0.18288)
		(layer "In4.Cu")
		(net "M_G_CPU1_SA_DQ<21>")
	)
	(segment
		(start 177.599594 -288.883598)
		(end 177.408078 -288.692082)
		(width 0.18288)
		(layer "In4.Cu")
		(net "M_G_CPU1_SA_DQ<21>")
	)
	(segment
		(start 135.057896 -263.361932)
		(end 135.052054 -263.365488)
		(width 0.088646)
		(layer "In4.Cu")
		(net "M_G_CPU1_SA_DQ<21>")
	)
	(segment
		(start 163.517326 -281.070304)
		(end 163.517326 -280.557224)
		(width 0.18288)
		(layer "In4.Cu")
		(net "M_G_CPU1_SA_DQ<21>")
	)
	(segment
		(start 185.432446 -288.280348)
		(end 185.069226 -288.280348)
		(width 0.18288)
		(layer "In4.Cu")
		(net "M_G_CPU1_SA_DQ<21>")
	)
	(segment
		(start 141.134846 -263.87171)
		(end 138.665204 -263.87171)
		(width 0.18288)
		(layer "In4.Cu")
		(net "M_G_CPU1_SA_DQ<21>")
	)
	(segment
		(start 168.30548 -287.94837)
		(end 168.30548 -287.46069)
		(width 0.18288)
		(layer "In4.Cu")
		(net "M_G_CPU1_SA_DQ<21>")
	)
	(segment
		(start 176.399698 -288.871152)
		(end 176.239678 -289.031172)
		(width 0.18288)
		(layer "In4.Cu")
		(net "M_G_CPU1_SA_DQ<21>")
	)
	(segment
		(start 185.673238 -288.52114)
		(end 185.432446 -288.280348)
		(width 0.18288)
		(layer "In4.Cu")
		(net "M_G_CPU1_SA_DQ<21>")
	)
	(segment
		(start 135.061706 -263.3599)
		(end 135.057896 -263.361932)
		(width 0.088646)
		(layer "In4.Cu")
		(net "M_G_CPU1_SA_DQ<21>")
	)
	(segment
		(start 183.595772 -288.89452)
		(end 183.368442 -288.66719)
		(width 0.18288)
		(layer "In4.Cu")
		(net "M_G_CPU1_SA_DQ<21>")
	)
	(segment
		(start 132.051044 -263.686544)
		(end 132.051044 -263.692894)
		(width 0.088646)
		(layer "In4.Cu")
		(net "M_G_CPU1_SA_DQ<21>")
	)
	(segment
		(start 132.244338 -263.35863)
		(end 132.238496 -263.361932)
		(width 0.088646)
		(layer "In4.Cu")
		(net "M_G_CPU1_SA_DQ<21>")
	)
	(segment
		(start 136.002014 -263.359392)
		(end 135.997696 -263.361932)
		(width 0.088646)
		(layer "In4.Cu")
		(net "M_G_CPU1_SA_DQ<21>")
	)
	(segment
		(start 146.97837 -266.427712)
		(end 144.905222 -266.427712)
		(width 0.18288)
		(layer "In4.Cu")
		(net "M_G_CPU1_SA_DQ<21>")
	)
	(segment
		(start 133.184138 -263.35863)
		(end 133.178296 -263.361932)
		(width 0.088646)
		(layer "In4.Cu")
		(net "M_G_CPU1_SA_DQ<21>")
	)
	(segment
		(start 185.673238 -289.310064)
		(end 185.673238 -288.52114)
		(width 0.18288)
		(layer "In4.Cu")
		(net "M_G_CPU1_SA_DQ<21>")
	)
	(segment
		(start 164.583618 -283.85389)
		(end 164.262562 -283.85389)
		(width 0.18288)
		(layer "In4.Cu")
		(net "M_G_CPU1_SA_DQ<21>")
	)
	(segment
		(start 175.731678 -288.871152)
		(end 175.731678 -288.738564)
		(width 0.18288)
		(layer "In4.Cu")
		(net "M_G_CPU1_SA_DQ<21>")
	)
	(segment
		(start 175.731678 -288.738564)
		(end 175.571658 -288.578544)
		(width 0.18288)
		(layer "In4.Cu")
		(net "M_G_CPU1_SA_DQ<21>")
	)
	(segment
		(start 187.883546 -289.966654)
		(end 187.36691 -289.450018)
		(width 0.18288)
		(layer "In4.Cu")
		(net "M_G_CPU1_SA_DQ<21>")
	)
	(segment
		(start 185.813192 -289.450018)
		(end 185.673238 -289.310064)
		(width 0.18288)
		(layer "In4.Cu")
		(net "M_G_CPU1_SA_DQ<21>")
	)
	(segment
		(start 159.909256 -278.644096)
		(end 157.541722 -278.644096)
		(width 0.18288)
		(layer "In4.Cu")
		(net "M_G_CPU1_SA_DQ<21>")
	)
	(segment
		(start 133.178296 -263.361932)
		(end 133.172454 -263.365488)
		(width 0.088646)
		(layer "In4.Cu")
		(net "M_G_CPU1_SA_DQ<21>")
	)
	(segment
		(start 163.517326 -283.108654)
		(end 163.517326 -282.058364)
		(width 0.18288)
		(layer "In4.Cu")
		(net "M_G_CPU1_SA_DQ<21>")
	)
	(segment
		(start 144.905222 -266.427712)
		(end 142.832074 -265.568938)
		(width 0.18288)
		(layer "In4.Cu")
		(net "M_G_CPU1_SA_DQ<21>")
	)
	(segment
		(start 137.780268 -263.437878)
		(end 137.606278 -263.437878)
		(width 0.088646)
		(layer "In4.Cu")
		(net "M_G_CPU1_SA_DQ<21>")
	)
	(segment
		(start 166.996364 -286.731202)
		(end 166.255446 -285.990284)
		(width 0.18288)
		(layer "In4.Cu")
		(net "M_G_CPU1_SA_DQ<21>")
	)
	(segment
		(start 138.665204 -263.87171)
		(end 138.574526 -263.87171)
		(width 0.088646)
		(layer "In4.Cu")
		(net "M_G_CPU1_SA_DQ<21>")
	)
	(segment
		(start 183.595772 -289.187636)
		(end 183.595772 -288.89452)
		(width 0.18288)
		(layer "In4.Cu")
		(net "M_G_CPU1_SA_DQ<21>")
	)
	(segment
		(start 181.668166 -289.08883)
		(end 181.224936 -289.08883)
		(width 0.18288)
		(layer "In4.Cu")
		(net "M_G_CPU1_SA_DQ<21>")
	)
	(segment
		(start 160.443926 -279.587706)
		(end 160.443926 -279.178766)
		(width 0.18288)
		(layer "In4.Cu")
		(net "M_G_CPU1_SA_DQ<21>")
	)
	(segment
		(start 138.574272 -263.871964)
		(end 138.214354 -263.871964)
		(width 0.088646)
		(layer "In4.Cu")
		(net "M_G_CPU1_SA_DQ<21>")
	)
	(segment
		(start 142.832074 -265.568938)
		(end 141.134846 -263.87171)
		(width 0.18288)
		(layer "In4.Cu")
		(net "M_G_CPU1_SA_DQ<21>")
	)
	(segment
		(start 178.314096 -288.930842)
		(end 178.314096 -289.115754)
		(width 0.18288)
		(layer "In4.Cu")
		(net "M_G_CPU1_SA_DQ<21>")
	)
	(segment
		(start 166.255446 -285.525718)
		(end 164.583618 -283.85389)
		(width 0.18288)
		(layer "In4.Cu")
		(net "M_G_CPU1_SA_DQ<21>")
	)
	(segment
		(start 163.677346 -281.230324)
		(end 163.517326 -281.070304)
		(width 0.18288)
		(layer "In4.Cu")
		(net "M_G_CPU1_SA_DQ<21>")
	)
	(segment
		(start 176.559718 -288.692082)
		(end 176.399698 -288.852102)
		(width 0.18288)
		(layer "In4.Cu")
		(net "M_G_CPU1_SA_DQ<21>")
	)
	(segment
		(start 163.517326 -280.557224)
		(end 163.126928 -280.166826)
		(width 0.18288)
		(layer "In4.Cu")
		(net "M_G_CPU1_SA_DQ<21>")
	)
	(segment
		(start 173.270926 -289.542474)
		(end 171.21886 -289.542474)
		(width 0.18288)
		(layer "In4.Cu")
		(net "M_G_CPU1_SA_DQ<21>")
	)
	(segment
		(start 163.126928 -280.166826)
		(end 161.023046 -280.166826)
		(width 0.18288)
		(layer "In4.Cu")
		(net "M_G_CPU1_SA_DQ<21>")
	)
	(arc
		(start 135.052054 -263.365488)
		(mid 134.771919 -263.437771)
		(end 134.492746 -263.361932)
		(width 0.088646)
		(layer "In4.Cu")
		(net "M_G_CPU1_SA_DQ<21>")
	)
	(arc
		(start 132.613146 -263.361932)
		(mid 132.429192 -263.311803)
		(end 132.244338 -263.35863)
		(width 0.088646)
		(layer "In4.Cu")
		(net "M_G_CPU1_SA_DQ<21>")
	)
	(arc
		(start 133.172454 -263.365488)
		(mid 132.892319 -263.437771)
		(end 132.613146 -263.361932)
		(width 0.088646)
		(layer "In4.Cu")
		(net "M_G_CPU1_SA_DQ<21>")
	)
	(arc
		(start 132.051044 -263.692894)
		(mid 131.973727 -263.971697)
		(end 131.768596 -264.175748)
		(width 0.088646)
		(layer "In4.Cu")
		(net "M_G_CPU1_SA_DQ<21>")
	)
	(arc
		(start 135.432546 -263.361932)
		(mid 135.247396 -263.311828)
		(end 135.061706 -263.3599)
		(width 0.088646)
		(layer "In4.Cu")
		(net "M_G_CPU1_SA_DQ<21>")
	)
	(arc
		(start 136.937496 -263.362186)
		(mid 136.654794 -263.437928)
		(end 136.372092 -263.362186)
		(width 0.088646)
		(layer "In4.Cu")
		(net "M_G_CPU1_SA_DQ<21>")
	)
	(arc
		(start 132.233416 -263.36498)
		(mid 132.0998 -263.5017)
		(end 132.051044 -263.686544)
		(width 0.088646)
		(layer "In4.Cu")
		(net "M_G_CPU1_SA_DQ<21>")
	)
	(arc
		(start 137.606278 -263.437878)
		(mid 137.45389 -263.420215)
		(end 137.311892 -263.362186)
		(width 0.088646)
		(layer "In4.Cu")
		(net "M_G_CPU1_SA_DQ<21>")
	)
	(arc
		(start 136.372346 -263.361932)
		(mid 136.187509 -263.311671)
		(end 136.002014 -263.359392)
		(width 0.088646)
		(layer "In4.Cu")
		(net "M_G_CPU1_SA_DQ<21>")
	)
	(arc
		(start 135.997696 -263.361932)
		(mid 135.715138 -263.437581)
		(end 135.432546 -263.361932)
		(width 0.088646)
		(layer "In4.Cu")
		(net "M_G_CPU1_SA_DQ<21>")
	)
	(arc
		(start 134.112254 -263.365488)
		(mid 133.832119 -263.437771)
		(end 133.552946 -263.361932)
		(width 0.088646)
		(layer "In4.Cu")
		(net "M_G_CPU1_SA_DQ<21>")
	)
	(arc
		(start 134.492746 -263.361932)
		(mid 134.308792 -263.311803)
		(end 134.123938 -263.35863)
		(width 0.088646)
		(layer "In4.Cu")
		(net "M_G_CPU1_SA_DQ<21>")
	)
	(arc
		(start 131.141978 -263.933178)
		(mid 130.868686 -263.750634)
		(end 130.546348 -263.686544)
		(width 0.088646)
		(layer "In4.Cu")
		(net "M_G_CPU1_SA_DQ<21>")
	)
	(arc
		(start 137.311892 -263.362186)
		(mid 137.124694 -263.312043)
		(end 136.937496 -263.362186)
		(width 0.088646)
		(layer "In4.Cu")
		(net "M_G_CPU1_SA_DQ<21>")
	)
	(arc
		(start 131.768596 -264.175748)
		(mid 131.537637 -264.221677)
		(end 131.326382 -264.117582)
		(width 0.088646)
		(layer "In4.Cu")
		(net "M_G_CPU1_SA_DQ<21>")
	)
	(arc
		(start 133.552946 -263.361932)
		(mid 133.368992 -263.311803)
		(end 133.184138 -263.35863)
		(width 0.088646)
		(layer "In4.Cu")
		(net "M_G_CPU1_SA_DQ<21>")
	)
	(segment
		(start 194.092576 -291.241734)
		(end 191.930782 -291.241734)
		(width 0.1016)
		(layer "F.Cu")
		(net "M_G_CPU1_SA_DQ<20>")
	)
	(segment
		(start 196.531992 -291.66693)
		(end 194.940428 -291.66693)
		(width 0.20066)
		(layer "F.Cu")
		(net "M_G_CPU1_SA_DQ<20>")
	)
	(segment
		(start 190.75781 -291.915342)
		(end 190.509144 -291.666676)
		(width 0.20066)
		(layer "F.Cu")
		(net "M_G_CPU1_SA_DQ<20>")
	)
	(segment
		(start 196.532246 -291.666676)
		(end 196.531992 -291.66693)
		(width 0.20066)
		(layer "F.Cu")
		(net "M_G_CPU1_SA_DQ<20>")
	)
	(segment
		(start 130.076448 -264.500106)
		(end 130.076194 -264.50036)
		(width 0.20066)
		(layer "F.Cu")
		(net "M_G_CPU1_SA_DQ<20>")
	)
	(segment
		(start 190.509144 -291.666676)
		(end 188.988446 -291.666676)
		(width 0.20066)
		(layer "F.Cu")
		(net "M_G_CPU1_SA_DQ<20>")
	)
	(segment
		(start 191.421004 -291.359844)
		(end 191.421004 -291.727382)
		(width 0.20066)
		(layer "F.Cu")
		(net "M_G_CPU1_SA_DQ<20>")
	)
	(segment
		(start 194.098926 -291.235384)
		(end 194.092576 -291.241734)
		(width 0.1016)
		(layer "F.Cu")
		(net "M_G_CPU1_SA_DQ<20>")
	)
	(segment
		(start 194.508882 -291.235384)
		(end 194.098926 -291.235384)
		(width 0.20066)
		(layer "F.Cu")
		(net "M_G_CPU1_SA_DQ<20>")
	)
	(segment
		(start 191.883792 -291.241734)
		(end 191.539114 -291.241734)
		(width 0.20066)
		(layer "F.Cu")
		(net "M_G_CPU1_SA_DQ<20>")
	)
	(segment
		(start 130.076448 -263.96442)
		(end 130.076448 -264.500106)
		(width 0.20066)
		(layer "F.Cu")
		(net "M_G_CPU1_SA_DQ<20>")
	)
	(segment
		(start 194.940428 -291.66693)
		(end 194.508882 -291.235384)
		(width 0.20066)
		(layer "F.Cu")
		(net "M_G_CPU1_SA_DQ<20>")
	)
	(segment
		(start 191.233044 -291.915342)
		(end 190.75781 -291.915342)
		(width 0.20066)
		(layer "F.Cu")
		(net "M_G_CPU1_SA_DQ<20>")
	)
	(segment
		(start 188.988446 -291.666676)
		(end 187.883546 -291.666676)
		(width 0.20066)
		(layer "F.Cu")
		(net "M_G_CPU1_SA_DQ<20>")
	)
	(segment
		(start 191.930782 -291.241734)
		(end 191.883792 -291.241734)
		(width 0.101854)
		(layer "F.Cu")
		(net "M_G_CPU1_SA_DQ<20>")
	)
	(segment
		(start 191.421004 -291.727382)
		(end 191.233044 -291.915342)
		(width 0.20066)
		(layer "F.Cu")
		(net "M_G_CPU1_SA_DQ<20>")
	)
	(segment
		(start 191.539114 -291.241734)
		(end 191.421004 -291.359844)
		(width 0.20066)
		(layer "F.Cu")
		(net "M_G_CPU1_SA_DQ<20>")
	)
	(segment
		(start 180.717698 -290.34359)
		(end 179.620926 -290.34359)
		(width 0.18288)
		(layer "In4.Cu")
		(net "M_G_CPU1_SA_DQ<20>")
	)
	(segment
		(start 181.714648 -290.490656)
		(end 181.714648 -290.802314)
		(width 0.18288)
		(layer "In4.Cu")
		(net "M_G_CPU1_SA_DQ<20>")
	)
	(segment
		(start 177.510948 -290.774882)
		(end 177.510948 -290.578286)
		(width 0.18288)
		(layer "In4.Cu")
		(net "M_G_CPU1_SA_DQ<20>")
	)
	(segment
		(start 172.381926 -291.242496)
		(end 172.253656 -291.114226)
		(width 0.18288)
		(layer "In4.Cu")
		(net "M_G_CPU1_SA_DQ<20>")
	)
	(segment
		(start 140.833094 -264.5537)
		(end 138.665204 -264.5537)
		(width 0.18288)
		(layer "In4.Cu")
		(net "M_G_CPU1_SA_DQ<20>")
	)
	(segment
		(start 138.148822 -264.5537)
		(end 137.720324 -264.125202)
		(width 0.088646)
		(layer "In4.Cu")
		(net "M_G_CPU1_SA_DQ<20>")
	)
	(segment
		(start 134.587996 -264.176002)
		(end 134.587996 -264.175748)
		(width 0.088646)
		(layer "In4.Cu")
		(net "M_G_CPU1_SA_DQ<20>")
	)
	(segment
		(start 183.786526 -291.20719)
		(end 182.909972 -290.330636)
		(width 0.18288)
		(layer "In4.Cu")
		(net "M_G_CPU1_SA_DQ<20>")
	)
	(segment
		(start 173.539404 -291.574474)
		(end 173.207426 -291.242496)
		(width 0.18288)
		(layer "In4.Cu")
		(net "M_G_CPU1_SA_DQ<20>")
	)
	(segment
		(start 181.037738 -290.975288)
		(end 180.877718 -290.815268)
		(width 0.18288)
		(layer "In4.Cu")
		(net "M_G_CPU1_SA_DQ<20>")
	)
	(segment
		(start 173.207426 -291.242496)
		(end 172.381926 -291.242496)
		(width 0.18288)
		(layer "In4.Cu")
		(net "M_G_CPU1_SA_DQ<20>")
	)
	(segment
		(start 175.506126 -290.225226)
		(end 174.463964 -290.225226)
		(width 0.18288)
		(layer "In4.Cu")
		(net "M_G_CPU1_SA_DQ<20>")
	)
	(segment
		(start 164.911024 -286.716216)
		(end 163.483544 -285.288736)
		(width 0.18288)
		(layer "In4.Cu")
		(net "M_G_CPU1_SA_DQ<20>")
	)
	(segment
		(start 163.483544 -285.288736)
		(end 163.483544 -284.763464)
		(width 0.18288)
		(layer "In4.Cu")
		(net "M_G_CPU1_SA_DQ<20>")
	)
	(segment
		(start 166.66591 -288.523426)
		(end 165.824154 -287.68167)
		(width 0.18288)
		(layer "In4.Cu")
		(net "M_G_CPU1_SA_DQ<20>")
	)
	(segment
		(start 163.483544 -284.763464)
		(end 162.422586 -283.702506)
		(width 0.18288)
		(layer "In4.Cu")
		(net "M_G_CPU1_SA_DQ<20>")
	)
	(segment
		(start 170.807126 -290.555426)
		(end 170.682666 -290.430966)
		(width 0.18288)
		(layer "In4.Cu")
		(net "M_G_CPU1_SA_DQ<20>")
	)
	(segment
		(start 160.139126 -280.878026)
		(end 158.329122 -280.878026)
		(width 0.18288)
		(layer "In4.Cu")
		(net "M_G_CPU1_SA_DQ<20>")
	)
	(segment
		(start 177.670968 -290.934902)
		(end 177.510948 -290.774882)
		(width 0.18288)
		(layer "In4.Cu")
		(net "M_G_CPU1_SA_DQ<20>")
	)
	(segment
		(start 179.021486 -290.68395)
		(end 178.729894 -290.392358)
		(width 0.18288)
		(layer "In4.Cu")
		(net "M_G_CPU1_SA_DQ<20>")
	)
	(segment
		(start 170.682666 -290.430966)
		(end 169.125646 -290.430966)
		(width 0.18288)
		(layer "In4.Cu")
		(net "M_G_CPU1_SA_DQ<20>")
	)
	(segment
		(start 138.665204 -264.5537)
		(end 138.148822 -264.5537)
		(width 0.088646)
		(layer "In4.Cu")
		(net "M_G_CPU1_SA_DQ<20>")
	)
	(segment
		(start 181.874668 -290.330636)
		(end 181.714648 -290.490656)
		(width 0.18288)
		(layer "In4.Cu")
		(net "M_G_CPU1_SA_DQ<20>")
	)
	(segment
		(start 137.720324 -264.125202)
		(end 137.594848 -264.125202)
		(width 0.088646)
		(layer "In4.Cu")
		(net "M_G_CPU1_SA_DQ<20>")
	)
	(segment
		(start 173.985428 -291.574474)
		(end 173.539404 -291.574474)
		(width 0.18288)
		(layer "In4.Cu")
		(net "M_G_CPU1_SA_DQ<20>")
	)
	(segment
		(start 187.883546 -291.666676)
		(end 187.261246 -291.0459)
		(width 0.18288)
		(layer "In4.Cu")
		(net "M_G_CPU1_SA_DQ<20>")
	)
	(segment
		(start 186.065668 -291.58692)
		(end 185.014616 -291.58692)
		(width 0.18288)
		(layer "In4.Cu")
		(net "M_G_CPU1_SA_DQ<20>")
	)
	(segment
		(start 174.353474 -291.206428)
		(end 173.985428 -291.574474)
		(width 0.18288)
		(layer "In4.Cu")
		(net "M_G_CPU1_SA_DQ<20>")
	)
	(segment
		(start 144.706086 -267.423392)
		(end 142.993618 -266.714224)
		(width 0.18288)
		(layer "In4.Cu")
		(net "M_G_CPU1_SA_DQ<20>")
	)
	(segment
		(start 180.877718 -290.50361)
		(end 180.717698 -290.34359)
		(width 0.18288)
		(layer "In4.Cu")
		(net "M_G_CPU1_SA_DQ<20>")
	)
	(segment
		(start 184.634886 -291.20719)
		(end 183.786526 -291.20719)
		(width 0.18288)
		(layer "In4.Cu")
		(net "M_G_CPU1_SA_DQ<20>")
	)
	(segment
		(start 162.035744 -281.682444)
		(end 160.943544 -281.682444)
		(width 0.18288)
		(layer "In4.Cu")
		(net "M_G_CPU1_SA_DQ<20>")
	)
	(segment
		(start 162.422586 -283.702506)
		(end 162.422586 -282.069286)
		(width 0.18288)
		(layer "In4.Cu")
		(net "M_G_CPU1_SA_DQ<20>")
	)
	(segment
		(start 177.32502 -290.392358)
		(end 175.673258 -290.392358)
		(width 0.18288)
		(layer "In4.Cu")
		(net "M_G_CPU1_SA_DQ<20>")
	)
	(segment
		(start 179.280566 -290.68395)
		(end 179.021486 -290.68395)
		(width 0.18288)
		(layer "In4.Cu")
		(net "M_G_CPU1_SA_DQ<20>")
	)
	(segment
		(start 182.909972 -290.330636)
		(end 181.874668 -290.330636)
		(width 0.18288)
		(layer "In4.Cu")
		(net "M_G_CPU1_SA_DQ<20>")
	)
	(segment
		(start 165.824154 -287.149032)
		(end 165.391338 -286.716216)
		(width 0.18288)
		(layer "In4.Cu")
		(net "M_G_CPU1_SA_DQ<20>")
	)
	(segment
		(start 185.014616 -291.58692)
		(end 184.634886 -291.20719)
		(width 0.18288)
		(layer "In4.Cu")
		(net "M_G_CPU1_SA_DQ<20>")
	)
	(segment
		(start 171.594526 -291.114226)
		(end 171.188126 -291.520626)
		(width 0.18288)
		(layer "In4.Cu")
		(net "M_G_CPU1_SA_DQ<20>")
	)
	(segment
		(start 132.186426 -264.799826)
		(end 132.143246 -264.824718)
		(width 0.088646)
		(layer "In4.Cu")
		(net "M_G_CPU1_SA_DQ<20>")
	)
	(segment
		(start 133.083046 -264.175748)
		(end 133.077204 -264.172446)
		(width 0.088646)
		(layer "In4.Cu")
		(net "M_G_CPU1_SA_DQ<20>")
	)
	(segment
		(start 169.125646 -290.430966)
		(end 168.648126 -289.953446)
		(width 0.18288)
		(layer "In4.Cu")
		(net "M_G_CPU1_SA_DQ<20>")
	)
	(segment
		(start 158.329122 -280.878026)
		(end 156.910532 -279.930098)
		(width 0.18288)
		(layer "In4.Cu")
		(net "M_G_CPU1_SA_DQ<20>")
	)
	(segment
		(start 160.943544 -281.682444)
		(end 160.139126 -280.878026)
		(width 0.18288)
		(layer "In4.Cu")
		(net "M_G_CPU1_SA_DQ<20>")
	)
	(segment
		(start 170.591226 -290.974526)
		(end 170.807126 -290.758626)
		(width 0.18288)
		(layer "In4.Cu")
		(net "M_G_CPU1_SA_DQ<20>")
	)
	(segment
		(start 178.222148 -290.552378)
		(end 178.222148 -290.774882)
		(width 0.18288)
		(layer "In4.Cu")
		(net "M_G_CPU1_SA_DQ<20>")
	)
	(segment
		(start 181.714648 -290.802314)
		(end 181.541674 -290.975288)
		(width 0.18288)
		(layer "In4.Cu")
		(net "M_G_CPU1_SA_DQ<20>")
	)
	(segment
		(start 175.673258 -290.392358)
		(end 175.506126 -290.225226)
		(width 0.18288)
		(layer "In4.Cu")
		(net "M_G_CPU1_SA_DQ<20>")
	)
	(segment
		(start 165.391338 -286.716216)
		(end 164.911024 -286.716216)
		(width 0.18288)
		(layer "In4.Cu")
		(net "M_G_CPU1_SA_DQ<20>")
	)
	(segment
		(start 170.591226 -291.279326)
		(end 170.591226 -290.974526)
		(width 0.18288)
		(layer "In4.Cu")
		(net "M_G_CPU1_SA_DQ<20>")
	)
	(segment
		(start 162.422586 -282.069286)
		(end 162.035744 -281.682444)
		(width 0.18288)
		(layer "In4.Cu")
		(net "M_G_CPU1_SA_DQ<20>")
	)
	(segment
		(start 170.832526 -291.520626)
		(end 170.591226 -291.279326)
		(width 0.18288)
		(layer "In4.Cu")
		(net "M_G_CPU1_SA_DQ<20>")
	)
	(segment
		(start 177.510948 -290.578286)
		(end 177.32502 -290.392358)
		(width 0.18288)
		(layer "In4.Cu")
		(net "M_G_CPU1_SA_DQ<20>")
	)
	(segment
		(start 155.38196 -276.239478)
		(end 146.565874 -267.423392)
		(width 0.18288)
		(layer "In4.Cu")
		(net "M_G_CPU1_SA_DQ<20>")
	)
	(segment
		(start 178.222148 -290.774882)
		(end 178.062128 -290.934902)
		(width 0.18288)
		(layer "In4.Cu")
		(net "M_G_CPU1_SA_DQ<20>")
	)
	(segment
		(start 132.143246 -264.824718)
		(end 132.138674 -264.827512)
		(width 0.088646)
		(layer "In4.Cu")
		(net "M_G_CPU1_SA_DQ<20>")
	)
	(segment
		(start 178.062128 -290.934902)
		(end 177.670968 -290.934902)
		(width 0.18288)
		(layer "In4.Cu")
		(net "M_G_CPU1_SA_DQ<20>")
	)
	(segment
		(start 168.648126 -289.706558)
		(end 167.464994 -288.523426)
		(width 0.18288)
		(layer "In4.Cu")
		(net "M_G_CPU1_SA_DQ<20>")
	)
	(segment
		(start 134.022846 -264.175748)
		(end 134.017004 -264.172446)
		(width 0.088646)
		(layer "In4.Cu")
		(net "M_G_CPU1_SA_DQ<20>")
	)
	(segment
		(start 168.648126 -289.953446)
		(end 168.648126 -289.706558)
		(width 0.18288)
		(layer "In4.Cu")
		(net "M_G_CPU1_SA_DQ<20>")
	)
	(segment
		(start 170.807126 -290.758626)
		(end 170.807126 -290.555426)
		(width 0.18288)
		(layer "In4.Cu")
		(net "M_G_CPU1_SA_DQ<20>")
	)
	(segment
		(start 134.028688 -264.179304)
		(end 134.022846 -264.175748)
		(width 0.088646)
		(layer "In4.Cu")
		(net "M_G_CPU1_SA_DQ<20>")
	)
	(segment
		(start 165.824154 -287.68167)
		(end 165.824154 -287.149032)
		(width 0.18288)
		(layer "In4.Cu")
		(net "M_G_CPU1_SA_DQ<20>")
	)
	(segment
		(start 171.188126 -291.520626)
		(end 170.832526 -291.520626)
		(width 0.18288)
		(layer "In4.Cu")
		(net "M_G_CPU1_SA_DQ<20>")
	)
	(segment
		(start 181.541674 -290.975288)
		(end 181.037738 -290.975288)
		(width 0.18288)
		(layer "In4.Cu")
		(net "M_G_CPU1_SA_DQ<20>")
	)
	(segment
		(start 167.464994 -288.523426)
		(end 166.66591 -288.523426)
		(width 0.18288)
		(layer "In4.Cu")
		(net "M_G_CPU1_SA_DQ<20>")
	)
	(segment
		(start 146.565874 -267.423392)
		(end 144.706086 -267.423392)
		(width 0.18288)
		(layer "In4.Cu")
		(net "M_G_CPU1_SA_DQ<20>")
	)
	(segment
		(start 179.620926 -290.34359)
		(end 179.280566 -290.68395)
		(width 0.18288)
		(layer "In4.Cu")
		(net "M_G_CPU1_SA_DQ<20>")
	)
	(segment
		(start 156.910532 -279.930098)
		(end 155.38196 -276.239478)
		(width 0.18288)
		(layer "In4.Cu")
		(net "M_G_CPU1_SA_DQ<20>")
	)
	(segment
		(start 178.729894 -290.392358)
		(end 178.382168 -290.392358)
		(width 0.18288)
		(layer "In4.Cu")
		(net "M_G_CPU1_SA_DQ<20>")
	)
	(segment
		(start 187.261246 -291.0459)
		(end 186.606688 -291.0459)
		(width 0.18288)
		(layer "In4.Cu")
		(net "M_G_CPU1_SA_DQ<20>")
	)
	(segment
		(start 133.088888 -264.179304)
		(end 133.083046 -264.175748)
		(width 0.088646)
		(layer "In4.Cu")
		(net "M_G_CPU1_SA_DQ<20>")
	)
	(segment
		(start 132.580634 -264.297668)
		(end 132.400294 -264.578084)
		(width 0.088646)
		(layer "In4.Cu")
		(net "M_G_CPU1_SA_DQ<20>")
	)
	(segment
		(start 174.353474 -290.335716)
		(end 174.353474 -291.206428)
		(width 0.18288)
		(layer "In4.Cu")
		(net "M_G_CPU1_SA_DQ<20>")
	)
	(segment
		(start 186.606688 -291.0459)
		(end 186.065668 -291.58692)
		(width 0.18288)
		(layer "In4.Cu")
		(net "M_G_CPU1_SA_DQ<20>")
	)
	(segment
		(start 142.993618 -266.714224)
		(end 140.833094 -264.5537)
		(width 0.18288)
		(layer "In4.Cu")
		(net "M_G_CPU1_SA_DQ<20>")
	)
	(segment
		(start 130.17754 -264.50036)
		(end 130.076194 -264.50036)
		(width 0.088646)
		(layer "In4.Cu")
		(net "M_G_CPU1_SA_DQ<20>")
	)
	(segment
		(start 172.253656 -291.114226)
		(end 171.594526 -291.114226)
		(width 0.18288)
		(layer "In4.Cu")
		(net "M_G_CPU1_SA_DQ<20>")
	)
	(segment
		(start 180.877718 -290.815268)
		(end 180.877718 -290.50361)
		(width 0.18288)
		(layer "In4.Cu")
		(net "M_G_CPU1_SA_DQ<20>")
	)
	(segment
		(start 178.382168 -290.392358)
		(end 178.222148 -290.552378)
		(width 0.18288)
		(layer "In4.Cu")
		(net "M_G_CPU1_SA_DQ<20>")
	)
	(segment
		(start 131.957318 -264.878566)
		(end 131.02971 -264.878566)
		(width 0.088646)
		(layer "In4.Cu")
		(net "M_G_CPU1_SA_DQ<20>")
	)
	(segment
		(start 174.463964 -290.225226)
		(end 174.353474 -290.335716)
		(width 0.18288)
		(layer "In4.Cu")
		(net "M_G_CPU1_SA_DQ<20>")
	)
	(arc
		(start 136.467596 -264.176002)
		(mid 136.184894 -264.251778)
		(end 135.902192 -264.176002)
		(width 0.088646)
		(layer "In4.Cu")
		(net "M_G_CPU1_SA_DQ<20>")
	)
	(arc
		(start 131.02971 -264.878566)
		(mid 130.9648 -264.873125)
		(end 130.901694 -264.856976)
		(width 0.088646)
		(layer "In4.Cu")
		(net "M_G_CPU1_SA_DQ<20>")
	)
	(arc
		(start 130.901694 -264.856976)
		(mid 130.812294 -264.814598)
		(end 130.737102 -264.750296)
		(width 0.088646)
		(layer "In4.Cu")
		(net "M_G_CPU1_SA_DQ<20>")
	)
	(arc
		(start 137.407396 -264.176002)
		(mid 137.124694 -264.251778)
		(end 136.841992 -264.176002)
		(width 0.088646)
		(layer "In4.Cu")
		(net "M_G_CPU1_SA_DQ<20>")
	)
	(arc
		(start 132.138674 -264.827512)
		(mid 132.051514 -264.865522)
		(end 131.957318 -264.878566)
		(width 0.088646)
		(layer "In4.Cu")
		(net "M_G_CPU1_SA_DQ<20>")
	)
	(arc
		(start 130.737102 -264.750296)
		(mid 130.483963 -264.56568)
		(end 130.17754 -264.50036)
		(width 0.088646)
		(layer "In4.Cu")
		(net "M_G_CPU1_SA_DQ<20>")
	)
	(arc
		(start 136.841992 -264.176002)
		(mid 136.654794 -264.125859)
		(end 136.467596 -264.176002)
		(width 0.088646)
		(layer "In4.Cu")
		(net "M_G_CPU1_SA_DQ<20>")
	)
	(arc
		(start 133.077204 -264.172446)
		(mid 132.892349 -264.125528)
		(end 132.708396 -264.175748)
		(width 0.088646)
		(layer "In4.Cu")
		(net "M_G_CPU1_SA_DQ<20>")
	)
	(arc
		(start 137.594848 -264.125202)
		(mid 137.497778 -264.138259)
		(end 137.407396 -264.176002)
		(width 0.088646)
		(layer "In4.Cu")
		(net "M_G_CPU1_SA_DQ<20>")
	)
	(arc
		(start 135.902192 -264.176002)
		(mid 135.714994 -264.125859)
		(end 135.527796 -264.176002)
		(width 0.088646)
		(layer "In4.Cu")
		(net "M_G_CPU1_SA_DQ<20>")
	)
	(arc
		(start 133.648196 -264.175748)
		(mid 133.369022 -264.251547)
		(end 133.088888 -264.179304)
		(width 0.088646)
		(layer "In4.Cu")
		(net "M_G_CPU1_SA_DQ<20>")
	)
	(arc
		(start 134.962392 -264.176002)
		(mid 134.775194 -264.125859)
		(end 134.587996 -264.176002)
		(width 0.088646)
		(layer "In4.Cu")
		(net "M_G_CPU1_SA_DQ<20>")
	)
	(arc
		(start 132.259324 -264.75309)
		(mid 132.223413 -264.777298)
		(end 132.186426 -264.799826)
		(width 0.088646)
		(layer "In4.Cu")
		(net "M_G_CPU1_SA_DQ<20>")
	)
	(arc
		(start 132.708396 -264.175748)
		(mid 132.637225 -264.22907)
		(end 132.580634 -264.297668)
		(width 0.088646)
		(layer "In4.Cu")
		(net "M_G_CPU1_SA_DQ<20>")
	)
	(arc
		(start 134.587996 -264.175748)
		(mid 134.308822 -264.251547)
		(end 134.028688 -264.179304)
		(width 0.088646)
		(layer "In4.Cu")
		(net "M_G_CPU1_SA_DQ<20>")
	)
	(arc
		(start 132.400294 -264.578084)
		(mid 132.334488 -264.669356)
		(end 132.259324 -264.75309)
		(width 0.088646)
		(layer "In4.Cu")
		(net "M_G_CPU1_SA_DQ<20>")
	)
	(arc
		(start 135.527796 -264.176002)
		(mid 135.245094 -264.251778)
		(end 134.962392 -264.176002)
		(width 0.088646)
		(layer "In4.Cu")
		(net "M_G_CPU1_SA_DQ<20>")
	)
	(arc
		(start 134.017004 -264.172446)
		(mid 133.832149 -264.125528)
		(end 133.648196 -264.175748)
		(width 0.088646)
		(layer "In4.Cu")
		(net "M_G_CPU1_SA_DQ<20>")
	)
	(segment
		(start 130.076448 -275.35886)
		(end 130.076448 -275.894546)
		(width 0.20066)
		(layer "F.Cu")
		(net "M_G_CPU1_SA_DQ<1>")
	)
	(segment
		(start 188.988446 -314.616592)
		(end 187.883546 -314.616592)
		(width 0.20066)
		(layer "F.Cu")
		(net "M_G_CPU1_SA_DQ<1>")
	)
	(segment
		(start 191.421004 -314.677298)
		(end 191.233044 -314.865258)
		(width 0.20066)
		(layer "F.Cu")
		(net "M_G_CPU1_SA_DQ<1>")
	)
	(segment
		(start 190.75781 -314.865258)
		(end 190.509144 -314.616592)
		(width 0.20066)
		(layer "F.Cu")
		(net "M_G_CPU1_SA_DQ<1>")
	)
	(segment
		(start 194.940428 -314.616846)
		(end 194.508882 -314.1853)
		(width 0.20066)
		(layer "F.Cu")
		(net "M_G_CPU1_SA_DQ<1>")
	)
	(segment
		(start 191.539114 -314.19165)
		(end 191.421004 -314.30976)
		(width 0.20066)
		(layer "F.Cu")
		(net "M_G_CPU1_SA_DQ<1>")
	)
	(segment
		(start 194.092576 -314.19165)
		(end 191.903858 -314.19165)
		(width 0.1016)
		(layer "F.Cu")
		(net "M_G_CPU1_SA_DQ<1>")
	)
	(segment
		(start 191.903858 -314.19165)
		(end 191.883792 -314.19165)
		(width 0.101854)
		(layer "F.Cu")
		(net "M_G_CPU1_SA_DQ<1>")
	)
	(segment
		(start 190.509144 -314.616592)
		(end 188.988446 -314.616592)
		(width 0.20066)
		(layer "F.Cu")
		(net "M_G_CPU1_SA_DQ<1>")
	)
	(segment
		(start 130.076448 -275.894546)
		(end 130.076194 -275.8948)
		(width 0.20066)
		(layer "F.Cu")
		(net "M_G_CPU1_SA_DQ<1>")
	)
	(segment
		(start 191.233044 -314.865258)
		(end 190.75781 -314.865258)
		(width 0.20066)
		(layer "F.Cu")
		(net "M_G_CPU1_SA_DQ<1>")
	)
	(segment
		(start 191.421004 -314.30976)
		(end 191.421004 -314.677298)
		(width 0.20066)
		(layer "F.Cu")
		(net "M_G_CPU1_SA_DQ<1>")
	)
	(segment
		(start 194.508882 -314.1853)
		(end 194.098926 -314.1853)
		(width 0.20066)
		(layer "F.Cu")
		(net "M_G_CPU1_SA_DQ<1>")
	)
	(segment
		(start 191.883792 -314.19165)
		(end 191.539114 -314.19165)
		(width 0.20066)
		(layer "F.Cu")
		(net "M_G_CPU1_SA_DQ<1>")
	)
	(segment
		(start 194.098926 -314.1853)
		(end 194.092576 -314.19165)
		(width 0.1016)
		(layer "F.Cu")
		(net "M_G_CPU1_SA_DQ<1>")
	)
	(segment
		(start 196.532246 -314.616592)
		(end 196.531992 -314.616846)
		(width 0.20066)
		(layer "F.Cu")
		(net "M_G_CPU1_SA_DQ<1>")
	)
	(segment
		(start 196.531992 -314.616846)
		(end 194.940428 -314.616846)
		(width 0.20066)
		(layer "F.Cu")
		(net "M_G_CPU1_SA_DQ<1>")
	)
	(segment
		(start 187.357512 -315.142626)
		(end 186.304682 -315.142626)
		(width 0.18288)
		(layer "In4.Cu")
		(net "M_G_CPU1_SA_DQ<1>")
	)
	(segment
		(start 173.371256 -317.683896)
		(end 171.392596 -317.683896)
		(width 0.18288)
		(layer "In4.Cu")
		(net "M_G_CPU1_SA_DQ<1>")
	)
	(segment
		(start 134.680198 -276.72411)
		(end 134.680198 -276.708616)
		(width 0.088646)
		(layer "In4.Cu")
		(net "M_G_CPU1_SA_DQ<1>")
	)
	(segment
		(start 179.92598 -315.90488)
		(end 179.747926 -315.726826)
		(width 0.18288)
		(layer "In4.Cu")
		(net "M_G_CPU1_SA_DQ<1>")
	)
	(segment
		(start 171.392596 -317.683896)
		(end 169.511726 -315.803026)
		(width 0.18288)
		(layer "In4.Cu")
		(net "M_G_CPU1_SA_DQ<1>")
	)
	(segment
		(start 167.898826 -314.926726)
		(end 167.065198 -314.926726)
		(width 0.18288)
		(layer "In4.Cu")
		(net "M_G_CPU1_SA_DQ<1>")
	)
	(segment
		(start 181.354984 -315.951108)
		(end 180.975762 -316.33033)
		(width 0.18288)
		(layer "In4.Cu")
		(net "M_G_CPU1_SA_DQ<1>")
	)
	(segment
		(start 181.559962 -314.964826)
		(end 181.354984 -315.169804)
		(width 0.18288)
		(layer "In4.Cu")
		(net "M_G_CPU1_SA_DQ<1>")
	)
	(segment
		(start 132.238496 -276.384258)
		(end 132.232654 -276.38756)
		(width 0.088646)
		(layer "In4.Cu")
		(net "M_G_CPU1_SA_DQ<1>")
	)
	(segment
		(start 180.975762 -316.33033)
		(end 180.059838 -316.33033)
		(width 0.18288)
		(layer "In4.Cu")
		(net "M_G_CPU1_SA_DQ<1>")
	)
	(segment
		(start 159.634174 -312.384694)
		(end 157.931612 -310.682132)
		(width 0.18288)
		(layer "In4.Cu")
		(net "M_G_CPU1_SA_DQ<1>")
	)
	(segment
		(start 168.775126 -315.803026)
		(end 167.898826 -314.926726)
		(width 0.18288)
		(layer "In4.Cu")
		(net "M_G_CPU1_SA_DQ<1>")
	)
	(segment
		(start 141.596618 -283.726636)
		(end 140.486638 -281.046936)
		(width 0.18288)
		(layer "In4.Cu")
		(net "M_G_CPU1_SA_DQ<1>")
	)
	(segment
		(start 182.973726 -314.964826)
		(end 181.559962 -314.964826)
		(width 0.18288)
		(layer "In4.Cu")
		(net "M_G_CPU1_SA_DQ<1>")
	)
	(segment
		(start 136.08939 -277.522432)
		(end 136.089644 -277.522432)
		(width 0.088646)
		(layer "In4.Cu")
		(net "M_G_CPU1_SA_DQ<1>")
	)
	(segment
		(start 178.351942 -316.582044)
		(end 178.191922 -316.742064)
		(width 0.18288)
		(layer "In4.Cu")
		(net "M_G_CPU1_SA_DQ<1>")
	)
	(segment
		(start 140.486638 -281.046936)
		(end 139.43203 -279.992328)
		(width 0.18288)
		(layer "In4.Cu")
		(net "M_G_CPU1_SA_DQ<1>")
	)
	(segment
		(start 179.747926 -315.726826)
		(end 178.630326 -315.726826)
		(width 0.18288)
		(layer "In4.Cu")
		(net "M_G_CPU1_SA_DQ<1>")
	)
	(segment
		(start 147.313904 -297.964098)
		(end 141.596618 -284.161992)
		(width 0.18288)
		(layer "In4.Cu")
		(net "M_G_CPU1_SA_DQ<1>")
	)
	(segment
		(start 161.490406 -313.496706)
		(end 160.378394 -312.384694)
		(width 0.18288)
		(layer "In4.Cu")
		(net "M_G_CPU1_SA_DQ<1>")
	)
	(segment
		(start 185.913776 -314.312046)
		(end 185.753756 -314.152026)
		(width 0.18288)
		(layer "In4.Cu")
		(net "M_G_CPU1_SA_DQ<1>")
	)
	(segment
		(start 130.733546 -276.384258)
		(end 130.65506 -276.338792)
		(width 0.088646)
		(layer "In4.Cu")
		(net "M_G_CPU1_SA_DQ<1>")
	)
	(segment
		(start 160.378394 -312.384694)
		(end 159.634174 -312.384694)
		(width 0.18288)
		(layer "In4.Cu")
		(net "M_G_CPU1_SA_DQ<1>")
	)
	(segment
		(start 133.567678 -276.392894)
		(end 133.552946 -276.384258)
		(width 0.088646)
		(layer "In4.Cu")
		(net "M_G_CPU1_SA_DQ<1>")
	)
	(segment
		(start 178.191922 -316.742064)
		(end 174.313088 -316.742064)
		(width 0.18288)
		(layer "In4.Cu")
		(net "M_G_CPU1_SA_DQ<1>")
	)
	(segment
		(start 163.45662 -314.114688)
		(end 162.838638 -313.496706)
		(width 0.18288)
		(layer "In4.Cu")
		(net "M_G_CPU1_SA_DQ<1>")
	)
	(segment
		(start 132.623306 -276.390354)
		(end 132.612892 -276.384258)
		(width 0.088646)
		(layer "In4.Cu")
		(net "M_G_CPU1_SA_DQ<1>")
	)
	(segment
		(start 135.527796 -277.198074)
		(end 135.513064 -277.20671)
		(width 0.088646)
		(layer "In4.Cu")
		(net "M_G_CPU1_SA_DQ<1>")
	)
	(segment
		(start 156.603954 -310.682132)
		(end 154.214576 -308.292754)
		(width 0.18288)
		(layer "In4.Cu")
		(net "M_G_CPU1_SA_DQ<1>")
	)
	(segment
		(start 157.931612 -310.682132)
		(end 156.603954 -310.682132)
		(width 0.18288)
		(layer "In4.Cu")
		(net "M_G_CPU1_SA_DQ<1>")
	)
	(segment
		(start 136.559544 -278.336756)
		(end 136.559544 -278.336502)
		(width 0.088646)
		(layer "In4.Cu")
		(net "M_G_CPU1_SA_DQ<1>")
	)
	(segment
		(start 183.786526 -314.152026)
		(end 182.973726 -314.964826)
		(width 0.18288)
		(layer "In4.Cu")
		(net "M_G_CPU1_SA_DQ<1>")
	)
	(segment
		(start 185.913776 -314.75172)
		(end 185.913776 -314.312046)
		(width 0.18288)
		(layer "In4.Cu")
		(net "M_G_CPU1_SA_DQ<1>")
	)
	(segment
		(start 174.313088 -316.742064)
		(end 173.371256 -317.683896)
		(width 0.18288)
		(layer "In4.Cu")
		(net "M_G_CPU1_SA_DQ<1>")
	)
	(segment
		(start 178.351942 -316.00521)
		(end 178.351942 -316.582044)
		(width 0.18288)
		(layer "In4.Cu")
		(net "M_G_CPU1_SA_DQ<1>")
	)
	(segment
		(start 186.304682 -315.142626)
		(end 185.913776 -314.75172)
		(width 0.18288)
		(layer "In4.Cu")
		(net "M_G_CPU1_SA_DQ<1>")
	)
	(segment
		(start 138.607038 -279.63241)
		(end 137.85977 -278.885142)
		(width 0.088646)
		(layer "In4.Cu")
		(net "M_G_CPU1_SA_DQ<1>")
	)
	(segment
		(start 162.838638 -313.496706)
		(end 161.490406 -313.496706)
		(width 0.18288)
		(layer "In4.Cu")
		(net "M_G_CPU1_SA_DQ<1>")
	)
	(segment
		(start 164.660326 -314.355226)
		(end 164.419788 -314.114688)
		(width 0.18288)
		(layer "In4.Cu")
		(net "M_G_CPU1_SA_DQ<1>")
	)
	(segment
		(start 136.08939 -277.530052)
		(end 136.08939 -277.522432)
		(width 0.088646)
		(layer "In4.Cu")
		(net "M_G_CPU1_SA_DQ<1>")
	)
	(segment
		(start 139.43203 -279.992328)
		(end 139.072112 -279.63241)
		(width 0.088646)
		(layer "In4.Cu")
		(net "M_G_CPU1_SA_DQ<1>")
	)
	(segment
		(start 181.354984 -315.169804)
		(end 181.354984 -315.951108)
		(width 0.18288)
		(layer "In4.Cu")
		(net "M_G_CPU1_SA_DQ<1>")
	)
	(segment
		(start 169.511726 -315.803026)
		(end 168.775126 -315.803026)
		(width 0.18288)
		(layer "In4.Cu")
		(net "M_G_CPU1_SA_DQ<1>")
	)
	(segment
		(start 187.883546 -314.616592)
		(end 187.357512 -315.142626)
		(width 0.18288)
		(layer "In4.Cu")
		(net "M_G_CPU1_SA_DQ<1>")
	)
	(segment
		(start 178.630326 -315.726826)
		(end 178.351942 -316.00521)
		(width 0.18288)
		(layer "In4.Cu")
		(net "M_G_CPU1_SA_DQ<1>")
	)
	(segment
		(start 135.911082 -277.203154)
		(end 135.902192 -277.198074)
		(width 0.088646)
		(layer "In4.Cu")
		(net "M_G_CPU1_SA_DQ<1>")
	)
	(segment
		(start 139.072112 -279.63241)
		(end 138.607038 -279.63241)
		(width 0.088646)
		(layer "In4.Cu")
		(net "M_G_CPU1_SA_DQ<1>")
	)
	(segment
		(start 136.380982 -278.017224)
		(end 136.372092 -278.012144)
		(width 0.088646)
		(layer "In4.Cu")
		(net "M_G_CPU1_SA_DQ<1>")
	)
	(segment
		(start 141.596618 -284.161992)
		(end 141.596618 -283.726636)
		(width 0.18288)
		(layer "In4.Cu")
		(net "M_G_CPU1_SA_DQ<1>")
	)
	(segment
		(start 164.419788 -314.114688)
		(end 163.45662 -314.114688)
		(width 0.18288)
		(layer "In4.Cu")
		(net "M_G_CPU1_SA_DQ<1>")
	)
	(segment
		(start 179.92598 -316.196472)
		(end 179.92598 -315.90488)
		(width 0.18288)
		(layer "In4.Cu")
		(net "M_G_CPU1_SA_DQ<1>")
	)
	(segment
		(start 154.214576 -308.292754)
		(end 147.313904 -297.964098)
		(width 0.18288)
		(layer "In4.Cu")
		(net "M_G_CPU1_SA_DQ<1>")
	)
	(segment
		(start 166.493698 -314.355226)
		(end 164.660326 -314.355226)
		(width 0.18288)
		(layer "In4.Cu")
		(net "M_G_CPU1_SA_DQ<1>")
	)
	(segment
		(start 167.065198 -314.926726)
		(end 166.493698 -314.355226)
		(width 0.18288)
		(layer "In4.Cu")
		(net "M_G_CPU1_SA_DQ<1>")
	)
	(segment
		(start 131.304538 -276.380956)
		(end 131.292854 -276.38756)
		(width 0.088646)
		(layer "In4.Cu")
		(net "M_G_CPU1_SA_DQ<1>")
	)
	(segment
		(start 134.501636 -276.389338)
		(end 134.492746 -276.384258)
		(width 0.088646)
		(layer "In4.Cu")
		(net "M_G_CPU1_SA_DQ<1>")
	)
	(segment
		(start 185.753756 -314.152026)
		(end 183.786526 -314.152026)
		(width 0.18288)
		(layer "In4.Cu")
		(net "M_G_CPU1_SA_DQ<1>")
	)
	(segment
		(start 180.059838 -316.33033)
		(end 179.92598 -316.196472)
		(width 0.18288)
		(layer "In4.Cu")
		(net "M_G_CPU1_SA_DQ<1>")
	)
	(arc
		(start 134.962392 -277.198074)
		(mid 134.759569 -276.997843)
		(end 134.680198 -276.72411)
		(width 0.088646)
		(layer "In4.Cu")
		(net "M_G_CPU1_SA_DQ<1>")
	)
	(arc
		(start 132.232654 -276.38756)
		(mid 131.952549 -276.460002)
		(end 131.673346 -276.384258)
		(width 0.088646)
		(layer "In4.Cu")
		(net "M_G_CPU1_SA_DQ<1>")
	)
	(arc
		(start 136.089644 -277.522432)
		(mid 136.041965 -277.339532)
		(end 135.911082 -277.203154)
		(width 0.088646)
		(layer "In4.Cu")
		(net "M_G_CPU1_SA_DQ<1>")
	)
	(arc
		(start 133.552946 -276.384258)
		(mid 133.365748 -276.334115)
		(end 133.17855 -276.384258)
		(width 0.088646)
		(layer "In4.Cu")
		(net "M_G_CPU1_SA_DQ<1>")
	)
	(arc
		(start 137.407396 -278.82596)
		(mid 137.124694 -278.901736)
		(end 136.841992 -278.82596)
		(width 0.088646)
		(layer "In4.Cu")
		(net "M_G_CPU1_SA_DQ<1>")
	)
	(arc
		(start 135.902192 -277.198074)
		(mid 135.714994 -277.147931)
		(end 135.527796 -277.198074)
		(width 0.088646)
		(layer "In4.Cu")
		(net "M_G_CPU1_SA_DQ<1>")
	)
	(arc
		(start 134.680198 -276.708616)
		(mid 134.632519 -276.525716)
		(end 134.501636 -276.389338)
		(width 0.088646)
		(layer "In4.Cu")
		(net "M_G_CPU1_SA_DQ<1>")
	)
	(arc
		(start 136.841992 -278.82596)
		(mid 136.635232 -278.619197)
		(end 136.559544 -278.336756)
		(width 0.088646)
		(layer "In4.Cu")
		(net "M_G_CPU1_SA_DQ<1>")
	)
	(arc
		(start 134.492746 -276.384258)
		(mid 134.305548 -276.334115)
		(end 134.11835 -276.384258)
		(width 0.088646)
		(layer "In4.Cu")
		(net "M_G_CPU1_SA_DQ<1>")
	)
	(arc
		(start 137.85977 -278.885142)
		(mid 137.82272 -278.852996)
		(end 137.781792 -278.82596)
		(width 0.088646)
		(layer "In4.Cu")
		(net "M_G_CPU1_SA_DQ<1>")
	)
	(arc
		(start 131.673346 -276.384258)
		(mid 131.489392 -276.334129)
		(end 131.304538 -276.380956)
		(width 0.088646)
		(layer "In4.Cu")
		(net "M_G_CPU1_SA_DQ<1>")
	)
	(arc
		(start 130.65506 -276.338792)
		(mid 130.351252 -276.135537)
		(end 130.076194 -275.8948)
		(width 0.088646)
		(layer "In4.Cu")
		(net "M_G_CPU1_SA_DQ<1>")
	)
	(arc
		(start 136.559544 -278.336502)
		(mid 136.511865 -278.153602)
		(end 136.380982 -278.017224)
		(width 0.088646)
		(layer "In4.Cu")
		(net "M_G_CPU1_SA_DQ<1>")
	)
	(arc
		(start 137.781792 -278.82596)
		(mid 137.594594 -278.775817)
		(end 137.407396 -278.82596)
		(width 0.088646)
		(layer "In4.Cu")
		(net "M_G_CPU1_SA_DQ<1>")
	)
	(arc
		(start 133.17855 -276.384258)
		(mid 132.901737 -276.460128)
		(end 132.623306 -276.390354)
		(width 0.088646)
		(layer "In4.Cu")
		(net "M_G_CPU1_SA_DQ<1>")
	)
	(arc
		(start 134.11835 -276.384258)
		(mid 133.844151 -276.460093)
		(end 133.567678 -276.392894)
		(width 0.088646)
		(layer "In4.Cu")
		(net "M_G_CPU1_SA_DQ<1>")
	)
	(arc
		(start 136.372092 -278.012144)
		(mid 136.16702 -277.808465)
		(end 136.08939 -277.530052)
		(width 0.088646)
		(layer "In4.Cu")
		(net "M_G_CPU1_SA_DQ<1>")
	)
	(arc
		(start 132.612892 -276.384258)
		(mid 132.425694 -276.334115)
		(end 132.238496 -276.384258)
		(width 0.088646)
		(layer "In4.Cu")
		(net "M_G_CPU1_SA_DQ<1>")
	)
	(arc
		(start 135.513064 -277.20671)
		(mid 135.236589 -277.27403)
		(end 134.962392 -277.198074)
		(width 0.088646)
		(layer "In4.Cu")
		(net "M_G_CPU1_SA_DQ<1>")
	)
	(arc
		(start 131.292854 -276.38756)
		(mid 131.012749 -276.460002)
		(end 130.733546 -276.384258)
		(width 0.088646)
		(layer "In4.Cu")
		(net "M_G_CPU1_SA_DQ<1>")
	)
	(segment
		(start 195.218812 -295.498774)
		(end 195.510658 -295.498774)
		(width 0.20066)
		(layer "F.Cu")
		(net "M_G_CPU1_SA_DQ<19>")
	)
	(segment
		(start 198.223886 -295.503854)
		(end 198.427848 -295.299892)
		(width 0.20066)
		(layer "F.Cu")
		(net "M_G_CPU1_SA_DQ<19>")
	)
	(segment
		(start 131.956048 -265.592306)
		(end 131.956048 -266.127992)
		(width 0.20066)
		(layer "F.Cu")
		(net "M_G_CPU1_SA_DQ<19>")
	)
	(segment
		(start 193.088514 -295.06672)
		(end 194.786758 -295.06672)
		(width 0.20066)
		(layer "F.Cu")
		(net "M_G_CPU1_SA_DQ<19>")
	)
	(segment
		(start 195.522596 -295.491662)
		(end 197.530466 -295.491662)
		(width 0.1016)
		(layer "F.Cu")
		(net "M_G_CPU1_SA_DQ<19>")
	)
	(segment
		(start 195.515484 -295.498774)
		(end 195.522596 -295.491662)
		(width 0.1016)
		(layer "F.Cu")
		(net "M_G_CPU1_SA_DQ<19>")
	)
	(segment
		(start 197.530466 -295.491662)
		(end 197.542658 -295.503854)
		(width 0.1016)
		(layer "F.Cu")
		(net "M_G_CPU1_SA_DQ<19>")
	)
	(segment
		(start 198.427848 -295.04894)
		(end 198.662036 -294.814752)
		(width 0.20066)
		(layer "F.Cu")
		(net "M_G_CPU1_SA_DQ<19>")
	)
	(segment
		(start 191.983614 -295.06672)
		(end 193.088514 -295.06672)
		(width 0.20066)
		(layer "F.Cu")
		(net "M_G_CPU1_SA_DQ<19>")
	)
	(segment
		(start 131.956048 -266.127992)
		(end 131.955794 -266.128246)
		(width 0.20066)
		(layer "F.Cu")
		(net "M_G_CPU1_SA_DQ<19>")
	)
	(segment
		(start 199.046084 -294.814752)
		(end 199.298052 -295.06672)
		(width 0.20066)
		(layer "F.Cu")
		(net "M_G_CPU1_SA_DQ<19>")
	)
	(segment
		(start 194.786758 -295.06672)
		(end 195.218812 -295.498774)
		(width 0.20066)
		(layer "F.Cu")
		(net "M_G_CPU1_SA_DQ<19>")
	)
	(segment
		(start 197.542658 -295.503854)
		(end 198.223886 -295.503854)
		(width 0.20066)
		(layer "F.Cu")
		(net "M_G_CPU1_SA_DQ<19>")
	)
	(segment
		(start 199.298052 -295.06672)
		(end 200.632314 -295.06672)
		(width 0.20066)
		(layer "F.Cu")
		(net "M_G_CPU1_SA_DQ<19>")
	)
	(segment
		(start 198.662036 -294.814752)
		(end 199.046084 -294.814752)
		(width 0.20066)
		(layer "F.Cu")
		(net "M_G_CPU1_SA_DQ<19>")
	)
	(segment
		(start 198.427848 -295.299892)
		(end 198.427848 -295.04894)
		(width 0.20066)
		(layer "F.Cu")
		(net "M_G_CPU1_SA_DQ<19>")
	)
	(segment
		(start 195.510658 -295.498774)
		(end 195.515484 -295.498774)
		(width 0.101854)
		(layer "F.Cu")
		(net "M_G_CPU1_SA_DQ<19>")
	)
	(segment
		(start 190.102998 -296.221404)
		(end 189.775338 -296.221404)
		(width 0.18288)
		(layer "In4.Cu")
		(net "M_G_CPU1_SA_DQ<19>")
	)
	(segment
		(start 134.022846 -266.452604)
		(end 134.017004 -266.455906)
		(width 0.088646)
		(layer "In4.Cu")
		(net "M_G_CPU1_SA_DQ<19>")
	)
	(segment
		(start 144.214088 -269.536672)
		(end 143.021558 -269.042642)
		(width 0.18288)
		(layer "In4.Cu")
		(net "M_G_CPU1_SA_DQ<19>")
	)
	(segment
		(start 172.616622 -296.342308)
		(end 172.161454 -295.88714)
		(width 0.18288)
		(layer "In4.Cu")
		(net "M_G_CPU1_SA_DQ<19>")
	)
	(segment
		(start 134.028688 -266.449048)
		(end 134.022846 -266.452604)
		(width 0.088646)
		(layer "In4.Cu")
		(net "M_G_CPU1_SA_DQ<19>")
	)
	(segment
		(start 153.363168 -277.210774)
		(end 145.689066 -269.536672)
		(width 0.18288)
		(layer "In4.Cu")
		(net "M_G_CPU1_SA_DQ<19>")
	)
	(segment
		(start 189.592458 -296.038524)
		(end 189.592458 -295.675304)
		(width 0.18288)
		(layer "In4.Cu")
		(net "M_G_CPU1_SA_DQ<19>")
	)
	(segment
		(start 167.697404 -293.015162)
		(end 167.63492 -292.952678)
		(width 0.18288)
		(layer "In4.Cu")
		(net "M_G_CPU1_SA_DQ<19>")
	)
	(segment
		(start 138.665204 -266.247372)
		(end 137.98677 -266.247372)
		(width 0.088646)
		(layer "In4.Cu")
		(net "M_G_CPU1_SA_DQ<19>")
	)
	(segment
		(start 140.141706 -266.247372)
		(end 138.665204 -266.247372)
		(width 0.18288)
		(layer "In4.Cu")
		(net "M_G_CPU1_SA_DQ<19>")
	)
	(segment
		(start 179.747926 -294.86479)
		(end 178.630326 -294.86479)
		(width 0.18288)
		(layer "In4.Cu")
		(net "M_G_CPU1_SA_DQ<19>")
	)
	(segment
		(start 189.775338 -296.221404)
		(end 189.592458 -296.038524)
		(width 0.18288)
		(layer "In4.Cu")
		(net "M_G_CPU1_SA_DQ<19>")
	)
	(segment
		(start 168.724326 -293.015162)
		(end 167.697404 -293.015162)
		(width 0.18288)
		(layer "In4.Cu")
		(net "M_G_CPU1_SA_DQ<19>")
	)
	(segment
		(start 171.189904 -295.48074)
		(end 168.724326 -293.015162)
		(width 0.18288)
		(layer "In4.Cu")
		(net "M_G_CPU1_SA_DQ<19>")
	)
	(segment
		(start 173.23943 -296.342308)
		(end 172.616622 -296.342308)
		(width 0.18288)
		(layer "In4.Cu")
		(net "M_G_CPU1_SA_DQ<19>")
	)
	(segment
		(start 162.647122 -288.402522)
		(end 160.93694 -286.69234)
		(width 0.18288)
		(layer "In4.Cu")
		(net "M_G_CPU1_SA_DQ<19>")
	)
	(segment
		(start 143.021558 -269.042642)
		(end 142.877032 -268.982698)
		(width 0.18288)
		(layer "In4.Cu")
		(net "M_G_CPU1_SA_DQ<19>")
	)
	(segment
		(start 132.708396 -266.452604)
		(end 132.504688 -266.335002)
		(width 0.088646)
		(layer "In4.Cu")
		(net "M_G_CPU1_SA_DQ<19>")
	)
	(segment
		(start 165.016942 -291.252402)
		(end 164.761926 -290.997386)
		(width 0.18288)
		(layer "In4.Cu")
		(net "M_G_CPU1_SA_DQ<19>")
	)
	(segment
		(start 160.93694 -286.69234)
		(end 160.244282 -286.69234)
		(width 0.18288)
		(layer "In4.Cu")
		(net "M_G_CPU1_SA_DQ<19>")
	)
	(segment
		(start 178.001676 -295.49344)
		(end 176.617122 -295.49344)
		(width 0.18288)
		(layer "In4.Cu")
		(net "M_G_CPU1_SA_DQ<19>")
	)
	(segment
		(start 171.891452 -295.575736)
		(end 171.661836 -295.48074)
		(width 0.18288)
		(layer "In4.Cu")
		(net "M_G_CPU1_SA_DQ<19>")
	)
	(segment
		(start 172.161454 -295.845738)
		(end 171.891452 -295.575736)
		(width 0.18288)
		(layer "In4.Cu")
		(net "M_G_CPU1_SA_DQ<19>")
	)
	(segment
		(start 142.877032 -268.982698)
		(end 140.141706 -266.247372)
		(width 0.18288)
		(layer "In4.Cu")
		(net "M_G_CPU1_SA_DQ<19>")
	)
	(segment
		(start 189.409578 -295.492424)
		(end 187.644532 -295.492424)
		(width 0.18288)
		(layer "In4.Cu")
		(net "M_G_CPU1_SA_DQ<19>")
	)
	(segment
		(start 137.98677 -266.247372)
		(end 137.781792 -266.45235)
		(width 0.088646)
		(layer "In4.Cu")
		(net "M_G_CPU1_SA_DQ<19>")
	)
	(segment
		(start 190.285878 -296.038524)
		(end 190.102998 -296.221404)
		(width 0.18288)
		(layer "In4.Cu")
		(net "M_G_CPU1_SA_DQ<19>")
	)
	(segment
		(start 165.565582 -291.252402)
		(end 165.016942 -291.252402)
		(width 0.18288)
		(layer "In4.Cu")
		(net "M_G_CPU1_SA_DQ<19>")
	)
	(segment
		(start 132.504688 -266.335002)
		(end 132.098542 -266.166346)
		(width 0.088646)
		(layer "In4.Cu")
		(net "M_G_CPU1_SA_DQ<19>")
	)
	(segment
		(start 134.966456 -266.450318)
		(end 134.962646 -266.452604)
		(width 0.088646)
		(layer "In4.Cu")
		(net "M_G_CPU1_SA_DQ<19>")
	)
	(segment
		(start 145.689066 -269.536672)
		(end 144.214088 -269.536672)
		(width 0.18288)
		(layer "In4.Cu")
		(net "M_G_CPU1_SA_DQ<19>")
	)
	(segment
		(start 191.55791 -295.492424)
		(end 190.468758 -295.492424)
		(width 0.18288)
		(layer "In4.Cu")
		(net "M_G_CPU1_SA_DQ<19>")
	)
	(segment
		(start 157.211776 -284.662626)
		(end 156.158946 -283.959046)
		(width 0.18288)
		(layer "In4.Cu")
		(net "M_G_CPU1_SA_DQ<19>")
	)
	(segment
		(start 187.644532 -295.492424)
		(end 186.915298 -294.76319)
		(width 0.18288)
		(layer "In4.Cu")
		(net "M_G_CPU1_SA_DQ<19>")
	)
	(segment
		(start 163.48837 -289.522662)
		(end 162.647122 -288.681414)
		(width 0.18288)
		(layer "In4.Cu")
		(net "M_G_CPU1_SA_DQ<19>")
	)
	(segment
		(start 135.902192 -266.45235)
		(end 135.902446 -266.452604)
		(width 0.088646)
		(layer "In4.Cu")
		(net "M_G_CPU1_SA_DQ<19>")
	)
	(segment
		(start 160.244282 -286.69234)
		(end 158.214568 -284.662626)
		(width 0.18288)
		(layer "In4.Cu")
		(net "M_G_CPU1_SA_DQ<19>")
	)
	(segment
		(start 191.983614 -295.06672)
		(end 191.55791 -295.492424)
		(width 0.18288)
		(layer "In4.Cu")
		(net "M_G_CPU1_SA_DQ<19>")
	)
	(segment
		(start 176.617122 -295.49344)
		(end 176.509172 -295.60139)
		(width 0.18288)
		(layer "In4.Cu")
		(net "M_G_CPU1_SA_DQ<19>")
	)
	(segment
		(start 186.915298 -294.76319)
		(end 183.735726 -294.76319)
		(width 0.18288)
		(layer "In4.Cu")
		(net "M_G_CPU1_SA_DQ<19>")
	)
	(segment
		(start 162.647122 -288.681414)
		(end 162.647122 -288.402522)
		(width 0.18288)
		(layer "In4.Cu")
		(net "M_G_CPU1_SA_DQ<19>")
	)
	(segment
		(start 183.342026 -294.36949)
		(end 180.243226 -294.36949)
		(width 0.18288)
		(layer "In4.Cu")
		(net "M_G_CPU1_SA_DQ<19>")
	)
	(segment
		(start 167.63492 -292.952678)
		(end 167.265858 -292.952678)
		(width 0.18288)
		(layer "In4.Cu")
		(net "M_G_CPU1_SA_DQ<19>")
	)
	(segment
		(start 164.406834 -290.479734)
		(end 163.83889 -290.479734)
		(width 0.18288)
		(layer "In4.Cu")
		(net "M_G_CPU1_SA_DQ<19>")
	)
	(segment
		(start 156.158946 -283.959046)
		(end 153.363168 -277.210774)
		(width 0.18288)
		(layer "In4.Cu")
		(net "M_G_CPU1_SA_DQ<19>")
	)
	(segment
		(start 176.509172 -295.60139)
		(end 173.980348 -295.60139)
		(width 0.18288)
		(layer "In4.Cu")
		(net "M_G_CPU1_SA_DQ<19>")
	)
	(segment
		(start 134.962646 -266.452604)
		(end 134.956804 -266.455906)
		(width 0.088646)
		(layer "In4.Cu")
		(net "M_G_CPU1_SA_DQ<19>")
	)
	(segment
		(start 164.761926 -290.997386)
		(end 164.761926 -290.834826)
		(width 0.18288)
		(layer "In4.Cu")
		(net "M_G_CPU1_SA_DQ<19>")
	)
	(segment
		(start 167.265858 -292.952678)
		(end 165.565582 -291.252402)
		(width 0.18288)
		(layer "In4.Cu")
		(net "M_G_CPU1_SA_DQ<19>")
	)
	(segment
		(start 133.088888 -266.449048)
		(end 133.083046 -266.452604)
		(width 0.088646)
		(layer "In4.Cu")
		(net "M_G_CPU1_SA_DQ<19>")
	)
	(segment
		(start 158.214568 -284.662626)
		(end 157.211776 -284.662626)
		(width 0.18288)
		(layer "In4.Cu")
		(net "M_G_CPU1_SA_DQ<19>")
	)
	(segment
		(start 133.083046 -266.452604)
		(end 133.077204 -266.455906)
		(width 0.088646)
		(layer "In4.Cu")
		(net "M_G_CPU1_SA_DQ<19>")
	)
	(segment
		(start 189.592458 -295.675304)
		(end 189.409578 -295.492424)
		(width 0.18288)
		(layer "In4.Cu")
		(net "M_G_CPU1_SA_DQ<19>")
	)
	(segment
		(start 180.243226 -294.36949)
		(end 179.747926 -294.86479)
		(width 0.18288)
		(layer "In4.Cu")
		(net "M_G_CPU1_SA_DQ<19>")
	)
	(segment
		(start 163.48837 -290.129214)
		(end 163.48837 -289.522662)
		(width 0.18288)
		(layer "In4.Cu")
		(net "M_G_CPU1_SA_DQ<19>")
	)
	(segment
		(start 178.630326 -294.86479)
		(end 178.001676 -295.49344)
		(width 0.18288)
		(layer "In4.Cu")
		(net "M_G_CPU1_SA_DQ<19>")
	)
	(segment
		(start 190.468758 -295.492424)
		(end 190.285878 -295.675304)
		(width 0.18288)
		(layer "In4.Cu")
		(net "M_G_CPU1_SA_DQ<19>")
	)
	(segment
		(start 173.980348 -295.60139)
		(end 173.23943 -296.342308)
		(width 0.18288)
		(layer "In4.Cu")
		(net "M_G_CPU1_SA_DQ<19>")
	)
	(segment
		(start 164.761926 -290.834826)
		(end 164.406834 -290.479734)
		(width 0.18288)
		(layer "In4.Cu")
		(net "M_G_CPU1_SA_DQ<19>")
	)
	(segment
		(start 172.161454 -295.88714)
		(end 172.161454 -295.845738)
		(width 0.18288)
		(layer "In4.Cu")
		(net "M_G_CPU1_SA_DQ<19>")
	)
	(segment
		(start 183.735726 -294.76319)
		(end 183.342026 -294.36949)
		(width 0.18288)
		(layer "In4.Cu")
		(net "M_G_CPU1_SA_DQ<19>")
	)
	(segment
		(start 132.098542 -266.166346)
		(end 131.955794 -266.128246)
		(width 0.088646)
		(layer "In4.Cu")
		(net "M_G_CPU1_SA_DQ<19>")
	)
	(segment
		(start 190.285878 -295.675304)
		(end 190.285878 -296.038524)
		(width 0.18288)
		(layer "In4.Cu")
		(net "M_G_CPU1_SA_DQ<19>")
	)
	(segment
		(start 171.661836 -295.48074)
		(end 171.189904 -295.48074)
		(width 0.18288)
		(layer "In4.Cu")
		(net "M_G_CPU1_SA_DQ<19>")
	)
	(segment
		(start 163.83889 -290.479734)
		(end 163.48837 -290.129214)
		(width 0.18288)
		(layer "In4.Cu")
		(net "M_G_CPU1_SA_DQ<19>")
	)
	(arc
		(start 136.841992 -266.45235)
		(mid 136.654794 -266.502527)
		(end 136.467596 -266.45235)
		(width 0.088646)
		(layer "In4.Cu")
		(net "M_G_CPU1_SA_DQ<19>")
	)
	(arc
		(start 133.077204 -266.455906)
		(mid 132.892349 -266.502856)
		(end 132.708396 -266.452604)
		(width 0.088646)
		(layer "In4.Cu")
		(net "M_G_CPU1_SA_DQ<19>")
	)
	(arc
		(start 137.781792 -266.45235)
		(mid 137.594594 -266.502527)
		(end 137.407396 -266.45235)
		(width 0.088646)
		(layer "In4.Cu")
		(net "M_G_CPU1_SA_DQ<19>")
	)
	(arc
		(start 133.648196 -266.452604)
		(mid 133.369022 -266.376805)
		(end 133.088888 -266.449048)
		(width 0.088646)
		(layer "In4.Cu")
		(net "M_G_CPU1_SA_DQ<19>")
	)
	(arc
		(start 134.956804 -266.455906)
		(mid 134.771949 -266.502856)
		(end 134.587996 -266.452604)
		(width 0.088646)
		(layer "In4.Cu")
		(net "M_G_CPU1_SA_DQ<19>")
	)
	(arc
		(start 135.527796 -266.452604)
		(mid 135.247425 -266.376799)
		(end 134.966456 -266.450318)
		(width 0.088646)
		(layer "In4.Cu")
		(net "M_G_CPU1_SA_DQ<19>")
	)
	(arc
		(start 137.407396 -266.45235)
		(mid 137.124694 -266.376574)
		(end 136.841992 -266.45235)
		(width 0.088646)
		(layer "In4.Cu")
		(net "M_G_CPU1_SA_DQ<19>")
	)
	(arc
		(start 136.467596 -266.45235)
		(mid 136.184894 -266.376574)
		(end 135.902192 -266.45235)
		(width 0.088646)
		(layer "In4.Cu")
		(net "M_G_CPU1_SA_DQ<19>")
	)
	(arc
		(start 134.017004 -266.455906)
		(mid 133.832149 -266.502856)
		(end 133.648196 -266.452604)
		(width 0.088646)
		(layer "In4.Cu")
		(net "M_G_CPU1_SA_DQ<19>")
	)
	(arc
		(start 134.587996 -266.452604)
		(mid 134.308822 -266.376805)
		(end 134.028688 -266.449048)
		(width 0.088646)
		(layer "In4.Cu")
		(net "M_G_CPU1_SA_DQ<19>")
	)
	(arc
		(start 135.902446 -266.452604)
		(mid 135.715138 -266.502713)
		(end 135.527796 -266.452604)
		(width 0.088646)
		(layer "In4.Cu")
		(net "M_G_CPU1_SA_DQ<19>")
	)
	(segment
		(start 198.223886 -297.203876)
		(end 198.427848 -296.999914)
		(width 0.20066)
		(layer "F.Cu")
		(net "M_G_CPU1_SA_DQ<18>")
	)
	(segment
		(start 191.983614 -296.766742)
		(end 193.088514 -296.766742)
		(width 0.20066)
		(layer "F.Cu")
		(net "M_G_CPU1_SA_DQ<18>")
	)
	(segment
		(start 195.510658 -297.198796)
		(end 195.515484 -297.198796)
		(width 0.101854)
		(layer "F.Cu")
		(net "M_G_CPU1_SA_DQ<18>")
	)
	(segment
		(start 193.088514 -296.766742)
		(end 194.786758 -296.766742)
		(width 0.20066)
		(layer "F.Cu")
		(net "M_G_CPU1_SA_DQ<18>")
	)
	(segment
		(start 131.485894 -266.405868)
		(end 131.485894 -266.941554)
		(width 0.20066)
		(layer "F.Cu")
		(net "M_G_CPU1_SA_DQ<18>")
	)
	(segment
		(start 198.427848 -296.999914)
		(end 198.427848 -296.748962)
		(width 0.20066)
		(layer "F.Cu")
		(net "M_G_CPU1_SA_DQ<18>")
	)
	(segment
		(start 195.522596 -297.191684)
		(end 197.530466 -297.191684)
		(width 0.1016)
		(layer "F.Cu")
		(net "M_G_CPU1_SA_DQ<18>")
	)
	(segment
		(start 198.662036 -296.514774)
		(end 199.046084 -296.514774)
		(width 0.20066)
		(layer "F.Cu")
		(net "M_G_CPU1_SA_DQ<18>")
	)
	(segment
		(start 195.218812 -297.198796)
		(end 195.510658 -297.198796)
		(width 0.20066)
		(layer "F.Cu")
		(net "M_G_CPU1_SA_DQ<18>")
	)
	(segment
		(start 195.515484 -297.198796)
		(end 195.522596 -297.191684)
		(width 0.1016)
		(layer "F.Cu")
		(net "M_G_CPU1_SA_DQ<18>")
	)
	(segment
		(start 197.542658 -297.203876)
		(end 198.223886 -297.203876)
		(width 0.20066)
		(layer "F.Cu")
		(net "M_G_CPU1_SA_DQ<18>")
	)
	(segment
		(start 131.485894 -266.941554)
		(end 131.486148 -266.941808)
		(width 0.20066)
		(layer "F.Cu")
		(net "M_G_CPU1_SA_DQ<18>")
	)
	(segment
		(start 198.427848 -296.748962)
		(end 198.662036 -296.514774)
		(width 0.20066)
		(layer "F.Cu")
		(net "M_G_CPU1_SA_DQ<18>")
	)
	(segment
		(start 197.530466 -297.191684)
		(end 197.542658 -297.203876)
		(width 0.1016)
		(layer "F.Cu")
		(net "M_G_CPU1_SA_DQ<18>")
	)
	(segment
		(start 199.046084 -296.514774)
		(end 199.298052 -296.766742)
		(width 0.20066)
		(layer "F.Cu")
		(net "M_G_CPU1_SA_DQ<18>")
	)
	(segment
		(start 194.786758 -296.766742)
		(end 195.218812 -297.198796)
		(width 0.20066)
		(layer "F.Cu")
		(net "M_G_CPU1_SA_DQ<18>")
	)
	(segment
		(start 199.298052 -296.766742)
		(end 200.632314 -296.766742)
		(width 0.20066)
		(layer "F.Cu")
		(net "M_G_CPU1_SA_DQ<18>")
	)
	(segment
		(start 136.000236 -267.267944)
		(end 135.997696 -267.26642)
		(width 0.088646)
		(layer "In4.Cu")
		(net "M_G_CPU1_SA_DQ<18>")
	)
	(segment
		(start 187.362846 -297.19143)
		(end 186.405266 -297.04919)
		(width 0.18288)
		(layer "In4.Cu")
		(net "M_G_CPU1_SA_DQ<18>")
	)
	(segment
		(start 131.115816 -266.999212)
		(end 131.17322 -266.941808)
		(width 0.088646)
		(layer "In4.Cu")
		(net "M_G_CPU1_SA_DQ<18>")
	)
	(segment
		(start 190.950596 -297.19143)
		(end 187.362846 -297.19143)
		(width 0.18288)
		(layer "In4.Cu")
		(net "M_G_CPU1_SA_DQ<18>")
	)
	(segment
		(start 167.9067 -294.592502)
		(end 167.166544 -294.174672)
		(width 0.18288)
		(layer "In4.Cu")
		(net "M_G_CPU1_SA_DQ<18>")
	)
	(segment
		(start 179.877212 -296.33164)
		(end 178.589686 -296.972482)
		(width 0.18288)
		(layer "In4.Cu")
		(net "M_G_CPU1_SA_DQ<18>")
	)
	(segment
		(start 173.983396 -297.192446)
		(end 173.137576 -298.038266)
		(width 0.18288)
		(layer "In4.Cu")
		(net "M_G_CPU1_SA_DQ<18>")
	)
	(segment
		(start 152.517856 -277.773638)
		(end 145.35404 -270.609822)
		(width 0.18288)
		(layer "In4.Cu")
		(net "M_G_CPU1_SA_DQ<18>")
	)
	(segment
		(start 133.182868 -267.26896)
		(end 133.178296 -267.26642)
		(width 0.088646)
		(layer "In4.Cu")
		(net "M_G_CPU1_SA_DQ<18>")
	)
	(segment
		(start 157.551628 -286.50438)
		(end 156.73832 -285.691072)
		(width 0.18288)
		(layer "In4.Cu")
		(net "M_G_CPU1_SA_DQ<18>")
	)
	(segment
		(start 171.262802 -297.057064)
		(end 169.95394 -295.748202)
		(width 0.18288)
		(layer "In4.Cu")
		(net "M_G_CPU1_SA_DQ<18>")
	)
	(segment
		(start 172.15104 -297.556936)
		(end 171.651168 -297.057064)
		(width 0.18288)
		(layer "In4.Cu")
		(net "M_G_CPU1_SA_DQ<18>")
	)
	(segment
		(start 145.35404 -270.609822)
		(end 144.179798 -270.609822)
		(width 0.18288)
		(layer "In4.Cu")
		(net "M_G_CPU1_SA_DQ<18>")
	)
	(segment
		(start 143.021558 -270.129762)
		(end 139.822682 -266.930886)
		(width 0.18288)
		(layer "In4.Cu")
		(net "M_G_CPU1_SA_DQ<18>")
	)
	(segment
		(start 136.372092 -267.266166)
		(end 136.372346 -267.26642)
		(width 0.088646)
		(layer "In4.Cu")
		(net "M_G_CPU1_SA_DQ<18>")
	)
	(segment
		(start 138.665204 -266.930886)
		(end 138.069574 -266.930886)
		(width 0.088646)
		(layer "In4.Cu")
		(net "M_G_CPU1_SA_DQ<18>")
	)
	(segment
		(start 158.690056 -287.019238)
		(end 158.175198 -286.50438)
		(width 0.18288)
		(layer "In4.Cu")
		(net "M_G_CPU1_SA_DQ<18>")
	)
	(segment
		(start 144.179798 -270.609822)
		(end 143.021558 -270.129762)
		(width 0.18288)
		(layer "In4.Cu")
		(net "M_G_CPU1_SA_DQ<18>")
	)
	(segment
		(start 159.35325 -288.593276)
		(end 158.690056 -287.930082)
		(width 0.18288)
		(layer "In4.Cu")
		(net "M_G_CPU1_SA_DQ<18>")
	)
	(segment
		(start 160.136586 -288.593276)
		(end 159.35325 -288.593276)
		(width 0.18288)
		(layer "In4.Cu")
		(net "M_G_CPU1_SA_DQ<18>")
	)
	(segment
		(start 172.502576 -298.038266)
		(end 172.15104 -297.68673)
		(width 0.18288)
		(layer "In4.Cu")
		(net "M_G_CPU1_SA_DQ<18>")
	)
	(segment
		(start 158.690056 -287.930082)
		(end 158.690056 -287.019238)
		(width 0.18288)
		(layer "In4.Cu")
		(net "M_G_CPU1_SA_DQ<18>")
	)
	(segment
		(start 131.303268 -267.26896)
		(end 131.298696 -267.26642)
		(width 0.088646)
		(layer "In4.Cu")
		(net "M_G_CPU1_SA_DQ<18>")
	)
	(segment
		(start 168.64457 -295.330372)
		(end 167.9067 -294.592502)
		(width 0.18288)
		(layer "In4.Cu")
		(net "M_G_CPU1_SA_DQ<18>")
	)
	(segment
		(start 133.178296 -267.26642)
		(end 133.17093 -267.262102)
		(width 0.088646)
		(layer "In4.Cu")
		(net "M_G_CPU1_SA_DQ<18>")
	)
	(segment
		(start 158.175198 -286.50438)
		(end 157.551628 -286.50438)
		(width 0.18288)
		(layer "In4.Cu")
		(net "M_G_CPU1_SA_DQ<18>")
	)
	(segment
		(start 139.822682 -266.930886)
		(end 138.665204 -266.930886)
		(width 0.18288)
		(layer "In4.Cu")
		(net "M_G_CPU1_SA_DQ<18>")
	)
	(segment
		(start 162.111436 -290.419536)
		(end 161.585656 -290.419536)
		(width 0.18288)
		(layer "In4.Cu")
		(net "M_G_CPU1_SA_DQ<18>")
	)
	(segment
		(start 135.061706 -267.268452)
		(end 135.057896 -267.26642)
		(width 0.088646)
		(layer "In4.Cu")
		(net "M_G_CPU1_SA_DQ<18>")
	)
	(segment
		(start 186.405266 -297.04919)
		(end 184.15889 -296.653966)
		(width 0.18288)
		(layer "In4.Cu")
		(net "M_G_CPU1_SA_DQ<18>")
	)
	(segment
		(start 171.651168 -297.057064)
		(end 171.262802 -297.057064)
		(width 0.18288)
		(layer "In4.Cu")
		(net "M_G_CPU1_SA_DQ<18>")
	)
	(segment
		(start 161.006536 -289.840416)
		(end 161.006536 -289.463226)
		(width 0.18288)
		(layer "In4.Cu")
		(net "M_G_CPU1_SA_DQ<18>")
	)
	(segment
		(start 169.95394 -295.748202)
		(end 169.213784 -295.330372)
		(width 0.18288)
		(layer "In4.Cu")
		(net "M_G_CPU1_SA_DQ<18>")
	)
	(segment
		(start 156.73832 -285.691072)
		(end 155.437332 -284.82163)
		(width 0.18288)
		(layer "In4.Cu")
		(net "M_G_CPU1_SA_DQ<18>")
	)
	(segment
		(start 166.92753 -294.028622)
		(end 165.867334 -292.968426)
		(width 0.18288)
		(layer "In4.Cu")
		(net "M_G_CPU1_SA_DQ<18>")
	)
	(segment
		(start 135.057896 -267.26642)
		(end 135.05053 -267.262102)
		(width 0.088646)
		(layer "In4.Cu")
		(net "M_G_CPU1_SA_DQ<18>")
	)
	(segment
		(start 137.981182 -267.019278)
		(end 137.539222 -267.019278)
		(width 0.088646)
		(layer "In4.Cu")
		(net "M_G_CPU1_SA_DQ<18>")
	)
	(segment
		(start 191.983614 -296.766742)
		(end 190.950596 -297.19143)
		(width 0.18288)
		(layer "In4.Cu")
		(net "M_G_CPU1_SA_DQ<18>")
	)
	(segment
		(start 138.069574 -266.930886)
		(end 137.981182 -267.019278)
		(width 0.088646)
		(layer "In4.Cu")
		(net "M_G_CPU1_SA_DQ<18>")
	)
	(segment
		(start 184.15889 -296.653966)
		(end 182.908956 -296.33164)
		(width 0.18288)
		(layer "In4.Cu")
		(net "M_G_CPU1_SA_DQ<18>")
	)
	(segment
		(start 167.166544 -294.174672)
		(end 166.92753 -294.028622)
		(width 0.18288)
		(layer "In4.Cu")
		(net "M_G_CPU1_SA_DQ<18>")
	)
	(segment
		(start 177.299366 -297.192446)
		(end 173.983396 -297.192446)
		(width 0.18288)
		(layer "In4.Cu")
		(net "M_G_CPU1_SA_DQ<18>")
	)
	(segment
		(start 134.118096 -267.26642)
		(end 134.11073 -267.262102)
		(width 0.088646)
		(layer "In4.Cu")
		(net "M_G_CPU1_SA_DQ<18>")
	)
	(segment
		(start 161.006536 -289.463226)
		(end 160.136586 -288.593276)
		(width 0.18288)
		(layer "In4.Cu")
		(net "M_G_CPU1_SA_DQ<18>")
	)
	(segment
		(start 161.585656 -290.419536)
		(end 161.006536 -289.840416)
		(width 0.18288)
		(layer "In4.Cu")
		(net "M_G_CPU1_SA_DQ<18>")
	)
	(segment
		(start 155.437332 -284.82163)
		(end 152.517856 -277.773638)
		(width 0.18288)
		(layer "In4.Cu")
		(net "M_G_CPU1_SA_DQ<18>")
	)
	(segment
		(start 173.137576 -298.038266)
		(end 172.502576 -298.038266)
		(width 0.18288)
		(layer "In4.Cu")
		(net "M_G_CPU1_SA_DQ<18>")
	)
	(segment
		(start 134.122668 -267.26896)
		(end 134.118096 -267.26642)
		(width 0.088646)
		(layer "In4.Cu")
		(net "M_G_CPU1_SA_DQ<18>")
	)
	(segment
		(start 132.238496 -267.26642)
		(end 132.23113 -267.262102)
		(width 0.088646)
		(layer "In4.Cu")
		(net "M_G_CPU1_SA_DQ<18>")
	)
	(segment
		(start 165.867334 -292.968426)
		(end 164.660326 -292.968426)
		(width 0.18288)
		(layer "In4.Cu")
		(net "M_G_CPU1_SA_DQ<18>")
	)
	(segment
		(start 164.660326 -292.968426)
		(end 162.111436 -290.419536)
		(width 0.18288)
		(layer "In4.Cu")
		(net "M_G_CPU1_SA_DQ<18>")
	)
	(segment
		(start 178.589686 -296.972482)
		(end 177.299366 -297.192446)
		(width 0.18288)
		(layer "In4.Cu")
		(net "M_G_CPU1_SA_DQ<18>")
	)
	(segment
		(start 182.908956 -296.33164)
		(end 179.877212 -296.33164)
		(width 0.18288)
		(layer "In4.Cu")
		(net "M_G_CPU1_SA_DQ<18>")
	)
	(segment
		(start 137.539222 -267.019278)
		(end 137.272268 -267.286232)
		(width 0.088646)
		(layer "In4.Cu")
		(net "M_G_CPU1_SA_DQ<18>")
	)
	(segment
		(start 169.213784 -295.330372)
		(end 168.64457 -295.330372)
		(width 0.18288)
		(layer "In4.Cu")
		(net "M_G_CPU1_SA_DQ<18>")
	)
	(segment
		(start 131.17322 -266.941808)
		(end 131.486148 -266.941808)
		(width 0.088646)
		(layer "In4.Cu")
		(net "M_G_CPU1_SA_DQ<18>")
	)
	(segment
		(start 131.298696 -267.26642)
		(end 131.29514 -267.264388)
		(width 0.088646)
		(layer "In4.Cu")
		(net "M_G_CPU1_SA_DQ<18>")
	)
	(segment
		(start 172.15104 -297.68673)
		(end 172.15104 -297.556936)
		(width 0.18288)
		(layer "In4.Cu")
		(net "M_G_CPU1_SA_DQ<18>")
	)
	(segment
		(start 132.243068 -267.26896)
		(end 132.238496 -267.26642)
		(width 0.088646)
		(layer "In4.Cu")
		(net "M_G_CPU1_SA_DQ<18>")
	)
	(arc
		(start 132.23113 -267.262102)
		(mid 131.951669 -267.190665)
		(end 131.673346 -267.26642)
		(width 0.088646)
		(layer "In4.Cu")
		(net "M_G_CPU1_SA_DQ<18>")
	)
	(arc
		(start 132.613146 -267.26642)
		(mid 132.428452 -267.316521)
		(end 132.243068 -267.26896)
		(width 0.088646)
		(layer "In4.Cu")
		(net "M_G_CPU1_SA_DQ<18>")
	)
	(arc
		(start 136.372346 -267.26642)
		(mid 136.186485 -267.316653)
		(end 136.000236 -267.267944)
		(width 0.088646)
		(layer "In4.Cu")
		(net "M_G_CPU1_SA_DQ<18>")
	)
	(arc
		(start 133.552946 -267.26642)
		(mid 133.368252 -267.316521)
		(end 133.182868 -267.26896)
		(width 0.088646)
		(layer "In4.Cu")
		(net "M_G_CPU1_SA_DQ<18>")
	)
	(arc
		(start 135.997696 -267.26642)
		(mid 135.715138 -267.190771)
		(end 135.432546 -267.26642)
		(width 0.088646)
		(layer "In4.Cu")
		(net "M_G_CPU1_SA_DQ<18>")
	)
	(arc
		(start 137.272268 -267.286232)
		(mid 137.102514 -267.315744)
		(end 136.937496 -267.266166)
		(width 0.088646)
		(layer "In4.Cu")
		(net "M_G_CPU1_SA_DQ<18>")
	)
	(arc
		(start 135.05053 -267.262102)
		(mid 134.771069 -267.190665)
		(end 134.492746 -267.26642)
		(width 0.088646)
		(layer "In4.Cu")
		(net "M_G_CPU1_SA_DQ<18>")
	)
	(arc
		(start 133.17093 -267.262102)
		(mid 132.891469 -267.190665)
		(end 132.613146 -267.26642)
		(width 0.088646)
		(layer "In4.Cu")
		(net "M_G_CPU1_SA_DQ<18>")
	)
	(arc
		(start 134.11073 -267.262102)
		(mid 133.831269 -267.190665)
		(end 133.552946 -267.26642)
		(width 0.088646)
		(layer "In4.Cu")
		(net "M_G_CPU1_SA_DQ<18>")
	)
	(arc
		(start 135.432546 -267.26642)
		(mid 135.247396 -267.316524)
		(end 135.061706 -267.268452)
		(width 0.088646)
		(layer "In4.Cu")
		(net "M_G_CPU1_SA_DQ<18>")
	)
	(arc
		(start 131.673346 -267.26642)
		(mid 131.488652 -267.316521)
		(end 131.303268 -267.26896)
		(width 0.088646)
		(layer "In4.Cu")
		(net "M_G_CPU1_SA_DQ<18>")
	)
	(arc
		(start 131.29514 -267.264388)
		(mid 131.175755 -267.151906)
		(end 131.115816 -266.999212)
		(width 0.088646)
		(layer "In4.Cu")
		(net "M_G_CPU1_SA_DQ<18>")
	)
	(arc
		(start 134.492746 -267.26642)
		(mid 134.308052 -267.316521)
		(end 134.122668 -267.26896)
		(width 0.088646)
		(layer "In4.Cu")
		(net "M_G_CPU1_SA_DQ<18>")
	)
	(arc
		(start 136.937496 -267.266166)
		(mid 136.654794 -267.190424)
		(end 136.372092 -267.266166)
		(width 0.088646)
		(layer "In4.Cu")
		(net "M_G_CPU1_SA_DQ<18>")
	)
	(segment
		(start 191.539114 -295.491662)
		(end 191.421004 -295.609772)
		(width 0.20066)
		(layer "F.Cu")
		(net "M_G_CPU1_SA_DQ<17>")
	)
	(segment
		(start 191.903858 -295.491662)
		(end 191.883792 -295.491662)
		(width 0.101854)
		(layer "F.Cu")
		(net "M_G_CPU1_SA_DQ<17>")
	)
	(segment
		(start 130.076448 -266.127992)
		(end 130.076194 -266.128246)
		(width 0.20066)
		(layer "F.Cu")
		(net "M_G_CPU1_SA_DQ<17>")
	)
	(segment
		(start 196.531992 -295.916858)
		(end 194.940428 -295.916858)
		(width 0.20066)
		(layer "F.Cu")
		(net "M_G_CPU1_SA_DQ<17>")
	)
	(segment
		(start 190.509144 -295.916604)
		(end 188.988446 -295.916604)
		(width 0.20066)
		(layer "F.Cu")
		(net "M_G_CPU1_SA_DQ<17>")
	)
	(segment
		(start 194.940428 -295.916858)
		(end 194.508882 -295.485312)
		(width 0.20066)
		(layer "F.Cu")
		(net "M_G_CPU1_SA_DQ<17>")
	)
	(segment
		(start 130.076448 -265.592306)
		(end 130.076448 -266.127992)
		(width 0.20066)
		(layer "F.Cu")
		(net "M_G_CPU1_SA_DQ<17>")
	)
	(segment
		(start 190.75781 -296.16527)
		(end 190.509144 -295.916604)
		(width 0.20066)
		(layer "F.Cu")
		(net "M_G_CPU1_SA_DQ<17>")
	)
	(segment
		(start 194.092576 -295.491662)
		(end 191.903858 -295.491662)
		(width 0.1016)
		(layer "F.Cu")
		(net "M_G_CPU1_SA_DQ<17>")
	)
	(segment
		(start 188.988446 -295.916604)
		(end 187.883546 -295.916604)
		(width 0.20066)
		(layer "F.Cu")
		(net "M_G_CPU1_SA_DQ<17>")
	)
	(segment
		(start 194.098926 -295.485312)
		(end 194.092576 -295.491662)
		(width 0.1016)
		(layer "F.Cu")
		(net "M_G_CPU1_SA_DQ<17>")
	)
	(segment
		(start 191.233044 -296.16527)
		(end 190.75781 -296.16527)
		(width 0.20066)
		(layer "F.Cu")
		(net "M_G_CPU1_SA_DQ<17>")
	)
	(segment
		(start 196.532246 -295.916604)
		(end 196.531992 -295.916858)
		(width 0.20066)
		(layer "F.Cu")
		(net "M_G_CPU1_SA_DQ<17>")
	)
	(segment
		(start 191.883792 -295.491662)
		(end 191.539114 -295.491662)
		(width 0.20066)
		(layer "F.Cu")
		(net "M_G_CPU1_SA_DQ<17>")
	)
	(segment
		(start 194.508882 -295.485312)
		(end 194.098926 -295.485312)
		(width 0.20066)
		(layer "F.Cu")
		(net "M_G_CPU1_SA_DQ<17>")
	)
	(segment
		(start 191.421004 -295.609772)
		(end 191.421004 -295.97731)
		(width 0.20066)
		(layer "F.Cu")
		(net "M_G_CPU1_SA_DQ<17>")
	)
	(segment
		(start 191.421004 -295.97731)
		(end 191.233044 -296.16527)
		(width 0.20066)
		(layer "F.Cu")
		(net "M_G_CPU1_SA_DQ<17>")
	)
	(segment
		(start 177.347372 -296.54119)
		(end 177.148236 -296.342054)
		(width 0.18288)
		(layer "In4.Cu")
		(net "M_G_CPU1_SA_DQ<17>")
	)
	(segment
		(start 144.115028 -270.034512)
		(end 143.021558 -269.58163)
		(width 0.18288)
		(layer "In4.Cu")
		(net "M_G_CPU1_SA_DQ<17>")
	)
	(segment
		(start 155.76804 -284.316678)
		(end 152.940004 -277.491698)
		(width 0.18288)
		(layer "In4.Cu")
		(net "M_G_CPU1_SA_DQ<17>")
	)
	(segment
		(start 131.304538 -266.614148)
		(end 131.298696 -266.61745)
		(width 0.088646)
		(layer "In4.Cu")
		(net "M_G_CPU1_SA_DQ<17>")
	)
	(segment
		(start 135.057896 -266.61745)
		(end 135.052054 -266.621006)
		(width 0.088646)
		(layer "In4.Cu")
		(net "M_G_CPU1_SA_DQ<17>")
	)
	(segment
		(start 183.938418 -295.60139)
		(end 181.979824 -295.60139)
		(width 0.18288)
		(layer "In4.Cu")
		(net "M_G_CPU1_SA_DQ<17>")
	)
	(segment
		(start 133.184138 -266.614148)
		(end 133.178296 -266.61745)
		(width 0.088646)
		(layer "In4.Cu")
		(net "M_G_CPU1_SA_DQ<17>")
	)
	(segment
		(start 132.244338 -266.614148)
		(end 132.238496 -266.61745)
		(width 0.088646)
		(layer "In4.Cu")
		(net "M_G_CPU1_SA_DQ<17>")
	)
	(segment
		(start 135.997696 -266.617704)
		(end 135.997696 -266.61745)
		(width 0.088646)
		(layer "In4.Cu")
		(net "M_G_CPU1_SA_DQ<17>")
	)
	(segment
		(start 172.522388 -297.192446)
		(end 171.861226 -296.531284)
		(width 0.18288)
		(layer "In4.Cu")
		(net "M_G_CPU1_SA_DQ<17>")
	)
	(segment
		(start 131.298696 -266.61745)
		(end 131.292854 -266.621006)
		(width 0.088646)
		(layer "In4.Cu")
		(net "M_G_CPU1_SA_DQ<17>")
	)
	(segment
		(start 185.351928 -295.32199)
		(end 184.217818 -295.32199)
		(width 0.18288)
		(layer "In4.Cu")
		(net "M_G_CPU1_SA_DQ<17>")
	)
	(segment
		(start 175.342804 -296.168826)
		(end 174.184056 -296.168826)
		(width 0.18288)
		(layer "In4.Cu")
		(net "M_G_CPU1_SA_DQ<17>")
	)
	(segment
		(start 165.405054 -291.800026)
		(end 164.851334 -291.800026)
		(width 0.18288)
		(layer "In4.Cu")
		(net "M_G_CPU1_SA_DQ<17>")
	)
	(segment
		(start 185.438034 -295.839388)
		(end 185.54065 -295.736772)
		(width 0.18288)
		(layer "In4.Cu")
		(net "M_G_CPU1_SA_DQ<17>")
	)
	(segment
		(start 134.118096 -266.61745)
		(end 134.112254 -266.621006)
		(width 0.088646)
		(layer "In4.Cu")
		(net "M_G_CPU1_SA_DQ<17>")
	)
	(segment
		(start 133.178296 -266.61745)
		(end 133.172454 -266.621006)
		(width 0.088646)
		(layer "In4.Cu")
		(net "M_G_CPU1_SA_DQ<17>")
	)
	(segment
		(start 137.89533 -266.66952)
		(end 137.757662 -266.66952)
		(width 0.088646)
		(layer "In4.Cu")
		(net "M_G_CPU1_SA_DQ<17>")
	)
	(segment
		(start 134.123938 -266.614148)
		(end 134.118096 -266.61745)
		(width 0.088646)
		(layer "In4.Cu")
		(net "M_G_CPU1_SA_DQ<17>")
	)
	(segment
		(start 130.733546 -266.61745)
		(end 130.65887 -266.574524)
		(width 0.088646)
		(layer "In4.Cu")
		(net "M_G_CPU1_SA_DQ<17>")
	)
	(segment
		(start 181.793896 -295.05021)
		(end 181.633876 -294.89019)
		(width 0.18288)
		(layer "In4.Cu")
		(net "M_G_CPU1_SA_DQ<17>")
	)
	(segment
		(start 176.20107 -296.679112)
		(end 175.85309 -296.679112)
		(width 0.18288)
		(layer "In4.Cu")
		(net "M_G_CPU1_SA_DQ<17>")
	)
	(segment
		(start 187.28436 -296.51579)
		(end 186.593226 -296.51579)
		(width 0.18288)
		(layer "In4.Cu")
		(net "M_G_CPU1_SA_DQ<17>")
	)
	(segment
		(start 185.54065 -295.736772)
		(end 185.54065 -295.510712)
		(width 0.18288)
		(layer "In4.Cu")
		(net "M_G_CPU1_SA_DQ<17>")
	)
	(segment
		(start 186.299602 -296.222166)
		(end 186.073542 -296.222166)
		(width 0.18288)
		(layer "In4.Cu")
		(net "M_G_CPU1_SA_DQ<17>")
	)
	(segment
		(start 142.913608 -269.536926)
		(end 139.969494 -266.592812)
		(width 0.18288)
		(layer "In4.Cu")
		(net "M_G_CPU1_SA_DQ<17>")
	)
	(segment
		(start 181.633876 -294.89019)
		(end 181.191662 -294.89019)
		(width 0.18288)
		(layer "In4.Cu")
		(net "M_G_CPU1_SA_DQ<17>")
	)
	(segment
		(start 143.021558 -269.58163)
		(end 142.913608 -269.536926)
		(width 0.18288)
		(layer "In4.Cu")
		(net "M_G_CPU1_SA_DQ<17>")
	)
	(segment
		(start 179.697126 -295.44899)
		(end 178.858926 -295.44899)
		(width 0.18288)
		(layer "In4.Cu")
		(net "M_G_CPU1_SA_DQ<17>")
	)
	(segment
		(start 130.65887 -266.574524)
		(end 130.076448 -266.128246)
		(width 0.088646)
		(layer "In4.Cu")
		(net "M_G_CPU1_SA_DQ<17>")
	)
	(segment
		(start 139.969494 -266.592812)
		(end 138.665204 -266.592812)
		(width 0.18288)
		(layer "In4.Cu")
		(net "M_G_CPU1_SA_DQ<17>")
	)
	(segment
		(start 160.31083 -287.996376)
		(end 159.5628 -287.996376)
		(width 0.18288)
		(layer "In4.Cu")
		(net "M_G_CPU1_SA_DQ<17>")
	)
	(segment
		(start 181.008782 -295.44137)
		(end 180.848762 -295.60139)
		(width 0.18288)
		(layer "In4.Cu")
		(net "M_G_CPU1_SA_DQ<17>")
	)
	(segment
		(start 179.849526 -295.60139)
		(end 179.697126 -295.44899)
		(width 0.18288)
		(layer "In4.Cu")
		(net "M_G_CPU1_SA_DQ<17>")
	)
	(segment
		(start 138.665204 -266.592812)
		(end 137.972038 -266.592812)
		(width 0.088646)
		(layer "In4.Cu")
		(net "M_G_CPU1_SA_DQ<17>")
	)
	(segment
		(start 177.148236 -296.342054)
		(end 176.538128 -296.342054)
		(width 0.18288)
		(layer "In4.Cu")
		(net "M_G_CPU1_SA_DQ<17>")
	)
	(segment
		(start 185.684414 -296.385234)
		(end 185.438034 -296.138854)
		(width 0.18288)
		(layer "In4.Cu")
		(net "M_G_CPU1_SA_DQ<17>")
	)
	(segment
		(start 164.851334 -291.800026)
		(end 164.076634 -291.025326)
		(width 0.18288)
		(layer "In4.Cu")
		(net "M_G_CPU1_SA_DQ<17>")
	)
	(segment
		(start 178.579526 -295.95699)
		(end 177.995326 -296.54119)
		(width 0.18288)
		(layer "In4.Cu")
		(net "M_G_CPU1_SA_DQ<17>")
	)
	(segment
		(start 162.95751 -289.840162)
		(end 161.928048 -288.8107)
		(width 0.18288)
		(layer "In4.Cu")
		(net "M_G_CPU1_SA_DQ<17>")
	)
	(segment
		(start 181.191662 -294.89019)
		(end 181.008782 -295.07307)
		(width 0.18288)
		(layer "In4.Cu")
		(net "M_G_CPU1_SA_DQ<17>")
	)
	(segment
		(start 152.940004 -277.491698)
		(end 145.482818 -270.034512)
		(width 0.18288)
		(layer "In4.Cu")
		(net "M_G_CPU1_SA_DQ<17>")
	)
	(segment
		(start 132.238496 -266.61745)
		(end 132.232654 -266.621006)
		(width 0.088646)
		(layer "In4.Cu")
		(net "M_G_CPU1_SA_DQ<17>")
	)
	(segment
		(start 157.980888 -285.181294)
		(end 157.062424 -285.181294)
		(width 0.18288)
		(layer "In4.Cu")
		(net "M_G_CPU1_SA_DQ<17>")
	)
	(segment
		(start 173.160436 -297.192446)
		(end 172.522388 -297.192446)
		(width 0.18288)
		(layer "In4.Cu")
		(net "M_G_CPU1_SA_DQ<17>")
	)
	(segment
		(start 170.034712 -295.105836)
		(end 169.064432 -294.7035)
		(width 0.18288)
		(layer "In4.Cu")
		(net "M_G_CPU1_SA_DQ<17>")
	)
	(segment
		(start 174.184056 -296.168826)
		(end 173.160436 -297.192446)
		(width 0.18288)
		(layer "In4.Cu")
		(net "M_G_CPU1_SA_DQ<17>")
	)
	(segment
		(start 157.062424 -285.181294)
		(end 155.76804 -284.316678)
		(width 0.18288)
		(layer "In4.Cu")
		(net "M_G_CPU1_SA_DQ<17>")
	)
	(segment
		(start 162.95751 -290.319714)
		(end 162.95751 -289.840162)
		(width 0.18288)
		(layer "In4.Cu")
		(net "M_G_CPU1_SA_DQ<17>")
	)
	(segment
		(start 163.663122 -291.025326)
		(end 162.95751 -290.319714)
		(width 0.18288)
		(layer "In4.Cu")
		(net "M_G_CPU1_SA_DQ<17>")
	)
	(segment
		(start 161.125154 -288.8107)
		(end 160.31083 -287.996376)
		(width 0.18288)
		(layer "In4.Cu")
		(net "M_G_CPU1_SA_DQ<17>")
	)
	(segment
		(start 187.883546 -295.916604)
		(end 187.28436 -296.51579)
		(width 0.18288)
		(layer "In4.Cu")
		(net "M_G_CPU1_SA_DQ<17>")
	)
	(segment
		(start 181.793896 -295.415462)
		(end 181.793896 -295.05021)
		(width 0.18288)
		(layer "In4.Cu")
		(net "M_G_CPU1_SA_DQ<17>")
	)
	(segment
		(start 185.438034 -296.138854)
		(end 185.438034 -295.839388)
		(width 0.18288)
		(layer "In4.Cu")
		(net "M_G_CPU1_SA_DQ<17>")
	)
	(segment
		(start 159.5628 -287.996376)
		(end 159.40278 -287.836356)
		(width 0.18288)
		(layer "In4.Cu")
		(net "M_G_CPU1_SA_DQ<17>")
	)
	(segment
		(start 159.40278 -287.836356)
		(end 159.40278 -286.603186)
		(width 0.18288)
		(layer "In4.Cu")
		(net "M_G_CPU1_SA_DQ<17>")
	)
	(segment
		(start 167.176704 -293.571676)
		(end 165.405054 -291.800026)
		(width 0.18288)
		(layer "In4.Cu")
		(net "M_G_CPU1_SA_DQ<17>")
	)
	(segment
		(start 145.482818 -270.034512)
		(end 144.115028 -270.034512)
		(width 0.18288)
		(layer "In4.Cu")
		(net "M_G_CPU1_SA_DQ<17>")
	)
	(segment
		(start 186.073542 -296.222166)
		(end 185.910474 -296.385234)
		(width 0.18288)
		(layer "In4.Cu")
		(net "M_G_CPU1_SA_DQ<17>")
	)
	(segment
		(start 169.064432 -294.7035)
		(end 167.176704 -293.571676)
		(width 0.18288)
		(layer "In4.Cu")
		(net "M_G_CPU1_SA_DQ<17>")
	)
	(segment
		(start 137.972038 -266.592812)
		(end 137.89533 -266.66952)
		(width 0.088646)
		(layer "In4.Cu")
		(net "M_G_CPU1_SA_DQ<17>")
	)
	(segment
		(start 181.979824 -295.60139)
		(end 181.793896 -295.415462)
		(width 0.18288)
		(layer "In4.Cu")
		(net "M_G_CPU1_SA_DQ<17>")
	)
	(segment
		(start 178.858926 -295.44899)
		(end 178.579526 -295.72839)
		(width 0.18288)
		(layer "In4.Cu")
		(net "M_G_CPU1_SA_DQ<17>")
	)
	(segment
		(start 180.848762 -295.60139)
		(end 179.849526 -295.60139)
		(width 0.18288)
		(layer "In4.Cu")
		(net "M_G_CPU1_SA_DQ<17>")
	)
	(segment
		(start 171.46016 -296.531284)
		(end 170.034712 -295.105836)
		(width 0.18288)
		(layer "In4.Cu")
		(net "M_G_CPU1_SA_DQ<17>")
	)
	(segment
		(start 176.538128 -296.342054)
		(end 176.20107 -296.679112)
		(width 0.18288)
		(layer "In4.Cu")
		(net "M_G_CPU1_SA_DQ<17>")
	)
	(segment
		(start 171.861226 -296.531284)
		(end 171.46016 -296.531284)
		(width 0.18288)
		(layer "In4.Cu")
		(net "M_G_CPU1_SA_DQ<17>")
	)
	(segment
		(start 186.593226 -296.51579)
		(end 186.299602 -296.222166)
		(width 0.18288)
		(layer "In4.Cu")
		(net "M_G_CPU1_SA_DQ<17>")
	)
	(segment
		(start 159.40278 -286.603186)
		(end 157.980888 -285.181294)
		(width 0.18288)
		(layer "In4.Cu")
		(net "M_G_CPU1_SA_DQ<17>")
	)
	(segment
		(start 175.85309 -296.679112)
		(end 175.342804 -296.168826)
		(width 0.18288)
		(layer "In4.Cu")
		(net "M_G_CPU1_SA_DQ<17>")
	)
	(segment
		(start 185.910474 -296.385234)
		(end 185.684414 -296.385234)
		(width 0.18288)
		(layer "In4.Cu")
		(net "M_G_CPU1_SA_DQ<17>")
	)
	(segment
		(start 164.076634 -291.025326)
		(end 163.663122 -291.025326)
		(width 0.18288)
		(layer "In4.Cu")
		(net "M_G_CPU1_SA_DQ<17>")
	)
	(segment
		(start 184.217818 -295.32199)
		(end 183.938418 -295.60139)
		(width 0.18288)
		(layer "In4.Cu")
		(net "M_G_CPU1_SA_DQ<17>")
	)
	(segment
		(start 135.062214 -266.61491)
		(end 135.057896 -266.61745)
		(width 0.088646)
		(layer "In4.Cu")
		(net "M_G_CPU1_SA_DQ<17>")
	)
	(segment
		(start 185.54065 -295.510712)
		(end 185.351928 -295.32199)
		(width 0.18288)
		(layer "In4.Cu")
		(net "M_G_CPU1_SA_DQ<17>")
	)
	(segment
		(start 178.579526 -295.72839)
		(end 178.579526 -295.95699)
		(width 0.18288)
		(layer "In4.Cu")
		(net "M_G_CPU1_SA_DQ<17>")
	)
	(segment
		(start 177.995326 -296.54119)
		(end 177.347372 -296.54119)
		(width 0.18288)
		(layer "In4.Cu")
		(net "M_G_CPU1_SA_DQ<17>")
	)
	(segment
		(start 161.928048 -288.8107)
		(end 161.125154 -288.8107)
		(width 0.18288)
		(layer "In4.Cu")
		(net "M_G_CPU1_SA_DQ<17>")
	)
	(segment
		(start 130.076448 -266.128246)
		(end 130.076194 -266.128246)
		(width 0.088646)
		(layer "In4.Cu")
		(net "M_G_CPU1_SA_DQ<17>")
	)
	(segment
		(start 181.008782 -295.07307)
		(end 181.008782 -295.44137)
		(width 0.18288)
		(layer "In4.Cu")
		(net "M_G_CPU1_SA_DQ<17>")
	)
	(arc
		(start 132.232654 -266.621006)
		(mid 131.952519 -266.693322)
		(end 131.673346 -266.61745)
		(width 0.088646)
		(layer "In4.Cu")
		(net "M_G_CPU1_SA_DQ<17>")
	)
	(arc
		(start 133.552946 -266.61745)
		(mid 133.368992 -266.567321)
		(end 133.184138 -266.614148)
		(width 0.088646)
		(layer "In4.Cu")
		(net "M_G_CPU1_SA_DQ<17>")
	)
	(arc
		(start 137.311892 -266.617704)
		(mid 137.124694 -266.567527)
		(end 136.937496 -266.617704)
		(width 0.088646)
		(layer "In4.Cu")
		(net "M_G_CPU1_SA_DQ<17>")
	)
	(arc
		(start 136.372092 -266.617704)
		(mid 136.184894 -266.567527)
		(end 135.997696 -266.617704)
		(width 0.088646)
		(layer "In4.Cu")
		(net "M_G_CPU1_SA_DQ<17>")
	)
	(arc
		(start 133.172454 -266.621006)
		(mid 132.892319 -266.693322)
		(end 132.613146 -266.61745)
		(width 0.088646)
		(layer "In4.Cu")
		(net "M_G_CPU1_SA_DQ<17>")
	)
	(arc
		(start 132.613146 -266.61745)
		(mid 132.429192 -266.567321)
		(end 132.244338 -266.614148)
		(width 0.088646)
		(layer "In4.Cu")
		(net "M_G_CPU1_SA_DQ<17>")
	)
	(arc
		(start 134.492746 -266.61745)
		(mid 134.308792 -266.567321)
		(end 134.123938 -266.614148)
		(width 0.088646)
		(layer "In4.Cu")
		(net "M_G_CPU1_SA_DQ<17>")
	)
	(arc
		(start 136.937496 -266.617704)
		(mid 136.654794 -266.69348)
		(end 136.372092 -266.617704)
		(width 0.088646)
		(layer "In4.Cu")
		(net "M_G_CPU1_SA_DQ<17>")
	)
	(arc
		(start 135.052054 -266.621006)
		(mid 134.771919 -266.693322)
		(end 134.492746 -266.61745)
		(width 0.088646)
		(layer "In4.Cu")
		(net "M_G_CPU1_SA_DQ<17>")
	)
	(arc
		(start 135.997696 -266.61745)
		(mid 135.715138 -266.693099)
		(end 135.432546 -266.61745)
		(width 0.088646)
		(layer "In4.Cu")
		(net "M_G_CPU1_SA_DQ<17>")
	)
	(arc
		(start 134.112254 -266.621006)
		(mid 133.832119 -266.693322)
		(end 133.552946 -266.61745)
		(width 0.088646)
		(layer "In4.Cu")
		(net "M_G_CPU1_SA_DQ<17>")
	)
	(arc
		(start 135.432546 -266.61745)
		(mid 135.247709 -266.567189)
		(end 135.062214 -266.61491)
		(width 0.088646)
		(layer "In4.Cu")
		(net "M_G_CPU1_SA_DQ<17>")
	)
	(arc
		(start 137.757662 -266.66952)
		(mid 137.529403 -266.689779)
		(end 137.311892 -266.617704)
		(width 0.088646)
		(layer "In4.Cu")
		(net "M_G_CPU1_SA_DQ<17>")
	)
	(arc
		(start 131.292854 -266.621006)
		(mid 131.012719 -266.693322)
		(end 130.733546 -266.61745)
		(width 0.088646)
		(layer "In4.Cu")
		(net "M_G_CPU1_SA_DQ<17>")
	)
	(arc
		(start 131.673346 -266.61745)
		(mid 131.489392 -266.567321)
		(end 131.304538 -266.614148)
		(width 0.088646)
		(layer "In4.Cu")
		(net "M_G_CPU1_SA_DQ<17>")
	)
	(segment
		(start 194.092576 -297.191684)
		(end 191.930782 -297.191684)
		(width 0.1016)
		(layer "F.Cu")
		(net "M_G_CPU1_SA_DQ<16>")
	)
	(segment
		(start 191.930782 -297.191684)
		(end 191.883792 -297.191684)
		(width 0.101854)
		(layer "F.Cu")
		(net "M_G_CPU1_SA_DQ<16>")
	)
	(segment
		(start 130.546094 -266.405868)
		(end 130.546094 -266.941554)
		(width 0.20066)
		(layer "F.Cu")
		(net "M_G_CPU1_SA_DQ<16>")
	)
	(segment
		(start 130.546094 -266.941554)
		(end 130.546348 -266.941808)
		(width 0.20066)
		(layer "F.Cu")
		(net "M_G_CPU1_SA_DQ<16>")
	)
	(segment
		(start 191.233044 -297.865292)
		(end 190.75781 -297.865292)
		(width 0.20066)
		(layer "F.Cu")
		(net "M_G_CPU1_SA_DQ<16>")
	)
	(segment
		(start 194.508882 -297.185334)
		(end 194.098926 -297.185334)
		(width 0.20066)
		(layer "F.Cu")
		(net "M_G_CPU1_SA_DQ<16>")
	)
	(segment
		(start 196.532246 -297.616626)
		(end 196.531992 -297.61688)
		(width 0.20066)
		(layer "F.Cu")
		(net "M_G_CPU1_SA_DQ<16>")
	)
	(segment
		(start 194.098926 -297.185334)
		(end 194.092576 -297.191684)
		(width 0.1016)
		(layer "F.Cu")
		(net "M_G_CPU1_SA_DQ<16>")
	)
	(segment
		(start 194.940428 -297.61688)
		(end 194.508882 -297.185334)
		(width 0.20066)
		(layer "F.Cu")
		(net "M_G_CPU1_SA_DQ<16>")
	)
	(segment
		(start 190.75781 -297.865292)
		(end 190.509144 -297.616626)
		(width 0.20066)
		(layer "F.Cu")
		(net "M_G_CPU1_SA_DQ<16>")
	)
	(segment
		(start 191.421004 -297.309794)
		(end 191.421004 -297.677332)
		(width 0.20066)
		(layer "F.Cu")
		(net "M_G_CPU1_SA_DQ<16>")
	)
	(segment
		(start 191.883792 -297.191684)
		(end 191.539114 -297.191684)
		(width 0.20066)
		(layer "F.Cu")
		(net "M_G_CPU1_SA_DQ<16>")
	)
	(segment
		(start 196.531992 -297.61688)
		(end 194.940428 -297.61688)
		(width 0.20066)
		(layer "F.Cu")
		(net "M_G_CPU1_SA_DQ<16>")
	)
	(segment
		(start 191.421004 -297.677332)
		(end 191.233044 -297.865292)
		(width 0.20066)
		(layer "F.Cu")
		(net "M_G_CPU1_SA_DQ<16>")
	)
	(segment
		(start 191.539114 -297.191684)
		(end 191.421004 -297.309794)
		(width 0.20066)
		(layer "F.Cu")
		(net "M_G_CPU1_SA_DQ<16>")
	)
	(segment
		(start 188.988446 -297.616626)
		(end 187.883546 -297.616626)
		(width 0.20066)
		(layer "F.Cu")
		(net "M_G_CPU1_SA_DQ<16>")
	)
	(segment
		(start 190.509144 -297.616626)
		(end 188.988446 -297.616626)
		(width 0.20066)
		(layer "F.Cu")
		(net "M_G_CPU1_SA_DQ<16>")
	)
	(segment
		(start 143.086582 -270.73098)
		(end 139.638532 -267.28293)
		(width 0.18288)
		(layer "In4.Cu")
		(net "M_G_CPU1_SA_DQ<16>")
	)
	(segment
		(start 136.467596 -267.43152)
		(end 136.467596 -267.431266)
		(width 0.088646)
		(layer "In4.Cu")
		(net "M_G_CPU1_SA_DQ<16>")
	)
	(segment
		(start 170.706288 -298.141136)
		(end 168.827958 -296.262806)
		(width 0.18288)
		(layer "In4.Cu")
		(net "M_G_CPU1_SA_DQ<16>")
	)
	(segment
		(start 185.114184 -297.65879)
		(end 185.114184 -298.096432)
		(width 0.18288)
		(layer "In4.Cu")
		(net "M_G_CPU1_SA_DQ<16>")
	)
	(segment
		(start 181.587394 -298.3738)
		(end 181.239414 -298.3738)
		(width 0.18288)
		(layer "In4.Cu")
		(net "M_G_CPU1_SA_DQ<16>")
	)
	(segment
		(start 134.962646 -267.431266)
		(end 134.958074 -267.428726)
		(width 0.088646)
		(layer "In4.Cu")
		(net "M_G_CPU1_SA_DQ<16>")
	)
	(segment
		(start 166.72433 -294.546782)
		(end 165.704774 -293.527226)
		(width 0.18288)
		(layer "In4.Cu")
		(net "M_G_CPU1_SA_DQ<16>")
	)
	(segment
		(start 179.376832 -298.042584)
		(end 173.922944 -298.042584)
		(width 0.18288)
		(layer "In4.Cu")
		(net "M_G_CPU1_SA_DQ<16>")
	)
	(segment
		(start 171.807886 -298.141136)
		(end 170.706288 -298.141136)
		(width 0.18288)
		(layer "In4.Cu")
		(net "M_G_CPU1_SA_DQ<16>")
	)
	(segment
		(start 143.374618 -270.85036)
		(end 143.086582 -270.73098)
		(width 0.18288)
		(layer "In4.Cu")
		(net "M_G_CPU1_SA_DQ<16>")
	)
	(segment
		(start 139.638532 -267.28293)
		(end 139.529312 -267.28293)
		(width 0.18288)
		(layer "In4.Cu")
		(net "M_G_CPU1_SA_DQ<16>")
	)
	(segment
		(start 156.092144 -286.252666)
		(end 155.188666 -285.649162)
		(width 0.18288)
		(layer "In4.Cu")
		(net "M_G_CPU1_SA_DQ<16>")
	)
	(segment
		(start 164.380926 -293.527226)
		(end 162.040316 -291.186616)
		(width 0.18288)
		(layer "In4.Cu")
		(net "M_G_CPU1_SA_DQ<16>")
	)
	(segment
		(start 173.075854 -298.889674)
		(end 172.556424 -298.889674)
		(width 0.18288)
		(layer "In4.Cu")
		(net "M_G_CPU1_SA_DQ<16>")
	)
	(segment
		(start 133.090412 -267.435584)
		(end 133.083046 -267.431266)
		(width 0.088646)
		(layer "In4.Cu")
		(net "M_G_CPU1_SA_DQ<16>")
	)
	(segment
		(start 185.90768 -298.096432)
		(end 185.90768 -297.645836)
		(width 0.18288)
		(layer "In4.Cu")
		(net "M_G_CPU1_SA_DQ<16>")
	)
	(segment
		(start 185.287158 -297.485816)
		(end 185.114184 -297.65879)
		(width 0.18288)
		(layer "In4.Cu")
		(net "M_G_CPU1_SA_DQ<16>")
	)
	(segment
		(start 181.737508 -298.223686)
		(end 181.587394 -298.3738)
		(width 0.18288)
		(layer "In4.Cu")
		(net "M_G_CPU1_SA_DQ<16>")
	)
	(segment
		(start 186.0677 -298.256452)
		(end 185.90768 -298.096432)
		(width 0.18288)
		(layer "In4.Cu")
		(net "M_G_CPU1_SA_DQ<16>")
	)
	(segment
		(start 187.883546 -297.616626)
		(end 187.24372 -298.256452)
		(width 0.18288)
		(layer "In4.Cu")
		(net "M_G_CPU1_SA_DQ<16>")
	)
	(segment
		(start 137.55624 -267.28293)
		(end 137.412476 -267.426694)
		(width 0.088646)
		(layer "In4.Cu")
		(net "M_G_CPU1_SA_DQ<16>")
	)
	(segment
		(start 181.897528 -297.36669)
		(end 181.737508 -297.52671)
		(width 0.18288)
		(layer "In4.Cu")
		(net "M_G_CPU1_SA_DQ<16>")
	)
	(segment
		(start 131.203446 -267.431266)
		(end 131.201414 -267.43025)
		(width 0.088646)
		(layer "In4.Cu")
		(net "M_G_CPU1_SA_DQ<16>")
	)
	(segment
		(start 181.026054 -297.538394)
		(end 180.866034 -297.378374)
		(width 0.18288)
		(layer "In4.Cu")
		(net "M_G_CPU1_SA_DQ<16>")
	)
	(segment
		(start 134.967218 -267.43406)
		(end 134.962646 -267.431266)
		(width 0.088646)
		(layer "In4.Cu")
		(net "M_G_CPU1_SA_DQ<16>")
	)
	(segment
		(start 139.529312 -267.28293)
		(end 137.55624 -267.28293)
		(width 0.088646)
		(layer "In4.Cu")
		(net "M_G_CPU1_SA_DQ<16>")
	)
	(segment
		(start 183.223408 -298.256452)
		(end 182.333646 -297.36669)
		(width 0.18288)
		(layer "In4.Cu")
		(net "M_G_CPU1_SA_DQ<16>")
	)
	(segment
		(start 185.114184 -298.096432)
		(end 184.954164 -298.256452)
		(width 0.18288)
		(layer "In4.Cu")
		(net "M_G_CPU1_SA_DQ<16>")
	)
	(segment
		(start 131.210812 -267.435584)
		(end 131.203446 -267.431266)
		(width 0.088646)
		(layer "In4.Cu")
		(net "M_G_CPU1_SA_DQ<16>")
	)
	(segment
		(start 158.214822 -288.18713)
		(end 157.47238 -288.18713)
		(width 0.18288)
		(layer "In4.Cu")
		(net "M_G_CPU1_SA_DQ<16>")
	)
	(segment
		(start 167.444674 -295.689782)
		(end 167.023288 -295.268396)
		(width 0.18288)
		(layer "In4.Cu")
		(net "M_G_CPU1_SA_DQ<16>")
	)
	(segment
		(start 132.143246 -267.431266)
		(end 132.138674 -267.428726)
		(width 0.088646)
		(layer "In4.Cu")
		(net "M_G_CPU1_SA_DQ<16>")
	)
	(segment
		(start 185.74766 -297.485816)
		(end 185.287158 -297.485816)
		(width 0.18288)
		(layer "In4.Cu")
		(net "M_G_CPU1_SA_DQ<16>")
	)
	(segment
		(start 152.005792 -277.965662)
		(end 145.147792 -271.107662)
		(width 0.18288)
		(layer "In4.Cu")
		(net "M_G_CPU1_SA_DQ<16>")
	)
	(segment
		(start 180.866034 -297.378374)
		(end 180.041042 -297.378374)
		(width 0.18288)
		(layer "In4.Cu")
		(net "M_G_CPU1_SA_DQ<16>")
	)
	(segment
		(start 181.737508 -297.52671)
		(end 181.737508 -298.223686)
		(width 0.18288)
		(layer "In4.Cu")
		(net "M_G_CPU1_SA_DQ<16>")
	)
	(segment
		(start 173.922944 -298.042584)
		(end 173.075854 -298.889674)
		(width 0.18288)
		(layer "In4.Cu")
		(net "M_G_CPU1_SA_DQ<16>")
	)
	(segment
		(start 167.023288 -295.268396)
		(end 166.72433 -294.546782)
		(width 0.18288)
		(layer "In4.Cu")
		(net "M_G_CPU1_SA_DQ<16>")
	)
	(segment
		(start 180.041042 -297.378374)
		(end 179.376832 -298.042584)
		(width 0.18288)
		(layer "In4.Cu")
		(net "M_G_CPU1_SA_DQ<16>")
	)
	(segment
		(start 134.030212 -267.435584)
		(end 134.022846 -267.431266)
		(width 0.088646)
		(layer "In4.Cu")
		(net "M_G_CPU1_SA_DQ<16>")
	)
	(segment
		(start 184.954164 -298.256452)
		(end 183.223408 -298.256452)
		(width 0.18288)
		(layer "In4.Cu")
		(net "M_G_CPU1_SA_DQ<16>")
	)
	(segment
		(start 133.083046 -267.431266)
		(end 133.078474 -267.428726)
		(width 0.088646)
		(layer "In4.Cu")
		(net "M_G_CPU1_SA_DQ<16>")
	)
	(segment
		(start 162.040316 -291.186616)
		(end 161.646108 -291.186616)
		(width 0.18288)
		(layer "In4.Cu")
		(net "M_G_CPU1_SA_DQ<16>")
	)
	(segment
		(start 172.556424 -298.889674)
		(end 171.807886 -298.141136)
		(width 0.18288)
		(layer "In4.Cu")
		(net "M_G_CPU1_SA_DQ<16>")
	)
	(segment
		(start 168.827958 -296.262806)
		(end 167.444674 -295.689782)
		(width 0.18288)
		(layer "In4.Cu")
		(net "M_G_CPU1_SA_DQ<16>")
	)
	(segment
		(start 157.016958 -287.731708)
		(end 157.016958 -287.17748)
		(width 0.18288)
		(layer "In4.Cu")
		(net "M_G_CPU1_SA_DQ<16>")
	)
	(segment
		(start 130.859022 -266.941808)
		(end 130.546348 -266.941808)
		(width 0.088646)
		(layer "In4.Cu")
		(net "M_G_CPU1_SA_DQ<16>")
	)
	(segment
		(start 165.704774 -293.527226)
		(end 164.380926 -293.527226)
		(width 0.18288)
		(layer "In4.Cu")
		(net "M_G_CPU1_SA_DQ<16>")
	)
	(segment
		(start 132.150612 -267.435584)
		(end 132.143246 -267.431266)
		(width 0.088646)
		(layer "In4.Cu")
		(net "M_G_CPU1_SA_DQ<16>")
	)
	(segment
		(start 134.022846 -267.431266)
		(end 134.018274 -267.428726)
		(width 0.088646)
		(layer "In4.Cu")
		(net "M_G_CPU1_SA_DQ<16>")
	)
	(segment
		(start 182.333646 -297.36669)
		(end 181.897528 -297.36669)
		(width 0.18288)
		(layer "In4.Cu")
		(net "M_G_CPU1_SA_DQ<16>")
	)
	(segment
		(start 187.24372 -298.256452)
		(end 186.0677 -298.256452)
		(width 0.18288)
		(layer "In4.Cu")
		(net "M_G_CPU1_SA_DQ<16>")
	)
	(segment
		(start 181.239414 -298.3738)
		(end 181.026054 -298.16044)
		(width 0.18288)
		(layer "In4.Cu")
		(net "M_G_CPU1_SA_DQ<16>")
	)
	(segment
		(start 159.812482 -289.78479)
		(end 158.214822 -288.18713)
		(width 0.18288)
		(layer "In4.Cu")
		(net "M_G_CPU1_SA_DQ<16>")
	)
	(segment
		(start 155.188666 -285.649162)
		(end 152.005792 -277.965662)
		(width 0.18288)
		(layer "In4.Cu")
		(net "M_G_CPU1_SA_DQ<16>")
	)
	(segment
		(start 181.026054 -298.16044)
		(end 181.026054 -297.538394)
		(width 0.18288)
		(layer "In4.Cu")
		(net "M_G_CPU1_SA_DQ<16>")
	)
	(segment
		(start 130.924554 -267.007594)
		(end 130.859022 -266.941808)
		(width 0.088646)
		(layer "In4.Cu")
		(net "M_G_CPU1_SA_DQ<16>")
	)
	(segment
		(start 135.908034 -267.434568)
		(end 135.902446 -267.431266)
		(width 0.088646)
		(layer "In4.Cu")
		(net "M_G_CPU1_SA_DQ<16>")
	)
	(segment
		(start 137.412476 -267.426694)
		(end 137.407396 -267.43152)
		(width 0.088646)
		(layer "In4.Cu")
		(net "M_G_CPU1_SA_DQ<16>")
	)
	(segment
		(start 157.016958 -287.17748)
		(end 156.092144 -286.252666)
		(width 0.18288)
		(layer "In4.Cu")
		(net "M_G_CPU1_SA_DQ<16>")
	)
	(segment
		(start 161.646108 -291.186616)
		(end 160.244282 -289.78479)
		(width 0.18288)
		(layer "In4.Cu")
		(net "M_G_CPU1_SA_DQ<16>")
	)
	(segment
		(start 143.995902 -271.107662)
		(end 143.374618 -270.85036)
		(width 0.18288)
		(layer "In4.Cu")
		(net "M_G_CPU1_SA_DQ<16>")
	)
	(segment
		(start 160.244282 -289.78479)
		(end 159.812482 -289.78479)
		(width 0.18288)
		(layer "In4.Cu")
		(net "M_G_CPU1_SA_DQ<16>")
	)
	(segment
		(start 185.90768 -297.645836)
		(end 185.74766 -297.485816)
		(width 0.18288)
		(layer "In4.Cu")
		(net "M_G_CPU1_SA_DQ<16>")
	)
	(segment
		(start 145.147792 -271.107662)
		(end 143.995902 -271.107662)
		(width 0.18288)
		(layer "In4.Cu")
		(net "M_G_CPU1_SA_DQ<16>")
	)
	(segment
		(start 157.47238 -288.18713)
		(end 157.016958 -287.731708)
		(width 0.18288)
		(layer "In4.Cu")
		(net "M_G_CPU1_SA_DQ<16>")
	)
	(arc
		(start 132.138674 -267.428726)
		(mid 131.953289 -267.381088)
		(end 131.768596 -267.431266)
		(width 0.088646)
		(layer "In4.Cu")
		(net "M_G_CPU1_SA_DQ<16>")
	)
	(arc
		(start 137.407396 -267.43152)
		(mid 137.124694 -267.507262)
		(end 136.841992 -267.43152)
		(width 0.088646)
		(layer "In4.Cu")
		(net "M_G_CPU1_SA_DQ<16>")
	)
	(arc
		(start 135.527796 -267.431266)
		(mid 135.247882 -267.507035)
		(end 134.967218 -267.43406)
		(width 0.088646)
		(layer "In4.Cu")
		(net "M_G_CPU1_SA_DQ<16>")
	)
	(arc
		(start 131.201414 -267.43025)
		(mid 131.013096 -267.251592)
		(end 130.924554 -267.007594)
		(width 0.088646)
		(layer "In4.Cu")
		(net "M_G_CPU1_SA_DQ<16>")
	)
	(arc
		(start 133.078474 -267.428726)
		(mid 132.893089 -267.381088)
		(end 132.708396 -267.431266)
		(width 0.088646)
		(layer "In4.Cu")
		(net "M_G_CPU1_SA_DQ<16>")
	)
	(arc
		(start 134.018274 -267.428726)
		(mid 133.832889 -267.381088)
		(end 133.648196 -267.431266)
		(width 0.088646)
		(layer "In4.Cu")
		(net "M_G_CPU1_SA_DQ<16>")
	)
	(arc
		(start 136.841992 -267.43152)
		(mid 136.654794 -267.381377)
		(end 136.467596 -267.43152)
		(width 0.088646)
		(layer "In4.Cu")
		(net "M_G_CPU1_SA_DQ<16>")
	)
	(arc
		(start 132.708396 -267.431266)
		(mid 132.430073 -267.507025)
		(end 132.150612 -267.435584)
		(width 0.088646)
		(layer "In4.Cu")
		(net "M_G_CPU1_SA_DQ<16>")
	)
	(arc
		(start 135.902446 -267.431266)
		(mid 135.715138 -267.381157)
		(end 135.527796 -267.431266)
		(width 0.088646)
		(layer "In4.Cu")
		(net "M_G_CPU1_SA_DQ<16>")
	)
	(arc
		(start 134.587996 -267.431266)
		(mid 134.309673 -267.507025)
		(end 134.030212 -267.435584)
		(width 0.088646)
		(layer "In4.Cu")
		(net "M_G_CPU1_SA_DQ<16>")
	)
	(arc
		(start 131.768596 -267.431266)
		(mid 131.490273 -267.507025)
		(end 131.210812 -267.435584)
		(width 0.088646)
		(layer "In4.Cu")
		(net "M_G_CPU1_SA_DQ<16>")
	)
	(arc
		(start 134.958074 -267.428726)
		(mid 134.772689 -267.381088)
		(end 134.587996 -267.431266)
		(width 0.088646)
		(layer "In4.Cu")
		(net "M_G_CPU1_SA_DQ<16>")
	)
	(arc
		(start 136.467596 -267.431266)
		(mid 136.188249 -267.507032)
		(end 135.908034 -267.434568)
		(width 0.088646)
		(layer "In4.Cu")
		(net "M_G_CPU1_SA_DQ<16>")
	)
	(arc
		(start 133.648196 -267.431266)
		(mid 133.369873 -267.507025)
		(end 133.090412 -267.435584)
		(width 0.088646)
		(layer "In4.Cu")
		(net "M_G_CPU1_SA_DQ<16>")
	)
	(segment
		(start 199.046084 -298.214796)
		(end 199.298052 -298.466764)
		(width 0.20066)
		(layer "F.Cu")
		(net "M_G_CPU1_SA_DQ<15>")
	)
	(segment
		(start 193.088514 -298.466764)
		(end 194.786758 -298.466764)
		(width 0.20066)
		(layer "F.Cu")
		(net "M_G_CPU1_SA_DQ<15>")
	)
	(segment
		(start 198.427848 -298.699936)
		(end 198.427848 -298.448984)
		(width 0.20066)
		(layer "F.Cu")
		(net "M_G_CPU1_SA_DQ<15>")
	)
	(segment
		(start 198.223886 -298.903898)
		(end 198.427848 -298.699936)
		(width 0.20066)
		(layer "F.Cu")
		(net "M_G_CPU1_SA_DQ<15>")
	)
	(segment
		(start 198.662036 -298.214796)
		(end 199.046084 -298.214796)
		(width 0.20066)
		(layer "F.Cu")
		(net "M_G_CPU1_SA_DQ<15>")
	)
	(segment
		(start 197.530466 -298.891706)
		(end 197.542658 -298.903898)
		(width 0.1016)
		(layer "F.Cu")
		(net "M_G_CPU1_SA_DQ<15>")
	)
	(segment
		(start 199.298052 -298.466764)
		(end 200.632314 -298.466764)
		(width 0.20066)
		(layer "F.Cu")
		(net "M_G_CPU1_SA_DQ<15>")
	)
	(segment
		(start 191.983614 -298.466764)
		(end 193.088514 -298.466764)
		(width 0.20066)
		(layer "F.Cu")
		(net "M_G_CPU1_SA_DQ<15>")
	)
	(segment
		(start 195.522596 -298.891706)
		(end 197.530466 -298.891706)
		(width 0.1016)
		(layer "F.Cu")
		(net "M_G_CPU1_SA_DQ<15>")
	)
	(segment
		(start 195.515484 -298.898818)
		(end 195.522596 -298.891706)
		(width 0.1016)
		(layer "F.Cu")
		(net "M_G_CPU1_SA_DQ<15>")
	)
	(segment
		(start 195.218812 -298.898818)
		(end 195.510658 -298.898818)
		(width 0.20066)
		(layer "F.Cu")
		(net "M_G_CPU1_SA_DQ<15>")
	)
	(segment
		(start 197.542658 -298.903898)
		(end 198.223886 -298.903898)
		(width 0.20066)
		(layer "F.Cu")
		(net "M_G_CPU1_SA_DQ<15>")
	)
	(segment
		(start 194.786758 -298.466764)
		(end 195.218812 -298.898818)
		(width 0.20066)
		(layer "F.Cu")
		(net "M_G_CPU1_SA_DQ<15>")
	)
	(segment
		(start 195.510658 -298.898818)
		(end 195.515484 -298.898818)
		(width 0.101854)
		(layer "F.Cu")
		(net "M_G_CPU1_SA_DQ<15>")
	)
	(segment
		(start 128.196848 -270.475456)
		(end 128.196848 -271.011142)
		(width 0.20066)
		(layer "F.Cu")
		(net "M_G_CPU1_SA_DQ<15>")
	)
	(segment
		(start 198.427848 -298.448984)
		(end 198.662036 -298.214796)
		(width 0.20066)
		(layer "F.Cu")
		(net "M_G_CPU1_SA_DQ<15>")
	)
	(segment
		(start 128.196848 -271.011142)
		(end 128.196594 -271.011396)
		(width 0.20066)
		(layer "F.Cu")
		(net "M_G_CPU1_SA_DQ<15>")
	)
	(segment
		(start 131.688078 -270.513302)
		(end 131.673346 -270.521938)
		(width 0.088646)
		(layer "In6.Cu")
		(net "M_G_CPU1_SA_DQ<15>")
	)
	(segment
		(start 185.869326 -296.651426)
		(end 184.472326 -295.254426)
		(width 0.18288)
		(layer "In6.Cu")
		(net "M_G_CPU1_SA_DQ<15>")
	)
	(segment
		(start 179.189126 -293.019226)
		(end 177.412142 -291.242242)
		(width 0.18288)
		(layer "In6.Cu")
		(net "M_G_CPU1_SA_DQ<15>")
	)
	(segment
		(start 168.038526 -289.691826)
		(end 166.547038 -289.691826)
		(width 0.18288)
		(layer "In6.Cu")
		(net "M_G_CPU1_SA_DQ<15>")
	)
	(segment
		(start 128.868678 -270.513302)
		(end 128.853946 -270.521938)
		(width 0.088646)
		(layer "In6.Cu")
		(net "M_G_CPU1_SA_DQ<15>")
	)
	(segment
		(start 128.853946 -270.521938)
		(end 128.84785 -270.525494)
		(width 0.088646)
		(layer "In6.Cu")
		(net "M_G_CPU1_SA_DQ<15>")
	)
	(segment
		(start 142.664434 -271.953736)
		(end 141.643862 -271.53108)
		(width 0.18288)
		(layer "In6.Cu")
		(net "M_G_CPU1_SA_DQ<15>")
	)
	(segment
		(start 182.541926 -294.263826)
		(end 181.068726 -294.263826)
		(width 0.18288)
		(layer "In6.Cu")
		(net "M_G_CPU1_SA_DQ<15>")
	)
	(segment
		(start 166.547038 -289.691826)
		(end 165.511988 -288.656776)
		(width 0.18288)
		(layer "In6.Cu")
		(net "M_G_CPU1_SA_DQ<15>")
	)
	(segment
		(start 127.88392 -271.011396)
		(end 128.196594 -271.011396)
		(width 0.088646)
		(layer "In6.Cu")
		(net "M_G_CPU1_SA_DQ<15>")
	)
	(segment
		(start 129.808478 -270.513302)
		(end 129.793746 -270.521938)
		(width 0.088646)
		(layer "In6.Cu")
		(net "M_G_CPU1_SA_DQ<15>")
	)
	(segment
		(start 165.00729 -288.656776)
		(end 164.654738 -289.009328)
		(width 0.18288)
		(layer "In6.Cu")
		(net "M_G_CPU1_SA_DQ<15>")
	)
	(segment
		(start 183.532526 -295.254426)
		(end 182.541926 -294.263826)
		(width 0.18288)
		(layer "In6.Cu")
		(net "M_G_CPU1_SA_DQ<15>")
	)
	(segment
		(start 184.472326 -295.254426)
		(end 183.532526 -295.254426)
		(width 0.18288)
		(layer "In6.Cu")
		(net "M_G_CPU1_SA_DQ<15>")
	)
	(segment
		(start 177.412142 -291.242242)
		(end 176.667668 -291.242242)
		(width 0.18288)
		(layer "In6.Cu")
		(net "M_G_CPU1_SA_DQ<15>")
	)
	(segment
		(start 173.133258 -290.392358)
		(end 172.481494 -290.392358)
		(width 0.18288)
		(layer "In6.Cu")
		(net "M_G_CPU1_SA_DQ<15>")
	)
	(segment
		(start 164.654738 -289.009328)
		(end 161.487866 -289.009328)
		(width 0.18288)
		(layer "In6.Cu")
		(net "M_G_CPU1_SA_DQ<15>")
	)
	(segment
		(start 133.563106 -270.515842)
		(end 133.552692 -270.521938)
		(width 0.088646)
		(layer "In6.Cu")
		(net "M_G_CPU1_SA_DQ<15>")
	)
	(segment
		(start 157.729682 -288.045906)
		(end 157.008322 -287.324546)
		(width 0.18288)
		(layer "In6.Cu")
		(net "M_G_CPU1_SA_DQ<15>")
	)
	(segment
		(start 172.481494 -290.392358)
		(end 172.318426 -290.555426)
		(width 0.18288)
		(layer "In6.Cu")
		(net "M_G_CPU1_SA_DQ<15>")
	)
	(segment
		(start 134.507478 -270.513302)
		(end 134.492746 -270.521938)
		(width 0.088646)
		(layer "In6.Cu")
		(net "M_G_CPU1_SA_DQ<15>")
	)
	(segment
		(start 140.595604 -271.53108)
		(end 140.48359 -271.53108)
		(width 0.088646)
		(layer "In6.Cu")
		(net "M_G_CPU1_SA_DQ<15>")
	)
	(segment
		(start 176.31664 -291.59327)
		(end 174.33417 -291.59327)
		(width 0.18288)
		(layer "In6.Cu")
		(net "M_G_CPU1_SA_DQ<15>")
	)
	(segment
		(start 140.48359 -271.53108)
		(end 139.836144 -270.883634)
		(width 0.088646)
		(layer "In6.Cu")
		(net "M_G_CPU1_SA_DQ<15>")
	)
	(segment
		(start 137.326878 -270.513302)
		(end 137.312146 -270.521938)
		(width 0.088646)
		(layer "In6.Cu")
		(net "M_G_CPU1_SA_DQ<15>")
	)
	(segment
		(start 128.392682 -271.330674)
		(end 128.383792 -271.335754)
		(width 0.088646)
		(layer "In6.Cu")
		(net "M_G_CPU1_SA_DQ<15>")
	)
	(segment
		(start 161.487866 -289.009328)
		(end 160.524444 -288.045906)
		(width 0.18288)
		(layer "In6.Cu")
		(net "M_G_CPU1_SA_DQ<15>")
	)
	(segment
		(start 138.931142 -270.446246)
		(end 138.534394 -270.446246)
		(width 0.088646)
		(layer "In6.Cu")
		(net "M_G_CPU1_SA_DQ<15>")
	)
	(segment
		(start 172.318426 -290.555426)
		(end 168.902126 -290.555426)
		(width 0.18288)
		(layer "In6.Cu")
		(net "M_G_CPU1_SA_DQ<15>")
	)
	(segment
		(start 191.983614 -298.466764)
		(end 191.558164 -298.892214)
		(width 0.18288)
		(layer "In6.Cu")
		(net "M_G_CPU1_SA_DQ<15>")
	)
	(segment
		(start 157.008322 -279.818338)
		(end 149.14372 -271.953736)
		(width 0.18288)
		(layer "In6.Cu")
		(net "M_G_CPU1_SA_DQ<15>")
	)
	(segment
		(start 186.274202 -298.10329)
		(end 185.869326 -297.698414)
		(width 0.18288)
		(layer "In6.Cu")
		(net "M_G_CPU1_SA_DQ<15>")
	)
	(segment
		(start 176.667668 -291.242242)
		(end 176.31664 -291.59327)
		(width 0.18288)
		(layer "In6.Cu")
		(net "M_G_CPU1_SA_DQ<15>")
	)
	(segment
		(start 149.14372 -271.953736)
		(end 142.664434 -271.953736)
		(width 0.18288)
		(layer "In6.Cu")
		(net "M_G_CPU1_SA_DQ<15>")
	)
	(segment
		(start 139.36853 -270.883634)
		(end 138.931142 -270.446246)
		(width 0.088646)
		(layer "In6.Cu")
		(net "M_G_CPU1_SA_DQ<15>")
	)
	(segment
		(start 135.447278 -270.513302)
		(end 135.432546 -270.521938)
		(width 0.088646)
		(layer "In6.Cu")
		(net "M_G_CPU1_SA_DQ<15>")
	)
	(segment
		(start 165.511988 -288.656776)
		(end 165.00729 -288.656776)
		(width 0.18288)
		(layer "In6.Cu")
		(net "M_G_CPU1_SA_DQ<15>")
	)
	(segment
		(start 127.826516 -271.0688)
		(end 127.88392 -271.011396)
		(width 0.088646)
		(layer "In6.Cu")
		(net "M_G_CPU1_SA_DQ<15>")
	)
	(segment
		(start 179.824126 -293.019226)
		(end 179.189126 -293.019226)
		(width 0.18288)
		(layer "In6.Cu")
		(net "M_G_CPU1_SA_DQ<15>")
	)
	(segment
		(start 157.008322 -287.324546)
		(end 157.008322 -279.818338)
		(width 0.18288)
		(layer "In6.Cu")
		(net "M_G_CPU1_SA_DQ<15>")
	)
	(segment
		(start 174.33417 -291.59327)
		(end 173.133258 -290.392358)
		(width 0.18288)
		(layer "In6.Cu")
		(net "M_G_CPU1_SA_DQ<15>")
	)
	(segment
		(start 186.921902 -298.10329)
		(end 186.274202 -298.10329)
		(width 0.18288)
		(layer "In6.Cu")
		(net "M_G_CPU1_SA_DQ<15>")
	)
	(segment
		(start 191.558164 -298.892214)
		(end 187.710826 -298.892214)
		(width 0.18288)
		(layer "In6.Cu")
		(net "M_G_CPU1_SA_DQ<15>")
	)
	(segment
		(start 185.869326 -297.698414)
		(end 185.869326 -296.651426)
		(width 0.18288)
		(layer "In6.Cu")
		(net "M_G_CPU1_SA_DQ<15>")
	)
	(segment
		(start 136.387078 -270.513302)
		(end 136.372346 -270.521938)
		(width 0.088646)
		(layer "In6.Cu")
		(net "M_G_CPU1_SA_DQ<15>")
	)
	(segment
		(start 141.643862 -271.53108)
		(end 140.595604 -271.53108)
		(width 0.18288)
		(layer "In6.Cu")
		(net "M_G_CPU1_SA_DQ<15>")
	)
	(segment
		(start 130.748278 -270.513302)
		(end 130.733546 -270.521938)
		(width 0.088646)
		(layer "In6.Cu")
		(net "M_G_CPU1_SA_DQ<15>")
	)
	(segment
		(start 132.62356 -270.515842)
		(end 132.613146 -270.521938)
		(width 0.088646)
		(layer "In6.Cu")
		(net "M_G_CPU1_SA_DQ<15>")
	)
	(segment
		(start 181.068726 -294.263826)
		(end 179.824126 -293.019226)
		(width 0.18288)
		(layer "In6.Cu")
		(net "M_G_CPU1_SA_DQ<15>")
	)
	(segment
		(start 128.009396 -271.335754)
		(end 128.000506 -271.330674)
		(width 0.088646)
		(layer "In6.Cu")
		(net "M_G_CPU1_SA_DQ<15>")
	)
	(segment
		(start 187.710826 -298.892214)
		(end 186.921902 -298.10329)
		(width 0.18288)
		(layer "In6.Cu")
		(net "M_G_CPU1_SA_DQ<15>")
	)
	(segment
		(start 168.902126 -290.555426)
		(end 168.038526 -289.691826)
		(width 0.18288)
		(layer "In6.Cu")
		(net "M_G_CPU1_SA_DQ<15>")
	)
	(segment
		(start 139.836144 -270.883634)
		(end 139.36853 -270.883634)
		(width 0.088646)
		(layer "In6.Cu")
		(net "M_G_CPU1_SA_DQ<15>")
	)
	(segment
		(start 160.524444 -288.045906)
		(end 157.729682 -288.045906)
		(width 0.18288)
		(layer "In6.Cu")
		(net "M_G_CPU1_SA_DQ<15>")
	)
	(arc
		(start 130.733546 -270.521938)
		(mid 130.546348 -270.572081)
		(end 130.35915 -270.521938)
		(width 0.088646)
		(layer "In6.Cu")
		(net "M_G_CPU1_SA_DQ<15>")
	)
	(arc
		(start 131.29895 -270.521938)
		(mid 131.024751 -270.446103)
		(end 130.748278 -270.513302)
		(width 0.088646)
		(layer "In6.Cu")
		(net "M_G_CPU1_SA_DQ<15>")
	)
	(arc
		(start 130.35915 -270.521938)
		(mid 130.084951 -270.446103)
		(end 129.808478 -270.513302)
		(width 0.088646)
		(layer "In6.Cu")
		(net "M_G_CPU1_SA_DQ<15>")
	)
	(arc
		(start 134.492746 -270.521938)
		(mid 134.305548 -270.572081)
		(end 134.11835 -270.521938)
		(width 0.088646)
		(layer "In6.Cu")
		(net "M_G_CPU1_SA_DQ<15>")
	)
	(arc
		(start 129.793746 -270.521938)
		(mid 129.606548 -270.572081)
		(end 129.41935 -270.521938)
		(width 0.088646)
		(layer "In6.Cu")
		(net "M_G_CPU1_SA_DQ<15>")
	)
	(arc
		(start 135.05815 -270.521938)
		(mid 134.783951 -270.446103)
		(end 134.507478 -270.513302)
		(width 0.088646)
		(layer "In6.Cu")
		(net "M_G_CPU1_SA_DQ<15>")
	)
	(arc
		(start 134.11835 -270.521938)
		(mid 133.841537 -270.446068)
		(end 133.563106 -270.515842)
		(width 0.088646)
		(layer "In6.Cu")
		(net "M_G_CPU1_SA_DQ<15>")
	)
	(arc
		(start 132.613146 -270.521938)
		(mid 132.425948 -270.572081)
		(end 132.23875 -270.521938)
		(width 0.088646)
		(layer "In6.Cu")
		(net "M_G_CPU1_SA_DQ<15>")
	)
	(arc
		(start 135.99795 -270.521938)
		(mid 135.723751 -270.446103)
		(end 135.447278 -270.513302)
		(width 0.088646)
		(layer "In6.Cu")
		(net "M_G_CPU1_SA_DQ<15>")
	)
	(arc
		(start 129.41935 -270.521938)
		(mid 129.145151 -270.446103)
		(end 128.868678 -270.513302)
		(width 0.088646)
		(layer "In6.Cu")
		(net "M_G_CPU1_SA_DQ<15>")
	)
	(arc
		(start 138.251946 -270.521938)
		(mid 138.064748 -270.572081)
		(end 137.87755 -270.521938)
		(width 0.088646)
		(layer "In6.Cu")
		(net "M_G_CPU1_SA_DQ<15>")
	)
	(arc
		(start 128.383792 -271.335754)
		(mid 128.196594 -271.385897)
		(end 128.009396 -271.335754)
		(width 0.088646)
		(layer "In6.Cu")
		(net "M_G_CPU1_SA_DQ<15>")
	)
	(arc
		(start 128.571244 -271.011396)
		(mid 128.523565 -271.194296)
		(end 128.392682 -271.330674)
		(width 0.088646)
		(layer "In6.Cu")
		(net "M_G_CPU1_SA_DQ<15>")
	)
	(arc
		(start 138.534394 -270.446246)
		(mid 138.388186 -270.465495)
		(end 138.251946 -270.521938)
		(width 0.088646)
		(layer "In6.Cu")
		(net "M_G_CPU1_SA_DQ<15>")
	)
	(arc
		(start 137.312146 -270.521938)
		(mid 137.124948 -270.572081)
		(end 136.93775 -270.521938)
		(width 0.088646)
		(layer "In6.Cu")
		(net "M_G_CPU1_SA_DQ<15>")
	)
	(arc
		(start 131.673346 -270.521938)
		(mid 131.486148 -270.572081)
		(end 131.29895 -270.521938)
		(width 0.088646)
		(layer "In6.Cu")
		(net "M_G_CPU1_SA_DQ<15>")
	)
	(arc
		(start 128.84785 -270.525494)
		(mid 128.645263 -270.731845)
		(end 128.571244 -271.011396)
		(width 0.088646)
		(layer "In6.Cu")
		(net "M_G_CPU1_SA_DQ<15>")
	)
	(arc
		(start 133.178296 -270.521938)
		(mid 132.901737 -270.446195)
		(end 132.62356 -270.515842)
		(width 0.088646)
		(layer "In6.Cu")
		(net "M_G_CPU1_SA_DQ<15>")
	)
	(arc
		(start 137.87755 -270.521938)
		(mid 137.603351 -270.446103)
		(end 137.326878 -270.513302)
		(width 0.088646)
		(layer "In6.Cu")
		(net "M_G_CPU1_SA_DQ<15>")
	)
	(arc
		(start 128.000506 -271.330674)
		(mid 127.884767 -271.21885)
		(end 127.826516 -271.0688)
		(width 0.088646)
		(layer "In6.Cu")
		(net "M_G_CPU1_SA_DQ<15>")
	)
	(arc
		(start 136.372346 -270.521938)
		(mid 136.185148 -270.572081)
		(end 135.99795 -270.521938)
		(width 0.088646)
		(layer "In6.Cu")
		(net "M_G_CPU1_SA_DQ<15>")
	)
	(arc
		(start 133.552692 -270.521938)
		(mid 133.365494 -270.572081)
		(end 133.178296 -270.521938)
		(width 0.088646)
		(layer "In6.Cu")
		(net "M_G_CPU1_SA_DQ<15>")
	)
	(arc
		(start 136.93775 -270.521938)
		(mid 136.663551 -270.446103)
		(end 136.387078 -270.513302)
		(width 0.088646)
		(layer "In6.Cu")
		(net "M_G_CPU1_SA_DQ<15>")
	)
	(arc
		(start 132.23875 -270.521938)
		(mid 131.964551 -270.446103)
		(end 131.688078 -270.513302)
		(width 0.088646)
		(layer "In6.Cu")
		(net "M_G_CPU1_SA_DQ<15>")
	)
	(arc
		(start 135.432546 -270.521938)
		(mid 135.245348 -270.572081)
		(end 135.05815 -270.521938)
		(width 0.088646)
		(layer "In6.Cu")
		(net "M_G_CPU1_SA_DQ<15>")
	)
	(segment
		(start 128.666494 -271.289272)
		(end 128.666748 -271.825212)
		(width 0.20066)
		(layer "F.Cu")
		(net "M_G_CPU1_SA_DQ<14>")
	)
	(segment
		(start 198.223886 -300.60392)
		(end 198.427848 -300.399958)
		(width 0.20066)
		(layer "F.Cu")
		(net "M_G_CPU1_SA_DQ<14>")
	)
	(segment
		(start 195.522596 -300.591728)
		(end 197.530466 -300.591728)
		(width 0.1016)
		(layer "F.Cu")
		(net "M_G_CPU1_SA_DQ<14>")
	)
	(segment
		(start 199.046084 -299.914818)
		(end 199.298052 -300.166786)
		(width 0.20066)
		(layer "F.Cu")
		(net "M_G_CPU1_SA_DQ<14>")
	)
	(segment
		(start 199.298052 -300.166786)
		(end 200.632314 -300.166786)
		(width 0.20066)
		(layer "F.Cu")
		(net "M_G_CPU1_SA_DQ<14>")
	)
	(segment
		(start 197.530466 -300.591728)
		(end 197.542658 -300.60392)
		(width 0.1016)
		(layer "F.Cu")
		(net "M_G_CPU1_SA_DQ<14>")
	)
	(segment
		(start 195.510658 -300.59884)
		(end 195.515484 -300.59884)
		(width 0.101854)
		(layer "F.Cu")
		(net "M_G_CPU1_SA_DQ<14>")
	)
	(segment
		(start 197.542658 -300.60392)
		(end 198.223886 -300.60392)
		(width 0.20066)
		(layer "F.Cu")
		(net "M_G_CPU1_SA_DQ<14>")
	)
	(segment
		(start 198.427848 -300.399958)
		(end 198.427848 -300.149006)
		(width 0.20066)
		(layer "F.Cu")
		(net "M_G_CPU1_SA_DQ<14>")
	)
	(segment
		(start 198.427848 -300.149006)
		(end 198.662036 -299.914818)
		(width 0.20066)
		(layer "F.Cu")
		(net "M_G_CPU1_SA_DQ<14>")
	)
	(segment
		(start 198.662036 -299.914818)
		(end 199.046084 -299.914818)
		(width 0.20066)
		(layer "F.Cu")
		(net "M_G_CPU1_SA_DQ<14>")
	)
	(segment
		(start 195.218812 -300.59884)
		(end 195.510658 -300.59884)
		(width 0.20066)
		(layer "F.Cu")
		(net "M_G_CPU1_SA_DQ<14>")
	)
	(segment
		(start 191.941704 -300.166786)
		(end 193.088514 -300.166786)
		(width 0.20066)
		(layer "F.Cu")
		(net "M_G_CPU1_SA_DQ<14>")
	)
	(segment
		(start 193.088514 -300.166786)
		(end 194.786758 -300.166786)
		(width 0.20066)
		(layer "F.Cu")
		(net "M_G_CPU1_SA_DQ<14>")
	)
	(segment
		(start 194.786758 -300.166786)
		(end 195.218812 -300.59884)
		(width 0.20066)
		(layer "F.Cu")
		(net "M_G_CPU1_SA_DQ<14>")
	)
	(segment
		(start 195.515484 -300.59884)
		(end 195.522596 -300.591728)
		(width 0.1016)
		(layer "F.Cu")
		(net "M_G_CPU1_SA_DQ<14>")
	)
	(segment
		(start 159.191452 -289.489896)
		(end 159.191452 -289.489642)
		(width 0.18288)
		(layer "In6.Cu")
		(net "M_G_CPU1_SA_DQ<14>")
	)
	(segment
		(start 132.149088 -271.332452)
		(end 132.143246 -271.336008)
		(width 0.088646)
		(layer "In6.Cu")
		(net "M_G_CPU1_SA_DQ<14>")
	)
	(segment
		(start 158.371032 -289.642296)
		(end 157.63748 -289.642296)
		(width 0.18288)
		(layer "In6.Cu")
		(net "M_G_CPU1_SA_DQ<14>")
	)
	(segment
		(start 132.143246 -271.336008)
		(end 132.137404 -271.33931)
		(width 0.088646)
		(layer "In6.Cu")
		(net "M_G_CPU1_SA_DQ<14>")
	)
	(segment
		(start 164.518086 -290.453826)
		(end 161.036254 -290.453826)
		(width 0.18288)
		(layer "In6.Cu")
		(net "M_G_CPU1_SA_DQ<14>")
	)
	(segment
		(start 140.27785 -272.533364)
		(end 139.569698 -271.825212)
		(width 0.088646)
		(layer "In6.Cu")
		(net "M_G_CPU1_SA_DQ<14>")
	)
	(segment
		(start 141.453616 -272.533364)
		(end 140.595604 -272.533364)
		(width 0.18288)
		(layer "In6.Cu")
		(net "M_G_CPU1_SA_DQ<14>")
	)
	(segment
		(start 142.458186 -272.949416)
		(end 141.453616 -272.533364)
		(width 0.18288)
		(layer "In6.Cu")
		(net "M_G_CPU1_SA_DQ<14>")
	)
	(segment
		(start 160.232344 -289.649916)
		(end 159.351472 -289.649916)
		(width 0.18288)
		(layer "In6.Cu")
		(net "M_G_CPU1_SA_DQ<14>")
	)
	(segment
		(start 133.088888 -271.332452)
		(end 133.083046 -271.336008)
		(width 0.088646)
		(layer "In6.Cu")
		(net "M_G_CPU1_SA_DQ<14>")
	)
	(segment
		(start 137.407396 -271.335754)
		(end 137.392664 -271.327118)
		(width 0.088646)
		(layer "In6.Cu")
		(net "M_G_CPU1_SA_DQ<14>")
	)
	(segment
		(start 140.595604 -272.533364)
		(end 140.27785 -272.533364)
		(width 0.088646)
		(layer "In6.Cu")
		(net "M_G_CPU1_SA_DQ<14>")
	)
	(segment
		(start 131.209288 -271.332452)
		(end 131.203446 -271.336008)
		(width 0.088646)
		(layer "In6.Cu")
		(net "M_G_CPU1_SA_DQ<14>")
	)
	(segment
		(start 158.683452 -289.329622)
		(end 158.523432 -289.489642)
		(width 0.18288)
		(layer "In6.Cu")
		(net "M_G_CPU1_SA_DQ<14>")
	)
	(segment
		(start 165.702742 -290.263072)
		(end 164.70884 -290.263072)
		(width 0.18288)
		(layer "In6.Cu")
		(net "M_G_CPU1_SA_DQ<14>")
	)
	(segment
		(start 180.763926 -295.610026)
		(end 180.205126 -295.610026)
		(width 0.18288)
		(layer "In6.Cu")
		(net "M_G_CPU1_SA_DQ<14>")
	)
	(segment
		(start 136.467596 -271.335754)
		(end 136.452864 -271.327118)
		(width 0.088646)
		(layer "In6.Cu")
		(net "M_G_CPU1_SA_DQ<14>")
	)
	(segment
		(start 134.028688 -271.332452)
		(end 134.022846 -271.336008)
		(width 0.088646)
		(layer "In6.Cu")
		(net "M_G_CPU1_SA_DQ<14>")
	)
	(segment
		(start 167.774112 -291.316156)
		(end 166.755826 -291.316156)
		(width 0.18288)
		(layer "In6.Cu")
		(net "M_G_CPU1_SA_DQ<14>")
	)
	(segment
		(start 189.457584 -300.43247)
		(end 189.457584 -300.125892)
		(width 0.18288)
		(layer "In6.Cu")
		(net "M_G_CPU1_SA_DQ<14>")
	)
	(segment
		(start 135.902192 -271.335754)
		(end 135.902446 -271.336008)
		(width 0.088646)
		(layer "In6.Cu")
		(net "M_G_CPU1_SA_DQ<14>")
	)
	(segment
		(start 180.205126 -295.610026)
		(end 179.275994 -294.680894)
		(width 0.18288)
		(layer "In6.Cu")
		(net "M_G_CPU1_SA_DQ<14>")
	)
	(segment
		(start 184.142126 -298.226226)
		(end 183.253126 -297.337226)
		(width 0.18288)
		(layer "In6.Cu")
		(net "M_G_CPU1_SA_DQ<14>")
	)
	(segment
		(start 158.523432 -289.489896)
		(end 158.371032 -289.642296)
		(width 0.18288)
		(layer "In6.Cu")
		(net "M_G_CPU1_SA_DQ<14>")
	)
	(segment
		(start 183.253126 -297.337226)
		(end 182.491126 -297.337226)
		(width 0.18288)
		(layer "In6.Cu")
		(net "M_G_CPU1_SA_DQ<14>")
	)
	(segment
		(start 148.731224 -272.949416)
		(end 142.458186 -272.949416)
		(width 0.18288)
		(layer "In6.Cu")
		(net "M_G_CPU1_SA_DQ<14>")
	)
	(segment
		(start 161.036254 -290.453826)
		(end 160.232344 -289.649916)
		(width 0.18288)
		(layer "In6.Cu")
		(net "M_G_CPU1_SA_DQ<14>")
	)
	(segment
		(start 159.031432 -289.329622)
		(end 158.683452 -289.329622)
		(width 0.18288)
		(layer "In6.Cu")
		(net "M_G_CPU1_SA_DQ<14>")
	)
	(segment
		(start 191.941704 -300.166786)
		(end 191.516 -300.59249)
		(width 0.18288)
		(layer "In6.Cu")
		(net "M_G_CPU1_SA_DQ<14>")
	)
	(segment
		(start 166.755826 -291.316156)
		(end 165.702742 -290.263072)
		(width 0.18288)
		(layer "In6.Cu")
		(net "M_G_CPU1_SA_DQ<14>")
	)
	(segment
		(start 129.329688 -271.332452)
		(end 129.280666 -271.360138)
		(width 0.088646)
		(layer "In6.Cu")
		(net "M_G_CPU1_SA_DQ<14>")
	)
	(segment
		(start 169.40022 -292.942264)
		(end 167.774112 -291.316156)
		(width 0.18288)
		(layer "In6.Cu")
		(net "M_G_CPU1_SA_DQ<14>")
	)
	(segment
		(start 184.751726 -298.226226)
		(end 184.142126 -298.226226)
		(width 0.18288)
		(layer "In6.Cu")
		(net "M_G_CPU1_SA_DQ<14>")
	)
	(segment
		(start 178.11369 -294.680894)
		(end 177.224944 -293.792148)
		(width 0.18288)
		(layer "In6.Cu")
		(net "M_G_CPU1_SA_DQ<14>")
	)
	(segment
		(start 177.224944 -293.792148)
		(end 174.780448 -293.792148)
		(width 0.18288)
		(layer "In6.Cu")
		(net "M_G_CPU1_SA_DQ<14>")
	)
	(segment
		(start 134.966456 -271.333722)
		(end 134.962646 -271.336008)
		(width 0.088646)
		(layer "In6.Cu")
		(net "M_G_CPU1_SA_DQ<14>")
	)
	(segment
		(start 158.523432 -289.489642)
		(end 158.523432 -289.489896)
		(width 0.18288)
		(layer "In6.Cu")
		(net "M_G_CPU1_SA_DQ<14>")
	)
	(segment
		(start 189.297564 -299.965872)
		(end 188.924184 -299.965872)
		(width 0.18288)
		(layer "In6.Cu")
		(net "M_G_CPU1_SA_DQ<14>")
	)
	(segment
		(start 172.547026 -292.092126)
		(end 171.696888 -292.942264)
		(width 0.18288)
		(layer "In6.Cu")
		(net "M_G_CPU1_SA_DQ<14>")
	)
	(segment
		(start 164.70884 -290.263072)
		(end 164.518086 -290.453826)
		(width 0.18288)
		(layer "In6.Cu")
		(net "M_G_CPU1_SA_DQ<14>")
	)
	(segment
		(start 130.269488 -271.332452)
		(end 130.263646 -271.336008)
		(width 0.088646)
		(layer "In6.Cu")
		(net "M_G_CPU1_SA_DQ<14>")
	)
	(segment
		(start 173.080426 -292.092126)
		(end 172.547026 -292.092126)
		(width 0.18288)
		(layer "In6.Cu")
		(net "M_G_CPU1_SA_DQ<14>")
	)
	(segment
		(start 187.000388 -299.882814)
		(end 186.408314 -299.882814)
		(width 0.18288)
		(layer "In6.Cu")
		(net "M_G_CPU1_SA_DQ<14>")
	)
	(segment
		(start 189.457584 -300.125892)
		(end 189.297564 -299.965872)
		(width 0.18288)
		(layer "In6.Cu")
		(net "M_G_CPU1_SA_DQ<14>")
	)
	(segment
		(start 156.012642 -288.017458)
		(end 156.012642 -280.230834)
		(width 0.18288)
		(layer "In6.Cu")
		(net "M_G_CPU1_SA_DQ<14>")
	)
	(segment
		(start 188.764164 -300.43247)
		(end 188.603128 -300.593506)
		(width 0.18288)
		(layer "In6.Cu")
		(net "M_G_CPU1_SA_DQ<14>")
	)
	(segment
		(start 189.617604 -300.59249)
		(end 189.457584 -300.43247)
		(width 0.18288)
		(layer "In6.Cu")
		(net "M_G_CPU1_SA_DQ<14>")
	)
	(segment
		(start 138.347196 -271.335754)
		(end 138.332464 -271.327118)
		(width 0.088646)
		(layer "In6.Cu")
		(net "M_G_CPU1_SA_DQ<14>")
	)
	(segment
		(start 131.203446 -271.336008)
		(end 131.197604 -271.33931)
		(width 0.088646)
		(layer "In6.Cu")
		(net "M_G_CPU1_SA_DQ<14>")
	)
	(segment
		(start 188.603128 -300.593506)
		(end 187.71108 -300.593506)
		(width 0.18288)
		(layer "In6.Cu")
		(net "M_G_CPU1_SA_DQ<14>")
	)
	(segment
		(start 133.083046 -271.336008)
		(end 133.077204 -271.33931)
		(width 0.088646)
		(layer "In6.Cu")
		(net "M_G_CPU1_SA_DQ<14>")
	)
	(segment
		(start 159.351472 -289.649916)
		(end 159.191452 -289.489896)
		(width 0.18288)
		(layer "In6.Cu")
		(net "M_G_CPU1_SA_DQ<14>")
	)
	(segment
		(start 130.263646 -271.336008)
		(end 130.257804 -271.33931)
		(width 0.088646)
		(layer "In6.Cu")
		(net "M_G_CPU1_SA_DQ<14>")
	)
	(segment
		(start 174.780448 -293.792148)
		(end 173.080426 -292.092126)
		(width 0.18288)
		(layer "In6.Cu")
		(net "M_G_CPU1_SA_DQ<14>")
	)
	(segment
		(start 187.71108 -300.593506)
		(end 187.000388 -299.882814)
		(width 0.18288)
		(layer "In6.Cu")
		(net "M_G_CPU1_SA_DQ<14>")
	)
	(segment
		(start 156.012642 -280.230834)
		(end 148.731224 -272.949416)
		(width 0.18288)
		(layer "In6.Cu")
		(net "M_G_CPU1_SA_DQ<14>")
	)
	(segment
		(start 179.275994 -294.680894)
		(end 178.11369 -294.680894)
		(width 0.18288)
		(layer "In6.Cu")
		(net "M_G_CPU1_SA_DQ<14>")
	)
	(segment
		(start 134.962646 -271.336008)
		(end 134.956804 -271.33931)
		(width 0.088646)
		(layer "In6.Cu")
		(net "M_G_CPU1_SA_DQ<14>")
	)
	(segment
		(start 188.924184 -299.965872)
		(end 188.764164 -300.125892)
		(width 0.18288)
		(layer "In6.Cu")
		(net "M_G_CPU1_SA_DQ<14>")
	)
	(segment
		(start 191.516 -300.59249)
		(end 189.617604 -300.59249)
		(width 0.18288)
		(layer "In6.Cu")
		(net "M_G_CPU1_SA_DQ<14>")
	)
	(segment
		(start 182.491126 -297.337226)
		(end 180.763926 -295.610026)
		(width 0.18288)
		(layer "In6.Cu")
		(net "M_G_CPU1_SA_DQ<14>")
	)
	(segment
		(start 186.408314 -299.882814)
		(end 184.751726 -298.226226)
		(width 0.18288)
		(layer "In6.Cu")
		(net "M_G_CPU1_SA_DQ<14>")
	)
	(segment
		(start 171.696888 -292.942264)
		(end 169.40022 -292.942264)
		(width 0.18288)
		(layer "In6.Cu")
		(net "M_G_CPU1_SA_DQ<14>")
	)
	(segment
		(start 159.191452 -289.489642)
		(end 159.031432 -289.329622)
		(width 0.18288)
		(layer "In6.Cu")
		(net "M_G_CPU1_SA_DQ<14>")
	)
	(segment
		(start 134.022846 -271.336008)
		(end 134.017004 -271.33931)
		(width 0.088646)
		(layer "In6.Cu")
		(net "M_G_CPU1_SA_DQ<14>")
	)
	(segment
		(start 188.764164 -300.125892)
		(end 188.764164 -300.43247)
		(width 0.18288)
		(layer "In6.Cu")
		(net "M_G_CPU1_SA_DQ<14>")
	)
	(segment
		(start 157.63748 -289.642296)
		(end 156.012642 -288.017458)
		(width 0.18288)
		(layer "In6.Cu")
		(net "M_G_CPU1_SA_DQ<14>")
	)
	(arc
		(start 133.648196 -271.336008)
		(mid 133.369022 -271.260209)
		(end 133.088888 -271.332452)
		(width 0.088646)
		(layer "In6.Cu")
		(net "M_G_CPU1_SA_DQ<14>")
	)
	(arc
		(start 136.841992 -271.335754)
		(mid 136.654794 -271.385897)
		(end 136.467596 -271.335754)
		(width 0.088646)
		(layer "In6.Cu")
		(net "M_G_CPU1_SA_DQ<14>")
	)
	(arc
		(start 130.828796 -271.336008)
		(mid 130.549622 -271.260209)
		(end 130.269488 -271.332452)
		(width 0.088646)
		(layer "In6.Cu")
		(net "M_G_CPU1_SA_DQ<14>")
	)
	(arc
		(start 138.332464 -271.327118)
		(mid 138.055989 -271.259798)
		(end 137.781792 -271.335754)
		(width 0.088646)
		(layer "In6.Cu")
		(net "M_G_CPU1_SA_DQ<14>")
	)
	(arc
		(start 130.257804 -271.33931)
		(mid 130.072949 -271.38626)
		(end 129.888996 -271.336008)
		(width 0.088646)
		(layer "In6.Cu")
		(net "M_G_CPU1_SA_DQ<14>")
	)
	(arc
		(start 131.197604 -271.33931)
		(mid 131.012749 -271.38626)
		(end 130.828796 -271.336008)
		(width 0.088646)
		(layer "In6.Cu")
		(net "M_G_CPU1_SA_DQ<14>")
	)
	(arc
		(start 138.721592 -271.335754)
		(mid 138.534394 -271.385897)
		(end 138.347196 -271.335754)
		(width 0.088646)
		(layer "In6.Cu")
		(net "M_G_CPU1_SA_DQ<14>")
	)
	(arc
		(start 137.781792 -271.335754)
		(mid 137.594594 -271.385897)
		(end 137.407396 -271.335754)
		(width 0.088646)
		(layer "In6.Cu")
		(net "M_G_CPU1_SA_DQ<14>")
	)
	(arc
		(start 134.017004 -271.33931)
		(mid 133.832149 -271.38626)
		(end 133.648196 -271.336008)
		(width 0.088646)
		(layer "In6.Cu")
		(net "M_G_CPU1_SA_DQ<14>")
	)
	(arc
		(start 137.392664 -271.327118)
		(mid 137.116189 -271.259798)
		(end 136.841992 -271.335754)
		(width 0.088646)
		(layer "In6.Cu")
		(net "M_G_CPU1_SA_DQ<14>")
	)
	(arc
		(start 132.708396 -271.336008)
		(mid 132.429222 -271.260209)
		(end 132.149088 -271.332452)
		(width 0.088646)
		(layer "In6.Cu")
		(net "M_G_CPU1_SA_DQ<14>")
	)
	(arc
		(start 139.569698 -271.825212)
		(mid 139.286985 -271.335698)
		(end 138.721592 -271.335754)
		(width 0.088646)
		(layer "In6.Cu")
		(net "M_G_CPU1_SA_DQ<14>")
	)
	(arc
		(start 132.137404 -271.33931)
		(mid 131.952549 -271.38626)
		(end 131.768596 -271.336008)
		(width 0.088646)
		(layer "In6.Cu")
		(net "M_G_CPU1_SA_DQ<14>")
	)
	(arc
		(start 134.956804 -271.33931)
		(mid 134.771949 -271.38626)
		(end 134.587996 -271.336008)
		(width 0.088646)
		(layer "In6.Cu")
		(net "M_G_CPU1_SA_DQ<14>")
	)
	(arc
		(start 129.888996 -271.336008)
		(mid 129.609822 -271.260209)
		(end 129.329688 -271.332452)
		(width 0.088646)
		(layer "In6.Cu")
		(net "M_G_CPU1_SA_DQ<14>")
	)
	(arc
		(start 136.452864 -271.327118)
		(mid 136.176389 -271.259798)
		(end 135.902192 -271.335754)
		(width 0.088646)
		(layer "In6.Cu")
		(net "M_G_CPU1_SA_DQ<14>")
	)
	(arc
		(start 134.587996 -271.336008)
		(mid 134.308822 -271.260209)
		(end 134.028688 -271.332452)
		(width 0.088646)
		(layer "In6.Cu")
		(net "M_G_CPU1_SA_DQ<14>")
	)
	(arc
		(start 129.280666 -271.360138)
		(mid 128.95808 -271.572047)
		(end 128.666748 -271.825212)
		(width 0.088646)
		(layer "In6.Cu")
		(net "M_G_CPU1_SA_DQ<14>")
	)
	(arc
		(start 135.902446 -271.336008)
		(mid 135.715138 -271.386151)
		(end 135.527796 -271.336008)
		(width 0.088646)
		(layer "In6.Cu")
		(net "M_G_CPU1_SA_DQ<14>")
	)
	(arc
		(start 133.077204 -271.33931)
		(mid 132.892349 -271.38626)
		(end 132.708396 -271.336008)
		(width 0.088646)
		(layer "In6.Cu")
		(net "M_G_CPU1_SA_DQ<14>")
	)
	(arc
		(start 131.768596 -271.336008)
		(mid 131.489422 -271.260209)
		(end 131.209288 -271.332452)
		(width 0.088646)
		(layer "In6.Cu")
		(net "M_G_CPU1_SA_DQ<14>")
	)
	(arc
		(start 135.527796 -271.336008)
		(mid 135.247425 -271.260203)
		(end 134.966456 -271.333722)
		(width 0.088646)
		(layer "In6.Cu")
		(net "M_G_CPU1_SA_DQ<14>")
	)
	(segment
		(start 194.098926 -298.885356)
		(end 194.092576 -298.891706)
		(width 0.1016)
		(layer "F.Cu")
		(net "M_G_CPU1_SA_DQ<13>")
	)
	(segment
		(start 127.257048 -271.011142)
		(end 127.256794 -271.011396)
		(width 0.20066)
		(layer "F.Cu")
		(net "M_G_CPU1_SA_DQ<13>")
	)
	(segment
		(start 191.883792 -298.891706)
		(end 191.539114 -298.891706)
		(width 0.20066)
		(layer "F.Cu")
		(net "M_G_CPU1_SA_DQ<13>")
	)
	(segment
		(start 190.75781 -299.565314)
		(end 190.509144 -299.316648)
		(width 0.20066)
		(layer "F.Cu")
		(net "M_G_CPU1_SA_DQ<13>")
	)
	(segment
		(start 191.233044 -299.565314)
		(end 190.75781 -299.565314)
		(width 0.20066)
		(layer "F.Cu")
		(net "M_G_CPU1_SA_DQ<13>")
	)
	(segment
		(start 196.532246 -299.316648)
		(end 196.531992 -299.316902)
		(width 0.20066)
		(layer "F.Cu")
		(net "M_G_CPU1_SA_DQ<13>")
	)
	(segment
		(start 190.509144 -299.316648)
		(end 188.988446 -299.316648)
		(width 0.20066)
		(layer "F.Cu")
		(net "M_G_CPU1_SA_DQ<13>")
	)
	(segment
		(start 196.531992 -299.316902)
		(end 194.940428 -299.316902)
		(width 0.20066)
		(layer "F.Cu")
		(net "M_G_CPU1_SA_DQ<13>")
	)
	(segment
		(start 194.940428 -299.316902)
		(end 194.508882 -298.885356)
		(width 0.20066)
		(layer "F.Cu")
		(net "M_G_CPU1_SA_DQ<13>")
	)
	(segment
		(start 191.421004 -299.009816)
		(end 191.421004 -299.377354)
		(width 0.20066)
		(layer "F.Cu")
		(net "M_G_CPU1_SA_DQ<13>")
	)
	(segment
		(start 188.988446 -299.316648)
		(end 187.883546 -299.316648)
		(width 0.20066)
		(layer "F.Cu")
		(net "M_G_CPU1_SA_DQ<13>")
	)
	(segment
		(start 194.508882 -298.885356)
		(end 194.098926 -298.885356)
		(width 0.20066)
		(layer "F.Cu")
		(net "M_G_CPU1_SA_DQ<13>")
	)
	(segment
		(start 127.257048 -270.475456)
		(end 127.257048 -271.011142)
		(width 0.20066)
		(layer "F.Cu")
		(net "M_G_CPU1_SA_DQ<13>")
	)
	(segment
		(start 191.903858 -298.891706)
		(end 191.883792 -298.891706)
		(width 0.101854)
		(layer "F.Cu")
		(net "M_G_CPU1_SA_DQ<13>")
	)
	(segment
		(start 194.092576 -298.891706)
		(end 191.903858 -298.891706)
		(width 0.1016)
		(layer "F.Cu")
		(net "M_G_CPU1_SA_DQ<13>")
	)
	(segment
		(start 191.421004 -299.377354)
		(end 191.233044 -299.565314)
		(width 0.20066)
		(layer "F.Cu")
		(net "M_G_CPU1_SA_DQ<13>")
	)
	(segment
		(start 191.539114 -298.891706)
		(end 191.421004 -299.009816)
		(width 0.20066)
		(layer "F.Cu")
		(net "M_G_CPU1_SA_DQ<13>")
	)
	(segment
		(start 165.828472 -289.678872)
		(end 164.798756 -289.678872)
		(width 0.18288)
		(layer "In6.Cu")
		(net "M_G_CPU1_SA_DQ<13>")
	)
	(segment
		(start 164.63518 -289.515296)
		(end 161.09061 -289.515296)
		(width 0.18288)
		(layer "In6.Cu")
		(net "M_G_CPU1_SA_DQ<13>")
	)
	(segment
		(start 178.290982 -293.170102)
		(end 177.928778 -293.532306)
		(width 0.18288)
		(layer "In6.Cu")
		(net "M_G_CPU1_SA_DQ<13>")
	)
	(segment
		(start 177.928778 -293.532306)
		(end 177.670206 -293.532306)
		(width 0.18288)
		(layer "In6.Cu")
		(net "M_G_CPU1_SA_DQ<13>")
	)
	(segment
		(start 141.537944 -272.029174)
		(end 140.595604 -272.029174)
		(width 0.18288)
		(layer "In6.Cu")
		(net "M_G_CPU1_SA_DQ<13>")
	)
	(segment
		(start 142.557754 -272.451576)
		(end 141.537944 -272.029174)
		(width 0.18288)
		(layer "In6.Cu")
		(net "M_G_CPU1_SA_DQ<13>")
	)
	(segment
		(start 156.510482 -287.531048)
		(end 156.510482 -280.024586)
		(width 0.18288)
		(layer "In6.Cu")
		(net "M_G_CPU1_SA_DQ<13>")
	)
	(segment
		(start 177.471832 -292.09238)
		(end 176.14138 -292.09238)
		(width 0.18288)
		(layer "In6.Cu")
		(net "M_G_CPU1_SA_DQ<13>")
	)
	(segment
		(start 157.54731 -288.567876)
		(end 156.510482 -287.531048)
		(width 0.18288)
		(layer "In6.Cu")
		(net "M_G_CPU1_SA_DQ<13>")
	)
	(segment
		(start 186.221878 -298.841414)
		(end 185.310526 -297.930062)
		(width 0.18288)
		(layer "In6.Cu")
		(net "M_G_CPU1_SA_DQ<13>")
	)
	(segment
		(start 160.14319 -288.567876)
		(end 157.54731 -288.567876)
		(width 0.18288)
		(layer "In6.Cu")
		(net "M_G_CPU1_SA_DQ<13>")
	)
	(segment
		(start 187.883546 -299.316648)
		(end 187.30976 -299.316648)
		(width 0.18288)
		(layer "In6.Cu")
		(net "M_G_CPU1_SA_DQ<13>")
	)
	(segment
		(start 170.681904 -292.377368)
		(end 170.354244 -292.377368)
		(width 0.18288)
		(layer "In6.Cu")
		(net "M_G_CPU1_SA_DQ<13>")
	)
	(segment
		(start 136.467596 -270.687038)
		(end 136.452864 -270.695674)
		(width 0.088646)
		(layer "In6.Cu")
		(net "M_G_CPU1_SA_DQ<13>")
	)
	(segment
		(start 182.694326 -296.092626)
		(end 182.186326 -296.092626)
		(width 0.18288)
		(layer "In6.Cu")
		(net "M_G_CPU1_SA_DQ<13>")
	)
	(segment
		(start 127.914146 -271.500854)
		(end 127.90805 -271.497298)
		(width 0.088646)
		(layer "In6.Cu")
		(net "M_G_CPU1_SA_DQ<13>")
	)
	(segment
		(start 184.777126 -296.854626)
		(end 183.456326 -296.854626)
		(width 0.18288)
		(layer "In6.Cu")
		(net "M_G_CPU1_SA_DQ<13>")
	)
	(segment
		(start 178.549554 -293.170102)
		(end 178.290982 -293.170102)
		(width 0.18288)
		(layer "In6.Cu")
		(net "M_G_CPU1_SA_DQ<13>")
	)
	(segment
		(start 175.742346 -293.169086)
		(end 175.097186 -293.169086)
		(width 0.18288)
		(layer "In6.Cu")
		(net "M_G_CPU1_SA_DQ<13>")
	)
	(segment
		(start 130.828796 -270.687038)
		(end 130.814064 -270.695674)
		(width 0.088646)
		(layer "In6.Cu")
		(net "M_G_CPU1_SA_DQ<13>")
	)
	(segment
		(start 187.30976 -299.316648)
		(end 186.834526 -298.841414)
		(width 0.18288)
		(layer "In6.Cu")
		(net "M_G_CPU1_SA_DQ<13>")
	)
	(segment
		(start 169.988484 -291.239702)
		(end 168.804082 -291.239702)
		(width 0.18288)
		(layer "In6.Cu")
		(net "M_G_CPU1_SA_DQ<13>")
	)
	(segment
		(start 161.09061 -289.515296)
		(end 160.14319 -288.567876)
		(width 0.18288)
		(layer "In6.Cu")
		(net "M_G_CPU1_SA_DQ<13>")
	)
	(segment
		(start 177.438304 -293.300404)
		(end 177.438304 -293.041832)
		(width 0.18288)
		(layer "In6.Cu")
		(net "M_G_CPU1_SA_DQ<13>")
	)
	(segment
		(start 179.671726 -293.578026)
		(end 178.957478 -293.578026)
		(width 0.18288)
		(layer "In6.Cu")
		(net "M_G_CPU1_SA_DQ<13>")
	)
	(segment
		(start 170.864784 -291.422582)
		(end 170.864784 -292.194488)
		(width 0.18288)
		(layer "In6.Cu")
		(net "M_G_CPU1_SA_DQ<13>")
	)
	(segment
		(start 140.595604 -272.029174)
		(end 140.436854 -272.029174)
		(width 0.088646)
		(layer "In6.Cu")
		(net "M_G_CPU1_SA_DQ<13>")
	)
	(segment
		(start 134.587996 -270.687038)
		(end 134.573264 -270.695674)
		(width 0.088646)
		(layer "In6.Cu")
		(net "M_G_CPU1_SA_DQ<13>")
	)
	(segment
		(start 167.840406 -290.276026)
		(end 166.425626 -290.276026)
		(width 0.18288)
		(layer "In6.Cu")
		(net "M_G_CPU1_SA_DQ<13>")
	)
	(segment
		(start 185.310526 -297.388026)
		(end 184.777126 -296.854626)
		(width 0.18288)
		(layer "In6.Cu")
		(net "M_G_CPU1_SA_DQ<13>")
	)
	(segment
		(start 177.438304 -293.041832)
		(end 177.800508 -292.679628)
		(width 0.18288)
		(layer "In6.Cu")
		(net "M_G_CPU1_SA_DQ<13>")
	)
	(segment
		(start 156.510482 -280.024586)
		(end 148.937472 -272.451576)
		(width 0.18288)
		(layer "In6.Cu")
		(net "M_G_CPU1_SA_DQ<13>")
	)
	(segment
		(start 178.957478 -293.578026)
		(end 178.549554 -293.170102)
		(width 0.18288)
		(layer "In6.Cu")
		(net "M_G_CPU1_SA_DQ<13>")
	)
	(segment
		(start 137.407396 -270.687038)
		(end 137.392664 -270.695674)
		(width 0.088646)
		(layer "In6.Cu")
		(net "M_G_CPU1_SA_DQ<13>")
	)
	(segment
		(start 175.097186 -293.169086)
		(end 173.167802 -291.239702)
		(width 0.18288)
		(layer "In6.Cu")
		(net "M_G_CPU1_SA_DQ<13>")
	)
	(segment
		(start 171.047664 -291.239702)
		(end 170.864784 -291.422582)
		(width 0.18288)
		(layer "In6.Cu")
		(net "M_G_CPU1_SA_DQ<13>")
	)
	(segment
		(start 183.456326 -296.854626)
		(end 182.694326 -296.092626)
		(width 0.18288)
		(layer "In6.Cu")
		(net "M_G_CPU1_SA_DQ<13>")
	)
	(segment
		(start 164.798756 -289.678872)
		(end 164.63518 -289.515296)
		(width 0.18288)
		(layer "In6.Cu")
		(net "M_G_CPU1_SA_DQ<13>")
	)
	(segment
		(start 175.981106 -292.930326)
		(end 175.742346 -293.169086)
		(width 0.18288)
		(layer "In6.Cu")
		(net "M_G_CPU1_SA_DQ<13>")
	)
	(segment
		(start 166.425626 -290.276026)
		(end 165.828472 -289.678872)
		(width 0.18288)
		(layer "In6.Cu")
		(net "M_G_CPU1_SA_DQ<13>")
	)
	(segment
		(start 170.864784 -292.194488)
		(end 170.681904 -292.377368)
		(width 0.18288)
		(layer "In6.Cu")
		(net "M_G_CPU1_SA_DQ<13>")
	)
	(segment
		(start 170.171364 -291.422582)
		(end 169.988484 -291.239702)
		(width 0.18288)
		(layer "In6.Cu")
		(net "M_G_CPU1_SA_DQ<13>")
	)
	(segment
		(start 138.852148 -270.636492)
		(end 138.534394 -270.636492)
		(width 0.088646)
		(layer "In6.Cu")
		(net "M_G_CPU1_SA_DQ<13>")
	)
	(segment
		(start 127.569468 -271.011396)
		(end 127.256794 -271.011396)
		(width 0.088646)
		(layer "In6.Cu")
		(net "M_G_CPU1_SA_DQ<13>")
	)
	(segment
		(start 177.800508 -292.421056)
		(end 177.471832 -292.09238)
		(width 0.18288)
		(layer "In6.Cu")
		(net "M_G_CPU1_SA_DQ<13>")
	)
	(segment
		(start 139.48156 -271.07388)
		(end 139.289536 -271.07388)
		(width 0.088646)
		(layer "In6.Cu")
		(net "M_G_CPU1_SA_DQ<13>")
	)
	(segment
		(start 128.949196 -270.687038)
		(end 128.940306 -270.692118)
		(width 0.088646)
		(layer "In6.Cu")
		(net "M_G_CPU1_SA_DQ<13>")
	)
	(segment
		(start 132.708396 -270.687038)
		(end 132.693664 -270.695674)
		(width 0.088646)
		(layer "In6.Cu")
		(net "M_G_CPU1_SA_DQ<13>")
	)
	(segment
		(start 127.928878 -271.50949)
		(end 127.914146 -271.500854)
		(width 0.088646)
		(layer "In6.Cu")
		(net "M_G_CPU1_SA_DQ<13>")
	)
	(segment
		(start 182.186326 -296.092626)
		(end 179.671726 -293.578026)
		(width 0.18288)
		(layer "In6.Cu")
		(net "M_G_CPU1_SA_DQ<13>")
	)
	(segment
		(start 173.167802 -291.239702)
		(end 171.047664 -291.239702)
		(width 0.18288)
		(layer "In6.Cu")
		(net "M_G_CPU1_SA_DQ<13>")
	)
	(segment
		(start 135.527796 -270.687038)
		(end 135.513064 -270.695674)
		(width 0.088646)
		(layer "In6.Cu")
		(net "M_G_CPU1_SA_DQ<13>")
	)
	(segment
		(start 177.800508 -292.679628)
		(end 177.800508 -292.421056)
		(width 0.18288)
		(layer "In6.Cu")
		(net "M_G_CPU1_SA_DQ<13>")
	)
	(segment
		(start 128.761744 -271.011396)
		(end 128.761744 -271.02689)
		(width 0.088646)
		(layer "In6.Cu")
		(net "M_G_CPU1_SA_DQ<13>")
	)
	(segment
		(start 127.635254 -271.077182)
		(end 127.569468 -271.011396)
		(width 0.088646)
		(layer "In6.Cu")
		(net "M_G_CPU1_SA_DQ<13>")
	)
	(segment
		(start 175.981106 -292.252654)
		(end 175.981106 -292.930326)
		(width 0.18288)
		(layer "In6.Cu")
		(net "M_G_CPU1_SA_DQ<13>")
	)
	(segment
		(start 129.888996 -270.687038)
		(end 129.874264 -270.695674)
		(width 0.088646)
		(layer "In6.Cu")
		(net "M_G_CPU1_SA_DQ<13>")
	)
	(segment
		(start 170.354244 -292.377368)
		(end 170.171364 -292.194488)
		(width 0.18288)
		(layer "In6.Cu")
		(net "M_G_CPU1_SA_DQ<13>")
	)
	(segment
		(start 170.171364 -292.194488)
		(end 170.171364 -291.422582)
		(width 0.18288)
		(layer "In6.Cu")
		(net "M_G_CPU1_SA_DQ<13>")
	)
	(segment
		(start 131.768596 -270.687038)
		(end 131.753864 -270.695674)
		(width 0.088646)
		(layer "In6.Cu")
		(net "M_G_CPU1_SA_DQ<13>")
	)
	(segment
		(start 176.14138 -292.09238)
		(end 175.981106 -292.252654)
		(width 0.18288)
		(layer "In6.Cu")
		(net "M_G_CPU1_SA_DQ<13>")
	)
	(segment
		(start 140.436854 -272.029174)
		(end 139.48156 -271.07388)
		(width 0.088646)
		(layer "In6.Cu")
		(net "M_G_CPU1_SA_DQ<13>")
	)
	(segment
		(start 177.670206 -293.532306)
		(end 177.438304 -293.300404)
		(width 0.18288)
		(layer "In6.Cu")
		(net "M_G_CPU1_SA_DQ<13>")
	)
	(segment
		(start 186.834526 -298.841414)
		(end 186.221878 -298.841414)
		(width 0.18288)
		(layer "In6.Cu")
		(net "M_G_CPU1_SA_DQ<13>")
	)
	(segment
		(start 185.310526 -297.930062)
		(end 185.310526 -297.388026)
		(width 0.18288)
		(layer "In6.Cu")
		(net "M_G_CPU1_SA_DQ<13>")
	)
	(segment
		(start 148.937472 -272.451576)
		(end 142.557754 -272.451576)
		(width 0.18288)
		(layer "In6.Cu")
		(net "M_G_CPU1_SA_DQ<13>")
	)
	(segment
		(start 139.289536 -271.07388)
		(end 138.852148 -270.636492)
		(width 0.088646)
		(layer "In6.Cu")
		(net "M_G_CPU1_SA_DQ<13>")
	)
	(segment
		(start 168.804082 -291.239702)
		(end 167.840406 -290.276026)
		(width 0.18288)
		(layer "In6.Cu")
		(net "M_G_CPU1_SA_DQ<13>")
	)
	(arc
		(start 130.263392 -270.687038)
		(mid 130.076194 -270.636895)
		(end 129.888996 -270.687038)
		(width 0.088646)
		(layer "In6.Cu")
		(net "M_G_CPU1_SA_DQ<13>")
	)
	(arc
		(start 127.90805 -271.497298)
		(mid 127.722595 -271.319103)
		(end 127.635254 -271.077182)
		(width 0.088646)
		(layer "In6.Cu")
		(net "M_G_CPU1_SA_DQ<13>")
	)
	(arc
		(start 128.761744 -271.02689)
		(mid 128.682374 -271.300624)
		(end 128.47955 -271.500854)
		(width 0.088646)
		(layer "In6.Cu")
		(net "M_G_CPU1_SA_DQ<13>")
	)
	(arc
		(start 137.392664 -270.695674)
		(mid 137.116189 -270.762994)
		(end 136.841992 -270.687038)
		(width 0.088646)
		(layer "In6.Cu")
		(net "M_G_CPU1_SA_DQ<13>")
	)
	(arc
		(start 132.693664 -270.695674)
		(mid 132.417189 -270.762994)
		(end 132.142992 -270.687038)
		(width 0.088646)
		(layer "In6.Cu")
		(net "M_G_CPU1_SA_DQ<13>")
	)
	(arc
		(start 134.022592 -270.687038)
		(mid 133.835394 -270.636895)
		(end 133.648196 -270.687038)
		(width 0.088646)
		(layer "In6.Cu")
		(net "M_G_CPU1_SA_DQ<13>")
	)
	(arc
		(start 134.573264 -270.695674)
		(mid 134.296789 -270.762994)
		(end 134.022592 -270.687038)
		(width 0.088646)
		(layer "In6.Cu")
		(net "M_G_CPU1_SA_DQ<13>")
	)
	(arc
		(start 136.841992 -270.687038)
		(mid 136.654794 -270.636895)
		(end 136.467596 -270.687038)
		(width 0.088646)
		(layer "In6.Cu")
		(net "M_G_CPU1_SA_DQ<13>")
	)
	(arc
		(start 138.332464 -270.695674)
		(mid 138.055989 -270.762994)
		(end 137.781792 -270.687038)
		(width 0.088646)
		(layer "In6.Cu")
		(net "M_G_CPU1_SA_DQ<13>")
	)
	(arc
		(start 137.781792 -270.687038)
		(mid 137.594594 -270.636895)
		(end 137.407396 -270.687038)
		(width 0.088646)
		(layer "In6.Cu")
		(net "M_G_CPU1_SA_DQ<13>")
	)
	(arc
		(start 129.874264 -270.695674)
		(mid 129.597789 -270.762994)
		(end 129.323592 -270.687038)
		(width 0.088646)
		(layer "In6.Cu")
		(net "M_G_CPU1_SA_DQ<13>")
	)
	(arc
		(start 131.203192 -270.687038)
		(mid 131.015994 -270.636895)
		(end 130.828796 -270.687038)
		(width 0.088646)
		(layer "In6.Cu")
		(net "M_G_CPU1_SA_DQ<13>")
	)
	(arc
		(start 135.513064 -270.695674)
		(mid 135.236589 -270.762994)
		(end 134.962392 -270.687038)
		(width 0.088646)
		(layer "In6.Cu")
		(net "M_G_CPU1_SA_DQ<13>")
	)
	(arc
		(start 135.902192 -270.687038)
		(mid 135.714994 -270.636895)
		(end 135.527796 -270.687038)
		(width 0.088646)
		(layer "In6.Cu")
		(net "M_G_CPU1_SA_DQ<13>")
	)
	(arc
		(start 132.142992 -270.687038)
		(mid 131.955794 -270.636895)
		(end 131.768596 -270.687038)
		(width 0.088646)
		(layer "In6.Cu")
		(net "M_G_CPU1_SA_DQ<13>")
	)
	(arc
		(start 129.323592 -270.687038)
		(mid 129.136394 -270.636895)
		(end 128.949196 -270.687038)
		(width 0.088646)
		(layer "In6.Cu")
		(net "M_G_CPU1_SA_DQ<13>")
	)
	(arc
		(start 128.47955 -271.500854)
		(mid 128.205351 -271.576689)
		(end 127.928878 -271.50949)
		(width 0.088646)
		(layer "In6.Cu")
		(net "M_G_CPU1_SA_DQ<13>")
	)
	(arc
		(start 128.940306 -270.692118)
		(mid 128.809392 -270.828478)
		(end 128.761744 -271.011396)
		(width 0.088646)
		(layer "In6.Cu")
		(net "M_G_CPU1_SA_DQ<13>")
	)
	(arc
		(start 133.082792 -270.687038)
		(mid 132.895594 -270.636895)
		(end 132.708396 -270.687038)
		(width 0.088646)
		(layer "In6.Cu")
		(net "M_G_CPU1_SA_DQ<13>")
	)
	(arc
		(start 138.534394 -270.636492)
		(mid 138.429193 -270.651629)
		(end 138.332464 -270.695674)
		(width 0.088646)
		(layer "In6.Cu")
		(net "M_G_CPU1_SA_DQ<13>")
	)
	(arc
		(start 134.962392 -270.687038)
		(mid 134.775194 -270.636895)
		(end 134.587996 -270.687038)
		(width 0.088646)
		(layer "In6.Cu")
		(net "M_G_CPU1_SA_DQ<13>")
	)
	(arc
		(start 136.452864 -270.695674)
		(mid 136.176389 -270.762994)
		(end 135.902192 -270.687038)
		(width 0.088646)
		(layer "In6.Cu")
		(net "M_G_CPU1_SA_DQ<13>")
	)
	(arc
		(start 131.753864 -270.695674)
		(mid 131.477389 -270.762994)
		(end 131.203192 -270.687038)
		(width 0.088646)
		(layer "In6.Cu")
		(net "M_G_CPU1_SA_DQ<13>")
	)
	(arc
		(start 130.814064 -270.695674)
		(mid 130.537589 -270.762994)
		(end 130.263392 -270.687038)
		(width 0.088646)
		(layer "In6.Cu")
		(net "M_G_CPU1_SA_DQ<13>")
	)
	(arc
		(start 133.648196 -270.687038)
		(mid 133.365494 -270.762814)
		(end 133.082792 -270.687038)
		(width 0.088646)
		(layer "In6.Cu")
		(net "M_G_CPU1_SA_DQ<13>")
	)
	(segment
		(start 194.940428 -301.016924)
		(end 194.508882 -300.585378)
		(width 0.20066)
		(layer "F.Cu")
		(net "M_G_CPU1_SA_DQ<12>")
	)
	(segment
		(start 190.984124 -301.265336)
		(end 190.50889 -301.265336)
		(width 0.20066)
		(layer "F.Cu")
		(net "M_G_CPU1_SA_DQ<12>")
	)
	(segment
		(start 194.508882 -300.585378)
		(end 194.098926 -300.585378)
		(width 0.20066)
		(layer "F.Cu")
		(net "M_G_CPU1_SA_DQ<12>")
	)
	(segment
		(start 190.260224 -301.01667)
		(end 188.988446 -301.01667)
		(width 0.20066)
		(layer "F.Cu")
		(net "M_G_CPU1_SA_DQ<12>")
	)
	(segment
		(start 191.835278 -300.591728)
		(end 191.817244 -300.591728)
		(width 0.101854)
		(layer "F.Cu")
		(net "M_G_CPU1_SA_DQ<12>")
	)
	(segment
		(start 196.531992 -301.016924)
		(end 194.940428 -301.016924)
		(width 0.20066)
		(layer "F.Cu")
		(net "M_G_CPU1_SA_DQ<12>")
	)
	(segment
		(start 191.172084 -301.077376)
		(end 190.984124 -301.265336)
		(width 0.20066)
		(layer "F.Cu")
		(net "M_G_CPU1_SA_DQ<12>")
	)
	(segment
		(start 194.092576 -300.591728)
		(end 191.835278 -300.591728)
		(width 0.1016)
		(layer "F.Cu")
		(net "M_G_CPU1_SA_DQ<12>")
	)
	(segment
		(start 188.988446 -301.01667)
		(end 187.883546 -301.01667)
		(width 0.20066)
		(layer "F.Cu")
		(net "M_G_CPU1_SA_DQ<12>")
	)
	(segment
		(start 191.290194 -300.591728)
		(end 191.172084 -300.709838)
		(width 0.20066)
		(layer "F.Cu")
		(net "M_G_CPU1_SA_DQ<12>")
	)
	(segment
		(start 191.172084 -300.709838)
		(end 191.172084 -301.077376)
		(width 0.20066)
		(layer "F.Cu")
		(net "M_G_CPU1_SA_DQ<12>")
	)
	(segment
		(start 194.098926 -300.585378)
		(end 194.092576 -300.591728)
		(width 0.1016)
		(layer "F.Cu")
		(net "M_G_CPU1_SA_DQ<12>")
	)
	(segment
		(start 126.786894 -271.289272)
		(end 126.787148 -271.825212)
		(width 0.20066)
		(layer "F.Cu")
		(net "M_G_CPU1_SA_DQ<12>")
	)
	(segment
		(start 190.50889 -301.265336)
		(end 190.260224 -301.01667)
		(width 0.20066)
		(layer "F.Cu")
		(net "M_G_CPU1_SA_DQ<12>")
	)
	(segment
		(start 191.817244 -300.591728)
		(end 191.290194 -300.591728)
		(width 0.20066)
		(layer "F.Cu")
		(net "M_G_CPU1_SA_DQ<12>")
	)
	(segment
		(start 196.532246 -301.01667)
		(end 196.531992 -301.016924)
		(width 0.20066)
		(layer "F.Cu")
		(net "M_G_CPU1_SA_DQ<12>")
	)
	(segment
		(start 157.441392 -290.15055)
		(end 155.514802 -288.22396)
		(width 0.18288)
		(layer "In6.Cu")
		(net "M_G_CPU1_SA_DQ<12>")
	)
	(segment
		(start 177.37074 -294.642286)
		(end 174.462186 -294.642286)
		(width 0.18288)
		(layer "In6.Cu")
		(net "M_G_CPU1_SA_DQ<12>")
	)
	(segment
		(start 173.075346 -292.942264)
		(end 172.40885 -292.942264)
		(width 0.18288)
		(layer "In6.Cu")
		(net "M_G_CPU1_SA_DQ<12>")
	)
	(segment
		(start 137.326878 -271.50949)
		(end 137.312146 -271.500854)
		(width 0.088646)
		(layer "In6.Cu")
		(net "M_G_CPU1_SA_DQ<12>")
	)
	(segment
		(start 134.118096 -271.500854)
		(end 134.112254 -271.50441)
		(width 0.088646)
		(layer "In6.Cu")
		(net "M_G_CPU1_SA_DQ<12>")
	)
	(segment
		(start 159.467296 -290.15055)
		(end 159.284416 -290.33343)
		(width 0.18288)
		(layer "In6.Cu")
		(net "M_G_CPU1_SA_DQ<12>")
	)
	(segment
		(start 158.590996 -290.33343)
		(end 158.408116 -290.15055)
		(width 0.18288)
		(layer "In6.Cu")
		(net "M_G_CPU1_SA_DQ<12>")
	)
	(segment
		(start 167.951658 -292.367208)
		(end 167.426386 -291.841936)
		(width 0.18288)
		(layer "In6.Cu")
		(net "M_G_CPU1_SA_DQ<12>")
	)
	(segment
		(start 186.284616 -300.467014)
		(end 184.628028 -298.810426)
		(width 0.18288)
		(layer "In6.Cu")
		(net "M_G_CPU1_SA_DQ<12>")
	)
	(segment
		(start 187.358782 -301.01667)
		(end 186.809126 -300.467014)
		(width 0.18288)
		(layer "In6.Cu")
		(net "M_G_CPU1_SA_DQ<12>")
	)
	(segment
		(start 155.514802 -288.22396)
		(end 155.514802 -280.437336)
		(width 0.18288)
		(layer "In6.Cu")
		(net "M_G_CPU1_SA_DQ<12>")
	)
	(segment
		(start 127.53975 -272.14957)
		(end 127.512064 -272.133314)
		(width 0.088646)
		(layer "In6.Cu")
		(net "M_G_CPU1_SA_DQ<12>")
	)
	(segment
		(start 158.590996 -290.806124)
		(end 158.590996 -290.33343)
		(width 0.18288)
		(layer "In6.Cu")
		(net "M_G_CPU1_SA_DQ<12>")
	)
	(segment
		(start 172.40885 -292.942264)
		(end 171.874688 -293.476426)
		(width 0.18288)
		(layer "In6.Cu")
		(net "M_G_CPU1_SA_DQ<12>")
	)
	(segment
		(start 167.426386 -291.841936)
		(end 166.350442 -291.841936)
		(width 0.18288)
		(layer "In6.Cu")
		(net "M_G_CPU1_SA_DQ<12>")
	)
	(segment
		(start 174.462186 -294.642286)
		(end 173.828202 -294.008302)
		(width 0.18288)
		(layer "In6.Cu")
		(net "M_G_CPU1_SA_DQ<12>")
	)
	(segment
		(start 170.053762 -294.243252)
		(end 170.053762 -293.636446)
		(width 0.18288)
		(layer "In6.Cu")
		(net "M_G_CPU1_SA_DQ<12>")
	)
	(segment
		(start 187.883546 -301.01667)
		(end 187.358782 -301.01667)
		(width 0.18288)
		(layer "In6.Cu")
		(net "M_G_CPU1_SA_DQ<12>")
	)
	(segment
		(start 166.350442 -291.841936)
		(end 166.046404 -291.537898)
		(width 0.18288)
		(layer "In6.Cu")
		(net "M_G_CPU1_SA_DQ<12>")
	)
	(segment
		(start 133.184138 -271.497552)
		(end 133.178296 -271.500854)
		(width 0.088646)
		(layer "In6.Cu")
		(net "M_G_CPU1_SA_DQ<12>")
	)
	(segment
		(start 130.364738 -271.497552)
		(end 130.358896 -271.500854)
		(width 0.088646)
		(layer "In6.Cu")
		(net "M_G_CPU1_SA_DQ<12>")
	)
	(segment
		(start 127.512064 -272.133314)
		(end 126.787148 -271.825212)
		(width 0.088646)
		(layer "In6.Cu")
		(net "M_G_CPU1_SA_DQ<12>")
	)
	(segment
		(start 184.628028 -298.810426)
		(end 183.900064 -298.810426)
		(width 0.18288)
		(layer "In6.Cu")
		(net "M_G_CPU1_SA_DQ<12>")
	)
	(segment
		(start 173.828202 -293.69512)
		(end 173.075346 -292.942264)
		(width 0.18288)
		(layer "In6.Cu")
		(net "M_G_CPU1_SA_DQ<12>")
	)
	(segment
		(start 135.99795 -271.500854)
		(end 135.997696 -271.500854)
		(width 0.088646)
		(layer "In6.Cu")
		(net "M_G_CPU1_SA_DQ<12>")
	)
	(segment
		(start 170.587162 -294.403272)
		(end 170.213782 -294.403272)
		(width 0.18288)
		(layer "In6.Cu")
		(net "M_G_CPU1_SA_DQ<12>")
	)
	(segment
		(start 182.999126 -297.909488)
		(end 182.148988 -297.909488)
		(width 0.18288)
		(layer "In6.Cu")
		(net "M_G_CPU1_SA_DQ<12>")
	)
	(segment
		(start 162.983926 -291.783262)
		(end 162.656266 -291.783262)
		(width 0.18288)
		(layer "In6.Cu")
		(net "M_G_CPU1_SA_DQ<12>")
	)
	(segment
		(start 162.473386 -291.13861)
		(end 162.290506 -290.95573)
		(width 0.18288)
		(layer "In6.Cu")
		(net "M_G_CPU1_SA_DQ<12>")
	)
	(segment
		(start 134.123938 -271.497552)
		(end 134.118096 -271.500854)
		(width 0.088646)
		(layer "In6.Cu")
		(net "M_G_CPU1_SA_DQ<12>")
	)
	(segment
		(start 170.907202 -293.476426)
		(end 170.747182 -293.636446)
		(width 0.18288)
		(layer "In6.Cu")
		(net "M_G_CPU1_SA_DQ<12>")
	)
	(segment
		(start 166.046404 -291.537898)
		(end 164.896038 -291.537898)
		(width 0.18288)
		(layer "In6.Cu")
		(net "M_G_CPU1_SA_DQ<12>")
	)
	(segment
		(start 132.244338 -271.497552)
		(end 132.238496 -271.500854)
		(width 0.088646)
		(layer "In6.Cu")
		(net "M_G_CPU1_SA_DQ<12>")
	)
	(segment
		(start 158.408116 -290.15055)
		(end 157.441392 -290.15055)
		(width 0.18288)
		(layer "In6.Cu")
		(net "M_G_CPU1_SA_DQ<12>")
	)
	(segment
		(start 142.358618 -273.447256)
		(end 141.363954 -273.035268)
		(width 0.18288)
		(layer "In6.Cu")
		(net "M_G_CPU1_SA_DQ<12>")
	)
	(segment
		(start 159.101536 -290.989004)
		(end 158.773876 -290.989004)
		(width 0.18288)
		(layer "In6.Cu")
		(net "M_G_CPU1_SA_DQ<12>")
	)
	(segment
		(start 135.062214 -271.498314)
		(end 135.057896 -271.500854)
		(width 0.088646)
		(layer "In6.Cu")
		(net "M_G_CPU1_SA_DQ<12>")
	)
	(segment
		(start 170.213782 -294.403272)
		(end 170.053762 -294.243252)
		(width 0.18288)
		(layer "In6.Cu")
		(net "M_G_CPU1_SA_DQ<12>")
	)
	(segment
		(start 158.773876 -290.989004)
		(end 158.590996 -290.806124)
		(width 0.18288)
		(layer "In6.Cu")
		(net "M_G_CPU1_SA_DQ<12>")
	)
	(segment
		(start 163.166806 -291.600382)
		(end 162.983926 -291.783262)
		(width 0.18288)
		(layer "In6.Cu")
		(net "M_G_CPU1_SA_DQ<12>")
	)
	(segment
		(start 139.200636 -271.505934)
		(end 139.191746 -271.500854)
		(width 0.088646)
		(layer "In6.Cu")
		(net "M_G_CPU1_SA_DQ<12>")
	)
	(segment
		(start 186.809126 -300.467014)
		(end 186.284616 -300.467014)
		(width 0.18288)
		(layer "In6.Cu")
		(net "M_G_CPU1_SA_DQ<12>")
	)
	(segment
		(start 130.358896 -271.500854)
		(end 130.353054 -271.50441)
		(width 0.088646)
		(layer "In6.Cu")
		(net "M_G_CPU1_SA_DQ<12>")
	)
	(segment
		(start 167.951658 -293.234618)
		(end 167.951658 -292.367208)
		(width 0.18288)
		(layer "In6.Cu")
		(net "M_G_CPU1_SA_DQ<12>")
	)
	(segment
		(start 159.918146 -290.15055)
		(end 159.467296 -290.15055)
		(width 0.18288)
		(layer "In6.Cu")
		(net "M_G_CPU1_SA_DQ<12>")
	)
	(segment
		(start 170.747182 -294.243252)
		(end 170.587162 -294.403272)
		(width 0.18288)
		(layer "In6.Cu")
		(net "M_G_CPU1_SA_DQ<12>")
	)
	(segment
		(start 171.874688 -293.476426)
		(end 170.907202 -293.476426)
		(width 0.18288)
		(layer "In6.Cu")
		(net "M_G_CPU1_SA_DQ<12>")
	)
	(segment
		(start 164.896038 -291.537898)
		(end 164.31387 -290.95573)
		(width 0.18288)
		(layer "In6.Cu")
		(net "M_G_CPU1_SA_DQ<12>")
	)
	(segment
		(start 177.91176 -295.183306)
		(end 177.37074 -294.642286)
		(width 0.18288)
		(layer "In6.Cu")
		(net "M_G_CPU1_SA_DQ<12>")
	)
	(segment
		(start 159.284416 -290.33343)
		(end 159.284416 -290.806124)
		(width 0.18288)
		(layer "In6.Cu")
		(net "M_G_CPU1_SA_DQ<12>")
	)
	(segment
		(start 127.928878 -272.140934)
		(end 127.914146 -272.14957)
		(width 0.088646)
		(layer "In6.Cu")
		(net "M_G_CPU1_SA_DQ<12>")
	)
	(segment
		(start 169.893742 -293.476426)
		(end 168.193466 -293.476426)
		(width 0.18288)
		(layer "In6.Cu")
		(net "M_G_CPU1_SA_DQ<12>")
	)
	(segment
		(start 173.828202 -294.008302)
		(end 173.828202 -293.69512)
		(width 0.18288)
		(layer "In6.Cu")
		(net "M_G_CPU1_SA_DQ<12>")
	)
	(segment
		(start 170.747182 -293.636446)
		(end 170.747182 -294.243252)
		(width 0.18288)
		(layer "In6.Cu")
		(net "M_G_CPU1_SA_DQ<12>")
	)
	(segment
		(start 183.900064 -298.810426)
		(end 182.999126 -297.909488)
		(width 0.18288)
		(layer "In6.Cu")
		(net "M_G_CPU1_SA_DQ<12>")
	)
	(segment
		(start 133.178296 -271.500854)
		(end 133.172454 -271.50441)
		(width 0.088646)
		(layer "In6.Cu")
		(net "M_G_CPU1_SA_DQ<12>")
	)
	(segment
		(start 179.041806 -295.183306)
		(end 177.91176 -295.183306)
		(width 0.18288)
		(layer "In6.Cu")
		(net "M_G_CPU1_SA_DQ<12>")
	)
	(segment
		(start 140.595604 -273.035268)
		(end 140.41247 -273.035268)
		(width 0.088646)
		(layer "In6.Cu")
		(net "M_G_CPU1_SA_DQ<12>")
	)
	(segment
		(start 159.284416 -290.806124)
		(end 159.101536 -290.989004)
		(width 0.18288)
		(layer "In6.Cu")
		(net "M_G_CPU1_SA_DQ<12>")
	)
	(segment
		(start 163.166806 -291.13861)
		(end 163.166806 -291.600382)
		(width 0.18288)
		(layer "In6.Cu")
		(net "M_G_CPU1_SA_DQ<12>")
	)
	(segment
		(start 131.304538 -271.497552)
		(end 131.298696 -271.500854)
		(width 0.088646)
		(layer "In6.Cu")
		(net "M_G_CPU1_SA_DQ<12>")
	)
	(segment
		(start 138.266678 -271.50949)
		(end 138.251946 -271.500854)
		(width 0.088646)
		(layer "In6.Cu")
		(net "M_G_CPU1_SA_DQ<12>")
	)
	(segment
		(start 162.290506 -290.95573)
		(end 160.723326 -290.95573)
		(width 0.18288)
		(layer "In6.Cu")
		(net "M_G_CPU1_SA_DQ<12>")
	)
	(segment
		(start 164.31387 -290.95573)
		(end 163.349686 -290.95573)
		(width 0.18288)
		(layer "In6.Cu")
		(net "M_G_CPU1_SA_DQ<12>")
	)
	(segment
		(start 180.408326 -296.168826)
		(end 180.027326 -296.168826)
		(width 0.18288)
		(layer "In6.Cu")
		(net "M_G_CPU1_SA_DQ<12>")
	)
	(segment
		(start 168.193466 -293.476426)
		(end 167.951658 -293.234618)
		(width 0.18288)
		(layer "In6.Cu")
		(net "M_G_CPU1_SA_DQ<12>")
	)
	(segment
		(start 141.363954 -273.035268)
		(end 140.595604 -273.035268)
		(width 0.18288)
		(layer "In6.Cu")
		(net "M_G_CPU1_SA_DQ<12>")
	)
	(segment
		(start 162.473386 -291.600382)
		(end 162.473386 -291.13861)
		(width 0.18288)
		(layer "In6.Cu")
		(net "M_G_CPU1_SA_DQ<12>")
	)
	(segment
		(start 162.656266 -291.783262)
		(end 162.473386 -291.600382)
		(width 0.18288)
		(layer "In6.Cu")
		(net "M_G_CPU1_SA_DQ<12>")
	)
	(segment
		(start 155.514802 -280.437336)
		(end 148.524722 -273.447256)
		(width 0.18288)
		(layer "In6.Cu")
		(net "M_G_CPU1_SA_DQ<12>")
	)
	(segment
		(start 170.053762 -293.636446)
		(end 169.893742 -293.476426)
		(width 0.18288)
		(layer "In6.Cu")
		(net "M_G_CPU1_SA_DQ<12>")
	)
	(segment
		(start 180.027326 -296.168826)
		(end 179.041806 -295.183306)
		(width 0.18288)
		(layer "In6.Cu")
		(net "M_G_CPU1_SA_DQ<12>")
	)
	(segment
		(start 131.298696 -271.500854)
		(end 131.292854 -271.50441)
		(width 0.088646)
		(layer "In6.Cu")
		(net "M_G_CPU1_SA_DQ<12>")
	)
	(segment
		(start 163.349686 -290.95573)
		(end 163.166806 -291.13861)
		(width 0.18288)
		(layer "In6.Cu")
		(net "M_G_CPU1_SA_DQ<12>")
	)
	(segment
		(start 140.41247 -273.035268)
		(end 139.379198 -272.001996)
		(width 0.088646)
		(layer "In6.Cu")
		(net "M_G_CPU1_SA_DQ<12>")
	)
	(segment
		(start 148.524722 -273.447256)
		(end 142.358618 -273.447256)
		(width 0.18288)
		(layer "In6.Cu")
		(net "M_G_CPU1_SA_DQ<12>")
	)
	(segment
		(start 136.387078 -271.50949)
		(end 136.372346 -271.500854)
		(width 0.088646)
		(layer "In6.Cu")
		(net "M_G_CPU1_SA_DQ<12>")
	)
	(segment
		(start 135.057896 -271.500854)
		(end 135.052054 -271.50441)
		(width 0.088646)
		(layer "In6.Cu")
		(net "M_G_CPU1_SA_DQ<12>")
	)
	(segment
		(start 182.148988 -297.909488)
		(end 180.408326 -296.168826)
		(width 0.18288)
		(layer "In6.Cu")
		(net "M_G_CPU1_SA_DQ<12>")
	)
	(segment
		(start 139.379198 -272.001996)
		(end 139.379198 -271.825212)
		(width 0.088646)
		(layer "In6.Cu")
		(net "M_G_CPU1_SA_DQ<12>")
	)
	(segment
		(start 132.238496 -271.500854)
		(end 132.232654 -271.50441)
		(width 0.088646)
		(layer "In6.Cu")
		(net "M_G_CPU1_SA_DQ<12>")
	)
	(segment
		(start 160.723326 -290.95573)
		(end 159.918146 -290.15055)
		(width 0.18288)
		(layer "In6.Cu")
		(net "M_G_CPU1_SA_DQ<12>")
	)
	(arc
		(start 137.312146 -271.500854)
		(mid 137.124948 -271.450711)
		(end 136.93775 -271.500854)
		(width 0.088646)
		(layer "In6.Cu")
		(net "M_G_CPU1_SA_DQ<12>")
	)
	(arc
		(start 138.81735 -271.500854)
		(mid 138.543151 -271.576689)
		(end 138.266678 -271.50949)
		(width 0.088646)
		(layer "In6.Cu")
		(net "M_G_CPU1_SA_DQ<12>")
	)
	(arc
		(start 139.379198 -271.825212)
		(mid 139.331519 -271.642312)
		(end 139.200636 -271.505934)
		(width 0.088646)
		(layer "In6.Cu")
		(net "M_G_CPU1_SA_DQ<12>")
	)
	(arc
		(start 135.432546 -271.500854)
		(mid 135.247709 -271.450593)
		(end 135.062214 -271.498314)
		(width 0.088646)
		(layer "In6.Cu")
		(net "M_G_CPU1_SA_DQ<12>")
	)
	(arc
		(start 132.232654 -271.50441)
		(mid 131.952519 -271.576726)
		(end 131.673346 -271.500854)
		(width 0.088646)
		(layer "In6.Cu")
		(net "M_G_CPU1_SA_DQ<12>")
	)
	(arc
		(start 136.93775 -271.500854)
		(mid 136.663551 -271.576689)
		(end 136.387078 -271.50949)
		(width 0.088646)
		(layer "In6.Cu")
		(net "M_G_CPU1_SA_DQ<12>")
	)
	(arc
		(start 133.552946 -271.500854)
		(mid 133.368992 -271.450725)
		(end 133.184138 -271.497552)
		(width 0.088646)
		(layer "In6.Cu")
		(net "M_G_CPU1_SA_DQ<12>")
	)
	(arc
		(start 130.733546 -271.500854)
		(mid 130.549592 -271.450725)
		(end 130.364738 -271.497552)
		(width 0.088646)
		(layer "In6.Cu")
		(net "M_G_CPU1_SA_DQ<12>")
	)
	(arc
		(start 129.254504 -271.696942)
		(mid 129.22285 -271.769022)
		(end 129.182114 -271.836388)
		(width 0.088646)
		(layer "In6.Cu")
		(net "M_G_CPU1_SA_DQ<12>")
	)
	(arc
		(start 134.112254 -271.50441)
		(mid 133.832119 -271.576726)
		(end 133.552946 -271.500854)
		(width 0.088646)
		(layer "In6.Cu")
		(net "M_G_CPU1_SA_DQ<12>")
	)
	(arc
		(start 129.411984 -271.504918)
		(mid 129.316892 -271.587513)
		(end 129.254504 -271.696942)
		(width 0.088646)
		(layer "In6.Cu")
		(net "M_G_CPU1_SA_DQ<12>")
	)
	(arc
		(start 131.292854 -271.50441)
		(mid 131.012719 -271.576726)
		(end 130.733546 -271.500854)
		(width 0.088646)
		(layer "In6.Cu")
		(net "M_G_CPU1_SA_DQ<12>")
	)
	(arc
		(start 129.077466 -271.999964)
		(mid 128.968194 -272.078484)
		(end 128.853946 -272.14957)
		(width 0.088646)
		(layer "In6.Cu")
		(net "M_G_CPU1_SA_DQ<12>")
	)
	(arc
		(start 136.372346 -271.500854)
		(mid 136.185148 -271.450711)
		(end 135.99795 -271.500854)
		(width 0.088646)
		(layer "In6.Cu")
		(net "M_G_CPU1_SA_DQ<12>")
	)
	(arc
		(start 132.613146 -271.500854)
		(mid 132.429192 -271.450725)
		(end 132.244338 -271.497552)
		(width 0.088646)
		(layer "In6.Cu")
		(net "M_G_CPU1_SA_DQ<12>")
	)
	(arc
		(start 133.172454 -271.50441)
		(mid 132.892319 -271.576726)
		(end 132.613146 -271.500854)
		(width 0.088646)
		(layer "In6.Cu")
		(net "M_G_CPU1_SA_DQ<12>")
	)
	(arc
		(start 129.182114 -271.836388)
		(mid 129.144029 -271.927279)
		(end 129.077466 -271.999964)
		(width 0.088646)
		(layer "In6.Cu")
		(net "M_G_CPU1_SA_DQ<12>")
	)
	(arc
		(start 130.353054 -271.50441)
		(mid 130.072919 -271.576726)
		(end 129.793746 -271.500854)
		(width 0.088646)
		(layer "In6.Cu")
		(net "M_G_CPU1_SA_DQ<12>")
	)
	(arc
		(start 127.914146 -272.14957)
		(mid 127.726948 -272.199713)
		(end 127.53975 -272.14957)
		(width 0.088646)
		(layer "In6.Cu")
		(net "M_G_CPU1_SA_DQ<12>")
	)
	(arc
		(start 134.492746 -271.500854)
		(mid 134.308792 -271.450725)
		(end 134.123938 -271.497552)
		(width 0.088646)
		(layer "In6.Cu")
		(net "M_G_CPU1_SA_DQ<12>")
	)
	(arc
		(start 135.997696 -271.500854)
		(mid 135.715138 -271.576503)
		(end 135.432546 -271.500854)
		(width 0.088646)
		(layer "In6.Cu")
		(net "M_G_CPU1_SA_DQ<12>")
	)
	(arc
		(start 138.251946 -271.500854)
		(mid 138.064748 -271.450711)
		(end 137.87755 -271.500854)
		(width 0.088646)
		(layer "In6.Cu")
		(net "M_G_CPU1_SA_DQ<12>")
	)
	(arc
		(start 139.191746 -271.500854)
		(mid 139.004548 -271.450711)
		(end 138.81735 -271.500854)
		(width 0.088646)
		(layer "In6.Cu")
		(net "M_G_CPU1_SA_DQ<12>")
	)
	(arc
		(start 137.87755 -271.500854)
		(mid 137.603351 -271.576689)
		(end 137.326878 -271.50949)
		(width 0.088646)
		(layer "In6.Cu")
		(net "M_G_CPU1_SA_DQ<12>")
	)
	(arc
		(start 128.853946 -272.14957)
		(mid 128.666748 -272.199713)
		(end 128.47955 -272.14957)
		(width 0.088646)
		(layer "In6.Cu")
		(net "M_G_CPU1_SA_DQ<12>")
	)
	(arc
		(start 131.673346 -271.500854)
		(mid 131.489392 -271.450725)
		(end 131.304538 -271.497552)
		(width 0.088646)
		(layer "In6.Cu")
		(net "M_G_CPU1_SA_DQ<12>")
	)
	(arc
		(start 129.793746 -271.500854)
		(mid 129.602308 -271.450605)
		(end 129.411984 -271.504918)
		(width 0.088646)
		(layer "In6.Cu")
		(net "M_G_CPU1_SA_DQ<12>")
	)
	(arc
		(start 135.052054 -271.50441)
		(mid 134.771919 -271.576726)
		(end 134.492746 -271.500854)
		(width 0.088646)
		(layer "In6.Cu")
		(net "M_G_CPU1_SA_DQ<12>")
	)
	(arc
		(start 128.47955 -272.14957)
		(mid 128.205321 -272.073645)
		(end 127.928878 -272.140934)
		(width 0.088646)
		(layer "In6.Cu")
		(net "M_G_CPU1_SA_DQ<12>")
	)
	(segment
		(start 195.515484 -304.848768)
		(end 195.522596 -304.841656)
		(width 0.1016)
		(layer "F.Cu")
		(net "M_G_CPU1_SA_DQ<11>")
	)
	(segment
		(start 199.046084 -304.164746)
		(end 199.298052 -304.416714)
		(width 0.20066)
		(layer "F.Cu")
		(net "M_G_CPU1_SA_DQ<11>")
	)
	(segment
		(start 198.427848 -304.398934)
		(end 198.662036 -304.164746)
		(width 0.20066)
		(layer "F.Cu")
		(net "M_G_CPU1_SA_DQ<11>")
	)
	(segment
		(start 197.530466 -304.841656)
		(end 197.542658 -304.853848)
		(width 0.1016)
		(layer "F.Cu")
		(net "M_G_CPU1_SA_DQ<11>")
	)
	(segment
		(start 195.522596 -304.841656)
		(end 197.530466 -304.841656)
		(width 0.1016)
		(layer "F.Cu")
		(net "M_G_CPU1_SA_DQ<11>")
	)
	(segment
		(start 197.542658 -304.853848)
		(end 198.223886 -304.853848)
		(width 0.20066)
		(layer "F.Cu")
		(net "M_G_CPU1_SA_DQ<11>")
	)
	(segment
		(start 194.786758 -304.416714)
		(end 195.218812 -304.848768)
		(width 0.20066)
		(layer "F.Cu")
		(net "M_G_CPU1_SA_DQ<11>")
	)
	(segment
		(start 199.298052 -304.416714)
		(end 200.632314 -304.416714)
		(width 0.20066)
		(layer "F.Cu")
		(net "M_G_CPU1_SA_DQ<11>")
	)
	(segment
		(start 193.088514 -304.416714)
		(end 194.786758 -304.416714)
		(width 0.20066)
		(layer "F.Cu")
		(net "M_G_CPU1_SA_DQ<11>")
	)
	(segment
		(start 198.223886 -304.853848)
		(end 198.427848 -304.649886)
		(width 0.20066)
		(layer "F.Cu")
		(net "M_G_CPU1_SA_DQ<11>")
	)
	(segment
		(start 128.666494 -273.452844)
		(end 128.666748 -273.453098)
		(width 0.20066)
		(layer "F.Cu")
		(net "M_G_CPU1_SA_DQ<11>")
	)
	(segment
		(start 191.983614 -304.416714)
		(end 193.088514 -304.416714)
		(width 0.20066)
		(layer "F.Cu")
		(net "M_G_CPU1_SA_DQ<11>")
	)
	(segment
		(start 195.218812 -304.848768)
		(end 195.510658 -304.848768)
		(width 0.20066)
		(layer "F.Cu")
		(net "M_G_CPU1_SA_DQ<11>")
	)
	(segment
		(start 198.662036 -304.164746)
		(end 199.046084 -304.164746)
		(width 0.20066)
		(layer "F.Cu")
		(net "M_G_CPU1_SA_DQ<11>")
	)
	(segment
		(start 198.427848 -304.649886)
		(end 198.427848 -304.398934)
		(width 0.20066)
		(layer "F.Cu")
		(net "M_G_CPU1_SA_DQ<11>")
	)
	(segment
		(start 195.510658 -304.848768)
		(end 195.515484 -304.848768)
		(width 0.101854)
		(layer "F.Cu")
		(net "M_G_CPU1_SA_DQ<11>")
	)
	(segment
		(start 128.666494 -272.917158)
		(end 128.666494 -273.452844)
		(width 0.20066)
		(layer "F.Cu")
		(net "M_G_CPU1_SA_DQ<11>")
	)
	(segment
		(start 141.936978 -275.560536)
		(end 141.032992 -275.18614)
		(width 0.18288)
		(layer "In6.Cu")
		(net "M_G_CPU1_SA_DQ<11>")
	)
	(segment
		(start 141.032992 -275.18614)
		(end 140.595604 -275.18614)
		(width 0.18288)
		(layer "In6.Cu")
		(net "M_G_CPU1_SA_DQ<11>")
	)
	(segment
		(start 191.55918 -303.99228)
		(end 189.413896 -303.99228)
		(width 0.18288)
		(layer "In6.Cu")
		(net "M_G_CPU1_SA_DQ<11>")
	)
	(segment
		(start 170.096942 -297.712892)
		(end 170.096942 -297.995848)
		(width 0.18288)
		(layer "In6.Cu")
		(net "M_G_CPU1_SA_DQ<11>")
	)
	(segment
		(start 188.400436 -303.99228)
		(end 186.979814 -303.99228)
		(width 0.18288)
		(layer "In6.Cu")
		(net "M_G_CPU1_SA_DQ<11>")
	)
	(segment
		(start 189.413896 -303.99228)
		(end 189.253876 -304.1523)
		(width 0.18288)
		(layer "In6.Cu")
		(net "M_G_CPU1_SA_DQ<11>")
	)
	(segment
		(start 133.567678 -273.76882)
		(end 133.552946 -273.777456)
		(width 0.088646)
		(layer "In6.Cu")
		(net "M_G_CPU1_SA_DQ<11>")
	)
	(segment
		(start 162.381438 -294.670734)
		(end 161.387028 -294.670734)
		(width 0.18288)
		(layer "In6.Cu")
		(net "M_G_CPU1_SA_DQ<11>")
	)
	(segment
		(start 170.256962 -297.552872)
		(end 170.096942 -297.712892)
		(width 0.18288)
		(layer "In6.Cu")
		(net "M_G_CPU1_SA_DQ<11>")
	)
	(segment
		(start 168.110916 -297.320716)
		(end 167.374062 -297.320716)
		(width 0.18288)
		(layer "In6.Cu")
		(net "M_G_CPU1_SA_DQ<11>")
	)
	(segment
		(start 170.630342 -297.552872)
		(end 170.256962 -297.552872)
		(width 0.18288)
		(layer "In6.Cu")
		(net "M_G_CPU1_SA_DQ<11>")
	)
	(segment
		(start 181.789832 -301.439072)
		(end 180.977286 -300.626526)
		(width 0.18288)
		(layer "In6.Cu")
		(net "M_G_CPU1_SA_DQ<11>")
	)
	(segment
		(start 191.983614 -304.416714)
		(end 191.55918 -303.99228)
		(width 0.18288)
		(layer "In6.Cu")
		(net "M_G_CPU1_SA_DQ<11>")
	)
	(segment
		(start 170.790362 -297.995848)
		(end 170.790362 -297.712892)
		(width 0.18288)
		(layer "In6.Cu")
		(net "M_G_CPU1_SA_DQ<11>")
	)
	(segment
		(start 140.417042 -275.18614)
		(end 140.199618 -274.968716)
		(width 0.088646)
		(layer "In6.Cu")
		(net "M_G_CPU1_SA_DQ<11>")
	)
	(segment
		(start 130.364738 -273.781012)
		(end 130.358896 -273.777456)
		(width 0.088646)
		(layer "In6.Cu")
		(net "M_G_CPU1_SA_DQ<11>")
	)
	(segment
		(start 186.865514 -304.10658)
		(end 186.428126 -304.10658)
		(width 0.18288)
		(layer "In6.Cu")
		(net "M_G_CPU1_SA_DQ<11>")
	)
	(segment
		(start 139.082018 -273.701764)
		(end 138.534394 -273.701764)
		(width 0.088646)
		(layer "In6.Cu")
		(net "M_G_CPU1_SA_DQ<11>")
	)
	(segment
		(start 165.544754 -295.491408)
		(end 163.202112 -295.491408)
		(width 0.18288)
		(layer "In6.Cu")
		(net "M_G_CPU1_SA_DQ<11>")
	)
	(segment
		(start 180.116226 -300.626526)
		(end 179.379626 -299.889926)
		(width 0.18288)
		(layer "In6.Cu")
		(net "M_G_CPU1_SA_DQ<11>")
	)
	(segment
		(start 171.702984 -298.155868)
		(end 170.950382 -298.155868)
		(width 0.18288)
		(layer "In6.Cu")
		(net "M_G_CPU1_SA_DQ<11>")
	)
	(segment
		(start 174.595282 -298.892468)
		(end 173.745398 -298.042584)
		(width 0.18288)
		(layer "In6.Cu")
		(net "M_G_CPU1_SA_DQ<11>")
	)
	(segment
		(start 188.720476 -304.842672)
		(end 188.560456 -304.682652)
		(width 0.18288)
		(layer "In6.Cu")
		(net "M_G_CPU1_SA_DQ<11>")
	)
	(segment
		(start 173.745398 -298.042584)
		(end 171.816268 -298.042584)
		(width 0.18288)
		(layer "In6.Cu")
		(net "M_G_CPU1_SA_DQ<11>")
	)
	(segment
		(start 169.936922 -298.155868)
		(end 168.946068 -298.155868)
		(width 0.18288)
		(layer "In6.Cu")
		(net "M_G_CPU1_SA_DQ<11>")
	)
	(segment
		(start 180.977286 -300.626526)
		(end 180.116226 -300.626526)
		(width 0.18288)
		(layer "In6.Cu")
		(net "M_G_CPU1_SA_DQ<11>")
	)
	(segment
		(start 189.093856 -304.842672)
		(end 188.720476 -304.842672)
		(width 0.18288)
		(layer "In6.Cu")
		(net "M_G_CPU1_SA_DQ<11>")
	)
	(segment
		(start 129.424938 -273.781012)
		(end 129.419096 -273.777456)
		(width 0.088646)
		(layer "In6.Cu")
		(net "M_G_CPU1_SA_DQ<11>")
	)
	(segment
		(start 188.560456 -304.1523)
		(end 188.400436 -303.99228)
		(width 0.18288)
		(layer "In6.Cu")
		(net "M_G_CPU1_SA_DQ<11>")
	)
	(segment
		(start 188.560456 -304.682652)
		(end 188.560456 -304.1523)
		(width 0.18288)
		(layer "In6.Cu")
		(net "M_G_CPU1_SA_DQ<11>")
	)
	(segment
		(start 189.253876 -304.1523)
		(end 189.253876 -304.682652)
		(width 0.18288)
		(layer "In6.Cu")
		(net "M_G_CPU1_SA_DQ<11>")
	)
	(segment
		(start 185.909712 -303.588166)
		(end 185.081926 -303.588166)
		(width 0.18288)
		(layer "In6.Cu")
		(net "M_G_CPU1_SA_DQ<11>")
	)
	(segment
		(start 140.595604 -275.18614)
		(end 140.417042 -275.18614)
		(width 0.088646)
		(layer "In6.Cu")
		(net "M_G_CPU1_SA_DQ<11>")
	)
	(segment
		(start 179.379626 -299.889926)
		(end 179.024026 -299.889926)
		(width 0.18288)
		(layer "In6.Cu")
		(net "M_G_CPU1_SA_DQ<11>")
	)
	(segment
		(start 161.387028 -294.670734)
		(end 160.751774 -294.03548)
		(width 0.18288)
		(layer "In6.Cu")
		(net "M_G_CPU1_SA_DQ<11>")
	)
	(segment
		(start 186.428126 -304.10658)
		(end 185.909712 -303.588166)
		(width 0.18288)
		(layer "In6.Cu")
		(net "M_G_CPU1_SA_DQ<11>")
	)
	(segment
		(start 153.401522 -290.138358)
		(end 153.401522 -281.314652)
		(width 0.18288)
		(layer "In6.Cu")
		(net "M_G_CPU1_SA_DQ<11>")
	)
	(segment
		(start 163.202112 -295.491408)
		(end 162.381438 -294.670734)
		(width 0.18288)
		(layer "In6.Cu")
		(net "M_G_CPU1_SA_DQ<11>")
	)
	(segment
		(start 171.816268 -298.042584)
		(end 171.702984 -298.155868)
		(width 0.18288)
		(layer "In6.Cu")
		(net "M_G_CPU1_SA_DQ<11>")
	)
	(segment
		(start 168.946068 -298.155868)
		(end 168.110916 -297.320716)
		(width 0.18288)
		(layer "In6.Cu")
		(net "M_G_CPU1_SA_DQ<11>")
	)
	(segment
		(start 170.950382 -298.155868)
		(end 170.790362 -297.995848)
		(width 0.18288)
		(layer "In6.Cu")
		(net "M_G_CPU1_SA_DQ<11>")
	)
	(segment
		(start 160.751774 -294.03548)
		(end 157.298644 -294.03548)
		(width 0.18288)
		(layer "In6.Cu")
		(net "M_G_CPU1_SA_DQ<11>")
	)
	(segment
		(start 134.507478 -273.76882)
		(end 134.492746 -273.777456)
		(width 0.088646)
		(layer "In6.Cu")
		(net "M_G_CPU1_SA_DQ<11>")
	)
	(segment
		(start 157.298644 -294.03548)
		(end 153.401522 -290.138358)
		(width 0.18288)
		(layer "In6.Cu")
		(net "M_G_CPU1_SA_DQ<11>")
	)
	(segment
		(start 129.419096 -273.777456)
		(end 129.021332 -273.548094)
		(width 0.088646)
		(layer "In6.Cu")
		(net "M_G_CPU1_SA_DQ<11>")
	)
	(segment
		(start 170.790362 -297.712892)
		(end 170.630342 -297.552872)
		(width 0.18288)
		(layer "In6.Cu")
		(net "M_G_CPU1_SA_DQ<11>")
	)
	(segment
		(start 147.648422 -275.560536)
		(end 141.936978 -275.560536)
		(width 0.18288)
		(layer "In6.Cu")
		(net "M_G_CPU1_SA_DQ<11>")
	)
	(segment
		(start 186.979814 -303.99228)
		(end 186.865514 -304.10658)
		(width 0.18288)
		(layer "In6.Cu")
		(net "M_G_CPU1_SA_DQ<11>")
	)
	(segment
		(start 170.096942 -297.995848)
		(end 169.936922 -298.155868)
		(width 0.18288)
		(layer "In6.Cu")
		(net "M_G_CPU1_SA_DQ<11>")
	)
	(segment
		(start 135.44296 -273.77136)
		(end 135.432546 -273.777456)
		(width 0.088646)
		(layer "In6.Cu")
		(net "M_G_CPU1_SA_DQ<11>")
	)
	(segment
		(start 189.253876 -304.682652)
		(end 189.093856 -304.842672)
		(width 0.18288)
		(layer "In6.Cu")
		(net "M_G_CPU1_SA_DQ<11>")
	)
	(segment
		(start 140.199618 -274.819364)
		(end 139.082018 -273.701764)
		(width 0.088646)
		(layer "In6.Cu")
		(net "M_G_CPU1_SA_DQ<11>")
	)
	(segment
		(start 130.748278 -273.76882)
		(end 130.733546 -273.777456)
		(width 0.088646)
		(layer "In6.Cu")
		(net "M_G_CPU1_SA_DQ<11>")
	)
	(segment
		(start 130.358896 -273.777456)
		(end 130.353054 -273.774154)
		(width 0.088646)
		(layer "In6.Cu")
		(net "M_G_CPU1_SA_DQ<11>")
	)
	(segment
		(start 179.024026 -299.889926)
		(end 178.026568 -298.892468)
		(width 0.18288)
		(layer "In6.Cu")
		(net "M_G_CPU1_SA_DQ<11>")
	)
	(segment
		(start 140.199618 -274.968716)
		(end 140.199618 -274.819364)
		(width 0.088646)
		(layer "In6.Cu")
		(net "M_G_CPU1_SA_DQ<11>")
	)
	(segment
		(start 153.401522 -281.314652)
		(end 147.648422 -275.560536)
		(width 0.18288)
		(layer "In6.Cu")
		(net "M_G_CPU1_SA_DQ<11>")
	)
	(segment
		(start 178.026568 -298.892468)
		(end 174.595282 -298.892468)
		(width 0.18288)
		(layer "In6.Cu")
		(net "M_G_CPU1_SA_DQ<11>")
	)
	(segment
		(start 182.932832 -301.439072)
		(end 181.789832 -301.439072)
		(width 0.18288)
		(layer "In6.Cu")
		(net "M_G_CPU1_SA_DQ<11>")
	)
	(segment
		(start 167.374062 -297.320716)
		(end 165.544754 -295.491408)
		(width 0.18288)
		(layer "In6.Cu")
		(net "M_G_CPU1_SA_DQ<11>")
	)
	(segment
		(start 185.081926 -303.588166)
		(end 182.932832 -301.439072)
		(width 0.18288)
		(layer "In6.Cu")
		(net "M_G_CPU1_SA_DQ<11>")
	)
	(segment
		(start 131.688078 -273.76882)
		(end 131.673346 -273.777456)
		(width 0.088646)
		(layer "In6.Cu")
		(net "M_G_CPU1_SA_DQ<11>")
	)
	(arc
		(start 132.613146 -273.777456)
		(mid 132.425948 -273.827599)
		(end 132.23875 -273.777456)
		(width 0.088646)
		(layer "In6.Cu")
		(net "M_G_CPU1_SA_DQ<11>")
	)
	(arc
		(start 131.673346 -273.777456)
		(mid 131.486148 -273.827599)
		(end 131.29895 -273.777456)
		(width 0.088646)
		(layer "In6.Cu")
		(net "M_G_CPU1_SA_DQ<11>")
	)
	(arc
		(start 129.793746 -273.777456)
		(mid 129.609822 -273.82771)
		(end 129.424938 -273.781012)
		(width 0.088646)
		(layer "In6.Cu")
		(net "M_G_CPU1_SA_DQ<11>")
	)
	(arc
		(start 136.372092 -273.777456)
		(mid 136.184894 -273.827599)
		(end 135.997696 -273.777456)
		(width 0.088646)
		(layer "In6.Cu")
		(net "M_G_CPU1_SA_DQ<11>")
	)
	(arc
		(start 133.552946 -273.777456)
		(mid 133.365748 -273.827599)
		(end 133.17855 -273.777456)
		(width 0.088646)
		(layer "In6.Cu")
		(net "M_G_CPU1_SA_DQ<11>")
	)
	(arc
		(start 135.432546 -273.777456)
		(mid 135.245348 -273.827599)
		(end 135.05815 -273.777456)
		(width 0.088646)
		(layer "In6.Cu")
		(net "M_G_CPU1_SA_DQ<11>")
	)
	(arc
		(start 132.23875 -273.777456)
		(mid 131.964551 -273.701621)
		(end 131.688078 -273.76882)
		(width 0.088646)
		(layer "In6.Cu")
		(net "M_G_CPU1_SA_DQ<11>")
	)
	(arc
		(start 135.997696 -273.777456)
		(mid 135.721137 -273.701713)
		(end 135.44296 -273.77136)
		(width 0.088646)
		(layer "In6.Cu")
		(net "M_G_CPU1_SA_DQ<11>")
	)
	(arc
		(start 134.11835 -273.777456)
		(mid 133.844151 -273.701621)
		(end 133.567678 -273.76882)
		(width 0.088646)
		(layer "In6.Cu")
		(net "M_G_CPU1_SA_DQ<11>")
	)
	(arc
		(start 138.251692 -273.777456)
		(mid 138.064494 -273.827599)
		(end 137.877296 -273.777456)
		(width 0.088646)
		(layer "In6.Cu")
		(net "M_G_CPU1_SA_DQ<11>")
	)
	(arc
		(start 134.492746 -273.777456)
		(mid 134.305548 -273.827599)
		(end 134.11835 -273.777456)
		(width 0.088646)
		(layer "In6.Cu")
		(net "M_G_CPU1_SA_DQ<11>")
	)
	(arc
		(start 136.937496 -273.777456)
		(mid 136.654794 -273.70168)
		(end 136.372092 -273.777456)
		(width 0.088646)
		(layer "In6.Cu")
		(net "M_G_CPU1_SA_DQ<11>")
	)
	(arc
		(start 135.05815 -273.777456)
		(mid 134.783951 -273.701621)
		(end 134.507478 -273.76882)
		(width 0.088646)
		(layer "In6.Cu")
		(net "M_G_CPU1_SA_DQ<11>")
	)
	(arc
		(start 138.534394 -273.701764)
		(mid 138.388071 -273.721026)
		(end 138.251692 -273.777456)
		(width 0.088646)
		(layer "In6.Cu")
		(net "M_G_CPU1_SA_DQ<11>")
	)
	(arc
		(start 130.353054 -273.774154)
		(mid 130.072949 -273.701712)
		(end 129.793746 -273.777456)
		(width 0.088646)
		(layer "In6.Cu")
		(net "M_G_CPU1_SA_DQ<11>")
	)
	(arc
		(start 130.733546 -273.777456)
		(mid 130.549622 -273.82771)
		(end 130.364738 -273.781012)
		(width 0.088646)
		(layer "In6.Cu")
		(net "M_G_CPU1_SA_DQ<11>")
	)
	(arc
		(start 129.021332 -273.548094)
		(mid 128.85028 -273.477313)
		(end 128.666748 -273.453098)
		(width 0.088646)
		(layer "In6.Cu")
		(net "M_G_CPU1_SA_DQ<11>")
	)
	(arc
		(start 137.311892 -273.777456)
		(mid 137.124694 -273.827599)
		(end 136.937496 -273.777456)
		(width 0.088646)
		(layer "In6.Cu")
		(net "M_G_CPU1_SA_DQ<11>")
	)
	(arc
		(start 133.17855 -273.777456)
		(mid 132.895848 -273.70168)
		(end 132.613146 -273.777456)
		(width 0.088646)
		(layer "In6.Cu")
		(net "M_G_CPU1_SA_DQ<11>")
	)
	(arc
		(start 137.877296 -273.777456)
		(mid 137.594594 -273.70168)
		(end 137.311892 -273.777456)
		(width 0.088646)
		(layer "In6.Cu")
		(net "M_G_CPU1_SA_DQ<11>")
	)
	(arc
		(start 131.29895 -273.777456)
		(mid 131.024751 -273.701621)
		(end 130.748278 -273.76882)
		(width 0.088646)
		(layer "In6.Cu")
		(net "M_G_CPU1_SA_DQ<11>")
	)
	(segment
		(start 195.510658 -306.54879)
		(end 195.515484 -306.54879)
		(width 0.101854)
		(layer "F.Cu")
		(net "M_G_CPU1_SA_DQ<10>")
	)
	(segment
		(start 198.427848 -306.349908)
		(end 198.427848 -306.098956)
		(width 0.20066)
		(layer "F.Cu")
		(net "M_G_CPU1_SA_DQ<10>")
	)
	(segment
		(start 199.298052 -306.116736)
		(end 200.632314 -306.116736)
		(width 0.20066)
		(layer "F.Cu")
		(net "M_G_CPU1_SA_DQ<10>")
	)
	(segment
		(start 191.983614 -306.116736)
		(end 193.088514 -306.116736)
		(width 0.20066)
		(layer "F.Cu")
		(net "M_G_CPU1_SA_DQ<10>")
	)
	(segment
		(start 198.223886 -306.55387)
		(end 198.427848 -306.349908)
		(width 0.20066)
		(layer "F.Cu")
		(net "M_G_CPU1_SA_DQ<10>")
	)
	(segment
		(start 128.196848 -274.26666)
		(end 128.196594 -274.266914)
		(width 0.20066)
		(layer "F.Cu")
		(net "M_G_CPU1_SA_DQ<10>")
	)
	(segment
		(start 199.046084 -305.864768)
		(end 199.298052 -306.116736)
		(width 0.20066)
		(layer "F.Cu")
		(net "M_G_CPU1_SA_DQ<10>")
	)
	(segment
		(start 195.522596 -306.541678)
		(end 197.530466 -306.541678)
		(width 0.1016)
		(layer "F.Cu")
		(net "M_G_CPU1_SA_DQ<10>")
	)
	(segment
		(start 197.542658 -306.55387)
		(end 198.223886 -306.55387)
		(width 0.20066)
		(layer "F.Cu")
		(net "M_G_CPU1_SA_DQ<10>")
	)
	(segment
		(start 198.427848 -306.098956)
		(end 198.662036 -305.864768)
		(width 0.20066)
		(layer "F.Cu")
		(net "M_G_CPU1_SA_DQ<10>")
	)
	(segment
		(start 198.662036 -305.864768)
		(end 199.046084 -305.864768)
		(width 0.20066)
		(layer "F.Cu")
		(net "M_G_CPU1_SA_DQ<10>")
	)
	(segment
		(start 193.088514 -306.116736)
		(end 194.786758 -306.116736)
		(width 0.20066)
		(layer "F.Cu")
		(net "M_G_CPU1_SA_DQ<10>")
	)
	(segment
		(start 197.530466 -306.541678)
		(end 197.542658 -306.55387)
		(width 0.1016)
		(layer "F.Cu")
		(net "M_G_CPU1_SA_DQ<10>")
	)
	(segment
		(start 128.196848 -273.730974)
		(end 128.196848 -274.26666)
		(width 0.20066)
		(layer "F.Cu")
		(net "M_G_CPU1_SA_DQ<10>")
	)
	(segment
		(start 195.515484 -306.54879)
		(end 195.522596 -306.541678)
		(width 0.1016)
		(layer "F.Cu")
		(net "M_G_CPU1_SA_DQ<10>")
	)
	(segment
		(start 195.218812 -306.54879)
		(end 195.510658 -306.54879)
		(width 0.20066)
		(layer "F.Cu")
		(net "M_G_CPU1_SA_DQ<10>")
	)
	(segment
		(start 194.786758 -306.116736)
		(end 195.218812 -306.54879)
		(width 0.20066)
		(layer "F.Cu")
		(net "M_G_CPU1_SA_DQ<10>")
	)
	(segment
		(start 191.983614 -305.830478)
		(end 191.800734 -305.647598)
		(width 0.18288)
		(layer "In6.Cu")
		(net "M_G_CPU1_SA_DQ<10>")
	)
	(segment
		(start 140.881608 -276.201378)
		(end 140.016484 -276.201378)
		(width 0.18288)
		(layer "In6.Cu")
		(net "M_G_CPU1_SA_DQ<10>")
	)
	(segment
		(start 162.527996 -296.409872)
		(end 161.940748 -296.409872)
		(width 0.18288)
		(layer "In6.Cu")
		(net "M_G_CPU1_SA_DQ<10>")
	)
	(segment
		(start 127.826516 -274.324318)
		(end 127.88392 -274.266914)
		(width 0.088646)
		(layer "In6.Cu")
		(net "M_G_CPU1_SA_DQ<10>")
	)
	(segment
		(start 152.405842 -290.550854)
		(end 152.405842 -281.727402)
		(width 0.18288)
		(layer "In6.Cu")
		(net "M_G_CPU1_SA_DQ<10>")
	)
	(segment
		(start 168.28008 -299.115226)
		(end 167.32377 -299.115226)
		(width 0.18288)
		(layer "In6.Cu")
		(net "M_G_CPU1_SA_DQ<10>")
	)
	(segment
		(start 171.632372 -299.92828)
		(end 169.093134 -299.92828)
		(width 0.18288)
		(layer "In6.Cu")
		(net "M_G_CPU1_SA_DQ<10>")
	)
	(segment
		(start 189.99581 -305.692302)
		(end 185.882788 -305.692302)
		(width 0.18288)
		(layer "In6.Cu")
		(net "M_G_CPU1_SA_DQ<10>")
	)
	(segment
		(start 139.650978 -275.835872)
		(end 139.556998 -275.741892)
		(width 0.088646)
		(layer "In6.Cu")
		(net "M_G_CPU1_SA_DQ<10>")
	)
	(segment
		(start 129.888996 -274.591272)
		(end 129.874264 -274.582636)
		(width 0.088646)
		(layer "In6.Cu")
		(net "M_G_CPU1_SA_DQ<10>")
	)
	(segment
		(start 190.198248 -305.489864)
		(end 189.99581 -305.692302)
		(width 0.18288)
		(layer "In6.Cu")
		(net "M_G_CPU1_SA_DQ<10>")
	)
	(segment
		(start 185.882788 -305.692302)
		(end 184.98058 -304.790094)
		(width 0.18288)
		(layer "In6.Cu")
		(net "M_G_CPU1_SA_DQ<10>")
	)
	(segment
		(start 133.09346 -274.585176)
		(end 133.083046 -274.591272)
		(width 0.088646)
		(layer "In6.Cu")
		(net "M_G_CPU1_SA_DQ<10>")
	)
	(segment
		(start 190.875412 -305.647598)
		(end 190.717678 -305.489864)
		(width 0.18288)
		(layer "In6.Cu")
		(net "M_G_CPU1_SA_DQ<10>")
	)
	(segment
		(start 152.405842 -281.727402)
		(end 147.235926 -276.556216)
		(width 0.18288)
		(layer "In6.Cu")
		(net "M_G_CPU1_SA_DQ<10>")
	)
	(segment
		(start 161.939986 -296.40911)
		(end 161.152586 -296.40911)
		(width 0.18288)
		(layer "In6.Cu")
		(net "M_G_CPU1_SA_DQ<10>")
	)
	(segment
		(start 161.940748 -296.409872)
		(end 161.939986 -296.40911)
		(width 0.18288)
		(layer "In6.Cu")
		(net "M_G_CPU1_SA_DQ<10>")
	)
	(segment
		(start 191.800734 -305.647598)
		(end 190.875412 -305.647598)
		(width 0.18288)
		(layer "In6.Cu")
		(net "M_G_CPU1_SA_DQ<10>")
	)
	(segment
		(start 140.016484 -276.201378)
		(end 139.650978 -275.835872)
		(width 0.18288)
		(layer "In6.Cu")
		(net "M_G_CPU1_SA_DQ<10>")
	)
	(segment
		(start 171.8183 -299.742352)
		(end 171.632372 -299.92828)
		(width 0.18288)
		(layer "In6.Cu")
		(net "M_G_CPU1_SA_DQ<10>")
	)
	(segment
		(start 141.73835 -276.556216)
		(end 140.881608 -276.201378)
		(width 0.18288)
		(layer "In6.Cu")
		(net "M_G_CPU1_SA_DQ<10>")
	)
	(segment
		(start 128.009396 -274.591272)
		(end 128.000506 -274.586192)
		(width 0.088646)
		(layer "In6.Cu")
		(net "M_G_CPU1_SA_DQ<10>")
	)
	(segment
		(start 163.308792 -297.190668)
		(end 162.527996 -296.409872)
		(width 0.18288)
		(layer "In6.Cu")
		(net "M_G_CPU1_SA_DQ<10>")
	)
	(segment
		(start 134.587996 -274.591272)
		(end 134.573264 -274.582636)
		(width 0.088646)
		(layer "In6.Cu")
		(net "M_G_CPU1_SA_DQ<10>")
	)
	(segment
		(start 191.983614 -306.116736)
		(end 191.983614 -305.830478)
		(width 0.18288)
		(layer "In6.Cu")
		(net "M_G_CPU1_SA_DQ<10>")
	)
	(segment
		(start 174.606712 -300.592236)
		(end 173.756828 -299.742352)
		(width 0.18288)
		(layer "In6.Cu")
		(net "M_G_CPU1_SA_DQ<10>")
	)
	(segment
		(start 180.758846 -302.32985)
		(end 179.733448 -302.32985)
		(width 0.18288)
		(layer "In6.Cu")
		(net "M_G_CPU1_SA_DQ<10>")
	)
	(segment
		(start 177.995834 -300.592236)
		(end 174.606712 -300.592236)
		(width 0.18288)
		(layer "In6.Cu")
		(net "M_G_CPU1_SA_DQ<10>")
	)
	(segment
		(start 184.98058 -304.790094)
		(end 184.178702 -304.790094)
		(width 0.18288)
		(layer "In6.Cu")
		(net "M_G_CPU1_SA_DQ<10>")
	)
	(segment
		(start 127.88392 -274.266914)
		(end 128.196594 -274.266914)
		(width 0.088646)
		(layer "In6.Cu")
		(net "M_G_CPU1_SA_DQ<10>")
	)
	(segment
		(start 139.615418 -274.844764)
		(end 139.28598 -274.515326)
		(width 0.088646)
		(layer "In6.Cu")
		(net "M_G_CPU1_SA_DQ<10>")
	)
	(segment
		(start 139.28598 -274.515326)
		(end 138.064748 -274.515326)
		(width 0.088646)
		(layer "In6.Cu")
		(net "M_G_CPU1_SA_DQ<10>")
	)
	(segment
		(start 169.093134 -299.92828)
		(end 168.28008 -299.115226)
		(width 0.18288)
		(layer "In6.Cu")
		(net "M_G_CPU1_SA_DQ<10>")
	)
	(segment
		(start 161.152586 -296.40911)
		(end 160.452562 -295.709086)
		(width 0.18288)
		(layer "In6.Cu")
		(net "M_G_CPU1_SA_DQ<10>")
	)
	(segment
		(start 167.32377 -299.115226)
		(end 165.399212 -297.190668)
		(width 0.18288)
		(layer "In6.Cu")
		(net "M_G_CPU1_SA_DQ<10>")
	)
	(segment
		(start 132.70865 -274.591272)
		(end 132.698236 -274.585176)
		(width 0.088646)
		(layer "In6.Cu")
		(net "M_G_CPU1_SA_DQ<10>")
	)
	(segment
		(start 139.556998 -275.422614)
		(end 139.615418 -275.28139)
		(width 0.088646)
		(layer "In6.Cu")
		(net "M_G_CPU1_SA_DQ<10>")
	)
	(segment
		(start 147.235926 -276.556216)
		(end 141.73835 -276.556216)
		(width 0.18288)
		(layer "In6.Cu")
		(net "M_G_CPU1_SA_DQ<10>")
	)
	(segment
		(start 179.733448 -302.32985)
		(end 177.995834 -300.592236)
		(width 0.18288)
		(layer "In6.Cu")
		(net "M_G_CPU1_SA_DQ<10>")
	)
	(segment
		(start 157.564074 -295.709086)
		(end 152.405842 -290.550854)
		(width 0.18288)
		(layer "In6.Cu")
		(net "M_G_CPU1_SA_DQ<10>")
	)
	(segment
		(start 184.178702 -304.790094)
		(end 183.31688 -303.928272)
		(width 0.18288)
		(layer "In6.Cu")
		(net "M_G_CPU1_SA_DQ<10>")
	)
	(segment
		(start 173.756828 -299.742352)
		(end 171.8183 -299.742352)
		(width 0.18288)
		(layer "In6.Cu")
		(net "M_G_CPU1_SA_DQ<10>")
	)
	(segment
		(start 165.399212 -297.190668)
		(end 163.308792 -297.190668)
		(width 0.18288)
		(layer "In6.Cu")
		(net "M_G_CPU1_SA_DQ<10>")
	)
	(segment
		(start 182.357268 -303.928272)
		(end 180.758846 -302.32985)
		(width 0.18288)
		(layer "In6.Cu")
		(net "M_G_CPU1_SA_DQ<10>")
	)
	(segment
		(start 136.467596 -274.591272)
		(end 136.452864 -274.582636)
		(width 0.088646)
		(layer "In6.Cu")
		(net "M_G_CPU1_SA_DQ<10>")
	)
	(segment
		(start 131.768596 -274.591272)
		(end 131.753864 -274.582636)
		(width 0.088646)
		(layer "In6.Cu")
		(net "M_G_CPU1_SA_DQ<10>")
	)
	(segment
		(start 135.527796 -274.591272)
		(end 135.513064 -274.582636)
		(width 0.088646)
		(layer "In6.Cu")
		(net "M_G_CPU1_SA_DQ<10>")
	)
	(segment
		(start 139.556998 -275.741892)
		(end 139.556998 -275.422614)
		(width 0.088646)
		(layer "In6.Cu")
		(net "M_G_CPU1_SA_DQ<10>")
	)
	(segment
		(start 128.949196 -274.591272)
		(end 128.934464 -274.582636)
		(width 0.088646)
		(layer "In6.Cu")
		(net "M_G_CPU1_SA_DQ<10>")
	)
	(segment
		(start 183.31688 -303.928272)
		(end 182.357268 -303.928272)
		(width 0.18288)
		(layer "In6.Cu")
		(net "M_G_CPU1_SA_DQ<10>")
	)
	(segment
		(start 130.828796 -274.591272)
		(end 130.814064 -274.582636)
		(width 0.088646)
		(layer "In6.Cu")
		(net "M_G_CPU1_SA_DQ<10>")
	)
	(segment
		(start 160.452562 -295.709086)
		(end 157.564074 -295.709086)
		(width 0.18288)
		(layer "In6.Cu")
		(net "M_G_CPU1_SA_DQ<10>")
	)
	(segment
		(start 190.717678 -305.489864)
		(end 190.198248 -305.489864)
		(width 0.18288)
		(layer "In6.Cu")
		(net "M_G_CPU1_SA_DQ<10>")
	)
	(segment
		(start 139.615418 -275.28139)
		(end 139.615418 -274.844764)
		(width 0.088646)
		(layer "In6.Cu")
		(net "M_G_CPU1_SA_DQ<10>")
	)
	(segment
		(start 137.407396 -274.591272)
		(end 137.392664 -274.582636)
		(width 0.088646)
		(layer "In6.Cu")
		(net "M_G_CPU1_SA_DQ<10>")
	)
	(arc
		(start 129.323592 -274.591272)
		(mid 129.136394 -274.641415)
		(end 128.949196 -274.591272)
		(width 0.088646)
		(layer "In6.Cu")
		(net "M_G_CPU1_SA_DQ<10>")
	)
	(arc
		(start 129.874264 -274.582636)
		(mid 129.597789 -274.515316)
		(end 129.323592 -274.591272)
		(width 0.088646)
		(layer "In6.Cu")
		(net "M_G_CPU1_SA_DQ<10>")
	)
	(arc
		(start 135.902192 -274.591272)
		(mid 135.714994 -274.641415)
		(end 135.527796 -274.591272)
		(width 0.088646)
		(layer "In6.Cu")
		(net "M_G_CPU1_SA_DQ<10>")
	)
	(arc
		(start 137.392664 -274.582636)
		(mid 137.116223 -274.51547)
		(end 136.841992 -274.591272)
		(width 0.088646)
		(layer "In6.Cu")
		(net "M_G_CPU1_SA_DQ<10>")
	)
	(arc
		(start 136.452864 -274.582636)
		(mid 136.176423 -274.51547)
		(end 135.902192 -274.591272)
		(width 0.088646)
		(layer "In6.Cu")
		(net "M_G_CPU1_SA_DQ<10>")
	)
	(arc
		(start 132.142992 -274.591272)
		(mid 131.955794 -274.641415)
		(end 131.768596 -274.591272)
		(width 0.088646)
		(layer "In6.Cu")
		(net "M_G_CPU1_SA_DQ<10>")
	)
	(arc
		(start 133.083046 -274.591272)
		(mid 132.895848 -274.641415)
		(end 132.70865 -274.591272)
		(width 0.088646)
		(layer "In6.Cu")
		(net "M_G_CPU1_SA_DQ<10>")
	)
	(arc
		(start 130.814064 -274.582636)
		(mid 130.537589 -274.515316)
		(end 130.263392 -274.591272)
		(width 0.088646)
		(layer "In6.Cu")
		(net "M_G_CPU1_SA_DQ<10>")
	)
	(arc
		(start 134.962392 -274.591272)
		(mid 134.775194 -274.641415)
		(end 134.587996 -274.591272)
		(width 0.088646)
		(layer "In6.Cu")
		(net "M_G_CPU1_SA_DQ<10>")
	)
	(arc
		(start 128.000506 -274.586192)
		(mid 127.884767 -274.474368)
		(end 127.826516 -274.324318)
		(width 0.088646)
		(layer "In6.Cu")
		(net "M_G_CPU1_SA_DQ<10>")
	)
	(arc
		(start 131.203192 -274.591272)
		(mid 131.015994 -274.641415)
		(end 130.828796 -274.591272)
		(width 0.088646)
		(layer "In6.Cu")
		(net "M_G_CPU1_SA_DQ<10>")
	)
	(arc
		(start 134.573264 -274.582636)
		(mid 134.296789 -274.515316)
		(end 134.022592 -274.591272)
		(width 0.088646)
		(layer "In6.Cu")
		(net "M_G_CPU1_SA_DQ<10>")
	)
	(arc
		(start 134.022592 -274.591272)
		(mid 133.835394 -274.641415)
		(end 133.648196 -274.591272)
		(width 0.088646)
		(layer "In6.Cu")
		(net "M_G_CPU1_SA_DQ<10>")
	)
	(arc
		(start 137.781792 -274.591272)
		(mid 137.594594 -274.641415)
		(end 137.407396 -274.591272)
		(width 0.088646)
		(layer "In6.Cu")
		(net "M_G_CPU1_SA_DQ<10>")
	)
	(arc
		(start 128.383792 -274.591272)
		(mid 128.196594 -274.641415)
		(end 128.009396 -274.591272)
		(width 0.088646)
		(layer "In6.Cu")
		(net "M_G_CPU1_SA_DQ<10>")
	)
	(arc
		(start 132.698236 -274.585176)
		(mid 132.419804 -274.51533)
		(end 132.142992 -274.591272)
		(width 0.088646)
		(layer "In6.Cu")
		(net "M_G_CPU1_SA_DQ<10>")
	)
	(arc
		(start 136.841992 -274.591272)
		(mid 136.654794 -274.641415)
		(end 136.467596 -274.591272)
		(width 0.088646)
		(layer "In6.Cu")
		(net "M_G_CPU1_SA_DQ<10>")
	)
	(arc
		(start 138.064748 -274.515326)
		(mid 137.918273 -274.534679)
		(end 137.781792 -274.591272)
		(width 0.088646)
		(layer "In6.Cu")
		(net "M_G_CPU1_SA_DQ<10>")
	)
	(arc
		(start 133.648196 -274.591272)
		(mid 133.371637 -274.515529)
		(end 133.09346 -274.585176)
		(width 0.088646)
		(layer "In6.Cu")
		(net "M_G_CPU1_SA_DQ<10>")
	)
	(arc
		(start 135.513064 -274.582636)
		(mid 135.236623 -274.51547)
		(end 134.962392 -274.591272)
		(width 0.088646)
		(layer "In6.Cu")
		(net "M_G_CPU1_SA_DQ<10>")
	)
	(arc
		(start 131.753864 -274.582636)
		(mid 131.477389 -274.515316)
		(end 131.203192 -274.591272)
		(width 0.088646)
		(layer "In6.Cu")
		(net "M_G_CPU1_SA_DQ<10>")
	)
	(arc
		(start 128.934464 -274.582636)
		(mid 128.657989 -274.515316)
		(end 128.383792 -274.591272)
		(width 0.088646)
		(layer "In6.Cu")
		(net "M_G_CPU1_SA_DQ<10>")
	)
	(arc
		(start 130.263392 -274.591272)
		(mid 130.076194 -274.641415)
		(end 129.888996 -274.591272)
		(width 0.088646)
		(layer "In6.Cu")
		(net "M_G_CPU1_SA_DQ<10>")
	)
	(segment
		(start 196.532246 -316.316614)
		(end 196.531992 -316.316868)
		(width 0.20066)
		(layer "F.Cu")
		(net "M_G_CPU1_SA_DQ<0>")
	)
	(segment
		(start 191.930782 -315.891672)
		(end 191.883792 -315.891672)
		(width 0.101854)
		(layer "F.Cu")
		(net "M_G_CPU1_SA_DQ<0>")
	)
	(segment
		(start 191.421004 -316.37732)
		(end 191.233044 -316.56528)
		(width 0.20066)
		(layer "F.Cu")
		(net "M_G_CPU1_SA_DQ<0>")
	)
	(segment
		(start 194.092576 -315.891672)
		(end 191.930782 -315.891672)
		(width 0.1016)
		(layer "F.Cu")
		(net "M_G_CPU1_SA_DQ<0>")
	)
	(segment
		(start 194.098926 -315.885322)
		(end 194.092576 -315.891672)
		(width 0.1016)
		(layer "F.Cu")
		(net "M_G_CPU1_SA_DQ<0>")
	)
	(segment
		(start 194.508882 -315.885322)
		(end 194.098926 -315.885322)
		(width 0.20066)
		(layer "F.Cu")
		(net "M_G_CPU1_SA_DQ<0>")
	)
	(segment
		(start 194.940428 -316.316868)
		(end 194.508882 -315.885322)
		(width 0.20066)
		(layer "F.Cu")
		(net "M_G_CPU1_SA_DQ<0>")
	)
	(segment
		(start 190.75781 -316.56528)
		(end 190.509144 -316.316614)
		(width 0.20066)
		(layer "F.Cu")
		(net "M_G_CPU1_SA_DQ<0>")
	)
	(segment
		(start 130.546094 -276.172676)
		(end 130.546348 -276.708616)
		(width 0.20066)
		(layer "F.Cu")
		(net "M_G_CPU1_SA_DQ<0>")
	)
	(segment
		(start 191.539114 -315.891672)
		(end 191.421004 -316.009782)
		(width 0.20066)
		(layer "F.Cu")
		(net "M_G_CPU1_SA_DQ<0>")
	)
	(segment
		(start 191.421004 -316.009782)
		(end 191.421004 -316.37732)
		(width 0.20066)
		(layer "F.Cu")
		(net "M_G_CPU1_SA_DQ<0>")
	)
	(segment
		(start 188.988446 -316.316614)
		(end 187.883546 -316.316614)
		(width 0.20066)
		(layer "F.Cu")
		(net "M_G_CPU1_SA_DQ<0>")
	)
	(segment
		(start 191.233044 -316.56528)
		(end 190.75781 -316.56528)
		(width 0.20066)
		(layer "F.Cu")
		(net "M_G_CPU1_SA_DQ<0>")
	)
	(segment
		(start 196.531992 -316.316868)
		(end 194.940428 -316.316868)
		(width 0.20066)
		(layer "F.Cu")
		(net "M_G_CPU1_SA_DQ<0>")
	)
	(segment
		(start 191.883792 -315.891672)
		(end 191.539114 -315.891672)
		(width 0.20066)
		(layer "F.Cu")
		(net "M_G_CPU1_SA_DQ<0>")
	)
	(segment
		(start 190.509144 -316.316614)
		(end 188.988446 -316.316614)
		(width 0.20066)
		(layer "F.Cu")
		(net "M_G_CPU1_SA_DQ<0>")
	)
	(segment
		(start 158.708598 -314.249308)
		(end 153.46172 -309.00243)
		(width 0.18288)
		(layer "In4.Cu")
		(net "M_G_CPU1_SA_DQ<0>")
	)
	(segment
		(start 175.235362 -318.812926)
		(end 175.235362 -318.371474)
		(width 0.18288)
		(layer "In4.Cu")
		(net "M_G_CPU1_SA_DQ<0>")
	)
	(segment
		(start 160.364932 -314.249308)
		(end 158.708598 -314.249308)
		(width 0.18288)
		(layer "In4.Cu")
		(net "M_G_CPU1_SA_DQ<0>")
	)
	(segment
		(start 165.56355 -316.565026)
		(end 164.861748 -315.863224)
		(width 0.18288)
		(layer "In4.Cu")
		(net "M_G_CPU1_SA_DQ<0>")
	)
	(segment
		(start 131.768596 -277.198074)
		(end 131.758182 -277.20417)
		(width 0.088646)
		(layer "In4.Cu")
		(net "M_G_CPU1_SA_DQ<0>")
	)
	(segment
		(start 186.931554 -317.268606)
		(end 186.295538 -317.268606)
		(width 0.18288)
		(layer "In4.Cu")
		(net "M_G_CPU1_SA_DQ<0>")
	)
	(segment
		(start 176.31283 -318.442848)
		(end 175.782732 -318.972946)
		(width 0.18288)
		(layer "In4.Cu")
		(net "M_G_CPU1_SA_DQ<0>")
	)
	(segment
		(start 140.653516 -283.311346)
		(end 139.847828 -281.36596)
		(width 0.18288)
		(layer "In4.Cu")
		(net "M_G_CPU1_SA_DQ<0>")
	)
	(segment
		(start 174.515272 -318.371474)
		(end 174.515272 -318.812926)
		(width 0.18288)
		(layer "In4.Cu")
		(net "M_G_CPU1_SA_DQ<0>")
	)
	(segment
		(start 140.653516 -284.535372)
		(end 140.653516 -283.311346)
		(width 0.18288)
		(layer "In4.Cu")
		(net "M_G_CPU1_SA_DQ<0>")
	)
	(segment
		(start 174.355252 -318.972946)
		(end 171.125388 -318.972946)
		(width 0.18288)
		(layer "In4.Cu")
		(net "M_G_CPU1_SA_DQ<0>")
	)
	(segment
		(start 175.782732 -318.972946)
		(end 175.395382 -318.972946)
		(width 0.18288)
		(layer "In4.Cu")
		(net "M_G_CPU1_SA_DQ<0>")
	)
	(segment
		(start 169.065702 -317.59271)
		(end 168.038018 -316.565026)
		(width 0.18288)
		(layer "In4.Cu")
		(net "M_G_CPU1_SA_DQ<0>")
	)
	(segment
		(start 130.924554 -276.774148)
		(end 130.859022 -276.708616)
		(width 0.088646)
		(layer "In4.Cu")
		(net "M_G_CPU1_SA_DQ<0>")
	)
	(segment
		(start 135.997696 -279.639776)
		(end 135.987282 -279.645872)
		(width 0.088646)
		(layer "In4.Cu")
		(net "M_G_CPU1_SA_DQ<0>")
	)
	(segment
		(start 187.883546 -316.316614)
		(end 186.931554 -317.268606)
		(width 0.18288)
		(layer "In4.Cu")
		(net "M_G_CPU1_SA_DQ<0>")
	)
	(segment
		(start 178.834542 -319.084452)
		(end 178.458622 -319.084452)
		(width 0.18288)
		(layer "In4.Cu")
		(net "M_G_CPU1_SA_DQ<0>")
	)
	(segment
		(start 133.648196 -277.198074)
		(end 133.633464 -277.20671)
		(width 0.088646)
		(layer "In4.Cu")
		(net "M_G_CPU1_SA_DQ<0>")
	)
	(segment
		(start 182.49519 -316.590426)
		(end 180.581046 -318.50457)
		(width 0.18288)
		(layer "In4.Cu")
		(net "M_G_CPU1_SA_DQ<0>")
	)
	(segment
		(start 163.375086 -315.863224)
		(end 162.620452 -315.10859)
		(width 0.18288)
		(layer "In4.Cu")
		(net "M_G_CPU1_SA_DQ<0>")
	)
	(segment
		(start 138.11504 -280.18613)
		(end 137.644632 -279.715722)
		(width 0.088646)
		(layer "In4.Cu")
		(net "M_G_CPU1_SA_DQ<0>")
	)
	(segment
		(start 161.224214 -315.10859)
		(end 160.364932 -314.249308)
		(width 0.18288)
		(layer "In4.Cu")
		(net "M_G_CPU1_SA_DQ<0>")
	)
	(segment
		(start 134.501382 -278.017224)
		(end 134.492492 -278.012144)
		(width 0.088646)
		(layer "In4.Cu")
		(net "M_G_CPU1_SA_DQ<0>")
	)
	(segment
		(start 178.994562 -318.66459)
		(end 178.994562 -318.924432)
		(width 0.18288)
		(layer "In4.Cu")
		(net "M_G_CPU1_SA_DQ<0>")
	)
	(segment
		(start 182.846726 -316.590426)
		(end 182.49519 -316.590426)
		(width 0.18288)
		(layer "In4.Cu")
		(net "M_G_CPU1_SA_DQ<0>")
	)
	(segment
		(start 178.458622 -319.084452)
		(end 178.298602 -318.924432)
		(width 0.18288)
		(layer "In4.Cu")
		(net "M_G_CPU1_SA_DQ<0>")
	)
	(segment
		(start 171.125388 -318.972946)
		(end 169.745152 -317.59271)
		(width 0.18288)
		(layer "In4.Cu")
		(net "M_G_CPU1_SA_DQ<0>")
	)
	(segment
		(start 174.675292 -318.211454)
		(end 174.515272 -318.371474)
		(width 0.18288)
		(layer "In4.Cu")
		(net "M_G_CPU1_SA_DQ<0>")
	)
	(segment
		(start 186.295538 -317.268606)
		(end 184.829958 -315.803026)
		(width 0.18288)
		(layer "In4.Cu")
		(net "M_G_CPU1_SA_DQ<0>")
	)
	(segment
		(start 174.515272 -318.812926)
		(end 174.355252 -318.972946)
		(width 0.18288)
		(layer "In4.Cu")
		(net "M_G_CPU1_SA_DQ<0>")
	)
	(segment
		(start 162.620452 -315.10859)
		(end 161.224214 -315.10859)
		(width 0.18288)
		(layer "In4.Cu")
		(net "M_G_CPU1_SA_DQ<0>")
	)
	(segment
		(start 134.971282 -278.83104)
		(end 134.962392 -278.82596)
		(width 0.088646)
		(layer "In4.Cu")
		(net "M_G_CPU1_SA_DQ<0>")
	)
	(segment
		(start 178.298602 -318.610996)
		(end 178.130454 -318.442848)
		(width 0.18288)
		(layer "In4.Cu")
		(net "M_G_CPU1_SA_DQ<0>")
	)
	(segment
		(start 139.847828 -281.36596)
		(end 139.435586 -280.953718)
		(width 0.18288)
		(layer "In4.Cu")
		(net "M_G_CPU1_SA_DQ<0>")
	)
	(segment
		(start 139.435586 -280.953718)
		(end 138.667998 -280.18613)
		(width 0.088646)
		(layer "In4.Cu")
		(net "M_G_CPU1_SA_DQ<0>")
	)
	(segment
		(start 175.075342 -318.211454)
		(end 174.675292 -318.211454)
		(width 0.18288)
		(layer "In4.Cu")
		(net "M_G_CPU1_SA_DQ<0>")
	)
	(segment
		(start 183.634126 -315.803026)
		(end 182.846726 -316.590426)
		(width 0.18288)
		(layer "In4.Cu")
		(net "M_G_CPU1_SA_DQ<0>")
	)
	(segment
		(start 146.430238 -298.479464)
		(end 140.653516 -284.535372)
		(width 0.18288)
		(layer "In4.Cu")
		(net "M_G_CPU1_SA_DQ<0>")
	)
	(segment
		(start 153.46172 -309.00243)
		(end 146.430238 -298.479464)
		(width 0.18288)
		(layer "In4.Cu")
		(net "M_G_CPU1_SA_DQ<0>")
	)
	(segment
		(start 164.861748 -315.863224)
		(end 163.375086 -315.863224)
		(width 0.18288)
		(layer "In4.Cu")
		(net "M_G_CPU1_SA_DQ<0>")
	)
	(segment
		(start 180.581046 -318.50457)
		(end 179.154582 -318.50457)
		(width 0.18288)
		(layer "In4.Cu")
		(net "M_G_CPU1_SA_DQ<0>")
	)
	(segment
		(start 178.130454 -318.442848)
		(end 176.31283 -318.442848)
		(width 0.18288)
		(layer "In4.Cu")
		(net "M_G_CPU1_SA_DQ<0>")
	)
	(segment
		(start 134.031482 -277.203154)
		(end 134.022592 -277.198074)
		(width 0.088646)
		(layer "In4.Cu")
		(net "M_G_CPU1_SA_DQ<0>")
	)
	(segment
		(start 175.235362 -318.371474)
		(end 175.075342 -318.211454)
		(width 0.18288)
		(layer "In4.Cu")
		(net "M_G_CPU1_SA_DQ<0>")
	)
	(segment
		(start 168.038018 -316.565026)
		(end 165.56355 -316.565026)
		(width 0.18288)
		(layer "In4.Cu")
		(net "M_G_CPU1_SA_DQ<0>")
	)
	(segment
		(start 135.149844 -279.165812)
		(end 135.149844 -279.150318)
		(width 0.088646)
		(layer "In4.Cu")
		(net "M_G_CPU1_SA_DQ<0>")
	)
	(segment
		(start 138.667998 -280.18613)
		(end 138.11504 -280.18613)
		(width 0.088646)
		(layer "In4.Cu")
		(net "M_G_CPU1_SA_DQ<0>")
	)
	(segment
		(start 184.829958 -315.803026)
		(end 183.634126 -315.803026)
		(width 0.18288)
		(layer "In4.Cu")
		(net "M_G_CPU1_SA_DQ<0>")
	)
	(segment
		(start 178.994562 -318.924432)
		(end 178.834542 -319.084452)
		(width 0.18288)
		(layer "In4.Cu")
		(net "M_G_CPU1_SA_DQ<0>")
	)
	(segment
		(start 175.395382 -318.972946)
		(end 175.235362 -318.812926)
		(width 0.18288)
		(layer "In4.Cu")
		(net "M_G_CPU1_SA_DQ<0>")
	)
	(segment
		(start 179.154582 -318.50457)
		(end 178.994562 -318.66459)
		(width 0.18288)
		(layer "In4.Cu")
		(net "M_G_CPU1_SA_DQ<0>")
	)
	(segment
		(start 169.745152 -317.59271)
		(end 169.065702 -317.59271)
		(width 0.18288)
		(layer "In4.Cu")
		(net "M_G_CPU1_SA_DQ<0>")
	)
	(segment
		(start 134.679944 -278.346408)
		(end 134.679944 -278.336502)
		(width 0.088646)
		(layer "In4.Cu")
		(net "M_G_CPU1_SA_DQ<0>")
	)
	(segment
		(start 178.298602 -318.924432)
		(end 178.298602 -318.610996)
		(width 0.18288)
		(layer "In4.Cu")
		(net "M_G_CPU1_SA_DQ<0>")
	)
	(segment
		(start 130.859022 -276.708616)
		(end 130.546348 -276.708616)
		(width 0.088646)
		(layer "In4.Cu")
		(net "M_G_CPU1_SA_DQ<0>")
	)
	(segment
		(start 137.644632 -279.715722)
		(end 137.594594 -279.715722)
		(width 0.088646)
		(layer "In4.Cu")
		(net "M_G_CPU1_SA_DQ<0>")
	)
	(segment
		(start 134.210044 -277.540974)
		(end 134.210044 -277.522432)
		(width 0.088646)
		(layer "In4.Cu")
		(net "M_G_CPU1_SA_DQ<0>")
	)
	(arc
		(start 135.149844 -279.150318)
		(mid 135.102165 -278.967418)
		(end 134.971282 -278.83104)
		(width 0.088646)
		(layer "In4.Cu")
		(net "M_G_CPU1_SA_DQ<0>")
	)
	(arc
		(start 134.210044 -277.522432)
		(mid 134.162365 -277.339532)
		(end 134.031482 -277.203154)
		(width 0.088646)
		(layer "In4.Cu")
		(net "M_G_CPU1_SA_DQ<0>")
	)
	(arc
		(start 136.937496 -279.639776)
		(mid 136.654794 -279.715552)
		(end 136.372092 -279.639776)
		(width 0.088646)
		(layer "In4.Cu")
		(net "M_G_CPU1_SA_DQ<0>")
	)
	(arc
		(start 136.372092 -279.639776)
		(mid 136.184894 -279.589633)
		(end 135.997696 -279.639776)
		(width 0.088646)
		(layer "In4.Cu")
		(net "M_G_CPU1_SA_DQ<0>")
	)
	(arc
		(start 131.203446 -277.198074)
		(mid 131.013766 -277.019165)
		(end 130.924554 -276.774148)
		(width 0.088646)
		(layer "In4.Cu")
		(net "M_G_CPU1_SA_DQ<0>")
	)
	(arc
		(start 135.987282 -279.645872)
		(mid 135.70885 -279.715718)
		(end 135.432038 -279.639776)
		(width 0.088646)
		(layer "In4.Cu")
		(net "M_G_CPU1_SA_DQ<0>")
	)
	(arc
		(start 131.758182 -277.20417)
		(mid 131.480004 -277.273893)
		(end 131.203446 -277.198074)
		(width 0.088646)
		(layer "In4.Cu")
		(net "M_G_CPU1_SA_DQ<0>")
	)
	(arc
		(start 132.142992 -277.198074)
		(mid 131.955794 -277.147931)
		(end 131.768596 -277.198074)
		(width 0.088646)
		(layer "In4.Cu")
		(net "M_G_CPU1_SA_DQ<0>")
	)
	(arc
		(start 134.962392 -278.82596)
		(mid 134.758057 -278.623355)
		(end 134.679944 -278.346408)
		(width 0.088646)
		(layer "In4.Cu")
		(net "M_G_CPU1_SA_DQ<0>")
	)
	(arc
		(start 132.708396 -277.198074)
		(mid 132.425694 -277.27385)
		(end 132.142992 -277.198074)
		(width 0.088646)
		(layer "In4.Cu")
		(net "M_G_CPU1_SA_DQ<0>")
	)
	(arc
		(start 135.432038 -279.639776)
		(mid 135.229215 -279.439545)
		(end 135.149844 -279.165812)
		(width 0.088646)
		(layer "In4.Cu")
		(net "M_G_CPU1_SA_DQ<0>")
	)
	(arc
		(start 137.311892 -279.639776)
		(mid 137.124694 -279.589633)
		(end 136.937496 -279.639776)
		(width 0.088646)
		(layer "In4.Cu")
		(net "M_G_CPU1_SA_DQ<0>")
	)
	(arc
		(start 137.594594 -279.715722)
		(mid 137.570061 -279.715234)
		(end 137.545572 -279.71369)
		(width 0.088646)
		(layer "In4.Cu")
		(net "M_G_CPU1_SA_DQ<0>")
	)
	(arc
		(start 134.679944 -278.336502)
		(mid 134.632265 -278.153602)
		(end 134.501382 -278.017224)
		(width 0.088646)
		(layer "In4.Cu")
		(net "M_G_CPU1_SA_DQ<0>")
	)
	(arc
		(start 134.492492 -278.012144)
		(mid 134.290206 -277.813163)
		(end 134.210044 -277.540974)
		(width 0.088646)
		(layer "In4.Cu")
		(net "M_G_CPU1_SA_DQ<0>")
	)
	(arc
		(start 133.082792 -277.198074)
		(mid 132.895594 -277.147931)
		(end 132.708396 -277.198074)
		(width 0.088646)
		(layer "In4.Cu")
		(net "M_G_CPU1_SA_DQ<0>")
	)
	(arc
		(start 137.545572 -279.71369)
		(mid 137.424673 -279.689561)
		(end 137.311892 -279.639776)
		(width 0.088646)
		(layer "In4.Cu")
		(net "M_G_CPU1_SA_DQ<0>")
	)
	(arc
		(start 133.633464 -277.20671)
		(mid 133.356989 -277.27403)
		(end 133.082792 -277.198074)
		(width 0.088646)
		(layer "In4.Cu")
		(net "M_G_CPU1_SA_DQ<0>")
	)
	(arc
		(start 134.022592 -277.198074)
		(mid 133.835394 -277.147931)
		(end 133.648196 -277.198074)
		(width 0.088646)
		(layer "In4.Cu")
		(net "M_G_CPU1_SA_DQ<0>")
	)
	(segment
		(start 126.786894 -258.2672)
		(end 126.787148 -258.267454)
		(width 0.20066)
		(layer "F.Cu")
		(net "M_G_CPU1_SA_CS_N<3>")
	)
	(segment
		(start 126.787148 -258.267454)
		(end 126.787148 -258.80314)
		(width 0.20066)
		(layer "F.Cu")
		(net "M_G_CPU1_SA_CS_N<3>")
	)
	(segment
		(start 193.088514 -267.016738)
		(end 191.983614 -267.016738)
		(width 0.20066)
		(layer "F.Cu")
		(net "M_G_CPU1_SA_CS_N<3>")
	)
	(segment
		(start 162.31616 -263.312402)
		(end 161.588704 -263.312402)
		(width 0.18288)
		(layer "In4.Cu")
		(net "M_G_CPU1_SA_CS_N<3>")
	)
	(segment
		(start 127.923036 -259.122418)
		(end 127.914146 -259.127498)
		(width 0.088646)
		(layer "In4.Cu")
		(net "M_G_CPU1_SA_CS_N<3>")
	)
	(segment
		(start 128.101598 -258.781042)
		(end 128.101598 -258.80314)
		(width 0.088646)
		(layer "In4.Cu")
		(net "M_G_CPU1_SA_CS_N<3>")
	)
	(segment
		(start 186.310016 -267.31341)
		(end 184.578752 -265.582146)
		(width 0.18288)
		(layer "In4.Cu")
		(net "M_G_CPU1_SA_CS_N<3>")
	)
	(segment
		(start 136.790176 -256.544826)
		(end 136.42848 -256.544826)
		(width 0.088646)
		(layer "In4.Cu")
		(net "M_G_CPU1_SA_CS_N<3>")
	)
	(segment
		(start 163.04641 -264.042652)
		(end 162.31616 -263.312402)
		(width 0.18288)
		(layer "In4.Cu")
		(net "M_G_CPU1_SA_CS_N<3>")
	)
	(segment
		(start 187.57265 -267.38707)
		(end 187.435998 -267.31341)
		(width 0.18288)
		(layer "In4.Cu")
		(net "M_G_CPU1_SA_CS_N<3>")
	)
	(segment
		(start 144.867884 -257.578606)
		(end 141.860524 -256.33299)
		(width 0.18288)
		(layer "In4.Cu")
		(net "M_G_CPU1_SA_CS_N<3>")
	)
	(segment
		(start 161.588704 -263.312402)
		(end 161.294826 -263.018524)
		(width 0.18288)
		(layer "In4.Cu")
		(net "M_G_CPU1_SA_CS_N<3>")
	)
	(segment
		(start 191.983614 -267.016738)
		(end 191.519302 -266.552426)
		(width 0.18288)
		(layer "In4.Cu")
		(net "M_G_CPU1_SA_CS_N<3>")
	)
	(segment
		(start 126.943612 -259.074158)
		(end 126.787148 -258.80314)
		(width 0.088646)
		(layer "In4.Cu")
		(net "M_G_CPU1_SA_CS_N<3>")
	)
	(segment
		(start 179.935124 -264.638028)
		(end 179.682394 -264.890758)
		(width 0.18288)
		(layer "In4.Cu")
		(net "M_G_CPU1_SA_CS_N<3>")
	)
	(segment
		(start 182.950866 -264.802366)
		(end 182.275226 -264.802366)
		(width 0.18288)
		(layer "In4.Cu")
		(net "M_G_CPU1_SA_CS_N<3>")
	)
	(segment
		(start 157.078426 -262.421878)
		(end 152.043384 -257.386836)
		(width 0.18288)
		(layer "In4.Cu")
		(net "M_G_CPU1_SA_CS_N<3>")
	)
	(segment
		(start 141.860524 -256.33299)
		(end 137.29335 -256.33299)
		(width 0.18288)
		(layer "In4.Cu")
		(net "M_G_CPU1_SA_CS_N<3>")
	)
	(segment
		(start 133.648196 -256.685796)
		(end 133.633464 -256.67716)
		(width 0.088646)
		(layer "In4.Cu")
		(net "M_G_CPU1_SA_CS_N<3>")
	)
	(segment
		(start 147.464272 -257.578606)
		(end 144.867884 -257.578606)
		(width 0.18288)
		(layer "In4.Cu")
		(net "M_G_CPU1_SA_CS_N<3>")
	)
	(segment
		(start 183.730646 -265.582146)
		(end 182.950866 -264.802366)
		(width 0.18288)
		(layer "In4.Cu")
		(net "M_G_CPU1_SA_CS_N<3>")
	)
	(segment
		(start 131.768596 -256.685796)
		(end 131.753864 -256.67716)
		(width 0.088646)
		(layer "In4.Cu")
		(net "M_G_CPU1_SA_CS_N<3>")
	)
	(segment
		(start 129.802636 -257.494532)
		(end 129.793746 -257.499612)
		(width 0.088646)
		(layer "In4.Cu")
		(net "M_G_CPU1_SA_CS_N<3>")
	)
	(segment
		(start 188.002926 -267.442696)
		(end 188.002926 -267.440918)
		(width 0.18288)
		(layer "In4.Cu")
		(net "M_G_CPU1_SA_CS_N<3>")
	)
	(segment
		(start 158.99511 -262.421878)
		(end 157.078426 -262.421878)
		(width 0.18288)
		(layer "In4.Cu")
		(net "M_G_CPU1_SA_CS_N<3>")
	)
	(segment
		(start 179.682394 -264.890758)
		(end 176.048162 -264.890758)
		(width 0.18288)
		(layer "In4.Cu")
		(net "M_G_CPU1_SA_CS_N<3>")
	)
	(segment
		(start 187.435998 -267.31341)
		(end 186.310016 -267.31341)
		(width 0.18288)
		(layer "In4.Cu")
		(net "M_G_CPU1_SA_CS_N<3>")
	)
	(segment
		(start 130.828796 -256.685796)
		(end 130.814064 -256.67716)
		(width 0.088646)
		(layer "In4.Cu")
		(net "M_G_CPU1_SA_CS_N<3>")
	)
	(segment
		(start 188.002926 -267.440918)
		(end 187.672726 -267.440918)
		(width 0.18288)
		(layer "In4.Cu")
		(net "M_G_CPU1_SA_CS_N<3>")
	)
	(segment
		(start 191.519302 -266.552426)
		(end 189.780926 -266.552426)
		(width 0.18288)
		(layer "In4.Cu")
		(net "M_G_CPU1_SA_CS_N<3>")
	)
	(segment
		(start 175.200056 -264.042652)
		(end 163.04641 -264.042652)
		(width 0.18288)
		(layer "In4.Cu")
		(net "M_G_CPU1_SA_CS_N<3>")
	)
	(segment
		(start 129.981198 -257.15976)
		(end 129.981198 -257.175254)
		(width 0.088646)
		(layer "In4.Cu")
		(net "M_G_CPU1_SA_CS_N<3>")
	)
	(segment
		(start 152.043384 -257.386836)
		(end 147.927822 -257.386836)
		(width 0.18288)
		(layer "In4.Cu")
		(net "M_G_CPU1_SA_CS_N<3>")
	)
	(segment
		(start 147.927822 -257.386836)
		(end 147.464272 -257.578606)
		(width 0.18288)
		(layer "In4.Cu")
		(net "M_G_CPU1_SA_CS_N<3>")
	)
	(segment
		(start 129.332482 -258.308348)
		(end 129.323592 -258.313428)
		(width 0.088646)
		(layer "In4.Cu")
		(net "M_G_CPU1_SA_CS_N<3>")
	)
	(segment
		(start 137.29335 -256.33299)
		(end 137.002012 -256.33299)
		(width 0.088646)
		(layer "In4.Cu")
		(net "M_G_CPU1_SA_CS_N<3>")
	)
	(segment
		(start 187.672726 -267.440918)
		(end 187.57265 -267.38707)
		(width 0.18288)
		(layer "In4.Cu")
		(net "M_G_CPU1_SA_CS_N<3>")
	)
	(segment
		(start 127.032512 -259.09778)
		(end 126.943612 -259.074158)
		(width 0.088646)
		(layer "In4.Cu")
		(net "M_G_CPU1_SA_CS_N<3>")
	)
	(segment
		(start 188.890656 -267.442696)
		(end 188.002926 -267.442696)
		(width 0.18288)
		(layer "In4.Cu")
		(net "M_G_CPU1_SA_CS_N<3>")
	)
	(segment
		(start 159.591756 -263.018524)
		(end 158.99511 -262.421878)
		(width 0.18288)
		(layer "In4.Cu")
		(net "M_G_CPU1_SA_CS_N<3>")
	)
	(segment
		(start 189.780926 -266.552426)
		(end 188.890656 -267.442696)
		(width 0.18288)
		(layer "In4.Cu")
		(net "M_G_CPU1_SA_CS_N<3>")
	)
	(segment
		(start 182.110888 -264.638028)
		(end 179.935124 -264.638028)
		(width 0.18288)
		(layer "In4.Cu")
		(net "M_G_CPU1_SA_CS_N<3>")
	)
	(segment
		(start 129.793746 -257.499612)
		(end 129.78765 -257.503168)
		(width 0.088646)
		(layer "In4.Cu")
		(net "M_G_CPU1_SA_CS_N<3>")
	)
	(segment
		(start 137.002012 -256.33299)
		(end 136.790176 -256.544826)
		(width 0.088646)
		(layer "In4.Cu")
		(net "M_G_CPU1_SA_CS_N<3>")
	)
	(segment
		(start 184.578752 -265.582146)
		(end 183.730646 -265.582146)
		(width 0.18288)
		(layer "In4.Cu")
		(net "M_G_CPU1_SA_CS_N<3>")
	)
	(segment
		(start 182.275226 -264.802366)
		(end 182.110888 -264.638028)
		(width 0.18288)
		(layer "In4.Cu")
		(net "M_G_CPU1_SA_CS_N<3>")
	)
	(segment
		(start 161.294826 -263.018524)
		(end 159.591756 -263.018524)
		(width 0.18288)
		(layer "In4.Cu")
		(net "M_G_CPU1_SA_CS_N<3>")
	)
	(segment
		(start 128.949196 -258.313428)
		(end 128.934464 -258.304792)
		(width 0.088646)
		(layer "In4.Cu")
		(net "M_G_CPU1_SA_CS_N<3>")
	)
	(segment
		(start 176.048162 -264.890758)
		(end 175.200056 -264.042652)
		(width 0.18288)
		(layer "In4.Cu")
		(net "M_G_CPU1_SA_CS_N<3>")
	)
	(arc
		(start 136.42848 -256.544826)
		(mid 136.156065 -256.580689)
		(end 135.902192 -256.685796)
		(width 0.088646)
		(layer "In4.Cu")
		(net "M_G_CPU1_SA_CS_N<3>")
	)
	(arc
		(start 129.981198 -257.175254)
		(mid 129.933519 -257.358154)
		(end 129.802636 -257.494532)
		(width 0.088646)
		(layer "In4.Cu")
		(net "M_G_CPU1_SA_CS_N<3>")
	)
	(arc
		(start 134.587996 -256.685796)
		(mid 134.305294 -256.61002)
		(end 134.022592 -256.685796)
		(width 0.088646)
		(layer "In4.Cu")
		(net "M_G_CPU1_SA_CS_N<3>")
	)
	(arc
		(start 128.383792 -258.313428)
		(mid 128.18251 -258.510915)
		(end 128.101598 -258.781042)
		(width 0.088646)
		(layer "In4.Cu")
		(net "M_G_CPU1_SA_CS_N<3>")
	)
	(arc
		(start 133.082792 -256.685796)
		(mid 132.895594 -256.735939)
		(end 132.708396 -256.685796)
		(width 0.088646)
		(layer "In4.Cu")
		(net "M_G_CPU1_SA_CS_N<3>")
	)
	(arc
		(start 133.633464 -256.67716)
		(mid 133.356989 -256.60984)
		(end 133.082792 -256.685796)
		(width 0.088646)
		(layer "In4.Cu")
		(net "M_G_CPU1_SA_CS_N<3>")
	)
	(arc
		(start 127.914146 -259.127498)
		(mid 127.726948 -259.177641)
		(end 127.53975 -259.127498)
		(width 0.088646)
		(layer "In4.Cu")
		(net "M_G_CPU1_SA_CS_N<3>")
	)
	(arc
		(start 129.511044 -257.98907)
		(mid 129.463365 -258.17197)
		(end 129.332482 -258.308348)
		(width 0.088646)
		(layer "In4.Cu")
		(net "M_G_CPU1_SA_CS_N<3>")
	)
	(arc
		(start 129.78765 -257.503168)
		(mid 129.585063 -257.709519)
		(end 129.511044 -257.98907)
		(width 0.088646)
		(layer "In4.Cu")
		(net "M_G_CPU1_SA_CS_N<3>")
	)
	(arc
		(start 135.527796 -256.685796)
		(mid 135.245094 -256.61002)
		(end 134.962392 -256.685796)
		(width 0.088646)
		(layer "In4.Cu")
		(net "M_G_CPU1_SA_CS_N<3>")
	)
	(arc
		(start 128.101598 -258.80314)
		(mid 128.053919 -258.98604)
		(end 127.923036 -259.122418)
		(width 0.088646)
		(layer "In4.Cu")
		(net "M_G_CPU1_SA_CS_N<3>")
	)
	(arc
		(start 128.934464 -258.304792)
		(mid 128.658023 -258.237626)
		(end 128.383792 -258.313428)
		(width 0.088646)
		(layer "In4.Cu")
		(net "M_G_CPU1_SA_CS_N<3>")
	)
	(arc
		(start 134.022592 -256.685796)
		(mid 133.835394 -256.735939)
		(end 133.648196 -256.685796)
		(width 0.088646)
		(layer "In4.Cu")
		(net "M_G_CPU1_SA_CS_N<3>")
	)
	(arc
		(start 135.902192 -256.685796)
		(mid 135.714994 -256.735939)
		(end 135.527796 -256.685796)
		(width 0.088646)
		(layer "In4.Cu")
		(net "M_G_CPU1_SA_CS_N<3>")
	)
	(arc
		(start 130.263392 -256.685796)
		(mid 130.060569 -256.886027)
		(end 129.981198 -257.15976)
		(width 0.088646)
		(layer "In4.Cu")
		(net "M_G_CPU1_SA_CS_N<3>")
	)
	(arc
		(start 134.962392 -256.685796)
		(mid 134.775194 -256.735939)
		(end 134.587996 -256.685796)
		(width 0.088646)
		(layer "In4.Cu")
		(net "M_G_CPU1_SA_CS_N<3>")
	)
	(arc
		(start 131.753864 -256.67716)
		(mid 131.477389 -256.60984)
		(end 131.203192 -256.685796)
		(width 0.088646)
		(layer "In4.Cu")
		(net "M_G_CPU1_SA_CS_N<3>")
	)
	(arc
		(start 131.203192 -256.685796)
		(mid 131.015994 -256.735939)
		(end 130.828796 -256.685796)
		(width 0.088646)
		(layer "In4.Cu")
		(net "M_G_CPU1_SA_CS_N<3>")
	)
	(arc
		(start 129.323592 -258.313428)
		(mid 129.136394 -258.363571)
		(end 128.949196 -258.313428)
		(width 0.088646)
		(layer "In4.Cu")
		(net "M_G_CPU1_SA_CS_N<3>")
	)
	(arc
		(start 132.142992 -256.685796)
		(mid 131.955794 -256.735939)
		(end 131.768596 -256.685796)
		(width 0.088646)
		(layer "In4.Cu")
		(net "M_G_CPU1_SA_CS_N<3>")
	)
	(arc
		(start 127.53975 -259.127498)
		(mid 127.289653 -259.052438)
		(end 127.032512 -259.09778)
		(width 0.088646)
		(layer "In4.Cu")
		(net "M_G_CPU1_SA_CS_N<3>")
	)
	(arc
		(start 130.814064 -256.67716)
		(mid 130.537589 -256.60984)
		(end 130.263392 -256.685796)
		(width 0.088646)
		(layer "In4.Cu")
		(net "M_G_CPU1_SA_CS_N<3>")
	)
	(arc
		(start 132.708396 -256.685796)
		(mid 132.425694 -256.61002)
		(end 132.142992 -256.685796)
		(width 0.088646)
		(layer "In4.Cu")
		(net "M_G_CPU1_SA_CS_N<3>")
	)
	(segment
		(start 127.257048 -259.093462)
		(end 127.256794 -259.616956)
		(width 0.20066)
		(layer "F.Cu")
		(net "M_G_CPU1_SA_CS_N<2>")
	)
	(segment
		(start 187.883546 -267.866622)
		(end 188.988446 -267.866622)
		(width 0.20066)
		(layer "F.Cu")
		(net "M_G_CPU1_SA_CS_N<2>")
	)
	(segment
		(start 127.257048 -259.081016)
		(end 127.257048 -259.093462)
		(width 0.20066)
		(layer "F.Cu")
		(net "M_G_CPU1_SA_CS_N<2>")
	)
	(segment
		(start 148.375624 -257.884676)
		(end 148.218906 -257.819652)
		(width 0.18288)
		(layer "In4.Cu")
		(net "M_G_CPU1_SA_CS_N<2>")
	)
	(segment
		(start 157.055058 -263.107678)
		(end 151.832056 -257.884676)
		(width 0.18288)
		(layer "In4.Cu")
		(net "M_G_CPU1_SA_CS_N<2>")
	)
	(segment
		(start 128.86436 -258.484878)
		(end 128.853946 -258.478782)
		(width 0.088646)
		(layer "In4.Cu")
		(net "M_G_CPU1_SA_CS_N<2>")
	)
	(segment
		(start 182.83174 -266.591288)
		(end 181.829202 -265.58875)
		(width 0.18288)
		(layer "In4.Cu")
		(net "M_G_CPU1_SA_CS_N<2>")
	)
	(segment
		(start 129.888996 -257.664712)
		(end 129.880106 -257.669792)
		(width 0.088646)
		(layer "In4.Cu")
		(net "M_G_CPU1_SA_CS_N<2>")
	)
	(segment
		(start 129.895092 -257.661156)
		(end 129.888996 -257.664712)
		(width 0.088646)
		(layer "In4.Cu")
		(net "M_G_CPU1_SA_CS_N<2>")
	)
	(segment
		(start 141.82471 -256.681732)
		(end 137.29335 -256.681732)
		(width 0.18288)
		(layer "In4.Cu")
		(net "M_G_CPU1_SA_CS_N<2>")
	)
	(segment
		(start 136.945624 -256.681732)
		(end 136.827006 -256.80035)
		(width 0.088646)
		(layer "In4.Cu")
		(net "M_G_CPU1_SA_CS_N<2>")
	)
	(segment
		(start 137.29335 -256.681732)
		(end 136.945624 -256.681732)
		(width 0.088646)
		(layer "In4.Cu")
		(net "M_G_CPU1_SA_CS_N<2>")
	)
	(segment
		(start 178.798982 -265.485626)
		(end 178.543712 -265.740896)
		(width 0.18288)
		(layer "In4.Cu")
		(net "M_G_CPU1_SA_CS_N<2>")
	)
	(segment
		(start 147.884388 -257.77063)
		(end 147.538694 -257.913886)
		(width 0.18288)
		(layer "In4.Cu")
		(net "M_G_CPU1_SA_CS_N<2>")
	)
	(segment
		(start 128.47955 -258.478782)
		(end 128.47066 -258.483862)
		(width 0.088646)
		(layer "In4.Cu")
		(net "M_G_CPU1_SA_CS_N<2>")
	)
	(segment
		(start 127.121412 -259.26796)
		(end 127.10033 -259.345938)
		(width 0.088646)
		(layer "In4.Cu")
		(net "M_G_CPU1_SA_CS_N<2>")
	)
	(segment
		(start 161.259774 -263.926066)
		(end 161.095944 -264.089896)
		(width 0.18288)
		(layer "In4.Cu")
		(net "M_G_CPU1_SA_CS_N<2>")
	)
	(segment
		(start 158.714186 -263.107678)
		(end 157.055058 -263.107678)
		(width 0.18288)
		(layer "In4.Cu")
		(net "M_G_CPU1_SA_CS_N<2>")
	)
	(segment
		(start 132.623306 -256.856992)
		(end 132.612892 -256.850896)
		(width 0.088646)
		(layer "In4.Cu")
		(net "M_G_CPU1_SA_CS_N<2>")
	)
	(segment
		(start 187.883546 -267.866622)
		(end 187.315602 -267.866622)
		(width 0.18288)
		(layer "In4.Cu")
		(net "M_G_CPU1_SA_CS_N<2>")
	)
	(segment
		(start 128.009396 -259.292598)
		(end 127.994664 -259.301234)
		(width 0.088646)
		(layer "In4.Cu")
		(net "M_G_CPU1_SA_CS_N<2>")
	)
	(segment
		(start 163.053268 -264.892536)
		(end 162.086798 -263.926066)
		(width 0.18288)
		(layer "In4.Cu")
		(net "M_G_CPU1_SA_CS_N<2>")
	)
	(segment
		(start 130.35915 -256.850896)
		(end 130.35026 -256.855976)
		(width 0.088646)
		(layer "In4.Cu")
		(net "M_G_CPU1_SA_CS_N<2>")
	)
	(segment
		(start 184.679844 -266.591288)
		(end 182.83174 -266.591288)
		(width 0.18288)
		(layer "In4.Cu")
		(net "M_G_CPU1_SA_CS_N<2>")
	)
	(segment
		(start 180.484526 -265.866626)
		(end 179.620926 -265.866626)
		(width 0.18288)
		(layer "In4.Cu")
		(net "M_G_CPU1_SA_CS_N<2>")
	)
	(segment
		(start 172.602906 -264.892536)
		(end 163.053268 -264.892536)
		(width 0.18288)
		(layer "In4.Cu")
		(net "M_G_CPU1_SA_CS_N<2>")
	)
	(segment
		(start 186.783726 -268.398498)
		(end 186.487054 -268.398498)
		(width 0.18288)
		(layer "In4.Cu")
		(net "M_G_CPU1_SA_CS_N<2>")
	)
	(segment
		(start 127.10033 -259.345938)
		(end 127.256794 -259.616956)
		(width 0.088646)
		(layer "In4.Cu")
		(net "M_G_CPU1_SA_CS_N<2>")
	)
	(segment
		(start 179.239926 -265.485626)
		(end 178.798982 -265.485626)
		(width 0.18288)
		(layer "In4.Cu")
		(net "M_G_CPU1_SA_CS_N<2>")
	)
	(segment
		(start 151.832056 -257.884676)
		(end 148.375624 -257.884676)
		(width 0.18288)
		(layer "In4.Cu")
		(net "M_G_CPU1_SA_CS_N<2>")
	)
	(segment
		(start 187.315602 -267.866622)
		(end 186.783726 -268.398498)
		(width 0.18288)
		(layer "In4.Cu")
		(net "M_G_CPU1_SA_CS_N<2>")
	)
	(segment
		(start 129.701544 -257.98907)
		(end 129.701544 -258.007612)
		(width 0.088646)
		(layer "In4.Cu")
		(net "M_G_CPU1_SA_CS_N<2>")
	)
	(segment
		(start 133.56336 -256.856992)
		(end 133.552946 -256.850896)
		(width 0.088646)
		(layer "In4.Cu")
		(net "M_G_CPU1_SA_CS_N<2>")
	)
	(segment
		(start 136.827006 -256.80035)
		(end 136.184894 -256.80035)
		(width 0.088646)
		(layer "In4.Cu")
		(net "M_G_CPU1_SA_CS_N<2>")
	)
	(segment
		(start 186.487054 -268.398498)
		(end 184.679844 -266.591288)
		(width 0.18288)
		(layer "In4.Cu")
		(net "M_G_CPU1_SA_CS_N<2>")
	)
	(segment
		(start 147.538694 -257.913886)
		(end 144.799812 -257.913886)
		(width 0.18288)
		(layer "In4.Cu")
		(net "M_G_CPU1_SA_CS_N<2>")
	)
	(segment
		(start 180.762402 -265.58875)
		(end 180.484526 -265.866626)
		(width 0.18288)
		(layer "In4.Cu")
		(net "M_G_CPU1_SA_CS_N<2>")
	)
	(segment
		(start 130.748278 -256.859532)
		(end 130.733546 -256.850896)
		(width 0.088646)
		(layer "In4.Cu")
		(net "M_G_CPU1_SA_CS_N<2>")
	)
	(segment
		(start 161.095944 -264.089896)
		(end 159.696404 -264.089896)
		(width 0.18288)
		(layer "In4.Cu")
		(net "M_G_CPU1_SA_CS_N<2>")
	)
	(segment
		(start 148.100288 -257.77063)
		(end 147.884388 -257.77063)
		(width 0.18288)
		(layer "In4.Cu")
		(net "M_G_CPU1_SA_CS_N<2>")
	)
	(segment
		(start 175.308006 -264.890758)
		(end 172.602906 -264.890758)
		(width 0.18288)
		(layer "In4.Cu")
		(net "M_G_CPU1_SA_CS_N<2>")
	)
	(segment
		(start 131.68376 -256.856992)
		(end 131.673346 -256.850896)
		(width 0.088646)
		(layer "In4.Cu")
		(net "M_G_CPU1_SA_CS_N<2>")
	)
	(segment
		(start 159.696404 -264.089896)
		(end 158.714186 -263.107678)
		(width 0.18288)
		(layer "In4.Cu")
		(net "M_G_CPU1_SA_CS_N<2>")
	)
	(segment
		(start 179.620926 -265.866626)
		(end 179.239926 -265.485626)
		(width 0.18288)
		(layer "In4.Cu")
		(net "M_G_CPU1_SA_CS_N<2>")
	)
	(segment
		(start 176.158144 -265.740896)
		(end 175.308006 -264.890758)
		(width 0.18288)
		(layer "In4.Cu")
		(net "M_G_CPU1_SA_CS_N<2>")
	)
	(segment
		(start 144.799812 -257.913886)
		(end 141.82471 -256.681732)
		(width 0.18288)
		(layer "In4.Cu")
		(net "M_G_CPU1_SA_CS_N<2>")
	)
	(segment
		(start 181.829202 -265.58875)
		(end 180.762402 -265.58875)
		(width 0.18288)
		(layer "In4.Cu")
		(net "M_G_CPU1_SA_CS_N<2>")
	)
	(segment
		(start 148.218906 -257.819652)
		(end 148.100288 -257.77063)
		(width 0.18288)
		(layer "In4.Cu")
		(net "M_G_CPU1_SA_CS_N<2>")
	)
	(segment
		(start 172.602906 -264.890758)
		(end 172.602906 -264.892536)
		(width 0.18288)
		(layer "In4.Cu")
		(net "M_G_CPU1_SA_CS_N<2>")
	)
	(segment
		(start 128.015492 -259.289042)
		(end 128.009396 -259.292598)
		(width 0.088646)
		(layer "In4.Cu")
		(net "M_G_CPU1_SA_CS_N<2>")
	)
	(segment
		(start 178.543712 -265.740896)
		(end 176.158144 -265.740896)
		(width 0.18288)
		(layer "In4.Cu")
		(net "M_G_CPU1_SA_CS_N<2>")
	)
	(segment
		(start 162.086798 -263.926066)
		(end 161.259774 -263.926066)
		(width 0.18288)
		(layer "In4.Cu")
		(net "M_G_CPU1_SA_CS_N<2>")
	)
	(arc
		(start 130.171698 -257.175254)
		(mid 130.097707 -257.45482)
		(end 129.895092 -257.661156)
		(width 0.088646)
		(layer "In4.Cu")
		(net "M_G_CPU1_SA_CS_N<2>")
	)
	(arc
		(start 128.853946 -258.478782)
		(mid 128.666748 -258.428639)
		(end 128.47955 -258.478782)
		(width 0.088646)
		(layer "In4.Cu")
		(net "M_G_CPU1_SA_CS_N<2>")
	)
	(arc
		(start 131.29895 -256.850896)
		(mid 131.024751 -256.926731)
		(end 130.748278 -256.859532)
		(width 0.088646)
		(layer "In4.Cu")
		(net "M_G_CPU1_SA_CS_N<2>")
	)
	(arc
		(start 136.184894 -256.80035)
		(mid 136.087971 -256.813308)
		(end 135.997696 -256.850896)
		(width 0.088646)
		(layer "In4.Cu")
		(net "M_G_CPU1_SA_CS_N<2>")
	)
	(arc
		(start 135.057896 -256.850896)
		(mid 134.775194 -256.926672)
		(end 134.492492 -256.850896)
		(width 0.088646)
		(layer "In4.Cu")
		(net "M_G_CPU1_SA_CS_N<2>")
	)
	(arc
		(start 132.612892 -256.850896)
		(mid 132.425694 -256.800753)
		(end 132.238496 -256.850896)
		(width 0.088646)
		(layer "In4.Cu")
		(net "M_G_CPU1_SA_CS_N<2>")
	)
	(arc
		(start 129.880106 -257.669792)
		(mid 129.749192 -257.806152)
		(end 129.701544 -257.98907)
		(width 0.088646)
		(layer "In4.Cu")
		(net "M_G_CPU1_SA_CS_N<2>")
	)
	(arc
		(start 131.673346 -256.850896)
		(mid 131.486148 -256.800753)
		(end 131.29895 -256.850896)
		(width 0.088646)
		(layer "In4.Cu")
		(net "M_G_CPU1_SA_CS_N<2>")
	)
	(arc
		(start 135.432292 -256.850896)
		(mid 135.245094 -256.800753)
		(end 135.057896 -256.850896)
		(width 0.088646)
		(layer "In4.Cu")
		(net "M_G_CPU1_SA_CS_N<2>")
	)
	(arc
		(start 132.238496 -256.850896)
		(mid 131.961937 -256.926639)
		(end 131.68376 -256.856992)
		(width 0.088646)
		(layer "In4.Cu")
		(net "M_G_CPU1_SA_CS_N<2>")
	)
	(arc
		(start 130.733546 -256.850896)
		(mid 130.546348 -256.800753)
		(end 130.35915 -256.850896)
		(width 0.088646)
		(layer "In4.Cu")
		(net "M_G_CPU1_SA_CS_N<2>")
	)
	(arc
		(start 129.419096 -258.478782)
		(mid 129.142537 -258.554491)
		(end 128.86436 -258.484878)
		(width 0.088646)
		(layer "In4.Cu")
		(net "M_G_CPU1_SA_CS_N<2>")
	)
	(arc
		(start 128.292098 -258.80314)
		(mid 128.218107 -259.082706)
		(end 128.015492 -259.289042)
		(width 0.088646)
		(layer "In4.Cu")
		(net "M_G_CPU1_SA_CS_N<2>")
	)
	(arc
		(start 134.492492 -256.850896)
		(mid 134.305294 -256.800753)
		(end 134.118096 -256.850896)
		(width 0.088646)
		(layer "In4.Cu")
		(net "M_G_CPU1_SA_CS_N<2>")
	)
	(arc
		(start 129.701544 -258.007612)
		(mid 129.621382 -258.279801)
		(end 129.419096 -258.478782)
		(width 0.088646)
		(layer "In4.Cu")
		(net "M_G_CPU1_SA_CS_N<2>")
	)
	(arc
		(start 134.118096 -256.850896)
		(mid 133.841537 -256.926639)
		(end 133.56336 -256.856992)
		(width 0.088646)
		(layer "In4.Cu")
		(net "M_G_CPU1_SA_CS_N<2>")
	)
	(arc
		(start 133.17855 -256.850896)
		(mid 132.901737 -256.926766)
		(end 132.623306 -256.856992)
		(width 0.088646)
		(layer "In4.Cu")
		(net "M_G_CPU1_SA_CS_N<2>")
	)
	(arc
		(start 133.552946 -256.850896)
		(mid 133.365748 -256.800753)
		(end 133.17855 -256.850896)
		(width 0.088646)
		(layer "In4.Cu")
		(net "M_G_CPU1_SA_CS_N<2>")
	)
	(arc
		(start 127.994664 -259.301234)
		(mid 127.718189 -259.368554)
		(end 127.443992 -259.292598)
		(width 0.088646)
		(layer "In4.Cu")
		(net "M_G_CPU1_SA_CS_N<2>")
	)
	(arc
		(start 135.997696 -256.850896)
		(mid 135.714994 -256.926672)
		(end 135.432292 -256.850896)
		(width 0.088646)
		(layer "In4.Cu")
		(net "M_G_CPU1_SA_CS_N<2>")
	)
	(arc
		(start 128.47066 -258.483862)
		(mid 128.339746 -258.620222)
		(end 128.292098 -258.80314)
		(width 0.088646)
		(layer "In4.Cu")
		(net "M_G_CPU1_SA_CS_N<2>")
	)
	(arc
		(start 127.443992 -259.292598)
		(mid 127.285504 -259.243665)
		(end 127.121412 -259.26796)
		(width 0.088646)
		(layer "In4.Cu")
		(net "M_G_CPU1_SA_CS_N<2>")
	)
	(arc
		(start 130.35026 -256.855976)
		(mid 130.219346 -256.992336)
		(end 130.171698 -257.175254)
		(width 0.088646)
		(layer "In4.Cu")
		(net "M_G_CPU1_SA_CS_N<2>")
	)
	(segment
		(start 128.666494 -258.2672)
		(end 128.666748 -258.267454)
		(width 0.20066)
		(layer "F.Cu")
		(net "M_G_CPU1_SA_CS_N<1>")
	)
	(segment
		(start 128.666748 -258.267454)
		(end 128.666748 -258.80314)
		(width 0.20066)
		(layer "F.Cu")
		(net "M_G_CPU1_SA_CS_N<1>")
	)
	(segment
		(start 200.632314 -267.016738)
		(end 199.527414 -267.016738)
		(width 0.20066)
		(layer "F.Cu")
		(net "M_G_CPU1_SA_CS_N<1>")
	)
	(segment
		(start 172.590206 -265.742674)
		(end 162.992308 -265.742674)
		(width 0.18288)
		(layer "In4.Cu")
		(net "M_G_CPU1_SA_CS_N<1>")
	)
	(segment
		(start 179.570126 -266.755626)
		(end 178.449478 -266.755626)
		(width 0.18288)
		(layer "In4.Cu")
		(net "M_G_CPU1_SA_CS_N<1>")
	)
	(segment
		(start 187.481972 -268.418818)
		(end 186.915044 -268.985746)
		(width 0.18288)
		(layer "In4.Cu")
		(net "M_G_CPU1_SA_CS_N<1>")
	)
	(segment
		(start 187.725558 -268.290802)
		(end 187.550298 -268.383004)
		(width 0.18288)
		(layer "In4.Cu")
		(net "M_G_CPU1_SA_CS_N<1>")
	)
	(segment
		(start 129.802382 -259.122418)
		(end 129.793492 -259.127498)
		(width 0.088646)
		(layer "In4.Cu")
		(net "M_G_CPU1_SA_CS_N<1>")
	)
	(segment
		(start 180.931566 -266.460986)
		(end 179.864766 -266.460986)
		(width 0.18288)
		(layer "In4.Cu")
		(net "M_G_CPU1_SA_CS_N<1>")
	)
	(segment
		(start 128.515618 -259.093462)
		(end 128.510284 -259.074158)
		(width 0.088646)
		(layer "In4.Cu")
		(net "M_G_CPU1_SA_CS_N<1>")
	)
	(segment
		(start 162.239706 -264.990072)
		(end 160.527492 -264.990072)
		(width 0.18288)
		(layer "In4.Cu")
		(net "M_G_CPU1_SA_CS_N<1>")
	)
	(segment
		(start 199.527414 -267.016738)
		(end 199.084438 -266.573762)
		(width 0.18288)
		(layer "In4.Cu")
		(net "M_G_CPU1_SA_CS_N<1>")
	)
	(segment
		(start 159.514286 -264.695432)
		(end 159.103568 -264.284714)
		(width 0.18288)
		(layer "In4.Cu")
		(net "M_G_CPU1_SA_CS_N<1>")
	)
	(segment
		(start 194.758056 -266.573762)
		(end 193.890646 -267.441172)
		(width 0.18288)
		(layer "In4.Cu")
		(net "M_G_CPU1_SA_CS_N<1>")
	)
	(segment
		(start 160.232852 -264.695432)
		(end 159.514286 -264.695432)
		(width 0.18288)
		(layer "In4.Cu")
		(net "M_G_CPU1_SA_CS_N<1>")
	)
	(segment
		(start 181.910736 -267.440156)
		(end 180.931566 -266.460986)
		(width 0.18288)
		(layer "In4.Cu")
		(net "M_G_CPU1_SA_CS_N<1>")
	)
	(segment
		(start 144.750282 -258.256532)
		(end 141.80312 -257.035808)
		(width 0.18288)
		(layer "In4.Cu")
		(net "M_G_CPU1_SA_CS_N<1>")
	)
	(segment
		(start 132.238496 -257.499612)
		(end 132.228082 -257.493516)
		(width 0.088646)
		(layer "In4.Cu")
		(net "M_G_CPU1_SA_CS_N<1>")
	)
	(segment
		(start 147.782026 -258.256532)
		(end 144.750282 -258.256532)
		(width 0.18288)
		(layer "In4.Cu")
		(net "M_G_CPU1_SA_CS_N<1>")
	)
	(segment
		(start 159.103568 -264.284714)
		(end 157.520386 -264.284714)
		(width 0.18288)
		(layer "In4.Cu")
		(net "M_G_CPU1_SA_CS_N<1>")
	)
	(segment
		(start 137.155936 -257.035808)
		(end 136.848088 -257.343656)
		(width 0.088646)
		(layer "In4.Cu")
		(net "M_G_CPU1_SA_CS_N<1>")
	)
	(segment
		(start 199.084438 -266.573762)
		(end 194.758056 -266.573762)
		(width 0.18288)
		(layer "In4.Cu")
		(net "M_G_CPU1_SA_CS_N<1>")
	)
	(segment
		(start 151.618188 -258.382516)
		(end 148.087842 -258.382516)
		(width 0.18288)
		(layer "In4.Cu")
		(net "M_G_CPU1_SA_CS_N<1>")
	)
	(segment
		(start 189.668912 -267.441172)
		(end 188.817504 -268.29258)
		(width 0.18288)
		(layer "In4.Cu")
		(net "M_G_CPU1_SA_CS_N<1>")
	)
	(segment
		(start 128.531366 -259.152136)
		(end 128.515618 -259.093462)
		(width 0.088646)
		(layer "In4.Cu")
		(net "M_G_CPU1_SA_CS_N<1>")
	)
	(segment
		(start 148.087842 -258.382516)
		(end 147.782026 -258.256532)
		(width 0.18288)
		(layer "In4.Cu")
		(net "M_G_CPU1_SA_CS_N<1>")
	)
	(segment
		(start 162.992308 -265.742674)
		(end 162.239706 -264.990072)
		(width 0.18288)
		(layer "In4.Cu")
		(net "M_G_CPU1_SA_CS_N<1>")
	)
	(segment
		(start 186.217814 -268.985746)
		(end 184.672224 -267.440156)
		(width 0.18288)
		(layer "In4.Cu")
		(net "M_G_CPU1_SA_CS_N<1>")
	)
	(segment
		(start 193.890646 -267.441172)
		(end 189.668912 -267.441172)
		(width 0.18288)
		(layer "In4.Cu")
		(net "M_G_CPU1_SA_CS_N<1>")
	)
	(segment
		(start 160.527492 -264.990072)
		(end 160.232852 -264.695432)
		(width 0.18288)
		(layer "In4.Cu")
		(net "M_G_CPU1_SA_CS_N<1>")
	)
	(segment
		(start 188.817504 -268.29258)
		(end 188.104526 -268.29258)
		(width 0.18288)
		(layer "In4.Cu")
		(net "M_G_CPU1_SA_CS_N<1>")
	)
	(segment
		(start 128.86436 -259.121402)
		(end 128.853946 -259.127498)
		(width 0.088646)
		(layer "In4.Cu")
		(net "M_G_CPU1_SA_CS_N<1>")
	)
	(segment
		(start 136.848088 -257.343656)
		(end 136.655048 -257.423666)
		(width 0.088646)
		(layer "In4.Cu")
		(net "M_G_CPU1_SA_CS_N<1>")
	)
	(segment
		(start 130.748278 -257.490976)
		(end 130.733546 -257.499612)
		(width 0.088646)
		(layer "In4.Cu")
		(net "M_G_CPU1_SA_CS_N<1>")
	)
	(segment
		(start 132.623306 -257.493516)
		(end 132.612892 -257.499612)
		(width 0.088646)
		(layer "In4.Cu")
		(net "M_G_CPU1_SA_CS_N<1>")
	)
	(segment
		(start 129.980944 -258.788916)
		(end 129.980944 -258.80314)
		(width 0.088646)
		(layer "In4.Cu")
		(net "M_G_CPU1_SA_CS_N<1>")
	)
	(segment
		(start 178.449478 -266.755626)
		(end 178.282854 -266.589002)
		(width 0.18288)
		(layer "In4.Cu")
		(net "M_G_CPU1_SA_CS_N<1>")
	)
	(segment
		(start 141.80312 -257.035808)
		(end 137.29335 -257.035808)
		(width 0.18288)
		(layer "In4.Cu")
		(net "M_G_CPU1_SA_CS_N<1>")
	)
	(segment
		(start 179.864766 -266.460986)
		(end 179.570126 -266.755626)
		(width 0.18288)
		(layer "In4.Cu")
		(net "M_G_CPU1_SA_CS_N<1>")
	)
	(segment
		(start 174.664878 -265.740896)
		(end 172.590206 -265.740896)
		(width 0.18288)
		(layer "In4.Cu")
		(net "M_G_CPU1_SA_CS_N<1>")
	)
	(segment
		(start 130.272282 -258.308348)
		(end 130.263392 -258.313428)
		(width 0.088646)
		(layer "In4.Cu")
		(net "M_G_CPU1_SA_CS_N<1>")
	)
	(segment
		(start 184.672224 -267.440156)
		(end 181.910736 -267.440156)
		(width 0.18288)
		(layer "In4.Cu")
		(net "M_G_CPU1_SA_CS_N<1>")
	)
	(segment
		(start 128.510284 -259.074158)
		(end 128.666748 -258.80314)
		(width 0.088646)
		(layer "In4.Cu")
		(net "M_G_CPU1_SA_CS_N<1>")
	)
	(segment
		(start 157.520386 -264.284714)
		(end 151.618188 -258.382516)
		(width 0.18288)
		(layer "In4.Cu")
		(net "M_G_CPU1_SA_CS_N<1>")
	)
	(segment
		(start 188.104526 -268.290802)
		(end 187.725558 -268.290802)
		(width 0.18288)
		(layer "In4.Cu")
		(net "M_G_CPU1_SA_CS_N<1>")
	)
	(segment
		(start 134.118096 -257.499612)
		(end 134.107682 -257.493516)
		(width 0.088646)
		(layer "In4.Cu")
		(net "M_G_CPU1_SA_CS_N<1>")
	)
	(segment
		(start 172.590206 -265.740896)
		(end 172.590206 -265.742674)
		(width 0.18288)
		(layer "In4.Cu")
		(net "M_G_CPU1_SA_CS_N<1>")
	)
	(segment
		(start 187.550298 -268.383004)
		(end 187.481972 -268.418818)
		(width 0.18288)
		(layer "In4.Cu")
		(net "M_G_CPU1_SA_CS_N<1>")
	)
	(segment
		(start 186.915044 -268.985746)
		(end 186.217814 -268.985746)
		(width 0.18288)
		(layer "In4.Cu")
		(net "M_G_CPU1_SA_CS_N<1>")
	)
	(segment
		(start 178.282854 -266.589002)
		(end 175.512984 -266.589002)
		(width 0.18288)
		(layer "In4.Cu")
		(net "M_G_CPU1_SA_CS_N<1>")
	)
	(segment
		(start 137.29335 -257.035808)
		(end 137.155936 -257.035808)
		(width 0.088646)
		(layer "In4.Cu")
		(net "M_G_CPU1_SA_CS_N<1>")
	)
	(segment
		(start 188.104526 -268.29258)
		(end 188.104526 -268.290802)
		(width 0.18288)
		(layer "In4.Cu")
		(net "M_G_CPU1_SA_CS_N<1>")
	)
	(segment
		(start 175.512984 -266.589002)
		(end 174.664878 -265.740896)
		(width 0.18288)
		(layer "In4.Cu")
		(net "M_G_CPU1_SA_CS_N<1>")
	)
	(segment
		(start 130.733546 -257.499612)
		(end 130.72745 -257.503168)
		(width 0.088646)
		(layer "In4.Cu")
		(net "M_G_CPU1_SA_CS_N<1>")
	)
	(arc
		(start 132.228082 -257.493516)
		(mid 131.949904 -257.423793)
		(end 131.673346 -257.499612)
		(width 0.088646)
		(layer "In4.Cu")
		(net "M_G_CPU1_SA_CS_N<1>")
	)
	(arc
		(start 131.673346 -257.499612)
		(mid 131.486148 -257.549755)
		(end 131.29895 -257.499612)
		(width 0.088646)
		(layer "In4.Cu")
		(net "M_G_CPU1_SA_CS_N<1>")
	)
	(arc
		(start 130.72745 -257.503168)
		(mid 130.524863 -257.709519)
		(end 130.450844 -257.98907)
		(width 0.088646)
		(layer "In4.Cu")
		(net "M_G_CPU1_SA_CS_N<1>")
	)
	(arc
		(start 128.853946 -259.127498)
		(mid 128.695458 -259.176431)
		(end 128.531366 -259.152136)
		(width 0.088646)
		(layer "In4.Cu")
		(net "M_G_CPU1_SA_CS_N<1>")
	)
	(arc
		(start 130.263392 -258.313428)
		(mid 130.060087 -258.514294)
		(end 129.980944 -258.788916)
		(width 0.088646)
		(layer "In4.Cu")
		(net "M_G_CPU1_SA_CS_N<1>")
	)
	(arc
		(start 132.612892 -257.499612)
		(mid 132.425694 -257.549755)
		(end 132.238496 -257.499612)
		(width 0.088646)
		(layer "In4.Cu")
		(net "M_G_CPU1_SA_CS_N<1>")
	)
	(arc
		(start 130.450844 -257.98907)
		(mid 130.403165 -258.17197)
		(end 130.272282 -258.308348)
		(width 0.088646)
		(layer "In4.Cu")
		(net "M_G_CPU1_SA_CS_N<1>")
	)
	(arc
		(start 134.107682 -257.493516)
		(mid 133.829504 -257.423793)
		(end 133.552946 -257.499612)
		(width 0.088646)
		(layer "In4.Cu")
		(net "M_G_CPU1_SA_CS_N<1>")
	)
	(arc
		(start 136.372092 -257.499612)
		(mid 136.184894 -257.549755)
		(end 135.997696 -257.499612)
		(width 0.088646)
		(layer "In4.Cu")
		(net "M_G_CPU1_SA_CS_N<1>")
	)
	(arc
		(start 135.432292 -257.499612)
		(mid 135.245094 -257.549755)
		(end 135.057896 -257.499612)
		(width 0.088646)
		(layer "In4.Cu")
		(net "M_G_CPU1_SA_CS_N<1>")
	)
	(arc
		(start 133.17855 -257.499612)
		(mid 132.901737 -257.423742)
		(end 132.623306 -257.493516)
		(width 0.088646)
		(layer "In4.Cu")
		(net "M_G_CPU1_SA_CS_N<1>")
	)
	(arc
		(start 134.492492 -257.499612)
		(mid 134.305294 -257.549755)
		(end 134.118096 -257.499612)
		(width 0.088646)
		(layer "In4.Cu")
		(net "M_G_CPU1_SA_CS_N<1>")
	)
	(arc
		(start 129.980944 -258.80314)
		(mid 129.933265 -258.98604)
		(end 129.802382 -259.122418)
		(width 0.088646)
		(layer "In4.Cu")
		(net "M_G_CPU1_SA_CS_N<1>")
	)
	(arc
		(start 129.419096 -259.127498)
		(mid 129.142537 -259.051755)
		(end 128.86436 -259.121402)
		(width 0.088646)
		(layer "In4.Cu")
		(net "M_G_CPU1_SA_CS_N<1>")
	)
	(arc
		(start 135.057896 -257.499612)
		(mid 134.775194 -257.423836)
		(end 134.492492 -257.499612)
		(width 0.088646)
		(layer "In4.Cu")
		(net "M_G_CPU1_SA_CS_N<1>")
	)
	(arc
		(start 131.29895 -257.499612)
		(mid 131.024751 -257.423777)
		(end 130.748278 -257.490976)
		(width 0.088646)
		(layer "In4.Cu")
		(net "M_G_CPU1_SA_CS_N<1>")
	)
	(arc
		(start 129.793492 -259.127498)
		(mid 129.606294 -259.177641)
		(end 129.419096 -259.127498)
		(width 0.088646)
		(layer "In4.Cu")
		(net "M_G_CPU1_SA_CS_N<1>")
	)
	(arc
		(start 135.997696 -257.499612)
		(mid 135.714994 -257.423836)
		(end 135.432292 -257.499612)
		(width 0.088646)
		(layer "In4.Cu")
		(net "M_G_CPU1_SA_CS_N<1>")
	)
	(arc
		(start 136.655048 -257.423666)
		(mid 136.508561 -257.442981)
		(end 136.372092 -257.499612)
		(width 0.088646)
		(layer "In4.Cu")
		(net "M_G_CPU1_SA_CS_N<1>")
	)
	(arc
		(start 133.552946 -257.499612)
		(mid 133.365748 -257.549755)
		(end 133.17855 -257.499612)
		(width 0.088646)
		(layer "In4.Cu")
		(net "M_G_CPU1_SA_CS_N<1>")
	)
	(segment
		(start 128.196848 -259.081016)
		(end 128.196848 -259.093462)
		(width 0.20066)
		(layer "F.Cu")
		(net "M_G_CPU1_SA_CS_N<0>")
	)
	(segment
		(start 196.532246 -267.866622)
		(end 195.427346 -267.866622)
		(width 0.20066)
		(layer "F.Cu")
		(net "M_G_CPU1_SA_CS_N<0>")
	)
	(segment
		(start 128.196848 -259.093462)
		(end 128.196594 -259.616956)
		(width 0.20066)
		(layer "F.Cu")
		(net "M_G_CPU1_SA_CS_N<0>")
	)
	(segment
		(start 187.007246 -270.037306)
		(end 183.154574 -270.037306)
		(width 0.18288)
		(layer "In4.Cu")
		(net "M_G_CPU1_SA_CS_N<0>")
	)
	(segment
		(start 147.1676 -258.60121)
		(end 144.705832 -258.60121)
		(width 0.18288)
		(layer "In4.Cu")
		(net "M_G_CPU1_SA_CS_N<0>")
	)
	(segment
		(start 133.64845 -257.664712)
		(end 133.638036 -257.670808)
		(width 0.088646)
		(layer "In4.Cu")
		(net "M_G_CPU1_SA_CS_N<0>")
	)
	(segment
		(start 131.76885 -257.664712)
		(end 131.758436 -257.670808)
		(width 0.088646)
		(layer "In4.Cu")
		(net "M_G_CPU1_SA_CS_N<0>")
	)
	(segment
		(start 136.793732 -257.613912)
		(end 136.655048 -257.613912)
		(width 0.088646)
		(layer "In4.Cu")
		(net "M_G_CPU1_SA_CS_N<0>")
	)
	(segment
		(start 187.164726 -269.58671)
		(end 187.164726 -269.879826)
		(width 0.18288)
		(layer "In4.Cu")
		(net "M_G_CPU1_SA_CS_N<0>")
	)
	(segment
		(start 157.418786 -264.89025)
		(end 151.468074 -258.939538)
		(width 0.18288)
		(layer "In4.Cu")
		(net "M_G_CPU1_SA_CS_N<0>")
	)
	(segment
		(start 128.949196 -259.292598)
		(end 128.934464 -259.301234)
		(width 0.088646)
		(layer "In4.Cu")
		(net "M_G_CPU1_SA_CS_N<0>")
	)
	(segment
		(start 137.36066 -257.378962)
		(end 136.793732 -257.613912)
		(width 0.088646)
		(layer "In4.Cu")
		(net "M_G_CPU1_SA_CS_N<0>")
	)
	(segment
		(start 134.03326 -257.670808)
		(end 134.022846 -257.664712)
		(width 0.088646)
		(layer "In4.Cu")
		(net "M_G_CPU1_SA_CS_N<0>")
	)
	(segment
		(start 188.84265 -269.142718)
		(end 188.030358 -269.142718)
		(width 0.18288)
		(layer "In4.Cu")
		(net "M_G_CPU1_SA_CS_N<0>")
	)
	(segment
		(start 130.641344 -257.98907)
		(end 130.641344 -258.011168)
		(width 0.088646)
		(layer "In4.Cu")
		(net "M_G_CPU1_SA_CS_N<0>")
	)
	(segment
		(start 141.755114 -257.378962)
		(end 138.84275 -257.378962)
		(width 0.18288)
		(layer "In4.Cu")
		(net "M_G_CPU1_SA_CS_N<0>")
	)
	(segment
		(start 130.828796 -257.664712)
		(end 130.819906 -257.669792)
		(width 0.088646)
		(layer "In4.Cu")
		(net "M_G_CPU1_SA_CS_N<0>")
	)
	(segment
		(start 189.697106 -268.288262)
		(end 188.84265 -269.142718)
		(width 0.18288)
		(layer "In4.Cu")
		(net "M_G_CPU1_SA_CS_N<0>")
	)
	(segment
		(start 160.325054 -265.845544)
		(end 159.643572 -265.845544)
		(width 0.18288)
		(layer "In4.Cu")
		(net "M_G_CPU1_SA_CS_N<0>")
	)
	(segment
		(start 173.893226 -266.59078)
		(end 172.597826 -266.59078)
		(width 0.18288)
		(layer "In4.Cu")
		(net "M_G_CPU1_SA_CS_N<0>")
	)
	(segment
		(start 195.005706 -268.288262)
		(end 189.697106 -268.288262)
		(width 0.18288)
		(layer "In4.Cu")
		(net "M_G_CPU1_SA_CS_N<0>")
	)
	(segment
		(start 172.597826 -266.59078)
		(end 172.597826 -266.592558)
		(width 0.18288)
		(layer "In4.Cu")
		(net "M_G_CPU1_SA_CS_N<0>")
	)
	(segment
		(start 147.984972 -258.939538)
		(end 147.358354 -258.680204)
		(width 0.18288)
		(layer "In4.Cu")
		(net "M_G_CPU1_SA_CS_N<0>")
	)
	(segment
		(start 162.008566 -265.673332)
		(end 160.497266 -265.673332)
		(width 0.18288)
		(layer "In4.Cu")
		(net "M_G_CPU1_SA_CS_N<0>")
	)
	(segment
		(start 160.497266 -265.673332)
		(end 160.325054 -265.845544)
		(width 0.18288)
		(layer "In4.Cu")
		(net "M_G_CPU1_SA_CS_N<0>")
	)
	(segment
		(start 135.912606 -257.670808)
		(end 135.902192 -257.664712)
		(width 0.088646)
		(layer "In4.Cu")
		(net "M_G_CPU1_SA_CS_N<0>")
	)
	(segment
		(start 144.705832 -258.60121)
		(end 141.755114 -257.378962)
		(width 0.18288)
		(layer "In4.Cu")
		(net "M_G_CPU1_SA_CS_N<0>")
	)
	(segment
		(start 172.597826 -266.592558)
		(end 162.927792 -266.592558)
		(width 0.18288)
		(layer "In4.Cu")
		(net "M_G_CPU1_SA_CS_N<0>")
	)
	(segment
		(start 138.84275 -257.378962)
		(end 137.36066 -257.378962)
		(width 0.088646)
		(layer "In4.Cu")
		(net "M_G_CPU1_SA_CS_N<0>")
	)
	(segment
		(start 183.154574 -270.037306)
		(end 180.560218 -267.44295)
		(width 0.18288)
		(layer "In4.Cu")
		(net "M_G_CPU1_SA_CS_N<0>")
	)
	(segment
		(start 187.164726 -269.879826)
		(end 187.007246 -270.037306)
		(width 0.18288)
		(layer "In4.Cu")
		(net "M_G_CPU1_SA_CS_N<0>")
	)
	(segment
		(start 159.643572 -265.845544)
		(end 158.688278 -264.89025)
		(width 0.18288)
		(layer "In4.Cu")
		(net "M_G_CPU1_SA_CS_N<0>")
	)
	(segment
		(start 151.468074 -258.939538)
		(end 147.984972 -258.939538)
		(width 0.18288)
		(layer "In4.Cu")
		(net "M_G_CPU1_SA_CS_N<0>")
	)
	(segment
		(start 162.927792 -266.592558)
		(end 162.008566 -265.673332)
		(width 0.18288)
		(layer "In4.Cu")
		(net "M_G_CPU1_SA_CS_N<0>")
	)
	(segment
		(start 128.442212 -259.322062)
		(end 128.353058 -259.345938)
		(width 0.088646)
		(layer "In4.Cu")
		(net "M_G_CPU1_SA_CS_N<0>")
	)
	(segment
		(start 174.745396 -267.44295)
		(end 173.893226 -266.59078)
		(width 0.18288)
		(layer "In4.Cu")
		(net "M_G_CPU1_SA_CS_N<0>")
	)
	(segment
		(start 128.353058 -259.345938)
		(end 128.196594 -259.616956)
		(width 0.088646)
		(layer "In4.Cu")
		(net "M_G_CPU1_SA_CS_N<0>")
	)
	(segment
		(start 129.901188 -259.285486)
		(end 129.888996 -259.292598)
		(width 0.088646)
		(layer "In4.Cu")
		(net "M_G_CPU1_SA_CS_N<0>")
	)
	(segment
		(start 132.15366 -257.670808)
		(end 132.143246 -257.664712)
		(width 0.088646)
		(layer "In4.Cu")
		(net "M_G_CPU1_SA_CS_N<0>")
	)
	(segment
		(start 187.608718 -269.142718)
		(end 187.164726 -269.58671)
		(width 0.18288)
		(layer "In4.Cu")
		(net "M_G_CPU1_SA_CS_N<0>")
	)
	(segment
		(start 180.560218 -267.44295)
		(end 174.745396 -267.44295)
		(width 0.18288)
		(layer "In4.Cu")
		(net "M_G_CPU1_SA_CS_N<0>")
	)
	(segment
		(start 188.02858 -269.14094)
		(end 187.723526 -269.14094)
		(width 0.18288)
		(layer "In4.Cu")
		(net "M_G_CPU1_SA_CS_N<0>")
	)
	(segment
		(start 158.688278 -264.89025)
		(end 157.418786 -264.89025)
		(width 0.18288)
		(layer "In4.Cu")
		(net "M_G_CPU1_SA_CS_N<0>")
	)
	(segment
		(start 147.358354 -258.680204)
		(end 147.1676 -258.60121)
		(width 0.18288)
		(layer "In4.Cu")
		(net "M_G_CPU1_SA_CS_N<0>")
	)
	(segment
		(start 187.721748 -269.142718)
		(end 187.608718 -269.142718)
		(width 0.18288)
		(layer "In4.Cu")
		(net "M_G_CPU1_SA_CS_N<0>")
	)
	(segment
		(start 188.030358 -269.142718)
		(end 188.02858 -269.14094)
		(width 0.18288)
		(layer "In4.Cu")
		(net "M_G_CPU1_SA_CS_N<0>")
	)
	(segment
		(start 187.723526 -269.14094)
		(end 187.721748 -269.142718)
		(width 0.18288)
		(layer "In4.Cu")
		(net "M_G_CPU1_SA_CS_N<0>")
	)
	(segment
		(start 195.427346 -267.866622)
		(end 195.005706 -268.288262)
		(width 0.18288)
		(layer "In4.Cu")
		(net "M_G_CPU1_SA_CS_N<0>")
	)
	(segment
		(start 130.35915 -258.478782)
		(end 130.35026 -258.483862)
		(width 0.088646)
		(layer "In4.Cu")
		(net "M_G_CPU1_SA_CS_N<0>")
	)
	(arc
		(start 132.708396 -257.664712)
		(mid 132.431837 -257.740455)
		(end 132.15366 -257.670808)
		(width 0.088646)
		(layer "In4.Cu")
		(net "M_G_CPU1_SA_CS_N<0>")
	)
	(arc
		(start 131.758436 -257.670808)
		(mid 131.480004 -257.740654)
		(end 131.203192 -257.664712)
		(width 0.088646)
		(layer "In4.Cu")
		(net "M_G_CPU1_SA_CS_N<0>")
	)
	(arc
		(start 129.888996 -259.292598)
		(mid 129.606294 -259.368374)
		(end 129.323592 -259.292598)
		(width 0.088646)
		(layer "In4.Cu")
		(net "M_G_CPU1_SA_CS_N<0>")
	)
	(arc
		(start 134.587996 -257.664712)
		(mid 134.311437 -257.740455)
		(end 134.03326 -257.670808)
		(width 0.088646)
		(layer "In4.Cu")
		(net "M_G_CPU1_SA_CS_N<0>")
	)
	(arc
		(start 131.203192 -257.664712)
		(mid 131.015994 -257.614569)
		(end 130.828796 -257.664712)
		(width 0.088646)
		(layer "In4.Cu")
		(net "M_G_CPU1_SA_CS_N<0>")
	)
	(arc
		(start 133.082792 -257.664712)
		(mid 132.895594 -257.614569)
		(end 132.708396 -257.664712)
		(width 0.088646)
		(layer "In4.Cu")
		(net "M_G_CPU1_SA_CS_N<0>")
	)
	(arc
		(start 130.35026 -258.483862)
		(mid 130.219346 -258.620222)
		(end 130.171698 -258.80314)
		(width 0.088646)
		(layer "In4.Cu")
		(net "M_G_CPU1_SA_CS_N<0>")
	)
	(arc
		(start 128.934464 -259.301234)
		(mid 128.69072 -259.368113)
		(end 128.442212 -259.322062)
		(width 0.088646)
		(layer "In4.Cu")
		(net "M_G_CPU1_SA_CS_N<0>")
	)
	(arc
		(start 135.902192 -257.664712)
		(mid 135.714994 -257.614569)
		(end 135.527796 -257.664712)
		(width 0.088646)
		(layer "In4.Cu")
		(net "M_G_CPU1_SA_CS_N<0>")
	)
	(arc
		(start 136.46785 -257.664712)
		(mid 136.191037 -257.740582)
		(end 135.912606 -257.670808)
		(width 0.088646)
		(layer "In4.Cu")
		(net "M_G_CPU1_SA_CS_N<0>")
	)
	(arc
		(start 130.641344 -258.011168)
		(mid 130.560433 -258.281296)
		(end 130.35915 -258.478782)
		(width 0.088646)
		(layer "In4.Cu")
		(net "M_G_CPU1_SA_CS_N<0>")
	)
	(arc
		(start 134.962392 -257.664712)
		(mid 134.775194 -257.614569)
		(end 134.587996 -257.664712)
		(width 0.088646)
		(layer "In4.Cu")
		(net "M_G_CPU1_SA_CS_N<0>")
	)
	(arc
		(start 132.143246 -257.664712)
		(mid 131.956048 -257.614569)
		(end 131.76885 -257.664712)
		(width 0.088646)
		(layer "In4.Cu")
		(net "M_G_CPU1_SA_CS_N<0>")
	)
	(arc
		(start 135.527796 -257.664712)
		(mid 135.245094 -257.740488)
		(end 134.962392 -257.664712)
		(width 0.088646)
		(layer "In4.Cu")
		(net "M_G_CPU1_SA_CS_N<0>")
	)
	(arc
		(start 130.171698 -258.80314)
		(mid 130.099463 -259.079664)
		(end 129.901188 -259.285486)
		(width 0.088646)
		(layer "In4.Cu")
		(net "M_G_CPU1_SA_CS_N<0>")
	)
	(arc
		(start 129.323592 -259.292598)
		(mid 129.136394 -259.242455)
		(end 128.949196 -259.292598)
		(width 0.088646)
		(layer "In4.Cu")
		(net "M_G_CPU1_SA_CS_N<0>")
	)
	(arc
		(start 134.022846 -257.664712)
		(mid 133.835648 -257.614569)
		(end 133.64845 -257.664712)
		(width 0.088646)
		(layer "In4.Cu")
		(net "M_G_CPU1_SA_CS_N<0>")
	)
	(arc
		(start 136.655048 -257.613912)
		(mid 136.558109 -257.627002)
		(end 136.46785 -257.664712)
		(width 0.088646)
		(layer "In4.Cu")
		(net "M_G_CPU1_SA_CS_N<0>")
	)
	(arc
		(start 133.638036 -257.670808)
		(mid 133.359604 -257.740654)
		(end 133.082792 -257.664712)
		(width 0.088646)
		(layer "In4.Cu")
		(net "M_G_CPU1_SA_CS_N<0>")
	)
	(arc
		(start 130.819906 -257.669792)
		(mid 130.688992 -257.806152)
		(end 130.641344 -257.98907)
		(width 0.088646)
		(layer "In4.Cu")
		(net "M_G_CPU1_SA_CS_N<0>")
	)
	(segment
		(start 199.024494 -270.143224)
		(end 199.298052 -270.416782)
		(width 0.20066)
		(layer "F.Cu")
		(net "M_G_CPU1_SA_CB<7>")
	)
	(segment
		(start 199.298052 -270.416782)
		(end 200.632314 -270.416782)
		(width 0.20066)
		(layer "F.Cu")
		(net "M_G_CPU1_SA_CB<7>")
	)
	(segment
		(start 195.218812 -270.841724)
		(end 195.343018 -270.841724)
		(width 0.20066)
		(layer "F.Cu")
		(net "M_G_CPU1_SA_CB<7>")
	)
	(segment
		(start 197.530466 -270.841724)
		(end 197.834504 -270.841724)
		(width 0.101854)
		(layer "F.Cu")
		(net "M_G_CPU1_SA_CB<7>")
	)
	(segment
		(start 128.196848 -260.708902)
		(end 128.196848 -261.244334)
		(width 0.20066)
		(layer "F.Cu")
		(net "M_G_CPU1_SA_CB<7>")
	)
	(segment
		(start 195.343018 -270.841724)
		(end 195.522596 -270.841724)
		(width 0.101854)
		(layer "F.Cu")
		(net "M_G_CPU1_SA_CB<7>")
	)
	(segment
		(start 195.522596 -270.841724)
		(end 197.530466 -270.841724)
		(width 0.1016)
		(layer "F.Cu")
		(net "M_G_CPU1_SA_CB<7>")
	)
	(segment
		(start 193.088514 -270.416782)
		(end 194.79387 -270.416782)
		(width 0.20066)
		(layer "F.Cu")
		(net "M_G_CPU1_SA_CB<7>")
	)
	(segment
		(start 197.834504 -270.841724)
		(end 198.227188 -270.841724)
		(width 0.20066)
		(layer "F.Cu")
		(net "M_G_CPU1_SA_CB<7>")
	)
	(segment
		(start 198.427848 -270.641064)
		(end 198.427848 -270.343884)
		(width 0.20066)
		(layer "F.Cu")
		(net "M_G_CPU1_SA_CB<7>")
	)
	(segment
		(start 194.79387 -270.416782)
		(end 195.218812 -270.841724)
		(width 0.20066)
		(layer "F.Cu")
		(net "M_G_CPU1_SA_CB<7>")
	)
	(segment
		(start 191.958214 -270.416782)
		(end 193.088514 -270.416782)
		(width 0.20066)
		(layer "F.Cu")
		(net "M_G_CPU1_SA_CB<7>")
	)
	(segment
		(start 198.227188 -270.841724)
		(end 198.427848 -270.641064)
		(width 0.20066)
		(layer "F.Cu")
		(net "M_G_CPU1_SA_CB<7>")
	)
	(segment
		(start 128.196594 -261.244588)
		(end 128.196594 -261.244842)
		(width 0.20066)
		(layer "F.Cu")
		(net "M_G_CPU1_SA_CB<7>")
	)
	(segment
		(start 198.628508 -270.143224)
		(end 199.024494 -270.143224)
		(width 0.20066)
		(layer "F.Cu")
		(net "M_G_CPU1_SA_CB<7>")
	)
	(segment
		(start 198.427848 -270.343884)
		(end 198.628508 -270.143224)
		(width 0.20066)
		(layer "F.Cu")
		(net "M_G_CPU1_SA_CB<7>")
	)
	(segment
		(start 128.196848 -261.244334)
		(end 128.196594 -261.244588)
		(width 0.20066)
		(layer "F.Cu")
		(net "M_G_CPU1_SA_CB<7>")
	)
	(segment
		(start 173.856142 -258.9403)
		(end 173.004226 -259.792216)
		(width 0.18288)
		(layer "In6.Cu")
		(net "M_G_CPU1_SA_CB<7>")
	)
	(segment
		(start 191.958214 -270.416782)
		(end 191.53378 -269.992348)
		(width 0.18288)
		(layer "In6.Cu")
		(net "M_G_CPU1_SA_CB<7>")
	)
	(segment
		(start 132.62356 -260.749034)
		(end 132.613146 -260.75513)
		(width 0.088646)
		(layer "In6.Cu")
		(net "M_G_CPU1_SA_CB<7>")
	)
	(segment
		(start 191.53378 -269.992348)
		(end 187.568078 -269.992348)
		(width 0.18288)
		(layer "In6.Cu")
		(net "M_G_CPU1_SA_CB<7>")
	)
	(segment
		(start 173.004226 -259.792216)
		(end 169.831004 -259.792216)
		(width 0.18288)
		(layer "In6.Cu")
		(net "M_G_CPU1_SA_CB<7>")
	)
	(segment
		(start 187.385198 -262.504936)
		(end 186.6138 -261.733538)
		(width 0.18288)
		(layer "In6.Cu")
		(net "M_G_CPU1_SA_CB<7>")
	)
	(segment
		(start 133.563106 -260.749034)
		(end 133.552692 -260.75513)
		(width 0.088646)
		(layer "In6.Cu")
		(net "M_G_CPU1_SA_CB<7>")
	)
	(segment
		(start 151.233378 -259.982716)
		(end 145.410174 -259.982716)
		(width 0.18288)
		(layer "In6.Cu")
		(net "M_G_CPU1_SA_CB<7>")
	)
	(segment
		(start 129.808478 -260.746494)
		(end 129.793746 -260.75513)
		(width 0.088646)
		(layer "In6.Cu")
		(net "M_G_CPU1_SA_CB<7>")
	)
	(segment
		(start 131.688078 -260.746494)
		(end 131.673346 -260.75513)
		(width 0.088646)
		(layer "In6.Cu")
		(net "M_G_CPU1_SA_CB<7>")
	)
	(segment
		(start 151.7142 -259.501894)
		(end 151.233378 -259.982716)
		(width 0.18288)
		(layer "In6.Cu")
		(net "M_G_CPU1_SA_CB<7>")
	)
	(segment
		(start 128.392682 -261.56412)
		(end 128.383792 -261.5692)
		(width 0.088646)
		(layer "In6.Cu")
		(net "M_G_CPU1_SA_CB<7>")
	)
	(segment
		(start 169.540682 -259.501894)
		(end 151.7142 -259.501894)
		(width 0.18288)
		(layer "In6.Cu")
		(net "M_G_CPU1_SA_CB<7>")
	)
	(segment
		(start 128.571244 -261.230618)
		(end 128.571244 -261.244842)
		(width 0.088646)
		(layer "In6.Cu")
		(net "M_G_CPU1_SA_CB<7>")
	)
	(segment
		(start 139.254738 -259.510022)
		(end 138.902948 -259.861812)
		(width 0.088646)
		(layer "In6.Cu")
		(net "M_G_CPU1_SA_CB<7>")
	)
	(segment
		(start 139.70635 -259.510022)
		(end 139.254738 -259.510022)
		(width 0.088646)
		(layer "In6.Cu")
		(net "M_G_CPU1_SA_CB<7>")
	)
	(segment
		(start 186.6138 -261.733538)
		(end 184.383426 -261.733538)
		(width 0.18288)
		(layer "In6.Cu")
		(net "M_G_CPU1_SA_CB<7>")
	)
	(segment
		(start 145.410174 -259.982716)
		(end 143.05534 -259.51434)
		(width 0.18288)
		(layer "In6.Cu")
		(net "M_G_CPU1_SA_CB<7>")
	)
	(segment
		(start 138.260582 -260.75005)
		(end 138.251692 -260.75513)
		(width 0.088646)
		(layer "In6.Cu")
		(net "M_G_CPU1_SA_CB<7>")
	)
	(segment
		(start 130.748278 -260.746494)
		(end 130.733546 -260.75513)
		(width 0.088646)
		(layer "In6.Cu")
		(net "M_G_CPU1_SA_CB<7>")
	)
	(segment
		(start 138.439144 -260.415278)
		(end 138.439144 -260.430772)
		(width 0.088646)
		(layer "In6.Cu")
		(net "M_G_CPU1_SA_CB<7>")
	)
	(segment
		(start 183.443626 -260.793738)
		(end 179.97551 -260.793738)
		(width 0.18288)
		(layer "In6.Cu")
		(net "M_G_CPU1_SA_CB<7>")
	)
	(segment
		(start 128.009396 -261.5692)
		(end 128.000506 -261.56412)
		(width 0.088646)
		(layer "In6.Cu")
		(net "M_G_CPU1_SA_CB<7>")
	)
	(segment
		(start 143.044926 -259.510022)
		(end 139.70635 -259.510022)
		(width 0.18288)
		(layer "In6.Cu")
		(net "M_G_CPU1_SA_CB<7>")
	)
	(segment
		(start 143.05534 -259.51434)
		(end 143.044926 -259.510022)
		(width 0.18288)
		(layer "In6.Cu")
		(net "M_G_CPU1_SA_CB<7>")
	)
	(segment
		(start 187.385198 -269.809468)
		(end 187.385198 -262.504936)
		(width 0.18288)
		(layer "In6.Cu")
		(net "M_G_CPU1_SA_CB<7>")
	)
	(segment
		(start 178.122072 -258.9403)
		(end 173.856142 -258.9403)
		(width 0.18288)
		(layer "In6.Cu")
		(net "M_G_CPU1_SA_CB<7>")
	)
	(segment
		(start 187.568078 -269.992348)
		(end 187.385198 -269.809468)
		(width 0.18288)
		(layer "In6.Cu")
		(net "M_G_CPU1_SA_CB<7>")
	)
	(segment
		(start 179.97551 -260.793738)
		(end 178.122072 -258.9403)
		(width 0.18288)
		(layer "In6.Cu")
		(net "M_G_CPU1_SA_CB<7>")
	)
	(segment
		(start 134.50316 -260.749034)
		(end 134.492746 -260.75513)
		(width 0.088646)
		(layer "In6.Cu")
		(net "M_G_CPU1_SA_CB<7>")
	)
	(segment
		(start 127.88392 -261.244842)
		(end 128.196594 -261.244842)
		(width 0.088646)
		(layer "In6.Cu")
		(net "M_G_CPU1_SA_CB<7>")
	)
	(segment
		(start 128.868678 -260.746494)
		(end 128.853946 -260.75513)
		(width 0.088646)
		(layer "In6.Cu")
		(net "M_G_CPU1_SA_CB<7>")
	)
	(segment
		(start 184.383426 -261.733538)
		(end 183.443626 -260.793738)
		(width 0.18288)
		(layer "In6.Cu")
		(net "M_G_CPU1_SA_CB<7>")
	)
	(segment
		(start 169.831004 -259.792216)
		(end 169.540682 -259.501894)
		(width 0.18288)
		(layer "In6.Cu")
		(net "M_G_CPU1_SA_CB<7>")
	)
	(segment
		(start 127.826516 -261.302246)
		(end 127.88392 -261.244842)
		(width 0.088646)
		(layer "In6.Cu")
		(net "M_G_CPU1_SA_CB<7>")
	)
	(arc
		(start 128.000506 -261.56412)
		(mid 127.884767 -261.452296)
		(end 127.826516 -261.302246)
		(width 0.088646)
		(layer "In6.Cu")
		(net "M_G_CPU1_SA_CB<7>")
	)
	(arc
		(start 132.23875 -260.75513)
		(mid 131.964521 -260.679205)
		(end 131.688078 -260.746494)
		(width 0.088646)
		(layer "In6.Cu")
		(net "M_G_CPU1_SA_CB<7>")
	)
	(arc
		(start 136.937496 -260.75513)
		(mid 136.654794 -260.679388)
		(end 136.372092 -260.75513)
		(width 0.088646)
		(layer "In6.Cu")
		(net "M_G_CPU1_SA_CB<7>")
	)
	(arc
		(start 136.372092 -260.75513)
		(mid 136.184894 -260.805273)
		(end 135.997696 -260.75513)
		(width 0.088646)
		(layer "In6.Cu")
		(net "M_G_CPU1_SA_CB<7>")
	)
	(arc
		(start 133.552692 -260.75513)
		(mid 133.365494 -260.805273)
		(end 133.178296 -260.75513)
		(width 0.088646)
		(layer "In6.Cu")
		(net "M_G_CPU1_SA_CB<7>")
	)
	(arc
		(start 135.997696 -260.75513)
		(mid 135.714994 -260.679388)
		(end 135.432292 -260.75513)
		(width 0.088646)
		(layer "In6.Cu")
		(net "M_G_CPU1_SA_CB<7>")
	)
	(arc
		(start 133.178296 -260.75513)
		(mid 132.901737 -260.679421)
		(end 132.62356 -260.749034)
		(width 0.088646)
		(layer "In6.Cu")
		(net "M_G_CPU1_SA_CB<7>")
	)
	(arc
		(start 138.251692 -260.75513)
		(mid 138.064494 -260.805273)
		(end 137.877296 -260.75513)
		(width 0.088646)
		(layer "In6.Cu")
		(net "M_G_CPU1_SA_CB<7>")
	)
	(arc
		(start 128.383792 -261.5692)
		(mid 128.196594 -261.619343)
		(end 128.009396 -261.5692)
		(width 0.088646)
		(layer "In6.Cu")
		(net "M_G_CPU1_SA_CB<7>")
	)
	(arc
		(start 129.793746 -260.75513)
		(mid 129.606548 -260.805273)
		(end 129.41935 -260.75513)
		(width 0.088646)
		(layer "In6.Cu")
		(net "M_G_CPU1_SA_CB<7>")
	)
	(arc
		(start 130.35915 -260.75513)
		(mid 130.084921 -260.679205)
		(end 129.808478 -260.746494)
		(width 0.088646)
		(layer "In6.Cu")
		(net "M_G_CPU1_SA_CB<7>")
	)
	(arc
		(start 131.29895 -260.75513)
		(mid 131.024721 -260.679205)
		(end 130.748278 -260.746494)
		(width 0.088646)
		(layer "In6.Cu")
		(net "M_G_CPU1_SA_CB<7>")
	)
	(arc
		(start 132.613146 -260.75513)
		(mid 132.425948 -260.805273)
		(end 132.23875 -260.75513)
		(width 0.088646)
		(layer "In6.Cu")
		(net "M_G_CPU1_SA_CB<7>")
	)
	(arc
		(start 137.311892 -260.75513)
		(mid 137.124694 -260.805273)
		(end 136.937496 -260.75513)
		(width 0.088646)
		(layer "In6.Cu")
		(net "M_G_CPU1_SA_CB<7>")
	)
	(arc
		(start 129.41935 -260.75513)
		(mid 129.145121 -260.679205)
		(end 128.868678 -260.746494)
		(width 0.088646)
		(layer "In6.Cu")
		(net "M_G_CPU1_SA_CB<7>")
	)
	(arc
		(start 128.853946 -260.75513)
		(mid 128.650465 -260.955934)
		(end 128.571244 -261.230618)
		(width 0.088646)
		(layer "In6.Cu")
		(net "M_G_CPU1_SA_CB<7>")
	)
	(arc
		(start 134.11835 -260.75513)
		(mid 133.841537 -260.679294)
		(end 133.563106 -260.749034)
		(width 0.088646)
		(layer "In6.Cu")
		(net "M_G_CPU1_SA_CB<7>")
	)
	(arc
		(start 137.877296 -260.75513)
		(mid 137.594594 -260.679388)
		(end 137.311892 -260.75513)
		(width 0.088646)
		(layer "In6.Cu")
		(net "M_G_CPU1_SA_CB<7>")
	)
	(arc
		(start 135.057896 -260.75513)
		(mid 134.781337 -260.679421)
		(end 134.50316 -260.749034)
		(width 0.088646)
		(layer "In6.Cu")
		(net "M_G_CPU1_SA_CB<7>")
	)
	(arc
		(start 131.673346 -260.75513)
		(mid 131.486148 -260.805273)
		(end 131.29895 -260.75513)
		(width 0.088646)
		(layer "In6.Cu")
		(net "M_G_CPU1_SA_CB<7>")
	)
	(arc
		(start 135.432292 -260.75513)
		(mid 135.245094 -260.805273)
		(end 135.057896 -260.75513)
		(width 0.088646)
		(layer "In6.Cu")
		(net "M_G_CPU1_SA_CB<7>")
	)
	(arc
		(start 138.439144 -260.430772)
		(mid 138.391465 -260.613672)
		(end 138.260582 -260.75005)
		(width 0.088646)
		(layer "In6.Cu")
		(net "M_G_CPU1_SA_CB<7>")
	)
	(arc
		(start 138.902948 -259.861812)
		(mid 138.574676 -260.057801)
		(end 138.439144 -260.415278)
		(width 0.088646)
		(layer "In6.Cu")
		(net "M_G_CPU1_SA_CB<7>")
	)
	(arc
		(start 130.733546 -260.75513)
		(mid 130.546348 -260.805273)
		(end 130.35915 -260.75513)
		(width 0.088646)
		(layer "In6.Cu")
		(net "M_G_CPU1_SA_CB<7>")
	)
	(arc
		(start 128.571244 -261.244842)
		(mid 128.523565 -261.427742)
		(end 128.392682 -261.56412)
		(width 0.088646)
		(layer "In6.Cu")
		(net "M_G_CPU1_SA_CB<7>")
	)
	(arc
		(start 134.492746 -260.75513)
		(mid 134.305548 -260.805273)
		(end 134.11835 -260.75513)
		(width 0.088646)
		(layer "In6.Cu")
		(net "M_G_CPU1_SA_CB<7>")
	)
	(segment
		(start 199.298052 -272.116804)
		(end 200.632314 -272.116804)
		(width 0.20066)
		(layer "F.Cu")
		(net "M_G_CPU1_SA_CB<6>")
	)
	(segment
		(start 193.088514 -272.116804)
		(end 194.685158 -272.116804)
		(width 0.20066)
		(layer "F.Cu")
		(net "M_G_CPU1_SA_CB<6>")
	)
	(segment
		(start 128.666748 -261.522972)
		(end 128.666748 -262.058658)
		(width 0.20066)
		(layer "F.Cu")
		(net "M_G_CPU1_SA_CB<6>")
	)
	(segment
		(start 191.941704 -272.116804)
		(end 193.088514 -272.116804)
		(width 0.20066)
		(layer "F.Cu")
		(net "M_G_CPU1_SA_CB<6>")
	)
	(segment
		(start 197.48881 -272.541746)
		(end 197.834504 -272.541746)
		(width 0.101854)
		(layer "F.Cu")
		(net "M_G_CPU1_SA_CB<6>")
	)
	(segment
		(start 195.1101 -272.541746)
		(end 195.343018 -272.541746)
		(width 0.20066)
		(layer "F.Cu")
		(net "M_G_CPU1_SA_CB<6>")
	)
	(segment
		(start 198.427848 -272.341086)
		(end 198.427848 -272.02257)
		(width 0.20066)
		(layer "F.Cu")
		(net "M_G_CPU1_SA_CB<6>")
	)
	(segment
		(start 198.427848 -272.02257)
		(end 198.628508 -271.82191)
		(width 0.20066)
		(layer "F.Cu")
		(net "M_G_CPU1_SA_CB<6>")
	)
	(segment
		(start 197.834504 -272.541746)
		(end 198.227188 -272.541746)
		(width 0.20066)
		(layer "F.Cu")
		(net "M_G_CPU1_SA_CB<6>")
	)
	(segment
		(start 195.522596 -272.541746)
		(end 197.48881 -272.541746)
		(width 0.1016)
		(layer "F.Cu")
		(net "M_G_CPU1_SA_CB<6>")
	)
	(segment
		(start 128.666494 -261.522718)
		(end 128.666748 -261.522972)
		(width 0.20066)
		(layer "F.Cu")
		(net "M_G_CPU1_SA_CB<6>")
	)
	(segment
		(start 199.003158 -271.82191)
		(end 199.298052 -272.116804)
		(width 0.20066)
		(layer "F.Cu")
		(net "M_G_CPU1_SA_CB<6>")
	)
	(segment
		(start 198.628508 -271.82191)
		(end 199.003158 -271.82191)
		(width 0.20066)
		(layer "F.Cu")
		(net "M_G_CPU1_SA_CB<6>")
	)
	(segment
		(start 198.227188 -272.541746)
		(end 198.427848 -272.341086)
		(width 0.20066)
		(layer "F.Cu")
		(net "M_G_CPU1_SA_CB<6>")
	)
	(segment
		(start 195.343018 -272.541746)
		(end 195.522596 -272.541746)
		(width 0.101854)
		(layer "F.Cu")
		(net "M_G_CPU1_SA_CB<6>")
	)
	(segment
		(start 194.685158 -272.116804)
		(end 195.1101 -272.541746)
		(width 0.20066)
		(layer "F.Cu")
		(net "M_G_CPU1_SA_CB<6>")
	)
	(segment
		(start 181.87416 -262.312658)
		(end 181.87416 -262.035544)
		(width 0.18288)
		(layer "In6.Cu")
		(net "M_G_CPU1_SA_CB<6>")
	)
	(segment
		(start 140.46835 -260.521196)
		(end 139.975844 -260.521196)
		(width 0.088646)
		(layer "In6.Cu")
		(net "M_G_CPU1_SA_CB<6>")
	)
	(segment
		(start 181.36362 -261.852664)
		(end 181.18074 -262.035544)
		(width 0.18288)
		(layer "In6.Cu")
		(net "M_G_CPU1_SA_CB<6>")
	)
	(segment
		(start 188.73978 -271.083024)
		(end 188.73978 -271.50949)
		(width 0.18288)
		(layer "In6.Cu")
		(net "M_G_CPU1_SA_CB<6>")
	)
	(segment
		(start 182.05704 -262.495538)
		(end 181.87416 -262.312658)
		(width 0.18288)
		(layer "In6.Cu")
		(net "M_G_CPU1_SA_CB<6>")
	)
	(segment
		(start 174.765208 -262.419338)
		(end 173.837854 -261.491984)
		(width 0.18288)
		(layer "In6.Cu")
		(net "M_G_CPU1_SA_CB<6>")
	)
	(segment
		(start 139.81811 -260.67893)
		(end 139.474956 -260.67893)
		(width 0.088646)
		(layer "In6.Cu")
		(net "M_G_CPU1_SA_CB<6>")
	)
	(segment
		(start 130.828796 -261.5692)
		(end 130.814064 -261.560564)
		(width 0.088646)
		(layer "In6.Cu")
		(net "M_G_CPU1_SA_CB<6>")
	)
	(segment
		(start 189.61608 -271.69237)
		(end 189.4332 -271.50949)
		(width 0.18288)
		(layer "In6.Cu")
		(net "M_G_CPU1_SA_CB<6>")
	)
	(segment
		(start 176.407826 -261.492238)
		(end 175.480726 -262.419338)
		(width 0.18288)
		(layer "In6.Cu")
		(net "M_G_CPU1_SA_CB<6>")
	)
	(segment
		(start 181.69128 -261.852664)
		(end 181.36362 -261.852664)
		(width 0.18288)
		(layer "In6.Cu")
		(net "M_G_CPU1_SA_CB<6>")
	)
	(segment
		(start 173.837854 -261.491984)
		(end 173.557946 -261.492238)
		(width 0.18288)
		(layer "In6.Cu")
		(net "M_G_CPU1_SA_CB<6>")
	)
	(segment
		(start 162.635692 -261.01548)
		(end 162.635692 -261.445502)
		(width 0.18288)
		(layer "In6.Cu")
		(net "M_G_CPU1_SA_CB<6>")
	)
	(segment
		(start 131.768596 -261.5692)
		(end 131.753864 -261.560564)
		(width 0.088646)
		(layer "In6.Cu")
		(net "M_G_CPU1_SA_CB<6>")
	)
	(segment
		(start 186.272424 -271.69237)
		(end 185.530998 -270.950944)
		(width 0.18288)
		(layer "In6.Cu")
		(net "M_G_CPU1_SA_CB<6>")
	)
	(segment
		(start 184.993534 -263.473692)
		(end 184.295034 -263.473692)
		(width 0.18288)
		(layer "In6.Cu")
		(net "M_G_CPU1_SA_CB<6>")
	)
	(segment
		(start 163.212272 -260.78688)
		(end 162.864292 -260.78688)
		(width 0.18288)
		(layer "In6.Cu")
		(net "M_G_CPU1_SA_CB<6>")
	)
	(segment
		(start 157.147514 -260.978396)
		(end 145.309844 -260.978396)
		(width 0.18288)
		(layer "In6.Cu")
		(net "M_G_CPU1_SA_CB<6>")
	)
	(segment
		(start 183.31688 -262.495538)
		(end 182.05704 -262.495538)
		(width 0.18288)
		(layer "In6.Cu")
		(net "M_G_CPU1_SA_CB<6>")
	)
	(segment
		(start 177.612294 -261.492238)
		(end 176.407826 -261.492238)
		(width 0.18288)
		(layer "In6.Cu")
		(net "M_G_CPU1_SA_CB<6>")
	)
	(segment
		(start 162.475672 -261.605522)
		(end 160.382966 -261.605522)
		(width 0.18288)
		(layer "In6.Cu")
		(net "M_G_CPU1_SA_CB<6>")
	)
	(segment
		(start 143.01089 -260.521196)
		(end 140.46835 -260.521196)
		(width 0.18288)
		(layer "In6.Cu")
		(net "M_G_CPU1_SA_CB<6>")
	)
	(segment
		(start 188.92266 -270.900144)
		(end 188.73978 -271.083024)
		(width 0.18288)
		(layer "In6.Cu")
		(net "M_G_CPU1_SA_CB<6>")
	)
	(segment
		(start 162.635692 -261.445502)
		(end 162.475672 -261.605522)
		(width 0.18288)
		(layer "In6.Cu")
		(net "M_G_CPU1_SA_CB<6>")
	)
	(segment
		(start 157.545024 -261.375906)
		(end 157.147514 -260.978396)
		(width 0.18288)
		(layer "In6.Cu")
		(net "M_G_CPU1_SA_CB<6>")
	)
	(segment
		(start 138.909044 -261.2263)
		(end 138.909044 -261.244842)
		(width 0.088646)
		(layer "In6.Cu")
		(net "M_G_CPU1_SA_CB<6>")
	)
	(segment
		(start 179.887626 -262.495538)
		(end 179.684426 -262.292338)
		(width 0.18288)
		(layer "In6.Cu")
		(net "M_G_CPU1_SA_CB<6>")
	)
	(segment
		(start 191.941704 -272.082768)
		(end 191.551306 -271.69237)
		(width 0.18288)
		(layer "In6.Cu")
		(net "M_G_CPU1_SA_CB<6>")
	)
	(segment
		(start 179.684426 -262.292338)
		(end 178.412394 -262.292338)
		(width 0.18288)
		(layer "In6.Cu")
		(net "M_G_CPU1_SA_CB<6>")
	)
	(segment
		(start 163.55314 -261.62254)
		(end 163.39312 -261.46252)
		(width 0.18288)
		(layer "In6.Cu")
		(net "M_G_CPU1_SA_CB<6>")
	)
	(segment
		(start 189.4332 -271.50949)
		(end 189.4332 -271.083024)
		(width 0.18288)
		(layer "In6.Cu")
		(net "M_G_CPU1_SA_CB<6>")
	)
	(segment
		(start 185.530998 -264.011156)
		(end 184.993534 -263.473692)
		(width 0.18288)
		(layer "In6.Cu")
		(net "M_G_CPU1_SA_CB<6>")
	)
	(segment
		(start 181.87416 -262.035544)
		(end 181.69128 -261.852664)
		(width 0.18288)
		(layer "In6.Cu")
		(net "M_G_CPU1_SA_CB<6>")
	)
	(segment
		(start 188.5569 -271.69237)
		(end 186.272424 -271.69237)
		(width 0.18288)
		(layer "In6.Cu")
		(net "M_G_CPU1_SA_CB<6>")
	)
	(segment
		(start 164.737796 -261.342632)
		(end 164.457888 -261.62254)
		(width 0.18288)
		(layer "In6.Cu")
		(net "M_G_CPU1_SA_CB<6>")
	)
	(segment
		(start 175.480726 -262.419338)
		(end 174.765208 -262.419338)
		(width 0.18288)
		(layer "In6.Cu")
		(net "M_G_CPU1_SA_CB<6>")
	)
	(segment
		(start 189.4332 -271.083024)
		(end 189.25032 -270.900144)
		(width 0.18288)
		(layer "In6.Cu")
		(net "M_G_CPU1_SA_CB<6>")
	)
	(segment
		(start 133.648196 -261.5692)
		(end 133.633464 -261.560564)
		(width 0.088646)
		(layer "In6.Cu")
		(net "M_G_CPU1_SA_CB<6>")
	)
	(segment
		(start 160.15335 -261.375906)
		(end 157.545024 -261.375906)
		(width 0.18288)
		(layer "In6.Cu")
		(net "M_G_CPU1_SA_CB<6>")
	)
	(segment
		(start 129.888996 -261.5692)
		(end 129.874264 -261.560564)
		(width 0.088646)
		(layer "In6.Cu")
		(net "M_G_CPU1_SA_CB<6>")
	)
	(segment
		(start 184.295034 -263.473692)
		(end 183.31688 -262.495538)
		(width 0.18288)
		(layer "In6.Cu")
		(net "M_G_CPU1_SA_CB<6>")
	)
	(segment
		(start 145.309844 -260.978396)
		(end 143.01089 -260.521196)
		(width 0.18288)
		(layer "In6.Cu")
		(net "M_G_CPU1_SA_CB<6>")
	)
	(segment
		(start 163.39312 -261.46252)
		(end 163.39312 -260.967728)
		(width 0.18288)
		(layer "In6.Cu")
		(net "M_G_CPU1_SA_CB<6>")
	)
	(segment
		(start 163.39312 -260.967728)
		(end 163.212272 -260.78688)
		(width 0.18288)
		(layer "In6.Cu")
		(net "M_G_CPU1_SA_CB<6>")
	)
	(segment
		(start 160.382966 -261.605522)
		(end 160.15335 -261.375906)
		(width 0.18288)
		(layer "In6.Cu")
		(net "M_G_CPU1_SA_CB<6>")
	)
	(segment
		(start 134.587996 -261.5692)
		(end 134.573264 -261.560564)
		(width 0.088646)
		(layer "In6.Cu")
		(net "M_G_CPU1_SA_CB<6>")
	)
	(segment
		(start 139.975844 -260.521196)
		(end 139.81811 -260.67893)
		(width 0.088646)
		(layer "In6.Cu")
		(net "M_G_CPU1_SA_CB<6>")
	)
	(segment
		(start 189.25032 -270.900144)
		(end 188.92266 -270.900144)
		(width 0.18288)
		(layer "In6.Cu")
		(net "M_G_CPU1_SA_CB<6>")
	)
	(segment
		(start 191.551306 -271.69237)
		(end 189.61608 -271.69237)
		(width 0.18288)
		(layer "In6.Cu")
		(net "M_G_CPU1_SA_CB<6>")
	)
	(segment
		(start 181.18074 -262.312658)
		(end 180.99786 -262.495538)
		(width 0.18288)
		(layer "In6.Cu")
		(net "M_G_CPU1_SA_CB<6>")
	)
	(segment
		(start 164.457888 -261.62254)
		(end 163.55314 -261.62254)
		(width 0.18288)
		(layer "In6.Cu")
		(net "M_G_CPU1_SA_CB<6>")
	)
	(segment
		(start 188.73978 -271.50949)
		(end 188.5569 -271.69237)
		(width 0.18288)
		(layer "In6.Cu")
		(net "M_G_CPU1_SA_CB<6>")
	)
	(segment
		(start 178.412394 -262.292338)
		(end 177.612294 -261.492238)
		(width 0.18288)
		(layer "In6.Cu")
		(net "M_G_CPU1_SA_CB<6>")
	)
	(segment
		(start 173.557946 -261.492238)
		(end 168.324276 -261.492238)
		(width 0.18288)
		(layer "In6.Cu")
		(net "M_G_CPU1_SA_CB<6>")
	)
	(segment
		(start 181.18074 -262.035544)
		(end 181.18074 -262.312658)
		(width 0.18288)
		(layer "In6.Cu")
		(net "M_G_CPU1_SA_CB<6>")
	)
	(segment
		(start 191.941704 -272.116804)
		(end 191.941704 -272.082768)
		(width 0.18288)
		(layer "In6.Cu")
		(net "M_G_CPU1_SA_CB<6>")
	)
	(segment
		(start 138.730482 -261.56412)
		(end 138.721592 -261.5692)
		(width 0.088646)
		(layer "In6.Cu")
		(net "M_G_CPU1_SA_CB<6>")
	)
	(segment
		(start 185.530998 -270.950944)
		(end 185.530998 -264.011156)
		(width 0.18288)
		(layer "In6.Cu")
		(net "M_G_CPU1_SA_CB<6>")
	)
	(segment
		(start 168.17467 -261.342632)
		(end 164.737796 -261.342632)
		(width 0.18288)
		(layer "In6.Cu")
		(net "M_G_CPU1_SA_CB<6>")
	)
	(segment
		(start 168.324276 -261.492238)
		(end 168.17467 -261.342632)
		(width 0.18288)
		(layer "In6.Cu")
		(net "M_G_CPU1_SA_CB<6>")
	)
	(segment
		(start 180.99786 -262.495538)
		(end 179.887626 -262.495538)
		(width 0.18288)
		(layer "In6.Cu")
		(net "M_G_CPU1_SA_CB<6>")
	)
	(segment
		(start 162.864292 -260.78688)
		(end 162.635692 -261.01548)
		(width 0.18288)
		(layer "In6.Cu")
		(net "M_G_CPU1_SA_CB<6>")
	)
	(arc
		(start 132.142992 -261.5692)
		(mid 131.955794 -261.619343)
		(end 131.768596 -261.5692)
		(width 0.088646)
		(layer "In6.Cu")
		(net "M_G_CPU1_SA_CB<6>")
	)
	(arc
		(start 130.814064 -261.560564)
		(mid 130.537589 -261.493244)
		(end 130.263392 -261.5692)
		(width 0.088646)
		(layer "In6.Cu")
		(net "M_G_CPU1_SA_CB<6>")
	)
	(arc
		(start 136.841992 -261.5692)
		(mid 136.654794 -261.619343)
		(end 136.467596 -261.5692)
		(width 0.088646)
		(layer "In6.Cu")
		(net "M_G_CPU1_SA_CB<6>")
	)
	(arc
		(start 134.962392 -261.5692)
		(mid 134.775194 -261.619343)
		(end 134.587996 -261.5692)
		(width 0.088646)
		(layer "In6.Cu")
		(net "M_G_CPU1_SA_CB<6>")
	)
	(arc
		(start 138.721592 -261.5692)
		(mid 138.534394 -261.619343)
		(end 138.347196 -261.5692)
		(width 0.088646)
		(layer "In6.Cu")
		(net "M_G_CPU1_SA_CB<6>")
	)
	(arc
		(start 130.263392 -261.5692)
		(mid 130.076194 -261.619343)
		(end 129.888996 -261.5692)
		(width 0.088646)
		(layer "In6.Cu")
		(net "M_G_CPU1_SA_CB<6>")
	)
	(arc
		(start 133.082792 -261.5692)
		(mid 132.895594 -261.619343)
		(end 132.708396 -261.5692)
		(width 0.088646)
		(layer "In6.Cu")
		(net "M_G_CPU1_SA_CB<6>")
	)
	(arc
		(start 135.902192 -261.5692)
		(mid 135.714994 -261.619343)
		(end 135.527796 -261.5692)
		(width 0.088646)
		(layer "In6.Cu")
		(net "M_G_CPU1_SA_CB<6>")
	)
	(arc
		(start 136.467596 -261.5692)
		(mid 136.184894 -261.493424)
		(end 135.902192 -261.5692)
		(width 0.088646)
		(layer "In6.Cu")
		(net "M_G_CPU1_SA_CB<6>")
	)
	(arc
		(start 134.022592 -261.5692)
		(mid 133.835394 -261.619343)
		(end 133.648196 -261.5692)
		(width 0.088646)
		(layer "In6.Cu")
		(net "M_G_CPU1_SA_CB<6>")
	)
	(arc
		(start 137.407396 -261.5692)
		(mid 137.124694 -261.493424)
		(end 136.841992 -261.5692)
		(width 0.088646)
		(layer "In6.Cu")
		(net "M_G_CPU1_SA_CB<6>")
	)
	(arc
		(start 131.203192 -261.5692)
		(mid 131.015994 -261.619343)
		(end 130.828796 -261.5692)
		(width 0.088646)
		(layer "In6.Cu")
		(net "M_G_CPU1_SA_CB<6>")
	)
	(arc
		(start 135.527796 -261.5692)
		(mid 135.245094 -261.493424)
		(end 134.962392 -261.5692)
		(width 0.088646)
		(layer "In6.Cu")
		(net "M_G_CPU1_SA_CB<6>")
	)
	(arc
		(start 138.909044 -261.244842)
		(mid 138.861365 -261.427742)
		(end 138.730482 -261.56412)
		(width 0.088646)
		(layer "In6.Cu")
		(net "M_G_CPU1_SA_CB<6>")
	)
	(arc
		(start 138.347196 -261.5692)
		(mid 138.064494 -261.493424)
		(end 137.781792 -261.5692)
		(width 0.088646)
		(layer "In6.Cu")
		(net "M_G_CPU1_SA_CB<6>")
	)
	(arc
		(start 139.474956 -260.67893)
		(mid 139.328191 -260.69831)
		(end 139.191492 -260.75513)
		(width 0.088646)
		(layer "In6.Cu")
		(net "M_G_CPU1_SA_CB<6>")
	)
	(arc
		(start 133.633464 -261.560564)
		(mid 133.356989 -261.493244)
		(end 133.082792 -261.5692)
		(width 0.088646)
		(layer "In6.Cu")
		(net "M_G_CPU1_SA_CB<6>")
	)
	(arc
		(start 137.781792 -261.5692)
		(mid 137.594594 -261.619343)
		(end 137.407396 -261.5692)
		(width 0.088646)
		(layer "In6.Cu")
		(net "M_G_CPU1_SA_CB<6>")
	)
	(arc
		(start 129.323592 -261.5692)
		(mid 128.980937 -261.794827)
		(end 128.666748 -262.058658)
		(width 0.088646)
		(layer "In6.Cu")
		(net "M_G_CPU1_SA_CB<6>")
	)
	(arc
		(start 131.753864 -261.560564)
		(mid 131.477389 -261.493244)
		(end 131.203192 -261.5692)
		(width 0.088646)
		(layer "In6.Cu")
		(net "M_G_CPU1_SA_CB<6>")
	)
	(arc
		(start 129.874264 -261.560564)
		(mid 129.597789 -261.493244)
		(end 129.323592 -261.5692)
		(width 0.088646)
		(layer "In6.Cu")
		(net "M_G_CPU1_SA_CB<6>")
	)
	(arc
		(start 134.573264 -261.560564)
		(mid 134.296789 -261.493244)
		(end 134.022592 -261.5692)
		(width 0.088646)
		(layer "In6.Cu")
		(net "M_G_CPU1_SA_CB<6>")
	)
	(arc
		(start 139.191492 -260.75513)
		(mid 138.989206 -260.954111)
		(end 138.909044 -261.2263)
		(width 0.088646)
		(layer "In6.Cu")
		(net "M_G_CPU1_SA_CB<6>")
	)
	(arc
		(start 132.708396 -261.5692)
		(mid 132.425694 -261.493424)
		(end 132.142992 -261.5692)
		(width 0.088646)
		(layer "In6.Cu")
		(net "M_G_CPU1_SA_CB<6>")
	)
	(segment
		(start 127.256794 -261.244588)
		(end 127.256794 -261.244842)
		(width 0.20066)
		(layer "F.Cu")
		(net "M_G_CPU1_SA_CB<5>")
	)
	(segment
		(start 190.509144 -271.266666)
		(end 188.988446 -271.266666)
		(width 0.20066)
		(layer "F.Cu")
		(net "M_G_CPU1_SA_CB<5>")
	)
	(segment
		(start 191.421004 -270.959834)
		(end 191.421004 -271.327372)
		(width 0.20066)
		(layer "F.Cu")
		(net "M_G_CPU1_SA_CB<5>")
	)
	(segment
		(start 194.241166 -270.841724)
		(end 191.930782 -270.841724)
		(width 0.1016)
		(layer "F.Cu")
		(net "M_G_CPU1_SA_CB<5>")
	)
	(segment
		(start 196.531992 -271.26692)
		(end 194.901312 -271.26692)
		(width 0.20066)
		(layer "F.Cu")
		(net "M_G_CPU1_SA_CB<5>")
	)
	(segment
		(start 194.901312 -271.26692)
		(end 194.476116 -270.841724)
		(width 0.20066)
		(layer "F.Cu")
		(net "M_G_CPU1_SA_CB<5>")
	)
	(segment
		(start 191.421004 -271.327372)
		(end 191.233044 -271.515332)
		(width 0.20066)
		(layer "F.Cu")
		(net "M_G_CPU1_SA_CB<5>")
	)
	(segment
		(start 191.233044 -271.515332)
		(end 190.75781 -271.515332)
		(width 0.20066)
		(layer "F.Cu")
		(net "M_G_CPU1_SA_CB<5>")
	)
	(segment
		(start 191.786256 -270.841724)
		(end 191.539114 -270.841724)
		(width 0.20066)
		(layer "F.Cu")
		(net "M_G_CPU1_SA_CB<5>")
	)
	(segment
		(start 190.75781 -271.515332)
		(end 190.509144 -271.266666)
		(width 0.20066)
		(layer "F.Cu")
		(net "M_G_CPU1_SA_CB<5>")
	)
	(segment
		(start 191.539114 -270.841724)
		(end 191.421004 -270.959834)
		(width 0.20066)
		(layer "F.Cu")
		(net "M_G_CPU1_SA_CB<5>")
	)
	(segment
		(start 127.257048 -261.244334)
		(end 127.256794 -261.244588)
		(width 0.20066)
		(layer "F.Cu")
		(net "M_G_CPU1_SA_CB<5>")
	)
	(segment
		(start 127.257048 -260.708902)
		(end 127.257048 -261.244334)
		(width 0.20066)
		(layer "F.Cu")
		(net "M_G_CPU1_SA_CB<5>")
	)
	(segment
		(start 191.930782 -270.841724)
		(end 191.786256 -270.841724)
		(width 0.101854)
		(layer "F.Cu")
		(net "M_G_CPU1_SA_CB<5>")
	)
	(segment
		(start 194.277742 -270.841724)
		(end 194.241166 -270.841724)
		(width 0.101854)
		(layer "F.Cu")
		(net "M_G_CPU1_SA_CB<5>")
	)
	(segment
		(start 196.532246 -271.266666)
		(end 196.531992 -271.26692)
		(width 0.20066)
		(layer "F.Cu")
		(net "M_G_CPU1_SA_CB<5>")
	)
	(segment
		(start 194.476116 -270.841724)
		(end 194.277742 -270.841724)
		(width 0.20066)
		(layer "F.Cu")
		(net "M_G_CPU1_SA_CB<5>")
	)
	(segment
		(start 188.988446 -271.266666)
		(end 187.883546 -271.266666)
		(width 0.20066)
		(layer "F.Cu")
		(net "M_G_CPU1_SA_CB<5>")
	)
	(segment
		(start 186.70016 -268.997176)
		(end 186.88304 -268.814296)
		(width 0.18288)
		(layer "In6.Cu")
		(net "M_G_CPU1_SA_CB<5>")
	)
	(segment
		(start 186.88304 -268.486636)
		(end 186.70016 -268.303756)
		(width 0.18288)
		(layer "In6.Cu")
		(net "M_G_CPU1_SA_CB<5>")
	)
	(segment
		(start 186.040776 -270.419576)
		(end 186.040776 -269.180056)
		(width 0.18288)
		(layer "In6.Cu")
		(net "M_G_CPU1_SA_CB<5>")
	)
	(segment
		(start 186.040776 -266.449556)
		(end 186.040776 -262.68807)
		(width 0.18288)
		(layer "In6.Cu")
		(net "M_G_CPU1_SA_CB<5>")
	)
	(segment
		(start 159.44723 -260.782562)
		(end 159.26435 -260.599682)
		(width 0.18288)
		(layer "In6.Cu")
		(net "M_G_CPU1_SA_CB<5>")
	)
	(segment
		(start 179.791106 -261.347458)
		(end 179.405026 -261.733538)
		(width 0.18288)
		(layer "In6.Cu")
		(net "M_G_CPU1_SA_CB<5>")
	)
	(segment
		(start 142.983204 -260.007862)
		(end 139.70635 -260.007862)
		(width 0.18288)
		(layer "In6.Cu")
		(net "M_G_CPU1_SA_CB<5>")
	)
	(segment
		(start 177.488596 -260.642354)
		(end 176.218342 -260.642354)
		(width 0.18288)
		(layer "In6.Cu")
		(net "M_G_CPU1_SA_CB<5>")
	)
	(segment
		(start 127.635254 -261.310628)
		(end 127.569468 -261.244842)
		(width 0.088646)
		(layer "In6.Cu")
		(net "M_G_CPU1_SA_CB<5>")
	)
	(segment
		(start 186.675014 -266.632436)
		(end 186.223656 -266.632436)
		(width 0.18288)
		(layer "In6.Cu")
		(net "M_G_CPU1_SA_CB<5>")
	)
	(segment
		(start 134.587996 -260.920484)
		(end 134.573264 -260.92912)
		(width 0.088646)
		(layer "In6.Cu")
		(net "M_G_CPU1_SA_CB<5>")
	)
	(segment
		(start 132.708396 -260.920484)
		(end 132.693664 -260.92912)
		(width 0.088646)
		(layer "In6.Cu")
		(net "M_G_CPU1_SA_CB<5>")
	)
	(segment
		(start 151.263604 -260.479794)
		(end 151.262842 -260.480556)
		(width 0.18288)
		(layer "In6.Cu")
		(net "M_G_CPU1_SA_CB<5>")
	)
	(segment
		(start 128.949196 -260.920484)
		(end 128.940306 -260.925564)
		(width 0.088646)
		(layer "In6.Cu")
		(net "M_G_CPU1_SA_CB<5>")
	)
	(segment
		(start 186.040776 -267.508736)
		(end 186.223656 -267.325856)
		(width 0.18288)
		(layer "In6.Cu")
		(net "M_G_CPU1_SA_CB<5>")
	)
	(segment
		(start 158.38805 -260.782562)
		(end 157.655768 -260.782562)
		(width 0.18288)
		(layer "In6.Cu")
		(net "M_G_CPU1_SA_CB<5>")
	)
	(segment
		(start 157.353 -260.479794)
		(end 151.263604 -260.479794)
		(width 0.18288)
		(layer "In6.Cu")
		(net "M_G_CPU1_SA_CB<5>")
	)
	(segment
		(start 145.359882 -260.480556)
		(end 142.983204 -260.007862)
		(width 0.18288)
		(layer "In6.Cu")
		(net "M_G_CPU1_SA_CB<5>")
	)
	(segment
		(start 159.26435 -260.186678)
		(end 159.08147 -260.003798)
		(width 0.18288)
		(layer "In6.Cu")
		(net "M_G_CPU1_SA_CB<5>")
	)
	(segment
		(start 127.914146 -261.7343)
		(end 127.90805 -261.730744)
		(width 0.088646)
		(layer "In6.Cu")
		(net "M_G_CPU1_SA_CB<5>")
	)
	(segment
		(start 173.245526 -260.642354)
		(end 164.521642 -260.642354)
		(width 0.18288)
		(layer "In6.Cu")
		(net "M_G_CPU1_SA_CB<5>")
	)
	(segment
		(start 128.761744 -261.244842)
		(end 128.761744 -261.260336)
		(width 0.088646)
		(layer "In6.Cu")
		(net "M_G_CPU1_SA_CB<5>")
	)
	(segment
		(start 185.594244 -262.241538)
		(end 184.129426 -262.241538)
		(width 0.18288)
		(layer "In6.Cu")
		(net "M_G_CPU1_SA_CB<5>")
	)
	(segment
		(start 151.262842 -260.480556)
		(end 145.359882 -260.480556)
		(width 0.18288)
		(layer "In6.Cu")
		(net "M_G_CPU1_SA_CB<5>")
	)
	(segment
		(start 158.75381 -260.003798)
		(end 158.57093 -260.186678)
		(width 0.18288)
		(layer "In6.Cu")
		(net "M_G_CPU1_SA_CB<5>")
	)
	(segment
		(start 157.655768 -260.782562)
		(end 157.353 -260.479794)
		(width 0.18288)
		(layer "In6.Cu")
		(net "M_G_CPU1_SA_CB<5>")
	)
	(segment
		(start 184.129426 -262.241538)
		(end 183.235346 -261.347458)
		(width 0.18288)
		(layer "In6.Cu")
		(net "M_G_CPU1_SA_CB<5>")
	)
	(segment
		(start 186.040776 -269.180056)
		(end 186.223656 -268.997176)
		(width 0.18288)
		(layer "In6.Cu")
		(net "M_G_CPU1_SA_CB<5>")
	)
	(segment
		(start 186.675014 -267.325856)
		(end 186.857894 -267.142976)
		(width 0.18288)
		(layer "In6.Cu")
		(net "M_G_CPU1_SA_CB<5>")
	)
	(segment
		(start 186.040776 -262.68807)
		(end 185.594244 -262.241538)
		(width 0.18288)
		(layer "In6.Cu")
		(net "M_G_CPU1_SA_CB<5>")
	)
	(segment
		(start 131.768596 -260.920484)
		(end 131.753864 -260.92912)
		(width 0.088646)
		(layer "In6.Cu")
		(net "M_G_CPU1_SA_CB<5>")
	)
	(segment
		(start 186.223656 -266.632436)
		(end 186.040776 -266.449556)
		(width 0.18288)
		(layer "In6.Cu")
		(net "M_G_CPU1_SA_CB<5>")
	)
	(segment
		(start 174.186342 -259.701538)
		(end 173.245526 -260.642354)
		(width 0.18288)
		(layer "In6.Cu")
		(net "M_G_CPU1_SA_CB<5>")
	)
	(segment
		(start 159.08147 -260.003798)
		(end 158.75381 -260.003798)
		(width 0.18288)
		(layer "In6.Cu")
		(net "M_G_CPU1_SA_CB<5>")
	)
	(segment
		(start 127.928878 -261.742936)
		(end 127.914146 -261.7343)
		(width 0.088646)
		(layer "In6.Cu")
		(net "M_G_CPU1_SA_CB<5>")
	)
	(segment
		(start 186.40552 -270.78432)
		(end 186.040776 -270.419576)
		(width 0.18288)
		(layer "In6.Cu")
		(net "M_G_CPU1_SA_CB<5>")
	)
	(segment
		(start 160.836102 -260.114796)
		(end 160.168336 -260.782562)
		(width 0.18288)
		(layer "In6.Cu")
		(net "M_G_CPU1_SA_CB<5>")
	)
	(segment
		(start 186.223656 -267.325856)
		(end 186.675014 -267.325856)
		(width 0.18288)
		(layer "In6.Cu")
		(net "M_G_CPU1_SA_CB<5>")
	)
	(segment
		(start 179.405026 -261.733538)
		(end 178.57978 -261.733538)
		(width 0.18288)
		(layer "In6.Cu")
		(net "M_G_CPU1_SA_CB<5>")
	)
	(segment
		(start 160.168336 -260.782562)
		(end 159.44723 -260.782562)
		(width 0.18288)
		(layer "In6.Cu")
		(net "M_G_CPU1_SA_CB<5>")
	)
	(segment
		(start 139.078462 -260.007862)
		(end 139.04087 -260.045454)
		(width 0.088646)
		(layer "In6.Cu")
		(net "M_G_CPU1_SA_CB<5>")
	)
	(segment
		(start 187.4012 -270.78432)
		(end 186.40552 -270.78432)
		(width 0.18288)
		(layer "In6.Cu")
		(net "M_G_CPU1_SA_CB<5>")
	)
	(segment
		(start 163.994084 -260.114796)
		(end 160.836102 -260.114796)
		(width 0.18288)
		(layer "In6.Cu")
		(net "M_G_CPU1_SA_CB<5>")
	)
	(segment
		(start 183.235346 -261.347458)
		(end 179.791106 -261.347458)
		(width 0.18288)
		(layer "In6.Cu")
		(net "M_G_CPU1_SA_CB<5>")
	)
	(segment
		(start 159.26435 -260.599682)
		(end 159.26435 -260.186678)
		(width 0.18288)
		(layer "In6.Cu")
		(net "M_G_CPU1_SA_CB<5>")
	)
	(segment
		(start 129.888996 -260.920484)
		(end 129.874264 -260.92912)
		(width 0.088646)
		(layer "In6.Cu")
		(net "M_G_CPU1_SA_CB<5>")
	)
	(segment
		(start 164.521642 -260.642354)
		(end 163.994084 -260.114796)
		(width 0.18288)
		(layer "In6.Cu")
		(net "M_G_CPU1_SA_CB<5>")
	)
	(segment
		(start 186.88304 -268.814296)
		(end 186.88304 -268.486636)
		(width 0.18288)
		(layer "In6.Cu")
		(net "M_G_CPU1_SA_CB<5>")
	)
	(segment
		(start 178.57978 -261.733538)
		(end 177.488596 -260.642354)
		(width 0.18288)
		(layer "In6.Cu")
		(net "M_G_CPU1_SA_CB<5>")
	)
	(segment
		(start 186.857894 -266.815316)
		(end 186.675014 -266.632436)
		(width 0.18288)
		(layer "In6.Cu")
		(net "M_G_CPU1_SA_CB<5>")
	)
	(segment
		(start 186.223656 -268.997176)
		(end 186.70016 -268.997176)
		(width 0.18288)
		(layer "In6.Cu")
		(net "M_G_CPU1_SA_CB<5>")
	)
	(segment
		(start 186.223656 -268.303756)
		(end 186.040776 -268.120876)
		(width 0.18288)
		(layer "In6.Cu")
		(net "M_G_CPU1_SA_CB<5>")
	)
	(segment
		(start 127.569468 -261.244842)
		(end 127.256794 -261.244842)
		(width 0.088646)
		(layer "In6.Cu")
		(net "M_G_CPU1_SA_CB<5>")
	)
	(segment
		(start 186.70016 -268.303756)
		(end 186.223656 -268.303756)
		(width 0.18288)
		(layer "In6.Cu")
		(net "M_G_CPU1_SA_CB<5>")
	)
	(segment
		(start 130.828796 -260.920484)
		(end 130.814064 -260.92912)
		(width 0.088646)
		(layer "In6.Cu")
		(net "M_G_CPU1_SA_CB<5>")
	)
	(segment
		(start 186.857894 -267.142976)
		(end 186.857894 -266.815316)
		(width 0.18288)
		(layer "In6.Cu")
		(net "M_G_CPU1_SA_CB<5>")
	)
	(segment
		(start 158.57093 -260.599682)
		(end 158.38805 -260.782562)
		(width 0.18288)
		(layer "In6.Cu")
		(net "M_G_CPU1_SA_CB<5>")
	)
	(segment
		(start 186.040776 -268.120876)
		(end 186.040776 -267.508736)
		(width 0.18288)
		(layer "In6.Cu")
		(net "M_G_CPU1_SA_CB<5>")
	)
	(segment
		(start 187.883546 -271.266666)
		(end 187.4012 -270.78432)
		(width 0.18288)
		(layer "In6.Cu")
		(net "M_G_CPU1_SA_CB<5>")
	)
	(segment
		(start 138.629644 -260.430772)
		(end 138.629644 -260.449314)
		(width 0.088646)
		(layer "In6.Cu")
		(net "M_G_CPU1_SA_CB<5>")
	)
	(segment
		(start 158.57093 -260.186678)
		(end 158.57093 -260.599682)
		(width 0.18288)
		(layer "In6.Cu")
		(net "M_G_CPU1_SA_CB<5>")
	)
	(segment
		(start 176.218342 -260.642354)
		(end 175.277526 -259.701538)
		(width 0.18288)
		(layer "In6.Cu")
		(net "M_G_CPU1_SA_CB<5>")
	)
	(segment
		(start 139.70635 -260.007862)
		(end 139.078462 -260.007862)
		(width 0.088646)
		(layer "In6.Cu")
		(net "M_G_CPU1_SA_CB<5>")
	)
	(segment
		(start 175.277526 -259.701538)
		(end 174.186342 -259.701538)
		(width 0.18288)
		(layer "In6.Cu")
		(net "M_G_CPU1_SA_CB<5>")
	)
	(arc
		(start 134.962392 -260.920484)
		(mid 134.775194 -260.870341)
		(end 134.587996 -260.920484)
		(width 0.088646)
		(layer "In6.Cu")
		(net "M_G_CPU1_SA_CB<5>")
	)
	(arc
		(start 134.573264 -260.92912)
		(mid 134.296823 -260.996286)
		(end 134.022592 -260.920484)
		(width 0.088646)
		(layer "In6.Cu")
		(net "M_G_CPU1_SA_CB<5>")
	)
	(arc
		(start 128.47955 -261.7343)
		(mid 128.205351 -261.810135)
		(end 127.928878 -261.742936)
		(width 0.088646)
		(layer "In6.Cu")
		(net "M_G_CPU1_SA_CB<5>")
	)
	(arc
		(start 132.693664 -260.92912)
		(mid 132.417223 -260.996286)
		(end 132.142992 -260.920484)
		(width 0.088646)
		(layer "In6.Cu")
		(net "M_G_CPU1_SA_CB<5>")
	)
	(arc
		(start 135.902192 -260.920484)
		(mid 135.714994 -260.870341)
		(end 135.527796 -260.920484)
		(width 0.088646)
		(layer "In6.Cu")
		(net "M_G_CPU1_SA_CB<5>")
	)
	(arc
		(start 129.323592 -260.920484)
		(mid 129.136394 -260.870341)
		(end 128.949196 -260.920484)
		(width 0.088646)
		(layer "In6.Cu")
		(net "M_G_CPU1_SA_CB<5>")
	)
	(arc
		(start 130.263392 -260.920484)
		(mid 130.076194 -260.870341)
		(end 129.888996 -260.920484)
		(width 0.088646)
		(layer "In6.Cu")
		(net "M_G_CPU1_SA_CB<5>")
	)
	(arc
		(start 138.629644 -260.449314)
		(mid 138.549482 -260.721503)
		(end 138.347196 -260.920484)
		(width 0.088646)
		(layer "In6.Cu")
		(net "M_G_CPU1_SA_CB<5>")
	)
	(arc
		(start 136.467596 -260.920484)
		(mid 136.184894 -260.996226)
		(end 135.902192 -260.920484)
		(width 0.088646)
		(layer "In6.Cu")
		(net "M_G_CPU1_SA_CB<5>")
	)
	(arc
		(start 127.90805 -261.730744)
		(mid 127.722595 -261.552549)
		(end 127.635254 -261.310628)
		(width 0.088646)
		(layer "In6.Cu")
		(net "M_G_CPU1_SA_CB<5>")
	)
	(arc
		(start 133.648196 -260.920484)
		(mid 133.365494 -260.996226)
		(end 133.082792 -260.920484)
		(width 0.088646)
		(layer "In6.Cu")
		(net "M_G_CPU1_SA_CB<5>")
	)
	(arc
		(start 135.527796 -260.920484)
		(mid 135.245094 -260.996226)
		(end 134.962392 -260.920484)
		(width 0.088646)
		(layer "In6.Cu")
		(net "M_G_CPU1_SA_CB<5>")
	)
	(arc
		(start 139.04087 -260.045454)
		(mid 138.91994 -260.06228)
		(end 138.808206 -260.111494)
		(width 0.088646)
		(layer "In6.Cu")
		(net "M_G_CPU1_SA_CB<5>")
	)
	(arc
		(start 128.761744 -261.260336)
		(mid 128.682374 -261.53407)
		(end 128.47955 -261.7343)
		(width 0.088646)
		(layer "In6.Cu")
		(net "M_G_CPU1_SA_CB<5>")
	)
	(arc
		(start 129.874264 -260.92912)
		(mid 129.597823 -260.996286)
		(end 129.323592 -260.920484)
		(width 0.088646)
		(layer "In6.Cu")
		(net "M_G_CPU1_SA_CB<5>")
	)
	(arc
		(start 137.407396 -260.920484)
		(mid 137.124694 -260.996226)
		(end 136.841992 -260.920484)
		(width 0.088646)
		(layer "In6.Cu")
		(net "M_G_CPU1_SA_CB<5>")
	)
	(arc
		(start 131.203192 -260.920484)
		(mid 131.015994 -260.870341)
		(end 130.828796 -260.920484)
		(width 0.088646)
		(layer "In6.Cu")
		(net "M_G_CPU1_SA_CB<5>")
	)
	(arc
		(start 132.142992 -260.920484)
		(mid 131.955794 -260.870341)
		(end 131.768596 -260.920484)
		(width 0.088646)
		(layer "In6.Cu")
		(net "M_G_CPU1_SA_CB<5>")
	)
	(arc
		(start 136.841992 -260.920484)
		(mid 136.654794 -260.870341)
		(end 136.467596 -260.920484)
		(width 0.088646)
		(layer "In6.Cu")
		(net "M_G_CPU1_SA_CB<5>")
	)
	(arc
		(start 134.022592 -260.920484)
		(mid 133.835394 -260.870341)
		(end 133.648196 -260.920484)
		(width 0.088646)
		(layer "In6.Cu")
		(net "M_G_CPU1_SA_CB<5>")
	)
	(arc
		(start 133.082792 -260.920484)
		(mid 132.895594 -260.870341)
		(end 132.708396 -260.920484)
		(width 0.088646)
		(layer "In6.Cu")
		(net "M_G_CPU1_SA_CB<5>")
	)
	(arc
		(start 138.347196 -260.920484)
		(mid 138.064494 -260.996226)
		(end 137.781792 -260.920484)
		(width 0.088646)
		(layer "In6.Cu")
		(net "M_G_CPU1_SA_CB<5>")
	)
	(arc
		(start 138.808206 -260.111494)
		(mid 138.677292 -260.247854)
		(end 138.629644 -260.430772)
		(width 0.088646)
		(layer "In6.Cu")
		(net "M_G_CPU1_SA_CB<5>")
	)
	(arc
		(start 128.940306 -260.925564)
		(mid 128.809392 -261.061924)
		(end 128.761744 -261.244842)
		(width 0.088646)
		(layer "In6.Cu")
		(net "M_G_CPU1_SA_CB<5>")
	)
	(arc
		(start 130.814064 -260.92912)
		(mid 130.537623 -260.996286)
		(end 130.263392 -260.920484)
		(width 0.088646)
		(layer "In6.Cu")
		(net "M_G_CPU1_SA_CB<5>")
	)
	(arc
		(start 131.753864 -260.92912)
		(mid 131.477423 -260.996286)
		(end 131.203192 -260.920484)
		(width 0.088646)
		(layer "In6.Cu")
		(net "M_G_CPU1_SA_CB<5>")
	)
	(arc
		(start 137.781792 -260.920484)
		(mid 137.594594 -260.870341)
		(end 137.407396 -260.920484)
		(width 0.088646)
		(layer "In6.Cu")
		(net "M_G_CPU1_SA_CB<5>")
	)
	(segment
		(start 190.75781 -273.215354)
		(end 190.509144 -272.966688)
		(width 0.20066)
		(layer "F.Cu")
		(net "M_G_CPU1_SA_CB<4>")
	)
	(segment
		(start 191.539114 -272.541746)
		(end 191.421004 -272.659856)
		(width 0.20066)
		(layer "F.Cu")
		(net "M_G_CPU1_SA_CB<4>")
	)
	(segment
		(start 191.930782 -272.541746)
		(end 191.786256 -272.541746)
		(width 0.101854)
		(layer "F.Cu")
		(net "M_G_CPU1_SA_CB<4>")
	)
	(segment
		(start 188.988446 -272.966688)
		(end 187.883546 -272.966688)
		(width 0.20066)
		(layer "F.Cu")
		(net "M_G_CPU1_SA_CB<4>")
	)
	(segment
		(start 194.277742 -272.541746)
		(end 194.241166 -272.541746)
		(width 0.101854)
		(layer "F.Cu")
		(net "M_G_CPU1_SA_CB<4>")
	)
	(segment
		(start 190.509144 -272.966688)
		(end 188.988446 -272.966688)
		(width 0.20066)
		(layer "F.Cu")
		(net "M_G_CPU1_SA_CB<4>")
	)
	(segment
		(start 191.786256 -272.541746)
		(end 191.539114 -272.541746)
		(width 0.20066)
		(layer "F.Cu")
		(net "M_G_CPU1_SA_CB<4>")
	)
	(segment
		(start 194.901312 -272.966942)
		(end 194.476116 -272.541746)
		(width 0.20066)
		(layer "F.Cu")
		(net "M_G_CPU1_SA_CB<4>")
	)
	(segment
		(start 126.786894 -261.522718)
		(end 126.787148 -261.522972)
		(width 0.20066)
		(layer "F.Cu")
		(net "M_G_CPU1_SA_CB<4>")
	)
	(segment
		(start 191.421004 -273.027394)
		(end 191.233044 -273.215354)
		(width 0.20066)
		(layer "F.Cu")
		(net "M_G_CPU1_SA_CB<4>")
	)
	(segment
		(start 194.241166 -272.541746)
		(end 191.930782 -272.541746)
		(width 0.1016)
		(layer "F.Cu")
		(net "M_G_CPU1_SA_CB<4>")
	)
	(segment
		(start 196.531992 -272.966942)
		(end 194.901312 -272.966942)
		(width 0.20066)
		(layer "F.Cu")
		(net "M_G_CPU1_SA_CB<4>")
	)
	(segment
		(start 194.476116 -272.541746)
		(end 194.277742 -272.541746)
		(width 0.20066)
		(layer "F.Cu")
		(net "M_G_CPU1_SA_CB<4>")
	)
	(segment
		(start 126.787148 -261.522972)
		(end 126.787148 -262.058658)
		(width 0.20066)
		(layer "F.Cu")
		(net "M_G_CPU1_SA_CB<4>")
	)
	(segment
		(start 191.421004 -272.659856)
		(end 191.421004 -273.027394)
		(width 0.20066)
		(layer "F.Cu")
		(net "M_G_CPU1_SA_CB<4>")
	)
	(segment
		(start 196.532246 -272.966688)
		(end 196.531992 -272.966942)
		(width 0.20066)
		(layer "F.Cu")
		(net "M_G_CPU1_SA_CB<4>")
	)
	(segment
		(start 191.233044 -273.215354)
		(end 190.75781 -273.215354)
		(width 0.20066)
		(layer "F.Cu")
		(net "M_G_CPU1_SA_CB<4>")
	)
	(segment
		(start 160.887156 -262.374888)
		(end 157.47238 -262.374888)
		(width 0.18288)
		(layer "In6.Cu")
		(net "M_G_CPU1_SA_CB<4>")
	)
	(segment
		(start 129.003552 -262.2931)
		(end 128.853946 -262.383016)
		(width 0.088646)
		(layer "In6.Cu")
		(net "M_G_CPU1_SA_CB<4>")
	)
	(segment
		(start 139.972542 -261.024624)
		(end 139.817094 -260.869176)
		(width 0.088646)
		(layer "In6.Cu")
		(net "M_G_CPU1_SA_CB<4>")
	)
	(segment
		(start 162.531806 -262.27913)
		(end 162.371786 -262.11911)
		(width 0.18288)
		(layer "In6.Cu")
		(net "M_G_CPU1_SA_CB<4>")
	)
	(segment
		(start 132.623306 -261.740396)
		(end 132.612892 -261.7343)
		(width 0.088646)
		(layer "In6.Cu")
		(net "M_G_CPU1_SA_CB<4>")
	)
	(segment
		(start 181.265322 -263.901174)
		(end 181.082442 -263.718294)
		(width 0.18288)
		(layer "In6.Cu")
		(net "M_G_CPU1_SA_CB<4>")
	)
	(segment
		(start 139.099544 -261.244842)
		(end 139.099544 -261.254748)
		(width 0.088646)
		(layer "In6.Cu")
		(net "M_G_CPU1_SA_CB<4>")
	)
	(segment
		(start 175.760126 -263.003538)
		(end 174.41418 -263.003538)
		(width 0.18288)
		(layer "In6.Cu")
		(net "M_G_CPU1_SA_CB<4>")
	)
	(segment
		(start 127.511048 -262.366252)
		(end 126.787148 -262.058658)
		(width 0.088646)
		(layer "In6.Cu")
		(net "M_G_CPU1_SA_CB<4>")
	)
	(segment
		(start 181.775862 -263.206484)
		(end 181.775862 -263.718294)
		(width 0.18288)
		(layer "In6.Cu")
		(net "M_G_CPU1_SA_CB<4>")
	)
	(segment
		(start 180.01996 -263.023604)
		(end 179.620672 -263.422892)
		(width 0.18288)
		(layer "In6.Cu")
		(net "M_G_CPU1_SA_CB<4>")
	)
	(segment
		(start 187.260484 -272.343626)
		(end 186.186572 -272.343626)
		(width 0.18288)
		(layer "In6.Cu")
		(net "M_G_CPU1_SA_CB<4>")
	)
	(segment
		(start 134.50316 -261.740396)
		(end 134.492746 -261.7343)
		(width 0.088646)
		(layer "In6.Cu")
		(net "M_G_CPU1_SA_CB<4>")
	)
	(segment
		(start 172.033946 -262.342376)
		(end 171.686982 -261.995412)
		(width 0.18288)
		(layer "In6.Cu")
		(net "M_G_CPU1_SA_CB<4>")
	)
	(segment
		(start 140.468604 -261.024624)
		(end 139.972542 -261.024624)
		(width 0.088646)
		(layer "In6.Cu")
		(net "M_G_CPU1_SA_CB<4>")
	)
	(segment
		(start 166.678356 -262.178038)
		(end 166.678356 -262.024876)
		(width 0.18288)
		(layer "In6.Cu")
		(net "M_G_CPU1_SA_CB<4>")
	)
	(segment
		(start 185.01995 -264.308336)
		(end 184.742582 -264.030968)
		(width 0.18288)
		(layer "In6.Cu")
		(net "M_G_CPU1_SA_CB<4>")
	)
	(segment
		(start 181.082442 -263.718294)
		(end 181.082442 -263.206484)
		(width 0.18288)
		(layer "In6.Cu")
		(net "M_G_CPU1_SA_CB<4>")
	)
	(segment
		(start 185.01995 -271.177004)
		(end 185.01995 -264.308336)
		(width 0.18288)
		(layer "In6.Cu")
		(net "M_G_CPU1_SA_CB<4>")
	)
	(segment
		(start 133.567678 -261.742936)
		(end 133.552946 -261.7343)
		(width 0.088646)
		(layer "In6.Cu")
		(net "M_G_CPU1_SA_CB<4>")
	)
	(segment
		(start 179.620672 -263.422892)
		(end 178.57978 -263.422892)
		(width 0.18288)
		(layer "In6.Cu")
		(net "M_G_CPU1_SA_CB<4>")
	)
	(segment
		(start 181.082442 -263.206484)
		(end 180.899562 -263.023604)
		(width 0.18288)
		(layer "In6.Cu")
		(net "M_G_CPU1_SA_CB<4>")
	)
	(segment
		(start 173.753018 -262.342376)
		(end 172.033946 -262.342376)
		(width 0.18288)
		(layer "In6.Cu")
		(net "M_G_CPU1_SA_CB<4>")
	)
	(segment
		(start 184.03951 -264.030968)
		(end 183.032146 -263.023604)
		(width 0.18288)
		(layer "In6.Cu")
		(net "M_G_CPU1_SA_CB<4>")
	)
	(segment
		(start 168.285414 -261.995412)
		(end 167.919908 -262.360918)
		(width 0.18288)
		(layer "In6.Cu")
		(net "M_G_CPU1_SA_CB<4>")
	)
	(segment
		(start 174.41418 -263.003538)
		(end 173.753018 -262.342376)
		(width 0.18288)
		(layer "In6.Cu")
		(net "M_G_CPU1_SA_CB<4>")
	)
	(segment
		(start 166.495476 -261.841996)
		(end 166.167816 -261.841996)
		(width 0.18288)
		(layer "In6.Cu")
		(net "M_G_CPU1_SA_CB<4>")
	)
	(segment
		(start 139.286996 -260.920484)
		(end 139.278106 -260.925564)
		(width 0.088646)
		(layer "In6.Cu")
		(net "M_G_CPU1_SA_CB<4>")
	)
	(segment
		(start 183.032146 -263.023604)
		(end 181.958742 -263.023604)
		(width 0.18288)
		(layer "In6.Cu")
		(net "M_G_CPU1_SA_CB<4>")
	)
	(segment
		(start 166.861236 -262.360918)
		(end 166.678356 -262.178038)
		(width 0.18288)
		(layer "In6.Cu")
		(net "M_G_CPU1_SA_CB<4>")
	)
	(segment
		(start 164.699696 -262.360918)
		(end 164.48405 -262.145272)
		(width 0.18288)
		(layer "In6.Cu")
		(net "M_G_CPU1_SA_CB<4>")
	)
	(segment
		(start 142.988792 -261.024624)
		(end 140.468604 -261.024624)
		(width 0.18288)
		(layer "In6.Cu")
		(net "M_G_CPU1_SA_CB<4>")
	)
	(segment
		(start 163.463732 -262.145272)
		(end 163.303712 -262.305292)
		(width 0.18288)
		(layer "In6.Cu")
		(net "M_G_CPU1_SA_CB<4>")
	)
	(segment
		(start 163.303712 -262.305292)
		(end 163.303712 -262.69569)
		(width 0.18288)
		(layer "In6.Cu")
		(net "M_G_CPU1_SA_CB<4>")
	)
	(segment
		(start 130.748278 -261.742936)
		(end 130.733546 -261.7343)
		(width 0.088646)
		(layer "In6.Cu")
		(net "M_G_CPU1_SA_CB<4>")
	)
	(segment
		(start 129.808478 -261.742936)
		(end 129.793746 -261.7343)
		(width 0.088646)
		(layer "In6.Cu")
		(net "M_G_CPU1_SA_CB<4>")
	)
	(segment
		(start 184.742582 -264.030968)
		(end 184.03951 -264.030968)
		(width 0.18288)
		(layer "In6.Cu")
		(net "M_G_CPU1_SA_CB<4>")
	)
	(segment
		(start 165.984936 -262.024876)
		(end 165.984936 -262.178038)
		(width 0.18288)
		(layer "In6.Cu")
		(net "M_G_CPU1_SA_CB<4>")
	)
	(segment
		(start 187.883546 -272.966688)
		(end 187.260484 -272.343626)
		(width 0.18288)
		(layer "In6.Cu")
		(net "M_G_CPU1_SA_CB<4>")
	)
	(segment
		(start 131.68376 -261.740396)
		(end 131.673346 -261.7343)
		(width 0.088646)
		(layer "In6.Cu")
		(net "M_G_CPU1_SA_CB<4>")
	)
	(segment
		(start 162.371786 -262.11911)
		(end 161.142934 -262.11911)
		(width 0.18288)
		(layer "In6.Cu")
		(net "M_G_CPU1_SA_CB<4>")
	)
	(segment
		(start 162.531806 -262.69569)
		(end 162.531806 -262.27913)
		(width 0.18288)
		(layer "In6.Cu")
		(net "M_G_CPU1_SA_CB<4>")
	)
	(segment
		(start 145.287492 -261.481824)
		(end 142.988792 -261.024624)
		(width 0.18288)
		(layer "In6.Cu")
		(net "M_G_CPU1_SA_CB<4>")
	)
	(segment
		(start 127.53975 -262.383016)
		(end 127.511048 -262.366252)
		(width 0.088646)
		(layer "In6.Cu")
		(net "M_G_CPU1_SA_CB<4>")
	)
	(segment
		(start 186.186572 -272.343626)
		(end 185.01995 -271.177004)
		(width 0.18288)
		(layer "In6.Cu")
		(net "M_G_CPU1_SA_CB<4>")
	)
	(segment
		(start 165.802056 -262.360918)
		(end 164.699696 -262.360918)
		(width 0.18288)
		(layer "In6.Cu")
		(net "M_G_CPU1_SA_CB<4>")
	)
	(segment
		(start 181.592982 -263.901174)
		(end 181.265322 -263.901174)
		(width 0.18288)
		(layer "In6.Cu")
		(net "M_G_CPU1_SA_CB<4>")
	)
	(segment
		(start 166.167816 -261.841996)
		(end 165.984936 -262.024876)
		(width 0.18288)
		(layer "In6.Cu")
		(net "M_G_CPU1_SA_CB<4>")
	)
	(segment
		(start 171.686982 -261.995412)
		(end 168.285414 -261.995412)
		(width 0.18288)
		(layer "In6.Cu")
		(net "M_G_CPU1_SA_CB<4>")
	)
	(segment
		(start 162.691826 -262.85571)
		(end 162.531806 -262.69569)
		(width 0.18288)
		(layer "In6.Cu")
		(net "M_G_CPU1_SA_CB<4>")
	)
	(segment
		(start 161.142934 -262.11911)
		(end 160.887156 -262.374888)
		(width 0.18288)
		(layer "In6.Cu")
		(net "M_G_CPU1_SA_CB<4>")
	)
	(segment
		(start 178.57978 -263.422892)
		(end 177.499264 -262.342376)
		(width 0.18288)
		(layer "In6.Cu")
		(net "M_G_CPU1_SA_CB<4>")
	)
	(segment
		(start 139.817094 -260.869176)
		(end 139.474956 -260.869176)
		(width 0.088646)
		(layer "In6.Cu")
		(net "M_G_CPU1_SA_CB<4>")
	)
	(segment
		(start 127.928878 -262.37438)
		(end 127.914146 -262.383016)
		(width 0.088646)
		(layer "In6.Cu")
		(net "M_G_CPU1_SA_CB<4>")
	)
	(segment
		(start 176.421288 -262.342376)
		(end 175.760126 -263.003538)
		(width 0.18288)
		(layer "In6.Cu")
		(net "M_G_CPU1_SA_CB<4>")
	)
	(segment
		(start 177.499264 -262.342376)
		(end 176.421288 -262.342376)
		(width 0.18288)
		(layer "In6.Cu")
		(net "M_G_CPU1_SA_CB<4>")
	)
	(segment
		(start 180.899562 -263.023604)
		(end 180.01996 -263.023604)
		(width 0.18288)
		(layer "In6.Cu")
		(net "M_G_CPU1_SA_CB<4>")
	)
	(segment
		(start 129.1844 -262.047482)
		(end 129.003552 -262.2931)
		(width 0.088646)
		(layer "In6.Cu")
		(net "M_G_CPU1_SA_CB<4>")
	)
	(segment
		(start 163.143692 -262.85571)
		(end 162.691826 -262.85571)
		(width 0.18288)
		(layer "In6.Cu")
		(net "M_G_CPU1_SA_CB<4>")
	)
	(segment
		(start 164.48405 -262.145272)
		(end 163.463732 -262.145272)
		(width 0.18288)
		(layer "In6.Cu")
		(net "M_G_CPU1_SA_CB<4>")
	)
	(segment
		(start 157.47238 -262.374888)
		(end 156.579316 -261.481824)
		(width 0.18288)
		(layer "In6.Cu")
		(net "M_G_CPU1_SA_CB<4>")
	)
	(segment
		(start 163.303712 -262.69569)
		(end 163.143692 -262.85571)
		(width 0.18288)
		(layer "In6.Cu")
		(net "M_G_CPU1_SA_CB<4>")
	)
	(segment
		(start 165.984936 -262.178038)
		(end 165.802056 -262.360918)
		(width 0.18288)
		(layer "In6.Cu")
		(net "M_G_CPU1_SA_CB<4>")
	)
	(segment
		(start 181.958742 -263.023604)
		(end 181.775862 -263.206484)
		(width 0.18288)
		(layer "In6.Cu")
		(net "M_G_CPU1_SA_CB<4>")
	)
	(segment
		(start 166.678356 -262.024876)
		(end 166.495476 -261.841996)
		(width 0.18288)
		(layer "In6.Cu")
		(net "M_G_CPU1_SA_CB<4>")
	)
	(segment
		(start 156.579316 -261.481824)
		(end 145.287492 -261.481824)
		(width 0.18288)
		(layer "In6.Cu")
		(net "M_G_CPU1_SA_CB<4>")
	)
	(segment
		(start 167.919908 -262.360918)
		(end 166.861236 -262.360918)
		(width 0.18288)
		(layer "In6.Cu")
		(net "M_G_CPU1_SA_CB<4>")
	)
	(segment
		(start 181.775862 -263.718294)
		(end 181.592982 -263.901174)
		(width 0.18288)
		(layer "In6.Cu")
		(net "M_G_CPU1_SA_CB<4>")
	)
	(segment
		(start 129.27838 -261.877556)
		(end 129.1844 -262.047482)
		(width 0.088646)
		(layer "In6.Cu")
		(net "M_G_CPU1_SA_CB<4>")
	)
	(arc
		(start 134.11835 -261.7343)
		(mid 133.844151 -261.810135)
		(end 133.567678 -261.742936)
		(width 0.088646)
		(layer "In6.Cu")
		(net "M_G_CPU1_SA_CB<4>")
	)
	(arc
		(start 128.47955 -262.383016)
		(mid 128.205351 -262.307181)
		(end 127.928878 -262.37438)
		(width 0.088646)
		(layer "In6.Cu")
		(net "M_G_CPU1_SA_CB<4>")
	)
	(arc
		(start 131.29895 -261.7343)
		(mid 131.024751 -261.810135)
		(end 130.748278 -261.742936)
		(width 0.088646)
		(layer "In6.Cu")
		(net "M_G_CPU1_SA_CB<4>")
	)
	(arc
		(start 136.372092 -261.7343)
		(mid 136.184894 -261.684157)
		(end 135.997696 -261.7343)
		(width 0.088646)
		(layer "In6.Cu")
		(net "M_G_CPU1_SA_CB<4>")
	)
	(arc
		(start 133.552946 -261.7343)
		(mid 133.365748 -261.684157)
		(end 133.17855 -261.7343)
		(width 0.088646)
		(layer "In6.Cu")
		(net "M_G_CPU1_SA_CB<4>")
	)
	(arc
		(start 130.733546 -261.7343)
		(mid 130.546348 -261.684157)
		(end 130.35915 -261.7343)
		(width 0.088646)
		(layer "In6.Cu")
		(net "M_G_CPU1_SA_CB<4>")
	)
	(arc
		(start 135.997696 -261.7343)
		(mid 135.714994 -261.810076)
		(end 135.432292 -261.7343)
		(width 0.088646)
		(layer "In6.Cu")
		(net "M_G_CPU1_SA_CB<4>")
	)
	(arc
		(start 128.853946 -262.383016)
		(mid 128.666748 -262.433159)
		(end 128.47955 -262.383016)
		(width 0.088646)
		(layer "In6.Cu")
		(net "M_G_CPU1_SA_CB<4>")
	)
	(arc
		(start 139.099544 -261.254748)
		(mid 139.021433 -261.531697)
		(end 138.817096 -261.7343)
		(width 0.088646)
		(layer "In6.Cu")
		(net "M_G_CPU1_SA_CB<4>")
	)
	(arc
		(start 137.311892 -261.7343)
		(mid 137.124694 -261.684157)
		(end 136.937496 -261.7343)
		(width 0.088646)
		(layer "In6.Cu")
		(net "M_G_CPU1_SA_CB<4>")
	)
	(arc
		(start 139.474956 -260.869176)
		(mid 139.377576 -260.882386)
		(end 139.286996 -260.920484)
		(width 0.088646)
		(layer "In6.Cu")
		(net "M_G_CPU1_SA_CB<4>")
	)
	(arc
		(start 132.612892 -261.7343)
		(mid 132.425694 -261.684157)
		(end 132.238496 -261.7343)
		(width 0.088646)
		(layer "In6.Cu")
		(net "M_G_CPU1_SA_CB<4>")
	)
	(arc
		(start 139.278106 -260.925564)
		(mid 139.147192 -261.061924)
		(end 139.099544 -261.244842)
		(width 0.088646)
		(layer "In6.Cu")
		(net "M_G_CPU1_SA_CB<4>")
	)
	(arc
		(start 129.793746 -261.7343)
		(mid 129.606548 -261.684157)
		(end 129.41935 -261.7343)
		(width 0.088646)
		(layer "In6.Cu")
		(net "M_G_CPU1_SA_CB<4>")
	)
	(arc
		(start 134.492746 -261.7343)
		(mid 134.305548 -261.684157)
		(end 134.11835 -261.7343)
		(width 0.088646)
		(layer "In6.Cu")
		(net "M_G_CPU1_SA_CB<4>")
	)
	(arc
		(start 130.35915 -261.7343)
		(mid 130.084951 -261.810135)
		(end 129.808478 -261.742936)
		(width 0.088646)
		(layer "In6.Cu")
		(net "M_G_CPU1_SA_CB<4>")
	)
	(arc
		(start 135.057896 -261.7343)
		(mid 134.781337 -261.810043)
		(end 134.50316 -261.740396)
		(width 0.088646)
		(layer "In6.Cu")
		(net "M_G_CPU1_SA_CB<4>")
	)
	(arc
		(start 131.673346 -261.7343)
		(mid 131.486148 -261.684157)
		(end 131.29895 -261.7343)
		(width 0.088646)
		(layer "In6.Cu")
		(net "M_G_CPU1_SA_CB<4>")
	)
	(arc
		(start 133.17855 -261.7343)
		(mid 132.901737 -261.81017)
		(end 132.623306 -261.740396)
		(width 0.088646)
		(layer "In6.Cu")
		(net "M_G_CPU1_SA_CB<4>")
	)
	(arc
		(start 138.251692 -261.7343)
		(mid 138.064494 -261.684157)
		(end 137.877296 -261.7343)
		(width 0.088646)
		(layer "In6.Cu")
		(net "M_G_CPU1_SA_CB<4>")
	)
	(arc
		(start 136.937496 -261.7343)
		(mid 136.654794 -261.810076)
		(end 136.372092 -261.7343)
		(width 0.088646)
		(layer "In6.Cu")
		(net "M_G_CPU1_SA_CB<4>")
	)
	(arc
		(start 137.877296 -261.7343)
		(mid 137.594594 -261.810076)
		(end 137.311892 -261.7343)
		(width 0.088646)
		(layer "In6.Cu")
		(net "M_G_CPU1_SA_CB<4>")
	)
	(arc
		(start 132.238496 -261.7343)
		(mid 131.961937 -261.810043)
		(end 131.68376 -261.740396)
		(width 0.088646)
		(layer "In6.Cu")
		(net "M_G_CPU1_SA_CB<4>")
	)
	(arc
		(start 129.41935 -261.7343)
		(mid 129.339106 -261.796332)
		(end 129.27838 -261.877556)
		(width 0.088646)
		(layer "In6.Cu")
		(net "M_G_CPU1_SA_CB<4>")
	)
	(arc
		(start 135.432292 -261.7343)
		(mid 135.245094 -261.684157)
		(end 135.057896 -261.7343)
		(width 0.088646)
		(layer "In6.Cu")
		(net "M_G_CPU1_SA_CB<4>")
	)
	(arc
		(start 127.914146 -262.383016)
		(mid 127.726948 -262.433159)
		(end 127.53975 -262.383016)
		(width 0.088646)
		(layer "In6.Cu")
		(net "M_G_CPU1_SA_CB<4>")
	)
	(arc
		(start 138.817096 -261.7343)
		(mid 138.534394 -261.810076)
		(end 138.251692 -261.7343)
		(width 0.088646)
		(layer "In6.Cu")
		(net "M_G_CPU1_SA_CB<4>")
	)
	(segment
		(start 128.666494 -263.68629)
		(end 128.666748 -263.686544)
		(width 0.20066)
		(layer "F.Cu")
		(net "M_G_CPU1_SA_CB<3>")
	)
	(segment
		(start 195.343018 -276.791674)
		(end 195.522596 -276.791674)
		(width 0.101854)
		(layer "F.Cu")
		(net "M_G_CPU1_SA_CB<3>")
	)
	(segment
		(start 195.218812 -276.791674)
		(end 195.343018 -276.791674)
		(width 0.20066)
		(layer "F.Cu")
		(net "M_G_CPU1_SA_CB<3>")
	)
	(segment
		(start 194.79387 -276.366732)
		(end 195.218812 -276.791674)
		(width 0.20066)
		(layer "F.Cu")
		(net "M_G_CPU1_SA_CB<3>")
	)
	(segment
		(start 128.666494 -263.150604)
		(end 128.666494 -263.68629)
		(width 0.20066)
		(layer "F.Cu")
		(net "M_G_CPU1_SA_CB<3>")
	)
	(segment
		(start 198.227188 -276.791674)
		(end 198.427848 -276.591014)
		(width 0.20066)
		(layer "F.Cu")
		(net "M_G_CPU1_SA_CB<3>")
	)
	(segment
		(start 198.427848 -276.293834)
		(end 198.628508 -276.093174)
		(width 0.20066)
		(layer "F.Cu")
		(net "M_G_CPU1_SA_CB<3>")
	)
	(segment
		(start 197.834504 -276.791674)
		(end 198.227188 -276.791674)
		(width 0.20066)
		(layer "F.Cu")
		(net "M_G_CPU1_SA_CB<3>")
	)
	(segment
		(start 198.427848 -276.591014)
		(end 198.427848 -276.293834)
		(width 0.20066)
		(layer "F.Cu")
		(net "M_G_CPU1_SA_CB<3>")
	)
	(segment
		(start 199.298052 -276.366732)
		(end 200.632314 -276.366732)
		(width 0.20066)
		(layer "F.Cu")
		(net "M_G_CPU1_SA_CB<3>")
	)
	(segment
		(start 198.628508 -276.093174)
		(end 199.024494 -276.093174)
		(width 0.20066)
		(layer "F.Cu")
		(net "M_G_CPU1_SA_CB<3>")
	)
	(segment
		(start 199.024494 -276.093174)
		(end 199.298052 -276.366732)
		(width 0.20066)
		(layer "F.Cu")
		(net "M_G_CPU1_SA_CB<3>")
	)
	(segment
		(start 197.530466 -276.791674)
		(end 197.834504 -276.791674)
		(width 0.101854)
		(layer "F.Cu")
		(net "M_G_CPU1_SA_CB<3>")
	)
	(segment
		(start 195.522596 -276.791674)
		(end 197.530466 -276.791674)
		(width 0.1016)
		(layer "F.Cu")
		(net "M_G_CPU1_SA_CB<3>")
	)
	(segment
		(start 193.088514 -276.366732)
		(end 194.79387 -276.366732)
		(width 0.20066)
		(layer "F.Cu")
		(net "M_G_CPU1_SA_CB<3>")
	)
	(segment
		(start 191.983614 -276.366732)
		(end 193.088514 -276.366732)
		(width 0.20066)
		(layer "F.Cu")
		(net "M_G_CPU1_SA_CB<3>")
	)
	(segment
		(start 188.599572 -275.941282)
		(end 185.998104 -275.941282)
		(width 0.18288)
		(layer "In6.Cu")
		(net "M_G_CPU1_SA_CB<3>")
	)
	(segment
		(start 190.608966 -275.493226)
		(end 190.426086 -275.310346)
		(width 0.18288)
		(layer "In6.Cu")
		(net "M_G_CPU1_SA_CB<3>")
	)
	(segment
		(start 139.632182 -263.93521)
		(end 139.47394 -263.93521)
		(width 0.088646)
		(layer "In6.Cu")
		(net "M_G_CPU1_SA_CB<3>")
	)
	(segment
		(start 174.433484 -268.110716)
		(end 174.433484 -266.872212)
		(width 0.18288)
		(layer "In6.Cu")
		(net "M_G_CPU1_SA_CB<3>")
	)
	(segment
		(start 131.304538 -264.014204)
		(end 131.298696 -264.010902)
		(width 0.088646)
		(layer "In6.Cu")
		(net "M_G_CPU1_SA_CB<3>")
	)
	(segment
		(start 180.738272 -268.293596)
		(end 174.616364 -268.293596)
		(width 0.18288)
		(layer "In6.Cu")
		(net "M_G_CPU1_SA_CB<3>")
	)
	(segment
		(start 189.549786 -275.493226)
		(end 189.047628 -275.493226)
		(width 0.18288)
		(layer "In6.Cu")
		(net "M_G_CPU1_SA_CB<3>")
	)
	(segment
		(start 189.732666 -274.696174)
		(end 189.732666 -275.310346)
		(width 0.18288)
		(layer "In6.Cu")
		(net "M_G_CPU1_SA_CB<3>")
	)
	(segment
		(start 155.354274 -263.660382)
		(end 145.213832 -263.660382)
		(width 0.18288)
		(layer "In6.Cu")
		(net "M_G_CPU1_SA_CB<3>")
	)
	(segment
		(start 168.636188 -266.781026)
		(end 167.629332 -265.77417)
		(width 0.18288)
		(layer "In6.Cu")
		(net "M_G_CPU1_SA_CB<3>")
	)
	(segment
		(start 164.18052 -266.612116)
		(end 160.436052 -266.612116)
		(width 0.18288)
		(layer "In6.Cu")
		(net "M_G_CPU1_SA_CB<3>")
	)
	(segment
		(start 189.732666 -275.310346)
		(end 189.549786 -275.493226)
		(width 0.18288)
		(layer "In6.Cu")
		(net "M_G_CPU1_SA_CB<3>")
	)
	(segment
		(start 174.616364 -268.293596)
		(end 174.433484 -268.110716)
		(width 0.18288)
		(layer "In6.Cu")
		(net "M_G_CPU1_SA_CB<3>")
	)
	(segment
		(start 167.629332 -265.77417)
		(end 165.018466 -265.77417)
		(width 0.18288)
		(layer "In6.Cu")
		(net "M_G_CPU1_SA_CB<3>")
	)
	(segment
		(start 129.424938 -264.014204)
		(end 129.419096 -264.010902)
		(width 0.088646)
		(layer "In6.Cu")
		(net "M_G_CPU1_SA_CB<3>")
	)
	(segment
		(start 132.244338 -264.014204)
		(end 132.238496 -264.010902)
		(width 0.088646)
		(layer "In6.Cu")
		(net "M_G_CPU1_SA_CB<3>")
	)
	(segment
		(start 165.018466 -265.77417)
		(end 164.18052 -266.612116)
		(width 0.18288)
		(layer "In6.Cu")
		(net "M_G_CPU1_SA_CB<3>")
	)
	(segment
		(start 185.998104 -275.941282)
		(end 184.49544 -274.438618)
		(width 0.18288)
		(layer "In6.Cu")
		(net "M_G_CPU1_SA_CB<3>")
	)
	(segment
		(start 172.13199 -266.781026)
		(end 168.636188 -266.781026)
		(width 0.18288)
		(layer "In6.Cu")
		(net "M_G_CPU1_SA_CB<3>")
	)
	(segment
		(start 181.302152 -268.857476)
		(end 180.738272 -268.293596)
		(width 0.18288)
		(layer "In6.Cu")
		(net "M_G_CPU1_SA_CB<3>")
	)
	(segment
		(start 131.298696 -264.010902)
		(end 131.292854 -264.007346)
		(width 0.088646)
		(layer "In6.Cu")
		(net "M_G_CPU1_SA_CB<3>")
	)
	(segment
		(start 134.50316 -264.004806)
		(end 134.492746 -264.010902)
		(width 0.088646)
		(layer "In6.Cu")
		(net "M_G_CPU1_SA_CB<3>")
	)
	(segment
		(start 190.426086 -274.696174)
		(end 190.243206 -274.513294)
		(width 0.18288)
		(layer "In6.Cu")
		(net "M_G_CPU1_SA_CB<3>")
	)
	(segment
		(start 174.433484 -266.872212)
		(end 174.153576 -266.592304)
		(width 0.18288)
		(layer "In6.Cu")
		(net "M_G_CPU1_SA_CB<3>")
	)
	(segment
		(start 191.177418 -275.493226)
		(end 190.608966 -275.493226)
		(width 0.18288)
		(layer "In6.Cu")
		(net "M_G_CPU1_SA_CB<3>")
	)
	(segment
		(start 191.983614 -276.366732)
		(end 191.538606 -276.366732)
		(width 0.18288)
		(layer "In6.Cu")
		(net "M_G_CPU1_SA_CB<3>")
	)
	(segment
		(start 137.322306 -264.004806)
		(end 137.311892 -264.010902)
		(width 0.088646)
		(layer "In6.Cu")
		(net "M_G_CPU1_SA_CB<3>")
	)
	(segment
		(start 189.915546 -274.513294)
		(end 189.732666 -274.696174)
		(width 0.18288)
		(layer "In6.Cu")
		(net "M_G_CPU1_SA_CB<3>")
	)
	(segment
		(start 157.59303 -265.899138)
		(end 155.354274 -263.660382)
		(width 0.18288)
		(layer "In6.Cu")
		(net "M_G_CPU1_SA_CB<3>")
	)
	(segment
		(start 191.34709 -275.662898)
		(end 191.177418 -275.493226)
		(width 0.18288)
		(layer "In6.Cu")
		(net "M_G_CPU1_SA_CB<3>")
	)
	(segment
		(start 191.34709 -276.175216)
		(end 191.34709 -275.662898)
		(width 0.18288)
		(layer "In6.Cu")
		(net "M_G_CPU1_SA_CB<3>")
	)
	(segment
		(start 132.238496 -264.010902)
		(end 132.232654 -264.007346)
		(width 0.088646)
		(layer "In6.Cu")
		(net "M_G_CPU1_SA_CB<3>")
	)
	(segment
		(start 133.178296 -264.010902)
		(end 133.172454 -264.007346)
		(width 0.088646)
		(layer "In6.Cu")
		(net "M_G_CPU1_SA_CB<3>")
	)
	(segment
		(start 191.538606 -276.366732)
		(end 191.34709 -276.175216)
		(width 0.18288)
		(layer "In6.Cu")
		(net "M_G_CPU1_SA_CB<3>")
	)
	(segment
		(start 130.364738 -264.014204)
		(end 130.358896 -264.010902)
		(width 0.088646)
		(layer "In6.Cu")
		(net "M_G_CPU1_SA_CB<3>")
	)
	(segment
		(start 174.153576 -266.592304)
		(end 172.320712 -266.592304)
		(width 0.18288)
		(layer "In6.Cu")
		(net "M_G_CPU1_SA_CB<3>")
	)
	(segment
		(start 172.320712 -266.592304)
		(end 172.13199 -266.781026)
		(width 0.18288)
		(layer "In6.Cu")
		(net "M_G_CPU1_SA_CB<3>")
	)
	(segment
		(start 181.302152 -273.73199)
		(end 181.302152 -268.857476)
		(width 0.18288)
		(layer "In6.Cu")
		(net "M_G_CPU1_SA_CB<3>")
	)
	(segment
		(start 140.40104 -263.166352)
		(end 139.632182 -263.93521)
		(width 0.088646)
		(layer "In6.Cu")
		(net "M_G_CPU1_SA_CB<3>")
	)
	(segment
		(start 159.723074 -265.899138)
		(end 157.59303 -265.899138)
		(width 0.18288)
		(layer "In6.Cu")
		(net "M_G_CPU1_SA_CB<3>")
	)
	(segment
		(start 130.358896 -264.010902)
		(end 130.353054 -264.007346)
		(width 0.088646)
		(layer "In6.Cu")
		(net "M_G_CPU1_SA_CB<3>")
	)
	(segment
		(start 190.243206 -274.513294)
		(end 189.915546 -274.513294)
		(width 0.18288)
		(layer "In6.Cu")
		(net "M_G_CPU1_SA_CB<3>")
	)
	(segment
		(start 142.729966 -263.166352)
		(end 140.595604 -263.166352)
		(width 0.18288)
		(layer "In6.Cu")
		(net "M_G_CPU1_SA_CB<3>")
	)
	(segment
		(start 145.213832 -263.660382)
		(end 142.729966 -263.166352)
		(width 0.18288)
		(layer "In6.Cu")
		(net "M_G_CPU1_SA_CB<3>")
	)
	(segment
		(start 138.266678 -264.002266)
		(end 138.251946 -264.010902)
		(width 0.088646)
		(layer "In6.Cu")
		(net "M_G_CPU1_SA_CB<3>")
	)
	(segment
		(start 160.436052 -266.612116)
		(end 159.723074 -265.899138)
		(width 0.18288)
		(layer "In6.Cu")
		(net "M_G_CPU1_SA_CB<3>")
	)
	(segment
		(start 140.595604 -263.166352)
		(end 140.40104 -263.166352)
		(width 0.088646)
		(layer "In6.Cu")
		(net "M_G_CPU1_SA_CB<3>")
	)
	(segment
		(start 133.184138 -264.014204)
		(end 133.178296 -264.010902)
		(width 0.088646)
		(layer "In6.Cu")
		(net "M_G_CPU1_SA_CB<3>")
	)
	(segment
		(start 184.49544 -274.438618)
		(end 182.00878 -274.438618)
		(width 0.18288)
		(layer "In6.Cu")
		(net "M_G_CPU1_SA_CB<3>")
	)
	(segment
		(start 190.426086 -275.310346)
		(end 190.426086 -274.696174)
		(width 0.18288)
		(layer "In6.Cu")
		(net "M_G_CPU1_SA_CB<3>")
	)
	(segment
		(start 129.419096 -264.010902)
		(end 129.021332 -263.78154)
		(width 0.088646)
		(layer "In6.Cu")
		(net "M_G_CPU1_SA_CB<3>")
	)
	(segment
		(start 133.567678 -264.002266)
		(end 133.552946 -264.010902)
		(width 0.088646)
		(layer "In6.Cu")
		(net "M_G_CPU1_SA_CB<3>")
	)
	(segment
		(start 189.047628 -275.493226)
		(end 188.599572 -275.941282)
		(width 0.18288)
		(layer "In6.Cu")
		(net "M_G_CPU1_SA_CB<3>")
	)
	(segment
		(start 182.00878 -274.438618)
		(end 181.302152 -273.73199)
		(width 0.18288)
		(layer "In6.Cu")
		(net "M_G_CPU1_SA_CB<3>")
	)
	(arc
		(start 133.552946 -264.010902)
		(mid 133.368992 -264.061031)
		(end 133.184138 -264.014204)
		(width 0.088646)
		(layer "In6.Cu")
		(net "M_G_CPU1_SA_CB<3>")
	)
	(arc
		(start 139.437618 -263.936226)
		(mid 139.31039 -263.959424)
		(end 139.191746 -264.010902)
		(width 0.088646)
		(layer "In6.Cu")
		(net "M_G_CPU1_SA_CB<3>")
	)
	(arc
		(start 132.232654 -264.007346)
		(mid 131.952519 -263.935063)
		(end 131.673346 -264.010902)
		(width 0.088646)
		(layer "In6.Cu")
		(net "M_G_CPU1_SA_CB<3>")
	)
	(arc
		(start 138.81735 -264.010902)
		(mid 138.543151 -263.935067)
		(end 138.266678 -264.002266)
		(width 0.088646)
		(layer "In6.Cu")
		(net "M_G_CPU1_SA_CB<3>")
	)
	(arc
		(start 130.733546 -264.010902)
		(mid 130.549592 -264.061031)
		(end 130.364738 -264.014204)
		(width 0.088646)
		(layer "In6.Cu")
		(net "M_G_CPU1_SA_CB<3>")
	)
	(arc
		(start 136.937496 -264.010902)
		(mid 136.654794 -263.935126)
		(end 136.372092 -264.010902)
		(width 0.088646)
		(layer "In6.Cu")
		(net "M_G_CPU1_SA_CB<3>")
	)
	(arc
		(start 135.432292 -264.010902)
		(mid 135.245094 -264.061045)
		(end 135.057896 -264.010902)
		(width 0.088646)
		(layer "In6.Cu")
		(net "M_G_CPU1_SA_CB<3>")
	)
	(arc
		(start 134.492746 -264.010902)
		(mid 134.305548 -264.061045)
		(end 134.11835 -264.010902)
		(width 0.088646)
		(layer "In6.Cu")
		(net "M_G_CPU1_SA_CB<3>")
	)
	(arc
		(start 136.372092 -264.010902)
		(mid 136.184894 -264.061045)
		(end 135.997696 -264.010902)
		(width 0.088646)
		(layer "In6.Cu")
		(net "M_G_CPU1_SA_CB<3>")
	)
	(arc
		(start 132.613146 -264.010902)
		(mid 132.429192 -264.061031)
		(end 132.244338 -264.014204)
		(width 0.088646)
		(layer "In6.Cu")
		(net "M_G_CPU1_SA_CB<3>")
	)
	(arc
		(start 133.172454 -264.007346)
		(mid 132.892319 -263.935063)
		(end 132.613146 -264.010902)
		(width 0.088646)
		(layer "In6.Cu")
		(net "M_G_CPU1_SA_CB<3>")
	)
	(arc
		(start 139.191746 -264.010902)
		(mid 139.004548 -264.061045)
		(end 138.81735 -264.010902)
		(width 0.088646)
		(layer "In6.Cu")
		(net "M_G_CPU1_SA_CB<3>")
	)
	(arc
		(start 135.057896 -264.010902)
		(mid 134.781337 -263.935159)
		(end 134.50316 -264.004806)
		(width 0.088646)
		(layer "In6.Cu")
		(net "M_G_CPU1_SA_CB<3>")
	)
	(arc
		(start 129.793746 -264.010902)
		(mid 129.609792 -264.061031)
		(end 129.424938 -264.014204)
		(width 0.088646)
		(layer "In6.Cu")
		(net "M_G_CPU1_SA_CB<3>")
	)
	(arc
		(start 130.353054 -264.007346)
		(mid 130.072919 -263.935063)
		(end 129.793746 -264.010902)
		(width 0.088646)
		(layer "In6.Cu")
		(net "M_G_CPU1_SA_CB<3>")
	)
	(arc
		(start 135.997696 -264.010902)
		(mid 135.714994 -263.935126)
		(end 135.432292 -264.010902)
		(width 0.088646)
		(layer "In6.Cu")
		(net "M_G_CPU1_SA_CB<3>")
	)
	(arc
		(start 138.251946 -264.010902)
		(mid 138.064748 -264.061045)
		(end 137.87755 -264.010902)
		(width 0.088646)
		(layer "In6.Cu")
		(net "M_G_CPU1_SA_CB<3>")
	)
	(arc
		(start 139.47394 -263.93521)
		(mid 139.455771 -263.935429)
		(end 139.437618 -263.936226)
		(width 0.088646)
		(layer "In6.Cu")
		(net "M_G_CPU1_SA_CB<3>")
	)
	(arc
		(start 137.311892 -264.010902)
		(mid 137.124694 -264.061045)
		(end 136.937496 -264.010902)
		(width 0.088646)
		(layer "In6.Cu")
		(net "M_G_CPU1_SA_CB<3>")
	)
	(arc
		(start 134.11835 -264.010902)
		(mid 133.844151 -263.935067)
		(end 133.567678 -264.002266)
		(width 0.088646)
		(layer "In6.Cu")
		(net "M_G_CPU1_SA_CB<3>")
	)
	(arc
		(start 129.021332 -263.78154)
		(mid 128.85028 -263.710759)
		(end 128.666748 -263.686544)
		(width 0.088646)
		(layer "In6.Cu")
		(net "M_G_CPU1_SA_CB<3>")
	)
	(arc
		(start 131.292854 -264.007346)
		(mid 131.012719 -263.935063)
		(end 130.733546 -264.010902)
		(width 0.088646)
		(layer "In6.Cu")
		(net "M_G_CPU1_SA_CB<3>")
	)
	(arc
		(start 137.87755 -264.010902)
		(mid 137.600737 -263.935032)
		(end 137.322306 -264.004806)
		(width 0.088646)
		(layer "In6.Cu")
		(net "M_G_CPU1_SA_CB<3>")
	)
	(arc
		(start 131.673346 -264.010902)
		(mid 131.489392 -264.061031)
		(end 131.304538 -264.014204)
		(width 0.088646)
		(layer "In6.Cu")
		(net "M_G_CPU1_SA_CB<3>")
	)
	(segment
		(start 193.088514 -278.066754)
		(end 194.685158 -278.066754)
		(width 0.20066)
		(layer "F.Cu")
		(net "M_G_CPU1_SA_CB<2>")
	)
	(segment
		(start 191.983614 -278.066754)
		(end 193.088514 -278.066754)
		(width 0.20066)
		(layer "F.Cu")
		(net "M_G_CPU1_SA_CB<2>")
	)
	(segment
		(start 128.196848 -263.96442)
		(end 128.196848 -264.500106)
		(width 0.20066)
		(layer "F.Cu")
		(net "M_G_CPU1_SA_CB<2>")
	)
	(segment
		(start 128.196848 -264.500106)
		(end 128.196594 -264.50036)
		(width 0.20066)
		(layer "F.Cu")
		(net "M_G_CPU1_SA_CB<2>")
	)
	(segment
		(start 194.685158 -278.066754)
		(end 195.1101 -278.491696)
		(width 0.20066)
		(layer "F.Cu")
		(net "M_G_CPU1_SA_CB<2>")
	)
	(segment
		(start 195.1101 -278.491696)
		(end 195.343018 -278.491696)
		(width 0.20066)
		(layer "F.Cu")
		(net "M_G_CPU1_SA_CB<2>")
	)
	(segment
		(start 198.227188 -278.491696)
		(end 198.427848 -278.291036)
		(width 0.20066)
		(layer "F.Cu")
		(net "M_G_CPU1_SA_CB<2>")
	)
	(segment
		(start 195.343018 -278.491696)
		(end 195.522596 -278.491696)
		(width 0.101854)
		(layer "F.Cu")
		(net "M_G_CPU1_SA_CB<2>")
	)
	(segment
		(start 195.522596 -278.491696)
		(end 197.48881 -278.491696)
		(width 0.1016)
		(layer "F.Cu")
		(net "M_G_CPU1_SA_CB<2>")
	)
	(segment
		(start 197.834504 -278.491696)
		(end 198.227188 -278.491696)
		(width 0.20066)
		(layer "F.Cu")
		(net "M_G_CPU1_SA_CB<2>")
	)
	(segment
		(start 197.48881 -278.491696)
		(end 197.834504 -278.491696)
		(width 0.101854)
		(layer "F.Cu")
		(net "M_G_CPU1_SA_CB<2>")
	)
	(segment
		(start 199.298052 -278.066754)
		(end 200.632314 -278.066754)
		(width 0.20066)
		(layer "F.Cu")
		(net "M_G_CPU1_SA_CB<2>")
	)
	(segment
		(start 198.427848 -278.291036)
		(end 198.427848 -277.97252)
		(width 0.20066)
		(layer "F.Cu")
		(net "M_G_CPU1_SA_CB<2>")
	)
	(segment
		(start 199.003158 -277.77186)
		(end 199.298052 -278.066754)
		(width 0.20066)
		(layer "F.Cu")
		(net "M_G_CPU1_SA_CB<2>")
	)
	(segment
		(start 198.427848 -277.97252)
		(end 198.628508 -277.77186)
		(width 0.20066)
		(layer "F.Cu")
		(net "M_G_CPU1_SA_CB<2>")
	)
	(segment
		(start 198.628508 -277.77186)
		(end 199.003158 -277.77186)
		(width 0.20066)
		(layer "F.Cu")
		(net "M_G_CPU1_SA_CB<2>")
	)
	(segment
		(start 181.844696 -275.781008)
		(end 181.844696 -276.391116)
		(width 0.18288)
		(layer "In6.Cu")
		(net "M_G_CPU1_SA_CB<2>")
	)
	(segment
		(start 181.334156 -276.573996)
		(end 181.151276 -276.391116)
		(width 0.18288)
		(layer "In6.Cu")
		(net "M_G_CPU1_SA_CB<2>")
	)
	(segment
		(start 163.425632 -268.292072)
		(end 159.328612 -268.292072)
		(width 0.18288)
		(layer "In6.Cu")
		(net "M_G_CPU1_SA_CB<2>")
	)
	(segment
		(start 189.235588 -276.75332)
		(end 189.052708 -276.9362)
		(width 0.18288)
		(layer "In6.Cu")
		(net "M_G_CPU1_SA_CB<2>")
	)
	(segment
		(start 186.522614 -277.792434)
		(end 184.35955 -276.629368)
		(width 0.18288)
		(layer "In6.Cu")
		(net "M_G_CPU1_SA_CB<2>")
	)
	(segment
		(start 178.695096 -271.750536)
		(end 178.512216 -271.567656)
		(width 0.18288)
		(layer "In6.Cu")
		(net "M_G_CPU1_SA_CB<2>")
	)
	(segment
		(start 191.983614 -278.066754)
		(end 191.557656 -277.640796)
		(width 0.18288)
		(layer "In6.Cu")
		(net "M_G_CPU1_SA_CB<2>")
	)
	(segment
		(start 145.100294 -264.684256)
		(end 142.52321 -264.171684)
		(width 0.18288)
		(layer "In6.Cu")
		(net "M_G_CPU1_SA_CB<2>")
	)
	(segment
		(start 189.746128 -276.9362)
		(end 189.563248 -276.75332)
		(width 0.18288)
		(layer "In6.Cu")
		(net "M_G_CPU1_SA_CB<2>")
	)
	(segment
		(start 163.601654 -268.468094)
		(end 163.425632 -268.292072)
		(width 0.18288)
		(layer "In6.Cu")
		(net "M_G_CPU1_SA_CB<2>")
	)
	(segment
		(start 166.596314 -267.91031)
		(end 166.418006 -268.088618)
		(width 0.18288)
		(layer "In6.Cu")
		(net "M_G_CPU1_SA_CB<2>")
	)
	(segment
		(start 136.467596 -264.824718)
		(end 136.452864 -264.816082)
		(width 0.088646)
		(layer "In6.Cu")
		(net "M_G_CPU1_SA_CB<2>")
	)
	(segment
		(start 166.418006 -268.088618)
		(end 164.73805 -268.088618)
		(width 0.18288)
		(layer "In6.Cu")
		(net "M_G_CPU1_SA_CB<2>")
	)
	(segment
		(start 179.097686 -272.443956)
		(end 179.280566 -272.261076)
		(width 0.18288)
		(layer "In6.Cu")
		(net "M_G_CPU1_SA_CB<2>")
	)
	(segment
		(start 183.76646 -276.629368)
		(end 182.73522 -275.598128)
		(width 0.18288)
		(layer "In6.Cu")
		(net "M_G_CPU1_SA_CB<2>")
	)
	(segment
		(start 178.512216 -272.626836)
		(end 178.695096 -272.443956)
		(width 0.18288)
		(layer "In6.Cu")
		(net "M_G_CPU1_SA_CB<2>")
	)
	(segment
		(start 173.105826 -269.142464)
		(end 172.33392 -269.142464)
		(width 0.18288)
		(layer "In6.Cu")
		(net "M_G_CPU1_SA_CB<2>")
	)
	(segment
		(start 181.844696 -276.391116)
		(end 181.661816 -276.573996)
		(width 0.18288)
		(layer "In6.Cu")
		(net "M_G_CPU1_SA_CB<2>")
	)
	(segment
		(start 159.328612 -268.292072)
		(end 158.599886 -267.563346)
		(width 0.18288)
		(layer "In6.Cu")
		(net "M_G_CPU1_SA_CB<2>")
	)
	(segment
		(start 187.214002 -277.640796)
		(end 187.062364 -277.792434)
		(width 0.18288)
		(layer "In6.Cu")
		(net "M_G_CPU1_SA_CB<2>")
	)
	(segment
		(start 129.331212 -264.8204)
		(end 129.323846 -264.824718)
		(width 0.088646)
		(layer "In6.Cu")
		(net "M_G_CPU1_SA_CB<2>")
	)
	(segment
		(start 132.150612 -264.8204)
		(end 132.143246 -264.824718)
		(width 0.088646)
		(layer "In6.Cu")
		(net "M_G_CPU1_SA_CB<2>")
	)
	(segment
		(start 176.081944 -269.992348)
		(end 175.86579 -269.776194)
		(width 0.18288)
		(layer "In6.Cu")
		(net "M_G_CPU1_SA_CB<2>")
	)
	(segment
		(start 130.263646 -264.824718)
		(end 130.259074 -264.827512)
		(width 0.088646)
		(layer "In6.Cu")
		(net "M_G_CPU1_SA_CB<2>")
	)
	(segment
		(start 182.027576 -275.598128)
		(end 181.844696 -275.781008)
		(width 0.18288)
		(layer "In6.Cu")
		(net "M_G_CPU1_SA_CB<2>")
	)
	(segment
		(start 179.280566 -272.261076)
		(end 179.280566 -271.933416)
		(width 0.18288)
		(layer "In6.Cu")
		(net "M_G_CPU1_SA_CB<2>")
	)
	(segment
		(start 181.151276 -275.781008)
		(end 180.968396 -275.598128)
		(width 0.18288)
		(layer "In6.Cu")
		(net "M_G_CPU1_SA_CB<2>")
	)
	(segment
		(start 189.746128 -277.457916)
		(end 189.746128 -276.9362)
		(width 0.18288)
		(layer "In6.Cu")
		(net "M_G_CPU1_SA_CB<2>")
	)
	(segment
		(start 184.35955 -276.629368)
		(end 183.76646 -276.629368)
		(width 0.18288)
		(layer "In6.Cu")
		(net "M_G_CPU1_SA_CB<2>")
	)
	(segment
		(start 131.203446 -264.824718)
		(end 131.198874 -264.827512)
		(width 0.088646)
		(layer "In6.Cu")
		(net "M_G_CPU1_SA_CB<2>")
	)
	(segment
		(start 182.73522 -275.598128)
		(end 182.027576 -275.598128)
		(width 0.18288)
		(layer "In6.Cu")
		(net "M_G_CPU1_SA_CB<2>")
	)
	(segment
		(start 134.022846 -264.824718)
		(end 134.018274 -264.827512)
		(width 0.088646)
		(layer "In6.Cu")
		(net "M_G_CPU1_SA_CB<2>")
	)
	(segment
		(start 133.083046 -264.824718)
		(end 133.078474 -264.827512)
		(width 0.088646)
		(layer "In6.Cu")
		(net "M_G_CPU1_SA_CB<2>")
	)
	(segment
		(start 129.323846 -264.824718)
		(end 129.319274 -264.827512)
		(width 0.088646)
		(layer "In6.Cu")
		(net "M_G_CPU1_SA_CB<2>")
	)
	(segment
		(start 174.209456 -269.758922)
		(end 173.105826 -269.142464)
		(width 0.18288)
		(layer "In6.Cu")
		(net "M_G_CPU1_SA_CB<2>")
	)
	(segment
		(start 179.846224 -275.598128)
		(end 178.512216 -274.26412)
		(width 0.18288)
		(layer "In6.Cu")
		(net "M_G_CPU1_SA_CB<2>")
	)
	(segment
		(start 140.333222 -264.171684)
		(end 139.73937 -264.765536)
		(width 0.088646)
		(layer "In6.Cu")
		(net "M_G_CPU1_SA_CB<2>")
	)
	(segment
		(start 135.527796 -264.824718)
		(end 135.513064 -264.816082)
		(width 0.088646)
		(layer "In6.Cu")
		(net "M_G_CPU1_SA_CB<2>")
	)
	(segment
		(start 187.062364 -277.792434)
		(end 186.522614 -277.792434)
		(width 0.18288)
		(layer "In6.Cu")
		(net "M_G_CPU1_SA_CB<2>")
	)
	(segment
		(start 140.595604 -264.171684)
		(end 140.333222 -264.171684)
		(width 0.088646)
		(layer "In6.Cu")
		(net "M_G_CPU1_SA_CB<2>")
	)
	(segment
		(start 132.143246 -264.824718)
		(end 132.138674 -264.827512)
		(width 0.088646)
		(layer "In6.Cu")
		(net "M_G_CPU1_SA_CB<2>")
	)
	(segment
		(start 178.512216 -271.567656)
		(end 178.512216 -270.471138)
		(width 0.18288)
		(layer "In6.Cu")
		(net "M_G_CPU1_SA_CB<2>")
	)
	(segment
		(start 133.090412 -264.8204)
		(end 133.083046 -264.824718)
		(width 0.088646)
		(layer "In6.Cu")
		(net "M_G_CPU1_SA_CB<2>")
	)
	(segment
		(start 168.340024 -267.91031)
		(end 166.596314 -267.91031)
		(width 0.18288)
		(layer "In6.Cu")
		(net "M_G_CPU1_SA_CB<2>")
	)
	(segment
		(start 142.52321 -264.171684)
		(end 140.595604 -264.171684)
		(width 0.18288)
		(layer "In6.Cu")
		(net "M_G_CPU1_SA_CB<2>")
	)
	(segment
		(start 189.052708 -277.457916)
		(end 188.869828 -277.640796)
		(width 0.18288)
		(layer "In6.Cu")
		(net "M_G_CPU1_SA_CB<2>")
	)
	(segment
		(start 180.968396 -275.598128)
		(end 179.846224 -275.598128)
		(width 0.18288)
		(layer "In6.Cu")
		(net "M_G_CPU1_SA_CB<2>")
	)
	(segment
		(start 189.929008 -277.640796)
		(end 189.746128 -277.457916)
		(width 0.18288)
		(layer "In6.Cu")
		(net "M_G_CPU1_SA_CB<2>")
	)
	(segment
		(start 154.756612 -264.684256)
		(end 145.100294 -264.684256)
		(width 0.18288)
		(layer "In6.Cu")
		(net "M_G_CPU1_SA_CB<2>")
	)
	(segment
		(start 131.210812 -264.8204)
		(end 131.203446 -264.824718)
		(width 0.088646)
		(layer "In6.Cu")
		(net "M_G_CPU1_SA_CB<2>")
	)
	(segment
		(start 181.151276 -276.391116)
		(end 181.151276 -275.781008)
		(width 0.18288)
		(layer "In6.Cu")
		(net "M_G_CPU1_SA_CB<2>")
	)
	(segment
		(start 178.695096 -272.443956)
		(end 179.097686 -272.443956)
		(width 0.18288)
		(layer "In6.Cu")
		(net "M_G_CPU1_SA_CB<2>")
	)
	(segment
		(start 172.33392 -269.142464)
		(end 171.523406 -268.33195)
		(width 0.18288)
		(layer "In6.Cu")
		(net "M_G_CPU1_SA_CB<2>")
	)
	(segment
		(start 137.407396 -264.824718)
		(end 137.392664 -264.816082)
		(width 0.088646)
		(layer "In6.Cu")
		(net "M_G_CPU1_SA_CB<2>")
	)
	(segment
		(start 179.097686 -271.750536)
		(end 178.695096 -271.750536)
		(width 0.18288)
		(layer "In6.Cu")
		(net "M_G_CPU1_SA_CB<2>")
	)
	(segment
		(start 188.869828 -277.640796)
		(end 187.214002 -277.640796)
		(width 0.18288)
		(layer "In6.Cu")
		(net "M_G_CPU1_SA_CB<2>")
	)
	(segment
		(start 134.030212 -264.8204)
		(end 134.022846 -264.824718)
		(width 0.088646)
		(layer "In6.Cu")
		(net "M_G_CPU1_SA_CB<2>")
	)
	(segment
		(start 175.86579 -269.776194)
		(end 174.226728 -269.776194)
		(width 0.18288)
		(layer "In6.Cu")
		(net "M_G_CPU1_SA_CB<2>")
	)
	(segment
		(start 168.761664 -268.33195)
		(end 168.340024 -267.91031)
		(width 0.18288)
		(layer "In6.Cu")
		(net "M_G_CPU1_SA_CB<2>")
	)
	(segment
		(start 164.73805 -268.088618)
		(end 164.358574 -268.468094)
		(width 0.18288)
		(layer "In6.Cu")
		(net "M_G_CPU1_SA_CB<2>")
	)
	(segment
		(start 181.661816 -276.573996)
		(end 181.334156 -276.573996)
		(width 0.18288)
		(layer "In6.Cu")
		(net "M_G_CPU1_SA_CB<2>")
	)
	(segment
		(start 189.052708 -276.9362)
		(end 189.052708 -277.457916)
		(width 0.18288)
		(layer "In6.Cu")
		(net "M_G_CPU1_SA_CB<2>")
	)
	(segment
		(start 138.347196 -264.824718)
		(end 138.332464 -264.816082)
		(width 0.088646)
		(layer "In6.Cu")
		(net "M_G_CPU1_SA_CB<2>")
	)
	(segment
		(start 130.271012 -264.8204)
		(end 130.263646 -264.824718)
		(width 0.088646)
		(layer "In6.Cu")
		(net "M_G_CPU1_SA_CB<2>")
	)
	(segment
		(start 191.557656 -277.640796)
		(end 189.929008 -277.640796)
		(width 0.18288)
		(layer "In6.Cu")
		(net "M_G_CPU1_SA_CB<2>")
	)
	(segment
		(start 178.033426 -269.992348)
		(end 176.081944 -269.992348)
		(width 0.18288)
		(layer "In6.Cu")
		(net "M_G_CPU1_SA_CB<2>")
	)
	(segment
		(start 178.512216 -270.471138)
		(end 178.033426 -269.992348)
		(width 0.18288)
		(layer "In6.Cu")
		(net "M_G_CPU1_SA_CB<2>")
	)
	(segment
		(start 189.563248 -276.75332)
		(end 189.235588 -276.75332)
		(width 0.18288)
		(layer "In6.Cu")
		(net "M_G_CPU1_SA_CB<2>")
	)
	(segment
		(start 158.599886 -267.563346)
		(end 157.635702 -267.563346)
		(width 0.18288)
		(layer "In6.Cu")
		(net "M_G_CPU1_SA_CB<2>")
	)
	(segment
		(start 174.226728 -269.776194)
		(end 174.209456 -269.758922)
		(width 0.18288)
		(layer "In6.Cu")
		(net "M_G_CPU1_SA_CB<2>")
	)
	(segment
		(start 139.286996 -264.824718)
		(end 139.272264 -264.816082)
		(width 0.088646)
		(layer "In6.Cu")
		(net "M_G_CPU1_SA_CB<2>")
	)
	(segment
		(start 179.280566 -271.933416)
		(end 179.097686 -271.750536)
		(width 0.18288)
		(layer "In6.Cu")
		(net "M_G_CPU1_SA_CB<2>")
	)
	(segment
		(start 164.358574 -268.468094)
		(end 163.601654 -268.468094)
		(width 0.18288)
		(layer "In6.Cu")
		(net "M_G_CPU1_SA_CB<2>")
	)
	(segment
		(start 178.512216 -274.26412)
		(end 178.512216 -272.626836)
		(width 0.18288)
		(layer "In6.Cu")
		(net "M_G_CPU1_SA_CB<2>")
	)
	(segment
		(start 171.523406 -268.33195)
		(end 168.761664 -268.33195)
		(width 0.18288)
		(layer "In6.Cu")
		(net "M_G_CPU1_SA_CB<2>")
	)
	(segment
		(start 157.635702 -267.563346)
		(end 154.756612 -264.684256)
		(width 0.18288)
		(layer "In6.Cu")
		(net "M_G_CPU1_SA_CB<2>")
	)
	(arc
		(start 131.198874 -264.827512)
		(mid 131.01346 -264.875024)
		(end 130.828796 -264.824718)
		(width 0.088646)
		(layer "In6.Cu")
		(net "M_G_CPU1_SA_CB<2>")
	)
	(arc
		(start 128.668526 -264.749026)
		(mid 128.401798 -264.683064)
		(end 128.196594 -264.50036)
		(width 0.088646)
		(layer "In6.Cu")
		(net "M_G_CPU1_SA_CB<2>")
	)
	(arc
		(start 136.841992 -264.824718)
		(mid 136.654794 -264.874861)
		(end 136.467596 -264.824718)
		(width 0.088646)
		(layer "In6.Cu")
		(net "M_G_CPU1_SA_CB<2>")
	)
	(arc
		(start 138.721592 -264.824718)
		(mid 138.534394 -264.874861)
		(end 138.347196 -264.824718)
		(width 0.088646)
		(layer "In6.Cu")
		(net "M_G_CPU1_SA_CB<2>")
	)
	(arc
		(start 130.828796 -264.824718)
		(mid 130.550473 -264.748959)
		(end 130.271012 -264.8204)
		(width 0.088646)
		(layer "In6.Cu")
		(net "M_G_CPU1_SA_CB<2>")
	)
	(arc
		(start 139.661392 -264.824718)
		(mid 139.474194 -264.874861)
		(end 139.286996 -264.824718)
		(width 0.088646)
		(layer "In6.Cu")
		(net "M_G_CPU1_SA_CB<2>")
	)
	(arc
		(start 133.078474 -264.827512)
		(mid 132.89306 -264.875024)
		(end 132.708396 -264.824718)
		(width 0.088646)
		(layer "In6.Cu")
		(net "M_G_CPU1_SA_CB<2>")
	)
	(arc
		(start 137.392664 -264.816082)
		(mid 137.116189 -264.748762)
		(end 136.841992 -264.824718)
		(width 0.088646)
		(layer "In6.Cu")
		(net "M_G_CPU1_SA_CB<2>")
	)
	(arc
		(start 131.768596 -264.824718)
		(mid 131.490273 -264.748959)
		(end 131.210812 -264.8204)
		(width 0.088646)
		(layer "In6.Cu")
		(net "M_G_CPU1_SA_CB<2>")
	)
	(arc
		(start 135.902192 -264.824718)
		(mid 135.714994 -264.874861)
		(end 135.527796 -264.824718)
		(width 0.088646)
		(layer "In6.Cu")
		(net "M_G_CPU1_SA_CB<2>")
	)
	(arc
		(start 132.708396 -264.824718)
		(mid 132.430073 -264.748959)
		(end 132.150612 -264.8204)
		(width 0.088646)
		(layer "In6.Cu")
		(net "M_G_CPU1_SA_CB<2>")
	)
	(arc
		(start 138.332464 -264.816082)
		(mid 138.055989 -264.748762)
		(end 137.781792 -264.824718)
		(width 0.088646)
		(layer "In6.Cu")
		(net "M_G_CPU1_SA_CB<2>")
	)
	(arc
		(start 137.781792 -264.824718)
		(mid 137.594594 -264.874861)
		(end 137.407396 -264.824718)
		(width 0.088646)
		(layer "In6.Cu")
		(net "M_G_CPU1_SA_CB<2>")
	)
	(arc
		(start 136.452864 -264.816082)
		(mid 136.176389 -264.748762)
		(end 135.902192 -264.824718)
		(width 0.088646)
		(layer "In6.Cu")
		(net "M_G_CPU1_SA_CB<2>")
	)
	(arc
		(start 134.587996 -264.824718)
		(mid 134.309673 -264.748959)
		(end 134.030212 -264.8204)
		(width 0.088646)
		(layer "In6.Cu")
		(net "M_G_CPU1_SA_CB<2>")
	)
	(arc
		(start 135.513064 -264.816082)
		(mid 135.236589 -264.748762)
		(end 134.962392 -264.824718)
		(width 0.088646)
		(layer "In6.Cu")
		(net "M_G_CPU1_SA_CB<2>")
	)
	(arc
		(start 130.259074 -264.827512)
		(mid 130.07366 -264.875024)
		(end 129.888996 -264.824718)
		(width 0.088646)
		(layer "In6.Cu")
		(net "M_G_CPU1_SA_CB<2>")
	)
	(arc
		(start 132.138674 -264.827512)
		(mid 131.95326 -264.875024)
		(end 131.768596 -264.824718)
		(width 0.088646)
		(layer "In6.Cu")
		(net "M_G_CPU1_SA_CB<2>")
	)
	(arc
		(start 134.018274 -264.827512)
		(mid 133.83286 -264.875024)
		(end 133.648196 -264.824718)
		(width 0.088646)
		(layer "In6.Cu")
		(net "M_G_CPU1_SA_CB<2>")
	)
	(arc
		(start 133.648196 -264.824718)
		(mid 133.369873 -264.748959)
		(end 133.090412 -264.8204)
		(width 0.088646)
		(layer "In6.Cu")
		(net "M_G_CPU1_SA_CB<2>")
	)
	(arc
		(start 134.962392 -264.824718)
		(mid 134.775194 -264.874861)
		(end 134.587996 -264.824718)
		(width 0.088646)
		(layer "In6.Cu")
		(net "M_G_CPU1_SA_CB<2>")
	)
	(arc
		(start 129.888996 -264.824718)
		(mid 129.610673 -264.748959)
		(end 129.331212 -264.8204)
		(width 0.088646)
		(layer "In6.Cu")
		(net "M_G_CPU1_SA_CB<2>")
	)
	(arc
		(start 129.319274 -264.827512)
		(mid 129.13386 -264.875024)
		(end 128.949196 -264.824718)
		(width 0.088646)
		(layer "In6.Cu")
		(net "M_G_CPU1_SA_CB<2>")
	)
	(arc
		(start 139.272264 -264.816082)
		(mid 138.995789 -264.748762)
		(end 138.721592 -264.824718)
		(width 0.088646)
		(layer "In6.Cu")
		(net "M_G_CPU1_SA_CB<2>")
	)
	(arc
		(start 128.949196 -264.824718)
		(mid 128.813808 -264.768539)
		(end 128.668526 -264.749026)
		(width 0.088646)
		(layer "In6.Cu")
		(net "M_G_CPU1_SA_CB<2>")
	)
	(arc
		(start 139.73937 -264.765536)
		(mid 139.70232 -264.797682)
		(end 139.661392 -264.824718)
		(width 0.088646)
		(layer "In6.Cu")
		(net "M_G_CPU1_SA_CB<2>")
	)
	(segment
		(start 126.786894 -263.68629)
		(end 126.787148 -263.686544)
		(width 0.20066)
		(layer "F.Cu")
		(net "M_G_CPU1_SA_CB<1>")
	)
	(segment
		(start 191.421004 -277.277322)
		(end 191.233044 -277.465282)
		(width 0.20066)
		(layer "F.Cu")
		(net "M_G_CPU1_SA_CB<1>")
	)
	(segment
		(start 194.476116 -276.791674)
		(end 194.277742 -276.791674)
		(width 0.20066)
		(layer "F.Cu")
		(net "M_G_CPU1_SA_CB<1>")
	)
	(segment
		(start 194.277742 -276.791674)
		(end 194.241166 -276.791674)
		(width 0.101854)
		(layer "F.Cu")
		(net "M_G_CPU1_SA_CB<1>")
	)
	(segment
		(start 191.539114 -276.791674)
		(end 191.421004 -276.909784)
		(width 0.20066)
		(layer "F.Cu")
		(net "M_G_CPU1_SA_CB<1>")
	)
	(segment
		(start 191.421004 -276.909784)
		(end 191.421004 -277.277322)
		(width 0.20066)
		(layer "F.Cu")
		(net "M_G_CPU1_SA_CB<1>")
	)
	(segment
		(start 194.241166 -276.791674)
		(end 191.930782 -276.791674)
		(width 0.1016)
		(layer "F.Cu")
		(net "M_G_CPU1_SA_CB<1>")
	)
	(segment
		(start 191.786256 -276.791674)
		(end 191.539114 -276.791674)
		(width 0.20066)
		(layer "F.Cu")
		(net "M_G_CPU1_SA_CB<1>")
	)
	(segment
		(start 196.532246 -277.216616)
		(end 196.531992 -277.21687)
		(width 0.20066)
		(layer "F.Cu")
		(net "M_G_CPU1_SA_CB<1>")
	)
	(segment
		(start 126.786894 -263.150604)
		(end 126.786894 -263.68629)
		(width 0.20066)
		(layer "F.Cu")
		(net "M_G_CPU1_SA_CB<1>")
	)
	(segment
		(start 191.930782 -276.791674)
		(end 191.786256 -276.791674)
		(width 0.101854)
		(layer "F.Cu")
		(net "M_G_CPU1_SA_CB<1>")
	)
	(segment
		(start 190.509144 -277.216616)
		(end 188.988446 -277.216616)
		(width 0.20066)
		(layer "F.Cu")
		(net "M_G_CPU1_SA_CB<1>")
	)
	(segment
		(start 196.531992 -277.21687)
		(end 194.901312 -277.21687)
		(width 0.20066)
		(layer "F.Cu")
		(net "M_G_CPU1_SA_CB<1>")
	)
	(segment
		(start 194.901312 -277.21687)
		(end 194.476116 -276.791674)
		(width 0.20066)
		(layer "F.Cu")
		(net "M_G_CPU1_SA_CB<1>")
	)
	(segment
		(start 190.75781 -277.465282)
		(end 190.509144 -277.216616)
		(width 0.20066)
		(layer "F.Cu")
		(net "M_G_CPU1_SA_CB<1>")
	)
	(segment
		(start 191.233044 -277.465282)
		(end 190.75781 -277.465282)
		(width 0.20066)
		(layer "F.Cu")
		(net "M_G_CPU1_SA_CB<1>")
	)
	(segment
		(start 188.988446 -277.216616)
		(end 187.883546 -277.216616)
		(width 0.20066)
		(layer "F.Cu")
		(net "M_G_CPU1_SA_CB<1>")
	)
	(segment
		(start 180.783992 -273.151092)
		(end 180.783992 -272.823432)
		(width 0.18288)
		(layer "In6.Cu")
		(net "M_G_CPU1_SA_CB<1>")
	)
	(segment
		(start 179.79517 -270.773144)
		(end 179.79517 -269.335758)
		(width 0.18288)
		(layer "In6.Cu")
		(net "M_G_CPU1_SA_CB<1>")
	)
	(segment
		(start 175.549052 -269.13205)
		(end 175.404526 -269.276576)
		(width 0.18288)
		(layer "In6.Cu")
		(net "M_G_CPU1_SA_CB<1>")
	)
	(segment
		(start 140.291566 -263.672066)
		(end 139.838176 -264.125456)
		(width 0.088646)
		(layer "In6.Cu")
		(net "M_G_CPU1_SA_CB<1>")
	)
	(segment
		(start 171.116244 -267.441426)
		(end 170.806618 -267.751052)
		(width 0.18288)
		(layer "In6.Cu")
		(net "M_G_CPU1_SA_CB<1>")
	)
	(segment
		(start 133.088888 -264.179304)
		(end 133.083046 -264.175748)
		(width 0.088646)
		(layer "In6.Cu")
		(net "M_G_CPU1_SA_CB<1>")
	)
	(segment
		(start 170.806618 -267.751052)
		(end 170.126914 -267.751052)
		(width 0.18288)
		(layer "In6.Cu")
		(net "M_G_CPU1_SA_CB<1>")
	)
	(segment
		(start 178.362356 -269.13205)
		(end 175.549052 -269.13205)
		(width 0.18288)
		(layer "In6.Cu")
		(net "M_G_CPU1_SA_CB<1>")
	)
	(segment
		(start 132.143246 -264.175748)
		(end 132.137404 -264.172446)
		(width 0.088646)
		(layer "In6.Cu")
		(net "M_G_CPU1_SA_CB<1>")
	)
	(segment
		(start 138.347196 -264.176002)
		(end 138.332464 -264.184638)
		(width 0.088646)
		(layer "In6.Cu")
		(net "M_G_CPU1_SA_CB<1>")
	)
	(segment
		(start 174.432976 -269.276576)
		(end 173.737016 -268.580616)
		(width 0.18288)
		(layer "In6.Cu")
		(net "M_G_CPU1_SA_CB<1>")
	)
	(segment
		(start 173.902878 -267.674598)
		(end 173.669706 -267.441426)
		(width 0.18288)
		(layer "In6.Cu")
		(net "M_G_CPU1_SA_CB<1>")
	)
	(segment
		(start 163.279328 -267.546836)
		(end 163.096448 -267.729716)
		(width 0.18288)
		(layer "In6.Cu")
		(net "M_G_CPU1_SA_CB<1>")
	)
	(segment
		(start 180.783992 -272.823432)
		(end 180.601112 -272.640552)
		(width 0.18288)
		(layer "In6.Cu")
		(net "M_G_CPU1_SA_CB<1>")
	)
	(segment
		(start 179.79517 -271.832324)
		(end 179.97805 -271.649444)
		(width 0.18288)
		(layer "In6.Cu")
		(net "M_G_CPU1_SA_CB<1>")
	)
	(segment
		(start 140.595604 -263.672066)
		(end 140.291566 -263.672066)
		(width 0.088646)
		(layer "In6.Cu")
		(net "M_G_CPU1_SA_CB<1>")
	)
	(segment
		(start 155.128976 -264.16)
		(end 145.01749 -264.16)
		(width 0.18288)
		(layer "In6.Cu")
		(net "M_G_CPU1_SA_CB<1>")
	)
	(segment
		(start 162.585908 -267.546836)
		(end 162.585908 -267.304266)
		(width 0.18288)
		(layer "In6.Cu")
		(net "M_G_CPU1_SA_CB<1>")
	)
	(segment
		(start 180.551582 -274.966938)
		(end 179.79517 -274.210526)
		(width 0.18288)
		(layer "In6.Cu")
		(net "M_G_CPU1_SA_CB<1>")
	)
	(segment
		(start 162.585908 -267.304266)
		(end 162.403028 -267.121386)
		(width 0.18288)
		(layer "In6.Cu")
		(net "M_G_CPU1_SA_CB<1>")
	)
	(segment
		(start 179.79517 -273.516852)
		(end 179.97805 -273.333972)
		(width 0.18288)
		(layer "In6.Cu")
		(net "M_G_CPU1_SA_CB<1>")
	)
	(segment
		(start 179.97805 -273.333972)
		(end 180.601112 -273.333972)
		(width 0.18288)
		(layer "In6.Cu")
		(net "M_G_CPU1_SA_CB<1>")
	)
	(segment
		(start 165.418262 -267.541502)
		(end 164.585396 -267.541502)
		(width 0.18288)
		(layer "In6.Cu")
		(net "M_G_CPU1_SA_CB<1>")
	)
	(segment
		(start 163.462208 -267.121386)
		(end 163.279328 -267.304266)
		(width 0.18288)
		(layer "In6.Cu")
		(net "M_G_CPU1_SA_CB<1>")
	)
	(segment
		(start 132.149088 -264.179304)
		(end 132.143246 -264.175748)
		(width 0.088646)
		(layer "In6.Cu")
		(net "M_G_CPU1_SA_CB<1>")
	)
	(segment
		(start 159.773874 -267.656056)
		(end 158.53283 -266.415012)
		(width 0.18288)
		(layer "In6.Cu")
		(net "M_G_CPU1_SA_CB<1>")
	)
	(segment
		(start 142.564104 -263.672066)
		(end 140.595604 -263.672066)
		(width 0.18288)
		(layer "In6.Cu")
		(net "M_G_CPU1_SA_CB<1>")
	)
	(segment
		(start 173.902878 -267.998702)
		(end 173.902878 -267.674598)
		(width 0.18288)
		(layer "In6.Cu")
		(net "M_G_CPU1_SA_CB<1>")
	)
	(segment
		(start 179.79517 -274.210526)
		(end 179.79517 -273.516852)
		(width 0.18288)
		(layer "In6.Cu")
		(net "M_G_CPU1_SA_CB<1>")
	)
	(segment
		(start 133.083046 -264.175748)
		(end 133.077204 -264.172446)
		(width 0.088646)
		(layer "In6.Cu")
		(net "M_G_CPU1_SA_CB<1>")
	)
	(segment
		(start 179.79517 -272.457672)
		(end 179.79517 -271.832324)
		(width 0.18288)
		(layer "In6.Cu")
		(net "M_G_CPU1_SA_CB<1>")
	)
	(segment
		(start 179.79517 -269.335758)
		(end 179.288948 -268.829536)
		(width 0.18288)
		(layer "In6.Cu")
		(net "M_G_CPU1_SA_CB<1>")
	)
	(segment
		(start 180.76926 -271.138904)
		(end 180.58638 -270.956024)
		(width 0.18288)
		(layer "In6.Cu")
		(net "M_G_CPU1_SA_CB<1>")
	)
	(segment
		(start 130.269488 -264.179304)
		(end 130.263646 -264.175748)
		(width 0.088646)
		(layer "In6.Cu")
		(net "M_G_CPU1_SA_CB<1>")
	)
	(segment
		(start 168.413176 -267.309092)
		(end 167.588946 -266.484862)
		(width 0.18288)
		(layer "In6.Cu")
		(net "M_G_CPU1_SA_CB<1>")
	)
	(segment
		(start 133.648196 -264.176002)
		(end 133.648196 -264.175748)
		(width 0.088646)
		(layer "In6.Cu")
		(net "M_G_CPU1_SA_CB<1>")
	)
	(segment
		(start 134.587996 -264.176002)
		(end 134.573264 -264.184638)
		(width 0.088646)
		(layer "In6.Cu")
		(net "M_G_CPU1_SA_CB<1>")
	)
	(segment
		(start 162.768788 -267.729716)
		(end 162.585908 -267.546836)
		(width 0.18288)
		(layer "In6.Cu")
		(net "M_G_CPU1_SA_CB<1>")
	)
	(segment
		(start 164.585396 -267.541502)
		(end 164.16528 -267.121386)
		(width 0.18288)
		(layer "In6.Cu")
		(net "M_G_CPU1_SA_CB<1>")
	)
	(segment
		(start 166.474902 -266.484862)
		(end 165.418262 -267.541502)
		(width 0.18288)
		(layer "In6.Cu")
		(net "M_G_CPU1_SA_CB<1>")
	)
	(segment
		(start 179.288948 -268.829536)
		(end 178.66487 -268.829536)
		(width 0.18288)
		(layer "In6.Cu")
		(net "M_G_CPU1_SA_CB<1>")
	)
	(segment
		(start 128.022604 -264.083292)
		(end 127.543814 -264.083292)
		(width 0.088646)
		(layer "In6.Cu")
		(net "M_G_CPU1_SA_CB<1>")
	)
	(segment
		(start 131.203446 -264.175748)
		(end 131.197604 -264.172446)
		(width 0.088646)
		(layer "In6.Cu")
		(net "M_G_CPU1_SA_CB<1>")
	)
	(segment
		(start 161.136076 -267.121386)
		(end 160.601406 -267.656056)
		(width 0.18288)
		(layer "In6.Cu")
		(net "M_G_CPU1_SA_CB<1>")
	)
	(segment
		(start 187.883546 -277.216616)
		(end 187.353956 -276.687026)
		(width 0.18288)
		(layer "In6.Cu")
		(net "M_G_CPU1_SA_CB<1>")
	)
	(segment
		(start 185.905648 -276.687026)
		(end 185.296048 -276.077426)
		(width 0.18288)
		(layer "In6.Cu")
		(net "M_G_CPU1_SA_CB<1>")
	)
	(segment
		(start 163.279328 -267.304266)
		(end 163.279328 -267.546836)
		(width 0.18288)
		(layer "In6.Cu")
		(net "M_G_CPU1_SA_CB<1>")
	)
	(segment
		(start 130.263646 -264.175748)
		(end 130.257804 -264.172446)
		(width 0.088646)
		(layer "In6.Cu")
		(net "M_G_CPU1_SA_CB<1>")
	)
	(segment
		(start 158.53283 -266.415012)
		(end 157.383988 -266.415012)
		(width 0.18288)
		(layer "In6.Cu")
		(net "M_G_CPU1_SA_CB<1>")
	)
	(segment
		(start 145.01749 -264.16)
		(end 142.564104 -263.672066)
		(width 0.18288)
		(layer "In6.Cu")
		(net "M_G_CPU1_SA_CB<1>")
	)
	(segment
		(start 175.404526 -269.276576)
		(end 174.432976 -269.276576)
		(width 0.18288)
		(layer "In6.Cu")
		(net "M_G_CPU1_SA_CB<1>")
	)
	(segment
		(start 157.383988 -266.415012)
		(end 155.128976 -264.16)
		(width 0.18288)
		(layer "In6.Cu")
		(net "M_G_CPU1_SA_CB<1>")
	)
	(segment
		(start 131.209288 -264.179304)
		(end 131.203446 -264.175748)
		(width 0.088646)
		(layer "In6.Cu")
		(net "M_G_CPU1_SA_CB<1>")
	)
	(segment
		(start 178.66487 -268.829536)
		(end 178.362356 -269.13205)
		(width 0.18288)
		(layer "In6.Cu")
		(net "M_G_CPU1_SA_CB<1>")
	)
	(segment
		(start 162.403028 -267.121386)
		(end 161.136076 -267.121386)
		(width 0.18288)
		(layer "In6.Cu")
		(net "M_G_CPU1_SA_CB<1>")
	)
	(segment
		(start 179.97805 -271.649444)
		(end 180.58638 -271.649444)
		(width 0.18288)
		(layer "In6.Cu")
		(net "M_G_CPU1_SA_CB<1>")
	)
	(segment
		(start 185.296048 -276.077426)
		(end 184.01665 -276.077426)
		(width 0.18288)
		(layer "In6.Cu")
		(net "M_G_CPU1_SA_CB<1>")
	)
	(segment
		(start 180.601112 -273.333972)
		(end 180.783992 -273.151092)
		(width 0.18288)
		(layer "In6.Cu")
		(net "M_G_CPU1_SA_CB<1>")
	)
	(segment
		(start 182.906162 -274.966938)
		(end 180.551582 -274.966938)
		(width 0.18288)
		(layer "In6.Cu")
		(net "M_G_CPU1_SA_CB<1>")
	)
	(segment
		(start 167.588946 -266.484862)
		(end 166.474902 -266.484862)
		(width 0.18288)
		(layer "In6.Cu")
		(net "M_G_CPU1_SA_CB<1>")
	)
	(segment
		(start 129.323846 -264.175748)
		(end 129.318004 -264.172446)
		(width 0.088646)
		(layer "In6.Cu")
		(net "M_G_CPU1_SA_CB<1>")
	)
	(segment
		(start 180.58638 -270.956024)
		(end 179.97805 -270.956024)
		(width 0.18288)
		(layer "In6.Cu")
		(net "M_G_CPU1_SA_CB<1>")
	)
	(segment
		(start 173.737016 -268.164564)
		(end 173.902878 -267.998702)
		(width 0.18288)
		(layer "In6.Cu")
		(net "M_G_CPU1_SA_CB<1>")
	)
	(segment
		(start 169.684954 -267.309092)
		(end 168.413176 -267.309092)
		(width 0.18288)
		(layer "In6.Cu")
		(net "M_G_CPU1_SA_CB<1>")
	)
	(segment
		(start 163.096448 -267.729716)
		(end 162.768788 -267.729716)
		(width 0.18288)
		(layer "In6.Cu")
		(net "M_G_CPU1_SA_CB<1>")
	)
	(segment
		(start 129.329688 -264.179304)
		(end 129.323846 -264.175748)
		(width 0.088646)
		(layer "In6.Cu")
		(net "M_G_CPU1_SA_CB<1>")
	)
	(segment
		(start 180.58638 -271.649444)
		(end 180.76926 -271.466564)
		(width 0.18288)
		(layer "In6.Cu")
		(net "M_G_CPU1_SA_CB<1>")
	)
	(segment
		(start 160.601406 -267.656056)
		(end 159.773874 -267.656056)
		(width 0.18288)
		(layer "In6.Cu")
		(net "M_G_CPU1_SA_CB<1>")
	)
	(segment
		(start 170.126914 -267.751052)
		(end 169.684954 -267.309092)
		(width 0.18288)
		(layer "In6.Cu")
		(net "M_G_CPU1_SA_CB<1>")
	)
	(segment
		(start 180.601112 -272.640552)
		(end 179.97805 -272.640552)
		(width 0.18288)
		(layer "In6.Cu")
		(net "M_G_CPU1_SA_CB<1>")
	)
	(segment
		(start 173.669706 -267.441426)
		(end 171.116244 -267.441426)
		(width 0.18288)
		(layer "In6.Cu")
		(net "M_G_CPU1_SA_CB<1>")
	)
	(segment
		(start 139.286996 -264.176002)
		(end 139.272264 -264.184638)
		(width 0.088646)
		(layer "In6.Cu")
		(net "M_G_CPU1_SA_CB<1>")
	)
	(segment
		(start 184.01665 -276.077426)
		(end 182.906162 -274.966938)
		(width 0.18288)
		(layer "In6.Cu")
		(net "M_G_CPU1_SA_CB<1>")
	)
	(segment
		(start 179.97805 -272.640552)
		(end 179.79517 -272.457672)
		(width 0.18288)
		(layer "In6.Cu")
		(net "M_G_CPU1_SA_CB<1>")
	)
	(segment
		(start 173.737016 -268.580616)
		(end 173.737016 -268.164564)
		(width 0.18288)
		(layer "In6.Cu")
		(net "M_G_CPU1_SA_CB<1>")
	)
	(segment
		(start 187.353956 -276.687026)
		(end 185.905648 -276.687026)
		(width 0.18288)
		(layer "In6.Cu")
		(net "M_G_CPU1_SA_CB<1>")
	)
	(segment
		(start 179.97805 -270.956024)
		(end 179.79517 -270.773144)
		(width 0.18288)
		(layer "In6.Cu")
		(net "M_G_CPU1_SA_CB<1>")
	)
	(segment
		(start 180.76926 -271.466564)
		(end 180.76926 -271.138904)
		(width 0.18288)
		(layer "In6.Cu")
		(net "M_G_CPU1_SA_CB<1>")
	)
	(segment
		(start 139.838176 -264.125456)
		(end 139.474194 -264.125456)
		(width 0.088646)
		(layer "In6.Cu")
		(net "M_G_CPU1_SA_CB<1>")
	)
	(segment
		(start 164.16528 -267.121386)
		(end 163.462208 -267.121386)
		(width 0.18288)
		(layer "In6.Cu")
		(net "M_G_CPU1_SA_CB<1>")
	)
	(arc
		(start 130.257804 -264.172446)
		(mid 130.072949 -264.125528)
		(end 129.888996 -264.175748)
		(width 0.088646)
		(layer "In6.Cu")
		(net "M_G_CPU1_SA_CB<1>")
	)
	(arc
		(start 130.828796 -264.175748)
		(mid 130.549622 -264.251513)
		(end 130.269488 -264.179304)
		(width 0.088646)
		(layer "In6.Cu")
		(net "M_G_CPU1_SA_CB<1>")
	)
	(arc
		(start 139.272264 -264.184638)
		(mid 138.995789 -264.251958)
		(end 138.721592 -264.176002)
		(width 0.088646)
		(layer "In6.Cu")
		(net "M_G_CPU1_SA_CB<1>")
	)
	(arc
		(start 128.949196 -264.175748)
		(mid 128.670022 -264.251513)
		(end 128.389888 -264.179304)
		(width 0.088646)
		(layer "In6.Cu")
		(net "M_G_CPU1_SA_CB<1>")
	)
	(arc
		(start 127.543814 -264.083292)
		(mid 127.116621 -263.978095)
		(end 126.787148 -263.686544)
		(width 0.088646)
		(layer "In6.Cu")
		(net "M_G_CPU1_SA_CB<1>")
	)
	(arc
		(start 134.573264 -264.184638)
		(mid 134.296789 -264.251958)
		(end 134.022592 -264.176002)
		(width 0.088646)
		(layer "In6.Cu")
		(net "M_G_CPU1_SA_CB<1>")
	)
	(arc
		(start 139.474194 -264.125456)
		(mid 139.377271 -264.138414)
		(end 139.286996 -264.176002)
		(width 0.088646)
		(layer "In6.Cu")
		(net "M_G_CPU1_SA_CB<1>")
	)
	(arc
		(start 129.318004 -264.172446)
		(mid 129.133149 -264.125528)
		(end 128.949196 -264.175748)
		(width 0.088646)
		(layer "In6.Cu")
		(net "M_G_CPU1_SA_CB<1>")
	)
	(arc
		(start 135.527796 -264.176002)
		(mid 135.245094 -264.251778)
		(end 134.962392 -264.176002)
		(width 0.088646)
		(layer "In6.Cu")
		(net "M_G_CPU1_SA_CB<1>")
	)
	(arc
		(start 129.888996 -264.175748)
		(mid 129.609822 -264.251513)
		(end 129.329688 -264.179304)
		(width 0.088646)
		(layer "In6.Cu")
		(net "M_G_CPU1_SA_CB<1>")
	)
	(arc
		(start 134.962392 -264.176002)
		(mid 134.775194 -264.125859)
		(end 134.587996 -264.176002)
		(width 0.088646)
		(layer "In6.Cu")
		(net "M_G_CPU1_SA_CB<1>")
	)
	(arc
		(start 132.137404 -264.172446)
		(mid 131.952549 -264.125528)
		(end 131.768596 -264.175748)
		(width 0.088646)
		(layer "In6.Cu")
		(net "M_G_CPU1_SA_CB<1>")
	)
	(arc
		(start 138.332464 -264.184638)
		(mid 138.055989 -264.251958)
		(end 137.781792 -264.176002)
		(width 0.088646)
		(layer "In6.Cu")
		(net "M_G_CPU1_SA_CB<1>")
	)
	(arc
		(start 137.781792 -264.176002)
		(mid 137.594594 -264.125859)
		(end 137.407396 -264.176002)
		(width 0.088646)
		(layer "In6.Cu")
		(net "M_G_CPU1_SA_CB<1>")
	)
	(arc
		(start 136.841992 -264.176002)
		(mid 136.654794 -264.125859)
		(end 136.467596 -264.176002)
		(width 0.088646)
		(layer "In6.Cu")
		(net "M_G_CPU1_SA_CB<1>")
	)
	(arc
		(start 138.721592 -264.176002)
		(mid 138.534394 -264.125859)
		(end 138.347196 -264.176002)
		(width 0.088646)
		(layer "In6.Cu")
		(net "M_G_CPU1_SA_CB<1>")
	)
	(arc
		(start 136.467596 -264.176002)
		(mid 136.184894 -264.251778)
		(end 135.902192 -264.176002)
		(width 0.088646)
		(layer "In6.Cu")
		(net "M_G_CPU1_SA_CB<1>")
	)
	(arc
		(start 134.022592 -264.176002)
		(mid 133.835394 -264.125859)
		(end 133.648196 -264.176002)
		(width 0.088646)
		(layer "In6.Cu")
		(net "M_G_CPU1_SA_CB<1>")
	)
	(arc
		(start 135.902192 -264.176002)
		(mid 135.714994 -264.125859)
		(end 135.527796 -264.176002)
		(width 0.088646)
		(layer "In6.Cu")
		(net "M_G_CPU1_SA_CB<1>")
	)
	(arc
		(start 132.708396 -264.175748)
		(mid 132.429222 -264.251513)
		(end 132.149088 -264.179304)
		(width 0.088646)
		(layer "In6.Cu")
		(net "M_G_CPU1_SA_CB<1>")
	)
	(arc
		(start 131.768596 -264.175748)
		(mid 131.489422 -264.251513)
		(end 131.209288 -264.179304)
		(width 0.088646)
		(layer "In6.Cu")
		(net "M_G_CPU1_SA_CB<1>")
	)
	(arc
		(start 133.648196 -264.175748)
		(mid 133.369022 -264.251513)
		(end 133.088888 -264.179304)
		(width 0.088646)
		(layer "In6.Cu")
		(net "M_G_CPU1_SA_CB<1>")
	)
	(arc
		(start 137.407396 -264.176002)
		(mid 137.124694 -264.251778)
		(end 136.841992 -264.176002)
		(width 0.088646)
		(layer "In6.Cu")
		(net "M_G_CPU1_SA_CB<1>")
	)
	(arc
		(start 133.077204 -264.172446)
		(mid 132.892349 -264.125528)
		(end 132.708396 -264.175748)
		(width 0.088646)
		(layer "In6.Cu")
		(net "M_G_CPU1_SA_CB<1>")
	)
	(arc
		(start 128.389888 -264.179304)
		(mid 128.212412 -264.107721)
		(end 128.022604 -264.083292)
		(width 0.088646)
		(layer "In6.Cu")
		(net "M_G_CPU1_SA_CB<1>")
	)
	(arc
		(start 131.197604 -264.172446)
		(mid 131.012749 -264.125528)
		(end 130.828796 -264.175748)
		(width 0.088646)
		(layer "In6.Cu")
		(net "M_G_CPU1_SA_CB<1>")
	)
	(segment
		(start 188.988446 -278.916638)
		(end 187.883546 -278.916638)
		(width 0.20066)
		(layer "F.Cu")
		(net "M_G_CPU1_SA_CB<0>")
	)
	(segment
		(start 196.531992 -278.916892)
		(end 194.901312 -278.916892)
		(width 0.20066)
		(layer "F.Cu")
		(net "M_G_CPU1_SA_CB<0>")
	)
	(segment
		(start 127.257048 -264.500106)
		(end 127.256794 -264.50036)
		(width 0.20066)
		(layer "F.Cu")
		(net "M_G_CPU1_SA_CB<0>")
	)
	(segment
		(start 190.75781 -279.165304)
		(end 190.509144 -278.916638)
		(width 0.20066)
		(layer "F.Cu")
		(net "M_G_CPU1_SA_CB<0>")
	)
	(segment
		(start 191.233044 -279.165304)
		(end 190.75781 -279.165304)
		(width 0.20066)
		(layer "F.Cu")
		(net "M_G_CPU1_SA_CB<0>")
	)
	(segment
		(start 190.509144 -278.916638)
		(end 188.988446 -278.916638)
		(width 0.20066)
		(layer "F.Cu")
		(net "M_G_CPU1_SA_CB<0>")
	)
	(segment
		(start 191.421004 -278.977344)
		(end 191.233044 -279.165304)
		(width 0.20066)
		(layer "F.Cu")
		(net "M_G_CPU1_SA_CB<0>")
	)
	(segment
		(start 194.277742 -278.491696)
		(end 194.241166 -278.491696)
		(width 0.101854)
		(layer "F.Cu")
		(net "M_G_CPU1_SA_CB<0>")
	)
	(segment
		(start 191.930782 -278.491696)
		(end 191.786256 -278.491696)
		(width 0.101854)
		(layer "F.Cu")
		(net "M_G_CPU1_SA_CB<0>")
	)
	(segment
		(start 127.257048 -263.96442)
		(end 127.257048 -264.500106)
		(width 0.20066)
		(layer "F.Cu")
		(net "M_G_CPU1_SA_CB<0>")
	)
	(segment
		(start 194.476116 -278.491696)
		(end 194.277742 -278.491696)
		(width 0.20066)
		(layer "F.Cu")
		(net "M_G_CPU1_SA_CB<0>")
	)
	(segment
		(start 194.901312 -278.916892)
		(end 194.476116 -278.491696)
		(width 0.20066)
		(layer "F.Cu")
		(net "M_G_CPU1_SA_CB<0>")
	)
	(segment
		(start 196.532246 -278.916638)
		(end 196.531992 -278.916892)
		(width 0.20066)
		(layer "F.Cu")
		(net "M_G_CPU1_SA_CB<0>")
	)
	(segment
		(start 194.241166 -278.491696)
		(end 191.930782 -278.491696)
		(width 0.1016)
		(layer "F.Cu")
		(net "M_G_CPU1_SA_CB<0>")
	)
	(segment
		(start 191.539114 -278.491696)
		(end 191.421004 -278.609806)
		(width 0.20066)
		(layer "F.Cu")
		(net "M_G_CPU1_SA_CB<0>")
	)
	(segment
		(start 191.421004 -278.609806)
		(end 191.421004 -278.977344)
		(width 0.20066)
		(layer "F.Cu")
		(net "M_G_CPU1_SA_CB<0>")
	)
	(segment
		(start 191.786256 -278.491696)
		(end 191.539114 -278.491696)
		(width 0.20066)
		(layer "F.Cu")
		(net "M_G_CPU1_SA_CB<0>")
	)
	(segment
		(start 177.82794 -272.138902)
		(end 177.98796 -271.978882)
		(width 0.18288)
		(layer "In6.Cu")
		(net "M_G_CPU1_SA_CB<0>")
	)
	(segment
		(start 165.782498 -270.148812)
		(end 165.599618 -269.965932)
		(width 0.18288)
		(layer "In6.Cu")
		(net "M_G_CPU1_SA_CB<0>")
	)
	(segment
		(start 128.479296 -264.989818)
		(end 128.47193 -264.994136)
		(width 0.088646)
		(layer "In6.Cu")
		(net "M_G_CPU1_SA_CB<0>")
	)
	(segment
		(start 131.303268 -264.987024)
		(end 131.298696 -264.989818)
		(width 0.088646)
		(layer "In6.Cu")
		(net "M_G_CPU1_SA_CB<0>")
	)
	(segment
		(start 140.10259 -264.671556)
		(end 139.87399 -264.900156)
		(width 0.088646)
		(layer "In6.Cu")
		(net "M_G_CPU1_SA_CB<0>")
	)
	(segment
		(start 158.469838 -268.23543)
		(end 157.603698 -268.23543)
		(width 0.18288)
		(layer "In6.Cu")
		(net "M_G_CPU1_SA_CB<0>")
	)
	(segment
		(start 172.046138 -270.832072)
		(end 171.718478 -270.832072)
		(width 0.18288)
		(layer "In6.Cu")
		(net "M_G_CPU1_SA_CB<0>")
	)
	(segment
		(start 160.292796 -269.312644)
		(end 160.292796 -269.808452)
		(width 0.18288)
		(layer "In6.Cu")
		(net "M_G_CPU1_SA_CB<0>")
	)
	(segment
		(start 183.79313 -277.999444)
		(end 183.79313 -277.334218)
		(width 0.18288)
		(layer "In6.Cu")
		(net "M_G_CPU1_SA_CB<0>")
	)
	(segment
		(start 177.546 -273.525742)
		(end 177.82794 -273.525742)
		(width 0.18288)
		(layer "In6.Cu")
		(net "M_G_CPU1_SA_CB<0>")
	)
	(segment
		(start 177.82794 -273.525742)
		(end 177.98796 -273.365722)
		(width 0.18288)
		(layer "In6.Cu")
		(net "M_G_CPU1_SA_CB<0>")
	)
	(segment
		(start 179.922424 -277.08733)
		(end 177.98796 -275.152866)
		(width 0.18288)
		(layer "In6.Cu")
		(net "M_G_CPU1_SA_CB<0>")
	)
	(segment
		(start 160.465262 -269.140178)
		(end 160.292796 -269.312644)
		(width 0.18288)
		(layer "In6.Cu")
		(net "M_G_CPU1_SA_CB<0>")
	)
	(segment
		(start 187.541662 -278.325834)
		(end 184.11952 -278.325834)
		(width 0.18288)
		(layer "In6.Cu")
		(net "M_G_CPU1_SA_CB<0>")
	)
	(segment
		(start 131.298696 -264.989818)
		(end 131.29133 -264.994136)
		(width 0.088646)
		(layer "In6.Cu")
		(net "M_G_CPU1_SA_CB<0>")
	)
	(segment
		(start 136.387078 -264.998454)
		(end 136.372346 -264.989818)
		(width 0.088646)
		(layer "In6.Cu")
		(net "M_G_CPU1_SA_CB<0>")
	)
	(segment
		(start 171.535598 -270.175482)
		(end 171.352718 -269.992602)
		(width 0.18288)
		(layer "In6.Cu")
		(net "M_G_CPU1_SA_CB<0>")
	)
	(segment
		(start 142.45971 -264.671556)
		(end 140.595604 -264.671556)
		(width 0.18288)
		(layer "In6.Cu")
		(net "M_G_CPU1_SA_CB<0>")
	)
	(segment
		(start 134.118096 -264.989818)
		(end 134.11073 -264.994136)
		(width 0.088646)
		(layer "In6.Cu")
		(net "M_G_CPU1_SA_CB<0>")
	)
	(segment
		(start 134.122668 -264.987024)
		(end 134.118096 -264.989818)
		(width 0.088646)
		(layer "In6.Cu")
		(net "M_G_CPU1_SA_CB<0>")
	)
	(segment
		(start 166.293038 -269.965932)
		(end 166.110158 -270.148812)
		(width 0.18288)
		(layer "In6.Cu")
		(net "M_G_CPU1_SA_CB<0>")
	)
	(segment
		(start 140.595604 -264.671556)
		(end 140.10259 -264.671556)
		(width 0.088646)
		(layer "In6.Cu")
		(net "M_G_CPU1_SA_CB<0>")
	)
	(segment
		(start 165.599618 -269.965932)
		(end 165.599618 -269.323058)
		(width 0.18288)
		(layer "In6.Cu")
		(net "M_G_CPU1_SA_CB<0>")
	)
	(segment
		(start 134.507478 -264.998454)
		(end 134.492746 -264.989818)
		(width 0.088646)
		(layer "In6.Cu")
		(net "M_G_CPU1_SA_CB<0>")
	)
	(segment
		(start 167.690292 -269.323058)
		(end 167.507412 -269.140178)
		(width 0.18288)
		(layer "In6.Cu")
		(net "M_G_CPU1_SA_CB<0>")
	)
	(segment
		(start 183.546242 -277.08733)
		(end 179.922424 -277.08733)
		(width 0.18288)
		(layer "In6.Cu")
		(net "M_G_CPU1_SA_CB<0>")
	)
	(segment
		(start 154.56027 -265.192002)
		(end 145.076672 -265.192002)
		(width 0.18288)
		(layer "In6.Cu")
		(net "M_G_CPU1_SA_CB<0>")
	)
	(segment
		(start 171.718478 -270.832072)
		(end 171.535598 -270.649192)
		(width 0.18288)
		(layer "In6.Cu")
		(net "M_G_CPU1_SA_CB<0>")
	)
	(segment
		(start 130.363468 -264.987024)
		(end 130.358896 -264.989818)
		(width 0.088646)
		(layer "In6.Cu")
		(net "M_G_CPU1_SA_CB<0>")
	)
	(segment
		(start 168.200832 -269.860522)
		(end 167.873172 -269.860522)
		(width 0.18288)
		(layer "In6.Cu")
		(net "M_G_CPU1_SA_CB<0>")
	)
	(segment
		(start 159.599376 -269.312644)
		(end 159.439356 -269.152624)
		(width 0.18288)
		(layer "In6.Cu")
		(net "M_G_CPU1_SA_CB<0>")
	)
	(segment
		(start 183.79313 -277.334218)
		(end 183.546242 -277.08733)
		(width 0.18288)
		(layer "In6.Cu")
		(net "M_G_CPU1_SA_CB<0>")
	)
	(segment
		(start 171.535598 -270.649192)
		(end 171.535598 -270.175482)
		(width 0.18288)
		(layer "In6.Cu")
		(net "M_G_CPU1_SA_CB<0>")
	)
	(segment
		(start 174.248318 -270.841724)
		(end 173.399196 -269.992602)
		(width 0.18288)
		(layer "In6.Cu")
		(net "M_G_CPU1_SA_CB<0>")
	)
	(segment
		(start 160.132776 -269.968472)
		(end 159.759396 -269.968472)
		(width 0.18288)
		(layer "In6.Cu")
		(net "M_G_CPU1_SA_CB<0>")
	)
	(segment
		(start 177.98796 -271.295368)
		(end 177.534316 -270.841724)
		(width 0.18288)
		(layer "In6.Cu")
		(net "M_G_CPU1_SA_CB<0>")
	)
	(segment
		(start 177.98796 -275.152866)
		(end 177.98796 -274.379182)
		(width 0.18288)
		(layer "In6.Cu")
		(net "M_G_CPU1_SA_CB<0>")
	)
	(segment
		(start 187.883546 -278.667718)
		(end 187.541662 -278.325834)
		(width 0.18288)
		(layer "In6.Cu")
		(net "M_G_CPU1_SA_CB<0>")
	)
	(segment
		(start 159.439356 -269.152624)
		(end 159.387032 -269.152624)
		(width 0.18288)
		(layer "In6.Cu")
		(net "M_G_CPU1_SA_CB<0>")
	)
	(segment
		(start 177.82794 -274.219162)
		(end 177.546 -274.219162)
		(width 0.18288)
		(layer "In6.Cu")
		(net "M_G_CPU1_SA_CB<0>")
	)
	(segment
		(start 177.98796 -274.379182)
		(end 177.82794 -274.219162)
		(width 0.18288)
		(layer "In6.Cu")
		(net "M_G_CPU1_SA_CB<0>")
	)
	(segment
		(start 167.873172 -269.860522)
		(end 167.690292 -269.677642)
		(width 0.18288)
		(layer "In6.Cu")
		(net "M_G_CPU1_SA_CB<0>")
	)
	(segment
		(start 172.411898 -269.992602)
		(end 172.229018 -270.175482)
		(width 0.18288)
		(layer "In6.Cu")
		(net "M_G_CPU1_SA_CB<0>")
	)
	(segment
		(start 177.82794 -272.832322)
		(end 177.546 -272.832322)
		(width 0.18288)
		(layer "In6.Cu")
		(net "M_G_CPU1_SA_CB<0>")
	)
	(segment
		(start 168.566592 -269.140178)
		(end 168.383712 -269.323058)
		(width 0.18288)
		(layer "In6.Cu")
		(net "M_G_CPU1_SA_CB<0>")
	)
	(segment
		(start 177.98796 -271.978882)
		(end 177.98796 -271.295368)
		(width 0.18288)
		(layer "In6.Cu")
		(net "M_G_CPU1_SA_CB<0>")
	)
	(segment
		(start 187.883546 -278.916638)
		(end 187.883546 -278.667718)
		(width 0.18288)
		(layer "In6.Cu")
		(net "M_G_CPU1_SA_CB<0>")
	)
	(segment
		(start 177.98796 -272.992342)
		(end 177.82794 -272.832322)
		(width 0.18288)
		(layer "In6.Cu")
		(net "M_G_CPU1_SA_CB<0>")
	)
	(segment
		(start 177.546 -272.832322)
		(end 177.38598 -272.672302)
		(width 0.18288)
		(layer "In6.Cu")
		(net "M_G_CPU1_SA_CB<0>")
	)
	(segment
		(start 132.238496 -264.989818)
		(end 132.23113 -264.994136)
		(width 0.088646)
		(layer "In6.Cu")
		(net "M_G_CPU1_SA_CB<0>")
	)
	(segment
		(start 177.534316 -270.841724)
		(end 174.248318 -270.841724)
		(width 0.18288)
		(layer "In6.Cu")
		(net "M_G_CPU1_SA_CB<0>")
	)
	(segment
		(start 165.416738 -269.140178)
		(end 160.465262 -269.140178)
		(width 0.18288)
		(layer "In6.Cu")
		(net "M_G_CPU1_SA_CB<0>")
	)
	(segment
		(start 171.352718 -269.992602)
		(end 171.02455 -269.992602)
		(width 0.18288)
		(layer "In6.Cu")
		(net "M_G_CPU1_SA_CB<0>")
	)
	(segment
		(start 157.603698 -268.23543)
		(end 154.56027 -265.192002)
		(width 0.18288)
		(layer "In6.Cu")
		(net "M_G_CPU1_SA_CB<0>")
	)
	(segment
		(start 168.383712 -269.677642)
		(end 168.200832 -269.860522)
		(width 0.18288)
		(layer "In6.Cu")
		(net "M_G_CPU1_SA_CB<0>")
	)
	(segment
		(start 166.475918 -269.140178)
		(end 166.293038 -269.323058)
		(width 0.18288)
		(layer "In6.Cu")
		(net "M_G_CPU1_SA_CB<0>")
	)
	(segment
		(start 129.423668 -264.987024)
		(end 129.419096 -264.989818)
		(width 0.088646)
		(layer "In6.Cu")
		(net "M_G_CPU1_SA_CB<0>")
	)
	(segment
		(start 133.182868 -264.987024)
		(end 133.178296 -264.989818)
		(width 0.088646)
		(layer "In6.Cu")
		(net "M_G_CPU1_SA_CB<0>")
	)
	(segment
		(start 184.11952 -278.325834)
		(end 183.79313 -277.999444)
		(width 0.18288)
		(layer "In6.Cu")
		(net "M_G_CPU1_SA_CB<0>")
	)
	(segment
		(start 167.690292 -269.677642)
		(end 167.690292 -269.323058)
		(width 0.18288)
		(layer "In6.Cu")
		(net "M_G_CPU1_SA_CB<0>")
	)
	(segment
		(start 166.110158 -270.148812)
		(end 165.782498 -270.148812)
		(width 0.18288)
		(layer "In6.Cu")
		(net "M_G_CPU1_SA_CB<0>")
	)
	(segment
		(start 165.599618 -269.323058)
		(end 165.416738 -269.140178)
		(width 0.18288)
		(layer "In6.Cu")
		(net "M_G_CPU1_SA_CB<0>")
	)
	(segment
		(start 135.447278 -264.998454)
		(end 135.432546 -264.989818)
		(width 0.088646)
		(layer "In6.Cu")
		(net "M_G_CPU1_SA_CB<0>")
	)
	(segment
		(start 172.229018 -270.175482)
		(end 172.229018 -270.649192)
		(width 0.18288)
		(layer "In6.Cu")
		(net "M_G_CPU1_SA_CB<0>")
	)
	(segment
		(start 170.172126 -269.140178)
		(end 168.566592 -269.140178)
		(width 0.18288)
		(layer "In6.Cu")
		(net "M_G_CPU1_SA_CB<0>")
	)
	(segment
		(start 167.507412 -269.140178)
		(end 166.475918 -269.140178)
		(width 0.18288)
		(layer "In6.Cu")
		(net "M_G_CPU1_SA_CB<0>")
	)
	(segment
		(start 160.292796 -269.808452)
		(end 160.132776 -269.968472)
		(width 0.18288)
		(layer "In6.Cu")
		(net "M_G_CPU1_SA_CB<0>")
	)
	(segment
		(start 177.38598 -274.059142)
		(end 177.38598 -273.685762)
		(width 0.18288)
		(layer "In6.Cu")
		(net "M_G_CPU1_SA_CB<0>")
	)
	(segment
		(start 138.266678 -264.998454)
		(end 138.251946 -264.989818)
		(width 0.088646)
		(layer "In6.Cu")
		(net "M_G_CPU1_SA_CB<0>")
	)
	(segment
		(start 159.387032 -269.152624)
		(end 158.469838 -268.23543)
		(width 0.18288)
		(layer "In6.Cu")
		(net "M_G_CPU1_SA_CB<0>")
	)
	(segment
		(start 159.759396 -269.968472)
		(end 159.599376 -269.808452)
		(width 0.18288)
		(layer "In6.Cu")
		(net "M_G_CPU1_SA_CB<0>")
	)
	(segment
		(start 130.358896 -264.989818)
		(end 130.35153 -264.994136)
		(width 0.088646)
		(layer "In6.Cu")
		(net "M_G_CPU1_SA_CB<0>")
	)
	(segment
		(start 132.243068 -264.987024)
		(end 132.238496 -264.989818)
		(width 0.088646)
		(layer "In6.Cu")
		(net "M_G_CPU1_SA_CB<0>")
	)
	(segment
		(start 172.229018 -270.649192)
		(end 172.046138 -270.832072)
		(width 0.18288)
		(layer "In6.Cu")
		(net "M_G_CPU1_SA_CB<0>")
	)
	(segment
		(start 129.419096 -264.989818)
		(end 129.41173 -264.994136)
		(width 0.088646)
		(layer "In6.Cu")
		(net "M_G_CPU1_SA_CB<0>")
	)
	(segment
		(start 171.02455 -269.992602)
		(end 170.172126 -269.140178)
		(width 0.18288)
		(layer "In6.Cu")
		(net "M_G_CPU1_SA_CB<0>")
	)
	(segment
		(start 166.293038 -269.323058)
		(end 166.293038 -269.965932)
		(width 0.18288)
		(layer "In6.Cu")
		(net "M_G_CPU1_SA_CB<0>")
	)
	(segment
		(start 139.206478 -264.998454)
		(end 139.191746 -264.989818)
		(width 0.088646)
		(layer "In6.Cu")
		(net "M_G_CPU1_SA_CB<0>")
	)
	(segment
		(start 177.98796 -273.365722)
		(end 177.98796 -272.992342)
		(width 0.18288)
		(layer "In6.Cu")
		(net "M_G_CPU1_SA_CB<0>")
	)
	(segment
		(start 137.326878 -264.998454)
		(end 137.312146 -264.989818)
		(width 0.088646)
		(layer "In6.Cu")
		(net "M_G_CPU1_SA_CB<0>")
	)
	(segment
		(start 173.399196 -269.992602)
		(end 172.411898 -269.992602)
		(width 0.18288)
		(layer "In6.Cu")
		(net "M_G_CPU1_SA_CB<0>")
	)
	(segment
		(start 168.383712 -269.323058)
		(end 168.383712 -269.677642)
		(width 0.18288)
		(layer "In6.Cu")
		(net "M_G_CPU1_SA_CB<0>")
	)
	(segment
		(start 177.38598 -273.685762)
		(end 177.546 -273.525742)
		(width 0.18288)
		(layer "In6.Cu")
		(net "M_G_CPU1_SA_CB<0>")
	)
	(segment
		(start 177.546 -274.219162)
		(end 177.38598 -274.059142)
		(width 0.18288)
		(layer "In6.Cu")
		(net "M_G_CPU1_SA_CB<0>")
	)
	(segment
		(start 133.178296 -264.989818)
		(end 133.17093 -264.994136)
		(width 0.088646)
		(layer "In6.Cu")
		(net "M_G_CPU1_SA_CB<0>")
	)
	(segment
		(start 128.483868 -264.987024)
		(end 128.479296 -264.989818)
		(width 0.088646)
		(layer "In6.Cu")
		(net "M_G_CPU1_SA_CB<0>")
	)
	(segment
		(start 159.599376 -269.808452)
		(end 159.599376 -269.312644)
		(width 0.18288)
		(layer "In6.Cu")
		(net "M_G_CPU1_SA_CB<0>")
	)
	(segment
		(start 177.38598 -272.298922)
		(end 177.546 -272.138902)
		(width 0.18288)
		(layer "In6.Cu")
		(net "M_G_CPU1_SA_CB<0>")
	)
	(segment
		(start 177.38598 -272.672302)
		(end 177.38598 -272.298922)
		(width 0.18288)
		(layer "In6.Cu")
		(net "M_G_CPU1_SA_CB<0>")
	)
	(segment
		(start 177.546 -272.138902)
		(end 177.82794 -272.138902)
		(width 0.18288)
		(layer "In6.Cu")
		(net "M_G_CPU1_SA_CB<0>")
	)
	(segment
		(start 145.076672 -265.192002)
		(end 142.45971 -264.671556)
		(width 0.18288)
		(layer "In6.Cu")
		(net "M_G_CPU1_SA_CB<0>")
	)
	(arc
		(start 130.35153 -264.994136)
		(mid 130.072069 -265.065573)
		(end 129.793746 -264.989818)
		(width 0.088646)
		(layer "In6.Cu")
		(net "M_G_CPU1_SA_CB<0>")
	)
	(arc
		(start 129.793746 -264.989818)
		(mid 129.609082 -264.939558)
		(end 129.423668 -264.987024)
		(width 0.088646)
		(layer "In6.Cu")
		(net "M_G_CPU1_SA_CB<0>")
	)
	(arc
		(start 132.23113 -264.994136)
		(mid 131.951669 -265.065573)
		(end 131.673346 -264.989818)
		(width 0.088646)
		(layer "In6.Cu")
		(net "M_G_CPU1_SA_CB<0>")
	)
	(arc
		(start 137.87755 -264.989818)
		(mid 137.603351 -265.065653)
		(end 137.326878 -264.998454)
		(width 0.088646)
		(layer "In6.Cu")
		(net "M_G_CPU1_SA_CB<0>")
	)
	(arc
		(start 139.87399 -264.900156)
		(mid 139.55651 -265.059733)
		(end 139.206478 -264.998454)
		(width 0.088646)
		(layer "In6.Cu")
		(net "M_G_CPU1_SA_CB<0>")
	)
	(arc
		(start 129.41173 -264.994136)
		(mid 129.132269 -265.065573)
		(end 128.853946 -264.989818)
		(width 0.088646)
		(layer "In6.Cu")
		(net "M_G_CPU1_SA_CB<0>")
	)
	(arc
		(start 135.05815 -264.989818)
		(mid 134.783951 -265.065653)
		(end 134.507478 -264.998454)
		(width 0.088646)
		(layer "In6.Cu")
		(net "M_G_CPU1_SA_CB<0>")
	)
	(arc
		(start 139.191746 -264.989818)
		(mid 139.004548 -264.939675)
		(end 138.81735 -264.989818)
		(width 0.088646)
		(layer "In6.Cu")
		(net "M_G_CPU1_SA_CB<0>")
	)
	(arc
		(start 136.372346 -264.989818)
		(mid 136.185148 -264.939675)
		(end 135.99795 -264.989818)
		(width 0.088646)
		(layer "In6.Cu")
		(net "M_G_CPU1_SA_CB<0>")
	)
	(arc
		(start 128.47193 -264.994136)
		(mid 128.192469 -265.065573)
		(end 127.914146 -264.989818)
		(width 0.088646)
		(layer "In6.Cu")
		(net "M_G_CPU1_SA_CB<0>")
	)
	(arc
		(start 132.613146 -264.989818)
		(mid 132.428482 -264.939558)
		(end 132.243068 -264.987024)
		(width 0.088646)
		(layer "In6.Cu")
		(net "M_G_CPU1_SA_CB<0>")
	)
	(arc
		(start 133.552946 -264.989818)
		(mid 133.368282 -264.939558)
		(end 133.182868 -264.987024)
		(width 0.088646)
		(layer "In6.Cu")
		(net "M_G_CPU1_SA_CB<0>")
	)
	(arc
		(start 131.29133 -264.994136)
		(mid 131.011869 -265.065573)
		(end 130.733546 -264.989818)
		(width 0.088646)
		(layer "In6.Cu")
		(net "M_G_CPU1_SA_CB<0>")
	)
	(arc
		(start 130.733546 -264.989818)
		(mid 130.548882 -264.939558)
		(end 130.363468 -264.987024)
		(width 0.088646)
		(layer "In6.Cu")
		(net "M_G_CPU1_SA_CB<0>")
	)
	(arc
		(start 135.99795 -264.989818)
		(mid 135.723751 -265.065653)
		(end 135.447278 -264.998454)
		(width 0.088646)
		(layer "In6.Cu")
		(net "M_G_CPU1_SA_CB<0>")
	)
	(arc
		(start 128.853946 -264.989818)
		(mid 128.669282 -264.939558)
		(end 128.483868 -264.987024)
		(width 0.088646)
		(layer "In6.Cu")
		(net "M_G_CPU1_SA_CB<0>")
	)
	(arc
		(start 138.251946 -264.989818)
		(mid 138.064748 -264.939675)
		(end 137.87755 -264.989818)
		(width 0.088646)
		(layer "In6.Cu")
		(net "M_G_CPU1_SA_CB<0>")
	)
	(arc
		(start 134.492746 -264.989818)
		(mid 134.308082 -264.939558)
		(end 134.122668 -264.987024)
		(width 0.088646)
		(layer "In6.Cu")
		(net "M_G_CPU1_SA_CB<0>")
	)
	(arc
		(start 127.789432 -264.892028)
		(mid 127.539964 -264.673278)
		(end 127.256794 -264.50036)
		(width 0.088646)
		(layer "In6.Cu")
		(net "M_G_CPU1_SA_CB<0>")
	)
	(arc
		(start 137.312146 -264.989818)
		(mid 137.124948 -264.939675)
		(end 136.93775 -264.989818)
		(width 0.088646)
		(layer "In6.Cu")
		(net "M_G_CPU1_SA_CB<0>")
	)
	(arc
		(start 127.914146 -264.989818)
		(mid 127.848349 -264.945311)
		(end 127.789432 -264.892028)
		(width 0.088646)
		(layer "In6.Cu")
		(net "M_G_CPU1_SA_CB<0>")
	)
	(arc
		(start 138.81735 -264.989818)
		(mid 138.543151 -265.065653)
		(end 138.266678 -264.998454)
		(width 0.088646)
		(layer "In6.Cu")
		(net "M_G_CPU1_SA_CB<0>")
	)
	(arc
		(start 135.432546 -264.989818)
		(mid 135.245348 -264.939675)
		(end 135.05815 -264.989818)
		(width 0.088646)
		(layer "In6.Cu")
		(net "M_G_CPU1_SA_CB<0>")
	)
	(arc
		(start 134.11073 -264.994136)
		(mid 133.831269 -265.065573)
		(end 133.552946 -264.989818)
		(width 0.088646)
		(layer "In6.Cu")
		(net "M_G_CPU1_SA_CB<0>")
	)
	(arc
		(start 133.17093 -264.994136)
		(mid 132.891469 -265.065573)
		(end 132.613146 -264.989818)
		(width 0.088646)
		(layer "In6.Cu")
		(net "M_G_CPU1_SA_CB<0>")
	)
	(arc
		(start 131.673346 -264.989818)
		(mid 131.488682 -264.939558)
		(end 131.303268 -264.987024)
		(width 0.088646)
		(layer "In6.Cu")
		(net "M_G_CPU1_SA_CB<0>")
	)
	(arc
		(start 136.93775 -264.989818)
		(mid 136.663551 -265.065653)
		(end 136.387078 -264.998454)
		(width 0.088646)
		(layer "In6.Cu")
		(net "M_G_CPU1_SA_CB<0>")
	)
	(segment
		(start 188.988446 -261.066788)
		(end 190.053976 -261.066788)
		(width 0.20066)
		(layer "F.Cu")
		(net "M_G_CPU1_SA_CA<6>")
	)
	(segment
		(start 191.79286 -261.49173)
		(end 191.900302 -261.49173)
		(width 0.20066)
		(layer "F.Cu")
		(net "M_G_CPU1_SA_CA<6>")
	)
	(segment
		(start 191.914018 -261.49173)
		(end 194.08648 -261.49173)
		(width 0.1016)
		(layer "F.Cu")
		(net "M_G_CPU1_SA_CA<6>")
	)
	(segment
		(start 126.676912 -249.342148)
		(end 126.677166 -249.341894)
		(width 0.20066)
		(layer "F.Cu")
		(net "M_G_CPU1_SA_CA<6>")
	)
	(segment
		(start 194.95262 -261.066534)
		(end 196.531992 -261.066534)
		(width 0.20066)
		(layer "F.Cu")
		(net "M_G_CPU1_SA_CA<6>")
	)
	(segment
		(start 194.08648 -261.49173)
		(end 194.098926 -261.504176)
		(width 0.1016)
		(layer "F.Cu")
		(net "M_G_CPU1_SA_CA<6>")
	)
	(segment
		(start 187.883546 -261.066788)
		(end 188.988446 -261.066788)
		(width 0.20066)
		(layer "F.Cu")
		(net "M_G_CPU1_SA_CA<6>")
	)
	(segment
		(start 190.54826 -260.572504)
		(end 190.873634 -260.572504)
		(width 0.20066)
		(layer "F.Cu")
		(net "M_G_CPU1_SA_CA<6>")
	)
	(segment
		(start 194.514978 -261.504176)
		(end 194.95262 -261.066534)
		(width 0.20066)
		(layer "F.Cu")
		(net "M_G_CPU1_SA_CA<6>")
	)
	(segment
		(start 190.873634 -260.572504)
		(end 191.79286 -261.49173)
		(width 0.20066)
		(layer "F.Cu")
		(net "M_G_CPU1_SA_CA<6>")
	)
	(segment
		(start 196.531992 -261.066534)
		(end 196.532246 -261.066788)
		(width 0.20066)
		(layer "F.Cu")
		(net "M_G_CPU1_SA_CA<6>")
	)
	(segment
		(start 194.098926 -261.504176)
		(end 194.514978 -261.504176)
		(width 0.20066)
		(layer "F.Cu")
		(net "M_G_CPU1_SA_CA<6>")
	)
	(segment
		(start 190.053976 -261.066788)
		(end 190.54826 -260.572504)
		(width 0.20066)
		(layer "F.Cu")
		(net "M_G_CPU1_SA_CA<6>")
	)
	(segment
		(start 126.677166 -249.341894)
		(end 126.677166 -248.806208)
		(width 0.20066)
		(layer "F.Cu")
		(net "M_G_CPU1_SA_CA<6>")
	)
	(segment
		(start 191.900302 -261.49173)
		(end 191.914018 -261.49173)
		(width 0.101854)
		(layer "F.Cu")
		(net "M_G_CPU1_SA_CA<6>")
	)
	(segment
		(start 125.409452 -250.392692)
		(end 125.409452 -250.135136)
		(width 0.088646)
		(layer "In4.Cu")
		(net "M_G_CPU1_SA_CA<6>")
	)
	(segment
		(start 148.959062 -253.863094)
		(end 148.28393 -254.538226)
		(width 0.18288)
		(layer "In4.Cu")
		(net "M_G_CPU1_SA_CA<6>")
	)
	(segment
		(start 159.212534 -257.252724)
		(end 155.834334 -255.853692)
		(width 0.18288)
		(layer "In4.Cu")
		(net "M_G_CPU1_SA_CA<6>")
	)
	(segment
		(start 125.409452 -250.135136)
		(end 125.641862 -249.902726)
		(width 0.088646)
		(layer "In4.Cu")
		(net "M_G_CPU1_SA_CA<6>")
	)
	(segment
		(start 125.918468 -249.134122)
		(end 125.924564 -249.130566)
		(width 0.088646)
		(layer "In4.Cu")
		(net "M_G_CPU1_SA_CA<6>")
	)
	(segment
		(start 141.98473 -252.743208)
		(end 126.865888 -252.743208)
		(width 0.18288)
		(layer "In4.Cu")
		(net "M_G_CPU1_SA_CA<6>")
	)
	(segment
		(start 185.335926 -258.018026)
		(end 163.061396 -258.018026)
		(width 0.18288)
		(layer "In4.Cu")
		(net "M_G_CPU1_SA_CA<6>")
	)
	(segment
		(start 146.610324 -255.231392)
		(end 145.337784 -255.231392)
		(width 0.18288)
		(layer "In4.Cu")
		(net "M_G_CPU1_SA_CA<6>")
	)
	(segment
		(start 185.732166 -258.915408)
		(end 185.732166 -258.414266)
		(width 0.18288)
		(layer "In4.Cu")
		(net "M_G_CPU1_SA_CA<6>")
	)
	(segment
		(start 145.337784 -255.231392)
		(end 143.861282 -254.61976)
		(width 0.18288)
		(layer "In4.Cu")
		(net "M_G_CPU1_SA_CA<6>")
	)
	(segment
		(start 125.936248 -249.123708)
		(end 126.215394 -248.934224)
		(width 0.088646)
		(layer "In4.Cu")
		(net "M_G_CPU1_SA_CA<6>")
	)
	(segment
		(start 125.641862 -249.902726)
		(end 125.641862 -249.620024)
		(width 0.088646)
		(layer "In4.Cu")
		(net "M_G_CPU1_SA_CA<6>")
	)
	(segment
		(start 153.843736 -253.863094)
		(end 148.959062 -253.863094)
		(width 0.18288)
		(layer "In4.Cu")
		(net "M_G_CPU1_SA_CA<6>")
	)
	(segment
		(start 155.834334 -255.853692)
		(end 153.843736 -253.863094)
		(width 0.18288)
		(layer "In4.Cu")
		(net "M_G_CPU1_SA_CA<6>")
	)
	(segment
		(start 126.865888 -252.743208)
		(end 125.409452 -251.286772)
		(width 0.18288)
		(layer "In4.Cu")
		(net "M_G_CPU1_SA_CA<6>")
	)
	(segment
		(start 143.861282 -254.61976)
		(end 141.98473 -252.743208)
		(width 0.18288)
		(layer "In4.Cu")
		(net "M_G_CPU1_SA_CA<6>")
	)
	(segment
		(start 125.409452 -251.286772)
		(end 125.409452 -250.392692)
		(width 0.18288)
		(layer "In4.Cu")
		(net "M_G_CPU1_SA_CA<6>")
	)
	(segment
		(start 126.631954 -248.806208)
		(end 126.677166 -248.806208)
		(width 0.088646)
		(layer "In4.Cu")
		(net "M_G_CPU1_SA_CA<6>")
	)
	(segment
		(start 125.924564 -249.130566)
		(end 125.936248 -249.123708)
		(width 0.088646)
		(layer "In4.Cu")
		(net "M_G_CPU1_SA_CA<6>")
	)
	(segment
		(start 185.732166 -258.414266)
		(end 185.335926 -258.018026)
		(width 0.18288)
		(layer "In4.Cu")
		(net "M_G_CPU1_SA_CA<6>")
	)
	(segment
		(start 148.28393 -254.538226)
		(end 146.610324 -255.231392)
		(width 0.18288)
		(layer "In4.Cu")
		(net "M_G_CPU1_SA_CA<6>")
	)
	(segment
		(start 187.883546 -261.066788)
		(end 185.732166 -258.915408)
		(width 0.18288)
		(layer "In4.Cu")
		(net "M_G_CPU1_SA_CA<6>")
	)
	(segment
		(start 163.061396 -258.018026)
		(end 159.212534 -257.252724)
		(width 0.18288)
		(layer "In4.Cu")
		(net "M_G_CPU1_SA_CA<6>")
	)
	(arc
		(start 125.641862 -249.620024)
		(mid 125.715853 -249.340458)
		(end 125.918468 -249.134122)
		(width 0.088646)
		(layer "In4.Cu")
		(net "M_G_CPU1_SA_CA<6>")
	)
	(arc
		(start 126.215394 -248.934224)
		(mid 126.414052 -248.838894)
		(end 126.631954 -248.806208)
		(width 0.088646)
		(layer "In4.Cu")
		(net "M_G_CPU1_SA_CA<6>")
	)
	(segment
		(start 128.196848 -256.361184)
		(end 128.196594 -256.361438)
		(width 0.20066)
		(layer "F.Cu")
		(net "M_G_CPU1_SA_CA<5>")
	)
	(segment
		(start 195.510658 -262.352282)
		(end 195.515484 -262.352282)
		(width 0.101854)
		(layer "F.Cu")
		(net "M_G_CPU1_SA_CA<5>")
	)
	(segment
		(start 191.983614 -261.916672)
		(end 193.088514 -261.916672)
		(width 0.20066)
		(layer "F.Cu")
		(net "M_G_CPU1_SA_CA<5>")
	)
	(segment
		(start 195.526152 -262.341614)
		(end 197.535292 -262.341614)
		(width 0.1016)
		(layer "F.Cu")
		(net "M_G_CPU1_SA_CA<5>")
	)
	(segment
		(start 199.517762 -261.916672)
		(end 200.632314 -261.916672)
		(width 0.20066)
		(layer "F.Cu")
		(net "M_G_CPU1_SA_CA<5>")
	)
	(segment
		(start 195.159884 -262.352282)
		(end 195.510658 -262.352282)
		(width 0.20066)
		(layer "F.Cu")
		(net "M_G_CPU1_SA_CA<5>")
	)
	(segment
		(start 128.196848 -255.825498)
		(end 128.196848 -256.361184)
		(width 0.20066)
		(layer "F.Cu")
		(net "M_G_CPU1_SA_CA<5>")
	)
	(segment
		(start 197.816724 -262.34898)
		(end 198.681594 -261.48411)
		(width 0.20066)
		(layer "F.Cu")
		(net "M_G_CPU1_SA_CA<5>")
	)
	(segment
		(start 199.0852 -261.48411)
		(end 199.517762 -261.916672)
		(width 0.20066)
		(layer "F.Cu")
		(net "M_G_CPU1_SA_CA<5>")
	)
	(segment
		(start 195.515484 -262.352282)
		(end 195.526152 -262.341614)
		(width 0.1016)
		(layer "F.Cu")
		(net "M_G_CPU1_SA_CA<5>")
	)
	(segment
		(start 197.535292 -262.341614)
		(end 197.542658 -262.34898)
		(width 0.1016)
		(layer "F.Cu")
		(net "M_G_CPU1_SA_CA<5>")
	)
	(segment
		(start 197.542658 -262.34898)
		(end 197.816724 -262.34898)
		(width 0.20066)
		(layer "F.Cu")
		(net "M_G_CPU1_SA_CA<5>")
	)
	(segment
		(start 193.088514 -261.916672)
		(end 194.724274 -261.916672)
		(width 0.20066)
		(layer "F.Cu")
		(net "M_G_CPU1_SA_CA<5>")
	)
	(segment
		(start 198.681594 -261.48411)
		(end 199.0852 -261.48411)
		(width 0.20066)
		(layer "F.Cu")
		(net "M_G_CPU1_SA_CA<5>")
	)
	(segment
		(start 194.724274 -261.916672)
		(end 195.159884 -262.352282)
		(width 0.20066)
		(layer "F.Cu")
		(net "M_G_CPU1_SA_CA<5>")
	)
	(segment
		(start 146.870674 -255.901952)
		(end 145.203418 -255.901952)
		(width 0.18288)
		(layer "In4.Cu")
		(net "M_G_CPU1_SA_CA<5>")
	)
	(segment
		(start 175.702214 -259.792724)
		(end 172.945298 -259.792724)
		(width 0.18288)
		(layer "In4.Cu")
		(net "M_G_CPU1_SA_CA<5>")
	)
	(segment
		(start 183.145176 -260.640576)
		(end 176.550066 -260.640576)
		(width 0.18288)
		(layer "In4.Cu")
		(net "M_G_CPU1_SA_CA<5>")
	)
	(segment
		(start 187.680854 -263.192514)
		(end 186.266074 -263.192514)
		(width 0.18288)
		(layer "In4.Cu")
		(net "M_G_CPU1_SA_CA<5>")
	)
	(segment
		(start 128.949196 -254.409194)
		(end 128.940306 -254.414274)
		(width 0.088646)
		(layer "In4.Cu")
		(net "M_G_CPU1_SA_CA<5>")
	)
	(segment
		(start 163.372546 -259.79247)
		(end 163.024566 -259.44449)
		(width 0.18288)
		(layer "In4.Cu")
		(net "M_G_CPU1_SA_CA<5>")
	)
	(segment
		(start 127.826516 -256.304288)
		(end 127.883666 -256.361438)
		(width 0.088646)
		(layer "In4.Cu")
		(net "M_G_CPU1_SA_CA<5>")
	)
	(segment
		(start 186.266074 -263.192514)
		(end 184.655206 -261.581646)
		(width 0.18288)
		(layer "In4.Cu")
		(net "M_G_CPU1_SA_CA<5>")
	)
	(segment
		(start 155.662122 -257.197352)
		(end 153.323544 -254.858774)
		(width 0.18288)
		(layer "In4.Cu")
		(net "M_G_CPU1_SA_CA<5>")
	)
	(segment
		(start 184.655206 -261.581646)
		(end 184.086246 -261.581646)
		(width 0.18288)
		(layer "In4.Cu")
		(net "M_G_CPU1_SA_CA<5>")
	)
	(segment
		(start 145.203418 -255.901952)
		(end 143.459454 -255.179576)
		(width 0.18288)
		(layer "In4.Cu")
		(net "M_G_CPU1_SA_CA<5>")
	)
	(segment
		(start 172.945298 -259.792724)
		(end 172.945044 -259.79247)
		(width 0.18288)
		(layer "In4.Cu")
		(net "M_G_CPU1_SA_CA<5>")
	)
	(segment
		(start 153.323544 -254.858774)
		(end 149.072854 -254.858774)
		(width 0.18288)
		(layer "In4.Cu")
		(net "M_G_CPU1_SA_CA<5>")
	)
	(segment
		(start 184.086246 -261.581646)
		(end 183.145176 -260.640576)
		(width 0.18288)
		(layer "In4.Cu")
		(net "M_G_CPU1_SA_CA<5>")
	)
	(segment
		(start 160.94202 -259.44449)
		(end 160.514284 -259.016754)
		(width 0.18288)
		(layer "In4.Cu")
		(net "M_G_CPU1_SA_CA<5>")
	)
	(segment
		(start 191.983614 -261.916672)
		(end 190.708026 -263.19226)
		(width 0.18288)
		(layer "In4.Cu")
		(net "M_G_CPU1_SA_CA<5>")
	)
	(segment
		(start 187.681108 -263.19226)
		(end 187.680854 -263.192514)
		(width 0.18288)
		(layer "In4.Cu")
		(net "M_G_CPU1_SA_CA<5>")
	)
	(segment
		(start 160.514284 -259.016754)
		(end 159.737298 -259.016754)
		(width 0.18288)
		(layer "In4.Cu")
		(net "M_G_CPU1_SA_CA<5>")
	)
	(segment
		(start 130.84175 -253.471426)
		(end 129.38252 -253.471426)
		(width 0.088646)
		(layer "In4.Cu")
		(net "M_G_CPU1_SA_CA<5>")
	)
	(segment
		(start 163.024566 -259.44449)
		(end 160.94202 -259.44449)
		(width 0.18288)
		(layer "In4.Cu")
		(net "M_G_CPU1_SA_CA<5>")
	)
	(segment
		(start 141.751304 -253.471426)
		(end 130.84175 -253.471426)
		(width 0.18288)
		(layer "In4.Cu")
		(net "M_G_CPU1_SA_CA<5>")
	)
	(segment
		(start 128.761744 -254.733552)
		(end 128.761744 -254.75565)
		(width 0.088646)
		(layer "In4.Cu")
		(net "M_G_CPU1_SA_CA<5>")
	)
	(segment
		(start 148.849334 -255.082294)
		(end 146.870674 -255.901952)
		(width 0.18288)
		(layer "In4.Cu")
		(net "M_G_CPU1_SA_CA<5>")
	)
	(segment
		(start 176.550066 -260.640576)
		(end 175.702214 -259.792724)
		(width 0.18288)
		(layer "In4.Cu")
		(net "M_G_CPU1_SA_CA<5>")
	)
	(segment
		(start 172.945044 -259.79247)
		(end 163.372546 -259.79247)
		(width 0.18288)
		(layer "In4.Cu")
		(net "M_G_CPU1_SA_CA<5>")
	)
	(segment
		(start 190.708026 -263.19226)
		(end 187.681108 -263.19226)
		(width 0.18288)
		(layer "In4.Cu")
		(net "M_G_CPU1_SA_CA<5>")
	)
	(segment
		(start 149.072854 -254.858774)
		(end 148.849334 -255.082294)
		(width 0.18288)
		(layer "In4.Cu")
		(net "M_G_CPU1_SA_CA<5>")
	)
	(segment
		(start 129.38252 -253.471426)
		(end 129.231644 -253.622302)
		(width 0.088646)
		(layer "In4.Cu")
		(net "M_G_CPU1_SA_CA<5>")
	)
	(segment
		(start 128.47955 -255.223264)
		(end 128.47066 -255.228344)
		(width 0.088646)
		(layer "In4.Cu")
		(net "M_G_CPU1_SA_CA<5>")
	)
	(segment
		(start 159.737298 -259.016754)
		(end 159.512762 -258.792218)
		(width 0.18288)
		(layer "In4.Cu")
		(net "M_G_CPU1_SA_CA<5>")
	)
	(segment
		(start 128.015492 -256.033524)
		(end 128.009396 -256.03708)
		(width 0.088646)
		(layer "In4.Cu")
		(net "M_G_CPU1_SA_CA<5>")
	)
	(segment
		(start 129.231644 -253.622302)
		(end 129.231644 -253.929642)
		(width 0.088646)
		(layer "In4.Cu")
		(net "M_G_CPU1_SA_CA<5>")
	)
	(segment
		(start 159.512762 -258.792218)
		(end 155.662122 -257.197352)
		(width 0.18288)
		(layer "In4.Cu")
		(net "M_G_CPU1_SA_CA<5>")
	)
	(segment
		(start 143.459454 -255.179576)
		(end 141.751304 -253.471426)
		(width 0.18288)
		(layer "In4.Cu")
		(net "M_G_CPU1_SA_CA<5>")
	)
	(segment
		(start 128.009396 -256.03708)
		(end 128.000506 -256.04216)
		(width 0.088646)
		(layer "In4.Cu")
		(net "M_G_CPU1_SA_CA<5>")
	)
	(segment
		(start 127.883666 -256.361438)
		(end 128.196594 -256.361438)
		(width 0.088646)
		(layer "In4.Cu")
		(net "M_G_CPU1_SA_CA<5>")
	)
	(arc
		(start 129.231644 -253.929642)
		(mid 129.153533 -254.206591)
		(end 128.949196 -254.409194)
		(width 0.088646)
		(layer "In4.Cu")
		(net "M_G_CPU1_SA_CA<5>")
	)
	(arc
		(start 128.292098 -255.547622)
		(mid 128.218107 -255.827188)
		(end 128.015492 -256.033524)
		(width 0.088646)
		(layer "In4.Cu")
		(net "M_G_CPU1_SA_CA<5>")
	)
	(arc
		(start 128.940306 -254.414274)
		(mid 128.809392 -254.550634)
		(end 128.761744 -254.733552)
		(width 0.088646)
		(layer "In4.Cu")
		(net "M_G_CPU1_SA_CA<5>")
	)
	(arc
		(start 128.47066 -255.228344)
		(mid 128.339746 -255.364704)
		(end 128.292098 -255.547622)
		(width 0.088646)
		(layer "In4.Cu")
		(net "M_G_CPU1_SA_CA<5>")
	)
	(arc
		(start 128.000506 -256.04216)
		(mid 127.884697 -256.154089)
		(end 127.826516 -256.304288)
		(width 0.088646)
		(layer "In4.Cu")
		(net "M_G_CPU1_SA_CA<5>")
	)
	(arc
		(start 128.761744 -254.75565)
		(mid 128.680833 -255.025778)
		(end 128.47955 -255.223264)
		(width 0.088646)
		(layer "In4.Cu")
		(net "M_G_CPU1_SA_CA<5>")
	)
	(segment
		(start 127.256794 -255.825752)
		(end 127.256794 -256.361438)
		(width 0.20066)
		(layer "F.Cu")
		(net "M_G_CPU1_SA_CA<4>")
	)
	(segment
		(start 194.08648 -263.191752)
		(end 194.098926 -263.204198)
		(width 0.1016)
		(layer "F.Cu")
		(net "M_G_CPU1_SA_CA<4>")
	)
	(segment
		(start 127.257048 -255.825498)
		(end 127.256794 -255.825752)
		(width 0.20066)
		(layer "F.Cu")
		(net "M_G_CPU1_SA_CA<4>")
	)
	(segment
		(start 191.831976 -263.191752)
		(end 194.08648 -263.191752)
		(width 0.1016)
		(layer "F.Cu")
		(net "M_G_CPU1_SA_CA<4>")
	)
	(segment
		(start 190.635636 -262.294116)
		(end 191.533272 -263.191752)
		(width 0.20066)
		(layer "F.Cu")
		(net "M_G_CPU1_SA_CA<4>")
	)
	(segment
		(start 187.883546 -262.766556)
		(end 187.8838 -262.76681)
		(width 0.20066)
		(layer "F.Cu")
		(net "M_G_CPU1_SA_CA<4>")
	)
	(segment
		(start 191.802766 -263.191752)
		(end 191.831976 -263.191752)
		(width 0.101854)
		(layer "F.Cu")
		(net "M_G_CPU1_SA_CA<4>")
	)
	(segment
		(start 194.95262 -262.766556)
		(end 196.531992 -262.766556)
		(width 0.20066)
		(layer "F.Cu")
		(net "M_G_CPU1_SA_CA<4>")
	)
	(segment
		(start 189.878716 -262.76681)
		(end 190.35141 -262.294116)
		(width 0.20066)
		(layer "F.Cu")
		(net "M_G_CPU1_SA_CA<4>")
	)
	(segment
		(start 196.531992 -262.766556)
		(end 196.532246 -262.76681)
		(width 0.20066)
		(layer "F.Cu")
		(net "M_G_CPU1_SA_CA<4>")
	)
	(segment
		(start 190.35141 -262.294116)
		(end 190.635636 -262.294116)
		(width 0.20066)
		(layer "F.Cu")
		(net "M_G_CPU1_SA_CA<4>")
	)
	(segment
		(start 194.514978 -263.204198)
		(end 194.95262 -262.766556)
		(width 0.20066)
		(layer "F.Cu")
		(net "M_G_CPU1_SA_CA<4>")
	)
	(segment
		(start 187.8838 -262.76681)
		(end 188.988446 -262.76681)
		(width 0.20066)
		(layer "F.Cu")
		(net "M_G_CPU1_SA_CA<4>")
	)
	(segment
		(start 194.098926 -263.204198)
		(end 194.514978 -263.204198)
		(width 0.20066)
		(layer "F.Cu")
		(net "M_G_CPU1_SA_CA<4>")
	)
	(segment
		(start 191.533272 -263.191752)
		(end 191.802766 -263.191752)
		(width 0.20066)
		(layer "F.Cu")
		(net "M_G_CPU1_SA_CA<4>")
	)
	(segment
		(start 188.988446 -262.76681)
		(end 189.878716 -262.76681)
		(width 0.20066)
		(layer "F.Cu")
		(net "M_G_CPU1_SA_CA<4>")
	)
	(segment
		(start 187.145422 -262.028432)
		(end 186.715654 -262.028432)
		(width 0.18288)
		(layer "In4.Cu")
		(net "M_G_CPU1_SA_CA<4>")
	)
	(segment
		(start 155.527756 -256.309114)
		(end 153.579576 -254.360934)
		(width 0.18288)
		(layer "In4.Cu")
		(net "M_G_CPU1_SA_CA<4>")
	)
	(segment
		(start 148.935694 -254.360934)
		(end 148.457412 -254.839216)
		(width 0.18288)
		(layer "In4.Cu")
		(net "M_G_CPU1_SA_CA<4>")
	)
	(segment
		(start 130.84175 -253.099062)
		(end 130.57886 -253.099062)
		(width 0.088646)
		(layer "In4.Cu")
		(net "M_G_CPU1_SA_CA<4>")
	)
	(segment
		(start 160.444688 -258.064508)
		(end 159.765746 -258.064508)
		(width 0.18288)
		(layer "In4.Cu")
		(net "M_G_CPU1_SA_CA<4>")
	)
	(segment
		(start 184.842658 -258.943856)
		(end 161.324036 -258.943856)
		(width 0.18288)
		(layer "In4.Cu")
		(net "M_G_CPU1_SA_CA<4>")
	)
	(segment
		(start 129.041144 -253.543308)
		(end 129.041144 -253.919736)
		(width 0.088646)
		(layer "In4.Cu")
		(net "M_G_CPU1_SA_CA<4>")
	)
	(segment
		(start 141.853412 -253.099062)
		(end 130.84175 -253.099062)
		(width 0.18288)
		(layer "In4.Cu")
		(net "M_G_CPU1_SA_CA<4>")
	)
	(segment
		(start 128.392682 -255.05283)
		(end 128.383792 -255.05791)
		(width 0.088646)
		(layer "In4.Cu")
		(net "M_G_CPU1_SA_CA<4>")
	)
	(segment
		(start 130.57886 -253.099062)
		(end 130.396996 -253.280926)
		(width 0.088646)
		(layer "In4.Cu")
		(net "M_G_CPU1_SA_CA<4>")
	)
	(segment
		(start 185.079386 -260.392164)
		(end 185.079386 -259.180584)
		(width 0.18288)
		(layer "In4.Cu")
		(net "M_G_CPU1_SA_CA<4>")
	)
	(segment
		(start 161.324036 -258.943856)
		(end 160.444688 -258.064508)
		(width 0.18288)
		(layer "In4.Cu")
		(net "M_G_CPU1_SA_CA<4>")
	)
	(segment
		(start 128.862582 -254.239014)
		(end 128.853692 -254.244094)
		(width 0.088646)
		(layer "In4.Cu")
		(net "M_G_CPU1_SA_CA<4>")
	)
	(segment
		(start 187.883546 -262.766556)
		(end 187.145422 -262.028432)
		(width 0.18288)
		(layer "In4.Cu")
		(net "M_G_CPU1_SA_CA<4>")
	)
	(segment
		(start 143.649446 -254.895096)
		(end 141.853412 -253.099062)
		(width 0.18288)
		(layer "In4.Cu")
		(net "M_G_CPU1_SA_CA<4>")
	)
	(segment
		(start 127.923036 -255.8669)
		(end 127.914146 -255.87198)
		(width 0.088646)
		(layer "In4.Cu")
		(net "M_G_CPU1_SA_CA<4>")
	)
	(segment
		(start 146.701764 -255.566672)
		(end 145.270474 -255.566672)
		(width 0.18288)
		(layer "In4.Cu")
		(net "M_G_CPU1_SA_CA<4>")
	)
	(segment
		(start 186.715654 -262.028432)
		(end 185.079386 -260.392164)
		(width 0.18288)
		(layer "In4.Cu")
		(net "M_G_CPU1_SA_CA<4>")
	)
	(segment
		(start 185.079386 -259.180584)
		(end 184.842658 -258.943856)
		(width 0.18288)
		(layer "In4.Cu")
		(net "M_G_CPU1_SA_CA<4>")
	)
	(segment
		(start 159.765746 -258.064508)
		(end 155.527756 -256.309114)
		(width 0.18288)
		(layer "In4.Cu")
		(net "M_G_CPU1_SA_CA<4>")
	)
	(segment
		(start 128.101598 -255.525524)
		(end 128.101598 -255.547622)
		(width 0.088646)
		(layer "In4.Cu")
		(net "M_G_CPU1_SA_CA<4>")
	)
	(segment
		(start 153.579576 -254.360934)
		(end 148.935694 -254.360934)
		(width 0.18288)
		(layer "In4.Cu")
		(net "M_G_CPU1_SA_CA<4>")
	)
	(segment
		(start 148.457412 -254.839216)
		(end 146.701764 -255.566672)
		(width 0.18288)
		(layer "In4.Cu")
		(net "M_G_CPU1_SA_CA<4>")
	)
	(segment
		(start 127.911352 -255.873504)
		(end 127.90805 -255.875536)
		(width 0.088646)
		(layer "In4.Cu")
		(net "M_G_CPU1_SA_CA<4>")
	)
	(segment
		(start 127.569722 -256.361438)
		(end 127.256794 -256.361438)
		(width 0.088646)
		(layer "In4.Cu")
		(net "M_G_CPU1_SA_CA<4>")
	)
	(segment
		(start 127.635254 -256.295906)
		(end 127.569722 -256.361438)
		(width 0.088646)
		(layer "In4.Cu")
		(net "M_G_CPU1_SA_CA<4>")
	)
	(segment
		(start 130.396996 -253.280926)
		(end 129.303526 -253.280926)
		(width 0.088646)
		(layer "In4.Cu")
		(net "M_G_CPU1_SA_CA<4>")
	)
	(segment
		(start 128.571244 -254.723646)
		(end 128.571244 -254.733552)
		(width 0.088646)
		(layer "In4.Cu")
		(net "M_G_CPU1_SA_CA<4>")
	)
	(segment
		(start 129.303526 -253.280926)
		(end 129.041144 -253.543308)
		(width 0.088646)
		(layer "In4.Cu")
		(net "M_G_CPU1_SA_CA<4>")
	)
	(segment
		(start 127.914146 -255.87198)
		(end 127.911352 -255.873504)
		(width 0.088646)
		(layer "In4.Cu")
		(net "M_G_CPU1_SA_CA<4>")
	)
	(segment
		(start 145.270474 -255.566672)
		(end 143.649446 -254.895096)
		(width 0.18288)
		(layer "In4.Cu")
		(net "M_G_CPU1_SA_CA<4>")
	)
	(arc
		(start 128.853692 -254.244094)
		(mid 128.649357 -254.446699)
		(end 128.571244 -254.723646)
		(width 0.088646)
		(layer "In4.Cu")
		(net "M_G_CPU1_SA_CA<4>")
	)
	(arc
		(start 128.101598 -255.547622)
		(mid 128.053919 -255.730522)
		(end 127.923036 -255.8669)
		(width 0.088646)
		(layer "In4.Cu")
		(net "M_G_CPU1_SA_CA<4>")
	)
	(arc
		(start 129.041144 -253.919736)
		(mid 128.993465 -254.102636)
		(end 128.862582 -254.239014)
		(width 0.088646)
		(layer "In4.Cu")
		(net "M_G_CPU1_SA_CA<4>")
	)
	(arc
		(start 128.383792 -255.05791)
		(mid 128.18251 -255.255397)
		(end 128.101598 -255.525524)
		(width 0.088646)
		(layer "In4.Cu")
		(net "M_G_CPU1_SA_CA<4>")
	)
	(arc
		(start 128.571244 -254.733552)
		(mid 128.523565 -254.916452)
		(end 128.392682 -255.05283)
		(width 0.088646)
		(layer "In4.Cu")
		(net "M_G_CPU1_SA_CA<4>")
	)
	(arc
		(start 127.90805 -255.875536)
		(mid 127.722527 -256.053837)
		(end 127.635254 -256.295906)
		(width 0.088646)
		(layer "In4.Cu")
		(net "M_G_CPU1_SA_CA<4>")
	)
	(segment
		(start 128.666494 -257.175)
		(end 128.666748 -257.175254)
		(width 0.20066)
		(layer "F.Cu")
		(net "M_G_CPU1_SA_CA<3>")
	)
	(segment
		(start 197.535292 -264.041636)
		(end 197.542658 -264.049002)
		(width 0.1016)
		(layer "F.Cu")
		(net "M_G_CPU1_SA_CA<3>")
	)
	(segment
		(start 191.907414 -263.616694)
		(end 193.088514 -263.616694)
		(width 0.20066)
		(layer "F.Cu")
		(net "M_G_CPU1_SA_CA<3>")
	)
	(segment
		(start 199.0852 -263.184132)
		(end 199.517762 -263.616694)
		(width 0.20066)
		(layer "F.Cu")
		(net "M_G_CPU1_SA_CA<3>")
	)
	(segment
		(start 194.724274 -263.616694)
		(end 195.159884 -264.052304)
		(width 0.20066)
		(layer "F.Cu")
		(net "M_G_CPU1_SA_CA<3>")
	)
	(segment
		(start 195.510658 -264.052304)
		(end 195.515484 -264.052304)
		(width 0.101854)
		(layer "F.Cu")
		(net "M_G_CPU1_SA_CA<3>")
	)
	(segment
		(start 199.517762 -263.616694)
		(end 200.632314 -263.616694)
		(width 0.20066)
		(layer "F.Cu")
		(net "M_G_CPU1_SA_CA<3>")
	)
	(segment
		(start 197.816724 -264.049002)
		(end 198.681594 -263.184132)
		(width 0.20066)
		(layer "F.Cu")
		(net "M_G_CPU1_SA_CA<3>")
	)
	(segment
		(start 193.088514 -263.616694)
		(end 194.724274 -263.616694)
		(width 0.20066)
		(layer "F.Cu")
		(net "M_G_CPU1_SA_CA<3>")
	)
	(segment
		(start 195.526152 -264.041636)
		(end 197.535292 -264.041636)
		(width 0.1016)
		(layer "F.Cu")
		(net "M_G_CPU1_SA_CA<3>")
	)
	(segment
		(start 195.159884 -264.052304)
		(end 195.510658 -264.052304)
		(width 0.20066)
		(layer "F.Cu")
		(net "M_G_CPU1_SA_CA<3>")
	)
	(segment
		(start 195.515484 -264.052304)
		(end 195.526152 -264.041636)
		(width 0.1016)
		(layer "F.Cu")
		(net "M_G_CPU1_SA_CA<3>")
	)
	(segment
		(start 197.542658 -264.049002)
		(end 197.816724 -264.049002)
		(width 0.20066)
		(layer "F.Cu")
		(net "M_G_CPU1_SA_CA<3>")
	)
	(segment
		(start 128.666494 -256.639314)
		(end 128.666494 -257.175)
		(width 0.20066)
		(layer "F.Cu")
		(net "M_G_CPU1_SA_CA<3>")
	)
	(segment
		(start 198.681594 -263.184132)
		(end 199.0852 -263.184132)
		(width 0.20066)
		(layer "F.Cu")
		(net "M_G_CPU1_SA_CA<3>")
	)
	(segment
		(start 184.871106 -263.349486)
		(end 183.982106 -263.349486)
		(width 0.18288)
		(layer "In4.Cu")
		(net "M_G_CPU1_SA_CA<3>")
	)
	(segment
		(start 145.069306 -256.572766)
		(end 141.08303 -254.921766)
		(width 0.18288)
		(layer "In4.Cu")
		(net "M_G_CPU1_SA_CA<3>")
	)
	(segment
		(start 152.668478 -255.854454)
		(end 148.927566 -255.854454)
		(width 0.18288)
		(layer "In4.Cu")
		(net "M_G_CPU1_SA_CA<3>")
	)
	(segment
		(start 136.327388 -255.172464)
		(end 136.184894 -255.172464)
		(width 0.088646)
		(layer "In4.Cu")
		(net "M_G_CPU1_SA_CA<3>")
	)
	(segment
		(start 134.50316 -255.22936)
		(end 134.492746 -255.223264)
		(width 0.088646)
		(layer "In4.Cu")
		(net "M_G_CPU1_SA_CA<3>")
	)
	(segment
		(start 190.631826 -264.892282)
		(end 186.424062 -264.892282)
		(width 0.18288)
		(layer "In4.Cu")
		(net "M_G_CPU1_SA_CA<3>")
	)
	(segment
		(start 133.563106 -255.22936)
		(end 133.552692 -255.223264)
		(width 0.088646)
		(layer "In4.Cu")
		(net "M_G_CPU1_SA_CA<3>")
	)
	(segment
		(start 178.259486 -262.341106)
		(end 178.259232 -262.340852)
		(width 0.18288)
		(layer "In4.Cu")
		(net "M_G_CPU1_SA_CA<3>")
	)
	(segment
		(start 136.980168 -254.855472)
		(end 136.64438 -254.855472)
		(width 0.088646)
		(layer "In4.Cu")
		(net "M_G_CPU1_SA_CA<3>")
	)
	(segment
		(start 128.94945 -256.03708)
		(end 128.94056 -256.04216)
		(width 0.088646)
		(layer "In4.Cu")
		(net "M_G_CPU1_SA_CA<3>")
	)
	(segment
		(start 178.259232 -262.340852)
		(end 176.496218 -262.340852)
		(width 0.18288)
		(layer "In4.Cu")
		(net "M_G_CPU1_SA_CA<3>")
	)
	(segment
		(start 148.927566 -255.854454)
		(end 147.193254 -256.572766)
		(width 0.18288)
		(layer "In4.Cu")
		(net "M_G_CPU1_SA_CA<3>")
	)
	(segment
		(start 131.688078 -255.2319)
		(end 131.673346 -255.223264)
		(width 0.088646)
		(layer "In4.Cu")
		(net "M_G_CPU1_SA_CA<3>")
	)
	(segment
		(start 182.973726 -262.341106)
		(end 178.259486 -262.341106)
		(width 0.18288)
		(layer "In4.Cu")
		(net "M_G_CPU1_SA_CA<3>")
	)
	(segment
		(start 162.380422 -260.643878)
		(end 159.719518 -260.643878)
		(width 0.18288)
		(layer "In4.Cu")
		(net "M_G_CPU1_SA_CA<3>")
	)
	(segment
		(start 132.6134 -255.223264)
		(end 132.605018 -255.218438)
		(width 0.088646)
		(layer "In4.Cu")
		(net "M_G_CPU1_SA_CA<3>")
	)
	(segment
		(start 183.982106 -263.349486)
		(end 182.973726 -262.341106)
		(width 0.18288)
		(layer "In4.Cu")
		(net "M_G_CPU1_SA_CA<3>")
	)
	(segment
		(start 158.805118 -259.729478)
		(end 156.543502 -259.729478)
		(width 0.18288)
		(layer "In4.Cu")
		(net "M_G_CPU1_SA_CA<3>")
	)
	(segment
		(start 128.761998 -256.361438)
		(end 128.761998 -256.945384)
		(width 0.088646)
		(layer "In4.Cu")
		(net "M_G_CPU1_SA_CA<3>")
	)
	(segment
		(start 147.193254 -256.572766)
		(end 145.069306 -256.572766)
		(width 0.18288)
		(layer "In4.Cu")
		(net "M_G_CPU1_SA_CA<3>")
	)
	(segment
		(start 138.889994 -254.855472)
		(end 136.980168 -254.855472)
		(width 0.18288)
		(layer "In4.Cu")
		(net "M_G_CPU1_SA_CA<3>")
	)
	(segment
		(start 163.229036 -261.492492)
		(end 162.380422 -260.643878)
		(width 0.18288)
		(layer "In4.Cu")
		(net "M_G_CPU1_SA_CA<3>")
	)
	(segment
		(start 156.543502 -259.729478)
		(end 152.668478 -255.854454)
		(width 0.18288)
		(layer "In4.Cu")
		(net "M_G_CPU1_SA_CA<3>")
	)
	(segment
		(start 191.907414 -263.616694)
		(end 190.631826 -264.892282)
		(width 0.18288)
		(layer "In4.Cu")
		(net "M_G_CPU1_SA_CA<3>")
	)
	(segment
		(start 130.748278 -255.2319)
		(end 130.733546 -255.223264)
		(width 0.088646)
		(layer "In4.Cu")
		(net "M_G_CPU1_SA_CA<3>")
	)
	(segment
		(start 138.956288 -254.921766)
		(end 138.889994 -254.855472)
		(width 0.18288)
		(layer "In4.Cu")
		(net "M_G_CPU1_SA_CA<3>")
	)
	(segment
		(start 129.41935 -255.223264)
		(end 129.41046 -255.228344)
		(width 0.088646)
		(layer "In4.Cu")
		(net "M_G_CPU1_SA_CA<3>")
	)
	(segment
		(start 159.719518 -260.643878)
		(end 158.805118 -259.729478)
		(width 0.18288)
		(layer "In4.Cu")
		(net "M_G_CPU1_SA_CA<3>")
	)
	(segment
		(start 176.496218 -262.340852)
		(end 175.647858 -261.492492)
		(width 0.18288)
		(layer "In4.Cu")
		(net "M_G_CPU1_SA_CA<3>")
	)
	(segment
		(start 185.297826 -263.766046)
		(end 185.287666 -263.766046)
		(width 0.18288)
		(layer "In4.Cu")
		(net "M_G_CPU1_SA_CA<3>")
	)
	(segment
		(start 136.64438 -254.855472)
		(end 136.327388 -255.172464)
		(width 0.088646)
		(layer "In4.Cu")
		(net "M_G_CPU1_SA_CA<3>")
	)
	(segment
		(start 186.424062 -264.892282)
		(end 185.297826 -263.766046)
		(width 0.18288)
		(layer "In4.Cu")
		(net "M_G_CPU1_SA_CA<3>")
	)
	(segment
		(start 175.647858 -261.492492)
		(end 163.229036 -261.492492)
		(width 0.18288)
		(layer "In4.Cu")
		(net "M_G_CPU1_SA_CA<3>")
	)
	(segment
		(start 129.231898 -255.547622)
		(end 129.231898 -255.557528)
		(width 0.088646)
		(layer "In4.Cu")
		(net "M_G_CPU1_SA_CA<3>")
	)
	(segment
		(start 185.287666 -263.766046)
		(end 184.871106 -263.349486)
		(width 0.18288)
		(layer "In4.Cu")
		(net "M_G_CPU1_SA_CA<3>")
	)
	(segment
		(start 129.808478 -255.2319)
		(end 129.793746 -255.223264)
		(width 0.088646)
		(layer "In4.Cu")
		(net "M_G_CPU1_SA_CA<3>")
	)
	(segment
		(start 141.08303 -254.921766)
		(end 138.956288 -254.921766)
		(width 0.18288)
		(layer "In4.Cu")
		(net "M_G_CPU1_SA_CA<3>")
	)
	(arc
		(start 135.057896 -255.223264)
		(mid 134.781337 -255.298973)
		(end 134.50316 -255.22936)
		(width 0.088646)
		(layer "In4.Cu")
		(net "M_G_CPU1_SA_CA<3>")
	)
	(arc
		(start 128.761998 -256.945384)
		(mid 128.73725 -257.069802)
		(end 128.666748 -257.175254)
		(width 0.088646)
		(layer "In4.Cu")
		(net "M_G_CPU1_SA_CA<3>")
	)
	(arc
		(start 131.673346 -255.223264)
		(mid 131.486148 -255.173121)
		(end 131.29895 -255.223264)
		(width 0.088646)
		(layer "In4.Cu")
		(net "M_G_CPU1_SA_CA<3>")
	)
	(arc
		(start 135.432292 -255.223264)
		(mid 135.245094 -255.173121)
		(end 135.057896 -255.223264)
		(width 0.088646)
		(layer "In4.Cu")
		(net "M_G_CPU1_SA_CA<3>")
	)
	(arc
		(start 131.29895 -255.223264)
		(mid 131.024721 -255.299189)
		(end 130.748278 -255.2319)
		(width 0.088646)
		(layer "In4.Cu")
		(net "M_G_CPU1_SA_CA<3>")
	)
	(arc
		(start 135.997696 -255.223264)
		(mid 135.714994 -255.299006)
		(end 135.432292 -255.223264)
		(width 0.088646)
		(layer "In4.Cu")
		(net "M_G_CPU1_SA_CA<3>")
	)
	(arc
		(start 129.41046 -255.228344)
		(mid 129.279546 -255.364704)
		(end 129.231898 -255.547622)
		(width 0.088646)
		(layer "In4.Cu")
		(net "M_G_CPU1_SA_CA<3>")
	)
	(arc
		(start 132.23875 -255.223264)
		(mid 131.964521 -255.299189)
		(end 131.688078 -255.2319)
		(width 0.088646)
		(layer "In4.Cu")
		(net "M_G_CPU1_SA_CA<3>")
	)
	(arc
		(start 132.605018 -255.218438)
		(mid 132.421256 -255.173038)
		(end 132.23875 -255.223264)
		(width 0.088646)
		(layer "In4.Cu")
		(net "M_G_CPU1_SA_CA<3>")
	)
	(arc
		(start 134.11835 -255.223264)
		(mid 133.841537 -255.2991)
		(end 133.563106 -255.22936)
		(width 0.088646)
		(layer "In4.Cu")
		(net "M_G_CPU1_SA_CA<3>")
	)
	(arc
		(start 133.552692 -255.223264)
		(mid 133.365494 -255.173121)
		(end 133.178296 -255.223264)
		(width 0.088646)
		(layer "In4.Cu")
		(net "M_G_CPU1_SA_CA<3>")
	)
	(arc
		(start 130.733546 -255.223264)
		(mid 130.546348 -255.173121)
		(end 130.35915 -255.223264)
		(width 0.088646)
		(layer "In4.Cu")
		(net "M_G_CPU1_SA_CA<3>")
	)
	(arc
		(start 130.35915 -255.223264)
		(mid 130.084921 -255.299189)
		(end 129.808478 -255.2319)
		(width 0.088646)
		(layer "In4.Cu")
		(net "M_G_CPU1_SA_CA<3>")
	)
	(arc
		(start 134.492746 -255.223264)
		(mid 134.305548 -255.173121)
		(end 134.11835 -255.223264)
		(width 0.088646)
		(layer "In4.Cu")
		(net "M_G_CPU1_SA_CA<3>")
	)
	(arc
		(start 133.178296 -255.223264)
		(mid 132.895848 -255.298879)
		(end 132.6134 -255.223264)
		(width 0.088646)
		(layer "In4.Cu")
		(net "M_G_CPU1_SA_CA<3>")
	)
	(arc
		(start 129.231898 -255.557528)
		(mid 129.153787 -255.834477)
		(end 128.94945 -256.03708)
		(width 0.088646)
		(layer "In4.Cu")
		(net "M_G_CPU1_SA_CA<3>")
	)
	(arc
		(start 136.184894 -255.172464)
		(mid 136.087955 -255.185554)
		(end 135.997696 -255.223264)
		(width 0.088646)
		(layer "In4.Cu")
		(net "M_G_CPU1_SA_CA<3>")
	)
	(arc
		(start 128.94056 -256.04216)
		(mid 128.809646 -256.17852)
		(end 128.761998 -256.361438)
		(width 0.088646)
		(layer "In4.Cu")
		(net "M_G_CPU1_SA_CA<3>")
	)
	(arc
		(start 129.793746 -255.223264)
		(mid 129.606548 -255.173121)
		(end 129.41935 -255.223264)
		(width 0.088646)
		(layer "In4.Cu")
		(net "M_G_CPU1_SA_CA<3>")
	)
	(segment
		(start 126.786894 -257.175)
		(end 126.787148 -257.175254)
		(width 0.20066)
		(layer "F.Cu")
		(net "M_G_CPU1_SA_CA<2>")
	)
	(segment
		(start 194.08648 -264.89152)
		(end 194.098926 -264.903966)
		(width 0.1016)
		(layer "F.Cu")
		(net "M_G_CPU1_SA_CA<2>")
	)
	(segment
		(start 191.821054 -264.89152)
		(end 194.08648 -264.89152)
		(width 0.1016)
		(layer "F.Cu")
		(net "M_G_CPU1_SA_CA<2>")
	)
	(segment
		(start 196.531992 -264.466324)
		(end 196.532246 -264.466578)
		(width 0.20066)
		(layer "F.Cu")
		(net "M_G_CPU1_SA_CA<2>")
	)
	(segment
		(start 188.988446 -264.466578)
		(end 189.908688 -264.466578)
		(width 0.20066)
		(layer "F.Cu")
		(net "M_G_CPU1_SA_CA<2>")
	)
	(segment
		(start 191.558164 -264.89152)
		(end 191.778636 -264.89152)
		(width 0.20066)
		(layer "F.Cu")
		(net "M_G_CPU1_SA_CA<2>")
	)
	(segment
		(start 191.778636 -264.89152)
		(end 191.821054 -264.89152)
		(width 0.101854)
		(layer "F.Cu")
		(net "M_G_CPU1_SA_CA<2>")
	)
	(segment
		(start 190.378842 -263.996424)
		(end 190.663068 -263.996424)
		(width 0.20066)
		(layer "F.Cu")
		(net "M_G_CPU1_SA_CA<2>")
	)
	(segment
		(start 126.786894 -256.639314)
		(end 126.786894 -257.175)
		(width 0.20066)
		(layer "F.Cu")
		(net "M_G_CPU1_SA_CA<2>")
	)
	(segment
		(start 187.883546 -264.466578)
		(end 188.988446 -264.466578)
		(width 0.20066)
		(layer "F.Cu")
		(net "M_G_CPU1_SA_CA<2>")
	)
	(segment
		(start 194.514978 -264.903966)
		(end 194.95262 -264.466324)
		(width 0.20066)
		(layer "F.Cu")
		(net "M_G_CPU1_SA_CA<2>")
	)
	(segment
		(start 189.908688 -264.466578)
		(end 190.378842 -263.996424)
		(width 0.20066)
		(layer "F.Cu")
		(net "M_G_CPU1_SA_CA<2>")
	)
	(segment
		(start 194.95262 -264.466324)
		(end 196.531992 -264.466324)
		(width 0.20066)
		(layer "F.Cu")
		(net "M_G_CPU1_SA_CA<2>")
	)
	(segment
		(start 194.098926 -264.903966)
		(end 194.514978 -264.903966)
		(width 0.20066)
		(layer "F.Cu")
		(net "M_G_CPU1_SA_CA<2>")
	)
	(segment
		(start 190.663068 -263.996424)
		(end 191.558164 -264.89152)
		(width 0.20066)
		(layer "F.Cu")
		(net "M_G_CPU1_SA_CA<2>")
	)
	(segment
		(start 128.392682 -256.680716)
		(end 128.383792 -256.685796)
		(width 0.088646)
		(layer "In4.Cu")
		(net "M_G_CPU1_SA_CA<2>")
	)
	(segment
		(start 176.433734 -261.492492)
		(end 175.581818 -260.640576)
		(width 0.18288)
		(layer "In4.Cu")
		(net "M_G_CPU1_SA_CA<2>")
	)
	(segment
		(start 138.838686 -254.089408)
		(end 137.555732 -254.089408)
		(width 0.18288)
		(layer "In4.Cu")
		(net "M_G_CPU1_SA_CA<2>")
	)
	(segment
		(start 127.443992 -256.685796)
		(end 127.366776 -256.730246)
		(width 0.088646)
		(layer "In4.Cu")
		(net "M_G_CPU1_SA_CA<2>")
	)
	(segment
		(start 182.940706 -261.492746)
		(end 178.960018 -261.492746)
		(width 0.18288)
		(layer "In4.Cu")
		(net "M_G_CPU1_SA_CA<2>")
	)
	(segment
		(start 131.776978 -255.062736)
		(end 131.768596 -255.05791)
		(width 0.088646)
		(layer "In4.Cu")
		(net "M_G_CPU1_SA_CA<2>")
	)
	(segment
		(start 162.665664 -259.948426)
		(end 160.68802 -259.948426)
		(width 0.18288)
		(layer "In4.Cu")
		(net "M_G_CPU1_SA_CA<2>")
	)
	(segment
		(start 184.563766 -262.249666)
		(end 183.697626 -262.249666)
		(width 0.18288)
		(layer "In4.Cu")
		(net "M_G_CPU1_SA_CA<2>")
	)
	(segment
		(start 139.33551 -254.586232)
		(end 138.838686 -254.089408)
		(width 0.18288)
		(layer "In4.Cu")
		(net "M_G_CPU1_SA_CA<2>")
	)
	(segment
		(start 163.357814 -260.640576)
		(end 162.665664 -259.948426)
		(width 0.18288)
		(layer "In4.Cu")
		(net "M_G_CPU1_SA_CA<2>")
	)
	(segment
		(start 128.853946 -255.87198)
		(end 128.841754 -255.879092)
		(width 0.088646)
		(layer "In4.Cu")
		(net "M_G_CPU1_SA_CA<2>")
	)
	(segment
		(start 133.09346 -255.051814)
		(end 133.083046 -255.05791)
		(width 0.088646)
		(layer "In4.Cu")
		(net "M_G_CPU1_SA_CA<2>")
	)
	(segment
		(start 132.70865 -255.05791)
		(end 132.693918 -255.049274)
		(width 0.088646)
		(layer "In4.Cu")
		(net "M_G_CPU1_SA_CA<2>")
	)
	(segment
		(start 136.980168 -254.335026)
		(end 136.696704 -254.335026)
		(width 0.088646)
		(layer "In4.Cu")
		(net "M_G_CPU1_SA_CA<2>")
	)
	(segment
		(start 149.124924 -255.356614)
		(end 146.998182 -256.237486)
		(width 0.18288)
		(layer "In4.Cu")
		(net "M_G_CPU1_SA_CA<2>")
	)
	(segment
		(start 183.697626 -262.249666)
		(end 182.940706 -261.492746)
		(width 0.18288)
		(layer "In4.Cu")
		(net "M_G_CPU1_SA_CA<2>")
	)
	(segment
		(start 178.959764 -261.492492)
		(end 176.433734 -261.492492)
		(width 0.18288)
		(layer "In4.Cu")
		(net "M_G_CPU1_SA_CA<2>")
	)
	(segment
		(start 137.310114 -254.335026)
		(end 136.980168 -254.335026)
		(width 0.18288)
		(layer "In4.Cu")
		(net "M_G_CPU1_SA_CA<2>")
	)
	(segment
		(start 186.147456 -263.833356)
		(end 184.563766 -262.249666)
		(width 0.18288)
		(layer "In4.Cu")
		(net "M_G_CPU1_SA_CA<2>")
	)
	(segment
		(start 160.68802 -259.948426)
		(end 160.396682 -259.657088)
		(width 0.18288)
		(layer "In4.Cu")
		(net "M_G_CPU1_SA_CA<2>")
	)
	(segment
		(start 146.998182 -256.237486)
		(end 145.136616 -256.237486)
		(width 0.18288)
		(layer "In4.Cu")
		(net "M_G_CPU1_SA_CA<2>")
	)
	(segment
		(start 187.883546 -264.466578)
		(end 187.250324 -263.833356)
		(width 0.18288)
		(layer "In4.Cu")
		(net "M_G_CPU1_SA_CA<2>")
	)
	(segment
		(start 160.396682 -259.657088)
		(end 159.515302 -259.657088)
		(width 0.18288)
		(layer "In4.Cu")
		(net "M_G_CPU1_SA_CA<2>")
	)
	(segment
		(start 134.587996 -255.05791)
		(end 134.573264 -255.049274)
		(width 0.088646)
		(layer "In4.Cu")
		(net "M_G_CPU1_SA_CA<2>")
	)
	(segment
		(start 175.581818 -260.640576)
		(end 163.357814 -260.640576)
		(width 0.18288)
		(layer "In4.Cu")
		(net "M_G_CPU1_SA_CA<2>")
	)
	(segment
		(start 187.250324 -263.833356)
		(end 186.147456 -263.833356)
		(width 0.18288)
		(layer "In4.Cu")
		(net "M_G_CPU1_SA_CA<2>")
	)
	(segment
		(start 136.696704 -254.335026)
		(end 136.026906 -255.004824)
		(width 0.088646)
		(layer "In4.Cu")
		(net "M_G_CPU1_SA_CA<2>")
	)
	(segment
		(start 178.960018 -261.492746)
		(end 178.959764 -261.492492)
		(width 0.18288)
		(layer "In4.Cu")
		(net "M_G_CPU1_SA_CA<2>")
	)
	(segment
		(start 141.149832 -254.586232)
		(end 139.33551 -254.586232)
		(width 0.18288)
		(layer "In4.Cu")
		(net "M_G_CPU1_SA_CA<2>")
	)
	(segment
		(start 137.555732 -254.089408)
		(end 137.310114 -254.335026)
		(width 0.18288)
		(layer "In4.Cu")
		(net "M_G_CPU1_SA_CA<2>")
	)
	(segment
		(start 131.768596 -255.05791)
		(end 131.753864 -255.049274)
		(width 0.088646)
		(layer "In4.Cu")
		(net "M_G_CPU1_SA_CA<2>")
	)
	(segment
		(start 145.136616 -256.237486)
		(end 141.149832 -254.586232)
		(width 0.18288)
		(layer "In4.Cu")
		(net "M_G_CPU1_SA_CA<2>")
	)
	(segment
		(start 129.888996 -255.05791)
		(end 129.874264 -255.049274)
		(width 0.088646)
		(layer "In4.Cu")
		(net "M_G_CPU1_SA_CA<2>")
	)
	(segment
		(start 153.076402 -255.356614)
		(end 149.124924 -255.356614)
		(width 0.18288)
		(layer "In4.Cu")
		(net "M_G_CPU1_SA_CA<2>")
	)
	(segment
		(start 128.862836 -255.8669)
		(end 128.853946 -255.87198)
		(width 0.088646)
		(layer "In4.Cu")
		(net "M_G_CPU1_SA_CA<2>")
	)
	(segment
		(start 130.828796 -255.05791)
		(end 130.814064 -255.049274)
		(width 0.088646)
		(layer "In4.Cu")
		(net "M_G_CPU1_SA_CA<2>")
	)
	(segment
		(start 129.041398 -255.525524)
		(end 129.041398 -255.547622)
		(width 0.088646)
		(layer "In4.Cu")
		(net "M_G_CPU1_SA_CA<2>")
	)
	(segment
		(start 156.839666 -259.119878)
		(end 153.076402 -255.356614)
		(width 0.18288)
		(layer "In4.Cu")
		(net "M_G_CPU1_SA_CA<2>")
	)
	(segment
		(start 159.515302 -259.657088)
		(end 158.978092 -259.119878)
		(width 0.18288)
		(layer "In4.Cu")
		(net "M_G_CPU1_SA_CA<2>")
	)
	(segment
		(start 158.978092 -259.119878)
		(end 156.839666 -259.119878)
		(width 0.18288)
		(layer "In4.Cu")
		(net "M_G_CPU1_SA_CA<2>")
	)
	(arc
		(start 131.753864 -255.049274)
		(mid 131.477423 -254.982108)
		(end 131.203192 -255.05791)
		(width 0.088646)
		(layer "In4.Cu")
		(net "M_G_CPU1_SA_CA<2>")
	)
	(arc
		(start 136.026906 -255.004824)
		(mid 135.962951 -255.027614)
		(end 135.902192 -255.05791)
		(width 0.088646)
		(layer "In4.Cu")
		(net "M_G_CPU1_SA_CA<2>")
	)
	(arc
		(start 133.083046 -255.05791)
		(mid 132.895848 -255.108053)
		(end 132.70865 -255.05791)
		(width 0.088646)
		(layer "In4.Cu")
		(net "M_G_CPU1_SA_CA<2>")
	)
	(arc
		(start 128.383792 -256.685796)
		(mid 128.196594 -256.735939)
		(end 128.009396 -256.685796)
		(width 0.088646)
		(layer "In4.Cu")
		(net "M_G_CPU1_SA_CA<2>")
	)
	(arc
		(start 129.323592 -255.05791)
		(mid 129.12231 -255.255397)
		(end 129.041398 -255.525524)
		(width 0.088646)
		(layer "In4.Cu")
		(net "M_G_CPU1_SA_CA<2>")
	)
	(arc
		(start 128.009396 -256.685796)
		(mid 127.726694 -256.61002)
		(end 127.443992 -256.685796)
		(width 0.088646)
		(layer "In4.Cu")
		(net "M_G_CPU1_SA_CA<2>")
	)
	(arc
		(start 135.527796 -255.05791)
		(mid 135.245094 -254.982168)
		(end 134.962392 -255.05791)
		(width 0.088646)
		(layer "In4.Cu")
		(net "M_G_CPU1_SA_CA<2>")
	)
	(arc
		(start 133.648196 -255.05791)
		(mid 133.371637 -254.982201)
		(end 133.09346 -255.051814)
		(width 0.088646)
		(layer "In4.Cu")
		(net "M_G_CPU1_SA_CA<2>")
	)
	(arc
		(start 130.814064 -255.049274)
		(mid 130.537623 -254.982108)
		(end 130.263392 -255.05791)
		(width 0.088646)
		(layer "In4.Cu")
		(net "M_G_CPU1_SA_CA<2>")
	)
	(arc
		(start 134.022592 -255.05791)
		(mid 133.835394 -255.108053)
		(end 133.648196 -255.05791)
		(width 0.088646)
		(layer "In4.Cu")
		(net "M_G_CPU1_SA_CA<2>")
	)
	(arc
		(start 134.962392 -255.05791)
		(mid 134.775194 -255.108053)
		(end 134.587996 -255.05791)
		(width 0.088646)
		(layer "In4.Cu")
		(net "M_G_CPU1_SA_CA<2>")
	)
	(arc
		(start 135.902192 -255.05791)
		(mid 135.714994 -255.108053)
		(end 135.527796 -255.05791)
		(width 0.088646)
		(layer "In4.Cu")
		(net "M_G_CPU1_SA_CA<2>")
	)
	(arc
		(start 130.263392 -255.05791)
		(mid 130.076194 -255.108053)
		(end 129.888996 -255.05791)
		(width 0.088646)
		(layer "In4.Cu")
		(net "M_G_CPU1_SA_CA<2>")
	)
	(arc
		(start 132.143246 -255.05791)
		(mid 131.960741 -255.108148)
		(end 131.776978 -255.062736)
		(width 0.088646)
		(layer "In4.Cu")
		(net "M_G_CPU1_SA_CA<2>")
	)
	(arc
		(start 128.841754 -255.879092)
		(mid 128.643526 -256.08494)
		(end 128.571244 -256.361438)
		(width 0.088646)
		(layer "In4.Cu")
		(net "M_G_CPU1_SA_CA<2>")
	)
	(arc
		(start 132.693918 -255.049274)
		(mid 132.417477 -254.982108)
		(end 132.143246 -255.05791)
		(width 0.088646)
		(layer "In4.Cu")
		(net "M_G_CPU1_SA_CA<2>")
	)
	(arc
		(start 129.041398 -255.547622)
		(mid 128.993719 -255.730522)
		(end 128.862836 -255.8669)
		(width 0.088646)
		(layer "In4.Cu")
		(net "M_G_CPU1_SA_CA<2>")
	)
	(arc
		(start 127.366776 -256.730246)
		(mid 127.062395 -256.933775)
		(end 126.787148 -257.175254)
		(width 0.088646)
		(layer "In4.Cu")
		(net "M_G_CPU1_SA_CA<2>")
	)
	(arc
		(start 134.573264 -255.049274)
		(mid 134.296823 -254.982108)
		(end 134.022592 -255.05791)
		(width 0.088646)
		(layer "In4.Cu")
		(net "M_G_CPU1_SA_CA<2>")
	)
	(arc
		(start 128.571244 -256.361438)
		(mid 128.523565 -256.544338)
		(end 128.392682 -256.680716)
		(width 0.088646)
		(layer "In4.Cu")
		(net "M_G_CPU1_SA_CA<2>")
	)
	(arc
		(start 129.874264 -255.049274)
		(mid 129.597823 -254.982108)
		(end 129.323592 -255.05791)
		(width 0.088646)
		(layer "In4.Cu")
		(net "M_G_CPU1_SA_CA<2>")
	)
	(arc
		(start 131.203192 -255.05791)
		(mid 131.015994 -255.108053)
		(end 130.828796 -255.05791)
		(width 0.088646)
		(layer "In4.Cu")
		(net "M_G_CPU1_SA_CA<2>")
	)
	(segment
		(start 197.535292 -265.741658)
		(end 197.542658 -265.749024)
		(width 0.1016)
		(layer "F.Cu")
		(net "M_G_CPU1_SA_CA<1>")
	)
	(segment
		(start 191.907414 -265.316716)
		(end 193.088514 -265.316716)
		(width 0.20066)
		(layer "F.Cu")
		(net "M_G_CPU1_SA_CA<1>")
	)
	(segment
		(start 194.724274 -265.316716)
		(end 195.159884 -265.752326)
		(width 0.20066)
		(layer "F.Cu")
		(net "M_G_CPU1_SA_CA<1>")
	)
	(segment
		(start 199.0852 -264.884154)
		(end 199.517762 -265.316716)
		(width 0.20066)
		(layer "F.Cu")
		(net "M_G_CPU1_SA_CA<1>")
	)
	(segment
		(start 199.517762 -265.316716)
		(end 200.632314 -265.316716)
		(width 0.20066)
		(layer "F.Cu")
		(net "M_G_CPU1_SA_CA<1>")
	)
	(segment
		(start 195.526152 -265.741658)
		(end 197.535292 -265.741658)
		(width 0.1016)
		(layer "F.Cu")
		(net "M_G_CPU1_SA_CA<1>")
	)
	(segment
		(start 195.159884 -265.752326)
		(end 195.510658 -265.752326)
		(width 0.20066)
		(layer "F.Cu")
		(net "M_G_CPU1_SA_CA<1>")
	)
	(segment
		(start 195.510658 -265.752326)
		(end 195.515484 -265.752326)
		(width 0.101854)
		(layer "F.Cu")
		(net "M_G_CPU1_SA_CA<1>")
	)
	(segment
		(start 193.088514 -265.316716)
		(end 194.724274 -265.316716)
		(width 0.20066)
		(layer "F.Cu")
		(net "M_G_CPU1_SA_CA<1>")
	)
	(segment
		(start 198.681594 -264.884154)
		(end 199.0852 -264.884154)
		(width 0.20066)
		(layer "F.Cu")
		(net "M_G_CPU1_SA_CA<1>")
	)
	(segment
		(start 197.542658 -265.749024)
		(end 197.816724 -265.749024)
		(width 0.20066)
		(layer "F.Cu")
		(net "M_G_CPU1_SA_CA<1>")
	)
	(segment
		(start 129.136648 -257.45313)
		(end 129.136394 -257.98907)
		(width 0.20066)
		(layer "F.Cu")
		(net "M_G_CPU1_SA_CA<1>")
	)
	(segment
		(start 197.816724 -265.749024)
		(end 198.681594 -264.884154)
		(width 0.20066)
		(layer "F.Cu")
		(net "M_G_CPU1_SA_CA<1>")
	)
	(segment
		(start 195.515484 -265.752326)
		(end 195.526152 -265.741658)
		(width 0.1016)
		(layer "F.Cu")
		(net "M_G_CPU1_SA_CA<1>")
	)
	(segment
		(start 159.834326 -262.460994)
		(end 158.863792 -261.49046)
		(width 0.18288)
		(layer "In4.Cu")
		(net "M_G_CPU1_SA_CA<1>")
	)
	(segment
		(start 183.964326 -264.985246)
		(end 183.123586 -264.144506)
		(width 0.18288)
		(layer "In4.Cu")
		(net "M_G_CPU1_SA_CA<1>")
	)
	(segment
		(start 178.049682 -263.90727)
		(end 177.9143 -264.042652)
		(width 0.18288)
		(layer "In4.Cu")
		(net "M_G_CPU1_SA_CA<1>")
	)
	(segment
		(start 175.404526 -263.18845)
		(end 172.114972 -263.18845)
		(width 0.18288)
		(layer "In4.Cu")
		(net "M_G_CPU1_SA_CA<1>")
	)
	(segment
		(start 136.73201 -256.112772)
		(end 136.184894 -256.112772)
		(width 0.088646)
		(layer "In4.Cu")
		(net "M_G_CPU1_SA_CA<1>")
	)
	(segment
		(start 191.281304 -265.942826)
		(end 188.917326 -265.942826)
		(width 0.18288)
		(layer "In4.Cu")
		(net "M_G_CPU1_SA_CA<1>")
	)
	(segment
		(start 180.896006 -263.829546)
		(end 180.586126 -264.139426)
		(width 0.18288)
		(layer "In4.Cu")
		(net "M_G_CPU1_SA_CA<1>")
	)
	(segment
		(start 179.501038 -264.139426)
		(end 179.268882 -263.90727)
		(width 0.18288)
		(layer "In4.Cu")
		(net "M_G_CPU1_SA_CA<1>")
	)
	(segment
		(start 147.376388 -257.243326)
		(end 144.935194 -257.243326)
		(width 0.18288)
		(layer "In4.Cu")
		(net "M_G_CPU1_SA_CA<1>")
	)
	(segment
		(start 168.688512 -263.39673)
		(end 168.449498 -263.157716)
		(width 0.18288)
		(layer "In4.Cu")
		(net "M_G_CPU1_SA_CA<1>")
	)
	(segment
		(start 183.123586 -264.144506)
		(end 182.353966 -264.144506)
		(width 0.18288)
		(layer "In4.Cu")
		(net "M_G_CPU1_SA_CA<1>")
	)
	(segment
		(start 144.935194 -257.243326)
		(end 141.213332 -255.7018)
		(width 0.18288)
		(layer "In4.Cu")
		(net "M_G_CPU1_SA_CA<1>")
	)
	(segment
		(start 139.73175 -255.7018)
		(end 139.36472 -255.7018)
		(width 0.088646)
		(layer "In4.Cu")
		(net "M_G_CPU1_SA_CA<1>")
	)
	(segment
		(start 148.325586 -256.850134)
		(end 147.376388 -257.243326)
		(width 0.18288)
		(layer "In4.Cu")
		(net "M_G_CPU1_SA_CA<1>")
	)
	(segment
		(start 163.304728 -263.430004)
		(end 162.053778 -262.179054)
		(width 0.18288)
		(layer "In4.Cu")
		(net "M_G_CPU1_SA_CA<1>")
	)
	(segment
		(start 188.267848 -266.592304)
		(end 186.313064 -266.592304)
		(width 0.18288)
		(layer "In4.Cu")
		(net "M_G_CPU1_SA_CA<1>")
	)
	(segment
		(start 129.231898 -257.175254)
		(end 129.231898 -257.485642)
		(width 0.088646)
		(layer "In4.Cu")
		(net "M_G_CPU1_SA_CA<1>")
	)
	(segment
		(start 176.258728 -264.042652)
		(end 175.404526 -263.18845)
		(width 0.18288)
		(layer "In4.Cu")
		(net "M_G_CPU1_SA_CA<1>")
	)
	(segment
		(start 191.907414 -265.316716)
		(end 191.281304 -265.942826)
		(width 0.18288)
		(layer "In4.Cu")
		(net "M_G_CPU1_SA_CA<1>")
	)
	(segment
		(start 168.449498 -263.157716)
		(end 164.72789 -263.157716)
		(width 0.18288)
		(layer "In4.Cu")
		(net "M_G_CPU1_SA_CA<1>")
	)
	(segment
		(start 160.903158 -262.179054)
		(end 160.621218 -262.460994)
		(width 0.18288)
		(layer "In4.Cu")
		(net "M_G_CPU1_SA_CA<1>")
	)
	(segment
		(start 160.621218 -262.460994)
		(end 159.834326 -262.460994)
		(width 0.18288)
		(layer "In4.Cu")
		(net "M_G_CPU1_SA_CA<1>")
	)
	(segment
		(start 177.9143 -264.042652)
		(end 176.258728 -264.042652)
		(width 0.18288)
		(layer "In4.Cu")
		(net "M_G_CPU1_SA_CA<1>")
	)
	(segment
		(start 139.116308 -255.950212)
		(end 136.89457 -255.950212)
		(width 0.088646)
		(layer "In4.Cu")
		(net "M_G_CPU1_SA_CA<1>")
	)
	(segment
		(start 182.039006 -263.829546)
		(end 180.896006 -263.829546)
		(width 0.18288)
		(layer "In4.Cu")
		(net "M_G_CPU1_SA_CA<1>")
	)
	(segment
		(start 182.353966 -264.144506)
		(end 182.039006 -263.829546)
		(width 0.18288)
		(layer "In4.Cu")
		(net "M_G_CPU1_SA_CA<1>")
	)
	(segment
		(start 162.053778 -262.179054)
		(end 160.903158 -262.179054)
		(width 0.18288)
		(layer "In4.Cu")
		(net "M_G_CPU1_SA_CA<1>")
	)
	(segment
		(start 158.863792 -261.49046)
		(end 156.856938 -261.49046)
		(width 0.18288)
		(layer "In4.Cu")
		(net "M_G_CPU1_SA_CA<1>")
	)
	(segment
		(start 129.231898 -257.485642)
		(end 129.136394 -257.98907)
		(width 0.088646)
		(layer "In4.Cu")
		(net "M_G_CPU1_SA_CA<1>")
	)
	(segment
		(start 184.706006 -264.985246)
		(end 183.964326 -264.985246)
		(width 0.18288)
		(layer "In4.Cu")
		(net "M_G_CPU1_SA_CA<1>")
	)
	(segment
		(start 179.268882 -263.90727)
		(end 178.049682 -263.90727)
		(width 0.18288)
		(layer "In4.Cu")
		(net "M_G_CPU1_SA_CA<1>")
	)
	(segment
		(start 139.36472 -255.7018)
		(end 139.116308 -255.950212)
		(width 0.088646)
		(layer "In4.Cu")
		(net "M_G_CPU1_SA_CA<1>")
	)
	(segment
		(start 134.587996 -256.03708)
		(end 134.573264 -256.045716)
		(width 0.088646)
		(layer "In4.Cu")
		(net "M_G_CPU1_SA_CA<1>")
	)
	(segment
		(start 152.216612 -256.850134)
		(end 148.325586 -256.850134)
		(width 0.18288)
		(layer "In4.Cu")
		(net "M_G_CPU1_SA_CA<1>")
	)
	(segment
		(start 129.41935 -256.850896)
		(end 129.41046 -256.855976)
		(width 0.088646)
		(layer "In4.Cu")
		(net "M_G_CPU1_SA_CA<1>")
	)
	(segment
		(start 129.701798 -256.352802)
		(end 129.701798 -256.371344)
		(width 0.088646)
		(layer "In4.Cu")
		(net "M_G_CPU1_SA_CA<1>")
	)
	(segment
		(start 180.586126 -264.139426)
		(end 179.501038 -264.139426)
		(width 0.18288)
		(layer "In4.Cu")
		(net "M_G_CPU1_SA_CA<1>")
	)
	(segment
		(start 156.856938 -261.49046)
		(end 152.216612 -256.850134)
		(width 0.18288)
		(layer "In4.Cu")
		(net "M_G_CPU1_SA_CA<1>")
	)
	(segment
		(start 136.89457 -255.950212)
		(end 136.73201 -256.112772)
		(width 0.088646)
		(layer "In4.Cu")
		(net "M_G_CPU1_SA_CA<1>")
	)
	(segment
		(start 171.906692 -263.39673)
		(end 168.688512 -263.39673)
		(width 0.18288)
		(layer "In4.Cu")
		(net "M_G_CPU1_SA_CA<1>")
	)
	(segment
		(start 164.455602 -263.430004)
		(end 163.304728 -263.430004)
		(width 0.18288)
		(layer "In4.Cu")
		(net "M_G_CPU1_SA_CA<1>")
	)
	(segment
		(start 164.72789 -263.157716)
		(end 164.455602 -263.430004)
		(width 0.18288)
		(layer "In4.Cu")
		(net "M_G_CPU1_SA_CA<1>")
	)
	(segment
		(start 131.768596 -256.03708)
		(end 131.753864 -256.045716)
		(width 0.088646)
		(layer "In4.Cu")
		(net "M_G_CPU1_SA_CA<1>")
	)
	(segment
		(start 186.313064 -266.592304)
		(end 184.706006 -264.985246)
		(width 0.18288)
		(layer "In4.Cu")
		(net "M_G_CPU1_SA_CA<1>")
	)
	(segment
		(start 188.917326 -265.942826)
		(end 188.267848 -266.592304)
		(width 0.18288)
		(layer "In4.Cu")
		(net "M_G_CPU1_SA_CA<1>")
	)
	(segment
		(start 141.213332 -255.7018)
		(end 139.73175 -255.7018)
		(width 0.18288)
		(layer "In4.Cu")
		(net "M_G_CPU1_SA_CA<1>")
	)
	(segment
		(start 130.828796 -256.03708)
		(end 130.814064 -256.045716)
		(width 0.088646)
		(layer "In4.Cu")
		(net "M_G_CPU1_SA_CA<1>")
	)
	(segment
		(start 172.114972 -263.18845)
		(end 171.906692 -263.39673)
		(width 0.18288)
		(layer "In4.Cu")
		(net "M_G_CPU1_SA_CA<1>")
	)
	(arc
		(start 132.142992 -256.03708)
		(mid 131.955794 -255.986937)
		(end 131.768596 -256.03708)
		(width 0.088646)
		(layer "In4.Cu")
		(net "M_G_CPU1_SA_CA<1>")
	)
	(arc
		(start 130.814064 -256.045716)
		(mid 130.537589 -256.113036)
		(end 130.263392 -256.03708)
		(width 0.088646)
		(layer "In4.Cu")
		(net "M_G_CPU1_SA_CA<1>")
	)
	(arc
		(start 129.41046 -256.855976)
		(mid 129.279546 -256.992336)
		(end 129.231898 -257.175254)
		(width 0.088646)
		(layer "In4.Cu")
		(net "M_G_CPU1_SA_CA<1>")
	)
	(arc
		(start 131.203192 -256.03708)
		(mid 131.015994 -255.986937)
		(end 130.828796 -256.03708)
		(width 0.088646)
		(layer "In4.Cu")
		(net "M_G_CPU1_SA_CA<1>")
	)
	(arc
		(start 136.184894 -256.112772)
		(mid 136.03855 -256.093564)
		(end 135.902192 -256.03708)
		(width 0.088646)
		(layer "In4.Cu")
		(net "M_G_CPU1_SA_CA<1>")
	)
	(arc
		(start 134.022592 -256.03708)
		(mid 133.835394 -255.986937)
		(end 133.648196 -256.03708)
		(width 0.088646)
		(layer "In4.Cu")
		(net "M_G_CPU1_SA_CA<1>")
	)
	(arc
		(start 135.527796 -256.03708)
		(mid 135.245094 -256.112856)
		(end 134.962392 -256.03708)
		(width 0.088646)
		(layer "In4.Cu")
		(net "M_G_CPU1_SA_CA<1>")
	)
	(arc
		(start 133.648196 -256.03708)
		(mid 133.365494 -256.112856)
		(end 133.082792 -256.03708)
		(width 0.088646)
		(layer "In4.Cu")
		(net "M_G_CPU1_SA_CA<1>")
	)
	(arc
		(start 131.753864 -256.045716)
		(mid 131.477389 -256.113036)
		(end 131.203192 -256.03708)
		(width 0.088646)
		(layer "In4.Cu")
		(net "M_G_CPU1_SA_CA<1>")
	)
	(arc
		(start 132.708396 -256.03708)
		(mid 132.425694 -256.112856)
		(end 132.142992 -256.03708)
		(width 0.088646)
		(layer "In4.Cu")
		(net "M_G_CPU1_SA_CA<1>")
	)
	(arc
		(start 135.902192 -256.03708)
		(mid 135.714994 -255.986937)
		(end 135.527796 -256.03708)
		(width 0.088646)
		(layer "In4.Cu")
		(net "M_G_CPU1_SA_CA<1>")
	)
	(arc
		(start 129.888996 -256.03708)
		(mid 129.754063 -256.170434)
		(end 129.701798 -256.352802)
		(width 0.088646)
		(layer "In4.Cu")
		(net "M_G_CPU1_SA_CA<1>")
	)
	(arc
		(start 129.701798 -256.371344)
		(mid 129.623687 -256.648293)
		(end 129.41935 -256.850896)
		(width 0.088646)
		(layer "In4.Cu")
		(net "M_G_CPU1_SA_CA<1>")
	)
	(arc
		(start 134.573264 -256.045716)
		(mid 134.296789 -256.113036)
		(end 134.022592 -256.03708)
		(width 0.088646)
		(layer "In4.Cu")
		(net "M_G_CPU1_SA_CA<1>")
	)
	(arc
		(start 134.962392 -256.03708)
		(mid 134.775194 -255.986937)
		(end 134.587996 -256.03708)
		(width 0.088646)
		(layer "In4.Cu")
		(net "M_G_CPU1_SA_CA<1>")
	)
	(arc
		(start 133.082792 -256.03708)
		(mid 132.895594 -255.986937)
		(end 132.708396 -256.03708)
		(width 0.088646)
		(layer "In4.Cu")
		(net "M_G_CPU1_SA_CA<1>")
	)
	(arc
		(start 130.263392 -256.03708)
		(mid 130.076194 -255.986937)
		(end 129.888996 -256.03708)
		(width 0.088646)
		(layer "In4.Cu")
		(net "M_G_CPU1_SA_CA<1>")
	)
	(segment
		(start 194.08648 -266.591542)
		(end 194.098926 -266.603988)
		(width 0.1016)
		(layer "F.Cu")
		(net "M_G_CPU1_SA_CA<0>")
	)
	(segment
		(start 190.873634 -265.672316)
		(end 191.79286 -266.591542)
		(width 0.20066)
		(layer "F.Cu")
		(net "M_G_CPU1_SA_CA<0>")
	)
	(segment
		(start 126.317248 -257.45313)
		(end 126.316994 -257.98907)
		(width 0.20066)
		(layer "F.Cu")
		(net "M_G_CPU1_SA_CA<0>")
	)
	(segment
		(start 196.531992 -266.166346)
		(end 196.532246 -266.1666)
		(width 0.20066)
		(layer "F.Cu")
		(net "M_G_CPU1_SA_CA<0>")
	)
	(segment
		(start 194.95262 -266.166346)
		(end 196.531992 -266.166346)
		(width 0.20066)
		(layer "F.Cu")
		(net "M_G_CPU1_SA_CA<0>")
	)
	(segment
		(start 187.883546 -266.1666)
		(end 188.988446 -266.1666)
		(width 0.20066)
		(layer "F.Cu")
		(net "M_G_CPU1_SA_CA<0>")
	)
	(segment
		(start 194.514978 -266.603988)
		(end 194.95262 -266.166346)
		(width 0.20066)
		(layer "F.Cu")
		(net "M_G_CPU1_SA_CA<0>")
	)
	(segment
		(start 190.053976 -266.1666)
		(end 190.54826 -265.672316)
		(width 0.20066)
		(layer "F.Cu")
		(net "M_G_CPU1_SA_CA<0>")
	)
	(segment
		(start 188.988446 -266.1666)
		(end 190.053976 -266.1666)
		(width 0.20066)
		(layer "F.Cu")
		(net "M_G_CPU1_SA_CA<0>")
	)
	(segment
		(start 194.098926 -266.603988)
		(end 194.514978 -266.603988)
		(width 0.20066)
		(layer "F.Cu")
		(net "M_G_CPU1_SA_CA<0>")
	)
	(segment
		(start 191.914018 -266.591542)
		(end 194.08648 -266.591542)
		(width 0.1016)
		(layer "F.Cu")
		(net "M_G_CPU1_SA_CA<0>")
	)
	(segment
		(start 191.79286 -266.591542)
		(end 191.900302 -266.591542)
		(width 0.20066)
		(layer "F.Cu")
		(net "M_G_CPU1_SA_CA<0>")
	)
	(segment
		(start 190.54826 -265.672316)
		(end 190.873634 -265.672316)
		(width 0.20066)
		(layer "F.Cu")
		(net "M_G_CPU1_SA_CA<0>")
	)
	(segment
		(start 191.900302 -266.591542)
		(end 191.914018 -266.591542)
		(width 0.101854)
		(layer "F.Cu")
		(net "M_G_CPU1_SA_CA<0>")
	)
	(segment
		(start 138.538458 -255.154684)
		(end 136.990582 -255.154684)
		(width 0.088646)
		(layer "In4.Cu")
		(net "M_G_CPU1_SA_CA<0>")
	)
	(segment
		(start 134.50316 -255.865884)
		(end 134.492746 -255.87198)
		(width 0.088646)
		(layer "In4.Cu")
		(net "M_G_CPU1_SA_CA<0>")
	)
	(segment
		(start 184.751218 -263.936226)
		(end 183.72709 -263.936226)
		(width 0.18288)
		(layer "In4.Cu")
		(net "M_G_CPU1_SA_CA<0>")
	)
	(segment
		(start 136.990582 -255.154684)
		(end 136.860026 -255.28524)
		(width 0.088646)
		(layer "In4.Cu")
		(net "M_G_CPU1_SA_CA<0>")
	)
	(segment
		(start 185.617866 -264.802874)
		(end 184.751218 -263.936226)
		(width 0.18288)
		(layer "In4.Cu")
		(net "M_G_CPU1_SA_CA<0>")
	)
	(segment
		(start 179.544726 -263.326626)
		(end 178.318922 -263.326626)
		(width 0.18288)
		(layer "In4.Cu")
		(net "M_G_CPU1_SA_CA<0>")
	)
	(segment
		(start 161.547048 -261.565136)
		(end 161.294572 -261.31266)
		(width 0.18288)
		(layer "In4.Cu")
		(net "M_G_CPU1_SA_CA<0>")
	)
	(segment
		(start 185.617866 -264.812526)
		(end 185.617866 -264.802874)
		(width 0.18288)
		(layer "In4.Cu")
		(net "M_G_CPU1_SA_CA<0>")
	)
	(segment
		(start 138.75004 -255.366266)
		(end 138.538458 -255.154684)
		(width 0.088646)
		(layer "In4.Cu")
		(net "M_G_CPU1_SA_CA<0>")
	)
	(segment
		(start 129.793746 -255.87198)
		(end 129.78765 -255.875536)
		(width 0.088646)
		(layer "In4.Cu")
		(net "M_G_CPU1_SA_CA<0>")
	)
	(segment
		(start 178.18735 -263.195054)
		(end 176.454054 -263.195054)
		(width 0.18288)
		(layer "In4.Cu")
		(net "M_G_CPU1_SA_CA<0>")
	)
	(segment
		(start 131.68376 -255.865884)
		(end 131.673346 -255.87198)
		(width 0.088646)
		(layer "In4.Cu")
		(net "M_G_CPU1_SA_CA<0>")
	)
	(segment
		(start 129.041398 -257.165348)
		(end 129.041398 -257.175254)
		(width 0.088646)
		(layer "In4.Cu")
		(net "M_G_CPU1_SA_CA<0>")
	)
	(segment
		(start 128.862836 -257.494532)
		(end 128.853946 -257.499612)
		(width 0.088646)
		(layer "In4.Cu")
		(net "M_G_CPU1_SA_CA<0>")
	)
	(segment
		(start 130.748278 -255.863344)
		(end 130.733546 -255.87198)
		(width 0.088646)
		(layer "In4.Cu")
		(net "M_G_CPU1_SA_CA<0>")
	)
	(segment
		(start 179.823618 -263.047734)
		(end 179.544726 -263.326626)
		(width 0.18288)
		(layer "In4.Cu")
		(net "M_G_CPU1_SA_CA<0>")
	)
	(segment
		(start 186.417966 -265.612626)
		(end 185.617866 -264.812526)
		(width 0.18288)
		(layer "In4.Cu")
		(net "M_G_CPU1_SA_CA<0>")
	)
	(segment
		(start 147.274788 -256.908046)
		(end 145.001996 -256.908046)
		(width 0.18288)
		(layer "In4.Cu")
		(net "M_G_CPU1_SA_CA<0>")
	)
	(segment
		(start 175.599852 -262.340852)
		(end 163.228782 -262.340852)
		(width 0.18288)
		(layer "In4.Cu")
		(net "M_G_CPU1_SA_CA<0>")
	)
	(segment
		(start 159.259524 -260.889496)
		(end 156.967174 -260.889496)
		(width 0.18288)
		(layer "In4.Cu")
		(net "M_G_CPU1_SA_CA<0>")
	)
	(segment
		(start 141.27988 -255.366266)
		(end 139.73175 -255.366266)
		(width 0.18288)
		(layer "In4.Cu")
		(net "M_G_CPU1_SA_CA<0>")
	)
	(segment
		(start 152.429972 -256.352294)
		(end 148.616162 -256.352294)
		(width 0.18288)
		(layer "In4.Cu")
		(net "M_G_CPU1_SA_CA<0>")
	)
	(segment
		(start 178.318922 -263.326626)
		(end 178.18735 -263.195054)
		(width 0.18288)
		(layer "In4.Cu")
		(net "M_G_CPU1_SA_CA<0>")
	)
	(segment
		(start 139.73175 -255.366266)
		(end 138.75004 -255.366266)
		(width 0.088646)
		(layer "In4.Cu")
		(net "M_G_CPU1_SA_CA<0>")
	)
	(segment
		(start 145.001996 -256.908046)
		(end 141.27988 -255.366266)
		(width 0.18288)
		(layer "In4.Cu")
		(net "M_G_CPU1_SA_CA<0>")
	)
	(segment
		(start 161.294572 -261.31266)
		(end 159.682688 -261.31266)
		(width 0.18288)
		(layer "In4.Cu")
		(net "M_G_CPU1_SA_CA<0>")
	)
	(segment
		(start 136.325102 -255.919478)
		(end 136.228582 -255.919478)
		(width 0.088646)
		(layer "In4.Cu")
		(net "M_G_CPU1_SA_CA<0>")
	)
	(segment
		(start 182.838598 -263.047734)
		(end 179.823618 -263.047734)
		(width 0.18288)
		(layer "In4.Cu")
		(net "M_G_CPU1_SA_CA<0>")
	)
	(segment
		(start 183.72709 -263.936226)
		(end 182.838598 -263.047734)
		(width 0.18288)
		(layer "In4.Cu")
		(net "M_G_CPU1_SA_CA<0>")
	)
	(segment
		(start 187.883546 -266.1666)
		(end 187.329572 -265.612626)
		(width 0.18288)
		(layer "In4.Cu")
		(net "M_G_CPU1_SA_CA<0>")
	)
	(segment
		(start 156.967174 -260.889496)
		(end 152.429972 -256.352294)
		(width 0.18288)
		(layer "In4.Cu")
		(net "M_G_CPU1_SA_CA<0>")
	)
	(segment
		(start 148.616162 -256.352294)
		(end 147.274788 -256.908046)
		(width 0.18288)
		(layer "In4.Cu")
		(net "M_G_CPU1_SA_CA<0>")
	)
	(segment
		(start 129.511044 -256.361438)
		(end 129.511044 -256.370074)
		(width 0.088646)
		(layer "In4.Cu")
		(net "M_G_CPU1_SA_CA<0>")
	)
	(segment
		(start 159.682688 -261.31266)
		(end 159.259524 -260.889496)
		(width 0.18288)
		(layer "In4.Cu")
		(net "M_G_CPU1_SA_CA<0>")
	)
	(segment
		(start 176.454054 -263.195054)
		(end 175.599852 -262.340852)
		(width 0.18288)
		(layer "In4.Cu")
		(net "M_G_CPU1_SA_CA<0>")
	)
	(segment
		(start 163.228782 -262.340852)
		(end 162.453066 -261.565136)
		(width 0.18288)
		(layer "In4.Cu")
		(net "M_G_CPU1_SA_CA<0>")
	)
	(segment
		(start 162.453066 -261.565136)
		(end 161.547048 -261.565136)
		(width 0.18288)
		(layer "In4.Cu")
		(net "M_G_CPU1_SA_CA<0>")
	)
	(segment
		(start 126.659894 -257.646678)
		(end 126.316994 -257.98907)
		(width 0.088646)
		(layer "In4.Cu")
		(net "M_G_CPU1_SA_CA<0>")
	)
	(segment
		(start 133.563106 -255.865884)
		(end 133.552692 -255.87198)
		(width 0.088646)
		(layer "In4.Cu")
		(net "M_G_CPU1_SA_CA<0>")
	)
	(segment
		(start 129.808478 -255.863344)
		(end 129.793746 -255.87198)
		(width 0.088646)
		(layer "In4.Cu")
		(net "M_G_CPU1_SA_CA<0>")
	)
	(segment
		(start 187.329572 -265.612626)
		(end 186.417966 -265.612626)
		(width 0.18288)
		(layer "In4.Cu")
		(net "M_G_CPU1_SA_CA<0>")
	)
	(segment
		(start 136.84504 -255.305052)
		(end 136.591548 -255.761744)
		(width 0.088646)
		(layer "In4.Cu")
		(net "M_G_CPU1_SA_CA<0>")
	)
	(arc
		(start 130.35915 -255.87198)
		(mid 130.084951 -255.796145)
		(end 129.808478 -255.863344)
		(width 0.088646)
		(layer "In4.Cu")
		(net "M_G_CPU1_SA_CA<0>")
	)
	(arc
		(start 129.041398 -257.175254)
		(mid 128.993719 -257.358154)
		(end 128.862836 -257.494532)
		(width 0.088646)
		(layer "In4.Cu")
		(net "M_G_CPU1_SA_CA<0>")
	)
	(arc
		(start 132.612892 -255.87198)
		(mid 132.425694 -255.922123)
		(end 132.238496 -255.87198)
		(width 0.088646)
		(layer "In4.Cu")
		(net "M_G_CPU1_SA_CA<0>")
	)
	(arc
		(start 135.057896 -255.87198)
		(mid 134.781337 -255.796237)
		(end 134.50316 -255.865884)
		(width 0.088646)
		(layer "In4.Cu")
		(net "M_G_CPU1_SA_CA<0>")
	)
	(arc
		(start 129.511044 -256.370074)
		(mid 129.458774 -256.552439)
		(end 129.323846 -256.685796)
		(width 0.088646)
		(layer "In4.Cu")
		(net "M_G_CPU1_SA_CA<0>")
	)
	(arc
		(start 128.853946 -257.499612)
		(mid 128.666748 -257.549755)
		(end 128.47955 -257.499612)
		(width 0.088646)
		(layer "In4.Cu")
		(net "M_G_CPU1_SA_CA<0>")
	)
	(arc
		(start 135.432292 -255.87198)
		(mid 135.245094 -255.922123)
		(end 135.057896 -255.87198)
		(width 0.088646)
		(layer "In4.Cu")
		(net "M_G_CPU1_SA_CA<0>")
	)
	(arc
		(start 135.971788 -255.857756)
		(mid 135.700249 -255.796386)
		(end 135.432292 -255.87198)
		(width 0.088646)
		(layer "In4.Cu")
		(net "M_G_CPU1_SA_CA<0>")
	)
	(arc
		(start 136.860026 -255.28524)
		(mid 136.851858 -255.294633)
		(end 136.84504 -255.305052)
		(width 0.088646)
		(layer "In4.Cu")
		(net "M_G_CPU1_SA_CA<0>")
	)
	(arc
		(start 132.238496 -255.87198)
		(mid 131.961937 -255.796237)
		(end 131.68376 -255.865884)
		(width 0.088646)
		(layer "In4.Cu")
		(net "M_G_CPU1_SA_CA<0>")
	)
	(arc
		(start 127.951484 -257.479292)
		(mid 127.942129 -257.483704)
		(end 127.932688 -257.487928)
		(width 0.088646)
		(layer "In4.Cu")
		(net "M_G_CPU1_SA_CA<0>")
	)
	(arc
		(start 133.552692 -255.87198)
		(mid 133.365494 -255.922123)
		(end 133.178296 -255.87198)
		(width 0.088646)
		(layer "In4.Cu")
		(net "M_G_CPU1_SA_CA<0>")
	)
	(arc
		(start 127.932688 -257.487928)
		(mid 127.731379 -257.549656)
		(end 127.528574 -257.493008)
		(width 0.088646)
		(layer "In4.Cu")
		(net "M_G_CPU1_SA_CA<0>")
	)
	(arc
		(start 127.04445 -257.447542)
		(mid 126.957126 -257.509033)
		(end 126.855982 -257.5433)
		(width 0.088646)
		(layer "In4.Cu")
		(net "M_G_CPU1_SA_CA<0>")
	)
	(arc
		(start 126.855982 -257.5433)
		(mid 126.750128 -257.580166)
		(end 126.659894 -257.646678)
		(width 0.088646)
		(layer "In4.Cu")
		(net "M_G_CPU1_SA_CA<0>")
	)
	(arc
		(start 136.228582 -255.919478)
		(mid 136.096527 -255.903833)
		(end 135.971788 -255.857756)
		(width 0.088646)
		(layer "In4.Cu")
		(net "M_G_CPU1_SA_CA<0>")
	)
	(arc
		(start 131.673346 -255.87198)
		(mid 131.486148 -255.922123)
		(end 131.29895 -255.87198)
		(width 0.088646)
		(layer "In4.Cu")
		(net "M_G_CPU1_SA_CA<0>")
	)
	(arc
		(start 128.47955 -257.499612)
		(mid 128.218041 -257.423998)
		(end 127.951484 -257.479292)
		(width 0.088646)
		(layer "In4.Cu")
		(net "M_G_CPU1_SA_CA<0>")
	)
	(arc
		(start 131.29895 -255.87198)
		(mid 131.024751 -255.796145)
		(end 130.748278 -255.863344)
		(width 0.088646)
		(layer "In4.Cu")
		(net "M_G_CPU1_SA_CA<0>")
	)
	(arc
		(start 127.451358 -257.449066)
		(mid 127.302776 -257.39996)
		(end 127.146304 -257.398012)
		(width 0.088646)
		(layer "In4.Cu")
		(net "M_G_CPU1_SA_CA<0>")
	)
	(arc
		(start 136.591548 -255.761744)
		(mid 136.47989 -255.877045)
		(end 136.325102 -255.919478)
		(width 0.088646)
		(layer "In4.Cu")
		(net "M_G_CPU1_SA_CA<0>")
	)
	(arc
		(start 134.492746 -255.87198)
		(mid 134.305548 -255.922123)
		(end 134.11835 -255.87198)
		(width 0.088646)
		(layer "In4.Cu")
		(net "M_G_CPU1_SA_CA<0>")
	)
	(arc
		(start 133.178296 -255.87198)
		(mid 132.895594 -255.796204)
		(end 132.612892 -255.87198)
		(width 0.088646)
		(layer "In4.Cu")
		(net "M_G_CPU1_SA_CA<0>")
	)
	(arc
		(start 127.528574 -257.493008)
		(mid 127.490432 -257.470218)
		(end 127.451358 -257.449066)
		(width 0.088646)
		(layer "In4.Cu")
		(net "M_G_CPU1_SA_CA<0>")
	)
	(arc
		(start 129.78765 -255.875536)
		(mid 129.585063 -256.081887)
		(end 129.511044 -256.361438)
		(width 0.088646)
		(layer "In4.Cu")
		(net "M_G_CPU1_SA_CA<0>")
	)
	(arc
		(start 130.733546 -255.87198)
		(mid 130.546348 -255.922123)
		(end 130.35915 -255.87198)
		(width 0.088646)
		(layer "In4.Cu")
		(net "M_G_CPU1_SA_CA<0>")
	)
	(arc
		(start 127.146304 -257.398012)
		(mid 127.091557 -257.414912)
		(end 127.04445 -257.447542)
		(width 0.088646)
		(layer "In4.Cu")
		(net "M_G_CPU1_SA_CA<0>")
	)
	(arc
		(start 134.11835 -255.87198)
		(mid 133.841537 -255.79611)
		(end 133.563106 -255.865884)
		(width 0.088646)
		(layer "In4.Cu")
		(net "M_G_CPU1_SA_CA<0>")
	)
	(arc
		(start 129.323846 -256.685796)
		(mid 129.119511 -256.888401)
		(end 129.041398 -257.165348)
		(width 0.088646)
		(layer "In4.Cu")
		(net "M_G_CPU1_SA_CA<0>")
	)
	(segment
		(start 193.088514 -260.21665)
		(end 191.983614 -260.21665)
		(width 0.20066)
		(layer "F.Cu")
		(net "M_G_CPU1_CLK_DP<1>")
	)
	(segment
		(start 126.207266 -250.155964)
		(end 126.207012 -250.15571)
		(width 0.20066)
		(layer "F.Cu")
		(net "M_G_CPU1_CLK_DP<1>")
	)
	(segment
		(start 126.207012 -250.15571)
		(end 126.207012 -249.620024)
		(width 0.20066)
		(layer "F.Cu")
		(net "M_G_CPU1_CLK_DP<1>")
	)
	(segment
		(start 126.53264 -249.945652)
		(end 126.207012 -249.620024)
		(width 0.18288)
		(layer "In4.Cu")
		(net "M_G_CPU1_CLK_DP<1>")
	)
	(segment
		(start 188.544454 -257.399282)
		(end 186.062112 -256.905506)
		(width 0.18288)
		(layer "In4.Cu")
		(net "M_G_CPU1_CLK_DP<1>")
	)
	(segment
		(start 142.23746 -252.0061)
		(end 127.75057 -252.0061)
		(width 0.18288)
		(layer "In4.Cu")
		(net "M_G_CPU1_CLK_DP<1>")
	)
	(segment
		(start 127.75057 -252.0061)
		(end 126.53264 -250.78817)
		(width 0.18288)
		(layer "In4.Cu")
		(net "M_G_CPU1_CLK_DP<1>")
	)
	(segment
		(start 190.744602 -258.320286)
		(end 190.727838 -258.303522)
		(width 0.18288)
		(layer "In4.Cu")
		(net "M_G_CPU1_CLK_DP<1>")
	)
	(segment
		(start 159.387032 -256.232152)
		(end 156.80436 -255.162812)
		(width 0.18288)
		(layer "In4.Cu")
		(net "M_G_CPU1_CLK_DP<1>")
	)
	(segment
		(start 148.980652 -252.867414)
		(end 148.424646 -253.423674)
		(width 0.18288)
		(layer "In4.Cu")
		(net "M_G_CPU1_CLK_DP<1>")
	)
	(segment
		(start 190.727838 -258.303522)
		(end 188.544454 -257.399282)
		(width 0.18288)
		(layer "In4.Cu")
		(net "M_G_CPU1_CLK_DP<1>")
	)
	(segment
		(start 145.472404 -254.560832)
		(end 144.311116 -254.079756)
		(width 0.18288)
		(layer "In4.Cu")
		(net "M_G_CPU1_CLK_DP<1>")
	)
	(segment
		(start 147.868132 -253.980188)
		(end 146.466306 -254.560832)
		(width 0.18288)
		(layer "In4.Cu")
		(net "M_G_CPU1_CLK_DP<1>")
	)
	(segment
		(start 190.744602 -259.404104)
		(end 190.744602 -258.320286)
		(width 0.18288)
		(layer "In4.Cu")
		(net "M_G_CPU1_CLK_DP<1>")
	)
	(segment
		(start 146.466306 -254.560832)
		(end 145.472404 -254.560832)
		(width 0.18288)
		(layer "In4.Cu")
		(net "M_G_CPU1_CLK_DP<1>")
	)
	(segment
		(start 148.424646 -253.423674)
		(end 148.424392 -253.423674)
		(width 0.18288)
		(layer "In4.Cu")
		(net "M_G_CPU1_CLK_DP<1>")
	)
	(segment
		(start 191.702182 -259.935218)
		(end 191.275716 -259.935218)
		(width 0.18288)
		(layer "In4.Cu")
		(net "M_G_CPU1_CLK_DP<1>")
	)
	(segment
		(start 148.424392 -253.423674)
		(end 147.868132 -253.980188)
		(width 0.18288)
		(layer "In4.Cu")
		(net "M_G_CPU1_CLK_DP<1>")
	)
	(segment
		(start 144.311116 -254.079756)
		(end 142.23746 -252.0061)
		(width 0.18288)
		(layer "In4.Cu")
		(net "M_G_CPU1_CLK_DP<1>")
	)
	(segment
		(start 191.275716 -259.935218)
		(end 190.744602 -259.404104)
		(width 0.18288)
		(layer "In4.Cu")
		(net "M_G_CPU1_CLK_DP<1>")
	)
	(segment
		(start 160.06953 -256.368804)
		(end 159.387032 -256.232152)
		(width 0.18288)
		(layer "In4.Cu")
		(net "M_G_CPU1_CLK_DP<1>")
	)
	(segment
		(start 191.983614 -260.21665)
		(end 191.702182 -259.935218)
		(width 0.18288)
		(layer "In4.Cu")
		(net "M_G_CPU1_CLK_DP<1>")
	)
	(segment
		(start 186.062112 -256.905506)
		(end 165.52164 -256.905506)
		(width 0.18288)
		(layer "In4.Cu")
		(net "M_G_CPU1_CLK_DP<1>")
	)
	(segment
		(start 126.53264 -250.78817)
		(end 126.53264 -249.945652)
		(width 0.18288)
		(layer "In4.Cu")
		(net "M_G_CPU1_CLK_DP<1>")
	)
	(segment
		(start 165.52164 -256.905506)
		(end 160.06953 -256.368804)
		(width 0.18288)
		(layer "In4.Cu")
		(net "M_G_CPU1_CLK_DP<1>")
	)
	(segment
		(start 154.508962 -252.867414)
		(end 148.980652 -252.867414)
		(width 0.18288)
		(layer "In4.Cu")
		(net "M_G_CPU1_CLK_DP<1>")
	)
	(segment
		(start 156.80436 -255.162812)
		(end 154.508962 -252.867414)
		(width 0.18288)
		(layer "In4.Cu")
		(net "M_G_CPU1_CLK_DP<1>")
	)
	(segment
		(start 128.086612 -250.15571)
		(end 128.086612 -249.620024)
		(width 0.20066)
		(layer "F.Cu")
		(net "M_G_CPU1_CLK_DP<0>")
	)
	(segment
		(start 128.086866 -250.155964)
		(end 128.086612 -250.15571)
		(width 0.20066)
		(layer "F.Cu")
		(net "M_G_CPU1_CLK_DP<0>")
	)
	(segment
		(start 200.632314 -260.21665)
		(end 199.527414 -260.21665)
		(width 0.20066)
		(layer "F.Cu")
		(net "M_G_CPU1_CLK_DP<0>")
	)
	(segment
		(start 199.245982 -259.935218)
		(end 198.309484 -259.935218)
		(width 0.18288)
		(layer "In4.Cu")
		(net "M_G_CPU1_CLK_DP<0>")
	)
	(segment
		(start 199.527414 -260.21665)
		(end 199.245982 -259.935218)
		(width 0.18288)
		(layer "In4.Cu")
		(net "M_G_CPU1_CLK_DP<0>")
	)
	(segment
		(start 155.02001 -252.167644)
		(end 152.996392 -251.329444)
		(width 0.18288)
		(layer "In4.Cu")
		(net "M_G_CPU1_CLK_DP<0>")
	)
	(segment
		(start 128.395222 -249.928634)
		(end 128.086612 -249.620024)
		(width 0.18288)
		(layer "In4.Cu")
		(net "M_G_CPU1_CLK_DP<0>")
	)
	(segment
		(start 185.72861 -255.919732)
		(end 164.587174 -255.919732)
		(width 0.18288)
		(layer "In4.Cu")
		(net "M_G_CPU1_CLK_DP<0>")
	)
	(segment
		(start 198.309484 -259.935218)
		(end 198.022972 -259.648706)
		(width 0.18288)
		(layer "In4.Cu")
		(net "M_G_CPU1_CLK_DP<0>")
	)
	(segment
		(start 164.587174 -255.919732)
		(end 159.90062 -255.509522)
		(width 0.18288)
		(layer "In4.Cu")
		(net "M_G_CPU1_CLK_DP<0>")
	)
	(segment
		(start 128.395222 -250.71197)
		(end 128.395222 -249.928634)
		(width 0.18288)
		(layer "In4.Cu")
		(net "M_G_CPU1_CLK_DP<0>")
	)
	(segment
		(start 198.022972 -259.648706)
		(end 194.526662 -259.648706)
		(width 0.18288)
		(layer "In4.Cu")
		(net "M_G_CPU1_CLK_DP<0>")
	)
	(segment
		(start 145.098262 -249.3264)
		(end 142.092934 -251.335032)
		(width 0.18288)
		(layer "In4.Cu")
		(net "M_G_CPU1_CLK_DP<0>")
	)
	(segment
		(start 157.048708 -254.196342)
		(end 155.02001 -252.167644)
		(width 0.18288)
		(layer "In4.Cu")
		(net "M_G_CPU1_CLK_DP<0>")
	)
	(segment
		(start 158.748222 -255.089406)
		(end 157.951932 -254.717804)
		(width 0.18288)
		(layer "In4.Cu")
		(net "M_G_CPU1_CLK_DP<0>")
	)
	(segment
		(start 190.278004 -256.797302)
		(end 185.72861 -255.919732)
		(width 0.18288)
		(layer "In4.Cu")
		(net "M_G_CPU1_CLK_DP<0>")
	)
	(segment
		(start 157.951932 -254.717804)
		(end 157.048708 -254.196342)
		(width 0.18288)
		(layer "In4.Cu")
		(net "M_G_CPU1_CLK_DP<0>")
	)
	(segment
		(start 142.092934 -251.335032)
		(end 129.018284 -251.335032)
		(width 0.18288)
		(layer "In4.Cu")
		(net "M_G_CPU1_CLK_DP<0>")
	)
	(segment
		(start 129.018284 -251.335032)
		(end 128.395222 -250.71197)
		(width 0.18288)
		(layer "In4.Cu")
		(net "M_G_CPU1_CLK_DP<0>")
	)
	(segment
		(start 149.041358 -251.329444)
		(end 147.038314 -249.3264)
		(width 0.18288)
		(layer "In4.Cu")
		(net "M_G_CPU1_CLK_DP<0>")
	)
	(segment
		(start 147.038314 -249.3264)
		(end 145.098262 -249.3264)
		(width 0.18288)
		(layer "In4.Cu")
		(net "M_G_CPU1_CLK_DP<0>")
	)
	(segment
		(start 159.90062 -255.509522)
		(end 158.748222 -255.089406)
		(width 0.18288)
		(layer "In4.Cu")
		(net "M_G_CPU1_CLK_DP<0>")
	)
	(segment
		(start 152.996392 -251.329444)
		(end 149.041358 -251.329444)
		(width 0.18288)
		(layer "In4.Cu")
		(net "M_G_CPU1_CLK_DP<0>")
	)
	(segment
		(start 194.526662 -259.648706)
		(end 190.278004 -256.797302)
		(width 0.18288)
		(layer "In4.Cu")
		(net "M_G_CPU1_CLK_DP<0>")
	)
	(segment
		(start 191.983614 -259.366766)
		(end 193.088514 -259.366766)
		(width 0.20066)
		(layer "F.Cu")
		(net "M_G_CPU1_CLK_DN<1>")
	)
	(segment
		(start 127.146812 -250.15571)
		(end 127.146812 -249.620024)
		(width 0.20066)
		(layer "F.Cu")
		(net "M_G_CPU1_CLK_DN<1>")
	)
	(segment
		(start 127.147066 -250.155964)
		(end 127.146812 -250.15571)
		(width 0.20066)
		(layer "F.Cu")
		(net "M_G_CPU1_CLK_DN<1>")
	)
	(segment
		(start 146.404584 -254.250952)
		(end 145.534126 -254.250952)
		(width 0.18288)
		(layer "In4.Cu")
		(net "M_G_CPU1_CLK_DN<1>")
	)
	(segment
		(start 127.879094 -251.69622)
		(end 126.84252 -250.659646)
		(width 0.18288)
		(layer "In4.Cu")
		(net "M_G_CPU1_CLK_DN<1>")
	)
	(segment
		(start 126.84252 -250.659646)
		(end 126.84252 -249.924316)
		(width 0.18288)
		(layer "In4.Cu")
		(net "M_G_CPU1_CLK_DN<1>")
	)
	(segment
		(start 144.486884 -253.816866)
		(end 142.365984 -251.69622)
		(width 0.18288)
		(layer "In4.Cu")
		(net "M_G_CPU1_CLK_DN<1>")
	)
	(segment
		(start 177.161952 -256.471166)
		(end 177.037492 -256.595626)
		(width 0.18288)
		(layer "In4.Cu")
		(net "M_G_CPU1_CLK_DN<1>")
	)
	(segment
		(start 156.97962 -254.899668)
		(end 154.637486 -252.557534)
		(width 0.18288)
		(layer "In4.Cu")
		(net "M_G_CPU1_CLK_DN<1>")
	)
	(segment
		(start 191.725042 -259.625338)
		(end 191.40424 -259.625338)
		(width 0.18288)
		(layer "In4.Cu")
		(net "M_G_CPU1_CLK_DN<1>")
	)
	(segment
		(start 159.47771 -255.933956)
		(end 156.980128 -254.899922)
		(width 0.18288)
		(layer "In4.Cu")
		(net "M_G_CPU1_CLK_DN<1>")
	)
	(segment
		(start 178.698398 -256.471166)
		(end 178.573938 -256.595626)
		(width 0.18288)
		(layer "In4.Cu")
		(net "M_G_CPU1_CLK_DN<1>")
	)
	(segment
		(start 147.692364 -253.717298)
		(end 146.404584 -254.250952)
		(width 0.18288)
		(layer "In4.Cu")
		(net "M_G_CPU1_CLK_DN<1>")
	)
	(segment
		(start 180.887116 -256.473706)
		(end 180.765196 -256.595626)
		(width 0.18288)
		(layer "In4.Cu")
		(net "M_G_CPU1_CLK_DN<1>")
	)
	(segment
		(start 182.152036 -256.471166)
		(end 182.027576 -256.595626)
		(width 0.18288)
		(layer "In4.Cu")
		(net "M_G_CPU1_CLK_DN<1>")
	)
	(segment
		(start 180.765196 -256.595626)
		(end 179.368958 -256.595626)
		(width 0.18288)
		(layer "In4.Cu")
		(net "M_G_CPU1_CLK_DN<1>")
	)
	(segment
		(start 191.054482 -258.191508)
		(end 190.903098 -258.040632)
		(width 0.18288)
		(layer "In4.Cu")
		(net "M_G_CPU1_CLK_DN<1>")
	)
	(segment
		(start 181.481476 -256.595626)
		(end 181.359556 -256.473706)
		(width 0.18288)
		(layer "In4.Cu")
		(net "M_G_CPU1_CLK_DN<1>")
	)
	(segment
		(start 188.634878 -257.101086)
		(end 186.092846 -256.595626)
		(width 0.18288)
		(layer "In4.Cu")
		(net "M_G_CPU1_CLK_DN<1>")
	)
	(segment
		(start 142.365984 -251.69622)
		(end 127.879094 -251.69622)
		(width 0.18288)
		(layer "In4.Cu")
		(net "M_G_CPU1_CLK_DN<1>")
	)
	(segment
		(start 179.244498 -256.471166)
		(end 178.698398 -256.471166)
		(width 0.18288)
		(layer "In4.Cu")
		(net "M_G_CPU1_CLK_DN<1>")
	)
	(segment
		(start 191.054482 -259.27558)
		(end 191.054482 -258.191508)
		(width 0.18288)
		(layer "In4.Cu")
		(net "M_G_CPU1_CLK_DN<1>")
	)
	(segment
		(start 148.852128 -252.557534)
		(end 147.692364 -253.717298)
		(width 0.18288)
		(layer "In4.Cu")
		(net "M_G_CPU1_CLK_DN<1>")
	)
	(segment
		(start 182.822596 -256.595626)
		(end 182.698136 -256.471166)
		(width 0.18288)
		(layer "In4.Cu")
		(net "M_G_CPU1_CLK_DN<1>")
	)
	(segment
		(start 186.092846 -256.595626)
		(end 182.822596 -256.595626)
		(width 0.18288)
		(layer "In4.Cu")
		(net "M_G_CPU1_CLK_DN<1>")
	)
	(segment
		(start 177.037492 -256.595626)
		(end 165.538912 -256.595626)
		(width 0.18288)
		(layer "In4.Cu")
		(net "M_G_CPU1_CLK_DN<1>")
	)
	(segment
		(start 182.698136 -256.471166)
		(end 182.152036 -256.471166)
		(width 0.18288)
		(layer "In4.Cu")
		(net "M_G_CPU1_CLK_DN<1>")
	)
	(segment
		(start 191.40424 -259.625338)
		(end 191.054482 -259.27558)
		(width 0.18288)
		(layer "In4.Cu")
		(net "M_G_CPU1_CLK_DN<1>")
	)
	(segment
		(start 156.980128 -254.899922)
		(end 156.97962 -254.899668)
		(width 0.18288)
		(layer "In4.Cu")
		(net "M_G_CPU1_CLK_DN<1>")
	)
	(segment
		(start 126.84252 -249.924316)
		(end 127.146812 -249.620024)
		(width 0.18288)
		(layer "In4.Cu")
		(net "M_G_CPU1_CLK_DN<1>")
	)
	(segment
		(start 154.637486 -252.557534)
		(end 148.852128 -252.557534)
		(width 0.18288)
		(layer "In4.Cu")
		(net "M_G_CPU1_CLK_DN<1>")
	)
	(segment
		(start 145.534126 -254.250952)
		(end 144.486884 -253.816866)
		(width 0.18288)
		(layer "In4.Cu")
		(net "M_G_CPU1_CLK_DN<1>")
	)
	(segment
		(start 178.573938 -256.595626)
		(end 177.832512 -256.595626)
		(width 0.18288)
		(layer "In4.Cu")
		(net "M_G_CPU1_CLK_DN<1>")
	)
	(segment
		(start 160.11525 -256.061718)
		(end 159.47771 -255.933956)
		(width 0.18288)
		(layer "In4.Cu")
		(net "M_G_CPU1_CLK_DN<1>")
	)
	(segment
		(start 179.368958 -256.595626)
		(end 179.244498 -256.471166)
		(width 0.18288)
		(layer "In4.Cu")
		(net "M_G_CPU1_CLK_DN<1>")
	)
	(segment
		(start 182.027576 -256.595626)
		(end 181.481476 -256.595626)
		(width 0.18288)
		(layer "In4.Cu")
		(net "M_G_CPU1_CLK_DN<1>")
	)
	(segment
		(start 177.708052 -256.471166)
		(end 177.161952 -256.471166)
		(width 0.18288)
		(layer "In4.Cu")
		(net "M_G_CPU1_CLK_DN<1>")
	)
	(segment
		(start 165.538912 -256.595626)
		(end 160.11525 -256.061718)
		(width 0.18288)
		(layer "In4.Cu")
		(net "M_G_CPU1_CLK_DN<1>")
	)
	(segment
		(start 177.832512 -256.595626)
		(end 177.708052 -256.471166)
		(width 0.18288)
		(layer "In4.Cu")
		(net "M_G_CPU1_CLK_DN<1>")
	)
	(segment
		(start 181.359556 -256.473706)
		(end 180.887116 -256.473706)
		(width 0.18288)
		(layer "In4.Cu")
		(net "M_G_CPU1_CLK_DN<1>")
	)
	(segment
		(start 190.903098 -258.040632)
		(end 188.634878 -257.101086)
		(width 0.18288)
		(layer "In4.Cu")
		(net "M_G_CPU1_CLK_DN<1>")
	)
	(segment
		(start 191.983614 -259.366766)
		(end 191.725042 -259.625338)
		(width 0.18288)
		(layer "In4.Cu")
		(net "M_G_CPU1_CLK_DN<1>")
	)
	(segment
		(start 199.527414 -259.366766)
		(end 200.632314 -259.366766)
		(width 0.20066)
		(layer "F.Cu")
		(net "M_G_CPU1_CLK_DN<0>")
	)
	(segment
		(start 129.026666 -250.155964)
		(end 129.026412 -250.15571)
		(width 0.20066)
		(layer "F.Cu")
		(net "M_G_CPU1_CLK_DN<0>")
	)
	(segment
		(start 129.026412 -250.15571)
		(end 129.026412 -249.620024)
		(width 0.20066)
		(layer "F.Cu")
		(net "M_G_CPU1_CLK_DN<0>")
	)
	(segment
		(start 192.073022 -257.47853)
		(end 191.619124 -257.173984)
		(width 0.18288)
		(layer "In4.Cu")
		(net "M_G_CPU1_CLK_DN<0>")
	)
	(segment
		(start 193.186558 -258.226052)
		(end 192.732914 -257.921506)
		(width 0.18288)
		(layer "In4.Cu")
		(net "M_G_CPU1_CLK_DN<0>")
	)
	(segment
		(start 195.964048 -259.214366)
		(end 195.839588 -259.338826)
		(width 0.18288)
		(layer "In4.Cu")
		(net "M_G_CPU1_CLK_DN<0>")
	)
	(segment
		(start 155.195778 -251.904754)
		(end 153.058114 -251.019564)
		(width 0.18288)
		(layer "In4.Cu")
		(net "M_G_CPU1_CLK_DN<0>")
	)
	(segment
		(start 192.106804 -257.65125)
		(end 192.073022 -257.47853)
		(width 0.18288)
		(layer "In4.Cu")
		(net "M_G_CPU1_CLK_DN<0>")
	)
	(segment
		(start 191.619124 -257.173984)
		(end 191.446404 -257.20802)
		(width 0.18288)
		(layer "In4.Cu")
		(net "M_G_CPU1_CLK_DN<0>")
	)
	(segment
		(start 185.758328 -255.609852)
		(end 164.60089 -255.609852)
		(width 0.18288)
		(layer "In4.Cu")
		(net "M_G_CPU1_CLK_DN<0>")
	)
	(segment
		(start 157.239208 -253.948184)
		(end 155.195778 -251.904754)
		(width 0.18288)
		(layer "In4.Cu")
		(net "M_G_CPU1_CLK_DN<0>")
	)
	(segment
		(start 191.446404 -257.20802)
		(end 190.398654 -256.504694)
		(width 0.18288)
		(layer "In4.Cu")
		(net "M_G_CPU1_CLK_DN<0>")
	)
	(segment
		(start 129.146808 -251.025152)
		(end 128.705102 -250.583446)
		(width 0.18288)
		(layer "In4.Cu")
		(net "M_G_CPU1_CLK_DN<0>")
	)
	(segment
		(start 196.510148 -259.214366)
		(end 195.964048 -259.214366)
		(width 0.18288)
		(layer "In4.Cu")
		(net "M_G_CPU1_CLK_DN<0>")
	)
	(segment
		(start 145.004028 -249.01652)
		(end 141.9987 -251.025152)
		(width 0.18288)
		(layer "In4.Cu")
		(net "M_G_CPU1_CLK_DN<0>")
	)
	(segment
		(start 194.62115 -259.338826)
		(end 193.220594 -258.398772)
		(width 0.18288)
		(layer "In4.Cu")
		(net "M_G_CPU1_CLK_DN<0>")
	)
	(segment
		(start 164.60089 -255.609852)
		(end 159.968438 -255.204214)
		(width 0.18288)
		(layer "In4.Cu")
		(net "M_G_CPU1_CLK_DN<0>")
	)
	(segment
		(start 195.839588 -259.338826)
		(end 194.62115 -259.338826)
		(width 0.18288)
		(layer "In4.Cu")
		(net "M_G_CPU1_CLK_DN<0>")
	)
	(segment
		(start 158.095188 -254.442468)
		(end 157.239208 -253.948184)
		(width 0.18288)
		(layer "In4.Cu")
		(net "M_G_CPU1_CLK_DN<0>")
	)
	(segment
		(start 189.22746 -256.151888)
		(end 189.081664 -256.250694)
		(width 0.18288)
		(layer "In4.Cu")
		(net "M_G_CPU1_CLK_DN<0>")
	)
	(segment
		(start 199.527414 -259.366766)
		(end 199.268842 -259.625338)
		(width 0.18288)
		(layer "In4.Cu")
		(net "M_G_CPU1_CLK_DN<0>")
	)
	(segment
		(start 189.081664 -256.250694)
		(end 185.758328 -255.609852)
		(width 0.18288)
		(layer "In4.Cu")
		(net "M_G_CPU1_CLK_DN<0>")
	)
	(segment
		(start 128.705102 -249.941334)
		(end 129.026412 -249.620024)
		(width 0.18288)
		(layer "In4.Cu")
		(net "M_G_CPU1_CLK_DN<0>")
	)
	(segment
		(start 128.705102 -250.583446)
		(end 128.705102 -249.941334)
		(width 0.18288)
		(layer "In4.Cu")
		(net "M_G_CPU1_CLK_DN<0>")
	)
	(segment
		(start 149.169882 -251.019564)
		(end 147.166838 -249.01652)
		(width 0.18288)
		(layer "In4.Cu")
		(net "M_G_CPU1_CLK_DN<0>")
	)
	(segment
		(start 193.220594 -258.398772)
		(end 193.186558 -258.226052)
		(width 0.18288)
		(layer "In4.Cu")
		(net "M_G_CPU1_CLK_DN<0>")
	)
	(segment
		(start 196.634608 -259.338826)
		(end 196.510148 -259.214366)
		(width 0.18288)
		(layer "In4.Cu")
		(net "M_G_CPU1_CLK_DN<0>")
	)
	(segment
		(start 189.763908 -256.255266)
		(end 189.22746 -256.151888)
		(width 0.18288)
		(layer "In4.Cu")
		(net "M_G_CPU1_CLK_DN<0>")
	)
	(segment
		(start 192.732914 -257.921506)
		(end 192.560194 -257.955542)
		(width 0.18288)
		(layer "In4.Cu")
		(net "M_G_CPU1_CLK_DN<0>")
	)
	(segment
		(start 147.166838 -249.01652)
		(end 145.004028 -249.01652)
		(width 0.18288)
		(layer "In4.Cu")
		(net "M_G_CPU1_CLK_DN<0>")
	)
	(segment
		(start 198.438008 -259.625338)
		(end 198.151496 -259.338826)
		(width 0.18288)
		(layer "In4.Cu")
		(net "M_G_CPU1_CLK_DN<0>")
	)
	(segment
		(start 189.86246 -256.401316)
		(end 189.763908 -256.255266)
		(width 0.18288)
		(layer "In4.Cu")
		(net "M_G_CPU1_CLK_DN<0>")
	)
	(segment
		(start 190.398654 -256.504694)
		(end 189.86246 -256.401316)
		(width 0.18288)
		(layer "In4.Cu")
		(net "M_G_CPU1_CLK_DN<0>")
	)
	(segment
		(start 198.151496 -259.338826)
		(end 196.634608 -259.338826)
		(width 0.18288)
		(layer "In4.Cu")
		(net "M_G_CPU1_CLK_DN<0>")
	)
	(segment
		(start 158.867094 -254.802894)
		(end 158.095188 -254.442468)
		(width 0.18288)
		(layer "In4.Cu")
		(net "M_G_CPU1_CLK_DN<0>")
	)
	(segment
		(start 153.058114 -251.019564)
		(end 149.169882 -251.019564)
		(width 0.18288)
		(layer "In4.Cu")
		(net "M_G_CPU1_CLK_DN<0>")
	)
	(segment
		(start 141.9987 -251.025152)
		(end 129.146808 -251.025152)
		(width 0.18288)
		(layer "In4.Cu")
		(net "M_G_CPU1_CLK_DN<0>")
	)
	(segment
		(start 192.560194 -257.955542)
		(end 192.106804 -257.65125)
		(width 0.18288)
		(layer "In4.Cu")
		(net "M_G_CPU1_CLK_DN<0>")
	)
	(segment
		(start 159.968438 -255.204214)
		(end 158.867094 -254.802894)
		(width 0.18288)
		(layer "In4.Cu")
		(net "M_G_CPU1_CLK_DN<0>")
	)
	(segment
		(start 199.268842 -259.625338)
		(end 198.438008 -259.625338)
		(width 0.18288)
		(layer "In4.Cu")
		(net "M_G_CPU1_CLK_DN<0>")
	)
	(segment
		(start 191.930782 -269.141702)
		(end 191.786256 -269.141702)
		(width 0.101854)
		(layer "F.Cu")
		(net "M_G_CPU1_ALERT_N")
	)
	(segment
		(start 196.532246 -269.566644)
		(end 196.531992 -269.566898)
		(width 0.20066)
		(layer "F.Cu")
		(net "M_G_CPU1_ALERT_N")
	)
	(segment
		(start 191.229742 -269.259812)
		(end 191.229742 -269.62735)
		(width 0.20066)
		(layer "F.Cu")
		(net "M_G_CPU1_ALERT_N")
	)
	(segment
		(start 194.901312 -269.566898)
		(end 194.476116 -269.141702)
		(width 0.20066)
		(layer "F.Cu")
		(net "M_G_CPU1_ALERT_N")
	)
	(segment
		(start 190.75781 -269.81531)
		(end 190.509144 -269.566644)
		(width 0.20066)
		(layer "F.Cu")
		(net "M_G_CPU1_ALERT_N")
	)
	(segment
		(start 121.618248 -255.825498)
		(end 121.618248 -256.36093)
		(width 0.20066)
		(layer "F.Cu")
		(net "M_G_CPU1_ALERT_N")
	)
	(segment
		(start 191.229742 -269.62735)
		(end 191.041782 -269.81531)
		(width 0.20066)
		(layer "F.Cu")
		(net "M_G_CPU1_ALERT_N")
	)
	(segment
		(start 191.786256 -269.141702)
		(end 191.347852 -269.141702)
		(width 0.20066)
		(layer "F.Cu")
		(net "M_G_CPU1_ALERT_N")
	)
	(segment
		(start 190.509144 -269.566644)
		(end 188.988446 -269.566644)
		(width 0.20066)
		(layer "F.Cu")
		(net "M_G_CPU1_ALERT_N")
	)
	(segment
		(start 194.277742 -269.141702)
		(end 194.241166 -269.141702)
		(width 0.101854)
		(layer "F.Cu")
		(net "M_G_CPU1_ALERT_N")
	)
	(segment
		(start 196.531992 -269.566898)
		(end 194.901312 -269.566898)
		(width 0.20066)
		(layer "F.Cu")
		(net "M_G_CPU1_ALERT_N")
	)
	(segment
		(start 188.988446 -269.566644)
		(end 187.883546 -269.566644)
		(width 0.20066)
		(layer "F.Cu")
		(net "M_G_CPU1_ALERT_N")
	)
	(segment
		(start 191.041782 -269.81531)
		(end 190.75781 -269.81531)
		(width 0.20066)
		(layer "F.Cu")
		(net "M_G_CPU1_ALERT_N")
	)
	(segment
		(start 191.347852 -269.141702)
		(end 191.229742 -269.259812)
		(width 0.20066)
		(layer "F.Cu")
		(net "M_G_CPU1_ALERT_N")
	)
	(segment
		(start 194.241166 -269.141702)
		(end 191.930782 -269.141702)
		(width 0.1016)
		(layer "F.Cu")
		(net "M_G_CPU1_ALERT_N")
	)
	(segment
		(start 194.476116 -269.141702)
		(end 194.277742 -269.141702)
		(width 0.20066)
		(layer "F.Cu")
		(net "M_G_CPU1_ALERT_N")
	)
	(via
		(at 121.617994 -256.361438)
		(size 0.4572)
		(drill 0.2032)
		(layers "F.Cu" "B.Cu")
		(net "M_G_CPU1_ALERT_N")
	)
	(via
		(at 187.883546 -269.566644)
		(size 0.4572)
		(drill 0.2032)
		(layers "F.Cu" "B.Cu")
		(net "M_G_CPU1_ALERT_N")
	)
	(arc
		(start 121.618248 -256.36093)
		(mid 121.61819 -256.361222)
		(end 121.617994 -256.361438)
		(width 0.20066)
		(layer "F.Cu")
		(net "M_G_CPU1_ALERT_N")
	)
	(segment
		(start 136.889998 -256.768346)
		(end 136.880346 -256.773934)
		(width 0.18288)
		(layer "In6.Cu")
		(net "M_G_CPU1_ALERT_N")
	)
	(segment
		(start 122.312684 -256.768346)
		(end 121.620026 -256.36855)
		(width 0.18288)
		(layer "In6.Cu")
		(net "M_G_CPU1_ALERT_N")
	)
	(segment
		(start 121.620026 -256.36855)
		(end 121.617994 -256.361438)
		(width 0.18288)
		(layer "In6.Cu")
		(net "M_G_CPU1_ALERT_N")
	)
	(segment
		(start 133.600444 -256.768346)
		(end 133.586982 -256.760472)
		(width 0.18288)
		(layer "In6.Cu")
		(net "M_G_CPU1_ALERT_N")
	)
	(segment
		(start 128.901698 -256.768346)
		(end 128.892046 -256.762758)
		(width 0.18288)
		(layer "In6.Cu")
		(net "M_G_CPU1_ALERT_N")
	)
	(segment
		(start 124.202444 -256.768346)
		(end 124.188982 -256.760472)
		(width 0.18288)
		(layer "In6.Cu")
		(net "M_G_CPU1_ALERT_N")
	)
	(segment
		(start 127.021844 -256.768346)
		(end 127.008382 -256.760472)
		(width 0.18288)
		(layer "In6.Cu")
		(net "M_G_CPU1_ALERT_N")
	)
	(segment
		(start 140.30198 -257.349752)
		(end 138.881104 -257.349752)
		(width 0.18288)
		(layer "In6.Cu")
		(net "M_G_CPU1_ALERT_N")
	)
	(segment
		(start 143.336772 -258.606544)
		(end 140.30198 -257.349752)
		(width 0.18288)
		(layer "In6.Cu")
		(net "M_G_CPU1_ALERT_N")
	)
	(segment
		(start 138.881104 -257.349752)
		(end 138.299698 -256.768346)
		(width 0.18288)
		(layer "In6.Cu")
		(net "M_G_CPU1_ALERT_N")
	)
	(segment
		(start 130.781044 -256.768346)
		(end 130.767582 -256.760472)
		(width 0.18288)
		(layer "In6.Cu")
		(net "M_G_CPU1_ALERT_N")
	)
	(segment
		(start 151.976582 -257.880358)
		(end 150.819104 -259.037836)
		(width 0.18288)
		(layer "In6.Cu")
		(net "M_G_CPU1_ALERT_N")
	)
	(segment
		(start 129.841244 -256.768346)
		(end 129.831592 -256.762758)
		(width 0.18288)
		(layer "In6.Cu")
		(net "M_G_CPU1_ALERT_N")
	)
	(segment
		(start 145.504408 -259.037836)
		(end 143.336772 -258.606544)
		(width 0.18288)
		(layer "In6.Cu")
		(net "M_G_CPU1_ALERT_N")
	)
	(segment
		(start 188.471302 -268.978888)
		(end 188.471302 -258.118102)
		(width 0.18288)
		(layer "In6.Cu")
		(net "M_G_CPU1_ALERT_N")
	)
	(segment
		(start 187.883546 -269.566644)
		(end 188.471302 -268.978888)
		(width 0.18288)
		(layer "In6.Cu")
		(net "M_G_CPU1_ALERT_N")
	)
	(segment
		(start 123.262644 -256.768346)
		(end 123.252992 -256.762758)
		(width 0.18288)
		(layer "In6.Cu")
		(net "M_G_CPU1_ALERT_N")
	)
	(segment
		(start 188.233558 -257.880358)
		(end 151.976582 -257.880358)
		(width 0.18288)
		(layer "In6.Cu")
		(net "M_G_CPU1_ALERT_N")
	)
	(segment
		(start 131.720844 -256.768346)
		(end 131.707382 -256.760472)
		(width 0.18288)
		(layer "In6.Cu")
		(net "M_G_CPU1_ALERT_N")
	)
	(segment
		(start 150.819104 -259.037836)
		(end 145.504408 -259.037836)
		(width 0.18288)
		(layer "In6.Cu")
		(net "M_G_CPU1_ALERT_N")
	)
	(segment
		(start 188.471302 -258.118102)
		(end 188.233558 -257.880358)
		(width 0.18288)
		(layer "In6.Cu")
		(net "M_G_CPU1_ALERT_N")
	)
	(arc
		(start 135.480044 -256.768346)
		(mid 135.245094 -256.705386)
		(end 135.010144 -256.768346)
		(width 0.18288)
		(layer "In6.Cu")
		(net "M_G_CPU1_ALERT_N")
	)
	(arc
		(start 122.792998 -256.768346)
		(mid 122.552858 -256.832621)
		(end 122.312684 -256.768346)
		(width 0.18288)
		(layer "In6.Cu")
		(net "M_G_CPU1_ALERT_N")
	)
	(arc
		(start 128.431544 -256.768346)
		(mid 128.196594 -256.831306)
		(end 127.961644 -256.768346)
		(width 0.18288)
		(layer "In6.Cu")
		(net "M_G_CPU1_ALERT_N")
	)
	(arc
		(start 132.660644 -256.768346)
		(mid 132.425694 -256.705386)
		(end 132.190744 -256.768346)
		(width 0.18288)
		(layer "In6.Cu")
		(net "M_G_CPU1_ALERT_N")
	)
	(arc
		(start 124.188982 -256.760472)
		(mid 123.959729 -256.705228)
		(end 123.732544 -256.768346)
		(width 0.18288)
		(layer "In6.Cu")
		(net "M_G_CPU1_ALERT_N")
	)
	(arc
		(start 133.130544 -256.768346)
		(mid 132.895594 -256.831306)
		(end 132.660644 -256.768346)
		(width 0.18288)
		(layer "In6.Cu")
		(net "M_G_CPU1_ALERT_N")
	)
	(arc
		(start 134.070344 -256.768346)
		(mid 133.835394 -256.831306)
		(end 133.600444 -256.768346)
		(width 0.18288)
		(layer "In6.Cu")
		(net "M_G_CPU1_ALERT_N")
	)
	(arc
		(start 128.892046 -256.762758)
		(mid 128.661061 -256.705275)
		(end 128.431544 -256.768346)
		(width 0.18288)
		(layer "In6.Cu")
		(net "M_G_CPU1_ALERT_N")
	)
	(arc
		(start 125.142244 -256.768346)
		(mid 124.907294 -256.705386)
		(end 124.672344 -256.768346)
		(width 0.18288)
		(layer "In6.Cu")
		(net "M_G_CPU1_ALERT_N")
	)
	(arc
		(start 135.949944 -256.768346)
		(mid 135.714994 -256.831306)
		(end 135.480044 -256.768346)
		(width 0.18288)
		(layer "In6.Cu")
		(net "M_G_CPU1_ALERT_N")
	)
	(arc
		(start 123.732544 -256.768346)
		(mid 123.497594 -256.831306)
		(end 123.262644 -256.768346)
		(width 0.18288)
		(layer "In6.Cu")
		(net "M_G_CPU1_ALERT_N")
	)
	(arc
		(start 131.707382 -256.760472)
		(mid 131.478129 -256.705228)
		(end 131.250944 -256.768346)
		(width 0.18288)
		(layer "In6.Cu")
		(net "M_G_CPU1_ALERT_N")
	)
	(arc
		(start 131.250944 -256.768346)
		(mid 131.015994 -256.831306)
		(end 130.781044 -256.768346)
		(width 0.18288)
		(layer "In6.Cu")
		(net "M_G_CPU1_ALERT_N")
	)
	(arc
		(start 136.880346 -256.773934)
		(mid 136.649361 -256.831417)
		(end 136.419844 -256.768346)
		(width 0.18288)
		(layer "In6.Cu")
		(net "M_G_CPU1_ALERT_N")
	)
	(arc
		(start 123.252992 -256.762758)
		(mid 123.022261 -256.705397)
		(end 122.792998 -256.768346)
		(width 0.18288)
		(layer "In6.Cu")
		(net "M_G_CPU1_ALERT_N")
	)
	(arc
		(start 133.586982 -256.760472)
		(mid 133.357729 -256.705228)
		(end 133.130544 -256.768346)
		(width 0.18288)
		(layer "In6.Cu")
		(net "M_G_CPU1_ALERT_N")
	)
	(arc
		(start 126.551944 -256.768346)
		(mid 126.316994 -256.831306)
		(end 126.082044 -256.768346)
		(width 0.18288)
		(layer "In6.Cu")
		(net "M_G_CPU1_ALERT_N")
	)
	(arc
		(start 125.612144 -256.768346)
		(mid 125.377194 -256.831306)
		(end 125.142244 -256.768346)
		(width 0.18288)
		(layer "In6.Cu")
		(net "M_G_CPU1_ALERT_N")
	)
	(arc
		(start 135.010144 -256.768346)
		(mid 134.775194 -256.831306)
		(end 134.540244 -256.768346)
		(width 0.18288)
		(layer "In6.Cu")
		(net "M_G_CPU1_ALERT_N")
	)
	(arc
		(start 129.371598 -256.768346)
		(mid 129.136648 -256.831306)
		(end 128.901698 -256.768346)
		(width 0.18288)
		(layer "In6.Cu")
		(net "M_G_CPU1_ALERT_N")
	)
	(arc
		(start 137.359898 -256.768346)
		(mid 137.124948 -256.705386)
		(end 136.889998 -256.768346)
		(width 0.18288)
		(layer "In6.Cu")
		(net "M_G_CPU1_ALERT_N")
	)
	(arc
		(start 129.831592 -256.762758)
		(mid 129.600861 -256.705397)
		(end 129.371598 -256.768346)
		(width 0.18288)
		(layer "In6.Cu")
		(net "M_G_CPU1_ALERT_N")
	)
	(arc
		(start 137.829798 -256.768346)
		(mid 137.594848 -256.831306)
		(end 137.359898 -256.768346)
		(width 0.18288)
		(layer "In6.Cu")
		(net "M_G_CPU1_ALERT_N")
	)
	(arc
		(start 124.672344 -256.768346)
		(mid 124.437394 -256.831306)
		(end 124.202444 -256.768346)
		(width 0.18288)
		(layer "In6.Cu")
		(net "M_G_CPU1_ALERT_N")
	)
	(arc
		(start 134.540244 -256.768346)
		(mid 134.305294 -256.705386)
		(end 134.070344 -256.768346)
		(width 0.18288)
		(layer "In6.Cu")
		(net "M_G_CPU1_ALERT_N")
	)
	(arc
		(start 127.491744 -256.768346)
		(mid 127.256794 -256.831306)
		(end 127.021844 -256.768346)
		(width 0.18288)
		(layer "In6.Cu")
		(net "M_G_CPU1_ALERT_N")
	)
	(arc
		(start 127.961644 -256.768346)
		(mid 127.726694 -256.705386)
		(end 127.491744 -256.768346)
		(width 0.18288)
		(layer "In6.Cu")
		(net "M_G_CPU1_ALERT_N")
	)
	(arc
		(start 127.008382 -256.760472)
		(mid 126.779129 -256.705228)
		(end 126.551944 -256.768346)
		(width 0.18288)
		(layer "In6.Cu")
		(net "M_G_CPU1_ALERT_N")
	)
	(arc
		(start 126.082044 -256.768346)
		(mid 125.847094 -256.705386)
		(end 125.612144 -256.768346)
		(width 0.18288)
		(layer "In6.Cu")
		(net "M_G_CPU1_ALERT_N")
	)
	(arc
		(start 130.767582 -256.760472)
		(mid 130.538329 -256.705228)
		(end 130.311144 -256.768346)
		(width 0.18288)
		(layer "In6.Cu")
		(net "M_G_CPU1_ALERT_N")
	)
	(arc
		(start 130.311144 -256.768346)
		(mid 130.076194 -256.831306)
		(end 129.841244 -256.768346)
		(width 0.18288)
		(layer "In6.Cu")
		(net "M_G_CPU1_ALERT_N")
	)
	(arc
		(start 132.190744 -256.768346)
		(mid 131.955794 -256.831306)
		(end 131.720844 -256.768346)
		(width 0.18288)
		(layer "In6.Cu")
		(net "M_G_CPU1_ALERT_N")
	)
	(arc
		(start 138.299698 -256.768346)
		(mid 138.064748 -256.705386)
		(end 137.829798 -256.768346)
		(width 0.18288)
		(layer "In6.Cu")
		(net "M_G_CPU1_ALERT_N")
	)
	(arc
		(start 136.419844 -256.768346)
		(mid 136.184894 -256.705386)
		(end 135.949944 -256.768346)
		(width 0.18288)
		(layer "In6.Cu")
		(net "M_G_CPU1_ALERT_N")
	)
	(segment
		(start 378.486416 -253.38405)
		(end 378.486416 -253.919736)
		(width 0.20066)
		(layer "F.Cu")
		(net "M_G_CPU0_SB_RSP<1>")
	)
	(segment
		(start 378.486162 -253.383796)
		(end 378.486416 -253.38405)
		(width 0.20066)
		(layer "F.Cu")
		(net "M_G_CPU0_SB_RSP<1>")
	)
	(segment
		(start 435.823614 -243.216684)
		(end 436.928514 -243.216684)
		(width 0.20066)
		(layer "F.Cu")
		(net "M_G_CPU0_SB_RSP<1>")
	)
	(segment
		(start 416.921696 -247.892316)
		(end 415.960814 -248.853198)
		(width 0.18288)
		(layer "In6.Cu")
		(net "M_G_CPU0_SB_RSP<1>")
	)
	(segment
		(start 415.960814 -248.853198)
		(end 413.54375 -248.853198)
		(width 0.18288)
		(layer "In6.Cu")
		(net "M_G_CPU0_SB_RSP<1>")
	)
	(segment
		(start 428.70374 -246.188484)
		(end 427.279816 -246.188484)
		(width 0.18288)
		(layer "In6.Cu")
		(net "M_G_CPU0_SB_RSP<1>")
	)
	(segment
		(start 435.823614 -243.216684)
		(end 434.655976 -243.216684)
		(width 0.18288)
		(layer "In6.Cu")
		(net "M_G_CPU0_SB_RSP<1>")
	)
	(segment
		(start 425.538646 -246.778018)
		(end 425.985178 -247.22455)
		(width 0.18288)
		(layer "In6.Cu")
		(net "M_G_CPU0_SB_RSP<1>")
	)
	(segment
		(start 425.575984 -247.892316)
		(end 416.921696 -247.892316)
		(width 0.18288)
		(layer "In6.Cu")
		(net "M_G_CPU0_SB_RSP<1>")
	)
	(segment
		(start 429.432212 -246.568976)
		(end 429.084232 -246.568976)
		(width 0.18288)
		(layer "In6.Cu")
		(net "M_G_CPU0_SB_RSP<1>")
	)
	(segment
		(start 413.54375 -248.853198)
		(end 412.60395 -249.792998)
		(width 0.18288)
		(layer "In6.Cu")
		(net "M_G_CPU0_SB_RSP<1>")
	)
	(segment
		(start 426.734224 -246.734076)
		(end 426.475652 -246.734076)
		(width 0.18288)
		(layer "In6.Cu")
		(net "M_G_CPU0_SB_RSP<1>")
	)
	(segment
		(start 429.084232 -246.568976)
		(end 428.70374 -246.188484)
		(width 0.18288)
		(layer "In6.Cu")
		(net "M_G_CPU0_SB_RSP<1>")
	)
	(segment
		(start 427.279816 -246.188484)
		(end 426.734224 -246.734076)
		(width 0.18288)
		(layer "In6.Cu")
		(net "M_G_CPU0_SB_RSP<1>")
	)
	(segment
		(start 394.97 -254.28067)
		(end 393.765786 -254.28067)
		(width 0.18288)
		(layer "In6.Cu")
		(net "M_G_CPU0_SB_RSP<1>")
	)
	(segment
		(start 412.60395 -249.792998)
		(end 409.267406 -249.792998)
		(width 0.18288)
		(layer "In6.Cu")
		(net "M_G_CPU0_SB_RSP<1>")
	)
	(segment
		(start 403.822916 -251.068586)
		(end 398.182084 -251.068586)
		(width 0.18288)
		(layer "In6.Cu")
		(net "M_G_CPU0_SB_RSP<1>")
	)
	(segment
		(start 433.378356 -244.494304)
		(end 431.959004 -244.494304)
		(width 0.18288)
		(layer "In6.Cu")
		(net "M_G_CPU0_SB_RSP<1>")
	)
	(segment
		(start 425.538646 -246.519446)
		(end 425.538646 -246.778018)
		(width 0.18288)
		(layer "In6.Cu")
		(net "M_G_CPU0_SB_RSP<1>")
	)
	(segment
		(start 408.556968 -250.503436)
		(end 404.388066 -250.503436)
		(width 0.18288)
		(layer "In6.Cu")
		(net "M_G_CPU0_SB_RSP<1>")
	)
	(segment
		(start 426.475652 -246.734076)
		(end 426.02912 -246.287544)
		(width 0.18288)
		(layer "In6.Cu")
		(net "M_G_CPU0_SB_RSP<1>")
	)
	(segment
		(start 434.655976 -243.216684)
		(end 433.378356 -244.494304)
		(width 0.18288)
		(layer "In6.Cu")
		(net "M_G_CPU0_SB_RSP<1>")
	)
	(segment
		(start 398.182084 -251.068586)
		(end 394.97 -254.28067)
		(width 0.18288)
		(layer "In6.Cu")
		(net "M_G_CPU0_SB_RSP<1>")
	)
	(segment
		(start 431.959004 -244.494304)
		(end 431.627534 -244.825774)
		(width 0.18288)
		(layer "In6.Cu")
		(net "M_G_CPU0_SB_RSP<1>")
	)
	(segment
		(start 391.065258 -252.491748)
		(end 379.124972 -252.491748)
		(width 0.18288)
		(layer "In6.Cu")
		(net "M_G_CPU0_SB_RSP<1>")
	)
	(segment
		(start 426.02912 -246.287544)
		(end 425.770548 -246.287544)
		(width 0.18288)
		(layer "In6.Cu")
		(net "M_G_CPU0_SB_RSP<1>")
	)
	(segment
		(start 393.765786 -254.28067)
		(end 392.973814 -254.122682)
		(width 0.18288)
		(layer "In6.Cu")
		(net "M_G_CPU0_SB_RSP<1>")
	)
	(segment
		(start 425.985178 -247.22455)
		(end 425.985178 -247.483122)
		(width 0.18288)
		(layer "In6.Cu")
		(net "M_G_CPU0_SB_RSP<1>")
	)
	(segment
		(start 392.500612 -253.927102)
		(end 391.065258 -252.491748)
		(width 0.18288)
		(layer "In6.Cu")
		(net "M_G_CPU0_SB_RSP<1>")
	)
	(segment
		(start 425.770548 -246.287544)
		(end 425.538646 -246.519446)
		(width 0.18288)
		(layer "In6.Cu")
		(net "M_G_CPU0_SB_RSP<1>")
	)
	(segment
		(start 429.592232 -246.408956)
		(end 429.432212 -246.568976)
		(width 0.18288)
		(layer "In6.Cu")
		(net "M_G_CPU0_SB_RSP<1>")
	)
	(segment
		(start 425.985178 -247.483122)
		(end 425.575984 -247.892316)
		(width 0.18288)
		(layer "In6.Cu")
		(net "M_G_CPU0_SB_RSP<1>")
	)
	(segment
		(start 429.592232 -245.689374)
		(end 429.592232 -246.408956)
		(width 0.18288)
		(layer "In6.Cu")
		(net "M_G_CPU0_SB_RSP<1>")
	)
	(segment
		(start 429.719232 -245.562374)
		(end 429.592232 -245.689374)
		(width 0.18288)
		(layer "In6.Cu")
		(net "M_G_CPU0_SB_RSP<1>")
	)
	(segment
		(start 392.973814 -254.122682)
		(end 392.500612 -253.927102)
		(width 0.18288)
		(layer "In6.Cu")
		(net "M_G_CPU0_SB_RSP<1>")
	)
	(segment
		(start 379.124972 -252.491748)
		(end 378.486416 -253.130304)
		(width 0.18288)
		(layer "In6.Cu")
		(net "M_G_CPU0_SB_RSP<1>")
	)
	(segment
		(start 378.486416 -253.130304)
		(end 378.486416 -253.919736)
		(width 0.18288)
		(layer "In6.Cu")
		(net "M_G_CPU0_SB_RSP<1>")
	)
	(segment
		(start 409.267406 -249.792998)
		(end 408.556968 -250.503436)
		(width 0.18288)
		(layer "In6.Cu")
		(net "M_G_CPU0_SB_RSP<1>")
	)
	(segment
		(start 431.355246 -245.562374)
		(end 429.719232 -245.562374)
		(width 0.18288)
		(layer "In6.Cu")
		(net "M_G_CPU0_SB_RSP<1>")
	)
	(segment
		(start 431.627534 -244.825774)
		(end 431.627534 -245.290086)
		(width 0.18288)
		(layer "In6.Cu")
		(net "M_G_CPU0_SB_RSP<1>")
	)
	(segment
		(start 404.388066 -250.503436)
		(end 403.822916 -251.068586)
		(width 0.18288)
		(layer "In6.Cu")
		(net "M_G_CPU0_SB_RSP<1>")
	)
	(segment
		(start 431.627534 -245.290086)
		(end 431.355246 -245.562374)
		(width 0.18288)
		(layer "In6.Cu")
		(net "M_G_CPU0_SB_RSP<1>")
	)
	(segment
		(start 378.016516 -254.733298)
		(end 378.016262 -254.733552)
		(width 0.20066)
		(layer "F.Cu")
		(net "M_G_CPU0_SB_RSP<0>")
	)
	(segment
		(start 378.016516 -254.197612)
		(end 378.016516 -254.733298)
		(width 0.20066)
		(layer "F.Cu")
		(net "M_G_CPU0_SB_RSP<0>")
	)
	(segment
		(start 443.367414 -243.216684)
		(end 444.472314 -243.216684)
		(width 0.20066)
		(layer "F.Cu")
		(net "M_G_CPU0_SB_RSP<0>")
	)
	(segment
		(start 379.800612 -253.517908)
		(end 379.800612 -253.94412)
		(width 0.088646)
		(layer "In6.Cu")
		(net "M_G_CPU0_SB_RSP<0>")
	)
	(segment
		(start 437.065166 -246.192294)
		(end 434.283866 -246.192294)
		(width 0.18288)
		(layer "In6.Cu")
		(net "M_G_CPU0_SB_RSP<0>")
	)
	(segment
		(start 384.203702 -253.19355)
		(end 380.12497 -253.19355)
		(width 0.088646)
		(layer "In6.Cu")
		(net "M_G_CPU0_SB_RSP<0>")
	)
	(segment
		(start 404.182072 -252.30709)
		(end 403.257512 -253.23165)
		(width 0.18288)
		(layer "In6.Cu")
		(net "M_G_CPU0_SB_RSP<0>")
	)
	(segment
		(start 416.030664 -250.54306)
		(end 415.044128 -250.54306)
		(width 0.18288)
		(layer "In6.Cu")
		(net "M_G_CPU0_SB_RSP<0>")
	)
	(segment
		(start 430.172368 -248.92889)
		(end 427.939454 -248.92889)
		(width 0.18288)
		(layer "In6.Cu")
		(net "M_G_CPU0_SB_RSP<0>")
	)
	(segment
		(start 440.21883 -245.34241)
		(end 437.91505 -245.34241)
		(width 0.18288)
		(layer "In6.Cu")
		(net "M_G_CPU0_SB_RSP<0>")
	)
	(segment
		(start 393.814554 -255.196594)
		(end 392.814048 -254.997712)
		(width 0.18288)
		(layer "In6.Cu")
		(net "M_G_CPU0_SB_RSP<0>")
	)
	(segment
		(start 427.62297 -248.612406)
		(end 426.641514 -248.612406)
		(width 0.18288)
		(layer "In6.Cu")
		(net "M_G_CPU0_SB_RSP<0>")
	)
	(segment
		(start 434.283866 -246.192294)
		(end 432.519328 -247.956832)
		(width 0.18288)
		(layer "In6.Cu")
		(net "M_G_CPU0_SB_RSP<0>")
	)
	(segment
		(start 416.981386 -249.592338)
		(end 416.030664 -250.54306)
		(width 0.18288)
		(layer "In6.Cu")
		(net "M_G_CPU0_SB_RSP<0>")
	)
	(segment
		(start 403.257512 -253.23165)
		(end 397.667226 -253.23165)
		(width 0.18288)
		(layer "In6.Cu")
		(net "M_G_CPU0_SB_RSP<0>")
	)
	(segment
		(start 426.641514 -248.612406)
		(end 425.661582 -249.592338)
		(width 0.18288)
		(layer "In6.Cu")
		(net "M_G_CPU0_SB_RSP<0>")
	)
	(segment
		(start 397.667226 -253.23165)
		(end 395.702282 -255.196594)
		(width 0.18288)
		(layer "In6.Cu")
		(net "M_G_CPU0_SB_RSP<0>")
	)
	(segment
		(start 380.12497 -253.19355)
		(end 379.800612 -253.517908)
		(width 0.088646)
		(layer "In6.Cu")
		(net "M_G_CPU0_SB_RSP<0>")
	)
	(segment
		(start 425.661582 -249.592338)
		(end 416.981386 -249.592338)
		(width 0.18288)
		(layer "In6.Cu")
		(net "M_G_CPU0_SB_RSP<0>")
	)
	(segment
		(start 391.955274 -254.641858)
		(end 390.506966 -253.19355)
		(width 0.18288)
		(layer "In6.Cu")
		(net "M_G_CPU0_SB_RSP<0>")
	)
	(segment
		(start 443.367414 -243.216684)
		(end 442.344556 -243.216684)
		(width 0.18288)
		(layer "In6.Cu")
		(net "M_G_CPU0_SB_RSP<0>")
	)
	(segment
		(start 390.506966 -253.19355)
		(end 384.203702 -253.19355)
		(width 0.18288)
		(layer "In6.Cu")
		(net "M_G_CPU0_SB_RSP<0>")
	)
	(segment
		(start 432.519328 -247.956832)
		(end 430.172368 -248.92889)
		(width 0.18288)
		(layer "In6.Cu")
		(net "M_G_CPU0_SB_RSP<0>")
	)
	(segment
		(start 415.044128 -250.54306)
		(end 413.280098 -252.30709)
		(width 0.18288)
		(layer "In6.Cu")
		(net "M_G_CPU0_SB_RSP<0>")
	)
	(segment
		(start 413.280098 -252.30709)
		(end 404.182072 -252.30709)
		(width 0.18288)
		(layer "In6.Cu")
		(net "M_G_CPU0_SB_RSP<0>")
	)
	(segment
		(start 379.433328 -254.309626)
		(end 378.754894 -254.309626)
		(width 0.088646)
		(layer "In6.Cu")
		(net "M_G_CPU0_SB_RSP<0>")
	)
	(segment
		(start 392.814048 -254.997712)
		(end 391.955274 -254.641858)
		(width 0.18288)
		(layer "In6.Cu")
		(net "M_G_CPU0_SB_RSP<0>")
	)
	(segment
		(start 378.754894 -254.309626)
		(end 378.016262 -254.733552)
		(width 0.088646)
		(layer "In6.Cu")
		(net "M_G_CPU0_SB_RSP<0>")
	)
	(segment
		(start 427.939454 -248.92889)
		(end 427.62297 -248.612406)
		(width 0.18288)
		(layer "In6.Cu")
		(net "M_G_CPU0_SB_RSP<0>")
	)
	(segment
		(start 395.702282 -255.196594)
		(end 393.814554 -255.196594)
		(width 0.18288)
		(layer "In6.Cu")
		(net "M_G_CPU0_SB_RSP<0>")
	)
	(segment
		(start 442.344556 -243.216684)
		(end 440.21883 -245.34241)
		(width 0.18288)
		(layer "In6.Cu")
		(net "M_G_CPU0_SB_RSP<0>")
	)
	(segment
		(start 437.91505 -245.34241)
		(end 437.065166 -246.192294)
		(width 0.18288)
		(layer "In6.Cu")
		(net "M_G_CPU0_SB_RSP<0>")
	)
	(arc
		(start 379.800612 -253.94412)
		(mid 379.753615 -254.124411)
		(end 379.62459 -254.258826)
		(width 0.088646)
		(layer "In6.Cu")
		(net "M_G_CPU0_SB_RSP<0>")
	)
	(arc
		(start 379.62459 -254.258826)
		(mid 379.532273 -254.296698)
		(end 379.433328 -254.309626)
		(width 0.088646)
		(layer "In6.Cu")
		(net "M_G_CPU0_SB_RSP<0>")
	)
	(segment
		(start 445.47536 -247.04167)
		(end 445.482726 -247.049036)
		(width 0.1016)
		(layer "F.Cu")
		(net "M_G_CPU0_SB_PAR")
	)
	(segment
		(start 445.756792 -247.049036)
		(end 446.621662 -246.184166)
		(width 0.20066)
		(layer "F.Cu")
		(net "M_G_CPU0_SB_PAR")
	)
	(segment
		(start 443.46622 -247.04167)
		(end 445.47536 -247.04167)
		(width 0.1016)
		(layer "F.Cu")
		(net "M_G_CPU0_SB_PAR")
	)
	(segment
		(start 441.028582 -246.616728)
		(end 442.664342 -246.616728)
		(width 0.20066)
		(layer "F.Cu")
		(net "M_G_CPU0_SB_PAR")
	)
	(segment
		(start 380.256034 -247.714008)
		(end 380.256034 -247.178322)
		(width 0.20066)
		(layer "F.Cu")
		(net "M_G_CPU0_SB_PAR")
	)
	(segment
		(start 442.664342 -246.616728)
		(end 443.099952 -247.052338)
		(width 0.20066)
		(layer "F.Cu")
		(net "M_G_CPU0_SB_PAR")
	)
	(segment
		(start 446.621662 -246.184166)
		(end 447.025268 -246.184166)
		(width 0.20066)
		(layer "F.Cu")
		(net "M_G_CPU0_SB_PAR")
	)
	(segment
		(start 447.025268 -246.184166)
		(end 447.45783 -246.616728)
		(width 0.20066)
		(layer "F.Cu")
		(net "M_G_CPU0_SB_PAR")
	)
	(segment
		(start 445.482726 -247.049036)
		(end 445.756792 -247.049036)
		(width 0.20066)
		(layer "F.Cu")
		(net "M_G_CPU0_SB_PAR")
	)
	(segment
		(start 380.25578 -247.714262)
		(end 380.256034 -247.714008)
		(width 0.20066)
		(layer "F.Cu")
		(net "M_G_CPU0_SB_PAR")
	)
	(segment
		(start 439.898282 -246.616728)
		(end 441.028582 -246.616728)
		(width 0.20066)
		(layer "F.Cu")
		(net "M_G_CPU0_SB_PAR")
	)
	(segment
		(start 443.099952 -247.052338)
		(end 443.450726 -247.052338)
		(width 0.20066)
		(layer "F.Cu")
		(net "M_G_CPU0_SB_PAR")
	)
	(segment
		(start 443.450726 -247.052338)
		(end 443.455552 -247.052338)
		(width 0.101854)
		(layer "F.Cu")
		(net "M_G_CPU0_SB_PAR")
	)
	(segment
		(start 447.45783 -246.616728)
		(end 448.572382 -246.616728)
		(width 0.20066)
		(layer "F.Cu")
		(net "M_G_CPU0_SB_PAR")
	)
	(segment
		(start 443.455552 -247.052338)
		(end 443.46622 -247.04167)
		(width 0.1016)
		(layer "F.Cu")
		(net "M_G_CPU0_SB_PAR")
	)
	(segment
		(start 435.3179 -247.042432)
		(end 435.10454 -246.829072)
		(width 0.18288)
		(layer "In4.Cu")
		(net "M_G_CPU0_SB_PAR")
	)
	(segment
		(start 439.636916 -247.890792)
		(end 439.371994 -248.155714)
		(width 0.18288)
		(layer "In4.Cu")
		(net "M_G_CPU0_SB_PAR")
	)
	(segment
		(start 403.22881 -246.095774)
		(end 396.483586 -246.095774)
		(width 0.18288)
		(layer "In4.Cu")
		(net "M_G_CPU0_SB_PAR")
	)
	(segment
		(start 390.40816 -246.333264)
		(end 389.23468 -247.506744)
		(width 0.18288)
		(layer "In4.Cu")
		(net "M_G_CPU0_SB_PAR")
	)
	(segment
		(start 437.110124 -248.255536)
		(end 436.63997 -248.255536)
		(width 0.18288)
		(layer "In4.Cu")
		(net "M_G_CPU0_SB_PAR")
	)
	(segment
		(start 436.63997 -248.255536)
		(end 436.374794 -247.99036)
		(width 0.18288)
		(layer "In4.Cu")
		(net "M_G_CPU0_SB_PAR")
	)
	(segment
		(start 396.483586 -246.095774)
		(end 396.246096 -246.333264)
		(width 0.18288)
		(layer "In4.Cu")
		(net "M_G_CPU0_SB_PAR")
	)
	(segment
		(start 381.008382 -247.50268)
		(end 380.62535 -247.278398)
		(width 0.088646)
		(layer "In4.Cu")
		(net "M_G_CPU0_SB_PAR")
	)
	(segment
		(start 433.009548 -247.045226)
		(end 432.764438 -247.045226)
		(width 0.18288)
		(layer "In4.Cu")
		(net "M_G_CPU0_SB_PAR")
	)
	(segment
		(start 424.690794 -247.042432)
		(end 424.69054 -247.042686)
		(width 0.18288)
		(layer "In4.Cu")
		(net "M_G_CPU0_SB_PAR")
	)
	(segment
		(start 437.261254 -248.406666)
		(end 437.110124 -248.255536)
		(width 0.18288)
		(layer "In4.Cu")
		(net "M_G_CPU0_SB_PAR")
	)
	(segment
		(start 396.246096 -246.333264)
		(end 390.40816 -246.333264)
		(width 0.18288)
		(layer "In4.Cu")
		(net "M_G_CPU0_SB_PAR")
	)
	(segment
		(start 425.047664 -247.042432)
		(end 424.690794 -247.042432)
		(width 0.18288)
		(layer "In4.Cu")
		(net "M_G_CPU0_SB_PAR")
	)
	(segment
		(start 431.07356 -246.800624)
		(end 430.803558 -247.070626)
		(width 0.18288)
		(layer "In4.Cu")
		(net "M_G_CPU0_SB_PAR")
	)
	(segment
		(start 436.214774 -247.042432)
		(end 435.3179 -247.042432)
		(width 0.18288)
		(layer "In4.Cu")
		(net "M_G_CPU0_SB_PAR")
	)
	(segment
		(start 436.374794 -247.99036)
		(end 436.374794 -247.202452)
		(width 0.18288)
		(layer "In4.Cu")
		(net "M_G_CPU0_SB_PAR")
	)
	(segment
		(start 427.576234 -246.867426)
		(end 425.22267 -246.867426)
		(width 0.18288)
		(layer "In4.Cu")
		(net "M_G_CPU0_SB_PAR")
	)
	(segment
		(start 421.081454 -247.042686)
		(end 421.079676 -247.040908)
		(width 0.18288)
		(layer "In4.Cu")
		(net "M_G_CPU0_SB_PAR")
	)
	(segment
		(start 441.359544 -247.890792)
		(end 439.636916 -247.890792)
		(width 0.18288)
		(layer "In4.Cu")
		(net "M_G_CPU0_SB_PAR")
	)
	(segment
		(start 405.510492 -247.040908)
		(end 403.22881 -246.095774)
		(width 0.18288)
		(layer "In4.Cu")
		(net "M_G_CPU0_SB_PAR")
	)
	(segment
		(start 439.371994 -248.155714)
		(end 439.371994 -248.764806)
		(width 0.18288)
		(layer "In4.Cu")
		(net "M_G_CPU0_SB_PAR")
	)
	(segment
		(start 441.683394 -247.154446)
		(end 441.683394 -247.566942)
		(width 0.18288)
		(layer "In4.Cu")
		(net "M_G_CPU0_SB_PAR")
	)
	(segment
		(start 382.888236 -247.50268)
		(end 382.873504 -247.494044)
		(width 0.088646)
		(layer "In4.Cu")
		(net "M_G_CPU0_SB_PAR")
	)
	(segment
		(start 431.904648 -247.070626)
		(end 431.55108 -247.070626)
		(width 0.18288)
		(layer "In4.Cu")
		(net "M_G_CPU0_SB_PAR")
	)
	(segment
		(start 381.016764 -247.507506)
		(end 381.008382 -247.50268)
		(width 0.088646)
		(layer "In4.Cu")
		(net "M_G_CPU0_SB_PAR")
	)
	(segment
		(start 425.22267 -246.867426)
		(end 425.047664 -247.042432)
		(width 0.18288)
		(layer "In4.Cu")
		(net "M_G_CPU0_SB_PAR")
	)
	(segment
		(start 432.764438 -247.045226)
		(end 432.548284 -246.829072)
		(width 0.18288)
		(layer "In4.Cu")
		(net "M_G_CPU0_SB_PAR")
	)
	(segment
		(start 424.69054 -247.042686)
		(end 421.081454 -247.042686)
		(width 0.18288)
		(layer "In4.Cu")
		(net "M_G_CPU0_SB_PAR")
	)
	(segment
		(start 440.27598 -246.994426)
		(end 441.523374 -246.994426)
		(width 0.18288)
		(layer "In4.Cu")
		(net "M_G_CPU0_SB_PAR")
	)
	(segment
		(start 427.779434 -247.070626)
		(end 427.576234 -246.867426)
		(width 0.18288)
		(layer "In4.Cu")
		(net "M_G_CPU0_SB_PAR")
	)
	(segment
		(start 436.374794 -247.202452)
		(end 436.214774 -247.042432)
		(width 0.18288)
		(layer "In4.Cu")
		(net "M_G_CPU0_SB_PAR")
	)
	(segment
		(start 385.766818 -247.506744)
		(end 385.381246 -247.506744)
		(width 0.088646)
		(layer "In4.Cu")
		(net "M_G_CPU0_SB_PAR")
	)
	(segment
		(start 441.523374 -246.994426)
		(end 441.683394 -247.154446)
		(width 0.18288)
		(layer "In4.Cu")
		(net "M_G_CPU0_SB_PAR")
	)
	(segment
		(start 430.803558 -247.070626)
		(end 427.779434 -247.070626)
		(width 0.18288)
		(layer "In4.Cu")
		(net "M_G_CPU0_SB_PAR")
	)
	(segment
		(start 389.23468 -247.506744)
		(end 385.766818 -247.506744)
		(width 0.18288)
		(layer "In4.Cu")
		(net "M_G_CPU0_SB_PAR")
	)
	(segment
		(start 432.548284 -246.829072)
		(end 432.146202 -246.829072)
		(width 0.18288)
		(layer "In4.Cu")
		(net "M_G_CPU0_SB_PAR")
	)
	(segment
		(start 437.459374 -248.924826)
		(end 437.261254 -248.726706)
		(width 0.18288)
		(layer "In4.Cu")
		(net "M_G_CPU0_SB_PAR")
	)
	(segment
		(start 432.146202 -246.829072)
		(end 431.904648 -247.070626)
		(width 0.18288)
		(layer "In4.Cu")
		(net "M_G_CPU0_SB_PAR")
	)
	(segment
		(start 385.381246 -247.506744)
		(end 385.295648 -247.592342)
		(width 0.088646)
		(layer "In4.Cu")
		(net "M_G_CPU0_SB_PAR")
	)
	(segment
		(start 385.295648 -247.592342)
		(end 383.94513 -247.592342)
		(width 0.088646)
		(layer "In4.Cu")
		(net "M_G_CPU0_SB_PAR")
	)
	(segment
		(start 433.225702 -246.829072)
		(end 433.009548 -247.045226)
		(width 0.18288)
		(layer "In4.Cu")
		(net "M_G_CPU0_SB_PAR")
	)
	(segment
		(start 431.55108 -247.070626)
		(end 431.281078 -246.800624)
		(width 0.18288)
		(layer "In4.Cu")
		(net "M_G_CPU0_SB_PAR")
	)
	(segment
		(start 381.948436 -247.50268)
		(end 381.933704 -247.494044)
		(width 0.088646)
		(layer "In4.Cu")
		(net "M_G_CPU0_SB_PAR")
	)
	(segment
		(start 435.10454 -246.829072)
		(end 433.225702 -246.829072)
		(width 0.18288)
		(layer "In4.Cu")
		(net "M_G_CPU0_SB_PAR")
	)
	(segment
		(start 439.371994 -248.764806)
		(end 439.211974 -248.924826)
		(width 0.18288)
		(layer "In4.Cu")
		(net "M_G_CPU0_SB_PAR")
	)
	(segment
		(start 431.281078 -246.800624)
		(end 431.07356 -246.800624)
		(width 0.18288)
		(layer "In4.Cu")
		(net "M_G_CPU0_SB_PAR")
	)
	(segment
		(start 439.898282 -246.616728)
		(end 440.27598 -246.994426)
		(width 0.18288)
		(layer "In4.Cu")
		(net "M_G_CPU0_SB_PAR")
	)
	(segment
		(start 439.211974 -248.924826)
		(end 437.459374 -248.924826)
		(width 0.18288)
		(layer "In4.Cu")
		(net "M_G_CPU0_SB_PAR")
	)
	(segment
		(start 421.079676 -247.040908)
		(end 405.510492 -247.040908)
		(width 0.18288)
		(layer "In4.Cu")
		(net "M_G_CPU0_SB_PAR")
	)
	(segment
		(start 437.261254 -248.726706)
		(end 437.261254 -248.406666)
		(width 0.18288)
		(layer "In4.Cu")
		(net "M_G_CPU0_SB_PAR")
	)
	(segment
		(start 441.683394 -247.566942)
		(end 441.359544 -247.890792)
		(width 0.18288)
		(layer "In4.Cu")
		(net "M_G_CPU0_SB_PAR")
	)
	(arc
		(start 380.62535 -247.278398)
		(mid 380.44736 -247.203736)
		(end 380.256034 -247.178322)
		(width 0.088646)
		(layer "In4.Cu")
		(net "M_G_CPU0_SB_PAR")
	)
	(arc
		(start 383.94513 -247.592342)
		(mid 383.889525 -247.543668)
		(end 383.828036 -247.50268)
		(width 0.088646)
		(layer "In4.Cu")
		(net "M_G_CPU0_SB_PAR")
	)
	(arc
		(start 383.262632 -247.50268)
		(mid 383.075434 -247.552823)
		(end 382.888236 -247.50268)
		(width 0.088646)
		(layer "In4.Cu")
		(net "M_G_CPU0_SB_PAR")
	)
	(arc
		(start 381.933704 -247.494044)
		(mid 381.657229 -247.426724)
		(end 381.383032 -247.50268)
		(width 0.088646)
		(layer "In4.Cu")
		(net "M_G_CPU0_SB_PAR")
	)
	(arc
		(start 383.828036 -247.50268)
		(mid 383.545334 -247.426904)
		(end 383.262632 -247.50268)
		(width 0.088646)
		(layer "In4.Cu")
		(net "M_G_CPU0_SB_PAR")
	)
	(arc
		(start 381.383032 -247.50268)
		(mid 381.200527 -247.552918)
		(end 381.016764 -247.507506)
		(width 0.088646)
		(layer "In4.Cu")
		(net "M_G_CPU0_SB_PAR")
	)
	(arc
		(start 382.322832 -247.50268)
		(mid 382.135634 -247.552823)
		(end 381.948436 -247.50268)
		(width 0.088646)
		(layer "In4.Cu")
		(net "M_G_CPU0_SB_PAR")
	)
	(arc
		(start 382.873504 -247.494044)
		(mid 382.597029 -247.426724)
		(end 382.322832 -247.50268)
		(width 0.088646)
		(layer "In4.Cu")
		(net "M_G_CPU0_SB_PAR")
	)
	(segment
		(start 439.710322 -238.541814)
		(end 439.839354 -238.541814)
		(width 0.20066)
		(layer "F.Cu")
		(net "M_G_CPU0_SB_DQS_DP<9>")
	)
	(segment
		(start 443.035436 -238.245396)
		(end 443.4459 -237.834932)
		(width 0.20066)
		(layer "F.Cu")
		(net "M_G_CPU0_SB_DQS_DP<9>")
	)
	(segment
		(start 436.928514 -238.116618)
		(end 437.517794 -238.116618)
		(width 0.20066)
		(layer "F.Cu")
		(net "M_G_CPU0_SB_DQS_DP<9>")
	)
	(segment
		(start 439.875676 -238.541814)
		(end 442.032898 -238.541814)
		(width 0.1016)
		(layer "F.Cu")
		(net "M_G_CPU0_SB_DQS_DP<9>")
	)
	(segment
		(start 443.641988 -237.834932)
		(end 443.923674 -238.116618)
		(width 0.20066)
		(layer "F.Cu")
		(net "M_G_CPU0_SB_DQS_DP<9>")
	)
	(segment
		(start 442.032898 -238.541814)
		(end 442.24702 -238.541814)
		(width 0.101854)
		(layer "F.Cu")
		(net "M_G_CPU0_SB_DQS_DP<9>")
	)
	(segment
		(start 377.436634 -242.830604)
		(end 377.436634 -242.294918)
		(width 0.20066)
		(layer "F.Cu")
		(net "M_G_CPU0_SB_DQS_DP<9>")
	)
	(segment
		(start 437.517794 -238.116618)
		(end 437.758332 -237.87608)
		(width 0.20066)
		(layer "F.Cu")
		(net "M_G_CPU0_SB_DQS_DP<9>")
	)
	(segment
		(start 435.823614 -238.116618)
		(end 436.928514 -238.116618)
		(width 0.20066)
		(layer "F.Cu")
		(net "M_G_CPU0_SB_DQS_DP<9>")
	)
	(segment
		(start 442.66485 -238.245396)
		(end 443.035436 -238.245396)
		(width 0.20066)
		(layer "F.Cu")
		(net "M_G_CPU0_SB_DQS_DP<9>")
	)
	(segment
		(start 439.459116 -238.290608)
		(end 439.710322 -238.541814)
		(width 0.20066)
		(layer "F.Cu")
		(net "M_G_CPU0_SB_DQS_DP<9>")
	)
	(segment
		(start 438.328816 -237.87608)
		(end 438.743344 -238.290608)
		(width 0.20066)
		(layer "F.Cu")
		(net "M_G_CPU0_SB_DQS_DP<9>")
	)
	(segment
		(start 443.923674 -238.116618)
		(end 444.472314 -238.116618)
		(width 0.20066)
		(layer "F.Cu")
		(net "M_G_CPU0_SB_DQS_DP<9>")
	)
	(segment
		(start 438.743344 -238.290608)
		(end 439.459116 -238.290608)
		(width 0.20066)
		(layer "F.Cu")
		(net "M_G_CPU0_SB_DQS_DP<9>")
	)
	(segment
		(start 439.839354 -238.541814)
		(end 439.875676 -238.541814)
		(width 0.101854)
		(layer "F.Cu")
		(net "M_G_CPU0_SB_DQS_DP<9>")
	)
	(segment
		(start 442.368432 -238.541814)
		(end 442.66485 -238.245396)
		(width 0.20066)
		(layer "F.Cu")
		(net "M_G_CPU0_SB_DQS_DP<9>")
	)
	(segment
		(start 443.4459 -237.834932)
		(end 443.641988 -237.834932)
		(width 0.20066)
		(layer "F.Cu")
		(net "M_G_CPU0_SB_DQS_DP<9>")
	)
	(segment
		(start 437.758332 -237.87608)
		(end 438.328816 -237.87608)
		(width 0.20066)
		(layer "F.Cu")
		(net "M_G_CPU0_SB_DQS_DP<9>")
	)
	(segment
		(start 377.43638 -242.830858)
		(end 377.436634 -242.830604)
		(width 0.20066)
		(layer "F.Cu")
		(net "M_G_CPU0_SB_DQS_DP<9>")
	)
	(segment
		(start 442.24702 -238.541814)
		(end 442.368432 -238.541814)
		(width 0.20066)
		(layer "F.Cu")
		(net "M_G_CPU0_SB_DQS_DP<9>")
	)
	(segment
		(start 420.544244 -239.393984)
		(end 420.252652 -239.102392)
		(width 0.18288)
		(layer "In4.Cu")
		(net "M_G_CPU0_SB_DQS_DP<9>")
	)
	(segment
		(start 388.255764 -242.417092)
		(end 388.232396 -242.417092)
		(width 0.088646)
		(layer "In4.Cu")
		(net "M_G_CPU0_SB_DQS_DP<9>")
	)
	(segment
		(start 425.311316 -238.26089)
		(end 425.02836 -238.543846)
		(width 0.18288)
		(layer "In4.Cu")
		(net "M_G_CPU0_SB_DQS_DP<9>")
	)
	(segment
		(start 419.394894 -239.102392)
		(end 419.142418 -238.849916)
		(width 0.18288)
		(layer "In4.Cu")
		(net "M_G_CPU0_SB_DQS_DP<9>")
	)
	(segment
		(start 412.682182 -238.256572)
		(end 412.382462 -238.556292)
		(width 0.18288)
		(layer "In4.Cu")
		(net "M_G_CPU0_SB_DQS_DP<9>")
	)
	(segment
		(start 413.654494 -238.256572)
		(end 412.682182 -238.256572)
		(width 0.18288)
		(layer "In4.Cu")
		(net "M_G_CPU0_SB_DQS_DP<9>")
	)
	(segment
		(start 416.085274 -238.511334)
		(end 413.909256 -238.511334)
		(width 0.18288)
		(layer "In4.Cu")
		(net "M_G_CPU0_SB_DQS_DP<9>")
	)
	(segment
		(start 421.710104 -239.111028)
		(end 421.211248 -239.111028)
		(width 0.18288)
		(layer "In4.Cu")
		(net "M_G_CPU0_SB_DQS_DP<9>")
	)
	(segment
		(start 383.358136 -242.78463)
		(end 383.347722 -242.790726)
		(width 0.088646)
		(layer "In4.Cu")
		(net "M_G_CPU0_SB_DQS_DP<9>")
	)
	(segment
		(start 399.27276 -239.891824)
		(end 394.914628 -239.891824)
		(width 0.18288)
		(layer "In4.Cu")
		(net "M_G_CPU0_SB_DQS_DP<9>")
	)
	(segment
		(start 388.172452 -242.357148)
		(end 387.093714 -242.357148)
		(width 0.088646)
		(layer "In4.Cu")
		(net "M_G_CPU0_SB_DQS_DP<9>")
	)
	(segment
		(start 408.417268 -238.490252)
		(end 400.674332 -238.490252)
		(width 0.18288)
		(layer "In4.Cu")
		(net "M_G_CPU0_SB_DQS_DP<9>")
	)
	(segment
		(start 387.093714 -242.357148)
		(end 386.717286 -242.733576)
		(width 0.088646)
		(layer "In4.Cu")
		(net "M_G_CPU0_SB_DQS_DP<9>")
	)
	(segment
		(start 435.537356 -237.83036)
		(end 435.041548 -237.83036)
		(width 0.18288)
		(layer "In4.Cu")
		(net "M_G_CPU0_SB_DQS_DP<9>")
	)
	(segment
		(start 382.418082 -242.78463)
		(end 382.407668 -242.790726)
		(width 0.088646)
		(layer "In4.Cu")
		(net "M_G_CPU0_SB_DQS_DP<9>")
	)
	(segment
		(start 420.928292 -239.393984)
		(end 420.544244 -239.393984)
		(width 0.18288)
		(layer "In4.Cu")
		(net "M_G_CPU0_SB_DQS_DP<9>")
	)
	(segment
		(start 419.142418 -238.849916)
		(end 416.423856 -238.849916)
		(width 0.18288)
		(layer "In4.Cu")
		(net "M_G_CPU0_SB_DQS_DP<9>")
	)
	(segment
		(start 426.23105 -238.26089)
		(end 425.311316 -238.26089)
		(width 0.18288)
		(layer "In4.Cu")
		(net "M_G_CPU0_SB_DQS_DP<9>")
	)
	(segment
		(start 424.644312 -238.543846)
		(end 424.35272 -238.252254)
		(width 0.18288)
		(layer "In4.Cu")
		(net "M_G_CPU0_SB_DQS_DP<9>")
	)
	(segment
		(start 400.674332 -238.490252)
		(end 399.27276 -239.891824)
		(width 0.18288)
		(layer "In4.Cu")
		(net "M_G_CPU0_SB_DQS_DP<9>")
	)
	(segment
		(start 409.215082 -237.692438)
		(end 408.417268 -238.490252)
		(width 0.18288)
		(layer "In4.Cu")
		(net "M_G_CPU0_SB_DQS_DP<9>")
	)
	(segment
		(start 424.35272 -238.252254)
		(end 422.568878 -238.252254)
		(width 0.18288)
		(layer "In4.Cu")
		(net "M_G_CPU0_SB_DQS_DP<9>")
	)
	(segment
		(start 411.719268 -238.252254)
		(end 411.235652 -238.252254)
		(width 0.18288)
		(layer "In4.Cu")
		(net "M_G_CPU0_SB_DQS_DP<9>")
	)
	(segment
		(start 388.232396 -242.417092)
		(end 388.172452 -242.357148)
		(width 0.088646)
		(layer "In4.Cu")
		(net "M_G_CPU0_SB_DQS_DP<9>")
	)
	(segment
		(start 425.02836 -238.543846)
		(end 424.644312 -238.543846)
		(width 0.18288)
		(layer "In4.Cu")
		(net "M_G_CPU0_SB_DQS_DP<9>")
	)
	(segment
		(start 435.041548 -237.83036)
		(end 434.830474 -237.619286)
		(width 0.18288)
		(layer "In4.Cu")
		(net "M_G_CPU0_SB_DQS_DP<9>")
	)
	(segment
		(start 386.717286 -242.733576)
		(end 386.364988 -242.733576)
		(width 0.088646)
		(layer "In4.Cu")
		(net "M_G_CPU0_SB_DQS_DP<9>")
	)
	(segment
		(start 410.27604 -237.692438)
		(end 409.215082 -237.692438)
		(width 0.18288)
		(layer "In4.Cu")
		(net "M_G_CPU0_SB_DQS_DP<9>")
	)
	(segment
		(start 434.830474 -237.619286)
		(end 426.872654 -237.619286)
		(width 0.18288)
		(layer "In4.Cu")
		(net "M_G_CPU0_SB_DQS_DP<9>")
	)
	(segment
		(start 412.023306 -238.556292)
		(end 411.719268 -238.252254)
		(width 0.18288)
		(layer "In4.Cu")
		(net "M_G_CPU0_SB_DQS_DP<9>")
	)
	(segment
		(start 422.568878 -238.252254)
		(end 421.710104 -239.111028)
		(width 0.18288)
		(layer "In4.Cu")
		(net "M_G_CPU0_SB_DQS_DP<9>")
	)
	(segment
		(start 421.211248 -239.111028)
		(end 420.928292 -239.393984)
		(width 0.18288)
		(layer "In4.Cu")
		(net "M_G_CPU0_SB_DQS_DP<9>")
	)
	(segment
		(start 412.382462 -238.556292)
		(end 412.023306 -238.556292)
		(width 0.18288)
		(layer "In4.Cu")
		(net "M_G_CPU0_SB_DQS_DP<9>")
	)
	(segment
		(start 380.538736 -242.78463)
		(end 380.528322 -242.790726)
		(width 0.088646)
		(layer "In4.Cu")
		(net "M_G_CPU0_SB_DQS_DP<9>")
	)
	(segment
		(start 377.749308 -242.295172)
		(end 377.436634 -242.294918)
		(width 0.088646)
		(layer "In4.Cu")
		(net "M_G_CPU0_SB_DQS_DP<9>")
	)
	(segment
		(start 411.235652 -238.252254)
		(end 410.836364 -238.252762)
		(width 0.18288)
		(layer "In4.Cu")
		(net "M_G_CPU0_SB_DQS_DP<9>")
	)
	(segment
		(start 380.927864 -242.793266)
		(end 380.913132 -242.78463)
		(width 0.088646)
		(layer "In4.Cu")
		(net "M_G_CPU0_SB_DQS_DP<9>")
	)
	(segment
		(start 416.423856 -238.849916)
		(end 416.085274 -238.511334)
		(width 0.18288)
		(layer "In4.Cu")
		(net "M_G_CPU0_SB_DQS_DP<9>")
	)
	(segment
		(start 426.872654 -237.619286)
		(end 426.23105 -238.26089)
		(width 0.18288)
		(layer "In4.Cu")
		(net "M_G_CPU0_SB_DQS_DP<9>")
	)
	(segment
		(start 378.658882 -242.78463)
		(end 378.64415 -242.793266)
		(width 0.088646)
		(layer "In4.Cu")
		(net "M_G_CPU0_SB_DQS_DP<9>")
	)
	(segment
		(start 379.598682 -242.78463)
		(end 379.58395 -242.793266)
		(width 0.088646)
		(layer "In4.Cu")
		(net "M_G_CPU0_SB_DQS_DP<9>")
	)
	(segment
		(start 394.914628 -239.891824)
		(end 392.38936 -242.417092)
		(width 0.18288)
		(layer "In4.Cu")
		(net "M_G_CPU0_SB_DQS_DP<9>")
	)
	(segment
		(start 392.38936 -242.417092)
		(end 388.255764 -242.417092)
		(width 0.18288)
		(layer "In4.Cu")
		(net "M_G_CPU0_SB_DQS_DP<9>")
	)
	(segment
		(start 413.909256 -238.511334)
		(end 413.654494 -238.256572)
		(width 0.18288)
		(layer "In4.Cu")
		(net "M_G_CPU0_SB_DQS_DP<9>")
	)
	(segment
		(start 435.823614 -238.116618)
		(end 435.537356 -237.83036)
		(width 0.18288)
		(layer "In4.Cu")
		(net "M_G_CPU0_SB_DQS_DP<9>")
	)
	(segment
		(start 377.81484 -242.360704)
		(end 377.749308 -242.295172)
		(width 0.088646)
		(layer "In4.Cu")
		(net "M_G_CPU0_SB_DQS_DP<9>")
	)
	(segment
		(start 410.836364 -238.252762)
		(end 410.27604 -237.692438)
		(width 0.18288)
		(layer "In4.Cu")
		(net "M_G_CPU0_SB_DQS_DP<9>")
	)
	(segment
		(start 420.252652 -239.102392)
		(end 419.394894 -239.102392)
		(width 0.18288)
		(layer "In4.Cu")
		(net "M_G_CPU0_SB_DQS_DP<9>")
	)
	(arc
		(start 382.407668 -242.790726)
		(mid 382.12949 -242.860449)
		(end 381.852932 -242.78463)
		(width 0.088646)
		(layer "In4.Cu")
		(net "M_G_CPU0_SB_DQS_DP<9>")
	)
	(arc
		(start 381.478536 -242.78463)
		(mid 381.204337 -242.860465)
		(end 380.927864 -242.793266)
		(width 0.088646)
		(layer "In4.Cu")
		(net "M_G_CPU0_SB_DQS_DP<9>")
	)
	(arc
		(start 380.913132 -242.78463)
		(mid 380.725934 -242.734487)
		(end 380.538736 -242.78463)
		(width 0.088646)
		(layer "In4.Cu")
		(net "M_G_CPU0_SB_DQS_DP<9>")
	)
	(arc
		(start 383.347722 -242.790726)
		(mid 383.06929 -242.860572)
		(end 382.792478 -242.78463)
		(width 0.088646)
		(layer "In4.Cu")
		(net "M_G_CPU0_SB_DQS_DP<9>")
	)
	(arc
		(start 382.792478 -242.78463)
		(mid 382.60528 -242.734487)
		(end 382.418082 -242.78463)
		(width 0.088646)
		(layer "In4.Cu")
		(net "M_G_CPU0_SB_DQS_DP<9>")
	)
	(arc
		(start 386.177536 -242.78463)
		(mid 385.894834 -242.860372)
		(end 385.612132 -242.78463)
		(width 0.088646)
		(layer "In4.Cu")
		(net "M_G_CPU0_SB_DQS_DP<9>")
	)
	(arc
		(start 378.093478 -242.78463)
		(mid 377.909887 -242.614495)
		(end 377.817634 -242.381786)
		(width 0.088646)
		(layer "In4.Cu")
		(net "M_G_CPU0_SB_DQS_DP<9>")
	)
	(arc
		(start 385.237736 -242.78463)
		(mid 384.955034 -242.860372)
		(end 384.672332 -242.78463)
		(width 0.088646)
		(layer "In4.Cu")
		(net "M_G_CPU0_SB_DQS_DP<9>")
	)
	(arc
		(start 379.973078 -242.78463)
		(mid 379.78588 -242.734487)
		(end 379.598682 -242.78463)
		(width 0.088646)
		(layer "In4.Cu")
		(net "M_G_CPU0_SB_DQS_DP<9>")
	)
	(arc
		(start 381.852932 -242.78463)
		(mid 381.665734 -242.734487)
		(end 381.478536 -242.78463)
		(width 0.088646)
		(layer "In4.Cu")
		(net "M_G_CPU0_SB_DQS_DP<9>")
	)
	(arc
		(start 379.033278 -242.78463)
		(mid 378.84608 -242.734487)
		(end 378.658882 -242.78463)
		(width 0.088646)
		(layer "In4.Cu")
		(net "M_G_CPU0_SB_DQS_DP<9>")
	)
	(arc
		(start 384.672332 -242.78463)
		(mid 384.485134 -242.734487)
		(end 384.297936 -242.78463)
		(width 0.088646)
		(layer "In4.Cu")
		(net "M_G_CPU0_SB_DQS_DP<9>")
	)
	(arc
		(start 377.817634 -242.381786)
		(mid 377.816138 -242.371258)
		(end 377.81484 -242.360704)
		(width 0.088646)
		(layer "In4.Cu")
		(net "M_G_CPU0_SB_DQS_DP<9>")
	)
	(arc
		(start 385.612132 -242.78463)
		(mid 385.424934 -242.734487)
		(end 385.237736 -242.78463)
		(width 0.088646)
		(layer "In4.Cu")
		(net "M_G_CPU0_SB_DQS_DP<9>")
	)
	(arc
		(start 386.364988 -242.733576)
		(mid 386.267907 -242.746772)
		(end 386.177536 -242.78463)
		(width 0.088646)
		(layer "In4.Cu")
		(net "M_G_CPU0_SB_DQS_DP<9>")
	)
	(arc
		(start 383.732532 -242.78463)
		(mid 383.545334 -242.734487)
		(end 383.358136 -242.78463)
		(width 0.088646)
		(layer "In4.Cu")
		(net "M_G_CPU0_SB_DQS_DP<9>")
	)
	(arc
		(start 378.64415 -242.793266)
		(mid 378.367675 -242.860586)
		(end 378.093478 -242.78463)
		(width 0.088646)
		(layer "In4.Cu")
		(net "M_G_CPU0_SB_DQS_DP<9>")
	)
	(arc
		(start 384.297936 -242.78463)
		(mid 384.015234 -242.860372)
		(end 383.732532 -242.78463)
		(width 0.088646)
		(layer "In4.Cu")
		(net "M_G_CPU0_SB_DQS_DP<9>")
	)
	(arc
		(start 380.528322 -242.790726)
		(mid 380.24989 -242.860572)
		(end 379.973078 -242.78463)
		(width 0.088646)
		(layer "In4.Cu")
		(net "M_G_CPU0_SB_DQS_DP<9>")
	)
	(arc
		(start 379.58395 -242.793266)
		(mid 379.307475 -242.860586)
		(end 379.033278 -242.78463)
		(width 0.088646)
		(layer "In4.Cu")
		(net "M_G_CPU0_SB_DQS_DP<9>")
	)
	(segment
		(start 443.450726 -198.584566)
		(end 443.455552 -198.584566)
		(width 0.101854)
		(layer "F.Cu")
		(net "M_G_CPU0_SB_DQS_DP<8>")
	)
	(segment
		(start 439.923682 -199.01662)
		(end 441.028582 -199.01662)
		(width 0.20066)
		(layer "F.Cu")
		(net "M_G_CPU0_SB_DQS_DP<8>")
	)
	(segment
		(start 442.177932 -199.267826)
		(end 442.602874 -198.842884)
		(width 0.20066)
		(layer "F.Cu")
		(net "M_G_CPU0_SB_DQS_DP<8>")
	)
	(segment
		(start 445.47536 -198.591678)
		(end 445.482726 -198.584312)
		(width 0.1016)
		(layer "F.Cu")
		(net "M_G_CPU0_SB_DQS_DP<8>")
	)
	(segment
		(start 443.455552 -198.584566)
		(end 443.462664 -198.591678)
		(width 0.1016)
		(layer "F.Cu")
		(net "M_G_CPU0_SB_DQS_DP<8>")
	)
	(segment
		(start 443.462664 -198.591678)
		(end 445.47536 -198.591678)
		(width 0.1016)
		(layer "F.Cu")
		(net "M_G_CPU0_SB_DQS_DP<8>")
	)
	(segment
		(start 385.424934 -217.064336)
		(end 385.424934 -217.600276)
		(width 0.20066)
		(layer "F.Cu")
		(net "M_G_CPU0_SB_DQS_DP<8>")
	)
	(segment
		(start 446.713102 -198.839328)
		(end 447.158618 -199.284844)
		(width 0.20066)
		(layer "F.Cu")
		(net "M_G_CPU0_SB_DQS_DP<8>")
	)
	(segment
		(start 442.881258 -198.842884)
		(end 443.139576 -198.584566)
		(width 0.20066)
		(layer "F.Cu")
		(net "M_G_CPU0_SB_DQS_DP<8>")
	)
	(segment
		(start 447.736214 -199.284844)
		(end 448.004438 -199.01662)
		(width 0.20066)
		(layer "F.Cu")
		(net "M_G_CPU0_SB_DQS_DP<8>")
	)
	(segment
		(start 441.028582 -199.01662)
		(end 441.621926 -199.01662)
		(width 0.20066)
		(layer "F.Cu")
		(net "M_G_CPU0_SB_DQS_DP<8>")
	)
	(segment
		(start 442.602874 -198.842884)
		(end 442.881258 -198.842884)
		(width 0.20066)
		(layer "F.Cu")
		(net "M_G_CPU0_SB_DQS_DP<8>")
	)
	(segment
		(start 445.482726 -198.584312)
		(end 445.804544 -198.584312)
		(width 0.20066)
		(layer "F.Cu")
		(net "M_G_CPU0_SB_DQS_DP<8>")
	)
	(segment
		(start 446.05956 -198.839328)
		(end 446.713102 -198.839328)
		(width 0.20066)
		(layer "F.Cu")
		(net "M_G_CPU0_SB_DQS_DP<8>")
	)
	(segment
		(start 448.004438 -199.01662)
		(end 448.572382 -199.01662)
		(width 0.20066)
		(layer "F.Cu")
		(net "M_G_CPU0_SB_DQS_DP<8>")
	)
	(segment
		(start 445.804544 -198.584312)
		(end 446.05956 -198.839328)
		(width 0.20066)
		(layer "F.Cu")
		(net "M_G_CPU0_SB_DQS_DP<8>")
	)
	(segment
		(start 443.139576 -198.584566)
		(end 443.450726 -198.584566)
		(width 0.20066)
		(layer "F.Cu")
		(net "M_G_CPU0_SB_DQS_DP<8>")
	)
	(segment
		(start 447.158618 -199.284844)
		(end 447.736214 -199.284844)
		(width 0.20066)
		(layer "F.Cu")
		(net "M_G_CPU0_SB_DQS_DP<8>")
	)
	(segment
		(start 441.621926 -199.01662)
		(end 441.873132 -199.267826)
		(width 0.20066)
		(layer "F.Cu")
		(net "M_G_CPU0_SB_DQS_DP<8>")
	)
	(segment
		(start 441.873132 -199.267826)
		(end 442.177932 -199.267826)
		(width 0.20066)
		(layer "F.Cu")
		(net "M_G_CPU0_SB_DQS_DP<8>")
	)
	(segment
		(start 420.92372 -196.892418)
		(end 420.533576 -196.892418)
		(width 0.18288)
		(layer "In6.Cu")
		(net "M_G_CPU0_SB_DQS_DP<8>")
	)
	(segment
		(start 387.506464 -217.380058)
		(end 387.491732 -217.388694)
		(width 0.088646)
		(layer "In6.Cu")
		(net "M_G_CPU0_SB_DQS_DP<8>")
	)
	(segment
		(start 427.70806 -198.339202)
		(end 427.51248 -198.53402)
		(width 0.18288)
		(layer "In6.Cu")
		(net "M_G_CPU0_SB_DQS_DP<8>")
	)
	(segment
		(start 435.65064 -198.59244)
		(end 435.37251 -198.87057)
		(width 0.18288)
		(layer "In6.Cu")
		(net "M_G_CPU0_SB_DQS_DP<8>")
	)
	(segment
		(start 439.635392 -199.30491)
		(end 439.316876 -199.30491)
		(width 0.18288)
		(layer "In6.Cu")
		(net "M_G_CPU0_SB_DQS_DP<8>")
	)
	(segment
		(start 417.21786 -197.164198)
		(end 415.65957 -197.809866)
		(width 0.18288)
		(layer "In6.Cu")
		(net "M_G_CPU0_SB_DQS_DP<8>")
	)
	(segment
		(start 389.576564 -215.709246)
		(end 389.560054 -215.725756)
		(width 0.088646)
		(layer "In6.Cu")
		(net "M_G_CPU0_SB_DQS_DP<8>")
	)
	(segment
		(start 422.391332 -197.50913)
		(end 422.236646 -197.354444)
		(width 0.18288)
		(layer "In6.Cu")
		(net "M_G_CPU0_SB_DQS_DP<8>")
	)
	(segment
		(start 438.067958 -199.492362)
		(end 436.562754 -198.87057)
		(width 0.18288)
		(layer "In6.Cu")
		(net "M_G_CPU0_SB_DQS_DP<8>")
	)
	(segment
		(start 396.325344 -208.960466)
		(end 389.576564 -215.709246)
		(width 0.18288)
		(layer "In6.Cu")
		(net "M_G_CPU0_SB_DQS_DP<8>")
	)
	(segment
		(start 423.42308 -198.028306)
		(end 422.546018 -197.663562)
		(width 0.18288)
		(layer "In6.Cu")
		(net "M_G_CPU0_SB_DQS_DP<8>")
	)
	(segment
		(start 426.047154 -198.194168)
		(end 425.630594 -198.020686)
		(width 0.18288)
		(layer "In6.Cu")
		(net "M_G_CPU0_SB_DQS_DP<8>")
	)
	(segment
		(start 415.65957 -197.809866)
		(end 413.17164 -197.809866)
		(width 0.18288)
		(layer "In6.Cu")
		(net "M_G_CPU0_SB_DQS_DP<8>")
	)
	(segment
		(start 428.0154 -198.211948)
		(end 427.70806 -198.339202)
		(width 0.18288)
		(layer "In6.Cu")
		(net "M_G_CPU0_SB_DQS_DP<8>")
	)
	(segment
		(start 389.346694 -216.867232)
		(end 388.900924 -217.313002)
		(width 0.088646)
		(layer "In6.Cu")
		(net "M_G_CPU0_SB_DQS_DP<8>")
	)
	(segment
		(start 436.288942 -198.87057)
		(end 436.010812 -198.59244)
		(width 0.18288)
		(layer "In6.Cu")
		(net "M_G_CPU0_SB_DQS_DP<8>")
	)
	(segment
		(start 424.369738 -198.028306)
		(end 423.42308 -198.028306)
		(width 0.18288)
		(layer "In6.Cu")
		(net "M_G_CPU0_SB_DQS_DP<8>")
	)
	(segment
		(start 436.562754 -198.87057)
		(end 436.288942 -198.87057)
		(width 0.18288)
		(layer "In6.Cu")
		(net "M_G_CPU0_SB_DQS_DP<8>")
	)
	(segment
		(start 405.653748 -197.820026)
		(end 396.325344 -207.14843)
		(width 0.18288)
		(layer "In6.Cu")
		(net "M_G_CPU0_SB_DQS_DP<8>")
	)
	(segment
		(start 422.236646 -197.354444)
		(end 421.759888 -197.15607)
		(width 0.18288)
		(layer "In6.Cu")
		(net "M_G_CPU0_SB_DQS_DP<8>")
	)
	(segment
		(start 435.37251 -198.87057)
		(end 432.440588 -198.87057)
		(width 0.18288)
		(layer "In6.Cu")
		(net "M_G_CPU0_SB_DQS_DP<8>")
	)
	(segment
		(start 389.560054 -215.810084)
		(end 389.346694 -216.023444)
		(width 0.088646)
		(layer "In6.Cu")
		(net "M_G_CPU0_SB_DQS_DP<8>")
	)
	(segment
		(start 408.990038 -197.415658)
		(end 408.01671 -197.820026)
		(width 0.18288)
		(layer "In6.Cu")
		(net "M_G_CPU0_SB_DQS_DP<8>")
	)
	(segment
		(start 408.01671 -197.820026)
		(end 405.653748 -197.820026)
		(width 0.18288)
		(layer "In6.Cu")
		(net "M_G_CPU0_SB_DQS_DP<8>")
	)
	(segment
		(start 424.655488 -197.742556)
		(end 424.369738 -198.028306)
		(width 0.18288)
		(layer "In6.Cu")
		(net "M_G_CPU0_SB_DQS_DP<8>")
	)
	(segment
		(start 426.626782 -198.648828)
		(end 426.412152 -198.55942)
		(width 0.18288)
		(layer "In6.Cu")
		(net "M_G_CPU0_SB_DQS_DP<8>")
	)
	(segment
		(start 386.566664 -217.380058)
		(end 386.551932 -217.388694)
		(width 0.088646)
		(layer "In6.Cu")
		(net "M_G_CPU0_SB_DQS_DP<8>")
	)
	(segment
		(start 426.412152 -198.55942)
		(end 426.047154 -198.194168)
		(width 0.18288)
		(layer "In6.Cu")
		(net "M_G_CPU0_SB_DQS_DP<8>")
	)
	(segment
		(start 385.26847 -217.335354)
		(end 385.424934 -217.064336)
		(width 0.088646)
		(layer "In6.Cu")
		(net "M_G_CPU0_SB_DQS_DP<8>")
	)
	(segment
		(start 413.17164 -197.809866)
		(end 412.349442 -197.415658)
		(width 0.18288)
		(layer "In6.Cu")
		(net "M_G_CPU0_SB_DQS_DP<8>")
	)
	(segment
		(start 396.325344 -207.14843)
		(end 396.325344 -208.960466)
		(width 0.18288)
		(layer "In6.Cu")
		(net "M_G_CPU0_SB_DQS_DP<8>")
	)
	(segment
		(start 430.851564 -198.211948)
		(end 428.0154 -198.211948)
		(width 0.18288)
		(layer "In6.Cu")
		(net "M_G_CPU0_SB_DQS_DP<8>")
	)
	(segment
		(start 389.560054 -215.725756)
		(end 389.560054 -215.810084)
		(width 0.088646)
		(layer "In6.Cu")
		(net "M_G_CPU0_SB_DQS_DP<8>")
	)
	(segment
		(start 425.630594 -198.020686)
		(end 425.312586 -198.020686)
		(width 0.18288)
		(layer "In6.Cu")
		(net "M_G_CPU0_SB_DQS_DP<8>")
	)
	(segment
		(start 385.289552 -217.413332)
		(end 385.26847 -217.335354)
		(width 0.088646)
		(layer "In6.Cu")
		(net "M_G_CPU0_SB_DQS_DP<8>")
	)
	(segment
		(start 420.261796 -197.164198)
		(end 417.21786 -197.164198)
		(width 0.18288)
		(layer "In6.Cu")
		(net "M_G_CPU0_SB_DQS_DP<8>")
	)
	(segment
		(start 427.51248 -198.53402)
		(end 427.235874 -198.648828)
		(width 0.18288)
		(layer "In6.Cu")
		(net "M_G_CPU0_SB_DQS_DP<8>")
	)
	(segment
		(start 386.177536 -217.388694)
		(end 386.162804 -217.380058)
		(width 0.088646)
		(layer "In6.Cu")
		(net "M_G_CPU0_SB_DQS_DP<8>")
	)
	(segment
		(start 388.900924 -217.313002)
		(end 388.71398 -217.313002)
		(width 0.088646)
		(layer "In6.Cu")
		(net "M_G_CPU0_SB_DQS_DP<8>")
	)
	(segment
		(start 422.546018 -197.663562)
		(end 422.391332 -197.50913)
		(width 0.18288)
		(layer "In6.Cu")
		(net "M_G_CPU0_SB_DQS_DP<8>")
	)
	(segment
		(start 432.440588 -198.87057)
		(end 430.851564 -198.211948)
		(width 0.18288)
		(layer "In6.Cu")
		(net "M_G_CPU0_SB_DQS_DP<8>")
	)
	(segment
		(start 425.034456 -197.742556)
		(end 424.655488 -197.742556)
		(width 0.18288)
		(layer "In6.Cu")
		(net "M_G_CPU0_SB_DQS_DP<8>")
	)
	(segment
		(start 438.374282 -199.492362)
		(end 438.067958 -199.492362)
		(width 0.18288)
		(layer "In6.Cu")
		(net "M_G_CPU0_SB_DQS_DP<8>")
	)
	(segment
		(start 439.316876 -199.30491)
		(end 438.374282 -199.492362)
		(width 0.18288)
		(layer "In6.Cu")
		(net "M_G_CPU0_SB_DQS_DP<8>")
	)
	(segment
		(start 439.923682 -199.01662)
		(end 439.635392 -199.30491)
		(width 0.18288)
		(layer "In6.Cu")
		(net "M_G_CPU0_SB_DQS_DP<8>")
	)
	(segment
		(start 412.349442 -197.415658)
		(end 408.990038 -197.415658)
		(width 0.18288)
		(layer "In6.Cu")
		(net "M_G_CPU0_SB_DQS_DP<8>")
	)
	(segment
		(start 425.312586 -198.020686)
		(end 425.034456 -197.742556)
		(width 0.18288)
		(layer "In6.Cu")
		(net "M_G_CPU0_SB_DQS_DP<8>")
	)
	(segment
		(start 427.235874 -198.648828)
		(end 426.626782 -198.648828)
		(width 0.18288)
		(layer "In6.Cu")
		(net "M_G_CPU0_SB_DQS_DP<8>")
	)
	(segment
		(start 436.010812 -198.59244)
		(end 435.65064 -198.59244)
		(width 0.18288)
		(layer "In6.Cu")
		(net "M_G_CPU0_SB_DQS_DP<8>")
	)
	(segment
		(start 420.533576 -196.892418)
		(end 420.261796 -197.164198)
		(width 0.18288)
		(layer "In6.Cu")
		(net "M_G_CPU0_SB_DQS_DP<8>")
	)
	(segment
		(start 421.187372 -197.15607)
		(end 420.92372 -196.892418)
		(width 0.18288)
		(layer "In6.Cu")
		(net "M_G_CPU0_SB_DQS_DP<8>")
	)
	(segment
		(start 421.759888 -197.15607)
		(end 421.187372 -197.15607)
		(width 0.18288)
		(layer "In6.Cu")
		(net "M_G_CPU0_SB_DQS_DP<8>")
	)
	(segment
		(start 389.346694 -216.023444)
		(end 389.346694 -216.867232)
		(width 0.088646)
		(layer "In6.Cu")
		(net "M_G_CPU0_SB_DQS_DP<8>")
	)
	(arc
		(start 388.057136 -217.388694)
		(mid 387.782907 -217.312769)
		(end 387.506464 -217.380058)
		(width 0.088646)
		(layer "In6.Cu")
		(net "M_G_CPU0_SB_DQS_DP<8>")
	)
	(arc
		(start 386.551932 -217.388694)
		(mid 386.364734 -217.438837)
		(end 386.177536 -217.388694)
		(width 0.088646)
		(layer "In6.Cu")
		(net "M_G_CPU0_SB_DQS_DP<8>")
	)
	(arc
		(start 388.71398 -217.313002)
		(mid 388.567788 -217.332297)
		(end 388.431532 -217.388694)
		(width 0.088646)
		(layer "In6.Cu")
		(net "M_G_CPU0_SB_DQS_DP<8>")
	)
	(arc
		(start 387.117336 -217.388694)
		(mid 386.843107 -217.312769)
		(end 386.566664 -217.380058)
		(width 0.088646)
		(layer "In6.Cu")
		(net "M_G_CPU0_SB_DQS_DP<8>")
	)
	(arc
		(start 385.612132 -217.388694)
		(mid 385.453644 -217.437627)
		(end 385.289552 -217.413332)
		(width 0.088646)
		(layer "In6.Cu")
		(net "M_G_CPU0_SB_DQS_DP<8>")
	)
	(arc
		(start 388.431532 -217.388694)
		(mid 388.244334 -217.438837)
		(end 388.057136 -217.388694)
		(width 0.088646)
		(layer "In6.Cu")
		(net "M_G_CPU0_SB_DQS_DP<8>")
	)
	(arc
		(start 386.162804 -217.380058)
		(mid 385.886363 -217.312892)
		(end 385.612132 -217.388694)
		(width 0.088646)
		(layer "In6.Cu")
		(net "M_G_CPU0_SB_DQS_DP<8>")
	)
	(arc
		(start 387.491732 -217.388694)
		(mid 387.304534 -217.438837)
		(end 387.117336 -217.388694)
		(width 0.088646)
		(layer "In6.Cu")
		(net "M_G_CPU0_SB_DQS_DP<8>")
	)
	(segment
		(start 442.177932 -208.61782)
		(end 442.602874 -208.192878)
		(width 0.20066)
		(layer "F.Cu")
		(net "M_G_CPU0_SB_DQS_DP<7>")
	)
	(segment
		(start 446.713102 -208.189322)
		(end 447.158618 -208.634838)
		(width 0.20066)
		(layer "F.Cu")
		(net "M_G_CPU0_SB_DQS_DP<7>")
	)
	(segment
		(start 443.450726 -207.93456)
		(end 443.455552 -207.93456)
		(width 0.101854)
		(layer "F.Cu")
		(net "M_G_CPU0_SB_DQS_DP<7>")
	)
	(segment
		(start 445.47536 -207.941672)
		(end 445.482726 -207.934306)
		(width 0.1016)
		(layer "F.Cu")
		(net "M_G_CPU0_SB_DQS_DP<7>")
	)
	(segment
		(start 443.462664 -207.941672)
		(end 445.47536 -207.941672)
		(width 0.1016)
		(layer "F.Cu")
		(net "M_G_CPU0_SB_DQS_DP<7>")
	)
	(segment
		(start 448.004438 -208.366614)
		(end 448.572382 -208.366614)
		(width 0.20066)
		(layer "F.Cu")
		(net "M_G_CPU0_SB_DQS_DP<7>")
	)
	(segment
		(start 443.455552 -207.93456)
		(end 443.462664 -207.941672)
		(width 0.1016)
		(layer "F.Cu")
		(net "M_G_CPU0_SB_DQS_DP<7>")
	)
	(segment
		(start 442.881258 -208.192878)
		(end 443.139576 -207.93456)
		(width 0.20066)
		(layer "F.Cu")
		(net "M_G_CPU0_SB_DQS_DP<7>")
	)
	(segment
		(start 441.028582 -208.366614)
		(end 441.621926 -208.366614)
		(width 0.20066)
		(layer "F.Cu")
		(net "M_G_CPU0_SB_DQS_DP<7>")
	)
	(segment
		(start 445.482726 -207.934306)
		(end 445.804544 -207.934306)
		(width 0.20066)
		(layer "F.Cu")
		(net "M_G_CPU0_SB_DQS_DP<7>")
	)
	(segment
		(start 447.736214 -208.634838)
		(end 448.004438 -208.366614)
		(width 0.20066)
		(layer "F.Cu")
		(net "M_G_CPU0_SB_DQS_DP<7>")
	)
	(segment
		(start 379.31598 -233.064304)
		(end 379.31598 -232.528618)
		(width 0.20066)
		(layer "F.Cu")
		(net "M_G_CPU0_SB_DQS_DP<7>")
	)
	(segment
		(start 441.621926 -208.366614)
		(end 441.873132 -208.61782)
		(width 0.20066)
		(layer "F.Cu")
		(net "M_G_CPU0_SB_DQS_DP<7>")
	)
	(segment
		(start 445.804544 -207.934306)
		(end 446.05956 -208.189322)
		(width 0.20066)
		(layer "F.Cu")
		(net "M_G_CPU0_SB_DQS_DP<7>")
	)
	(segment
		(start 446.05956 -208.189322)
		(end 446.713102 -208.189322)
		(width 0.20066)
		(layer "F.Cu")
		(net "M_G_CPU0_SB_DQS_DP<7>")
	)
	(segment
		(start 447.158618 -208.634838)
		(end 447.736214 -208.634838)
		(width 0.20066)
		(layer "F.Cu")
		(net "M_G_CPU0_SB_DQS_DP<7>")
	)
	(segment
		(start 443.139576 -207.93456)
		(end 443.450726 -207.93456)
		(width 0.20066)
		(layer "F.Cu")
		(net "M_G_CPU0_SB_DQS_DP<7>")
	)
	(segment
		(start 439.923682 -208.366614)
		(end 441.028582 -208.366614)
		(width 0.20066)
		(layer "F.Cu")
		(net "M_G_CPU0_SB_DQS_DP<7>")
	)
	(segment
		(start 441.873132 -208.61782)
		(end 442.177932 -208.61782)
		(width 0.20066)
		(layer "F.Cu")
		(net "M_G_CPU0_SB_DQS_DP<7>")
	)
	(segment
		(start 442.602874 -208.192878)
		(end 442.881258 -208.192878)
		(width 0.20066)
		(layer "F.Cu")
		(net "M_G_CPU0_SB_DQS_DP<7>")
	)
	(segment
		(start 379.31598 -232.528618)
		(end 379.316234 -232.528364)
		(width 0.20066)
		(layer "F.Cu")
		(net "M_G_CPU0_SB_DQS_DP<7>")
	)
	(segment
		(start 438.493662 -208.20888)
		(end 438.227216 -207.942434)
		(width 0.18288)
		(layer "In4.Cu")
		(net "M_G_CPU0_SB_DQS_DP<7>")
	)
	(segment
		(start 434.373782 -207.946244)
		(end 432.603402 -207.946244)
		(width 0.18288)
		(layer "In4.Cu")
		(net "M_G_CPU0_SB_DQS_DP<7>")
	)
	(segment
		(start 435.61254 -207.942434)
		(end 435.362604 -208.19237)
		(width 0.18288)
		(layer "In4.Cu")
		(net "M_G_CPU0_SB_DQS_DP<7>")
	)
	(segment
		(start 420.275004 -210.74253)
		(end 419.310566 -210.74253)
		(width 0.18288)
		(layer "In4.Cu")
		(net "M_G_CPU0_SB_DQS_DP<7>")
	)
	(segment
		(start 384.681222 -232.033826)
		(end 384.672332 -232.038906)
		(width 0.088646)
		(layer "In4.Cu")
		(net "M_G_CPU0_SB_DQS_DP<7>")
	)
	(segment
		(start 385.799584 -230.076756)
		(end 385.799584 -230.086662)
		(width 0.088646)
		(layer "In4.Cu")
		(net "M_G_CPU0_SB_DQS_DP<7>")
	)
	(segment
		(start 380.802388 -232.102914)
		(end 380.698756 -232.130854)
		(width 0.088646)
		(layer "In4.Cu")
		(net "M_G_CPU0_SB_DQS_DP<7>")
	)
	(segment
		(start 386.55244 -228.783388)
		(end 386.538978 -228.791262)
		(width 0.088646)
		(layer "In4.Cu")
		(net "M_G_CPU0_SB_DQS_DP<7>")
	)
	(segment
		(start 424.625008 -211.342478)
		(end 424.39971 -211.567776)
		(width 0.18288)
		(layer "In4.Cu")
		(net "M_G_CPU0_SB_DQS_DP<7>")
	)
	(segment
		(start 439.280554 -208.5467)
		(end 438.942734 -208.20888)
		(width 0.18288)
		(layer "In4.Cu")
		(net "M_G_CPU0_SB_DQS_DP<7>")
	)
	(segment
		(start 438.942734 -208.20888)
		(end 438.493662 -208.20888)
		(width 0.18288)
		(layer "In4.Cu")
		(net "M_G_CPU0_SB_DQS_DP<7>")
	)
	(segment
		(start 409.10764 -211.012786)
		(end 408.694636 -211.42579)
		(width 0.18288)
		(layer "In4.Cu")
		(net "M_G_CPU0_SB_DQS_DP<7>")
	)
	(segment
		(start 380.893828 -232.050336)
		(end 380.802388 -232.102914)
		(width 0.088646)
		(layer "In4.Cu")
		(net "M_G_CPU0_SB_DQS_DP<7>")
	)
	(segment
		(start 439.469276 -208.62544)
		(end 439.280554 -208.5467)
		(width 0.18288)
		(layer "In4.Cu")
		(net "M_G_CPU0_SB_DQS_DP<7>")
	)
	(segment
		(start 416.13963 -211.406486)
		(end 412.674054 -211.406486)
		(width 0.18288)
		(layer "In4.Cu")
		(net "M_G_CPU0_SB_DQS_DP<7>")
	)
	(segment
		(start 412.280354 -211.012786)
		(end 409.10764 -211.012786)
		(width 0.18288)
		(layer "In4.Cu")
		(net "M_G_CPU0_SB_DQS_DP<7>")
	)
	(segment
		(start 388.348728 -226.743514)
		(end 386.739892 -228.35235)
		(width 0.088646)
		(layer "In4.Cu")
		(net "M_G_CPU0_SB_DQS_DP<7>")
	)
	(segment
		(start 384.859784 -231.696006)
		(end 384.859784 -231.714548)
		(width 0.088646)
		(layer "In4.Cu")
		(net "M_G_CPU0_SB_DQS_DP<7>")
	)
	(segment
		(start 437.58231 -208.182464)
		(end 436.257446 -208.182464)
		(width 0.18288)
		(layer "In4.Cu")
		(net "M_G_CPU0_SB_DQS_DP<7>")
	)
	(segment
		(start 419.10635 -210.946746)
		(end 416.59937 -210.946746)
		(width 0.18288)
		(layer "In4.Cu")
		(net "M_G_CPU0_SB_DQS_DP<7>")
	)
	(segment
		(start 421.188388 -210.751166)
		(end 420.929816 -210.492594)
		(width 0.18288)
		(layer "In4.Cu")
		(net "M_G_CPU0_SB_DQS_DP<7>")
	)
	(segment
		(start 438.227216 -207.942434)
		(end 437.82234 -207.942434)
		(width 0.18288)
		(layer "In4.Cu")
		(net "M_G_CPU0_SB_DQS_DP<7>")
	)
	(segment
		(start 379.321568 -232.533698)
		(end 379.316234 -232.528364)
		(width 0.088646)
		(layer "In4.Cu")
		(net "M_G_CPU0_SB_DQS_DP<7>")
	)
	(segment
		(start 434.968142 -208.19237)
		(end 434.373782 -207.946244)
		(width 0.18288)
		(layer "In4.Cu")
		(net "M_G_CPU0_SB_DQS_DP<7>")
	)
	(segment
		(start 426.117512 -211.60105)
		(end 425.288456 -211.60105)
		(width 0.18288)
		(layer "In4.Cu")
		(net "M_G_CPU0_SB_DQS_DP<7>")
	)
	(segment
		(start 386.090922 -229.592124)
		(end 386.082032 -229.597204)
		(width 0.088646)
		(layer "In4.Cu")
		(net "M_G_CPU0_SB_DQS_DP<7>")
	)
	(segment
		(start 427.602396 -210.116166)
		(end 426.117512 -211.60105)
		(width 0.18288)
		(layer "In4.Cu")
		(net "M_G_CPU0_SB_DQS_DP<7>")
	)
	(segment
		(start 424.39971 -211.567776)
		(end 422.9608 -211.567776)
		(width 0.18288)
		(layer "In4.Cu")
		(net "M_G_CPU0_SB_DQS_DP<7>")
	)
	(segment
		(start 380.912878 -232.038906)
		(end 380.911862 -232.039414)
		(width 0.088646)
		(layer "In4.Cu")
		(net "M_G_CPU0_SB_DQS_DP<7>")
	)
	(segment
		(start 390.546336 -226.683824)
		(end 388.71271 -226.683824)
		(width 0.18288)
		(layer "In4.Cu")
		(net "M_G_CPU0_SB_DQS_DP<7>")
	)
	(segment
		(start 380.923292 -232.03281)
		(end 380.912878 -232.038906)
		(width 0.088646)
		(layer "In4.Cu")
		(net "M_G_CPU0_SB_DQS_DP<7>")
	)
	(segment
		(start 412.674054 -211.406486)
		(end 412.280354 -211.012786)
		(width 0.18288)
		(layer "In4.Cu")
		(net "M_G_CPU0_SB_DQS_DP<7>")
	)
	(segment
		(start 422.9608 -211.567776)
		(end 422.14419 -210.751166)
		(width 0.18288)
		(layer "In4.Cu")
		(net "M_G_CPU0_SB_DQS_DP<7>")
	)
	(segment
		(start 386.26923 -229.26294)
		(end 386.269484 -229.272846)
		(width 0.088646)
		(layer "In4.Cu")
		(net "M_G_CPU0_SB_DQS_DP<7>")
	)
	(segment
		(start 425.288456 -211.60105)
		(end 425.029884 -211.342478)
		(width 0.18288)
		(layer "In4.Cu")
		(net "M_G_CPU0_SB_DQS_DP<7>")
	)
	(segment
		(start 432.603402 -207.946244)
		(end 430.52365 -210.025996)
		(width 0.18288)
		(layer "In4.Cu")
		(net "M_G_CPU0_SB_DQS_DP<7>")
	)
	(segment
		(start 430.52365 -210.025996)
		(end 430.30648 -210.116166)
		(width 0.18288)
		(layer "In4.Cu")
		(net "M_G_CPU0_SB_DQS_DP<7>")
	)
	(segment
		(start 425.029884 -211.342478)
		(end 424.625008 -211.342478)
		(width 0.18288)
		(layer "In4.Cu")
		(net "M_G_CPU0_SB_DQS_DP<7>")
	)
	(segment
		(start 385.151122 -231.219756)
		(end 385.142232 -231.224836)
		(width 0.088646)
		(layer "In4.Cu")
		(net "M_G_CPU0_SB_DQS_DP<7>")
	)
	(segment
		(start 420.929816 -210.492594)
		(end 420.52494 -210.492594)
		(width 0.18288)
		(layer "In4.Cu")
		(net "M_G_CPU0_SB_DQS_DP<7>")
	)
	(segment
		(start 379.885956 -232.47096)
		(end 379.823218 -232.533698)
		(width 0.088646)
		(layer "In4.Cu")
		(net "M_G_CPU0_SB_DQS_DP<7>")
	)
	(segment
		(start 439.639456 -208.62544)
		(end 439.469276 -208.62544)
		(width 0.18288)
		(layer "In4.Cu")
		(net "M_G_CPU0_SB_DQS_DP<7>")
	)
	(segment
		(start 420.52494 -210.492594)
		(end 420.275004 -210.74253)
		(width 0.18288)
		(layer "In4.Cu")
		(net "M_G_CPU0_SB_DQS_DP<7>")
	)
	(segment
		(start 436.017416 -207.942434)
		(end 435.61254 -207.942434)
		(width 0.18288)
		(layer "In4.Cu")
		(net "M_G_CPU0_SB_DQS_DP<7>")
	)
	(segment
		(start 439.923682 -208.366614)
		(end 439.898282 -208.366614)
		(width 0.18288)
		(layer "In4.Cu")
		(net "M_G_CPU0_SB_DQS_DP<7>")
	)
	(segment
		(start 422.14419 -210.751166)
		(end 421.188388 -210.751166)
		(width 0.18288)
		(layer "In4.Cu")
		(net "M_G_CPU0_SB_DQS_DP<7>")
	)
	(segment
		(start 386.538978 -228.791262)
		(end 386.538724 -228.790754)
		(width 0.088646)
		(layer "In4.Cu")
		(net "M_G_CPU0_SB_DQS_DP<7>")
	)
	(segment
		(start 388.71271 -226.683824)
		(end 388.689342 -226.683824)
		(width 0.088646)
		(layer "In4.Cu")
		(net "M_G_CPU0_SB_DQS_DP<7>")
	)
	(segment
		(start 385.329684 -230.890572)
		(end 385.329684 -230.900478)
		(width 0.088646)
		(layer "In4.Cu")
		(net "M_G_CPU0_SB_DQS_DP<7>")
	)
	(segment
		(start 385.621022 -230.40594)
		(end 385.612132 -230.41102)
		(width 0.088646)
		(layer "In4.Cu")
		(net "M_G_CPU0_SB_DQS_DP<7>")
	)
	(segment
		(start 439.898282 -208.366614)
		(end 439.639456 -208.62544)
		(width 0.18288)
		(layer "In4.Cu")
		(net "M_G_CPU0_SB_DQS_DP<7>")
	)
	(segment
		(start 436.257446 -208.182464)
		(end 436.017416 -207.942434)
		(width 0.18288)
		(layer "In4.Cu")
		(net "M_G_CPU0_SB_DQS_DP<7>")
	)
	(segment
		(start 419.310566 -210.74253)
		(end 419.10635 -210.946746)
		(width 0.18288)
		(layer "In4.Cu")
		(net "M_G_CPU0_SB_DQS_DP<7>")
	)
	(segment
		(start 388.689342 -226.683824)
		(end 388.629652 -226.743514)
		(width 0.088646)
		(layer "In4.Cu")
		(net "M_G_CPU0_SB_DQS_DP<7>")
	)
	(segment
		(start 408.694636 -211.42579)
		(end 405.80437 -211.42579)
		(width 0.18288)
		(layer "In4.Cu")
		(net "M_G_CPU0_SB_DQS_DP<7>")
	)
	(segment
		(start 405.80437 -211.42579)
		(end 390.546336 -226.683824)
		(width 0.18288)
		(layer "In4.Cu")
		(net "M_G_CPU0_SB_DQS_DP<7>")
	)
	(segment
		(start 430.30648 -210.116166)
		(end 427.602396 -210.116166)
		(width 0.18288)
		(layer "In4.Cu")
		(net "M_G_CPU0_SB_DQS_DP<7>")
	)
	(segment
		(start 386.739892 -228.35235)
		(end 386.739892 -228.466396)
		(width 0.088646)
		(layer "In4.Cu")
		(net "M_G_CPU0_SB_DQS_DP<7>")
	)
	(segment
		(start 435.362604 -208.19237)
		(end 434.968142 -208.19237)
		(width 0.18288)
		(layer "In4.Cu")
		(net "M_G_CPU0_SB_DQS_DP<7>")
	)
	(segment
		(start 416.59937 -210.946746)
		(end 416.13963 -211.406486)
		(width 0.18288)
		(layer "In4.Cu")
		(net "M_G_CPU0_SB_DQS_DP<7>")
	)
	(segment
		(start 380.698756 -232.130854)
		(end 380.26213 -232.130854)
		(width 0.088646)
		(layer "In4.Cu")
		(net "M_G_CPU0_SB_DQS_DP<7>")
	)
	(segment
		(start 379.823218 -232.533698)
		(end 379.321568 -232.533698)
		(width 0.088646)
		(layer "In4.Cu")
		(net "M_G_CPU0_SB_DQS_DP<7>")
	)
	(segment
		(start 380.911862 -232.039414)
		(end 380.893828 -232.050336)
		(width 0.088646)
		(layer "In4.Cu")
		(net "M_G_CPU0_SB_DQS_DP<7>")
	)
	(segment
		(start 388.629652 -226.743514)
		(end 388.348728 -226.743514)
		(width 0.088646)
		(layer "In4.Cu")
		(net "M_G_CPU0_SB_DQS_DP<7>")
	)
	(segment
		(start 437.82234 -207.942434)
		(end 437.58231 -208.182464)
		(width 0.18288)
		(layer "In4.Cu")
		(net "M_G_CPU0_SB_DQS_DP<7>")
	)
	(arc
		(start 382.792732 -232.038906)
		(mid 382.605534 -232.089049)
		(end 382.418336 -232.038906)
		(width 0.088646)
		(layer "In4.Cu")
		(net "M_G_CPU0_SB_DQS_DP<7>")
	)
	(arc
		(start 385.799584 -230.086662)
		(mid 385.751905 -230.269562)
		(end 385.621022 -230.40594)
		(width 0.088646)
		(layer "In4.Cu")
		(net "M_G_CPU0_SB_DQS_DP<7>")
	)
	(arc
		(start 386.739892 -228.466396)
		(mid 386.687725 -228.649456)
		(end 386.55244 -228.783388)
		(width 0.088646)
		(layer "In4.Cu")
		(net "M_G_CPU0_SB_DQS_DP<7>")
	)
	(arc
		(start 383.358136 -232.038906)
		(mid 383.075434 -231.96313)
		(end 382.792732 -232.038906)
		(width 0.088646)
		(layer "In4.Cu")
		(net "M_G_CPU0_SB_DQS_DP<7>")
	)
	(arc
		(start 385.329684 -230.900478)
		(mid 385.282005 -231.083378)
		(end 385.151122 -231.219756)
		(width 0.088646)
		(layer "In4.Cu")
		(net "M_G_CPU0_SB_DQS_DP<7>")
	)
	(arc
		(start 380.170182 -232.154984)
		(mid 380.14496 -232.168204)
		(end 380.118874 -232.179622)
		(width 0.088646)
		(layer "In4.Cu")
		(net "M_G_CPU0_SB_DQS_DP<7>")
	)
	(arc
		(start 386.269484 -229.272846)
		(mid 386.221805 -229.455746)
		(end 386.090922 -229.592124)
		(width 0.088646)
		(layer "In4.Cu")
		(net "M_G_CPU0_SB_DQS_DP<7>")
	)
	(arc
		(start 384.672332 -232.038906)
		(mid 384.485134 -232.089049)
		(end 384.297936 -232.038906)
		(width 0.088646)
		(layer "In4.Cu")
		(net "M_G_CPU0_SB_DQS_DP<7>")
	)
	(arc
		(start 385.142232 -231.224836)
		(mid 384.939946 -231.423817)
		(end 384.859784 -231.696006)
		(width 0.088646)
		(layer "In4.Cu")
		(net "M_G_CPU0_SB_DQS_DP<7>")
	)
	(arc
		(start 380.26213 -232.130854)
		(mid 380.2146 -232.136988)
		(end 380.170182 -232.154984)
		(width 0.088646)
		(layer "In4.Cu")
		(net "M_G_CPU0_SB_DQS_DP<7>")
	)
	(arc
		(start 386.538724 -228.790754)
		(mid 386.343524 -228.992339)
		(end 386.26923 -229.26294)
		(width 0.088646)
		(layer "In4.Cu")
		(net "M_G_CPU0_SB_DQS_DP<7>")
	)
	(arc
		(start 380.118874 -232.179622)
		(mid 379.963541 -232.29422)
		(end 379.885956 -232.47096)
		(width 0.088646)
		(layer "In4.Cu")
		(net "M_G_CPU0_SB_DQS_DP<7>")
	)
	(arc
		(start 382.418336 -232.038906)
		(mid 382.135634 -231.96313)
		(end 381.852932 -232.038906)
		(width 0.088646)
		(layer "In4.Cu")
		(net "M_G_CPU0_SB_DQS_DP<7>")
	)
	(arc
		(start 381.478536 -232.038906)
		(mid 381.201723 -231.963036)
		(end 380.923292 -232.03281)
		(width 0.088646)
		(layer "In4.Cu")
		(net "M_G_CPU0_SB_DQS_DP<7>")
	)
	(arc
		(start 381.852932 -232.038906)
		(mid 381.665734 -232.089049)
		(end 381.478536 -232.038906)
		(width 0.088646)
		(layer "In4.Cu")
		(net "M_G_CPU0_SB_DQS_DP<7>")
	)
	(arc
		(start 384.859784 -231.714548)
		(mid 384.812105 -231.897448)
		(end 384.681222 -232.033826)
		(width 0.088646)
		(layer "In4.Cu")
		(net "M_G_CPU0_SB_DQS_DP<7>")
	)
	(arc
		(start 385.612132 -230.41102)
		(mid 385.407797 -230.613625)
		(end 385.329684 -230.890572)
		(width 0.088646)
		(layer "In4.Cu")
		(net "M_G_CPU0_SB_DQS_DP<7>")
	)
	(arc
		(start 386.082032 -229.597204)
		(mid 385.877697 -229.799809)
		(end 385.799584 -230.076756)
		(width 0.088646)
		(layer "In4.Cu")
		(net "M_G_CPU0_SB_DQS_DP<7>")
	)
	(arc
		(start 384.297936 -232.038906)
		(mid 384.015234 -231.96313)
		(end 383.732532 -232.038906)
		(width 0.088646)
		(layer "In4.Cu")
		(net "M_G_CPU0_SB_DQS_DP<7>")
	)
	(arc
		(start 383.732532 -232.038906)
		(mid 383.545334 -232.089049)
		(end 383.358136 -232.038906)
		(width 0.088646)
		(layer "In4.Cu")
		(net "M_G_CPU0_SB_DQS_DP<7>")
	)
	(segment
		(start 447.736214 -217.984832)
		(end 448.004438 -217.716608)
		(width 0.20066)
		(layer "F.Cu")
		(net "M_G_CPU0_SB_DQS_DP<6>")
	)
	(segment
		(start 445.47536 -217.291666)
		(end 445.482726 -217.2843)
		(width 0.1016)
		(layer "F.Cu")
		(net "M_G_CPU0_SB_DQS_DP<6>")
	)
	(segment
		(start 442.881258 -217.542872)
		(end 443.139576 -217.284554)
		(width 0.20066)
		(layer "F.Cu")
		(net "M_G_CPU0_SB_DQS_DP<6>")
	)
	(segment
		(start 443.139576 -217.284554)
		(end 443.450726 -217.284554)
		(width 0.20066)
		(layer "F.Cu")
		(net "M_G_CPU0_SB_DQS_DP<6>")
	)
	(segment
		(start 446.05956 -217.539316)
		(end 446.713102 -217.539316)
		(width 0.20066)
		(layer "F.Cu")
		(net "M_G_CPU0_SB_DQS_DP<6>")
	)
	(segment
		(start 445.804544 -217.2843)
		(end 446.05956 -217.539316)
		(width 0.20066)
		(layer "F.Cu")
		(net "M_G_CPU0_SB_DQS_DP<6>")
	)
	(segment
		(start 439.923682 -217.716608)
		(end 441.028582 -217.716608)
		(width 0.20066)
		(layer "F.Cu")
		(net "M_G_CPU0_SB_DQS_DP<6>")
	)
	(segment
		(start 446.713102 -217.539316)
		(end 447.158618 -217.984832)
		(width 0.20066)
		(layer "F.Cu")
		(net "M_G_CPU0_SB_DQS_DP<6>")
	)
	(segment
		(start 441.028582 -217.716608)
		(end 441.621926 -217.716608)
		(width 0.20066)
		(layer "F.Cu")
		(net "M_G_CPU0_SB_DQS_DP<6>")
	)
	(segment
		(start 442.602874 -217.542872)
		(end 442.881258 -217.542872)
		(width 0.20066)
		(layer "F.Cu")
		(net "M_G_CPU0_SB_DQS_DP<6>")
	)
	(segment
		(start 443.450726 -217.284554)
		(end 443.455552 -217.284554)
		(width 0.101854)
		(layer "F.Cu")
		(net "M_G_CPU0_SB_DQS_DP<6>")
	)
	(segment
		(start 376.96648 -235.505752)
		(end 376.96648 -234.970066)
		(width 0.20066)
		(layer "F.Cu")
		(net "M_G_CPU0_SB_DQS_DP<6>")
	)
	(segment
		(start 448.004438 -217.716608)
		(end 448.572382 -217.716608)
		(width 0.20066)
		(layer "F.Cu")
		(net "M_G_CPU0_SB_DQS_DP<6>")
	)
	(segment
		(start 376.966734 -235.506006)
		(end 376.96648 -235.505752)
		(width 0.20066)
		(layer "F.Cu")
		(net "M_G_CPU0_SB_DQS_DP<6>")
	)
	(segment
		(start 442.177932 -217.967814)
		(end 442.602874 -217.542872)
		(width 0.20066)
		(layer "F.Cu")
		(net "M_G_CPU0_SB_DQS_DP<6>")
	)
	(segment
		(start 443.455552 -217.284554)
		(end 443.462664 -217.291666)
		(width 0.1016)
		(layer "F.Cu")
		(net "M_G_CPU0_SB_DQS_DP<6>")
	)
	(segment
		(start 443.462664 -217.291666)
		(end 445.47536 -217.291666)
		(width 0.1016)
		(layer "F.Cu")
		(net "M_G_CPU0_SB_DQS_DP<6>")
	)
	(segment
		(start 441.873132 -217.967814)
		(end 442.177932 -217.967814)
		(width 0.20066)
		(layer "F.Cu")
		(net "M_G_CPU0_SB_DQS_DP<6>")
	)
	(segment
		(start 447.158618 -217.984832)
		(end 447.736214 -217.984832)
		(width 0.20066)
		(layer "F.Cu")
		(net "M_G_CPU0_SB_DQS_DP<6>")
	)
	(segment
		(start 441.621926 -217.716608)
		(end 441.873132 -217.967814)
		(width 0.20066)
		(layer "F.Cu")
		(net "M_G_CPU0_SB_DQS_DP<6>")
	)
	(segment
		(start 445.482726 -217.2843)
		(end 445.804544 -217.2843)
		(width 0.20066)
		(layer "F.Cu")
		(net "M_G_CPU0_SB_DQS_DP<6>")
	)
	(segment
		(start 379.979174 -235.291122)
		(end 379.96749 -235.297726)
		(width 0.088646)
		(layer "In6.Cu")
		(net "M_G_CPU0_SB_DQS_DP<6>")
	)
	(segment
		(start 386.079746 -234.481878)
		(end 386.077714 -234.483148)
		(width 0.088646)
		(layer "In6.Cu")
		(net "M_G_CPU0_SB_DQS_DP<6>")
	)
	(segment
		(start 425.966382 -222.549466)
		(end 425.697142 -222.661226)
		(width 0.18288)
		(layer "In6.Cu")
		(net "M_G_CPU0_SB_DQS_DP<6>")
	)
	(segment
		(start 427.549818 -221.560644)
		(end 427.084998 -221.753176)
		(width 0.18288)
		(layer "In6.Cu")
		(net "M_G_CPU0_SB_DQS_DP<6>")
	)
	(segment
		(start 405.090376 -221.191582)
		(end 404.965916 -221.067122)
		(width 0.18288)
		(layer "In6.Cu")
		(net "M_G_CPU0_SB_DQS_DP<6>")
	)
	(segment
		(start 386.096764 -234.471972)
		(end 386.082032 -234.480608)
		(width 0.088646)
		(layer "In6.Cu")
		(net "M_G_CPU0_SB_DQS_DP<6>")
	)
	(segment
		(start 387.94944 -233.629962)
		(end 387.88975 -233.689652)
		(width 0.088646)
		(layer "In6.Cu")
		(net "M_G_CPU0_SB_DQS_DP<6>")
	)
	(segment
		(start 425.014136 -222.392494)
		(end 424.662092 -222.392494)
		(width 0.18288)
		(layer "In6.Cu")
		(net "M_G_CPU0_SB_DQS_DP<6>")
	)
	(segment
		(start 418.993066 -223.376998)
		(end 418.868606 -223.501458)
		(width 0.18288)
		(layer "In6.Cu")
		(net "M_G_CPU0_SB_DQS_DP<6>")
	)
	(segment
		(start 416.981386 -223.501458)
		(end 416.86734 -223.454214)
		(width 0.18288)
		(layer "In6.Cu")
		(net "M_G_CPU0_SB_DQS_DP<6>")
	)
	(segment
		(start 421.191944 -223.522794)
		(end 420.911528 -223.242378)
		(width 0.18288)
		(layer "In6.Cu")
		(net "M_G_CPU0_SB_DQS_DP<6>")
	)
	(segment
		(start 432.730402 -219.845382)
		(end 432.002946 -219.845382)
		(width 0.18288)
		(layer "In6.Cu")
		(net "M_G_CPU0_SB_DQS_DP<6>")
	)
	(segment
		(start 402.484844 -222.526098)
		(end 402.308822 -222.526098)
		(width 0.18288)
		(layer "In6.Cu")
		(net "M_G_CPU0_SB_DQS_DP<6>")
	)
	(segment
		(start 419.539166 -223.376998)
		(end 418.993066 -223.376998)
		(width 0.18288)
		(layer "In6.Cu")
		(net "M_G_CPU0_SB_DQS_DP<6>")
	)
	(segment
		(start 403.81936 -221.191582)
		(end 403.43328 -221.577662)
		(width 0.18288)
		(layer "In6.Cu")
		(net "M_G_CPU0_SB_DQS_DP<6>")
	)
	(segment
		(start 401.922488 -223.088454)
		(end 401.536408 -223.474534)
		(width 0.18288)
		(layer "In6.Cu")
		(net "M_G_CPU0_SB_DQS_DP<6>")
	)
	(segment
		(start 408.813508 -221.191582)
		(end 408.207464 -221.191582)
		(width 0.18288)
		(layer "In6.Cu")
		(net "M_G_CPU0_SB_DQS_DP<6>")
	)
	(segment
		(start 400.025616 -224.985326)
		(end 391.38098 -233.629962)
		(width 0.18288)
		(layer "In6.Cu")
		(net "M_G_CPU0_SB_DQS_DP<6>")
	)
	(segment
		(start 406.307036 -221.067122)
		(end 405.760936 -221.067122)
		(width 0.18288)
		(layer "In6.Cu")
		(net "M_G_CPU0_SB_DQS_DP<6>")
	)
	(segment
		(start 379.039374 -235.291122)
		(end 379.02769 -235.297726)
		(width 0.088646)
		(layer "In6.Cu")
		(net "M_G_CPU0_SB_DQS_DP<6>")
	)
	(segment
		(start 407.536904 -221.067122)
		(end 407.412444 -221.191582)
		(width 0.18288)
		(layer "In6.Cu")
		(net "M_G_CPU0_SB_DQS_DP<6>")
	)
	(segment
		(start 438.238392 -218.495372)
		(end 438.06237 -218.495372)
		(width 0.18288)
		(layer "In6.Cu")
		(net "M_G_CPU0_SB_DQS_DP<6>")
	)
	(segment
		(start 405.760936 -221.067122)
		(end 405.636476 -221.191582)
		(width 0.18288)
		(layer "In6.Cu")
		(net "M_G_CPU0_SB_DQS_DP<6>")
	)
	(segment
		(start 415.868358 -222.455232)
		(end 414.979358 -222.455232)
		(width 0.18288)
		(layer "In6.Cu")
		(net "M_G_CPU0_SB_DQS_DP<6>")
	)
	(segment
		(start 418.322506 -223.501458)
		(end 418.198046 -223.376998)
		(width 0.18288)
		(layer "In6.Cu")
		(net "M_G_CPU0_SB_DQS_DP<6>")
	)
	(segment
		(start 431.074068 -220.573092)
		(end 430.741074 -220.711268)
		(width 0.18288)
		(layer "In6.Cu")
		(net "M_G_CPU0_SB_DQS_DP<6>")
	)
	(segment
		(start 378.098558 -235.29163)
		(end 378.097796 -235.292138)
		(width 0.088646)
		(layer "In6.Cu")
		(net "M_G_CPU0_SB_DQS_DP<6>")
	)
	(segment
		(start 402.870924 -222.140018)
		(end 402.484844 -222.526098)
		(width 0.18288)
		(layer "In6.Cu")
		(net "M_G_CPU0_SB_DQS_DP<6>")
	)
	(segment
		(start 377.079256 -235.082842)
		(end 376.96648 -234.970066)
		(width 0.088646)
		(layer "In6.Cu")
		(net "M_G_CPU0_SB_DQS_DP<6>")
	)
	(segment
		(start 386.082032 -234.480608)
		(end 386.079746 -234.481878)
		(width 0.088646)
		(layer "In6.Cu")
		(net "M_G_CPU0_SB_DQS_DP<6>")
	)
	(segment
		(start 427.084998 -221.753176)
		(end 426.53458 -221.981268)
		(width 0.18288)
		(layer "In6.Cu")
		(net "M_G_CPU0_SB_DQS_DP<6>")
	)
	(segment
		(start 419.663626 -223.501458)
		(end 419.539166 -223.376998)
		(width 0.18288)
		(layer "In6.Cu")
		(net "M_G_CPU0_SB_DQS_DP<6>")
	)
	(segment
		(start 424.662092 -222.392494)
		(end 424.382438 -222.672148)
		(width 0.18288)
		(layer "In6.Cu")
		(net "M_G_CPU0_SB_DQS_DP<6>")
	)
	(segment
		(start 417.527486 -223.501458)
		(end 416.981386 -223.501458)
		(width 0.18288)
		(layer "In6.Cu")
		(net "M_G_CPU0_SB_DQS_DP<6>")
	)
	(segment
		(start 436.093108 -219.842588)
		(end 435.56428 -219.842588)
		(width 0.18288)
		(layer "In6.Cu")
		(net "M_G_CPU0_SB_DQS_DP<6>")
	)
	(segment
		(start 422.834816 -222.672148)
		(end 422.296844 -222.894398)
		(width 0.18288)
		(layer "In6.Cu")
		(net "M_G_CPU0_SB_DQS_DP<6>")
	)
	(segment
		(start 437.676036 -219.057728)
		(end 436.724552 -220.009212)
		(width 0.18288)
		(layer "In6.Cu")
		(net "M_G_CPU0_SB_DQS_DP<6>")
	)
	(segment
		(start 425.697142 -222.661226)
		(end 425.282868 -222.661226)
		(width 0.18288)
		(layer "In6.Cu")
		(net "M_G_CPU0_SB_DQS_DP<6>")
	)
	(segment
		(start 406.431496 -221.191582)
		(end 406.307036 -221.067122)
		(width 0.18288)
		(layer "In6.Cu")
		(net "M_G_CPU0_SB_DQS_DP<6>")
	)
	(segment
		(start 432.002946 -219.845382)
		(end 431.659792 -219.987368)
		(width 0.18288)
		(layer "In6.Cu")
		(net "M_G_CPU0_SB_DQS_DP<6>")
	)
	(segment
		(start 385.620768 -235.289344)
		(end 385.611878 -235.294424)
		(width 0.088646)
		(layer "In6.Cu")
		(net "M_G_CPU0_SB_DQS_DP<6>")
	)
	(segment
		(start 438.805828 -218.034362)
		(end 438.624472 -218.109292)
		(width 0.18288)
		(layer "In6.Cu")
		(net "M_G_CPU0_SB_DQS_DP<6>")
	)
	(segment
		(start 408.083004 -221.067122)
		(end 407.536904 -221.067122)
		(width 0.18288)
		(layer "In6.Cu")
		(net "M_G_CPU0_SB_DQS_DP<6>")
	)
	(segment
		(start 378.099574 -235.291122)
		(end 378.098558 -235.29163)
		(width 0.088646)
		(layer "In6.Cu")
		(net "M_G_CPU0_SB_DQS_DP<6>")
	)
	(segment
		(start 421.856662 -223.33458)
		(end 421.40505 -223.522794)
		(width 0.18288)
		(layer "In6.Cu")
		(net "M_G_CPU0_SB_DQS_DP<6>")
	)
	(segment
		(start 410.366464 -221.414086)
		(end 410.242004 -221.538546)
		(width 0.18288)
		(layer "In6.Cu")
		(net "M_G_CPU0_SB_DQS_DP<6>")
	)
	(segment
		(start 402.870924 -221.963996)
		(end 402.870924 -222.140018)
		(width 0.18288)
		(layer "In6.Cu")
		(net "M_G_CPU0_SB_DQS_DP<6>")
	)
	(segment
		(start 391.38098 -233.629962)
		(end 388.001764 -233.629962)
		(width 0.18288)
		(layer "In6.Cu")
		(net "M_G_CPU0_SB_DQS_DP<6>")
	)
	(segment
		(start 417.651946 -223.376998)
		(end 417.527486 -223.501458)
		(width 0.18288)
		(layer "In6.Cu")
		(net "M_G_CPU0_SB_DQS_DP<6>")
	)
	(segment
		(start 436.541926 -220.086174)
		(end 436.336694 -220.086174)
		(width 0.18288)
		(layer "In6.Cu")
		(net "M_G_CPU0_SB_DQS_DP<6>")
	)
	(segment
		(start 403.43328 -221.577662)
		(end 403.257258 -221.577662)
		(width 0.18288)
		(layer "In6.Cu")
		(net "M_G_CPU0_SB_DQS_DP<6>")
	)
	(segment
		(start 416.86734 -223.454214)
		(end 415.868358 -222.455232)
		(width 0.18288)
		(layer "In6.Cu")
		(net "M_G_CPU0_SB_DQS_DP<6>")
	)
	(segment
		(start 401.922488 -222.912432)
		(end 401.922488 -223.088454)
		(width 0.18288)
		(layer "In6.Cu")
		(net "M_G_CPU0_SB_DQS_DP<6>")
	)
	(segment
		(start 413.723074 -221.198948)
		(end 413.012128 -221.198948)
		(width 0.18288)
		(layer "In6.Cu")
		(net "M_G_CPU0_SB_DQS_DP<6>")
	)
	(segment
		(start 402.308822 -222.526098)
		(end 401.922488 -222.912432)
		(width 0.18288)
		(layer "In6.Cu")
		(net "M_G_CPU0_SB_DQS_DP<6>")
	)
	(segment
		(start 401.536408 -223.474534)
		(end 401.360386 -223.474534)
		(width 0.18288)
		(layer "In6.Cu")
		(net "M_G_CPU0_SB_DQS_DP<6>")
	)
	(segment
		(start 438.06237 -218.495372)
		(end 437.676036 -218.881706)
		(width 0.18288)
		(layer "In6.Cu")
		(net "M_G_CPU0_SB_DQS_DP<6>")
	)
	(segment
		(start 435.56428 -219.842588)
		(end 435.561486 -219.845382)
		(width 0.18288)
		(layer "In6.Cu")
		(net "M_G_CPU0_SB_DQS_DP<6>")
	)
	(segment
		(start 410.912564 -221.414086)
		(end 410.366464 -221.414086)
		(width 0.18288)
		(layer "In6.Cu")
		(net "M_G_CPU0_SB_DQS_DP<6>")
	)
	(segment
		(start 400.974052 -223.860868)
		(end 400.974052 -224.03689)
		(width 0.18288)
		(layer "In6.Cu")
		(net "M_G_CPU0_SB_DQS_DP<6>")
	)
	(segment
		(start 428.820834 -220.711268)
		(end 427.549818 -221.560644)
		(width 0.18288)
		(layer "In6.Cu")
		(net "M_G_CPU0_SB_DQS_DP<6>")
	)
	(segment
		(start 425.282868 -222.661226)
		(end 425.014136 -222.392494)
		(width 0.18288)
		(layer "In6.Cu")
		(net "M_G_CPU0_SB_DQS_DP<6>")
	)
	(segment
		(start 414.979358 -222.455232)
		(end 413.723074 -221.198948)
		(width 0.18288)
		(layer "In6.Cu")
		(net "M_G_CPU0_SB_DQS_DP<6>")
	)
	(segment
		(start 432.854862 -219.720922)
		(end 432.730402 -219.845382)
		(width 0.18288)
		(layer "In6.Cu")
		(net "M_G_CPU0_SB_DQS_DP<6>")
	)
	(segment
		(start 387.360668 -233.996992)
		(end 386.924804 -234.317286)
		(width 0.088646)
		(layer "In6.Cu")
		(net "M_G_CPU0_SB_DQS_DP<6>")
	)
	(segment
		(start 420.911528 -223.242378)
		(end 420.56304 -223.242378)
		(width 0.18288)
		(layer "In6.Cu")
		(net "M_G_CPU0_SB_DQS_DP<6>")
	)
	(segment
		(start 439.923682 -217.716608)
		(end 439.90133 -217.716608)
		(width 0.18288)
		(layer "In6.Cu")
		(net "M_G_CPU0_SB_DQS_DP<6>")
	)
	(segment
		(start 388.001764 -233.629962)
		(end 387.94944 -233.629962)
		(width 0.088646)
		(layer "In6.Cu")
		(net "M_G_CPU0_SB_DQS_DP<6>")
	)
	(segment
		(start 420.56304 -223.242378)
		(end 420.30396 -223.501458)
		(width 0.18288)
		(layer "In6.Cu")
		(net "M_G_CPU0_SB_DQS_DP<6>")
	)
	(segment
		(start 418.868606 -223.501458)
		(end 418.322506 -223.501458)
		(width 0.18288)
		(layer "In6.Cu")
		(net "M_G_CPU0_SB_DQS_DP<6>")
	)
	(segment
		(start 400.587972 -224.42297)
		(end 400.41195 -224.42297)
		(width 0.18288)
		(layer "In6.Cu")
		(net "M_G_CPU0_SB_DQS_DP<6>")
	)
	(segment
		(start 404.295356 -221.191582)
		(end 403.81936 -221.191582)
		(width 0.18288)
		(layer "In6.Cu")
		(net "M_G_CPU0_SB_DQS_DP<6>")
	)
	(segment
		(start 421.40505 -223.522794)
		(end 421.191944 -223.522794)
		(width 0.18288)
		(layer "In6.Cu")
		(net "M_G_CPU0_SB_DQS_DP<6>")
	)
	(segment
		(start 424.382438 -222.672148)
		(end 422.834816 -222.672148)
		(width 0.18288)
		(layer "In6.Cu")
		(net "M_G_CPU0_SB_DQS_DP<6>")
	)
	(segment
		(start 377.701048 -235.283756)
		(end 377.419362 -235.09986)
		(width 0.088646)
		(layer "In6.Cu")
		(net "M_G_CPU0_SB_DQS_DP<6>")
	)
	(segment
		(start 378.097796 -235.292138)
		(end 378.08789 -235.297726)
		(width 0.088646)
		(layer "In6.Cu")
		(net "M_G_CPU0_SB_DQS_DP<6>")
	)
	(segment
		(start 400.41195 -224.42297)
		(end 400.025616 -224.809304)
		(width 0.18288)
		(layer "In6.Cu")
		(net "M_G_CPU0_SB_DQS_DP<6>")
	)
	(segment
		(start 430.741074 -220.711268)
		(end 428.820834 -220.711268)
		(width 0.18288)
		(layer "In6.Cu")
		(net "M_G_CPU0_SB_DQS_DP<6>")
	)
	(segment
		(start 433.400962 -219.720922)
		(end 432.854862 -219.720922)
		(width 0.18288)
		(layer "In6.Cu")
		(net "M_G_CPU0_SB_DQS_DP<6>")
	)
	(segment
		(start 405.636476 -221.191582)
		(end 405.090376 -221.191582)
		(width 0.18288)
		(layer "In6.Cu")
		(net "M_G_CPU0_SB_DQS_DP<6>")
	)
	(segment
		(start 408.207464 -221.191582)
		(end 408.083004 -221.067122)
		(width 0.18288)
		(layer "In6.Cu")
		(net "M_G_CPU0_SB_DQS_DP<6>")
	)
	(segment
		(start 437.676036 -218.881706)
		(end 437.676036 -219.057728)
		(width 0.18288)
		(layer "In6.Cu")
		(net "M_G_CPU0_SB_DQS_DP<6>")
	)
	(segment
		(start 409.160472 -221.538546)
		(end 408.813508 -221.191582)
		(width 0.18288)
		(layer "In6.Cu")
		(net "M_G_CPU0_SB_DQS_DP<6>")
	)
	(segment
		(start 403.257258 -221.577662)
		(end 402.870924 -221.963996)
		(width 0.18288)
		(layer "In6.Cu")
		(net "M_G_CPU0_SB_DQS_DP<6>")
	)
	(segment
		(start 433.525422 -219.845382)
		(end 433.400962 -219.720922)
		(width 0.18288)
		(layer "In6.Cu")
		(net "M_G_CPU0_SB_DQS_DP<6>")
	)
	(segment
		(start 431.659792 -219.987368)
		(end 431.074068 -220.573092)
		(width 0.18288)
		(layer "In6.Cu")
		(net "M_G_CPU0_SB_DQS_DP<6>")
	)
	(segment
		(start 381.478536 -235.294424)
		(end 381.468122 -235.288328)
		(width 0.088646)
		(layer "In6.Cu")
		(net "M_G_CPU0_SB_DQS_DP<6>")
	)
	(segment
		(start 410.242004 -221.538546)
		(end 409.160472 -221.538546)
		(width 0.18288)
		(layer "In6.Cu")
		(net "M_G_CPU0_SB_DQS_DP<6>")
	)
	(segment
		(start 426.53458 -221.981268)
		(end 425.966382 -222.549466)
		(width 0.18288)
		(layer "In6.Cu")
		(net "M_G_CPU0_SB_DQS_DP<6>")
	)
	(segment
		(start 401.360386 -223.474534)
		(end 400.974052 -223.860868)
		(width 0.18288)
		(layer "In6.Cu")
		(net "M_G_CPU0_SB_DQS_DP<6>")
	)
	(segment
		(start 413.012128 -221.198948)
		(end 412.19247 -221.538546)
		(width 0.18288)
		(layer "In6.Cu")
		(net "M_G_CPU0_SB_DQS_DP<6>")
	)
	(segment
		(start 435.561486 -219.845382)
		(end 433.525422 -219.845382)
		(width 0.18288)
		(layer "In6.Cu")
		(net "M_G_CPU0_SB_DQS_DP<6>")
	)
	(segment
		(start 438.624472 -218.109292)
		(end 438.238392 -218.495372)
		(width 0.18288)
		(layer "In6.Cu")
		(net "M_G_CPU0_SB_DQS_DP<6>")
	)
	(segment
		(start 412.19247 -221.538546)
		(end 411.037024 -221.538546)
		(width 0.18288)
		(layer "In6.Cu")
		(net "M_G_CPU0_SB_DQS_DP<6>")
	)
	(segment
		(start 439.583576 -218.034362)
		(end 438.805828 -218.034362)
		(width 0.18288)
		(layer "In6.Cu")
		(net "M_G_CPU0_SB_DQS_DP<6>")
	)
	(segment
		(start 387.677914 -233.689652)
		(end 387.427978 -233.939334)
		(width 0.088646)
		(layer "In6.Cu")
		(net "M_G_CPU0_SB_DQS_DP<6>")
	)
	(segment
		(start 411.037024 -221.538546)
		(end 410.912564 -221.414086)
		(width 0.18288)
		(layer "In6.Cu")
		(net "M_G_CPU0_SB_DQS_DP<6>")
	)
	(segment
		(start 436.336694 -220.086174)
		(end 436.093108 -219.842588)
		(width 0.18288)
		(layer "In6.Cu")
		(net "M_G_CPU0_SB_DQS_DP<6>")
	)
	(segment
		(start 436.724552 -220.009212)
		(end 436.541926 -220.086174)
		(width 0.18288)
		(layer "In6.Cu")
		(net "M_G_CPU0_SB_DQS_DP<6>")
	)
	(segment
		(start 422.296844 -222.894398)
		(end 421.856662 -223.33458)
		(width 0.18288)
		(layer "In6.Cu")
		(net "M_G_CPU0_SB_DQS_DP<6>")
	)
	(segment
		(start 386.077714 -234.483148)
		(end 386.075936 -234.484164)
		(width 0.088646)
		(layer "In6.Cu")
		(net "M_G_CPU0_SB_DQS_DP<6>")
	)
	(segment
		(start 407.412444 -221.191582)
		(end 406.431496 -221.191582)
		(width 0.18288)
		(layer "In6.Cu")
		(net "M_G_CPU0_SB_DQS_DP<6>")
	)
	(segment
		(start 439.90133 -217.716608)
		(end 439.583576 -218.034362)
		(width 0.18288)
		(layer "In6.Cu")
		(net "M_G_CPU0_SB_DQS_DP<6>")
	)
	(segment
		(start 404.965916 -221.067122)
		(end 404.419816 -221.067122)
		(width 0.18288)
		(layer "In6.Cu")
		(net "M_G_CPU0_SB_DQS_DP<6>")
	)
	(segment
		(start 384.297682 -235.294424)
		(end 384.287268 -235.288328)
		(width 0.088646)
		(layer "In6.Cu")
		(net "M_G_CPU0_SB_DQS_DP<6>")
	)
	(segment
		(start 387.88975 -233.689652)
		(end 387.677914 -233.689652)
		(width 0.088646)
		(layer "In6.Cu")
		(net "M_G_CPU0_SB_DQS_DP<6>")
	)
	(segment
		(start 400.025616 -224.809304)
		(end 400.025616 -224.985326)
		(width 0.18288)
		(layer "In6.Cu")
		(net "M_G_CPU0_SB_DQS_DP<6>")
	)
	(segment
		(start 385.237482 -235.294424)
		(end 385.22275 -235.285788)
		(width 0.088646)
		(layer "In6.Cu")
		(net "M_G_CPU0_SB_DQS_DP<6>")
	)
	(segment
		(start 418.198046 -223.376998)
		(end 417.651946 -223.376998)
		(width 0.18288)
		(layer "In6.Cu")
		(net "M_G_CPU0_SB_DQS_DP<6>")
	)
	(segment
		(start 420.30396 -223.501458)
		(end 419.663626 -223.501458)
		(width 0.18288)
		(layer "In6.Cu")
		(net "M_G_CPU0_SB_DQS_DP<6>")
	)
	(segment
		(start 377.419362 -235.09986)
		(end 377.079256 -235.082842)
		(width 0.088646)
		(layer "In6.Cu")
		(net "M_G_CPU0_SB_DQS_DP<6>")
	)
	(segment
		(start 404.419816 -221.067122)
		(end 404.295356 -221.191582)
		(width 0.18288)
		(layer "In6.Cu")
		(net "M_G_CPU0_SB_DQS_DP<6>")
	)
	(segment
		(start 400.974052 -224.03689)
		(end 400.587972 -224.42297)
		(width 0.18288)
		(layer "In6.Cu")
		(net "M_G_CPU0_SB_DQS_DP<6>")
	)
	(arc
		(start 385.22275 -235.285788)
		(mid 384.946275 -235.218468)
		(end 384.672078 -235.294424)
		(width 0.088646)
		(layer "In6.Cu")
		(net "M_G_CPU0_SB_DQS_DP<6>")
	)
	(arc
		(start 380.538482 -235.294424)
		(mid 380.259279 -235.218784)
		(end 379.979174 -235.291122)
		(width 0.088646)
		(layer "In6.Cu")
		(net "M_G_CPU0_SB_DQS_DP<6>")
	)
	(arc
		(start 382.418336 -235.294424)
		(mid 382.135634 -235.218648)
		(end 381.852932 -235.294424)
		(width 0.088646)
		(layer "In6.Cu")
		(net "M_G_CPU0_SB_DQS_DP<6>")
	)
	(arc
		(start 383.358136 -235.294424)
		(mid 383.075434 -235.218648)
		(end 382.792732 -235.294424)
		(width 0.088646)
		(layer "In6.Cu")
		(net "M_G_CPU0_SB_DQS_DP<6>")
	)
	(arc
		(start 381.468122 -235.288328)
		(mid 381.18969 -235.218482)
		(end 380.912878 -235.294424)
		(width 0.088646)
		(layer "In6.Cu")
		(net "M_G_CPU0_SB_DQS_DP<6>")
	)
	(arc
		(start 385.79933 -234.970066)
		(mid 385.751651 -235.152966)
		(end 385.620768 -235.289344)
		(width 0.088646)
		(layer "In6.Cu")
		(net "M_G_CPU0_SB_DQS_DP<6>")
	)
	(arc
		(start 384.672078 -235.294424)
		(mid 384.48488 -235.344567)
		(end 384.297682 -235.294424)
		(width 0.088646)
		(layer "In6.Cu")
		(net "M_G_CPU0_SB_DQS_DP<6>")
	)
	(arc
		(start 386.075936 -234.484164)
		(mid 385.873349 -234.690515)
		(end 385.79933 -234.970066)
		(width 0.088646)
		(layer "In6.Cu")
		(net "M_G_CPU0_SB_DQS_DP<6>")
	)
	(arc
		(start 379.96749 -235.297726)
		(mid 379.782635 -235.344676)
		(end 379.598682 -235.294424)
		(width 0.088646)
		(layer "In6.Cu")
		(net "M_G_CPU0_SB_DQS_DP<6>")
	)
	(arc
		(start 387.427978 -233.939334)
		(mid 387.395413 -233.969435)
		(end 387.360668 -233.996992)
		(width 0.088646)
		(layer "In6.Cu")
		(net "M_G_CPU0_SB_DQS_DP<6>")
	)
	(arc
		(start 379.598682 -235.294424)
		(mid 379.319479 -235.218784)
		(end 379.039374 -235.291122)
		(width 0.088646)
		(layer "In6.Cu")
		(net "M_G_CPU0_SB_DQS_DP<6>")
	)
	(arc
		(start 386.924804 -234.317286)
		(mid 386.711464 -234.413893)
		(end 386.477256 -234.415838)
		(width 0.088646)
		(layer "In6.Cu")
		(net "M_G_CPU0_SB_DQS_DP<6>")
	)
	(arc
		(start 386.477256 -234.415838)
		(mid 386.282104 -234.410598)
		(end 386.096764 -234.471972)
		(width 0.088646)
		(layer "In6.Cu")
		(net "M_G_CPU0_SB_DQS_DP<6>")
	)
	(arc
		(start 383.732532 -235.294424)
		(mid 383.545334 -235.344567)
		(end 383.358136 -235.294424)
		(width 0.088646)
		(layer "In6.Cu")
		(net "M_G_CPU0_SB_DQS_DP<6>")
	)
	(arc
		(start 378.658882 -235.294424)
		(mid 378.379679 -235.218784)
		(end 378.099574 -235.291122)
		(width 0.088646)
		(layer "In6.Cu")
		(net "M_G_CPU0_SB_DQS_DP<6>")
	)
	(arc
		(start 385.611878 -235.294424)
		(mid 385.42468 -235.344567)
		(end 385.237482 -235.294424)
		(width 0.088646)
		(layer "In6.Cu")
		(net "M_G_CPU0_SB_DQS_DP<6>")
	)
	(arc
		(start 384.287268 -235.288328)
		(mid 384.00909 -235.218605)
		(end 383.732532 -235.294424)
		(width 0.088646)
		(layer "In6.Cu")
		(net "M_G_CPU0_SB_DQS_DP<6>")
	)
	(arc
		(start 379.02769 -235.297726)
		(mid 378.842835 -235.344676)
		(end 378.658882 -235.294424)
		(width 0.088646)
		(layer "In6.Cu")
		(net "M_G_CPU0_SB_DQS_DP<6>")
	)
	(arc
		(start 380.912878 -235.294424)
		(mid 380.72568 -235.344567)
		(end 380.538482 -235.294424)
		(width 0.088646)
		(layer "In6.Cu")
		(net "M_G_CPU0_SB_DQS_DP<6>")
	)
	(arc
		(start 378.08789 -235.297726)
		(mid 377.892521 -235.344475)
		(end 377.701048 -235.283756)
		(width 0.088646)
		(layer "In6.Cu")
		(net "M_G_CPU0_SB_DQS_DP<6>")
	)
	(arc
		(start 382.792732 -235.294424)
		(mid 382.605534 -235.344567)
		(end 382.418336 -235.294424)
		(width 0.088646)
		(layer "In6.Cu")
		(net "M_G_CPU0_SB_DQS_DP<6>")
	)
	(arc
		(start 381.852932 -235.294424)
		(mid 381.665734 -235.344567)
		(end 381.478536 -235.294424)
		(width 0.088646)
		(layer "In6.Cu")
		(net "M_G_CPU0_SB_DQS_DP<6>")
	)
	(segment
		(start 443.455552 -226.634548)
		(end 443.462664 -226.64166)
		(width 0.1016)
		(layer "F.Cu")
		(net "M_G_CPU0_SB_DQS_DP<5>")
	)
	(segment
		(start 442.602874 -226.892866)
		(end 442.881258 -226.892866)
		(width 0.20066)
		(layer "F.Cu")
		(net "M_G_CPU0_SB_DQS_DP<5>")
	)
	(segment
		(start 447.158618 -227.334826)
		(end 447.736214 -227.334826)
		(width 0.20066)
		(layer "F.Cu")
		(net "M_G_CPU0_SB_DQS_DP<5>")
	)
	(segment
		(start 445.47536 -226.64166)
		(end 445.482726 -226.634294)
		(width 0.1016)
		(layer "F.Cu")
		(net "M_G_CPU0_SB_DQS_DP<5>")
	)
	(segment
		(start 441.621926 -227.066602)
		(end 441.873132 -227.317808)
		(width 0.20066)
		(layer "F.Cu")
		(net "M_G_CPU0_SB_DQS_DP<5>")
	)
	(segment
		(start 443.462664 -226.64166)
		(end 445.47536 -226.64166)
		(width 0.1016)
		(layer "F.Cu")
		(net "M_G_CPU0_SB_DQS_DP<5>")
	)
	(segment
		(start 442.881258 -226.892866)
		(end 443.139576 -226.634548)
		(width 0.20066)
		(layer "F.Cu")
		(net "M_G_CPU0_SB_DQS_DP<5>")
	)
	(segment
		(start 446.05956 -226.88931)
		(end 446.713102 -226.88931)
		(width 0.20066)
		(layer "F.Cu")
		(net "M_G_CPU0_SB_DQS_DP<5>")
	)
	(segment
		(start 443.450726 -226.634548)
		(end 443.455552 -226.634548)
		(width 0.101854)
		(layer "F.Cu")
		(net "M_G_CPU0_SB_DQS_DP<5>")
	)
	(segment
		(start 445.804544 -226.634294)
		(end 446.05956 -226.88931)
		(width 0.20066)
		(layer "F.Cu")
		(net "M_G_CPU0_SB_DQS_DP<5>")
	)
	(segment
		(start 442.177932 -227.317808)
		(end 442.602874 -226.892866)
		(width 0.20066)
		(layer "F.Cu")
		(net "M_G_CPU0_SB_DQS_DP<5>")
	)
	(segment
		(start 439.923682 -227.066602)
		(end 441.028582 -227.066602)
		(width 0.20066)
		(layer "F.Cu")
		(net "M_G_CPU0_SB_DQS_DP<5>")
	)
	(segment
		(start 441.873132 -227.317808)
		(end 442.177932 -227.317808)
		(width 0.20066)
		(layer "F.Cu")
		(net "M_G_CPU0_SB_DQS_DP<5>")
	)
	(segment
		(start 376.02668 -240.388902)
		(end 376.02668 -239.853216)
		(width 0.20066)
		(layer "F.Cu")
		(net "M_G_CPU0_SB_DQS_DP<5>")
	)
	(segment
		(start 376.026934 -240.389156)
		(end 376.02668 -240.388902)
		(width 0.20066)
		(layer "F.Cu")
		(net "M_G_CPU0_SB_DQS_DP<5>")
	)
	(segment
		(start 445.482726 -226.634294)
		(end 445.804544 -226.634294)
		(width 0.20066)
		(layer "F.Cu")
		(net "M_G_CPU0_SB_DQS_DP<5>")
	)
	(segment
		(start 443.139576 -226.634548)
		(end 443.450726 -226.634548)
		(width 0.20066)
		(layer "F.Cu")
		(net "M_G_CPU0_SB_DQS_DP<5>")
	)
	(segment
		(start 446.713102 -226.88931)
		(end 447.158618 -227.334826)
		(width 0.20066)
		(layer "F.Cu")
		(net "M_G_CPU0_SB_DQS_DP<5>")
	)
	(segment
		(start 441.028582 -227.066602)
		(end 441.621926 -227.066602)
		(width 0.20066)
		(layer "F.Cu")
		(net "M_G_CPU0_SB_DQS_DP<5>")
	)
	(segment
		(start 447.736214 -227.334826)
		(end 448.004438 -227.066602)
		(width 0.20066)
		(layer "F.Cu")
		(net "M_G_CPU0_SB_DQS_DP<5>")
	)
	(segment
		(start 448.004438 -227.066602)
		(end 448.572382 -227.066602)
		(width 0.20066)
		(layer "F.Cu")
		(net "M_G_CPU0_SB_DQS_DP<5>")
	)
	(segment
		(start 394.2715 -238.93653)
		(end 388.359396 -238.93653)
		(width 0.18288)
		(layer "In6.Cu")
		(net "M_G_CPU0_SB_DQS_DP<5>")
	)
	(segment
		(start 405.157178 -232.905046)
		(end 400.302984 -232.905046)
		(width 0.18288)
		(layer "In6.Cu")
		(net "M_G_CPU0_SB_DQS_DP<5>")
	)
	(segment
		(start 420.291768 -232.862882)
		(end 416.87115 -232.862882)
		(width 0.18288)
		(layer "In6.Cu")
		(net "M_G_CPU0_SB_DQS_DP<5>")
	)
	(segment
		(start 387.68655 -239.288066)
		(end 387.36778 -239.288066)
		(width 0.088646)
		(layer "In6.Cu")
		(net "M_G_CPU0_SB_DQS_DP<5>")
	)
	(segment
		(start 436.344822 -226.894136)
		(end 436.093108 -226.642422)
		(width 0.18288)
		(layer "In6.Cu")
		(net "M_G_CPU0_SB_DQS_DP<5>")
	)
	(segment
		(start 377.623832 -239.364012)
		(end 377.523756 -239.421924)
		(width 0.088646)
		(layer "In6.Cu")
		(net "M_G_CPU0_SB_DQS_DP<5>")
	)
	(segment
		(start 377.492514 -239.430306)
		(end 377.123706 -239.430306)
		(width 0.088646)
		(layer "In6.Cu")
		(net "M_G_CPU0_SB_DQS_DP<5>")
	)
	(segment
		(start 408.63266 -232.753662)
		(end 408.13101 -232.252012)
		(width 0.18288)
		(layer "In6.Cu")
		(net "M_G_CPU0_SB_DQS_DP<5>")
	)
	(segment
		(start 435.0258 -227.180902)
		(end 433.955952 -227.180902)
		(width 0.18288)
		(layer "In6.Cu")
		(net "M_G_CPU0_SB_DQS_DP<5>")
	)
	(segment
		(start 425.28109 -232.013506)
		(end 425.010072 -231.742488)
		(width 0.18288)
		(layer "In6.Cu")
		(net "M_G_CPU0_SB_DQS_DP<5>")
	)
	(segment
		(start 377.123706 -239.430306)
		(end 376.969528 -239.46104)
		(width 0.088646)
		(layer "In6.Cu")
		(net "M_G_CPU0_SB_DQS_DP<5>")
	)
	(segment
		(start 427.506892 -231.401366)
		(end 426.546772 -231.401366)
		(width 0.18288)
		(layer "In6.Cu")
		(net "M_G_CPU0_SB_DQS_DP<5>")
	)
	(segment
		(start 387.36778 -239.288066)
		(end 387.367526 -239.287812)
		(width 0.088646)
		(layer "In6.Cu")
		(net "M_G_CPU0_SB_DQS_DP<5>")
	)
	(segment
		(start 430.287684 -228.782626)
		(end 429.753776 -229.316534)
		(width 0.18288)
		(layer "In6.Cu")
		(net "M_G_CPU0_SB_DQS_DP<5>")
	)
	(segment
		(start 439.013346 -227.525834)
		(end 438.024524 -227.525834)
		(width 0.18288)
		(layer "In6.Cu")
		(net "M_G_CPU0_SB_DQS_DP<5>")
	)
	(segment
		(start 439.471816 -227.336604)
		(end 439.013346 -227.525834)
		(width 0.18288)
		(layer "In6.Cu")
		(net "M_G_CPU0_SB_DQS_DP<5>")
	)
	(segment
		(start 431.25644 -228.782626)
		(end 430.287684 -228.782626)
		(width 0.18288)
		(layer "In6.Cu")
		(net "M_G_CPU0_SB_DQS_DP<5>")
	)
	(segment
		(start 412.498794 -231.416606)
		(end 411.128718 -231.416606)
		(width 0.18288)
		(layer "In6.Cu")
		(net "M_G_CPU0_SB_DQS_DP<5>")
	)
	(segment
		(start 420.912544 -232.592626)
		(end 420.562024 -232.592626)
		(width 0.18288)
		(layer "In6.Cu")
		(net "M_G_CPU0_SB_DQS_DP<5>")
	)
	(segment
		(start 416.87115 -232.862882)
		(end 416.275266 -232.266998)
		(width 0.18288)
		(layer "In6.Cu")
		(net "M_G_CPU0_SB_DQS_DP<5>")
	)
	(segment
		(start 387.367526 -239.287812)
		(end 387.367272 -239.288066)
		(width 0.088646)
		(layer "In6.Cu")
		(net "M_G_CPU0_SB_DQS_DP<5>")
	)
	(segment
		(start 405.469598 -232.592626)
		(end 405.157178 -232.905046)
		(width 0.18288)
		(layer "In6.Cu")
		(net "M_G_CPU0_SB_DQS_DP<5>")
	)
	(segment
		(start 420.562024 -232.592626)
		(end 420.291768 -232.862882)
		(width 0.18288)
		(layer "In6.Cu")
		(net "M_G_CPU0_SB_DQS_DP<5>")
	)
	(segment
		(start 425.010072 -231.742488)
		(end 424.660568 -231.742488)
		(width 0.18288)
		(layer "In6.Cu")
		(net "M_G_CPU0_SB_DQS_DP<5>")
	)
	(segment
		(start 432.984148 -227.718366)
		(end 431.853086 -228.18598)
		(width 0.18288)
		(layer "In6.Cu")
		(net "M_G_CPU0_SB_DQS_DP<5>")
	)
	(segment
		(start 384.217164 -239.355122)
		(end 384.202432 -239.363758)
		(width 0.088646)
		(layer "In6.Cu")
		(net "M_G_CPU0_SB_DQS_DP<5>")
	)
	(segment
		(start 405.824436 -232.592626)
		(end 405.469598 -232.592626)
		(width 0.18288)
		(layer "In6.Cu")
		(net "M_G_CPU0_SB_DQS_DP<5>")
	)
	(segment
		(start 416.275266 -232.266998)
		(end 413.60598 -232.266998)
		(width 0.18288)
		(layer "In6.Cu")
		(net "M_G_CPU0_SB_DQS_DP<5>")
	)
	(segment
		(start 436.560214 -226.894136)
		(end 436.344822 -226.894136)
		(width 0.18288)
		(layer "In6.Cu")
		(net "M_G_CPU0_SB_DQS_DP<5>")
	)
	(segment
		(start 431.853086 -228.18598)
		(end 431.25644 -228.782626)
		(width 0.18288)
		(layer "In6.Cu")
		(net "M_G_CPU0_SB_DQS_DP<5>")
	)
	(segment
		(start 437.36514 -227.227384)
		(end 436.560214 -226.894136)
		(width 0.18288)
		(layer "In6.Cu")
		(net "M_G_CPU0_SB_DQS_DP<5>")
	)
	(segment
		(start 400.302984 -232.905046)
		(end 394.2715 -238.93653)
		(width 0.18288)
		(layer "In6.Cu")
		(net "M_G_CPU0_SB_DQS_DP<5>")
	)
	(segment
		(start 421.18661 -232.866692)
		(end 420.912544 -232.592626)
		(width 0.18288)
		(layer "In6.Cu")
		(net "M_G_CPU0_SB_DQS_DP<5>")
	)
	(segment
		(start 387.367272 -239.288066)
		(end 387.304026 -239.288066)
		(width 0.088646)
		(layer "In6.Cu")
		(net "M_G_CPU0_SB_DQS_DP<5>")
	)
	(segment
		(start 382.337564 -239.355122)
		(end 382.322832 -239.363758)
		(width 0.088646)
		(layer "In6.Cu")
		(net "M_G_CPU0_SB_DQS_DP<5>")
	)
	(segment
		(start 387.978396 -238.99622)
		(end 387.68655 -239.288066)
		(width 0.088646)
		(layer "In6.Cu")
		(net "M_G_CPU0_SB_DQS_DP<5>")
	)
	(segment
		(start 407.43505 -232.252012)
		(end 406.81275 -232.874312)
		(width 0.18288)
		(layer "In6.Cu")
		(net "M_G_CPU0_SB_DQS_DP<5>")
	)
	(segment
		(start 425.934632 -232.013506)
		(end 425.28109 -232.013506)
		(width 0.18288)
		(layer "In6.Cu")
		(net "M_G_CPU0_SB_DQS_DP<5>")
	)
	(segment
		(start 376.539252 -239.853216)
		(end 376.02668 -239.853216)
		(width 0.088646)
		(layer "In6.Cu")
		(net "M_G_CPU0_SB_DQS_DP<5>")
	)
	(segment
		(start 424.382438 -232.020618)
		(end 422.166796 -232.020618)
		(width 0.18288)
		(layer "In6.Cu")
		(net "M_G_CPU0_SB_DQS_DP<5>")
	)
	(segment
		(start 388.299706 -238.99622)
		(end 387.978396 -238.99622)
		(width 0.088646)
		(layer "In6.Cu")
		(net "M_G_CPU0_SB_DQS_DP<5>")
	)
	(segment
		(start 433.955952 -227.180902)
		(end 433.418488 -227.718366)
		(width 0.18288)
		(layer "In6.Cu")
		(net "M_G_CPU0_SB_DQS_DP<5>")
	)
	(segment
		(start 427.993048 -231.887522)
		(end 427.506892 -231.401366)
		(width 0.18288)
		(layer "In6.Cu")
		(net "M_G_CPU0_SB_DQS_DP<5>")
	)
	(segment
		(start 378.578364 -239.355122)
		(end 378.563632 -239.363758)
		(width 0.088646)
		(layer "In6.Cu")
		(net "M_G_CPU0_SB_DQS_DP<5>")
	)
	(segment
		(start 380.457964 -239.355122)
		(end 380.443232 -239.363758)
		(width 0.088646)
		(layer "In6.Cu")
		(net "M_G_CPU0_SB_DQS_DP<5>")
	)
	(segment
		(start 424.660568 -231.742488)
		(end 424.382438 -232.020618)
		(width 0.18288)
		(layer "In6.Cu")
		(net "M_G_CPU0_SB_DQS_DP<5>")
	)
	(segment
		(start 426.546772 -231.401366)
		(end 425.934632 -232.013506)
		(width 0.18288)
		(layer "In6.Cu")
		(net "M_G_CPU0_SB_DQS_DP<5>")
	)
	(segment
		(start 433.418488 -227.718366)
		(end 432.984148 -227.718366)
		(width 0.18288)
		(layer "In6.Cu")
		(net "M_G_CPU0_SB_DQS_DP<5>")
	)
	(segment
		(start 385.156964 -239.355122)
		(end 385.142232 -239.363758)
		(width 0.088646)
		(layer "In6.Cu")
		(net "M_G_CPU0_SB_DQS_DP<5>")
	)
	(segment
		(start 406.106122 -232.874312)
		(end 405.824436 -232.592626)
		(width 0.18288)
		(layer "In6.Cu")
		(net "M_G_CPU0_SB_DQS_DP<5>")
	)
	(segment
		(start 428.342552 -231.887522)
		(end 427.993048 -231.887522)
		(width 0.18288)
		(layer "In6.Cu")
		(net "M_G_CPU0_SB_DQS_DP<5>")
	)
	(segment
		(start 422.166796 -232.020618)
		(end 421.320722 -232.866692)
		(width 0.18288)
		(layer "In6.Cu")
		(net "M_G_CPU0_SB_DQS_DP<5>")
	)
	(segment
		(start 435.56428 -226.642422)
		(end 435.0258 -227.180902)
		(width 0.18288)
		(layer "In6.Cu")
		(net "M_G_CPU0_SB_DQS_DP<5>")
	)
	(segment
		(start 406.81275 -232.874312)
		(end 406.106122 -232.874312)
		(width 0.18288)
		(layer "In6.Cu")
		(net "M_G_CPU0_SB_DQS_DP<5>")
	)
	(segment
		(start 386.096764 -239.355122)
		(end 386.082032 -239.363758)
		(width 0.088646)
		(layer "In6.Cu")
		(net "M_G_CPU0_SB_DQS_DP<5>")
	)
	(segment
		(start 408.13101 -232.252012)
		(end 407.43505 -232.252012)
		(width 0.18288)
		(layer "In6.Cu")
		(net "M_G_CPU0_SB_DQS_DP<5>")
	)
	(segment
		(start 376.969528 -239.46104)
		(end 376.919744 -239.481614)
		(width 0.088646)
		(layer "In6.Cu")
		(net "M_G_CPU0_SB_DQS_DP<5>")
	)
	(segment
		(start 378.189236 -239.363758)
		(end 378.188728 -239.364012)
		(width 0.088646)
		(layer "In6.Cu")
		(net "M_G_CPU0_SB_DQS_DP<5>")
	)
	(segment
		(start 413.167322 -232.08488)
		(end 412.498794 -231.416606)
		(width 0.18288)
		(layer "In6.Cu")
		(net "M_G_CPU0_SB_DQS_DP<5>")
	)
	(segment
		(start 436.093108 -226.642422)
		(end 435.56428 -226.642422)
		(width 0.18288)
		(layer "In6.Cu")
		(net "M_G_CPU0_SB_DQS_DP<5>")
	)
	(segment
		(start 388.359396 -238.93653)
		(end 388.299706 -238.99622)
		(width 0.088646)
		(layer "In6.Cu")
		(net "M_G_CPU0_SB_DQS_DP<5>")
	)
	(segment
		(start 413.60598 -232.266998)
		(end 413.167322 -232.08488)
		(width 0.18288)
		(layer "In6.Cu")
		(net "M_G_CPU0_SB_DQS_DP<5>")
	)
	(segment
		(start 439.923682 -227.066602)
		(end 439.65368 -227.336604)
		(width 0.18288)
		(layer "In6.Cu")
		(net "M_G_CPU0_SB_DQS_DP<5>")
	)
	(segment
		(start 439.65368 -227.336604)
		(end 439.471816 -227.336604)
		(width 0.18288)
		(layer "In6.Cu")
		(net "M_G_CPU0_SB_DQS_DP<5>")
	)
	(segment
		(start 409.791662 -232.753662)
		(end 408.63266 -232.753662)
		(width 0.18288)
		(layer "In6.Cu")
		(net "M_G_CPU0_SB_DQS_DP<5>")
	)
	(segment
		(start 429.753776 -229.316534)
		(end 429.753776 -230.476298)
		(width 0.18288)
		(layer "In6.Cu")
		(net "M_G_CPU0_SB_DQS_DP<5>")
	)
	(segment
		(start 421.320722 -232.866692)
		(end 421.18661 -232.866692)
		(width 0.18288)
		(layer "In6.Cu")
		(net "M_G_CPU0_SB_DQS_DP<5>")
	)
	(segment
		(start 429.753776 -230.476298)
		(end 428.342552 -231.887522)
		(width 0.18288)
		(layer "In6.Cu")
		(net "M_G_CPU0_SB_DQS_DP<5>")
	)
	(segment
		(start 376.777758 -239.52962)
		(end 376.770392 -239.533938)
		(width 0.088646)
		(layer "In6.Cu")
		(net "M_G_CPU0_SB_DQS_DP<5>")
	)
	(segment
		(start 376.596402 -239.796066)
		(end 376.539252 -239.853216)
		(width 0.088646)
		(layer "In6.Cu")
		(net "M_G_CPU0_SB_DQS_DP<5>")
	)
	(segment
		(start 377.523756 -239.421924)
		(end 377.492514 -239.430306)
		(width 0.088646)
		(layer "In6.Cu")
		(net "M_G_CPU0_SB_DQS_DP<5>")
	)
	(segment
		(start 376.779282 -239.528858)
		(end 376.777758 -239.52962)
		(width 0.088646)
		(layer "In6.Cu")
		(net "M_G_CPU0_SB_DQS_DP<5>")
	)
	(segment
		(start 438.024524 -227.525834)
		(end 437.36514 -227.227384)
		(width 0.18288)
		(layer "In6.Cu")
		(net "M_G_CPU0_SB_DQS_DP<5>")
	)
	(segment
		(start 411.128718 -231.416606)
		(end 409.791662 -232.753662)
		(width 0.18288)
		(layer "In6.Cu")
		(net "M_G_CPU0_SB_DQS_DP<5>")
	)
	(arc
		(start 380.068836 -239.363758)
		(mid 379.786134 -239.287982)
		(end 379.503432 -239.363758)
		(width 0.088646)
		(layer "In6.Cu")
		(net "M_G_CPU0_SB_DQS_DP<5>")
	)
	(arc
		(start 378.188728 -239.364012)
		(mid 377.90628 -239.288329)
		(end 377.623832 -239.364012)
		(width 0.088646)
		(layer "In6.Cu")
		(net "M_G_CPU0_SB_DQS_DP<5>")
	)
	(arc
		(start 382.888236 -239.363758)
		(mid 382.614037 -239.287923)
		(end 382.337564 -239.355122)
		(width 0.088646)
		(layer "In6.Cu")
		(net "M_G_CPU0_SB_DQS_DP<5>")
	)
	(arc
		(start 382.322832 -239.363758)
		(mid 382.135634 -239.413901)
		(end 381.948436 -239.363758)
		(width 0.088646)
		(layer "In6.Cu")
		(net "M_G_CPU0_SB_DQS_DP<5>")
	)
	(arc
		(start 386.082032 -239.363758)
		(mid 385.894834 -239.413901)
		(end 385.707636 -239.363758)
		(width 0.088646)
		(layer "In6.Cu")
		(net "M_G_CPU0_SB_DQS_DP<5>")
	)
	(arc
		(start 381.008636 -239.363758)
		(mid 380.734437 -239.287923)
		(end 380.457964 -239.355122)
		(width 0.088646)
		(layer "In6.Cu")
		(net "M_G_CPU0_SB_DQS_DP<5>")
	)
	(arc
		(start 381.948436 -239.363758)
		(mid 381.665734 -239.287982)
		(end 381.383032 -239.363758)
		(width 0.088646)
		(layer "In6.Cu")
		(net "M_G_CPU0_SB_DQS_DP<5>")
	)
	(arc
		(start 379.503432 -239.363758)
		(mid 379.316234 -239.413901)
		(end 379.129036 -239.363758)
		(width 0.088646)
		(layer "In6.Cu")
		(net "M_G_CPU0_SB_DQS_DP<5>")
	)
	(arc
		(start 386.647436 -239.363758)
		(mid 386.373237 -239.287923)
		(end 386.096764 -239.355122)
		(width 0.088646)
		(layer "In6.Cu")
		(net "M_G_CPU0_SB_DQS_DP<5>")
	)
	(arc
		(start 376.919744 -239.481614)
		(mid 376.847147 -239.498206)
		(end 376.779282 -239.528858)
		(width 0.088646)
		(layer "In6.Cu")
		(net "M_G_CPU0_SB_DQS_DP<5>")
	)
	(arc
		(start 380.443232 -239.363758)
		(mid 380.256034 -239.413901)
		(end 380.068836 -239.363758)
		(width 0.088646)
		(layer "In6.Cu")
		(net "M_G_CPU0_SB_DQS_DP<5>")
	)
	(arc
		(start 378.563632 -239.363758)
		(mid 378.376434 -239.413901)
		(end 378.189236 -239.363758)
		(width 0.088646)
		(layer "In6.Cu")
		(net "M_G_CPU0_SB_DQS_DP<5>")
	)
	(arc
		(start 384.202432 -239.363758)
		(mid 384.015234 -239.413901)
		(end 383.828036 -239.363758)
		(width 0.088646)
		(layer "In6.Cu")
		(net "M_G_CPU0_SB_DQS_DP<5>")
	)
	(arc
		(start 385.142232 -239.363758)
		(mid 384.955034 -239.413901)
		(end 384.767836 -239.363758)
		(width 0.088646)
		(layer "In6.Cu")
		(net "M_G_CPU0_SB_DQS_DP<5>")
	)
	(arc
		(start 383.262632 -239.363758)
		(mid 383.075434 -239.413901)
		(end 382.888236 -239.363758)
		(width 0.088646)
		(layer "In6.Cu")
		(net "M_G_CPU0_SB_DQS_DP<5>")
	)
	(arc
		(start 383.828036 -239.363758)
		(mid 383.545334 -239.287982)
		(end 383.262632 -239.363758)
		(width 0.088646)
		(layer "In6.Cu")
		(net "M_G_CPU0_SB_DQS_DP<5>")
	)
	(arc
		(start 384.767836 -239.363758)
		(mid 384.493637 -239.287923)
		(end 384.217164 -239.355122)
		(width 0.088646)
		(layer "In6.Cu")
		(net "M_G_CPU0_SB_DQS_DP<5>")
	)
	(arc
		(start 387.304026 -239.288066)
		(mid 387.157945 -239.30734)
		(end 387.021832 -239.363758)
		(width 0.088646)
		(layer "In6.Cu")
		(net "M_G_CPU0_SB_DQS_DP<5>")
	)
	(arc
		(start 379.129036 -239.363758)
		(mid 378.854837 -239.287923)
		(end 378.578364 -239.355122)
		(width 0.088646)
		(layer "In6.Cu")
		(net "M_G_CPU0_SB_DQS_DP<5>")
	)
	(arc
		(start 376.770392 -239.533938)
		(mid 376.654583 -239.645867)
		(end 376.596402 -239.796066)
		(width 0.088646)
		(layer "In6.Cu")
		(net "M_G_CPU0_SB_DQS_DP<5>")
	)
	(arc
		(start 385.707636 -239.363758)
		(mid 385.433437 -239.287923)
		(end 385.156964 -239.355122)
		(width 0.088646)
		(layer "In6.Cu")
		(net "M_G_CPU0_SB_DQS_DP<5>")
	)
	(arc
		(start 387.021832 -239.363758)
		(mid 386.834634 -239.413901)
		(end 386.647436 -239.363758)
		(width 0.088646)
		(layer "In6.Cu")
		(net "M_G_CPU0_SB_DQS_DP<5>")
	)
	(arc
		(start 381.383032 -239.363758)
		(mid 381.195834 -239.413901)
		(end 381.008636 -239.363758)
		(width 0.088646)
		(layer "In6.Cu")
		(net "M_G_CPU0_SB_DQS_DP<5>")
	)
	(segment
		(start 447.158618 -236.68482)
		(end 447.736214 -236.68482)
		(width 0.20066)
		(layer "F.Cu")
		(net "M_G_CPU0_SB_DQS_DP<4>")
	)
	(segment
		(start 442.869828 -236.24286)
		(end 443.121034 -235.991654)
		(width 0.20066)
		(layer "F.Cu")
		(net "M_G_CPU0_SB_DQS_DP<4>")
	)
	(segment
		(start 442.602874 -236.24286)
		(end 442.869828 -236.24286)
		(width 0.20066)
		(layer "F.Cu")
		(net "M_G_CPU0_SB_DQS_DP<4>")
	)
	(segment
		(start 441.028582 -236.416596)
		(end 441.621926 -236.416596)
		(width 0.20066)
		(layer "F.Cu")
		(net "M_G_CPU0_SB_DQS_DP<4>")
	)
	(segment
		(start 443.121034 -235.991654)
		(end 443.228984 -235.991654)
		(width 0.20066)
		(layer "F.Cu")
		(net "M_G_CPU0_SB_DQS_DP<4>")
	)
	(segment
		(start 445.47536 -235.991654)
		(end 445.661542 -235.991654)
		(width 0.101854)
		(layer "F.Cu")
		(net "M_G_CPU0_SB_DQS_DP<4>")
	)
	(segment
		(start 379.31598 -242.830858)
		(end 379.316234 -242.830604)
		(width 0.20066)
		(layer "F.Cu")
		(net "M_G_CPU0_SB_DQS_DP<4>")
	)
	(segment
		(start 445.81191 -235.991654)
		(end 446.05956 -236.239304)
		(width 0.20066)
		(layer "F.Cu")
		(net "M_G_CPU0_SB_DQS_DP<4>")
	)
	(segment
		(start 445.661542 -235.991654)
		(end 445.81191 -235.991654)
		(width 0.20066)
		(layer "F.Cu")
		(net "M_G_CPU0_SB_DQS_DP<4>")
	)
	(segment
		(start 441.873132 -236.667802)
		(end 442.177932 -236.667802)
		(width 0.20066)
		(layer "F.Cu")
		(net "M_G_CPU0_SB_DQS_DP<4>")
	)
	(segment
		(start 439.923682 -236.416596)
		(end 441.028582 -236.416596)
		(width 0.20066)
		(layer "F.Cu")
		(net "M_G_CPU0_SB_DQS_DP<4>")
	)
	(segment
		(start 443.462664 -235.991654)
		(end 445.47536 -235.991654)
		(width 0.1016)
		(layer "F.Cu")
		(net "M_G_CPU0_SB_DQS_DP<4>")
	)
	(segment
		(start 447.736214 -236.68482)
		(end 448.004438 -236.416596)
		(width 0.20066)
		(layer "F.Cu")
		(net "M_G_CPU0_SB_DQS_DP<4>")
	)
	(segment
		(start 379.316234 -242.830604)
		(end 379.316234 -242.294918)
		(width 0.20066)
		(layer "F.Cu")
		(net "M_G_CPU0_SB_DQS_DP<4>")
	)
	(segment
		(start 441.621926 -236.416596)
		(end 441.873132 -236.667802)
		(width 0.20066)
		(layer "F.Cu")
		(net "M_G_CPU0_SB_DQS_DP<4>")
	)
	(segment
		(start 442.177932 -236.667802)
		(end 442.602874 -236.24286)
		(width 0.20066)
		(layer "F.Cu")
		(net "M_G_CPU0_SB_DQS_DP<4>")
	)
	(segment
		(start 443.228984 -235.991654)
		(end 443.462664 -235.991654)
		(width 0.101854)
		(layer "F.Cu")
		(net "M_G_CPU0_SB_DQS_DP<4>")
	)
	(segment
		(start 448.004438 -236.416596)
		(end 448.572382 -236.416596)
		(width 0.20066)
		(layer "F.Cu")
		(net "M_G_CPU0_SB_DQS_DP<4>")
	)
	(segment
		(start 446.05956 -236.239304)
		(end 446.713102 -236.239304)
		(width 0.20066)
		(layer "F.Cu")
		(net "M_G_CPU0_SB_DQS_DP<4>")
	)
	(segment
		(start 446.713102 -236.239304)
		(end 447.158618 -236.68482)
		(width 0.20066)
		(layer "F.Cu")
		(net "M_G_CPU0_SB_DQS_DP<4>")
	)
	(segment
		(start 381.478536 -241.80546)
		(end 381.468122 -241.799364)
		(width 0.088646)
		(layer "In4.Cu")
		(net "M_G_CPU0_SB_DQS_DP<4>")
	)
	(segment
		(start 439.12917 -236.67466)
		(end 438.834022 -236.969808)
		(width 0.18288)
		(layer "In4.Cu")
		(net "M_G_CPU0_SB_DQS_DP<4>")
	)
	(segment
		(start 391.47242 -241.410744)
		(end 388.255764 -241.410744)
		(width 0.18288)
		(layer "In4.Cu")
		(net "M_G_CPU0_SB_DQS_DP<4>")
	)
	(segment
		(start 394.437108 -238.774224)
		(end 392.032998 -241.178334)
		(width 0.18288)
		(layer "In4.Cu")
		(net "M_G_CPU0_SB_DQS_DP<4>")
	)
	(segment
		(start 420.929816 -235.992416)
		(end 420.52494 -235.992416)
		(width 0.18288)
		(layer "In4.Cu")
		(net "M_G_CPU0_SB_DQS_DP<4>")
	)
	(segment
		(start 420.275004 -236.242352)
		(end 419.415468 -236.242352)
		(width 0.18288)
		(layer "In4.Cu")
		(net "M_G_CPU0_SB_DQS_DP<4>")
	)
	(segment
		(start 400.960336 -237.131606)
		(end 399.975578 -237.539276)
		(width 0.18288)
		(layer "In4.Cu")
		(net "M_G_CPU0_SB_DQS_DP<4>")
	)
	(segment
		(start 398.740884 -238.774224)
		(end 394.437108 -238.774224)
		(width 0.18288)
		(layer "In4.Cu")
		(net "M_G_CPU0_SB_DQS_DP<4>")
	)
	(segment
		(start 380.068836 -241.97056)
		(end 380.059946 -241.97564)
		(width 0.088646)
		(layer "In4.Cu")
		(net "M_G_CPU0_SB_DQS_DP<4>")
	)
	(segment
		(start 388.255764 -241.410744)
		(end 388.232396 -241.410744)
		(width 0.088646)
		(layer "In4.Cu")
		(net "M_G_CPU0_SB_DQS_DP<4>")
	)
	(segment
		(start 408.734514 -236.572806)
		(end 408.175714 -237.131606)
		(width 0.18288)
		(layer "In4.Cu")
		(net "M_G_CPU0_SB_DQS_DP<4>")
	)
	(segment
		(start 388.172706 -241.470434)
		(end 387.757162 -241.470434)
		(width 0.088646)
		(layer "In4.Cu")
		(net "M_G_CPU0_SB_DQS_DP<4>")
	)
	(segment
		(start 380.696724 -241.897662)
		(end 380.26213 -241.897662)
		(width 0.088646)
		(layer "In4.Cu")
		(net "M_G_CPU0_SB_DQS_DP<4>")
	)
	(segment
		(start 439.923682 -236.416596)
		(end 439.665618 -236.67466)
		(width 0.18288)
		(layer "In4.Cu")
		(net "M_G_CPU0_SB_DQS_DP<4>")
	)
	(segment
		(start 412.961836 -236.903006)
		(end 412.16453 -236.572806)
		(width 0.18288)
		(layer "In4.Cu")
		(net "M_G_CPU0_SB_DQS_DP<4>")
	)
	(segment
		(start 380.803404 -241.86896)
		(end 380.696724 -241.897662)
		(width 0.088646)
		(layer "In4.Cu")
		(net "M_G_CPU0_SB_DQS_DP<4>")
	)
	(segment
		(start 392.032998 -241.178334)
		(end 391.47242 -241.410744)
		(width 0.18288)
		(layer "In4.Cu")
		(net "M_G_CPU0_SB_DQS_DP<4>")
	)
	(segment
		(start 387.757162 -241.470434)
		(end 387.498082 -241.729514)
		(width 0.088646)
		(layer "In4.Cu")
		(net "M_G_CPU0_SB_DQS_DP<4>")
	)
	(segment
		(start 436.961534 -236.250988)
		(end 436.275988 -236.250988)
		(width 0.18288)
		(layer "In4.Cu")
		(net "M_G_CPU0_SB_DQS_DP<4>")
	)
	(segment
		(start 437.680354 -236.969808)
		(end 436.961534 -236.250988)
		(width 0.18288)
		(layer "In4.Cu")
		(net "M_G_CPU0_SB_DQS_DP<4>")
	)
	(segment
		(start 423.168826 -235.37799)
		(end 422.295828 -236.250988)
		(width 0.18288)
		(layer "In4.Cu")
		(net "M_G_CPU0_SB_DQS_DP<4>")
	)
	(segment
		(start 435.336442 -236.268514)
		(end 435.122828 -236.268514)
		(width 0.18288)
		(layer "In4.Cu")
		(net "M_G_CPU0_SB_DQS_DP<4>")
	)
	(segment
		(start 424.38955 -235.37799)
		(end 423.168826 -235.37799)
		(width 0.18288)
		(layer "In4.Cu")
		(net "M_G_CPU0_SB_DQS_DP<4>")
	)
	(segment
		(start 388.232396 -241.410744)
		(end 388.172706 -241.470434)
		(width 0.088646)
		(layer "In4.Cu")
		(net "M_G_CPU0_SB_DQS_DP<4>")
	)
	(segment
		(start 421.188388 -236.250988)
		(end 420.929816 -235.992416)
		(width 0.18288)
		(layer "In4.Cu")
		(net "M_G_CPU0_SB_DQS_DP<4>")
	)
	(segment
		(start 438.834022 -236.969808)
		(end 437.680354 -236.969808)
		(width 0.18288)
		(layer "In4.Cu")
		(net "M_G_CPU0_SB_DQS_DP<4>")
	)
	(segment
		(start 399.975578 -237.539276)
		(end 398.740884 -238.774224)
		(width 0.18288)
		(layer "In4.Cu")
		(net "M_G_CPU0_SB_DQS_DP<4>")
	)
	(segment
		(start 427.25467 -236.041946)
		(end 426.726858 -236.041946)
		(width 0.18288)
		(layer "In4.Cu")
		(net "M_G_CPU0_SB_DQS_DP<4>")
	)
	(segment
		(start 380.912878 -241.80546)
		(end 380.913132 -241.805714)
		(width 0.088646)
		(layer "In4.Cu")
		(net "M_G_CPU0_SB_DQS_DP<4>")
	)
	(segment
		(start 387.498082 -241.729514)
		(end 386.834634 -241.729514)
		(width 0.088646)
		(layer "In4.Cu")
		(net "M_G_CPU0_SB_DQS_DP<4>")
	)
	(segment
		(start 422.295828 -236.250988)
		(end 421.188388 -236.250988)
		(width 0.18288)
		(layer "In4.Cu")
		(net "M_G_CPU0_SB_DQS_DP<4>")
	)
	(segment
		(start 431.00625 -235.410248)
		(end 427.886368 -235.410248)
		(width 0.18288)
		(layer "In4.Cu")
		(net "M_G_CPU0_SB_DQS_DP<4>")
	)
	(segment
		(start 379.828806 -242.294918)
		(end 379.316234 -242.294918)
		(width 0.088646)
		(layer "In4.Cu")
		(net "M_G_CPU0_SB_DQS_DP<4>")
	)
	(segment
		(start 427.886368 -235.410248)
		(end 427.25467 -236.041946)
		(width 0.18288)
		(layer "In4.Cu")
		(net "M_G_CPU0_SB_DQS_DP<4>")
	)
	(segment
		(start 417.820348 -236.903006)
		(end 412.961836 -236.903006)
		(width 0.18288)
		(layer "In4.Cu")
		(net "M_G_CPU0_SB_DQS_DP<4>")
	)
	(segment
		(start 385.237736 -241.80546)
		(end 385.237482 -241.80546)
		(width 0.088646)
		(layer "In4.Cu")
		(net "M_G_CPU0_SB_DQS_DP<4>")
	)
	(segment
		(start 420.52494 -235.992416)
		(end 420.275004 -236.242352)
		(width 0.18288)
		(layer "In4.Cu")
		(net "M_G_CPU0_SB_DQS_DP<4>")
	)
	(segment
		(start 384.672586 -241.80546)
		(end 384.672332 -241.80546)
		(width 0.088646)
		(layer "In4.Cu")
		(net "M_G_CPU0_SB_DQS_DP<4>")
	)
	(segment
		(start 380.913132 -241.805714)
		(end 380.803404 -241.86896)
		(width 0.088646)
		(layer "In4.Cu")
		(net "M_G_CPU0_SB_DQS_DP<4>")
	)
	(segment
		(start 436.017416 -235.992416)
		(end 435.61254 -235.992416)
		(width 0.18288)
		(layer "In4.Cu")
		(net "M_G_CPU0_SB_DQS_DP<4>")
	)
	(segment
		(start 436.275988 -236.250988)
		(end 436.017416 -235.992416)
		(width 0.18288)
		(layer "In4.Cu")
		(net "M_G_CPU0_SB_DQS_DP<4>")
	)
	(segment
		(start 419.415468 -236.242352)
		(end 417.820348 -236.903006)
		(width 0.18288)
		(layer "In4.Cu")
		(net "M_G_CPU0_SB_DQS_DP<4>")
	)
	(segment
		(start 431.663348 -236.067346)
		(end 431.00625 -235.410248)
		(width 0.18288)
		(layer "In4.Cu")
		(net "M_G_CPU0_SB_DQS_DP<4>")
	)
	(segment
		(start 408.175714 -237.131606)
		(end 400.960336 -237.131606)
		(width 0.18288)
		(layer "In4.Cu")
		(net "M_G_CPU0_SB_DQS_DP<4>")
	)
	(segment
		(start 439.665618 -236.67466)
		(end 439.12917 -236.67466)
		(width 0.18288)
		(layer "In4.Cu")
		(net "M_G_CPU0_SB_DQS_DP<4>")
	)
	(segment
		(start 426.094906 -235.409994)
		(end 425.297346 -235.409994)
		(width 0.18288)
		(layer "In4.Cu")
		(net "M_G_CPU0_SB_DQS_DP<4>")
	)
	(segment
		(start 379.885956 -242.237768)
		(end 379.828806 -242.294918)
		(width 0.088646)
		(layer "In4.Cu")
		(net "M_G_CPU0_SB_DQS_DP<4>")
	)
	(segment
		(start 434.92166 -236.067346)
		(end 431.663348 -236.067346)
		(width 0.18288)
		(layer "In4.Cu")
		(net "M_G_CPU0_SB_DQS_DP<4>")
	)
	(segment
		(start 426.726858 -236.041946)
		(end 426.094906 -235.409994)
		(width 0.18288)
		(layer "In4.Cu")
		(net "M_G_CPU0_SB_DQS_DP<4>")
	)
	(segment
		(start 425.297346 -235.409994)
		(end 425.029884 -235.142532)
		(width 0.18288)
		(layer "In4.Cu")
		(net "M_G_CPU0_SB_DQS_DP<4>")
	)
	(segment
		(start 382.797558 -241.80292)
		(end 382.792224 -241.805968)
		(width 0.088646)
		(layer "In4.Cu")
		(net "M_G_CPU0_SB_DQS_DP<4>")
	)
	(segment
		(start 425.029884 -235.142532)
		(end 424.625008 -235.142532)
		(width 0.18288)
		(layer "In4.Cu")
		(net "M_G_CPU0_SB_DQS_DP<4>")
	)
	(segment
		(start 435.122828 -236.268514)
		(end 434.92166 -236.067346)
		(width 0.18288)
		(layer "In4.Cu")
		(net "M_G_CPU0_SB_DQS_DP<4>")
	)
	(segment
		(start 412.16453 -236.572806)
		(end 408.734514 -236.572806)
		(width 0.18288)
		(layer "In4.Cu")
		(net "M_G_CPU0_SB_DQS_DP<4>")
	)
	(segment
		(start 435.61254 -235.992416)
		(end 435.336442 -236.268514)
		(width 0.18288)
		(layer "In4.Cu")
		(net "M_G_CPU0_SB_DQS_DP<4>")
	)
	(segment
		(start 382.430528 -241.81308)
		(end 382.41859 -241.805968)
		(width 0.088646)
		(layer "In4.Cu")
		(net "M_G_CPU0_SB_DQS_DP<4>")
	)
	(segment
		(start 424.625008 -235.142532)
		(end 424.38955 -235.37799)
		(width 0.18288)
		(layer "In4.Cu")
		(net "M_G_CPU0_SB_DQS_DP<4>")
	)
	(segment
		(start 383.358136 -241.80546)
		(end 383.357628 -241.805714)
		(width 0.088646)
		(layer "In4.Cu")
		(net "M_G_CPU0_SB_DQS_DP<4>")
	)
	(arc
		(start 384.297936 -241.80546)
		(mid 384.015234 -241.729684)
		(end 383.732532 -241.80546)
		(width 0.088646)
		(layer "In4.Cu")
		(net "M_G_CPU0_SB_DQS_DP<4>")
	)
	(arc
		(start 386.834634 -241.729514)
		(mid 386.810101 -241.730002)
		(end 386.785612 -241.731546)
		(width 0.088646)
		(layer "In4.Cu")
		(net "M_G_CPU0_SB_DQS_DP<4>")
	)
	(arc
		(start 385.237482 -241.80546)
		(mid 384.955034 -241.729811)
		(end 384.672586 -241.80546)
		(width 0.088646)
		(layer "In4.Cu")
		(net "M_G_CPU0_SB_DQS_DP<4>")
	)
	(arc
		(start 382.792224 -241.805968)
		(mid 382.612303 -241.855973)
		(end 382.430528 -241.81308)
		(width 0.088646)
		(layer "In4.Cu")
		(net "M_G_CPU0_SB_DQS_DP<4>")
	)
	(arc
		(start 383.732532 -241.80546)
		(mid 383.545334 -241.855603)
		(end 383.358136 -241.80546)
		(width 0.088646)
		(layer "In4.Cu")
		(net "M_G_CPU0_SB_DQS_DP<4>")
	)
	(arc
		(start 380.118874 -241.94643)
		(mid 380.093405 -241.957563)
		(end 380.068836 -241.97056)
		(width 0.088646)
		(layer "In4.Cu")
		(net "M_G_CPU0_SB_DQS_DP<4>")
	)
	(arc
		(start 385.612132 -241.80546)
		(mid 385.424934 -241.855603)
		(end 385.237736 -241.80546)
		(width 0.088646)
		(layer "In4.Cu")
		(net "M_G_CPU0_SB_DQS_DP<4>")
	)
	(arc
		(start 380.059946 -241.97564)
		(mid 379.944137 -242.087569)
		(end 379.885956 -242.237768)
		(width 0.088646)
		(layer "In4.Cu")
		(net "M_G_CPU0_SB_DQS_DP<4>")
	)
	(arc
		(start 381.852932 -241.80546)
		(mid 381.665734 -241.855603)
		(end 381.478536 -241.80546)
		(width 0.088646)
		(layer "In4.Cu")
		(net "M_G_CPU0_SB_DQS_DP<4>")
	)
	(arc
		(start 381.85344 -241.805714)
		(mid 381.853049 -241.805792)
		(end 381.852932 -241.80546)
		(width 0.088646)
		(layer "In4.Cu")
		(net "M_G_CPU0_SB_DQS_DP<4>")
	)
	(arc
		(start 382.41859 -241.805968)
		(mid 382.136061 -241.730124)
		(end 381.85344 -241.805714)
		(width 0.088646)
		(layer "In4.Cu")
		(net "M_G_CPU0_SB_DQS_DP<4>")
	)
	(arc
		(start 380.26213 -241.897662)
		(mid 380.214016 -241.904018)
		(end 380.169166 -241.922554)
		(width 0.088646)
		(layer "In4.Cu")
		(net "M_G_CPU0_SB_DQS_DP<4>")
	)
	(arc
		(start 380.169166 -241.922554)
		(mid 380.144461 -241.935421)
		(end 380.118874 -241.94643)
		(width 0.088646)
		(layer "In4.Cu")
		(net "M_G_CPU0_SB_DQS_DP<4>")
	)
	(arc
		(start 384.672332 -241.80546)
		(mid 384.485134 -241.855603)
		(end 384.297936 -241.80546)
		(width 0.088646)
		(layer "In4.Cu")
		(net "M_G_CPU0_SB_DQS_DP<4>")
	)
	(arc
		(start 386.177536 -241.80546)
		(mid 385.894834 -241.729684)
		(end 385.612132 -241.80546)
		(width 0.088646)
		(layer "In4.Cu")
		(net "M_G_CPU0_SB_DQS_DP<4>")
	)
	(arc
		(start 381.468122 -241.799364)
		(mid 381.18969 -241.729518)
		(end 380.912878 -241.80546)
		(width 0.088646)
		(layer "In4.Cu")
		(net "M_G_CPU0_SB_DQS_DP<4>")
	)
	(arc
		(start 383.357628 -241.805714)
		(mid 383.077968 -241.730038)
		(end 382.797558 -241.80292)
		(width 0.088646)
		(layer "In4.Cu")
		(net "M_G_CPU0_SB_DQS_DP<4>")
	)
	(arc
		(start 386.551932 -241.80546)
		(mid 386.364734 -241.855603)
		(end 386.177536 -241.80546)
		(width 0.088646)
		(layer "In4.Cu")
		(net "M_G_CPU0_SB_DQS_DP<4>")
	)
	(arc
		(start 386.785612 -241.731546)
		(mid 386.664708 -241.755665)
		(end 386.551932 -241.80546)
		(width 0.088646)
		(layer "In4.Cu")
		(net "M_G_CPU0_SB_DQS_DP<4>")
	)
	(segment
		(start 442.038994 -201.147934)
		(end 442.362336 -201.147934)
		(width 0.20066)
		(layer "F.Cu")
		(net "M_G_CPU0_SB_DQS_DP<3>")
	)
	(segment
		(start 442.362336 -201.147934)
		(end 442.66485 -200.84542)
		(width 0.20066)
		(layer "F.Cu")
		(net "M_G_CPU0_SB_DQS_DP<3>")
	)
	(segment
		(start 438.358788 -200.476104)
		(end 438.773316 -200.890632)
		(width 0.20066)
		(layer "F.Cu")
		(net "M_G_CPU0_SB_DQS_DP<3>")
	)
	(segment
		(start 437.758332 -200.476104)
		(end 438.358788 -200.476104)
		(width 0.20066)
		(layer "F.Cu")
		(net "M_G_CPU0_SB_DQS_DP<3>")
	)
	(segment
		(start 438.773316 -200.890632)
		(end 439.459116 -200.890632)
		(width 0.20066)
		(layer "F.Cu")
		(net "M_G_CPU0_SB_DQS_DP<3>")
	)
	(segment
		(start 443.4459 -200.434956)
		(end 443.641988 -200.434956)
		(width 0.20066)
		(layer "F.Cu")
		(net "M_G_CPU0_SB_DQS_DP<3>")
	)
	(segment
		(start 439.710322 -201.141838)
		(end 439.849768 -201.141838)
		(width 0.20066)
		(layer "F.Cu")
		(net "M_G_CPU0_SB_DQS_DP<3>")
	)
	(segment
		(start 385.42976 -218.697048)
		(end 385.424934 -218.692222)
		(width 0.20066)
		(layer "F.Cu")
		(net "M_G_CPU0_SB_DQS_DP<3>")
	)
	(segment
		(start 439.849768 -201.141838)
		(end 439.875676 -201.141838)
		(width 0.101854)
		(layer "F.Cu")
		(net "M_G_CPU0_SB_DQS_DP<3>")
	)
	(segment
		(start 436.928514 -200.716642)
		(end 437.517794 -200.716642)
		(width 0.20066)
		(layer "F.Cu")
		(net "M_G_CPU0_SB_DQS_DP<3>")
	)
	(segment
		(start 385.424934 -219.228162)
		(end 385.42976 -218.697048)
		(width 0.20066)
		(layer "F.Cu")
		(net "M_G_CPU0_SB_DQS_DP<3>")
	)
	(segment
		(start 435.823614 -200.716642)
		(end 436.928514 -200.716642)
		(width 0.20066)
		(layer "F.Cu")
		(net "M_G_CPU0_SB_DQS_DP<3>")
	)
	(segment
		(start 439.459116 -200.890632)
		(end 439.710322 -201.141838)
		(width 0.20066)
		(layer "F.Cu")
		(net "M_G_CPU0_SB_DQS_DP<3>")
	)
	(segment
		(start 437.517794 -200.716642)
		(end 437.758332 -200.476104)
		(width 0.20066)
		(layer "F.Cu")
		(net "M_G_CPU0_SB_DQS_DP<3>")
	)
	(segment
		(start 442.66485 -200.84542)
		(end 443.035436 -200.84542)
		(width 0.20066)
		(layer "F.Cu")
		(net "M_G_CPU0_SB_DQS_DP<3>")
	)
	(segment
		(start 443.641988 -200.434956)
		(end 443.923674 -200.716642)
		(width 0.20066)
		(layer "F.Cu")
		(net "M_G_CPU0_SB_DQS_DP<3>")
	)
	(segment
		(start 442.032898 -201.141838)
		(end 442.038994 -201.147934)
		(width 0.1016)
		(layer "F.Cu")
		(net "M_G_CPU0_SB_DQS_DP<3>")
	)
	(segment
		(start 443.035436 -200.84542)
		(end 443.4459 -200.434956)
		(width 0.20066)
		(layer "F.Cu")
		(net "M_G_CPU0_SB_DQS_DP<3>")
	)
	(segment
		(start 439.875676 -201.141838)
		(end 442.032898 -201.141838)
		(width 0.1016)
		(layer "F.Cu")
		(net "M_G_CPU0_SB_DQS_DP<3>")
	)
	(segment
		(start 443.923674 -200.716642)
		(end 444.472314 -200.716642)
		(width 0.20066)
		(layer "F.Cu")
		(net "M_G_CPU0_SB_DQS_DP<3>")
	)
	(segment
		(start 423.319448 -200.194926)
		(end 422.928288 -200.194926)
		(width 0.18288)
		(layer "In6.Cu")
		(net "M_G_CPU0_SB_DQS_DP<3>")
	)
	(segment
		(start 389.624824 -218.117166)
		(end 389.424926 -218.317064)
		(width 0.088646)
		(layer "In6.Cu")
		(net "M_G_CPU0_SB_DQS_DP<3>")
	)
	(segment
		(start 425.9834 -200.880472)
		(end 425.289726 -200.880472)
		(width 0.18288)
		(layer "In6.Cu")
		(net "M_G_CPU0_SB_DQS_DP<3>")
	)
	(segment
		(start 388.996682 -218.367356)
		(end 388.996936 -218.367864)
		(width 0.088646)
		(layer "In6.Cu")
		(net "M_G_CPU0_SB_DQS_DP<3>")
	)
	(segment
		(start 435.823614 -200.716642)
		(end 435.539134 -200.432162)
		(width 0.18288)
		(layer "In6.Cu")
		(net "M_G_CPU0_SB_DQS_DP<3>")
	)
	(segment
		(start 421.196262 -199.18045)
		(end 420.935912 -199.4408)
		(width 0.18288)
		(layer "In6.Cu")
		(net "M_G_CPU0_SB_DQS_DP<3>")
	)
	(segment
		(start 387.506464 -218.3765)
		(end 387.491732 -218.367864)
		(width 0.088646)
		(layer "In6.Cu")
		(net "M_G_CPU0_SB_DQS_DP<3>")
	)
	(segment
		(start 424.004994 -200.880472)
		(end 423.319448 -200.194926)
		(width 0.18288)
		(layer "In6.Cu")
		(net "M_G_CPU0_SB_DQS_DP<3>")
	)
	(segment
		(start 435.539134 -200.432162)
		(end 435.03596 -200.432162)
		(width 0.18288)
		(layer "In6.Cu")
		(net "M_G_CPU0_SB_DQS_DP<3>")
	)
	(segment
		(start 390.161526 -217.06205)
		(end 389.624824 -217.598752)
		(width 0.088646)
		(layer "In6.Cu")
		(net "M_G_CPU0_SB_DQS_DP<3>")
	)
	(segment
		(start 390.161526 -216.63025)
		(end 390.161526 -217.06205)
		(width 0.088646)
		(layer "In6.Cu")
		(net "M_G_CPU0_SB_DQS_DP<3>")
	)
	(segment
		(start 435.03596 -200.432162)
		(end 434.620416 -200.016618)
		(width 0.18288)
		(layer "In6.Cu")
		(net "M_G_CPU0_SB_DQS_DP<3>")
	)
	(segment
		(start 420.241222 -199.148954)
		(end 417.557712 -199.148954)
		(width 0.18288)
		(layer "In6.Cu")
		(net "M_G_CPU0_SB_DQS_DP<3>")
	)
	(segment
		(start 390.355328 -216.521284)
		(end 390.270492 -216.521284)
		(width 0.088646)
		(layer "In6.Cu")
		(net "M_G_CPU0_SB_DQS_DP<3>")
	)
	(segment
		(start 430.753774 -200.5838)
		(end 430.143666 -199.973692)
		(width 0.18288)
		(layer "In6.Cu")
		(net "M_G_CPU0_SB_DQS_DP<3>")
	)
	(segment
		(start 426.86732 -199.996552)
		(end 425.9834 -200.880472)
		(width 0.18288)
		(layer "In6.Cu")
		(net "M_G_CPU0_SB_DQS_DP<3>")
	)
	(segment
		(start 422.928288 -200.194926)
		(end 421.913812 -199.18045)
		(width 0.18288)
		(layer "In6.Cu")
		(net "M_G_CPU0_SB_DQS_DP<3>")
	)
	(segment
		(start 386.177536 -218.367864)
		(end 386.162804 -218.3765)
		(width 0.088646)
		(layer "In6.Cu")
		(net "M_G_CPU0_SB_DQS_DP<3>")
	)
	(segment
		(start 389.624824 -217.598752)
		(end 389.624824 -218.117166)
		(width 0.088646)
		(layer "In6.Cu")
		(net "M_G_CPU0_SB_DQS_DP<3>")
	)
	(segment
		(start 429.765714 -199.973692)
		(end 429.142398 -200.597008)
		(width 0.18288)
		(layer "In6.Cu")
		(net "M_G_CPU0_SB_DQS_DP<3>")
	)
	(segment
		(start 429.142398 -200.597008)
		(end 428.297086 -200.597008)
		(width 0.18288)
		(layer "In6.Cu")
		(net "M_G_CPU0_SB_DQS_DP<3>")
	)
	(segment
		(start 424.37177 -200.880472)
		(end 424.004994 -200.880472)
		(width 0.18288)
		(layer "In6.Cu")
		(net "M_G_CPU0_SB_DQS_DP<3>")
	)
	(segment
		(start 420.533068 -199.4408)
		(end 420.241222 -199.148954)
		(width 0.18288)
		(layer "In6.Cu")
		(net "M_G_CPU0_SB_DQS_DP<3>")
	)
	(segment
		(start 424.63212 -201.140822)
		(end 424.37177 -200.880472)
		(width 0.18288)
		(layer "In6.Cu")
		(net "M_G_CPU0_SB_DQS_DP<3>")
	)
	(segment
		(start 389.183372 -218.317064)
		(end 389.183118 -218.317318)
		(width 0.088646)
		(layer "In6.Cu")
		(net "M_G_CPU0_SB_DQS_DP<3>")
	)
	(segment
		(start 389.424926 -218.317064)
		(end 389.183372 -218.317064)
		(width 0.088646)
		(layer "In6.Cu")
		(net "M_G_CPU0_SB_DQS_DP<3>")
	)
	(segment
		(start 397.54429 -209.332322)
		(end 390.371838 -216.504774)
		(width 0.18288)
		(layer "In6.Cu")
		(net "M_G_CPU0_SB_DQS_DP<3>")
	)
	(segment
		(start 428.297086 -200.597008)
		(end 427.69663 -199.996552)
		(width 0.18288)
		(layer "In6.Cu")
		(net "M_G_CPU0_SB_DQS_DP<3>")
	)
	(segment
		(start 421.913812 -199.18045)
		(end 421.196262 -199.18045)
		(width 0.18288)
		(layer "In6.Cu")
		(net "M_G_CPU0_SB_DQS_DP<3>")
	)
	(segment
		(start 430.143666 -199.973692)
		(end 429.765714 -199.973692)
		(width 0.18288)
		(layer "In6.Cu")
		(net "M_G_CPU0_SB_DQS_DP<3>")
	)
	(segment
		(start 405.641302 -199.769476)
		(end 397.54429 -207.866488)
		(width 0.18288)
		(layer "In6.Cu")
		(net "M_G_CPU0_SB_DQS_DP<3>")
	)
	(segment
		(start 425.289726 -200.880472)
		(end 425.029376 -201.140822)
		(width 0.18288)
		(layer "In6.Cu")
		(net "M_G_CPU0_SB_DQS_DP<3>")
	)
	(segment
		(start 390.371838 -216.504774)
		(end 390.355328 -216.521284)
		(width 0.088646)
		(layer "In6.Cu")
		(net "M_G_CPU0_SB_DQS_DP<3>")
	)
	(segment
		(start 385.670552 -218.397328)
		(end 385.581398 -218.421204)
		(width 0.088646)
		(layer "In6.Cu")
		(net "M_G_CPU0_SB_DQS_DP<3>")
	)
	(segment
		(start 397.54429 -207.866488)
		(end 397.54429 -209.332322)
		(width 0.18288)
		(layer "In6.Cu")
		(net "M_G_CPU0_SB_DQS_DP<3>")
	)
	(segment
		(start 386.566664 -218.3765)
		(end 386.551932 -218.367864)
		(width 0.088646)
		(layer "In6.Cu")
		(net "M_G_CPU0_SB_DQS_DP<3>")
	)
	(segment
		(start 432.286156 -200.016618)
		(end 431.718974 -200.5838)
		(width 0.18288)
		(layer "In6.Cu")
		(net "M_G_CPU0_SB_DQS_DP<3>")
	)
	(segment
		(start 420.935912 -199.4408)
		(end 420.533068 -199.4408)
		(width 0.18288)
		(layer "In6.Cu")
		(net "M_G_CPU0_SB_DQS_DP<3>")
	)
	(segment
		(start 425.029376 -201.140822)
		(end 424.63212 -201.140822)
		(width 0.18288)
		(layer "In6.Cu")
		(net "M_G_CPU0_SB_DQS_DP<3>")
	)
	(segment
		(start 388.446264 -218.3765)
		(end 388.431532 -218.367864)
		(width 0.088646)
		(layer "In6.Cu")
		(net "M_G_CPU0_SB_DQS_DP<3>")
	)
	(segment
		(start 416.93719 -199.769476)
		(end 405.641302 -199.769476)
		(width 0.18288)
		(layer "In6.Cu")
		(net "M_G_CPU0_SB_DQS_DP<3>")
	)
	(segment
		(start 390.270492 -216.521284)
		(end 390.161526 -216.63025)
		(width 0.088646)
		(layer "In6.Cu")
		(net "M_G_CPU0_SB_DQS_DP<3>")
	)
	(segment
		(start 417.557712 -199.148954)
		(end 416.93719 -199.769476)
		(width 0.18288)
		(layer "In6.Cu")
		(net "M_G_CPU0_SB_DQS_DP<3>")
	)
	(segment
		(start 385.581398 -218.421204)
		(end 385.424934 -218.692222)
		(width 0.088646)
		(layer "In6.Cu")
		(net "M_G_CPU0_SB_DQS_DP<3>")
	)
	(segment
		(start 431.718974 -200.5838)
		(end 430.753774 -200.5838)
		(width 0.18288)
		(layer "In6.Cu")
		(net "M_G_CPU0_SB_DQS_DP<3>")
	)
	(segment
		(start 427.69663 -199.996552)
		(end 426.86732 -199.996552)
		(width 0.18288)
		(layer "In6.Cu")
		(net "M_G_CPU0_SB_DQS_DP<3>")
	)
	(segment
		(start 434.620416 -200.016618)
		(end 432.286156 -200.016618)
		(width 0.18288)
		(layer "In6.Cu")
		(net "M_G_CPU0_SB_DQS_DP<3>")
	)
	(arc
		(start 388.996936 -218.367864)
		(mid 388.722737 -218.443699)
		(end 388.446264 -218.3765)
		(width 0.088646)
		(layer "In6.Cu")
		(net "M_G_CPU0_SB_DQS_DP<3>")
	)
	(arc
		(start 386.551932 -218.367864)
		(mid 386.364734 -218.317721)
		(end 386.177536 -218.367864)
		(width 0.088646)
		(layer "In6.Cu")
		(net "M_G_CPU0_SB_DQS_DP<3>")
	)
	(arc
		(start 386.162804 -218.3765)
		(mid 385.929889 -218.442711)
		(end 385.690618 -218.405456)
		(width 0.088646)
		(layer "In6.Cu")
		(net "M_G_CPU0_SB_DQS_DP<3>")
	)
	(arc
		(start 389.183118 -218.317318)
		(mid 389.086596 -218.330036)
		(end 388.996682 -218.367356)
		(width 0.088646)
		(layer "In6.Cu")
		(net "M_G_CPU0_SB_DQS_DP<3>")
	)
	(arc
		(start 388.057136 -218.367864)
		(mid 387.782937 -218.443699)
		(end 387.506464 -218.3765)
		(width 0.088646)
		(layer "In6.Cu")
		(net "M_G_CPU0_SB_DQS_DP<3>")
	)
	(arc
		(start 388.431532 -218.367864)
		(mid 388.244334 -218.317721)
		(end 388.057136 -218.367864)
		(width 0.088646)
		(layer "In6.Cu")
		(net "M_G_CPU0_SB_DQS_DP<3>")
	)
	(arc
		(start 387.117336 -218.367864)
		(mid 386.843137 -218.443699)
		(end 386.566664 -218.3765)
		(width 0.088646)
		(layer "In6.Cu")
		(net "M_G_CPU0_SB_DQS_DP<3>")
	)
	(arc
		(start 387.491732 -218.367864)
		(mid 387.304534 -218.317721)
		(end 387.117336 -218.367864)
		(width 0.088646)
		(layer "In6.Cu")
		(net "M_G_CPU0_SB_DQS_DP<3>")
	)
	(arc
		(start 385.690618 -218.405456)
		(mid 385.680546 -218.401489)
		(end 385.670552 -218.397328)
		(width 0.088646)
		(layer "In6.Cu")
		(net "M_G_CPU0_SB_DQS_DP<3>")
	)
	(segment
		(start 377.43638 -233.064304)
		(end 377.43638 -232.528618)
		(width 0.20066)
		(layer "F.Cu")
		(net "M_G_CPU0_SB_DQS_DP<2>")
	)
	(segment
		(start 438.773316 -210.240626)
		(end 439.459116 -210.240626)
		(width 0.20066)
		(layer "F.Cu")
		(net "M_G_CPU0_SB_DQS_DP<2>")
	)
	(segment
		(start 442.032898 -210.491832)
		(end 442.038994 -210.497928)
		(width 0.1016)
		(layer "F.Cu")
		(net "M_G_CPU0_SB_DQS_DP<2>")
	)
	(segment
		(start 437.517794 -210.066636)
		(end 437.758332 -209.826098)
		(width 0.20066)
		(layer "F.Cu")
		(net "M_G_CPU0_SB_DQS_DP<2>")
	)
	(segment
		(start 442.038994 -210.497928)
		(end 442.362336 -210.497928)
		(width 0.20066)
		(layer "F.Cu")
		(net "M_G_CPU0_SB_DQS_DP<2>")
	)
	(segment
		(start 439.875676 -210.491832)
		(end 442.032898 -210.491832)
		(width 0.1016)
		(layer "F.Cu")
		(net "M_G_CPU0_SB_DQS_DP<2>")
	)
	(segment
		(start 436.928514 -210.066636)
		(end 437.517794 -210.066636)
		(width 0.20066)
		(layer "F.Cu")
		(net "M_G_CPU0_SB_DQS_DP<2>")
	)
	(segment
		(start 439.710322 -210.491832)
		(end 439.849768 -210.491832)
		(width 0.20066)
		(layer "F.Cu")
		(net "M_G_CPU0_SB_DQS_DP<2>")
	)
	(segment
		(start 443.923674 -210.066636)
		(end 444.472314 -210.066636)
		(width 0.20066)
		(layer "F.Cu")
		(net "M_G_CPU0_SB_DQS_DP<2>")
	)
	(segment
		(start 377.43638 -232.528618)
		(end 377.436634 -232.528364)
		(width 0.20066)
		(layer "F.Cu")
		(net "M_G_CPU0_SB_DQS_DP<2>")
	)
	(segment
		(start 443.641988 -209.78495)
		(end 443.923674 -210.066636)
		(width 0.20066)
		(layer "F.Cu")
		(net "M_G_CPU0_SB_DQS_DP<2>")
	)
	(segment
		(start 438.358788 -209.826098)
		(end 438.773316 -210.240626)
		(width 0.20066)
		(layer "F.Cu")
		(net "M_G_CPU0_SB_DQS_DP<2>")
	)
	(segment
		(start 442.362336 -210.497928)
		(end 442.66485 -210.195414)
		(width 0.20066)
		(layer "F.Cu")
		(net "M_G_CPU0_SB_DQS_DP<2>")
	)
	(segment
		(start 439.459116 -210.240626)
		(end 439.710322 -210.491832)
		(width 0.20066)
		(layer "F.Cu")
		(net "M_G_CPU0_SB_DQS_DP<2>")
	)
	(segment
		(start 442.66485 -210.195414)
		(end 443.035436 -210.195414)
		(width 0.20066)
		(layer "F.Cu")
		(net "M_G_CPU0_SB_DQS_DP<2>")
	)
	(segment
		(start 443.035436 -210.195414)
		(end 443.4459 -209.78495)
		(width 0.20066)
		(layer "F.Cu")
		(net "M_G_CPU0_SB_DQS_DP<2>")
	)
	(segment
		(start 435.823614 -210.066636)
		(end 436.928514 -210.066636)
		(width 0.20066)
		(layer "F.Cu")
		(net "M_G_CPU0_SB_DQS_DP<2>")
	)
	(segment
		(start 437.758332 -209.826098)
		(end 438.358788 -209.826098)
		(width 0.20066)
		(layer "F.Cu")
		(net "M_G_CPU0_SB_DQS_DP<2>")
	)
	(segment
		(start 443.4459 -209.78495)
		(end 443.641988 -209.78495)
		(width 0.20066)
		(layer "F.Cu")
		(net "M_G_CPU0_SB_DQS_DP<2>")
	)
	(segment
		(start 439.849768 -210.491832)
		(end 439.875676 -210.491832)
		(width 0.101854)
		(layer "F.Cu")
		(net "M_G_CPU0_SB_DQS_DP<2>")
	)
	(segment
		(start 434.89753 -209.57159)
		(end 434.149754 -209.57159)
		(width 0.18288)
		(layer "In4.Cu")
		(net "M_G_CPU0_SB_DQS_DP<2>")
	)
	(segment
		(start 428.569628 -213.720172)
		(end 428.065184 -213.720172)
		(width 0.18288)
		(layer "In4.Cu")
		(net "M_G_CPU0_SB_DQS_DP<2>")
	)
	(segment
		(start 413.95142 -213.067646)
		(end 413.65551 -213.363556)
		(width 0.18288)
		(layer "In4.Cu")
		(net "M_G_CPU0_SB_DQS_DP<2>")
	)
	(segment
		(start 432.242722 -211.007198)
		(end 431.307494 -211.942426)
		(width 0.18288)
		(layer "In4.Cu")
		(net "M_G_CPU0_SB_DQS_DP<2>")
	)
	(segment
		(start 386.647436 -230.57612)
		(end 386.646674 -230.576628)
		(width 0.088646)
		(layer "In4.Cu")
		(net "M_G_CPU0_SB_DQS_DP<2>")
	)
	(segment
		(start 378.658882 -233.017822)
		(end 378.64415 -233.026458)
		(width 0.088646)
		(layer "In4.Cu")
		(net "M_G_CPU0_SB_DQS_DP<2>")
	)
	(segment
		(start 408.99842 -212.916008)
		(end 408.516328 -213.3981)
		(width 0.18288)
		(layer "In4.Cu")
		(net "M_G_CPU0_SB_DQS_DP<2>")
	)
	(segment
		(start 408.516328 -213.3981)
		(end 405.970232 -213.3981)
		(width 0.18288)
		(layer "In4.Cu")
		(net "M_G_CPU0_SB_DQS_DP<2>")
	)
	(segment
		(start 416.799522 -212.983572)
		(end 416.359848 -213.423246)
		(width 0.18288)
		(layer "In4.Cu")
		(net "M_G_CPU0_SB_DQS_DP<2>")
	)
	(segment
		(start 417.74364 -212.983572)
		(end 416.799522 -212.983572)
		(width 0.18288)
		(layer "In4.Cu")
		(net "M_G_CPU0_SB_DQS_DP<2>")
	)
	(segment
		(start 426.063664 -213.61019)
		(end 425.312078 -213.61019)
		(width 0.18288)
		(layer "In4.Cu")
		(net "M_G_CPU0_SB_DQS_DP<2>")
	)
	(segment
		(start 387.921246 -228.243638)
		(end 387.921246 -228.957124)
		(width 0.088646)
		(layer "In4.Cu")
		(net "M_G_CPU0_SB_DQS_DP<2>")
	)
	(segment
		(start 384.672332 -233.017822)
		(end 384.67284 -233.017568)
		(width 0.088646)
		(layer "In4.Cu")
		(net "M_G_CPU0_SB_DQS_DP<2>")
	)
	(segment
		(start 420.252652 -212.752432)
		(end 419.277292 -212.752432)
		(width 0.18288)
		(layer "In4.Cu")
		(net "M_G_CPU0_SB_DQS_DP<2>")
	)
	(segment
		(start 426.683678 -214.230204)
		(end 426.063664 -213.61019)
		(width 0.18288)
		(layer "In4.Cu")
		(net "M_G_CPU0_SB_DQS_DP<2>")
	)
	(segment
		(start 421.96512 -212.761068)
		(end 421.211248 -212.761068)
		(width 0.18288)
		(layer "In4.Cu")
		(net "M_G_CPU0_SB_DQS_DP<2>")
	)
	(segment
		(start 419.277292 -212.752432)
		(end 418.839396 -213.190328)
		(width 0.18288)
		(layer "In4.Cu")
		(net "M_G_CPU0_SB_DQS_DP<2>")
	)
	(segment
		(start 385.707636 -232.204006)
		(end 385.698746 -232.209086)
		(width 0.088646)
		(layer "In4.Cu")
		(net "M_G_CPU0_SB_DQS_DP<2>")
	)
	(segment
		(start 385.713732 -232.20045)
		(end 385.707636 -232.204006)
		(width 0.088646)
		(layer "In4.Cu")
		(net "M_G_CPU0_SB_DQS_DP<2>")
	)
	(segment
		(start 377.749308 -232.528364)
		(end 377.436634 -232.528364)
		(width 0.088646)
		(layer "In4.Cu")
		(net "M_G_CPU0_SB_DQS_DP<2>")
	)
	(segment
		(start 405.970232 -213.3981)
		(end 391.566908 -227.801424)
		(width 0.18288)
		(layer "In4.Cu")
		(net "M_G_CPU0_SB_DQS_DP<2>")
	)
	(segment
		(start 435.823614 -210.066636)
		(end 435.575202 -209.818224)
		(width 0.18288)
		(layer "In4.Cu")
		(net "M_G_CPU0_SB_DQS_DP<2>")
	)
	(segment
		(start 386.929884 -230.086662)
		(end 386.929884 -230.096568)
		(width 0.088646)
		(layer "In4.Cu")
		(net "M_G_CPU0_SB_DQS_DP<2>")
	)
	(segment
		(start 425.312078 -213.61019)
		(end 425.02836 -213.893908)
		(width 0.18288)
		(layer "In4.Cu")
		(net "M_G_CPU0_SB_DQS_DP<2>")
	)
	(segment
		(start 391.566908 -227.801424)
		(end 388.71271 -227.801424)
		(width 0.18288)
		(layer "In4.Cu")
		(net "M_G_CPU0_SB_DQS_DP<2>")
	)
	(segment
		(start 385.520184 -232.528364)
		(end 385.520184 -232.53827)
		(width 0.088646)
		(layer "In4.Cu")
		(net "M_G_CPU0_SB_DQS_DP<2>")
	)
	(segment
		(start 435.575202 -209.818224)
		(end 435.144164 -209.818224)
		(width 0.18288)
		(layer "In4.Cu")
		(net "M_G_CPU0_SB_DQS_DP<2>")
	)
	(segment
		(start 417.950396 -213.190328)
		(end 417.74364 -212.983572)
		(width 0.18288)
		(layer "In4.Cu")
		(net "M_G_CPU0_SB_DQS_DP<2>")
	)
	(segment
		(start 384.297428 -233.017568)
		(end 384.297682 -233.018076)
		(width 0.088646)
		(layer "In4.Cu")
		(net "M_G_CPU0_SB_DQS_DP<2>")
	)
	(segment
		(start 420.544244 -213.044024)
		(end 420.252652 -212.752432)
		(width 0.18288)
		(layer "In4.Cu")
		(net "M_G_CPU0_SB_DQS_DP<2>")
	)
	(segment
		(start 412.612332 -213.363556)
		(end 412.164784 -212.916008)
		(width 0.18288)
		(layer "In4.Cu")
		(net "M_G_CPU0_SB_DQS_DP<2>")
	)
	(segment
		(start 387.114542 -229.763828)
		(end 387.11378 -229.764336)
		(width 0.088646)
		(layer "In4.Cu")
		(net "M_G_CPU0_SB_DQS_DP<2>")
	)
	(segment
		(start 387.111748 -229.765352)
		(end 387.109716 -229.766622)
		(width 0.088646)
		(layer "In4.Cu")
		(net "M_G_CPU0_SB_DQS_DP<2>")
	)
	(segment
		(start 431.307494 -211.942426)
		(end 430.347374 -211.942426)
		(width 0.18288)
		(layer "In4.Cu")
		(net "M_G_CPU0_SB_DQS_DP<2>")
	)
	(segment
		(start 427.555152 -214.230204)
		(end 426.683678 -214.230204)
		(width 0.18288)
		(layer "In4.Cu")
		(net "M_G_CPU0_SB_DQS_DP<2>")
	)
	(segment
		(start 380.538736 -233.017822)
		(end 380.528322 -233.023918)
		(width 0.088646)
		(layer "In4.Cu")
		(net "M_G_CPU0_SB_DQS_DP<2>")
	)
	(segment
		(start 387.11378 -229.764336)
		(end 387.111748 -229.765352)
		(width 0.088646)
		(layer "In4.Cu")
		(net "M_G_CPU0_SB_DQS_DP<2>")
	)
	(segment
		(start 388.689342 -227.801424)
		(end 388.629398 -227.74148)
		(width 0.088646)
		(layer "In4.Cu")
		(net "M_G_CPU0_SB_DQS_DP<2>")
	)
	(segment
		(start 425.02836 -213.893908)
		(end 424.644312 -213.893908)
		(width 0.18288)
		(layer "In4.Cu")
		(net "M_G_CPU0_SB_DQS_DP<2>")
	)
	(segment
		(start 387.921246 -228.957124)
		(end 387.114542 -229.763828)
		(width 0.088646)
		(layer "In4.Cu")
		(net "M_G_CPU0_SB_DQS_DP<2>")
	)
	(segment
		(start 424.644312 -213.893908)
		(end 424.35272 -213.602316)
		(width 0.18288)
		(layer "In4.Cu")
		(net "M_G_CPU0_SB_DQS_DP<2>")
	)
	(segment
		(start 380.927864 -233.026458)
		(end 380.913132 -233.017822)
		(width 0.088646)
		(layer "In4.Cu")
		(net "M_G_CPU0_SB_DQS_DP<2>")
	)
	(segment
		(start 386.177536 -231.39019)
		(end 386.168646 -231.39527)
		(width 0.088646)
		(layer "In4.Cu")
		(net "M_G_CPU0_SB_DQS_DP<2>")
	)
	(segment
		(start 412.164784 -212.916008)
		(end 408.99842 -212.916008)
		(width 0.18288)
		(layer "In4.Cu")
		(net "M_G_CPU0_SB_DQS_DP<2>")
	)
	(segment
		(start 414.791144 -213.067646)
		(end 413.95142 -213.067646)
		(width 0.18288)
		(layer "In4.Cu")
		(net "M_G_CPU0_SB_DQS_DP<2>")
	)
	(segment
		(start 386.646674 -230.576628)
		(end 386.638546 -230.5812)
		(width 0.088646)
		(layer "In4.Cu")
		(net "M_G_CPU0_SB_DQS_DP<2>")
	)
	(segment
		(start 422.806368 -213.602316)
		(end 421.96512 -212.761068)
		(width 0.18288)
		(layer "In4.Cu")
		(net "M_G_CPU0_SB_DQS_DP<2>")
	)
	(segment
		(start 416.359848 -213.423246)
		(end 415.146744 -213.423246)
		(width 0.18288)
		(layer "In4.Cu")
		(net "M_G_CPU0_SB_DQS_DP<2>")
	)
	(segment
		(start 388.629398 -227.74148)
		(end 388.423404 -227.74148)
		(width 0.088646)
		(layer "In4.Cu")
		(net "M_G_CPU0_SB_DQS_DP<2>")
	)
	(segment
		(start 418.839396 -213.190328)
		(end 417.950396 -213.190328)
		(width 0.18288)
		(layer "In4.Cu")
		(net "M_G_CPU0_SB_DQS_DP<2>")
	)
	(segment
		(start 388.423404 -227.74148)
		(end 387.921246 -228.243638)
		(width 0.088646)
		(layer "In4.Cu")
		(net "M_G_CPU0_SB_DQS_DP<2>")
	)
	(segment
		(start 421.211248 -212.761068)
		(end 420.928292 -213.044024)
		(width 0.18288)
		(layer "In4.Cu")
		(net "M_G_CPU0_SB_DQS_DP<2>")
	)
	(segment
		(start 435.144164 -209.818224)
		(end 434.89753 -209.57159)
		(width 0.18288)
		(layer "In4.Cu")
		(net "M_G_CPU0_SB_DQS_DP<2>")
	)
	(segment
		(start 386.459984 -230.900478)
		(end 386.459984 -230.914702)
		(width 0.088646)
		(layer "In4.Cu")
		(net "M_G_CPU0_SB_DQS_DP<2>")
	)
	(segment
		(start 379.598682 -233.017822)
		(end 379.58395 -233.026458)
		(width 0.088646)
		(layer "In4.Cu")
		(net "M_G_CPU0_SB_DQS_DP<2>")
	)
	(segment
		(start 428.065184 -213.720172)
		(end 427.555152 -214.230204)
		(width 0.18288)
		(layer "In4.Cu")
		(net "M_G_CPU0_SB_DQS_DP<2>")
	)
	(segment
		(start 432.714146 -211.007198)
		(end 432.242722 -211.007198)
		(width 0.18288)
		(layer "In4.Cu")
		(net "M_G_CPU0_SB_DQS_DP<2>")
	)
	(segment
		(start 377.81484 -232.593896)
		(end 377.749308 -232.528364)
		(width 0.088646)
		(layer "In4.Cu")
		(net "M_G_CPU0_SB_DQS_DP<2>")
	)
	(segment
		(start 424.35272 -213.602316)
		(end 422.806368 -213.602316)
		(width 0.18288)
		(layer "In4.Cu")
		(net "M_G_CPU0_SB_DQS_DP<2>")
	)
	(segment
		(start 387.109716 -229.766622)
		(end 387.108446 -229.767384)
		(width 0.088646)
		(layer "In4.Cu")
		(net "M_G_CPU0_SB_DQS_DP<2>")
	)
	(segment
		(start 415.146744 -213.423246)
		(end 414.791144 -213.067646)
		(width 0.18288)
		(layer "In4.Cu")
		(net "M_G_CPU0_SB_DQS_DP<2>")
	)
	(segment
		(start 434.149754 -209.57159)
		(end 432.714146 -211.007198)
		(width 0.18288)
		(layer "In4.Cu")
		(net "M_G_CPU0_SB_DQS_DP<2>")
	)
	(segment
		(start 384.67284 -233.017568)
		(end 384.672586 -233.017568)
		(width 0.088646)
		(layer "In4.Cu")
		(net "M_G_CPU0_SB_DQS_DP<2>")
	)
	(segment
		(start 430.347374 -211.942426)
		(end 428.569628 -213.720172)
		(width 0.18288)
		(layer "In4.Cu")
		(net "M_G_CPU0_SB_DQS_DP<2>")
	)
	(segment
		(start 413.65551 -213.363556)
		(end 412.612332 -213.363556)
		(width 0.18288)
		(layer "In4.Cu")
		(net "M_G_CPU0_SB_DQS_DP<2>")
	)
	(segment
		(start 420.928292 -213.044024)
		(end 420.544244 -213.044024)
		(width 0.18288)
		(layer "In4.Cu")
		(net "M_G_CPU0_SB_DQS_DP<2>")
	)
	(segment
		(start 388.71271 -227.801424)
		(end 388.689342 -227.801424)
		(width 0.088646)
		(layer "In4.Cu")
		(net "M_G_CPU0_SB_DQS_DP<2>")
	)
	(arc
		(start 380.528322 -233.023918)
		(mid 380.24989 -233.093764)
		(end 379.973078 -233.017822)
		(width 0.088646)
		(layer "In4.Cu")
		(net "M_G_CPU0_SB_DQS_DP<2>")
	)
	(arc
		(start 378.093478 -233.017822)
		(mid 377.909887 -232.847687)
		(end 377.817634 -232.614978)
		(width 0.088646)
		(layer "In4.Cu")
		(net "M_G_CPU0_SB_DQS_DP<2>")
	)
	(arc
		(start 385.990084 -231.714548)
		(mid 385.916168 -231.99405)
		(end 385.713732 -232.20045)
		(width 0.088646)
		(layer "In4.Cu")
		(net "M_G_CPU0_SB_DQS_DP<2>")
	)
	(arc
		(start 385.520184 -232.53827)
		(mid 385.442073 -232.815219)
		(end 385.237736 -233.017822)
		(width 0.088646)
		(layer "In4.Cu")
		(net "M_G_CPU0_SB_DQS_DP<2>")
	)
	(arc
		(start 386.459984 -230.914702)
		(mid 386.380843 -231.189325)
		(end 386.177536 -231.39019)
		(width 0.088646)
		(layer "In4.Cu")
		(net "M_G_CPU0_SB_DQS_DP<2>")
	)
	(arc
		(start 386.168646 -231.39527)
		(mid 386.037732 -231.53163)
		(end 385.990084 -231.714548)
		(width 0.088646)
		(layer "In4.Cu")
		(net "M_G_CPU0_SB_DQS_DP<2>")
	)
	(arc
		(start 384.297682 -233.018076)
		(mid 384.015061 -233.093691)
		(end 383.732532 -233.017822)
		(width 0.088646)
		(layer "In4.Cu")
		(net "M_G_CPU0_SB_DQS_DP<2>")
	)
	(arc
		(start 382.792732 -233.017822)
		(mid 382.605534 -232.967679)
		(end 382.418336 -233.017822)
		(width 0.088646)
		(layer "In4.Cu")
		(net "M_G_CPU0_SB_DQS_DP<2>")
	)
	(arc
		(start 379.58395 -233.026458)
		(mid 379.307475 -233.093778)
		(end 379.033278 -233.017822)
		(width 0.088646)
		(layer "In4.Cu")
		(net "M_G_CPU0_SB_DQS_DP<2>")
	)
	(arc
		(start 382.418336 -233.017822)
		(mid 382.135634 -233.093598)
		(end 381.852932 -233.017822)
		(width 0.088646)
		(layer "In4.Cu")
		(net "M_G_CPU0_SB_DQS_DP<2>")
	)
	(arc
		(start 386.929884 -230.096568)
		(mid 386.851773 -230.373517)
		(end 386.647436 -230.57612)
		(width 0.088646)
		(layer "In4.Cu")
		(net "M_G_CPU0_SB_DQS_DP<2>")
	)
	(arc
		(start 381.852932 -233.017822)
		(mid 381.665734 -232.967679)
		(end 381.478536 -233.017822)
		(width 0.088646)
		(layer "In4.Cu")
		(net "M_G_CPU0_SB_DQS_DP<2>")
	)
	(arc
		(start 379.033278 -233.017822)
		(mid 378.84608 -232.967679)
		(end 378.658882 -233.017822)
		(width 0.088646)
		(layer "In4.Cu")
		(net "M_G_CPU0_SB_DQS_DP<2>")
	)
	(arc
		(start 383.358136 -233.017822)
		(mid 383.075434 -233.093598)
		(end 382.792732 -233.017822)
		(width 0.088646)
		(layer "In4.Cu")
		(net "M_G_CPU0_SB_DQS_DP<2>")
	)
	(arc
		(start 378.64415 -233.026458)
		(mid 378.367675 -233.093778)
		(end 378.093478 -233.017822)
		(width 0.088646)
		(layer "In4.Cu")
		(net "M_G_CPU0_SB_DQS_DP<2>")
	)
	(arc
		(start 385.698746 -232.209086)
		(mid 385.567832 -232.345446)
		(end 385.520184 -232.528364)
		(width 0.088646)
		(layer "In4.Cu")
		(net "M_G_CPU0_SB_DQS_DP<2>")
	)
	(arc
		(start 386.638546 -230.5812)
		(mid 386.507632 -230.71756)
		(end 386.459984 -230.900478)
		(width 0.088646)
		(layer "In4.Cu")
		(net "M_G_CPU0_SB_DQS_DP<2>")
	)
	(arc
		(start 387.108446 -229.767384)
		(mid 386.977532 -229.903744)
		(end 386.929884 -230.086662)
		(width 0.088646)
		(layer "In4.Cu")
		(net "M_G_CPU0_SB_DQS_DP<2>")
	)
	(arc
		(start 385.237736 -233.017822)
		(mid 384.955034 -233.093598)
		(end 384.672332 -233.017822)
		(width 0.088646)
		(layer "In4.Cu")
		(net "M_G_CPU0_SB_DQS_DP<2>")
	)
	(arc
		(start 384.672586 -233.017568)
		(mid 384.485024 -232.967332)
		(end 384.297428 -233.017568)
		(width 0.088646)
		(layer "In4.Cu")
		(net "M_G_CPU0_SB_DQS_DP<2>")
	)
	(arc
		(start 379.973078 -233.017822)
		(mid 379.78588 -232.967679)
		(end 379.598682 -233.017822)
		(width 0.088646)
		(layer "In4.Cu")
		(net "M_G_CPU0_SB_DQS_DP<2>")
	)
	(arc
		(start 381.478536 -233.017822)
		(mid 381.204337 -233.093657)
		(end 380.927864 -233.026458)
		(width 0.088646)
		(layer "In4.Cu")
		(net "M_G_CPU0_SB_DQS_DP<2>")
	)
	(arc
		(start 383.732532 -233.017822)
		(mid 383.545334 -232.967679)
		(end 383.358136 -233.017822)
		(width 0.088646)
		(layer "In4.Cu")
		(net "M_G_CPU0_SB_DQS_DP<2>")
	)
	(arc
		(start 380.913132 -233.017822)
		(mid 380.725934 -232.967679)
		(end 380.538736 -233.017822)
		(width 0.088646)
		(layer "In4.Cu")
		(net "M_G_CPU0_SB_DQS_DP<2>")
	)
	(arc
		(start 377.817634 -232.614978)
		(mid 377.816138 -232.60445)
		(end 377.81484 -232.593896)
		(width 0.088646)
		(layer "In4.Cu")
		(net "M_G_CPU0_SB_DQS_DP<2>")
	)
	(segment
		(start 443.035436 -219.545408)
		(end 443.4459 -219.134944)
		(width 0.20066)
		(layer "F.Cu")
		(net "M_G_CPU0_SB_DQS_DP<1>")
	)
	(segment
		(start 442.362336 -219.847922)
		(end 442.66485 -219.545408)
		(width 0.20066)
		(layer "F.Cu")
		(net "M_G_CPU0_SB_DQS_DP<1>")
	)
	(segment
		(start 442.66485 -219.545408)
		(end 443.035436 -219.545408)
		(width 0.20066)
		(layer "F.Cu")
		(net "M_G_CPU0_SB_DQS_DP<1>")
	)
	(segment
		(start 443.923674 -219.41663)
		(end 444.472314 -219.41663)
		(width 0.20066)
		(layer "F.Cu")
		(net "M_G_CPU0_SB_DQS_DP<1>")
	)
	(segment
		(start 438.773316 -219.59062)
		(end 439.459116 -219.59062)
		(width 0.20066)
		(layer "F.Cu")
		(net "M_G_CPU0_SB_DQS_DP<1>")
	)
	(segment
		(start 442.032898 -219.841826)
		(end 442.038994 -219.847922)
		(width 0.1016)
		(layer "F.Cu")
		(net "M_G_CPU0_SB_DQS_DP<1>")
	)
	(segment
		(start 439.459116 -219.59062)
		(end 439.710322 -219.841826)
		(width 0.20066)
		(layer "F.Cu")
		(net "M_G_CPU0_SB_DQS_DP<1>")
	)
	(segment
		(start 437.517794 -219.41663)
		(end 437.758332 -219.176092)
		(width 0.20066)
		(layer "F.Cu")
		(net "M_G_CPU0_SB_DQS_DP<1>")
	)
	(segment
		(start 439.849768 -219.841826)
		(end 439.875676 -219.841826)
		(width 0.101854)
		(layer "F.Cu")
		(net "M_G_CPU0_SB_DQS_DP<1>")
	)
	(segment
		(start 435.823614 -219.41663)
		(end 436.928514 -219.41663)
		(width 0.20066)
		(layer "F.Cu")
		(net "M_G_CPU0_SB_DQS_DP<1>")
	)
	(segment
		(start 443.4459 -219.134944)
		(end 443.641988 -219.134944)
		(width 0.20066)
		(layer "F.Cu")
		(net "M_G_CPU0_SB_DQS_DP<1>")
	)
	(segment
		(start 438.358788 -219.176092)
		(end 438.773316 -219.59062)
		(width 0.20066)
		(layer "F.Cu")
		(net "M_G_CPU0_SB_DQS_DP<1>")
	)
	(segment
		(start 375.087134 -235.506006)
		(end 375.08688 -235.505752)
		(width 0.20066)
		(layer "F.Cu")
		(net "M_G_CPU0_SB_DQS_DP<1>")
	)
	(segment
		(start 439.710322 -219.841826)
		(end 439.849768 -219.841826)
		(width 0.20066)
		(layer "F.Cu")
		(net "M_G_CPU0_SB_DQS_DP<1>")
	)
	(segment
		(start 375.08688 -235.505752)
		(end 375.08688 -234.970066)
		(width 0.20066)
		(layer "F.Cu")
		(net "M_G_CPU0_SB_DQS_DP<1>")
	)
	(segment
		(start 436.928514 -219.41663)
		(end 437.517794 -219.41663)
		(width 0.20066)
		(layer "F.Cu")
		(net "M_G_CPU0_SB_DQS_DP<1>")
	)
	(segment
		(start 442.038994 -219.847922)
		(end 442.362336 -219.847922)
		(width 0.20066)
		(layer "F.Cu")
		(net "M_G_CPU0_SB_DQS_DP<1>")
	)
	(segment
		(start 439.875676 -219.841826)
		(end 442.032898 -219.841826)
		(width 0.1016)
		(layer "F.Cu")
		(net "M_G_CPU0_SB_DQS_DP<1>")
	)
	(segment
		(start 437.758332 -219.176092)
		(end 438.358788 -219.176092)
		(width 0.20066)
		(layer "F.Cu")
		(net "M_G_CPU0_SB_DQS_DP<1>")
	)
	(segment
		(start 443.641988 -219.134944)
		(end 443.923674 -219.41663)
		(width 0.20066)
		(layer "F.Cu")
		(net "M_G_CPU0_SB_DQS_DP<1>")
	)
	(segment
		(start 374.899682 -234.645708)
		(end 374.898158 -234.64647)
		(width 0.088646)
		(layer "In6.Cu")
		(net "M_G_CPU0_SB_DQS_DP<1>")
	)
	(segment
		(start 424.386502 -221.285562)
		(end 422.878504 -221.285562)
		(width 0.18288)
		(layer "In6.Cu")
		(net "M_G_CPU0_SB_DQS_DP<1>")
	)
	(segment
		(start 385.238244 -234.6452)
		(end 385.237482 -234.645708)
		(width 0.088646)
		(layer "In6.Cu")
		(net "M_G_CPU0_SB_DQS_DP<1>")
	)
	(segment
		(start 425.29125 -221.263972)
		(end 425.01439 -221.540832)
		(width 0.18288)
		(layer "In6.Cu")
		(net "M_G_CPU0_SB_DQS_DP<1>")
	)
	(segment
		(start 374.898158 -234.64647)
		(end 374.890792 -234.650788)
		(width 0.088646)
		(layer "In6.Cu")
		(net "M_G_CPU0_SB_DQS_DP<1>")
	)
	(segment
		(start 376.779282 -234.645708)
		(end 376.76455 -234.654344)
		(width 0.088646)
		(layer "In6.Cu")
		(net "M_G_CPU0_SB_DQS_DP<1>")
	)
	(segment
		(start 390.984232 -233.130852)
		(end 388.783322 -233.130852)
		(width 0.18288)
		(layer "In6.Cu")
		(net "M_G_CPU0_SB_DQS_DP<1>")
	)
	(segment
		(start 406.46858 -219.85478)
		(end 406.34412 -219.73032)
		(width 0.18288)
		(layer "In6.Cu")
		(net "M_G_CPU0_SB_DQS_DP<1>")
	)
	(segment
		(start 422.878504 -221.285562)
		(end 422.024302 -222.139764)
		(width 0.18288)
		(layer "In6.Cu")
		(net "M_G_CPU0_SB_DQS_DP<1>")
	)
	(segment
		(start 421.204136 -222.139764)
		(end 420.95293 -222.39097)
		(width 0.18288)
		(layer "In6.Cu")
		(net "M_G_CPU0_SB_DQS_DP<1>")
	)
	(segment
		(start 388.521702 -233.131106)
		(end 387.978142 -233.131106)
		(width 0.18288)
		(layer "In6.Cu")
		(net "M_G_CPU0_SB_DQS_DP<1>")
	)
	(segment
		(start 420.549324 -222.39097)
		(end 420.282116 -222.123762)
		(width 0.18288)
		(layer "In6.Cu")
		(net "M_G_CPU0_SB_DQS_DP<1>")
	)
	(segment
		(start 375.839482 -234.645708)
		(end 375.82475 -234.654344)
		(width 0.088646)
		(layer "In6.Cu")
		(net "M_G_CPU0_SB_DQS_DP<1>")
	)
	(segment
		(start 408.608784 -219.73032)
		(end 407.13914 -219.73032)
		(width 0.18288)
		(layer "In6.Cu")
		(net "M_G_CPU0_SB_DQS_DP<1>")
	)
	(segment
		(start 387.918198 -233.071162)
		(end 387.810756 -233.071162)
		(width 0.088646)
		(layer "In6.Cu")
		(net "M_G_CPU0_SB_DQS_DP<1>")
	)
	(segment
		(start 434.924708 -219.138246)
		(end 434.659786 -218.873324)
		(width 0.18288)
		(layer "In6.Cu")
		(net "M_G_CPU0_SB_DQS_DP<1>")
	)
	(segment
		(start 417.776406 -222.123762)
		(end 414.870646 -220.92031)
		(width 0.18288)
		(layer "In6.Cu")
		(net "M_G_CPU0_SB_DQS_DP<1>")
	)
	(segment
		(start 413.98317 -220.208856)
		(end 413.596582 -219.822268)
		(width 0.18288)
		(layer "In6.Cu")
		(net "M_G_CPU0_SB_DQS_DP<1>")
	)
	(segment
		(start 379.598936 -234.645708)
		(end 379.588522 -234.651804)
		(width 0.088646)
		(layer "In6.Cu")
		(net "M_G_CPU0_SB_DQS_DP<1>")
	)
	(segment
		(start 427.193456 -220.535246)
		(end 426.75302 -220.535246)
		(width 0.18288)
		(layer "In6.Cu")
		(net "M_G_CPU0_SB_DQS_DP<1>")
	)
	(segment
		(start 430.95164 -219.816426)
		(end 427.912276 -219.816426)
		(width 0.18288)
		(layer "In6.Cu")
		(net "M_G_CPU0_SB_DQS_DP<1>")
	)
	(segment
		(start 420.282116 -222.123762)
		(end 417.776406 -222.123762)
		(width 0.18288)
		(layer "In6.Cu")
		(net "M_G_CPU0_SB_DQS_DP<1>")
	)
	(segment
		(start 420.95293 -222.39097)
		(end 420.549324 -222.39097)
		(width 0.18288)
		(layer "In6.Cu")
		(net "M_G_CPU0_SB_DQS_DP<1>")
	)
	(segment
		(start 385.237482 -234.645708)
		(end 385.22275 -234.654344)
		(width 0.088646)
		(layer "In6.Cu")
		(net "M_G_CPU0_SB_DQS_DP<1>")
	)
	(segment
		(start 407.13914 -219.73032)
		(end 407.01468 -219.85478)
		(width 0.18288)
		(layer "In6.Cu")
		(net "M_G_CPU0_SB_DQS_DP<1>")
	)
	(segment
		(start 406.34412 -219.73032)
		(end 404.384764 -219.73032)
		(width 0.18288)
		(layer "In6.Cu")
		(net "M_G_CPU0_SB_DQS_DP<1>")
	)
	(segment
		(start 414.159192 -220.208856)
		(end 413.98317 -220.208856)
		(width 0.18288)
		(layer "In6.Cu")
		(net "M_G_CPU0_SB_DQS_DP<1>")
	)
	(segment
		(start 380.538482 -234.645708)
		(end 380.528068 -234.651804)
		(width 0.088646)
		(layer "In6.Cu")
		(net "M_G_CPU0_SB_DQS_DP<1>")
	)
	(segment
		(start 388.783322 -233.130852)
		(end 388.521702 -233.131106)
		(width 0.18288)
		(layer "In6.Cu")
		(net "M_G_CPU0_SB_DQS_DP<1>")
	)
	(segment
		(start 434.659786 -218.873324)
		(end 431.894742 -218.873324)
		(width 0.18288)
		(layer "In6.Cu")
		(net "M_G_CPU0_SB_DQS_DP<1>")
	)
	(segment
		(start 385.707636 -233.831892)
		(end 385.698746 -233.836972)
		(width 0.088646)
		(layer "In6.Cu")
		(net "M_G_CPU0_SB_DQS_DP<1>")
	)
	(segment
		(start 403.436328 -220.678756)
		(end 390.984232 -233.130852)
		(width 0.18288)
		(layer "In6.Cu")
		(net "M_G_CPU0_SB_DQS_DP<1>")
	)
	(segment
		(start 403.61235 -220.678756)
		(end 403.436328 -220.678756)
		(width 0.18288)
		(layer "In6.Cu")
		(net "M_G_CPU0_SB_DQS_DP<1>")
	)
	(segment
		(start 414.870646 -220.92031)
		(end 414.159192 -220.208856)
		(width 0.18288)
		(layer "In6.Cu")
		(net "M_G_CPU0_SB_DQS_DP<1>")
	)
	(segment
		(start 424.641772 -221.540832)
		(end 424.386502 -221.285562)
		(width 0.18288)
		(layer "In6.Cu")
		(net "M_G_CPU0_SB_DQS_DP<1>")
	)
	(segment
		(start 374.773952 -234.970066)
		(end 375.08688 -234.970066)
		(width 0.088646)
		(layer "In6.Cu")
		(net "M_G_CPU0_SB_DQS_DP<1>")
	)
	(segment
		(start 413.596582 -219.822268)
		(end 413.596582 -219.646246)
		(width 0.18288)
		(layer "In6.Cu")
		(net "M_G_CPU0_SB_DQS_DP<1>")
	)
	(segment
		(start 409.170378 -220.291914)
		(end 408.608784 -219.73032)
		(width 0.18288)
		(layer "In6.Cu")
		(net "M_G_CPU0_SB_DQS_DP<1>")
	)
	(segment
		(start 403.998684 -220.1164)
		(end 403.998684 -220.292422)
		(width 0.18288)
		(layer "In6.Cu")
		(net "M_G_CPU0_SB_DQS_DP<1>")
	)
	(segment
		(start 407.01468 -219.85478)
		(end 406.46858 -219.85478)
		(width 0.18288)
		(layer "In6.Cu")
		(net "M_G_CPU0_SB_DQS_DP<1>")
	)
	(segment
		(start 426.024294 -221.263972)
		(end 425.29125 -221.263972)
		(width 0.18288)
		(layer "In6.Cu")
		(net "M_G_CPU0_SB_DQS_DP<1>")
	)
	(segment
		(start 384.297682 -234.645708)
		(end 384.287268 -234.651804)
		(width 0.088646)
		(layer "In6.Cu")
		(net "M_G_CPU0_SB_DQS_DP<1>")
	)
	(segment
		(start 435.823614 -219.41663)
		(end 435.54523 -219.138246)
		(width 0.18288)
		(layer "In6.Cu")
		(net "M_G_CPU0_SB_DQS_DP<1>")
	)
	(segment
		(start 381.478536 -234.645708)
		(end 381.468122 -234.651804)
		(width 0.088646)
		(layer "In6.Cu")
		(net "M_G_CPU0_SB_DQS_DP<1>")
	)
	(segment
		(start 427.912276 -219.816426)
		(end 427.193456 -220.535246)
		(width 0.18288)
		(layer "In6.Cu")
		(net "M_G_CPU0_SB_DQS_DP<1>")
	)
	(segment
		(start 378.658882 -234.645708)
		(end 378.64415 -234.654344)
		(width 0.088646)
		(layer "In6.Cu")
		(net "M_G_CPU0_SB_DQS_DP<1>")
	)
	(segment
		(start 385.243578 -234.642152)
		(end 385.238244 -234.6452)
		(width 0.088646)
		(layer "In6.Cu")
		(net "M_G_CPU0_SB_DQS_DP<1>")
	)
	(segment
		(start 435.54523 -219.138246)
		(end 434.924708 -219.138246)
		(width 0.18288)
		(layer "In6.Cu")
		(net "M_G_CPU0_SB_DQS_DP<1>")
	)
	(segment
		(start 387.810756 -233.071162)
		(end 387.567932 -233.313986)
		(width 0.088646)
		(layer "In6.Cu")
		(net "M_G_CPU0_SB_DQS_DP<1>")
	)
	(segment
		(start 412.933642 -218.983306)
		(end 411.807914 -218.983306)
		(width 0.18288)
		(layer "In6.Cu")
		(net "M_G_CPU0_SB_DQS_DP<1>")
	)
	(segment
		(start 425.01439 -221.540832)
		(end 424.641772 -221.540832)
		(width 0.18288)
		(layer "In6.Cu")
		(net "M_G_CPU0_SB_DQS_DP<1>")
	)
	(segment
		(start 411.807914 -218.983306)
		(end 410.499306 -220.291914)
		(width 0.18288)
		(layer "In6.Cu")
		(net "M_G_CPU0_SB_DQS_DP<1>")
	)
	(segment
		(start 431.894742 -218.873324)
		(end 430.95164 -219.816426)
		(width 0.18288)
		(layer "In6.Cu")
		(net "M_G_CPU0_SB_DQS_DP<1>")
	)
	(segment
		(start 404.384764 -219.73032)
		(end 403.998684 -220.1164)
		(width 0.18288)
		(layer "In6.Cu")
		(net "M_G_CPU0_SB_DQS_DP<1>")
	)
	(segment
		(start 413.596582 -219.646246)
		(end 412.933642 -218.983306)
		(width 0.18288)
		(layer "In6.Cu")
		(net "M_G_CPU0_SB_DQS_DP<1>")
	)
	(segment
		(start 387.978142 -233.131106)
		(end 387.918198 -233.071162)
		(width 0.088646)
		(layer "In6.Cu")
		(net "M_G_CPU0_SB_DQS_DP<1>")
	)
	(segment
		(start 374.716802 -234.912916)
		(end 374.773952 -234.970066)
		(width 0.088646)
		(layer "In6.Cu")
		(net "M_G_CPU0_SB_DQS_DP<1>")
	)
	(segment
		(start 426.75302 -220.535246)
		(end 426.024294 -221.263972)
		(width 0.18288)
		(layer "In6.Cu")
		(net "M_G_CPU0_SB_DQS_DP<1>")
	)
	(segment
		(start 422.024302 -222.139764)
		(end 421.204136 -222.139764)
		(width 0.18288)
		(layer "In6.Cu")
		(net "M_G_CPU0_SB_DQS_DP<1>")
	)
	(segment
		(start 403.998684 -220.292422)
		(end 403.61235 -220.678756)
		(width 0.18288)
		(layer "In6.Cu")
		(net "M_G_CPU0_SB_DQS_DP<1>")
	)
	(segment
		(start 410.499306 -220.291914)
		(end 409.170378 -220.291914)
		(width 0.18288)
		(layer "In6.Cu")
		(net "M_G_CPU0_SB_DQS_DP<1>")
	)
	(arc
		(start 380.912878 -234.645708)
		(mid 380.72568 -234.595565)
		(end 380.538482 -234.645708)
		(width 0.088646)
		(layer "In6.Cu")
		(net "M_G_CPU0_SB_DQS_DP<1>")
	)
	(arc
		(start 374.890792 -234.650788)
		(mid 374.774983 -234.762717)
		(end 374.716802 -234.912916)
		(width 0.088646)
		(layer "In6.Cu")
		(net "M_G_CPU0_SB_DQS_DP<1>")
	)
	(arc
		(start 377.719082 -234.645708)
		(mid 377.43638 -234.721484)
		(end 377.153678 -234.645708)
		(width 0.088646)
		(layer "In6.Cu")
		(net "M_G_CPU0_SB_DQS_DP<1>")
	)
	(arc
		(start 381.852932 -234.645708)
		(mid 381.665734 -234.595565)
		(end 381.478536 -234.645708)
		(width 0.088646)
		(layer "In6.Cu")
		(net "M_G_CPU0_SB_DQS_DP<1>")
	)
	(arc
		(start 385.22275 -234.654344)
		(mid 384.946275 -234.721664)
		(end 384.672078 -234.645708)
		(width 0.088646)
		(layer "In6.Cu")
		(net "M_G_CPU0_SB_DQS_DP<1>")
	)
	(arc
		(start 383.732532 -234.645708)
		(mid 383.545334 -234.595565)
		(end 383.358136 -234.645708)
		(width 0.088646)
		(layer "In6.Cu")
		(net "M_G_CPU0_SB_DQS_DP<1>")
	)
	(arc
		(start 379.033278 -234.645708)
		(mid 378.84608 -234.595565)
		(end 378.658882 -234.645708)
		(width 0.088646)
		(layer "In6.Cu")
		(net "M_G_CPU0_SB_DQS_DP<1>")
	)
	(arc
		(start 387.567932 -233.313986)
		(mid 387.521877 -233.367113)
		(end 387.483858 -233.426254)
		(width 0.088646)
		(layer "In6.Cu")
		(net "M_G_CPU0_SB_DQS_DP<1>")
	)
	(arc
		(start 380.528068 -234.651804)
		(mid 380.24989 -234.721527)
		(end 379.973332 -234.645708)
		(width 0.088646)
		(layer "In6.Cu")
		(net "M_G_CPU0_SB_DQS_DP<1>")
	)
	(arc
		(start 387.483858 -233.426254)
		(mid 387.231879 -233.686875)
		(end 386.882132 -233.782108)
		(width 0.088646)
		(layer "In6.Cu")
		(net "M_G_CPU0_SB_DQS_DP<1>")
	)
	(arc
		(start 378.093478 -234.645708)
		(mid 377.90628 -234.595565)
		(end 377.719082 -234.645708)
		(width 0.088646)
		(layer "In6.Cu")
		(net "M_G_CPU0_SB_DQS_DP<1>")
	)
	(arc
		(start 376.76455 -234.654344)
		(mid 376.488075 -234.721664)
		(end 376.213878 -234.645708)
		(width 0.088646)
		(layer "In6.Cu")
		(net "M_G_CPU0_SB_DQS_DP<1>")
	)
	(arc
		(start 386.622798 -233.844846)
		(mid 386.350755 -233.90732)
		(end 386.082032 -233.831892)
		(width 0.088646)
		(layer "In6.Cu")
		(net "M_G_CPU0_SB_DQS_DP<1>")
	)
	(arc
		(start 386.082032 -233.831892)
		(mid 385.894834 -233.781749)
		(end 385.707636 -233.831892)
		(width 0.088646)
		(layer "In6.Cu")
		(net "M_G_CPU0_SB_DQS_DP<1>")
	)
	(arc
		(start 383.358136 -234.645708)
		(mid 383.075434 -234.721484)
		(end 382.792732 -234.645708)
		(width 0.088646)
		(layer "In6.Cu")
		(net "M_G_CPU0_SB_DQS_DP<1>")
	)
	(arc
		(start 376.213878 -234.645708)
		(mid 376.02668 -234.595565)
		(end 375.839482 -234.645708)
		(width 0.088646)
		(layer "In6.Cu")
		(net "M_G_CPU0_SB_DQS_DP<1>")
	)
	(arc
		(start 379.973332 -234.645708)
		(mid 379.786134 -234.595565)
		(end 379.598936 -234.645708)
		(width 0.088646)
		(layer "In6.Cu")
		(net "M_G_CPU0_SB_DQS_DP<1>")
	)
	(arc
		(start 375.274078 -234.645708)
		(mid 375.08688 -234.595565)
		(end 374.899682 -234.645708)
		(width 0.088646)
		(layer "In6.Cu")
		(net "M_G_CPU0_SB_DQS_DP<1>")
	)
	(arc
		(start 382.418336 -234.645708)
		(mid 382.135634 -234.721484)
		(end 381.852932 -234.645708)
		(width 0.088646)
		(layer "In6.Cu")
		(net "M_G_CPU0_SB_DQS_DP<1>")
	)
	(arc
		(start 386.882132 -233.782108)
		(mid 386.748715 -233.797966)
		(end 386.622798 -233.844846)
		(width 0.088646)
		(layer "In6.Cu")
		(net "M_G_CPU0_SB_DQS_DP<1>")
	)
	(arc
		(start 377.153678 -234.645708)
		(mid 376.96648 -234.595565)
		(end 376.779282 -234.645708)
		(width 0.088646)
		(layer "In6.Cu")
		(net "M_G_CPU0_SB_DQS_DP<1>")
	)
	(arc
		(start 385.698746 -233.836972)
		(mid 385.567832 -233.973332)
		(end 385.520184 -234.15625)
		(width 0.088646)
		(layer "In6.Cu")
		(net "M_G_CPU0_SB_DQS_DP<1>")
	)
	(arc
		(start 385.520184 -234.15625)
		(mid 385.446193 -234.435816)
		(end 385.243578 -234.642152)
		(width 0.088646)
		(layer "In6.Cu")
		(net "M_G_CPU0_SB_DQS_DP<1>")
	)
	(arc
		(start 375.82475 -234.654344)
		(mid 375.548275 -234.721664)
		(end 375.274078 -234.645708)
		(width 0.088646)
		(layer "In6.Cu")
		(net "M_G_CPU0_SB_DQS_DP<1>")
	)
	(arc
		(start 379.588522 -234.651804)
		(mid 379.31009 -234.72165)
		(end 379.033278 -234.645708)
		(width 0.088646)
		(layer "In6.Cu")
		(net "M_G_CPU0_SB_DQS_DP<1>")
	)
	(arc
		(start 378.64415 -234.654344)
		(mid 378.367675 -234.721664)
		(end 378.093478 -234.645708)
		(width 0.088646)
		(layer "In6.Cu")
		(net "M_G_CPU0_SB_DQS_DP<1>")
	)
	(arc
		(start 382.792732 -234.645708)
		(mid 382.605534 -234.595565)
		(end 382.418336 -234.645708)
		(width 0.088646)
		(layer "In6.Cu")
		(net "M_G_CPU0_SB_DQS_DP<1>")
	)
	(arc
		(start 381.468122 -234.651804)
		(mid 381.18969 -234.72165)
		(end 380.912878 -234.645708)
		(width 0.088646)
		(layer "In6.Cu")
		(net "M_G_CPU0_SB_DQS_DP<1>")
	)
	(arc
		(start 384.287268 -234.651804)
		(mid 384.00909 -234.721527)
		(end 383.732532 -234.645708)
		(width 0.088646)
		(layer "In6.Cu")
		(net "M_G_CPU0_SB_DQS_DP<1>")
	)
	(arc
		(start 384.672078 -234.645708)
		(mid 384.48488 -234.595565)
		(end 384.297682 -234.645708)
		(width 0.088646)
		(layer "In6.Cu")
		(net "M_G_CPU0_SB_DQS_DP<1>")
	)
	(segment
		(start 435.823614 -228.766624)
		(end 436.928514 -228.766624)
		(width 0.20066)
		(layer "F.Cu")
		(net "M_G_CPU0_SB_DQS_DP<0>")
	)
	(segment
		(start 443.035436 -228.895402)
		(end 443.4459 -228.484938)
		(width 0.20066)
		(layer "F.Cu")
		(net "M_G_CPU0_SB_DQS_DP<0>")
	)
	(segment
		(start 442.66485 -228.895402)
		(end 443.035436 -228.895402)
		(width 0.20066)
		(layer "F.Cu")
		(net "M_G_CPU0_SB_DQS_DP<0>")
	)
	(segment
		(start 437.517794 -228.766624)
		(end 437.758332 -228.526086)
		(width 0.20066)
		(layer "F.Cu")
		(net "M_G_CPU0_SB_DQS_DP<0>")
	)
	(segment
		(start 439.710322 -229.19182)
		(end 439.849768 -229.19182)
		(width 0.20066)
		(layer "F.Cu")
		(net "M_G_CPU0_SB_DQS_DP<0>")
	)
	(segment
		(start 436.928514 -228.766624)
		(end 437.517794 -228.766624)
		(width 0.20066)
		(layer "F.Cu")
		(net "M_G_CPU0_SB_DQS_DP<0>")
	)
	(segment
		(start 442.362336 -229.197916)
		(end 442.66485 -228.895402)
		(width 0.20066)
		(layer "F.Cu")
		(net "M_G_CPU0_SB_DQS_DP<0>")
	)
	(segment
		(start 375.08688 -240.388902)
		(end 375.08688 -239.853216)
		(width 0.20066)
		(layer "F.Cu")
		(net "M_G_CPU0_SB_DQS_DP<0>")
	)
	(segment
		(start 437.758332 -228.526086)
		(end 438.358788 -228.526086)
		(width 0.20066)
		(layer "F.Cu")
		(net "M_G_CPU0_SB_DQS_DP<0>")
	)
	(segment
		(start 443.641988 -228.484938)
		(end 443.923674 -228.766624)
		(width 0.20066)
		(layer "F.Cu")
		(net "M_G_CPU0_SB_DQS_DP<0>")
	)
	(segment
		(start 439.875676 -229.19182)
		(end 442.032898 -229.19182)
		(width 0.1016)
		(layer "F.Cu")
		(net "M_G_CPU0_SB_DQS_DP<0>")
	)
	(segment
		(start 443.923674 -228.766624)
		(end 444.472314 -228.766624)
		(width 0.20066)
		(layer "F.Cu")
		(net "M_G_CPU0_SB_DQS_DP<0>")
	)
	(segment
		(start 442.038994 -229.197916)
		(end 442.362336 -229.197916)
		(width 0.20066)
		(layer "F.Cu")
		(net "M_G_CPU0_SB_DQS_DP<0>")
	)
	(segment
		(start 443.4459 -228.484938)
		(end 443.641988 -228.484938)
		(width 0.20066)
		(layer "F.Cu")
		(net "M_G_CPU0_SB_DQS_DP<0>")
	)
	(segment
		(start 442.032898 -229.19182)
		(end 442.038994 -229.197916)
		(width 0.1016)
		(layer "F.Cu")
		(net "M_G_CPU0_SB_DQS_DP<0>")
	)
	(segment
		(start 439.459116 -228.940614)
		(end 439.710322 -229.19182)
		(width 0.20066)
		(layer "F.Cu")
		(net "M_G_CPU0_SB_DQS_DP<0>")
	)
	(segment
		(start 438.358788 -228.526086)
		(end 438.773316 -228.940614)
		(width 0.20066)
		(layer "F.Cu")
		(net "M_G_CPU0_SB_DQS_DP<0>")
	)
	(segment
		(start 439.849768 -229.19182)
		(end 439.875676 -229.19182)
		(width 0.101854)
		(layer "F.Cu")
		(net "M_G_CPU0_SB_DQS_DP<0>")
	)
	(segment
		(start 438.773316 -228.940614)
		(end 439.459116 -228.940614)
		(width 0.20066)
		(layer "F.Cu")
		(net "M_G_CPU0_SB_DQS_DP<0>")
	)
	(segment
		(start 375.087134 -240.389156)
		(end 375.08688 -240.388902)
		(width 0.20066)
		(layer "F.Cu")
		(net "M_G_CPU0_SB_DQS_DP<0>")
	)
	(segment
		(start 403.564598 -234.392978)
		(end 403.018498 -234.392978)
		(width 0.18288)
		(layer "In6.Cu")
		(net "M_G_CPU0_SB_DQS_DP<0>")
	)
	(segment
		(start 429.511968 -233.532426)
		(end 429.335946 -233.532426)
		(width 0.18288)
		(layer "In6.Cu")
		(net "M_G_CPU0_SB_DQS_DP<0>")
	)
	(segment
		(start 382.337564 -240.351564)
		(end 382.322832 -240.342928)
		(width 0.088646)
		(layer "In6.Cu")
		(net "M_G_CPU0_SB_DQS_DP<0>")
	)
	(segment
		(start 430.338738 -232.529634)
		(end 429.898302 -232.97007)
		(width 0.18288)
		(layer "In6.Cu")
		(net "M_G_CPU0_SB_DQS_DP<0>")
	)
	(segment
		(start 424.64736 -234.29087)
		(end 424.38701 -234.03052)
		(width 0.18288)
		(layer "In6.Cu")
		(net "M_G_CPU0_SB_DQS_DP<0>")
	)
	(segment
		(start 430.51476 -232.529634)
		(end 430.338738 -232.529634)
		(width 0.18288)
		(layer "In6.Cu")
		(net "M_G_CPU0_SB_DQS_DP<0>")
	)
	(segment
		(start 418.95776 -234.86491)
		(end 418.41166 -234.86491)
		(width 0.18288)
		(layer "In6.Cu")
		(net "M_G_CPU0_SB_DQS_DP<0>")
	)
	(segment
		(start 376.698764 -240.351564)
		(end 376.684032 -240.342928)
		(width 0.088646)
		(layer "In6.Cu")
		(net "M_G_CPU0_SB_DQS_DP<0>")
	)
	(segment
		(start 405.060912 -234.392978)
		(end 404.514812 -234.392978)
		(width 0.18288)
		(layer "In6.Cu")
		(net "M_G_CPU0_SB_DQS_DP<0>")
	)
	(segment
		(start 426.076364 -234.02036)
		(end 425.278804 -234.02036)
		(width 0.18288)
		(layer "In6.Cu")
		(net "M_G_CPU0_SB_DQS_DP<0>")
	)
	(segment
		(start 416.060382 -233.951526)
		(end 415.514282 -233.951526)
		(width 0.18288)
		(layer "In6.Cu")
		(net "M_G_CPU0_SB_DQS_DP<0>")
	)
	(segment
		(start 406.298654 -234.392978)
		(end 406.174194 -234.268518)
		(width 0.18288)
		(layer "In6.Cu")
		(net "M_G_CPU0_SB_DQS_DP<0>")
	)
	(segment
		(start 421.187372 -234.867196)
		(end 420.913814 -235.140754)
		(width 0.18288)
		(layer "In6.Cu")
		(net "M_G_CPU0_SB_DQS_DP<0>")
	)
	(segment
		(start 380.068582 -240.342928)
		(end 380.058168 -240.349024)
		(width 0.088646)
		(layer "In6.Cu")
		(net "M_G_CPU0_SB_DQS_DP<0>")
	)
	(segment
		(start 429.898302 -232.97007)
		(end 429.898302 -233.146092)
		(width 0.18288)
		(layer "In6.Cu")
		(net "M_G_CPU0_SB_DQS_DP<0>")
	)
	(segment
		(start 405.185372 -234.268518)
		(end 405.060912 -234.392978)
		(width 0.18288)
		(layer "In6.Cu")
		(net "M_G_CPU0_SB_DQS_DP<0>")
	)
	(segment
		(start 403.689058 -234.268518)
		(end 403.564598 -234.392978)
		(width 0.18288)
		(layer "In6.Cu")
		(net "M_G_CPU0_SB_DQS_DP<0>")
	)
	(segment
		(start 403.018498 -234.392978)
		(end 402.894038 -234.268518)
		(width 0.18288)
		(layer "In6.Cu")
		(net "M_G_CPU0_SB_DQS_DP<0>")
	)
	(segment
		(start 384.217164 -240.351564)
		(end 384.202432 -240.342928)
		(width 0.088646)
		(layer "In6.Cu")
		(net "M_G_CPU0_SB_DQS_DP<0>")
	)
	(segment
		(start 401.401788 -234.268518)
		(end 400.818096 -234.268518)
		(width 0.18288)
		(layer "In6.Cu")
		(net "M_G_CPU0_SB_DQS_DP<0>")
	)
	(segment
		(start 432.925728 -229.806246)
		(end 432.322478 -229.806246)
		(width 0.18288)
		(layer "In6.Cu")
		(net "M_G_CPU0_SB_DQS_DP<0>")
	)
	(segment
		(start 383.82829 -240.342674)
		(end 383.828036 -240.342928)
		(width 0.088646)
		(layer "In6.Cu")
		(net "M_G_CPU0_SB_DQS_DP<0>")
	)
	(segment
		(start 388.359396 -240.05667)
		(end 388.299452 -239.996726)
		(width 0.088646)
		(layer "In6.Cu")
		(net "M_G_CPU0_SB_DQS_DP<0>")
	)
	(segment
		(start 395.029944 -240.05667)
		(end 388.359396 -240.05667)
		(width 0.18288)
		(layer "In6.Cu")
		(net "M_G_CPU0_SB_DQS_DP<0>")
	)
	(segment
		(start 427.38421 -233.359706)
		(end 426.737018 -233.359706)
		(width 0.18288)
		(layer "In6.Cu")
		(net "M_G_CPU0_SB_DQS_DP<0>")
	)
	(segment
		(start 429.335946 -233.532426)
		(end 428.949866 -233.918506)
		(width 0.18288)
		(layer "In6.Cu")
		(net "M_G_CPU0_SB_DQS_DP<0>")
	)
	(segment
		(start 426.737018 -233.359706)
		(end 426.076364 -234.02036)
		(width 0.18288)
		(layer "In6.Cu")
		(net "M_G_CPU0_SB_DQS_DP<0>")
	)
	(segment
		(start 435.559708 -228.502718)
		(end 435.09184 -228.502718)
		(width 0.18288)
		(layer "In6.Cu")
		(net "M_G_CPU0_SB_DQS_DP<0>")
	)
	(segment
		(start 431.287174 -230.84155)
		(end 431.287174 -231.581198)
		(width 0.18288)
		(layer "In6.Cu")
		(net "M_G_CPU0_SB_DQS_DP<0>")
	)
	(segment
		(start 420.554404 -235.140754)
		(end 420.27856 -234.86491)
		(width 0.18288)
		(layer "In6.Cu")
		(net "M_G_CPU0_SB_DQS_DP<0>")
	)
	(segment
		(start 411.35173 -233.336846)
		(end 410.08427 -234.604306)
		(width 0.18288)
		(layer "In6.Cu")
		(net "M_G_CPU0_SB_DQS_DP<0>")
	)
	(segment
		(start 406.174194 -234.268518)
		(end 405.185372 -234.268518)
		(width 0.18288)
		(layer "In6.Cu")
		(net "M_G_CPU0_SB_DQS_DP<0>")
	)
	(segment
		(start 410.08427 -234.604306)
		(end 409.477464 -234.604306)
		(width 0.18288)
		(layer "In6.Cu")
		(net "M_G_CPU0_SB_DQS_DP<0>")
	)
	(segment
		(start 417.7411 -234.98937)
		(end 417.61664 -234.86491)
		(width 0.18288)
		(layer "In6.Cu")
		(net "M_G_CPU0_SB_DQS_DP<0>")
	)
	(segment
		(start 386.096764 -240.351564)
		(end 386.082032 -240.342928)
		(width 0.088646)
		(layer "In6.Cu")
		(net "M_G_CPU0_SB_DQS_DP<0>")
	)
	(segment
		(start 415.514282 -233.951526)
		(end 415.389822 -234.075986)
		(width 0.18288)
		(layer "In6.Cu")
		(net "M_G_CPU0_SB_DQS_DP<0>")
	)
	(segment
		(start 433.48783 -229.420166)
		(end 433.311808 -229.420166)
		(width 0.18288)
		(layer "In6.Cu")
		(net "M_G_CPU0_SB_DQS_DP<0>")
	)
	(segment
		(start 423.109898 -234.15498)
		(end 422.985438 -234.03052)
		(width 0.18288)
		(layer "In6.Cu")
		(net "M_G_CPU0_SB_DQS_DP<0>")
	)
	(segment
		(start 414.069276 -233.951526)
		(end 413.944816 -234.075986)
		(width 0.18288)
		(layer "In6.Cu")
		(net "M_G_CPU0_SB_DQS_DP<0>")
	)
	(segment
		(start 435.823614 -228.766624)
		(end 435.559708 -228.502718)
		(width 0.18288)
		(layer "In6.Cu")
		(net "M_G_CPU0_SB_DQS_DP<0>")
	)
	(segment
		(start 407.789126 -234.268518)
		(end 406.969214 -234.268518)
		(width 0.18288)
		(layer "In6.Cu")
		(net "M_G_CPU0_SB_DQS_DP<0>")
	)
	(segment
		(start 413.398716 -234.075986)
		(end 413.274256 -233.951526)
		(width 0.18288)
		(layer "In6.Cu")
		(net "M_G_CPU0_SB_DQS_DP<0>")
	)
	(segment
		(start 422.985438 -234.03052)
		(end 422.400222 -234.03052)
		(width 0.18288)
		(layer "In6.Cu")
		(net "M_G_CPU0_SB_DQS_DP<0>")
	)
	(segment
		(start 402.894038 -234.268518)
		(end 402.196808 -234.268518)
		(width 0.18288)
		(layer "In6.Cu")
		(net "M_G_CPU0_SB_DQS_DP<0>")
	)
	(segment
		(start 416.973766 -234.86491)
		(end 416.060382 -233.951526)
		(width 0.18288)
		(layer "In6.Cu")
		(net "M_G_CPU0_SB_DQS_DP<0>")
	)
	(segment
		(start 384.202432 -240.342928)
		(end 384.202178 -240.342674)
		(width 0.088646)
		(layer "In6.Cu")
		(net "M_G_CPU0_SB_DQS_DP<0>")
	)
	(segment
		(start 404.514812 -234.392978)
		(end 404.390352 -234.268518)
		(width 0.18288)
		(layer "In6.Cu")
		(net "M_G_CPU0_SB_DQS_DP<0>")
	)
	(segment
		(start 417.61664 -234.86491)
		(end 416.973766 -234.86491)
		(width 0.18288)
		(layer "In6.Cu")
		(net "M_G_CPU0_SB_DQS_DP<0>")
	)
	(segment
		(start 434.391816 -228.340158)
		(end 433.874164 -228.85781)
		(width 0.18288)
		(layer "In6.Cu")
		(net "M_G_CPU0_SB_DQS_DP<0>")
	)
	(segment
		(start 388.299452 -239.996726)
		(end 388.027672 -239.996726)
		(width 0.088646)
		(layer "In6.Cu")
		(net "M_G_CPU0_SB_DQS_DP<0>")
	)
	(segment
		(start 414.843722 -234.075986)
		(end 414.719262 -233.951526)
		(width 0.18288)
		(layer "In6.Cu")
		(net "M_G_CPU0_SB_DQS_DP<0>")
	)
	(segment
		(start 387.605778 -240.41862)
		(end 387.30428 -240.41862)
		(width 0.088646)
		(layer "In6.Cu")
		(net "M_G_CPU0_SB_DQS_DP<0>")
	)
	(segment
		(start 385.156964 -240.351564)
		(end 385.142232 -240.342928)
		(width 0.088646)
		(layer "In6.Cu")
		(net "M_G_CPU0_SB_DQS_DP<0>")
	)
	(segment
		(start 402.072348 -234.392978)
		(end 401.526248 -234.392978)
		(width 0.18288)
		(layer "In6.Cu")
		(net "M_G_CPU0_SB_DQS_DP<0>")
	)
	(segment
		(start 428.949866 -233.918506)
		(end 427.94301 -233.918506)
		(width 0.18288)
		(layer "In6.Cu")
		(net "M_G_CPU0_SB_DQS_DP<0>")
	)
	(segment
		(start 413.944816 -234.075986)
		(end 413.398716 -234.075986)
		(width 0.18288)
		(layer "In6.Cu")
		(net "M_G_CPU0_SB_DQS_DP<0>")
	)
	(segment
		(start 375.758964 -240.351564)
		(end 375.744232 -240.342928)
		(width 0.088646)
		(layer "In6.Cu")
		(net "M_G_CPU0_SB_DQS_DP<0>")
	)
	(segment
		(start 434.92928 -228.340158)
		(end 434.391816 -228.340158)
		(width 0.18288)
		(layer "In6.Cu")
		(net "M_G_CPU0_SB_DQS_DP<0>")
	)
	(segment
		(start 388.027672 -239.996726)
		(end 387.605778 -240.41862)
		(width 0.088646)
		(layer "In6.Cu")
		(net "M_G_CPU0_SB_DQS_DP<0>")
	)
	(segment
		(start 413.274256 -233.951526)
		(end 412.64459 -233.951526)
		(width 0.18288)
		(layer "In6.Cu")
		(net "M_G_CPU0_SB_DQS_DP<0>")
	)
	(segment
		(start 415.389822 -234.075986)
		(end 414.843722 -234.075986)
		(width 0.18288)
		(layer "In6.Cu")
		(net "M_G_CPU0_SB_DQS_DP<0>")
	)
	(segment
		(start 377.638564 -240.351564)
		(end 377.623832 -240.342928)
		(width 0.088646)
		(layer "In6.Cu")
		(net "M_G_CPU0_SB_DQS_DP<0>")
	)
	(segment
		(start 433.874164 -229.033832)
		(end 433.48783 -229.420166)
		(width 0.18288)
		(layer "In6.Cu")
		(net "M_G_CPU0_SB_DQS_DP<0>")
	)
	(segment
		(start 400.818096 -234.268518)
		(end 395.029944 -240.05667)
		(width 0.18288)
		(layer "In6.Cu")
		(net "M_G_CPU0_SB_DQS_DP<0>")
	)
	(segment
		(start 424.38701 -234.03052)
		(end 423.780458 -234.03052)
		(width 0.18288)
		(layer "In6.Cu")
		(net "M_G_CPU0_SB_DQS_DP<0>")
	)
	(segment
		(start 420.27856 -234.86491)
		(end 419.75278 -234.86491)
		(width 0.18288)
		(layer "In6.Cu")
		(net "M_G_CPU0_SB_DQS_DP<0>")
	)
	(segment
		(start 419.08222 -234.98937)
		(end 418.95776 -234.86491)
		(width 0.18288)
		(layer "In6.Cu")
		(net "M_G_CPU0_SB_DQS_DP<0>")
	)
	(segment
		(start 425.008294 -234.29087)
		(end 424.64736 -234.29087)
		(width 0.18288)
		(layer "In6.Cu")
		(net "M_G_CPU0_SB_DQS_DP<0>")
	)
	(segment
		(start 404.390352 -234.268518)
		(end 403.689058 -234.268518)
		(width 0.18288)
		(layer "In6.Cu")
		(net "M_G_CPU0_SB_DQS_DP<0>")
	)
	(segment
		(start 418.41166 -234.86491)
		(end 418.2872 -234.98937)
		(width 0.18288)
		(layer "In6.Cu")
		(net "M_G_CPU0_SB_DQS_DP<0>")
	)
	(segment
		(start 425.278804 -234.02036)
		(end 425.008294 -234.29087)
		(width 0.18288)
		(layer "In6.Cu")
		(net "M_G_CPU0_SB_DQS_DP<0>")
	)
	(segment
		(start 432.322478 -229.806246)
		(end 431.287174 -230.84155)
		(width 0.18288)
		(layer "In6.Cu")
		(net "M_G_CPU0_SB_DQS_DP<0>")
	)
	(segment
		(start 429.898302 -233.146092)
		(end 429.511968 -233.532426)
		(width 0.18288)
		(layer "In6.Cu")
		(net "M_G_CPU0_SB_DQS_DP<0>")
	)
	(segment
		(start 406.844754 -234.392978)
		(end 406.298654 -234.392978)
		(width 0.18288)
		(layer "In6.Cu")
		(net "M_G_CPU0_SB_DQS_DP<0>")
	)
	(segment
		(start 433.311808 -229.420166)
		(end 432.925728 -229.806246)
		(width 0.18288)
		(layer "In6.Cu")
		(net "M_G_CPU0_SB_DQS_DP<0>")
	)
	(segment
		(start 423.780458 -234.03052)
		(end 423.655998 -234.15498)
		(width 0.18288)
		(layer "In6.Cu")
		(net "M_G_CPU0_SB_DQS_DP<0>")
	)
	(segment
		(start 435.09184 -228.502718)
		(end 434.92928 -228.340158)
		(width 0.18288)
		(layer "In6.Cu")
		(net "M_G_CPU0_SB_DQS_DP<0>")
	)
	(segment
		(start 433.874164 -228.85781)
		(end 433.874164 -229.033832)
		(width 0.18288)
		(layer "In6.Cu")
		(net "M_G_CPU0_SB_DQS_DP<0>")
	)
	(segment
		(start 421.563546 -234.867196)
		(end 421.187372 -234.867196)
		(width 0.18288)
		(layer "In6.Cu")
		(net "M_G_CPU0_SB_DQS_DP<0>")
	)
	(segment
		(start 380.453392 -240.349024)
		(end 380.442978 -240.342928)
		(width 0.088646)
		(layer "In6.Cu")
		(net "M_G_CPU0_SB_DQS_DP<0>")
	)
	(segment
		(start 414.719262 -233.951526)
		(end 414.069276 -233.951526)
		(width 0.18288)
		(layer "In6.Cu")
		(net "M_G_CPU0_SB_DQS_DP<0>")
	)
	(segment
		(start 427.94301 -233.918506)
		(end 427.38421 -233.359706)
		(width 0.18288)
		(layer "In6.Cu")
		(net "M_G_CPU0_SB_DQS_DP<0>")
	)
	(segment
		(start 422.400222 -234.03052)
		(end 421.563546 -234.867196)
		(width 0.18288)
		(layer "In6.Cu")
		(net "M_G_CPU0_SB_DQS_DP<0>")
	)
	(segment
		(start 406.969214 -234.268518)
		(end 406.844754 -234.392978)
		(width 0.18288)
		(layer "In6.Cu")
		(net "M_G_CPU0_SB_DQS_DP<0>")
	)
	(segment
		(start 412.64459 -233.951526)
		(end 412.02991 -233.336846)
		(width 0.18288)
		(layer "In6.Cu")
		(net "M_G_CPU0_SB_DQS_DP<0>")
	)
	(segment
		(start 419.75278 -234.86491)
		(end 419.62832 -234.98937)
		(width 0.18288)
		(layer "In6.Cu")
		(net "M_G_CPU0_SB_DQS_DP<0>")
	)
	(segment
		(start 402.196808 -234.268518)
		(end 402.072348 -234.392978)
		(width 0.18288)
		(layer "In6.Cu")
		(net "M_G_CPU0_SB_DQS_DP<0>")
	)
	(segment
		(start 409.477464 -234.604306)
		(end 407.789126 -234.268518)
		(width 0.18288)
		(layer "In6.Cu")
		(net "M_G_CPU0_SB_DQS_DP<0>")
	)
	(segment
		(start 418.2872 -234.98937)
		(end 417.7411 -234.98937)
		(width 0.18288)
		(layer "In6.Cu")
		(net "M_G_CPU0_SB_DQS_DP<0>")
	)
	(segment
		(start 419.62832 -234.98937)
		(end 419.08222 -234.98937)
		(width 0.18288)
		(layer "In6.Cu")
		(net "M_G_CPU0_SB_DQS_DP<0>")
	)
	(segment
		(start 430.901094 -232.1433)
		(end 430.51476 -232.529634)
		(width 0.18288)
		(layer "In6.Cu")
		(net "M_G_CPU0_SB_DQS_DP<0>")
	)
	(segment
		(start 431.287174 -231.581198)
		(end 430.901094 -231.967278)
		(width 0.18288)
		(layer "In6.Cu")
		(net "M_G_CPU0_SB_DQS_DP<0>")
	)
	(segment
		(start 430.901094 -231.967278)
		(end 430.901094 -232.1433)
		(width 0.18288)
		(layer "In6.Cu")
		(net "M_G_CPU0_SB_DQS_DP<0>")
	)
	(segment
		(start 423.655998 -234.15498)
		(end 423.109898 -234.15498)
		(width 0.18288)
		(layer "In6.Cu")
		(net "M_G_CPU0_SB_DQS_DP<0>")
	)
	(segment
		(start 378.578364 -240.351564)
		(end 378.563632 -240.342928)
		(width 0.088646)
		(layer "In6.Cu")
		(net "M_G_CPU0_SB_DQS_DP<0>")
	)
	(segment
		(start 420.913814 -235.140754)
		(end 420.554404 -235.140754)
		(width 0.18288)
		(layer "In6.Cu")
		(net "M_G_CPU0_SB_DQS_DP<0>")
	)
	(segment
		(start 412.02991 -233.336846)
		(end 411.35173 -233.336846)
		(width 0.18288)
		(layer "In6.Cu")
		(net "M_G_CPU0_SB_DQS_DP<0>")
	)
	(segment
		(start 401.526248 -234.392978)
		(end 401.401788 -234.268518)
		(width 0.18288)
		(layer "In6.Cu")
		(net "M_G_CPU0_SB_DQS_DP<0>")
	)
	(arc
		(start 383.828036 -240.342928)
		(mid 383.545334 -240.41867)
		(end 383.262632 -240.342928)
		(width 0.088646)
		(layer "In6.Cu")
		(net "M_G_CPU0_SB_DQS_DP<0>")
	)
	(arc
		(start 382.888236 -240.342928)
		(mid 382.614007 -240.418853)
		(end 382.337564 -240.351564)
		(width 0.088646)
		(layer "In6.Cu")
		(net "M_G_CPU0_SB_DQS_DP<0>")
	)
	(arc
		(start 377.623832 -240.342928)
		(mid 377.436634 -240.292785)
		(end 377.249436 -240.342928)
		(width 0.088646)
		(layer "In6.Cu")
		(net "M_G_CPU0_SB_DQS_DP<0>")
	)
	(arc
		(start 375.744232 -240.342928)
		(mid 375.402068 -240.116177)
		(end 375.08688 -239.853216)
		(width 0.088646)
		(layer "In6.Cu")
		(net "M_G_CPU0_SB_DQS_DP<0>")
	)
	(arc
		(start 380.058168 -240.349024)
		(mid 379.77999 -240.418716)
		(end 379.503432 -240.342928)
		(width 0.088646)
		(layer "In6.Cu")
		(net "M_G_CPU0_SB_DQS_DP<0>")
	)
	(arc
		(start 381.008636 -240.342928)
		(mid 380.731823 -240.418764)
		(end 380.453392 -240.349024)
		(width 0.088646)
		(layer "In6.Cu")
		(net "M_G_CPU0_SB_DQS_DP<0>")
	)
	(arc
		(start 380.442978 -240.342928)
		(mid 380.25578 -240.292785)
		(end 380.068582 -240.342928)
		(width 0.088646)
		(layer "In6.Cu")
		(net "M_G_CPU0_SB_DQS_DP<0>")
	)
	(arc
		(start 383.262632 -240.342928)
		(mid 383.075434 -240.292785)
		(end 382.888236 -240.342928)
		(width 0.088646)
		(layer "In6.Cu")
		(net "M_G_CPU0_SB_DQS_DP<0>")
	)
	(arc
		(start 384.767836 -240.342928)
		(mid 384.493607 -240.418853)
		(end 384.217164 -240.351564)
		(width 0.088646)
		(layer "In6.Cu")
		(net "M_G_CPU0_SB_DQS_DP<0>")
	)
	(arc
		(start 379.129036 -240.342928)
		(mid 378.854807 -240.418853)
		(end 378.578364 -240.351564)
		(width 0.088646)
		(layer "In6.Cu")
		(net "M_G_CPU0_SB_DQS_DP<0>")
	)
	(arc
		(start 378.189236 -240.342928)
		(mid 377.915007 -240.418853)
		(end 377.638564 -240.351564)
		(width 0.088646)
		(layer "In6.Cu")
		(net "M_G_CPU0_SB_DQS_DP<0>")
	)
	(arc
		(start 377.249436 -240.342928)
		(mid 376.975207 -240.418853)
		(end 376.698764 -240.351564)
		(width 0.088646)
		(layer "In6.Cu")
		(net "M_G_CPU0_SB_DQS_DP<0>")
	)
	(arc
		(start 386.647436 -240.342928)
		(mid 386.373207 -240.418853)
		(end 386.096764 -240.351564)
		(width 0.088646)
		(layer "In6.Cu")
		(net "M_G_CPU0_SB_DQS_DP<0>")
	)
	(arc
		(start 379.503432 -240.342928)
		(mid 379.316234 -240.292785)
		(end 379.129036 -240.342928)
		(width 0.088646)
		(layer "In6.Cu")
		(net "M_G_CPU0_SB_DQS_DP<0>")
	)
	(arc
		(start 384.202178 -240.342674)
		(mid 384.015234 -240.29259)
		(end 383.82829 -240.342674)
		(width 0.088646)
		(layer "In6.Cu")
		(net "M_G_CPU0_SB_DQS_DP<0>")
	)
	(arc
		(start 385.707636 -240.342928)
		(mid 385.433407 -240.418853)
		(end 385.156964 -240.351564)
		(width 0.088646)
		(layer "In6.Cu")
		(net "M_G_CPU0_SB_DQS_DP<0>")
	)
	(arc
		(start 382.322832 -240.342928)
		(mid 382.135634 -240.292785)
		(end 381.948436 -240.342928)
		(width 0.088646)
		(layer "In6.Cu")
		(net "M_G_CPU0_SB_DQS_DP<0>")
	)
	(arc
		(start 387.021832 -240.342928)
		(mid 386.834634 -240.292785)
		(end 386.647436 -240.342928)
		(width 0.088646)
		(layer "In6.Cu")
		(net "M_G_CPU0_SB_DQS_DP<0>")
	)
	(arc
		(start 381.948436 -240.342928)
		(mid 381.665734 -240.41867)
		(end 381.383032 -240.342928)
		(width 0.088646)
		(layer "In6.Cu")
		(net "M_G_CPU0_SB_DQS_DP<0>")
	)
	(arc
		(start 376.684032 -240.342928)
		(mid 376.496834 -240.292785)
		(end 376.309636 -240.342928)
		(width 0.088646)
		(layer "In6.Cu")
		(net "M_G_CPU0_SB_DQS_DP<0>")
	)
	(arc
		(start 387.30428 -240.41862)
		(mid 387.158088 -240.399325)
		(end 387.021832 -240.342928)
		(width 0.088646)
		(layer "In6.Cu")
		(net "M_G_CPU0_SB_DQS_DP<0>")
	)
	(arc
		(start 381.383032 -240.342928)
		(mid 381.195834 -240.292785)
		(end 381.008636 -240.342928)
		(width 0.088646)
		(layer "In6.Cu")
		(net "M_G_CPU0_SB_DQS_DP<0>")
	)
	(arc
		(start 385.142232 -240.342928)
		(mid 384.955034 -240.292785)
		(end 384.767836 -240.342928)
		(width 0.088646)
		(layer "In6.Cu")
		(net "M_G_CPU0_SB_DQS_DP<0>")
	)
	(arc
		(start 376.309636 -240.342928)
		(mid 376.035407 -240.418853)
		(end 375.758964 -240.351564)
		(width 0.088646)
		(layer "In6.Cu")
		(net "M_G_CPU0_SB_DQS_DP<0>")
	)
	(arc
		(start 386.082032 -240.342928)
		(mid 385.894834 -240.292785)
		(end 385.707636 -240.342928)
		(width 0.088646)
		(layer "In6.Cu")
		(net "M_G_CPU0_SB_DQS_DP<0>")
	)
	(arc
		(start 378.563632 -240.342928)
		(mid 378.376434 -240.292785)
		(end 378.189236 -240.342928)
		(width 0.088646)
		(layer "In6.Cu")
		(net "M_G_CPU0_SB_DQS_DP<0>")
	)
	(segment
		(start 442.368432 -237.691676)
		(end 442.594492 -237.917736)
		(width 0.20066)
		(layer "F.Cu")
		(net "M_G_CPU0_SB_DQS_DN<9>")
	)
	(segment
		(start 442.594492 -237.917736)
		(end 442.899546 -237.917736)
		(width 0.20066)
		(layer "F.Cu")
		(net "M_G_CPU0_SB_DQS_DN<9>")
	)
	(segment
		(start 439.854086 -237.691676)
		(end 442.03366 -237.691676)
		(width 0.1016)
		(layer "F.Cu")
		(net "M_G_CPU0_SB_DQS_DN<9>")
	)
	(segment
		(start 443.642496 -237.507272)
		(end 443.883034 -237.266734)
		(width 0.20066)
		(layer "F.Cu")
		(net "M_G_CPU0_SB_DQS_DN<9>")
	)
	(segment
		(start 439.785252 -237.691676)
		(end 439.854086 -237.691676)
		(width 0.101854)
		(layer "F.Cu")
		(net "M_G_CPU0_SB_DQS_DN<9>")
	)
	(segment
		(start 378.376434 -242.830604)
		(end 378.376434 -242.294918)
		(width 0.20066)
		(layer "F.Cu")
		(net "M_G_CPU0_SB_DQS_DN<9>")
	)
	(segment
		(start 442.899546 -237.917736)
		(end 443.31001 -237.507272)
		(width 0.20066)
		(layer "F.Cu")
		(net "M_G_CPU0_SB_DQS_DN<9>")
	)
	(segment
		(start 442.03366 -237.691676)
		(end 442.21781 -237.691676)
		(width 0.101854)
		(layer "F.Cu")
		(net "M_G_CPU0_SB_DQS_DN<9>")
	)
	(segment
		(start 438.879234 -237.962948)
		(end 439.430922 -237.962948)
		(width 0.20066)
		(layer "F.Cu")
		(net "M_G_CPU0_SB_DQS_DN<9>")
	)
	(segment
		(start 439.430922 -237.962948)
		(end 439.702194 -237.691676)
		(width 0.20066)
		(layer "F.Cu")
		(net "M_G_CPU0_SB_DQS_DN<9>")
	)
	(segment
		(start 443.31001 -237.507272)
		(end 443.642496 -237.507272)
		(width 0.20066)
		(layer "F.Cu")
		(net "M_G_CPU0_SB_DQS_DN<9>")
	)
	(segment
		(start 439.702194 -237.691676)
		(end 439.785252 -237.691676)
		(width 0.20066)
		(layer "F.Cu")
		(net "M_G_CPU0_SB_DQS_DN<9>")
	)
	(segment
		(start 438.464706 -237.54842)
		(end 438.879234 -237.962948)
		(width 0.20066)
		(layer "F.Cu")
		(net "M_G_CPU0_SB_DQS_DN<9>")
	)
	(segment
		(start 378.37618 -242.830858)
		(end 378.376434 -242.830604)
		(width 0.20066)
		(layer "F.Cu")
		(net "M_G_CPU0_SB_DQS_DN<9>")
	)
	(segment
		(start 442.21781 -237.691676)
		(end 442.368432 -237.691676)
		(width 0.20066)
		(layer "F.Cu")
		(net "M_G_CPU0_SB_DQS_DN<9>")
	)
	(segment
		(start 443.883034 -237.266734)
		(end 444.472314 -237.266734)
		(width 0.20066)
		(layer "F.Cu")
		(net "M_G_CPU0_SB_DQS_DN<9>")
	)
	(segment
		(start 435.823614 -237.266734)
		(end 436.928514 -237.266734)
		(width 0.20066)
		(layer "F.Cu")
		(net "M_G_CPU0_SB_DQS_DN<9>")
	)
	(segment
		(start 436.928514 -237.266734)
		(end 437.477154 -237.266734)
		(width 0.20066)
		(layer "F.Cu")
		(net "M_G_CPU0_SB_DQS_DN<9>")
	)
	(segment
		(start 437.75884 -237.54842)
		(end 438.464706 -237.54842)
		(width 0.20066)
		(layer "F.Cu")
		(net "M_G_CPU0_SB_DQS_DN<9>")
	)
	(segment
		(start 437.477154 -237.266734)
		(end 437.75884 -237.54842)
		(width 0.20066)
		(layer "F.Cu")
		(net "M_G_CPU0_SB_DQS_DN<9>")
	)
	(segment
		(start 434.288438 -237.184946)
		(end 433.742338 -237.184946)
		(width 0.18288)
		(layer "In4.Cu")
		(net "M_G_CPU0_SB_DQS_DN<9>")
	)
	(segment
		(start 432.276758 -237.309406)
		(end 431.073814 -237.309406)
		(width 0.18288)
		(layer "In4.Cu")
		(net "M_G_CPU0_SB_DQS_DN<9>")
	)
	(segment
		(start 388.172706 -242.166902)
		(end 387.015228 -242.166902)
		(width 0.088646)
		(layer "In4.Cu")
		(net "M_G_CPU0_SB_DQS_DN<9>")
	)
	(segment
		(start 424.625008 -237.692438)
		(end 424.375072 -237.942374)
		(width 0.18288)
		(layer "In4.Cu")
		(net "M_G_CPU0_SB_DQS_DN<9>")
	)
	(segment
		(start 378.06376 -242.295172)
		(end 378.376434 -242.294918)
		(width 0.088646)
		(layer "In4.Cu")
		(net "M_G_CPU0_SB_DQS_DN<9>")
	)
	(segment
		(start 388.255764 -242.107212)
		(end 388.232396 -242.107212)
		(width 0.088646)
		(layer "In4.Cu")
		(net "M_G_CPU0_SB_DQS_DN<9>")
	)
	(segment
		(start 435.569868 -237.52048)
		(end 435.170072 -237.52048)
		(width 0.18288)
		(layer "In4.Cu")
		(net "M_G_CPU0_SB_DQS_DN<9>")
	)
	(segment
		(start 412.006542 -237.677452)
		(end 411.74162 -237.942374)
		(width 0.18288)
		(layer "In4.Cu")
		(net "M_G_CPU0_SB_DQS_DN<9>")
	)
	(segment
		(start 378.005848 -242.35283)
		(end 378.006102 -242.35283)
		(width 0.088646)
		(layer "In4.Cu")
		(net "M_G_CPU0_SB_DQS_DN<9>")
	)
	(segment
		(start 419.270942 -238.540036)
		(end 416.55238 -238.540036)
		(width 0.18288)
		(layer "In4.Cu")
		(net "M_G_CPU0_SB_DQS_DN<9>")
	)
	(segment
		(start 424.375072 -237.942374)
		(end 422.440354 -237.942374)
		(width 0.18288)
		(layer "In4.Cu")
		(net "M_G_CPU0_SB_DQS_DN<9>")
	)
	(segment
		(start 381.020828 -242.62715)
		(end 381.00889 -242.620038)
		(width 0.088646)
		(layer "In4.Cu")
		(net "M_G_CPU0_SB_DQS_DN<9>")
	)
	(segment
		(start 383.262632 -242.619276)
		(end 383.252472 -242.62588)
		(width 0.088646)
		(layer "In4.Cu")
		(net "M_G_CPU0_SB_DQS_DN<9>")
	)
	(segment
		(start 426.74413 -237.309406)
		(end 426.102526 -237.95101)
		(width 0.18288)
		(layer "In4.Cu")
		(net "M_G_CPU0_SB_DQS_DN<9>")
	)
	(segment
		(start 426.102526 -237.95101)
		(end 425.288456 -237.95101)
		(width 0.18288)
		(layer "In4.Cu")
		(net "M_G_CPU0_SB_DQS_DN<9>")
	)
	(segment
		(start 421.58158 -238.801148)
		(end 421.188388 -238.801148)
		(width 0.18288)
		(layer "In4.Cu")
		(net "M_G_CPU0_SB_DQS_DN<9>")
	)
	(segment
		(start 430.403254 -237.184946)
		(end 430.278794 -237.309406)
		(width 0.18288)
		(layer "In4.Cu")
		(net "M_G_CPU0_SB_DQS_DN<9>")
	)
	(segment
		(start 410.96438 -237.942374)
		(end 410.404564 -237.382558)
		(width 0.18288)
		(layer "In4.Cu")
		(net "M_G_CPU0_SB_DQS_DN<9>")
	)
	(segment
		(start 433.742338 -237.184946)
		(end 433.617878 -237.309406)
		(width 0.18288)
		(layer "In4.Cu")
		(net "M_G_CPU0_SB_DQS_DN<9>")
	)
	(segment
		(start 399.144236 -239.581944)
		(end 394.786104 -239.581944)
		(width 0.18288)
		(layer "In4.Cu")
		(net "M_G_CPU0_SB_DQS_DN<9>")
	)
	(segment
		(start 400.545808 -238.180372)
		(end 399.144236 -239.581944)
		(width 0.18288)
		(layer "In4.Cu")
		(net "M_G_CPU0_SB_DQS_DN<9>")
	)
	(segment
		(start 412.381446 -237.677452)
		(end 412.006542 -237.677452)
		(width 0.18288)
		(layer "In4.Cu")
		(net "M_G_CPU0_SB_DQS_DN<9>")
	)
	(segment
		(start 382.322324 -242.620038)
		(end 382.313942 -242.625118)
		(width 0.088646)
		(layer "In4.Cu")
		(net "M_G_CPU0_SB_DQS_DN<9>")
	)
	(segment
		(start 411.74162 -237.942374)
		(end 410.96438 -237.942374)
		(width 0.18288)
		(layer "In4.Cu")
		(net "M_G_CPU0_SB_DQS_DN<9>")
	)
	(segment
		(start 425.288456 -237.95101)
		(end 425.029884 -237.692438)
		(width 0.18288)
		(layer "In4.Cu")
		(net "M_G_CPU0_SB_DQS_DN<9>")
	)
	(segment
		(start 416.213798 -238.201454)
		(end 414.03778 -238.201454)
		(width 0.18288)
		(layer "In4.Cu")
		(net "M_G_CPU0_SB_DQS_DN<9>")
	)
	(segment
		(start 434.412898 -237.309406)
		(end 434.288438 -237.184946)
		(width 0.18288)
		(layer "In4.Cu")
		(net "M_G_CPU0_SB_DQS_DN<9>")
	)
	(segment
		(start 414.03778 -238.201454)
		(end 413.783018 -237.946692)
		(width 0.18288)
		(layer "In4.Cu")
		(net "M_G_CPU0_SB_DQS_DN<9>")
	)
	(segment
		(start 435.170072 -237.52048)
		(end 434.958998 -237.309406)
		(width 0.18288)
		(layer "In4.Cu")
		(net "M_G_CPU0_SB_DQS_DN<9>")
	)
	(segment
		(start 388.232396 -242.107212)
		(end 388.172706 -242.166902)
		(width 0.088646)
		(layer "In4.Cu")
		(net "M_G_CPU0_SB_DQS_DN<9>")
	)
	(segment
		(start 434.958998 -237.309406)
		(end 434.412898 -237.309406)
		(width 0.18288)
		(layer "In4.Cu")
		(net "M_G_CPU0_SB_DQS_DN<9>")
	)
	(segment
		(start 430.278794 -237.309406)
		(end 426.74413 -237.309406)
		(width 0.18288)
		(layer "In4.Cu")
		(net "M_G_CPU0_SB_DQS_DN<9>")
	)
	(segment
		(start 420.52494 -238.542576)
		(end 420.275004 -238.792512)
		(width 0.18288)
		(layer "In4.Cu")
		(net "M_G_CPU0_SB_DQS_DN<9>")
	)
	(segment
		(start 409.086558 -237.382558)
		(end 408.288744 -238.180372)
		(width 0.18288)
		(layer "In4.Cu")
		(net "M_G_CPU0_SB_DQS_DN<9>")
	)
	(segment
		(start 387.014974 -242.166648)
		(end 386.638292 -242.54333)
		(width 0.088646)
		(layer "In4.Cu")
		(net "M_G_CPU0_SB_DQS_DN<9>")
	)
	(segment
		(start 432.947318 -237.184946)
		(end 432.401218 -237.184946)
		(width 0.18288)
		(layer "In4.Cu")
		(net "M_G_CPU0_SB_DQS_DN<9>")
	)
	(segment
		(start 420.929816 -238.542576)
		(end 420.52494 -238.542576)
		(width 0.18288)
		(layer "In4.Cu")
		(net "M_G_CPU0_SB_DQS_DN<9>")
	)
	(segment
		(start 422.440354 -237.942374)
		(end 421.58158 -238.801148)
		(width 0.18288)
		(layer "In4.Cu")
		(net "M_G_CPU0_SB_DQS_DN<9>")
	)
	(segment
		(start 413.783018 -237.946692)
		(end 412.650686 -237.946692)
		(width 0.18288)
		(layer "In4.Cu")
		(net "M_G_CPU0_SB_DQS_DN<9>")
	)
	(segment
		(start 433.617878 -237.309406)
		(end 433.071778 -237.309406)
		(width 0.18288)
		(layer "In4.Cu")
		(net "M_G_CPU0_SB_DQS_DN<9>")
	)
	(segment
		(start 378.006102 -242.35283)
		(end 378.06376 -242.295172)
		(width 0.088646)
		(layer "In4.Cu")
		(net "M_G_CPU0_SB_DQS_DN<9>")
	)
	(segment
		(start 380.442978 -242.620038)
		(end 380.434596 -242.625118)
		(width 0.088646)
		(layer "In4.Cu")
		(net "M_G_CPU0_SB_DQS_DN<9>")
	)
	(segment
		(start 432.401218 -237.184946)
		(end 432.276758 -237.309406)
		(width 0.18288)
		(layer "In4.Cu")
		(net "M_G_CPU0_SB_DQS_DN<9>")
	)
	(segment
		(start 430.949354 -237.184946)
		(end 430.403254 -237.184946)
		(width 0.18288)
		(layer "In4.Cu")
		(net "M_G_CPU0_SB_DQS_DN<9>")
	)
	(segment
		(start 387.015228 -242.166902)
		(end 387.014974 -242.166648)
		(width 0.088646)
		(layer "In4.Cu")
		(net "M_G_CPU0_SB_DQS_DN<9>")
	)
	(segment
		(start 425.029884 -237.692438)
		(end 424.625008 -237.692438)
		(width 0.18288)
		(layer "In4.Cu")
		(net "M_G_CPU0_SB_DQS_DN<9>")
	)
	(segment
		(start 386.638292 -242.54333)
		(end 386.364988 -242.54333)
		(width 0.088646)
		(layer "In4.Cu")
		(net "M_G_CPU0_SB_DQS_DN<9>")
	)
	(segment
		(start 408.288744 -238.180372)
		(end 400.545808 -238.180372)
		(width 0.18288)
		(layer "In4.Cu")
		(net "M_G_CPU0_SB_DQS_DN<9>")
	)
	(segment
		(start 378.563124 -242.620038)
		(end 378.551186 -242.62715)
		(width 0.088646)
		(layer "In4.Cu")
		(net "M_G_CPU0_SB_DQS_DN<9>")
	)
	(segment
		(start 412.650686 -237.946692)
		(end 412.381446 -237.677452)
		(width 0.18288)
		(layer "In4.Cu")
		(net "M_G_CPU0_SB_DQS_DN<9>")
	)
	(segment
		(start 392.260836 -242.107212)
		(end 388.255764 -242.107212)
		(width 0.18288)
		(layer "In4.Cu")
		(net "M_G_CPU0_SB_DQS_DN<9>")
	)
	(segment
		(start 410.404564 -237.382558)
		(end 409.086558 -237.382558)
		(width 0.18288)
		(layer "In4.Cu")
		(net "M_G_CPU0_SB_DQS_DN<9>")
	)
	(segment
		(start 420.275004 -238.792512)
		(end 419.523418 -238.792512)
		(width 0.18288)
		(layer "In4.Cu")
		(net "M_G_CPU0_SB_DQS_DN<9>")
	)
	(segment
		(start 435.823614 -237.266734)
		(end 435.569868 -237.52048)
		(width 0.18288)
		(layer "In4.Cu")
		(net "M_G_CPU0_SB_DQS_DN<9>")
	)
	(segment
		(start 394.786104 -239.581944)
		(end 392.260836 -242.107212)
		(width 0.18288)
		(layer "In4.Cu")
		(net "M_G_CPU0_SB_DQS_DN<9>")
	)
	(segment
		(start 433.071778 -237.309406)
		(end 432.947318 -237.184946)
		(width 0.18288)
		(layer "In4.Cu")
		(net "M_G_CPU0_SB_DQS_DN<9>")
	)
	(segment
		(start 421.188388 -238.801148)
		(end 420.929816 -238.542576)
		(width 0.18288)
		(layer "In4.Cu")
		(net "M_G_CPU0_SB_DQS_DN<9>")
	)
	(segment
		(start 431.073814 -237.309406)
		(end 430.949354 -237.184946)
		(width 0.18288)
		(layer "In4.Cu")
		(net "M_G_CPU0_SB_DQS_DN<9>")
	)
	(segment
		(start 379.502924 -242.620038)
		(end 379.490986 -242.62715)
		(width 0.088646)
		(layer "In4.Cu")
		(net "M_G_CPU0_SB_DQS_DN<9>")
	)
	(segment
		(start 416.55238 -238.540036)
		(end 416.213798 -238.201454)
		(width 0.18288)
		(layer "In4.Cu")
		(net "M_G_CPU0_SB_DQS_DN<9>")
	)
	(segment
		(start 419.523418 -238.792512)
		(end 419.270942 -238.540036)
		(width 0.18288)
		(layer "In4.Cu")
		(net "M_G_CPU0_SB_DQS_DN<9>")
	)
	(arc
		(start 386.082032 -242.619276)
		(mid 385.894834 -242.669419)
		(end 385.707636 -242.619276)
		(width 0.088646)
		(layer "In4.Cu")
		(net "M_G_CPU0_SB_DQS_DN<9>")
	)
	(arc
		(start 384.767836 -242.619276)
		(mid 384.485134 -242.543534)
		(end 384.202432 -242.619276)
		(width 0.088646)
		(layer "In4.Cu")
		(net "M_G_CPU0_SB_DQS_DN<9>")
	)
	(arc
		(start 382.313942 -242.625118)
		(mid 382.130375 -242.670055)
		(end 381.948182 -242.619784)
		(width 0.088646)
		(layer "In4.Cu")
		(net "M_G_CPU0_SB_DQS_DN<9>")
	)
	(arc
		(start 381.00889 -242.620038)
		(mid 380.725934 -242.544067)
		(end 380.442978 -242.620038)
		(width 0.088646)
		(layer "In4.Cu")
		(net "M_G_CPU0_SB_DQS_DN<9>")
	)
	(arc
		(start 380.434596 -242.625118)
		(mid 380.250775 -242.670176)
		(end 380.068328 -242.619784)
		(width 0.088646)
		(layer "In4.Cu")
		(net "M_G_CPU0_SB_DQS_DN<9>")
	)
	(arc
		(start 380.068328 -242.619784)
		(mid 379.785597 -242.544101)
		(end 379.502924 -242.620038)
		(width 0.088646)
		(layer "In4.Cu")
		(net "M_G_CPU0_SB_DQS_DN<9>")
	)
	(arc
		(start 378.188728 -242.619784)
		(mid 378.067046 -242.507034)
		(end 378.005848 -242.35283)
		(width 0.088646)
		(layer "In4.Cu")
		(net "M_G_CPU0_SB_DQS_DN<9>")
	)
	(arc
		(start 383.828036 -242.619276)
		(mid 383.545334 -242.543534)
		(end 383.262632 -242.619276)
		(width 0.088646)
		(layer "In4.Cu")
		(net "M_G_CPU0_SB_DQS_DN<9>")
	)
	(arc
		(start 385.142232 -242.619276)
		(mid 384.955034 -242.669419)
		(end 384.767836 -242.619276)
		(width 0.088646)
		(layer "In4.Cu")
		(net "M_G_CPU0_SB_DQS_DN<9>")
	)
	(arc
		(start 384.202432 -242.619276)
		(mid 384.015234 -242.669419)
		(end 383.828036 -242.619276)
		(width 0.088646)
		(layer "In4.Cu")
		(net "M_G_CPU0_SB_DQS_DN<9>")
	)
	(arc
		(start 378.551186 -242.62715)
		(mid 378.369016 -242.670139)
		(end 378.188728 -242.619784)
		(width 0.088646)
		(layer "In4.Cu")
		(net "M_G_CPU0_SB_DQS_DN<9>")
	)
	(arc
		(start 385.707636 -242.619276)
		(mid 385.424934 -242.543534)
		(end 385.142232 -242.619276)
		(width 0.088646)
		(layer "In4.Cu")
		(net "M_G_CPU0_SB_DQS_DN<9>")
	)
	(arc
		(start 381.948182 -242.619784)
		(mid 381.665734 -242.544101)
		(end 381.383286 -242.619784)
		(width 0.088646)
		(layer "In4.Cu")
		(net "M_G_CPU0_SB_DQS_DN<9>")
	)
	(arc
		(start 379.128528 -242.619784)
		(mid 378.845797 -242.544101)
		(end 378.563124 -242.620038)
		(width 0.088646)
		(layer "In4.Cu")
		(net "M_G_CPU0_SB_DQS_DN<9>")
	)
	(arc
		(start 379.490986 -242.62715)
		(mid 379.308816 -242.670139)
		(end 379.128528 -242.619784)
		(width 0.088646)
		(layer "In4.Cu")
		(net "M_G_CPU0_SB_DQS_DN<9>")
	)
	(arc
		(start 383.252472 -242.62588)
		(mid 383.069324 -242.670112)
		(end 382.887728 -242.619784)
		(width 0.088646)
		(layer "In4.Cu")
		(net "M_G_CPU0_SB_DQS_DN<9>")
	)
	(arc
		(start 386.364988 -242.54333)
		(mid 386.218518 -242.56269)
		(end 386.082032 -242.619276)
		(width 0.088646)
		(layer "In4.Cu")
		(net "M_G_CPU0_SB_DQS_DN<9>")
	)
	(arc
		(start 381.383286 -242.619784)
		(mid 381.202999 -242.670196)
		(end 381.020828 -242.62715)
		(width 0.088646)
		(layer "In4.Cu")
		(net "M_G_CPU0_SB_DQS_DN<9>")
	)
	(arc
		(start 382.887728 -242.619784)
		(mid 382.604997 -242.544101)
		(end 382.322324 -242.620038)
		(width 0.088646)
		(layer "In4.Cu")
		(net "M_G_CPU0_SB_DQS_DN<9>")
	)
	(segment
		(start 442.861192 -199.170544)
		(end 443.13856 -199.447912)
		(width 0.20066)
		(layer "F.Cu")
		(net "M_G_CPU0_SB_DQS_DN<8>")
	)
	(segment
		(start 443.13856 -199.447912)
		(end 443.450726 -199.447912)
		(width 0.20066)
		(layer "F.Cu")
		(net "M_G_CPU0_SB_DQS_DN<8>")
	)
	(segment
		(start 443.455552 -199.447912)
		(end 443.461648 -199.441816)
		(width 0.1016)
		(layer "F.Cu")
		(net "M_G_CPU0_SB_DQS_DN<8>")
	)
	(segment
		(start 439.923682 -199.866758)
		(end 441.028582 -199.866758)
		(width 0.20066)
		(layer "F.Cu")
		(net "M_G_CPU0_SB_DQS_DN<8>")
	)
	(segment
		(start 445.471804 -199.441816)
		(end 445.482726 -199.452738)
		(width 0.1016)
		(layer "F.Cu")
		(net "M_G_CPU0_SB_DQS_DN<8>")
	)
	(segment
		(start 443.461648 -199.441816)
		(end 445.471804 -199.441816)
		(width 0.1016)
		(layer "F.Cu")
		(net "M_G_CPU0_SB_DQS_DN<8>")
	)
	(segment
		(start 442.313822 -199.595486)
		(end 442.738764 -199.170544)
		(width 0.20066)
		(layer "F.Cu")
		(net "M_G_CPU0_SB_DQS_DN<8>")
	)
	(segment
		(start 442.738764 -199.170544)
		(end 442.861192 -199.170544)
		(width 0.20066)
		(layer "F.Cu")
		(net "M_G_CPU0_SB_DQS_DN<8>")
	)
	(segment
		(start 443.450726 -199.447912)
		(end 443.455552 -199.447912)
		(width 0.101854)
		(layer "F.Cu")
		(net "M_G_CPU0_SB_DQS_DN<8>")
	)
	(segment
		(start 446.577212 -199.166988)
		(end 447.022728 -199.612504)
		(width 0.20066)
		(layer "F.Cu")
		(net "M_G_CPU0_SB_DQS_DN<8>")
	)
	(segment
		(start 445.801496 -199.452738)
		(end 446.087246 -199.166988)
		(width 0.20066)
		(layer "F.Cu")
		(net "M_G_CPU0_SB_DQS_DN<8>")
	)
	(segment
		(start 441.559188 -199.866758)
		(end 441.83046 -199.595486)
		(width 0.20066)
		(layer "F.Cu")
		(net "M_G_CPU0_SB_DQS_DN<8>")
	)
	(segment
		(start 384.95478 -218.414346)
		(end 384.955034 -217.878406)
		(width 0.20066)
		(layer "F.Cu")
		(net "M_G_CPU0_SB_DQS_DN<8>")
	)
	(segment
		(start 448.0687 -199.866758)
		(end 448.572382 -199.866758)
		(width 0.20066)
		(layer "F.Cu")
		(net "M_G_CPU0_SB_DQS_DN<8>")
	)
	(segment
		(start 446.087246 -199.166988)
		(end 446.577212 -199.166988)
		(width 0.20066)
		(layer "F.Cu")
		(net "M_G_CPU0_SB_DQS_DN<8>")
	)
	(segment
		(start 447.022728 -199.612504)
		(end 447.814446 -199.612504)
		(width 0.20066)
		(layer "F.Cu")
		(net "M_G_CPU0_SB_DQS_DN<8>")
	)
	(segment
		(start 441.83046 -199.595486)
		(end 442.313822 -199.595486)
		(width 0.20066)
		(layer "F.Cu")
		(net "M_G_CPU0_SB_DQS_DN<8>")
	)
	(segment
		(start 447.814446 -199.612504)
		(end 448.0687 -199.866758)
		(width 0.20066)
		(layer "F.Cu")
		(net "M_G_CPU0_SB_DQS_DN<8>")
	)
	(segment
		(start 441.028582 -199.866758)
		(end 441.559188 -199.866758)
		(width 0.20066)
		(layer "F.Cu")
		(net "M_G_CPU0_SB_DQS_DN<8>")
	)
	(segment
		(start 445.482726 -199.452738)
		(end 445.801496 -199.452738)
		(width 0.20066)
		(layer "F.Cu")
		(net "M_G_CPU0_SB_DQS_DN<8>")
	)
	(segment
		(start 432.378866 -199.18045)
		(end 430.789842 -198.521828)
		(width 0.18288)
		(layer "In6.Cu")
		(net "M_G_CPU0_SB_DQS_DN<8>")
	)
	(segment
		(start 421.192452 -197.46595)
		(end 420.917624 -197.740778)
		(width 0.18288)
		(layer "In6.Cu")
		(net "M_G_CPU0_SB_DQS_DN<8>")
	)
	(segment
		(start 424.646344 -198.590916)
		(end 424.393614 -198.338186)
		(width 0.18288)
		(layer "In6.Cu")
		(net "M_G_CPU0_SB_DQS_DN<8>")
	)
	(segment
		(start 420.285672 -197.474078)
		(end 417.279582 -197.474078)
		(width 0.18288)
		(layer "In6.Cu")
		(net "M_G_CPU0_SB_DQS_DN<8>")
	)
	(segment
		(start 422.060878 -197.61708)
		(end 421.697912 -197.46595)
		(width 0.18288)
		(layer "In6.Cu")
		(net "M_G_CPU0_SB_DQS_DN<8>")
	)
	(segment
		(start 428.077122 -198.521828)
		(end 427.88332 -198.602346)
		(width 0.18288)
		(layer "In6.Cu")
		(net "M_G_CPU0_SB_DQS_DN<8>")
	)
	(segment
		(start 389.69442 -215.944958)
		(end 389.53694 -216.102438)
		(width 0.088646)
		(layer "In6.Cu")
		(net "M_G_CPU0_SB_DQS_DN<8>")
	)
	(segment
		(start 425.304458 -198.330566)
		(end 425.044108 -198.590916)
		(width 0.18288)
		(layer "In6.Cu")
		(net "M_G_CPU0_SB_DQS_DN<8>")
	)
	(segment
		(start 439.923682 -199.866758)
		(end 439.671714 -199.61479)
		(width 0.18288)
		(layer "In6.Cu")
		(net "M_G_CPU0_SB_DQS_DN<8>")
	)
	(segment
		(start 405.782272 -198.129906)
		(end 396.635224 -207.276954)
		(width 0.18288)
		(layer "In6.Cu")
		(net "M_G_CPU0_SB_DQS_DN<8>")
	)
	(segment
		(start 389.53694 -216.946226)
		(end 388.979918 -217.503248)
		(width 0.088646)
		(layer "In6.Cu")
		(net "M_G_CPU0_SB_DQS_DN<8>")
	)
	(segment
		(start 436.278274 -199.18045)
		(end 436.017924 -199.4408)
		(width 0.18288)
		(layer "In6.Cu")
		(net "M_G_CPU0_SB_DQS_DN<8>")
	)
	(segment
		(start 427.29785 -198.958708)
		(end 426.564552 -198.958708)
		(width 0.18288)
		(layer "In6.Cu")
		(net "M_G_CPU0_SB_DQS_DN<8>")
	)
	(segment
		(start 385.111498 -217.607388)
		(end 384.955034 -217.878406)
		(width 0.088646)
		(layer "In6.Cu")
		(net "M_G_CPU0_SB_DQS_DN<8>")
	)
	(segment
		(start 388.526782 -217.554048)
		(end 388.51205 -217.562684)
		(width 0.088646)
		(layer "In6.Cu")
		(net "M_G_CPU0_SB_DQS_DN<8>")
	)
	(segment
		(start 409.052014 -197.725538)
		(end 408.078686 -198.129906)
		(width 0.18288)
		(layer "In6.Cu")
		(net "M_G_CPU0_SB_DQS_DN<8>")
	)
	(segment
		(start 420.552372 -197.740778)
		(end 420.285672 -197.474078)
		(width 0.18288)
		(layer "In6.Cu")
		(net "M_G_CPU0_SB_DQS_DN<8>")
	)
	(segment
		(start 427.689264 -198.796148)
		(end 427.29785 -198.958708)
		(width 0.18288)
		(layer "In6.Cu")
		(net "M_G_CPU0_SB_DQS_DN<8>")
	)
	(segment
		(start 435.339998 -199.18045)
		(end 432.378866 -199.18045)
		(width 0.18288)
		(layer "In6.Cu")
		(net "M_G_CPU0_SB_DQS_DN<8>")
	)
	(segment
		(start 436.017924 -199.4408)
		(end 435.600348 -199.4408)
		(width 0.18288)
		(layer "In6.Cu")
		(net "M_G_CPU0_SB_DQS_DN<8>")
	)
	(segment
		(start 412.27883 -197.725538)
		(end 409.052014 -197.725538)
		(width 0.18288)
		(layer "In6.Cu")
		(net "M_G_CPU0_SB_DQS_DN<8>")
	)
	(segment
		(start 421.697912 -197.46595)
		(end 421.192452 -197.46595)
		(width 0.18288)
		(layer "In6.Cu")
		(net "M_G_CPU0_SB_DQS_DN<8>")
	)
	(segment
		(start 408.078686 -198.129906)
		(end 405.782272 -198.129906)
		(width 0.18288)
		(layer "In6.Cu")
		(net "M_G_CPU0_SB_DQS_DN<8>")
	)
	(segment
		(start 438.405016 -199.802242)
		(end 438.006236 -199.802242)
		(width 0.18288)
		(layer "In6.Cu")
		(net "M_G_CPU0_SB_DQS_DN<8>")
	)
	(segment
		(start 424.393614 -198.338186)
		(end 423.361104 -198.338186)
		(width 0.18288)
		(layer "In6.Cu")
		(net "M_G_CPU0_SB_DQS_DN<8>")
	)
	(segment
		(start 385.200398 -217.583766)
		(end 385.111498 -217.607388)
		(width 0.088646)
		(layer "In6.Cu")
		(net "M_G_CPU0_SB_DQS_DN<8>")
	)
	(segment
		(start 396.635224 -209.08899)
		(end 389.795766 -215.928448)
		(width 0.18288)
		(layer "In6.Cu")
		(net "M_G_CPU0_SB_DQS_DN<8>")
	)
	(segment
		(start 425.871132 -198.456804)
		(end 425.568364 -198.330566)
		(width 0.18288)
		(layer "In6.Cu")
		(net "M_G_CPU0_SB_DQS_DN<8>")
	)
	(segment
		(start 426.236384 -198.822056)
		(end 425.871132 -198.456804)
		(width 0.18288)
		(layer "In6.Cu")
		(net "M_G_CPU0_SB_DQS_DN<8>")
	)
	(segment
		(start 389.779256 -215.944958)
		(end 389.69442 -215.944958)
		(width 0.088646)
		(layer "In6.Cu")
		(net "M_G_CPU0_SB_DQS_DN<8>")
	)
	(segment
		(start 396.635224 -207.276954)
		(end 396.635224 -209.08899)
		(width 0.18288)
		(layer "In6.Cu")
		(net "M_G_CPU0_SB_DQS_DN<8>")
	)
	(segment
		(start 423.361104 -198.338186)
		(end 422.37025 -197.926452)
		(width 0.18288)
		(layer "In6.Cu")
		(net "M_G_CPU0_SB_DQS_DN<8>")
	)
	(segment
		(start 438.006236 -199.802242)
		(end 436.501032 -199.18045)
		(width 0.18288)
		(layer "In6.Cu")
		(net "M_G_CPU0_SB_DQS_DN<8>")
	)
	(segment
		(start 389.53694 -216.102438)
		(end 389.53694 -216.946226)
		(width 0.088646)
		(layer "In6.Cu")
		(net "M_G_CPU0_SB_DQS_DN<8>")
	)
	(segment
		(start 436.501032 -199.18045)
		(end 436.278274 -199.18045)
		(width 0.18288)
		(layer "In6.Cu")
		(net "M_G_CPU0_SB_DQS_DN<8>")
	)
	(segment
		(start 439.671714 -199.61479)
		(end 439.34761 -199.61479)
		(width 0.18288)
		(layer "In6.Cu")
		(net "M_G_CPU0_SB_DQS_DN<8>")
	)
	(segment
		(start 417.279582 -197.474078)
		(end 415.721292 -198.119746)
		(width 0.18288)
		(layer "In6.Cu")
		(net "M_G_CPU0_SB_DQS_DN<8>")
	)
	(segment
		(start 435.600348 -199.4408)
		(end 435.339998 -199.18045)
		(width 0.18288)
		(layer "In6.Cu")
		(net "M_G_CPU0_SB_DQS_DN<8>")
	)
	(segment
		(start 389.795766 -215.928448)
		(end 389.779256 -215.944958)
		(width 0.088646)
		(layer "In6.Cu")
		(net "M_G_CPU0_SB_DQS_DN<8>")
	)
	(segment
		(start 427.88332 -198.602346)
		(end 427.689264 -198.796148)
		(width 0.18288)
		(layer "In6.Cu")
		(net "M_G_CPU0_SB_DQS_DN<8>")
	)
	(segment
		(start 387.586982 -217.554048)
		(end 387.57225 -217.562684)
		(width 0.088646)
		(layer "In6.Cu")
		(net "M_G_CPU0_SB_DQS_DN<8>")
	)
	(segment
		(start 425.044108 -198.590916)
		(end 424.646344 -198.590916)
		(width 0.18288)
		(layer "In6.Cu")
		(net "M_G_CPU0_SB_DQS_DN<8>")
	)
	(segment
		(start 388.979918 -217.503248)
		(end 388.71398 -217.503248)
		(width 0.088646)
		(layer "In6.Cu")
		(net "M_G_CPU0_SB_DQS_DN<8>")
	)
	(segment
		(start 425.568364 -198.330566)
		(end 425.304458 -198.330566)
		(width 0.18288)
		(layer "In6.Cu")
		(net "M_G_CPU0_SB_DQS_DN<8>")
	)
	(segment
		(start 420.917624 -197.740778)
		(end 420.552372 -197.740778)
		(width 0.18288)
		(layer "In6.Cu")
		(net "M_G_CPU0_SB_DQS_DN<8>")
	)
	(segment
		(start 415.721292 -198.119746)
		(end 413.101028 -198.119746)
		(width 0.18288)
		(layer "In6.Cu")
		(net "M_G_CPU0_SB_DQS_DN<8>")
	)
	(segment
		(start 430.789842 -198.521828)
		(end 428.077122 -198.521828)
		(width 0.18288)
		(layer "In6.Cu")
		(net "M_G_CPU0_SB_DQS_DN<8>")
	)
	(segment
		(start 413.101028 -198.119746)
		(end 412.27883 -197.725538)
		(width 0.18288)
		(layer "In6.Cu")
		(net "M_G_CPU0_SB_DQS_DN<8>")
	)
	(segment
		(start 422.37025 -197.926452)
		(end 422.060878 -197.61708)
		(width 0.18288)
		(layer "In6.Cu")
		(net "M_G_CPU0_SB_DQS_DN<8>")
	)
	(segment
		(start 439.34761 -199.61479)
		(end 438.405016 -199.802242)
		(width 0.18288)
		(layer "In6.Cu")
		(net "M_G_CPU0_SB_DQS_DN<8>")
	)
	(segment
		(start 426.564552 -198.958708)
		(end 426.236384 -198.822056)
		(width 0.18288)
		(layer "In6.Cu")
		(net "M_G_CPU0_SB_DQS_DN<8>")
	)
	(arc
		(start 386.647182 -217.554048)
		(mid 386.364734 -217.629663)
		(end 386.082286 -217.554048)
		(width 0.088646)
		(layer "In6.Cu")
		(net "M_G_CPU0_SB_DQS_DN<8>")
	)
	(arc
		(start 388.51205 -217.562684)
		(mid 388.235609 -217.62985)
		(end 387.961378 -217.554048)
		(width 0.088646)
		(layer "In6.Cu")
		(net "M_G_CPU0_SB_DQS_DN<8>")
	)
	(arc
		(start 387.57225 -217.562684)
		(mid 387.295809 -217.62985)
		(end 387.021578 -217.554048)
		(width 0.088646)
		(layer "In6.Cu")
		(net "M_G_CPU0_SB_DQS_DN<8>")
	)
	(arc
		(start 387.021578 -217.554048)
		(mid 386.83438 -217.503905)
		(end 386.647182 -217.554048)
		(width 0.088646)
		(layer "In6.Cu")
		(net "M_G_CPU0_SB_DQS_DN<8>")
	)
	(arc
		(start 386.082286 -217.554048)
		(mid 385.895088 -217.503905)
		(end 385.70789 -217.554048)
		(width 0.088646)
		(layer "In6.Cu")
		(net "M_G_CPU0_SB_DQS_DN<8>")
	)
	(arc
		(start 387.961378 -217.554048)
		(mid 387.77418 -217.503905)
		(end 387.586982 -217.554048)
		(width 0.088646)
		(layer "In6.Cu")
		(net "M_G_CPU0_SB_DQS_DN<8>")
	)
	(arc
		(start 385.220464 -217.591894)
		(mid 385.210392 -217.587927)
		(end 385.200398 -217.583766)
		(width 0.088646)
		(layer "In6.Cu")
		(net "M_G_CPU0_SB_DQS_DN<8>")
	)
	(arc
		(start 388.71398 -217.503248)
		(mid 388.617041 -217.516338)
		(end 388.526782 -217.554048)
		(width 0.088646)
		(layer "In6.Cu")
		(net "M_G_CPU0_SB_DQS_DN<8>")
	)
	(arc
		(start 385.70789 -217.554048)
		(mid 385.468477 -217.62838)
		(end 385.220464 -217.591894)
		(width 0.088646)
		(layer "In6.Cu")
		(net "M_G_CPU0_SB_DQS_DN<8>")
	)
	(segment
		(start 445.482726 -208.802732)
		(end 445.801496 -208.802732)
		(width 0.20066)
		(layer "F.Cu")
		(net "M_G_CPU0_SB_DQS_DN<7>")
	)
	(segment
		(start 441.559188 -209.216752)
		(end 441.83046 -208.94548)
		(width 0.20066)
		(layer "F.Cu")
		(net "M_G_CPU0_SB_DQS_DN<7>")
	)
	(segment
		(start 446.087246 -208.516982)
		(end 446.577212 -208.516982)
		(width 0.20066)
		(layer "F.Cu")
		(net "M_G_CPU0_SB_DQS_DN<7>")
	)
	(segment
		(start 445.471804 -208.79181)
		(end 445.482726 -208.802732)
		(width 0.1016)
		(layer "F.Cu")
		(net "M_G_CPU0_SB_DQS_DN<7>")
	)
	(segment
		(start 443.461648 -208.79181)
		(end 445.471804 -208.79181)
		(width 0.1016)
		(layer "F.Cu")
		(net "M_G_CPU0_SB_DQS_DN<7>")
	)
	(segment
		(start 380.25578 -232.528618)
		(end 380.256034 -232.528364)
		(width 0.20066)
		(layer "F.Cu")
		(net "M_G_CPU0_SB_DQS_DN<7>")
	)
	(segment
		(start 443.450726 -208.797906)
		(end 443.455552 -208.797906)
		(width 0.101854)
		(layer "F.Cu")
		(net "M_G_CPU0_SB_DQS_DN<7>")
	)
	(segment
		(start 443.455552 -208.797906)
		(end 443.461648 -208.79181)
		(width 0.1016)
		(layer "F.Cu")
		(net "M_G_CPU0_SB_DQS_DN<7>")
	)
	(segment
		(start 442.738764 -208.520538)
		(end 442.861192 -208.520538)
		(width 0.20066)
		(layer "F.Cu")
		(net "M_G_CPU0_SB_DQS_DN<7>")
	)
	(segment
		(start 439.923682 -209.216752)
		(end 441.028582 -209.216752)
		(width 0.20066)
		(layer "F.Cu")
		(net "M_G_CPU0_SB_DQS_DN<7>")
	)
	(segment
		(start 441.028582 -209.216752)
		(end 441.559188 -209.216752)
		(width 0.20066)
		(layer "F.Cu")
		(net "M_G_CPU0_SB_DQS_DN<7>")
	)
	(segment
		(start 443.13856 -208.797906)
		(end 443.450726 -208.797906)
		(width 0.20066)
		(layer "F.Cu")
		(net "M_G_CPU0_SB_DQS_DN<7>")
	)
	(segment
		(start 380.25578 -233.064304)
		(end 380.25578 -232.528618)
		(width 0.20066)
		(layer "F.Cu")
		(net "M_G_CPU0_SB_DQS_DN<7>")
	)
	(segment
		(start 442.313822 -208.94548)
		(end 442.738764 -208.520538)
		(width 0.20066)
		(layer "F.Cu")
		(net "M_G_CPU0_SB_DQS_DN<7>")
	)
	(segment
		(start 445.801496 -208.802732)
		(end 446.087246 -208.516982)
		(width 0.20066)
		(layer "F.Cu")
		(net "M_G_CPU0_SB_DQS_DN<7>")
	)
	(segment
		(start 446.577212 -208.516982)
		(end 447.022728 -208.962498)
		(width 0.20066)
		(layer "F.Cu")
		(net "M_G_CPU0_SB_DQS_DN<7>")
	)
	(segment
		(start 442.861192 -208.520538)
		(end 443.13856 -208.797906)
		(width 0.20066)
		(layer "F.Cu")
		(net "M_G_CPU0_SB_DQS_DN<7>")
	)
	(segment
		(start 447.022728 -208.962498)
		(end 447.814446 -208.962498)
		(width 0.20066)
		(layer "F.Cu")
		(net "M_G_CPU0_SB_DQS_DN<7>")
	)
	(segment
		(start 441.83046 -208.94548)
		(end 442.313822 -208.94548)
		(width 0.20066)
		(layer "F.Cu")
		(net "M_G_CPU0_SB_DQS_DN<7>")
	)
	(segment
		(start 448.0687 -209.216752)
		(end 448.572382 -209.216752)
		(width 0.20066)
		(layer "F.Cu")
		(net "M_G_CPU0_SB_DQS_DN<7>")
	)
	(segment
		(start 447.814446 -208.962498)
		(end 448.0687 -209.216752)
		(width 0.20066)
		(layer "F.Cu")
		(net "M_G_CPU0_SB_DQS_DN<7>")
	)
	(segment
		(start 386.930138 -228.431344)
		(end 386.930138 -228.468428)
		(width 0.088646)
		(layer "In4.Cu")
		(net "M_G_CPU0_SB_DQS_DN<7>")
	)
	(segment
		(start 380.875794 -232.28046)
		(end 380.723902 -232.3211)
		(width 0.088646)
		(layer "In4.Cu")
		(net "M_G_CPU0_SB_DQS_DN<7>")
	)
	(segment
		(start 415.10331 -211.840826)
		(end 414.55721 -211.840826)
		(width 0.18288)
		(layer "In4.Cu")
		(net "M_G_CPU0_SB_DQS_DN<7>")
	)
	(segment
		(start 439.4073 -208.93532)
		(end 439.115454 -208.813908)
		(width 0.18288)
		(layer "In4.Cu")
		(net "M_G_CPU0_SB_DQS_DN<7>")
	)
	(segment
		(start 381.948436 -232.204006)
		(end 381.938022 -232.210102)
		(width 0.088646)
		(layer "In4.Cu")
		(net "M_G_CPU0_SB_DQS_DN<7>")
	)
	(segment
		(start 429.599598 -210.550506)
		(end 429.053498 -210.550506)
		(width 0.18288)
		(layer "In4.Cu")
		(net "M_G_CPU0_SB_DQS_DN<7>")
	)
	(segment
		(start 381.383032 -232.20426)
		(end 381.382778 -232.204006)
		(width 0.088646)
		(layer "In4.Cu")
		(net "M_G_CPU0_SB_DQS_DN<7>")
	)
	(segment
		(start 418.018214 -211.381086)
		(end 417.893754 -211.256626)
		(width 0.18288)
		(layer "In4.Cu")
		(net "M_G_CPU0_SB_DQS_DN<7>")
	)
	(segment
		(start 407.149554 -211.86013)
		(end 406.603454 -211.86013)
		(width 0.18288)
		(layer "In4.Cu")
		(net "M_G_CPU0_SB_DQS_DN<7>")
	)
	(segment
		(start 405.932894 -211.73567)
		(end 390.67486 -226.993704)
		(width 0.18288)
		(layer "In4.Cu")
		(net "M_G_CPU0_SB_DQS_DN<7>")
	)
	(segment
		(start 413.09163 -211.716366)
		(end 412.54553 -211.716366)
		(width 0.18288)
		(layer "In4.Cu")
		(net "M_G_CPU0_SB_DQS_DN<7>")
	)
	(segment
		(start 420.252652 -211.05241)
		(end 419.43909 -211.05241)
		(width 0.18288)
		(layer "In4.Cu")
		(net "M_G_CPU0_SB_DQS_DN<7>")
	)
	(segment
		(start 390.67486 -226.993704)
		(end 388.71271 -226.993704)
		(width 0.18288)
		(layer "In4.Cu")
		(net "M_G_CPU0_SB_DQS_DN<7>")
	)
	(segment
		(start 420.544244 -211.344002)
		(end 420.252652 -211.05241)
		(width 0.18288)
		(layer "In4.Cu")
		(net "M_G_CPU0_SB_DQS_DN<7>")
	)
	(segment
		(start 425.311316 -211.91093)
		(end 425.02836 -212.193886)
		(width 0.18288)
		(layer "In4.Cu")
		(net "M_G_CPU0_SB_DQS_DN<7>")
	)
	(segment
		(start 435.631844 -208.793842)
		(end 435.340252 -208.50225)
		(width 0.18288)
		(layer "In4.Cu")
		(net "M_G_CPU0_SB_DQS_DN<7>")
	)
	(segment
		(start 413.88665 -211.716366)
		(end 413.76219 -211.840826)
		(width 0.18288)
		(layer "In4.Cu")
		(net "M_G_CPU0_SB_DQS_DN<7>")
	)
	(segment
		(start 418.564314 -211.381086)
		(end 418.018214 -211.381086)
		(width 0.18288)
		(layer "In4.Cu")
		(net "M_G_CPU0_SB_DQS_DN<7>")
	)
	(segment
		(start 410.344366 -211.322666)
		(end 409.236164 -211.322666)
		(width 0.18288)
		(layer "In4.Cu")
		(net "M_G_CPU0_SB_DQS_DN<7>")
	)
	(segment
		(start 386.177536 -229.762304)
		(end 386.168646 -229.767384)
		(width 0.088646)
		(layer "In4.Cu")
		(net "M_G_CPU0_SB_DQS_DN<7>")
	)
	(segment
		(start 429.724058 -210.426046)
		(end 429.599598 -210.550506)
		(width 0.18288)
		(layer "In4.Cu")
		(net "M_G_CPU0_SB_DQS_DN<7>")
	)
	(segment
		(start 430.876456 -210.111594)
		(end 430.876964 -210.112102)
		(width 0.18288)
		(layer "In4.Cu")
		(net "M_G_CPU0_SB_DQS_DN<7>")
	)
	(segment
		(start 431.262536 -209.725514)
		(end 430.876456 -210.111594)
		(width 0.18288)
		(layer "In4.Cu")
		(net "M_G_CPU0_SB_DQS_DN<7>")
	)
	(segment
		(start 411.139386 -211.322666)
		(end 411.014926 -211.447126)
		(width 0.18288)
		(layer "In4.Cu")
		(net "M_G_CPU0_SB_DQS_DN<7>")
	)
	(segment
		(start 434.90642 -208.50225)
		(end 434.31206 -208.256124)
		(width 0.18288)
		(layer "In4.Cu")
		(net "M_G_CPU0_SB_DQS_DN<7>")
	)
	(segment
		(start 427.73092 -210.426046)
		(end 426.246036 -211.91093)
		(width 0.18288)
		(layer "In4.Cu")
		(net "M_G_CPU0_SB_DQS_DN<7>")
	)
	(segment
		(start 431.824892 -209.33918)
		(end 431.438558 -209.725514)
		(width 0.18288)
		(layer "In4.Cu")
		(net "M_G_CPU0_SB_DQS_DN<7>")
	)
	(segment
		(start 422.015666 -211.061046)
		(end 421.211248 -211.061046)
		(width 0.18288)
		(layer "In4.Cu")
		(net "M_G_CPU0_SB_DQS_DN<7>")
	)
	(segment
		(start 421.211248 -211.061046)
		(end 420.928292 -211.344002)
		(width 0.18288)
		(layer "In4.Cu")
		(net "M_G_CPU0_SB_DQS_DN<7>")
	)
	(segment
		(start 410.468826 -211.447126)
		(end 410.344366 -211.322666)
		(width 0.18288)
		(layer "In4.Cu")
		(net "M_G_CPU0_SB_DQS_DN<7>")
	)
	(segment
		(start 438.500774 -208.51876)
		(end 438.225692 -208.793842)
		(width 0.18288)
		(layer "In4.Cu")
		(net "M_G_CPU0_SB_DQS_DN<7>")
	)
	(segment
		(start 380.723902 -232.3211)
		(end 380.330456 -232.3211)
		(width 0.088646)
		(layer "In4.Cu")
		(net "M_G_CPU0_SB_DQS_DN<7>")
	)
	(segment
		(start 407.274014 -211.73567)
		(end 407.149554 -211.86013)
		(width 0.18288)
		(layer "In4.Cu")
		(net "M_G_CPU0_SB_DQS_DN<7>")
	)
	(segment
		(start 420.928292 -211.344002)
		(end 420.544244 -211.344002)
		(width 0.18288)
		(layer "In4.Cu")
		(net "M_G_CPU0_SB_DQS_DN<7>")
	)
	(segment
		(start 428.929038 -210.426046)
		(end 427.73092 -210.426046)
		(width 0.18288)
		(layer "In4.Cu")
		(net "M_G_CPU0_SB_DQS_DN<7>")
	)
	(segment
		(start 416.727894 -211.256626)
		(end 416.268154 -211.716366)
		(width 0.18288)
		(layer "In4.Cu")
		(net "M_G_CPU0_SB_DQS_DN<7>")
	)
	(segment
		(start 430.368202 -210.426046)
		(end 429.724058 -210.426046)
		(width 0.18288)
		(layer "In4.Cu")
		(net "M_G_CPU0_SB_DQS_DN<7>")
	)
	(segment
		(start 429.053498 -210.550506)
		(end 428.929038 -210.426046)
		(width 0.18288)
		(layer "In4.Cu")
		(net "M_G_CPU0_SB_DQS_DN<7>")
	)
	(segment
		(start 385.520184 -230.900478)
		(end 385.520184 -230.91902)
		(width 0.088646)
		(layer "In4.Cu")
		(net "M_G_CPU0_SB_DQS_DN<7>")
	)
	(segment
		(start 411.014926 -211.447126)
		(end 410.468826 -211.447126)
		(width 0.18288)
		(layer "In4.Cu")
		(net "M_G_CPU0_SB_DQS_DN<7>")
	)
	(segment
		(start 439.103008 -208.807558)
		(end 438.81421 -208.51876)
		(width 0.18288)
		(layer "In4.Cu")
		(net "M_G_CPU0_SB_DQS_DN<7>")
	)
	(segment
		(start 419.43909 -211.05241)
		(end 419.234874 -211.256626)
		(width 0.18288)
		(layer "In4.Cu")
		(net "M_G_CPU0_SB_DQS_DN<7>")
	)
	(segment
		(start 385.050284 -231.714548)
		(end 385.050284 -231.73309)
		(width 0.088646)
		(layer "In4.Cu")
		(net "M_G_CPU0_SB_DQS_DN<7>")
	)
	(segment
		(start 430.876964 -210.112102)
		(end 430.700688 -210.288378)
		(width 0.18288)
		(layer "In4.Cu")
		(net "M_G_CPU0_SB_DQS_DN<7>")
	)
	(segment
		(start 436.31739 -208.492344)
		(end 436.015892 -208.793842)
		(width 0.18288)
		(layer "In4.Cu")
		(net "M_G_CPU0_SB_DQS_DN<7>")
	)
	(segment
		(start 439.115454 -208.813908)
		(end 439.103008 -208.807558)
		(width 0.18288)
		(layer "In4.Cu")
		(net "M_G_CPU0_SB_DQS_DN<7>")
	)
	(segment
		(start 384.767836 -232.20426)
		(end 384.767836 -232.204006)
		(width 0.088646)
		(layer "In4.Cu")
		(net "M_G_CPU0_SB_DQS_DN<7>")
	)
	(segment
		(start 386.647436 -228.948488)
		(end 386.633212 -228.956616)
		(width 0.088646)
		(layer "In4.Cu")
		(net "M_G_CPU0_SB_DQS_DN<7>")
	)
	(segment
		(start 412.15183 -211.322666)
		(end 411.139386 -211.322666)
		(width 0.18288)
		(layer "In4.Cu")
		(net "M_G_CPU0_SB_DQS_DN<7>")
	)
	(segment
		(start 424.644312 -212.193886)
		(end 424.328082 -211.877656)
		(width 0.18288)
		(layer "In4.Cu")
		(net "M_G_CPU0_SB_DQS_DN<7>")
	)
	(segment
		(start 385.707636 -230.57612)
		(end 385.698746 -230.5812)
		(width 0.088646)
		(layer "In4.Cu")
		(net "M_G_CPU0_SB_DQS_DN<7>")
	)
	(segment
		(start 439.923682 -209.216752)
		(end 439.898282 -209.216752)
		(width 0.18288)
		(layer "In4.Cu")
		(net "M_G_CPU0_SB_DQS_DN<7>")
	)
	(segment
		(start 437.540146 -208.492344)
		(end 436.31739 -208.492344)
		(width 0.18288)
		(layer "In4.Cu")
		(net "M_G_CPU0_SB_DQS_DN<7>")
	)
	(segment
		(start 415.22777 -211.716366)
		(end 415.10331 -211.840826)
		(width 0.18288)
		(layer "In4.Cu")
		(net "M_G_CPU0_SB_DQS_DN<7>")
	)
	(segment
		(start 381.008382 -232.204006)
		(end 380.875794 -232.28046)
		(width 0.088646)
		(layer "In4.Cu")
		(net "M_G_CPU0_SB_DQS_DN<7>")
	)
	(segment
		(start 385.990084 -230.086662)
		(end 385.990084 -230.096568)
		(width 0.088646)
		(layer "In4.Cu")
		(net "M_G_CPU0_SB_DQS_DN<7>")
	)
	(segment
		(start 437.841644 -208.793842)
		(end 437.540146 -208.492344)
		(width 0.18288)
		(layer "In4.Cu")
		(net "M_G_CPU0_SB_DQS_DN<7>")
	)
	(segment
		(start 380.256034 -232.395522)
		(end 380.256034 -232.528364)
		(width 0.088646)
		(layer "In4.Cu")
		(net "M_G_CPU0_SB_DQS_DN<7>")
	)
	(segment
		(start 417.893754 -211.256626)
		(end 416.727894 -211.256626)
		(width 0.18288)
		(layer "In4.Cu")
		(net "M_G_CPU0_SB_DQS_DN<7>")
	)
	(segment
		(start 388.629398 -226.93376)
		(end 388.427722 -226.93376)
		(width 0.088646)
		(layer "In4.Cu")
		(net "M_G_CPU0_SB_DQS_DN<7>")
	)
	(segment
		(start 434.31206 -208.256124)
		(end 432.731926 -208.256124)
		(width 0.18288)
		(layer "In4.Cu")
		(net "M_G_CPU0_SB_DQS_DN<7>")
	)
	(segment
		(start 419.234874 -211.256626)
		(end 418.688774 -211.256626)
		(width 0.18288)
		(layer "In4.Cu")
		(net "M_G_CPU0_SB_DQS_DN<7>")
	)
	(segment
		(start 435.340252 -208.50225)
		(end 434.90642 -208.50225)
		(width 0.18288)
		(layer "In4.Cu")
		(net "M_G_CPU0_SB_DQS_DN<7>")
	)
	(segment
		(start 431.438558 -209.725514)
		(end 431.262536 -209.725514)
		(width 0.18288)
		(layer "In4.Cu")
		(net "M_G_CPU0_SB_DQS_DN<7>")
	)
	(segment
		(start 413.76219 -211.840826)
		(end 413.21609 -211.840826)
		(width 0.18288)
		(layer "In4.Cu")
		(net "M_G_CPU0_SB_DQS_DN<7>")
	)
	(segment
		(start 416.268154 -211.716366)
		(end 415.22777 -211.716366)
		(width 0.18288)
		(layer "In4.Cu")
		(net "M_G_CPU0_SB_DQS_DN<7>")
	)
	(segment
		(start 388.689342 -226.993704)
		(end 388.629398 -226.93376)
		(width 0.088646)
		(layer "In4.Cu")
		(net "M_G_CPU0_SB_DQS_DN<7>")
	)
	(segment
		(start 430.700688 -210.288378)
		(end 430.368202 -210.426046)
		(width 0.18288)
		(layer "In4.Cu")
		(net "M_G_CPU0_SB_DQS_DN<7>")
	)
	(segment
		(start 422.832276 -211.877656)
		(end 422.015666 -211.061046)
		(width 0.18288)
		(layer "In4.Cu")
		(net "M_G_CPU0_SB_DQS_DN<7>")
	)
	(segment
		(start 414.55721 -211.840826)
		(end 414.43275 -211.716366)
		(width 0.18288)
		(layer "In4.Cu")
		(net "M_G_CPU0_SB_DQS_DN<7>")
	)
	(segment
		(start 406.603454 -211.86013)
		(end 406.478994 -211.73567)
		(width 0.18288)
		(layer "In4.Cu")
		(net "M_G_CPU0_SB_DQS_DN<7>")
	)
	(segment
		(start 409.236164 -211.322666)
		(end 408.82316 -211.73567)
		(width 0.18288)
		(layer "In4.Cu")
		(net "M_G_CPU0_SB_DQS_DN<7>")
	)
	(segment
		(start 431.824892 -209.163158)
		(end 431.824892 -209.33918)
		(width 0.18288)
		(layer "In4.Cu")
		(net "M_G_CPU0_SB_DQS_DN<7>")
	)
	(segment
		(start 412.54553 -211.716366)
		(end 412.15183 -211.322666)
		(width 0.18288)
		(layer "In4.Cu")
		(net "M_G_CPU0_SB_DQS_DN<7>")
	)
	(segment
		(start 388.71271 -226.993704)
		(end 388.689342 -226.993704)
		(width 0.088646)
		(layer "In4.Cu")
		(net "M_G_CPU0_SB_DQS_DN<7>")
	)
	(segment
		(start 425.02836 -212.193886)
		(end 424.644312 -212.193886)
		(width 0.18288)
		(layer "In4.Cu")
		(net "M_G_CPU0_SB_DQS_DN<7>")
	)
	(segment
		(start 406.478994 -211.73567)
		(end 405.932894 -211.73567)
		(width 0.18288)
		(layer "In4.Cu")
		(net "M_G_CPU0_SB_DQS_DN<7>")
	)
	(segment
		(start 385.237736 -231.39019)
		(end 385.228846 -231.39527)
		(width 0.088646)
		(layer "In4.Cu")
		(net "M_G_CPU0_SB_DQS_DN<7>")
	)
	(segment
		(start 413.21609 -211.840826)
		(end 413.09163 -211.716366)
		(width 0.18288)
		(layer "In4.Cu")
		(net "M_G_CPU0_SB_DQS_DN<7>")
	)
	(segment
		(start 439.61685 -208.93532)
		(end 439.4073 -208.93532)
		(width 0.18288)
		(layer "In4.Cu")
		(net "M_G_CPU0_SB_DQS_DN<7>")
	)
	(segment
		(start 386.459984 -229.272592)
		(end 386.459984 -229.282752)
		(width 0.088646)
		(layer "In4.Cu")
		(net "M_G_CPU0_SB_DQS_DN<7>")
	)
	(segment
		(start 388.427722 -226.93376)
		(end 386.930138 -228.431344)
		(width 0.088646)
		(layer "In4.Cu")
		(net "M_G_CPU0_SB_DQS_DN<7>")
	)
	(segment
		(start 438.225692 -208.793842)
		(end 437.841644 -208.793842)
		(width 0.18288)
		(layer "In4.Cu")
		(net "M_G_CPU0_SB_DQS_DN<7>")
	)
	(segment
		(start 438.81421 -208.51876)
		(end 438.500774 -208.51876)
		(width 0.18288)
		(layer "In4.Cu")
		(net "M_G_CPU0_SB_DQS_DN<7>")
	)
	(segment
		(start 414.43275 -211.716366)
		(end 413.88665 -211.716366)
		(width 0.18288)
		(layer "In4.Cu")
		(net "M_G_CPU0_SB_DQS_DN<7>")
	)
	(segment
		(start 408.82316 -211.73567)
		(end 407.274014 -211.73567)
		(width 0.18288)
		(layer "In4.Cu")
		(net "M_G_CPU0_SB_DQS_DN<7>")
	)
	(segment
		(start 439.898282 -209.216752)
		(end 439.61685 -208.93532)
		(width 0.18288)
		(layer "In4.Cu")
		(net "M_G_CPU0_SB_DQS_DN<7>")
	)
	(segment
		(start 436.015892 -208.793842)
		(end 435.631844 -208.793842)
		(width 0.18288)
		(layer "In4.Cu")
		(net "M_G_CPU0_SB_DQS_DN<7>")
	)
	(segment
		(start 424.328082 -211.877656)
		(end 422.832276 -211.877656)
		(width 0.18288)
		(layer "In4.Cu")
		(net "M_G_CPU0_SB_DQS_DN<7>")
	)
	(segment
		(start 426.246036 -211.91093)
		(end 425.311316 -211.91093)
		(width 0.18288)
		(layer "In4.Cu")
		(net "M_G_CPU0_SB_DQS_DN<7>")
	)
	(segment
		(start 418.688774 -211.256626)
		(end 418.564314 -211.381086)
		(width 0.18288)
		(layer "In4.Cu")
		(net "M_G_CPU0_SB_DQS_DN<7>")
	)
	(segment
		(start 432.731926 -208.256124)
		(end 431.824892 -209.163158)
		(width 0.18288)
		(layer "In4.Cu")
		(net "M_G_CPU0_SB_DQS_DN<7>")
	)
	(arc
		(start 386.633212 -228.956616)
		(mid 386.506169 -229.092432)
		(end 386.459984 -229.272592)
		(width 0.088646)
		(layer "In4.Cu")
		(net "M_G_CPU0_SB_DQS_DN<7>")
	)
	(arc
		(start 385.990084 -230.096568)
		(mid 385.911973 -230.373517)
		(end 385.707636 -230.57612)
		(width 0.088646)
		(layer "In4.Cu")
		(net "M_G_CPU0_SB_DQS_DN<7>")
	)
	(arc
		(start 385.520184 -230.91902)
		(mid 385.440022 -231.191209)
		(end 385.237736 -231.39019)
		(width 0.088646)
		(layer "In4.Cu")
		(net "M_G_CPU0_SB_DQS_DN<7>")
	)
	(arc
		(start 385.050284 -231.73309)
		(mid 384.970122 -232.005279)
		(end 384.767836 -232.20426)
		(width 0.088646)
		(layer "In4.Cu")
		(net "M_G_CPU0_SB_DQS_DN<7>")
	)
	(arc
		(start 386.930138 -228.468428)
		(mid 386.852 -228.745669)
		(end 386.647436 -228.948488)
		(width 0.088646)
		(layer "In4.Cu")
		(net "M_G_CPU0_SB_DQS_DN<7>")
	)
	(arc
		(start 383.262632 -232.204006)
		(mid 383.075434 -232.153863)
		(end 382.888236 -232.204006)
		(width 0.088646)
		(layer "In4.Cu")
		(net "M_G_CPU0_SB_DQS_DN<7>")
	)
	(arc
		(start 382.322832 -232.204006)
		(mid 382.135634 -232.153863)
		(end 381.948436 -232.204006)
		(width 0.088646)
		(layer "In4.Cu")
		(net "M_G_CPU0_SB_DQS_DN<7>")
	)
	(arc
		(start 384.202432 -232.204006)
		(mid 384.015234 -232.153863)
		(end 383.828036 -232.204006)
		(width 0.088646)
		(layer "In4.Cu")
		(net "M_G_CPU0_SB_DQS_DN<7>")
	)
	(arc
		(start 384.767836 -232.204006)
		(mid 384.485134 -232.279782)
		(end 384.202432 -232.204006)
		(width 0.088646)
		(layer "In4.Cu")
		(net "M_G_CPU0_SB_DQS_DN<7>")
	)
	(arc
		(start 380.330456 -232.3211)
		(mid 380.277832 -232.342898)
		(end 380.256034 -232.395522)
		(width 0.088646)
		(layer "In4.Cu")
		(net "M_G_CPU0_SB_DQS_DN<7>")
	)
	(arc
		(start 382.888236 -232.204006)
		(mid 382.605534 -232.279782)
		(end 382.322832 -232.204006)
		(width 0.088646)
		(layer "In4.Cu")
		(net "M_G_CPU0_SB_DQS_DN<7>")
	)
	(arc
		(start 383.828036 -232.204006)
		(mid 383.545334 -232.279782)
		(end 383.262632 -232.204006)
		(width 0.088646)
		(layer "In4.Cu")
		(net "M_G_CPU0_SB_DQS_DN<7>")
	)
	(arc
		(start 381.938022 -232.210102)
		(mid 381.659764 -232.27995)
		(end 381.383032 -232.20426)
		(width 0.088646)
		(layer "In4.Cu")
		(net "M_G_CPU0_SB_DQS_DN<7>")
	)
	(arc
		(start 386.459984 -229.282752)
		(mid 386.381873 -229.559701)
		(end 386.177536 -229.762304)
		(width 0.088646)
		(layer "In4.Cu")
		(net "M_G_CPU0_SB_DQS_DN<7>")
	)
	(arc
		(start 385.698746 -230.5812)
		(mid 385.567832 -230.71756)
		(end 385.520184 -230.900478)
		(width 0.088646)
		(layer "In4.Cu")
		(net "M_G_CPU0_SB_DQS_DN<7>")
	)
	(arc
		(start 385.228846 -231.39527)
		(mid 385.097932 -231.53163)
		(end 385.050284 -231.714548)
		(width 0.088646)
		(layer "In4.Cu")
		(net "M_G_CPU0_SB_DQS_DN<7>")
	)
	(arc
		(start 386.168646 -229.767384)
		(mid 386.037732 -229.903744)
		(end 385.990084 -230.086662)
		(width 0.088646)
		(layer "In4.Cu")
		(net "M_G_CPU0_SB_DQS_DN<7>")
	)
	(arc
		(start 381.382778 -232.204006)
		(mid 381.19558 -232.153863)
		(end 381.008382 -232.204006)
		(width 0.088646)
		(layer "In4.Cu")
		(net "M_G_CPU0_SB_DQS_DN<7>")
	)
	(segment
		(start 376.026934 -235.506006)
		(end 376.02668 -235.505752)
		(width 0.20066)
		(layer "F.Cu")
		(net "M_G_CPU0_SB_DQS_DN<6>")
	)
	(segment
		(start 439.923682 -218.566746)
		(end 441.028582 -218.566746)
		(width 0.20066)
		(layer "F.Cu")
		(net "M_G_CPU0_SB_DQS_DN<6>")
	)
	(segment
		(start 447.814446 -218.312492)
		(end 448.0687 -218.566746)
		(width 0.20066)
		(layer "F.Cu")
		(net "M_G_CPU0_SB_DQS_DN<6>")
	)
	(segment
		(start 442.738764 -217.870532)
		(end 442.861192 -217.870532)
		(width 0.20066)
		(layer "F.Cu")
		(net "M_G_CPU0_SB_DQS_DN<6>")
	)
	(segment
		(start 445.482726 -218.152726)
		(end 445.801496 -218.152726)
		(width 0.20066)
		(layer "F.Cu")
		(net "M_G_CPU0_SB_DQS_DN<6>")
	)
	(segment
		(start 442.313822 -218.295474)
		(end 442.738764 -217.870532)
		(width 0.20066)
		(layer "F.Cu")
		(net "M_G_CPU0_SB_DQS_DN<6>")
	)
	(segment
		(start 445.801496 -218.152726)
		(end 446.087246 -217.866976)
		(width 0.20066)
		(layer "F.Cu")
		(net "M_G_CPU0_SB_DQS_DN<6>")
	)
	(segment
		(start 446.087246 -217.866976)
		(end 446.577212 -217.866976)
		(width 0.20066)
		(layer "F.Cu")
		(net "M_G_CPU0_SB_DQS_DN<6>")
	)
	(segment
		(start 443.13856 -218.1479)
		(end 443.450726 -218.1479)
		(width 0.20066)
		(layer "F.Cu")
		(net "M_G_CPU0_SB_DQS_DN<6>")
	)
	(segment
		(start 441.559188 -218.566746)
		(end 441.83046 -218.295474)
		(width 0.20066)
		(layer "F.Cu")
		(net "M_G_CPU0_SB_DQS_DN<6>")
	)
	(segment
		(start 448.0687 -218.566746)
		(end 448.572382 -218.566746)
		(width 0.20066)
		(layer "F.Cu")
		(net "M_G_CPU0_SB_DQS_DN<6>")
	)
	(segment
		(start 443.450726 -218.1479)
		(end 443.455552 -218.1479)
		(width 0.101854)
		(layer "F.Cu")
		(net "M_G_CPU0_SB_DQS_DN<6>")
	)
	(segment
		(start 441.83046 -218.295474)
		(end 442.313822 -218.295474)
		(width 0.20066)
		(layer "F.Cu")
		(net "M_G_CPU0_SB_DQS_DN<6>")
	)
	(segment
		(start 442.861192 -217.870532)
		(end 443.13856 -218.1479)
		(width 0.20066)
		(layer "F.Cu")
		(net "M_G_CPU0_SB_DQS_DN<6>")
	)
	(segment
		(start 376.02668 -235.505752)
		(end 376.02668 -234.970066)
		(width 0.20066)
		(layer "F.Cu")
		(net "M_G_CPU0_SB_DQS_DN<6>")
	)
	(segment
		(start 441.028582 -218.566746)
		(end 441.559188 -218.566746)
		(width 0.20066)
		(layer "F.Cu")
		(net "M_G_CPU0_SB_DQS_DN<6>")
	)
	(segment
		(start 447.022728 -218.312492)
		(end 447.814446 -218.312492)
		(width 0.20066)
		(layer "F.Cu")
		(net "M_G_CPU0_SB_DQS_DN<6>")
	)
	(segment
		(start 446.577212 -217.866976)
		(end 447.022728 -218.312492)
		(width 0.20066)
		(layer "F.Cu")
		(net "M_G_CPU0_SB_DQS_DN<6>")
	)
	(segment
		(start 445.471804 -218.141804)
		(end 445.482726 -218.152726)
		(width 0.1016)
		(layer "F.Cu")
		(net "M_G_CPU0_SB_DQS_DN<6>")
	)
	(segment
		(start 443.455552 -218.1479)
		(end 443.461648 -218.141804)
		(width 0.1016)
		(layer "F.Cu")
		(net "M_G_CPU0_SB_DQS_DN<6>")
	)
	(segment
		(start 443.461648 -218.141804)
		(end 445.471804 -218.141804)
		(width 0.1016)
		(layer "F.Cu")
		(net "M_G_CPU0_SB_DQS_DN<6>")
	)
	(segment
		(start 416.805872 -223.764348)
		(end 416.691826 -223.717104)
		(width 0.18288)
		(layer "In6.Cu")
		(net "M_G_CPU0_SB_DQS_DN<6>")
	)
	(segment
		(start 436.604664 -220.396054)
		(end 436.335424 -220.396054)
		(width 0.18288)
		(layer "In6.Cu")
		(net "M_G_CPU0_SB_DQS_DN<6>")
	)
	(segment
		(start 425.015914 -223.240854)
		(end 424.660568 -223.240854)
		(width 0.18288)
		(layer "In6.Cu")
		(net "M_G_CPU0_SB_DQS_DN<6>")
	)
	(segment
		(start 413.07385 -221.508828)
		(end 412.254192 -221.848426)
		(width 0.18288)
		(layer "In6.Cu")
		(net "M_G_CPU0_SB_DQS_DN<6>")
	)
	(segment
		(start 387.756908 -233.879898)
		(end 387.562344 -234.074208)
		(width 0.088646)
		(layer "In6.Cu")
		(net "M_G_CPU0_SB_DQS_DN<6>")
	)
	(segment
		(start 409.031948 -221.848426)
		(end 408.684984 -221.501462)
		(width 0.18288)
		(layer "In6.Cu")
		(net "M_G_CPU0_SB_DQS_DN<6>")
	)
	(segment
		(start 378.192284 -235.457492)
		(end 378.189744 -235.459016)
		(width 0.088646)
		(layer "In6.Cu")
		(net "M_G_CPU0_SB_DQS_DN<6>")
	)
	(segment
		(start 412.254192 -221.848426)
		(end 409.031948 -221.848426)
		(width 0.18288)
		(layer "In6.Cu")
		(net "M_G_CPU0_SB_DQS_DN<6>")
	)
	(segment
		(start 386.175758 -234.64647)
		(end 386.168392 -234.650788)
		(width 0.088646)
		(layer "In6.Cu")
		(net "M_G_CPU0_SB_DQS_DN<6>")
	)
	(segment
		(start 413.59455 -221.508828)
		(end 413.07385 -221.508828)
		(width 0.18288)
		(layer "In6.Cu")
		(net "M_G_CPU0_SB_DQS_DN<6>")
	)
	(segment
		(start 421.200834 -223.832674)
		(end 420.94277 -224.090738)
		(width 0.18288)
		(layer "In6.Cu")
		(net "M_G_CPU0_SB_DQS_DN<6>")
	)
	(segment
		(start 439.923682 -218.566746)
		(end 439.701178 -218.344242)
		(width 0.18288)
		(layer "In6.Cu")
		(net "M_G_CPU0_SB_DQS_DN<6>")
	)
	(segment
		(start 378.189744 -235.459016)
		(end 378.179838 -235.46435)
		(width 0.088646)
		(layer "In6.Cu")
		(net "M_G_CPU0_SB_DQS_DN<6>")
	)
	(segment
		(start 439.701178 -218.344242)
		(end 438.86755 -218.344242)
		(width 0.18288)
		(layer "In6.Cu")
		(net "M_G_CPU0_SB_DQS_DN<6>")
	)
	(segment
		(start 376.596402 -235.027216)
		(end 376.539252 -234.970066)
		(width 0.088646)
		(layer "In6.Cu")
		(net "M_G_CPU0_SB_DQS_DN<6>")
	)
	(segment
		(start 377.181618 -235.278676)
		(end 377.153678 -235.294424)
		(width 0.088646)
		(layer "In6.Cu")
		(net "M_G_CPU0_SB_DQS_DN<6>")
	)
	(segment
		(start 424.660568 -223.240854)
		(end 424.401742 -222.982028)
		(width 0.18288)
		(layer "In6.Cu")
		(net "M_G_CPU0_SB_DQS_DN<6>")
	)
	(segment
		(start 379.134624 -235.456222)
		(end 379.12294 -235.462826)
		(width 0.088646)
		(layer "In6.Cu")
		(net "M_G_CPU0_SB_DQS_DN<6>")
	)
	(segment
		(start 438.86755 -218.344242)
		(end 438.799986 -218.372182)
		(width 0.18288)
		(layer "In6.Cu")
		(net "M_G_CPU0_SB_DQS_DN<6>")
	)
	(segment
		(start 376.539252 -234.970066)
		(end 376.02668 -234.970066)
		(width 0.088646)
		(layer "In6.Cu")
		(net "M_G_CPU0_SB_DQS_DN<6>")
	)
	(segment
		(start 386.177282 -234.645708)
		(end 386.175758 -234.64647)
		(width 0.088646)
		(layer "In6.Cu")
		(net "M_G_CPU0_SB_DQS_DN<6>")
	)
	(segment
		(start 426.710348 -222.244158)
		(end 426.14215 -222.812356)
		(width 0.18288)
		(layer "In6.Cu")
		(net "M_G_CPU0_SB_DQS_DN<6>")
	)
	(segment
		(start 403.947884 -221.501462)
		(end 391.509504 -233.939842)
		(width 0.18288)
		(layer "In6.Cu")
		(net "M_G_CPU0_SB_DQS_DN<6>")
	)
	(segment
		(start 387.949694 -233.939842)
		(end 387.88975 -233.879898)
		(width 0.088646)
		(layer "In6.Cu")
		(net "M_G_CPU0_SB_DQS_DN<6>")
	)
	(segment
		(start 420.94277 -224.090738)
		(end 420.562532 -224.090738)
		(width 0.18288)
		(layer "In6.Cu")
		(net "M_G_CPU0_SB_DQS_DN<6>")
	)
	(segment
		(start 436.335424 -220.396054)
		(end 436.042308 -220.68917)
		(width 0.18288)
		(layer "In6.Cu")
		(net "M_G_CPU0_SB_DQS_DN<6>")
	)
	(segment
		(start 416.691826 -223.717104)
		(end 415.739834 -222.765112)
		(width 0.18288)
		(layer "In6.Cu")
		(net "M_G_CPU0_SB_DQS_DN<6>")
	)
	(segment
		(start 420.562532 -224.090738)
		(end 420.283132 -223.811338)
		(width 0.18288)
		(layer "In6.Cu")
		(net "M_G_CPU0_SB_DQS_DN<6>")
	)
	(segment
		(start 380.453392 -235.46562)
		(end 380.442978 -235.459524)
		(width 0.088646)
		(layer "In6.Cu")
		(net "M_G_CPU0_SB_DQS_DN<6>")
	)
	(segment
		(start 377.358402 -235.287312)
		(end 377.181618 -235.278676)
		(width 0.088646)
		(layer "In6.Cu")
		(net "M_G_CPU0_SB_DQS_DN<6>")
	)
	(segment
		(start 416.919664 -223.811338)
		(end 416.805872 -223.764348)
		(width 0.18288)
		(layer "In6.Cu")
		(net "M_G_CPU0_SB_DQS_DN<6>")
	)
	(segment
		(start 420.283132 -223.811338)
		(end 416.919664 -223.811338)
		(width 0.18288)
		(layer "In6.Cu")
		(net "M_G_CPU0_SB_DQS_DN<6>")
	)
	(segment
		(start 438.799986 -218.372182)
		(end 436.900828 -220.27134)
		(width 0.18288)
		(layer "In6.Cu")
		(net "M_G_CPU0_SB_DQS_DN<6>")
	)
	(segment
		(start 430.802796 -221.021148)
		(end 428.915068 -221.021148)
		(width 0.18288)
		(layer "In6.Cu")
		(net "M_G_CPU0_SB_DQS_DN<6>")
	)
	(segment
		(start 426.14215 -222.812356)
		(end 425.759118 -222.971106)
		(width 0.18288)
		(layer "In6.Cu")
		(net "M_G_CPU0_SB_DQS_DN<6>")
	)
	(segment
		(start 425.759118 -222.971106)
		(end 425.285662 -222.971106)
		(width 0.18288)
		(layer "In6.Cu")
		(net "M_G_CPU0_SB_DQS_DN<6>")
	)
	(segment
		(start 387.47319 -234.150408)
		(end 387.03758 -234.470702)
		(width 0.088646)
		(layer "In6.Cu")
		(net "M_G_CPU0_SB_DQS_DN<6>")
	)
	(segment
		(start 435.049168 -220.155262)
		(end 432.064668 -220.155262)
		(width 0.18288)
		(layer "In6.Cu")
		(net "M_G_CPU0_SB_DQS_DN<6>")
	)
	(segment
		(start 436.900828 -220.27134)
		(end 436.604664 -220.396054)
		(width 0.18288)
		(layer "In6.Cu")
		(net "M_G_CPU0_SB_DQS_DN<6>")
	)
	(segment
		(start 415.739834 -222.765112)
		(end 414.850834 -222.765112)
		(width 0.18288)
		(layer "In6.Cu")
		(net "M_G_CPU0_SB_DQS_DN<6>")
	)
	(segment
		(start 422.896538 -222.982028)
		(end 422.472358 -223.157288)
		(width 0.18288)
		(layer "In6.Cu")
		(net "M_G_CPU0_SB_DQS_DN<6>")
	)
	(segment
		(start 436.042308 -220.68917)
		(end 435.583076 -220.68917)
		(width 0.18288)
		(layer "In6.Cu")
		(net "M_G_CPU0_SB_DQS_DN<6>")
	)
	(segment
		(start 377.596908 -235.443014)
		(end 377.358402 -235.287312)
		(width 0.088646)
		(layer "In6.Cu")
		(net "M_G_CPU0_SB_DQS_DN<6>")
	)
	(segment
		(start 408.684984 -221.501462)
		(end 403.947884 -221.501462)
		(width 0.18288)
		(layer "In6.Cu")
		(net "M_G_CPU0_SB_DQS_DN<6>")
	)
	(segment
		(start 424.401742 -222.982028)
		(end 422.896538 -222.982028)
		(width 0.18288)
		(layer "In6.Cu")
		(net "M_G_CPU0_SB_DQS_DN<6>")
	)
	(segment
		(start 425.285662 -222.971106)
		(end 425.015914 -223.240854)
		(width 0.18288)
		(layer "In6.Cu")
		(net "M_G_CPU0_SB_DQS_DN<6>")
	)
	(segment
		(start 421.467026 -223.832674)
		(end 421.200834 -223.832674)
		(width 0.18288)
		(layer "In6.Cu")
		(net "M_G_CPU0_SB_DQS_DN<6>")
	)
	(segment
		(start 385.98983 -234.970066)
		(end 385.98983 -234.98556)
		(width 0.088646)
		(layer "In6.Cu")
		(net "M_G_CPU0_SB_DQS_DN<6>")
	)
	(segment
		(start 378.193046 -235.456984)
		(end 378.192284 -235.457492)
		(width 0.088646)
		(layer "In6.Cu")
		(net "M_G_CPU0_SB_DQS_DN<6>")
	)
	(segment
		(start 391.509504 -233.939842)
		(end 388.001764 -233.939842)
		(width 0.18288)
		(layer "In6.Cu")
		(net "M_G_CPU0_SB_DQS_DN<6>")
	)
	(segment
		(start 428.915068 -221.021148)
		(end 427.69663 -221.835472)
		(width 0.18288)
		(layer "In6.Cu")
		(net "M_G_CPU0_SB_DQS_DN<6>")
	)
	(segment
		(start 387.88975 -233.879898)
		(end 387.756908 -233.879898)
		(width 0.088646)
		(layer "In6.Cu")
		(net "M_G_CPU0_SB_DQS_DN<6>")
	)
	(segment
		(start 414.850834 -222.765112)
		(end 413.59455 -221.508828)
		(width 0.18288)
		(layer "In6.Cu")
		(net "M_G_CPU0_SB_DQS_DN<6>")
	)
	(segment
		(start 435.583076 -220.68917)
		(end 435.049168 -220.155262)
		(width 0.18288)
		(layer "In6.Cu")
		(net "M_G_CPU0_SB_DQS_DN<6>")
	)
	(segment
		(start 431.249836 -220.835982)
		(end 430.802796 -221.021148)
		(width 0.18288)
		(layer "In6.Cu")
		(net "M_G_CPU0_SB_DQS_DN<6>")
	)
	(segment
		(start 388.001764 -233.939842)
		(end 387.949694 -233.939842)
		(width 0.088646)
		(layer "In6.Cu")
		(net "M_G_CPU0_SB_DQS_DN<6>")
	)
	(segment
		(start 385.156964 -235.46816)
		(end 385.142232 -235.459524)
		(width 0.088646)
		(layer "In6.Cu")
		(net "M_G_CPU0_SB_DQS_DN<6>")
	)
	(segment
		(start 380.442978 -235.459524)
		(end 380.443232 -235.459524)
		(width 0.088646)
		(layer "In6.Cu")
		(net "M_G_CPU0_SB_DQS_DN<6>")
	)
	(segment
		(start 431.83556 -220.250258)
		(end 431.249836 -220.835982)
		(width 0.18288)
		(layer "In6.Cu")
		(net "M_G_CPU0_SB_DQS_DN<6>")
	)
	(segment
		(start 422.031922 -223.597724)
		(end 421.467026 -223.832674)
		(width 0.18288)
		(layer "In6.Cu")
		(net "M_G_CPU0_SB_DQS_DN<6>")
	)
	(segment
		(start 427.69663 -221.835472)
		(end 426.710348 -222.244158)
		(width 0.18288)
		(layer "In6.Cu")
		(net "M_G_CPU0_SB_DQS_DN<6>")
	)
	(segment
		(start 432.064668 -220.155262)
		(end 431.83556 -220.250258)
		(width 0.18288)
		(layer "In6.Cu")
		(net "M_G_CPU0_SB_DQS_DN<6>")
	)
	(segment
		(start 422.472358 -223.157288)
		(end 422.031922 -223.597724)
		(width 0.18288)
		(layer "In6.Cu")
		(net "M_G_CPU0_SB_DQS_DN<6>")
	)
	(segment
		(start 380.074424 -235.456222)
		(end 380.06274 -235.462826)
		(width 0.088646)
		(layer "In6.Cu")
		(net "M_G_CPU0_SB_DQS_DN<6>")
	)
	(segment
		(start 384.217164 -235.46816)
		(end 384.202432 -235.459524)
		(width 0.088646)
		(layer "In6.Cu")
		(net "M_G_CPU0_SB_DQS_DN<6>")
	)
	(arc
		(start 386.439156 -234.602274)
		(mid 386.304236 -234.600005)
		(end 386.177282 -234.645708)
		(width 0.088646)
		(layer "In6.Cu")
		(net "M_G_CPU0_SB_DQS_DN<6>")
	)
	(arc
		(start 385.707636 -235.459524)
		(mid 385.433437 -235.535359)
		(end 385.156964 -235.46816)
		(width 0.088646)
		(layer "In6.Cu")
		(net "M_G_CPU0_SB_DQS_DN<6>")
	)
	(arc
		(start 385.98983 -234.98556)
		(mid 385.91046 -235.259294)
		(end 385.707636 -235.459524)
		(width 0.088646)
		(layer "In6.Cu")
		(net "M_G_CPU0_SB_DQS_DN<6>")
	)
	(arc
		(start 387.562344 -234.074208)
		(mid 387.519211 -234.113998)
		(end 387.47319 -234.150408)
		(width 0.088646)
		(layer "In6.Cu")
		(net "M_G_CPU0_SB_DQS_DN<6>")
	)
	(arc
		(start 381.383032 -235.459524)
		(mid 381.195834 -235.409381)
		(end 381.008636 -235.459524)
		(width 0.088646)
		(layer "In6.Cu")
		(net "M_G_CPU0_SB_DQS_DN<6>")
	)
	(arc
		(start 386.168392 -234.650788)
		(mid 386.037478 -234.787148)
		(end 385.98983 -234.970066)
		(width 0.088646)
		(layer "In6.Cu")
		(net "M_G_CPU0_SB_DQS_DN<6>")
	)
	(arc
		(start 384.202432 -235.459524)
		(mid 384.015234 -235.409381)
		(end 383.828036 -235.459524)
		(width 0.088646)
		(layer "In6.Cu")
		(net "M_G_CPU0_SB_DQS_DN<6>")
	)
	(arc
		(start 383.828036 -235.459524)
		(mid 383.545334 -235.5353)
		(end 383.262632 -235.459524)
		(width 0.088646)
		(layer "In6.Cu")
		(net "M_G_CPU0_SB_DQS_DN<6>")
	)
	(arc
		(start 381.008636 -235.459524)
		(mid 380.731823 -235.535394)
		(end 380.453392 -235.46562)
		(width 0.088646)
		(layer "In6.Cu")
		(net "M_G_CPU0_SB_DQS_DN<6>")
	)
	(arc
		(start 385.142232 -235.459524)
		(mid 384.955034 -235.409381)
		(end 384.767836 -235.459524)
		(width 0.088646)
		(layer "In6.Cu")
		(net "M_G_CPU0_SB_DQS_DN<6>")
	)
	(arc
		(start 377.153678 -235.294424)
		(mid 376.804573 -235.30776)
		(end 376.596402 -235.027216)
		(width 0.088646)
		(layer "In6.Cu")
		(net "M_G_CPU0_SB_DQS_DN<6>")
	)
	(arc
		(start 383.262632 -235.459524)
		(mid 383.075434 -235.409381)
		(end 382.888236 -235.459524)
		(width 0.088646)
		(layer "In6.Cu")
		(net "M_G_CPU0_SB_DQS_DN<6>")
	)
	(arc
		(start 380.443232 -235.459524)
		(mid 380.259278 -235.409395)
		(end 380.074424 -235.456222)
		(width 0.088646)
		(layer "In6.Cu")
		(net "M_G_CPU0_SB_DQS_DN<6>")
	)
	(arc
		(start 381.948436 -235.459524)
		(mid 381.665734 -235.5353)
		(end 381.383032 -235.459524)
		(width 0.088646)
		(layer "In6.Cu")
		(net "M_G_CPU0_SB_DQS_DN<6>")
	)
	(arc
		(start 382.322832 -235.459524)
		(mid 382.135634 -235.409381)
		(end 381.948436 -235.459524)
		(width 0.088646)
		(layer "In6.Cu")
		(net "M_G_CPU0_SB_DQS_DN<6>")
	)
	(arc
		(start 378.179838 -235.46435)
		(mid 377.885399 -235.534683)
		(end 377.596908 -235.443014)
		(width 0.088646)
		(layer "In6.Cu")
		(net "M_G_CPU0_SB_DQS_DN<6>")
	)
	(arc
		(start 387.03758 -234.470702)
		(mid 386.752302 -234.599869)
		(end 386.439156 -234.602274)
		(width 0.088646)
		(layer "In6.Cu")
		(net "M_G_CPU0_SB_DQS_DN<6>")
	)
	(arc
		(start 382.888236 -235.459524)
		(mid 382.605534 -235.5353)
		(end 382.322832 -235.459524)
		(width 0.088646)
		(layer "In6.Cu")
		(net "M_G_CPU0_SB_DQS_DN<6>")
	)
	(arc
		(start 379.12294 -235.462826)
		(mid 378.842835 -235.535268)
		(end 378.563632 -235.459524)
		(width 0.088646)
		(layer "In6.Cu")
		(net "M_G_CPU0_SB_DQS_DN<6>")
	)
	(arc
		(start 384.767836 -235.459524)
		(mid 384.493637 -235.535359)
		(end 384.217164 -235.46816)
		(width 0.088646)
		(layer "In6.Cu")
		(net "M_G_CPU0_SB_DQS_DN<6>")
	)
	(arc
		(start 378.563632 -235.459524)
		(mid 378.379678 -235.409395)
		(end 378.194824 -235.456222)
		(width 0.088646)
		(layer "In6.Cu")
		(net "M_G_CPU0_SB_DQS_DN<6>")
	)
	(arc
		(start 378.194824 -235.456222)
		(mid 378.193935 -235.456602)
		(end 378.193046 -235.456984)
		(width 0.088646)
		(layer "In6.Cu")
		(net "M_G_CPU0_SB_DQS_DN<6>")
	)
	(arc
		(start 380.06274 -235.462826)
		(mid 379.782635 -235.535268)
		(end 379.503432 -235.459524)
		(width 0.088646)
		(layer "In6.Cu")
		(net "M_G_CPU0_SB_DQS_DN<6>")
	)
	(arc
		(start 379.503432 -235.459524)
		(mid 379.319478 -235.409395)
		(end 379.134624 -235.456222)
		(width 0.088646)
		(layer "In6.Cu")
		(net "M_G_CPU0_SB_DQS_DN<6>")
	)
	(segment
		(start 441.559188 -227.91674)
		(end 441.83046 -227.645468)
		(width 0.20066)
		(layer "F.Cu")
		(net "M_G_CPU0_SB_DQS_DN<5>")
	)
	(segment
		(start 445.801496 -227.50272)
		(end 446.087246 -227.21697)
		(width 0.20066)
		(layer "F.Cu")
		(net "M_G_CPU0_SB_DQS_DN<5>")
	)
	(segment
		(start 443.13856 -227.497894)
		(end 443.450726 -227.497894)
		(width 0.20066)
		(layer "F.Cu")
		(net "M_G_CPU0_SB_DQS_DN<5>")
	)
	(segment
		(start 447.022728 -227.662486)
		(end 447.814446 -227.662486)
		(width 0.20066)
		(layer "F.Cu")
		(net "M_G_CPU0_SB_DQS_DN<5>")
	)
	(segment
		(start 376.966734 -240.389156)
		(end 376.96648 -240.388902)
		(width 0.20066)
		(layer "F.Cu")
		(net "M_G_CPU0_SB_DQS_DN<5>")
	)
	(segment
		(start 441.83046 -227.645468)
		(end 442.313822 -227.645468)
		(width 0.20066)
		(layer "F.Cu")
		(net "M_G_CPU0_SB_DQS_DN<5>")
	)
	(segment
		(start 445.471804 -227.491798)
		(end 445.482726 -227.50272)
		(width 0.1016)
		(layer "F.Cu")
		(net "M_G_CPU0_SB_DQS_DN<5>")
	)
	(segment
		(start 441.028582 -227.91674)
		(end 441.559188 -227.91674)
		(width 0.20066)
		(layer "F.Cu")
		(net "M_G_CPU0_SB_DQS_DN<5>")
	)
	(segment
		(start 442.861192 -227.220526)
		(end 443.13856 -227.497894)
		(width 0.20066)
		(layer "F.Cu")
		(net "M_G_CPU0_SB_DQS_DN<5>")
	)
	(segment
		(start 439.923682 -227.91674)
		(end 441.028582 -227.91674)
		(width 0.20066)
		(layer "F.Cu")
		(net "M_G_CPU0_SB_DQS_DN<5>")
	)
	(segment
		(start 446.577212 -227.21697)
		(end 447.022728 -227.662486)
		(width 0.20066)
		(layer "F.Cu")
		(net "M_G_CPU0_SB_DQS_DN<5>")
	)
	(segment
		(start 445.482726 -227.50272)
		(end 445.801496 -227.50272)
		(width 0.20066)
		(layer "F.Cu")
		(net "M_G_CPU0_SB_DQS_DN<5>")
	)
	(segment
		(start 443.450726 -227.497894)
		(end 443.455552 -227.497894)
		(width 0.101854)
		(layer "F.Cu")
		(net "M_G_CPU0_SB_DQS_DN<5>")
	)
	(segment
		(start 446.087246 -227.21697)
		(end 446.577212 -227.21697)
		(width 0.20066)
		(layer "F.Cu")
		(net "M_G_CPU0_SB_DQS_DN<5>")
	)
	(segment
		(start 448.0687 -227.91674)
		(end 448.572382 -227.91674)
		(width 0.20066)
		(layer "F.Cu")
		(net "M_G_CPU0_SB_DQS_DN<5>")
	)
	(segment
		(start 442.738764 -227.220526)
		(end 442.861192 -227.220526)
		(width 0.20066)
		(layer "F.Cu")
		(net "M_G_CPU0_SB_DQS_DN<5>")
	)
	(segment
		(start 442.313822 -227.645468)
		(end 442.738764 -227.220526)
		(width 0.20066)
		(layer "F.Cu")
		(net "M_G_CPU0_SB_DQS_DN<5>")
	)
	(segment
		(start 447.814446 -227.662486)
		(end 448.0687 -227.91674)
		(width 0.20066)
		(layer "F.Cu")
		(net "M_G_CPU0_SB_DQS_DN<5>")
	)
	(segment
		(start 443.455552 -227.497894)
		(end 443.461648 -227.491798)
		(width 0.1016)
		(layer "F.Cu")
		(net "M_G_CPU0_SB_DQS_DN<5>")
	)
	(segment
		(start 376.96648 -240.388902)
		(end 376.96648 -239.853216)
		(width 0.20066)
		(layer "F.Cu")
		(net "M_G_CPU0_SB_DQS_DN<5>")
	)
	(segment
		(start 443.461648 -227.491798)
		(end 445.471804 -227.491798)
		(width 0.1016)
		(layer "F.Cu")
		(net "M_G_CPU0_SB_DQS_DN<5>")
	)
	(segment
		(start 412.37027 -231.726486)
		(end 411.257242 -231.726486)
		(width 0.18288)
		(layer "In6.Cu")
		(net "M_G_CPU0_SB_DQS_DN<5>")
	)
	(segment
		(start 383.358136 -239.528858)
		(end 383.347722 -239.534954)
		(width 0.088646)
		(layer "In6.Cu")
		(net "M_G_CPU0_SB_DQS_DN<5>")
	)
	(segment
		(start 414.246822 -232.701338)
		(end 414.122362 -232.576878)
		(width 0.18288)
		(layer "In6.Cu")
		(net "M_G_CPU0_SB_DQS_DN<5>")
	)
	(segment
		(start 397.762222 -236.060234)
		(end 397.5862 -236.060234)
		(width 0.18288)
		(layer "In6.Cu")
		(net "M_G_CPU0_SB_DQS_DN<5>")
	)
	(segment
		(start 424.401234 -232.330498)
		(end 423.63644 -232.330498)
		(width 0.18288)
		(layer "In6.Cu")
		(net "M_G_CPU0_SB_DQS_DN<5>")
	)
	(segment
		(start 422.29532 -232.330498)
		(end 421.449246 -233.176572)
		(width 0.18288)
		(layer "In6.Cu")
		(net "M_G_CPU0_SB_DQS_DN<5>")
	)
	(segment
		(start 422.96588 -232.454958)
		(end 422.84142 -232.330498)
		(width 0.18288)
		(layer "In6.Cu")
		(net "M_G_CPU0_SB_DQS_DN<5>")
	)
	(segment
		(start 437.957468 -227.835714)
		(end 437.24195 -227.511864)
		(width 0.18288)
		(layer "In6.Cu")
		(net "M_G_CPU0_SB_DQS_DN<5>")
	)
	(segment
		(start 388.299452 -239.186466)
		(end 388.05739 -239.186466)
		(width 0.088646)
		(layer "In6.Cu")
		(net "M_G_CPU0_SB_DQS_DN<5>")
	)
	(segment
		(start 423.51198 -232.454958)
		(end 422.96588 -232.454958)
		(width 0.18288)
		(layer "In6.Cu")
		(net "M_G_CPU0_SB_DQS_DN<5>")
	)
	(segment
		(start 419.300406 -233.297222)
		(end 418.754306 -233.297222)
		(width 0.18288)
		(layer "In6.Cu")
		(net "M_G_CPU0_SB_DQS_DN<5>")
	)
	(segment
		(start 399.659094 -234.163362)
		(end 399.483072 -234.163362)
		(width 0.18288)
		(layer "In6.Cu")
		(net "M_G_CPU0_SB_DQS_DN<5>")
	)
	(segment
		(start 418.083746 -233.172762)
		(end 417.959286 -233.297222)
		(width 0.18288)
		(layer "In6.Cu")
		(net "M_G_CPU0_SB_DQS_DN<5>")
	)
	(segment
		(start 382.418082 -239.528858)
		(end 382.407668 -239.534954)
		(width 0.088646)
		(layer "In6.Cu")
		(net "M_G_CPU0_SB_DQS_DN<5>")
	)
	(segment
		(start 426.675296 -231.711246)
		(end 426.063156 -232.323386)
		(width 0.18288)
		(layer "In6.Cu")
		(net "M_G_CPU0_SB_DQS_DN<5>")
	)
	(segment
		(start 388.359396 -239.24641)
		(end 388.299452 -239.186466)
		(width 0.088646)
		(layer "In6.Cu")
		(net "M_G_CPU0_SB_DQS_DN<5>")
	)
	(segment
		(start 416.146742 -232.576878)
		(end 414.917382 -232.576878)
		(width 0.18288)
		(layer "In6.Cu")
		(net "M_G_CPU0_SB_DQS_DN<5>")
	)
	(segment
		(start 398.710658 -235.111798)
		(end 398.534636 -235.111798)
		(width 0.18288)
		(layer "In6.Cu")
		(net "M_G_CPU0_SB_DQS_DN<5>")
	)
	(segment
		(start 436.498492 -227.204016)
		(end 436.327296 -227.204016)
		(width 0.18288)
		(layer "In6.Cu")
		(net "M_G_CPU0_SB_DQS_DN<5>")
	)
	(segment
		(start 397.5862 -236.060234)
		(end 394.400024 -239.24641)
		(width 0.18288)
		(layer "In6.Cu")
		(net "M_G_CPU0_SB_DQS_DN<5>")
	)
	(segment
		(start 387.765544 -239.478312)
		(end 387.30428 -239.478312)
		(width 0.088646)
		(layer "In6.Cu")
		(net "M_G_CPU0_SB_DQS_DN<5>")
	)
	(segment
		(start 388.05739 -239.186466)
		(end 387.765544 -239.478312)
		(width 0.088646)
		(layer "In6.Cu")
		(net "M_G_CPU0_SB_DQS_DN<5>")
	)
	(segment
		(start 406.083516 -233.184192)
		(end 405.825452 -233.442256)
		(width 0.18288)
		(layer "In6.Cu")
		(net "M_G_CPU0_SB_DQS_DN<5>")
	)
	(segment
		(start 421.449246 -233.176572)
		(end 421.180768 -233.176572)
		(width 0.18288)
		(layer "In6.Cu")
		(net "M_G_CPU0_SB_DQS_DN<5>")
	)
	(segment
		(start 439.075068 -227.835714)
		(end 437.957468 -227.835714)
		(width 0.18288)
		(layer "In6.Cu")
		(net "M_G_CPU0_SB_DQS_DN<5>")
	)
	(segment
		(start 410.482288 -232.677462)
		(end 410.306266 -232.677462)
		(width 0.18288)
		(layer "In6.Cu")
		(net "M_G_CPU0_SB_DQS_DN<5>")
	)
	(segment
		(start 432.0286 -228.44887)
		(end 431.384964 -229.092506)
		(width 0.18288)
		(layer "In6.Cu")
		(net "M_G_CPU0_SB_DQS_DN<5>")
	)
	(segment
		(start 436.04053 -227.490782)
		(end 434.084476 -227.490782)
		(width 0.18288)
		(layer "In6.Cu")
		(net "M_G_CPU0_SB_DQS_DN<5>")
	)
	(segment
		(start 402.6281 -233.214926)
		(end 402.50364 -233.339386)
		(width 0.18288)
		(layer "In6.Cu")
		(net "M_G_CPU0_SB_DQS_DN<5>")
	)
	(segment
		(start 406.941274 -233.184192)
		(end 406.083516 -233.184192)
		(width 0.18288)
		(layer "In6.Cu")
		(net "M_G_CPU0_SB_DQS_DN<5>")
	)
	(segment
		(start 394.400024 -239.24641)
		(end 388.359396 -239.24641)
		(width 0.18288)
		(layer "In6.Cu")
		(net "M_G_CPU0_SB_DQS_DN<5>")
	)
	(segment
		(start 427.864524 -232.197402)
		(end 427.378368 -231.711246)
		(width 0.18288)
		(layer "In6.Cu")
		(net "M_G_CPU0_SB_DQS_DN<5>")
	)
	(segment
		(start 421.180768 -233.176572)
		(end 420.916354 -233.440986)
		(width 0.18288)
		(layer "In6.Cu")
		(net "M_G_CPU0_SB_DQS_DN<5>")
	)
	(segment
		(start 423.63644 -232.330498)
		(end 423.51198 -232.454958)
		(width 0.18288)
		(layer "In6.Cu")
		(net "M_G_CPU0_SB_DQS_DN<5>")
	)
	(segment
		(start 433.547012 -228.028246)
		(end 433.04587 -228.028246)
		(width 0.18288)
		(layer "In6.Cu")
		(net "M_G_CPU0_SB_DQS_DN<5>")
	)
	(segment
		(start 417.288726 -233.172762)
		(end 416.742626 -233.172762)
		(width 0.18288)
		(layer "In6.Cu")
		(net "M_G_CPU0_SB_DQS_DN<5>")
	)
	(segment
		(start 400.045428 -233.601006)
		(end 400.045428 -233.777028)
		(width 0.18288)
		(layer "In6.Cu")
		(net "M_G_CPU0_SB_DQS_DN<5>")
	)
	(segment
		(start 380.538482 -239.528858)
		(end 380.528068 -239.534954)
		(width 0.088646)
		(layer "In6.Cu")
		(net "M_G_CPU0_SB_DQS_DN<5>")
	)
	(segment
		(start 399.483072 -234.163362)
		(end 399.096992 -234.549442)
		(width 0.18288)
		(layer "In6.Cu")
		(net "M_G_CPU0_SB_DQS_DN<5>")
	)
	(segment
		(start 377.142502 -239.620552)
		(end 377.026932 -239.643666)
		(width 0.088646)
		(layer "In6.Cu")
		(net "M_G_CPU0_SB_DQS_DN<5>")
	)
	(segment
		(start 433.04587 -228.028246)
		(end 432.0286 -228.44887)
		(width 0.18288)
		(layer "In6.Cu")
		(net "M_G_CPU0_SB_DQS_DN<5>")
	)
	(segment
		(start 439.653426 -227.646484)
		(end 439.533538 -227.646484)
		(width 0.18288)
		(layer "In6.Cu")
		(net "M_G_CPU0_SB_DQS_DN<5>")
	)
	(segment
		(start 376.96648 -239.704118)
		(end 376.96648 -239.853216)
		(width 0.088646)
		(layer "In6.Cu")
		(net "M_G_CPU0_SB_DQS_DN<5>")
	)
	(segment
		(start 430.063656 -229.445058)
		(end 430.063656 -230.604822)
		(width 0.18288)
		(layer "In6.Cu")
		(net "M_G_CPU0_SB_DQS_DN<5>")
	)
	(segment
		(start 414.792922 -232.701338)
		(end 414.246822 -232.701338)
		(width 0.18288)
		(layer "In6.Cu")
		(net "M_G_CPU0_SB_DQS_DN<5>")
	)
	(segment
		(start 411.257242 -231.726486)
		(end 410.868622 -232.115106)
		(width 0.18288)
		(layer "In6.Cu")
		(net "M_G_CPU0_SB_DQS_DN<5>")
	)
	(segment
		(start 403.29866 -233.339386)
		(end 403.1742 -233.214926)
		(width 0.18288)
		(layer "In6.Cu")
		(net "M_G_CPU0_SB_DQS_DN<5>")
	)
	(segment
		(start 401.83308 -233.214926)
		(end 400.431508 -233.214926)
		(width 0.18288)
		(layer "In6.Cu")
		(net "M_G_CPU0_SB_DQS_DN<5>")
	)
	(segment
		(start 405.4475 -233.442256)
		(end 405.22017 -233.214926)
		(width 0.18288)
		(layer "In6.Cu")
		(net "M_G_CPU0_SB_DQS_DN<5>")
	)
	(segment
		(start 384.297682 -239.528858)
		(end 384.297428 -239.528858)
		(width 0.088646)
		(layer "In6.Cu")
		(net "M_G_CPU0_SB_DQS_DN<5>")
	)
	(segment
		(start 398.534636 -235.111798)
		(end 398.148556 -235.497878)
		(width 0.18288)
		(layer "In6.Cu")
		(net "M_G_CPU0_SB_DQS_DN<5>")
	)
	(segment
		(start 416.742626 -233.172762)
		(end 416.146742 -232.576878)
		(width 0.18288)
		(layer "In6.Cu")
		(net "M_G_CPU0_SB_DQS_DN<5>")
	)
	(segment
		(start 398.148556 -235.6739)
		(end 397.762222 -236.060234)
		(width 0.18288)
		(layer "In6.Cu")
		(net "M_G_CPU0_SB_DQS_DN<5>")
	)
	(segment
		(start 418.629846 -233.172762)
		(end 418.083746 -233.172762)
		(width 0.18288)
		(layer "In6.Cu")
		(net "M_G_CPU0_SB_DQS_DN<5>")
	)
	(segment
		(start 401.95754 -233.339386)
		(end 401.83308 -233.214926)
		(width 0.18288)
		(layer "In6.Cu")
		(net "M_G_CPU0_SB_DQS_DN<5>")
	)
	(segment
		(start 408.504136 -233.063542)
		(end 408.002486 -232.561892)
		(width 0.18288)
		(layer "In6.Cu")
		(net "M_G_CPU0_SB_DQS_DN<5>")
	)
	(segment
		(start 385.237482 -239.528858)
		(end 385.22275 -239.537494)
		(width 0.088646)
		(layer "In6.Cu")
		(net "M_G_CPU0_SB_DQS_DN<5>")
	)
	(segment
		(start 403.1742 -233.214926)
		(end 402.6281 -233.214926)
		(width 0.18288)
		(layer "In6.Cu")
		(net "M_G_CPU0_SB_DQS_DN<5>")
	)
	(segment
		(start 429.149256 -231.695244)
		(end 428.973234 -231.695244)
		(width 0.18288)
		(layer "In6.Cu")
		(net "M_G_CPU0_SB_DQS_DN<5>")
	)
	(segment
		(start 431.384964 -229.092506)
		(end 430.416208 -229.092506)
		(width 0.18288)
		(layer "In6.Cu")
		(net "M_G_CPU0_SB_DQS_DN<5>")
	)
	(segment
		(start 439.533538 -227.646484)
		(end 439.075068 -227.835714)
		(width 0.18288)
		(layer "In6.Cu")
		(net "M_G_CPU0_SB_DQS_DN<5>")
	)
	(segment
		(start 402.50364 -233.339386)
		(end 401.95754 -233.339386)
		(width 0.18288)
		(layer "In6.Cu")
		(net "M_G_CPU0_SB_DQS_DN<5>")
	)
	(segment
		(start 398.148556 -235.497878)
		(end 398.148556 -235.6739)
		(width 0.18288)
		(layer "In6.Cu")
		(net "M_G_CPU0_SB_DQS_DN<5>")
	)
	(segment
		(start 429.53559 -231.132888)
		(end 429.53559 -231.30891)
		(width 0.18288)
		(layer "In6.Cu")
		(net "M_G_CPU0_SB_DQS_DN<5>")
	)
	(segment
		(start 427.378368 -231.711246)
		(end 426.675296 -231.711246)
		(width 0.18288)
		(layer "In6.Cu")
		(net "M_G_CPU0_SB_DQS_DN<5>")
	)
	(segment
		(start 412.991554 -232.347516)
		(end 412.37027 -231.726486)
		(width 0.18288)
		(layer "In6.Cu")
		(net "M_G_CPU0_SB_DQS_DN<5>")
	)
	(segment
		(start 417.959286 -233.297222)
		(end 417.413186 -233.297222)
		(width 0.18288)
		(layer "In6.Cu")
		(net "M_G_CPU0_SB_DQS_DN<5>")
	)
	(segment
		(start 403.96922 -233.214926)
		(end 403.84476 -233.339386)
		(width 0.18288)
		(layer "In6.Cu")
		(net "M_G_CPU0_SB_DQS_DN<5>")
	)
	(segment
		(start 430.416208 -229.092506)
		(end 430.063656 -229.445058)
		(width 0.18288)
		(layer "In6.Cu")
		(net "M_G_CPU0_SB_DQS_DN<5>")
	)
	(segment
		(start 410.868622 -232.291128)
		(end 410.482288 -232.677462)
		(width 0.18288)
		(layer "In6.Cu")
		(net "M_G_CPU0_SB_DQS_DN<5>")
	)
	(segment
		(start 436.327296 -227.204016)
		(end 436.04053 -227.490782)
		(width 0.18288)
		(layer "In6.Cu")
		(net "M_G_CPU0_SB_DQS_DN<5>")
	)
	(segment
		(start 429.53559 -231.30891)
		(end 429.149256 -231.695244)
		(width 0.18288)
		(layer "In6.Cu")
		(net "M_G_CPU0_SB_DQS_DN<5>")
	)
	(segment
		(start 437.24195 -227.511864)
		(end 436.498492 -227.204016)
		(width 0.18288)
		(layer "In6.Cu")
		(net "M_G_CPU0_SB_DQS_DN<5>")
	)
	(segment
		(start 403.84476 -233.339386)
		(end 403.29866 -233.339386)
		(width 0.18288)
		(layer "In6.Cu")
		(net "M_G_CPU0_SB_DQS_DN<5>")
	)
	(segment
		(start 377.51766 -239.620552)
		(end 377.142502 -239.620552)
		(width 0.088646)
		(layer "In6.Cu")
		(net "M_G_CPU0_SB_DQS_DN<5>")
	)
	(segment
		(start 378.658882 -239.528858)
		(end 378.64415 -239.537494)
		(width 0.088646)
		(layer "In6.Cu")
		(net "M_G_CPU0_SB_DQS_DN<5>")
	)
	(segment
		(start 420.916354 -233.440986)
		(end 420.562532 -233.440986)
		(width 0.18288)
		(layer "In6.Cu")
		(net "M_G_CPU0_SB_DQS_DN<5>")
	)
	(segment
		(start 410.868622 -232.115106)
		(end 410.868622 -232.291128)
		(width 0.18288)
		(layer "In6.Cu")
		(net "M_G_CPU0_SB_DQS_DN<5>")
	)
	(segment
		(start 418.754306 -233.297222)
		(end 418.629846 -233.172762)
		(width 0.18288)
		(layer "In6.Cu")
		(net "M_G_CPU0_SB_DQS_DN<5>")
	)
	(segment
		(start 377.597416 -239.599216)
		(end 377.51766 -239.620552)
		(width 0.088646)
		(layer "In6.Cu")
		(net "M_G_CPU0_SB_DQS_DN<5>")
	)
	(segment
		(start 409.920186 -233.063542)
		(end 408.504136 -233.063542)
		(width 0.18288)
		(layer "In6.Cu")
		(net "M_G_CPU0_SB_DQS_DN<5>")
	)
	(segment
		(start 377.719082 -239.528858)
		(end 377.597416 -239.599216)
		(width 0.088646)
		(layer "In6.Cu")
		(net "M_G_CPU0_SB_DQS_DN<5>")
	)
	(segment
		(start 408.002486 -232.561892)
		(end 407.563574 -232.561892)
		(width 0.18288)
		(layer "In6.Cu")
		(net "M_G_CPU0_SB_DQS_DN<5>")
	)
	(segment
		(start 424.661584 -232.590848)
		(end 424.401234 -232.330498)
		(width 0.18288)
		(layer "In6.Cu")
		(net "M_G_CPU0_SB_DQS_DN<5>")
	)
	(segment
		(start 425.012358 -232.590848)
		(end 424.661584 -232.590848)
		(width 0.18288)
		(layer "In6.Cu")
		(net "M_G_CPU0_SB_DQS_DN<5>")
	)
	(segment
		(start 414.917382 -232.576878)
		(end 414.792922 -232.701338)
		(width 0.18288)
		(layer "In6.Cu")
		(net "M_G_CPU0_SB_DQS_DN<5>")
	)
	(segment
		(start 417.413186 -233.297222)
		(end 417.288726 -233.172762)
		(width 0.18288)
		(layer "In6.Cu")
		(net "M_G_CPU0_SB_DQS_DN<5>")
	)
	(segment
		(start 407.563574 -232.561892)
		(end 406.941274 -233.184192)
		(width 0.18288)
		(layer "In6.Cu")
		(net "M_G_CPU0_SB_DQS_DN<5>")
	)
	(segment
		(start 381.478536 -239.528858)
		(end 381.468122 -239.534954)
		(width 0.088646)
		(layer "In6.Cu")
		(net "M_G_CPU0_SB_DQS_DN<5>")
	)
	(segment
		(start 410.306266 -232.677462)
		(end 409.920186 -233.063542)
		(width 0.18288)
		(layer "In6.Cu")
		(net "M_G_CPU0_SB_DQS_DN<5>")
	)
	(segment
		(start 400.045428 -233.777028)
		(end 399.659094 -234.163362)
		(width 0.18288)
		(layer "In6.Cu")
		(net "M_G_CPU0_SB_DQS_DN<5>")
	)
	(segment
		(start 399.096992 -234.549442)
		(end 399.096992 -234.725464)
		(width 0.18288)
		(layer "In6.Cu")
		(net "M_G_CPU0_SB_DQS_DN<5>")
	)
	(segment
		(start 405.825452 -233.442256)
		(end 405.4475 -233.442256)
		(width 0.18288)
		(layer "In6.Cu")
		(net "M_G_CPU0_SB_DQS_DN<5>")
	)
	(segment
		(start 400.431508 -233.214926)
		(end 400.045428 -233.601006)
		(width 0.18288)
		(layer "In6.Cu")
		(net "M_G_CPU0_SB_DQS_DN<5>")
	)
	(segment
		(start 413.544004 -232.576878)
		(end 412.991554 -232.347516)
		(width 0.18288)
		(layer "In6.Cu")
		(net "M_G_CPU0_SB_DQS_DN<5>")
	)
	(segment
		(start 383.73304 -239.528604)
		(end 383.732532 -239.528858)
		(width 0.088646)
		(layer "In6.Cu")
		(net "M_G_CPU0_SB_DQS_DN<5>")
	)
	(segment
		(start 428.973234 -231.695244)
		(end 428.471076 -232.197402)
		(width 0.18288)
		(layer "In6.Cu")
		(net "M_G_CPU0_SB_DQS_DN<5>")
	)
	(segment
		(start 439.923682 -227.91674)
		(end 439.653426 -227.646484)
		(width 0.18288)
		(layer "In6.Cu")
		(net "M_G_CPU0_SB_DQS_DN<5>")
	)
	(segment
		(start 386.177282 -239.528858)
		(end 386.16255 -239.537494)
		(width 0.088646)
		(layer "In6.Cu")
		(net "M_G_CPU0_SB_DQS_DN<5>")
	)
	(segment
		(start 420.562532 -233.440986)
		(end 420.294308 -233.172762)
		(width 0.18288)
		(layer "In6.Cu")
		(net "M_G_CPU0_SB_DQS_DN<5>")
	)
	(segment
		(start 426.063156 -232.323386)
		(end 425.27982 -232.323386)
		(width 0.18288)
		(layer "In6.Cu")
		(net "M_G_CPU0_SB_DQS_DN<5>")
	)
	(segment
		(start 377.026932 -239.643666)
		(end 376.96648 -239.704118)
		(width 0.088646)
		(layer "In6.Cu")
		(net "M_G_CPU0_SB_DQS_DN<5>")
	)
	(segment
		(start 434.084476 -227.490782)
		(end 433.547012 -228.028246)
		(width 0.18288)
		(layer "In6.Cu")
		(net "M_G_CPU0_SB_DQS_DN<5>")
	)
	(segment
		(start 399.096992 -234.725464)
		(end 398.710658 -235.111798)
		(width 0.18288)
		(layer "In6.Cu")
		(net "M_G_CPU0_SB_DQS_DN<5>")
	)
	(segment
		(start 405.22017 -233.214926)
		(end 403.96922 -233.214926)
		(width 0.18288)
		(layer "In6.Cu")
		(net "M_G_CPU0_SB_DQS_DN<5>")
	)
	(segment
		(start 422.84142 -232.330498)
		(end 422.29532 -232.330498)
		(width 0.18288)
		(layer "In6.Cu")
		(net "M_G_CPU0_SB_DQS_DN<5>")
	)
	(segment
		(start 420.294308 -233.172762)
		(end 419.424866 -233.172762)
		(width 0.18288)
		(layer "In6.Cu")
		(net "M_G_CPU0_SB_DQS_DN<5>")
	)
	(segment
		(start 419.424866 -233.172762)
		(end 419.300406 -233.297222)
		(width 0.18288)
		(layer "In6.Cu")
		(net "M_G_CPU0_SB_DQS_DN<5>")
	)
	(segment
		(start 414.122362 -232.576878)
		(end 413.544004 -232.576878)
		(width 0.18288)
		(layer "In6.Cu")
		(net "M_G_CPU0_SB_DQS_DN<5>")
	)
	(segment
		(start 428.471076 -232.197402)
		(end 427.864524 -232.197402)
		(width 0.18288)
		(layer "In6.Cu")
		(net "M_G_CPU0_SB_DQS_DN<5>")
	)
	(segment
		(start 379.598936 -239.528858)
		(end 379.588522 -239.534954)
		(width 0.088646)
		(layer "In6.Cu")
		(net "M_G_CPU0_SB_DQS_DN<5>")
	)
	(segment
		(start 430.063656 -230.604822)
		(end 429.53559 -231.132888)
		(width 0.18288)
		(layer "In6.Cu")
		(net "M_G_CPU0_SB_DQS_DN<5>")
	)
	(segment
		(start 425.27982 -232.323386)
		(end 425.012358 -232.590848)
		(width 0.18288)
		(layer "In6.Cu")
		(net "M_G_CPU0_SB_DQS_DN<5>")
	)
	(arc
		(start 384.672078 -239.528858)
		(mid 384.48488 -239.478715)
		(end 384.297682 -239.528858)
		(width 0.088646)
		(layer "In6.Cu")
		(net "M_G_CPU0_SB_DQS_DN<5>")
	)
	(arc
		(start 383.732532 -239.528858)
		(mid 383.545334 -239.478715)
		(end 383.358136 -239.528858)
		(width 0.088646)
		(layer "In6.Cu")
		(net "M_G_CPU0_SB_DQS_DN<5>")
	)
	(arc
		(start 387.10235 -239.537494)
		(mid 386.825875 -239.604814)
		(end 386.551678 -239.528858)
		(width 0.088646)
		(layer "In6.Cu")
		(net "M_G_CPU0_SB_DQS_DN<5>")
	)
	(arc
		(start 384.297428 -239.528858)
		(mid 384.015205 -239.604253)
		(end 383.73304 -239.528604)
		(width 0.088646)
		(layer "In6.Cu")
		(net "M_G_CPU0_SB_DQS_DN<5>")
	)
	(arc
		(start 382.792478 -239.528858)
		(mid 382.60528 -239.478715)
		(end 382.418082 -239.528858)
		(width 0.088646)
		(layer "In6.Cu")
		(net "M_G_CPU0_SB_DQS_DN<5>")
	)
	(arc
		(start 379.973332 -239.528858)
		(mid 379.786134 -239.478715)
		(end 379.598936 -239.528858)
		(width 0.088646)
		(layer "In6.Cu")
		(net "M_G_CPU0_SB_DQS_DN<5>")
	)
	(arc
		(start 380.528068 -239.534954)
		(mid 380.24989 -239.604677)
		(end 379.973332 -239.528858)
		(width 0.088646)
		(layer "In6.Cu")
		(net "M_G_CPU0_SB_DQS_DN<5>")
	)
	(arc
		(start 378.64415 -239.537494)
		(mid 378.367675 -239.604814)
		(end 378.093478 -239.528858)
		(width 0.088646)
		(layer "In6.Cu")
		(net "M_G_CPU0_SB_DQS_DN<5>")
	)
	(arc
		(start 381.468122 -239.534954)
		(mid 381.18969 -239.6048)
		(end 380.912878 -239.528858)
		(width 0.088646)
		(layer "In6.Cu")
		(net "M_G_CPU0_SB_DQS_DN<5>")
	)
	(arc
		(start 386.16255 -239.537494)
		(mid 385.886075 -239.604814)
		(end 385.611878 -239.528858)
		(width 0.088646)
		(layer "In6.Cu")
		(net "M_G_CPU0_SB_DQS_DN<5>")
	)
	(arc
		(start 381.852932 -239.528858)
		(mid 381.665734 -239.478715)
		(end 381.478536 -239.528858)
		(width 0.088646)
		(layer "In6.Cu")
		(net "M_G_CPU0_SB_DQS_DN<5>")
	)
	(arc
		(start 380.912878 -239.528858)
		(mid 380.72568 -239.478715)
		(end 380.538482 -239.528858)
		(width 0.088646)
		(layer "In6.Cu")
		(net "M_G_CPU0_SB_DQS_DN<5>")
	)
	(arc
		(start 379.033278 -239.528858)
		(mid 378.84608 -239.478715)
		(end 378.658882 -239.528858)
		(width 0.088646)
		(layer "In6.Cu")
		(net "M_G_CPU0_SB_DQS_DN<5>")
	)
	(arc
		(start 385.22275 -239.537494)
		(mid 384.946275 -239.604814)
		(end 384.672078 -239.528858)
		(width 0.088646)
		(layer "In6.Cu")
		(net "M_G_CPU0_SB_DQS_DN<5>")
	)
	(arc
		(start 378.093478 -239.528858)
		(mid 377.90628 -239.478715)
		(end 377.719082 -239.528858)
		(width 0.088646)
		(layer "In6.Cu")
		(net "M_G_CPU0_SB_DQS_DN<5>")
	)
	(arc
		(start 379.588522 -239.534954)
		(mid 379.31009 -239.6048)
		(end 379.033278 -239.528858)
		(width 0.088646)
		(layer "In6.Cu")
		(net "M_G_CPU0_SB_DQS_DN<5>")
	)
	(arc
		(start 382.407668 -239.534954)
		(mid 382.12949 -239.604677)
		(end 381.852932 -239.528858)
		(width 0.088646)
		(layer "In6.Cu")
		(net "M_G_CPU0_SB_DQS_DN<5>")
	)
	(arc
		(start 383.347722 -239.534954)
		(mid 383.06929 -239.6048)
		(end 382.792478 -239.528858)
		(width 0.088646)
		(layer "In6.Cu")
		(net "M_G_CPU0_SB_DQS_DN<5>")
	)
	(arc
		(start 386.551678 -239.528858)
		(mid 386.36448 -239.478715)
		(end 386.177282 -239.528858)
		(width 0.088646)
		(layer "In6.Cu")
		(net "M_G_CPU0_SB_DQS_DN<5>")
	)
	(arc
		(start 385.611878 -239.528858)
		(mid 385.42468 -239.478715)
		(end 385.237482 -239.528858)
		(width 0.088646)
		(layer "In6.Cu")
		(net "M_G_CPU0_SB_DQS_DN<5>")
	)
	(arc
		(start 387.30428 -239.478312)
		(mid 387.199079 -239.493449)
		(end 387.10235 -239.537494)
		(width 0.088646)
		(layer "In6.Cu")
		(net "M_G_CPU0_SB_DQS_DN<5>")
	)
	(segment
		(start 447.814446 -237.01248)
		(end 448.0687 -237.266734)
		(width 0.20066)
		(layer "F.Cu")
		(net "M_G_CPU0_SB_DQS_DN<4>")
	)
	(segment
		(start 448.0687 -237.266734)
		(end 448.572382 -237.266734)
		(width 0.20066)
		(layer "F.Cu")
		(net "M_G_CPU0_SB_DQS_DN<4>")
	)
	(segment
		(start 443.283086 -236.841792)
		(end 443.461648 -236.841792)
		(width 0.101854)
		(layer "F.Cu")
		(net "M_G_CPU0_SB_DQS_DN<4>")
	)
	(segment
		(start 443.461648 -236.841792)
		(end 445.471804 -236.841792)
		(width 0.1016)
		(layer "F.Cu")
		(net "M_G_CPU0_SB_DQS_DN<4>")
	)
	(segment
		(start 441.559188 -237.266734)
		(end 441.83046 -236.995462)
		(width 0.20066)
		(layer "F.Cu")
		(net "M_G_CPU0_SB_DQS_DN<4>")
	)
	(segment
		(start 380.256034 -242.830604)
		(end 380.256034 -242.294918)
		(width 0.20066)
		(layer "F.Cu")
		(net "M_G_CPU0_SB_DQS_DN<4>")
	)
	(segment
		(start 380.25578 -242.830858)
		(end 380.256034 -242.830604)
		(width 0.20066)
		(layer "F.Cu")
		(net "M_G_CPU0_SB_DQS_DN<4>")
	)
	(segment
		(start 445.812418 -236.841792)
		(end 446.087246 -236.566964)
		(width 0.20066)
		(layer "F.Cu")
		(net "M_G_CPU0_SB_DQS_DN<4>")
	)
	(segment
		(start 445.690752 -236.841792)
		(end 445.812418 -236.841792)
		(width 0.20066)
		(layer "F.Cu")
		(net "M_G_CPU0_SB_DQS_DN<4>")
	)
	(segment
		(start 443.13856 -236.841792)
		(end 443.283086 -236.841792)
		(width 0.20066)
		(layer "F.Cu")
		(net "M_G_CPU0_SB_DQS_DN<4>")
	)
	(segment
		(start 441.83046 -236.995462)
		(end 442.313822 -236.995462)
		(width 0.20066)
		(layer "F.Cu")
		(net "M_G_CPU0_SB_DQS_DN<4>")
	)
	(segment
		(start 442.867288 -236.57052)
		(end 443.13856 -236.841792)
		(width 0.20066)
		(layer "F.Cu")
		(net "M_G_CPU0_SB_DQS_DN<4>")
	)
	(segment
		(start 442.738764 -236.57052)
		(end 442.867288 -236.57052)
		(width 0.20066)
		(layer "F.Cu")
		(net "M_G_CPU0_SB_DQS_DN<4>")
	)
	(segment
		(start 447.022728 -237.01248)
		(end 447.814446 -237.01248)
		(width 0.20066)
		(layer "F.Cu")
		(net "M_G_CPU0_SB_DQS_DN<4>")
	)
	(segment
		(start 439.923682 -237.266734)
		(end 441.028582 -237.266734)
		(width 0.20066)
		(layer "F.Cu")
		(net "M_G_CPU0_SB_DQS_DN<4>")
	)
	(segment
		(start 446.577212 -236.566964)
		(end 447.022728 -237.01248)
		(width 0.20066)
		(layer "F.Cu")
		(net "M_G_CPU0_SB_DQS_DN<4>")
	)
	(segment
		(start 445.471804 -236.841792)
		(end 445.690752 -236.841792)
		(width 0.101854)
		(layer "F.Cu")
		(net "M_G_CPU0_SB_DQS_DN<4>")
	)
	(segment
		(start 442.313822 -236.995462)
		(end 442.738764 -236.57052)
		(width 0.20066)
		(layer "F.Cu")
		(net "M_G_CPU0_SB_DQS_DN<4>")
	)
	(segment
		(start 446.087246 -236.566964)
		(end 446.577212 -236.566964)
		(width 0.20066)
		(layer "F.Cu")
		(net "M_G_CPU0_SB_DQS_DN<4>")
	)
	(segment
		(start 441.028582 -237.266734)
		(end 441.559188 -237.266734)
		(width 0.20066)
		(layer "F.Cu")
		(net "M_G_CPU0_SB_DQS_DN<4>")
	)
	(segment
		(start 413.959548 -237.212886)
		(end 412.900114 -237.212886)
		(width 0.18288)
		(layer "In4.Cu")
		(net "M_G_CPU0_SB_DQS_DN<4>")
	)
	(segment
		(start 405.075898 -237.441486)
		(end 404.951438 -237.565946)
		(width 0.18288)
		(layer "In4.Cu")
		(net "M_G_CPU0_SB_DQS_DN<4>")
	)
	(segment
		(start 419.47719 -236.552232)
		(end 417.88207 -237.212886)
		(width 0.18288)
		(layer "In4.Cu")
		(net "M_G_CPU0_SB_DQS_DN<4>")
	)
	(segment
		(start 412.102808 -236.882686)
		(end 411.556708 -236.882686)
		(width 0.18288)
		(layer "In4.Cu")
		(net "M_G_CPU0_SB_DQS_DN<4>")
	)
	(segment
		(start 439.641488 -236.98454)
		(end 439.257694 -236.98454)
		(width 0.18288)
		(layer "In4.Cu")
		(net "M_G_CPU0_SB_DQS_DN<4>")
	)
	(segment
		(start 436.83301 -236.560868)
		(end 436.298848 -236.560868)
		(width 0.18288)
		(layer "In4.Cu")
		(net "M_G_CPU0_SB_DQS_DN<4>")
	)
	(segment
		(start 404.405338 -237.565946)
		(end 404.280878 -237.441486)
		(width 0.18288)
		(layer "In4.Cu")
		(net "M_G_CPU0_SB_DQS_DN<4>")
	)
	(segment
		(start 388.255764 -241.720624)
		(end 388.232396 -241.720624)
		(width 0.088646)
		(layer "In4.Cu")
		(net "M_G_CPU0_SB_DQS_DN<4>")
	)
	(segment
		(start 406.292558 -237.565946)
		(end 405.746458 -237.565946)
		(width 0.18288)
		(layer "In4.Cu")
		(net "M_G_CPU0_SB_DQS_DN<4>")
	)
	(segment
		(start 398.869408 -239.084104)
		(end 394.565632 -239.084104)
		(width 0.18288)
		(layer "In4.Cu")
		(net "M_G_CPU0_SB_DQS_DN<4>")
	)
	(segment
		(start 401.022058 -237.441486)
		(end 400.151346 -237.802166)
		(width 0.18288)
		(layer "In4.Cu")
		(net "M_G_CPU0_SB_DQS_DN<4>")
	)
	(segment
		(start 439.257694 -236.98454)
		(end 438.962546 -237.279688)
		(width 0.18288)
		(layer "In4.Cu")
		(net "M_G_CPU0_SB_DQS_DN<4>")
	)
	(segment
		(start 411.556708 -236.882686)
		(end 411.432248 -237.007146)
		(width 0.18288)
		(layer "In4.Cu")
		(net "M_G_CPU0_SB_DQS_DN<4>")
	)
	(segment
		(start 414.084008 -237.337346)
		(end 413.959548 -237.212886)
		(width 0.18288)
		(layer "In4.Cu")
		(net "M_G_CPU0_SB_DQS_DN<4>")
	)
	(segment
		(start 388.232396 -241.720624)
		(end 388.172452 -241.66068)
		(width 0.088646)
		(layer "In4.Cu")
		(net "M_G_CPU0_SB_DQS_DN<4>")
	)
	(segment
		(start 438.962546 -237.279688)
		(end 437.55183 -237.279688)
		(width 0.18288)
		(layer "In4.Cu")
		(net "M_G_CPU0_SB_DQS_DN<4>")
	)
	(segment
		(start 437.55183 -237.279688)
		(end 436.83301 -236.560868)
		(width 0.18288)
		(layer "In4.Cu")
		(net "M_G_CPU0_SB_DQS_DN<4>")
	)
	(segment
		(start 436.015892 -236.843824)
		(end 435.631844 -236.843824)
		(width 0.18288)
		(layer "In4.Cu")
		(net "M_G_CPU0_SB_DQS_DN<4>")
	)
	(segment
		(start 402.393658 -237.441486)
		(end 402.269198 -237.565946)
		(width 0.18288)
		(layer "In4.Cu")
		(net "M_G_CPU0_SB_DQS_DN<4>")
	)
	(segment
		(start 435.631844 -236.843824)
		(end 435.366414 -236.578394)
		(width 0.18288)
		(layer "In4.Cu")
		(net "M_G_CPU0_SB_DQS_DN<4>")
	)
	(segment
		(start 425.02836 -235.99394)
		(end 424.644312 -235.99394)
		(width 0.18288)
		(layer "In4.Cu")
		(net "M_G_CPU0_SB_DQS_DN<4>")
	)
	(segment
		(start 415.971228 -237.337346)
		(end 415.425128 -237.337346)
		(width 0.18288)
		(layer "In4.Cu")
		(net "M_G_CPU0_SB_DQS_DN<4>")
	)
	(segment
		(start 407.087578 -237.565946)
		(end 406.963118 -237.441486)
		(width 0.18288)
		(layer "In4.Cu")
		(net "M_G_CPU0_SB_DQS_DN<4>")
	)
	(segment
		(start 382.892554 -241.96802)
		(end 382.888236 -241.97056)
		(width 0.088646)
		(layer "In4.Cu")
		(net "M_G_CPU0_SB_DQS_DN<4>")
	)
	(segment
		(start 403.610318 -237.565946)
		(end 403.064218 -237.565946)
		(width 0.18288)
		(layer "In4.Cu")
		(net "M_G_CPU0_SB_DQS_DN<4>")
	)
	(segment
		(start 404.951438 -237.565946)
		(end 404.405338 -237.565946)
		(width 0.18288)
		(layer "In4.Cu")
		(net "M_G_CPU0_SB_DQS_DN<4>")
	)
	(segment
		(start 415.300668 -237.212886)
		(end 414.754568 -237.212886)
		(width 0.18288)
		(layer "In4.Cu")
		(net "M_G_CPU0_SB_DQS_DN<4>")
	)
	(segment
		(start 428.014892 -235.720128)
		(end 427.383194 -236.351826)
		(width 0.18288)
		(layer "In4.Cu")
		(net "M_G_CPU0_SB_DQS_DN<4>")
	)
	(segment
		(start 412.900114 -237.212886)
		(end 412.102808 -236.882686)
		(width 0.18288)
		(layer "In4.Cu")
		(net "M_G_CPU0_SB_DQS_DN<4>")
	)
	(segment
		(start 416.095688 -237.212886)
		(end 415.971228 -237.337346)
		(width 0.18288)
		(layer "In4.Cu")
		(net "M_G_CPU0_SB_DQS_DN<4>")
	)
	(segment
		(start 431.534824 -236.377226)
		(end 430.877726 -235.720128)
		(width 0.18288)
		(layer "In4.Cu")
		(net "M_G_CPU0_SB_DQS_DN<4>")
	)
	(segment
		(start 401.723098 -237.565946)
		(end 401.598638 -237.441486)
		(width 0.18288)
		(layer "In4.Cu")
		(net "M_G_CPU0_SB_DQS_DN<4>")
	)
	(segment
		(start 435.366414 -236.578394)
		(end 434.994304 -236.578394)
		(width 0.18288)
		(layer "In4.Cu")
		(net "M_G_CPU0_SB_DQS_DN<4>")
	)
	(segment
		(start 381.008636 -241.97056)
		(end 381.008382 -241.97056)
		(width 0.088646)
		(layer "In4.Cu")
		(net "M_G_CPU0_SB_DQS_DN<4>")
	)
	(segment
		(start 434.994304 -236.578394)
		(end 434.793136 -236.377226)
		(width 0.18288)
		(layer "In4.Cu")
		(net "M_G_CPU0_SB_DQS_DN<4>")
	)
	(segment
		(start 423.29735 -235.68787)
		(end 422.424352 -236.560868)
		(width 0.18288)
		(layer "In4.Cu")
		(net "M_G_CPU0_SB_DQS_DN<4>")
	)
	(segment
		(start 421.211248 -236.560868)
		(end 420.928292 -236.843824)
		(width 0.18288)
		(layer "In4.Cu")
		(net "M_G_CPU0_SB_DQS_DN<4>")
	)
	(segment
		(start 394.565632 -239.084104)
		(end 392.208766 -241.441224)
		(width 0.18288)
		(layer "In4.Cu")
		(net "M_G_CPU0_SB_DQS_DN<4>")
	)
	(segment
		(start 411.432248 -237.007146)
		(end 410.886148 -237.007146)
		(width 0.18288)
		(layer "In4.Cu")
		(net "M_G_CPU0_SB_DQS_DN<4>")
	)
	(segment
		(start 425.302426 -235.719874)
		(end 425.02836 -235.99394)
		(width 0.18288)
		(layer "In4.Cu")
		(net "M_G_CPU0_SB_DQS_DN<4>")
	)
	(segment
		(start 391.534142 -241.720624)
		(end 388.255764 -241.720624)
		(width 0.18288)
		(layer "In4.Cu")
		(net "M_G_CPU0_SB_DQS_DN<4>")
	)
	(segment
		(start 415.425128 -237.337346)
		(end 415.300668 -237.212886)
		(width 0.18288)
		(layer "In4.Cu")
		(net "M_G_CPU0_SB_DQS_DN<4>")
	)
	(segment
		(start 425.966382 -235.719874)
		(end 425.302426 -235.719874)
		(width 0.18288)
		(layer "In4.Cu")
		(net "M_G_CPU0_SB_DQS_DN<4>")
	)
	(segment
		(start 382.337564 -241.979196)
		(end 382.322832 -241.97056)
		(width 0.088646)
		(layer "In4.Cu")
		(net "M_G_CPU0_SB_DQS_DN<4>")
	)
	(segment
		(start 430.877726 -235.720128)
		(end 428.014892 -235.720128)
		(width 0.18288)
		(layer "In4.Cu")
		(net "M_G_CPU0_SB_DQS_DN<4>")
	)
	(segment
		(start 384.767582 -241.970306)
		(end 384.767836 -241.97056)
		(width 0.088646)
		(layer "In4.Cu")
		(net "M_G_CPU0_SB_DQS_DN<4>")
	)
	(segment
		(start 403.064218 -237.565946)
		(end 402.939758 -237.441486)
		(width 0.18288)
		(layer "In4.Cu")
		(net "M_G_CPU0_SB_DQS_DN<4>")
	)
	(segment
		(start 439.923682 -237.266734)
		(end 439.641488 -236.98454)
		(width 0.18288)
		(layer "In4.Cu")
		(net "M_G_CPU0_SB_DQS_DN<4>")
	)
	(segment
		(start 380.267972 -242.145566)
		(end 380.256034 -242.294918)
		(width 0.088646)
		(layer "In4.Cu")
		(net "M_G_CPU0_SB_DQS_DN<4>")
	)
	(segment
		(start 434.793136 -236.377226)
		(end 431.534824 -236.377226)
		(width 0.18288)
		(layer "In4.Cu")
		(net "M_G_CPU0_SB_DQS_DN<4>")
	)
	(segment
		(start 408.304238 -237.441486)
		(end 407.758138 -237.441486)
		(width 0.18288)
		(layer "In4.Cu")
		(net "M_G_CPU0_SB_DQS_DN<4>")
	)
	(segment
		(start 387.836156 -241.66068)
		(end 387.577076 -241.91976)
		(width 0.088646)
		(layer "In4.Cu")
		(net "M_G_CPU0_SB_DQS_DN<4>")
	)
	(segment
		(start 407.758138 -237.441486)
		(end 407.633678 -237.565946)
		(width 0.18288)
		(layer "In4.Cu")
		(net "M_G_CPU0_SB_DQS_DN<4>")
	)
	(segment
		(start 381.008382 -241.97056)
		(end 380.87681 -242.046506)
		(width 0.088646)
		(layer "In4.Cu")
		(net "M_G_CPU0_SB_DQS_DN<4>")
	)
	(segment
		(start 387.577076 -241.91976)
		(end 386.834634 -241.91976)
		(width 0.088646)
		(layer "In4.Cu")
		(net "M_G_CPU0_SB_DQS_DN<4>")
	)
	(segment
		(start 436.298848 -236.560868)
		(end 436.015892 -236.843824)
		(width 0.18288)
		(layer "In4.Cu")
		(net "M_G_CPU0_SB_DQS_DN<4>")
	)
	(segment
		(start 380.72187 -242.087908)
		(end 380.330456 -242.087908)
		(width 0.088646)
		(layer "In4.Cu")
		(net "M_G_CPU0_SB_DQS_DN<4>")
	)
	(segment
		(start 402.939758 -237.441486)
		(end 402.393658 -237.441486)
		(width 0.18288)
		(layer "In4.Cu")
		(net "M_G_CPU0_SB_DQS_DN<4>")
	)
	(segment
		(start 388.172452 -241.66068)
		(end 387.836156 -241.66068)
		(width 0.088646)
		(layer "In4.Cu")
		(net "M_G_CPU0_SB_DQS_DN<4>")
	)
	(segment
		(start 407.633678 -237.565946)
		(end 407.087578 -237.565946)
		(width 0.18288)
		(layer "In4.Cu")
		(net "M_G_CPU0_SB_DQS_DN<4>")
	)
	(segment
		(start 392.208766 -241.441224)
		(end 391.534142 -241.720624)
		(width 0.18288)
		(layer "In4.Cu")
		(net "M_G_CPU0_SB_DQS_DN<4>")
	)
	(segment
		(start 400.151346 -237.802166)
		(end 398.869408 -239.084104)
		(width 0.18288)
		(layer "In4.Cu")
		(net "M_G_CPU0_SB_DQS_DN<4>")
	)
	(segment
		(start 404.280878 -237.441486)
		(end 403.734778 -237.441486)
		(width 0.18288)
		(layer "In4.Cu")
		(net "M_G_CPU0_SB_DQS_DN<4>")
	)
	(segment
		(start 380.87681 -242.046506)
		(end 380.72187 -242.087908)
		(width 0.088646)
		(layer "In4.Cu")
		(net "M_G_CPU0_SB_DQS_DN<4>")
	)
	(segment
		(start 417.88207 -237.212886)
		(end 416.095688 -237.212886)
		(width 0.18288)
		(layer "In4.Cu")
		(net "M_G_CPU0_SB_DQS_DN<4>")
	)
	(segment
		(start 408.863038 -236.882686)
		(end 408.304238 -237.441486)
		(width 0.18288)
		(layer "In4.Cu")
		(net "M_G_CPU0_SB_DQS_DN<4>")
	)
	(segment
		(start 406.963118 -237.441486)
		(end 406.417018 -237.441486)
		(width 0.18288)
		(layer "In4.Cu")
		(net "M_G_CPU0_SB_DQS_DN<4>")
	)
	(segment
		(start 401.598638 -237.441486)
		(end 401.022058 -237.441486)
		(width 0.18288)
		(layer "In4.Cu")
		(net "M_G_CPU0_SB_DQS_DN<4>")
	)
	(segment
		(start 403.734778 -237.441486)
		(end 403.610318 -237.565946)
		(width 0.18288)
		(layer "In4.Cu")
		(net "M_G_CPU0_SB_DQS_DN<4>")
	)
	(segment
		(start 427.383194 -236.351826)
		(end 426.598334 -236.351826)
		(width 0.18288)
		(layer "In4.Cu")
		(net "M_G_CPU0_SB_DQS_DN<4>")
	)
	(segment
		(start 420.252652 -236.552232)
		(end 419.47719 -236.552232)
		(width 0.18288)
		(layer "In4.Cu")
		(net "M_G_CPU0_SB_DQS_DN<4>")
	)
	(segment
		(start 385.142232 -241.97056)
		(end 385.142486 -241.970306)
		(width 0.088646)
		(layer "In4.Cu")
		(net "M_G_CPU0_SB_DQS_DN<4>")
	)
	(segment
		(start 422.424352 -236.560868)
		(end 421.211248 -236.560868)
		(width 0.18288)
		(layer "In4.Cu")
		(net "M_G_CPU0_SB_DQS_DN<4>")
	)
	(segment
		(start 420.544244 -236.843824)
		(end 420.252652 -236.552232)
		(width 0.18288)
		(layer "In4.Cu")
		(net "M_G_CPU0_SB_DQS_DN<4>")
	)
	(segment
		(start 420.928292 -236.843824)
		(end 420.544244 -236.843824)
		(width 0.18288)
		(layer "In4.Cu")
		(net "M_G_CPU0_SB_DQS_DN<4>")
	)
	(segment
		(start 410.886148 -237.007146)
		(end 410.761688 -236.882686)
		(width 0.18288)
		(layer "In4.Cu")
		(net "M_G_CPU0_SB_DQS_DN<4>")
	)
	(segment
		(start 406.417018 -237.441486)
		(end 406.292558 -237.565946)
		(width 0.18288)
		(layer "In4.Cu")
		(net "M_G_CPU0_SB_DQS_DN<4>")
	)
	(segment
		(start 424.338242 -235.68787)
		(end 423.29735 -235.68787)
		(width 0.18288)
		(layer "In4.Cu")
		(net "M_G_CPU0_SB_DQS_DN<4>")
	)
	(segment
		(start 426.598334 -236.351826)
		(end 425.966382 -235.719874)
		(width 0.18288)
		(layer "In4.Cu")
		(net "M_G_CPU0_SB_DQS_DN<4>")
	)
	(segment
		(start 410.761688 -236.882686)
		(end 408.863038 -236.882686)
		(width 0.18288)
		(layer "In4.Cu")
		(net "M_G_CPU0_SB_DQS_DN<4>")
	)
	(segment
		(start 402.269198 -237.565946)
		(end 401.723098 -237.565946)
		(width 0.18288)
		(layer "In4.Cu")
		(net "M_G_CPU0_SB_DQS_DN<4>")
	)
	(segment
		(start 405.621998 -237.441486)
		(end 405.075898 -237.441486)
		(width 0.18288)
		(layer "In4.Cu")
		(net "M_G_CPU0_SB_DQS_DN<4>")
	)
	(segment
		(start 414.630108 -237.337346)
		(end 414.084008 -237.337346)
		(width 0.18288)
		(layer "In4.Cu")
		(net "M_G_CPU0_SB_DQS_DN<4>")
	)
	(segment
		(start 424.644312 -235.99394)
		(end 424.338242 -235.68787)
		(width 0.18288)
		(layer "In4.Cu")
		(net "M_G_CPU0_SB_DQS_DN<4>")
	)
	(segment
		(start 414.754568 -237.212886)
		(end 414.630108 -237.337346)
		(width 0.18288)
		(layer "In4.Cu")
		(net "M_G_CPU0_SB_DQS_DN<4>")
	)
	(segment
		(start 405.746458 -237.565946)
		(end 405.621998 -237.441486)
		(width 0.18288)
		(layer "In4.Cu")
		(net "M_G_CPU0_SB_DQS_DN<4>")
	)
	(arc
		(start 386.834634 -241.91976)
		(mid 386.818616 -241.920178)
		(end 386.80263 -241.921284)
		(width 0.088646)
		(layer "In4.Cu")
		(net "M_G_CPU0_SB_DQS_DN<4>")
	)
	(arc
		(start 384.767836 -241.97056)
		(mid 384.485134 -242.046336)
		(end 384.202432 -241.97056)
		(width 0.088646)
		(layer "In4.Cu")
		(net "M_G_CPU0_SB_DQS_DN<4>")
	)
	(arc
		(start 381.948436 -241.97056)
		(mid 381.665734 -242.046336)
		(end 381.383032 -241.97056)
		(width 0.088646)
		(layer "In4.Cu")
		(net "M_G_CPU0_SB_DQS_DN<4>")
	)
	(arc
		(start 385.707636 -241.97056)
		(mid 385.424934 -242.046336)
		(end 385.142232 -241.97056)
		(width 0.088646)
		(layer "In4.Cu")
		(net "M_G_CPU0_SB_DQS_DN<4>")
	)
	(arc
		(start 386.082032 -241.97056)
		(mid 385.894834 -241.920417)
		(end 385.707636 -241.97056)
		(width 0.088646)
		(layer "In4.Cu")
		(net "M_G_CPU0_SB_DQS_DN<4>")
	)
	(arc
		(start 382.322832 -241.97056)
		(mid 382.135634 -241.920417)
		(end 381.948436 -241.97056)
		(width 0.088646)
		(layer "In4.Cu")
		(net "M_G_CPU0_SB_DQS_DN<4>")
	)
	(arc
		(start 385.142486 -241.970306)
		(mid 384.955034 -241.92007)
		(end 384.767582 -241.970306)
		(width 0.088646)
		(layer "In4.Cu")
		(net "M_G_CPU0_SB_DQS_DN<4>")
	)
	(arc
		(start 386.647436 -241.97056)
		(mid 386.364734 -242.046336)
		(end 386.082032 -241.97056)
		(width 0.088646)
		(layer "In4.Cu")
		(net "M_G_CPU0_SB_DQS_DN<4>")
	)
	(arc
		(start 383.828036 -241.97056)
		(mid 383.545334 -242.046336)
		(end 383.262632 -241.97056)
		(width 0.088646)
		(layer "In4.Cu")
		(net "M_G_CPU0_SB_DQS_DN<4>")
	)
	(arc
		(start 380.330456 -242.087908)
		(mid 380.287929 -242.104521)
		(end 380.267972 -242.145566)
		(width 0.088646)
		(layer "In4.Cu")
		(net "M_G_CPU0_SB_DQS_DN<4>")
	)
	(arc
		(start 382.888236 -241.97056)
		(mid 382.614037 -242.046395)
		(end 382.337564 -241.979196)
		(width 0.088646)
		(layer "In4.Cu")
		(net "M_G_CPU0_SB_DQS_DN<4>")
	)
	(arc
		(start 386.80263 -241.921284)
		(mid 386.722315 -241.937371)
		(end 386.647436 -241.97056)
		(width 0.088646)
		(layer "In4.Cu")
		(net "M_G_CPU0_SB_DQS_DN<4>")
	)
	(arc
		(start 384.202432 -241.97056)
		(mid 384.015234 -241.920417)
		(end 383.828036 -241.97056)
		(width 0.088646)
		(layer "In4.Cu")
		(net "M_G_CPU0_SB_DQS_DN<4>")
	)
	(arc
		(start 383.262632 -241.97056)
		(mid 383.077938 -241.920459)
		(end 382.892554 -241.96802)
		(width 0.088646)
		(layer "In4.Cu")
		(net "M_G_CPU0_SB_DQS_DN<4>")
	)
	(arc
		(start 381.383032 -241.97056)
		(mid 381.195834 -241.920417)
		(end 381.008636 -241.97056)
		(width 0.088646)
		(layer "In4.Cu")
		(net "M_G_CPU0_SB_DQS_DN<4>")
	)
	(segment
		(start 439.430922 -200.562972)
		(end 439.702194 -200.2917)
		(width 0.20066)
		(layer "F.Cu")
		(net "M_G_CPU0_SB_DQS_DN<3>")
	)
	(segment
		(start 438.909206 -200.562972)
		(end 439.430922 -200.562972)
		(width 0.20066)
		(layer "F.Cu")
		(net "M_G_CPU0_SB_DQS_DN<3>")
	)
	(segment
		(start 439.854086 -200.2917)
		(end 442.03366 -200.2917)
		(width 0.1016)
		(layer "F.Cu")
		(net "M_G_CPU0_SB_DQS_DN<3>")
	)
	(segment
		(start 385.894834 -218.414346)
		(end 385.894834 -217.878406)
		(width 0.20066)
		(layer "F.Cu")
		(net "M_G_CPU0_SB_DQS_DN<3>")
	)
	(segment
		(start 442.038994 -200.286366)
		(end 442.363098 -200.286366)
		(width 0.20066)
		(layer "F.Cu")
		(net "M_G_CPU0_SB_DQS_DN<3>")
	)
	(segment
		(start 435.823614 -199.866758)
		(end 436.928514 -199.866758)
		(width 0.20066)
		(layer "F.Cu")
		(net "M_G_CPU0_SB_DQS_DN<3>")
	)
	(segment
		(start 442.363098 -200.286366)
		(end 442.594492 -200.51776)
		(width 0.20066)
		(layer "F.Cu")
		(net "M_G_CPU0_SB_DQS_DN<3>")
	)
	(segment
		(start 443.642496 -200.107296)
		(end 443.883034 -199.866758)
		(width 0.20066)
		(layer "F.Cu")
		(net "M_G_CPU0_SB_DQS_DN<3>")
	)
	(segment
		(start 438.494678 -200.148444)
		(end 438.909206 -200.562972)
		(width 0.20066)
		(layer "F.Cu")
		(net "M_G_CPU0_SB_DQS_DN<3>")
	)
	(segment
		(start 442.03366 -200.2917)
		(end 442.038994 -200.286366)
		(width 0.1016)
		(layer "F.Cu")
		(net "M_G_CPU0_SB_DQS_DN<3>")
	)
	(segment
		(start 439.849768 -200.2917)
		(end 439.854086 -200.2917)
		(width 0.101854)
		(layer "F.Cu")
		(net "M_G_CPU0_SB_DQS_DN<3>")
	)
	(segment
		(start 436.928514 -199.866758)
		(end 437.477154 -199.866758)
		(width 0.20066)
		(layer "F.Cu")
		(net "M_G_CPU0_SB_DQS_DN<3>")
	)
	(segment
		(start 443.31001 -200.107296)
		(end 443.642496 -200.107296)
		(width 0.20066)
		(layer "F.Cu")
		(net "M_G_CPU0_SB_DQS_DN<3>")
	)
	(segment
		(start 437.477154 -199.866758)
		(end 437.75884 -200.148444)
		(width 0.20066)
		(layer "F.Cu")
		(net "M_G_CPU0_SB_DQS_DN<3>")
	)
	(segment
		(start 439.702194 -200.2917)
		(end 439.849768 -200.2917)
		(width 0.20066)
		(layer "F.Cu")
		(net "M_G_CPU0_SB_DQS_DN<3>")
	)
	(segment
		(start 442.899546 -200.51776)
		(end 443.31001 -200.107296)
		(width 0.20066)
		(layer "F.Cu")
		(net "M_G_CPU0_SB_DQS_DN<3>")
	)
	(segment
		(start 437.75884 -200.148444)
		(end 438.494678 -200.148444)
		(width 0.20066)
		(layer "F.Cu")
		(net "M_G_CPU0_SB_DQS_DN<3>")
	)
	(segment
		(start 442.594492 -200.51776)
		(end 442.899546 -200.51776)
		(width 0.20066)
		(layer "F.Cu")
		(net "M_G_CPU0_SB_DQS_DN<3>")
	)
	(segment
		(start 443.883034 -199.866758)
		(end 444.472314 -199.866758)
		(width 0.20066)
		(layer "F.Cu")
		(net "M_G_CPU0_SB_DQS_DN<3>")
	)
	(segment
		(start 435.823614 -199.866758)
		(end 435.56809 -200.122282)
		(width 0.18288)
		(layer "In6.Cu")
		(net "M_G_CPU0_SB_DQS_DN<3>")
	)
	(segment
		(start 423.447972 -199.885046)
		(end 423.056812 -199.885046)
		(width 0.18288)
		(layer "In6.Cu")
		(net "M_G_CPU0_SB_DQS_DN<3>")
	)
	(segment
		(start 397.23441 -207.737964)
		(end 397.23441 -209.203798)
		(width 0.18288)
		(layer "In6.Cu")
		(net "M_G_CPU0_SB_DQS_DN<3>")
	)
	(segment
		(start 429.63719 -199.663812)
		(end 429.013874 -200.287128)
		(width 0.18288)
		(layer "In6.Cu")
		(net "M_G_CPU0_SB_DQS_DN<3>")
	)
	(segment
		(start 390.136126 -216.302082)
		(end 390.136126 -216.38641)
		(width 0.088646)
		(layer "In6.Cu")
		(net "M_G_CPU0_SB_DQS_DN<3>")
	)
	(segment
		(start 423.056812 -199.885046)
		(end 422.042336 -198.87057)
		(width 0.18288)
		(layer "In6.Cu")
		(net "M_G_CPU0_SB_DQS_DN<3>")
	)
	(segment
		(start 385.759706 -218.227402)
		(end 385.738624 -218.149424)
		(width 0.088646)
		(layer "In6.Cu")
		(net "M_G_CPU0_SB_DQS_DN<3>")
	)
	(segment
		(start 430.27219 -199.663812)
		(end 429.63719 -199.663812)
		(width 0.18288)
		(layer "In6.Cu")
		(net "M_G_CPU0_SB_DQS_DN<3>")
	)
	(segment
		(start 420.30269 -198.839074)
		(end 417.429188 -198.839074)
		(width 0.18288)
		(layer "In6.Cu")
		(net "M_G_CPU0_SB_DQS_DN<3>")
	)
	(segment
		(start 389.434578 -217.519758)
		(end 389.434578 -218.038172)
		(width 0.088646)
		(layer "In6.Cu")
		(net "M_G_CPU0_SB_DQS_DN<3>")
	)
	(segment
		(start 424.133518 -200.570592)
		(end 423.447972 -199.885046)
		(width 0.18288)
		(layer "In6.Cu")
		(net "M_G_CPU0_SB_DQS_DN<3>")
	)
	(segment
		(start 432.157632 -199.706738)
		(end 431.59045 -200.27392)
		(width 0.18288)
		(layer "In6.Cu")
		(net "M_G_CPU0_SB_DQS_DN<3>")
	)
	(segment
		(start 416.808666 -199.459596)
		(end 405.512778 -199.459596)
		(width 0.18288)
		(layer "In6.Cu")
		(net "M_G_CPU0_SB_DQS_DN<3>")
	)
	(segment
		(start 426.738796 -199.686672)
		(end 425.854876 -200.570592)
		(width 0.18288)
		(layer "In6.Cu")
		(net "M_G_CPU0_SB_DQS_DN<3>")
	)
	(segment
		(start 425.854876 -200.570592)
		(end 425.31157 -200.570592)
		(width 0.18288)
		(layer "In6.Cu")
		(net "M_G_CPU0_SB_DQS_DN<3>")
	)
	(segment
		(start 420.549324 -198.59244)
		(end 420.30269 -198.839074)
		(width 0.18288)
		(layer "In6.Cu")
		(net "M_G_CPU0_SB_DQS_DN<3>")
	)
	(segment
		(start 421.203882 -198.87057)
		(end 420.925752 -198.59244)
		(width 0.18288)
		(layer "In6.Cu")
		(net "M_G_CPU0_SB_DQS_DN<3>")
	)
	(segment
		(start 389.97128 -216.983056)
		(end 389.434578 -217.519758)
		(width 0.088646)
		(layer "In6.Cu")
		(net "M_G_CPU0_SB_DQS_DN<3>")
	)
	(segment
		(start 425.03344 -200.292462)
		(end 424.660568 -200.292462)
		(width 0.18288)
		(layer "In6.Cu")
		(net "M_G_CPU0_SB_DQS_DN<3>")
	)
	(segment
		(start 397.23441 -209.203798)
		(end 390.152636 -216.285572)
		(width 0.18288)
		(layer "In6.Cu")
		(net "M_G_CPU0_SB_DQS_DN<3>")
	)
	(segment
		(start 389.434578 -218.038172)
		(end 389.345932 -218.126818)
		(width 0.088646)
		(layer "In6.Cu")
		(net "M_G_CPU0_SB_DQS_DN<3>")
	)
	(segment
		(start 389.345932 -218.126818)
		(end 389.183118 -218.126818)
		(width 0.088646)
		(layer "In6.Cu")
		(net "M_G_CPU0_SB_DQS_DN<3>")
	)
	(segment
		(start 424.382438 -200.570592)
		(end 424.133518 -200.570592)
		(width 0.18288)
		(layer "In6.Cu")
		(net "M_G_CPU0_SB_DQS_DN<3>")
	)
	(segment
		(start 431.59045 -200.27392)
		(end 430.882298 -200.27392)
		(width 0.18288)
		(layer "In6.Cu")
		(net "M_G_CPU0_SB_DQS_DN<3>")
	)
	(segment
		(start 388.526782 -218.202764)
		(end 388.51205 -218.194128)
		(width 0.088646)
		(layer "In6.Cu")
		(net "M_G_CPU0_SB_DQS_DN<3>")
	)
	(segment
		(start 434.74894 -199.706738)
		(end 432.157632 -199.706738)
		(width 0.18288)
		(layer "In6.Cu")
		(net "M_G_CPU0_SB_DQS_DN<3>")
	)
	(segment
		(start 389.97128 -216.551256)
		(end 389.97128 -216.983056)
		(width 0.088646)
		(layer "In6.Cu")
		(net "M_G_CPU0_SB_DQS_DN<3>")
	)
	(segment
		(start 430.882298 -200.27392)
		(end 430.27219 -199.663812)
		(width 0.18288)
		(layer "In6.Cu")
		(net "M_G_CPU0_SB_DQS_DN<3>")
	)
	(segment
		(start 435.56809 -200.122282)
		(end 435.164484 -200.122282)
		(width 0.18288)
		(layer "In6.Cu")
		(net "M_G_CPU0_SB_DQS_DN<3>")
	)
	(segment
		(start 427.825154 -199.686672)
		(end 426.738796 -199.686672)
		(width 0.18288)
		(layer "In6.Cu")
		(net "M_G_CPU0_SB_DQS_DN<3>")
	)
	(segment
		(start 424.660568 -200.292462)
		(end 424.382438 -200.570592)
		(width 0.18288)
		(layer "In6.Cu")
		(net "M_G_CPU0_SB_DQS_DN<3>")
	)
	(segment
		(start 390.136126 -216.38641)
		(end 389.97128 -216.551256)
		(width 0.088646)
		(layer "In6.Cu")
		(net "M_G_CPU0_SB_DQS_DN<3>")
	)
	(segment
		(start 420.925752 -198.59244)
		(end 420.549324 -198.59244)
		(width 0.18288)
		(layer "In6.Cu")
		(net "M_G_CPU0_SB_DQS_DN<3>")
	)
	(segment
		(start 390.152636 -216.285572)
		(end 390.136126 -216.302082)
		(width 0.088646)
		(layer "In6.Cu")
		(net "M_G_CPU0_SB_DQS_DN<3>")
	)
	(segment
		(start 385.738624 -218.149424)
		(end 385.894834 -217.878406)
		(width 0.088646)
		(layer "In6.Cu")
		(net "M_G_CPU0_SB_DQS_DN<3>")
	)
	(segment
		(start 387.586982 -218.202764)
		(end 387.57225 -218.194128)
		(width 0.088646)
		(layer "In6.Cu")
		(net "M_G_CPU0_SB_DQS_DN<3>")
	)
	(segment
		(start 429.013874 -200.287128)
		(end 428.42561 -200.287128)
		(width 0.18288)
		(layer "In6.Cu")
		(net "M_G_CPU0_SB_DQS_DN<3>")
	)
	(segment
		(start 428.42561 -200.287128)
		(end 427.825154 -199.686672)
		(width 0.18288)
		(layer "In6.Cu")
		(net "M_G_CPU0_SB_DQS_DN<3>")
	)
	(segment
		(start 417.429188 -198.839074)
		(end 416.808666 -199.459596)
		(width 0.18288)
		(layer "In6.Cu")
		(net "M_G_CPU0_SB_DQS_DN<3>")
	)
	(segment
		(start 422.042336 -198.87057)
		(end 421.203882 -198.87057)
		(width 0.18288)
		(layer "In6.Cu")
		(net "M_G_CPU0_SB_DQS_DN<3>")
	)
	(segment
		(start 425.31157 -200.570592)
		(end 425.03344 -200.292462)
		(width 0.18288)
		(layer "In6.Cu")
		(net "M_G_CPU0_SB_DQS_DN<3>")
	)
	(segment
		(start 405.512778 -199.459596)
		(end 397.23441 -207.737964)
		(width 0.18288)
		(layer "In6.Cu")
		(net "M_G_CPU0_SB_DQS_DN<3>")
	)
	(segment
		(start 435.164484 -200.122282)
		(end 434.74894 -199.706738)
		(width 0.18288)
		(layer "In6.Cu")
		(net "M_G_CPU0_SB_DQS_DN<3>")
	)
	(arc
		(start 388.51205 -218.194128)
		(mid 388.235575 -218.126808)
		(end 387.961378 -218.202764)
		(width 0.088646)
		(layer "In6.Cu")
		(net "M_G_CPU0_SB_DQS_DN<3>")
	)
	(arc
		(start 386.082286 -218.202764)
		(mid 385.923798 -218.251697)
		(end 385.759706 -218.227402)
		(width 0.088646)
		(layer "In6.Cu")
		(net "M_G_CPU0_SB_DQS_DN<3>")
	)
	(arc
		(start 387.57225 -218.194128)
		(mid 387.295775 -218.126808)
		(end 387.021578 -218.202764)
		(width 0.088646)
		(layer "In6.Cu")
		(net "M_G_CPU0_SB_DQS_DN<3>")
	)
	(arc
		(start 387.961378 -218.202764)
		(mid 387.77418 -218.252907)
		(end 387.586982 -218.202764)
		(width 0.088646)
		(layer "In6.Cu")
		(net "M_G_CPU0_SB_DQS_DN<3>")
	)
	(arc
		(start 387.021578 -218.202764)
		(mid 386.83438 -218.252907)
		(end 386.647182 -218.202764)
		(width 0.088646)
		(layer "In6.Cu")
		(net "M_G_CPU0_SB_DQS_DN<3>")
	)
	(arc
		(start 389.183118 -218.126818)
		(mid 389.034021 -218.146915)
		(end 388.89559 -218.205812)
		(width 0.088646)
		(layer "In6.Cu")
		(net "M_G_CPU0_SB_DQS_DN<3>")
	)
	(arc
		(start 386.647182 -218.202764)
		(mid 386.364734 -218.127115)
		(end 386.082286 -218.202764)
		(width 0.088646)
		(layer "In6.Cu")
		(net "M_G_CPU0_SB_DQS_DN<3>")
	)
	(arc
		(start 388.89559 -218.205812)
		(mid 388.710798 -218.252795)
		(end 388.526782 -218.202764)
		(width 0.088646)
		(layer "In6.Cu")
		(net "M_G_CPU0_SB_DQS_DN<3>")
	)
	(segment
		(start 378.37618 -232.528618)
		(end 378.376434 -232.528364)
		(width 0.20066)
		(layer "F.Cu")
		(net "M_G_CPU0_SB_DQS_DN<2>")
	)
	(segment
		(start 442.038994 -209.63636)
		(end 442.363098 -209.63636)
		(width 0.20066)
		(layer "F.Cu")
		(net "M_G_CPU0_SB_DQS_DN<2>")
	)
	(segment
		(start 442.594492 -209.867754)
		(end 442.899546 -209.867754)
		(width 0.20066)
		(layer "F.Cu")
		(net "M_G_CPU0_SB_DQS_DN<2>")
	)
	(segment
		(start 439.430922 -209.912966)
		(end 439.702194 -209.641694)
		(width 0.20066)
		(layer "F.Cu")
		(net "M_G_CPU0_SB_DQS_DN<2>")
	)
	(segment
		(start 436.928514 -209.216752)
		(end 437.477154 -209.216752)
		(width 0.20066)
		(layer "F.Cu")
		(net "M_G_CPU0_SB_DQS_DN<2>")
	)
	(segment
		(start 439.702194 -209.641694)
		(end 439.849768 -209.641694)
		(width 0.20066)
		(layer "F.Cu")
		(net "M_G_CPU0_SB_DQS_DN<2>")
	)
	(segment
		(start 442.03366 -209.641694)
		(end 442.038994 -209.63636)
		(width 0.1016)
		(layer "F.Cu")
		(net "M_G_CPU0_SB_DQS_DN<2>")
	)
	(segment
		(start 439.849768 -209.641694)
		(end 439.854086 -209.641694)
		(width 0.101854)
		(layer "F.Cu")
		(net "M_G_CPU0_SB_DQS_DN<2>")
	)
	(segment
		(start 443.31001 -209.45729)
		(end 443.642496 -209.45729)
		(width 0.20066)
		(layer "F.Cu")
		(net "M_G_CPU0_SB_DQS_DN<2>")
	)
	(segment
		(start 437.75884 -209.498438)
		(end 438.494678 -209.498438)
		(width 0.20066)
		(layer "F.Cu")
		(net "M_G_CPU0_SB_DQS_DN<2>")
	)
	(segment
		(start 443.883034 -209.216752)
		(end 444.472314 -209.216752)
		(width 0.20066)
		(layer "F.Cu")
		(net "M_G_CPU0_SB_DQS_DN<2>")
	)
	(segment
		(start 442.899546 -209.867754)
		(end 443.31001 -209.45729)
		(width 0.20066)
		(layer "F.Cu")
		(net "M_G_CPU0_SB_DQS_DN<2>")
	)
	(segment
		(start 378.37618 -233.064304)
		(end 378.37618 -232.528618)
		(width 0.20066)
		(layer "F.Cu")
		(net "M_G_CPU0_SB_DQS_DN<2>")
	)
	(segment
		(start 438.909206 -209.912966)
		(end 439.430922 -209.912966)
		(width 0.20066)
		(layer "F.Cu")
		(net "M_G_CPU0_SB_DQS_DN<2>")
	)
	(segment
		(start 438.494678 -209.498438)
		(end 438.909206 -209.912966)
		(width 0.20066)
		(layer "F.Cu")
		(net "M_G_CPU0_SB_DQS_DN<2>")
	)
	(segment
		(start 439.854086 -209.641694)
		(end 442.03366 -209.641694)
		(width 0.1016)
		(layer "F.Cu")
		(net "M_G_CPU0_SB_DQS_DN<2>")
	)
	(segment
		(start 442.363098 -209.63636)
		(end 442.594492 -209.867754)
		(width 0.20066)
		(layer "F.Cu")
		(net "M_G_CPU0_SB_DQS_DN<2>")
	)
	(segment
		(start 443.642496 -209.45729)
		(end 443.883034 -209.216752)
		(width 0.20066)
		(layer "F.Cu")
		(net "M_G_CPU0_SB_DQS_DN<2>")
	)
	(segment
		(start 437.477154 -209.216752)
		(end 437.75884 -209.498438)
		(width 0.20066)
		(layer "F.Cu")
		(net "M_G_CPU0_SB_DQS_DN<2>")
	)
	(segment
		(start 435.823614 -209.216752)
		(end 436.928514 -209.216752)
		(width 0.20066)
		(layer "F.Cu")
		(net "M_G_CPU0_SB_DQS_DN<2>")
	)
	(segment
		(start 385.329684 -232.51287)
		(end 385.329684 -232.528364)
		(width 0.088646)
		(layer "In4.Cu")
		(net "M_G_CPU0_SB_DQS_DN<2>")
	)
	(segment
		(start 386.551932 -230.41102)
		(end 386.53974 -230.418132)
		(width 0.088646)
		(layer "In4.Cu")
		(net "M_G_CPU0_SB_DQS_DN<2>")
	)
	(segment
		(start 418.710872 -212.880448)
		(end 418.07892 -212.880448)
		(width 0.18288)
		(layer "In4.Cu")
		(net "M_G_CPU0_SB_DQS_DN<2>")
	)
	(segment
		(start 426.812202 -213.920324)
		(end 426.192188 -213.30031)
		(width 0.18288)
		(layer "In4.Cu")
		(net "M_G_CPU0_SB_DQS_DN<2>")
	)
	(segment
		(start 385.612894 -232.038398)
		(end 385.611878 -232.038906)
		(width 0.088646)
		(layer "In4.Cu")
		(net "M_G_CPU0_SB_DQS_DN<2>")
	)
	(segment
		(start 388.71271 -227.491544)
		(end 388.689342 -227.491544)
		(width 0.088646)
		(layer "In4.Cu")
		(net "M_G_CPU0_SB_DQS_DN<2>")
	)
	(segment
		(start 424.625008 -213.0425)
		(end 424.375072 -213.292436)
		(width 0.18288)
		(layer "In4.Cu")
		(net "M_G_CPU0_SB_DQS_DN<2>")
	)
	(segment
		(start 407.182828 -213.08822)
		(end 407.058368 -212.96376)
		(width 0.18288)
		(layer "In4.Cu")
		(net "M_G_CPU0_SB_DQS_DN<2>")
	)
	(segment
		(start 425.287694 -213.30031)
		(end 425.029884 -213.0425)
		(width 0.18288)
		(layer "In4.Cu")
		(net "M_G_CPU0_SB_DQS_DN<2>")
	)
	(segment
		(start 388.629652 -227.551234)
		(end 388.34441 -227.551234)
		(width 0.088646)
		(layer "In4.Cu")
		(net "M_G_CPU0_SB_DQS_DN<2>")
	)
	(segment
		(start 431.17897 -211.632546)
		(end 430.21885 -211.632546)
		(width 0.18288)
		(layer "In4.Cu")
		(net "M_G_CPU0_SB_DQS_DN<2>")
	)
	(segment
		(start 387.731 -228.164644)
		(end 387.731 -228.87813)
		(width 0.088646)
		(layer "In4.Cu")
		(net "M_G_CPU0_SB_DQS_DN<2>")
	)
	(segment
		(start 406.387808 -213.08822)
		(end 405.841708 -213.08822)
		(width 0.18288)
		(layer "In4.Cu")
		(net "M_G_CPU0_SB_DQS_DN<2>")
	)
	(segment
		(start 434.02123 -209.26171)
		(end 433.63515 -209.64779)
		(width 0.18288)
		(layer "In4.Cu")
		(net "M_G_CPU0_SB_DQS_DN<2>")
	)
	(segment
		(start 391.438384 -227.491544)
		(end 388.71271 -227.491544)
		(width 0.18288)
		(layer "In4.Cu")
		(net "M_G_CPU0_SB_DQS_DN<2>")
	)
	(segment
		(start 379.518164 -232.844086)
		(end 379.503432 -232.852722)
		(width 0.088646)
		(layer "In4.Cu")
		(net "M_G_CPU0_SB_DQS_DN<2>")
	)
	(segment
		(start 435.823614 -209.216752)
		(end 435.532022 -209.508344)
		(width 0.18288)
		(layer "In4.Cu")
		(net "M_G_CPU0_SB_DQS_DN<2>")
	)
	(segment
		(start 429.60163 -212.249766)
		(end 429.425608 -212.249766)
		(width 0.18288)
		(layer "In4.Cu")
		(net "M_G_CPU0_SB_DQS_DN<2>")
	)
	(segment
		(start 408.387804 -213.08822)
		(end 407.182828 -213.08822)
		(width 0.18288)
		(layer "In4.Cu")
		(net "M_G_CPU0_SB_DQS_DN<2>")
	)
	(segment
		(start 427.93666 -213.410292)
		(end 427.426628 -213.920324)
		(width 0.18288)
		(layer "In4.Cu")
		(net "M_G_CPU0_SB_DQS_DN<2>")
	)
	(segment
		(start 378.189236 -232.852722)
		(end 378.180346 -232.847642)
		(width 0.088646)
		(layer "In4.Cu")
		(net "M_G_CPU0_SB_DQS_DN<2>")
	)
	(segment
		(start 429.03902 -212.636354)
		(end 429.03902 -212.812376)
		(width 0.18288)
		(layer "In4.Cu")
		(net "M_G_CPU0_SB_DQS_DN<2>")
	)
	(segment
		(start 378.006356 -232.585768)
		(end 378.06376 -232.528364)
		(width 0.088646)
		(layer "In4.Cu")
		(net "M_G_CPU0_SB_DQS_DN<2>")
	)
	(segment
		(start 387.731 -228.87813)
		(end 386.99567 -229.61346)
		(width 0.088646)
		(layer "In4.Cu")
		(net "M_G_CPU0_SB_DQS_DN<2>")
	)
	(segment
		(start 385.620768 -232.033826)
		(end 385.612894 -232.038398)
		(width 0.088646)
		(layer "In4.Cu")
		(net "M_G_CPU0_SB_DQS_DN<2>")
	)
	(segment
		(start 385.151122 -232.847642)
		(end 385.142232 -232.852722)
		(width 0.088646)
		(layer "In4.Cu")
		(net "M_G_CPU0_SB_DQS_DN<2>")
	)
	(segment
		(start 413.526986 -213.053676)
		(end 412.740856 -213.053676)
		(width 0.18288)
		(layer "In4.Cu")
		(net "M_G_CPU0_SB_DQS_DN<2>")
	)
	(segment
		(start 435.026054 -209.26171)
		(end 434.02123 -209.26171)
		(width 0.18288)
		(layer "In4.Cu")
		(net "M_G_CPU0_SB_DQS_DN<2>")
	)
	(segment
		(start 386.739384 -230.076756)
		(end 386.739384 -230.086662)
		(width 0.088646)
		(layer "In4.Cu")
		(net "M_G_CPU0_SB_DQS_DN<2>")
	)
	(segment
		(start 427.426628 -213.920324)
		(end 426.812202 -213.920324)
		(width 0.18288)
		(layer "In4.Cu")
		(net "M_G_CPU0_SB_DQS_DN<2>")
	)
	(segment
		(start 408.869896 -212.606128)
		(end 408.387804 -213.08822)
		(width 0.18288)
		(layer "In4.Cu")
		(net "M_G_CPU0_SB_DQS_DN<2>")
	)
	(segment
		(start 420.929816 -212.192616)
		(end 420.52494 -212.192616)
		(width 0.18288)
		(layer "In4.Cu")
		(net "M_G_CPU0_SB_DQS_DN<2>")
	)
	(segment
		(start 420.275004 -212.442552)
		(end 419.148768 -212.442552)
		(width 0.18288)
		(layer "In4.Cu")
		(net "M_G_CPU0_SB_DQS_DN<2>")
	)
	(segment
		(start 429.03902 -212.812376)
		(end 428.441104 -213.410292)
		(width 0.18288)
		(layer "In4.Cu")
		(net "M_G_CPU0_SB_DQS_DN<2>")
	)
	(segment
		(start 421.188388 -212.451188)
		(end 420.929816 -212.192616)
		(width 0.18288)
		(layer "In4.Cu")
		(net "M_G_CPU0_SB_DQS_DN<2>")
	)
	(segment
		(start 417.872164 -212.673692)
		(end 416.670998 -212.673692)
		(width 0.18288)
		(layer "In4.Cu")
		(net "M_G_CPU0_SB_DQS_DN<2>")
	)
	(segment
		(start 405.841708 -213.08822)
		(end 391.438384 -227.491544)
		(width 0.18288)
		(layer "In4.Cu")
		(net "M_G_CPU0_SB_DQS_DN<2>")
	)
	(segment
		(start 388.34441 -227.551234)
		(end 387.731 -228.164644)
		(width 0.088646)
		(layer "In4.Cu")
		(net "M_G_CPU0_SB_DQS_DN<2>")
	)
	(segment
		(start 432.114198 -210.697318)
		(end 431.17897 -211.632546)
		(width 0.18288)
		(layer "In4.Cu")
		(net "M_G_CPU0_SB_DQS_DN<2>")
	)
	(segment
		(start 378.578364 -232.844086)
		(end 378.563632 -232.852722)
		(width 0.088646)
		(layer "In4.Cu")
		(net "M_G_CPU0_SB_DQS_DN<2>")
	)
	(segment
		(start 432.585622 -210.697318)
		(end 432.114198 -210.697318)
		(width 0.18288)
		(layer "In4.Cu")
		(net "M_G_CPU0_SB_DQS_DN<2>")
	)
	(segment
		(start 415.275268 -213.113366)
		(end 414.919668 -212.757766)
		(width 0.18288)
		(layer "In4.Cu")
		(net "M_G_CPU0_SB_DQS_DN<2>")
	)
	(segment
		(start 378.06376 -232.528364)
		(end 378.376434 -232.528364)
		(width 0.088646)
		(layer "In4.Cu")
		(net "M_G_CPU0_SB_DQS_DN<2>")
	)
	(segment
		(start 422.934892 -213.292436)
		(end 422.093644 -212.451188)
		(width 0.18288)
		(layer "In4.Cu")
		(net "M_G_CPU0_SB_DQS_DN<2>")
	)
	(segment
		(start 412.293308 -212.606128)
		(end 408.869896 -212.606128)
		(width 0.18288)
		(layer "In4.Cu")
		(net "M_G_CPU0_SB_DQS_DN<2>")
	)
	(segment
		(start 381.008382 -232.852722)
		(end 380.997968 -232.846626)
		(width 0.088646)
		(layer "In4.Cu")
		(net "M_G_CPU0_SB_DQS_DN<2>")
	)
	(segment
		(start 388.689342 -227.491544)
		(end 388.629652 -227.551234)
		(width 0.088646)
		(layer "In4.Cu")
		(net "M_G_CPU0_SB_DQS_DN<2>")
	)
	(segment
		(start 386.560822 -230.40594)
		(end 386.551932 -230.41102)
		(width 0.088646)
		(layer "In4.Cu")
		(net "M_G_CPU0_SB_DQS_DN<2>")
	)
	(segment
		(start 412.740856 -213.053676)
		(end 412.293308 -212.606128)
		(width 0.18288)
		(layer "In4.Cu")
		(net "M_G_CPU0_SB_DQS_DN<2>")
	)
	(segment
		(start 433.072794 -210.210146)
		(end 432.585622 -210.697318)
		(width 0.18288)
		(layer "In4.Cu")
		(net "M_G_CPU0_SB_DQS_DN<2>")
	)
	(segment
		(start 416.670998 -212.673692)
		(end 416.231324 -213.113366)
		(width 0.18288)
		(layer "In4.Cu")
		(net "M_G_CPU0_SB_DQS_DN<2>")
	)
	(segment
		(start 422.093644 -212.451188)
		(end 421.188388 -212.451188)
		(width 0.18288)
		(layer "In4.Cu")
		(net "M_G_CPU0_SB_DQS_DN<2>")
	)
	(segment
		(start 430.21885 -211.632546)
		(end 429.60163 -212.249766)
		(width 0.18288)
		(layer "In4.Cu")
		(net "M_G_CPU0_SB_DQS_DN<2>")
	)
	(segment
		(start 433.459128 -209.64779)
		(end 433.072794 -210.034124)
		(width 0.18288)
		(layer "In4.Cu")
		(net "M_G_CPU0_SB_DQS_DN<2>")
	)
	(segment
		(start 381.948436 -232.852722)
		(end 381.938022 -232.846626)
		(width 0.088646)
		(layer "In4.Cu")
		(net "M_G_CPU0_SB_DQS_DN<2>")
	)
	(segment
		(start 435.272688 -209.508344)
		(end 435.026054 -209.26171)
		(width 0.18288)
		(layer "In4.Cu")
		(net "M_G_CPU0_SB_DQS_DN<2>")
	)
	(segment
		(start 424.375072 -213.292436)
		(end 422.934892 -213.292436)
		(width 0.18288)
		(layer "In4.Cu")
		(net "M_G_CPU0_SB_DQS_DN<2>")
	)
	(segment
		(start 414.919668 -212.757766)
		(end 413.822896 -212.757766)
		(width 0.18288)
		(layer "In4.Cu")
		(net "M_G_CPU0_SB_DQS_DN<2>")
	)
	(segment
		(start 418.07892 -212.880448)
		(end 417.872164 -212.673692)
		(width 0.18288)
		(layer "In4.Cu")
		(net "M_G_CPU0_SB_DQS_DN<2>")
	)
	(segment
		(start 435.532022 -209.508344)
		(end 435.272688 -209.508344)
		(width 0.18288)
		(layer "In4.Cu")
		(net "M_G_CPU0_SB_DQS_DN<2>")
	)
	(segment
		(start 419.148768 -212.442552)
		(end 418.710872 -212.880448)
		(width 0.18288)
		(layer "In4.Cu")
		(net "M_G_CPU0_SB_DQS_DN<2>")
	)
	(segment
		(start 426.192188 -213.30031)
		(end 425.287694 -213.30031)
		(width 0.18288)
		(layer "In4.Cu")
		(net "M_G_CPU0_SB_DQS_DN<2>")
	)
	(segment
		(start 407.058368 -212.96376)
		(end 406.512268 -212.96376)
		(width 0.18288)
		(layer "In4.Cu")
		(net "M_G_CPU0_SB_DQS_DN<2>")
	)
	(segment
		(start 428.441104 -213.410292)
		(end 427.93666 -213.410292)
		(width 0.18288)
		(layer "In4.Cu")
		(net "M_G_CPU0_SB_DQS_DN<2>")
	)
	(segment
		(start 429.425608 -212.249766)
		(end 429.03902 -212.636354)
		(width 0.18288)
		(layer "In4.Cu")
		(net "M_G_CPU0_SB_DQS_DN<2>")
	)
	(segment
		(start 416.231324 -213.113366)
		(end 415.275268 -213.113366)
		(width 0.18288)
		(layer "In4.Cu")
		(net "M_G_CPU0_SB_DQS_DN<2>")
	)
	(segment
		(start 425.029884 -213.0425)
		(end 424.625008 -213.0425)
		(width 0.18288)
		(layer "In4.Cu")
		(net "M_G_CPU0_SB_DQS_DN<2>")
	)
	(segment
		(start 433.63515 -209.64779)
		(end 433.459128 -209.64779)
		(width 0.18288)
		(layer "In4.Cu")
		(net "M_G_CPU0_SB_DQS_DN<2>")
	)
	(segment
		(start 433.072794 -210.034124)
		(end 433.072794 -210.210146)
		(width 0.18288)
		(layer "In4.Cu")
		(net "M_G_CPU0_SB_DQS_DN<2>")
	)
	(segment
		(start 406.512268 -212.96376)
		(end 406.387808 -213.08822)
		(width 0.18288)
		(layer "In4.Cu")
		(net "M_G_CPU0_SB_DQS_DN<2>")
	)
	(segment
		(start 420.52494 -212.192616)
		(end 420.275004 -212.442552)
		(width 0.18288)
		(layer "In4.Cu")
		(net "M_G_CPU0_SB_DQS_DN<2>")
	)
	(segment
		(start 385.79933 -231.700324)
		(end 385.79933 -231.714548)
		(width 0.088646)
		(layer "In4.Cu")
		(net "M_G_CPU0_SB_DQS_DN<2>")
	)
	(segment
		(start 413.822896 -212.757766)
		(end 413.526986 -213.053676)
		(width 0.18288)
		(layer "In4.Cu")
		(net "M_G_CPU0_SB_DQS_DN<2>")
	)
	(segment
		(start 386.090668 -231.219756)
		(end 386.081778 -231.224836)
		(width 0.088646)
		(layer "In4.Cu")
		(net "M_G_CPU0_SB_DQS_DN<2>")
	)
	(arc
		(start 383.262632 -232.852722)
		(mid 383.075434 -232.902865)
		(end 382.888236 -232.852722)
		(width 0.088646)
		(layer "In4.Cu")
		(net "M_G_CPU0_SB_DQS_DN<2>")
	)
	(arc
		(start 386.26923 -230.900478)
		(mid 386.221551 -231.083378)
		(end 386.090668 -231.219756)
		(width 0.088646)
		(layer "In4.Cu")
		(net "M_G_CPU0_SB_DQS_DN<2>")
	)
	(arc
		(start 379.503432 -232.852722)
		(mid 379.316234 -232.902865)
		(end 379.129036 -232.852722)
		(width 0.088646)
		(layer "In4.Cu")
		(net "M_G_CPU0_SB_DQS_DN<2>")
	)
	(arc
		(start 380.068836 -232.852722)
		(mid 379.794637 -232.776887)
		(end 379.518164 -232.844086)
		(width 0.088646)
		(layer "In4.Cu")
		(net "M_G_CPU0_SB_DQS_DN<2>")
	)
	(arc
		(start 383.828036 -232.852722)
		(mid 383.545334 -232.776946)
		(end 383.262632 -232.852722)
		(width 0.088646)
		(layer "In4.Cu")
		(net "M_G_CPU0_SB_DQS_DN<2>")
	)
	(arc
		(start 380.443232 -232.852722)
		(mid 380.256034 -232.902865)
		(end 380.068836 -232.852722)
		(width 0.088646)
		(layer "In4.Cu")
		(net "M_G_CPU0_SB_DQS_DN<2>")
	)
	(arc
		(start 385.611878 -232.038906)
		(mid 385.409055 -232.239137)
		(end 385.329684 -232.51287)
		(width 0.088646)
		(layer "In4.Cu")
		(net "M_G_CPU0_SB_DQS_DN<2>")
	)
	(arc
		(start 382.322832 -232.852722)
		(mid 382.135634 -232.902865)
		(end 381.948436 -232.852722)
		(width 0.088646)
		(layer "In4.Cu")
		(net "M_G_CPU0_SB_DQS_DN<2>")
	)
	(arc
		(start 379.129036 -232.852722)
		(mid 378.854837 -232.776887)
		(end 378.578364 -232.844086)
		(width 0.088646)
		(layer "In4.Cu")
		(net "M_G_CPU0_SB_DQS_DN<2>")
	)
	(arc
		(start 385.142232 -232.852722)
		(mid 384.955034 -232.902865)
		(end 384.767836 -232.852722)
		(width 0.088646)
		(layer "In4.Cu")
		(net "M_G_CPU0_SB_DQS_DN<2>")
	)
	(arc
		(start 378.180346 -232.847642)
		(mid 378.064607 -232.735818)
		(end 378.006356 -232.585768)
		(width 0.088646)
		(layer "In4.Cu")
		(net "M_G_CPU0_SB_DQS_DN<2>")
	)
	(arc
		(start 380.997968 -232.846626)
		(mid 380.71979 -232.776903)
		(end 380.443232 -232.852722)
		(width 0.088646)
		(layer "In4.Cu")
		(net "M_G_CPU0_SB_DQS_DN<2>")
	)
	(arc
		(start 386.739384 -230.086662)
		(mid 386.691705 -230.269562)
		(end 386.560822 -230.40594)
		(width 0.088646)
		(layer "In4.Cu")
		(net "M_G_CPU0_SB_DQS_DN<2>")
	)
	(arc
		(start 384.202432 -232.852722)
		(mid 384.015234 -232.902865)
		(end 383.828036 -232.852722)
		(width 0.088646)
		(layer "In4.Cu")
		(net "M_G_CPU0_SB_DQS_DN<2>")
	)
	(arc
		(start 386.99567 -229.61346)
		(mid 386.809904 -229.81324)
		(end 386.739384 -230.076756)
		(width 0.088646)
		(layer "In4.Cu")
		(net "M_G_CPU0_SB_DQS_DN<2>")
	)
	(arc
		(start 381.382778 -232.852722)
		(mid 381.19558 -232.902865)
		(end 381.008382 -232.852722)
		(width 0.088646)
		(layer "In4.Cu")
		(net "M_G_CPU0_SB_DQS_DN<2>")
	)
	(arc
		(start 378.563632 -232.852722)
		(mid 378.376434 -232.902865)
		(end 378.189236 -232.852722)
		(width 0.088646)
		(layer "In4.Cu")
		(net "M_G_CPU0_SB_DQS_DN<2>")
	)
	(arc
		(start 385.79933 -231.714548)
		(mid 385.751651 -231.897448)
		(end 385.620768 -232.033826)
		(width 0.088646)
		(layer "In4.Cu")
		(net "M_G_CPU0_SB_DQS_DN<2>")
	)
	(arc
		(start 385.329684 -232.528364)
		(mid 385.282005 -232.711264)
		(end 385.151122 -232.847642)
		(width 0.088646)
		(layer "In4.Cu")
		(net "M_G_CPU0_SB_DQS_DN<2>")
	)
	(arc
		(start 384.767836 -232.852722)
		(mid 384.485134 -232.776946)
		(end 384.202432 -232.852722)
		(width 0.088646)
		(layer "In4.Cu")
		(net "M_G_CPU0_SB_DQS_DN<2>")
	)
	(arc
		(start 386.081778 -231.224836)
		(mid 385.878473 -231.425702)
		(end 385.79933 -231.700324)
		(width 0.088646)
		(layer "In4.Cu")
		(net "M_G_CPU0_SB_DQS_DN<2>")
	)
	(arc
		(start 386.53974 -230.418132)
		(mid 386.341512 -230.62398)
		(end 386.26923 -230.900478)
		(width 0.088646)
		(layer "In4.Cu")
		(net "M_G_CPU0_SB_DQS_DN<2>")
	)
	(arc
		(start 382.888236 -232.852722)
		(mid 382.605534 -232.776946)
		(end 382.322832 -232.852722)
		(width 0.088646)
		(layer "In4.Cu")
		(net "M_G_CPU0_SB_DQS_DN<2>")
	)
	(arc
		(start 381.938022 -232.846626)
		(mid 381.65959 -232.77678)
		(end 381.382778 -232.852722)
		(width 0.088646)
		(layer "In4.Cu")
		(net "M_G_CPU0_SB_DQS_DN<2>")
	)
	(segment
		(start 439.854086 -218.991688)
		(end 442.03366 -218.991688)
		(width 0.1016)
		(layer "F.Cu")
		(net "M_G_CPU0_SB_DQS_DN<1>")
	)
	(segment
		(start 435.823614 -218.566746)
		(end 436.928514 -218.566746)
		(width 0.20066)
		(layer "F.Cu")
		(net "M_G_CPU0_SB_DQS_DN<1>")
	)
	(segment
		(start 442.594492 -219.217748)
		(end 442.899546 -219.217748)
		(width 0.20066)
		(layer "F.Cu")
		(net "M_G_CPU0_SB_DQS_DN<1>")
	)
	(segment
		(start 443.31001 -218.807284)
		(end 443.642496 -218.807284)
		(width 0.20066)
		(layer "F.Cu")
		(net "M_G_CPU0_SB_DQS_DN<1>")
	)
	(segment
		(start 442.363098 -218.986354)
		(end 442.594492 -219.217748)
		(width 0.20066)
		(layer "F.Cu")
		(net "M_G_CPU0_SB_DQS_DN<1>")
	)
	(segment
		(start 439.849768 -218.991688)
		(end 439.854086 -218.991688)
		(width 0.101854)
		(layer "F.Cu")
		(net "M_G_CPU0_SB_DQS_DN<1>")
	)
	(segment
		(start 439.702194 -218.991688)
		(end 439.849768 -218.991688)
		(width 0.20066)
		(layer "F.Cu")
		(net "M_G_CPU0_SB_DQS_DN<1>")
	)
	(segment
		(start 443.883034 -218.566746)
		(end 444.472314 -218.566746)
		(width 0.20066)
		(layer "F.Cu")
		(net "M_G_CPU0_SB_DQS_DN<1>")
	)
	(segment
		(start 437.75884 -218.848432)
		(end 438.494678 -218.848432)
		(width 0.20066)
		(layer "F.Cu")
		(net "M_G_CPU0_SB_DQS_DN<1>")
	)
	(segment
		(start 442.899546 -219.217748)
		(end 443.31001 -218.807284)
		(width 0.20066)
		(layer "F.Cu")
		(net "M_G_CPU0_SB_DQS_DN<1>")
	)
	(segment
		(start 438.909206 -219.26296)
		(end 439.430922 -219.26296)
		(width 0.20066)
		(layer "F.Cu")
		(net "M_G_CPU0_SB_DQS_DN<1>")
	)
	(segment
		(start 374.147334 -235.506006)
		(end 374.14708 -235.505752)
		(width 0.20066)
		(layer "F.Cu")
		(net "M_G_CPU0_SB_DQS_DN<1>")
	)
	(segment
		(start 443.642496 -218.807284)
		(end 443.883034 -218.566746)
		(width 0.20066)
		(layer "F.Cu")
		(net "M_G_CPU0_SB_DQS_DN<1>")
	)
	(segment
		(start 442.03366 -218.991688)
		(end 442.038994 -218.986354)
		(width 0.1016)
		(layer "F.Cu")
		(net "M_G_CPU0_SB_DQS_DN<1>")
	)
	(segment
		(start 437.477154 -218.566746)
		(end 437.75884 -218.848432)
		(width 0.20066)
		(layer "F.Cu")
		(net "M_G_CPU0_SB_DQS_DN<1>")
	)
	(segment
		(start 442.038994 -218.986354)
		(end 442.363098 -218.986354)
		(width 0.20066)
		(layer "F.Cu")
		(net "M_G_CPU0_SB_DQS_DN<1>")
	)
	(segment
		(start 439.430922 -219.26296)
		(end 439.702194 -218.991688)
		(width 0.20066)
		(layer "F.Cu")
		(net "M_G_CPU0_SB_DQS_DN<1>")
	)
	(segment
		(start 438.494678 -218.848432)
		(end 438.909206 -219.26296)
		(width 0.20066)
		(layer "F.Cu")
		(net "M_G_CPU0_SB_DQS_DN<1>")
	)
	(segment
		(start 374.14708 -235.505752)
		(end 374.14708 -234.970066)
		(width 0.20066)
		(layer "F.Cu")
		(net "M_G_CPU0_SB_DQS_DN<1>")
	)
	(segment
		(start 436.928514 -218.566746)
		(end 437.477154 -218.566746)
		(width 0.20066)
		(layer "F.Cu")
		(net "M_G_CPU0_SB_DQS_DN<1>")
	)
	(segment
		(start 409.298902 -219.982034)
		(end 408.737308 -219.42044)
		(width 0.18288)
		(layer "In6.Cu")
		(net "M_G_CPU0_SB_DQS_DN<1>")
	)
	(segment
		(start 424.662092 -220.692472)
		(end 424.378882 -220.975682)
		(width 0.18288)
		(layer "In6.Cu")
		(net "M_G_CPU0_SB_DQS_DN<1>")
	)
	(segment
		(start 417.838128 -221.813882)
		(end 415.046414 -220.65742)
		(width 0.18288)
		(layer "In6.Cu")
		(net "M_G_CPU0_SB_DQS_DN<1>")
	)
	(segment
		(start 435.053232 -218.828366)
		(end 434.78831 -218.563444)
		(width 0.18288)
		(layer "In6.Cu")
		(net "M_G_CPU0_SB_DQS_DN<1>")
	)
	(segment
		(start 435.561994 -218.828366)
		(end 435.053232 -218.828366)
		(width 0.18288)
		(layer "In6.Cu")
		(net "M_G_CPU0_SB_DQS_DN<1>")
	)
	(segment
		(start 374.460008 -234.970066)
		(end 374.14708 -234.970066)
		(width 0.088646)
		(layer "In6.Cu")
		(net "M_G_CPU0_SB_DQS_DN<1>")
	)
	(segment
		(start 388.783068 -232.820972)
		(end 388.521448 -232.821226)
		(width 0.18288)
		(layer "In6.Cu")
		(net "M_G_CPU0_SB_DQS_DN<1>")
	)
	(segment
		(start 388.521448 -232.821226)
		(end 387.978142 -232.821226)
		(width 0.18288)
		(layer "In6.Cu")
		(net "M_G_CPU0_SB_DQS_DN<1>")
	)
	(segment
		(start 374.819164 -234.471972)
		(end 374.804432 -234.480608)
		(width 0.088646)
		(layer "In6.Cu")
		(net "M_G_CPU0_SB_DQS_DN<1>")
	)
	(segment
		(start 387.918452 -232.880916)
		(end 387.731762 -232.880916)
		(width 0.088646)
		(layer "In6.Cu")
		(net "M_G_CPU0_SB_DQS_DN<1>")
	)
	(segment
		(start 385.329684 -234.137708)
		(end 385.329684 -234.15625)
		(width 0.088646)
		(layer "In6.Cu")
		(net "M_G_CPU0_SB_DQS_DN<1>")
	)
	(segment
		(start 421.895778 -221.829884)
		(end 421.210994 -221.829884)
		(width 0.18288)
		(layer "In6.Cu")
		(net "M_G_CPU0_SB_DQS_DN<1>")
	)
	(segment
		(start 421.210994 -221.829884)
		(end 420.92372 -221.54261)
		(width 0.18288)
		(layer "In6.Cu")
		(net "M_G_CPU0_SB_DQS_DN<1>")
	)
	(segment
		(start 427.783752 -219.506546)
		(end 427.064932 -220.225366)
		(width 0.18288)
		(layer "In6.Cu")
		(net "M_G_CPU0_SB_DQS_DN<1>")
	)
	(segment
		(start 378.578364 -234.471972)
		(end 378.563632 -234.480608)
		(width 0.088646)
		(layer "In6.Cu")
		(net "M_G_CPU0_SB_DQS_DN<1>")
	)
	(segment
		(start 434.78831 -218.563444)
		(end 431.766218 -218.563444)
		(width 0.18288)
		(layer "In6.Cu")
		(net "M_G_CPU0_SB_DQS_DN<1>")
	)
	(segment
		(start 427.064932 -220.225366)
		(end 426.624496 -220.225366)
		(width 0.18288)
		(layer "In6.Cu")
		(net "M_G_CPU0_SB_DQS_DN<1>")
	)
	(segment
		(start 384.217164 -234.471972)
		(end 384.202432 -234.480608)
		(width 0.088646)
		(layer "In6.Cu")
		(net "M_G_CPU0_SB_DQS_DN<1>")
	)
	(segment
		(start 420.27856 -221.813882)
		(end 417.838128 -221.813882)
		(width 0.18288)
		(layer "In6.Cu")
		(net "M_G_CPU0_SB_DQS_DN<1>")
	)
	(segment
		(start 424.378882 -220.975682)
		(end 422.74998 -220.975682)
		(width 0.18288)
		(layer "In6.Cu")
		(net "M_G_CPU0_SB_DQS_DN<1>")
	)
	(segment
		(start 413.062166 -218.673426)
		(end 411.67939 -218.673426)
		(width 0.18288)
		(layer "In6.Cu")
		(net "M_G_CPU0_SB_DQS_DN<1>")
	)
	(segment
		(start 425.270168 -220.954092)
		(end 425.008548 -220.692472)
		(width 0.18288)
		(layer "In6.Cu")
		(net "M_G_CPU0_SB_DQS_DN<1>")
	)
	(segment
		(start 408.737308 -219.42044)
		(end 404.25624 -219.42044)
		(width 0.18288)
		(layer "In6.Cu")
		(net "M_G_CPU0_SB_DQS_DN<1>")
	)
	(segment
		(start 376.694446 -234.474512)
		(end 376.684032 -234.480608)
		(width 0.088646)
		(layer "In6.Cu")
		(net "M_G_CPU0_SB_DQS_DN<1>")
	)
	(segment
		(start 404.25624 -219.42044)
		(end 390.855708 -232.820972)
		(width 0.18288)
		(layer "In6.Cu")
		(net "M_G_CPU0_SB_DQS_DN<1>")
	)
	(segment
		(start 387.978142 -232.821226)
		(end 387.918452 -232.880916)
		(width 0.088646)
		(layer "In6.Cu")
		(net "M_G_CPU0_SB_DQS_DN<1>")
	)
	(segment
		(start 420.549832 -221.54261)
		(end 420.27856 -221.813882)
		(width 0.18288)
		(layer "In6.Cu")
		(net "M_G_CPU0_SB_DQS_DN<1>")
	)
	(segment
		(start 387.731762 -232.880916)
		(end 387.433312 -233.179366)
		(width 0.088646)
		(layer "In6.Cu")
		(net "M_G_CPU0_SB_DQS_DN<1>")
	)
	(segment
		(start 435.823614 -218.566746)
		(end 435.561994 -218.828366)
		(width 0.18288)
		(layer "In6.Cu")
		(net "M_G_CPU0_SB_DQS_DN<1>")
	)
	(segment
		(start 430.823116 -219.506546)
		(end 427.783752 -219.506546)
		(width 0.18288)
		(layer "In6.Cu")
		(net "M_G_CPU0_SB_DQS_DN<1>")
	)
	(segment
		(start 385.151122 -234.475528)
		(end 385.143756 -234.479846)
		(width 0.088646)
		(layer "In6.Cu")
		(net "M_G_CPU0_SB_DQS_DN<1>")
	)
	(segment
		(start 375.758964 -234.471972)
		(end 375.744232 -234.480608)
		(width 0.088646)
		(layer "In6.Cu")
		(net "M_G_CPU0_SB_DQS_DN<1>")
	)
	(segment
		(start 415.046414 -220.65742)
		(end 413.062166 -218.673426)
		(width 0.18288)
		(layer "In6.Cu")
		(net "M_G_CPU0_SB_DQS_DN<1>")
	)
	(segment
		(start 420.92372 -221.54261)
		(end 420.549832 -221.54261)
		(width 0.18288)
		(layer "In6.Cu")
		(net "M_G_CPU0_SB_DQS_DN<1>")
	)
	(segment
		(start 431.766218 -218.563444)
		(end 430.823116 -219.506546)
		(width 0.18288)
		(layer "In6.Cu")
		(net "M_G_CPU0_SB_DQS_DN<1>")
	)
	(segment
		(start 374.52554 -234.904534)
		(end 374.460008 -234.970066)
		(width 0.088646)
		(layer "In6.Cu")
		(net "M_G_CPU0_SB_DQS_DN<1>")
	)
	(segment
		(start 422.74998 -220.975682)
		(end 421.895778 -221.829884)
		(width 0.18288)
		(layer "In6.Cu")
		(net "M_G_CPU0_SB_DQS_DN<1>")
	)
	(segment
		(start 374.80367 -234.481116)
		(end 374.798336 -234.484164)
		(width 0.088646)
		(layer "In6.Cu")
		(net "M_G_CPU0_SB_DQS_DN<1>")
	)
	(segment
		(start 410.370782 -219.982034)
		(end 409.298902 -219.982034)
		(width 0.18288)
		(layer "In6.Cu")
		(net "M_G_CPU0_SB_DQS_DN<1>")
	)
	(segment
		(start 380.457964 -234.471972)
		(end 380.443232 -234.480608)
		(width 0.088646)
		(layer "In6.Cu")
		(net "M_G_CPU0_SB_DQS_DN<1>")
	)
	(segment
		(start 385.143756 -234.479846)
		(end 385.142232 -234.480608)
		(width 0.088646)
		(layer "In6.Cu")
		(net "M_G_CPU0_SB_DQS_DN<1>")
	)
	(segment
		(start 411.67939 -218.673426)
		(end 410.370782 -219.982034)
		(width 0.18288)
		(layer "In6.Cu")
		(net "M_G_CPU0_SB_DQS_DN<1>")
	)
	(segment
		(start 425.008548 -220.692472)
		(end 424.662092 -220.692472)
		(width 0.18288)
		(layer "In6.Cu")
		(net "M_G_CPU0_SB_DQS_DN<1>")
	)
	(segment
		(start 390.855708 -232.820972)
		(end 388.783068 -232.820972)
		(width 0.18288)
		(layer "In6.Cu")
		(net "M_G_CPU0_SB_DQS_DN<1>")
	)
	(segment
		(start 426.624496 -220.225366)
		(end 425.89577 -220.954092)
		(width 0.18288)
		(layer "In6.Cu")
		(net "M_G_CPU0_SB_DQS_DN<1>")
	)
	(segment
		(start 374.804432 -234.480608)
		(end 374.80367 -234.481116)
		(width 0.088646)
		(layer "In6.Cu")
		(net "M_G_CPU0_SB_DQS_DN<1>")
	)
	(segment
		(start 377.633992 -234.474512)
		(end 377.623578 -234.480608)
		(width 0.088646)
		(layer "In6.Cu")
		(net "M_G_CPU0_SB_DQS_DN<1>")
	)
	(segment
		(start 425.89577 -220.954092)
		(end 425.270168 -220.954092)
		(width 0.18288)
		(layer "In6.Cu")
		(net "M_G_CPU0_SB_DQS_DN<1>")
	)
	(arc
		(start 380.068836 -234.480608)
		(mid 379.786134 -234.404832)
		(end 379.503432 -234.480608)
		(width 0.088646)
		(layer "In6.Cu")
		(net "M_G_CPU0_SB_DQS_DN<1>")
	)
	(arc
		(start 383.828036 -234.480608)
		(mid 383.545334 -234.404832)
		(end 383.262632 -234.480608)
		(width 0.088646)
		(layer "In6.Cu")
		(net "M_G_CPU0_SB_DQS_DN<1>")
	)
	(arc
		(start 380.443232 -234.480608)
		(mid 380.256034 -234.530751)
		(end 380.068836 -234.480608)
		(width 0.088646)
		(layer "In6.Cu")
		(net "M_G_CPU0_SB_DQS_DN<1>")
	)
	(arc
		(start 374.798336 -234.484164)
		(mid 374.612813 -234.662465)
		(end 374.52554 -234.904534)
		(width 0.088646)
		(layer "In6.Cu")
		(net "M_G_CPU0_SB_DQS_DN<1>")
	)
	(arc
		(start 382.322832 -234.480608)
		(mid 382.135634 -234.530751)
		(end 381.948436 -234.480608)
		(width 0.088646)
		(layer "In6.Cu")
		(net "M_G_CPU0_SB_DQS_DN<1>")
	)
	(arc
		(start 384.767836 -234.480608)
		(mid 384.493637 -234.404773)
		(end 384.217164 -234.471972)
		(width 0.088646)
		(layer "In6.Cu")
		(net "M_G_CPU0_SB_DQS_DN<1>")
	)
	(arc
		(start 386.882386 -233.591862)
		(mid 386.704003 -233.612987)
		(end 386.535676 -233.675682)
		(width 0.088646)
		(layer "In6.Cu")
		(net "M_G_CPU0_SB_DQS_DN<1>")
	)
	(arc
		(start 377.249182 -234.480608)
		(mid 376.972623 -234.404865)
		(end 376.694446 -234.474512)
		(width 0.088646)
		(layer "In6.Cu")
		(net "M_G_CPU0_SB_DQS_DN<1>")
	)
	(arc
		(start 385.612132 -233.666538)
		(mid 385.409846 -233.865519)
		(end 385.329684 -234.137708)
		(width 0.088646)
		(layer "In6.Cu")
		(net "M_G_CPU0_SB_DQS_DN<1>")
	)
	(arc
		(start 377.623578 -234.480608)
		(mid 377.43638 -234.530751)
		(end 377.249182 -234.480608)
		(width 0.088646)
		(layer "In6.Cu")
		(net "M_G_CPU0_SB_DQS_DN<1>")
	)
	(arc
		(start 376.684032 -234.480608)
		(mid 376.496834 -234.530751)
		(end 376.309636 -234.480608)
		(width 0.088646)
		(layer "In6.Cu")
		(net "M_G_CPU0_SB_DQS_DN<1>")
	)
	(arc
		(start 381.008636 -234.480608)
		(mid 380.734437 -234.404773)
		(end 380.457964 -234.471972)
		(width 0.088646)
		(layer "In6.Cu")
		(net "M_G_CPU0_SB_DQS_DN<1>")
	)
	(arc
		(start 382.888236 -234.480608)
		(mid 382.605534 -234.404832)
		(end 382.322832 -234.480608)
		(width 0.088646)
		(layer "In6.Cu")
		(net "M_G_CPU0_SB_DQS_DN<1>")
	)
	(arc
		(start 386.177536 -233.666538)
		(mid 385.894834 -233.590796)
		(end 385.612132 -233.666538)
		(width 0.088646)
		(layer "In6.Cu")
		(net "M_G_CPU0_SB_DQS_DN<1>")
	)
	(arc
		(start 385.329684 -234.15625)
		(mid 385.282005 -234.33915)
		(end 385.151122 -234.475528)
		(width 0.088646)
		(layer "In6.Cu")
		(net "M_G_CPU0_SB_DQS_DN<1>")
	)
	(arc
		(start 385.142232 -234.480608)
		(mid 384.955034 -234.530751)
		(end 384.767836 -234.480608)
		(width 0.088646)
		(layer "In6.Cu")
		(net "M_G_CPU0_SB_DQS_DN<1>")
	)
	(arc
		(start 375.369836 -234.480608)
		(mid 375.095637 -234.404773)
		(end 374.819164 -234.471972)
		(width 0.088646)
		(layer "In6.Cu")
		(net "M_G_CPU0_SB_DQS_DN<1>")
	)
	(arc
		(start 381.948436 -234.480608)
		(mid 381.665734 -234.404832)
		(end 381.383032 -234.480608)
		(width 0.088646)
		(layer "In6.Cu")
		(net "M_G_CPU0_SB_DQS_DN<1>")
	)
	(arc
		(start 378.563632 -234.480608)
		(mid 378.376434 -234.530751)
		(end 378.189236 -234.480608)
		(width 0.088646)
		(layer "In6.Cu")
		(net "M_G_CPU0_SB_DQS_DN<1>")
	)
	(arc
		(start 379.129036 -234.480608)
		(mid 378.854837 -234.404773)
		(end 378.578364 -234.471972)
		(width 0.088646)
		(layer "In6.Cu")
		(net "M_G_CPU0_SB_DQS_DN<1>")
	)
	(arc
		(start 378.189236 -234.480608)
		(mid 377.912423 -234.404738)
		(end 377.633992 -234.474512)
		(width 0.088646)
		(layer "In6.Cu")
		(net "M_G_CPU0_SB_DQS_DN<1>")
	)
	(arc
		(start 384.202432 -234.480608)
		(mid 384.015234 -234.530751)
		(end 383.828036 -234.480608)
		(width 0.088646)
		(layer "In6.Cu")
		(net "M_G_CPU0_SB_DQS_DN<1>")
	)
	(arc
		(start 376.309636 -234.480608)
		(mid 376.035437 -234.404773)
		(end 375.758964 -234.471972)
		(width 0.088646)
		(layer "In6.Cu")
		(net "M_G_CPU0_SB_DQS_DN<1>")
	)
	(arc
		(start 379.503432 -234.480608)
		(mid 379.316234 -234.530751)
		(end 379.129036 -234.480608)
		(width 0.088646)
		(layer "In6.Cu")
		(net "M_G_CPU0_SB_DQS_DN<1>")
	)
	(arc
		(start 381.383032 -234.480608)
		(mid 381.195834 -234.530751)
		(end 381.008636 -234.480608)
		(width 0.088646)
		(layer "In6.Cu")
		(net "M_G_CPU0_SB_DQS_DN<1>")
	)
	(arc
		(start 375.744232 -234.480608)
		(mid 375.557034 -234.530751)
		(end 375.369836 -234.480608)
		(width 0.088646)
		(layer "In6.Cu")
		(net "M_G_CPU0_SB_DQS_DN<1>")
	)
	(arc
		(start 387.31698 -233.334814)
		(mid 387.13501 -233.523089)
		(end 386.882386 -233.591862)
		(width 0.088646)
		(layer "In6.Cu")
		(net "M_G_CPU0_SB_DQS_DN<1>")
	)
	(arc
		(start 383.262632 -234.480608)
		(mid 383.075434 -234.530751)
		(end 382.888236 -234.480608)
		(width 0.088646)
		(layer "In6.Cu")
		(net "M_G_CPU0_SB_DQS_DN<1>")
	)
	(arc
		(start 386.535676 -233.675682)
		(mid 386.35544 -233.716702)
		(end 386.177536 -233.666538)
		(width 0.088646)
		(layer "In6.Cu")
		(net "M_G_CPU0_SB_DQS_DN<1>")
	)
	(arc
		(start 387.433312 -233.179366)
		(mid 387.369596 -233.252938)
		(end 387.31698 -233.334814)
		(width 0.088646)
		(layer "In6.Cu")
		(net "M_G_CPU0_SB_DQS_DN<1>")
	)
	(segment
		(start 435.823614 -227.91674)
		(end 436.928514 -227.91674)
		(width 0.20066)
		(layer "F.Cu")
		(net "M_G_CPU0_SB_DQS_DN<0>")
	)
	(segment
		(start 442.038994 -228.336348)
		(end 442.363098 -228.336348)
		(width 0.20066)
		(layer "F.Cu")
		(net "M_G_CPU0_SB_DQS_DN<0>")
	)
	(segment
		(start 442.899546 -228.567742)
		(end 443.31001 -228.157278)
		(width 0.20066)
		(layer "F.Cu")
		(net "M_G_CPU0_SB_DQS_DN<0>")
	)
	(segment
		(start 374.14708 -240.388902)
		(end 374.14708 -239.853216)
		(width 0.20066)
		(layer "F.Cu")
		(net "M_G_CPU0_SB_DQS_DN<0>")
	)
	(segment
		(start 442.363098 -228.336348)
		(end 442.594492 -228.567742)
		(width 0.20066)
		(layer "F.Cu")
		(net "M_G_CPU0_SB_DQS_DN<0>")
	)
	(segment
		(start 442.594492 -228.567742)
		(end 442.899546 -228.567742)
		(width 0.20066)
		(layer "F.Cu")
		(net "M_G_CPU0_SB_DQS_DN<0>")
	)
	(segment
		(start 443.31001 -228.157278)
		(end 443.642496 -228.157278)
		(width 0.20066)
		(layer "F.Cu")
		(net "M_G_CPU0_SB_DQS_DN<0>")
	)
	(segment
		(start 438.494678 -228.198426)
		(end 438.909206 -228.612954)
		(width 0.20066)
		(layer "F.Cu")
		(net "M_G_CPU0_SB_DQS_DN<0>")
	)
	(segment
		(start 439.854086 -228.341682)
		(end 442.03366 -228.341682)
		(width 0.1016)
		(layer "F.Cu")
		(net "M_G_CPU0_SB_DQS_DN<0>")
	)
	(segment
		(start 439.430922 -228.612954)
		(end 439.702194 -228.341682)
		(width 0.20066)
		(layer "F.Cu")
		(net "M_G_CPU0_SB_DQS_DN<0>")
	)
	(segment
		(start 443.642496 -228.157278)
		(end 443.883034 -227.91674)
		(width 0.20066)
		(layer "F.Cu")
		(net "M_G_CPU0_SB_DQS_DN<0>")
	)
	(segment
		(start 437.75884 -228.198426)
		(end 438.494678 -228.198426)
		(width 0.20066)
		(layer "F.Cu")
		(net "M_G_CPU0_SB_DQS_DN<0>")
	)
	(segment
		(start 439.702194 -228.341682)
		(end 439.849768 -228.341682)
		(width 0.20066)
		(layer "F.Cu")
		(net "M_G_CPU0_SB_DQS_DN<0>")
	)
	(segment
		(start 438.909206 -228.612954)
		(end 439.430922 -228.612954)
		(width 0.20066)
		(layer "F.Cu")
		(net "M_G_CPU0_SB_DQS_DN<0>")
	)
	(segment
		(start 436.928514 -227.91674)
		(end 437.477154 -227.91674)
		(width 0.20066)
		(layer "F.Cu")
		(net "M_G_CPU0_SB_DQS_DN<0>")
	)
	(segment
		(start 443.883034 -227.91674)
		(end 444.472314 -227.91674)
		(width 0.20066)
		(layer "F.Cu")
		(net "M_G_CPU0_SB_DQS_DN<0>")
	)
	(segment
		(start 374.147334 -240.389156)
		(end 374.14708 -240.388902)
		(width 0.20066)
		(layer "F.Cu")
		(net "M_G_CPU0_SB_DQS_DN<0>")
	)
	(segment
		(start 439.849768 -228.341682)
		(end 439.854086 -228.341682)
		(width 0.101854)
		(layer "F.Cu")
		(net "M_G_CPU0_SB_DQS_DN<0>")
	)
	(segment
		(start 442.03366 -228.341682)
		(end 442.038994 -228.336348)
		(width 0.1016)
		(layer "F.Cu")
		(net "M_G_CPU0_SB_DQS_DN<0>")
	)
	(segment
		(start 437.477154 -227.91674)
		(end 437.75884 -228.198426)
		(width 0.20066)
		(layer "F.Cu")
		(net "M_G_CPU0_SB_DQS_DN<0>")
	)
	(segment
		(start 432.797204 -229.496366)
		(end 432.193954 -229.496366)
		(width 0.18288)
		(layer "In6.Cu")
		(net "M_G_CPU0_SB_DQS_DN<0>")
	)
	(segment
		(start 424.362626 -233.72064)
		(end 422.271698 -233.72064)
		(width 0.18288)
		(layer "In6.Cu")
		(net "M_G_CPU0_SB_DQS_DN<0>")
	)
	(segment
		(start 435.057804 -228.030278)
		(end 434.263292 -228.030278)
		(width 0.18288)
		(layer "In6.Cu")
		(net "M_G_CPU0_SB_DQS_DN<0>")
	)
	(segment
		(start 435.823614 -227.91674)
		(end 435.547516 -228.192838)
		(width 0.18288)
		(layer "In6.Cu")
		(net "M_G_CPU0_SB_DQS_DN<0>")
	)
	(segment
		(start 384.297682 -240.177574)
		(end 384.297428 -240.177574)
		(width 0.088646)
		(layer "In6.Cu")
		(net "M_G_CPU0_SB_DQS_DN<0>")
	)
	(segment
		(start 381.478536 -240.177574)
		(end 381.468122 -240.171478)
		(width 0.088646)
		(layer "In6.Cu")
		(net "M_G_CPU0_SB_DQS_DN<0>")
	)
	(segment
		(start 416.188906 -233.641646)
		(end 412.773114 -233.641646)
		(width 0.18288)
		(layer "In6.Cu")
		(net "M_G_CPU0_SB_DQS_DN<0>")
	)
	(segment
		(start 430.977294 -230.713026)
		(end 430.977294 -231.452674)
		(width 0.18288)
		(layer "In6.Cu")
		(net "M_G_CPU0_SB_DQS_DN<0>")
	)
	(segment
		(start 374.659652 -239.853216)
		(end 374.14708 -239.853216)
		(width 0.088646)
		(layer "In6.Cu")
		(net "M_G_CPU0_SB_DQS_DN<0>")
	)
	(segment
		(start 382.792986 -240.177828)
		(end 382.792478 -240.177574)
		(width 0.088646)
		(layer "In6.Cu")
		(net "M_G_CPU0_SB_DQS_DN<0>")
	)
	(segment
		(start 379.598936 -240.177574)
		(end 379.588522 -240.171478)
		(width 0.088646)
		(layer "In6.Cu")
		(net "M_G_CPU0_SB_DQS_DN<0>")
	)
	(segment
		(start 422.271698 -233.72064)
		(end 421.435022 -234.557316)
		(width 0.18288)
		(layer "In6.Cu")
		(net "M_G_CPU0_SB_DQS_DN<0>")
	)
	(segment
		(start 421.435022 -234.557316)
		(end 421.175942 -234.557316)
		(width 0.18288)
		(layer "In6.Cu")
		(net "M_G_CPU0_SB_DQS_DN<0>")
	)
	(segment
		(start 425.029376 -233.44251)
		(end 424.640756 -233.44251)
		(width 0.18288)
		(layer "In6.Cu")
		(net "M_G_CPU0_SB_DQS_DN<0>")
	)
	(segment
		(start 412.158434 -233.026966)
		(end 411.223206 -233.026966)
		(width 0.18288)
		(layer "In6.Cu")
		(net "M_G_CPU0_SB_DQS_DN<0>")
	)
	(segment
		(start 374.719596 -239.777524)
		(end 374.716802 -239.796066)
		(width 0.088646)
		(layer "In6.Cu")
		(net "M_G_CPU0_SB_DQS_DN<0>")
	)
	(segment
		(start 387.117082 -240.177574)
		(end 387.10235 -240.168938)
		(width 0.088646)
		(layer "In6.Cu")
		(net "M_G_CPU0_SB_DQS_DN<0>")
	)
	(segment
		(start 387.526784 -240.228374)
		(end 387.30428 -240.228374)
		(width 0.088646)
		(layer "In6.Cu")
		(net "M_G_CPU0_SB_DQS_DN<0>")
	)
	(segment
		(start 386.177282 -240.177574)
		(end 386.16255 -240.168938)
		(width 0.088646)
		(layer "In6.Cu")
		(net "M_G_CPU0_SB_DQS_DN<0>")
	)
	(segment
		(start 375.282968 -239.533938)
		(end 375.274078 -239.528858)
		(width 0.088646)
		(layer "In6.Cu")
		(net "M_G_CPU0_SB_DQS_DN<0>")
	)
	(segment
		(start 377.719082 -240.177574)
		(end 377.70435 -240.168938)
		(width 0.088646)
		(layer "In6.Cu")
		(net "M_G_CPU0_SB_DQS_DN<0>")
	)
	(segment
		(start 409.508198 -234.294426)
		(end 407.81986 -233.958638)
		(width 0.18288)
		(layer "In6.Cu")
		(net "M_G_CPU0_SB_DQS_DN<0>")
	)
	(segment
		(start 421.175942 -234.557316)
		(end 420.91102 -234.292394)
		(width 0.18288)
		(layer "In6.Cu")
		(net "M_G_CPU0_SB_DQS_DN<0>")
	)
	(segment
		(start 375.59869 -239.799876)
		(end 375.493788 -239.694974)
		(width 0.088646)
		(layer "In6.Cu")
		(net "M_G_CPU0_SB_DQS_DN<0>")
	)
	(segment
		(start 420.299896 -234.55503)
		(end 417.10229 -234.55503)
		(width 0.18288)
		(layer "In6.Cu")
		(net "M_G_CPU0_SB_DQS_DN<0>")
	)
	(segment
		(start 430.977294 -231.452674)
		(end 428.821342 -233.608626)
		(width 0.18288)
		(layer "In6.Cu")
		(net "M_G_CPU0_SB_DQS_DN<0>")
	)
	(segment
		(start 435.220364 -228.192838)
		(end 435.057804 -228.030278)
		(width 0.18288)
		(layer "In6.Cu")
		(net "M_G_CPU0_SB_DQS_DN<0>")
	)
	(segment
		(start 425.297346 -233.71048)
		(end 425.029376 -233.44251)
		(width 0.18288)
		(layer "In6.Cu")
		(net "M_G_CPU0_SB_DQS_DN<0>")
	)
	(segment
		(start 394.90142 -239.74679)
		(end 388.359396 -239.74679)
		(width 0.18288)
		(layer "In6.Cu")
		(net "M_G_CPU0_SB_DQS_DN<0>")
	)
	(segment
		(start 409.955746 -234.294426)
		(end 409.508198 -234.294426)
		(width 0.18288)
		(layer "In6.Cu")
		(net "M_G_CPU0_SB_DQS_DN<0>")
	)
	(segment
		(start 385.237482 -240.177574)
		(end 385.22275 -240.168938)
		(width 0.088646)
		(layer "In6.Cu")
		(net "M_G_CPU0_SB_DQS_DN<0>")
	)
	(segment
		(start 374.899682 -239.528858)
		(end 374.898158 -239.52962)
		(width 0.088646)
		(layer "In6.Cu")
		(net "M_G_CPU0_SB_DQS_DN<0>")
	)
	(segment
		(start 378.658882 -240.177574)
		(end 378.64415 -240.168938)
		(width 0.088646)
		(layer "In6.Cu")
		(net "M_G_CPU0_SB_DQS_DN<0>")
	)
	(segment
		(start 388.359396 -239.74679)
		(end 388.299706 -239.80648)
		(width 0.088646)
		(layer "In6.Cu")
		(net "M_G_CPU0_SB_DQS_DN<0>")
	)
	(segment
		(start 412.773114 -233.641646)
		(end 412.158434 -233.026966)
		(width 0.18288)
		(layer "In6.Cu")
		(net "M_G_CPU0_SB_DQS_DN<0>")
	)
	(segment
		(start 417.10229 -234.55503)
		(end 416.188906 -233.641646)
		(width 0.18288)
		(layer "In6.Cu")
		(net "M_G_CPU0_SB_DQS_DN<0>")
	)
	(segment
		(start 382.418082 -240.177574)
		(end 382.407668 -240.171478)
		(width 0.088646)
		(layer "In6.Cu")
		(net "M_G_CPU0_SB_DQS_DN<0>")
	)
	(segment
		(start 374.898158 -239.52962)
		(end 374.87479 -239.543844)
		(width 0.088646)
		(layer "In6.Cu")
		(net "M_G_CPU0_SB_DQS_DN<0>")
	)
	(segment
		(start 426.608494 -233.049826)
		(end 425.94784 -233.71048)
		(width 0.18288)
		(layer "In6.Cu")
		(net "M_G_CPU0_SB_DQS_DN<0>")
	)
	(segment
		(start 387.948678 -239.80648)
		(end 387.526784 -240.228374)
		(width 0.088646)
		(layer "In6.Cu")
		(net "M_G_CPU0_SB_DQS_DN<0>")
	)
	(segment
		(start 428.821342 -233.608626)
		(end 428.071534 -233.608626)
		(width 0.18288)
		(layer "In6.Cu")
		(net "M_G_CPU0_SB_DQS_DN<0>")
	)
	(segment
		(start 379.983746 -240.171478)
		(end 379.973332 -240.177574)
		(width 0.088646)
		(layer "In6.Cu")
		(net "M_G_CPU0_SB_DQS_DN<0>")
	)
	(segment
		(start 434.263292 -228.030278)
		(end 432.797204 -229.496366)
		(width 0.18288)
		(layer "In6.Cu")
		(net "M_G_CPU0_SB_DQS_DN<0>")
	)
	(segment
		(start 411.223206 -233.026966)
		(end 409.955746 -234.294426)
		(width 0.18288)
		(layer "In6.Cu")
		(net "M_G_CPU0_SB_DQS_DN<0>")
	)
	(segment
		(start 400.689572 -233.958638)
		(end 394.90142 -239.74679)
		(width 0.18288)
		(layer "In6.Cu")
		(net "M_G_CPU0_SB_DQS_DN<0>")
	)
	(segment
		(start 388.299706 -239.80648)
		(end 387.948678 -239.80648)
		(width 0.088646)
		(layer "In6.Cu")
		(net "M_G_CPU0_SB_DQS_DN<0>")
	)
	(segment
		(start 427.512734 -233.049826)
		(end 426.608494 -233.049826)
		(width 0.18288)
		(layer "In6.Cu")
		(net "M_G_CPU0_SB_DQS_DN<0>")
	)
	(segment
		(start 420.562532 -234.292394)
		(end 420.299896 -234.55503)
		(width 0.18288)
		(layer "In6.Cu")
		(net "M_G_CPU0_SB_DQS_DN<0>")
	)
	(segment
		(start 376.779282 -240.177574)
		(end 376.76455 -240.168938)
		(width 0.088646)
		(layer "In6.Cu")
		(net "M_G_CPU0_SB_DQS_DN<0>")
	)
	(segment
		(start 374.716802 -239.796066)
		(end 374.659652 -239.853216)
		(width 0.088646)
		(layer "In6.Cu")
		(net "M_G_CPU0_SB_DQS_DN<0>")
	)
	(segment
		(start 407.81986 -233.958638)
		(end 400.689572 -233.958638)
		(width 0.18288)
		(layer "In6.Cu")
		(net "M_G_CPU0_SB_DQS_DN<0>")
	)
	(segment
		(start 428.071534 -233.608626)
		(end 427.512734 -233.049826)
		(width 0.18288)
		(layer "In6.Cu")
		(net "M_G_CPU0_SB_DQS_DN<0>")
	)
	(segment
		(start 420.91102 -234.292394)
		(end 420.562532 -234.292394)
		(width 0.18288)
		(layer "In6.Cu")
		(net "M_G_CPU0_SB_DQS_DN<0>")
	)
	(segment
		(start 435.547516 -228.192838)
		(end 435.220364 -228.192838)
		(width 0.18288)
		(layer "In6.Cu")
		(net "M_G_CPU0_SB_DQS_DN<0>")
	)
	(segment
		(start 425.94784 -233.71048)
		(end 425.297346 -233.71048)
		(width 0.18288)
		(layer "In6.Cu")
		(net "M_G_CPU0_SB_DQS_DN<0>")
	)
	(segment
		(start 432.193954 -229.496366)
		(end 430.977294 -230.713026)
		(width 0.18288)
		(layer "In6.Cu")
		(net "M_G_CPU0_SB_DQS_DN<0>")
	)
	(segment
		(start 424.640756 -233.44251)
		(end 424.362626 -233.72064)
		(width 0.18288)
		(layer "In6.Cu")
		(net "M_G_CPU0_SB_DQS_DN<0>")
	)
	(arc
		(start 382.792478 -240.177574)
		(mid 382.60528 -240.227717)
		(end 382.418082 -240.177574)
		(width 0.088646)
		(layer "In6.Cu")
		(net "M_G_CPU0_SB_DQS_DN<0>")
	)
	(arc
		(start 378.093478 -240.177574)
		(mid 377.90628 -240.227717)
		(end 377.719082 -240.177574)
		(width 0.088646)
		(layer "In6.Cu")
		(net "M_G_CPU0_SB_DQS_DN<0>")
	)
	(arc
		(start 379.588522 -240.171478)
		(mid 379.31009 -240.101664)
		(end 379.033278 -240.177574)
		(width 0.088646)
		(layer "In6.Cu")
		(net "M_G_CPU0_SB_DQS_DN<0>")
	)
	(arc
		(start 387.30428 -240.228374)
		(mid 387.207341 -240.215284)
		(end 387.117082 -240.177574)
		(width 0.088646)
		(layer "In6.Cu")
		(net "M_G_CPU0_SB_DQS_DN<0>")
	)
	(arc
		(start 385.22275 -240.168938)
		(mid 384.946309 -240.101772)
		(end 384.672078 -240.177574)
		(width 0.088646)
		(layer "In6.Cu")
		(net "M_G_CPU0_SB_DQS_DN<0>")
	)
	(arc
		(start 375.656856 -239.913414)
		(mid 375.636724 -239.852056)
		(end 375.59869 -239.799876)
		(width 0.088646)
		(layer "In6.Cu")
		(net "M_G_CPU0_SB_DQS_DN<0>")
	)
	(arc
		(start 383.727198 -240.180876)
		(mid 383.542152 -240.22795)
		(end 383.357882 -240.177828)
		(width 0.088646)
		(layer "In6.Cu")
		(net "M_G_CPU0_SB_DQS_DN<0>")
	)
	(arc
		(start 375.274078 -239.528858)
		(mid 375.08688 -239.478715)
		(end 374.899682 -239.528858)
		(width 0.088646)
		(layer "In6.Cu")
		(net "M_G_CPU0_SB_DQS_DN<0>")
	)
	(arc
		(start 377.70435 -240.168938)
		(mid 377.427909 -240.101772)
		(end 377.153678 -240.177574)
		(width 0.088646)
		(layer "In6.Cu")
		(net "M_G_CPU0_SB_DQS_DN<0>")
	)
	(arc
		(start 380.538482 -240.177574)
		(mid 380.261923 -240.101865)
		(end 379.983746 -240.171478)
		(width 0.088646)
		(layer "In6.Cu")
		(net "M_G_CPU0_SB_DQS_DN<0>")
	)
	(arc
		(start 381.468122 -240.171478)
		(mid 381.18969 -240.101664)
		(end 380.912878 -240.177574)
		(width 0.088646)
		(layer "In6.Cu")
		(net "M_G_CPU0_SB_DQS_DN<0>")
	)
	(arc
		(start 382.407668 -240.171478)
		(mid 382.12949 -240.101786)
		(end 381.852932 -240.177574)
		(width 0.088646)
		(layer "In6.Cu")
		(net "M_G_CPU0_SB_DQS_DN<0>")
	)
	(arc
		(start 375.493788 -239.694974)
		(mid 375.393741 -239.607436)
		(end 375.282968 -239.533938)
		(width 0.088646)
		(layer "In6.Cu")
		(net "M_G_CPU0_SB_DQS_DN<0>")
	)
	(arc
		(start 384.297428 -240.177574)
		(mid 384.011879 -240.101994)
		(end 383.727198 -240.180876)
		(width 0.088646)
		(layer "In6.Cu")
		(net "M_G_CPU0_SB_DQS_DN<0>")
	)
	(arc
		(start 387.10235 -240.168938)
		(mid 386.825909 -240.101772)
		(end 386.551678 -240.177574)
		(width 0.088646)
		(layer "In6.Cu")
		(net "M_G_CPU0_SB_DQS_DN<0>")
	)
	(arc
		(start 386.16255 -240.168938)
		(mid 385.886109 -240.101772)
		(end 385.611878 -240.177574)
		(width 0.088646)
		(layer "In6.Cu")
		(net "M_G_CPU0_SB_DQS_DN<0>")
	)
	(arc
		(start 385.611878 -240.177574)
		(mid 385.42468 -240.227717)
		(end 385.237482 -240.177574)
		(width 0.088646)
		(layer "In6.Cu")
		(net "M_G_CPU0_SB_DQS_DN<0>")
	)
	(arc
		(start 378.64415 -240.168938)
		(mid 378.367709 -240.101772)
		(end 378.093478 -240.177574)
		(width 0.088646)
		(layer "In6.Cu")
		(net "M_G_CPU0_SB_DQS_DN<0>")
	)
	(arc
		(start 379.033278 -240.177574)
		(mid 378.84608 -240.227717)
		(end 378.658882 -240.177574)
		(width 0.088646)
		(layer "In6.Cu")
		(net "M_G_CPU0_SB_DQS_DN<0>")
	)
	(arc
		(start 380.912878 -240.177574)
		(mid 380.72568 -240.227717)
		(end 380.538482 -240.177574)
		(width 0.088646)
		(layer "In6.Cu")
		(net "M_G_CPU0_SB_DQS_DN<0>")
	)
	(arc
		(start 383.357882 -240.177828)
		(mid 383.075434 -240.102179)
		(end 382.792986 -240.177828)
		(width 0.088646)
		(layer "In6.Cu")
		(net "M_G_CPU0_SB_DQS_DN<0>")
	)
	(arc
		(start 379.973332 -240.177574)
		(mid 379.786134 -240.227717)
		(end 379.598936 -240.177574)
		(width 0.088646)
		(layer "In6.Cu")
		(net "M_G_CPU0_SB_DQS_DN<0>")
	)
	(arc
		(start 376.76455 -240.168938)
		(mid 376.488109 -240.101772)
		(end 376.213878 -240.177574)
		(width 0.088646)
		(layer "In6.Cu")
		(net "M_G_CPU0_SB_DQS_DN<0>")
	)
	(arc
		(start 377.153678 -240.177574)
		(mid 376.96648 -240.227717)
		(end 376.779282 -240.177574)
		(width 0.088646)
		(layer "In6.Cu")
		(net "M_G_CPU0_SB_DQS_DN<0>")
	)
	(arc
		(start 386.551678 -240.177574)
		(mid 386.36448 -240.227717)
		(end 386.177282 -240.177574)
		(width 0.088646)
		(layer "In6.Cu")
		(net "M_G_CPU0_SB_DQS_DN<0>")
	)
	(arc
		(start 374.87479 -239.543844)
		(mid 374.771515 -239.643619)
		(end 374.719596 -239.777524)
		(width 0.088646)
		(layer "In6.Cu")
		(net "M_G_CPU0_SB_DQS_DN<0>")
	)
	(arc
		(start 381.852932 -240.177574)
		(mid 381.665734 -240.227717)
		(end 381.478536 -240.177574)
		(width 0.088646)
		(layer "In6.Cu")
		(net "M_G_CPU0_SB_DQS_DN<0>")
	)
	(arc
		(start 384.672078 -240.177574)
		(mid 384.48488 -240.227717)
		(end 384.297682 -240.177574)
		(width 0.088646)
		(layer "In6.Cu")
		(net "M_G_CPU0_SB_DQS_DN<0>")
	)
	(arc
		(start 376.213878 -240.177574)
		(mid 375.866149 -240.191567)
		(end 375.656856 -239.913414)
		(width 0.088646)
		(layer "In6.Cu")
		(net "M_G_CPU0_SB_DQS_DN<0>")
	)
	(segment
		(start 438.697878 -221.365318)
		(end 438.449212 -221.116652)
		(width 0.20066)
		(layer "F.Cu")
		(net "M_G_CPU0_SB_DQ<9>")
	)
	(segment
		(start 439.361072 -221.177358)
		(end 439.173112 -221.365318)
		(width 0.20066)
		(layer "F.Cu")
		(net "M_G_CPU0_SB_DQ<9>")
	)
	(segment
		(start 442.038994 -220.68536)
		(end 442.032644 -220.69171)
		(width 0.1016)
		(layer "F.Cu")
		(net "M_G_CPU0_SB_DQ<9>")
	)
	(segment
		(start 444.47206 -221.116906)
		(end 442.880496 -221.116906)
		(width 0.20066)
		(layer "F.Cu")
		(net "M_G_CPU0_SB_DQ<9>")
	)
	(segment
		(start 436.928514 -221.116652)
		(end 435.823614 -221.116652)
		(width 0.20066)
		(layer "F.Cu")
		(net "M_G_CPU0_SB_DQ<9>")
	)
	(segment
		(start 442.880496 -221.116906)
		(end 442.44895 -220.68536)
		(width 0.20066)
		(layer "F.Cu")
		(net "M_G_CPU0_SB_DQ<9>")
	)
	(segment
		(start 439.82386 -220.69171)
		(end 439.479182 -220.69171)
		(width 0.20066)
		(layer "F.Cu")
		(net "M_G_CPU0_SB_DQ<9>")
	)
	(segment
		(start 438.449212 -221.116652)
		(end 436.928514 -221.116652)
		(width 0.20066)
		(layer "F.Cu")
		(net "M_G_CPU0_SB_DQ<9>")
	)
	(segment
		(start 439.843926 -220.69171)
		(end 439.82386 -220.69171)
		(width 0.101854)
		(layer "F.Cu")
		(net "M_G_CPU0_SB_DQ<9>")
	)
	(segment
		(start 444.472314 -221.116652)
		(end 444.47206 -221.116906)
		(width 0.20066)
		(layer "F.Cu")
		(net "M_G_CPU0_SB_DQ<9>")
	)
	(segment
		(start 439.479182 -220.69171)
		(end 439.361072 -220.80982)
		(width 0.20066)
		(layer "F.Cu")
		(net "M_G_CPU0_SB_DQ<9>")
	)
	(segment
		(start 442.032644 -220.69171)
		(end 439.843926 -220.69171)
		(width 0.1016)
		(layer "F.Cu")
		(net "M_G_CPU0_SB_DQ<9>")
	)
	(segment
		(start 439.361072 -220.80982)
		(end 439.361072 -221.177358)
		(width 0.20066)
		(layer "F.Cu")
		(net "M_G_CPU0_SB_DQ<9>")
	)
	(segment
		(start 374.61698 -236.319822)
		(end 374.617234 -236.319568)
		(width 0.20066)
		(layer "F.Cu")
		(net "M_G_CPU0_SB_DQ<9>")
	)
	(segment
		(start 374.617234 -236.319568)
		(end 374.617234 -235.783882)
		(width 0.20066)
		(layer "F.Cu")
		(net "M_G_CPU0_SB_DQ<9>")
	)
	(segment
		(start 439.173112 -221.365318)
		(end 438.697878 -221.365318)
		(width 0.20066)
		(layer "F.Cu")
		(net "M_G_CPU0_SB_DQ<9>")
	)
	(segment
		(start 442.44895 -220.68536)
		(end 442.038994 -220.68536)
		(width 0.20066)
		(layer "F.Cu")
		(net "M_G_CPU0_SB_DQ<9>")
	)
	(segment
		(start 387.117082 -235.294424)
		(end 387.10235 -235.285788)
		(width 0.088646)
		(layer "In6.Cu")
		(net "M_G_CPU0_SB_DQ<9>")
	)
	(segment
		(start 413.490664 -222.395796)
		(end 413.322516 -222.395796)
		(width 0.18288)
		(layer "In6.Cu")
		(net "M_G_CPU0_SB_DQ<9>")
	)
	(segment
		(start 388.001764 -234.439714)
		(end 387.801104 -234.439714)
		(width 0.088646)
		(layer "In6.Cu")
		(net "M_G_CPU0_SB_DQ<9>")
	)
	(segment
		(start 380.453392 -236.102144)
		(end 380.442978 -236.10824)
		(width 0.088646)
		(layer "In6.Cu")
		(net "M_G_CPU0_SB_DQ<9>")
	)
	(segment
		(start 412.286196 -222.391478)
		(end 407.593292 -222.391478)
		(width 0.18288)
		(layer "In6.Cu")
		(net "M_G_CPU0_SB_DQ<9>")
	)
	(segment
		(start 425.973494 -223.448626)
		(end 425.329858 -224.092262)
		(width 0.18288)
		(layer "In6.Cu")
		(net "M_G_CPU0_SB_DQ<9>")
	)
	(segment
		(start 418.8206 -225.106738)
		(end 418.8206 -224.556574)
		(width 0.18288)
		(layer "In6.Cu")
		(net "M_G_CPU0_SB_DQ<9>")
	)
	(segment
		(start 429.475138 -221.54515)
		(end 428.562262 -222.458026)
		(width 0.18288)
		(layer "In6.Cu")
		(net "M_G_CPU0_SB_DQ<9>")
	)
	(segment
		(start 418.63772 -224.373694)
		(end 418.31006 -224.373694)
		(width 0.18288)
		(layer "In6.Cu")
		(net "M_G_CPU0_SB_DQ<9>")
	)
	(segment
		(start 425.329858 -224.092262)
		(end 422.358312 -224.092262)
		(width 0.18288)
		(layer "In6.Cu")
		(net "M_G_CPU0_SB_DQ<9>")
	)
	(segment
		(start 407.227786 -222.025972)
		(end 406.505918 -222.025972)
		(width 0.18288)
		(layer "In6.Cu")
		(net "M_G_CPU0_SB_DQ<9>")
	)
	(segment
		(start 412.469076 -222.574358)
		(end 412.286196 -222.391478)
		(width 0.18288)
		(layer "In6.Cu")
		(net "M_G_CPU0_SB_DQ<9>")
	)
	(segment
		(start 377.638564 -236.099604)
		(end 377.623832 -236.10824)
		(width 0.088646)
		(layer "In6.Cu")
		(net "M_G_CPU0_SB_DQ<9>")
	)
	(segment
		(start 407.593292 -222.391478)
		(end 407.227786 -222.025972)
		(width 0.18288)
		(layer "In6.Cu")
		(net "M_G_CPU0_SB_DQ<9>")
	)
	(segment
		(start 377.050554 -235.957364)
		(end 377.003564 -235.910374)
		(width 0.088646)
		(layer "In6.Cu")
		(net "M_G_CPU0_SB_DQ<9>")
	)
	(segment
		(start 415.330894 -224.236026)
		(end 414.857184 -223.762316)
		(width 0.18288)
		(layer "In6.Cu")
		(net "M_G_CPU0_SB_DQ<9>")
	)
	(segment
		(start 387.679184 -234.561634)
		(end 387.679184 -235.151168)
		(width 0.088646)
		(layer "In6.Cu")
		(net "M_G_CPU0_SB_DQ<9>")
	)
	(segment
		(start 376.098816 -235.406692)
		(end 375.528078 -235.406692)
		(width 0.088646)
		(layer "In6.Cu")
		(net "M_G_CPU0_SB_DQ<9>")
	)
	(segment
		(start 435.24932 -221.116652)
		(end 434.787294 -220.654626)
		(width 0.18288)
		(layer "In6.Cu")
		(net "M_G_CPU0_SB_DQ<9>")
	)
	(segment
		(start 431.28057 -221.54515)
		(end 429.475138 -221.54515)
		(width 0.18288)
		(layer "In6.Cu")
		(net "M_G_CPU0_SB_DQ<9>")
	)
	(segment
		(start 391.718038 -234.439714)
		(end 388.001764 -234.439714)
		(width 0.18288)
		(layer "In6.Cu")
		(net "M_G_CPU0_SB_DQ<9>")
	)
	(segment
		(start 413.630364 -224.008188)
		(end 413.630364 -223.782128)
		(width 0.18288)
		(layer "In6.Cu")
		(net "M_G_CPU0_SB_DQ<9>")
	)
	(segment
		(start 418.31006 -224.373694)
		(end 418.12718 -224.556574)
		(width 0.18288)
		(layer "In6.Cu")
		(net "M_G_CPU0_SB_DQ<9>")
	)
	(segment
		(start 379.513846 -236.102144)
		(end 379.503432 -236.10824)
		(width 0.088646)
		(layer "In6.Cu")
		(net "M_G_CPU0_SB_DQ<9>")
	)
	(segment
		(start 378.578364 -236.099604)
		(end 378.563632 -236.10824)
		(width 0.088646)
		(layer "In6.Cu")
		(net "M_G_CPU0_SB_DQ<9>")
	)
	(segment
		(start 384.217164 -236.099604)
		(end 384.202432 -236.10824)
		(width 0.088646)
		(layer "In6.Cu")
		(net "M_G_CPU0_SB_DQ<9>")
	)
	(segment
		(start 416.219894 -224.236026)
		(end 415.330894 -224.236026)
		(width 0.18288)
		(layer "In6.Cu")
		(net "M_G_CPU0_SB_DQ<9>")
	)
	(segment
		(start 414.631124 -223.762316)
		(end 414.120838 -224.272602)
		(width 0.18288)
		(layer "In6.Cu")
		(net "M_G_CPU0_SB_DQ<9>")
	)
	(segment
		(start 413.162496 -222.555816)
		(end 413.162496 -223.072452)
		(width 0.18288)
		(layer "In6.Cu")
		(net "M_G_CPU0_SB_DQ<9>")
	)
	(segment
		(start 383.277364 -236.099604)
		(end 383.262632 -236.10824)
		(width 0.088646)
		(layer "In6.Cu")
		(net "M_G_CPU0_SB_DQ<9>")
	)
	(segment
		(start 435.823614 -221.116652)
		(end 435.24932 -221.116652)
		(width 0.18288)
		(layer "In6.Cu")
		(net "M_G_CPU0_SB_DQ<9>")
	)
	(segment
		(start 414.14065 -223.271842)
		(end 414.14065 -223.045782)
		(width 0.18288)
		(layer "In6.Cu")
		(net "M_G_CPU0_SB_DQ<9>")
	)
	(segment
		(start 428.132494 -222.458026)
		(end 427.141894 -223.448626)
		(width 0.18288)
		(layer "In6.Cu")
		(net "M_G_CPU0_SB_DQ<9>")
	)
	(segment
		(start 385.156964 -236.099604)
		(end 385.142232 -236.10824)
		(width 0.088646)
		(layer "In6.Cu")
		(net "M_G_CPU0_SB_DQ<9>")
	)
	(segment
		(start 412.629096 -223.232472)
		(end 412.469076 -223.072452)
		(width 0.18288)
		(layer "In6.Cu")
		(net "M_G_CPU0_SB_DQ<9>")
	)
	(segment
		(start 376.499374 -235.409486)
		(end 376.098816 -235.406692)
		(width 0.088646)
		(layer "In6.Cu")
		(net "M_G_CPU0_SB_DQ<9>")
	)
	(segment
		(start 434.787294 -220.654626)
		(end 432.171094 -220.654626)
		(width 0.18288)
		(layer "In6.Cu")
		(net "M_G_CPU0_SB_DQ<9>")
	)
	(segment
		(start 406.505918 -222.025972)
		(end 406.10028 -222.43161)
		(width 0.18288)
		(layer "In6.Cu")
		(net "M_G_CPU0_SB_DQ<9>")
	)
	(segment
		(start 432.171094 -220.654626)
		(end 431.28057 -221.54515)
		(width 0.18288)
		(layer "In6.Cu")
		(net "M_G_CPU0_SB_DQ<9>")
	)
	(segment
		(start 387.679184 -235.151168)
		(end 387.485382 -235.34497)
		(width 0.088646)
		(layer "In6.Cu")
		(net "M_G_CPU0_SB_DQ<9>")
	)
	(segment
		(start 428.562262 -222.458026)
		(end 428.132494 -222.458026)
		(width 0.18288)
		(layer "In6.Cu")
		(net "M_G_CPU0_SB_DQ<9>")
	)
	(segment
		(start 417.273486 -225.289618)
		(end 416.219894 -224.236026)
		(width 0.18288)
		(layer "In6.Cu")
		(net "M_G_CPU0_SB_DQ<9>")
	)
	(segment
		(start 406.10028 -222.43161)
		(end 403.726142 -222.43161)
		(width 0.18288)
		(layer "In6.Cu")
		(net "M_G_CPU0_SB_DQ<9>")
	)
	(segment
		(start 414.14065 -223.045782)
		(end 413.490664 -222.395796)
		(width 0.18288)
		(layer "In6.Cu")
		(net "M_G_CPU0_SB_DQ<9>")
	)
	(segment
		(start 422.358312 -224.092262)
		(end 421.508174 -224.9424)
		(width 0.18288)
		(layer "In6.Cu")
		(net "M_G_CPU0_SB_DQ<9>")
	)
	(segment
		(start 413.894778 -224.272602)
		(end 413.630364 -224.008188)
		(width 0.18288)
		(layer "In6.Cu")
		(net "M_G_CPU0_SB_DQ<9>")
	)
	(segment
		(start 387.801104 -234.439714)
		(end 387.679184 -234.561634)
		(width 0.088646)
		(layer "In6.Cu")
		(net "M_G_CPU0_SB_DQ<9>")
	)
	(segment
		(start 413.322516 -222.395796)
		(end 413.162496 -222.555816)
		(width 0.18288)
		(layer "In6.Cu")
		(net "M_G_CPU0_SB_DQ<9>")
	)
	(segment
		(start 413.162496 -223.072452)
		(end 413.002476 -223.232472)
		(width 0.18288)
		(layer "In6.Cu")
		(net "M_G_CPU0_SB_DQ<9>")
	)
	(segment
		(start 421.508174 -224.9424)
		(end 420.304468 -224.9424)
		(width 0.18288)
		(layer "In6.Cu")
		(net "M_G_CPU0_SB_DQ<9>")
	)
	(segment
		(start 414.120838 -224.272602)
		(end 413.894778 -224.272602)
		(width 0.18288)
		(layer "In6.Cu")
		(net "M_G_CPU0_SB_DQ<9>")
	)
	(segment
		(start 413.630364 -223.782128)
		(end 414.14065 -223.271842)
		(width 0.18288)
		(layer "In6.Cu")
		(net "M_G_CPU0_SB_DQ<9>")
	)
	(segment
		(start 376.802142 -235.528104)
		(end 376.684032 -235.459524)
		(width 0.088646)
		(layer "In6.Cu")
		(net "M_G_CPU0_SB_DQ<9>")
	)
	(segment
		(start 417.9443 -225.289618)
		(end 417.273486 -225.289618)
		(width 0.18288)
		(layer "In6.Cu")
		(net "M_G_CPU0_SB_DQ<9>")
	)
	(segment
		(start 403.726142 -222.43161)
		(end 391.718038 -234.439714)
		(width 0.18288)
		(layer "In6.Cu")
		(net "M_G_CPU0_SB_DQ<9>")
	)
	(segment
		(start 427.141894 -223.448626)
		(end 425.973494 -223.448626)
		(width 0.18288)
		(layer "In6.Cu")
		(net "M_G_CPU0_SB_DQ<9>")
	)
	(segment
		(start 414.857184 -223.762316)
		(end 414.631124 -223.762316)
		(width 0.18288)
		(layer "In6.Cu")
		(net "M_G_CPU0_SB_DQ<9>")
	)
	(segment
		(start 418.12718 -224.556574)
		(end 418.12718 -225.106738)
		(width 0.18288)
		(layer "In6.Cu")
		(net "M_G_CPU0_SB_DQ<9>")
	)
	(segment
		(start 386.269484 -235.768388)
		(end 386.269484 -235.783882)
		(width 0.088646)
		(layer "In6.Cu")
		(net "M_G_CPU0_SB_DQ<9>")
	)
	(segment
		(start 420.304468 -224.9424)
		(end 419.95725 -225.289618)
		(width 0.18288)
		(layer "In6.Cu")
		(net "M_G_CPU0_SB_DQ<9>")
	)
	(segment
		(start 418.8206 -224.556574)
		(end 418.63772 -224.373694)
		(width 0.18288)
		(layer "In6.Cu")
		(net "M_G_CPU0_SB_DQ<9>")
	)
	(segment
		(start 377.249436 -236.10824)
		(end 377.253754 -236.111034)
		(width 0.088646)
		(layer "In6.Cu")
		(net "M_G_CPU0_SB_DQ<9>")
	)
	(segment
		(start 419.00348 -225.289618)
		(end 418.8206 -225.106738)
		(width 0.18288)
		(layer "In6.Cu")
		(net "M_G_CPU0_SB_DQ<9>")
	)
	(segment
		(start 418.12718 -225.106738)
		(end 417.9443 -225.289618)
		(width 0.18288)
		(layer "In6.Cu")
		(net "M_G_CPU0_SB_DQ<9>")
	)
	(segment
		(start 376.874278 -235.599478)
		(end 376.802142 -235.528104)
		(width 0.088646)
		(layer "In6.Cu")
		(net "M_G_CPU0_SB_DQ<9>")
	)
	(segment
		(start 412.469076 -223.072452)
		(end 412.469076 -222.574358)
		(width 0.18288)
		(layer "In6.Cu")
		(net "M_G_CPU0_SB_DQ<9>")
	)
	(segment
		(start 387.485382 -235.34497)
		(end 387.30428 -235.34497)
		(width 0.088646)
		(layer "In6.Cu")
		(net "M_G_CPU0_SB_DQ<9>")
	)
	(segment
		(start 413.002476 -223.232472)
		(end 412.629096 -223.232472)
		(width 0.18288)
		(layer "In6.Cu")
		(net "M_G_CPU0_SB_DQ<9>")
	)
	(segment
		(start 419.95725 -225.289618)
		(end 419.00348 -225.289618)
		(width 0.18288)
		(layer "In6.Cu")
		(net "M_G_CPU0_SB_DQ<9>")
	)
	(arc
		(start 384.767836 -236.10824)
		(mid 384.493607 -236.032315)
		(end 384.217164 -236.099604)
		(width 0.088646)
		(layer "In6.Cu")
		(net "M_G_CPU0_SB_DQ<9>")
	)
	(arc
		(start 376.931682 -235.736892)
		(mid 376.916709 -235.662449)
		(end 376.874278 -235.599478)
		(width 0.088646)
		(layer "In6.Cu")
		(net "M_G_CPU0_SB_DQ<9>")
	)
	(arc
		(start 379.503432 -236.10824)
		(mid 379.316234 -236.158383)
		(end 379.129036 -236.10824)
		(width 0.088646)
		(layer "In6.Cu")
		(net "M_G_CPU0_SB_DQ<9>")
	)
	(arc
		(start 381.948436 -236.10824)
		(mid 381.665734 -236.032498)
		(end 381.383032 -236.10824)
		(width 0.088646)
		(layer "In6.Cu")
		(net "M_G_CPU0_SB_DQ<9>")
	)
	(arc
		(start 376.684032 -235.459524)
		(mid 376.594951 -235.422525)
		(end 376.499374 -235.409486)
		(width 0.088646)
		(layer "In6.Cu")
		(net "M_G_CPU0_SB_DQ<9>")
	)
	(arc
		(start 377.623832 -236.10824)
		(mid 377.436634 -236.158383)
		(end 377.249436 -236.10824)
		(width 0.088646)
		(layer "In6.Cu")
		(net "M_G_CPU0_SB_DQ<9>")
	)
	(arc
		(start 386.269484 -235.783882)
		(mid 386.082185 -236.108323)
		(end 385.707636 -236.10824)
		(width 0.088646)
		(layer "In6.Cu")
		(net "M_G_CPU0_SB_DQ<9>")
	)
	(arc
		(start 382.888236 -236.10824)
		(mid 382.605534 -236.032498)
		(end 382.322832 -236.10824)
		(width 0.088646)
		(layer "In6.Cu")
		(net "M_G_CPU0_SB_DQ<9>")
	)
	(arc
		(start 382.322832 -236.10824)
		(mid 382.135634 -236.158383)
		(end 381.948436 -236.10824)
		(width 0.088646)
		(layer "In6.Cu")
		(net "M_G_CPU0_SB_DQ<9>")
	)
	(arc
		(start 378.563632 -236.10824)
		(mid 378.376434 -236.158383)
		(end 378.189236 -236.10824)
		(width 0.088646)
		(layer "In6.Cu")
		(net "M_G_CPU0_SB_DQ<9>")
	)
	(arc
		(start 380.442978 -236.10824)
		(mid 380.25578 -236.158383)
		(end 380.068582 -236.10824)
		(width 0.088646)
		(layer "In6.Cu")
		(net "M_G_CPU0_SB_DQ<9>")
	)
	(arc
		(start 378.189236 -236.10824)
		(mid 377.915007 -236.032315)
		(end 377.638564 -236.099604)
		(width 0.088646)
		(layer "In6.Cu")
		(net "M_G_CPU0_SB_DQ<9>")
	)
	(arc
		(start 384.202432 -236.10824)
		(mid 384.015234 -236.158383)
		(end 383.828036 -236.10824)
		(width 0.088646)
		(layer "In6.Cu")
		(net "M_G_CPU0_SB_DQ<9>")
	)
	(arc
		(start 387.30428 -235.34497)
		(mid 387.207357 -235.332012)
		(end 387.117082 -235.294424)
		(width 0.088646)
		(layer "In6.Cu")
		(net "M_G_CPU0_SB_DQ<9>")
	)
	(arc
		(start 377.253754 -236.111034)
		(mid 377.146851 -236.041211)
		(end 377.050554 -235.957364)
		(width 0.088646)
		(layer "In6.Cu")
		(net "M_G_CPU0_SB_DQ<9>")
	)
	(arc
		(start 383.828036 -236.10824)
		(mid 383.553807 -236.032315)
		(end 383.277364 -236.099604)
		(width 0.088646)
		(layer "In6.Cu")
		(net "M_G_CPU0_SB_DQ<9>")
	)
	(arc
		(start 379.129036 -236.10824)
		(mid 378.854807 -236.032315)
		(end 378.578364 -236.099604)
		(width 0.088646)
		(layer "In6.Cu")
		(net "M_G_CPU0_SB_DQ<9>")
	)
	(arc
		(start 381.383032 -236.10824)
		(mid 381.195834 -236.158383)
		(end 381.008636 -236.10824)
		(width 0.088646)
		(layer "In6.Cu")
		(net "M_G_CPU0_SB_DQ<9>")
	)
	(arc
		(start 385.142232 -236.10824)
		(mid 384.955034 -236.158383)
		(end 384.767836 -236.10824)
		(width 0.088646)
		(layer "In6.Cu")
		(net "M_G_CPU0_SB_DQ<9>")
	)
	(arc
		(start 387.10235 -235.285788)
		(mid 386.825875 -235.218468)
		(end 386.551678 -235.294424)
		(width 0.088646)
		(layer "In6.Cu")
		(net "M_G_CPU0_SB_DQ<9>")
	)
	(arc
		(start 385.707636 -236.10824)
		(mid 385.433407 -236.032315)
		(end 385.156964 -236.099604)
		(width 0.088646)
		(layer "In6.Cu")
		(net "M_G_CPU0_SB_DQ<9>")
	)
	(arc
		(start 377.003564 -235.910374)
		(mid 376.950381 -235.83078)
		(end 376.931682 -235.736892)
		(width 0.088646)
		(layer "In6.Cu")
		(net "M_G_CPU0_SB_DQ<9>")
	)
	(arc
		(start 383.262632 -236.10824)
		(mid 383.075434 -236.158383)
		(end 382.888236 -236.10824)
		(width 0.088646)
		(layer "In6.Cu")
		(net "M_G_CPU0_SB_DQ<9>")
	)
	(arc
		(start 380.068582 -236.10824)
		(mid 379.792023 -236.032531)
		(end 379.513846 -236.102144)
		(width 0.088646)
		(layer "In6.Cu")
		(net "M_G_CPU0_SB_DQ<9>")
	)
	(arc
		(start 375.528078 -235.406692)
		(mid 375.035154 -235.504723)
		(end 374.617234 -235.783882)
		(width 0.088646)
		(layer "In6.Cu")
		(net "M_G_CPU0_SB_DQ<9>")
	)
	(arc
		(start 386.551678 -235.294424)
		(mid 386.348855 -235.494655)
		(end 386.269484 -235.768388)
		(width 0.088646)
		(layer "In6.Cu")
		(net "M_G_CPU0_SB_DQ<9>")
	)
	(arc
		(start 381.008636 -236.10824)
		(mid 380.731823 -236.032404)
		(end 380.453392 -236.102144)
		(width 0.088646)
		(layer "In6.Cu")
		(net "M_G_CPU0_SB_DQ<9>")
	)
	(segment
		(start 439.87085 -222.391732)
		(end 439.82386 -222.391732)
		(width 0.101854)
		(layer "F.Cu")
		(net "M_G_CPU0_SB_DQ<8>")
	)
	(segment
		(start 438.449212 -222.816674)
		(end 436.928514 -222.816674)
		(width 0.20066)
		(layer "F.Cu")
		(net "M_G_CPU0_SB_DQ<8>")
	)
	(segment
		(start 439.479182 -222.391732)
		(end 439.361072 -222.509842)
		(width 0.20066)
		(layer "F.Cu")
		(net "M_G_CPU0_SB_DQ<8>")
	)
	(segment
		(start 439.173112 -223.06534)
		(end 438.697878 -223.06534)
		(width 0.20066)
		(layer "F.Cu")
		(net "M_G_CPU0_SB_DQ<8>")
	)
	(segment
		(start 439.82386 -222.391732)
		(end 439.479182 -222.391732)
		(width 0.20066)
		(layer "F.Cu")
		(net "M_G_CPU0_SB_DQ<8>")
	)
	(segment
		(start 442.44895 -222.385382)
		(end 442.038994 -222.385382)
		(width 0.20066)
		(layer "F.Cu")
		(net "M_G_CPU0_SB_DQ<8>")
	)
	(segment
		(start 444.472314 -222.816674)
		(end 444.47206 -222.816928)
		(width 0.20066)
		(layer "F.Cu")
		(net "M_G_CPU0_SB_DQ<8>")
	)
	(segment
		(start 444.47206 -222.816928)
		(end 442.880496 -222.816928)
		(width 0.20066)
		(layer "F.Cu")
		(net "M_G_CPU0_SB_DQ<8>")
	)
	(segment
		(start 376.026934 -237.133892)
		(end 376.02668 -237.133638)
		(width 0.20066)
		(layer "F.Cu")
		(net "M_G_CPU0_SB_DQ<8>")
	)
	(segment
		(start 439.361072 -222.87738)
		(end 439.173112 -223.06534)
		(width 0.20066)
		(layer "F.Cu")
		(net "M_G_CPU0_SB_DQ<8>")
	)
	(segment
		(start 442.880496 -222.816928)
		(end 442.44895 -222.385382)
		(width 0.20066)
		(layer "F.Cu")
		(net "M_G_CPU0_SB_DQ<8>")
	)
	(segment
		(start 442.038994 -222.385382)
		(end 442.032644 -222.391732)
		(width 0.1016)
		(layer "F.Cu")
		(net "M_G_CPU0_SB_DQ<8>")
	)
	(segment
		(start 439.361072 -222.509842)
		(end 439.361072 -222.87738)
		(width 0.20066)
		(layer "F.Cu")
		(net "M_G_CPU0_SB_DQ<8>")
	)
	(segment
		(start 442.032644 -222.391732)
		(end 439.87085 -222.391732)
		(width 0.1016)
		(layer "F.Cu")
		(net "M_G_CPU0_SB_DQ<8>")
	)
	(segment
		(start 438.697878 -223.06534)
		(end 438.449212 -222.816674)
		(width 0.20066)
		(layer "F.Cu")
		(net "M_G_CPU0_SB_DQ<8>")
	)
	(segment
		(start 376.02668 -237.133638)
		(end 376.02668 -236.597952)
		(width 0.20066)
		(layer "F.Cu")
		(net "M_G_CPU0_SB_DQ<8>")
	)
	(segment
		(start 436.928514 -222.816674)
		(end 435.823614 -222.816674)
		(width 0.20066)
		(layer "F.Cu")
		(net "M_G_CPU0_SB_DQ<8>")
	)
	(segment
		(start 405.745188 -224.942146)
		(end 405.744934 -224.941892)
		(width 0.18288)
		(layer "In6.Cu")
		(net "M_G_CPU0_SB_DQ<8>")
	)
	(segment
		(start 412.960058 -226.602036)
		(end 411.927294 -225.569272)
		(width 0.18288)
		(layer "In6.Cu")
		(net "M_G_CPU0_SB_DQ<8>")
	)
	(segment
		(start 410.74594 -225.569272)
		(end 410.11856 -224.941892)
		(width 0.18288)
		(layer "In6.Cu")
		(net "M_G_CPU0_SB_DQ<8>")
	)
	(segment
		(start 378.578364 -237.096046)
		(end 378.563632 -237.08741)
		(width 0.088646)
		(layer "In6.Cu")
		(net "M_G_CPU0_SB_DQ<8>")
	)
	(segment
		(start 428.132494 -224.845626)
		(end 427.268894 -225.709226)
		(width 0.18288)
		(layer "In6.Cu")
		(net "M_G_CPU0_SB_DQ<8>")
	)
	(segment
		(start 408.95778 -226.737672)
		(end 408.5844 -226.737672)
		(width 0.18288)
		(layer "In6.Cu")
		(net "M_G_CPU0_SB_DQ<8>")
	)
	(segment
		(start 380.453646 -237.093506)
		(end 380.443232 -237.08741)
		(width 0.088646)
		(layer "In6.Cu")
		(net "M_G_CPU0_SB_DQ<8>")
	)
	(segment
		(start 386.096764 -237.096046)
		(end 386.082032 -237.08741)
		(width 0.088646)
		(layer "In6.Cu")
		(net "M_G_CPU0_SB_DQ<8>")
	)
	(segment
		(start 384.217164 -237.096046)
		(end 384.202432 -237.08741)
		(width 0.088646)
		(layer "In6.Cu")
		(net "M_G_CPU0_SB_DQ<8>")
	)
	(segment
		(start 392.462258 -235.942632)
		(end 388.162546 -235.942632)
		(width 0.18288)
		(layer "In6.Cu")
		(net "M_G_CPU0_SB_DQ<8>")
	)
	(segment
		(start 428.582582 -224.845626)
		(end 428.132494 -224.845626)
		(width 0.18288)
		(layer "In6.Cu")
		(net "M_G_CPU0_SB_DQ<8>")
	)
	(segment
		(start 405.744934 -224.941892)
		(end 403.462998 -224.941892)
		(width 0.18288)
		(layer "In6.Cu")
		(net "M_G_CPU0_SB_DQ<8>")
	)
	(segment
		(start 406.203404 -224.942146)
		(end 405.745188 -224.942146)
		(width 0.18288)
		(layer "In6.Cu")
		(net "M_G_CPU0_SB_DQ<8>")
	)
	(segment
		(start 377.638564 -237.096046)
		(end 377.623832 -237.08741)
		(width 0.088646)
		(layer "In6.Cu")
		(net "M_G_CPU0_SB_DQ<8>")
	)
	(segment
		(start 421.752014 -227.492306)
		(end 416.732974 -227.492306)
		(width 0.18288)
		(layer "In6.Cu")
		(net "M_G_CPU0_SB_DQ<8>")
	)
	(segment
		(start 381.948436 -237.08741)
		(end 381.938022 -237.093506)
		(width 0.088646)
		(layer "In6.Cu")
		(net "M_G_CPU0_SB_DQ<8>")
	)
	(segment
		(start 422.602152 -226.642168)
		(end 421.752014 -227.492306)
		(width 0.18288)
		(layer "In6.Cu")
		(net "M_G_CPU0_SB_DQ<8>")
	)
	(segment
		(start 407.216864 -224.942146)
		(end 407.056844 -225.102166)
		(width 0.18288)
		(layer "In6.Cu")
		(net "M_G_CPU0_SB_DQ<8>")
	)
	(segment
		(start 407.056844 -226.679252)
		(end 406.896824 -226.839272)
		(width 0.18288)
		(layer "In6.Cu")
		(net "M_G_CPU0_SB_DQ<8>")
	)
	(segment
		(start 410.11856 -224.941892)
		(end 409.27782 -224.941892)
		(width 0.18288)
		(layer "In6.Cu")
		(net "M_G_CPU0_SB_DQ<8>")
	)
	(segment
		(start 411.927294 -225.569272)
		(end 410.74594 -225.569272)
		(width 0.18288)
		(layer "In6.Cu")
		(net "M_G_CPU0_SB_DQ<8>")
	)
	(segment
		(start 406.523444 -226.839272)
		(end 406.363424 -226.679252)
		(width 0.18288)
		(layer "In6.Cu")
		(net "M_G_CPU0_SB_DQ<8>")
	)
	(segment
		(start 406.896824 -226.839272)
		(end 406.523444 -226.839272)
		(width 0.18288)
		(layer "In6.Cu")
		(net "M_G_CPU0_SB_DQ<8>")
	)
	(segment
		(start 408.26436 -224.941892)
		(end 407.292302 -224.941892)
		(width 0.18288)
		(layer "In6.Cu")
		(net "M_G_CPU0_SB_DQ<8>")
	)
	(segment
		(start 415.842704 -226.602036)
		(end 412.960058 -226.602036)
		(width 0.18288)
		(layer "In6.Cu")
		(net "M_G_CPU0_SB_DQ<8>")
	)
	(segment
		(start 388.162546 -235.942632)
		(end 387.848094 -235.942632)
		(width 0.088646)
		(layer "In6.Cu")
		(net "M_G_CPU0_SB_DQ<8>")
	)
	(segment
		(start 387.567932 -236.222794)
		(end 387.30428 -236.222794)
		(width 0.088646)
		(layer "In6.Cu")
		(net "M_G_CPU0_SB_DQ<8>")
	)
	(segment
		(start 406.363424 -226.679252)
		(end 406.363424 -225.102166)
		(width 0.18288)
		(layer "In6.Cu")
		(net "M_G_CPU0_SB_DQ<8>")
	)
	(segment
		(start 386.92963 -236.597952)
		(end 386.92963 -236.613446)
		(width 0.088646)
		(layer "In6.Cu")
		(net "M_G_CPU0_SB_DQ<8>")
	)
	(segment
		(start 385.156964 -237.096046)
		(end 385.142232 -237.08741)
		(width 0.088646)
		(layer "In6.Cu")
		(net "M_G_CPU0_SB_DQ<8>")
	)
	(segment
		(start 376.684032 -237.08741)
		(end 376.606308 -237.042452)
		(width 0.088646)
		(layer "In6.Cu")
		(net "M_G_CPU0_SB_DQ<8>")
	)
	(segment
		(start 387.117082 -236.273594)
		(end 387.108192 -236.278674)
		(width 0.088646)
		(layer "In6.Cu")
		(net "M_G_CPU0_SB_DQ<8>")
	)
	(segment
		(start 431.053494 -224.134426)
		(end 429.293782 -224.134426)
		(width 0.18288)
		(layer "In6.Cu")
		(net "M_G_CPU0_SB_DQ<8>")
	)
	(segment
		(start 425.195746 -226.642168)
		(end 422.602152 -226.642168)
		(width 0.18288)
		(layer "In6.Cu")
		(net "M_G_CPU0_SB_DQ<8>")
	)
	(segment
		(start 435.823614 -222.816674)
		(end 435.370986 -223.269302)
		(width 0.18288)
		(layer "In6.Cu")
		(net "M_G_CPU0_SB_DQ<8>")
	)
	(segment
		(start 408.42438 -225.101912)
		(end 408.26436 -224.941892)
		(width 0.18288)
		(layer "In6.Cu")
		(net "M_G_CPU0_SB_DQ<8>")
	)
	(segment
		(start 379.518164 -237.096046)
		(end 379.503432 -237.08741)
		(width 0.088646)
		(layer "In6.Cu")
		(net "M_G_CPU0_SB_DQ<8>")
	)
	(segment
		(start 431.918618 -223.269302)
		(end 431.053494 -224.134426)
		(width 0.18288)
		(layer "In6.Cu")
		(net "M_G_CPU0_SB_DQ<8>")
	)
	(segment
		(start 383.277364 -237.096046)
		(end 383.262632 -237.08741)
		(width 0.088646)
		(layer "In6.Cu")
		(net "M_G_CPU0_SB_DQ<8>")
	)
	(segment
		(start 408.5844 -226.737672)
		(end 408.42438 -226.577652)
		(width 0.18288)
		(layer "In6.Cu")
		(net "M_G_CPU0_SB_DQ<8>")
	)
	(segment
		(start 409.1178 -226.577652)
		(end 408.95778 -226.737672)
		(width 0.18288)
		(layer "In6.Cu")
		(net "M_G_CPU0_SB_DQ<8>")
	)
	(segment
		(start 426.128688 -225.709226)
		(end 425.195746 -226.642168)
		(width 0.18288)
		(layer "In6.Cu")
		(net "M_G_CPU0_SB_DQ<8>")
	)
	(segment
		(start 403.462998 -224.941892)
		(end 392.462258 -235.942632)
		(width 0.18288)
		(layer "In6.Cu")
		(net "M_G_CPU0_SB_DQ<8>")
	)
	(segment
		(start 409.1178 -225.101912)
		(end 409.1178 -226.577652)
		(width 0.18288)
		(layer "In6.Cu")
		(net "M_G_CPU0_SB_DQ<8>")
	)
	(segment
		(start 406.363424 -225.102166)
		(end 406.203404 -224.942146)
		(width 0.18288)
		(layer "In6.Cu")
		(net "M_G_CPU0_SB_DQ<8>")
	)
	(segment
		(start 409.27782 -224.941892)
		(end 409.1178 -225.101912)
		(width 0.18288)
		(layer "In6.Cu")
		(net "M_G_CPU0_SB_DQ<8>")
	)
	(segment
		(start 408.42438 -226.577652)
		(end 408.42438 -225.101912)
		(width 0.18288)
		(layer "In6.Cu")
		(net "M_G_CPU0_SB_DQ<8>")
	)
	(segment
		(start 435.370986 -223.269302)
		(end 431.918618 -223.269302)
		(width 0.18288)
		(layer "In6.Cu")
		(net "M_G_CPU0_SB_DQ<8>")
	)
	(segment
		(start 407.292302 -224.941892)
		(end 407.292048 -224.942146)
		(width 0.18288)
		(layer "In6.Cu")
		(net "M_G_CPU0_SB_DQ<8>")
	)
	(segment
		(start 429.293782 -224.134426)
		(end 428.582582 -224.845626)
		(width 0.18288)
		(layer "In6.Cu")
		(net "M_G_CPU0_SB_DQ<8>")
	)
	(segment
		(start 387.848094 -235.942632)
		(end 387.567932 -236.222794)
		(width 0.088646)
		(layer "In6.Cu")
		(net "M_G_CPU0_SB_DQ<8>")
	)
	(segment
		(start 416.732974 -227.492306)
		(end 415.842704 -226.602036)
		(width 0.18288)
		(layer "In6.Cu")
		(net "M_G_CPU0_SB_DQ<8>")
	)
	(segment
		(start 407.292048 -224.942146)
		(end 407.216864 -224.942146)
		(width 0.18288)
		(layer "In6.Cu")
		(net "M_G_CPU0_SB_DQ<8>")
	)
	(segment
		(start 407.056844 -225.102166)
		(end 407.056844 -226.679252)
		(width 0.18288)
		(layer "In6.Cu")
		(net "M_G_CPU0_SB_DQ<8>")
	)
	(segment
		(start 427.268894 -225.709226)
		(end 426.128688 -225.709226)
		(width 0.18288)
		(layer "In6.Cu")
		(net "M_G_CPU0_SB_DQ<8>")
	)
	(arc
		(start 386.647436 -237.08741)
		(mid 386.373237 -237.163245)
		(end 386.096764 -237.096046)
		(width 0.088646)
		(layer "In6.Cu")
		(net "M_G_CPU0_SB_DQ<8>")
	)
	(arc
		(start 385.142232 -237.08741)
		(mid 384.955034 -237.037233)
		(end 384.767836 -237.08741)
		(width 0.088646)
		(layer "In6.Cu")
		(net "M_G_CPU0_SB_DQ<8>")
	)
	(arc
		(start 377.249436 -237.08741)
		(mid 376.966734 -237.163186)
		(end 376.684032 -237.08741)
		(width 0.088646)
		(layer "In6.Cu")
		(net "M_G_CPU0_SB_DQ<8>")
	)
	(arc
		(start 383.262632 -237.08741)
		(mid 383.075434 -237.037233)
		(end 382.888236 -237.08741)
		(width 0.088646)
		(layer "In6.Cu")
		(net "M_G_CPU0_SB_DQ<8>")
	)
	(arc
		(start 382.888236 -237.08741)
		(mid 382.605534 -237.163186)
		(end 382.322832 -237.08741)
		(width 0.088646)
		(layer "In6.Cu")
		(net "M_G_CPU0_SB_DQ<8>")
	)
	(arc
		(start 379.503432 -237.08741)
		(mid 379.316234 -237.037233)
		(end 379.129036 -237.08741)
		(width 0.088646)
		(layer "In6.Cu")
		(net "M_G_CPU0_SB_DQ<8>")
	)
	(arc
		(start 382.322832 -237.08741)
		(mid 382.135634 -237.037233)
		(end 381.948436 -237.08741)
		(width 0.088646)
		(layer "In6.Cu")
		(net "M_G_CPU0_SB_DQ<8>")
	)
	(arc
		(start 380.443232 -237.08741)
		(mid 380.256034 -237.037233)
		(end 380.068836 -237.08741)
		(width 0.088646)
		(layer "In6.Cu")
		(net "M_G_CPU0_SB_DQ<8>")
	)
	(arc
		(start 381.008382 -237.08741)
		(mid 380.731823 -237.163153)
		(end 380.453646 -237.093506)
		(width 0.088646)
		(layer "In6.Cu")
		(net "M_G_CPU0_SB_DQ<8>")
	)
	(arc
		(start 383.828036 -237.08741)
		(mid 383.553837 -237.163245)
		(end 383.277364 -237.096046)
		(width 0.088646)
		(layer "In6.Cu")
		(net "M_G_CPU0_SB_DQ<8>")
	)
	(arc
		(start 377.623832 -237.08741)
		(mid 377.436634 -237.037233)
		(end 377.249436 -237.08741)
		(width 0.088646)
		(layer "In6.Cu")
		(net "M_G_CPU0_SB_DQ<8>")
	)
	(arc
		(start 385.707636 -237.08741)
		(mid 385.433437 -237.163245)
		(end 385.156964 -237.096046)
		(width 0.088646)
		(layer "In6.Cu")
		(net "M_G_CPU0_SB_DQ<8>")
	)
	(arc
		(start 386.92963 -236.613446)
		(mid 386.85026 -236.88718)
		(end 386.647436 -237.08741)
		(width 0.088646)
		(layer "In6.Cu")
		(net "M_G_CPU0_SB_DQ<8>")
	)
	(arc
		(start 381.382778 -237.08741)
		(mid 381.19558 -237.037233)
		(end 381.008382 -237.08741)
		(width 0.088646)
		(layer "In6.Cu")
		(net "M_G_CPU0_SB_DQ<8>")
	)
	(arc
		(start 378.189236 -237.08741)
		(mid 377.915037 -237.163245)
		(end 377.638564 -237.096046)
		(width 0.088646)
		(layer "In6.Cu")
		(net "M_G_CPU0_SB_DQ<8>")
	)
	(arc
		(start 376.606308 -237.042452)
		(mid 376.301909 -236.839222)
		(end 376.02668 -236.597952)
		(width 0.088646)
		(layer "In6.Cu")
		(net "M_G_CPU0_SB_DQ<8>")
	)
	(arc
		(start 386.082032 -237.08741)
		(mid 385.894834 -237.037233)
		(end 385.707636 -237.08741)
		(width 0.088646)
		(layer "In6.Cu")
		(net "M_G_CPU0_SB_DQ<8>")
	)
	(arc
		(start 384.202432 -237.08741)
		(mid 384.015234 -237.037233)
		(end 383.828036 -237.08741)
		(width 0.088646)
		(layer "In6.Cu")
		(net "M_G_CPU0_SB_DQ<8>")
	)
	(arc
		(start 381.938022 -237.093506)
		(mid 381.65959 -237.163352)
		(end 381.382778 -237.08741)
		(width 0.088646)
		(layer "In6.Cu")
		(net "M_G_CPU0_SB_DQ<8>")
	)
	(arc
		(start 387.30428 -236.222794)
		(mid 387.207341 -236.235884)
		(end 387.117082 -236.273594)
		(width 0.088646)
		(layer "In6.Cu")
		(net "M_G_CPU0_SB_DQ<8>")
	)
	(arc
		(start 387.108192 -236.278674)
		(mid 386.977278 -236.415034)
		(end 386.92963 -236.597952)
		(width 0.088646)
		(layer "In6.Cu")
		(net "M_G_CPU0_SB_DQ<8>")
	)
	(arc
		(start 380.068836 -237.08741)
		(mid 379.794637 -237.163245)
		(end 379.518164 -237.096046)
		(width 0.088646)
		(layer "In6.Cu")
		(net "M_G_CPU0_SB_DQ<8>")
	)
	(arc
		(start 384.767836 -237.08741)
		(mid 384.493637 -237.163245)
		(end 384.217164 -237.096046)
		(width 0.088646)
		(layer "In6.Cu")
		(net "M_G_CPU0_SB_DQ<8>")
	)
	(arc
		(start 378.563632 -237.08741)
		(mid 378.376434 -237.037233)
		(end 378.189236 -237.08741)
		(width 0.088646)
		(layer "In6.Cu")
		(net "M_G_CPU0_SB_DQ<8>")
	)
	(arc
		(start 379.129036 -237.08741)
		(mid 378.854837 -237.163245)
		(end 378.578364 -237.096046)
		(width 0.088646)
		(layer "In6.Cu")
		(net "M_G_CPU0_SB_DQ<8>")
	)
	(segment
		(start 446.602104 -223.41459)
		(end 446.986152 -223.41459)
		(width 0.20066)
		(layer "F.Cu")
		(net "M_G_CPU0_SB_DQ<7>")
	)
	(segment
		(start 376.026934 -238.761524)
		(end 376.02668 -238.76127)
		(width 0.20066)
		(layer "F.Cu")
		(net "M_G_CPU0_SB_DQ<7>")
	)
	(segment
		(start 443.455552 -224.098612)
		(end 443.462664 -224.0915)
		(width 0.1016)
		(layer "F.Cu")
		(net "M_G_CPU0_SB_DQ<7>")
	)
	(segment
		(start 447.23812 -223.666558)
		(end 448.572382 -223.666558)
		(width 0.20066)
		(layer "F.Cu")
		(net "M_G_CPU0_SB_DQ<7>")
	)
	(segment
		(start 446.367916 -223.89973)
		(end 446.367916 -223.648778)
		(width 0.20066)
		(layer "F.Cu")
		(net "M_G_CPU0_SB_DQ<7>")
	)
	(segment
		(start 443.462664 -224.0915)
		(end 445.470534 -224.0915)
		(width 0.1016)
		(layer "F.Cu")
		(net "M_G_CPU0_SB_DQ<7>")
	)
	(segment
		(start 443.15888 -224.098612)
		(end 443.450726 -224.098612)
		(width 0.20066)
		(layer "F.Cu")
		(net "M_G_CPU0_SB_DQ<7>")
	)
	(segment
		(start 376.02668 -238.76127)
		(end 376.02668 -238.225584)
		(width 0.20066)
		(layer "F.Cu")
		(net "M_G_CPU0_SB_DQ<7>")
	)
	(segment
		(start 442.726826 -223.666558)
		(end 443.15888 -224.098612)
		(width 0.20066)
		(layer "F.Cu")
		(net "M_G_CPU0_SB_DQ<7>")
	)
	(segment
		(start 443.450726 -224.098612)
		(end 443.455552 -224.098612)
		(width 0.101854)
		(layer "F.Cu")
		(net "M_G_CPU0_SB_DQ<7>")
	)
	(segment
		(start 446.986152 -223.41459)
		(end 447.23812 -223.666558)
		(width 0.20066)
		(layer "F.Cu")
		(net "M_G_CPU0_SB_DQ<7>")
	)
	(segment
		(start 441.028582 -223.666558)
		(end 442.726826 -223.666558)
		(width 0.20066)
		(layer "F.Cu")
		(net "M_G_CPU0_SB_DQ<7>")
	)
	(segment
		(start 446.163954 -224.103692)
		(end 446.367916 -223.89973)
		(width 0.20066)
		(layer "F.Cu")
		(net "M_G_CPU0_SB_DQ<7>")
	)
	(segment
		(start 439.923682 -223.666558)
		(end 441.028582 -223.666558)
		(width 0.20066)
		(layer "F.Cu")
		(net "M_G_CPU0_SB_DQ<7>")
	)
	(segment
		(start 445.482726 -224.103692)
		(end 446.163954 -224.103692)
		(width 0.20066)
		(layer "F.Cu")
		(net "M_G_CPU0_SB_DQ<7>")
	)
	(segment
		(start 446.367916 -223.648778)
		(end 446.602104 -223.41459)
		(width 0.20066)
		(layer "F.Cu")
		(net "M_G_CPU0_SB_DQ<7>")
	)
	(segment
		(start 445.470534 -224.0915)
		(end 445.482726 -224.103692)
		(width 0.1016)
		(layer "F.Cu")
		(net "M_G_CPU0_SB_DQ<7>")
	)
	(segment
		(start 420.106094 -229.316026)
		(end 419.01364 -229.316026)
		(width 0.18288)
		(layer "In6.Cu")
		(net "M_G_CPU0_SB_DQ<7>")
	)
	(segment
		(start 434.194458 -224.092262)
		(end 433.161694 -225.125026)
		(width 0.18288)
		(layer "In6.Cu")
		(net "M_G_CPU0_SB_DQ<7>")
	)
	(segment
		(start 420.229792 -229.192328)
		(end 420.106094 -229.316026)
		(width 0.18288)
		(layer "In6.Cu")
		(net "M_G_CPU0_SB_DQ<7>")
	)
	(segment
		(start 381.948182 -237.736126)
		(end 381.944626 -237.73384)
		(width 0.088646)
		(layer "In6.Cu")
		(net "M_G_CPU0_SB_DQ<7>")
	)
	(segment
		(start 407.011378 -228.342444)
		(end 406.161748 -229.192074)
		(width 0.18288)
		(layer "In6.Cu")
		(net "M_G_CPU0_SB_DQ<7>")
	)
	(segment
		(start 379.134624 -237.739428)
		(end 379.128782 -237.736126)
		(width 0.088646)
		(layer "In6.Cu")
		(net "M_G_CPU0_SB_DQ<7>")
	)
	(segment
		(start 376.684032 -237.736126)
		(end 376.604022 -237.782354)
		(width 0.088646)
		(layer "In6.Cu")
		(net "M_G_CPU0_SB_DQ<7>")
	)
	(segment
		(start 388.162546 -236.745526)
		(end 388.030974 -236.745526)
		(width 0.088646)
		(layer "In6.Cu")
		(net "M_G_CPU0_SB_DQ<7>")
	)
	(segment
		(start 418.83076 -228.556566)
		(end 418.64788 -228.373686)
		(width 0.18288)
		(layer "In6.Cu")
		(net "M_G_CPU0_SB_DQ<7>")
	)
	(segment
		(start 418.32022 -228.373686)
		(end 418.13734 -228.556566)
		(width 0.18288)
		(layer "In6.Cu")
		(net "M_G_CPU0_SB_DQ<7>")
	)
	(segment
		(start 379.128782 -237.736126)
		(end 379.12294 -237.73257)
		(width 0.088646)
		(layer "In6.Cu")
		(net "M_G_CPU0_SB_DQ<7>")
	)
	(segment
		(start 415.324036 -228.093016)
		(end 411.164024 -228.093016)
		(width 0.18288)
		(layer "In6.Cu")
		(net "M_G_CPU0_SB_DQ<7>")
	)
	(segment
		(start 405.080724 -229.005892)
		(end 400.52625 -229.005892)
		(width 0.18288)
		(layer "In6.Cu")
		(net "M_G_CPU0_SB_DQ<7>")
	)
	(segment
		(start 407.694384 -228.342444)
		(end 407.011378 -228.342444)
		(width 0.18288)
		(layer "In6.Cu")
		(net "M_G_CPU0_SB_DQ<7>")
	)
	(segment
		(start 418.64788 -228.373686)
		(end 418.32022 -228.373686)
		(width 0.18288)
		(layer "In6.Cu")
		(net "M_G_CPU0_SB_DQ<7>")
	)
	(segment
		(start 418.13734 -229.133146)
		(end 417.95446 -229.316026)
		(width 0.18288)
		(layer "In6.Cu")
		(net "M_G_CPU0_SB_DQ<7>")
	)
	(segment
		(start 377.249182 -237.736126)
		(end 377.24334 -237.73257)
		(width 0.088646)
		(layer "In6.Cu")
		(net "M_G_CPU0_SB_DQ<7>")
	)
	(segment
		(start 381.008382 -237.736126)
		(end 381.00254 -237.73257)
		(width 0.088646)
		(layer "In6.Cu")
		(net "M_G_CPU0_SB_DQ<7>")
	)
	(segment
		(start 400.52625 -229.005892)
		(end 392.786616 -236.745526)
		(width 0.18288)
		(layer "In6.Cu")
		(net "M_G_CPU0_SB_DQ<7>")
	)
	(segment
		(start 422.27373 -228.342444)
		(end 421.423846 -229.192328)
		(width 0.18288)
		(layer "In6.Cu")
		(net "M_G_CPU0_SB_DQ<7>")
	)
	(segment
		(start 428.551086 -225.810826)
		(end 426.019468 -228.342444)
		(width 0.18288)
		(layer "In6.Cu")
		(net "M_G_CPU0_SB_DQ<7>")
	)
	(segment
		(start 377.255024 -237.739428)
		(end 377.249182 -237.736126)
		(width 0.088646)
		(layer "In6.Cu")
		(net "M_G_CPU0_SB_DQ<7>")
	)
	(segment
		(start 378.188982 -237.736126)
		(end 378.18314 -237.73257)
		(width 0.088646)
		(layer "In6.Cu")
		(net "M_G_CPU0_SB_DQ<7>")
	)
	(segment
		(start 408.570684 -227.736146)
		(end 408.387804 -227.553266)
		(width 0.18288)
		(layer "In6.Cu")
		(net "M_G_CPU0_SB_DQ<7>")
	)
	(segment
		(start 410.914596 -228.342444)
		(end 408.753564 -228.342444)
		(width 0.18288)
		(layer "In6.Cu")
		(net "M_G_CPU0_SB_DQ<7>")
	)
	(segment
		(start 439.923682 -223.666558)
		(end 439.497978 -224.092262)
		(width 0.18288)
		(layer "In6.Cu")
		(net "M_G_CPU0_SB_DQ<7>")
	)
	(segment
		(start 380.068582 -237.736126)
		(end 380.06274 -237.73257)
		(width 0.088646)
		(layer "In6.Cu")
		(net "M_G_CPU0_SB_DQ<7>")
	)
	(segment
		(start 407.877264 -227.736146)
		(end 407.877264 -228.159564)
		(width 0.18288)
		(layer "In6.Cu")
		(net "M_G_CPU0_SB_DQ<7>")
	)
	(segment
		(start 392.786616 -236.745526)
		(end 388.162546 -236.745526)
		(width 0.18288)
		(layer "In6.Cu")
		(net "M_G_CPU0_SB_DQ<7>")
	)
	(segment
		(start 380.074424 -237.739428)
		(end 380.068582 -237.736126)
		(width 0.088646)
		(layer "In6.Cu")
		(net "M_G_CPU0_SB_DQ<7>")
	)
	(segment
		(start 407.877264 -228.159564)
		(end 407.694384 -228.342444)
		(width 0.18288)
		(layer "In6.Cu")
		(net "M_G_CPU0_SB_DQ<7>")
	)
	(segment
		(start 433.161694 -225.125026)
		(end 431.536094 -225.125026)
		(width 0.18288)
		(layer "In6.Cu")
		(net "M_G_CPU0_SB_DQ<7>")
	)
	(segment
		(start 408.753564 -228.342444)
		(end 408.570684 -228.159564)
		(width 0.18288)
		(layer "In6.Cu")
		(net "M_G_CPU0_SB_DQ<7>")
	)
	(segment
		(start 418.13734 -228.556566)
		(end 418.13734 -229.133146)
		(width 0.18288)
		(layer "In6.Cu")
		(net "M_G_CPU0_SB_DQ<7>")
	)
	(segment
		(start 411.164024 -228.093016)
		(end 410.914596 -228.342444)
		(width 0.18288)
		(layer "In6.Cu")
		(net "M_G_CPU0_SB_DQ<7>")
	)
	(segment
		(start 417.95446 -229.316026)
		(end 416.547046 -229.316026)
		(width 0.18288)
		(layer "In6.Cu")
		(net "M_G_CPU0_SB_DQ<7>")
	)
	(segment
		(start 381.014224 -237.739428)
		(end 381.008382 -237.736126)
		(width 0.088646)
		(layer "In6.Cu")
		(net "M_G_CPU0_SB_DQ<7>")
	)
	(segment
		(start 426.019468 -228.342444)
		(end 422.27373 -228.342444)
		(width 0.18288)
		(layer "In6.Cu")
		(net "M_G_CPU0_SB_DQ<7>")
	)
	(segment
		(start 439.497978 -224.092262)
		(end 434.194458 -224.092262)
		(width 0.18288)
		(layer "In6.Cu")
		(net "M_G_CPU0_SB_DQ<7>")
	)
	(segment
		(start 430.850294 -225.810826)
		(end 428.551086 -225.810826)
		(width 0.18288)
		(layer "In6.Cu")
		(net "M_G_CPU0_SB_DQ<7>")
	)
	(segment
		(start 408.570684 -228.159564)
		(end 408.570684 -227.736146)
		(width 0.18288)
		(layer "In6.Cu")
		(net "M_G_CPU0_SB_DQ<7>")
	)
	(segment
		(start 419.01364 -229.316026)
		(end 418.83076 -229.133146)
		(width 0.18288)
		(layer "In6.Cu")
		(net "M_G_CPU0_SB_DQ<7>")
	)
	(segment
		(start 378.194824 -237.739428)
		(end 378.188982 -237.736126)
		(width 0.088646)
		(layer "In6.Cu")
		(net "M_G_CPU0_SB_DQ<7>")
	)
	(segment
		(start 416.547046 -229.316026)
		(end 415.324036 -228.093016)
		(width 0.18288)
		(layer "In6.Cu")
		(net "M_G_CPU0_SB_DQ<7>")
	)
	(segment
		(start 418.83076 -229.133146)
		(end 418.83076 -228.556566)
		(width 0.18288)
		(layer "In6.Cu")
		(net "M_G_CPU0_SB_DQ<7>")
	)
	(segment
		(start 406.161748 -229.192074)
		(end 405.266906 -229.192074)
		(width 0.18288)
		(layer "In6.Cu")
		(net "M_G_CPU0_SB_DQ<7>")
	)
	(segment
		(start 421.423846 -229.192328)
		(end 420.229792 -229.192328)
		(width 0.18288)
		(layer "In6.Cu")
		(net "M_G_CPU0_SB_DQ<7>")
	)
	(segment
		(start 382.322832 -237.735872)
		(end 382.322832 -237.736126)
		(width 0.088646)
		(layer "In6.Cu")
		(net "M_G_CPU0_SB_DQ<7>")
	)
	(segment
		(start 408.060144 -227.553266)
		(end 407.877264 -227.736146)
		(width 0.18288)
		(layer "In6.Cu")
		(net "M_G_CPU0_SB_DQ<7>")
	)
	(segment
		(start 431.536094 -225.125026)
		(end 430.850294 -225.810826)
		(width 0.18288)
		(layer "In6.Cu")
		(net "M_G_CPU0_SB_DQ<7>")
	)
	(segment
		(start 408.387804 -227.553266)
		(end 408.060144 -227.553266)
		(width 0.18288)
		(layer "In6.Cu")
		(net "M_G_CPU0_SB_DQ<7>")
	)
	(segment
		(start 405.266906 -229.192074)
		(end 405.080724 -229.005892)
		(width 0.18288)
		(layer "In6.Cu")
		(net "M_G_CPU0_SB_DQ<7>")
	)
	(segment
		(start 388.030974 -236.745526)
		(end 387.09981 -237.67669)
		(width 0.088646)
		(layer "In6.Cu")
		(net "M_G_CPU0_SB_DQ<7>")
	)
	(arc
		(start 384.202432 -237.735872)
		(mid 384.015234 -237.786015)
		(end 383.828036 -237.735872)
		(width 0.088646)
		(layer "In6.Cu")
		(net "M_G_CPU0_SB_DQ<7>")
	)
	(arc
		(start 387.09981 -237.67669)
		(mid 387.06276 -237.708836)
		(end 387.021832 -237.735872)
		(width 0.088646)
		(layer "In6.Cu")
		(net "M_G_CPU0_SB_DQ<7>")
	)
	(arc
		(start 379.503432 -237.736126)
		(mid 379.319478 -237.786255)
		(end 379.134624 -237.739428)
		(width 0.088646)
		(layer "In6.Cu")
		(net "M_G_CPU0_SB_DQ<7>")
	)
	(arc
		(start 385.142232 -237.735872)
		(mid 384.955034 -237.786015)
		(end 384.767836 -237.735872)
		(width 0.088646)
		(layer "In6.Cu")
		(net "M_G_CPU0_SB_DQ<7>")
	)
	(arc
		(start 378.18314 -237.73257)
		(mid 377.903005 -237.660287)
		(end 377.623832 -237.736126)
		(width 0.088646)
		(layer "In6.Cu")
		(net "M_G_CPU0_SB_DQ<7>")
	)
	(arc
		(start 376.604022 -237.782354)
		(mid 376.300858 -237.985089)
		(end 376.02668 -238.225584)
		(width 0.088646)
		(layer "In6.Cu")
		(net "M_G_CPU0_SB_DQ<7>")
	)
	(arc
		(start 382.322832 -237.736126)
		(mid 382.135524 -237.786269)
		(end 381.948182 -237.736126)
		(width 0.088646)
		(layer "In6.Cu")
		(net "M_G_CPU0_SB_DQ<7>")
	)
	(arc
		(start 377.24334 -237.73257)
		(mid 376.963205 -237.660287)
		(end 376.684032 -237.736126)
		(width 0.088646)
		(layer "In6.Cu")
		(net "M_G_CPU0_SB_DQ<7>")
	)
	(arc
		(start 387.021832 -237.735872)
		(mid 386.834634 -237.786015)
		(end 386.647436 -237.735872)
		(width 0.088646)
		(layer "In6.Cu")
		(net "M_G_CPU0_SB_DQ<7>")
	)
	(arc
		(start 383.828036 -237.735872)
		(mid 383.545334 -237.66013)
		(end 383.262632 -237.735872)
		(width 0.088646)
		(layer "In6.Cu")
		(net "M_G_CPU0_SB_DQ<7>")
	)
	(arc
		(start 381.00254 -237.73257)
		(mid 380.722405 -237.660287)
		(end 380.443232 -237.736126)
		(width 0.088646)
		(layer "In6.Cu")
		(net "M_G_CPU0_SB_DQ<7>")
	)
	(arc
		(start 386.082032 -237.735872)
		(mid 385.894834 -237.786015)
		(end 385.707636 -237.735872)
		(width 0.088646)
		(layer "In6.Cu")
		(net "M_G_CPU0_SB_DQ<7>")
	)
	(arc
		(start 385.707636 -237.735872)
		(mid 385.424934 -237.66013)
		(end 385.142232 -237.735872)
		(width 0.088646)
		(layer "In6.Cu")
		(net "M_G_CPU0_SB_DQ<7>")
	)
	(arc
		(start 379.12294 -237.73257)
		(mid 378.842805 -237.660287)
		(end 378.563632 -237.736126)
		(width 0.088646)
		(layer "In6.Cu")
		(net "M_G_CPU0_SB_DQ<7>")
	)
	(arc
		(start 381.944626 -237.73384)
		(mid 381.663513 -237.660263)
		(end 381.383032 -237.736126)
		(width 0.088646)
		(layer "In6.Cu")
		(net "M_G_CPU0_SB_DQ<7>")
	)
	(arc
		(start 380.06274 -237.73257)
		(mid 379.782605 -237.660287)
		(end 379.503432 -237.736126)
		(width 0.088646)
		(layer "In6.Cu")
		(net "M_G_CPU0_SB_DQ<7>")
	)
	(arc
		(start 382.888236 -237.735872)
		(mid 382.605534 -237.66013)
		(end 382.322832 -237.735872)
		(width 0.088646)
		(layer "In6.Cu")
		(net "M_G_CPU0_SB_DQ<7>")
	)
	(arc
		(start 377.623832 -237.736126)
		(mid 377.439878 -237.786255)
		(end 377.255024 -237.739428)
		(width 0.088646)
		(layer "In6.Cu")
		(net "M_G_CPU0_SB_DQ<7>")
	)
	(arc
		(start 384.767836 -237.735872)
		(mid 384.485134 -237.66013)
		(end 384.202432 -237.735872)
		(width 0.088646)
		(layer "In6.Cu")
		(net "M_G_CPU0_SB_DQ<7>")
	)
	(arc
		(start 381.383032 -237.736126)
		(mid 381.199078 -237.786255)
		(end 381.014224 -237.739428)
		(width 0.088646)
		(layer "In6.Cu")
		(net "M_G_CPU0_SB_DQ<7>")
	)
	(arc
		(start 380.443232 -237.736126)
		(mid 380.259278 -237.786255)
		(end 380.074424 -237.739428)
		(width 0.088646)
		(layer "In6.Cu")
		(net "M_G_CPU0_SB_DQ<7>")
	)
	(arc
		(start 378.563632 -237.736126)
		(mid 378.379678 -237.786255)
		(end 378.194824 -237.739428)
		(width 0.088646)
		(layer "In6.Cu")
		(net "M_G_CPU0_SB_DQ<7>")
	)
	(arc
		(start 383.262632 -237.735872)
		(mid 383.075434 -237.786015)
		(end 382.888236 -237.735872)
		(width 0.088646)
		(layer "In6.Cu")
		(net "M_G_CPU0_SB_DQ<7>")
	)
	(arc
		(start 386.647436 -237.735872)
		(mid 386.364734 -237.66013)
		(end 386.082032 -237.735872)
		(width 0.088646)
		(layer "In6.Cu")
		(net "M_G_CPU0_SB_DQ<7>")
	)
	(segment
		(start 445.482726 -225.803714)
		(end 446.163954 -225.803714)
		(width 0.20066)
		(layer "F.Cu")
		(net "M_G_CPU0_SB_DQ<6>")
	)
	(segment
		(start 446.367916 -225.599752)
		(end 446.367916 -225.3488)
		(width 0.20066)
		(layer "F.Cu")
		(net "M_G_CPU0_SB_DQ<6>")
	)
	(segment
		(start 439.923682 -225.36658)
		(end 441.028582 -225.36658)
		(width 0.20066)
		(layer "F.Cu")
		(net "M_G_CPU0_SB_DQ<6>")
	)
	(segment
		(start 446.986152 -225.114612)
		(end 447.23812 -225.36658)
		(width 0.20066)
		(layer "F.Cu")
		(net "M_G_CPU0_SB_DQ<6>")
	)
	(segment
		(start 446.602104 -225.114612)
		(end 446.986152 -225.114612)
		(width 0.20066)
		(layer "F.Cu")
		(net "M_G_CPU0_SB_DQ<6>")
	)
	(segment
		(start 441.028582 -225.36658)
		(end 442.726826 -225.36658)
		(width 0.20066)
		(layer "F.Cu")
		(net "M_G_CPU0_SB_DQ<6>")
	)
	(segment
		(start 376.49658 -239.57534)
		(end 376.496834 -239.575086)
		(width 0.20066)
		(layer "F.Cu")
		(net "M_G_CPU0_SB_DQ<6>")
	)
	(segment
		(start 376.496834 -239.575086)
		(end 376.496834 -239.0394)
		(width 0.20066)
		(layer "F.Cu")
		(net "M_G_CPU0_SB_DQ<6>")
	)
	(segment
		(start 443.455552 -225.798634)
		(end 443.462664 -225.791522)
		(width 0.1016)
		(layer "F.Cu")
		(net "M_G_CPU0_SB_DQ<6>")
	)
	(segment
		(start 447.23812 -225.36658)
		(end 448.572382 -225.36658)
		(width 0.20066)
		(layer "F.Cu")
		(net "M_G_CPU0_SB_DQ<6>")
	)
	(segment
		(start 445.470534 -225.791522)
		(end 445.482726 -225.803714)
		(width 0.1016)
		(layer "F.Cu")
		(net "M_G_CPU0_SB_DQ<6>")
	)
	(segment
		(start 446.367916 -225.3488)
		(end 446.602104 -225.114612)
		(width 0.20066)
		(layer "F.Cu")
		(net "M_G_CPU0_SB_DQ<6>")
	)
	(segment
		(start 443.462664 -225.791522)
		(end 445.470534 -225.791522)
		(width 0.1016)
		(layer "F.Cu")
		(net "M_G_CPU0_SB_DQ<6>")
	)
	(segment
		(start 446.163954 -225.803714)
		(end 446.367916 -225.599752)
		(width 0.20066)
		(layer "F.Cu")
		(net "M_G_CPU0_SB_DQ<6>")
	)
	(segment
		(start 443.15888 -225.798634)
		(end 443.450726 -225.798634)
		(width 0.20066)
		(layer "F.Cu")
		(net "M_G_CPU0_SB_DQ<6>")
	)
	(segment
		(start 443.450726 -225.798634)
		(end 443.455552 -225.798634)
		(width 0.101854)
		(layer "F.Cu")
		(net "M_G_CPU0_SB_DQ<6>")
	)
	(segment
		(start 442.726826 -225.36658)
		(end 443.15888 -225.798634)
		(width 0.20066)
		(layer "F.Cu")
		(net "M_G_CPU0_SB_DQ<6>")
	)
	(segment
		(start 434.34381 -225.79203)
		(end 433.969414 -226.166426)
		(width 0.18288)
		(layer "In6.Cu")
		(net "M_G_CPU0_SB_DQ<6>")
	)
	(segment
		(start 402.373084 -230.83012)
		(end 402.373084 -231.048052)
		(width 0.18288)
		(layer "In6.Cu")
		(net "M_G_CPU0_SB_DQ<6>")
	)
	(segment
		(start 402.190204 -231.230932)
		(end 401.862544 -231.230932)
		(width 0.18288)
		(layer "In6.Cu")
		(net "M_G_CPU0_SB_DQ<6>")
	)
	(segment
		(start 430.792128 -227.614226)
		(end 429.200818 -227.614226)
		(width 0.18288)
		(layer "In6.Cu")
		(net "M_G_CPU0_SB_DQ<6>")
	)
	(segment
		(start 408.103578 -230.042212)
		(end 406.984708 -230.042212)
		(width 0.18288)
		(layer "In6.Cu")
		(net "M_G_CPU0_SB_DQ<6>")
	)
	(segment
		(start 378.101098 -238.545624)
		(end 378.093732 -238.549942)
		(width 0.088646)
		(layer "In6.Cu")
		(net "M_G_CPU0_SB_DQ<6>")
	)
	(segment
		(start 403.759924 -231.048052)
		(end 403.577044 -231.230932)
		(width 0.18288)
		(layer "In6.Cu")
		(net "M_G_CPU0_SB_DQ<6>")
	)
	(segment
		(start 411.654498 -229.916482)
		(end 411.528768 -230.042212)
		(width 0.18288)
		(layer "In6.Cu")
		(net "M_G_CPU0_SB_DQ<6>")
	)
	(segment
		(start 402.883624 -230.64724)
		(end 402.555964 -230.64724)
		(width 0.18288)
		(layer "In6.Cu")
		(net "M_G_CPU0_SB_DQ<6>")
	)
	(segment
		(start 439.923682 -225.36658)
		(end 439.502042 -224.94494)
		(width 0.18288)
		(layer "In6.Cu")
		(net "M_G_CPU0_SB_DQ<6>")
	)
	(segment
		(start 428.83963 -228.74351)
		(end 428.581058 -228.74351)
		(width 0.18288)
		(layer "In6.Cu")
		(net "M_G_CPU0_SB_DQ<6>")
	)
	(segment
		(start 402.373084 -231.048052)
		(end 402.190204 -231.230932)
		(width 0.18288)
		(layer "In6.Cu")
		(net "M_G_CPU0_SB_DQ<6>")
	)
	(segment
		(start 377.161298 -238.545624)
		(end 377.050046 -238.611156)
		(width 0.088646)
		(layer "In6.Cu")
		(net "M_G_CPU0_SB_DQ<6>")
	)
	(segment
		(start 425.871894 -230.042212)
		(end 424.167046 -230.042212)
		(width 0.18288)
		(layer "In6.Cu")
		(net "M_G_CPU0_SB_DQ<6>")
	)
	(segment
		(start 403.577044 -231.230932)
		(end 403.249384 -231.230932)
		(width 0.18288)
		(layer "In6.Cu")
		(net "M_G_CPU0_SB_DQ<6>")
	)
	(segment
		(start 428.946056 -228.12756)
		(end 429.071532 -228.253036)
		(width 0.18288)
		(layer "In6.Cu")
		(net "M_G_CPU0_SB_DQ<6>")
	)
	(segment
		(start 428.946056 -227.868988)
		(end 428.946056 -228.12756)
		(width 0.18288)
		(layer "In6.Cu")
		(net "M_G_CPU0_SB_DQ<6>")
	)
	(segment
		(start 379.033532 -238.549942)
		(end 379.02896 -238.552736)
		(width 0.088646)
		(layer "In6.Cu")
		(net "M_G_CPU0_SB_DQ<6>")
	)
	(segment
		(start 424.167046 -230.042212)
		(end 423.823892 -230.385366)
		(width 0.18288)
		(layer "In6.Cu")
		(net "M_G_CPU0_SB_DQ<6>")
	)
	(segment
		(start 403.759924 -230.83012)
		(end 403.759924 -231.048052)
		(width 0.18288)
		(layer "In6.Cu")
		(net "M_G_CPU0_SB_DQ<6>")
	)
	(segment
		(start 400.50593 -230.64724)
		(end 393.261596 -237.891574)
		(width 0.18288)
		(layer "In6.Cu")
		(net "M_G_CPU0_SB_DQ<6>")
	)
	(segment
		(start 431.731928 -226.674426)
		(end 430.792128 -227.614226)
		(width 0.18288)
		(layer "In6.Cu")
		(net "M_G_CPU0_SB_DQ<6>")
	)
	(segment
		(start 412.968694 -230.314246)
		(end 412.57093 -229.916482)
		(width 0.18288)
		(layer "In6.Cu")
		(net "M_G_CPU0_SB_DQ<6>")
	)
	(segment
		(start 422.276524 -230.042212)
		(end 421.42664 -230.892096)
		(width 0.18288)
		(layer "In6.Cu")
		(net "M_G_CPU0_SB_DQ<6>")
	)
	(segment
		(start 433.969414 -226.166426)
		(end 433.529486 -226.166426)
		(width 0.18288)
		(layer "In6.Cu")
		(net "M_G_CPU0_SB_DQ<6>")
	)
	(segment
		(start 406.150572 -230.891588)
		(end 405.378412 -230.891588)
		(width 0.18288)
		(layer "In6.Cu")
		(net "M_G_CPU0_SB_DQ<6>")
	)
	(segment
		(start 401.862544 -231.230932)
		(end 401.679664 -231.048052)
		(width 0.18288)
		(layer "In6.Cu")
		(net "M_G_CPU0_SB_DQ<6>")
	)
	(segment
		(start 382.418336 -238.549942)
		(end 382.418082 -238.549942)
		(width 0.088646)
		(layer "In6.Cu")
		(net "M_G_CPU0_SB_DQ<6>")
	)
	(segment
		(start 401.496784 -230.64724)
		(end 400.50593 -230.64724)
		(width 0.18288)
		(layer "In6.Cu")
		(net "M_G_CPU0_SB_DQ<6>")
	)
	(segment
		(start 423.823892 -230.385366)
		(end 423.473626 -230.385366)
		(width 0.18288)
		(layer "In6.Cu")
		(net "M_G_CPU0_SB_DQ<6>")
	)
	(segment
		(start 406.984708 -230.042212)
		(end 406.451308 -230.575612)
		(width 0.18288)
		(layer "In6.Cu")
		(net "M_G_CPU0_SB_DQ<6>")
	)
	(segment
		(start 403.942804 -230.64724)
		(end 403.759924 -230.83012)
		(width 0.18288)
		(layer "In6.Cu")
		(net "M_G_CPU0_SB_DQ<6>")
	)
	(segment
		(start 403.066504 -231.048052)
		(end 403.066504 -230.83012)
		(width 0.18288)
		(layer "In6.Cu")
		(net "M_G_CPU0_SB_DQ<6>")
	)
	(segment
		(start 405.378412 -230.891588)
		(end 405.134064 -230.64724)
		(width 0.18288)
		(layer "In6.Cu")
		(net "M_G_CPU0_SB_DQ<6>")
	)
	(segment
		(start 403.066504 -230.83012)
		(end 402.883624 -230.64724)
		(width 0.18288)
		(layer "In6.Cu")
		(net "M_G_CPU0_SB_DQ<6>")
	)
	(segment
		(start 429.071532 -228.511608)
		(end 428.83963 -228.74351)
		(width 0.18288)
		(layer "In6.Cu")
		(net "M_G_CPU0_SB_DQ<6>")
	)
	(segment
		(start 428.455582 -228.618034)
		(end 428.19701 -228.618034)
		(width 0.18288)
		(layer "In6.Cu")
		(net "M_G_CPU0_SB_DQ<6>")
	)
	(segment
		(start 433.021486 -226.674426)
		(end 431.731928 -226.674426)
		(width 0.18288)
		(layer "In6.Cu")
		(net "M_G_CPU0_SB_DQ<6>")
	)
	(segment
		(start 379.973332 -238.549942)
		(end 379.96876 -238.552736)
		(width 0.088646)
		(layer "In6.Cu")
		(net "M_G_CPU0_SB_DQ<6>")
	)
	(segment
		(start 406.451308 -230.575612)
		(end 406.451308 -230.590852)
		(width 0.18288)
		(layer "In6.Cu")
		(net "M_G_CPU0_SB_DQ<6>")
	)
	(segment
		(start 379.980698 -238.545624)
		(end 379.973332 -238.549942)
		(width 0.088646)
		(layer "In6.Cu")
		(net "M_G_CPU0_SB_DQ<6>")
	)
	(segment
		(start 376.497088 -239.039146)
		(end 376.496834 -239.0394)
		(width 0.088646)
		(layer "In6.Cu")
		(net "M_G_CPU0_SB_DQ<6>")
	)
	(segment
		(start 403.249384 -231.230932)
		(end 403.066504 -231.048052)
		(width 0.18288)
		(layer "In6.Cu")
		(net "M_G_CPU0_SB_DQ<6>")
	)
	(segment
		(start 439.502042 -224.94494)
		(end 437.857392 -224.94494)
		(width 0.18288)
		(layer "In6.Cu")
		(net "M_G_CPU0_SB_DQ<6>")
	)
	(segment
		(start 387.383274 -238.566198)
		(end 387.177534 -238.566198)
		(width 0.088646)
		(layer "In6.Cu")
		(net "M_G_CPU0_SB_DQ<6>")
	)
	(segment
		(start 437.010302 -225.79203)
		(end 434.34381 -225.79203)
		(width 0.18288)
		(layer "In6.Cu")
		(net "M_G_CPU0_SB_DQ<6>")
	)
	(segment
		(start 414.999678 -230.892096)
		(end 414.421828 -230.314246)
		(width 0.18288)
		(layer "In6.Cu")
		(net "M_G_CPU0_SB_DQ<6>")
	)
	(segment
		(start 437.857392 -224.94494)
		(end 437.010302 -225.79203)
		(width 0.18288)
		(layer "In6.Cu")
		(net "M_G_CPU0_SB_DQ<6>")
	)
	(segment
		(start 393.261596 -237.891574)
		(end 388.382764 -237.891574)
		(width 0.18288)
		(layer "In6.Cu")
		(net "M_G_CPU0_SB_DQ<6>")
	)
	(segment
		(start 380.913132 -238.549942)
		(end 380.90856 -238.552736)
		(width 0.088646)
		(layer "In6.Cu")
		(net "M_G_CPU0_SB_DQ<6>")
	)
	(segment
		(start 405.134064 -230.64724)
		(end 403.942804 -230.64724)
		(width 0.18288)
		(layer "In6.Cu")
		(net "M_G_CPU0_SB_DQ<6>")
	)
	(segment
		(start 409.141422 -230.042212)
		(end 408.796998 -230.386636)
		(width 0.18288)
		(layer "In6.Cu")
		(net "M_G_CPU0_SB_DQ<6>")
	)
	(segment
		(start 428.581058 -228.74351)
		(end 428.455582 -228.618034)
		(width 0.18288)
		(layer "In6.Cu")
		(net "M_G_CPU0_SB_DQ<6>")
	)
	(segment
		(start 414.421828 -230.314246)
		(end 412.968694 -230.314246)
		(width 0.18288)
		(layer "In6.Cu")
		(net "M_G_CPU0_SB_DQ<6>")
	)
	(segment
		(start 388.382764 -237.891574)
		(end 388.057898 -237.891574)
		(width 0.088646)
		(layer "In6.Cu")
		(net "M_G_CPU0_SB_DQ<6>")
	)
	(segment
		(start 401.679664 -231.048052)
		(end 401.679664 -230.83012)
		(width 0.18288)
		(layer "In6.Cu")
		(net "M_G_CPU0_SB_DQ<6>")
	)
	(segment
		(start 412.57093 -229.916482)
		(end 411.654498 -229.916482)
		(width 0.18288)
		(layer "In6.Cu")
		(net "M_G_CPU0_SB_DQ<6>")
	)
	(segment
		(start 378.093732 -238.549942)
		(end 378.08916 -238.552736)
		(width 0.088646)
		(layer "In6.Cu")
		(net "M_G_CPU0_SB_DQ<6>")
	)
	(segment
		(start 408.448002 -230.386636)
		(end 408.103578 -230.042212)
		(width 0.18288)
		(layer "In6.Cu")
		(net "M_G_CPU0_SB_DQ<6>")
	)
	(segment
		(start 401.679664 -230.83012)
		(end 401.496784 -230.64724)
		(width 0.18288)
		(layer "In6.Cu")
		(net "M_G_CPU0_SB_DQ<6>")
	)
	(segment
		(start 380.920498 -238.545624)
		(end 380.913132 -238.549942)
		(width 0.088646)
		(layer "In6.Cu")
		(net "M_G_CPU0_SB_DQ<6>")
	)
	(segment
		(start 379.040898 -238.545624)
		(end 379.033532 -238.549942)
		(width 0.088646)
		(layer "In6.Cu")
		(net "M_G_CPU0_SB_DQ<6>")
	)
	(segment
		(start 429.071532 -228.253036)
		(end 429.071532 -228.511608)
		(width 0.18288)
		(layer "In6.Cu")
		(net "M_G_CPU0_SB_DQ<6>")
	)
	(segment
		(start 429.200818 -227.614226)
		(end 428.946056 -227.868988)
		(width 0.18288)
		(layer "In6.Cu")
		(net "M_G_CPU0_SB_DQ<6>")
	)
	(segment
		(start 433.529486 -226.166426)
		(end 433.021486 -226.674426)
		(width 0.18288)
		(layer "In6.Cu")
		(net "M_G_CPU0_SB_DQ<6>")
	)
	(segment
		(start 411.528768 -230.042212)
		(end 409.141422 -230.042212)
		(width 0.18288)
		(layer "In6.Cu")
		(net "M_G_CPU0_SB_DQ<6>")
	)
	(segment
		(start 423.473626 -230.385366)
		(end 423.130472 -230.042212)
		(width 0.18288)
		(layer "In6.Cu")
		(net "M_G_CPU0_SB_DQ<6>")
	)
	(segment
		(start 423.130472 -230.042212)
		(end 422.276524 -230.042212)
		(width 0.18288)
		(layer "In6.Cu")
		(net "M_G_CPU0_SB_DQ<6>")
	)
	(segment
		(start 388.057898 -237.891574)
		(end 387.383274 -238.566198)
		(width 0.088646)
		(layer "In6.Cu")
		(net "M_G_CPU0_SB_DQ<6>")
	)
	(segment
		(start 428.19701 -228.618034)
		(end 427.295056 -229.519988)
		(width 0.18288)
		(layer "In6.Cu")
		(net "M_G_CPU0_SB_DQ<6>")
	)
	(segment
		(start 381.852932 -238.549942)
		(end 381.850392 -238.551466)
		(width 0.088646)
		(layer "In6.Cu")
		(net "M_G_CPU0_SB_DQ<6>")
	)
	(segment
		(start 426.394118 -229.519988)
		(end 425.871894 -230.042212)
		(width 0.18288)
		(layer "In6.Cu")
		(net "M_G_CPU0_SB_DQ<6>")
	)
	(segment
		(start 427.295056 -229.519988)
		(end 426.394118 -229.519988)
		(width 0.18288)
		(layer "In6.Cu")
		(net "M_G_CPU0_SB_DQ<6>")
	)
	(segment
		(start 408.796998 -230.386636)
		(end 408.448002 -230.386636)
		(width 0.18288)
		(layer "In6.Cu")
		(net "M_G_CPU0_SB_DQ<6>")
	)
	(segment
		(start 421.42664 -230.892096)
		(end 414.999678 -230.892096)
		(width 0.18288)
		(layer "In6.Cu")
		(net "M_G_CPU0_SB_DQ<6>")
	)
	(segment
		(start 402.555964 -230.64724)
		(end 402.373084 -230.83012)
		(width 0.18288)
		(layer "In6.Cu")
		(net "M_G_CPU0_SB_DQ<6>")
	)
	(segment
		(start 406.451308 -230.590852)
		(end 406.150572 -230.891588)
		(width 0.18288)
		(layer "In6.Cu")
		(net "M_G_CPU0_SB_DQ<6>")
	)
	(arc
		(start 386.551932 -238.549942)
		(mid 386.364734 -238.600085)
		(end 386.177536 -238.549942)
		(width 0.088646)
		(layer "In6.Cu")
		(net "M_G_CPU0_SB_DQ<6>")
	)
	(arc
		(start 386.177536 -238.549942)
		(mid 385.894834 -238.474166)
		(end 385.612132 -238.549942)
		(width 0.088646)
		(layer "In6.Cu")
		(net "M_G_CPU0_SB_DQ<6>")
	)
	(arc
		(start 379.96876 -238.552736)
		(mid 379.783346 -238.600248)
		(end 379.598682 -238.549942)
		(width 0.088646)
		(layer "In6.Cu")
		(net "M_G_CPU0_SB_DQ<6>")
	)
	(arc
		(start 381.850392 -238.551466)
		(mid 381.664143 -238.600144)
		(end 381.478282 -238.549942)
		(width 0.088646)
		(layer "In6.Cu")
		(net "M_G_CPU0_SB_DQ<6>")
	)
	(arc
		(start 377.719082 -238.549942)
		(mid 377.440759 -238.474183)
		(end 377.161298 -238.545624)
		(width 0.088646)
		(layer "In6.Cu")
		(net "M_G_CPU0_SB_DQ<6>")
	)
	(arc
		(start 387.177534 -238.566198)
		(mid 387.146352 -238.562072)
		(end 387.117336 -238.549942)
		(width 0.088646)
		(layer "In6.Cu")
		(net "M_G_CPU0_SB_DQ<6>")
	)
	(arc
		(start 385.612132 -238.549942)
		(mid 385.424934 -238.600085)
		(end 385.237736 -238.549942)
		(width 0.088646)
		(layer "In6.Cu")
		(net "M_G_CPU0_SB_DQ<6>")
	)
	(arc
		(start 381.478282 -238.549942)
		(mid 381.199959 -238.474183)
		(end 380.920498 -238.545624)
		(width 0.088646)
		(layer "In6.Cu")
		(net "M_G_CPU0_SB_DQ<6>")
	)
	(arc
		(start 384.672332 -238.549942)
		(mid 384.485134 -238.600085)
		(end 384.297936 -238.549942)
		(width 0.088646)
		(layer "In6.Cu")
		(net "M_G_CPU0_SB_DQ<6>")
	)
	(arc
		(start 379.598682 -238.549942)
		(mid 379.320359 -238.474183)
		(end 379.040898 -238.545624)
		(width 0.088646)
		(layer "In6.Cu")
		(net "M_G_CPU0_SB_DQ<6>")
	)
	(arc
		(start 385.237736 -238.549942)
		(mid 384.955034 -238.474166)
		(end 384.672332 -238.549942)
		(width 0.088646)
		(layer "In6.Cu")
		(net "M_G_CPU0_SB_DQ<6>")
	)
	(arc
		(start 384.297936 -238.549942)
		(mid 384.015234 -238.474166)
		(end 383.732532 -238.549942)
		(width 0.088646)
		(layer "In6.Cu")
		(net "M_G_CPU0_SB_DQ<6>")
	)
	(arc
		(start 383.732532 -238.549942)
		(mid 383.545334 -238.600085)
		(end 383.358136 -238.549942)
		(width 0.088646)
		(layer "In6.Cu")
		(net "M_G_CPU0_SB_DQ<6>")
	)
	(arc
		(start 387.117336 -238.549942)
		(mid 386.834634 -238.474166)
		(end 386.551932 -238.549942)
		(width 0.088646)
		(layer "In6.Cu")
		(net "M_G_CPU0_SB_DQ<6>")
	)
	(arc
		(start 380.90856 -238.552736)
		(mid 380.723146 -238.600248)
		(end 380.538482 -238.549942)
		(width 0.088646)
		(layer "In6.Cu")
		(net "M_G_CPU0_SB_DQ<6>")
	)
	(arc
		(start 379.02896 -238.552736)
		(mid 378.843546 -238.600248)
		(end 378.658882 -238.549942)
		(width 0.088646)
		(layer "In6.Cu")
		(net "M_G_CPU0_SB_DQ<6>")
	)
	(arc
		(start 382.418082 -238.549942)
		(mid 382.135524 -238.474293)
		(end 381.852932 -238.549942)
		(width 0.088646)
		(layer "In6.Cu")
		(net "M_G_CPU0_SB_DQ<6>")
	)
	(arc
		(start 382.792732 -238.549942)
		(mid 382.605534 -238.600085)
		(end 382.418336 -238.549942)
		(width 0.088646)
		(layer "In6.Cu")
		(net "M_G_CPU0_SB_DQ<6>")
	)
	(arc
		(start 380.538482 -238.549942)
		(mid 380.260159 -238.474183)
		(end 379.980698 -238.545624)
		(width 0.088646)
		(layer "In6.Cu")
		(net "M_G_CPU0_SB_DQ<6>")
	)
	(arc
		(start 378.08916 -238.552736)
		(mid 377.903746 -238.600248)
		(end 377.719082 -238.549942)
		(width 0.088646)
		(layer "In6.Cu")
		(net "M_G_CPU0_SB_DQ<6>")
	)
	(arc
		(start 383.358136 -238.549942)
		(mid 383.075434 -238.474166)
		(end 382.792732 -238.549942)
		(width 0.088646)
		(layer "In6.Cu")
		(net "M_G_CPU0_SB_DQ<6>")
	)
	(arc
		(start 377.050046 -238.611156)
		(mid 376.760022 -238.80765)
		(end 376.497088 -239.039146)
		(width 0.088646)
		(layer "In6.Cu")
		(net "M_G_CPU0_SB_DQ<6>")
	)
	(arc
		(start 378.658882 -238.549942)
		(mid 378.380559 -238.474183)
		(end 378.101098 -238.545624)
		(width 0.088646)
		(layer "In6.Cu")
		(net "M_G_CPU0_SB_DQ<6>")
	)
	(segment
		(start 442.44895 -224.085404)
		(end 442.038994 -224.085404)
		(width 0.20066)
		(layer "F.Cu")
		(net "M_G_CPU0_SB_DQ<5>")
	)
	(segment
		(start 442.032644 -224.091754)
		(end 439.843926 -224.091754)
		(width 0.1016)
		(layer "F.Cu")
		(net "M_G_CPU0_SB_DQ<5>")
	)
	(segment
		(start 439.173112 -224.765362)
		(end 438.697878 -224.765362)
		(width 0.20066)
		(layer "F.Cu")
		(net "M_G_CPU0_SB_DQ<5>")
	)
	(segment
		(start 436.928514 -224.516696)
		(end 435.823614 -224.516696)
		(width 0.20066)
		(layer "F.Cu")
		(net "M_G_CPU0_SB_DQ<5>")
	)
	(segment
		(start 444.472314 -224.516696)
		(end 444.47206 -224.51695)
		(width 0.20066)
		(layer "F.Cu")
		(net "M_G_CPU0_SB_DQ<5>")
	)
	(segment
		(start 444.47206 -224.51695)
		(end 442.880496 -224.51695)
		(width 0.20066)
		(layer "F.Cu")
		(net "M_G_CPU0_SB_DQ<5>")
	)
	(segment
		(start 442.880496 -224.51695)
		(end 442.44895 -224.085404)
		(width 0.20066)
		(layer "F.Cu")
		(net "M_G_CPU0_SB_DQ<5>")
	)
	(segment
		(start 439.479182 -224.091754)
		(end 439.361072 -224.209864)
		(width 0.20066)
		(layer "F.Cu")
		(net "M_G_CPU0_SB_DQ<5>")
	)
	(segment
		(start 439.361072 -224.209864)
		(end 439.361072 -224.577402)
		(width 0.20066)
		(layer "F.Cu")
		(net "M_G_CPU0_SB_DQ<5>")
	)
	(segment
		(start 375.087134 -238.761524)
		(end 375.08688 -238.76127)
		(width 0.20066)
		(layer "F.Cu")
		(net "M_G_CPU0_SB_DQ<5>")
	)
	(segment
		(start 439.843926 -224.091754)
		(end 439.82386 -224.091754)
		(width 0.101854)
		(layer "F.Cu")
		(net "M_G_CPU0_SB_DQ<5>")
	)
	(segment
		(start 438.697878 -224.765362)
		(end 438.449212 -224.516696)
		(width 0.20066)
		(layer "F.Cu")
		(net "M_G_CPU0_SB_DQ<5>")
	)
	(segment
		(start 439.361072 -224.577402)
		(end 439.173112 -224.765362)
		(width 0.20066)
		(layer "F.Cu")
		(net "M_G_CPU0_SB_DQ<5>")
	)
	(segment
		(start 442.038994 -224.085404)
		(end 442.032644 -224.091754)
		(width 0.1016)
		(layer "F.Cu")
		(net "M_G_CPU0_SB_DQ<5>")
	)
	(segment
		(start 438.449212 -224.516696)
		(end 436.928514 -224.516696)
		(width 0.20066)
		(layer "F.Cu")
		(net "M_G_CPU0_SB_DQ<5>")
	)
	(segment
		(start 439.82386 -224.091754)
		(end 439.479182 -224.091754)
		(width 0.20066)
		(layer "F.Cu")
		(net "M_G_CPU0_SB_DQ<5>")
	)
	(segment
		(start 375.08688 -238.76127)
		(end 375.08688 -238.225584)
		(width 0.20066)
		(layer "F.Cu")
		(net "M_G_CPU0_SB_DQ<5>")
	)
	(segment
		(start 410.71038 -229.005892)
		(end 410.71038 -229.24516)
		(width 0.18288)
		(layer "In6.Cu")
		(net "M_G_CPU0_SB_DQ<5>")
	)
	(segment
		(start 414.77565 -229.606348)
		(end 415.27603 -229.105968)
		(width 0.18288)
		(layer "In6.Cu")
		(net "M_G_CPU0_SB_DQ<5>")
	)
	(segment
		(start 411.24378 -228.845872)
		(end 410.8704 -228.845872)
		(width 0.18288)
		(layer "In6.Cu")
		(net "M_G_CPU0_SB_DQ<5>")
	)
	(segment
		(start 402.682456 -229.858824)
		(end 402.682456 -229.7049)
		(width 0.18288)
		(layer "In6.Cu")
		(net "M_G_CPU0_SB_DQ<5>")
	)
	(segment
		(start 423.423588 -229.192074)
		(end 422.338246 -229.192074)
		(width 0.18288)
		(layer "In6.Cu")
		(net "M_G_CPU0_SB_DQ<5>")
	)
	(segment
		(start 381.852932 -237.900972)
		(end 381.848614 -237.898432)
		(width 0.088646)
		(layer "In6.Cu")
		(net "M_G_CPU0_SB_DQ<5>")
	)
	(segment
		(start 404.069296 -229.858824)
		(end 404.069296 -229.7049)
		(width 0.18288)
		(layer "In6.Cu")
		(net "M_G_CPU0_SB_DQ<5>")
	)
	(segment
		(start 410.8704 -228.845872)
		(end 410.71038 -229.005892)
		(width 0.18288)
		(layer "In6.Cu")
		(net "M_G_CPU0_SB_DQ<5>")
	)
	(segment
		(start 378.093732 -237.900972)
		(end 378.08789 -237.89767)
		(width 0.088646)
		(layer "In6.Cu")
		(net "M_G_CPU0_SB_DQ<5>")
	)
	(segment
		(start 433.390294 -225.683826)
		(end 431.713894 -225.683826)
		(width 0.18288)
		(layer "In6.Cu")
		(net "M_G_CPU0_SB_DQ<5>")
	)
	(segment
		(start 401.806156 -230.041704)
		(end 400.380454 -230.041704)
		(width 0.18288)
		(layer "In6.Cu")
		(net "M_G_CPU0_SB_DQ<5>")
	)
	(segment
		(start 401.989036 -229.7049)
		(end 401.989036 -229.858824)
		(width 0.18288)
		(layer "In6.Cu")
		(net "M_G_CPU0_SB_DQ<5>")
	)
	(segment
		(start 418.308028 -230.392986)
		(end 418.125148 -230.210106)
		(width 0.18288)
		(layer "In6.Cu")
		(net "M_G_CPU0_SB_DQ<5>")
	)
	(segment
		(start 402.865336 -230.041704)
		(end 402.682456 -229.858824)
		(width 0.18288)
		(layer "In6.Cu")
		(net "M_G_CPU0_SB_DQ<5>")
	)
	(segment
		(start 376.561096 -238.410242)
		(end 376.298206 -238.673132)
		(width 0.088646)
		(layer "In6.Cu")
		(net "M_G_CPU0_SB_DQ<5>")
	)
	(segment
		(start 415.142934 -230.199692)
		(end 414.77565 -229.832408)
		(width 0.18288)
		(layer "In6.Cu")
		(net "M_G_CPU0_SB_DQ<5>")
	)
	(segment
		(start 387.94309 -237.374684)
		(end 387.506464 -237.81131)
		(width 0.088646)
		(layer "In6.Cu")
		(net "M_G_CPU0_SB_DQ<5>")
	)
	(segment
		(start 419.001448 -229.874826)
		(end 418.818568 -230.057706)
		(width 0.18288)
		(layer "In6.Cu")
		(net "M_G_CPU0_SB_DQ<5>")
	)
	(segment
		(start 424.405806 -229.192074)
		(end 424.117008 -229.480872)
		(width 0.18288)
		(layer "In6.Cu")
		(net "M_G_CPU0_SB_DQ<5>")
	)
	(segment
		(start 375.08688 -238.225838)
		(end 375.08688 -238.225584)
		(width 0.088646)
		(layer "In6.Cu")
		(net "M_G_CPU0_SB_DQ<5>")
	)
	(segment
		(start 414.285176 -229.115874)
		(end 414.059116 -229.115874)
		(width 0.18288)
		(layer "In6.Cu")
		(net "M_G_CPU0_SB_DQ<5>")
	)
	(segment
		(start 404.069296 -229.7049)
		(end 403.886416 -229.52202)
		(width 0.18288)
		(layer "In6.Cu")
		(net "M_G_CPU0_SB_DQ<5>")
	)
	(segment
		(start 409.939998 -229.192074)
		(end 406.971246 -229.192074)
		(width 0.18288)
		(layer "In6.Cu")
		(net "M_G_CPU0_SB_DQ<5>")
	)
	(segment
		(start 424.117008 -229.480872)
		(end 423.712386 -229.480872)
		(width 0.18288)
		(layer "In6.Cu")
		(net "M_G_CPU0_SB_DQ<5>")
	)
	(segment
		(start 378.099574 -237.904528)
		(end 378.093732 -237.900972)
		(width 0.088646)
		(layer "In6.Cu")
		(net "M_G_CPU0_SB_DQ<5>")
	)
	(segment
		(start 388.382764 -237.374684)
		(end 387.94309 -237.374684)
		(width 0.088646)
		(layer "In6.Cu")
		(net "M_G_CPU0_SB_DQ<5>")
	)
	(segment
		(start 428.176944 -227.880672)
		(end 427.236128 -227.880672)
		(width 0.18288)
		(layer "In6.Cu")
		(net "M_G_CPU0_SB_DQ<5>")
	)
	(segment
		(start 418.818568 -230.057706)
		(end 418.818568 -230.210106)
		(width 0.18288)
		(layer "In6.Cu")
		(net "M_G_CPU0_SB_DQ<5>")
	)
	(segment
		(start 413.087312 -228.633528)
		(end 412.31566 -229.40518)
		(width 0.18288)
		(layer "In6.Cu")
		(net "M_G_CPU0_SB_DQ<5>")
	)
	(segment
		(start 418.125148 -230.210106)
		(end 418.125148 -230.057706)
		(width 0.18288)
		(layer "In6.Cu")
		(net "M_G_CPU0_SB_DQ<5>")
	)
	(segment
		(start 423.712386 -229.480872)
		(end 423.423588 -229.192074)
		(width 0.18288)
		(layer "In6.Cu")
		(net "M_G_CPU0_SB_DQ<5>")
	)
	(segment
		(start 403.886416 -229.52202)
		(end 403.558756 -229.52202)
		(width 0.18288)
		(layer "In6.Cu")
		(net "M_G_CPU0_SB_DQ<5>")
	)
	(segment
		(start 414.785556 -228.615494)
		(end 414.285176 -229.115874)
		(width 0.18288)
		(layer "In6.Cu")
		(net "M_G_CPU0_SB_DQ<5>")
	)
	(segment
		(start 403.192996 -230.041704)
		(end 402.865336 -230.041704)
		(width 0.18288)
		(layer "In6.Cu")
		(net "M_G_CPU0_SB_DQ<5>")
	)
	(segment
		(start 410.153104 -229.40518)
		(end 409.939998 -229.192074)
		(width 0.18288)
		(layer "In6.Cu")
		(net "M_G_CPU0_SB_DQ<5>")
	)
	(segment
		(start 416.714178 -229.874826)
		(end 416.389312 -230.199692)
		(width 0.18288)
		(layer "In6.Cu")
		(net "M_G_CPU0_SB_DQ<5>")
	)
	(segment
		(start 374.960134 -238.577882)
		(end 374.93067 -238.496602)
		(width 0.088646)
		(layer "In6.Cu")
		(net "M_G_CPU0_SB_DQ<5>")
	)
	(segment
		(start 415.011616 -228.615494)
		(end 414.785556 -228.615494)
		(width 0.18288)
		(layer "In6.Cu")
		(net "M_G_CPU0_SB_DQ<5>")
	)
	(segment
		(start 414.059116 -229.115874)
		(end 413.57677 -228.633528)
		(width 0.18288)
		(layer "In6.Cu")
		(net "M_G_CPU0_SB_DQ<5>")
	)
	(segment
		(start 429.618394 -226.439222)
		(end 428.176944 -227.880672)
		(width 0.18288)
		(layer "In6.Cu")
		(net "M_G_CPU0_SB_DQ<5>")
	)
	(segment
		(start 415.27603 -229.105968)
		(end 415.27603 -228.879908)
		(width 0.18288)
		(layer "In6.Cu")
		(net "M_G_CPU0_SB_DQ<5>")
	)
	(segment
		(start 414.77565 -229.832408)
		(end 414.77565 -229.606348)
		(width 0.18288)
		(layer "In6.Cu")
		(net "M_G_CPU0_SB_DQ<5>")
	)
	(segment
		(start 377.153932 -237.900972)
		(end 377.14809 -237.89767)
		(width 0.088646)
		(layer "In6.Cu")
		(net "M_G_CPU0_SB_DQ<5>")
	)
	(segment
		(start 376.298206 -238.673132)
		(end 375.98731 -238.673132)
		(width 0.088646)
		(layer "In6.Cu")
		(net "M_G_CPU0_SB_DQ<5>")
	)
	(segment
		(start 377.159774 -237.904528)
		(end 377.153932 -237.900972)
		(width 0.088646)
		(layer "In6.Cu")
		(net "M_G_CPU0_SB_DQ<5>")
	)
	(segment
		(start 393.047474 -237.374684)
		(end 388.382764 -237.374684)
		(width 0.18288)
		(layer "In6.Cu")
		(net "M_G_CPU0_SB_DQ<5>")
	)
	(segment
		(start 412.31566 -229.40518)
		(end 411.56382 -229.40518)
		(width 0.18288)
		(layer "In6.Cu")
		(net "M_G_CPU0_SB_DQ<5>")
	)
	(segment
		(start 402.171916 -229.52202)
		(end 401.989036 -229.7049)
		(width 0.18288)
		(layer "In6.Cu")
		(net "M_G_CPU0_SB_DQ<5>")
	)
	(segment
		(start 417.942268 -229.874826)
		(end 416.714178 -229.874826)
		(width 0.18288)
		(layer "In6.Cu")
		(net "M_G_CPU0_SB_DQ<5>")
	)
	(segment
		(start 418.125148 -230.057706)
		(end 417.942268 -229.874826)
		(width 0.18288)
		(layer "In6.Cu")
		(net "M_G_CPU0_SB_DQ<5>")
	)
	(segment
		(start 379.039374 -237.904528)
		(end 379.033532 -237.900972)
		(width 0.088646)
		(layer "In6.Cu")
		(net "M_G_CPU0_SB_DQ<5>")
	)
	(segment
		(start 379.973332 -237.900972)
		(end 379.96749 -237.89767)
		(width 0.088646)
		(layer "In6.Cu")
		(net "M_G_CPU0_SB_DQ<5>")
	)
	(segment
		(start 421.488362 -230.041958)
		(end 419.917626 -230.041958)
		(width 0.18288)
		(layer "In6.Cu")
		(net "M_G_CPU0_SB_DQ<5>")
	)
	(segment
		(start 403.375876 -229.858824)
		(end 403.192996 -230.041704)
		(width 0.18288)
		(layer "In6.Cu")
		(net "M_G_CPU0_SB_DQ<5>")
	)
	(segment
		(start 435.823614 -224.516696)
		(end 435.798214 -224.516696)
		(width 0.18288)
		(layer "In6.Cu")
		(net "M_G_CPU0_SB_DQ<5>")
	)
	(segment
		(start 406.971246 -229.192074)
		(end 406.121616 -230.041704)
		(width 0.18288)
		(layer "In6.Cu")
		(net "M_G_CPU0_SB_DQ<5>")
	)
	(segment
		(start 411.4038 -229.005892)
		(end 411.24378 -228.845872)
		(width 0.18288)
		(layer "In6.Cu")
		(net "M_G_CPU0_SB_DQ<5>")
	)
	(segment
		(start 419.750494 -229.874826)
		(end 419.001448 -229.874826)
		(width 0.18288)
		(layer "In6.Cu")
		(net "M_G_CPU0_SB_DQ<5>")
	)
	(segment
		(start 413.57677 -228.633528)
		(end 413.087312 -228.633528)
		(width 0.18288)
		(layer "In6.Cu")
		(net "M_G_CPU0_SB_DQ<5>")
	)
	(segment
		(start 415.27603 -228.879908)
		(end 415.011616 -228.615494)
		(width 0.18288)
		(layer "In6.Cu")
		(net "M_G_CPU0_SB_DQ<5>")
	)
	(segment
		(start 418.635688 -230.392986)
		(end 418.308028 -230.392986)
		(width 0.18288)
		(layer "In6.Cu")
		(net "M_G_CPU0_SB_DQ<5>")
	)
	(segment
		(start 427.236128 -227.880672)
		(end 425.924726 -229.192074)
		(width 0.18288)
		(layer "In6.Cu")
		(net "M_G_CPU0_SB_DQ<5>")
	)
	(segment
		(start 431.713894 -225.683826)
		(end 430.958498 -226.439222)
		(width 0.18288)
		(layer "In6.Cu")
		(net "M_G_CPU0_SB_DQ<5>")
	)
	(segment
		(start 406.121616 -230.041704)
		(end 404.252176 -230.041704)
		(width 0.18288)
		(layer "In6.Cu")
		(net "M_G_CPU0_SB_DQ<5>")
	)
	(segment
		(start 411.4038 -229.24516)
		(end 411.4038 -229.005892)
		(width 0.18288)
		(layer "In6.Cu")
		(net "M_G_CPU0_SB_DQ<5>")
	)
	(segment
		(start 380.913132 -237.900972)
		(end 380.90729 -237.89767)
		(width 0.088646)
		(layer "In6.Cu")
		(net "M_G_CPU0_SB_DQ<5>")
	)
	(segment
		(start 402.499576 -229.52202)
		(end 402.171916 -229.52202)
		(width 0.18288)
		(layer "In6.Cu")
		(net "M_G_CPU0_SB_DQ<5>")
	)
	(segment
		(start 410.55036 -229.40518)
		(end 410.153104 -229.40518)
		(width 0.18288)
		(layer "In6.Cu")
		(net "M_G_CPU0_SB_DQ<5>")
	)
	(segment
		(start 403.375876 -229.7049)
		(end 403.375876 -229.858824)
		(width 0.18288)
		(layer "In6.Cu")
		(net "M_G_CPU0_SB_DQ<5>")
	)
	(segment
		(start 376.592084 -238.222028)
		(end 376.592084 -238.225584)
		(width 0.088646)
		(layer "In6.Cu")
		(net "M_G_CPU0_SB_DQ<5>")
	)
	(segment
		(start 382.418336 -237.901226)
		(end 382.418082 -237.900972)
		(width 0.088646)
		(layer "In6.Cu")
		(net "M_G_CPU0_SB_DQ<5>")
	)
	(segment
		(start 434.003958 -225.070162)
		(end 433.390294 -225.683826)
		(width 0.18288)
		(layer "In6.Cu")
		(net "M_G_CPU0_SB_DQ<5>")
	)
	(segment
		(start 379.033532 -237.900972)
		(end 379.02769 -237.89767)
		(width 0.088646)
		(layer "In6.Cu")
		(net "M_G_CPU0_SB_DQ<5>")
	)
	(segment
		(start 425.924726 -229.192074)
		(end 424.405806 -229.192074)
		(width 0.18288)
		(layer "In6.Cu")
		(net "M_G_CPU0_SB_DQ<5>")
	)
	(segment
		(start 416.389312 -230.199692)
		(end 415.142934 -230.199692)
		(width 0.18288)
		(layer "In6.Cu")
		(net "M_G_CPU0_SB_DQ<5>")
	)
	(segment
		(start 411.56382 -229.40518)
		(end 411.4038 -229.24516)
		(width 0.18288)
		(layer "In6.Cu")
		(net "M_G_CPU0_SB_DQ<5>")
	)
	(segment
		(start 418.818568 -230.210106)
		(end 418.635688 -230.392986)
		(width 0.18288)
		(layer "In6.Cu")
		(net "M_G_CPU0_SB_DQ<5>")
	)
	(segment
		(start 419.917626 -230.041958)
		(end 419.750494 -229.874826)
		(width 0.18288)
		(layer "In6.Cu")
		(net "M_G_CPU0_SB_DQ<5>")
	)
	(segment
		(start 430.958498 -226.439222)
		(end 429.618394 -226.439222)
		(width 0.18288)
		(layer "In6.Cu")
		(net "M_G_CPU0_SB_DQ<5>")
	)
	(segment
		(start 435.798214 -224.516696)
		(end 435.244748 -225.070162)
		(width 0.18288)
		(layer "In6.Cu")
		(net "M_G_CPU0_SB_DQ<5>")
	)
	(segment
		(start 379.979174 -237.904528)
		(end 379.973332 -237.900972)
		(width 0.088646)
		(layer "In6.Cu")
		(net "M_G_CPU0_SB_DQ<5>")
	)
	(segment
		(start 387.506464 -237.81131)
		(end 387.23443 -237.81131)
		(width 0.088646)
		(layer "In6.Cu")
		(net "M_G_CPU0_SB_DQ<5>")
	)
	(segment
		(start 402.682456 -229.7049)
		(end 402.499576 -229.52202)
		(width 0.18288)
		(layer "In6.Cu")
		(net "M_G_CPU0_SB_DQ<5>")
	)
	(segment
		(start 403.558756 -229.52202)
		(end 403.375876 -229.7049)
		(width 0.18288)
		(layer "In6.Cu")
		(net "M_G_CPU0_SB_DQ<5>")
	)
	(segment
		(start 401.989036 -229.858824)
		(end 401.806156 -230.041704)
		(width 0.18288)
		(layer "In6.Cu")
		(net "M_G_CPU0_SB_DQ<5>")
	)
	(segment
		(start 374.93067 -238.496602)
		(end 375.08688 -238.225838)
		(width 0.088646)
		(layer "In6.Cu")
		(net "M_G_CPU0_SB_DQ<5>")
	)
	(segment
		(start 422.338246 -229.192074)
		(end 421.488362 -230.041958)
		(width 0.18288)
		(layer "In6.Cu")
		(net "M_G_CPU0_SB_DQ<5>")
	)
	(segment
		(start 375.289318 -238.541306)
		(end 375.26976 -238.552736)
		(width 0.088646)
		(layer "In6.Cu")
		(net "M_G_CPU0_SB_DQ<5>")
	)
	(segment
		(start 400.380454 -230.041704)
		(end 393.047474 -237.374684)
		(width 0.18288)
		(layer "In6.Cu")
		(net "M_G_CPU0_SB_DQ<5>")
	)
	(segment
		(start 380.918974 -237.904528)
		(end 380.913132 -237.900972)
		(width 0.088646)
		(layer "In6.Cu")
		(net "M_G_CPU0_SB_DQ<5>")
	)
	(segment
		(start 435.244748 -225.070162)
		(end 434.003958 -225.070162)
		(width 0.18288)
		(layer "In6.Cu")
		(net "M_G_CPU0_SB_DQ<5>")
	)
	(segment
		(start 404.252176 -230.041704)
		(end 404.069296 -229.858824)
		(width 0.18288)
		(layer "In6.Cu")
		(net "M_G_CPU0_SB_DQ<5>")
	)
	(segment
		(start 410.71038 -229.24516)
		(end 410.55036 -229.40518)
		(width 0.18288)
		(layer "In6.Cu")
		(net "M_G_CPU0_SB_DQ<5>")
	)
	(arc
		(start 383.358136 -237.901226)
		(mid 383.075434 -237.976968)
		(end 382.792732 -237.901226)
		(width 0.088646)
		(layer "In6.Cu")
		(net "M_G_CPU0_SB_DQ<5>")
	)
	(arc
		(start 382.792732 -237.901226)
		(mid 382.605534 -237.851083)
		(end 382.418336 -237.901226)
		(width 0.088646)
		(layer "In6.Cu")
		(net "M_G_CPU0_SB_DQ<5>")
	)
	(arc
		(start 379.598682 -237.900972)
		(mid 379.319508 -237.976737)
		(end 379.039374 -237.904528)
		(width 0.088646)
		(layer "In6.Cu")
		(net "M_G_CPU0_SB_DQ<5>")
	)
	(arc
		(start 384.297936 -237.901226)
		(mid 384.015234 -237.976968)
		(end 383.732532 -237.901226)
		(width 0.088646)
		(layer "In6.Cu")
		(net "M_G_CPU0_SB_DQ<5>")
	)
	(arc
		(start 379.02769 -237.89767)
		(mid 378.842835 -237.850752)
		(end 378.658882 -237.900972)
		(width 0.088646)
		(layer "In6.Cu")
		(net "M_G_CPU0_SB_DQ<5>")
	)
	(arc
		(start 385.612132 -237.901226)
		(mid 385.424934 -237.851083)
		(end 385.237736 -237.901226)
		(width 0.088646)
		(layer "In6.Cu")
		(net "M_G_CPU0_SB_DQ<5>")
	)
	(arc
		(start 380.90729 -237.89767)
		(mid 380.722435 -237.850752)
		(end 380.538482 -237.900972)
		(width 0.088646)
		(layer "In6.Cu")
		(net "M_G_CPU0_SB_DQ<5>")
	)
	(arc
		(start 375.26976 -238.552736)
		(mid 375.117827 -238.600891)
		(end 374.960134 -238.577882)
		(width 0.088646)
		(layer "In6.Cu")
		(net "M_G_CPU0_SB_DQ<5>")
	)
	(arc
		(start 377.719082 -237.900972)
		(mid 377.439908 -237.976737)
		(end 377.159774 -237.904528)
		(width 0.088646)
		(layer "In6.Cu")
		(net "M_G_CPU0_SB_DQ<5>")
	)
	(arc
		(start 387.23443 -237.81131)
		(mid 386.908447 -237.972072)
		(end 386.551932 -237.901226)
		(width 0.088646)
		(layer "In6.Cu")
		(net "M_G_CPU0_SB_DQ<5>")
	)
	(arc
		(start 386.551932 -237.901226)
		(mid 386.364734 -237.851083)
		(end 386.177536 -237.901226)
		(width 0.088646)
		(layer "In6.Cu")
		(net "M_G_CPU0_SB_DQ<5>")
	)
	(arc
		(start 381.478282 -237.900972)
		(mid 381.199108 -237.976737)
		(end 380.918974 -237.904528)
		(width 0.088646)
		(layer "In6.Cu")
		(net "M_G_CPU0_SB_DQ<5>")
	)
	(arc
		(start 383.732532 -237.901226)
		(mid 383.545334 -237.851083)
		(end 383.358136 -237.901226)
		(width 0.088646)
		(layer "In6.Cu")
		(net "M_G_CPU0_SB_DQ<5>")
	)
	(arc
		(start 386.177536 -237.901226)
		(mid 385.894834 -237.976968)
		(end 385.612132 -237.901226)
		(width 0.088646)
		(layer "In6.Cu")
		(net "M_G_CPU0_SB_DQ<5>")
	)
	(arc
		(start 379.96749 -237.89767)
		(mid 379.782635 -237.850752)
		(end 379.598682 -237.900972)
		(width 0.088646)
		(layer "In6.Cu")
		(net "M_G_CPU0_SB_DQ<5>")
	)
	(arc
		(start 378.08789 -237.89767)
		(mid 377.903035 -237.850752)
		(end 377.719082 -237.900972)
		(width 0.088646)
		(layer "In6.Cu")
		(net "M_G_CPU0_SB_DQ<5>")
	)
	(arc
		(start 378.658882 -237.900972)
		(mid 378.379708 -237.976737)
		(end 378.099574 -237.904528)
		(width 0.088646)
		(layer "In6.Cu")
		(net "M_G_CPU0_SB_DQ<5>")
	)
	(arc
		(start 380.538482 -237.900972)
		(mid 380.259308 -237.976737)
		(end 379.979174 -237.904528)
		(width 0.088646)
		(layer "In6.Cu")
		(net "M_G_CPU0_SB_DQ<5>")
	)
	(arc
		(start 381.848614 -237.898432)
		(mid 381.663119 -237.850795)
		(end 381.478282 -237.900972)
		(width 0.088646)
		(layer "In6.Cu")
		(net "M_G_CPU0_SB_DQ<5>")
	)
	(arc
		(start 385.237736 -237.901226)
		(mid 384.955034 -237.976968)
		(end 384.672332 -237.901226)
		(width 0.088646)
		(layer "In6.Cu")
		(net "M_G_CPU0_SB_DQ<5>")
	)
	(arc
		(start 384.672332 -237.901226)
		(mid 384.485134 -237.851083)
		(end 384.297936 -237.901226)
		(width 0.088646)
		(layer "In6.Cu")
		(net "M_G_CPU0_SB_DQ<5>")
	)
	(arc
		(start 377.14809 -237.89767)
		(mid 376.963235 -237.850752)
		(end 376.779282 -237.900972)
		(width 0.088646)
		(layer "In6.Cu")
		(net "M_G_CPU0_SB_DQ<5>")
	)
	(arc
		(start 376.592084 -238.225584)
		(mid 376.584276 -238.319202)
		(end 376.561096 -238.410242)
		(width 0.088646)
		(layer "In6.Cu")
		(net "M_G_CPU0_SB_DQ<5>")
	)
	(arc
		(start 375.98731 -238.673132)
		(mid 375.661619 -238.48387)
		(end 375.289318 -238.541306)
		(width 0.088646)
		(layer "In6.Cu")
		(net "M_G_CPU0_SB_DQ<5>")
	)
	(arc
		(start 376.779282 -237.900972)
		(mid 376.643085 -238.036657)
		(end 376.592084 -238.222028)
		(width 0.088646)
		(layer "In6.Cu")
		(net "M_G_CPU0_SB_DQ<5>")
	)
	(arc
		(start 382.418082 -237.900972)
		(mid 382.135524 -237.976621)
		(end 381.852932 -237.900972)
		(width 0.088646)
		(layer "In6.Cu")
		(net "M_G_CPU0_SB_DQ<5>")
	)
	(segment
		(start 442.032644 -225.791776)
		(end 439.87085 -225.791776)
		(width 0.1016)
		(layer "F.Cu")
		(net "M_G_CPU0_SB_DQ<4>")
	)
	(segment
		(start 442.44895 -225.785426)
		(end 442.038994 -225.785426)
		(width 0.20066)
		(layer "F.Cu")
		(net "M_G_CPU0_SB_DQ<4>")
	)
	(segment
		(start 439.82386 -225.791776)
		(end 439.479182 -225.791776)
		(width 0.20066)
		(layer "F.Cu")
		(net "M_G_CPU0_SB_DQ<4>")
	)
	(segment
		(start 438.697878 -226.465384)
		(end 438.449212 -226.216718)
		(width 0.20066)
		(layer "F.Cu")
		(net "M_G_CPU0_SB_DQ<4>")
	)
	(segment
		(start 436.928514 -226.216718)
		(end 435.823614 -226.216718)
		(width 0.20066)
		(layer "F.Cu")
		(net "M_G_CPU0_SB_DQ<4>")
	)
	(segment
		(start 442.880496 -226.216972)
		(end 442.44895 -225.785426)
		(width 0.20066)
		(layer "F.Cu")
		(net "M_G_CPU0_SB_DQ<4>")
	)
	(segment
		(start 374.617234 -239.575086)
		(end 374.617234 -239.0394)
		(width 0.20066)
		(layer "F.Cu")
		(net "M_G_CPU0_SB_DQ<4>")
	)
	(segment
		(start 438.449212 -226.216718)
		(end 436.928514 -226.216718)
		(width 0.20066)
		(layer "F.Cu")
		(net "M_G_CPU0_SB_DQ<4>")
	)
	(segment
		(start 442.038994 -225.785426)
		(end 442.032644 -225.791776)
		(width 0.1016)
		(layer "F.Cu")
		(net "M_G_CPU0_SB_DQ<4>")
	)
	(segment
		(start 439.479182 -225.791776)
		(end 439.361072 -225.909886)
		(width 0.20066)
		(layer "F.Cu")
		(net "M_G_CPU0_SB_DQ<4>")
	)
	(segment
		(start 444.47206 -226.216972)
		(end 442.880496 -226.216972)
		(width 0.20066)
		(layer "F.Cu")
		(net "M_G_CPU0_SB_DQ<4>")
	)
	(segment
		(start 374.61698 -239.57534)
		(end 374.617234 -239.575086)
		(width 0.20066)
		(layer "F.Cu")
		(net "M_G_CPU0_SB_DQ<4>")
	)
	(segment
		(start 439.361072 -226.277424)
		(end 439.173112 -226.465384)
		(width 0.20066)
		(layer "F.Cu")
		(net "M_G_CPU0_SB_DQ<4>")
	)
	(segment
		(start 439.361072 -225.909886)
		(end 439.361072 -226.277424)
		(width 0.20066)
		(layer "F.Cu")
		(net "M_G_CPU0_SB_DQ<4>")
	)
	(segment
		(start 444.472314 -226.216718)
		(end 444.47206 -226.216972)
		(width 0.20066)
		(layer "F.Cu")
		(net "M_G_CPU0_SB_DQ<4>")
	)
	(segment
		(start 439.87085 -225.791776)
		(end 439.82386 -225.791776)
		(width 0.101854)
		(layer "F.Cu")
		(net "M_G_CPU0_SB_DQ<4>")
	)
	(segment
		(start 439.173112 -226.465384)
		(end 438.697878 -226.465384)
		(width 0.20066)
		(layer "F.Cu")
		(net "M_G_CPU0_SB_DQ<4>")
	)
	(segment
		(start 404.76805 -231.74198)
		(end 404.58517 -231.92486)
		(width 0.18288)
		(layer "In6.Cu")
		(net "M_G_CPU0_SB_DQ<4>")
	)
	(segment
		(start 417.821364 -231.738932)
		(end 414.93186 -231.738932)
		(width 0.18288)
		(layer "In6.Cu")
		(net "M_G_CPU0_SB_DQ<4>")
	)
	(segment
		(start 403.70887 -231.74198)
		(end 403.38121 -231.74198)
		(width 0.18288)
		(layer "In6.Cu")
		(net "M_G_CPU0_SB_DQ<4>")
	)
	(segment
		(start 378.193554 -238.712248)
		(end 378.188982 -238.715042)
		(width 0.088646)
		(layer "In6.Cu")
		(net "M_G_CPU0_SB_DQ<4>")
	)
	(segment
		(start 425.94657 -230.89235)
		(end 422.28897 -230.89235)
		(width 0.18288)
		(layer "In6.Cu")
		(net "M_G_CPU0_SB_DQ<4>")
	)
	(segment
		(start 400.93519 -231.74198)
		(end 400.165062 -231.74198)
		(width 0.18288)
		(layer "In6.Cu")
		(net "M_G_CPU0_SB_DQ<4>")
	)
	(segment
		(start 418.7063 -231.919272)
		(end 418.001704 -231.919272)
		(width 0.18288)
		(layer "In6.Cu")
		(net "M_G_CPU0_SB_DQ<4>")
	)
	(segment
		(start 403.19833 -231.92486)
		(end 403.19833 -232.21569)
		(width 0.18288)
		(layer "In6.Cu")
		(net "M_G_CPU0_SB_DQ<4>")
	)
	(segment
		(start 434.81498 -226.67214)
		(end 433.746148 -226.67214)
		(width 0.18288)
		(layer "In6.Cu")
		(net "M_G_CPU0_SB_DQ<4>")
	)
	(segment
		(start 406.857962 -230.89235)
		(end 406.008332 -231.74198)
		(width 0.18288)
		(layer "In6.Cu")
		(net "M_G_CPU0_SB_DQ<4>")
	)
	(segment
		(start 376.280934 -239.346994)
		(end 376.038872 -239.312704)
		(width 0.088646)
		(layer "In6.Cu")
		(net "M_G_CPU0_SB_DQ<4>")
	)
	(segment
		(start 433.24399 -227.174298)
		(end 431.950622 -227.174298)
		(width 0.18288)
		(layer "In6.Cu")
		(net "M_G_CPU0_SB_DQ<4>")
	)
	(segment
		(start 377.171458 -238.773716)
		(end 377.105164 -238.84001)
		(width 0.088646)
		(layer "In6.Cu")
		(net "M_G_CPU0_SB_DQ<4>")
	)
	(segment
		(start 408.701494 -231.909112)
		(end 408.541474 -231.749092)
		(width 0.18288)
		(layer "In6.Cu")
		(net "M_G_CPU0_SB_DQ<4>")
	)
	(segment
		(start 411.778196 -230.890826)
		(end 411.46857 -230.5812)
		(width 0.18288)
		(layer "In6.Cu")
		(net "M_G_CPU0_SB_DQ<4>")
	)
	(segment
		(start 377.253754 -238.712248)
		(end 377.249182 -238.715042)
		(width 0.088646)
		(layer "In6.Cu")
		(net "M_G_CPU0_SB_DQ<4>")
	)
	(segment
		(start 379.133354 -238.712248)
		(end 379.128782 -238.715042)
		(width 0.088646)
		(layer "In6.Cu")
		(net "M_G_CPU0_SB_DQ<4>")
	)
	(segment
		(start 406.008332 -231.74198)
		(end 404.76805 -231.74198)
		(width 0.18288)
		(layer "In6.Cu")
		(net "M_G_CPU0_SB_DQ<4>")
	)
	(segment
		(start 401.99437 -231.74198)
		(end 401.81149 -231.92486)
		(width 0.18288)
		(layer "In6.Cu")
		(net "M_G_CPU0_SB_DQ<4>")
	)
	(segment
		(start 376.038872 -239.312704)
		(end 375.93143 -239.205262)
		(width 0.088646)
		(layer "In6.Cu")
		(net "M_G_CPU0_SB_DQ<4>")
	)
	(segment
		(start 409.074874 -231.909112)
		(end 408.701494 -231.909112)
		(width 0.18288)
		(layer "In6.Cu")
		(net "M_G_CPU0_SB_DQ<4>")
	)
	(segment
		(start 388.382764 -238.397034)
		(end 387.953504 -238.397034)
		(width 0.088646)
		(layer "In6.Cu")
		(net "M_G_CPU0_SB_DQ<4>")
	)
	(segment
		(start 428.792894 -230.078026)
		(end 428.573438 -230.297482)
		(width 0.18288)
		(layer "In6.Cu")
		(net "M_G_CPU0_SB_DQ<4>")
	)
	(segment
		(start 427.548294 -230.027226)
		(end 426.811694 -230.027226)
		(width 0.18288)
		(layer "In6.Cu")
		(net "M_G_CPU0_SB_DQ<4>")
	)
	(segment
		(start 427.81855 -230.297482)
		(end 427.548294 -230.027226)
		(width 0.18288)
		(layer "In6.Cu")
		(net "M_G_CPU0_SB_DQ<4>")
	)
	(segment
		(start 419.893496 -231.541828)
		(end 419.083744 -231.541828)
		(width 0.18288)
		(layer "In6.Cu")
		(net "M_G_CPU0_SB_DQ<4>")
	)
	(segment
		(start 374.773444 -238.768382)
		(end 374.617234 -239.039146)
		(width 0.088646)
		(layer "In6.Cu")
		(net "M_G_CPU0_SB_DQ<4>")
	)
	(segment
		(start 401.11807 -232.21569)
		(end 401.11807 -231.92486)
		(width 0.18288)
		(layer "In6.Cu")
		(net "M_G_CPU0_SB_DQ<4>")
	)
	(segment
		(start 400.165062 -231.74198)
		(end 393.510008 -238.397034)
		(width 0.18288)
		(layer "In6.Cu")
		(net "M_G_CPU0_SB_DQ<4>")
	)
	(segment
		(start 404.58517 -231.92486)
		(end 404.58517 -232.21569)
		(width 0.18288)
		(layer "In6.Cu")
		(net "M_G_CPU0_SB_DQ<4>")
	)
	(segment
		(start 401.81149 -231.92486)
		(end 401.81149 -232.21569)
		(width 0.18288)
		(layer "In6.Cu")
		(net "M_G_CPU0_SB_DQ<4>")
	)
	(segment
		(start 431.950622 -227.174298)
		(end 431.008282 -228.116638)
		(width 0.18288)
		(layer "In6.Cu")
		(net "M_G_CPU0_SB_DQ<4>")
	)
	(segment
		(start 387.594094 -238.756444)
		(end 387.138164 -238.756444)
		(width 0.088646)
		(layer "In6.Cu")
		(net "M_G_CPU0_SB_DQ<4>")
	)
	(segment
		(start 435.270402 -226.216718)
		(end 434.81498 -226.67214)
		(width 0.18288)
		(layer "In6.Cu")
		(net "M_G_CPU0_SB_DQ<4>")
	)
	(segment
		(start 409.394914 -230.89235)
		(end 409.234894 -231.05237)
		(width 0.18288)
		(layer "In6.Cu")
		(net "M_G_CPU0_SB_DQ<4>")
	)
	(segment
		(start 419.083744 -231.541828)
		(end 418.7063 -231.919272)
		(width 0.18288)
		(layer "In6.Cu")
		(net "M_G_CPU0_SB_DQ<4>")
	)
	(segment
		(start 431.008282 -228.116638)
		(end 430.18329 -228.116638)
		(width 0.18288)
		(layer "In6.Cu")
		(net "M_G_CPU0_SB_DQ<4>")
	)
	(segment
		(start 404.58517 -232.21569)
		(end 404.40229 -232.39857)
		(width 0.18288)
		(layer "In6.Cu")
		(net "M_G_CPU0_SB_DQ<4>")
	)
	(segment
		(start 381.012954 -238.712248)
		(end 381.008382 -238.715042)
		(width 0.088646)
		(layer "In6.Cu")
		(net "M_G_CPU0_SB_DQ<4>")
	)
	(segment
		(start 380.073154 -238.712248)
		(end 380.068582 -238.715042)
		(width 0.088646)
		(layer "In6.Cu")
		(net "M_G_CPU0_SB_DQ<4>")
	)
	(segment
		(start 379.128782 -238.715042)
		(end 379.121416 -238.71936)
		(width 0.088646)
		(layer "In6.Cu")
		(net "M_G_CPU0_SB_DQ<4>")
	)
	(segment
		(start 422.28897 -230.89235)
		(end 421.439086 -231.742234)
		(width 0.18288)
		(layer "In6.Cu")
		(net "M_G_CPU0_SB_DQ<4>")
	)
	(segment
		(start 420.093902 -231.742234)
		(end 419.893496 -231.541828)
		(width 0.18288)
		(layer "In6.Cu")
		(net "M_G_CPU0_SB_DQ<4>")
	)
	(segment
		(start 375.93143 -239.205262)
		(end 375.93143 -239.0394)
		(width 0.088646)
		(layer "In6.Cu")
		(net "M_G_CPU0_SB_DQ<4>")
	)
	(segment
		(start 401.81149 -232.21569)
		(end 401.62861 -232.39857)
		(width 0.18288)
		(layer "In6.Cu")
		(net "M_G_CPU0_SB_DQ<4>")
	)
	(segment
		(start 403.01545 -232.39857)
		(end 402.68779 -232.39857)
		(width 0.18288)
		(layer "In6.Cu")
		(net "M_G_CPU0_SB_DQ<4>")
	)
	(segment
		(start 380.068582 -238.715042)
		(end 380.061216 -238.71936)
		(width 0.088646)
		(layer "In6.Cu")
		(net "M_G_CPU0_SB_DQ<4>")
	)
	(segment
		(start 402.32203 -231.74198)
		(end 401.99437 -231.74198)
		(width 0.18288)
		(layer "In6.Cu")
		(net "M_G_CPU0_SB_DQ<4>")
	)
	(segment
		(start 433.746148 -226.67214)
		(end 433.24399 -227.174298)
		(width 0.18288)
		(layer "In6.Cu")
		(net "M_G_CPU0_SB_DQ<4>")
	)
	(segment
		(start 376.309636 -239.363758)
		(end 376.280934 -239.346994)
		(width 0.088646)
		(layer "In6.Cu")
		(net "M_G_CPU0_SB_DQ<4>")
	)
	(segment
		(start 381.008382 -238.715042)
		(end 381.001016 -238.71936)
		(width 0.088646)
		(layer "In6.Cu")
		(net "M_G_CPU0_SB_DQ<4>")
	)
	(segment
		(start 414.93186 -231.738932)
		(end 414.083754 -230.890826)
		(width 0.18288)
		(layer "In6.Cu")
		(net "M_G_CPU0_SB_DQ<4>")
	)
	(segment
		(start 408.541474 -231.749092)
		(end 408.541474 -231.05237)
		(width 0.18288)
		(layer "In6.Cu")
		(net "M_G_CPU0_SB_DQ<4>")
	)
	(segment
		(start 402.50491 -231.92486)
		(end 402.32203 -231.74198)
		(width 0.18288)
		(layer "In6.Cu")
		(net "M_G_CPU0_SB_DQ<4>")
	)
	(segment
		(start 404.07463 -232.39857)
		(end 403.89175 -232.21569)
		(width 0.18288)
		(layer "In6.Cu")
		(net "M_G_CPU0_SB_DQ<4>")
	)
	(segment
		(start 421.439086 -231.742234)
		(end 420.093902 -231.742234)
		(width 0.18288)
		(layer "In6.Cu")
		(net "M_G_CPU0_SB_DQ<4>")
	)
	(segment
		(start 409.234894 -231.749092)
		(end 409.074874 -231.909112)
		(width 0.18288)
		(layer "In6.Cu")
		(net "M_G_CPU0_SB_DQ<4>")
	)
	(segment
		(start 408.381454 -230.89235)
		(end 406.857962 -230.89235)
		(width 0.18288)
		(layer "In6.Cu")
		(net "M_G_CPU0_SB_DQ<4>")
	)
	(segment
		(start 403.38121 -231.74198)
		(end 403.19833 -231.92486)
		(width 0.18288)
		(layer "In6.Cu")
		(net "M_G_CPU0_SB_DQ<4>")
	)
	(segment
		(start 401.62861 -232.39857)
		(end 401.30095 -232.39857)
		(width 0.18288)
		(layer "In6.Cu")
		(net "M_G_CPU0_SB_DQ<4>")
	)
	(segment
		(start 401.11807 -231.92486)
		(end 400.93519 -231.74198)
		(width 0.18288)
		(layer "In6.Cu")
		(net "M_G_CPU0_SB_DQ<4>")
	)
	(segment
		(start 414.083754 -230.890826)
		(end 411.778196 -230.890826)
		(width 0.18288)
		(layer "In6.Cu")
		(net "M_G_CPU0_SB_DQ<4>")
	)
	(segment
		(start 410.047186 -230.89235)
		(end 409.394914 -230.89235)
		(width 0.18288)
		(layer "In6.Cu")
		(net "M_G_CPU0_SB_DQ<4>")
	)
	(segment
		(start 387.953504 -238.397034)
		(end 387.594094 -238.756444)
		(width 0.088646)
		(layer "In6.Cu")
		(net "M_G_CPU0_SB_DQ<4>")
	)
	(segment
		(start 402.50491 -232.21569)
		(end 402.50491 -231.92486)
		(width 0.18288)
		(layer "In6.Cu")
		(net "M_G_CPU0_SB_DQ<4>")
	)
	(segment
		(start 381.948182 -238.715042)
		(end 381.942594 -238.718344)
		(width 0.088646)
		(layer "In6.Cu")
		(net "M_G_CPU0_SB_DQ<4>")
	)
	(segment
		(start 426.811694 -230.027226)
		(end 425.94657 -230.89235)
		(width 0.18288)
		(layer "In6.Cu")
		(net "M_G_CPU0_SB_DQ<4>")
	)
	(segment
		(start 428.792894 -229.507034)
		(end 428.792894 -230.078026)
		(width 0.18288)
		(layer "In6.Cu")
		(net "M_G_CPU0_SB_DQ<4>")
	)
	(segment
		(start 404.40229 -232.39857)
		(end 404.07463 -232.39857)
		(width 0.18288)
		(layer "In6.Cu")
		(net "M_G_CPU0_SB_DQ<4>")
	)
	(segment
		(start 430.18329 -228.116638)
		(end 428.792894 -229.507034)
		(width 0.18288)
		(layer "In6.Cu")
		(net "M_G_CPU0_SB_DQ<4>")
	)
	(segment
		(start 403.89175 -232.21569)
		(end 403.89175 -231.92486)
		(width 0.18288)
		(layer "In6.Cu")
		(net "M_G_CPU0_SB_DQ<4>")
	)
	(segment
		(start 377.249182 -238.715042)
		(end 377.245626 -238.717074)
		(width 0.088646)
		(layer "In6.Cu")
		(net "M_G_CPU0_SB_DQ<4>")
	)
	(segment
		(start 410.358336 -230.5812)
		(end 410.047186 -230.89235)
		(width 0.18288)
		(layer "In6.Cu")
		(net "M_G_CPU0_SB_DQ<4>")
	)
	(segment
		(start 374.617234 -239.039146)
		(end 374.617234 -239.0394)
		(width 0.088646)
		(layer "In6.Cu")
		(net "M_G_CPU0_SB_DQ<4>")
	)
	(segment
		(start 374.870726 -238.748062)
		(end 374.773444 -238.768382)
		(width 0.088646)
		(layer "In6.Cu")
		(net "M_G_CPU0_SB_DQ<4>")
	)
	(segment
		(start 408.541474 -231.05237)
		(end 408.381454 -230.89235)
		(width 0.18288)
		(layer "In6.Cu")
		(net "M_G_CPU0_SB_DQ<4>")
	)
	(segment
		(start 393.510008 -238.397034)
		(end 388.382764 -238.397034)
		(width 0.18288)
		(layer "In6.Cu")
		(net "M_G_CPU0_SB_DQ<4>")
	)
	(segment
		(start 378.188982 -238.715042)
		(end 378.181616 -238.71936)
		(width 0.088646)
		(layer "In6.Cu")
		(net "M_G_CPU0_SB_DQ<4>")
	)
	(segment
		(start 377.105164 -238.84001)
		(end 376.85599 -239.166908)
		(width 0.088646)
		(layer "In6.Cu")
		(net "M_G_CPU0_SB_DQ<4>")
	)
	(segment
		(start 403.89175 -231.92486)
		(end 403.70887 -231.74198)
		(width 0.18288)
		(layer "In6.Cu")
		(net "M_G_CPU0_SB_DQ<4>")
	)
	(segment
		(start 401.30095 -232.39857)
		(end 401.11807 -232.21569)
		(width 0.18288)
		(layer "In6.Cu")
		(net "M_G_CPU0_SB_DQ<4>")
	)
	(segment
		(start 428.573438 -230.297482)
		(end 427.81855 -230.297482)
		(width 0.18288)
		(layer "In6.Cu")
		(net "M_G_CPU0_SB_DQ<4>")
	)
	(segment
		(start 402.68779 -232.39857)
		(end 402.50491 -232.21569)
		(width 0.18288)
		(layer "In6.Cu")
		(net "M_G_CPU0_SB_DQ<4>")
	)
	(segment
		(start 409.234894 -231.05237)
		(end 409.234894 -231.749092)
		(width 0.18288)
		(layer "In6.Cu")
		(net "M_G_CPU0_SB_DQ<4>")
	)
	(segment
		(start 435.823614 -226.216718)
		(end 435.270402 -226.216718)
		(width 0.18288)
		(layer "In6.Cu")
		(net "M_G_CPU0_SB_DQ<4>")
	)
	(segment
		(start 411.46857 -230.5812)
		(end 410.358336 -230.5812)
		(width 0.18288)
		(layer "In6.Cu")
		(net "M_G_CPU0_SB_DQ<4>")
	)
	(segment
		(start 403.19833 -232.21569)
		(end 403.01545 -232.39857)
		(width 0.18288)
		(layer "In6.Cu")
		(net "M_G_CPU0_SB_DQ<4>")
	)
	(segment
		(start 418.001704 -231.919272)
		(end 417.821364 -231.738932)
		(width 0.18288)
		(layer "In6.Cu")
		(net "M_G_CPU0_SB_DQ<4>")
	)
	(segment
		(start 375.36755 -238.716312)
		(end 375.366788 -238.71682)
		(width 0.088646)
		(layer "In6.Cu")
		(net "M_G_CPU0_SB_DQ<4>")
	)
	(arc
		(start 383.828036 -238.715042)
		(mid 383.545334 -238.790818)
		(end 383.262632 -238.715042)
		(width 0.088646)
		(layer "In6.Cu")
		(net "M_G_CPU0_SB_DQ<4>")
	)
	(arc
		(start 375.93143 -239.0394)
		(mid 375.743125 -238.714527)
		(end 375.36755 -238.716312)
		(width 0.088646)
		(layer "In6.Cu")
		(net "M_G_CPU0_SB_DQ<4>")
	)
	(arc
		(start 378.181616 -238.71936)
		(mid 377.902155 -238.790797)
		(end 377.623832 -238.715042)
		(width 0.088646)
		(layer "In6.Cu")
		(net "M_G_CPU0_SB_DQ<4>")
	)
	(arc
		(start 377.245626 -238.717074)
		(mid 377.206658 -238.742928)
		(end 377.171458 -238.773716)
		(width 0.088646)
		(layer "In6.Cu")
		(net "M_G_CPU0_SB_DQ<4>")
	)
	(arc
		(start 381.001016 -238.71936)
		(mid 380.721555 -238.790797)
		(end 380.443232 -238.715042)
		(width 0.088646)
		(layer "In6.Cu")
		(net "M_G_CPU0_SB_DQ<4>")
	)
	(arc
		(start 379.503432 -238.715042)
		(mid 379.318768 -238.664782)
		(end 379.133354 -238.712248)
		(width 0.088646)
		(layer "In6.Cu")
		(net "M_G_CPU0_SB_DQ<4>")
	)
	(arc
		(start 384.767836 -238.715042)
		(mid 384.485134 -238.790818)
		(end 384.202432 -238.715042)
		(width 0.088646)
		(layer "In6.Cu")
		(net "M_G_CPU0_SB_DQ<4>")
	)
	(arc
		(start 377.623832 -238.715042)
		(mid 377.439168 -238.664782)
		(end 377.253754 -238.712248)
		(width 0.088646)
		(layer "In6.Cu")
		(net "M_G_CPU0_SB_DQ<4>")
	)
	(arc
		(start 379.121416 -238.71936)
		(mid 378.841955 -238.790797)
		(end 378.563632 -238.715042)
		(width 0.088646)
		(layer "In6.Cu")
		(net "M_G_CPU0_SB_DQ<4>")
	)
	(arc
		(start 387.114288 -238.753396)
		(mid 387.066779 -238.737308)
		(end 387.021832 -238.715042)
		(width 0.088646)
		(layer "In6.Cu")
		(net "M_G_CPU0_SB_DQ<4>")
	)
	(arc
		(start 381.383032 -238.715042)
		(mid 381.198368 -238.664782)
		(end 381.012954 -238.712248)
		(width 0.088646)
		(layer "In6.Cu")
		(net "M_G_CPU0_SB_DQ<4>")
	)
	(arc
		(start 386.647436 -238.715042)
		(mid 386.364734 -238.790818)
		(end 386.082032 -238.715042)
		(width 0.088646)
		(layer "In6.Cu")
		(net "M_G_CPU0_SB_DQ<4>")
	)
	(arc
		(start 375.366788 -238.71682)
		(mid 375.122512 -238.791999)
		(end 374.870726 -238.748062)
		(width 0.088646)
		(layer "In6.Cu")
		(net "M_G_CPU0_SB_DQ<4>")
	)
	(arc
		(start 385.707636 -238.715042)
		(mid 385.424934 -238.790818)
		(end 385.142232 -238.715042)
		(width 0.088646)
		(layer "In6.Cu")
		(net "M_G_CPU0_SB_DQ<4>")
	)
	(arc
		(start 387.021832 -238.715042)
		(mid 386.834634 -238.664899)
		(end 386.647436 -238.715042)
		(width 0.088646)
		(layer "In6.Cu")
		(net "M_G_CPU0_SB_DQ<4>")
	)
	(arc
		(start 386.082032 -238.715042)
		(mid 385.894834 -238.664899)
		(end 385.707636 -238.715042)
		(width 0.088646)
		(layer "In6.Cu")
		(net "M_G_CPU0_SB_DQ<4>")
	)
	(arc
		(start 384.202432 -238.715042)
		(mid 384.015234 -238.664899)
		(end 383.828036 -238.715042)
		(width 0.088646)
		(layer "In6.Cu")
		(net "M_G_CPU0_SB_DQ<4>")
	)
	(arc
		(start 376.85599 -239.166908)
		(mid 376.786355 -239.279605)
		(end 376.684032 -239.363758)
		(width 0.088646)
		(layer "In6.Cu")
		(net "M_G_CPU0_SB_DQ<4>")
	)
	(arc
		(start 378.563632 -238.715042)
		(mid 378.378968 -238.664782)
		(end 378.193554 -238.712248)
		(width 0.088646)
		(layer "In6.Cu")
		(net "M_G_CPU0_SB_DQ<4>")
	)
	(arc
		(start 380.443232 -238.715042)
		(mid 380.258568 -238.664782)
		(end 380.073154 -238.712248)
		(width 0.088646)
		(layer "In6.Cu")
		(net "M_G_CPU0_SB_DQ<4>")
	)
	(arc
		(start 382.322832 -238.715042)
		(mid 382.135524 -238.664899)
		(end 381.948182 -238.715042)
		(width 0.088646)
		(layer "In6.Cu")
		(net "M_G_CPU0_SB_DQ<4>")
	)
	(arc
		(start 380.061216 -238.71936)
		(mid 379.781755 -238.790797)
		(end 379.503432 -238.715042)
		(width 0.088646)
		(layer "In6.Cu")
		(net "M_G_CPU0_SB_DQ<4>")
	)
	(arc
		(start 383.262632 -238.715042)
		(mid 383.075434 -238.664899)
		(end 382.888236 -238.715042)
		(width 0.088646)
		(layer "In6.Cu")
		(net "M_G_CPU0_SB_DQ<4>")
	)
	(arc
		(start 376.684032 -239.363758)
		(mid 376.496834 -239.413901)
		(end 376.309636 -239.363758)
		(width 0.088646)
		(layer "In6.Cu")
		(net "M_G_CPU0_SB_DQ<4>")
	)
	(arc
		(start 385.142232 -238.715042)
		(mid 384.955034 -238.664899)
		(end 384.767836 -238.715042)
		(width 0.088646)
		(layer "In6.Cu")
		(net "M_G_CPU0_SB_DQ<4>")
	)
	(arc
		(start 387.138164 -238.756444)
		(mid 387.126131 -238.755671)
		(end 387.114288 -238.753396)
		(width 0.088646)
		(layer "In6.Cu")
		(net "M_G_CPU0_SB_DQ<4>")
	)
	(arc
		(start 382.888236 -238.715042)
		(mid 382.605534 -238.790818)
		(end 382.322832 -238.715042)
		(width 0.088646)
		(layer "In6.Cu")
		(net "M_G_CPU0_SB_DQ<4>")
	)
	(arc
		(start 381.942594 -238.718344)
		(mid 381.662379 -238.790785)
		(end 381.383032 -238.715042)
		(width 0.088646)
		(layer "In6.Cu")
		(net "M_G_CPU0_SB_DQ<4>")
	)
	(segment
		(start 446.602104 -229.364794)
		(end 446.986152 -229.364794)
		(width 0.20066)
		(layer "F.Cu")
		(net "M_G_CPU0_SB_DQ<3>")
	)
	(segment
		(start 376.496834 -241.202972)
		(end 376.496834 -240.667286)
		(width 0.20066)
		(layer "F.Cu")
		(net "M_G_CPU0_SB_DQ<3>")
	)
	(segment
		(start 447.23812 -229.616762)
		(end 448.572382 -229.616762)
		(width 0.20066)
		(layer "F.Cu")
		(net "M_G_CPU0_SB_DQ<3>")
	)
	(segment
		(start 441.028582 -229.616762)
		(end 442.726826 -229.616762)
		(width 0.20066)
		(layer "F.Cu")
		(net "M_G_CPU0_SB_DQ<3>")
	)
	(segment
		(start 376.49658 -241.203226)
		(end 376.496834 -241.202972)
		(width 0.20066)
		(layer "F.Cu")
		(net "M_G_CPU0_SB_DQ<3>")
	)
	(segment
		(start 445.482726 -230.053896)
		(end 446.163954 -230.053896)
		(width 0.20066)
		(layer "F.Cu")
		(net "M_G_CPU0_SB_DQ<3>")
	)
	(segment
		(start 443.450726 -230.048816)
		(end 443.455552 -230.048816)
		(width 0.101854)
		(layer "F.Cu")
		(net "M_G_CPU0_SB_DQ<3>")
	)
	(segment
		(start 446.367916 -229.598982)
		(end 446.602104 -229.364794)
		(width 0.20066)
		(layer "F.Cu")
		(net "M_G_CPU0_SB_DQ<3>")
	)
	(segment
		(start 443.15888 -230.048816)
		(end 443.450726 -230.048816)
		(width 0.20066)
		(layer "F.Cu")
		(net "M_G_CPU0_SB_DQ<3>")
	)
	(segment
		(start 446.986152 -229.364794)
		(end 447.23812 -229.616762)
		(width 0.20066)
		(layer "F.Cu")
		(net "M_G_CPU0_SB_DQ<3>")
	)
	(segment
		(start 443.462664 -230.041704)
		(end 445.470534 -230.041704)
		(width 0.1016)
		(layer "F.Cu")
		(net "M_G_CPU0_SB_DQ<3>")
	)
	(segment
		(start 446.367916 -229.849934)
		(end 446.367916 -229.598982)
		(width 0.20066)
		(layer "F.Cu")
		(net "M_G_CPU0_SB_DQ<3>")
	)
	(segment
		(start 446.163954 -230.053896)
		(end 446.367916 -229.849934)
		(width 0.20066)
		(layer "F.Cu")
		(net "M_G_CPU0_SB_DQ<3>")
	)
	(segment
		(start 443.455552 -230.048816)
		(end 443.462664 -230.041704)
		(width 0.1016)
		(layer "F.Cu")
		(net "M_G_CPU0_SB_DQ<3>")
	)
	(segment
		(start 439.923682 -229.616762)
		(end 441.028582 -229.616762)
		(width 0.20066)
		(layer "F.Cu")
		(net "M_G_CPU0_SB_DQ<3>")
	)
	(segment
		(start 442.726826 -229.616762)
		(end 443.15888 -230.048816)
		(width 0.20066)
		(layer "F.Cu")
		(net "M_G_CPU0_SB_DQ<3>")
	)
	(segment
		(start 445.470534 -230.041704)
		(end 445.482726 -230.053896)
		(width 0.1016)
		(layer "F.Cu")
		(net "M_G_CPU0_SB_DQ<3>")
	)
	(segment
		(start 431.891694 -232.255822)
		(end 430.43729 -233.710226)
		(width 0.18288)
		(layer "In6.Cu")
		(net "M_G_CPU0_SB_DQ<3>")
	)
	(segment
		(start 408.447494 -235.183426)
		(end 405.745188 -235.183426)
		(width 0.18288)
		(layer "In6.Cu")
		(net "M_G_CPU0_SB_DQ<3>")
	)
	(segment
		(start 435.092094 -229.192328)
		(end 434.739796 -229.544626)
		(width 0.18288)
		(layer "In6.Cu")
		(net "M_G_CPU0_SB_DQ<3>")
	)
	(segment
		(start 434.02504 -230.46182)
		(end 434.02504 -230.68788)
		(width 0.18288)
		(layer "In6.Cu")
		(net "M_G_CPU0_SB_DQ<3>")
	)
	(segment
		(start 415.09696 -235.217716)
		(end 414.91408 -235.400596)
		(width 0.18288)
		(layer "In6.Cu")
		(net "M_G_CPU0_SB_DQ<3>")
	)
	(segment
		(start 414.22066 -235.400596)
		(end 414.03778 -235.217716)
		(width 0.18288)
		(layer "In6.Cu")
		(net "M_G_CPU0_SB_DQ<3>")
	)
	(segment
		(start 434.177694 -229.544626)
		(end 433.7558 -229.96652)
		(width 0.18288)
		(layer "In6.Cu")
		(net "M_G_CPU0_SB_DQ<3>")
	)
	(segment
		(start 378.578364 -240.983008)
		(end 378.563632 -240.991644)
		(width 0.088646)
		(layer "In6.Cu")
		(net "M_G_CPU0_SB_DQ<3>")
	)
	(segment
		(start 433.7558 -230.19258)
		(end 434.02504 -230.46182)
		(width 0.18288)
		(layer "In6.Cu")
		(net "M_G_CPU0_SB_DQ<3>")
	)
	(segment
		(start 388.382764 -240.557812)
		(end 388.105142 -240.557812)
		(width 0.088646)
		(layer "In6.Cu")
		(net "M_G_CPU0_SB_DQ<3>")
	)
	(segment
		(start 438.930796 -229.192328)
		(end 435.092094 -229.192328)
		(width 0.18288)
		(layer "In6.Cu")
		(net "M_G_CPU0_SB_DQ<3>")
	)
	(segment
		(start 416.530282 -236.052106)
		(end 415.695892 -235.217716)
		(width 0.18288)
		(layer "In6.Cu")
		(net "M_G_CPU0_SB_DQ<3>")
	)
	(segment
		(start 419.211252 -235.691426)
		(end 418.501576 -235.691426)
		(width 0.18288)
		(layer "In6.Cu")
		(net "M_G_CPU0_SB_DQ<3>")
	)
	(segment
		(start 382.337564 -240.983008)
		(end 382.322832 -240.991644)
		(width 0.088646)
		(layer "In6.Cu")
		(net "M_G_CPU0_SB_DQ<3>")
	)
	(segment
		(start 418.140896 -236.052106)
		(end 416.530282 -236.052106)
		(width 0.18288)
		(layer "In6.Cu")
		(net "M_G_CPU0_SB_DQ<3>")
	)
	(segment
		(start 430.342294 -233.710226)
		(end 428.911258 -235.141262)
		(width 0.18288)
		(layer "In6.Cu")
		(net "M_G_CPU0_SB_DQ<3>")
	)
	(segment
		(start 415.695892 -235.217716)
		(end 415.09696 -235.217716)
		(width 0.18288)
		(layer "In6.Cu")
		(net "M_G_CPU0_SB_DQ<3>")
	)
	(segment
		(start 379.513846 -240.985548)
		(end 379.503432 -240.991644)
		(width 0.088646)
		(layer "In6.Cu")
		(net "M_G_CPU0_SB_DQ<3>")
	)
	(segment
		(start 414.22066 -235.817156)
		(end 414.22066 -235.400596)
		(width 0.18288)
		(layer "In6.Cu")
		(net "M_G_CPU0_SB_DQ<3>")
	)
	(segment
		(start 377.638564 -240.983008)
		(end 377.623832 -240.991644)
		(width 0.088646)
		(layer "In6.Cu")
		(net "M_G_CPU0_SB_DQ<3>")
	)
	(segment
		(start 433.7558 -229.96652)
		(end 433.7558 -230.19258)
		(width 0.18288)
		(layer "In6.Cu")
		(net "M_G_CPU0_SB_DQ<3>")
	)
	(segment
		(start 434.02504 -230.68788)
		(end 433.760626 -230.952294)
		(width 0.18288)
		(layer "In6.Cu")
		(net "M_G_CPU0_SB_DQ<3>")
	)
	(segment
		(start 431.891694 -231.830626)
		(end 431.891694 -232.255822)
		(width 0.18288)
		(layer "In6.Cu")
		(net "M_G_CPU0_SB_DQ<3>")
	)
	(segment
		(start 414.7312 -236.000036)
		(end 414.40354 -236.000036)
		(width 0.18288)
		(layer "In6.Cu")
		(net "M_G_CPU0_SB_DQ<3>")
	)
	(segment
		(start 433.039266 -230.683054)
		(end 431.891694 -231.830626)
		(width 0.18288)
		(layer "In6.Cu")
		(net "M_G_CPU0_SB_DQ<3>")
	)
	(segment
		(start 433.534566 -230.952294)
		(end 433.265326 -230.683054)
		(width 0.18288)
		(layer "In6.Cu")
		(net "M_G_CPU0_SB_DQ<3>")
	)
	(segment
		(start 418.501576 -235.691426)
		(end 418.140896 -236.052106)
		(width 0.18288)
		(layer "In6.Cu")
		(net "M_G_CPU0_SB_DQ<3>")
	)
	(segment
		(start 376.126756 -240.72469)
		(end 376.18416 -240.667286)
		(width 0.088646)
		(layer "In6.Cu")
		(net "M_G_CPU0_SB_DQ<3>")
	)
	(segment
		(start 428.911258 -235.141262)
		(end 422.456356 -235.141262)
		(width 0.18288)
		(layer "In6.Cu")
		(net "M_G_CPU0_SB_DQ<3>")
	)
	(segment
		(start 376.18416 -240.667286)
		(end 376.496834 -240.667286)
		(width 0.088646)
		(layer "In6.Cu")
		(net "M_G_CPU0_SB_DQ<3>")
	)
	(segment
		(start 405.744934 -235.183172)
		(end 401.01393 -235.183172)
		(width 0.18288)
		(layer "In6.Cu")
		(net "M_G_CPU0_SB_DQ<3>")
	)
	(segment
		(start 434.739796 -229.544626)
		(end 434.177694 -229.544626)
		(width 0.18288)
		(layer "In6.Cu")
		(net "M_G_CPU0_SB_DQ<3>")
	)
	(segment
		(start 414.40354 -236.000036)
		(end 414.22066 -235.817156)
		(width 0.18288)
		(layer "In6.Cu")
		(net "M_G_CPU0_SB_DQ<3>")
	)
	(segment
		(start 387.220714 -240.81613)
		(end 387.021832 -240.991644)
		(width 0.088646)
		(layer "In6.Cu")
		(net "M_G_CPU0_SB_DQ<3>")
	)
	(segment
		(start 387.846824 -240.81613)
		(end 387.220714 -240.81613)
		(width 0.088646)
		(layer "In6.Cu")
		(net "M_G_CPU0_SB_DQ<3>")
	)
	(segment
		(start 405.745188 -235.183426)
		(end 405.744934 -235.183172)
		(width 0.18288)
		(layer "In6.Cu")
		(net "M_G_CPU0_SB_DQ<3>")
	)
	(segment
		(start 414.91408 -235.400596)
		(end 414.91408 -235.817156)
		(width 0.18288)
		(layer "In6.Cu")
		(net "M_G_CPU0_SB_DQ<3>")
	)
	(segment
		(start 414.91408 -235.817156)
		(end 414.7312 -236.000036)
		(width 0.18288)
		(layer "In6.Cu")
		(net "M_G_CPU0_SB_DQ<3>")
	)
	(segment
		(start 401.01393 -235.183172)
		(end 395.63929 -240.557812)
		(width 0.18288)
		(layer "In6.Cu")
		(net "M_G_CPU0_SB_DQ<3>")
	)
	(segment
		(start 433.265326 -230.683054)
		(end 433.039266 -230.683054)
		(width 0.18288)
		(layer "In6.Cu")
		(net "M_G_CPU0_SB_DQ<3>")
	)
	(segment
		(start 439.35523 -229.616762)
		(end 438.930796 -229.192328)
		(width 0.18288)
		(layer "In6.Cu")
		(net "M_G_CPU0_SB_DQ<3>")
	)
	(segment
		(start 414.03778 -235.217716)
		(end 412.952184 -235.217716)
		(width 0.18288)
		(layer "In6.Cu")
		(net "M_G_CPU0_SB_DQ<3>")
	)
	(segment
		(start 395.63929 -240.557812)
		(end 388.382764 -240.557812)
		(width 0.18288)
		(layer "In6.Cu")
		(net "M_G_CPU0_SB_DQ<3>")
	)
	(segment
		(start 376.309636 -240.991644)
		(end 376.300746 -240.986564)
		(width 0.088646)
		(layer "In6.Cu")
		(net "M_G_CPU0_SB_DQ<3>")
	)
	(segment
		(start 433.760626 -230.952294)
		(end 433.534566 -230.952294)
		(width 0.18288)
		(layer "In6.Cu")
		(net "M_G_CPU0_SB_DQ<3>")
	)
	(segment
		(start 439.923682 -229.616762)
		(end 439.35523 -229.616762)
		(width 0.18288)
		(layer "In6.Cu")
		(net "M_G_CPU0_SB_DQ<3>")
	)
	(segment
		(start 412.952184 -235.217716)
		(end 412.638494 -234.904026)
		(width 0.18288)
		(layer "In6.Cu")
		(net "M_G_CPU0_SB_DQ<3>")
	)
	(segment
		(start 422.456356 -235.141262)
		(end 421.605202 -235.992416)
		(width 0.18288)
		(layer "In6.Cu")
		(net "M_G_CPU0_SB_DQ<3>")
	)
	(segment
		(start 430.43729 -233.710226)
		(end 430.342294 -233.710226)
		(width 0.18288)
		(layer "In6.Cu")
		(net "M_G_CPU0_SB_DQ<3>")
	)
	(segment
		(start 421.605202 -235.992416)
		(end 419.512242 -235.992416)
		(width 0.18288)
		(layer "In6.Cu")
		(net "M_G_CPU0_SB_DQ<3>")
	)
	(segment
		(start 419.512242 -235.992416)
		(end 419.211252 -235.691426)
		(width 0.18288)
		(layer "In6.Cu")
		(net "M_G_CPU0_SB_DQ<3>")
	)
	(segment
		(start 411.25521 -234.904026)
		(end 410.11221 -236.047026)
		(width 0.18288)
		(layer "In6.Cu")
		(net "M_G_CPU0_SB_DQ<3>")
	)
	(segment
		(start 409.311094 -236.047026)
		(end 408.447494 -235.183426)
		(width 0.18288)
		(layer "In6.Cu")
		(net "M_G_CPU0_SB_DQ<3>")
	)
	(segment
		(start 410.11221 -236.047026)
		(end 409.311094 -236.047026)
		(width 0.18288)
		(layer "In6.Cu")
		(net "M_G_CPU0_SB_DQ<3>")
	)
	(segment
		(start 412.638494 -234.904026)
		(end 411.25521 -234.904026)
		(width 0.18288)
		(layer "In6.Cu")
		(net "M_G_CPU0_SB_DQ<3>")
	)
	(segment
		(start 388.105142 -240.557812)
		(end 387.846824 -240.81613)
		(width 0.088646)
		(layer "In6.Cu")
		(net "M_G_CPU0_SB_DQ<3>")
	)
	(segment
		(start 380.453392 -240.985548)
		(end 380.442978 -240.991644)
		(width 0.088646)
		(layer "In6.Cu")
		(net "M_G_CPU0_SB_DQ<3>")
	)
	(arc
		(start 381.383032 -240.991644)
		(mid 381.195834 -241.041787)
		(end 381.008636 -240.991644)
		(width 0.088646)
		(layer "In6.Cu")
		(net "M_G_CPU0_SB_DQ<3>")
	)
	(arc
		(start 383.828036 -240.991644)
		(mid 383.545334 -240.915868)
		(end 383.262632 -240.991644)
		(width 0.088646)
		(layer "In6.Cu")
		(net "M_G_CPU0_SB_DQ<3>")
	)
	(arc
		(start 379.129036 -240.991644)
		(mid 378.854837 -240.915809)
		(end 378.578364 -240.983008)
		(width 0.088646)
		(layer "In6.Cu")
		(net "M_G_CPU0_SB_DQ<3>")
	)
	(arc
		(start 377.249436 -240.991644)
		(mid 376.966734 -240.915868)
		(end 376.684032 -240.991644)
		(width 0.088646)
		(layer "In6.Cu")
		(net "M_G_CPU0_SB_DQ<3>")
	)
	(arc
		(start 381.008636 -240.991644)
		(mid 380.731823 -240.915774)
		(end 380.453392 -240.985548)
		(width 0.088646)
		(layer "In6.Cu")
		(net "M_G_CPU0_SB_DQ<3>")
	)
	(arc
		(start 378.563632 -240.991644)
		(mid 378.376434 -241.041787)
		(end 378.189236 -240.991644)
		(width 0.088646)
		(layer "In6.Cu")
		(net "M_G_CPU0_SB_DQ<3>")
	)
	(arc
		(start 384.767836 -240.991644)
		(mid 384.485134 -240.915868)
		(end 384.202432 -240.991644)
		(width 0.088646)
		(layer "In6.Cu")
		(net "M_G_CPU0_SB_DQ<3>")
	)
	(arc
		(start 386.647436 -240.991644)
		(mid 386.364734 -240.915868)
		(end 386.082032 -240.991644)
		(width 0.088646)
		(layer "In6.Cu")
		(net "M_G_CPU0_SB_DQ<3>")
	)
	(arc
		(start 377.623832 -240.991644)
		(mid 377.436634 -241.041787)
		(end 377.249436 -240.991644)
		(width 0.088646)
		(layer "In6.Cu")
		(net "M_G_CPU0_SB_DQ<3>")
	)
	(arc
		(start 380.068582 -240.991644)
		(mid 379.792023 -240.915901)
		(end 379.513846 -240.985548)
		(width 0.088646)
		(layer "In6.Cu")
		(net "M_G_CPU0_SB_DQ<3>")
	)
	(arc
		(start 385.142232 -240.991644)
		(mid 384.955034 -241.041787)
		(end 384.767836 -240.991644)
		(width 0.088646)
		(layer "In6.Cu")
		(net "M_G_CPU0_SB_DQ<3>")
	)
	(arc
		(start 376.684032 -240.991644)
		(mid 376.496834 -241.041787)
		(end 376.309636 -240.991644)
		(width 0.088646)
		(layer "In6.Cu")
		(net "M_G_CPU0_SB_DQ<3>")
	)
	(arc
		(start 378.189236 -240.991644)
		(mid 377.915037 -240.915809)
		(end 377.638564 -240.983008)
		(width 0.088646)
		(layer "In6.Cu")
		(net "M_G_CPU0_SB_DQ<3>")
	)
	(arc
		(start 379.503432 -240.991644)
		(mid 379.316234 -241.041787)
		(end 379.129036 -240.991644)
		(width 0.088646)
		(layer "In6.Cu")
		(net "M_G_CPU0_SB_DQ<3>")
	)
	(arc
		(start 387.021832 -240.991644)
		(mid 386.834634 -241.041787)
		(end 386.647436 -240.991644)
		(width 0.088646)
		(layer "In6.Cu")
		(net "M_G_CPU0_SB_DQ<3>")
	)
	(arc
		(start 381.948436 -240.991644)
		(mid 381.665734 -240.915868)
		(end 381.383032 -240.991644)
		(width 0.088646)
		(layer "In6.Cu")
		(net "M_G_CPU0_SB_DQ<3>")
	)
	(arc
		(start 382.322832 -240.991644)
		(mid 382.135634 -241.041787)
		(end 381.948436 -240.991644)
		(width 0.088646)
		(layer "In6.Cu")
		(net "M_G_CPU0_SB_DQ<3>")
	)
	(arc
		(start 386.082032 -240.991644)
		(mid 385.894834 -241.041787)
		(end 385.707636 -240.991644)
		(width 0.088646)
		(layer "In6.Cu")
		(net "M_G_CPU0_SB_DQ<3>")
	)
	(arc
		(start 376.300746 -240.986564)
		(mid 376.185007 -240.87474)
		(end 376.126756 -240.72469)
		(width 0.088646)
		(layer "In6.Cu")
		(net "M_G_CPU0_SB_DQ<3>")
	)
	(arc
		(start 384.202432 -240.991644)
		(mid 384.015234 -241.041787)
		(end 383.828036 -240.991644)
		(width 0.088646)
		(layer "In6.Cu")
		(net "M_G_CPU0_SB_DQ<3>")
	)
	(arc
		(start 380.442978 -240.991644)
		(mid 380.25578 -241.041787)
		(end 380.068582 -240.991644)
		(width 0.088646)
		(layer "In6.Cu")
		(net "M_G_CPU0_SB_DQ<3>")
	)
	(arc
		(start 385.707636 -240.991644)
		(mid 385.424934 -240.915868)
		(end 385.142232 -240.991644)
		(width 0.088646)
		(layer "In6.Cu")
		(net "M_G_CPU0_SB_DQ<3>")
	)
	(arc
		(start 383.262632 -240.991644)
		(mid 383.075434 -241.041787)
		(end 382.888236 -240.991644)
		(width 0.088646)
		(layer "In6.Cu")
		(net "M_G_CPU0_SB_DQ<3>")
	)
	(arc
		(start 382.888236 -240.991644)
		(mid 382.614037 -240.915809)
		(end 382.337564 -240.983008)
		(width 0.088646)
		(layer "In6.Cu")
		(net "M_G_CPU0_SB_DQ<3>")
	)
	(segment
		(start 442.726826 -195.616576)
		(end 443.15888 -196.04863)
		(width 0.20066)
		(layer "F.Cu")
		(net "M_G_CPU0_SB_DQ<31>")
	)
	(segment
		(start 439.923682 -195.616576)
		(end 441.028582 -195.616576)
		(width 0.20066)
		(layer "F.Cu")
		(net "M_G_CPU0_SB_DQ<31>")
	)
	(segment
		(start 447.23812 -195.616576)
		(end 448.572382 -195.616576)
		(width 0.20066)
		(layer "F.Cu")
		(net "M_G_CPU0_SB_DQ<31>")
	)
	(segment
		(start 446.602104 -195.364608)
		(end 446.986152 -195.364608)
		(width 0.20066)
		(layer "F.Cu")
		(net "M_G_CPU0_SB_DQ<31>")
	)
	(segment
		(start 446.367916 -195.598796)
		(end 446.602104 -195.364608)
		(width 0.20066)
		(layer "F.Cu")
		(net "M_G_CPU0_SB_DQ<31>")
	)
	(segment
		(start 384.955034 -216.786206)
		(end 384.955034 -216.25052)
		(width 0.20066)
		(layer "F.Cu")
		(net "M_G_CPU0_SB_DQ<31>")
	)
	(segment
		(start 443.450726 -196.04863)
		(end 443.455552 -196.04863)
		(width 0.101854)
		(layer "F.Cu")
		(net "M_G_CPU0_SB_DQ<31>")
	)
	(segment
		(start 445.482726 -196.05371)
		(end 446.163954 -196.05371)
		(width 0.20066)
		(layer "F.Cu")
		(net "M_G_CPU0_SB_DQ<31>")
	)
	(segment
		(start 443.455552 -196.04863)
		(end 443.462664 -196.041518)
		(width 0.1016)
		(layer "F.Cu")
		(net "M_G_CPU0_SB_DQ<31>")
	)
	(segment
		(start 441.028582 -195.616576)
		(end 442.726826 -195.616576)
		(width 0.20066)
		(layer "F.Cu")
		(net "M_G_CPU0_SB_DQ<31>")
	)
	(segment
		(start 384.95478 -216.78646)
		(end 384.955034 -216.786206)
		(width 0.20066)
		(layer "F.Cu")
		(net "M_G_CPU0_SB_DQ<31>")
	)
	(segment
		(start 443.15888 -196.04863)
		(end 443.450726 -196.04863)
		(width 0.20066)
		(layer "F.Cu")
		(net "M_G_CPU0_SB_DQ<31>")
	)
	(segment
		(start 445.470534 -196.041518)
		(end 445.482726 -196.05371)
		(width 0.1016)
		(layer "F.Cu")
		(net "M_G_CPU0_SB_DQ<31>")
	)
	(segment
		(start 443.462664 -196.041518)
		(end 445.470534 -196.041518)
		(width 0.1016)
		(layer "F.Cu")
		(net "M_G_CPU0_SB_DQ<31>")
	)
	(segment
		(start 446.986152 -195.364608)
		(end 447.23812 -195.616576)
		(width 0.20066)
		(layer "F.Cu")
		(net "M_G_CPU0_SB_DQ<31>")
	)
	(segment
		(start 446.163954 -196.05371)
		(end 446.367916 -195.849748)
		(width 0.20066)
		(layer "F.Cu")
		(net "M_G_CPU0_SB_DQ<31>")
	)
	(segment
		(start 446.367916 -195.849748)
		(end 446.367916 -195.598796)
		(width 0.20066)
		(layer "F.Cu")
		(net "M_G_CPU0_SB_DQ<31>")
	)
	(segment
		(start 386.182108 -215.760554)
		(end 386.17779 -215.758014)
		(width 0.088646)
		(layer "In6.Cu")
		(net "M_G_CPU0_SB_DQ<31>")
	)
	(segment
		(start 387.117844 -215.760554)
		(end 387.10743 -215.754458)
		(width 0.088646)
		(layer "In6.Cu")
		(net "M_G_CPU0_SB_DQ<31>")
	)
	(segment
		(start 384.955796 -216.24925)
		(end 384.955034 -216.250012)
		(width 0.088646)
		(layer "In6.Cu")
		(net "M_G_CPU0_SB_DQ<31>")
	)
	(segment
		(start 430.333912 -193.749676)
		(end 430.150778 -193.932302)
		(width 0.18288)
		(layer "In6.Cu")
		(net "M_G_CPU0_SB_DQ<31>")
	)
	(segment
		(start 385.582414 -215.775032)
		(end 384.955796 -216.24925)
		(width 0.088646)
		(layer "In6.Cu")
		(net "M_G_CPU0_SB_DQ<31>")
	)
	(segment
		(start 429.45685 -194.14871)
		(end 429.457358 -193.930524)
		(width 0.18288)
		(layer "In6.Cu")
		(net "M_G_CPU0_SB_DQ<31>")
	)
	(segment
		(start 405.679148 -194.262756)
		(end 394.191998 -205.749906)
		(width 0.18288)
		(layer "In6.Cu")
		(net "M_G_CPU0_SB_DQ<31>")
	)
	(segment
		(start 387.969506 -215.490044)
		(end 387.774942 -215.684608)
		(width 0.088646)
		(layer "In6.Cu")
		(net "M_G_CPU0_SB_DQ<31>")
	)
	(segment
		(start 429.274986 -193.747644)
		(end 410.779976 -193.713354)
		(width 0.18288)
		(layer "In6.Cu")
		(net "M_G_CPU0_SB_DQ<31>")
	)
	(segment
		(start 410.230574 -194.262756)
		(end 405.679148 -194.262756)
		(width 0.18288)
		(layer "In6.Cu")
		(net "M_G_CPU0_SB_DQ<31>")
	)
	(segment
		(start 429.456088 -194.49542)
		(end 429.45685 -194.14871)
		(width 0.18288)
		(layer "In6.Cu")
		(net "M_G_CPU0_SB_DQ<31>")
	)
	(segment
		(start 410.779976 -193.713354)
		(end 410.230574 -194.262756)
		(width 0.18288)
		(layer "In6.Cu")
		(net "M_G_CPU0_SB_DQ<31>")
	)
	(segment
		(start 394.191998 -205.749906)
		(end 394.191998 -208.108042)
		(width 0.18288)
		(layer "In6.Cu")
		(net "M_G_CPU0_SB_DQ<31>")
	)
	(segment
		(start 387.969506 -214.330534)
		(end 387.969506 -215.490044)
		(width 0.088646)
		(layer "In6.Cu")
		(net "M_G_CPU0_SB_DQ<31>")
	)
	(segment
		(start 394.191998 -208.108042)
		(end 388.083552 -214.216488)
		(width 0.18288)
		(layer "In6.Cu")
		(net "M_G_CPU0_SB_DQ<31>")
	)
	(segment
		(start 430.15027 -194.14871)
		(end 430.149508 -194.497198)
		(width 0.18288)
		(layer "In6.Cu")
		(net "M_G_CPU0_SB_DQ<31>")
	)
	(segment
		(start 438.554368 -195.049394)
		(end 434.29428 -193.756788)
		(width 0.18288)
		(layer "In6.Cu")
		(net "M_G_CPU0_SB_DQ<31>")
	)
	(segment
		(start 385.612132 -215.758014)
		(end 385.582414 -215.775032)
		(width 0.088646)
		(layer "In6.Cu")
		(net "M_G_CPU0_SB_DQ<31>")
	)
	(segment
		(start 385.612386 -215.758014)
		(end 385.612132 -215.758014)
		(width 0.088646)
		(layer "In6.Cu")
		(net "M_G_CPU0_SB_DQ<31>")
	)
	(segment
		(start 439.923682 -195.616576)
		(end 438.554368 -195.049394)
		(width 0.18288)
		(layer "In6.Cu")
		(net "M_G_CPU0_SB_DQ<31>")
	)
	(segment
		(start 388.083552 -214.216488)
		(end 387.969506 -214.330534)
		(width 0.088646)
		(layer "In6.Cu")
		(net "M_G_CPU0_SB_DQ<31>")
	)
	(segment
		(start 387.126226 -215.76538)
		(end 387.117844 -215.760554)
		(width 0.088646)
		(layer "In6.Cu")
		(net "M_G_CPU0_SB_DQ<31>")
	)
	(segment
		(start 429.457358 -193.930524)
		(end 429.274986 -193.747644)
		(width 0.18288)
		(layer "In6.Cu")
		(net "M_G_CPU0_SB_DQ<31>")
	)
	(segment
		(start 429.966628 -194.67957)
		(end 429.638714 -194.678554)
		(width 0.18288)
		(layer "In6.Cu")
		(net "M_G_CPU0_SB_DQ<31>")
	)
	(segment
		(start 384.955034 -216.250012)
		(end 384.955034 -216.25052)
		(width 0.088646)
		(layer "In6.Cu")
		(net "M_G_CPU0_SB_DQ<31>")
	)
	(segment
		(start 430.150778 -193.932302)
		(end 430.15027 -194.14871)
		(width 0.18288)
		(layer "In6.Cu")
		(net "M_G_CPU0_SB_DQ<31>")
	)
	(segment
		(start 434.29428 -193.756788)
		(end 430.333912 -193.749676)
		(width 0.18288)
		(layer "In6.Cu")
		(net "M_G_CPU0_SB_DQ<31>")
	)
	(segment
		(start 430.149508 -194.497198)
		(end 429.966628 -194.67957)
		(width 0.18288)
		(layer "In6.Cu")
		(net "M_G_CPU0_SB_DQ<31>")
	)
	(segment
		(start 429.638714 -194.678554)
		(end 429.456088 -194.49542)
		(width 0.18288)
		(layer "In6.Cu")
		(net "M_G_CPU0_SB_DQ<31>")
	)
	(arc
		(start 386.552186 -215.760554)
		(mid 386.367164 -215.810099)
		(end 386.182108 -215.760554)
		(width 0.088646)
		(layer "In6.Cu")
		(net "M_G_CPU0_SB_DQ<31>")
	)
	(arc
		(start 386.17779 -215.758014)
		(mid 385.895088 -215.682204)
		(end 385.612386 -215.758014)
		(width 0.088646)
		(layer "In6.Cu")
		(net "M_G_CPU0_SB_DQ<31>")
	)
	(arc
		(start 387.491986 -215.760554)
		(mid 387.309735 -215.810733)
		(end 387.126226 -215.76538)
		(width 0.088646)
		(layer "In6.Cu")
		(net "M_G_CPU0_SB_DQ<31>")
	)
	(arc
		(start 387.774942 -215.684608)
		(mid 387.628455 -215.703923)
		(end 387.491986 -215.760554)
		(width 0.088646)
		(layer "In6.Cu")
		(net "M_G_CPU0_SB_DQ<31>")
	)
	(arc
		(start 387.10743 -215.754458)
		(mid 386.828998 -215.684581)
		(end 386.552186 -215.760554)
		(width 0.088646)
		(layer "In6.Cu")
		(net "M_G_CPU0_SB_DQ<31>")
	)
	(segment
		(start 446.367916 -197.54977)
		(end 446.367916 -197.298818)
		(width 0.20066)
		(layer "F.Cu")
		(net "M_G_CPU0_SB_DQ<30>")
	)
	(segment
		(start 446.367916 -197.298818)
		(end 446.602104 -197.06463)
		(width 0.20066)
		(layer "F.Cu")
		(net "M_G_CPU0_SB_DQ<30>")
	)
	(segment
		(start 443.462664 -197.74154)
		(end 445.470534 -197.74154)
		(width 0.1016)
		(layer "F.Cu")
		(net "M_G_CPU0_SB_DQ<30>")
	)
	(segment
		(start 445.470534 -197.74154)
		(end 445.482726 -197.753732)
		(width 0.1016)
		(layer "F.Cu")
		(net "M_G_CPU0_SB_DQ<30>")
	)
	(segment
		(start 439.923682 -197.316598)
		(end 441.028582 -197.316598)
		(width 0.20066)
		(layer "F.Cu")
		(net "M_G_CPU0_SB_DQ<30>")
	)
	(segment
		(start 442.726826 -197.316598)
		(end 443.15888 -197.748652)
		(width 0.20066)
		(layer "F.Cu")
		(net "M_G_CPU0_SB_DQ<30>")
	)
	(segment
		(start 443.455552 -197.748652)
		(end 443.462664 -197.74154)
		(width 0.1016)
		(layer "F.Cu")
		(net "M_G_CPU0_SB_DQ<30>")
	)
	(segment
		(start 443.15888 -197.748652)
		(end 443.450726 -197.748652)
		(width 0.20066)
		(layer "F.Cu")
		(net "M_G_CPU0_SB_DQ<30>")
	)
	(segment
		(start 446.986152 -197.06463)
		(end 447.23812 -197.316598)
		(width 0.20066)
		(layer "F.Cu")
		(net "M_G_CPU0_SB_DQ<30>")
	)
	(segment
		(start 385.894834 -216.25052)
		(end 385.894834 -216.78646)
		(width 0.20066)
		(layer "F.Cu")
		(net "M_G_CPU0_SB_DQ<30>")
	)
	(segment
		(start 446.163954 -197.753732)
		(end 446.367916 -197.54977)
		(width 0.20066)
		(layer "F.Cu")
		(net "M_G_CPU0_SB_DQ<30>")
	)
	(segment
		(start 446.602104 -197.06463)
		(end 446.986152 -197.06463)
		(width 0.20066)
		(layer "F.Cu")
		(net "M_G_CPU0_SB_DQ<30>")
	)
	(segment
		(start 441.028582 -197.316598)
		(end 442.726826 -197.316598)
		(width 0.20066)
		(layer "F.Cu")
		(net "M_G_CPU0_SB_DQ<30>")
	)
	(segment
		(start 443.450726 -197.748652)
		(end 443.455552 -197.748652)
		(width 0.101854)
		(layer "F.Cu")
		(net "M_G_CPU0_SB_DQ<30>")
	)
	(segment
		(start 447.23812 -197.316598)
		(end 448.572382 -197.316598)
		(width 0.20066)
		(layer "F.Cu")
		(net "M_G_CPU0_SB_DQ<30>")
	)
	(segment
		(start 445.482726 -197.753732)
		(end 446.163954 -197.753732)
		(width 0.20066)
		(layer "F.Cu")
		(net "M_G_CPU0_SB_DQ<30>")
	)
	(segment
		(start 414.54197 -195.288916)
		(end 414.21431 -195.288916)
		(width 0.18288)
		(layer "In6.Cu")
		(net "M_G_CPU0_SB_DQ<30>")
	)
	(segment
		(start 419.965124 -195.192396)
		(end 419.801294 -195.356226)
		(width 0.18288)
		(layer "In6.Cu")
		(net "M_G_CPU0_SB_DQ<30>")
	)
	(segment
		(start 386.64769 -216.57437)
		(end 386.61975 -216.55786)
		(width 0.088646)
		(layer "In6.Cu")
		(net "M_G_CPU0_SB_DQ<30>")
	)
	(segment
		(start 411.932374 -195.350892)
		(end 411.772354 -195.190872)
		(width 0.18288)
		(layer "In6.Cu")
		(net "M_G_CPU0_SB_DQ<30>")
	)
	(segment
		(start 387.961886 -216.574116)
		(end 387.949948 -216.581228)
		(width 0.088646)
		(layer "In6.Cu")
		(net "M_G_CPU0_SB_DQ<30>")
	)
	(segment
		(start 387.036818 -216.565734)
		(end 387.022086 -216.57437)
		(width 0.088646)
		(layer "In6.Cu")
		(net "M_G_CPU0_SB_DQ<30>")
	)
	(segment
		(start 439.923682 -197.316598)
		(end 439.914538 -197.321424)
		(width 0.18288)
		(layer "In6.Cu")
		(net "M_G_CPU0_SB_DQ<30>")
	)
	(segment
		(start 385.898644 -216.25433)
		(end 385.894834 -216.25052)
		(width 0.088646)
		(layer "In6.Cu")
		(net "M_G_CPU0_SB_DQ<30>")
	)
	(segment
		(start 411.932374 -195.780406)
		(end 411.932374 -195.350892)
		(width 0.18288)
		(layer "In6.Cu")
		(net "M_G_CPU0_SB_DQ<30>")
	)
	(segment
		(start 412.092394 -195.940426)
		(end 411.932374 -195.780406)
		(width 0.18288)
		(layer "In6.Cu")
		(net "M_G_CPU0_SB_DQ<30>")
	)
	(segment
		(start 388.817104 -214.95004)
		(end 388.645146 -215.121998)
		(width 0.088646)
		(layer "In6.Cu")
		(net "M_G_CPU0_SB_DQ<30>")
	)
	(segment
		(start 438.49798 -196.892672)
		(end 432.144678 -196.892672)
		(width 0.18288)
		(layer "In6.Cu")
		(net "M_G_CPU0_SB_DQ<30>")
	)
	(segment
		(start 388.645146 -216.097612)
		(end 388.24408 -216.498678)
		(width 0.088646)
		(layer "In6.Cu")
		(net "M_G_CPU0_SB_DQ<30>")
	)
	(segment
		(start 414.21431 -195.288916)
		(end 414.03143 -195.471796)
		(width 0.18288)
		(layer "In6.Cu")
		(net "M_G_CPU0_SB_DQ<30>")
	)
	(segment
		(start 387.022086 -216.57437)
		(end 387.010148 -216.581228)
		(width 0.088646)
		(layer "In6.Cu")
		(net "M_G_CPU0_SB_DQ<30>")
	)
	(segment
		(start 412.740094 -196.143626)
		(end 412.536894 -195.940426)
		(width 0.18288)
		(layer "In6.Cu")
		(net "M_G_CPU0_SB_DQ<30>")
	)
	(segment
		(start 412.536894 -195.940426)
		(end 412.092394 -195.940426)
		(width 0.18288)
		(layer "In6.Cu")
		(net "M_G_CPU0_SB_DQ<30>")
	)
	(segment
		(start 414.72485 -195.471796)
		(end 414.54197 -195.288916)
		(width 0.18288)
		(layer "In6.Cu")
		(net "M_G_CPU0_SB_DQ<30>")
	)
	(segment
		(start 414.90773 -196.143626)
		(end 414.72485 -195.960746)
		(width 0.18288)
		(layer "In6.Cu")
		(net "M_G_CPU0_SB_DQ<30>")
	)
	(segment
		(start 411.398974 -195.190872)
		(end 411.238954 -195.350892)
		(width 0.18288)
		(layer "In6.Cu")
		(net "M_G_CPU0_SB_DQ<30>")
	)
	(segment
		(start 388.645146 -215.121998)
		(end 388.645146 -216.097612)
		(width 0.088646)
		(layer "In6.Cu")
		(net "M_G_CPU0_SB_DQ<30>")
	)
	(segment
		(start 439.914538 -197.321424)
		(end 438.49798 -196.892672)
		(width 0.18288)
		(layer "In6.Cu")
		(net "M_G_CPU0_SB_DQ<30>")
	)
	(segment
		(start 408.947112 -196.050408)
		(end 405.426164 -196.050408)
		(width 0.18288)
		(layer "In6.Cu")
		(net "M_G_CPU0_SB_DQ<30>")
	)
	(segment
		(start 424.271948 -196.04228)
		(end 423.422064 -195.192396)
		(width 0.18288)
		(layer "In6.Cu")
		(net "M_G_CPU0_SB_DQ<30>")
	)
	(segment
		(start 386.61975 -216.55786)
		(end 385.898644 -216.25433)
		(width 0.088646)
		(layer "In6.Cu")
		(net "M_G_CPU0_SB_DQ<30>")
	)
	(segment
		(start 414.03143 -195.960746)
		(end 413.84855 -196.143626)
		(width 0.18288)
		(layer "In6.Cu")
		(net "M_G_CPU0_SB_DQ<30>")
	)
	(segment
		(start 413.84855 -196.143626)
		(end 412.740094 -196.143626)
		(width 0.18288)
		(layer "In6.Cu")
		(net "M_G_CPU0_SB_DQ<30>")
	)
	(segment
		(start 415.994342 -195.71081)
		(end 415.561526 -196.143626)
		(width 0.18288)
		(layer "In6.Cu")
		(net "M_G_CPU0_SB_DQ<30>")
	)
	(segment
		(start 395.259052 -208.493868)
		(end 388.817104 -214.95004)
		(width 0.18288)
		(layer "In6.Cu")
		(net "M_G_CPU0_SB_DQ<30>")
	)
	(segment
		(start 423.422064 -195.192396)
		(end 419.965124 -195.192396)
		(width 0.18288)
		(layer "In6.Cu")
		(net "M_G_CPU0_SB_DQ<30>")
	)
	(segment
		(start 417.177474 -195.356226)
		(end 415.994342 -195.71081)
		(width 0.18288)
		(layer "In6.Cu")
		(net "M_G_CPU0_SB_DQ<30>")
	)
	(segment
		(start 405.426164 -196.050408)
		(end 395.256258 -206.245206)
		(width 0.18288)
		(layer "In6.Cu")
		(net "M_G_CPU0_SB_DQ<30>")
	)
	(segment
		(start 395.256258 -206.245206)
		(end 395.259052 -208.493868)
		(width 0.18288)
		(layer "In6.Cu")
		(net "M_G_CPU0_SB_DQ<30>")
	)
	(segment
		(start 415.561526 -196.143626)
		(end 414.90773 -196.143626)
		(width 0.18288)
		(layer "In6.Cu")
		(net "M_G_CPU0_SB_DQ<30>")
	)
	(segment
		(start 414.03143 -195.471796)
		(end 414.03143 -195.960746)
		(width 0.18288)
		(layer "In6.Cu")
		(net "M_G_CPU0_SB_DQ<30>")
	)
	(segment
		(start 419.801294 -195.356226)
		(end 417.177474 -195.356226)
		(width 0.18288)
		(layer "In6.Cu")
		(net "M_G_CPU0_SB_DQ<30>")
	)
	(segment
		(start 411.238954 -195.350892)
		(end 411.238954 -195.780406)
		(width 0.18288)
		(layer "In6.Cu")
		(net "M_G_CPU0_SB_DQ<30>")
	)
	(segment
		(start 432.144678 -196.892672)
		(end 431.294286 -196.04228)
		(width 0.18288)
		(layer "In6.Cu")
		(net "M_G_CPU0_SB_DQ<30>")
	)
	(segment
		(start 414.72485 -195.960746)
		(end 414.72485 -195.471796)
		(width 0.18288)
		(layer "In6.Cu")
		(net "M_G_CPU0_SB_DQ<30>")
	)
	(segment
		(start 411.772354 -195.190872)
		(end 411.398974 -195.190872)
		(width 0.18288)
		(layer "In6.Cu")
		(net "M_G_CPU0_SB_DQ<30>")
	)
	(segment
		(start 409.057094 -195.940426)
		(end 408.947112 -196.050408)
		(width 0.18288)
		(layer "In6.Cu")
		(net "M_G_CPU0_SB_DQ<30>")
	)
	(segment
		(start 411.078934 -195.940426)
		(end 409.057094 -195.940426)
		(width 0.18288)
		(layer "In6.Cu")
		(net "M_G_CPU0_SB_DQ<30>")
	)
	(segment
		(start 411.238954 -195.780406)
		(end 411.078934 -195.940426)
		(width 0.18288)
		(layer "In6.Cu")
		(net "M_G_CPU0_SB_DQ<30>")
	)
	(segment
		(start 431.294286 -196.04228)
		(end 424.271948 -196.04228)
		(width 0.18288)
		(layer "In6.Cu")
		(net "M_G_CPU0_SB_DQ<30>")
	)
	(arc
		(start 388.24408 -216.498678)
		(mid 388.098026 -216.517859)
		(end 387.961886 -216.574116)
		(width 0.088646)
		(layer "In6.Cu")
		(net "M_G_CPU0_SB_DQ<30>")
	)
	(arc
		(start 387.010148 -216.581228)
		(mid 386.828037 -216.624523)
		(end 386.64769 -216.57437)
		(width 0.088646)
		(layer "In6.Cu")
		(net "M_G_CPU0_SB_DQ<30>")
	)
	(arc
		(start 387.58749 -216.57437)
		(mid 387.313261 -216.498479)
		(end 387.036818 -216.565734)
		(width 0.088646)
		(layer "In6.Cu")
		(net "M_G_CPU0_SB_DQ<30>")
	)
	(arc
		(start 387.949948 -216.581228)
		(mid 387.767837 -216.624523)
		(end 387.58749 -216.57437)
		(width 0.088646)
		(layer "In6.Cu")
		(net "M_G_CPU0_SB_DQ<30>")
	)
	(segment
		(start 443.462664 -231.741726)
		(end 445.470534 -231.741726)
		(width 0.1016)
		(layer "F.Cu")
		(net "M_G_CPU0_SB_DQ<2>")
	)
	(segment
		(start 446.163954 -231.753918)
		(end 446.367916 -231.549956)
		(width 0.20066)
		(layer "F.Cu")
		(net "M_G_CPU0_SB_DQ<2>")
	)
	(segment
		(start 446.367916 -231.299004)
		(end 446.602104 -231.064816)
		(width 0.20066)
		(layer "F.Cu")
		(net "M_G_CPU0_SB_DQ<2>")
	)
	(segment
		(start 441.028582 -231.316784)
		(end 442.726826 -231.316784)
		(width 0.20066)
		(layer "F.Cu")
		(net "M_G_CPU0_SB_DQ<2>")
	)
	(segment
		(start 443.455552 -231.748838)
		(end 443.462664 -231.741726)
		(width 0.1016)
		(layer "F.Cu")
		(net "M_G_CPU0_SB_DQ<2>")
	)
	(segment
		(start 446.367916 -231.549956)
		(end 446.367916 -231.299004)
		(width 0.20066)
		(layer "F.Cu")
		(net "M_G_CPU0_SB_DQ<2>")
	)
	(segment
		(start 443.450726 -231.748838)
		(end 443.455552 -231.748838)
		(width 0.101854)
		(layer "F.Cu")
		(net "M_G_CPU0_SB_DQ<2>")
	)
	(segment
		(start 447.23812 -231.316784)
		(end 448.572382 -231.316784)
		(width 0.20066)
		(layer "F.Cu")
		(net "M_G_CPU0_SB_DQ<2>")
	)
	(segment
		(start 446.986152 -231.064816)
		(end 447.23812 -231.316784)
		(width 0.20066)
		(layer "F.Cu")
		(net "M_G_CPU0_SB_DQ<2>")
	)
	(segment
		(start 442.726826 -231.316784)
		(end 443.15888 -231.748838)
		(width 0.20066)
		(layer "F.Cu")
		(net "M_G_CPU0_SB_DQ<2>")
	)
	(segment
		(start 445.470534 -231.741726)
		(end 445.482726 -231.753918)
		(width 0.1016)
		(layer "F.Cu")
		(net "M_G_CPU0_SB_DQ<2>")
	)
	(segment
		(start 445.482726 -231.753918)
		(end 446.163954 -231.753918)
		(width 0.20066)
		(layer "F.Cu")
		(net "M_G_CPU0_SB_DQ<2>")
	)
	(segment
		(start 376.026934 -242.017042)
		(end 376.02668 -242.016788)
		(width 0.20066)
		(layer "F.Cu")
		(net "M_G_CPU0_SB_DQ<2>")
	)
	(segment
		(start 446.602104 -231.064816)
		(end 446.986152 -231.064816)
		(width 0.20066)
		(layer "F.Cu")
		(net "M_G_CPU0_SB_DQ<2>")
	)
	(segment
		(start 376.02668 -242.016788)
		(end 376.02668 -241.481102)
		(width 0.20066)
		(layer "F.Cu")
		(net "M_G_CPU0_SB_DQ<2>")
	)
	(segment
		(start 439.923682 -231.316784)
		(end 441.028582 -231.316784)
		(width 0.20066)
		(layer "F.Cu")
		(net "M_G_CPU0_SB_DQ<2>")
	)
	(segment
		(start 443.15888 -231.748838)
		(end 443.450726 -231.748838)
		(width 0.20066)
		(layer "F.Cu")
		(net "M_G_CPU0_SB_DQ<2>")
	)
	(segment
		(start 382.418082 -241.80546)
		(end 382.407668 -241.799364)
		(width 0.088646)
		(layer "In6.Cu")
		(net "M_G_CPU0_SB_DQ<2>")
	)
	(segment
		(start 418.631878 -238.238538)
		(end 418.304218 -238.238538)
		(width 0.18288)
		(layer "In6.Cu")
		(net "M_G_CPU0_SB_DQ<2>")
	)
	(segment
		(start 388.131558 -241.55781)
		(end 387.749288 -241.94008)
		(width 0.088646)
		(layer "In6.Cu")
		(net "M_G_CPU0_SB_DQ<2>")
	)
	(segment
		(start 378.658882 -241.80546)
		(end 378.64415 -241.796824)
		(width 0.088646)
		(layer "In6.Cu")
		(net "M_G_CPU0_SB_DQ<2>")
	)
	(segment
		(start 430.961292 -235.907072)
		(end 429.847248 -235.907072)
		(width 0.18288)
		(layer "In6.Cu")
		(net "M_G_CPU0_SB_DQ<2>")
	)
	(segment
		(start 376.779536 -241.80546)
		(end 376.769122 -241.799364)
		(width 0.088646)
		(layer "In6.Cu")
		(net "M_G_CPU0_SB_DQ<2>")
	)
	(segment
		(start 407.335736 -236.903006)
		(end 407.335736 -236.371892)
		(width 0.18288)
		(layer "In6.Cu")
		(net "M_G_CPU0_SB_DQ<2>")
	)
	(segment
		(start 417.938458 -237.444026)
		(end 413.50057 -237.444026)
		(width 0.18288)
		(layer "In6.Cu")
		(net "M_G_CPU0_SB_DQ<2>")
	)
	(segment
		(start 381.478536 -241.80546)
		(end 381.468122 -241.799364)
		(width 0.088646)
		(layer "In6.Cu")
		(net "M_G_CPU0_SB_DQ<2>")
	)
	(segment
		(start 387.749288 -241.94008)
		(end 387.276086 -241.94008)
		(width 0.088646)
		(layer "In6.Cu")
		(net "M_G_CPU0_SB_DQ<2>")
	)
	(segment
		(start 438.997852 -231.316784)
		(end 438.572402 -231.742234)
		(width 0.18288)
		(layer "In6.Cu")
		(net "M_G_CPU0_SB_DQ<2>")
	)
	(segment
		(start 407.175716 -236.211872)
		(end 406.802336 -236.211872)
		(width 0.18288)
		(layer "In6.Cu")
		(net "M_G_CPU0_SB_DQ<2>")
	)
	(segment
		(start 437.121554 -231.23271)
		(end 436.938674 -231.04983)
		(width 0.18288)
		(layer "In6.Cu")
		(net "M_G_CPU0_SB_DQ<2>")
	)
	(segment
		(start 413.50057 -237.444026)
		(end 413.11957 -237.063026)
		(width 0.18288)
		(layer "In6.Cu")
		(net "M_G_CPU0_SB_DQ<2>")
	)
	(segment
		(start 396.44193 -241.55781)
		(end 388.382764 -241.55781)
		(width 0.18288)
		(layer "In6.Cu")
		(net "M_G_CPU0_SB_DQ<2>")
	)
	(segment
		(start 407.335736 -236.371892)
		(end 407.175716 -236.211872)
		(width 0.18288)
		(layer "In6.Cu")
		(net "M_G_CPU0_SB_DQ<2>")
	)
	(segment
		(start 418.814758 -237.626906)
		(end 418.814758 -238.055658)
		(width 0.18288)
		(layer "In6.Cu")
		(net "M_G_CPU0_SB_DQ<2>")
	)
	(segment
		(start 436.611014 -231.04983)
		(end 436.428134 -231.23271)
		(width 0.18288)
		(layer "In6.Cu")
		(net "M_G_CPU0_SB_DQ<2>")
	)
	(segment
		(start 388.382764 -241.55781)
		(end 388.131558 -241.55781)
		(width 0.088646)
		(layer "In6.Cu")
		(net "M_G_CPU0_SB_DQ<2>")
	)
	(segment
		(start 436.428134 -231.559354)
		(end 436.245254 -231.742234)
		(width 0.18288)
		(layer "In6.Cu")
		(net "M_G_CPU0_SB_DQ<2>")
	)
	(segment
		(start 377.719082 -241.80546)
		(end 377.708668 -241.799364)
		(width 0.088646)
		(layer "In6.Cu")
		(net "M_G_CPU0_SB_DQ<2>")
	)
	(segment
		(start 422.348406 -236.83849)
		(end 421.495474 -237.691422)
		(width 0.18288)
		(layer "In6.Cu")
		(net "M_G_CPU0_SB_DQ<2>")
	)
	(segment
		(start 420.185088 -237.691422)
		(end 419.937692 -237.444026)
		(width 0.18288)
		(layer "In6.Cu")
		(net "M_G_CPU0_SB_DQ<2>")
	)
	(segment
		(start 418.121338 -237.626906)
		(end 417.938458 -237.444026)
		(width 0.18288)
		(layer "In6.Cu")
		(net "M_G_CPU0_SB_DQ<2>")
	)
	(segment
		(start 418.814758 -238.055658)
		(end 418.631878 -238.238538)
		(width 0.18288)
		(layer "In6.Cu")
		(net "M_G_CPU0_SB_DQ<2>")
	)
	(segment
		(start 406.642316 -236.371892)
		(end 406.642316 -236.903006)
		(width 0.18288)
		(layer "In6.Cu")
		(net "M_G_CPU0_SB_DQ<2>")
	)
	(segment
		(start 375.656602 -241.538506)
		(end 375.714006 -241.481102)
		(width 0.088646)
		(layer "In6.Cu")
		(net "M_G_CPU0_SB_DQ<2>")
	)
	(segment
		(start 436.938674 -231.04983)
		(end 436.611014 -231.04983)
		(width 0.18288)
		(layer "In6.Cu")
		(net "M_G_CPU0_SB_DQ<2>")
	)
	(segment
		(start 418.997638 -237.444026)
		(end 418.814758 -237.626906)
		(width 0.18288)
		(layer "In6.Cu")
		(net "M_G_CPU0_SB_DQ<2>")
	)
	(segment
		(start 437.121554 -231.559354)
		(end 437.121554 -231.23271)
		(width 0.18288)
		(layer "In6.Cu")
		(net "M_G_CPU0_SB_DQ<2>")
	)
	(segment
		(start 400.936714 -237.063026)
		(end 396.44193 -241.55781)
		(width 0.18288)
		(layer "In6.Cu")
		(net "M_G_CPU0_SB_DQ<2>")
	)
	(segment
		(start 433.720494 -232.414826)
		(end 433.720494 -233.14787)
		(width 0.18288)
		(layer "In6.Cu")
		(net "M_G_CPU0_SB_DQ<2>")
	)
	(segment
		(start 434.393086 -231.742234)
		(end 433.720494 -232.414826)
		(width 0.18288)
		(layer "In6.Cu")
		(net "M_G_CPU0_SB_DQ<2>")
	)
	(segment
		(start 428.742094 -237.012226)
		(end 425.700952 -237.012226)
		(width 0.18288)
		(layer "In6.Cu")
		(net "M_G_CPU0_SB_DQ<2>")
	)
	(segment
		(start 406.802336 -236.211872)
		(end 406.642316 -236.371892)
		(width 0.18288)
		(layer "In6.Cu")
		(net "M_G_CPU0_SB_DQ<2>")
	)
	(segment
		(start 437.304434 -231.742234)
		(end 437.121554 -231.559354)
		(width 0.18288)
		(layer "In6.Cu")
		(net "M_G_CPU0_SB_DQ<2>")
	)
	(segment
		(start 433.720494 -233.14787)
		(end 430.961292 -235.907072)
		(width 0.18288)
		(layer "In6.Cu")
		(net "M_G_CPU0_SB_DQ<2>")
	)
	(segment
		(start 439.923682 -231.316784)
		(end 438.997852 -231.316784)
		(width 0.18288)
		(layer "In6.Cu")
		(net "M_G_CPU0_SB_DQ<2>")
	)
	(segment
		(start 419.937692 -237.444026)
		(end 418.997638 -237.444026)
		(width 0.18288)
		(layer "In6.Cu")
		(net "M_G_CPU0_SB_DQ<2>")
	)
	(segment
		(start 421.495474 -237.691422)
		(end 420.185088 -237.691422)
		(width 0.18288)
		(layer "In6.Cu")
		(net "M_G_CPU0_SB_DQ<2>")
	)
	(segment
		(start 429.847248 -235.907072)
		(end 428.742094 -237.012226)
		(width 0.18288)
		(layer "In6.Cu")
		(net "M_G_CPU0_SB_DQ<2>")
	)
	(segment
		(start 379.598682 -241.80546)
		(end 379.58395 -241.796824)
		(width 0.088646)
		(layer "In6.Cu")
		(net "M_G_CPU0_SB_DQ<2>")
	)
	(segment
		(start 375.714006 -241.481102)
		(end 376.02668 -241.481102)
		(width 0.088646)
		(layer "In6.Cu")
		(net "M_G_CPU0_SB_DQ<2>")
	)
	(segment
		(start 407.495756 -237.063026)
		(end 407.335736 -236.903006)
		(width 0.18288)
		(layer "In6.Cu")
		(net "M_G_CPU0_SB_DQ<2>")
	)
	(segment
		(start 406.482296 -237.063026)
		(end 400.936714 -237.063026)
		(width 0.18288)
		(layer "In6.Cu")
		(net "M_G_CPU0_SB_DQ<2>")
	)
	(segment
		(start 438.572402 -231.742234)
		(end 437.304434 -231.742234)
		(width 0.18288)
		(layer "In6.Cu")
		(net "M_G_CPU0_SB_DQ<2>")
	)
	(segment
		(start 425.527216 -236.83849)
		(end 422.348406 -236.83849)
		(width 0.18288)
		(layer "In6.Cu")
		(net "M_G_CPU0_SB_DQ<2>")
	)
	(segment
		(start 425.700952 -237.012226)
		(end 425.527216 -236.83849)
		(width 0.18288)
		(layer "In6.Cu")
		(net "M_G_CPU0_SB_DQ<2>")
	)
	(segment
		(start 418.121338 -238.055658)
		(end 418.121338 -237.626906)
		(width 0.18288)
		(layer "In6.Cu")
		(net "M_G_CPU0_SB_DQ<2>")
	)
	(segment
		(start 383.358136 -241.80546)
		(end 383.347722 -241.799364)
		(width 0.088646)
		(layer "In6.Cu")
		(net "M_G_CPU0_SB_DQ<2>")
	)
	(segment
		(start 375.839482 -241.80546)
		(end 375.830592 -241.80038)
		(width 0.088646)
		(layer "In6.Cu")
		(net "M_G_CPU0_SB_DQ<2>")
	)
	(segment
		(start 436.428134 -231.23271)
		(end 436.428134 -231.559354)
		(width 0.18288)
		(layer "In6.Cu")
		(net "M_G_CPU0_SB_DQ<2>")
	)
	(segment
		(start 436.245254 -231.742234)
		(end 434.393086 -231.742234)
		(width 0.18288)
		(layer "In6.Cu")
		(net "M_G_CPU0_SB_DQ<2>")
	)
	(segment
		(start 418.304218 -238.238538)
		(end 418.121338 -238.055658)
		(width 0.18288)
		(layer "In6.Cu")
		(net "M_G_CPU0_SB_DQ<2>")
	)
	(segment
		(start 387.276086 -241.94008)
		(end 387.164326 -241.82832)
		(width 0.088646)
		(layer "In6.Cu")
		(net "M_G_CPU0_SB_DQ<2>")
	)
	(segment
		(start 413.11957 -237.063026)
		(end 407.495756 -237.063026)
		(width 0.18288)
		(layer "In6.Cu")
		(net "M_G_CPU0_SB_DQ<2>")
	)
	(segment
		(start 380.538482 -241.80546)
		(end 380.52375 -241.796824)
		(width 0.088646)
		(layer "In6.Cu")
		(net "M_G_CPU0_SB_DQ<2>")
	)
	(segment
		(start 406.642316 -236.903006)
		(end 406.482296 -237.063026)
		(width 0.18288)
		(layer "In6.Cu")
		(net "M_G_CPU0_SB_DQ<2>")
	)
	(arc
		(start 384.297936 -241.80546)
		(mid 384.015234 -241.729684)
		(end 383.732532 -241.80546)
		(width 0.088646)
		(layer "In6.Cu")
		(net "M_G_CPU0_SB_DQ<2>")
	)
	(arc
		(start 383.732532 -241.80546)
		(mid 383.545334 -241.855603)
		(end 383.358136 -241.80546)
		(width 0.088646)
		(layer "In6.Cu")
		(net "M_G_CPU0_SB_DQ<2>")
	)
	(arc
		(start 379.033278 -241.80546)
		(mid 378.84608 -241.855603)
		(end 378.658882 -241.80546)
		(width 0.088646)
		(layer "In6.Cu")
		(net "M_G_CPU0_SB_DQ<2>")
	)
	(arc
		(start 380.912878 -241.80546)
		(mid 380.72568 -241.855603)
		(end 380.538482 -241.80546)
		(width 0.088646)
		(layer "In6.Cu")
		(net "M_G_CPU0_SB_DQ<2>")
	)
	(arc
		(start 381.468122 -241.799364)
		(mid 381.18969 -241.729518)
		(end 380.912878 -241.80546)
		(width 0.088646)
		(layer "In6.Cu")
		(net "M_G_CPU0_SB_DQ<2>")
	)
	(arc
		(start 376.213878 -241.80546)
		(mid 376.02668 -241.855603)
		(end 375.839482 -241.80546)
		(width 0.088646)
		(layer "In6.Cu")
		(net "M_G_CPU0_SB_DQ<2>")
	)
	(arc
		(start 381.852932 -241.80546)
		(mid 381.665734 -241.855603)
		(end 381.478536 -241.80546)
		(width 0.088646)
		(layer "In6.Cu")
		(net "M_G_CPU0_SB_DQ<2>")
	)
	(arc
		(start 387.164326 -241.82832)
		(mid 387.140431 -241.817712)
		(end 387.117336 -241.80546)
		(width 0.088646)
		(layer "In6.Cu")
		(net "M_G_CPU0_SB_DQ<2>")
	)
	(arc
		(start 386.177536 -241.80546)
		(mid 385.894834 -241.729684)
		(end 385.612132 -241.80546)
		(width 0.088646)
		(layer "In6.Cu")
		(net "M_G_CPU0_SB_DQ<2>")
	)
	(arc
		(start 386.551932 -241.80546)
		(mid 386.364734 -241.855603)
		(end 386.177536 -241.80546)
		(width 0.088646)
		(layer "In6.Cu")
		(net "M_G_CPU0_SB_DQ<2>")
	)
	(arc
		(start 376.769122 -241.799364)
		(mid 376.49069 -241.729518)
		(end 376.213878 -241.80546)
		(width 0.088646)
		(layer "In6.Cu")
		(net "M_G_CPU0_SB_DQ<2>")
	)
	(arc
		(start 380.52375 -241.796824)
		(mid 380.247275 -241.729504)
		(end 379.973078 -241.80546)
		(width 0.088646)
		(layer "In6.Cu")
		(net "M_G_CPU0_SB_DQ<2>")
	)
	(arc
		(start 379.973078 -241.80546)
		(mid 379.78588 -241.855603)
		(end 379.598682 -241.80546)
		(width 0.088646)
		(layer "In6.Cu")
		(net "M_G_CPU0_SB_DQ<2>")
	)
	(arc
		(start 378.093478 -241.80546)
		(mid 377.90628 -241.855603)
		(end 377.719082 -241.80546)
		(width 0.088646)
		(layer "In6.Cu")
		(net "M_G_CPU0_SB_DQ<2>")
	)
	(arc
		(start 379.58395 -241.796824)
		(mid 379.307475 -241.729504)
		(end 379.033278 -241.80546)
		(width 0.088646)
		(layer "In6.Cu")
		(net "M_G_CPU0_SB_DQ<2>")
	)
	(arc
		(start 385.612132 -241.80546)
		(mid 385.424934 -241.855603)
		(end 385.237736 -241.80546)
		(width 0.088646)
		(layer "In6.Cu")
		(net "M_G_CPU0_SB_DQ<2>")
	)
	(arc
		(start 375.830592 -241.80038)
		(mid 375.714853 -241.688556)
		(end 375.656602 -241.538506)
		(width 0.088646)
		(layer "In6.Cu")
		(net "M_G_CPU0_SB_DQ<2>")
	)
	(arc
		(start 377.708668 -241.799364)
		(mid 377.43049 -241.729641)
		(end 377.153932 -241.80546)
		(width 0.088646)
		(layer "In6.Cu")
		(net "M_G_CPU0_SB_DQ<2>")
	)
	(arc
		(start 385.237736 -241.80546)
		(mid 384.955034 -241.729684)
		(end 384.672332 -241.80546)
		(width 0.088646)
		(layer "In6.Cu")
		(net "M_G_CPU0_SB_DQ<2>")
	)
	(arc
		(start 377.153932 -241.80546)
		(mid 376.966734 -241.855603)
		(end 376.779536 -241.80546)
		(width 0.088646)
		(layer "In6.Cu")
		(net "M_G_CPU0_SB_DQ<2>")
	)
	(arc
		(start 384.672332 -241.80546)
		(mid 384.485134 -241.855603)
		(end 384.297936 -241.80546)
		(width 0.088646)
		(layer "In6.Cu")
		(net "M_G_CPU0_SB_DQ<2>")
	)
	(arc
		(start 382.792478 -241.80546)
		(mid 382.60528 -241.855603)
		(end 382.418082 -241.80546)
		(width 0.088646)
		(layer "In6.Cu")
		(net "M_G_CPU0_SB_DQ<2>")
	)
	(arc
		(start 387.117336 -241.80546)
		(mid 386.834634 -241.729684)
		(end 386.551932 -241.80546)
		(width 0.088646)
		(layer "In6.Cu")
		(net "M_G_CPU0_SB_DQ<2>")
	)
	(arc
		(start 382.407668 -241.799364)
		(mid 382.12949 -241.729641)
		(end 381.852932 -241.80546)
		(width 0.088646)
		(layer "In6.Cu")
		(net "M_G_CPU0_SB_DQ<2>")
	)
	(arc
		(start 378.64415 -241.796824)
		(mid 378.367675 -241.729504)
		(end 378.093478 -241.80546)
		(width 0.088646)
		(layer "In6.Cu")
		(net "M_G_CPU0_SB_DQ<2>")
	)
	(arc
		(start 383.347722 -241.799364)
		(mid 383.06929 -241.729518)
		(end 382.792478 -241.80546)
		(width 0.088646)
		(layer "In6.Cu")
		(net "M_G_CPU0_SB_DQ<2>")
	)
	(segment
		(start 383.545334 -217.600276)
		(end 383.545334 -217.064336)
		(width 0.20066)
		(layer "F.Cu")
		(net "M_G_CPU0_SB_DQ<29>")
	)
	(segment
		(start 442.880496 -196.466968)
		(end 442.44895 -196.035422)
		(width 0.20066)
		(layer "F.Cu")
		(net "M_G_CPU0_SB_DQ<29>")
	)
	(segment
		(start 439.173112 -196.71538)
		(end 438.697878 -196.71538)
		(width 0.20066)
		(layer "F.Cu")
		(net "M_G_CPU0_SB_DQ<29>")
	)
	(segment
		(start 436.928514 -196.466714)
		(end 435.823614 -196.466714)
		(width 0.20066)
		(layer "F.Cu")
		(net "M_G_CPU0_SB_DQ<29>")
	)
	(segment
		(start 439.361072 -196.159882)
		(end 439.361072 -196.52742)
		(width 0.20066)
		(layer "F.Cu")
		(net "M_G_CPU0_SB_DQ<29>")
	)
	(segment
		(start 439.82386 -196.041772)
		(end 439.479182 -196.041772)
		(width 0.20066)
		(layer "F.Cu")
		(net "M_G_CPU0_SB_DQ<29>")
	)
	(segment
		(start 439.479182 -196.041772)
		(end 439.361072 -196.159882)
		(width 0.20066)
		(layer "F.Cu")
		(net "M_G_CPU0_SB_DQ<29>")
	)
	(segment
		(start 442.032644 -196.041772)
		(end 439.843926 -196.041772)
		(width 0.1016)
		(layer "F.Cu")
		(net "M_G_CPU0_SB_DQ<29>")
	)
	(segment
		(start 442.44895 -196.035422)
		(end 442.038994 -196.035422)
		(width 0.20066)
		(layer "F.Cu")
		(net "M_G_CPU0_SB_DQ<29>")
	)
	(segment
		(start 442.038994 -196.035422)
		(end 442.032644 -196.041772)
		(width 0.1016)
		(layer "F.Cu")
		(net "M_G_CPU0_SB_DQ<29>")
	)
	(segment
		(start 439.361072 -196.52742)
		(end 439.173112 -196.71538)
		(width 0.20066)
		(layer "F.Cu")
		(net "M_G_CPU0_SB_DQ<29>")
	)
	(segment
		(start 439.843926 -196.041772)
		(end 439.82386 -196.041772)
		(width 0.101854)
		(layer "F.Cu")
		(net "M_G_CPU0_SB_DQ<29>")
	)
	(segment
		(start 438.697878 -196.71538)
		(end 438.449212 -196.466714)
		(width 0.20066)
		(layer "F.Cu")
		(net "M_G_CPU0_SB_DQ<29>")
	)
	(segment
		(start 438.449212 -196.466714)
		(end 436.928514 -196.466714)
		(width 0.20066)
		(layer "F.Cu")
		(net "M_G_CPU0_SB_DQ<29>")
	)
	(segment
		(start 444.47206 -196.466968)
		(end 442.880496 -196.466968)
		(width 0.20066)
		(layer "F.Cu")
		(net "M_G_CPU0_SB_DQ<29>")
	)
	(segment
		(start 444.472314 -196.466714)
		(end 444.47206 -196.466968)
		(width 0.20066)
		(layer "F.Cu")
		(net "M_G_CPU0_SB_DQ<29>")
	)
	(segment
		(start 408.231594 -195.305426)
		(end 408.055064 -195.128896)
		(width 0.18288)
		(layer "In6.Cu")
		(net "M_G_CPU0_SB_DQ<29>")
	)
	(segment
		(start 408.238198 -195.305426)
		(end 408.231594 -195.305426)
		(width 0.18288)
		(layer "In6.Cu")
		(net "M_G_CPU0_SB_DQ<29>")
	)
	(segment
		(start 385.203192 -216.539572)
		(end 385.142232 -216.574878)
		(width 0.088646)
		(layer "In6.Cu")
		(net "M_G_CPU0_SB_DQ<29>")
	)
	(segment
		(start 385.708398 -215.923368)
		(end 385.707128 -215.923876)
		(width 0.088646)
		(layer "In6.Cu")
		(net "M_G_CPU0_SB_DQ<29>")
	)
	(segment
		(start 418.59454 -194.845686)
		(end 418.26688 -194.845686)
		(width 0.18288)
		(layer "In6.Cu")
		(net "M_G_CPU0_SB_DQ<29>")
	)
	(segment
		(start 405.51862 -195.128896)
		(end 394.69695 -205.950566)
		(width 0.18288)
		(layer "In6.Cu")
		(net "M_G_CPU0_SB_DQ<29>")
	)
	(segment
		(start 386.08635 -215.925908)
		(end 386.082032 -215.923368)
		(width 0.088646)
		(layer "In6.Cu")
		(net "M_G_CPU0_SB_DQ<29>")
	)
	(segment
		(start 418.77742 -194.662806)
		(end 418.59454 -194.845686)
		(width 0.18288)
		(layer "In6.Cu")
		(net "M_G_CPU0_SB_DQ<29>")
	)
	(segment
		(start 414.996122 -194.987672)
		(end 414.996122 -194.482466)
		(width 0.18288)
		(layer "In6.Cu")
		(net "M_G_CPU0_SB_DQ<29>")
	)
	(segment
		(start 411.355794 -194.299586)
		(end 410.320744 -195.334636)
		(width 0.18288)
		(layer "In6.Cu")
		(net "M_G_CPU0_SB_DQ<29>")
	)
	(segment
		(start 414.996122 -194.482466)
		(end 414.813242 -194.299586)
		(width 0.18288)
		(layer "In6.Cu")
		(net "M_G_CPU0_SB_DQ<29>")
	)
	(segment
		(start 418.084 -194.662806)
		(end 418.084 -194.482466)
		(width 0.18288)
		(layer "In6.Cu")
		(net "M_G_CPU0_SB_DQ<29>")
	)
	(segment
		(start 394.69695 -208.339182)
		(end 388.451598 -214.584534)
		(width 0.18288)
		(layer "In6.Cu")
		(net "M_G_CPU0_SB_DQ<29>")
	)
	(segment
		(start 408.055064 -195.128896)
		(end 405.51862 -195.128896)
		(width 0.18288)
		(layer "In6.Cu")
		(net "M_G_CPU0_SB_DQ<29>")
	)
	(segment
		(start 418.77742 -194.482466)
		(end 418.77742 -194.662806)
		(width 0.18288)
		(layer "In6.Cu")
		(net "M_G_CPU0_SB_DQ<29>")
	)
	(segment
		(start 418.084 -194.482466)
		(end 417.90112 -194.299586)
		(width 0.18288)
		(layer "In6.Cu")
		(net "M_G_CPU0_SB_DQ<29>")
	)
	(segment
		(start 385.502404 -216.292938)
		(end 385.429506 -216.36609)
		(width 0.088646)
		(layer "In6.Cu")
		(net "M_G_CPU0_SB_DQ<29>")
	)
	(segment
		(start 410.320744 -195.334636)
		(end 408.267408 -195.334636)
		(width 0.18288)
		(layer "In6.Cu")
		(net "M_G_CPU0_SB_DQ<29>")
	)
	(segment
		(start 388.297166 -214.738966)
		(end 388.297166 -215.450928)
		(width 0.088646)
		(layer "In6.Cu")
		(net "M_G_CPU0_SB_DQ<29>")
	)
	(segment
		(start 415.872422 -194.299586)
		(end 415.689542 -194.482466)
		(width 0.18288)
		(layer "In6.Cu")
		(net "M_G_CPU0_SB_DQ<29>")
	)
	(segment
		(start 383.78003 -217.356182)
		(end 383.701798 -217.335354)
		(width 0.088646)
		(layer "In6.Cu")
		(net "M_G_CPU0_SB_DQ<29>")
	)
	(segment
		(start 415.506662 -195.170552)
		(end 415.179002 -195.170552)
		(width 0.18288)
		(layer "In6.Cu")
		(net "M_G_CPU0_SB_DQ<29>")
	)
	(segment
		(start 415.689542 -194.987672)
		(end 415.506662 -195.170552)
		(width 0.18288)
		(layer "In6.Cu")
		(net "M_G_CPU0_SB_DQ<29>")
	)
	(segment
		(start 408.267408 -195.334636)
		(end 408.238198 -195.305426)
		(width 0.18288)
		(layer "In6.Cu")
		(net "M_G_CPU0_SB_DQ<29>")
	)
	(segment
		(start 414.813242 -194.299586)
		(end 411.355794 -194.299586)
		(width 0.18288)
		(layer "In6.Cu")
		(net "M_G_CPU0_SB_DQ<29>")
	)
	(segment
		(start 387.872986 -215.875108)
		(end 387.774942 -215.875108)
		(width 0.088646)
		(layer "In6.Cu")
		(net "M_G_CPU0_SB_DQ<29>")
	)
	(segment
		(start 385.520438 -216.247218)
		(end 385.520438 -216.249758)
		(width 0.088646)
		(layer "In6.Cu")
		(net "M_G_CPU0_SB_DQ<29>")
	)
	(segment
		(start 435.823614 -196.466714)
		(end 434.549296 -195.192396)
		(width 0.18288)
		(layer "In6.Cu")
		(net "M_G_CPU0_SB_DQ<29>")
	)
	(segment
		(start 434.549296 -195.192396)
		(end 424.38701 -195.192396)
		(width 0.18288)
		(layer "In6.Cu")
		(net "M_G_CPU0_SB_DQ<29>")
	)
	(segment
		(start 424.38701 -195.192396)
		(end 423.4942 -194.299586)
		(width 0.18288)
		(layer "In6.Cu")
		(net "M_G_CPU0_SB_DQ<29>")
	)
	(segment
		(start 388.451598 -214.584534)
		(end 388.297166 -214.738966)
		(width 0.088646)
		(layer "In6.Cu")
		(net "M_G_CPU0_SB_DQ<29>")
	)
	(segment
		(start 415.179002 -195.170552)
		(end 414.996122 -194.987672)
		(width 0.18288)
		(layer "In6.Cu")
		(net "M_G_CPU0_SB_DQ<29>")
	)
	(segment
		(start 388.297166 -215.450928)
		(end 387.872986 -215.875108)
		(width 0.088646)
		(layer "In6.Cu")
		(net "M_G_CPU0_SB_DQ<29>")
	)
	(segment
		(start 418.26688 -194.845686)
		(end 418.084 -194.662806)
		(width 0.18288)
		(layer "In6.Cu")
		(net "M_G_CPU0_SB_DQ<29>")
	)
	(segment
		(start 417.90112 -194.299586)
		(end 415.872422 -194.299586)
		(width 0.18288)
		(layer "In6.Cu")
		(net "M_G_CPU0_SB_DQ<29>")
	)
	(segment
		(start 394.69695 -205.950566)
		(end 394.69695 -208.339182)
		(width 0.18288)
		(layer "In6.Cu")
		(net "M_G_CPU0_SB_DQ<29>")
	)
	(segment
		(start 387.022086 -215.925908)
		(end 387.013704 -215.921082)
		(width 0.088646)
		(layer "In6.Cu")
		(net "M_G_CPU0_SB_DQ<29>")
	)
	(segment
		(start 418.9603 -194.299586)
		(end 418.77742 -194.482466)
		(width 0.18288)
		(layer "In6.Cu")
		(net "M_G_CPU0_SB_DQ<29>")
	)
	(segment
		(start 387.0325 -215.932004)
		(end 387.022086 -215.925908)
		(width 0.088646)
		(layer "In6.Cu")
		(net "M_G_CPU0_SB_DQ<29>")
	)
	(segment
		(start 383.701798 -217.335354)
		(end 383.545334 -217.064336)
		(width 0.088646)
		(layer "In6.Cu")
		(net "M_G_CPU0_SB_DQ<29>")
	)
	(segment
		(start 423.4942 -194.299586)
		(end 418.9603 -194.299586)
		(width 0.18288)
		(layer "In6.Cu")
		(net "M_G_CPU0_SB_DQ<29>")
	)
	(segment
		(start 383.919984 -217.05443)
		(end 383.919984 -217.064336)
		(width 0.088646)
		(layer "In6.Cu")
		(net "M_G_CPU0_SB_DQ<29>")
	)
	(segment
		(start 415.689542 -194.482466)
		(end 415.689542 -194.987672)
		(width 0.18288)
		(layer "In6.Cu")
		(net "M_G_CPU0_SB_DQ<29>")
	)
	(arc
		(start 385.520438 -216.249758)
		(mid 385.515696 -216.27313)
		(end 385.502404 -216.292938)
		(width 0.088646)
		(layer "In6.Cu")
		(net "M_G_CPU0_SB_DQ<29>")
	)
	(arc
		(start 384.202432 -216.574878)
		(mid 383.998097 -216.777483)
		(end 383.919984 -217.05443)
		(width 0.088646)
		(layer "In6.Cu")
		(net "M_G_CPU0_SB_DQ<29>")
	)
	(arc
		(start 383.919984 -217.064336)
		(mid 383.883124 -217.226133)
		(end 383.78003 -217.356182)
		(width 0.088646)
		(layer "In6.Cu")
		(net "M_G_CPU0_SB_DQ<29>")
	)
	(arc
		(start 386.647944 -215.925908)
		(mid 386.367164 -216.001179)
		(end 386.08635 -215.925908)
		(width 0.088646)
		(layer "In6.Cu")
		(net "M_G_CPU0_SB_DQ<29>")
	)
	(arc
		(start 387.587744 -215.925908)
		(mid 387.310931 -216.001812)
		(end 387.0325 -215.932004)
		(width 0.088646)
		(layer "In6.Cu")
		(net "M_G_CPU0_SB_DQ<29>")
	)
	(arc
		(start 387.013704 -215.921082)
		(mid 386.830196 -215.875742)
		(end 386.647944 -215.925908)
		(width 0.088646)
		(layer "In6.Cu")
		(net "M_G_CPU0_SB_DQ<29>")
	)
	(arc
		(start 385.707128 -215.923876)
		(mid 385.570471 -216.060537)
		(end 385.520438 -216.247218)
		(width 0.088646)
		(layer "In6.Cu")
		(net "M_G_CPU0_SB_DQ<29>")
	)
	(arc
		(start 384.767836 -216.574878)
		(mid 384.485134 -216.499102)
		(end 384.202432 -216.574878)
		(width 0.088646)
		(layer "In6.Cu")
		(net "M_G_CPU0_SB_DQ<29>")
	)
	(arc
		(start 386.082032 -215.923368)
		(mid 385.895232 -215.873343)
		(end 385.708398 -215.923368)
		(width 0.088646)
		(layer "In6.Cu")
		(net "M_G_CPU0_SB_DQ<29>")
	)
	(arc
		(start 387.774942 -215.875108)
		(mid 387.677987 -215.888152)
		(end 387.587744 -215.925908)
		(width 0.088646)
		(layer "In6.Cu")
		(net "M_G_CPU0_SB_DQ<29>")
	)
	(arc
		(start 385.429506 -216.36609)
		(mid 385.322042 -216.460259)
		(end 385.203192 -216.539572)
		(width 0.088646)
		(layer "In6.Cu")
		(net "M_G_CPU0_SB_DQ<29>")
	)
	(arc
		(start 385.142232 -216.574878)
		(mid 384.955034 -216.625021)
		(end 384.767836 -216.574878)
		(width 0.088646)
		(layer "In6.Cu")
		(net "M_G_CPU0_SB_DQ<29>")
	)
	(segment
		(start 444.47206 -198.16699)
		(end 442.880496 -198.16699)
		(width 0.20066)
		(layer "F.Cu")
		(net "M_G_CPU0_SB_DQ<28>")
	)
	(segment
		(start 444.472314 -198.166736)
		(end 444.47206 -198.16699)
		(width 0.20066)
		(layer "F.Cu")
		(net "M_G_CPU0_SB_DQ<28>")
	)
	(segment
		(start 442.880496 -198.16699)
		(end 442.44895 -197.735444)
		(width 0.20066)
		(layer "F.Cu")
		(net "M_G_CPU0_SB_DQ<28>")
	)
	(segment
		(start 439.82386 -197.741794)
		(end 439.479182 -197.741794)
		(width 0.20066)
		(layer "F.Cu")
		(net "M_G_CPU0_SB_DQ<28>")
	)
	(segment
		(start 442.44895 -197.735444)
		(end 442.038994 -197.735444)
		(width 0.20066)
		(layer "F.Cu")
		(net "M_G_CPU0_SB_DQ<28>")
	)
	(segment
		(start 439.87085 -197.741794)
		(end 439.82386 -197.741794)
		(width 0.101854)
		(layer "F.Cu")
		(net "M_G_CPU0_SB_DQ<28>")
	)
	(segment
		(start 442.038994 -197.735444)
		(end 442.032644 -197.741794)
		(width 0.1016)
		(layer "F.Cu")
		(net "M_G_CPU0_SB_DQ<28>")
	)
	(segment
		(start 384.015234 -217.878406)
		(end 384.015234 -218.414346)
		(width 0.20066)
		(layer "F.Cu")
		(net "M_G_CPU0_SB_DQ<28>")
	)
	(segment
		(start 438.697878 -198.415402)
		(end 438.449212 -198.166736)
		(width 0.20066)
		(layer "F.Cu")
		(net "M_G_CPU0_SB_DQ<28>")
	)
	(segment
		(start 439.361072 -197.859904)
		(end 439.361072 -198.227442)
		(width 0.20066)
		(layer "F.Cu")
		(net "M_G_CPU0_SB_DQ<28>")
	)
	(segment
		(start 439.479182 -197.741794)
		(end 439.361072 -197.859904)
		(width 0.20066)
		(layer "F.Cu")
		(net "M_G_CPU0_SB_DQ<28>")
	)
	(segment
		(start 439.173112 -198.415402)
		(end 438.697878 -198.415402)
		(width 0.20066)
		(layer "F.Cu")
		(net "M_G_CPU0_SB_DQ<28>")
	)
	(segment
		(start 438.449212 -198.166736)
		(end 436.928514 -198.166736)
		(width 0.20066)
		(layer "F.Cu")
		(net "M_G_CPU0_SB_DQ<28>")
	)
	(segment
		(start 436.928514 -198.166736)
		(end 435.823614 -198.166736)
		(width 0.20066)
		(layer "F.Cu")
		(net "M_G_CPU0_SB_DQ<28>")
	)
	(segment
		(start 442.032644 -197.741794)
		(end 439.87085 -197.741794)
		(width 0.1016)
		(layer "F.Cu")
		(net "M_G_CPU0_SB_DQ<28>")
	)
	(segment
		(start 439.361072 -198.227442)
		(end 439.173112 -198.415402)
		(width 0.20066)
		(layer "F.Cu")
		(net "M_G_CPU0_SB_DQ<28>")
	)
	(segment
		(start 388.351522 -216.689178)
		(end 388.244334 -216.689178)
		(width 0.088646)
		(layer "In6.Cu")
		(net "M_G_CPU0_SB_DQ<28>")
	)
	(segment
		(start 384.297936 -216.739978)
		(end 384.289046 -216.745058)
		(width 0.088646)
		(layer "In6.Cu")
		(net "M_G_CPU0_SB_DQ<28>")
	)
	(segment
		(start 431.35296 -196.892418)
		(end 423.979086 -196.892418)
		(width 0.18288)
		(layer "In6.Cu")
		(net "M_G_CPU0_SB_DQ<28>")
	)
	(segment
		(start 406.441148 -196.751194)
		(end 406.258268 -196.568314)
		(width 0.18288)
		(layer "In6.Cu")
		(net "M_G_CPU0_SB_DQ<28>")
	)
	(segment
		(start 406.624028 -197.308724)
		(end 406.441148 -197.125844)
		(width 0.18288)
		(layer "In6.Cu")
		(net "M_G_CPU0_SB_DQ<28>")
	)
	(segment
		(start 414.676082 -197.096126)
		(end 414.493202 -197.279006)
		(width 0.18288)
		(layer "In6.Cu")
		(net "M_G_CPU0_SB_DQ<28>")
	)
	(segment
		(start 389.198358 -215.331548)
		(end 388.977886 -215.55202)
		(width 0.088646)
		(layer "In6.Cu")
		(net "M_G_CPU0_SB_DQ<28>")
	)
	(segment
		(start 408.574494 -196.905626)
		(end 408.237182 -196.568314)
		(width 0.18288)
		(layer "In6.Cu")
		(net "M_G_CPU0_SB_DQ<28>")
	)
	(segment
		(start 435.823614 -198.166736)
		(end 435.197504 -197.540626)
		(width 0.18288)
		(layer "In6.Cu")
		(net "M_G_CPU0_SB_DQ<28>")
	)
	(segment
		(start 413.799782 -196.641466)
		(end 412.648654 -196.641466)
		(width 0.18288)
		(layer "In6.Cu")
		(net "M_G_CPU0_SB_DQ<28>")
	)
	(segment
		(start 406.951688 -197.308724)
		(end 406.624028 -197.308724)
		(width 0.18288)
		(layer "In6.Cu")
		(net "M_G_CPU0_SB_DQ<28>")
	)
	(segment
		(start 412.384494 -196.905626)
		(end 408.574494 -196.905626)
		(width 0.18288)
		(layer "In6.Cu")
		(net "M_G_CPU0_SB_DQ<28>")
	)
	(segment
		(start 418.794692 -196.466714)
		(end 418.611812 -196.649594)
		(width 0.18288)
		(layer "In6.Cu")
		(net "M_G_CPU0_SB_DQ<28>")
	)
	(segment
		(start 383.85877 -217.607388)
		(end 384.015234 -217.878406)
		(width 0.088646)
		(layer "In6.Cu")
		(net "M_G_CPU0_SB_DQ<28>")
	)
	(segment
		(start 386.185918 -216.734898)
		(end 386.177536 -216.739724)
		(width 0.088646)
		(layer "In6.Cu")
		(net "M_G_CPU0_SB_DQ<28>")
	)
	(segment
		(start 435.197504 -197.540626)
		(end 432.001168 -197.540626)
		(width 0.18288)
		(layer "In6.Cu")
		(net "M_G_CPU0_SB_DQ<28>")
	)
	(segment
		(start 406.441148 -197.125844)
		(end 406.441148 -196.751194)
		(width 0.18288)
		(layer "In6.Cu")
		(net "M_G_CPU0_SB_DQ<28>")
	)
	(segment
		(start 388.977886 -216.062814)
		(end 388.351522 -216.689178)
		(width 0.088646)
		(layer "In6.Cu")
		(net "M_G_CPU0_SB_DQ<28>")
	)
	(segment
		(start 414.676082 -196.824346)
		(end 414.676082 -197.096126)
		(width 0.18288)
		(layer "In6.Cu")
		(net "M_G_CPU0_SB_DQ<28>")
	)
	(segment
		(start 414.493202 -197.279006)
		(end 414.165542 -197.279006)
		(width 0.18288)
		(layer "In6.Cu")
		(net "M_G_CPU0_SB_DQ<28>")
	)
	(segment
		(start 407.134568 -196.751194)
		(end 407.134568 -197.125844)
		(width 0.18288)
		(layer "In6.Cu")
		(net "M_G_CPU0_SB_DQ<28>")
	)
	(segment
		(start 405.653748 -196.568314)
		(end 395.785086 -206.436976)
		(width 0.18288)
		(layer "In6.Cu")
		(net "M_G_CPU0_SB_DQ<28>")
	)
	(segment
		(start 418.794692 -196.097906)
		(end 418.794692 -196.466714)
		(width 0.18288)
		(layer "In6.Cu")
		(net "M_G_CPU0_SB_DQ<28>")
	)
	(segment
		(start 417.06673 -195.915026)
		(end 416.34029 -196.641466)
		(width 0.18288)
		(layer "In6.Cu")
		(net "M_G_CPU0_SB_DQ<28>")
	)
	(segment
		(start 419.928548 -196.04228)
		(end 419.801294 -195.915026)
		(width 0.18288)
		(layer "In6.Cu")
		(net "M_G_CPU0_SB_DQ<28>")
	)
	(segment
		(start 387.129528 -216.732866)
		(end 387.11759 -216.739724)
		(width 0.088646)
		(layer "In6.Cu")
		(net "M_G_CPU0_SB_DQ<28>")
	)
	(segment
		(start 418.101272 -196.097906)
		(end 417.918392 -195.915026)
		(width 0.18288)
		(layer "In6.Cu")
		(net "M_G_CPU0_SB_DQ<28>")
	)
	(segment
		(start 395.785086 -208.74482)
		(end 389.198358 -215.331548)
		(width 0.18288)
		(layer "In6.Cu")
		(net "M_G_CPU0_SB_DQ<28>")
	)
	(segment
		(start 388.977886 -215.55202)
		(end 388.977886 -216.062814)
		(width 0.088646)
		(layer "In6.Cu")
		(net "M_G_CPU0_SB_DQ<28>")
	)
	(segment
		(start 419.801294 -195.915026)
		(end 418.977572 -195.915026)
		(width 0.18288)
		(layer "In6.Cu")
		(net "M_G_CPU0_SB_DQ<28>")
	)
	(segment
		(start 418.611812 -196.649594)
		(end 418.284152 -196.649594)
		(width 0.18288)
		(layer "In6.Cu")
		(net "M_G_CPU0_SB_DQ<28>")
	)
	(segment
		(start 387.11759 -216.739724)
		(end 387.102858 -216.74836)
		(width 0.088646)
		(layer "In6.Cu")
		(net "M_G_CPU0_SB_DQ<28>")
	)
	(segment
		(start 412.648654 -196.641466)
		(end 412.384494 -196.905626)
		(width 0.18288)
		(layer "In6.Cu")
		(net "M_G_CPU0_SB_DQ<28>")
	)
	(segment
		(start 418.977572 -195.915026)
		(end 418.794692 -196.097906)
		(width 0.18288)
		(layer "In6.Cu")
		(net "M_G_CPU0_SB_DQ<28>")
	)
	(segment
		(start 407.134568 -197.125844)
		(end 406.951688 -197.308724)
		(width 0.18288)
		(layer "In6.Cu")
		(net "M_G_CPU0_SB_DQ<28>")
	)
	(segment
		(start 395.785086 -206.436976)
		(end 395.785086 -208.74482)
		(width 0.18288)
		(layer "In6.Cu")
		(net "M_G_CPU0_SB_DQ<28>")
	)
	(segment
		(start 414.165542 -197.279006)
		(end 413.982662 -197.096126)
		(width 0.18288)
		(layer "In6.Cu")
		(net "M_G_CPU0_SB_DQ<28>")
	)
	(segment
		(start 413.982662 -197.096126)
		(end 413.982662 -196.824346)
		(width 0.18288)
		(layer "In6.Cu")
		(net "M_G_CPU0_SB_DQ<28>")
	)
	(segment
		(start 384.110484 -217.064336)
		(end 384.110484 -217.082878)
		(width 0.088646)
		(layer "In6.Cu")
		(net "M_G_CPU0_SB_DQ<28>")
	)
	(segment
		(start 407.317448 -196.568314)
		(end 407.134568 -196.751194)
		(width 0.18288)
		(layer "In6.Cu")
		(net "M_G_CPU0_SB_DQ<28>")
	)
	(segment
		(start 385.488942 -216.68867)
		(end 385.429252 -216.68867)
		(width 0.088646)
		(layer "In6.Cu")
		(net "M_G_CPU0_SB_DQ<28>")
	)
	(segment
		(start 413.982662 -196.824346)
		(end 413.799782 -196.641466)
		(width 0.18288)
		(layer "In6.Cu")
		(net "M_G_CPU0_SB_DQ<28>")
	)
	(segment
		(start 418.284152 -196.649594)
		(end 418.101272 -196.466714)
		(width 0.18288)
		(layer "In6.Cu")
		(net "M_G_CPU0_SB_DQ<28>")
	)
	(segment
		(start 432.001168 -197.540626)
		(end 431.35296 -196.892418)
		(width 0.18288)
		(layer "In6.Cu")
		(net "M_G_CPU0_SB_DQ<28>")
	)
	(segment
		(start 423.979086 -196.892418)
		(end 423.128948 -196.04228)
		(width 0.18288)
		(layer "In6.Cu")
		(net "M_G_CPU0_SB_DQ<28>")
	)
	(segment
		(start 416.34029 -196.641466)
		(end 414.858962 -196.641466)
		(width 0.18288)
		(layer "In6.Cu")
		(net "M_G_CPU0_SB_DQ<28>")
	)
	(segment
		(start 383.8829 -217.518234)
		(end 383.85877 -217.607388)
		(width 0.088646)
		(layer "In6.Cu")
		(net "M_G_CPU0_SB_DQ<28>")
	)
	(segment
		(start 408.237182 -196.568314)
		(end 407.317448 -196.568314)
		(width 0.18288)
		(layer "In6.Cu")
		(net "M_G_CPU0_SB_DQ<28>")
	)
	(segment
		(start 414.858962 -196.641466)
		(end 414.676082 -196.824346)
		(width 0.18288)
		(layer "In6.Cu")
		(net "M_G_CPU0_SB_DQ<28>")
	)
	(segment
		(start 417.918392 -195.915026)
		(end 417.06673 -195.915026)
		(width 0.18288)
		(layer "In6.Cu")
		(net "M_G_CPU0_SB_DQ<28>")
	)
	(segment
		(start 418.101272 -196.466714)
		(end 418.101272 -196.097906)
		(width 0.18288)
		(layer "In6.Cu")
		(net "M_G_CPU0_SB_DQ<28>")
	)
	(segment
		(start 423.128948 -196.04228)
		(end 419.928548 -196.04228)
		(width 0.18288)
		(layer "In6.Cu")
		(net "M_G_CPU0_SB_DQ<28>")
	)
	(segment
		(start 406.258268 -196.568314)
		(end 405.653748 -196.568314)
		(width 0.18288)
		(layer "In6.Cu")
		(net "M_G_CPU0_SB_DQ<28>")
	)
	(arc
		(start 387.102858 -216.74836)
		(mid 386.826417 -216.815496)
		(end 386.552186 -216.739724)
		(width 0.088646)
		(layer "In6.Cu")
		(net "M_G_CPU0_SB_DQ<28>")
	)
	(arc
		(start 384.672332 -216.739978)
		(mid 384.485134 -216.689835)
		(end 384.297936 -216.739978)
		(width 0.088646)
		(layer "In6.Cu")
		(net "M_G_CPU0_SB_DQ<28>")
	)
	(arc
		(start 388.244334 -216.689178)
		(mid 388.139265 -216.70435)
		(end 388.042658 -216.74836)
		(width 0.088646)
		(layer "In6.Cu")
		(net "M_G_CPU0_SB_DQ<28>")
	)
	(arc
		(start 384.110484 -217.082878)
		(mid 384.046435 -217.326558)
		(end 383.8829 -217.518234)
		(width 0.088646)
		(layer "In6.Cu")
		(net "M_G_CPU0_SB_DQ<28>")
	)
	(arc
		(start 385.237736 -216.739978)
		(mid 384.955034 -216.815754)
		(end 384.672332 -216.739978)
		(width 0.088646)
		(layer "In6.Cu")
		(net "M_G_CPU0_SB_DQ<28>")
	)
	(arc
		(start 388.042658 -216.74836)
		(mid 387.766217 -216.815496)
		(end 387.491986 -216.739724)
		(width 0.088646)
		(layer "In6.Cu")
		(net "M_G_CPU0_SB_DQ<28>")
	)
	(arc
		(start 384.289046 -216.745058)
		(mid 384.158132 -216.881418)
		(end 384.110484 -217.064336)
		(width 0.088646)
		(layer "In6.Cu")
		(net "M_G_CPU0_SB_DQ<28>")
	)
	(arc
		(start 385.612132 -216.739724)
		(mid 385.555612 -216.701959)
		(end 385.488942 -216.68867)
		(width 0.088646)
		(layer "In6.Cu")
		(net "M_G_CPU0_SB_DQ<28>")
	)
	(arc
		(start 387.491986 -216.739724)
		(mid 387.311639 -216.689555)
		(end 387.129528 -216.732866)
		(width 0.088646)
		(layer "In6.Cu")
		(net "M_G_CPU0_SB_DQ<28>")
	)
	(arc
		(start 386.552186 -216.739724)
		(mid 386.369681 -216.68952)
		(end 386.185918 -216.734898)
		(width 0.088646)
		(layer "In6.Cu")
		(net "M_G_CPU0_SB_DQ<28>")
	)
	(arc
		(start 385.429252 -216.68867)
		(mid 385.330123 -216.701729)
		(end 385.237736 -216.739978)
		(width 0.088646)
		(layer "In6.Cu")
		(net "M_G_CPU0_SB_DQ<28>")
	)
	(arc
		(start 386.177536 -216.739724)
		(mid 385.894834 -216.815432)
		(end 385.612132 -216.739724)
		(width 0.088646)
		(layer "In6.Cu")
		(net "M_G_CPU0_SB_DQ<28>")
	)
	(segment
		(start 442.726826 -201.56678)
		(end 443.15888 -201.998834)
		(width 0.20066)
		(layer "F.Cu")
		(net "M_G_CPU0_SB_DQ<27>")
	)
	(segment
		(start 443.15888 -201.998834)
		(end 443.450726 -201.998834)
		(width 0.20066)
		(layer "F.Cu")
		(net "M_G_CPU0_SB_DQ<27>")
	)
	(segment
		(start 446.986152 -201.314812)
		(end 447.23812 -201.56678)
		(width 0.20066)
		(layer "F.Cu")
		(net "M_G_CPU0_SB_DQ<27>")
	)
	(segment
		(start 441.028582 -201.56678)
		(end 442.726826 -201.56678)
		(width 0.20066)
		(layer "F.Cu")
		(net "M_G_CPU0_SB_DQ<27>")
	)
	(segment
		(start 447.23812 -201.56678)
		(end 448.572382 -201.56678)
		(width 0.20066)
		(layer "F.Cu")
		(net "M_G_CPU0_SB_DQ<27>")
	)
	(segment
		(start 443.455552 -201.998834)
		(end 443.462664 -201.991722)
		(width 0.1016)
		(layer "F.Cu")
		(net "M_G_CPU0_SB_DQ<27>")
	)
	(segment
		(start 446.163954 -202.003914)
		(end 446.367916 -201.799952)
		(width 0.20066)
		(layer "F.Cu")
		(net "M_G_CPU0_SB_DQ<27>")
	)
	(segment
		(start 439.923682 -201.56678)
		(end 441.028582 -201.56678)
		(width 0.20066)
		(layer "F.Cu")
		(net "M_G_CPU0_SB_DQ<27>")
	)
	(segment
		(start 445.482726 -202.003914)
		(end 446.163954 -202.003914)
		(width 0.20066)
		(layer "F.Cu")
		(net "M_G_CPU0_SB_DQ<27>")
	)
	(segment
		(start 443.450726 -201.998834)
		(end 443.455552 -201.998834)
		(width 0.101854)
		(layer "F.Cu")
		(net "M_G_CPU0_SB_DQ<27>")
	)
	(segment
		(start 446.367916 -201.799952)
		(end 446.367916 -201.549)
		(width 0.20066)
		(layer "F.Cu")
		(net "M_G_CPU0_SB_DQ<27>")
	)
	(segment
		(start 446.367916 -201.549)
		(end 446.602104 -201.314812)
		(width 0.20066)
		(layer "F.Cu")
		(net "M_G_CPU0_SB_DQ<27>")
	)
	(segment
		(start 443.462664 -201.991722)
		(end 445.470534 -201.991722)
		(width 0.1016)
		(layer "F.Cu")
		(net "M_G_CPU0_SB_DQ<27>")
	)
	(segment
		(start 445.470534 -201.991722)
		(end 445.482726 -202.003914)
		(width 0.1016)
		(layer "F.Cu")
		(net "M_G_CPU0_SB_DQ<27>")
	)
	(segment
		(start 386.83438 -220.041978)
		(end 386.83438 -219.506038)
		(width 0.20066)
		(layer "F.Cu")
		(net "M_G_CPU0_SB_DQ<27>")
	)
	(segment
		(start 446.602104 -201.314812)
		(end 446.986152 -201.314812)
		(width 0.20066)
		(layer "F.Cu")
		(net "M_G_CPU0_SB_DQ<27>")
	)
	(segment
		(start 418.20973 -200.982326)
		(end 418.04971 -201.142346)
		(width 0.18288)
		(layer "In6.Cu")
		(net "M_G_CPU0_SB_DQ<27>")
	)
	(segment
		(start 389.875014 -218.7194)
		(end 389.653526 -218.940888)
		(width 0.088646)
		(layer "In6.Cu")
		(net "M_G_CPU0_SB_DQ<27>")
	)
	(segment
		(start 410.510482 -201.299826)
		(end 409.68041 -201.299826)
		(width 0.18288)
		(layer "In6.Cu")
		(net "M_G_CPU0_SB_DQ<27>")
	)
	(segment
		(start 410.830522 -200.53808)
		(end 410.670502 -200.6981)
		(width 0.18288)
		(layer "In6.Cu")
		(net "M_G_CPU0_SB_DQ<27>")
	)
	(segment
		(start 410.670502 -200.6981)
		(end 410.670502 -201.139806)
		(width 0.18288)
		(layer "In6.Cu")
		(net "M_G_CPU0_SB_DQ<27>")
	)
	(segment
		(start 411.523942 -201.299826)
		(end 411.363922 -201.139806)
		(width 0.18288)
		(layer "In6.Cu")
		(net "M_G_CPU0_SB_DQ<27>")
	)
	(segment
		(start 422.451022 -201.142346)
		(end 422.291002 -200.982326)
		(width 0.18288)
		(layer "In6.Cu")
		(net "M_G_CPU0_SB_DQ<27>")
	)
	(segment
		(start 418.90315 -200.982326)
		(end 418.90315 -200.380092)
		(width 0.18288)
		(layer "In6.Cu")
		(net "M_G_CPU0_SB_DQ<27>")
	)
	(segment
		(start 418.90315 -200.380092)
		(end 418.74313 -200.220072)
		(width 0.18288)
		(layer "In6.Cu")
		(net "M_G_CPU0_SB_DQ<27>")
	)
	(segment
		(start 411.363922 -200.6981)
		(end 411.203902 -200.53808)
		(width 0.18288)
		(layer "In6.Cu")
		(net "M_G_CPU0_SB_DQ<27>")
	)
	(segment
		(start 425.792392 -201.992484)
		(end 424.278552 -201.992484)
		(width 0.18288)
		(layer "In6.Cu")
		(net "M_G_CPU0_SB_DQ<27>")
	)
	(segment
		(start 410.670502 -201.139806)
		(end 410.510482 -201.299826)
		(width 0.18288)
		(layer "In6.Cu")
		(net "M_G_CPU0_SB_DQ<27>")
	)
	(segment
		(start 439.497724 -201.140822)
		(end 426.644054 -201.140822)
		(width 0.18288)
		(layer "In6.Cu")
		(net "M_G_CPU0_SB_DQ<27>")
	)
	(segment
		(start 419.06317 -201.142346)
		(end 418.90315 -200.982326)
		(width 0.18288)
		(layer "In6.Cu")
		(net "M_G_CPU0_SB_DQ<27>")
	)
	(segment
		(start 426.644054 -201.140822)
		(end 425.792392 -201.992484)
		(width 0.18288)
		(layer "In6.Cu")
		(net "M_G_CPU0_SB_DQ<27>")
	)
	(segment
		(start 406.072086 -200.308718)
		(end 398.07134 -208.309464)
		(width 0.18288)
		(layer "In6.Cu")
		(net "M_G_CPU0_SB_DQ<27>")
	)
	(segment
		(start 409.68041 -201.299826)
		(end 408.689302 -200.308718)
		(width 0.18288)
		(layer "In6.Cu")
		(net "M_G_CPU0_SB_DQ<27>")
	)
	(segment
		(start 387.461506 -219.033852)
		(end 386.83438 -219.506038)
		(width 0.088646)
		(layer "In6.Cu")
		(net "M_G_CPU0_SB_DQ<27>")
	)
	(segment
		(start 421.757602 -200.245472)
		(end 421.597582 -200.405492)
		(width 0.18288)
		(layer "In6.Cu")
		(net "M_G_CPU0_SB_DQ<27>")
	)
	(segment
		(start 423.428414 -201.142346)
		(end 422.451022 -201.142346)
		(width 0.18288)
		(layer "In6.Cu")
		(net "M_G_CPU0_SB_DQ<27>")
	)
	(segment
		(start 418.20973 -200.380092)
		(end 418.20973 -200.982326)
		(width 0.18288)
		(layer "In6.Cu")
		(net "M_G_CPU0_SB_DQ<27>")
	)
	(segment
		(start 418.74313 -200.220072)
		(end 418.36975 -200.220072)
		(width 0.18288)
		(layer "In6.Cu")
		(net "M_G_CPU0_SB_DQ<27>")
	)
	(segment
		(start 411.363922 -201.139806)
		(end 411.363922 -200.6981)
		(width 0.18288)
		(layer "In6.Cu")
		(net "M_G_CPU0_SB_DQ<27>")
	)
	(segment
		(start 439.923682 -201.56678)
		(end 439.497724 -201.140822)
		(width 0.18288)
		(layer "In6.Cu")
		(net "M_G_CPU0_SB_DQ<27>")
	)
	(segment
		(start 412.516574 -201.142346)
		(end 412.359094 -201.299826)
		(width 0.18288)
		(layer "In6.Cu")
		(net "M_G_CPU0_SB_DQ<27>")
	)
	(segment
		(start 412.359094 -201.299826)
		(end 411.523942 -201.299826)
		(width 0.18288)
		(layer "In6.Cu")
		(net "M_G_CPU0_SB_DQ<27>")
	)
	(segment
		(start 421.597582 -200.405492)
		(end 421.597582 -200.982326)
		(width 0.18288)
		(layer "In6.Cu")
		(net "M_G_CPU0_SB_DQ<27>")
	)
	(segment
		(start 421.597582 -200.982326)
		(end 421.437562 -201.142346)
		(width 0.18288)
		(layer "In6.Cu")
		(net "M_G_CPU0_SB_DQ<27>")
	)
	(segment
		(start 418.04971 -201.142346)
		(end 412.516574 -201.142346)
		(width 0.18288)
		(layer "In6.Cu")
		(net "M_G_CPU0_SB_DQ<27>")
	)
	(segment
		(start 388.446264 -219.007944)
		(end 388.431532 -219.01658)
		(width 0.088646)
		(layer "In6.Cu")
		(net "M_G_CPU0_SB_DQ<27>")
	)
	(segment
		(start 421.437562 -201.142346)
		(end 419.06317 -201.142346)
		(width 0.18288)
		(layer "In6.Cu")
		(net "M_G_CPU0_SB_DQ<27>")
	)
	(segment
		(start 422.291002 -200.982326)
		(end 422.291002 -200.405492)
		(width 0.18288)
		(layer "In6.Cu")
		(net "M_G_CPU0_SB_DQ<27>")
	)
	(segment
		(start 408.689302 -200.308718)
		(end 406.072086 -200.308718)
		(width 0.18288)
		(layer "In6.Cu")
		(net "M_G_CPU0_SB_DQ<27>")
	)
	(segment
		(start 422.291002 -200.405492)
		(end 422.130982 -200.245472)
		(width 0.18288)
		(layer "In6.Cu")
		(net "M_G_CPU0_SB_DQ<27>")
	)
	(segment
		(start 418.36975 -200.220072)
		(end 418.20973 -200.380092)
		(width 0.18288)
		(layer "In6.Cu")
		(net "M_G_CPU0_SB_DQ<27>")
	)
	(segment
		(start 398.07134 -209.540094)
		(end 390.370822 -217.240612)
		(width 0.18288)
		(layer "In6.Cu")
		(net "M_G_CPU0_SB_DQ<27>")
	)
	(segment
		(start 390.370822 -217.240612)
		(end 389.875014 -217.73642)
		(width 0.088646)
		(layer "In6.Cu")
		(net "M_G_CPU0_SB_DQ<27>")
	)
	(segment
		(start 387.506464 -219.007944)
		(end 387.461506 -219.033852)
		(width 0.088646)
		(layer "In6.Cu")
		(net "M_G_CPU0_SB_DQ<27>")
	)
	(segment
		(start 389.875014 -217.73642)
		(end 389.875014 -218.7194)
		(width 0.088646)
		(layer "In6.Cu")
		(net "M_G_CPU0_SB_DQ<27>")
	)
	(segment
		(start 398.07134 -208.309464)
		(end 398.07134 -209.540094)
		(width 0.18288)
		(layer "In6.Cu")
		(net "M_G_CPU0_SB_DQ<27>")
	)
	(segment
		(start 411.203902 -200.53808)
		(end 410.830522 -200.53808)
		(width 0.18288)
		(layer "In6.Cu")
		(net "M_G_CPU0_SB_DQ<27>")
	)
	(segment
		(start 424.278552 -201.992484)
		(end 423.428414 -201.142346)
		(width 0.18288)
		(layer "In6.Cu")
		(net "M_G_CPU0_SB_DQ<27>")
	)
	(segment
		(start 422.130982 -200.245472)
		(end 421.757602 -200.245472)
		(width 0.18288)
		(layer "In6.Cu")
		(net "M_G_CPU0_SB_DQ<27>")
	)
	(arc
		(start 389.653526 -218.940888)
		(mid 389.635357 -218.941107)
		(end 389.617204 -218.941904)
		(width 0.088646)
		(layer "In6.Cu")
		(net "M_G_CPU0_SB_DQ<27>")
	)
	(arc
		(start 388.057136 -219.01658)
		(mid 387.782937 -218.940745)
		(end 387.506464 -219.007944)
		(width 0.088646)
		(layer "In6.Cu")
		(net "M_G_CPU0_SB_DQ<27>")
	)
	(arc
		(start 388.431532 -219.01658)
		(mid 388.244334 -219.066723)
		(end 388.057136 -219.01658)
		(width 0.088646)
		(layer "In6.Cu")
		(net "M_G_CPU0_SB_DQ<27>")
	)
	(arc
		(start 389.617204 -218.941904)
		(mid 389.489976 -218.965102)
		(end 389.371332 -219.01658)
		(width 0.088646)
		(layer "In6.Cu")
		(net "M_G_CPU0_SB_DQ<27>")
	)
	(arc
		(start 389.371332 -219.01658)
		(mid 389.184134 -219.066723)
		(end 388.996936 -219.01658)
		(width 0.088646)
		(layer "In6.Cu")
		(net "M_G_CPU0_SB_DQ<27>")
	)
	(arc
		(start 388.996936 -219.01658)
		(mid 388.722737 -218.940745)
		(end 388.446264 -219.007944)
		(width 0.088646)
		(layer "In6.Cu")
		(net "M_G_CPU0_SB_DQ<27>")
	)
	(segment
		(start 443.455552 -203.698856)
		(end 443.462664 -203.691744)
		(width 0.1016)
		(layer "F.Cu")
		(net "M_G_CPU0_SB_DQ<26>")
	)
	(segment
		(start 446.602104 -203.014834)
		(end 446.986152 -203.014834)
		(width 0.20066)
		(layer "F.Cu")
		(net "M_G_CPU0_SB_DQ<26>")
	)
	(segment
		(start 445.470534 -203.691744)
		(end 445.482726 -203.703936)
		(width 0.1016)
		(layer "F.Cu")
		(net "M_G_CPU0_SB_DQ<26>")
	)
	(segment
		(start 439.923682 -203.266802)
		(end 441.028582 -203.266802)
		(width 0.20066)
		(layer "F.Cu")
		(net "M_G_CPU0_SB_DQ<26>")
	)
	(segment
		(start 442.726826 -203.266802)
		(end 443.15888 -203.698856)
		(width 0.20066)
		(layer "F.Cu")
		(net "M_G_CPU0_SB_DQ<26>")
	)
	(segment
		(start 447.23812 -203.266802)
		(end 448.572382 -203.266802)
		(width 0.20066)
		(layer "F.Cu")
		(net "M_G_CPU0_SB_DQ<26>")
	)
	(segment
		(start 443.462664 -203.691744)
		(end 445.470534 -203.691744)
		(width 0.1016)
		(layer "F.Cu")
		(net "M_G_CPU0_SB_DQ<26>")
	)
	(segment
		(start 441.028582 -203.266802)
		(end 442.726826 -203.266802)
		(width 0.20066)
		(layer "F.Cu")
		(net "M_G_CPU0_SB_DQ<26>")
	)
	(segment
		(start 446.367916 -203.499974)
		(end 446.367916 -203.249022)
		(width 0.20066)
		(layer "F.Cu")
		(net "M_G_CPU0_SB_DQ<26>")
	)
	(segment
		(start 445.482726 -203.703936)
		(end 446.163954 -203.703936)
		(width 0.20066)
		(layer "F.Cu")
		(net "M_G_CPU0_SB_DQ<26>")
	)
	(segment
		(start 443.450726 -203.698856)
		(end 443.455552 -203.698856)
		(width 0.101854)
		(layer "F.Cu")
		(net "M_G_CPU0_SB_DQ<26>")
	)
	(segment
		(start 446.163954 -203.703936)
		(end 446.367916 -203.499974)
		(width 0.20066)
		(layer "F.Cu")
		(net "M_G_CPU0_SB_DQ<26>")
	)
	(segment
		(start 385.894834 -219.506292)
		(end 385.89458 -219.506038)
		(width 0.20066)
		(layer "F.Cu")
		(net "M_G_CPU0_SB_DQ<26>")
	)
	(segment
		(start 443.15888 -203.698856)
		(end 443.450726 -203.698856)
		(width 0.20066)
		(layer "F.Cu")
		(net "M_G_CPU0_SB_DQ<26>")
	)
	(segment
		(start 446.986152 -203.014834)
		(end 447.23812 -203.266802)
		(width 0.20066)
		(layer "F.Cu")
		(net "M_G_CPU0_SB_DQ<26>")
	)
	(segment
		(start 385.894834 -220.041978)
		(end 385.894834 -219.506292)
		(width 0.20066)
		(layer "F.Cu")
		(net "M_G_CPU0_SB_DQ<26>")
	)
	(segment
		(start 446.367916 -203.249022)
		(end 446.602104 -203.014834)
		(width 0.20066)
		(layer "F.Cu")
		(net "M_G_CPU0_SB_DQ<26>")
	)
	(segment
		(start 390.291066 -218.762072)
		(end 390.291066 -218.939364)
		(width 0.088646)
		(layer "In6.Cu")
		(net "M_G_CPU0_SB_DQ<26>")
	)
	(segment
		(start 386.177536 -220.644212)
		(end 386.168646 -220.639132)
		(width 0.088646)
		(layer "In6.Cu")
		(net "M_G_CPU0_SB_DQ<26>")
	)
	(segment
		(start 414.536382 -203.289408)
		(end 414.163002 -203.289408)
		(width 0.18288)
		(layer "In6.Cu")
		(net "M_G_CPU0_SB_DQ<26>")
	)
	(segment
		(start 410.707078 -202.553824)
		(end 410.707078 -202.90282)
		(width 0.18288)
		(layer "In6.Cu")
		(net "M_G_CPU0_SB_DQ<26>")
	)
	(segment
		(start 407.543 -202.576176)
		(end 407.36012 -202.759056)
		(width 0.18288)
		(layer "In6.Cu")
		(net "M_G_CPU0_SB_DQ<26>")
	)
	(segment
		(start 385.990084 -220.286326)
		(end 385.89458 -219.506038)
		(width 0.088646)
		(layer "In6.Cu")
		(net "M_G_CPU0_SB_DQ<26>")
	)
	(segment
		(start 414.002982 -202.869546)
		(end 413.842962 -202.709526)
		(width 0.18288)
		(layer "In6.Cu")
		(net "M_G_CPU0_SB_DQ<26>")
	)
	(segment
		(start 389.531352 -219.699078)
		(end 389.395462 -219.699078)
		(width 0.088646)
		(layer "In6.Cu")
		(net "M_G_CPU0_SB_DQ<26>")
	)
	(segment
		(start 423.325036 -202.842368)
		(end 419.935152 -202.842368)
		(width 0.18288)
		(layer "In6.Cu")
		(net "M_G_CPU0_SB_DQ<26>")
	)
	(segment
		(start 424.175174 -203.692506)
		(end 423.325036 -202.842368)
		(width 0.18288)
		(layer "In6.Cu")
		(net "M_G_CPU0_SB_DQ<26>")
	)
	(segment
		(start 426.69841 -202.84059)
		(end 425.846494 -203.692506)
		(width 0.18288)
		(layer "In6.Cu")
		(net "M_G_CPU0_SB_DQ<26>")
	)
	(segment
		(start 414.856422 -202.709526)
		(end 414.696402 -202.869546)
		(width 0.18288)
		(layer "In6.Cu")
		(net "M_G_CPU0_SB_DQ<26>")
	)
	(segment
		(start 411.583378 -203.0857)
		(end 411.400498 -202.90282)
		(width 0.18288)
		(layer "In6.Cu")
		(net "M_G_CPU0_SB_DQ<26>")
	)
	(segment
		(start 410.524198 -203.0857)
		(end 409.674568 -203.0857)
		(width 0.18288)
		(layer "In6.Cu")
		(net "M_G_CPU0_SB_DQ<26>")
	)
	(segment
		(start 411.400498 -202.553824)
		(end 411.217618 -202.370944)
		(width 0.18288)
		(layer "In6.Cu")
		(net "M_G_CPU0_SB_DQ<26>")
	)
	(segment
		(start 410.707078 -202.90282)
		(end 410.524198 -203.0857)
		(width 0.18288)
		(layer "In6.Cu")
		(net "M_G_CPU0_SB_DQ<26>")
	)
	(segment
		(start 385.990084 -220.319854)
		(end 385.990084 -220.286326)
		(width 0.088646)
		(layer "In6.Cu")
		(net "M_G_CPU0_SB_DQ<26>")
	)
	(segment
		(start 437.24703 -202.84059)
		(end 426.69841 -202.84059)
		(width 0.18288)
		(layer "In6.Cu")
		(net "M_G_CPU0_SB_DQ<26>")
	)
	(segment
		(start 416.511994 -202.709526)
		(end 414.856422 -202.709526)
		(width 0.18288)
		(layer "In6.Cu")
		(net "M_G_CPU0_SB_DQ<26>")
	)
	(segment
		(start 409.165044 -202.576176)
		(end 407.543 -202.576176)
		(width 0.18288)
		(layer "In6.Cu")
		(net "M_G_CPU0_SB_DQ<26>")
	)
	(segment
		(start 439.923682 -203.004674)
		(end 439.682636 -202.763628)
		(width 0.18288)
		(layer "In6.Cu")
		(net "M_G_CPU0_SB_DQ<26>")
	)
	(segment
		(start 399.11147 -209.190844)
		(end 399.11147 -209.941668)
		(width 0.18288)
		(layer "In6.Cu")
		(net "M_G_CPU0_SB_DQ<26>")
	)
	(segment
		(start 406.6667 -202.759056)
		(end 406.48382 -202.576176)
		(width 0.18288)
		(layer "In6.Cu")
		(net "M_G_CPU0_SB_DQ<26>")
	)
	(segment
		(start 406.48382 -202.576176)
		(end 405.726138 -202.576176)
		(width 0.18288)
		(layer "In6.Cu")
		(net "M_G_CPU0_SB_DQ<26>")
	)
	(segment
		(start 390.291066 -218.939364)
		(end 389.531352 -219.699078)
		(width 0.088646)
		(layer "In6.Cu")
		(net "M_G_CPU0_SB_DQ<26>")
	)
	(segment
		(start 412.37662 -203.0857)
		(end 411.583378 -203.0857)
		(width 0.18288)
		(layer "In6.Cu")
		(net "M_G_CPU0_SB_DQ<26>")
	)
	(segment
		(start 439.682636 -202.763628)
		(end 437.323992 -202.763628)
		(width 0.18288)
		(layer "In6.Cu")
		(net "M_G_CPU0_SB_DQ<26>")
	)
	(segment
		(start 439.923682 -203.266802)
		(end 439.923682 -203.004674)
		(width 0.18288)
		(layer "In6.Cu")
		(net "M_G_CPU0_SB_DQ<26>")
	)
	(segment
		(start 414.002982 -203.129388)
		(end 414.002982 -202.869546)
		(width 0.18288)
		(layer "In6.Cu")
		(net "M_G_CPU0_SB_DQ<26>")
	)
	(segment
		(start 411.217618 -202.370944)
		(end 410.889958 -202.370944)
		(width 0.18288)
		(layer "In6.Cu")
		(net "M_G_CPU0_SB_DQ<26>")
	)
	(segment
		(start 419.935152 -202.842368)
		(end 419.725094 -203.052426)
		(width 0.18288)
		(layer "In6.Cu")
		(net "M_G_CPU0_SB_DQ<26>")
	)
	(segment
		(start 389.395462 -219.699078)
		(end 388.50951 -220.58503)
		(width 0.088646)
		(layer "In6.Cu")
		(net "M_G_CPU0_SB_DQ<26>")
	)
	(segment
		(start 437.323992 -202.763628)
		(end 437.24703 -202.84059)
		(width 0.18288)
		(layer "In6.Cu")
		(net "M_G_CPU0_SB_DQ<26>")
	)
	(segment
		(start 411.400498 -202.90282)
		(end 411.400498 -202.553824)
		(width 0.18288)
		(layer "In6.Cu")
		(net "M_G_CPU0_SB_DQ<26>")
	)
	(segment
		(start 412.752794 -202.709526)
		(end 412.37662 -203.0857)
		(width 0.18288)
		(layer "In6.Cu")
		(net "M_G_CPU0_SB_DQ<26>")
	)
	(segment
		(start 405.726138 -202.576176)
		(end 399.11147 -209.190844)
		(width 0.18288)
		(layer "In6.Cu")
		(net "M_G_CPU0_SB_DQ<26>")
	)
	(segment
		(start 413.842962 -202.709526)
		(end 412.752794 -202.709526)
		(width 0.18288)
		(layer "In6.Cu")
		(net "M_G_CPU0_SB_DQ<26>")
	)
	(segment
		(start 414.696402 -202.869546)
		(end 414.696402 -203.129388)
		(width 0.18288)
		(layer "In6.Cu")
		(net "M_G_CPU0_SB_DQ<26>")
	)
	(segment
		(start 406.6667 -203.048362)
		(end 406.6667 -202.759056)
		(width 0.18288)
		(layer "In6.Cu")
		(net "M_G_CPU0_SB_DQ<26>")
	)
	(segment
		(start 390.461754 -218.591384)
		(end 390.291066 -218.762072)
		(width 0.088646)
		(layer "In6.Cu")
		(net "M_G_CPU0_SB_DQ<26>")
	)
	(segment
		(start 414.163002 -203.289408)
		(end 414.002982 -203.129388)
		(width 0.18288)
		(layer "In6.Cu")
		(net "M_G_CPU0_SB_DQ<26>")
	)
	(segment
		(start 407.36012 -202.759056)
		(end 407.36012 -203.048362)
		(width 0.18288)
		(layer "In6.Cu")
		(net "M_G_CPU0_SB_DQ<26>")
	)
	(segment
		(start 407.36012 -203.048362)
		(end 407.17724 -203.231242)
		(width 0.18288)
		(layer "In6.Cu")
		(net "M_G_CPU0_SB_DQ<26>")
	)
	(segment
		(start 414.696402 -203.129388)
		(end 414.536382 -203.289408)
		(width 0.18288)
		(layer "In6.Cu")
		(net "M_G_CPU0_SB_DQ<26>")
	)
	(segment
		(start 425.846494 -203.692506)
		(end 424.175174 -203.692506)
		(width 0.18288)
		(layer "In6.Cu")
		(net "M_G_CPU0_SB_DQ<26>")
	)
	(segment
		(start 416.854894 -203.052426)
		(end 416.511994 -202.709526)
		(width 0.18288)
		(layer "In6.Cu")
		(net "M_G_CPU0_SB_DQ<26>")
	)
	(segment
		(start 419.725094 -203.052426)
		(end 416.854894 -203.052426)
		(width 0.18288)
		(layer "In6.Cu")
		(net "M_G_CPU0_SB_DQ<26>")
	)
	(segment
		(start 407.17724 -203.231242)
		(end 406.84958 -203.231242)
		(width 0.18288)
		(layer "In6.Cu")
		(net "M_G_CPU0_SB_DQ<26>")
	)
	(segment
		(start 410.889958 -202.370944)
		(end 410.707078 -202.553824)
		(width 0.18288)
		(layer "In6.Cu")
		(net "M_G_CPU0_SB_DQ<26>")
	)
	(segment
		(start 406.84958 -203.231242)
		(end 406.6667 -203.048362)
		(width 0.18288)
		(layer "In6.Cu")
		(net "M_G_CPU0_SB_DQ<26>")
	)
	(segment
		(start 399.11147 -209.941668)
		(end 390.461754 -218.591384)
		(width 0.18288)
		(layer "In6.Cu")
		(net "M_G_CPU0_SB_DQ<26>")
	)
	(segment
		(start 409.674568 -203.0857)
		(end 409.165044 -202.576176)
		(width 0.18288)
		(layer "In6.Cu")
		(net "M_G_CPU0_SB_DQ<26>")
	)
	(arc
		(start 386.551932 -220.644212)
		(mid 386.364734 -220.694355)
		(end 386.177536 -220.644212)
		(width 0.088646)
		(layer "In6.Cu")
		(net "M_G_CPU0_SB_DQ<26>")
	)
	(arc
		(start 387.491732 -220.644212)
		(mid 387.304534 -220.694355)
		(end 387.117336 -220.644212)
		(width 0.088646)
		(layer "In6.Cu")
		(net "M_G_CPU0_SB_DQ<26>")
	)
	(arc
		(start 388.431532 -220.644212)
		(mid 388.244334 -220.694355)
		(end 388.057136 -220.644212)
		(width 0.088646)
		(layer "In6.Cu")
		(net "M_G_CPU0_SB_DQ<26>")
	)
	(arc
		(start 386.168646 -220.639132)
		(mid 386.037732 -220.502772)
		(end 385.990084 -220.319854)
		(width 0.088646)
		(layer "In6.Cu")
		(net "M_G_CPU0_SB_DQ<26>")
	)
	(arc
		(start 387.117336 -220.644212)
		(mid 386.834634 -220.56847)
		(end 386.551932 -220.644212)
		(width 0.088646)
		(layer "In6.Cu")
		(net "M_G_CPU0_SB_DQ<26>")
	)
	(arc
		(start 388.057136 -220.644212)
		(mid 387.774434 -220.56847)
		(end 387.491732 -220.644212)
		(width 0.088646)
		(layer "In6.Cu")
		(net "M_G_CPU0_SB_DQ<26>")
	)
	(arc
		(start 388.50951 -220.58503)
		(mid 388.47246 -220.617176)
		(end 388.431532 -220.644212)
		(width 0.088646)
		(layer "In6.Cu")
		(net "M_G_CPU0_SB_DQ<26>")
	)
	(segment
		(start 444.472314 -202.416664)
		(end 444.47206 -202.416918)
		(width 0.20066)
		(layer "F.Cu")
		(net "M_G_CPU0_SB_DQ<25>")
	)
	(segment
		(start 442.038994 -201.985372)
		(end 442.032644 -201.991722)
		(width 0.1016)
		(layer "F.Cu")
		(net "M_G_CPU0_SB_DQ<25>")
	)
	(segment
		(start 444.47206 -202.416918)
		(end 442.880496 -202.416918)
		(width 0.20066)
		(layer "F.Cu")
		(net "M_G_CPU0_SB_DQ<25>")
	)
	(segment
		(start 438.449212 -202.416664)
		(end 436.928514 -202.416664)
		(width 0.20066)
		(layer "F.Cu")
		(net "M_G_CPU0_SB_DQ<25>")
	)
	(segment
		(start 383.075434 -220.041724)
		(end 383.075434 -219.506038)
		(width 0.20066)
		(layer "F.Cu")
		(net "M_G_CPU0_SB_DQ<25>")
	)
	(segment
		(start 383.07518 -220.041978)
		(end 383.075434 -220.041724)
		(width 0.20066)
		(layer "F.Cu")
		(net "M_G_CPU0_SB_DQ<25>")
	)
	(segment
		(start 442.44895 -201.985372)
		(end 442.038994 -201.985372)
		(width 0.20066)
		(layer "F.Cu")
		(net "M_G_CPU0_SB_DQ<25>")
	)
	(segment
		(start 439.173112 -202.66533)
		(end 438.697878 -202.66533)
		(width 0.20066)
		(layer "F.Cu")
		(net "M_G_CPU0_SB_DQ<25>")
	)
	(segment
		(start 439.843926 -201.991722)
		(end 439.82386 -201.991722)
		(width 0.101854)
		(layer "F.Cu")
		(net "M_G_CPU0_SB_DQ<25>")
	)
	(segment
		(start 439.479182 -201.991722)
		(end 439.361072 -202.109832)
		(width 0.20066)
		(layer "F.Cu")
		(net "M_G_CPU0_SB_DQ<25>")
	)
	(segment
		(start 439.82386 -201.991722)
		(end 439.479182 -201.991722)
		(width 0.20066)
		(layer "F.Cu")
		(net "M_G_CPU0_SB_DQ<25>")
	)
	(segment
		(start 442.880496 -202.416918)
		(end 442.44895 -201.985372)
		(width 0.20066)
		(layer "F.Cu")
		(net "M_G_CPU0_SB_DQ<25>")
	)
	(segment
		(start 438.697878 -202.66533)
		(end 438.449212 -202.416664)
		(width 0.20066)
		(layer "F.Cu")
		(net "M_G_CPU0_SB_DQ<25>")
	)
	(segment
		(start 439.361072 -202.109832)
		(end 439.361072 -202.47737)
		(width 0.20066)
		(layer "F.Cu")
		(net "M_G_CPU0_SB_DQ<25>")
	)
	(segment
		(start 442.032644 -201.991722)
		(end 439.843926 -201.991722)
		(width 0.1016)
		(layer "F.Cu")
		(net "M_G_CPU0_SB_DQ<25>")
	)
	(segment
		(start 436.928514 -202.416664)
		(end 435.823614 -202.416664)
		(width 0.20066)
		(layer "F.Cu")
		(net "M_G_CPU0_SB_DQ<25>")
	)
	(segment
		(start 439.361072 -202.47737)
		(end 439.173112 -202.66533)
		(width 0.20066)
		(layer "F.Cu")
		(net "M_G_CPU0_SB_DQ<25>")
	)
	(segment
		(start 407.21915 -201.876406)
		(end 407.21915 -200.97369)
		(width 0.18288)
		(layer "In6.Cu")
		(net "M_G_CPU0_SB_DQ<25>")
	)
	(segment
		(start 398.606264 -208.778856)
		(end 398.606264 -209.732626)
		(width 0.18288)
		(layer "In6.Cu")
		(net "M_G_CPU0_SB_DQ<25>")
	)
	(segment
		(start 389.751316 -219.131896)
		(end 389.653018 -219.131388)
		(width 0.088646)
		(layer "In6.Cu")
		(net "M_G_CPU0_SB_DQ<25>")
	)
	(segment
		(start 435.823614 -202.416664)
		(end 435.40172 -201.99477)
		(width 0.18288)
		(layer "In6.Cu")
		(net "M_G_CPU0_SB_DQ<25>")
	)
	(segment
		(start 418.841936 -201.858626)
		(end 418.659056 -202.041506)
		(width 0.18288)
		(layer "In6.Cu")
		(net "M_G_CPU0_SB_DQ<25>")
	)
	(segment
		(start 421.748458 -202.302872)
		(end 421.437816 -201.99223)
		(width 0.18288)
		(layer "In6.Cu")
		(net "M_G_CPU0_SB_DQ<25>")
	)
	(segment
		(start 414.05683 -202.028806)
		(end 413.89681 -202.188826)
		(width 0.18288)
		(layer "In6.Cu")
		(net "M_G_CPU0_SB_DQ<25>")
	)
	(segment
		(start 389.466582 -219.18168)
		(end 389.45185 -219.190316)
		(width 0.088646)
		(layer "In6.Cu")
		(net "M_G_CPU0_SB_DQ<25>")
	)
	(segment
		(start 418.148516 -202.54214)
		(end 417.965636 -202.35926)
		(width 0.18288)
		(layer "In6.Cu")
		(net "M_G_CPU0_SB_DQ<25>")
	)
	(segment
		(start 426.63999 -201.99477)
		(end 425.792392 -202.842368)
		(width 0.18288)
		(layer "In6.Cu")
		(net "M_G_CPU0_SB_DQ<25>")
	)
	(segment
		(start 383.828036 -219.18168)
		(end 383.800096 -219.197936)
		(width 0.088646)
		(layer "In6.Cu")
		(net "M_G_CPU0_SB_DQ<25>")
	)
	(segment
		(start 418.659056 -202.35926)
		(end 418.476176 -202.54214)
		(width 0.18288)
		(layer "In6.Cu")
		(net "M_G_CPU0_SB_DQ<25>")
	)
	(segment
		(start 418.476176 -202.54214)
		(end 418.148516 -202.54214)
		(width 0.18288)
		(layer "In6.Cu")
		(net "M_G_CPU0_SB_DQ<25>")
	)
	(segment
		(start 421.437816 -201.99223)
		(end 419.985698 -201.99223)
		(width 0.18288)
		(layer "In6.Cu")
		(net "M_G_CPU0_SB_DQ<25>")
	)
	(segment
		(start 412.384494 -201.833226)
		(end 409.463494 -201.833226)
		(width 0.18288)
		(layer "In6.Cu")
		(net "M_G_CPU0_SB_DQ<25>")
	)
	(segment
		(start 386.552694 -219.995496)
		(end 386.551932 -219.995242)
		(width 0.088646)
		(layer "In6.Cu")
		(net "M_G_CPU0_SB_DQ<25>")
	)
	(segment
		(start 409.463494 -201.833226)
		(end 409.260294 -202.036426)
		(width 0.18288)
		(layer "In6.Cu")
		(net "M_G_CPU0_SB_DQ<25>")
	)
	(segment
		(start 384.767582 -219.18168)
		(end 384.757168 -219.187776)
		(width 0.088646)
		(layer "In6.Cu")
		(net "M_G_CPU0_SB_DQ<25>")
	)
	(segment
		(start 406.68575 -200.81367)
		(end 406.52573 -200.97369)
		(width 0.18288)
		(layer "In6.Cu")
		(net "M_G_CPU0_SB_DQ<25>")
	)
	(segment
		(start 385.707382 -219.18168)
		(end 385.69265 -219.190316)
		(width 0.088646)
		(layer "In6.Cu")
		(net "M_G_CPU0_SB_DQ<25>")
	)
	(segment
		(start 417.965636 -202.35926)
		(end 417.965636 -202.041506)
		(width 0.18288)
		(layer "In6.Cu")
		(net "M_G_CPU0_SB_DQ<25>")
	)
	(segment
		(start 406.52573 -201.876406)
		(end 406.36571 -202.036426)
		(width 0.18288)
		(layer "In6.Cu")
		(net "M_G_CPU0_SB_DQ<25>")
	)
	(segment
		(start 407.37917 -202.036426)
		(end 407.21915 -201.876406)
		(width 0.18288)
		(layer "In6.Cu")
		(net "M_G_CPU0_SB_DQ<25>")
	)
	(segment
		(start 422.131236 -202.302872)
		(end 421.748458 -202.302872)
		(width 0.18288)
		(layer "In6.Cu")
		(net "M_G_CPU0_SB_DQ<25>")
	)
	(segment
		(start 406.36571 -202.036426)
		(end 405.348694 -202.036426)
		(width 0.18288)
		(layer "In6.Cu")
		(net "M_G_CPU0_SB_DQ<25>")
	)
	(segment
		(start 387.39953 -219.506292)
		(end 387.39953 -219.506546)
		(width 0.088646)
		(layer "In6.Cu")
		(net "M_G_CPU0_SB_DQ<25>")
	)
	(segment
		(start 412.740094 -202.188826)
		(end 412.384494 -201.833226)
		(width 0.18288)
		(layer "In6.Cu")
		(net "M_G_CPU0_SB_DQ<25>")
	)
	(segment
		(start 417.965636 -202.041506)
		(end 417.782756 -201.858626)
		(width 0.18288)
		(layer "In6.Cu")
		(net "M_G_CPU0_SB_DQ<25>")
	)
	(segment
		(start 388.526782 -219.18168)
		(end 388.51205 -219.190316)
		(width 0.088646)
		(layer "In6.Cu")
		(net "M_G_CPU0_SB_DQ<25>")
	)
	(segment
		(start 405.348694 -202.036426)
		(end 398.606264 -208.778856)
		(width 0.18288)
		(layer "In6.Cu")
		(net "M_G_CPU0_SB_DQ<25>")
	)
	(segment
		(start 414.91027 -202.188826)
		(end 414.75025 -202.028806)
		(width 0.18288)
		(layer "In6.Cu")
		(net "M_G_CPU0_SB_DQ<25>")
	)
	(segment
		(start 390.35863 -217.98026)
		(end 390.072118 -218.266772)
		(width 0.088646)
		(layer "In6.Cu")
		(net "M_G_CPU0_SB_DQ<25>")
	)
	(segment
		(start 407.05913 -200.81367)
		(end 406.68575 -200.81367)
		(width 0.18288)
		(layer "In6.Cu")
		(net "M_G_CPU0_SB_DQ<25>")
	)
	(segment
		(start 386.082032 -219.181934)
		(end 386.081778 -219.18168)
		(width 0.088646)
		(layer "In6.Cu")
		(net "M_G_CPU0_SB_DQ<25>")
	)
	(segment
		(start 390.072118 -218.811094)
		(end 389.751316 -219.131896)
		(width 0.088646)
		(layer "In6.Cu")
		(net "M_G_CPU0_SB_DQ<25>")
	)
	(segment
		(start 435.40172 -201.99477)
		(end 426.63999 -201.99477)
		(width 0.18288)
		(layer "In6.Cu")
		(net "M_G_CPU0_SB_DQ<25>")
	)
	(segment
		(start 414.75025 -202.028806)
		(end 414.75025 -201.802492)
		(width 0.18288)
		(layer "In6.Cu")
		(net "M_G_CPU0_SB_DQ<25>")
	)
	(segment
		(start 383.800096 -219.197936)
		(end 383.075434 -219.506038)
		(width 0.088646)
		(layer "In6.Cu")
		(net "M_G_CPU0_SB_DQ<25>")
	)
	(segment
		(start 419.985698 -201.99223)
		(end 419.852094 -201.858626)
		(width 0.18288)
		(layer "In6.Cu")
		(net "M_G_CPU0_SB_DQ<25>")
	)
	(segment
		(start 414.75025 -201.802492)
		(end 414.59023 -201.642472)
		(width 0.18288)
		(layer "In6.Cu")
		(net "M_G_CPU0_SB_DQ<25>")
	)
	(segment
		(start 424.188636 -202.842368)
		(end 423.338498 -201.99223)
		(width 0.18288)
		(layer "In6.Cu")
		(net "M_G_CPU0_SB_DQ<25>")
	)
	(segment
		(start 416.880294 -201.858626)
		(end 416.550094 -202.188826)
		(width 0.18288)
		(layer "In6.Cu")
		(net "M_G_CPU0_SB_DQ<25>")
	)
	(segment
		(start 413.89681 -202.188826)
		(end 412.740094 -202.188826)
		(width 0.18288)
		(layer "In6.Cu")
		(net "M_G_CPU0_SB_DQ<25>")
	)
	(segment
		(start 423.338498 -201.99223)
		(end 422.441878 -201.99223)
		(width 0.18288)
		(layer "In6.Cu")
		(net "M_G_CPU0_SB_DQ<25>")
	)
	(segment
		(start 398.606264 -209.732626)
		(end 390.35863 -217.98026)
		(width 0.18288)
		(layer "In6.Cu")
		(net "M_G_CPU0_SB_DQ<25>")
	)
	(segment
		(start 390.072118 -218.266772)
		(end 390.072118 -218.811094)
		(width 0.088646)
		(layer "In6.Cu")
		(net "M_G_CPU0_SB_DQ<25>")
	)
	(segment
		(start 425.792392 -202.842368)
		(end 424.188636 -202.842368)
		(width 0.18288)
		(layer "In6.Cu")
		(net "M_G_CPU0_SB_DQ<25>")
	)
	(segment
		(start 414.59023 -201.642472)
		(end 414.21685 -201.642472)
		(width 0.18288)
		(layer "In6.Cu")
		(net "M_G_CPU0_SB_DQ<25>")
	)
	(segment
		(start 409.260294 -202.036426)
		(end 407.37917 -202.036426)
		(width 0.18288)
		(layer "In6.Cu")
		(net "M_G_CPU0_SB_DQ<25>")
	)
	(segment
		(start 422.441878 -201.99223)
		(end 422.131236 -202.302872)
		(width 0.18288)
		(layer "In6.Cu")
		(net "M_G_CPU0_SB_DQ<25>")
	)
	(segment
		(start 418.659056 -202.041506)
		(end 418.659056 -202.35926)
		(width 0.18288)
		(layer "In6.Cu")
		(net "M_G_CPU0_SB_DQ<25>")
	)
	(segment
		(start 407.21915 -200.97369)
		(end 407.05913 -200.81367)
		(width 0.18288)
		(layer "In6.Cu")
		(net "M_G_CPU0_SB_DQ<25>")
	)
	(segment
		(start 414.05683 -201.802492)
		(end 414.05683 -202.028806)
		(width 0.18288)
		(layer "In6.Cu")
		(net "M_G_CPU0_SB_DQ<25>")
	)
	(segment
		(start 406.52573 -200.97369)
		(end 406.52573 -201.876406)
		(width 0.18288)
		(layer "In6.Cu")
		(net "M_G_CPU0_SB_DQ<25>")
	)
	(segment
		(start 416.550094 -202.188826)
		(end 414.91027 -202.188826)
		(width 0.18288)
		(layer "In6.Cu")
		(net "M_G_CPU0_SB_DQ<25>")
	)
	(segment
		(start 419.852094 -201.858626)
		(end 418.841936 -201.858626)
		(width 0.18288)
		(layer "In6.Cu")
		(net "M_G_CPU0_SB_DQ<25>")
	)
	(segment
		(start 417.782756 -201.858626)
		(end 416.880294 -201.858626)
		(width 0.18288)
		(layer "In6.Cu")
		(net "M_G_CPU0_SB_DQ<25>")
	)
	(segment
		(start 414.21685 -201.642472)
		(end 414.05683 -201.802492)
		(width 0.18288)
		(layer "In6.Cu")
		(net "M_G_CPU0_SB_DQ<25>")
	)
	(arc
		(start 386.551932 -219.995242)
		(mid 386.344988 -219.788532)
		(end 386.26923 -219.506038)
		(width 0.088646)
		(layer "In6.Cu")
		(net "M_G_CPU0_SB_DQ<25>")
	)
	(arc
		(start 387.39953 -219.506546)
		(mid 387.117247 -219.995518)
		(end 386.552694 -219.995496)
		(width 0.088646)
		(layer "In6.Cu")
		(net "M_G_CPU0_SB_DQ<25>")
	)
	(arc
		(start 389.45185 -219.190316)
		(mid 389.175375 -219.257636)
		(end 388.901178 -219.18168)
		(width 0.088646)
		(layer "In6.Cu")
		(net "M_G_CPU0_SB_DQ<25>")
	)
	(arc
		(start 386.081778 -219.18168)
		(mid 385.89458 -219.131537)
		(end 385.707382 -219.18168)
		(width 0.088646)
		(layer "In6.Cu")
		(net "M_G_CPU0_SB_DQ<25>")
	)
	(arc
		(start 387.586982 -219.18168)
		(mid 387.449798 -219.318882)
		(end 387.39953 -219.506292)
		(width 0.088646)
		(layer "In6.Cu")
		(net "M_G_CPU0_SB_DQ<25>")
	)
	(arc
		(start 389.653018 -219.131388)
		(mid 389.5565 -219.144305)
		(end 389.466582 -219.18168)
		(width 0.088646)
		(layer "In6.Cu")
		(net "M_G_CPU0_SB_DQ<25>")
	)
	(arc
		(start 388.901178 -219.18168)
		(mid 388.71398 -219.131537)
		(end 388.526782 -219.18168)
		(width 0.088646)
		(layer "In6.Cu")
		(net "M_G_CPU0_SB_DQ<25>")
	)
	(arc
		(start 388.51205 -219.190316)
		(mid 388.235575 -219.257636)
		(end 387.961378 -219.18168)
		(width 0.088646)
		(layer "In6.Cu")
		(net "M_G_CPU0_SB_DQ<25>")
	)
	(arc
		(start 386.26923 -219.506038)
		(mid 386.219066 -219.3189)
		(end 386.082032 -219.181934)
		(width 0.088646)
		(layer "In6.Cu")
		(net "M_G_CPU0_SB_DQ<25>")
	)
	(arc
		(start 387.961378 -219.18168)
		(mid 387.77418 -219.131537)
		(end 387.586982 -219.18168)
		(width 0.088646)
		(layer "In6.Cu")
		(net "M_G_CPU0_SB_DQ<25>")
	)
	(arc
		(start 384.202432 -219.18168)
		(mid 384.015234 -219.131503)
		(end 383.828036 -219.18168)
		(width 0.088646)
		(layer "In6.Cu")
		(net "M_G_CPU0_SB_DQ<25>")
	)
	(arc
		(start 384.757168 -219.187776)
		(mid 384.47899 -219.257499)
		(end 384.202432 -219.18168)
		(width 0.088646)
		(layer "In6.Cu")
		(net "M_G_CPU0_SB_DQ<25>")
	)
	(arc
		(start 385.69265 -219.190316)
		(mid 385.416175 -219.257636)
		(end 385.141978 -219.18168)
		(width 0.088646)
		(layer "In6.Cu")
		(net "M_G_CPU0_SB_DQ<25>")
	)
	(arc
		(start 385.141978 -219.18168)
		(mid 384.95478 -219.131537)
		(end 384.767582 -219.18168)
		(width 0.088646)
		(layer "In6.Cu")
		(net "M_G_CPU0_SB_DQ<25>")
	)
	(segment
		(start 439.361072 -204.177392)
		(end 439.173112 -204.365352)
		(width 0.20066)
		(layer "F.Cu")
		(net "M_G_CPU0_SB_DQ<24>")
	)
	(segment
		(start 442.032644 -203.691744)
		(end 439.87085 -203.691744)
		(width 0.1016)
		(layer "F.Cu")
		(net "M_G_CPU0_SB_DQ<24>")
	)
	(segment
		(start 436.928514 -204.116686)
		(end 435.823614 -204.116686)
		(width 0.20066)
		(layer "F.Cu")
		(net "M_G_CPU0_SB_DQ<24>")
	)
	(segment
		(start 444.47206 -204.11694)
		(end 442.880496 -204.11694)
		(width 0.20066)
		(layer "F.Cu")
		(net "M_G_CPU0_SB_DQ<24>")
	)
	(segment
		(start 439.479182 -203.691744)
		(end 439.361072 -203.809854)
		(width 0.20066)
		(layer "F.Cu")
		(net "M_G_CPU0_SB_DQ<24>")
	)
	(segment
		(start 439.173112 -204.365352)
		(end 438.697878 -204.365352)
		(width 0.20066)
		(layer "F.Cu")
		(net "M_G_CPU0_SB_DQ<24>")
	)
	(segment
		(start 384.015234 -220.041978)
		(end 384.015234 -219.506038)
		(width 0.20066)
		(layer "F.Cu")
		(net "M_G_CPU0_SB_DQ<24>")
	)
	(segment
		(start 438.697878 -204.365352)
		(end 438.449212 -204.116686)
		(width 0.20066)
		(layer "F.Cu")
		(net "M_G_CPU0_SB_DQ<24>")
	)
	(segment
		(start 444.472314 -204.116686)
		(end 444.47206 -204.11694)
		(width 0.20066)
		(layer "F.Cu")
		(net "M_G_CPU0_SB_DQ<24>")
	)
	(segment
		(start 439.361072 -203.809854)
		(end 439.361072 -204.177392)
		(width 0.20066)
		(layer "F.Cu")
		(net "M_G_CPU0_SB_DQ<24>")
	)
	(segment
		(start 438.449212 -204.116686)
		(end 436.928514 -204.116686)
		(width 0.20066)
		(layer "F.Cu")
		(net "M_G_CPU0_SB_DQ<24>")
	)
	(segment
		(start 442.038994 -203.685394)
		(end 442.032644 -203.691744)
		(width 0.1016)
		(layer "F.Cu")
		(net "M_G_CPU0_SB_DQ<24>")
	)
	(segment
		(start 439.87085 -203.691744)
		(end 439.82386 -203.691744)
		(width 0.101854)
		(layer "F.Cu")
		(net "M_G_CPU0_SB_DQ<24>")
	)
	(segment
		(start 442.44895 -203.685394)
		(end 442.038994 -203.685394)
		(width 0.20066)
		(layer "F.Cu")
		(net "M_G_CPU0_SB_DQ<24>")
	)
	(segment
		(start 439.82386 -203.691744)
		(end 439.479182 -203.691744)
		(width 0.20066)
		(layer "F.Cu")
		(net "M_G_CPU0_SB_DQ<24>")
	)
	(segment
		(start 442.880496 -204.11694)
		(end 442.44895 -203.685394)
		(width 0.20066)
		(layer "F.Cu")
		(net "M_G_CPU0_SB_DQ<24>")
	)
	(segment
		(start 389.579358 -220.18371)
		(end 389.18007 -220.18371)
		(width 0.088646)
		(layer "In6.Cu")
		(net "M_G_CPU0_SB_DQ<24>")
	)
	(segment
		(start 399.620486 -210.141058)
		(end 390.33831 -219.423234)
		(width 0.18288)
		(layer "In6.Cu")
		(net "M_G_CPU0_SB_DQ<24>")
	)
	(segment
		(start 407.157682 -203.792836)
		(end 406.974802 -203.975716)
		(width 0.18288)
		(layer "In6.Cu")
		(net "M_G_CPU0_SB_DQ<24>")
	)
	(segment
		(start 416.875468 -203.692252)
		(end 416.575494 -203.992226)
		(width 0.18288)
		(layer "In6.Cu")
		(net "M_G_CPU0_SB_DQ<24>")
	)
	(segment
		(start 431.735992 -204.35951)
		(end 431.362612 -204.35951)
		(width 0.18288)
		(layer "In6.Cu")
		(net "M_G_CPU0_SB_DQ<24>")
	)
	(segment
		(start 406.974802 -203.975716)
		(end 406.974802 -204.404722)
		(width 0.18288)
		(layer "In6.Cu")
		(net "M_G_CPU0_SB_DQ<24>")
	)
	(segment
		(start 421.905684 -204.38237)
		(end 421.722804 -204.19949)
		(width 0.18288)
		(layer "In6.Cu")
		(net "M_G_CPU0_SB_DQ<24>")
	)
	(segment
		(start 390.33831 -219.424758)
		(end 389.579358 -220.18371)
		(width 0.088646)
		(layer "In6.Cu")
		(net "M_G_CPU0_SB_DQ<24>")
	)
	(segment
		(start 425.973494 -204.54239)
		(end 424.059858 -204.54239)
		(width 0.18288)
		(layer "In6.Cu")
		(net "M_G_CPU0_SB_DQ<24>")
	)
	(segment
		(start 422.233344 -204.38237)
		(end 421.905684 -204.38237)
		(width 0.18288)
		(layer "In6.Cu")
		(net "M_G_CPU0_SB_DQ<24>")
	)
	(segment
		(start 422.416224 -203.875132)
		(end 422.416224 -204.19949)
		(width 0.18288)
		(layer "In6.Cu")
		(net "M_G_CPU0_SB_DQ<24>")
	)
	(segment
		(start 428.01921 -204.183742)
		(end 427.49216 -203.656692)
		(width 0.18288)
		(layer "In6.Cu")
		(net "M_G_CPU0_SB_DQ<24>")
	)
	(segment
		(start 417.85921 -203.692252)
		(end 416.875468 -203.692252)
		(width 0.18288)
		(layer "In6.Cu")
		(net "M_G_CPU0_SB_DQ<24>")
	)
	(segment
		(start 418.73551 -204.259434)
		(end 418.55263 -204.442314)
		(width 0.18288)
		(layer "In6.Cu")
		(net "M_G_CPU0_SB_DQ<24>")
	)
	(segment
		(start 384.681222 -220.000576)
		(end 384.672332 -219.995496)
		(width 0.088646)
		(layer "In6.Cu")
		(net "M_G_CPU0_SB_DQ<24>")
	)
	(segment
		(start 431.896012 -204.19949)
		(end 431.735992 -204.35951)
		(width 0.18288)
		(layer "In6.Cu")
		(net "M_G_CPU0_SB_DQ<24>")
	)
	(segment
		(start 416.575494 -203.992226)
		(end 413.070294 -203.992226)
		(width 0.18288)
		(layer "In6.Cu")
		(net "M_G_CPU0_SB_DQ<24>")
	)
	(segment
		(start 405.217884 -203.792836)
		(end 399.620486 -209.390234)
		(width 0.18288)
		(layer "In6.Cu")
		(net "M_G_CPU0_SB_DQ<24>")
	)
	(segment
		(start 390.33831 -219.423234)
		(end 390.33831 -219.424758)
		(width 0.088646)
		(layer "In6.Cu")
		(net "M_G_CPU0_SB_DQ<24>")
	)
	(segment
		(start 406.281382 -204.404722)
		(end 406.281382 -203.975716)
		(width 0.18288)
		(layer "In6.Cu")
		(net "M_G_CPU0_SB_DQ<24>")
	)
	(segment
		(start 421.722804 -203.875132)
		(end 421.539924 -203.692252)
		(width 0.18288)
		(layer "In6.Cu")
		(net "M_G_CPU0_SB_DQ<24>")
	)
	(segment
		(start 412.664402 -203.586334)
		(end 411.471872 -203.586334)
		(width 0.18288)
		(layer "In6.Cu")
		(net "M_G_CPU0_SB_DQ<24>")
	)
	(segment
		(start 411.288992 -204.225144)
		(end 411.106112 -204.408024)
		(width 0.18288)
		(layer "In6.Cu")
		(net "M_G_CPU0_SB_DQ<24>")
	)
	(segment
		(start 410.412692 -203.586334)
		(end 409.107386 -203.586334)
		(width 0.18288)
		(layer "In6.Cu")
		(net "M_G_CPU0_SB_DQ<24>")
	)
	(segment
		(start 424.059858 -204.54239)
		(end 423.20972 -203.692252)
		(width 0.18288)
		(layer "In6.Cu")
		(net "M_G_CPU0_SB_DQ<24>")
	)
	(segment
		(start 427.49216 -203.656692)
		(end 426.859192 -203.656692)
		(width 0.18288)
		(layer "In6.Cu")
		(net "M_G_CPU0_SB_DQ<24>")
	)
	(segment
		(start 410.595572 -203.769214)
		(end 410.412692 -203.586334)
		(width 0.18288)
		(layer "In6.Cu")
		(net "M_G_CPU0_SB_DQ<24>")
	)
	(segment
		(start 422.416224 -204.19949)
		(end 422.233344 -204.38237)
		(width 0.18288)
		(layer "In6.Cu")
		(net "M_G_CPU0_SB_DQ<24>")
	)
	(segment
		(start 411.288992 -203.769214)
		(end 411.288992 -204.225144)
		(width 0.18288)
		(layer "In6.Cu")
		(net "M_G_CPU0_SB_DQ<24>")
	)
	(segment
		(start 411.106112 -204.408024)
		(end 410.778452 -204.408024)
		(width 0.18288)
		(layer "In6.Cu")
		(net "M_G_CPU0_SB_DQ<24>")
	)
	(segment
		(start 418.91839 -203.692252)
		(end 418.73551 -203.875132)
		(width 0.18288)
		(layer "In6.Cu")
		(net "M_G_CPU0_SB_DQ<24>")
	)
	(segment
		(start 430.194974 -204.183742)
		(end 428.01921 -204.183742)
		(width 0.18288)
		(layer "In6.Cu")
		(net "M_G_CPU0_SB_DQ<24>")
	)
	(segment
		(start 384.64363 -219.97924)
		(end 384.015234 -219.506038)
		(width 0.088646)
		(layer "In6.Cu")
		(net "M_G_CPU0_SB_DQ<24>")
	)
	(segment
		(start 410.595572 -204.225144)
		(end 410.595572 -203.769214)
		(width 0.18288)
		(layer "In6.Cu")
		(net "M_G_CPU0_SB_DQ<24>")
	)
	(segment
		(start 430.8602 -203.518516)
		(end 430.194974 -204.183742)
		(width 0.18288)
		(layer "In6.Cu")
		(net "M_G_CPU0_SB_DQ<24>")
	)
	(segment
		(start 421.722804 -204.19949)
		(end 421.722804 -203.875132)
		(width 0.18288)
		(layer "In6.Cu")
		(net "M_G_CPU0_SB_DQ<24>")
	)
	(segment
		(start 431.042572 -203.518516)
		(end 430.8602 -203.518516)
		(width 0.18288)
		(layer "In6.Cu")
		(net "M_G_CPU0_SB_DQ<24>")
	)
	(segment
		(start 406.464262 -204.587602)
		(end 406.281382 -204.404722)
		(width 0.18288)
		(layer "In6.Cu")
		(net "M_G_CPU0_SB_DQ<24>")
	)
	(segment
		(start 406.974802 -204.404722)
		(end 406.791922 -204.587602)
		(width 0.18288)
		(layer "In6.Cu")
		(net "M_G_CPU0_SB_DQ<24>")
	)
	(segment
		(start 422.599104 -203.692252)
		(end 422.416224 -203.875132)
		(width 0.18288)
		(layer "In6.Cu")
		(net "M_G_CPU0_SB_DQ<24>")
	)
	(segment
		(start 384.672332 -219.995496)
		(end 384.64363 -219.97924)
		(width 0.088646)
		(layer "In6.Cu")
		(net "M_G_CPU0_SB_DQ<24>")
	)
	(segment
		(start 406.791922 -204.587602)
		(end 406.464262 -204.587602)
		(width 0.18288)
		(layer "In6.Cu")
		(net "M_G_CPU0_SB_DQ<24>")
	)
	(segment
		(start 418.55263 -204.442314)
		(end 418.22497 -204.442314)
		(width 0.18288)
		(layer "In6.Cu")
		(net "M_G_CPU0_SB_DQ<24>")
	)
	(segment
		(start 431.202592 -204.19949)
		(end 431.202592 -203.678536)
		(width 0.18288)
		(layer "In6.Cu")
		(net "M_G_CPU0_SB_DQ<24>")
	)
	(segment
		(start 431.362612 -204.35951)
		(end 431.202592 -204.19949)
		(width 0.18288)
		(layer "In6.Cu")
		(net "M_G_CPU0_SB_DQ<24>")
	)
	(segment
		(start 418.22497 -204.442314)
		(end 418.04209 -204.259434)
		(width 0.18288)
		(layer "In6.Cu")
		(net "M_G_CPU0_SB_DQ<24>")
	)
	(segment
		(start 389.18007 -220.18371)
		(end 388.64413 -220.71965)
		(width 0.088646)
		(layer "In6.Cu")
		(net "M_G_CPU0_SB_DQ<24>")
	)
	(segment
		(start 431.202592 -203.678536)
		(end 431.042572 -203.518516)
		(width 0.18288)
		(layer "In6.Cu")
		(net "M_G_CPU0_SB_DQ<24>")
	)
	(segment
		(start 426.859192 -203.656692)
		(end 425.973494 -204.54239)
		(width 0.18288)
		(layer "In6.Cu")
		(net "M_G_CPU0_SB_DQ<24>")
	)
	(segment
		(start 410.778452 -204.408024)
		(end 410.595572 -204.225144)
		(width 0.18288)
		(layer "In6.Cu")
		(net "M_G_CPU0_SB_DQ<24>")
	)
	(segment
		(start 406.281382 -203.975716)
		(end 406.098502 -203.792836)
		(width 0.18288)
		(layer "In6.Cu")
		(net "M_G_CPU0_SB_DQ<24>")
	)
	(segment
		(start 413.070294 -203.992226)
		(end 412.664402 -203.586334)
		(width 0.18288)
		(layer "In6.Cu")
		(net "M_G_CPU0_SB_DQ<24>")
	)
	(segment
		(start 435.225444 -203.518516)
		(end 432.056032 -203.518516)
		(width 0.18288)
		(layer "In6.Cu")
		(net "M_G_CPU0_SB_DQ<24>")
	)
	(segment
		(start 406.098502 -203.792836)
		(end 405.217884 -203.792836)
		(width 0.18288)
		(layer "In6.Cu")
		(net "M_G_CPU0_SB_DQ<24>")
	)
	(segment
		(start 435.823614 -204.116686)
		(end 435.225444 -203.518516)
		(width 0.18288)
		(layer "In6.Cu")
		(net "M_G_CPU0_SB_DQ<24>")
	)
	(segment
		(start 431.896012 -203.678536)
		(end 431.896012 -204.19949)
		(width 0.18288)
		(layer "In6.Cu")
		(net "M_G_CPU0_SB_DQ<24>")
	)
	(segment
		(start 421.539924 -203.692252)
		(end 418.91839 -203.692252)
		(width 0.18288)
		(layer "In6.Cu")
		(net "M_G_CPU0_SB_DQ<24>")
	)
	(segment
		(start 384.859784 -220.320362)
		(end 384.859784 -220.319854)
		(width 0.088646)
		(layer "In6.Cu")
		(net "M_G_CPU0_SB_DQ<24>")
	)
	(segment
		(start 418.04209 -204.259434)
		(end 418.04209 -203.875132)
		(width 0.18288)
		(layer "In6.Cu")
		(net "M_G_CPU0_SB_DQ<24>")
	)
	(segment
		(start 418.04209 -203.875132)
		(end 417.85921 -203.692252)
		(width 0.18288)
		(layer "In6.Cu")
		(net "M_G_CPU0_SB_DQ<24>")
	)
	(segment
		(start 432.056032 -203.518516)
		(end 431.896012 -203.678536)
		(width 0.18288)
		(layer "In6.Cu")
		(net "M_G_CPU0_SB_DQ<24>")
	)
	(segment
		(start 399.620486 -209.390234)
		(end 399.620486 -210.141058)
		(width 0.18288)
		(layer "In6.Cu")
		(net "M_G_CPU0_SB_DQ<24>")
	)
	(segment
		(start 409.107386 -203.586334)
		(end 408.900884 -203.792836)
		(width 0.18288)
		(layer "In6.Cu")
		(net "M_G_CPU0_SB_DQ<24>")
	)
	(segment
		(start 418.73551 -203.875132)
		(end 418.73551 -204.259434)
		(width 0.18288)
		(layer "In6.Cu")
		(net "M_G_CPU0_SB_DQ<24>")
	)
	(segment
		(start 411.471872 -203.586334)
		(end 411.288992 -203.769214)
		(width 0.18288)
		(layer "In6.Cu")
		(net "M_G_CPU0_SB_DQ<24>")
	)
	(segment
		(start 423.20972 -203.692252)
		(end 422.599104 -203.692252)
		(width 0.18288)
		(layer "In6.Cu")
		(net "M_G_CPU0_SB_DQ<24>")
	)
	(segment
		(start 408.900884 -203.792836)
		(end 407.157682 -203.792836)
		(width 0.18288)
		(layer "In6.Cu")
		(net "M_G_CPU0_SB_DQ<24>")
	)
	(arc
		(start 384.859784 -220.319854)
		(mid 384.812105 -220.136954)
		(end 384.681222 -220.000576)
		(width 0.088646)
		(layer "In6.Cu")
		(net "M_G_CPU0_SB_DQ<24>")
	)
	(arc
		(start 388.64413 -220.71965)
		(mid 388.318147 -220.880412)
		(end 387.961632 -220.809566)
		(width 0.088646)
		(layer "In6.Cu")
		(net "M_G_CPU0_SB_DQ<24>")
	)
	(arc
		(start 386.647436 -220.809566)
		(mid 386.364734 -220.885308)
		(end 386.082032 -220.809566)
		(width 0.088646)
		(layer "In6.Cu")
		(net "M_G_CPU0_SB_DQ<24>")
	)
	(arc
		(start 387.587236 -220.809566)
		(mid 387.304534 -220.885308)
		(end 387.021832 -220.809566)
		(width 0.088646)
		(layer "In6.Cu")
		(net "M_G_CPU0_SB_DQ<24>")
	)
	(arc
		(start 386.082032 -220.809566)
		(mid 385.894834 -220.759423)
		(end 385.707636 -220.809566)
		(width 0.088646)
		(layer "In6.Cu")
		(net "M_G_CPU0_SB_DQ<24>")
	)
	(arc
		(start 387.961632 -220.809566)
		(mid 387.774434 -220.759423)
		(end 387.587236 -220.809566)
		(width 0.088646)
		(layer "In6.Cu")
		(net "M_G_CPU0_SB_DQ<24>")
	)
	(arc
		(start 385.142232 -220.809566)
		(mid 384.935472 -220.602803)
		(end 384.859784 -220.320362)
		(width 0.088646)
		(layer "In6.Cu")
		(net "M_G_CPU0_SB_DQ<24>")
	)
	(arc
		(start 385.707636 -220.809566)
		(mid 385.424934 -220.885308)
		(end 385.142232 -220.809566)
		(width 0.088646)
		(layer "In6.Cu")
		(net "M_G_CPU0_SB_DQ<24>")
	)
	(arc
		(start 387.021832 -220.809566)
		(mid 386.834634 -220.759423)
		(end 386.647436 -220.809566)
		(width 0.088646)
		(layer "In6.Cu")
		(net "M_G_CPU0_SB_DQ<24>")
	)
	(segment
		(start 443.15888 -205.398624)
		(end 443.450726 -205.398624)
		(width 0.20066)
		(layer "F.Cu")
		(net "M_G_CPU0_SB_DQ<23>")
	)
	(segment
		(start 379.31598 -231.436418)
		(end 379.31598 -230.900732)
		(width 0.20066)
		(layer "F.Cu")
		(net "M_G_CPU0_SB_DQ<23>")
	)
	(segment
		(start 447.23812 -204.96657)
		(end 448.572382 -204.96657)
		(width 0.20066)
		(layer "F.Cu")
		(net "M_G_CPU0_SB_DQ<23>")
	)
	(segment
		(start 379.31598 -230.900732)
		(end 379.316234 -230.900478)
		(width 0.20066)
		(layer "F.Cu")
		(net "M_G_CPU0_SB_DQ<23>")
	)
	(segment
		(start 446.367916 -205.199742)
		(end 446.367916 -204.94879)
		(width 0.20066)
		(layer "F.Cu")
		(net "M_G_CPU0_SB_DQ<23>")
	)
	(segment
		(start 443.455552 -205.398624)
		(end 443.462664 -205.391512)
		(width 0.1016)
		(layer "F.Cu")
		(net "M_G_CPU0_SB_DQ<23>")
	)
	(segment
		(start 439.923682 -204.96657)
		(end 441.028582 -204.96657)
		(width 0.20066)
		(layer "F.Cu")
		(net "M_G_CPU0_SB_DQ<23>")
	)
	(segment
		(start 443.462664 -205.391512)
		(end 445.470534 -205.391512)
		(width 0.1016)
		(layer "F.Cu")
		(net "M_G_CPU0_SB_DQ<23>")
	)
	(segment
		(start 442.726826 -204.96657)
		(end 443.15888 -205.398624)
		(width 0.20066)
		(layer "F.Cu")
		(net "M_G_CPU0_SB_DQ<23>")
	)
	(segment
		(start 446.367916 -204.94879)
		(end 446.602104 -204.714602)
		(width 0.20066)
		(layer "F.Cu")
		(net "M_G_CPU0_SB_DQ<23>")
	)
	(segment
		(start 446.986152 -204.714602)
		(end 447.23812 -204.96657)
		(width 0.20066)
		(layer "F.Cu")
		(net "M_G_CPU0_SB_DQ<23>")
	)
	(segment
		(start 446.602104 -204.714602)
		(end 446.986152 -204.714602)
		(width 0.20066)
		(layer "F.Cu")
		(net "M_G_CPU0_SB_DQ<23>")
	)
	(segment
		(start 443.450726 -205.398624)
		(end 443.455552 -205.398624)
		(width 0.101854)
		(layer "F.Cu")
		(net "M_G_CPU0_SB_DQ<23>")
	)
	(segment
		(start 445.470534 -205.391512)
		(end 445.482726 -205.403704)
		(width 0.1016)
		(layer "F.Cu")
		(net "M_G_CPU0_SB_DQ<23>")
	)
	(segment
		(start 446.163954 -205.403704)
		(end 446.367916 -205.199742)
		(width 0.20066)
		(layer "F.Cu")
		(net "M_G_CPU0_SB_DQ<23>")
	)
	(segment
		(start 441.028582 -204.96657)
		(end 442.726826 -204.96657)
		(width 0.20066)
		(layer "F.Cu")
		(net "M_G_CPU0_SB_DQ<23>")
	)
	(segment
		(start 445.482726 -205.403704)
		(end 446.163954 -205.403704)
		(width 0.20066)
		(layer "F.Cu")
		(net "M_G_CPU0_SB_DQ<23>")
	)
	(segment
		(start 379.973332 -230.41102)
		(end 379.91034 -230.448104)
		(width 0.088646)
		(layer "In4.Cu")
		(net "M_G_CPU0_SB_DQ<23>")
	)
	(segment
		(start 383.741422 -230.40594)
		(end 383.732532 -230.41102)
		(width 0.088646)
		(layer "In4.Cu")
		(net "M_G_CPU0_SB_DQ<23>")
	)
	(segment
		(start 414.97123 -207.375506)
		(end 414.61055 -207.014826)
		(width 0.18288)
		(layer "In4.Cu")
		(net "M_G_CPU0_SB_DQ<23>")
	)
	(segment
		(start 385.329684 -227.64496)
		(end 385.32943 -227.64496)
		(width 0.088646)
		(layer "In4.Cu")
		(net "M_G_CPU0_SB_DQ<23>")
	)
	(segment
		(start 414.61055 -207.014826)
		(end 413.603694 -207.014826)
		(width 0.18288)
		(layer "In4.Cu")
		(net "M_G_CPU0_SB_DQ<23>")
	)
	(segment
		(start 379.83668 -230.497888)
		(end 379.316234 -230.900478)
		(width 0.088646)
		(layer "In4.Cu")
		(net "M_G_CPU0_SB_DQ<23>")
	)
	(segment
		(start 389.822944 -224.590356)
		(end 388.71271 -224.590356)
		(width 0.18288)
		(layer "In4.Cu")
		(net "M_G_CPU0_SB_DQ<23>")
	)
	(segment
		(start 407.092404 -207.85963)
		(end 404.75408 -207.85963)
		(width 0.18288)
		(layer "In4.Cu")
		(net "M_G_CPU0_SB_DQ<23>")
	)
	(segment
		(start 413.603694 -207.014826)
		(end 413.366204 -207.252316)
		(width 0.18288)
		(layer "In4.Cu")
		(net "M_G_CPU0_SB_DQ<23>")
	)
	(segment
		(start 439.923682 -204.96657)
		(end 438.787286 -204.485748)
		(width 0.18288)
		(layer "In4.Cu")
		(net "M_G_CPU0_SB_DQ<23>")
	)
	(segment
		(start 382.792732 -230.41102)
		(end 382.788922 -230.413306)
		(width 0.088646)
		(layer "In4.Cu")
		(net "M_G_CPU0_SB_DQ<23>")
	)
	(segment
		(start 403.36089 -209.25282)
		(end 402.08835 -212.324696)
		(width 0.18288)
		(layer "In4.Cu")
		(net "M_G_CPU0_SB_DQ<23>")
	)
	(segment
		(start 382.798574 -230.407718)
		(end 382.792732 -230.41102)
		(width 0.088646)
		(layer "In4.Cu")
		(net "M_G_CPU0_SB_DQ<23>")
	)
	(segment
		(start 384.672332 -228.783388)
		(end 384.666236 -228.786944)
		(width 0.088646)
		(layer "In4.Cu")
		(net "M_G_CPU0_SB_DQ<23>")
	)
	(segment
		(start 411.67304 -206.985616)
		(end 409.452318 -206.985616)
		(width 0.18288)
		(layer "In4.Cu")
		(net "M_G_CPU0_SB_DQ<23>")
	)
	(segment
		(start 407.10104 -207.850994)
		(end 407.092404 -207.85963)
		(width 0.18288)
		(layer "In4.Cu")
		(net "M_G_CPU0_SB_DQ<23>")
	)
	(segment
		(start 437.70677 -204.485748)
		(end 437.648858 -204.54366)
		(width 0.18288)
		(layer "In4.Cu")
		(net "M_G_CPU0_SB_DQ<23>")
	)
	(segment
		(start 380.918974 -230.407718)
		(end 380.90729 -230.414322)
		(width 0.088646)
		(layer "In4.Cu")
		(net "M_G_CPU0_SB_DQ<23>")
	)
	(segment
		(start 388.71271 -224.590356)
		(end 388.104634 -224.590356)
		(width 0.088646)
		(layer "In4.Cu")
		(net "M_G_CPU0_SB_DQ<23>")
	)
	(segment
		(start 381.852932 -230.41102)
		(end 381.848614 -230.41356)
		(width 0.088646)
		(layer "In4.Cu")
		(net "M_G_CPU0_SB_DQ<23>")
	)
	(segment
		(start 420.551864 -206.243682)
		(end 420.261542 -206.534004)
		(width 0.18288)
		(layer "In4.Cu")
		(net "M_G_CPU0_SB_DQ<23>")
	)
	(segment
		(start 416.311842 -207.375506)
		(end 414.97123 -207.375506)
		(width 0.18288)
		(layer "In4.Cu")
		(net "M_G_CPU0_SB_DQ<23>")
	)
	(segment
		(start 428.944278 -205.067662)
		(end 426.918374 -207.093566)
		(width 0.18288)
		(layer "In4.Cu")
		(net "M_G_CPU0_SB_DQ<23>")
	)
	(segment
		(start 387.243066 -225.451924)
		(end 386.834634 -225.451924)
		(width 0.088646)
		(layer "In4.Cu")
		(net "M_G_CPU0_SB_DQ<23>")
	)
	(segment
		(start 385.329684 -227.635054)
		(end 385.329684 -227.64496)
		(width 0.088646)
		(layer "In4.Cu")
		(net "M_G_CPU0_SB_DQ<23>")
	)
	(segment
		(start 426.918374 -207.093566)
		(end 424.347894 -207.093566)
		(width 0.18288)
		(layer "In4.Cu")
		(net "M_G_CPU0_SB_DQ<23>")
	)
	(segment
		(start 385.621022 -227.150422)
		(end 385.612132 -227.155502)
		(width 0.088646)
		(layer "In4.Cu")
		(net "M_G_CPU0_SB_DQ<23>")
	)
	(segment
		(start 409.452318 -206.985616)
		(end 407.710894 -207.850994)
		(width 0.18288)
		(layer "In4.Cu")
		(net "M_G_CPU0_SB_DQ<23>")
	)
	(segment
		(start 437.648858 -204.54366)
		(end 430.22266 -204.54366)
		(width 0.18288)
		(layer "In4.Cu")
		(net "M_G_CPU0_SB_DQ<23>")
	)
	(segment
		(start 420.261542 -206.534004)
		(end 419.013386 -206.534004)
		(width 0.18288)
		(layer "In4.Cu")
		(net "M_G_CPU0_SB_DQ<23>")
	)
	(segment
		(start 388.104634 -224.590356)
		(end 387.243066 -225.451924)
		(width 0.088646)
		(layer "In4.Cu")
		(net "M_G_CPU0_SB_DQ<23>")
	)
	(segment
		(start 402.08835 -212.324696)
		(end 389.822944 -224.590356)
		(width 0.18288)
		(layer "In4.Cu")
		(net "M_G_CPU0_SB_DQ<23>")
	)
	(segment
		(start 386.090922 -226.336606)
		(end 386.082032 -226.341686)
		(width 0.088646)
		(layer "In4.Cu")
		(net "M_G_CPU0_SB_DQ<23>")
	)
	(segment
		(start 412.928054 -207.252316)
		(end 412.14167 -206.977996)
		(width 0.18288)
		(layer "In4.Cu")
		(net "M_G_CPU0_SB_DQ<23>")
	)
	(segment
		(start 424.347894 -207.093566)
		(end 423.787824 -206.533496)
		(width 0.18288)
		(layer "In4.Cu")
		(net "M_G_CPU0_SB_DQ<23>")
	)
	(segment
		(start 420.91864 -206.243682)
		(end 420.551864 -206.243682)
		(width 0.18288)
		(layer "In4.Cu")
		(net "M_G_CPU0_SB_DQ<23>")
	)
	(segment
		(start 413.366204 -207.252316)
		(end 412.928054 -207.252316)
		(width 0.18288)
		(layer "In4.Cu")
		(net "M_G_CPU0_SB_DQ<23>")
	)
	(segment
		(start 384.681222 -228.778308)
		(end 384.672332 -228.783388)
		(width 0.088646)
		(layer "In4.Cu")
		(net "M_G_CPU0_SB_DQ<23>")
	)
	(segment
		(start 379.979174 -230.407718)
		(end 379.973332 -230.41102)
		(width 0.088646)
		(layer "In4.Cu")
		(net "M_G_CPU0_SB_DQ<23>")
	)
	(segment
		(start 384.859276 -228.443536)
		(end 384.85953 -228.45903)
		(width 0.088646)
		(layer "In4.Cu")
		(net "M_G_CPU0_SB_DQ<23>")
	)
	(segment
		(start 404.75408 -207.85963)
		(end 403.36089 -209.25282)
		(width 0.18288)
		(layer "In4.Cu")
		(net "M_G_CPU0_SB_DQ<23>")
	)
	(segment
		(start 384.38963 -229.272846)
		(end 384.38963 -229.281482)
		(width 0.088646)
		(layer "In4.Cu")
		(net "M_G_CPU0_SB_DQ<23>")
	)
	(segment
		(start 419.013386 -206.534004)
		(end 418.51961 -207.02778)
		(width 0.18288)
		(layer "In4.Cu")
		(net "M_G_CPU0_SB_DQ<23>")
	)
	(segment
		(start 383.919984 -230.076756)
		(end 383.919984 -230.086662)
		(width 0.088646)
		(layer "In4.Cu")
		(net "M_G_CPU0_SB_DQ<23>")
	)
	(segment
		(start 418.51961 -207.02778)
		(end 416.659568 -207.02778)
		(width 0.18288)
		(layer "In4.Cu")
		(net "M_G_CPU0_SB_DQ<23>")
	)
	(segment
		(start 423.278046 -206.243682)
		(end 421.746172 -206.243682)
		(width 0.18288)
		(layer "In4.Cu")
		(net "M_G_CPU0_SB_DQ<23>")
	)
	(segment
		(start 385.799584 -226.821238)
		(end 385.799584 -226.831144)
		(width 0.088646)
		(layer "In4.Cu")
		(net "M_G_CPU0_SB_DQ<23>")
	)
	(segment
		(start 430.22266 -204.54366)
		(end 428.944278 -205.067662)
		(width 0.18288)
		(layer "In4.Cu")
		(net "M_G_CPU0_SB_DQ<23>")
	)
	(segment
		(start 421.08755 -206.412592)
		(end 420.91864 -206.243682)
		(width 0.18288)
		(layer "In4.Cu")
		(net "M_G_CPU0_SB_DQ<23>")
	)
	(segment
		(start 407.710894 -207.850994)
		(end 407.10104 -207.850994)
		(width 0.18288)
		(layer "In4.Cu")
		(net "M_G_CPU0_SB_DQ<23>")
	)
	(segment
		(start 421.577262 -206.412592)
		(end 421.08755 -206.412592)
		(width 0.18288)
		(layer "In4.Cu")
		(net "M_G_CPU0_SB_DQ<23>")
	)
	(segment
		(start 416.659568 -207.02778)
		(end 416.311842 -207.375506)
		(width 0.18288)
		(layer "In4.Cu")
		(net "M_G_CPU0_SB_DQ<23>")
	)
	(segment
		(start 438.787286 -204.485748)
		(end 437.70677 -204.485748)
		(width 0.18288)
		(layer "In4.Cu")
		(net "M_G_CPU0_SB_DQ<23>")
	)
	(segment
		(start 386.269484 -225.998786)
		(end 386.269484 -226.017328)
		(width 0.088646)
		(layer "In4.Cu")
		(net "M_G_CPU0_SB_DQ<23>")
	)
	(segment
		(start 423.787824 -206.533496)
		(end 423.278046 -206.243682)
		(width 0.18288)
		(layer "In4.Cu")
		(net "M_G_CPU0_SB_DQ<23>")
	)
	(segment
		(start 383.732532 -230.41102)
		(end 383.728214 -230.41356)
		(width 0.088646)
		(layer "In4.Cu")
		(net "M_G_CPU0_SB_DQ<23>")
	)
	(segment
		(start 385.150868 -227.964238)
		(end 385.141978 -227.969318)
		(width 0.088646)
		(layer "In4.Cu")
		(net "M_G_CPU0_SB_DQ<23>")
	)
	(segment
		(start 421.746172 -206.243682)
		(end 421.577262 -206.412592)
		(width 0.18288)
		(layer "In4.Cu")
		(net "M_G_CPU0_SB_DQ<23>")
	)
	(segment
		(start 412.14167 -206.977996)
		(end 411.67304 -206.985616)
		(width 0.18288)
		(layer "In4.Cu")
		(net "M_G_CPU0_SB_DQ<23>")
	)
	(segment
		(start 384.85953 -228.45903)
		(end 384.859784 -228.45903)
		(width 0.088646)
		(layer "In4.Cu")
		(net "M_G_CPU0_SB_DQ<23>")
	)
	(arc
		(start 379.91034 -230.448104)
		(mid 379.872729 -230.471841)
		(end 379.83668 -230.497888)
		(width 0.088646)
		(layer "In4.Cu")
		(net "M_G_CPU0_SB_DQ<23>")
	)
	(arc
		(start 382.418082 -230.41102)
		(mid 382.135524 -230.335371)
		(end 381.852932 -230.41102)
		(width 0.088646)
		(layer "In4.Cu")
		(net "M_G_CPU0_SB_DQ<23>")
	)
	(arc
		(start 385.141978 -227.969318)
		(mid 384.938735 -228.169544)
		(end 384.859276 -228.443536)
		(width 0.088646)
		(layer "In4.Cu")
		(net "M_G_CPU0_SB_DQ<23>")
	)
	(arc
		(start 386.834634 -225.451924)
		(mid 386.441443 -225.611025)
		(end 386.269484 -225.998786)
		(width 0.088646)
		(layer "In4.Cu")
		(net "M_G_CPU0_SB_DQ<23>")
	)
	(arc
		(start 380.538482 -230.41102)
		(mid 380.259279 -230.33538)
		(end 379.979174 -230.407718)
		(width 0.088646)
		(layer "In4.Cu")
		(net "M_G_CPU0_SB_DQ<23>")
	)
	(arc
		(start 386.269484 -226.017328)
		(mid 386.221805 -226.200228)
		(end 386.090922 -226.336606)
		(width 0.088646)
		(layer "In4.Cu")
		(net "M_G_CPU0_SB_DQ<23>")
	)
	(arc
		(start 383.728214 -230.41356)
		(mid 383.542719 -230.461229)
		(end 383.357882 -230.41102)
		(width 0.088646)
		(layer "In4.Cu")
		(net "M_G_CPU0_SB_DQ<23>")
	)
	(arc
		(start 385.32943 -227.64496)
		(mid 385.281751 -227.82786)
		(end 385.150868 -227.964238)
		(width 0.088646)
		(layer "In4.Cu")
		(net "M_G_CPU0_SB_DQ<23>")
	)
	(arc
		(start 384.859784 -228.45903)
		(mid 384.812105 -228.64193)
		(end 384.681222 -228.778308)
		(width 0.088646)
		(layer "In4.Cu")
		(net "M_G_CPU0_SB_DQ<23>")
	)
	(arc
		(start 383.919984 -230.086662)
		(mid 383.872305 -230.269562)
		(end 383.741422 -230.40594)
		(width 0.088646)
		(layer "In4.Cu")
		(net "M_G_CPU0_SB_DQ<23>")
	)
	(arc
		(start 386.082032 -226.341686)
		(mid 385.877697 -226.544291)
		(end 385.799584 -226.821238)
		(width 0.088646)
		(layer "In4.Cu")
		(net "M_G_CPU0_SB_DQ<23>")
	)
	(arc
		(start 384.666236 -228.786944)
		(mid 384.463649 -228.993295)
		(end 384.38963 -229.272846)
		(width 0.088646)
		(layer "In4.Cu")
		(net "M_G_CPU0_SB_DQ<23>")
	)
	(arc
		(start 382.788922 -230.413306)
		(mid 382.603203 -230.461258)
		(end 382.418082 -230.41102)
		(width 0.088646)
		(layer "In4.Cu")
		(net "M_G_CPU0_SB_DQ<23>")
	)
	(arc
		(start 381.848614 -230.41356)
		(mid 381.663119 -230.461229)
		(end 381.478282 -230.41102)
		(width 0.088646)
		(layer "In4.Cu")
		(net "M_G_CPU0_SB_DQ<23>")
	)
	(arc
		(start 380.90729 -230.414322)
		(mid 380.722435 -230.461272)
		(end 380.538482 -230.41102)
		(width 0.088646)
		(layer "In4.Cu")
		(net "M_G_CPU0_SB_DQ<23>")
	)
	(arc
		(start 383.357882 -230.41102)
		(mid 383.078679 -230.33538)
		(end 382.798574 -230.407718)
		(width 0.088646)
		(layer "In4.Cu")
		(net "M_G_CPU0_SB_DQ<23>")
	)
	(arc
		(start 381.478282 -230.41102)
		(mid 381.199079 -230.33538)
		(end 380.918974 -230.407718)
		(width 0.088646)
		(layer "In4.Cu")
		(net "M_G_CPU0_SB_DQ<23>")
	)
	(arc
		(start 385.612132 -227.155502)
		(mid 385.407797 -227.358107)
		(end 385.329684 -227.635054)
		(width 0.088646)
		(layer "In4.Cu")
		(net "M_G_CPU0_SB_DQ<23>")
	)
	(arc
		(start 384.202432 -229.597204)
		(mid 383.998097 -229.799809)
		(end 383.919984 -230.076756)
		(width 0.088646)
		(layer "In4.Cu")
		(net "M_G_CPU0_SB_DQ<23>")
	)
	(arc
		(start 385.799584 -226.831144)
		(mid 385.751905 -227.014044)
		(end 385.621022 -227.150422)
		(width 0.088646)
		(layer "In4.Cu")
		(net "M_G_CPU0_SB_DQ<23>")
	)
	(arc
		(start 384.38963 -229.281482)
		(mid 384.33736 -229.463847)
		(end 384.202432 -229.597204)
		(width 0.088646)
		(layer "In4.Cu")
		(net "M_G_CPU0_SB_DQ<23>")
	)
	(segment
		(start 379.786134 -232.250488)
		(end 379.78588 -232.250234)
		(width 0.20066)
		(layer "F.Cu")
		(net "M_G_CPU0_SB_DQ<22>")
	)
	(segment
		(start 446.602104 -206.414624)
		(end 446.986152 -206.414624)
		(width 0.20066)
		(layer "F.Cu")
		(net "M_G_CPU0_SB_DQ<22>")
	)
	(segment
		(start 447.23812 -206.666592)
		(end 448.572382 -206.666592)
		(width 0.20066)
		(layer "F.Cu")
		(net "M_G_CPU0_SB_DQ<22>")
	)
	(segment
		(start 443.462664 -207.091534)
		(end 445.470534 -207.091534)
		(width 0.1016)
		(layer "F.Cu")
		(net "M_G_CPU0_SB_DQ<22>")
	)
	(segment
		(start 446.367916 -206.899764)
		(end 446.367916 -206.648812)
		(width 0.20066)
		(layer "F.Cu")
		(net "M_G_CPU0_SB_DQ<22>")
	)
	(segment
		(start 379.78588 -232.250234)
		(end 379.78588 -231.714548)
		(width 0.20066)
		(layer "F.Cu")
		(net "M_G_CPU0_SB_DQ<22>")
	)
	(segment
		(start 446.163954 -207.103726)
		(end 446.367916 -206.899764)
		(width 0.20066)
		(layer "F.Cu")
		(net "M_G_CPU0_SB_DQ<22>")
	)
	(segment
		(start 441.028582 -206.666592)
		(end 442.726826 -206.666592)
		(width 0.20066)
		(layer "F.Cu")
		(net "M_G_CPU0_SB_DQ<22>")
	)
	(segment
		(start 443.15888 -207.098646)
		(end 443.450726 -207.098646)
		(width 0.20066)
		(layer "F.Cu")
		(net "M_G_CPU0_SB_DQ<22>")
	)
	(segment
		(start 445.482726 -207.103726)
		(end 446.163954 -207.103726)
		(width 0.20066)
		(layer "F.Cu")
		(net "M_G_CPU0_SB_DQ<22>")
	)
	(segment
		(start 445.470534 -207.091534)
		(end 445.482726 -207.103726)
		(width 0.1016)
		(layer "F.Cu")
		(net "M_G_CPU0_SB_DQ<22>")
	)
	(segment
		(start 446.986152 -206.414624)
		(end 447.23812 -206.666592)
		(width 0.20066)
		(layer "F.Cu")
		(net "M_G_CPU0_SB_DQ<22>")
	)
	(segment
		(start 439.923682 -206.666592)
		(end 441.028582 -206.666592)
		(width 0.20066)
		(layer "F.Cu")
		(net "M_G_CPU0_SB_DQ<22>")
	)
	(segment
		(start 443.450726 -207.098646)
		(end 443.455552 -207.098646)
		(width 0.101854)
		(layer "F.Cu")
		(net "M_G_CPU0_SB_DQ<22>")
	)
	(segment
		(start 442.726826 -206.666592)
		(end 443.15888 -207.098646)
		(width 0.20066)
		(layer "F.Cu")
		(net "M_G_CPU0_SB_DQ<22>")
	)
	(segment
		(start 443.455552 -207.098646)
		(end 443.462664 -207.091534)
		(width 0.1016)
		(layer "F.Cu")
		(net "M_G_CPU0_SB_DQ<22>")
	)
	(segment
		(start 446.367916 -206.648812)
		(end 446.602104 -206.414624)
		(width 0.20066)
		(layer "F.Cu")
		(net "M_G_CPU0_SB_DQ<22>")
	)
	(segment
		(start 383.827782 -231.22509)
		(end 383.822194 -231.221788)
		(width 0.088646)
		(layer "In4.Cu")
		(net "M_G_CPU0_SB_DQ<22>")
	)
	(segment
		(start 403.904704 -210.957922)
		(end 403.226524 -212.594952)
		(width 0.18288)
		(layer "In4.Cu")
		(net "M_G_CPU0_SB_DQ<22>")
	)
	(segment
		(start 425.465494 -209.643726)
		(end 424.302682 -209.643726)
		(width 0.18288)
		(layer "In4.Cu")
		(net "M_G_CPU0_SB_DQ<22>")
	)
	(segment
		(start 381.948182 -231.22509)
		(end 381.942594 -231.221788)
		(width 0.088646)
		(layer "In4.Cu")
		(net "M_G_CPU0_SB_DQ<22>")
	)
	(segment
		(start 380.443232 -231.22509)
		(end 380.365 -231.270048)
		(width 0.088646)
		(layer "In4.Cu")
		(net "M_G_CPU0_SB_DQ<22>")
	)
	(segment
		(start 405.27732 -209.585306)
		(end 403.904704 -210.957922)
		(width 0.18288)
		(layer "In4.Cu")
		(net "M_G_CPU0_SB_DQ<22>")
	)
	(segment
		(start 382.892554 -231.22763)
		(end 382.887982 -231.22509)
		(width 0.088646)
		(layer "In4.Cu")
		(net "M_G_CPU0_SB_DQ<22>")
	)
	(segment
		(start 388.283704 -225.921316)
		(end 388.283704 -226.10064)
		(width 0.088646)
		(layer "In4.Cu")
		(net "M_G_CPU0_SB_DQ<22>")
	)
	(segment
		(start 419.190424 -208.844896)
		(end 418.504624 -208.844896)
		(width 0.18288)
		(layer "In4.Cu")
		(net "M_G_CPU0_SB_DQ<22>")
	)
	(segment
		(start 388.283704 -226.10064)
		(end 387.989318 -226.395026)
		(width 0.088646)
		(layer "In4.Cu")
		(net "M_G_CPU0_SB_DQ<22>")
	)
	(segment
		(start 386.985764 -226.395026)
		(end 386.73913 -226.64166)
		(width 0.088646)
		(layer "In4.Cu")
		(net "M_G_CPU0_SB_DQ<22>")
	)
	(segment
		(start 383.828036 -231.224836)
		(end 383.827782 -231.22509)
		(width 0.088646)
		(layer "In4.Cu")
		(net "M_G_CPU0_SB_DQ<22>")
	)
	(segment
		(start 384.859784 -230.071168)
		(end 384.859784 -230.086662)
		(width 0.088646)
		(layer "In4.Cu")
		(net "M_G_CPU0_SB_DQ<22>")
	)
	(segment
		(start 387.989318 -226.395026)
		(end 386.985764 -226.395026)
		(width 0.088646)
		(layer "In4.Cu")
		(net "M_G_CPU0_SB_DQ<22>")
	)
	(segment
		(start 424.07332 -208.543652)
		(end 423.473118 -207.94345)
		(width 0.18288)
		(layer "In4.Cu")
		(net "M_G_CPU0_SB_DQ<22>")
	)
	(segment
		(start 382.887982 -231.22509)
		(end 382.88341 -231.222296)
		(width 0.088646)
		(layer "In4.Cu")
		(net "M_G_CPU0_SB_DQ<22>")
	)
	(segment
		(start 428.386494 -208.894426)
		(end 426.214794 -208.894426)
		(width 0.18288)
		(layer "In4.Cu")
		(net "M_G_CPU0_SB_DQ<22>")
	)
	(segment
		(start 423.473118 -207.94345)
		(end 420.09187 -207.94345)
		(width 0.18288)
		(layer "In4.Cu")
		(net "M_G_CPU0_SB_DQ<22>")
	)
	(segment
		(start 424.302682 -209.643726)
		(end 424.07332 -209.414364)
		(width 0.18288)
		(layer "In4.Cu")
		(net "M_G_CPU0_SB_DQ<22>")
	)
	(segment
		(start 439.923682 -206.666592)
		(end 439.500772 -206.243682)
		(width 0.18288)
		(layer "In4.Cu")
		(net "M_G_CPU0_SB_DQ<22>")
	)
	(segment
		(start 388.57682 -225.6282)
		(end 388.283704 -225.921316)
		(width 0.088646)
		(layer "In4.Cu")
		(net "M_G_CPU0_SB_DQ<22>")
	)
	(segment
		(start 416.095942 -208.843626)
		(end 412.373826 -208.843626)
		(width 0.18288)
		(layer "In4.Cu")
		(net "M_G_CPU0_SB_DQ<22>")
	)
	(segment
		(start 385.612132 -228.783388)
		(end 385.59994 -228.7905)
		(width 0.088646)
		(layer "In4.Cu")
		(net "M_G_CPU0_SB_DQ<22>")
	)
	(segment
		(start 412.373826 -208.843626)
		(end 411.632146 -209.585306)
		(width 0.18288)
		(layer "In4.Cu")
		(net "M_G_CPU0_SB_DQ<22>")
	)
	(segment
		(start 381.008382 -231.22509)
		(end 381.001016 -231.220772)
		(width 0.088646)
		(layer "In4.Cu")
		(net "M_G_CPU0_SB_DQ<22>")
	)
	(segment
		(start 384.389884 -230.890572)
		(end 384.389884 -230.900478)
		(width 0.088646)
		(layer "In4.Cu")
		(net "M_G_CPU0_SB_DQ<22>")
	)
	(segment
		(start 428.589694 -208.691226)
		(end 428.386494 -208.894426)
		(width 0.18288)
		(layer "In4.Cu")
		(net "M_G_CPU0_SB_DQ<22>")
	)
	(segment
		(start 386.551932 -227.155502)
		(end 386.545836 -227.159058)
		(width 0.088646)
		(layer "In4.Cu")
		(net "M_G_CPU0_SB_DQ<22>")
	)
	(segment
		(start 431.850038 -206.243682)
		(end 429.402494 -208.691226)
		(width 0.18288)
		(layer "In4.Cu")
		(net "M_G_CPU0_SB_DQ<22>")
	)
	(segment
		(start 411.632146 -209.585306)
		(end 405.27732 -209.585306)
		(width 0.18288)
		(layer "In4.Cu")
		(net "M_G_CPU0_SB_DQ<22>")
	)
	(segment
		(start 388.71271 -225.6282)
		(end 388.57682 -225.6282)
		(width 0.088646)
		(layer "In4.Cu")
		(net "M_G_CPU0_SB_DQ<22>")
	)
	(segment
		(start 424.07332 -209.414364)
		(end 424.07332 -208.543652)
		(width 0.18288)
		(layer "In4.Cu")
		(net "M_G_CPU0_SB_DQ<22>")
	)
	(segment
		(start 386.26923 -227.64496)
		(end 386.26923 -227.653596)
		(width 0.088646)
		(layer "In4.Cu")
		(net "M_G_CPU0_SB_DQ<22>")
	)
	(segment
		(start 416.38855 -208.551018)
		(end 416.095942 -208.843626)
		(width 0.18288)
		(layer "In4.Cu")
		(net "M_G_CPU0_SB_DQ<22>")
	)
	(segment
		(start 384.211322 -231.219756)
		(end 384.202432 -231.224836)
		(width 0.088646)
		(layer "In4.Cu")
		(net "M_G_CPU0_SB_DQ<22>")
	)
	(segment
		(start 418.210746 -208.551018)
		(end 416.38855 -208.551018)
		(width 0.18288)
		(layer "In4.Cu")
		(net "M_G_CPU0_SB_DQ<22>")
	)
	(segment
		(start 439.500772 -206.243682)
		(end 431.850038 -206.243682)
		(width 0.18288)
		(layer "In4.Cu")
		(net "M_G_CPU0_SB_DQ<22>")
	)
	(segment
		(start 380.077726 -231.461818)
		(end 379.78588 -231.714548)
		(width 0.088646)
		(layer "In4.Cu")
		(net "M_G_CPU0_SB_DQ<22>")
	)
	(segment
		(start 403.226524 -212.594952)
		(end 390.193276 -225.6282)
		(width 0.18288)
		(layer "In4.Cu")
		(net "M_G_CPU0_SB_DQ<22>")
	)
	(segment
		(start 385.621022 -228.778308)
		(end 385.612132 -228.783388)
		(width 0.088646)
		(layer "In4.Cu")
		(net "M_G_CPU0_SB_DQ<22>")
	)
	(segment
		(start 426.214794 -208.894426)
		(end 425.465494 -209.643726)
		(width 0.18288)
		(layer "In4.Cu")
		(net "M_G_CPU0_SB_DQ<22>")
	)
	(segment
		(start 429.402494 -208.691226)
		(end 428.589694 -208.691226)
		(width 0.18288)
		(layer "In4.Cu")
		(net "M_G_CPU0_SB_DQ<22>")
	)
	(segment
		(start 390.193276 -225.6282)
		(end 388.71271 -225.6282)
		(width 0.18288)
		(layer "In4.Cu")
		(net "M_G_CPU0_SB_DQ<22>")
	)
	(segment
		(start 386.73913 -226.64166)
		(end 386.73913 -226.83978)
		(width 0.088646)
		(layer "In4.Cu")
		(net "M_G_CPU0_SB_DQ<22>")
	)
	(segment
		(start 385.150868 -229.592124)
		(end 385.141978 -229.597204)
		(width 0.088646)
		(layer "In4.Cu")
		(net "M_G_CPU0_SB_DQ<22>")
	)
	(segment
		(start 385.799584 -228.440488)
		(end 385.799584 -228.45903)
		(width 0.088646)
		(layer "In4.Cu")
		(net "M_G_CPU0_SB_DQ<22>")
	)
	(segment
		(start 418.504624 -208.844896)
		(end 418.210746 -208.551018)
		(width 0.18288)
		(layer "In4.Cu")
		(net "M_G_CPU0_SB_DQ<22>")
	)
	(segment
		(start 384.681222 -230.40594)
		(end 384.672332 -230.41102)
		(width 0.088646)
		(layer "In4.Cu")
		(net "M_G_CPU0_SB_DQ<22>")
	)
	(segment
		(start 420.09187 -207.94345)
		(end 419.190424 -208.844896)
		(width 0.18288)
		(layer "In4.Cu")
		(net "M_G_CPU0_SB_DQ<22>")
	)
	(segment
		(start 381.012954 -231.22763)
		(end 381.008382 -231.22509)
		(width 0.088646)
		(layer "In4.Cu")
		(net "M_G_CPU0_SB_DQ<22>")
	)
	(arc
		(start 386.73913 -226.83978)
		(mid 386.68686 -227.022145)
		(end 386.551932 -227.155502)
		(width 0.088646)
		(layer "In4.Cu")
		(net "M_G_CPU0_SB_DQ<22>")
	)
	(arc
		(start 385.32943 -229.272846)
		(mid 385.281751 -229.455746)
		(end 385.150868 -229.592124)
		(width 0.088646)
		(layer "In4.Cu")
		(net "M_G_CPU0_SB_DQ<22>")
	)
	(arc
		(start 384.672332 -230.41102)
		(mid 384.467997 -230.613625)
		(end 384.389884 -230.890572)
		(width 0.088646)
		(layer "In4.Cu")
		(net "M_G_CPU0_SB_DQ<22>")
	)
	(arc
		(start 380.365 -231.270048)
		(mid 380.238237 -231.347331)
		(end 380.115826 -231.431338)
		(width 0.088646)
		(layer "In4.Cu")
		(net "M_G_CPU0_SB_DQ<22>")
	)
	(arc
		(start 382.322832 -231.22509)
		(mid 382.135524 -231.275199)
		(end 381.948182 -231.22509)
		(width 0.088646)
		(layer "In4.Cu")
		(net "M_G_CPU0_SB_DQ<22>")
	)
	(arc
		(start 381.383032 -231.22509)
		(mid 381.198338 -231.275191)
		(end 381.012954 -231.22763)
		(width 0.088646)
		(layer "In4.Cu")
		(net "M_G_CPU0_SB_DQ<22>")
	)
	(arc
		(start 383.822194 -231.221788)
		(mid 383.541979 -231.149347)
		(end 383.262632 -231.22509)
		(width 0.088646)
		(layer "In4.Cu")
		(net "M_G_CPU0_SB_DQ<22>")
	)
	(arc
		(start 384.859784 -230.086662)
		(mid 384.812105 -230.269562)
		(end 384.681222 -230.40594)
		(width 0.088646)
		(layer "In4.Cu")
		(net "M_G_CPU0_SB_DQ<22>")
	)
	(arc
		(start 385.59994 -228.7905)
		(mid 385.401712 -228.996348)
		(end 385.32943 -229.272846)
		(width 0.088646)
		(layer "In4.Cu")
		(net "M_G_CPU0_SB_DQ<22>")
	)
	(arc
		(start 381.942594 -231.221788)
		(mid 381.662379 -231.149347)
		(end 381.383032 -231.22509)
		(width 0.088646)
		(layer "In4.Cu")
		(net "M_G_CPU0_SB_DQ<22>")
	)
	(arc
		(start 382.88341 -231.222296)
		(mid 382.602746 -231.149288)
		(end 382.322832 -231.22509)
		(width 0.088646)
		(layer "In4.Cu")
		(net "M_G_CPU0_SB_DQ<22>")
	)
	(arc
		(start 386.26923 -227.653596)
		(mid 386.21696 -227.835961)
		(end 386.082032 -227.969318)
		(width 0.088646)
		(layer "In4.Cu")
		(net "M_G_CPU0_SB_DQ<22>")
	)
	(arc
		(start 385.141978 -229.597204)
		(mid 384.939155 -229.797435)
		(end 384.859784 -230.071168)
		(width 0.088646)
		(layer "In4.Cu")
		(net "M_G_CPU0_SB_DQ<22>")
	)
	(arc
		(start 385.799584 -228.45903)
		(mid 385.751905 -228.64193)
		(end 385.621022 -228.778308)
		(width 0.088646)
		(layer "In4.Cu")
		(net "M_G_CPU0_SB_DQ<22>")
	)
	(arc
		(start 381.001016 -231.220772)
		(mid 380.721555 -231.149335)
		(end 380.443232 -231.22509)
		(width 0.088646)
		(layer "In4.Cu")
		(net "M_G_CPU0_SB_DQ<22>")
	)
	(arc
		(start 380.115826 -231.431338)
		(mid 380.096455 -231.446177)
		(end 380.077726 -231.461818)
		(width 0.088646)
		(layer "In4.Cu")
		(net "M_G_CPU0_SB_DQ<22>")
	)
	(arc
		(start 386.082032 -227.969318)
		(mid 385.879746 -228.168299)
		(end 385.799584 -228.440488)
		(width 0.088646)
		(layer "In4.Cu")
		(net "M_G_CPU0_SB_DQ<22>")
	)
	(arc
		(start 384.389884 -230.900478)
		(mid 384.342205 -231.083378)
		(end 384.211322 -231.219756)
		(width 0.088646)
		(layer "In4.Cu")
		(net "M_G_CPU0_SB_DQ<22>")
	)
	(arc
		(start 384.202432 -231.224836)
		(mid 384.015234 -231.274979)
		(end 383.828036 -231.224836)
		(width 0.088646)
		(layer "In4.Cu")
		(net "M_G_CPU0_SB_DQ<22>")
	)
	(arc
		(start 383.262632 -231.22509)
		(mid 383.077938 -231.275191)
		(end 382.892554 -231.22763)
		(width 0.088646)
		(layer "In4.Cu")
		(net "M_G_CPU0_SB_DQ<22>")
	)
	(arc
		(start 386.545836 -227.159058)
		(mid 386.343249 -227.365409)
		(end 386.26923 -227.64496)
		(width 0.088646)
		(layer "In4.Cu")
		(net "M_G_CPU0_SB_DQ<22>")
	)
	(segment
		(start 436.928514 -205.816708)
		(end 435.823614 -205.816708)
		(width 0.20066)
		(layer "F.Cu")
		(net "M_G_CPU0_SB_DQ<21>")
	)
	(segment
		(start 439.361072 -205.877414)
		(end 439.173112 -206.065374)
		(width 0.20066)
		(layer "F.Cu")
		(net "M_G_CPU0_SB_DQ<21>")
	)
	(segment
		(start 442.880496 -205.816962)
		(end 442.44895 -205.385416)
		(width 0.20066)
		(layer "F.Cu")
		(net "M_G_CPU0_SB_DQ<21>")
	)
	(segment
		(start 378.37618 -230.900732)
		(end 378.376434 -230.900478)
		(width 0.20066)
		(layer "F.Cu")
		(net "M_G_CPU0_SB_DQ<21>")
	)
	(segment
		(start 439.479182 -205.391766)
		(end 439.361072 -205.509876)
		(width 0.20066)
		(layer "F.Cu")
		(net "M_G_CPU0_SB_DQ<21>")
	)
	(segment
		(start 442.038994 -205.385416)
		(end 442.032644 -205.391766)
		(width 0.1016)
		(layer "F.Cu")
		(net "M_G_CPU0_SB_DQ<21>")
	)
	(segment
		(start 439.361072 -205.509876)
		(end 439.361072 -205.877414)
		(width 0.20066)
		(layer "F.Cu")
		(net "M_G_CPU0_SB_DQ<21>")
	)
	(segment
		(start 439.82386 -205.391766)
		(end 439.479182 -205.391766)
		(width 0.20066)
		(layer "F.Cu")
		(net "M_G_CPU0_SB_DQ<21>")
	)
	(segment
		(start 444.47206 -205.816962)
		(end 442.880496 -205.816962)
		(width 0.20066)
		(layer "F.Cu")
		(net "M_G_CPU0_SB_DQ<21>")
	)
	(segment
		(start 442.44895 -205.385416)
		(end 442.038994 -205.385416)
		(width 0.20066)
		(layer "F.Cu")
		(net "M_G_CPU0_SB_DQ<21>")
	)
	(segment
		(start 439.843926 -205.391766)
		(end 439.82386 -205.391766)
		(width 0.101854)
		(layer "F.Cu")
		(net "M_G_CPU0_SB_DQ<21>")
	)
	(segment
		(start 438.697878 -206.065374)
		(end 438.449212 -205.816708)
		(width 0.20066)
		(layer "F.Cu")
		(net "M_G_CPU0_SB_DQ<21>")
	)
	(segment
		(start 378.37618 -231.436418)
		(end 378.37618 -230.900732)
		(width 0.20066)
		(layer "F.Cu")
		(net "M_G_CPU0_SB_DQ<21>")
	)
	(segment
		(start 438.449212 -205.816708)
		(end 436.928514 -205.816708)
		(width 0.20066)
		(layer "F.Cu")
		(net "M_G_CPU0_SB_DQ<21>")
	)
	(segment
		(start 444.472314 -205.816708)
		(end 444.47206 -205.816962)
		(width 0.20066)
		(layer "F.Cu")
		(net "M_G_CPU0_SB_DQ<21>")
	)
	(segment
		(start 442.032644 -205.391766)
		(end 439.843926 -205.391766)
		(width 0.1016)
		(layer "F.Cu")
		(net "M_G_CPU0_SB_DQ<21>")
	)
	(segment
		(start 439.173112 -206.065374)
		(end 438.697878 -206.065374)
		(width 0.20066)
		(layer "F.Cu")
		(net "M_G_CPU0_SB_DQ<21>")
	)
	(segment
		(start 416.58921 -207.892142)
		(end 412.479236 -207.892142)
		(width 0.18288)
		(layer "In4.Cu")
		(net "M_G_CPU0_SB_DQ<21>")
	)
	(segment
		(start 410.289248 -208.21904)
		(end 410.289248 -208.80705)
		(width 0.18288)
		(layer "In4.Cu")
		(net "M_G_CPU0_SB_DQ<21>")
	)
	(segment
		(start 382.893824 -230.572818)
		(end 382.88341 -230.57866)
		(width 0.088646)
		(layer "In4.Cu")
		(net "M_G_CPU0_SB_DQ<21>")
	)
	(segment
		(start 435.823614 -205.816708)
		(end 435.370732 -205.363826)
		(width 0.18288)
		(layer "In4.Cu")
		(net "M_G_CPU0_SB_DQ<21>")
	)
	(segment
		(start 387.33222 -225.64217)
		(end 386.834634 -225.64217)
		(width 0.088646)
		(layer "In4.Cu")
		(net "M_G_CPU0_SB_DQ<21>")
	)
	(segment
		(start 390.029192 -225.088196)
		(end 388.71271 -225.088196)
		(width 0.18288)
		(layer "In4.Cu")
		(net "M_G_CPU0_SB_DQ<21>")
	)
	(segment
		(start 386.459984 -226.017328)
		(end 386.459984 -226.027234)
		(width 0.088646)
		(layer "In4.Cu")
		(net "M_G_CPU0_SB_DQ<21>")
	)
	(segment
		(start 385.25323 -228.12502)
		(end 385.237228 -228.134418)
		(width 0.088646)
		(layer "In4.Cu")
		(net "M_G_CPU0_SB_DQ<21>")
	)
	(segment
		(start 429.42891 -206.354426)
		(end 427.842172 -207.941164)
		(width 0.18288)
		(layer "In4.Cu")
		(net "M_G_CPU0_SB_DQ<21>")
	)
	(segment
		(start 427.842172 -207.941164)
		(end 424.182032 -207.941164)
		(width 0.18288)
		(layer "In4.Cu")
		(net "M_G_CPU0_SB_DQ<21>")
	)
	(segment
		(start 409.412948 -208.03616)
		(end 408.933142 -208.03616)
		(width 0.18288)
		(layer "In4.Cu")
		(net "M_G_CPU0_SB_DQ<21>")
	)
	(segment
		(start 403.599142 -210.13166)
		(end 402.618448 -212.49894)
		(width 0.18288)
		(layer "In4.Cu")
		(net "M_G_CPU0_SB_DQ<21>")
	)
	(segment
		(start 416.74415 -208.047082)
		(end 416.58921 -207.892142)
		(width 0.18288)
		(layer "In4.Cu")
		(net "M_G_CPU0_SB_DQ<21>")
	)
	(segment
		(start 384.297936 -229.762304)
		(end 384.289046 -229.767384)
		(width 0.088646)
		(layer "In4.Cu")
		(net "M_G_CPU0_SB_DQ<21>")
	)
	(segment
		(start 410.472128 -208.03616)
		(end 410.289248 -208.21904)
		(width 0.18288)
		(layer "In4.Cu")
		(net "M_G_CPU0_SB_DQ<21>")
	)
	(segment
		(start 385.707636 -227.320602)
		(end 385.698746 -227.325682)
		(width 0.088646)
		(layer "In4.Cu")
		(net "M_G_CPU0_SB_DQ<21>")
	)
	(segment
		(start 385.05003 -228.45014)
		(end 385.05003 -228.458776)
		(width 0.088646)
		(layer "In4.Cu")
		(net "M_G_CPU0_SB_DQ<21>")
	)
	(segment
		(start 409.595828 -208.80705)
		(end 409.595828 -208.21904)
		(width 0.18288)
		(layer "In4.Cu")
		(net "M_G_CPU0_SB_DQ<21>")
	)
	(segment
		(start 410.289248 -208.80705)
		(end 410.106368 -208.98993)
		(width 0.18288)
		(layer "In4.Cu")
		(net "M_G_CPU0_SB_DQ<21>")
	)
	(segment
		(start 431.347118 -205.832202)
		(end 430.610518 -205.832202)
		(width 0.18288)
		(layer "In4.Cu")
		(net "M_G_CPU0_SB_DQ<21>")
	)
	(segment
		(start 381.014224 -230.572818)
		(end 381.00254 -230.579422)
		(width 0.088646)
		(layer "In4.Cu")
		(net "M_G_CPU0_SB_DQ<21>")
	)
	(segment
		(start 431.815494 -205.363826)
		(end 431.347118 -205.832202)
		(width 0.18288)
		(layer "In4.Cu")
		(net "M_G_CPU0_SB_DQ<21>")
	)
	(segment
		(start 423.611294 -207.370426)
		(end 422.874694 -207.370426)
		(width 0.18288)
		(layer "In4.Cu")
		(net "M_G_CPU0_SB_DQ<21>")
	)
	(segment
		(start 408.933142 -208.03616)
		(end 408.080718 -208.888584)
		(width 0.18288)
		(layer "In4.Cu")
		(net "M_G_CPU0_SB_DQ<21>")
	)
	(segment
		(start 383.828036 -230.57612)
		(end 383.824226 -230.578152)
		(width 0.088646)
		(layer "In4.Cu")
		(net "M_G_CPU0_SB_DQ<21>")
	)
	(segment
		(start 379.15342 -231.329484)
		(end 378.376434 -230.900478)
		(width 0.088646)
		(layer "In4.Cu")
		(net "M_G_CPU0_SB_DQ<21>")
	)
	(segment
		(start 430.610518 -205.832202)
		(end 430.088294 -206.354426)
		(width 0.18288)
		(layer "In4.Cu")
		(net "M_G_CPU0_SB_DQ<21>")
	)
	(segment
		(start 422.874694 -207.370426)
		(end 422.597834 -207.093566)
		(width 0.18288)
		(layer "In4.Cu")
		(net "M_G_CPU0_SB_DQ<21>")
	)
	(segment
		(start 388.71271 -225.088196)
		(end 387.886194 -225.088196)
		(width 0.088646)
		(layer "In4.Cu")
		(net "M_G_CPU0_SB_DQ<21>")
	)
	(segment
		(start 422.597834 -207.093566)
		(end 419.278562 -207.093566)
		(width 0.18288)
		(layer "In4.Cu")
		(net "M_G_CPU0_SB_DQ<21>")
	)
	(segment
		(start 424.182032 -207.941164)
		(end 423.611294 -207.370426)
		(width 0.18288)
		(layer "In4.Cu")
		(net "M_G_CPU0_SB_DQ<21>")
	)
	(segment
		(start 412.479236 -207.892142)
		(end 412.335218 -208.03616)
		(width 0.18288)
		(layer "In4.Cu")
		(net "M_G_CPU0_SB_DQ<21>")
	)
	(segment
		(start 418.325046 -208.047082)
		(end 416.74415 -208.047082)
		(width 0.18288)
		(layer "In4.Cu")
		(net "M_G_CPU0_SB_DQ<21>")
	)
	(segment
		(start 405.72563 -208.88833)
		(end 404.842472 -208.88833)
		(width 0.18288)
		(layer "In4.Cu")
		(net "M_G_CPU0_SB_DQ<21>")
	)
	(segment
		(start 435.370732 -205.363826)
		(end 431.815494 -205.363826)
		(width 0.18288)
		(layer "In4.Cu")
		(net "M_G_CPU0_SB_DQ<21>")
	)
	(segment
		(start 384.773678 -228.944932)
		(end 384.767582 -228.948488)
		(width 0.088646)
		(layer "In4.Cu")
		(net "M_G_CPU0_SB_DQ<21>")
	)
	(segment
		(start 411.676088 -208.80705)
		(end 411.493208 -208.98993)
		(width 0.18288)
		(layer "In4.Cu")
		(net "M_G_CPU0_SB_DQ<21>")
	)
	(segment
		(start 408.080718 -208.888584)
		(end 405.725884 -208.888584)
		(width 0.18288)
		(layer "In4.Cu")
		(net "M_G_CPU0_SB_DQ<21>")
	)
	(segment
		(start 411.676088 -208.21904)
		(end 411.676088 -208.80705)
		(width 0.18288)
		(layer "In4.Cu")
		(net "M_G_CPU0_SB_DQ<21>")
	)
	(segment
		(start 410.799788 -208.03616)
		(end 410.472128 -208.03616)
		(width 0.18288)
		(layer "In4.Cu")
		(net "M_G_CPU0_SB_DQ<21>")
	)
	(segment
		(start 410.982668 -208.80705)
		(end 410.982668 -208.21904)
		(width 0.18288)
		(layer "In4.Cu")
		(net "M_G_CPU0_SB_DQ<21>")
	)
	(segment
		(start 410.106368 -208.98993)
		(end 409.778708 -208.98993)
		(width 0.18288)
		(layer "In4.Cu")
		(net "M_G_CPU0_SB_DQ<21>")
	)
	(segment
		(start 411.165548 -208.98993)
		(end 410.982668 -208.80705)
		(width 0.18288)
		(layer "In4.Cu")
		(net "M_G_CPU0_SB_DQ<21>")
	)
	(segment
		(start 384.110484 -230.086662)
		(end 384.110484 -230.096568)
		(width 0.088646)
		(layer "In4.Cu")
		(net "M_G_CPU0_SB_DQ<21>")
	)
	(segment
		(start 384.580384 -229.26421)
		(end 384.580384 -229.282752)
		(width 0.088646)
		(layer "In4.Cu")
		(net "M_G_CPU0_SB_DQ<21>")
	)
	(segment
		(start 385.05003 -228.458776)
		(end 385.050284 -228.45903)
		(width 0.088646)
		(layer "In4.Cu")
		(net "M_G_CPU0_SB_DQ<21>")
	)
	(segment
		(start 385.990084 -226.831144)
		(end 385.990084 -226.84105)
		(width 0.088646)
		(layer "In4.Cu")
		(net "M_G_CPU0_SB_DQ<21>")
	)
	(segment
		(start 381.948182 -230.57612)
		(end 381.944626 -230.578152)
		(width 0.088646)
		(layer "In4.Cu")
		(net "M_G_CPU0_SB_DQ<21>")
	)
	(segment
		(start 430.088294 -206.354426)
		(end 429.42891 -206.354426)
		(width 0.18288)
		(layer "In4.Cu")
		(net "M_G_CPU0_SB_DQ<21>")
	)
	(segment
		(start 411.493208 -208.98993)
		(end 411.165548 -208.98993)
		(width 0.18288)
		(layer "In4.Cu")
		(net "M_G_CPU0_SB_DQ<21>")
	)
	(segment
		(start 402.618448 -212.49894)
		(end 390.029192 -225.088196)
		(width 0.18288)
		(layer "In4.Cu")
		(net "M_G_CPU0_SB_DQ<21>")
	)
	(segment
		(start 387.886194 -225.088196)
		(end 387.33222 -225.64217)
		(width 0.088646)
		(layer "In4.Cu")
		(net "M_G_CPU0_SB_DQ<21>")
	)
	(segment
		(start 405.725884 -208.888584)
		(end 405.72563 -208.88833)
		(width 0.18288)
		(layer "In4.Cu")
		(net "M_G_CPU0_SB_DQ<21>")
	)
	(segment
		(start 409.778708 -208.98993)
		(end 409.595828 -208.80705)
		(width 0.18288)
		(layer "In4.Cu")
		(net "M_G_CPU0_SB_DQ<21>")
	)
	(segment
		(start 409.595828 -208.21904)
		(end 409.412948 -208.03616)
		(width 0.18288)
		(layer "In4.Cu")
		(net "M_G_CPU0_SB_DQ<21>")
	)
	(segment
		(start 419.278562 -207.093566)
		(end 418.325046 -208.047082)
		(width 0.18288)
		(layer "In4.Cu")
		(net "M_G_CPU0_SB_DQ<21>")
	)
	(segment
		(start 411.858968 -208.03616)
		(end 411.676088 -208.21904)
		(width 0.18288)
		(layer "In4.Cu")
		(net "M_G_CPU0_SB_DQ<21>")
	)
	(segment
		(start 410.982668 -208.21904)
		(end 410.799788 -208.03616)
		(width 0.18288)
		(layer "In4.Cu")
		(net "M_G_CPU0_SB_DQ<21>")
	)
	(segment
		(start 412.335218 -208.03616)
		(end 411.858968 -208.03616)
		(width 0.18288)
		(layer "In4.Cu")
		(net "M_G_CPU0_SB_DQ<21>")
	)
	(segment
		(start 386.177536 -226.506786)
		(end 386.168646 -226.511866)
		(width 0.088646)
		(layer "In4.Cu")
		(net "M_G_CPU0_SB_DQ<21>")
	)
	(segment
		(start 404.842472 -208.88833)
		(end 403.599142 -210.13166)
		(width 0.18288)
		(layer "In4.Cu")
		(net "M_G_CPU0_SB_DQ<21>")
	)
	(arc
		(start 386.638546 -225.69805)
		(mid 386.507632 -225.83441)
		(end 386.459984 -226.017328)
		(width 0.088646)
		(layer "In4.Cu")
		(net "M_G_CPU0_SB_DQ<21>")
	)
	(arc
		(start 384.580384 -229.282752)
		(mid 384.502273 -229.559701)
		(end 384.297936 -229.762304)
		(width 0.088646)
		(layer "In4.Cu")
		(net "M_G_CPU0_SB_DQ<21>")
	)
	(arc
		(start 386.834634 -225.64217)
		(mid 386.732711 -225.656506)
		(end 386.638546 -225.69805)
		(width 0.088646)
		(layer "In4.Cu")
		(net "M_G_CPU0_SB_DQ<21>")
	)
	(arc
		(start 384.289046 -229.767384)
		(mid 384.158132 -229.903744)
		(end 384.110484 -230.086662)
		(width 0.088646)
		(layer "In4.Cu")
		(net "M_G_CPU0_SB_DQ<21>")
	)
	(arc
		(start 386.168646 -226.511866)
		(mid 386.037732 -226.648226)
		(end 385.990084 -226.831144)
		(width 0.088646)
		(layer "In4.Cu")
		(net "M_G_CPU0_SB_DQ<21>")
	)
	(arc
		(start 384.767582 -228.948488)
		(mid 384.632649 -229.081842)
		(end 384.580384 -229.26421)
		(width 0.088646)
		(layer "In4.Cu")
		(net "M_G_CPU0_SB_DQ<21>")
	)
	(arc
		(start 384.110484 -230.096568)
		(mid 384.032373 -230.373517)
		(end 383.828036 -230.57612)
		(width 0.088646)
		(layer "In4.Cu")
		(net "M_G_CPU0_SB_DQ<21>")
	)
	(arc
		(start 386.459984 -226.027234)
		(mid 386.381873 -226.304183)
		(end 386.177536 -226.506786)
		(width 0.088646)
		(layer "In4.Cu")
		(net "M_G_CPU0_SB_DQ<21>")
	)
	(arc
		(start 381.383032 -230.57612)
		(mid 381.199078 -230.525991)
		(end 381.014224 -230.572818)
		(width 0.088646)
		(layer "In4.Cu")
		(net "M_G_CPU0_SB_DQ<21>")
	)
	(arc
		(start 382.322832 -230.57612)
		(mid 382.135524 -230.525977)
		(end 381.948182 -230.57612)
		(width 0.088646)
		(layer "In4.Cu")
		(net "M_G_CPU0_SB_DQ<21>")
	)
	(arc
		(start 381.944626 -230.578152)
		(mid 381.663542 -230.651889)
		(end 381.383032 -230.57612)
		(width 0.088646)
		(layer "In4.Cu")
		(net "M_G_CPU0_SB_DQ<21>")
	)
	(arc
		(start 385.050284 -228.45903)
		(mid 384.976293 -228.738596)
		(end 384.773678 -228.944932)
		(width 0.088646)
		(layer "In4.Cu")
		(net "M_G_CPU0_SB_DQ<21>")
	)
	(arc
		(start 383.262632 -230.57612)
		(mid 383.078678 -230.525991)
		(end 382.893824 -230.572818)
		(width 0.088646)
		(layer "In4.Cu")
		(net "M_G_CPU0_SB_DQ<21>")
	)
	(arc
		(start 380.443232 -230.57612)
		(mid 380.068535 -230.576001)
		(end 379.88113 -230.900478)
		(width 0.088646)
		(layer "In4.Cu")
		(net "M_G_CPU0_SB_DQ<21>")
	)
	(arc
		(start 385.520184 -227.64496)
		(mid 385.448959 -227.91961)
		(end 385.25323 -228.12502)
		(width 0.088646)
		(layer "In4.Cu")
		(net "M_G_CPU0_SB_DQ<21>")
	)
	(arc
		(start 385.237228 -228.134418)
		(mid 385.102295 -228.267772)
		(end 385.05003 -228.45014)
		(width 0.088646)
		(layer "In4.Cu")
		(net "M_G_CPU0_SB_DQ<21>")
	)
	(arc
		(start 382.88341 -230.57866)
		(mid 382.602775 -230.651828)
		(end 382.322832 -230.57612)
		(width 0.088646)
		(layer "In4.Cu")
		(net "M_G_CPU0_SB_DQ<21>")
	)
	(arc
		(start 385.990084 -226.84105)
		(mid 385.911973 -227.117999)
		(end 385.707636 -227.320602)
		(width 0.088646)
		(layer "In4.Cu")
		(net "M_G_CPU0_SB_DQ<21>")
	)
	(arc
		(start 381.00254 -230.579422)
		(mid 380.722435 -230.651864)
		(end 380.443232 -230.57612)
		(width 0.088646)
		(layer "In4.Cu")
		(net "M_G_CPU0_SB_DQ<21>")
	)
	(arc
		(start 383.824226 -230.578152)
		(mid 383.543142 -230.651889)
		(end 383.262632 -230.57612)
		(width 0.088646)
		(layer "In4.Cu")
		(net "M_G_CPU0_SB_DQ<21>")
	)
	(arc
		(start 379.88113 -230.900478)
		(mid 379.639804 -231.322959)
		(end 379.15342 -231.329484)
		(width 0.088646)
		(layer "In4.Cu")
		(net "M_G_CPU0_SB_DQ<21>")
	)
	(arc
		(start 385.698746 -227.325682)
		(mid 385.567832 -227.462042)
		(end 385.520184 -227.64496)
		(width 0.088646)
		(layer "In4.Cu")
		(net "M_G_CPU0_SB_DQ<21>")
	)
	(segment
		(start 442.880496 -207.516984)
		(end 442.44895 -207.085438)
		(width 0.20066)
		(layer "F.Cu")
		(net "M_G_CPU0_SB_DQ<20>")
	)
	(segment
		(start 436.928514 -207.51673)
		(end 435.823614 -207.51673)
		(width 0.20066)
		(layer "F.Cu")
		(net "M_G_CPU0_SB_DQ<20>")
	)
	(segment
		(start 439.87085 -207.091788)
		(end 439.82386 -207.091788)
		(width 0.101854)
		(layer "F.Cu")
		(net "M_G_CPU0_SB_DQ<20>")
	)
	(segment
		(start 377.90628 -232.250234)
		(end 377.90628 -231.714548)
		(width 0.20066)
		(layer "F.Cu")
		(net "M_G_CPU0_SB_DQ<20>")
	)
	(segment
		(start 439.173112 -207.765396)
		(end 438.697878 -207.765396)
		(width 0.20066)
		(layer "F.Cu")
		(net "M_G_CPU0_SB_DQ<20>")
	)
	(segment
		(start 439.82386 -207.091788)
		(end 439.479182 -207.091788)
		(width 0.20066)
		(layer "F.Cu")
		(net "M_G_CPU0_SB_DQ<20>")
	)
	(segment
		(start 377.906534 -232.250488)
		(end 377.90628 -232.250234)
		(width 0.20066)
		(layer "F.Cu")
		(net "M_G_CPU0_SB_DQ<20>")
	)
	(segment
		(start 439.361072 -207.577436)
		(end 439.173112 -207.765396)
		(width 0.20066)
		(layer "F.Cu")
		(net "M_G_CPU0_SB_DQ<20>")
	)
	(segment
		(start 438.697878 -207.765396)
		(end 438.449212 -207.51673)
		(width 0.20066)
		(layer "F.Cu")
		(net "M_G_CPU0_SB_DQ<20>")
	)
	(segment
		(start 444.472314 -207.51673)
		(end 444.47206 -207.516984)
		(width 0.20066)
		(layer "F.Cu")
		(net "M_G_CPU0_SB_DQ<20>")
	)
	(segment
		(start 444.47206 -207.516984)
		(end 442.880496 -207.516984)
		(width 0.20066)
		(layer "F.Cu")
		(net "M_G_CPU0_SB_DQ<20>")
	)
	(segment
		(start 442.038994 -207.085438)
		(end 442.032644 -207.091788)
		(width 0.1016)
		(layer "F.Cu")
		(net "M_G_CPU0_SB_DQ<20>")
	)
	(segment
		(start 442.44895 -207.085438)
		(end 442.038994 -207.085438)
		(width 0.20066)
		(layer "F.Cu")
		(net "M_G_CPU0_SB_DQ<20>")
	)
	(segment
		(start 439.361072 -207.209898)
		(end 439.361072 -207.577436)
		(width 0.20066)
		(layer "F.Cu")
		(net "M_G_CPU0_SB_DQ<20>")
	)
	(segment
		(start 439.479182 -207.091788)
		(end 439.361072 -207.209898)
		(width 0.20066)
		(layer "F.Cu")
		(net "M_G_CPU0_SB_DQ<20>")
	)
	(segment
		(start 438.449212 -207.51673)
		(end 436.928514 -207.51673)
		(width 0.20066)
		(layer "F.Cu")
		(net "M_G_CPU0_SB_DQ<20>")
	)
	(segment
		(start 442.032644 -207.091788)
		(end 439.87085 -207.091788)
		(width 0.1016)
		(layer "F.Cu")
		(net "M_G_CPU0_SB_DQ<20>")
	)
	(segment
		(start 408.52725 -210.443826)
		(end 407.307288 -210.443826)
		(width 0.18288)
		(layer "In4.Cu")
		(net "M_G_CPU0_SB_DQ<20>")
	)
	(segment
		(start 431.993294 -206.913226)
		(end 431.383694 -207.522826)
		(width 0.18288)
		(layer "In4.Cu")
		(net "M_G_CPU0_SB_DQ<20>")
	)
	(segment
		(start 413.197294 -209.554826)
		(end 412.249874 -210.502246)
		(width 0.18288)
		(layer "In4.Cu")
		(net "M_G_CPU0_SB_DQ<20>")
	)
	(segment
		(start 388.075424 -226.593146)
		(end 387.056884 -226.593146)
		(width 0.088646)
		(layer "In4.Cu")
		(net "M_G_CPU0_SB_DQ<20>")
	)
	(segment
		(start 385.237736 -229.762304)
		(end 385.228846 -229.767384)
		(width 0.088646)
		(layer "In4.Cu")
		(net "M_G_CPU0_SB_DQ<20>")
	)
	(segment
		(start 413.77743 -210.468972)
		(end 413.77743 -209.737706)
		(width 0.18288)
		(layer "In4.Cu")
		(net "M_G_CPU0_SB_DQ<20>")
	)
	(segment
		(start 383.732532 -231.39019)
		(end 383.732532 -231.389936)
		(width 0.088646)
		(layer "In4.Cu")
		(net "M_G_CPU0_SB_DQ<20>")
	)
	(segment
		(start 435.823614 -207.51673)
		(end 435.218586 -206.913226)
		(width 0.18288)
		(layer "In4.Cu")
		(net "M_G_CPU0_SB_DQ<20>")
	)
	(segment
		(start 380.538482 -231.389936)
		(end 380.449328 -231.441498)
		(width 0.088646)
		(layer "In4.Cu")
		(net "M_G_CPU0_SB_DQ<20>")
	)
	(segment
		(start 379.033532 -232.038906)
		(end 379.02769 -232.042208)
		(width 0.088646)
		(layer "In4.Cu")
		(net "M_G_CPU0_SB_DQ<20>")
	)
	(segment
		(start 386.92963 -226.7204)
		(end 386.92963 -226.83089)
		(width 0.088646)
		(layer "In4.Cu")
		(net "M_G_CPU0_SB_DQ<20>")
	)
	(segment
		(start 427.903894 -209.580226)
		(end 427.726094 -209.402426)
		(width 0.18288)
		(layer "In4.Cu")
		(net "M_G_CPU0_SB_DQ<20>")
	)
	(segment
		(start 435.218586 -206.913226)
		(end 431.993294 -206.913226)
		(width 0.18288)
		(layer "In4.Cu")
		(net "M_G_CPU0_SB_DQ<20>")
	)
	(segment
		(start 396.563596 -219.961968)
		(end 390.399524 -226.12604)
		(width 0.18288)
		(layer "In4.Cu")
		(net "M_G_CPU0_SB_DQ<20>")
	)
	(segment
		(start 413.77743 -209.737706)
		(end 413.59455 -209.554826)
		(width 0.18288)
		(layer "In4.Cu")
		(net "M_G_CPU0_SB_DQ<20>")
	)
	(segment
		(start 390.399524 -226.12604)
		(end 388.71271 -226.12604)
		(width 0.18288)
		(layer "In4.Cu")
		(net "M_G_CPU0_SB_DQ<20>")
	)
	(segment
		(start 430.139094 -209.580226)
		(end 427.903894 -209.580226)
		(width 0.18288)
		(layer "In4.Cu")
		(net "M_G_CPU0_SB_DQ<20>")
	)
	(segment
		(start 406.362408 -210.443826)
		(end 405.39289 -210.443826)
		(width 0.18288)
		(layer "In4.Cu")
		(net "M_G_CPU0_SB_DQ<20>")
	)
	(segment
		(start 405.39289 -210.443826)
		(end 404.629366 -211.20735)
		(width 0.18288)
		(layer "In4.Cu")
		(net "M_G_CPU0_SB_DQ<20>")
	)
	(segment
		(start 384.767836 -230.57612)
		(end 384.758946 -230.5812)
		(width 0.088646)
		(layer "In4.Cu")
		(net "M_G_CPU0_SB_DQ<20>")
	)
	(segment
		(start 382.792732 -231.389936)
		(end 382.788922 -231.387904)
		(width 0.088646)
		(layer "In4.Cu")
		(net "M_G_CPU0_SB_DQ<20>")
	)
	(segment
		(start 380.050294 -231.994456)
		(end 379.96749 -232.042208)
		(width 0.088646)
		(layer "In4.Cu")
		(net "M_G_CPU0_SB_DQ<20>")
	)
	(segment
		(start 406.639268 -210.720686)
		(end 406.362408 -210.443826)
		(width 0.18288)
		(layer "In4.Cu")
		(net "M_G_CPU0_SB_DQ<20>")
	)
	(segment
		(start 412.249874 -210.502246)
		(end 408.58567 -210.502246)
		(width 0.18288)
		(layer "In4.Cu")
		(net "M_G_CPU0_SB_DQ<20>")
	)
	(segment
		(start 422.646856 -208.793588)
		(end 420.003732 -208.793588)
		(width 0.18288)
		(layer "In4.Cu")
		(net "M_G_CPU0_SB_DQ<20>")
	)
	(segment
		(start 424.346878 -210.49361)
		(end 422.646856 -208.793588)
		(width 0.18288)
		(layer "In4.Cu")
		(net "M_G_CPU0_SB_DQ<20>")
	)
	(segment
		(start 414.47085 -209.737706)
		(end 414.47085 -210.468972)
		(width 0.18288)
		(layer "In4.Cu")
		(net "M_G_CPU0_SB_DQ<20>")
	)
	(segment
		(start 380.913132 -231.389936)
		(end 380.90856 -231.387396)
		(width 0.088646)
		(layer "In4.Cu")
		(net "M_G_CPU0_SB_DQ<20>")
	)
	(segment
		(start 404.629366 -211.20735)
		(end 404.14194 -212.383878)
		(width 0.18288)
		(layer "In4.Cu")
		(net "M_G_CPU0_SB_DQ<20>")
	)
	(segment
		(start 385.050284 -230.086662)
		(end 385.050284 -230.096568)
		(width 0.088646)
		(layer "In4.Cu")
		(net "M_G_CPU0_SB_DQ<20>")
	)
	(segment
		(start 426.734478 -209.402426)
		(end 425.643294 -210.49361)
		(width 0.18288)
		(layer "In4.Cu")
		(net "M_G_CPU0_SB_DQ<20>")
	)
	(segment
		(start 386.177536 -228.134672)
		(end 386.168646 -228.139752)
		(width 0.088646)
		(layer "In4.Cu")
		(net "M_G_CPU0_SB_DQ<20>")
	)
	(segment
		(start 388.71271 -226.12604)
		(end 388.54253 -226.12604)
		(width 0.088646)
		(layer "In4.Cu")
		(net "M_G_CPU0_SB_DQ<20>")
	)
	(segment
		(start 407.307288 -210.443826)
		(end 407.030428 -210.720686)
		(width 0.18288)
		(layer "In4.Cu")
		(net "M_G_CPU0_SB_DQ<20>")
	)
	(segment
		(start 414.28797 -210.651852)
		(end 413.96031 -210.651852)
		(width 0.18288)
		(layer "In4.Cu")
		(net "M_G_CPU0_SB_DQ<20>")
	)
	(segment
		(start 381.852932 -231.389936)
		(end 381.850392 -231.388412)
		(width 0.088646)
		(layer "In4.Cu")
		(net "M_G_CPU0_SB_DQ<20>")
	)
	(segment
		(start 388.54253 -226.12604)
		(end 388.075424 -226.593146)
		(width 0.088646)
		(layer "In4.Cu")
		(net "M_G_CPU0_SB_DQ<20>")
	)
	(segment
		(start 378.600716 -232.01376)
		(end 377.90628 -231.714548)
		(width 0.088646)
		(layer "In4.Cu")
		(net "M_G_CPU0_SB_DQ<20>")
	)
	(segment
		(start 385.707636 -228.948488)
		(end 385.698746 -228.953568)
		(width 0.088646)
		(layer "In4.Cu")
		(net "M_G_CPU0_SB_DQ<20>")
	)
	(segment
		(start 419.242494 -209.554826)
		(end 414.65373 -209.554826)
		(width 0.18288)
		(layer "In4.Cu")
		(net "M_G_CPU0_SB_DQ<20>")
	)
	(segment
		(start 404.14194 -212.383878)
		(end 396.563596 -219.962222)
		(width 0.18288)
		(layer "In4.Cu")
		(net "M_G_CPU0_SB_DQ<20>")
	)
	(segment
		(start 414.47085 -210.468972)
		(end 414.28797 -210.651852)
		(width 0.18288)
		(layer "In4.Cu")
		(net "M_G_CPU0_SB_DQ<20>")
	)
	(segment
		(start 385.243832 -229.758748)
		(end 385.237736 -229.762304)
		(width 0.088646)
		(layer "In4.Cu")
		(net "M_G_CPU0_SB_DQ<20>")
	)
	(segment
		(start 380.261368 -231.819196)
		(end 380.203964 -231.8766)
		(width 0.088646)
		(layer "In4.Cu")
		(net "M_G_CPU0_SB_DQ<20>")
	)
	(segment
		(start 386.92963 -226.83089)
		(end 386.929884 -226.846384)
		(width 0.088646)
		(layer "In4.Cu")
		(net "M_G_CPU0_SB_DQ<20>")
	)
	(segment
		(start 384.580384 -230.900478)
		(end 384.580384 -230.91902)
		(width 0.088646)
		(layer "In4.Cu")
		(net "M_G_CPU0_SB_DQ<20>")
	)
	(segment
		(start 387.056884 -226.593146)
		(end 386.92963 -226.7204)
		(width 0.088646)
		(layer "In4.Cu")
		(net "M_G_CPU0_SB_DQ<20>")
	)
	(segment
		(start 380.920498 -231.394254)
		(end 380.913132 -231.389936)
		(width 0.088646)
		(layer "In4.Cu")
		(net "M_G_CPU0_SB_DQ<20>")
	)
	(segment
		(start 383.732532 -231.389936)
		(end 383.729992 -231.388412)
		(width 0.088646)
		(layer "In4.Cu")
		(net "M_G_CPU0_SB_DQ<20>")
	)
	(segment
		(start 407.030428 -210.720686)
		(end 406.639268 -210.720686)
		(width 0.18288)
		(layer "In4.Cu")
		(net "M_G_CPU0_SB_DQ<20>")
	)
	(segment
		(start 413.59455 -209.554826)
		(end 413.197294 -209.554826)
		(width 0.18288)
		(layer "In4.Cu")
		(net "M_G_CPU0_SB_DQ<20>")
	)
	(segment
		(start 396.563596 -219.962222)
		(end 396.563596 -219.961968)
		(width 0.18288)
		(layer "In4.Cu")
		(net "M_G_CPU0_SB_DQ<20>")
	)
	(segment
		(start 386.459984 -227.636324)
		(end 386.459984 -227.663502)
		(width 0.088646)
		(layer "In4.Cu")
		(net "M_G_CPU0_SB_DQ<20>")
	)
	(segment
		(start 431.383694 -208.335626)
		(end 430.139094 -209.580226)
		(width 0.18288)
		(layer "In4.Cu")
		(net "M_G_CPU0_SB_DQ<20>")
	)
	(segment
		(start 431.383694 -207.522826)
		(end 431.383694 -208.335626)
		(width 0.18288)
		(layer "In4.Cu")
		(net "M_G_CPU0_SB_DQ<20>")
	)
	(segment
		(start 414.65373 -209.554826)
		(end 414.47085 -209.737706)
		(width 0.18288)
		(layer "In4.Cu")
		(net "M_G_CPU0_SB_DQ<20>")
	)
	(segment
		(start 427.726094 -209.402426)
		(end 426.734478 -209.402426)
		(width 0.18288)
		(layer "In4.Cu")
		(net "M_G_CPU0_SB_DQ<20>")
	)
	(segment
		(start 420.003732 -208.793588)
		(end 419.242494 -209.554826)
		(width 0.18288)
		(layer "In4.Cu")
		(net "M_G_CPU0_SB_DQ<20>")
	)
	(segment
		(start 385.990084 -228.45903)
		(end 385.990084 -228.468936)
		(width 0.088646)
		(layer "In4.Cu")
		(net "M_G_CPU0_SB_DQ<20>")
	)
	(segment
		(start 379.039374 -232.03535)
		(end 379.033532 -232.038906)
		(width 0.088646)
		(layer "In4.Cu")
		(net "M_G_CPU0_SB_DQ<20>")
	)
	(segment
		(start 408.58567 -210.502246)
		(end 408.52725 -210.443826)
		(width 0.18288)
		(layer "In4.Cu")
		(net "M_G_CPU0_SB_DQ<20>")
	)
	(segment
		(start 425.643294 -210.49361)
		(end 424.346878 -210.49361)
		(width 0.18288)
		(layer "In4.Cu")
		(net "M_G_CPU0_SB_DQ<20>")
	)
	(segment
		(start 382.800098 -231.394254)
		(end 382.792732 -231.389936)
		(width 0.088646)
		(layer "In4.Cu")
		(net "M_G_CPU0_SB_DQ<20>")
	)
	(segment
		(start 413.96031 -210.651852)
		(end 413.77743 -210.468972)
		(width 0.18288)
		(layer "In4.Cu")
		(net "M_G_CPU0_SB_DQ<20>")
	)
	(arc
		(start 385.520184 -229.272846)
		(mid 385.446268 -229.552348)
		(end 385.243832 -229.758748)
		(width 0.088646)
		(layer "In4.Cu")
		(net "M_G_CPU0_SB_DQ<20>")
	)
	(arc
		(start 384.580384 -230.91902)
		(mid 384.500222 -231.191209)
		(end 384.297936 -231.39019)
		(width 0.088646)
		(layer "In4.Cu")
		(net "M_G_CPU0_SB_DQ<20>")
	)
	(arc
		(start 384.297936 -231.39019)
		(mid 384.015234 -231.465932)
		(end 383.732532 -231.39019)
		(width 0.088646)
		(layer "In4.Cu")
		(net "M_G_CPU0_SB_DQ<20>")
	)
	(arc
		(start 380.203964 -231.8766)
		(mid 380.130999 -231.940575)
		(end 380.050294 -231.994456)
		(width 0.088646)
		(layer "In4.Cu")
		(net "M_G_CPU0_SB_DQ<20>")
	)
	(arc
		(start 385.228846 -229.767384)
		(mid 385.097932 -229.903744)
		(end 385.050284 -230.086662)
		(width 0.088646)
		(layer "In4.Cu")
		(net "M_G_CPU0_SB_DQ<20>")
	)
	(arc
		(start 381.850392 -231.388412)
		(mid 381.664143 -231.339767)
		(end 381.478282 -231.389936)
		(width 0.088646)
		(layer "In4.Cu")
		(net "M_G_CPU0_SB_DQ<20>")
	)
	(arc
		(start 380.90856 -231.387396)
		(mid 380.723175 -231.339758)
		(end 380.538482 -231.389936)
		(width 0.088646)
		(layer "In4.Cu")
		(net "M_G_CPU0_SB_DQ<20>")
	)
	(arc
		(start 386.459984 -227.663502)
		(mid 386.379822 -227.935691)
		(end 386.177536 -228.134672)
		(width 0.088646)
		(layer "In4.Cu")
		(net "M_G_CPU0_SB_DQ<20>")
	)
	(arc
		(start 380.337568 -231.635046)
		(mid 380.317765 -231.734692)
		(end 380.261368 -231.819196)
		(width 0.088646)
		(layer "In4.Cu")
		(net "M_G_CPU0_SB_DQ<20>")
	)
	(arc
		(start 385.990084 -228.468936)
		(mid 385.911973 -228.745885)
		(end 385.707636 -228.948488)
		(width 0.088646)
		(layer "In4.Cu")
		(net "M_G_CPU0_SB_DQ<20>")
	)
	(arc
		(start 378.681488 -232.051098)
		(mid 378.641326 -232.031944)
		(end 378.600716 -232.01376)
		(width 0.088646)
		(layer "In4.Cu")
		(net "M_G_CPU0_SB_DQ<20>")
	)
	(arc
		(start 386.647182 -227.320602)
		(mid 386.512249 -227.453956)
		(end 386.459984 -227.636324)
		(width 0.088646)
		(layer "In4.Cu")
		(net "M_G_CPU0_SB_DQ<20>")
	)
	(arc
		(start 383.357882 -231.389936)
		(mid 383.079559 -231.465695)
		(end 382.800098 -231.394254)
		(width 0.088646)
		(layer "In4.Cu")
		(net "M_G_CPU0_SB_DQ<20>")
	)
	(arc
		(start 384.758946 -230.5812)
		(mid 384.628032 -230.71756)
		(end 384.580384 -230.900478)
		(width 0.088646)
		(layer "In4.Cu")
		(net "M_G_CPU0_SB_DQ<20>")
	)
	(arc
		(start 381.478282 -231.389936)
		(mid 381.199959 -231.465695)
		(end 380.920498 -231.394254)
		(width 0.088646)
		(layer "In4.Cu")
		(net "M_G_CPU0_SB_DQ<20>")
	)
	(arc
		(start 386.929884 -226.846384)
		(mid 386.850346 -227.120329)
		(end 386.647182 -227.320602)
		(width 0.088646)
		(layer "In4.Cu")
		(net "M_G_CPU0_SB_DQ<20>")
	)
	(arc
		(start 386.168646 -228.139752)
		(mid 386.037732 -228.276112)
		(end 385.990084 -228.45903)
		(width 0.088646)
		(layer "In4.Cu")
		(net "M_G_CPU0_SB_DQ<20>")
	)
	(arc
		(start 385.698746 -228.953568)
		(mid 385.567832 -229.089928)
		(end 385.520184 -229.272846)
		(width 0.088646)
		(layer "In4.Cu")
		(net "M_G_CPU0_SB_DQ<20>")
	)
	(arc
		(start 379.598682 -232.038906)
		(mid 379.319508 -231.963141)
		(end 379.039374 -232.03535)
		(width 0.088646)
		(layer "In4.Cu")
		(net "M_G_CPU0_SB_DQ<20>")
	)
	(arc
		(start 379.96749 -232.042208)
		(mid 379.782635 -232.089158)
		(end 379.598682 -232.038906)
		(width 0.088646)
		(layer "In4.Cu")
		(net "M_G_CPU0_SB_DQ<20>")
	)
	(arc
		(start 385.050284 -230.096568)
		(mid 384.972173 -230.373517)
		(end 384.767836 -230.57612)
		(width 0.088646)
		(layer "In4.Cu")
		(net "M_G_CPU0_SB_DQ<20>")
	)
	(arc
		(start 383.729992 -231.388412)
		(mid 383.543743 -231.339767)
		(end 383.357882 -231.389936)
		(width 0.088646)
		(layer "In4.Cu")
		(net "M_G_CPU0_SB_DQ<20>")
	)
	(arc
		(start 380.449328 -231.441498)
		(mid 380.36753 -231.523303)
		(end 380.337568 -231.635046)
		(width 0.088646)
		(layer "In4.Cu")
		(net "M_G_CPU0_SB_DQ<20>")
	)
	(arc
		(start 379.02769 -232.042208)
		(mid 378.85568 -232.089049)
		(end 378.681488 -232.051098)
		(width 0.088646)
		(layer "In4.Cu")
		(net "M_G_CPU0_SB_DQ<20>")
	)
	(arc
		(start 382.788922 -231.387904)
		(mid 382.603232 -231.339826)
		(end 382.418082 -231.389936)
		(width 0.088646)
		(layer "In4.Cu")
		(net "M_G_CPU0_SB_DQ<20>")
	)
	(arc
		(start 382.418082 -231.389936)
		(mid 382.135524 -231.465585)
		(end 381.852932 -231.389936)
		(width 0.088646)
		(layer "In4.Cu")
		(net "M_G_CPU0_SB_DQ<20>")
	)
	(segment
		(start 439.82386 -230.041704)
		(end 439.479182 -230.041704)
		(width 0.20066)
		(layer "F.Cu")
		(net "M_G_CPU0_SB_DQ<1>")
	)
	(segment
		(start 436.928514 -230.466646)
		(end 435.823614 -230.466646)
		(width 0.20066)
		(layer "F.Cu")
		(net "M_G_CPU0_SB_DQ<1>")
	)
	(segment
		(start 439.173112 -230.715312)
		(end 438.697878 -230.715312)
		(width 0.20066)
		(layer "F.Cu")
		(net "M_G_CPU0_SB_DQ<1>")
	)
	(segment
		(start 374.61698 -241.203226)
		(end 374.617234 -241.202972)
		(width 0.20066)
		(layer "F.Cu")
		(net "M_G_CPU0_SB_DQ<1>")
	)
	(segment
		(start 374.617234 -241.202972)
		(end 374.617234 -240.667286)
		(width 0.20066)
		(layer "F.Cu")
		(net "M_G_CPU0_SB_DQ<1>")
	)
	(segment
		(start 444.47206 -230.4669)
		(end 442.880496 -230.4669)
		(width 0.20066)
		(layer "F.Cu")
		(net "M_G_CPU0_SB_DQ<1>")
	)
	(segment
		(start 442.038994 -230.035354)
		(end 442.032644 -230.041704)
		(width 0.1016)
		(layer "F.Cu")
		(net "M_G_CPU0_SB_DQ<1>")
	)
	(segment
		(start 438.697878 -230.715312)
		(end 438.449212 -230.466646)
		(width 0.20066)
		(layer "F.Cu")
		(net "M_G_CPU0_SB_DQ<1>")
	)
	(segment
		(start 438.449212 -230.466646)
		(end 436.928514 -230.466646)
		(width 0.20066)
		(layer "F.Cu")
		(net "M_G_CPU0_SB_DQ<1>")
	)
	(segment
		(start 442.880496 -230.4669)
		(end 442.44895 -230.035354)
		(width 0.20066)
		(layer "F.Cu")
		(net "M_G_CPU0_SB_DQ<1>")
	)
	(segment
		(start 439.479182 -230.041704)
		(end 439.361072 -230.159814)
		(width 0.20066)
		(layer "F.Cu")
		(net "M_G_CPU0_SB_DQ<1>")
	)
	(segment
		(start 439.361072 -230.159814)
		(end 439.361072 -230.527352)
		(width 0.20066)
		(layer "F.Cu")
		(net "M_G_CPU0_SB_DQ<1>")
	)
	(segment
		(start 444.472314 -230.466646)
		(end 444.47206 -230.4669)
		(width 0.20066)
		(layer "F.Cu")
		(net "M_G_CPU0_SB_DQ<1>")
	)
	(segment
		(start 442.032644 -230.041704)
		(end 439.843926 -230.041704)
		(width 0.1016)
		(layer "F.Cu")
		(net "M_G_CPU0_SB_DQ<1>")
	)
	(segment
		(start 439.843926 -230.041704)
		(end 439.82386 -230.041704)
		(width 0.101854)
		(layer "F.Cu")
		(net "M_G_CPU0_SB_DQ<1>")
	)
	(segment
		(start 439.361072 -230.527352)
		(end 439.173112 -230.715312)
		(width 0.20066)
		(layer "F.Cu")
		(net "M_G_CPU0_SB_DQ<1>")
	)
	(segment
		(start 442.44895 -230.035354)
		(end 442.038994 -230.035354)
		(width 0.20066)
		(layer "F.Cu")
		(net "M_G_CPU0_SB_DQ<1>")
	)
	(segment
		(start 403.618192 -235.703872)
		(end 403.458172 -235.863892)
		(width 0.18288)
		(layer "In6.Cu")
		(net "M_G_CPU0_SB_DQ<1>")
	)
	(segment
		(start 427.919134 -235.818426)
		(end 427.257972 -236.479588)
		(width 0.18288)
		(layer "In6.Cu")
		(net "M_G_CPU0_SB_DQ<1>")
	)
	(segment
		(start 401.448778 -235.703872)
		(end 396.09268 -241.05997)
		(width 0.18288)
		(layer "In6.Cu")
		(net "M_G_CPU0_SB_DQ<1>")
	)
	(segment
		(start 430.824386 -234.42295)
		(end 431.088038 -234.686602)
		(width 0.18288)
		(layer "In6.Cu")
		(net "M_G_CPU0_SB_DQ<1>")
	)
	(segment
		(start 403.298152 -236.389672)
		(end 402.924772 -236.389672)
		(width 0.18288)
		(layer "In6.Cu")
		(net "M_G_CPU0_SB_DQ<1>")
	)
	(segment
		(start 403.458172 -235.863892)
		(end 403.458172 -236.229652)
		(width 0.18288)
		(layer "In6.Cu")
		(net "M_G_CPU0_SB_DQ<1>")
	)
	(segment
		(start 402.924772 -236.389672)
		(end 402.764752 -236.229652)
		(width 0.18288)
		(layer "In6.Cu")
		(net "M_G_CPU0_SB_DQ<1>")
	)
	(segment
		(start 417.521898 -236.936026)
		(end 417.15436 -236.568488)
		(width 0.18288)
		(layer "In6.Cu")
		(net "M_G_CPU0_SB_DQ<1>")
	)
	(segment
		(start 414.101534 -236.936026)
		(end 413.077914 -235.912406)
		(width 0.18288)
		(layer "In6.Cu")
		(net "M_G_CPU0_SB_DQ<1>")
	)
	(segment
		(start 379.598682 -241.156744)
		(end 379.58395 -241.16538)
		(width 0.088646)
		(layer "In6.Cu")
		(net "M_G_CPU0_SB_DQ<1>")
	)
	(segment
		(start 432.779932 -231.654604)
		(end 432.779932 -231.913176)
		(width 0.18288)
		(layer "In6.Cu")
		(net "M_G_CPU0_SB_DQ<1>")
	)
	(segment
		(start 404.311612 -236.389672)
		(end 404.151592 -236.229652)
		(width 0.18288)
		(layer "In6.Cu")
		(net "M_G_CPU0_SB_DQ<1>")
	)
	(segment
		(start 418.024818 -236.936026)
		(end 417.521898 -236.936026)
		(width 0.18288)
		(layer "In6.Cu")
		(net "M_G_CPU0_SB_DQ<1>")
	)
	(segment
		(start 435.348634 -230.941626)
		(end 434.480462 -230.941626)
		(width 0.18288)
		(layer "In6.Cu")
		(net "M_G_CPU0_SB_DQ<1>")
	)
	(segment
		(start 377.719082 -241.156744)
		(end 377.708668 -241.16284)
		(width 0.088646)
		(layer "In6.Cu")
		(net "M_G_CPU0_SB_DQ<1>")
	)
	(segment
		(start 387.602984 -241.60988)
		(end 387.251448 -241.60988)
		(width 0.088646)
		(layer "In6.Cu")
		(net "M_G_CPU0_SB_DQ<1>")
	)
	(segment
		(start 402.764752 -236.229652)
		(end 402.764752 -235.863892)
		(width 0.18288)
		(layer "In6.Cu")
		(net "M_G_CPU0_SB_DQ<1>")
	)
	(segment
		(start 422.690798 -235.63961)
		(end 421.488362 -236.842046)
		(width 0.18288)
		(layer "In6.Cu")
		(net "M_G_CPU0_SB_DQ<1>")
	)
	(segment
		(start 418.392356 -236.568488)
		(end 418.024818 -236.936026)
		(width 0.18288)
		(layer "In6.Cu")
		(net "M_G_CPU0_SB_DQ<1>")
	)
	(segment
		(start 431.731166 -234.02671)
		(end 431.472086 -234.02671)
		(width 0.18288)
		(layer "In6.Cu")
		(net "M_G_CPU0_SB_DQ<1>")
	)
	(segment
		(start 375.889012 -241.045492)
		(end 375.530364 -241.045492)
		(width 0.088646)
		(layer "In6.Cu")
		(net "M_G_CPU0_SB_DQ<1>")
	)
	(segment
		(start 402.764752 -235.863892)
		(end 402.604732 -235.703872)
		(width 0.18288)
		(layer "In6.Cu")
		(net "M_G_CPU0_SB_DQ<1>")
	)
	(segment
		(start 423.972228 -235.63961)
		(end 422.690798 -235.63961)
		(width 0.18288)
		(layer "In6.Cu")
		(net "M_G_CPU0_SB_DQ<1>")
	)
	(segment
		(start 433.764182 -231.657906)
		(end 433.50561 -231.657906)
		(width 0.18288)
		(layer "In6.Cu")
		(net "M_G_CPU0_SB_DQ<1>")
	)
	(segment
		(start 376.779536 -241.156744)
		(end 376.769122 -241.16284)
		(width 0.088646)
		(layer "In6.Cu")
		(net "M_G_CPU0_SB_DQ<1>")
	)
	(segment
		(start 432.08194 -232.840276)
		(end 431.898806 -233.02341)
		(width 0.18288)
		(layer "In6.Cu")
		(net "M_G_CPU0_SB_DQ<1>")
	)
	(segment
		(start 433.011834 -231.422702)
		(end 432.779932 -231.654604)
		(width 0.18288)
		(layer "In6.Cu")
		(net "M_G_CPU0_SB_DQ<1>")
	)
	(segment
		(start 416.274758 -236.936026)
		(end 414.101534 -236.936026)
		(width 0.18288)
		(layer "In6.Cu")
		(net "M_G_CPU0_SB_DQ<1>")
	)
	(segment
		(start 375.977404 -241.03965)
		(end 375.889012 -241.045492)
		(width 0.088646)
		(layer "In6.Cu")
		(net "M_G_CPU0_SB_DQ<1>")
	)
	(segment
		(start 404.845012 -235.863892)
		(end 404.845012 -236.229652)
		(width 0.18288)
		(layer "In6.Cu")
		(net "M_G_CPU0_SB_DQ<1>")
	)
	(segment
		(start 378.658882 -241.156744)
		(end 378.64415 -241.16538)
		(width 0.088646)
		(layer "In6.Cu")
		(net "M_G_CPU0_SB_DQ<1>")
	)
	(segment
		(start 417.15436 -236.568488)
		(end 416.642296 -236.568488)
		(width 0.18288)
		(layer "In6.Cu")
		(net "M_G_CPU0_SB_DQ<1>")
	)
	(segment
		(start 388.382764 -241.05997)
		(end 388.152894 -241.05997)
		(width 0.088646)
		(layer "In6.Cu")
		(net "M_G_CPU0_SB_DQ<1>")
	)
	(segment
		(start 432.581812 -232.840276)
		(end 432.08194 -232.840276)
		(width 0.18288)
		(layer "In6.Cu")
		(net "M_G_CPU0_SB_DQ<1>")
	)
	(segment
		(start 434.480462 -230.941626)
		(end 433.764182 -231.657906)
		(width 0.18288)
		(layer "In6.Cu")
		(net "M_G_CPU0_SB_DQ<1>")
	)
	(segment
		(start 427.257972 -236.479588)
		(end 426.409358 -236.479588)
		(width 0.18288)
		(layer "In6.Cu")
		(net "M_G_CPU0_SB_DQ<1>")
	)
	(segment
		(start 396.09268 -241.05997)
		(end 388.382764 -241.05997)
		(width 0.18288)
		(layer "In6.Cu")
		(net "M_G_CPU0_SB_DQ<1>")
	)
	(segment
		(start 425.921678 -235.991908)
		(end 424.324526 -235.991908)
		(width 0.18288)
		(layer "In6.Cu")
		(net "M_G_CPU0_SB_DQ<1>")
	)
	(segment
		(start 430.735994 -235.297726)
		(end 429.465994 -235.297726)
		(width 0.18288)
		(layer "In6.Cu")
		(net "M_G_CPU0_SB_DQ<1>")
	)
	(segment
		(start 376.10415 -241.07394)
		(end 375.977404 -241.03965)
		(width 0.088646)
		(layer "In6.Cu")
		(net "M_G_CPU0_SB_DQ<1>")
	)
	(segment
		(start 435.823614 -230.466646)
		(end 435.348634 -230.941626)
		(width 0.18288)
		(layer "In6.Cu")
		(net "M_G_CPU0_SB_DQ<1>")
	)
	(segment
		(start 404.151592 -236.229652)
		(end 404.151592 -235.863892)
		(width 0.18288)
		(layer "In6.Cu")
		(net "M_G_CPU0_SB_DQ<1>")
	)
	(segment
		(start 383.358136 -241.156744)
		(end 383.347722 -241.16284)
		(width 0.088646)
		(layer "In6.Cu")
		(net "M_G_CPU0_SB_DQ<1>")
	)
	(segment
		(start 431.472086 -234.02671)
		(end 431.306732 -233.861356)
		(width 0.18288)
		(layer "In6.Cu")
		(net "M_G_CPU0_SB_DQ<1>")
	)
	(segment
		(start 404.845012 -236.229652)
		(end 404.684992 -236.389672)
		(width 0.18288)
		(layer "In6.Cu")
		(net "M_G_CPU0_SB_DQ<1>")
	)
	(segment
		(start 403.991572 -235.703872)
		(end 403.618192 -235.703872)
		(width 0.18288)
		(layer "In6.Cu")
		(net "M_G_CPU0_SB_DQ<1>")
	)
	(segment
		(start 432.779932 -231.913176)
		(end 433.015136 -232.14838)
		(width 0.18288)
		(layer "In6.Cu")
		(net "M_G_CPU0_SB_DQ<1>")
	)
	(segment
		(start 402.604732 -235.703872)
		(end 401.448778 -235.703872)
		(width 0.18288)
		(layer "In6.Cu")
		(net "M_G_CPU0_SB_DQ<1>")
	)
	(segment
		(start 388.152894 -241.05997)
		(end 387.602984 -241.60988)
		(width 0.088646)
		(layer "In6.Cu")
		(net "M_G_CPU0_SB_DQ<1>")
	)
	(segment
		(start 433.50561 -231.657906)
		(end 433.270406 -231.422702)
		(width 0.18288)
		(layer "In6.Cu")
		(net "M_G_CPU0_SB_DQ<1>")
	)
	(segment
		(start 382.418082 -241.156744)
		(end 382.407668 -241.16284)
		(width 0.088646)
		(layer "In6.Cu")
		(net "M_G_CPU0_SB_DQ<1>")
	)
	(segment
		(start 404.684992 -236.389672)
		(end 404.311612 -236.389672)
		(width 0.18288)
		(layer "In6.Cu")
		(net "M_G_CPU0_SB_DQ<1>")
	)
	(segment
		(start 405.005032 -235.703872)
		(end 404.845012 -235.863892)
		(width 0.18288)
		(layer "In6.Cu")
		(net "M_G_CPU0_SB_DQ<1>")
	)
	(segment
		(start 408.25674 -235.703872)
		(end 405.005032 -235.703872)
		(width 0.18288)
		(layer "In6.Cu")
		(net "M_G_CPU0_SB_DQ<1>")
	)
	(segment
		(start 431.306732 -233.861356)
		(end 431.04816 -233.861356)
		(width 0.18288)
		(layer "In6.Cu")
		(net "M_G_CPU0_SB_DQ<1>")
	)
	(segment
		(start 428.945294 -235.818426)
		(end 427.919134 -235.818426)
		(width 0.18288)
		(layer "In6.Cu")
		(net "M_G_CPU0_SB_DQ<1>")
	)
	(segment
		(start 416.642296 -236.568488)
		(end 416.274758 -236.936026)
		(width 0.18288)
		(layer "In6.Cu")
		(net "M_G_CPU0_SB_DQ<1>")
	)
	(segment
		(start 431.04816 -233.861356)
		(end 430.824386 -234.08513)
		(width 0.18288)
		(layer "In6.Cu")
		(net "M_G_CPU0_SB_DQ<1>")
	)
	(segment
		(start 413.077914 -235.912406)
		(end 412.434278 -235.912406)
		(width 0.18288)
		(layer "In6.Cu")
		(net "M_G_CPU0_SB_DQ<1>")
	)
	(segment
		(start 433.015136 -232.406952)
		(end 432.581812 -232.840276)
		(width 0.18288)
		(layer "In6.Cu")
		(net "M_G_CPU0_SB_DQ<1>")
	)
	(segment
		(start 403.458172 -236.229652)
		(end 403.298152 -236.389672)
		(width 0.18288)
		(layer "In6.Cu")
		(net "M_G_CPU0_SB_DQ<1>")
	)
	(segment
		(start 421.488362 -236.842046)
		(end 419.275768 -236.842046)
		(width 0.18288)
		(layer "In6.Cu")
		(net "M_G_CPU0_SB_DQ<1>")
	)
	(segment
		(start 426.409358 -236.479588)
		(end 425.921678 -235.991908)
		(width 0.18288)
		(layer "In6.Cu")
		(net "M_G_CPU0_SB_DQ<1>")
	)
	(segment
		(start 386.674868 -241.27968)
		(end 386.551932 -241.156744)
		(width 0.088646)
		(layer "In6.Cu")
		(net "M_G_CPU0_SB_DQ<1>")
	)
	(segment
		(start 404.151592 -235.863892)
		(end 403.991572 -235.703872)
		(width 0.18288)
		(layer "In6.Cu")
		(net "M_G_CPU0_SB_DQ<1>")
	)
	(segment
		(start 419.00221 -236.568488)
		(end 418.392356 -236.568488)
		(width 0.18288)
		(layer "In6.Cu")
		(net "M_G_CPU0_SB_DQ<1>")
	)
	(segment
		(start 433.015136 -232.14838)
		(end 433.015136 -232.406952)
		(width 0.18288)
		(layer "In6.Cu")
		(net "M_G_CPU0_SB_DQ<1>")
	)
	(segment
		(start 430.824386 -234.08513)
		(end 430.824386 -234.42295)
		(width 0.18288)
		(layer "In6.Cu")
		(net "M_G_CPU0_SB_DQ<1>")
	)
	(segment
		(start 412.434278 -235.912406)
		(end 411.791658 -236.555026)
		(width 0.18288)
		(layer "In6.Cu")
		(net "M_G_CPU0_SB_DQ<1>")
	)
	(segment
		(start 387.251448 -241.60988)
		(end 386.921248 -241.27968)
		(width 0.088646)
		(layer "In6.Cu")
		(net "M_G_CPU0_SB_DQ<1>")
	)
	(segment
		(start 429.465994 -235.297726)
		(end 428.945294 -235.818426)
		(width 0.18288)
		(layer "In6.Cu")
		(net "M_G_CPU0_SB_DQ<1>")
	)
	(segment
		(start 431.088038 -234.945682)
		(end 430.735994 -235.297726)
		(width 0.18288)
		(layer "In6.Cu")
		(net "M_G_CPU0_SB_DQ<1>")
	)
	(segment
		(start 419.275768 -236.842046)
		(end 419.00221 -236.568488)
		(width 0.18288)
		(layer "In6.Cu")
		(net "M_G_CPU0_SB_DQ<1>")
	)
	(segment
		(start 424.324526 -235.991908)
		(end 423.972228 -235.63961)
		(width 0.18288)
		(layer "In6.Cu")
		(net "M_G_CPU0_SB_DQ<1>")
	)
	(segment
		(start 431.898806 -233.85907)
		(end 431.731166 -234.02671)
		(width 0.18288)
		(layer "In6.Cu")
		(net "M_G_CPU0_SB_DQ<1>")
	)
	(segment
		(start 431.898806 -233.02341)
		(end 431.898806 -233.85907)
		(width 0.18288)
		(layer "In6.Cu")
		(net "M_G_CPU0_SB_DQ<1>")
	)
	(segment
		(start 409.107894 -236.555026)
		(end 408.25674 -235.703872)
		(width 0.18288)
		(layer "In6.Cu")
		(net "M_G_CPU0_SB_DQ<1>")
	)
	(segment
		(start 386.921248 -241.27968)
		(end 386.674868 -241.27968)
		(width 0.088646)
		(layer "In6.Cu")
		(net "M_G_CPU0_SB_DQ<1>")
	)
	(segment
		(start 431.088038 -234.686602)
		(end 431.088038 -234.945682)
		(width 0.18288)
		(layer "In6.Cu")
		(net "M_G_CPU0_SB_DQ<1>")
	)
	(segment
		(start 411.791658 -236.555026)
		(end 409.107894 -236.555026)
		(width 0.18288)
		(layer "In6.Cu")
		(net "M_G_CPU0_SB_DQ<1>")
	)
	(segment
		(start 433.270406 -231.422702)
		(end 433.011834 -231.422702)
		(width 0.18288)
		(layer "In6.Cu")
		(net "M_G_CPU0_SB_DQ<1>")
	)
	(segment
		(start 381.478536 -241.156744)
		(end 381.468122 -241.16284)
		(width 0.088646)
		(layer "In6.Cu")
		(net "M_G_CPU0_SB_DQ<1>")
	)
	(arc
		(start 385.612132 -241.156744)
		(mid 385.424934 -241.106601)
		(end 385.237736 -241.156744)
		(width 0.088646)
		(layer "In6.Cu")
		(net "M_G_CPU0_SB_DQ<1>")
	)
	(arc
		(start 376.213878 -241.156744)
		(mid 376.156497 -241.118679)
		(end 376.10415 -241.07394)
		(width 0.088646)
		(layer "In6.Cu")
		(net "M_G_CPU0_SB_DQ<1>")
	)
	(arc
		(start 386.551932 -241.156744)
		(mid 386.364734 -241.106601)
		(end 386.177536 -241.156744)
		(width 0.088646)
		(layer "In6.Cu")
		(net "M_G_CPU0_SB_DQ<1>")
	)
	(arc
		(start 382.407668 -241.16284)
		(mid 382.12949 -241.232563)
		(end 381.852932 -241.156744)
		(width 0.088646)
		(layer "In6.Cu")
		(net "M_G_CPU0_SB_DQ<1>")
	)
	(arc
		(start 377.153932 -241.156744)
		(mid 376.966734 -241.106601)
		(end 376.779536 -241.156744)
		(width 0.088646)
		(layer "In6.Cu")
		(net "M_G_CPU0_SB_DQ<1>")
	)
	(arc
		(start 382.792478 -241.156744)
		(mid 382.60528 -241.106601)
		(end 382.418082 -241.156744)
		(width 0.088646)
		(layer "In6.Cu")
		(net "M_G_CPU0_SB_DQ<1>")
	)
	(arc
		(start 379.033278 -241.156744)
		(mid 378.84608 -241.106601)
		(end 378.658882 -241.156744)
		(width 0.088646)
		(layer "In6.Cu")
		(net "M_G_CPU0_SB_DQ<1>")
	)
	(arc
		(start 384.297936 -241.156744)
		(mid 384.015234 -241.23252)
		(end 383.732532 -241.156744)
		(width 0.088646)
		(layer "In6.Cu")
		(net "M_G_CPU0_SB_DQ<1>")
	)
	(arc
		(start 378.64415 -241.16538)
		(mid 378.367675 -241.2327)
		(end 378.093478 -241.156744)
		(width 0.088646)
		(layer "In6.Cu")
		(net "M_G_CPU0_SB_DQ<1>")
	)
	(arc
		(start 383.347722 -241.16284)
		(mid 383.06929 -241.232686)
		(end 382.792478 -241.156744)
		(width 0.088646)
		(layer "In6.Cu")
		(net "M_G_CPU0_SB_DQ<1>")
	)
	(arc
		(start 379.973078 -241.156744)
		(mid 379.78588 -241.106601)
		(end 379.598682 -241.156744)
		(width 0.088646)
		(layer "In6.Cu")
		(net "M_G_CPU0_SB_DQ<1>")
	)
	(arc
		(start 380.912878 -241.156744)
		(mid 380.72568 -241.106601)
		(end 380.538482 -241.156744)
		(width 0.088646)
		(layer "In6.Cu")
		(net "M_G_CPU0_SB_DQ<1>")
	)
	(arc
		(start 383.732532 -241.156744)
		(mid 383.545334 -241.106601)
		(end 383.358136 -241.156744)
		(width 0.088646)
		(layer "In6.Cu")
		(net "M_G_CPU0_SB_DQ<1>")
	)
	(arc
		(start 378.093478 -241.156744)
		(mid 377.90628 -241.106601)
		(end 377.719082 -241.156744)
		(width 0.088646)
		(layer "In6.Cu")
		(net "M_G_CPU0_SB_DQ<1>")
	)
	(arc
		(start 379.58395 -241.16538)
		(mid 379.307475 -241.2327)
		(end 379.033278 -241.156744)
		(width 0.088646)
		(layer "In6.Cu")
		(net "M_G_CPU0_SB_DQ<1>")
	)
	(arc
		(start 377.708668 -241.16284)
		(mid 377.43049 -241.232563)
		(end 377.153932 -241.156744)
		(width 0.088646)
		(layer "In6.Cu")
		(net "M_G_CPU0_SB_DQ<1>")
	)
	(arc
		(start 381.852932 -241.156744)
		(mid 381.665734 -241.106601)
		(end 381.478536 -241.156744)
		(width 0.088646)
		(layer "In6.Cu")
		(net "M_G_CPU0_SB_DQ<1>")
	)
	(arc
		(start 380.538482 -241.156744)
		(mid 380.25578 -241.23252)
		(end 379.973078 -241.156744)
		(width 0.088646)
		(layer "In6.Cu")
		(net "M_G_CPU0_SB_DQ<1>")
	)
	(arc
		(start 386.177536 -241.156744)
		(mid 385.894834 -241.23252)
		(end 385.612132 -241.156744)
		(width 0.088646)
		(layer "In6.Cu")
		(net "M_G_CPU0_SB_DQ<1>")
	)
	(arc
		(start 385.237736 -241.156744)
		(mid 384.955034 -241.23252)
		(end 384.672332 -241.156744)
		(width 0.088646)
		(layer "In6.Cu")
		(net "M_G_CPU0_SB_DQ<1>")
	)
	(arc
		(start 376.769122 -241.16284)
		(mid 376.49069 -241.232686)
		(end 376.213878 -241.156744)
		(width 0.088646)
		(layer "In6.Cu")
		(net "M_G_CPU0_SB_DQ<1>")
	)
	(arc
		(start 384.672332 -241.156744)
		(mid 384.485134 -241.106601)
		(end 384.297936 -241.156744)
		(width 0.088646)
		(layer "In6.Cu")
		(net "M_G_CPU0_SB_DQ<1>")
	)
	(arc
		(start 381.468122 -241.16284)
		(mid 381.18969 -241.232686)
		(end 380.912878 -241.156744)
		(width 0.088646)
		(layer "In6.Cu")
		(net "M_G_CPU0_SB_DQ<1>")
	)
	(arc
		(start 375.530364 -241.045492)
		(mid 375.036191 -240.947195)
		(end 374.617234 -240.667286)
		(width 0.088646)
		(layer "In6.Cu")
		(net "M_G_CPU0_SB_DQ<1>")
	)
	(segment
		(start 443.462664 -211.341716)
		(end 445.470534 -211.341716)
		(width 0.1016)
		(layer "F.Cu")
		(net "M_G_CPU0_SB_DQ<19>")
	)
	(segment
		(start 443.15888 -211.348828)
		(end 443.450726 -211.348828)
		(width 0.20066)
		(layer "F.Cu")
		(net "M_G_CPU0_SB_DQ<19>")
	)
	(segment
		(start 446.367916 -210.898994)
		(end 446.602104 -210.664806)
		(width 0.20066)
		(layer "F.Cu")
		(net "M_G_CPU0_SB_DQ<19>")
	)
	(segment
		(start 446.986152 -210.664806)
		(end 447.23812 -210.916774)
		(width 0.20066)
		(layer "F.Cu")
		(net "M_G_CPU0_SB_DQ<19>")
	)
	(segment
		(start 442.726826 -210.916774)
		(end 443.15888 -211.348828)
		(width 0.20066)
		(layer "F.Cu")
		(net "M_G_CPU0_SB_DQ<19>")
	)
	(segment
		(start 446.367916 -211.149946)
		(end 446.367916 -210.898994)
		(width 0.20066)
		(layer "F.Cu")
		(net "M_G_CPU0_SB_DQ<19>")
	)
	(segment
		(start 379.786134 -233.87812)
		(end 379.78588 -233.877866)
		(width 0.20066)
		(layer "F.Cu")
		(net "M_G_CPU0_SB_DQ<19>")
	)
	(segment
		(start 447.23812 -210.916774)
		(end 448.572382 -210.916774)
		(width 0.20066)
		(layer "F.Cu")
		(net "M_G_CPU0_SB_DQ<19>")
	)
	(segment
		(start 441.028582 -210.916774)
		(end 442.726826 -210.916774)
		(width 0.20066)
		(layer "F.Cu")
		(net "M_G_CPU0_SB_DQ<19>")
	)
	(segment
		(start 443.455552 -211.348828)
		(end 443.462664 -211.341716)
		(width 0.1016)
		(layer "F.Cu")
		(net "M_G_CPU0_SB_DQ<19>")
	)
	(segment
		(start 446.163954 -211.353908)
		(end 446.367916 -211.149946)
		(width 0.20066)
		(layer "F.Cu")
		(net "M_G_CPU0_SB_DQ<19>")
	)
	(segment
		(start 446.602104 -210.664806)
		(end 446.986152 -210.664806)
		(width 0.20066)
		(layer "F.Cu")
		(net "M_G_CPU0_SB_DQ<19>")
	)
	(segment
		(start 445.470534 -211.341716)
		(end 445.482726 -211.353908)
		(width 0.1016)
		(layer "F.Cu")
		(net "M_G_CPU0_SB_DQ<19>")
	)
	(segment
		(start 445.482726 -211.353908)
		(end 446.163954 -211.353908)
		(width 0.20066)
		(layer "F.Cu")
		(net "M_G_CPU0_SB_DQ<19>")
	)
	(segment
		(start 439.923682 -210.916774)
		(end 441.028582 -210.916774)
		(width 0.20066)
		(layer "F.Cu")
		(net "M_G_CPU0_SB_DQ<19>")
	)
	(segment
		(start 379.78588 -233.877866)
		(end 379.78588 -233.34218)
		(width 0.20066)
		(layer "F.Cu")
		(net "M_G_CPU0_SB_DQ<19>")
	)
	(segment
		(start 443.450726 -211.348828)
		(end 443.455552 -211.348828)
		(width 0.101854)
		(layer "F.Cu")
		(net "M_G_CPU0_SB_DQ<19>")
	)
	(segment
		(start 411.194504 -213.893146)
		(end 411.011624 -213.710266)
		(width 0.18288)
		(layer "In4.Cu")
		(net "M_G_CPU0_SB_DQ<19>")
	)
	(segment
		(start 410.501084 -214.426546)
		(end 410.318204 -214.609426)
		(width 0.18288)
		(layer "In4.Cu")
		(net "M_G_CPU0_SB_DQ<19>")
	)
	(segment
		(start 427.776894 -215.727026)
		(end 426.786294 -215.727026)
		(width 0.18288)
		(layer "In4.Cu")
		(net "M_G_CPU0_SB_DQ<19>")
	)
	(segment
		(start 437.146954 -210.49361)
		(end 435.09311 -210.49361)
		(width 0.18288)
		(layer "In4.Cu")
		(net "M_G_CPU0_SB_DQ<19>")
	)
	(segment
		(start 413.843978 -214.664798)
		(end 413.73425 -214.774526)
		(width 0.18288)
		(layer "In4.Cu")
		(net "M_G_CPU0_SB_DQ<19>")
	)
	(segment
		(start 408.549094 -214.609426)
		(end 408.295094 -214.863426)
		(width 0.18288)
		(layer "In4.Cu")
		(net "M_G_CPU0_SB_DQ<19>")
	)
	(segment
		(start 387.679184 -229.910386)
		(end 387.679184 -230.086662)
		(width 0.088646)
		(layer "In4.Cu")
		(net "M_G_CPU0_SB_DQ<19>")
	)
	(segment
		(start 410.501084 -213.893146)
		(end 410.501084 -214.426546)
		(width 0.18288)
		(layer "In4.Cu")
		(net "M_G_CPU0_SB_DQ<19>")
	)
	(segment
		(start 387.030722 -231.219756)
		(end 387.021832 -231.224836)
		(width 0.088646)
		(layer "In4.Cu")
		(net "M_G_CPU0_SB_DQ<19>")
	)
	(segment
		(start 431.790094 -212.298026)
		(end 430.215294 -213.872826)
		(width 0.18288)
		(layer "In4.Cu")
		(net "M_G_CPU0_SB_DQ<19>")
	)
	(segment
		(start 412.981394 -214.774526)
		(end 412.816294 -214.609426)
		(width 0.18288)
		(layer "In4.Cu")
		(net "M_G_CPU0_SB_DQ<19>")
	)
	(segment
		(start 387.862572 -229.726998)
		(end 387.82879 -229.76078)
		(width 0.18288)
		(layer "In4.Cu")
		(net "M_G_CPU0_SB_DQ<19>")
	)
	(segment
		(start 411.194504 -214.426546)
		(end 411.194504 -213.893146)
		(width 0.18288)
		(layer "In4.Cu")
		(net "M_G_CPU0_SB_DQ<19>")
	)
	(segment
		(start 389.885174 -228.299264)
		(end 388.45744 -229.726998)
		(width 0.18288)
		(layer "In4.Cu")
		(net "M_G_CPU0_SB_DQ<19>")
	)
	(segment
		(start 386.090922 -232.847642)
		(end 386.082032 -232.852722)
		(width 0.088646)
		(layer "In4.Cu")
		(net "M_G_CPU0_SB_DQ<19>")
	)
	(segment
		(start 387.491986 -230.410766)
		(end 387.491732 -230.41102)
		(width 0.088646)
		(layer "In4.Cu")
		(net "M_G_CPU0_SB_DQ<19>")
	)
	(segment
		(start 410.318204 -214.609426)
		(end 408.549094 -214.609426)
		(width 0.18288)
		(layer "In4.Cu")
		(net "M_G_CPU0_SB_DQ<19>")
	)
	(segment
		(start 405.977852 -214.863426)
		(end 392.542014 -228.299264)
		(width 0.18288)
		(layer "In4.Cu")
		(net "M_G_CPU0_SB_DQ<19>")
	)
	(segment
		(start 433.288694 -212.298026)
		(end 431.790094 -212.298026)
		(width 0.18288)
		(layer "In4.Cu")
		(net "M_G_CPU0_SB_DQ<19>")
	)
	(segment
		(start 420.189406 -214.743538)
		(end 419.489636 -214.043768)
		(width 0.18288)
		(layer "In4.Cu")
		(net "M_G_CPU0_SB_DQ<19>")
	)
	(segment
		(start 417.522152 -214.043768)
		(end 416.791394 -214.774526)
		(width 0.18288)
		(layer "In4.Cu")
		(net "M_G_CPU0_SB_DQ<19>")
	)
	(segment
		(start 412.816294 -214.609426)
		(end 411.377384 -214.609426)
		(width 0.18288)
		(layer "In4.Cu")
		(net "M_G_CPU0_SB_DQ<19>")
	)
	(segment
		(start 439.323734 -210.316826)
		(end 437.323738 -210.316826)
		(width 0.18288)
		(layer "In4.Cu")
		(net "M_G_CPU0_SB_DQ<19>")
	)
	(segment
		(start 382.792732 -233.666792)
		(end 382.788922 -233.668824)
		(width 0.088646)
		(layer "In4.Cu")
		(net "M_G_CPU0_SB_DQ<19>")
	)
	(segment
		(start 419.489636 -214.043768)
		(end 417.522152 -214.043768)
		(width 0.18288)
		(layer "In4.Cu")
		(net "M_G_CPU0_SB_DQ<19>")
	)
	(segment
		(start 388.45744 -229.726998)
		(end 387.862572 -229.726998)
		(width 0.18288)
		(layer "In4.Cu")
		(net "M_G_CPU0_SB_DQ<19>")
	)
	(segment
		(start 385.621022 -233.661458)
		(end 385.612132 -233.666538)
		(width 0.088646)
		(layer "In4.Cu")
		(net "M_G_CPU0_SB_DQ<19>")
	)
	(segment
		(start 435.09311 -210.49361)
		(end 433.288694 -212.298026)
		(width 0.18288)
		(layer "In4.Cu")
		(net "M_G_CPU0_SB_DQ<19>")
	)
	(segment
		(start 439.923682 -210.916774)
		(end 439.323734 -210.316826)
		(width 0.18288)
		(layer "In4.Cu")
		(net "M_G_CPU0_SB_DQ<19>")
	)
	(segment
		(start 380.538482 -233.666792)
		(end 380.141734 -233.43743)
		(width 0.088646)
		(layer "In4.Cu")
		(net "M_G_CPU0_SB_DQ<19>")
	)
	(segment
		(start 426.786294 -215.727026)
		(end 425.802806 -214.743538)
		(width 0.18288)
		(layer "In4.Cu")
		(net "M_G_CPU0_SB_DQ<19>")
	)
	(segment
		(start 392.542014 -228.299264)
		(end 389.885174 -228.299264)
		(width 0.18288)
		(layer "In4.Cu")
		(net "M_G_CPU0_SB_DQ<19>")
	)
	(segment
		(start 429.631094 -213.872826)
		(end 427.776894 -215.727026)
		(width 0.18288)
		(layer "In4.Cu")
		(net "M_G_CPU0_SB_DQ<19>")
	)
	(segment
		(start 413.73425 -214.774526)
		(end 412.981394 -214.774526)
		(width 0.18288)
		(layer "In4.Cu")
		(net "M_G_CPU0_SB_DQ<19>")
	)
	(segment
		(start 410.683964 -213.710266)
		(end 410.501084 -213.893146)
		(width 0.18288)
		(layer "In4.Cu")
		(net "M_G_CPU0_SB_DQ<19>")
	)
	(segment
		(start 414.612582 -214.664798)
		(end 413.843978 -214.664798)
		(width 0.18288)
		(layer "In4.Cu")
		(net "M_G_CPU0_SB_DQ<19>")
	)
	(segment
		(start 430.215294 -213.872826)
		(end 429.631094 -213.872826)
		(width 0.18288)
		(layer "In4.Cu")
		(net "M_G_CPU0_SB_DQ<19>")
	)
	(segment
		(start 411.377384 -214.609426)
		(end 411.194504 -214.426546)
		(width 0.18288)
		(layer "In4.Cu")
		(net "M_G_CPU0_SB_DQ<19>")
	)
	(segment
		(start 416.791394 -214.774526)
		(end 414.72231 -214.774526)
		(width 0.18288)
		(layer "In4.Cu")
		(net "M_G_CPU0_SB_DQ<19>")
	)
	(segment
		(start 386.739384 -231.696006)
		(end 386.739384 -231.714548)
		(width 0.088646)
		(layer "In4.Cu")
		(net "M_G_CPU0_SB_DQ<19>")
	)
	(segment
		(start 387.82879 -229.76078)
		(end 387.679184 -229.910386)
		(width 0.088646)
		(layer "In4.Cu")
		(net "M_G_CPU0_SB_DQ<19>")
	)
	(segment
		(start 380.913132 -233.666792)
		(end 380.90856 -233.669332)
		(width 0.088646)
		(layer "In4.Cu")
		(net "M_G_CPU0_SB_DQ<19>")
	)
	(segment
		(start 386.560822 -232.033826)
		(end 386.551932 -232.038906)
		(width 0.088646)
		(layer "In4.Cu")
		(net "M_G_CPU0_SB_DQ<19>")
	)
	(segment
		(start 411.011624 -213.710266)
		(end 410.683964 -213.710266)
		(width 0.18288)
		(layer "In4.Cu")
		(net "M_G_CPU0_SB_DQ<19>")
	)
	(segment
		(start 386.269484 -232.518458)
		(end 386.269484 -232.528364)
		(width 0.088646)
		(layer "In4.Cu")
		(net "M_G_CPU0_SB_DQ<19>")
	)
	(segment
		(start 381.852932 -233.666792)
		(end 381.850392 -233.668316)
		(width 0.088646)
		(layer "In4.Cu")
		(net "M_G_CPU0_SB_DQ<19>")
	)
	(segment
		(start 382.800098 -233.662474)
		(end 382.792732 -233.666792)
		(width 0.088646)
		(layer "In4.Cu")
		(net "M_G_CPU0_SB_DQ<19>")
	)
	(segment
		(start 379.786134 -233.34218)
		(end 379.78588 -233.34218)
		(width 0.088646)
		(layer "In4.Cu")
		(net "M_G_CPU0_SB_DQ<19>")
	)
	(segment
		(start 380.920498 -233.662474)
		(end 380.913132 -233.666792)
		(width 0.088646)
		(layer "In4.Cu")
		(net "M_G_CPU0_SB_DQ<19>")
	)
	(segment
		(start 414.72231 -214.774526)
		(end 414.612582 -214.664798)
		(width 0.18288)
		(layer "In4.Cu")
		(net "M_G_CPU0_SB_DQ<19>")
	)
	(segment
		(start 387.209284 -230.890572)
		(end 387.209284 -230.900478)
		(width 0.088646)
		(layer "In4.Cu")
		(net "M_G_CPU0_SB_DQ<19>")
	)
	(segment
		(start 437.323738 -210.316826)
		(end 437.146954 -210.49361)
		(width 0.18288)
		(layer "In4.Cu")
		(net "M_G_CPU0_SB_DQ<19>")
	)
	(segment
		(start 385.799584 -233.332274)
		(end 385.799584 -233.34218)
		(width 0.088646)
		(layer "In4.Cu")
		(net "M_G_CPU0_SB_DQ<19>")
	)
	(segment
		(start 408.295094 -214.863426)
		(end 405.977852 -214.863426)
		(width 0.18288)
		(layer "In4.Cu")
		(net "M_G_CPU0_SB_DQ<19>")
	)
	(segment
		(start 383.732532 -233.666538)
		(end 383.729992 -233.668316)
		(width 0.088646)
		(layer "In4.Cu")
		(net "M_G_CPU0_SB_DQ<19>")
	)
	(segment
		(start 425.802806 -214.743538)
		(end 420.189406 -214.743538)
		(width 0.18288)
		(layer "In4.Cu")
		(net "M_G_CPU0_SB_DQ<19>")
	)
	(arc
		(start 384.672332 -233.666538)
		(mid 384.485134 -233.716681)
		(end 384.297936 -233.666538)
		(width 0.088646)
		(layer "In4.Cu")
		(net "M_G_CPU0_SB_DQ<19>")
	)
	(arc
		(start 381.850392 -233.668316)
		(mid 381.664143 -233.716961)
		(end 381.478282 -233.666792)
		(width 0.088646)
		(layer "In4.Cu")
		(net "M_G_CPU0_SB_DQ<19>")
	)
	(arc
		(start 387.021832 -231.224836)
		(mid 386.819546 -231.423817)
		(end 386.739384 -231.696006)
		(width 0.088646)
		(layer "In4.Cu")
		(net "M_G_CPU0_SB_DQ<19>")
	)
	(arc
		(start 381.478282 -233.666792)
		(mid 381.199959 -233.591033)
		(end 380.920498 -233.662474)
		(width 0.088646)
		(layer "In4.Cu")
		(net "M_G_CPU0_SB_DQ<19>")
	)
	(arc
		(start 387.209284 -230.900478)
		(mid 387.161605 -231.083378)
		(end 387.030722 -231.219756)
		(width 0.088646)
		(layer "In4.Cu")
		(net "M_G_CPU0_SB_DQ<19>")
	)
	(arc
		(start 385.799584 -233.34218)
		(mid 385.751905 -233.52508)
		(end 385.621022 -233.661458)
		(width 0.088646)
		(layer "In4.Cu")
		(net "M_G_CPU0_SB_DQ<19>")
	)
	(arc
		(start 380.90856 -233.669332)
		(mid 380.723175 -233.71697)
		(end 380.538482 -233.666792)
		(width 0.088646)
		(layer "In4.Cu")
		(net "M_G_CPU0_SB_DQ<19>")
	)
	(arc
		(start 386.269484 -232.528364)
		(mid 386.221805 -232.711264)
		(end 386.090922 -232.847642)
		(width 0.088646)
		(layer "In4.Cu")
		(net "M_G_CPU0_SB_DQ<19>")
	)
	(arc
		(start 382.788922 -233.668824)
		(mid 382.603232 -233.716902)
		(end 382.418082 -233.666792)
		(width 0.088646)
		(layer "In4.Cu")
		(net "M_G_CPU0_SB_DQ<19>")
	)
	(arc
		(start 386.739384 -231.714548)
		(mid 386.691705 -231.897448)
		(end 386.560822 -232.033826)
		(width 0.088646)
		(layer "In4.Cu")
		(net "M_G_CPU0_SB_DQ<19>")
	)
	(arc
		(start 385.237736 -233.666538)
		(mid 384.955034 -233.590796)
		(end 384.672332 -233.666538)
		(width 0.088646)
		(layer "In4.Cu")
		(net "M_G_CPU0_SB_DQ<19>")
	)
	(arc
		(start 385.612132 -233.666538)
		(mid 385.424934 -233.716681)
		(end 385.237736 -233.666538)
		(width 0.088646)
		(layer "In4.Cu")
		(net "M_G_CPU0_SB_DQ<19>")
	)
	(arc
		(start 386.551932 -232.038906)
		(mid 386.347597 -232.241511)
		(end 386.269484 -232.518458)
		(width 0.088646)
		(layer "In4.Cu")
		(net "M_G_CPU0_SB_DQ<19>")
	)
	(arc
		(start 384.297936 -233.666538)
		(mid 384.015234 -233.590796)
		(end 383.732532 -233.666538)
		(width 0.088646)
		(layer "In4.Cu")
		(net "M_G_CPU0_SB_DQ<19>")
	)
	(arc
		(start 383.729992 -233.668316)
		(mid 383.543743 -233.716961)
		(end 383.357882 -233.666792)
		(width 0.088646)
		(layer "In4.Cu")
		(net "M_G_CPU0_SB_DQ<19>")
	)
	(arc
		(start 383.357882 -233.666792)
		(mid 383.079559 -233.591033)
		(end 382.800098 -233.662474)
		(width 0.088646)
		(layer "In4.Cu")
		(net "M_G_CPU0_SB_DQ<19>")
	)
	(arc
		(start 382.418082 -233.666792)
		(mid 382.135524 -233.591143)
		(end 381.852932 -233.666792)
		(width 0.088646)
		(layer "In4.Cu")
		(net "M_G_CPU0_SB_DQ<19>")
	)
	(arc
		(start 387.491732 -230.41102)
		(mid 387.287397 -230.613625)
		(end 387.209284 -230.890572)
		(width 0.088646)
		(layer "In4.Cu")
		(net "M_G_CPU0_SB_DQ<19>")
	)
	(arc
		(start 386.082032 -232.852722)
		(mid 385.877697 -233.055327)
		(end 385.799584 -233.332274)
		(width 0.088646)
		(layer "In4.Cu")
		(net "M_G_CPU0_SB_DQ<19>")
	)
	(arc
		(start 380.141734 -233.43743)
		(mid 379.970206 -233.366384)
		(end 379.786134 -233.34218)
		(width 0.088646)
		(layer "In4.Cu")
		(net "M_G_CPU0_SB_DQ<19>")
	)
	(arc
		(start 387.679184 -230.086662)
		(mid 387.62902 -230.2738)
		(end 387.491986 -230.410766)
		(width 0.088646)
		(layer "In4.Cu")
		(net "M_G_CPU0_SB_DQ<19>")
	)
	(segment
		(start 446.163954 -213.05393)
		(end 446.367916 -212.849968)
		(width 0.20066)
		(layer "F.Cu")
		(net "M_G_CPU0_SB_DQ<18>")
	)
	(segment
		(start 441.028582 -212.616796)
		(end 442.726826 -212.616796)
		(width 0.20066)
		(layer "F.Cu")
		(net "M_G_CPU0_SB_DQ<18>")
	)
	(segment
		(start 443.455552 -213.04885)
		(end 443.462664 -213.041738)
		(width 0.1016)
		(layer "F.Cu")
		(net "M_G_CPU0_SB_DQ<18>")
	)
	(segment
		(start 439.923682 -212.616796)
		(end 441.028582 -212.616796)
		(width 0.20066)
		(layer "F.Cu")
		(net "M_G_CPU0_SB_DQ<18>")
	)
	(segment
		(start 445.470534 -213.041738)
		(end 445.482726 -213.05393)
		(width 0.1016)
		(layer "F.Cu")
		(net "M_G_CPU0_SB_DQ<18>")
	)
	(segment
		(start 379.31598 -234.69219)
		(end 379.316234 -234.691936)
		(width 0.20066)
		(layer "F.Cu")
		(net "M_G_CPU0_SB_DQ<18>")
	)
	(segment
		(start 447.23812 -212.616796)
		(end 448.572382 -212.616796)
		(width 0.20066)
		(layer "F.Cu")
		(net "M_G_CPU0_SB_DQ<18>")
	)
	(segment
		(start 445.482726 -213.05393)
		(end 446.163954 -213.05393)
		(width 0.20066)
		(layer "F.Cu")
		(net "M_G_CPU0_SB_DQ<18>")
	)
	(segment
		(start 446.367916 -212.599016)
		(end 446.602104 -212.364828)
		(width 0.20066)
		(layer "F.Cu")
		(net "M_G_CPU0_SB_DQ<18>")
	)
	(segment
		(start 446.602104 -212.364828)
		(end 446.986152 -212.364828)
		(width 0.20066)
		(layer "F.Cu")
		(net "M_G_CPU0_SB_DQ<18>")
	)
	(segment
		(start 443.462664 -213.041738)
		(end 445.470534 -213.041738)
		(width 0.1016)
		(layer "F.Cu")
		(net "M_G_CPU0_SB_DQ<18>")
	)
	(segment
		(start 379.316234 -234.691936)
		(end 379.316234 -234.15625)
		(width 0.20066)
		(layer "F.Cu")
		(net "M_G_CPU0_SB_DQ<18>")
	)
	(segment
		(start 443.450726 -213.04885)
		(end 443.455552 -213.04885)
		(width 0.101854)
		(layer "F.Cu")
		(net "M_G_CPU0_SB_DQ<18>")
	)
	(segment
		(start 446.367916 -212.849968)
		(end 446.367916 -212.599016)
		(width 0.20066)
		(layer "F.Cu")
		(net "M_G_CPU0_SB_DQ<18>")
	)
	(segment
		(start 443.15888 -213.04885)
		(end 443.450726 -213.04885)
		(width 0.20066)
		(layer "F.Cu")
		(net "M_G_CPU0_SB_DQ<18>")
	)
	(segment
		(start 446.986152 -212.364828)
		(end 447.23812 -212.616796)
		(width 0.20066)
		(layer "F.Cu")
		(net "M_G_CPU0_SB_DQ<18>")
	)
	(segment
		(start 442.726826 -212.616796)
		(end 443.15888 -213.04885)
		(width 0.20066)
		(layer "F.Cu")
		(net "M_G_CPU0_SB_DQ<18>")
	)
	(segment
		(start 406.430226 -217.230706)
		(end 406.247346 -217.047826)
		(width 0.18288)
		(layer "In4.Cu")
		(net "M_G_CPU0_SB_DQ<18>")
	)
	(segment
		(start 427.980094 -217.124026)
		(end 427.649894 -217.454226)
		(width 0.18288)
		(layer "In4.Cu")
		(net "M_G_CPU0_SB_DQ<18>")
	)
	(segment
		(start 408.949906 -216.387426)
		(end 408.289506 -217.047826)
		(width 0.18288)
		(layer "In4.Cu")
		(net "M_G_CPU0_SB_DQ<18>")
	)
	(segment
		(start 390.29767 -229.294944)
		(end 388.543038 -231.049576)
		(width 0.18288)
		(layer "In4.Cu")
		(net "M_G_CPU0_SB_DQ<18>")
	)
	(segment
		(start 388.543038 -231.049576)
		(end 388.254748 -231.049576)
		(width 0.18288)
		(layer "In4.Cu")
		(net "M_G_CPU0_SB_DQ<18>")
	)
	(segment
		(start 427.649894 -217.454226)
		(end 426.57776 -217.454226)
		(width 0.18288)
		(layer "In4.Cu")
		(net "M_G_CPU0_SB_DQ<18>")
	)
	(segment
		(start 419.283388 -216.660984)
		(end 418.462714 -216.660984)
		(width 0.18288)
		(layer "In4.Cu")
		(net "M_G_CPU0_SB_DQ<18>")
	)
	(segment
		(start 412.875984 -216.650316)
		(end 412.613094 -216.387426)
		(width 0.18288)
		(layer "In4.Cu")
		(net "M_G_CPU0_SB_DQ<18>")
	)
	(segment
		(start 386.269484 -234.137708)
		(end 386.269484 -234.15625)
		(width 0.088646)
		(layer "In4.Cu")
		(net "M_G_CPU0_SB_DQ<18>")
	)
	(segment
		(start 387.679184 -231.62514)
		(end 387.679184 -231.714548)
		(width 0.088646)
		(layer "In4.Cu")
		(net "M_G_CPU0_SB_DQ<18>")
	)
	(segment
		(start 384.217164 -234.471972)
		(end 384.202432 -234.480608)
		(width 0.088646)
		(layer "In4.Cu")
		(net "M_G_CPU0_SB_DQ<18>")
	)
	(segment
		(start 386.739384 -233.332274)
		(end 386.739384 -233.34218)
		(width 0.088646)
		(layer "In4.Cu")
		(net "M_G_CPU0_SB_DQ<18>")
	)
	(segment
		(start 407.123646 -217.505534)
		(end 406.940766 -217.688414)
		(width 0.18288)
		(layer "In4.Cu")
		(net "M_G_CPU0_SB_DQ<18>")
	)
	(segment
		(start 435.405022 -213.04377)
		(end 435.193694 -213.255098)
		(width 0.18288)
		(layer "In4.Cu")
		(net "M_G_CPU0_SB_DQ<18>")
	)
	(segment
		(start 434.177694 -213.771226)
		(end 432.831494 -213.771226)
		(width 0.18288)
		(layer "In4.Cu")
		(net "M_G_CPU0_SB_DQ<18>")
	)
	(segment
		(start 439.923682 -212.616796)
		(end 439.302652 -213.237826)
		(width 0.18288)
		(layer "In4.Cu")
		(net "M_G_CPU0_SB_DQ<18>")
	)
	(segment
		(start 430.266094 -215.523826)
		(end 428.665894 -217.124026)
		(width 0.18288)
		(layer "In4.Cu")
		(net "M_G_CPU0_SB_DQ<18>")
	)
	(segment
		(start 385.156964 -234.471972)
		(end 385.142232 -234.480608)
		(width 0.088646)
		(layer "In4.Cu")
		(net "M_G_CPU0_SB_DQ<18>")
	)
	(segment
		(start 387.030722 -232.847642)
		(end 387.021832 -232.852722)
		(width 0.088646)
		(layer "In4.Cu")
		(net "M_G_CPU0_SB_DQ<18>")
	)
	(segment
		(start 406.430226 -217.505534)
		(end 406.430226 -217.230706)
		(width 0.18288)
		(layer "In4.Cu")
		(net "M_G_CPU0_SB_DQ<18>")
	)
	(segment
		(start 378.946156 -234.213654)
		(end 379.00356 -234.15625)
		(width 0.088646)
		(layer "In4.Cu")
		(net "M_G_CPU0_SB_DQ<18>")
	)
	(segment
		(start 386.560822 -233.661458)
		(end 386.551932 -233.666538)
		(width 0.088646)
		(layer "In4.Cu")
		(net "M_G_CPU0_SB_DQ<18>")
	)
	(segment
		(start 423.745406 -216.659714)
		(end 422.867328 -216.659714)
		(width 0.18288)
		(layer "In4.Cu")
		(net "M_G_CPU0_SB_DQ<18>")
	)
	(segment
		(start 416.880294 -216.362026)
		(end 416.592004 -216.650316)
		(width 0.18288)
		(layer "In4.Cu")
		(net "M_G_CPU0_SB_DQ<18>")
	)
	(segment
		(start 407.306526 -217.047826)
		(end 407.123646 -217.230706)
		(width 0.18288)
		(layer "In4.Cu")
		(net "M_G_CPU0_SB_DQ<18>")
	)
	(segment
		(start 386.090922 -234.475528)
		(end 386.082032 -234.480608)
		(width 0.088646)
		(layer "In4.Cu")
		(net "M_G_CPU0_SB_DQ<18>")
	)
	(segment
		(start 434.355494 -213.949026)
		(end 434.177694 -213.771226)
		(width 0.18288)
		(layer "In4.Cu")
		(net "M_G_CPU0_SB_DQ<18>")
	)
	(segment
		(start 428.665894 -217.124026)
		(end 427.980094 -217.124026)
		(width 0.18288)
		(layer "In4.Cu")
		(net "M_G_CPU0_SB_DQ<18>")
	)
	(segment
		(start 431.078894 -215.523826)
		(end 430.266094 -215.523826)
		(width 0.18288)
		(layer "In4.Cu")
		(net "M_G_CPU0_SB_DQ<18>")
	)
	(segment
		(start 379.00356 -234.15625)
		(end 379.316234 -234.15625)
		(width 0.088646)
		(layer "In4.Cu")
		(net "M_G_CPU0_SB_DQ<18>")
	)
	(segment
		(start 412.613094 -216.387426)
		(end 408.949906 -216.387426)
		(width 0.18288)
		(layer "In4.Cu")
		(net "M_G_CPU0_SB_DQ<18>")
	)
	(segment
		(start 437.340502 -213.04377)
		(end 435.405022 -213.04377)
		(width 0.18288)
		(layer "In4.Cu")
		(net "M_G_CPU0_SB_DQ<18>")
	)
	(segment
		(start 388.241794 -231.06253)
		(end 387.679184 -231.62514)
		(width 0.088646)
		(layer "In4.Cu")
		(net "M_G_CPU0_SB_DQ<18>")
	)
	(segment
		(start 422.867328 -216.659714)
		(end 422.651174 -216.44356)
		(width 0.18288)
		(layer "In4.Cu")
		(net "M_G_CPU0_SB_DQ<18>")
	)
	(segment
		(start 388.254748 -231.049576)
		(end 388.241794 -231.06253)
		(width 0.18288)
		(layer "In4.Cu")
		(net "M_G_CPU0_SB_DQ<18>")
	)
	(segment
		(start 406.940766 -217.688414)
		(end 406.613106 -217.688414)
		(width 0.18288)
		(layer "In4.Cu")
		(net "M_G_CPU0_SB_DQ<18>")
	)
	(segment
		(start 437.534558 -213.237826)
		(end 437.340502 -213.04377)
		(width 0.18288)
		(layer "In4.Cu")
		(net "M_G_CPU0_SB_DQ<18>")
	)
	(segment
		(start 425.567094 -216.44356)
		(end 424.711114 -216.44356)
		(width 0.18288)
		(layer "In4.Cu")
		(net "M_G_CPU0_SB_DQ<18>")
	)
	(segment
		(start 416.592004 -216.650316)
		(end 412.875984 -216.650316)
		(width 0.18288)
		(layer "In4.Cu")
		(net "M_G_CPU0_SB_DQ<18>")
	)
	(segment
		(start 426.57776 -217.454226)
		(end 425.567094 -216.44356)
		(width 0.18288)
		(layer "In4.Cu")
		(net "M_G_CPU0_SB_DQ<18>")
	)
	(segment
		(start 424.711114 -216.44102)
		(end 423.9641 -216.44102)
		(width 0.18288)
		(layer "In4.Cu")
		(net "M_G_CPU0_SB_DQ<18>")
	)
	(segment
		(start 432.831494 -213.771226)
		(end 431.078894 -215.523826)
		(width 0.18288)
		(layer "In4.Cu")
		(net "M_G_CPU0_SB_DQ<18>")
	)
	(segment
		(start 387.209284 -232.518458)
		(end 387.209284 -232.528364)
		(width 0.088646)
		(layer "In4.Cu")
		(net "M_G_CPU0_SB_DQ<18>")
	)
	(segment
		(start 406.613106 -217.688414)
		(end 406.430226 -217.505534)
		(width 0.18288)
		(layer "In4.Cu")
		(net "M_G_CPU0_SB_DQ<18>")
	)
	(segment
		(start 422.651174 -216.44356)
		(end 419.500812 -216.44356)
		(width 0.18288)
		(layer "In4.Cu")
		(net "M_G_CPU0_SB_DQ<18>")
	)
	(segment
		(start 435.193694 -213.255098)
		(end 435.193694 -213.542626)
		(width 0.18288)
		(layer "In4.Cu")
		(net "M_G_CPU0_SB_DQ<18>")
	)
	(segment
		(start 380.457964 -234.471972)
		(end 380.443232 -234.480608)
		(width 0.088646)
		(layer "In4.Cu")
		(net "M_G_CPU0_SB_DQ<18>")
	)
	(segment
		(start 439.302652 -213.237826)
		(end 437.534558 -213.237826)
		(width 0.18288)
		(layer "In4.Cu")
		(net "M_G_CPU0_SB_DQ<18>")
	)
	(segment
		(start 406.247346 -217.047826)
		(end 405.506936 -217.047826)
		(width 0.18288)
		(layer "In4.Cu")
		(net "M_G_CPU0_SB_DQ<18>")
	)
	(segment
		(start 419.500812 -216.44356)
		(end 419.283388 -216.660984)
		(width 0.18288)
		(layer "In4.Cu")
		(net "M_G_CPU0_SB_DQ<18>")
	)
	(segment
		(start 387.500622 -232.033826)
		(end 387.491732 -232.038906)
		(width 0.088646)
		(layer "In4.Cu")
		(net "M_G_CPU0_SB_DQ<18>")
	)
	(segment
		(start 418.163756 -216.362026)
		(end 416.880294 -216.362026)
		(width 0.18288)
		(layer "In4.Cu")
		(net "M_G_CPU0_SB_DQ<18>")
	)
	(segment
		(start 405.506936 -217.047826)
		(end 393.259818 -229.294944)
		(width 0.18288)
		(layer "In4.Cu")
		(net "M_G_CPU0_SB_DQ<18>")
	)
	(segment
		(start 379.129036 -234.480608)
		(end 379.120146 -234.475528)
		(width 0.088646)
		(layer "In4.Cu")
		(net "M_G_CPU0_SB_DQ<18>")
	)
	(segment
		(start 407.123646 -217.230706)
		(end 407.123646 -217.505534)
		(width 0.18288)
		(layer "In4.Cu")
		(net "M_G_CPU0_SB_DQ<18>")
	)
	(segment
		(start 408.289506 -217.047826)
		(end 407.306526 -217.047826)
		(width 0.18288)
		(layer "In4.Cu")
		(net "M_G_CPU0_SB_DQ<18>")
	)
	(segment
		(start 418.462714 -216.660984)
		(end 418.163756 -216.362026)
		(width 0.18288)
		(layer "In4.Cu")
		(net "M_G_CPU0_SB_DQ<18>")
	)
	(segment
		(start 393.259818 -229.294944)
		(end 390.29767 -229.294944)
		(width 0.18288)
		(layer "In4.Cu")
		(net "M_G_CPU0_SB_DQ<18>")
	)
	(segment
		(start 434.787294 -213.949026)
		(end 434.355494 -213.949026)
		(width 0.18288)
		(layer "In4.Cu")
		(net "M_G_CPU0_SB_DQ<18>")
	)
	(segment
		(start 424.711114 -216.44356)
		(end 424.711114 -216.44102)
		(width 0.18288)
		(layer "In4.Cu")
		(net "M_G_CPU0_SB_DQ<18>")
	)
	(segment
		(start 423.9641 -216.44102)
		(end 423.745406 -216.659714)
		(width 0.18288)
		(layer "In4.Cu")
		(net "M_G_CPU0_SB_DQ<18>")
	)
	(segment
		(start 435.193694 -213.542626)
		(end 434.787294 -213.949026)
		(width 0.18288)
		(layer "In4.Cu")
		(net "M_G_CPU0_SB_DQ<18>")
	)
	(arc
		(start 383.828036 -234.480608)
		(mid 383.545334 -234.404832)
		(end 383.262632 -234.480608)
		(width 0.088646)
		(layer "In4.Cu")
		(net "M_G_CPU0_SB_DQ<18>")
	)
	(arc
		(start 386.551932 -233.666538)
		(mid 386.349646 -233.865519)
		(end 386.269484 -234.137708)
		(width 0.088646)
		(layer "In4.Cu")
		(net "M_G_CPU0_SB_DQ<18>")
	)
	(arc
		(start 387.021832 -232.852722)
		(mid 386.817497 -233.055327)
		(end 386.739384 -233.332274)
		(width 0.088646)
		(layer "In4.Cu")
		(net "M_G_CPU0_SB_DQ<18>")
	)
	(arc
		(start 387.209284 -232.528364)
		(mid 387.161605 -232.711264)
		(end 387.030722 -232.847642)
		(width 0.088646)
		(layer "In4.Cu")
		(net "M_G_CPU0_SB_DQ<18>")
	)
	(arc
		(start 386.082032 -234.480608)
		(mid 385.894834 -234.530751)
		(end 385.707636 -234.480608)
		(width 0.088646)
		(layer "In4.Cu")
		(net "M_G_CPU0_SB_DQ<18>")
	)
	(arc
		(start 384.202432 -234.480608)
		(mid 384.015234 -234.530751)
		(end 383.828036 -234.480608)
		(width 0.088646)
		(layer "In4.Cu")
		(net "M_G_CPU0_SB_DQ<18>")
	)
	(arc
		(start 381.948436 -234.480608)
		(mid 381.665734 -234.404832)
		(end 381.383032 -234.480608)
		(width 0.088646)
		(layer "In4.Cu")
		(net "M_G_CPU0_SB_DQ<18>")
	)
	(arc
		(start 387.679184 -231.714548)
		(mid 387.631505 -231.897448)
		(end 387.500622 -232.033826)
		(width 0.088646)
		(layer "In4.Cu")
		(net "M_G_CPU0_SB_DQ<18>")
	)
	(arc
		(start 381.383032 -234.480608)
		(mid 381.195834 -234.530751)
		(end 381.008636 -234.480608)
		(width 0.088646)
		(layer "In4.Cu")
		(net "M_G_CPU0_SB_DQ<18>")
	)
	(arc
		(start 380.443232 -234.480608)
		(mid 380.256034 -234.530751)
		(end 380.068836 -234.480608)
		(width 0.088646)
		(layer "In4.Cu")
		(net "M_G_CPU0_SB_DQ<18>")
	)
	(arc
		(start 384.767836 -234.480608)
		(mid 384.493637 -234.404773)
		(end 384.217164 -234.471972)
		(width 0.088646)
		(layer "In4.Cu")
		(net "M_G_CPU0_SB_DQ<18>")
	)
	(arc
		(start 386.739384 -233.34218)
		(mid 386.691705 -233.52508)
		(end 386.560822 -233.661458)
		(width 0.088646)
		(layer "In4.Cu")
		(net "M_G_CPU0_SB_DQ<18>")
	)
	(arc
		(start 379.120146 -234.475528)
		(mid 379.004407 -234.363704)
		(end 378.946156 -234.213654)
		(width 0.088646)
		(layer "In4.Cu")
		(net "M_G_CPU0_SB_DQ<18>")
	)
	(arc
		(start 381.008636 -234.480608)
		(mid 380.734437 -234.404773)
		(end 380.457964 -234.471972)
		(width 0.088646)
		(layer "In4.Cu")
		(net "M_G_CPU0_SB_DQ<18>")
	)
	(arc
		(start 385.707636 -234.480608)
		(mid 385.433437 -234.404773)
		(end 385.156964 -234.471972)
		(width 0.088646)
		(layer "In4.Cu")
		(net "M_G_CPU0_SB_DQ<18>")
	)
	(arc
		(start 385.142232 -234.480608)
		(mid 384.955034 -234.530751)
		(end 384.767836 -234.480608)
		(width 0.088646)
		(layer "In4.Cu")
		(net "M_G_CPU0_SB_DQ<18>")
	)
	(arc
		(start 382.322832 -234.480608)
		(mid 382.135634 -234.530751)
		(end 381.948436 -234.480608)
		(width 0.088646)
		(layer "In4.Cu")
		(net "M_G_CPU0_SB_DQ<18>")
	)
	(arc
		(start 383.262632 -234.480608)
		(mid 383.075434 -234.530751)
		(end 382.888236 -234.480608)
		(width 0.088646)
		(layer "In4.Cu")
		(net "M_G_CPU0_SB_DQ<18>")
	)
	(arc
		(start 387.491732 -232.038906)
		(mid 387.287397 -232.241511)
		(end 387.209284 -232.518458)
		(width 0.088646)
		(layer "In4.Cu")
		(net "M_G_CPU0_SB_DQ<18>")
	)
	(arc
		(start 382.888236 -234.480608)
		(mid 382.605534 -234.404832)
		(end 382.322832 -234.480608)
		(width 0.088646)
		(layer "In4.Cu")
		(net "M_G_CPU0_SB_DQ<18>")
	)
	(arc
		(start 386.269484 -234.15625)
		(mid 386.221805 -234.33915)
		(end 386.090922 -234.475528)
		(width 0.088646)
		(layer "In4.Cu")
		(net "M_G_CPU0_SB_DQ<18>")
	)
	(arc
		(start 380.068836 -234.480608)
		(mid 379.786134 -234.404832)
		(end 379.503432 -234.480608)
		(width 0.088646)
		(layer "In4.Cu")
		(net "M_G_CPU0_SB_DQ<18>")
	)
	(arc
		(start 379.503432 -234.480608)
		(mid 379.316234 -234.530751)
		(end 379.129036 -234.480608)
		(width 0.088646)
		(layer "In4.Cu")
		(net "M_G_CPU0_SB_DQ<18>")
	)
	(segment
		(start 438.449212 -211.766658)
		(end 436.928514 -211.766658)
		(width 0.20066)
		(layer "F.Cu")
		(net "M_G_CPU0_SB_DQ<17>")
	)
	(segment
		(start 439.82386 -211.341716)
		(end 439.479182 -211.341716)
		(width 0.20066)
		(layer "F.Cu")
		(net "M_G_CPU0_SB_DQ<17>")
	)
	(segment
		(start 442.032644 -211.341716)
		(end 439.843926 -211.341716)
		(width 0.1016)
		(layer "F.Cu")
		(net "M_G_CPU0_SB_DQ<17>")
	)
	(segment
		(start 438.697878 -212.015324)
		(end 438.449212 -211.766658)
		(width 0.20066)
		(layer "F.Cu")
		(net "M_G_CPU0_SB_DQ<17>")
	)
	(segment
		(start 439.843926 -211.341716)
		(end 439.82386 -211.341716)
		(width 0.101854)
		(layer "F.Cu")
		(net "M_G_CPU0_SB_DQ<17>")
	)
	(segment
		(start 444.47206 -211.766912)
		(end 442.880496 -211.766912)
		(width 0.20066)
		(layer "F.Cu")
		(net "M_G_CPU0_SB_DQ<17>")
	)
	(segment
		(start 377.906534 -233.87812)
		(end 377.90628 -233.877866)
		(width 0.20066)
		(layer "F.Cu")
		(net "M_G_CPU0_SB_DQ<17>")
	)
	(segment
		(start 439.479182 -211.341716)
		(end 439.361072 -211.459826)
		(width 0.20066)
		(layer "F.Cu")
		(net "M_G_CPU0_SB_DQ<17>")
	)
	(segment
		(start 439.173112 -212.015324)
		(end 438.697878 -212.015324)
		(width 0.20066)
		(layer "F.Cu")
		(net "M_G_CPU0_SB_DQ<17>")
	)
	(segment
		(start 444.472314 -211.766658)
		(end 444.47206 -211.766912)
		(width 0.20066)
		(layer "F.Cu")
		(net "M_G_CPU0_SB_DQ<17>")
	)
	(segment
		(start 442.880496 -211.766912)
		(end 442.44895 -211.335366)
		(width 0.20066)
		(layer "F.Cu")
		(net "M_G_CPU0_SB_DQ<17>")
	)
	(segment
		(start 442.038994 -211.335366)
		(end 442.032644 -211.341716)
		(width 0.1016)
		(layer "F.Cu")
		(net "M_G_CPU0_SB_DQ<17>")
	)
	(segment
		(start 436.928514 -211.766658)
		(end 435.823614 -211.766658)
		(width 0.20066)
		(layer "F.Cu")
		(net "M_G_CPU0_SB_DQ<17>")
	)
	(segment
		(start 442.44895 -211.335366)
		(end 442.038994 -211.335366)
		(width 0.20066)
		(layer "F.Cu")
		(net "M_G_CPU0_SB_DQ<17>")
	)
	(segment
		(start 377.90628 -233.877866)
		(end 377.90628 -233.34218)
		(width 0.20066)
		(layer "F.Cu")
		(net "M_G_CPU0_SB_DQ<17>")
	)
	(segment
		(start 439.361072 -211.459826)
		(end 439.361072 -211.827364)
		(width 0.20066)
		(layer "F.Cu")
		(net "M_G_CPU0_SB_DQ<17>")
	)
	(segment
		(start 439.361072 -211.827364)
		(end 439.173112 -212.015324)
		(width 0.20066)
		(layer "F.Cu")
		(net "M_G_CPU0_SB_DQ<17>")
	)
	(segment
		(start 425.53509 -215.593422)
		(end 424.34129 -215.593422)
		(width 0.18288)
		(layer "In4.Cu")
		(net "M_G_CPU0_SB_DQ<17>")
	)
	(segment
		(start 387.399784 -230.900478)
		(end 387.399784 -230.91902)
		(width 0.088646)
		(layer "In4.Cu")
		(net "M_G_CPU0_SB_DQ<17>")
	)
	(segment
		(start 415.864294 -215.676226)
		(end 415.711894 -215.523826)
		(width 0.18288)
		(layer "In4.Cu")
		(net "M_G_CPU0_SB_DQ<17>")
	)
	(segment
		(start 434.990494 -212.043772)
		(end 434.990494 -212.614256)
		(width 0.18288)
		(layer "In4.Cu")
		(net "M_G_CPU0_SB_DQ<17>")
	)
	(segment
		(start 428.907194 -215.587072)
		(end 428.907194 -216.08161)
		(width 0.18288)
		(layer "In4.Cu")
		(net "M_G_CPU0_SB_DQ<17>")
	)
	(segment
		(start 424.060874 -215.313006)
		(end 422.90746 -215.313006)
		(width 0.18288)
		(layer "In4.Cu")
		(net "M_G_CPU0_SB_DQ<17>")
	)
	(segment
		(start 431.917094 -212.983826)
		(end 431.561494 -213.339426)
		(width 0.18288)
		(layer "In4.Cu")
		(net "M_G_CPU0_SB_DQ<17>")
	)
	(segment
		(start 409.47594 -215.82507)
		(end 409.200096 -215.549226)
		(width 0.18288)
		(layer "In4.Cu")
		(net "M_G_CPU0_SB_DQ<17>")
	)
	(segment
		(start 386.459984 -232.528364)
		(end 386.459984 -232.53827)
		(width 0.088646)
		(layer "In4.Cu")
		(net "M_G_CPU0_SB_DQ<17>")
	)
	(segment
		(start 418.005006 -214.870284)
		(end 418.005006 -215.386412)
		(width 0.18288)
		(layer "In4.Cu")
		(net "M_G_CPU0_SB_DQ<17>")
	)
	(segment
		(start 382.892554 -233.829098)
		(end 382.887982 -233.831638)
		(width 0.088646)
		(layer "In4.Cu")
		(net "M_G_CPU0_SB_DQ<17>")
	)
	(segment
		(start 406.049734 -215.549226)
		(end 405.866854 -215.732106)
		(width 0.18288)
		(layer "In4.Cu")
		(net "M_G_CPU0_SB_DQ<17>")
	)
	(segment
		(start 417.715192 -215.676226)
		(end 415.864294 -215.676226)
		(width 0.18288)
		(layer "In4.Cu")
		(net "M_G_CPU0_SB_DQ<17>")
	)
	(segment
		(start 418.758878 -214.885016)
		(end 418.584126 -214.710264)
		(width 0.18288)
		(layer "In4.Cu")
		(net "M_G_CPU0_SB_DQ<17>")
	)
	(segment
		(start 406.616662 -215.549226)
		(end 406.049734 -215.549226)
		(width 0.18288)
		(layer "In4.Cu")
		(net "M_G_CPU0_SB_DQ<17>")
	)
	(segment
		(start 428.398178 -216.590626)
		(end 427.726094 -216.590626)
		(width 0.18288)
		(layer "In4.Cu")
		(net "M_G_CPU0_SB_DQ<17>")
	)
	(segment
		(start 426.227494 -216.285826)
		(end 425.53509 -215.593422)
		(width 0.18288)
		(layer "In4.Cu")
		(net "M_G_CPU0_SB_DQ<17>")
	)
	(segment
		(start 387.980174 -230.280718)
		(end 387.938518 -230.322374)
		(width 0.088646)
		(layer "In4.Cu")
		(net "M_G_CPU0_SB_DQ<17>")
	)
	(segment
		(start 387.117336 -231.39019)
		(end 387.108446 -231.39527)
		(width 0.088646)
		(layer "In4.Cu")
		(net "M_G_CPU0_SB_DQ<17>")
	)
	(segment
		(start 414.026604 -215.523826)
		(end 413.782764 -215.279986)
		(width 0.18288)
		(layer "In4.Cu")
		(net "M_G_CPU0_SB_DQ<17>")
	)
	(segment
		(start 382.887982 -233.831638)
		(end 382.88341 -233.834432)
		(width 0.088646)
		(layer "In4.Cu")
		(net "M_G_CPU0_SB_DQ<17>")
	)
	(segment
		(start 386.929884 -231.714548)
		(end 386.929884 -231.724454)
		(width 0.088646)
		(layer "In4.Cu")
		(net "M_G_CPU0_SB_DQ<17>")
	)
	(segment
		(start 406.799542 -216.198196)
		(end 406.799542 -215.732106)
		(width 0.18288)
		(layer "In4.Cu")
		(net "M_G_CPU0_SB_DQ<17>")
	)
	(segment
		(start 418.165026 -214.710264)
		(end 418.005006 -214.870284)
		(width 0.18288)
		(layer "In4.Cu")
		(net "M_G_CPU0_SB_DQ<17>")
	)
	(segment
		(start 380.068582 -233.831638)
		(end 380.061216 -233.835956)
		(width 0.088646)
		(layer "In4.Cu")
		(net "M_G_CPU0_SB_DQ<17>")
	)
	(segment
		(start 421.516556 -215.885522)
		(end 421.224456 -215.593422)
		(width 0.18288)
		(layer "In4.Cu")
		(net "M_G_CPU0_SB_DQ<17>")
	)
	(segment
		(start 431.561494 -213.339426)
		(end 431.561494 -214.203026)
		(width 0.18288)
		(layer "In4.Cu")
		(net "M_G_CPU0_SB_DQ<17>")
	)
	(segment
		(start 431.561494 -214.203026)
		(end 430.799748 -214.964772)
		(width 0.18288)
		(layer "In4.Cu")
		(net "M_G_CPU0_SB_DQ<17>")
	)
	(segment
		(start 430.799748 -214.964772)
		(end 429.529494 -214.964772)
		(width 0.18288)
		(layer "In4.Cu")
		(net "M_G_CPU0_SB_DQ<17>")
	)
	(segment
		(start 424.34129 -215.593422)
		(end 424.060874 -215.313006)
		(width 0.18288)
		(layer "In4.Cu")
		(net "M_G_CPU0_SB_DQ<17>")
	)
	(segment
		(start 406.982422 -216.381076)
		(end 406.799542 -216.198196)
		(width 0.18288)
		(layer "In4.Cu")
		(net "M_G_CPU0_SB_DQ<17>")
	)
	(segment
		(start 381.008382 -233.831638)
		(end 381.001016 -233.835956)
		(width 0.088646)
		(layer "In4.Cu")
		(net "M_G_CPU0_SB_DQ<17>")
	)
	(segment
		(start 406.799542 -215.732106)
		(end 406.616662 -215.549226)
		(width 0.18288)
		(layer "In4.Cu")
		(net "M_G_CPU0_SB_DQ<17>")
	)
	(segment
		(start 380.073154 -233.829098)
		(end 380.068582 -233.831638)
		(width 0.088646)
		(layer "In4.Cu")
		(net "M_G_CPU0_SB_DQ<17>")
	)
	(segment
		(start 405.866854 -216.344246)
		(end 405.706834 -216.504266)
		(width 0.18288)
		(layer "In4.Cu")
		(net "M_G_CPU0_SB_DQ<17>")
	)
	(segment
		(start 378.563632 -233.831638)
		(end 378.490226 -233.789474)
		(width 0.088646)
		(layer "In4.Cu")
		(net "M_G_CPU0_SB_DQ<17>")
	)
	(segment
		(start 413.161734 -215.279986)
		(end 412.848298 -215.593422)
		(width 0.18288)
		(layer "In4.Cu")
		(net "M_G_CPU0_SB_DQ<17>")
	)
	(segment
		(start 410.186886 -215.82507)
		(end 409.47594 -215.82507)
		(width 0.18288)
		(layer "In4.Cu")
		(net "M_G_CPU0_SB_DQ<17>")
	)
	(segment
		(start 385.990084 -233.34218)
		(end 385.990084 -233.352086)
		(width 0.088646)
		(layer "In4.Cu")
		(net "M_G_CPU0_SB_DQ<17>")
	)
	(segment
		(start 405.346408 -216.504266)
		(end 393.05357 -228.797104)
		(width 0.18288)
		(layer "In4.Cu")
		(net "M_G_CPU0_SB_DQ<17>")
	)
	(segment
		(start 410.418534 -215.593422)
		(end 410.186886 -215.82507)
		(width 0.18288)
		(layer "In4.Cu")
		(net "M_G_CPU0_SB_DQ<17>")
	)
	(segment
		(start 434.620924 -212.983826)
		(end 431.917094 -212.983826)
		(width 0.18288)
		(layer "In4.Cu")
		(net "M_G_CPU0_SB_DQ<17>")
	)
	(segment
		(start 407.492962 -215.732106)
		(end 407.492962 -216.198196)
		(width 0.18288)
		(layer "In4.Cu")
		(net "M_G_CPU0_SB_DQ<17>")
	)
	(segment
		(start 418.758878 -215.316816)
		(end 418.758878 -214.885016)
		(width 0.18288)
		(layer "In4.Cu")
		(net "M_G_CPU0_SB_DQ<17>")
	)
	(segment
		(start 421.224456 -215.593422)
		(end 419.035484 -215.593422)
		(width 0.18288)
		(layer "In4.Cu")
		(net "M_G_CPU0_SB_DQ<17>")
	)
	(segment
		(start 405.706834 -216.504266)
		(end 405.346408 -216.504266)
		(width 0.18288)
		(layer "In4.Cu")
		(net "M_G_CPU0_SB_DQ<17>")
	)
	(segment
		(start 407.310082 -216.381076)
		(end 406.982422 -216.381076)
		(width 0.18288)
		(layer "In4.Cu")
		(net "M_G_CPU0_SB_DQ<17>")
	)
	(segment
		(start 381.012954 -233.829098)
		(end 381.008382 -233.831638)
		(width 0.088646)
		(layer "In4.Cu")
		(net "M_G_CPU0_SB_DQ<17>")
	)
	(segment
		(start 415.711894 -215.523826)
		(end 414.026604 -215.523826)
		(width 0.18288)
		(layer "In4.Cu")
		(net "M_G_CPU0_SB_DQ<17>")
	)
	(segment
		(start 390.091422 -228.797104)
		(end 388.607808 -230.280718)
		(width 0.18288)
		(layer "In4.Cu")
		(net "M_G_CPU0_SB_DQ<17>")
	)
	(segment
		(start 407.492962 -216.198196)
		(end 407.310082 -216.381076)
		(width 0.18288)
		(layer "In4.Cu")
		(net "M_G_CPU0_SB_DQ<17>")
	)
	(segment
		(start 419.035484 -215.593422)
		(end 418.758878 -215.316816)
		(width 0.18288)
		(layer "In4.Cu")
		(net "M_G_CPU0_SB_DQ<17>")
	)
	(segment
		(start 422.334944 -215.885522)
		(end 421.516556 -215.885522)
		(width 0.18288)
		(layer "In4.Cu")
		(net "M_G_CPU0_SB_DQ<17>")
	)
	(segment
		(start 383.828036 -233.831892)
		(end 383.822194 -233.83494)
		(width 0.088646)
		(layer "In4.Cu")
		(net "M_G_CPU0_SB_DQ<17>")
	)
	(segment
		(start 435.267608 -211.766658)
		(end 434.990494 -212.043772)
		(width 0.18288)
		(layer "In4.Cu")
		(net "M_G_CPU0_SB_DQ<17>")
	)
	(segment
		(start 427.421294 -216.285826)
		(end 426.227494 -216.285826)
		(width 0.18288)
		(layer "In4.Cu")
		(net "M_G_CPU0_SB_DQ<17>")
	)
	(segment
		(start 388.348982 -230.280718)
		(end 387.980174 -230.280718)
		(width 0.088646)
		(layer "In4.Cu")
		(net "M_G_CPU0_SB_DQ<17>")
	)
	(segment
		(start 418.005006 -215.386412)
		(end 417.715192 -215.676226)
		(width 0.18288)
		(layer "In4.Cu")
		(net "M_G_CPU0_SB_DQ<17>")
	)
	(segment
		(start 434.990494 -212.614256)
		(end 434.620924 -212.983826)
		(width 0.18288)
		(layer "In4.Cu")
		(net "M_G_CPU0_SB_DQ<17>")
	)
	(segment
		(start 427.726094 -216.590626)
		(end 427.421294 -216.285826)
		(width 0.18288)
		(layer "In4.Cu")
		(net "M_G_CPU0_SB_DQ<17>")
	)
	(segment
		(start 429.529494 -214.964772)
		(end 428.907194 -215.587072)
		(width 0.18288)
		(layer "In4.Cu")
		(net "M_G_CPU0_SB_DQ<17>")
	)
	(segment
		(start 386.177536 -233.017822)
		(end 386.168646 -233.022902)
		(width 0.088646)
		(layer "In4.Cu")
		(net "M_G_CPU0_SB_DQ<17>")
	)
	(segment
		(start 412.848298 -215.593422)
		(end 410.418534 -215.593422)
		(width 0.18288)
		(layer "In4.Cu")
		(net "M_G_CPU0_SB_DQ<17>")
	)
	(segment
		(start 379.128782 -233.831638)
		(end 379.121416 -233.835956)
		(width 0.088646)
		(layer "In4.Cu")
		(net "M_G_CPU0_SB_DQ<17>")
	)
	(segment
		(start 407.675842 -215.549226)
		(end 407.492962 -215.732106)
		(width 0.18288)
		(layer "In4.Cu")
		(net "M_G_CPU0_SB_DQ<17>")
	)
	(segment
		(start 379.133354 -233.829098)
		(end 379.128782 -233.831638)
		(width 0.088646)
		(layer "In4.Cu")
		(net "M_G_CPU0_SB_DQ<17>")
	)
	(segment
		(start 435.823614 -211.766658)
		(end 435.267608 -211.766658)
		(width 0.18288)
		(layer "In4.Cu")
		(net "M_G_CPU0_SB_DQ<17>")
	)
	(segment
		(start 388.607808 -230.280718)
		(end 388.348982 -230.280718)
		(width 0.18288)
		(layer "In4.Cu")
		(net "M_G_CPU0_SB_DQ<17>")
	)
	(segment
		(start 393.05357 -228.797104)
		(end 390.091422 -228.797104)
		(width 0.18288)
		(layer "In4.Cu")
		(net "M_G_CPU0_SB_DQ<17>")
	)
	(segment
		(start 385.707636 -233.831638)
		(end 385.707636 -233.831892)
		(width 0.088646)
		(layer "In4.Cu")
		(net "M_G_CPU0_SB_DQ<17>")
	)
	(segment
		(start 409.200096 -215.549226)
		(end 407.675842 -215.549226)
		(width 0.18288)
		(layer "In4.Cu")
		(net "M_G_CPU0_SB_DQ<17>")
	)
	(segment
		(start 381.948182 -233.831638)
		(end 381.942594 -233.83494)
		(width 0.088646)
		(layer "In4.Cu")
		(net "M_G_CPU0_SB_DQ<17>")
	)
	(segment
		(start 386.647436 -232.204006)
		(end 386.638546 -232.209086)
		(width 0.088646)
		(layer "In4.Cu")
		(net "M_G_CPU0_SB_DQ<17>")
	)
	(segment
		(start 422.90746 -215.313006)
		(end 422.334944 -215.885522)
		(width 0.18288)
		(layer "In4.Cu")
		(net "M_G_CPU0_SB_DQ<17>")
	)
	(segment
		(start 428.907194 -216.08161)
		(end 428.398178 -216.590626)
		(width 0.18288)
		(layer "In4.Cu")
		(net "M_G_CPU0_SB_DQ<17>")
	)
	(segment
		(start 405.866854 -215.732106)
		(end 405.866854 -216.344246)
		(width 0.18288)
		(layer "In4.Cu")
		(net "M_G_CPU0_SB_DQ<17>")
	)
	(segment
		(start 413.782764 -215.279986)
		(end 413.161734 -215.279986)
		(width 0.18288)
		(layer "In4.Cu")
		(net "M_G_CPU0_SB_DQ<17>")
	)
	(segment
		(start 418.584126 -214.710264)
		(end 418.165026 -214.710264)
		(width 0.18288)
		(layer "In4.Cu")
		(net "M_G_CPU0_SB_DQ<17>")
	)
	(arc
		(start 379.121416 -233.835956)
		(mid 378.841955 -233.907393)
		(end 378.563632 -233.831638)
		(width 0.088646)
		(layer "In4.Cu")
		(net "M_G_CPU0_SB_DQ<17>")
	)
	(arc
		(start 380.443232 -233.831638)
		(mid 380.258538 -233.781537)
		(end 380.073154 -233.829098)
		(width 0.088646)
		(layer "In4.Cu")
		(net "M_G_CPU0_SB_DQ<17>")
	)
	(arc
		(start 378.490226 -233.789474)
		(mid 378.183477 -233.585119)
		(end 377.90628 -233.34218)
		(width 0.088646)
		(layer "In4.Cu")
		(net "M_G_CPU0_SB_DQ<17>")
	)
	(arc
		(start 386.929884 -231.724454)
		(mid 386.851773 -232.001403)
		(end 386.647436 -232.204006)
		(width 0.088646)
		(layer "In4.Cu")
		(net "M_G_CPU0_SB_DQ<17>")
	)
	(arc
		(start 387.108446 -231.39527)
		(mid 386.977532 -231.53163)
		(end 386.929884 -231.714548)
		(width 0.088646)
		(layer "In4.Cu")
		(net "M_G_CPU0_SB_DQ<17>")
	)
	(arc
		(start 385.990084 -233.352086)
		(mid 385.911973 -233.629035)
		(end 385.707636 -233.831638)
		(width 0.088646)
		(layer "In4.Cu")
		(net "M_G_CPU0_SB_DQ<17>")
	)
	(arc
		(start 386.638546 -232.209086)
		(mid 386.507632 -232.345446)
		(end 386.459984 -232.528364)
		(width 0.088646)
		(layer "In4.Cu")
		(net "M_G_CPU0_SB_DQ<17>")
	)
	(arc
		(start 383.822194 -233.83494)
		(mid 383.541979 -233.907381)
		(end 383.262632 -233.831638)
		(width 0.088646)
		(layer "In4.Cu")
		(net "M_G_CPU0_SB_DQ<17>")
	)
	(arc
		(start 381.383032 -233.831638)
		(mid 381.198338 -233.781537)
		(end 381.012954 -233.829098)
		(width 0.088646)
		(layer "In4.Cu")
		(net "M_G_CPU0_SB_DQ<17>")
	)
	(arc
		(start 382.322832 -233.831638)
		(mid 382.135524 -233.781529)
		(end 381.948182 -233.831638)
		(width 0.088646)
		(layer "In4.Cu")
		(net "M_G_CPU0_SB_DQ<17>")
	)
	(arc
		(start 386.459984 -232.53827)
		(mid 386.381873 -232.815219)
		(end 386.177536 -233.017822)
		(width 0.088646)
		(layer "In4.Cu")
		(net "M_G_CPU0_SB_DQ<17>")
	)
	(arc
		(start 383.262632 -233.831638)
		(mid 383.077938 -233.781537)
		(end 382.892554 -233.829098)
		(width 0.088646)
		(layer "In4.Cu")
		(net "M_G_CPU0_SB_DQ<17>")
	)
	(arc
		(start 382.88341 -233.834432)
		(mid 382.602746 -233.90744)
		(end 382.322832 -233.831638)
		(width 0.088646)
		(layer "In4.Cu")
		(net "M_G_CPU0_SB_DQ<17>")
	)
	(arc
		(start 387.399784 -230.91902)
		(mid 387.319622 -231.191209)
		(end 387.117336 -231.39019)
		(width 0.088646)
		(layer "In4.Cu")
		(net "M_G_CPU0_SB_DQ<17>")
	)
	(arc
		(start 381.001016 -233.835956)
		(mid 380.721555 -233.907393)
		(end 380.443232 -233.831638)
		(width 0.088646)
		(layer "In4.Cu")
		(net "M_G_CPU0_SB_DQ<17>")
	)
	(arc
		(start 384.202432 -233.831892)
		(mid 384.015234 -233.781749)
		(end 383.828036 -233.831892)
		(width 0.088646)
		(layer "In4.Cu")
		(net "M_G_CPU0_SB_DQ<17>")
	)
	(arc
		(start 381.942594 -233.83494)
		(mid 381.662379 -233.907381)
		(end 381.383032 -233.831638)
		(width 0.088646)
		(layer "In4.Cu")
		(net "M_G_CPU0_SB_DQ<17>")
	)
	(arc
		(start 387.578346 -230.5812)
		(mid 387.447432 -230.71756)
		(end 387.399784 -230.900478)
		(width 0.088646)
		(layer "In4.Cu")
		(net "M_G_CPU0_SB_DQ<17>")
	)
	(arc
		(start 380.061216 -233.835956)
		(mid 379.781755 -233.907393)
		(end 379.503432 -233.831638)
		(width 0.088646)
		(layer "In4.Cu")
		(net "M_G_CPU0_SB_DQ<17>")
	)
	(arc
		(start 379.503432 -233.831638)
		(mid 379.318738 -233.781537)
		(end 379.133354 -233.829098)
		(width 0.088646)
		(layer "In4.Cu")
		(net "M_G_CPU0_SB_DQ<17>")
	)
	(arc
		(start 384.767836 -233.831892)
		(mid 384.485134 -233.907634)
		(end 384.202432 -233.831892)
		(width 0.088646)
		(layer "In4.Cu")
		(net "M_G_CPU0_SB_DQ<17>")
	)
	(arc
		(start 385.142232 -233.831892)
		(mid 384.955034 -233.781749)
		(end 384.767836 -233.831892)
		(width 0.088646)
		(layer "In4.Cu")
		(net "M_G_CPU0_SB_DQ<17>")
	)
	(arc
		(start 386.168646 -233.022902)
		(mid 386.037732 -233.159262)
		(end 385.990084 -233.34218)
		(width 0.088646)
		(layer "In4.Cu")
		(net "M_G_CPU0_SB_DQ<17>")
	)
	(arc
		(start 387.938518 -230.322374)
		(mid 387.766091 -230.462444)
		(end 387.578346 -230.5812)
		(width 0.088646)
		(layer "In4.Cu")
		(net "M_G_CPU0_SB_DQ<17>")
	)
	(arc
		(start 385.707636 -233.831892)
		(mid 385.424934 -233.907634)
		(end 385.142232 -233.831892)
		(width 0.088646)
		(layer "In4.Cu")
		(net "M_G_CPU0_SB_DQ<17>")
	)
	(segment
		(start 436.928514 -213.46668)
		(end 435.823614 -213.46668)
		(width 0.20066)
		(layer "F.Cu")
		(net "M_G_CPU0_SB_DQ<16>")
	)
	(segment
		(start 378.376434 -234.691936)
		(end 378.376434 -234.15625)
		(width 0.20066)
		(layer "F.Cu")
		(net "M_G_CPU0_SB_DQ<16>")
	)
	(segment
		(start 438.697878 -213.715346)
		(end 438.449212 -213.46668)
		(width 0.20066)
		(layer "F.Cu")
		(net "M_G_CPU0_SB_DQ<16>")
	)
	(segment
		(start 444.47206 -213.466934)
		(end 442.880496 -213.466934)
		(width 0.20066)
		(layer "F.Cu")
		(net "M_G_CPU0_SB_DQ<16>")
	)
	(segment
		(start 439.173112 -213.715346)
		(end 438.697878 -213.715346)
		(width 0.20066)
		(layer "F.Cu")
		(net "M_G_CPU0_SB_DQ<16>")
	)
	(segment
		(start 439.479182 -213.041738)
		(end 439.361072 -213.159848)
		(width 0.20066)
		(layer "F.Cu")
		(net "M_G_CPU0_SB_DQ<16>")
	)
	(segment
		(start 439.361072 -213.527386)
		(end 439.173112 -213.715346)
		(width 0.20066)
		(layer "F.Cu")
		(net "M_G_CPU0_SB_DQ<16>")
	)
	(segment
		(start 439.82386 -213.041738)
		(end 439.479182 -213.041738)
		(width 0.20066)
		(layer "F.Cu")
		(net "M_G_CPU0_SB_DQ<16>")
	)
	(segment
		(start 442.038994 -213.035388)
		(end 442.032644 -213.041738)
		(width 0.1016)
		(layer "F.Cu")
		(net "M_G_CPU0_SB_DQ<16>")
	)
	(segment
		(start 378.37618 -234.69219)
		(end 378.376434 -234.691936)
		(width 0.20066)
		(layer "F.Cu")
		(net "M_G_CPU0_SB_DQ<16>")
	)
	(segment
		(start 439.87085 -213.041738)
		(end 439.82386 -213.041738)
		(width 0.101854)
		(layer "F.Cu")
		(net "M_G_CPU0_SB_DQ<16>")
	)
	(segment
		(start 442.880496 -213.466934)
		(end 442.44895 -213.035388)
		(width 0.20066)
		(layer "F.Cu")
		(net "M_G_CPU0_SB_DQ<16>")
	)
	(segment
		(start 438.449212 -213.46668)
		(end 436.928514 -213.46668)
		(width 0.20066)
		(layer "F.Cu")
		(net "M_G_CPU0_SB_DQ<16>")
	)
	(segment
		(start 442.44895 -213.035388)
		(end 442.038994 -213.035388)
		(width 0.20066)
		(layer "F.Cu")
		(net "M_G_CPU0_SB_DQ<16>")
	)
	(segment
		(start 444.472314 -213.46668)
		(end 444.47206 -213.466934)
		(width 0.20066)
		(layer "F.Cu")
		(net "M_G_CPU0_SB_DQ<16>")
	)
	(segment
		(start 442.032644 -213.041738)
		(end 439.87085 -213.041738)
		(width 0.1016)
		(layer "F.Cu")
		(net "M_G_CPU0_SB_DQ<16>")
	)
	(segment
		(start 439.361072 -213.159848)
		(end 439.361072 -213.527386)
		(width 0.20066)
		(layer "F.Cu")
		(net "M_G_CPU0_SB_DQ<16>")
	)
	(segment
		(start 428.097696 -218.606624)
		(end 426.994574 -218.606624)
		(width 0.18288)
		(layer "In4.Cu")
		(net "M_G_CPU0_SB_DQ<16>")
	)
	(segment
		(start 434.094636 -216.235026)
		(end 433.911756 -216.052146)
		(width 0.18288)
		(layer "In4.Cu")
		(net "M_G_CPU0_SB_DQ<16>")
	)
	(segment
		(start 433.911756 -214.5792)
		(end 433.728876 -214.39632)
		(width 0.18288)
		(layer "In4.Cu")
		(net "M_G_CPU0_SB_DQ<16>")
	)
	(segment
		(start 379.598936 -234.645708)
		(end 379.588522 -234.651804)
		(width 0.088646)
		(layer "In4.Cu")
		(net "M_G_CPU0_SB_DQ<16>")
	)
	(segment
		(start 387.587236 -232.204006)
		(end 387.578346 -232.209086)
		(width 0.088646)
		(layer "In4.Cu")
		(net "M_G_CPU0_SB_DQ<16>")
	)
	(segment
		(start 435.243986 -214.299038)
		(end 435.243986 -216.075006)
		(width 0.18288)
		(layer "In4.Cu")
		(net "M_G_CPU0_SB_DQ<16>")
	)
	(segment
		(start 388.264146 -231.66959)
		(end 388.017766 -231.66959)
		(width 0.088646)
		(layer "In4.Cu")
		(net "M_G_CPU0_SB_DQ<16>")
	)
	(segment
		(start 387.117336 -233.017822)
		(end 387.108446 -233.022902)
		(width 0.088646)
		(layer "In4.Cu")
		(net "M_G_CPU0_SB_DQ<16>")
	)
	(segment
		(start 388.373366 -231.77881)
		(end 388.264146 -231.66959)
		(width 0.088646)
		(layer "In4.Cu")
		(net "M_G_CPU0_SB_DQ<16>")
	)
	(segment
		(start 378.689108 -234.15625)
		(end 378.376434 -234.15625)
		(width 0.088646)
		(layer "In4.Cu")
		(net "M_G_CPU0_SB_DQ<16>")
	)
	(segment
		(start 432.475894 -216.235026)
		(end 432.247294 -216.006426)
		(width 0.18288)
		(layer "In4.Cu")
		(net "M_G_CPU0_SB_DQ<16>")
	)
	(segment
		(start 433.035456 -216.235026)
		(end 432.475894 -216.235026)
		(width 0.18288)
		(layer "In4.Cu")
		(net "M_G_CPU0_SB_DQ<16>")
	)
	(segment
		(start 385.237482 -234.645708)
		(end 385.22275 -234.654344)
		(width 0.088646)
		(layer "In4.Cu")
		(net "M_G_CPU0_SB_DQ<16>")
	)
	(segment
		(start 425.681394 -217.293444)
		(end 420.311072 -217.293444)
		(width 0.18288)
		(layer "In4.Cu")
		(net "M_G_CPU0_SB_DQ<16>")
	)
	(segment
		(start 410.107638 -217.292682)
		(end 409.031694 -218.368626)
		(width 0.18288)
		(layer "In4.Cu")
		(net "M_G_CPU0_SB_DQ<16>")
	)
	(segment
		(start 390.504172 -229.792784)
		(end 388.73811 -231.558846)
		(width 0.18288)
		(layer "In4.Cu")
		(net "M_G_CPU0_SB_DQ<16>")
	)
	(segment
		(start 433.911756 -216.052146)
		(end 433.911756 -214.5792)
		(width 0.18288)
		(layer "In4.Cu")
		(net "M_G_CPU0_SB_DQ<16>")
	)
	(segment
		(start 419.297104 -218.307412)
		(end 418.314378 -218.307412)
		(width 0.18288)
		(layer "In4.Cu")
		(net "M_G_CPU0_SB_DQ<16>")
	)
	(segment
		(start 435.083966 -216.235026)
		(end 434.094636 -216.235026)
		(width 0.18288)
		(layer "In4.Cu")
		(net "M_G_CPU0_SB_DQ<16>")
	)
	(segment
		(start 388.73811 -231.558846)
		(end 388.518146 -231.77881)
		(width 0.088646)
		(layer "In4.Cu")
		(net "M_G_CPU0_SB_DQ<16>")
	)
	(segment
		(start 380.538482 -234.645708)
		(end 380.528068 -234.651804)
		(width 0.088646)
		(layer "In4.Cu")
		(net "M_G_CPU0_SB_DQ<16>")
	)
	(segment
		(start 387.399784 -232.528364)
		(end 387.399784 -232.53827)
		(width 0.088646)
		(layer "In4.Cu")
		(net "M_G_CPU0_SB_DQ<16>")
	)
	(segment
		(start 386.929884 -233.34218)
		(end 386.929884 -233.360722)
		(width 0.088646)
		(layer "In4.Cu")
		(net "M_G_CPU0_SB_DQ<16>")
	)
	(segment
		(start 381.478536 -234.645708)
		(end 381.468122 -234.651804)
		(width 0.088646)
		(layer "In4.Cu")
		(net "M_G_CPU0_SB_DQ<16>")
	)
	(segment
		(start 435.823614 -213.71941)
		(end 435.243986 -214.299038)
		(width 0.18288)
		(layer "In4.Cu")
		(net "M_G_CPU0_SB_DQ<16>")
	)
	(segment
		(start 432.247294 -216.006426)
		(end 431.485294 -216.006426)
		(width 0.18288)
		(layer "In4.Cu")
		(net "M_G_CPU0_SB_DQ<16>")
	)
	(segment
		(start 384.297682 -234.645708)
		(end 384.287268 -234.651804)
		(width 0.088646)
		(layer "In4.Cu")
		(net "M_G_CPU0_SB_DQ<16>")
	)
	(segment
		(start 388.518146 -231.77881)
		(end 388.373366 -231.77881)
		(width 0.088646)
		(layer "In4.Cu")
		(net "M_G_CPU0_SB_DQ<16>")
	)
	(segment
		(start 388.017766 -231.66959)
		(end 387.881876 -231.80548)
		(width 0.088646)
		(layer "In4.Cu")
		(net "M_G_CPU0_SB_DQ<16>")
	)
	(segment
		(start 435.243986 -216.075006)
		(end 435.083966 -216.235026)
		(width 0.18288)
		(layer "In4.Cu")
		(net "M_G_CPU0_SB_DQ<16>")
	)
	(segment
		(start 418.314378 -218.307412)
		(end 417.299648 -217.292682)
		(width 0.18288)
		(layer "In4.Cu")
		(net "M_G_CPU0_SB_DQ<16>")
	)
	(segment
		(start 420.311072 -217.293444)
		(end 419.297104 -218.307412)
		(width 0.18288)
		(layer "In4.Cu")
		(net "M_G_CPU0_SB_DQ<16>")
	)
	(segment
		(start 386.647436 -233.831892)
		(end 386.638546 -233.836972)
		(width 0.088646)
		(layer "In4.Cu")
		(net "M_G_CPU0_SB_DQ<16>")
	)
	(segment
		(start 430.012094 -217.479626)
		(end 429.224694 -217.479626)
		(width 0.18288)
		(layer "In4.Cu")
		(net "M_G_CPU0_SB_DQ<16>")
	)
	(segment
		(start 433.728876 -214.39632)
		(end 433.401216 -214.39632)
		(width 0.18288)
		(layer "In4.Cu")
		(net "M_G_CPU0_SB_DQ<16>")
	)
	(segment
		(start 378.75464 -234.221782)
		(end 378.689108 -234.15625)
		(width 0.088646)
		(layer "In4.Cu")
		(net "M_G_CPU0_SB_DQ<16>")
	)
	(segment
		(start 426.994574 -218.606624)
		(end 425.681394 -217.293444)
		(width 0.18288)
		(layer "In4.Cu")
		(net "M_G_CPU0_SB_DQ<16>")
	)
	(segment
		(start 433.401216 -214.39632)
		(end 433.218336 -214.5792)
		(width 0.18288)
		(layer "In4.Cu")
		(net "M_G_CPU0_SB_DQ<16>")
	)
	(segment
		(start 409.031694 -218.368626)
		(end 404.999698 -218.368626)
		(width 0.18288)
		(layer "In4.Cu")
		(net "M_G_CPU0_SB_DQ<16>")
	)
	(segment
		(start 404.999698 -218.368626)
		(end 393.57554 -229.792784)
		(width 0.18288)
		(layer "In4.Cu")
		(net "M_G_CPU0_SB_DQ<16>")
	)
	(segment
		(start 386.183378 -234.642152)
		(end 386.177282 -234.645708)
		(width 0.088646)
		(layer "In4.Cu")
		(net "M_G_CPU0_SB_DQ<16>")
	)
	(segment
		(start 417.299648 -217.292682)
		(end 410.107638 -217.292682)
		(width 0.18288)
		(layer "In4.Cu")
		(net "M_G_CPU0_SB_DQ<16>")
	)
	(segment
		(start 386.177282 -234.645708)
		(end 386.16255 -234.654344)
		(width 0.088646)
		(layer "In4.Cu")
		(net "M_G_CPU0_SB_DQ<16>")
	)
	(segment
		(start 433.218336 -216.052146)
		(end 433.035456 -216.235026)
		(width 0.18288)
		(layer "In4.Cu")
		(net "M_G_CPU0_SB_DQ<16>")
	)
	(segment
		(start 435.823614 -213.46668)
		(end 435.823614 -213.71941)
		(width 0.18288)
		(layer "In4.Cu")
		(net "M_G_CPU0_SB_DQ<16>")
	)
	(segment
		(start 429.224694 -217.479626)
		(end 428.097696 -218.606624)
		(width 0.18288)
		(layer "In4.Cu")
		(net "M_G_CPU0_SB_DQ<16>")
	)
	(segment
		(start 393.57554 -229.792784)
		(end 390.504172 -229.792784)
		(width 0.18288)
		(layer "In4.Cu")
		(net "M_G_CPU0_SB_DQ<16>")
	)
	(segment
		(start 431.485294 -216.006426)
		(end 430.012094 -217.479626)
		(width 0.18288)
		(layer "In4.Cu")
		(net "M_G_CPU0_SB_DQ<16>")
	)
	(segment
		(start 433.218336 -214.5792)
		(end 433.218336 -216.052146)
		(width 0.18288)
		(layer "In4.Cu")
		(net "M_G_CPU0_SB_DQ<16>")
	)
	(arc
		(start 382.792732 -234.645708)
		(mid 382.605534 -234.595565)
		(end 382.418336 -234.645708)
		(width 0.088646)
		(layer "In4.Cu")
		(net "M_G_CPU0_SB_DQ<16>")
	)
	(arc
		(start 379.973332 -234.645708)
		(mid 379.786134 -234.595565)
		(end 379.598936 -234.645708)
		(width 0.088646)
		(layer "In4.Cu")
		(net "M_G_CPU0_SB_DQ<16>")
	)
	(arc
		(start 387.850634 -231.859836)
		(mid 387.753279 -232.058222)
		(end 387.587236 -232.204006)
		(width 0.088646)
		(layer "In4.Cu")
		(net "M_G_CPU0_SB_DQ<16>")
	)
	(arc
		(start 385.22275 -234.654344)
		(mid 384.946275 -234.721664)
		(end 384.672078 -234.645708)
		(width 0.088646)
		(layer "In4.Cu")
		(net "M_G_CPU0_SB_DQ<16>")
	)
	(arc
		(start 379.033278 -234.645708)
		(mid 378.843765 -234.466743)
		(end 378.75464 -234.221782)
		(width 0.088646)
		(layer "In4.Cu")
		(net "M_G_CPU0_SB_DQ<16>")
	)
	(arc
		(start 387.881876 -231.80548)
		(mid 387.862672 -231.830598)
		(end 387.850634 -231.859836)
		(width 0.088646)
		(layer "In4.Cu")
		(net "M_G_CPU0_SB_DQ<16>")
	)
	(arc
		(start 384.287268 -234.651804)
		(mid 384.00909 -234.721527)
		(end 383.732532 -234.645708)
		(width 0.088646)
		(layer "In4.Cu")
		(net "M_G_CPU0_SB_DQ<16>")
	)
	(arc
		(start 387.578346 -232.209086)
		(mid 387.447432 -232.345446)
		(end 387.399784 -232.528364)
		(width 0.088646)
		(layer "In4.Cu")
		(net "M_G_CPU0_SB_DQ<16>")
	)
	(arc
		(start 382.418336 -234.645708)
		(mid 382.135634 -234.721484)
		(end 381.852932 -234.645708)
		(width 0.088646)
		(layer "In4.Cu")
		(net "M_G_CPU0_SB_DQ<16>")
	)
	(arc
		(start 380.912878 -234.645708)
		(mid 380.72568 -234.595565)
		(end 380.538482 -234.645708)
		(width 0.088646)
		(layer "In4.Cu")
		(net "M_G_CPU0_SB_DQ<16>")
	)
	(arc
		(start 387.399784 -232.53827)
		(mid 387.321673 -232.815219)
		(end 387.117336 -233.017822)
		(width 0.088646)
		(layer "In4.Cu")
		(net "M_G_CPU0_SB_DQ<16>")
	)
	(arc
		(start 383.358136 -234.645708)
		(mid 383.075434 -234.721484)
		(end 382.792732 -234.645708)
		(width 0.088646)
		(layer "In4.Cu")
		(net "M_G_CPU0_SB_DQ<16>")
	)
	(arc
		(start 386.459984 -234.15625)
		(mid 386.385993 -234.435816)
		(end 386.183378 -234.642152)
		(width 0.088646)
		(layer "In4.Cu")
		(net "M_G_CPU0_SB_DQ<16>")
	)
	(arc
		(start 385.611878 -234.645708)
		(mid 385.42468 -234.595565)
		(end 385.237482 -234.645708)
		(width 0.088646)
		(layer "In4.Cu")
		(net "M_G_CPU0_SB_DQ<16>")
	)
	(arc
		(start 386.638546 -233.836972)
		(mid 386.507632 -233.973332)
		(end 386.459984 -234.15625)
		(width 0.088646)
		(layer "In4.Cu")
		(net "M_G_CPU0_SB_DQ<16>")
	)
	(arc
		(start 387.108446 -233.022902)
		(mid 386.977532 -233.159262)
		(end 386.929884 -233.34218)
		(width 0.088646)
		(layer "In4.Cu")
		(net "M_G_CPU0_SB_DQ<16>")
	)
	(arc
		(start 384.672078 -234.645708)
		(mid 384.48488 -234.595565)
		(end 384.297682 -234.645708)
		(width 0.088646)
		(layer "In4.Cu")
		(net "M_G_CPU0_SB_DQ<16>")
	)
	(arc
		(start 381.468122 -234.651804)
		(mid 381.18969 -234.72165)
		(end 380.912878 -234.645708)
		(width 0.088646)
		(layer "In4.Cu")
		(net "M_G_CPU0_SB_DQ<16>")
	)
	(arc
		(start 386.929884 -233.360722)
		(mid 386.849722 -233.632911)
		(end 386.647436 -233.831892)
		(width 0.088646)
		(layer "In4.Cu")
		(net "M_G_CPU0_SB_DQ<16>")
	)
	(arc
		(start 379.588522 -234.651804)
		(mid 379.31009 -234.72165)
		(end 379.033278 -234.645708)
		(width 0.088646)
		(layer "In4.Cu")
		(net "M_G_CPU0_SB_DQ<16>")
	)
	(arc
		(start 380.528068 -234.651804)
		(mid 380.24989 -234.721527)
		(end 379.973332 -234.645708)
		(width 0.088646)
		(layer "In4.Cu")
		(net "M_G_CPU0_SB_DQ<16>")
	)
	(arc
		(start 386.16255 -234.654344)
		(mid 385.886075 -234.721664)
		(end 385.611878 -234.645708)
		(width 0.088646)
		(layer "In4.Cu")
		(net "M_G_CPU0_SB_DQ<16>")
	)
	(arc
		(start 383.732532 -234.645708)
		(mid 383.545334 -234.595565)
		(end 383.358136 -234.645708)
		(width 0.088646)
		(layer "In4.Cu")
		(net "M_G_CPU0_SB_DQ<16>")
	)
	(arc
		(start 381.852932 -234.645708)
		(mid 381.665734 -234.595565)
		(end 381.478536 -234.645708)
		(width 0.088646)
		(layer "In4.Cu")
		(net "M_G_CPU0_SB_DQ<16>")
	)
	(segment
		(start 443.455552 -214.748618)
		(end 443.462664 -214.741506)
		(width 0.1016)
		(layer "F.Cu")
		(net "M_G_CPU0_SB_DQ<15>")
	)
	(segment
		(start 445.470534 -214.741506)
		(end 445.482726 -214.753698)
		(width 0.1016)
		(layer "F.Cu")
		(net "M_G_CPU0_SB_DQ<15>")
	)
	(segment
		(start 446.163954 -214.753698)
		(end 446.367916 -214.549736)
		(width 0.20066)
		(layer "F.Cu")
		(net "M_G_CPU0_SB_DQ<15>")
	)
	(segment
		(start 439.923682 -214.316564)
		(end 441.028582 -214.316564)
		(width 0.20066)
		(layer "F.Cu")
		(net "M_G_CPU0_SB_DQ<15>")
	)
	(segment
		(start 443.462664 -214.741506)
		(end 445.470534 -214.741506)
		(width 0.1016)
		(layer "F.Cu")
		(net "M_G_CPU0_SB_DQ<15>")
	)
	(segment
		(start 447.23812 -214.316564)
		(end 448.572382 -214.316564)
		(width 0.20066)
		(layer "F.Cu")
		(net "M_G_CPU0_SB_DQ<15>")
	)
	(segment
		(start 446.986152 -214.064596)
		(end 447.23812 -214.316564)
		(width 0.20066)
		(layer "F.Cu")
		(net "M_G_CPU0_SB_DQ<15>")
	)
	(segment
		(start 443.15888 -214.748618)
		(end 443.450726 -214.748618)
		(width 0.20066)
		(layer "F.Cu")
		(net "M_G_CPU0_SB_DQ<15>")
	)
	(segment
		(start 376.02668 -233.877866)
		(end 376.02668 -233.34218)
		(width 0.20066)
		(layer "F.Cu")
		(net "M_G_CPU0_SB_DQ<15>")
	)
	(segment
		(start 441.028582 -214.316564)
		(end 442.726826 -214.316564)
		(width 0.20066)
		(layer "F.Cu")
		(net "M_G_CPU0_SB_DQ<15>")
	)
	(segment
		(start 445.482726 -214.753698)
		(end 446.163954 -214.753698)
		(width 0.20066)
		(layer "F.Cu")
		(net "M_G_CPU0_SB_DQ<15>")
	)
	(segment
		(start 442.726826 -214.316564)
		(end 443.15888 -214.748618)
		(width 0.20066)
		(layer "F.Cu")
		(net "M_G_CPU0_SB_DQ<15>")
	)
	(segment
		(start 376.026934 -233.87812)
		(end 376.02668 -233.877866)
		(width 0.20066)
		(layer "F.Cu")
		(net "M_G_CPU0_SB_DQ<15>")
	)
	(segment
		(start 446.602104 -214.064596)
		(end 446.986152 -214.064596)
		(width 0.20066)
		(layer "F.Cu")
		(net "M_G_CPU0_SB_DQ<15>")
	)
	(segment
		(start 443.450726 -214.748618)
		(end 443.455552 -214.748618)
		(width 0.101854)
		(layer "F.Cu")
		(net "M_G_CPU0_SB_DQ<15>")
	)
	(segment
		(start 446.367916 -214.549736)
		(end 446.367916 -214.298784)
		(width 0.20066)
		(layer "F.Cu")
		(net "M_G_CPU0_SB_DQ<15>")
	)
	(segment
		(start 446.367916 -214.298784)
		(end 446.602104 -214.064596)
		(width 0.20066)
		(layer "F.Cu")
		(net "M_G_CPU0_SB_DQ<15>")
	)
	(segment
		(start 406.75941 -217.659204)
		(end 406.57653 -217.476324)
		(width 0.18288)
		(layer "In6.Cu")
		(net "M_G_CPU0_SB_DQ<15>")
	)
	(segment
		(start 407.08707 -217.659204)
		(end 406.75941 -217.659204)
		(width 0.18288)
		(layer "In6.Cu")
		(net "M_G_CPU0_SB_DQ<15>")
	)
	(segment
		(start 406.57653 -217.291666)
		(end 406.39365 -217.108786)
		(width 0.18288)
		(layer "In6.Cu")
		(net "M_G_CPU0_SB_DQ<15>")
	)
	(segment
		(start 427.319694 -217.962226)
		(end 425.572936 -217.962226)
		(width 0.18288)
		(layer "In6.Cu")
		(net "M_G_CPU0_SB_DQ<15>")
	)
	(segment
		(start 411.04947 -216.387426)
		(end 409.944824 -217.492072)
		(width 0.18288)
		(layer "In6.Cu")
		(net "M_G_CPU0_SB_DQ<15>")
	)
	(segment
		(start 431.763932 -216.442036)
		(end 430.980088 -216.743026)
		(width 0.18288)
		(layer "In6.Cu")
		(net "M_G_CPU0_SB_DQ<15>")
	)
	(segment
		(start 409.34894 -217.492072)
		(end 408.965654 -217.108786)
		(width 0.18288)
		(layer "In6.Cu")
		(net "M_G_CPU0_SB_DQ<15>")
	)
	(segment
		(start 416.616134 -217.792808)
		(end 415.525458 -216.702132)
		(width 0.18288)
		(layer "In6.Cu")
		(net "M_G_CPU0_SB_DQ<15>")
	)
	(segment
		(start 430.012094 -216.743026)
		(end 429.250094 -217.225626)
		(width 0.18288)
		(layer "In6.Cu")
		(net "M_G_CPU0_SB_DQ<15>")
	)
	(segment
		(start 375.839482 -233.017822)
		(end 375.830592 -233.022902)
		(width 0.088646)
		(layer "In6.Cu")
		(net "M_G_CPU0_SB_DQ<15>")
	)
	(segment
		(start 407.26995 -217.476324)
		(end 407.08707 -217.659204)
		(width 0.18288)
		(layer "In6.Cu")
		(net "M_G_CPU0_SB_DQ<15>")
	)
	(segment
		(start 409.944824 -217.492072)
		(end 409.34894 -217.492072)
		(width 0.18288)
		(layer "In6.Cu")
		(net "M_G_CPU0_SB_DQ<15>")
	)
	(segment
		(start 378.658882 -233.017822)
		(end 378.64415 -233.026458)
		(width 0.088646)
		(layer "In6.Cu")
		(net "M_G_CPU0_SB_DQ<15>")
	)
	(segment
		(start 377.719082 -233.017822)
		(end 377.70435 -233.026458)
		(width 0.088646)
		(layer "In6.Cu")
		(net "M_G_CPU0_SB_DQ<15>")
	)
	(segment
		(start 429.250094 -217.225626)
		(end 428.056294 -217.225626)
		(width 0.18288)
		(layer "In6.Cu")
		(net "M_G_CPU0_SB_DQ<15>")
	)
	(segment
		(start 438.857136 -214.935562)
		(end 436.260494 -216.442036)
		(width 0.18288)
		(layer "In6.Cu")
		(net "M_G_CPU0_SB_DQ<15>")
	)
	(segment
		(start 412.895288 -216.702132)
		(end 412.580582 -216.387426)
		(width 0.18288)
		(layer "In6.Cu")
		(net "M_G_CPU0_SB_DQ<15>")
	)
	(segment
		(start 425.393612 -218.14155)
		(end 423.62501 -218.14155)
		(width 0.18288)
		(layer "In6.Cu")
		(net "M_G_CPU0_SB_DQ<15>")
	)
	(segment
		(start 415.525458 -216.702132)
		(end 412.895288 -216.702132)
		(width 0.18288)
		(layer "In6.Cu")
		(net "M_G_CPU0_SB_DQ<15>")
	)
	(segment
		(start 387.680454 -231.875584)
		(end 387.401816 -232.154222)
		(width 0.088646)
		(layer "In6.Cu")
		(net "M_G_CPU0_SB_DQ<15>")
	)
	(segment
		(start 408.965654 -217.108786)
		(end 407.45283 -217.108786)
		(width 0.18288)
		(layer "In6.Cu")
		(net "M_G_CPU0_SB_DQ<15>")
	)
	(segment
		(start 412.580582 -216.387426)
		(end 411.04947 -216.387426)
		(width 0.18288)
		(layer "In6.Cu")
		(net "M_G_CPU0_SB_DQ<15>")
	)
	(segment
		(start 407.45283 -217.108786)
		(end 407.26995 -217.291666)
		(width 0.18288)
		(layer "In6.Cu")
		(net "M_G_CPU0_SB_DQ<15>")
	)
	(segment
		(start 406.57653 -217.476324)
		(end 406.57653 -217.291666)
		(width 0.18288)
		(layer "In6.Cu")
		(net "M_G_CPU0_SB_DQ<15>")
	)
	(segment
		(start 436.260494 -216.442036)
		(end 431.763932 -216.442036)
		(width 0.18288)
		(layer "In6.Cu")
		(net "M_G_CPU0_SB_DQ<15>")
	)
	(segment
		(start 388.114286 -231.281732)
		(end 387.961886 -231.281732)
		(width 0.088646)
		(layer "In6.Cu")
		(net "M_G_CPU0_SB_DQ<15>")
	)
	(segment
		(start 404.264876 -217.108786)
		(end 390.09193 -231.281732)
		(width 0.18288)
		(layer "In6.Cu")
		(net "M_G_CPU0_SB_DQ<15>")
	)
	(segment
		(start 387.961886 -231.281732)
		(end 387.680454 -231.563164)
		(width 0.088646)
		(layer "In6.Cu")
		(net "M_G_CPU0_SB_DQ<15>")
	)
	(segment
		(start 425.572936 -217.962226)
		(end 425.393612 -218.14155)
		(width 0.18288)
		(layer "In6.Cu")
		(net "M_G_CPU0_SB_DQ<15>")
	)
	(segment
		(start 380.538736 -233.017822)
		(end 380.528322 -233.023918)
		(width 0.088646)
		(layer "In6.Cu")
		(net "M_G_CPU0_SB_DQ<15>")
	)
	(segment
		(start 375.656602 -233.284776)
		(end 375.714006 -233.34218)
		(width 0.088646)
		(layer "In6.Cu")
		(net "M_G_CPU0_SB_DQ<15>")
	)
	(segment
		(start 428.056294 -217.225626)
		(end 427.319694 -217.962226)
		(width 0.18288)
		(layer "In6.Cu")
		(net "M_G_CPU0_SB_DQ<15>")
	)
	(segment
		(start 375.714006 -233.34218)
		(end 376.02668 -233.34218)
		(width 0.088646)
		(layer "In6.Cu")
		(net "M_G_CPU0_SB_DQ<15>")
	)
	(segment
		(start 439.304684 -214.935562)
		(end 438.857136 -214.935562)
		(width 0.18288)
		(layer "In6.Cu")
		(net "M_G_CPU0_SB_DQ<15>")
	)
	(segment
		(start 380.927864 -233.026458)
		(end 380.913132 -233.017822)
		(width 0.088646)
		(layer "In6.Cu")
		(net "M_G_CPU0_SB_DQ<15>")
	)
	(segment
		(start 439.923682 -214.316564)
		(end 439.304684 -214.935562)
		(width 0.18288)
		(layer "In6.Cu")
		(net "M_G_CPU0_SB_DQ<15>")
	)
	(segment
		(start 387.401816 -232.154222)
		(end 386.848604 -232.154222)
		(width 0.088646)
		(layer "In6.Cu")
		(net "M_G_CPU0_SB_DQ<15>")
	)
	(segment
		(start 420.04869 -218.833192)
		(end 416.616134 -217.792808)
		(width 0.18288)
		(layer "In6.Cu")
		(net "M_G_CPU0_SB_DQ<15>")
	)
	(segment
		(start 421.304212 -218.99499)
		(end 420.210488 -218.99499)
		(width 0.18288)
		(layer "In6.Cu")
		(net "M_G_CPU0_SB_DQ<15>")
	)
	(segment
		(start 407.26995 -217.291666)
		(end 407.26995 -217.476324)
		(width 0.18288)
		(layer "In6.Cu")
		(net "M_G_CPU0_SB_DQ<15>")
	)
	(segment
		(start 384.767836 -232.204006)
		(end 384.758946 -232.209086)
		(width 0.088646)
		(layer "In6.Cu")
		(net "M_G_CPU0_SB_DQ<15>")
	)
	(segment
		(start 406.39365 -217.108786)
		(end 404.264876 -217.108786)
		(width 0.18288)
		(layer "In6.Cu")
		(net "M_G_CPU0_SB_DQ<15>")
	)
	(segment
		(start 387.680454 -231.563164)
		(end 387.680454 -231.875584)
		(width 0.088646)
		(layer "In6.Cu")
		(net "M_G_CPU0_SB_DQ<15>")
	)
	(segment
		(start 423.44721 -218.31935)
		(end 421.979852 -218.31935)
		(width 0.18288)
		(layer "In6.Cu")
		(net "M_G_CPU0_SB_DQ<15>")
	)
	(segment
		(start 421.979852 -218.31935)
		(end 421.304212 -218.99499)
		(width 0.18288)
		(layer "In6.Cu")
		(net "M_G_CPU0_SB_DQ<15>")
	)
	(segment
		(start 430.980088 -216.743026)
		(end 430.012094 -216.743026)
		(width 0.18288)
		(layer "In6.Cu")
		(net "M_G_CPU0_SB_DQ<15>")
	)
	(segment
		(start 420.210488 -218.99499)
		(end 420.04869 -218.833192)
		(width 0.18288)
		(layer "In6.Cu")
		(net "M_G_CPU0_SB_DQ<15>")
	)
	(segment
		(start 384.580384 -232.528364)
		(end 384.580384 -232.53827)
		(width 0.088646)
		(layer "In6.Cu")
		(net "M_G_CPU0_SB_DQ<15>")
	)
	(segment
		(start 423.62501 -218.14155)
		(end 423.44721 -218.31935)
		(width 0.18288)
		(layer "In6.Cu")
		(net "M_G_CPU0_SB_DQ<15>")
	)
	(segment
		(start 379.598682 -233.017822)
		(end 379.58395 -233.026458)
		(width 0.088646)
		(layer "In6.Cu")
		(net "M_G_CPU0_SB_DQ<15>")
	)
	(segment
		(start 390.09193 -231.281732)
		(end 388.114286 -231.281732)
		(width 0.18288)
		(layer "In6.Cu")
		(net "M_G_CPU0_SB_DQ<15>")
	)
	(segment
		(start 376.779282 -233.017822)
		(end 376.76455 -233.026458)
		(width 0.088646)
		(layer "In6.Cu")
		(net "M_G_CPU0_SB_DQ<15>")
	)
	(arc
		(start 378.093478 -233.017822)
		(mid 377.90628 -232.967679)
		(end 377.719082 -233.017822)
		(width 0.088646)
		(layer "In6.Cu")
		(net "M_G_CPU0_SB_DQ<15>")
	)
	(arc
		(start 379.58395 -233.026458)
		(mid 379.307475 -233.093778)
		(end 379.033278 -233.017822)
		(width 0.088646)
		(layer "In6.Cu")
		(net "M_G_CPU0_SB_DQ<15>")
	)
	(arc
		(start 377.70435 -233.026458)
		(mid 377.427875 -233.093778)
		(end 377.153678 -233.017822)
		(width 0.088646)
		(layer "In6.Cu")
		(net "M_G_CPU0_SB_DQ<15>")
	)
	(arc
		(start 383.358136 -233.017822)
		(mid 383.075434 -233.093598)
		(end 382.792732 -233.017822)
		(width 0.088646)
		(layer "In6.Cu")
		(net "M_G_CPU0_SB_DQ<15>")
	)
	(arc
		(start 385.142232 -232.204006)
		(mid 384.955034 -232.153863)
		(end 384.767836 -232.204006)
		(width 0.088646)
		(layer "In6.Cu")
		(net "M_G_CPU0_SB_DQ<15>")
	)
	(arc
		(start 380.913132 -233.017822)
		(mid 380.725934 -232.967679)
		(end 380.538736 -233.017822)
		(width 0.088646)
		(layer "In6.Cu")
		(net "M_G_CPU0_SB_DQ<15>")
	)
	(arc
		(start 385.707636 -232.204006)
		(mid 385.424934 -232.279782)
		(end 385.142232 -232.204006)
		(width 0.088646)
		(layer "In6.Cu")
		(net "M_G_CPU0_SB_DQ<15>")
	)
	(arc
		(start 384.297936 -233.017822)
		(mid 384.015234 -233.093598)
		(end 383.732532 -233.017822)
		(width 0.088646)
		(layer "In6.Cu")
		(net "M_G_CPU0_SB_DQ<15>")
	)
	(arc
		(start 382.792732 -233.017822)
		(mid 382.605534 -232.967679)
		(end 382.418336 -233.017822)
		(width 0.088646)
		(layer "In6.Cu")
		(net "M_G_CPU0_SB_DQ<15>")
	)
	(arc
		(start 386.082032 -232.204006)
		(mid 385.894834 -232.153863)
		(end 385.707636 -232.204006)
		(width 0.088646)
		(layer "In6.Cu")
		(net "M_G_CPU0_SB_DQ<15>")
	)
	(arc
		(start 384.758946 -232.209086)
		(mid 384.628032 -232.345446)
		(end 384.580384 -232.528364)
		(width 0.088646)
		(layer "In6.Cu")
		(net "M_G_CPU0_SB_DQ<15>")
	)
	(arc
		(start 380.528322 -233.023918)
		(mid 380.24989 -233.093764)
		(end 379.973078 -233.017822)
		(width 0.088646)
		(layer "In6.Cu")
		(net "M_G_CPU0_SB_DQ<15>")
	)
	(arc
		(start 381.478536 -233.017822)
		(mid 381.204337 -233.093657)
		(end 380.927864 -233.026458)
		(width 0.088646)
		(layer "In6.Cu")
		(net "M_G_CPU0_SB_DQ<15>")
	)
	(arc
		(start 375.830592 -233.022902)
		(mid 375.714853 -233.134726)
		(end 375.656602 -233.284776)
		(width 0.088646)
		(layer "In6.Cu")
		(net "M_G_CPU0_SB_DQ<15>")
	)
	(arc
		(start 386.647436 -232.204006)
		(mid 386.364734 -232.279782)
		(end 386.082032 -232.204006)
		(width 0.088646)
		(layer "In6.Cu")
		(net "M_G_CPU0_SB_DQ<15>")
	)
	(arc
		(start 383.732532 -233.017822)
		(mid 383.545334 -232.967679)
		(end 383.358136 -233.017822)
		(width 0.088646)
		(layer "In6.Cu")
		(net "M_G_CPU0_SB_DQ<15>")
	)
	(arc
		(start 386.848604 -232.154222)
		(mid 386.7445 -232.1649)
		(end 386.647436 -232.204006)
		(width 0.088646)
		(layer "In6.Cu")
		(net "M_G_CPU0_SB_DQ<15>")
	)
	(arc
		(start 379.973078 -233.017822)
		(mid 379.78588 -232.967679)
		(end 379.598682 -233.017822)
		(width 0.088646)
		(layer "In6.Cu")
		(net "M_G_CPU0_SB_DQ<15>")
	)
	(arc
		(start 376.213878 -233.017822)
		(mid 376.02668 -232.967679)
		(end 375.839482 -233.017822)
		(width 0.088646)
		(layer "In6.Cu")
		(net "M_G_CPU0_SB_DQ<15>")
	)
	(arc
		(start 384.580384 -232.53827)
		(mid 384.502273 -232.815219)
		(end 384.297936 -233.017822)
		(width 0.088646)
		(layer "In6.Cu")
		(net "M_G_CPU0_SB_DQ<15>")
	)
	(arc
		(start 381.852932 -233.017822)
		(mid 381.665734 -232.967679)
		(end 381.478536 -233.017822)
		(width 0.088646)
		(layer "In6.Cu")
		(net "M_G_CPU0_SB_DQ<15>")
	)
	(arc
		(start 382.418336 -233.017822)
		(mid 382.135634 -233.093598)
		(end 381.852932 -233.017822)
		(width 0.088646)
		(layer "In6.Cu")
		(net "M_G_CPU0_SB_DQ<15>")
	)
	(arc
		(start 376.76455 -233.026458)
		(mid 376.488075 -233.093778)
		(end 376.213878 -233.017822)
		(width 0.088646)
		(layer "In6.Cu")
		(net "M_G_CPU0_SB_DQ<15>")
	)
	(arc
		(start 378.64415 -233.026458)
		(mid 378.367675 -233.093778)
		(end 378.093478 -233.017822)
		(width 0.088646)
		(layer "In6.Cu")
		(net "M_G_CPU0_SB_DQ<15>")
	)
	(arc
		(start 379.033278 -233.017822)
		(mid 378.84608 -232.967679)
		(end 378.658882 -233.017822)
		(width 0.088646)
		(layer "In6.Cu")
		(net "M_G_CPU0_SB_DQ<15>")
	)
	(arc
		(start 377.153678 -233.017822)
		(mid 376.96648 -232.967679)
		(end 376.779282 -233.017822)
		(width 0.088646)
		(layer "In6.Cu")
		(net "M_G_CPU0_SB_DQ<15>")
	)
	(segment
		(start 443.450726 -216.44864)
		(end 443.455552 -216.44864)
		(width 0.101854)
		(layer "F.Cu")
		(net "M_G_CPU0_SB_DQ<14>")
	)
	(segment
		(start 442.726826 -216.016586)
		(end 443.15888 -216.44864)
		(width 0.20066)
		(layer "F.Cu")
		(net "M_G_CPU0_SB_DQ<14>")
	)
	(segment
		(start 439.923682 -216.016586)
		(end 441.028582 -216.016586)
		(width 0.20066)
		(layer "F.Cu")
		(net "M_G_CPU0_SB_DQ<14>")
	)
	(segment
		(start 443.462664 -216.441528)
		(end 445.470534 -216.441528)
		(width 0.1016)
		(layer "F.Cu")
		(net "M_G_CPU0_SB_DQ<14>")
	)
	(segment
		(start 443.455552 -216.44864)
		(end 443.462664 -216.441528)
		(width 0.1016)
		(layer "F.Cu")
		(net "M_G_CPU0_SB_DQ<14>")
	)
	(segment
		(start 446.367916 -215.998806)
		(end 446.602104 -215.764618)
		(width 0.20066)
		(layer "F.Cu")
		(net "M_G_CPU0_SB_DQ<14>")
	)
	(segment
		(start 445.470534 -216.441528)
		(end 445.482726 -216.45372)
		(width 0.1016)
		(layer "F.Cu")
		(net "M_G_CPU0_SB_DQ<14>")
	)
	(segment
		(start 446.163954 -216.45372)
		(end 446.367916 -216.249758)
		(width 0.20066)
		(layer "F.Cu")
		(net "M_G_CPU0_SB_DQ<14>")
	)
	(segment
		(start 441.028582 -216.016586)
		(end 442.726826 -216.016586)
		(width 0.20066)
		(layer "F.Cu")
		(net "M_G_CPU0_SB_DQ<14>")
	)
	(segment
		(start 446.367916 -216.249758)
		(end 446.367916 -215.998806)
		(width 0.20066)
		(layer "F.Cu")
		(net "M_G_CPU0_SB_DQ<14>")
	)
	(segment
		(start 445.482726 -216.45372)
		(end 446.163954 -216.45372)
		(width 0.20066)
		(layer "F.Cu")
		(net "M_G_CPU0_SB_DQ<14>")
	)
	(segment
		(start 446.602104 -215.764618)
		(end 446.986152 -215.764618)
		(width 0.20066)
		(layer "F.Cu")
		(net "M_G_CPU0_SB_DQ<14>")
	)
	(segment
		(start 446.986152 -215.764618)
		(end 447.23812 -216.016586)
		(width 0.20066)
		(layer "F.Cu")
		(net "M_G_CPU0_SB_DQ<14>")
	)
	(segment
		(start 376.49658 -234.69219)
		(end 376.496834 -234.691936)
		(width 0.20066)
		(layer "F.Cu")
		(net "M_G_CPU0_SB_DQ<14>")
	)
	(segment
		(start 443.15888 -216.44864)
		(end 443.450726 -216.44864)
		(width 0.20066)
		(layer "F.Cu")
		(net "M_G_CPU0_SB_DQ<14>")
	)
	(segment
		(start 376.496834 -234.691936)
		(end 376.496834 -234.15625)
		(width 0.20066)
		(layer "F.Cu")
		(net "M_G_CPU0_SB_DQ<14>")
	)
	(segment
		(start 447.23812 -216.016586)
		(end 448.572382 -216.016586)
		(width 0.20066)
		(layer "F.Cu")
		(net "M_G_CPU0_SB_DQ<14>")
	)
	(segment
		(start 385.237736 -233.017822)
		(end 385.228846 -233.022902)
		(width 0.088646)
		(layer "In6.Cu")
		(net "M_G_CPU0_SB_DQ<14>")
	)
	(segment
		(start 380.068836 -233.831892)
		(end 380.061216 -233.835956)
		(width 0.088646)
		(layer "In6.Cu")
		(net "M_G_CPU0_SB_DQ<14>")
	)
	(segment
		(start 379.133354 -233.829098)
		(end 379.121416 -233.835956)
		(width 0.088646)
		(layer "In6.Cu")
		(net "M_G_CPU0_SB_DQ<14>")
	)
	(segment
		(start 411.139894 -218.165426)
		(end 410.631894 -218.673426)
		(width 0.18288)
		(layer "In6.Cu")
		(net "M_G_CPU0_SB_DQ<14>")
	)
	(segment
		(start 414.757616 -218.658948)
		(end 414.264094 -218.165426)
		(width 0.18288)
		(layer "In6.Cu")
		(net "M_G_CPU0_SB_DQ<14>")
	)
	(segment
		(start 410.631894 -218.673426)
		(end 409.184602 -218.673426)
		(width 0.18288)
		(layer "In6.Cu")
		(net "M_G_CPU0_SB_DQ<14>")
	)
	(segment
		(start 436.943246 -218.142058)
		(end 435.272688 -218.142058)
		(width 0.18288)
		(layer "In6.Cu")
		(net "M_G_CPU0_SB_DQ<14>")
	)
	(segment
		(start 414.746948 -219.650564)
		(end 414.515046 -219.418662)
		(width 0.18288)
		(layer "In6.Cu")
		(net "M_G_CPU0_SB_DQ<14>")
	)
	(segment
		(start 414.264094 -218.165426)
		(end 411.139894 -218.165426)
		(width 0.18288)
		(layer "In6.Cu")
		(net "M_G_CPU0_SB_DQ<14>")
	)
	(segment
		(start 409.184602 -218.673426)
		(end 408.954986 -218.903042)
		(width 0.18288)
		(layer "In6.Cu")
		(net "M_G_CPU0_SB_DQ<14>")
	)
	(segment
		(start 430.410112 -218.986608)
		(end 426.752512 -218.986608)
		(width 0.18288)
		(layer "In6.Cu")
		(net "M_G_CPU0_SB_DQ<14>")
	)
	(segment
		(start 377.253754 -233.829098)
		(end 376.852688 -234.060746)
		(width 0.088646)
		(layer "In6.Cu")
		(net "M_G_CPU0_SB_DQ<14>")
	)
	(segment
		(start 390.529572 -232.29189)
		(end 388.114286 -232.29189)
		(width 0.18288)
		(layer "In6.Cu")
		(net "M_G_CPU0_SB_DQ<14>")
	)
	(segment
		(start 378.188982 -233.831638)
		(end 378.181616 -233.835956)
		(width 0.088646)
		(layer "In6.Cu")
		(net "M_G_CPU0_SB_DQ<14>")
	)
	(segment
		(start 414.515046 -219.16009)
		(end 414.757616 -218.91752)
		(width 0.18288)
		(layer "In6.Cu")
		(net "M_G_CPU0_SB_DQ<14>")
	)
	(segment
		(start 414.757616 -218.91752)
		(end 414.757616 -218.658948)
		(width 0.18288)
		(layer "In6.Cu")
		(net "M_G_CPU0_SB_DQ<14>")
	)
	(segment
		(start 378.193554 -233.829098)
		(end 378.188982 -233.831638)
		(width 0.088646)
		(layer "In6.Cu")
		(net "M_G_CPU0_SB_DQ<14>")
	)
	(segment
		(start 387.885432 -232.29189)
		(end 387.278118 -232.899204)
		(width 0.088646)
		(layer "In6.Cu")
		(net "M_G_CPU0_SB_DQ<14>")
	)
	(segment
		(start 408.286966 -218.673426)
		(end 404.244556 -218.673426)
		(width 0.18288)
		(layer "In6.Cu")
		(net "M_G_CPU0_SB_DQ<14>")
	)
	(segment
		(start 426.752512 -218.986608)
		(end 425.898056 -219.841064)
		(width 0.18288)
		(layer "In6.Cu")
		(net "M_G_CPU0_SB_DQ<14>")
	)
	(segment
		(start 416.792156 -220.693488)
		(end 415.506662 -219.407994)
		(width 0.18288)
		(layer "In6.Cu")
		(net "M_G_CPU0_SB_DQ<14>")
	)
	(segment
		(start 415.00552 -219.650564)
		(end 414.746948 -219.650564)
		(width 0.18288)
		(layer "In6.Cu")
		(net "M_G_CPU0_SB_DQ<14>")
	)
	(segment
		(start 404.244556 -218.673426)
		(end 390.694418 -232.223564)
		(width 0.18288)
		(layer "In6.Cu")
		(net "M_G_CPU0_SB_DQ<14>")
	)
	(segment
		(start 408.516582 -218.903042)
		(end 408.286966 -218.673426)
		(width 0.18288)
		(layer "In6.Cu")
		(net "M_G_CPU0_SB_DQ<14>")
	)
	(segment
		(start 439.923682 -216.016586)
		(end 439.068718 -216.016586)
		(width 0.18288)
		(layer "In6.Cu")
		(net "M_G_CPU0_SB_DQ<14>")
	)
	(segment
		(start 385.050284 -233.34218)
		(end 385.050284 -233.360722)
		(width 0.088646)
		(layer "In6.Cu")
		(net "M_G_CPU0_SB_DQ<14>")
	)
	(segment
		(start 431.495454 -217.901266)
		(end 430.410112 -218.986608)
		(width 0.18288)
		(layer "In6.Cu")
		(net "M_G_CPU0_SB_DQ<14>")
	)
	(segment
		(start 435.031896 -217.901266)
		(end 431.495454 -217.901266)
		(width 0.18288)
		(layer "In6.Cu")
		(net "M_G_CPU0_SB_DQ<14>")
	)
	(segment
		(start 408.954986 -218.903042)
		(end 408.516582 -218.903042)
		(width 0.18288)
		(layer "In6.Cu")
		(net "M_G_CPU0_SB_DQ<14>")
	)
	(segment
		(start 439.068718 -216.016586)
		(end 436.943246 -218.142058)
		(width 0.18288)
		(layer "In6.Cu")
		(net "M_G_CPU0_SB_DQ<14>")
	)
	(segment
		(start 425.898056 -219.841064)
		(end 422.291256 -219.841064)
		(width 0.18288)
		(layer "In6.Cu")
		(net "M_G_CPU0_SB_DQ<14>")
	)
	(segment
		(start 388.114286 -232.29189)
		(end 387.885432 -232.29189)
		(width 0.088646)
		(layer "In6.Cu")
		(net "M_G_CPU0_SB_DQ<14>")
	)
	(segment
		(start 421.438832 -220.693488)
		(end 416.792156 -220.693488)
		(width 0.18288)
		(layer "In6.Cu")
		(net "M_G_CPU0_SB_DQ<14>")
	)
	(segment
		(start 422.291256 -219.841064)
		(end 421.438832 -220.693488)
		(width 0.18288)
		(layer "In6.Cu")
		(net "M_G_CPU0_SB_DQ<14>")
	)
	(segment
		(start 415.24809 -219.407994)
		(end 415.00552 -219.650564)
		(width 0.18288)
		(layer "In6.Cu")
		(net "M_G_CPU0_SB_DQ<14>")
	)
	(segment
		(start 414.515046 -219.418662)
		(end 414.515046 -219.16009)
		(width 0.18288)
		(layer "In6.Cu")
		(net "M_G_CPU0_SB_DQ<14>")
	)
	(segment
		(start 415.506662 -219.407994)
		(end 415.24809 -219.407994)
		(width 0.18288)
		(layer "In6.Cu")
		(net "M_G_CPU0_SB_DQ<14>")
	)
	(segment
		(start 435.272688 -218.142058)
		(end 435.031896 -217.901266)
		(width 0.18288)
		(layer "In6.Cu")
		(net "M_G_CPU0_SB_DQ<14>")
	)
	(arc
		(start 376.852688 -234.060746)
		(mid 376.681057 -234.131973)
		(end 376.496834 -234.15625)
		(width 0.088646)
		(layer "In6.Cu")
		(net "M_G_CPU0_SB_DQ<14>")
	)
	(arc
		(start 387.0706 -233.042206)
		(mid 386.808306 -233.093065)
		(end 386.551932 -233.017822)
		(width 0.088646)
		(layer "In6.Cu")
		(net "M_G_CPU0_SB_DQ<14>")
	)
	(arc
		(start 381.948436 -233.831892)
		(mid 381.665734 -233.907634)
		(end 381.383032 -233.831892)
		(width 0.088646)
		(layer "In6.Cu")
		(net "M_G_CPU0_SB_DQ<14>")
	)
	(arc
		(start 381.008636 -233.831892)
		(mid 380.725934 -233.907634)
		(end 380.443232 -233.831892)
		(width 0.088646)
		(layer "In6.Cu")
		(net "M_G_CPU0_SB_DQ<14>")
	)
	(arc
		(start 383.262632 -233.831892)
		(mid 383.075434 -233.781749)
		(end 382.888236 -233.831892)
		(width 0.088646)
		(layer "In6.Cu")
		(net "M_G_CPU0_SB_DQ<14>")
	)
	(arc
		(start 387.074156 -233.040428)
		(mid 387.072377 -233.041314)
		(end 387.0706 -233.042206)
		(width 0.088646)
		(layer "In6.Cu")
		(net "M_G_CPU0_SB_DQ<14>")
	)
	(arc
		(start 386.177536 -233.017822)
		(mid 385.894834 -233.093598)
		(end 385.612132 -233.017822)
		(width 0.088646)
		(layer "In6.Cu")
		(net "M_G_CPU0_SB_DQ<14>")
	)
	(arc
		(start 382.888236 -233.831892)
		(mid 382.605534 -233.907634)
		(end 382.322832 -233.831892)
		(width 0.088646)
		(layer "In6.Cu")
		(net "M_G_CPU0_SB_DQ<14>")
	)
	(arc
		(start 381.383032 -233.831892)
		(mid 381.195834 -233.781749)
		(end 381.008636 -233.831892)
		(width 0.088646)
		(layer "In6.Cu")
		(net "M_G_CPU0_SB_DQ<14>")
	)
	(arc
		(start 384.767836 -233.831892)
		(mid 384.485134 -233.907634)
		(end 384.202432 -233.831892)
		(width 0.088646)
		(layer "In6.Cu")
		(net "M_G_CPU0_SB_DQ<14>")
	)
	(arc
		(start 382.322832 -233.831892)
		(mid 382.135634 -233.781749)
		(end 381.948436 -233.831892)
		(width 0.088646)
		(layer "In6.Cu")
		(net "M_G_CPU0_SB_DQ<14>")
	)
	(arc
		(start 383.828036 -233.831892)
		(mid 383.545334 -233.907634)
		(end 383.262632 -233.831892)
		(width 0.088646)
		(layer "In6.Cu")
		(net "M_G_CPU0_SB_DQ<14>")
	)
	(arc
		(start 378.181616 -233.835956)
		(mid 377.902155 -233.907393)
		(end 377.623832 -233.831638)
		(width 0.088646)
		(layer "In6.Cu")
		(net "M_G_CPU0_SB_DQ<14>")
	)
	(arc
		(start 380.443232 -233.831892)
		(mid 380.256034 -233.781749)
		(end 380.068836 -233.831892)
		(width 0.088646)
		(layer "In6.Cu")
		(net "M_G_CPU0_SB_DQ<14>")
	)
	(arc
		(start 384.202432 -233.831892)
		(mid 384.015234 -233.781749)
		(end 383.828036 -233.831892)
		(width 0.088646)
		(layer "In6.Cu")
		(net "M_G_CPU0_SB_DQ<14>")
	)
	(arc
		(start 379.121416 -233.835956)
		(mid 378.841955 -233.907393)
		(end 378.563632 -233.831638)
		(width 0.088646)
		(layer "In6.Cu")
		(net "M_G_CPU0_SB_DQ<14>")
	)
	(arc
		(start 379.503432 -233.831638)
		(mid 379.318738 -233.781537)
		(end 379.133354 -233.829098)
		(width 0.088646)
		(layer "In6.Cu")
		(net "M_G_CPU0_SB_DQ<14>")
	)
	(arc
		(start 378.563632 -233.831638)
		(mid 378.378938 -233.781537)
		(end 378.193554 -233.829098)
		(width 0.088646)
		(layer "In6.Cu")
		(net "M_G_CPU0_SB_DQ<14>")
	)
	(arc
		(start 380.061216 -233.835956)
		(mid 379.781755 -233.907393)
		(end 379.503432 -233.831638)
		(width 0.088646)
		(layer "In6.Cu")
		(net "M_G_CPU0_SB_DQ<14>")
	)
	(arc
		(start 385.228846 -233.022902)
		(mid 385.097932 -233.159262)
		(end 385.050284 -233.34218)
		(width 0.088646)
		(layer "In6.Cu")
		(net "M_G_CPU0_SB_DQ<14>")
	)
	(arc
		(start 377.623832 -233.831638)
		(mid 377.439138 -233.781537)
		(end 377.253754 -233.829098)
		(width 0.088646)
		(layer "In6.Cu")
		(net "M_G_CPU0_SB_DQ<14>")
	)
	(arc
		(start 386.551932 -233.017822)
		(mid 386.364734 -232.967679)
		(end 386.177536 -233.017822)
		(width 0.088646)
		(layer "In6.Cu")
		(net "M_G_CPU0_SB_DQ<14>")
	)
	(arc
		(start 385.612132 -233.017822)
		(mid 385.424934 -232.967679)
		(end 385.237736 -233.017822)
		(width 0.088646)
		(layer "In6.Cu")
		(net "M_G_CPU0_SB_DQ<14>")
	)
	(arc
		(start 385.050284 -233.360722)
		(mid 384.970122 -233.632911)
		(end 384.767836 -233.831892)
		(width 0.088646)
		(layer "In6.Cu")
		(net "M_G_CPU0_SB_DQ<14>")
	)
	(arc
		(start 390.694418 -232.223564)
		(mid 390.6188 -232.274153)
		(end 390.529572 -232.29189)
		(width 0.18288)
		(layer "In6.Cu")
		(net "M_G_CPU0_SB_DQ<14>")
	)
	(arc
		(start 387.278118 -232.899204)
		(mid 387.182497 -232.979004)
		(end 387.074156 -233.040428)
		(width 0.088646)
		(layer "In6.Cu")
		(net "M_G_CPU0_SB_DQ<14>")
	)
	(segment
		(start 439.173112 -215.415368)
		(end 438.697878 -215.415368)
		(width 0.20066)
		(layer "F.Cu")
		(net "M_G_CPU0_SB_DQ<13>")
	)
	(segment
		(start 375.087134 -233.87812)
		(end 375.08688 -233.877866)
		(width 0.20066)
		(layer "F.Cu")
		(net "M_G_CPU0_SB_DQ<13>")
	)
	(segment
		(start 439.843926 -214.74176)
		(end 439.82386 -214.74176)
		(width 0.101854)
		(layer "F.Cu")
		(net "M_G_CPU0_SB_DQ<13>")
	)
	(segment
		(start 442.032644 -214.74176)
		(end 439.843926 -214.74176)
		(width 0.1016)
		(layer "F.Cu")
		(net "M_G_CPU0_SB_DQ<13>")
	)
	(segment
		(start 439.82386 -214.74176)
		(end 439.479182 -214.74176)
		(width 0.20066)
		(layer "F.Cu")
		(net "M_G_CPU0_SB_DQ<13>")
	)
	(segment
		(start 444.472314 -215.166702)
		(end 444.47206 -215.166956)
		(width 0.20066)
		(layer "F.Cu")
		(net "M_G_CPU0_SB_DQ<13>")
	)
	(segment
		(start 375.08688 -233.877866)
		(end 375.08688 -233.34218)
		(width 0.20066)
		(layer "F.Cu")
		(net "M_G_CPU0_SB_DQ<13>")
	)
	(segment
		(start 444.47206 -215.166956)
		(end 442.880496 -215.166956)
		(width 0.20066)
		(layer "F.Cu")
		(net "M_G_CPU0_SB_DQ<13>")
	)
	(segment
		(start 439.479182 -214.74176)
		(end 439.361072 -214.85987)
		(width 0.20066)
		(layer "F.Cu")
		(net "M_G_CPU0_SB_DQ<13>")
	)
	(segment
		(start 442.880496 -215.166956)
		(end 442.44895 -214.73541)
		(width 0.20066)
		(layer "F.Cu")
		(net "M_G_CPU0_SB_DQ<13>")
	)
	(segment
		(start 442.44895 -214.73541)
		(end 442.038994 -214.73541)
		(width 0.20066)
		(layer "F.Cu")
		(net "M_G_CPU0_SB_DQ<13>")
	)
	(segment
		(start 442.038994 -214.73541)
		(end 442.032644 -214.74176)
		(width 0.1016)
		(layer "F.Cu")
		(net "M_G_CPU0_SB_DQ<13>")
	)
	(segment
		(start 438.449212 -215.166702)
		(end 436.928514 -215.166702)
		(width 0.20066)
		(layer "F.Cu")
		(net "M_G_CPU0_SB_DQ<13>")
	)
	(segment
		(start 439.361072 -215.227408)
		(end 439.173112 -215.415368)
		(width 0.20066)
		(layer "F.Cu")
		(net "M_G_CPU0_SB_DQ<13>")
	)
	(segment
		(start 436.928514 -215.166702)
		(end 435.823614 -215.166702)
		(width 0.20066)
		(layer "F.Cu")
		(net "M_G_CPU0_SB_DQ<13>")
	)
	(segment
		(start 438.697878 -215.415368)
		(end 438.449212 -215.166702)
		(width 0.20066)
		(layer "F.Cu")
		(net "M_G_CPU0_SB_DQ<13>")
	)
	(segment
		(start 439.361072 -214.85987)
		(end 439.361072 -215.227408)
		(width 0.20066)
		(layer "F.Cu")
		(net "M_G_CPU0_SB_DQ<13>")
	)
	(segment
		(start 379.518164 -232.844086)
		(end 379.503432 -232.852722)
		(width 0.088646)
		(layer "In6.Cu")
		(net "M_G_CPU0_SB_DQ<13>")
	)
	(segment
		(start 412.37916 -215.701626)
		(end 410.150056 -215.701626)
		(width 0.18288)
		(layer "In6.Cu")
		(net "M_G_CPU0_SB_DQ<13>")
	)
	(segment
		(start 406.528524 -216.30005)
		(end 406.528524 -216.425272)
		(width 0.18288)
		(layer "In6.Cu")
		(net "M_G_CPU0_SB_DQ<13>")
	)
	(segment
		(start 427.878494 -216.692226)
		(end 427.192694 -217.378026)
		(width 0.18288)
		(layer "In6.Cu")
		(net "M_G_CPU0_SB_DQ<13>")
	)
	(segment
		(start 389.90397 -230.749094)
		(end 388.00151 -230.749094)
		(width 0.18288)
		(layer "In6.Cu")
		(net "M_G_CPU0_SB_DQ<13>")
	)
	(segment
		(start 410.150056 -215.701626)
		(end 409.24353 -216.608152)
		(width 0.18288)
		(layer "In6.Cu")
		(net "M_G_CPU0_SB_DQ<13>")
	)
	(segment
		(start 421.137334 -218.14409)
		(end 419.786562 -218.14409)
		(width 0.18288)
		(layer "In6.Cu")
		(net "M_G_CPU0_SB_DQ<13>")
	)
	(segment
		(start 384.211322 -232.847642)
		(end 384.202432 -232.852722)
		(width 0.088646)
		(layer "In6.Cu")
		(net "M_G_CPU0_SB_DQ<13>")
	)
	(segment
		(start 388.00151 -230.749094)
		(end 387.62432 -230.749094)
		(width 0.088646)
		(layer "In6.Cu")
		(net "M_G_CPU0_SB_DQ<13>")
	)
	(segment
		(start 378.578364 -232.844086)
		(end 378.563632 -232.852722)
		(width 0.088646)
		(layer "In6.Cu")
		(net "M_G_CPU0_SB_DQ<13>")
	)
	(segment
		(start 413.971994 -215.473026)
		(end 412.60776 -215.473026)
		(width 0.18288)
		(layer "In6.Cu")
		(net "M_G_CPU0_SB_DQ<13>")
	)
	(segment
		(start 375.46534 -233.276394)
		(end 375.399554 -233.34218)
		(width 0.088646)
		(layer "In6.Cu")
		(net "M_G_CPU0_SB_DQ<13>")
	)
	(segment
		(start 422.313354 -216.96807)
		(end 421.137334 -218.14409)
		(width 0.18288)
		(layer "In6.Cu")
		(net "M_G_CPU0_SB_DQ<13>")
	)
	(segment
		(start 430.329594 -215.485726)
		(end 429.123094 -216.692226)
		(width 0.18288)
		(layer "In6.Cu")
		(net "M_G_CPU0_SB_DQ<13>")
	)
	(segment
		(start 423.43451 -217.294968)
		(end 423.107612 -216.96807)
		(width 0.18288)
		(layer "In6.Cu")
		(net "M_G_CPU0_SB_DQ<13>")
	)
	(segment
		(start 409.24353 -216.608152)
		(end 407.404824 -216.608152)
		(width 0.18288)
		(layer "In6.Cu")
		(net "M_G_CPU0_SB_DQ<13>")
	)
	(segment
		(start 427.192694 -217.378026)
		(end 426.596302 -217.378026)
		(width 0.18288)
		(layer "In6.Cu")
		(net "M_G_CPU0_SB_DQ<13>")
	)
	(segment
		(start 407.221944 -216.30005)
		(end 407.039064 -216.11717)
		(width 0.18288)
		(layer "In6.Cu")
		(net "M_G_CPU0_SB_DQ<13>")
	)
	(segment
		(start 375.744232 -232.852722)
		(end 375.738136 -232.856278)
		(width 0.088646)
		(layer "In6.Cu")
		(net "M_G_CPU0_SB_DQ<13>")
	)
	(segment
		(start 377.638564 -232.844086)
		(end 377.623832 -232.852722)
		(width 0.088646)
		(layer "In6.Cu")
		(net "M_G_CPU0_SB_DQ<13>")
	)
	(segment
		(start 406.528524 -216.425272)
		(end 406.345644 -216.608152)
		(width 0.18288)
		(layer "In6.Cu")
		(net "M_G_CPU0_SB_DQ<13>")
	)
	(segment
		(start 431.98923 -215.804242)
		(end 431.670714 -215.485726)
		(width 0.18288)
		(layer "In6.Cu")
		(net "M_G_CPU0_SB_DQ<13>")
	)
	(segment
		(start 418.006022 -217.563954)
		(end 417.74745 -217.563954)
		(width 0.18288)
		(layer "In6.Cu")
		(net "M_G_CPU0_SB_DQ<13>")
	)
	(segment
		(start 414.759394 -215.854026)
		(end 414.352994 -215.854026)
		(width 0.18288)
		(layer "In6.Cu")
		(net "M_G_CPU0_SB_DQ<13>")
	)
	(segment
		(start 407.404824 -216.608152)
		(end 407.221944 -216.425272)
		(width 0.18288)
		(layer "In6.Cu")
		(net "M_G_CPU0_SB_DQ<13>")
	)
	(segment
		(start 417.673282 -216.03081)
		(end 416.345878 -216.03081)
		(width 0.18288)
		(layer "In6.Cu")
		(net "M_G_CPU0_SB_DQ<13>")
	)
	(segment
		(start 376.698764 -232.844086)
		(end 376.684032 -232.852722)
		(width 0.088646)
		(layer "In6.Cu")
		(net "M_G_CPU0_SB_DQ<13>")
	)
	(segment
		(start 426.436282 -217.218006)
		(end 426.436282 -216.81059)
		(width 0.18288)
		(layer "In6.Cu")
		(net "M_G_CPU0_SB_DQ<13>")
	)
	(segment
		(start 412.60776 -215.473026)
		(end 412.37916 -215.701626)
		(width 0.18288)
		(layer "In6.Cu")
		(net "M_G_CPU0_SB_DQ<13>")
	)
	(segment
		(start 415.140394 -215.473026)
		(end 414.759394 -215.854026)
		(width 0.18288)
		(layer "In6.Cu")
		(net "M_G_CPU0_SB_DQ<13>")
	)
	(segment
		(start 431.670714 -215.485726)
		(end 430.329594 -215.485726)
		(width 0.18288)
		(layer "In6.Cu")
		(net "M_G_CPU0_SB_DQ<13>")
	)
	(segment
		(start 417.986464 -216.602564)
		(end 417.986464 -216.343992)
		(width 0.18288)
		(layer "In6.Cu")
		(net "M_G_CPU0_SB_DQ<13>")
	)
	(segment
		(start 418.73551 -217.093038)
		(end 418.476938 -217.093038)
		(width 0.18288)
		(layer "In6.Cu")
		(net "M_G_CPU0_SB_DQ<13>")
	)
	(segment
		(start 429.123094 -216.692226)
		(end 427.878494 -216.692226)
		(width 0.18288)
		(layer "In6.Cu")
		(net "M_G_CPU0_SB_DQ<13>")
	)
	(segment
		(start 435.823614 -215.166702)
		(end 435.186074 -215.804242)
		(width 0.18288)
		(layer "In6.Cu")
		(net "M_G_CPU0_SB_DQ<13>")
	)
	(segment
		(start 381.008382 -232.852722)
		(end 380.997968 -232.846626)
		(width 0.088646)
		(layer "In6.Cu")
		(net "M_G_CPU0_SB_DQ<13>")
	)
	(segment
		(start 375.758964 -232.844086)
		(end 375.744232 -232.852722)
		(width 0.088646)
		(layer "In6.Cu")
		(net "M_G_CPU0_SB_DQ<13>")
	)
	(segment
		(start 435.186074 -215.804242)
		(end 431.98923 -215.804242)
		(width 0.18288)
		(layer "In6.Cu")
		(net "M_G_CPU0_SB_DQ<13>")
	)
	(segment
		(start 415.788094 -215.473026)
		(end 415.140394 -215.473026)
		(width 0.18288)
		(layer "In6.Cu")
		(net "M_G_CPU0_SB_DQ<13>")
	)
	(segment
		(start 426.436282 -216.81059)
		(end 426.253402 -216.62771)
		(width 0.18288)
		(layer "In6.Cu")
		(net "M_G_CPU0_SB_DQ<13>")
	)
	(segment
		(start 426.253402 -216.62771)
		(end 425.739052 -216.62771)
		(width 0.18288)
		(layer "In6.Cu")
		(net "M_G_CPU0_SB_DQ<13>")
	)
	(segment
		(start 384.389884 -232.518458)
		(end 384.389884 -232.528364)
		(width 0.088646)
		(layer "In6.Cu")
		(net "M_G_CPU0_SB_DQ<13>")
	)
	(segment
		(start 414.352994 -215.854026)
		(end 413.971994 -215.473026)
		(width 0.18288)
		(layer "In6.Cu")
		(net "M_G_CPU0_SB_DQ<13>")
	)
	(segment
		(start 407.039064 -216.11717)
		(end 406.711404 -216.11717)
		(width 0.18288)
		(layer "In6.Cu")
		(net "M_G_CPU0_SB_DQ<13>")
	)
	(segment
		(start 416.345878 -216.03081)
		(end 415.788094 -215.473026)
		(width 0.18288)
		(layer "In6.Cu")
		(net "M_G_CPU0_SB_DQ<13>")
	)
	(segment
		(start 381.948436 -232.852722)
		(end 381.938022 -232.846626)
		(width 0.088646)
		(layer "In6.Cu")
		(net "M_G_CPU0_SB_DQ<13>")
	)
	(segment
		(start 404.044912 -216.608152)
		(end 389.90397 -230.749094)
		(width 0.18288)
		(layer "In6.Cu")
		(net "M_G_CPU0_SB_DQ<13>")
	)
	(segment
		(start 407.221944 -216.425272)
		(end 407.221944 -216.30005)
		(width 0.18288)
		(layer "In6.Cu")
		(net "M_G_CPU0_SB_DQ<13>")
	)
	(segment
		(start 417.74745 -217.563954)
		(end 417.515548 -217.332052)
		(width 0.18288)
		(layer "In6.Cu")
		(net "M_G_CPU0_SB_DQ<13>")
	)
	(segment
		(start 375.399554 -233.34218)
		(end 375.08688 -233.34218)
		(width 0.088646)
		(layer "In6.Cu")
		(net "M_G_CPU0_SB_DQ<13>")
	)
	(segment
		(start 387.62432 -230.749094)
		(end 386.921248 -231.452166)
		(width 0.088646)
		(layer "In6.Cu")
		(net "M_G_CPU0_SB_DQ<13>")
	)
	(segment
		(start 406.711404 -216.11717)
		(end 406.528524 -216.30005)
		(width 0.18288)
		(layer "In6.Cu")
		(net "M_G_CPU0_SB_DQ<13>")
	)
	(segment
		(start 426.596302 -217.378026)
		(end 426.436282 -217.218006)
		(width 0.18288)
		(layer "In6.Cu")
		(net "M_G_CPU0_SB_DQ<13>")
	)
	(segment
		(start 425.071794 -217.294968)
		(end 423.43451 -217.294968)
		(width 0.18288)
		(layer "In6.Cu")
		(net "M_G_CPU0_SB_DQ<13>")
	)
	(segment
		(start 418.476938 -217.093038)
		(end 418.006022 -217.563954)
		(width 0.18288)
		(layer "In6.Cu")
		(net "M_G_CPU0_SB_DQ<13>")
	)
	(segment
		(start 423.107612 -216.96807)
		(end 422.313354 -216.96807)
		(width 0.18288)
		(layer "In6.Cu")
		(net "M_G_CPU0_SB_DQ<13>")
	)
	(segment
		(start 417.515548 -217.332052)
		(end 417.515548 -217.07348)
		(width 0.18288)
		(layer "In6.Cu")
		(net "M_G_CPU0_SB_DQ<13>")
	)
	(segment
		(start 425.739052 -216.62771)
		(end 425.071794 -217.294968)
		(width 0.18288)
		(layer "In6.Cu")
		(net "M_G_CPU0_SB_DQ<13>")
	)
	(segment
		(start 406.345644 -216.608152)
		(end 404.044912 -216.608152)
		(width 0.18288)
		(layer "In6.Cu")
		(net "M_G_CPU0_SB_DQ<13>")
	)
	(segment
		(start 417.515548 -217.07348)
		(end 417.986464 -216.602564)
		(width 0.18288)
		(layer "In6.Cu")
		(net "M_G_CPU0_SB_DQ<13>")
	)
	(segment
		(start 419.786562 -218.14409)
		(end 418.73551 -217.093038)
		(width 0.18288)
		(layer "In6.Cu")
		(net "M_G_CPU0_SB_DQ<13>")
	)
	(segment
		(start 417.986464 -216.343992)
		(end 417.673282 -216.03081)
		(width 0.18288)
		(layer "In6.Cu")
		(net "M_G_CPU0_SB_DQ<13>")
	)
	(arc
		(start 379.129036 -232.852722)
		(mid 378.854837 -232.776887)
		(end 378.578364 -232.844086)
		(width 0.088646)
		(layer "In6.Cu")
		(net "M_G_CPU0_SB_DQ<13>")
	)
	(arc
		(start 385.237736 -232.038906)
		(mid 384.955034 -231.96313)
		(end 384.672332 -232.038906)
		(width 0.088646)
		(layer "In6.Cu")
		(net "M_G_CPU0_SB_DQ<13>")
	)
	(arc
		(start 383.262632 -232.852722)
		(mid 383.075434 -232.902865)
		(end 382.888236 -232.852722)
		(width 0.088646)
		(layer "In6.Cu")
		(net "M_G_CPU0_SB_DQ<13>")
	)
	(arc
		(start 376.309636 -232.852722)
		(mid 376.035437 -232.776887)
		(end 375.758964 -232.844086)
		(width 0.088646)
		(layer "In6.Cu")
		(net "M_G_CPU0_SB_DQ<13>")
	)
	(arc
		(start 386.889752 -231.535478)
		(mid 386.895454 -231.590884)
		(end 386.905246 -231.645714)
		(width 0.088646)
		(layer "In6.Cu")
		(net "M_G_CPU0_SB_DQ<13>")
	)
	(arc
		(start 383.828036 -232.852722)
		(mid 383.545334 -232.776946)
		(end 383.262632 -232.852722)
		(width 0.088646)
		(layer "In6.Cu")
		(net "M_G_CPU0_SB_DQ<13>")
	)
	(arc
		(start 380.997968 -232.846626)
		(mid 380.71979 -232.776903)
		(end 380.443232 -232.852722)
		(width 0.088646)
		(layer "In6.Cu")
		(net "M_G_CPU0_SB_DQ<13>")
	)
	(arc
		(start 382.322832 -232.852722)
		(mid 382.135634 -232.902865)
		(end 381.948436 -232.852722)
		(width 0.088646)
		(layer "In6.Cu")
		(net "M_G_CPU0_SB_DQ<13>")
	)
	(arc
		(start 384.389884 -232.528364)
		(mid 384.342205 -232.711264)
		(end 384.211322 -232.847642)
		(width 0.088646)
		(layer "In6.Cu")
		(net "M_G_CPU0_SB_DQ<13>")
	)
	(arc
		(start 377.623832 -232.852722)
		(mid 377.436634 -232.902865)
		(end 377.249436 -232.852722)
		(width 0.088646)
		(layer "In6.Cu")
		(net "M_G_CPU0_SB_DQ<13>")
	)
	(arc
		(start 378.189236 -232.852722)
		(mid 377.915037 -232.776887)
		(end 377.638564 -232.844086)
		(width 0.088646)
		(layer "In6.Cu")
		(net "M_G_CPU0_SB_DQ<13>")
	)
	(arc
		(start 386.905246 -231.645714)
		(mid 386.869182 -231.855034)
		(end 386.697474 -231.979978)
		(width 0.088646)
		(layer "In6.Cu")
		(net "M_G_CPU0_SB_DQ<13>")
	)
	(arc
		(start 386.177536 -232.038906)
		(mid 385.894834 -231.96313)
		(end 385.612132 -232.038906)
		(width 0.088646)
		(layer "In6.Cu")
		(net "M_G_CPU0_SB_DQ<13>")
	)
	(arc
		(start 377.249436 -232.852722)
		(mid 376.975237 -232.776887)
		(end 376.698764 -232.844086)
		(width 0.088646)
		(layer "In6.Cu")
		(net "M_G_CPU0_SB_DQ<13>")
	)
	(arc
		(start 381.382778 -232.852722)
		(mid 381.19558 -232.902865)
		(end 381.008382 -232.852722)
		(width 0.088646)
		(layer "In6.Cu")
		(net "M_G_CPU0_SB_DQ<13>")
	)
	(arc
		(start 378.563632 -232.852722)
		(mid 378.376434 -232.902865)
		(end 378.189236 -232.852722)
		(width 0.088646)
		(layer "In6.Cu")
		(net "M_G_CPU0_SB_DQ<13>")
	)
	(arc
		(start 386.921248 -231.452166)
		(mid 386.896468 -231.490405)
		(end 386.889752 -231.535478)
		(width 0.088646)
		(layer "In6.Cu")
		(net "M_G_CPU0_SB_DQ<13>")
	)
	(arc
		(start 382.888236 -232.852722)
		(mid 382.605534 -232.776946)
		(end 382.322832 -232.852722)
		(width 0.088646)
		(layer "In6.Cu")
		(net "M_G_CPU0_SB_DQ<13>")
	)
	(arc
		(start 381.938022 -232.846626)
		(mid 381.65959 -232.77678)
		(end 381.382778 -232.852722)
		(width 0.088646)
		(layer "In6.Cu")
		(net "M_G_CPU0_SB_DQ<13>")
	)
	(arc
		(start 384.672332 -232.038906)
		(mid 384.467997 -232.241511)
		(end 384.389884 -232.518458)
		(width 0.088646)
		(layer "In6.Cu")
		(net "M_G_CPU0_SB_DQ<13>")
	)
	(arc
		(start 380.068836 -232.852722)
		(mid 379.794637 -232.776887)
		(end 379.518164 -232.844086)
		(width 0.088646)
		(layer "In6.Cu")
		(net "M_G_CPU0_SB_DQ<13>")
	)
	(arc
		(start 384.202432 -232.852722)
		(mid 384.015234 -232.902865)
		(end 383.828036 -232.852722)
		(width 0.088646)
		(layer "In6.Cu")
		(net "M_G_CPU0_SB_DQ<13>")
	)
	(arc
		(start 380.443232 -232.852722)
		(mid 380.256034 -232.902865)
		(end 380.068836 -232.852722)
		(width 0.088646)
		(layer "In6.Cu")
		(net "M_G_CPU0_SB_DQ<13>")
	)
	(arc
		(start 385.612132 -232.038906)
		(mid 385.424934 -232.089049)
		(end 385.237736 -232.038906)
		(width 0.088646)
		(layer "In6.Cu")
		(net "M_G_CPU0_SB_DQ<13>")
	)
	(arc
		(start 379.503432 -232.852722)
		(mid 379.316234 -232.902865)
		(end 379.129036 -232.852722)
		(width 0.088646)
		(layer "In6.Cu")
		(net "M_G_CPU0_SB_DQ<13>")
	)
	(arc
		(start 376.684032 -232.852722)
		(mid 376.496834 -232.902865)
		(end 376.309636 -232.852722)
		(width 0.088646)
		(layer "In6.Cu")
		(net "M_G_CPU0_SB_DQ<13>")
	)
	(arc
		(start 386.551932 -232.038906)
		(mid 386.364734 -232.089049)
		(end 386.177536 -232.038906)
		(width 0.088646)
		(layer "In6.Cu")
		(net "M_G_CPU0_SB_DQ<13>")
	)
	(arc
		(start 386.697474 -231.979978)
		(mid 386.622652 -232.004374)
		(end 386.551932 -232.038906)
		(width 0.088646)
		(layer "In6.Cu")
		(net "M_G_CPU0_SB_DQ<13>")
	)
	(arc
		(start 375.738136 -232.856278)
		(mid 375.552681 -233.034473)
		(end 375.46534 -233.276394)
		(width 0.088646)
		(layer "In6.Cu")
		(net "M_G_CPU0_SB_DQ<13>")
	)
	(segment
		(start 444.472314 -216.866724)
		(end 444.47206 -216.866978)
		(width 0.20066)
		(layer "F.Cu")
		(net "M_G_CPU0_SB_DQ<12>")
	)
	(segment
		(start 439.82386 -216.441782)
		(end 439.479182 -216.441782)
		(width 0.20066)
		(layer "F.Cu")
		(net "M_G_CPU0_SB_DQ<12>")
	)
	(segment
		(start 438.697878 -217.11539)
		(end 438.449212 -216.866724)
		(width 0.20066)
		(layer "F.Cu")
		(net "M_G_CPU0_SB_DQ<12>")
	)
	(segment
		(start 374.617234 -234.691936)
		(end 374.617234 -234.15625)
		(width 0.20066)
		(layer "F.Cu")
		(net "M_G_CPU0_SB_DQ<12>")
	)
	(segment
		(start 374.61698 -234.69219)
		(end 374.617234 -234.691936)
		(width 0.20066)
		(layer "F.Cu")
		(net "M_G_CPU0_SB_DQ<12>")
	)
	(segment
		(start 439.87085 -216.441782)
		(end 439.82386 -216.441782)
		(width 0.101854)
		(layer "F.Cu")
		(net "M_G_CPU0_SB_DQ<12>")
	)
	(segment
		(start 442.038994 -216.435432)
		(end 442.032644 -216.441782)
		(width 0.1016)
		(layer "F.Cu")
		(net "M_G_CPU0_SB_DQ<12>")
	)
	(segment
		(start 444.47206 -216.866978)
		(end 442.880496 -216.866978)
		(width 0.20066)
		(layer "F.Cu")
		(net "M_G_CPU0_SB_DQ<12>")
	)
	(segment
		(start 439.361072 -216.92743)
		(end 439.173112 -217.11539)
		(width 0.20066)
		(layer "F.Cu")
		(net "M_G_CPU0_SB_DQ<12>")
	)
	(segment
		(start 442.44895 -216.435432)
		(end 442.038994 -216.435432)
		(width 0.20066)
		(layer "F.Cu")
		(net "M_G_CPU0_SB_DQ<12>")
	)
	(segment
		(start 438.449212 -216.866724)
		(end 436.928514 -216.866724)
		(width 0.20066)
		(layer "F.Cu")
		(net "M_G_CPU0_SB_DQ<12>")
	)
	(segment
		(start 436.928514 -216.866724)
		(end 435.823614 -216.866724)
		(width 0.20066)
		(layer "F.Cu")
		(net "M_G_CPU0_SB_DQ<12>")
	)
	(segment
		(start 439.361072 -216.559892)
		(end 439.361072 -216.92743)
		(width 0.20066)
		(layer "F.Cu")
		(net "M_G_CPU0_SB_DQ<12>")
	)
	(segment
		(start 439.479182 -216.441782)
		(end 439.361072 -216.559892)
		(width 0.20066)
		(layer "F.Cu")
		(net "M_G_CPU0_SB_DQ<12>")
	)
	(segment
		(start 439.173112 -217.11539)
		(end 438.697878 -217.11539)
		(width 0.20066)
		(layer "F.Cu")
		(net "M_G_CPU0_SB_DQ<12>")
	)
	(segment
		(start 442.880496 -216.866978)
		(end 442.44895 -216.435432)
		(width 0.20066)
		(layer "F.Cu")
		(net "M_G_CPU0_SB_DQ<12>")
	)
	(segment
		(start 442.032644 -216.441782)
		(end 439.87085 -216.441782)
		(width 0.1016)
		(layer "F.Cu")
		(net "M_G_CPU0_SB_DQ<12>")
	)
	(segment
		(start 434.029104 -217.297508)
		(end 433.741068 -217.009472)
		(width 0.18288)
		(layer "In6.Cu")
		(net "M_G_CPU0_SB_DQ<12>")
	)
	(segment
		(start 429.029622 -218.462098)
		(end 426.097192 -218.462098)
		(width 0.18288)
		(layer "In6.Cu")
		(net "M_G_CPU0_SB_DQ<12>")
	)
	(segment
		(start 387.980936 -231.779572)
		(end 387.870446 -231.890062)
		(width 0.088646)
		(layer "In6.Cu")
		(net "M_G_CPU0_SB_DQ<12>")
	)
	(segment
		(start 418.382196 -219.668852)
		(end 418.222176 -219.828872)
		(width 0.18288)
		(layer "In6.Cu")
		(net "M_G_CPU0_SB_DQ<12>")
	)
	(segment
		(start 390.349486 -231.779572)
		(end 388.114286 -231.779572)
		(width 0.18288)
		(layer "In6.Cu")
		(net "M_G_CPU0_SB_DQ<12>")
	)
	(segment
		(start 417.375594 -220.006672)
		(end 416.91814 -220.006672)
		(width 0.18288)
		(layer "In6.Cu")
		(net "M_G_CPU0_SB_DQ<12>")
	)
	(segment
		(start 418.542216 -219.016072)
		(end 418.382196 -219.176092)
		(width 0.18288)
		(layer "In6.Cu")
		(net "M_G_CPU0_SB_DQ<12>")
	)
	(segment
		(start 416.49015 -218.282774)
		(end 416.26409 -218.282774)
		(width 0.18288)
		(layer "In6.Cu")
		(net "M_G_CPU0_SB_DQ<12>")
	)
	(segment
		(start 378.658882 -233.666538)
		(end 378.64415 -233.657902)
		(width 0.088646)
		(layer "In6.Cu")
		(net "M_G_CPU0_SB_DQ<12>")
	)
	(segment
		(start 388.114286 -231.779572)
		(end 387.980936 -231.779572)
		(width 0.088646)
		(layer "In6.Cu")
		(net "M_G_CPU0_SB_DQ<12>")
	)
	(segment
		(start 430.197006 -217.294714)
		(end 429.029622 -218.462098)
		(width 0.18288)
		(layer "In6.Cu")
		(net "M_G_CPU0_SB_DQ<12>")
	)
	(segment
		(start 414.203642 -217.292174)
		(end 410.87294 -217.292174)
		(width 0.18288)
		(layer "In6.Cu")
		(net "M_G_CPU0_SB_DQ<12>")
	)
	(segment
		(start 387.304534 -232.560876)
		(end 387.09092 -232.790746)
		(width 0.088646)
		(layer "In6.Cu")
		(net "M_G_CPU0_SB_DQ<12>")
	)
	(segment
		(start 416.754564 -218.547188)
		(end 416.49015 -218.282774)
		(width 0.18288)
		(layer "In6.Cu")
		(net "M_G_CPU0_SB_DQ<12>")
	)
	(segment
		(start 424.643296 -218.992196)
		(end 424.36542 -219.270072)
		(width 0.18288)
		(layer "In6.Cu")
		(net "M_G_CPU0_SB_DQ<12>")
	)
	(segment
		(start 380.538736 -233.666538)
		(end 380.528322 -233.660442)
		(width 0.088646)
		(layer "In6.Cu")
		(net "M_G_CPU0_SB_DQ<12>")
	)
	(segment
		(start 384.681222 -233.661458)
		(end 384.672332 -233.666538)
		(width 0.088646)
		(layer "In6.Cu")
		(net "M_G_CPU0_SB_DQ<12>")
	)
	(segment
		(start 375.246392 -233.682286)
		(end 374.617234 -234.15625)
		(width 0.088646)
		(layer "In6.Cu")
		(net "M_G_CPU0_SB_DQ<12>")
	)
	(segment
		(start 419.075616 -219.176092)
		(end 418.915596 -219.016072)
		(width 0.18288)
		(layer "In6.Cu")
		(net "M_G_CPU0_SB_DQ<12>")
	)
	(segment
		(start 403.968966 -218.160092)
		(end 390.349486 -231.779572)
		(width 0.18288)
		(layer "In6.Cu")
		(net "M_G_CPU0_SB_DQ<12>")
	)
	(segment
		(start 418.222176 -219.828872)
		(end 417.553394 -219.828872)
		(width 0.18288)
		(layer "In6.Cu")
		(net "M_G_CPU0_SB_DQ<12>")
	)
	(segment
		(start 384.859784 -233.332274)
		(end 384.859784 -233.34218)
		(width 0.088646)
		(layer "In6.Cu")
		(net "M_G_CPU0_SB_DQ<12>")
	)
	(segment
		(start 417.553394 -219.828872)
		(end 417.375594 -220.006672)
		(width 0.18288)
		(layer "In6.Cu")
		(net "M_G_CPU0_SB_DQ<12>")
	)
	(segment
		(start 435.39283 -217.297508)
		(end 434.029104 -217.297508)
		(width 0.18288)
		(layer "In6.Cu")
		(net "M_G_CPU0_SB_DQ<12>")
	)
	(segment
		(start 376.779282 -233.666538)
		(end 376.76455 -233.657902)
		(width 0.088646)
		(layer "In6.Cu")
		(net "M_G_CPU0_SB_DQ<12>")
	)
	(segment
		(start 415.842196 -218.704668)
		(end 415.616136 -218.704668)
		(width 0.18288)
		(layer "In6.Cu")
		(net "M_G_CPU0_SB_DQ<12>")
	)
	(segment
		(start 421.212518 -219.842334)
		(end 419.249098 -219.842334)
		(width 0.18288)
		(layer "In6.Cu")
		(net "M_G_CPU0_SB_DQ<12>")
	)
	(segment
		(start 422.97858 -219.270072)
		(end 422.563036 -219.270072)
		(width 0.18288)
		(layer "In6.Cu")
		(net "M_G_CPU0_SB_DQ<12>")
	)
	(segment
		(start 418.382196 -219.176092)
		(end 418.382196 -219.668852)
		(width 0.18288)
		(layer "In6.Cu")
		(net "M_G_CPU0_SB_DQ<12>")
	)
	(segment
		(start 433.050442 -217.294714)
		(end 430.197006 -217.294714)
		(width 0.18288)
		(layer "In6.Cu")
		(net "M_G_CPU0_SB_DQ<12>")
	)
	(segment
		(start 410.87294 -217.292174)
		(end 410.005022 -218.160092)
		(width 0.18288)
		(layer "In6.Cu")
		(net "M_G_CPU0_SB_DQ<12>")
	)
	(segment
		(start 422.062656 -218.992196)
		(end 421.212518 -219.842334)
		(width 0.18288)
		(layer "In6.Cu")
		(net "M_G_CPU0_SB_DQ<12>")
	)
	(segment
		(start 410.005022 -218.160092)
		(end 403.968966 -218.160092)
		(width 0.18288)
		(layer "In6.Cu")
		(net "M_G_CPU0_SB_DQ<12>")
	)
	(segment
		(start 423.949876 -219.270072)
		(end 423.672 -218.992196)
		(width 0.18288)
		(layer "In6.Cu")
		(net "M_G_CPU0_SB_DQ<12>")
	)
	(segment
		(start 387.870446 -231.994964)
		(end 387.304534 -232.560876)
		(width 0.088646)
		(layer "In6.Cu")
		(net "M_G_CPU0_SB_DQ<12>")
	)
	(segment
		(start 387.870446 -231.890062)
		(end 387.870446 -231.994964)
		(width 0.088646)
		(layer "In6.Cu")
		(net "M_G_CPU0_SB_DQ<12>")
	)
	(segment
		(start 416.91814 -220.006672)
		(end 416.33267 -219.421202)
		(width 0.18288)
		(layer "In6.Cu")
		(net "M_G_CPU0_SB_DQ<12>")
	)
	(segment
		(start 426.097192 -218.462098)
		(end 425.567094 -218.992196)
		(width 0.18288)
		(layer "In6.Cu")
		(net "M_G_CPU0_SB_DQ<12>")
	)
	(segment
		(start 416.33267 -219.421202)
		(end 416.33267 -219.195142)
		(width 0.18288)
		(layer "In6.Cu")
		(net "M_G_CPU0_SB_DQ<12>")
	)
	(segment
		(start 422.28516 -218.992196)
		(end 422.062656 -218.992196)
		(width 0.18288)
		(layer "In6.Cu")
		(net "M_G_CPU0_SB_DQ<12>")
	)
	(segment
		(start 375.274078 -233.666538)
		(end 375.246392 -233.682286)
		(width 0.088646)
		(layer "In6.Cu")
		(net "M_G_CPU0_SB_DQ<12>")
	)
	(segment
		(start 379.598682 -233.666538)
		(end 379.58395 -233.657902)
		(width 0.088646)
		(layer "In6.Cu")
		(net "M_G_CPU0_SB_DQ<12>")
	)
	(segment
		(start 423.256456 -218.992196)
		(end 422.97858 -219.270072)
		(width 0.18288)
		(layer "In6.Cu")
		(net "M_G_CPU0_SB_DQ<12>")
	)
	(segment
		(start 419.075616 -219.668852)
		(end 419.075616 -219.176092)
		(width 0.18288)
		(layer "In6.Cu")
		(net "M_G_CPU0_SB_DQ<12>")
	)
	(segment
		(start 425.567094 -218.992196)
		(end 424.643296 -218.992196)
		(width 0.18288)
		(layer "In6.Cu")
		(net "M_G_CPU0_SB_DQ<12>")
	)
	(segment
		(start 424.36542 -219.270072)
		(end 423.949876 -219.270072)
		(width 0.18288)
		(layer "In6.Cu")
		(net "M_G_CPU0_SB_DQ<12>")
	)
	(segment
		(start 415.616136 -218.704668)
		(end 414.203642 -217.292174)
		(width 0.18288)
		(layer "In6.Cu")
		(net "M_G_CPU0_SB_DQ<12>")
	)
	(segment
		(start 423.672 -218.992196)
		(end 423.256456 -218.992196)
		(width 0.18288)
		(layer "In6.Cu")
		(net "M_G_CPU0_SB_DQ<12>")
	)
	(segment
		(start 375.839482 -233.666538)
		(end 375.82475 -233.657902)
		(width 0.088646)
		(layer "In6.Cu")
		(net "M_G_CPU0_SB_DQ<12>")
	)
	(segment
		(start 418.915596 -219.016072)
		(end 418.542216 -219.016072)
		(width 0.18288)
		(layer "In6.Cu")
		(net "M_G_CPU0_SB_DQ<12>")
	)
	(segment
		(start 416.754564 -218.773248)
		(end 416.754564 -218.547188)
		(width 0.18288)
		(layer "In6.Cu")
		(net "M_G_CPU0_SB_DQ<12>")
	)
	(segment
		(start 422.563036 -219.270072)
		(end 422.28516 -218.992196)
		(width 0.18288)
		(layer "In6.Cu")
		(net "M_G_CPU0_SB_DQ<12>")
	)
	(segment
		(start 435.823614 -216.866724)
		(end 435.39283 -217.297508)
		(width 0.18288)
		(layer "In6.Cu")
		(net "M_G_CPU0_SB_DQ<12>")
	)
	(segment
		(start 433.335684 -217.009472)
		(end 433.050442 -217.294714)
		(width 0.18288)
		(layer "In6.Cu")
		(net "M_G_CPU0_SB_DQ<12>")
	)
	(segment
		(start 433.741068 -217.009472)
		(end 433.335684 -217.009472)
		(width 0.18288)
		(layer "In6.Cu")
		(net "M_G_CPU0_SB_DQ<12>")
	)
	(segment
		(start 416.33267 -219.195142)
		(end 416.754564 -218.773248)
		(width 0.18288)
		(layer "In6.Cu")
		(net "M_G_CPU0_SB_DQ<12>")
	)
	(segment
		(start 419.249098 -219.842334)
		(end 419.075616 -219.668852)
		(width 0.18288)
		(layer "In6.Cu")
		(net "M_G_CPU0_SB_DQ<12>")
	)
	(segment
		(start 416.26409 -218.282774)
		(end 415.842196 -218.704668)
		(width 0.18288)
		(layer "In6.Cu")
		(net "M_G_CPU0_SB_DQ<12>")
	)
	(arc
		(start 378.093478 -233.666538)
		(mid 377.90628 -233.716681)
		(end 377.719082 -233.666538)
		(width 0.088646)
		(layer "In6.Cu")
		(net "M_G_CPU0_SB_DQ<12>")
	)
	(arc
		(start 382.418336 -233.666538)
		(mid 382.135634 -233.590796)
		(end 381.852932 -233.666538)
		(width 0.088646)
		(layer "In6.Cu")
		(net "M_G_CPU0_SB_DQ<12>")
	)
	(arc
		(start 386.819902 -232.90276)
		(mid 386.730618 -232.888249)
		(end 386.647436 -232.852722)
		(width 0.088646)
		(layer "In6.Cu")
		(net "M_G_CPU0_SB_DQ<12>")
	)
	(arc
		(start 387.09092 -232.790746)
		(mid 386.967651 -232.876335)
		(end 386.819902 -232.90276)
		(width 0.088646)
		(layer "In6.Cu")
		(net "M_G_CPU0_SB_DQ<12>")
	)
	(arc
		(start 384.297936 -233.666538)
		(mid 384.015234 -233.590796)
		(end 383.732532 -233.666538)
		(width 0.088646)
		(layer "In6.Cu")
		(net "M_G_CPU0_SB_DQ<12>")
	)
	(arc
		(start 384.672332 -233.666538)
		(mid 384.485134 -233.716681)
		(end 384.297936 -233.666538)
		(width 0.088646)
		(layer "In6.Cu")
		(net "M_G_CPU0_SB_DQ<12>")
	)
	(arc
		(start 383.732532 -233.666538)
		(mid 383.545334 -233.716681)
		(end 383.358136 -233.666538)
		(width 0.088646)
		(layer "In6.Cu")
		(net "M_G_CPU0_SB_DQ<12>")
	)
	(arc
		(start 382.792732 -233.666538)
		(mid 382.605534 -233.716681)
		(end 382.418336 -233.666538)
		(width 0.088646)
		(layer "In6.Cu")
		(net "M_G_CPU0_SB_DQ<12>")
	)
	(arc
		(start 380.913132 -233.666538)
		(mid 380.725934 -233.716681)
		(end 380.538736 -233.666538)
		(width 0.088646)
		(layer "In6.Cu")
		(net "M_G_CPU0_SB_DQ<12>")
	)
	(arc
		(start 386.647436 -232.852722)
		(mid 386.364734 -232.776946)
		(end 386.082032 -232.852722)
		(width 0.088646)
		(layer "In6.Cu")
		(net "M_G_CPU0_SB_DQ<12>")
	)
	(arc
		(start 376.213878 -233.666538)
		(mid 376.02668 -233.716681)
		(end 375.839482 -233.666538)
		(width 0.088646)
		(layer "In6.Cu")
		(net "M_G_CPU0_SB_DQ<12>")
	)
	(arc
		(start 375.82475 -233.657902)
		(mid 375.548309 -233.590736)
		(end 375.274078 -233.666538)
		(width 0.088646)
		(layer "In6.Cu")
		(net "M_G_CPU0_SB_DQ<12>")
	)
	(arc
		(start 381.478536 -233.666538)
		(mid 381.195834 -233.590796)
		(end 380.913132 -233.666538)
		(width 0.088646)
		(layer "In6.Cu")
		(net "M_G_CPU0_SB_DQ<12>")
	)
	(arc
		(start 379.58395 -233.657902)
		(mid 379.307509 -233.590736)
		(end 379.033278 -233.666538)
		(width 0.088646)
		(layer "In6.Cu")
		(net "M_G_CPU0_SB_DQ<12>")
	)
	(arc
		(start 378.64415 -233.657902)
		(mid 378.367709 -233.590736)
		(end 378.093478 -233.666538)
		(width 0.088646)
		(layer "In6.Cu")
		(net "M_G_CPU0_SB_DQ<12>")
	)
	(arc
		(start 385.707636 -232.852722)
		(mid 385.424934 -232.776946)
		(end 385.142232 -232.852722)
		(width 0.088646)
		(layer "In6.Cu")
		(net "M_G_CPU0_SB_DQ<12>")
	)
	(arc
		(start 380.528322 -233.660442)
		(mid 380.24989 -233.590628)
		(end 379.973078 -233.666538)
		(width 0.088646)
		(layer "In6.Cu")
		(net "M_G_CPU0_SB_DQ<12>")
	)
	(arc
		(start 377.153678 -233.666538)
		(mid 376.96648 -233.716681)
		(end 376.779282 -233.666538)
		(width 0.088646)
		(layer "In6.Cu")
		(net "M_G_CPU0_SB_DQ<12>")
	)
	(arc
		(start 379.033278 -233.666538)
		(mid 378.84608 -233.716681)
		(end 378.658882 -233.666538)
		(width 0.088646)
		(layer "In6.Cu")
		(net "M_G_CPU0_SB_DQ<12>")
	)
	(arc
		(start 383.358136 -233.666538)
		(mid 383.075434 -233.590796)
		(end 382.792732 -233.666538)
		(width 0.088646)
		(layer "In6.Cu")
		(net "M_G_CPU0_SB_DQ<12>")
	)
	(arc
		(start 385.142232 -232.852722)
		(mid 384.937897 -233.055327)
		(end 384.859784 -233.332274)
		(width 0.088646)
		(layer "In6.Cu")
		(net "M_G_CPU0_SB_DQ<12>")
	)
	(arc
		(start 377.719082 -233.666538)
		(mid 377.43638 -233.590796)
		(end 377.153678 -233.666538)
		(width 0.088646)
		(layer "In6.Cu")
		(net "M_G_CPU0_SB_DQ<12>")
	)
	(arc
		(start 379.973078 -233.666538)
		(mid 379.78588 -233.716681)
		(end 379.598682 -233.666538)
		(width 0.088646)
		(layer "In6.Cu")
		(net "M_G_CPU0_SB_DQ<12>")
	)
	(arc
		(start 384.859784 -233.34218)
		(mid 384.812105 -233.52508)
		(end 384.681222 -233.661458)
		(width 0.088646)
		(layer "In6.Cu")
		(net "M_G_CPU0_SB_DQ<12>")
	)
	(arc
		(start 386.082032 -232.852722)
		(mid 385.894834 -232.902865)
		(end 385.707636 -232.852722)
		(width 0.088646)
		(layer "In6.Cu")
		(net "M_G_CPU0_SB_DQ<12>")
	)
	(arc
		(start 376.76455 -233.657902)
		(mid 376.488109 -233.590736)
		(end 376.213878 -233.666538)
		(width 0.088646)
		(layer "In6.Cu")
		(net "M_G_CPU0_SB_DQ<12>")
	)
	(arc
		(start 381.852932 -233.666538)
		(mid 381.665734 -233.716681)
		(end 381.478536 -233.666538)
		(width 0.088646)
		(layer "In6.Cu")
		(net "M_G_CPU0_SB_DQ<12>")
	)
	(segment
		(start 445.482726 -220.703902)
		(end 446.163954 -220.703902)
		(width 0.20066)
		(layer "F.Cu")
		(net "M_G_CPU0_SB_DQ<11>")
	)
	(segment
		(start 443.450726 -220.698822)
		(end 443.455552 -220.698822)
		(width 0.101854)
		(layer "F.Cu")
		(net "M_G_CPU0_SB_DQ<11>")
	)
	(segment
		(start 446.602104 -220.0148)
		(end 446.986152 -220.0148)
		(width 0.20066)
		(layer "F.Cu")
		(net "M_G_CPU0_SB_DQ<11>")
	)
	(segment
		(start 446.367916 -220.248988)
		(end 446.602104 -220.0148)
		(width 0.20066)
		(layer "F.Cu")
		(net "M_G_CPU0_SB_DQ<11>")
	)
	(segment
		(start 446.163954 -220.703902)
		(end 446.367916 -220.49994)
		(width 0.20066)
		(layer "F.Cu")
		(net "M_G_CPU0_SB_DQ<11>")
	)
	(segment
		(start 446.367916 -220.49994)
		(end 446.367916 -220.248988)
		(width 0.20066)
		(layer "F.Cu")
		(net "M_G_CPU0_SB_DQ<11>")
	)
	(segment
		(start 439.923682 -220.266768)
		(end 441.028582 -220.266768)
		(width 0.20066)
		(layer "F.Cu")
		(net "M_G_CPU0_SB_DQ<11>")
	)
	(segment
		(start 445.470534 -220.69171)
		(end 445.482726 -220.703902)
		(width 0.1016)
		(layer "F.Cu")
		(net "M_G_CPU0_SB_DQ<11>")
	)
	(segment
		(start 441.028582 -220.266768)
		(end 442.726826 -220.266768)
		(width 0.20066)
		(layer "F.Cu")
		(net "M_G_CPU0_SB_DQ<11>")
	)
	(segment
		(start 443.15888 -220.698822)
		(end 443.450726 -220.698822)
		(width 0.20066)
		(layer "F.Cu")
		(net "M_G_CPU0_SB_DQ<11>")
	)
	(segment
		(start 376.496834 -236.319568)
		(end 376.496834 -235.783882)
		(width 0.20066)
		(layer "F.Cu")
		(net "M_G_CPU0_SB_DQ<11>")
	)
	(segment
		(start 376.49658 -236.319822)
		(end 376.496834 -236.319568)
		(width 0.20066)
		(layer "F.Cu")
		(net "M_G_CPU0_SB_DQ<11>")
	)
	(segment
		(start 443.455552 -220.698822)
		(end 443.462664 -220.69171)
		(width 0.1016)
		(layer "F.Cu")
		(net "M_G_CPU0_SB_DQ<11>")
	)
	(segment
		(start 443.462664 -220.69171)
		(end 445.470534 -220.69171)
		(width 0.1016)
		(layer "F.Cu")
		(net "M_G_CPU0_SB_DQ<11>")
	)
	(segment
		(start 442.726826 -220.266768)
		(end 443.15888 -220.698822)
		(width 0.20066)
		(layer "F.Cu")
		(net "M_G_CPU0_SB_DQ<11>")
	)
	(segment
		(start 446.986152 -220.0148)
		(end 447.23812 -220.266768)
		(width 0.20066)
		(layer "F.Cu")
		(net "M_G_CPU0_SB_DQ<11>")
	)
	(segment
		(start 447.23812 -220.266768)
		(end 448.572382 -220.266768)
		(width 0.20066)
		(layer "F.Cu")
		(net "M_G_CPU0_SB_DQ<11>")
	)
	(segment
		(start 438.648348 -221.542102)
		(end 435.651402 -221.542102)
		(width 0.18288)
		(layer "In6.Cu")
		(net "M_G_CPU0_SB_DQ<11>")
	)
	(segment
		(start 435.651402 -221.542102)
		(end 435.312058 -221.881446)
		(width 0.18288)
		(layer "In6.Cu")
		(net "M_G_CPU0_SB_DQ<11>")
	)
	(segment
		(start 433.829206 -221.36989)
		(end 433.646326 -221.18701)
		(width 0.18288)
		(layer "In6.Cu")
		(net "M_G_CPU0_SB_DQ<11>")
	)
	(segment
		(start 387.565646 -235.535216)
		(end 387.30428 -235.535216)
		(width 0.088646)
		(layer "In6.Cu")
		(net "M_G_CPU0_SB_DQ<11>")
	)
	(segment
		(start 379.598682 -236.273594)
		(end 379.58395 -236.28223)
		(width 0.088646)
		(layer "In6.Cu")
		(net "M_G_CPU0_SB_DQ<11>")
	)
	(segment
		(start 426.268896 -223.982026)
		(end 425.30903 -224.941892)
		(width 0.18288)
		(layer "In6.Cu")
		(net "M_G_CPU0_SB_DQ<11>")
	)
	(segment
		(start 433.135786 -221.36989)
		(end 433.135786 -221.698566)
		(width 0.18288)
		(layer "In6.Cu")
		(net "M_G_CPU0_SB_DQ<11>")
	)
	(segment
		(start 386.177282 -236.273594)
		(end 386.16255 -236.28223)
		(width 0.088646)
		(layer "In6.Cu")
		(net "M_G_CPU0_SB_DQ<11>")
	)
	(segment
		(start 388.162546 -234.939332)
		(end 387.970776 -234.939332)
		(width 0.088646)
		(layer "In6.Cu")
		(net "M_G_CPU0_SB_DQ<11>")
	)
	(segment
		(start 421.36949 -225.79203)
		(end 416.861498 -225.79203)
		(width 0.18288)
		(layer "In6.Cu")
		(net "M_G_CPU0_SB_DQ<11>")
	)
	(segment
		(start 407.366724 -222.966026)
		(end 407.206704 -223.126046)
		(width 0.18288)
		(layer "In6.Cu")
		(net "M_G_CPU0_SB_DQ<11>")
	)
	(segment
		(start 386.647436 -235.459524)
		(end 386.638546 -235.464604)
		(width 0.088646)
		(layer "In6.Cu")
		(net "M_G_CPU0_SB_DQ<11>")
	)
	(segment
		(start 387.869684 -235.231178)
		(end 387.565646 -235.535216)
		(width 0.088646)
		(layer "In6.Cu")
		(net "M_G_CPU0_SB_DQ<11>")
	)
	(segment
		(start 411.416246 -223.24187)
		(end 409.231338 -223.24187)
		(width 0.18288)
		(layer "In6.Cu")
		(net "M_G_CPU0_SB_DQ<11>")
	)
	(segment
		(start 425.30903 -224.941892)
		(end 422.219628 -224.941892)
		(width 0.18288)
		(layer "In6.Cu")
		(net "M_G_CPU0_SB_DQ<11>")
	)
	(segment
		(start 383.357882 -236.273594)
		(end 383.347468 -236.27969)
		(width 0.088646)
		(layer "In6.Cu")
		(net "M_G_CPU0_SB_DQ<11>")
	)
	(segment
		(start 439.923682 -220.266768)
		(end 438.648348 -221.542102)
		(width 0.18288)
		(layer "In6.Cu")
		(net "M_G_CPU0_SB_DQ<11>")
	)
	(segment
		(start 381.478536 -236.273594)
		(end 381.468122 -236.27969)
		(width 0.088646)
		(layer "In6.Cu")
		(net "M_G_CPU0_SB_DQ<11>")
	)
	(segment
		(start 377.153932 -236.273594)
		(end 377.161298 -236.277658)
		(width 0.088646)
		(layer "In6.Cu")
		(net "M_G_CPU0_SB_DQ<11>")
	)
	(segment
		(start 377.161298 -236.277658)
		(end 377.055126 -236.215428)
		(width 0.088646)
		(layer "In6.Cu")
		(net "M_G_CPU0_SB_DQ<11>")
	)
	(segment
		(start 409.231338 -223.24187)
		(end 408.955494 -222.966026)
		(width 0.18288)
		(layer "In6.Cu")
		(net "M_G_CPU0_SB_DQ<11>")
	)
	(segment
		(start 432.952906 -221.881446)
		(end 431.718974 -221.881446)
		(width 0.18288)
		(layer "In6.Cu")
		(net "M_G_CPU0_SB_DQ<11>")
	)
	(segment
		(start 415.841434 -224.771966)
		(end 414.825942 -224.771966)
		(width 0.18288)
		(layer "In6.Cu")
		(net "M_G_CPU0_SB_DQ<11>")
	)
	(segment
		(start 433.829206 -221.698566)
		(end 433.829206 -221.36989)
		(width 0.18288)
		(layer "In6.Cu")
		(net "M_G_CPU0_SB_DQ<11>")
	)
	(segment
		(start 414.643062 -224.954846)
		(end 414.643062 -225.3869)
		(width 0.18288)
		(layer "In6.Cu")
		(net "M_G_CPU0_SB_DQ<11>")
	)
	(segment
		(start 406.67305 -223.600264)
		(end 406.502616 -223.42983)
		(width 0.18288)
		(layer "In6.Cu")
		(net "M_G_CPU0_SB_DQ<11>")
	)
	(segment
		(start 414.460182 -225.56978)
		(end 414.132522 -225.56978)
		(width 0.18288)
		(layer "In6.Cu")
		(net "M_G_CPU0_SB_DQ<11>")
	)
	(segment
		(start 386.459984 -235.783882)
		(end 386.459984 -235.798106)
		(width 0.088646)
		(layer "In6.Cu")
		(net "M_G_CPU0_SB_DQ<11>")
	)
	(segment
		(start 407.206704 -223.41459)
		(end 407.02103 -223.600264)
		(width 0.18288)
		(layer "In6.Cu")
		(net "M_G_CPU0_SB_DQ<11>")
	)
	(segment
		(start 413.949642 -224.954846)
		(end 413.766762 -224.771966)
		(width 0.18288)
		(layer "In6.Cu")
		(net "M_G_CPU0_SB_DQ<11>")
	)
	(segment
		(start 385.237482 -236.273594)
		(end 385.22275 -236.28223)
		(width 0.088646)
		(layer "In6.Cu")
		(net "M_G_CPU0_SB_DQ<11>")
	)
	(segment
		(start 391.94232 -234.939332)
		(end 388.162546 -234.939332)
		(width 0.18288)
		(layer "In6.Cu")
		(net "M_G_CPU0_SB_DQ<11>")
	)
	(segment
		(start 412.946342 -224.771966)
		(end 411.416246 -223.24187)
		(width 0.18288)
		(layer "In6.Cu")
		(net "M_G_CPU0_SB_DQ<11>")
	)
	(segment
		(start 414.643062 -225.3869)
		(end 414.460182 -225.56978)
		(width 0.18288)
		(layer "In6.Cu")
		(net "M_G_CPU0_SB_DQ<11>")
	)
	(segment
		(start 377.719082 -236.273594)
		(end 377.708668 -236.27969)
		(width 0.088646)
		(layer "In6.Cu")
		(net "M_G_CPU0_SB_DQ<11>")
	)
	(segment
		(start 403.915626 -222.966026)
		(end 391.94232 -234.939332)
		(width 0.18288)
		(layer "In6.Cu")
		(net "M_G_CPU0_SB_DQ<11>")
	)
	(segment
		(start 422.219628 -224.941892)
		(end 421.36949 -225.79203)
		(width 0.18288)
		(layer "In6.Cu")
		(net "M_G_CPU0_SB_DQ<11>")
	)
	(segment
		(start 387.869684 -235.040424)
		(end 387.869684 -235.231178)
		(width 0.088646)
		(layer "In6.Cu")
		(net "M_G_CPU0_SB_DQ<11>")
	)
	(segment
		(start 406.502616 -223.42983)
		(end 406.502616 -223.126046)
		(width 0.18288)
		(layer "In6.Cu")
		(net "M_G_CPU0_SB_DQ<11>")
	)
	(segment
		(start 413.949642 -225.3869)
		(end 413.949642 -224.954846)
		(width 0.18288)
		(layer "In6.Cu")
		(net "M_G_CPU0_SB_DQ<11>")
	)
	(segment
		(start 428.310294 -222.991426)
		(end 427.319694 -223.982026)
		(width 0.18288)
		(layer "In6.Cu")
		(net "M_G_CPU0_SB_DQ<11>")
	)
	(segment
		(start 414.825942 -224.771966)
		(end 414.643062 -224.954846)
		(width 0.18288)
		(layer "In6.Cu")
		(net "M_G_CPU0_SB_DQ<11>")
	)
	(segment
		(start 406.502616 -223.126046)
		(end 406.342596 -222.966026)
		(width 0.18288)
		(layer "In6.Cu")
		(net "M_G_CPU0_SB_DQ<11>")
	)
	(segment
		(start 387.970776 -234.939332)
		(end 387.869684 -235.040424)
		(width 0.088646)
		(layer "In6.Cu")
		(net "M_G_CPU0_SB_DQ<11>")
	)
	(segment
		(start 407.206704 -223.126046)
		(end 407.206704 -223.41459)
		(width 0.18288)
		(layer "In6.Cu")
		(net "M_G_CPU0_SB_DQ<11>")
	)
	(segment
		(start 428.755302 -222.991426)
		(end 428.310294 -222.991426)
		(width 0.18288)
		(layer "In6.Cu")
		(net "M_G_CPU0_SB_DQ<11>")
	)
	(segment
		(start 378.658882 -236.273594)
		(end 378.64415 -236.28223)
		(width 0.088646)
		(layer "In6.Cu")
		(net "M_G_CPU0_SB_DQ<11>")
	)
	(segment
		(start 407.02103 -223.600264)
		(end 406.67305 -223.600264)
		(width 0.18288)
		(layer "In6.Cu")
		(net "M_G_CPU0_SB_DQ<11>")
	)
	(segment
		(start 434.012086 -221.881446)
		(end 433.829206 -221.698566)
		(width 0.18288)
		(layer "In6.Cu")
		(net "M_G_CPU0_SB_DQ<11>")
	)
	(segment
		(start 431.028094 -222.572326)
		(end 429.174402 -222.572326)
		(width 0.18288)
		(layer "In6.Cu")
		(net "M_G_CPU0_SB_DQ<11>")
	)
	(segment
		(start 408.955494 -222.966026)
		(end 407.366724 -222.966026)
		(width 0.18288)
		(layer "In6.Cu")
		(net "M_G_CPU0_SB_DQ<11>")
	)
	(segment
		(start 384.297682 -236.273594)
		(end 384.28295 -236.28223)
		(width 0.088646)
		(layer "In6.Cu")
		(net "M_G_CPU0_SB_DQ<11>")
	)
	(segment
		(start 433.646326 -221.18701)
		(end 433.318666 -221.18701)
		(width 0.18288)
		(layer "In6.Cu")
		(net "M_G_CPU0_SB_DQ<11>")
	)
	(segment
		(start 433.135786 -221.698566)
		(end 432.952906 -221.881446)
		(width 0.18288)
		(layer "In6.Cu")
		(net "M_G_CPU0_SB_DQ<11>")
	)
	(segment
		(start 414.132522 -225.56978)
		(end 413.949642 -225.3869)
		(width 0.18288)
		(layer "In6.Cu")
		(net "M_G_CPU0_SB_DQ<11>")
	)
	(segment
		(start 413.766762 -224.771966)
		(end 412.946342 -224.771966)
		(width 0.18288)
		(layer "In6.Cu")
		(net "M_G_CPU0_SB_DQ<11>")
	)
	(segment
		(start 431.718974 -221.881446)
		(end 431.028094 -222.572326)
		(width 0.18288)
		(layer "In6.Cu")
		(net "M_G_CPU0_SB_DQ<11>")
	)
	(segment
		(start 406.342596 -222.966026)
		(end 403.915626 -222.966026)
		(width 0.18288)
		(layer "In6.Cu")
		(net "M_G_CPU0_SB_DQ<11>")
	)
	(segment
		(start 427.319694 -223.982026)
		(end 426.268896 -223.982026)
		(width 0.18288)
		(layer "In6.Cu")
		(net "M_G_CPU0_SB_DQ<11>")
	)
	(segment
		(start 435.312058 -221.881446)
		(end 434.012086 -221.881446)
		(width 0.18288)
		(layer "In6.Cu")
		(net "M_G_CPU0_SB_DQ<11>")
	)
	(segment
		(start 416.861498 -225.79203)
		(end 415.841434 -224.771966)
		(width 0.18288)
		(layer "In6.Cu")
		(net "M_G_CPU0_SB_DQ<11>")
	)
	(segment
		(start 376.497088 -235.784136)
		(end 376.496834 -235.783882)
		(width 0.088646)
		(layer "In6.Cu")
		(net "M_G_CPU0_SB_DQ<11>")
	)
	(segment
		(start 429.174402 -222.572326)
		(end 428.755302 -222.991426)
		(width 0.18288)
		(layer "In6.Cu")
		(net "M_G_CPU0_SB_DQ<11>")
	)
	(segment
		(start 433.318666 -221.18701)
		(end 433.135786 -221.36989)
		(width 0.18288)
		(layer "In6.Cu")
		(net "M_G_CPU0_SB_DQ<11>")
	)
	(arc
		(start 379.033278 -236.273594)
		(mid 378.84608 -236.223451)
		(end 378.658882 -236.273594)
		(width 0.088646)
		(layer "In6.Cu")
		(net "M_G_CPU0_SB_DQ<11>")
	)
	(arc
		(start 382.792732 -236.273594)
		(mid 382.605534 -236.223451)
		(end 382.418336 -236.273594)
		(width 0.088646)
		(layer "In6.Cu")
		(net "M_G_CPU0_SB_DQ<11>")
	)
	(arc
		(start 383.347468 -236.27969)
		(mid 383.06929 -236.349382)
		(end 382.792732 -236.273594)
		(width 0.088646)
		(layer "In6.Cu")
		(net "M_G_CPU0_SB_DQ<11>")
	)
	(arc
		(start 380.538482 -236.273594)
		(mid 380.25578 -236.349336)
		(end 379.973078 -236.273594)
		(width 0.088646)
		(layer "In6.Cu")
		(net "M_G_CPU0_SB_DQ<11>")
	)
	(arc
		(start 378.093478 -236.273594)
		(mid 377.90628 -236.223451)
		(end 377.719082 -236.273594)
		(width 0.088646)
		(layer "In6.Cu")
		(net "M_G_CPU0_SB_DQ<11>")
	)
	(arc
		(start 386.459984 -235.798106)
		(mid 386.380765 -236.072791)
		(end 386.177282 -236.273594)
		(width 0.088646)
		(layer "In6.Cu")
		(net "M_G_CPU0_SB_DQ<11>")
	)
	(arc
		(start 378.64415 -236.28223)
		(mid 378.367709 -236.349396)
		(end 378.093478 -236.273594)
		(width 0.088646)
		(layer "In6.Cu")
		(net "M_G_CPU0_SB_DQ<11>")
	)
	(arc
		(start 383.732278 -236.273594)
		(mid 383.54508 -236.223451)
		(end 383.357882 -236.273594)
		(width 0.088646)
		(layer "In6.Cu")
		(net "M_G_CPU0_SB_DQ<11>")
	)
	(arc
		(start 377.708668 -236.27969)
		(mid 377.43049 -236.349382)
		(end 377.153932 -236.273594)
		(width 0.088646)
		(layer "In6.Cu")
		(net "M_G_CPU0_SB_DQ<11>")
	)
	(arc
		(start 384.28295 -236.28223)
		(mid 384.006509 -236.349396)
		(end 383.732278 -236.273594)
		(width 0.088646)
		(layer "In6.Cu")
		(net "M_G_CPU0_SB_DQ<11>")
	)
	(arc
		(start 381.468122 -236.27969)
		(mid 381.18969 -236.349504)
		(end 380.912878 -236.273594)
		(width 0.088646)
		(layer "In6.Cu")
		(net "M_G_CPU0_SB_DQ<11>")
	)
	(arc
		(start 386.16255 -236.28223)
		(mid 385.886109 -236.349396)
		(end 385.611878 -236.273594)
		(width 0.088646)
		(layer "In6.Cu")
		(net "M_G_CPU0_SB_DQ<11>")
	)
	(arc
		(start 387.021832 -235.459524)
		(mid 386.834634 -235.409381)
		(end 386.647436 -235.459524)
		(width 0.088646)
		(layer "In6.Cu")
		(net "M_G_CPU0_SB_DQ<11>")
	)
	(arc
		(start 386.638546 -235.464604)
		(mid 386.507632 -235.600964)
		(end 386.459984 -235.783882)
		(width 0.088646)
		(layer "In6.Cu")
		(net "M_G_CPU0_SB_DQ<11>")
	)
	(arc
		(start 379.58395 -236.28223)
		(mid 379.307509 -236.349396)
		(end 379.033278 -236.273594)
		(width 0.088646)
		(layer "In6.Cu")
		(net "M_G_CPU0_SB_DQ<11>")
	)
	(arc
		(start 381.852932 -236.273594)
		(mid 381.665734 -236.223451)
		(end 381.478536 -236.273594)
		(width 0.088646)
		(layer "In6.Cu")
		(net "M_G_CPU0_SB_DQ<11>")
	)
	(arc
		(start 380.912878 -236.273594)
		(mid 380.72568 -236.223451)
		(end 380.538482 -236.273594)
		(width 0.088646)
		(layer "In6.Cu")
		(net "M_G_CPU0_SB_DQ<11>")
	)
	(arc
		(start 385.22275 -236.28223)
		(mid 384.946309 -236.349396)
		(end 384.672078 -236.273594)
		(width 0.088646)
		(layer "In6.Cu")
		(net "M_G_CPU0_SB_DQ<11>")
	)
	(arc
		(start 377.055126 -236.215428)
		(mid 376.762343 -236.017591)
		(end 376.497088 -235.784136)
		(width 0.088646)
		(layer "In6.Cu")
		(net "M_G_CPU0_SB_DQ<11>")
	)
	(arc
		(start 379.973078 -236.273594)
		(mid 379.78588 -236.223451)
		(end 379.598682 -236.273594)
		(width 0.088646)
		(layer "In6.Cu")
		(net "M_G_CPU0_SB_DQ<11>")
	)
	(arc
		(start 384.672078 -236.273594)
		(mid 384.48488 -236.223451)
		(end 384.297682 -236.273594)
		(width 0.088646)
		(layer "In6.Cu")
		(net "M_G_CPU0_SB_DQ<11>")
	)
	(arc
		(start 385.611878 -236.273594)
		(mid 385.42468 -236.223451)
		(end 385.237482 -236.273594)
		(width 0.088646)
		(layer "In6.Cu")
		(net "M_G_CPU0_SB_DQ<11>")
	)
	(arc
		(start 387.30428 -235.535216)
		(mid 387.158072 -235.515967)
		(end 387.021832 -235.459524)
		(width 0.088646)
		(layer "In6.Cu")
		(net "M_G_CPU0_SB_DQ<11>")
	)
	(arc
		(start 382.418336 -236.273594)
		(mid 382.135634 -236.349336)
		(end 381.852932 -236.273594)
		(width 0.088646)
		(layer "In6.Cu")
		(net "M_G_CPU0_SB_DQ<11>")
	)
	(segment
		(start 446.602104 -221.714822)
		(end 446.986152 -221.714822)
		(width 0.20066)
		(layer "F.Cu")
		(net "M_G_CPU0_SB_DQ<10>")
	)
	(segment
		(start 375.08688 -237.133638)
		(end 375.08688 -236.597952)
		(width 0.20066)
		(layer "F.Cu")
		(net "M_G_CPU0_SB_DQ<10>")
	)
	(segment
		(start 441.028582 -221.96679)
		(end 442.726826 -221.96679)
		(width 0.20066)
		(layer "F.Cu")
		(net "M_G_CPU0_SB_DQ<10>")
	)
	(segment
		(start 443.15888 -222.398844)
		(end 443.450726 -222.398844)
		(width 0.20066)
		(layer "F.Cu")
		(net "M_G_CPU0_SB_DQ<10>")
	)
	(segment
		(start 446.367916 -222.199962)
		(end 446.367916 -221.94901)
		(width 0.20066)
		(layer "F.Cu")
		(net "M_G_CPU0_SB_DQ<10>")
	)
	(segment
		(start 443.455552 -222.398844)
		(end 443.462664 -222.391732)
		(width 0.1016)
		(layer "F.Cu")
		(net "M_G_CPU0_SB_DQ<10>")
	)
	(segment
		(start 445.470534 -222.391732)
		(end 445.482726 -222.403924)
		(width 0.1016)
		(layer "F.Cu")
		(net "M_G_CPU0_SB_DQ<10>")
	)
	(segment
		(start 447.23812 -221.96679)
		(end 448.572382 -221.96679)
		(width 0.20066)
		(layer "F.Cu")
		(net "M_G_CPU0_SB_DQ<10>")
	)
	(segment
		(start 439.923682 -221.96679)
		(end 441.028582 -221.96679)
		(width 0.20066)
		(layer "F.Cu")
		(net "M_G_CPU0_SB_DQ<10>")
	)
	(segment
		(start 375.087134 -237.133892)
		(end 375.08688 -237.133638)
		(width 0.20066)
		(layer "F.Cu")
		(net "M_G_CPU0_SB_DQ<10>")
	)
	(segment
		(start 446.986152 -221.714822)
		(end 447.23812 -221.96679)
		(width 0.20066)
		(layer "F.Cu")
		(net "M_G_CPU0_SB_DQ<10>")
	)
	(segment
		(start 446.367916 -221.94901)
		(end 446.602104 -221.714822)
		(width 0.20066)
		(layer "F.Cu")
		(net "M_G_CPU0_SB_DQ<10>")
	)
	(segment
		(start 442.726826 -221.96679)
		(end 443.15888 -222.398844)
		(width 0.20066)
		(layer "F.Cu")
		(net "M_G_CPU0_SB_DQ<10>")
	)
	(segment
		(start 445.482726 -222.403924)
		(end 446.163954 -222.403924)
		(width 0.20066)
		(layer "F.Cu")
		(net "M_G_CPU0_SB_DQ<10>")
	)
	(segment
		(start 443.450726 -222.398844)
		(end 443.455552 -222.398844)
		(width 0.101854)
		(layer "F.Cu")
		(net "M_G_CPU0_SB_DQ<10>")
	)
	(segment
		(start 443.462664 -222.391732)
		(end 445.470534 -222.391732)
		(width 0.1016)
		(layer "F.Cu")
		(net "M_G_CPU0_SB_DQ<10>")
	)
	(segment
		(start 446.163954 -222.403924)
		(end 446.367916 -222.199962)
		(width 0.20066)
		(layer "F.Cu")
		(net "M_G_CPU0_SB_DQ<10>")
	)
	(segment
		(start 425.255436 -225.79203)
		(end 422.276778 -225.79203)
		(width 0.18288)
		(layer "In6.Cu")
		(net "M_G_CPU0_SB_DQ<10>")
	)
	(segment
		(start 408.473148 -224.4217)
		(end 406.46604 -224.4217)
		(width 0.18288)
		(layer "In6.Cu")
		(net "M_G_CPU0_SB_DQ<10>")
	)
	(segment
		(start 412.101284 -224.985072)
		(end 411.060138 -224.985072)
		(width 0.18288)
		(layer "In6.Cu")
		(net "M_G_CPU0_SB_DQ<10>")
	)
	(segment
		(start 438.83453 -223.055942)
		(end 437.420766 -223.055942)
		(width 0.18288)
		(layer "In6.Cu")
		(net "M_G_CPU0_SB_DQ<10>")
	)
	(segment
		(start 376.592084 -236.597952)
		(end 376.592084 -236.53242)
		(width 0.088646)
		(layer "In6.Cu")
		(net "M_G_CPU0_SB_DQ<10>")
	)
	(segment
		(start 422.276778 -225.79203)
		(end 421.42664 -226.642168)
		(width 0.18288)
		(layer "In6.Cu")
		(net "M_G_CPU0_SB_DQ<10>")
	)
	(segment
		(start 388.162546 -235.439204)
		(end 387.940804 -235.439204)
		(width 0.088646)
		(layer "In6.Cu")
		(net "M_G_CPU0_SB_DQ<10>")
	)
	(segment
		(start 387.30428 -236.027468)
		(end 387.249416 -236.035088)
		(width 0.088646)
		(layer "In6.Cu")
		(net "M_G_CPU0_SB_DQ<10>")
	)
	(segment
		(start 416.201098 -226.09683)
		(end 413.213042 -226.09683)
		(width 0.18288)
		(layer "In6.Cu")
		(net "M_G_CPU0_SB_DQ<10>")
	)
	(segment
		(start 408.803094 -224.091754)
		(end 408.473148 -224.4217)
		(width 0.18288)
		(layer "In6.Cu")
		(net "M_G_CPU0_SB_DQ<10>")
	)
	(segment
		(start 380.923292 -236.91596)
		(end 380.912878 -236.922056)
		(width 0.088646)
		(layer "In6.Cu")
		(net "M_G_CPU0_SB_DQ<10>")
	)
	(segment
		(start 392.23315 -235.439204)
		(end 388.162546 -235.439204)
		(width 0.18288)
		(layer "In6.Cu")
		(net "M_G_CPU0_SB_DQ<10>")
	)
	(segment
		(start 387.940804 -235.439204)
		(end 387.35254 -236.027468)
		(width 0.088646)
		(layer "In6.Cu")
		(net "M_G_CPU0_SB_DQ<10>")
	)
	(segment
		(start 376.592084 -236.53242)
		(end 376.390662 -236.330998)
		(width 0.088646)
		(layer "In6.Cu")
		(net "M_G_CPU0_SB_DQ<10>")
	)
	(segment
		(start 418.169344 -226.366832)
		(end 418.009324 -226.526852)
		(width 0.18288)
		(layer "In6.Cu")
		(net "M_G_CPU0_SB_DQ<10>")
	)
	(segment
		(start 436.757064 -222.39224)
		(end 432.05908 -222.39224)
		(width 0.18288)
		(layer "In6.Cu")
		(net "M_G_CPU0_SB_DQ<10>")
	)
	(segment
		(start 431.307494 -223.143826)
		(end 429.44415 -223.143826)
		(width 0.18288)
		(layer "In6.Cu")
		(net "M_G_CPU0_SB_DQ<10>")
	)
	(segment
		(start 384.297682 -236.922056)
		(end 384.28295 -236.91342)
		(width 0.088646)
		(layer "In6.Cu")
		(net "M_G_CPU0_SB_DQ<10>")
	)
	(segment
		(start 425.92244 -225.125026)
		(end 425.255436 -225.79203)
		(width 0.18288)
		(layer "In6.Cu")
		(net "M_G_CPU0_SB_DQ<10>")
	)
	(segment
		(start 380.538482 -236.922056)
		(end 380.52375 -236.91342)
		(width 0.088646)
		(layer "In6.Cu")
		(net "M_G_CPU0_SB_DQ<10>")
	)
	(segment
		(start 411.060138 -224.985072)
		(end 410.16682 -224.091754)
		(width 0.18288)
		(layer "In6.Cu")
		(net "M_G_CPU0_SB_DQ<10>")
	)
	(segment
		(start 403.5806 -224.091754)
		(end 392.23315 -235.439204)
		(width 0.18288)
		(layer "In6.Cu")
		(net "M_G_CPU0_SB_DQ<10>")
	)
	(segment
		(start 413.213042 -226.09683)
		(end 412.101284 -224.985072)
		(width 0.18288)
		(layer "In6.Cu")
		(net "M_G_CPU0_SB_DQ<10>")
	)
	(segment
		(start 416.804094 -226.699826)
		(end 416.201098 -226.09683)
		(width 0.18288)
		(layer "In6.Cu")
		(net "M_G_CPU0_SB_DQ<10>")
	)
	(segment
		(start 385.237482 -236.922056)
		(end 385.22275 -236.91342)
		(width 0.088646)
		(layer "In6.Cu")
		(net "M_G_CPU0_SB_DQ<10>")
	)
	(segment
		(start 417.849304 -226.699826)
		(end 416.804094 -226.699826)
		(width 0.18288)
		(layer "In6.Cu")
		(net "M_G_CPU0_SB_DQ<10>")
	)
	(segment
		(start 378.658882 -236.922056)
		(end 378.64415 -236.91342)
		(width 0.088646)
		(layer "In6.Cu")
		(net "M_G_CPU0_SB_DQ<10>")
	)
	(segment
		(start 387.35254 -236.027468)
		(end 387.30428 -236.027468)
		(width 0.088646)
		(layer "In6.Cu")
		(net "M_G_CPU0_SB_DQ<10>")
	)
	(segment
		(start 379.598682 -236.922056)
		(end 379.58395 -236.91342)
		(width 0.088646)
		(layer "In6.Cu")
		(net "M_G_CPU0_SB_DQ<10>")
	)
	(segment
		(start 429.44415 -223.143826)
		(end 428.27575 -224.312226)
		(width 0.18288)
		(layer "In6.Cu")
		(net "M_G_CPU0_SB_DQ<10>")
	)
	(segment
		(start 386.565902 -236.913928)
		(end 386.551678 -236.922056)
		(width 0.088646)
		(layer "In6.Cu")
		(net "M_G_CPU0_SB_DQ<10>")
	)
	(segment
		(start 432.05908 -222.39224)
		(end 431.307494 -223.143826)
		(width 0.18288)
		(layer "In6.Cu")
		(net "M_G_CPU0_SB_DQ<10>")
	)
	(segment
		(start 419.24859 -226.642168)
		(end 418.973254 -226.366832)
		(width 0.18288)
		(layer "In6.Cu")
		(net "M_G_CPU0_SB_DQ<10>")
	)
	(segment
		(start 427.954694 -224.312226)
		(end 427.141894 -225.125026)
		(width 0.18288)
		(layer "In6.Cu")
		(net "M_G_CPU0_SB_DQ<10>")
	)
	(segment
		(start 383.357882 -236.922056)
		(end 383.347468 -236.91596)
		(width 0.088646)
		(layer "In6.Cu")
		(net "M_G_CPU0_SB_DQ<10>")
	)
	(segment
		(start 418.009324 -226.526852)
		(end 418.009324 -226.539806)
		(width 0.18288)
		(layer "In6.Cu")
		(net "M_G_CPU0_SB_DQ<10>")
	)
	(segment
		(start 376.779536 -236.922056)
		(end 376.765312 -236.913928)
		(width 0.088646)
		(layer "In6.Cu")
		(net "M_G_CPU0_SB_DQ<10>")
	)
	(segment
		(start 406.46604 -224.4217)
		(end 406.136094 -224.091754)
		(width 0.18288)
		(layer "In6.Cu")
		(net "M_G_CPU0_SB_DQ<10>")
	)
	(segment
		(start 418.009324 -226.539806)
		(end 417.849304 -226.699826)
		(width 0.18288)
		(layer "In6.Cu")
		(net "M_G_CPU0_SB_DQ<10>")
	)
	(segment
		(start 418.973254 -226.366832)
		(end 418.169344 -226.366832)
		(width 0.18288)
		(layer "In6.Cu")
		(net "M_G_CPU0_SB_DQ<10>")
	)
	(segment
		(start 377.719082 -236.922056)
		(end 377.708668 -236.91596)
		(width 0.088646)
		(layer "In6.Cu")
		(net "M_G_CPU0_SB_DQ<10>")
	)
	(segment
		(start 437.420766 -223.055942)
		(end 436.757064 -222.39224)
		(width 0.18288)
		(layer "In6.Cu")
		(net "M_G_CPU0_SB_DQ<10>")
	)
	(segment
		(start 439.923682 -221.96679)
		(end 438.83453 -223.055942)
		(width 0.18288)
		(layer "In6.Cu")
		(net "M_G_CPU0_SB_DQ<10>")
	)
	(segment
		(start 427.141894 -225.125026)
		(end 425.92244 -225.125026)
		(width 0.18288)
		(layer "In6.Cu")
		(net "M_G_CPU0_SB_DQ<10>")
	)
	(segment
		(start 410.16682 -224.091754)
		(end 408.803094 -224.091754)
		(width 0.18288)
		(layer "In6.Cu")
		(net "M_G_CPU0_SB_DQ<10>")
	)
	(segment
		(start 375.421144 -236.315504)
		(end 375.08688 -236.597952)
		(width 0.088646)
		(layer "In6.Cu")
		(net "M_G_CPU0_SB_DQ<10>")
	)
	(segment
		(start 386.177282 -236.922056)
		(end 386.16255 -236.91342)
		(width 0.088646)
		(layer "In6.Cu")
		(net "M_G_CPU0_SB_DQ<10>")
	)
	(segment
		(start 386.73913 -236.583728)
		(end 386.73913 -236.597952)
		(width 0.088646)
		(layer "In6.Cu")
		(net "M_G_CPU0_SB_DQ<10>")
	)
	(segment
		(start 406.136094 -224.091754)
		(end 403.5806 -224.091754)
		(width 0.18288)
		(layer "In6.Cu")
		(net "M_G_CPU0_SB_DQ<10>")
	)
	(segment
		(start 428.27575 -224.312226)
		(end 427.954694 -224.312226)
		(width 0.18288)
		(layer "In6.Cu")
		(net "M_G_CPU0_SB_DQ<10>")
	)
	(segment
		(start 421.42664 -226.642168)
		(end 419.24859 -226.642168)
		(width 0.18288)
		(layer "In6.Cu")
		(net "M_G_CPU0_SB_DQ<10>")
	)
	(arc
		(start 386.551678 -236.922056)
		(mid 386.36448 -236.972233)
		(end 386.177282 -236.922056)
		(width 0.088646)
		(layer "In6.Cu")
		(net "M_G_CPU0_SB_DQ<10>")
	)
	(arc
		(start 378.093478 -236.922056)
		(mid 377.90628 -236.972233)
		(end 377.719082 -236.922056)
		(width 0.088646)
		(layer "In6.Cu")
		(net "M_G_CPU0_SB_DQ<10>")
	)
	(arc
		(start 385.611878 -236.922056)
		(mid 385.42468 -236.972233)
		(end 385.237482 -236.922056)
		(width 0.088646)
		(layer "In6.Cu")
		(net "M_G_CPU0_SB_DQ<10>")
	)
	(arc
		(start 382.418336 -236.922056)
		(mid 382.135634 -236.84628)
		(end 381.852932 -236.922056)
		(width 0.088646)
		(layer "In6.Cu")
		(net "M_G_CPU0_SB_DQ<10>")
	)
	(arc
		(start 376.390662 -236.330998)
		(mid 375.909039 -236.126905)
		(end 375.421144 -236.315504)
		(width 0.088646)
		(layer "In6.Cu")
		(net "M_G_CPU0_SB_DQ<10>")
	)
	(arc
		(start 386.73913 -236.597952)
		(mid 386.692991 -236.778137)
		(end 386.565902 -236.913928)
		(width 0.088646)
		(layer "In6.Cu")
		(net "M_G_CPU0_SB_DQ<10>")
	)
	(arc
		(start 381.478536 -236.922056)
		(mid 381.201723 -236.846186)
		(end 380.923292 -236.91596)
		(width 0.088646)
		(layer "In6.Cu")
		(net "M_G_CPU0_SB_DQ<10>")
	)
	(arc
		(start 387.249416 -236.035088)
		(mid 387.13172 -236.059513)
		(end 387.021832 -236.10824)
		(width 0.088646)
		(layer "In6.Cu")
		(net "M_G_CPU0_SB_DQ<10>")
	)
	(arc
		(start 377.708668 -236.91596)
		(mid 377.43049 -236.846237)
		(end 377.153932 -236.922056)
		(width 0.088646)
		(layer "In6.Cu")
		(net "M_G_CPU0_SB_DQ<10>")
	)
	(arc
		(start 379.58395 -236.91342)
		(mid 379.307475 -236.8461)
		(end 379.033278 -236.922056)
		(width 0.088646)
		(layer "In6.Cu")
		(net "M_G_CPU0_SB_DQ<10>")
	)
	(arc
		(start 380.912878 -236.922056)
		(mid 380.72568 -236.972233)
		(end 380.538482 -236.922056)
		(width 0.088646)
		(layer "In6.Cu")
		(net "M_G_CPU0_SB_DQ<10>")
	)
	(arc
		(start 377.153932 -236.922056)
		(mid 376.966734 -236.972233)
		(end 376.779536 -236.922056)
		(width 0.088646)
		(layer "In6.Cu")
		(net "M_G_CPU0_SB_DQ<10>")
	)
	(arc
		(start 379.973078 -236.922056)
		(mid 379.78588 -236.972233)
		(end 379.598682 -236.922056)
		(width 0.088646)
		(layer "In6.Cu")
		(net "M_G_CPU0_SB_DQ<10>")
	)
	(arc
		(start 376.765312 -236.913928)
		(mid 376.638269 -236.778112)
		(end 376.592084 -236.597952)
		(width 0.088646)
		(layer "In6.Cu")
		(net "M_G_CPU0_SB_DQ<10>")
	)
	(arc
		(start 381.852932 -236.922056)
		(mid 381.665734 -236.972233)
		(end 381.478536 -236.922056)
		(width 0.088646)
		(layer "In6.Cu")
		(net "M_G_CPU0_SB_DQ<10>")
	)
	(arc
		(start 378.64415 -236.91342)
		(mid 378.367675 -236.8461)
		(end 378.093478 -236.922056)
		(width 0.088646)
		(layer "In6.Cu")
		(net "M_G_CPU0_SB_DQ<10>")
	)
	(arc
		(start 383.347468 -236.91596)
		(mid 383.06929 -236.846237)
		(end 382.792732 -236.922056)
		(width 0.088646)
		(layer "In6.Cu")
		(net "M_G_CPU0_SB_DQ<10>")
	)
	(arc
		(start 385.22275 -236.91342)
		(mid 384.946275 -236.8461)
		(end 384.672078 -236.922056)
		(width 0.088646)
		(layer "In6.Cu")
		(net "M_G_CPU0_SB_DQ<10>")
	)
	(arc
		(start 380.52375 -236.91342)
		(mid 380.247275 -236.8461)
		(end 379.973078 -236.922056)
		(width 0.088646)
		(layer "In6.Cu")
		(net "M_G_CPU0_SB_DQ<10>")
	)
	(arc
		(start 382.792732 -236.922056)
		(mid 382.605534 -236.972233)
		(end 382.418336 -236.922056)
		(width 0.088646)
		(layer "In6.Cu")
		(net "M_G_CPU0_SB_DQ<10>")
	)
	(arc
		(start 386.16255 -236.91342)
		(mid 385.886075 -236.8461)
		(end 385.611878 -236.922056)
		(width 0.088646)
		(layer "In6.Cu")
		(net "M_G_CPU0_SB_DQ<10>")
	)
	(arc
		(start 379.033278 -236.922056)
		(mid 378.84608 -236.972233)
		(end 378.658882 -236.922056)
		(width 0.088646)
		(layer "In6.Cu")
		(net "M_G_CPU0_SB_DQ<10>")
	)
	(arc
		(start 387.021832 -236.10824)
		(mid 386.818351 -236.309044)
		(end 386.73913 -236.583728)
		(width 0.088646)
		(layer "In6.Cu")
		(net "M_G_CPU0_SB_DQ<10>")
	)
	(arc
		(start 384.28295 -236.91342)
		(mid 384.006475 -236.8461)
		(end 383.732278 -236.922056)
		(width 0.088646)
		(layer "In6.Cu")
		(net "M_G_CPU0_SB_DQ<10>")
	)
	(arc
		(start 383.732278 -236.922056)
		(mid 383.54508 -236.972233)
		(end 383.357882 -236.922056)
		(width 0.088646)
		(layer "In6.Cu")
		(net "M_G_CPU0_SB_DQ<10>")
	)
	(arc
		(start 384.672078 -236.922056)
		(mid 384.48488 -236.972233)
		(end 384.297682 -236.922056)
		(width 0.088646)
		(layer "In6.Cu")
		(net "M_G_CPU0_SB_DQ<10>")
	)
	(segment
		(start 442.032644 -231.741726)
		(end 439.87085 -231.741726)
		(width 0.1016)
		(layer "F.Cu")
		(net "M_G_CPU0_SB_DQ<0>")
	)
	(segment
		(start 439.361072 -231.859836)
		(end 439.361072 -232.227374)
		(width 0.20066)
		(layer "F.Cu")
		(net "M_G_CPU0_SB_DQ<0>")
	)
	(segment
		(start 442.44895 -231.735376)
		(end 442.038994 -231.735376)
		(width 0.20066)
		(layer "F.Cu")
		(net "M_G_CPU0_SB_DQ<0>")
	)
	(segment
		(start 375.08688 -242.016788)
		(end 375.08688 -241.481102)
		(width 0.20066)
		(layer "F.Cu")
		(net "M_G_CPU0_SB_DQ<0>")
	)
	(segment
		(start 439.361072 -232.227374)
		(end 439.173112 -232.415334)
		(width 0.20066)
		(layer "F.Cu")
		(net "M_G_CPU0_SB_DQ<0>")
	)
	(segment
		(start 444.47206 -232.166922)
		(end 442.880496 -232.166922)
		(width 0.20066)
		(layer "F.Cu")
		(net "M_G_CPU0_SB_DQ<0>")
	)
	(segment
		(start 439.87085 -231.741726)
		(end 439.82386 -231.741726)
		(width 0.101854)
		(layer "F.Cu")
		(net "M_G_CPU0_SB_DQ<0>")
	)
	(segment
		(start 436.928514 -232.166668)
		(end 435.823614 -232.166668)
		(width 0.20066)
		(layer "F.Cu")
		(net "M_G_CPU0_SB_DQ<0>")
	)
	(segment
		(start 438.697878 -232.415334)
		(end 438.449212 -232.166668)
		(width 0.20066)
		(layer "F.Cu")
		(net "M_G_CPU0_SB_DQ<0>")
	)
	(segment
		(start 439.82386 -231.741726)
		(end 439.479182 -231.741726)
		(width 0.20066)
		(layer "F.Cu")
		(net "M_G_CPU0_SB_DQ<0>")
	)
	(segment
		(start 375.087134 -242.017042)
		(end 375.08688 -242.016788)
		(width 0.20066)
		(layer "F.Cu")
		(net "M_G_CPU0_SB_DQ<0>")
	)
	(segment
		(start 438.449212 -232.166668)
		(end 436.928514 -232.166668)
		(width 0.20066)
		(layer "F.Cu")
		(net "M_G_CPU0_SB_DQ<0>")
	)
	(segment
		(start 444.472314 -232.166668)
		(end 444.47206 -232.166922)
		(width 0.20066)
		(layer "F.Cu")
		(net "M_G_CPU0_SB_DQ<0>")
	)
	(segment
		(start 439.173112 -232.415334)
		(end 438.697878 -232.415334)
		(width 0.20066)
		(layer "F.Cu")
		(net "M_G_CPU0_SB_DQ<0>")
	)
	(segment
		(start 439.479182 -231.741726)
		(end 439.361072 -231.859836)
		(width 0.20066)
		(layer "F.Cu")
		(net "M_G_CPU0_SB_DQ<0>")
	)
	(segment
		(start 442.880496 -232.166922)
		(end 442.44895 -231.735376)
		(width 0.20066)
		(layer "F.Cu")
		(net "M_G_CPU0_SB_DQ<0>")
	)
	(segment
		(start 442.038994 -231.735376)
		(end 442.032644 -231.741726)
		(width 0.1016)
		(layer "F.Cu")
		(net "M_G_CPU0_SB_DQ<0>")
	)
	(segment
		(start 412.824676 -237.580932)
		(end 404.16099 -237.580932)
		(width 0.18288)
		(layer "In6.Cu")
		(net "M_G_CPU0_SB_DQ<0>")
	)
	(segment
		(start 396.700248 -242.056158)
		(end 388.38124 -242.056158)
		(width 0.18288)
		(layer "In6.Cu")
		(net "M_G_CPU0_SB_DQ<0>")
	)
	(segment
		(start 378.578364 -241.979196)
		(end 378.563632 -241.97056)
		(width 0.088646)
		(layer "In6.Cu")
		(net "M_G_CPU0_SB_DQ<0>")
	)
	(segment
		(start 430.88179 -237.69193)
		(end 423.064686 -237.69193)
		(width 0.18288)
		(layer "In6.Cu")
		(net "M_G_CPU0_SB_DQ<0>")
	)
	(segment
		(start 435.823614 -232.166668)
		(end 434.92039 -233.069892)
		(width 0.18288)
		(layer "In6.Cu")
		(net "M_G_CPU0_SB_DQ<0>")
	)
	(segment
		(start 375.744232 -241.97056)
		(end 375.738136 -241.967004)
		(width 0.088646)
		(layer "In6.Cu")
		(net "M_G_CPU0_SB_DQ<0>")
	)
	(segment
		(start 434.369464 -237.280196)
		(end 434.369464 -237.559088)
		(width 0.18288)
		(layer "In6.Cu")
		(net "M_G_CPU0_SB_DQ<0>")
	)
	(segment
		(start 434.538628 -233.069892)
		(end 433.960778 -233.647742)
		(width 0.18288)
		(layer "In6.Cu")
		(net "M_G_CPU0_SB_DQ<0>")
	)
	(segment
		(start 433.488338 -235.311442)
		(end 433.262278 -235.311442)
		(width 0.18288)
		(layer "In6.Cu")
		(net "M_G_CPU0_SB_DQ<0>")
	)
	(segment
		(start 431.908204 -236.924088)
		(end 432.19497 -237.210854)
		(width 0.18288)
		(layer "In6.Cu")
		(net "M_G_CPU0_SB_DQ<0>")
	)
	(segment
		(start 432.211734 -236.361986)
		(end 431.908204 -236.665516)
		(width 0.18288)
		(layer "In6.Cu")
		(net "M_G_CPU0_SB_DQ<0>")
	)
	(segment
		(start 375.399554 -241.481102)
		(end 375.08688 -241.481102)
		(width 0.088646)
		(layer "In6.Cu")
		(net "M_G_CPU0_SB_DQ<0>")
	)
	(segment
		(start 431.41773 -237.414562)
		(end 431.159158 -237.414562)
		(width 0.18288)
		(layer "In6.Cu")
		(net "M_G_CPU0_SB_DQ<0>")
	)
	(segment
		(start 432.19497 -237.469426)
		(end 431.963068 -237.701328)
		(width 0.18288)
		(layer "In6.Cu")
		(net "M_G_CPU0_SB_DQ<0>")
	)
	(segment
		(start 433.74818 -235.571284)
		(end 433.488338 -235.311442)
		(width 0.18288)
		(layer "In6.Cu")
		(net "M_G_CPU0_SB_DQ<0>")
	)
	(segment
		(start 433.960778 -233.647742)
		(end 433.960778 -234.314238)
		(width 0.18288)
		(layer "In6.Cu")
		(net "M_G_CPU0_SB_DQ<0>")
	)
	(segment
		(start 433.262278 -235.311442)
		(end 432.96078 -235.61294)
		(width 0.18288)
		(layer "In6.Cu")
		(net "M_G_CPU0_SB_DQ<0>")
	)
	(segment
		(start 431.908204 -236.665516)
		(end 431.908204 -236.924088)
		(width 0.18288)
		(layer "In6.Cu")
		(net "M_G_CPU0_SB_DQ<0>")
	)
	(segment
		(start 434.469286 -235.076238)
		(end 433.97424 -235.571284)
		(width 0.18288)
		(layer "In6.Cu")
		(net "M_G_CPU0_SB_DQ<0>")
	)
	(segment
		(start 413.30245 -238.058706)
		(end 412.824676 -237.580932)
		(width 0.18288)
		(layer "In6.Cu")
		(net "M_G_CPU0_SB_DQ<0>")
	)
	(segment
		(start 387.295898 -242.244626)
		(end 387.021832 -241.97056)
		(width 0.088646)
		(layer "In6.Cu")
		(net "M_G_CPU0_SB_DQ<0>")
	)
	(segment
		(start 431.963068 -237.701328)
		(end 431.704496 -237.701328)
		(width 0.18288)
		(layer "In6.Cu")
		(net "M_G_CPU0_SB_DQ<0>")
	)
	(segment
		(start 416.174174 -238.058706)
		(end 413.30245 -238.058706)
		(width 0.18288)
		(layer "In6.Cu")
		(net "M_G_CPU0_SB_DQ<0>")
	)
	(segment
		(start 423.064686 -237.69193)
		(end 422.216326 -238.54029)
		(width 0.18288)
		(layer "In6.Cu")
		(net "M_G_CPU0_SB_DQ<0>")
	)
	(segment
		(start 434.469286 -234.822746)
		(end 434.469286 -235.076238)
		(width 0.18288)
		(layer "In6.Cu")
		(net "M_G_CPU0_SB_DQ<0>")
	)
	(segment
		(start 432.19497 -237.210854)
		(end 432.19497 -237.469426)
		(width 0.18288)
		(layer "In6.Cu")
		(net "M_G_CPU0_SB_DQ<0>")
	)
	(segment
		(start 431.159158 -237.414562)
		(end 430.88179 -237.69193)
		(width 0.18288)
		(layer "In6.Cu")
		(net "M_G_CPU0_SB_DQ<0>")
	)
	(segment
		(start 433.97424 -235.571284)
		(end 433.74818 -235.571284)
		(width 0.18288)
		(layer "In6.Cu")
		(net "M_G_CPU0_SB_DQ<0>")
	)
	(segment
		(start 380.457964 -241.979196)
		(end 380.443232 -241.97056)
		(width 0.088646)
		(layer "In6.Cu")
		(net "M_G_CPU0_SB_DQ<0>")
	)
	(segment
		(start 433.88915 -237.78083)
		(end 432.470306 -236.361986)
		(width 0.18288)
		(layer "In6.Cu")
		(net "M_G_CPU0_SB_DQ<0>")
	)
	(segment
		(start 388.043928 -242.244626)
		(end 387.295898 -242.244626)
		(width 0.088646)
		(layer "In6.Cu")
		(net "M_G_CPU0_SB_DQ<0>")
	)
	(segment
		(start 431.704496 -237.701328)
		(end 431.41773 -237.414562)
		(width 0.18288)
		(layer "In6.Cu")
		(net "M_G_CPU0_SB_DQ<0>")
	)
	(segment
		(start 382.337564 -241.979196)
		(end 382.322832 -241.97056)
		(width 0.088646)
		(layer "In6.Cu")
		(net "M_G_CPU0_SB_DQ<0>")
	)
	(segment
		(start 403.150832 -238.59109)
		(end 400.165316 -238.59109)
		(width 0.18288)
		(layer "In6.Cu")
		(net "M_G_CPU0_SB_DQ<0>")
	)
	(segment
		(start 432.96078 -235.871512)
		(end 434.369464 -237.280196)
		(width 0.18288)
		(layer "In6.Cu")
		(net "M_G_CPU0_SB_DQ<0>")
	)
	(segment
		(start 379.518164 -241.979196)
		(end 379.503432 -241.97056)
		(width 0.088646)
		(layer "In6.Cu")
		(net "M_G_CPU0_SB_DQ<0>")
	)
	(segment
		(start 404.16099 -237.580932)
		(end 403.150832 -238.59109)
		(width 0.18288)
		(layer "In6.Cu")
		(net "M_G_CPU0_SB_DQ<0>")
	)
	(segment
		(start 400.165316 -238.59109)
		(end 396.700248 -242.056158)
		(width 0.18288)
		(layer "In6.Cu")
		(net "M_G_CPU0_SB_DQ<0>")
	)
	(segment
		(start 434.92039 -233.069892)
		(end 434.538628 -233.069892)
		(width 0.18288)
		(layer "In6.Cu")
		(net "M_G_CPU0_SB_DQ<0>")
	)
	(segment
		(start 432.96078 -235.61294)
		(end 432.96078 -235.871512)
		(width 0.18288)
		(layer "In6.Cu")
		(net "M_G_CPU0_SB_DQ<0>")
	)
	(segment
		(start 434.369464 -237.559088)
		(end 434.147722 -237.78083)
		(width 0.18288)
		(layer "In6.Cu")
		(net "M_G_CPU0_SB_DQ<0>")
	)
	(segment
		(start 419.895274 -238.771684)
		(end 416.887152 -238.771684)
		(width 0.18288)
		(layer "In6.Cu")
		(net "M_G_CPU0_SB_DQ<0>")
	)
	(segment
		(start 377.638564 -241.979196)
		(end 377.623832 -241.97056)
		(width 0.088646)
		(layer "In6.Cu")
		(net "M_G_CPU0_SB_DQ<0>")
	)
	(segment
		(start 432.470306 -236.361986)
		(end 432.211734 -236.361986)
		(width 0.18288)
		(layer "In6.Cu")
		(net "M_G_CPU0_SB_DQ<0>")
	)
	(segment
		(start 420.126668 -238.54029)
		(end 419.895274 -238.771684)
		(width 0.18288)
		(layer "In6.Cu")
		(net "M_G_CPU0_SB_DQ<0>")
	)
	(segment
		(start 388.38124 -242.056158)
		(end 388.232396 -242.056158)
		(width 0.088646)
		(layer "In6.Cu")
		(net "M_G_CPU0_SB_DQ<0>")
	)
	(segment
		(start 375.758964 -241.979196)
		(end 375.744232 -241.97056)
		(width 0.088646)
		(layer "In6.Cu")
		(net "M_G_CPU0_SB_DQ<0>")
	)
	(segment
		(start 416.887152 -238.771684)
		(end 416.174174 -238.058706)
		(width 0.18288)
		(layer "In6.Cu")
		(net "M_G_CPU0_SB_DQ<0>")
	)
	(segment
		(start 422.216326 -238.54029)
		(end 420.126668 -238.54029)
		(width 0.18288)
		(layer "In6.Cu")
		(net "M_G_CPU0_SB_DQ<0>")
	)
	(segment
		(start 375.46534 -241.546888)
		(end 375.399554 -241.481102)
		(width 0.088646)
		(layer "In6.Cu")
		(net "M_G_CPU0_SB_DQ<0>")
	)
	(segment
		(start 433.960778 -234.314238)
		(end 434.469286 -234.822746)
		(width 0.18288)
		(layer "In6.Cu")
		(net "M_G_CPU0_SB_DQ<0>")
	)
	(segment
		(start 388.232396 -242.056158)
		(end 388.043928 -242.244626)
		(width 0.088646)
		(layer "In6.Cu")
		(net "M_G_CPU0_SB_DQ<0>")
	)
	(segment
		(start 434.147722 -237.78083)
		(end 433.88915 -237.78083)
		(width 0.18288)
		(layer "In6.Cu")
		(net "M_G_CPU0_SB_DQ<0>")
	)
	(arc
		(start 381.948436 -241.97056)
		(mid 381.665734 -242.046336)
		(end 381.383032 -241.97056)
		(width 0.088646)
		(layer "In6.Cu")
		(net "M_G_CPU0_SB_DQ<0>")
	)
	(arc
		(start 381.008636 -241.97056)
		(mid 380.734437 -242.046395)
		(end 380.457964 -241.979196)
		(width 0.088646)
		(layer "In6.Cu")
		(net "M_G_CPU0_SB_DQ<0>")
	)
	(arc
		(start 386.647436 -241.97056)
		(mid 386.364734 -242.046336)
		(end 386.082032 -241.97056)
		(width 0.088646)
		(layer "In6.Cu")
		(net "M_G_CPU0_SB_DQ<0>")
	)
	(arc
		(start 377.623832 -241.97056)
		(mid 377.436634 -241.920417)
		(end 377.249436 -241.97056)
		(width 0.088646)
		(layer "In6.Cu")
		(net "M_G_CPU0_SB_DQ<0>")
	)
	(arc
		(start 376.684032 -241.97056)
		(mid 376.496834 -241.920417)
		(end 376.309636 -241.97056)
		(width 0.088646)
		(layer "In6.Cu")
		(net "M_G_CPU0_SB_DQ<0>")
	)
	(arc
		(start 380.443232 -241.97056)
		(mid 380.256034 -241.920417)
		(end 380.068836 -241.97056)
		(width 0.088646)
		(layer "In6.Cu")
		(net "M_G_CPU0_SB_DQ<0>")
	)
	(arc
		(start 383.262632 -241.97056)
		(mid 383.075434 -241.920417)
		(end 382.888236 -241.97056)
		(width 0.088646)
		(layer "In6.Cu")
		(net "M_G_CPU0_SB_DQ<0>")
	)
	(arc
		(start 378.189236 -241.97056)
		(mid 377.915037 -242.046395)
		(end 377.638564 -241.979196)
		(width 0.088646)
		(layer "In6.Cu")
		(net "M_G_CPU0_SB_DQ<0>")
	)
	(arc
		(start 382.888236 -241.97056)
		(mid 382.614037 -242.046395)
		(end 382.337564 -241.979196)
		(width 0.088646)
		(layer "In6.Cu")
		(net "M_G_CPU0_SB_DQ<0>")
	)
	(arc
		(start 382.322832 -241.97056)
		(mid 382.135634 -241.920417)
		(end 381.948436 -241.97056)
		(width 0.088646)
		(layer "In6.Cu")
		(net "M_G_CPU0_SB_DQ<0>")
	)
	(arc
		(start 385.142232 -241.97056)
		(mid 384.955034 -241.920417)
		(end 384.767836 -241.97056)
		(width 0.088646)
		(layer "In6.Cu")
		(net "M_G_CPU0_SB_DQ<0>")
	)
	(arc
		(start 375.738136 -241.967004)
		(mid 375.552681 -241.788809)
		(end 375.46534 -241.546888)
		(width 0.088646)
		(layer "In6.Cu")
		(net "M_G_CPU0_SB_DQ<0>")
	)
	(arc
		(start 384.202432 -241.97056)
		(mid 384.015234 -241.920417)
		(end 383.828036 -241.97056)
		(width 0.088646)
		(layer "In6.Cu")
		(net "M_G_CPU0_SB_DQ<0>")
	)
	(arc
		(start 379.129036 -241.97056)
		(mid 378.854837 -242.046395)
		(end 378.578364 -241.979196)
		(width 0.088646)
		(layer "In6.Cu")
		(net "M_G_CPU0_SB_DQ<0>")
	)
	(arc
		(start 378.563632 -241.97056)
		(mid 378.376434 -241.920417)
		(end 378.189236 -241.97056)
		(width 0.088646)
		(layer "In6.Cu")
		(net "M_G_CPU0_SB_DQ<0>")
	)
	(arc
		(start 376.309636 -241.97056)
		(mid 376.035437 -242.046395)
		(end 375.758964 -241.979196)
		(width 0.088646)
		(layer "In6.Cu")
		(net "M_G_CPU0_SB_DQ<0>")
	)
	(arc
		(start 387.021832 -241.97056)
		(mid 386.834634 -241.920417)
		(end 386.647436 -241.97056)
		(width 0.088646)
		(layer "In6.Cu")
		(net "M_G_CPU0_SB_DQ<0>")
	)
	(arc
		(start 383.828036 -241.97056)
		(mid 383.545334 -242.046336)
		(end 383.262632 -241.97056)
		(width 0.088646)
		(layer "In6.Cu")
		(net "M_G_CPU0_SB_DQ<0>")
	)
	(arc
		(start 380.068836 -241.97056)
		(mid 379.794637 -242.046395)
		(end 379.518164 -241.979196)
		(width 0.088646)
		(layer "In6.Cu")
		(net "M_G_CPU0_SB_DQ<0>")
	)
	(arc
		(start 377.249436 -241.97056)
		(mid 376.966734 -242.046336)
		(end 376.684032 -241.97056)
		(width 0.088646)
		(layer "In6.Cu")
		(net "M_G_CPU0_SB_DQ<0>")
	)
	(arc
		(start 379.503432 -241.97056)
		(mid 379.316234 -241.920417)
		(end 379.129036 -241.97056)
		(width 0.088646)
		(layer "In6.Cu")
		(net "M_G_CPU0_SB_DQ<0>")
	)
	(arc
		(start 386.082032 -241.97056)
		(mid 385.894834 -241.920417)
		(end 385.707636 -241.97056)
		(width 0.088646)
		(layer "In6.Cu")
		(net "M_G_CPU0_SB_DQ<0>")
	)
	(arc
		(start 385.707636 -241.97056)
		(mid 385.424934 -242.046336)
		(end 385.142232 -241.97056)
		(width 0.088646)
		(layer "In6.Cu")
		(net "M_G_CPU0_SB_DQ<0>")
	)
	(arc
		(start 381.383032 -241.97056)
		(mid 381.195834 -241.920417)
		(end 381.008636 -241.97056)
		(width 0.088646)
		(layer "In6.Cu")
		(net "M_G_CPU0_SB_DQ<0>")
	)
	(arc
		(start 384.767836 -241.97056)
		(mid 384.485134 -242.046336)
		(end 384.202432 -241.97056)
		(width 0.088646)
		(layer "In6.Cu")
		(net "M_G_CPU0_SB_DQ<0>")
	)
	(segment
		(start 441.028582 -244.916706)
		(end 439.923682 -244.916706)
		(width 0.20066)
		(layer "F.Cu")
		(net "M_G_CPU0_SB_CS_N<3>")
	)
	(segment
		(start 378.37618 -246.08663)
		(end 378.376434 -246.086376)
		(width 0.20066)
		(layer "F.Cu")
		(net "M_G_CPU0_SB_CS_N<3>")
	)
	(segment
		(start 378.376434 -246.086376)
		(end 378.376434 -245.55069)
		(width 0.20066)
		(layer "F.Cu")
		(net "M_G_CPU0_SB_CS_N<3>")
	)
	(segment
		(start 423.356024 -244.491002)
		(end 422.657016 -244.491002)
		(width 0.18288)
		(layer "In4.Cu")
		(net "M_G_CPU0_SB_CS_N<3>")
	)
	(segment
		(start 439.923682 -244.916706)
		(end 439.923682 -244.652546)
		(width 0.18288)
		(layer "In4.Cu")
		(net "M_G_CPU0_SB_CS_N<3>")
	)
	(segment
		(start 379.977904 -246.042942)
		(end 379.908308 -246.00154)
		(width 0.088646)
		(layer "In4.Cu")
		(net "M_G_CPU0_SB_CS_N<3>")
	)
	(segment
		(start 439.281824 -243.931186)
		(end 439.121804 -243.771166)
		(width 0.18288)
		(layer "In4.Cu")
		(net "M_G_CPU0_SB_CS_N<3>")
	)
	(segment
		(start 428.462694 -244.492526)
		(end 427.459394 -244.492526)
		(width 0.18288)
		(layer "In4.Cu")
		(net "M_G_CPU0_SB_CS_N<3>")
	)
	(segment
		(start 439.281824 -244.332506)
		(end 439.281824 -243.931186)
		(width 0.18288)
		(layer "In4.Cu")
		(net "M_G_CPU0_SB_CS_N<3>")
	)
	(segment
		(start 439.441844 -244.492526)
		(end 439.281824 -244.332506)
		(width 0.18288)
		(layer "In4.Cu")
		(net "M_G_CPU0_SB_CS_N<3>")
	)
	(segment
		(start 439.923682 -244.652546)
		(end 439.763662 -244.492526)
		(width 0.18288)
		(layer "In4.Cu")
		(net "M_G_CPU0_SB_CS_N<3>")
	)
	(segment
		(start 414.937194 -243.768626)
		(end 414.352994 -244.352826)
		(width 0.18288)
		(layer "In4.Cu")
		(net "M_G_CPU0_SB_CS_N<3>")
	)
	(segment
		(start 428.627794 -244.327426)
		(end 428.462694 -244.492526)
		(width 0.18288)
		(layer "In4.Cu")
		(net "M_G_CPU0_SB_CS_N<3>")
	)
	(segment
		(start 387.30682 -246.0498)
		(end 386.295138 -246.0498)
		(width 0.18288)
		(layer "In4.Cu")
		(net "M_G_CPU0_SB_CS_N<3>")
	)
	(segment
		(start 424.482514 -244.492526)
		(end 424.48226 -244.49278)
		(width 0.18288)
		(layer "In4.Cu")
		(net "M_G_CPU0_SB_CS_N<3>")
	)
	(segment
		(start 424.363134 -244.49278)
		(end 424.020488 -244.835426)
		(width 0.18288)
		(layer "In4.Cu")
		(net "M_G_CPU0_SB_CS_N<3>")
	)
	(segment
		(start 386.02031 -245.774972)
		(end 385.766564 -245.774972)
		(width 0.18288)
		(layer "In4.Cu")
		(net "M_G_CPU0_SB_CS_N<3>")
	)
	(segment
		(start 438.558686 -243.948458)
		(end 438.558686 -244.320314)
		(width 0.18288)
		(layer "In4.Cu")
		(net "M_G_CPU0_SB_CS_N<3>")
	)
	(segment
		(start 439.763662 -244.492526)
		(end 439.441844 -244.492526)
		(width 0.18288)
		(layer "In4.Cu")
		(net "M_G_CPU0_SB_CS_N<3>")
	)
	(segment
		(start 395.369288 -245.327424)
		(end 389.052054 -245.327424)
		(width 0.18288)
		(layer "In4.Cu")
		(net "M_G_CPU0_SB_CS_N<3>")
	)
	(segment
		(start 439.121804 -243.771166)
		(end 438.735978 -243.771166)
		(width 0.18288)
		(layer "In4.Cu")
		(net "M_G_CPU0_SB_CS_N<3>")
	)
	(segment
		(start 422.657016 -244.491002)
		(end 422.35374 -244.187726)
		(width 0.18288)
		(layer "In4.Cu")
		(net "M_G_CPU0_SB_CS_N<3>")
	)
	(segment
		(start 384.590798 -245.774972)
		(end 384.414776 -245.950994)
		(width 0.088646)
		(layer "In4.Cu")
		(net "M_G_CPU0_SB_CS_N<3>")
	)
	(segment
		(start 380.537974 -246.039894)
		(end 380.522226 -246.049038)
		(width 0.088646)
		(layer "In4.Cu")
		(net "M_G_CPU0_SB_CS_N<3>")
	)
	(segment
		(start 421.261794 -244.187726)
		(end 420.956994 -244.492526)
		(width 0.18288)
		(layer "In4.Cu")
		(net "M_G_CPU0_SB_CS_N<3>")
	)
	(segment
		(start 431.470562 -244.490494)
		(end 431.307494 -244.327426)
		(width 0.18288)
		(layer "In4.Cu")
		(net "M_G_CPU0_SB_CS_N<3>")
	)
	(segment
		(start 413.469836 -244.494304)
		(end 403.770084 -244.494304)
		(width 0.18288)
		(layer "In4.Cu")
		(net "M_G_CPU0_SB_CS_N<3>")
	)
	(segment
		(start 414.352994 -244.352826)
		(end 413.611314 -244.352826)
		(width 0.18288)
		(layer "In4.Cu")
		(net "M_G_CPU0_SB_CS_N<3>")
	)
	(segment
		(start 427.459394 -244.492526)
		(end 427.294294 -244.657626)
		(width 0.18288)
		(layer "In4.Cu")
		(net "M_G_CPU0_SB_CS_N<3>")
	)
	(segment
		(start 413.611314 -244.352826)
		(end 413.469836 -244.494304)
		(width 0.18288)
		(layer "In4.Cu")
		(net "M_G_CPU0_SB_CS_N<3>")
	)
	(segment
		(start 420.956994 -244.492526)
		(end 419.278816 -244.492526)
		(width 0.18288)
		(layer "In4.Cu")
		(net "M_G_CPU0_SB_CS_N<3>")
	)
	(segment
		(start 416.64382 -244.556026)
		(end 415.85642 -243.768626)
		(width 0.18288)
		(layer "In4.Cu")
		(net "M_G_CPU0_SB_CS_N<3>")
	)
	(segment
		(start 378.97435 -245.993412)
		(end 378.8283 -245.847362)
		(width 0.088646)
		(layer "In4.Cu")
		(net "M_G_CPU0_SB_CS_N<3>")
	)
	(segment
		(start 379.979174 -246.043704)
		(end 379.977904 -246.042942)
		(width 0.088646)
		(layer "In4.Cu")
		(net "M_G_CPU0_SB_CS_N<3>")
	)
	(segment
		(start 424.48226 -244.49278)
		(end 424.363134 -244.49278)
		(width 0.18288)
		(layer "In4.Cu")
		(net "M_G_CPU0_SB_CS_N<3>")
	)
	(segment
		(start 438.388506 -244.490494)
		(end 431.470562 -244.490494)
		(width 0.18288)
		(layer "In4.Cu")
		(net "M_G_CPU0_SB_CS_N<3>")
	)
	(segment
		(start 419.215316 -244.556026)
		(end 416.64382 -244.556026)
		(width 0.18288)
		(layer "In4.Cu")
		(net "M_G_CPU0_SB_CS_N<3>")
	)
	(segment
		(start 431.307494 -244.327426)
		(end 428.627794 -244.327426)
		(width 0.18288)
		(layer "In4.Cu")
		(net "M_G_CPU0_SB_CS_N<3>")
	)
	(segment
		(start 403.662134 -244.602254)
		(end 396.094458 -244.602254)
		(width 0.18288)
		(layer "In4.Cu")
		(net "M_G_CPU0_SB_CS_N<3>")
	)
	(segment
		(start 422.35374 -244.187726)
		(end 421.261794 -244.187726)
		(width 0.18288)
		(layer "In4.Cu")
		(net "M_G_CPU0_SB_CS_N<3>")
	)
	(segment
		(start 424.020488 -244.835426)
		(end 423.700448 -244.835426)
		(width 0.18288)
		(layer "In4.Cu")
		(net "M_G_CPU0_SB_CS_N<3>")
	)
	(segment
		(start 389.052054 -245.327424)
		(end 387.30682 -246.0498)
		(width 0.18288)
		(layer "In4.Cu")
		(net "M_G_CPU0_SB_CS_N<3>")
	)
	(segment
		(start 427.294294 -244.657626)
		(end 425.592494 -244.657626)
		(width 0.18288)
		(layer "In4.Cu")
		(net "M_G_CPU0_SB_CS_N<3>")
	)
	(segment
		(start 438.735978 -243.771166)
		(end 438.558686 -243.948458)
		(width 0.18288)
		(layer "In4.Cu")
		(net "M_G_CPU0_SB_CS_N<3>")
	)
	(segment
		(start 425.592494 -244.657626)
		(end 425.427394 -244.492526)
		(width 0.18288)
		(layer "In4.Cu")
		(net "M_G_CPU0_SB_CS_N<3>")
	)
	(segment
		(start 396.094458 -244.602254)
		(end 395.369288 -245.327424)
		(width 0.18288)
		(layer "In4.Cu")
		(net "M_G_CPU0_SB_CS_N<3>")
	)
	(segment
		(start 378.758958 -245.79199)
		(end 378.376434 -245.55069)
		(width 0.088646)
		(layer "In4.Cu")
		(net "M_G_CPU0_SB_CS_N<3>")
	)
	(segment
		(start 423.700448 -244.835426)
		(end 423.356024 -244.491002)
		(width 0.18288)
		(layer "In4.Cu")
		(net "M_G_CPU0_SB_CS_N<3>")
	)
	(segment
		(start 379.046994 -246.04853)
		(end 379.04547 -246.047006)
		(width 0.088646)
		(layer "In4.Cu")
		(net "M_G_CPU0_SB_CS_N<3>")
	)
	(segment
		(start 380.927864 -246.048784)
		(end 380.894844 -246.02948)
		(width 0.088646)
		(layer "In4.Cu")
		(net "M_G_CPU0_SB_CS_N<3>")
	)
	(segment
		(start 419.278816 -244.492526)
		(end 419.215316 -244.556026)
		(width 0.18288)
		(layer "In4.Cu")
		(net "M_G_CPU0_SB_CS_N<3>")
	)
	(segment
		(start 386.295138 -246.0498)
		(end 386.02031 -245.774972)
		(width 0.18288)
		(layer "In4.Cu")
		(net "M_G_CPU0_SB_CS_N<3>")
	)
	(segment
		(start 438.558686 -244.320314)
		(end 438.388506 -244.490494)
		(width 0.18288)
		(layer "In4.Cu")
		(net "M_G_CPU0_SB_CS_N<3>")
	)
	(segment
		(start 415.85642 -243.768626)
		(end 414.937194 -243.768626)
		(width 0.18288)
		(layer "In4.Cu")
		(net "M_G_CPU0_SB_CS_N<3>")
	)
	(segment
		(start 425.427394 -244.492526)
		(end 424.482514 -244.492526)
		(width 0.18288)
		(layer "In4.Cu")
		(net "M_G_CPU0_SB_CS_N<3>")
	)
	(segment
		(start 385.766564 -245.774972)
		(end 384.590798 -245.774972)
		(width 0.088646)
		(layer "In4.Cu")
		(net "M_G_CPU0_SB_CS_N<3>")
	)
	(segment
		(start 403.770084 -244.494304)
		(end 403.662134 -244.602254)
		(width 0.18288)
		(layer "In4.Cu")
		(net "M_G_CPU0_SB_CS_N<3>")
	)
	(arc
		(start 381.478536 -246.040148)
		(mid 381.204337 -246.115983)
		(end 380.927864 -246.048784)
		(width 0.088646)
		(layer "In4.Cu")
		(net "M_G_CPU0_SB_CS_N<3>")
	)
	(arc
		(start 380.751588 -245.990618)
		(mid 380.748288 -245.990434)
		(end 380.744984 -245.990364)
		(width 0.088646)
		(layer "In4.Cu")
		(net "M_G_CPU0_SB_CS_N<3>")
	)
	(arc
		(start 379.516894 -246.054626)
		(mid 379.354772 -246.143302)
		(end 379.170438 -246.130318)
		(width 0.088646)
		(layer "In4.Cu")
		(net "M_G_CPU0_SB_CS_N<3>")
	)
	(arc
		(start 379.993144 -246.051832)
		(mid 379.986097 -246.047875)
		(end 379.979174 -246.043704)
		(width 0.088646)
		(layer "In4.Cu")
		(net "M_G_CPU0_SB_CS_N<3>")
	)
	(arc
		(start 380.75616 -245.990872)
		(mid 380.753874 -245.990738)
		(end 380.751588 -245.990618)
		(width 0.088646)
		(layer "In4.Cu")
		(net "M_G_CPU0_SB_CS_N<3>")
	)
	(arc
		(start 380.51486 -246.053102)
		(mid 380.253852 -246.1162)
		(end 379.993144 -246.051832)
		(width 0.088646)
		(layer "In4.Cu")
		(net "M_G_CPU0_SB_CS_N<3>")
	)
	(arc
		(start 382.418336 -246.040148)
		(mid 382.135634 -246.115924)
		(end 381.852932 -246.040148)
		(width 0.088646)
		(layer "In4.Cu")
		(net "M_G_CPU0_SB_CS_N<3>")
	)
	(arc
		(start 380.580138 -246.019066)
		(mid 380.558732 -246.028824)
		(end 380.537974 -246.039894)
		(width 0.088646)
		(layer "In4.Cu")
		(net "M_G_CPU0_SB_CS_N<3>")
	)
	(arc
		(start 380.593854 -246.013986)
		(mid 380.587013 -246.016573)
		(end 380.580138 -246.019066)
		(width 0.088646)
		(layer "In4.Cu")
		(net "M_G_CPU0_SB_CS_N<3>")
	)
	(arc
		(start 382.792732 -246.040148)
		(mid 382.605534 -245.990005)
		(end 382.418336 -246.040148)
		(width 0.088646)
		(layer "In4.Cu")
		(net "M_G_CPU0_SB_CS_N<3>")
	)
	(arc
		(start 379.908308 -246.00154)
		(mid 379.868426 -245.981567)
		(end 379.826012 -245.967758)
		(width 0.088646)
		(layer "In4.Cu")
		(net "M_G_CPU0_SB_CS_N<3>")
	)
	(arc
		(start 380.757176 -245.990872)
		(mid 380.756668 -245.990871)
		(end 380.75616 -245.990872)
		(width 0.088646)
		(layer "In4.Cu")
		(net "M_G_CPU0_SB_CS_N<3>")
	)
	(arc
		(start 380.894844 -246.02948)
		(mid 380.827862 -246.003579)
		(end 380.757176 -245.990872)
		(width 0.088646)
		(layer "In4.Cu")
		(net "M_G_CPU0_SB_CS_N<3>")
	)
	(arc
		(start 384.361944 -245.997222)
		(mid 384.330672 -246.019777)
		(end 384.297936 -246.040148)
		(width 0.088646)
		(layer "In4.Cu")
		(net "M_G_CPU0_SB_CS_N<3>")
	)
	(arc
		(start 379.04547 -246.047006)
		(mid 379.007987 -246.02276)
		(end 378.97435 -245.993412)
		(width 0.088646)
		(layer "In4.Cu")
		(net "M_G_CPU0_SB_CS_N<3>")
	)
	(arc
		(start 383.732532 -246.040148)
		(mid 383.545334 -245.990005)
		(end 383.358136 -246.040148)
		(width 0.088646)
		(layer "In4.Cu")
		(net "M_G_CPU0_SB_CS_N<3>")
	)
	(arc
		(start 379.094492 -246.084344)
		(mid 379.071452 -246.065497)
		(end 379.046994 -246.04853)
		(width 0.088646)
		(layer "In4.Cu")
		(net "M_G_CPU0_SB_CS_N<3>")
	)
	(arc
		(start 379.170438 -246.130318)
		(mid 379.130335 -246.110848)
		(end 379.094492 -246.084344)
		(width 0.088646)
		(layer "In4.Cu")
		(net "M_G_CPU0_SB_CS_N<3>")
	)
	(arc
		(start 380.522226 -246.049038)
		(mid 380.518564 -246.051109)
		(end 380.51486 -246.053102)
		(width 0.088646)
		(layer "In4.Cu")
		(net "M_G_CPU0_SB_CS_N<3>")
	)
	(arc
		(start 384.414776 -245.950994)
		(mid 384.389078 -245.974928)
		(end 384.361944 -245.997222)
		(width 0.088646)
		(layer "In4.Cu")
		(net "M_G_CPU0_SB_CS_N<3>")
	)
	(arc
		(start 381.852932 -246.040148)
		(mid 381.665734 -245.990005)
		(end 381.478536 -246.040148)
		(width 0.088646)
		(layer "In4.Cu")
		(net "M_G_CPU0_SB_CS_N<3>")
	)
	(arc
		(start 380.744984 -245.990364)
		(mid 380.668194 -245.994356)
		(end 380.593854 -246.013986)
		(width 0.088646)
		(layer "In4.Cu")
		(net "M_G_CPU0_SB_CS_N<3>")
	)
	(arc
		(start 379.826012 -245.967758)
		(mid 379.660088 -245.970763)
		(end 379.516894 -246.054626)
		(width 0.088646)
		(layer "In4.Cu")
		(net "M_G_CPU0_SB_CS_N<3>")
	)
	(arc
		(start 383.358136 -246.040148)
		(mid 383.075434 -246.115924)
		(end 382.792732 -246.040148)
		(width 0.088646)
		(layer "In4.Cu")
		(net "M_G_CPU0_SB_CS_N<3>")
	)
	(arc
		(start 378.8283 -245.847362)
		(mid 378.795166 -245.817753)
		(end 378.758958 -245.79199)
		(width 0.088646)
		(layer "In4.Cu")
		(net "M_G_CPU0_SB_CS_N<3>")
	)
	(arc
		(start 384.297936 -246.040148)
		(mid 384.015234 -246.115924)
		(end 383.732532 -246.040148)
		(width 0.088646)
		(layer "In4.Cu")
		(net "M_G_CPU0_SB_CS_N<3>")
	)
	(segment
		(start 377.906534 -246.900446)
		(end 377.90628 -246.900192)
		(width 0.20066)
		(layer "F.Cu")
		(net "M_G_CPU0_SB_CS_N<2>")
	)
	(segment
		(start 377.90628 -246.900192)
		(end 377.90628 -246.364506)
		(width 0.20066)
		(layer "F.Cu")
		(net "M_G_CPU0_SB_CS_N<2>")
	)
	(segment
		(start 436.928514 -245.76659)
		(end 435.823614 -245.76659)
		(width 0.20066)
		(layer "F.Cu")
		(net "M_G_CPU0_SB_CS_N<2>")
	)
	(segment
		(start 430.845976 -246.286528)
		(end 430.591468 -246.03202)
		(width 0.18288)
		(layer "In4.Cu")
		(net "M_G_CPU0_SB_CS_N<2>")
	)
	(segment
		(start 408.256994 -246.283226)
		(end 408.051254 -246.077486)
		(width 0.18288)
		(layer "In4.Cu")
		(net "M_G_CPU0_SB_CS_N<2>")
	)
	(segment
		(start 418.515292 -245.650766)
		(end 418.187632 -245.650766)
		(width 0.18288)
		(layer "In4.Cu")
		(net "M_G_CPU0_SB_CS_N<2>")
	)
	(segment
		(start 387.585458 -246.67845)
		(end 387.176264 -247.087644)
		(width 0.18288)
		(layer "In4.Cu")
		(net "M_G_CPU0_SB_CS_N<2>")
	)
	(segment
		(start 426.30598 -245.680992)
		(end 425.97832 -245.680992)
		(width 0.18288)
		(layer "In4.Cu")
		(net "M_G_CPU0_SB_CS_N<2>")
	)
	(segment
		(start 412.25597 -246.34063)
		(end 411.433264 -246.34063)
		(width 0.18288)
		(layer "In4.Cu")
		(net "M_G_CPU0_SB_CS_N<2>")
	)
	(segment
		(start 412.437834 -246.158766)
		(end 412.25597 -246.34063)
		(width 0.18288)
		(layer "In4.Cu")
		(net "M_G_CPU0_SB_CS_N<2>")
	)
	(segment
		(start 425.045124 -246.192802)
		(end 421.160448 -246.192802)
		(width 0.18288)
		(layer "In4.Cu")
		(net "M_G_CPU0_SB_CS_N<2>")
	)
	(segment
		(start 419.674294 -246.486426)
		(end 418.881052 -246.486426)
		(width 0.18288)
		(layer "In4.Cu")
		(net "M_G_CPU0_SB_CS_N<2>")
	)
	(segment
		(start 414.80232 -246.015256)
		(end 414.6423 -245.855236)
		(width 0.18288)
		(layer "In4.Cu")
		(net "M_G_CPU0_SB_CS_N<2>")
	)
	(segment
		(start 380.068582 -246.853964)
		(end 380.05385 -246.8626)
		(width 0.088646)
		(layer "In4.Cu")
		(net "M_G_CPU0_SB_CS_N<2>")
	)
	(segment
		(start 418.698172 -245.833646)
		(end 418.515292 -245.650766)
		(width 0.18288)
		(layer "In4.Cu")
		(net "M_G_CPU0_SB_CS_N<2>")
	)
	(segment
		(start 381.948436 -246.853964)
		(end 381.938022 -246.86006)
		(width 0.088646)
		(layer "In4.Cu")
		(net "M_G_CPU0_SB_CS_N<2>")
	)
	(segment
		(start 404.633176 -246.077486)
		(end 403.47519 -245.597934)
		(width 0.18288)
		(layer "In4.Cu")
		(net "M_G_CPU0_SB_CS_N<2>")
	)
	(segment
		(start 385.582922 -247.087644)
		(end 385.424934 -246.929656)
		(width 0.088646)
		(layer "In4.Cu")
		(net "M_G_CPU0_SB_CS_N<2>")
	)
	(segment
		(start 429.558704 -246.551196)
		(end 429.210724 -246.551196)
		(width 0.18288)
		(layer "In4.Cu")
		(net "M_G_CPU0_SB_CS_N<2>")
	)
	(segment
		(start 426.67174 -246.359426)
		(end 426.48886 -246.176546)
		(width 0.18288)
		(layer "In4.Cu")
		(net "M_G_CPU0_SB_CS_N<2>")
	)
	(segment
		(start 410.669232 -245.826534)
		(end 410.486098 -246.009668)
		(width 0.18288)
		(layer "In4.Cu")
		(net "M_G_CPU0_SB_CS_N<2>")
	)
	(segment
		(start 429.210724 -246.551196)
		(end 428.85106 -246.191532)
		(width 0.18288)
		(layer "In4.Cu")
		(net "M_G_CPU0_SB_CS_N<2>")
	)
	(segment
		(start 411.226254 -245.986554)
		(end 411.066234 -245.826534)
		(width 0.18288)
		(layer "In4.Cu")
		(net "M_G_CPU0_SB_CS_N<2>")
	)
	(segment
		(start 426.48886 -246.176546)
		(end 426.48886 -245.863872)
		(width 0.18288)
		(layer "In4.Cu")
		(net "M_G_CPU0_SB_CS_N<2>")
	)
	(segment
		(start 381.008382 -246.853964)
		(end 380.926086 -246.902224)
		(width 0.088646)
		(layer "In4.Cu")
		(net "M_G_CPU0_SB_CS_N<2>")
	)
	(segment
		(start 382.8796 -246.85879)
		(end 382.877568 -246.86006)
		(width 0.088646)
		(layer "In4.Cu")
		(net "M_G_CPU0_SB_CS_N<2>")
	)
	(segment
		(start 416.12439 -245.970806)
		(end 416.12439 -245.605046)
		(width 0.18288)
		(layer "In4.Cu")
		(net "M_G_CPU0_SB_CS_N<2>")
	)
	(segment
		(start 387.176264 -247.087644)
		(end 385.766564 -247.087644)
		(width 0.18288)
		(layer "In4.Cu")
		(net "M_G_CPU0_SB_CS_N<2>")
	)
	(segment
		(start 396.106904 -245.997984)
		(end 389.228076 -245.997984)
		(width 0.18288)
		(layer "In4.Cu")
		(net "M_G_CPU0_SB_CS_N<2>")
	)
	(segment
		(start 378.563632 -246.853964)
		(end 378.53493 -246.837708)
		(width 0.088646)
		(layer "In4.Cu")
		(net "M_G_CPU0_SB_CS_N<2>")
	)
	(segment
		(start 412.56585 -245.971568)
		(end 412.437834 -246.099584)
		(width 0.18288)
		(layer "In4.Cu")
		(net "M_G_CPU0_SB_CS_N<2>")
	)
	(segment
		(start 425.79544 -246.176546)
		(end 425.61256 -246.359426)
		(width 0.18288)
		(layer "In4.Cu")
		(net "M_G_CPU0_SB_CS_N<2>")
	)
	(segment
		(start 435.823614 -245.76659)
		(end 435.303676 -246.286528)
		(width 0.18288)
		(layer "In4.Cu")
		(net "M_G_CPU0_SB_CS_N<2>")
	)
	(segment
		(start 410.486098 -246.009668)
		(end 410.486098 -246.123206)
		(width 0.18288)
		(layer "In4.Cu")
		(net "M_G_CPU0_SB_CS_N<2>")
	)
	(segment
		(start 417.013644 -246.130826)
		(end 416.28441 -246.130826)
		(width 0.18288)
		(layer "In4.Cu")
		(net "M_G_CPU0_SB_CS_N<2>")
	)
	(segment
		(start 410.326078 -246.283226)
		(end 408.256994 -246.283226)
		(width 0.18288)
		(layer "In4.Cu")
		(net "M_G_CPU0_SB_CS_N<2>")
	)
	(segment
		(start 425.97832 -245.680992)
		(end 425.79544 -245.863872)
		(width 0.18288)
		(layer "In4.Cu")
		(net "M_G_CPU0_SB_CS_N<2>")
	)
	(segment
		(start 418.187632 -245.650766)
		(end 418.004752 -245.833646)
		(width 0.18288)
		(layer "In4.Cu")
		(net "M_G_CPU0_SB_CS_N<2>")
	)
	(segment
		(start 433.301902 -245.792498)
		(end 433.301902 -246.126508)
		(width 0.18288)
		(layer "In4.Cu")
		(net "M_G_CPU0_SB_CS_N<2>")
	)
	(segment
		(start 413.57677 -245.971568)
		(end 412.56585 -245.971568)
		(width 0.18288)
		(layer "In4.Cu")
		(net "M_G_CPU0_SB_CS_N<2>")
	)
	(segment
		(start 419.968172 -246.192548)
		(end 419.674294 -246.486426)
		(width 0.18288)
		(layer "In4.Cu")
		(net "M_G_CPU0_SB_CS_N<2>")
	)
	(segment
		(start 380.068836 -246.853964)
		(end 380.068582 -246.853964)
		(width 0.088646)
		(layer "In4.Cu")
		(net "M_G_CPU0_SB_CS_N<2>")
	)
	(segment
		(start 417.821872 -246.486426)
		(end 417.369244 -246.486426)
		(width 0.18288)
		(layer "In4.Cu")
		(net "M_G_CPU0_SB_CS_N<2>")
	)
	(segment
		(start 434.001672 -245.780814)
		(end 433.841652 -245.620794)
		(width 0.18288)
		(layer "In4.Cu")
		(net "M_G_CPU0_SB_CS_N<2>")
	)
	(segment
		(start 380.448312 -246.856758)
		(end 380.44755 -246.856504)
		(width 0.088646)
		(layer "In4.Cu")
		(net "M_G_CPU0_SB_CS_N<2>")
	)
	(segment
		(start 427.167294 -246.359426)
		(end 426.67174 -246.359426)
		(width 0.18288)
		(layer "In4.Cu")
		(net "M_G_CPU0_SB_CS_N<2>")
	)
	(segment
		(start 410.486098 -246.123206)
		(end 410.326078 -246.283226)
		(width 0.18288)
		(layer "In4.Cu")
		(net "M_G_CPU0_SB_CS_N<2>")
	)
	(segment
		(start 429.718724 -246.19204)
		(end 429.718724 -246.391176)
		(width 0.18288)
		(layer "In4.Cu")
		(net "M_G_CPU0_SB_CS_N<2>")
	)
	(segment
		(start 421.160448 -246.192802)
		(end 421.160194 -246.192548)
		(width 0.18288)
		(layer "In4.Cu")
		(net "M_G_CPU0_SB_CS_N<2>")
	)
	(segment
		(start 425.79544 -245.863872)
		(end 425.79544 -246.176546)
		(width 0.18288)
		(layer "In4.Cu")
		(net "M_G_CPU0_SB_CS_N<2>")
	)
	(segment
		(start 433.473606 -245.620794)
		(end 433.301902 -245.792498)
		(width 0.18288)
		(layer "In4.Cu")
		(net "M_G_CPU0_SB_CS_N<2>")
	)
	(segment
		(start 378.53493 -246.837708)
		(end 377.90628 -246.364506)
		(width 0.088646)
		(layer "In4.Cu")
		(net "M_G_CPU0_SB_CS_N<2>")
	)
	(segment
		(start 416.12439 -245.605046)
		(end 415.96437 -245.445026)
		(width 0.18288)
		(layer "In4.Cu")
		(net "M_G_CPU0_SB_CS_N<2>")
	)
	(segment
		(start 396.506954 -245.597934)
		(end 396.106904 -245.997984)
		(width 0.18288)
		(layer "In4.Cu")
		(net "M_G_CPU0_SB_CS_N<2>")
	)
	(segment
		(start 389.228076 -245.997984)
		(end 387.585458 -246.67845)
		(width 0.18288)
		(layer "In4.Cu")
		(net "M_G_CPU0_SB_CS_N<2>")
	)
	(segment
		(start 412.437834 -246.099584)
		(end 412.437834 -246.158766)
		(width 0.18288)
		(layer "In4.Cu")
		(net "M_G_CPU0_SB_CS_N<2>")
	)
	(segment
		(start 434.001672 -246.126508)
		(end 434.001672 -245.780814)
		(width 0.18288)
		(layer "In4.Cu")
		(net "M_G_CPU0_SB_CS_N<2>")
	)
	(segment
		(start 433.841652 -245.620794)
		(end 433.473606 -245.620794)
		(width 0.18288)
		(layer "In4.Cu")
		(net "M_G_CPU0_SB_CS_N<2>")
	)
	(segment
		(start 414.103312 -245.445026)
		(end 413.57677 -245.971568)
		(width 0.18288)
		(layer "In4.Cu")
		(net "M_G_CPU0_SB_CS_N<2>")
	)
	(segment
		(start 415.36239 -245.855236)
		(end 415.20237 -246.015256)
		(width 0.18288)
		(layer "In4.Cu")
		(net "M_G_CPU0_SB_CS_N<2>")
	)
	(segment
		(start 414.6423 -245.636796)
		(end 414.45053 -245.445026)
		(width 0.18288)
		(layer "In4.Cu")
		(net "M_G_CPU0_SB_CS_N<2>")
	)
	(segment
		(start 417.369244 -246.486426)
		(end 417.013644 -246.130826)
		(width 0.18288)
		(layer "In4.Cu")
		(net "M_G_CPU0_SB_CS_N<2>")
	)
	(segment
		(start 411.226254 -246.13362)
		(end 411.226254 -245.986554)
		(width 0.18288)
		(layer "In4.Cu")
		(net "M_G_CPU0_SB_CS_N<2>")
	)
	(segment
		(start 434.161692 -246.286528)
		(end 434.001672 -246.126508)
		(width 0.18288)
		(layer "In4.Cu")
		(net "M_G_CPU0_SB_CS_N<2>")
	)
	(segment
		(start 415.36239 -245.605046)
		(end 415.36239 -245.855236)
		(width 0.18288)
		(layer "In4.Cu")
		(net "M_G_CPU0_SB_CS_N<2>")
	)
	(segment
		(start 418.698172 -246.303546)
		(end 418.698172 -245.833646)
		(width 0.18288)
		(layer "In4.Cu")
		(net "M_G_CPU0_SB_CS_N<2>")
	)
	(segment
		(start 408.051254 -246.077486)
		(end 404.633176 -246.077486)
		(width 0.18288)
		(layer "In4.Cu")
		(net "M_G_CPU0_SB_CS_N<2>")
	)
	(segment
		(start 418.004752 -246.303546)
		(end 417.821872 -246.486426)
		(width 0.18288)
		(layer "In4.Cu")
		(net "M_G_CPU0_SB_CS_N<2>")
	)
	(segment
		(start 433.141882 -246.286528)
		(end 430.845976 -246.286528)
		(width 0.18288)
		(layer "In4.Cu")
		(net "M_G_CPU0_SB_CS_N<2>")
	)
	(segment
		(start 411.066234 -245.826534)
		(end 410.669232 -245.826534)
		(width 0.18288)
		(layer "In4.Cu")
		(net "M_G_CPU0_SB_CS_N<2>")
	)
	(segment
		(start 418.881052 -246.486426)
		(end 418.698172 -246.303546)
		(width 0.18288)
		(layer "In4.Cu")
		(net "M_G_CPU0_SB_CS_N<2>")
	)
	(segment
		(start 421.160194 -246.192548)
		(end 419.968172 -246.192548)
		(width 0.18288)
		(layer "In4.Cu")
		(net "M_G_CPU0_SB_CS_N<2>")
	)
	(segment
		(start 415.52241 -245.445026)
		(end 415.36239 -245.605046)
		(width 0.18288)
		(layer "In4.Cu")
		(net "M_G_CPU0_SB_CS_N<2>")
	)
	(segment
		(start 418.004752 -245.833646)
		(end 418.004752 -246.303546)
		(width 0.18288)
		(layer "In4.Cu")
		(net "M_G_CPU0_SB_CS_N<2>")
	)
	(segment
		(start 426.48886 -245.863872)
		(end 426.30598 -245.680992)
		(width 0.18288)
		(layer "In4.Cu")
		(net "M_G_CPU0_SB_CS_N<2>")
	)
	(segment
		(start 411.433264 -246.34063)
		(end 411.226254 -246.13362)
		(width 0.18288)
		(layer "In4.Cu")
		(net "M_G_CPU0_SB_CS_N<2>")
	)
	(segment
		(start 403.47519 -245.597934)
		(end 396.506954 -245.597934)
		(width 0.18288)
		(layer "In4.Cu")
		(net "M_G_CPU0_SB_CS_N<2>")
	)
	(segment
		(start 425.211748 -246.359426)
		(end 425.045124 -246.192802)
		(width 0.18288)
		(layer "In4.Cu")
		(net "M_G_CPU0_SB_CS_N<2>")
	)
	(segment
		(start 385.766564 -247.087644)
		(end 385.582922 -247.087644)
		(width 0.088646)
		(layer "In4.Cu")
		(net "M_G_CPU0_SB_CS_N<2>")
	)
	(segment
		(start 430.591468 -246.03202)
		(end 429.878744 -246.03202)
		(width 0.18288)
		(layer "In4.Cu")
		(net "M_G_CPU0_SB_CS_N<2>")
	)
	(segment
		(start 429.878744 -246.03202)
		(end 429.718724 -246.19204)
		(width 0.18288)
		(layer "In4.Cu")
		(net "M_G_CPU0_SB_CS_N<2>")
	)
	(segment
		(start 416.28441 -246.130826)
		(end 416.12439 -245.970806)
		(width 0.18288)
		(layer "In4.Cu")
		(net "M_G_CPU0_SB_CS_N<2>")
	)
	(segment
		(start 414.45053 -245.445026)
		(end 414.103312 -245.445026)
		(width 0.18288)
		(layer "In4.Cu")
		(net "M_G_CPU0_SB_CS_N<2>")
	)
	(segment
		(start 382.888236 -246.853964)
		(end 382.8796 -246.85879)
		(width 0.088646)
		(layer "In4.Cu")
		(net "M_G_CPU0_SB_CS_N<2>")
	)
	(segment
		(start 427.335188 -246.191532)
		(end 427.167294 -246.359426)
		(width 0.18288)
		(layer "In4.Cu")
		(net "M_G_CPU0_SB_CS_N<2>")
	)
	(segment
		(start 433.301902 -246.126508)
		(end 433.141882 -246.286528)
		(width 0.18288)
		(layer "In4.Cu")
		(net "M_G_CPU0_SB_CS_N<2>")
	)
	(segment
		(start 425.61256 -246.359426)
		(end 425.211748 -246.359426)
		(width 0.18288)
		(layer "In4.Cu")
		(net "M_G_CPU0_SB_CS_N<2>")
	)
	(segment
		(start 415.96437 -245.445026)
		(end 415.52241 -245.445026)
		(width 0.18288)
		(layer "In4.Cu")
		(net "M_G_CPU0_SB_CS_N<2>")
	)
	(segment
		(start 435.303676 -246.286528)
		(end 434.161692 -246.286528)
		(width 0.18288)
		(layer "In4.Cu")
		(net "M_G_CPU0_SB_CS_N<2>")
	)
	(segment
		(start 429.718724 -246.391176)
		(end 429.558704 -246.551196)
		(width 0.18288)
		(layer "In4.Cu")
		(net "M_G_CPU0_SB_CS_N<2>")
	)
	(segment
		(start 415.20237 -246.015256)
		(end 414.80232 -246.015256)
		(width 0.18288)
		(layer "In4.Cu")
		(net "M_G_CPU0_SB_CS_N<2>")
	)
	(segment
		(start 414.6423 -245.855236)
		(end 414.6423 -245.636796)
		(width 0.18288)
		(layer "In4.Cu")
		(net "M_G_CPU0_SB_CS_N<2>")
	)
	(segment
		(start 428.85106 -246.191532)
		(end 427.335188 -246.191532)
		(width 0.18288)
		(layer "In4.Cu")
		(net "M_G_CPU0_SB_CS_N<2>")
	)
	(segment
		(start 379.128782 -246.853964)
		(end 379.128528 -246.853964)
		(width 0.088646)
		(layer "In4.Cu")
		(net "M_G_CPU0_SB_CS_N<2>")
	)
	(arc
		(start 380.926086 -246.902224)
		(mid 380.727007 -246.955387)
		(end 380.52883 -246.898922)
		(width 0.088646)
		(layer "In4.Cu")
		(net "M_G_CPU0_SB_CS_N<2>")
	)
	(arc
		(start 384.202432 -246.853964)
		(mid 384.015234 -246.803821)
		(end 383.828036 -246.853964)
		(width 0.088646)
		(layer "In4.Cu")
		(net "M_G_CPU0_SB_CS_N<2>")
	)
	(arc
		(start 380.52883 -246.898922)
		(mid 380.509322 -246.887809)
		(end 380.489206 -246.87784)
		(width 0.088646)
		(layer "In4.Cu")
		(net "M_G_CPU0_SB_CS_N<2>")
	)
	(arc
		(start 379.503178 -246.853964)
		(mid 379.31598 -246.803821)
		(end 379.128782 -246.853964)
		(width 0.088646)
		(layer "In4.Cu")
		(net "M_G_CPU0_SB_CS_N<2>")
	)
	(arc
		(start 382.322832 -246.853964)
		(mid 382.135634 -246.803821)
		(end 381.948436 -246.853964)
		(width 0.088646)
		(layer "In4.Cu")
		(net "M_G_CPU0_SB_CS_N<2>")
	)
	(arc
		(start 380.05385 -246.8626)
		(mid 379.777375 -246.92992)
		(end 379.503178 -246.853964)
		(width 0.088646)
		(layer "In4.Cu")
		(net "M_G_CPU0_SB_CS_N<2>")
	)
	(arc
		(start 381.938022 -246.86006)
		(mid 381.65959 -246.929906)
		(end 381.382778 -246.853964)
		(width 0.088646)
		(layer "In4.Cu")
		(net "M_G_CPU0_SB_CS_N<2>")
	)
	(arc
		(start 381.382778 -246.853964)
		(mid 381.19558 -246.803821)
		(end 381.008382 -246.853964)
		(width 0.088646)
		(layer "In4.Cu")
		(net "M_G_CPU0_SB_CS_N<2>")
	)
	(arc
		(start 380.44755 -246.856504)
		(mid 380.258539 -246.803837)
		(end 380.068836 -246.853964)
		(width 0.088646)
		(layer "In4.Cu")
		(net "M_G_CPU0_SB_CS_N<2>")
	)
	(arc
		(start 380.489206 -246.87784)
		(mid 380.468545 -246.867715)
		(end 380.448312 -246.856758)
		(width 0.088646)
		(layer "In4.Cu")
		(net "M_G_CPU0_SB_CS_N<2>")
	)
	(arc
		(start 383.828036 -246.853964)
		(mid 383.545334 -246.929706)
		(end 383.262632 -246.853964)
		(width 0.088646)
		(layer "In4.Cu")
		(net "M_G_CPU0_SB_CS_N<2>")
	)
	(arc
		(start 382.877568 -246.86006)
		(mid 382.59939 -246.929783)
		(end 382.322832 -246.853964)
		(width 0.088646)
		(layer "In4.Cu")
		(net "M_G_CPU0_SB_CS_N<2>")
	)
	(arc
		(start 379.128528 -246.853964)
		(mid 378.84608 -246.929647)
		(end 378.563632 -246.853964)
		(width 0.088646)
		(layer "In4.Cu")
		(net "M_G_CPU0_SB_CS_N<2>")
	)
	(arc
		(start 384.767836 -246.853964)
		(mid 384.485134 -246.92974)
		(end 384.202432 -246.853964)
		(width 0.088646)
		(layer "In4.Cu")
		(net "M_G_CPU0_SB_CS_N<2>")
	)
	(arc
		(start 385.142232 -246.853964)
		(mid 384.955034 -246.803821)
		(end 384.767836 -246.853964)
		(width 0.088646)
		(layer "In4.Cu")
		(net "M_G_CPU0_SB_CS_N<2>")
	)
	(arc
		(start 385.424934 -246.929656)
		(mid 385.27859 -246.910448)
		(end 385.142232 -246.853964)
		(width 0.088646)
		(layer "In4.Cu")
		(net "M_G_CPU0_SB_CS_N<2>")
	)
	(arc
		(start 383.262632 -246.853964)
		(mid 383.075434 -246.803821)
		(end 382.888236 -246.853964)
		(width 0.088646)
		(layer "In4.Cu")
		(net "M_G_CPU0_SB_CS_N<2>")
	)
	(segment
		(start 379.31598 -246.08663)
		(end 379.316234 -246.086376)
		(width 0.20066)
		(layer "F.Cu")
		(net "M_G_CPU0_SB_CS_N<1>")
	)
	(segment
		(start 379.316234 -246.086376)
		(end 379.316234 -245.55069)
		(width 0.20066)
		(layer "F.Cu")
		(net "M_G_CPU0_SB_CS_N<1>")
	)
	(segment
		(start 448.572382 -244.916706)
		(end 447.467482 -244.916706)
		(width 0.20066)
		(layer "F.Cu")
		(net "M_G_CPU0_SB_CS_N<1>")
	)
	(segment
		(start 407.365708 -243.642642)
		(end 407.365454 -243.642388)
		(width 0.18288)
		(layer "In4.Cu")
		(net "M_G_CPU0_SB_CS_N<1>")
	)
	(segment
		(start 441.846716 -244.489478)
		(end 440.145678 -242.78844)
		(width 0.18288)
		(layer "In4.Cu")
		(net "M_G_CPU0_SB_CS_N<1>")
	)
	(segment
		(start 433.787042 -243.029232)
		(end 433.224432 -243.029232)
		(width 0.18288)
		(layer "In4.Cu")
		(net "M_G_CPU0_SB_CS_N<1>")
	)
	(segment
		(start 403.385782 -244.091206)
		(end 395.706346 -244.091206)
		(width 0.18288)
		(layer "In4.Cu")
		(net "M_G_CPU0_SB_CS_N<1>")
	)
	(segment
		(start 380.442978 -245.875048)
		(end 380.427484 -245.883938)
		(width 0.088646)
		(layer "In4.Cu")
		(net "M_G_CPU0_SB_CS_N<1>")
	)
	(segment
		(start 432.904392 -243.642388)
		(end 427.422056 -243.642388)
		(width 0.18288)
		(layer "In4.Cu")
		(net "M_G_CPU0_SB_CS_N<1>")
	)
	(segment
		(start 414.174178 -243.642642)
		(end 407.365708 -243.642642)
		(width 0.18288)
		(layer "In4.Cu")
		(net "M_G_CPU0_SB_CS_N<1>")
	)
	(segment
		(start 394.805408 -244.992144)
		(end 388.850124 -244.992144)
		(width 0.18288)
		(layer "In4.Cu")
		(net "M_G_CPU0_SB_CS_N<1>")
	)
	(segment
		(start 447.467482 -244.916706)
		(end 447.040254 -244.489478)
		(width 0.18288)
		(layer "In4.Cu")
		(net "M_G_CPU0_SB_CS_N<1>")
	)
	(segment
		(start 386.504942 -245.711726)
		(end 386.199634 -245.406418)
		(width 0.18288)
		(layer "In4.Cu")
		(net "M_G_CPU0_SB_CS_N<1>")
	)
	(segment
		(start 414.708594 -243.108226)
		(end 414.174178 -243.642642)
		(width 0.18288)
		(layer "In4.Cu")
		(net "M_G_CPU0_SB_CS_N<1>")
	)
	(segment
		(start 434.129942 -243.642388)
		(end 433.947062 -243.459508)
		(width 0.18288)
		(layer "In4.Cu")
		(net "M_G_CPU0_SB_CS_N<1>")
	)
	(segment
		(start 447.040254 -244.489478)
		(end 441.846716 -244.489478)
		(width 0.18288)
		(layer "In4.Cu")
		(net "M_G_CPU0_SB_CS_N<1>")
	)
	(segment
		(start 433.947062 -243.189252)
		(end 433.787042 -243.029232)
		(width 0.18288)
		(layer "In4.Cu")
		(net "M_G_CPU0_SB_CS_N<1>")
	)
	(segment
		(start 418.271452 -243.642388)
		(end 418.271198 -243.642642)
		(width 0.18288)
		(layer "In4.Cu")
		(net "M_G_CPU0_SB_CS_N<1>")
	)
	(segment
		(start 387.221984 -245.711726)
		(end 386.504942 -245.711726)
		(width 0.18288)
		(layer "In4.Cu")
		(net "M_G_CPU0_SB_CS_N<1>")
	)
	(segment
		(start 440.145678 -242.78844)
		(end 438.527698 -242.78844)
		(width 0.18288)
		(layer "In4.Cu")
		(net "M_G_CPU0_SB_CS_N<1>")
	)
	(segment
		(start 433.224432 -243.029232)
		(end 433.064412 -243.189252)
		(width 0.18288)
		(layer "In4.Cu")
		(net "M_G_CPU0_SB_CS_N<1>")
	)
	(segment
		(start 425.083478 -243.642388)
		(end 418.271452 -243.642388)
		(width 0.18288)
		(layer "In4.Cu")
		(net "M_G_CPU0_SB_CS_N<1>")
	)
	(segment
		(start 382.888236 -245.875048)
		(end 382.8796 -245.870222)
		(width 0.088646)
		(layer "In4.Cu")
		(net "M_G_CPU0_SB_CS_N<1>")
	)
	(segment
		(start 418.271198 -243.642642)
		(end 416.64001 -243.642642)
		(width 0.18288)
		(layer "In4.Cu")
		(net "M_G_CPU0_SB_CS_N<1>")
	)
	(segment
		(start 380.081028 -245.882668)
		(end 379.70206 -245.656862)
		(width 0.088646)
		(layer "In4.Cu")
		(net "M_G_CPU0_SB_CS_N<1>")
	)
	(segment
		(start 433.064412 -243.482368)
		(end 432.904392 -243.642388)
		(width 0.18288)
		(layer "In4.Cu")
		(net "M_G_CPU0_SB_CS_N<1>")
	)
	(segment
		(start 385.766564 -245.406418)
		(end 384.689858 -245.406418)
		(width 0.088646)
		(layer "In4.Cu")
		(net "M_G_CPU0_SB_CS_N<1>")
	)
	(segment
		(start 437.67375 -243.642388)
		(end 434.129942 -243.642388)
		(width 0.18288)
		(layer "In4.Cu")
		(net "M_G_CPU0_SB_CS_N<1>")
	)
	(segment
		(start 388.773924 -245.068344)
		(end 387.221984 -245.711726)
		(width 0.18288)
		(layer "In4.Cu")
		(net "M_G_CPU0_SB_CS_N<1>")
	)
	(segment
		(start 433.947062 -243.459508)
		(end 433.947062 -243.189252)
		(width 0.18288)
		(layer "In4.Cu")
		(net "M_G_CPU0_SB_CS_N<1>")
	)
	(segment
		(start 416.64001 -243.642642)
		(end 416.105594 -243.108226)
		(width 0.18288)
		(layer "In4.Cu")
		(net "M_G_CPU0_SB_CS_N<1>")
	)
	(segment
		(start 381.008382 -245.875048)
		(end 380.99365 -245.866412)
		(width 0.088646)
		(layer "In4.Cu")
		(net "M_G_CPU0_SB_CS_N<1>")
	)
	(segment
		(start 427.422056 -243.642388)
		(end 427.192694 -243.413026)
		(width 0.18288)
		(layer "In4.Cu")
		(net "M_G_CPU0_SB_CS_N<1>")
	)
	(segment
		(start 395.706346 -244.091206)
		(end 394.805408 -244.992144)
		(width 0.18288)
		(layer "In4.Cu")
		(net "M_G_CPU0_SB_CS_N<1>")
	)
	(segment
		(start 416.105594 -243.108226)
		(end 414.708594 -243.108226)
		(width 0.18288)
		(layer "In4.Cu")
		(net "M_G_CPU0_SB_CS_N<1>")
	)
	(segment
		(start 427.192694 -243.413026)
		(end 425.31284 -243.413026)
		(width 0.18288)
		(layer "In4.Cu")
		(net "M_G_CPU0_SB_CS_N<1>")
	)
	(segment
		(start 425.31284 -243.413026)
		(end 425.083478 -243.642388)
		(width 0.18288)
		(layer "In4.Cu")
		(net "M_G_CPU0_SB_CS_N<1>")
	)
	(segment
		(start 407.365454 -243.642388)
		(end 403.8346 -243.642388)
		(width 0.18288)
		(layer "In4.Cu")
		(net "M_G_CPU0_SB_CS_N<1>")
	)
	(segment
		(start 438.527698 -242.78844)
		(end 437.67375 -243.642388)
		(width 0.18288)
		(layer "In4.Cu")
		(net "M_G_CPU0_SB_CS_N<1>")
	)
	(segment
		(start 381.020828 -245.882668)
		(end 381.00889 -245.875556)
		(width 0.088646)
		(layer "In4.Cu")
		(net "M_G_CPU0_SB_CS_N<1>")
	)
	(segment
		(start 388.850124 -244.992144)
		(end 388.773924 -245.068344)
		(width 0.18288)
		(layer "In4.Cu")
		(net "M_G_CPU0_SB_CS_N<1>")
	)
	(segment
		(start 384.689858 -245.406418)
		(end 384.28041 -245.815866)
		(width 0.088646)
		(layer "In4.Cu")
		(net "M_G_CPU0_SB_CS_N<1>")
	)
	(segment
		(start 433.064412 -243.189252)
		(end 433.064412 -243.482368)
		(width 0.18288)
		(layer "In4.Cu")
		(net "M_G_CPU0_SB_CS_N<1>")
	)
	(segment
		(start 403.8346 -243.642388)
		(end 403.385782 -244.091206)
		(width 0.18288)
		(layer "In4.Cu")
		(net "M_G_CPU0_SB_CS_N<1>")
	)
	(segment
		(start 382.8796 -245.870222)
		(end 382.877568 -245.868952)
		(width 0.088646)
		(layer "In4.Cu")
		(net "M_G_CPU0_SB_CS_N<1>")
	)
	(segment
		(start 381.383032 -245.875048)
		(end 381.383032 -245.875302)
		(width 0.088646)
		(layer "In4.Cu")
		(net "M_G_CPU0_SB_CS_N<1>")
	)
	(segment
		(start 386.199634 -245.406418)
		(end 385.766564 -245.406418)
		(width 0.18288)
		(layer "In4.Cu")
		(net "M_G_CPU0_SB_CS_N<1>")
	)
	(arc
		(start 383.828036 -245.875048)
		(mid 383.545334 -245.799272)
		(end 383.262632 -245.875048)
		(width 0.088646)
		(layer "In4.Cu")
		(net "M_G_CPU0_SB_CS_N<1>")
	)
	(arc
		(start 382.877568 -245.868952)
		(mid 382.59939 -245.799229)
		(end 382.322832 -245.875048)
		(width 0.088646)
		(layer "In4.Cu")
		(net "M_G_CPU0_SB_CS_N<1>")
	)
	(arc
		(start 384.28041 -245.815866)
		(mid 384.24336 -245.848012)
		(end 384.202432 -245.875048)
		(width 0.088646)
		(layer "In4.Cu")
		(net "M_G_CPU0_SB_CS_N<1>")
	)
	(arc
		(start 380.99365 -245.866412)
		(mid 380.717175 -245.799092)
		(end 380.442978 -245.875048)
		(width 0.088646)
		(layer "In4.Cu")
		(net "M_G_CPU0_SB_CS_N<1>")
	)
	(arc
		(start 379.70206 -245.656862)
		(mid 379.516323 -245.577691)
		(end 379.316234 -245.55069)
		(width 0.088646)
		(layer "In4.Cu")
		(net "M_G_CPU0_SB_CS_N<1>")
	)
	(arc
		(start 384.202432 -245.875048)
		(mid 384.015234 -245.925191)
		(end 383.828036 -245.875048)
		(width 0.088646)
		(layer "In4.Cu")
		(net "M_G_CPU0_SB_CS_N<1>")
	)
	(arc
		(start 383.262632 -245.875048)
		(mid 383.075434 -245.925191)
		(end 382.888236 -245.875048)
		(width 0.088646)
		(layer "In4.Cu")
		(net "M_G_CPU0_SB_CS_N<1>")
	)
	(arc
		(start 381.948436 -245.875048)
		(mid 381.665734 -245.799272)
		(end 381.383032 -245.875048)
		(width 0.088646)
		(layer "In4.Cu")
		(net "M_G_CPU0_SB_CS_N<1>")
	)
	(arc
		(start 381.383032 -245.875302)
		(mid 381.202887 -245.925589)
		(end 381.020828 -245.882668)
		(width 0.088646)
		(layer "In4.Cu")
		(net "M_G_CPU0_SB_CS_N<1>")
	)
	(arc
		(start 381.00889 -245.875556)
		(mid 381.008636 -245.875302)
		(end 381.008382 -245.875048)
		(width 0.088646)
		(layer "In4.Cu")
		(net "M_G_CPU0_SB_CS_N<1>")
	)
	(arc
		(start 382.322832 -245.875048)
		(mid 382.135634 -245.925191)
		(end 381.948436 -245.875048)
		(width 0.088646)
		(layer "In4.Cu")
		(net "M_G_CPU0_SB_CS_N<1>")
	)
	(arc
		(start 380.427484 -245.883938)
		(mid 380.254106 -245.925686)
		(end 380.081028 -245.882668)
		(width 0.088646)
		(layer "In4.Cu")
		(net "M_G_CPU0_SB_CS_N<1>")
	)
	(segment
		(start 379.78588 -246.900192)
		(end 379.78588 -246.364506)
		(width 0.20066)
		(layer "F.Cu")
		(net "M_G_CPU0_SB_CS_N<0>")
	)
	(segment
		(start 444.472314 -245.76659)
		(end 443.367414 -245.76659)
		(width 0.20066)
		(layer "F.Cu")
		(net "M_G_CPU0_SB_CS_N<0>")
	)
	(segment
		(start 379.786134 -246.900446)
		(end 379.78588 -246.900192)
		(width 0.20066)
		(layer "F.Cu")
		(net "M_G_CPU0_SB_CS_N<0>")
	)
	(segment
		(start 396.300706 -245.100094)
		(end 395.738096 -245.662704)
		(width 0.18288)
		(layer "In4.Cu")
		(net "M_G_CPU0_SB_CS_N<0>")
	)
	(segment
		(start 441.292234 -246.032528)
		(end 441.292234 -245.07571)
		(width 0.18288)
		(layer "In4.Cu")
		(net "M_G_CPU0_SB_CS_N<0>")
	)
	(segment
		(start 439.239152 -245.52148)
		(end 439.239152 -246.529352)
		(width 0.18288)
		(layer "In4.Cu")
		(net "M_G_CPU0_SB_CS_N<0>")
	)
	(segment
		(start 427.395894 -245.165626)
		(end 425.211494 -245.165626)
		(width 0.18288)
		(layer "In4.Cu")
		(net "M_G_CPU0_SB_CS_N<0>")
	)
	(segment
		(start 408.002994 -245.521226)
		(end 407.331926 -245.521226)
		(width 0.18288)
		(layer "In4.Cu")
		(net "M_G_CPU0_SB_CS_N<0>")
	)
	(segment
		(start 436.21833 -245.34241)
		(end 435.374034 -245.34241)
		(width 0.18288)
		(layer "In4.Cu")
		(net "M_G_CPU0_SB_CS_N<0>")
	)
	(segment
		(start 415.749994 -244.454426)
		(end 415.064194 -244.454426)
		(width 0.18288)
		(layer "In4.Cu")
		(net "M_G_CPU0_SB_CS_N<0>")
	)
	(segment
		(start 424.119294 -245.564406)
		(end 423.619168 -245.564406)
		(width 0.18288)
		(layer "In4.Cu")
		(net "M_G_CPU0_SB_CS_N<0>")
	)
	(segment
		(start 443.367414 -245.76659)
		(end 442.905388 -246.228616)
		(width 0.18288)
		(layer "In4.Cu")
		(net "M_G_CPU0_SB_CS_N<0>")
	)
	(segment
		(start 440.338464 -245.34495)
		(end 439.415682 -245.34495)
		(width 0.18288)
		(layer "In4.Cu")
		(net "M_G_CPU0_SB_CS_N<0>")
	)
	(segment
		(start 441.488322 -246.228616)
		(end 441.292234 -246.032528)
		(width 0.18288)
		(layer "In4.Cu")
		(net "M_G_CPU0_SB_CS_N<0>")
	)
	(segment
		(start 387.380226 -246.390922)
		(end 387.031738 -246.73941)
		(width 0.18288)
		(layer "In4.Cu")
		(net "M_G_CPU0_SB_CS_N<0>")
	)
	(segment
		(start 407.331926 -245.521226)
		(end 407.171906 -245.361206)
		(width 0.18288)
		(layer "In4.Cu")
		(net "M_G_CPU0_SB_CS_N<0>")
	)
	(segment
		(start 435.374034 -245.34241)
		(end 435.14645 -245.114826)
		(width 0.18288)
		(layer "In4.Cu")
		(net "M_G_CPU0_SB_CS_N<0>")
	)
	(segment
		(start 437.411114 -245.38051)
		(end 437.251094 -245.54053)
		(width 0.18288)
		(layer "In4.Cu")
		(net "M_G_CPU0_SB_CS_N<0>")
	)
	(segment
		(start 424.34129 -245.34241)
		(end 424.119294 -245.564406)
		(width 0.18288)
		(layer "In4.Cu")
		(net "M_G_CPU0_SB_CS_N<0>")
	)
	(segment
		(start 408.358594 -245.165626)
		(end 408.002994 -245.521226)
		(width 0.18288)
		(layer "In4.Cu")
		(net "M_G_CPU0_SB_CS_N<0>")
	)
	(segment
		(start 438.545732 -246.529352)
		(end 438.545732 -245.54053)
		(width 0.18288)
		(layer "In4.Cu")
		(net "M_G_CPU0_SB_CS_N<0>")
	)
	(segment
		(start 436.397654 -245.331234)
		(end 436.229506 -245.331234)
		(width 0.18288)
		(layer "In4.Cu")
		(net "M_G_CPU0_SB_CS_N<0>")
	)
	(segment
		(start 423.619168 -245.564406)
		(end 423.397426 -245.342664)
		(width 0.18288)
		(layer "In4.Cu")
		(net "M_G_CPU0_SB_CS_N<0>")
	)
	(segment
		(start 412.524194 -245.165626)
		(end 408.358594 -245.165626)
		(width 0.18288)
		(layer "In4.Cu")
		(net "M_G_CPU0_SB_CS_N<0>")
	)
	(segment
		(start 425.211494 -245.165626)
		(end 425.03471 -245.34241)
		(width 0.18288)
		(layer "In4.Cu")
		(net "M_G_CPU0_SB_CS_N<0>")
	)
	(segment
		(start 438.545732 -245.54053)
		(end 438.385712 -245.38051)
		(width 0.18288)
		(layer "In4.Cu")
		(net "M_G_CPU0_SB_CS_N<0>")
	)
	(segment
		(start 439.239152 -246.529352)
		(end 439.079132 -246.689372)
		(width 0.18288)
		(layer "In4.Cu")
		(net "M_G_CPU0_SB_CS_N<0>")
	)
	(segment
		(start 387.031738 -246.73941)
		(end 385.766564 -246.73941)
		(width 0.18288)
		(layer "In4.Cu")
		(net "M_G_CPU0_SB_CS_N<0>")
	)
	(segment
		(start 441.132214 -244.91569)
		(end 440.767724 -244.91569)
		(width 0.18288)
		(layer "In4.Cu")
		(net "M_G_CPU0_SB_CS_N<0>")
	)
	(segment
		(start 417.764214 -245.135146)
		(end 417.657534 -245.241826)
		(width 0.18288)
		(layer "In4.Cu")
		(net "M_G_CPU0_SB_CS_N<0>")
	)
	(segment
		(start 379.786134 -246.364506)
		(end 379.78588 -246.364506)
		(width 0.088646)
		(layer "In4.Cu")
		(net "M_G_CPU0_SB_CS_N<0>")
	)
	(segment
		(start 413.895794 -244.886226)
		(end 413.40024 -245.38178)
		(width 0.18288)
		(layer "In4.Cu")
		(net "M_G_CPU0_SB_CS_N<0>")
	)
	(segment
		(start 389.138668 -245.662704)
		(end 387.380226 -246.390922)
		(width 0.18288)
		(layer "In4.Cu")
		(net "M_G_CPU0_SB_CS_N<0>")
	)
	(segment
		(start 380.510034 -246.672354)
		(end 379.786134 -246.364506)
		(width 0.088646)
		(layer "In4.Cu")
		(net "M_G_CPU0_SB_CS_N<0>")
	)
	(segment
		(start 395.738096 -245.662704)
		(end 389.138668 -245.662704)
		(width 0.18288)
		(layer "In4.Cu")
		(net "M_G_CPU0_SB_CS_N<0>")
	)
	(segment
		(start 403.738842 -245.100094)
		(end 396.300706 -245.100094)
		(width 0.18288)
		(layer "In4.Cu")
		(net "M_G_CPU0_SB_CS_N<0>")
	)
	(segment
		(start 413.40024 -245.38178)
		(end 412.740348 -245.38178)
		(width 0.18288)
		(layer "In4.Cu")
		(net "M_G_CPU0_SB_CS_N<0>")
	)
	(segment
		(start 441.292234 -245.07571)
		(end 441.132214 -244.91569)
		(width 0.18288)
		(layer "In4.Cu")
		(net "M_G_CPU0_SB_CS_N<0>")
	)
	(segment
		(start 419.320218 -245.34241)
		(end 419.112954 -245.135146)
		(width 0.18288)
		(layer "In4.Cu")
		(net "M_G_CPU0_SB_CS_N<0>")
	)
	(segment
		(start 437.251094 -246.569738)
		(end 437.091074 -246.729758)
		(width 0.18288)
		(layer "In4.Cu")
		(net "M_G_CPU0_SB_CS_N<0>")
	)
	(segment
		(start 416.537394 -245.241826)
		(end 415.749994 -244.454426)
		(width 0.18288)
		(layer "In4.Cu")
		(net "M_G_CPU0_SB_CS_N<0>")
	)
	(segment
		(start 438.385712 -245.38051)
		(end 437.411114 -245.38051)
		(width 0.18288)
		(layer "In4.Cu")
		(net "M_G_CPU0_SB_CS_N<0>")
	)
	(segment
		(start 380.538482 -246.688864)
		(end 380.510034 -246.672354)
		(width 0.088646)
		(layer "In4.Cu")
		(net "M_G_CPU0_SB_CS_N<0>")
	)
	(segment
		(start 436.717694 -246.729758)
		(end 436.557674 -246.569738)
		(width 0.18288)
		(layer "In4.Cu")
		(net "M_G_CPU0_SB_CS_N<0>")
	)
	(segment
		(start 406.478486 -245.226332)
		(end 406.318466 -245.386352)
		(width 0.18288)
		(layer "In4.Cu")
		(net "M_G_CPU0_SB_CS_N<0>")
	)
	(segment
		(start 412.740348 -245.38178)
		(end 412.524194 -245.165626)
		(width 0.18288)
		(layer "In4.Cu")
		(net "M_G_CPU0_SB_CS_N<0>")
	)
	(segment
		(start 433.047394 -245.338346)
		(end 427.568614 -245.338346)
		(width 0.18288)
		(layer "In4.Cu")
		(net "M_G_CPU0_SB_CS_N<0>")
	)
	(segment
		(start 436.229506 -245.331234)
		(end 436.21833 -245.34241)
		(width 0.18288)
		(layer "In4.Cu")
		(net "M_G_CPU0_SB_CS_N<0>")
	)
	(segment
		(start 435.14645 -245.114826)
		(end 433.270914 -245.114826)
		(width 0.18288)
		(layer "In4.Cu")
		(net "M_G_CPU0_SB_CS_N<0>")
	)
	(segment
		(start 436.557674 -245.491254)
		(end 436.397654 -245.331234)
		(width 0.18288)
		(layer "In4.Cu")
		(net "M_G_CPU0_SB_CS_N<0>")
	)
	(segment
		(start 406.638506 -245.029482)
		(end 406.478486 -245.189502)
		(width 0.18288)
		(layer "In4.Cu")
		(net "M_G_CPU0_SB_CS_N<0>")
	)
	(segment
		(start 407.171906 -245.189502)
		(end 407.011886 -245.029482)
		(width 0.18288)
		(layer "In4.Cu")
		(net "M_G_CPU0_SB_CS_N<0>")
	)
	(segment
		(start 385.766564 -246.73941)
		(end 385.424934 -246.73941)
		(width 0.088646)
		(layer "In4.Cu")
		(net "M_G_CPU0_SB_CS_N<0>")
	)
	(segment
		(start 437.091074 -246.729758)
		(end 436.717694 -246.729758)
		(width 0.18288)
		(layer "In4.Cu")
		(net "M_G_CPU0_SB_CS_N<0>")
	)
	(segment
		(start 425.03471 -245.34241)
		(end 424.34129 -245.34241)
		(width 0.18288)
		(layer "In4.Cu")
		(net "M_G_CPU0_SB_CS_N<0>")
	)
	(segment
		(start 419.112954 -245.135146)
		(end 417.764214 -245.135146)
		(width 0.18288)
		(layer "In4.Cu")
		(net "M_G_CPU0_SB_CS_N<0>")
	)
	(segment
		(start 427.568614 -245.338346)
		(end 427.395894 -245.165626)
		(width 0.18288)
		(layer "In4.Cu")
		(net "M_G_CPU0_SB_CS_N<0>")
	)
	(segment
		(start 414.632394 -244.886226)
		(end 413.895794 -244.886226)
		(width 0.18288)
		(layer "In4.Cu")
		(net "M_G_CPU0_SB_CS_N<0>")
	)
	(segment
		(start 415.064194 -244.454426)
		(end 414.632394 -244.886226)
		(width 0.18288)
		(layer "In4.Cu")
		(net "M_G_CPU0_SB_CS_N<0>")
	)
	(segment
		(start 438.705752 -246.689372)
		(end 438.545732 -246.529352)
		(width 0.18288)
		(layer "In4.Cu")
		(net "M_G_CPU0_SB_CS_N<0>")
	)
	(segment
		(start 406.318466 -245.386352)
		(end 404.429722 -245.386352)
		(width 0.18288)
		(layer "In4.Cu")
		(net "M_G_CPU0_SB_CS_N<0>")
	)
	(segment
		(start 417.657534 -245.241826)
		(end 416.537394 -245.241826)
		(width 0.18288)
		(layer "In4.Cu")
		(net "M_G_CPU0_SB_CS_N<0>")
	)
	(segment
		(start 433.270914 -245.114826)
		(end 433.047394 -245.338346)
		(width 0.18288)
		(layer "In4.Cu")
		(net "M_G_CPU0_SB_CS_N<0>")
	)
	(segment
		(start 439.415682 -245.34495)
		(end 439.239152 -245.52148)
		(width 0.18288)
		(layer "In4.Cu")
		(net "M_G_CPU0_SB_CS_N<0>")
	)
	(segment
		(start 406.478486 -245.189502)
		(end 406.478486 -245.226332)
		(width 0.18288)
		(layer "In4.Cu")
		(net "M_G_CPU0_SB_CS_N<0>")
	)
	(segment
		(start 380.927864 -246.680228)
		(end 380.913132 -246.688864)
		(width 0.088646)
		(layer "In4.Cu")
		(net "M_G_CPU0_SB_CS_N<0>")
	)
	(segment
		(start 420.943532 -245.342664)
		(end 420.943278 -245.34241)
		(width 0.18288)
		(layer "In4.Cu")
		(net "M_G_CPU0_SB_CS_N<0>")
	)
	(segment
		(start 423.397426 -245.342664)
		(end 420.943532 -245.342664)
		(width 0.18288)
		(layer "In4.Cu")
		(net "M_G_CPU0_SB_CS_N<0>")
	)
	(segment
		(start 440.767724 -244.91569)
		(end 440.338464 -245.34495)
		(width 0.18288)
		(layer "In4.Cu")
		(net "M_G_CPU0_SB_CS_N<0>")
	)
	(segment
		(start 407.011886 -245.029482)
		(end 406.638506 -245.029482)
		(width 0.18288)
		(layer "In4.Cu")
		(net "M_G_CPU0_SB_CS_N<0>")
	)
	(segment
		(start 437.251094 -245.54053)
		(end 437.251094 -246.569738)
		(width 0.18288)
		(layer "In4.Cu")
		(net "M_G_CPU0_SB_CS_N<0>")
	)
	(segment
		(start 420.943278 -245.34241)
		(end 419.320218 -245.34241)
		(width 0.18288)
		(layer "In4.Cu")
		(net "M_G_CPU0_SB_CS_N<0>")
	)
	(segment
		(start 404.429722 -245.386352)
		(end 403.738842 -245.100094)
		(width 0.18288)
		(layer "In4.Cu")
		(net "M_G_CPU0_SB_CS_N<0>")
	)
	(segment
		(start 439.079132 -246.689372)
		(end 438.705752 -246.689372)
		(width 0.18288)
		(layer "In4.Cu")
		(net "M_G_CPU0_SB_CS_N<0>")
	)
	(segment
		(start 407.171906 -245.361206)
		(end 407.171906 -245.189502)
		(width 0.18288)
		(layer "In4.Cu")
		(net "M_G_CPU0_SB_CS_N<0>")
	)
	(segment
		(start 442.905388 -246.228616)
		(end 441.488322 -246.228616)
		(width 0.18288)
		(layer "In4.Cu")
		(net "M_G_CPU0_SB_CS_N<0>")
	)
	(segment
		(start 436.557674 -246.569738)
		(end 436.557674 -245.491254)
		(width 0.18288)
		(layer "In4.Cu")
		(net "M_G_CPU0_SB_CS_N<0>")
	)
	(segment
		(start 380.913132 -246.688864)
		(end 380.912878 -246.688864)
		(width 0.088646)
		(layer "In4.Cu")
		(net "M_G_CPU0_SB_CS_N<0>")
	)
	(arc
		(start 385.424934 -246.73941)
		(mid 385.328011 -246.726452)
		(end 385.237736 -246.688864)
		(width 0.088646)
		(layer "In4.Cu")
		(net "M_G_CPU0_SB_CS_N<0>")
	)
	(arc
		(start 381.478536 -246.688864)
		(mid 381.204337 -246.613029)
		(end 380.927864 -246.680228)
		(width 0.088646)
		(layer "In4.Cu")
		(net "M_G_CPU0_SB_CS_N<0>")
	)
	(arc
		(start 383.732532 -246.688864)
		(mid 383.545334 -246.739007)
		(end 383.358136 -246.688864)
		(width 0.088646)
		(layer "In4.Cu")
		(net "M_G_CPU0_SB_CS_N<0>")
	)
	(arc
		(start 384.297936 -246.688864)
		(mid 384.015234 -246.613088)
		(end 383.732532 -246.688864)
		(width 0.088646)
		(layer "In4.Cu")
		(net "M_G_CPU0_SB_CS_N<0>")
	)
	(arc
		(start 385.237736 -246.688864)
		(mid 384.955034 -246.613088)
		(end 384.672332 -246.688864)
		(width 0.088646)
		(layer "In4.Cu")
		(net "M_G_CPU0_SB_CS_N<0>")
	)
	(arc
		(start 380.912878 -246.688864)
		(mid 380.72568 -246.739041)
		(end 380.538482 -246.688864)
		(width 0.088646)
		(layer "In4.Cu")
		(net "M_G_CPU0_SB_CS_N<0>")
	)
	(arc
		(start 384.672332 -246.688864)
		(mid 384.485134 -246.739007)
		(end 384.297936 -246.688864)
		(width 0.088646)
		(layer "In4.Cu")
		(net "M_G_CPU0_SB_CS_N<0>")
	)
	(arc
		(start 382.792732 -246.688864)
		(mid 382.605534 -246.739007)
		(end 382.418336 -246.688864)
		(width 0.088646)
		(layer "In4.Cu")
		(net "M_G_CPU0_SB_CS_N<0>")
	)
	(arc
		(start 383.358136 -246.688864)
		(mid 383.075434 -246.613088)
		(end 382.792732 -246.688864)
		(width 0.088646)
		(layer "In4.Cu")
		(net "M_G_CPU0_SB_CS_N<0>")
	)
	(arc
		(start 381.852932 -246.688864)
		(mid 381.665734 -246.739007)
		(end 381.478536 -246.688864)
		(width 0.088646)
		(layer "In4.Cu")
		(net "M_G_CPU0_SB_CS_N<0>")
	)
	(arc
		(start 382.418336 -246.688864)
		(mid 382.135634 -246.613088)
		(end 381.852932 -246.688864)
		(width 0.088646)
		(layer "In4.Cu")
		(net "M_G_CPU0_SB_CS_N<0>")
	)
	(segment
		(start 446.367916 -239.191038)
		(end 446.367916 -238.893858)
		(width 0.20066)
		(layer "F.Cu")
		(net "M_G_CPU0_SB_CB<7>")
	)
	(segment
		(start 446.367916 -238.893858)
		(end 446.568576 -238.693198)
		(width 0.20066)
		(layer "F.Cu")
		(net "M_G_CPU0_SB_CB<7>")
	)
	(segment
		(start 441.028582 -238.966756)
		(end 442.733938 -238.966756)
		(width 0.20066)
		(layer "F.Cu")
		(net "M_G_CPU0_SB_CB<7>")
	)
	(segment
		(start 443.283086 -239.391698)
		(end 443.462664 -239.391698)
		(width 0.101854)
		(layer "F.Cu")
		(net "M_G_CPU0_SB_CB<7>")
	)
	(segment
		(start 447.23812 -238.966756)
		(end 448.572382 -238.966756)
		(width 0.20066)
		(layer "F.Cu")
		(net "M_G_CPU0_SB_CB<7>")
	)
	(segment
		(start 445.774572 -239.391698)
		(end 446.167256 -239.391698)
		(width 0.20066)
		(layer "F.Cu")
		(net "M_G_CPU0_SB_CB<7>")
	)
	(segment
		(start 446.964562 -238.693198)
		(end 447.23812 -238.966756)
		(width 0.20066)
		(layer "F.Cu")
		(net "M_G_CPU0_SB_CB<7>")
	)
	(segment
		(start 446.568576 -238.693198)
		(end 446.964562 -238.693198)
		(width 0.20066)
		(layer "F.Cu")
		(net "M_G_CPU0_SB_CB<7>")
	)
	(segment
		(start 445.470534 -239.391698)
		(end 445.774572 -239.391698)
		(width 0.101854)
		(layer "F.Cu")
		(net "M_G_CPU0_SB_CB<7>")
	)
	(segment
		(start 446.167256 -239.391698)
		(end 446.367916 -239.191038)
		(width 0.20066)
		(layer "F.Cu")
		(net "M_G_CPU0_SB_CB<7>")
	)
	(segment
		(start 439.923682 -238.966756)
		(end 441.028582 -238.966756)
		(width 0.20066)
		(layer "F.Cu")
		(net "M_G_CPU0_SB_CB<7>")
	)
	(segment
		(start 443.462664 -239.391698)
		(end 445.470534 -239.391698)
		(width 0.1016)
		(layer "F.Cu")
		(net "M_G_CPU0_SB_CB<7>")
	)
	(segment
		(start 443.15888 -239.391698)
		(end 443.283086 -239.391698)
		(width 0.20066)
		(layer "F.Cu")
		(net "M_G_CPU0_SB_CB<7>")
	)
	(segment
		(start 379.786134 -243.644928)
		(end 379.78588 -243.644674)
		(width 0.20066)
		(layer "F.Cu")
		(net "M_G_CPU0_SB_CB<7>")
	)
	(segment
		(start 379.78588 -243.644674)
		(end 379.78588 -243.108988)
		(width 0.20066)
		(layer "F.Cu")
		(net "M_G_CPU0_SB_CB<7>")
	)
	(segment
		(start 442.733938 -238.966756)
		(end 443.15888 -239.391698)
		(width 0.20066)
		(layer "F.Cu")
		(net "M_G_CPU0_SB_CB<7>")
	)
	(segment
		(start 407.533094 -239.425226)
		(end 405.725884 -239.425226)
		(width 0.18288)
		(layer "In4.Cu")
		(net "M_G_CPU0_SB_CB<7>")
	)
	(segment
		(start 414.703768 -239.668812)
		(end 414.252918 -239.217962)
		(width 0.18288)
		(layer "In4.Cu")
		(net "M_G_CPU0_SB_CB<7>")
	)
	(segment
		(start 421.828722 -240.242598)
		(end 420.812468 -240.242598)
		(width 0.18288)
		(layer "In4.Cu")
		(net "M_G_CPU0_SB_CB<7>")
	)
	(segment
		(start 400.519138 -239.424972)
		(end 399.554446 -240.389664)
		(width 0.18288)
		(layer "In4.Cu")
		(net "M_G_CPU0_SB_CB<7>")
	)
	(segment
		(start 405.72563 -239.424972)
		(end 400.519138 -239.424972)
		(width 0.18288)
		(layer "In4.Cu")
		(net "M_G_CPU0_SB_CB<7>")
	)
	(segment
		(start 426.570394 -238.764826)
		(end 425.941744 -239.393476)
		(width 0.18288)
		(layer "In4.Cu")
		(net "M_G_CPU0_SB_CB<7>")
	)
	(segment
		(start 410.906976 -238.939832)
		(end 410.746956 -238.779812)
		(width 0.18288)
		(layer "In4.Cu")
		(net "M_G_CPU0_SB_CB<7>")
	)
	(segment
		(start 414.252918 -239.217962)
		(end 413.857186 -239.217962)
		(width 0.18288)
		(layer "In4.Cu")
		(net "M_G_CPU0_SB_CB<7>")
	)
	(segment
		(start 434.609494 -238.663226)
		(end 431.675794 -238.663226)
		(width 0.18288)
		(layer "In4.Cu")
		(net "M_G_CPU0_SB_CB<7>")
	)
	(segment
		(start 435.338728 -239.39246)
		(end 434.609494 -238.663226)
		(width 0.18288)
		(layer "In4.Cu")
		(net "M_G_CPU0_SB_CB<7>")
	)
	(segment
		(start 413.192468 -239.526826)
		(end 413.106108 -239.613186)
		(width 0.18288)
		(layer "In4.Cu")
		(net "M_G_CPU0_SB_CB<7>")
	)
	(segment
		(start 388.255764 -242.907566)
		(end 387.091174 -242.907566)
		(width 0.088646)
		(layer "In4.Cu")
		(net "M_G_CPU0_SB_CB<7>")
	)
	(segment
		(start 381.852932 -243.433346)
		(end 381.848614 -243.435886)
		(width 0.088646)
		(layer "In4.Cu")
		(net "M_G_CPU0_SB_CB<7>")
	)
	(segment
		(start 410.053536 -239.249712)
		(end 409.680156 -239.249712)
		(width 0.18288)
		(layer "In4.Cu")
		(net "M_G_CPU0_SB_CB<7>")
	)
	(segment
		(start 413.106108 -239.613186)
		(end 412.674054 -239.613186)
		(width 0.18288)
		(layer "In4.Cu")
		(net "M_G_CPU0_SB_CB<7>")
	)
	(segment
		(start 410.213556 -239.089692)
		(end 410.053536 -239.249712)
		(width 0.18288)
		(layer "In4.Cu")
		(net "M_G_CPU0_SB_CB<7>")
	)
	(segment
		(start 431.497994 -238.485426)
		(end 427.967394 -238.485426)
		(width 0.18288)
		(layer "In4.Cu")
		(net "M_G_CPU0_SB_CB<7>")
	)
	(segment
		(start 413.857186 -239.217962)
		(end 413.548322 -239.526826)
		(width 0.18288)
		(layer "In4.Cu")
		(net "M_G_CPU0_SB_CB<7>")
	)
	(segment
		(start 422.569894 -239.501426)
		(end 421.828722 -240.242598)
		(width 0.18288)
		(layer "In4.Cu")
		(net "M_G_CPU0_SB_CB<7>")
	)
	(segment
		(start 420.812468 -240.242598)
		(end 420.812214 -240.242344)
		(width 0.18288)
		(layer "In4.Cu")
		(net "M_G_CPU0_SB_CB<7>")
	)
	(segment
		(start 420.812214 -240.242344)
		(end 420.063168 -240.242344)
		(width 0.18288)
		(layer "In4.Cu")
		(net "M_G_CPU0_SB_CB<7>")
	)
	(segment
		(start 412.435294 -239.374426)
		(end 411.416754 -239.374426)
		(width 0.18288)
		(layer "In4.Cu")
		(net "M_G_CPU0_SB_CB<7>")
	)
	(segment
		(start 408.523694 -239.392714)
		(end 408.276806 -239.392714)
		(width 0.18288)
		(layer "In4.Cu")
		(net "M_G_CPU0_SB_CB<7>")
	)
	(segment
		(start 380.538482 -243.433346)
		(end 380.14148 -243.204238)
		(width 0.088646)
		(layer "In4.Cu")
		(net "M_G_CPU0_SB_CB<7>")
	)
	(segment
		(start 408.117294 -239.552226)
		(end 407.660094 -239.552226)
		(width 0.18288)
		(layer "In4.Cu")
		(net "M_G_CPU0_SB_CB<7>")
	)
	(segment
		(start 410.906976 -239.089692)
		(end 410.906976 -238.939832)
		(width 0.18288)
		(layer "In4.Cu")
		(net "M_G_CPU0_SB_CB<7>")
	)
	(segment
		(start 413.548322 -239.526826)
		(end 413.192468 -239.526826)
		(width 0.18288)
		(layer "In4.Cu")
		(net "M_G_CPU0_SB_CB<7>")
	)
	(segment
		(start 382.792732 -243.433346)
		(end 382.788922 -243.435632)
		(width 0.088646)
		(layer "In4.Cu")
		(net "M_G_CPU0_SB_CB<7>")
	)
	(segment
		(start 386.514848 -243.483892)
		(end 385.424934 -243.483892)
		(width 0.088646)
		(layer "In4.Cu")
		(net "M_G_CPU0_SB_CB<7>")
	)
	(segment
		(start 439.125106 -239.765332)
		(end 438.531 -239.765332)
		(width 0.18288)
		(layer "In4.Cu")
		(net "M_G_CPU0_SB_CB<7>")
	)
	(segment
		(start 419.996112 -240.3094)
		(end 419.341808 -240.3094)
		(width 0.18288)
		(layer "In4.Cu")
		(net "M_G_CPU0_SB_CB<7>")
	)
	(segment
		(start 416.867594 -239.374426)
		(end 416.573208 -239.668812)
		(width 0.18288)
		(layer "In4.Cu")
		(net "M_G_CPU0_SB_CB<7>")
	)
	(segment
		(start 427.687994 -238.764826)
		(end 426.570394 -238.764826)
		(width 0.18288)
		(layer "In4.Cu")
		(net "M_G_CPU0_SB_CB<7>")
	)
	(segment
		(start 424.44924 -239.501426)
		(end 422.569894 -239.501426)
		(width 0.18288)
		(layer "In4.Cu")
		(net "M_G_CPU0_SB_CB<7>")
	)
	(segment
		(start 418.406834 -239.374426)
		(end 416.867594 -239.374426)
		(width 0.18288)
		(layer "In4.Cu")
		(net "M_G_CPU0_SB_CB<7>")
	)
	(segment
		(start 408.826716 -239.089692)
		(end 408.523694 -239.392714)
		(width 0.18288)
		(layer "In4.Cu")
		(net "M_G_CPU0_SB_CB<7>")
	)
	(segment
		(start 408.826716 -238.939832)
		(end 408.826716 -239.089692)
		(width 0.18288)
		(layer "In4.Cu")
		(net "M_G_CPU0_SB_CB<7>")
	)
	(segment
		(start 405.725884 -239.425226)
		(end 405.72563 -239.424972)
		(width 0.18288)
		(layer "In4.Cu")
		(net "M_G_CPU0_SB_CB<7>")
	)
	(segment
		(start 411.416754 -239.374426)
		(end 411.29204 -239.249712)
		(width 0.18288)
		(layer "In4.Cu")
		(net "M_G_CPU0_SB_CB<7>")
	)
	(segment
		(start 408.276806 -239.392714)
		(end 408.117294 -239.552226)
		(width 0.18288)
		(layer "In4.Cu")
		(net "M_G_CPU0_SB_CB<7>")
	)
	(segment
		(start 399.554446 -240.389664)
		(end 395.126972 -240.389664)
		(width 0.18288)
		(layer "In4.Cu")
		(net "M_G_CPU0_SB_CB<7>")
	)
	(segment
		(start 416.573208 -239.668812)
		(end 414.703768 -239.668812)
		(width 0.18288)
		(layer "In4.Cu")
		(net "M_G_CPU0_SB_CB<7>")
	)
	(segment
		(start 427.967394 -238.485426)
		(end 427.687994 -238.764826)
		(width 0.18288)
		(layer "In4.Cu")
		(net "M_G_CPU0_SB_CB<7>")
	)
	(segment
		(start 412.674054 -239.613186)
		(end 412.435294 -239.374426)
		(width 0.18288)
		(layer "In4.Cu")
		(net "M_G_CPU0_SB_CB<7>")
	)
	(segment
		(start 424.55719 -239.393476)
		(end 424.44924 -239.501426)
		(width 0.18288)
		(layer "In4.Cu")
		(net "M_G_CPU0_SB_CB<7>")
	)
	(segment
		(start 409.520136 -239.089692)
		(end 409.520136 -238.939832)
		(width 0.18288)
		(layer "In4.Cu")
		(net "M_G_CPU0_SB_CB<7>")
	)
	(segment
		(start 411.29204 -239.249712)
		(end 411.066996 -239.249712)
		(width 0.18288)
		(layer "In4.Cu")
		(net "M_G_CPU0_SB_CB<7>")
	)
	(segment
		(start 383.732532 -243.433346)
		(end 383.728214 -243.435886)
		(width 0.088646)
		(layer "In4.Cu")
		(net "M_G_CPU0_SB_CB<7>")
	)
	(segment
		(start 410.373576 -238.779812)
		(end 410.213556 -238.939832)
		(width 0.18288)
		(layer "In4.Cu")
		(net "M_G_CPU0_SB_CB<7>")
	)
	(segment
		(start 431.675794 -238.663226)
		(end 431.497994 -238.485426)
		(width 0.18288)
		(layer "In4.Cu")
		(net "M_G_CPU0_SB_CB<7>")
	)
	(segment
		(start 439.923682 -238.966756)
		(end 439.125106 -239.765332)
		(width 0.18288)
		(layer "In4.Cu")
		(net "M_G_CPU0_SB_CB<7>")
	)
	(segment
		(start 387.091174 -242.907566)
		(end 386.514848 -243.483892)
		(width 0.088646)
		(layer "In4.Cu")
		(net "M_G_CPU0_SB_CB<7>")
	)
	(segment
		(start 409.360116 -238.779812)
		(end 408.986736 -238.779812)
		(width 0.18288)
		(layer "In4.Cu")
		(net "M_G_CPU0_SB_CB<7>")
	)
	(segment
		(start 408.986736 -238.779812)
		(end 408.826716 -238.939832)
		(width 0.18288)
		(layer "In4.Cu")
		(net "M_G_CPU0_SB_CB<7>")
	)
	(segment
		(start 419.341808 -240.3094)
		(end 418.406834 -239.374426)
		(width 0.18288)
		(layer "In4.Cu")
		(net "M_G_CPU0_SB_CB<7>")
	)
	(segment
		(start 411.066996 -239.249712)
		(end 410.906976 -239.089692)
		(width 0.18288)
		(layer "In4.Cu")
		(net "M_G_CPU0_SB_CB<7>")
	)
	(segment
		(start 410.213556 -238.939832)
		(end 410.213556 -239.089692)
		(width 0.18288)
		(layer "In4.Cu")
		(net "M_G_CPU0_SB_CB<7>")
	)
	(segment
		(start 379.786134 -243.108988)
		(end 379.78588 -243.108988)
		(width 0.088646)
		(layer "In4.Cu")
		(net "M_G_CPU0_SB_CB<7>")
	)
	(segment
		(start 382.798574 -243.430044)
		(end 382.792732 -243.433346)
		(width 0.088646)
		(layer "In4.Cu")
		(net "M_G_CPU0_SB_CB<7>")
	)
	(segment
		(start 407.660094 -239.552226)
		(end 407.533094 -239.425226)
		(width 0.18288)
		(layer "In4.Cu")
		(net "M_G_CPU0_SB_CB<7>")
	)
	(segment
		(start 395.126972 -240.389664)
		(end 392.60907 -242.907566)
		(width 0.18288)
		(layer "In4.Cu")
		(net "M_G_CPU0_SB_CB<7>")
	)
	(segment
		(start 410.746956 -238.779812)
		(end 410.373576 -238.779812)
		(width 0.18288)
		(layer "In4.Cu")
		(net "M_G_CPU0_SB_CB<7>")
	)
	(segment
		(start 392.60907 -242.907566)
		(end 388.255764 -242.907566)
		(width 0.18288)
		(layer "In4.Cu")
		(net "M_G_CPU0_SB_CB<7>")
	)
	(segment
		(start 425.941744 -239.393476)
		(end 424.55719 -239.393476)
		(width 0.18288)
		(layer "In4.Cu")
		(net "M_G_CPU0_SB_CB<7>")
	)
	(segment
		(start 380.918974 -243.430044)
		(end 380.90729 -243.436648)
		(width 0.088646)
		(layer "In4.Cu")
		(net "M_G_CPU0_SB_CB<7>")
	)
	(segment
		(start 409.520136 -238.939832)
		(end 409.360116 -238.779812)
		(width 0.18288)
		(layer "In4.Cu")
		(net "M_G_CPU0_SB_CB<7>")
	)
	(segment
		(start 438.531 -239.765332)
		(end 438.158128 -239.39246)
		(width 0.18288)
		(layer "In4.Cu")
		(net "M_G_CPU0_SB_CB<7>")
	)
	(segment
		(start 420.063168 -240.242344)
		(end 419.996112 -240.3094)
		(width 0.18288)
		(layer "In4.Cu")
		(net "M_G_CPU0_SB_CB<7>")
	)
	(segment
		(start 409.680156 -239.249712)
		(end 409.520136 -239.089692)
		(width 0.18288)
		(layer "In4.Cu")
		(net "M_G_CPU0_SB_CB<7>")
	)
	(segment
		(start 438.158128 -239.39246)
		(end 435.338728 -239.39246)
		(width 0.18288)
		(layer "In4.Cu")
		(net "M_G_CPU0_SB_CB<7>")
	)
	(arc
		(start 384.297936 -243.433346)
		(mid 384.015234 -243.35757)
		(end 383.732532 -243.433346)
		(width 0.088646)
		(layer "In4.Cu")
		(net "M_G_CPU0_SB_CB<7>")
	)
	(arc
		(start 385.237736 -243.433346)
		(mid 384.955034 -243.35757)
		(end 384.672332 -243.433346)
		(width 0.088646)
		(layer "In4.Cu")
		(net "M_G_CPU0_SB_CB<7>")
	)
	(arc
		(start 382.788922 -243.435632)
		(mid 382.603203 -243.483584)
		(end 382.418082 -243.433346)
		(width 0.088646)
		(layer "In4.Cu")
		(net "M_G_CPU0_SB_CB<7>")
	)
	(arc
		(start 380.90729 -243.436648)
		(mid 380.722435 -243.483598)
		(end 380.538482 -243.433346)
		(width 0.088646)
		(layer "In4.Cu")
		(net "M_G_CPU0_SB_CB<7>")
	)
	(arc
		(start 380.14148 -243.204238)
		(mid 379.970074 -243.133225)
		(end 379.786134 -243.108988)
		(width 0.088646)
		(layer "In4.Cu")
		(net "M_G_CPU0_SB_CB<7>")
	)
	(arc
		(start 383.728214 -243.435886)
		(mid 383.542719 -243.483555)
		(end 383.357882 -243.433346)
		(width 0.088646)
		(layer "In4.Cu")
		(net "M_G_CPU0_SB_CB<7>")
	)
	(arc
		(start 384.672332 -243.433346)
		(mid 384.485134 -243.483489)
		(end 384.297936 -243.433346)
		(width 0.088646)
		(layer "In4.Cu")
		(net "M_G_CPU0_SB_CB<7>")
	)
	(arc
		(start 383.357882 -243.433346)
		(mid 383.078679 -243.357706)
		(end 382.798574 -243.430044)
		(width 0.088646)
		(layer "In4.Cu")
		(net "M_G_CPU0_SB_CB<7>")
	)
	(arc
		(start 381.478282 -243.433346)
		(mid 381.199079 -243.357706)
		(end 380.918974 -243.430044)
		(width 0.088646)
		(layer "In4.Cu")
		(net "M_G_CPU0_SB_CB<7>")
	)
	(arc
		(start 381.848614 -243.435886)
		(mid 381.663119 -243.483555)
		(end 381.478282 -243.433346)
		(width 0.088646)
		(layer "In4.Cu")
		(net "M_G_CPU0_SB_CB<7>")
	)
	(arc
		(start 385.424934 -243.483892)
		(mid 385.328006 -243.470941)
		(end 385.237736 -243.433346)
		(width 0.088646)
		(layer "In4.Cu")
		(net "M_G_CPU0_SB_CB<7>")
	)
	(arc
		(start 382.418082 -243.433346)
		(mid 382.135524 -243.357697)
		(end 381.852932 -243.433346)
		(width 0.088646)
		(layer "In4.Cu")
		(net "M_G_CPU0_SB_CB<7>")
	)
	(segment
		(start 446.568576 -240.371884)
		(end 446.943226 -240.371884)
		(width 0.20066)
		(layer "F.Cu")
		(net "M_G_CPU0_SB_CB<6>")
	)
	(segment
		(start 441.028582 -240.666778)
		(end 442.625226 -240.666778)
		(width 0.20066)
		(layer "F.Cu")
		(net "M_G_CPU0_SB_CB<6>")
	)
	(segment
		(start 443.462664 -241.09172)
		(end 445.428878 -241.09172)
		(width 0.1016)
		(layer "F.Cu")
		(net "M_G_CPU0_SB_CB<6>")
	)
	(segment
		(start 447.23812 -240.666778)
		(end 448.572382 -240.666778)
		(width 0.20066)
		(layer "F.Cu")
		(net "M_G_CPU0_SB_CB<6>")
	)
	(segment
		(start 442.625226 -240.666778)
		(end 443.050168 -241.09172)
		(width 0.20066)
		(layer "F.Cu")
		(net "M_G_CPU0_SB_CB<6>")
	)
	(segment
		(start 446.367916 -240.572544)
		(end 446.568576 -240.371884)
		(width 0.20066)
		(layer "F.Cu")
		(net "M_G_CPU0_SB_CB<6>")
	)
	(segment
		(start 445.428878 -241.09172)
		(end 445.774572 -241.09172)
		(width 0.101854)
		(layer "F.Cu")
		(net "M_G_CPU0_SB_CB<6>")
	)
	(segment
		(start 443.050168 -241.09172)
		(end 443.283086 -241.09172)
		(width 0.20066)
		(layer "F.Cu")
		(net "M_G_CPU0_SB_CB<6>")
	)
	(segment
		(start 446.367916 -240.89106)
		(end 446.367916 -240.572544)
		(width 0.20066)
		(layer "F.Cu")
		(net "M_G_CPU0_SB_CB<6>")
	)
	(segment
		(start 443.283086 -241.09172)
		(end 443.462664 -241.09172)
		(width 0.101854)
		(layer "F.Cu")
		(net "M_G_CPU0_SB_CB<6>")
	)
	(segment
		(start 445.774572 -241.09172)
		(end 446.167256 -241.09172)
		(width 0.20066)
		(layer "F.Cu")
		(net "M_G_CPU0_SB_CB<6>")
	)
	(segment
		(start 379.316234 -244.45849)
		(end 379.316234 -243.922804)
		(width 0.20066)
		(layer "F.Cu")
		(net "M_G_CPU0_SB_CB<6>")
	)
	(segment
		(start 446.167256 -241.09172)
		(end 446.367916 -240.89106)
		(width 0.20066)
		(layer "F.Cu")
		(net "M_G_CPU0_SB_CB<6>")
	)
	(segment
		(start 439.923682 -240.666778)
		(end 441.028582 -240.666778)
		(width 0.20066)
		(layer "F.Cu")
		(net "M_G_CPU0_SB_CB<6>")
	)
	(segment
		(start 446.943226 -240.371884)
		(end 447.23812 -240.666778)
		(width 0.20066)
		(layer "F.Cu")
		(net "M_G_CPU0_SB_CB<6>")
	)
	(segment
		(start 379.31598 -244.458744)
		(end 379.316234 -244.45849)
		(width 0.20066)
		(layer "F.Cu")
		(net "M_G_CPU0_SB_CB<6>")
	)
	(segment
		(start 404.134828 -241.568224)
		(end 404.134828 -241.944906)
		(width 0.18288)
		(layer "In4.Cu")
		(net "M_G_CPU0_SB_CB<6>")
	)
	(segment
		(start 380.068582 -244.247416)
		(end 380.061216 -244.243098)
		(width 0.088646)
		(layer "In4.Cu")
		(net "M_G_CPU0_SB_CB<6>")
	)
	(segment
		(start 418.033708 -240.89614)
		(end 416.13328 -240.89614)
		(width 0.18288)
		(layer "In4.Cu")
		(net "M_G_CPU0_SB_CB<6>")
	)
	(segment
		(start 383.826512 -244.2464)
		(end 383.822194 -244.24386)
		(width 0.088646)
		(layer "In4.Cu")
		(net "M_G_CPU0_SB_CB<6>")
	)
	(segment
		(start 403.951948 -242.127786)
		(end 403.624288 -242.127786)
		(width 0.18288)
		(layer "In4.Cu")
		(net "M_G_CPU0_SB_CB<6>")
	)
	(segment
		(start 403.441408 -241.944906)
		(end 403.441408 -241.568224)
		(width 0.18288)
		(layer "In4.Cu")
		(net "M_G_CPU0_SB_CB<6>")
	)
	(segment
		(start 439.234834 -241.355626)
		(end 438.038494 -241.355626)
		(width 0.18288)
		(layer "In4.Cu")
		(net "M_G_CPU0_SB_CB<6>")
	)
	(segment
		(start 382.887982 -244.247416)
		(end 382.88341 -244.244622)
		(width 0.088646)
		(layer "In4.Cu")
		(net "M_G_CPU0_SB_CB<6>")
	)
	(segment
		(start 403.624288 -242.127786)
		(end 403.441408 -241.944906)
		(width 0.18288)
		(layer "In4.Cu")
		(net "M_G_CPU0_SB_CB<6>")
	)
	(segment
		(start 388.216648 -243.699284)
		(end 387.059424 -243.699284)
		(width 0.088646)
		(layer "In4.Cu")
		(net "M_G_CPU0_SB_CB<6>")
	)
	(segment
		(start 412.333694 -241.177826)
		(end 411.99816 -240.842292)
		(width 0.18288)
		(layer "In4.Cu")
		(net "M_G_CPU0_SB_CB<6>")
	)
	(segment
		(start 438.038494 -241.355626)
		(end 437.775858 -241.09299)
		(width 0.18288)
		(layer "In4.Cu")
		(net "M_G_CPU0_SB_CB<6>")
	)
	(segment
		(start 409.183078 -241.206274)
		(end 407.688542 -241.206274)
		(width 0.18288)
		(layer "In4.Cu")
		(net "M_G_CPU0_SB_CB<6>")
	)
	(segment
		(start 404.134828 -241.944906)
		(end 403.951948 -242.127786)
		(width 0.18288)
		(layer "In4.Cu")
		(net "M_G_CPU0_SB_CB<6>")
	)
	(segment
		(start 404.317708 -241.385344)
		(end 404.134828 -241.568224)
		(width 0.18288)
		(layer "In4.Cu")
		(net "M_G_CPU0_SB_CB<6>")
	)
	(segment
		(start 403.441408 -241.568224)
		(end 403.258528 -241.385344)
		(width 0.18288)
		(layer "In4.Cu")
		(net "M_G_CPU0_SB_CB<6>")
	)
	(segment
		(start 402.747988 -241.944906)
		(end 402.565108 -242.127786)
		(width 0.18288)
		(layer "In4.Cu")
		(net "M_G_CPU0_SB_CB<6>")
	)
	(segment
		(start 434.332634 -241.091466)
		(end 433.707794 -240.466626)
		(width 0.18288)
		(layer "In4.Cu")
		(net "M_G_CPU0_SB_CB<6>")
	)
	(segment
		(start 388.255764 -243.690648)
		(end 388.225284 -243.690648)
		(width 0.088646)
		(layer "In4.Cu")
		(net "M_G_CPU0_SB_CB<6>")
	)
	(segment
		(start 379.003306 -243.922804)
		(end 379.316234 -243.922804)
		(width 0.088646)
		(layer "In4.Cu")
		(net "M_G_CPU0_SB_CB<6>")
	)
	(segment
		(start 415.851594 -241.177826)
		(end 412.333694 -241.177826)
		(width 0.18288)
		(layer "In4.Cu")
		(net "M_G_CPU0_SB_CB<6>")
	)
	(segment
		(start 437.775858 -241.09299)
		(end 435.988206 -241.09299)
		(width 0.18288)
		(layer "In4.Cu")
		(net "M_G_CPU0_SB_CB<6>")
	)
	(segment
		(start 421.833294 -241.94262)
		(end 419.080188 -241.94262)
		(width 0.18288)
		(layer "In4.Cu")
		(net "M_G_CPU0_SB_CB<6>")
	)
	(segment
		(start 411.99816 -240.842292)
		(end 409.54706 -240.842292)
		(width 0.18288)
		(layer "In4.Cu")
		(net "M_G_CPU0_SB_CB<6>")
	)
	(segment
		(start 402.237448 -242.127786)
		(end 402.054568 -241.944906)
		(width 0.18288)
		(layer "In4.Cu")
		(net "M_G_CPU0_SB_CB<6>")
	)
	(segment
		(start 427.560994 -240.212626)
		(end 426.681138 -241.092482)
		(width 0.18288)
		(layer "In4.Cu")
		(net "M_G_CPU0_SB_CB<6>")
	)
	(segment
		(start 379.133354 -244.249956)
		(end 379.128782 -244.247416)
		(width 0.088646)
		(layer "In4.Cu")
		(net "M_G_CPU0_SB_CB<6>")
	)
	(segment
		(start 422.683432 -241.092482)
		(end 421.833294 -241.94262)
		(width 0.18288)
		(layer "In4.Cu")
		(net "M_G_CPU0_SB_CB<6>")
	)
	(segment
		(start 416.13328 -240.89614)
		(end 415.851594 -241.177826)
		(width 0.18288)
		(layer "In4.Cu")
		(net "M_G_CPU0_SB_CB<6>")
	)
	(segment
		(start 406.855168 -241.385344)
		(end 404.317708 -241.385344)
		(width 0.18288)
		(layer "In4.Cu")
		(net "M_G_CPU0_SB_CB<6>")
	)
	(segment
		(start 439.923682 -240.666778)
		(end 439.234834 -241.355626)
		(width 0.18288)
		(layer "In4.Cu")
		(net "M_G_CPU0_SB_CB<6>")
	)
	(segment
		(start 433.707794 -240.466626)
		(end 432.031394 -240.466626)
		(width 0.18288)
		(layer "In4.Cu")
		(net "M_G_CPU0_SB_CB<6>")
	)
	(segment
		(start 426.681138 -241.092482)
		(end 422.683432 -241.092482)
		(width 0.18288)
		(layer "In4.Cu")
		(net "M_G_CPU0_SB_CB<6>")
	)
	(segment
		(start 402.747988 -241.568224)
		(end 402.747988 -241.944906)
		(width 0.18288)
		(layer "In4.Cu")
		(net "M_G_CPU0_SB_CB<6>")
	)
	(segment
		(start 435.986682 -241.091466)
		(end 434.332634 -241.091466)
		(width 0.18288)
		(layer "In4.Cu")
		(net "M_G_CPU0_SB_CB<6>")
	)
	(segment
		(start 419.080188 -241.94262)
		(end 418.033708 -240.89614)
		(width 0.18288)
		(layer "In4.Cu")
		(net "M_G_CPU0_SB_CB<6>")
	)
	(segment
		(start 381.008382 -244.247416)
		(end 381.001016 -244.243098)
		(width 0.088646)
		(layer "In4.Cu")
		(net "M_G_CPU0_SB_CB<6>")
	)
	(segment
		(start 379.128782 -244.247416)
		(end 379.125226 -244.24513)
		(width 0.088646)
		(layer "In4.Cu")
		(net "M_G_CPU0_SB_CB<6>")
	)
	(segment
		(start 435.988206 -241.09299)
		(end 435.986682 -241.091466)
		(width 0.18288)
		(layer "In4.Cu")
		(net "M_G_CPU0_SB_CB<6>")
	)
	(segment
		(start 407.688542 -241.206274)
		(end 407.558494 -241.076226)
		(width 0.18288)
		(layer "In4.Cu")
		(net "M_G_CPU0_SB_CB<6>")
	)
	(segment
		(start 381.948182 -244.247416)
		(end 381.942594 -244.24386)
		(width 0.088646)
		(layer "In4.Cu")
		(net "M_G_CPU0_SB_CB<6>")
	)
	(segment
		(start 403.258528 -241.385344)
		(end 402.930868 -241.385344)
		(width 0.18288)
		(layer "In4.Cu")
		(net "M_G_CPU0_SB_CB<6>")
	)
	(segment
		(start 431.777394 -240.212626)
		(end 427.560994 -240.212626)
		(width 0.18288)
		(layer "In4.Cu")
		(net "M_G_CPU0_SB_CB<6>")
	)
	(segment
		(start 402.054568 -241.568224)
		(end 401.871688 -241.385344)
		(width 0.18288)
		(layer "In4.Cu")
		(net "M_G_CPU0_SB_CB<6>")
	)
	(segment
		(start 386.587238 -244.17147)
		(end 386.364734 -244.17147)
		(width 0.088646)
		(layer "In4.Cu")
		(net "M_G_CPU0_SB_CB<6>")
	)
	(segment
		(start 383.828036 -244.247162)
		(end 383.826512 -244.2464)
		(width 0.088646)
		(layer "In4.Cu")
		(net "M_G_CPU0_SB_CB<6>")
	)
	(segment
		(start 382.892554 -244.249956)
		(end 382.887982 -244.247416)
		(width 0.088646)
		(layer "In4.Cu")
		(net "M_G_CPU0_SB_CB<6>")
	)
	(segment
		(start 393.56665 -243.690648)
		(end 388.255764 -243.690648)
		(width 0.18288)
		(layer "In4.Cu")
		(net "M_G_CPU0_SB_CB<6>")
	)
	(segment
		(start 401.871688 -241.385344)
		(end 395.871954 -241.385344)
		(width 0.18288)
		(layer "In4.Cu")
		(net "M_G_CPU0_SB_CB<6>")
	)
	(segment
		(start 381.012954 -244.249956)
		(end 381.008382 -244.247416)
		(width 0.088646)
		(layer "In4.Cu")
		(net "M_G_CPU0_SB_CB<6>")
	)
	(segment
		(start 395.871954 -241.385344)
		(end 393.56665 -243.690648)
		(width 0.18288)
		(layer "In4.Cu")
		(net "M_G_CPU0_SB_CB<6>")
	)
	(segment
		(start 378.945902 -243.980208)
		(end 379.003306 -243.922804)
		(width 0.088646)
		(layer "In4.Cu")
		(net "M_G_CPU0_SB_CB<6>")
	)
	(segment
		(start 387.059424 -243.699284)
		(end 386.587238 -244.17147)
		(width 0.088646)
		(layer "In4.Cu")
		(net "M_G_CPU0_SB_CB<6>")
	)
	(segment
		(start 409.54706 -240.842292)
		(end 409.183078 -241.206274)
		(width 0.18288)
		(layer "In4.Cu")
		(net "M_G_CPU0_SB_CB<6>")
	)
	(segment
		(start 402.930868 -241.385344)
		(end 402.747988 -241.568224)
		(width 0.18288)
		(layer "In4.Cu")
		(net "M_G_CPU0_SB_CB<6>")
	)
	(segment
		(start 380.073154 -244.249956)
		(end 380.068582 -244.247416)
		(width 0.088646)
		(layer "In4.Cu")
		(net "M_G_CPU0_SB_CB<6>")
	)
	(segment
		(start 402.054568 -241.944906)
		(end 402.054568 -241.568224)
		(width 0.18288)
		(layer "In4.Cu")
		(net "M_G_CPU0_SB_CB<6>")
	)
	(segment
		(start 407.558494 -241.076226)
		(end 407.164286 -241.076226)
		(width 0.18288)
		(layer "In4.Cu")
		(net "M_G_CPU0_SB_CB<6>")
	)
	(segment
		(start 388.225284 -243.690648)
		(end 388.216648 -243.699284)
		(width 0.088646)
		(layer "In4.Cu")
		(net "M_G_CPU0_SB_CB<6>")
	)
	(segment
		(start 402.565108 -242.127786)
		(end 402.237448 -242.127786)
		(width 0.18288)
		(layer "In4.Cu")
		(net "M_G_CPU0_SB_CB<6>")
	)
	(segment
		(start 407.164286 -241.076226)
		(end 406.855168 -241.385344)
		(width 0.18288)
		(layer "In4.Cu")
		(net "M_G_CPU0_SB_CB<6>")
	)
	(segment
		(start 432.031394 -240.466626)
		(end 431.777394 -240.212626)
		(width 0.18288)
		(layer "In4.Cu")
		(net "M_G_CPU0_SB_CB<6>")
	)
	(arc
		(start 384.767836 -244.247162)
		(mid 384.485134 -244.171386)
		(end 384.202432 -244.247162)
		(width 0.088646)
		(layer "In4.Cu")
		(net "M_G_CPU0_SB_CB<6>")
	)
	(arc
		(start 383.822194 -244.24386)
		(mid 383.541949 -244.171545)
		(end 383.262632 -244.247416)
		(width 0.088646)
		(layer "In4.Cu")
		(net "M_G_CPU0_SB_CB<6>")
	)
	(arc
		(start 379.125226 -244.24513)
		(mid 379.005837 -244.132786)
		(end 378.945902 -243.980208)
		(width 0.088646)
		(layer "In4.Cu")
		(net "M_G_CPU0_SB_CB<6>")
	)
	(arc
		(start 380.061216 -244.243098)
		(mid 379.781755 -244.171629)
		(end 379.503432 -244.247416)
		(width 0.088646)
		(layer "In4.Cu")
		(net "M_G_CPU0_SB_CB<6>")
	)
	(arc
		(start 382.322832 -244.247416)
		(mid 382.135524 -244.297525)
		(end 381.948182 -244.247416)
		(width 0.088646)
		(layer "In4.Cu")
		(net "M_G_CPU0_SB_CB<6>")
	)
	(arc
		(start 381.001016 -244.243098)
		(mid 380.721555 -244.171629)
		(end 380.443232 -244.247416)
		(width 0.088646)
		(layer "In4.Cu")
		(net "M_G_CPU0_SB_CB<6>")
	)
	(arc
		(start 386.364734 -244.17147)
		(mid 386.21839 -244.190678)
		(end 386.082032 -244.247162)
		(width 0.088646)
		(layer "In4.Cu")
		(net "M_G_CPU0_SB_CB<6>")
	)
	(arc
		(start 385.707636 -244.247162)
		(mid 385.424934 -244.171386)
		(end 385.142232 -244.247162)
		(width 0.088646)
		(layer "In4.Cu")
		(net "M_G_CPU0_SB_CB<6>")
	)
	(arc
		(start 384.202432 -244.247162)
		(mid 384.015234 -244.297305)
		(end 383.828036 -244.247162)
		(width 0.088646)
		(layer "In4.Cu")
		(net "M_G_CPU0_SB_CB<6>")
	)
	(arc
		(start 383.262632 -244.247416)
		(mid 383.077938 -244.297517)
		(end 382.892554 -244.249956)
		(width 0.088646)
		(layer "In4.Cu")
		(net "M_G_CPU0_SB_CB<6>")
	)
	(arc
		(start 380.443232 -244.247416)
		(mid 380.258538 -244.297517)
		(end 380.073154 -244.249956)
		(width 0.088646)
		(layer "In4.Cu")
		(net "M_G_CPU0_SB_CB<6>")
	)
	(arc
		(start 379.503432 -244.247416)
		(mid 379.318738 -244.297517)
		(end 379.133354 -244.249956)
		(width 0.088646)
		(layer "In4.Cu")
		(net "M_G_CPU0_SB_CB<6>")
	)
	(arc
		(start 382.88341 -244.244622)
		(mid 382.602746 -244.171581)
		(end 382.322832 -244.247416)
		(width 0.088646)
		(layer "In4.Cu")
		(net "M_G_CPU0_SB_CB<6>")
	)
	(arc
		(start 385.142232 -244.247162)
		(mid 384.955034 -244.297305)
		(end 384.767836 -244.247162)
		(width 0.088646)
		(layer "In4.Cu")
		(net "M_G_CPU0_SB_CB<6>")
	)
	(arc
		(start 386.082032 -244.247162)
		(mid 385.894834 -244.297339)
		(end 385.707636 -244.247162)
		(width 0.088646)
		(layer "In4.Cu")
		(net "M_G_CPU0_SB_CB<6>")
	)
	(arc
		(start 381.942594 -244.24386)
		(mid 381.662349 -244.171545)
		(end 381.383032 -244.247416)
		(width 0.088646)
		(layer "In4.Cu")
		(net "M_G_CPU0_SB_CB<6>")
	)
	(arc
		(start 381.383032 -244.247416)
		(mid 381.198338 -244.297517)
		(end 381.012954 -244.249956)
		(width 0.088646)
		(layer "In4.Cu")
		(net "M_G_CPU0_SB_CB<6>")
	)
	(segment
		(start 442.416184 -239.391698)
		(end 442.21781 -239.391698)
		(width 0.20066)
		(layer "F.Cu")
		(net "M_G_CPU0_SB_CB<5>")
	)
	(segment
		(start 444.47206 -239.816894)
		(end 442.84138 -239.816894)
		(width 0.20066)
		(layer "F.Cu")
		(net "M_G_CPU0_SB_CB<5>")
	)
	(segment
		(start 377.90628 -243.644674)
		(end 377.90628 -243.108988)
		(width 0.20066)
		(layer "F.Cu")
		(net "M_G_CPU0_SB_CB<5>")
	)
	(segment
		(start 438.697878 -240.065306)
		(end 438.449212 -239.81664)
		(width 0.20066)
		(layer "F.Cu")
		(net "M_G_CPU0_SB_CB<5>")
	)
	(segment
		(start 439.361072 -239.877346)
		(end 439.173112 -240.065306)
		(width 0.20066)
		(layer "F.Cu")
		(net "M_G_CPU0_SB_CB<5>")
	)
	(segment
		(start 436.928514 -239.81664)
		(end 435.823614 -239.81664)
		(width 0.20066)
		(layer "F.Cu")
		(net "M_G_CPU0_SB_CB<5>")
	)
	(segment
		(start 438.449212 -239.81664)
		(end 436.928514 -239.81664)
		(width 0.20066)
		(layer "F.Cu")
		(net "M_G_CPU0_SB_CB<5>")
	)
	(segment
		(start 444.472314 -239.81664)
		(end 444.47206 -239.816894)
		(width 0.20066)
		(layer "F.Cu")
		(net "M_G_CPU0_SB_CB<5>")
	)
	(segment
		(start 439.87085 -239.391698)
		(end 439.726324 -239.391698)
		(width 0.101854)
		(layer "F.Cu")
		(net "M_G_CPU0_SB_CB<5>")
	)
	(segment
		(start 439.479182 -239.391698)
		(end 439.361072 -239.509808)
		(width 0.20066)
		(layer "F.Cu")
		(net "M_G_CPU0_SB_CB<5>")
	)
	(segment
		(start 439.361072 -239.509808)
		(end 439.361072 -239.877346)
		(width 0.20066)
		(layer "F.Cu")
		(net "M_G_CPU0_SB_CB<5>")
	)
	(segment
		(start 442.84138 -239.816894)
		(end 442.416184 -239.391698)
		(width 0.20066)
		(layer "F.Cu")
		(net "M_G_CPU0_SB_CB<5>")
	)
	(segment
		(start 377.906534 -243.644928)
		(end 377.90628 -243.644674)
		(width 0.20066)
		(layer "F.Cu")
		(net "M_G_CPU0_SB_CB<5>")
	)
	(segment
		(start 439.726324 -239.391698)
		(end 439.479182 -239.391698)
		(width 0.20066)
		(layer "F.Cu")
		(net "M_G_CPU0_SB_CB<5>")
	)
	(segment
		(start 442.21781 -239.391698)
		(end 442.181234 -239.391698)
		(width 0.101854)
		(layer "F.Cu")
		(net "M_G_CPU0_SB_CB<5>")
	)
	(segment
		(start 442.181234 -239.391698)
		(end 439.87085 -239.391698)
		(width 0.1016)
		(layer "F.Cu")
		(net "M_G_CPU0_SB_CB<5>")
	)
	(segment
		(start 439.173112 -240.065306)
		(end 438.697878 -240.065306)
		(width 0.20066)
		(layer "F.Cu")
		(net "M_G_CPU0_SB_CB<5>")
	)
	(segment
		(start 415.915094 -240.187226)
		(end 414.508696 -240.187226)
		(width 0.18288)
		(layer "In4.Cu")
		(net "M_G_CPU0_SB_CB<5>")
	)
	(segment
		(start 393.229846 -243.323364)
		(end 388.255764 -243.323364)
		(width 0.18288)
		(layer "In4.Cu")
		(net "M_G_CPU0_SB_CB<5>")
	)
	(segment
		(start 429.020986 -239.51057)
		(end 428.838106 -239.69345)
		(width 0.18288)
		(layer "In4.Cu")
		(net "M_G_CPU0_SB_CB<5>")
	)
	(segment
		(start 406.919938 -240.271046)
		(end 406.919938 -240.510568)
		(width 0.18288)
		(layer "In4.Cu")
		(net "M_G_CPU0_SB_CB<5>")
	)
	(segment
		(start 381.948182 -243.598446)
		(end 381.944626 -243.600478)
		(width 0.088646)
		(layer "In4.Cu")
		(net "M_G_CPU0_SB_CB<5>")
	)
	(segment
		(start 421.871394 -241.092482)
		(end 420.12235 -241.092482)
		(width 0.18288)
		(layer "In4.Cu")
		(net "M_G_CPU0_SB_CB<5>")
	)
	(segment
		(start 403.332442 -240.293652)
		(end 403.332442 -240.541048)
		(width 0.18288)
		(layer "In4.Cu")
		(net "M_G_CPU0_SB_CB<5>")
	)
	(segment
		(start 400.586702 -240.110772)
		(end 399.80997 -240.887504)
		(width 0.18288)
		(layer "In4.Cu")
		(net "M_G_CPU0_SB_CB<5>")
	)
	(segment
		(start 432.7779 -239.505998)
		(end 432.092354 -239.222026)
		(width 0.18288)
		(layer "In4.Cu")
		(net "M_G_CPU0_SB_CB<5>")
	)
	(segment
		(start 431.28057 -239.69345)
		(end 429.897286 -239.69345)
		(width 0.18288)
		(layer "In4.Cu")
		(net "M_G_CPU0_SB_CB<5>")
	)
	(segment
		(start 413.495236 -240.187226)
		(end 412.562294 -240.187226)
		(width 0.18288)
		(layer "In4.Cu")
		(net "M_G_CPU0_SB_CB<5>")
	)
	(segment
		(start 433.670456 -239.581182)
		(end 433.583842 -239.371632)
		(width 0.18288)
		(layer "In4.Cu")
		(net "M_G_CPU0_SB_CB<5>")
	)
	(segment
		(start 414.188656 -240.535714)
		(end 413.815276 -240.535714)
		(width 0.18288)
		(layer "In4.Cu")
		(net "M_G_CPU0_SB_CB<5>")
	)
	(segment
		(start 406.919938 -240.510568)
		(end 406.759918 -240.670588)
		(width 0.18288)
		(layer "In4.Cu")
		(net "M_G_CPU0_SB_CB<5>")
	)
	(segment
		(start 435.823614 -239.81664)
		(end 435.224428 -240.415826)
		(width 0.18288)
		(layer "In4.Cu")
		(net "M_G_CPU0_SB_CB<5>")
	)
	(segment
		(start 413.655256 -240.375694)
		(end 413.655256 -240.347246)
		(width 0.18288)
		(layer "In4.Cu")
		(net "M_G_CPU0_SB_CB<5>")
	)
	(segment
		(start 411.08249 -240.156746)
		(end 411.08249 -239.902238)
		(width 0.18288)
		(layer "In4.Cu")
		(net "M_G_CPU0_SB_CB<5>")
	)
	(segment
		(start 414.348676 -240.375694)
		(end 414.188656 -240.535714)
		(width 0.18288)
		(layer "In4.Cu")
		(net "M_G_CPU0_SB_CB<5>")
	)
	(segment
		(start 411.08249 -239.902238)
		(end 410.89961 -239.719358)
		(width 0.18288)
		(layer "In4.Cu")
		(net "M_G_CPU0_SB_CB<5>")
	)
	(segment
		(start 412.562294 -240.187226)
		(end 412.409894 -240.339626)
		(width 0.18288)
		(layer "In4.Cu")
		(net "M_G_CPU0_SB_CB<5>")
	)
	(segment
		(start 386.593842 -243.674138)
		(end 385.424934 -243.674138)
		(width 0.088646)
		(layer "In4.Cu")
		(net "M_G_CPU0_SB_CB<5>")
	)
	(segment
		(start 413.655256 -240.347246)
		(end 413.495236 -240.187226)
		(width 0.18288)
		(layer "In4.Cu")
		(net "M_G_CPU0_SB_CB<5>")
	)
	(segment
		(start 404.025862 -240.541048)
		(end 404.025862 -240.293652)
		(width 0.18288)
		(layer "In4.Cu")
		(net "M_G_CPU0_SB_CB<5>")
	)
	(segment
		(start 407.079958 -240.111026)
		(end 406.919938 -240.271046)
		(width 0.18288)
		(layer "In4.Cu")
		(net "M_G_CPU0_SB_CB<5>")
	)
	(segment
		(start 433.029614 -239.315244)
		(end 432.986434 -239.419384)
		(width 0.18288)
		(layer "In4.Cu")
		(net "M_G_CPU0_SB_CB<5>")
	)
	(segment
		(start 423.61231 -240.124742)
		(end 422.839134 -240.124742)
		(width 0.18288)
		(layer "In4.Cu")
		(net "M_G_CPU0_SB_CB<5>")
	)
	(segment
		(start 429.203866 -238.984028)
		(end 429.020986 -239.166908)
		(width 0.18288)
		(layer "In4.Cu")
		(net "M_G_CPU0_SB_CB<5>")
	)
	(segment
		(start 418.543994 -240.288826)
		(end 416.016694 -240.288826)
		(width 0.18288)
		(layer "In4.Cu")
		(net "M_G_CPU0_SB_CB<5>")
	)
	(segment
		(start 429.714406 -239.51057)
		(end 429.714406 -239.166908)
		(width 0.18288)
		(layer "In4.Cu")
		(net "M_G_CPU0_SB_CB<5>")
	)
	(segment
		(start 410.57195 -239.719358)
		(end 410.38907 -239.902238)
		(width 0.18288)
		(layer "In4.Cu")
		(net "M_G_CPU0_SB_CB<5>")
	)
	(segment
		(start 413.815276 -240.535714)
		(end 413.655256 -240.375694)
		(width 0.18288)
		(layer "In4.Cu")
		(net "M_G_CPU0_SB_CB<5>")
	)
	(segment
		(start 404.025862 -240.293652)
		(end 403.842982 -240.110772)
		(width 0.18288)
		(layer "In4.Cu")
		(net "M_G_CPU0_SB_CB<5>")
	)
	(segment
		(start 432.092354 -239.222026)
		(end 431.751994 -239.222026)
		(width 0.18288)
		(layer "In4.Cu")
		(net "M_G_CPU0_SB_CB<5>")
	)
	(segment
		(start 405.72563 -240.110772)
		(end 404.902162 -240.110772)
		(width 0.18288)
		(layer "In4.Cu")
		(net "M_G_CPU0_SB_CB<5>")
	)
	(segment
		(start 410.38907 -239.902238)
		(end 410.38907 -240.156746)
		(width 0.18288)
		(layer "In4.Cu")
		(net "M_G_CPU0_SB_CB<5>")
	)
	(segment
		(start 408.975306 -240.111026)
		(end 407.079958 -240.111026)
		(width 0.18288)
		(layer "In4.Cu")
		(net "M_G_CPU0_SB_CB<5>")
	)
	(segment
		(start 416.016694 -240.288826)
		(end 415.915094 -240.187226)
		(width 0.18288)
		(layer "In4.Cu")
		(net "M_G_CPU0_SB_CB<5>")
	)
	(segment
		(start 404.902162 -240.110772)
		(end 404.719282 -240.293652)
		(width 0.18288)
		(layer "In4.Cu")
		(net "M_G_CPU0_SB_CB<5>")
	)
	(segment
		(start 403.515322 -240.110772)
		(end 403.332442 -240.293652)
		(width 0.18288)
		(layer "In4.Cu")
		(net "M_G_CPU0_SB_CB<5>")
	)
	(segment
		(start 412.409894 -240.339626)
		(end 411.26537 -240.339626)
		(width 0.18288)
		(layer "In4.Cu")
		(net "M_G_CPU0_SB_CB<5>")
	)
	(segment
		(start 404.208742 -240.723928)
		(end 404.025862 -240.541048)
		(width 0.18288)
		(layer "In4.Cu")
		(net "M_G_CPU0_SB_CB<5>")
	)
	(segment
		(start 428.838106 -239.69345)
		(end 427.981618 -239.69345)
		(width 0.18288)
		(layer "In4.Cu")
		(net "M_G_CPU0_SB_CB<5>")
	)
	(segment
		(start 383.827782 -243.598446)
		(end 383.824226 -243.600478)
		(width 0.088646)
		(layer "In4.Cu")
		(net "M_G_CPU0_SB_CB<5>")
	)
	(segment
		(start 426.798994 -239.349026)
		(end 426.519594 -239.628426)
		(width 0.18288)
		(layer "In4.Cu")
		(net "M_G_CPU0_SB_CB<5>")
	)
	(segment
		(start 429.020986 -239.166908)
		(end 429.020986 -239.51057)
		(width 0.18288)
		(layer "In4.Cu")
		(net "M_G_CPU0_SB_CB<5>")
	)
	(segment
		(start 404.719282 -240.541048)
		(end 404.536402 -240.723928)
		(width 0.18288)
		(layer "In4.Cu")
		(net "M_G_CPU0_SB_CB<5>")
	)
	(segment
		(start 432.986434 -239.419384)
		(end 432.7779 -239.505998)
		(width 0.18288)
		(layer "In4.Cu")
		(net "M_G_CPU0_SB_CB<5>")
	)
	(segment
		(start 433.238402 -239.228884)
		(end 433.029614 -239.315244)
		(width 0.18288)
		(layer "In4.Cu")
		(net "M_G_CPU0_SB_CB<5>")
	)
	(segment
		(start 426.519594 -239.857026)
		(end 425.935394 -240.441226)
		(width 0.18288)
		(layer "In4.Cu")
		(net "M_G_CPU0_SB_CB<5>")
	)
	(segment
		(start 406.386538 -240.670588)
		(end 406.226518 -240.510568)
		(width 0.18288)
		(layer "In4.Cu")
		(net "M_G_CPU0_SB_CB<5>")
	)
	(segment
		(start 427.637194 -239.349026)
		(end 426.798994 -239.349026)
		(width 0.18288)
		(layer "In4.Cu")
		(net "M_G_CPU0_SB_CB<5>")
	)
	(segment
		(start 419.178994 -240.923826)
		(end 418.543994 -240.288826)
		(width 0.18288)
		(layer "In4.Cu")
		(net "M_G_CPU0_SB_CB<5>")
	)
	(segment
		(start 404.719282 -240.293652)
		(end 404.719282 -240.541048)
		(width 0.18288)
		(layer "In4.Cu")
		(net "M_G_CPU0_SB_CB<5>")
	)
	(segment
		(start 431.751994 -239.222026)
		(end 431.28057 -239.69345)
		(width 0.18288)
		(layer "In4.Cu")
		(net "M_G_CPU0_SB_CB<5>")
	)
	(segment
		(start 395.665706 -240.887504)
		(end 393.229846 -243.323364)
		(width 0.18288)
		(layer "In4.Cu")
		(net "M_G_CPU0_SB_CB<5>")
	)
	(segment
		(start 386.944616 -243.323364)
		(end 386.593842 -243.674138)
		(width 0.088646)
		(layer "In4.Cu")
		(net "M_G_CPU0_SB_CB<5>")
	)
	(segment
		(start 414.508696 -240.187226)
		(end 414.348676 -240.347246)
		(width 0.18288)
		(layer "In4.Cu")
		(net "M_G_CPU0_SB_CB<5>")
	)
	(segment
		(start 382.893824 -243.595144)
		(end 382.88341 -243.600986)
		(width 0.088646)
		(layer "In4.Cu")
		(net "M_G_CPU0_SB_CB<5>")
	)
	(segment
		(start 434.531262 -240.415826)
		(end 434.217826 -240.10239)
		(width 0.18288)
		(layer "In4.Cu")
		(net "M_G_CPU0_SB_CB<5>")
	)
	(segment
		(start 406.226518 -240.271046)
		(end 406.066498 -240.111026)
		(width 0.18288)
		(layer "In4.Cu")
		(net "M_G_CPU0_SB_CB<5>")
	)
	(segment
		(start 403.149562 -240.723928)
		(end 402.821902 -240.723928)
		(width 0.18288)
		(layer "In4.Cu")
		(net "M_G_CPU0_SB_CB<5>")
	)
	(segment
		(start 433.71389 -239.893602)
		(end 433.62753 -239.685068)
		(width 0.18288)
		(layer "In4.Cu")
		(net "M_G_CPU0_SB_CB<5>")
	)
	(segment
		(start 427.981618 -239.69345)
		(end 427.637194 -239.349026)
		(width 0.18288)
		(layer "In4.Cu")
		(net "M_G_CPU0_SB_CB<5>")
	)
	(segment
		(start 383.828036 -243.598446)
		(end 383.827782 -243.598446)
		(width 0.088646)
		(layer "In4.Cu")
		(net "M_G_CPU0_SB_CB<5>")
	)
	(segment
		(start 404.536402 -240.723928)
		(end 404.208742 -240.723928)
		(width 0.18288)
		(layer "In4.Cu")
		(net "M_G_CPU0_SB_CB<5>")
	)
	(segment
		(start 425.935394 -240.441226)
		(end 425.28744 -240.441226)
		(width 0.18288)
		(layer "In4.Cu")
		(net "M_G_CPU0_SB_CB<5>")
	)
	(segment
		(start 409.203906 -240.339626)
		(end 408.975306 -240.111026)
		(width 0.18288)
		(layer "In4.Cu")
		(net "M_G_CPU0_SB_CB<5>")
	)
	(segment
		(start 403.842982 -240.110772)
		(end 403.515322 -240.110772)
		(width 0.18288)
		(layer "In4.Cu")
		(net "M_G_CPU0_SB_CB<5>")
	)
	(segment
		(start 406.759918 -240.670588)
		(end 406.386538 -240.670588)
		(width 0.18288)
		(layer "In4.Cu")
		(net "M_G_CPU0_SB_CB<5>")
	)
	(segment
		(start 381.014224 -243.595144)
		(end 381.00254 -243.601748)
		(width 0.088646)
		(layer "In4.Cu")
		(net "M_G_CPU0_SB_CB<5>")
	)
	(segment
		(start 410.89961 -239.719358)
		(end 410.57195 -239.719358)
		(width 0.18288)
		(layer "In4.Cu")
		(net "M_G_CPU0_SB_CB<5>")
	)
	(segment
		(start 435.224428 -240.415826)
		(end 434.531262 -240.415826)
		(width 0.18288)
		(layer "In4.Cu")
		(net "M_G_CPU0_SB_CB<5>")
	)
	(segment
		(start 378.563632 -243.598446)
		(end 378.483622 -243.552218)
		(width 0.088646)
		(layer "In4.Cu")
		(net "M_G_CPU0_SB_CB<5>")
	)
	(segment
		(start 410.20619 -240.339626)
		(end 409.203906 -240.339626)
		(width 0.18288)
		(layer "In4.Cu")
		(net "M_G_CPU0_SB_CB<5>")
	)
	(segment
		(start 434.217826 -240.10239)
		(end 433.71389 -239.893602)
		(width 0.18288)
		(layer "In4.Cu")
		(net "M_G_CPU0_SB_CB<5>")
	)
	(segment
		(start 429.897286 -239.69345)
		(end 429.714406 -239.51057)
		(width 0.18288)
		(layer "In4.Cu")
		(net "M_G_CPU0_SB_CB<5>")
	)
	(segment
		(start 406.066498 -240.111026)
		(end 405.725884 -240.111026)
		(width 0.18288)
		(layer "In4.Cu")
		(net "M_G_CPU0_SB_CB<5>")
	)
	(segment
		(start 429.714406 -239.166908)
		(end 429.531526 -238.984028)
		(width 0.18288)
		(layer "In4.Cu")
		(net "M_G_CPU0_SB_CB<5>")
	)
	(segment
		(start 433.62753 -239.685068)
		(end 433.670456 -239.581182)
		(width 0.18288)
		(layer "In4.Cu")
		(net "M_G_CPU0_SB_CB<5>")
	)
	(segment
		(start 423.72915 -240.241582)
		(end 423.61231 -240.124742)
		(width 0.18288)
		(layer "In4.Cu")
		(net "M_G_CPU0_SB_CB<5>")
	)
	(segment
		(start 402.639022 -240.541048)
		(end 402.639022 -240.293652)
		(width 0.18288)
		(layer "In4.Cu")
		(net "M_G_CPU0_SB_CB<5>")
	)
	(segment
		(start 379.134624 -243.595144)
		(end 379.12294 -243.601748)
		(width 0.088646)
		(layer "In4.Cu")
		(net "M_G_CPU0_SB_CB<5>")
	)
	(segment
		(start 388.255764 -243.323364)
		(end 386.944616 -243.323364)
		(width 0.088646)
		(layer "In4.Cu")
		(net "M_G_CPU0_SB_CB<5>")
	)
	(segment
		(start 419.953694 -240.923826)
		(end 419.178994 -240.923826)
		(width 0.18288)
		(layer "In4.Cu")
		(net "M_G_CPU0_SB_CB<5>")
	)
	(segment
		(start 425.28744 -240.441226)
		(end 425.087796 -240.241582)
		(width 0.18288)
		(layer "In4.Cu")
		(net "M_G_CPU0_SB_CB<5>")
	)
	(segment
		(start 405.725884 -240.111026)
		(end 405.72563 -240.110772)
		(width 0.18288)
		(layer "In4.Cu")
		(net "M_G_CPU0_SB_CB<5>")
	)
	(segment
		(start 433.583842 -239.371632)
		(end 433.238402 -239.228884)
		(width 0.18288)
		(layer "In4.Cu")
		(net "M_G_CPU0_SB_CB<5>")
	)
	(segment
		(start 410.38907 -240.156746)
		(end 410.20619 -240.339626)
		(width 0.18288)
		(layer "In4.Cu")
		(net "M_G_CPU0_SB_CB<5>")
	)
	(segment
		(start 402.821902 -240.723928)
		(end 402.639022 -240.541048)
		(width 0.18288)
		(layer "In4.Cu")
		(net "M_G_CPU0_SB_CB<5>")
	)
	(segment
		(start 403.332442 -240.541048)
		(end 403.149562 -240.723928)
		(width 0.18288)
		(layer "In4.Cu")
		(net "M_G_CPU0_SB_CB<5>")
	)
	(segment
		(start 414.348676 -240.347246)
		(end 414.348676 -240.375694)
		(width 0.18288)
		(layer "In4.Cu")
		(net "M_G_CPU0_SB_CB<5>")
	)
	(segment
		(start 402.639022 -240.293652)
		(end 402.456142 -240.110772)
		(width 0.18288)
		(layer "In4.Cu")
		(net "M_G_CPU0_SB_CB<5>")
	)
	(segment
		(start 406.226518 -240.510568)
		(end 406.226518 -240.271046)
		(width 0.18288)
		(layer "In4.Cu")
		(net "M_G_CPU0_SB_CB<5>")
	)
	(segment
		(start 426.519594 -239.628426)
		(end 426.519594 -239.857026)
		(width 0.18288)
		(layer "In4.Cu")
		(net "M_G_CPU0_SB_CB<5>")
	)
	(segment
		(start 411.26537 -240.339626)
		(end 411.08249 -240.156746)
		(width 0.18288)
		(layer "In4.Cu")
		(net "M_G_CPU0_SB_CB<5>")
	)
	(segment
		(start 402.456142 -240.110772)
		(end 400.586702 -240.110772)
		(width 0.18288)
		(layer "In4.Cu")
		(net "M_G_CPU0_SB_CB<5>")
	)
	(segment
		(start 380.074424 -243.595144)
		(end 380.06274 -243.601748)
		(width 0.088646)
		(layer "In4.Cu")
		(net "M_G_CPU0_SB_CB<5>")
	)
	(segment
		(start 399.80997 -240.887504)
		(end 395.665706 -240.887504)
		(width 0.18288)
		(layer "In4.Cu")
		(net "M_G_CPU0_SB_CB<5>")
	)
	(segment
		(start 425.087796 -240.241582)
		(end 423.72915 -240.241582)
		(width 0.18288)
		(layer "In4.Cu")
		(net "M_G_CPU0_SB_CB<5>")
	)
	(segment
		(start 429.531526 -238.984028)
		(end 429.203866 -238.984028)
		(width 0.18288)
		(layer "In4.Cu")
		(net "M_G_CPU0_SB_CB<5>")
	)
	(segment
		(start 422.839134 -240.124742)
		(end 421.871394 -241.092482)
		(width 0.18288)
		(layer "In4.Cu")
		(net "M_G_CPU0_SB_CB<5>")
	)
	(segment
		(start 420.12235 -241.092482)
		(end 419.953694 -240.923826)
		(width 0.18288)
		(layer "In4.Cu")
		(net "M_G_CPU0_SB_CB<5>")
	)
	(arc
		(start 383.824226 -243.600478)
		(mid 383.543142 -243.674215)
		(end 383.262632 -243.598446)
		(width 0.088646)
		(layer "In4.Cu")
		(net "M_G_CPU0_SB_CB<5>")
	)
	(arc
		(start 380.06274 -243.601748)
		(mid 379.782635 -243.67419)
		(end 379.503432 -243.598446)
		(width 0.088646)
		(layer "In4.Cu")
		(net "M_G_CPU0_SB_CB<5>")
	)
	(arc
		(start 381.944626 -243.600478)
		(mid 381.663542 -243.674215)
		(end 381.383032 -243.598446)
		(width 0.088646)
		(layer "In4.Cu")
		(net "M_G_CPU0_SB_CB<5>")
	)
	(arc
		(start 378.483622 -243.552218)
		(mid 378.181723 -243.347834)
		(end 377.90628 -243.108988)
		(width 0.088646)
		(layer "In4.Cu")
		(net "M_G_CPU0_SB_CB<5>")
	)
	(arc
		(start 379.12294 -243.601748)
		(mid 378.842835 -243.67419)
		(end 378.563632 -243.598446)
		(width 0.088646)
		(layer "In4.Cu")
		(net "M_G_CPU0_SB_CB<5>")
	)
	(arc
		(start 383.262632 -243.598446)
		(mid 383.078678 -243.548317)
		(end 382.893824 -243.595144)
		(width 0.088646)
		(layer "In4.Cu")
		(net "M_G_CPU0_SB_CB<5>")
	)
	(arc
		(start 385.424934 -243.674138)
		(mid 385.278611 -243.654876)
		(end 385.142232 -243.598446)
		(width 0.088646)
		(layer "In4.Cu")
		(net "M_G_CPU0_SB_CB<5>")
	)
	(arc
		(start 384.202432 -243.598446)
		(mid 384.015234 -243.548303)
		(end 383.828036 -243.598446)
		(width 0.088646)
		(layer "In4.Cu")
		(net "M_G_CPU0_SB_CB<5>")
	)
	(arc
		(start 381.383032 -243.598446)
		(mid 381.199078 -243.548317)
		(end 381.014224 -243.595144)
		(width 0.088646)
		(layer "In4.Cu")
		(net "M_G_CPU0_SB_CB<5>")
	)
	(arc
		(start 382.88341 -243.600986)
		(mid 382.602775 -243.674154)
		(end 382.322832 -243.598446)
		(width 0.088646)
		(layer "In4.Cu")
		(net "M_G_CPU0_SB_CB<5>")
	)
	(arc
		(start 385.142232 -243.598446)
		(mid 384.955034 -243.548303)
		(end 384.767836 -243.598446)
		(width 0.088646)
		(layer "In4.Cu")
		(net "M_G_CPU0_SB_CB<5>")
	)
	(arc
		(start 384.767836 -243.598446)
		(mid 384.485134 -243.674222)
		(end 384.202432 -243.598446)
		(width 0.088646)
		(layer "In4.Cu")
		(net "M_G_CPU0_SB_CB<5>")
	)
	(arc
		(start 381.00254 -243.601748)
		(mid 380.722435 -243.67419)
		(end 380.443232 -243.598446)
		(width 0.088646)
		(layer "In4.Cu")
		(net "M_G_CPU0_SB_CB<5>")
	)
	(arc
		(start 380.443232 -243.598446)
		(mid 380.259278 -243.548317)
		(end 380.074424 -243.595144)
		(width 0.088646)
		(layer "In4.Cu")
		(net "M_G_CPU0_SB_CB<5>")
	)
	(arc
		(start 379.503432 -243.598446)
		(mid 379.319478 -243.548317)
		(end 379.134624 -243.595144)
		(width 0.088646)
		(layer "In4.Cu")
		(net "M_G_CPU0_SB_CB<5>")
	)
	(arc
		(start 382.322832 -243.598446)
		(mid 382.135524 -243.548303)
		(end 381.948182 -243.598446)
		(width 0.088646)
		(layer "In4.Cu")
		(net "M_G_CPU0_SB_CB<5>")
	)
	(segment
		(start 378.37618 -244.458744)
		(end 378.376434 -244.45849)
		(width 0.20066)
		(layer "F.Cu")
		(net "M_G_CPU0_SB_CB<4>")
	)
	(segment
		(start 438.449212 -241.516662)
		(end 436.928514 -241.516662)
		(width 0.20066)
		(layer "F.Cu")
		(net "M_G_CPU0_SB_CB<4>")
	)
	(segment
		(start 378.376434 -244.45849)
		(end 378.376434 -243.922804)
		(width 0.20066)
		(layer "F.Cu")
		(net "M_G_CPU0_SB_CB<4>")
	)
	(segment
		(start 439.726324 -241.09172)
		(end 439.479182 -241.09172)
		(width 0.20066)
		(layer "F.Cu")
		(net "M_G_CPU0_SB_CB<4>")
	)
	(segment
		(start 442.84138 -241.516916)
		(end 442.416184 -241.09172)
		(width 0.20066)
		(layer "F.Cu")
		(net "M_G_CPU0_SB_CB<4>")
	)
	(segment
		(start 442.181234 -241.09172)
		(end 439.87085 -241.09172)
		(width 0.1016)
		(layer "F.Cu")
		(net "M_G_CPU0_SB_CB<4>")
	)
	(segment
		(start 438.697878 -241.765328)
		(end 438.449212 -241.516662)
		(width 0.20066)
		(layer "F.Cu")
		(net "M_G_CPU0_SB_CB<4>")
	)
	(segment
		(start 439.361072 -241.577368)
		(end 439.173112 -241.765328)
		(width 0.20066)
		(layer "F.Cu")
		(net "M_G_CPU0_SB_CB<4>")
	)
	(segment
		(start 444.472314 -241.516662)
		(end 444.47206 -241.516916)
		(width 0.20066)
		(layer "F.Cu")
		(net "M_G_CPU0_SB_CB<4>")
	)
	(segment
		(start 436.928514 -241.516662)
		(end 435.823614 -241.516662)
		(width 0.20066)
		(layer "F.Cu")
		(net "M_G_CPU0_SB_CB<4>")
	)
	(segment
		(start 439.173112 -241.765328)
		(end 438.697878 -241.765328)
		(width 0.20066)
		(layer "F.Cu")
		(net "M_G_CPU0_SB_CB<4>")
	)
	(segment
		(start 439.479182 -241.09172)
		(end 439.361072 -241.20983)
		(width 0.20066)
		(layer "F.Cu")
		(net "M_G_CPU0_SB_CB<4>")
	)
	(segment
		(start 439.87085 -241.09172)
		(end 439.726324 -241.09172)
		(width 0.101854)
		(layer "F.Cu")
		(net "M_G_CPU0_SB_CB<4>")
	)
	(segment
		(start 439.361072 -241.20983)
		(end 439.361072 -241.577368)
		(width 0.20066)
		(layer "F.Cu")
		(net "M_G_CPU0_SB_CB<4>")
	)
	(segment
		(start 442.416184 -241.09172)
		(end 442.21781 -241.09172)
		(width 0.20066)
		(layer "F.Cu")
		(net "M_G_CPU0_SB_CB<4>")
	)
	(segment
		(start 444.47206 -241.516916)
		(end 442.84138 -241.516916)
		(width 0.20066)
		(layer "F.Cu")
		(net "M_G_CPU0_SB_CB<4>")
	)
	(segment
		(start 442.21781 -241.09172)
		(end 442.181234 -241.09172)
		(width 0.101854)
		(layer "F.Cu")
		(net "M_G_CPU0_SB_CB<4>")
	)
	(segment
		(start 435.189376 -242.1509)
		(end 434.332888 -242.1509)
		(width 0.18288)
		(layer "In4.Cu")
		(net "M_G_CPU0_SB_CB<4>")
	)
	(segment
		(start 422.899078 -241.623088)
		(end 422.021254 -242.500912)
		(width 0.18288)
		(layer "In4.Cu")
		(net "M_G_CPU0_SB_CB<4>")
	)
	(segment
		(start 422.021254 -242.500912)
		(end 421.259762 -242.500912)
		(width 0.18288)
		(layer "In4.Cu")
		(net "M_G_CPU0_SB_CB<4>")
	)
	(segment
		(start 430.033176 -241.266726)
		(end 429.873156 -241.426746)
		(width 0.18288)
		(layer "In4.Cu")
		(net "M_G_CPU0_SB_CB<4>")
	)
	(segment
		(start 411.697424 -242.69319)
		(end 411.369764 -242.69319)
		(width 0.18288)
		(layer "In4.Cu")
		(net "M_G_CPU0_SB_CB<4>")
	)
	(segment
		(start 415.917634 -241.688366)
		(end 413.169354 -241.688366)
		(width 0.18288)
		(layer "In4.Cu")
		(net "M_G_CPU0_SB_CB<4>")
	)
	(segment
		(start 412.063184 -242.066826)
		(end 411.880304 -242.249706)
		(width 0.18288)
		(layer "In4.Cu")
		(net "M_G_CPU0_SB_CB<4>")
	)
	(segment
		(start 409.245816 -241.883184)
		(end 404.941786 -241.883184)
		(width 0.18288)
		(layer "In4.Cu")
		(net "M_G_CPU0_SB_CB<4>")
	)
	(segment
		(start 410.038804 -241.943636)
		(end 409.306268 -241.943636)
		(width 0.18288)
		(layer "In4.Cu")
		(net "M_G_CPU0_SB_CB<4>")
	)
	(segment
		(start 382.800098 -244.41658)
		(end 382.792732 -244.412262)
		(width 0.088646)
		(layer "In4.Cu")
		(net "M_G_CPU0_SB_CB<4>")
	)
	(segment
		(start 411.880304 -242.51031)
		(end 411.697424 -242.69319)
		(width 0.18288)
		(layer "In4.Cu")
		(net "M_G_CPU0_SB_CB<4>")
	)
	(segment
		(start 383.732532 -244.412262)
		(end 383.729992 -244.410738)
		(width 0.088646)
		(layer "In4.Cu")
		(net "M_G_CPU0_SB_CB<4>")
	)
	(segment
		(start 388.255764 -244.047264)
		(end 388.239508 -244.047264)
		(width 0.088646)
		(layer "In4.Cu")
		(net "M_G_CPU0_SB_CB<4>")
	)
	(segment
		(start 435.823614 -241.516662)
		(end 435.189376 -242.1509)
		(width 0.18288)
		(layer "In4.Cu")
		(net "M_G_CPU0_SB_CB<4>")
	)
	(segment
		(start 413.169354 -241.688366)
		(end 412.790894 -242.066826)
		(width 0.18288)
		(layer "In4.Cu")
		(net "M_G_CPU0_SB_CB<4>")
	)
	(segment
		(start 404.127462 -242.697508)
		(end 395.293342 -242.697508)
		(width 0.18288)
		(layer "In4.Cu")
		(net "M_G_CPU0_SB_CB<4>")
	)
	(segment
		(start 430.992534 -241.426746)
		(end 430.832514 -241.266726)
		(width 0.18288)
		(layer "In4.Cu")
		(net "M_G_CPU0_SB_CB<4>")
	)
	(segment
		(start 379.973332 -244.412262)
		(end 379.96876 -244.409722)
		(width 0.088646)
		(layer "In4.Cu")
		(net "M_G_CPU0_SB_CB<4>")
	)
	(segment
		(start 431.734468 -241.269774)
		(end 431.734468 -241.960146)
		(width 0.18288)
		(layer "In4.Cu")
		(net "M_G_CPU0_SB_CB<4>")
	)
	(segment
		(start 410.161994 -242.066826)
		(end 410.038804 -241.943636)
		(width 0.18288)
		(layer "In4.Cu")
		(net "M_G_CPU0_SB_CB<4>")
	)
	(segment
		(start 420.501572 -242.792504)
		(end 420.207694 -242.498626)
		(width 0.18288)
		(layer "In4.Cu")
		(net "M_G_CPU0_SB_CB<4>")
	)
	(segment
		(start 381.852932 -244.412262)
		(end 381.850392 -244.410738)
		(width 0.088646)
		(layer "In4.Cu")
		(net "M_G_CPU0_SB_CB<4>")
	)
	(segment
		(start 411.186884 -242.51031)
		(end 411.186884 -242.249706)
		(width 0.18288)
		(layer "In4.Cu")
		(net "M_G_CPU0_SB_CB<4>")
	)
	(segment
		(start 380.920498 -244.41658)
		(end 380.913132 -244.412262)
		(width 0.088646)
		(layer "In4.Cu")
		(net "M_G_CPU0_SB_CB<4>")
	)
	(segment
		(start 430.832514 -241.266726)
		(end 430.033176 -241.266726)
		(width 0.18288)
		(layer "In4.Cu")
		(net "M_G_CPU0_SB_CB<4>")
	)
	(segment
		(start 411.880304 -242.249706)
		(end 411.880304 -242.51031)
		(width 0.18288)
		(layer "In4.Cu")
		(net "M_G_CPU0_SB_CB<4>")
	)
	(segment
		(start 404.941786 -241.883184)
		(end 404.127462 -242.697508)
		(width 0.18288)
		(layer "In4.Cu")
		(net "M_G_CPU0_SB_CB<4>")
	)
	(segment
		(start 395.293342 -242.697508)
		(end 393.943586 -244.047264)
		(width 0.18288)
		(layer "In4.Cu")
		(net "M_G_CPU0_SB_CB<4>")
	)
	(segment
		(start 424.541188 -241.94262)
		(end 424.221656 -241.623088)
		(width 0.18288)
		(layer "In4.Cu")
		(net "M_G_CPU0_SB_CB<4>")
	)
	(segment
		(start 379.980698 -244.41658)
		(end 379.973332 -244.412262)
		(width 0.088646)
		(layer "In4.Cu")
		(net "M_G_CPU0_SB_CB<4>")
	)
	(segment
		(start 429.3362 -242.669568)
		(end 429.153066 -242.486434)
		(width 0.18288)
		(layer "In4.Cu")
		(net "M_G_CPU0_SB_CB<4>")
	)
	(segment
		(start 425.606464 -242.302284)
		(end 425.2468 -241.94262)
		(width 0.18288)
		(layer "In4.Cu")
		(net "M_G_CPU0_SB_CB<4>")
	)
	(segment
		(start 378.81687 -244.18798)
		(end 378.376434 -243.922804)
		(width 0.088646)
		(layer "In4.Cu")
		(net "M_G_CPU0_SB_CB<4>")
	)
	(segment
		(start 411.004004 -242.066826)
		(end 410.161994 -242.066826)
		(width 0.18288)
		(layer "In4.Cu")
		(net "M_G_CPU0_SB_CB<4>")
	)
	(segment
		(start 418.3126 -242.498626)
		(end 417.756594 -241.94262)
		(width 0.18288)
		(layer "In4.Cu")
		(net "M_G_CPU0_SB_CB<4>")
	)
	(segment
		(start 429.153066 -241.487452)
		(end 428.993046 -241.327432)
		(width 0.18288)
		(layer "In4.Cu")
		(net "M_G_CPU0_SB_CB<4>")
	)
	(segment
		(start 386.666232 -244.361716)
		(end 386.364734 -244.361716)
		(width 0.088646)
		(layer "In4.Cu")
		(net "M_G_CPU0_SB_CB<4>")
	)
	(segment
		(start 431.551334 -242.14328)
		(end 431.152554 -242.14328)
		(width 0.18288)
		(layer "In4.Cu")
		(net "M_G_CPU0_SB_CB<4>")
	)
	(segment
		(start 424.221656 -241.623088)
		(end 422.899078 -241.623088)
		(width 0.18288)
		(layer "In4.Cu")
		(net "M_G_CPU0_SB_CB<4>")
	)
	(segment
		(start 420.207694 -242.498626)
		(end 418.3126 -242.498626)
		(width 0.18288)
		(layer "In4.Cu")
		(net "M_G_CPU0_SB_CB<4>")
	)
	(segment
		(start 420.96817 -242.792504)
		(end 420.501572 -242.792504)
		(width 0.18288)
		(layer "In4.Cu")
		(net "M_G_CPU0_SB_CB<4>")
	)
	(segment
		(start 431.152554 -242.14328)
		(end 430.992534 -241.98326)
		(width 0.18288)
		(layer "In4.Cu")
		(net "M_G_CPU0_SB_CB<4>")
	)
	(segment
		(start 429.873156 -241.426746)
		(end 429.873156 -242.509548)
		(width 0.18288)
		(layer "In4.Cu")
		(net "M_G_CPU0_SB_CB<4>")
	)
	(segment
		(start 416.171888 -241.94262)
		(end 415.917634 -241.688366)
		(width 0.18288)
		(layer "In4.Cu")
		(net "M_G_CPU0_SB_CB<4>")
	)
	(segment
		(start 425.2468 -241.94262)
		(end 424.541188 -241.94262)
		(width 0.18288)
		(layer "In4.Cu")
		(net "M_G_CPU0_SB_CB<4>")
	)
	(segment
		(start 434.332888 -242.1509)
		(end 433.232814 -241.050826)
		(width 0.18288)
		(layer "In4.Cu")
		(net "M_G_CPU0_SB_CB<4>")
	)
	(segment
		(start 388.228332 -244.036088)
		(end 386.99186 -244.036088)
		(width 0.088646)
		(layer "In4.Cu")
		(net "M_G_CPU0_SB_CB<4>")
	)
	(segment
		(start 431.953416 -241.050826)
		(end 431.734468 -241.269774)
		(width 0.18288)
		(layer "In4.Cu")
		(net "M_G_CPU0_SB_CB<4>")
	)
	(segment
		(start 417.756594 -241.94262)
		(end 416.171888 -241.94262)
		(width 0.18288)
		(layer "In4.Cu")
		(net "M_G_CPU0_SB_CB<4>")
	)
	(segment
		(start 409.306268 -241.943636)
		(end 409.245816 -241.883184)
		(width 0.18288)
		(layer "In4.Cu")
		(net "M_G_CPU0_SB_CB<4>")
	)
	(segment
		(start 393.943586 -244.047264)
		(end 388.255764 -244.047264)
		(width 0.18288)
		(layer "In4.Cu")
		(net "M_G_CPU0_SB_CB<4>")
	)
	(segment
		(start 412.790894 -242.066826)
		(end 412.063184 -242.066826)
		(width 0.18288)
		(layer "In4.Cu")
		(net "M_G_CPU0_SB_CB<4>")
	)
	(segment
		(start 427.932088 -241.327432)
		(end 426.957236 -242.302284)
		(width 0.18288)
		(layer "In4.Cu")
		(net "M_G_CPU0_SB_CB<4>")
	)
	(segment
		(start 429.713136 -242.669568)
		(end 429.3362 -242.669568)
		(width 0.18288)
		(layer "In4.Cu")
		(net "M_G_CPU0_SB_CB<4>")
	)
	(segment
		(start 411.186884 -242.249706)
		(end 411.004004 -242.066826)
		(width 0.18288)
		(layer "In4.Cu")
		(net "M_G_CPU0_SB_CB<4>")
	)
	(segment
		(start 388.239508 -244.047264)
		(end 388.228332 -244.036088)
		(width 0.088646)
		(layer "In4.Cu")
		(net "M_G_CPU0_SB_CB<4>")
	)
	(segment
		(start 429.873156 -242.509548)
		(end 429.713136 -242.669568)
		(width 0.18288)
		(layer "In4.Cu")
		(net "M_G_CPU0_SB_CB<4>")
	)
	(segment
		(start 382.792732 -244.412262)
		(end 382.788922 -244.41023)
		(width 0.088646)
		(layer "In4.Cu")
		(net "M_G_CPU0_SB_CB<4>")
	)
	(segment
		(start 430.992534 -241.98326)
		(end 430.992534 -241.426746)
		(width 0.18288)
		(layer "In4.Cu")
		(net "M_G_CPU0_SB_CB<4>")
	)
	(segment
		(start 433.232814 -241.050826)
		(end 431.953416 -241.050826)
		(width 0.18288)
		(layer "In4.Cu")
		(net "M_G_CPU0_SB_CB<4>")
	)
	(segment
		(start 426.957236 -242.302284)
		(end 425.606464 -242.302284)
		(width 0.18288)
		(layer "In4.Cu")
		(net "M_G_CPU0_SB_CB<4>")
	)
	(segment
		(start 431.734468 -241.960146)
		(end 431.551334 -242.14328)
		(width 0.18288)
		(layer "In4.Cu")
		(net "M_G_CPU0_SB_CB<4>")
	)
	(segment
		(start 380.913132 -244.412262)
		(end 380.90856 -244.409722)
		(width 0.088646)
		(layer "In4.Cu")
		(net "M_G_CPU0_SB_CB<4>")
	)
	(segment
		(start 428.993046 -241.327432)
		(end 427.932088 -241.327432)
		(width 0.18288)
		(layer "In4.Cu")
		(net "M_G_CPU0_SB_CB<4>")
	)
	(segment
		(start 386.99186 -244.036088)
		(end 386.666232 -244.361716)
		(width 0.088646)
		(layer "In4.Cu")
		(net "M_G_CPU0_SB_CB<4>")
	)
	(segment
		(start 429.153066 -242.486434)
		(end 429.153066 -241.487452)
		(width 0.18288)
		(layer "In4.Cu")
		(net "M_G_CPU0_SB_CB<4>")
	)
	(segment
		(start 421.259762 -242.500912)
		(end 420.96817 -242.792504)
		(width 0.18288)
		(layer "In4.Cu")
		(net "M_G_CPU0_SB_CB<4>")
	)
	(segment
		(start 411.369764 -242.69319)
		(end 411.186884 -242.51031)
		(width 0.18288)
		(layer "In4.Cu")
		(net "M_G_CPU0_SB_CB<4>")
	)
	(arc
		(start 384.672332 -244.412262)
		(mid 384.485134 -244.362119)
		(end 384.297936 -244.412262)
		(width 0.088646)
		(layer "In4.Cu")
		(net "M_G_CPU0_SB_CB<4>")
	)
	(arc
		(start 385.237736 -244.412262)
		(mid 384.955034 -244.488038)
		(end 384.672332 -244.412262)
		(width 0.088646)
		(layer "In4.Cu")
		(net "M_G_CPU0_SB_CB<4>")
	)
	(arc
		(start 385.612132 -244.412262)
		(mid 385.424934 -244.362119)
		(end 385.237736 -244.412262)
		(width 0.088646)
		(layer "In4.Cu")
		(net "M_G_CPU0_SB_CB<4>")
	)
	(arc
		(start 381.850392 -244.410738)
		(mid 381.664143 -244.362093)
		(end 381.478282 -244.412262)
		(width 0.088646)
		(layer "In4.Cu")
		(net "M_G_CPU0_SB_CB<4>")
	)
	(arc
		(start 379.598682 -244.412262)
		(mid 379.16014 -244.46613)
		(end 378.81687 -244.18798)
		(width 0.088646)
		(layer "In4.Cu")
		(net "M_G_CPU0_SB_CB<4>")
	)
	(arc
		(start 382.788922 -244.41023)
		(mid 382.603232 -244.362152)
		(end 382.418082 -244.412262)
		(width 0.088646)
		(layer "In4.Cu")
		(net "M_G_CPU0_SB_CB<4>")
	)
	(arc
		(start 384.297936 -244.412262)
		(mid 384.015234 -244.488038)
		(end 383.732532 -244.412262)
		(width 0.088646)
		(layer "In4.Cu")
		(net "M_G_CPU0_SB_CB<4>")
	)
	(arc
		(start 381.478282 -244.412262)
		(mid 381.199959 -244.488021)
		(end 380.920498 -244.41658)
		(width 0.088646)
		(layer "In4.Cu")
		(net "M_G_CPU0_SB_CB<4>")
	)
	(arc
		(start 382.418082 -244.412262)
		(mid 382.135524 -244.487911)
		(end 381.852932 -244.412262)
		(width 0.088646)
		(layer "In4.Cu")
		(net "M_G_CPU0_SB_CB<4>")
	)
	(arc
		(start 386.177536 -244.412262)
		(mid 385.894834 -244.488004)
		(end 385.612132 -244.412262)
		(width 0.088646)
		(layer "In4.Cu")
		(net "M_G_CPU0_SB_CB<4>")
	)
	(arc
		(start 380.538482 -244.412262)
		(mid 380.260159 -244.488021)
		(end 379.980698 -244.41658)
		(width 0.088646)
		(layer "In4.Cu")
		(net "M_G_CPU0_SB_CB<4>")
	)
	(arc
		(start 380.90856 -244.409722)
		(mid 380.723175 -244.362084)
		(end 380.538482 -244.412262)
		(width 0.088646)
		(layer "In4.Cu")
		(net "M_G_CPU0_SB_CB<4>")
	)
	(arc
		(start 379.96876 -244.409722)
		(mid 379.783375 -244.362084)
		(end 379.598682 -244.412262)
		(width 0.088646)
		(layer "In4.Cu")
		(net "M_G_CPU0_SB_CB<4>")
	)
	(arc
		(start 386.364734 -244.361716)
		(mid 386.267811 -244.374674)
		(end 386.177536 -244.412262)
		(width 0.088646)
		(layer "In4.Cu")
		(net "M_G_CPU0_SB_CB<4>")
	)
	(arc
		(start 383.729992 -244.410738)
		(mid 383.543743 -244.362093)
		(end 383.357882 -244.412262)
		(width 0.088646)
		(layer "In4.Cu")
		(net "M_G_CPU0_SB_CB<4>")
	)
	(arc
		(start 383.357882 -244.412262)
		(mid 383.079559 -244.488021)
		(end 382.800098 -244.41658)
		(width 0.088646)
		(layer "In4.Cu")
		(net "M_G_CPU0_SB_CB<4>")
	)
	(segment
		(start 443.462664 -233.441748)
		(end 445.470534 -233.441748)
		(width 0.1016)
		(layer "F.Cu")
		(net "M_G_CPU0_SB_CB<3>")
	)
	(segment
		(start 379.31598 -241.203226)
		(end 379.316234 -241.202972)
		(width 0.20066)
		(layer "F.Cu")
		(net "M_G_CPU0_SB_CB<3>")
	)
	(segment
		(start 446.367916 -233.241088)
		(end 446.367916 -232.943908)
		(width 0.20066)
		(layer "F.Cu")
		(net "M_G_CPU0_SB_CB<3>")
	)
	(segment
		(start 442.733938 -233.016806)
		(end 443.15888 -233.441748)
		(width 0.20066)
		(layer "F.Cu")
		(net "M_G_CPU0_SB_CB<3>")
	)
	(segment
		(start 445.774572 -233.441748)
		(end 446.167256 -233.441748)
		(width 0.20066)
		(layer "F.Cu")
		(net "M_G_CPU0_SB_CB<3>")
	)
	(segment
		(start 446.568576 -232.743248)
		(end 446.964562 -232.743248)
		(width 0.20066)
		(layer "F.Cu")
		(net "M_G_CPU0_SB_CB<3>")
	)
	(segment
		(start 439.923682 -233.016806)
		(end 441.028582 -233.016806)
		(width 0.20066)
		(layer "F.Cu")
		(net "M_G_CPU0_SB_CB<3>")
	)
	(segment
		(start 443.283086 -233.441748)
		(end 443.462664 -233.441748)
		(width 0.101854)
		(layer "F.Cu")
		(net "M_G_CPU0_SB_CB<3>")
	)
	(segment
		(start 443.15888 -233.441748)
		(end 443.283086 -233.441748)
		(width 0.20066)
		(layer "F.Cu")
		(net "M_G_CPU0_SB_CB<3>")
	)
	(segment
		(start 446.964562 -232.743248)
		(end 447.23812 -233.016806)
		(width 0.20066)
		(layer "F.Cu")
		(net "M_G_CPU0_SB_CB<3>")
	)
	(segment
		(start 446.367916 -232.943908)
		(end 446.568576 -232.743248)
		(width 0.20066)
		(layer "F.Cu")
		(net "M_G_CPU0_SB_CB<3>")
	)
	(segment
		(start 445.470534 -233.441748)
		(end 445.774572 -233.441748)
		(width 0.101854)
		(layer "F.Cu")
		(net "M_G_CPU0_SB_CB<3>")
	)
	(segment
		(start 447.23812 -233.016806)
		(end 448.572382 -233.016806)
		(width 0.20066)
		(layer "F.Cu")
		(net "M_G_CPU0_SB_CB<3>")
	)
	(segment
		(start 446.167256 -233.441748)
		(end 446.367916 -233.241088)
		(width 0.20066)
		(layer "F.Cu")
		(net "M_G_CPU0_SB_CB<3>")
	)
	(segment
		(start 379.316234 -241.202972)
		(end 379.316234 -240.667286)
		(width 0.20066)
		(layer "F.Cu")
		(net "M_G_CPU0_SB_CB<3>")
	)
	(segment
		(start 441.028582 -233.016806)
		(end 442.733938 -233.016806)
		(width 0.20066)
		(layer "F.Cu")
		(net "M_G_CPU0_SB_CB<3>")
	)
	(segment
		(start 437.495696 -232.440226)
		(end 437.344312 -232.59161)
		(width 0.18288)
		(layer "In4.Cu")
		(net "M_G_CPU0_SB_CB<3>")
	)
	(segment
		(start 412.900114 -233.430572)
		(end 411.142434 -233.430572)
		(width 0.18288)
		(layer "In4.Cu")
		(net "M_G_CPU0_SB_CB<3>")
	)
	(segment
		(start 437.344312 -232.59161)
		(end 434.329078 -232.59161)
		(width 0.18288)
		(layer "In4.Cu")
		(net "M_G_CPU0_SB_CB<3>")
	)
	(segment
		(start 408.36723 -233.68889)
		(end 401.009612 -233.68889)
		(width 0.18288)
		(layer "In4.Cu")
		(net "M_G_CPU0_SB_CB<3>")
	)
	(segment
		(start 410.266134 -232.893362)
		(end 410.266134 -233.247692)
		(width 0.18288)
		(layer "In4.Cu")
		(net "M_G_CPU0_SB_CB<3>")
	)
	(segment
		(start 432.808888 -232.437432)
		(end 432.539394 -232.706926)
		(width 0.18288)
		(layer "In4.Cu")
		(net "M_G_CPU0_SB_CB<3>")
	)
	(segment
		(start 401.009612 -233.68889)
		(end 397.915638 -236.782864)
		(width 0.18288)
		(layer "In4.Cu")
		(net "M_G_CPU0_SB_CB<3>")
	)
	(segment
		(start 379.979174 -240.174272)
		(end 379.874526 -240.23574)
		(width 0.088646)
		(layer "In4.Cu")
		(net "M_G_CPU0_SB_CB<3>")
	)
	(segment
		(start 410.266134 -233.247692)
		(end 410.083254 -233.430572)
		(width 0.18288)
		(layer "In4.Cu")
		(net "M_G_CPU0_SB_CB<3>")
	)
	(segment
		(start 390.927082 -239.30483)
		(end 388.255764 -239.30483)
		(width 0.18288)
		(layer "In4.Cu")
		(net "M_G_CPU0_SB_CB<3>")
	)
	(segment
		(start 380.918974 -240.174272)
		(end 380.913132 -240.177828)
		(width 0.088646)
		(layer "In4.Cu")
		(net "M_G_CPU0_SB_CB<3>")
	)
	(segment
		(start 431.188622 -231.830626)
		(end 427.916594 -231.830626)
		(width 0.18288)
		(layer "In4.Cu")
		(net "M_G_CPU0_SB_CB<3>")
	)
	(segment
		(start 410.776674 -232.710482)
		(end 410.449014 -232.710482)
		(width 0.18288)
		(layer "In4.Cu")
		(net "M_G_CPU0_SB_CB<3>")
	)
	(segment
		(start 426.760386 -231.742234)
		(end 422.245028 -231.742234)
		(width 0.18288)
		(layer "In4.Cu")
		(net "M_G_CPU0_SB_CB<3>")
	)
	(segment
		(start 412.99892 -233.529378)
		(end 412.900114 -233.430572)
		(width 0.18288)
		(layer "In4.Cu")
		(net "M_G_CPU0_SB_CB<3>")
	)
	(segment
		(start 427.916594 -231.830626)
		(end 427.63694 -231.550972)
		(width 0.18288)
		(layer "In4.Cu")
		(net "M_G_CPU0_SB_CB<3>")
	)
	(segment
		(start 434.329078 -232.59161)
		(end 434.1749 -232.437432)
		(width 0.18288)
		(layer "In4.Cu")
		(net "M_G_CPU0_SB_CB<3>")
	)
	(segment
		(start 408.625548 -233.430572)
		(end 408.36723 -233.68889)
		(width 0.18288)
		(layer "In4.Cu")
		(net "M_G_CPU0_SB_CB<3>")
	)
	(segment
		(start 420.46271 -232.594404)
		(end 420.123112 -232.934002)
		(width 0.18288)
		(layer "In4.Cu")
		(net "M_G_CPU0_SB_CB<3>")
	)
	(segment
		(start 438.267094 -232.440226)
		(end 437.495696 -232.440226)
		(width 0.18288)
		(layer "In4.Cu")
		(net "M_G_CPU0_SB_CB<3>")
	)
	(segment
		(start 382.798574 -240.174272)
		(end 382.792732 -240.177828)
		(width 0.088646)
		(layer "In4.Cu")
		(net "M_G_CPU0_SB_CB<3>")
	)
	(segment
		(start 379.316488 -240.667032)
		(end 379.316234 -240.667286)
		(width 0.088646)
		(layer "In4.Cu")
		(net "M_G_CPU0_SB_CB<3>")
	)
	(segment
		(start 380.913132 -240.177828)
		(end 380.90729 -240.18113)
		(width 0.088646)
		(layer "In4.Cu")
		(net "M_G_CPU0_SB_CB<3>")
	)
	(segment
		(start 382.792732 -240.177828)
		(end 382.788922 -240.17986)
		(width 0.088646)
		(layer "In4.Cu")
		(net "M_G_CPU0_SB_CB<3>")
	)
	(segment
		(start 387.117082 -240.177574)
		(end 387.10235 -240.168938)
		(width 0.088646)
		(layer "In4.Cu")
		(net "M_G_CPU0_SB_CB<3>")
	)
	(segment
		(start 388.14248 -239.30483)
		(end 387.793484 -239.653826)
		(width 0.088646)
		(layer "In4.Cu")
		(net "M_G_CPU0_SB_CB<3>")
	)
	(segment
		(start 385.237482 -240.177574)
		(end 385.22275 -240.168938)
		(width 0.088646)
		(layer "In4.Cu")
		(net "M_G_CPU0_SB_CB<3>")
	)
	(segment
		(start 417.199826 -232.934002)
		(end 416.60445 -233.529378)
		(width 0.18288)
		(layer "In4.Cu")
		(net "M_G_CPU0_SB_CB<3>")
	)
	(segment
		(start 420.123112 -232.934002)
		(end 417.199826 -232.934002)
		(width 0.18288)
		(layer "In4.Cu")
		(net "M_G_CPU0_SB_CB<3>")
	)
	(segment
		(start 387.520942 -240.185702)
		(end 387.39064 -240.217706)
		(width 0.088646)
		(layer "In4.Cu")
		(net "M_G_CPU0_SB_CB<3>")
	)
	(segment
		(start 397.915638 -236.782864)
		(end 393.449048 -236.782864)
		(width 0.18288)
		(layer "In4.Cu")
		(net "M_G_CPU0_SB_CB<3>")
	)
	(segment
		(start 410.083254 -233.430572)
		(end 408.625548 -233.430572)
		(width 0.18288)
		(layer "In4.Cu")
		(net "M_G_CPU0_SB_CB<3>")
	)
	(segment
		(start 383.732532 -240.177828)
		(end 383.728214 -240.180368)
		(width 0.088646)
		(layer "In4.Cu")
		(net "M_G_CPU0_SB_CB<3>")
	)
	(segment
		(start 432.064922 -232.706926)
		(end 431.188622 -231.830626)
		(width 0.18288)
		(layer "In4.Cu")
		(net "M_G_CPU0_SB_CB<3>")
	)
	(segment
		(start 416.60445 -233.529378)
		(end 412.99892 -233.529378)
		(width 0.18288)
		(layer "In4.Cu")
		(net "M_G_CPU0_SB_CB<3>")
	)
	(segment
		(start 427.63694 -231.550972)
		(end 426.951648 -231.550972)
		(width 0.18288)
		(layer "In4.Cu")
		(net "M_G_CPU0_SB_CB<3>")
	)
	(segment
		(start 432.539394 -232.706926)
		(end 432.064922 -232.706926)
		(width 0.18288)
		(layer "In4.Cu")
		(net "M_G_CPU0_SB_CB<3>")
	)
	(segment
		(start 421.392858 -232.594404)
		(end 420.46271 -232.594404)
		(width 0.18288)
		(layer "In4.Cu")
		(net "M_G_CPU0_SB_CB<3>")
	)
	(segment
		(start 426.951648 -231.550972)
		(end 426.760386 -231.742234)
		(width 0.18288)
		(layer "In4.Cu")
		(net "M_G_CPU0_SB_CB<3>")
	)
	(segment
		(start 388.255764 -239.30483)
		(end 388.14248 -239.30483)
		(width 0.088646)
		(layer "In4.Cu")
		(net "M_G_CPU0_SB_CB<3>")
	)
	(segment
		(start 386.177282 -240.177574)
		(end 386.16255 -240.168938)
		(width 0.088646)
		(layer "In4.Cu")
		(net "M_G_CPU0_SB_CB<3>")
	)
	(segment
		(start 387.793484 -239.91316)
		(end 387.520942 -240.185702)
		(width 0.088646)
		(layer "In4.Cu")
		(net "M_G_CPU0_SB_CB<3>")
	)
	(segment
		(start 439.923682 -233.016806)
		(end 439.477404 -232.867962)
		(width 0.18288)
		(layer "In4.Cu")
		(net "M_G_CPU0_SB_CB<3>")
	)
	(segment
		(start 439.477404 -232.867962)
		(end 438.267094 -232.440226)
		(width 0.18288)
		(layer "In4.Cu")
		(net "M_G_CPU0_SB_CB<3>")
	)
	(segment
		(start 384.297682 -240.177574)
		(end 384.297682 -240.177828)
		(width 0.088646)
		(layer "In4.Cu")
		(net "M_G_CPU0_SB_CB<3>")
	)
	(segment
		(start 387.793484 -239.653826)
		(end 387.793484 -239.91316)
		(width 0.088646)
		(layer "In4.Cu")
		(net "M_G_CPU0_SB_CB<3>")
	)
	(segment
		(start 422.245028 -231.742234)
		(end 421.392858 -232.594404)
		(width 0.18288)
		(layer "In4.Cu")
		(net "M_G_CPU0_SB_CB<3>")
	)
	(segment
		(start 410.449014 -232.710482)
		(end 410.266134 -232.893362)
		(width 0.18288)
		(layer "In4.Cu")
		(net "M_G_CPU0_SB_CB<3>")
	)
	(segment
		(start 434.1749 -232.437432)
		(end 432.808888 -232.437432)
		(width 0.18288)
		(layer "In4.Cu")
		(net "M_G_CPU0_SB_CB<3>")
	)
	(segment
		(start 410.959554 -233.247692)
		(end 410.959554 -232.893362)
		(width 0.18288)
		(layer "In4.Cu")
		(net "M_G_CPU0_SB_CB<3>")
	)
	(segment
		(start 411.142434 -233.430572)
		(end 410.959554 -233.247692)
		(width 0.18288)
		(layer "In4.Cu")
		(net "M_G_CPU0_SB_CB<3>")
	)
	(segment
		(start 381.852932 -240.177828)
		(end 381.848614 -240.180368)
		(width 0.088646)
		(layer "In4.Cu")
		(net "M_G_CPU0_SB_CB<3>")
	)
	(segment
		(start 410.959554 -232.893362)
		(end 410.776674 -232.710482)
		(width 0.18288)
		(layer "In4.Cu")
		(net "M_G_CPU0_SB_CB<3>")
	)
	(segment
		(start 393.449048 -236.782864)
		(end 390.927082 -239.30483)
		(width 0.18288)
		(layer "In4.Cu")
		(net "M_G_CPU0_SB_CB<3>")
	)
	(arc
		(start 385.22275 -240.168938)
		(mid 384.946309 -240.101772)
		(end 384.672078 -240.177574)
		(width 0.088646)
		(layer "In4.Cu")
		(net "M_G_CPU0_SB_CB<3>")
	)
	(arc
		(start 379.874526 -240.23574)
		(mid 379.581743 -240.433577)
		(end 379.316488 -240.667032)
		(width 0.088646)
		(layer "In4.Cu")
		(net "M_G_CPU0_SB_CB<3>")
	)
	(arc
		(start 383.357882 -240.177828)
		(mid 383.078708 -240.102063)
		(end 382.798574 -240.174272)
		(width 0.088646)
		(layer "In4.Cu")
		(net "M_G_CPU0_SB_CB<3>")
	)
	(arc
		(start 385.611878 -240.177574)
		(mid 385.42468 -240.227717)
		(end 385.237482 -240.177574)
		(width 0.088646)
		(layer "In4.Cu")
		(net "M_G_CPU0_SB_CB<3>")
	)
	(arc
		(start 387.10235 -240.168938)
		(mid 386.825909 -240.101772)
		(end 386.551678 -240.177574)
		(width 0.088646)
		(layer "In4.Cu")
		(net "M_G_CPU0_SB_CB<3>")
	)
	(arc
		(start 384.672078 -240.177574)
		(mid 384.48488 -240.227717)
		(end 384.297682 -240.177574)
		(width 0.088646)
		(layer "In4.Cu")
		(net "M_G_CPU0_SB_CB<3>")
	)
	(arc
		(start 380.538482 -240.177828)
		(mid 380.259308 -240.102063)
		(end 379.979174 -240.174272)
		(width 0.088646)
		(layer "In4.Cu")
		(net "M_G_CPU0_SB_CB<3>")
	)
	(arc
		(start 387.39064 -240.217706)
		(mid 387.250009 -240.223845)
		(end 387.117082 -240.177574)
		(width 0.088646)
		(layer "In4.Cu")
		(net "M_G_CPU0_SB_CB<3>")
	)
	(arc
		(start 383.728214 -240.180368)
		(mid 383.542719 -240.228037)
		(end 383.357882 -240.177828)
		(width 0.088646)
		(layer "In4.Cu")
		(net "M_G_CPU0_SB_CB<3>")
	)
	(arc
		(start 381.478282 -240.177828)
		(mid 381.199108 -240.102063)
		(end 380.918974 -240.174272)
		(width 0.088646)
		(layer "In4.Cu")
		(net "M_G_CPU0_SB_CB<3>")
	)
	(arc
		(start 386.551678 -240.177574)
		(mid 386.36448 -240.227717)
		(end 386.177282 -240.177574)
		(width 0.088646)
		(layer "In4.Cu")
		(net "M_G_CPU0_SB_CB<3>")
	)
	(arc
		(start 384.297682 -240.177828)
		(mid 384.015124 -240.102179)
		(end 383.732532 -240.177828)
		(width 0.088646)
		(layer "In4.Cu")
		(net "M_G_CPU0_SB_CB<3>")
	)
	(arc
		(start 382.418082 -240.177828)
		(mid 382.135524 -240.102179)
		(end 381.852932 -240.177828)
		(width 0.088646)
		(layer "In4.Cu")
		(net "M_G_CPU0_SB_CB<3>")
	)
	(arc
		(start 382.788922 -240.17986)
		(mid 382.603232 -240.227938)
		(end 382.418082 -240.177828)
		(width 0.088646)
		(layer "In4.Cu")
		(net "M_G_CPU0_SB_CB<3>")
	)
	(arc
		(start 386.16255 -240.168938)
		(mid 385.886109 -240.101772)
		(end 385.611878 -240.177574)
		(width 0.088646)
		(layer "In4.Cu")
		(net "M_G_CPU0_SB_CB<3>")
	)
	(arc
		(start 381.848614 -240.180368)
		(mid 381.663119 -240.228037)
		(end 381.478282 -240.177828)
		(width 0.088646)
		(layer "In4.Cu")
		(net "M_G_CPU0_SB_CB<3>")
	)
	(arc
		(start 380.90729 -240.18113)
		(mid 380.722435 -240.22808)
		(end 380.538482 -240.177828)
		(width 0.088646)
		(layer "In4.Cu")
		(net "M_G_CPU0_SB_CB<3>")
	)
	(segment
		(start 379.786134 -242.017042)
		(end 379.78588 -242.016788)
		(width 0.20066)
		(layer "F.Cu")
		(net "M_G_CPU0_SB_CB<2>")
	)
	(segment
		(start 446.568576 -234.42168)
		(end 446.943226 -234.42168)
		(width 0.20066)
		(layer "F.Cu")
		(net "M_G_CPU0_SB_CB<2>")
	)
	(segment
		(start 442.625226 -234.716574)
		(end 443.050168 -235.141516)
		(width 0.20066)
		(layer "F.Cu")
		(net "M_G_CPU0_SB_CB<2>")
	)
	(segment
		(start 443.283086 -235.141516)
		(end 443.462664 -235.141516)
		(width 0.101854)
		(layer "F.Cu")
		(net "M_G_CPU0_SB_CB<2>")
	)
	(segment
		(start 446.167256 -235.141516)
		(end 446.367916 -234.940856)
		(width 0.20066)
		(layer "F.Cu")
		(net "M_G_CPU0_SB_CB<2>")
	)
	(segment
		(start 379.78588 -242.016788)
		(end 379.78588 -241.481102)
		(width 0.20066)
		(layer "F.Cu")
		(net "M_G_CPU0_SB_CB<2>")
	)
	(segment
		(start 445.774572 -235.141516)
		(end 446.167256 -235.141516)
		(width 0.20066)
		(layer "F.Cu")
		(net "M_G_CPU0_SB_CB<2>")
	)
	(segment
		(start 441.028582 -234.716574)
		(end 442.625226 -234.716574)
		(width 0.20066)
		(layer "F.Cu")
		(net "M_G_CPU0_SB_CB<2>")
	)
	(segment
		(start 446.367916 -234.62234)
		(end 446.568576 -234.42168)
		(width 0.20066)
		(layer "F.Cu")
		(net "M_G_CPU0_SB_CB<2>")
	)
	(segment
		(start 443.050168 -235.141516)
		(end 443.283086 -235.141516)
		(width 0.20066)
		(layer "F.Cu")
		(net "M_G_CPU0_SB_CB<2>")
	)
	(segment
		(start 446.367916 -234.940856)
		(end 446.367916 -234.62234)
		(width 0.20066)
		(layer "F.Cu")
		(net "M_G_CPU0_SB_CB<2>")
	)
	(segment
		(start 446.943226 -234.42168)
		(end 447.23812 -234.716574)
		(width 0.20066)
		(layer "F.Cu")
		(net "M_G_CPU0_SB_CB<2>")
	)
	(segment
		(start 445.428878 -235.141516)
		(end 445.774572 -235.141516)
		(width 0.101854)
		(layer "F.Cu")
		(net "M_G_CPU0_SB_CB<2>")
	)
	(segment
		(start 439.923682 -234.716574)
		(end 441.028582 -234.716574)
		(width 0.20066)
		(layer "F.Cu")
		(net "M_G_CPU0_SB_CB<2>")
	)
	(segment
		(start 443.462664 -235.141516)
		(end 445.428878 -235.141516)
		(width 0.1016)
		(layer "F.Cu")
		(net "M_G_CPU0_SB_CB<2>")
	)
	(segment
		(start 447.23812 -234.716574)
		(end 448.572382 -234.716574)
		(width 0.20066)
		(layer "F.Cu")
		(net "M_G_CPU0_SB_CB<2>")
	)
	(segment
		(start 437.786272 -234.292648)
		(end 435.96306 -234.292648)
		(width 0.18288)
		(layer "In4.Cu")
		(net "M_G_CPU0_SB_CB<2>")
	)
	(segment
		(start 422.39311 -233.44251)
		(end 421.543226 -234.292394)
		(width 0.18288)
		(layer "In4.Cu")
		(net "M_G_CPU0_SB_CB<2>")
	)
	(segment
		(start 427.865794 -233.507026)
		(end 427.637194 -233.278426)
		(width 0.18288)
		(layer "In4.Cu")
		(net "M_G_CPU0_SB_CB<2>")
	)
	(segment
		(start 438.929272 -233.722164)
		(end 438.356756 -233.722164)
		(width 0.18288)
		(layer "In4.Cu")
		(net "M_G_CPU0_SB_CB<2>")
	)
	(segment
		(start 416.304984 -235.174536)
		(end 412.994602 -235.174536)
		(width 0.18288)
		(layer "In4.Cu")
		(net "M_G_CPU0_SB_CB<2>")
	)
	(segment
		(start 418.665406 -234.292394)
		(end 418.142928 -234.814872)
		(width 0.18288)
		(layer "In4.Cu")
		(net "M_G_CPU0_SB_CB<2>")
	)
	(segment
		(start 388.255764 -240.30051)
		(end 388.009892 -240.30051)
		(width 0.088646)
		(layer "In4.Cu")
		(net "M_G_CPU0_SB_CB<2>")
	)
	(segment
		(start 386.54863 -240.915952)
		(end 386.36448 -240.915952)
		(width 0.088646)
		(layer "In4.Cu")
		(net "M_G_CPU0_SB_CB<2>")
	)
	(segment
		(start 412.994602 -235.174536)
		(end 412.689294 -234.869228)
		(width 0.18288)
		(layer "In4.Cu")
		(net "M_G_CPU0_SB_CB<2>")
	)
	(segment
		(start 418.142928 -234.814872)
		(end 416.664648 -234.814872)
		(width 0.18288)
		(layer "In4.Cu")
		(net "M_G_CPU0_SB_CB<2>")
	)
	(segment
		(start 433.933092 -234.396026)
		(end 431.755042 -234.396026)
		(width 0.18288)
		(layer "In4.Cu")
		(net "M_G_CPU0_SB_CB<2>")
	)
	(segment
		(start 416.664648 -234.814872)
		(end 416.304984 -235.174536)
		(width 0.18288)
		(layer "In4.Cu")
		(net "M_G_CPU0_SB_CB<2>")
	)
	(segment
		(start 400.872706 -235.233972)
		(end 398.328134 -237.778544)
		(width 0.18288)
		(layer "In4.Cu")
		(net "M_G_CPU0_SB_CB<2>")
	)
	(segment
		(start 406.59558 -235.051346)
		(end 406.4127 -235.234226)
		(width 0.18288)
		(layer "In4.Cu")
		(net "M_G_CPU0_SB_CB<2>")
	)
	(segment
		(start 407.289 -235.051346)
		(end 407.289 -234.88015)
		(width 0.18288)
		(layer "In4.Cu")
		(net "M_G_CPU0_SB_CB<2>")
	)
	(segment
		(start 388.009892 -240.30051)
		(end 387.686804 -240.623598)
		(width 0.088646)
		(layer "In4.Cu")
		(net "M_G_CPU0_SB_CB<2>")
	)
	(segment
		(start 407.10612 -234.69727)
		(end 406.77846 -234.69727)
		(width 0.18288)
		(layer "In4.Cu")
		(net "M_G_CPU0_SB_CB<2>")
	)
	(segment
		(start 435.962044 -234.291632)
		(end 434.037486 -234.291632)
		(width 0.18288)
		(layer "In4.Cu")
		(net "M_G_CPU0_SB_CB<2>")
	)
	(segment
		(start 398.328134 -237.778544)
		(end 393.861544 -237.778544)
		(width 0.18288)
		(layer "In4.Cu")
		(net "M_G_CPU0_SB_CB<2>")
	)
	(segment
		(start 434.037486 -234.291632)
		(end 433.933092 -234.396026)
		(width 0.18288)
		(layer "In4.Cu")
		(net "M_G_CPU0_SB_CB<2>")
	)
	(segment
		(start 412.689294 -234.869228)
		(end 409.498292 -234.869228)
		(width 0.18288)
		(layer "In4.Cu")
		(net "M_G_CPU0_SB_CB<2>")
	)
	(segment
		(start 381.014224 -240.994946)
		(end 381.00254 -240.988342)
		(width 0.088646)
		(layer "In4.Cu")
		(net "M_G_CPU0_SB_CB<2>")
	)
	(segment
		(start 407.47188 -235.234226)
		(end 407.289 -235.051346)
		(width 0.18288)
		(layer "In4.Cu")
		(net "M_G_CPU0_SB_CB<2>")
	)
	(segment
		(start 426.943266 -233.278426)
		(end 426.451268 -233.770424)
		(width 0.18288)
		(layer "In4.Cu")
		(net "M_G_CPU0_SB_CB<2>")
	)
	(segment
		(start 426.451268 -233.770424)
		(end 425.787312 -233.770424)
		(width 0.18288)
		(layer "In4.Cu")
		(net "M_G_CPU0_SB_CB<2>")
	)
	(segment
		(start 387.686804 -240.623598)
		(end 387.110224 -240.623598)
		(width 0.088646)
		(layer "In4.Cu")
		(net "M_G_CPU0_SB_CB<2>")
	)
	(segment
		(start 382.893824 -240.994946)
		(end 382.88341 -240.989104)
		(width 0.088646)
		(layer "In4.Cu")
		(net "M_G_CPU0_SB_CB<2>")
	)
	(segment
		(start 383.828036 -240.991644)
		(end 383.824226 -240.989612)
		(width 0.088646)
		(layer "In4.Cu")
		(net "M_G_CPU0_SB_CB<2>")
	)
	(segment
		(start 435.96306 -234.292648)
		(end 435.962044 -234.291632)
		(width 0.18288)
		(layer "In4.Cu")
		(net "M_G_CPU0_SB_CB<2>")
	)
	(segment
		(start 405.72563 -235.233972)
		(end 400.872706 -235.233972)
		(width 0.18288)
		(layer "In4.Cu")
		(net "M_G_CPU0_SB_CB<2>")
	)
	(segment
		(start 421.543226 -234.292394)
		(end 418.665406 -234.292394)
		(width 0.18288)
		(layer "In4.Cu")
		(net "M_G_CPU0_SB_CB<2>")
	)
	(segment
		(start 391.339578 -240.30051)
		(end 388.255764 -240.30051)
		(width 0.18288)
		(layer "In4.Cu")
		(net "M_G_CPU0_SB_CB<2>")
	)
	(segment
		(start 380.443232 -240.991644)
		(end 380.363222 -241.037872)
		(width 0.088646)
		(layer "In4.Cu")
		(net "M_G_CPU0_SB_CB<2>")
	)
	(segment
		(start 439.923682 -234.716574)
		(end 438.929272 -233.722164)
		(width 0.18288)
		(layer "In4.Cu")
		(net "M_G_CPU0_SB_CB<2>")
	)
	(segment
		(start 387.110224 -240.623598)
		(end 386.794502 -240.757964)
		(width 0.088646)
		(layer "In4.Cu")
		(net "M_G_CPU0_SB_CB<2>")
	)
	(segment
		(start 431.755042 -234.396026)
		(end 430.866042 -233.507026)
		(width 0.18288)
		(layer "In4.Cu")
		(net "M_G_CPU0_SB_CB<2>")
	)
	(segment
		(start 409.498292 -234.869228)
		(end 409.133294 -235.234226)
		(width 0.18288)
		(layer "In4.Cu")
		(net "M_G_CPU0_SB_CB<2>")
	)
	(segment
		(start 425.459398 -233.44251)
		(end 422.39311 -233.44251)
		(width 0.18288)
		(layer "In4.Cu")
		(net "M_G_CPU0_SB_CB<2>")
	)
	(segment
		(start 406.59558 -234.88015)
		(end 406.59558 -235.051346)
		(width 0.18288)
		(layer "In4.Cu")
		(net "M_G_CPU0_SB_CB<2>")
	)
	(segment
		(start 406.4127 -235.234226)
		(end 405.725884 -235.234226)
		(width 0.18288)
		(layer "In4.Cu")
		(net "M_G_CPU0_SB_CB<2>")
	)
	(segment
		(start 438.356756 -233.722164)
		(end 437.786272 -234.292648)
		(width 0.18288)
		(layer "In4.Cu")
		(net "M_G_CPU0_SB_CB<2>")
	)
	(segment
		(start 430.866042 -233.507026)
		(end 427.865794 -233.507026)
		(width 0.18288)
		(layer "In4.Cu")
		(net "M_G_CPU0_SB_CB<2>")
	)
	(segment
		(start 409.133294 -235.234226)
		(end 407.47188 -235.234226)
		(width 0.18288)
		(layer "In4.Cu")
		(net "M_G_CPU0_SB_CB<2>")
	)
	(segment
		(start 393.861544 -237.778544)
		(end 391.339578 -240.30051)
		(width 0.18288)
		(layer "In4.Cu")
		(net "M_G_CPU0_SB_CB<2>")
	)
	(segment
		(start 425.787312 -233.770424)
		(end 425.459398 -233.44251)
		(width 0.18288)
		(layer "In4.Cu")
		(net "M_G_CPU0_SB_CB<2>")
	)
	(segment
		(start 381.948182 -240.991644)
		(end 381.944626 -240.989612)
		(width 0.088646)
		(layer "In4.Cu")
		(net "M_G_CPU0_SB_CB<2>")
	)
	(segment
		(start 386.794502 -240.757964)
		(end 386.54863 -240.915952)
		(width 0.088646)
		(layer "In4.Cu")
		(net "M_G_CPU0_SB_CB<2>")
	)
	(segment
		(start 405.725884 -235.234226)
		(end 405.72563 -235.233972)
		(width 0.18288)
		(layer "In4.Cu")
		(net "M_G_CPU0_SB_CB<2>")
	)
	(segment
		(start 406.77846 -234.69727)
		(end 406.59558 -234.88015)
		(width 0.18288)
		(layer "In4.Cu")
		(net "M_G_CPU0_SB_CB<2>")
	)
	(segment
		(start 427.637194 -233.278426)
		(end 426.943266 -233.278426)
		(width 0.18288)
		(layer "In4.Cu")
		(net "M_G_CPU0_SB_CB<2>")
	)
	(segment
		(start 407.289 -234.88015)
		(end 407.10612 -234.69727)
		(width 0.18288)
		(layer "In4.Cu")
		(net "M_G_CPU0_SB_CB<2>")
	)
	(arc
		(start 384.202432 -240.991644)
		(mid 384.015234 -241.041787)
		(end 383.828036 -240.991644)
		(width 0.088646)
		(layer "In4.Cu")
		(net "M_G_CPU0_SB_CB<2>")
	)
	(arc
		(start 383.262632 -240.991644)
		(mid 383.078678 -241.041773)
		(end 382.893824 -240.994946)
		(width 0.088646)
		(layer "In4.Cu")
		(net "M_G_CPU0_SB_CB<2>")
	)
	(arc
		(start 384.767836 -240.991644)
		(mid 384.485134 -240.915868)
		(end 384.202432 -240.991644)
		(width 0.088646)
		(layer "In4.Cu")
		(net "M_G_CPU0_SB_CB<2>")
	)
	(arc
		(start 383.824226 -240.989612)
		(mid 383.543142 -240.915875)
		(end 383.262632 -240.991644)
		(width 0.088646)
		(layer "In4.Cu")
		(net "M_G_CPU0_SB_CB<2>")
	)
	(arc
		(start 380.363222 -241.037872)
		(mid 380.060058 -241.240607)
		(end 379.78588 -241.481102)
		(width 0.088646)
		(layer "In4.Cu")
		(net "M_G_CPU0_SB_CB<2>")
	)
	(arc
		(start 381.00254 -240.988342)
		(mid 380.722435 -240.9159)
		(end 380.443232 -240.991644)
		(width 0.088646)
		(layer "In4.Cu")
		(net "M_G_CPU0_SB_CB<2>")
	)
	(arc
		(start 382.322832 -240.991644)
		(mid 382.135524 -241.041787)
		(end 381.948182 -240.991644)
		(width 0.088646)
		(layer "In4.Cu")
		(net "M_G_CPU0_SB_CB<2>")
	)
	(arc
		(start 381.944626 -240.989612)
		(mid 381.663542 -240.915875)
		(end 381.383032 -240.991644)
		(width 0.088646)
		(layer "In4.Cu")
		(net "M_G_CPU0_SB_CB<2>")
	)
	(arc
		(start 381.383032 -240.991644)
		(mid 381.199078 -241.041773)
		(end 381.014224 -240.994946)
		(width 0.088646)
		(layer "In4.Cu")
		(net "M_G_CPU0_SB_CB<2>")
	)
	(arc
		(start 385.707636 -240.991644)
		(mid 385.424934 -240.915868)
		(end 385.142232 -240.991644)
		(width 0.088646)
		(layer "In4.Cu")
		(net "M_G_CPU0_SB_CB<2>")
	)
	(arc
		(start 386.36448 -240.915952)
		(mid 386.218267 -240.935193)
		(end 386.082032 -240.991644)
		(width 0.088646)
		(layer "In4.Cu")
		(net "M_G_CPU0_SB_CB<2>")
	)
	(arc
		(start 385.142232 -240.991644)
		(mid 384.955034 -241.041787)
		(end 384.767836 -240.991644)
		(width 0.088646)
		(layer "In4.Cu")
		(net "M_G_CPU0_SB_CB<2>")
	)
	(arc
		(start 382.88341 -240.989104)
		(mid 382.602775 -240.915936)
		(end 382.322832 -240.991644)
		(width 0.088646)
		(layer "In4.Cu")
		(net "M_G_CPU0_SB_CB<2>")
	)
	(arc
		(start 386.082032 -240.991644)
		(mid 385.894834 -241.041787)
		(end 385.707636 -240.991644)
		(width 0.088646)
		(layer "In4.Cu")
		(net "M_G_CPU0_SB_CB<2>")
	)
	(segment
		(start 436.928514 -233.86669)
		(end 435.823614 -233.86669)
		(width 0.20066)
		(layer "F.Cu")
		(net "M_G_CPU0_SB_CB<1>")
	)
	(segment
		(start 439.87085 -233.441748)
		(end 439.726324 -233.441748)
		(width 0.101854)
		(layer "F.Cu")
		(net "M_G_CPU0_SB_CB<1>")
	)
	(segment
		(start 442.84138 -233.866944)
		(end 442.416184 -233.441748)
		(width 0.20066)
		(layer "F.Cu")
		(net "M_G_CPU0_SB_CB<1>")
	)
	(segment
		(start 442.181234 -233.441748)
		(end 439.87085 -233.441748)
		(width 0.1016)
		(layer "F.Cu")
		(net "M_G_CPU0_SB_CB<1>")
	)
	(segment
		(start 442.416184 -233.441748)
		(end 442.21781 -233.441748)
		(width 0.20066)
		(layer "F.Cu")
		(net "M_G_CPU0_SB_CB<1>")
	)
	(segment
		(start 439.479182 -233.441748)
		(end 439.361072 -233.559858)
		(width 0.20066)
		(layer "F.Cu")
		(net "M_G_CPU0_SB_CB<1>")
	)
	(segment
		(start 439.173112 -234.115356)
		(end 438.697878 -234.115356)
		(width 0.20066)
		(layer "F.Cu")
		(net "M_G_CPU0_SB_CB<1>")
	)
	(segment
		(start 442.21781 -233.441748)
		(end 442.181234 -233.441748)
		(width 0.101854)
		(layer "F.Cu")
		(net "M_G_CPU0_SB_CB<1>")
	)
	(segment
		(start 439.361072 -233.559858)
		(end 439.361072 -233.927396)
		(width 0.20066)
		(layer "F.Cu")
		(net "M_G_CPU0_SB_CB<1>")
	)
	(segment
		(start 444.472314 -233.86669)
		(end 444.47206 -233.866944)
		(width 0.20066)
		(layer "F.Cu")
		(net "M_G_CPU0_SB_CB<1>")
	)
	(segment
		(start 439.726324 -233.441748)
		(end 439.479182 -233.441748)
		(width 0.20066)
		(layer "F.Cu")
		(net "M_G_CPU0_SB_CB<1>")
	)
	(segment
		(start 444.47206 -233.866944)
		(end 442.84138 -233.866944)
		(width 0.20066)
		(layer "F.Cu")
		(net "M_G_CPU0_SB_CB<1>")
	)
	(segment
		(start 438.449212 -233.86669)
		(end 436.928514 -233.86669)
		(width 0.20066)
		(layer "F.Cu")
		(net "M_G_CPU0_SB_CB<1>")
	)
	(segment
		(start 378.376434 -241.202972)
		(end 378.376434 -240.667286)
		(width 0.20066)
		(layer "F.Cu")
		(net "M_G_CPU0_SB_CB<1>")
	)
	(segment
		(start 378.37618 -241.203226)
		(end 378.376434 -241.202972)
		(width 0.20066)
		(layer "F.Cu")
		(net "M_G_CPU0_SB_CB<1>")
	)
	(segment
		(start 439.361072 -233.927396)
		(end 439.173112 -234.115356)
		(width 0.20066)
		(layer "F.Cu")
		(net "M_G_CPU0_SB_CB<1>")
	)
	(segment
		(start 438.697878 -234.115356)
		(end 438.449212 -233.86669)
		(width 0.20066)
		(layer "F.Cu")
		(net "M_G_CPU0_SB_CB<1>")
	)
	(segment
		(start 402.344382 -234.192826)
		(end 401.209764 -234.192826)
		(width 0.18288)
		(layer "In4.Cu")
		(net "M_G_CPU0_SB_CB<1>")
	)
	(segment
		(start 408.701494 -234.192826)
		(end 404.790402 -234.192826)
		(width 0.18288)
		(layer "In4.Cu")
		(net "M_G_CPU0_SB_CB<1>")
	)
	(segment
		(start 403.220682 -234.375706)
		(end 403.220682 -234.54868)
		(width 0.18288)
		(layer "In4.Cu")
		(net "M_G_CPU0_SB_CB<1>")
	)
	(segment
		(start 421.529256 -233.439716)
		(end 418.408104 -233.439716)
		(width 0.18288)
		(layer "In4.Cu")
		(net "M_G_CPU0_SB_CB<1>")
	)
	(segment
		(start 380.068582 -240.342928)
		(end 380.063502 -240.345722)
		(width 0.088646)
		(layer "In4.Cu")
		(net "M_G_CPU0_SB_CB<1>")
	)
	(segment
		(start 393.655296 -237.280704)
		(end 391.13333 -239.80267)
		(width 0.18288)
		(layer "In4.Cu")
		(net "M_G_CPU0_SB_CB<1>")
	)
	(segment
		(start 429.07839 -232.434638)
		(end 428.049182 -232.434638)
		(width 0.18288)
		(layer "In4.Cu")
		(net "M_G_CPU0_SB_CB<1>")
	)
	(segment
		(start 388.255764 -239.80267)
		(end 388.213346 -239.80267)
		(width 0.088646)
		(layer "In4.Cu")
		(net "M_G_CPU0_SB_CB<1>")
	)
	(segment
		(start 415.034222 -234.19943)
		(end 414.5788 -234.654852)
		(width 0.18288)
		(layer "In4.Cu")
		(net "M_G_CPU0_SB_CB<1>")
	)
	(segment
		(start 432.990752 -233.095292)
		(end 432.990752 -233.275632)
		(width 0.18288)
		(layer "In4.Cu")
		(net "M_G_CPU0_SB_CB<1>")
	)
	(segment
		(start 416.395408 -234.19943)
		(end 415.034222 -234.19943)
		(width 0.18288)
		(layer "In4.Cu")
		(net "M_G_CPU0_SB_CB<1>")
	)
	(segment
		(start 382.893824 -240.339372)
		(end 382.887982 -240.342928)
		(width 0.088646)
		(layer "In4.Cu")
		(net "M_G_CPU0_SB_CB<1>")
	)
	(segment
		(start 426.368972 -232.925112)
		(end 426.208952 -233.085132)
		(width 0.18288)
		(layer "In4.Cu")
		(net "M_G_CPU0_SB_CB<1>")
	)
	(segment
		(start 412.677864 -234.077256)
		(end 412.384494 -234.370626)
		(width 0.18288)
		(layer "In4.Cu")
		(net "M_G_CPU0_SB_CB<1>")
	)
	(segment
		(start 435.823614 -233.86669)
		(end 435.392576 -233.435652)
		(width 0.18288)
		(layer "In4.Cu")
		(net "M_G_CPU0_SB_CB<1>")
	)
	(segment
		(start 404.607522 -234.375706)
		(end 404.607522 -234.54868)
		(width 0.18288)
		(layer "In4.Cu")
		(net "M_G_CPU0_SB_CB<1>")
	)
	(segment
		(start 403.403562 -234.192826)
		(end 403.220682 -234.375706)
		(width 0.18288)
		(layer "In4.Cu")
		(net "M_G_CPU0_SB_CB<1>")
	)
	(segment
		(start 379.039374 -241.160046)
		(end 379.033532 -241.156744)
		(width 0.088646)
		(layer "In4.Cu")
		(net "M_G_CPU0_SB_CB<1>")
	)
	(segment
		(start 433.524152 -232.935272)
		(end 433.150772 -232.935272)
		(width 0.18288)
		(layer "In4.Cu")
		(net "M_G_CPU0_SB_CB<1>")
	)
	(segment
		(start 432.990752 -233.275632)
		(end 432.830732 -233.435652)
		(width 0.18288)
		(layer "In4.Cu")
		(net "M_G_CPU0_SB_CB<1>")
	)
	(segment
		(start 382.887982 -240.342928)
		(end 382.88341 -240.345468)
		(width 0.088646)
		(layer "In4.Cu")
		(net "M_G_CPU0_SB_CB<1>")
	)
	(segment
		(start 426.368972 -232.808272)
		(end 426.368972 -232.925112)
		(width 0.18288)
		(layer "In4.Cu")
		(net "M_G_CPU0_SB_CB<1>")
	)
	(segment
		(start 413.215074 -234.077256)
		(end 412.677864 -234.077256)
		(width 0.18288)
		(layer "In4.Cu")
		(net "M_G_CPU0_SB_CB<1>")
	)
	(segment
		(start 379.033532 -241.156744)
		(end 378.929646 -241.09553)
		(width 0.088646)
		(layer "In4.Cu")
		(net "M_G_CPU0_SB_CB<1>")
	)
	(segment
		(start 384.217164 -240.351564)
		(end 384.202432 -240.342928)
		(width 0.088646)
		(layer "In4.Cu")
		(net "M_G_CPU0_SB_CB<1>")
	)
	(segment
		(start 404.424642 -234.73156)
		(end 404.096982 -234.73156)
		(width 0.18288)
		(layer "In4.Cu")
		(net "M_G_CPU0_SB_CB<1>")
	)
	(segment
		(start 425.675552 -232.752138)
		(end 425.515532 -232.592118)
		(width 0.18288)
		(layer "In4.Cu")
		(net "M_G_CPU0_SB_CB<1>")
	)
	(segment
		(start 404.790402 -234.192826)
		(end 404.607522 -234.375706)
		(width 0.18288)
		(layer "In4.Cu")
		(net "M_G_CPU0_SB_CB<1>")
	)
	(segment
		(start 431.343816 -232.872026)
		(end 430.906428 -232.434638)
		(width 0.18288)
		(layer "In4.Cu")
		(net "M_G_CPU0_SB_CB<1>")
	)
	(segment
		(start 426.528992 -232.648252)
		(end 426.368972 -232.808272)
		(width 0.18288)
		(layer "In4.Cu")
		(net "M_G_CPU0_SB_CB<1>")
	)
	(segment
		(start 413.844994 -234.269026)
		(end 413.406844 -234.269026)
		(width 0.18288)
		(layer "In4.Cu")
		(net "M_G_CPU0_SB_CB<1>")
	)
	(segment
		(start 433.844192 -233.435652)
		(end 433.684172 -233.275632)
		(width 0.18288)
		(layer "In4.Cu")
		(net "M_G_CPU0_SB_CB<1>")
	)
	(segment
		(start 435.392576 -233.435652)
		(end 433.844192 -233.435652)
		(width 0.18288)
		(layer "In4.Cu")
		(net "M_G_CPU0_SB_CB<1>")
	)
	(segment
		(start 425.835572 -233.085132)
		(end 425.675552 -232.925112)
		(width 0.18288)
		(layer "In4.Cu")
		(net "M_G_CPU0_SB_CB<1>")
	)
	(segment
		(start 429.93183 -232.769918)
		(end 429.77181 -232.929938)
		(width 0.18288)
		(layer "In4.Cu")
		(net "M_G_CPU0_SB_CB<1>")
	)
	(segment
		(start 427.738794 -232.745026)
		(end 427.256702 -232.745026)
		(width 0.18288)
		(layer "In4.Cu")
		(net "M_G_CPU0_SB_CB<1>")
	)
	(segment
		(start 404.096982 -234.73156)
		(end 403.914102 -234.54868)
		(width 0.18288)
		(layer "In4.Cu")
		(net "M_G_CPU0_SB_CB<1>")
	)
	(segment
		(start 387.036564 -240.351564)
		(end 387.021832 -240.342928)
		(width 0.088646)
		(layer "In4.Cu")
		(net "M_G_CPU0_SB_CB<1>")
	)
	(segment
		(start 381.008382 -240.342928)
		(end 381.00254 -240.34623)
		(width 0.088646)
		(layer "In4.Cu")
		(net "M_G_CPU0_SB_CB<1>")
	)
	(segment
		(start 429.93183 -232.594658)
		(end 429.93183 -232.769918)
		(width 0.18288)
		(layer "In4.Cu")
		(net "M_G_CPU0_SB_CB<1>")
	)
	(segment
		(start 417.551616 -234.296204)
		(end 416.492182 -234.296204)
		(width 0.18288)
		(layer "In4.Cu")
		(net "M_G_CPU0_SB_CB<1>")
	)
	(segment
		(start 429.77181 -232.929938)
		(end 429.39843 -232.929938)
		(width 0.18288)
		(layer "In4.Cu")
		(net "M_G_CPU0_SB_CB<1>")
	)
	(segment
		(start 433.684172 -233.095292)
		(end 433.524152 -232.935272)
		(width 0.18288)
		(layer "In4.Cu")
		(net "M_G_CPU0_SB_CB<1>")
	)
	(segment
		(start 403.731222 -234.192826)
		(end 403.403562 -234.192826)
		(width 0.18288)
		(layer "In4.Cu")
		(net "M_G_CPU0_SB_CB<1>")
	)
	(segment
		(start 408.879294 -234.370626)
		(end 408.701494 -234.192826)
		(width 0.18288)
		(layer "In4.Cu")
		(net "M_G_CPU0_SB_CB<1>")
	)
	(segment
		(start 432.830732 -233.435652)
		(end 432.609498 -233.435652)
		(width 0.18288)
		(layer "In4.Cu")
		(net "M_G_CPU0_SB_CB<1>")
	)
	(segment
		(start 416.492182 -234.296204)
		(end 416.395408 -234.19943)
		(width 0.18288)
		(layer "In4.Cu")
		(net "M_G_CPU0_SB_CB<1>")
	)
	(segment
		(start 412.384494 -234.370626)
		(end 408.879294 -234.370626)
		(width 0.18288)
		(layer "In4.Cu")
		(net "M_G_CPU0_SB_CB<1>")
	)
	(segment
		(start 432.561238 -233.387392)
		(end 431.490628 -233.387392)
		(width 0.18288)
		(layer "In4.Cu")
		(net "M_G_CPU0_SB_CB<1>")
	)
	(segment
		(start 404.607522 -234.54868)
		(end 404.424642 -234.73156)
		(width 0.18288)
		(layer "In4.Cu")
		(net "M_G_CPU0_SB_CB<1>")
	)
	(segment
		(start 425.675552 -232.925112)
		(end 425.675552 -232.752138)
		(width 0.18288)
		(layer "In4.Cu")
		(net "M_G_CPU0_SB_CB<1>")
	)
	(segment
		(start 387.599936 -240.41608)
		(end 387.359906 -240.41608)
		(width 0.088646)
		(layer "In4.Cu")
		(net "M_G_CPU0_SB_CB<1>")
	)
	(segment
		(start 402.710142 -234.73156)
		(end 402.527262 -234.54868)
		(width 0.18288)
		(layer "In4.Cu")
		(net "M_G_CPU0_SB_CB<1>")
	)
	(segment
		(start 403.220682 -234.54868)
		(end 403.037802 -234.73156)
		(width 0.18288)
		(layer "In4.Cu")
		(net "M_G_CPU0_SB_CB<1>")
	)
	(segment
		(start 431.490628 -233.387392)
		(end 431.343816 -233.24058)
		(width 0.18288)
		(layer "In4.Cu")
		(net "M_G_CPU0_SB_CB<1>")
	)
	(segment
		(start 386.096764 -240.351564)
		(end 386.082032 -240.342928)
		(width 0.088646)
		(layer "In4.Cu")
		(net "M_G_CPU0_SB_CB<1>")
	)
	(segment
		(start 427.159928 -232.648252)
		(end 426.528992 -232.648252)
		(width 0.18288)
		(layer "In4.Cu")
		(net "M_G_CPU0_SB_CB<1>")
	)
	(segment
		(start 414.5788 -234.654852)
		(end 414.23082 -234.654852)
		(width 0.18288)
		(layer "In4.Cu")
		(net "M_G_CPU0_SB_CB<1>")
	)
	(segment
		(start 429.23841 -232.594658)
		(end 429.07839 -232.434638)
		(width 0.18288)
		(layer "In4.Cu")
		(net "M_G_CPU0_SB_CB<1>")
	)
	(segment
		(start 385.156964 -240.351564)
		(end 385.142232 -240.342928)
		(width 0.088646)
		(layer "In4.Cu")
		(net "M_G_CPU0_SB_CB<1>")
	)
	(segment
		(start 431.343816 -233.24058)
		(end 431.343816 -232.872026)
		(width 0.18288)
		(layer "In4.Cu")
		(net "M_G_CPU0_SB_CB<1>")
	)
	(segment
		(start 433.684172 -233.275632)
		(end 433.684172 -233.095292)
		(width 0.18288)
		(layer "In4.Cu")
		(net "M_G_CPU0_SB_CB<1>")
	)
	(segment
		(start 429.23841 -232.769918)
		(end 429.23841 -232.594658)
		(width 0.18288)
		(layer "In4.Cu")
		(net "M_G_CPU0_SB_CB<1>")
	)
	(segment
		(start 403.914102 -234.54868)
		(end 403.914102 -234.375706)
		(width 0.18288)
		(layer "In4.Cu")
		(net "M_G_CPU0_SB_CB<1>")
	)
	(segment
		(start 391.13333 -239.80267)
		(end 388.255764 -239.80267)
		(width 0.18288)
		(layer "In4.Cu")
		(net "M_G_CPU0_SB_CB<1>")
	)
	(segment
		(start 426.208952 -233.085132)
		(end 425.835572 -233.085132)
		(width 0.18288)
		(layer "In4.Cu")
		(net "M_G_CPU0_SB_CB<1>")
	)
	(segment
		(start 379.88113 -240.667286)
		(end 379.88113 -240.673636)
		(width 0.088646)
		(layer "In4.Cu")
		(net "M_G_CPU0_SB_CB<1>")
	)
	(segment
		(start 433.150772 -232.935272)
		(end 432.990752 -233.095292)
		(width 0.18288)
		(layer "In4.Cu")
		(net "M_G_CPU0_SB_CB<1>")
	)
	(segment
		(start 398.121886 -237.280704)
		(end 393.655296 -237.280704)
		(width 0.18288)
		(layer "In4.Cu")
		(net "M_G_CPU0_SB_CB<1>")
	)
	(segment
		(start 381.014224 -240.339372)
		(end 381.008382 -240.342928)
		(width 0.088646)
		(layer "In4.Cu")
		(net "M_G_CPU0_SB_CB<1>")
	)
	(segment
		(start 427.256702 -232.745026)
		(end 427.159928 -232.648252)
		(width 0.18288)
		(layer "In4.Cu")
		(net "M_G_CPU0_SB_CB<1>")
	)
	(segment
		(start 388.213346 -239.80267)
		(end 387.599936 -240.41608)
		(width 0.088646)
		(layer "In4.Cu")
		(net "M_G_CPU0_SB_CB<1>")
	)
	(segment
		(start 402.527262 -234.375706)
		(end 402.344382 -234.192826)
		(width 0.18288)
		(layer "In4.Cu")
		(net "M_G_CPU0_SB_CB<1>")
	)
	(segment
		(start 401.209764 -234.192826)
		(end 398.121886 -237.280704)
		(width 0.18288)
		(layer "In4.Cu")
		(net "M_G_CPU0_SB_CB<1>")
	)
	(segment
		(start 380.074424 -240.339372)
		(end 380.068582 -240.342928)
		(width 0.088646)
		(layer "In4.Cu")
		(net "M_G_CPU0_SB_CB<1>")
	)
	(segment
		(start 414.23082 -234.654852)
		(end 413.844994 -234.269026)
		(width 0.18288)
		(layer "In4.Cu")
		(net "M_G_CPU0_SB_CB<1>")
	)
	(segment
		(start 413.406844 -234.269026)
		(end 413.215074 -234.077256)
		(width 0.18288)
		(layer "In4.Cu")
		(net "M_G_CPU0_SB_CB<1>")
	)
	(segment
		(start 432.609498 -233.435652)
		(end 432.561238 -233.387392)
		(width 0.18288)
		(layer "In4.Cu")
		(net "M_G_CPU0_SB_CB<1>")
	)
	(segment
		(start 425.515532 -232.592118)
		(end 422.376854 -232.592118)
		(width 0.18288)
		(layer "In4.Cu")
		(net "M_G_CPU0_SB_CB<1>")
	)
	(segment
		(start 422.376854 -232.592118)
		(end 421.529256 -233.439716)
		(width 0.18288)
		(layer "In4.Cu")
		(net "M_G_CPU0_SB_CB<1>")
	)
	(segment
		(start 428.049182 -232.434638)
		(end 427.738794 -232.745026)
		(width 0.18288)
		(layer "In4.Cu")
		(net "M_G_CPU0_SB_CB<1>")
	)
	(segment
		(start 381.948182 -240.342928)
		(end 381.944626 -240.34496)
		(width 0.088646)
		(layer "In4.Cu")
		(net "M_G_CPU0_SB_CB<1>")
	)
	(segment
		(start 418.408104 -233.439716)
		(end 417.551616 -234.296204)
		(width 0.18288)
		(layer "In4.Cu")
		(net "M_G_CPU0_SB_CB<1>")
	)
	(segment
		(start 383.827782 -240.342928)
		(end 383.824226 -240.34496)
		(width 0.088646)
		(layer "In4.Cu")
		(net "M_G_CPU0_SB_CB<1>")
	)
	(segment
		(start 378.376688 -240.66754)
		(end 378.376434 -240.667286)
		(width 0.088646)
		(layer "In4.Cu")
		(net "M_G_CPU0_SB_CB<1>")
	)
	(segment
		(start 403.914102 -234.375706)
		(end 403.731222 -234.192826)
		(width 0.18288)
		(layer "In4.Cu")
		(net "M_G_CPU0_SB_CB<1>")
	)
	(segment
		(start 429.39843 -232.929938)
		(end 429.23841 -232.769918)
		(width 0.18288)
		(layer "In4.Cu")
		(net "M_G_CPU0_SB_CB<1>")
	)
	(segment
		(start 403.037802 -234.73156)
		(end 402.710142 -234.73156)
		(width 0.18288)
		(layer "In4.Cu")
		(net "M_G_CPU0_SB_CB<1>")
	)
	(segment
		(start 430.906428 -232.434638)
		(end 430.09185 -232.434638)
		(width 0.18288)
		(layer "In4.Cu")
		(net "M_G_CPU0_SB_CB<1>")
	)
	(segment
		(start 402.527262 -234.54868)
		(end 402.527262 -234.375706)
		(width 0.18288)
		(layer "In4.Cu")
		(net "M_G_CPU0_SB_CB<1>")
	)
	(segment
		(start 430.09185 -232.434638)
		(end 429.93183 -232.594658)
		(width 0.18288)
		(layer "In4.Cu")
		(net "M_G_CPU0_SB_CB<1>")
	)
	(arc
		(start 381.383032 -240.342674)
		(mid 381.199078 -240.292579)
		(end 381.014224 -240.339372)
		(width 0.088646)
		(layer "In4.Cu")
		(net "M_G_CPU0_SB_CB<1>")
	)
	(arc
		(start 387.021832 -240.342928)
		(mid 386.834634 -240.292785)
		(end 386.647436 -240.342928)
		(width 0.088646)
		(layer "In4.Cu")
		(net "M_G_CPU0_SB_CB<1>")
	)
	(arc
		(start 382.88341 -240.345468)
		(mid 382.602775 -240.418636)
		(end 382.322832 -240.342928)
		(width 0.088646)
		(layer "In4.Cu")
		(net "M_G_CPU0_SB_CB<1>")
	)
	(arc
		(start 379.88113 -240.673636)
		(mid 379.803875 -240.952582)
		(end 379.598682 -241.156744)
		(width 0.088646)
		(layer "In4.Cu")
		(net "M_G_CPU0_SB_CB<1>")
	)
	(arc
		(start 386.082032 -240.342928)
		(mid 385.894834 -240.292785)
		(end 385.707636 -240.342928)
		(width 0.088646)
		(layer "In4.Cu")
		(net "M_G_CPU0_SB_CB<1>")
	)
	(arc
		(start 384.767836 -240.342928)
		(mid 384.493607 -240.418853)
		(end 384.217164 -240.351564)
		(width 0.088646)
		(layer "In4.Cu")
		(net "M_G_CPU0_SB_CB<1>")
	)
	(arc
		(start 379.598682 -241.156744)
		(mid 379.319479 -241.232384)
		(end 379.039374 -241.160046)
		(width 0.088646)
		(layer "In4.Cu")
		(net "M_G_CPU0_SB_CB<1>")
	)
	(arc
		(start 378.929646 -241.09553)
		(mid 378.639622 -240.899036)
		(end 378.376688 -240.66754)
		(width 0.088646)
		(layer "In4.Cu")
		(net "M_G_CPU0_SB_CB<1>")
	)
	(arc
		(start 385.707636 -240.342928)
		(mid 385.433407 -240.418853)
		(end 385.156964 -240.351564)
		(width 0.088646)
		(layer "In4.Cu")
		(net "M_G_CPU0_SB_CB<1>")
	)
	(arc
		(start 383.262632 -240.342674)
		(mid 383.078678 -240.292579)
		(end 382.893824 -240.339372)
		(width 0.088646)
		(layer "In4.Cu")
		(net "M_G_CPU0_SB_CB<1>")
	)
	(arc
		(start 380.063502 -240.345722)
		(mid 379.929886 -240.482442)
		(end 379.88113 -240.667286)
		(width 0.088646)
		(layer "In4.Cu")
		(net "M_G_CPU0_SB_CB<1>")
	)
	(arc
		(start 380.443232 -240.342674)
		(mid 380.259278 -240.292579)
		(end 380.074424 -240.339372)
		(width 0.088646)
		(layer "In4.Cu")
		(net "M_G_CPU0_SB_CB<1>")
	)
	(arc
		(start 383.824226 -240.34496)
		(mid 383.543113 -240.418537)
		(end 383.262632 -240.342674)
		(width 0.088646)
		(layer "In4.Cu")
		(net "M_G_CPU0_SB_CB<1>")
	)
	(arc
		(start 381.00254 -240.34623)
		(mid 380.722405 -240.418546)
		(end 380.443232 -240.342674)
		(width 0.088646)
		(layer "In4.Cu")
		(net "M_G_CPU0_SB_CB<1>")
	)
	(arc
		(start 387.359906 -240.41608)
		(mid 387.193422 -240.407928)
		(end 387.036564 -240.351564)
		(width 0.088646)
		(layer "In4.Cu")
		(net "M_G_CPU0_SB_CB<1>")
	)
	(arc
		(start 382.322832 -240.342928)
		(mid 382.135524 -240.292785)
		(end 381.948182 -240.342928)
		(width 0.088646)
		(layer "In4.Cu")
		(net "M_G_CPU0_SB_CB<1>")
	)
	(arc
		(start 384.202432 -240.342928)
		(mid 384.015124 -240.292785)
		(end 383.827782 -240.342928)
		(width 0.088646)
		(layer "In4.Cu")
		(net "M_G_CPU0_SB_CB<1>")
	)
	(arc
		(start 386.647436 -240.342928)
		(mid 386.373207 -240.418853)
		(end 386.096764 -240.351564)
		(width 0.088646)
		(layer "In4.Cu")
		(net "M_G_CPU0_SB_CB<1>")
	)
	(arc
		(start 381.944626 -240.34496)
		(mid 381.663513 -240.418537)
		(end 381.383032 -240.342674)
		(width 0.088646)
		(layer "In4.Cu")
		(net "M_G_CPU0_SB_CB<1>")
	)
	(arc
		(start 385.142232 -240.342928)
		(mid 384.955034 -240.292785)
		(end 384.767836 -240.342928)
		(width 0.088646)
		(layer "In4.Cu")
		(net "M_G_CPU0_SB_CB<1>")
	)
	(segment
		(start 438.697878 -235.815378)
		(end 438.449212 -235.566712)
		(width 0.20066)
		(layer "F.Cu")
		(net "M_G_CPU0_SB_CB<0>")
	)
	(segment
		(start 439.726324 -235.14177)
		(end 439.479182 -235.14177)
		(width 0.20066)
		(layer "F.Cu")
		(net "M_G_CPU0_SB_CB<0>")
	)
	(segment
		(start 442.181234 -235.14177)
		(end 439.87085 -235.14177)
		(width 0.1016)
		(layer "F.Cu")
		(net "M_G_CPU0_SB_CB<0>")
	)
	(segment
		(start 442.21781 -235.14177)
		(end 442.181234 -235.14177)
		(width 0.101854)
		(layer "F.Cu")
		(net "M_G_CPU0_SB_CB<0>")
	)
	(segment
		(start 439.173112 -235.815378)
		(end 438.697878 -235.815378)
		(width 0.20066)
		(layer "F.Cu")
		(net "M_G_CPU0_SB_CB<0>")
	)
	(segment
		(start 436.928514 -235.566712)
		(end 435.823614 -235.566712)
		(width 0.20066)
		(layer "F.Cu")
		(net "M_G_CPU0_SB_CB<0>")
	)
	(segment
		(start 439.479182 -235.14177)
		(end 439.361072 -235.25988)
		(width 0.20066)
		(layer "F.Cu")
		(net "M_G_CPU0_SB_CB<0>")
	)
	(segment
		(start 439.87085 -235.14177)
		(end 439.726324 -235.14177)
		(width 0.101854)
		(layer "F.Cu")
		(net "M_G_CPU0_SB_CB<0>")
	)
	(segment
		(start 377.906534 -242.017042)
		(end 377.90628 -242.016788)
		(width 0.20066)
		(layer "F.Cu")
		(net "M_G_CPU0_SB_CB<0>")
	)
	(segment
		(start 444.472314 -235.566712)
		(end 444.47206 -235.566966)
		(width 0.20066)
		(layer "F.Cu")
		(net "M_G_CPU0_SB_CB<0>")
	)
	(segment
		(start 439.361072 -235.25988)
		(end 439.361072 -235.627418)
		(width 0.20066)
		(layer "F.Cu")
		(net "M_G_CPU0_SB_CB<0>")
	)
	(segment
		(start 444.47206 -235.566966)
		(end 442.84138 -235.566966)
		(width 0.20066)
		(layer "F.Cu")
		(net "M_G_CPU0_SB_CB<0>")
	)
	(segment
		(start 442.416184 -235.14177)
		(end 442.21781 -235.14177)
		(width 0.20066)
		(layer "F.Cu")
		(net "M_G_CPU0_SB_CB<0>")
	)
	(segment
		(start 377.90628 -242.016788)
		(end 377.90628 -241.481102)
		(width 0.20066)
		(layer "F.Cu")
		(net "M_G_CPU0_SB_CB<0>")
	)
	(segment
		(start 439.361072 -235.627418)
		(end 439.173112 -235.815378)
		(width 0.20066)
		(layer "F.Cu")
		(net "M_G_CPU0_SB_CB<0>")
	)
	(segment
		(start 442.84138 -235.566966)
		(end 442.416184 -235.14177)
		(width 0.20066)
		(layer "F.Cu")
		(net "M_G_CPU0_SB_CB<0>")
	)
	(segment
		(start 438.449212 -235.566712)
		(end 436.928514 -235.566712)
		(width 0.20066)
		(layer "F.Cu")
		(net "M_G_CPU0_SB_CB<0>")
	)
	(segment
		(start 411.19679 -235.889546)
		(end 411.19679 -235.555536)
		(width 0.18288)
		(layer "In4.Cu")
		(net "M_G_CPU0_SB_CB<0>")
	)
	(segment
		(start 414.48609 -236.395768)
		(end 414.15843 -236.395768)
		(width 0.18288)
		(layer "In4.Cu")
		(net "M_G_CPU0_SB_CB<0>")
	)
	(segment
		(start 414.66897 -235.865924)
		(end 414.66897 -236.212888)
		(width 0.18288)
		(layer "In4.Cu")
		(net "M_G_CPU0_SB_CB<0>")
	)
	(segment
		(start 417.870132 -235.793534)
		(end 417.291012 -236.372654)
		(width 0.18288)
		(layer "In4.Cu")
		(net "M_G_CPU0_SB_CB<0>")
	)
	(segment
		(start 427.399196 -234.292394)
		(end 427.216316 -234.475274)
		(width 0.18288)
		(layer "In4.Cu")
		(net "M_G_CPU0_SB_CB<0>")
	)
	(segment
		(start 413.97555 -235.865924)
		(end 413.79267 -235.683044)
		(width 0.18288)
		(layer "In4.Cu")
		(net "M_G_CPU0_SB_CB<0>")
	)
	(segment
		(start 382.792732 -241.156744)
		(end 382.788922 -241.154458)
		(width 0.088646)
		(layer "In4.Cu")
		(net "M_G_CPU0_SB_CB<0>")
	)
	(segment
		(start 417.291012 -236.372654)
		(end 416.781996 -236.372654)
		(width 0.18288)
		(layer "In4.Cu")
		(net "M_G_CPU0_SB_CB<0>")
	)
	(segment
		(start 427.216316 -234.475274)
		(end 427.216316 -234.94746)
		(width 0.18288)
		(layer "In4.Cu")
		(net "M_G_CPU0_SB_CB<0>")
	)
	(segment
		(start 429.750728 -234.243626)
		(end 429.533812 -234.460542)
		(width 0.18288)
		(layer "In4.Cu")
		(net "M_G_CPU0_SB_CB<0>")
	)
	(segment
		(start 377.906534 -241.481102)
		(end 377.90628 -241.481102)
		(width 0.088646)
		(layer "In4.Cu")
		(net "M_G_CPU0_SB_CB<0>")
	)
	(segment
		(start 418.314886 -235.793534)
		(end 417.870132 -235.793534)
		(width 0.18288)
		(layer "In4.Cu")
		(net "M_G_CPU0_SB_CB<0>")
	)
	(segment
		(start 408.853894 -236.072426)
		(end 408.650694 -235.869226)
		(width 0.18288)
		(layer "In4.Cu")
		(net "M_G_CPU0_SB_CB<0>")
	)
	(segment
		(start 400.94154 -235.869226)
		(end 398.534382 -238.276384)
		(width 0.18288)
		(layer "In4.Cu")
		(net "M_G_CPU0_SB_CB<0>")
	)
	(segment
		(start 426.522896 -234.475274)
		(end 426.340016 -234.292394)
		(width 0.18288)
		(layer "In4.Cu")
		(net "M_G_CPU0_SB_CB<0>")
	)
	(segment
		(start 418.966142 -235.142278)
		(end 418.314886 -235.793534)
		(width 0.18288)
		(layer "In4.Cu")
		(net "M_G_CPU0_SB_CB<0>")
	)
	(segment
		(start 434.061616 -235.325412)
		(end 432.77028 -235.325412)
		(width 0.18288)
		(layer "In4.Cu")
		(net "M_G_CPU0_SB_CB<0>")
	)
	(segment
		(start 391.521188 -240.822988)
		(end 388.231888 -240.822988)
		(width 0.18288)
		(layer "In4.Cu")
		(net "M_G_CPU0_SB_CB<0>")
	)
	(segment
		(start 410.32049 -236.072426)
		(end 408.853894 -236.072426)
		(width 0.18288)
		(layer "In4.Cu")
		(net "M_G_CPU0_SB_CB<0>")
	)
	(segment
		(start 408.650694 -235.869226)
		(end 400.94154 -235.869226)
		(width 0.18288)
		(layer "In4.Cu")
		(net "M_G_CPU0_SB_CB<0>")
	)
	(segment
		(start 379.040898 -241.801396)
		(end 379.033532 -241.80546)
		(width 0.088646)
		(layer "In4.Cu")
		(net "M_G_CPU0_SB_CB<0>")
	)
	(segment
		(start 421.607742 -235.142278)
		(end 418.966142 -235.142278)
		(width 0.18288)
		(layer "In4.Cu")
		(net "M_G_CPU0_SB_CB<0>")
	)
	(segment
		(start 434.305202 -235.081826)
		(end 434.061616 -235.325412)
		(width 0.18288)
		(layer "In4.Cu")
		(net "M_G_CPU0_SB_CB<0>")
	)
	(segment
		(start 412.333694 -236.072426)
		(end 411.37967 -236.072426)
		(width 0.18288)
		(layer "In4.Cu")
		(net "M_G_CPU0_SB_CB<0>")
	)
	(segment
		(start 411.19679 -235.555536)
		(end 411.01391 -235.372656)
		(width 0.18288)
		(layer "In4.Cu")
		(net "M_G_CPU0_SB_CB<0>")
	)
	(segment
		(start 435.823614 -235.566712)
		(end 435.798214 -235.566712)
		(width 0.18288)
		(layer "In4.Cu")
		(net "M_G_CPU0_SB_CB<0>")
	)
	(segment
		(start 387.1849 -240.822988)
		(end 386.877306 -240.950496)
		(width 0.088646)
		(layer "In4.Cu")
		(net "M_G_CPU0_SB_CB<0>")
	)
	(segment
		(start 431.712878 -235.107226)
		(end 430.849278 -234.243626)
		(width 0.18288)
		(layer "In4.Cu")
		(net "M_G_CPU0_SB_CB<0>")
	)
	(segment
		(start 388.231888 -240.822988)
		(end 387.1849 -240.822988)
		(width 0.088646)
		(layer "In4.Cu")
		(net "M_G_CPU0_SB_CB<0>")
	)
	(segment
		(start 380.232412 -241.537236)
		(end 380.198376 -241.619786)
		(width 0.088646)
		(layer "In4.Cu")
		(net "M_G_CPU0_SB_CB<0>")
	)
	(segment
		(start 381.852932 -241.156744)
		(end 381.848614 -241.154204)
		(width 0.088646)
		(layer "In4.Cu")
		(net "M_G_CPU0_SB_CB<0>")
	)
	(segment
		(start 426.522896 -234.94746)
		(end 426.522896 -234.475274)
		(width 0.18288)
		(layer "In4.Cu")
		(net "M_G_CPU0_SB_CB<0>")
	)
	(segment
		(start 394.067792 -238.276384)
		(end 391.521188 -240.822988)
		(width 0.18288)
		(layer "In4.Cu")
		(net "M_G_CPU0_SB_CB<0>")
	)
	(segment
		(start 429.533812 -234.460542)
		(end 428.922688 -234.460542)
		(width 0.18288)
		(layer "In4.Cu")
		(net "M_G_CPU0_SB_CB<0>")
	)
	(segment
		(start 430.849278 -234.243626)
		(end 429.750728 -234.243626)
		(width 0.18288)
		(layer "In4.Cu")
		(net "M_G_CPU0_SB_CB<0>")
	)
	(segment
		(start 386.721604 -241.106198)
		(end 386.364734 -241.106198)
		(width 0.088646)
		(layer "In4.Cu")
		(net "M_G_CPU0_SB_CB<0>")
	)
	(segment
		(start 398.534382 -238.276384)
		(end 394.067792 -238.276384)
		(width 0.18288)
		(layer "In4.Cu")
		(net "M_G_CPU0_SB_CB<0>")
	)
	(segment
		(start 413.97555 -236.212888)
		(end 413.97555 -235.865924)
		(width 0.18288)
		(layer "In4.Cu")
		(net "M_G_CPU0_SB_CB<0>")
	)
	(segment
		(start 413.79267 -235.683044)
		(end 412.723076 -235.683044)
		(width 0.18288)
		(layer "In4.Cu")
		(net "M_G_CPU0_SB_CB<0>")
	)
	(segment
		(start 378.658882 -241.80546)
		(end 378.26188 -241.576352)
		(width 0.088646)
		(layer "In4.Cu")
		(net "M_G_CPU0_SB_CB<0>")
	)
	(segment
		(start 386.877306 -240.950496)
		(end 386.721604 -241.106198)
		(width 0.088646)
		(layer "In4.Cu")
		(net "M_G_CPU0_SB_CB<0>")
	)
	(segment
		(start 432.77028 -235.325412)
		(end 432.552094 -235.107226)
		(width 0.18288)
		(layer "In4.Cu")
		(net "M_G_CPU0_SB_CB<0>")
	)
	(segment
		(start 411.37967 -236.072426)
		(end 411.19679 -235.889546)
		(width 0.18288)
		(layer "In4.Cu")
		(net "M_G_CPU0_SB_CB<0>")
	)
	(segment
		(start 414.15843 -236.395768)
		(end 413.97555 -236.212888)
		(width 0.18288)
		(layer "In4.Cu")
		(net "M_G_CPU0_SB_CB<0>")
	)
	(segment
		(start 414.85185 -235.683044)
		(end 414.66897 -235.865924)
		(width 0.18288)
		(layer "In4.Cu")
		(net "M_G_CPU0_SB_CB<0>")
	)
	(segment
		(start 410.50337 -235.555536)
		(end 410.50337 -235.889546)
		(width 0.18288)
		(layer "In4.Cu")
		(net "M_G_CPU0_SB_CB<0>")
	)
	(segment
		(start 380.01321 -241.782346)
		(end 379.973332 -241.80546)
		(width 0.088646)
		(layer "In4.Cu")
		(net "M_G_CPU0_SB_CB<0>")
	)
	(segment
		(start 426.705776 -235.13034)
		(end 426.522896 -234.94746)
		(width 0.18288)
		(layer "In4.Cu")
		(net "M_G_CPU0_SB_CB<0>")
	)
	(segment
		(start 410.50337 -235.889546)
		(end 410.32049 -236.072426)
		(width 0.18288)
		(layer "In4.Cu")
		(net "M_G_CPU0_SB_CB<0>")
	)
	(segment
		(start 416.092386 -235.683044)
		(end 414.85185 -235.683044)
		(width 0.18288)
		(layer "In4.Cu")
		(net "M_G_CPU0_SB_CB<0>")
	)
	(segment
		(start 422.582594 -234.167426)
		(end 421.607742 -235.142278)
		(width 0.18288)
		(layer "In4.Cu")
		(net "M_G_CPU0_SB_CB<0>")
	)
	(segment
		(start 428.922688 -234.460542)
		(end 428.75454 -234.292394)
		(width 0.18288)
		(layer "In4.Cu")
		(net "M_G_CPU0_SB_CB<0>")
	)
	(segment
		(start 383.732532 -241.156744)
		(end 383.728214 -241.154204)
		(width 0.088646)
		(layer "In4.Cu")
		(net "M_G_CPU0_SB_CB<0>")
	)
	(segment
		(start 412.723076 -235.683044)
		(end 412.333694 -236.072426)
		(width 0.18288)
		(layer "In4.Cu")
		(net "M_G_CPU0_SB_CB<0>")
	)
	(segment
		(start 380.454662 -241.221006)
		(end 380.335536 -241.340132)
		(width 0.088646)
		(layer "In4.Cu")
		(net "M_G_CPU0_SB_CB<0>")
	)
	(segment
		(start 379.033532 -241.80546)
		(end 379.02896 -241.808254)
		(width 0.088646)
		(layer "In4.Cu")
		(net "M_G_CPU0_SB_CB<0>")
	)
	(segment
		(start 432.552094 -235.107226)
		(end 431.712878 -235.107226)
		(width 0.18288)
		(layer "In4.Cu")
		(net "M_G_CPU0_SB_CB<0>")
	)
	(segment
		(start 382.798574 -241.160046)
		(end 382.792732 -241.156744)
		(width 0.088646)
		(layer "In4.Cu")
		(net "M_G_CPU0_SB_CB<0>")
	)
	(segment
		(start 410.68625 -235.372656)
		(end 410.50337 -235.555536)
		(width 0.18288)
		(layer "In4.Cu")
		(net "M_G_CPU0_SB_CB<0>")
	)
	(segment
		(start 428.75454 -234.292394)
		(end 427.399196 -234.292394)
		(width 0.18288)
		(layer "In4.Cu")
		(net "M_G_CPU0_SB_CB<0>")
	)
	(segment
		(start 416.781996 -236.372654)
		(end 416.092386 -235.683044)
		(width 0.18288)
		(layer "In4.Cu")
		(net "M_G_CPU0_SB_CB<0>")
	)
	(segment
		(start 414.66897 -236.212888)
		(end 414.48609 -236.395768)
		(width 0.18288)
		(layer "In4.Cu")
		(net "M_G_CPU0_SB_CB<0>")
	)
	(segment
		(start 435.313328 -235.081826)
		(end 434.305202 -235.081826)
		(width 0.18288)
		(layer "In4.Cu")
		(net "M_G_CPU0_SB_CB<0>")
	)
	(segment
		(start 427.033436 -235.13034)
		(end 426.705776 -235.13034)
		(width 0.18288)
		(layer "In4.Cu")
		(net "M_G_CPU0_SB_CB<0>")
	)
	(segment
		(start 423.687494 -234.167426)
		(end 422.582594 -234.167426)
		(width 0.18288)
		(layer "In4.Cu")
		(net "M_G_CPU0_SB_CB<0>")
	)
	(segment
		(start 427.216316 -234.94746)
		(end 427.033436 -235.13034)
		(width 0.18288)
		(layer "In4.Cu")
		(net "M_G_CPU0_SB_CB<0>")
	)
	(segment
		(start 435.798214 -235.566712)
		(end 435.313328 -235.081826)
		(width 0.18288)
		(layer "In4.Cu")
		(net "M_G_CPU0_SB_CB<0>")
	)
	(segment
		(start 411.01391 -235.372656)
		(end 410.68625 -235.372656)
		(width 0.18288)
		(layer "In4.Cu")
		(net "M_G_CPU0_SB_CB<0>")
	)
	(segment
		(start 380.918974 -241.160046)
		(end 380.90729 -241.153442)
		(width 0.088646)
		(layer "In4.Cu")
		(net "M_G_CPU0_SB_CB<0>")
	)
	(segment
		(start 426.340016 -234.292394)
		(end 423.812462 -234.292394)
		(width 0.18288)
		(layer "In4.Cu")
		(net "M_G_CPU0_SB_CB<0>")
	)
	(segment
		(start 379.973332 -241.80546)
		(end 379.96876 -241.808254)
		(width 0.088646)
		(layer "In4.Cu")
		(net "M_G_CPU0_SB_CB<0>")
	)
	(segment
		(start 423.812462 -234.292394)
		(end 423.687494 -234.167426)
		(width 0.18288)
		(layer "In4.Cu")
		(net "M_G_CPU0_SB_CB<0>")
	)
	(arc
		(start 379.606048 -241.809778)
		(mid 379.596903 -241.80495)
		(end 379.587506 -241.800634)
		(width 0.088646)
		(layer "In4.Cu")
		(net "M_G_CPU0_SB_CB<0>")
	)
	(arc
		(start 385.237736 -241.156744)
		(mid 384.955034 -241.23252)
		(end 384.672332 -241.156744)
		(width 0.088646)
		(layer "In4.Cu")
		(net "M_G_CPU0_SB_CB<0>")
	)
	(arc
		(start 380.335536 -241.340132)
		(mid 380.293386 -241.392978)
		(end 380.264162 -241.453924)
		(width 0.088646)
		(layer "In4.Cu")
		(net "M_G_CPU0_SB_CB<0>")
	)
	(arc
		(start 381.848614 -241.154204)
		(mid 381.663119 -241.106535)
		(end 381.478282 -241.156744)
		(width 0.088646)
		(layer "In4.Cu")
		(net "M_G_CPU0_SB_CB<0>")
	)
	(arc
		(start 385.612132 -241.156744)
		(mid 385.424934 -241.106601)
		(end 385.237736 -241.156744)
		(width 0.088646)
		(layer "In4.Cu")
		(net "M_G_CPU0_SB_CB<0>")
	)
	(arc
		(start 382.788922 -241.154458)
		(mid 382.603203 -241.106506)
		(end 382.418082 -241.156744)
		(width 0.088646)
		(layer "In4.Cu")
		(net "M_G_CPU0_SB_CB<0>")
	)
	(arc
		(start 381.478282 -241.156744)
		(mid 381.199079 -241.232384)
		(end 380.918974 -241.160046)
		(width 0.088646)
		(layer "In4.Cu")
		(net "M_G_CPU0_SB_CB<0>")
	)
	(arc
		(start 380.14529 -241.69116)
		(mid 380.081088 -241.739416)
		(end 380.01321 -241.782346)
		(width 0.088646)
		(layer "In4.Cu")
		(net "M_G_CPU0_SB_CB<0>")
	)
	(arc
		(start 379.96876 -241.808254)
		(mid 379.787614 -241.855773)
		(end 379.606048 -241.809778)
		(width 0.088646)
		(layer "In4.Cu")
		(net "M_G_CPU0_SB_CB<0>")
	)
	(arc
		(start 383.728214 -241.154204)
		(mid 383.542719 -241.106535)
		(end 383.357882 -241.156744)
		(width 0.088646)
		(layer "In4.Cu")
		(net "M_G_CPU0_SB_CB<0>")
	)
	(arc
		(start 379.587506 -241.800634)
		(mid 379.314134 -241.746742)
		(end 379.040898 -241.801396)
		(width 0.088646)
		(layer "In4.Cu")
		(net "M_G_CPU0_SB_CB<0>")
	)
	(arc
		(start 380.264162 -241.453924)
		(mid 380.248892 -241.49581)
		(end 380.232412 -241.537236)
		(width 0.088646)
		(layer "In4.Cu")
		(net "M_G_CPU0_SB_CB<0>")
	)
	(arc
		(start 386.177536 -241.156744)
		(mid 385.894834 -241.23252)
		(end 385.612132 -241.156744)
		(width 0.088646)
		(layer "In4.Cu")
		(net "M_G_CPU0_SB_CB<0>")
	)
	(arc
		(start 378.26188 -241.576352)
		(mid 378.090474 -241.505339)
		(end 377.906534 -241.481102)
		(width 0.088646)
		(layer "In4.Cu")
		(net "M_G_CPU0_SB_CB<0>")
	)
	(arc
		(start 386.364734 -241.106198)
		(mid 386.267811 -241.119156)
		(end 386.177536 -241.156744)
		(width 0.088646)
		(layer "In4.Cu")
		(net "M_G_CPU0_SB_CB<0>")
	)
	(arc
		(start 382.418082 -241.156744)
		(mid 382.135524 -241.232393)
		(end 381.852932 -241.156744)
		(width 0.088646)
		(layer "In4.Cu")
		(net "M_G_CPU0_SB_CB<0>")
	)
	(arc
		(start 384.297936 -241.156744)
		(mid 384.015234 -241.23252)
		(end 383.732532 -241.156744)
		(width 0.088646)
		(layer "In4.Cu")
		(net "M_G_CPU0_SB_CB<0>")
	)
	(arc
		(start 379.02896 -241.808254)
		(mid 378.843546 -241.855766)
		(end 378.658882 -241.80546)
		(width 0.088646)
		(layer "In4.Cu")
		(net "M_G_CPU0_SB_CB<0>")
	)
	(arc
		(start 380.90729 -241.153442)
		(mid 380.722435 -241.106492)
		(end 380.538482 -241.156744)
		(width 0.088646)
		(layer "In4.Cu")
		(net "M_G_CPU0_SB_CB<0>")
	)
	(arc
		(start 383.357882 -241.156744)
		(mid 383.078679 -241.232384)
		(end 382.798574 -241.160046)
		(width 0.088646)
		(layer "In4.Cu")
		(net "M_G_CPU0_SB_CB<0>")
	)
	(arc
		(start 384.672332 -241.156744)
		(mid 384.485134 -241.106601)
		(end 384.297936 -241.156744)
		(width 0.088646)
		(layer "In4.Cu")
		(net "M_G_CPU0_SB_CB<0>")
	)
	(arc
		(start 380.538482 -241.156744)
		(mid 380.49446 -241.186121)
		(end 380.454662 -241.221006)
		(width 0.088646)
		(layer "In4.Cu")
		(net "M_G_CPU0_SB_CB<0>")
	)
	(arc
		(start 380.198376 -241.619786)
		(mid 380.176267 -241.658772)
		(end 380.14529 -241.69116)
		(width 0.088646)
		(layer "In4.Cu")
		(net "M_G_CPU0_SB_CB<0>")
	)
	(segment
		(start 442.455046 -247.904)
		(end 442.892688 -247.466358)
		(width 0.20066)
		(layer "F.Cu")
		(net "M_G_CPU0_SB_CA<6>")
	)
	(segment
		(start 435.823614 -247.466612)
		(end 436.928514 -247.466612)
		(width 0.20066)
		(layer "F.Cu")
		(net "M_G_CPU0_SB_CA<6>")
	)
	(segment
		(start 438.813702 -246.972328)
		(end 439.732928 -247.891554)
		(width 0.20066)
		(layer "F.Cu")
		(net "M_G_CPU0_SB_CA<6>")
	)
	(segment
		(start 444.47206 -247.466358)
		(end 444.472314 -247.466612)
		(width 0.20066)
		(layer "F.Cu")
		(net "M_G_CPU0_SB_CA<6>")
	)
	(segment
		(start 438.488328 -246.972328)
		(end 438.813702 -246.972328)
		(width 0.20066)
		(layer "F.Cu")
		(net "M_G_CPU0_SB_CA<6>")
	)
	(segment
		(start 377.436634 -247.714008)
		(end 377.436634 -247.178322)
		(width 0.20066)
		(layer "F.Cu")
		(net "M_G_CPU0_SB_CA<6>")
	)
	(segment
		(start 442.026548 -247.891554)
		(end 442.038994 -247.904)
		(width 0.1016)
		(layer "F.Cu")
		(net "M_G_CPU0_SB_CA<6>")
	)
	(segment
		(start 437.994044 -247.466612)
		(end 438.488328 -246.972328)
		(width 0.20066)
		(layer "F.Cu")
		(net "M_G_CPU0_SB_CA<6>")
	)
	(segment
		(start 442.892688 -247.466358)
		(end 444.47206 -247.466358)
		(width 0.20066)
		(layer "F.Cu")
		(net "M_G_CPU0_SB_CA<6>")
	)
	(segment
		(start 436.928514 -247.466612)
		(end 437.994044 -247.466612)
		(width 0.20066)
		(layer "F.Cu")
		(net "M_G_CPU0_SB_CA<6>")
	)
	(segment
		(start 439.854086 -247.891554)
		(end 442.026548 -247.891554)
		(width 0.1016)
		(layer "F.Cu")
		(net "M_G_CPU0_SB_CA<6>")
	)
	(segment
		(start 377.43638 -247.714262)
		(end 377.436634 -247.714008)
		(width 0.20066)
		(layer "F.Cu")
		(net "M_G_CPU0_SB_CA<6>")
	)
	(segment
		(start 439.84037 -247.891554)
		(end 439.854086 -247.891554)
		(width 0.101854)
		(layer "F.Cu")
		(net "M_G_CPU0_SB_CA<6>")
	)
	(segment
		(start 439.732928 -247.891554)
		(end 439.84037 -247.891554)
		(width 0.20066)
		(layer "F.Cu")
		(net "M_G_CPU0_SB_CA<6>")
	)
	(segment
		(start 442.038994 -247.904)
		(end 442.455046 -247.904)
		(width 0.20066)
		(layer "F.Cu")
		(net "M_G_CPU0_SB_CA<6>")
	)
	(segment
		(start 389.371332 -247.844564)
		(end 385.766818 -247.844564)
		(width 0.18288)
		(layer "In4.Cu")
		(net "M_G_CPU0_SB_CA<6>")
	)
	(segment
		(start 435.823614 -247.736106)
		(end 435.656228 -247.903492)
		(width 0.18288)
		(layer "In4.Cu")
		(net "M_G_CPU0_SB_CA<6>")
	)
	(segment
		(start 385.372102 -247.844564)
		(end 385.318762 -247.791224)
		(width 0.088646)
		(layer "In4.Cu")
		(net "M_G_CPU0_SB_CA<6>")
	)
	(segment
		(start 428.9425 -248.22023)
		(end 428.9425 -247.773444)
		(width 0.18288)
		(layer "In4.Cu")
		(net "M_G_CPU0_SB_CA<6>")
	)
	(segment
		(start 381.867918 -247.676416)
		(end 381.853186 -247.66778)
		(width 0.088646)
		(layer "In4.Cu")
		(net "M_G_CPU0_SB_CA<6>")
	)
	(segment
		(start 380.538736 -247.66778)
		(end 380.528322 -247.673876)
		(width 0.088646)
		(layer "In4.Cu")
		(net "M_G_CPU0_SB_CA<6>")
	)
	(segment
		(start 424.48861 -247.89257)
		(end 424.266614 -248.114566)
		(width 0.18288)
		(layer "In4.Cu")
		(net "M_G_CPU0_SB_CA<6>")
	)
	(segment
		(start 424.266614 -248.114566)
		(end 423.786554 -248.114566)
		(width 0.18288)
		(layer "In4.Cu")
		(net "M_G_CPU0_SB_CA<6>")
	)
	(segment
		(start 434.749194 -248.086626)
		(end 434.749194 -248.50598)
		(width 0.18288)
		(layer "In4.Cu")
		(net "M_G_CPU0_SB_CA<6>")
	)
	(segment
		(start 426.427138 -247.929146)
		(end 426.427138 -247.575832)
		(width 0.18288)
		(layer "In4.Cu")
		(net "M_G_CPU0_SB_CA<6>")
	)
	(segment
		(start 379.043946 -247.673876)
		(end 379.033532 -247.66778)
		(width 0.088646)
		(layer "In4.Cu")
		(net "M_G_CPU0_SB_CA<6>")
	)
	(segment
		(start 429.8188 -247.590564)
		(end 429.63592 -247.773444)
		(width 0.18288)
		(layer "In4.Cu")
		(net "M_G_CPU0_SB_CA<6>")
	)
	(segment
		(start 434.749194 -248.50598)
		(end 434.607462 -248.647712)
		(width 0.18288)
		(layer "In4.Cu")
		(net "M_G_CPU0_SB_CA<6>")
	)
	(segment
		(start 382.8034 -247.673876)
		(end 382.792986 -247.66778)
		(width 0.088646)
		(layer "In4.Cu")
		(net "M_G_CPU0_SB_CA<6>")
	)
	(segment
		(start 402.77796 -246.593614)
		(end 396.460218 -246.593614)
		(width 0.18288)
		(layer "In4.Cu")
		(net "M_G_CPU0_SB_CA<6>")
	)
	(segment
		(start 433.403502 -247.41378)
		(end 433.243482 -247.5738)
		(width 0.18288)
		(layer "In4.Cu")
		(net "M_G_CPU0_SB_CA<6>")
	)
	(segment
		(start 426.610018 -248.112026)
		(end 426.427138 -247.929146)
		(width 0.18288)
		(layer "In4.Cu")
		(net "M_G_CPU0_SB_CA<6>")
	)
	(segment
		(start 433.130198 -248.188226)
		(end 431.015902 -248.188226)
		(width 0.18288)
		(layer "In4.Cu")
		(net "M_G_CPU0_SB_CA<6>")
	)
	(segment
		(start 405.913844 -247.89257)
		(end 402.77796 -246.593614)
		(width 0.18288)
		(layer "In4.Cu")
		(net "M_G_CPU0_SB_CA<6>")
	)
	(segment
		(start 390.547352 -246.668544)
		(end 389.371332 -247.844564)
		(width 0.18288)
		(layer "In4.Cu")
		(net "M_G_CPU0_SB_CA<6>")
	)
	(segment
		(start 434.012594 -248.469404)
		(end 434.012594 -247.5738)
		(width 0.18288)
		(layer "In4.Cu")
		(net "M_G_CPU0_SB_CA<6>")
	)
	(segment
		(start 434.607462 -248.647712)
		(end 434.190902 -248.647712)
		(width 0.18288)
		(layer "In4.Cu")
		(net "M_G_CPU0_SB_CA<6>")
	)
	(segment
		(start 429.45304 -248.40311)
		(end 429.12538 -248.40311)
		(width 0.18288)
		(layer "In4.Cu")
		(net "M_G_CPU0_SB_CA<6>")
	)
	(segment
		(start 434.012594 -247.5738)
		(end 433.852574 -247.41378)
		(width 0.18288)
		(layer "In4.Cu")
		(net "M_G_CPU0_SB_CA<6>")
	)
	(segment
		(start 434.190902 -248.647712)
		(end 434.012594 -248.469404)
		(width 0.18288)
		(layer "In4.Cu")
		(net "M_G_CPU0_SB_CA<6>")
	)
	(segment
		(start 433.243482 -248.074942)
		(end 433.130198 -248.188226)
		(width 0.18288)
		(layer "In4.Cu")
		(net "M_G_CPU0_SB_CA<6>")
	)
	(segment
		(start 427.044866 -248.112026)
		(end 426.610018 -248.112026)
		(width 0.18288)
		(layer "In4.Cu")
		(net "M_G_CPU0_SB_CA<6>")
	)
	(segment
		(start 426.244258 -247.392952)
		(end 425.916598 -247.392952)
		(width 0.18288)
		(layer "In4.Cu")
		(net "M_G_CPU0_SB_CA<6>")
	)
	(segment
		(start 396.460218 -246.593614)
		(end 396.385288 -246.668544)
		(width 0.18288)
		(layer "In4.Cu")
		(net "M_G_CPU0_SB_CA<6>")
	)
	(segment
		(start 428.9425 -247.773444)
		(end 428.75962 -247.590564)
		(width 0.18288)
		(layer "In4.Cu")
		(net "M_G_CPU0_SB_CA<6>")
	)
	(segment
		(start 383.81051 -247.727216)
		(end 383.81051 -247.726962)
		(width 0.088646)
		(layer "In4.Cu")
		(net "M_G_CPU0_SB_CA<6>")
	)
	(segment
		(start 425.106338 -247.89257)
		(end 424.48861 -247.89257)
		(width 0.18288)
		(layer "In4.Cu")
		(net "M_G_CPU0_SB_CA<6>")
	)
	(segment
		(start 421.236394 -247.731026)
		(end 421.07485 -247.89257)
		(width 0.18288)
		(layer "In4.Cu")
		(net "M_G_CPU0_SB_CA<6>")
	)
	(segment
		(start 380.927864 -247.676416)
		(end 380.913132 -247.66778)
		(width 0.088646)
		(layer "In4.Cu")
		(net "M_G_CPU0_SB_CA<6>")
	)
	(segment
		(start 434.932328 -247.903492)
		(end 434.749194 -248.086626)
		(width 0.18288)
		(layer "In4.Cu")
		(net "M_G_CPU0_SB_CA<6>")
	)
	(segment
		(start 396.385288 -246.668544)
		(end 390.547352 -246.668544)
		(width 0.18288)
		(layer "In4.Cu")
		(net "M_G_CPU0_SB_CA<6>")
	)
	(segment
		(start 385.318762 -247.791224)
		(end 383.890012 -247.791224)
		(width 0.088646)
		(layer "In4.Cu")
		(net "M_G_CPU0_SB_CA<6>")
	)
	(segment
		(start 428.75962 -247.590564)
		(end 427.566328 -247.590564)
		(width 0.18288)
		(layer "In4.Cu")
		(net "M_G_CPU0_SB_CA<6>")
	)
	(segment
		(start 381.853186 -247.66778)
		(end 381.844804 -247.662954)
		(width 0.088646)
		(layer "In4.Cu")
		(net "M_G_CPU0_SB_CA<6>")
	)
	(segment
		(start 385.766818 -247.844564)
		(end 385.372102 -247.844564)
		(width 0.088646)
		(layer "In4.Cu")
		(net "M_G_CPU0_SB_CA<6>")
	)
	(segment
		(start 425.733718 -247.929146)
		(end 425.550838 -248.112026)
		(width 0.18288)
		(layer "In4.Cu")
		(net "M_G_CPU0_SB_CA<6>")
	)
	(segment
		(start 425.916598 -247.392952)
		(end 425.733718 -247.575832)
		(width 0.18288)
		(layer "In4.Cu")
		(net "M_G_CPU0_SB_CA<6>")
	)
	(segment
		(start 378.659136 -247.66778)
		(end 378.648722 -247.673876)
		(width 0.088646)
		(layer "In4.Cu")
		(net "M_G_CPU0_SB_CA<6>")
	)
	(segment
		(start 425.325794 -248.112026)
		(end 425.106338 -247.89257)
		(width 0.18288)
		(layer "In4.Cu")
		(net "M_G_CPU0_SB_CA<6>")
	)
	(segment
		(start 431.015902 -248.188226)
		(end 430.41824 -247.590564)
		(width 0.18288)
		(layer "In4.Cu")
		(net "M_G_CPU0_SB_CA<6>")
	)
	(segment
		(start 429.63592 -247.773444)
		(end 429.63592 -248.22023)
		(width 0.18288)
		(layer "In4.Cu")
		(net "M_G_CPU0_SB_CA<6>")
	)
	(segment
		(start 427.566328 -247.590564)
		(end 427.044866 -248.112026)
		(width 0.18288)
		(layer "In4.Cu")
		(net "M_G_CPU0_SB_CA<6>")
	)
	(segment
		(start 435.823614 -247.466612)
		(end 435.823614 -247.736106)
		(width 0.18288)
		(layer "In4.Cu")
		(net "M_G_CPU0_SB_CA<6>")
	)
	(segment
		(start 435.656228 -247.903492)
		(end 434.932328 -247.903492)
		(width 0.18288)
		(layer "In4.Cu")
		(net "M_G_CPU0_SB_CA<6>")
	)
	(segment
		(start 430.41824 -247.590564)
		(end 429.8188 -247.590564)
		(width 0.18288)
		(layer "In4.Cu")
		(net "M_G_CPU0_SB_CA<6>")
	)
	(segment
		(start 426.427138 -247.575832)
		(end 426.244258 -247.392952)
		(width 0.18288)
		(layer "In4.Cu")
		(net "M_G_CPU0_SB_CA<6>")
	)
	(segment
		(start 423.786554 -248.114566)
		(end 423.403014 -247.731026)
		(width 0.18288)
		(layer "In4.Cu")
		(net "M_G_CPU0_SB_CA<6>")
	)
	(segment
		(start 433.852574 -247.41378)
		(end 433.403502 -247.41378)
		(width 0.18288)
		(layer "In4.Cu")
		(net "M_G_CPU0_SB_CA<6>")
	)
	(segment
		(start 429.12538 -248.40311)
		(end 428.9425 -248.22023)
		(width 0.18288)
		(layer "In4.Cu")
		(net "M_G_CPU0_SB_CA<6>")
	)
	(segment
		(start 429.63592 -248.22023)
		(end 429.45304 -248.40311)
		(width 0.18288)
		(layer "In4.Cu")
		(net "M_G_CPU0_SB_CA<6>")
	)
	(segment
		(start 425.733718 -247.575832)
		(end 425.733718 -247.929146)
		(width 0.18288)
		(layer "In4.Cu")
		(net "M_G_CPU0_SB_CA<6>")
	)
	(segment
		(start 433.243482 -247.5738)
		(end 433.243482 -248.074942)
		(width 0.18288)
		(layer "In4.Cu")
		(net "M_G_CPU0_SB_CA<6>")
	)
	(segment
		(start 378.093478 -247.66778)
		(end 378.015246 -247.622568)
		(width 0.088646)
		(layer "In4.Cu")
		(net "M_G_CPU0_SB_CA<6>")
	)
	(segment
		(start 423.403014 -247.731026)
		(end 421.236394 -247.731026)
		(width 0.18288)
		(layer "In4.Cu")
		(net "M_G_CPU0_SB_CA<6>")
	)
	(segment
		(start 383.890012 -247.791224)
		(end 383.818638 -247.735344)
		(width 0.088646)
		(layer "In4.Cu")
		(net "M_G_CPU0_SB_CA<6>")
	)
	(segment
		(start 425.550838 -248.112026)
		(end 425.325794 -248.112026)
		(width 0.18288)
		(layer "In4.Cu")
		(net "M_G_CPU0_SB_CA<6>")
	)
	(segment
		(start 421.07485 -247.89257)
		(end 405.913844 -247.89257)
		(width 0.18288)
		(layer "In4.Cu")
		(net "M_G_CPU0_SB_CA<6>")
	)
	(segment
		(start 383.818638 -247.735344)
		(end 383.81051 -247.727216)
		(width 0.088646)
		(layer "In4.Cu")
		(net "M_G_CPU0_SB_CA<6>")
	)
	(arc
		(start 378.015246 -247.622568)
		(mid 377.711406 -247.419374)
		(end 377.436634 -247.178322)
		(width 0.088646)
		(layer "In4.Cu")
		(net "M_G_CPU0_SB_CA<6>")
	)
	(arc
		(start 380.913132 -247.66778)
		(mid 380.725934 -247.617637)
		(end 380.538736 -247.66778)
		(width 0.088646)
		(layer "In4.Cu")
		(net "M_G_CPU0_SB_CA<6>")
	)
	(arc
		(start 382.792986 -247.66778)
		(mid 382.605788 -247.617637)
		(end 382.41859 -247.66778)
		(width 0.088646)
		(layer "In4.Cu")
		(net "M_G_CPU0_SB_CA<6>")
	)
	(arc
		(start 383.732532 -247.66778)
		(mid 383.545334 -247.617637)
		(end 383.358136 -247.66778)
		(width 0.088646)
		(layer "In4.Cu")
		(net "M_G_CPU0_SB_CA<6>")
	)
	(arc
		(start 379.973078 -247.66778)
		(mid 379.78588 -247.617637)
		(end 379.598682 -247.66778)
		(width 0.088646)
		(layer "In4.Cu")
		(net "M_G_CPU0_SB_CA<6>")
	)
	(arc
		(start 381.844804 -247.662954)
		(mid 381.661042 -247.617554)
		(end 381.478536 -247.66778)
		(width 0.088646)
		(layer "In4.Cu")
		(net "M_G_CPU0_SB_CA<6>")
	)
	(arc
		(start 381.478536 -247.66778)
		(mid 381.204337 -247.743615)
		(end 380.927864 -247.676416)
		(width 0.088646)
		(layer "In4.Cu")
		(net "M_G_CPU0_SB_CA<6>")
	)
	(arc
		(start 379.598682 -247.66778)
		(mid 379.322123 -247.743523)
		(end 379.043946 -247.673876)
		(width 0.088646)
		(layer "In4.Cu")
		(net "M_G_CPU0_SB_CA<6>")
	)
	(arc
		(start 379.033532 -247.66778)
		(mid 378.846334 -247.617637)
		(end 378.659136 -247.66778)
		(width 0.088646)
		(layer "In4.Cu")
		(net "M_G_CPU0_SB_CA<6>")
	)
	(arc
		(start 383.358136 -247.66778)
		(mid 383.081577 -247.743523)
		(end 382.8034 -247.673876)
		(width 0.088646)
		(layer "In4.Cu")
		(net "M_G_CPU0_SB_CA<6>")
	)
	(arc
		(start 383.81051 -247.726962)
		(mid 383.77346 -247.694816)
		(end 383.732532 -247.66778)
		(width 0.088646)
		(layer "In4.Cu")
		(net "M_G_CPU0_SB_CA<6>")
	)
	(arc
		(start 380.528322 -247.673876)
		(mid 380.24989 -247.743722)
		(end 379.973078 -247.66778)
		(width 0.088646)
		(layer "In4.Cu")
		(net "M_G_CPU0_SB_CA<6>")
	)
	(arc
		(start 382.41859 -247.66778)
		(mid 382.144391 -247.743615)
		(end 381.867918 -247.676416)
		(width 0.088646)
		(layer "In4.Cu")
		(net "M_G_CPU0_SB_CA<6>")
	)
	(arc
		(start 378.648722 -247.673876)
		(mid 378.37029 -247.743722)
		(end 378.093478 -247.66778)
		(width 0.088646)
		(layer "In4.Cu")
		(net "M_G_CPU0_SB_CA<6>")
	)
	(segment
		(start 445.47536 -248.741692)
		(end 445.482726 -248.749058)
		(width 0.1016)
		(layer "F.Cu")
		(net "M_G_CPU0_SB_CA<5>")
	)
	(segment
		(start 442.664342 -248.31675)
		(end 443.099952 -248.75236)
		(width 0.20066)
		(layer "F.Cu")
		(net "M_G_CPU0_SB_CA<5>")
	)
	(segment
		(start 443.099952 -248.75236)
		(end 443.450726 -248.75236)
		(width 0.20066)
		(layer "F.Cu")
		(net "M_G_CPU0_SB_CA<5>")
	)
	(segment
		(start 443.450726 -248.75236)
		(end 443.455552 -248.75236)
		(width 0.101854)
		(layer "F.Cu")
		(net "M_G_CPU0_SB_CA<5>")
	)
	(segment
		(start 447.45783 -248.31675)
		(end 448.572382 -248.31675)
		(width 0.20066)
		(layer "F.Cu")
		(net "M_G_CPU0_SB_CA<5>")
	)
	(segment
		(start 441.028582 -248.31675)
		(end 442.664342 -248.31675)
		(width 0.20066)
		(layer "F.Cu")
		(net "M_G_CPU0_SB_CA<5>")
	)
	(segment
		(start 445.482726 -248.749058)
		(end 445.756792 -248.749058)
		(width 0.20066)
		(layer "F.Cu")
		(net "M_G_CPU0_SB_CA<5>")
	)
	(segment
		(start 443.46622 -248.741692)
		(end 445.47536 -248.741692)
		(width 0.1016)
		(layer "F.Cu")
		(net "M_G_CPU0_SB_CA<5>")
	)
	(segment
		(start 447.025268 -247.884188)
		(end 447.45783 -248.31675)
		(width 0.20066)
		(layer "F.Cu")
		(net "M_G_CPU0_SB_CA<5>")
	)
	(segment
		(start 379.786134 -247.992392)
		(end 379.78588 -247.992138)
		(width 0.20066)
		(layer "F.Cu")
		(net "M_G_CPU0_SB_CA<5>")
	)
	(segment
		(start 445.756792 -248.749058)
		(end 446.621662 -247.884188)
		(width 0.20066)
		(layer "F.Cu")
		(net "M_G_CPU0_SB_CA<5>")
	)
	(segment
		(start 379.786134 -248.528078)
		(end 379.786134 -247.992392)
		(width 0.20066)
		(layer "F.Cu")
		(net "M_G_CPU0_SB_CA<5>")
	)
	(segment
		(start 439.923682 -248.31675)
		(end 441.028582 -248.31675)
		(width 0.20066)
		(layer "F.Cu")
		(net "M_G_CPU0_SB_CA<5>")
	)
	(segment
		(start 446.621662 -247.884188)
		(end 447.025268 -247.884188)
		(width 0.20066)
		(layer "F.Cu")
		(net "M_G_CPU0_SB_CA<5>")
	)
	(segment
		(start 443.455552 -248.75236)
		(end 443.46622 -248.741692)
		(width 0.1016)
		(layer "F.Cu")
		(net "M_G_CPU0_SB_CA<5>")
	)
	(segment
		(start 420.866316 -248.74093)
		(end 420.575994 -248.74093)
		(width 0.18288)
		(layer "In4.Cu")
		(net "M_G_CPU0_SB_CA<5>")
	)
	(segment
		(start 437.291988 -249.590814)
		(end 437.017668 -249.865134)
		(width 0.18288)
		(layer "In4.Cu")
		(net "M_G_CPU0_SB_CA<5>")
	)
	(segment
		(start 436.380382 -249.682254)
		(end 436.380382 -248.945146)
		(width 0.18288)
		(layer "In4.Cu")
		(net "M_G_CPU0_SB_CA<5>")
	)
	(segment
		(start 405.72563 -248.742454)
		(end 405.510746 -248.742454)
		(width 0.18288)
		(layer "In4.Cu")
		(net "M_G_CPU0_SB_CA<5>")
	)
	(segment
		(start 435.431692 -248.74093)
		(end 435.033166 -249.139456)
		(width 0.18288)
		(layer "In4.Cu")
		(net "M_G_CPU0_SB_CA<5>")
	)
	(segment
		(start 436.176166 -248.74093)
		(end 435.431692 -248.74093)
		(width 0.18288)
		(layer "In4.Cu")
		(net "M_G_CPU0_SB_CA<5>")
	)
	(segment
		(start 385.740402 -248.216928)
		(end 385.736592 -248.213118)
		(width 0.088646)
		(layer "In4.Cu")
		(net "M_G_CPU0_SB_CA<5>")
	)
	(segment
		(start 427.70425 -248.648982)
		(end 425.68622 -248.648982)
		(width 0.18288)
		(layer "In4.Cu")
		(net "M_G_CPU0_SB_CA<5>")
	)
	(segment
		(start 425.033694 -248.742708)
		(end 425.031916 -248.74093)
		(width 0.18288)
		(layer "In4.Cu")
		(net "M_G_CPU0_SB_CA<5>")
	)
	(segment
		(start 436.563262 -249.865134)
		(end 436.380382 -249.682254)
		(width 0.18288)
		(layer "In4.Cu")
		(net "M_G_CPU0_SB_CA<5>")
	)
	(segment
		(start 435.033166 -249.3899)
		(end 434.781452 -249.641614)
		(width 0.18288)
		(layer "In4.Cu")
		(net "M_G_CPU0_SB_CA<5>")
	)
	(segment
		(start 435.033166 -249.139456)
		(end 435.033166 -249.3899)
		(width 0.18288)
		(layer "In4.Cu")
		(net "M_G_CPU0_SB_CA<5>")
	)
	(segment
		(start 405.510746 -248.742454)
		(end 401.524724 -247.091454)
		(width 0.18288)
		(layer "In4.Cu")
		(net "M_G_CPU0_SB_CA<5>")
	)
	(segment
		(start 425.592494 -248.742708)
		(end 425.033694 -248.742708)
		(width 0.18288)
		(layer "In4.Cu")
		(net "M_G_CPU0_SB_CA<5>")
	)
	(segment
		(start 441.472828 -248.569226)
		(end 441.651644 -248.748042)
		(width 0.18288)
		(layer "In4.Cu")
		(net "M_G_CPU0_SB_CA<5>")
	)
	(segment
		(start 425.031916 -248.74093)
		(end 423.43959 -248.74093)
		(width 0.18288)
		(layer "In4.Cu")
		(net "M_G_CPU0_SB_CA<5>")
	)
	(segment
		(start 423.281094 -248.899426)
		(end 421.262048 -248.899426)
		(width 0.18288)
		(layer "In4.Cu")
		(net "M_G_CPU0_SB_CA<5>")
	)
	(segment
		(start 397.497046 -247.091454)
		(end 397.409416 -247.003824)
		(width 0.18288)
		(layer "In4.Cu")
		(net "M_G_CPU0_SB_CA<5>")
	)
	(segment
		(start 420.868094 -248.742708)
		(end 420.866316 -248.74093)
		(width 0.18288)
		(layer "In4.Cu")
		(net "M_G_CPU0_SB_CA<5>")
	)
	(segment
		(start 383.358136 -248.316496)
		(end 383.347722 -248.3104)
		(width 0.088646)
		(layer "In4.Cu")
		(net "M_G_CPU0_SB_CA<5>")
	)
	(segment
		(start 441.45962 -249.590814)
		(end 437.291988 -249.590814)
		(width 0.18288)
		(layer "In4.Cu")
		(net "M_G_CPU0_SB_CA<5>")
	)
	(segment
		(start 405.725884 -248.742708)
		(end 405.72563 -248.742454)
		(width 0.18288)
		(layer "In4.Cu")
		(net "M_G_CPU0_SB_CA<5>")
	)
	(segment
		(start 440.176158 -248.569226)
		(end 441.472828 -248.569226)
		(width 0.18288)
		(layer "In4.Cu")
		(net "M_G_CPU0_SB_CA<5>")
	)
	(segment
		(start 423.43959 -248.74093)
		(end 423.281094 -248.899426)
		(width 0.18288)
		(layer "In4.Cu")
		(net "M_G_CPU0_SB_CA<5>")
	)
	(segment
		(start 434.781452 -249.641614)
		(end 434.259228 -249.641614)
		(width 0.18288)
		(layer "In4.Cu")
		(net "M_G_CPU0_SB_CA<5>")
	)
	(segment
		(start 382.41859 -248.316496)
		(end 382.418336 -248.316496)
		(width 0.088646)
		(layer "In4.Cu")
		(net "M_G_CPU0_SB_CA<5>")
	)
	(segment
		(start 385.766818 -248.216928)
		(end 385.740402 -248.216928)
		(width 0.088646)
		(layer "In4.Cu")
		(net "M_G_CPU0_SB_CA<5>")
	)
	(segment
		(start 441.651644 -249.39879)
		(end 441.45962 -249.590814)
		(width 0.18288)
		(layer "In4.Cu")
		(net "M_G_CPU0_SB_CA<5>")
	)
	(segment
		(start 401.524724 -247.091454)
		(end 397.497046 -247.091454)
		(width 0.18288)
		(layer "In4.Cu")
		(net "M_G_CPU0_SB_CA<5>")
	)
	(segment
		(start 431.462942 -248.696226)
		(end 431.235358 -248.92381)
		(width 0.18288)
		(layer "In4.Cu")
		(net "M_G_CPU0_SB_CA<5>")
	)
	(segment
		(start 434.259228 -249.641614)
		(end 433.31384 -248.696226)
		(width 0.18288)
		(layer "In4.Cu")
		(net "M_G_CPU0_SB_CA<5>")
	)
	(segment
		(start 380.153164 -248.091452)
		(end 379.78588 -247.992138)
		(width 0.088646)
		(layer "In4.Cu")
		(net "M_G_CPU0_SB_CA<5>")
	)
	(segment
		(start 390.686544 -247.003824)
		(end 389.47344 -248.216928)
		(width 0.18288)
		(layer "In4.Cu")
		(net "M_G_CPU0_SB_CA<5>")
	)
	(segment
		(start 425.68622 -248.648982)
		(end 425.592494 -248.742708)
		(width 0.18288)
		(layer "In4.Cu")
		(net "M_G_CPU0_SB_CA<5>")
	)
	(segment
		(start 389.47344 -248.216928)
		(end 385.766818 -248.216928)
		(width 0.18288)
		(layer "In4.Cu")
		(net "M_G_CPU0_SB_CA<5>")
	)
	(segment
		(start 433.31384 -248.696226)
		(end 431.462942 -248.696226)
		(width 0.18288)
		(layer "In4.Cu")
		(net "M_G_CPU0_SB_CA<5>")
	)
	(segment
		(start 397.409416 -247.003824)
		(end 390.686544 -247.003824)
		(width 0.18288)
		(layer "In4.Cu")
		(net "M_G_CPU0_SB_CA<5>")
	)
	(segment
		(start 385.736592 -248.213118)
		(end 384.118612 -248.213118)
		(width 0.088646)
		(layer "In4.Cu")
		(net "M_G_CPU0_SB_CA<5>")
	)
	(segment
		(start 441.651644 -248.748042)
		(end 441.651644 -249.39879)
		(width 0.18288)
		(layer "In4.Cu")
		(net "M_G_CPU0_SB_CA<5>")
	)
	(segment
		(start 421.262048 -248.899426)
		(end 421.10533 -248.742708)
		(width 0.18288)
		(layer "In4.Cu")
		(net "M_G_CPU0_SB_CA<5>")
	)
	(segment
		(start 437.017668 -249.865134)
		(end 436.563262 -249.865134)
		(width 0.18288)
		(layer "In4.Cu")
		(net "M_G_CPU0_SB_CA<5>")
	)
	(segment
		(start 427.979078 -248.92381)
		(end 427.70425 -248.648982)
		(width 0.18288)
		(layer "In4.Cu")
		(net "M_G_CPU0_SB_CA<5>")
	)
	(segment
		(start 420.574216 -248.742708)
		(end 405.725884 -248.742708)
		(width 0.18288)
		(layer "In4.Cu")
		(net "M_G_CPU0_SB_CA<5>")
	)
	(segment
		(start 421.10533 -248.742708)
		(end 420.868094 -248.742708)
		(width 0.18288)
		(layer "In4.Cu")
		(net "M_G_CPU0_SB_CA<5>")
	)
	(segment
		(start 420.575994 -248.74093)
		(end 420.574216 -248.742708)
		(width 0.18288)
		(layer "In4.Cu")
		(net "M_G_CPU0_SB_CA<5>")
	)
	(segment
		(start 380.538736 -248.316496)
		(end 380.153164 -248.091452)
		(width 0.088646)
		(layer "In4.Cu")
		(net "M_G_CPU0_SB_CA<5>")
	)
	(segment
		(start 431.235358 -248.92381)
		(end 427.979078 -248.92381)
		(width 0.18288)
		(layer "In4.Cu")
		(net "M_G_CPU0_SB_CA<5>")
	)
	(segment
		(start 436.380382 -248.945146)
		(end 436.176166 -248.74093)
		(width 0.18288)
		(layer "In4.Cu")
		(net "M_G_CPU0_SB_CA<5>")
	)
	(segment
		(start 439.923682 -248.31675)
		(end 440.176158 -248.569226)
		(width 0.18288)
		(layer "In4.Cu")
		(net "M_G_CPU0_SB_CA<5>")
	)
	(arc
		(start 382.418336 -248.316496)
		(mid 382.135634 -248.240754)
		(end 381.852932 -248.316496)
		(width 0.088646)
		(layer "In4.Cu")
		(net "M_G_CPU0_SB_CA<5>")
	)
	(arc
		(start 383.732532 -248.316496)
		(mid 383.545334 -248.366639)
		(end 383.358136 -248.316496)
		(width 0.088646)
		(layer "In4.Cu")
		(net "M_G_CPU0_SB_CA<5>")
	)
	(arc
		(start 382.792986 -248.316496)
		(mid 382.605788 -248.366639)
		(end 382.41859 -248.316496)
		(width 0.088646)
		(layer "In4.Cu")
		(net "M_G_CPU0_SB_CA<5>")
	)
	(arc
		(start 381.852932 -248.316496)
		(mid 381.665734 -248.366639)
		(end 381.478536 -248.316496)
		(width 0.088646)
		(layer "In4.Cu")
		(net "M_G_CPU0_SB_CA<5>")
	)
	(arc
		(start 383.347722 -248.3104)
		(mid 383.069544 -248.240708)
		(end 382.792986 -248.316496)
		(width 0.088646)
		(layer "In4.Cu")
		(net "M_G_CPU0_SB_CA<5>")
	)
	(arc
		(start 381.478536 -248.316496)
		(mid 381.195834 -248.240754)
		(end 380.913132 -248.316496)
		(width 0.088646)
		(layer "In4.Cu")
		(net "M_G_CPU0_SB_CA<5>")
	)
	(arc
		(start 380.913132 -248.316496)
		(mid 380.725934 -248.366639)
		(end 380.538736 -248.316496)
		(width 0.088646)
		(layer "In4.Cu")
		(net "M_G_CPU0_SB_CA<5>")
	)
	(arc
		(start 384.118612 -248.213118)
		(mid 383.91878 -248.239424)
		(end 383.732532 -248.316496)
		(width 0.088646)
		(layer "In4.Cu")
		(net "M_G_CPU0_SB_CA<5>")
	)
	(segment
		(start 442.038994 -249.604022)
		(end 442.455046 -249.604022)
		(width 0.20066)
		(layer "F.Cu")
		(net "M_G_CPU0_SB_CA<4>")
	)
	(segment
		(start 436.928514 -249.166634)
		(end 437.994044 -249.166634)
		(width 0.20066)
		(layer "F.Cu")
		(net "M_G_CPU0_SB_CA<4>")
	)
	(segment
		(start 442.026548 -249.591576)
		(end 442.038994 -249.604022)
		(width 0.1016)
		(layer "F.Cu")
		(net "M_G_CPU0_SB_CA<4>")
	)
	(segment
		(start 439.84037 -249.591576)
		(end 439.854086 -249.591576)
		(width 0.101854)
		(layer "F.Cu")
		(net "M_G_CPU0_SB_CA<4>")
	)
	(segment
		(start 438.488328 -248.67235)
		(end 438.813702 -248.67235)
		(width 0.20066)
		(layer "F.Cu")
		(net "M_G_CPU0_SB_CA<4>")
	)
	(segment
		(start 444.47206 -249.16638)
		(end 444.472314 -249.166634)
		(width 0.20066)
		(layer "F.Cu")
		(net "M_G_CPU0_SB_CA<4>")
	)
	(segment
		(start 377.906534 -247.992392)
		(end 377.90628 -247.992138)
		(width 0.20066)
		(layer "F.Cu")
		(net "M_G_CPU0_SB_CA<4>")
	)
	(segment
		(start 377.906534 -248.528078)
		(end 377.906534 -247.992392)
		(width 0.20066)
		(layer "F.Cu")
		(net "M_G_CPU0_SB_CA<4>")
	)
	(segment
		(start 442.455046 -249.604022)
		(end 442.892688 -249.16638)
		(width 0.20066)
		(layer "F.Cu")
		(net "M_G_CPU0_SB_CA<4>")
	)
	(segment
		(start 439.854086 -249.591576)
		(end 442.026548 -249.591576)
		(width 0.1016)
		(layer "F.Cu")
		(net "M_G_CPU0_SB_CA<4>")
	)
	(segment
		(start 439.732928 -249.591576)
		(end 439.84037 -249.591576)
		(width 0.20066)
		(layer "F.Cu")
		(net "M_G_CPU0_SB_CA<4>")
	)
	(segment
		(start 442.892688 -249.16638)
		(end 444.47206 -249.16638)
		(width 0.20066)
		(layer "F.Cu")
		(net "M_G_CPU0_SB_CA<4>")
	)
	(segment
		(start 435.823614 -249.166634)
		(end 436.928514 -249.166634)
		(width 0.20066)
		(layer "F.Cu")
		(net "M_G_CPU0_SB_CA<4>")
	)
	(segment
		(start 437.994044 -249.166634)
		(end 438.488328 -248.67235)
		(width 0.20066)
		(layer "F.Cu")
		(net "M_G_CPU0_SB_CA<4>")
	)
	(segment
		(start 438.813702 -248.67235)
		(end 439.732928 -249.591576)
		(width 0.20066)
		(layer "F.Cu")
		(net "M_G_CPU0_SB_CA<4>")
	)
	(segment
		(start 405.725884 -249.407426)
		(end 405.72563 -249.407172)
		(width 0.18288)
		(layer "In4.Cu")
		(net "M_G_CPU0_SB_CA<4>")
	)
	(segment
		(start 383.2733 -248.487946)
		(end 383.262886 -248.48185)
		(width 0.088646)
		(layer "In4.Cu")
		(net "M_G_CPU0_SB_CA<4>")
	)
	(segment
		(start 379.551184 -248.3993)
		(end 379.550422 -248.399046)
		(width 0.088646)
		(layer "In4.Cu")
		(net "M_G_CPU0_SB_CA<4>")
	)
	(segment
		(start 427.489874 -249.45594)
		(end 427.353222 -249.592592)
		(width 0.18288)
		(layer "In4.Cu")
		(net "M_G_CPU0_SB_CA<4>")
	)
	(segment
		(start 387.50748 -249.127518)
		(end 386.936488 -248.556526)
		(width 0.18288)
		(layer "In4.Cu")
		(net "M_G_CPU0_SB_CA<4>")
	)
	(segment
		(start 386.936488 -248.556526)
		(end 385.766818 -248.556526)
		(width 0.18288)
		(layer "In4.Cu")
		(net "M_G_CPU0_SB_CA<4>")
	)
	(segment
		(start 379.081284 -248.399046)
		(end 379.081284 -248.3993)
		(width 0.088646)
		(layer "In4.Cu")
		(net "M_G_CPU0_SB_CA<4>")
	)
	(segment
		(start 382.88849 -248.48185)
		(end 382.878076 -248.487946)
		(width 0.088646)
		(layer "In4.Cu")
		(net "M_G_CPU0_SB_CA<4>")
	)
	(segment
		(start 378.611384 -248.3993)
		(end 378.611384 -248.399046)
		(width 0.088646)
		(layer "In4.Cu")
		(net "M_G_CPU0_SB_CA<4>")
	)
	(segment
		(start 428.895764 -249.45594)
		(end 427.489874 -249.45594)
		(width 0.18288)
		(layer "In4.Cu")
		(net "M_G_CPU0_SB_CA<4>")
	)
	(segment
		(start 427.353222 -249.592592)
		(end 426.837856 -249.592592)
		(width 0.18288)
		(layer "In4.Cu")
		(net "M_G_CPU0_SB_CA<4>")
	)
	(segment
		(start 430.01438 -249.45594)
		(end 429.954944 -249.45594)
		(width 0.18288)
		(layer "In4.Cu")
		(net "M_G_CPU0_SB_CA<4>")
	)
	(segment
		(start 426.654976 -250.55068)
		(end 426.472096 -250.73356)
		(width 0.18288)
		(layer "In4.Cu")
		(net "M_G_CPU0_SB_CA<4>")
	)
	(segment
		(start 385.372864 -248.556526)
		(end 385.23545 -248.419112)
		(width 0.088646)
		(layer "In4.Cu")
		(net "M_G_CPU0_SB_CA<4>")
	)
	(segment
		(start 416.804094 -249.864626)
		(end 416.334448 -249.39498)
		(width 0.18288)
		(layer "In4.Cu")
		(net "M_G_CPU0_SB_CA<4>")
	)
	(segment
		(start 397.041116 -247.339612)
		(end 390.824974 -247.339612)
		(width 0.18288)
		(layer "In4.Cu")
		(net "M_G_CPU0_SB_CA<4>")
	)
	(segment
		(start 435.529228 -249.46102)
		(end 435.529228 -249.605546)
		(width 0.18288)
		(layer "In4.Cu")
		(net "M_G_CPU0_SB_CA<4>")
	)
	(segment
		(start 408.795728 -249.407426)
		(end 405.725884 -249.407426)
		(width 0.18288)
		(layer "In4.Cu")
		(net "M_G_CPU0_SB_CA<4>")
	)
	(segment
		(start 429.772064 -249.63882)
		(end 429.772064 -250.27001)
		(width 0.18288)
		(layer "In4.Cu")
		(net "M_G_CPU0_SB_CA<4>")
	)
	(segment
		(start 435.529228 -249.605546)
		(end 434.703728 -250.431046)
		(width 0.18288)
		(layer "In4.Cu")
		(net "M_G_CPU0_SB_CA<4>")
	)
	(segment
		(start 420.111428 -249.592592)
		(end 419.839394 -249.864626)
		(width 0.18288)
		(layer "In4.Cu")
		(net "M_G_CPU0_SB_CA<4>")
	)
	(segment
		(start 429.261524 -250.45289)
		(end 429.078644 -250.27001)
		(width 0.18288)
		(layer "In4.Cu")
		(net "M_G_CPU0_SB_CA<4>")
	)
	(segment
		(start 412.67634 -249.39498)
		(end 412.333694 -249.737626)
		(width 0.18288)
		(layer "In4.Cu")
		(net "M_G_CPU0_SB_CA<4>")
	)
	(segment
		(start 425.961556 -250.55068)
		(end 425.961556 -249.775472)
		(width 0.18288)
		(layer "In4.Cu")
		(net "M_G_CPU0_SB_CA<4>")
	)
	(segment
		(start 430.018698 -249.451622)
		(end 430.01438 -249.45594)
		(width 0.18288)
		(layer "In4.Cu")
		(net "M_G_CPU0_SB_CA<4>")
	)
	(segment
		(start 425.961556 -249.775472)
		(end 425.778676 -249.592592)
		(width 0.18288)
		(layer "In4.Cu")
		(net "M_G_CPU0_SB_CA<4>")
	)
	(segment
		(start 409.125928 -249.737626)
		(end 408.795728 -249.407426)
		(width 0.18288)
		(layer "In4.Cu")
		(net "M_G_CPU0_SB_CA<4>")
	)
	(segment
		(start 397.632428 -247.930924)
		(end 397.041116 -247.339612)
		(width 0.18288)
		(layer "In4.Cu")
		(net "M_G_CPU0_SB_CA<4>")
	)
	(segment
		(start 421.26916 -249.432826)
		(end 421.109394 -249.592592)
		(width 0.18288)
		(layer "In4.Cu")
		(net "M_G_CPU0_SB_CA<4>")
	)
	(segment
		(start 405.72563 -249.407172)
		(end 405.087582 -249.407172)
		(width 0.18288)
		(layer "In4.Cu")
		(net "M_G_CPU0_SB_CA<4>")
	)
	(segment
		(start 426.837856 -249.592592)
		(end 426.654976 -249.775472)
		(width 0.18288)
		(layer "In4.Cu")
		(net "M_G_CPU0_SB_CA<4>")
	)
	(segment
		(start 429.589184 -250.45289)
		(end 429.261524 -250.45289)
		(width 0.18288)
		(layer "In4.Cu")
		(net "M_G_CPU0_SB_CA<4>")
	)
	(segment
		(start 429.078644 -250.27001)
		(end 429.078644 -249.63882)
		(width 0.18288)
		(layer "In4.Cu")
		(net "M_G_CPU0_SB_CA<4>")
	)
	(segment
		(start 435.823614 -249.166634)
		(end 435.529228 -249.46102)
		(width 0.18288)
		(layer "In4.Cu")
		(net "M_G_CPU0_SB_CA<4>")
	)
	(segment
		(start 429.772064 -250.27001)
		(end 429.589184 -250.45289)
		(width 0.18288)
		(layer "In4.Cu")
		(net "M_G_CPU0_SB_CA<4>")
	)
	(segment
		(start 379.564646 -248.407174)
		(end 379.551184 -248.3993)
		(width 0.088646)
		(layer "In4.Cu")
		(net "M_G_CPU0_SB_CA<4>")
	)
	(segment
		(start 429.954944 -249.45594)
		(end 429.772064 -249.63882)
		(width 0.18288)
		(layer "In4.Cu")
		(net "M_G_CPU0_SB_CA<4>")
	)
	(segment
		(start 426.144436 -250.73356)
		(end 425.961556 -250.55068)
		(width 0.18288)
		(layer "In4.Cu")
		(net "M_G_CPU0_SB_CA<4>")
	)
	(segment
		(start 433.537614 -250.431046)
		(end 432.869594 -249.763026)
		(width 0.18288)
		(layer "In4.Cu")
		(net "M_G_CPU0_SB_CA<4>")
	)
	(segment
		(start 429.078644 -249.63882)
		(end 428.895764 -249.45594)
		(width 0.18288)
		(layer "In4.Cu")
		(net "M_G_CPU0_SB_CA<4>")
	)
	(segment
		(start 426.472096 -250.73356)
		(end 426.144436 -250.73356)
		(width 0.18288)
		(layer "In4.Cu")
		(net "M_G_CPU0_SB_CA<4>")
	)
	(segment
		(start 401.523708 -247.930924)
		(end 397.632428 -247.930924)
		(width 0.18288)
		(layer "In4.Cu")
		(net "M_G_CPU0_SB_CA<4>")
	)
	(segment
		(start 425.778676 -249.592592)
		(end 423.77106 -249.592592)
		(width 0.18288)
		(layer "In4.Cu")
		(net "M_G_CPU0_SB_CA<4>")
	)
	(segment
		(start 385.766818 -248.556526)
		(end 385.372864 -248.556526)
		(width 0.088646)
		(layer "In4.Cu")
		(net "M_G_CPU0_SB_CA<4>")
	)
	(segment
		(start 423.611294 -249.432826)
		(end 421.26916 -249.432826)
		(width 0.18288)
		(layer "In4.Cu")
		(net "M_G_CPU0_SB_CA<4>")
	)
	(segment
		(start 426.654976 -249.775472)
		(end 426.654976 -250.55068)
		(width 0.18288)
		(layer "In4.Cu")
		(net "M_G_CPU0_SB_CA<4>")
	)
	(segment
		(start 421.109394 -249.592592)
		(end 420.111428 -249.592592)
		(width 0.18288)
		(layer "In4.Cu")
		(net "M_G_CPU0_SB_CA<4>")
	)
	(segment
		(start 390.824974 -247.339612)
		(end 389.037068 -249.127518)
		(width 0.18288)
		(layer "In4.Cu")
		(net "M_G_CPU0_SB_CA<4>")
	)
	(segment
		(start 432.869594 -249.763026)
		(end 431.307494 -249.763026)
		(width 0.18288)
		(layer "In4.Cu")
		(net "M_G_CPU0_SB_CA<4>")
	)
	(segment
		(start 380.443232 -248.48185)
		(end 380.299722 -248.399046)
		(width 0.088646)
		(layer "In4.Cu")
		(net "M_G_CPU0_SB_CA<4>")
	)
	(segment
		(start 380.02083 -248.399046)
		(end 380.021084 -248.3993)
		(width 0.088646)
		(layer "In4.Cu")
		(net "M_G_CPU0_SB_CA<4>")
	)
	(segment
		(start 405.087582 -249.407172)
		(end 401.523708 -247.930924)
		(width 0.18288)
		(layer "In4.Cu")
		(net "M_G_CPU0_SB_CA<4>")
	)
	(segment
		(start 434.703728 -250.431046)
		(end 433.537614 -250.431046)
		(width 0.18288)
		(layer "In4.Cu")
		(net "M_G_CPU0_SB_CA<4>")
	)
	(segment
		(start 385.23545 -248.419112)
		(end 384.0607 -248.419112)
		(width 0.088646)
		(layer "In4.Cu")
		(net "M_G_CPU0_SB_CA<4>")
	)
	(segment
		(start 431.307494 -249.763026)
		(end 430.99609 -249.451622)
		(width 0.18288)
		(layer "In4.Cu")
		(net "M_G_CPU0_SB_CA<4>")
	)
	(segment
		(start 412.333694 -249.737626)
		(end 409.125928 -249.737626)
		(width 0.18288)
		(layer "In4.Cu")
		(net "M_G_CPU0_SB_CA<4>")
	)
	(segment
		(start 416.334448 -249.39498)
		(end 412.67634 -249.39498)
		(width 0.18288)
		(layer "In4.Cu")
		(net "M_G_CPU0_SB_CA<4>")
	)
	(segment
		(start 419.839394 -249.864626)
		(end 416.804094 -249.864626)
		(width 0.18288)
		(layer "In4.Cu")
		(net "M_G_CPU0_SB_CA<4>")
	)
	(segment
		(start 430.99609 -249.451622)
		(end 430.018698 -249.451622)
		(width 0.18288)
		(layer "In4.Cu")
		(net "M_G_CPU0_SB_CA<4>")
	)
	(segment
		(start 378.611384 -248.399046)
		(end 377.90628 -247.992138)
		(width 0.088646)
		(layer "In4.Cu")
		(net "M_G_CPU0_SB_CA<4>")
	)
	(segment
		(start 389.037068 -249.127518)
		(end 387.50748 -249.127518)
		(width 0.18288)
		(layer "In4.Cu")
		(net "M_G_CPU0_SB_CA<4>")
	)
	(segment
		(start 423.77106 -249.592592)
		(end 423.611294 -249.432826)
		(width 0.18288)
		(layer "In4.Cu")
		(net "M_G_CPU0_SB_CA<4>")
	)
	(arc
		(start 381.383032 -248.48185)
		(mid 381.195834 -248.431707)
		(end 381.008636 -248.48185)
		(width 0.088646)
		(layer "In4.Cu")
		(net "M_G_CPU0_SB_CA<4>")
	)
	(arc
		(start 380.299722 -248.399046)
		(mid 380.160276 -248.361685)
		(end 380.02083 -248.399046)
		(width 0.088646)
		(layer "In4.Cu")
		(net "M_G_CPU0_SB_CA<4>")
	)
	(arc
		(start 382.878076 -248.487946)
		(mid 382.599644 -248.55776)
		(end 382.322832 -248.48185)
		(width 0.088646)
		(layer "In4.Cu")
		(net "M_G_CPU0_SB_CA<4>")
	)
	(arc
		(start 379.081284 -248.3993)
		(mid 378.846334 -248.462226)
		(end 378.611384 -248.3993)
		(width 0.088646)
		(layer "In4.Cu")
		(net "M_G_CPU0_SB_CA<4>")
	)
	(arc
		(start 380.021084 -248.3993)
		(mid 379.793897 -248.462284)
		(end 379.564646 -248.407174)
		(width 0.088646)
		(layer "In4.Cu")
		(net "M_G_CPU0_SB_CA<4>")
	)
	(arc
		(start 381.948436 -248.48185)
		(mid 381.665734 -248.557592)
		(end 381.383032 -248.48185)
		(width 0.088646)
		(layer "In4.Cu")
		(net "M_G_CPU0_SB_CA<4>")
	)
	(arc
		(start 383.262886 -248.48185)
		(mid 383.075688 -248.431707)
		(end 382.88849 -248.48185)
		(width 0.088646)
		(layer "In4.Cu")
		(net "M_G_CPU0_SB_CA<4>")
	)
	(arc
		(start 379.550422 -248.399046)
		(mid 379.31587 -248.336272)
		(end 379.081284 -248.399046)
		(width 0.088646)
		(layer "In4.Cu")
		(net "M_G_CPU0_SB_CA<4>")
	)
	(arc
		(start 382.322832 -248.48185)
		(mid 382.135634 -248.431707)
		(end 381.948436 -248.48185)
		(width 0.088646)
		(layer "In4.Cu")
		(net "M_G_CPU0_SB_CA<4>")
	)
	(arc
		(start 381.008636 -248.48185)
		(mid 380.725934 -248.557592)
		(end 380.443232 -248.48185)
		(width 0.088646)
		(layer "In4.Cu")
		(net "M_G_CPU0_SB_CA<4>")
	)
	(arc
		(start 383.828036 -248.48185)
		(mid 383.551477 -248.557559)
		(end 383.2733 -248.487946)
		(width 0.088646)
		(layer "In4.Cu")
		(net "M_G_CPU0_SB_CA<4>")
	)
	(arc
		(start 384.0607 -248.419112)
		(mid 383.940213 -248.435072)
		(end 383.828036 -248.48185)
		(width 0.088646)
		(layer "In4.Cu")
		(net "M_G_CPU0_SB_CA<4>")
	)
	(segment
		(start 445.482726 -250.44908)
		(end 445.756792 -250.44908)
		(width 0.20066)
		(layer "F.Cu")
		(net "M_G_CPU0_SB_CA<3>")
	)
	(segment
		(start 443.455552 -250.452382)
		(end 443.46622 -250.441714)
		(width 0.1016)
		(layer "F.Cu")
		(net "M_G_CPU0_SB_CA<3>")
	)
	(segment
		(start 443.099952 -250.452382)
		(end 443.450726 -250.452382)
		(width 0.20066)
		(layer "F.Cu")
		(net "M_G_CPU0_SB_CA<3>")
	)
	(segment
		(start 443.450726 -250.452382)
		(end 443.455552 -250.452382)
		(width 0.101854)
		(layer "F.Cu")
		(net "M_G_CPU0_SB_CA<3>")
	)
	(segment
		(start 446.621662 -249.58421)
		(end 447.025268 -249.58421)
		(width 0.20066)
		(layer "F.Cu")
		(net "M_G_CPU0_SB_CA<3>")
	)
	(segment
		(start 379.316234 -249.341894)
		(end 379.316234 -248.806208)
		(width 0.20066)
		(layer "F.Cu")
		(net "M_G_CPU0_SB_CA<3>")
	)
	(segment
		(start 442.664342 -250.016772)
		(end 443.099952 -250.452382)
		(width 0.20066)
		(layer "F.Cu")
		(net "M_G_CPU0_SB_CA<3>")
	)
	(segment
		(start 443.46622 -250.441714)
		(end 445.47536 -250.441714)
		(width 0.1016)
		(layer "F.Cu")
		(net "M_G_CPU0_SB_CA<3>")
	)
	(segment
		(start 445.47536 -250.441714)
		(end 445.482726 -250.44908)
		(width 0.1016)
		(layer "F.Cu")
		(net "M_G_CPU0_SB_CA<3>")
	)
	(segment
		(start 447.025268 -249.58421)
		(end 447.45783 -250.016772)
		(width 0.20066)
		(layer "F.Cu")
		(net "M_G_CPU0_SB_CA<3>")
	)
	(segment
		(start 379.31598 -249.342148)
		(end 379.316234 -249.341894)
		(width 0.20066)
		(layer "F.Cu")
		(net "M_G_CPU0_SB_CA<3>")
	)
	(segment
		(start 439.923682 -250.016772)
		(end 441.028582 -250.016772)
		(width 0.20066)
		(layer "F.Cu")
		(net "M_G_CPU0_SB_CA<3>")
	)
	(segment
		(start 441.028582 -250.016772)
		(end 442.664342 -250.016772)
		(width 0.20066)
		(layer "F.Cu")
		(net "M_G_CPU0_SB_CA<3>")
	)
	(segment
		(start 447.45783 -250.016772)
		(end 448.572382 -250.016772)
		(width 0.20066)
		(layer "F.Cu")
		(net "M_G_CPU0_SB_CA<3>")
	)
	(segment
		(start 445.756792 -250.44908)
		(end 446.621662 -249.58421)
		(width 0.20066)
		(layer "F.Cu")
		(net "M_G_CPU0_SB_CA<3>")
	)
	(segment
		(start 383.282698 -249.497596)
		(end 383.00533 -249.220228)
		(width 0.088646)
		(layer "In4.Cu")
		(net "M_G_CPU0_SB_CA<3>")
	)
	(segment
		(start 433.682394 -251.337826)
		(end 432.615594 -250.271026)
		(width 0.18288)
		(layer "In4.Cu")
		(net "M_G_CPU0_SB_CA<3>")
	)
	(segment
		(start 389.200136 -249.462798)
		(end 387.368542 -249.462798)
		(width 0.18288)
		(layer "In4.Cu")
		(net "M_G_CPU0_SB_CA<3>")
	)
	(segment
		(start 397.596868 -248.624852)
		(end 396.647416 -247.6754)
		(width 0.18288)
		(layer "In4.Cu")
		(net "M_G_CPU0_SB_CA<3>")
	)
	(segment
		(start 390.987534 -247.6754)
		(end 389.200136 -249.462798)
		(width 0.18288)
		(layer "In4.Cu")
		(net "M_G_CPU0_SB_CA<3>")
	)
	(segment
		(start 435.40553 -250.44019)
		(end 435.142894 -250.702826)
		(width 0.18288)
		(layer "In4.Cu")
		(net "M_G_CPU0_SB_CA<3>")
	)
	(segment
		(start 439.500264 -250.44019)
		(end 435.40553 -250.44019)
		(width 0.18288)
		(layer "In4.Cu")
		(net "M_G_CPU0_SB_CA<3>")
	)
	(segment
		(start 396.647416 -247.6754)
		(end 390.987534 -247.6754)
		(width 0.18288)
		(layer "In4.Cu")
		(net "M_G_CPU0_SB_CA<3>")
	)
	(segment
		(start 439.923682 -250.016772)
		(end 439.500264 -250.44019)
		(width 0.18288)
		(layer "In4.Cu")
		(net "M_G_CPU0_SB_CA<3>")
	)
	(segment
		(start 385.766818 -249.035316)
		(end 385.300474 -249.035316)
		(width 0.088646)
		(layer "In4.Cu")
		(net "M_G_CPU0_SB_CA<3>")
	)
	(segment
		(start 387.368542 -249.462798)
		(end 386.94106 -249.035316)
		(width 0.18288)
		(layer "In4.Cu")
		(net "M_G_CPU0_SB_CA<3>")
	)
	(segment
		(start 385.300474 -249.035316)
		(end 385.154678 -249.181112)
		(width 0.088646)
		(layer "In4.Cu")
		(net "M_G_CPU0_SB_CA<3>")
	)
	(segment
		(start 435.142894 -250.982226)
		(end 434.787294 -251.337826)
		(width 0.18288)
		(layer "In4.Cu")
		(net "M_G_CPU0_SB_CA<3>")
	)
	(segment
		(start 379.129036 -249.130566)
		(end 379.120146 -249.125486)
		(width 0.088646)
		(layer "In4.Cu")
		(net "M_G_CPU0_SB_CA<3>")
	)
	(segment
		(start 430.151794 -250.626626)
		(end 429.749204 -251.029216)
		(width 0.18288)
		(layer "In4.Cu")
		(net "M_G_CPU0_SB_CA<3>")
	)
	(segment
		(start 431.278538 -250.626626)
		(end 430.151794 -250.626626)
		(width 0.18288)
		(layer "In4.Cu")
		(net "M_G_CPU0_SB_CA<3>")
	)
	(segment
		(start 426.062394 -251.414026)
		(end 425.091098 -250.44273)
		(width 0.18288)
		(layer "In4.Cu")
		(net "M_G_CPU0_SB_CA<3>")
	)
	(segment
		(start 432.615594 -250.271026)
		(end 431.634138 -250.271026)
		(width 0.18288)
		(layer "In4.Cu")
		(net "M_G_CPU0_SB_CA<3>")
	)
	(segment
		(start 431.634138 -250.271026)
		(end 431.278538 -250.626626)
		(width 0.18288)
		(layer "In4.Cu")
		(net "M_G_CPU0_SB_CA<3>")
	)
	(segment
		(start 425.091098 -250.44273)
		(end 405.39416 -250.44273)
		(width 0.18288)
		(layer "In4.Cu")
		(net "M_G_CPU0_SB_CA<3>")
	)
	(segment
		(start 427.891194 -251.414026)
		(end 426.062394 -251.414026)
		(width 0.18288)
		(layer "In4.Cu")
		(net "M_G_CPU0_SB_CA<3>")
	)
	(segment
		(start 405.39416 -250.44273)
		(end 401.005294 -248.624852)
		(width 0.18288)
		(layer "In4.Cu")
		(net "M_G_CPU0_SB_CA<3>")
	)
	(segment
		(start 385.154678 -249.181112)
		(end 384.955034 -249.181112)
		(width 0.088646)
		(layer "In4.Cu")
		(net "M_G_CPU0_SB_CA<3>")
	)
	(segment
		(start 435.142894 -250.702826)
		(end 435.142894 -250.982226)
		(width 0.18288)
		(layer "In4.Cu")
		(net "M_G_CPU0_SB_CA<3>")
	)
	(segment
		(start 378.946156 -248.863358)
		(end 379.003306 -248.806208)
		(width 0.088646)
		(layer "In4.Cu")
		(net "M_G_CPU0_SB_CA<3>")
	)
	(segment
		(start 379.003306 -248.806208)
		(end 379.316234 -248.806208)
		(width 0.088646)
		(layer "In4.Cu")
		(net "M_G_CPU0_SB_CA<3>")
	)
	(segment
		(start 401.005294 -248.624852)
		(end 397.596868 -248.624852)
		(width 0.18288)
		(layer "In4.Cu")
		(net "M_G_CPU0_SB_CA<3>")
	)
	(segment
		(start 429.749204 -251.029216)
		(end 428.276004 -251.029216)
		(width 0.18288)
		(layer "In4.Cu")
		(net "M_G_CPU0_SB_CA<3>")
	)
	(segment
		(start 384.166872 -249.05462)
		(end 383.723896 -249.497596)
		(width 0.088646)
		(layer "In4.Cu")
		(net "M_G_CPU0_SB_CA<3>")
	)
	(segment
		(start 428.276004 -251.029216)
		(end 427.891194 -251.414026)
		(width 0.18288)
		(layer "In4.Cu")
		(net "M_G_CPU0_SB_CA<3>")
	)
	(segment
		(start 386.94106 -249.035316)
		(end 385.766818 -249.035316)
		(width 0.18288)
		(layer "In4.Cu")
		(net "M_G_CPU0_SB_CA<3>")
	)
	(segment
		(start 383.723896 -249.497596)
		(end 383.282698 -249.497596)
		(width 0.088646)
		(layer "In4.Cu")
		(net "M_G_CPU0_SB_CA<3>")
	)
	(segment
		(start 384.476752 -249.05462)
		(end 384.166872 -249.05462)
		(width 0.088646)
		(layer "In4.Cu")
		(net "M_G_CPU0_SB_CA<3>")
	)
	(segment
		(start 434.787294 -251.337826)
		(end 433.682394 -251.337826)
		(width 0.18288)
		(layer "In4.Cu")
		(net "M_G_CPU0_SB_CA<3>")
	)
	(arc
		(start 379.120146 -249.125486)
		(mid 379.004337 -249.013557)
		(end 378.946156 -248.863358)
		(width 0.088646)
		(layer "In4.Cu")
		(net "M_G_CPU0_SB_CA<3>")
	)
	(arc
		(start 383.00533 -249.220228)
		(mid 382.949725 -249.171554)
		(end 382.888236 -249.130566)
		(width 0.088646)
		(layer "In4.Cu")
		(net "M_G_CPU0_SB_CA<3>")
	)
	(arc
		(start 379.503432 -249.130566)
		(mid 379.316234 -249.180709)
		(end 379.129036 -249.130566)
		(width 0.088646)
		(layer "In4.Cu")
		(net "M_G_CPU0_SB_CA<3>")
	)
	(arc
		(start 382.888236 -249.130566)
		(mid 382.605534 -249.05479)
		(end 382.322832 -249.130566)
		(width 0.088646)
		(layer "In4.Cu")
		(net "M_G_CPU0_SB_CA<3>")
	)
	(arc
		(start 384.753104 -249.12193)
		(mid 384.61923 -249.07061)
		(end 384.476752 -249.05462)
		(width 0.088646)
		(layer "In4.Cu")
		(net "M_G_CPU0_SB_CA<3>")
	)
	(arc
		(start 381.948436 -249.130566)
		(mid 381.665734 -249.05479)
		(end 381.383032 -249.130566)
		(width 0.088646)
		(layer "In4.Cu")
		(net "M_G_CPU0_SB_CA<3>")
	)
	(arc
		(start 380.068836 -249.130566)
		(mid 379.786134 -249.05479)
		(end 379.503432 -249.130566)
		(width 0.088646)
		(layer "In4.Cu")
		(net "M_G_CPU0_SB_CA<3>")
	)
	(arc
		(start 381.008636 -249.130566)
		(mid 380.725934 -249.05479)
		(end 380.443232 -249.130566)
		(width 0.088646)
		(layer "In4.Cu")
		(net "M_G_CPU0_SB_CA<3>")
	)
	(arc
		(start 380.443232 -249.130566)
		(mid 380.256034 -249.180709)
		(end 380.068836 -249.130566)
		(width 0.088646)
		(layer "In4.Cu")
		(net "M_G_CPU0_SB_CA<3>")
	)
	(arc
		(start 384.955034 -249.181112)
		(mid 384.849833 -249.165975)
		(end 384.753104 -249.12193)
		(width 0.088646)
		(layer "In4.Cu")
		(net "M_G_CPU0_SB_CA<3>")
	)
	(arc
		(start 381.383032 -249.130566)
		(mid 381.195834 -249.180709)
		(end 381.008636 -249.130566)
		(width 0.088646)
		(layer "In4.Cu")
		(net "M_G_CPU0_SB_CA<3>")
	)
	(arc
		(start 382.322832 -249.130566)
		(mid 382.135634 -249.180709)
		(end 381.948436 -249.130566)
		(width 0.088646)
		(layer "In4.Cu")
		(net "M_G_CPU0_SB_CA<3>")
	)
	(segment
		(start 442.038994 -251.304044)
		(end 442.455046 -251.304044)
		(width 0.20066)
		(layer "F.Cu")
		(net "M_G_CPU0_SB_CA<2>")
	)
	(segment
		(start 444.47206 -250.866402)
		(end 444.472314 -250.866656)
		(width 0.20066)
		(layer "F.Cu")
		(net "M_G_CPU0_SB_CA<2>")
	)
	(segment
		(start 437.994044 -250.866656)
		(end 438.488328 -250.372372)
		(width 0.20066)
		(layer "F.Cu")
		(net "M_G_CPU0_SB_CA<2>")
	)
	(segment
		(start 378.37618 -249.342148)
		(end 378.376434 -249.341894)
		(width 0.20066)
		(layer "F.Cu")
		(net "M_G_CPU0_SB_CA<2>")
	)
	(segment
		(start 439.854086 -251.291598)
		(end 442.026548 -251.291598)
		(width 0.1016)
		(layer "F.Cu")
		(net "M_G_CPU0_SB_CA<2>")
	)
	(segment
		(start 435.823614 -250.866656)
		(end 436.928514 -250.866656)
		(width 0.20066)
		(layer "F.Cu")
		(net "M_G_CPU0_SB_CA<2>")
	)
	(segment
		(start 442.892688 -250.866402)
		(end 444.47206 -250.866402)
		(width 0.20066)
		(layer "F.Cu")
		(net "M_G_CPU0_SB_CA<2>")
	)
	(segment
		(start 442.455046 -251.304044)
		(end 442.892688 -250.866402)
		(width 0.20066)
		(layer "F.Cu")
		(net "M_G_CPU0_SB_CA<2>")
	)
	(segment
		(start 442.026548 -251.291598)
		(end 442.038994 -251.304044)
		(width 0.1016)
		(layer "F.Cu")
		(net "M_G_CPU0_SB_CA<2>")
	)
	(segment
		(start 438.813702 -250.372372)
		(end 439.732928 -251.291598)
		(width 0.20066)
		(layer "F.Cu")
		(net "M_G_CPU0_SB_CA<2>")
	)
	(segment
		(start 436.928514 -250.866656)
		(end 437.994044 -250.866656)
		(width 0.20066)
		(layer "F.Cu")
		(net "M_G_CPU0_SB_CA<2>")
	)
	(segment
		(start 439.84037 -251.291598)
		(end 439.854086 -251.291598)
		(width 0.101854)
		(layer "F.Cu")
		(net "M_G_CPU0_SB_CA<2>")
	)
	(segment
		(start 438.488328 -250.372372)
		(end 438.813702 -250.372372)
		(width 0.20066)
		(layer "F.Cu")
		(net "M_G_CPU0_SB_CA<2>")
	)
	(segment
		(start 378.376434 -249.341894)
		(end 378.376434 -248.806208)
		(width 0.20066)
		(layer "F.Cu")
		(net "M_G_CPU0_SB_CA<2>")
	)
	(segment
		(start 439.732928 -251.291598)
		(end 439.84037 -251.291598)
		(width 0.20066)
		(layer "F.Cu")
		(net "M_G_CPU0_SB_CA<2>")
	)
	(segment
		(start 426.77207 -253.067566)
		(end 426.58919 -252.884686)
		(width 0.18288)
		(layer "In4.Cu")
		(net "M_G_CPU0_SB_CA<2>")
	)
	(segment
		(start 420.333932 -251.490226)
		(end 419.270434 -251.490226)
		(width 0.18288)
		(layer "In4.Cu")
		(net "M_G_CPU0_SB_CA<2>")
	)
	(segment
		(start 426.40631 -252.288802)
		(end 426.20057 -252.288802)
		(width 0.18288)
		(layer "In4.Cu")
		(net "M_G_CPU0_SB_CA<2>")
	)
	(segment
		(start 401.09267 -249.253502)
		(end 397.510508 -249.253502)
		(width 0.18288)
		(layer "In4.Cu")
		(net "M_G_CPU0_SB_CA<2>")
	)
	(segment
		(start 427.46549 -252.288802)
		(end 427.28261 -252.471682)
		(width 0.18288)
		(layer "In4.Cu")
		(net "M_G_CPU0_SB_CA<2>")
	)
	(segment
		(start 428.66945 -252.884686)
		(end 428.48657 -253.067566)
		(width 0.18288)
		(layer "In4.Cu")
		(net "M_G_CPU0_SB_CA<2>")
	)
	(segment
		(start 429.226218 -252.288802)
		(end 428.85233 -252.288802)
		(width 0.18288)
		(layer "In4.Cu")
		(net "M_G_CPU0_SB_CA<2>")
	)
	(segment
		(start 427.97603 -252.884686)
		(end 427.97603 -252.471682)
		(width 0.18288)
		(layer "In4.Cu")
		(net "M_G_CPU0_SB_CA<2>")
	)
	(segment
		(start 433.593494 -251.972826)
		(end 433.129944 -251.509276)
		(width 0.18288)
		(layer "In4.Cu")
		(net "M_G_CPU0_SB_CA<2>")
	)
	(segment
		(start 418.394134 -251.86513)
		(end 418.394134 -251.673106)
		(width 0.18288)
		(layer "In4.Cu")
		(net "M_G_CPU0_SB_CA<2>")
	)
	(segment
		(start 385.766818 -249.371866)
		(end 385.500372 -249.371866)
		(width 0.088646)
		(layer "In4.Cu")
		(net "M_G_CPU0_SB_CA<2>")
	)
	(segment
		(start 428.15891 -253.067566)
		(end 427.97603 -252.884686)
		(width 0.18288)
		(layer "In4.Cu")
		(net "M_G_CPU0_SB_CA<2>")
	)
	(segment
		(start 435.823614 -251.115576)
		(end 434.966364 -251.972826)
		(width 0.18288)
		(layer "In4.Cu")
		(net "M_G_CPU0_SB_CA<2>")
	)
	(segment
		(start 428.48657 -253.067566)
		(end 428.15891 -253.067566)
		(width 0.18288)
		(layer "In4.Cu")
		(net "M_G_CPU0_SB_CA<2>")
	)
	(segment
		(start 420.531544 -251.292614)
		(end 420.333932 -251.490226)
		(width 0.18288)
		(layer "In4.Cu")
		(net "M_G_CPU0_SB_CA<2>")
	)
	(segment
		(start 408.549348 -251.231146)
		(end 405.866854 -251.231146)
		(width 0.18288)
		(layer "In4.Cu")
		(net "M_G_CPU0_SB_CA<2>")
	)
	(segment
		(start 417.190174 -252.04801)
		(end 417.007294 -251.86513)
		(width 0.18288)
		(layer "In4.Cu")
		(net "M_G_CPU0_SB_CA<2>")
	)
	(segment
		(start 415.619692 -251.261626)
		(end 412.789116 -251.261626)
		(width 0.18288)
		(layer "In4.Cu")
		(net "M_G_CPU0_SB_CA<2>")
	)
	(segment
		(start 418.394134 -251.673106)
		(end 418.211254 -251.490226)
		(width 0.18288)
		(layer "In4.Cu")
		(net "M_G_CPU0_SB_CA<2>")
	)
	(segment
		(start 426.58919 -252.471682)
		(end 426.40631 -252.288802)
		(width 0.18288)
		(layer "In4.Cu")
		(net "M_G_CPU0_SB_CA<2>")
	)
	(segment
		(start 427.09973 -253.067566)
		(end 426.77207 -253.067566)
		(width 0.18288)
		(layer "In4.Cu")
		(net "M_G_CPU0_SB_CA<2>")
	)
	(segment
		(start 435.823614 -250.866656)
		(end 435.823614 -251.115576)
		(width 0.18288)
		(layer "In4.Cu")
		(net "M_G_CPU0_SB_CA<2>")
	)
	(segment
		(start 412.585916 -251.464826)
		(end 408.783028 -251.464826)
		(width 0.18288)
		(layer "In4.Cu")
		(net "M_G_CPU0_SB_CA<2>")
	)
	(segment
		(start 418.211254 -251.490226)
		(end 417.883594 -251.490226)
		(width 0.18288)
		(layer "In4.Cu")
		(net "M_G_CPU0_SB_CA<2>")
	)
	(segment
		(start 428.85233 -252.288802)
		(end 428.66945 -252.471682)
		(width 0.18288)
		(layer "In4.Cu")
		(net "M_G_CPU0_SB_CA<2>")
	)
	(segment
		(start 433.129944 -251.509276)
		(end 430.99609 -251.509276)
		(width 0.18288)
		(layer "In4.Cu")
		(net "M_G_CPU0_SB_CA<2>")
	)
	(segment
		(start 383.203704 -249.687842)
		(end 382.87071 -249.354848)
		(width 0.088646)
		(layer "In4.Cu")
		(net "M_G_CPU0_SB_CA<2>")
	)
	(segment
		(start 427.79315 -252.288802)
		(end 427.46549 -252.288802)
		(width 0.18288)
		(layer "In4.Cu")
		(net "M_G_CPU0_SB_CA<2>")
	)
	(segment
		(start 417.883594 -251.490226)
		(end 417.700714 -251.673106)
		(width 0.18288)
		(layer "In4.Cu")
		(net "M_G_CPU0_SB_CA<2>")
	)
	(segment
		(start 416.824414 -251.490226)
		(end 415.848292 -251.490226)
		(width 0.18288)
		(layer "In4.Cu")
		(net "M_G_CPU0_SB_CA<2>")
	)
	(segment
		(start 427.97603 -252.471682)
		(end 427.79315 -252.288802)
		(width 0.18288)
		(layer "In4.Cu")
		(net "M_G_CPU0_SB_CA<2>")
	)
	(segment
		(start 378.689362 -248.806208)
		(end 378.376434 -248.806208)
		(width 0.088646)
		(layer "In4.Cu")
		(net "M_G_CPU0_SB_CA<2>")
	)
	(segment
		(start 384.259582 -249.245374)
		(end 383.817114 -249.687842)
		(width 0.088646)
		(layer "In4.Cu")
		(net "M_G_CPU0_SB_CA<2>")
	)
	(segment
		(start 378.75464 -248.871486)
		(end 378.689362 -248.806208)
		(width 0.088646)
		(layer "In4.Cu")
		(net "M_G_CPU0_SB_CA<2>")
	)
	(segment
		(start 379.598936 -249.295666)
		(end 379.588522 -249.301762)
		(width 0.088646)
		(layer "In4.Cu")
		(net "M_G_CPU0_SB_CA<2>")
	)
	(segment
		(start 427.28261 -252.884686)
		(end 427.09973 -253.067566)
		(width 0.18288)
		(layer "In4.Cu")
		(net "M_G_CPU0_SB_CA<2>")
	)
	(segment
		(start 396.267686 -248.01068)
		(end 391.231374 -248.01068)
		(width 0.18288)
		(layer "In4.Cu")
		(net "M_G_CPU0_SB_CA<2>")
	)
	(segment
		(start 418.904674 -252.04801)
		(end 418.577014 -252.04801)
		(width 0.18288)
		(layer "In4.Cu")
		(net "M_G_CPU0_SB_CA<2>")
	)
	(segment
		(start 417.007294 -251.673106)
		(end 416.824414 -251.490226)
		(width 0.18288)
		(layer "In4.Cu")
		(net "M_G_CPU0_SB_CA<2>")
	)
	(segment
		(start 384.480562 -249.245374)
		(end 384.259582 -249.245374)
		(width 0.088646)
		(layer "In4.Cu")
		(net "M_G_CPU0_SB_CA<2>")
	)
	(segment
		(start 428.66945 -252.471682)
		(end 428.66945 -252.884686)
		(width 0.18288)
		(layer "In4.Cu")
		(net "M_G_CPU0_SB_CA<2>")
	)
	(segment
		(start 383.817114 -249.687842)
		(end 383.203704 -249.687842)
		(width 0.088646)
		(layer "In4.Cu")
		(net "M_G_CPU0_SB_CA<2>")
	)
	(segment
		(start 417.517834 -252.04801)
		(end 417.190174 -252.04801)
		(width 0.18288)
		(layer "In4.Cu")
		(net "M_G_CPU0_SB_CA<2>")
	)
	(segment
		(start 417.700714 -251.673106)
		(end 417.700714 -251.86513)
		(width 0.18288)
		(layer "In4.Cu")
		(net "M_G_CPU0_SB_CA<2>")
	)
	(segment
		(start 430.99609 -251.509276)
		(end 430.72304 -251.236226)
		(width 0.18288)
		(layer "In4.Cu")
		(net "M_G_CPU0_SB_CA<2>")
	)
	(segment
		(start 408.783028 -251.464826)
		(end 408.549348 -251.231146)
		(width 0.18288)
		(layer "In4.Cu")
		(net "M_G_CPU0_SB_CA<2>")
	)
	(segment
		(start 405.866854 -251.231146)
		(end 401.09267 -249.253502)
		(width 0.18288)
		(layer "In4.Cu")
		(net "M_G_CPU0_SB_CA<2>")
	)
	(segment
		(start 426.20057 -252.288802)
		(end 425.204382 -251.292614)
		(width 0.18288)
		(layer "In4.Cu")
		(net "M_G_CPU0_SB_CA<2>")
	)
	(segment
		(start 427.28261 -252.471682)
		(end 427.28261 -252.884686)
		(width 0.18288)
		(layer "In4.Cu")
		(net "M_G_CPU0_SB_CA<2>")
	)
	(segment
		(start 385.500372 -249.371866)
		(end 385.499864 -249.371358)
		(width 0.088646)
		(layer "In4.Cu")
		(net "M_G_CPU0_SB_CA<2>")
	)
	(segment
		(start 430.72304 -251.236226)
		(end 430.278794 -251.236226)
		(width 0.18288)
		(layer "In4.Cu")
		(net "M_G_CPU0_SB_CA<2>")
	)
	(segment
		(start 415.848292 -251.490226)
		(end 415.619692 -251.261626)
		(width 0.18288)
		(layer "In4.Cu")
		(net "M_G_CPU0_SB_CA<2>")
	)
	(segment
		(start 419.087554 -251.673106)
		(end 419.087554 -251.86513)
		(width 0.18288)
		(layer "In4.Cu")
		(net "M_G_CPU0_SB_CA<2>")
	)
	(segment
		(start 391.231374 -248.01068)
		(end 389.38962 -249.852434)
		(width 0.18288)
		(layer "In4.Cu")
		(net "M_G_CPU0_SB_CA<2>")
	)
	(segment
		(start 419.270434 -251.490226)
		(end 419.087554 -251.673106)
		(width 0.18288)
		(layer "In4.Cu")
		(net "M_G_CPU0_SB_CA<2>")
	)
	(segment
		(start 386.61721 -249.371866)
		(end 385.766818 -249.371866)
		(width 0.18288)
		(layer "In4.Cu")
		(net "M_G_CPU0_SB_CA<2>")
	)
	(segment
		(start 434.966364 -251.972826)
		(end 433.593494 -251.972826)
		(width 0.18288)
		(layer "In4.Cu")
		(net "M_G_CPU0_SB_CA<2>")
	)
	(segment
		(start 389.38962 -249.852434)
		(end 387.097778 -249.852434)
		(width 0.18288)
		(layer "In4.Cu")
		(net "M_G_CPU0_SB_CA<2>")
	)
	(segment
		(start 387.097778 -249.852434)
		(end 386.61721 -249.371866)
		(width 0.18288)
		(layer "In4.Cu")
		(net "M_G_CPU0_SB_CA<2>")
	)
	(segment
		(start 417.007294 -251.86513)
		(end 417.007294 -251.673106)
		(width 0.18288)
		(layer "In4.Cu")
		(net "M_G_CPU0_SB_CA<2>")
	)
	(segment
		(start 419.087554 -251.86513)
		(end 418.904674 -252.04801)
		(width 0.18288)
		(layer "In4.Cu")
		(net "M_G_CPU0_SB_CA<2>")
	)
	(segment
		(start 425.204382 -251.292614)
		(end 420.531544 -251.292614)
		(width 0.18288)
		(layer "In4.Cu")
		(net "M_G_CPU0_SB_CA<2>")
	)
	(segment
		(start 385.499864 -249.371358)
		(end 384.954526 -249.371358)
		(width 0.088646)
		(layer "In4.Cu")
		(net "M_G_CPU0_SB_CA<2>")
	)
	(segment
		(start 418.577014 -252.04801)
		(end 418.394134 -251.86513)
		(width 0.18288)
		(layer "In4.Cu")
		(net "M_G_CPU0_SB_CA<2>")
	)
	(segment
		(start 397.510508 -249.253502)
		(end 396.267686 -248.01068)
		(width 0.18288)
		(layer "In4.Cu")
		(net "M_G_CPU0_SB_CA<2>")
	)
	(segment
		(start 417.700714 -251.86513)
		(end 417.517834 -252.04801)
		(width 0.18288)
		(layer "In4.Cu")
		(net "M_G_CPU0_SB_CA<2>")
	)
	(segment
		(start 426.58919 -252.884686)
		(end 426.58919 -252.471682)
		(width 0.18288)
		(layer "In4.Cu")
		(net "M_G_CPU0_SB_CA<2>")
	)
	(segment
		(start 412.789116 -251.261626)
		(end 412.585916 -251.464826)
		(width 0.18288)
		(layer "In4.Cu")
		(net "M_G_CPU0_SB_CA<2>")
	)
	(segment
		(start 430.278794 -251.236226)
		(end 429.226218 -252.288802)
		(width 0.18288)
		(layer "In4.Cu")
		(net "M_G_CPU0_SB_CA<2>")
	)
	(arc
		(start 384.664204 -249.29084)
		(mid 384.575296 -249.256357)
		(end 384.480562 -249.245374)
		(width 0.088646)
		(layer "In4.Cu")
		(net "M_G_CPU0_SB_CA<2>")
	)
	(arc
		(start 381.852932 -249.295666)
		(mid 381.665734 -249.245523)
		(end 381.478536 -249.295666)
		(width 0.088646)
		(layer "In4.Cu")
		(net "M_G_CPU0_SB_CA<2>")
	)
	(arc
		(start 382.418336 -249.295666)
		(mid 382.135634 -249.371442)
		(end 381.852932 -249.295666)
		(width 0.088646)
		(layer "In4.Cu")
		(net "M_G_CPU0_SB_CA<2>")
	)
	(arc
		(start 381.478536 -249.295666)
		(mid 381.195834 -249.371442)
		(end 380.913132 -249.295666)
		(width 0.088646)
		(layer "In4.Cu")
		(net "M_G_CPU0_SB_CA<2>")
	)
	(arc
		(start 382.87071 -249.354848)
		(mid 382.83366 -249.322702)
		(end 382.792732 -249.295666)
		(width 0.088646)
		(layer "In4.Cu")
		(net "M_G_CPU0_SB_CA<2>")
	)
	(arc
		(start 379.973332 -249.295666)
		(mid 379.786134 -249.245523)
		(end 379.598936 -249.295666)
		(width 0.088646)
		(layer "In4.Cu")
		(net "M_G_CPU0_SB_CA<2>")
	)
	(arc
		(start 384.954526 -249.371358)
		(mid 384.803906 -249.350786)
		(end 384.664204 -249.29084)
		(width 0.088646)
		(layer "In4.Cu")
		(net "M_G_CPU0_SB_CA<2>")
	)
	(arc
		(start 379.033278 -249.295666)
		(mid 378.843695 -249.116596)
		(end 378.75464 -248.871486)
		(width 0.088646)
		(layer "In4.Cu")
		(net "M_G_CPU0_SB_CA<2>")
	)
	(arc
		(start 382.792732 -249.295666)
		(mid 382.605534 -249.245523)
		(end 382.418336 -249.295666)
		(width 0.088646)
		(layer "In4.Cu")
		(net "M_G_CPU0_SB_CA<2>")
	)
	(arc
		(start 380.913132 -249.295666)
		(mid 380.725934 -249.245523)
		(end 380.538736 -249.295666)
		(width 0.088646)
		(layer "In4.Cu")
		(net "M_G_CPU0_SB_CA<2>")
	)
	(arc
		(start 379.588522 -249.301762)
		(mid 379.31009 -249.371608)
		(end 379.033278 -249.295666)
		(width 0.088646)
		(layer "In4.Cu")
		(net "M_G_CPU0_SB_CA<2>")
	)
	(arc
		(start 380.538736 -249.295666)
		(mid 380.256034 -249.371442)
		(end 379.973332 -249.295666)
		(width 0.088646)
		(layer "In4.Cu")
		(net "M_G_CPU0_SB_CA<2>")
	)
	(segment
		(start 445.47536 -252.141736)
		(end 445.482726 -252.149102)
		(width 0.1016)
		(layer "F.Cu")
		(net "M_G_CPU0_SB_CA<1>")
	)
	(segment
		(start 447.45783 -251.716794)
		(end 448.572382 -251.716794)
		(width 0.20066)
		(layer "F.Cu")
		(net "M_G_CPU0_SB_CA<1>")
	)
	(segment
		(start 443.46622 -252.141736)
		(end 445.47536 -252.141736)
		(width 0.1016)
		(layer "F.Cu")
		(net "M_G_CPU0_SB_CA<1>")
	)
	(segment
		(start 439.923682 -251.716794)
		(end 441.028582 -251.716794)
		(width 0.20066)
		(layer "F.Cu")
		(net "M_G_CPU0_SB_CA<1>")
	)
	(segment
		(start 443.450726 -252.152404)
		(end 443.455552 -252.152404)
		(width 0.101854)
		(layer "F.Cu")
		(net "M_G_CPU0_SB_CA<1>")
	)
	(segment
		(start 443.099952 -252.152404)
		(end 443.450726 -252.152404)
		(width 0.20066)
		(layer "F.Cu")
		(net "M_G_CPU0_SB_CA<1>")
	)
	(segment
		(start 445.756792 -252.149102)
		(end 446.621662 -251.284232)
		(width 0.20066)
		(layer "F.Cu")
		(net "M_G_CPU0_SB_CA<1>")
	)
	(segment
		(start 443.455552 -252.152404)
		(end 443.46622 -252.141736)
		(width 0.1016)
		(layer "F.Cu")
		(net "M_G_CPU0_SB_CA<1>")
	)
	(segment
		(start 445.482726 -252.149102)
		(end 445.756792 -252.149102)
		(width 0.20066)
		(layer "F.Cu")
		(net "M_G_CPU0_SB_CA<1>")
	)
	(segment
		(start 376.49658 -249.342148)
		(end 376.49658 -248.806462)
		(width 0.20066)
		(layer "F.Cu")
		(net "M_G_CPU0_SB_CA<1>")
	)
	(segment
		(start 442.664342 -251.716794)
		(end 443.099952 -252.152404)
		(width 0.20066)
		(layer "F.Cu")
		(net "M_G_CPU0_SB_CA<1>")
	)
	(segment
		(start 441.028582 -251.716794)
		(end 442.664342 -251.716794)
		(width 0.20066)
		(layer "F.Cu")
		(net "M_G_CPU0_SB_CA<1>")
	)
	(segment
		(start 376.49658 -248.806462)
		(end 376.496834 -248.806208)
		(width 0.20066)
		(layer "F.Cu")
		(net "M_G_CPU0_SB_CA<1>")
	)
	(segment
		(start 447.025268 -251.284232)
		(end 447.45783 -251.716794)
		(width 0.20066)
		(layer "F.Cu")
		(net "M_G_CPU0_SB_CA<1>")
	)
	(segment
		(start 446.621662 -251.284232)
		(end 447.025268 -251.284232)
		(width 0.20066)
		(layer "F.Cu")
		(net "M_G_CPU0_SB_CA<1>")
	)
	(segment
		(start 439.923682 -251.716794)
		(end 439.174636 -252.46584)
		(width 0.18288)
		(layer "In4.Cu")
		(net "M_G_CPU0_SB_CA<1>")
	)
	(segment
		(start 377.636278 -249.97664)
		(end 377.531884 -249.872246)
		(width 0.088646)
		(layer "In4.Cu")
		(net "M_G_CPU0_SB_CA<1>")
	)
	(segment
		(start 432.782218 -252.02515)
		(end 431.534062 -252.02515)
		(width 0.18288)
		(layer "In4.Cu")
		(net "M_G_CPU0_SB_CA<1>")
	)
	(segment
		(start 401.045934 -249.823732)
		(end 397.354552 -249.823732)
		(width 0.18288)
		(layer "In4.Cu")
		(net "M_G_CPU0_SB_CA<1>")
	)
	(segment
		(start 430.278794 -252.353826)
		(end 429.059594 -253.573026)
		(width 0.18288)
		(layer "In4.Cu")
		(net "M_G_CPU0_SB_CA<1>")
	)
	(segment
		(start 424.98518 -252.142498)
		(end 424.633644 -252.142498)
		(width 0.18288)
		(layer "In4.Cu")
		(net "M_G_CPU0_SB_CA<1>")
	)
	(segment
		(start 377.76277 -250.103132)
		(end 377.636278 -249.97664)
		(width 0.18288)
		(layer "In4.Cu")
		(net "M_G_CPU0_SB_CA<1>")
	)
	(segment
		(start 419.890194 -252.557026)
		(end 409.83154 -252.557026)
		(width 0.18288)
		(layer "In4.Cu")
		(net "M_G_CPU0_SB_CA<1>")
	)
	(segment
		(start 397.354552 -249.823732)
		(end 395.87678 -248.34596)
		(width 0.18288)
		(layer "In4.Cu")
		(net "M_G_CPU0_SB_CA<1>")
	)
	(segment
		(start 386.33527 -249.724926)
		(end 385.880864 -249.724926)
		(width 0.18288)
		(layer "In4.Cu")
		(net "M_G_CPU0_SB_CA<1>")
	)
	(segment
		(start 436.235094 -252.140974)
		(end 435.562502 -252.140974)
		(width 0.18288)
		(layer "In4.Cu")
		(net "M_G_CPU0_SB_CA<1>")
	)
	(segment
		(start 404.478744 -251.245624)
		(end 401.045934 -249.823732)
		(width 0.18288)
		(layer "In4.Cu")
		(net "M_G_CPU0_SB_CA<1>")
	)
	(segment
		(start 385.880864 -249.724926)
		(end 385.502658 -250.103132)
		(width 0.18288)
		(layer "In4.Cu")
		(net "M_G_CPU0_SB_CA<1>")
	)
	(segment
		(start 431.534062 -252.02515)
		(end 431.205386 -252.353826)
		(width 0.18288)
		(layer "In4.Cu")
		(net "M_G_CPU0_SB_CA<1>")
	)
	(segment
		(start 429.059594 -253.573026)
		(end 426.54474 -253.573026)
		(width 0.18288)
		(layer "In4.Cu")
		(net "M_G_CPU0_SB_CA<1>")
	)
	(segment
		(start 436.55996 -252.46584)
		(end 436.235094 -252.140974)
		(width 0.18288)
		(layer "In4.Cu")
		(net "M_G_CPU0_SB_CA<1>")
	)
	(segment
		(start 439.174636 -252.46584)
		(end 436.55996 -252.46584)
		(width 0.18288)
		(layer "In4.Cu")
		(net "M_G_CPU0_SB_CA<1>")
	)
	(segment
		(start 409.259532 -251.985018)
		(end 408.295602 -251.985018)
		(width 0.18288)
		(layer "In4.Cu")
		(net "M_G_CPU0_SB_CA<1>")
	)
	(segment
		(start 386.83946 -250.229116)
		(end 386.33527 -249.724926)
		(width 0.18288)
		(layer "In4.Cu")
		(net "M_G_CPU0_SB_CA<1>")
	)
	(segment
		(start 431.205386 -252.353826)
		(end 430.278794 -252.353826)
		(width 0.18288)
		(layer "In4.Cu")
		(net "M_G_CPU0_SB_CA<1>")
	)
	(segment
		(start 409.83154 -252.557026)
		(end 409.259532 -251.985018)
		(width 0.18288)
		(layer "In4.Cu")
		(net "M_G_CPU0_SB_CA<1>")
	)
	(segment
		(start 435.562502 -252.140974)
		(end 435.22265 -252.480826)
		(width 0.18288)
		(layer "In4.Cu")
		(net "M_G_CPU0_SB_CA<1>")
	)
	(segment
		(start 389.59917 -250.229116)
		(end 386.83946 -250.229116)
		(width 0.18288)
		(layer "In4.Cu")
		(net "M_G_CPU0_SB_CA<1>")
	)
	(segment
		(start 391.482326 -248.34596)
		(end 389.59917 -250.229116)
		(width 0.18288)
		(layer "In4.Cu")
		(net "M_G_CPU0_SB_CA<1>")
	)
	(segment
		(start 385.502658 -250.103132)
		(end 377.76277 -250.103132)
		(width 0.18288)
		(layer "In4.Cu")
		(net "M_G_CPU0_SB_CA<1>")
	)
	(segment
		(start 425.114466 -252.142752)
		(end 424.985434 -252.142752)
		(width 0.18288)
		(layer "In4.Cu")
		(net "M_G_CPU0_SB_CA<1>")
	)
	(segment
		(start 424.985434 -252.142752)
		(end 424.98518 -252.142498)
		(width 0.18288)
		(layer "In4.Cu")
		(net "M_G_CPU0_SB_CA<1>")
	)
	(segment
		(start 426.54474 -253.573026)
		(end 425.114466 -252.142752)
		(width 0.18288)
		(layer "In4.Cu")
		(net "M_G_CPU0_SB_CA<1>")
	)
	(segment
		(start 408.024584 -252.256036)
		(end 405.489156 -252.256036)
		(width 0.18288)
		(layer "In4.Cu")
		(net "M_G_CPU0_SB_CA<1>")
	)
	(segment
		(start 405.489156 -252.256036)
		(end 404.478744 -251.245624)
		(width 0.18288)
		(layer "In4.Cu")
		(net "M_G_CPU0_SB_CA<1>")
	)
	(segment
		(start 435.22265 -252.480826)
		(end 433.237894 -252.480826)
		(width 0.18288)
		(layer "In4.Cu")
		(net "M_G_CPU0_SB_CA<1>")
	)
	(segment
		(start 421.52062 -252.142752)
		(end 421.520366 -252.142498)
		(width 0.18288)
		(layer "In4.Cu")
		(net "M_G_CPU0_SB_CA<1>")
	)
	(segment
		(start 420.60368 -252.142752)
		(end 420.304468 -252.142752)
		(width 0.18288)
		(layer "In4.Cu")
		(net "M_G_CPU0_SB_CA<1>")
	)
	(segment
		(start 424.63339 -252.142752)
		(end 421.52062 -252.142752)
		(width 0.18288)
		(layer "In4.Cu")
		(net "M_G_CPU0_SB_CA<1>")
	)
	(segment
		(start 433.237894 -252.480826)
		(end 432.782218 -252.02515)
		(width 0.18288)
		(layer "In4.Cu")
		(net "M_G_CPU0_SB_CA<1>")
	)
	(segment
		(start 420.304468 -252.142752)
		(end 419.890194 -252.557026)
		(width 0.18288)
		(layer "In4.Cu")
		(net "M_G_CPU0_SB_CA<1>")
	)
	(segment
		(start 408.295602 -251.985018)
		(end 408.024584 -252.256036)
		(width 0.18288)
		(layer "In4.Cu")
		(net "M_G_CPU0_SB_CA<1>")
	)
	(segment
		(start 420.603934 -252.142498)
		(end 420.60368 -252.142752)
		(width 0.18288)
		(layer "In4.Cu")
		(net "M_G_CPU0_SB_CA<1>")
	)
	(segment
		(start 421.520366 -252.142498)
		(end 420.603934 -252.142498)
		(width 0.18288)
		(layer "In4.Cu")
		(net "M_G_CPU0_SB_CA<1>")
	)
	(segment
		(start 395.87678 -248.34596)
		(end 391.482326 -248.34596)
		(width 0.18288)
		(layer "In4.Cu")
		(net "M_G_CPU0_SB_CA<1>")
	)
	(segment
		(start 377.255278 -249.134122)
		(end 376.867674 -248.906792)
		(width 0.088646)
		(layer "In4.Cu")
		(net "M_G_CPU0_SB_CA<1>")
	)
	(segment
		(start 424.633644 -252.142498)
		(end 424.63339 -252.142752)
		(width 0.18288)
		(layer "In4.Cu")
		(net "M_G_CPU0_SB_CA<1>")
	)
	(segment
		(start 377.531884 -249.872246)
		(end 377.531884 -249.620024)
		(width 0.088646)
		(layer "In4.Cu")
		(net "M_G_CPU0_SB_CA<1>")
	)
	(arc
		(start 377.531884 -249.620024)
		(mid 377.457893 -249.340458)
		(end 377.255278 -249.134122)
		(width 0.088646)
		(layer "In4.Cu")
		(net "M_G_CPU0_SB_CA<1>")
	)
	(arc
		(start 376.867674 -248.906792)
		(mid 376.688955 -248.83179)
		(end 376.496834 -248.806208)
		(width 0.088646)
		(layer "In4.Cu")
		(net "M_G_CPU0_SB_CA<1>")
	)
	(segment
		(start 376.026934 -248.528078)
		(end 376.02668 -248.527824)
		(width 0.20066)
		(layer "F.Cu")
		(net "M_G_CPU0_SB_CA<0>")
	)
	(segment
		(start 439.918856 -253.17958)
		(end 442.758322 -253.17958)
		(width 0.20066)
		(layer "F.Cu")
		(net "M_G_CPU0_SB_CA<0>")
	)
	(segment
		(start 436.928514 -252.566678)
		(end 438.150762 -252.566678)
		(width 0.20066)
		(layer "F.Cu")
		(net "M_G_CPU0_SB_CA<0>")
	)
	(segment
		(start 442.758322 -253.17958)
		(end 443.371224 -252.566678)
		(width 0.20066)
		(layer "F.Cu")
		(net "M_G_CPU0_SB_CA<0>")
	)
	(segment
		(start 443.371224 -252.566678)
		(end 444.472314 -252.566678)
		(width 0.20066)
		(layer "F.Cu")
		(net "M_G_CPU0_SB_CA<0>")
	)
	(segment
		(start 439.001408 -252.262132)
		(end 439.918856 -253.17958)
		(width 0.20066)
		(layer "F.Cu")
		(net "M_G_CPU0_SB_CA<0>")
	)
	(segment
		(start 435.823614 -252.566678)
		(end 436.928514 -252.566678)
		(width 0.20066)
		(layer "F.Cu")
		(net "M_G_CPU0_SB_CA<0>")
	)
	(segment
		(start 438.455308 -252.262132)
		(end 439.001408 -252.262132)
		(width 0.20066)
		(layer "F.Cu")
		(net "M_G_CPU0_SB_CA<0>")
	)
	(segment
		(start 438.150762 -252.566678)
		(end 438.455308 -252.262132)
		(width 0.20066)
		(layer "F.Cu")
		(net "M_G_CPU0_SB_CA<0>")
	)
	(segment
		(start 376.02668 -248.527824)
		(end 376.02668 -247.992138)
		(width 0.20066)
		(layer "F.Cu")
		(net "M_G_CPU0_SB_CA<0>")
	)
	(segment
		(start 405.280368 -252.785626)
		(end 404.16861 -251.673868)
		(width 0.18288)
		(layer "In4.Cu")
		(net "M_G_CPU0_SB_CA<0>")
	)
	(segment
		(start 377.294902 -250.402852)
		(end 377.294902 -250.050046)
		(width 0.18288)
		(layer "In4.Cu")
		(net "M_G_CPU0_SB_CA<0>")
	)
	(segment
		(start 431.053494 -252.912626)
		(end 430.481994 -252.912626)
		(width 0.18288)
		(layer "In4.Cu")
		(net "M_G_CPU0_SB_CA<0>")
	)
	(segment
		(start 414.922716 -253.10592)
		(end 414.446466 -253.58217)
		(width 0.18288)
		(layer "In4.Cu")
		(net "M_G_CPU0_SB_CA<0>")
	)
	(segment
		(start 389.898636 -250.63069)
		(end 377.52274 -250.63069)
		(width 0.18288)
		(layer "In4.Cu")
		(net "M_G_CPU0_SB_CA<0>")
	)
	(segment
		(start 376.026934 -249.041666)
		(end 376.026934 -248.367296)
		(width 0.088646)
		(layer "In4.Cu")
		(net "M_G_CPU0_SB_CA<0>")
	)
	(segment
		(start 391.848086 -248.68124)
		(end 389.898636 -250.63069)
		(width 0.18288)
		(layer "In4.Cu")
		(net "M_G_CPU0_SB_CA<0>")
	)
	(segment
		(start 411.688788 -253.58217)
		(end 410.67101 -253.58217)
		(width 0.18288)
		(layer "In4.Cu")
		(net "M_G_CPU0_SB_CA<0>")
	)
	(segment
		(start 376.02668 -248.367042)
		(end 376.02668 -247.992138)
		(width 0.088646)
		(layer "In4.Cu")
		(net "M_G_CPU0_SB_CA<0>")
	)
	(segment
		(start 395.497812 -248.68124)
		(end 391.848086 -248.68124)
		(width 0.18288)
		(layer "In4.Cu")
		(net "M_G_CPU0_SB_CA<0>")
	)
	(segment
		(start 376.316494 -249.331226)
		(end 376.026934 -249.041666)
		(width 0.088646)
		(layer "In4.Cu")
		(net "M_G_CPU0_SB_CA<0>")
	)
	(segment
		(start 410.67101 -253.58217)
		(end 410.19476 -253.10592)
		(width 0.18288)
		(layer "In4.Cu")
		(net "M_G_CPU0_SB_CA<0>")
	)
	(segment
		(start 429.237394 -254.157226)
		(end 425.986194 -254.157226)
		(width 0.18288)
		(layer "In4.Cu")
		(net "M_G_CPU0_SB_CA<0>")
	)
	(segment
		(start 431.295556 -253.154688)
		(end 431.053494 -252.912626)
		(width 0.18288)
		(layer "In4.Cu")
		(net "M_G_CPU0_SB_CA<0>")
	)
	(segment
		(start 425.986194 -254.157226)
		(end 424.934888 -253.10592)
		(width 0.18288)
		(layer "In4.Cu")
		(net "M_G_CPU0_SB_CA<0>")
	)
	(segment
		(start 377.341384 -249.780806)
		(end 377.341384 -249.624596)
		(width 0.088646)
		(layer "In4.Cu")
		(net "M_G_CPU0_SB_CA<0>")
	)
	(segment
		(start 435.823614 -252.566678)
		(end 435.823614 -252.948694)
		(width 0.18288)
		(layer "In4.Cu")
		(net "M_G_CPU0_SB_CA<0>")
	)
	(segment
		(start 435.61762 -253.154688)
		(end 431.295556 -253.154688)
		(width 0.18288)
		(layer "In4.Cu")
		(net "M_G_CPU0_SB_CA<0>")
	)
	(segment
		(start 376.026934 -248.367296)
		(end 376.02668 -248.367042)
		(width 0.088646)
		(layer "In4.Cu")
		(net "M_G_CPU0_SB_CA<0>")
	)
	(segment
		(start 424.934888 -253.10592)
		(end 414.922716 -253.10592)
		(width 0.18288)
		(layer "In4.Cu")
		(net "M_G_CPU0_SB_CA<0>")
	)
	(segment
		(start 412.639256 -253.214378)
		(end 412.05658 -253.214378)
		(width 0.18288)
		(layer "In4.Cu")
		(net "M_G_CPU0_SB_CA<0>")
	)
	(segment
		(start 377.52274 -250.63069)
		(end 377.294902 -250.402852)
		(width 0.18288)
		(layer "In4.Cu")
		(net "M_G_CPU0_SB_CA<0>")
	)
	(segment
		(start 377.294902 -250.050046)
		(end 377.294902 -249.827288)
		(width 0.088646)
		(layer "In4.Cu")
		(net "M_G_CPU0_SB_CA<0>")
	)
	(segment
		(start 413.007048 -253.58217)
		(end 412.639256 -253.214378)
		(width 0.18288)
		(layer "In4.Cu")
		(net "M_G_CPU0_SB_CA<0>")
	)
	(segment
		(start 414.446466 -253.58217)
		(end 413.007048 -253.58217)
		(width 0.18288)
		(layer "In4.Cu")
		(net "M_G_CPU0_SB_CA<0>")
	)
	(segment
		(start 408.203146 -252.785626)
		(end 405.280368 -252.785626)
		(width 0.18288)
		(layer "In4.Cu")
		(net "M_G_CPU0_SB_CA<0>")
	)
	(segment
		(start 397.254222 -250.43765)
		(end 395.497812 -248.68124)
		(width 0.18288)
		(layer "In4.Cu")
		(net "M_G_CPU0_SB_CA<0>")
	)
	(segment
		(start 408.52344 -253.10592)
		(end 408.203146 -252.785626)
		(width 0.18288)
		(layer "In4.Cu")
		(net "M_G_CPU0_SB_CA<0>")
	)
	(segment
		(start 410.19476 -253.10592)
		(end 408.52344 -253.10592)
		(width 0.18288)
		(layer "In4.Cu")
		(net "M_G_CPU0_SB_CA<0>")
	)
	(segment
		(start 435.823614 -252.948694)
		(end 435.61762 -253.154688)
		(width 0.18288)
		(layer "In4.Cu")
		(net "M_G_CPU0_SB_CA<0>")
	)
	(segment
		(start 412.05658 -253.214378)
		(end 411.688788 -253.58217)
		(width 0.18288)
		(layer "In4.Cu")
		(net "M_G_CPU0_SB_CA<0>")
	)
	(segment
		(start 430.481994 -252.912626)
		(end 429.237394 -254.157226)
		(width 0.18288)
		(layer "In4.Cu")
		(net "M_G_CPU0_SB_CA<0>")
	)
	(segment
		(start 377.152408 -249.294396)
		(end 377.08332 -249.25401)
		(width 0.088646)
		(layer "In4.Cu")
		(net "M_G_CPU0_SB_CA<0>")
	)
	(segment
		(start 401.18411 -250.43765)
		(end 397.254222 -250.43765)
		(width 0.18288)
		(layer "In4.Cu")
		(net "M_G_CPU0_SB_CA<0>")
	)
	(segment
		(start 377.294902 -249.827288)
		(end 377.341384 -249.780806)
		(width 0.088646)
		(layer "In4.Cu")
		(net "M_G_CPU0_SB_CA<0>")
	)
	(segment
		(start 376.646694 -249.331226)
		(end 376.316494 -249.331226)
		(width 0.088646)
		(layer "In4.Cu")
		(net "M_G_CPU0_SB_CA<0>")
	)
	(segment
		(start 404.16861 -251.673868)
		(end 401.18411 -250.43765)
		(width 0.18288)
		(layer "In4.Cu")
		(net "M_G_CPU0_SB_CA<0>")
	)
	(arc
		(start 377.08332 -249.25401)
		(mid 377.043006 -249.234714)
		(end 377.000008 -249.222514)
		(width 0.088646)
		(layer "In4.Cu")
		(net "M_G_CPU0_SB_CA<0>")
	)
	(arc
		(start 377.224036 -249.347736)
		(mid 377.189747 -249.319019)
		(end 377.152408 -249.294396)
		(width 0.088646)
		(layer "In4.Cu")
		(net "M_G_CPU0_SB_CA<0>")
	)
	(arc
		(start 377.000008 -249.222514)
		(mid 376.809812 -249.232917)
		(end 376.646694 -249.331226)
		(width 0.088646)
		(layer "In4.Cu")
		(net "M_G_CPU0_SB_CA<0>")
	)
	(arc
		(start 377.331478 -249.53595)
		(mid 377.291697 -249.433879)
		(end 377.224036 -249.347736)
		(width 0.088646)
		(layer "In4.Cu")
		(net "M_G_CPU0_SB_CA<0>")
	)
	(arc
		(start 377.341384 -249.624596)
		(mid 377.338941 -249.579993)
		(end 377.331478 -249.53595)
		(width 0.088646)
		(layer "In4.Cu")
		(net "M_G_CPU0_SB_CA<0>")
	)
	(segment
		(start 436.928514 -244.066568)
		(end 435.823614 -244.066568)
		(width 0.20066)
		(layer "F.Cu")
		(net "M_G_CPU0_SA_RSP<1>")
	)
	(segment
		(start 379.425962 -253.383796)
		(end 379.425962 -253.919736)
		(width 0.20066)
		(layer "F.Cu")
		(net "M_G_CPU0_SA_RSP<1>")
	)
	(segment
		(start 412.27375 -250.37669)
		(end 411.373828 -250.37669)
		(width 0.18288)
		(layer "In6.Cu")
		(net "M_G_CPU0_SA_RSP<1>")
	)
	(segment
		(start 411.213808 -250.53671)
		(end 411.213808 -251.393198)
		(width 0.18288)
		(layer "In6.Cu")
		(net "M_G_CPU0_SA_RSP<1>")
	)
	(segment
		(start 407.098754 -251.247402)
		(end 407.098754 -251.609606)
		(width 0.18288)
		(layer "In6.Cu")
		(net "M_G_CPU0_SA_RSP<1>")
	)
	(segment
		(start 406.335484 -251.609606)
		(end 406.335484 -251.247402)
		(width 0.18288)
		(layer "In6.Cu")
		(net "M_G_CPU0_SA_RSP<1>")
	)
	(segment
		(start 406.495504 -251.769626)
		(end 406.335484 -251.609606)
		(width 0.18288)
		(layer "In6.Cu")
		(net "M_G_CPU0_SA_RSP<1>")
	)
	(segment
		(start 412.58109 -250.68403)
		(end 412.27375 -250.37669)
		(width 0.18288)
		(layer "In6.Cu")
		(net "M_G_CPU0_SA_RSP<1>")
	)
	(segment
		(start 414.423098 -249.43689)
		(end 413.175958 -250.68403)
		(width 0.18288)
		(layer "In6.Cu")
		(net "M_G_CPU0_SA_RSP<1>")
	)
	(segment
		(start 397.918178 -252.144784)
		(end 395.358112 -254.70485)
		(width 0.18288)
		(layer "In6.Cu")
		(net "M_G_CPU0_SA_RSP<1>")
	)
	(segment
		(start 411.053788 -251.553218)
		(end 410.634434 -251.553218)
		(width 0.18288)
		(layer "In6.Cu")
		(net "M_G_CPU0_SA_RSP<1>")
	)
	(segment
		(start 427.60519 -247.967246)
		(end 426.417994 -247.967246)
		(width 0.18288)
		(layer "In6.Cu")
		(net "M_G_CPU0_SA_RSP<1>")
	)
	(segment
		(start 392.214862 -254.261366)
		(end 390.780524 -252.827028)
		(width 0.18288)
		(layer "In6.Cu")
		(net "M_G_CPU0_SA_RSP<1>")
	)
	(segment
		(start 405.004524 -251.621798)
		(end 404.844504 -251.781818)
		(width 0.18288)
		(layer "In6.Cu")
		(net "M_G_CPU0_SA_RSP<1>")
	)
	(segment
		(start 425.64304 -248.7422)
		(end 417.791138 -248.7422)
		(width 0.18288)
		(layer "In6.Cu")
		(net "M_G_CPU0_SA_RSP<1>")
	)
	(segment
		(start 408.798522 -251.087382)
		(end 407.258774 -251.087382)
		(width 0.18288)
		(layer "In6.Cu")
		(net "M_G_CPU0_SA_RSP<1>")
	)
	(segment
		(start 409.509214 -250.37669)
		(end 408.798522 -251.087382)
		(width 0.18288)
		(layer "In6.Cu")
		(net "M_G_CPU0_SA_RSP<1>")
	)
	(segment
		(start 393.7127 -254.70485)
		(end 392.890756 -254.541528)
		(width 0.18288)
		(layer "In6.Cu")
		(net "M_G_CPU0_SA_RSP<1>")
	)
	(segment
		(start 413.175958 -250.68403)
		(end 412.58109 -250.68403)
		(width 0.18288)
		(layer "In6.Cu")
		(net "M_G_CPU0_SA_RSP<1>")
	)
	(segment
		(start 407.258774 -251.087382)
		(end 407.098754 -251.247402)
		(width 0.18288)
		(layer "In6.Cu")
		(net "M_G_CPU0_SA_RSP<1>")
	)
	(segment
		(start 392.890756 -254.541528)
		(end 392.214862 -254.261366)
		(width 0.18288)
		(layer "In6.Cu")
		(net "M_G_CPU0_SA_RSP<1>")
	)
	(segment
		(start 406.175464 -251.087382)
		(end 405.124412 -251.087382)
		(width 0.18288)
		(layer "In6.Cu")
		(net "M_G_CPU0_SA_RSP<1>")
	)
	(segment
		(start 411.213808 -251.393198)
		(end 411.053788 -251.553218)
		(width 0.18288)
		(layer "In6.Cu")
		(net "M_G_CPU0_SA_RSP<1>")
	)
	(segment
		(start 395.358112 -254.70485)
		(end 393.7127 -254.70485)
		(width 0.18288)
		(layer "In6.Cu")
		(net "M_G_CPU0_SA_RSP<1>")
	)
	(segment
		(start 410.474414 -251.393198)
		(end 410.474414 -250.549664)
		(width 0.18288)
		(layer "In6.Cu")
		(net "M_G_CPU0_SA_RSP<1>")
	)
	(segment
		(start 410.30144 -250.37669)
		(end 409.509214 -250.37669)
		(width 0.18288)
		(layer "In6.Cu")
		(net "M_G_CPU0_SA_RSP<1>")
	)
	(segment
		(start 406.335484 -251.247402)
		(end 406.175464 -251.087382)
		(width 0.18288)
		(layer "In6.Cu")
		(net "M_G_CPU0_SA_RSP<1>")
	)
	(segment
		(start 403.96668 -251.781818)
		(end 403.603714 -252.144784)
		(width 0.18288)
		(layer "In6.Cu")
		(net "M_G_CPU0_SA_RSP<1>")
	)
	(segment
		(start 379.191012 -253.278894)
		(end 379.191012 -253.684786)
		(width 0.18288)
		(layer "In6.Cu")
		(net "M_G_CPU0_SA_RSP<1>")
	)
	(segment
		(start 416.924998 -248.660666)
		(end 416.148774 -249.43689)
		(width 0.18288)
		(layer "In6.Cu")
		(net "M_G_CPU0_SA_RSP<1>")
	)
	(segment
		(start 379.191012 -253.684786)
		(end 379.425962 -253.919736)
		(width 0.18288)
		(layer "In6.Cu")
		(net "M_G_CPU0_SA_RSP<1>")
	)
	(segment
		(start 390.780524 -252.827028)
		(end 379.642878 -252.827028)
		(width 0.18288)
		(layer "In6.Cu")
		(net "M_G_CPU0_SA_RSP<1>")
	)
	(segment
		(start 405.124412 -251.087382)
		(end 405.004524 -251.20727)
		(width 0.18288)
		(layer "In6.Cu")
		(net "M_G_CPU0_SA_RSP<1>")
	)
	(segment
		(start 427.858174 -247.714262)
		(end 427.60519 -247.967246)
		(width 0.18288)
		(layer "In6.Cu")
		(net "M_G_CPU0_SA_RSP<1>")
	)
	(segment
		(start 410.474414 -250.549664)
		(end 410.30144 -250.37669)
		(width 0.18288)
		(layer "In6.Cu")
		(net "M_G_CPU0_SA_RSP<1>")
	)
	(segment
		(start 426.417994 -247.967246)
		(end 425.64304 -248.7422)
		(width 0.18288)
		(layer "In6.Cu")
		(net "M_G_CPU0_SA_RSP<1>")
	)
	(segment
		(start 435.823614 -244.066568)
		(end 434.986176 -244.904006)
		(width 0.18288)
		(layer "In6.Cu")
		(net "M_G_CPU0_SA_RSP<1>")
	)
	(segment
		(start 410.634434 -251.553218)
		(end 410.474414 -251.393198)
		(width 0.18288)
		(layer "In6.Cu")
		(net "M_G_CPU0_SA_RSP<1>")
	)
	(segment
		(start 379.642878 -252.827028)
		(end 379.191012 -253.278894)
		(width 0.18288)
		(layer "In6.Cu")
		(net "M_G_CPU0_SA_RSP<1>")
	)
	(segment
		(start 407.098754 -251.609606)
		(end 406.938734 -251.769626)
		(width 0.18288)
		(layer "In6.Cu")
		(net "M_G_CPU0_SA_RSP<1>")
	)
	(segment
		(start 417.709604 -248.660666)
		(end 416.924998 -248.660666)
		(width 0.18288)
		(layer "In6.Cu")
		(net "M_G_CPU0_SA_RSP<1>")
	)
	(segment
		(start 411.373828 -250.37669)
		(end 411.213808 -250.53671)
		(width 0.18288)
		(layer "In6.Cu")
		(net "M_G_CPU0_SA_RSP<1>")
	)
	(segment
		(start 431.388774 -247.714262)
		(end 427.858174 -247.714262)
		(width 0.18288)
		(layer "In6.Cu")
		(net "M_G_CPU0_SA_RSP<1>")
	)
	(segment
		(start 434.986176 -244.904006)
		(end 434.19903 -244.904006)
		(width 0.18288)
		(layer "In6.Cu")
		(net "M_G_CPU0_SA_RSP<1>")
	)
	(segment
		(start 403.603714 -252.144784)
		(end 397.918178 -252.144784)
		(width 0.18288)
		(layer "In6.Cu")
		(net "M_G_CPU0_SA_RSP<1>")
	)
	(segment
		(start 417.791138 -248.7422)
		(end 417.709604 -248.660666)
		(width 0.18288)
		(layer "In6.Cu")
		(net "M_G_CPU0_SA_RSP<1>")
	)
	(segment
		(start 434.19903 -244.904006)
		(end 431.388774 -247.714262)
		(width 0.18288)
		(layer "In6.Cu")
		(net "M_G_CPU0_SA_RSP<1>")
	)
	(segment
		(start 416.148774 -249.43689)
		(end 414.423098 -249.43689)
		(width 0.18288)
		(layer "In6.Cu")
		(net "M_G_CPU0_SA_RSP<1>")
	)
	(segment
		(start 405.004524 -251.20727)
		(end 405.004524 -251.621798)
		(width 0.18288)
		(layer "In6.Cu")
		(net "M_G_CPU0_SA_RSP<1>")
	)
	(segment
		(start 406.938734 -251.769626)
		(end 406.495504 -251.769626)
		(width 0.18288)
		(layer "In6.Cu")
		(net "M_G_CPU0_SA_RSP<1>")
	)
	(segment
		(start 404.844504 -251.781818)
		(end 403.96668 -251.781818)
		(width 0.18288)
		(layer "In6.Cu")
		(net "M_G_CPU0_SA_RSP<1>")
	)
	(segment
		(start 444.472314 -244.066568)
		(end 443.367414 -244.066568)
		(width 0.20066)
		(layer "F.Cu")
		(net "M_G_CPU0_SA_RSP<0>")
	)
	(segment
		(start 379.896116 -254.733298)
		(end 379.89637 -254.733552)
		(width 0.20066)
		(layer "F.Cu")
		(net "M_G_CPU0_SA_RSP<0>")
	)
	(segment
		(start 379.896116 -254.197612)
		(end 379.896116 -254.733298)
		(width 0.20066)
		(layer "F.Cu")
		(net "M_G_CPU0_SA_RSP<0>")
	)
	(segment
		(start 429.210724 -250.64593)
		(end 429.027844 -250.46305)
		(width 0.18288)
		(layer "In6.Cu")
		(net "M_G_CPU0_SA_RSP<0>")
	)
	(segment
		(start 433.114958 -248.273062)
		(end 430.277524 -249.44832)
		(width 0.18288)
		(layer "In6.Cu")
		(net "M_G_CPU0_SA_RSP<0>")
	)
	(segment
		(start 381.271526 -253.40437)
		(end 380.835916 -253.83998)
		(width 0.088646)
		(layer "In6.Cu")
		(net "M_G_CPU0_SA_RSP<0>")
	)
	(segment
		(start 403.507702 -254.102362)
		(end 397.751808 -254.102362)
		(width 0.18288)
		(layer "In6.Cu")
		(net "M_G_CPU0_SA_RSP<0>")
	)
	(segment
		(start 392.645138 -255.42875)
		(end 391.703306 -255.038606)
		(width 0.18288)
		(layer "In6.Cu")
		(net "M_G_CPU0_SA_RSP<0>")
	)
	(segment
		(start 429.027844 -249.6312)
		(end 428.844964 -249.44832)
		(width 0.18288)
		(layer "In6.Cu")
		(net "M_G_CPU0_SA_RSP<0>")
	)
	(segment
		(start 434.345842 -247.042178)
		(end 433.114958 -248.273062)
		(width 0.18288)
		(layer "In6.Cu")
		(net "M_G_CPU0_SA_RSP<0>")
	)
	(segment
		(start 443.367414 -244.066568)
		(end 443.342014 -244.066568)
		(width 0.18288)
		(layer "In6.Cu")
		(net "M_G_CPU0_SA_RSP<0>")
	)
	(segment
		(start 415.317178 -251.12599)
		(end 413.429196 -253.013972)
		(width 0.18288)
		(layer "In6.Cu")
		(net "M_G_CPU0_SA_RSP<0>")
	)
	(segment
		(start 416.24377 -251.12599)
		(end 415.317178 -251.12599)
		(width 0.18288)
		(layer "In6.Cu")
		(net "M_G_CPU0_SA_RSP<0>")
	)
	(segment
		(start 443.078362 -244.33022)
		(end 440.161934 -246.192294)
		(width 0.18288)
		(layer "In6.Cu")
		(net "M_G_CPU0_SA_RSP<0>")
	)
	(segment
		(start 393.775438 -255.65354)
		(end 392.645138 -255.42875)
		(width 0.18288)
		(layer "In6.Cu")
		(net "M_G_CPU0_SA_RSP<0>")
	)
	(segment
		(start 385.332986 -253.57201)
		(end 385.274566 -253.51359)
		(width 0.088646)
		(layer "In6.Cu")
		(net "M_G_CPU0_SA_RSP<0>")
	)
	(segment
		(start 430.277524 -249.44832)
		(end 429.904144 -249.44832)
		(width 0.18288)
		(layer "In6.Cu")
		(net "M_G_CPU0_SA_RSP<0>")
	)
	(segment
		(start 380.835916 -254.105156)
		(end 380.566676 -254.374396)
		(width 0.088646)
		(layer "In6.Cu")
		(net "M_G_CPU0_SA_RSP<0>")
	)
	(segment
		(start 428.844964 -249.44832)
		(end 427.825916 -249.44832)
		(width 0.18288)
		(layer "In6.Cu")
		(net "M_G_CPU0_SA_RSP<0>")
	)
	(segment
		(start 429.538384 -250.64593)
		(end 429.210724 -250.64593)
		(width 0.18288)
		(layer "In6.Cu")
		(net "M_G_CPU0_SA_RSP<0>")
	)
	(segment
		(start 383.824226 -253.51359)
		(end 383.715006 -253.40437)
		(width 0.088646)
		(layer "In6.Cu")
		(net "M_G_CPU0_SA_RSP<0>")
	)
	(segment
		(start 397.751808 -254.102362)
		(end 396.20063 -255.65354)
		(width 0.18288)
		(layer "In6.Cu")
		(net "M_G_CPU0_SA_RSP<0>")
	)
	(segment
		(start 396.20063 -255.65354)
		(end 393.775438 -255.65354)
		(width 0.18288)
		(layer "In6.Cu")
		(net "M_G_CPU0_SA_RSP<0>")
	)
	(segment
		(start 416.927538 -250.442222)
		(end 416.24377 -251.12599)
		(width 0.18288)
		(layer "In6.Cu")
		(net "M_G_CPU0_SA_RSP<0>")
	)
	(segment
		(start 440.161934 -246.192294)
		(end 439.595514 -246.192294)
		(width 0.18288)
		(layer "In6.Cu")
		(net "M_G_CPU0_SA_RSP<0>")
	)
	(segment
		(start 429.027844 -250.46305)
		(end 429.027844 -249.6312)
		(width 0.18288)
		(layer "In6.Cu")
		(net "M_G_CPU0_SA_RSP<0>")
	)
	(segment
		(start 385.274566 -253.51359)
		(end 383.824226 -253.51359)
		(width 0.088646)
		(layer "In6.Cu")
		(net "M_G_CPU0_SA_RSP<0>")
	)
	(segment
		(start 404.596092 -253.013972)
		(end 403.507702 -254.102362)
		(width 0.18288)
		(layer "In6.Cu")
		(net "M_G_CPU0_SA_RSP<0>")
	)
	(segment
		(start 380.835916 -253.83998)
		(end 380.835916 -254.105156)
		(width 0.088646)
		(layer "In6.Cu")
		(net "M_G_CPU0_SA_RSP<0>")
	)
	(segment
		(start 429.721264 -249.6312)
		(end 429.721264 -250.46305)
		(width 0.18288)
		(layer "In6.Cu")
		(net "M_G_CPU0_SA_RSP<0>")
	)
	(segment
		(start 429.721264 -250.46305)
		(end 429.538384 -250.64593)
		(width 0.18288)
		(layer "In6.Cu")
		(net "M_G_CPU0_SA_RSP<0>")
	)
	(segment
		(start 391.703306 -255.038606)
		(end 390.23671 -253.57201)
		(width 0.18288)
		(layer "In6.Cu")
		(net "M_G_CPU0_SA_RSP<0>")
	)
	(segment
		(start 385.623816 -253.57201)
		(end 385.332986 -253.57201)
		(width 0.088646)
		(layer "In6.Cu")
		(net "M_G_CPU0_SA_RSP<0>")
	)
	(segment
		(start 383.715006 -253.40437)
		(end 381.271526 -253.40437)
		(width 0.088646)
		(layer "In6.Cu")
		(net "M_G_CPU0_SA_RSP<0>")
	)
	(segment
		(start 413.429196 -253.013972)
		(end 404.596092 -253.013972)
		(width 0.18288)
		(layer "In6.Cu")
		(net "M_G_CPU0_SA_RSP<0>")
	)
	(segment
		(start 426.832014 -250.442222)
		(end 416.927538 -250.442222)
		(width 0.18288)
		(layer "In6.Cu")
		(net "M_G_CPU0_SA_RSP<0>")
	)
	(segment
		(start 390.23671 -253.57201)
		(end 385.623816 -253.57201)
		(width 0.18288)
		(layer "In6.Cu")
		(net "M_G_CPU0_SA_RSP<0>")
	)
	(segment
		(start 443.342014 -244.066568)
		(end 443.078362 -244.33022)
		(width 0.18288)
		(layer "In6.Cu")
		(net "M_G_CPU0_SA_RSP<0>")
	)
	(segment
		(start 427.825916 -249.44832)
		(end 426.832014 -250.442222)
		(width 0.18288)
		(layer "In6.Cu")
		(net "M_G_CPU0_SA_RSP<0>")
	)
	(segment
		(start 429.904144 -249.44832)
		(end 429.721264 -249.6312)
		(width 0.18288)
		(layer "In6.Cu")
		(net "M_G_CPU0_SA_RSP<0>")
	)
	(segment
		(start 439.595514 -246.192294)
		(end 438.3024 -247.042178)
		(width 0.18288)
		(layer "In6.Cu")
		(net "M_G_CPU0_SA_RSP<0>")
	)
	(segment
		(start 438.3024 -247.042178)
		(end 434.345842 -247.042178)
		(width 0.18288)
		(layer "In6.Cu")
		(net "M_G_CPU0_SA_RSP<0>")
	)
	(segment
		(start 380.255526 -254.374396)
		(end 379.89637 -254.733552)
		(width 0.088646)
		(layer "In6.Cu")
		(net "M_G_CPU0_SA_RSP<0>")
	)
	(segment
		(start 380.566676 -254.374396)
		(end 380.255526 -254.374396)
		(width 0.088646)
		(layer "In6.Cu")
		(net "M_G_CPU0_SA_RSP<0>")
	)
	(segment
		(start 435.823614 -259.366766)
		(end 436.928514 -259.366766)
		(width 0.20066)
		(layer "F.Cu")
		(net "M_G_CPU0_SA_PAR")
	)
	(segment
		(start 442.026548 -258.941824)
		(end 442.038994 -258.95427)
		(width 0.1016)
		(layer "F.Cu")
		(net "M_G_CPU0_SA_PAR")
	)
	(segment
		(start 439.831226 -258.941824)
		(end 439.851546 -258.941824)
		(width 0.101854)
		(layer "F.Cu")
		(net "M_G_CPU0_SA_PAR")
	)
	(segment
		(start 439.851546 -258.941824)
		(end 442.026548 -258.941824)
		(width 0.1016)
		(layer "F.Cu")
		(net "M_G_CPU0_SA_PAR")
	)
	(segment
		(start 375.087134 -248.528078)
		(end 375.08688 -248.527824)
		(width 0.20066)
		(layer "F.Cu")
		(net "M_G_CPU0_SA_PAR")
	)
	(segment
		(start 442.038994 -258.95427)
		(end 442.593476 -258.95427)
		(width 0.20066)
		(layer "F.Cu")
		(net "M_G_CPU0_SA_PAR")
	)
	(segment
		(start 443.005972 -259.366766)
		(end 444.472314 -259.366766)
		(width 0.20066)
		(layer "F.Cu")
		(net "M_G_CPU0_SA_PAR")
	)
	(segment
		(start 375.08688 -248.527824)
		(end 375.08688 -247.992138)
		(width 0.20066)
		(layer "F.Cu")
		(net "M_G_CPU0_SA_PAR")
	)
	(segment
		(start 439.084974 -258.474464)
		(end 439.552334 -258.941824)
		(width 0.20066)
		(layer "F.Cu")
		(net "M_G_CPU0_SA_PAR")
	)
	(segment
		(start 438.708546 -258.474464)
		(end 439.084974 -258.474464)
		(width 0.20066)
		(layer "F.Cu")
		(net "M_G_CPU0_SA_PAR")
	)
	(segment
		(start 442.593476 -258.95427)
		(end 443.005972 -259.366766)
		(width 0.20066)
		(layer "F.Cu")
		(net "M_G_CPU0_SA_PAR")
	)
	(segment
		(start 437.816244 -259.366766)
		(end 438.708546 -258.474464)
		(width 0.20066)
		(layer "F.Cu")
		(net "M_G_CPU0_SA_PAR")
	)
	(segment
		(start 439.552334 -258.941824)
		(end 439.831226 -258.941824)
		(width 0.20066)
		(layer "F.Cu")
		(net "M_G_CPU0_SA_PAR")
	)
	(segment
		(start 436.928514 -259.366766)
		(end 437.816244 -259.366766)
		(width 0.20066)
		(layer "F.Cu")
		(net "M_G_CPU0_SA_PAR")
	)
	(segment
		(start 375.087134 -248.793762)
		(end 375.087134 -248.367296)
		(width 0.088646)
		(layer "In4.Cu")
		(net "M_G_CPU0_SA_PAR")
	)
	(segment
		(start 410.924502 -257.484626)
		(end 407.272744 -256.758186)
		(width 0.18288)
		(layer "In4.Cu")
		(net "M_G_CPU0_SA_PAR")
	)
	(segment
		(start 435.206394 -259.159756)
		(end 435.206394 -258.38531)
		(width 0.18288)
		(layer "In4.Cu")
		(net "M_G_CPU0_SA_PAR")
	)
	(segment
		(start 373.847614 -251.079254)
		(end 373.847614 -250.320048)
		(width 0.18288)
		(layer "In4.Cu")
		(net "M_G_CPU0_SA_PAR")
	)
	(segment
		(start 396.039848 -254.247904)
		(end 394.4747 -254.896112)
		(width 0.18288)
		(layer "In4.Cu")
		(net "M_G_CPU0_SA_PAR")
	)
	(segment
		(start 407.272744 -256.758186)
		(end 404.332948 -255.54051)
		(width 0.18288)
		(layer "In4.Cu")
		(net "M_G_CPU0_SA_PAR")
	)
	(segment
		(start 396.922498 -253.365254)
		(end 396.039848 -254.247904)
		(width 0.18288)
		(layer "In4.Cu")
		(net "M_G_CPU0_SA_PAR")
	)
	(segment
		(start 373.847614 -250.320048)
		(end 373.847614 -250.110244)
		(width 0.088646)
		(layer "In4.Cu")
		(net "M_G_CPU0_SA_PAR")
	)
	(segment
		(start 373.959882 -249.295666)
		(end 374.056656 -249.239786)
		(width 0.088646)
		(layer "In4.Cu")
		(net "M_G_CPU0_SA_PAR")
	)
	(segment
		(start 373.772684 -250.035314)
		(end 373.772684 -249.611388)
		(width 0.088646)
		(layer "In4.Cu")
		(net "M_G_CPU0_SA_PAR")
	)
	(segment
		(start 374.056656 -249.239786)
		(end 374.561862 -249.239786)
		(width 0.088646)
		(layer "In4.Cu")
		(net "M_G_CPU0_SA_PAR")
	)
	(segment
		(start 435.15915 -258.271518)
		(end 434.419502 -257.53187)
		(width 0.18288)
		(layer "In4.Cu")
		(net "M_G_CPU0_SA_PAR")
	)
	(segment
		(start 435.33314 -259.333492)
		(end 435.239668 -259.24002)
		(width 0.18288)
		(layer "In4.Cu")
		(net "M_G_CPU0_SA_PAR")
	)
	(segment
		(start 404.332948 -255.54051)
		(end 402.157692 -253.365254)
		(width 0.18288)
		(layer "In4.Cu")
		(net "M_G_CPU0_SA_PAR")
	)
	(segment
		(start 375.166382 -252.398022)
		(end 373.847614 -251.079254)
		(width 0.18288)
		(layer "In4.Cu")
		(net "M_G_CPU0_SA_PAR")
	)
	(segment
		(start 391.992612 -254.335788)
		(end 390.054846 -252.398022)
		(width 0.18288)
		(layer "In4.Cu")
		(net "M_G_CPU0_SA_PAR")
	)
	(segment
		(start 375.08688 -248.367042)
		(end 375.08688 -247.992138)
		(width 0.088646)
		(layer "In4.Cu")
		(net "M_G_CPU0_SA_PAR")
	)
	(segment
		(start 375.087134 -248.367296)
		(end 375.08688 -248.367042)
		(width 0.088646)
		(layer "In4.Cu")
		(net "M_G_CPU0_SA_PAR")
	)
	(segment
		(start 373.847614 -250.110244)
		(end 373.772684 -250.035314)
		(width 0.088646)
		(layer "In4.Cu")
		(net "M_G_CPU0_SA_PAR")
	)
	(segment
		(start 393.345162 -254.896112)
		(end 391.992612 -254.335788)
		(width 0.18288)
		(layer "In4.Cu")
		(net "M_G_CPU0_SA_PAR")
	)
	(segment
		(start 434.30571 -257.484626)
		(end 410.924502 -257.484626)
		(width 0.18288)
		(layer "In4.Cu")
		(net "M_G_CPU0_SA_PAR")
	)
	(segment
		(start 435.823614 -259.366766)
		(end 435.413404 -259.366766)
		(width 0.18288)
		(layer "In4.Cu")
		(net "M_G_CPU0_SA_PAR")
	)
	(segment
		(start 390.054846 -252.398022)
		(end 375.166382 -252.398022)
		(width 0.18288)
		(layer "In4.Cu")
		(net "M_G_CPU0_SA_PAR")
	)
	(segment
		(start 402.157692 -253.365254)
		(end 396.922498 -253.365254)
		(width 0.18288)
		(layer "In4.Cu")
		(net "M_G_CPU0_SA_PAR")
	)
	(segment
		(start 394.4747 -254.896112)
		(end 393.345162 -254.896112)
		(width 0.18288)
		(layer "In4.Cu")
		(net "M_G_CPU0_SA_PAR")
	)
	(arc
		(start 435.413404 -259.366766)
		(mid 435.369969 -259.358108)
		(end 435.33314 -259.333492)
		(width 0.18288)
		(layer "In4.Cu")
		(net "M_G_CPU0_SA_PAR")
	)
	(arc
		(start 434.419502 -257.53187)
		(mid 434.367294 -257.496986)
		(end 434.30571 -257.484626)
		(width 0.18288)
		(layer "In4.Cu")
		(net "M_G_CPU0_SA_PAR")
	)
	(arc
		(start 435.206394 -258.38531)
		(mid 435.194136 -258.323684)
		(end 435.15915 -258.271518)
		(width 0.18288)
		(layer "In4.Cu")
		(net "M_G_CPU0_SA_PAR")
	)
	(arc
		(start 374.972834 -249.069606)
		(mid 375.057398 -248.943048)
		(end 375.087134 -248.793762)
		(width 0.088646)
		(layer "In4.Cu")
		(net "M_G_CPU0_SA_PAR")
	)
	(arc
		(start 374.561862 -249.239786)
		(mid 374.784259 -249.195548)
		(end 374.972834 -249.069606)
		(width 0.088646)
		(layer "In4.Cu")
		(net "M_G_CPU0_SA_PAR")
	)
	(arc
		(start 435.239668 -259.24002)
		(mid 435.215008 -259.203209)
		(end 435.206394 -259.159756)
		(width 0.18288)
		(layer "In4.Cu")
		(net "M_G_CPU0_SA_PAR")
	)
	(arc
		(start 373.772684 -249.611388)
		(mid 373.824954 -249.429023)
		(end 373.959882 -249.295666)
		(width 0.088646)
		(layer "In4.Cu")
		(net "M_G_CPU0_SA_PAR")
	)
	(segment
		(start 447.736214 -274.084796)
		(end 448.004438 -273.816572)
		(width 0.20066)
		(layer "F.Cu")
		(net "M_G_CPU0_SA_DQS_DP<9>")
	)
	(segment
		(start 445.47536 -273.39163)
		(end 445.661542 -273.39163)
		(width 0.101854)
		(layer "F.Cu")
		(net "M_G_CPU0_SA_DQS_DP<9>")
	)
	(segment
		(start 443.228984 -273.39163)
		(end 443.462664 -273.39163)
		(width 0.101854)
		(layer "F.Cu")
		(net "M_G_CPU0_SA_DQS_DP<9>")
	)
	(segment
		(start 376.136916 -262.87222)
		(end 376.136662 -262.872474)
		(width 0.20066)
		(layer "F.Cu")
		(net "M_G_CPU0_SA_DQS_DP<9>")
	)
	(segment
		(start 446.05956 -273.63928)
		(end 446.713102 -273.63928)
		(width 0.20066)
		(layer "F.Cu")
		(net "M_G_CPU0_SA_DQS_DP<9>")
	)
	(segment
		(start 441.028582 -273.816572)
		(end 441.621926 -273.816572)
		(width 0.20066)
		(layer "F.Cu")
		(net "M_G_CPU0_SA_DQS_DP<9>")
	)
	(segment
		(start 447.158618 -274.084796)
		(end 447.736214 -274.084796)
		(width 0.20066)
		(layer "F.Cu")
		(net "M_G_CPU0_SA_DQS_DP<9>")
	)
	(segment
		(start 441.873132 -274.067778)
		(end 442.177932 -274.067778)
		(width 0.20066)
		(layer "F.Cu")
		(net "M_G_CPU0_SA_DQS_DP<9>")
	)
	(segment
		(start 441.621926 -273.816572)
		(end 441.873132 -274.067778)
		(width 0.20066)
		(layer "F.Cu")
		(net "M_G_CPU0_SA_DQS_DP<9>")
	)
	(segment
		(start 442.869828 -273.642836)
		(end 443.121034 -273.39163)
		(width 0.20066)
		(layer "F.Cu")
		(net "M_G_CPU0_SA_DQS_DP<9>")
	)
	(segment
		(start 439.923682 -273.816572)
		(end 441.028582 -273.816572)
		(width 0.20066)
		(layer "F.Cu")
		(net "M_G_CPU0_SA_DQS_DP<9>")
	)
	(segment
		(start 442.602874 -273.642836)
		(end 442.869828 -273.642836)
		(width 0.20066)
		(layer "F.Cu")
		(net "M_G_CPU0_SA_DQS_DP<9>")
	)
	(segment
		(start 448.004438 -273.816572)
		(end 448.572382 -273.816572)
		(width 0.20066)
		(layer "F.Cu")
		(net "M_G_CPU0_SA_DQS_DP<9>")
	)
	(segment
		(start 443.121034 -273.39163)
		(end 443.228984 -273.39163)
		(width 0.20066)
		(layer "F.Cu")
		(net "M_G_CPU0_SA_DQS_DP<9>")
	)
	(segment
		(start 442.177932 -274.067778)
		(end 442.602874 -273.642836)
		(width 0.20066)
		(layer "F.Cu")
		(net "M_G_CPU0_SA_DQS_DP<9>")
	)
	(segment
		(start 443.462664 -273.39163)
		(end 445.47536 -273.39163)
		(width 0.1016)
		(layer "F.Cu")
		(net "M_G_CPU0_SA_DQS_DP<9>")
	)
	(segment
		(start 446.713102 -273.63928)
		(end 447.158618 -274.084796)
		(width 0.20066)
		(layer "F.Cu")
		(net "M_G_CPU0_SA_DQS_DP<9>")
	)
	(segment
		(start 445.661542 -273.39163)
		(end 445.81191 -273.39163)
		(width 0.20066)
		(layer "F.Cu")
		(net "M_G_CPU0_SA_DQS_DP<9>")
	)
	(segment
		(start 376.136916 -262.336534)
		(end 376.136916 -262.87222)
		(width 0.20066)
		(layer "F.Cu")
		(net "M_G_CPU0_SA_DQS_DP<9>")
	)
	(segment
		(start 445.81191 -273.39163)
		(end 446.05956 -273.63928)
		(width 0.20066)
		(layer "F.Cu")
		(net "M_G_CPU0_SA_DQS_DP<9>")
	)
	(segment
		(start 420.185088 -263.483852)
		(end 416.447986 -263.483852)
		(width 0.18288)
		(layer "In6.Cu")
		(net "M_G_CPU0_SA_DQS_DP<9>")
	)
	(segment
		(start 377.641866 -262.436864)
		(end 377.472702 -262.476488)
		(width 0.088646)
		(layer "In6.Cu")
		(net "M_G_CPU0_SA_DQS_DP<9>")
	)
	(segment
		(start 435.563518 -273.393408)
		(end 435.26329 -273.693636)
		(width 0.18288)
		(layer "In6.Cu")
		(net "M_G_CPU0_SA_DQS_DP<9>")
	)
	(segment
		(start 427.185328 -264.961878)
		(end 426.840904 -264.961878)
		(width 0.18288)
		(layer "In6.Cu")
		(net "M_G_CPU0_SA_DQS_DP<9>")
	)
	(segment
		(start 434.814472 -273.693636)
		(end 434.071776 -273.384518)
		(width 0.18288)
		(layer "In6.Cu")
		(net "M_G_CPU0_SA_DQS_DP<9>")
	)
	(segment
		(start 437.887364 -273.085052)
		(end 436.482998 -273.666966)
		(width 0.18288)
		(layer "In6.Cu")
		(net "M_G_CPU0_SA_DQS_DP<9>")
	)
	(segment
		(start 439.643012 -274.097242)
		(end 439.384186 -274.097242)
		(width 0.18288)
		(layer "In6.Cu")
		(net "M_G_CPU0_SA_DQS_DP<9>")
	)
	(segment
		(start 380.178564 -262.383016)
		(end 380.16815 -262.37692)
		(width 0.088646)
		(layer "In6.Cu")
		(net "M_G_CPU0_SA_DQS_DP<9>")
	)
	(segment
		(start 378.688346 -262.37438)
		(end 378.673614 -262.383016)
		(width 0.088646)
		(layer "In6.Cu")
		(net "M_G_CPU0_SA_DQS_DP<9>")
	)
	(segment
		(start 388.317486 -261.493254)
		(end 387.884162 -261.493254)
		(width 0.088646)
		(layer "In6.Cu")
		(net "M_G_CPU0_SA_DQS_DP<9>")
	)
	(segment
		(start 412.653988 -262.868918)
		(end 412.048706 -263.4742)
		(width 0.18288)
		(layer "In6.Cu")
		(net "M_G_CPU0_SA_DQS_DP<9>")
	)
	(segment
		(start 421.005508 -263.19226)
		(end 420.47668 -263.19226)
		(width 0.18288)
		(layer "In6.Cu")
		(net "M_G_CPU0_SA_DQS_DP<9>")
	)
	(segment
		(start 376.889264 -262.548116)
		(end 376.88774 -262.548878)
		(width 0.088646)
		(layer "In6.Cu")
		(net "M_G_CPU0_SA_DQS_DP<9>")
	)
	(segment
		(start 436.482998 -273.666966)
		(end 436.299356 -273.666966)
		(width 0.18288)
		(layer "In6.Cu")
		(net "M_G_CPU0_SA_DQS_DP<9>")
	)
	(segment
		(start 377.748546 -262.37438)
		(end 377.641866 -262.436864)
		(width 0.088646)
		(layer "In6.Cu")
		(net "M_G_CPU0_SA_DQS_DP<9>")
	)
	(segment
		(start 424.576748 -264.042144)
		(end 424.318938 -264.299954)
		(width 0.18288)
		(layer "In6.Cu")
		(net "M_G_CPU0_SA_DQS_DP<9>")
	)
	(segment
		(start 432.237134 -272.037048)
		(end 432.007772 -271.65427)
		(width 0.18288)
		(layer "In6.Cu")
		(net "M_G_CPU0_SA_DQS_DP<9>")
	)
	(segment
		(start 436.299356 -273.666966)
		(end 436.025798 -273.393408)
		(width 0.18288)
		(layer "In6.Cu")
		(net "M_G_CPU0_SA_DQS_DP<9>")
	)
	(segment
		(start 388.817104 -261.528306)
		(end 388.757414 -261.587996)
		(width 0.088646)
		(layer "In6.Cu")
		(net "M_G_CPU0_SA_DQS_DP<9>")
	)
	(segment
		(start 415.833052 -262.868918)
		(end 412.653988 -262.868918)
		(width 0.18288)
		(layer "In6.Cu")
		(net "M_G_CPU0_SA_DQS_DP<9>")
	)
	(segment
		(start 376.649234 -262.872474)
		(end 376.136662 -262.872474)
		(width 0.088646)
		(layer "In6.Cu")
		(net "M_G_CPU0_SA_DQS_DP<9>")
	)
	(segment
		(start 384.31216 -262.383016)
		(end 384.312414 -262.38327)
		(width 0.088646)
		(layer "In6.Cu")
		(net "M_G_CPU0_SA_DQS_DP<9>")
	)
	(segment
		(start 386.757164 -262.383016)
		(end 386.742432 -262.37438)
		(width 0.088646)
		(layer "In6.Cu")
		(net "M_G_CPU0_SA_DQS_DP<9>")
	)
	(segment
		(start 432.007772 -271.65427)
		(end 431.89017 -271.457928)
		(width 0.18288)
		(layer "In6.Cu")
		(net "M_G_CPU0_SA_DQS_DP<9>")
	)
	(segment
		(start 377.099322 -262.476488)
		(end 377.07951 -262.480298)
		(width 0.088646)
		(layer "In6.Cu")
		(net "M_G_CPU0_SA_DQS_DP<9>")
	)
	(segment
		(start 426.840904 -264.961878)
		(end 426.215048 -264.336022)
		(width 0.18288)
		(layer "In6.Cu")
		(net "M_G_CPU0_SA_DQS_DP<9>")
	)
	(segment
		(start 388.412228 -261.587996)
		(end 388.317486 -261.493254)
		(width 0.088646)
		(layer "In6.Cu")
		(net "M_G_CPU0_SA_DQS_DP<9>")
	)
	(segment
		(start 381.507746 -262.37438)
		(end 381.493014 -262.383016)
		(width 0.088646)
		(layer "In6.Cu")
		(net "M_G_CPU0_SA_DQS_DP<9>")
	)
	(segment
		(start 425.399454 -264.336022)
		(end 425.105576 -264.042144)
		(width 0.18288)
		(layer "In6.Cu")
		(net "M_G_CPU0_SA_DQS_DP<9>")
	)
	(segment
		(start 439.384186 -274.097242)
		(end 438.371996 -273.085052)
		(width 0.18288)
		(layer "In6.Cu")
		(net "M_G_CPU0_SA_DQS_DP<9>")
	)
	(segment
		(start 387.318758 -262.048752)
		(end 387.319012 -262.058658)
		(width 0.088646)
		(layer "In6.Cu")
		(net "M_G_CPU0_SA_DQS_DP<9>")
	)
	(segment
		(start 421.972232 -263.440418)
		(end 421.253666 -263.440418)
		(width 0.18288)
		(layer "In6.Cu")
		(net "M_G_CPU0_SA_DQS_DP<9>")
	)
	(segment
		(start 416.447986 -263.483852)
		(end 415.833052 -262.868918)
		(width 0.18288)
		(layer "In6.Cu")
		(net "M_G_CPU0_SA_DQS_DP<9>")
	)
	(segment
		(start 405.157432 -262.883904)
		(end 404.25624 -261.982712)
		(width 0.18288)
		(layer "In6.Cu")
		(net "M_G_CPU0_SA_DQS_DP<9>")
	)
	(segment
		(start 390.8425 -261.528306)
		(end 388.840472 -261.528306)
		(width 0.18288)
		(layer "In6.Cu")
		(net "M_G_CPU0_SA_DQS_DP<9>")
	)
	(segment
		(start 430.724818 -264.459466)
		(end 427.68774 -264.459466)
		(width 0.18288)
		(layer "In6.Cu")
		(net "M_G_CPU0_SA_DQS_DP<9>")
	)
	(segment
		(start 388.757414 -261.587996)
		(end 388.412228 -261.587996)
		(width 0.088646)
		(layer "In6.Cu")
		(net "M_G_CPU0_SA_DQS_DP<9>")
	)
	(segment
		(start 431.89017 -265.624818)
		(end 430.724818 -264.459466)
		(width 0.18288)
		(layer "In6.Cu")
		(net "M_G_CPU0_SA_DQS_DP<9>")
	)
	(segment
		(start 412.048706 -263.4742)
		(end 408.966924 -263.4742)
		(width 0.18288)
		(layer "In6.Cu")
		(net "M_G_CPU0_SA_DQS_DP<9>")
	)
	(segment
		(start 378.30633 -262.386826)
		(end 378.299218 -262.383016)
		(width 0.088646)
		(layer "In6.Cu")
		(net "M_G_CPU0_SA_DQS_DP<9>")
	)
	(segment
		(start 436.025798 -273.393408)
		(end 435.563518 -273.393408)
		(width 0.18288)
		(layer "In6.Cu")
		(net "M_G_CPU0_SA_DQS_DP<9>")
	)
	(segment
		(start 377.472702 -262.476488)
		(end 377.099322 -262.476488)
		(width 0.088646)
		(layer "In6.Cu")
		(net "M_G_CPU0_SA_DQS_DP<9>")
	)
	(segment
		(start 393.126722 -261.982712)
		(end 390.8425 -261.528306)
		(width 0.18288)
		(layer "In6.Cu")
		(net "M_G_CPU0_SA_DQS_DP<9>")
	)
	(segment
		(start 427.68774 -264.459466)
		(end 427.185328 -264.961878)
		(width 0.18288)
		(layer "In6.Cu")
		(net "M_G_CPU0_SA_DQS_DP<9>")
	)
	(segment
		(start 387.14045 -262.377936)
		(end 387.13156 -262.383016)
		(width 0.088646)
		(layer "In6.Cu")
		(net "M_G_CPU0_SA_DQS_DP<9>")
	)
	(segment
		(start 425.105576 -264.042144)
		(end 424.576748 -264.042144)
		(width 0.18288)
		(layer "In6.Cu")
		(net "M_G_CPU0_SA_DQS_DP<9>")
	)
	(segment
		(start 384.877564 -262.383016)
		(end 384.87731 -262.382762)
		(width 0.088646)
		(layer "In6.Cu")
		(net "M_G_CPU0_SA_DQS_DP<9>")
	)
	(segment
		(start 376.706384 -262.815324)
		(end 376.649234 -262.872474)
		(width 0.088646)
		(layer "In6.Cu")
		(net "M_G_CPU0_SA_DQS_DP<9>")
	)
	(segment
		(start 408.376628 -262.883904)
		(end 405.157432 -262.883904)
		(width 0.18288)
		(layer "In6.Cu")
		(net "M_G_CPU0_SA_DQS_DP<9>")
	)
	(segment
		(start 424.318938 -264.299954)
		(end 422.831768 -264.299954)
		(width 0.18288)
		(layer "In6.Cu")
		(net "M_G_CPU0_SA_DQS_DP<9>")
	)
	(segment
		(start 380.563374 -262.37692)
		(end 380.55296 -262.383016)
		(width 0.088646)
		(layer "In6.Cu")
		(net "M_G_CPU0_SA_DQS_DP<9>")
	)
	(segment
		(start 376.88774 -262.548878)
		(end 376.880374 -262.553196)
		(width 0.088646)
		(layer "In6.Cu")
		(net "M_G_CPU0_SA_DQS_DP<9>")
	)
	(segment
		(start 377.07951 -262.480298)
		(end 377.029726 -262.500872)
		(width 0.088646)
		(layer "In6.Cu")
		(net "M_G_CPU0_SA_DQS_DP<9>")
	)
	(segment
		(start 382.443228 -262.37692)
		(end 382.432814 -262.383016)
		(width 0.088646)
		(layer "In6.Cu")
		(net "M_G_CPU0_SA_DQS_DP<9>")
	)
	(segment
		(start 420.47668 -263.19226)
		(end 420.185088 -263.483852)
		(width 0.18288)
		(layer "In6.Cu")
		(net "M_G_CPU0_SA_DQS_DP<9>")
	)
	(segment
		(start 408.966924 -263.4742)
		(end 408.376628 -262.883904)
		(width 0.18288)
		(layer "In6.Cu")
		(net "M_G_CPU0_SA_DQS_DP<9>")
	)
	(segment
		(start 439.923682 -273.816572)
		(end 439.643012 -274.097242)
		(width 0.18288)
		(layer "In6.Cu")
		(net "M_G_CPU0_SA_DQS_DP<9>")
	)
	(segment
		(start 421.253666 -263.440418)
		(end 421.005508 -263.19226)
		(width 0.18288)
		(layer "In6.Cu")
		(net "M_G_CPU0_SA_DQS_DP<9>")
	)
	(segment
		(start 426.215048 -264.336022)
		(end 425.399454 -264.336022)
		(width 0.18288)
		(layer "In6.Cu")
		(net "M_G_CPU0_SA_DQS_DP<9>")
	)
	(segment
		(start 404.25624 -261.982712)
		(end 393.126722 -261.982712)
		(width 0.18288)
		(layer "In6.Cu")
		(net "M_G_CPU0_SA_DQS_DP<9>")
	)
	(segment
		(start 434.071776 -273.384518)
		(end 433.285646 -272.598896)
		(width 0.18288)
		(layer "In6.Cu")
		(net "M_G_CPU0_SA_DQS_DP<9>")
	)
	(segment
		(start 431.89017 -271.457928)
		(end 431.89017 -265.624818)
		(width 0.18288)
		(layer "In6.Cu")
		(net "M_G_CPU0_SA_DQS_DP<9>")
	)
	(segment
		(start 422.831768 -264.299954)
		(end 421.972232 -263.440418)
		(width 0.18288)
		(layer "In6.Cu")
		(net "M_G_CPU0_SA_DQS_DP<9>")
	)
	(segment
		(start 388.840472 -261.528306)
		(end 388.817104 -261.528306)
		(width 0.088646)
		(layer "In6.Cu")
		(net "M_G_CPU0_SA_DQS_DP<9>")
	)
	(segment
		(start 438.371996 -273.085052)
		(end 437.887364 -273.085052)
		(width 0.18288)
		(layer "In6.Cu")
		(net "M_G_CPU0_SA_DQS_DP<9>")
	)
	(segment
		(start 383.937256 -262.38327)
		(end 383.93751 -262.382762)
		(width 0.088646)
		(layer "In6.Cu")
		(net "M_G_CPU0_SA_DQS_DP<9>")
	)
	(segment
		(start 435.26329 -273.693636)
		(end 434.814472 -273.693636)
		(width 0.18288)
		(layer "In6.Cu")
		(net "M_G_CPU0_SA_DQS_DP<9>")
	)
	(segment
		(start 433.285646 -272.598896)
		(end 432.237134 -272.037048)
		(width 0.18288)
		(layer "In6.Cu")
		(net "M_G_CPU0_SA_DQS_DP<9>")
	)
	(arc
		(start 387.884162 -261.493254)
		(mid 387.737818 -261.512462)
		(end 387.60146 -261.568946)
		(width 0.088646)
		(layer "In6.Cu")
		(net "M_G_CPU0_SA_DQS_DP<9>")
	)
	(arc
		(start 379.239018 -262.383016)
		(mid 378.964819 -262.307181)
		(end 378.688346 -262.37438)
		(width 0.088646)
		(layer "In6.Cu")
		(net "M_G_CPU0_SA_DQS_DP<9>")
	)
	(arc
		(start 381.118618 -262.383016)
		(mid 380.841805 -262.307146)
		(end 380.563374 -262.37692)
		(width 0.088646)
		(layer "In6.Cu")
		(net "M_G_CPU0_SA_DQS_DP<9>")
	)
	(arc
		(start 387.319012 -262.058658)
		(mid 387.271333 -262.241558)
		(end 387.14045 -262.377936)
		(width 0.088646)
		(layer "In6.Cu")
		(net "M_G_CPU0_SA_DQS_DP<9>")
	)
	(arc
		(start 384.87731 -262.382762)
		(mid 384.594689 -262.307147)
		(end 384.31216 -262.383016)
		(width 0.088646)
		(layer "In6.Cu")
		(net "M_G_CPU0_SA_DQS_DP<9>")
	)
	(arc
		(start 387.580378 -261.581646)
		(mid 387.390779 -261.782265)
		(end 387.318758 -262.048752)
		(width 0.088646)
		(layer "In6.Cu")
		(net "M_G_CPU0_SA_DQS_DP<9>")
	)
	(arc
		(start 387.13156 -262.383016)
		(mid 386.944362 -262.433159)
		(end 386.757164 -262.383016)
		(width 0.088646)
		(layer "In6.Cu")
		(net "M_G_CPU0_SA_DQS_DP<9>")
	)
	(arc
		(start 387.60146 -261.568946)
		(mid 387.590851 -261.575183)
		(end 387.580378 -261.581646)
		(width 0.088646)
		(layer "In6.Cu")
		(net "M_G_CPU0_SA_DQS_DP<9>")
	)
	(arc
		(start 383.37236 -262.383016)
		(mid 383.185162 -262.433159)
		(end 382.997964 -262.383016)
		(width 0.088646)
		(layer "In6.Cu")
		(net "M_G_CPU0_SA_DQS_DP<9>")
	)
	(arc
		(start 379.613414 -262.383016)
		(mid 379.426216 -262.433159)
		(end 379.239018 -262.383016)
		(width 0.088646)
		(layer "In6.Cu")
		(net "M_G_CPU0_SA_DQS_DP<9>")
	)
	(arc
		(start 378.299218 -262.383016)
		(mid 378.025019 -262.307181)
		(end 377.748546 -262.37438)
		(width 0.088646)
		(layer "In6.Cu")
		(net "M_G_CPU0_SA_DQS_DP<9>")
	)
	(arc
		(start 385.817364 -262.383016)
		(mid 385.534662 -262.30724)
		(end 385.25196 -262.383016)
		(width 0.088646)
		(layer "In6.Cu")
		(net "M_G_CPU0_SA_DQS_DP<9>")
	)
	(arc
		(start 386.19176 -262.383016)
		(mid 386.004562 -262.433159)
		(end 385.817364 -262.383016)
		(width 0.088646)
		(layer "In6.Cu")
		(net "M_G_CPU0_SA_DQS_DP<9>")
	)
	(arc
		(start 380.16815 -262.37692)
		(mid 379.889972 -262.307197)
		(end 379.613414 -262.383016)
		(width 0.088646)
		(layer "In6.Cu")
		(net "M_G_CPU0_SA_DQS_DP<9>")
	)
	(arc
		(start 382.997964 -262.383016)
		(mid 382.721405 -262.307273)
		(end 382.443228 -262.37692)
		(width 0.088646)
		(layer "In6.Cu")
		(net "M_G_CPU0_SA_DQS_DP<9>")
	)
	(arc
		(start 384.312414 -262.38327)
		(mid 384.124852 -262.433506)
		(end 383.937256 -262.38327)
		(width 0.088646)
		(layer "In6.Cu")
		(net "M_G_CPU0_SA_DQS_DP<9>")
	)
	(arc
		(start 381.493014 -262.383016)
		(mid 381.305816 -262.433159)
		(end 381.118618 -262.383016)
		(width 0.088646)
		(layer "In6.Cu")
		(net "M_G_CPU0_SA_DQS_DP<9>")
	)
	(arc
		(start 377.029726 -262.500872)
		(mid 376.957129 -262.517464)
		(end 376.889264 -262.548116)
		(width 0.088646)
		(layer "In6.Cu")
		(net "M_G_CPU0_SA_DQS_DP<9>")
	)
	(arc
		(start 382.432814 -262.383016)
		(mid 382.245616 -262.433159)
		(end 382.058418 -262.383016)
		(width 0.088646)
		(layer "In6.Cu")
		(net "M_G_CPU0_SA_DQS_DP<9>")
	)
	(arc
		(start 386.742432 -262.37438)
		(mid 386.465957 -262.30706)
		(end 386.19176 -262.383016)
		(width 0.088646)
		(layer "In6.Cu")
		(net "M_G_CPU0_SA_DQS_DP<9>")
	)
	(arc
		(start 385.25196 -262.383016)
		(mid 385.064762 -262.433159)
		(end 384.877564 -262.383016)
		(width 0.088646)
		(layer "In6.Cu")
		(net "M_G_CPU0_SA_DQS_DP<9>")
	)
	(arc
		(start 383.93751 -262.382762)
		(mid 383.654889 -262.307147)
		(end 383.37236 -262.383016)
		(width 0.088646)
		(layer "In6.Cu")
		(net "M_G_CPU0_SA_DQS_DP<9>")
	)
	(arc
		(start 378.673614 -262.383016)
		(mid 378.490481 -262.433013)
		(end 378.30633 -262.386826)
		(width 0.088646)
		(layer "In6.Cu")
		(net "M_G_CPU0_SA_DQS_DP<9>")
	)
	(arc
		(start 376.880374 -262.553196)
		(mid 376.764565 -262.665125)
		(end 376.706384 -262.815324)
		(width 0.088646)
		(layer "In6.Cu")
		(net "M_G_CPU0_SA_DQS_DP<9>")
	)
	(arc
		(start 380.55296 -262.383016)
		(mid 380.365762 -262.433159)
		(end 380.178564 -262.383016)
		(width 0.088646)
		(layer "In6.Cu")
		(net "M_G_CPU0_SA_DQS_DP<9>")
	)
	(arc
		(start 382.058418 -262.383016)
		(mid 381.784219 -262.307181)
		(end 381.507746 -262.37438)
		(width 0.088646)
		(layer "In6.Cu")
		(net "M_G_CPU0_SA_DQS_DP<9>")
	)
	(segment
		(start 439.923682 -283.166566)
		(end 441.028582 -283.166566)
		(width 0.20066)
		(layer "F.Cu")
		(net "M_G_CPU0_SA_DQS_DP<8>")
	)
	(segment
		(start 376.136662 -267.220192)
		(end 376.136662 -267.755878)
		(width 0.20066)
		(layer "F.Cu")
		(net "M_G_CPU0_SA_DQS_DP<8>")
	)
	(segment
		(start 445.47536 -282.741624)
		(end 445.482726 -282.734258)
		(width 0.1016)
		(layer "F.Cu")
		(net "M_G_CPU0_SA_DQS_DP<8>")
	)
	(segment
		(start 447.158618 -283.43479)
		(end 447.736214 -283.43479)
		(width 0.20066)
		(layer "F.Cu")
		(net "M_G_CPU0_SA_DQS_DP<8>")
	)
	(segment
		(start 443.455552 -282.734512)
		(end 443.462664 -282.741624)
		(width 0.1016)
		(layer "F.Cu")
		(net "M_G_CPU0_SA_DQS_DP<8>")
	)
	(segment
		(start 442.602874 -282.99283)
		(end 442.881258 -282.99283)
		(width 0.20066)
		(layer "F.Cu")
		(net "M_G_CPU0_SA_DQS_DP<8>")
	)
	(segment
		(start 448.004438 -283.166566)
		(end 448.572382 -283.166566)
		(width 0.20066)
		(layer "F.Cu")
		(net "M_G_CPU0_SA_DQS_DP<8>")
	)
	(segment
		(start 442.177932 -283.417772)
		(end 442.602874 -282.99283)
		(width 0.20066)
		(layer "F.Cu")
		(net "M_G_CPU0_SA_DQS_DP<8>")
	)
	(segment
		(start 445.482726 -282.734258)
		(end 445.804544 -282.734258)
		(width 0.20066)
		(layer "F.Cu")
		(net "M_G_CPU0_SA_DQS_DP<8>")
	)
	(segment
		(start 441.873132 -283.417772)
		(end 442.177932 -283.417772)
		(width 0.20066)
		(layer "F.Cu")
		(net "M_G_CPU0_SA_DQS_DP<8>")
	)
	(segment
		(start 446.05956 -282.989274)
		(end 446.713102 -282.989274)
		(width 0.20066)
		(layer "F.Cu")
		(net "M_G_CPU0_SA_DQS_DP<8>")
	)
	(segment
		(start 443.462664 -282.741624)
		(end 445.47536 -282.741624)
		(width 0.1016)
		(layer "F.Cu")
		(net "M_G_CPU0_SA_DQS_DP<8>")
	)
	(segment
		(start 376.136916 -267.219938)
		(end 376.136662 -267.220192)
		(width 0.20066)
		(layer "F.Cu")
		(net "M_G_CPU0_SA_DQS_DP<8>")
	)
	(segment
		(start 445.804544 -282.734258)
		(end 446.05956 -282.989274)
		(width 0.20066)
		(layer "F.Cu")
		(net "M_G_CPU0_SA_DQS_DP<8>")
	)
	(segment
		(start 442.881258 -282.99283)
		(end 443.139576 -282.734512)
		(width 0.20066)
		(layer "F.Cu")
		(net "M_G_CPU0_SA_DQS_DP<8>")
	)
	(segment
		(start 443.139576 -282.734512)
		(end 443.450726 -282.734512)
		(width 0.20066)
		(layer "F.Cu")
		(net "M_G_CPU0_SA_DQS_DP<8>")
	)
	(segment
		(start 447.736214 -283.43479)
		(end 448.004438 -283.166566)
		(width 0.20066)
		(layer "F.Cu")
		(net "M_G_CPU0_SA_DQS_DP<8>")
	)
	(segment
		(start 441.028582 -283.166566)
		(end 441.621926 -283.166566)
		(width 0.20066)
		(layer "F.Cu")
		(net "M_G_CPU0_SA_DQS_DP<8>")
	)
	(segment
		(start 441.621926 -283.166566)
		(end 441.873132 -283.417772)
		(width 0.20066)
		(layer "F.Cu")
		(net "M_G_CPU0_SA_DQS_DP<8>")
	)
	(segment
		(start 446.713102 -282.989274)
		(end 447.158618 -283.43479)
		(width 0.20066)
		(layer "F.Cu")
		(net "M_G_CPU0_SA_DQS_DP<8>")
	)
	(segment
		(start 443.450726 -282.734512)
		(end 443.455552 -282.734512)
		(width 0.101854)
		(layer "F.Cu")
		(net "M_G_CPU0_SA_DQS_DP<8>")
	)
	(segment
		(start 390.202166 -267.471398)
		(end 388.535672 -267.471398)
		(width 0.18288)
		(layer "In6.Cu")
		(net "M_G_CPU0_SA_DQS_DP<8>")
	)
	(segment
		(start 377.696476 -267.28674)
		(end 377.660154 -267.31087)
		(width 0.088646)
		(layer "In6.Cu")
		(net "M_G_CPU0_SA_DQS_DP<8>")
	)
	(segment
		(start 421.696388 -277.939246)
		(end 421.239442 -277.939246)
		(width 0.18288)
		(layer "In6.Cu")
		(net "M_G_CPU0_SA_DQS_DP<8>")
	)
	(segment
		(start 424.275758 -282.193238)
		(end 424.05046 -282.193238)
		(width 0.18288)
		(layer "In6.Cu")
		(net "M_G_CPU0_SA_DQS_DP<8>")
	)
	(segment
		(start 431.187352 -282.249626)
		(end 427.950122 -282.249626)
		(width 0.18288)
		(layer "In6.Cu")
		(net "M_G_CPU0_SA_DQS_DP<8>")
	)
	(segment
		(start 388.535672 -267.471398)
		(end 388.512304 -267.471398)
		(width 0.088646)
		(layer "In6.Cu")
		(net "M_G_CPU0_SA_DQS_DP<8>")
	)
	(segment
		(start 378.673106 -267.266928)
		(end 378.661168 -267.27404)
		(width 0.088646)
		(layer "In6.Cu")
		(net "M_G_CPU0_SA_DQS_DP<8>")
	)
	(segment
		(start 424.576748 -281.892248)
		(end 424.275758 -282.193238)
		(width 0.18288)
		(layer "In6.Cu")
		(net "M_G_CPU0_SA_DQS_DP<8>")
	)
	(segment
		(start 420.47668 -277.64232)
		(end 420.17569 -277.94331)
		(width 0.18288)
		(layer "In6.Cu")
		(net "M_G_CPU0_SA_DQS_DP<8>")
	)
	(segment
		(start 416.683698 -274.339558)
		(end 405.434292 -274.339558)
		(width 0.18288)
		(layer "In6.Cu")
		(net "M_G_CPU0_SA_DQS_DP<8>")
	)
	(segment
		(start 383.372106 -267.266928)
		(end 383.360168 -267.273786)
		(width 0.088646)
		(layer "In6.Cu")
		(net "M_G_CPU0_SA_DQS_DP<8>")
	)
	(segment
		(start 377.099322 -267.359892)
		(end 377.07951 -267.363702)
		(width 0.088646)
		(layer "In6.Cu")
		(net "M_G_CPU0_SA_DQS_DP<8>")
	)
	(segment
		(start 385.81711 -267.266928)
		(end 385.806442 -267.260578)
		(width 0.088646)
		(layer "In6.Cu")
		(net "M_G_CPU0_SA_DQS_DP<8>")
	)
	(segment
		(start 382.432052 -267.267182)
		(end 382.420876 -267.273532)
		(width 0.088646)
		(layer "In6.Cu")
		(net "M_G_CPU0_SA_DQS_DP<8>")
	)
	(segment
		(start 436.093108 -282.742386)
		(end 435.580536 -282.742386)
		(width 0.18288)
		(layer "In6.Cu")
		(net "M_G_CPU0_SA_DQS_DP<8>")
	)
	(segment
		(start 388.452614 -267.531088)
		(end 388.258304 -267.531088)
		(width 0.088646)
		(layer "In6.Cu")
		(net "M_G_CPU0_SA_DQS_DP<8>")
	)
	(segment
		(start 437.72582 -283.877766)
		(end 436.838598 -282.990544)
		(width 0.18288)
		(layer "In6.Cu")
		(net "M_G_CPU0_SA_DQS_DP<8>")
	)
	(segment
		(start 388.512304 -267.471398)
		(end 388.452614 -267.531088)
		(width 0.088646)
		(layer "In6.Cu")
		(net "M_G_CPU0_SA_DQS_DP<8>")
	)
	(segment
		(start 438.232296 -283.877766)
		(end 437.72582 -283.877766)
		(width 0.18288)
		(layer "In6.Cu")
		(net "M_G_CPU0_SA_DQS_DP<8>")
	)
	(segment
		(start 417.19754 -274.566126)
		(end 416.70732 -274.36318)
		(width 0.18288)
		(layer "In6.Cu")
		(net "M_G_CPU0_SA_DQS_DP<8>")
	)
	(segment
		(start 421.239442 -277.939246)
		(end 420.942516 -277.64232)
		(width 0.18288)
		(layer "In6.Cu")
		(net "M_G_CPU0_SA_DQS_DP<8>")
	)
	(segment
		(start 405.434292 -274.339558)
		(end 399.097246 -268.002512)
		(width 0.18288)
		(layer "In6.Cu")
		(net "M_G_CPU0_SA_DQS_DP<8>")
	)
	(segment
		(start 435.332632 -282.99029)
		(end 431.928016 -282.99029)
		(width 0.18288)
		(layer "In6.Cu")
		(net "M_G_CPU0_SA_DQS_DP<8>")
	)
	(segment
		(start 385.829302 -267.273786)
		(end 385.81711 -267.266928)
		(width 0.088646)
		(layer "In6.Cu")
		(net "M_G_CPU0_SA_DQS_DP<8>")
	)
	(segment
		(start 377.07951 -267.363702)
		(end 377.029726 -267.384276)
		(width 0.088646)
		(layer "In6.Cu")
		(net "M_G_CPU0_SA_DQS_DP<8>")
	)
	(segment
		(start 377.660154 -267.31087)
		(end 377.415044 -267.359892)
		(width 0.088646)
		(layer "In6.Cu")
		(net "M_G_CPU0_SA_DQS_DP<8>")
	)
	(segment
		(start 376.706384 -267.698728)
		(end 376.649234 -267.755878)
		(width 0.088646)
		(layer "In6.Cu")
		(net "M_G_CPU0_SA_DQS_DP<8>")
	)
	(segment
		(start 416.70732 -274.36318)
		(end 416.683698 -274.339558)
		(width 0.18288)
		(layer "In6.Cu")
		(net "M_G_CPU0_SA_DQS_DP<8>")
	)
	(segment
		(start 439.923682 -283.166566)
		(end 439.660538 -283.42971)
		(width 0.18288)
		(layer "In6.Cu")
		(net "M_G_CPU0_SA_DQS_DP<8>")
	)
	(segment
		(start 423.92346 -282.066238)
		(end 423.92346 -279.59177)
		(width 0.18288)
		(layer "In6.Cu")
		(net "M_G_CPU0_SA_DQS_DP<8>")
	)
	(segment
		(start 392.87196 -268.002512)
		(end 390.202166 -267.471398)
		(width 0.18288)
		(layer "In6.Cu")
		(net "M_G_CPU0_SA_DQS_DP<8>")
	)
	(segment
		(start 379.61316 -267.266928)
		(end 379.604778 -267.272008)
		(width 0.088646)
		(layer "In6.Cu")
		(net "M_G_CPU0_SA_DQS_DP<8>")
	)
	(segment
		(start 423.92346 -279.59177)
		(end 422.812464 -278.480774)
		(width 0.18288)
		(layer "In6.Cu")
		(net "M_G_CPU0_SA_DQS_DP<8>")
	)
	(segment
		(start 386.75691 -267.266928)
		(end 386.74167 -267.258038)
		(width 0.088646)
		(layer "In6.Cu")
		(net "M_G_CPU0_SA_DQS_DP<8>")
	)
	(segment
		(start 424.05046 -282.193238)
		(end 423.92346 -282.066238)
		(width 0.18288)
		(layer "In6.Cu")
		(net "M_G_CPU0_SA_DQS_DP<8>")
	)
	(segment
		(start 388.044182 -267.316966)
		(end 387.882892 -267.316966)
		(width 0.088646)
		(layer "In6.Cu")
		(net "M_G_CPU0_SA_DQS_DP<8>")
	)
	(segment
		(start 384.889756 -267.273786)
		(end 384.877818 -267.266928)
		(width 0.088646)
		(layer "In6.Cu")
		(net "M_G_CPU0_SA_DQS_DP<8>")
	)
	(segment
		(start 388.258304 -267.531088)
		(end 388.044182 -267.316966)
		(width 0.088646)
		(layer "In6.Cu")
		(net "M_G_CPU0_SA_DQS_DP<8>")
	)
	(segment
		(start 438.680352 -283.42971)
		(end 438.232296 -283.877766)
		(width 0.18288)
		(layer "In6.Cu")
		(net "M_G_CPU0_SA_DQS_DP<8>")
	)
	(segment
		(start 419.062662 -277.384256)
		(end 419.062662 -276.431502)
		(width 0.18288)
		(layer "In6.Cu")
		(net "M_G_CPU0_SA_DQS_DP<8>")
	)
	(segment
		(start 399.097246 -268.002512)
		(end 392.87196 -268.002512)
		(width 0.18288)
		(layer "In6.Cu")
		(net "M_G_CPU0_SA_DQS_DP<8>")
	)
	(segment
		(start 422.237916 -278.480774)
		(end 421.696388 -277.939246)
		(width 0.18288)
		(layer "In6.Cu")
		(net "M_G_CPU0_SA_DQS_DP<8>")
	)
	(segment
		(start 419.621716 -277.94331)
		(end 419.062662 -277.384256)
		(width 0.18288)
		(layer "In6.Cu")
		(net "M_G_CPU0_SA_DQS_DP<8>")
	)
	(segment
		(start 431.928016 -282.99029)
		(end 431.187352 -282.249626)
		(width 0.18288)
		(layer "In6.Cu")
		(net "M_G_CPU0_SA_DQS_DP<8>")
	)
	(segment
		(start 377.736608 -267.26515)
		(end 377.696476 -267.28674)
		(width 0.088646)
		(layer "In6.Cu")
		(net "M_G_CPU0_SA_DQS_DP<8>")
	)
	(segment
		(start 376.889264 -267.43152)
		(end 376.88774 -267.432282)
		(width 0.088646)
		(layer "In6.Cu")
		(net "M_G_CPU0_SA_DQS_DP<8>")
	)
	(segment
		(start 386.765546 -267.271754)
		(end 386.75691 -267.266928)
		(width 0.088646)
		(layer "In6.Cu")
		(net "M_G_CPU0_SA_DQS_DP<8>")
	)
	(segment
		(start 420.942516 -277.64232)
		(end 420.47668 -277.64232)
		(width 0.18288)
		(layer "In6.Cu")
		(net "M_G_CPU0_SA_DQS_DP<8>")
	)
	(segment
		(start 426.838872 -282.741116)
		(end 426.238162 -282.140406)
		(width 0.18288)
		(layer "In6.Cu")
		(net "M_G_CPU0_SA_DQS_DP<8>")
	)
	(segment
		(start 436.341266 -282.990544)
		(end 436.093108 -282.742386)
		(width 0.18288)
		(layer "In6.Cu")
		(net "M_G_CPU0_SA_DQS_DP<8>")
	)
	(segment
		(start 427.458632 -282.741116)
		(end 426.838872 -282.741116)
		(width 0.18288)
		(layer "In6.Cu")
		(net "M_G_CPU0_SA_DQS_DP<8>")
	)
	(segment
		(start 381.492506 -267.266928)
		(end 381.480568 -267.27404)
		(width 0.088646)
		(layer "In6.Cu")
		(net "M_G_CPU0_SA_DQS_DP<8>")
	)
	(segment
		(start 435.580536 -282.742386)
		(end 435.332632 -282.99029)
		(width 0.18288)
		(layer "In6.Cu")
		(net "M_G_CPU0_SA_DQS_DP<8>")
	)
	(segment
		(start 422.812464 -278.480774)
		(end 422.237916 -278.480774)
		(width 0.18288)
		(layer "In6.Cu")
		(net "M_G_CPU0_SA_DQS_DP<8>")
	)
	(segment
		(start 425.105576 -281.892248)
		(end 424.576748 -281.892248)
		(width 0.18288)
		(layer "In6.Cu")
		(net "M_G_CPU0_SA_DQS_DP<8>")
	)
	(segment
		(start 426.238162 -282.140406)
		(end 425.353734 -282.140406)
		(width 0.18288)
		(layer "In6.Cu")
		(net "M_G_CPU0_SA_DQS_DP<8>")
	)
	(segment
		(start 380.187454 -267.271754)
		(end 380.179072 -267.266928)
		(width 0.088646)
		(layer "In6.Cu")
		(net "M_G_CPU0_SA_DQS_DP<8>")
	)
	(segment
		(start 420.17569 -277.94331)
		(end 419.621716 -277.94331)
		(width 0.18288)
		(layer "In6.Cu")
		(net "M_G_CPU0_SA_DQS_DP<8>")
	)
	(segment
		(start 436.838598 -282.990544)
		(end 436.341266 -282.990544)
		(width 0.18288)
		(layer "In6.Cu")
		(net "M_G_CPU0_SA_DQS_DP<8>")
	)
	(segment
		(start 376.88774 -267.432282)
		(end 376.880374 -267.4366)
		(width 0.088646)
		(layer "In6.Cu")
		(net "M_G_CPU0_SA_DQS_DP<8>")
	)
	(segment
		(start 377.415044 -267.359892)
		(end 377.099322 -267.359892)
		(width 0.088646)
		(layer "In6.Cu")
		(net "M_G_CPU0_SA_DQS_DP<8>")
	)
	(segment
		(start 425.353734 -282.140406)
		(end 425.105576 -281.892248)
		(width 0.18288)
		(layer "In6.Cu")
		(net "M_G_CPU0_SA_DQS_DP<8>")
	)
	(segment
		(start 419.062662 -276.431502)
		(end 417.19754 -274.566126)
		(width 0.18288)
		(layer "In6.Cu")
		(net "M_G_CPU0_SA_DQS_DP<8>")
	)
	(segment
		(start 427.950122 -282.249626)
		(end 427.458632 -282.741116)
		(width 0.18288)
		(layer "In6.Cu")
		(net "M_G_CPU0_SA_DQS_DP<8>")
	)
	(segment
		(start 376.649234 -267.755878)
		(end 376.136662 -267.755878)
		(width 0.088646)
		(layer "In6.Cu")
		(net "M_G_CPU0_SA_DQS_DP<8>")
	)
	(segment
		(start 382.433068 -267.266674)
		(end 382.432052 -267.267182)
		(width 0.088646)
		(layer "In6.Cu")
		(net "M_G_CPU0_SA_DQS_DP<8>")
	)
	(segment
		(start 439.660538 -283.42971)
		(end 438.680352 -283.42971)
		(width 0.18288)
		(layer "In6.Cu")
		(net "M_G_CPU0_SA_DQS_DP<8>")
	)
	(arc
		(start 376.880374 -267.4366)
		(mid 376.764565 -267.548529)
		(end 376.706384 -267.698728)
		(width 0.088646)
		(layer "In6.Cu")
		(net "M_G_CPU0_SA_DQS_DP<8>")
	)
	(arc
		(start 385.806442 -267.260578)
		(mid 385.528518 -267.190946)
		(end 385.252214 -267.266674)
		(width 0.088646)
		(layer "In6.Cu")
		(net "M_G_CPU0_SA_DQS_DP<8>")
	)
	(arc
		(start 386.19176 -267.266674)
		(mid 386.011443 -267.31693)
		(end 385.829302 -267.273786)
		(width 0.088646)
		(layer "In6.Cu")
		(net "M_G_CPU0_SA_DQS_DP<8>")
	)
	(arc
		(start 383.937256 -267.266674)
		(mid 383.654634 -267.190991)
		(end 383.372106 -267.266928)
		(width 0.088646)
		(layer "In6.Cu")
		(net "M_G_CPU0_SA_DQS_DP<8>")
	)
	(arc
		(start 381.11811 -267.266674)
		(mid 380.835662 -267.190991)
		(end 380.553214 -267.266674)
		(width 0.088646)
		(layer "In6.Cu")
		(net "M_G_CPU0_SA_DQS_DP<8>")
	)
	(arc
		(start 382.99771 -267.266674)
		(mid 382.715406 -267.191118)
		(end 382.433068 -267.266674)
		(width 0.088646)
		(layer "In6.Cu")
		(net "M_G_CPU0_SA_DQS_DP<8>")
	)
	(arc
		(start 382.420876 -267.273532)
		(mid 382.238511 -267.316946)
		(end 382.05791 -267.266674)
		(width 0.088646)
		(layer "In6.Cu")
		(net "M_G_CPU0_SA_DQS_DP<8>")
	)
	(arc
		(start 380.179072 -267.266928)
		(mid 379.896116 -267.190957)
		(end 379.61316 -267.266928)
		(width 0.088646)
		(layer "In6.Cu")
		(net "M_G_CPU0_SA_DQS_DP<8>")
	)
	(arc
		(start 387.882892 -267.316966)
		(mid 387.785853 -267.304172)
		(end 387.69544 -267.266674)
		(width 0.088646)
		(layer "In6.Cu")
		(net "M_G_CPU0_SA_DQS_DP<8>")
	)
	(arc
		(start 384.877818 -267.266928)
		(mid 384.595289 -267.191084)
		(end 384.312668 -267.266674)
		(width 0.088646)
		(layer "In6.Cu")
		(net "M_G_CPU0_SA_DQS_DP<8>")
	)
	(arc
		(start 387.131052 -267.266674)
		(mid 386.948973 -267.316714)
		(end 386.765546 -267.271754)
		(width 0.088646)
		(layer "In6.Cu")
		(net "M_G_CPU0_SA_DQS_DP<8>")
	)
	(arc
		(start 379.23851 -267.266674)
		(mid 378.955779 -267.190991)
		(end 378.673106 -267.266928)
		(width 0.088646)
		(layer "In6.Cu")
		(net "M_G_CPU0_SA_DQS_DP<8>")
	)
	(arc
		(start 378.29871 -267.266674)
		(mid 378.017853 -267.190993)
		(end 377.736608 -267.26515)
		(width 0.088646)
		(layer "In6.Cu")
		(net "M_G_CPU0_SA_DQS_DP<8>")
	)
	(arc
		(start 387.69544 -267.266674)
		(mid 387.413246 -267.191118)
		(end 387.131052 -267.266674)
		(width 0.088646)
		(layer "In6.Cu")
		(net "M_G_CPU0_SA_DQS_DP<8>")
	)
	(arc
		(start 378.661168 -267.27404)
		(mid 378.478998 -267.317029)
		(end 378.29871 -267.266674)
		(width 0.088646)
		(layer "In6.Cu")
		(net "M_G_CPU0_SA_DQS_DP<8>")
	)
	(arc
		(start 382.05791 -267.266674)
		(mid 381.775179 -267.190991)
		(end 381.492506 -267.266928)
		(width 0.088646)
		(layer "In6.Cu")
		(net "M_G_CPU0_SA_DQS_DP<8>")
	)
	(arc
		(start 384.312668 -267.266674)
		(mid 384.124962 -267.317003)
		(end 383.937256 -267.266674)
		(width 0.088646)
		(layer "In6.Cu")
		(net "M_G_CPU0_SA_DQS_DP<8>")
	)
	(arc
		(start 380.553214 -267.266674)
		(mid 380.370992 -267.316874)
		(end 380.187454 -267.271754)
		(width 0.088646)
		(layer "In6.Cu")
		(net "M_G_CPU0_SA_DQS_DP<8>")
	)
	(arc
		(start 379.604778 -267.272008)
		(mid 379.420957 -267.317066)
		(end 379.23851 -267.266674)
		(width 0.088646)
		(layer "In6.Cu")
		(net "M_G_CPU0_SA_DQS_DP<8>")
	)
	(arc
		(start 386.74167 -267.258038)
		(mid 386.465593 -267.19093)
		(end 386.19176 -267.266674)
		(width 0.088646)
		(layer "In6.Cu")
		(net "M_G_CPU0_SA_DQS_DP<8>")
	)
	(arc
		(start 377.029726 -267.384276)
		(mid 376.957129 -267.400868)
		(end 376.889264 -267.43152)
		(width 0.088646)
		(layer "In6.Cu")
		(net "M_G_CPU0_SA_DQS_DP<8>")
	)
	(arc
		(start 383.360168 -267.273786)
		(mid 383.178027 -267.316899)
		(end 382.99771 -267.266674)
		(width 0.088646)
		(layer "In6.Cu")
		(net "M_G_CPU0_SA_DQS_DP<8>")
	)
	(arc
		(start 385.252214 -267.266674)
		(mid 385.071897 -267.31693)
		(end 384.889756 -267.273786)
		(width 0.088646)
		(layer "In6.Cu")
		(net "M_G_CPU0_SA_DQS_DP<8>")
	)
	(arc
		(start 381.480568 -267.27404)
		(mid 381.298398 -267.317029)
		(end 381.11811 -267.266674)
		(width 0.088646)
		(layer "In6.Cu")
		(net "M_G_CPU0_SA_DQS_DP<8>")
	)
	(segment
		(start 442.881258 -292.342824)
		(end 443.139322 -292.08476)
		(width 0.20066)
		(layer "F.Cu")
		(net "M_G_CPU0_SA_DQS_DP<7>")
	)
	(segment
		(start 443.455552 -292.08476)
		(end 443.462664 -292.091872)
		(width 0.1016)
		(layer "F.Cu")
		(net "M_G_CPU0_SA_DQS_DP<7>")
	)
	(segment
		(start 379.425962 -264.778236)
		(end 379.425962 -265.313922)
		(width 0.20066)
		(layer "F.Cu")
		(net "M_G_CPU0_SA_DQS_DP<7>")
	)
	(segment
		(start 446.05956 -292.339268)
		(end 446.713102 -292.339268)
		(width 0.20066)
		(layer "F.Cu")
		(net "M_G_CPU0_SA_DQS_DP<7>")
	)
	(segment
		(start 379.425962 -265.313922)
		(end 379.426216 -265.314176)
		(width 0.20066)
		(layer "F.Cu")
		(net "M_G_CPU0_SA_DQS_DP<7>")
	)
	(segment
		(start 442.602874 -292.342824)
		(end 442.881258 -292.342824)
		(width 0.20066)
		(layer "F.Cu")
		(net "M_G_CPU0_SA_DQS_DP<7>")
	)
	(segment
		(start 448.004184 -292.516814)
		(end 448.572382 -292.516814)
		(width 0.20066)
		(layer "F.Cu")
		(net "M_G_CPU0_SA_DQS_DP<7>")
	)
	(segment
		(start 441.028582 -292.516814)
		(end 441.62218 -292.516814)
		(width 0.20066)
		(layer "F.Cu")
		(net "M_G_CPU0_SA_DQS_DP<7>")
	)
	(segment
		(start 446.713102 -292.339268)
		(end 447.158618 -292.784784)
		(width 0.20066)
		(layer "F.Cu")
		(net "M_G_CPU0_SA_DQS_DP<7>")
	)
	(segment
		(start 447.158618 -292.784784)
		(end 447.736214 -292.784784)
		(width 0.20066)
		(layer "F.Cu")
		(net "M_G_CPU0_SA_DQS_DP<7>")
	)
	(segment
		(start 442.177932 -292.767766)
		(end 442.602874 -292.342824)
		(width 0.20066)
		(layer "F.Cu")
		(net "M_G_CPU0_SA_DQS_DP<7>")
	)
	(segment
		(start 445.804798 -292.084506)
		(end 446.05956 -292.339268)
		(width 0.20066)
		(layer "F.Cu")
		(net "M_G_CPU0_SA_DQS_DP<7>")
	)
	(segment
		(start 445.47536 -292.091872)
		(end 445.482726 -292.084506)
		(width 0.1016)
		(layer "F.Cu")
		(net "M_G_CPU0_SA_DQS_DP<7>")
	)
	(segment
		(start 443.139322 -292.08476)
		(end 443.450726 -292.08476)
		(width 0.20066)
		(layer "F.Cu")
		(net "M_G_CPU0_SA_DQS_DP<7>")
	)
	(segment
		(start 441.873132 -292.767766)
		(end 442.177932 -292.767766)
		(width 0.20066)
		(layer "F.Cu")
		(net "M_G_CPU0_SA_DQS_DP<7>")
	)
	(segment
		(start 439.923682 -292.51656)
		(end 439.923936 -292.516814)
		(width 0.20066)
		(layer "F.Cu")
		(net "M_G_CPU0_SA_DQS_DP<7>")
	)
	(segment
		(start 445.482726 -292.084506)
		(end 445.804798 -292.084506)
		(width 0.20066)
		(layer "F.Cu")
		(net "M_G_CPU0_SA_DQS_DP<7>")
	)
	(segment
		(start 443.450726 -292.08476)
		(end 443.455552 -292.08476)
		(width 0.101854)
		(layer "F.Cu")
		(net "M_G_CPU0_SA_DQS_DP<7>")
	)
	(segment
		(start 447.736214 -292.784784)
		(end 448.004184 -292.516814)
		(width 0.20066)
		(layer "F.Cu")
		(net "M_G_CPU0_SA_DQS_DP<7>")
	)
	(segment
		(start 443.462664 -292.091872)
		(end 445.47536 -292.091872)
		(width 0.1016)
		(layer "F.Cu")
		(net "M_G_CPU0_SA_DQS_DP<7>")
	)
	(segment
		(start 441.62218 -292.516814)
		(end 441.873132 -292.767766)
		(width 0.20066)
		(layer "F.Cu")
		(net "M_G_CPU0_SA_DQS_DP<7>")
	)
	(segment
		(start 439.923936 -292.516814)
		(end 441.028582 -292.516814)
		(width 0.20066)
		(layer "F.Cu")
		(net "M_G_CPU0_SA_DQS_DP<7>")
	)
	(segment
		(start 384.782822 -264.824972)
		(end 384.78206 -264.824718)
		(width 0.088646)
		(layer "In4.Cu")
		(net "M_G_CPU0_SA_DQS_DP<7>")
	)
	(segment
		(start 385.634992 -264.987024)
		(end 385.346448 -264.824464)
		(width 0.088646)
		(layer "In4.Cu")
		(net "M_G_CPU0_SA_DQS_DP<7>")
	)
	(segment
		(start 439.415936 -292.775386)
		(end 439.006996 -292.944804)
		(width 0.18288)
		(layer "In4.Cu")
		(net "M_G_CPU0_SA_DQS_DP<7>")
	)
	(segment
		(start 391.00379 -267.283946)
		(end 390.938004 -267.256768)
		(width 0.18288)
		(layer "In4.Cu")
		(net "M_G_CPU0_SA_DQS_DP<7>")
	)
	(segment
		(start 381.969518 -264.820654)
		(end 381.968248 -264.821416)
		(width 0.088646)
		(layer "In4.Cu")
		(net "M_G_CPU0_SA_DQS_DP<7>")
	)
	(segment
		(start 381.968248 -264.821416)
		(end 381.96266 -264.824718)
		(width 0.088646)
		(layer "In4.Cu")
		(net "M_G_CPU0_SA_DQS_DP<7>")
	)
	(segment
		(start 434.87975 -292.093396)
		(end 431.494946 -292.093396)
		(width 0.18288)
		(layer "In4.Cu")
		(net "M_G_CPU0_SA_DQS_DP<7>")
	)
	(segment
		(start 388.608316 -264.92708)
		(end 386.605272 -264.92708)
		(width 0.18288)
		(layer "In4.Cu")
		(net "M_G_CPU0_SA_DQS_DP<7>")
	)
	(segment
		(start 412.400242 -287.027366)
		(end 411.793944 -287.027366)
		(width 0.18288)
		(layer "In4.Cu")
		(net "M_G_CPU0_SA_DQS_DP<7>")
	)
	(segment
		(start 380.178818 -264.989818)
		(end 380.169928 -264.994898)
		(width 0.088646)
		(layer "In4.Cu")
		(net "M_G_CPU0_SA_DQS_DP<7>")
	)
	(segment
		(start 425.292774 -291.504878)
		(end 425.030392 -291.242496)
		(width 0.18288)
		(layer "In4.Cu")
		(net "M_G_CPU0_SA_DQS_DP<7>")
	)
	(segment
		(start 386.581904 -264.92708)
		(end 386.52196 -264.987024)
		(width 0.088646)
		(layer "In4.Cu")
		(net "M_G_CPU0_SA_DQS_DP<7>")
	)
	(segment
		(start 435.61254 -292.092634)
		(end 435.339744 -292.36543)
		(width 0.18288)
		(layer "In4.Cu")
		(net "M_G_CPU0_SA_DQS_DP<7>")
	)
	(segment
		(start 423.451782 -291.496242)
		(end 421.38727 -292.351206)
		(width 0.18288)
		(layer "In4.Cu")
		(net "M_G_CPU0_SA_DQS_DP<7>")
	)
	(segment
		(start 421.38727 -292.351206)
		(end 421.188388 -292.351206)
		(width 0.18288)
		(layer "In4.Cu")
		(net "M_G_CPU0_SA_DQS_DP<7>")
	)
	(segment
		(start 436.017416 -292.092634)
		(end 435.61254 -292.092634)
		(width 0.18288)
		(layer "In4.Cu")
		(net "M_G_CPU0_SA_DQS_DP<7>")
	)
	(segment
		(start 404.873714 -281.403806)
		(end 402.81733 -276.439122)
		(width 0.18288)
		(layer "In4.Cu")
		(net "M_G_CPU0_SA_DQS_DP<7>")
	)
	(segment
		(start 379.995938 -265.257026)
		(end 379.938788 -265.314176)
		(width 0.088646)
		(layer "In4.Cu")
		(net "M_G_CPU0_SA_DQS_DP<7>")
	)
	(segment
		(start 380.806706 -264.91692)
		(end 380.372112 -264.91692)
		(width 0.088646)
		(layer "In4.Cu")
		(net "M_G_CPU0_SA_DQS_DP<7>")
	)
	(segment
		(start 435.339744 -292.36543)
		(end 435.151784 -292.36543)
		(width 0.18288)
		(layer "In4.Cu")
		(net "M_G_CPU0_SA_DQS_DP<7>")
	)
	(segment
		(start 409.777692 -284.39364)
		(end 409.400248 -284.494478)
		(width 0.18288)
		(layer "In4.Cu")
		(net "M_G_CPU0_SA_DQS_DP<7>")
	)
	(segment
		(start 420.52494 -292.092634)
		(end 420.275004 -292.34257)
		(width 0.18288)
		(layer "In4.Cu")
		(net "M_G_CPU0_SA_DQS_DP<7>")
	)
	(segment
		(start 379.938788 -265.314176)
		(end 379.426216 -265.314176)
		(width 0.088646)
		(layer "In4.Cu")
		(net "M_G_CPU0_SA_DQS_DP<7>")
	)
	(segment
		(start 421.188388 -292.351206)
		(end 420.929816 -292.092634)
		(width 0.18288)
		(layer "In4.Cu")
		(net "M_G_CPU0_SA_DQS_DP<7>")
	)
	(segment
		(start 437.172608 -292.944804)
		(end 436.60187 -292.374066)
		(width 0.18288)
		(layer "In4.Cu")
		(net "M_G_CPU0_SA_DQS_DP<7>")
	)
	(segment
		(start 439.006996 -292.944804)
		(end 437.172608 -292.944804)
		(width 0.18288)
		(layer "In4.Cu")
		(net "M_G_CPU0_SA_DQS_DP<7>")
	)
	(segment
		(start 409.400248 -284.494478)
		(end 409.28036 -284.444948)
		(width 0.18288)
		(layer "In4.Cu")
		(net "M_G_CPU0_SA_DQS_DP<7>")
	)
	(segment
		(start 392.542268 -267.921232)
		(end 391.00379 -267.283946)
		(width 0.18288)
		(layer "In4.Cu")
		(net "M_G_CPU0_SA_DQS_DP<7>")
	)
	(segment
		(start 408.297126 -282.193746)
		(end 405.663654 -282.193746)
		(width 0.18288)
		(layer "In4.Cu")
		(net "M_G_CPU0_SA_DQS_DP<7>")
	)
	(segment
		(start 410.128466 -284.596078)
		(end 409.777692 -284.39364)
		(width 0.18288)
		(layer "In4.Cu")
		(net "M_G_CPU0_SA_DQS_DP<7>")
	)
	(segment
		(start 411.793944 -287.027366)
		(end 411.495748 -286.72917)
		(width 0.18288)
		(layer "In4.Cu")
		(net "M_G_CPU0_SA_DQS_DP<7>")
	)
	(segment
		(start 411.495748 -286.72917)
		(end 411.495748 -286.140144)
		(width 0.18288)
		(layer "In4.Cu")
		(net "M_G_CPU0_SA_DQS_DP<7>")
	)
	(segment
		(start 411.495748 -286.140144)
		(end 410.30779 -284.952186)
		(width 0.18288)
		(layer "In4.Cu")
		(net "M_G_CPU0_SA_DQS_DP<7>")
	)
	(segment
		(start 427.574964 -292.16477)
		(end 426.796454 -292.16477)
		(width 0.18288)
		(layer "In4.Cu")
		(net "M_G_CPU0_SA_DQS_DP<7>")
	)
	(segment
		(start 380.913386 -264.888218)
		(end 380.806706 -264.91692)
		(width 0.088646)
		(layer "In4.Cu")
		(net "M_G_CPU0_SA_DQS_DP<7>")
	)
	(segment
		(start 405.663654 -282.193746)
		(end 404.873714 -281.403806)
		(width 0.18288)
		(layer "In4.Cu")
		(net "M_G_CPU0_SA_DQS_DP<7>")
	)
	(segment
		(start 417.472876 -290.929568)
		(end 416.849814 -290.929568)
		(width 0.18288)
		(layer "In4.Cu")
		(net "M_G_CPU0_SA_DQS_DP<7>")
	)
	(segment
		(start 384.407664 -264.824718)
		(end 384.392932 -264.816082)
		(width 0.088646)
		(layer "In4.Cu")
		(net "M_G_CPU0_SA_DQS_DP<7>")
	)
	(segment
		(start 439.923682 -292.51656)
		(end 439.664856 -292.775386)
		(width 0.18288)
		(layer "In4.Cu")
		(net "M_G_CPU0_SA_DQS_DP<7>")
	)
	(segment
		(start 426.796454 -292.16477)
		(end 426.136562 -291.504878)
		(width 0.18288)
		(layer "In4.Cu")
		(net "M_G_CPU0_SA_DQS_DP<7>")
	)
	(segment
		(start 414.370012 -288.997136)
		(end 412.400242 -287.027366)
		(width 0.18288)
		(layer "In4.Cu")
		(net "M_G_CPU0_SA_DQS_DP<7>")
	)
	(segment
		(start 431.494946 -292.093396)
		(end 431.111152 -291.709602)
		(width 0.18288)
		(layer "In4.Cu")
		(net "M_G_CPU0_SA_DQS_DP<7>")
	)
	(segment
		(start 436.298848 -292.374066)
		(end 436.017416 -292.092634)
		(width 0.18288)
		(layer "In4.Cu")
		(net "M_G_CPU0_SA_DQS_DP<7>")
	)
	(segment
		(start 416.209226 -290.28898)
		(end 415.275014 -289.901884)
		(width 0.18288)
		(layer "In4.Cu")
		(net "M_G_CPU0_SA_DQS_DP<7>")
	)
	(segment
		(start 426.136562 -291.504878)
		(end 425.292774 -291.504878)
		(width 0.18288)
		(layer "In4.Cu")
		(net "M_G_CPU0_SA_DQS_DP<7>")
	)
	(segment
		(start 394.29944 -267.921232)
		(end 392.542268 -267.921232)
		(width 0.18288)
		(layer "In4.Cu")
		(net "M_G_CPU0_SA_DQS_DP<7>")
	)
	(segment
		(start 386.605272 -264.92708)
		(end 386.581904 -264.92708)
		(width 0.088646)
		(layer "In4.Cu")
		(net "M_G_CPU0_SA_DQS_DP<7>")
	)
	(segment
		(start 381.023114 -264.824972)
		(end 380.913386 -264.888218)
		(width 0.088646)
		(layer "In4.Cu")
		(net "M_G_CPU0_SA_DQS_DP<7>")
	)
	(segment
		(start 435.151784 -292.36543)
		(end 434.87975 -292.093396)
		(width 0.18288)
		(layer "In4.Cu")
		(net "M_G_CPU0_SA_DQS_DP<7>")
	)
	(segment
		(start 436.60187 -292.374066)
		(end 436.298848 -292.374066)
		(width 0.18288)
		(layer "In4.Cu")
		(net "M_G_CPU0_SA_DQS_DP<7>")
	)
	(segment
		(start 428.030132 -291.709602)
		(end 427.574964 -292.16477)
		(width 0.18288)
		(layer "In4.Cu")
		(net "M_G_CPU0_SA_DQS_DP<7>")
	)
	(segment
		(start 415.275014 -289.901884)
		(end 414.370266 -288.997136)
		(width 0.18288)
		(layer "In4.Cu")
		(net "M_G_CPU0_SA_DQS_DP<7>")
	)
	(segment
		(start 410.20873 -284.895036)
		(end 410.128466 -284.596078)
		(width 0.18288)
		(layer "In4.Cu")
		(net "M_G_CPU0_SA_DQS_DP<7>")
	)
	(segment
		(start 381.588264 -264.824718)
		(end 381.588264 -264.824972)
		(width 0.088646)
		(layer "In4.Cu")
		(net "M_G_CPU0_SA_DQS_DP<7>")
	)
	(segment
		(start 386.52196 -264.987024)
		(end 385.634992 -264.987024)
		(width 0.088646)
		(layer "In4.Cu")
		(net "M_G_CPU0_SA_DQS_DP<7>")
	)
	(segment
		(start 420.929816 -292.092634)
		(end 420.52494 -292.092634)
		(width 0.18288)
		(layer "In4.Cu")
		(net "M_G_CPU0_SA_DQS_DP<7>")
	)
	(segment
		(start 416.849814 -290.929568)
		(end 416.209226 -290.28898)
		(width 0.18288)
		(layer "In4.Cu")
		(net "M_G_CPU0_SA_DQS_DP<7>")
	)
	(segment
		(start 425.030392 -291.242496)
		(end 424.63085 -291.242496)
		(width 0.18288)
		(layer "In4.Cu")
		(net "M_G_CPU0_SA_DQS_DP<7>")
	)
	(segment
		(start 383.467864 -264.824718)
		(end 383.453132 -264.816082)
		(width 0.088646)
		(layer "In4.Cu")
		(net "M_G_CPU0_SA_DQS_DP<7>")
	)
	(segment
		(start 410.30779 -284.952186)
		(end 410.20873 -284.895036)
		(width 0.18288)
		(layer "In4.Cu")
		(net "M_G_CPU0_SA_DQS_DP<7>")
	)
	(segment
		(start 414.370266 -288.997136)
		(end 414.370012 -288.997136)
		(width 0.18288)
		(layer "In4.Cu")
		(net "M_G_CPU0_SA_DQS_DP<7>")
	)
	(segment
		(start 418.885878 -292.34257)
		(end 417.472876 -290.929568)
		(width 0.18288)
		(layer "In4.Cu")
		(net "M_G_CPU0_SA_DQS_DP<7>")
	)
	(segment
		(start 431.111152 -291.709602)
		(end 428.030132 -291.709602)
		(width 0.18288)
		(layer "In4.Cu")
		(net "M_G_CPU0_SA_DQS_DP<7>")
	)
	(segment
		(start 439.664856 -292.775386)
		(end 439.415936 -292.775386)
		(width 0.18288)
		(layer "In4.Cu")
		(net "M_G_CPU0_SA_DQS_DP<7>")
	)
	(segment
		(start 402.81733 -276.439122)
		(end 394.29944 -267.921232)
		(width 0.18288)
		(layer "In4.Cu")
		(net "M_G_CPU0_SA_DQS_DP<7>")
	)
	(segment
		(start 409.092146 -282.988766)
		(end 408.297126 -282.193746)
		(width 0.18288)
		(layer "In4.Cu")
		(net "M_G_CPU0_SA_DQS_DP<7>")
	)
	(segment
		(start 424.377104 -291.496242)
		(end 423.451782 -291.496242)
		(width 0.18288)
		(layer "In4.Cu")
		(net "M_G_CPU0_SA_DQS_DP<7>")
	)
	(segment
		(start 409.28036 -284.444948)
		(end 409.092146 -284.119066)
		(width 0.18288)
		(layer "In4.Cu")
		(net "M_G_CPU0_SA_DQS_DP<7>")
	)
	(segment
		(start 390.938004 -267.256768)
		(end 388.608316 -264.92708)
		(width 0.18288)
		(layer "In4.Cu")
		(net "M_G_CPU0_SA_DQS_DP<7>")
	)
	(segment
		(start 420.275004 -292.34257)
		(end 418.885878 -292.34257)
		(width 0.18288)
		(layer "In4.Cu")
		(net "M_G_CPU0_SA_DQS_DP<7>")
	)
	(segment
		(start 424.63085 -291.242496)
		(end 424.377104 -291.496242)
		(width 0.18288)
		(layer "In4.Cu")
		(net "M_G_CPU0_SA_DQS_DP<7>")
	)
	(segment
		(start 409.092146 -284.119066)
		(end 409.092146 -282.988766)
		(width 0.18288)
		(layer "In4.Cu")
		(net "M_G_CPU0_SA_DQS_DP<7>")
	)
	(arc
		(start 381.97028 -264.8204)
		(mid 381.969873 -264.820455)
		(end 381.969518 -264.820654)
		(width 0.088646)
		(layer "In4.Cu")
		(net "M_G_CPU0_SA_DQS_DP<7>")
	)
	(arc
		(start 384.78206 -264.824718)
		(mid 384.594862 -264.874861)
		(end 384.407664 -264.824718)
		(width 0.088646)
		(layer "In4.Cu")
		(net "M_G_CPU0_SA_DQS_DP<7>")
	)
	(arc
		(start 383.453132 -264.816082)
		(mid 383.176657 -264.748762)
		(end 382.90246 -264.824718)
		(width 0.088646)
		(layer "In4.Cu")
		(net "M_G_CPU0_SA_DQS_DP<7>")
	)
	(arc
		(start 383.84226 -264.824718)
		(mid 383.655062 -264.874861)
		(end 383.467864 -264.824718)
		(width 0.088646)
		(layer "In4.Cu")
		(net "M_G_CPU0_SA_DQS_DP<7>")
	)
	(arc
		(start 381.588264 -264.824972)
		(mid 381.305706 -264.749289)
		(end 381.023114 -264.824972)
		(width 0.088646)
		(layer "In4.Cu")
		(net "M_G_CPU0_SA_DQS_DP<7>")
	)
	(arc
		(start 381.96266 -264.824718)
		(mid 381.775462 -264.874861)
		(end 381.588264 -264.824718)
		(width 0.088646)
		(layer "In4.Cu")
		(net "M_G_CPU0_SA_DQS_DP<7>")
	)
	(arc
		(start 385.346448 -264.824464)
		(mid 385.064559 -264.749356)
		(end 384.782822 -264.824972)
		(width 0.088646)
		(layer "In4.Cu")
		(net "M_G_CPU0_SA_DQS_DP<7>")
	)
	(arc
		(start 380.228856 -264.965688)
		(mid 380.203387 -264.976821)
		(end 380.178818 -264.989818)
		(width 0.088646)
		(layer "In4.Cu")
		(net "M_G_CPU0_SA_DQS_DP<7>")
	)
	(arc
		(start 380.279148 -264.941812)
		(mid 380.254443 -264.954679)
		(end 380.228856 -264.965688)
		(width 0.088646)
		(layer "In4.Cu")
		(net "M_G_CPU0_SA_DQS_DP<7>")
	)
	(arc
		(start 382.528064 -264.824718)
		(mid 382.249741 -264.748959)
		(end 381.97028 -264.8204)
		(width 0.088646)
		(layer "In4.Cu")
		(net "M_G_CPU0_SA_DQS_DP<7>")
	)
	(arc
		(start 382.90246 -264.824718)
		(mid 382.715262 -264.874861)
		(end 382.528064 -264.824718)
		(width 0.088646)
		(layer "In4.Cu")
		(net "M_G_CPU0_SA_DQS_DP<7>")
	)
	(arc
		(start 380.169928 -264.994898)
		(mid 380.054119 -265.106827)
		(end 379.995938 -265.257026)
		(width 0.088646)
		(layer "In4.Cu")
		(net "M_G_CPU0_SA_DQS_DP<7>")
	)
	(arc
		(start 384.392932 -264.816082)
		(mid 384.116457 -264.748762)
		(end 383.84226 -264.824718)
		(width 0.088646)
		(layer "In4.Cu")
		(net "M_G_CPU0_SA_DQS_DP<7>")
	)
	(arc
		(start 380.372112 -264.91692)
		(mid 380.323998 -264.923276)
		(end 380.279148 -264.941812)
		(width 0.088646)
		(layer "In4.Cu")
		(net "M_G_CPU0_SA_DQS_DP<7>")
	)
	(segment
		(start 446.05956 -301.689262)
		(end 446.713102 -301.689262)
		(width 0.20066)
		(layer "F.Cu")
		(net "M_G_CPU0_SA_DQS_DP<6>")
	)
	(segment
		(start 443.455552 -301.434754)
		(end 443.462664 -301.441866)
		(width 0.1016)
		(layer "F.Cu")
		(net "M_G_CPU0_SA_DQS_DP<6>")
	)
	(segment
		(start 439.881772 -301.866808)
		(end 441.028582 -301.866808)
		(width 0.20066)
		(layer "F.Cu")
		(net "M_G_CPU0_SA_DQS_DP<6>")
	)
	(segment
		(start 441.028582 -301.866808)
		(end 441.62218 -301.866808)
		(width 0.20066)
		(layer "F.Cu")
		(net "M_G_CPU0_SA_DQS_DP<6>")
	)
	(segment
		(start 447.158618 -302.134778)
		(end 447.736214 -302.134778)
		(width 0.20066)
		(layer "F.Cu")
		(net "M_G_CPU0_SA_DQS_DP<6>")
	)
	(segment
		(start 445.482726 -301.4345)
		(end 445.804798 -301.4345)
		(width 0.20066)
		(layer "F.Cu")
		(net "M_G_CPU0_SA_DQS_DP<6>")
	)
	(segment
		(start 448.004184 -301.866808)
		(end 448.572382 -301.866808)
		(width 0.20066)
		(layer "F.Cu")
		(net "M_G_CPU0_SA_DQS_DP<6>")
	)
	(segment
		(start 442.177932 -302.11776)
		(end 442.602874 -301.692818)
		(width 0.20066)
		(layer "F.Cu")
		(net "M_G_CPU0_SA_DQS_DP<6>")
	)
	(segment
		(start 445.47536 -301.441866)
		(end 445.482726 -301.4345)
		(width 0.1016)
		(layer "F.Cu")
		(net "M_G_CPU0_SA_DQS_DP<6>")
	)
	(segment
		(start 441.873132 -302.11776)
		(end 442.177932 -302.11776)
		(width 0.20066)
		(layer "F.Cu")
		(net "M_G_CPU0_SA_DQS_DP<6>")
	)
	(segment
		(start 443.139322 -301.434754)
		(end 443.450726 -301.434754)
		(width 0.20066)
		(layer "F.Cu")
		(net "M_G_CPU0_SA_DQS_DP<6>")
	)
	(segment
		(start 441.62218 -301.866808)
		(end 441.873132 -302.11776)
		(width 0.20066)
		(layer "F.Cu")
		(net "M_G_CPU0_SA_DQS_DP<6>")
	)
	(segment
		(start 376.136916 -272.103342)
		(end 376.136662 -272.639282)
		(width 0.20066)
		(layer "F.Cu")
		(net "M_G_CPU0_SA_DQS_DP<6>")
	)
	(segment
		(start 442.881258 -301.692818)
		(end 443.139322 -301.434754)
		(width 0.20066)
		(layer "F.Cu")
		(net "M_G_CPU0_SA_DQS_DP<6>")
	)
	(segment
		(start 446.713102 -301.689262)
		(end 447.158618 -302.134778)
		(width 0.20066)
		(layer "F.Cu")
		(net "M_G_CPU0_SA_DQS_DP<6>")
	)
	(segment
		(start 443.450726 -301.434754)
		(end 443.455552 -301.434754)
		(width 0.101854)
		(layer "F.Cu")
		(net "M_G_CPU0_SA_DQS_DP<6>")
	)
	(segment
		(start 443.462664 -301.441866)
		(end 445.47536 -301.441866)
		(width 0.1016)
		(layer "F.Cu")
		(net "M_G_CPU0_SA_DQS_DP<6>")
	)
	(segment
		(start 447.736214 -302.134778)
		(end 448.004184 -301.866808)
		(width 0.20066)
		(layer "F.Cu")
		(net "M_G_CPU0_SA_DQS_DP<6>")
	)
	(segment
		(start 445.804798 -301.4345)
		(end 446.05956 -301.689262)
		(width 0.20066)
		(layer "F.Cu")
		(net "M_G_CPU0_SA_DQS_DP<6>")
	)
	(segment
		(start 442.602874 -301.692818)
		(end 442.881258 -301.692818)
		(width 0.20066)
		(layer "F.Cu")
		(net "M_G_CPU0_SA_DQS_DP<6>")
	)
	(segment
		(start 427.230794 -296.349166)
		(end 426.782992 -296.349166)
		(width 0.18288)
		(layer "In6.Cu")
		(net "M_G_CPU0_SA_DQS_DP<6>")
	)
	(segment
		(start 428.791624 -297.501056)
		(end 428.382684 -297.501056)
		(width 0.18288)
		(layer "In6.Cu")
		(net "M_G_CPU0_SA_DQS_DP<6>")
	)
	(segment
		(start 409.468574 -292.348158)
		(end 407.492708 -291.529008)
		(width 0.18288)
		(layer "In6.Cu")
		(net "M_G_CPU0_SA_DQS_DP<6>")
	)
	(segment
		(start 425.350686 -295.737788)
		(end 425.105576 -295.492678)
		(width 0.18288)
		(layer "In6.Cu")
		(net "M_G_CPU0_SA_DQS_DP<6>")
	)
	(segment
		(start 437.047894 -301.695104)
		(end 436.346092 -301.695104)
		(width 0.18288)
		(layer "In6.Cu")
		(net "M_G_CPU0_SA_DQS_DP<6>")
	)
	(segment
		(start 377.216162 -272.219928)
		(end 377.2154 -272.220182)
		(width 0.088646)
		(layer "In6.Cu")
		(net "M_G_CPU0_SA_DQS_DP<6>")
	)
	(segment
		(start 437.643524 -302.290734)
		(end 437.047894 -301.695104)
		(width 0.18288)
		(layer "In6.Cu")
		(net "M_G_CPU0_SA_DQS_DP<6>")
	)
	(segment
		(start 382.447546 -272.140934)
		(end 382.432814 -272.14957)
		(width 0.088646)
		(layer "In6.Cu")
		(net "M_G_CPU0_SA_DQS_DP<6>")
	)
	(segment
		(start 432.497992 -299.930566)
		(end 432.193192 -299.930566)
		(width 0.18288)
		(layer "In6.Cu")
		(net "M_G_CPU0_SA_DQS_DP<6>")
	)
	(segment
		(start 413.40913 -292.081712)
		(end 412.902654 -292.081712)
		(width 0.18288)
		(layer "In6.Cu")
		(net "M_G_CPU0_SA_DQS_DP<6>")
	)
	(segment
		(start 383.387346 -272.140934)
		(end 383.372614 -272.14957)
		(width 0.088646)
		(layer "In6.Cu")
		(net "M_G_CPU0_SA_DQS_DP<6>")
	)
	(segment
		(start 388.452614 -273.597116)
		(end 388.192264 -273.597116)
		(width 0.088646)
		(layer "In6.Cu")
		(net "M_G_CPU0_SA_DQS_DP<6>")
	)
	(segment
		(start 378.688346 -272.140934)
		(end 378.673614 -272.14957)
		(width 0.088646)
		(layer "In6.Cu")
		(net "M_G_CPU0_SA_DQS_DP<6>")
	)
	(segment
		(start 439.654442 -302.094138)
		(end 439.028078 -302.094138)
		(width 0.18288)
		(layer "In6.Cu")
		(net "M_G_CPU0_SA_DQS_DP<6>")
	)
	(segment
		(start 431.43678 -299.174154)
		(end 430.464722 -299.174154)
		(width 0.18288)
		(layer "In6.Cu")
		(net "M_G_CPU0_SA_DQS_DP<6>")
	)
	(segment
		(start 421.944292 -294.901366)
		(end 421.26408 -294.901366)
		(width 0.18288)
		(layer "In6.Cu")
		(net "M_G_CPU0_SA_DQS_DP<6>")
	)
	(segment
		(start 422.802558 -295.759632)
		(end 421.944292 -294.901366)
		(width 0.18288)
		(layer "In6.Cu")
		(net "M_G_CPU0_SA_DQS_DP<6>")
	)
	(segment
		(start 402.95703 -288.7218)
		(end 402.95703 -280.643838)
		(width 0.18288)
		(layer "In6.Cu")
		(net "M_G_CPU0_SA_DQS_DP<6>")
	)
	(segment
		(start 426.782992 -296.349166)
		(end 426.171614 -295.737788)
		(width 0.18288)
		(layer "In6.Cu")
		(net "M_G_CPU0_SA_DQS_DP<6>")
	)
	(segment
		(start 424.923712 -295.492678)
		(end 424.921934 -295.4909)
		(width 0.18288)
		(layer "In6.Cu")
		(net "M_G_CPU0_SA_DQS_DP<6>")
	)
	(segment
		(start 439.028078 -302.094138)
		(end 438.831482 -302.290734)
		(width 0.18288)
		(layer "In6.Cu")
		(net "M_G_CPU0_SA_DQS_DP<6>")
	)
	(segment
		(start 425.105576 -295.492678)
		(end 424.923712 -295.492678)
		(width 0.18288)
		(layer "In6.Cu")
		(net "M_G_CPU0_SA_DQS_DP<6>")
	)
	(segment
		(start 389.215376 -273.537426)
		(end 388.535672 -273.537426)
		(width 0.18288)
		(layer "In6.Cu")
		(net "M_G_CPU0_SA_DQS_DP<6>")
	)
	(segment
		(start 381.507746 -272.140934)
		(end 381.493014 -272.14957)
		(width 0.088646)
		(layer "In6.Cu")
		(net "M_G_CPU0_SA_DQS_DP<6>")
	)
	(segment
		(start 439.881772 -301.866808)
		(end 439.654442 -302.094138)
		(width 0.18288)
		(layer "In6.Cu")
		(net "M_G_CPU0_SA_DQS_DP<6>")
	)
	(segment
		(start 376.706384 -272.582132)
		(end 376.649234 -272.639282)
		(width 0.088646)
		(layer "In6.Cu")
		(net "M_G_CPU0_SA_DQS_DP<6>")
	)
	(segment
		(start 376.649234 -272.639282)
		(end 376.136662 -272.639282)
		(width 0.088646)
		(layer "In6.Cu")
		(net "M_G_CPU0_SA_DQS_DP<6>")
	)
	(segment
		(start 421.26408 -294.901366)
		(end 421.005508 -294.642794)
		(width 0.18288)
		(layer "In6.Cu")
		(net "M_G_CPU0_SA_DQS_DP<6>")
	)
	(segment
		(start 420.47668 -294.642794)
		(end 420.196264 -294.92321)
		(width 0.18288)
		(layer "In6.Cu")
		(net "M_G_CPU0_SA_DQS_DP<6>")
	)
	(segment
		(start 376.88774 -272.315686)
		(end 376.880374 -272.320004)
		(width 0.088646)
		(layer "In6.Cu")
		(net "M_G_CPU0_SA_DQS_DP<6>")
	)
	(segment
		(start 424.701716 -295.492678)
		(end 424.576748 -295.492678)
		(width 0.18288)
		(layer "In6.Cu")
		(net "M_G_CPU0_SA_DQS_DP<6>")
	)
	(segment
		(start 377.234958 -272.219674)
		(end 377.216162 -272.219928)
		(width 0.088646)
		(layer "In6.Cu")
		(net "M_G_CPU0_SA_DQS_DP<6>")
	)
	(segment
		(start 377.099322 -272.243042)
		(end 377.07951 -272.247106)
		(width 0.088646)
		(layer "In6.Cu")
		(net "M_G_CPU0_SA_DQS_DP<6>")
	)
	(segment
		(start 388.535672 -273.537426)
		(end 388.512304 -273.537426)
		(width 0.088646)
		(layer "In6.Cu")
		(net "M_G_CPU0_SA_DQS_DP<6>")
	)
	(segment
		(start 377.734068 -272.150078)
		(end 377.616466 -272.217642)
		(width 0.088646)
		(layer "In6.Cu")
		(net "M_G_CPU0_SA_DQS_DP<6>")
	)
	(segment
		(start 420.196264 -294.92321)
		(end 416.78098 -294.92321)
		(width 0.18288)
		(layer "In6.Cu")
		(net "M_G_CPU0_SA_DQS_DP<6>")
	)
	(segment
		(start 377.616466 -272.217642)
		(end 377.57862 -272.216372)
		(width 0.088646)
		(layer "In6.Cu")
		(net "M_G_CPU0_SA_DQS_DP<6>")
	)
	(segment
		(start 424.576748 -295.492678)
		(end 424.309794 -295.759632)
		(width 0.18288)
		(layer "In6.Cu")
		(net "M_G_CPU0_SA_DQS_DP<6>")
	)
	(segment
		(start 435.56428 -301.44212)
		(end 435.295548 -301.710852)
		(width 0.18288)
		(layer "In6.Cu")
		(net "M_G_CPU0_SA_DQS_DP<6>")
	)
	(segment
		(start 388.512304 -273.537426)
		(end 388.452614 -273.597116)
		(width 0.088646)
		(layer "In6.Cu")
		(net "M_G_CPU0_SA_DQS_DP<6>")
	)
	(segment
		(start 376.889264 -272.314924)
		(end 376.88774 -272.315686)
		(width 0.088646)
		(layer "In6.Cu")
		(net "M_G_CPU0_SA_DQS_DP<6>")
	)
	(segment
		(start 407.492708 -291.529008)
		(end 405.764238 -291.529008)
		(width 0.18288)
		(layer "In6.Cu")
		(net "M_G_CPU0_SA_DQS_DP<6>")
	)
	(segment
		(start 430.464722 -299.174154)
		(end 428.791624 -297.501056)
		(width 0.18288)
		(layer "In6.Cu")
		(net "M_G_CPU0_SA_DQS_DP<6>")
	)
	(segment
		(start 436.346092 -301.695104)
		(end 436.093108 -301.44212)
		(width 0.18288)
		(layer "In6.Cu")
		(net "M_G_CPU0_SA_DQS_DP<6>")
	)
	(segment
		(start 412.902654 -292.081712)
		(end 412.636208 -292.348158)
		(width 0.18288)
		(layer "In6.Cu")
		(net "M_G_CPU0_SA_DQS_DP<6>")
	)
	(segment
		(start 424.703494 -295.4909)
		(end 424.701716 -295.492678)
		(width 0.18288)
		(layer "In6.Cu")
		(net "M_G_CPU0_SA_DQS_DP<6>")
	)
	(segment
		(start 416.78098 -294.92321)
		(end 414.191196 -292.333426)
		(width 0.18288)
		(layer "In6.Cu")
		(net "M_G_CPU0_SA_DQS_DP<6>")
	)
	(segment
		(start 412.636208 -292.348158)
		(end 409.468574 -292.348158)
		(width 0.18288)
		(layer "In6.Cu")
		(net "M_G_CPU0_SA_DQS_DP<6>")
	)
	(segment
		(start 424.309794 -295.759632)
		(end 422.802558 -295.759632)
		(width 0.18288)
		(layer "In6.Cu")
		(net "M_G_CPU0_SA_DQS_DP<6>")
	)
	(segment
		(start 414.191196 -292.333426)
		(end 413.660844 -292.333426)
		(width 0.18288)
		(layer "In6.Cu")
		(net "M_G_CPU0_SA_DQS_DP<6>")
	)
	(segment
		(start 377.07951 -272.247106)
		(end 377.029726 -272.26768)
		(width 0.088646)
		(layer "In6.Cu")
		(net "M_G_CPU0_SA_DQS_DP<6>")
	)
	(segment
		(start 428.382684 -297.501056)
		(end 427.230794 -296.349166)
		(width 0.18288)
		(layer "In6.Cu")
		(net "M_G_CPU0_SA_DQS_DP<6>")
	)
	(segment
		(start 413.660844 -292.333426)
		(end 413.40913 -292.081712)
		(width 0.18288)
		(layer "In6.Cu")
		(net "M_G_CPU0_SA_DQS_DP<6>")
	)
	(segment
		(start 405.764238 -291.529008)
		(end 402.95703 -288.7218)
		(width 0.18288)
		(layer "In6.Cu")
		(net "M_G_CPU0_SA_DQS_DP<6>")
	)
	(segment
		(start 377.235466 -272.219674)
		(end 377.234958 -272.219674)
		(width 0.088646)
		(layer "In6.Cu")
		(net "M_G_CPU0_SA_DQS_DP<6>")
	)
	(segment
		(start 432.193192 -299.930566)
		(end 431.43678 -299.174154)
		(width 0.18288)
		(layer "In6.Cu")
		(net "M_G_CPU0_SA_DQS_DP<6>")
	)
	(segment
		(start 424.921934 -295.4909)
		(end 424.703494 -295.4909)
		(width 0.18288)
		(layer "In6.Cu")
		(net "M_G_CPU0_SA_DQS_DP<6>")
	)
	(segment
		(start 380.178564 -272.14957)
		(end 380.16815 -272.143474)
		(width 0.088646)
		(layer "In6.Cu")
		(net "M_G_CPU0_SA_DQS_DP<6>")
	)
	(segment
		(start 377.570746 -272.216372)
		(end 377.235466 -272.219674)
		(width 0.088646)
		(layer "In6.Cu")
		(net "M_G_CPU0_SA_DQS_DP<6>")
	)
	(segment
		(start 388.192264 -273.597116)
		(end 386.827522 -272.232374)
		(width 0.088646)
		(layer "In6.Cu")
		(net "M_G_CPU0_SA_DQS_DP<6>")
	)
	(segment
		(start 396.258288 -273.945096)
		(end 390.199626 -273.945096)
		(width 0.18288)
		(layer "In6.Cu")
		(net "M_G_CPU0_SA_DQS_DP<6>")
	)
	(segment
		(start 421.005508 -294.642794)
		(end 420.819326 -294.642794)
		(width 0.18288)
		(layer "In6.Cu")
		(net "M_G_CPU0_SA_DQS_DP<6>")
	)
	(segment
		(start 390.199626 -273.945096)
		(end 389.215376 -273.537426)
		(width 0.18288)
		(layer "In6.Cu")
		(net "M_G_CPU0_SA_DQS_DP<6>")
	)
	(segment
		(start 435.295548 -301.710852)
		(end 434.278278 -301.710852)
		(width 0.18288)
		(layer "In6.Cu")
		(net "M_G_CPU0_SA_DQS_DP<6>")
	)
	(segment
		(start 420.606474 -294.640762)
		(end 420.604442 -294.642794)
		(width 0.18288)
		(layer "In6.Cu")
		(net "M_G_CPU0_SA_DQS_DP<6>")
	)
	(segment
		(start 377.2154 -272.220182)
		(end 377.099322 -272.243042)
		(width 0.088646)
		(layer "In6.Cu")
		(net "M_G_CPU0_SA_DQS_DP<6>")
	)
	(segment
		(start 385.266946 -272.140934)
		(end 385.252214 -272.14957)
		(width 0.088646)
		(layer "In6.Cu")
		(net "M_G_CPU0_SA_DQS_DP<6>")
	)
	(segment
		(start 420.817294 -294.640762)
		(end 420.606474 -294.640762)
		(width 0.18288)
		(layer "In6.Cu")
		(net "M_G_CPU0_SA_DQS_DP<6>")
	)
	(segment
		(start 380.563374 -272.143474)
		(end 380.55296 -272.14957)
		(width 0.088646)
		(layer "In6.Cu")
		(net "M_G_CPU0_SA_DQS_DP<6>")
	)
	(segment
		(start 386.209032 -272.139918)
		(end 386.194808 -272.148046)
		(width 0.088646)
		(layer "In6.Cu")
		(net "M_G_CPU0_SA_DQS_DP<6>")
	)
	(segment
		(start 420.604442 -294.642794)
		(end 420.47668 -294.642794)
		(width 0.18288)
		(layer "In6.Cu")
		(net "M_G_CPU0_SA_DQS_DP<6>")
	)
	(segment
		(start 384.327146 -272.140934)
		(end 384.312414 -272.14957)
		(width 0.088646)
		(layer "In6.Cu")
		(net "M_G_CPU0_SA_DQS_DP<6>")
	)
	(segment
		(start 434.278278 -301.710852)
		(end 432.497992 -299.930566)
		(width 0.18288)
		(layer "In6.Cu")
		(net "M_G_CPU0_SA_DQS_DP<6>")
	)
	(segment
		(start 386.194808 -272.148046)
		(end 386.192014 -272.14957)
		(width 0.088646)
		(layer "In6.Cu")
		(net "M_G_CPU0_SA_DQS_DP<6>")
	)
	(segment
		(start 420.819326 -294.642794)
		(end 420.817294 -294.640762)
		(width 0.18288)
		(layer "In6.Cu")
		(net "M_G_CPU0_SA_DQS_DP<6>")
	)
	(segment
		(start 402.95703 -280.643838)
		(end 396.258288 -273.945096)
		(width 0.18288)
		(layer "In6.Cu")
		(net "M_G_CPU0_SA_DQS_DP<6>")
	)
	(segment
		(start 436.093108 -301.44212)
		(end 435.56428 -301.44212)
		(width 0.18288)
		(layer "In6.Cu")
		(net "M_G_CPU0_SA_DQS_DP<6>")
	)
	(segment
		(start 377.57862 -272.216372)
		(end 377.570746 -272.216372)
		(width 0.088646)
		(layer "In6.Cu")
		(net "M_G_CPU0_SA_DQS_DP<6>")
	)
	(segment
		(start 438.831482 -302.290734)
		(end 437.643524 -302.290734)
		(width 0.18288)
		(layer "In6.Cu")
		(net "M_G_CPU0_SA_DQS_DP<6>")
	)
	(segment
		(start 426.171614 -295.737788)
		(end 425.350686 -295.737788)
		(width 0.18288)
		(layer "In6.Cu")
		(net "M_G_CPU0_SA_DQS_DP<6>")
	)
	(arc
		(start 382.432814 -272.14957)
		(mid 382.245616 -272.199713)
		(end 382.058418 -272.14957)
		(width 0.088646)
		(layer "In6.Cu")
		(net "M_G_CPU0_SA_DQS_DP<6>")
	)
	(arc
		(start 381.493014 -272.14957)
		(mid 381.305816 -272.199713)
		(end 381.118618 -272.14957)
		(width 0.088646)
		(layer "In6.Cu")
		(net "M_G_CPU0_SA_DQS_DP<6>")
	)
	(arc
		(start 378.673614 -272.14957)
		(mid 378.486416 -272.199713)
		(end 378.299218 -272.14957)
		(width 0.088646)
		(layer "In6.Cu")
		(net "M_G_CPU0_SA_DQS_DP<6>")
	)
	(arc
		(start 379.239018 -272.14957)
		(mid 378.964789 -272.073645)
		(end 378.688346 -272.140934)
		(width 0.088646)
		(layer "In6.Cu")
		(net "M_G_CPU0_SA_DQS_DP<6>")
	)
	(arc
		(start 385.252214 -272.14957)
		(mid 385.065016 -272.199713)
		(end 384.877818 -272.14957)
		(width 0.088646)
		(layer "In6.Cu")
		(net "M_G_CPU0_SA_DQS_DP<6>")
	)
	(arc
		(start 381.118618 -272.14957)
		(mid 380.841805 -272.073734)
		(end 380.563374 -272.143474)
		(width 0.088646)
		(layer "In6.Cu")
		(net "M_G_CPU0_SA_DQS_DP<6>")
	)
	(arc
		(start 385.817618 -272.14957)
		(mid 385.543389 -272.073645)
		(end 385.266946 -272.140934)
		(width 0.088646)
		(layer "In6.Cu")
		(net "M_G_CPU0_SA_DQS_DP<6>")
	)
	(arc
		(start 378.299218 -272.14957)
		(mid 378.298837 -272.149824)
		(end 378.298456 -272.150078)
		(width 0.088646)
		(layer "In6.Cu")
		(net "M_G_CPU0_SA_DQS_DP<6>")
	)
	(arc
		(start 386.827522 -272.232374)
		(mid 386.533535 -272.084214)
		(end 386.209032 -272.139918)
		(width 0.088646)
		(layer "In6.Cu")
		(net "M_G_CPU0_SA_DQS_DP<6>")
	)
	(arc
		(start 383.938018 -272.14957)
		(mid 383.663789 -272.073645)
		(end 383.387346 -272.140934)
		(width 0.088646)
		(layer "In6.Cu")
		(net "M_G_CPU0_SA_DQS_DP<6>")
	)
	(arc
		(start 384.877818 -272.14957)
		(mid 384.603589 -272.073645)
		(end 384.327146 -272.140934)
		(width 0.088646)
		(layer "In6.Cu")
		(net "M_G_CPU0_SA_DQS_DP<6>")
	)
	(arc
		(start 380.16815 -272.143474)
		(mid 379.889972 -272.073782)
		(end 379.613414 -272.14957)
		(width 0.088646)
		(layer "In6.Cu")
		(net "M_G_CPU0_SA_DQS_DP<6>")
	)
	(arc
		(start 378.298456 -272.150078)
		(mid 378.016262 -272.074522)
		(end 377.734068 -272.150078)
		(width 0.088646)
		(layer "In6.Cu")
		(net "M_G_CPU0_SA_DQS_DP<6>")
	)
	(arc
		(start 386.192014 -272.14957)
		(mid 386.004816 -272.199713)
		(end 385.817618 -272.14957)
		(width 0.088646)
		(layer "In6.Cu")
		(net "M_G_CPU0_SA_DQS_DP<6>")
	)
	(arc
		(start 377.029726 -272.26768)
		(mid 376.957129 -272.284272)
		(end 376.889264 -272.314924)
		(width 0.088646)
		(layer "In6.Cu")
		(net "M_G_CPU0_SA_DQS_DP<6>")
	)
	(arc
		(start 376.880374 -272.320004)
		(mid 376.764565 -272.431933)
		(end 376.706384 -272.582132)
		(width 0.088646)
		(layer "In6.Cu")
		(net "M_G_CPU0_SA_DQS_DP<6>")
	)
	(arc
		(start 382.058418 -272.14957)
		(mid 381.784189 -272.073645)
		(end 381.507746 -272.140934)
		(width 0.088646)
		(layer "In6.Cu")
		(net "M_G_CPU0_SA_DQS_DP<6>")
	)
	(arc
		(start 382.998218 -272.14957)
		(mid 382.723989 -272.073645)
		(end 382.447546 -272.140934)
		(width 0.088646)
		(layer "In6.Cu")
		(net "M_G_CPU0_SA_DQS_DP<6>")
	)
	(arc
		(start 380.55296 -272.14957)
		(mid 380.365762 -272.199713)
		(end 380.178564 -272.14957)
		(width 0.088646)
		(layer "In6.Cu")
		(net "M_G_CPU0_SA_DQS_DP<6>")
	)
	(arc
		(start 379.613414 -272.14957)
		(mid 379.426216 -272.199713)
		(end 379.239018 -272.14957)
		(width 0.088646)
		(layer "In6.Cu")
		(net "M_G_CPU0_SA_DQS_DP<6>")
	)
	(arc
		(start 383.372614 -272.14957)
		(mid 383.185416 -272.199713)
		(end 382.998218 -272.14957)
		(width 0.088646)
		(layer "In6.Cu")
		(net "M_G_CPU0_SA_DQS_DP<6>")
	)
	(arc
		(start 384.312414 -272.14957)
		(mid 384.125216 -272.199713)
		(end 383.938018 -272.14957)
		(width 0.088646)
		(layer "In6.Cu")
		(net "M_G_CPU0_SA_DQS_DP<6>")
	)
	(segment
		(start 446.05956 -311.039256)
		(end 446.713102 -311.039256)
		(width 0.20066)
		(layer "F.Cu")
		(net "M_G_CPU0_SA_DQS_DP<5>")
	)
	(segment
		(start 443.462664 -310.79186)
		(end 445.47536 -310.79186)
		(width 0.1016)
		(layer "F.Cu")
		(net "M_G_CPU0_SA_DQS_DP<5>")
	)
	(segment
		(start 443.139322 -310.784748)
		(end 443.450726 -310.784748)
		(width 0.20066)
		(layer "F.Cu")
		(net "M_G_CPU0_SA_DQS_DP<5>")
	)
	(segment
		(start 439.923682 -311.216548)
		(end 439.923936 -311.216802)
		(width 0.20066)
		(layer "F.Cu")
		(net "M_G_CPU0_SA_DQS_DP<5>")
	)
	(segment
		(start 447.736214 -311.484772)
		(end 448.004184 -311.216802)
		(width 0.20066)
		(layer "F.Cu")
		(net "M_G_CPU0_SA_DQS_DP<5>")
	)
	(segment
		(start 445.482726 -310.784494)
		(end 445.804798 -310.784494)
		(width 0.20066)
		(layer "F.Cu")
		(net "M_G_CPU0_SA_DQS_DP<5>")
	)
	(segment
		(start 442.177932 -311.467754)
		(end 442.602874 -311.042812)
		(width 0.20066)
		(layer "F.Cu")
		(net "M_G_CPU0_SA_DQS_DP<5>")
	)
	(segment
		(start 442.881258 -311.042812)
		(end 443.139322 -310.784748)
		(width 0.20066)
		(layer "F.Cu")
		(net "M_G_CPU0_SA_DQS_DP<5>")
	)
	(segment
		(start 441.028582 -311.216802)
		(end 441.62218 -311.216802)
		(width 0.20066)
		(layer "F.Cu")
		(net "M_G_CPU0_SA_DQS_DP<5>")
	)
	(segment
		(start 447.158618 -311.484772)
		(end 447.736214 -311.484772)
		(width 0.20066)
		(layer "F.Cu")
		(net "M_G_CPU0_SA_DQS_DP<5>")
	)
	(segment
		(start 439.923936 -311.216802)
		(end 441.028582 -311.216802)
		(width 0.20066)
		(layer "F.Cu")
		(net "M_G_CPU0_SA_DQS_DP<5>")
	)
	(segment
		(start 441.62218 -311.216802)
		(end 441.873132 -311.467754)
		(width 0.20066)
		(layer "F.Cu")
		(net "M_G_CPU0_SA_DQS_DP<5>")
	)
	(segment
		(start 443.450726 -310.784748)
		(end 443.455552 -310.784748)
		(width 0.101854)
		(layer "F.Cu")
		(net "M_G_CPU0_SA_DQS_DP<5>")
	)
	(segment
		(start 442.602874 -311.042812)
		(end 442.881258 -311.042812)
		(width 0.20066)
		(layer "F.Cu")
		(net "M_G_CPU0_SA_DQS_DP<5>")
	)
	(segment
		(start 448.004184 -311.216802)
		(end 448.572382 -311.216802)
		(width 0.20066)
		(layer "F.Cu")
		(net "M_G_CPU0_SA_DQS_DP<5>")
	)
	(segment
		(start 446.713102 -311.039256)
		(end 447.158618 -311.484772)
		(width 0.20066)
		(layer "F.Cu")
		(net "M_G_CPU0_SA_DQS_DP<5>")
	)
	(segment
		(start 441.873132 -311.467754)
		(end 442.177932 -311.467754)
		(width 0.20066)
		(layer "F.Cu")
		(net "M_G_CPU0_SA_DQS_DP<5>")
	)
	(segment
		(start 445.804798 -310.784494)
		(end 446.05956 -311.039256)
		(width 0.20066)
		(layer "F.Cu")
		(net "M_G_CPU0_SA_DQS_DP<5>")
	)
	(segment
		(start 379.426216 -274.545044)
		(end 379.426216 -275.08073)
		(width 0.20066)
		(layer "F.Cu")
		(net "M_G_CPU0_SA_DQS_DP<5>")
	)
	(segment
		(start 379.425962 -274.54479)
		(end 379.426216 -274.545044)
		(width 0.20066)
		(layer "F.Cu")
		(net "M_G_CPU0_SA_DQS_DP<5>")
	)
	(segment
		(start 443.455552 -310.784748)
		(end 443.462664 -310.79186)
		(width 0.1016)
		(layer "F.Cu")
		(net "M_G_CPU0_SA_DQS_DP<5>")
	)
	(segment
		(start 445.47536 -310.79186)
		(end 445.482726 -310.784494)
		(width 0.1016)
		(layer "F.Cu")
		(net "M_G_CPU0_SA_DQS_DP<5>")
	)
	(segment
		(start 436.333392 -311.058052)
		(end 436.067962 -310.792622)
		(width 0.18288)
		(layer "In4.Cu")
		(net "M_G_CPU0_SA_DQS_DP<5>")
	)
	(segment
		(start 383.467864 -274.591272)
		(end 383.467356 -274.591526)
		(width 0.088646)
		(layer "In4.Cu")
		(net "M_G_CPU0_SA_DQS_DP<5>")
	)
	(segment
		(start 385.347464 -276.219158)
		(end 385.338574 -276.214078)
		(width 0.088646)
		(layer "In4.Cu")
		(net "M_G_CPU0_SA_DQS_DP<5>")
	)
	(segment
		(start 411.120082 -310.024272)
		(end 409.22194 -309.238142)
		(width 0.18288)
		(layer "In4.Cu")
		(net "M_G_CPU0_SA_DQS_DP<5>")
	)
	(segment
		(start 406.134062 -307.660294)
		(end 405.866346 -307.392578)
		(width 0.18288)
		(layer "In4.Cu")
		(net "M_G_CPU0_SA_DQS_DP<5>")
	)
	(segment
		(start 420.26713 -313.617356)
		(end 419.809422 -313.617356)
		(width 0.18288)
		(layer "In4.Cu")
		(net "M_G_CPU0_SA_DQS_DP<5>")
	)
	(segment
		(start 421.36949 -313.600592)
		(end 421.193468 -313.600592)
		(width 0.18288)
		(layer "In4.Cu")
		(net "M_G_CPU0_SA_DQS_DP<5>")
	)
	(segment
		(start 432.980846 -311.350406)
		(end 432.19116 -311.350406)
		(width 0.18288)
		(layer "In4.Cu")
		(net "M_G_CPU0_SA_DQS_DP<5>")
	)
	(segment
		(start 412.119572 -311.024016)
		(end 411.120082 -310.024272)
		(width 0.18288)
		(layer "In4.Cu")
		(net "M_G_CPU0_SA_DQS_DP<5>")
	)
	(segment
		(start 414.062164 -311.04332)
		(end 413.514032 -311.04332)
		(width 0.18288)
		(layer "In4.Cu")
		(net "M_G_CPU0_SA_DQS_DP<5>")
	)
	(segment
		(start 435.972966 -310.792622)
		(end 435.972712 -310.792368)
		(width 0.18288)
		(layer "In4.Cu")
		(net "M_G_CPU0_SA_DQS_DP<5>")
	)
	(segment
		(start 388.629906 -278.79294)
		(end 388.613396 -278.77643)
		(width 0.088646)
		(layer "In4.Cu")
		(net "M_G_CPU0_SA_DQS_DP<5>")
	)
	(segment
		(start 404.058628 -307.005482)
		(end 396.857982 -296.23004)
		(width 0.18288)
		(layer "In4.Cu")
		(net "M_G_CPU0_SA_DQS_DP<5>")
	)
	(segment
		(start 404.677626 -307.62448)
		(end 404.058628 -307.005482)
		(width 0.18288)
		(layer "In4.Cu")
		(net "M_G_CPU0_SA_DQS_DP<5>")
	)
	(segment
		(start 384.327146 -275.396706)
		(end 384.312414 -275.405342)
		(width 0.088646)
		(layer "In4.Cu")
		(net "M_G_CPU0_SA_DQS_DP<5>")
	)
	(segment
		(start 380.782068 -274.705826)
		(end 380.367032 -274.705826)
		(width 0.088646)
		(layer "In4.Cu")
		(net "M_G_CPU0_SA_DQS_DP<5>")
	)
	(segment
		(start 409.22194 -309.238142)
		(end 409.22194 -309.237888)
		(width 0.18288)
		(layer "In4.Cu")
		(net "M_G_CPU0_SA_DQS_DP<5>")
	)
	(segment
		(start 381.588264 -274.591272)
		(end 381.588518 -274.59178)
		(width 0.088646)
		(layer "In4.Cu")
		(net "M_G_CPU0_SA_DQS_DP<5>")
	)
	(segment
		(start 406.520142 -307.660294)
		(end 406.134062 -307.660294)
		(width 0.18288)
		(layer "In4.Cu")
		(net "M_G_CPU0_SA_DQS_DP<5>")
	)
	(segment
		(start 418.772086 -312.92419)
		(end 418.013896 -312.417714)
		(width 0.18288)
		(layer "In4.Cu")
		(net "M_G_CPU0_SA_DQS_DP<5>")
	)
	(segment
		(start 407.303478 -308.443376)
		(end 406.520142 -307.660294)
		(width 0.18288)
		(layer "In4.Cu")
		(net "M_G_CPU0_SA_DQS_DP<5>")
	)
	(segment
		(start 424.613832 -312.492136)
		(end 424.312588 -312.79338)
		(width 0.18288)
		(layer "In4.Cu")
		(net "M_G_CPU0_SA_DQS_DP<5>")
	)
	(segment
		(start 416.582352 -311.982866)
		(end 416.330638 -311.982866)
		(width 0.18288)
		(layer "In4.Cu")
		(net "M_G_CPU0_SA_DQS_DP<5>")
	)
	(segment
		(start 405.866346 -307.392578)
		(end 405.414734 -307.392578)
		(width 0.18288)
		(layer "In4.Cu")
		(net "M_G_CPU0_SA_DQS_DP<5>")
	)
	(segment
		(start 390.34593 -280.508964)
		(end 388.629906 -278.79294)
		(width 0.18288)
		(layer "In4.Cu")
		(net "M_G_CPU0_SA_DQS_DP<5>")
	)
	(segment
		(start 396.857982 -296.23004)
		(end 391.178796 -282.519882)
		(width 0.18288)
		(layer "In4.Cu")
		(net "M_G_CPU0_SA_DQS_DP<5>")
	)
	(segment
		(start 386.71119 -276.958552)
		(end 386.505958 -276.958552)
		(width 0.088646)
		(layer "In4.Cu")
		(net "M_G_CPU0_SA_DQS_DP<5>")
	)
	(segment
		(start 425.743116 -312.763662)
		(end 425.316904 -312.763662)
		(width 0.18288)
		(layer "In4.Cu")
		(net "M_G_CPU0_SA_DQS_DP<5>")
	)
	(segment
		(start 385.629912 -276.708616)
		(end 385.629912 -276.69871)
		(width 0.088646)
		(layer "In4.Cu")
		(net "M_G_CPU0_SA_DQS_DP<5>")
	)
	(segment
		(start 385.817364 -277.032974)
		(end 385.808474 -277.027894)
		(width 0.088646)
		(layer "In4.Cu")
		(net "M_G_CPU0_SA_DQS_DP<5>")
	)
	(segment
		(start 391.178796 -282.519882)
		(end 390.34593 -280.508964)
		(width 0.18288)
		(layer "In4.Cu")
		(net "M_G_CPU0_SA_DQS_DP<5>")
	)
	(segment
		(start 429.302418 -311.92597)
		(end 426.580808 -311.92597)
		(width 0.18288)
		(layer "In4.Cu")
		(net "M_G_CPU0_SA_DQS_DP<5>")
	)
	(segment
		(start 379.995938 -275.02358)
		(end 379.938788 -275.08073)
		(width 0.088646)
		(layer "In4.Cu")
		(net "M_G_CPU0_SA_DQS_DP<5>")
	)
	(segment
		(start 388.613396 -278.77643)
		(end 388.52856 -278.77643)
		(width 0.088646)
		(layer "In4.Cu")
		(net "M_G_CPU0_SA_DQS_DP<5>")
	)
	(segment
		(start 439.923682 -311.216548)
		(end 439.683398 -311.456832)
		(width 0.18288)
		(layer "In4.Cu")
		(net "M_G_CPU0_SA_DQS_DP<5>")
	)
	(segment
		(start 421.193468 -313.600592)
		(end 420.93515 -313.342274)
		(width 0.18288)
		(layer "In4.Cu")
		(net "M_G_CPU0_SA_DQS_DP<5>")
	)
	(segment
		(start 435.621176 -310.792368)
		(end 435.620922 -310.792622)
		(width 0.18288)
		(layer "In4.Cu")
		(net "M_G_CPU0_SA_DQS_DP<5>")
	)
	(segment
		(start 435.301898 -311.094628)
		(end 434.266848 -311.094628)
		(width 0.18288)
		(layer "In4.Cu")
		(net "M_G_CPU0_SA_DQS_DP<5>")
	)
	(segment
		(start 419.809422 -313.617356)
		(end 418.772086 -312.92419)
		(width 0.18288)
		(layer "In4.Cu")
		(net "M_G_CPU0_SA_DQS_DP<5>")
	)
	(segment
		(start 413.19577 -310.725058)
		(end 412.80334 -310.725058)
		(width 0.18288)
		(layer "In4.Cu")
		(net "M_G_CPU0_SA_DQS_DP<5>")
	)
	(segment
		(start 412.504382 -311.024016)
		(end 412.119572 -311.024016)
		(width 0.18288)
		(layer "In4.Cu")
		(net "M_G_CPU0_SA_DQS_DP<5>")
	)
	(segment
		(start 423.309288 -312.79338)
		(end 421.36949 -313.600592)
		(width 0.18288)
		(layer "In4.Cu")
		(net "M_G_CPU0_SA_DQS_DP<5>")
	)
	(segment
		(start 418.013896 -312.417714)
		(end 416.582352 -311.982866)
		(width 0.18288)
		(layer "In4.Cu")
		(net "M_G_CPU0_SA_DQS_DP<5>")
	)
	(segment
		(start 439.683398 -311.456832)
		(end 439.388504 -311.456832)
		(width 0.18288)
		(layer "In4.Cu")
		(net "M_G_CPU0_SA_DQS_DP<5>")
	)
	(segment
		(start 436.067962 -310.792622)
		(end 435.972966 -310.792622)
		(width 0.18288)
		(layer "In4.Cu")
		(net "M_G_CPU0_SA_DQS_DP<5>")
	)
	(segment
		(start 412.80334 -310.725058)
		(end 412.504382 -311.024016)
		(width 0.18288)
		(layer "In4.Cu")
		(net "M_G_CPU0_SA_DQS_DP<5>")
	)
	(segment
		(start 387.757416 -278.004778)
		(end 386.71119 -276.958552)
		(width 0.088646)
		(layer "In4.Cu")
		(net "M_G_CPU0_SA_DQS_DP<5>")
	)
	(segment
		(start 409.22194 -309.237888)
		(end 407.303478 -308.443376)
		(width 0.18288)
		(layer "In4.Cu")
		(net "M_G_CPU0_SA_DQS_DP<5>")
	)
	(segment
		(start 420.93515 -313.342274)
		(end 420.542212 -313.342274)
		(width 0.18288)
		(layer "In4.Cu")
		(net "M_G_CPU0_SA_DQS_DP<5>")
	)
	(segment
		(start 382.902968 -274.59178)
		(end 382.90246 -274.591272)
		(width 0.088646)
		(layer "In4.Cu")
		(net "M_G_CPU0_SA_DQS_DP<5>")
	)
	(segment
		(start 413.514032 -311.04332)
		(end 413.19577 -310.725058)
		(width 0.18288)
		(layer "In4.Cu")
		(net "M_G_CPU0_SA_DQS_DP<5>")
	)
	(segment
		(start 386.192014 -277.033228)
		(end 386.19176 -277.032974)
		(width 0.088646)
		(layer "In4.Cu")
		(net "M_G_CPU0_SA_DQS_DP<5>")
	)
	(segment
		(start 416.330638 -311.982866)
		(end 415.688526 -311.716928)
		(width 0.18288)
		(layer "In4.Cu")
		(net "M_G_CPU0_SA_DQS_DP<5>")
	)
	(segment
		(start 435.603904 -310.792622)
		(end 435.301898 -311.094628)
		(width 0.18288)
		(layer "In4.Cu")
		(net "M_G_CPU0_SA_DQS_DP<5>")
	)
	(segment
		(start 388.52856 -278.77643)
		(end 387.757416 -278.005286)
		(width 0.088646)
		(layer "In4.Cu")
		(net "M_G_CPU0_SA_DQS_DP<5>")
	)
	(segment
		(start 383.938018 -275.405342)
		(end 383.929128 -275.400262)
		(width 0.088646)
		(layer "In4.Cu")
		(net "M_G_CPU0_SA_DQS_DP<5>")
	)
	(segment
		(start 382.528064 -274.591272)
		(end 382.513332 -274.582636)
		(width 0.088646)
		(layer "In4.Cu")
		(net "M_G_CPU0_SA_DQS_DP<5>")
	)
	(segment
		(start 435.620922 -310.792622)
		(end 435.603904 -310.792622)
		(width 0.18288)
		(layer "In4.Cu")
		(net "M_G_CPU0_SA_DQS_DP<5>")
	)
	(segment
		(start 434.266848 -311.094628)
		(end 432.980846 -311.350406)
		(width 0.18288)
		(layer "In4.Cu")
		(net "M_G_CPU0_SA_DQS_DP<5>")
	)
	(segment
		(start 420.542212 -313.342274)
		(end 420.26713 -313.617356)
		(width 0.18288)
		(layer "In4.Cu")
		(net "M_G_CPU0_SA_DQS_DP<5>")
	)
	(segment
		(start 426.580808 -311.92597)
		(end 425.743116 -312.763662)
		(width 0.18288)
		(layer "In4.Cu")
		(net "M_G_CPU0_SA_DQS_DP<5>")
	)
	(segment
		(start 380.178818 -274.756372)
		(end 380.169928 -274.761452)
		(width 0.088646)
		(layer "In4.Cu")
		(net "M_G_CPU0_SA_DQS_DP<5>")
	)
	(segment
		(start 439.388504 -311.456832)
		(end 438.94756 -311.639458)
		(width 0.18288)
		(layer "In4.Cu")
		(net "M_G_CPU0_SA_DQS_DP<5>")
	)
	(segment
		(start 436.53837 -311.058052)
		(end 436.333392 -311.058052)
		(width 0.18288)
		(layer "In4.Cu")
		(net "M_G_CPU0_SA_DQS_DP<5>")
	)
	(segment
		(start 432.19116 -311.350406)
		(end 429.302418 -311.92597)
		(width 0.18288)
		(layer "In4.Cu")
		(net "M_G_CPU0_SA_DQS_DP<5>")
	)
	(segment
		(start 438.94756 -311.639458)
		(end 437.940958 -311.639458)
		(width 0.18288)
		(layer "In4.Cu")
		(net "M_G_CPU0_SA_DQS_DP<5>")
	)
	(segment
		(start 435.972712 -310.792368)
		(end 435.621176 -310.792368)
		(width 0.18288)
		(layer "In4.Cu")
		(net "M_G_CPU0_SA_DQS_DP<5>")
	)
	(segment
		(start 425.045378 -312.492136)
		(end 424.613832 -312.492136)
		(width 0.18288)
		(layer "In4.Cu")
		(net "M_G_CPU0_SA_DQS_DP<5>")
	)
	(segment
		(start 379.938788 -275.08073)
		(end 379.426216 -275.08073)
		(width 0.088646)
		(layer "In4.Cu")
		(net "M_G_CPU0_SA_DQS_DP<5>")
	)
	(segment
		(start 437.940958 -311.639458)
		(end 436.53837 -311.058052)
		(width 0.18288)
		(layer "In4.Cu")
		(net "M_G_CPU0_SA_DQS_DP<5>")
	)
	(segment
		(start 405.414734 -307.392578)
		(end 405.182578 -307.62448)
		(width 0.18288)
		(layer "In4.Cu")
		(net "M_G_CPU0_SA_DQS_DP<5>")
	)
	(segment
		(start 387.757416 -278.005286)
		(end 387.757416 -278.004778)
		(width 0.088646)
		(layer "In4.Cu")
		(net "M_G_CPU0_SA_DQS_DP<5>")
	)
	(segment
		(start 381.023368 -274.591526)
		(end 380.88443 -274.671282)
		(width 0.088646)
		(layer "In4.Cu")
		(net "M_G_CPU0_SA_DQS_DP<5>")
	)
	(segment
		(start 383.750566 -275.080984)
		(end 383.750566 -275.06676)
		(width 0.088646)
		(layer "In4.Cu")
		(net "M_G_CPU0_SA_DQS_DP<5>")
	)
	(segment
		(start 380.88443 -274.671282)
		(end 380.782068 -274.705826)
		(width 0.088646)
		(layer "In4.Cu")
		(net "M_G_CPU0_SA_DQS_DP<5>")
	)
	(segment
		(start 425.316904 -312.763662)
		(end 425.045378 -312.492136)
		(width 0.18288)
		(layer "In4.Cu")
		(net "M_G_CPU0_SA_DQS_DP<5>")
	)
	(segment
		(start 405.182578 -307.62448)
		(end 404.677626 -307.62448)
		(width 0.18288)
		(layer "In4.Cu")
		(net "M_G_CPU0_SA_DQS_DP<5>")
	)
	(segment
		(start 415.688526 -311.716928)
		(end 414.062164 -311.04332)
		(width 0.18288)
		(layer "In4.Cu")
		(net "M_G_CPU0_SA_DQS_DP<5>")
	)
	(segment
		(start 424.312588 -312.79338)
		(end 423.309288 -312.79338)
		(width 0.18288)
		(layer "In4.Cu")
		(net "M_G_CPU0_SA_DQS_DP<5>")
	)
	(segment
		(start 385.160012 -275.8948)
		(end 385.160012 -275.879306)
		(width 0.088646)
		(layer "In4.Cu")
		(net "M_G_CPU0_SA_DQS_DP<5>")
	)
	(arc
		(start 380.230634 -274.731734)
		(mid 380.229745 -274.731989)
		(end 380.228856 -274.732242)
		(width 0.088646)
		(layer "In4.Cu")
		(net "M_G_CPU0_SA_DQS_DP<5>")
	)
	(arc
		(start 386.19176 -277.032974)
		(mid 386.004562 -277.083117)
		(end 385.817364 -277.032974)
		(width 0.088646)
		(layer "In4.Cu")
		(net "M_G_CPU0_SA_DQS_DP<5>")
	)
	(arc
		(start 381.96266 -274.591272)
		(mid 381.775462 -274.641415)
		(end 381.588264 -274.591272)
		(width 0.088646)
		(layer "In4.Cu")
		(net "M_G_CPU0_SA_DQS_DP<5>")
	)
	(arc
		(start 385.629912 -276.69871)
		(mid 385.551801 -276.421761)
		(end 385.347464 -276.219158)
		(width 0.088646)
		(layer "In4.Cu")
		(net "M_G_CPU0_SA_DQS_DP<5>")
	)
	(arc
		(start 380.228856 -274.732242)
		(mid 380.203387 -274.743375)
		(end 380.178818 -274.756372)
		(width 0.088646)
		(layer "In4.Cu")
		(net "M_G_CPU0_SA_DQS_DP<5>")
	)
	(arc
		(start 383.929128 -275.400262)
		(mid 383.798214 -275.263902)
		(end 383.750566 -275.080984)
		(width 0.088646)
		(layer "In4.Cu")
		(net "M_G_CPU0_SA_DQS_DP<5>")
	)
	(arc
		(start 386.505958 -276.958552)
		(mid 386.343536 -276.972984)
		(end 386.192014 -277.033228)
		(width 0.088646)
		(layer "In4.Cu")
		(net "M_G_CPU0_SA_DQS_DP<5>")
	)
	(arc
		(start 383.750566 -275.06676)
		(mid 383.671347 -274.792075)
		(end 383.467864 -274.591272)
		(width 0.088646)
		(layer "In4.Cu")
		(net "M_G_CPU0_SA_DQS_DP<5>")
	)
	(arc
		(start 380.367032 -274.705826)
		(mid 380.297624 -274.712412)
		(end 380.230634 -274.731734)
		(width 0.088646)
		(layer "In4.Cu")
		(net "M_G_CPU0_SA_DQS_DP<5>")
	)
	(arc
		(start 384.877818 -275.405342)
		(mid 384.603619 -275.329507)
		(end 384.327146 -275.396706)
		(width 0.088646)
		(layer "In4.Cu")
		(net "M_G_CPU0_SA_DQS_DP<5>")
	)
	(arc
		(start 385.338574 -276.214078)
		(mid 385.20766 -276.077718)
		(end 385.160012 -275.8948)
		(width 0.088646)
		(layer "In4.Cu")
		(net "M_G_CPU0_SA_DQS_DP<5>")
	)
	(arc
		(start 382.513332 -274.582636)
		(mid 382.236857 -274.515316)
		(end 381.96266 -274.591272)
		(width 0.088646)
		(layer "In4.Cu")
		(net "M_G_CPU0_SA_DQS_DP<5>")
	)
	(arc
		(start 380.169928 -274.761452)
		(mid 380.054119 -274.873381)
		(end 379.995938 -275.02358)
		(width 0.088646)
		(layer "In4.Cu")
		(net "M_G_CPU0_SA_DQS_DP<5>")
	)
	(arc
		(start 384.312414 -275.405342)
		(mid 384.125216 -275.455485)
		(end 383.938018 -275.405342)
		(width 0.088646)
		(layer "In4.Cu")
		(net "M_G_CPU0_SA_DQS_DP<5>")
	)
	(arc
		(start 383.467356 -274.591526)
		(mid 383.185133 -274.516131)
		(end 382.902968 -274.59178)
		(width 0.088646)
		(layer "In4.Cu")
		(net "M_G_CPU0_SA_DQS_DP<5>")
	)
	(arc
		(start 385.808474 -277.027894)
		(mid 385.67756 -276.891534)
		(end 385.629912 -276.708616)
		(width 0.088646)
		(layer "In4.Cu")
		(net "M_G_CPU0_SA_DQS_DP<5>")
	)
	(arc
		(start 382.90246 -274.591272)
		(mid 382.722935 -274.641337)
		(end 382.541526 -274.598638)
		(width 0.088646)
		(layer "In4.Cu")
		(net "M_G_CPU0_SA_DQS_DP<5>")
	)
	(arc
		(start 382.541526 -274.598638)
		(mid 382.534757 -274.595025)
		(end 382.528064 -274.591272)
		(width 0.088646)
		(layer "In4.Cu")
		(net "M_G_CPU0_SA_DQS_DP<5>")
	)
	(arc
		(start 381.588518 -274.59178)
		(mid 381.305989 -274.515936)
		(end 381.023368 -274.591526)
		(width 0.088646)
		(layer "In4.Cu")
		(net "M_G_CPU0_SA_DQS_DP<5>")
	)
	(arc
		(start 385.160012 -275.879306)
		(mid 385.080642 -275.605572)
		(end 384.877818 -275.405342)
		(width 0.088646)
		(layer "In4.Cu")
		(net "M_G_CPU0_SA_DQS_DP<5>")
	)
	(segment
		(start 374.257316 -262.87222)
		(end 374.257062 -262.872474)
		(width 0.20066)
		(layer "F.Cu")
		(net "M_G_CPU0_SA_DQS_DP<4>")
	)
	(segment
		(start 436.928514 -275.516594)
		(end 437.517794 -275.516594)
		(width 0.20066)
		(layer "F.Cu")
		(net "M_G_CPU0_SA_DQS_DP<4>")
	)
	(segment
		(start 439.875676 -275.94179)
		(end 442.032898 -275.94179)
		(width 0.1016)
		(layer "F.Cu")
		(net "M_G_CPU0_SA_DQS_DP<4>")
	)
	(segment
		(start 442.032898 -275.94179)
		(end 442.24702 -275.94179)
		(width 0.101854)
		(layer "F.Cu")
		(net "M_G_CPU0_SA_DQS_DP<4>")
	)
	(segment
		(start 439.459116 -275.690584)
		(end 439.710322 -275.94179)
		(width 0.20066)
		(layer "F.Cu")
		(net "M_G_CPU0_SA_DQS_DP<4>")
	)
	(segment
		(start 443.641988 -275.234908)
		(end 443.923674 -275.516594)
		(width 0.20066)
		(layer "F.Cu")
		(net "M_G_CPU0_SA_DQS_DP<4>")
	)
	(segment
		(start 437.517794 -275.516594)
		(end 437.758332 -275.276056)
		(width 0.20066)
		(layer "F.Cu")
		(net "M_G_CPU0_SA_DQS_DP<4>")
	)
	(segment
		(start 442.24702 -275.94179)
		(end 442.368432 -275.94179)
		(width 0.20066)
		(layer "F.Cu")
		(net "M_G_CPU0_SA_DQS_DP<4>")
	)
	(segment
		(start 374.257316 -262.336534)
		(end 374.257316 -262.87222)
		(width 0.20066)
		(layer "F.Cu")
		(net "M_G_CPU0_SA_DQS_DP<4>")
	)
	(segment
		(start 435.823614 -275.516594)
		(end 436.928514 -275.516594)
		(width 0.20066)
		(layer "F.Cu")
		(net "M_G_CPU0_SA_DQS_DP<4>")
	)
	(segment
		(start 443.923674 -275.516594)
		(end 444.472314 -275.516594)
		(width 0.20066)
		(layer "F.Cu")
		(net "M_G_CPU0_SA_DQS_DP<4>")
	)
	(segment
		(start 443.035436 -275.645372)
		(end 443.4459 -275.234908)
		(width 0.20066)
		(layer "F.Cu")
		(net "M_G_CPU0_SA_DQS_DP<4>")
	)
	(segment
		(start 439.710322 -275.94179)
		(end 439.839354 -275.94179)
		(width 0.20066)
		(layer "F.Cu")
		(net "M_G_CPU0_SA_DQS_DP<4>")
	)
	(segment
		(start 443.4459 -275.234908)
		(end 443.641988 -275.234908)
		(width 0.20066)
		(layer "F.Cu")
		(net "M_G_CPU0_SA_DQS_DP<4>")
	)
	(segment
		(start 442.66485 -275.645372)
		(end 443.035436 -275.645372)
		(width 0.20066)
		(layer "F.Cu")
		(net "M_G_CPU0_SA_DQS_DP<4>")
	)
	(segment
		(start 439.839354 -275.94179)
		(end 439.875676 -275.94179)
		(width 0.101854)
		(layer "F.Cu")
		(net "M_G_CPU0_SA_DQS_DP<4>")
	)
	(segment
		(start 438.612534 -275.690584)
		(end 439.459116 -275.690584)
		(width 0.20066)
		(layer "F.Cu")
		(net "M_G_CPU0_SA_DQS_DP<4>")
	)
	(segment
		(start 438.198006 -275.276056)
		(end 438.612534 -275.690584)
		(width 0.20066)
		(layer "F.Cu")
		(net "M_G_CPU0_SA_DQS_DP<4>")
	)
	(segment
		(start 442.368432 -275.94179)
		(end 442.66485 -275.645372)
		(width 0.20066)
		(layer "F.Cu")
		(net "M_G_CPU0_SA_DQS_DP<4>")
	)
	(segment
		(start 437.758332 -275.276056)
		(end 438.198006 -275.276056)
		(width 0.20066)
		(layer "F.Cu")
		(net "M_G_CPU0_SA_DQS_DP<4>")
	)
	(segment
		(start 388.512304 -262.652256)
		(end 388.45236 -262.592312)
		(width 0.088646)
		(layer "In6.Cu")
		(net "M_G_CPU0_SA_DQS_DP<4>")
	)
	(segment
		(start 420.506906 -265.740896)
		(end 420.22522 -265.45921)
		(width 0.18288)
		(layer "In6.Cu")
		(net "M_G_CPU0_SA_DQS_DP<4>")
	)
	(segment
		(start 413.01924 -264.65276)
		(end 412.331154 -265.340846)
		(width 0.18288)
		(layer "In6.Cu")
		(net "M_G_CPU0_SA_DQS_DP<4>")
	)
	(segment
		(start 427.43882 -266.922758)
		(end 426.498512 -266.922758)
		(width 0.18288)
		(layer "In6.Cu")
		(net "M_G_CPU0_SA_DQS_DP<4>")
	)
	(segment
		(start 380.567946 -263.370822)
		(end 380.553214 -263.362186)
		(width 0.088646)
		(layer "In6.Cu")
		(net "M_G_CPU0_SA_DQS_DP<4>")
	)
	(segment
		(start 435.030372 -275.22805)
		(end 434.77688 -274.974558)
		(width 0.18288)
		(layer "In6.Cu")
		(net "M_G_CPU0_SA_DQS_DP<4>")
	)
	(segment
		(start 431.001932 -272.932144)
		(end 430.110646 -272.932144)
		(width 0.18288)
		(layer "In6.Cu")
		(net "M_G_CPU0_SA_DQS_DP<4>")
	)
	(segment
		(start 386.757164 -263.362186)
		(end 386.742432 -263.370822)
		(width 0.088646)
		(layer "In6.Cu")
		(net "M_G_CPU0_SA_DQS_DP<4>")
	)
	(segment
		(start 421.25138 -265.45032)
		(end 420.960804 -265.740896)
		(width 0.18288)
		(layer "In6.Cu")
		(net "M_G_CPU0_SA_DQS_DP<4>")
	)
	(segment
		(start 408.722068 -265.340846)
		(end 407.986738 -264.605516)
		(width 0.18288)
		(layer "In6.Cu")
		(net "M_G_CPU0_SA_DQS_DP<4>")
	)
	(segment
		(start 427.94682 -266.414758)
		(end 427.43882 -266.922758)
		(width 0.18288)
		(layer "In6.Cu")
		(net "M_G_CPU0_SA_DQS_DP<4>")
	)
	(segment
		(start 432.794664 -273.932142)
		(end 432.00193 -273.932142)
		(width 0.18288)
		(layer "In6.Cu")
		(net "M_G_CPU0_SA_DQS_DP<4>")
	)
	(segment
		(start 422.709594 -266.330176)
		(end 421.829738 -265.45032)
		(width 0.18288)
		(layer "In6.Cu")
		(net "M_G_CPU0_SA_DQS_DP<4>")
	)
	(segment
		(start 405.185626 -264.605516)
		(end 403.716236 -263.136126)
		(width 0.18288)
		(layer "In6.Cu")
		(net "M_G_CPU0_SA_DQS_DP<4>")
	)
	(segment
		(start 376.804428 -263.368282)
		(end 376.794014 -263.362186)
		(width 0.088646)
		(layer "In6.Cu")
		(net "M_G_CPU0_SA_DQS_DP<4>")
	)
	(segment
		(start 390.748774 -262.652256)
		(end 388.535672 -262.652256)
		(width 0.18288)
		(layer "In6.Cu")
		(net "M_G_CPU0_SA_DQS_DP<4>")
	)
	(segment
		(start 421.829738 -265.45032)
		(end 421.25138 -265.45032)
		(width 0.18288)
		(layer "In6.Cu")
		(net "M_G_CPU0_SA_DQS_DP<4>")
	)
	(segment
		(start 430.110646 -272.932144)
		(end 429.744378 -272.565876)
		(width 0.18288)
		(layer "In6.Cu")
		(net "M_G_CPU0_SA_DQS_DP<4>")
	)
	(segment
		(start 425.875958 -266.300204)
		(end 425.344844 -266.300204)
		(width 0.18288)
		(layer "In6.Cu")
		(net "M_G_CPU0_SA_DQS_DP<4>")
	)
	(segment
		(start 415.324036 -264.65276)
		(end 413.01924 -264.65276)
		(width 0.18288)
		(layer "In6.Cu")
		(net "M_G_CPU0_SA_DQS_DP<4>")
	)
	(segment
		(start 375.868946 -263.370822)
		(end 375.854214 -263.362186)
		(width 0.088646)
		(layer "In6.Cu")
		(net "M_G_CPU0_SA_DQS_DP<4>")
	)
	(segment
		(start 435.5338 -275.22805)
		(end 435.030372 -275.22805)
		(width 0.18288)
		(layer "In6.Cu")
		(net "M_G_CPU0_SA_DQS_DP<4>")
	)
	(segment
		(start 378.688346 -263.370822)
		(end 378.673614 -263.362186)
		(width 0.088646)
		(layer "In6.Cu")
		(net "M_G_CPU0_SA_DQS_DP<4>")
	)
	(segment
		(start 425.344844 -266.300204)
		(end 425.054268 -266.59078)
		(width 0.18288)
		(layer "In6.Cu")
		(net "M_G_CPU0_SA_DQS_DP<4>")
	)
	(segment
		(start 432.00193 -273.932142)
		(end 431.001932 -272.932144)
		(width 0.18288)
		(layer "In6.Cu")
		(net "M_G_CPU0_SA_DQS_DP<4>")
	)
	(segment
		(start 435.823614 -275.516594)
		(end 435.5338 -275.22805)
		(width 0.18288)
		(layer "In6.Cu")
		(net "M_G_CPU0_SA_DQS_DP<4>")
	)
	(segment
		(start 374.635268 -262.938006)
		(end 374.569736 -262.872474)
		(width 0.088646)
		(layer "In6.Cu")
		(net "M_G_CPU0_SA_DQS_DP<4>")
	)
	(segment
		(start 383.937764 -263.362186)
		(end 383.937256 -263.361678)
		(width 0.088646)
		(layer "In6.Cu")
		(net "M_G_CPU0_SA_DQS_DP<4>")
	)
	(segment
		(start 383.372868 -263.361678)
		(end 383.37236 -263.362186)
		(width 0.088646)
		(layer "In6.Cu")
		(net "M_G_CPU0_SA_DQS_DP<4>")
	)
	(segment
		(start 417.2712 -265.45921)
		(end 415.324036 -264.65276)
		(width 0.18288)
		(layer "In6.Cu")
		(net "M_G_CPU0_SA_DQS_DP<4>")
	)
	(segment
		(start 374.569736 -262.872474)
		(end 374.257062 -262.872474)
		(width 0.088646)
		(layer "In6.Cu")
		(net "M_G_CPU0_SA_DQS_DP<4>")
	)
	(segment
		(start 428.331376 -266.414758)
		(end 427.94682 -266.414758)
		(width 0.18288)
		(layer "In6.Cu")
		(net "M_G_CPU0_SA_DQS_DP<4>")
	)
	(segment
		(start 403.716236 -263.136126)
		(end 393.18057 -263.136126)
		(width 0.18288)
		(layer "In6.Cu")
		(net "M_G_CPU0_SA_DQS_DP<4>")
	)
	(segment
		(start 424.582336 -266.59078)
		(end 424.321732 -266.330176)
		(width 0.18288)
		(layer "In6.Cu")
		(net "M_G_CPU0_SA_DQS_DP<4>")
	)
	(segment
		(start 424.321732 -266.330176)
		(end 422.709594 -266.330176)
		(width 0.18288)
		(layer "In6.Cu")
		(net "M_G_CPU0_SA_DQS_DP<4>")
	)
	(segment
		(start 387.132322 -263.361678)
		(end 387.132068 -263.361678)
		(width 0.088646)
		(layer "In6.Cu")
		(net "M_G_CPU0_SA_DQS_DP<4>")
	)
	(segment
		(start 377.743974 -263.368282)
		(end 377.73356 -263.362186)
		(width 0.088646)
		(layer "In6.Cu")
		(net "M_G_CPU0_SA_DQS_DP<4>")
	)
	(segment
		(start 388.194296 -262.71474)
		(end 388.066026 -263.024112)
		(width 0.088646)
		(layer "In6.Cu")
		(net "M_G_CPU0_SA_DQS_DP<4>")
	)
	(segment
		(start 393.18057 -263.136126)
		(end 390.748774 -262.652256)
		(width 0.18288)
		(layer "In6.Cu")
		(net "M_G_CPU0_SA_DQS_DP<4>")
	)
	(segment
		(start 429.744378 -267.82776)
		(end 428.331376 -266.414758)
		(width 0.18288)
		(layer "In6.Cu")
		(net "M_G_CPU0_SA_DQS_DP<4>")
	)
	(segment
		(start 429.744378 -272.565876)
		(end 429.744378 -267.82776)
		(width 0.18288)
		(layer "In6.Cu")
		(net "M_G_CPU0_SA_DQS_DP<4>")
	)
	(segment
		(start 434.77688 -274.974558)
		(end 433.83708 -274.974558)
		(width 0.18288)
		(layer "In6.Cu")
		(net "M_G_CPU0_SA_DQS_DP<4>")
	)
	(segment
		(start 407.986738 -264.605516)
		(end 405.185626 -264.605516)
		(width 0.18288)
		(layer "In6.Cu")
		(net "M_G_CPU0_SA_DQS_DP<4>")
	)
	(segment
		(start 381.507746 -263.370822)
		(end 381.493014 -263.362186)
		(width 0.088646)
		(layer "In6.Cu")
		(net "M_G_CPU0_SA_DQS_DP<4>")
	)
	(segment
		(start 425.054268 -266.59078)
		(end 424.582336 -266.59078)
		(width 0.18288)
		(layer "In6.Cu")
		(net "M_G_CPU0_SA_DQS_DP<4>")
	)
	(segment
		(start 420.960804 -265.740896)
		(end 420.506906 -265.740896)
		(width 0.18288)
		(layer "In6.Cu")
		(net "M_G_CPU0_SA_DQS_DP<4>")
	)
	(segment
		(start 388.45236 -262.592312)
		(end 388.316724 -262.592312)
		(width 0.088646)
		(layer "In6.Cu")
		(net "M_G_CPU0_SA_DQS_DP<4>")
	)
	(segment
		(start 388.316724 -262.592312)
		(end 388.194296 -262.71474)
		(width 0.088646)
		(layer "In6.Cu")
		(net "M_G_CPU0_SA_DQS_DP<4>")
	)
	(segment
		(start 426.498512 -266.922758)
		(end 425.875958 -266.300204)
		(width 0.18288)
		(layer "In6.Cu")
		(net "M_G_CPU0_SA_DQS_DP<4>")
	)
	(segment
		(start 382.443228 -263.368282)
		(end 382.432814 -263.362186)
		(width 0.088646)
		(layer "In6.Cu")
		(net "M_G_CPU0_SA_DQS_DP<4>")
	)
	(segment
		(start 420.22522 -265.45921)
		(end 417.2712 -265.45921)
		(width 0.18288)
		(layer "In6.Cu")
		(net "M_G_CPU0_SA_DQS_DP<4>")
	)
	(segment
		(start 388.535672 -262.652256)
		(end 388.512304 -262.652256)
		(width 0.088646)
		(layer "In6.Cu")
		(net "M_G_CPU0_SA_DQS_DP<4>")
	)
	(segment
		(start 412.331154 -265.340846)
		(end 408.722068 -265.340846)
		(width 0.18288)
		(layer "In6.Cu")
		(net "M_G_CPU0_SA_DQS_DP<4>")
	)
	(segment
		(start 388.066026 -263.024112)
		(end 387.836156 -263.253982)
		(width 0.088646)
		(layer "In6.Cu")
		(net "M_G_CPU0_SA_DQS_DP<4>")
	)
	(segment
		(start 387.132068 -263.361678)
		(end 387.13156 -263.362186)
		(width 0.088646)
		(layer "In6.Cu")
		(net "M_G_CPU0_SA_DQS_DP<4>")
	)
	(segment
		(start 433.83708 -274.974558)
		(end 432.794664 -273.932142)
		(width 0.18288)
		(layer "In6.Cu")
		(net "M_G_CPU0_SA_DQS_DP<4>")
	)
	(arc
		(start 378.299218 -263.362186)
		(mid 378.022405 -263.438022)
		(end 377.743974 -263.368282)
		(width 0.088646)
		(layer "In6.Cu")
		(net "M_G_CPU0_SA_DQS_DP<4>")
	)
	(arc
		(start 381.493014 -263.362186)
		(mid 381.305816 -263.312043)
		(end 381.118618 -263.362186)
		(width 0.088646)
		(layer "In6.Cu")
		(net "M_G_CPU0_SA_DQS_DP<4>")
	)
	(arc
		(start 379.613414 -263.362186)
		(mid 379.426216 -263.312043)
		(end 379.239018 -263.362186)
		(width 0.088646)
		(layer "In6.Cu")
		(net "M_G_CPU0_SA_DQS_DP<4>")
	)
	(arc
		(start 387.723126 -263.345676)
		(mid 387.710279 -263.35385)
		(end 387.697218 -263.361678)
		(width 0.088646)
		(layer "In6.Cu")
		(net "M_G_CPU0_SA_DQS_DP<4>")
	)
	(arc
		(start 387.836156 -263.253982)
		(mid 387.782047 -263.302795)
		(end 387.723126 -263.345676)
		(width 0.088646)
		(layer "In6.Cu")
		(net "M_G_CPU0_SA_DQS_DP<4>")
	)
	(arc
		(start 378.673614 -263.362186)
		(mid 378.486416 -263.312043)
		(end 378.299218 -263.362186)
		(width 0.088646)
		(layer "In6.Cu")
		(net "M_G_CPU0_SA_DQS_DP<4>")
	)
	(arc
		(start 384.877564 -263.362186)
		(mid 384.594862 -263.437928)
		(end 384.31216 -263.362186)
		(width 0.088646)
		(layer "In6.Cu")
		(net "M_G_CPU0_SA_DQS_DP<4>")
	)
	(arc
		(start 377.73356 -263.362186)
		(mid 377.546362 -263.312043)
		(end 377.359164 -263.362186)
		(width 0.088646)
		(layer "In6.Cu")
		(net "M_G_CPU0_SA_DQS_DP<4>")
	)
	(arc
		(start 387.697218 -263.361678)
		(mid 387.41477 -263.437361)
		(end 387.132322 -263.361678)
		(width 0.088646)
		(layer "In6.Cu")
		(net "M_G_CPU0_SA_DQS_DP<4>")
	)
	(arc
		(start 376.794014 -263.362186)
		(mid 376.606816 -263.312043)
		(end 376.419618 -263.362186)
		(width 0.088646)
		(layer "In6.Cu")
		(net "M_G_CPU0_SA_DQS_DP<4>")
	)
	(arc
		(start 387.13156 -263.362186)
		(mid 386.944362 -263.312043)
		(end 386.757164 -263.362186)
		(width 0.088646)
		(layer "In6.Cu")
		(net "M_G_CPU0_SA_DQS_DP<4>")
	)
	(arc
		(start 375.479818 -263.362186)
		(mid 374.952616 -263.382598)
		(end 374.638062 -262.959088)
		(width 0.088646)
		(layer "In6.Cu")
		(net "M_G_CPU0_SA_DQS_DP<4>")
	)
	(arc
		(start 380.553214 -263.362186)
		(mid 380.366016 -263.312043)
		(end 380.178818 -263.362186)
		(width 0.088646)
		(layer "In6.Cu")
		(net "M_G_CPU0_SA_DQS_DP<4>")
	)
	(arc
		(start 386.19176 -263.362186)
		(mid 386.004562 -263.312043)
		(end 385.817364 -263.362186)
		(width 0.088646)
		(layer "In6.Cu")
		(net "M_G_CPU0_SA_DQS_DP<4>")
	)
	(arc
		(start 382.432814 -263.362186)
		(mid 382.245616 -263.312043)
		(end 382.058418 -263.362186)
		(width 0.088646)
		(layer "In6.Cu")
		(net "M_G_CPU0_SA_DQS_DP<4>")
	)
	(arc
		(start 380.178818 -263.362186)
		(mid 379.896116 -263.437928)
		(end 379.613414 -263.362186)
		(width 0.088646)
		(layer "In6.Cu")
		(net "M_G_CPU0_SA_DQS_DP<4>")
	)
	(arc
		(start 383.37236 -263.362186)
		(mid 383.185162 -263.312043)
		(end 382.997964 -263.362186)
		(width 0.088646)
		(layer "In6.Cu")
		(net "M_G_CPU0_SA_DQS_DP<4>")
	)
	(arc
		(start 384.31216 -263.362186)
		(mid 384.124962 -263.312043)
		(end 383.937764 -263.362186)
		(width 0.088646)
		(layer "In6.Cu")
		(net "M_G_CPU0_SA_DQS_DP<4>")
	)
	(arc
		(start 374.638062 -262.959088)
		(mid 374.636566 -262.94856)
		(end 374.635268 -262.938006)
		(width 0.088646)
		(layer "In6.Cu")
		(net "M_G_CPU0_SA_DQS_DP<4>")
	)
	(arc
		(start 383.937256 -263.361678)
		(mid 383.655062 -263.437234)
		(end 383.372868 -263.361678)
		(width 0.088646)
		(layer "In6.Cu")
		(net "M_G_CPU0_SA_DQS_DP<4>")
	)
	(arc
		(start 386.742432 -263.370822)
		(mid 386.465991 -263.437988)
		(end 386.19176 -263.362186)
		(width 0.088646)
		(layer "In6.Cu")
		(net "M_G_CPU0_SA_DQS_DP<4>")
	)
	(arc
		(start 375.854214 -263.362186)
		(mid 375.667016 -263.312043)
		(end 375.479818 -263.362186)
		(width 0.088646)
		(layer "In6.Cu")
		(net "M_G_CPU0_SA_DQS_DP<4>")
	)
	(arc
		(start 381.118618 -263.362186)
		(mid 380.844389 -263.438111)
		(end 380.567946 -263.370822)
		(width 0.088646)
		(layer "In6.Cu")
		(net "M_G_CPU0_SA_DQS_DP<4>")
	)
	(arc
		(start 379.239018 -263.362186)
		(mid 378.964789 -263.438111)
		(end 378.688346 -263.370822)
		(width 0.088646)
		(layer "In6.Cu")
		(net "M_G_CPU0_SA_DQS_DP<4>")
	)
	(arc
		(start 382.997964 -263.362186)
		(mid 382.721405 -263.437895)
		(end 382.443228 -263.368282)
		(width 0.088646)
		(layer "In6.Cu")
		(net "M_G_CPU0_SA_DQS_DP<4>")
	)
	(arc
		(start 376.419618 -263.362186)
		(mid 376.145389 -263.438111)
		(end 375.868946 -263.370822)
		(width 0.088646)
		(layer "In6.Cu")
		(net "M_G_CPU0_SA_DQS_DP<4>")
	)
	(arc
		(start 385.25196 -263.362186)
		(mid 385.064762 -263.312043)
		(end 384.877564 -263.362186)
		(width 0.088646)
		(layer "In6.Cu")
		(net "M_G_CPU0_SA_DQS_DP<4>")
	)
	(arc
		(start 382.058418 -263.362186)
		(mid 381.784189 -263.438111)
		(end 381.507746 -263.370822)
		(width 0.088646)
		(layer "In6.Cu")
		(net "M_G_CPU0_SA_DQS_DP<4>")
	)
	(arc
		(start 385.817364 -263.362186)
		(mid 385.534662 -263.437928)
		(end 385.25196 -263.362186)
		(width 0.088646)
		(layer "In6.Cu")
		(net "M_G_CPU0_SA_DQS_DP<4>")
	)
	(arc
		(start 377.359164 -263.362186)
		(mid 377.082605 -263.437895)
		(end 376.804428 -263.368282)
		(width 0.088646)
		(layer "In6.Cu")
		(net "M_G_CPU0_SA_DQS_DP<4>")
	)
	(segment
		(start 439.875676 -285.291784)
		(end 442.032898 -285.291784)
		(width 0.1016)
		(layer "F.Cu")
		(net "M_G_CPU0_SA_DQS_DP<3>")
	)
	(segment
		(start 443.4459 -284.584902)
		(end 443.641988 -284.584902)
		(width 0.20066)
		(layer "F.Cu")
		(net "M_G_CPU0_SA_DQS_DP<3>")
	)
	(segment
		(start 435.823614 -284.866588)
		(end 436.928514 -284.866588)
		(width 0.20066)
		(layer "F.Cu")
		(net "M_G_CPU0_SA_DQS_DP<3>")
	)
	(segment
		(start 438.358788 -284.62605)
		(end 438.773316 -285.040578)
		(width 0.20066)
		(layer "F.Cu")
		(net "M_G_CPU0_SA_DQS_DP<3>")
	)
	(segment
		(start 437.517794 -284.866588)
		(end 437.758332 -284.62605)
		(width 0.20066)
		(layer "F.Cu")
		(net "M_G_CPU0_SA_DQS_DP<3>")
	)
	(segment
		(start 439.849768 -285.291784)
		(end 439.875676 -285.291784)
		(width 0.101854)
		(layer "F.Cu")
		(net "M_G_CPU0_SA_DQS_DP<3>")
	)
	(segment
		(start 439.710322 -285.291784)
		(end 439.849768 -285.291784)
		(width 0.20066)
		(layer "F.Cu")
		(net "M_G_CPU0_SA_DQS_DP<3>")
	)
	(segment
		(start 436.928514 -284.866588)
		(end 437.517794 -284.866588)
		(width 0.20066)
		(layer "F.Cu")
		(net "M_G_CPU0_SA_DQS_DP<3>")
	)
	(segment
		(start 443.035436 -284.995366)
		(end 443.4459 -284.584902)
		(width 0.20066)
		(layer "F.Cu")
		(net "M_G_CPU0_SA_DQS_DP<3>")
	)
	(segment
		(start 442.038994 -285.29788)
		(end 442.362336 -285.29788)
		(width 0.20066)
		(layer "F.Cu")
		(net "M_G_CPU0_SA_DQS_DP<3>")
	)
	(segment
		(start 438.773316 -285.040578)
		(end 439.459116 -285.040578)
		(width 0.20066)
		(layer "F.Cu")
		(net "M_G_CPU0_SA_DQS_DP<3>")
	)
	(segment
		(start 439.459116 -285.040578)
		(end 439.710322 -285.291784)
		(width 0.20066)
		(layer "F.Cu")
		(net "M_G_CPU0_SA_DQS_DP<3>")
	)
	(segment
		(start 437.758332 -284.62605)
		(end 438.358788 -284.62605)
		(width 0.20066)
		(layer "F.Cu")
		(net "M_G_CPU0_SA_DQS_DP<3>")
	)
	(segment
		(start 442.032898 -285.291784)
		(end 442.038994 -285.29788)
		(width 0.1016)
		(layer "F.Cu")
		(net "M_G_CPU0_SA_DQS_DP<3>")
	)
	(segment
		(start 443.641988 -284.584902)
		(end 443.923674 -284.866588)
		(width 0.20066)
		(layer "F.Cu")
		(net "M_G_CPU0_SA_DQS_DP<3>")
	)
	(segment
		(start 443.923674 -284.866588)
		(end 444.472314 -284.866588)
		(width 0.20066)
		(layer "F.Cu")
		(net "M_G_CPU0_SA_DQS_DP<3>")
	)
	(segment
		(start 442.66485 -284.995366)
		(end 443.035436 -284.995366)
		(width 0.20066)
		(layer "F.Cu")
		(net "M_G_CPU0_SA_DQS_DP<3>")
	)
	(segment
		(start 442.362336 -285.29788)
		(end 442.66485 -284.995366)
		(width 0.20066)
		(layer "F.Cu")
		(net "M_G_CPU0_SA_DQS_DP<3>")
	)
	(segment
		(start 374.257316 -267.219938)
		(end 374.257062 -267.220192)
		(width 0.20066)
		(layer "F.Cu")
		(net "M_G_CPU0_SA_DQS_DP<3>")
	)
	(segment
		(start 374.257062 -267.220192)
		(end 374.257062 -267.755878)
		(width 0.20066)
		(layer "F.Cu")
		(net "M_G_CPU0_SA_DQS_DP<3>")
	)
	(segment
		(start 384.87731 -268.245336)
		(end 384.866896 -268.251432)
		(width 0.088646)
		(layer "In6.Cu")
		(net "M_G_CPU0_SA_DQS_DP<3>")
	)
	(segment
		(start 390.123426 -268.595602)
		(end 388.535672 -268.595602)
		(width 0.18288)
		(layer "In6.Cu")
		(net "M_G_CPU0_SA_DQS_DP<3>")
	)
	(segment
		(start 435.148736 -284.607762)
		(end 434.941472 -284.400498)
		(width 0.18288)
		(layer "In6.Cu")
		(net "M_G_CPU0_SA_DQS_DP<3>")
	)
	(segment
		(start 378.688346 -268.253972)
		(end 378.673614 -268.245336)
		(width 0.088646)
		(layer "In6.Cu")
		(net "M_G_CPU0_SA_DQS_DP<3>")
	)
	(segment
		(start 376.808746 -268.253972)
		(end 376.794014 -268.245336)
		(width 0.088646)
		(layer "In6.Cu")
		(net "M_G_CPU0_SA_DQS_DP<3>")
	)
	(segment
		(start 375.009664 -268.080236)
		(end 375.00814 -268.079474)
		(width 0.088646)
		(layer "In6.Cu")
		(net "M_G_CPU0_SA_DQS_DP<3>")
	)
	(segment
		(start 434.941472 -284.400498)
		(end 426.7073 -284.400498)
		(width 0.18288)
		(layer "In6.Cu")
		(net "M_G_CPU0_SA_DQS_DP<3>")
	)
	(segment
		(start 375.416572 -268.061694)
		(end 375.38406 -268.080236)
		(width 0.088646)
		(layer "In6.Cu")
		(net "M_G_CPU0_SA_DQS_DP<3>")
	)
	(segment
		(start 388.45236 -268.535658)
		(end 388.124954 -268.535658)
		(width 0.088646)
		(layer "In6.Cu")
		(net "M_G_CPU0_SA_DQS_DP<3>")
	)
	(segment
		(start 386.765038 -268.24051)
		(end 386.738622 -268.25575)
		(width 0.088646)
		(layer "In6.Cu")
		(net "M_G_CPU0_SA_DQS_DP<3>")
	)
	(segment
		(start 377.748546 -268.253972)
		(end 377.733814 -268.245336)
		(width 0.088646)
		(layer "In6.Cu")
		(net "M_G_CPU0_SA_DQS_DP<3>")
	)
	(segment
		(start 419.269672 -279.902412)
		(end 417.577524 -278.210264)
		(width 0.18288)
		(layer "In6.Cu")
		(net "M_G_CPU0_SA_DQS_DP<3>")
	)
	(segment
		(start 405.430482 -275.917152)
		(end 398.633442 -269.120112)
		(width 0.18288)
		(layer "In6.Cu")
		(net "M_G_CPU0_SA_DQS_DP<3>")
	)
	(segment
		(start 375.811288 -268.21765)
		(end 375.626884 -268.087602)
		(width 0.088646)
		(layer "In6.Cu")
		(net "M_G_CPU0_SA_DQS_DP<3>")
	)
	(segment
		(start 382.447546 -268.253972)
		(end 382.432814 -268.245336)
		(width 0.088646)
		(layer "In6.Cu")
		(net "M_G_CPU0_SA_DQS_DP<3>")
	)
	(segment
		(start 416.416744 -277.729188)
		(end 415.833814 -277.146766)
		(width 0.18288)
		(layer "In6.Cu")
		(net "M_G_CPU0_SA_DQS_DP<3>")
	)
	(segment
		(start 426.107352 -285.000446)
		(end 425.34332 -285.000446)
		(width 0.18288)
		(layer "In6.Cu")
		(net "M_G_CPU0_SA_DQS_DP<3>")
	)
	(segment
		(start 374.769634 -267.755878)
		(end 374.257062 -267.755878)
		(width 0.088646)
		(layer "In6.Cu")
		(net "M_G_CPU0_SA_DQS_DP<3>")
	)
	(segment
		(start 420.442644 -280.190956)
		(end 420.1541 -279.902412)
		(width 0.18288)
		(layer "In6.Cu")
		(net "M_G_CPU0_SA_DQS_DP<3>")
	)
	(segment
		(start 385.81711 -268.245336)
		(end 385.802378 -268.253972)
		(width 0.088646)
		(layer "In6.Cu")
		(net "M_G_CPU0_SA_DQS_DP<3>")
	)
	(segment
		(start 435.564788 -284.607762)
		(end 435.148736 -284.607762)
		(width 0.18288)
		(layer "In6.Cu")
		(net "M_G_CPU0_SA_DQS_DP<3>")
	)
	(segment
		(start 435.823614 -284.866588)
		(end 435.564788 -284.607762)
		(width 0.18288)
		(layer "In6.Cu")
		(net "M_G_CPU0_SA_DQS_DP<3>")
	)
	(segment
		(start 421.243252 -279.900634)
		(end 420.95293 -280.190956)
		(width 0.18288)
		(layer "In6.Cu")
		(net "M_G_CPU0_SA_DQS_DP<3>")
	)
	(segment
		(start 408.491436 -275.917152)
		(end 405.430482 -275.917152)
		(width 0.18288)
		(layer "In6.Cu")
		(net "M_G_CPU0_SA_DQS_DP<3>")
	)
	(segment
		(start 388.124954 -268.535658)
		(end 387.863842 -268.274546)
		(width 0.088646)
		(layer "In6.Cu")
		(net "M_G_CPU0_SA_DQS_DP<3>")
	)
	(segment
		(start 412.557722 -277.146766)
		(end 411.836108 -276.425152)
		(width 0.18288)
		(layer "In6.Cu")
		(net "M_G_CPU0_SA_DQS_DP<3>")
	)
	(segment
		(start 425.052998 -285.290768)
		(end 424.542712 -285.290768)
		(width 0.18288)
		(layer "In6.Cu")
		(net "M_G_CPU0_SA_DQS_DP<3>")
	)
	(segment
		(start 426.7073 -284.400498)
		(end 426.107352 -285.000446)
		(width 0.18288)
		(layer "In6.Cu")
		(net "M_G_CPU0_SA_DQS_DP<3>")
	)
	(segment
		(start 417.577524 -278.210264)
		(end 416.416744 -277.729188)
		(width 0.18288)
		(layer "In6.Cu")
		(net "M_G_CPU0_SA_DQS_DP<3>")
	)
	(segment
		(start 376.419618 -268.245336)
		(end 376.419364 -268.245336)
		(width 0.088646)
		(layer "In6.Cu")
		(net "M_G_CPU0_SA_DQS_DP<3>")
	)
	(segment
		(start 383.383028 -268.251432)
		(end 383.372614 -268.245336)
		(width 0.088646)
		(layer "In6.Cu")
		(net "M_G_CPU0_SA_DQS_DP<3>")
	)
	(segment
		(start 424.542712 -285.290768)
		(end 424.277028 -285.025084)
		(width 0.18288)
		(layer "In6.Cu")
		(net "M_G_CPU0_SA_DQS_DP<3>")
	)
	(segment
		(start 375.00814 -268.079474)
		(end 375.000774 -268.075156)
		(width 0.088646)
		(layer "In6.Cu")
		(net "M_G_CPU0_SA_DQS_DP<3>")
	)
	(segment
		(start 387.863842 -268.274546)
		(end 387.685534 -268.251432)
		(width 0.088646)
		(layer "In6.Cu")
		(net "M_G_CPU0_SA_DQS_DP<3>")
	)
	(segment
		(start 380.567946 -268.253972)
		(end 380.553214 -268.245336)
		(width 0.088646)
		(layer "In6.Cu")
		(net "M_G_CPU0_SA_DQS_DP<3>")
	)
	(segment
		(start 421.626792 -279.900634)
		(end 421.243252 -279.900634)
		(width 0.18288)
		(layer "In6.Cu")
		(net "M_G_CPU0_SA_DQS_DP<3>")
	)
	(segment
		(start 415.833814 -277.146766)
		(end 412.557722 -277.146766)
		(width 0.18288)
		(layer "In6.Cu")
		(net "M_G_CPU0_SA_DQS_DP<3>")
	)
	(segment
		(start 381.507746 -268.253972)
		(end 381.493014 -268.245336)
		(width 0.088646)
		(layer "In6.Cu")
		(net "M_G_CPU0_SA_DQS_DP<3>")
	)
	(segment
		(start 409.718002 -276.425152)
		(end 408.491436 -275.917152)
		(width 0.18288)
		(layer "In6.Cu")
		(net "M_G_CPU0_SA_DQS_DP<3>")
	)
	(segment
		(start 375.626884 -268.087602)
		(end 375.618502 -268.085316)
		(width 0.088646)
		(layer "In6.Cu")
		(net "M_G_CPU0_SA_DQS_DP<3>")
	)
	(segment
		(start 388.535672 -268.595602)
		(end 388.512304 -268.595602)
		(width 0.088646)
		(layer "In6.Cu")
		(net "M_G_CPU0_SA_DQS_DP<3>")
	)
	(segment
		(start 385.829048 -268.238478)
		(end 385.81711 -268.245336)
		(width 0.088646)
		(layer "In6.Cu")
		(net "M_G_CPU0_SA_DQS_DP<3>")
	)
	(segment
		(start 423.639234 -285.025084)
		(end 422.08069 -283.46654)
		(width 0.18288)
		(layer "In6.Cu")
		(net "M_G_CPU0_SA_DQS_DP<3>")
	)
	(segment
		(start 420.1541 -279.902412)
		(end 419.269672 -279.902412)
		(width 0.18288)
		(layer "In6.Cu")
		(net "M_G_CPU0_SA_DQS_DP<3>")
	)
	(segment
		(start 422.08069 -283.46654)
		(end 422.08069 -280.354532)
		(width 0.18288)
		(layer "In6.Cu")
		(net "M_G_CPU0_SA_DQS_DP<3>")
	)
	(segment
		(start 411.836108 -276.425152)
		(end 409.718002 -276.425152)
		(width 0.18288)
		(layer "In6.Cu")
		(net "M_G_CPU0_SA_DQS_DP<3>")
	)
	(segment
		(start 425.34332 -285.000446)
		(end 425.052998 -285.290768)
		(width 0.18288)
		(layer "In6.Cu")
		(net "M_G_CPU0_SA_DQS_DP<3>")
	)
	(segment
		(start 375.597674 -268.070584)
		(end 375.416572 -268.061694)
		(width 0.088646)
		(layer "In6.Cu")
		(net "M_G_CPU0_SA_DQS_DP<3>")
	)
	(segment
		(start 388.512304 -268.595602)
		(end 388.45236 -268.535658)
		(width 0.088646)
		(layer "In6.Cu")
		(net "M_G_CPU0_SA_DQS_DP<3>")
	)
	(segment
		(start 374.826784 -267.813028)
		(end 374.769634 -267.755878)
		(width 0.088646)
		(layer "In6.Cu")
		(net "M_G_CPU0_SA_DQS_DP<3>")
	)
	(segment
		(start 398.633442 -269.120112)
		(end 392.759184 -269.120112)
		(width 0.18288)
		(layer "In6.Cu")
		(net "M_G_CPU0_SA_DQS_DP<3>")
	)
	(segment
		(start 420.95293 -280.190956)
		(end 420.442644 -280.190956)
		(width 0.18288)
		(layer "In6.Cu")
		(net "M_G_CPU0_SA_DQS_DP<3>")
	)
	(segment
		(start 392.759184 -269.120112)
		(end 390.123426 -268.595602)
		(width 0.18288)
		(layer "In6.Cu")
		(net "M_G_CPU0_SA_DQS_DP<3>")
	)
	(segment
		(start 424.277028 -285.025084)
		(end 423.639234 -285.025084)
		(width 0.18288)
		(layer "In6.Cu")
		(net "M_G_CPU0_SA_DQS_DP<3>")
	)
	(segment
		(start 422.08069 -280.354532)
		(end 421.626792 -279.900634)
		(width 0.18288)
		(layer "In6.Cu")
		(net "M_G_CPU0_SA_DQS_DP<3>")
	)
	(segment
		(start 375.618502 -268.085316)
		(end 375.597674 -268.070584)
		(width 0.088646)
		(layer "In6.Cu")
		(net "M_G_CPU0_SA_DQS_DP<3>")
	)
	(arc
		(start 381.493014 -268.245336)
		(mid 381.305816 -268.195193)
		(end 381.118618 -268.245336)
		(width 0.088646)
		(layer "In6.Cu")
		(net "M_G_CPU0_SA_DQS_DP<3>")
	)
	(arc
		(start 383.372614 -268.245336)
		(mid 383.185416 -268.195193)
		(end 382.998218 -268.245336)
		(width 0.088646)
		(layer "In6.Cu")
		(net "M_G_CPU0_SA_DQS_DP<3>")
	)
	(arc
		(start 376.419364 -268.245336)
		(mid 376.111268 -268.32047)
		(end 375.811288 -268.21765)
		(width 0.088646)
		(layer "In6.Cu")
		(net "M_G_CPU0_SA_DQS_DP<3>")
	)
	(arc
		(start 385.251706 -268.245336)
		(mid 385.064508 -268.195193)
		(end 384.87731 -268.245336)
		(width 0.088646)
		(layer "In6.Cu")
		(net "M_G_CPU0_SA_DQS_DP<3>")
	)
	(arc
		(start 380.178818 -268.245336)
		(mid 379.896116 -268.321112)
		(end 379.613414 -268.245336)
		(width 0.088646)
		(layer "In6.Cu")
		(net "M_G_CPU0_SA_DQS_DP<3>")
	)
	(arc
		(start 376.452384 -268.228572)
		(mid 376.435794 -268.236549)
		(end 376.419618 -268.245336)
		(width 0.088646)
		(layer "In6.Cu")
		(net "M_G_CPU0_SA_DQS_DP<3>")
	)
	(arc
		(start 378.673614 -268.245336)
		(mid 378.486416 -268.195193)
		(end 378.299218 -268.245336)
		(width 0.088646)
		(layer "In6.Cu")
		(net "M_G_CPU0_SA_DQS_DP<3>")
	)
	(arc
		(start 381.118618 -268.245336)
		(mid 380.844419 -268.321171)
		(end 380.567946 -268.253972)
		(width 0.088646)
		(layer "In6.Cu")
		(net "M_G_CPU0_SA_DQS_DP<3>")
	)
	(arc
		(start 382.058418 -268.245336)
		(mid 381.784219 -268.321171)
		(end 381.507746 -268.253972)
		(width 0.088646)
		(layer "In6.Cu")
		(net "M_G_CPU0_SA_DQS_DP<3>")
	)
	(arc
		(start 378.299218 -268.245336)
		(mid 378.025019 -268.321171)
		(end 377.748546 -268.253972)
		(width 0.088646)
		(layer "In6.Cu")
		(net "M_G_CPU0_SA_DQS_DP<3>")
	)
	(arc
		(start 387.130798 -268.245336)
		(mid 386.948547 -268.195225)
		(end 386.765038 -268.24051)
		(width 0.088646)
		(layer "In6.Cu")
		(net "M_G_CPU0_SA_DQS_DP<3>")
	)
	(arc
		(start 385.802378 -268.253972)
		(mid 385.525903 -268.321292)
		(end 385.251706 -268.245336)
		(width 0.088646)
		(layer "In6.Cu")
		(net "M_G_CPU0_SA_DQS_DP<3>")
	)
	(arc
		(start 379.613414 -268.245336)
		(mid 379.426216 -268.195193)
		(end 379.239018 -268.245336)
		(width 0.088646)
		(layer "In6.Cu")
		(net "M_G_CPU0_SA_DQS_DP<3>")
	)
	(arc
		(start 384.866896 -268.251432)
		(mid 384.588718 -268.321155)
		(end 384.31216 -268.245336)
		(width 0.088646)
		(layer "In6.Cu")
		(net "M_G_CPU0_SA_DQS_DP<3>")
	)
	(arc
		(start 380.553214 -268.245336)
		(mid 380.366016 -268.195193)
		(end 380.178818 -268.245336)
		(width 0.088646)
		(layer "In6.Cu")
		(net "M_G_CPU0_SA_DQS_DP<3>")
	)
	(arc
		(start 383.937764 -268.245336)
		(mid 383.661205 -268.321079)
		(end 383.383028 -268.251432)
		(width 0.088646)
		(layer "In6.Cu")
		(net "M_G_CPU0_SA_DQS_DP<3>")
	)
	(arc
		(start 375.000774 -268.075156)
		(mid 374.884965 -267.963227)
		(end 374.826784 -267.813028)
		(width 0.088646)
		(layer "In6.Cu")
		(net "M_G_CPU0_SA_DQS_DP<3>")
	)
	(arc
		(start 384.31216 -268.245336)
		(mid 384.124962 -268.195193)
		(end 383.937764 -268.245336)
		(width 0.088646)
		(layer "In6.Cu")
		(net "M_G_CPU0_SA_DQS_DP<3>")
	)
	(arc
		(start 382.432814 -268.245336)
		(mid 382.245616 -268.195193)
		(end 382.058418 -268.245336)
		(width 0.088646)
		(layer "In6.Cu")
		(net "M_G_CPU0_SA_DQS_DP<3>")
	)
	(arc
		(start 386.738622 -268.25575)
		(mid 386.463718 -268.321154)
		(end 386.191506 -268.245336)
		(width 0.088646)
		(layer "In6.Cu")
		(net "M_G_CPU0_SA_DQS_DP<3>")
	)
	(arc
		(start 375.38406 -268.080236)
		(mid 375.196862 -268.130379)
		(end 375.009664 -268.080236)
		(width 0.088646)
		(layer "In6.Cu")
		(net "M_G_CPU0_SA_DQS_DP<3>")
	)
	(arc
		(start 382.998218 -268.245336)
		(mid 382.724019 -268.321171)
		(end 382.447546 -268.253972)
		(width 0.088646)
		(layer "In6.Cu")
		(net "M_G_CPU0_SA_DQS_DP<3>")
	)
	(arc
		(start 387.685534 -268.251432)
		(mid 387.407356 -268.321155)
		(end 387.130798 -268.245336)
		(width 0.088646)
		(layer "In6.Cu")
		(net "M_G_CPU0_SA_DQS_DP<3>")
	)
	(arc
		(start 386.191506 -268.245336)
		(mid 386.011159 -268.195133)
		(end 385.829048 -268.238478)
		(width 0.088646)
		(layer "In6.Cu")
		(net "M_G_CPU0_SA_DQS_DP<3>")
	)
	(arc
		(start 379.239018 -268.245336)
		(mid 378.964819 -268.321171)
		(end 378.688346 -268.253972)
		(width 0.088646)
		(layer "In6.Cu")
		(net "M_G_CPU0_SA_DQS_DP<3>")
	)
	(arc
		(start 376.794014 -268.245336)
		(mid 376.62522 -268.195645)
		(end 376.452384 -268.228572)
		(width 0.088646)
		(layer "In6.Cu")
		(net "M_G_CPU0_SA_DQS_DP<3>")
	)
	(arc
		(start 377.359418 -268.245336)
		(mid 377.085219 -268.321171)
		(end 376.808746 -268.253972)
		(width 0.088646)
		(layer "In6.Cu")
		(net "M_G_CPU0_SA_DQS_DP<3>")
	)
	(arc
		(start 377.733814 -268.245336)
		(mid 377.546616 -268.195193)
		(end 377.359418 -268.245336)
		(width 0.088646)
		(layer "In6.Cu")
		(net "M_G_CPU0_SA_DQS_DP<3>")
	)
	(segment
		(start 442.038994 -294.647874)
		(end 442.362336 -294.647874)
		(width 0.20066)
		(layer "F.Cu")
		(net "M_G_CPU0_SA_DQS_DP<2>")
	)
	(segment
		(start 442.032898 -294.641778)
		(end 442.038994 -294.647874)
		(width 0.1016)
		(layer "F.Cu")
		(net "M_G_CPU0_SA_DQS_DP<2>")
	)
	(segment
		(start 439.875676 -294.641778)
		(end 442.032898 -294.641778)
		(width 0.1016)
		(layer "F.Cu")
		(net "M_G_CPU0_SA_DQS_DP<2>")
	)
	(segment
		(start 439.849768 -294.641778)
		(end 439.875676 -294.641778)
		(width 0.101854)
		(layer "F.Cu")
		(net "M_G_CPU0_SA_DQS_DP<2>")
	)
	(segment
		(start 378.486162 -265.313922)
		(end 378.486416 -265.314176)
		(width 0.20066)
		(layer "F.Cu")
		(net "M_G_CPU0_SA_DQS_DP<2>")
	)
	(segment
		(start 436.928514 -294.216582)
		(end 437.517794 -294.216582)
		(width 0.20066)
		(layer "F.Cu")
		(net "M_G_CPU0_SA_DQS_DP<2>")
	)
	(segment
		(start 443.641988 -293.934896)
		(end 443.923674 -294.216582)
		(width 0.20066)
		(layer "F.Cu")
		(net "M_G_CPU0_SA_DQS_DP<2>")
	)
	(segment
		(start 443.035436 -294.34536)
		(end 443.4459 -293.934896)
		(width 0.20066)
		(layer "F.Cu")
		(net "M_G_CPU0_SA_DQS_DP<2>")
	)
	(segment
		(start 437.758332 -293.976044)
		(end 438.358788 -293.976044)
		(width 0.20066)
		(layer "F.Cu")
		(net "M_G_CPU0_SA_DQS_DP<2>")
	)
	(segment
		(start 439.459116 -294.390572)
		(end 439.710322 -294.641778)
		(width 0.20066)
		(layer "F.Cu")
		(net "M_G_CPU0_SA_DQS_DP<2>")
	)
	(segment
		(start 378.486162 -264.778236)
		(end 378.486162 -265.313922)
		(width 0.20066)
		(layer "F.Cu")
		(net "M_G_CPU0_SA_DQS_DP<2>")
	)
	(segment
		(start 443.4459 -293.934896)
		(end 443.641988 -293.934896)
		(width 0.20066)
		(layer "F.Cu")
		(net "M_G_CPU0_SA_DQS_DP<2>")
	)
	(segment
		(start 438.358788 -293.976044)
		(end 438.773316 -294.390572)
		(width 0.20066)
		(layer "F.Cu")
		(net "M_G_CPU0_SA_DQS_DP<2>")
	)
	(segment
		(start 442.362336 -294.647874)
		(end 442.66485 -294.34536)
		(width 0.20066)
		(layer "F.Cu")
		(net "M_G_CPU0_SA_DQS_DP<2>")
	)
	(segment
		(start 435.823614 -294.216582)
		(end 436.928514 -294.216582)
		(width 0.20066)
		(layer "F.Cu")
		(net "M_G_CPU0_SA_DQS_DP<2>")
	)
	(segment
		(start 438.773316 -294.390572)
		(end 439.459116 -294.390572)
		(width 0.20066)
		(layer "F.Cu")
		(net "M_G_CPU0_SA_DQS_DP<2>")
	)
	(segment
		(start 439.710322 -294.641778)
		(end 439.849768 -294.641778)
		(width 0.20066)
		(layer "F.Cu")
		(net "M_G_CPU0_SA_DQS_DP<2>")
	)
	(segment
		(start 442.66485 -294.34536)
		(end 443.035436 -294.34536)
		(width 0.20066)
		(layer "F.Cu")
		(net "M_G_CPU0_SA_DQS_DP<2>")
	)
	(segment
		(start 437.517794 -294.216582)
		(end 437.758332 -293.976044)
		(width 0.20066)
		(layer "F.Cu")
		(net "M_G_CPU0_SA_DQS_DP<2>")
	)
	(segment
		(start 443.923674 -294.216582)
		(end 444.472314 -294.216582)
		(width 0.20066)
		(layer "F.Cu")
		(net "M_G_CPU0_SA_DQS_DP<2>")
	)
	(segment
		(start 413.570928 -290.197286)
		(end 413.05734 -290.197286)
		(width 0.18288)
		(layer "In4.Cu")
		(net "M_G_CPU0_SA_DQS_DP<2>")
	)
	(segment
		(start 424.635422 -294.642286)
		(end 424.349164 -294.356028)
		(width 0.18288)
		(layer "In4.Cu")
		(net "M_G_CPU0_SA_DQS_DP<2>")
	)
	(segment
		(start 388.740142 -266.43076)
		(end 388.19455 -265.885168)
		(width 0.18288)
		(layer "In4.Cu")
		(net "M_G_CPU0_SA_DQS_DP<2>")
	)
	(segment
		(start 430.661064 -293.437818)
		(end 430.536604 -293.562278)
		(width 0.18288)
		(layer "In4.Cu")
		(net "M_G_CPU0_SA_DQS_DP<2>")
	)
	(segment
		(start 417.236656 -292.470586)
		(end 416.47237 -292.470586)
		(width 0.18288)
		(layer "In4.Cu")
		(net "M_G_CPU0_SA_DQS_DP<2>")
	)
	(segment
		(start 420.947342 -295.492678)
		(end 420.842694 -295.492678)
		(width 0.18288)
		(layer "In4.Cu")
		(net "M_G_CPU0_SA_DQS_DP<2>")
	)
	(segment
		(start 423.076624 -294.480488)
		(end 422.952164 -294.356028)
		(width 0.18288)
		(layer "In4.Cu")
		(net "M_G_CPU0_SA_DQS_DP<2>")
	)
	(segment
		(start 420.840916 -295.4909)
		(end 420.590472 -295.4909)
		(width 0.18288)
		(layer "In4.Cu")
		(net "M_G_CPU0_SA_DQS_DP<2>")
	)
	(segment
		(start 406.343612 -284.075378)
		(end 405.797512 -284.075378)
		(width 0.18288)
		(layer "In4.Cu")
		(net "M_G_CPU0_SA_DQS_DP<2>")
	)
	(segment
		(start 414.160462 -290.78682)
		(end 413.570928 -290.197286)
		(width 0.18288)
		(layer "In4.Cu")
		(net "M_G_CPU0_SA_DQS_DP<2>")
	)
	(segment
		(start 405.673052 -283.950918)
		(end 405.106632 -283.950918)
		(width 0.18288)
		(layer "In4.Cu")
		(net "M_G_CPU0_SA_DQS_DP<2>")
	)
	(segment
		(start 379.14326 -265.803888)
		(end 379.049534 -265.749786)
		(width 0.088646)
		(layer "In4.Cu")
		(net "M_G_CPU0_SA_DQS_DP<2>")
	)
	(segment
		(start 435.823614 -294.216582)
		(end 435.553358 -293.946326)
		(width 0.18288)
		(layer "In4.Cu")
		(net "M_G_CPU0_SA_DQS_DP<2>")
	)
	(segment
		(start 404.411688 -283.22397)
		(end 401.766786 -276.969982)
		(width 0.18288)
		(layer "In4.Cu")
		(net "M_G_CPU0_SA_DQS_DP<2>")
	)
	(segment
		(start 431.877724 -293.562278)
		(end 431.331624 -293.562278)
		(width 0.18288)
		(layer "In4.Cu")
		(net "M_G_CPU0_SA_DQS_DP<2>")
	)
	(segment
		(start 430.536604 -293.562278)
		(end 429.990504 -293.562278)
		(width 0.18288)
		(layer "In4.Cu")
		(net "M_G_CPU0_SA_DQS_DP<2>")
	)
	(segment
		(start 420.08044 -295.063926)
		(end 419.360096 -294.920416)
		(width 0.18288)
		(layer "In4.Cu")
		(net "M_G_CPU0_SA_DQS_DP<2>")
	)
	(segment
		(start 419.360096 -294.920416)
		(end 419.239446 -294.870886)
		(width 0.18288)
		(layer "In4.Cu")
		(net "M_G_CPU0_SA_DQS_DP<2>")
	)
	(segment
		(start 406.468072 -283.950918)
		(end 406.343612 -284.075378)
		(width 0.18288)
		(layer "In4.Cu")
		(net "M_G_CPU0_SA_DQS_DP<2>")
	)
	(segment
		(start 429.319944 -293.437818)
		(end 429.195484 -293.562278)
		(width 0.18288)
		(layer "In4.Cu")
		(net "M_G_CPU0_SA_DQS_DP<2>")
	)
	(segment
		(start 379.049534 -265.749786)
		(end 379.015498 -265.70686)
		(width 0.088646)
		(layer "In4.Cu")
		(net "M_G_CPU0_SA_DQS_DP<2>")
	)
	(segment
		(start 404.411434 -283.22397)
		(end 404.411688 -283.22397)
		(width 0.18288)
		(layer "In4.Cu")
		(net "M_G_CPU0_SA_DQS_DP<2>")
	)
	(segment
		(start 429.866044 -293.437818)
		(end 429.319944 -293.437818)
		(width 0.18288)
		(layer "In4.Cu")
		(net "M_G_CPU0_SA_DQS_DP<2>")
	)
	(segment
		(start 404.43531 -283.27985)
		(end 404.411434 -283.22397)
		(width 0.18288)
		(layer "In4.Cu")
		(net "M_G_CPU0_SA_DQS_DP<2>")
	)
	(segment
		(start 384.407664 -265.803888)
		(end 384.392932 -265.812524)
		(width 0.088646)
		(layer "In4.Cu")
		(net "M_G_CPU0_SA_DQS_DP<2>")
	)
	(segment
		(start 410.219144 -287.250378)
		(end 410.219144 -286.563562)
		(width 0.18288)
		(layer "In4.Cu")
		(net "M_G_CPU0_SA_DQS_DP<2>")
	)
	(segment
		(start 434.783484 -293.695374)
		(end 434.336952 -293.695374)
		(width 0.18288)
		(layer "In4.Cu")
		(net "M_G_CPU0_SA_DQS_DP<2>")
	)
	(segment
		(start 427.978824 -293.437818)
		(end 427.854364 -293.562278)
		(width 0.18288)
		(layer "In4.Cu")
		(net "M_G_CPU0_SA_DQS_DP<2>")
	)
	(segment
		(start 429.990504 -293.562278)
		(end 429.866044 -293.437818)
		(width 0.18288)
		(layer "In4.Cu")
		(net "M_G_CPU0_SA_DQS_DP<2>")
	)
	(segment
		(start 427.308264 -293.562278)
		(end 427.183804 -293.437818)
		(width 0.18288)
		(layer "In4.Cu")
		(net "M_G_CPU0_SA_DQS_DP<2>")
	)
	(segment
		(start 421.558974 -295.20261)
		(end 421.23741 -295.20261)
		(width 0.18288)
		(layer "In4.Cu")
		(net "M_G_CPU0_SA_DQS_DP<2>")
	)
	(segment
		(start 378.700284 -265.312144)
		(end 378.697744 -265.314176)
		(width 0.088646)
		(layer "In4.Cu")
		(net "M_G_CPU0_SA_DQS_DP<2>")
	)
	(segment
		(start 383.467864 -265.803888)
		(end 383.45618 -265.810746)
		(width 0.088646)
		(layer "In4.Cu")
		(net "M_G_CPU0_SA_DQS_DP<2>")
	)
	(segment
		(start 405.797512 -284.075378)
		(end 405.673052 -283.950918)
		(width 0.18288)
		(layer "In4.Cu")
		(net "M_G_CPU0_SA_DQS_DP<2>")
	)
	(segment
		(start 424.349164 -294.356028)
		(end 423.747184 -294.356028)
		(width 0.18288)
		(layer "In4.Cu")
		(net "M_G_CPU0_SA_DQS_DP<2>")
	)
	(segment
		(start 420.842694 -295.492678)
		(end 420.840916 -295.4909)
		(width 0.18288)
		(layer "In4.Cu")
		(net "M_G_CPU0_SA_DQS_DP<2>")
	)
	(segment
		(start 392.298936 -269.038832)
		(end 390.961626 -268.484858)
		(width 0.18288)
		(layer "In4.Cu")
		(net "M_G_CPU0_SA_DQS_DP<2>")
	)
	(segment
		(start 416.47237 -292.470586)
		(end 415.89325 -291.891466)
		(width 0.18288)
		(layer "In4.Cu")
		(net "M_G_CPU0_SA_DQS_DP<2>")
	)
	(segment
		(start 414.722818 -291.349176)
		(end 414.546796 -291.349176)
		(width 0.18288)
		(layer "In4.Cu")
		(net "M_G_CPU0_SA_DQS_DP<2>")
	)
	(segment
		(start 413.05734 -290.197286)
		(end 412.19374 -289.333686)
		(width 0.18288)
		(layer "In4.Cu")
		(net "M_G_CPU0_SA_DQS_DP<2>")
	)
	(segment
		(start 432.548284 -293.437818)
		(end 432.002184 -293.437818)
		(width 0.18288)
		(layer "In4.Cu")
		(net "M_G_CPU0_SA_DQS_DP<2>")
	)
	(segment
		(start 415.265362 -291.891466)
		(end 414.722818 -291.349176)
		(width 0.18288)
		(layer "In4.Cu")
		(net "M_G_CPU0_SA_DQS_DP<2>")
	)
	(segment
		(start 401.766786 -276.969982)
		(end 393.835636 -269.038832)
		(width 0.18288)
		(layer "In4.Cu")
		(net "M_G_CPU0_SA_DQS_DP<2>")
	)
	(segment
		(start 415.89325 -291.891466)
		(end 415.265362 -291.891466)
		(width 0.18288)
		(layer "In4.Cu")
		(net "M_G_CPU0_SA_DQS_DP<2>")
	)
	(segment
		(start 380.648464 -265.803634)
		(end 380.633732 -265.81227)
		(width 0.088646)
		(layer "In4.Cu")
		(net "M_G_CPU0_SA_DQS_DP<2>")
	)
	(segment
		(start 383.45618 -265.810746)
		(end 383.453132 -265.81227)
		(width 0.088646)
		(layer "In4.Cu")
		(net "M_G_CPU0_SA_DQS_DP<2>")
	)
	(segment
		(start 420.509192 -295.492678)
		(end 420.08044 -295.063926)
		(width 0.18288)
		(layer "In4.Cu")
		(net "M_G_CPU0_SA_DQS_DP<2>")
	)
	(segment
		(start 390.675622 -268.366494)
		(end 388.740142 -266.43076)
		(width 0.18288)
		(layer "In4.Cu")
		(net "M_G_CPU0_SA_DQS_DP<2>")
	)
	(segment
		(start 420.588694 -295.492678)
		(end 420.509192 -295.492678)
		(width 0.18288)
		(layer "In4.Cu")
		(net "M_G_CPU0_SA_DQS_DP<2>")
	)
	(segment
		(start 418.19068 -293.600632)
		(end 417.804092 -293.214044)
		(width 0.18288)
		(layer "In4.Cu")
		(net "M_G_CPU0_SA_DQS_DP<2>")
	)
	(segment
		(start 393.835636 -269.038832)
		(end 392.298936 -269.038832)
		(width 0.18288)
		(layer "In4.Cu")
		(net "M_G_CPU0_SA_DQS_DP<2>")
	)
	(segment
		(start 425.313094 -294.357552)
		(end 425.02836 -294.642286)
		(width 0.18288)
		(layer "In4.Cu")
		(net "M_G_CPU0_SA_DQS_DP<2>")
	)
	(segment
		(start 386.605272 -265.885168)
		(end 386.581904 -265.885168)
		(width 0.088646)
		(layer "In4.Cu")
		(net "M_G_CPU0_SA_DQS_DP<2>")
	)
	(segment
		(start 405.106632 -283.950918)
		(end 404.43531 -283.27985)
		(width 0.18288)
		(layer "In4.Cu")
		(net "M_G_CPU0_SA_DQS_DP<2>")
	)
	(segment
		(start 379.708664 -265.803888)
		(end 379.693932 -265.812524)
		(width 0.088646)
		(layer "In4.Cu")
		(net "M_G_CPU0_SA_DQS_DP<2>")
	)
	(segment
		(start 435.034436 -293.946326)
		(end 434.783484 -293.695374)
		(width 0.18288)
		(layer "In4.Cu")
		(net "M_G_CPU0_SA_DQS_DP<2>")
	)
	(segment
		(start 418.366702 -293.600632)
		(end 418.19068 -293.600632)
		(width 0.18288)
		(layer "In4.Cu")
		(net "M_G_CPU0_SA_DQS_DP<2>")
	)
	(segment
		(start 414.160462 -290.962842)
		(end 414.160462 -290.78682)
		(width 0.18288)
		(layer "In4.Cu")
		(net "M_G_CPU0_SA_DQS_DP<2>")
	)
	(segment
		(start 418.90569 -294.537384)
		(end 418.90569 -294.13962)
		(width 0.18288)
		(layer "In4.Cu")
		(net "M_G_CPU0_SA_DQS_DP<2>")
	)
	(segment
		(start 423.747184 -294.356028)
		(end 423.622724 -294.480488)
		(width 0.18288)
		(layer "In4.Cu")
		(net "M_G_CPU0_SA_DQS_DP<2>")
	)
	(segment
		(start 414.546796 -291.349176)
		(end 414.160462 -290.962842)
		(width 0.18288)
		(layer "In4.Cu")
		(net "M_G_CPU0_SA_DQS_DP<2>")
	)
	(segment
		(start 429.195484 -293.562278)
		(end 428.649384 -293.562278)
		(width 0.18288)
		(layer "In4.Cu")
		(net "M_G_CPU0_SA_DQS_DP<2>")
	)
	(segment
		(start 435.553358 -293.946326)
		(end 435.034436 -293.946326)
		(width 0.18288)
		(layer "In4.Cu")
		(net "M_G_CPU0_SA_DQS_DP<2>")
	)
	(segment
		(start 432.672744 -293.562278)
		(end 432.548284 -293.437818)
		(width 0.18288)
		(layer "In4.Cu")
		(net "M_G_CPU0_SA_DQS_DP<2>")
	)
	(segment
		(start 410.219144 -286.563562)
		(end 409.814014 -286.158432)
		(width 0.18288)
		(layer "In4.Cu")
		(net "M_G_CPU0_SA_DQS_DP<2>")
	)
	(segment
		(start 423.622724 -294.480488)
		(end 423.076624 -294.480488)
		(width 0.18288)
		(layer "In4.Cu")
		(net "M_G_CPU0_SA_DQS_DP<2>")
	)
	(segment
		(start 388.19455 -265.885168)
		(end 386.605272 -265.885168)
		(width 0.18288)
		(layer "In4.Cu")
		(net "M_G_CPU0_SA_DQS_DP<2>")
	)
	(segment
		(start 431.331624 -293.562278)
		(end 431.207164 -293.437818)
		(width 0.18288)
		(layer "In4.Cu")
		(net "M_G_CPU0_SA_DQS_DP<2>")
	)
	(segment
		(start 427.854364 -293.562278)
		(end 427.308264 -293.562278)
		(width 0.18288)
		(layer "In4.Cu")
		(net "M_G_CPU0_SA_DQS_DP<2>")
	)
	(segment
		(start 386.581904 -265.885168)
		(end 386.52196 -265.825224)
		(width 0.088646)
		(layer "In4.Cu")
		(net "M_G_CPU0_SA_DQS_DP<2>")
	)
	(segment
		(start 427.183804 -293.437818)
		(end 426.637704 -293.437818)
		(width 0.18288)
		(layer "In4.Cu")
		(net "M_G_CPU0_SA_DQS_DP<2>")
	)
	(segment
		(start 411.24632 -288.544508)
		(end 411.24632 -288.277554)
		(width 0.18288)
		(layer "In4.Cu")
		(net "M_G_CPU0_SA_DQS_DP<2>")
	)
	(segment
		(start 380.08306 -265.803634)
		(end 380.08306 -265.803888)
		(width 0.088646)
		(layer "In4.Cu")
		(net "M_G_CPU0_SA_DQS_DP<2>")
	)
	(segment
		(start 412.19374 -289.333686)
		(end 412.035498 -289.333686)
		(width 0.18288)
		(layer "In4.Cu")
		(net "M_G_CPU0_SA_DQS_DP<2>")
	)
	(segment
		(start 428.524924 -293.437818)
		(end 427.978824 -293.437818)
		(width 0.18288)
		(layer "In4.Cu")
		(net "M_G_CPU0_SA_DQS_DP<2>")
	)
	(segment
		(start 420.590472 -295.4909)
		(end 420.588694 -295.492678)
		(width 0.18288)
		(layer "In4.Cu")
		(net "M_G_CPU0_SA_DQS_DP<2>")
	)
	(segment
		(start 412.035498 -289.333686)
		(end 411.24632 -288.544508)
		(width 0.18288)
		(layer "In4.Cu")
		(net "M_G_CPU0_SA_DQS_DP<2>")
	)
	(segment
		(start 425.02836 -294.642286)
		(end 424.635422 -294.642286)
		(width 0.18288)
		(layer "In4.Cu")
		(net "M_G_CPU0_SA_DQS_DP<2>")
	)
	(segment
		(start 379.015498 -265.70686)
		(end 378.700284 -265.312144)
		(width 0.088646)
		(layer "In4.Cu")
		(net "M_G_CPU0_SA_DQS_DP<2>")
	)
	(segment
		(start 417.804092 -293.038022)
		(end 417.236656 -292.470586)
		(width 0.18288)
		(layer "In4.Cu")
		(net "M_G_CPU0_SA_DQS_DP<2>")
	)
	(segment
		(start 419.239446 -294.870886)
		(end 418.90569 -294.537384)
		(width 0.18288)
		(layer "In4.Cu")
		(net "M_G_CPU0_SA_DQS_DP<2>")
	)
	(segment
		(start 433.343304 -293.437818)
		(end 433.218844 -293.562278)
		(width 0.18288)
		(layer "In4.Cu")
		(net "M_G_CPU0_SA_DQS_DP<2>")
	)
	(segment
		(start 428.649384 -293.562278)
		(end 428.524924 -293.437818)
		(width 0.18288)
		(layer "In4.Cu")
		(net "M_G_CPU0_SA_DQS_DP<2>")
	)
	(segment
		(start 408.088592 -285.025338)
		(end 407.91257 -285.025338)
		(width 0.18288)
		(layer "In4.Cu")
		(net "M_G_CPU0_SA_DQS_DP<2>")
	)
	(segment
		(start 433.218844 -293.562278)
		(end 432.672744 -293.562278)
		(width 0.18288)
		(layer "In4.Cu")
		(net "M_G_CPU0_SA_DQS_DP<2>")
	)
	(segment
		(start 431.207164 -293.437818)
		(end 430.661064 -293.437818)
		(width 0.18288)
		(layer "In4.Cu")
		(net "M_G_CPU0_SA_DQS_DP<2>")
	)
	(segment
		(start 432.002184 -293.437818)
		(end 431.877724 -293.562278)
		(width 0.18288)
		(layer "In4.Cu")
		(net "M_G_CPU0_SA_DQS_DP<2>")
	)
	(segment
		(start 407.525982 -284.63875)
		(end 407.525982 -284.462728)
		(width 0.18288)
		(layer "In4.Cu")
		(net "M_G_CPU0_SA_DQS_DP<2>")
	)
	(segment
		(start 411.24632 -288.277554)
		(end 410.219144 -287.250378)
		(width 0.18288)
		(layer "In4.Cu")
		(net "M_G_CPU0_SA_DQS_DP<2>")
	)
	(segment
		(start 382.528064 -265.803634)
		(end 382.513332 -265.81227)
		(width 0.088646)
		(layer "In4.Cu")
		(net "M_G_CPU0_SA_DQS_DP<2>")
	)
	(segment
		(start 426.637704 -293.437818)
		(end 425.71797 -294.357552)
		(width 0.18288)
		(layer "In4.Cu")
		(net "M_G_CPU0_SA_DQS_DP<2>")
	)
	(segment
		(start 422.952164 -294.356028)
		(end 422.406064 -294.356028)
		(width 0.18288)
		(layer "In4.Cu")
		(net "M_G_CPU0_SA_DQS_DP<2>")
	)
	(segment
		(start 378.697744 -265.314176)
		(end 378.486416 -265.314176)
		(width 0.088646)
		(layer "In4.Cu")
		(net "M_G_CPU0_SA_DQS_DP<2>")
	)
	(segment
		(start 386.52196 -265.825224)
		(end 385.345686 -265.825224)
		(width 0.088646)
		(layer "In4.Cu")
		(net "M_G_CPU0_SA_DQS_DP<2>")
	)
	(segment
		(start 407.525982 -284.462728)
		(end 407.014172 -283.950918)
		(width 0.18288)
		(layer "In4.Cu")
		(net "M_G_CPU0_SA_DQS_DP<2>")
	)
	(segment
		(start 417.804092 -293.214044)
		(end 417.804092 -293.038022)
		(width 0.18288)
		(layer "In4.Cu")
		(net "M_G_CPU0_SA_DQS_DP<2>")
	)
	(segment
		(start 422.406064 -294.356028)
		(end 421.558974 -295.20261)
		(width 0.18288)
		(layer "In4.Cu")
		(net "M_G_CPU0_SA_DQS_DP<2>")
	)
	(segment
		(start 407.014172 -283.950918)
		(end 406.468072 -283.950918)
		(width 0.18288)
		(layer "In4.Cu")
		(net "M_G_CPU0_SA_DQS_DP<2>")
	)
	(segment
		(start 425.71797 -294.357552)
		(end 425.313094 -294.357552)
		(width 0.18288)
		(layer "In4.Cu")
		(net "M_G_CPU0_SA_DQS_DP<2>")
	)
	(segment
		(start 407.91257 -285.025338)
		(end 407.525982 -284.63875)
		(width 0.18288)
		(layer "In4.Cu")
		(net "M_G_CPU0_SA_DQS_DP<2>")
	)
	(segment
		(start 409.814014 -286.158432)
		(end 409.221686 -286.158432)
		(width 0.18288)
		(layer "In4.Cu")
		(net "M_G_CPU0_SA_DQS_DP<2>")
	)
	(segment
		(start 434.336952 -293.695374)
		(end 434.079396 -293.437818)
		(width 0.18288)
		(layer "In4.Cu")
		(net "M_G_CPU0_SA_DQS_DP<2>")
	)
	(segment
		(start 421.23741 -295.20261)
		(end 420.947342 -295.492678)
		(width 0.18288)
		(layer "In4.Cu")
		(net "M_G_CPU0_SA_DQS_DP<2>")
	)
	(segment
		(start 434.079396 -293.437818)
		(end 433.343304 -293.437818)
		(width 0.18288)
		(layer "In4.Cu")
		(net "M_G_CPU0_SA_DQS_DP<2>")
	)
	(segment
		(start 418.90569 -294.13962)
		(end 418.366702 -293.600632)
		(width 0.18288)
		(layer "In4.Cu")
		(net "M_G_CPU0_SA_DQS_DP<2>")
	)
	(segment
		(start 390.961626 -268.484858)
		(end 390.675622 -268.366494)
		(width 0.18288)
		(layer "In4.Cu")
		(net "M_G_CPU0_SA_DQS_DP<2>")
	)
	(segment
		(start 409.221686 -286.158432)
		(end 408.088592 -285.025338)
		(width 0.18288)
		(layer "In4.Cu")
		(net "M_G_CPU0_SA_DQS_DP<2>")
	)
	(arc
		(start 384.782822 -265.80338)
		(mid 384.782441 -265.803634)
		(end 384.78206 -265.803888)
		(width 0.088646)
		(layer "In4.Cu")
		(net "M_G_CPU0_SA_DQS_DP<2>")
	)
	(arc
		(start 381.02286 -265.803634)
		(mid 380.835662 -265.753491)
		(end 380.648464 -265.803634)
		(width 0.088646)
		(layer "In4.Cu")
		(net "M_G_CPU0_SA_DQS_DP<2>")
	)
	(arc
		(start 381.588264 -265.803634)
		(mid 381.305562 -265.87941)
		(end 381.02286 -265.803634)
		(width 0.088646)
		(layer "In4.Cu")
		(net "M_G_CPU0_SA_DQS_DP<2>")
	)
	(arc
		(start 384.78206 -265.803888)
		(mid 384.594862 -265.753745)
		(end 384.407664 -265.803888)
		(width 0.088646)
		(layer "In4.Cu")
		(net "M_G_CPU0_SA_DQS_DP<2>")
	)
	(arc
		(start 385.25958 -265.844782)
		(mid 385.016607 -265.877033)
		(end 384.782822 -265.80338)
		(width 0.088646)
		(layer "In4.Cu")
		(net "M_G_CPU0_SA_DQS_DP<2>")
	)
	(arc
		(start 382.513332 -265.81227)
		(mid 382.236857 -265.87959)
		(end 381.96266 -265.803634)
		(width 0.088646)
		(layer "In4.Cu")
		(net "M_G_CPU0_SA_DQS_DP<2>")
	)
	(arc
		(start 383.84226 -265.803888)
		(mid 383.655062 -265.753745)
		(end 383.467864 -265.803888)
		(width 0.088646)
		(layer "In4.Cu")
		(net "M_G_CPU0_SA_DQS_DP<2>")
	)
	(arc
		(start 380.633732 -265.81227)
		(mid 380.357257 -265.87959)
		(end 380.08306 -265.803634)
		(width 0.088646)
		(layer "In4.Cu")
		(net "M_G_CPU0_SA_DQS_DP<2>")
	)
	(arc
		(start 379.693932 -265.812524)
		(mid 379.417491 -265.87969)
		(end 379.14326 -265.803888)
		(width 0.088646)
		(layer "In4.Cu")
		(net "M_G_CPU0_SA_DQS_DP<2>")
	)
	(arc
		(start 383.453132 -265.81227)
		(mid 383.176657 -265.87959)
		(end 382.90246 -265.803634)
		(width 0.088646)
		(layer "In4.Cu")
		(net "M_G_CPU0_SA_DQS_DP<2>")
	)
	(arc
		(start 385.345686 -265.825224)
		(mid 385.301994 -265.83219)
		(end 385.25958 -265.844782)
		(width 0.088646)
		(layer "In4.Cu")
		(net "M_G_CPU0_SA_DQS_DP<2>")
	)
	(arc
		(start 380.08306 -265.803888)
		(mid 379.895862 -265.753745)
		(end 379.708664 -265.803888)
		(width 0.088646)
		(layer "In4.Cu")
		(net "M_G_CPU0_SA_DQS_DP<2>")
	)
	(arc
		(start 382.90246 -265.803634)
		(mid 382.715262 -265.753491)
		(end 382.528064 -265.803634)
		(width 0.088646)
		(layer "In4.Cu")
		(net "M_G_CPU0_SA_DQS_DP<2>")
	)
	(arc
		(start 384.392932 -265.812524)
		(mid 384.116491 -265.87969)
		(end 383.84226 -265.803888)
		(width 0.088646)
		(layer "In4.Cu")
		(net "M_G_CPU0_SA_DQS_DP<2>")
	)
	(arc
		(start 381.96266 -265.803634)
		(mid 381.775462 -265.753491)
		(end 381.588264 -265.803634)
		(width 0.088646)
		(layer "In4.Cu")
		(net "M_G_CPU0_SA_DQS_DP<2>")
	)
	(segment
		(start 435.823614 -303.566576)
		(end 436.928514 -303.566576)
		(width 0.20066)
		(layer "F.Cu")
		(net "M_G_CPU0_SA_DQS_DP<1>")
	)
	(segment
		(start 442.032898 -303.991772)
		(end 442.038994 -303.997868)
		(width 0.1016)
		(layer "F.Cu")
		(net "M_G_CPU0_SA_DQS_DP<1>")
	)
	(segment
		(start 375.197116 -272.103342)
		(end 375.196862 -272.639282)
		(width 0.20066)
		(layer "F.Cu")
		(net "M_G_CPU0_SA_DQS_DP<1>")
	)
	(segment
		(start 442.66485 -303.695354)
		(end 443.035436 -303.695354)
		(width 0.20066)
		(layer "F.Cu")
		(net "M_G_CPU0_SA_DQS_DP<1>")
	)
	(segment
		(start 443.035436 -303.695354)
		(end 443.4459 -303.28489)
		(width 0.20066)
		(layer "F.Cu")
		(net "M_G_CPU0_SA_DQS_DP<1>")
	)
	(segment
		(start 437.517794 -303.566576)
		(end 437.758332 -303.326038)
		(width 0.20066)
		(layer "F.Cu")
		(net "M_G_CPU0_SA_DQS_DP<1>")
	)
	(segment
		(start 439.710322 -303.991772)
		(end 439.849768 -303.991772)
		(width 0.20066)
		(layer "F.Cu")
		(net "M_G_CPU0_SA_DQS_DP<1>")
	)
	(segment
		(start 442.362336 -303.997868)
		(end 442.66485 -303.695354)
		(width 0.20066)
		(layer "F.Cu")
		(net "M_G_CPU0_SA_DQS_DP<1>")
	)
	(segment
		(start 439.875676 -303.991772)
		(end 442.032898 -303.991772)
		(width 0.1016)
		(layer "F.Cu")
		(net "M_G_CPU0_SA_DQS_DP<1>")
	)
	(segment
		(start 439.849768 -303.991772)
		(end 439.875676 -303.991772)
		(width 0.101854)
		(layer "F.Cu")
		(net "M_G_CPU0_SA_DQS_DP<1>")
	)
	(segment
		(start 443.923674 -303.566576)
		(end 444.472314 -303.566576)
		(width 0.20066)
		(layer "F.Cu")
		(net "M_G_CPU0_SA_DQS_DP<1>")
	)
	(segment
		(start 443.641988 -303.28489)
		(end 443.923674 -303.566576)
		(width 0.20066)
		(layer "F.Cu")
		(net "M_G_CPU0_SA_DQS_DP<1>")
	)
	(segment
		(start 442.038994 -303.997868)
		(end 442.362336 -303.997868)
		(width 0.20066)
		(layer "F.Cu")
		(net "M_G_CPU0_SA_DQS_DP<1>")
	)
	(segment
		(start 438.773316 -303.740566)
		(end 439.459116 -303.740566)
		(width 0.20066)
		(layer "F.Cu")
		(net "M_G_CPU0_SA_DQS_DP<1>")
	)
	(segment
		(start 443.4459 -303.28489)
		(end 443.641988 -303.28489)
		(width 0.20066)
		(layer "F.Cu")
		(net "M_G_CPU0_SA_DQS_DP<1>")
	)
	(segment
		(start 437.758332 -303.326038)
		(end 438.358788 -303.326038)
		(width 0.20066)
		(layer "F.Cu")
		(net "M_G_CPU0_SA_DQS_DP<1>")
	)
	(segment
		(start 436.928514 -303.566576)
		(end 437.517794 -303.566576)
		(width 0.20066)
		(layer "F.Cu")
		(net "M_G_CPU0_SA_DQS_DP<1>")
	)
	(segment
		(start 438.358788 -303.326038)
		(end 438.773316 -303.740566)
		(width 0.20066)
		(layer "F.Cu")
		(net "M_G_CPU0_SA_DQS_DP<1>")
	)
	(segment
		(start 439.459116 -303.740566)
		(end 439.710322 -303.991772)
		(width 0.20066)
		(layer "F.Cu")
		(net "M_G_CPU0_SA_DQS_DP<1>")
	)
	(segment
		(start 431.235104 -300.916086)
		(end 430.177448 -300.916086)
		(width 0.18288)
		(layer "In6.Cu")
		(net "M_G_CPU0_SA_DQS_DP<1>")
	)
	(segment
		(start 414.692338 -295.392856)
		(end 414.516316 -295.392856)
		(width 0.18288)
		(layer "In6.Cu")
		(net "M_G_CPU0_SA_DQS_DP<1>")
	)
	(segment
		(start 420.95293 -297.190922)
		(end 420.442644 -297.190922)
		(width 0.18288)
		(layer "In6.Cu")
		(net "M_G_CPU0_SA_DQS_DP<1>")
	)
	(segment
		(start 421.783002 -296.9006)
		(end 421.243252 -296.9006)
		(width 0.18288)
		(layer "In6.Cu")
		(net "M_G_CPU0_SA_DQS_DP<1>")
	)
	(segment
		(start 433.27828 -302.959262)
		(end 431.235104 -300.916086)
		(width 0.18288)
		(layer "In6.Cu")
		(net "M_G_CPU0_SA_DQS_DP<1>")
	)
	(segment
		(start 421.243252 -296.9006)
		(end 420.95293 -297.190922)
		(width 0.18288)
		(layer "In6.Cu")
		(net "M_G_CPU0_SA_DQS_DP<1>")
	)
	(segment
		(start 426.875956 -298.695364)
		(end 426.489622 -298.30903)
		(width 0.18288)
		(layer "In6.Cu")
		(net "M_G_CPU0_SA_DQS_DP<1>")
	)
	(segment
		(start 414.129728 -294.830246)
		(end 413.636968 -294.337486)
		(width 0.18288)
		(layer "In6.Cu")
		(net "M_G_CPU0_SA_DQS_DP<1>")
	)
	(segment
		(start 417.162234 -296.93235)
		(end 416.616134 -296.93235)
		(width 0.18288)
		(layer "In6.Cu")
		(net "M_G_CPU0_SA_DQS_DP<1>")
	)
	(segment
		(start 427.6979 -299.341286)
		(end 427.051978 -298.695364)
		(width 0.18288)
		(layer "In6.Cu")
		(net "M_G_CPU0_SA_DQS_DP<1>")
	)
	(segment
		(start 388.512304 -274.685252)
		(end 388.45236 -274.625308)
		(width 0.088646)
		(layer "In6.Cu")
		(net "M_G_CPU0_SA_DQS_DP<1>")
	)
	(segment
		(start 380.567946 -273.137376)
		(end 380.553214 -273.12874)
		(width 0.088646)
		(layer "In6.Cu")
		(net "M_G_CPU0_SA_DQS_DP<1>")
	)
	(segment
		(start 435.823614 -303.566576)
		(end 435.551072 -303.294034)
		(width 0.18288)
		(layer "In6.Cu")
		(net "M_G_CPU0_SA_DQS_DP<1>")
	)
	(segment
		(start 414.129728 -295.006268)
		(end 414.129728 -294.830246)
		(width 0.18288)
		(layer "In6.Cu")
		(net "M_G_CPU0_SA_DQS_DP<1>")
	)
	(segment
		(start 430.177448 -300.916086)
		(end 429.662082 -300.40072)
		(width 0.18288)
		(layer "In6.Cu")
		(net "M_G_CPU0_SA_DQS_DP<1>")
	)
	(segment
		(start 426.489622 -298.30903)
		(end 426.489622 -298.133008)
		(width 0.18288)
		(layer "In6.Cu")
		(net "M_G_CPU0_SA_DQS_DP<1>")
	)
	(segment
		(start 429.099472 -299.83811)
		(end 428.602648 -299.341286)
		(width 0.18288)
		(layer "In6.Cu")
		(net "M_G_CPU0_SA_DQS_DP<1>")
	)
	(segment
		(start 427.051978 -298.695364)
		(end 426.875956 -298.695364)
		(width 0.18288)
		(layer "In6.Cu")
		(net "M_G_CPU0_SA_DQS_DP<1>")
	)
	(segment
		(start 412.143956 -294.690546)
		(end 411.733238 -294.690546)
		(width 0.18288)
		(layer "In6.Cu")
		(net "M_G_CPU0_SA_DQS_DP<1>")
	)
	(segment
		(start 403.736302 -291.650674)
		(end 403.56028 -291.650674)
		(width 0.18288)
		(layer "In6.Cu")
		(net "M_G_CPU0_SA_DQS_DP<1>")
	)
	(segment
		(start 410.389324 -294.025066)
		(end 408.539442 -293.257732)
		(width 0.18288)
		(layer "In6.Cu")
		(net "M_G_CPU0_SA_DQS_DP<1>")
	)
	(segment
		(start 375.868946 -273.137376)
		(end 375.854214 -273.12874)
		(width 0.088646)
		(layer "In6.Cu")
		(net "M_G_CPU0_SA_DQS_DP<1>")
	)
	(segment
		(start 375.854214 -273.12874)
		(end 375.853452 -273.128232)
		(width 0.088646)
		(layer "In6.Cu")
		(net "M_G_CPU0_SA_DQS_DP<1>")
	)
	(segment
		(start 402.611844 -290.702238)
		(end 402.22551 -290.315904)
		(width 0.18288)
		(layer "In6.Cu")
		(net "M_G_CPU0_SA_DQS_DP<1>")
	)
	(segment
		(start 418.967412 -297.05681)
		(end 418.842952 -296.93235)
		(width 0.18288)
		(layer "In6.Cu")
		(net "M_G_CPU0_SA_DQS_DP<1>")
	)
	(segment
		(start 405.896064 -293.382192)
		(end 405.771604 -293.257732)
		(width 0.18288)
		(layer "In6.Cu")
		(net "M_G_CPU0_SA_DQS_DP<1>")
	)
	(segment
		(start 434.732938 -302.959262)
		(end 433.27828 -302.959262)
		(width 0.18288)
		(layer "In6.Cu")
		(net "M_G_CPU0_SA_DQS_DP<1>")
	)
	(segment
		(start 415.139378 -295.839896)
		(end 414.692338 -295.392856)
		(width 0.18288)
		(layer "In6.Cu")
		(net "M_G_CPU0_SA_DQS_DP<1>")
	)
	(segment
		(start 417.832794 -297.05681)
		(end 417.286694 -297.05681)
		(width 0.18288)
		(layer "In6.Cu")
		(net "M_G_CPU0_SA_DQS_DP<1>")
	)
	(segment
		(start 422.662858 -297.780456)
		(end 421.783002 -296.9006)
		(width 0.18288)
		(layer "In6.Cu")
		(net "M_G_CPU0_SA_DQS_DP<1>")
	)
	(segment
		(start 404.122382 -292.212776)
		(end 404.122382 -292.036754)
		(width 0.18288)
		(layer "In6.Cu")
		(net "M_G_CPU0_SA_DQS_DP<1>")
	)
	(segment
		(start 417.286694 -297.05681)
		(end 417.162234 -296.93235)
		(width 0.18288)
		(layer "In6.Cu")
		(net "M_G_CPU0_SA_DQS_DP<1>")
	)
	(segment
		(start 411.733238 -294.690546)
		(end 411.416754 -294.374062)
		(width 0.18288)
		(layer "In6.Cu")
		(net "M_G_CPU0_SA_DQS_DP<1>")
	)
	(segment
		(start 401.83943 -289.753802)
		(end 401.83943 -281.107134)
		(width 0.18288)
		(layer "In6.Cu")
		(net "M_G_CPU0_SA_DQS_DP<1>")
	)
	(segment
		(start 389.976106 -275.062696)
		(end 389.065008 -274.685252)
		(width 0.18288)
		(layer "In6.Cu")
		(net "M_G_CPU0_SA_DQS_DP<1>")
	)
	(segment
		(start 386.822188 -273.204432)
		(end 386.4737 -273.204432)
		(width 0.088646)
		(layer "In6.Cu")
		(net "M_G_CPU0_SA_DQS_DP<1>")
	)
	(segment
		(start 404.684738 -292.59911)
		(end 404.508716 -292.59911)
		(width 0.18288)
		(layer "In6.Cu")
		(net "M_G_CPU0_SA_DQS_DP<1>")
	)
	(segment
		(start 401.83943 -281.107134)
		(end 395.794992 -275.062696)
		(width 0.18288)
		(layer "In6.Cu")
		(net "M_G_CPU0_SA_DQS_DP<1>")
	)
	(segment
		(start 375.657618 -272.939256)
		(end 375.622566 -272.880328)
		(width 0.088646)
		(layer "In6.Cu")
		(net "M_G_CPU0_SA_DQS_DP<1>")
	)
	(segment
		(start 406.566624 -293.257732)
		(end 406.442164 -293.382192)
		(width 0.18288)
		(layer "In6.Cu")
		(net "M_G_CPU0_SA_DQS_DP<1>")
	)
	(segment
		(start 435.06771 -303.294034)
		(end 434.732938 -302.959262)
		(width 0.18288)
		(layer "In6.Cu")
		(net "M_G_CPU0_SA_DQS_DP<1>")
	)
	(segment
		(start 407.907744 -293.257732)
		(end 407.783284 -293.382192)
		(width 0.18288)
		(layer "In6.Cu")
		(net "M_G_CPU0_SA_DQS_DP<1>")
	)
	(segment
		(start 414.516316 -295.392856)
		(end 414.129728 -295.006268)
		(width 0.18288)
		(layer "In6.Cu")
		(net "M_G_CPU0_SA_DQS_DP<1>")
	)
	(segment
		(start 395.794992 -275.062696)
		(end 389.976106 -275.062696)
		(width 0.18288)
		(layer "In6.Cu")
		(net "M_G_CPU0_SA_DQS_DP<1>")
	)
	(segment
		(start 388.535672 -274.685252)
		(end 388.512304 -274.685252)
		(width 0.088646)
		(layer "In6.Cu")
		(net "M_G_CPU0_SA_DQS_DP<1>")
	)
	(segment
		(start 415.52368 -295.839896)
		(end 415.139378 -295.839896)
		(width 0.18288)
		(layer "In6.Cu")
		(net "M_G_CPU0_SA_DQS_DP<1>")
	)
	(segment
		(start 402.787866 -290.702238)
		(end 402.611844 -290.702238)
		(width 0.18288)
		(layer "In6.Cu")
		(net "M_G_CPU0_SA_DQS_DP<1>")
	)
	(segment
		(start 383.383028 -273.134836)
		(end 383.372614 -273.12874)
		(width 0.088646)
		(layer "In6.Cu")
		(net "M_G_CPU0_SA_DQS_DP<1>")
	)
	(segment
		(start 375.482612 -272.639282)
		(end 375.196862 -272.639282)
		(width 0.088646)
		(layer "In6.Cu")
		(net "M_G_CPU0_SA_DQS_DP<1>")
	)
	(segment
		(start 388.243064 -274.625308)
		(end 386.822188 -273.204432)
		(width 0.088646)
		(layer "In6.Cu")
		(net "M_G_CPU0_SA_DQS_DP<1>")
	)
	(segment
		(start 424.282362 -297.780456)
		(end 422.662858 -297.780456)
		(width 0.18288)
		(layer "In6.Cu")
		(net "M_G_CPU0_SA_DQS_DP<1>")
	)
	(segment
		(start 375.853452 -273.128232)
		(end 375.848118 -273.125184)
		(width 0.088646)
		(layer "In6.Cu")
		(net "M_G_CPU0_SA_DQS_DP<1>")
	)
	(segment
		(start 420.184072 -296.93235)
		(end 419.637972 -296.93235)
		(width 0.18288)
		(layer "In6.Cu")
		(net "M_G_CPU0_SA_DQS_DP<1>")
	)
	(segment
		(start 428.602648 -299.341286)
		(end 427.6979 -299.341286)
		(width 0.18288)
		(layer "In6.Cu")
		(net "M_G_CPU0_SA_DQS_DP<1>")
	)
	(segment
		(start 388.45236 -274.625308)
		(end 388.243064 -274.625308)
		(width 0.088646)
		(layer "In6.Cu")
		(net "M_G_CPU0_SA_DQS_DP<1>")
	)
	(segment
		(start 381.507746 -273.137376)
		(end 381.493014 -273.12874)
		(width 0.088646)
		(layer "In6.Cu")
		(net "M_G_CPU0_SA_DQS_DP<1>")
	)
	(segment
		(start 406.442164 -293.382192)
		(end 405.896064 -293.382192)
		(width 0.18288)
		(layer "In6.Cu")
		(net "M_G_CPU0_SA_DQS_DP<1>")
	)
	(segment
		(start 429.662082 -300.40072)
		(end 429.48606 -300.40072)
		(width 0.18288)
		(layer "In6.Cu")
		(net "M_G_CPU0_SA_DQS_DP<1>")
	)
	(segment
		(start 402.22551 -290.139882)
		(end 401.83943 -289.753802)
		(width 0.18288)
		(layer "In6.Cu")
		(net "M_G_CPU0_SA_DQS_DP<1>")
	)
	(segment
		(start 377.748546 -273.137376)
		(end 377.733814 -273.12874)
		(width 0.088646)
		(layer "In6.Cu")
		(net "M_G_CPU0_SA_DQS_DP<1>")
	)
	(segment
		(start 403.56028 -291.650674)
		(end 403.173946 -291.26434)
		(width 0.18288)
		(layer "In6.Cu")
		(net "M_G_CPU0_SA_DQS_DP<1>")
	)
	(segment
		(start 408.539442 -293.257732)
		(end 407.907744 -293.257732)
		(width 0.18288)
		(layer "In6.Cu")
		(net "M_G_CPU0_SA_DQS_DP<1>")
	)
	(segment
		(start 425.346876 -297.746928)
		(end 425.052998 -298.040806)
		(width 0.18288)
		(layer "In6.Cu")
		(net "M_G_CPU0_SA_DQS_DP<1>")
	)
	(segment
		(start 413.636968 -294.337486)
		(end 412.497016 -294.337486)
		(width 0.18288)
		(layer "In6.Cu")
		(net "M_G_CPU0_SA_DQS_DP<1>")
	)
	(segment
		(start 378.688346 -273.137376)
		(end 378.673614 -273.12874)
		(width 0.088646)
		(layer "In6.Cu")
		(net "M_G_CPU0_SA_DQS_DP<1>")
	)
	(segment
		(start 385.825492 -273.123914)
		(end 385.806696 -273.134836)
		(width 0.088646)
		(layer "In6.Cu")
		(net "M_G_CPU0_SA_DQS_DP<1>")
	)
	(segment
		(start 376.808746 -273.137376)
		(end 376.794014 -273.12874)
		(width 0.088646)
		(layer "In6.Cu")
		(net "M_G_CPU0_SA_DQS_DP<1>")
	)
	(segment
		(start 418.842952 -296.93235)
		(end 417.957254 -296.93235)
		(width 0.18288)
		(layer "In6.Cu")
		(net "M_G_CPU0_SA_DQS_DP<1>")
	)
	(segment
		(start 375.593356 -272.803874)
		(end 375.531126 -272.687796)
		(width 0.088646)
		(layer "In6.Cu")
		(net "M_G_CPU0_SA_DQS_DP<1>")
	)
	(segment
		(start 405.34336 -293.257732)
		(end 404.684738 -292.59911)
		(width 0.18288)
		(layer "In6.Cu")
		(net "M_G_CPU0_SA_DQS_DP<1>")
	)
	(segment
		(start 417.957254 -296.93235)
		(end 417.832794 -297.05681)
		(width 0.18288)
		(layer "In6.Cu")
		(net "M_G_CPU0_SA_DQS_DP<1>")
	)
	(segment
		(start 407.112724 -293.257732)
		(end 406.566624 -293.257732)
		(width 0.18288)
		(layer "In6.Cu")
		(net "M_G_CPU0_SA_DQS_DP<1>")
	)
	(segment
		(start 420.442644 -297.190922)
		(end 420.184072 -296.93235)
		(width 0.18288)
		(layer "In6.Cu")
		(net "M_G_CPU0_SA_DQS_DP<1>")
	)
	(segment
		(start 419.637972 -296.93235)
		(end 419.513512 -297.05681)
		(width 0.18288)
		(layer "In6.Cu")
		(net "M_G_CPU0_SA_DQS_DP<1>")
	)
	(segment
		(start 412.497016 -294.337486)
		(end 412.143956 -294.690546)
		(width 0.18288)
		(layer "In6.Cu")
		(net "M_G_CPU0_SA_DQS_DP<1>")
	)
	(segment
		(start 419.513512 -297.05681)
		(end 418.967412 -297.05681)
		(width 0.18288)
		(layer "In6.Cu")
		(net "M_G_CPU0_SA_DQS_DP<1>")
	)
	(segment
		(start 405.771604 -293.257732)
		(end 405.34336 -293.257732)
		(width 0.18288)
		(layer "In6.Cu")
		(net "M_G_CPU0_SA_DQS_DP<1>")
	)
	(segment
		(start 407.237184 -293.382192)
		(end 407.112724 -293.257732)
		(width 0.18288)
		(layer "In6.Cu")
		(net "M_G_CPU0_SA_DQS_DP<1>")
	)
	(segment
		(start 410.73832 -294.374062)
		(end 410.389324 -294.025066)
		(width 0.18288)
		(layer "In6.Cu")
		(net "M_G_CPU0_SA_DQS_DP<1>")
	)
	(segment
		(start 429.099472 -300.014132)
		(end 429.099472 -299.83811)
		(width 0.18288)
		(layer "In6.Cu")
		(net "M_G_CPU0_SA_DQS_DP<1>")
	)
	(segment
		(start 429.48606 -300.40072)
		(end 429.099472 -300.014132)
		(width 0.18288)
		(layer "In6.Cu")
		(net "M_G_CPU0_SA_DQS_DP<1>")
	)
	(segment
		(start 435.551072 -303.294034)
		(end 435.06771 -303.294034)
		(width 0.18288)
		(layer "In6.Cu")
		(net "M_G_CPU0_SA_DQS_DP<1>")
	)
	(segment
		(start 404.508716 -292.59911)
		(end 404.122382 -292.212776)
		(width 0.18288)
		(layer "In6.Cu")
		(net "M_G_CPU0_SA_DQS_DP<1>")
	)
	(segment
		(start 426.489622 -298.133008)
		(end 426.103542 -297.746928)
		(width 0.18288)
		(layer "In6.Cu")
		(net "M_G_CPU0_SA_DQS_DP<1>")
	)
	(segment
		(start 416.616134 -296.93235)
		(end 415.52368 -295.839896)
		(width 0.18288)
		(layer "In6.Cu")
		(net "M_G_CPU0_SA_DQS_DP<1>")
	)
	(segment
		(start 425.052998 -298.040806)
		(end 424.542712 -298.040806)
		(width 0.18288)
		(layer "In6.Cu")
		(net "M_G_CPU0_SA_DQS_DP<1>")
	)
	(segment
		(start 424.542712 -298.040806)
		(end 424.282362 -297.780456)
		(width 0.18288)
		(layer "In6.Cu")
		(net "M_G_CPU0_SA_DQS_DP<1>")
	)
	(segment
		(start 411.416754 -294.374062)
		(end 410.73832 -294.374062)
		(width 0.18288)
		(layer "In6.Cu")
		(net "M_G_CPU0_SA_DQS_DP<1>")
	)
	(segment
		(start 375.531126 -272.687796)
		(end 375.482612 -272.639282)
		(width 0.088646)
		(layer "In6.Cu")
		(net "M_G_CPU0_SA_DQS_DP<1>")
	)
	(segment
		(start 382.447546 -273.137376)
		(end 382.432814 -273.12874)
		(width 0.088646)
		(layer "In6.Cu")
		(net "M_G_CPU0_SA_DQS_DP<1>")
	)
	(segment
		(start 426.103542 -297.746928)
		(end 425.346876 -297.746928)
		(width 0.18288)
		(layer "In6.Cu")
		(net "M_G_CPU0_SA_DQS_DP<1>")
	)
	(segment
		(start 403.173946 -291.088318)
		(end 402.787866 -290.702238)
		(width 0.18288)
		(layer "In6.Cu")
		(net "M_G_CPU0_SA_DQS_DP<1>")
	)
	(segment
		(start 404.122382 -292.036754)
		(end 403.736302 -291.650674)
		(width 0.18288)
		(layer "In6.Cu")
		(net "M_G_CPU0_SA_DQS_DP<1>")
	)
	(segment
		(start 407.783284 -293.382192)
		(end 407.237184 -293.382192)
		(width 0.18288)
		(layer "In6.Cu")
		(net "M_G_CPU0_SA_DQS_DP<1>")
	)
	(segment
		(start 403.173946 -291.26434)
		(end 403.173946 -291.088318)
		(width 0.18288)
		(layer "In6.Cu")
		(net "M_G_CPU0_SA_DQS_DP<1>")
	)
	(segment
		(start 402.22551 -290.315904)
		(end 402.22551 -290.139882)
		(width 0.18288)
		(layer "In6.Cu")
		(net "M_G_CPU0_SA_DQS_DP<1>")
	)
	(segment
		(start 389.065008 -274.685252)
		(end 388.535672 -274.685252)
		(width 0.18288)
		(layer "In6.Cu")
		(net "M_G_CPU0_SA_DQS_DP<1>")
	)
	(arc
		(start 378.299218 -273.12874)
		(mid 378.025019 -273.204575)
		(end 377.748546 -273.137376)
		(width 0.088646)
		(layer "In6.Cu")
		(net "M_G_CPU0_SA_DQS_DP<1>")
	)
	(arc
		(start 382.998218 -273.12874)
		(mid 382.724019 -273.204575)
		(end 382.447546 -273.137376)
		(width 0.088646)
		(layer "In6.Cu")
		(net "M_G_CPU0_SA_DQS_DP<1>")
	)
	(arc
		(start 381.118618 -273.12874)
		(mid 380.844419 -273.204575)
		(end 380.567946 -273.137376)
		(width 0.088646)
		(layer "In6.Cu")
		(net "M_G_CPU0_SA_DQS_DP<1>")
	)
	(arc
		(start 382.058418 -273.12874)
		(mid 381.784219 -273.204575)
		(end 381.507746 -273.137376)
		(width 0.088646)
		(layer "In6.Cu")
		(net "M_G_CPU0_SA_DQS_DP<1>")
	)
	(arc
		(start 381.493014 -273.12874)
		(mid 381.305816 -273.078597)
		(end 381.118618 -273.12874)
		(width 0.088646)
		(layer "In6.Cu")
		(net "M_G_CPU0_SA_DQS_DP<1>")
	)
	(arc
		(start 375.84126 -273.120866)
		(mid 375.738915 -273.040703)
		(end 375.657618 -272.939256)
		(width 0.088646)
		(layer "In6.Cu")
		(net "M_G_CPU0_SA_DQS_DP<1>")
	)
	(arc
		(start 385.806696 -273.134836)
		(mid 385.528518 -273.204559)
		(end 385.25196 -273.12874)
		(width 0.088646)
		(layer "In6.Cu")
		(net "M_G_CPU0_SA_DQS_DP<1>")
	)
	(arc
		(start 378.673614 -273.12874)
		(mid 378.486416 -273.078597)
		(end 378.299218 -273.12874)
		(width 0.088646)
		(layer "In6.Cu")
		(net "M_G_CPU0_SA_DQS_DP<1>")
	)
	(arc
		(start 379.239018 -273.12874)
		(mid 378.964819 -273.204575)
		(end 378.688346 -273.137376)
		(width 0.088646)
		(layer "In6.Cu")
		(net "M_G_CPU0_SA_DQS_DP<1>")
	)
	(arc
		(start 375.622566 -272.880328)
		(mid 375.604681 -272.843353)
		(end 375.593356 -272.803874)
		(width 0.088646)
		(layer "In6.Cu")
		(net "M_G_CPU0_SA_DQS_DP<1>")
	)
	(arc
		(start 384.877564 -273.12874)
		(mid 384.594862 -273.204516)
		(end 384.31216 -273.12874)
		(width 0.088646)
		(layer "In6.Cu")
		(net "M_G_CPU0_SA_DQS_DP<1>")
	)
	(arc
		(start 376.794014 -273.12874)
		(mid 376.606816 -273.078597)
		(end 376.419618 -273.12874)
		(width 0.088646)
		(layer "In6.Cu")
		(net "M_G_CPU0_SA_DQS_DP<1>")
	)
	(arc
		(start 375.848118 -273.125184)
		(mid 375.844681 -273.123037)
		(end 375.84126 -273.120866)
		(width 0.088646)
		(layer "In6.Cu")
		(net "M_G_CPU0_SA_DQS_DP<1>")
	)
	(arc
		(start 383.372614 -273.12874)
		(mid 383.185416 -273.078597)
		(end 382.998218 -273.12874)
		(width 0.088646)
		(layer "In6.Cu")
		(net "M_G_CPU0_SA_DQS_DP<1>")
	)
	(arc
		(start 379.613414 -273.12874)
		(mid 379.426216 -273.078597)
		(end 379.239018 -273.12874)
		(width 0.088646)
		(layer "In6.Cu")
		(net "M_G_CPU0_SA_DQS_DP<1>")
	)
	(arc
		(start 386.4737 -273.204432)
		(mid 386.327508 -273.185137)
		(end 386.191252 -273.12874)
		(width 0.088646)
		(layer "In6.Cu")
		(net "M_G_CPU0_SA_DQS_DP<1>")
	)
	(arc
		(start 386.191252 -273.12874)
		(mid 386.009001 -273.078629)
		(end 385.825492 -273.123914)
		(width 0.088646)
		(layer "In6.Cu")
		(net "M_G_CPU0_SA_DQS_DP<1>")
	)
	(arc
		(start 380.553214 -273.12874)
		(mid 380.366016 -273.078597)
		(end 380.178818 -273.12874)
		(width 0.088646)
		(layer "In6.Cu")
		(net "M_G_CPU0_SA_DQS_DP<1>")
	)
	(arc
		(start 385.25196 -273.12874)
		(mid 385.064762 -273.078597)
		(end 384.877564 -273.12874)
		(width 0.088646)
		(layer "In6.Cu")
		(net "M_G_CPU0_SA_DQS_DP<1>")
	)
	(arc
		(start 383.937764 -273.12874)
		(mid 383.661205 -273.204483)
		(end 383.383028 -273.134836)
		(width 0.088646)
		(layer "In6.Cu")
		(net "M_G_CPU0_SA_DQS_DP<1>")
	)
	(arc
		(start 382.432814 -273.12874)
		(mid 382.245616 -273.078597)
		(end 382.058418 -273.12874)
		(width 0.088646)
		(layer "In6.Cu")
		(net "M_G_CPU0_SA_DQS_DP<1>")
	)
	(arc
		(start 377.733814 -273.12874)
		(mid 377.546616 -273.078597)
		(end 377.359418 -273.12874)
		(width 0.088646)
		(layer "In6.Cu")
		(net "M_G_CPU0_SA_DQS_DP<1>")
	)
	(arc
		(start 376.419618 -273.12874)
		(mid 376.145419 -273.204575)
		(end 375.868946 -273.137376)
		(width 0.088646)
		(layer "In6.Cu")
		(net "M_G_CPU0_SA_DQS_DP<1>")
	)
	(arc
		(start 380.178818 -273.12874)
		(mid 379.896116 -273.204516)
		(end 379.613414 -273.12874)
		(width 0.088646)
		(layer "In6.Cu")
		(net "M_G_CPU0_SA_DQS_DP<1>")
	)
	(arc
		(start 377.359418 -273.12874)
		(mid 377.085219 -273.204575)
		(end 376.808746 -273.137376)
		(width 0.088646)
		(layer "In6.Cu")
		(net "M_G_CPU0_SA_DQS_DP<1>")
	)
	(arc
		(start 384.31216 -273.12874)
		(mid 384.124962 -273.078597)
		(end 383.937764 -273.12874)
		(width 0.088646)
		(layer "In6.Cu")
		(net "M_G_CPU0_SA_DQS_DP<1>")
	)
	(segment
		(start 377.546616 -274.545044)
		(end 377.546616 -275.08073)
		(width 0.20066)
		(layer "F.Cu")
		(net "M_G_CPU0_SA_DQS_DP<0>")
	)
	(segment
		(start 438.773316 -313.09056)
		(end 439.459116 -313.09056)
		(width 0.20066)
		(layer "F.Cu")
		(net "M_G_CPU0_SA_DQS_DP<0>")
	)
	(segment
		(start 443.641988 -312.634884)
		(end 443.923674 -312.91657)
		(width 0.20066)
		(layer "F.Cu")
		(net "M_G_CPU0_SA_DQS_DP<0>")
	)
	(segment
		(start 443.035436 -313.045348)
		(end 443.4459 -312.634884)
		(width 0.20066)
		(layer "F.Cu")
		(net "M_G_CPU0_SA_DQS_DP<0>")
	)
	(segment
		(start 443.4459 -312.634884)
		(end 443.641988 -312.634884)
		(width 0.20066)
		(layer "F.Cu")
		(net "M_G_CPU0_SA_DQS_DP<0>")
	)
	(segment
		(start 439.849768 -313.341766)
		(end 439.875676 -313.341766)
		(width 0.101854)
		(layer "F.Cu")
		(net "M_G_CPU0_SA_DQS_DP<0>")
	)
	(segment
		(start 438.358788 -312.676032)
		(end 438.773316 -313.09056)
		(width 0.20066)
		(layer "F.Cu")
		(net "M_G_CPU0_SA_DQS_DP<0>")
	)
	(segment
		(start 442.032898 -313.341766)
		(end 442.038994 -313.347862)
		(width 0.1016)
		(layer "F.Cu")
		(net "M_G_CPU0_SA_DQS_DP<0>")
	)
	(segment
		(start 442.038994 -313.347862)
		(end 442.362336 -313.347862)
		(width 0.20066)
		(layer "F.Cu")
		(net "M_G_CPU0_SA_DQS_DP<0>")
	)
	(segment
		(start 443.923674 -312.91657)
		(end 444.472314 -312.91657)
		(width 0.20066)
		(layer "F.Cu")
		(net "M_G_CPU0_SA_DQS_DP<0>")
	)
	(segment
		(start 442.362336 -313.347862)
		(end 442.66485 -313.045348)
		(width 0.20066)
		(layer "F.Cu")
		(net "M_G_CPU0_SA_DQS_DP<0>")
	)
	(segment
		(start 439.875676 -313.341766)
		(end 442.032898 -313.341766)
		(width 0.1016)
		(layer "F.Cu")
		(net "M_G_CPU0_SA_DQS_DP<0>")
	)
	(segment
		(start 442.66485 -313.045348)
		(end 443.035436 -313.045348)
		(width 0.20066)
		(layer "F.Cu")
		(net "M_G_CPU0_SA_DQS_DP<0>")
	)
	(segment
		(start 439.710322 -313.341766)
		(end 439.849768 -313.341766)
		(width 0.20066)
		(layer "F.Cu")
		(net "M_G_CPU0_SA_DQS_DP<0>")
	)
	(segment
		(start 435.823614 -312.91657)
		(end 436.928514 -312.91657)
		(width 0.20066)
		(layer "F.Cu")
		(net "M_G_CPU0_SA_DQS_DP<0>")
	)
	(segment
		(start 439.459116 -313.09056)
		(end 439.710322 -313.341766)
		(width 0.20066)
		(layer "F.Cu")
		(net "M_G_CPU0_SA_DQS_DP<0>")
	)
	(segment
		(start 377.546362 -274.54479)
		(end 377.546616 -274.545044)
		(width 0.20066)
		(layer "F.Cu")
		(net "M_G_CPU0_SA_DQS_DP<0>")
	)
	(segment
		(start 437.758332 -312.676032)
		(end 438.358788 -312.676032)
		(width 0.20066)
		(layer "F.Cu")
		(net "M_G_CPU0_SA_DQS_DP<0>")
	)
	(segment
		(start 436.928514 -312.91657)
		(end 437.517794 -312.91657)
		(width 0.20066)
		(layer "F.Cu")
		(net "M_G_CPU0_SA_DQS_DP<0>")
	)
	(segment
		(start 437.517794 -312.91657)
		(end 437.758332 -312.676032)
		(width 0.20066)
		(layer "F.Cu")
		(net "M_G_CPU0_SA_DQS_DP<0>")
	)
	(segment
		(start 410.294074 -311.426606)
		(end 409.438602 -311.426606)
		(width 0.18288)
		(layer "In4.Cu")
		(net "M_G_CPU0_SA_DQS_DP<0>")
	)
	(segment
		(start 384.79095 -277.203154)
		(end 384.78206 -277.198074)
		(width 0.088646)
		(layer "In4.Cu")
		(net "M_G_CPU0_SA_DQS_DP<0>")
	)
	(segment
		(start 435.125114 -312.640726)
		(end 434.962554 -312.478166)
		(width 0.18288)
		(layer "In4.Cu")
		(net "M_G_CPU0_SA_DQS_DP<0>")
	)
	(segment
		(start 387.86308 -279.38349)
		(end 387.381496 -278.901906)
		(width 0.088646)
		(layer "In4.Cu")
		(net "M_G_CPU0_SA_DQS_DP<0>")
	)
	(segment
		(start 430.203356 -313.341512)
		(end 427.926754 -313.341512)
		(width 0.18288)
		(layer "In4.Cu")
		(net "M_G_CPU0_SA_DQS_DP<0>")
	)
	(segment
		(start 390.263888 -283.267404)
		(end 390.263634 -283.266896)
		(width 0.18288)
		(layer "In4.Cu")
		(net "M_G_CPU0_SA_DQS_DP<0>")
	)
	(segment
		(start 384.969512 -277.540974)
		(end 384.969512 -277.522432)
		(width 0.088646)
		(layer "In4.Cu")
		(net "M_G_CPU0_SA_DQS_DP<0>")
	)
	(segment
		(start 425.92752 -314.771278)
		(end 425.298362 -314.771278)
		(width 0.18288)
		(layer "In4.Cu")
		(net "M_G_CPU0_SA_DQS_DP<0>")
	)
	(segment
		(start 424.628564 -315.041788)
		(end 424.352466 -314.76569)
		(width 0.18288)
		(layer "In4.Cu")
		(net "M_G_CPU0_SA_DQS_DP<0>")
	)
	(segment
		(start 412.587948 -312.432446)
		(end 411.299914 -312.432446)
		(width 0.18288)
		(layer "In4.Cu")
		(net "M_G_CPU0_SA_DQS_DP<0>")
	)
	(segment
		(start 434.962554 -312.478166)
		(end 432.287934 -312.478166)
		(width 0.18288)
		(layer "In4.Cu")
		(net "M_G_CPU0_SA_DQS_DP<0>")
	)
	(segment
		(start 403.024086 -307.722524)
		(end 396.106142 -297.36923)
		(width 0.18288)
		(layer "In4.Cu")
		(net "M_G_CPU0_SA_DQS_DP<0>")
	)
	(segment
		(start 421.221916 -315.60389)
		(end 420.93388 -315.891926)
		(width 0.18288)
		(layer "In4.Cu")
		(net "M_G_CPU0_SA_DQS_DP<0>")
	)
	(segment
		(start 427.37024 -313.898026)
		(end 426.800772 -313.898026)
		(width 0.18288)
		(layer "In4.Cu")
		(net "M_G_CPU0_SA_DQS_DP<0>")
	)
	(segment
		(start 377.859544 -275.08073)
		(end 377.546616 -275.08073)
		(width 0.088646)
		(layer "In4.Cu")
		(net "M_G_CPU0_SA_DQS_DP<0>")
	)
	(segment
		(start 420.93388 -315.891926)
		(end 420.541196 -315.891926)
		(width 0.18288)
		(layer "In4.Cu")
		(net "M_G_CPU0_SA_DQS_DP<0>")
	)
	(segment
		(start 417.42741 -313.753246)
		(end 416.342068 -313.753246)
		(width 0.18288)
		(layer "In4.Cu")
		(net "M_G_CPU0_SA_DQS_DP<0>")
	)
	(segment
		(start 387.381496 -278.901906)
		(end 386.944108 -278.901906)
		(width 0.088646)
		(layer "In4.Cu")
		(net "M_G_CPU0_SA_DQS_DP<0>")
	)
	(segment
		(start 383.368296 -276.381718)
		(end 383.366518 -276.380702)
		(width 0.088646)
		(layer "In4.Cu")
		(net "M_G_CPU0_SA_DQS_DP<0>")
	)
	(segment
		(start 404.373334 -309.071772)
		(end 403.024086 -307.722524)
		(width 0.18288)
		(layer "In4.Cu")
		(net "M_G_CPU0_SA_DQS_DP<0>")
	)
	(segment
		(start 377.924568 -275.145754)
		(end 377.859544 -275.08073)
		(width 0.088646)
		(layer "In4.Cu")
		(net "M_G_CPU0_SA_DQS_DP<0>")
	)
	(segment
		(start 409.438602 -311.426606)
		(end 408.582622 -310.570626)
		(width 0.18288)
		(layer "In4.Cu")
		(net "M_G_CPU0_SA_DQS_DP<0>")
	)
	(segment
		(start 411.299914 -312.432446)
		(end 410.294074 -311.426606)
		(width 0.18288)
		(layer "In4.Cu")
		(net "M_G_CPU0_SA_DQS_DP<0>")
	)
	(segment
		(start 422.161208 -315.60389)
		(end 421.221916 -315.60389)
		(width 0.18288)
		(layer "In4.Cu")
		(net "M_G_CPU0_SA_DQS_DP<0>")
	)
	(segment
		(start 416.342068 -313.753246)
		(end 415.848546 -313.259724)
		(width 0.18288)
		(layer "In4.Cu")
		(net "M_G_CPU0_SA_DQS_DP<0>")
	)
	(segment
		(start 386.20065 -278.017224)
		(end 386.19176 -278.012144)
		(width 0.088646)
		(layer "In4.Cu")
		(net "M_G_CPU0_SA_DQS_DP<0>")
	)
	(segment
		(start 390.31291 -283.385768)
		(end 390.263888 -283.267404)
		(width 0.18288)
		(layer "In4.Cu")
		(net "M_G_CPU0_SA_DQS_DP<0>")
	)
	(segment
		(start 408.582622 -310.570626)
		(end 407.474166 -310.570626)
		(width 0.18288)
		(layer "In4.Cu")
		(net "M_G_CPU0_SA_DQS_DP<0>")
	)
	(segment
		(start 396.106142 -297.36923)
		(end 390.31291 -283.385768)
		(width 0.18288)
		(layer "In4.Cu")
		(net "M_G_CPU0_SA_DQS_DP<0>")
	)
	(segment
		(start 389.274304 -280.878788)
		(end 387.87959 -279.484836)
		(width 0.18288)
		(layer "In4.Cu")
		(net "M_G_CPU0_SA_DQS_DP<0>")
	)
	(segment
		(start 422.999408 -314.76569)
		(end 422.161208 -315.60389)
		(width 0.18288)
		(layer "In4.Cu")
		(net "M_G_CPU0_SA_DQS_DP<0>")
	)
	(segment
		(start 425.298362 -314.771278)
		(end 425.027852 -315.041788)
		(width 0.18288)
		(layer "In4.Cu")
		(net "M_G_CPU0_SA_DQS_DP<0>")
	)
	(segment
		(start 415.848546 -313.259724)
		(end 414.584642 -313.259724)
		(width 0.18288)
		(layer "In4.Cu")
		(net "M_G_CPU0_SA_DQS_DP<0>")
	)
	(segment
		(start 435.823614 -312.91657)
		(end 435.54777 -312.640726)
		(width 0.18288)
		(layer "In4.Cu")
		(net "M_G_CPU0_SA_DQS_DP<0>")
	)
	(segment
		(start 390.263634 -283.266896)
		(end 389.274304 -280.878788)
		(width 0.18288)
		(layer "In4.Cu")
		(net "M_G_CPU0_SA_DQS_DP<0>")
	)
	(segment
		(start 378.768864 -275.570442)
		(end 378.754132 -275.579078)
		(width 0.088646)
		(layer "In4.Cu")
		(net "M_G_CPU0_SA_DQS_DP<0>")
	)
	(segment
		(start 420.271448 -315.622178)
		(end 419.296342 -315.622178)
		(width 0.18288)
		(layer "In4.Cu")
		(net "M_G_CPU0_SA_DQS_DP<0>")
	)
	(segment
		(start 383.383028 -276.390354)
		(end 383.368296 -276.381718)
		(width 0.088646)
		(layer "In4.Cu")
		(net "M_G_CPU0_SA_DQS_DP<0>")
	)
	(segment
		(start 382.528064 -275.570442)
		(end 382.513332 -275.579078)
		(width 0.088646)
		(layer "In4.Cu")
		(net "M_G_CPU0_SA_DQS_DP<0>")
	)
	(segment
		(start 387.87959 -279.484836)
		(end 387.86308 -279.468326)
		(width 0.088646)
		(layer "In4.Cu")
		(net "M_G_CPU0_SA_DQS_DP<0>")
	)
	(segment
		(start 426.800772 -313.898026)
		(end 425.92752 -314.771278)
		(width 0.18288)
		(layer "In4.Cu")
		(net "M_G_CPU0_SA_DQS_DP<0>")
	)
	(segment
		(start 427.926754 -313.341512)
		(end 427.37024 -313.898026)
		(width 0.18288)
		(layer "In4.Cu")
		(net "M_G_CPU0_SA_DQS_DP<0>")
	)
	(segment
		(start 380.648464 -275.570442)
		(end 380.633732 -275.579078)
		(width 0.088646)
		(layer "In4.Cu")
		(net "M_G_CPU0_SA_DQS_DP<0>")
	)
	(segment
		(start 420.541196 -315.891926)
		(end 420.271448 -315.622178)
		(width 0.18288)
		(layer "In4.Cu")
		(net "M_G_CPU0_SA_DQS_DP<0>")
	)
	(segment
		(start 419.296342 -315.622178)
		(end 417.42741 -313.753246)
		(width 0.18288)
		(layer "In4.Cu")
		(net "M_G_CPU0_SA_DQS_DP<0>")
	)
	(segment
		(start 387.86308 -279.468326)
		(end 387.86308 -279.38349)
		(width 0.088646)
		(layer "In4.Cu")
		(net "M_G_CPU0_SA_DQS_DP<0>")
	)
	(segment
		(start 405.975312 -309.071772)
		(end 404.373334 -309.071772)
		(width 0.18288)
		(layer "In4.Cu")
		(net "M_G_CPU0_SA_DQS_DP<0>")
	)
	(segment
		(start 425.027852 -315.041788)
		(end 424.628564 -315.041788)
		(width 0.18288)
		(layer "In4.Cu")
		(net "M_G_CPU0_SA_DQS_DP<0>")
	)
	(segment
		(start 414.584642 -313.259724)
		(end 412.587948 -312.432446)
		(width 0.18288)
		(layer "In4.Cu")
		(net "M_G_CPU0_SA_DQS_DP<0>")
	)
	(segment
		(start 432.287934 -312.478166)
		(end 430.203356 -313.341512)
		(width 0.18288)
		(layer "In4.Cu")
		(net "M_G_CPU0_SA_DQS_DP<0>")
	)
	(segment
		(start 424.352466 -314.76569)
		(end 422.999408 -314.76569)
		(width 0.18288)
		(layer "In4.Cu")
		(net "M_G_CPU0_SA_DQS_DP<0>")
	)
	(segment
		(start 384.499612 -276.718522)
		(end 384.499612 -276.708616)
		(width 0.088646)
		(layer "In4.Cu")
		(net "M_G_CPU0_SA_DQS_DP<0>")
	)
	(segment
		(start 384.32105 -276.389338)
		(end 384.31216 -276.384258)
		(width 0.088646)
		(layer "In4.Cu")
		(net "M_G_CPU0_SA_DQS_DP<0>")
	)
	(segment
		(start 379.708664 -275.570442)
		(end 379.693932 -275.579078)
		(width 0.088646)
		(layer "In4.Cu")
		(net "M_G_CPU0_SA_DQS_DP<0>")
	)
	(segment
		(start 435.54777 -312.640726)
		(end 435.125114 -312.640726)
		(width 0.18288)
		(layer "In4.Cu")
		(net "M_G_CPU0_SA_DQS_DP<0>")
	)
	(segment
		(start 407.474166 -310.570626)
		(end 405.975312 -309.071772)
		(width 0.18288)
		(layer "In4.Cu")
		(net "M_G_CPU0_SA_DQS_DP<0>")
	)
	(segment
		(start 386.379212 -278.351996)
		(end 386.379212 -278.336502)
		(width 0.088646)
		(layer "In4.Cu")
		(net "M_G_CPU0_SA_DQS_DP<0>")
	)
	(arc
		(start 383.366518 -276.380702)
		(mid 383.163931 -276.174351)
		(end 383.089912 -275.8948)
		(width 0.088646)
		(layer "In4.Cu")
		(net "M_G_CPU0_SA_DQS_DP<0>")
	)
	(arc
		(start 378.754132 -275.579078)
		(mid 378.234157 -275.587082)
		(end 377.927362 -275.16709)
		(width 0.088646)
		(layer "In4.Cu")
		(net "M_G_CPU0_SA_DQS_DP<0>")
	)
	(arc
		(start 384.499612 -276.708616)
		(mid 384.451933 -276.525716)
		(end 384.32105 -276.389338)
		(width 0.088646)
		(layer "In4.Cu")
		(net "M_G_CPU0_SA_DQS_DP<0>")
	)
	(arc
		(start 381.588264 -275.570442)
		(mid 381.305562 -275.646184)
		(end 381.02286 -275.570442)
		(width 0.088646)
		(layer "In4.Cu")
		(net "M_G_CPU0_SA_DQS_DP<0>")
	)
	(arc
		(start 379.693932 -275.579078)
		(mid 379.417491 -275.646244)
		(end 379.14326 -275.570442)
		(width 0.088646)
		(layer "In4.Cu")
		(net "M_G_CPU0_SA_DQS_DP<0>")
	)
	(arc
		(start 381.02286 -275.570442)
		(mid 380.835662 -275.520299)
		(end 380.648464 -275.570442)
		(width 0.088646)
		(layer "In4.Cu")
		(net "M_G_CPU0_SA_DQS_DP<0>")
	)
	(arc
		(start 384.78206 -277.198074)
		(mid 384.577725 -276.995469)
		(end 384.499612 -276.718522)
		(width 0.088646)
		(layer "In4.Cu")
		(net "M_G_CPU0_SA_DQS_DP<0>")
	)
	(arc
		(start 385.25196 -278.012144)
		(mid 385.049674 -277.813163)
		(end 384.969512 -277.540974)
		(width 0.088646)
		(layer "In4.Cu")
		(net "M_G_CPU0_SA_DQS_DP<0>")
	)
	(arc
		(start 381.96266 -275.570442)
		(mid 381.775462 -275.520299)
		(end 381.588264 -275.570442)
		(width 0.088646)
		(layer "In4.Cu")
		(net "M_G_CPU0_SA_DQS_DP<0>")
	)
	(arc
		(start 384.969512 -277.522432)
		(mid 384.921833 -277.339532)
		(end 384.79095 -277.203154)
		(width 0.088646)
		(layer "In4.Cu")
		(net "M_G_CPU0_SA_DQS_DP<0>")
	)
	(arc
		(start 383.937764 -276.384258)
		(mid 383.661205 -276.460001)
		(end 383.383028 -276.390354)
		(width 0.088646)
		(layer "In4.Cu")
		(net "M_G_CPU0_SA_DQS_DP<0>")
	)
	(arc
		(start 382.513332 -275.579078)
		(mid 382.236891 -275.646244)
		(end 381.96266 -275.570442)
		(width 0.088646)
		(layer "In4.Cu")
		(net "M_G_CPU0_SA_DQS_DP<0>")
	)
	(arc
		(start 377.927362 -275.16709)
		(mid 377.925864 -275.156435)
		(end 377.924568 -275.145754)
		(width 0.088646)
		(layer "In4.Cu")
		(net "M_G_CPU0_SA_DQS_DP<0>")
	)
	(arc
		(start 384.31216 -276.384258)
		(mid 384.124962 -276.334115)
		(end 383.937764 -276.384258)
		(width 0.088646)
		(layer "In4.Cu")
		(net "M_G_CPU0_SA_DQS_DP<0>")
	)
	(arc
		(start 386.19176 -278.012144)
		(mid 386.004562 -277.962001)
		(end 385.817364 -278.012144)
		(width 0.088646)
		(layer "In4.Cu")
		(net "M_G_CPU0_SA_DQS_DP<0>")
	)
	(arc
		(start 379.14326 -275.570442)
		(mid 378.956062 -275.520299)
		(end 378.768864 -275.570442)
		(width 0.088646)
		(layer "In4.Cu")
		(net "M_G_CPU0_SA_DQS_DP<0>")
	)
	(arc
		(start 386.944108 -278.901906)
		(mid 386.549986 -278.741656)
		(end 386.379212 -278.351996)
		(width 0.088646)
		(layer "In4.Cu")
		(net "M_G_CPU0_SA_DQS_DP<0>")
	)
	(arc
		(start 385.817364 -278.012144)
		(mid 385.534662 -278.087886)
		(end 385.25196 -278.012144)
		(width 0.088646)
		(layer "In4.Cu")
		(net "M_G_CPU0_SA_DQS_DP<0>")
	)
	(arc
		(start 380.08306 -275.570442)
		(mid 379.895862 -275.520299)
		(end 379.708664 -275.570442)
		(width 0.088646)
		(layer "In4.Cu")
		(net "M_G_CPU0_SA_DQS_DP<0>")
	)
	(arc
		(start 386.379212 -278.336502)
		(mid 386.331533 -278.153602)
		(end 386.20065 -278.017224)
		(width 0.088646)
		(layer "In4.Cu")
		(net "M_G_CPU0_SA_DQS_DP<0>")
	)
	(arc
		(start 380.633732 -275.579078)
		(mid 380.357291 -275.646244)
		(end 380.08306 -275.570442)
		(width 0.088646)
		(layer "In4.Cu")
		(net "M_G_CPU0_SA_DQS_DP<0>")
	)
	(arc
		(start 383.089912 -275.8948)
		(mid 382.902613 -275.570359)
		(end 382.528064 -275.570442)
		(width 0.088646)
		(layer "In4.Cu")
		(net "M_G_CPU0_SA_DQS_DP<0>")
	)
	(segment
		(start 441.559188 -274.66671)
		(end 441.83046 -274.395438)
		(width 0.20066)
		(layer "F.Cu")
		(net "M_G_CPU0_SA_DQS_DN<9>")
	)
	(segment
		(start 442.867288 -273.970496)
		(end 443.13856 -274.241768)
		(width 0.20066)
		(layer "F.Cu")
		(net "M_G_CPU0_SA_DQS_DN<9>")
	)
	(segment
		(start 445.690752 -274.241768)
		(end 445.812418 -274.241768)
		(width 0.20066)
		(layer "F.Cu")
		(net "M_G_CPU0_SA_DQS_DN<9>")
	)
	(segment
		(start 443.283086 -274.241768)
		(end 443.461648 -274.241768)
		(width 0.101854)
		(layer "F.Cu")
		(net "M_G_CPU0_SA_DQS_DN<9>")
	)
	(segment
		(start 441.028582 -274.66671)
		(end 441.559188 -274.66671)
		(width 0.20066)
		(layer "F.Cu")
		(net "M_G_CPU0_SA_DQS_DN<9>")
	)
	(segment
		(start 443.13856 -274.241768)
		(end 443.283086 -274.241768)
		(width 0.20066)
		(layer "F.Cu")
		(net "M_G_CPU0_SA_DQS_DN<9>")
	)
	(segment
		(start 446.577212 -273.96694)
		(end 447.022728 -274.412456)
		(width 0.20066)
		(layer "F.Cu")
		(net "M_G_CPU0_SA_DQS_DN<9>")
	)
	(segment
		(start 441.83046 -274.395438)
		(end 442.313822 -274.395438)
		(width 0.20066)
		(layer "F.Cu")
		(net "M_G_CPU0_SA_DQS_DN<9>")
	)
	(segment
		(start 377.076716 -262.87222)
		(end 377.076462 -262.872474)
		(width 0.20066)
		(layer "F.Cu")
		(net "M_G_CPU0_SA_DQS_DN<9>")
	)
	(segment
		(start 445.812418 -274.241768)
		(end 446.087246 -273.96694)
		(width 0.20066)
		(layer "F.Cu")
		(net "M_G_CPU0_SA_DQS_DN<9>")
	)
	(segment
		(start 445.471804 -274.241768)
		(end 445.690752 -274.241768)
		(width 0.101854)
		(layer "F.Cu")
		(net "M_G_CPU0_SA_DQS_DN<9>")
	)
	(segment
		(start 443.461648 -274.241768)
		(end 445.471804 -274.241768)
		(width 0.1016)
		(layer "F.Cu")
		(net "M_G_CPU0_SA_DQS_DN<9>")
	)
	(segment
		(start 447.814446 -274.412456)
		(end 448.0687 -274.66671)
		(width 0.20066)
		(layer "F.Cu")
		(net "M_G_CPU0_SA_DQS_DN<9>")
	)
	(segment
		(start 442.313822 -274.395438)
		(end 442.738764 -273.970496)
		(width 0.20066)
		(layer "F.Cu")
		(net "M_G_CPU0_SA_DQS_DN<9>")
	)
	(segment
		(start 439.923682 -274.66671)
		(end 441.028582 -274.66671)
		(width 0.20066)
		(layer "F.Cu")
		(net "M_G_CPU0_SA_DQS_DN<9>")
	)
	(segment
		(start 446.087246 -273.96694)
		(end 446.577212 -273.96694)
		(width 0.20066)
		(layer "F.Cu")
		(net "M_G_CPU0_SA_DQS_DN<9>")
	)
	(segment
		(start 442.738764 -273.970496)
		(end 442.867288 -273.970496)
		(width 0.20066)
		(layer "F.Cu")
		(net "M_G_CPU0_SA_DQS_DN<9>")
	)
	(segment
		(start 448.0687 -274.66671)
		(end 448.572382 -274.66671)
		(width 0.20066)
		(layer "F.Cu")
		(net "M_G_CPU0_SA_DQS_DN<9>")
	)
	(segment
		(start 447.022728 -274.412456)
		(end 447.814446 -274.412456)
		(width 0.20066)
		(layer "F.Cu")
		(net "M_G_CPU0_SA_DQS_DN<9>")
	)
	(segment
		(start 377.076716 -262.336534)
		(end 377.076716 -262.87222)
		(width 0.20066)
		(layer "F.Cu")
		(net "M_G_CPU0_SA_DQS_DN<9>")
	)
	(segment
		(start 410.16555 -263.90854)
		(end 409.61945 -263.90854)
		(width 0.18288)
		(layer "In6.Cu")
		(net "M_G_CPU0_SA_DQS_DN<9>")
	)
	(segment
		(start 404.127716 -262.292592)
		(end 393.095988 -262.292592)
		(width 0.18288)
		(layer "In6.Cu")
		(net "M_G_CPU0_SA_DQS_DN<9>")
	)
	(segment
		(start 438.243472 -273.394932)
		(end 437.949086 -273.394932)
		(width 0.18288)
		(layer "In6.Cu")
		(net "M_G_CPU0_SA_DQS_DN<9>")
	)
	(segment
		(start 414.436306 -263.303258)
		(end 413.890206 -263.303258)
		(width 0.18288)
		(layer "In6.Cu")
		(net "M_G_CPU0_SA_DQS_DN<9>")
	)
	(segment
		(start 388.333234 -261.778242)
		(end 388.238492 -261.6835)
		(width 0.088646)
		(layer "In6.Cu")
		(net "M_G_CPU0_SA_DQS_DN<9>")
	)
	(segment
		(start 421.843708 -263.750298)
		(end 421.264334 -263.750298)
		(width 0.18288)
		(layer "In6.Cu")
		(net "M_G_CPU0_SA_DQS_DN<9>")
	)
	(segment
		(start 439.923682 -274.66671)
		(end 439.664094 -274.407122)
		(width 0.18288)
		(layer "In6.Cu")
		(net "M_G_CPU0_SA_DQS_DN<9>")
	)
	(segment
		(start 429.639984 -264.893806)
		(end 429.093884 -264.893806)
		(width 0.18288)
		(layer "In6.Cu")
		(net "M_G_CPU0_SA_DQS_DN<9>")
	)
	(segment
		(start 433.896008 -273.647408)
		(end 433.098702 -272.85061)
		(width 0.18288)
		(layer "In6.Cu")
		(net "M_G_CPU0_SA_DQS_DN<9>")
	)
	(segment
		(start 431.58029 -266.947142)
		(end 431.45583 -266.822682)
		(width 0.18288)
		(layer "In6.Cu")
		(net "M_G_CPU0_SA_DQS_DN<9>")
	)
	(segment
		(start 406.435814 -263.318244)
		(end 406.311354 -263.193784)
		(width 0.18288)
		(layer "In6.Cu")
		(net "M_G_CPU0_SA_DQS_DN<9>")
	)
	(segment
		(start 429.764444 -264.769346)
		(end 429.639984 -264.893806)
		(width 0.18288)
		(layer "In6.Cu")
		(net "M_G_CPU0_SA_DQS_DN<9>")
	)
	(segment
		(start 429.093884 -264.893806)
		(end 428.969424 -264.769346)
		(width 0.18288)
		(layer "In6.Cu")
		(net "M_G_CPU0_SA_DQS_DN<9>")
	)
	(segment
		(start 435.292754 -274.003516)
		(end 434.752496 -274.003516)
		(width 0.18288)
		(layer "In6.Cu")
		(net "M_G_CPU0_SA_DQS_DN<9>")
	)
	(segment
		(start 387.696964 -261.7343)
		(end 387.68274 -261.742428)
		(width 0.088646)
		(layer "In6.Cu")
		(net "M_G_CPU0_SA_DQS_DN<9>")
	)
	(segment
		(start 431.64633 -271.65427)
		(end 431.58029 -271.54378)
		(width 0.18288)
		(layer "In6.Cu")
		(net "M_G_CPU0_SA_DQS_DN<9>")
	)
	(segment
		(start 406.981914 -263.318244)
		(end 406.435814 -263.318244)
		(width 0.18288)
		(layer "In6.Cu")
		(net "M_G_CPU0_SA_DQS_DN<9>")
	)
	(segment
		(start 418.734748 -263.793732)
		(end 418.610288 -263.918192)
		(width 0.18288)
		(layer "In6.Cu")
		(net "M_G_CPU0_SA_DQS_DN<9>")
	)
	(segment
		(start 410.29001 -263.78408)
		(end 410.16555 -263.90854)
		(width 0.18288)
		(layer "In6.Cu")
		(net "M_G_CPU0_SA_DQS_DN<9>")
	)
	(segment
		(start 431.58029 -267.493242)
		(end 431.58029 -266.947142)
		(width 0.18288)
		(layer "In6.Cu")
		(net "M_G_CPU0_SA_DQS_DN<9>")
	)
	(segment
		(start 406.311354 -263.193784)
		(end 405.028908 -263.193784)
		(width 0.18288)
		(layer "In6.Cu")
		(net "M_G_CPU0_SA_DQS_DN<9>")
	)
	(segment
		(start 425.105576 -264.890758)
		(end 424.633644 -264.890758)
		(width 0.18288)
		(layer "In6.Cu")
		(net "M_G_CPU0_SA_DQS_DN<9>")
	)
	(segment
		(start 388.75716 -261.778242)
		(end 388.333234 -261.778242)
		(width 0.088646)
		(layer "In6.Cu")
		(net "M_G_CPU0_SA_DQS_DN<9>")
	)
	(segment
		(start 436.040784 -274.240752)
		(end 435.52999 -274.240752)
		(width 0.18288)
		(layer "In6.Cu")
		(net "M_G_CPU0_SA_DQS_DN<9>")
	)
	(segment
		(start 436.30469 -273.976846)
		(end 436.040784 -274.240752)
		(width 0.18288)
		(layer "In6.Cu")
		(net "M_G_CPU0_SA_DQS_DN<9>")
	)
	(segment
		(start 431.45583 -266.822682)
		(end 431.45583 -266.276582)
		(width 0.18288)
		(layer "In6.Cu")
		(net "M_G_CPU0_SA_DQS_DN<9>")
	)
	(segment
		(start 411.50667 -263.90854)
		(end 410.96057 -263.90854)
		(width 0.18288)
		(layer "In6.Cu")
		(net "M_G_CPU0_SA_DQS_DN<9>")
	)
	(segment
		(start 412.17723 -263.78408)
		(end 411.63113 -263.78408)
		(width 0.18288)
		(layer "In6.Cu")
		(net "M_G_CPU0_SA_DQS_DN<9>")
	)
	(segment
		(start 409.49499 -263.78408)
		(end 408.8384 -263.78408)
		(width 0.18288)
		(layer "In6.Cu")
		(net "M_G_CPU0_SA_DQS_DN<9>")
	)
	(segment
		(start 377.829064 -262.548116)
		(end 377.828048 -262.548624)
		(width 0.088646)
		(layer "In6.Cu")
		(net "M_G_CPU0_SA_DQS_DN<9>")
	)
	(segment
		(start 439.255662 -274.407122)
		(end 438.243472 -273.394932)
		(width 0.18288)
		(layer "In6.Cu")
		(net "M_G_CPU0_SA_DQS_DN<9>")
	)
	(segment
		(start 377.71324 -262.61568)
		(end 377.4948 -262.666734)
		(width 0.088646)
		(layer "In6.Cu")
		(net "M_G_CPU0_SA_DQS_DN<9>")
	)
	(segment
		(start 420.235634 -263.793732)
		(end 418.734748 -263.793732)
		(width 0.18288)
		(layer "In6.Cu")
		(net "M_G_CPU0_SA_DQS_DN<9>")
	)
	(segment
		(start 424.626024 -264.883138)
		(end 424.60164 -264.883138)
		(width 0.18288)
		(layer "In6.Cu")
		(net "M_G_CPU0_SA_DQS_DN<9>")
	)
	(segment
		(start 377.4948 -262.666734)
		(end 377.133104 -262.666734)
		(width 0.088646)
		(layer "In6.Cu")
		(net "M_G_CPU0_SA_DQS_DN<9>")
	)
	(segment
		(start 409.61945 -263.90854)
		(end 409.49499 -263.78408)
		(width 0.18288)
		(layer "In6.Cu")
		(net "M_G_CPU0_SA_DQS_DN<9>")
	)
	(segment
		(start 431.58029 -266.152122)
		(end 431.58029 -265.753342)
		(width 0.18288)
		(layer "In6.Cu")
		(net "M_G_CPU0_SA_DQS_DN<9>")
	)
	(segment
		(start 381.588264 -262.548116)
		(end 381.573532 -262.556752)
		(width 0.088646)
		(layer "In6.Cu")
		(net "M_G_CPU0_SA_DQS_DN<9>")
	)
	(segment
		(start 431.45583 -268.958822)
		(end 431.58029 -268.834362)
		(width 0.18288)
		(layer "In6.Cu")
		(net "M_G_CPU0_SA_DQS_DN<9>")
	)
	(segment
		(start 428.969424 -264.769346)
		(end 427.816264 -264.769346)
		(width 0.18288)
		(layer "In6.Cu")
		(net "M_G_CPU0_SA_DQS_DN<9>")
	)
	(segment
		(start 421.264334 -263.750298)
		(end 420.973758 -264.040874)
		(width 0.18288)
		(layer "In6.Cu")
		(net "M_G_CPU0_SA_DQS_DN<9>")
	)
	(segment
		(start 413.765746 -263.178798)
		(end 412.782512 -263.178798)
		(width 0.18288)
		(layer "In6.Cu")
		(net "M_G_CPU0_SA_DQS_DN<9>")
	)
	(segment
		(start 436.54472 -273.976846)
		(end 436.30469 -273.976846)
		(width 0.18288)
		(layer "In6.Cu")
		(net "M_G_CPU0_SA_DQS_DN<9>")
	)
	(segment
		(start 425.350432 -264.645902)
		(end 425.105576 -264.890758)
		(width 0.18288)
		(layer "In6.Cu")
		(net "M_G_CPU0_SA_DQS_DN<9>")
	)
	(segment
		(start 393.095988 -262.292592)
		(end 390.811766 -261.838186)
		(width 0.18288)
		(layer "In6.Cu")
		(net "M_G_CPU0_SA_DQS_DN<9>")
	)
	(segment
		(start 385.732274 -262.554212)
		(end 385.72186 -262.548116)
		(width 0.088646)
		(layer "In6.Cu")
		(net "M_G_CPU0_SA_DQS_DN<9>")
	)
	(segment
		(start 431.58029 -268.834362)
		(end 431.58029 -268.288262)
		(width 0.18288)
		(layer "In6.Cu")
		(net "M_G_CPU0_SA_DQS_DN<9>")
	)
	(segment
		(start 420.973758 -264.040874)
		(end 420.482776 -264.040874)
		(width 0.18288)
		(layer "In6.Cu")
		(net "M_G_CPU0_SA_DQS_DN<9>")
	)
	(segment
		(start 387.509512 -262.058404)
		(end 387.509512 -262.074152)
		(width 0.088646)
		(layer "In6.Cu")
		(net "M_G_CPU0_SA_DQS_DN<9>")
	)
	(segment
		(start 378.203714 -262.54837)
		(end 378.20346 -262.548116)
		(width 0.088646)
		(layer "In6.Cu")
		(net "M_G_CPU0_SA_DQS_DN<9>")
	)
	(segment
		(start 427.816264 -264.769346)
		(end 427.313852 -265.271758)
		(width 0.18288)
		(layer "In6.Cu")
		(net "M_G_CPU0_SA_DQS_DN<9>")
	)
	(segment
		(start 431.45583 -269.504922)
		(end 431.45583 -268.958822)
		(width 0.18288)
		(layer "In6.Cu")
		(net "M_G_CPU0_SA_DQS_DN<9>")
	)
	(segment
		(start 431.45583 -268.163802)
		(end 431.45583 -267.617702)
		(width 0.18288)
		(layer "In6.Cu")
		(net "M_G_CPU0_SA_DQS_DN<9>")
	)
	(segment
		(start 405.028908 -263.193784)
		(end 404.127716 -262.292592)
		(width 0.18288)
		(layer "In6.Cu")
		(net "M_G_CPU0_SA_DQS_DN<9>")
	)
	(segment
		(start 417.939728 -263.793732)
		(end 416.319462 -263.793732)
		(width 0.18288)
		(layer "In6.Cu")
		(net "M_G_CPU0_SA_DQS_DN<9>")
	)
	(segment
		(start 377.133104 -262.666734)
		(end 377.076462 -262.723376)
		(width 0.088646)
		(layer "In6.Cu")
		(net "M_G_CPU0_SA_DQS_DN<9>")
	)
	(segment
		(start 426.71238 -265.271758)
		(end 426.086524 -264.645902)
		(width 0.18288)
		(layer "In6.Cu")
		(net "M_G_CPU0_SA_DQS_DN<9>")
	)
	(segment
		(start 418.610288 -263.918192)
		(end 418.064188 -263.918192)
		(width 0.18288)
		(layer "In6.Cu")
		(net "M_G_CPU0_SA_DQS_DN<9>")
	)
	(segment
		(start 407.106374 -263.193784)
		(end 406.981914 -263.318244)
		(width 0.18288)
		(layer "In6.Cu")
		(net "M_G_CPU0_SA_DQS_DN<9>")
	)
	(segment
		(start 380.093728 -262.554212)
		(end 380.083314 -262.548116)
		(width 0.088646)
		(layer "In6.Cu")
		(net "M_G_CPU0_SA_DQS_DN<9>")
	)
	(segment
		(start 422.703244 -264.609834)
		(end 421.843708 -263.750298)
		(width 0.18288)
		(layer "In6.Cu")
		(net "M_G_CPU0_SA_DQS_DN<9>")
	)
	(segment
		(start 386.676646 -262.556752)
		(end 386.661914 -262.548116)
		(width 0.088646)
		(layer "In6.Cu")
		(net "M_G_CPU0_SA_DQS_DN<9>")
	)
	(segment
		(start 439.664094 -274.407122)
		(end 439.255662 -274.407122)
		(width 0.18288)
		(layer "In6.Cu")
		(net "M_G_CPU0_SA_DQS_DN<9>")
	)
	(segment
		(start 378.768864 -262.548116)
		(end 378.754132 -262.556752)
		(width 0.088646)
		(layer "In6.Cu")
		(net "M_G_CPU0_SA_DQS_DN<9>")
	)
	(segment
		(start 434.752496 -274.003516)
		(end 433.896008 -273.647408)
		(width 0.18288)
		(layer "In6.Cu")
		(net "M_G_CPU0_SA_DQS_DN<9>")
	)
	(segment
		(start 427.313852 -265.271758)
		(end 426.71238 -265.271758)
		(width 0.18288)
		(layer "In6.Cu")
		(net "M_G_CPU0_SA_DQS_DN<9>")
	)
	(segment
		(start 377.828048 -262.548624)
		(end 377.71324 -262.61568)
		(width 0.088646)
		(layer "In6.Cu")
		(net "M_G_CPU0_SA_DQS_DN<9>")
	)
	(segment
		(start 430.596294 -264.769346)
		(end 429.764444 -264.769346)
		(width 0.18288)
		(layer "In6.Cu")
		(net "M_G_CPU0_SA_DQS_DN<9>")
	)
	(segment
		(start 388.840472 -261.838186)
		(end 388.817104 -261.838186)
		(width 0.088646)
		(layer "In6.Cu")
		(net "M_G_CPU0_SA_DQS_DN<9>")
	)
	(segment
		(start 408.8384 -263.78408)
		(end 408.248104 -263.193784)
		(width 0.18288)
		(layer "In6.Cu")
		(net "M_G_CPU0_SA_DQS_DN<9>")
	)
	(segment
		(start 413.890206 -263.303258)
		(end 413.765746 -263.178798)
		(width 0.18288)
		(layer "In6.Cu")
		(net "M_G_CPU0_SA_DQS_DN<9>")
	)
	(segment
		(start 435.52999 -274.240752)
		(end 435.292754 -274.003516)
		(width 0.18288)
		(layer "In6.Cu")
		(net "M_G_CPU0_SA_DQS_DN<9>")
	)
	(segment
		(start 412.782512 -263.178798)
		(end 412.17723 -263.78408)
		(width 0.18288)
		(layer "In6.Cu")
		(net "M_G_CPU0_SA_DQS_DN<9>")
	)
	(segment
		(start 418.064188 -263.918192)
		(end 417.939728 -263.793732)
		(width 0.18288)
		(layer "In6.Cu")
		(net "M_G_CPU0_SA_DQS_DN<9>")
	)
	(segment
		(start 431.58029 -268.288262)
		(end 431.45583 -268.163802)
		(width 0.18288)
		(layer "In6.Cu")
		(net "M_G_CPU0_SA_DQS_DN<9>")
	)
	(segment
		(start 431.58029 -269.629382)
		(end 431.45583 -269.504922)
		(width 0.18288)
		(layer "In6.Cu")
		(net "M_G_CPU0_SA_DQS_DN<9>")
	)
	(segment
		(start 420.482776 -264.040874)
		(end 420.235634 -263.793732)
		(width 0.18288)
		(layer "In6.Cu")
		(net "M_G_CPU0_SA_DQS_DN<9>")
	)
	(segment
		(start 416.319462 -263.793732)
		(end 415.704528 -263.178798)
		(width 0.18288)
		(layer "In6.Cu")
		(net "M_G_CPU0_SA_DQS_DN<9>")
	)
	(segment
		(start 424.633644 -264.890758)
		(end 424.626024 -264.883138)
		(width 0.18288)
		(layer "In6.Cu")
		(net "M_G_CPU0_SA_DQS_DN<9>")
	)
	(segment
		(start 431.45583 -266.276582)
		(end 431.58029 -266.152122)
		(width 0.18288)
		(layer "In6.Cu")
		(net "M_G_CPU0_SA_DQS_DN<9>")
	)
	(segment
		(start 432.015138 -272.269966)
		(end 431.64633 -271.65427)
		(width 0.18288)
		(layer "In6.Cu")
		(net "M_G_CPU0_SA_DQS_DN<9>")
	)
	(segment
		(start 424.60164 -264.883138)
		(end 424.328336 -264.609834)
		(width 0.18288)
		(layer "In6.Cu")
		(net "M_G_CPU0_SA_DQS_DN<9>")
	)
	(segment
		(start 377.076462 -262.723376)
		(end 377.076462 -262.872474)
		(width 0.088646)
		(layer "In6.Cu")
		(net "M_G_CPU0_SA_DQS_DN<9>")
	)
	(segment
		(start 411.63113 -263.78408)
		(end 411.50667 -263.90854)
		(width 0.18288)
		(layer "In6.Cu")
		(net "M_G_CPU0_SA_DQS_DN<9>")
	)
	(segment
		(start 408.248104 -263.193784)
		(end 407.106374 -263.193784)
		(width 0.18288)
		(layer "In6.Cu")
		(net "M_G_CPU0_SA_DQS_DN<9>")
	)
	(segment
		(start 433.098702 -272.85061)
		(end 432.015138 -272.269966)
		(width 0.18288)
		(layer "In6.Cu")
		(net "M_G_CPU0_SA_DQS_DN<9>")
	)
	(segment
		(start 388.817104 -261.838186)
		(end 388.75716 -261.778242)
		(width 0.088646)
		(layer "In6.Cu")
		(net "M_G_CPU0_SA_DQS_DN<9>")
	)
	(segment
		(start 424.328336 -264.609834)
		(end 422.703244 -264.609834)
		(width 0.18288)
		(layer "In6.Cu")
		(net "M_G_CPU0_SA_DQS_DN<9>")
	)
	(segment
		(start 379.708918 -262.548116)
		(end 379.698504 -262.554212)
		(width 0.088646)
		(layer "In6.Cu")
		(net "M_G_CPU0_SA_DQS_DN<9>")
	)
	(segment
		(start 414.560766 -263.178798)
		(end 414.436306 -263.303258)
		(width 0.18288)
		(layer "In6.Cu")
		(net "M_G_CPU0_SA_DQS_DN<9>")
	)
	(segment
		(start 437.949086 -273.394932)
		(end 436.54472 -273.976846)
		(width 0.18288)
		(layer "In6.Cu")
		(net "M_G_CPU0_SA_DQS_DN<9>")
	)
	(segment
		(start 431.58029 -271.54378)
		(end 431.58029 -269.629382)
		(width 0.18288)
		(layer "In6.Cu")
		(net "M_G_CPU0_SA_DQS_DN<9>")
	)
	(segment
		(start 415.704528 -263.178798)
		(end 414.560766 -263.178798)
		(width 0.18288)
		(layer "In6.Cu")
		(net "M_G_CPU0_SA_DQS_DN<9>")
	)
	(segment
		(start 410.83611 -263.78408)
		(end 410.29001 -263.78408)
		(width 0.18288)
		(layer "In6.Cu")
		(net "M_G_CPU0_SA_DQS_DN<9>")
	)
	(segment
		(start 382.528064 -262.548116)
		(end 382.513332 -262.556752)
		(width 0.088646)
		(layer "In6.Cu")
		(net "M_G_CPU0_SA_DQS_DN<9>")
	)
	(segment
		(start 426.086524 -264.645902)
		(end 425.350432 -264.645902)
		(width 0.18288)
		(layer "In6.Cu")
		(net "M_G_CPU0_SA_DQS_DN<9>")
	)
	(segment
		(start 431.58029 -265.753342)
		(end 430.596294 -264.769346)
		(width 0.18288)
		(layer "In6.Cu")
		(net "M_G_CPU0_SA_DQS_DN<9>")
	)
	(segment
		(start 410.96057 -263.90854)
		(end 410.83611 -263.78408)
		(width 0.18288)
		(layer "In6.Cu")
		(net "M_G_CPU0_SA_DQS_DN<9>")
	)
	(segment
		(start 388.238492 -261.6835)
		(end 387.884162 -261.6835)
		(width 0.088646)
		(layer "In6.Cu")
		(net "M_G_CPU0_SA_DQS_DN<9>")
	)
	(segment
		(start 390.811766 -261.838186)
		(end 388.840472 -261.838186)
		(width 0.18288)
		(layer "In6.Cu")
		(net "M_G_CPU0_SA_DQS_DN<9>")
	)
	(segment
		(start 431.45583 -267.617702)
		(end 431.58029 -267.493242)
		(width 0.18288)
		(layer "In6.Cu")
		(net "M_G_CPU0_SA_DQS_DN<9>")
	)
	(arc
		(start 385.347464 -262.548116)
		(mid 385.064762 -262.623892)
		(end 384.78206 -262.548116)
		(width 0.088646)
		(layer "In6.Cu")
		(net "M_G_CPU0_SA_DQS_DN<9>")
	)
	(arc
		(start 385.72186 -262.548116)
		(mid 385.534662 -262.497973)
		(end 385.347464 -262.548116)
		(width 0.088646)
		(layer "In6.Cu")
		(net "M_G_CPU0_SA_DQS_DN<9>")
	)
	(arc
		(start 387.884162 -261.6835)
		(mid 387.787228 -261.696598)
		(end 387.696964 -261.7343)
		(width 0.088646)
		(layer "In6.Cu")
		(net "M_G_CPU0_SA_DQS_DN<9>")
	)
	(arc
		(start 382.513332 -262.556752)
		(mid 382.236857 -262.624072)
		(end 381.96266 -262.548116)
		(width 0.088646)
		(layer "In6.Cu")
		(net "M_G_CPU0_SA_DQS_DN<9>")
	)
	(arc
		(start 386.287518 -262.548116)
		(mid 386.010705 -262.623986)
		(end 385.732274 -262.554212)
		(width 0.088646)
		(layer "In6.Cu")
		(net "M_G_CPU0_SA_DQS_DN<9>")
	)
	(arc
		(start 387.68274 -261.742428)
		(mid 387.555697 -261.878244)
		(end 387.509512 -262.058404)
		(width 0.088646)
		(layer "In6.Cu")
		(net "M_G_CPU0_SA_DQS_DN<9>")
	)
	(arc
		(start 381.573532 -262.556752)
		(mid 381.297057 -262.624072)
		(end 381.02286 -262.548116)
		(width 0.088646)
		(layer "In6.Cu")
		(net "M_G_CPU0_SA_DQS_DN<9>")
	)
	(arc
		(start 381.02286 -262.548116)
		(mid 380.835662 -262.497973)
		(end 380.648464 -262.548116)
		(width 0.088646)
		(layer "In6.Cu")
		(net "M_G_CPU0_SA_DQS_DN<9>")
	)
	(arc
		(start 379.14326 -262.548116)
		(mid 378.956062 -262.497973)
		(end 378.768864 -262.548116)
		(width 0.088646)
		(layer "In6.Cu")
		(net "M_G_CPU0_SA_DQS_DN<9>")
	)
	(arc
		(start 380.648464 -262.548116)
		(mid 380.371905 -262.623859)
		(end 380.093728 -262.554212)
		(width 0.088646)
		(layer "In6.Cu")
		(net "M_G_CPU0_SA_DQS_DN<9>")
	)
	(arc
		(start 378.20346 -262.548116)
		(mid 378.016262 -262.497973)
		(end 377.829064 -262.548116)
		(width 0.088646)
		(layer "In6.Cu")
		(net "M_G_CPU0_SA_DQS_DN<9>")
	)
	(arc
		(start 380.083314 -262.548116)
		(mid 379.896116 -262.497973)
		(end 379.708918 -262.548116)
		(width 0.088646)
		(layer "In6.Cu")
		(net "M_G_CPU0_SA_DQS_DN<9>")
	)
	(arc
		(start 383.467864 -262.548116)
		(mid 383.185162 -262.623892)
		(end 382.90246 -262.548116)
		(width 0.088646)
		(layer "In6.Cu")
		(net "M_G_CPU0_SA_DQS_DN<9>")
	)
	(arc
		(start 381.96266 -262.548116)
		(mid 381.775462 -262.497973)
		(end 381.588264 -262.548116)
		(width 0.088646)
		(layer "In6.Cu")
		(net "M_G_CPU0_SA_DQS_DN<9>")
	)
	(arc
		(start 378.754132 -262.556752)
		(mid 378.47783 -262.624074)
		(end 378.203714 -262.54837)
		(width 0.088646)
		(layer "In6.Cu")
		(net "M_G_CPU0_SA_DQS_DN<9>")
	)
	(arc
		(start 384.78206 -262.548116)
		(mid 384.594862 -262.497973)
		(end 384.407664 -262.548116)
		(width 0.088646)
		(layer "In6.Cu")
		(net "M_G_CPU0_SA_DQS_DN<9>")
	)
	(arc
		(start 382.90246 -262.548116)
		(mid 382.715262 -262.497973)
		(end 382.528064 -262.548116)
		(width 0.088646)
		(layer "In6.Cu")
		(net "M_G_CPU0_SA_DQS_DN<9>")
	)
	(arc
		(start 379.698504 -262.554212)
		(mid 379.420072 -262.624058)
		(end 379.14326 -262.548116)
		(width 0.088646)
		(layer "In6.Cu")
		(net "M_G_CPU0_SA_DQS_DN<9>")
	)
	(arc
		(start 387.509512 -262.074152)
		(mid 387.430142 -262.347886)
		(end 387.227318 -262.548116)
		(width 0.088646)
		(layer "In6.Cu")
		(net "M_G_CPU0_SA_DQS_DN<9>")
	)
	(arc
		(start 383.84226 -262.548116)
		(mid 383.655062 -262.497973)
		(end 383.467864 -262.548116)
		(width 0.088646)
		(layer "In6.Cu")
		(net "M_G_CPU0_SA_DQS_DN<9>")
	)
	(arc
		(start 387.227318 -262.548116)
		(mid 386.953119 -262.623951)
		(end 386.676646 -262.556752)
		(width 0.088646)
		(layer "In6.Cu")
		(net "M_G_CPU0_SA_DQS_DN<9>")
	)
	(arc
		(start 384.407664 -262.548116)
		(mid 384.124962 -262.623892)
		(end 383.84226 -262.548116)
		(width 0.088646)
		(layer "In6.Cu")
		(net "M_G_CPU0_SA_DQS_DN<9>")
	)
	(arc
		(start 386.661914 -262.548116)
		(mid 386.474716 -262.497973)
		(end 386.287518 -262.548116)
		(width 0.088646)
		(layer "In6.Cu")
		(net "M_G_CPU0_SA_DQS_DN<9>")
	)
	(segment
		(start 442.861192 -283.32049)
		(end 443.13856 -283.597858)
		(width 0.20066)
		(layer "F.Cu")
		(net "M_G_CPU0_SA_DQS_DN<8>")
	)
	(segment
		(start 441.559188 -284.016704)
		(end 441.83046 -283.745432)
		(width 0.20066)
		(layer "F.Cu")
		(net "M_G_CPU0_SA_DQS_DN<8>")
	)
	(segment
		(start 441.028582 -284.016704)
		(end 441.559188 -284.016704)
		(width 0.20066)
		(layer "F.Cu")
		(net "M_G_CPU0_SA_DQS_DN<8>")
	)
	(segment
		(start 443.450726 -283.597858)
		(end 443.455552 -283.597858)
		(width 0.101854)
		(layer "F.Cu")
		(net "M_G_CPU0_SA_DQS_DN<8>")
	)
	(segment
		(start 441.83046 -283.745432)
		(end 442.313822 -283.745432)
		(width 0.20066)
		(layer "F.Cu")
		(net "M_G_CPU0_SA_DQS_DN<8>")
	)
	(segment
		(start 442.313822 -283.745432)
		(end 442.738764 -283.32049)
		(width 0.20066)
		(layer "F.Cu")
		(net "M_G_CPU0_SA_DQS_DN<8>")
	)
	(segment
		(start 442.738764 -283.32049)
		(end 442.861192 -283.32049)
		(width 0.20066)
		(layer "F.Cu")
		(net "M_G_CPU0_SA_DQS_DN<8>")
	)
	(segment
		(start 377.076716 -267.219938)
		(end 377.076462 -267.220192)
		(width 0.20066)
		(layer "F.Cu")
		(net "M_G_CPU0_SA_DQS_DN<8>")
	)
	(segment
		(start 443.461648 -283.591762)
		(end 445.471804 -283.591762)
		(width 0.1016)
		(layer "F.Cu")
		(net "M_G_CPU0_SA_DQS_DN<8>")
	)
	(segment
		(start 377.076462 -267.220192)
		(end 377.076462 -267.755878)
		(width 0.20066)
		(layer "F.Cu")
		(net "M_G_CPU0_SA_DQS_DN<8>")
	)
	(segment
		(start 446.087246 -283.316934)
		(end 446.577212 -283.316934)
		(width 0.20066)
		(layer "F.Cu")
		(net "M_G_CPU0_SA_DQS_DN<8>")
	)
	(segment
		(start 443.455552 -283.597858)
		(end 443.461648 -283.591762)
		(width 0.1016)
		(layer "F.Cu")
		(net "M_G_CPU0_SA_DQS_DN<8>")
	)
	(segment
		(start 447.022728 -283.76245)
		(end 447.814446 -283.76245)
		(width 0.20066)
		(layer "F.Cu")
		(net "M_G_CPU0_SA_DQS_DN<8>")
	)
	(segment
		(start 445.482726 -283.602684)
		(end 445.801496 -283.602684)
		(width 0.20066)
		(layer "F.Cu")
		(net "M_G_CPU0_SA_DQS_DN<8>")
	)
	(segment
		(start 447.814446 -283.76245)
		(end 448.0687 -284.016704)
		(width 0.20066)
		(layer "F.Cu")
		(net "M_G_CPU0_SA_DQS_DN<8>")
	)
	(segment
		(start 446.577212 -283.316934)
		(end 447.022728 -283.76245)
		(width 0.20066)
		(layer "F.Cu")
		(net "M_G_CPU0_SA_DQS_DN<8>")
	)
	(segment
		(start 448.0687 -284.016704)
		(end 448.572382 -284.016704)
		(width 0.20066)
		(layer "F.Cu")
		(net "M_G_CPU0_SA_DQS_DN<8>")
	)
	(segment
		(start 445.471804 -283.591762)
		(end 445.482726 -283.602684)
		(width 0.1016)
		(layer "F.Cu")
		(net "M_G_CPU0_SA_DQS_DN<8>")
	)
	(segment
		(start 439.923682 -284.016704)
		(end 441.028582 -284.016704)
		(width 0.20066)
		(layer "F.Cu")
		(net "M_G_CPU0_SA_DQS_DN<8>")
	)
	(segment
		(start 443.13856 -283.597858)
		(end 443.450726 -283.597858)
		(width 0.20066)
		(layer "F.Cu")
		(net "M_G_CPU0_SA_DQS_DN<8>")
	)
	(segment
		(start 445.801496 -283.602684)
		(end 446.087246 -283.316934)
		(width 0.20066)
		(layer "F.Cu")
		(net "M_G_CPU0_SA_DQS_DN<8>")
	)
	(segment
		(start 381.588264 -267.43152)
		(end 381.573532 -267.440156)
		(width 0.088646)
		(layer "In6.Cu")
		(net "M_G_CPU0_SA_DQS_DN<8>")
	)
	(segment
		(start 418.178234 -276.1615)
		(end 417.791646 -275.774912)
		(width 0.18288)
		(layer "In6.Cu")
		(net "M_G_CPU0_SA_DQS_DN<8>")
	)
	(segment
		(start 423.61358 -282.194762)
		(end 423.61358 -281.108404)
		(width 0.18288)
		(layer "In6.Cu")
		(net "M_G_CPU0_SA_DQS_DN<8>")
	)
	(segment
		(start 413.121094 -274.649438)
		(end 412.996634 -274.773898)
		(width 0.18288)
		(layer "In6.Cu")
		(net "M_G_CPU0_SA_DQS_DN<8>")
	)
	(segment
		(start 438.808876 -283.73959)
		(end 438.36082 -284.187646)
		(width 0.18288)
		(layer "In6.Cu")
		(net "M_G_CPU0_SA_DQS_DN<8>")
	)
	(segment
		(start 436.710074 -283.300424)
		(end 436.330852 -283.300424)
		(width 0.18288)
		(layer "In6.Cu")
		(net "M_G_CPU0_SA_DQS_DN<8>")
	)
	(segment
		(start 423.921936 -282.503118)
		(end 423.61358 -282.194762)
		(width 0.18288)
		(layer "In6.Cu")
		(net "M_G_CPU0_SA_DQS_DN<8>")
	)
	(segment
		(start 377.829064 -267.43152)
		(end 377.794266 -267.450316)
		(width 0.088646)
		(layer "In6.Cu")
		(net "M_G_CPU0_SA_DQS_DN<8>")
	)
	(segment
		(start 438.36082 -284.187646)
		(end 437.597296 -284.187646)
		(width 0.18288)
		(layer "In6.Cu")
		(net "M_G_CPU0_SA_DQS_DN<8>")
	)
	(segment
		(start 412.996634 -274.773898)
		(end 412.450534 -274.773898)
		(width 0.18288)
		(layer "In6.Cu")
		(net "M_G_CPU0_SA_DQS_DN<8>")
	)
	(segment
		(start 435.596792 -283.58973)
		(end 435.307232 -283.30017)
		(width 0.18288)
		(layer "In6.Cu")
		(net "M_G_CPU0_SA_DQS_DN<8>")
	)
	(segment
		(start 418.752782 -277.51278)
		(end 418.752782 -276.560026)
		(width 0.18288)
		(layer "In6.Cu")
		(net "M_G_CPU0_SA_DQS_DN<8>")
	)
	(segment
		(start 423.48912 -280.437844)
		(end 423.61358 -280.313384)
		(width 0.18288)
		(layer "In6.Cu")
		(net "M_G_CPU0_SA_DQS_DN<8>")
	)
	(segment
		(start 388.45236 -267.721334)
		(end 388.17931 -267.721334)
		(width 0.088646)
		(layer "In6.Cu")
		(net "M_G_CPU0_SA_DQS_DN<8>")
	)
	(segment
		(start 378.768864 -267.43152)
		(end 378.754132 -267.440156)
		(width 0.088646)
		(layer "In6.Cu")
		(net "M_G_CPU0_SA_DQS_DN<8>")
	)
	(segment
		(start 385.736338 -267.440156)
		(end 385.721606 -267.43152)
		(width 0.088646)
		(layer "In6.Cu")
		(net "M_G_CPU0_SA_DQS_DN<8>")
	)
	(segment
		(start 429.841152 -282.683966)
		(end 429.295052 -282.683966)
		(width 0.18288)
		(layer "In6.Cu")
		(net "M_G_CPU0_SA_DQS_DN<8>")
	)
	(segment
		(start 398.968722 -268.312392)
		(end 392.841226 -268.312392)
		(width 0.18288)
		(layer "In6.Cu")
		(net "M_G_CPU0_SA_DQS_DN<8>")
	)
	(segment
		(start 417.021772 -274.829016)
		(end 416.588448 -274.649438)
		(width 0.18288)
		(layer "In6.Cu")
		(net "M_G_CPU0_SA_DQS_DN<8>")
	)
	(segment
		(start 414.462214 -274.649438)
		(end 414.337754 -274.773898)
		(width 0.18288)
		(layer "In6.Cu")
		(net "M_G_CPU0_SA_DQS_DN<8>")
	)
	(segment
		(start 418.354256 -276.1615)
		(end 418.178234 -276.1615)
		(width 0.18288)
		(layer "In6.Cu")
		(net "M_G_CPU0_SA_DQS_DN<8>")
	)
	(segment
		(start 423.61358 -280.313384)
		(end 423.61358 -279.720294)
		(width 0.18288)
		(layer "In6.Cu")
		(net "M_G_CPU0_SA_DQS_DN<8>")
	)
	(segment
		(start 390.171432 -267.781278)
		(end 388.535672 -267.781278)
		(width 0.18288)
		(layer "In6.Cu")
		(net "M_G_CPU0_SA_DQS_DN<8>")
	)
	(segment
		(start 436.330852 -283.300424)
		(end 436.041546 -283.58973)
		(width 0.18288)
		(layer "In6.Cu")
		(net "M_G_CPU0_SA_DQS_DN<8>")
	)
	(segment
		(start 408.084528 -274.773898)
		(end 407.960068 -274.649438)
		(width 0.18288)
		(layer "In6.Cu")
		(net "M_G_CPU0_SA_DQS_DN<8>")
	)
	(segment
		(start 424.542712 -282.740608)
		(end 424.305222 -282.503118)
		(width 0.18288)
		(layer "In6.Cu")
		(net "M_G_CPU0_SA_DQS_DN<8>")
	)
	(segment
		(start 415.917888 -274.773898)
		(end 415.371788 -274.773898)
		(width 0.18288)
		(layer "In6.Cu")
		(net "M_G_CPU0_SA_DQS_DN<8>")
	)
	(segment
		(start 418.752782 -276.560026)
		(end 418.354256 -276.1615)
		(width 0.18288)
		(layer "In6.Cu")
		(net "M_G_CPU0_SA_DQS_DN<8>")
	)
	(segment
		(start 377.794266 -267.450316)
		(end 377.783852 -267.457174)
		(width 0.088646)
		(layer "In6.Cu")
		(net "M_G_CPU0_SA_DQS_DN<8>")
	)
	(segment
		(start 408.630628 -274.773898)
		(end 408.084528 -274.773898)
		(width 0.18288)
		(layer "In6.Cu")
		(net "M_G_CPU0_SA_DQS_DN<8>")
	)
	(segment
		(start 423.48912 -280.983944)
		(end 423.48912 -280.437844)
		(width 0.18288)
		(layer "In6.Cu")
		(net "M_G_CPU0_SA_DQS_DN<8>")
	)
	(segment
		(start 386.67182 -267.437616)
		(end 386.649468 -267.424662)
		(width 0.088646)
		(layer "In6.Cu")
		(net "M_G_CPU0_SA_DQS_DN<8>")
	)
	(segment
		(start 407.960068 -274.649438)
		(end 407.077926 -274.649438)
		(width 0.18288)
		(layer "In6.Cu")
		(net "M_G_CPU0_SA_DQS_DN<8>")
	)
	(segment
		(start 413.667194 -274.649438)
		(end 413.121094 -274.649438)
		(width 0.18288)
		(layer "In6.Cu")
		(net "M_G_CPU0_SA_DQS_DN<8>")
	)
	(segment
		(start 405.305768 -274.649438)
		(end 398.968722 -268.312392)
		(width 0.18288)
		(layer "In6.Cu")
		(net "M_G_CPU0_SA_DQS_DN<8>")
	)
	(segment
		(start 431.799492 -283.30017)
		(end 431.058828 -282.559506)
		(width 0.18288)
		(layer "In6.Cu")
		(net "M_G_CPU0_SA_DQS_DN<8>")
	)
	(segment
		(start 410.595572 -274.773898)
		(end 410.049472 -274.773898)
		(width 0.18288)
		(layer "In6.Cu")
		(net "M_G_CPU0_SA_DQS_DN<8>")
	)
	(segment
		(start 385.721606 -267.43152)
		(end 385.713224 -267.426694)
		(width 0.088646)
		(layer "In6.Cu")
		(net "M_G_CPU0_SA_DQS_DN<8>")
	)
	(segment
		(start 424.305222 -282.503118)
		(end 423.921936 -282.503118)
		(width 0.18288)
		(layer "In6.Cu")
		(net "M_G_CPU0_SA_DQS_DN<8>")
	)
	(segment
		(start 406.953466 -274.773898)
		(end 406.407366 -274.773898)
		(width 0.18288)
		(layer "In6.Cu")
		(net "M_G_CPU0_SA_DQS_DN<8>")
	)
	(segment
		(start 383.467864 -267.43152)
		(end 383.453132 -267.440156)
		(width 0.088646)
		(layer "In6.Cu")
		(net "M_G_CPU0_SA_DQS_DN<8>")
	)
	(segment
		(start 380.093728 -267.437616)
		(end 380.083314 -267.43152)
		(width 0.088646)
		(layer "In6.Cu")
		(net "M_G_CPU0_SA_DQS_DN<8>")
	)
	(segment
		(start 419.493192 -278.25319)
		(end 418.752782 -277.51278)
		(width 0.18288)
		(layer "In6.Cu")
		(net "M_G_CPU0_SA_DQS_DN<8>")
	)
	(segment
		(start 421.567864 -278.249126)
		(end 421.194484 -278.249126)
		(width 0.18288)
		(layer "In6.Cu")
		(net "M_G_CPU0_SA_DQS_DN<8>")
	)
	(segment
		(start 377.783852 -267.457174)
		(end 377.734322 -267.490194)
		(width 0.088646)
		(layer "In6.Cu")
		(net "M_G_CPU0_SA_DQS_DN<8>")
	)
	(segment
		(start 421.194484 -278.249126)
		(end 420.95293 -278.49068)
		(width 0.18288)
		(layer "In6.Cu")
		(net "M_G_CPU0_SA_DQS_DN<8>")
	)
	(segment
		(start 420.205154 -278.25319)
		(end 419.493192 -278.25319)
		(width 0.18288)
		(layer "In6.Cu")
		(net "M_G_CPU0_SA_DQS_DN<8>")
	)
	(segment
		(start 439.646568 -283.73959)
		(end 438.808876 -283.73959)
		(width 0.18288)
		(layer "In6.Cu")
		(net "M_G_CPU0_SA_DQS_DN<8>")
	)
	(segment
		(start 410.049472 -274.773898)
		(end 409.925012 -274.649438)
		(width 0.18288)
		(layer "In6.Cu")
		(net "M_G_CPU0_SA_DQS_DN<8>")
	)
	(segment
		(start 377.43384 -267.550138)
		(end 377.133104 -267.550138)
		(width 0.088646)
		(layer "In6.Cu")
		(net "M_G_CPU0_SA_DQS_DN<8>")
	)
	(segment
		(start 409.925012 -274.649438)
		(end 408.755088 -274.649438)
		(width 0.18288)
		(layer "In6.Cu")
		(net "M_G_CPU0_SA_DQS_DN<8>")
	)
	(segment
		(start 417.791646 -275.774912)
		(end 417.791646 -275.59889)
		(width 0.18288)
		(layer "In6.Cu")
		(net "M_G_CPU0_SA_DQS_DN<8>")
	)
	(segment
		(start 377.133104 -267.550138)
		(end 377.076462 -267.60678)
		(width 0.088646)
		(layer "In6.Cu")
		(net "M_G_CPU0_SA_DQS_DN<8>")
	)
	(segment
		(start 388.535672 -267.781278)
		(end 388.512304 -267.781278)
		(width 0.088646)
		(layer "In6.Cu")
		(net "M_G_CPU0_SA_DQS_DN<8>")
	)
	(segment
		(start 413.791654 -274.773898)
		(end 413.667194 -274.649438)
		(width 0.18288)
		(layer "In6.Cu")
		(net "M_G_CPU0_SA_DQS_DN<8>")
	)
	(segment
		(start 415.247328 -274.649438)
		(end 414.462214 -274.649438)
		(width 0.18288)
		(layer "In6.Cu")
		(net "M_G_CPU0_SA_DQS_DN<8>")
	)
	(segment
		(start 423.61358 -279.720294)
		(end 422.68394 -278.790654)
		(width 0.18288)
		(layer "In6.Cu")
		(net "M_G_CPU0_SA_DQS_DN<8>")
	)
	(segment
		(start 382.528064 -267.43152)
		(end 382.513332 -267.440156)
		(width 0.088646)
		(layer "In6.Cu")
		(net "M_G_CPU0_SA_DQS_DN<8>")
	)
	(segment
		(start 439.923682 -284.016704)
		(end 439.646568 -283.73959)
		(width 0.18288)
		(layer "In6.Cu")
		(net "M_G_CPU0_SA_DQS_DN<8>")
	)
	(segment
		(start 429.170592 -282.559506)
		(end 428.078646 -282.559506)
		(width 0.18288)
		(layer "In6.Cu")
		(net "M_G_CPU0_SA_DQS_DN<8>")
	)
	(segment
		(start 412.326074 -274.649438)
		(end 410.720032 -274.649438)
		(width 0.18288)
		(layer "In6.Cu")
		(net "M_G_CPU0_SA_DQS_DN<8>")
	)
	(segment
		(start 420.95293 -278.49068)
		(end 420.442644 -278.49068)
		(width 0.18288)
		(layer "In6.Cu")
		(net "M_G_CPU0_SA_DQS_DN<8>")
	)
	(segment
		(start 414.337754 -274.773898)
		(end 413.791654 -274.773898)
		(width 0.18288)
		(layer "In6.Cu")
		(net "M_G_CPU0_SA_DQS_DN<8>")
	)
	(segment
		(start 410.720032 -274.649438)
		(end 410.595572 -274.773898)
		(width 0.18288)
		(layer "In6.Cu")
		(net "M_G_CPU0_SA_DQS_DN<8>")
	)
	(segment
		(start 422.68394 -278.790654)
		(end 422.109392 -278.790654)
		(width 0.18288)
		(layer "In6.Cu")
		(net "M_G_CPU0_SA_DQS_DN<8>")
	)
	(segment
		(start 406.282906 -274.649438)
		(end 405.305768 -274.649438)
		(width 0.18288)
		(layer "In6.Cu")
		(net "M_G_CPU0_SA_DQS_DN<8>")
	)
	(segment
		(start 435.307232 -283.30017)
		(end 431.799492 -283.30017)
		(width 0.18288)
		(layer "In6.Cu")
		(net "M_G_CPU0_SA_DQS_DN<8>")
	)
	(segment
		(start 428.078646 -282.559506)
		(end 427.587156 -283.050996)
		(width 0.18288)
		(layer "In6.Cu")
		(net "M_G_CPU0_SA_DQS_DN<8>")
	)
	(segment
		(start 425.34332 -282.450286)
		(end 425.052998 -282.740608)
		(width 0.18288)
		(layer "In6.Cu")
		(net "M_G_CPU0_SA_DQS_DN<8>")
	)
	(segment
		(start 384.796792 -267.440156)
		(end 384.78206 -267.43152)
		(width 0.088646)
		(layer "In6.Cu")
		(net "M_G_CPU0_SA_DQS_DN<8>")
	)
	(segment
		(start 392.841226 -268.312392)
		(end 390.171432 -267.781278)
		(width 0.18288)
		(layer "In6.Cu")
		(net "M_G_CPU0_SA_DQS_DN<8>")
	)
	(segment
		(start 429.965612 -282.559506)
		(end 429.841152 -282.683966)
		(width 0.18288)
		(layer "In6.Cu")
		(net "M_G_CPU0_SA_DQS_DN<8>")
	)
	(segment
		(start 416.042348 -274.649438)
		(end 415.917888 -274.773898)
		(width 0.18288)
		(layer "In6.Cu")
		(net "M_G_CPU0_SA_DQS_DN<8>")
	)
	(segment
		(start 416.588448 -274.649438)
		(end 416.042348 -274.649438)
		(width 0.18288)
		(layer "In6.Cu")
		(net "M_G_CPU0_SA_DQS_DN<8>")
	)
	(segment
		(start 426.109638 -282.450286)
		(end 425.34332 -282.450286)
		(width 0.18288)
		(layer "In6.Cu")
		(net "M_G_CPU0_SA_DQS_DN<8>")
	)
	(segment
		(start 387.965188 -267.507212)
		(end 387.882892 -267.507212)
		(width 0.088646)
		(layer "In6.Cu")
		(net "M_G_CPU0_SA_DQS_DN<8>")
	)
	(segment
		(start 420.442644 -278.49068)
		(end 420.205154 -278.25319)
		(width 0.18288)
		(layer "In6.Cu")
		(net "M_G_CPU0_SA_DQS_DN<8>")
	)
	(segment
		(start 408.755088 -274.649438)
		(end 408.630628 -274.773898)
		(width 0.18288)
		(layer "In6.Cu")
		(net "M_G_CPU0_SA_DQS_DN<8>")
	)
	(segment
		(start 415.371788 -274.773898)
		(end 415.247328 -274.649438)
		(width 0.18288)
		(layer "In6.Cu")
		(net "M_G_CPU0_SA_DQS_DN<8>")
	)
	(segment
		(start 379.708918 -267.43152)
		(end 379.698504 -267.437616)
		(width 0.088646)
		(layer "In6.Cu")
		(net "M_G_CPU0_SA_DQS_DN<8>")
	)
	(segment
		(start 429.295052 -282.683966)
		(end 429.170592 -282.559506)
		(width 0.18288)
		(layer "In6.Cu")
		(net "M_G_CPU0_SA_DQS_DN<8>")
	)
	(segment
		(start 377.076462 -267.60678)
		(end 377.076462 -267.755878)
		(width 0.088646)
		(layer "In6.Cu")
		(net "M_G_CPU0_SA_DQS_DN<8>")
	)
	(segment
		(start 436.041546 -283.58973)
		(end 435.596792 -283.58973)
		(width 0.18288)
		(layer "In6.Cu")
		(net "M_G_CPU0_SA_DQS_DN<8>")
	)
	(segment
		(start 437.597296 -284.187646)
		(end 436.710074 -283.300424)
		(width 0.18288)
		(layer "In6.Cu")
		(net "M_G_CPU0_SA_DQS_DN<8>")
	)
	(segment
		(start 426.710348 -283.050996)
		(end 426.109638 -282.450286)
		(width 0.18288)
		(layer "In6.Cu")
		(net "M_G_CPU0_SA_DQS_DN<8>")
	)
	(segment
		(start 417.791646 -275.59889)
		(end 417.021772 -274.829016)
		(width 0.18288)
		(layer "In6.Cu")
		(net "M_G_CPU0_SA_DQS_DN<8>")
	)
	(segment
		(start 431.058828 -282.559506)
		(end 429.965612 -282.559506)
		(width 0.18288)
		(layer "In6.Cu")
		(net "M_G_CPU0_SA_DQS_DN<8>")
	)
	(segment
		(start 388.512304 -267.781278)
		(end 388.45236 -267.721334)
		(width 0.088646)
		(layer "In6.Cu")
		(net "M_G_CPU0_SA_DQS_DN<8>")
	)
	(segment
		(start 425.052998 -282.740608)
		(end 424.542712 -282.740608)
		(width 0.18288)
		(layer "In6.Cu")
		(net "M_G_CPU0_SA_DQS_DN<8>")
	)
	(segment
		(start 388.17931 -267.721334)
		(end 387.965188 -267.507212)
		(width 0.088646)
		(layer "In6.Cu")
		(net "M_G_CPU0_SA_DQS_DN<8>")
	)
	(segment
		(start 422.109392 -278.790654)
		(end 421.567864 -278.249126)
		(width 0.18288)
		(layer "In6.Cu")
		(net "M_G_CPU0_SA_DQS_DN<8>")
	)
	(segment
		(start 427.587156 -283.050996)
		(end 426.710348 -283.050996)
		(width 0.18288)
		(layer "In6.Cu")
		(net "M_G_CPU0_SA_DQS_DN<8>")
	)
	(segment
		(start 407.077926 -274.649438)
		(end 406.953466 -274.773898)
		(width 0.18288)
		(layer "In6.Cu")
		(net "M_G_CPU0_SA_DQS_DN<8>")
	)
	(segment
		(start 412.450534 -274.773898)
		(end 412.326074 -274.649438)
		(width 0.18288)
		(layer "In6.Cu")
		(net "M_G_CPU0_SA_DQS_DN<8>")
	)
	(segment
		(start 423.61358 -281.108404)
		(end 423.48912 -280.983944)
		(width 0.18288)
		(layer "In6.Cu")
		(net "M_G_CPU0_SA_DQS_DN<8>")
	)
	(segment
		(start 377.734322 -267.490194)
		(end 377.43384 -267.550138)
		(width 0.088646)
		(layer "In6.Cu")
		(net "M_G_CPU0_SA_DQS_DN<8>")
	)
	(segment
		(start 406.407366 -274.773898)
		(end 406.282906 -274.649438)
		(width 0.18288)
		(layer "In6.Cu")
		(net "M_G_CPU0_SA_DQS_DN<8>")
	)
	(arc
		(start 382.90246 -267.43152)
		(mid 382.715262 -267.381377)
		(end 382.528064 -267.43152)
		(width 0.088646)
		(layer "In6.Cu")
		(net "M_G_CPU0_SA_DQS_DN<8>")
	)
	(arc
		(start 379.14326 -267.43152)
		(mid 378.956062 -267.381377)
		(end 378.768864 -267.43152)
		(width 0.088646)
		(layer "In6.Cu")
		(net "M_G_CPU0_SA_DQS_DN<8>")
	)
	(arc
		(start 387.882892 -267.507212)
		(mid 387.736684 -267.487963)
		(end 387.600444 -267.43152)
		(width 0.088646)
		(layer "In6.Cu")
		(net "M_G_CPU0_SA_DQS_DN<8>")
	)
	(arc
		(start 379.698504 -267.437616)
		(mid 379.420072 -267.507462)
		(end 379.14326 -267.43152)
		(width 0.088646)
		(layer "In6.Cu")
		(net "M_G_CPU0_SA_DQS_DN<8>")
	)
	(arc
		(start 382.513332 -267.440156)
		(mid 382.236857 -267.507476)
		(end 381.96266 -267.43152)
		(width 0.088646)
		(layer "In6.Cu")
		(net "M_G_CPU0_SA_DQS_DN<8>")
	)
	(arc
		(start 380.648464 -267.43152)
		(mid 380.371905 -267.507263)
		(end 380.093728 -267.437616)
		(width 0.088646)
		(layer "In6.Cu")
		(net "M_G_CPU0_SA_DQS_DN<8>")
	)
	(arc
		(start 386.28701 -267.43152)
		(mid 386.012781 -267.507445)
		(end 385.736338 -267.440156)
		(width 0.088646)
		(layer "In6.Cu")
		(net "M_G_CPU0_SA_DQS_DN<8>")
	)
	(arc
		(start 380.083314 -267.43152)
		(mid 379.896116 -267.381377)
		(end 379.708918 -267.43152)
		(width 0.088646)
		(layer "In6.Cu")
		(net "M_G_CPU0_SA_DQS_DN<8>")
	)
	(arc
		(start 381.02286 -267.43152)
		(mid 380.835662 -267.381377)
		(end 380.648464 -267.43152)
		(width 0.088646)
		(layer "In6.Cu")
		(net "M_G_CPU0_SA_DQS_DN<8>")
	)
	(arc
		(start 385.713224 -267.426694)
		(mid 385.529716 -267.381416)
		(end 385.347464 -267.43152)
		(width 0.088646)
		(layer "In6.Cu")
		(net "M_G_CPU0_SA_DQS_DN<8>")
	)
	(arc
		(start 385.347464 -267.43152)
		(mid 385.073235 -267.507445)
		(end 384.796792 -267.440156)
		(width 0.088646)
		(layer "In6.Cu")
		(net "M_G_CPU0_SA_DQS_DN<8>")
	)
	(arc
		(start 387.226048 -267.43152)
		(mid 386.949743 -267.507102)
		(end 386.67182 -267.437616)
		(width 0.088646)
		(layer "In6.Cu")
		(net "M_G_CPU0_SA_DQS_DN<8>")
	)
	(arc
		(start 384.78206 -267.43152)
		(mid 384.594862 -267.381377)
		(end 384.407664 -267.43152)
		(width 0.088646)
		(layer "In6.Cu")
		(net "M_G_CPU0_SA_DQS_DN<8>")
	)
	(arc
		(start 383.84226 -267.43152)
		(mid 383.655062 -267.381377)
		(end 383.467864 -267.43152)
		(width 0.088646)
		(layer "In6.Cu")
		(net "M_G_CPU0_SA_DQS_DN<8>")
	)
	(arc
		(start 378.754132 -267.440156)
		(mid 378.477657 -267.507476)
		(end 378.20346 -267.43152)
		(width 0.088646)
		(layer "In6.Cu")
		(net "M_G_CPU0_SA_DQS_DN<8>")
	)
	(arc
		(start 383.453132 -267.440156)
		(mid 383.176691 -267.507322)
		(end 382.90246 -267.43152)
		(width 0.088646)
		(layer "In6.Cu")
		(net "M_G_CPU0_SA_DQS_DN<8>")
	)
	(arc
		(start 384.407664 -267.43152)
		(mid 384.124962 -267.507262)
		(end 383.84226 -267.43152)
		(width 0.088646)
		(layer "In6.Cu")
		(net "M_G_CPU0_SA_DQS_DN<8>")
	)
	(arc
		(start 378.20346 -267.43152)
		(mid 378.016262 -267.381377)
		(end 377.829064 -267.43152)
		(width 0.088646)
		(layer "In6.Cu")
		(net "M_G_CPU0_SA_DQS_DN<8>")
	)
	(arc
		(start 387.600444 -267.43152)
		(mid 387.413246 -267.381377)
		(end 387.226048 -267.43152)
		(width 0.088646)
		(layer "In6.Cu")
		(net "M_G_CPU0_SA_DQS_DN<8>")
	)
	(arc
		(start 381.573532 -267.440156)
		(mid 381.297057 -267.507476)
		(end 381.02286 -267.43152)
		(width 0.088646)
		(layer "In6.Cu")
		(net "M_G_CPU0_SA_DQS_DN<8>")
	)
	(arc
		(start 381.96266 -267.43152)
		(mid 381.775462 -267.381377)
		(end 381.588264 -267.43152)
		(width 0.088646)
		(layer "In6.Cu")
		(net "M_G_CPU0_SA_DQS_DN<8>")
	)
	(arc
		(start 386.649468 -267.424662)
		(mid 386.467357 -267.381337)
		(end 386.28701 -267.43152)
		(width 0.088646)
		(layer "In6.Cu")
		(net "M_G_CPU0_SA_DQS_DN<8>")
	)
	(segment
		(start 446.577212 -292.666928)
		(end 447.022728 -293.112444)
		(width 0.20066)
		(layer "F.Cu")
		(net "M_G_CPU0_SA_DQS_DN<7>")
	)
	(segment
		(start 443.455552 -292.947852)
		(end 443.461648 -292.941756)
		(width 0.1016)
		(layer "F.Cu")
		(net "M_G_CPU0_SA_DQS_DN<7>")
	)
	(segment
		(start 441.83046 -293.095426)
		(end 442.313822 -293.095426)
		(width 0.20066)
		(layer "F.Cu")
		(net "M_G_CPU0_SA_DQS_DN<7>")
	)
	(segment
		(start 380.365762 -265.313922)
		(end 380.366016 -265.314176)
		(width 0.20066)
		(layer "F.Cu")
		(net "M_G_CPU0_SA_DQS_DN<7>")
	)
	(segment
		(start 441.028582 -293.366698)
		(end 441.559188 -293.366698)
		(width 0.20066)
		(layer "F.Cu")
		(net "M_G_CPU0_SA_DQS_DN<7>")
	)
	(segment
		(start 443.461648 -292.941756)
		(end 445.471804 -292.941756)
		(width 0.1016)
		(layer "F.Cu")
		(net "M_G_CPU0_SA_DQS_DN<7>")
	)
	(segment
		(start 445.471804 -292.941756)
		(end 445.482726 -292.952678)
		(width 0.1016)
		(layer "F.Cu")
		(net "M_G_CPU0_SA_DQS_DN<7>")
	)
	(segment
		(start 447.814446 -293.112444)
		(end 448.0687 -293.366698)
		(width 0.20066)
		(layer "F.Cu")
		(net "M_G_CPU0_SA_DQS_DN<7>")
	)
	(segment
		(start 445.801496 -292.952678)
		(end 446.087246 -292.666928)
		(width 0.20066)
		(layer "F.Cu")
		(net "M_G_CPU0_SA_DQS_DN<7>")
	)
	(segment
		(start 442.861192 -292.670484)
		(end 443.13856 -292.947852)
		(width 0.20066)
		(layer "F.Cu")
		(net "M_G_CPU0_SA_DQS_DN<7>")
	)
	(segment
		(start 445.482726 -292.952678)
		(end 445.801496 -292.952678)
		(width 0.20066)
		(layer "F.Cu")
		(net "M_G_CPU0_SA_DQS_DN<7>")
	)
	(segment
		(start 441.559188 -293.366698)
		(end 441.83046 -293.095426)
		(width 0.20066)
		(layer "F.Cu")
		(net "M_G_CPU0_SA_DQS_DN<7>")
	)
	(segment
		(start 442.738764 -292.670484)
		(end 442.861192 -292.670484)
		(width 0.20066)
		(layer "F.Cu")
		(net "M_G_CPU0_SA_DQS_DN<7>")
	)
	(segment
		(start 446.087246 -292.666928)
		(end 446.577212 -292.666928)
		(width 0.20066)
		(layer "F.Cu")
		(net "M_G_CPU0_SA_DQS_DN<7>")
	)
	(segment
		(start 448.0687 -293.366698)
		(end 448.572382 -293.366698)
		(width 0.20066)
		(layer "F.Cu")
		(net "M_G_CPU0_SA_DQS_DN<7>")
	)
	(segment
		(start 439.923682 -293.366698)
		(end 441.028582 -293.366698)
		(width 0.20066)
		(layer "F.Cu")
		(net "M_G_CPU0_SA_DQS_DN<7>")
	)
	(segment
		(start 380.365762 -264.778236)
		(end 380.365762 -265.313922)
		(width 0.20066)
		(layer "F.Cu")
		(net "M_G_CPU0_SA_DQS_DN<7>")
	)
	(segment
		(start 443.13856 -292.947852)
		(end 443.450726 -292.947852)
		(width 0.20066)
		(layer "F.Cu")
		(net "M_G_CPU0_SA_DQS_DN<7>")
	)
	(segment
		(start 443.450726 -292.947852)
		(end 443.455552 -292.947852)
		(width 0.101854)
		(layer "F.Cu")
		(net "M_G_CPU0_SA_DQS_DN<7>")
	)
	(segment
		(start 442.313822 -293.095426)
		(end 442.738764 -292.670484)
		(width 0.20066)
		(layer "F.Cu")
		(net "M_G_CPU0_SA_DQS_DN<7>")
	)
	(segment
		(start 447.022728 -293.112444)
		(end 447.814446 -293.112444)
		(width 0.20066)
		(layer "F.Cu")
		(net "M_G_CPU0_SA_DQS_DN<7>")
	)
	(segment
		(start 381.118364 -264.989818)
		(end 380.986792 -265.065764)
		(width 0.088646)
		(layer "In4.Cu")
		(net "M_G_CPU0_SA_DQS_DN<7>")
	)
	(segment
		(start 429.559974 -292.019482)
		(end 428.158656 -292.019482)
		(width 0.18288)
		(layer "In4.Cu")
		(net "M_G_CPU0_SA_DQS_DN<7>")
	)
	(segment
		(start 409.064714 -284.691328)
		(end 408.782266 -284.202378)
		(width 0.18288)
		(layer "In4.Cu")
		(net "M_G_CPU0_SA_DQS_DN<7>")
	)
	(segment
		(start 408.782266 -283.11729)
		(end 408.168602 -282.503626)
		(width 0.18288)
		(layer "In4.Cu")
		(net "M_G_CPU0_SA_DQS_DN<7>")
	)
	(segment
		(start 433.349146 -292.403276)
		(end 432.707542 -292.403276)
		(width 0.18288)
		(layer "In4.Cu")
		(net "M_G_CPU0_SA_DQS_DN<7>")
	)
	(segment
		(start 380.986792 -265.065764)
		(end 380.831852 -265.107166)
		(width 0.088646)
		(layer "In4.Cu")
		(net "M_G_CPU0_SA_DQS_DN<7>")
	)
	(segment
		(start 386.522214 -265.17727)
		(end 385.584954 -265.17727)
		(width 0.088646)
		(layer "In4.Cu")
		(net "M_G_CPU0_SA_DQS_DN<7>")
	)
	(segment
		(start 429.684434 -292.143942)
		(end 429.559974 -292.019482)
		(width 0.18288)
		(layer "In4.Cu")
		(net "M_G_CPU0_SA_DQS_DN<7>")
	)
	(segment
		(start 388.479792 -265.23696)
		(end 386.605272 -265.23696)
		(width 0.18288)
		(layer "In4.Cu")
		(net "M_G_CPU0_SA_DQS_DN<7>")
	)
	(segment
		(start 417.344352 -291.239448)
		(end 416.72129 -291.239448)
		(width 0.18288)
		(layer "In4.Cu")
		(net "M_G_CPU0_SA_DQS_DN<7>")
	)
	(segment
		(start 439.64225 -293.085266)
		(end 439.477658 -293.085266)
		(width 0.18288)
		(layer "In4.Cu")
		(net "M_G_CPU0_SA_DQS_DN<7>")
	)
	(segment
		(start 409.368752 -285.140654)
		(end 409.270962 -284.776418)
		(width 0.18288)
		(layer "In4.Cu")
		(net "M_G_CPU0_SA_DQS_DN<7>")
	)
	(segment
		(start 414.15081 -289.216338)
		(end 413.433768 -288.499296)
		(width 0.18288)
		(layer "In4.Cu")
		(net "M_G_CPU0_SA_DQS_DN<7>")
	)
	(segment
		(start 430.354994 -292.019482)
		(end 430.230534 -292.143942)
		(width 0.18288)
		(layer "In4.Cu")
		(net "M_G_CPU0_SA_DQS_DN<7>")
	)
	(segment
		(start 421.211248 -292.661086)
		(end 420.928292 -292.944042)
		(width 0.18288)
		(layer "In4.Cu")
		(net "M_G_CPU0_SA_DQS_DN<7>")
	)
	(segment
		(start 418.757354 -292.65245)
		(end 417.344352 -291.239448)
		(width 0.18288)
		(layer "In4.Cu")
		(net "M_G_CPU0_SA_DQS_DN<7>")
	)
	(segment
		(start 430.982628 -292.019482)
		(end 430.354994 -292.019482)
		(width 0.18288)
		(layer "In4.Cu")
		(net "M_G_CPU0_SA_DQS_DN<7>")
	)
	(segment
		(start 407.498042 -282.628086)
		(end 406.951942 -282.628086)
		(width 0.18288)
		(layer "In4.Cu")
		(net "M_G_CPU0_SA_DQS_DN<7>")
	)
	(segment
		(start 406.951942 -282.628086)
		(end 406.827482 -282.503626)
		(width 0.18288)
		(layer "In4.Cu")
		(net "M_G_CPU0_SA_DQS_DN<7>")
	)
	(segment
		(start 434.144166 -292.403276)
		(end 434.019706 -292.527736)
		(width 0.18288)
		(layer "In4.Cu")
		(net "M_G_CPU0_SA_DQS_DN<7>")
	)
	(segment
		(start 430.230534 -292.143942)
		(end 429.684434 -292.143942)
		(width 0.18288)
		(layer "In4.Cu")
		(net "M_G_CPU0_SA_DQS_DN<7>")
	)
	(segment
		(start 425.310808 -291.827204)
		(end 425.045632 -292.09238)
		(width 0.18288)
		(layer "In4.Cu")
		(net "M_G_CPU0_SA_DQS_DN<7>")
	)
	(segment
		(start 412.871158 -287.936686)
		(end 412.271718 -287.337246)
		(width 0.18288)
		(layer "In4.Cu")
		(net "M_G_CPU0_SA_DQS_DN<7>")
	)
	(segment
		(start 436.473346 -292.683946)
		(end 436.275988 -292.683946)
		(width 0.18288)
		(layer "In4.Cu")
		(net "M_G_CPU0_SA_DQS_DN<7>")
	)
	(segment
		(start 420.544244 -292.944042)
		(end 420.252652 -292.65245)
		(width 0.18288)
		(layer "In4.Cu")
		(net "M_G_CPU0_SA_DQS_DN<7>")
	)
	(segment
		(start 435.363112 -292.67531)
		(end 435.02326 -292.67531)
		(width 0.18288)
		(layer "In4.Cu")
		(net "M_G_CPU0_SA_DQS_DN<7>")
	)
	(segment
		(start 382.062736 -264.987024)
		(end 382.058418 -264.989818)
		(width 0.088646)
		(layer "In4.Cu")
		(net "M_G_CPU0_SA_DQS_DN<7>")
	)
	(segment
		(start 422.688512 -292.147752)
		(end 422.620948 -292.310566)
		(width 0.18288)
		(layer "In4.Cu")
		(net "M_G_CPU0_SA_DQS_DN<7>")
	)
	(segment
		(start 381.503174 -264.995914)
		(end 381.49276 -264.989818)
		(width 0.088646)
		(layer "In4.Cu")
		(net "M_G_CPU0_SA_DQS_DN<7>")
	)
	(segment
		(start 411.185868 -286.857694)
		(end 411.185868 -286.268668)
		(width 0.18288)
		(layer "In4.Cu")
		(net "M_G_CPU0_SA_DQS_DN<7>")
	)
	(segment
		(start 406.827482 -282.503626)
		(end 405.53513 -282.503626)
		(width 0.18288)
		(layer "In4.Cu")
		(net "M_G_CPU0_SA_DQS_DN<7>")
	)
	(segment
		(start 412.271718 -287.337246)
		(end 411.66542 -287.337246)
		(width 0.18288)
		(layer "In4.Cu")
		(net "M_G_CPU0_SA_DQS_DN<7>")
	)
	(segment
		(start 413.433768 -288.499296)
		(end 413.257746 -288.499296)
		(width 0.18288)
		(layer "In4.Cu")
		(net "M_G_CPU0_SA_DQS_DN<7>")
	)
	(segment
		(start 421.449246 -292.661086)
		(end 421.211248 -292.661086)
		(width 0.18288)
		(layer "In4.Cu")
		(net "M_G_CPU0_SA_DQS_DN<7>")
	)
	(segment
		(start 423.513504 -291.806122)
		(end 422.688512 -292.147752)
		(width 0.18288)
		(layer "In4.Cu")
		(net "M_G_CPU0_SA_DQS_DN<7>")
	)
	(segment
		(start 426.008038 -291.814758)
		(end 425.327572 -291.814758)
		(width 0.18288)
		(layer "In4.Cu")
		(net "M_G_CPU0_SA_DQS_DN<7>")
	)
	(segment
		(start 411.185868 -286.268668)
		(end 410.1338 -285.216854)
		(width 0.18288)
		(layer "In4.Cu")
		(net "M_G_CPU0_SA_DQS_DN<7>")
	)
	(segment
		(start 410.1338 -285.216854)
		(end 409.701492 -285.332678)
		(width 0.18288)
		(layer "In4.Cu")
		(net "M_G_CPU0_SA_DQS_DN<7>")
	)
	(segment
		(start 414.713166 -289.778694)
		(end 414.537144 -289.778694)
		(width 0.18288)
		(layer "In4.Cu")
		(net "M_G_CPU0_SA_DQS_DN<7>")
	)
	(segment
		(start 411.66542 -287.337246)
		(end 411.185868 -286.857694)
		(width 0.18288)
		(layer "In4.Cu")
		(net "M_G_CPU0_SA_DQS_DN<7>")
	)
	(segment
		(start 407.622502 -282.503626)
		(end 407.498042 -282.628086)
		(width 0.18288)
		(layer "In4.Cu")
		(net "M_G_CPU0_SA_DQS_DN<7>")
	)
	(segment
		(start 425.315126 -291.827204)
		(end 425.310808 -291.827204)
		(width 0.18288)
		(layer "In4.Cu")
		(net "M_G_CPU0_SA_DQS_DN<7>")
	)
	(segment
		(start 431.366422 -292.403276)
		(end 430.982628 -292.019482)
		(width 0.18288)
		(layer "In4.Cu")
		(net "M_G_CPU0_SA_DQS_DN<7>")
	)
	(segment
		(start 424.63085 -292.09238)
		(end 424.344592 -291.806122)
		(width 0.18288)
		(layer "In4.Cu")
		(net "M_G_CPU0_SA_DQS_DN<7>")
	)
	(segment
		(start 427.703488 -292.47465)
		(end 426.66793 -292.47465)
		(width 0.18288)
		(layer "In4.Cu")
		(net "M_G_CPU0_SA_DQS_DN<7>")
	)
	(segment
		(start 420.928292 -292.944042)
		(end 420.544244 -292.944042)
		(width 0.18288)
		(layer "In4.Cu")
		(net "M_G_CPU0_SA_DQS_DN<7>")
	)
	(segment
		(start 404.610824 -281.579574)
		(end 402.55444 -276.61489)
		(width 0.18288)
		(layer "In4.Cu")
		(net "M_G_CPU0_SA_DQS_DN<7>")
	)
	(segment
		(start 437.714644 -293.379144)
		(end 437.590184 -293.254684)
		(width 0.18288)
		(layer "In4.Cu")
		(net "M_G_CPU0_SA_DQS_DN<7>")
	)
	(segment
		(start 405.53513 -282.503626)
		(end 404.610824 -281.579574)
		(width 0.18288)
		(layer "In4.Cu")
		(net "M_G_CPU0_SA_DQS_DN<7>")
	)
	(segment
		(start 386.605272 -265.23696)
		(end 386.581904 -265.23696)
		(width 0.088646)
		(layer "In4.Cu")
		(net "M_G_CPU0_SA_DQS_DN<7>")
	)
	(segment
		(start 438.385204 -293.254684)
		(end 438.260744 -293.379144)
		(width 0.18288)
		(layer "In4.Cu")
		(net "M_G_CPU0_SA_DQS_DN<7>")
	)
	(segment
		(start 386.581904 -265.23696)
		(end 386.522214 -265.17727)
		(width 0.088646)
		(layer "In4.Cu")
		(net "M_G_CPU0_SA_DQS_DN<7>")
	)
	(segment
		(start 420.252652 -292.65245)
		(end 418.757354 -292.65245)
		(width 0.18288)
		(layer "In4.Cu")
		(net "M_G_CPU0_SA_DQS_DN<7>")
	)
	(segment
		(start 439.923682 -293.366698)
		(end 439.64225 -293.085266)
		(width 0.18288)
		(layer "In4.Cu")
		(net "M_G_CPU0_SA_DQS_DN<7>")
	)
	(segment
		(start 402.554186 -276.614382)
		(end 394.170916 -268.231112)
		(width 0.18288)
		(layer "In4.Cu")
		(net "M_G_CPU0_SA_DQS_DN<7>")
	)
	(segment
		(start 439.477658 -293.085266)
		(end 439.068718 -293.254684)
		(width 0.18288)
		(layer "In4.Cu")
		(net "M_G_CPU0_SA_DQS_DN<7>")
	)
	(segment
		(start 434.751226 -292.403276)
		(end 434.144166 -292.403276)
		(width 0.18288)
		(layer "In4.Cu")
		(net "M_G_CPU0_SA_DQS_DN<7>")
	)
	(segment
		(start 382.447546 -264.998454)
		(end 382.432814 -264.989818)
		(width 0.088646)
		(layer "In4.Cu")
		(net "M_G_CPU0_SA_DQS_DN<7>")
	)
	(segment
		(start 425.327572 -291.814758)
		(end 425.315126 -291.827204)
		(width 0.18288)
		(layer "In4.Cu")
		(net "M_G_CPU0_SA_DQS_DN<7>")
	)
	(segment
		(start 416.72129 -291.239448)
		(end 416.033458 -290.55187)
		(width 0.18288)
		(layer "In4.Cu")
		(net "M_G_CPU0_SA_DQS_DN<7>")
	)
	(segment
		(start 437.044084 -293.254684)
		(end 436.473346 -292.683946)
		(width 0.18288)
		(layer "In4.Cu")
		(net "M_G_CPU0_SA_DQS_DN<7>")
	)
	(segment
		(start 390.994646 -267.615924)
		(end 390.762744 -267.519912)
		(width 0.18288)
		(layer "In4.Cu")
		(net "M_G_CPU0_SA_DQS_DN<7>")
	)
	(segment
		(start 421.95369 -292.452298)
		(end 421.449246 -292.661086)
		(width 0.18288)
		(layer "In4.Cu")
		(net "M_G_CPU0_SA_DQS_DN<7>")
	)
	(segment
		(start 408.168602 -282.503626)
		(end 407.622502 -282.503626)
		(width 0.18288)
		(layer "In4.Cu")
		(net "M_G_CPU0_SA_DQS_DN<7>")
	)
	(segment
		(start 435.631844 -292.944042)
		(end 435.363112 -292.67531)
		(width 0.18288)
		(layer "In4.Cu")
		(net "M_G_CPU0_SA_DQS_DN<7>")
	)
	(segment
		(start 437.590184 -293.254684)
		(end 437.044084 -293.254684)
		(width 0.18288)
		(layer "In4.Cu")
		(net "M_G_CPU0_SA_DQS_DN<7>")
	)
	(segment
		(start 408.782266 -284.202378)
		(end 408.782266 -283.11729)
		(width 0.18288)
		(layer "In4.Cu")
		(net "M_G_CPU0_SA_DQS_DN<7>")
	)
	(segment
		(start 426.66793 -292.47465)
		(end 426.008038 -291.814758)
		(width 0.18288)
		(layer "In4.Cu")
		(net "M_G_CPU0_SA_DQS_DN<7>")
	)
	(segment
		(start 432.707542 -292.403276)
		(end 432.583082 -292.527736)
		(width 0.18288)
		(layer "In4.Cu")
		(net "M_G_CPU0_SA_DQS_DN<7>")
	)
	(segment
		(start 414.537144 -289.778694)
		(end 414.15081 -289.39236)
		(width 0.18288)
		(layer "In4.Cu")
		(net "M_G_CPU0_SA_DQS_DN<7>")
	)
	(segment
		(start 412.871158 -288.112708)
		(end 412.871158 -287.936686)
		(width 0.18288)
		(layer "In4.Cu")
		(net "M_G_CPU0_SA_DQS_DN<7>")
	)
	(segment
		(start 436.275988 -292.683946)
		(end 436.015892 -292.944042)
		(width 0.18288)
		(layer "In4.Cu")
		(net "M_G_CPU0_SA_DQS_DN<7>")
	)
	(segment
		(start 416.033458 -290.55187)
		(end 415.099246 -290.164774)
		(width 0.18288)
		(layer "In4.Cu")
		(net "M_G_CPU0_SA_DQS_DN<7>")
	)
	(segment
		(start 422.620948 -292.310566)
		(end 422.11625 -292.519608)
		(width 0.18288)
		(layer "In4.Cu")
		(net "M_G_CPU0_SA_DQS_DN<7>")
	)
	(segment
		(start 415.099246 -290.164774)
		(end 414.713166 -289.778694)
		(width 0.18288)
		(layer "In4.Cu")
		(net "M_G_CPU0_SA_DQS_DN<7>")
	)
	(segment
		(start 431.912522 -292.403276)
		(end 431.366422 -292.403276)
		(width 0.18288)
		(layer "In4.Cu")
		(net "M_G_CPU0_SA_DQS_DN<7>")
	)
	(segment
		(start 414.15081 -289.39236)
		(end 414.15081 -289.216338)
		(width 0.18288)
		(layer "In4.Cu")
		(net "M_G_CPU0_SA_DQS_DN<7>")
	)
	(segment
		(start 380.377954 -265.164824)
		(end 380.366016 -265.314176)
		(width 0.088646)
		(layer "In4.Cu")
		(net "M_G_CPU0_SA_DQS_DN<7>")
	)
	(segment
		(start 380.831852 -265.107166)
		(end 380.440438 -265.107166)
		(width 0.088646)
		(layer "In4.Cu")
		(net "M_G_CPU0_SA_DQS_DN<7>")
	)
	(segment
		(start 428.158656 -292.019482)
		(end 427.703488 -292.47465)
		(width 0.18288)
		(layer "In4.Cu")
		(net "M_G_CPU0_SA_DQS_DN<7>")
	)
	(segment
		(start 409.701492 -285.332678)
		(end 409.368752 -285.140654)
		(width 0.18288)
		(layer "In4.Cu")
		(net "M_G_CPU0_SA_DQS_DN<7>")
	)
	(segment
		(start 424.344592 -291.806122)
		(end 423.513504 -291.806122)
		(width 0.18288)
		(layer "In4.Cu")
		(net "M_G_CPU0_SA_DQS_DN<7>")
	)
	(segment
		(start 425.045632 -292.09238)
		(end 424.63085 -292.09238)
		(width 0.18288)
		(layer "In4.Cu")
		(net "M_G_CPU0_SA_DQS_DN<7>")
	)
	(segment
		(start 392.480546 -268.231112)
		(end 390.994646 -267.615924)
		(width 0.18288)
		(layer "In4.Cu")
		(net "M_G_CPU0_SA_DQS_DN<7>")
	)
	(segment
		(start 390.762744 -267.519912)
		(end 388.479792 -265.23696)
		(width 0.18288)
		(layer "In4.Cu")
		(net "M_G_CPU0_SA_DQS_DN<7>")
	)
	(segment
		(start 439.068718 -293.254684)
		(end 438.385204 -293.254684)
		(width 0.18288)
		(layer "In4.Cu")
		(net "M_G_CPU0_SA_DQS_DN<7>")
	)
	(segment
		(start 434.019706 -292.527736)
		(end 433.473606 -292.527736)
		(width 0.18288)
		(layer "In4.Cu")
		(net "M_G_CPU0_SA_DQS_DN<7>")
	)
	(segment
		(start 394.170916 -268.231112)
		(end 392.480546 -268.231112)
		(width 0.18288)
		(layer "In4.Cu")
		(net "M_G_CPU0_SA_DQS_DN<7>")
	)
	(segment
		(start 432.036982 -292.527736)
		(end 431.912522 -292.403276)
		(width 0.18288)
		(layer "In4.Cu")
		(net "M_G_CPU0_SA_DQS_DN<7>")
	)
	(segment
		(start 384.327146 -264.998454)
		(end 384.312414 -264.989818)
		(width 0.088646)
		(layer "In4.Cu")
		(net "M_G_CPU0_SA_DQS_DN<7>")
	)
	(segment
		(start 409.270962 -284.776418)
		(end 409.064714 -284.691328)
		(width 0.18288)
		(layer "In4.Cu")
		(net "M_G_CPU0_SA_DQS_DN<7>")
	)
	(segment
		(start 438.260744 -293.379144)
		(end 437.714644 -293.379144)
		(width 0.18288)
		(layer "In4.Cu")
		(net "M_G_CPU0_SA_DQS_DN<7>")
	)
	(segment
		(start 436.015892 -292.944042)
		(end 435.631844 -292.944042)
		(width 0.18288)
		(layer "In4.Cu")
		(net "M_G_CPU0_SA_DQS_DN<7>")
	)
	(segment
		(start 433.473606 -292.527736)
		(end 433.349146 -292.403276)
		(width 0.18288)
		(layer "In4.Cu")
		(net "M_G_CPU0_SA_DQS_DN<7>")
	)
	(segment
		(start 422.11625 -292.519608)
		(end 421.95369 -292.452298)
		(width 0.18288)
		(layer "In4.Cu")
		(net "M_G_CPU0_SA_DQS_DN<7>")
	)
	(segment
		(start 385.252976 -264.99058)
		(end 385.251452 -264.989564)
		(width 0.088646)
		(layer "In4.Cu")
		(net "M_G_CPU0_SA_DQS_DN<7>")
	)
	(segment
		(start 413.257746 -288.499296)
		(end 412.871158 -288.112708)
		(width 0.18288)
		(layer "In4.Cu")
		(net "M_G_CPU0_SA_DQS_DN<7>")
	)
	(segment
		(start 383.387346 -264.998454)
		(end 383.372614 -264.989818)
		(width 0.088646)
		(layer "In4.Cu")
		(net "M_G_CPU0_SA_DQS_DN<7>")
	)
	(segment
		(start 402.55444 -276.61489)
		(end 402.554186 -276.614382)
		(width 0.18288)
		(layer "In4.Cu")
		(net "M_G_CPU0_SA_DQS_DN<7>")
	)
	(segment
		(start 435.02326 -292.67531)
		(end 434.751226 -292.403276)
		(width 0.18288)
		(layer "In4.Cu")
		(net "M_G_CPU0_SA_DQS_DN<7>")
	)
	(segment
		(start 432.583082 -292.527736)
		(end 432.036982 -292.527736)
		(width 0.18288)
		(layer "In4.Cu")
		(net "M_G_CPU0_SA_DQS_DN<7>")
	)
	(segment
		(start 385.584954 -265.17727)
		(end 385.252976 -264.99058)
		(width 0.088646)
		(layer "In4.Cu")
		(net "M_G_CPU0_SA_DQS_DN<7>")
	)
	(arc
		(start 381.49276 -264.989818)
		(mid 381.305562 -264.939675)
		(end 381.118364 -264.989818)
		(width 0.088646)
		(layer "In4.Cu")
		(net "M_G_CPU0_SA_DQS_DN<7>")
	)
	(arc
		(start 385.251452 -264.989564)
		(mid 385.064589 -264.939708)
		(end 384.877818 -264.989818)
		(width 0.088646)
		(layer "In4.Cu")
		(net "M_G_CPU0_SA_DQS_DN<7>")
	)
	(arc
		(start 382.058418 -264.989818)
		(mid 381.781605 -265.065688)
		(end 381.503174 -264.995914)
		(width 0.088646)
		(layer "In4.Cu")
		(net "M_G_CPU0_SA_DQS_DN<7>")
	)
	(arc
		(start 380.440438 -265.107166)
		(mid 380.397911 -265.123779)
		(end 380.377954 -265.164824)
		(width 0.088646)
		(layer "In4.Cu")
		(net "M_G_CPU0_SA_DQS_DN<7>")
	)
	(arc
		(start 382.432814 -264.989818)
		(mid 382.24815 -264.939558)
		(end 382.062736 -264.987024)
		(width 0.088646)
		(layer "In4.Cu")
		(net "M_G_CPU0_SA_DQS_DN<7>")
	)
	(arc
		(start 383.372614 -264.989818)
		(mid 383.185416 -264.939675)
		(end 382.998218 -264.989818)
		(width 0.088646)
		(layer "In4.Cu")
		(net "M_G_CPU0_SA_DQS_DN<7>")
	)
	(arc
		(start 383.938018 -264.989818)
		(mid 383.663819 -265.065653)
		(end 383.387346 -264.998454)
		(width 0.088646)
		(layer "In4.Cu")
		(net "M_G_CPU0_SA_DQS_DN<7>")
	)
	(arc
		(start 382.998218 -264.989818)
		(mid 382.724019 -265.065653)
		(end 382.447546 -264.998454)
		(width 0.088646)
		(layer "In4.Cu")
		(net "M_G_CPU0_SA_DQS_DN<7>")
	)
	(arc
		(start 384.877818 -264.989818)
		(mid 384.603619 -265.065653)
		(end 384.327146 -264.998454)
		(width 0.088646)
		(layer "In4.Cu")
		(net "M_G_CPU0_SA_DQS_DN<7>")
	)
	(arc
		(start 384.312414 -264.989818)
		(mid 384.125216 -264.939675)
		(end 383.938018 -264.989818)
		(width 0.088646)
		(layer "In4.Cu")
		(net "M_G_CPU0_SA_DQS_DN<7>")
	)
	(segment
		(start 447.814446 -302.462438)
		(end 448.0687 -302.716692)
		(width 0.20066)
		(layer "F.Cu")
		(net "M_G_CPU0_SA_DQS_DN<6>")
	)
	(segment
		(start 446.087246 -302.016922)
		(end 446.577212 -302.016922)
		(width 0.20066)
		(layer "F.Cu")
		(net "M_G_CPU0_SA_DQS_DN<6>")
	)
	(segment
		(start 445.471804 -302.29175)
		(end 445.482726 -302.302672)
		(width 0.1016)
		(layer "F.Cu")
		(net "M_G_CPU0_SA_DQS_DN<6>")
	)
	(segment
		(start 445.482726 -302.302672)
		(end 445.801496 -302.302672)
		(width 0.20066)
		(layer "F.Cu")
		(net "M_G_CPU0_SA_DQS_DN<6>")
	)
	(segment
		(start 441.83046 -302.44542)
		(end 442.313822 -302.44542)
		(width 0.20066)
		(layer "F.Cu")
		(net "M_G_CPU0_SA_DQS_DN<6>")
	)
	(segment
		(start 441.028582 -302.716692)
		(end 441.559188 -302.716692)
		(width 0.20066)
		(layer "F.Cu")
		(net "M_G_CPU0_SA_DQS_DN<6>")
	)
	(segment
		(start 377.076716 -272.103342)
		(end 377.076462 -272.639282)
		(width 0.20066)
		(layer "F.Cu")
		(net "M_G_CPU0_SA_DQS_DN<6>")
	)
	(segment
		(start 443.450726 -302.297846)
		(end 443.455552 -302.297846)
		(width 0.101854)
		(layer "F.Cu")
		(net "M_G_CPU0_SA_DQS_DN<6>")
	)
	(segment
		(start 448.0687 -302.716692)
		(end 448.572382 -302.716692)
		(width 0.20066)
		(layer "F.Cu")
		(net "M_G_CPU0_SA_DQS_DN<6>")
	)
	(segment
		(start 447.022728 -302.462438)
		(end 447.814446 -302.462438)
		(width 0.20066)
		(layer "F.Cu")
		(net "M_G_CPU0_SA_DQS_DN<6>")
	)
	(segment
		(start 446.577212 -302.016922)
		(end 447.022728 -302.462438)
		(width 0.20066)
		(layer "F.Cu")
		(net "M_G_CPU0_SA_DQS_DN<6>")
	)
	(segment
		(start 445.801496 -302.302672)
		(end 446.087246 -302.016922)
		(width 0.20066)
		(layer "F.Cu")
		(net "M_G_CPU0_SA_DQS_DN<6>")
	)
	(segment
		(start 443.455552 -302.297846)
		(end 443.461648 -302.29175)
		(width 0.1016)
		(layer "F.Cu")
		(net "M_G_CPU0_SA_DQS_DN<6>")
	)
	(segment
		(start 442.738764 -302.020478)
		(end 442.861192 -302.020478)
		(width 0.20066)
		(layer "F.Cu")
		(net "M_G_CPU0_SA_DQS_DN<6>")
	)
	(segment
		(start 441.559188 -302.716692)
		(end 441.83046 -302.44542)
		(width 0.20066)
		(layer "F.Cu")
		(net "M_G_CPU0_SA_DQS_DN<6>")
	)
	(segment
		(start 443.13856 -302.297846)
		(end 443.450726 -302.297846)
		(width 0.20066)
		(layer "F.Cu")
		(net "M_G_CPU0_SA_DQS_DN<6>")
	)
	(segment
		(start 442.313822 -302.44542)
		(end 442.738764 -302.020478)
		(width 0.20066)
		(layer "F.Cu")
		(net "M_G_CPU0_SA_DQS_DN<6>")
	)
	(segment
		(start 439.923682 -302.716692)
		(end 441.028582 -302.716692)
		(width 0.20066)
		(layer "F.Cu")
		(net "M_G_CPU0_SA_DQS_DN<6>")
	)
	(segment
		(start 442.861192 -302.020478)
		(end 443.13856 -302.297846)
		(width 0.20066)
		(layer "F.Cu")
		(net "M_G_CPU0_SA_DQS_DN<6>")
	)
	(segment
		(start 443.461648 -302.29175)
		(end 445.471804 -302.29175)
		(width 0.1016)
		(layer "F.Cu")
		(net "M_G_CPU0_SA_DQS_DN<6>")
	)
	(segment
		(start 418.055552 -295.23309)
		(end 417.931092 -295.35755)
		(width 0.18288)
		(layer "In6.Cu")
		(net "M_G_CPU0_SA_DQS_DN<6>")
	)
	(segment
		(start 422.674034 -296.069512)
		(end 421.815768 -295.211246)
		(width 0.18288)
		(layer "In6.Cu")
		(net "M_G_CPU0_SA_DQS_DN<6>")
	)
	(segment
		(start 436.91937 -302.004984)
		(end 436.323486 -302.004984)
		(width 0.18288)
		(layer "In6.Cu")
		(net "M_G_CPU0_SA_DQS_DN<6>")
	)
	(segment
		(start 409.954984 -292.658038)
		(end 409.406852 -292.658038)
		(width 0.18288)
		(layer "In6.Cu")
		(net "M_G_CPU0_SA_DQS_DN<6>")
	)
	(segment
		(start 438.960006 -302.600614)
		(end 437.515 -302.600614)
		(width 0.18288)
		(layer "In6.Cu")
		(net "M_G_CPU0_SA_DQS_DN<6>")
	)
	(segment
		(start 417.384992 -295.35755)
		(end 417.260532 -295.23309)
		(width 0.18288)
		(layer "In6.Cu")
		(net "M_G_CPU0_SA_DQS_DN<6>")
	)
	(segment
		(start 439.611008 -302.404018)
		(end 439.156602 -302.404018)
		(width 0.18288)
		(layer "In6.Cu")
		(net "M_G_CPU0_SA_DQS_DN<6>")
	)
	(segment
		(start 381.588264 -272.314924)
		(end 381.573532 -272.32356)
		(width 0.088646)
		(layer "In6.Cu")
		(net "M_G_CPU0_SA_DQS_DN<6>")
	)
	(segment
		(start 412.091124 -292.658038)
		(end 411.966664 -292.782498)
		(width 0.18288)
		(layer "In6.Cu")
		(net "M_G_CPU0_SA_DQS_DN<6>")
	)
	(segment
		(start 403.419564 -289.79876)
		(end 403.03323 -289.412426)
		(width 0.18288)
		(layer "In6.Cu")
		(net "M_G_CPU0_SA_DQS_DN<6>")
	)
	(segment
		(start 436.323486 -302.004984)
		(end 436.037736 -302.290734)
		(width 0.18288)
		(layer "In6.Cu")
		(net "M_G_CPU0_SA_DQS_DN<6>")
	)
	(segment
		(start 426.654468 -296.659046)
		(end 426.04309 -296.047668)
		(width 0.18288)
		(layer "In6.Cu")
		(net "M_G_CPU0_SA_DQS_DN<6>")
	)
	(segment
		(start 435.299866 -302.020732)
		(end 434.149754 -302.020732)
		(width 0.18288)
		(layer "In6.Cu")
		(net "M_G_CPU0_SA_DQS_DN<6>")
	)
	(segment
		(start 435.569868 -302.290734)
		(end 435.299866 -302.020732)
		(width 0.18288)
		(layer "In6.Cu")
		(net "M_G_CPU0_SA_DQS_DN<6>")
	)
	(segment
		(start 390.137904 -274.254976)
		(end 389.153654 -273.847306)
		(width 0.18288)
		(layer "In6.Cu")
		(net "M_G_CPU0_SA_DQS_DN<6>")
	)
	(segment
		(start 434.149754 -302.020732)
		(end 432.369468 -300.240446)
		(width 0.18288)
		(layer "In6.Cu")
		(net "M_G_CPU0_SA_DQS_DN<6>")
	)
	(segment
		(start 431.308256 -299.484034)
		(end 430.336198 -299.484034)
		(width 0.18288)
		(layer "In6.Cu")
		(net "M_G_CPU0_SA_DQS_DN<6>")
	)
	(segment
		(start 405.635714 -291.838888)
		(end 404.544022 -290.747196)
		(width 0.18288)
		(layer "In6.Cu")
		(net "M_G_CPU0_SA_DQS_DN<6>")
	)
	(segment
		(start 436.037736 -302.290734)
		(end 435.569868 -302.290734)
		(width 0.18288)
		(layer "In6.Cu")
		(net "M_G_CPU0_SA_DQS_DN<6>")
	)
	(segment
		(start 425.052998 -296.341038)
		(end 424.542712 -296.341038)
		(width 0.18288)
		(layer "In6.Cu")
		(net "M_G_CPU0_SA_DQS_DN<6>")
	)
	(segment
		(start 420.442644 -295.491154)
		(end 420.18458 -295.23309)
		(width 0.18288)
		(layer "In6.Cu")
		(net "M_G_CPU0_SA_DQS_DN<6>")
	)
	(segment
		(start 414.448752 -293.205408)
		(end 414.448752 -293.029386)
		(width 0.18288)
		(layer "In6.Cu")
		(net "M_G_CPU0_SA_DQS_DN<6>")
	)
	(segment
		(start 386.300726 -272.306796)
		(end 386.289042 -272.3134)
		(width 0.088646)
		(layer "In6.Cu")
		(net "M_G_CPU0_SA_DQS_DN<6>")
	)
	(segment
		(start 414.835086 -293.591742)
		(end 414.448752 -293.205408)
		(width 0.18288)
		(layer "In6.Cu")
		(net "M_G_CPU0_SA_DQS_DN<6>")
	)
	(segment
		(start 415.397188 -294.153844)
		(end 415.397188 -293.977822)
		(width 0.18288)
		(layer "In6.Cu")
		(net "M_G_CPU0_SA_DQS_DN<6>")
	)
	(segment
		(start 424.542712 -296.341038)
		(end 424.271186 -296.069512)
		(width 0.18288)
		(layer "In6.Cu")
		(net "M_G_CPU0_SA_DQS_DN<6>")
	)
	(segment
		(start 414.448752 -293.029386)
		(end 414.062672 -292.643306)
		(width 0.18288)
		(layer "In6.Cu")
		(net "M_G_CPU0_SA_DQS_DN<6>")
	)
	(segment
		(start 382.528064 -272.314924)
		(end 382.513332 -272.32356)
		(width 0.088646)
		(layer "In6.Cu")
		(net "M_G_CPU0_SA_DQS_DN<6>")
	)
	(segment
		(start 416.652456 -295.23309)
		(end 415.959544 -294.540178)
		(width 0.18288)
		(layer "In6.Cu")
		(net "M_G_CPU0_SA_DQS_DN<6>")
	)
	(segment
		(start 437.515 -302.600614)
		(end 436.91937 -302.004984)
		(width 0.18288)
		(layer "In6.Cu")
		(net "M_G_CPU0_SA_DQS_DN<6>")
	)
	(segment
		(start 415.959544 -294.540178)
		(end 415.783522 -294.540178)
		(width 0.18288)
		(layer "In6.Cu")
		(net "M_G_CPU0_SA_DQS_DN<6>")
	)
	(segment
		(start 377.13666 -272.43024)
		(end 377.13666 -272.429986)
		(width 0.088646)
		(layer "In6.Cu")
		(net "M_G_CPU0_SA_DQS_DN<6>")
	)
	(segment
		(start 417.260532 -295.23309)
		(end 416.652456 -295.23309)
		(width 0.18288)
		(layer "In6.Cu")
		(net "M_G_CPU0_SA_DQS_DN<6>")
	)
	(segment
		(start 415.783522 -294.540178)
		(end 415.397188 -294.153844)
		(width 0.18288)
		(layer "In6.Cu")
		(net "M_G_CPU0_SA_DQS_DN<6>")
	)
	(segment
		(start 413.66313 -292.643306)
		(end 413.358838 -292.947598)
		(width 0.18288)
		(layer "In6.Cu")
		(net "M_G_CPU0_SA_DQS_DN<6>")
	)
	(segment
		(start 388.11327 -273.787362)
		(end 386.692902 -272.366994)
		(width 0.088646)
		(layer "In6.Cu")
		(net "M_G_CPU0_SA_DQS_DN<6>")
	)
	(segment
		(start 378.768864 -272.314924)
		(end 378.754132 -272.32356)
		(width 0.088646)
		(layer "In6.Cu")
		(net "M_G_CPU0_SA_DQS_DN<6>")
	)
	(segment
		(start 417.931092 -295.35755)
		(end 417.384992 -295.35755)
		(width 0.18288)
		(layer "In6.Cu")
		(net "M_G_CPU0_SA_DQS_DN<6>")
	)
	(segment
		(start 432.369468 -300.240446)
		(end 432.064668 -300.240446)
		(width 0.18288)
		(layer "In6.Cu")
		(net "M_G_CPU0_SA_DQS_DN<6>")
	)
	(segment
		(start 413.358838 -292.947598)
		(end 412.926784 -292.947598)
		(width 0.18288)
		(layer "In6.Cu")
		(net "M_G_CPU0_SA_DQS_DN<6>")
	)
	(segment
		(start 388.535672 -273.847306)
		(end 388.512304 -273.847306)
		(width 0.088646)
		(layer "In6.Cu")
		(net "M_G_CPU0_SA_DQS_DN<6>")
	)
	(segment
		(start 406.370536 -291.963348)
		(end 406.246076 -291.838888)
		(width 0.18288)
		(layer "In6.Cu")
		(net "M_G_CPU0_SA_DQS_DN<6>")
	)
	(segment
		(start 384.407664 -272.314924)
		(end 384.392932 -272.32356)
		(width 0.088646)
		(layer "In6.Cu")
		(net "M_G_CPU0_SA_DQS_DN<6>")
	)
	(segment
		(start 377.572778 -272.406618)
		(end 377.572524 -272.407126)
		(width 0.088646)
		(layer "In6.Cu")
		(net "M_G_CPU0_SA_DQS_DN<6>")
	)
	(segment
		(start 411.966664 -292.782498)
		(end 411.420564 -292.782498)
		(width 0.18288)
		(layer "In6.Cu")
		(net "M_G_CPU0_SA_DQS_DN<6>")
	)
	(segment
		(start 404.544022 -290.747196)
		(end 404.368 -290.747196)
		(width 0.18288)
		(layer "In6.Cu")
		(net "M_G_CPU0_SA_DQS_DN<6>")
	)
	(segment
		(start 418.726112 -295.35755)
		(end 418.601652 -295.23309)
		(width 0.18288)
		(layer "In6.Cu")
		(net "M_G_CPU0_SA_DQS_DN<6>")
	)
	(segment
		(start 411.296104 -292.658038)
		(end 410.750004 -292.658038)
		(width 0.18288)
		(layer "In6.Cu")
		(net "M_G_CPU0_SA_DQS_DN<6>")
	)
	(segment
		(start 428.25416 -297.810936)
		(end 427.10227 -296.659046)
		(width 0.18288)
		(layer "In6.Cu")
		(net "M_G_CPU0_SA_DQS_DN<6>")
	)
	(segment
		(start 377.13666 -272.429986)
		(end 377.076462 -272.490184)
		(width 0.088646)
		(layer "In6.Cu")
		(net "M_G_CPU0_SA_DQS_DN<6>")
	)
	(segment
		(start 430.336198 -299.484034)
		(end 428.6631 -297.810936)
		(width 0.18288)
		(layer "In6.Cu")
		(net "M_G_CPU0_SA_DQS_DN<6>")
	)
	(segment
		(start 420.18458 -295.23309)
		(end 419.396672 -295.23309)
		(width 0.18288)
		(layer "In6.Cu")
		(net "M_G_CPU0_SA_DQS_DN<6>")
	)
	(segment
		(start 415.397188 -293.977822)
		(end 415.011108 -293.591742)
		(width 0.18288)
		(layer "In6.Cu")
		(net "M_G_CPU0_SA_DQS_DN<6>")
	)
	(segment
		(start 383.467864 -272.314924)
		(end 383.453132 -272.32356)
		(width 0.088646)
		(layer "In6.Cu")
		(net "M_G_CPU0_SA_DQS_DN<6>")
	)
	(segment
		(start 377.572524 -272.407126)
		(end 377.237244 -272.410174)
		(width 0.088646)
		(layer "In6.Cu")
		(net "M_G_CPU0_SA_DQS_DN<6>")
	)
	(segment
		(start 418.601652 -295.23309)
		(end 418.055552 -295.23309)
		(width 0.18288)
		(layer "In6.Cu")
		(net "M_G_CPU0_SA_DQS_DN<6>")
	)
	(segment
		(start 427.10227 -296.659046)
		(end 426.654468 -296.659046)
		(width 0.18288)
		(layer "In6.Cu")
		(net "M_G_CPU0_SA_DQS_DN<6>")
	)
	(segment
		(start 412.926784 -292.947598)
		(end 412.637224 -292.658038)
		(width 0.18288)
		(layer "In6.Cu")
		(net "M_G_CPU0_SA_DQS_DN<6>")
	)
	(segment
		(start 404.368 -290.747196)
		(end 403.981666 -290.360862)
		(width 0.18288)
		(layer "In6.Cu")
		(net "M_G_CPU0_SA_DQS_DN<6>")
	)
	(segment
		(start 428.6631 -297.810936)
		(end 428.25416 -297.810936)
		(width 0.18288)
		(layer "In6.Cu")
		(net "M_G_CPU0_SA_DQS_DN<6>")
	)
	(segment
		(start 420.95293 -295.491154)
		(end 420.442644 -295.491154)
		(width 0.18288)
		(layer "In6.Cu")
		(net "M_G_CPU0_SA_DQS_DN<6>")
	)
	(segment
		(start 380.093728 -272.32102)
		(end 380.083314 -272.314924)
		(width 0.088646)
		(layer "In6.Cu")
		(net "M_G_CPU0_SA_DQS_DN<6>")
	)
	(segment
		(start 410.750004 -292.658038)
		(end 410.625544 -292.782498)
		(width 0.18288)
		(layer "In6.Cu")
		(net "M_G_CPU0_SA_DQS_DN<6>")
	)
	(segment
		(start 377.076462 -272.490184)
		(end 377.076462 -272.639282)
		(width 0.088646)
		(layer "In6.Cu")
		(net "M_G_CPU0_SA_DQS_DN<6>")
	)
	(segment
		(start 403.03323 -289.412426)
		(end 403.03323 -289.236404)
		(width 0.18288)
		(layer "In6.Cu")
		(net "M_G_CPU0_SA_DQS_DN<6>")
	)
	(segment
		(start 396.129764 -274.254976)
		(end 390.137904 -274.254976)
		(width 0.18288)
		(layer "In6.Cu")
		(net "M_G_CPU0_SA_DQS_DN<6>")
	)
	(segment
		(start 439.156602 -302.404018)
		(end 438.960006 -302.600614)
		(width 0.18288)
		(layer "In6.Cu")
		(net "M_G_CPU0_SA_DQS_DN<6>")
	)
	(segment
		(start 407.430986 -291.838888)
		(end 407.041096 -291.838888)
		(width 0.18288)
		(layer "In6.Cu")
		(net "M_G_CPU0_SA_DQS_DN<6>")
	)
	(segment
		(start 410.625544 -292.782498)
		(end 410.079444 -292.782498)
		(width 0.18288)
		(layer "In6.Cu")
		(net "M_G_CPU0_SA_DQS_DN<6>")
	)
	(segment
		(start 424.271186 -296.069512)
		(end 422.674034 -296.069512)
		(width 0.18288)
		(layer "In6.Cu")
		(net "M_G_CPU0_SA_DQS_DN<6>")
	)
	(segment
		(start 415.011108 -293.591742)
		(end 414.835086 -293.591742)
		(width 0.18288)
		(layer "In6.Cu")
		(net "M_G_CPU0_SA_DQS_DN<6>")
	)
	(segment
		(start 403.981666 -290.360862)
		(end 403.981666 -290.18484)
		(width 0.18288)
		(layer "In6.Cu")
		(net "M_G_CPU0_SA_DQS_DN<6>")
	)
	(segment
		(start 407.041096 -291.838888)
		(end 406.916636 -291.963348)
		(width 0.18288)
		(layer "In6.Cu")
		(net "M_G_CPU0_SA_DQS_DN<6>")
	)
	(segment
		(start 414.062672 -292.643306)
		(end 413.66313 -292.643306)
		(width 0.18288)
		(layer "In6.Cu")
		(net "M_G_CPU0_SA_DQS_DN<6>")
	)
	(segment
		(start 406.916636 -291.963348)
		(end 406.370536 -291.963348)
		(width 0.18288)
		(layer "In6.Cu")
		(net "M_G_CPU0_SA_DQS_DN<6>")
	)
	(segment
		(start 378.203714 -272.315178)
		(end 378.20346 -272.314924)
		(width 0.088646)
		(layer "In6.Cu")
		(net "M_G_CPU0_SA_DQS_DN<6>")
	)
	(segment
		(start 410.079444 -292.782498)
		(end 409.954984 -292.658038)
		(width 0.18288)
		(layer "In6.Cu")
		(net "M_G_CPU0_SA_DQS_DN<6>")
	)
	(segment
		(start 412.637224 -292.658038)
		(end 412.091124 -292.658038)
		(width 0.18288)
		(layer "In6.Cu")
		(net "M_G_CPU0_SA_DQS_DN<6>")
	)
	(segment
		(start 425.346368 -296.047668)
		(end 425.052998 -296.341038)
		(width 0.18288)
		(layer "In6.Cu")
		(net "M_G_CPU0_SA_DQS_DN<6>")
	)
	(segment
		(start 388.512304 -273.847306)
		(end 388.45236 -273.787362)
		(width 0.088646)
		(layer "In6.Cu")
		(net "M_G_CPU0_SA_DQS_DN<6>")
	)
	(segment
		(start 432.064668 -300.240446)
		(end 431.308256 -299.484034)
		(width 0.18288)
		(layer "In6.Cu")
		(net "M_G_CPU0_SA_DQS_DN<6>")
	)
	(segment
		(start 409.406852 -292.658038)
		(end 407.430986 -291.838888)
		(width 0.18288)
		(layer "In6.Cu")
		(net "M_G_CPU0_SA_DQS_DN<6>")
	)
	(segment
		(start 377.236736 -272.410174)
		(end 377.13666 -272.43024)
		(width 0.088646)
		(layer "In6.Cu")
		(net "M_G_CPU0_SA_DQS_DN<6>")
	)
	(segment
		(start 411.420564 -292.782498)
		(end 411.296104 -292.658038)
		(width 0.18288)
		(layer "In6.Cu")
		(net "M_G_CPU0_SA_DQS_DN<6>")
	)
	(segment
		(start 419.396672 -295.23309)
		(end 419.272212 -295.35755)
		(width 0.18288)
		(layer "In6.Cu")
		(net "M_G_CPU0_SA_DQS_DN<6>")
	)
	(segment
		(start 419.272212 -295.35755)
		(end 418.726112 -295.35755)
		(width 0.18288)
		(layer "In6.Cu")
		(net "M_G_CPU0_SA_DQS_DN<6>")
	)
	(segment
		(start 402.64715 -280.772362)
		(end 396.129764 -274.254976)
		(width 0.18288)
		(layer "In6.Cu")
		(net "M_G_CPU0_SA_DQS_DN<6>")
	)
	(segment
		(start 389.153654 -273.847306)
		(end 388.535672 -273.847306)
		(width 0.18288)
		(layer "In6.Cu")
		(net "M_G_CPU0_SA_DQS_DN<6>")
	)
	(segment
		(start 377.829064 -272.314924)
		(end 377.664218 -272.40992)
		(width 0.088646)
		(layer "In6.Cu")
		(net "M_G_CPU0_SA_DQS_DN<6>")
	)
	(segment
		(start 439.923682 -302.716692)
		(end 439.611008 -302.404018)
		(width 0.18288)
		(layer "In6.Cu")
		(net "M_G_CPU0_SA_DQS_DN<6>")
	)
	(segment
		(start 406.246076 -291.838888)
		(end 405.635714 -291.838888)
		(width 0.18288)
		(layer "In6.Cu")
		(net "M_G_CPU0_SA_DQS_DN<6>")
	)
	(segment
		(start 403.981666 -290.18484)
		(end 403.595586 -289.79876)
		(width 0.18288)
		(layer "In6.Cu")
		(net "M_G_CPU0_SA_DQS_DN<6>")
	)
	(segment
		(start 403.595586 -289.79876)
		(end 403.419564 -289.79876)
		(width 0.18288)
		(layer "In6.Cu")
		(net "M_G_CPU0_SA_DQS_DN<6>")
	)
	(segment
		(start 385.347464 -272.314924)
		(end 385.332732 -272.32356)
		(width 0.088646)
		(layer "In6.Cu")
		(net "M_G_CPU0_SA_DQS_DN<6>")
	)
	(segment
		(start 402.64715 -288.850324)
		(end 402.64715 -280.772362)
		(width 0.18288)
		(layer "In6.Cu")
		(net "M_G_CPU0_SA_DQS_DN<6>")
	)
	(segment
		(start 388.45236 -273.787362)
		(end 388.11327 -273.787362)
		(width 0.088646)
		(layer "In6.Cu")
		(net "M_G_CPU0_SA_DQS_DN<6>")
	)
	(segment
		(start 421.232838 -295.211246)
		(end 420.95293 -295.491154)
		(width 0.18288)
		(layer "In6.Cu")
		(net "M_G_CPU0_SA_DQS_DN<6>")
	)
	(segment
		(start 386.287264 -272.314924)
		(end 386.272532 -272.32356)
		(width 0.088646)
		(layer "In6.Cu")
		(net "M_G_CPU0_SA_DQS_DN<6>")
	)
	(segment
		(start 426.04309 -296.047668)
		(end 425.346368 -296.047668)
		(width 0.18288)
		(layer "In6.Cu")
		(net "M_G_CPU0_SA_DQS_DN<6>")
	)
	(segment
		(start 386.289042 -272.3134)
		(end 386.288026 -272.313908)
		(width 0.088646)
		(layer "In6.Cu")
		(net "M_G_CPU0_SA_DQS_DN<6>")
	)
	(segment
		(start 421.815768 -295.211246)
		(end 421.232838 -295.211246)
		(width 0.18288)
		(layer "In6.Cu")
		(net "M_G_CPU0_SA_DQS_DN<6>")
	)
	(segment
		(start 403.03323 -289.236404)
		(end 402.64715 -288.850324)
		(width 0.18288)
		(layer "In6.Cu")
		(net "M_G_CPU0_SA_DQS_DN<6>")
	)
	(segment
		(start 377.664218 -272.40992)
		(end 377.572778 -272.406618)
		(width 0.088646)
		(layer "In6.Cu")
		(net "M_G_CPU0_SA_DQS_DN<6>")
	)
	(segment
		(start 379.708918 -272.314924)
		(end 379.698504 -272.32102)
		(width 0.088646)
		(layer "In6.Cu")
		(net "M_G_CPU0_SA_DQS_DN<6>")
	)
	(segment
		(start 377.237244 -272.410174)
		(end 377.236736 -272.410174)
		(width 0.088646)
		(layer "In6.Cu")
		(net "M_G_CPU0_SA_DQS_DN<6>")
	)
	(arc
		(start 381.96266 -272.314924)
		(mid 381.775462 -272.264781)
		(end 381.588264 -272.314924)
		(width 0.088646)
		(layer "In6.Cu")
		(net "M_G_CPU0_SA_DQS_DN<6>")
	)
	(arc
		(start 385.72186 -272.314924)
		(mid 385.534662 -272.264781)
		(end 385.347464 -272.314924)
		(width 0.088646)
		(layer "In6.Cu")
		(net "M_G_CPU0_SA_DQS_DN<6>")
	)
	(arc
		(start 379.14326 -272.314924)
		(mid 378.956062 -272.264781)
		(end 378.768864 -272.314924)
		(width 0.088646)
		(layer "In6.Cu")
		(net "M_G_CPU0_SA_DQS_DN<6>")
	)
	(arc
		(start 380.648464 -272.314924)
		(mid 380.371905 -272.390633)
		(end 380.093728 -272.32102)
		(width 0.088646)
		(layer "In6.Cu")
		(net "M_G_CPU0_SA_DQS_DN<6>")
	)
	(arc
		(start 383.84226 -272.314924)
		(mid 383.655062 -272.264781)
		(end 383.467864 -272.314924)
		(width 0.088646)
		(layer "In6.Cu")
		(net "M_G_CPU0_SA_DQS_DN<6>")
	)
	(arc
		(start 384.392932 -272.32356)
		(mid 384.116491 -272.390726)
		(end 383.84226 -272.314924)
		(width 0.088646)
		(layer "In6.Cu")
		(net "M_G_CPU0_SA_DQS_DN<6>")
	)
	(arc
		(start 378.754132 -272.32356)
		(mid 378.47783 -272.390852)
		(end 378.203714 -272.315178)
		(width 0.088646)
		(layer "In6.Cu")
		(net "M_G_CPU0_SA_DQS_DN<6>")
	)
	(arc
		(start 384.78206 -272.314924)
		(mid 384.594862 -272.264781)
		(end 384.407664 -272.314924)
		(width 0.088646)
		(layer "In6.Cu")
		(net "M_G_CPU0_SA_DQS_DN<6>")
	)
	(arc
		(start 380.083314 -272.314924)
		(mid 379.896116 -272.264781)
		(end 379.708918 -272.314924)
		(width 0.088646)
		(layer "In6.Cu")
		(net "M_G_CPU0_SA_DQS_DN<6>")
	)
	(arc
		(start 379.698504 -272.32102)
		(mid 379.420072 -272.390834)
		(end 379.14326 -272.314924)
		(width 0.088646)
		(layer "In6.Cu")
		(net "M_G_CPU0_SA_DQS_DN<6>")
	)
	(arc
		(start 382.513332 -272.32356)
		(mid 382.236891 -272.390726)
		(end 381.96266 -272.314924)
		(width 0.088646)
		(layer "In6.Cu")
		(net "M_G_CPU0_SA_DQS_DN<6>")
	)
	(arc
		(start 382.90246 -272.314924)
		(mid 382.715262 -272.264781)
		(end 382.528064 -272.314924)
		(width 0.088646)
		(layer "In6.Cu")
		(net "M_G_CPU0_SA_DQS_DN<6>")
	)
	(arc
		(start 378.20346 -272.314924)
		(mid 378.016262 -272.264781)
		(end 377.829064 -272.314924)
		(width 0.088646)
		(layer "In6.Cu")
		(net "M_G_CPU0_SA_DQS_DN<6>")
	)
	(arc
		(start 381.573532 -272.32356)
		(mid 381.297091 -272.390726)
		(end 381.02286 -272.314924)
		(width 0.088646)
		(layer "In6.Cu")
		(net "M_G_CPU0_SA_DQS_DN<6>")
	)
	(arc
		(start 383.453132 -272.32356)
		(mid 383.176691 -272.390726)
		(end 382.90246 -272.314924)
		(width 0.088646)
		(layer "In6.Cu")
		(net "M_G_CPU0_SA_DQS_DN<6>")
	)
	(arc
		(start 386.288026 -272.313908)
		(mid 386.287645 -272.314416)
		(end 386.287264 -272.314924)
		(width 0.088646)
		(layer "In6.Cu")
		(net "M_G_CPU0_SA_DQS_DN<6>")
	)
	(arc
		(start 386.692902 -272.366994)
		(mid 386.506684 -272.272772)
		(end 386.300726 -272.306796)
		(width 0.088646)
		(layer "In6.Cu")
		(net "M_G_CPU0_SA_DQS_DN<6>")
	)
	(arc
		(start 381.02286 -272.314924)
		(mid 380.835662 -272.264781)
		(end 380.648464 -272.314924)
		(width 0.088646)
		(layer "In6.Cu")
		(net "M_G_CPU0_SA_DQS_DN<6>")
	)
	(arc
		(start 386.272532 -272.32356)
		(mid 385.996091 -272.390726)
		(end 385.72186 -272.314924)
		(width 0.088646)
		(layer "In6.Cu")
		(net "M_G_CPU0_SA_DQS_DN<6>")
	)
	(arc
		(start 385.332732 -272.32356)
		(mid 385.056291 -272.390726)
		(end 384.78206 -272.314924)
		(width 0.088646)
		(layer "In6.Cu")
		(net "M_G_CPU0_SA_DQS_DN<6>")
	)
	(segment
		(start 446.087246 -311.366916)
		(end 446.577212 -311.366916)
		(width 0.20066)
		(layer "F.Cu")
		(net "M_G_CPU0_SA_DQS_DN<5>")
	)
	(segment
		(start 443.461648 -311.641744)
		(end 445.471804 -311.641744)
		(width 0.1016)
		(layer "F.Cu")
		(net "M_G_CPU0_SA_DQS_DN<5>")
	)
	(segment
		(start 380.365762 -274.54479)
		(end 380.366016 -274.545044)
		(width 0.20066)
		(layer "F.Cu")
		(net "M_G_CPU0_SA_DQS_DN<5>")
	)
	(segment
		(start 447.814446 -311.812432)
		(end 448.0687 -312.066686)
		(width 0.20066)
		(layer "F.Cu")
		(net "M_G_CPU0_SA_DQS_DN<5>")
	)
	(segment
		(start 447.022728 -311.812432)
		(end 447.814446 -311.812432)
		(width 0.20066)
		(layer "F.Cu")
		(net "M_G_CPU0_SA_DQS_DN<5>")
	)
	(segment
		(start 442.861192 -311.370472)
		(end 443.13856 -311.64784)
		(width 0.20066)
		(layer "F.Cu")
		(net "M_G_CPU0_SA_DQS_DN<5>")
	)
	(segment
		(start 441.83046 -311.795414)
		(end 442.313822 -311.795414)
		(width 0.20066)
		(layer "F.Cu")
		(net "M_G_CPU0_SA_DQS_DN<5>")
	)
	(segment
		(start 443.450726 -311.64784)
		(end 443.455552 -311.64784)
		(width 0.101854)
		(layer "F.Cu")
		(net "M_G_CPU0_SA_DQS_DN<5>")
	)
	(segment
		(start 441.028582 -312.066686)
		(end 441.559188 -312.066686)
		(width 0.20066)
		(layer "F.Cu")
		(net "M_G_CPU0_SA_DQS_DN<5>")
	)
	(segment
		(start 443.13856 -311.64784)
		(end 443.450726 -311.64784)
		(width 0.20066)
		(layer "F.Cu")
		(net "M_G_CPU0_SA_DQS_DN<5>")
	)
	(segment
		(start 445.801496 -311.652666)
		(end 446.087246 -311.366916)
		(width 0.20066)
		(layer "F.Cu")
		(net "M_G_CPU0_SA_DQS_DN<5>")
	)
	(segment
		(start 446.577212 -311.366916)
		(end 447.022728 -311.812432)
		(width 0.20066)
		(layer "F.Cu")
		(net "M_G_CPU0_SA_DQS_DN<5>")
	)
	(segment
		(start 445.471804 -311.641744)
		(end 445.482726 -311.652666)
		(width 0.1016)
		(layer "F.Cu")
		(net "M_G_CPU0_SA_DQS_DN<5>")
	)
	(segment
		(start 442.738764 -311.370472)
		(end 442.861192 -311.370472)
		(width 0.20066)
		(layer "F.Cu")
		(net "M_G_CPU0_SA_DQS_DN<5>")
	)
	(segment
		(start 448.0687 -312.066686)
		(end 448.572382 -312.066686)
		(width 0.20066)
		(layer "F.Cu")
		(net "M_G_CPU0_SA_DQS_DN<5>")
	)
	(segment
		(start 380.366016 -274.545044)
		(end 380.366016 -275.08073)
		(width 0.20066)
		(layer "F.Cu")
		(net "M_G_CPU0_SA_DQS_DN<5>")
	)
	(segment
		(start 441.559188 -312.066686)
		(end 441.83046 -311.795414)
		(width 0.20066)
		(layer "F.Cu")
		(net "M_G_CPU0_SA_DQS_DN<5>")
	)
	(segment
		(start 443.455552 -311.64784)
		(end 443.461648 -311.641744)
		(width 0.1016)
		(layer "F.Cu")
		(net "M_G_CPU0_SA_DQS_DN<5>")
	)
	(segment
		(start 442.313822 -311.795414)
		(end 442.738764 -311.370472)
		(width 0.20066)
		(layer "F.Cu")
		(net "M_G_CPU0_SA_DQS_DN<5>")
	)
	(segment
		(start 439.923682 -312.066686)
		(end 441.028582 -312.066686)
		(width 0.20066)
		(layer "F.Cu")
		(net "M_G_CPU0_SA_DQS_DN<5>")
	)
	(segment
		(start 445.482726 -311.652666)
		(end 445.801496 -311.652666)
		(width 0.20066)
		(layer "F.Cu")
		(net "M_G_CPU0_SA_DQS_DN<5>")
	)
	(segment
		(start 417.879784 -312.700924)
		(end 416.536124 -312.292746)
		(width 0.18288)
		(layer "In4.Cu")
		(net "M_G_CPU0_SA_DQS_DN<5>")
	)
	(segment
		(start 425.302426 -313.073542)
		(end 425.033948 -313.341766)
		(width 0.18288)
		(layer "In4.Cu")
		(net "M_G_CPU0_SA_DQS_DN<5>")
	)
	(segment
		(start 408.3685 -309.220108)
		(end 407.12771 -308.706266)
		(width 0.18288)
		(layer "In4.Cu")
		(net "M_G_CPU0_SA_DQS_DN<5>")
	)
	(segment
		(start 436.476648 -311.367932)
		(end 436.302658 -311.367932)
		(width 0.18288)
		(layer "In4.Cu")
		(net "M_G_CPU0_SA_DQS_DN<5>")
	)
	(segment
		(start 386.50037 -277.148798)
		(end 386.49529 -277.148544)
		(width 0.088646)
		(layer "In4.Cu")
		(net "M_G_CPU0_SA_DQS_DN<5>")
	)
	(segment
		(start 385.26085 -276.389338)
		(end 385.25196 -276.384258)
		(width 0.088646)
		(layer "In4.Cu")
		(net "M_G_CPU0_SA_DQS_DN<5>")
	)
	(segment
		(start 405.859742 -308.24297)
		(end 405.755094 -308.24297)
		(width 0.18288)
		(layer "In4.Cu")
		(net "M_G_CPU0_SA_DQS_DN<5>")
	)
	(segment
		(start 420.93007 -314.191904)
		(end 420.5351 -314.191904)
		(width 0.18288)
		(layer "In4.Cu")
		(net "M_G_CPU0_SA_DQS_DN<5>")
	)
	(segment
		(start 425.87164 -313.073542)
		(end 425.302426 -313.073542)
		(width 0.18288)
		(layer "In4.Cu")
		(net "M_G_CPU0_SA_DQS_DN<5>")
	)
	(segment
		(start 426.709332 -312.23585)
		(end 425.87164 -313.073542)
		(width 0.18288)
		(layer "In4.Cu")
		(net "M_G_CPU0_SA_DQS_DN<5>")
	)
	(segment
		(start 381.118364 -274.756372)
		(end 380.96317 -274.845526)
		(width 0.088646)
		(layer "In4.Cu")
		(net "M_G_CPU0_SA_DQS_DN<5>")
	)
	(segment
		(start 405.502872 -308.241192)
		(end 405.501094 -308.24297)
		(width 0.18288)
		(layer "In4.Cu")
		(net "M_G_CPU0_SA_DQS_DN<5>")
	)
	(segment
		(start 402.063204 -304.577496)
		(end 401.65528 -303.967134)
		(width 0.18288)
		(layer "In4.Cu")
		(net "M_G_CPU0_SA_DQS_DN<5>")
	)
	(segment
		(start 401.17903 -303.478438)
		(end 401.21332 -303.305972)
		(width 0.18288)
		(layer "In4.Cu")
		(net "M_G_CPU0_SA_DQS_DN<5>")
	)
	(segment
		(start 409.705048 -309.773828)
		(end 409.103322 -309.524654)
		(width 0.18288)
		(layer "In4.Cu")
		(net "M_G_CPU0_SA_DQS_DN<5>")
	)
	(segment
		(start 423.371264 -313.10326)
		(end 421.431466 -313.910472)
		(width 0.18288)
		(layer "In4.Cu")
		(net "M_G_CPU0_SA_DQS_DN<5>")
	)
	(segment
		(start 409.103322 -309.524654)
		(end 408.940762 -309.591964)
		(width 0.18288)
		(layer "In4.Cu")
		(net "M_G_CPU0_SA_DQS_DN<5>")
	)
	(segment
		(start 429.333152 -312.23585)
		(end 428.050452 -312.23585)
		(width 0.18288)
		(layer "In4.Cu")
		(net "M_G_CPU0_SA_DQS_DN<5>")
	)
	(segment
		(start 419.715188 -313.927236)
		(end 419.26129 -313.62396)
		(width 0.18288)
		(layer "In4.Cu")
		(net "M_G_CPU0_SA_DQS_DN<5>")
	)
	(segment
		(start 429.868584 -312.12917)
		(end 429.333152 -312.23585)
		(width 0.18288)
		(layer "In4.Cu")
		(net "M_G_CPU0_SA_DQS_DN<5>")
	)
	(segment
		(start 427.255432 -312.23585)
		(end 426.709332 -312.23585)
		(width 0.18288)
		(layer "In4.Cu")
		(net "M_G_CPU0_SA_DQS_DN<5>")
	)
	(segment
		(start 415.407348 -312.07075)
		(end 414.90265 -311.861708)
		(width 0.18288)
		(layer "In4.Cu")
		(net "M_G_CPU0_SA_DQS_DN<5>")
	)
	(segment
		(start 410.43987 -310.078374)
		(end 410.27731 -310.145684)
		(width 0.18288)
		(layer "In4.Cu")
		(net "M_G_CPU0_SA_DQS_DN<5>")
	)
	(segment
		(start 402.028914 -304.749962)
		(end 402.063204 -304.577496)
		(width 0.18288)
		(layer "In4.Cu")
		(net "M_G_CPU0_SA_DQS_DN<5>")
	)
	(segment
		(start 436.02783 -311.64276)
		(end 435.98846 -311.64276)
		(width 0.18288)
		(layer "In4.Cu")
		(net "M_G_CPU0_SA_DQS_DN<5>")
	)
	(segment
		(start 401.482814 -303.932844)
		(end 401.17903 -303.478438)
		(width 0.18288)
		(layer "In4.Cu")
		(net "M_G_CPU0_SA_DQS_DN<5>")
	)
	(segment
		(start 408.940762 -309.591964)
		(end 408.43581 -309.382922)
		(width 0.18288)
		(layer "In4.Cu")
		(net "M_G_CPU0_SA_DQS_DN<5>")
	)
	(segment
		(start 416.268916 -312.292746)
		(end 415.569908 -312.00344)
		(width 0.18288)
		(layer "In4.Cu")
		(net "M_G_CPU0_SA_DQS_DN<5>")
	)
	(segment
		(start 402.505164 -305.238658)
		(end 402.332444 -305.204368)
		(width 0.18288)
		(layer "In4.Cu")
		(net "M_G_CPU0_SA_DQS_DN<5>")
	)
	(segment
		(start 424.337734 -313.10326)
		(end 423.371264 -313.10326)
		(width 0.18288)
		(layer "In4.Cu")
		(net "M_G_CPU0_SA_DQS_DN<5>")
	)
	(segment
		(start 401.21332 -303.305464)
		(end 396.583154 -296.376852)
		(width 0.18288)
		(layer "In4.Cu")
		(net "M_G_CPU0_SA_DQS_DN<5>")
	)
	(segment
		(start 425.033948 -313.341766)
		(end 424.57624 -313.341766)
		(width 0.18288)
		(layer "In4.Cu")
		(net "M_G_CPU0_SA_DQS_DN<5>")
	)
	(segment
		(start 420.270432 -313.927236)
		(end 419.715188 -313.927236)
		(width 0.18288)
		(layer "In4.Cu")
		(net "M_G_CPU0_SA_DQS_DN<5>")
	)
	(segment
		(start 424.57624 -313.341766)
		(end 424.337734 -313.10326)
		(width 0.18288)
		(layer "In4.Cu")
		(net "M_G_CPU0_SA_DQS_DN<5>")
	)
	(segment
		(start 405.755094 -308.24297)
		(end 405.753316 -308.241192)
		(width 0.18288)
		(layer "In4.Cu")
		(net "M_G_CPU0_SA_DQS_DN<5>")
	)
	(segment
		(start 388.410704 -279.012142)
		(end 388.394194 -278.995632)
		(width 0.088646)
		(layer "In4.Cu")
		(net "M_G_CPU0_SA_DQS_DN<5>")
	)
	(segment
		(start 419.26129 -313.62396)
		(end 419.08857 -313.65825)
		(width 0.18288)
		(layer "In4.Cu")
		(net "M_G_CPU0_SA_DQS_DN<5>")
	)
	(segment
		(start 412.509208 -311.333896)
		(end 411.991048 -311.333896)
		(width 0.18288)
		(layer "In4.Cu")
		(net "M_G_CPU0_SA_DQS_DN<5>")
	)
	(segment
		(start 419.08857 -313.65825)
		(end 418.634418 -313.354466)
		(width 0.18288)
		(layer "In4.Cu")
		(net "M_G_CPU0_SA_DQS_DN<5>")
	)
	(segment
		(start 408.43581 -309.382922)
		(end 408.3685 -309.220108)
		(width 0.18288)
		(layer "In4.Cu")
		(net "M_G_CPU0_SA_DQS_DN<5>")
	)
	(segment
		(start 406.132538 -307.970174)
		(end 405.859742 -308.24297)
		(width 0.18288)
		(layer "In4.Cu")
		(net "M_G_CPU0_SA_DQS_DN<5>")
	)
	(segment
		(start 439.623708 -311.766712)
		(end 439.450226 -311.766712)
		(width 0.18288)
		(layer "In4.Cu")
		(net "M_G_CPU0_SA_DQS_DN<5>")
	)
	(segment
		(start 435.98846 -311.64276)
		(end 435.988206 -311.642506)
		(width 0.18288)
		(layer "In4.Cu")
		(net "M_G_CPU0_SA_DQS_DN<5>")
	)
	(segment
		(start 388.394194 -278.995632)
		(end 388.394194 -278.911304)
		(width 0.088646)
		(layer "In4.Cu")
		(net "M_G_CPU0_SA_DQS_DN<5>")
	)
	(segment
		(start 380.81331 -274.896072)
		(end 380.563882 -274.896072)
		(width 0.088646)
		(layer "In4.Cu")
		(net "M_G_CPU0_SA_DQS_DN<5>")
	)
	(segment
		(start 402.332444 -305.204368)
		(end 402.028914 -304.749962)
		(width 0.18288)
		(layer "In4.Cu")
		(net "M_G_CPU0_SA_DQS_DN<5>")
	)
	(segment
		(start 409.772612 -309.936642)
		(end 409.705048 -309.773828)
		(width 0.18288)
		(layer "In4.Cu")
		(net "M_G_CPU0_SA_DQS_DN<5>")
	)
	(segment
		(start 436.302658 -311.367932)
		(end 436.02783 -311.64276)
		(width 0.18288)
		(layer "In4.Cu")
		(net "M_G_CPU0_SA_DQS_DN<5>")
	)
	(segment
		(start 430.014888 -312.22696)
		(end 429.868584 -312.12917)
		(width 0.18288)
		(layer "In4.Cu")
		(net "M_G_CPU0_SA_DQS_DN<5>")
	)
	(segment
		(start 415.569908 -312.00344)
		(end 415.407348 -312.07075)
		(width 0.18288)
		(layer "In4.Cu")
		(net "M_G_CPU0_SA_DQS_DN<5>")
	)
	(segment
		(start 380.563882 -274.896072)
		(end 380.54153 -274.905216)
		(width 0.088646)
		(layer "In4.Cu")
		(net "M_G_CPU0_SA_DQS_DN<5>")
	)
	(segment
		(start 434.297582 -311.404508)
		(end 433.01158 -311.660286)
		(width 0.18288)
		(layer "In4.Cu")
		(net "M_G_CPU0_SA_DQS_DN<5>")
	)
	(segment
		(start 390.94156 -282.757118)
		(end 390.08304 -280.684732)
		(width 0.18288)
		(layer "In4.Cu")
		(net "M_G_CPU0_SA_DQS_DN<5>")
	)
	(segment
		(start 439.923682 -312.066686)
		(end 439.623708 -311.766712)
		(width 0.18288)
		(layer "In4.Cu")
		(net "M_G_CPU0_SA_DQS_DN<5>")
	)
	(segment
		(start 386.28701 -277.198074)
		(end 386.287264 -277.198074)
		(width 0.088646)
		(layer "In4.Cu")
		(net "M_G_CPU0_SA_DQS_DN<5>")
	)
	(segment
		(start 380.96317 -274.845526)
		(end 380.81331 -274.896072)
		(width 0.088646)
		(layer "In4.Cu")
		(net "M_G_CPU0_SA_DQS_DN<5>")
	)
	(segment
		(start 414.835086 -311.698894)
		(end 414.000442 -311.3532)
		(width 0.18288)
		(layer "In4.Cu")
		(net "M_G_CPU0_SA_DQS_DN<5>")
	)
	(segment
		(start 428.050452 -312.23585)
		(end 427.925992 -312.36031)
		(width 0.18288)
		(layer "In4.Cu")
		(net "M_G_CPU0_SA_DQS_DN<5>")
	)
	(segment
		(start 385.439412 -276.718522)
		(end 385.439412 -276.708616)
		(width 0.088646)
		(layer "In4.Cu")
		(net "M_G_CPU0_SA_DQS_DN<5>")
	)
	(segment
		(start 411.991048 -311.333896)
		(end 410.944314 -310.287162)
		(width 0.18288)
		(layer "In4.Cu")
		(net "M_G_CPU0_SA_DQS_DN<5>")
	)
	(segment
		(start 381.49276 -274.756372)
		(end 381.490728 -274.755102)
		(width 0.088646)
		(layer "In4.Cu")
		(net "M_G_CPU0_SA_DQS_DN<5>")
	)
	(segment
		(start 387.56717 -278.083772)
		(end 386.632196 -277.148798)
		(width 0.088646)
		(layer "In4.Cu")
		(net "M_G_CPU0_SA_DQS_DN<5>")
	)
	(segment
		(start 381.503174 -274.762468)
		(end 381.49276 -274.756372)
		(width 0.088646)
		(layer "In4.Cu")
		(net "M_G_CPU0_SA_DQS_DN<5>")
	)
	(segment
		(start 390.07669 -280.678128)
		(end 388.410704 -279.012142)
		(width 0.18288)
		(layer "In4.Cu")
		(net "M_G_CPU0_SA_DQS_DN<5>")
	)
	(segment
		(start 413.516064 -311.3532)
		(end 413.222694 -311.64657)
		(width 0.18288)
		(layer "In4.Cu")
		(net "M_G_CPU0_SA_DQS_DN<5>")
	)
	(segment
		(start 414.90265 -311.861708)
		(end 414.835086 -311.698894)
		(width 0.18288)
		(layer "In4.Cu")
		(net "M_G_CPU0_SA_DQS_DN<5>")
	)
	(segment
		(start 380.54153 -274.905216)
		(end 380.366016 -275.08073)
		(width 0.088646)
		(layer "In4.Cu")
		(net "M_G_CPU0_SA_DQS_DN<5>")
	)
	(segment
		(start 407.12771 -308.706266)
		(end 406.391618 -307.970174)
		(width 0.18288)
		(layer "In4.Cu")
		(net "M_G_CPU0_SA_DQS_DN<5>")
	)
	(segment
		(start 405.753316 -308.241192)
		(end 405.502872 -308.241192)
		(width 0.18288)
		(layer "In4.Cu")
		(net "M_G_CPU0_SA_DQS_DN<5>")
	)
	(segment
		(start 412.821882 -311.64657)
		(end 412.509208 -311.333896)
		(width 0.18288)
		(layer "In4.Cu")
		(net "M_G_CPU0_SA_DQS_DN<5>")
	)
	(segment
		(start 435.988206 -311.642506)
		(end 435.582822 -311.642506)
		(width 0.18288)
		(layer "In4.Cu")
		(net "M_G_CPU0_SA_DQS_DN<5>")
	)
	(segment
		(start 388.394194 -278.911304)
		(end 387.56717 -278.08428)
		(width 0.088646)
		(layer "In4.Cu")
		(net "M_G_CPU0_SA_DQS_DN<5>")
	)
	(segment
		(start 421.431466 -313.910472)
		(end 421.211502 -313.910472)
		(width 0.18288)
		(layer "In4.Cu")
		(net "M_G_CPU0_SA_DQS_DN<5>")
	)
	(segment
		(start 403.817836 -307.203094)
		(end 402.505164 -305.238658)
		(width 0.18288)
		(layer "In4.Cu")
		(net "M_G_CPU0_SA_DQS_DN<5>")
	)
	(segment
		(start 387.56717 -278.08428)
		(end 387.56717 -278.083772)
		(width 0.088646)
		(layer "In4.Cu")
		(net "M_G_CPU0_SA_DQS_DN<5>")
	)
	(segment
		(start 410.944314 -310.287162)
		(end 410.43987 -310.078374)
		(width 0.18288)
		(layer "In4.Cu")
		(net "M_G_CPU0_SA_DQS_DN<5>")
	)
	(segment
		(start 427.379892 -312.36031)
		(end 427.255432 -312.23585)
		(width 0.18288)
		(layer "In4.Cu")
		(net "M_G_CPU0_SA_DQS_DN<5>")
	)
	(segment
		(start 405.501094 -308.24297)
		(end 405.421592 -308.24297)
		(width 0.18288)
		(layer "In4.Cu")
		(net "M_G_CPU0_SA_DQS_DN<5>")
	)
	(segment
		(start 418.600128 -313.182254)
		(end 417.879784 -312.700924)
		(width 0.18288)
		(layer "In4.Cu")
		(net "M_G_CPU0_SA_DQS_DN<5>")
	)
	(segment
		(start 435.344824 -311.404508)
		(end 434.297582 -311.404508)
		(width 0.18288)
		(layer "In4.Cu")
		(net "M_G_CPU0_SA_DQS_DN<5>")
	)
	(segment
		(start 401.65528 -303.967134)
		(end 401.482814 -303.932844)
		(width 0.18288)
		(layer "In4.Cu")
		(net "M_G_CPU0_SA_DQS_DN<5>")
	)
	(segment
		(start 390.08304 -280.684732)
		(end 390.07669 -280.678128)
		(width 0.18288)
		(layer "In4.Cu")
		(net "M_G_CPU0_SA_DQS_DN<5>")
	)
	(segment
		(start 420.5351 -314.191904)
		(end 420.270432 -313.927236)
		(width 0.18288)
		(layer "In4.Cu")
		(net "M_G_CPU0_SA_DQS_DN<5>")
	)
	(segment
		(start 383.560066 -275.096478)
		(end 383.560066 -275.080984)
		(width 0.088646)
		(layer "In4.Cu")
		(net "M_G_CPU0_SA_DQS_DN<5>")
	)
	(segment
		(start 405.112982 -307.93436)
		(end 404.549102 -307.93436)
		(width 0.18288)
		(layer "In4.Cu")
		(net "M_G_CPU0_SA_DQS_DN<5>")
	)
	(segment
		(start 401.21332 -303.305972)
		(end 401.21332 -303.305464)
		(width 0.18288)
		(layer "In4.Cu")
		(net "M_G_CPU0_SA_DQS_DN<5>")
	)
	(segment
		(start 405.421592 -308.24297)
		(end 405.112982 -307.93436)
		(width 0.18288)
		(layer "In4.Cu")
		(net "M_G_CPU0_SA_DQS_DN<5>")
	)
	(segment
		(start 396.583154 -296.376852)
		(end 390.94156 -282.757118)
		(width 0.18288)
		(layer "In4.Cu")
		(net "M_G_CPU0_SA_DQS_DN<5>")
	)
	(segment
		(start 413.222694 -311.64657)
		(end 412.821882 -311.64657)
		(width 0.18288)
		(layer "In4.Cu")
		(net "M_G_CPU0_SA_DQS_DN<5>")
	)
	(segment
		(start 406.391618 -307.970174)
		(end 406.132538 -307.970174)
		(width 0.18288)
		(layer "In4.Cu")
		(net "M_G_CPU0_SA_DQS_DN<5>")
	)
	(segment
		(start 439.450226 -311.766712)
		(end 439.009282 -311.949338)
		(width 0.18288)
		(layer "In4.Cu")
		(net "M_G_CPU0_SA_DQS_DN<5>")
	)
	(segment
		(start 430.550828 -312.12028)
		(end 430.014888 -312.22696)
		(width 0.18288)
		(layer "In4.Cu")
		(net "M_G_CPU0_SA_DQS_DN<5>")
	)
	(segment
		(start 418.634418 -313.354466)
		(end 418.600128 -313.182254)
		(width 0.18288)
		(layer "In4.Cu")
		(net "M_G_CPU0_SA_DQS_DN<5>")
	)
	(segment
		(start 404.549102 -307.93436)
		(end 403.817836 -307.203094)
		(width 0.18288)
		(layer "In4.Cu")
		(net "M_G_CPU0_SA_DQS_DN<5>")
	)
	(segment
		(start 383.381504 -274.761706)
		(end 383.372614 -274.756626)
		(width 0.088646)
		(layer "In4.Cu")
		(net "M_G_CPU0_SA_DQS_DN<5>")
	)
	(segment
		(start 432.221894 -311.660286)
		(end 430.648618 -311.973722)
		(width 0.18288)
		(layer "In4.Cu")
		(net "M_G_CPU0_SA_DQS_DN<5>")
	)
	(segment
		(start 433.01158 -311.660286)
		(end 432.221894 -311.660286)
		(width 0.18288)
		(layer "In4.Cu")
		(net "M_G_CPU0_SA_DQS_DN<5>")
	)
	(segment
		(start 414.000442 -311.3532)
		(end 413.516064 -311.3532)
		(width 0.18288)
		(layer "In4.Cu")
		(net "M_G_CPU0_SA_DQS_DN<5>")
	)
	(segment
		(start 410.27731 -310.145684)
		(end 409.772612 -309.936642)
		(width 0.18288)
		(layer "In4.Cu")
		(net "M_G_CPU0_SA_DQS_DN<5>")
	)
	(segment
		(start 382.45288 -274.768056)
		(end 382.432814 -274.756372)
		(width 0.088646)
		(layer "In4.Cu")
		(net "M_G_CPU0_SA_DQS_DN<5>")
	)
	(segment
		(start 421.211502 -313.910472)
		(end 420.93007 -314.191904)
		(width 0.18288)
		(layer "In4.Cu")
		(net "M_G_CPU0_SA_DQS_DN<5>")
	)
	(segment
		(start 439.009282 -311.949338)
		(end 437.879236 -311.949338)
		(width 0.18288)
		(layer "In4.Cu")
		(net "M_G_CPU0_SA_DQS_DN<5>")
	)
	(segment
		(start 427.925992 -312.36031)
		(end 427.379892 -312.36031)
		(width 0.18288)
		(layer "In4.Cu")
		(net "M_G_CPU0_SA_DQS_DN<5>")
	)
	(segment
		(start 386.632196 -277.148798)
		(end 386.50037 -277.148798)
		(width 0.088646)
		(layer "In4.Cu")
		(net "M_G_CPU0_SA_DQS_DN<5>")
	)
	(segment
		(start 384.969512 -275.904706)
		(end 384.969512 -275.8948)
		(width 0.088646)
		(layer "In4.Cu")
		(net "M_G_CPU0_SA_DQS_DN<5>")
	)
	(segment
		(start 430.648618 -311.973722)
		(end 430.550828 -312.12028)
		(width 0.18288)
		(layer "In4.Cu")
		(net "M_G_CPU0_SA_DQS_DN<5>")
	)
	(segment
		(start 437.879236 -311.949338)
		(end 436.476648 -311.367932)
		(width 0.18288)
		(layer "In4.Cu")
		(net "M_G_CPU0_SA_DQS_DN<5>")
	)
	(segment
		(start 384.79095 -275.575522)
		(end 384.78206 -275.570442)
		(width 0.088646)
		(layer "In4.Cu")
		(net "M_G_CPU0_SA_DQS_DN<5>")
	)
	(segment
		(start 416.536124 -312.292746)
		(end 416.268916 -312.292746)
		(width 0.18288)
		(layer "In4.Cu")
		(net "M_G_CPU0_SA_DQS_DN<5>")
	)
	(segment
		(start 435.582822 -311.642506)
		(end 435.344824 -311.404508)
		(width 0.18288)
		(layer "In4.Cu")
		(net "M_G_CPU0_SA_DQS_DN<5>")
	)
	(segment
		(start 384.407664 -275.570442)
		(end 384.392932 -275.579078)
		(width 0.088646)
		(layer "In4.Cu")
		(net "M_G_CPU0_SA_DQS_DN<5>")
	)
	(arc
		(start 383.560066 -275.080984)
		(mid 383.512387 -274.898084)
		(end 383.381504 -274.761706)
		(width 0.088646)
		(layer "In4.Cu")
		(net "M_G_CPU0_SA_DQS_DN<5>")
	)
	(arc
		(start 383.372614 -274.756626)
		(mid 383.185416 -274.706483)
		(end 382.998218 -274.756626)
		(width 0.088646)
		(layer "In4.Cu")
		(net "M_G_CPU0_SA_DQS_DN<5>")
	)
	(arc
		(start 381.490728 -274.755102)
		(mid 381.304365 -274.706139)
		(end 381.118364 -274.756372)
		(width 0.088646)
		(layer "In4.Cu")
		(net "M_G_CPU0_SA_DQS_DN<5>")
	)
	(arc
		(start 386.49529 -277.148544)
		(mid 386.387539 -277.158117)
		(end 386.28701 -277.198074)
		(width 0.088646)
		(layer "In4.Cu")
		(net "M_G_CPU0_SA_DQS_DN<5>")
	)
	(arc
		(start 385.72186 -277.198074)
		(mid 385.517525 -276.995469)
		(end 385.439412 -276.718522)
		(width 0.088646)
		(layer "In4.Cu")
		(net "M_G_CPU0_SA_DQS_DN<5>")
	)
	(arc
		(start 382.058418 -274.756372)
		(mid 381.781605 -274.832242)
		(end 381.503174 -274.762468)
		(width 0.088646)
		(layer "In4.Cu")
		(net "M_G_CPU0_SA_DQS_DN<5>")
	)
	(arc
		(start 382.998218 -274.756626)
		(mid 382.727029 -274.832373)
		(end 382.45288 -274.768056)
		(width 0.088646)
		(layer "In4.Cu")
		(net "M_G_CPU0_SA_DQS_DN<5>")
	)
	(arc
		(start 384.392932 -275.579078)
		(mid 384.116457 -275.646398)
		(end 383.84226 -275.570442)
		(width 0.088646)
		(layer "In4.Cu")
		(net "M_G_CPU0_SA_DQS_DN<5>")
	)
	(arc
		(start 384.969512 -275.8948)
		(mid 384.921833 -275.7119)
		(end 384.79095 -275.575522)
		(width 0.088646)
		(layer "In4.Cu")
		(net "M_G_CPU0_SA_DQS_DN<5>")
	)
	(arc
		(start 385.25196 -276.384258)
		(mid 385.047625 -276.181653)
		(end 384.969512 -275.904706)
		(width 0.088646)
		(layer "In4.Cu")
		(net "M_G_CPU0_SA_DQS_DN<5>")
	)
	(arc
		(start 384.78206 -275.570442)
		(mid 384.594862 -275.520299)
		(end 384.407664 -275.570442)
		(width 0.088646)
		(layer "In4.Cu")
		(net "M_G_CPU0_SA_DQS_DN<5>")
	)
	(arc
		(start 386.287264 -277.198074)
		(mid 386.004562 -277.27385)
		(end 385.72186 -277.198074)
		(width 0.088646)
		(layer "In4.Cu")
		(net "M_G_CPU0_SA_DQS_DN<5>")
	)
	(arc
		(start 382.432814 -274.756372)
		(mid 382.245616 -274.706229)
		(end 382.058418 -274.756372)
		(width 0.088646)
		(layer "In4.Cu")
		(net "M_G_CPU0_SA_DQS_DN<5>")
	)
	(arc
		(start 385.439412 -276.708616)
		(mid 385.391733 -276.525716)
		(end 385.26085 -276.389338)
		(width 0.088646)
		(layer "In4.Cu")
		(net "M_G_CPU0_SA_DQS_DN<5>")
	)
	(arc
		(start 383.84226 -275.570442)
		(mid 383.639437 -275.370211)
		(end 383.560066 -275.096478)
		(width 0.088646)
		(layer "In4.Cu")
		(net "M_G_CPU0_SA_DQS_DN<5>")
	)
	(segment
		(start 375.197116 -262.87222)
		(end 375.196862 -262.872474)
		(width 0.20066)
		(layer "F.Cu")
		(net "M_G_CPU0_SA_DQS_DN<4>")
	)
	(segment
		(start 438.748424 -275.362924)
		(end 439.430922 -275.362924)
		(width 0.20066)
		(layer "F.Cu")
		(net "M_G_CPU0_SA_DQS_DN<4>")
	)
	(segment
		(start 437.75884 -274.948396)
		(end 438.333896 -274.948396)
		(width 0.20066)
		(layer "F.Cu")
		(net "M_G_CPU0_SA_DQS_DN<4>")
	)
	(segment
		(start 439.430922 -275.362924)
		(end 439.702194 -275.091652)
		(width 0.20066)
		(layer "F.Cu")
		(net "M_G_CPU0_SA_DQS_DN<4>")
	)
	(segment
		(start 442.899546 -275.317712)
		(end 443.31001 -274.907248)
		(width 0.20066)
		(layer "F.Cu")
		(net "M_G_CPU0_SA_DQS_DN<4>")
	)
	(segment
		(start 439.785252 -275.091652)
		(end 439.854086 -275.091652)
		(width 0.101854)
		(layer "F.Cu")
		(net "M_G_CPU0_SA_DQS_DN<4>")
	)
	(segment
		(start 442.21781 -275.091652)
		(end 442.368432 -275.091652)
		(width 0.20066)
		(layer "F.Cu")
		(net "M_G_CPU0_SA_DQS_DN<4>")
	)
	(segment
		(start 439.854086 -275.091652)
		(end 442.03366 -275.091652)
		(width 0.1016)
		(layer "F.Cu")
		(net "M_G_CPU0_SA_DQS_DN<4>")
	)
	(segment
		(start 443.642496 -274.907248)
		(end 443.883034 -274.66671)
		(width 0.20066)
		(layer "F.Cu")
		(net "M_G_CPU0_SA_DQS_DN<4>")
	)
	(segment
		(start 443.31001 -274.907248)
		(end 443.642496 -274.907248)
		(width 0.20066)
		(layer "F.Cu")
		(net "M_G_CPU0_SA_DQS_DN<4>")
	)
	(segment
		(start 436.928514 -274.66671)
		(end 437.477154 -274.66671)
		(width 0.20066)
		(layer "F.Cu")
		(net "M_G_CPU0_SA_DQS_DN<4>")
	)
	(segment
		(start 437.477154 -274.66671)
		(end 437.75884 -274.948396)
		(width 0.20066)
		(layer "F.Cu")
		(net "M_G_CPU0_SA_DQS_DN<4>")
	)
	(segment
		(start 439.702194 -275.091652)
		(end 439.785252 -275.091652)
		(width 0.20066)
		(layer "F.Cu")
		(net "M_G_CPU0_SA_DQS_DN<4>")
	)
	(segment
		(start 438.333896 -274.948396)
		(end 438.748424 -275.362924)
		(width 0.20066)
		(layer "F.Cu")
		(net "M_G_CPU0_SA_DQS_DN<4>")
	)
	(segment
		(start 442.03366 -275.091652)
		(end 442.21781 -275.091652)
		(width 0.101854)
		(layer "F.Cu")
		(net "M_G_CPU0_SA_DQS_DN<4>")
	)
	(segment
		(start 435.823614 -274.66671)
		(end 436.928514 -274.66671)
		(width 0.20066)
		(layer "F.Cu")
		(net "M_G_CPU0_SA_DQS_DN<4>")
	)
	(segment
		(start 442.594492 -275.317712)
		(end 442.899546 -275.317712)
		(width 0.20066)
		(layer "F.Cu")
		(net "M_G_CPU0_SA_DQS_DN<4>")
	)
	(segment
		(start 443.883034 -274.66671)
		(end 444.472314 -274.66671)
		(width 0.20066)
		(layer "F.Cu")
		(net "M_G_CPU0_SA_DQS_DN<4>")
	)
	(segment
		(start 375.197116 -262.336534)
		(end 375.197116 -262.87222)
		(width 0.20066)
		(layer "F.Cu")
		(net "M_G_CPU0_SA_DQS_DN<4>")
	)
	(segment
		(start 442.368432 -275.091652)
		(end 442.594492 -275.317712)
		(width 0.20066)
		(layer "F.Cu")
		(net "M_G_CPU0_SA_DQS_DN<4>")
	)
	(segment
		(start 433.965604 -274.664678)
		(end 432.923188 -273.622262)
		(width 0.18288)
		(layer "In6.Cu")
		(net "M_G_CPU0_SA_DQS_DN<4>")
	)
	(segment
		(start 381.588264 -263.196832)
		(end 381.573532 -263.188196)
		(width 0.088646)
		(layer "In6.Cu")
		(net "M_G_CPU0_SA_DQS_DN<4>")
	)
	(segment
		(start 430.054258 -270.135096)
		(end 430.178718 -270.010636)
		(width 0.18288)
		(layer "In6.Cu")
		(net "M_G_CPU0_SA_DQS_DN<4>")
	)
	(segment
		(start 417.332922 -265.14933)
		(end 415.385758 -264.34288)
		(width 0.18288)
		(layer "In6.Cu")
		(net "M_G_CPU0_SA_DQS_DN<4>")
	)
	(segment
		(start 390.779508 -262.342376)
		(end 388.535672 -262.342376)
		(width 0.18288)
		(layer "In6.Cu")
		(net "M_G_CPU0_SA_DQS_DN<4>")
	)
	(segment
		(start 430.178718 -271.724628)
		(end 430.178718 -271.178528)
		(width 0.18288)
		(layer "In6.Cu")
		(net "M_G_CPU0_SA_DQS_DN<4>")
	)
	(segment
		(start 430.23917 -272.622264)
		(end 430.054258 -272.437352)
		(width 0.18288)
		(layer "In6.Cu")
		(net "M_G_CPU0_SA_DQS_DN<4>")
	)
	(segment
		(start 420.219632 -265.14933)
		(end 417.332922 -265.14933)
		(width 0.18288)
		(layer "In6.Cu")
		(net "M_G_CPU0_SA_DQS_DN<4>")
	)
	(segment
		(start 425.353734 -265.990324)
		(end 425.105576 -265.742166)
		(width 0.18288)
		(layer "In6.Cu")
		(net "M_G_CPU0_SA_DQS_DN<4>")
	)
	(segment
		(start 431.130456 -272.622264)
		(end 430.23917 -272.622264)
		(width 0.18288)
		(layer "In6.Cu")
		(net "M_G_CPU0_SA_DQS_DN<4>")
	)
	(segment
		(start 430.054258 -271.054068)
		(end 430.054258 -270.135096)
		(width 0.18288)
		(layer "In6.Cu")
		(net "M_G_CPU0_SA_DQS_DN<4>")
	)
	(segment
		(start 429.50765 -266.976606)
		(end 429.121062 -266.590018)
		(width 0.18288)
		(layer "In6.Cu")
		(net "M_G_CPU0_SA_DQS_DN<4>")
	)
	(segment
		(start 405.31415 -264.295636)
		(end 403.84476 -262.826246)
		(width 0.18288)
		(layer "In6.Cu")
		(net "M_G_CPU0_SA_DQS_DN<4>")
	)
	(segment
		(start 426.004482 -265.990324)
		(end 425.353734 -265.990324)
		(width 0.18288)
		(layer "In6.Cu")
		(net "M_G_CPU0_SA_DQS_DN<4>")
	)
	(segment
		(start 421.958262 -265.14044)
		(end 421.253666 -265.14044)
		(width 0.18288)
		(layer "In6.Cu")
		(net "M_G_CPU0_SA_DQS_DN<4>")
	)
	(segment
		(start 425.105576 -265.742166)
		(end 424.576748 -265.742166)
		(width 0.18288)
		(layer "In6.Cu")
		(net "M_G_CPU0_SA_DQS_DN<4>")
	)
	(segment
		(start 393.211304 -262.826246)
		(end 390.779508 -262.342376)
		(width 0.18288)
		(layer "In6.Cu")
		(net "M_G_CPU0_SA_DQS_DN<4>")
	)
	(segment
		(start 427.310296 -266.612878)
		(end 426.627036 -266.612878)
		(width 0.18288)
		(layer "In6.Cu")
		(net "M_G_CPU0_SA_DQS_DN<4>")
	)
	(segment
		(start 412.890716 -264.34288)
		(end 412.20263 -265.030966)
		(width 0.18288)
		(layer "In6.Cu")
		(net "M_G_CPU0_SA_DQS_DN<4>")
	)
	(segment
		(start 374.884188 -262.872474)
		(end 375.196862 -262.872474)
		(width 0.088646)
		(layer "In6.Cu")
		(net "M_G_CPU0_SA_DQS_DN<4>")
	)
	(segment
		(start 424.576748 -265.742166)
		(end 424.298618 -266.020296)
		(width 0.18288)
		(layer "In6.Cu")
		(net "M_G_CPU0_SA_DQS_DN<4>")
	)
	(segment
		(start 429.121062 -266.590018)
		(end 428.94504 -266.590018)
		(width 0.18288)
		(layer "In6.Cu")
		(net "M_G_CPU0_SA_DQS_DN<4>")
	)
	(segment
		(start 379.708918 -263.196832)
		(end 379.698504 -263.190736)
		(width 0.088646)
		(layer "In6.Cu")
		(net "M_G_CPU0_SA_DQS_DN<4>")
	)
	(segment
		(start 430.054258 -272.437352)
		(end 430.054258 -271.849088)
		(width 0.18288)
		(layer "In6.Cu")
		(net "M_G_CPU0_SA_DQS_DN<4>")
	)
	(segment
		(start 430.054258 -271.849088)
		(end 430.178718 -271.724628)
		(width 0.18288)
		(layer "In6.Cu")
		(net "M_G_CPU0_SA_DQS_DN<4>")
	)
	(segment
		(start 426.627036 -266.612878)
		(end 426.004482 -265.990324)
		(width 0.18288)
		(layer "In6.Cu")
		(net "M_G_CPU0_SA_DQS_DN<4>")
	)
	(segment
		(start 430.054258 -267.699236)
		(end 429.50765 -267.152628)
		(width 0.18288)
		(layer "In6.Cu")
		(net "M_G_CPU0_SA_DQS_DN<4>")
	)
	(segment
		(start 387.701536 -263.119362)
		(end 387.701282 -263.119362)
		(width 0.088646)
		(layer "In6.Cu")
		(net "M_G_CPU0_SA_DQS_DN<4>")
	)
	(segment
		(start 386.676646 -263.188196)
		(end 386.661914 -263.196832)
		(width 0.088646)
		(layer "In6.Cu")
		(net "M_G_CPU0_SA_DQS_DN<4>")
	)
	(segment
		(start 388.535672 -262.342376)
		(end 388.512304 -262.342376)
		(width 0.088646)
		(layer "In6.Cu")
		(net "M_G_CPU0_SA_DQS_DN<4>")
	)
	(segment
		(start 387.904482 -262.916162)
		(end 387.701536 -263.119362)
		(width 0.088646)
		(layer "In6.Cu")
		(net "M_G_CPU0_SA_DQS_DN<4>")
	)
	(segment
		(start 378.768864 -263.196832)
		(end 378.754132 -263.188196)
		(width 0.088646)
		(layer "In6.Cu")
		(net "M_G_CPU0_SA_DQS_DN<4>")
	)
	(segment
		(start 428.4599 -266.104878)
		(end 427.818296 -266.104878)
		(width 0.18288)
		(layer "In6.Cu")
		(net "M_G_CPU0_SA_DQS_DN<4>")
	)
	(segment
		(start 435.158896 -274.91817)
		(end 434.905404 -274.664678)
		(width 0.18288)
		(layer "In6.Cu")
		(net "M_G_CPU0_SA_DQS_DN<4>")
	)
	(segment
		(start 388.032752 -262.60679)
		(end 387.904482 -262.916162)
		(width 0.088646)
		(layer "In6.Cu")
		(net "M_G_CPU0_SA_DQS_DN<4>")
	)
	(segment
		(start 385.732274 -263.190736)
		(end 385.72186 -263.196832)
		(width 0.088646)
		(layer "In6.Cu")
		(net "M_G_CPU0_SA_DQS_DN<4>")
	)
	(segment
		(start 430.178718 -271.178528)
		(end 430.054258 -271.054068)
		(width 0.18288)
		(layer "In6.Cu")
		(net "M_G_CPU0_SA_DQS_DN<4>")
	)
	(segment
		(start 424.298618 -266.020296)
		(end 422.838118 -266.020296)
		(width 0.18288)
		(layer "In6.Cu")
		(net "M_G_CPU0_SA_DQS_DN<4>")
	)
	(segment
		(start 380.648464 -263.196832)
		(end 380.63805 -263.190736)
		(width 0.088646)
		(layer "In6.Cu")
		(net "M_G_CPU0_SA_DQS_DN<4>")
	)
	(segment
		(start 430.054258 -269.340076)
		(end 430.054258 -267.699236)
		(width 0.18288)
		(layer "In6.Cu")
		(net "M_G_CPU0_SA_DQS_DN<4>")
	)
	(segment
		(start 415.385758 -264.34288)
		(end 412.890716 -264.34288)
		(width 0.18288)
		(layer "In6.Cu")
		(net "M_G_CPU0_SA_DQS_DN<4>")
	)
	(segment
		(start 434.905404 -274.664678)
		(end 433.965604 -274.664678)
		(width 0.18288)
		(layer "In6.Cu")
		(net "M_G_CPU0_SA_DQS_DN<4>")
	)
	(segment
		(start 388.23773 -262.402066)
		(end 388.032752 -262.60679)
		(width 0.088646)
		(layer "In6.Cu")
		(net "M_G_CPU0_SA_DQS_DN<4>")
	)
	(segment
		(start 432.130454 -273.622262)
		(end 431.130456 -272.622264)
		(width 0.18288)
		(layer "In6.Cu")
		(net "M_G_CPU0_SA_DQS_DN<4>")
	)
	(segment
		(start 430.178718 -270.010636)
		(end 430.178718 -269.464536)
		(width 0.18288)
		(layer "In6.Cu")
		(net "M_G_CPU0_SA_DQS_DN<4>")
	)
	(segment
		(start 388.512304 -262.342376)
		(end 388.452614 -262.402066)
		(width 0.088646)
		(layer "In6.Cu")
		(net "M_G_CPU0_SA_DQS_DN<4>")
	)
	(segment
		(start 375.949464 -263.196832)
		(end 375.934732 -263.188196)
		(width 0.088646)
		(layer "In6.Cu")
		(net "M_G_CPU0_SA_DQS_DN<4>")
	)
	(segment
		(start 429.50765 -267.152628)
		(end 429.50765 -266.976606)
		(width 0.18288)
		(layer "In6.Cu")
		(net "M_G_CPU0_SA_DQS_DN<4>")
	)
	(segment
		(start 427.818296 -266.104878)
		(end 427.310296 -266.612878)
		(width 0.18288)
		(layer "In6.Cu")
		(net "M_G_CPU0_SA_DQS_DN<4>")
	)
	(segment
		(start 421.005508 -264.892282)
		(end 420.47668 -264.892282)
		(width 0.18288)
		(layer "In6.Cu")
		(net "M_G_CPU0_SA_DQS_DN<4>")
	)
	(segment
		(start 403.84476 -262.826246)
		(end 393.211304 -262.826246)
		(width 0.18288)
		(layer "In6.Cu")
		(net "M_G_CPU0_SA_DQS_DN<4>")
	)
	(segment
		(start 428.94504 -266.590018)
		(end 428.4599 -266.104878)
		(width 0.18288)
		(layer "In6.Cu")
		(net "M_G_CPU0_SA_DQS_DN<4>")
	)
	(segment
		(start 412.20263 -265.030966)
		(end 408.850592 -265.030966)
		(width 0.18288)
		(layer "In6.Cu")
		(net "M_G_CPU0_SA_DQS_DN<4>")
	)
	(segment
		(start 376.889264 -263.196832)
		(end 376.874532 -263.188196)
		(width 0.088646)
		(layer "In6.Cu")
		(net "M_G_CPU0_SA_DQS_DN<4>")
	)
	(segment
		(start 435.823614 -274.66671)
		(end 435.571138 -274.91817)
		(width 0.18288)
		(layer "In6.Cu")
		(net "M_G_CPU0_SA_DQS_DN<4>")
	)
	(segment
		(start 388.452614 -262.402066)
		(end 388.23773 -262.402066)
		(width 0.088646)
		(layer "In6.Cu")
		(net "M_G_CPU0_SA_DQS_DN<4>")
	)
	(segment
		(start 374.826784 -262.929878)
		(end 374.884188 -262.872474)
		(width 0.088646)
		(layer "In6.Cu")
		(net "M_G_CPU0_SA_DQS_DN<4>")
	)
	(segment
		(start 421.253666 -265.14044)
		(end 421.005508 -264.892282)
		(width 0.18288)
		(layer "In6.Cu")
		(net "M_G_CPU0_SA_DQS_DN<4>")
	)
	(segment
		(start 408.115262 -264.295636)
		(end 405.31415 -264.295636)
		(width 0.18288)
		(layer "In6.Cu")
		(net "M_G_CPU0_SA_DQS_DN<4>")
	)
	(segment
		(start 387.61924 -263.186164)
		(end 387.618986 -263.186164)
		(width 0.088646)
		(layer "In6.Cu")
		(net "M_G_CPU0_SA_DQS_DN<4>")
	)
	(segment
		(start 382.528064 -263.196832)
		(end 382.513332 -263.188196)
		(width 0.088646)
		(layer "In6.Cu")
		(net "M_G_CPU0_SA_DQS_DN<4>")
	)
	(segment
		(start 420.47668 -264.892282)
		(end 420.219632 -265.14933)
		(width 0.18288)
		(layer "In6.Cu")
		(net "M_G_CPU0_SA_DQS_DN<4>")
	)
	(segment
		(start 435.571138 -274.91817)
		(end 435.158896 -274.91817)
		(width 0.18288)
		(layer "In6.Cu")
		(net "M_G_CPU0_SA_DQS_DN<4>")
	)
	(segment
		(start 430.178718 -269.464536)
		(end 430.054258 -269.340076)
		(width 0.18288)
		(layer "In6.Cu")
		(net "M_G_CPU0_SA_DQS_DN<4>")
	)
	(segment
		(start 408.850592 -265.030966)
		(end 408.115262 -264.295636)
		(width 0.18288)
		(layer "In6.Cu")
		(net "M_G_CPU0_SA_DQS_DN<4>")
	)
	(segment
		(start 422.838118 -266.020296)
		(end 421.958262 -265.14044)
		(width 0.18288)
		(layer "In6.Cu")
		(net "M_G_CPU0_SA_DQS_DN<4>")
	)
	(segment
		(start 432.923188 -273.622262)
		(end 432.130454 -273.622262)
		(width 0.18288)
		(layer "In6.Cu")
		(net "M_G_CPU0_SA_DQS_DN<4>")
	)
	(arc
		(start 387.227318 -263.196832)
		(mid 386.953089 -263.120907)
		(end 386.676646 -263.188196)
		(width 0.088646)
		(layer "In6.Cu")
		(net "M_G_CPU0_SA_DQS_DN<4>")
	)
	(arc
		(start 376.32386 -263.196832)
		(mid 376.136662 -263.246975)
		(end 375.949464 -263.196832)
		(width 0.088646)
		(layer "In6.Cu")
		(net "M_G_CPU0_SA_DQS_DN<4>")
	)
	(arc
		(start 384.407664 -263.196832)
		(mid 384.124962 -263.12109)
		(end 383.84226 -263.196832)
		(width 0.088646)
		(layer "In6.Cu")
		(net "M_G_CPU0_SA_DQS_DN<4>")
	)
	(arc
		(start 381.02286 -263.196832)
		(mid 380.835662 -263.246975)
		(end 380.648464 -263.196832)
		(width 0.088646)
		(layer "In6.Cu")
		(net "M_G_CPU0_SA_DQS_DN<4>")
	)
	(arc
		(start 376.874532 -263.188196)
		(mid 376.598091 -263.12103)
		(end 376.32386 -263.196832)
		(width 0.088646)
		(layer "In6.Cu")
		(net "M_G_CPU0_SA_DQS_DN<4>")
	)
	(arc
		(start 382.513332 -263.188196)
		(mid 382.236891 -263.12103)
		(end 381.96266 -263.196832)
		(width 0.088646)
		(layer "In6.Cu")
		(net "M_G_CPU0_SA_DQS_DN<4>")
	)
	(arc
		(start 381.573532 -263.188196)
		(mid 381.297091 -263.12103)
		(end 381.02286 -263.196832)
		(width 0.088646)
		(layer "In6.Cu")
		(net "M_G_CPU0_SA_DQS_DN<4>")
	)
	(arc
		(start 386.661914 -263.196832)
		(mid 386.474716 -263.246975)
		(end 386.287518 -263.196832)
		(width 0.088646)
		(layer "In6.Cu")
		(net "M_G_CPU0_SA_DQS_DN<4>")
	)
	(arc
		(start 378.20346 -263.196832)
		(mid 378.016262 -263.246975)
		(end 377.829064 -263.196832)
		(width 0.088646)
		(layer "In6.Cu")
		(net "M_G_CPU0_SA_DQS_DN<4>")
	)
	(arc
		(start 385.347464 -263.196832)
		(mid 385.064762 -263.12109)
		(end 384.78206 -263.196832)
		(width 0.088646)
		(layer "In6.Cu")
		(net "M_G_CPU0_SA_DQS_DN<4>")
	)
	(arc
		(start 377.829064 -263.196832)
		(mid 377.546362 -263.12109)
		(end 377.26366 -263.196832)
		(width 0.088646)
		(layer "In6.Cu")
		(net "M_G_CPU0_SA_DQS_DN<4>")
	)
	(arc
		(start 386.287518 -263.196832)
		(mid 386.010705 -263.120996)
		(end 385.732274 -263.190736)
		(width 0.088646)
		(layer "In6.Cu")
		(net "M_G_CPU0_SA_DQS_DN<4>")
	)
	(arc
		(start 379.698504 -263.190736)
		(mid 379.420072 -263.120922)
		(end 379.14326 -263.196832)
		(width 0.088646)
		(layer "In6.Cu")
		(net "M_G_CPU0_SA_DQS_DN<4>")
	)
	(arc
		(start 380.083314 -263.196832)
		(mid 379.896116 -263.246975)
		(end 379.708918 -263.196832)
		(width 0.088646)
		(layer "In6.Cu")
		(net "M_G_CPU0_SA_DQS_DN<4>")
	)
	(arc
		(start 384.78206 -263.196832)
		(mid 384.594862 -263.246975)
		(end 384.407664 -263.196832)
		(width 0.088646)
		(layer "In6.Cu")
		(net "M_G_CPU0_SA_DQS_DN<4>")
	)
	(arc
		(start 375.38406 -263.196832)
		(mid 375.035068 -263.210222)
		(end 374.826784 -262.929878)
		(width 0.088646)
		(layer "In6.Cu")
		(net "M_G_CPU0_SA_DQS_DN<4>")
	)
	(arc
		(start 375.934732 -263.188196)
		(mid 375.658291 -263.12103)
		(end 375.38406 -263.196832)
		(width 0.088646)
		(layer "In6.Cu")
		(net "M_G_CPU0_SA_DQS_DN<4>")
	)
	(arc
		(start 377.26366 -263.196832)
		(mid 377.076462 -263.246975)
		(end 376.889264 -263.196832)
		(width 0.088646)
		(layer "In6.Cu")
		(net "M_G_CPU0_SA_DQS_DN<4>")
	)
	(arc
		(start 379.14326 -263.196832)
		(mid 378.956062 -263.246975)
		(end 378.768864 -263.196832)
		(width 0.088646)
		(layer "In6.Cu")
		(net "M_G_CPU0_SA_DQS_DN<4>")
	)
	(arc
		(start 385.72186 -263.196832)
		(mid 385.534662 -263.246975)
		(end 385.347464 -263.196832)
		(width 0.088646)
		(layer "In6.Cu")
		(net "M_G_CPU0_SA_DQS_DN<4>")
	)
	(arc
		(start 382.90246 -263.196832)
		(mid 382.715262 -263.246975)
		(end 382.528064 -263.196832)
		(width 0.088646)
		(layer "In6.Cu")
		(net "M_G_CPU0_SA_DQS_DN<4>")
	)
	(arc
		(start 387.701282 -263.119362)
		(mid 387.662012 -263.154913)
		(end 387.61924 -263.186164)
		(width 0.088646)
		(layer "In6.Cu")
		(net "M_G_CPU0_SA_DQS_DN<4>")
	)
	(arc
		(start 387.601714 -263.196832)
		(mid 387.414516 -263.246975)
		(end 387.227318 -263.196832)
		(width 0.088646)
		(layer "In6.Cu")
		(net "M_G_CPU0_SA_DQS_DN<4>")
	)
	(arc
		(start 383.84226 -263.196832)
		(mid 383.655062 -263.246975)
		(end 383.467864 -263.196832)
		(width 0.088646)
		(layer "In6.Cu")
		(net "M_G_CPU0_SA_DQS_DN<4>")
	)
	(arc
		(start 378.754132 -263.188196)
		(mid 378.477691 -263.12103)
		(end 378.20346 -263.196832)
		(width 0.088646)
		(layer "In6.Cu")
		(net "M_G_CPU0_SA_DQS_DN<4>")
	)
	(arc
		(start 387.618986 -263.186164)
		(mid 387.610424 -263.191617)
		(end 387.601714 -263.196832)
		(width 0.088646)
		(layer "In6.Cu")
		(net "M_G_CPU0_SA_DQS_DN<4>")
	)
	(arc
		(start 381.96266 -263.196832)
		(mid 381.775462 -263.246975)
		(end 381.588264 -263.196832)
		(width 0.088646)
		(layer "In6.Cu")
		(net "M_G_CPU0_SA_DQS_DN<4>")
	)
	(arc
		(start 383.467864 -263.196832)
		(mid 383.185162 -263.12109)
		(end 382.90246 -263.196832)
		(width 0.088646)
		(layer "In6.Cu")
		(net "M_G_CPU0_SA_DQS_DN<4>")
	)
	(arc
		(start 380.63805 -263.190736)
		(mid 380.359872 -263.121044)
		(end 380.083314 -263.196832)
		(width 0.088646)
		(layer "In6.Cu")
		(net "M_G_CPU0_SA_DQS_DN<4>")
	)
	(segment
		(start 442.363098 -284.436312)
		(end 442.594492 -284.667706)
		(width 0.20066)
		(layer "F.Cu")
		(net "M_G_CPU0_SA_DQS_DN<3>")
	)
	(segment
		(start 442.038994 -284.436312)
		(end 442.363098 -284.436312)
		(width 0.20066)
		(layer "F.Cu")
		(net "M_G_CPU0_SA_DQS_DN<3>")
	)
	(segment
		(start 435.823614 -284.016704)
		(end 436.928514 -284.016704)
		(width 0.20066)
		(layer "F.Cu")
		(net "M_G_CPU0_SA_DQS_DN<3>")
	)
	(segment
		(start 439.702194 -284.441646)
		(end 439.849768 -284.441646)
		(width 0.20066)
		(layer "F.Cu")
		(net "M_G_CPU0_SA_DQS_DN<3>")
	)
	(segment
		(start 439.849768 -284.441646)
		(end 439.854086 -284.441646)
		(width 0.101854)
		(layer "F.Cu")
		(net "M_G_CPU0_SA_DQS_DN<3>")
	)
	(segment
		(start 443.642496 -284.257242)
		(end 443.883034 -284.016704)
		(width 0.20066)
		(layer "F.Cu")
		(net "M_G_CPU0_SA_DQS_DN<3>")
	)
	(segment
		(start 443.31001 -284.257242)
		(end 443.642496 -284.257242)
		(width 0.20066)
		(layer "F.Cu")
		(net "M_G_CPU0_SA_DQS_DN<3>")
	)
	(segment
		(start 439.854086 -284.441646)
		(end 442.03366 -284.441646)
		(width 0.1016)
		(layer "F.Cu")
		(net "M_G_CPU0_SA_DQS_DN<3>")
	)
	(segment
		(start 437.477154 -284.016704)
		(end 437.75884 -284.29839)
		(width 0.20066)
		(layer "F.Cu")
		(net "M_G_CPU0_SA_DQS_DN<3>")
	)
	(segment
		(start 439.430922 -284.712918)
		(end 439.702194 -284.441646)
		(width 0.20066)
		(layer "F.Cu")
		(net "M_G_CPU0_SA_DQS_DN<3>")
	)
	(segment
		(start 442.594492 -284.667706)
		(end 442.899546 -284.667706)
		(width 0.20066)
		(layer "F.Cu")
		(net "M_G_CPU0_SA_DQS_DN<3>")
	)
	(segment
		(start 375.197116 -267.219938)
		(end 375.196862 -267.220192)
		(width 0.20066)
		(layer "F.Cu")
		(net "M_G_CPU0_SA_DQS_DN<3>")
	)
	(segment
		(start 438.909206 -284.712918)
		(end 439.430922 -284.712918)
		(width 0.20066)
		(layer "F.Cu")
		(net "M_G_CPU0_SA_DQS_DN<3>")
	)
	(segment
		(start 437.75884 -284.29839)
		(end 438.494678 -284.29839)
		(width 0.20066)
		(layer "F.Cu")
		(net "M_G_CPU0_SA_DQS_DN<3>")
	)
	(segment
		(start 436.928514 -284.016704)
		(end 437.477154 -284.016704)
		(width 0.20066)
		(layer "F.Cu")
		(net "M_G_CPU0_SA_DQS_DN<3>")
	)
	(segment
		(start 375.196862 -267.220192)
		(end 375.196862 -267.755878)
		(width 0.20066)
		(layer "F.Cu")
		(net "M_G_CPU0_SA_DQS_DN<3>")
	)
	(segment
		(start 442.899546 -284.667706)
		(end 443.31001 -284.257242)
		(width 0.20066)
		(layer "F.Cu")
		(net "M_G_CPU0_SA_DQS_DN<3>")
	)
	(segment
		(start 442.03366 -284.441646)
		(end 442.038994 -284.436312)
		(width 0.1016)
		(layer "F.Cu")
		(net "M_G_CPU0_SA_DQS_DN<3>")
	)
	(segment
		(start 438.494678 -284.29839)
		(end 438.909206 -284.712918)
		(width 0.20066)
		(layer "F.Cu")
		(net "M_G_CPU0_SA_DQS_DN<3>")
	)
	(segment
		(start 443.883034 -284.016704)
		(end 444.472314 -284.016704)
		(width 0.20066)
		(layer "F.Cu")
		(net "M_G_CPU0_SA_DQS_DN<3>")
	)
	(segment
		(start 388.512304 -268.285722)
		(end 388.452614 -268.345412)
		(width 0.088646)
		(layer "In6.Cu")
		(net "M_G_CPU0_SA_DQS_DN<3>")
	)
	(segment
		(start 419.398196 -279.592532)
		(end 418.9476 -279.141936)
		(width 0.18288)
		(layer "In6.Cu")
		(net "M_G_CPU0_SA_DQS_DN<3>")
	)
	(segment
		(start 432.512216 -283.966158)
		(end 432.387756 -284.090618)
		(width 0.18288)
		(layer "In6.Cu")
		(net "M_G_CPU0_SA_DQS_DN<3>")
	)
	(segment
		(start 422.39057 -280.226008)
		(end 421.755316 -279.590754)
		(width 0.18288)
		(layer "In6.Cu")
		(net "M_G_CPU0_SA_DQS_DN<3>")
	)
	(segment
		(start 428.488856 -283.966158)
		(end 428.364396 -284.090618)
		(width 0.18288)
		(layer "In6.Cu")
		(net "M_G_CPU0_SA_DQS_DN<3>")
	)
	(segment
		(start 406.116536 -275.607272)
		(end 405.559006 -275.607272)
		(width 0.18288)
		(layer "In6.Cu")
		(net "M_G_CPU0_SA_DQS_DN<3>")
	)
	(segment
		(start 426.578776 -284.090618)
		(end 425.978828 -284.690566)
		(width 0.18288)
		(layer "In6.Cu")
		(net "M_G_CPU0_SA_DQS_DN<3>")
	)
	(segment
		(start 421.253666 -279.590754)
		(end 421.005508 -279.342596)
		(width 0.18288)
		(layer "In6.Cu")
		(net "M_G_CPU0_SA_DQS_DN<3>")
	)
	(segment
		(start 390.15416 -268.285722)
		(end 388.535672 -268.285722)
		(width 0.18288)
		(layer "In6.Cu")
		(net "M_G_CPU0_SA_DQS_DN<3>")
	)
	(segment
		(start 376.36831 -268.05509)
		(end 376.324368 -268.080236)
		(width 0.088646)
		(layer "In6.Cu")
		(net "M_G_CPU0_SA_DQS_DN<3>")
	)
	(segment
		(start 388.535672 -268.285722)
		(end 388.512304 -268.285722)
		(width 0.088646)
		(layer "In6.Cu")
		(net "M_G_CPU0_SA_DQS_DN<3>")
	)
	(segment
		(start 431.046636 -284.090618)
		(end 430.500536 -284.090618)
		(width 0.18288)
		(layer "In6.Cu")
		(net "M_G_CPU0_SA_DQS_DN<3>")
	)
	(segment
		(start 405.559006 -275.607272)
		(end 398.761966 -268.810232)
		(width 0.18288)
		(layer "In6.Cu")
		(net "M_G_CPU0_SA_DQS_DN<3>")
	)
	(segment
		(start 415.153094 -276.712426)
		(end 414.606994 -276.712426)
		(width 0.18288)
		(layer "In6.Cu")
		(net "M_G_CPU0_SA_DQS_DN<3>")
	)
	(segment
		(start 433.182776 -284.090618)
		(end 433.058316 -283.966158)
		(width 0.18288)
		(layer "In6.Cu")
		(net "M_G_CPU0_SA_DQS_DN<3>")
	)
	(segment
		(start 429.159416 -284.090618)
		(end 429.034956 -283.966158)
		(width 0.18288)
		(layer "In6.Cu")
		(net "M_G_CPU0_SA_DQS_DN<3>")
	)
	(segment
		(start 435.069996 -284.090618)
		(end 434.523896 -284.090618)
		(width 0.18288)
		(layer "In6.Cu")
		(net "M_G_CPU0_SA_DQS_DN<3>")
	)
	(segment
		(start 425.353734 -284.690566)
		(end 425.105576 -284.442408)
		(width 0.18288)
		(layer "In6.Cu")
		(net "M_G_CPU0_SA_DQS_DN<3>")
	)
	(segment
		(start 431.171096 -283.966158)
		(end 431.046636 -284.090618)
		(width 0.18288)
		(layer "In6.Cu")
		(net "M_G_CPU0_SA_DQS_DN<3>")
	)
	(segment
		(start 429.034956 -283.966158)
		(end 428.488856 -283.966158)
		(width 0.18288)
		(layer "In6.Cu")
		(net "M_G_CPU0_SA_DQS_DN<3>")
	)
	(segment
		(start 423.767758 -284.715204)
		(end 422.39057 -283.338016)
		(width 0.18288)
		(layer "In6.Cu")
		(net "M_G_CPU0_SA_DQS_DN<3>")
	)
	(segment
		(start 418.561012 -278.579326)
		(end 418.385244 -278.579326)
		(width 0.18288)
		(layer "In6.Cu")
		(net "M_G_CPU0_SA_DQS_DN<3>")
	)
	(segment
		(start 411.20695 -276.115272)
		(end 411.08249 -275.990812)
		(width 0.18288)
		(layer "In6.Cu")
		(net "M_G_CPU0_SA_DQS_DN<3>")
	)
	(segment
		(start 424.576748 -284.442408)
		(end 424.303952 -284.715204)
		(width 0.18288)
		(layer "In6.Cu")
		(net "M_G_CPU0_SA_DQS_DN<3>")
	)
	(segment
		(start 410.41193 -276.115272)
		(end 409.779724 -276.115272)
		(width 0.18288)
		(layer "In6.Cu")
		(net "M_G_CPU0_SA_DQS_DN<3>")
	)
	(segment
		(start 406.787096 -275.482812)
		(end 406.240996 -275.482812)
		(width 0.18288)
		(layer "In6.Cu")
		(net "M_G_CPU0_SA_DQS_DN<3>")
	)
	(segment
		(start 435.823614 -284.016704)
		(end 435.542436 -284.297882)
		(width 0.18288)
		(layer "In6.Cu")
		(net "M_G_CPU0_SA_DQS_DN<3>")
	)
	(segment
		(start 422.51503 -282.612846)
		(end 422.51503 -282.066746)
		(width 0.18288)
		(layer "In6.Cu")
		(net "M_G_CPU0_SA_DQS_DN<3>")
	)
	(segment
		(start 434.399436 -283.966158)
		(end 433.853336 -283.966158)
		(width 0.18288)
		(layer "In6.Cu")
		(net "M_G_CPU0_SA_DQS_DN<3>")
	)
	(segment
		(start 388.203948 -268.345412)
		(end 387.952742 -268.093952)
		(width 0.088646)
		(layer "In6.Cu")
		(net "M_G_CPU0_SA_DQS_DN<3>")
	)
	(segment
		(start 425.105576 -284.442408)
		(end 424.576748 -284.442408)
		(width 0.18288)
		(layer "In6.Cu")
		(net "M_G_CPU0_SA_DQS_DN<3>")
	)
	(segment
		(start 411.08249 -275.990812)
		(end 410.53639 -275.990812)
		(width 0.18288)
		(layer "In6.Cu")
		(net "M_G_CPU0_SA_DQS_DN<3>")
	)
	(segment
		(start 428.364396 -284.090618)
		(end 426.578776 -284.090618)
		(width 0.18288)
		(layer "In6.Cu")
		(net "M_G_CPU0_SA_DQS_DN<3>")
	)
	(segment
		(start 420.226744 -279.592532)
		(end 419.398196 -279.592532)
		(width 0.18288)
		(layer "In6.Cu")
		(net "M_G_CPU0_SA_DQS_DN<3>")
	)
	(segment
		(start 382.528064 -268.080236)
		(end 382.513332 -268.0716)
		(width 0.088646)
		(layer "In6.Cu")
		(net "M_G_CPU0_SA_DQS_DN<3>")
	)
	(segment
		(start 375.482612 -267.755878)
		(end 375.196862 -267.755878)
		(width 0.088646)
		(layer "In6.Cu")
		(net "M_G_CPU0_SA_DQS_DN<3>")
	)
	(segment
		(start 375.701052 -267.910564)
		(end 375.482612 -267.755878)
		(width 0.088646)
		(layer "In6.Cu")
		(net "M_G_CPU0_SA_DQS_DN<3>")
	)
	(segment
		(start 429.705516 -284.090618)
		(end 429.159416 -284.090618)
		(width 0.18288)
		(layer "In6.Cu")
		(net "M_G_CPU0_SA_DQS_DN<3>")
	)
	(segment
		(start 421.005508 -279.342596)
		(end 420.47668 -279.342596)
		(width 0.18288)
		(layer "In6.Cu")
		(net "M_G_CPU0_SA_DQS_DN<3>")
	)
	(segment
		(start 376.889264 -268.080236)
		(end 376.881898 -268.075918)
		(width 0.088646)
		(layer "In6.Cu")
		(net "M_G_CPU0_SA_DQS_DN<3>")
	)
	(segment
		(start 412.686246 -276.836886)
		(end 411.964632 -276.115272)
		(width 0.18288)
		(layer "In6.Cu")
		(net "M_G_CPU0_SA_DQS_DN<3>")
	)
	(segment
		(start 376.881898 -268.075918)
		(end 376.881898 -268.076172)
		(width 0.088646)
		(layer "In6.Cu")
		(net "M_G_CPU0_SA_DQS_DN<3>")
	)
	(segment
		(start 434.523896 -284.090618)
		(end 434.399436 -283.966158)
		(width 0.18288)
		(layer "In6.Cu")
		(net "M_G_CPU0_SA_DQS_DN<3>")
	)
	(segment
		(start 380.648464 -268.080236)
		(end 380.63805 -268.07414)
		(width 0.088646)
		(layer "In6.Cu")
		(net "M_G_CPU0_SA_DQS_DN<3>")
	)
	(segment
		(start 435.27726 -284.297882)
		(end 435.069996 -284.090618)
		(width 0.18288)
		(layer "In6.Cu")
		(net "M_G_CPU0_SA_DQS_DN<3>")
	)
	(segment
		(start 420.47668 -279.342596)
		(end 420.226744 -279.592532)
		(width 0.18288)
		(layer "In6.Cu")
		(net "M_G_CPU0_SA_DQS_DN<3>")
	)
	(segment
		(start 432.387756 -284.090618)
		(end 431.841656 -284.090618)
		(width 0.18288)
		(layer "In6.Cu")
		(net "M_G_CPU0_SA_DQS_DN<3>")
	)
	(segment
		(start 409.779724 -276.115272)
		(end 408.553158 -275.607272)
		(width 0.18288)
		(layer "In6.Cu")
		(net "M_G_CPU0_SA_DQS_DN<3>")
	)
	(segment
		(start 415.277554 -276.836886)
		(end 415.153094 -276.712426)
		(width 0.18288)
		(layer "In6.Cu")
		(net "M_G_CPU0_SA_DQS_DN<3>")
	)
	(segment
		(start 431.841656 -284.090618)
		(end 431.717196 -283.966158)
		(width 0.18288)
		(layer "In6.Cu")
		(net "M_G_CPU0_SA_DQS_DN<3>")
	)
	(segment
		(start 406.240996 -275.482812)
		(end 406.116536 -275.607272)
		(width 0.18288)
		(layer "In6.Cu")
		(net "M_G_CPU0_SA_DQS_DN<3>")
	)
	(segment
		(start 435.542436 -284.297882)
		(end 435.27726 -284.297882)
		(width 0.18288)
		(layer "In6.Cu")
		(net "M_G_CPU0_SA_DQS_DN<3>")
	)
	(segment
		(start 429.829976 -283.966158)
		(end 429.705516 -284.090618)
		(width 0.18288)
		(layer "In6.Cu")
		(net "M_G_CPU0_SA_DQS_DN<3>")
	)
	(segment
		(start 385.721606 -268.080236)
		(end 385.713224 -268.085062)
		(width 0.088646)
		(layer "In6.Cu")
		(net "M_G_CPU0_SA_DQS_DN<3>")
	)
	(segment
		(start 378.768864 -268.080236)
		(end 378.754132 -268.0716)
		(width 0.088646)
		(layer "In6.Cu")
		(net "M_G_CPU0_SA_DQS_DN<3>")
	)
	(segment
		(start 376.373898 -268.05509)
		(end 376.36831 -268.05509)
		(width 0.088646)
		(layer "In6.Cu")
		(net "M_G_CPU0_SA_DQS_DN<3>")
	)
	(segment
		(start 422.39057 -281.942286)
		(end 422.39057 -280.226008)
		(width 0.18288)
		(layer "In6.Cu")
		(net "M_G_CPU0_SA_DQS_DN<3>")
	)
	(segment
		(start 433.728876 -284.090618)
		(end 433.182776 -284.090618)
		(width 0.18288)
		(layer "In6.Cu")
		(net "M_G_CPU0_SA_DQS_DN<3>")
	)
	(segment
		(start 375.921016 -268.062202)
		(end 375.709434 -267.912596)
		(width 0.088646)
		(layer "In6.Cu")
		(net "M_G_CPU0_SA_DQS_DN<3>")
	)
	(segment
		(start 392.789918 -268.810232)
		(end 390.15416 -268.285722)
		(width 0.18288)
		(layer "In6.Cu")
		(net "M_G_CPU0_SA_DQS_DN<3>")
	)
	(segment
		(start 425.978828 -284.690566)
		(end 425.353734 -284.690566)
		(width 0.18288)
		(layer "In6.Cu")
		(net "M_G_CPU0_SA_DQS_DN<3>")
	)
	(segment
		(start 375.709434 -267.912596)
		(end 375.701052 -267.910564)
		(width 0.088646)
		(layer "In6.Cu")
		(net "M_G_CPU0_SA_DQS_DN<3>")
	)
	(segment
		(start 414.606994 -276.712426)
		(end 414.482534 -276.836886)
		(width 0.18288)
		(layer "In6.Cu")
		(net "M_G_CPU0_SA_DQS_DN<3>")
	)
	(segment
		(start 376.324368 -268.080236)
		(end 376.324368 -268.08049)
		(width 0.088646)
		(layer "In6.Cu")
		(net "M_G_CPU0_SA_DQS_DN<3>")
	)
	(segment
		(start 418.385244 -278.579326)
		(end 417.753292 -277.947374)
		(width 0.18288)
		(layer "In6.Cu")
		(net "M_G_CPU0_SA_DQS_DN<3>")
	)
	(segment
		(start 381.588264 -268.080236)
		(end 381.573532 -268.0716)
		(width 0.088646)
		(layer "In6.Cu")
		(net "M_G_CPU0_SA_DQS_DN<3>")
	)
	(segment
		(start 410.53639 -275.990812)
		(end 410.41193 -276.115272)
		(width 0.18288)
		(layer "In6.Cu")
		(net "M_G_CPU0_SA_DQS_DN<3>")
	)
	(segment
		(start 414.482534 -276.836886)
		(end 412.686246 -276.836886)
		(width 0.18288)
		(layer "In6.Cu")
		(net "M_G_CPU0_SA_DQS_DN<3>")
	)
	(segment
		(start 422.39057 -282.737306)
		(end 422.51503 -282.612846)
		(width 0.18288)
		(layer "In6.Cu")
		(net "M_G_CPU0_SA_DQS_DN<3>")
	)
	(segment
		(start 422.39057 -283.338016)
		(end 422.39057 -282.737306)
		(width 0.18288)
		(layer "In6.Cu")
		(net "M_G_CPU0_SA_DQS_DN<3>")
	)
	(segment
		(start 386.676138 -268.0716)
		(end 386.649468 -268.087094)
		(width 0.088646)
		(layer "In6.Cu")
		(net "M_G_CPU0_SA_DQS_DN<3>")
	)
	(segment
		(start 416.592258 -277.466298)
		(end 415.962338 -276.836886)
		(width 0.18288)
		(layer "In6.Cu")
		(net "M_G_CPU0_SA_DQS_DN<3>")
	)
	(segment
		(start 433.853336 -283.966158)
		(end 433.728876 -284.090618)
		(width 0.18288)
		(layer "In6.Cu")
		(net "M_G_CPU0_SA_DQS_DN<3>")
	)
	(segment
		(start 418.9476 -279.141936)
		(end 418.9476 -278.965914)
		(width 0.18288)
		(layer "In6.Cu")
		(net "M_G_CPU0_SA_DQS_DN<3>")
	)
	(segment
		(start 387.952742 -268.093952)
		(end 387.64845 -268.054582)
		(width 0.088646)
		(layer "In6.Cu")
		(net "M_G_CPU0_SA_DQS_DN<3>")
	)
	(segment
		(start 418.9476 -278.965914)
		(end 418.561012 -278.579326)
		(width 0.18288)
		(layer "In6.Cu")
		(net "M_G_CPU0_SA_DQS_DN<3>")
	)
	(segment
		(start 421.755316 -279.590754)
		(end 421.253666 -279.590754)
		(width 0.18288)
		(layer "In6.Cu")
		(net "M_G_CPU0_SA_DQS_DN<3>")
	)
	(segment
		(start 379.708918 -268.080236)
		(end 379.698504 -268.07414)
		(width 0.088646)
		(layer "In6.Cu")
		(net "M_G_CPU0_SA_DQS_DN<3>")
	)
	(segment
		(start 388.452614 -268.345412)
		(end 388.203948 -268.345412)
		(width 0.088646)
		(layer "In6.Cu")
		(net "M_G_CPU0_SA_DQS_DN<3>")
	)
	(segment
		(start 422.51503 -282.066746)
		(end 422.39057 -281.942286)
		(width 0.18288)
		(layer "In6.Cu")
		(net "M_G_CPU0_SA_DQS_DN<3>")
	)
	(segment
		(start 430.376076 -283.966158)
		(end 429.829976 -283.966158)
		(width 0.18288)
		(layer "In6.Cu")
		(net "M_G_CPU0_SA_DQS_DN<3>")
	)
	(segment
		(start 411.964632 -276.115272)
		(end 411.20695 -276.115272)
		(width 0.18288)
		(layer "In6.Cu")
		(net "M_G_CPU0_SA_DQS_DN<3>")
	)
	(segment
		(start 424.303952 -284.715204)
		(end 423.767758 -284.715204)
		(width 0.18288)
		(layer "In6.Cu")
		(net "M_G_CPU0_SA_DQS_DN<3>")
	)
	(segment
		(start 385.736338 -268.0716)
		(end 385.721606 -268.080236)
		(width 0.088646)
		(layer "In6.Cu")
		(net "M_G_CPU0_SA_DQS_DN<3>")
	)
	(segment
		(start 398.761966 -268.810232)
		(end 392.789918 -268.810232)
		(width 0.18288)
		(layer "In6.Cu")
		(net "M_G_CPU0_SA_DQS_DN<3>")
	)
	(segment
		(start 384.796792 -268.0716)
		(end 384.78206 -268.080236)
		(width 0.088646)
		(layer "In6.Cu")
		(net "M_G_CPU0_SA_DQS_DN<3>")
	)
	(segment
		(start 431.717196 -283.966158)
		(end 431.171096 -283.966158)
		(width 0.18288)
		(layer "In6.Cu")
		(net "M_G_CPU0_SA_DQS_DN<3>")
	)
	(segment
		(start 408.553158 -275.607272)
		(end 406.911556 -275.607272)
		(width 0.18288)
		(layer "In6.Cu")
		(net "M_G_CPU0_SA_DQS_DN<3>")
	)
	(segment
		(start 383.467864 -268.080236)
		(end 383.453132 -268.0716)
		(width 0.088646)
		(layer "In6.Cu")
		(net "M_G_CPU0_SA_DQS_DN<3>")
	)
	(segment
		(start 417.753292 -277.947374)
		(end 416.592258 -277.466298)
		(width 0.18288)
		(layer "In6.Cu")
		(net "M_G_CPU0_SA_DQS_DN<3>")
	)
	(segment
		(start 406.911556 -275.607272)
		(end 406.787096 -275.482812)
		(width 0.18288)
		(layer "In6.Cu")
		(net "M_G_CPU0_SA_DQS_DN<3>")
	)
	(segment
		(start 377.829064 -268.080236)
		(end 377.814332 -268.0716)
		(width 0.088646)
		(layer "In6.Cu")
		(net "M_G_CPU0_SA_DQS_DN<3>")
	)
	(segment
		(start 430.500536 -284.090618)
		(end 430.376076 -283.966158)
		(width 0.18288)
		(layer "In6.Cu")
		(net "M_G_CPU0_SA_DQS_DN<3>")
	)
	(segment
		(start 387.64845 -268.054582)
		(end 387.594094 -268.084554)
		(width 0.088646)
		(layer "In6.Cu")
		(net "M_G_CPU0_SA_DQS_DN<3>")
	)
	(segment
		(start 433.058316 -283.966158)
		(end 432.512216 -283.966158)
		(width 0.18288)
		(layer "In6.Cu")
		(net "M_G_CPU0_SA_DQS_DN<3>")
	)
	(segment
		(start 415.962338 -276.836886)
		(end 415.277554 -276.836886)
		(width 0.18288)
		(layer "In6.Cu")
		(net "M_G_CPU0_SA_DQS_DN<3>")
	)
	(arc
		(start 384.78206 -268.080236)
		(mid 384.594862 -268.130379)
		(end 384.407664 -268.080236)
		(width 0.088646)
		(layer "In6.Cu")
		(net "M_G_CPU0_SA_DQS_DN<3>")
	)
	(arc
		(start 385.347464 -268.080236)
		(mid 385.073265 -268.004401)
		(end 384.796792 -268.0716)
		(width 0.088646)
		(layer "In6.Cu")
		(net "M_G_CPU0_SA_DQS_DN<3>")
	)
	(arc
		(start 377.814332 -268.0716)
		(mid 377.537857 -268.00428)
		(end 377.26366 -268.080236)
		(width 0.088646)
		(layer "In6.Cu")
		(net "M_G_CPU0_SA_DQS_DN<3>")
	)
	(arc
		(start 386.649468 -268.087094)
		(mid 386.467357 -268.130419)
		(end 386.28701 -268.080236)
		(width 0.088646)
		(layer "In6.Cu")
		(net "M_G_CPU0_SA_DQS_DN<3>")
	)
	(arc
		(start 379.14326 -268.080236)
		(mid 378.956062 -268.130379)
		(end 378.768864 -268.080236)
		(width 0.088646)
		(layer "In6.Cu")
		(net "M_G_CPU0_SA_DQS_DN<3>")
	)
	(arc
		(start 380.083314 -268.080236)
		(mid 379.896116 -268.130379)
		(end 379.708918 -268.080236)
		(width 0.088646)
		(layer "In6.Cu")
		(net "M_G_CPU0_SA_DQS_DN<3>")
	)
	(arc
		(start 379.698504 -268.07414)
		(mid 379.420072 -268.004294)
		(end 379.14326 -268.080236)
		(width 0.088646)
		(layer "In6.Cu")
		(net "M_G_CPU0_SA_DQS_DN<3>")
	)
	(arc
		(start 378.20346 -268.080236)
		(mid 378.016262 -268.130379)
		(end 377.829064 -268.080236)
		(width 0.088646)
		(layer "In6.Cu")
		(net "M_G_CPU0_SA_DQS_DN<3>")
	)
	(arc
		(start 376.324368 -268.08049)
		(mid 376.120005 -268.130412)
		(end 375.921016 -268.062202)
		(width 0.088646)
		(layer "In6.Cu")
		(net "M_G_CPU0_SA_DQS_DN<3>")
	)
	(arc
		(start 387.594094 -268.084554)
		(mid 387.409404 -268.130878)
		(end 387.225794 -268.08049)
		(width 0.088646)
		(layer "In6.Cu")
		(net "M_G_CPU0_SA_DQS_DN<3>")
	)
	(arc
		(start 377.26366 -268.080236)
		(mid 377.076462 -268.130379)
		(end 376.889264 -268.080236)
		(width 0.088646)
		(layer "In6.Cu")
		(net "M_G_CPU0_SA_DQS_DN<3>")
	)
	(arc
		(start 376.881898 -268.076172)
		(mid 376.630412 -268.005292)
		(end 376.373898 -268.05509)
		(width 0.088646)
		(layer "In6.Cu")
		(net "M_G_CPU0_SA_DQS_DN<3>")
	)
	(arc
		(start 378.754132 -268.0716)
		(mid 378.477657 -268.00428)
		(end 378.20346 -268.080236)
		(width 0.088646)
		(layer "In6.Cu")
		(net "M_G_CPU0_SA_DQS_DN<3>")
	)
	(arc
		(start 386.28701 -268.080236)
		(mid 386.012811 -268.004401)
		(end 385.736338 -268.0716)
		(width 0.088646)
		(layer "In6.Cu")
		(net "M_G_CPU0_SA_DQS_DN<3>")
	)
	(arc
		(start 381.02286 -268.080236)
		(mid 380.835662 -268.130379)
		(end 380.648464 -268.080236)
		(width 0.088646)
		(layer "In6.Cu")
		(net "M_G_CPU0_SA_DQS_DN<3>")
	)
	(arc
		(start 387.225794 -268.08049)
		(mid 386.952133 -268.004752)
		(end 386.676138 -268.0716)
		(width 0.088646)
		(layer "In6.Cu")
		(net "M_G_CPU0_SA_DQS_DN<3>")
	)
	(arc
		(start 383.453132 -268.0716)
		(mid 383.176657 -268.00428)
		(end 382.90246 -268.080236)
		(width 0.088646)
		(layer "In6.Cu")
		(net "M_G_CPU0_SA_DQS_DN<3>")
	)
	(arc
		(start 382.90246 -268.080236)
		(mid 382.715262 -268.130379)
		(end 382.528064 -268.080236)
		(width 0.088646)
		(layer "In6.Cu")
		(net "M_G_CPU0_SA_DQS_DN<3>")
	)
	(arc
		(start 381.96266 -268.080236)
		(mid 381.775462 -268.130379)
		(end 381.588264 -268.080236)
		(width 0.088646)
		(layer "In6.Cu")
		(net "M_G_CPU0_SA_DQS_DN<3>")
	)
	(arc
		(start 382.513332 -268.0716)
		(mid 382.236857 -268.00428)
		(end 381.96266 -268.080236)
		(width 0.088646)
		(layer "In6.Cu")
		(net "M_G_CPU0_SA_DQS_DN<3>")
	)
	(arc
		(start 381.573532 -268.0716)
		(mid 381.297057 -268.00428)
		(end 381.02286 -268.080236)
		(width 0.088646)
		(layer "In6.Cu")
		(net "M_G_CPU0_SA_DQS_DN<3>")
	)
	(arc
		(start 380.63805 -268.07414)
		(mid 380.359872 -268.004417)
		(end 380.083314 -268.080236)
		(width 0.088646)
		(layer "In6.Cu")
		(net "M_G_CPU0_SA_DQS_DN<3>")
	)
	(arc
		(start 384.407664 -268.080236)
		(mid 384.124962 -268.00446)
		(end 383.84226 -268.080236)
		(width 0.088646)
		(layer "In6.Cu")
		(net "M_G_CPU0_SA_DQS_DN<3>")
	)
	(arc
		(start 385.713224 -268.085062)
		(mid 385.529716 -268.13034)
		(end 385.347464 -268.080236)
		(width 0.088646)
		(layer "In6.Cu")
		(net "M_G_CPU0_SA_DQS_DN<3>")
	)
	(arc
		(start 383.84226 -268.080236)
		(mid 383.655062 -268.130379)
		(end 383.467864 -268.080236)
		(width 0.088646)
		(layer "In6.Cu")
		(net "M_G_CPU0_SA_DQS_DN<3>")
	)
	(segment
		(start 439.849768 -293.79164)
		(end 439.854086 -293.79164)
		(width 0.101854)
		(layer "F.Cu")
		(net "M_G_CPU0_SA_DQS_DN<2>")
	)
	(segment
		(start 439.702194 -293.79164)
		(end 439.849768 -293.79164)
		(width 0.20066)
		(layer "F.Cu")
		(net "M_G_CPU0_SA_DQS_DN<2>")
	)
	(segment
		(start 442.03366 -293.79164)
		(end 442.038994 -293.786306)
		(width 0.1016)
		(layer "F.Cu")
		(net "M_G_CPU0_SA_DQS_DN<2>")
	)
	(segment
		(start 435.823614 -293.366698)
		(end 436.928514 -293.366698)
		(width 0.20066)
		(layer "F.Cu")
		(net "M_G_CPU0_SA_DQS_DN<2>")
	)
	(segment
		(start 377.546362 -265.313922)
		(end 377.546616 -265.314176)
		(width 0.20066)
		(layer "F.Cu")
		(net "M_G_CPU0_SA_DQS_DN<2>")
	)
	(segment
		(start 439.430922 -294.062912)
		(end 439.702194 -293.79164)
		(width 0.20066)
		(layer "F.Cu")
		(net "M_G_CPU0_SA_DQS_DN<2>")
	)
	(segment
		(start 438.494678 -293.648384)
		(end 438.909206 -294.062912)
		(width 0.20066)
		(layer "F.Cu")
		(net "M_G_CPU0_SA_DQS_DN<2>")
	)
	(segment
		(start 437.477154 -293.366698)
		(end 437.75884 -293.648384)
		(width 0.20066)
		(layer "F.Cu")
		(net "M_G_CPU0_SA_DQS_DN<2>")
	)
	(segment
		(start 436.928514 -293.366698)
		(end 437.477154 -293.366698)
		(width 0.20066)
		(layer "F.Cu")
		(net "M_G_CPU0_SA_DQS_DN<2>")
	)
	(segment
		(start 442.899546 -294.0177)
		(end 443.31001 -293.607236)
		(width 0.20066)
		(layer "F.Cu")
		(net "M_G_CPU0_SA_DQS_DN<2>")
	)
	(segment
		(start 443.642496 -293.607236)
		(end 443.883034 -293.366698)
		(width 0.20066)
		(layer "F.Cu")
		(net "M_G_CPU0_SA_DQS_DN<2>")
	)
	(segment
		(start 442.363098 -293.786306)
		(end 442.594492 -294.0177)
		(width 0.20066)
		(layer "F.Cu")
		(net "M_G_CPU0_SA_DQS_DN<2>")
	)
	(segment
		(start 442.038994 -293.786306)
		(end 442.363098 -293.786306)
		(width 0.20066)
		(layer "F.Cu")
		(net "M_G_CPU0_SA_DQS_DN<2>")
	)
	(segment
		(start 442.594492 -294.0177)
		(end 442.899546 -294.0177)
		(width 0.20066)
		(layer "F.Cu")
		(net "M_G_CPU0_SA_DQS_DN<2>")
	)
	(segment
		(start 443.883034 -293.366698)
		(end 444.472314 -293.366698)
		(width 0.20066)
		(layer "F.Cu")
		(net "M_G_CPU0_SA_DQS_DN<2>")
	)
	(segment
		(start 443.31001 -293.607236)
		(end 443.642496 -293.607236)
		(width 0.20066)
		(layer "F.Cu")
		(net "M_G_CPU0_SA_DQS_DN<2>")
	)
	(segment
		(start 439.854086 -293.79164)
		(end 442.03366 -293.79164)
		(width 0.1016)
		(layer "F.Cu")
		(net "M_G_CPU0_SA_DQS_DN<2>")
	)
	(segment
		(start 438.909206 -294.062912)
		(end 439.430922 -294.062912)
		(width 0.20066)
		(layer "F.Cu")
		(net "M_G_CPU0_SA_DQS_DN<2>")
	)
	(segment
		(start 437.75884 -293.648384)
		(end 438.494678 -293.648384)
		(width 0.20066)
		(layer "F.Cu")
		(net "M_G_CPU0_SA_DQS_DN<2>")
	)
	(segment
		(start 377.546362 -264.778236)
		(end 377.546362 -265.313922)
		(width 0.20066)
		(layer "F.Cu")
		(net "M_G_CPU0_SA_DQS_DN<2>")
	)
	(segment
		(start 412.164022 -289.023806)
		(end 411.5562 -288.415984)
		(width 0.18288)
		(layer "In4.Cu")
		(net "M_G_CPU0_SA_DQS_DN<2>")
	)
	(segment
		(start 388.323074 -265.575288)
		(end 386.605272 -265.575288)
		(width 0.18288)
		(layer "In4.Cu")
		(net "M_G_CPU0_SA_DQS_DN<2>")
	)
	(segment
		(start 392.360658 -268.728952)
		(end 390.961626 -268.149324)
		(width 0.18288)
		(layer "In4.Cu")
		(net "M_G_CPU0_SA_DQS_DN<2>")
	)
	(segment
		(start 404.7236 -283.129482)
		(end 404.697184 -283.10332)
		(width 0.18288)
		(layer "In4.Cu")
		(net "M_G_CPU0_SA_DQS_DN<2>")
	)
	(segment
		(start 378.875036 -265.225784)
		(end 378.87529 -265.22553)
		(width 0.088646)
		(layer "In4.Cu")
		(net "M_G_CPU0_SA_DQS_DN<2>")
	)
	(segment
		(start 425.292774 -294.047672)
		(end 425.037504 -293.792402)
		(width 0.18288)
		(layer "In4.Cu")
		(net "M_G_CPU0_SA_DQS_DN<2>")
	)
	(segment
		(start 421.20439 -294.89273)
		(end 420.953946 -294.642286)
		(width 0.18288)
		(layer "In4.Cu")
		(net "M_G_CPU0_SA_DQS_DN<2>")
	)
	(segment
		(start 402.028914 -276.793452)
		(end 393.96416 -268.728952)
		(width 0.18288)
		(layer "In4.Cu")
		(net "M_G_CPU0_SA_DQS_DN<2>")
	)
	(segment
		(start 404.697184 -283.10332)
		(end 402.028914 -276.793452)
		(width 0.18288)
		(layer "In4.Cu")
		(net "M_G_CPU0_SA_DQS_DN<2>")
	)
	(segment
		(start 385.328922 -265.634978)
		(end 385.32816 -265.63574)
		(width 0.088646)
		(layer "In4.Cu")
		(net "M_G_CPU0_SA_DQS_DN<2>")
	)
	(segment
		(start 410.529024 -286.435038)
		(end 409.942538 -285.848552)
		(width 0.18288)
		(layer "In4.Cu")
		(net "M_G_CPU0_SA_DQS_DN<2>")
	)
	(segment
		(start 413.699452 -289.887406)
		(end 413.185864 -289.887406)
		(width 0.18288)
		(layer "In4.Cu")
		(net "M_G_CPU0_SA_DQS_DN<2>")
	)
	(segment
		(start 419.414452 -294.607488)
		(end 419.21557 -294.40886)
		(width 0.18288)
		(layer "In4.Cu")
		(net "M_G_CPU0_SA_DQS_DN<2>")
	)
	(segment
		(start 379.628146 -265.629898)
		(end 379.613414 -265.638534)
		(width 0.088646)
		(layer "In4.Cu")
		(net "M_G_CPU0_SA_DQS_DN<2>")
	)
	(segment
		(start 424.641518 -293.792402)
		(end 424.387772 -294.046148)
		(width 0.18288)
		(layer "In4.Cu")
		(net "M_G_CPU0_SA_DQS_DN<2>")
	)
	(segment
		(start 382.447546 -265.629898)
		(end 382.432814 -265.638534)
		(width 0.088646)
		(layer "In4.Cu")
		(net "M_G_CPU0_SA_DQS_DN<2>")
	)
	(segment
		(start 383.387346 -265.629898)
		(end 383.372614 -265.638534)
		(width 0.088646)
		(layer "In4.Cu")
		(net "M_G_CPU0_SA_DQS_DN<2>")
	)
	(segment
		(start 386.605272 -265.575288)
		(end 386.581904 -265.575288)
		(width 0.088646)
		(layer "In4.Cu")
		(net "M_G_CPU0_SA_DQS_DN<2>")
	)
	(segment
		(start 417.36518 -292.160706)
		(end 416.600894 -292.160706)
		(width 0.18288)
		(layer "In4.Cu")
		(net "M_G_CPU0_SA_DQS_DN<2>")
	)
	(segment
		(start 434.20792 -293.127938)
		(end 426.50918 -293.127938)
		(width 0.18288)
		(layer "In4.Cu")
		(net "M_G_CPU0_SA_DQS_DN<2>")
	)
	(segment
		(start 416.600894 -292.160706)
		(end 416.021774 -291.581586)
		(width 0.18288)
		(layer "In4.Cu")
		(net "M_G_CPU0_SA_DQS_DN<2>")
	)
	(segment
		(start 420.953946 -294.642286)
		(end 420.502334 -294.642286)
		(width 0.18288)
		(layer "In4.Cu")
		(net "M_G_CPU0_SA_DQS_DN<2>")
	)
	(segment
		(start 386.581904 -265.575288)
		(end 386.522214 -265.634978)
		(width 0.088646)
		(layer "In4.Cu")
		(net "M_G_CPU0_SA_DQS_DN<2>")
	)
	(segment
		(start 419.21557 -294.40886)
		(end 419.21557 -294.011096)
		(width 0.18288)
		(layer "In4.Cu")
		(net "M_G_CPU0_SA_DQS_DN<2>")
	)
	(segment
		(start 378.059188 -265.314176)
		(end 377.546616 -265.314176)
		(width 0.088646)
		(layer "In4.Cu")
		(net "M_G_CPU0_SA_DQS_DN<2>")
	)
	(segment
		(start 390.85139 -268.103604)
		(end 388.323074 -265.575288)
		(width 0.18288)
		(layer "In4.Cu")
		(net "M_G_CPU0_SA_DQS_DN<2>")
	)
	(segment
		(start 426.50918 -293.127938)
		(end 425.589446 -294.047672)
		(width 0.18288)
		(layer "In4.Cu")
		(net "M_G_CPU0_SA_DQS_DN<2>")
	)
	(segment
		(start 422.27754 -294.046148)
		(end 421.43045 -294.89273)
		(width 0.18288)
		(layer "In4.Cu")
		(net "M_G_CPU0_SA_DQS_DN<2>")
	)
	(segment
		(start 434.912008 -293.385494)
		(end 434.465476 -293.385494)
		(width 0.18288)
		(layer "In4.Cu")
		(net "M_G_CPU0_SA_DQS_DN<2>")
	)
	(segment
		(start 378.82957 -265.157966)
		(end 378.812552 -265.128248)
		(width 0.088646)
		(layer "In4.Cu")
		(net "M_G_CPU0_SA_DQS_DN<2>")
	)
	(segment
		(start 405.235156 -283.641038)
		(end 404.7236 -283.129482)
		(width 0.18288)
		(layer "In4.Cu")
		(net "M_G_CPU0_SA_DQS_DN<2>")
	)
	(segment
		(start 379.239018 -265.638534)
		(end 379.17501 -265.601704)
		(width 0.088646)
		(layer "In4.Cu")
		(net "M_G_CPU0_SA_DQS_DN<2>")
	)
	(segment
		(start 421.43045 -294.89273)
		(end 421.20439 -294.89273)
		(width 0.18288)
		(layer "In4.Cu")
		(net "M_G_CPU0_SA_DQS_DN<2>")
	)
	(segment
		(start 407.142696 -283.641038)
		(end 405.235156 -283.641038)
		(width 0.18288)
		(layer "In4.Cu")
		(net "M_G_CPU0_SA_DQS_DN<2>")
	)
	(segment
		(start 381.503174 -265.632438)
		(end 381.49276 -265.638534)
		(width 0.088646)
		(layer "In4.Cu")
		(net "M_G_CPU0_SA_DQS_DN<2>")
	)
	(segment
		(start 411.5562 -288.14903)
		(end 410.529024 -287.121854)
		(width 0.18288)
		(layer "In4.Cu")
		(net "M_G_CPU0_SA_DQS_DN<2>")
	)
	(segment
		(start 384.327146 -265.629898)
		(end 384.312414 -265.638534)
		(width 0.088646)
		(layer "In4.Cu")
		(net "M_G_CPU0_SA_DQS_DN<2>")
	)
	(segment
		(start 378.116338 -265.257026)
		(end 378.059188 -265.314176)
		(width 0.088646)
		(layer "In4.Cu")
		(net "M_G_CPU0_SA_DQS_DN<2>")
	)
	(segment
		(start 424.387772 -294.046148)
		(end 422.27754 -294.046148)
		(width 0.18288)
		(layer "In4.Cu")
		(net "M_G_CPU0_SA_DQS_DN<2>")
	)
	(segment
		(start 420.502334 -294.642286)
		(end 420.387018 -294.757602)
		(width 0.18288)
		(layer "In4.Cu")
		(net "M_G_CPU0_SA_DQS_DN<2>")
	)
	(segment
		(start 419.450266 -294.62222)
		(end 419.414452 -294.607488)
		(width 0.18288)
		(layer "In4.Cu")
		(net "M_G_CPU0_SA_DQS_DN<2>")
	)
	(segment
		(start 420.129462 -294.757602)
		(end 419.450266 -294.62222)
		(width 0.18288)
		(layer "In4.Cu")
		(net "M_G_CPU0_SA_DQS_DN<2>")
	)
	(segment
		(start 379.17501 -265.601704)
		(end 378.875036 -265.225784)
		(width 0.088646)
		(layer "In4.Cu")
		(net "M_G_CPU0_SA_DQS_DN<2>")
	)
	(segment
		(start 420.387018 -294.757602)
		(end 420.129462 -294.757602)
		(width 0.18288)
		(layer "In4.Cu")
		(net "M_G_CPU0_SA_DQS_DN<2>")
	)
	(segment
		(start 413.185864 -289.887406)
		(end 412.322264 -289.023806)
		(width 0.18288)
		(layer "In4.Cu")
		(net "M_G_CPU0_SA_DQS_DN<2>")
	)
	(segment
		(start 411.5562 -288.415984)
		(end 411.5562 -288.14903)
		(width 0.18288)
		(layer "In4.Cu")
		(net "M_G_CPU0_SA_DQS_DN<2>")
	)
	(segment
		(start 425.037504 -293.792402)
		(end 424.641518 -293.792402)
		(width 0.18288)
		(layer "In4.Cu")
		(net "M_G_CPU0_SA_DQS_DN<2>")
	)
	(segment
		(start 434.465476 -293.385494)
		(end 434.20792 -293.127938)
		(width 0.18288)
		(layer "In4.Cu")
		(net "M_G_CPU0_SA_DQS_DN<2>")
	)
	(segment
		(start 393.96416 -268.728952)
		(end 392.360658 -268.728952)
		(width 0.18288)
		(layer "In4.Cu")
		(net "M_G_CPU0_SA_DQS_DN<2>")
	)
	(segment
		(start 410.529024 -287.121854)
		(end 410.529024 -286.435038)
		(width 0.18288)
		(layer "In4.Cu")
		(net "M_G_CPU0_SA_DQS_DN<2>")
	)
	(segment
		(start 409.942538 -285.848552)
		(end 409.35021 -285.848552)
		(width 0.18288)
		(layer "In4.Cu")
		(net "M_G_CPU0_SA_DQS_DN<2>")
	)
	(segment
		(start 386.522214 -265.634978)
		(end 385.328922 -265.634978)
		(width 0.088646)
		(layer "In4.Cu")
		(net "M_G_CPU0_SA_DQS_DN<2>")
	)
	(segment
		(start 409.35021 -285.848552)
		(end 407.142696 -283.641038)
		(width 0.18288)
		(layer "In4.Cu")
		(net "M_G_CPU0_SA_DQS_DN<2>")
	)
	(segment
		(start 419.21557 -294.011096)
		(end 417.36518 -292.160706)
		(width 0.18288)
		(layer "In4.Cu")
		(net "M_G_CPU0_SA_DQS_DN<2>")
	)
	(segment
		(start 435.553866 -293.636446)
		(end 435.16296 -293.636446)
		(width 0.18288)
		(layer "In4.Cu")
		(net "M_G_CPU0_SA_DQS_DN<2>")
	)
	(segment
		(start 378.658882 -264.981436)
		(end 378.65812 -264.980928)
		(width 0.088646)
		(layer "In4.Cu")
		(net "M_G_CPU0_SA_DQS_DN<2>")
	)
	(segment
		(start 435.823614 -293.366698)
		(end 435.553866 -293.636446)
		(width 0.18288)
		(layer "In4.Cu")
		(net "M_G_CPU0_SA_DQS_DN<2>")
	)
	(segment
		(start 415.393886 -291.581586)
		(end 413.699452 -289.887406)
		(width 0.18288)
		(layer "In4.Cu")
		(net "M_G_CPU0_SA_DQS_DN<2>")
	)
	(segment
		(start 390.961626 -268.149324)
		(end 390.85139 -268.103604)
		(width 0.18288)
		(layer "In4.Cu")
		(net "M_G_CPU0_SA_DQS_DN<2>")
	)
	(segment
		(start 412.322264 -289.023806)
		(end 412.164022 -289.023806)
		(width 0.18288)
		(layer "In4.Cu")
		(net "M_G_CPU0_SA_DQS_DN<2>")
	)
	(segment
		(start 416.021774 -291.581586)
		(end 415.393886 -291.581586)
		(width 0.18288)
		(layer "In4.Cu")
		(net "M_G_CPU0_SA_DQS_DN<2>")
	)
	(segment
		(start 425.589446 -294.047672)
		(end 425.292774 -294.047672)
		(width 0.18288)
		(layer "In4.Cu")
		(net "M_G_CPU0_SA_DQS_DN<2>")
	)
	(segment
		(start 435.16296 -293.636446)
		(end 434.912008 -293.385494)
		(width 0.18288)
		(layer "In4.Cu")
		(net "M_G_CPU0_SA_DQS_DN<2>")
	)
	(segment
		(start 380.563628 -265.632438)
		(end 380.553214 -265.638534)
		(width 0.088646)
		(layer "In4.Cu")
		(net "M_G_CPU0_SA_DQS_DN<2>")
	)
	(arc
		(start 385.194048 -265.665966)
		(mid 385.032885 -265.687393)
		(end 384.877818 -265.638534)
		(width 0.088646)
		(layer "In4.Cu")
		(net "M_G_CPU0_SA_DQS_DN<2>")
	)
	(arc
		(start 383.372614 -265.638534)
		(mid 383.185416 -265.688677)
		(end 382.998218 -265.638534)
		(width 0.088646)
		(layer "In4.Cu")
		(net "M_G_CPU0_SA_DQS_DN<2>")
	)
	(arc
		(start 384.312414 -265.638534)
		(mid 384.125216 -265.688677)
		(end 383.938018 -265.638534)
		(width 0.088646)
		(layer "In4.Cu")
		(net "M_G_CPU0_SA_DQS_DN<2>")
	)
	(arc
		(start 382.432814 -265.638534)
		(mid 382.245616 -265.688677)
		(end 382.058418 -265.638534)
		(width 0.088646)
		(layer "In4.Cu")
		(net "M_G_CPU0_SA_DQS_DN<2>")
	)
	(arc
		(start 381.118364 -265.638534)
		(mid 380.841805 -265.562791)
		(end 380.563628 -265.632438)
		(width 0.088646)
		(layer "In4.Cu")
		(net "M_G_CPU0_SA_DQS_DN<2>")
	)
	(arc
		(start 380.553214 -265.638534)
		(mid 380.366016 -265.688677)
		(end 380.178818 -265.638534)
		(width 0.088646)
		(layer "In4.Cu")
		(net "M_G_CPU0_SA_DQS_DN<2>")
	)
	(arc
		(start 382.998218 -265.638534)
		(mid 382.724019 -265.562699)
		(end 382.447546 -265.629898)
		(width 0.088646)
		(layer "In4.Cu")
		(net "M_G_CPU0_SA_DQS_DN<2>")
	)
	(arc
		(start 378.65812 -264.980928)
		(mid 378.316566 -264.980239)
		(end 378.116338 -265.257026)
		(width 0.088646)
		(layer "In4.Cu")
		(net "M_G_CPU0_SA_DQS_DN<2>")
	)
	(arc
		(start 378.87529 -265.22553)
		(mid 378.851088 -265.192655)
		(end 378.82957 -265.157966)
		(width 0.088646)
		(layer "In4.Cu")
		(net "M_G_CPU0_SA_DQS_DN<2>")
	)
	(arc
		(start 383.938018 -265.638534)
		(mid 383.663789 -265.562609)
		(end 383.387346 -265.629898)
		(width 0.088646)
		(layer "In4.Cu")
		(net "M_G_CPU0_SA_DQS_DN<2>")
	)
	(arc
		(start 384.877818 -265.638534)
		(mid 384.603589 -265.562609)
		(end 384.327146 -265.629898)
		(width 0.088646)
		(layer "In4.Cu")
		(net "M_G_CPU0_SA_DQS_DN<2>")
	)
	(arc
		(start 378.812552 -265.128248)
		(mid 378.746373 -265.043688)
		(end 378.658882 -264.981436)
		(width 0.088646)
		(layer "In4.Cu")
		(net "M_G_CPU0_SA_DQS_DN<2>")
	)
	(arc
		(start 381.49276 -265.638534)
		(mid 381.305562 -265.688677)
		(end 381.118364 -265.638534)
		(width 0.088646)
		(layer "In4.Cu")
		(net "M_G_CPU0_SA_DQS_DN<2>")
	)
	(arc
		(start 382.058418 -265.638534)
		(mid 381.781605 -265.562664)
		(end 381.503174 -265.632438)
		(width 0.088646)
		(layer "In4.Cu")
		(net "M_G_CPU0_SA_DQS_DN<2>")
	)
	(arc
		(start 379.613414 -265.638534)
		(mid 379.426216 -265.688677)
		(end 379.239018 -265.638534)
		(width 0.088646)
		(layer "In4.Cu")
		(net "M_G_CPU0_SA_DQS_DN<2>")
	)
	(arc
		(start 380.178818 -265.638534)
		(mid 379.904589 -265.562609)
		(end 379.628146 -265.629898)
		(width 0.088646)
		(layer "In4.Cu")
		(net "M_G_CPU0_SA_DQS_DN<2>")
	)
	(arc
		(start 385.32816 -265.63574)
		(mid 385.260122 -265.646494)
		(end 385.194048 -265.665966)
		(width 0.088646)
		(layer "In4.Cu")
		(net "M_G_CPU0_SA_DQS_DN<2>")
	)
	(segment
		(start 442.899546 -303.367694)
		(end 443.31001 -302.95723)
		(width 0.20066)
		(layer "F.Cu")
		(net "M_G_CPU0_SA_DQS_DN<1>")
	)
	(segment
		(start 436.928514 -302.716692)
		(end 437.477154 -302.716692)
		(width 0.20066)
		(layer "F.Cu")
		(net "M_G_CPU0_SA_DQS_DN<1>")
	)
	(segment
		(start 442.038994 -303.1363)
		(end 442.363098 -303.1363)
		(width 0.20066)
		(layer "F.Cu")
		(net "M_G_CPU0_SA_DQS_DN<1>")
	)
	(segment
		(start 437.75884 -302.998378)
		(end 438.494678 -302.998378)
		(width 0.20066)
		(layer "F.Cu")
		(net "M_G_CPU0_SA_DQS_DN<1>")
	)
	(segment
		(start 443.642496 -302.95723)
		(end 443.883034 -302.716692)
		(width 0.20066)
		(layer "F.Cu")
		(net "M_G_CPU0_SA_DQS_DN<1>")
	)
	(segment
		(start 374.257316 -272.103342)
		(end 374.257062 -272.639282)
		(width 0.20066)
		(layer "F.Cu")
		(net "M_G_CPU0_SA_DQS_DN<1>")
	)
	(segment
		(start 443.883034 -302.716692)
		(end 444.472314 -302.716692)
		(width 0.20066)
		(layer "F.Cu")
		(net "M_G_CPU0_SA_DQS_DN<1>")
	)
	(segment
		(start 442.363098 -303.1363)
		(end 442.594492 -303.367694)
		(width 0.20066)
		(layer "F.Cu")
		(net "M_G_CPU0_SA_DQS_DN<1>")
	)
	(segment
		(start 438.494678 -302.998378)
		(end 438.909206 -303.412906)
		(width 0.20066)
		(layer "F.Cu")
		(net "M_G_CPU0_SA_DQS_DN<1>")
	)
	(segment
		(start 435.823614 -302.716692)
		(end 436.928514 -302.716692)
		(width 0.20066)
		(layer "F.Cu")
		(net "M_G_CPU0_SA_DQS_DN<1>")
	)
	(segment
		(start 439.849768 -303.141634)
		(end 439.854086 -303.141634)
		(width 0.101854)
		(layer "F.Cu")
		(net "M_G_CPU0_SA_DQS_DN<1>")
	)
	(segment
		(start 442.594492 -303.367694)
		(end 442.899546 -303.367694)
		(width 0.20066)
		(layer "F.Cu")
		(net "M_G_CPU0_SA_DQS_DN<1>")
	)
	(segment
		(start 443.31001 -302.95723)
		(end 443.642496 -302.95723)
		(width 0.20066)
		(layer "F.Cu")
		(net "M_G_CPU0_SA_DQS_DN<1>")
	)
	(segment
		(start 438.909206 -303.412906)
		(end 439.430922 -303.412906)
		(width 0.20066)
		(layer "F.Cu")
		(net "M_G_CPU0_SA_DQS_DN<1>")
	)
	(segment
		(start 437.477154 -302.716692)
		(end 437.75884 -302.998378)
		(width 0.20066)
		(layer "F.Cu")
		(net "M_G_CPU0_SA_DQS_DN<1>")
	)
	(segment
		(start 439.702194 -303.141634)
		(end 439.849768 -303.141634)
		(width 0.20066)
		(layer "F.Cu")
		(net "M_G_CPU0_SA_DQS_DN<1>")
	)
	(segment
		(start 439.854086 -303.141634)
		(end 442.03366 -303.141634)
		(width 0.1016)
		(layer "F.Cu")
		(net "M_G_CPU0_SA_DQS_DN<1>")
	)
	(segment
		(start 439.430922 -303.412906)
		(end 439.702194 -303.141634)
		(width 0.20066)
		(layer "F.Cu")
		(net "M_G_CPU0_SA_DQS_DN<1>")
	)
	(segment
		(start 442.03366 -303.141634)
		(end 442.038994 -303.1363)
		(width 0.1016)
		(layer "F.Cu")
		(net "M_G_CPU0_SA_DQS_DN<1>")
	)
	(segment
		(start 413.765492 -294.027606)
		(end 412.481522 -294.027606)
		(width 0.18288)
		(layer "In6.Cu")
		(net "M_G_CPU0_SA_DQS_DN<1>")
	)
	(segment
		(start 425.350178 -297.437048)
		(end 425.105576 -297.192446)
		(width 0.18288)
		(layer "In6.Cu")
		(net "M_G_CPU0_SA_DQS_DN<1>")
	)
	(segment
		(start 383.467864 -272.96364)
		(end 383.453132 -272.955004)
		(width 0.088646)
		(layer "In6.Cu")
		(net "M_G_CPU0_SA_DQS_DN<1>")
	)
	(segment
		(start 412.194502 -293.740586)
		(end 411.769306 -293.740586)
		(width 0.18288)
		(layer "In6.Cu")
		(net "M_G_CPU0_SA_DQS_DN<1>")
	)
	(segment
		(start 375.39295 -272.320004)
		(end 375.38406 -272.314924)
		(width 0.088646)
		(layer "In6.Cu")
		(net "M_G_CPU0_SA_DQS_DN<1>")
	)
	(segment
		(start 411.769306 -293.740586)
		(end 411.44571 -294.064182)
		(width 0.18288)
		(layer "In6.Cu")
		(net "M_G_CPU0_SA_DQS_DN<1>")
	)
	(segment
		(start 412.481522 -294.027606)
		(end 412.194502 -293.740586)
		(width 0.18288)
		(layer "In6.Cu")
		(net "M_G_CPU0_SA_DQS_DN<1>")
	)
	(segment
		(start 376.889264 -272.96364)
		(end 376.874532 -272.955004)
		(width 0.088646)
		(layer "In6.Cu")
		(net "M_G_CPU0_SA_DQS_DN<1>")
	)
	(segment
		(start 421.911526 -296.59072)
		(end 421.253666 -296.59072)
		(width 0.18288)
		(layer "In6.Cu")
		(net "M_G_CPU0_SA_DQS_DN<1>")
	)
	(segment
		(start 375.949464 -272.96364)
		(end 375.94794 -272.962878)
		(width 0.088646)
		(layer "In6.Cu")
		(net "M_G_CPU0_SA_DQS_DN<1>")
	)
	(segment
		(start 416.744658 -296.62247)
		(end 415.652204 -295.530016)
		(width 0.18288)
		(layer "In6.Cu")
		(net "M_G_CPU0_SA_DQS_DN<1>")
	)
	(segment
		(start 374.826784 -272.582132)
		(end 374.769634 -272.639282)
		(width 0.088646)
		(layer "In6.Cu")
		(net "M_G_CPU0_SA_DQS_DN<1>")
	)
	(segment
		(start 390.037828 -274.752816)
		(end 389.12673 -274.375372)
		(width 0.18288)
		(layer "In6.Cu")
		(net "M_G_CPU0_SA_DQS_DN<1>")
	)
	(segment
		(start 375.94794 -272.962878)
		(end 375.944384 -272.960846)
		(width 0.088646)
		(layer "In6.Cu")
		(net "M_G_CPU0_SA_DQS_DN<1>")
	)
	(segment
		(start 421.005508 -296.342562)
		(end 420.47668 -296.342562)
		(width 0.18288)
		(layer "In6.Cu")
		(net "M_G_CPU0_SA_DQS_DN<1>")
	)
	(segment
		(start 430.305972 -300.606206)
		(end 428.731172 -299.031406)
		(width 0.18288)
		(layer "In6.Cu")
		(net "M_G_CPU0_SA_DQS_DN<1>")
	)
	(segment
		(start 388.535672 -274.375372)
		(end 388.512304 -274.375372)
		(width 0.088646)
		(layer "In6.Cu")
		(net "M_G_CPU0_SA_DQS_DN<1>")
	)
	(segment
		(start 425.105576 -297.192446)
		(end 424.576748 -297.192446)
		(width 0.18288)
		(layer "In6.Cu")
		(net "M_G_CPU0_SA_DQS_DN<1>")
	)
	(segment
		(start 426.232066 -297.437048)
		(end 425.350178 -297.437048)
		(width 0.18288)
		(layer "In6.Cu")
		(net "M_G_CPU0_SA_DQS_DN<1>")
	)
	(segment
		(start 410.565092 -293.762176)
		(end 408.601164 -292.947852)
		(width 0.18288)
		(layer "In6.Cu")
		(net "M_G_CPU0_SA_DQS_DN<1>")
	)
	(segment
		(start 433.406804 -302.649382)
		(end 431.363628 -300.606206)
		(width 0.18288)
		(layer "In6.Cu")
		(net "M_G_CPU0_SA_DQS_DN<1>")
	)
	(segment
		(start 385.73202 -272.957544)
		(end 385.713224 -272.968466)
		(width 0.088646)
		(layer "In6.Cu")
		(net "M_G_CPU0_SA_DQS_DN<1>")
	)
	(segment
		(start 402.14931 -289.625278)
		(end 402.14931 -280.97861)
		(width 0.18288)
		(layer "In6.Cu")
		(net "M_G_CPU0_SA_DQS_DN<1>")
	)
	(segment
		(start 424.298618 -297.470576)
		(end 422.791382 -297.470576)
		(width 0.18288)
		(layer "In6.Cu")
		(net "M_G_CPU0_SA_DQS_DN<1>")
	)
	(segment
		(start 378.768864 -272.96364)
		(end 378.754132 -272.955004)
		(width 0.088646)
		(layer "In6.Cu")
		(net "M_G_CPU0_SA_DQS_DN<1>")
	)
	(segment
		(start 420.196772 -296.62247)
		(end 416.744658 -296.62247)
		(width 0.18288)
		(layer "In6.Cu")
		(net "M_G_CPU0_SA_DQS_DN<1>")
	)
	(segment
		(start 428.731172 -299.031406)
		(end 427.826424 -299.031406)
		(width 0.18288)
		(layer "In6.Cu")
		(net "M_G_CPU0_SA_DQS_DN<1>")
	)
	(segment
		(start 388.322058 -274.435062)
		(end 386.901182 -273.014186)
		(width 0.088646)
		(layer "In6.Cu")
		(net "M_G_CPU0_SA_DQS_DN<1>")
	)
	(segment
		(start 410.866844 -294.064182)
		(end 410.565092 -293.762176)
		(width 0.18288)
		(layer "In6.Cu")
		(net "M_G_CPU0_SA_DQS_DN<1>")
	)
	(segment
		(start 420.47668 -296.342562)
		(end 420.196772 -296.62247)
		(width 0.18288)
		(layer "In6.Cu")
		(net "M_G_CPU0_SA_DQS_DN<1>")
	)
	(segment
		(start 402.14931 -280.97861)
		(end 395.923516 -274.752816)
		(width 0.18288)
		(layer "In6.Cu")
		(net "M_G_CPU0_SA_DQS_DN<1>")
	)
	(segment
		(start 434.861462 -302.649382)
		(end 433.406804 -302.649382)
		(width 0.18288)
		(layer "In6.Cu")
		(net "M_G_CPU0_SA_DQS_DN<1>")
	)
	(segment
		(start 386.286248 -272.963894)
		(end 386.286502 -272.963894)
		(width 0.088646)
		(layer "In6.Cu")
		(net "M_G_CPU0_SA_DQS_DN<1>")
	)
	(segment
		(start 388.452614 -274.435062)
		(end 388.322058 -274.435062)
		(width 0.088646)
		(layer "In6.Cu")
		(net "M_G_CPU0_SA_DQS_DN<1>")
	)
	(segment
		(start 408.601164 -292.947852)
		(end 405.471884 -292.947852)
		(width 0.18288)
		(layer "In6.Cu")
		(net "M_G_CPU0_SA_DQS_DN<1>")
	)
	(segment
		(start 375.009664 -272.314924)
		(end 375.00814 -272.315686)
		(width 0.088646)
		(layer "In6.Cu")
		(net "M_G_CPU0_SA_DQS_DN<1>")
	)
	(segment
		(start 375.00814 -272.315686)
		(end 375.000774 -272.320004)
		(width 0.088646)
		(layer "In6.Cu")
		(net "M_G_CPU0_SA_DQS_DN<1>")
	)
	(segment
		(start 411.44571 -294.064182)
		(end 410.866844 -294.064182)
		(width 0.18288)
		(layer "In6.Cu")
		(net "M_G_CPU0_SA_DQS_DN<1>")
	)
	(segment
		(start 377.829064 -272.96364)
		(end 377.814332 -272.955004)
		(width 0.088646)
		(layer "In6.Cu")
		(net "M_G_CPU0_SA_DQS_DN<1>")
	)
	(segment
		(start 427.826424 -299.031406)
		(end 426.232066 -297.437048)
		(width 0.18288)
		(layer "In6.Cu")
		(net "M_G_CPU0_SA_DQS_DN<1>")
	)
	(segment
		(start 431.363628 -300.606206)
		(end 430.305972 -300.606206)
		(width 0.18288)
		(layer "In6.Cu")
		(net "M_G_CPU0_SA_DQS_DN<1>")
	)
	(segment
		(start 375.755662 -272.693892)
		(end 375.698258 -272.581116)
		(width 0.088646)
		(layer "In6.Cu")
		(net "M_G_CPU0_SA_DQS_DN<1>")
	)
	(segment
		(start 389.12673 -274.375372)
		(end 388.535672 -274.375372)
		(width 0.18288)
		(layer "In6.Cu")
		(net "M_G_CPU0_SA_DQS_DN<1>")
	)
	(segment
		(start 386.901182 -273.014186)
		(end 386.473954 -273.014186)
		(width 0.088646)
		(layer "In6.Cu")
		(net "M_G_CPU0_SA_DQS_DN<1>")
	)
	(segment
		(start 374.769634 -272.639282)
		(end 374.257062 -272.639282)
		(width 0.088646)
		(layer "In6.Cu")
		(net "M_G_CPU0_SA_DQS_DN<1>")
	)
	(segment
		(start 405.471884 -292.947852)
		(end 402.14931 -289.625278)
		(width 0.18288)
		(layer "In6.Cu")
		(net "M_G_CPU0_SA_DQS_DN<1>")
	)
	(segment
		(start 415.267902 -295.530016)
		(end 413.765492 -294.027606)
		(width 0.18288)
		(layer "In6.Cu")
		(net "M_G_CPU0_SA_DQS_DN<1>")
	)
	(segment
		(start 435.556152 -302.984154)
		(end 435.196234 -302.984154)
		(width 0.18288)
		(layer "In6.Cu")
		(net "M_G_CPU0_SA_DQS_DN<1>")
	)
	(segment
		(start 388.512304 -274.375372)
		(end 388.452614 -274.435062)
		(width 0.088646)
		(layer "In6.Cu")
		(net "M_G_CPU0_SA_DQS_DN<1>")
	)
	(segment
		(start 380.648464 -272.96364)
		(end 380.63805 -272.957544)
		(width 0.088646)
		(layer "In6.Cu")
		(net "M_G_CPU0_SA_DQS_DN<1>")
	)
	(segment
		(start 381.588264 -272.96364)
		(end 381.573532 -272.955004)
		(width 0.088646)
		(layer "In6.Cu")
		(net "M_G_CPU0_SA_DQS_DN<1>")
	)
	(segment
		(start 424.576748 -297.192446)
		(end 424.298618 -297.470576)
		(width 0.18288)
		(layer "In6.Cu")
		(net "M_G_CPU0_SA_DQS_DN<1>")
	)
	(segment
		(start 382.528064 -272.96364)
		(end 382.513332 -272.955004)
		(width 0.088646)
		(layer "In6.Cu")
		(net "M_G_CPU0_SA_DQS_DN<1>")
	)
	(segment
		(start 422.791382 -297.470576)
		(end 421.911526 -296.59072)
		(width 0.18288)
		(layer "In6.Cu")
		(net "M_G_CPU0_SA_DQS_DN<1>")
	)
	(segment
		(start 415.652204 -295.530016)
		(end 415.267902 -295.530016)
		(width 0.18288)
		(layer "In6.Cu")
		(net "M_G_CPU0_SA_DQS_DN<1>")
	)
	(segment
		(start 435.196234 -302.984154)
		(end 434.861462 -302.649382)
		(width 0.18288)
		(layer "In6.Cu")
		(net "M_G_CPU0_SA_DQS_DN<1>")
	)
	(segment
		(start 395.923516 -274.752816)
		(end 390.037828 -274.752816)
		(width 0.18288)
		(layer "In6.Cu")
		(net "M_G_CPU0_SA_DQS_DN<1>")
	)
	(segment
		(start 375.68378 -272.56105)
		(end 375.60377 -272.48104)
		(width 0.088646)
		(layer "In6.Cu")
		(net "M_G_CPU0_SA_DQS_DN<1>")
	)
	(segment
		(start 435.823614 -302.716692)
		(end 435.556152 -302.984154)
		(width 0.18288)
		(layer "In6.Cu")
		(net "M_G_CPU0_SA_DQS_DN<1>")
	)
	(segment
		(start 386.286502 -272.963894)
		(end 386.286756 -272.96364)
		(width 0.088646)
		(layer "In6.Cu")
		(net "M_G_CPU0_SA_DQS_DN<1>")
	)
	(segment
		(start 379.708918 -272.96364)
		(end 379.698504 -272.957544)
		(width 0.088646)
		(layer "In6.Cu")
		(net "M_G_CPU0_SA_DQS_DN<1>")
	)
	(segment
		(start 375.944384 -272.960846)
		(end 375.944384 -272.960592)
		(width 0.088646)
		(layer "In6.Cu")
		(net "M_G_CPU0_SA_DQS_DN<1>")
	)
	(segment
		(start 421.253666 -296.59072)
		(end 421.005508 -296.342562)
		(width 0.18288)
		(layer "In6.Cu")
		(net "M_G_CPU0_SA_DQS_DN<1>")
	)
	(arc
		(start 375.698258 -272.581116)
		(mid 375.691806 -272.570516)
		(end 375.68378 -272.56105)
		(width 0.088646)
		(layer "In6.Cu")
		(net "M_G_CPU0_SA_DQS_DN<1>")
	)
	(arc
		(start 376.874532 -272.955004)
		(mid 376.598057 -272.887684)
		(end 376.32386 -272.96364)
		(width 0.088646)
		(layer "In6.Cu")
		(net "M_G_CPU0_SA_DQS_DN<1>")
	)
	(arc
		(start 382.513332 -272.955004)
		(mid 382.236857 -272.887684)
		(end 381.96266 -272.96364)
		(width 0.088646)
		(layer "In6.Cu")
		(net "M_G_CPU0_SA_DQS_DN<1>")
	)
	(arc
		(start 378.20346 -272.96364)
		(mid 378.016262 -273.013783)
		(end 377.829064 -272.96364)
		(width 0.088646)
		(layer "In6.Cu")
		(net "M_G_CPU0_SA_DQS_DN<1>")
	)
	(arc
		(start 375.60377 -272.48104)
		(mid 375.503723 -272.393502)
		(end 375.39295 -272.320004)
		(width 0.088646)
		(layer "In6.Cu")
		(net "M_G_CPU0_SA_DQS_DN<1>")
	)
	(arc
		(start 379.698504 -272.957544)
		(mid 379.420072 -272.887698)
		(end 379.14326 -272.96364)
		(width 0.088646)
		(layer "In6.Cu")
		(net "M_G_CPU0_SA_DQS_DN<1>")
	)
	(arc
		(start 384.78206 -272.96364)
		(mid 384.594862 -273.013783)
		(end 384.407664 -272.96364)
		(width 0.088646)
		(layer "In6.Cu")
		(net "M_G_CPU0_SA_DQS_DN<1>")
	)
	(arc
		(start 382.90246 -272.96364)
		(mid 382.715262 -273.013783)
		(end 382.528064 -272.96364)
		(width 0.088646)
		(layer "In6.Cu")
		(net "M_G_CPU0_SA_DQS_DN<1>")
	)
	(arc
		(start 383.453132 -272.955004)
		(mid 383.176657 -272.887684)
		(end 382.90246 -272.96364)
		(width 0.088646)
		(layer "In6.Cu")
		(net "M_G_CPU0_SA_DQS_DN<1>")
	)
	(arc
		(start 375.000774 -272.320004)
		(mid 374.884965 -272.431933)
		(end 374.826784 -272.582132)
		(width 0.088646)
		(layer "In6.Cu")
		(net "M_G_CPU0_SA_DQS_DN<1>")
	)
	(arc
		(start 377.814332 -272.955004)
		(mid 377.537857 -272.887684)
		(end 377.26366 -272.96364)
		(width 0.088646)
		(layer "In6.Cu")
		(net "M_G_CPU0_SA_DQS_DN<1>")
	)
	(arc
		(start 381.96266 -272.96364)
		(mid 381.775462 -273.013783)
		(end 381.588264 -272.96364)
		(width 0.088646)
		(layer "In6.Cu")
		(net "M_G_CPU0_SA_DQS_DN<1>")
	)
	(arc
		(start 386.286756 -272.96364)
		(mid 386.010197 -272.887897)
		(end 385.73202 -272.957544)
		(width 0.088646)
		(layer "In6.Cu")
		(net "M_G_CPU0_SA_DQS_DN<1>")
	)
	(arc
		(start 375.38406 -272.314924)
		(mid 375.196862 -272.264781)
		(end 375.009664 -272.314924)
		(width 0.088646)
		(layer "In6.Cu")
		(net "M_G_CPU0_SA_DQS_DN<1>")
	)
	(arc
		(start 381.573532 -272.955004)
		(mid 381.297057 -272.887684)
		(end 381.02286 -272.96364)
		(width 0.088646)
		(layer "In6.Cu")
		(net "M_G_CPU0_SA_DQS_DN<1>")
	)
	(arc
		(start 381.02286 -272.96364)
		(mid 380.835662 -273.013783)
		(end 380.648464 -272.96364)
		(width 0.088646)
		(layer "In6.Cu")
		(net "M_G_CPU0_SA_DQS_DN<1>")
	)
	(arc
		(start 378.754132 -272.955004)
		(mid 378.477657 -272.887684)
		(end 378.20346 -272.96364)
		(width 0.088646)
		(layer "In6.Cu")
		(net "M_G_CPU0_SA_DQS_DN<1>")
	)
	(arc
		(start 379.14326 -272.96364)
		(mid 378.956062 -273.013783)
		(end 378.768864 -272.96364)
		(width 0.088646)
		(layer "In6.Cu")
		(net "M_G_CPU0_SA_DQS_DN<1>")
	)
	(arc
		(start 380.63805 -272.957544)
		(mid 380.359872 -272.887821)
		(end 380.083314 -272.96364)
		(width 0.088646)
		(layer "In6.Cu")
		(net "M_G_CPU0_SA_DQS_DN<1>")
	)
	(arc
		(start 375.77903 -272.751804)
		(mid 375.768566 -272.722355)
		(end 375.755662 -272.693892)
		(width 0.088646)
		(layer "In6.Cu")
		(net "M_G_CPU0_SA_DQS_DN<1>")
	)
	(arc
		(start 385.347464 -272.96364)
		(mid 385.064762 -272.887864)
		(end 384.78206 -272.96364)
		(width 0.088646)
		(layer "In6.Cu")
		(net "M_G_CPU0_SA_DQS_DN<1>")
	)
	(arc
		(start 376.32386 -272.96364)
		(mid 376.136662 -273.013783)
		(end 375.949464 -272.96364)
		(width 0.088646)
		(layer "In6.Cu")
		(net "M_G_CPU0_SA_DQS_DN<1>")
	)
	(arc
		(start 377.26366 -272.96364)
		(mid 377.076462 -273.013783)
		(end 376.889264 -272.96364)
		(width 0.088646)
		(layer "In6.Cu")
		(net "M_G_CPU0_SA_DQS_DN<1>")
	)
	(arc
		(start 386.473954 -273.014186)
		(mid 386.376796 -273.001387)
		(end 386.286248 -272.963894)
		(width 0.088646)
		(layer "In6.Cu")
		(net "M_G_CPU0_SA_DQS_DN<1>")
	)
	(arc
		(start 375.942352 -272.959322)
		(mid 375.841799 -272.870432)
		(end 375.77903 -272.751804)
		(width 0.088646)
		(layer "In6.Cu")
		(net "M_G_CPU0_SA_DQS_DN<1>")
	)
	(arc
		(start 383.84226 -272.96364)
		(mid 383.655062 -273.013783)
		(end 383.467864 -272.96364)
		(width 0.088646)
		(layer "In6.Cu")
		(net "M_G_CPU0_SA_DQS_DN<1>")
	)
	(arc
		(start 384.407664 -272.96364)
		(mid 384.124962 -272.887864)
		(end 383.84226 -272.96364)
		(width 0.088646)
		(layer "In6.Cu")
		(net "M_G_CPU0_SA_DQS_DN<1>")
	)
	(arc
		(start 375.944384 -272.960592)
		(mid 375.943367 -272.959959)
		(end 375.942352 -272.959322)
		(width 0.088646)
		(layer "In6.Cu")
		(net "M_G_CPU0_SA_DQS_DN<1>")
	)
	(arc
		(start 380.083314 -272.96364)
		(mid 379.896116 -273.013783)
		(end 379.708918 -272.96364)
		(width 0.088646)
		(layer "In6.Cu")
		(net "M_G_CPU0_SA_DQS_DN<1>")
	)
	(arc
		(start 385.713224 -272.968466)
		(mid 385.529716 -273.013744)
		(end 385.347464 -272.96364)
		(width 0.088646)
		(layer "In6.Cu")
		(net "M_G_CPU0_SA_DQS_DN<1>")
	)
	(segment
		(start 442.038994 -312.486294)
		(end 442.363098 -312.486294)
		(width 0.20066)
		(layer "F.Cu")
		(net "M_G_CPU0_SA_DQS_DN<0>")
	)
	(segment
		(start 442.899546 -312.717688)
		(end 443.31001 -312.307224)
		(width 0.20066)
		(layer "F.Cu")
		(net "M_G_CPU0_SA_DQS_DN<0>")
	)
	(segment
		(start 439.849768 -312.491628)
		(end 439.854086 -312.491628)
		(width 0.101854)
		(layer "F.Cu")
		(net "M_G_CPU0_SA_DQS_DN<0>")
	)
	(segment
		(start 378.486416 -274.545044)
		(end 378.486416 -275.08073)
		(width 0.20066)
		(layer "F.Cu")
		(net "M_G_CPU0_SA_DQS_DN<0>")
	)
	(segment
		(start 439.702194 -312.491628)
		(end 439.849768 -312.491628)
		(width 0.20066)
		(layer "F.Cu")
		(net "M_G_CPU0_SA_DQS_DN<0>")
	)
	(segment
		(start 437.75884 -312.348372)
		(end 438.494678 -312.348372)
		(width 0.20066)
		(layer "F.Cu")
		(net "M_G_CPU0_SA_DQS_DN<0>")
	)
	(segment
		(start 442.03366 -312.491628)
		(end 442.038994 -312.486294)
		(width 0.1016)
		(layer "F.Cu")
		(net "M_G_CPU0_SA_DQS_DN<0>")
	)
	(segment
		(start 443.883034 -312.066686)
		(end 444.472314 -312.066686)
		(width 0.20066)
		(layer "F.Cu")
		(net "M_G_CPU0_SA_DQS_DN<0>")
	)
	(segment
		(start 378.486162 -274.54479)
		(end 378.486416 -274.545044)
		(width 0.20066)
		(layer "F.Cu")
		(net "M_G_CPU0_SA_DQS_DN<0>")
	)
	(segment
		(start 443.642496 -312.307224)
		(end 443.883034 -312.066686)
		(width 0.20066)
		(layer "F.Cu")
		(net "M_G_CPU0_SA_DQS_DN<0>")
	)
	(segment
		(start 436.928514 -312.066686)
		(end 437.477154 -312.066686)
		(width 0.20066)
		(layer "F.Cu")
		(net "M_G_CPU0_SA_DQS_DN<0>")
	)
	(segment
		(start 437.477154 -312.066686)
		(end 437.75884 -312.348372)
		(width 0.20066)
		(layer "F.Cu")
		(net "M_G_CPU0_SA_DQS_DN<0>")
	)
	(segment
		(start 435.823614 -312.066686)
		(end 436.928514 -312.066686)
		(width 0.20066)
		(layer "F.Cu")
		(net "M_G_CPU0_SA_DQS_DN<0>")
	)
	(segment
		(start 442.363098 -312.486294)
		(end 442.594492 -312.717688)
		(width 0.20066)
		(layer "F.Cu")
		(net "M_G_CPU0_SA_DQS_DN<0>")
	)
	(segment
		(start 439.430922 -312.7629)
		(end 439.702194 -312.491628)
		(width 0.20066)
		(layer "F.Cu")
		(net "M_G_CPU0_SA_DQS_DN<0>")
	)
	(segment
		(start 438.494678 -312.348372)
		(end 438.909206 -312.7629)
		(width 0.20066)
		(layer "F.Cu")
		(net "M_G_CPU0_SA_DQS_DN<0>")
	)
	(segment
		(start 442.594492 -312.717688)
		(end 442.899546 -312.717688)
		(width 0.20066)
		(layer "F.Cu")
		(net "M_G_CPU0_SA_DQS_DN<0>")
	)
	(segment
		(start 438.909206 -312.7629)
		(end 439.430922 -312.7629)
		(width 0.20066)
		(layer "F.Cu")
		(net "M_G_CPU0_SA_DQS_DN<0>")
	)
	(segment
		(start 439.854086 -312.491628)
		(end 442.03366 -312.491628)
		(width 0.1016)
		(layer "F.Cu")
		(net "M_G_CPU0_SA_DQS_DN<0>")
	)
	(segment
		(start 443.31001 -312.307224)
		(end 443.642496 -312.307224)
		(width 0.20066)
		(layer "F.Cu")
		(net "M_G_CPU0_SA_DQS_DN<0>")
	)
	(segment
		(start 415.97707 -312.949844)
		(end 414.646364 -312.949844)
		(width 0.18288)
		(layer "In4.Cu")
		(net "M_G_CPU0_SA_DQS_DN<0>")
	)
	(segment
		(start 416.470592 -313.443366)
		(end 415.97707 -312.949844)
		(width 0.18288)
		(layer "In4.Cu")
		(net "M_G_CPU0_SA_DQS_DN<0>")
	)
	(segment
		(start 407.21661 -309.874666)
		(end 407.21661 -309.698644)
		(width 0.18288)
		(layer "In4.Cu")
		(net "M_G_CPU0_SA_DQS_DN<0>")
	)
	(segment
		(start 386.569458 -278.346916)
		(end 386.569712 -278.346662)
		(width 0.088646)
		(layer "In4.Cu")
		(net "M_G_CPU0_SA_DQS_DN<0>")
	)
	(segment
		(start 384.877564 -277.032974)
		(end 384.868674 -277.027894)
		(width 0.088646)
		(layer "In4.Cu")
		(net "M_G_CPU0_SA_DQS_DN<0>")
	)
	(segment
		(start 425.798996 -314.461398)
		(end 425.297854 -314.461398)
		(width 0.18288)
		(layer "In4.Cu")
		(net "M_G_CPU0_SA_DQS_DN<0>")
	)
	(segment
		(start 384.690112 -276.708616)
		(end 384.690112 -276.69871)
		(width 0.088646)
		(layer "In4.Cu")
		(net "M_G_CPU0_SA_DQS_DN<0>")
	)
	(segment
		(start 385.160012 -277.522432)
		(end 385.160012 -277.512526)
		(width 0.088646)
		(layer "In4.Cu")
		(net "M_G_CPU0_SA_DQS_DN<0>")
	)
	(segment
		(start 418.95395 -314.841382)
		(end 418.95395 -314.66536)
		(width 0.18288)
		(layer "In4.Cu")
		(net "M_G_CPU0_SA_DQS_DN<0>")
	)
	(segment
		(start 385.347464 -277.84679)
		(end 385.338574 -277.84171)
		(width 0.088646)
		(layer "In4.Cu")
		(net "M_G_CPU0_SA_DQS_DN<0>")
	)
	(segment
		(start 383.46634 -276.218396)
		(end 383.458974 -276.214078)
		(width 0.088646)
		(layer "In4.Cu")
		(net "M_G_CPU0_SA_DQS_DN<0>")
	)
	(segment
		(start 428.79264 -313.031632)
		(end 427.79823 -313.031632)
		(width 0.18288)
		(layer "In4.Cu")
		(net "M_G_CPU0_SA_DQS_DN<0>")
	)
	(segment
		(start 380.563628 -275.398992)
		(end 380.553214 -275.405088)
		(width 0.088646)
		(layer "In4.Cu")
		(net "M_G_CPU0_SA_DQS_DN<0>")
	)
	(segment
		(start 387.997954 -279.249124)
		(end 387.46049 -278.71166)
		(width 0.088646)
		(layer "In4.Cu")
		(net "M_G_CPU0_SA_DQS_DN<0>")
	)
	(segment
		(start 406.103836 -308.761892)
		(end 404.501858 -308.761892)
		(width 0.18288)
		(layer "In4.Cu")
		(net "M_G_CPU0_SA_DQS_DN<0>")
	)
	(segment
		(start 427.241716 -313.588146)
		(end 426.672248 -313.588146)
		(width 0.18288)
		(layer "In4.Cu")
		(net "M_G_CPU0_SA_DQS_DN<0>")
	)
	(segment
		(start 417.555934 -313.443366)
		(end 416.470592 -313.443366)
		(width 0.18288)
		(layer "In4.Cu")
		(net "M_G_CPU0_SA_DQS_DN<0>")
	)
	(segment
		(start 407.60269 -310.260746)
		(end 407.21661 -309.874666)
		(width 0.18288)
		(layer "In4.Cu")
		(net "M_G_CPU0_SA_DQS_DN<0>")
	)
	(segment
		(start 418.567362 -314.278772)
		(end 418.39134 -314.278772)
		(width 0.18288)
		(layer "In4.Cu")
		(net "M_G_CPU0_SA_DQS_DN<0>")
	)
	(segment
		(start 378.173488 -275.08073)
		(end 378.486416 -275.08073)
		(width 0.088646)
		(layer "In4.Cu")
		(net "M_G_CPU0_SA_DQS_DN<0>")
	)
	(segment
		(start 424.635168 -314.192158)
		(end 424.371516 -314.45581)
		(width 0.18288)
		(layer "In4.Cu")
		(net "M_G_CPU0_SA_DQS_DN<0>")
	)
	(segment
		(start 425.297854 -314.461398)
		(end 425.028614 -314.192158)
		(width 0.18288)
		(layer "In4.Cu")
		(net "M_G_CPU0_SA_DQS_DN<0>")
	)
	(segment
		(start 429.58766 -313.031632)
		(end 429.4632 -312.907172)
		(width 0.18288)
		(layer "In4.Cu")
		(net "M_G_CPU0_SA_DQS_DN<0>")
	)
	(segment
		(start 378.688346 -275.396452)
		(end 378.673614 -275.405088)
		(width 0.088646)
		(layer "In4.Cu")
		(net "M_G_CPU0_SA_DQS_DN<0>")
	)
	(segment
		(start 406.654254 -309.31231)
		(end 406.103836 -308.761892)
		(width 0.18288)
		(layer "In4.Cu")
		(net "M_G_CPU0_SA_DQS_DN<0>")
	)
	(segment
		(start 382.438402 -275.401786)
		(end 382.432814 -275.405088)
		(width 0.088646)
		(layer "In4.Cu")
		(net "M_G_CPU0_SA_DQS_DN<0>")
	)
	(segment
		(start 425.028614 -314.192158)
		(end 424.635168 -314.192158)
		(width 0.18288)
		(layer "In4.Cu")
		(net "M_G_CPU0_SA_DQS_DN<0>")
	)
	(segment
		(start 418.39134 -314.278772)
		(end 417.555934 -313.443366)
		(width 0.18288)
		(layer "In4.Cu")
		(net "M_G_CPU0_SA_DQS_DN<0>")
	)
	(segment
		(start 403.264878 -307.524912)
		(end 396.38097 -297.222418)
		(width 0.18288)
		(layer "In4.Cu")
		(net "M_G_CPU0_SA_DQS_DN<0>")
	)
	(segment
		(start 435.253638 -312.330846)
		(end 435.091078 -312.168286)
		(width 0.18288)
		(layer "In4.Cu")
		(net "M_G_CPU0_SA_DQS_DN<0>")
	)
	(segment
		(start 420.541704 -315.042296)
		(end 420.271702 -315.312298)
		(width 0.18288)
		(layer "In4.Cu")
		(net "M_G_CPU0_SA_DQS_DN<0>")
	)
	(segment
		(start 427.79823 -313.031632)
		(end 427.241716 -313.588146)
		(width 0.18288)
		(layer "In4.Cu")
		(net "M_G_CPU0_SA_DQS_DN<0>")
	)
	(segment
		(start 383.280412 -275.8948)
		(end 383.280412 -275.879306)
		(width 0.088646)
		(layer "In4.Cu")
		(net "M_G_CPU0_SA_DQS_DN<0>")
	)
	(segment
		(start 379.628146 -275.396452)
		(end 379.613414 -275.405088)
		(width 0.088646)
		(layer "In4.Cu")
		(net "M_G_CPU0_SA_DQS_DN<0>")
	)
	(segment
		(start 378.299218 -275.405088)
		(end 378.290328 -275.400008)
		(width 0.088646)
		(layer "In4.Cu")
		(net "M_G_CPU0_SA_DQS_DN<0>")
	)
	(segment
		(start 426.672248 -313.588146)
		(end 425.798996 -314.461398)
		(width 0.18288)
		(layer "In4.Cu")
		(net "M_G_CPU0_SA_DQS_DN<0>")
	)
	(segment
		(start 410.422598 -311.116726)
		(end 409.567126 -311.116726)
		(width 0.18288)
		(layer "In4.Cu")
		(net "M_G_CPU0_SA_DQS_DN<0>")
	)
	(segment
		(start 413.374586 -312.422794)
		(end 412.64967 -312.122566)
		(width 0.18288)
		(layer "In4.Cu")
		(net "M_G_CPU0_SA_DQS_DN<0>")
	)
	(segment
		(start 387.46049 -278.71166)
		(end 386.944362 -278.71166)
		(width 0.088646)
		(layer "In4.Cu")
		(net "M_G_CPU0_SA_DQS_DN<0>")
	)
	(segment
		(start 420.271702 -315.312298)
		(end 419.424866 -315.312298)
		(width 0.18288)
		(layer "In4.Cu")
		(net "M_G_CPU0_SA_DQS_DN<0>")
	)
	(segment
		(start 435.559454 -312.330846)
		(end 435.253638 -312.330846)
		(width 0.18288)
		(layer "In4.Cu")
		(net "M_G_CPU0_SA_DQS_DN<0>")
	)
	(segment
		(start 420.931086 -315.042296)
		(end 420.541704 -315.042296)
		(width 0.18288)
		(layer "In4.Cu")
		(net "M_G_CPU0_SA_DQS_DN<0>")
	)
	(segment
		(start 422.870884 -314.45581)
		(end 422.032684 -315.29401)
		(width 0.18288)
		(layer "In4.Cu")
		(net "M_G_CPU0_SA_DQS_DN<0>")
	)
	(segment
		(start 390.550146 -283.148532)
		(end 389.53694 -280.702766)
		(width 0.18288)
		(layer "In4.Cu")
		(net "M_G_CPU0_SA_DQS_DN<0>")
	)
	(segment
		(start 424.371516 -314.45581)
		(end 422.870884 -314.45581)
		(width 0.18288)
		(layer "In4.Cu")
		(net "M_G_CPU0_SA_DQS_DN<0>")
	)
	(segment
		(start 429.4632 -312.907172)
		(end 428.9171 -312.907172)
		(width 0.18288)
		(layer "In4.Cu")
		(net "M_G_CPU0_SA_DQS_DN<0>")
	)
	(segment
		(start 428.9171 -312.907172)
		(end 428.79264 -313.031632)
		(width 0.18288)
		(layer "In4.Cu")
		(net "M_G_CPU0_SA_DQS_DN<0>")
	)
	(segment
		(start 408.711146 -310.260746)
		(end 407.60269 -310.260746)
		(width 0.18288)
		(layer "In4.Cu")
		(net "M_G_CPU0_SA_DQS_DN<0>")
	)
	(segment
		(start 388.082282 -279.249124)
		(end 387.997954 -279.249124)
		(width 0.088646)
		(layer "In4.Cu")
		(net "M_G_CPU0_SA_DQS_DN<0>")
	)
	(segment
		(start 419.424866 -315.312298)
		(end 418.95395 -314.841382)
		(width 0.18288)
		(layer "In4.Cu")
		(net "M_G_CPU0_SA_DQS_DN<0>")
	)
	(segment
		(start 421.1828 -315.29401)
		(end 420.931086 -315.042296)
		(width 0.18288)
		(layer "In4.Cu")
		(net "M_G_CPU0_SA_DQS_DN<0>")
	)
	(segment
		(start 432.226212 -312.168286)
		(end 430.141634 -313.031632)
		(width 0.18288)
		(layer "In4.Cu")
		(net "M_G_CPU0_SA_DQS_DN<0>")
	)
	(segment
		(start 435.091078 -312.168286)
		(end 432.226212 -312.168286)
		(width 0.18288)
		(layer "In4.Cu")
		(net "M_G_CPU0_SA_DQS_DN<0>")
	)
	(segment
		(start 411.428438 -312.122566)
		(end 410.422598 -311.116726)
		(width 0.18288)
		(layer "In4.Cu")
		(net "M_G_CPU0_SA_DQS_DN<0>")
	)
	(segment
		(start 388.098792 -279.265634)
		(end 388.082282 -279.249124)
		(width 0.088646)
		(layer "In4.Cu")
		(net "M_G_CPU0_SA_DQS_DN<0>")
	)
	(segment
		(start 404.501858 -308.761892)
		(end 403.264878 -307.524912)
		(width 0.18288)
		(layer "In4.Cu")
		(net "M_G_CPU0_SA_DQS_DN<0>")
	)
	(segment
		(start 389.53694 -280.702766)
		(end 388.098792 -279.265634)
		(width 0.18288)
		(layer "In4.Cu")
		(net "M_G_CPU0_SA_DQS_DN<0>")
	)
	(segment
		(start 407.21661 -309.698644)
		(end 406.830276 -309.31231)
		(width 0.18288)
		(layer "In4.Cu")
		(net "M_G_CPU0_SA_DQS_DN<0>")
	)
	(segment
		(start 381.503174 -275.398992)
		(end 381.49276 -275.405088)
		(width 0.088646)
		(layer "In4.Cu")
		(net "M_G_CPU0_SA_DQS_DN<0>")
	)
	(segment
		(start 396.38097 -297.222418)
		(end 390.550146 -283.148532)
		(width 0.18288)
		(layer "In4.Cu")
		(net "M_G_CPU0_SA_DQS_DN<0>")
	)
	(segment
		(start 414.646364 -312.949844)
		(end 414.109408 -312.72734)
		(width 0.18288)
		(layer "In4.Cu")
		(net "M_G_CPU0_SA_DQS_DN<0>")
	)
	(segment
		(start 383.467864 -276.219158)
		(end 383.46634 -276.218396)
		(width 0.088646)
		(layer "In4.Cu")
		(net "M_G_CPU0_SA_DQS_DN<0>")
	)
	(segment
		(start 412.64967 -312.122566)
		(end 411.428438 -312.122566)
		(width 0.18288)
		(layer "In4.Cu")
		(net "M_G_CPU0_SA_DQS_DN<0>")
	)
	(segment
		(start 418.95395 -314.66536)
		(end 418.567362 -314.278772)
		(width 0.18288)
		(layer "In4.Cu")
		(net "M_G_CPU0_SA_DQS_DN<0>")
	)
	(segment
		(start 430.141634 -313.031632)
		(end 429.58766 -313.031632)
		(width 0.18288)
		(layer "In4.Cu")
		(net "M_G_CPU0_SA_DQS_DN<0>")
	)
	(segment
		(start 378.116338 -275.13788)
		(end 378.173488 -275.08073)
		(width 0.088646)
		(layer "In4.Cu")
		(net "M_G_CPU0_SA_DQS_DN<0>")
	)
	(segment
		(start 435.823614 -312.066686)
		(end 435.559454 -312.330846)
		(width 0.18288)
		(layer "In4.Cu")
		(net "M_G_CPU0_SA_DQS_DN<0>")
	)
	(segment
		(start 422.032684 -315.29401)
		(end 421.1828 -315.29401)
		(width 0.18288)
		(layer "In4.Cu")
		(net "M_G_CPU0_SA_DQS_DN<0>")
	)
	(segment
		(start 414.109408 -312.72734)
		(end 414.041844 -312.564526)
		(width 0.18288)
		(layer "In4.Cu")
		(net "M_G_CPU0_SA_DQS_DN<0>")
	)
	(segment
		(start 414.041844 -312.564526)
		(end 413.537146 -312.355484)
		(width 0.18288)
		(layer "In4.Cu")
		(net "M_G_CPU0_SA_DQS_DN<0>")
	)
	(segment
		(start 386.569712 -278.336502)
		(end 386.569712 -278.31796)
		(width 0.088646)
		(layer "In4.Cu")
		(net "M_G_CPU0_SA_DQS_DN<0>")
	)
	(segment
		(start 413.537146 -312.355484)
		(end 413.374586 -312.422794)
		(width 0.18288)
		(layer "In4.Cu")
		(net "M_G_CPU0_SA_DQS_DN<0>")
	)
	(segment
		(start 406.830276 -309.31231)
		(end 406.654254 -309.31231)
		(width 0.18288)
		(layer "In4.Cu")
		(net "M_G_CPU0_SA_DQS_DN<0>")
	)
	(segment
		(start 409.567126 -311.116726)
		(end 408.711146 -310.260746)
		(width 0.18288)
		(layer "In4.Cu")
		(net "M_G_CPU0_SA_DQS_DN<0>")
	)
	(arc
		(start 384.407664 -276.219158)
		(mid 384.124962 -276.143382)
		(end 383.84226 -276.219158)
		(width 0.088646)
		(layer "In4.Cu")
		(net "M_G_CPU0_SA_DQS_DN<0>")
	)
	(arc
		(start 382.058418 -275.405088)
		(mid 381.781605 -275.329252)
		(end 381.503174 -275.398992)
		(width 0.088646)
		(layer "In4.Cu")
		(net "M_G_CPU0_SA_DQS_DN<0>")
	)
	(arc
		(start 378.290328 -275.400008)
		(mid 378.174519 -275.288079)
		(end 378.116338 -275.13788)
		(width 0.088646)
		(layer "In4.Cu")
		(net "M_G_CPU0_SA_DQS_DN<0>")
	)
	(arc
		(start 381.118364 -275.405088)
		(mid 380.841805 -275.329379)
		(end 380.563628 -275.398992)
		(width 0.088646)
		(layer "In4.Cu")
		(net "M_G_CPU0_SA_DQS_DN<0>")
	)
	(arc
		(start 386.569712 -278.31796)
		(mid 386.48955 -278.045771)
		(end 386.287264 -277.84679)
		(width 0.088646)
		(layer "In4.Cu")
		(net "M_G_CPU0_SA_DQS_DN<0>")
	)
	(arc
		(start 386.287264 -277.84679)
		(mid 386.004562 -277.771048)
		(end 385.72186 -277.84679)
		(width 0.088646)
		(layer "In4.Cu")
		(net "M_G_CPU0_SA_DQS_DN<0>")
	)
	(arc
		(start 386.569712 -278.346662)
		(mid 386.569678 -278.341582)
		(end 386.569712 -278.336502)
		(width 0.088646)
		(layer "In4.Cu")
		(net "M_G_CPU0_SA_DQS_DN<0>")
	)
	(arc
		(start 386.944362 -278.71166)
		(mid 386.682794 -278.605437)
		(end 386.569458 -278.346916)
		(width 0.088646)
		(layer "In4.Cu")
		(net "M_G_CPU0_SA_DQS_DN<0>")
	)
	(arc
		(start 379.239018 -275.405088)
		(mid 378.964789 -275.329163)
		(end 378.688346 -275.396452)
		(width 0.088646)
		(layer "In4.Cu")
		(net "M_G_CPU0_SA_DQS_DN<0>")
	)
	(arc
		(start 384.690112 -276.69871)
		(mid 384.612001 -276.421761)
		(end 384.407664 -276.219158)
		(width 0.088646)
		(layer "In4.Cu")
		(net "M_G_CPU0_SA_DQS_DN<0>")
	)
	(arc
		(start 380.553214 -275.405088)
		(mid 380.366016 -275.455231)
		(end 380.178818 -275.405088)
		(width 0.088646)
		(layer "In4.Cu")
		(net "M_G_CPU0_SA_DQS_DN<0>")
	)
	(arc
		(start 383.458974 -276.214078)
		(mid 383.32806 -276.077718)
		(end 383.280412 -275.8948)
		(width 0.088646)
		(layer "In4.Cu")
		(net "M_G_CPU0_SA_DQS_DN<0>")
	)
	(arc
		(start 381.49276 -275.405088)
		(mid 381.305562 -275.455231)
		(end 381.118364 -275.405088)
		(width 0.088646)
		(layer "In4.Cu")
		(net "M_G_CPU0_SA_DQS_DN<0>")
	)
	(arc
		(start 385.72186 -277.84679)
		(mid 385.534662 -277.896933)
		(end 385.347464 -277.84679)
		(width 0.088646)
		(layer "In4.Cu")
		(net "M_G_CPU0_SA_DQS_DN<0>")
	)
	(arc
		(start 384.868674 -277.027894)
		(mid 384.73776 -276.891534)
		(end 384.690112 -276.708616)
		(width 0.088646)
		(layer "In4.Cu")
		(net "M_G_CPU0_SA_DQS_DN<0>")
	)
	(arc
		(start 383.280412 -275.879306)
		(mid 383.201042 -275.605572)
		(end 382.998218 -275.405342)
		(width 0.088646)
		(layer "In4.Cu")
		(net "M_G_CPU0_SA_DQS_DN<0>")
	)
	(arc
		(start 379.613414 -275.405088)
		(mid 379.426216 -275.455231)
		(end 379.239018 -275.405088)
		(width 0.088646)
		(layer "In4.Cu")
		(net "M_G_CPU0_SA_DQS_DN<0>")
	)
	(arc
		(start 380.178818 -275.405088)
		(mid 379.904589 -275.329163)
		(end 379.628146 -275.396452)
		(width 0.088646)
		(layer "In4.Cu")
		(net "M_G_CPU0_SA_DQS_DN<0>")
	)
	(arc
		(start 385.338574 -277.84171)
		(mid 385.20766 -277.70535)
		(end 385.160012 -277.522432)
		(width 0.088646)
		(layer "In4.Cu")
		(net "M_G_CPU0_SA_DQS_DN<0>")
	)
	(arc
		(start 378.673614 -275.405088)
		(mid 378.486416 -275.455231)
		(end 378.299218 -275.405088)
		(width 0.088646)
		(layer "In4.Cu")
		(net "M_G_CPU0_SA_DQS_DN<0>")
	)
	(arc
		(start 383.84226 -276.219158)
		(mid 383.655062 -276.269301)
		(end 383.467864 -276.219158)
		(width 0.088646)
		(layer "In4.Cu")
		(net "M_G_CPU0_SA_DQS_DN<0>")
	)
	(arc
		(start 385.160012 -277.512526)
		(mid 385.081901 -277.235577)
		(end 384.877564 -277.032974)
		(width 0.088646)
		(layer "In4.Cu")
		(net "M_G_CPU0_SA_DQS_DN<0>")
	)
	(arc
		(start 382.998218 -275.405342)
		(mid 382.71879 -275.32945)
		(end 382.438402 -275.401786)
		(width 0.088646)
		(layer "In4.Cu")
		(net "M_G_CPU0_SA_DQS_DN<0>")
	)
	(arc
		(start 382.432814 -275.405088)
		(mid 382.245616 -275.455231)
		(end 382.058418 -275.405088)
		(width 0.088646)
		(layer "In4.Cu")
		(net "M_G_CPU0_SA_DQS_DN<0>")
	)
	(segment
		(start 444.472314 -305.266598)
		(end 444.47206 -305.266852)
		(width 0.20066)
		(layer "F.Cu")
		(net "M_G_CPU0_SA_DQ<9>")
	)
	(segment
		(start 442.032644 -304.841656)
		(end 439.843926 -304.841656)
		(width 0.1016)
		(layer "F.Cu")
		(net "M_G_CPU0_SA_DQ<9>")
	)
	(segment
		(start 439.843926 -304.841656)
		(end 439.82386 -304.841656)
		(width 0.101854)
		(layer "F.Cu")
		(net "M_G_CPU0_SA_DQ<9>")
	)
	(segment
		(start 442.038994 -304.835306)
		(end 442.032644 -304.841656)
		(width 0.1016)
		(layer "F.Cu")
		(net "M_G_CPU0_SA_DQ<9>")
	)
	(segment
		(start 442.44895 -304.835306)
		(end 442.038994 -304.835306)
		(width 0.20066)
		(layer "F.Cu")
		(net "M_G_CPU0_SA_DQ<9>")
	)
	(segment
		(start 438.697878 -305.515264)
		(end 438.449212 -305.266598)
		(width 0.20066)
		(layer "F.Cu")
		(net "M_G_CPU0_SA_DQ<9>")
	)
	(segment
		(start 439.479182 -304.841656)
		(end 439.361072 -304.959766)
		(width 0.20066)
		(layer "F.Cu")
		(net "M_G_CPU0_SA_DQ<9>")
	)
	(segment
		(start 439.361072 -305.327304)
		(end 439.173112 -305.515264)
		(width 0.20066)
		(layer "F.Cu")
		(net "M_G_CPU0_SA_DQ<9>")
	)
	(segment
		(start 439.82386 -304.841656)
		(end 439.479182 -304.841656)
		(width 0.20066)
		(layer "F.Cu")
		(net "M_G_CPU0_SA_DQ<9>")
	)
	(segment
		(start 439.361072 -304.959766)
		(end 439.361072 -305.327304)
		(width 0.20066)
		(layer "F.Cu")
		(net "M_G_CPU0_SA_DQ<9>")
	)
	(segment
		(start 436.928514 -305.266598)
		(end 435.823614 -305.266598)
		(width 0.20066)
		(layer "F.Cu")
		(net "M_G_CPU0_SA_DQ<9>")
	)
	(segment
		(start 442.880496 -305.266852)
		(end 442.44895 -304.835306)
		(width 0.20066)
		(layer "F.Cu")
		(net "M_G_CPU0_SA_DQ<9>")
	)
	(segment
		(start 444.47206 -305.266852)
		(end 442.880496 -305.266852)
		(width 0.20066)
		(layer "F.Cu")
		(net "M_G_CPU0_SA_DQ<9>")
	)
	(segment
		(start 439.173112 -305.515264)
		(end 438.697878 -305.515264)
		(width 0.20066)
		(layer "F.Cu")
		(net "M_G_CPU0_SA_DQ<9>")
	)
	(segment
		(start 374.726962 -272.917158)
		(end 374.726962 -273.452844)
		(width 0.20066)
		(layer "F.Cu")
		(net "M_G_CPU0_SA_DQ<9>")
	)
	(segment
		(start 374.726962 -273.452844)
		(end 374.727216 -273.453098)
		(width 0.20066)
		(layer "F.Cu")
		(net "M_G_CPU0_SA_DQ<9>")
	)
	(segment
		(start 438.449212 -305.266598)
		(end 436.928514 -305.266598)
		(width 0.20066)
		(layer "F.Cu")
		(net "M_G_CPU0_SA_DQ<9>")
	)
	(segment
		(start 419.826694 -298.734226)
		(end 418.935154 -298.734226)
		(width 0.18288)
		(layer "In6.Cu")
		(net "M_G_CPU0_SA_DQ<9>")
	)
	(segment
		(start 381.588264 -273.942556)
		(end 381.57785 -273.948652)
		(width 0.088646)
		(layer "In6.Cu")
		(net "M_G_CPU0_SA_DQ<9>")
	)
	(segment
		(start 426.701712 -300.414944)
		(end 426.028866 -299.742098)
		(width 0.18288)
		(layer "In6.Cu")
		(net "M_G_CPU0_SA_DQ<9>")
	)
	(segment
		(start 419.984682 -298.892214)
		(end 419.826694 -298.734226)
		(width 0.18288)
		(layer "In6.Cu")
		(net "M_G_CPU0_SA_DQ<9>")
	)
	(segment
		(start 430.459642 -302.890174)
		(end 430.622456 -302.727106)
		(width 0.18288)
		(layer "In6.Cu")
		(net "M_G_CPU0_SA_DQ<9>")
	)
	(segment
		(start 435.362096 -304.80508)
		(end 434.139594 -304.80508)
		(width 0.18288)
		(layer "In6.Cu")
		(net "M_G_CPU0_SA_DQ<9>")
	)
	(segment
		(start 400.84375 -281.521154)
		(end 395.382242 -276.058376)
		(width 0.18288)
		(layer "In6.Cu")
		(net "M_G_CPU0_SA_DQ<9>")
	)
	(segment
		(start 387.834886 -275.373592)
		(end 387.834886 -274.819364)
		(width 0.088646)
		(layer "In6.Cu")
		(net "M_G_CPU0_SA_DQ<9>")
	)
	(segment
		(start 417.921694 -298.734226)
		(end 416.677094 -298.734226)
		(width 0.18288)
		(layer "In6.Cu")
		(net "M_G_CPU0_SA_DQ<9>")
	)
	(segment
		(start 379.708664 -273.942556)
		(end 379.693932 -273.951192)
		(width 0.088646)
		(layer "In6.Cu")
		(net "M_G_CPU0_SA_DQ<9>")
	)
	(segment
		(start 414.918144 -297.62958)
		(end 414.506156 -297.62958)
		(width 0.18288)
		(layer "In6.Cu")
		(net "M_G_CPU0_SA_DQ<9>")
	)
	(segment
		(start 414.221676 -297.3451)
		(end 414.221676 -296.933112)
		(width 0.18288)
		(layer "In6.Cu")
		(net "M_G_CPU0_SA_DQ<9>")
	)
	(segment
		(start 428.747174 -301.325026)
		(end 428.043594 -301.325026)
		(width 0.18288)
		(layer "In6.Cu")
		(net "M_G_CPU0_SA_DQ<9>")
	)
	(segment
		(start 423.40276 -299.742098)
		(end 422.58361 -299.742098)
		(width 0.18288)
		(layer "In6.Cu")
		(net "M_G_CPU0_SA_DQ<9>")
	)
	(segment
		(start 430.949862 -303.380648)
		(end 430.691544 -303.380648)
		(width 0.18288)
		(layer "In6.Cu")
		(net "M_G_CPU0_SA_DQ<9>")
	)
	(segment
		(start 387.944106 -275.482812)
		(end 387.834886 -275.373592)
		(width 0.088646)
		(layer "In6.Cu")
		(net "M_G_CPU0_SA_DQ<9>")
	)
	(segment
		(start 413.630618 -296.342054)
		(end 412.579566 -296.342054)
		(width 0.18288)
		(layer "In6.Cu")
		(net "M_G_CPU0_SA_DQ<9>")
	)
	(segment
		(start 418.081714 -298.894246)
		(end 417.921694 -298.734226)
		(width 0.18288)
		(layer "In6.Cu")
		(net "M_G_CPU0_SA_DQ<9>")
	)
	(segment
		(start 433.45354 -304.119026)
		(end 432.272948 -304.119026)
		(width 0.18288)
		(layer "In6.Cu")
		(net "M_G_CPU0_SA_DQ<9>")
	)
	(segment
		(start 418.081714 -299.247052)
		(end 418.081714 -298.894246)
		(width 0.18288)
		(layer "In6.Cu")
		(net "M_G_CPU0_SA_DQ<9>")
	)
	(segment
		(start 430.456594 -302.302672)
		(end 429.72482 -302.302672)
		(width 0.18288)
		(layer "In6.Cu")
		(net "M_G_CPU0_SA_DQ<9>")
	)
	(segment
		(start 380.648718 -273.942556)
		(end 380.638304 -273.948652)
		(width 0.088646)
		(layer "In6.Cu")
		(net "M_G_CPU0_SA_DQ<9>")
	)
	(segment
		(start 432.272948 -304.119026)
		(end 431.371502 -303.21758)
		(width 0.18288)
		(layer "In6.Cu")
		(net "M_G_CPU0_SA_DQ<9>")
	)
	(segment
		(start 386.907532 -273.89201)
		(end 386.474462 -273.89201)
		(width 0.088646)
		(layer "In6.Cu")
		(net "M_G_CPU0_SA_DQ<9>")
	)
	(segment
		(start 400.84375 -290.344606)
		(end 400.84375 -281.521154)
		(width 0.18288)
		(layer "In6.Cu")
		(net "M_G_CPU0_SA_DQ<9>")
	)
	(segment
		(start 408.29611 -294.575484)
		(end 407.292556 -294.575484)
		(width 0.18288)
		(layer "In6.Cu")
		(net "M_G_CPU0_SA_DQ<9>")
	)
	(segment
		(start 383.467864 -273.942556)
		(end 383.453132 -273.951192)
		(width 0.088646)
		(layer "In6.Cu")
		(net "M_G_CPU0_SA_DQ<9>")
	)
	(segment
		(start 412.26613 -296.65549)
		(end 411.886146 -296.65549)
		(width 0.18288)
		(layer "In6.Cu")
		(net "M_G_CPU0_SA_DQ<9>")
	)
	(segment
		(start 378.203714 -273.942556)
		(end 378.197872 -273.939254)
		(width 0.088646)
		(layer "In6.Cu")
		(net "M_G_CPU0_SA_DQ<9>")
	)
	(segment
		(start 406.439116 -294.735504)
		(end 406.279096 -294.575484)
		(width 0.18288)
		(layer "In6.Cu")
		(net "M_G_CPU0_SA_DQ<9>")
	)
	(segment
		(start 395.382242 -276.058376)
		(end 389.777732 -276.058376)
		(width 0.18288)
		(layer "In6.Cu")
		(net "M_G_CPU0_SA_DQ<9>")
	)
	(segment
		(start 407.132536 -294.735504)
		(end 407.132536 -294.975026)
		(width 0.18288)
		(layer "In6.Cu")
		(net "M_G_CPU0_SA_DQ<9>")
	)
	(segment
		(start 378.209556 -273.946112)
		(end 378.203714 -273.942556)
		(width 0.088646)
		(layer "In6.Cu")
		(net "M_G_CPU0_SA_DQ<9>")
	)
	(segment
		(start 418.615114 -299.407072)
		(end 418.241734 -299.407072)
		(width 0.18288)
		(layer "In6.Cu")
		(net "M_G_CPU0_SA_DQ<9>")
	)
	(segment
		(start 415.28619 -297.997626)
		(end 414.918144 -297.62958)
		(width 0.18288)
		(layer "In6.Cu")
		(net "M_G_CPU0_SA_DQ<9>")
	)
	(segment
		(start 430.622456 -302.468534)
		(end 430.456594 -302.302672)
		(width 0.18288)
		(layer "In6.Cu")
		(net "M_G_CPU0_SA_DQ<9>")
	)
	(segment
		(start 416.677094 -298.734226)
		(end 415.940494 -297.997626)
		(width 0.18288)
		(layer "In6.Cu")
		(net "M_G_CPU0_SA_DQ<9>")
	)
	(segment
		(start 424.405806 -299.742098)
		(end 424.09618 -299.432472)
		(width 0.18288)
		(layer "In6.Cu")
		(net "M_G_CPU0_SA_DQ<9>")
	)
	(segment
		(start 388.882382 -275.687536)
		(end 388.14883 -275.687536)
		(width 0.18288)
		(layer "In6.Cu")
		(net "M_G_CPU0_SA_DQ<9>")
	)
	(segment
		(start 418.241734 -299.407072)
		(end 418.081714 -299.247052)
		(width 0.18288)
		(layer "In6.Cu")
		(net "M_G_CPU0_SA_DQ<9>")
	)
	(segment
		(start 430.691544 -303.380648)
		(end 430.459642 -303.148746)
		(width 0.18288)
		(layer "In6.Cu")
		(net "M_G_CPU0_SA_DQ<9>")
	)
	(segment
		(start 412.579566 -296.342054)
		(end 412.26613 -296.65549)
		(width 0.18288)
		(layer "In6.Cu")
		(net "M_G_CPU0_SA_DQ<9>")
	)
	(segment
		(start 423.712386 -299.432472)
		(end 423.40276 -299.742098)
		(width 0.18288)
		(layer "In6.Cu")
		(net "M_G_CPU0_SA_DQ<9>")
	)
	(segment
		(start 428.043594 -301.325026)
		(end 427.133512 -300.414944)
		(width 0.18288)
		(layer "In6.Cu")
		(net "M_G_CPU0_SA_DQ<9>")
	)
	(segment
		(start 409.184348 -295.463722)
		(end 408.29611 -294.575484)
		(width 0.18288)
		(layer "In6.Cu")
		(net "M_G_CPU0_SA_DQ<9>")
	)
	(segment
		(start 387.834886 -274.819364)
		(end 386.907532 -273.89201)
		(width 0.088646)
		(layer "In6.Cu")
		(net "M_G_CPU0_SA_DQ<9>")
	)
	(segment
		(start 406.972516 -295.135046)
		(end 406.599136 -295.135046)
		(width 0.18288)
		(layer "In6.Cu")
		(net "M_G_CPU0_SA_DQ<9>")
	)
	(segment
		(start 377.269756 -273.946112)
		(end 377.263914 -273.942556)
		(width 0.088646)
		(layer "In6.Cu")
		(net "M_G_CPU0_SA_DQ<9>")
	)
	(segment
		(start 431.11293 -303.21758)
		(end 430.949862 -303.380648)
		(width 0.18288)
		(layer "In6.Cu")
		(net "M_G_CPU0_SA_DQ<9>")
	)
	(segment
		(start 427.133512 -300.414944)
		(end 426.701712 -300.414944)
		(width 0.18288)
		(layer "In6.Cu")
		(net "M_G_CPU0_SA_DQ<9>")
	)
	(segment
		(start 414.221676 -296.933112)
		(end 413.630618 -296.342054)
		(width 0.18288)
		(layer "In6.Cu")
		(net "M_G_CPU0_SA_DQ<9>")
	)
	(segment
		(start 407.132536 -294.975026)
		(end 406.972516 -295.135046)
		(width 0.18288)
		(layer "In6.Cu")
		(net "M_G_CPU0_SA_DQ<9>")
	)
	(segment
		(start 424.09618 -299.432472)
		(end 423.712386 -299.432472)
		(width 0.18288)
		(layer "In6.Cu")
		(net "M_G_CPU0_SA_DQ<9>")
	)
	(segment
		(start 376.39117 -273.908774)
		(end 376.386598 -273.904202)
		(width 0.088646)
		(layer "In6.Cu")
		(net "M_G_CPU0_SA_DQ<9>")
	)
	(segment
		(start 418.775134 -298.894246)
		(end 418.775134 -299.247052)
		(width 0.18288)
		(layer "In6.Cu")
		(net "M_G_CPU0_SA_DQ<9>")
	)
	(segment
		(start 405.074628 -294.575484)
		(end 400.84375 -290.344606)
		(width 0.18288)
		(layer "In6.Cu")
		(net "M_G_CPU0_SA_DQ<9>")
	)
	(segment
		(start 382.528064 -273.942556)
		(end 382.513332 -273.951192)
		(width 0.088646)
		(layer "In6.Cu")
		(net "M_G_CPU0_SA_DQ<9>")
	)
	(segment
		(start 411.224476 -296.43324)
		(end 410.254958 -295.463722)
		(width 0.18288)
		(layer "In6.Cu")
		(net "M_G_CPU0_SA_DQ<9>")
	)
	(segment
		(start 415.940494 -297.997626)
		(end 415.28619 -297.997626)
		(width 0.18288)
		(layer "In6.Cu")
		(net "M_G_CPU0_SA_DQ<9>")
	)
	(segment
		(start 376.224038 -273.836892)
		(end 375.653554 -273.836892)
		(width 0.088646)
		(layer "In6.Cu")
		(net "M_G_CPU0_SA_DQ<9>")
	)
	(segment
		(start 388.14883 -275.687536)
		(end 387.944106 -275.482812)
		(width 0.18288)
		(layer "In6.Cu")
		(net "M_G_CPU0_SA_DQ<9>")
	)
	(segment
		(start 418.775134 -299.247052)
		(end 418.615114 -299.407072)
		(width 0.18288)
		(layer "In6.Cu")
		(net "M_G_CPU0_SA_DQ<9>")
	)
	(segment
		(start 376.889264 -273.942556)
		(end 376.84456 -273.968464)
		(width 0.088646)
		(layer "In6.Cu")
		(net "M_G_CPU0_SA_DQ<9>")
	)
	(segment
		(start 421.733726 -298.892214)
		(end 419.984682 -298.892214)
		(width 0.18288)
		(layer "In6.Cu")
		(net "M_G_CPU0_SA_DQ<9>")
	)
	(segment
		(start 411.663896 -296.43324)
		(end 411.224476 -296.43324)
		(width 0.18288)
		(layer "In6.Cu")
		(net "M_G_CPU0_SA_DQ<9>")
	)
	(segment
		(start 407.292556 -294.575484)
		(end 407.132536 -294.735504)
		(width 0.18288)
		(layer "In6.Cu")
		(net "M_G_CPU0_SA_DQ<9>")
	)
	(segment
		(start 430.459642 -303.148746)
		(end 430.459642 -302.890174)
		(width 0.18288)
		(layer "In6.Cu")
		(net "M_G_CPU0_SA_DQ<9>")
	)
	(segment
		(start 406.599136 -295.135046)
		(end 406.439116 -294.975026)
		(width 0.18288)
		(layer "In6.Cu")
		(net "M_G_CPU0_SA_DQ<9>")
	)
	(segment
		(start 406.279096 -294.575484)
		(end 405.074628 -294.575484)
		(width 0.18288)
		(layer "In6.Cu")
		(net "M_G_CPU0_SA_DQ<9>")
	)
	(segment
		(start 431.371502 -303.21758)
		(end 431.11293 -303.21758)
		(width 0.18288)
		(layer "In6.Cu")
		(net "M_G_CPU0_SA_DQ<9>")
	)
	(segment
		(start 434.139594 -304.80508)
		(end 433.45354 -304.119026)
		(width 0.18288)
		(layer "In6.Cu")
		(net "M_G_CPU0_SA_DQ<9>")
	)
	(segment
		(start 377.263914 -273.942556)
		(end 377.258072 -273.939254)
		(width 0.088646)
		(layer "In6.Cu")
		(net "M_G_CPU0_SA_DQ<9>")
	)
	(segment
		(start 414.506156 -297.62958)
		(end 414.221676 -297.3451)
		(width 0.18288)
		(layer "In6.Cu")
		(net "M_G_CPU0_SA_DQ<9>")
	)
	(segment
		(start 426.028866 -299.742098)
		(end 424.405806 -299.742098)
		(width 0.18288)
		(layer "In6.Cu")
		(net "M_G_CPU0_SA_DQ<9>")
	)
	(segment
		(start 411.886146 -296.65549)
		(end 411.663896 -296.43324)
		(width 0.18288)
		(layer "In6.Cu")
		(net "M_G_CPU0_SA_DQ<9>")
	)
	(segment
		(start 389.777732 -276.058376)
		(end 388.882382 -275.687536)
		(width 0.18288)
		(layer "In6.Cu")
		(net "M_G_CPU0_SA_DQ<9>")
	)
	(segment
		(start 429.72482 -302.302672)
		(end 428.747174 -301.325026)
		(width 0.18288)
		(layer "In6.Cu")
		(net "M_G_CPU0_SA_DQ<9>")
	)
	(segment
		(start 435.823614 -305.266598)
		(end 435.362096 -304.80508)
		(width 0.18288)
		(layer "In6.Cu")
		(net "M_G_CPU0_SA_DQ<9>")
	)
	(segment
		(start 418.935154 -298.734226)
		(end 418.775134 -298.894246)
		(width 0.18288)
		(layer "In6.Cu")
		(net "M_G_CPU0_SA_DQ<9>")
	)
	(segment
		(start 410.254958 -295.463722)
		(end 409.184348 -295.463722)
		(width 0.18288)
		(layer "In6.Cu")
		(net "M_G_CPU0_SA_DQ<9>")
	)
	(segment
		(start 422.58361 -299.742098)
		(end 421.733726 -298.892214)
		(width 0.18288)
		(layer "In6.Cu")
		(net "M_G_CPU0_SA_DQ<9>")
	)
	(segment
		(start 406.439116 -294.975026)
		(end 406.439116 -294.735504)
		(width 0.18288)
		(layer "In6.Cu")
		(net "M_G_CPU0_SA_DQ<9>")
	)
	(segment
		(start 430.622456 -302.727106)
		(end 430.622456 -302.468534)
		(width 0.18288)
		(layer "In6.Cu")
		(net "M_G_CPU0_SA_DQ<9>")
	)
	(arc
		(start 375.653554 -273.836892)
		(mid 375.152202 -273.737149)
		(end 374.727216 -273.453098)
		(width 0.088646)
		(layer "In6.Cu")
		(net "M_G_CPU0_SA_DQ<9>")
	)
	(arc
		(start 383.453132 -273.951192)
		(mid 383.176657 -274.018512)
		(end 382.90246 -273.942556)
		(width 0.088646)
		(layer "In6.Cu")
		(net "M_G_CPU0_SA_DQ<9>")
	)
	(arc
		(start 384.78206 -273.942556)
		(mid 384.594862 -273.892413)
		(end 384.407664 -273.942556)
		(width 0.088646)
		(layer "In6.Cu")
		(net "M_G_CPU0_SA_DQ<9>")
	)
	(arc
		(start 380.08306 -273.942556)
		(mid 379.895862 -273.892413)
		(end 379.708664 -273.942556)
		(width 0.088646)
		(layer "In6.Cu")
		(net "M_G_CPU0_SA_DQ<9>")
	)
	(arc
		(start 379.693932 -273.951192)
		(mid 379.417457 -274.018512)
		(end 379.14326 -273.942556)
		(width 0.088646)
		(layer "In6.Cu")
		(net "M_G_CPU0_SA_DQ<9>")
	)
	(arc
		(start 382.90246 -273.942556)
		(mid 382.715262 -273.892413)
		(end 382.528064 -273.942556)
		(width 0.088646)
		(layer "In6.Cu")
		(net "M_G_CPU0_SA_DQ<9>")
	)
	(arc
		(start 385.72186 -273.942556)
		(mid 385.534662 -273.892413)
		(end 385.347464 -273.942556)
		(width 0.088646)
		(layer "In6.Cu")
		(net "M_G_CPU0_SA_DQ<9>")
	)
	(arc
		(start 378.197872 -273.939254)
		(mid 378.013017 -273.892304)
		(end 377.829064 -273.942556)
		(width 0.088646)
		(layer "In6.Cu")
		(net "M_G_CPU0_SA_DQ<9>")
	)
	(arc
		(start 381.57785 -273.948652)
		(mid 381.299672 -274.018375)
		(end 381.023114 -273.942556)
		(width 0.088646)
		(layer "In6.Cu")
		(net "M_G_CPU0_SA_DQ<9>")
	)
	(arc
		(start 386.287264 -273.942556)
		(mid 386.004562 -274.018332)
		(end 385.72186 -273.942556)
		(width 0.088646)
		(layer "In6.Cu")
		(net "M_G_CPU0_SA_DQ<9>")
	)
	(arc
		(start 382.513332 -273.951192)
		(mid 382.236857 -274.018512)
		(end 381.96266 -273.942556)
		(width 0.088646)
		(layer "In6.Cu")
		(net "M_G_CPU0_SA_DQ<9>")
	)
	(arc
		(start 379.14326 -273.942556)
		(mid 378.956062 -273.892413)
		(end 378.768864 -273.942556)
		(width 0.088646)
		(layer "In6.Cu")
		(net "M_G_CPU0_SA_DQ<9>")
	)
	(arc
		(start 386.474462 -273.89201)
		(mid 386.377534 -273.904961)
		(end 386.287264 -273.942556)
		(width 0.088646)
		(layer "In6.Cu")
		(net "M_G_CPU0_SA_DQ<9>")
	)
	(arc
		(start 376.84456 -273.968464)
		(mid 376.607763 -274.015536)
		(end 376.39117 -273.908774)
		(width 0.088646)
		(layer "In6.Cu")
		(net "M_G_CPU0_SA_DQ<9>")
	)
	(arc
		(start 377.258072 -273.939254)
		(mid 377.073217 -273.892304)
		(end 376.889264 -273.942556)
		(width 0.088646)
		(layer "In6.Cu")
		(net "M_G_CPU0_SA_DQ<9>")
	)
	(arc
		(start 380.638304 -273.948652)
		(mid 380.359872 -274.018498)
		(end 380.08306 -273.942556)
		(width 0.088646)
		(layer "In6.Cu")
		(net "M_G_CPU0_SA_DQ<9>")
	)
	(arc
		(start 383.84226 -273.942556)
		(mid 383.655062 -273.892413)
		(end 383.467864 -273.942556)
		(width 0.088646)
		(layer "In6.Cu")
		(net "M_G_CPU0_SA_DQ<9>")
	)
	(arc
		(start 381.96266 -273.942556)
		(mid 381.775462 -273.892413)
		(end 381.588264 -273.942556)
		(width 0.088646)
		(layer "In6.Cu")
		(net "M_G_CPU0_SA_DQ<9>")
	)
	(arc
		(start 384.407664 -273.942556)
		(mid 384.124962 -274.018332)
		(end 383.84226 -273.942556)
		(width 0.088646)
		(layer "In6.Cu")
		(net "M_G_CPU0_SA_DQ<9>")
	)
	(arc
		(start 381.023114 -273.942556)
		(mid 380.835916 -273.892413)
		(end 380.648718 -273.942556)
		(width 0.088646)
		(layer "In6.Cu")
		(net "M_G_CPU0_SA_DQ<9>")
	)
	(arc
		(start 377.829064 -273.942556)
		(mid 377.54989 -274.018321)
		(end 377.269756 -273.946112)
		(width 0.088646)
		(layer "In6.Cu")
		(net "M_G_CPU0_SA_DQ<9>")
	)
	(arc
		(start 385.347464 -273.942556)
		(mid 385.064762 -274.018332)
		(end 384.78206 -273.942556)
		(width 0.088646)
		(layer "In6.Cu")
		(net "M_G_CPU0_SA_DQ<9>")
	)
	(arc
		(start 378.768864 -273.942556)
		(mid 378.48969 -274.018321)
		(end 378.209556 -273.946112)
		(width 0.088646)
		(layer "In6.Cu")
		(net "M_G_CPU0_SA_DQ<9>")
	)
	(arc
		(start 376.386598 -273.904202)
		(mid 376.312015 -273.854367)
		(end 376.224038 -273.836892)
		(width 0.088646)
		(layer "In6.Cu")
		(net "M_G_CPU0_SA_DQ<9>")
	)
	(segment
		(start 439.87085 -306.541678)
		(end 439.82386 -306.541678)
		(width 0.101854)
		(layer "F.Cu")
		(net "M_G_CPU0_SA_DQ<8>")
	)
	(segment
		(start 439.173112 -307.215286)
		(end 438.697878 -307.215286)
		(width 0.20066)
		(layer "F.Cu")
		(net "M_G_CPU0_SA_DQ<8>")
	)
	(segment
		(start 442.038994 -306.535328)
		(end 442.032644 -306.541678)
		(width 0.1016)
		(layer "F.Cu")
		(net "M_G_CPU0_SA_DQ<8>")
	)
	(segment
		(start 438.697878 -307.215286)
		(end 438.449212 -306.96662)
		(width 0.20066)
		(layer "F.Cu")
		(net "M_G_CPU0_SA_DQ<8>")
	)
	(segment
		(start 439.361072 -307.027326)
		(end 439.173112 -307.215286)
		(width 0.20066)
		(layer "F.Cu")
		(net "M_G_CPU0_SA_DQ<8>")
	)
	(segment
		(start 442.880496 -306.966874)
		(end 442.44895 -306.535328)
		(width 0.20066)
		(layer "F.Cu")
		(net "M_G_CPU0_SA_DQ<8>")
	)
	(segment
		(start 439.82386 -306.541678)
		(end 439.479182 -306.541678)
		(width 0.20066)
		(layer "F.Cu")
		(net "M_G_CPU0_SA_DQ<8>")
	)
	(segment
		(start 439.479182 -306.541678)
		(end 439.361072 -306.659788)
		(width 0.20066)
		(layer "F.Cu")
		(net "M_G_CPU0_SA_DQ<8>")
	)
	(segment
		(start 442.032644 -306.541678)
		(end 439.87085 -306.541678)
		(width 0.1016)
		(layer "F.Cu")
		(net "M_G_CPU0_SA_DQ<8>")
	)
	(segment
		(start 444.47206 -306.966874)
		(end 442.880496 -306.966874)
		(width 0.20066)
		(layer "F.Cu")
		(net "M_G_CPU0_SA_DQ<8>")
	)
	(segment
		(start 436.928514 -306.96662)
		(end 435.823614 -306.96662)
		(width 0.20066)
		(layer "F.Cu")
		(net "M_G_CPU0_SA_DQ<8>")
	)
	(segment
		(start 375.197116 -274.26666)
		(end 375.196862 -274.266914)
		(width 0.20066)
		(layer "F.Cu")
		(net "M_G_CPU0_SA_DQ<8>")
	)
	(segment
		(start 444.472314 -306.96662)
		(end 444.47206 -306.966874)
		(width 0.20066)
		(layer "F.Cu")
		(net "M_G_CPU0_SA_DQ<8>")
	)
	(segment
		(start 442.44895 -306.535328)
		(end 442.038994 -306.535328)
		(width 0.20066)
		(layer "F.Cu")
		(net "M_G_CPU0_SA_DQ<8>")
	)
	(segment
		(start 375.197116 -273.730974)
		(end 375.197116 -274.26666)
		(width 0.20066)
		(layer "F.Cu")
		(net "M_G_CPU0_SA_DQ<8>")
	)
	(segment
		(start 438.449212 -306.96662)
		(end 436.928514 -306.96662)
		(width 0.20066)
		(layer "F.Cu")
		(net "M_G_CPU0_SA_DQ<8>")
	)
	(segment
		(start 439.361072 -306.659788)
		(end 439.361072 -307.027326)
		(width 0.20066)
		(layer "F.Cu")
		(net "M_G_CPU0_SA_DQ<8>")
	)
	(segment
		(start 378.688346 -274.765008)
		(end 378.673614 -274.756372)
		(width 0.088646)
		(layer "In6.Cu")
		(net "M_G_CPU0_SA_DQ<8>")
	)
	(segment
		(start 375.575322 -274.3327)
		(end 375.509536 -274.266914)
		(width 0.088646)
		(layer "In6.Cu")
		(net "M_G_CPU0_SA_DQ<8>")
	)
	(segment
		(start 408.118818 -296.212006)
		(end 405.302974 -296.212006)
		(width 0.18288)
		(layer "In6.Cu")
		(net "M_G_CPU0_SA_DQ<8>")
	)
	(segment
		(start 412.483046 -298.4627)
		(end 412.323026 -298.62272)
		(width 0.18288)
		(layer "In6.Cu")
		(net "M_G_CPU0_SA_DQ<8>")
	)
	(segment
		(start 411.789626 -298.200826)
		(end 411.629606 -298.040806)
		(width 0.18288)
		(layer "In6.Cu")
		(net "M_G_CPU0_SA_DQ<8>")
	)
	(segment
		(start 429.42891 -304.409094)
		(end 429.42891 -303.987454)
		(width 0.18288)
		(layer "In6.Cu")
		(net "M_G_CPU0_SA_DQ<8>")
	)
	(segment
		(start 375.868946 -274.765008)
		(end 375.854214 -274.756372)
		(width 0.088646)
		(layer "In6.Cu")
		(net "M_G_CPU0_SA_DQ<8>")
	)
	(segment
		(start 428.27829 -302.836834)
		(end 426.432218 -302.836834)
		(width 0.18288)
		(layer "In6.Cu")
		(net "M_G_CPU0_SA_DQ<8>")
	)
	(segment
		(start 418.991034 -300.75251)
		(end 418.991034 -301.330106)
		(width 0.18288)
		(layer "In6.Cu")
		(net "M_G_CPU0_SA_DQ<8>")
	)
	(segment
		(start 428.214536 -303.464468)
		(end 428.4472 -303.231804)
		(width 0.18288)
		(layer "In6.Cu")
		(net "M_G_CPU0_SA_DQ<8>")
	)
	(segment
		(start 399.84807 -290.757102)
		(end 399.84807 -281.93365)
		(width 0.18288)
		(layer "In6.Cu")
		(net "M_G_CPU0_SA_DQ<8>")
	)
	(segment
		(start 389.579358 -277.054056)
		(end 389.00227 -276.815042)
		(width 0.18288)
		(layer "In6.Cu")
		(net "M_G_CPU0_SA_DQ<8>")
	)
	(segment
		(start 376.808746 -274.765008)
		(end 376.794014 -274.756372)
		(width 0.088646)
		(layer "In6.Cu")
		(net "M_G_CPU0_SA_DQ<8>")
	)
	(segment
		(start 423.519854 -301.98822)
		(end 423.519854 -301.602394)
		(width 0.18288)
		(layer "In6.Cu")
		(net "M_G_CPU0_SA_DQ<8>")
	)
	(segment
		(start 424.373294 -301.442374)
		(end 424.213274 -301.602394)
		(width 0.18288)
		(layer "In6.Cu")
		(net "M_G_CPU0_SA_DQ<8>")
	)
	(segment
		(start 432.173634 -306.136802)
		(end 431.915062 -306.136802)
		(width 0.18288)
		(layer "In6.Cu")
		(net "M_G_CPU0_SA_DQ<8>")
	)
	(segment
		(start 431.492406 -304.982626)
		(end 430.424082 -304.982626)
		(width 0.18288)
		(layer "In6.Cu")
		(net "M_G_CPU0_SA_DQ<8>")
	)
	(segment
		(start 430.130204 -304.688748)
		(end 429.708564 -304.688748)
		(width 0.18288)
		(layer "In6.Cu")
		(net "M_G_CPU0_SA_DQ<8>")
	)
	(segment
		(start 429.163734 -303.722278)
		(end 428.937674 -303.722278)
		(width 0.18288)
		(layer "In6.Cu")
		(net "M_G_CPU0_SA_DQ<8>")
	)
	(segment
		(start 423.359834 -301.442374)
		(end 422.28897 -301.442374)
		(width 0.18288)
		(layer "In6.Cu")
		(net "M_G_CPU0_SA_DQ<8>")
	)
	(segment
		(start 431.68316 -305.9049)
		(end 431.68316 -305.646328)
		(width 0.18288)
		(layer "In6.Cu")
		(net "M_G_CPU0_SA_DQ<8>")
	)
	(segment
		(start 410.157422 -296.918634)
		(end 408.825446 -296.918634)
		(width 0.18288)
		(layer "In6.Cu")
		(net "M_G_CPU0_SA_DQ<8>")
	)
	(segment
		(start 428.937674 -303.722278)
		(end 428.70501 -303.954942)
		(width 0.18288)
		(layer "In6.Cu")
		(net "M_G_CPU0_SA_DQ<8>")
	)
	(segment
		(start 413.421322 -298.040806)
		(end 412.643066 -298.040806)
		(width 0.18288)
		(layer "In6.Cu")
		(net "M_G_CPU0_SA_DQ<8>")
	)
	(segment
		(start 387.352794 -275.207476)
		(end 387.352794 -274.955762)
		(width 0.088646)
		(layer "In6.Cu")
		(net "M_G_CPU0_SA_DQ<8>")
	)
	(segment
		(start 411.279594 -298.040806)
		(end 410.157422 -296.918634)
		(width 0.18288)
		(layer "In6.Cu")
		(net "M_G_CPU0_SA_DQ<8>")
	)
	(segment
		(start 418.137594 -300.59249)
		(end 416.976306 -300.59249)
		(width 0.18288)
		(layer "In6.Cu")
		(net "M_G_CPU0_SA_DQ<8>")
	)
	(segment
		(start 423.679874 -302.14824)
		(end 423.519854 -301.98822)
		(width 0.18288)
		(layer "In6.Cu")
		(net "M_G_CPU0_SA_DQ<8>")
	)
	(segment
		(start 423.519854 -301.602394)
		(end 423.359834 -301.442374)
		(width 0.18288)
		(layer "In6.Cu")
		(net "M_G_CPU0_SA_DQ<8>")
	)
	(segment
		(start 435.271418 -306.414424)
		(end 432.924204 -306.414424)
		(width 0.18288)
		(layer "In6.Cu")
		(net "M_G_CPU0_SA_DQ<8>")
	)
	(segment
		(start 418.297614 -301.330106)
		(end 418.297614 -300.75251)
		(width 0.18288)
		(layer "In6.Cu")
		(net "M_G_CPU0_SA_DQ<8>")
	)
	(segment
		(start 431.915062 -306.136802)
		(end 431.68316 -305.9049)
		(width 0.18288)
		(layer "In6.Cu")
		(net "M_G_CPU0_SA_DQ<8>")
	)
	(segment
		(start 435.823614 -306.96662)
		(end 435.271418 -306.414424)
		(width 0.18288)
		(layer "In6.Cu")
		(net "M_G_CPU0_SA_DQ<8>")
	)
	(segment
		(start 389.00227 -276.815042)
		(end 388.307326 -276.815042)
		(width 0.18288)
		(layer "In6.Cu")
		(net "M_G_CPU0_SA_DQ<8>")
	)
	(segment
		(start 387.81736 -276.815042)
		(end 387.728206 -276.725888)
		(width 0.088646)
		(layer "In6.Cu")
		(net "M_G_CPU0_SA_DQ<8>")
	)
	(segment
		(start 387.278626 -275.956014)
		(end 387.278626 -275.386546)
		(width 0.088646)
		(layer "In6.Cu")
		(net "M_G_CPU0_SA_DQ<8>")
	)
	(segment
		(start 429.42891 -303.987454)
		(end 429.163734 -303.722278)
		(width 0.18288)
		(layer "In6.Cu")
		(net "M_G_CPU0_SA_DQ<8>")
	)
	(segment
		(start 416.032442 -299.648626)
		(end 415.029142 -299.648626)
		(width 0.18288)
		(layer "In6.Cu")
		(net "M_G_CPU0_SA_DQ<8>")
	)
	(segment
		(start 431.790348 -305.280568)
		(end 431.492406 -304.982626)
		(width 0.18288)
		(layer "In6.Cu")
		(net "M_G_CPU0_SA_DQ<8>")
	)
	(segment
		(start 399.84807 -281.93365)
		(end 394.968476 -277.054056)
		(width 0.18288)
		(layer "In6.Cu")
		(net "M_G_CPU0_SA_DQ<8>")
	)
	(segment
		(start 375.509536 -274.266914)
		(end 375.196862 -274.266914)
		(width 0.088646)
		(layer "In6.Cu")
		(net "M_G_CPU0_SA_DQ<8>")
	)
	(segment
		(start 411.629606 -298.040806)
		(end 411.279594 -298.040806)
		(width 0.18288)
		(layer "In6.Cu")
		(net "M_G_CPU0_SA_DQ<8>")
	)
	(segment
		(start 432.924204 -306.414424)
		(end 432.539394 -306.029614)
		(width 0.18288)
		(layer "In6.Cu")
		(net "M_G_CPU0_SA_DQ<8>")
	)
	(segment
		(start 430.424082 -304.982626)
		(end 430.130204 -304.688748)
		(width 0.18288)
		(layer "In6.Cu")
		(net "M_G_CPU0_SA_DQ<8>")
	)
	(segment
		(start 387.728206 -276.405594)
		(end 387.278626 -275.956014)
		(width 0.088646)
		(layer "In6.Cu")
		(net "M_G_CPU0_SA_DQ<8>")
	)
	(segment
		(start 381.118364 -274.756372)
		(end 381.10795 -274.762468)
		(width 0.088646)
		(layer "In6.Cu")
		(net "M_G_CPU0_SA_DQ<8>")
	)
	(segment
		(start 429.708564 -304.688748)
		(end 429.42891 -304.409094)
		(width 0.18288)
		(layer "In6.Cu")
		(net "M_G_CPU0_SA_DQ<8>")
	)
	(segment
		(start 385.266946 -274.765262)
		(end 385.252214 -274.756626)
		(width 0.088646)
		(layer "In6.Cu")
		(net "M_G_CPU0_SA_DQ<8>")
	)
	(segment
		(start 422.28897 -301.442374)
		(end 421.439086 -300.59249)
		(width 0.18288)
		(layer "In6.Cu")
		(net "M_G_CPU0_SA_DQ<8>")
	)
	(segment
		(start 432.539394 -306.029614)
		(end 432.280822 -306.029614)
		(width 0.18288)
		(layer "In6.Cu")
		(net "M_G_CPU0_SA_DQ<8>")
	)
	(segment
		(start 418.457634 -301.490126)
		(end 418.297614 -301.330106)
		(width 0.18288)
		(layer "In6.Cu")
		(net "M_G_CPU0_SA_DQ<8>")
	)
	(segment
		(start 387.102604 -274.705572)
		(end 386.00507 -274.705572)
		(width 0.088646)
		(layer "In6.Cu")
		(net "M_G_CPU0_SA_DQ<8>")
	)
	(segment
		(start 412.643066 -298.040806)
		(end 412.483046 -298.200826)
		(width 0.18288)
		(layer "In6.Cu")
		(net "M_G_CPU0_SA_DQ<8>")
	)
	(segment
		(start 408.825446 -296.918634)
		(end 408.118818 -296.212006)
		(width 0.18288)
		(layer "In6.Cu")
		(net "M_G_CPU0_SA_DQ<8>")
	)
	(segment
		(start 415.029142 -299.648626)
		(end 413.421322 -298.040806)
		(width 0.18288)
		(layer "In6.Cu")
		(net "M_G_CPU0_SA_DQ<8>")
	)
	(segment
		(start 425.037758 -301.442374)
		(end 424.373294 -301.442374)
		(width 0.18288)
		(layer "In6.Cu")
		(net "M_G_CPU0_SA_DQ<8>")
	)
	(segment
		(start 387.278626 -275.386546)
		(end 387.352794 -275.207476)
		(width 0.088646)
		(layer "In6.Cu")
		(net "M_G_CPU0_SA_DQ<8>")
	)
	(segment
		(start 382.45288 -274.768056)
		(end 382.432814 -274.756372)
		(width 0.088646)
		(layer "In6.Cu")
		(net "M_G_CPU0_SA_DQ<8>")
	)
	(segment
		(start 431.790348 -305.53914)
		(end 431.790348 -305.280568)
		(width 0.18288)
		(layer "In6.Cu")
		(net "M_G_CPU0_SA_DQ<8>")
	)
	(segment
		(start 418.831014 -301.490126)
		(end 418.457634 -301.490126)
		(width 0.18288)
		(layer "In6.Cu")
		(net "M_G_CPU0_SA_DQ<8>")
	)
	(segment
		(start 405.302974 -296.212006)
		(end 399.84807 -290.757102)
		(width 0.18288)
		(layer "In6.Cu")
		(net "M_G_CPU0_SA_DQ<8>")
	)
	(segment
		(start 428.4472 -303.231804)
		(end 428.4472 -303.005744)
		(width 0.18288)
		(layer "In6.Cu")
		(net "M_G_CPU0_SA_DQ<8>")
	)
	(segment
		(start 428.47895 -303.954942)
		(end 428.214536 -303.690528)
		(width 0.18288)
		(layer "In6.Cu")
		(net "M_G_CPU0_SA_DQ<8>")
	)
	(segment
		(start 428.70501 -303.954942)
		(end 428.47895 -303.954942)
		(width 0.18288)
		(layer "In6.Cu")
		(net "M_G_CPU0_SA_DQ<8>")
	)
	(segment
		(start 379.628146 -274.765008)
		(end 379.613414 -274.756372)
		(width 0.088646)
		(layer "In6.Cu")
		(net "M_G_CPU0_SA_DQ<8>")
	)
	(segment
		(start 418.297614 -300.75251)
		(end 418.137594 -300.59249)
		(width 0.18288)
		(layer "In6.Cu")
		(net "M_G_CPU0_SA_DQ<8>")
	)
	(segment
		(start 412.483046 -298.200826)
		(end 412.483046 -298.4627)
		(width 0.18288)
		(layer "In6.Cu")
		(net "M_G_CPU0_SA_DQ<8>")
	)
	(segment
		(start 383.387346 -274.765262)
		(end 383.372614 -274.756626)
		(width 0.088646)
		(layer "In6.Cu")
		(net "M_G_CPU0_SA_DQ<8>")
	)
	(segment
		(start 384.327146 -274.765262)
		(end 384.312414 -274.756626)
		(width 0.088646)
		(layer "In6.Cu")
		(net "M_G_CPU0_SA_DQ<8>")
	)
	(segment
		(start 387.352794 -274.955762)
		(end 387.102604 -274.705572)
		(width 0.088646)
		(layer "In6.Cu")
		(net "M_G_CPU0_SA_DQ<8>")
	)
	(segment
		(start 411.949646 -298.62272)
		(end 411.789626 -298.4627)
		(width 0.18288)
		(layer "In6.Cu")
		(net "M_G_CPU0_SA_DQ<8>")
	)
	(segment
		(start 424.213274 -301.98822)
		(end 424.053254 -302.14824)
		(width 0.18288)
		(layer "In6.Cu")
		(net "M_G_CPU0_SA_DQ<8>")
	)
	(segment
		(start 428.214536 -303.690528)
		(end 428.214536 -303.464468)
		(width 0.18288)
		(layer "In6.Cu")
		(net "M_G_CPU0_SA_DQ<8>")
	)
	(segment
		(start 424.213274 -301.602394)
		(end 424.213274 -301.98822)
		(width 0.18288)
		(layer "In6.Cu")
		(net "M_G_CPU0_SA_DQ<8>")
	)
	(segment
		(start 431.68316 -305.646328)
		(end 431.790348 -305.53914)
		(width 0.18288)
		(layer "In6.Cu")
		(net "M_G_CPU0_SA_DQ<8>")
	)
	(segment
		(start 412.323026 -298.62272)
		(end 411.949646 -298.62272)
		(width 0.18288)
		(layer "In6.Cu")
		(net "M_G_CPU0_SA_DQ<8>")
	)
	(segment
		(start 387.728206 -276.725888)
		(end 387.728206 -276.405594)
		(width 0.088646)
		(layer "In6.Cu")
		(net "M_G_CPU0_SA_DQ<8>")
	)
	(segment
		(start 394.968476 -277.054056)
		(end 389.579358 -277.054056)
		(width 0.18288)
		(layer "In6.Cu")
		(net "M_G_CPU0_SA_DQ<8>")
	)
	(segment
		(start 418.991034 -301.330106)
		(end 418.831014 -301.490126)
		(width 0.18288)
		(layer "In6.Cu")
		(net "M_G_CPU0_SA_DQ<8>")
	)
	(segment
		(start 388.307326 -276.815042)
		(end 387.81736 -276.815042)
		(width 0.088646)
		(layer "In6.Cu")
		(net "M_G_CPU0_SA_DQ<8>")
	)
	(segment
		(start 375.854214 -274.756372)
		(end 375.848118 -274.752816)
		(width 0.088646)
		(layer "In6.Cu")
		(net "M_G_CPU0_SA_DQ<8>")
	)
	(segment
		(start 424.053254 -302.14824)
		(end 423.679874 -302.14824)
		(width 0.18288)
		(layer "In6.Cu")
		(net "M_G_CPU0_SA_DQ<8>")
	)
	(segment
		(start 419.151054 -300.59249)
		(end 418.991034 -300.75251)
		(width 0.18288)
		(layer "In6.Cu")
		(net "M_G_CPU0_SA_DQ<8>")
	)
	(segment
		(start 426.432218 -302.836834)
		(end 425.037758 -301.442374)
		(width 0.18288)
		(layer "In6.Cu")
		(net "M_G_CPU0_SA_DQ<8>")
	)
	(segment
		(start 416.976306 -300.59249)
		(end 416.032442 -299.648626)
		(width 0.18288)
		(layer "In6.Cu")
		(net "M_G_CPU0_SA_DQ<8>")
	)
	(segment
		(start 377.748546 -274.765008)
		(end 377.733814 -274.756372)
		(width 0.088646)
		(layer "In6.Cu")
		(net "M_G_CPU0_SA_DQ<8>")
	)
	(segment
		(start 432.280822 -306.029614)
		(end 432.173634 -306.136802)
		(width 0.18288)
		(layer "In6.Cu")
		(net "M_G_CPU0_SA_DQ<8>")
	)
	(segment
		(start 381.503174 -274.762468)
		(end 381.49276 -274.756372)
		(width 0.088646)
		(layer "In6.Cu")
		(net "M_G_CPU0_SA_DQ<8>")
	)
	(segment
		(start 421.439086 -300.59249)
		(end 419.151054 -300.59249)
		(width 0.18288)
		(layer "In6.Cu")
		(net "M_G_CPU0_SA_DQ<8>")
	)
	(segment
		(start 428.4472 -303.005744)
		(end 428.27829 -302.836834)
		(width 0.18288)
		(layer "In6.Cu")
		(net "M_G_CPU0_SA_DQ<8>")
	)
	(segment
		(start 411.789626 -298.4627)
		(end 411.789626 -298.200826)
		(width 0.18288)
		(layer "In6.Cu")
		(net "M_G_CPU0_SA_DQ<8>")
	)
	(arc
		(start 383.938018 -274.756626)
		(mid 383.663789 -274.832551)
		(end 383.387346 -274.765262)
		(width 0.088646)
		(layer "In6.Cu")
		(net "M_G_CPU0_SA_DQ<8>")
	)
	(arc
		(start 382.998218 -274.756626)
		(mid 382.727029 -274.832373)
		(end 382.45288 -274.768056)
		(width 0.088646)
		(layer "In6.Cu")
		(net "M_G_CPU0_SA_DQ<8>")
	)
	(arc
		(start 385.252214 -274.756626)
		(mid 385.065016 -274.706483)
		(end 384.877818 -274.756626)
		(width 0.088646)
		(layer "In6.Cu")
		(net "M_G_CPU0_SA_DQ<8>")
	)
	(arc
		(start 386.00507 -274.705572)
		(mid 385.907984 -274.71876)
		(end 385.817618 -274.756626)
		(width 0.088646)
		(layer "In6.Cu")
		(net "M_G_CPU0_SA_DQ<8>")
	)
	(arc
		(start 382.432814 -274.756372)
		(mid 382.245616 -274.706229)
		(end 382.058418 -274.756372)
		(width 0.088646)
		(layer "In6.Cu")
		(net "M_G_CPU0_SA_DQ<8>")
	)
	(arc
		(start 376.419618 -274.756372)
		(mid 376.145419 -274.832207)
		(end 375.868946 -274.765008)
		(width 0.088646)
		(layer "In6.Cu")
		(net "M_G_CPU0_SA_DQ<8>")
	)
	(arc
		(start 384.877818 -274.756626)
		(mid 384.603589 -274.832551)
		(end 384.327146 -274.765262)
		(width 0.088646)
		(layer "In6.Cu")
		(net "M_G_CPU0_SA_DQ<8>")
	)
	(arc
		(start 380.553214 -274.756372)
		(mid 380.366016 -274.706229)
		(end 380.178818 -274.756372)
		(width 0.088646)
		(layer "In6.Cu")
		(net "M_G_CPU0_SA_DQ<8>")
	)
	(arc
		(start 378.299218 -274.756372)
		(mid 378.025019 -274.832207)
		(end 377.748546 -274.765008)
		(width 0.088646)
		(layer "In6.Cu")
		(net "M_G_CPU0_SA_DQ<8>")
	)
	(arc
		(start 379.239018 -274.756372)
		(mid 378.964819 -274.832207)
		(end 378.688346 -274.765008)
		(width 0.088646)
		(layer "In6.Cu")
		(net "M_G_CPU0_SA_DQ<8>")
	)
	(arc
		(start 384.312414 -274.756626)
		(mid 384.125216 -274.706483)
		(end 383.938018 -274.756626)
		(width 0.088646)
		(layer "In6.Cu")
		(net "M_G_CPU0_SA_DQ<8>")
	)
	(arc
		(start 382.058418 -274.756372)
		(mid 381.781605 -274.832242)
		(end 381.503174 -274.762468)
		(width 0.088646)
		(layer "In6.Cu")
		(net "M_G_CPU0_SA_DQ<8>")
	)
	(arc
		(start 375.848118 -274.752816)
		(mid 375.662663 -274.574621)
		(end 375.575322 -274.3327)
		(width 0.088646)
		(layer "In6.Cu")
		(net "M_G_CPU0_SA_DQ<8>")
	)
	(arc
		(start 385.817618 -274.756626)
		(mid 385.543389 -274.832551)
		(end 385.266946 -274.765262)
		(width 0.088646)
		(layer "In6.Cu")
		(net "M_G_CPU0_SA_DQ<8>")
	)
	(arc
		(start 377.359418 -274.756372)
		(mid 377.085219 -274.832207)
		(end 376.808746 -274.765008)
		(width 0.088646)
		(layer "In6.Cu")
		(net "M_G_CPU0_SA_DQ<8>")
	)
	(arc
		(start 379.613414 -274.756372)
		(mid 379.426216 -274.706229)
		(end 379.239018 -274.756372)
		(width 0.088646)
		(layer "In6.Cu")
		(net "M_G_CPU0_SA_DQ<8>")
	)
	(arc
		(start 377.733814 -274.756372)
		(mid 377.546616 -274.706229)
		(end 377.359418 -274.756372)
		(width 0.088646)
		(layer "In6.Cu")
		(net "M_G_CPU0_SA_DQ<8>")
	)
	(arc
		(start 378.673614 -274.756372)
		(mid 378.486416 -274.706229)
		(end 378.299218 -274.756372)
		(width 0.088646)
		(layer "In6.Cu")
		(net "M_G_CPU0_SA_DQ<8>")
	)
	(arc
		(start 380.178818 -274.756372)
		(mid 379.904619 -274.832207)
		(end 379.628146 -274.765008)
		(width 0.088646)
		(layer "In6.Cu")
		(net "M_G_CPU0_SA_DQ<8>")
	)
	(arc
		(start 381.49276 -274.756372)
		(mid 381.305562 -274.706229)
		(end 381.118364 -274.756372)
		(width 0.088646)
		(layer "In6.Cu")
		(net "M_G_CPU0_SA_DQ<8>")
	)
	(arc
		(start 383.372614 -274.756626)
		(mid 383.185416 -274.706483)
		(end 382.998218 -274.756626)
		(width 0.088646)
		(layer "In6.Cu")
		(net "M_G_CPU0_SA_DQ<8>")
	)
	(arc
		(start 381.10795 -274.762468)
		(mid 380.829772 -274.832191)
		(end 380.553214 -274.756372)
		(width 0.088646)
		(layer "In6.Cu")
		(net "M_G_CPU0_SA_DQ<8>")
	)
	(arc
		(start 376.794014 -274.756372)
		(mid 376.606816 -274.706229)
		(end 376.419618 -274.756372)
		(width 0.088646)
		(layer "In6.Cu")
		(net "M_G_CPU0_SA_DQ<8>")
	)
	(segment
		(start 447.23812 -307.816758)
		(end 448.572382 -307.816758)
		(width 0.20066)
		(layer "F.Cu")
		(net "M_G_CPU0_SA_DQ<7>")
	)
	(segment
		(start 441.028582 -307.816758)
		(end 442.726826 -307.816758)
		(width 0.20066)
		(layer "F.Cu")
		(net "M_G_CPU0_SA_DQ<7>")
	)
	(segment
		(start 446.367916 -307.798978)
		(end 446.602104 -307.56479)
		(width 0.20066)
		(layer "F.Cu")
		(net "M_G_CPU0_SA_DQ<7>")
	)
	(segment
		(start 445.482726 -308.253892)
		(end 446.163954 -308.253892)
		(width 0.20066)
		(layer "F.Cu")
		(net "M_G_CPU0_SA_DQ<7>")
	)
	(segment
		(start 446.367916 -308.04993)
		(end 446.367916 -307.798978)
		(width 0.20066)
		(layer "F.Cu")
		(net "M_G_CPU0_SA_DQ<7>")
	)
	(segment
		(start 379.425962 -273.452844)
		(end 379.426216 -273.453098)
		(width 0.20066)
		(layer "F.Cu")
		(net "M_G_CPU0_SA_DQ<7>")
	)
	(segment
		(start 446.986152 -307.56479)
		(end 447.23812 -307.816758)
		(width 0.20066)
		(layer "F.Cu")
		(net "M_G_CPU0_SA_DQ<7>")
	)
	(segment
		(start 443.462664 -308.2417)
		(end 445.470534 -308.2417)
		(width 0.1016)
		(layer "F.Cu")
		(net "M_G_CPU0_SA_DQ<7>")
	)
	(segment
		(start 443.15888 -308.248812)
		(end 443.450726 -308.248812)
		(width 0.20066)
		(layer "F.Cu")
		(net "M_G_CPU0_SA_DQ<7>")
	)
	(segment
		(start 446.163954 -308.253892)
		(end 446.367916 -308.04993)
		(width 0.20066)
		(layer "F.Cu")
		(net "M_G_CPU0_SA_DQ<7>")
	)
	(segment
		(start 443.450726 -308.248812)
		(end 443.455552 -308.248812)
		(width 0.101854)
		(layer "F.Cu")
		(net "M_G_CPU0_SA_DQ<7>")
	)
	(segment
		(start 379.425962 -272.917158)
		(end 379.425962 -273.452844)
		(width 0.20066)
		(layer "F.Cu")
		(net "M_G_CPU0_SA_DQ<7>")
	)
	(segment
		(start 443.455552 -308.248812)
		(end 443.462664 -308.2417)
		(width 0.1016)
		(layer "F.Cu")
		(net "M_G_CPU0_SA_DQ<7>")
	)
	(segment
		(start 442.726826 -307.816758)
		(end 443.15888 -308.248812)
		(width 0.20066)
		(layer "F.Cu")
		(net "M_G_CPU0_SA_DQ<7>")
	)
	(segment
		(start 439.923682 -307.816758)
		(end 441.028582 -307.816758)
		(width 0.20066)
		(layer "F.Cu")
		(net "M_G_CPU0_SA_DQ<7>")
	)
	(segment
		(start 446.602104 -307.56479)
		(end 446.986152 -307.56479)
		(width 0.20066)
		(layer "F.Cu")
		(net "M_G_CPU0_SA_DQ<7>")
	)
	(segment
		(start 445.470534 -308.2417)
		(end 445.482726 -308.253892)
		(width 0.1016)
		(layer "F.Cu")
		(net "M_G_CPU0_SA_DQ<7>")
	)
	(segment
		(start 412.267654 -307.545486)
		(end 411.792674 -307.545486)
		(width 0.18288)
		(layer "In4.Cu")
		(net "M_G_CPU0_SA_DQ<7>")
	)
	(segment
		(start 426.663612 -307.397658)
		(end 426.346112 -307.715158)
		(width 0.18288)
		(layer "In4.Cu")
		(net "M_G_CPU0_SA_DQ<7>")
	)
	(segment
		(start 407.671016 -304.893726)
		(end 406.768554 -303.991264)
		(width 0.18288)
		(layer "In4.Cu")
		(net "M_G_CPU0_SA_DQ<7>")
	)
	(segment
		(start 422.661842 -308.868826)
		(end 422.035732 -308.242716)
		(width 0.18288)
		(layer "In4.Cu")
		(net "M_G_CPU0_SA_DQ<7>")
	)
	(segment
		(start 438.494424 -307.040026)
		(end 438.035446 -307.040026)
		(width 0.18288)
		(layer "In4.Cu")
		(net "M_G_CPU0_SA_DQ<7>")
	)
	(segment
		(start 381.588264 -272.96364)
		(end 381.573532 -272.955004)
		(width 0.088646)
		(layer "In4.Cu")
		(net "M_G_CPU0_SA_DQ<7>")
	)
	(segment
		(start 392.826494 -280.981404)
		(end 387.52272 -275.67763)
		(width 0.18288)
		(layer "In4.Cu")
		(net "M_G_CPU0_SA_DQ<7>")
	)
	(segment
		(start 384.877564 -273.777456)
		(end 384.868674 -273.772376)
		(width 0.088646)
		(layer "In4.Cu")
		(net "M_G_CPU0_SA_DQ<7>")
	)
	(segment
		(start 422.035732 -308.242716)
		(end 420.551102 -308.242716)
		(width 0.18288)
		(layer "In4.Cu")
		(net "M_G_CPU0_SA_DQ<7>")
	)
	(segment
		(start 384.690112 -273.453098)
		(end 384.690112 -273.443192)
		(width 0.088646)
		(layer "In4.Cu")
		(net "M_G_CPU0_SA_DQ<7>")
	)
	(segment
		(start 438.035446 -307.040026)
		(end 437.685688 -307.389784)
		(width 0.18288)
		(layer "In4.Cu")
		(net "M_G_CPU0_SA_DQ<7>")
	)
	(segment
		(start 431.221134 -308.310026)
		(end 428.090838 -308.310026)
		(width 0.18288)
		(layer "In4.Cu")
		(net "M_G_CPU0_SA_DQ<7>")
	)
	(segment
		(start 379.056138 -273.510502)
		(end 379.113542 -273.453098)
		(width 0.088646)
		(layer "In4.Cu")
		(net "M_G_CPU0_SA_DQ<7>")
	)
	(segment
		(start 414.378394 -308.259226)
		(end 413.436054 -307.316886)
		(width 0.18288)
		(layer "In4.Cu")
		(net "M_G_CPU0_SA_DQ<7>")
	)
	(segment
		(start 415.879534 -308.259226)
		(end 414.378394 -308.259226)
		(width 0.18288)
		(layer "In4.Cu")
		(net "M_G_CPU0_SA_DQ<7>")
	)
	(segment
		(start 438.787032 -307.332634)
		(end 438.494424 -307.040026)
		(width 0.18288)
		(layer "In4.Cu")
		(net "M_G_CPU0_SA_DQ<7>")
	)
	(segment
		(start 438.787032 -307.688996)
		(end 438.787032 -307.332634)
		(width 0.18288)
		(layer "In4.Cu")
		(net "M_G_CPU0_SA_DQ<7>")
	)
	(segment
		(start 387.52272 -275.67763)
		(end 387.301232 -275.456142)
		(width 0.088646)
		(layer "In4.Cu")
		(net "M_G_CPU0_SA_DQ<7>")
	)
	(segment
		(start 419.507162 -309.286656)
		(end 416.906964 -309.286656)
		(width 0.18288)
		(layer "In4.Cu")
		(net "M_G_CPU0_SA_DQ<7>")
	)
	(segment
		(start 386.287264 -274.591272)
		(end 386.278374 -274.586192)
		(width 0.088646)
		(layer "In4.Cu")
		(net "M_G_CPU0_SA_DQ<7>")
	)
	(segment
		(start 408.396694 -304.893726)
		(end 407.671016 -304.893726)
		(width 0.18288)
		(layer "In4.Cu")
		(net "M_G_CPU0_SA_DQ<7>")
	)
	(segment
		(start 379.113542 -273.453098)
		(end 379.426216 -273.453098)
		(width 0.088646)
		(layer "In4.Cu")
		(net "M_G_CPU0_SA_DQ<7>")
	)
	(segment
		(start 428.090838 -308.310026)
		(end 427.17847 -307.397658)
		(width 0.18288)
		(layer "In4.Cu")
		(net "M_G_CPU0_SA_DQ<7>")
	)
	(segment
		(start 412.496254 -307.316886)
		(end 412.267654 -307.545486)
		(width 0.18288)
		(layer "In4.Cu")
		(net "M_G_CPU0_SA_DQ<7>")
	)
	(segment
		(start 425.771056 -307.715158)
		(end 425.445936 -307.390038)
		(width 0.18288)
		(layer "In4.Cu")
		(net "M_G_CPU0_SA_DQ<7>")
	)
	(segment
		(start 382.528064 -272.96364)
		(end 382.513332 -272.955004)
		(width 0.088646)
		(layer "In4.Cu")
		(net "M_G_CPU0_SA_DQ<7>")
	)
	(segment
		(start 438.914794 -307.816758)
		(end 438.787032 -307.688996)
		(width 0.18288)
		(layer "In4.Cu")
		(net "M_G_CPU0_SA_DQ<7>")
	)
	(segment
		(start 386.569966 -275.080984)
		(end 386.569966 -275.06676)
		(width 0.088646)
		(layer "In4.Cu")
		(net "M_G_CPU0_SA_DQ<7>")
	)
	(segment
		(start 379.622304 -273.772376)
		(end 379.613414 -273.777456)
		(width 0.088646)
		(layer "In4.Cu")
		(net "M_G_CPU0_SA_DQ<7>")
	)
	(segment
		(start 386.099812 -274.266914)
		(end 386.099812 -274.257008)
		(width 0.088646)
		(layer "In4.Cu")
		(net "M_G_CPU0_SA_DQ<7>")
	)
	(segment
		(start 427.17847 -307.397658)
		(end 426.663612 -307.397658)
		(width 0.18288)
		(layer "In4.Cu")
		(net "M_G_CPU0_SA_DQ<7>")
	)
	(segment
		(start 380.648464 -272.96364)
		(end 380.63805 -272.957544)
		(width 0.088646)
		(layer "In4.Cu")
		(net "M_G_CPU0_SA_DQ<7>")
	)
	(segment
		(start 403.145752 -301.915068)
		(end 398.80667 -295.41978)
		(width 0.18288)
		(layer "In4.Cu")
		(net "M_G_CPU0_SA_DQ<7>")
	)
	(segment
		(start 398.80667 -295.41978)
		(end 392.826494 -280.981404)
		(width 0.18288)
		(layer "In4.Cu")
		(net "M_G_CPU0_SA_DQ<7>")
	)
	(segment
		(start 425.445936 -307.390038)
		(end 424.569128 -307.390038)
		(width 0.18288)
		(layer "In4.Cu")
		(net "M_G_CPU0_SA_DQ<7>")
	)
	(segment
		(start 379.800866 -273.443192)
		(end 379.800866 -273.453098)
		(width 0.088646)
		(layer "In4.Cu")
		(net "M_G_CPU0_SA_DQ<7>")
	)
	(segment
		(start 432.141376 -307.389784)
		(end 431.221134 -308.310026)
		(width 0.18288)
		(layer "In4.Cu")
		(net "M_G_CPU0_SA_DQ<7>")
	)
	(segment
		(start 387.301232 -275.456142)
		(end 386.944616 -275.456142)
		(width 0.088646)
		(layer "In4.Cu")
		(net "M_G_CPU0_SA_DQ<7>")
	)
	(segment
		(start 406.768554 -303.991264)
		(end 405.221948 -303.991264)
		(width 0.18288)
		(layer "In4.Cu")
		(net "M_G_CPU0_SA_DQ<7>")
	)
	(segment
		(start 416.906964 -309.286656)
		(end 415.879534 -308.259226)
		(width 0.18288)
		(layer "In4.Cu")
		(net "M_G_CPU0_SA_DQ<7>")
	)
	(segment
		(start 413.436054 -307.316886)
		(end 412.496254 -307.316886)
		(width 0.18288)
		(layer "In4.Cu")
		(net "M_G_CPU0_SA_DQ<7>")
	)
	(segment
		(start 426.346112 -307.715158)
		(end 425.771056 -307.715158)
		(width 0.18288)
		(layer "In4.Cu")
		(net "M_G_CPU0_SA_DQ<7>")
	)
	(segment
		(start 424.569128 -307.390038)
		(end 423.09034 -308.868826)
		(width 0.18288)
		(layer "In4.Cu")
		(net "M_G_CPU0_SA_DQ<7>")
	)
	(segment
		(start 405.221948 -303.991264)
		(end 403.145752 -301.915068)
		(width 0.18288)
		(layer "In4.Cu")
		(net "M_G_CPU0_SA_DQ<7>")
	)
	(segment
		(start 411.279594 -307.032406)
		(end 411.279594 -306.852066)
		(width 0.18288)
		(layer "In4.Cu")
		(net "M_G_CPU0_SA_DQ<7>")
	)
	(segment
		(start 409.19527 -305.692302)
		(end 408.396694 -304.893726)
		(width 0.18288)
		(layer "In4.Cu")
		(net "M_G_CPU0_SA_DQ<7>")
	)
	(segment
		(start 410.11983 -305.692302)
		(end 409.19527 -305.692302)
		(width 0.18288)
		(layer "In4.Cu")
		(net "M_G_CPU0_SA_DQ<7>")
	)
	(segment
		(start 379.239018 -273.777456)
		(end 379.230128 -273.772376)
		(width 0.088646)
		(layer "In4.Cu")
		(net "M_G_CPU0_SA_DQ<7>")
	)
	(segment
		(start 411.279594 -306.852066)
		(end 410.11983 -305.692302)
		(width 0.18288)
		(layer "In4.Cu")
		(net "M_G_CPU0_SA_DQ<7>")
	)
	(segment
		(start 423.09034 -308.868826)
		(end 422.661842 -308.868826)
		(width 0.18288)
		(layer "In4.Cu")
		(net "M_G_CPU0_SA_DQ<7>")
	)
	(segment
		(start 439.923682 -307.816758)
		(end 438.914794 -307.816758)
		(width 0.18288)
		(layer "In4.Cu")
		(net "M_G_CPU0_SA_DQ<7>")
	)
	(segment
		(start 420.551102 -308.242716)
		(end 419.507162 -309.286656)
		(width 0.18288)
		(layer "In4.Cu")
		(net "M_G_CPU0_SA_DQ<7>")
	)
	(segment
		(start 383.467864 -272.96364)
		(end 383.453132 -272.955004)
		(width 0.088646)
		(layer "In4.Cu")
		(net "M_G_CPU0_SA_DQ<7>")
	)
	(segment
		(start 411.792674 -307.545486)
		(end 411.279594 -307.032406)
		(width 0.18288)
		(layer "In4.Cu")
		(net "M_G_CPU0_SA_DQ<7>")
	)
	(segment
		(start 437.685688 -307.389784)
		(end 432.141376 -307.389784)
		(width 0.18288)
		(layer "In4.Cu")
		(net "M_G_CPU0_SA_DQ<7>")
	)
	(arc
		(start 386.748528 -275.400262)
		(mid 386.617614 -275.263902)
		(end 386.569966 -275.080984)
		(width 0.088646)
		(layer "In4.Cu")
		(net "M_G_CPU0_SA_DQ<7>")
	)
	(arc
		(start 380.63805 -272.957544)
		(mid 380.359872 -272.887821)
		(end 380.083314 -272.96364)
		(width 0.088646)
		(layer "In4.Cu")
		(net "M_G_CPU0_SA_DQ<7>")
	)
	(arc
		(start 380.083314 -272.96364)
		(mid 379.878979 -273.166245)
		(end 379.800866 -273.443192)
		(width 0.088646)
		(layer "In4.Cu")
		(net "M_G_CPU0_SA_DQ<7>")
	)
	(arc
		(start 381.573532 -272.955004)
		(mid 381.297057 -272.887684)
		(end 381.02286 -272.96364)
		(width 0.088646)
		(layer "In4.Cu")
		(net "M_G_CPU0_SA_DQ<7>")
	)
	(arc
		(start 383.84226 -272.96364)
		(mid 383.655062 -273.013783)
		(end 383.467864 -272.96364)
		(width 0.088646)
		(layer "In4.Cu")
		(net "M_G_CPU0_SA_DQ<7>")
	)
	(arc
		(start 386.099812 -274.257008)
		(mid 386.021701 -273.980059)
		(end 385.817364 -273.777456)
		(width 0.088646)
		(layer "In4.Cu")
		(net "M_G_CPU0_SA_DQ<7>")
	)
	(arc
		(start 384.690112 -273.443192)
		(mid 384.612001 -273.166243)
		(end 384.407664 -272.96364)
		(width 0.088646)
		(layer "In4.Cu")
		(net "M_G_CPU0_SA_DQ<7>")
	)
	(arc
		(start 384.868674 -273.772376)
		(mid 384.73776 -273.636016)
		(end 384.690112 -273.453098)
		(width 0.088646)
		(layer "In4.Cu")
		(net "M_G_CPU0_SA_DQ<7>")
	)
	(arc
		(start 381.96266 -272.96364)
		(mid 381.775462 -273.013783)
		(end 381.588264 -272.96364)
		(width 0.088646)
		(layer "In4.Cu")
		(net "M_G_CPU0_SA_DQ<7>")
	)
	(arc
		(start 381.02286 -272.96364)
		(mid 380.835662 -273.013783)
		(end 380.648464 -272.96364)
		(width 0.088646)
		(layer "In4.Cu")
		(net "M_G_CPU0_SA_DQ<7>")
	)
	(arc
		(start 382.90246 -272.96364)
		(mid 382.715262 -273.013783)
		(end 382.528064 -272.96364)
		(width 0.088646)
		(layer "In4.Cu")
		(net "M_G_CPU0_SA_DQ<7>")
	)
	(arc
		(start 385.25196 -273.777456)
		(mid 385.064762 -273.827599)
		(end 384.877564 -273.777456)
		(width 0.088646)
		(layer "In4.Cu")
		(net "M_G_CPU0_SA_DQ<7>")
	)
	(arc
		(start 383.453132 -272.955004)
		(mid 383.176657 -272.887684)
		(end 382.90246 -272.96364)
		(width 0.088646)
		(layer "In4.Cu")
		(net "M_G_CPU0_SA_DQ<7>")
	)
	(arc
		(start 382.513332 -272.955004)
		(mid 382.236857 -272.887684)
		(end 381.96266 -272.96364)
		(width 0.088646)
		(layer "In4.Cu")
		(net "M_G_CPU0_SA_DQ<7>")
	)
	(arc
		(start 379.613414 -273.777456)
		(mid 379.426216 -273.827599)
		(end 379.239018 -273.777456)
		(width 0.088646)
		(layer "In4.Cu")
		(net "M_G_CPU0_SA_DQ<7>")
	)
	(arc
		(start 384.407664 -272.96364)
		(mid 384.124962 -272.887864)
		(end 383.84226 -272.96364)
		(width 0.088646)
		(layer "In4.Cu")
		(net "M_G_CPU0_SA_DQ<7>")
	)
	(arc
		(start 385.817364 -273.777456)
		(mid 385.534662 -273.70168)
		(end 385.25196 -273.777456)
		(width 0.088646)
		(layer "In4.Cu")
		(net "M_G_CPU0_SA_DQ<7>")
	)
	(arc
		(start 379.800866 -273.453098)
		(mid 379.753187 -273.635998)
		(end 379.622304 -273.772376)
		(width 0.088646)
		(layer "In4.Cu")
		(net "M_G_CPU0_SA_DQ<7>")
	)
	(arc
		(start 386.569966 -275.06676)
		(mid 386.490747 -274.792075)
		(end 386.287264 -274.591272)
		(width 0.088646)
		(layer "In4.Cu")
		(net "M_G_CPU0_SA_DQ<7>")
	)
	(arc
		(start 386.278374 -274.586192)
		(mid 386.14746 -274.449832)
		(end 386.099812 -274.266914)
		(width 0.088646)
		(layer "In4.Cu")
		(net "M_G_CPU0_SA_DQ<7>")
	)
	(arc
		(start 386.944616 -275.456142)
		(mid 386.842693 -275.441806)
		(end 386.748528 -275.400262)
		(width 0.088646)
		(layer "In4.Cu")
		(net "M_G_CPU0_SA_DQ<7>")
	)
	(arc
		(start 379.230128 -273.772376)
		(mid 379.114389 -273.660552)
		(end 379.056138 -273.510502)
		(width 0.088646)
		(layer "In4.Cu")
		(net "M_G_CPU0_SA_DQ<7>")
	)
	(segment
		(start 443.462664 -309.941722)
		(end 445.470534 -309.941722)
		(width 0.1016)
		(layer "F.Cu")
		(net "M_G_CPU0_SA_DQ<6>")
	)
	(segment
		(start 379.896116 -273.730974)
		(end 379.896116 -274.26666)
		(width 0.20066)
		(layer "F.Cu")
		(net "M_G_CPU0_SA_DQ<6>")
	)
	(segment
		(start 446.367916 -309.499)
		(end 446.602104 -309.264812)
		(width 0.20066)
		(layer "F.Cu")
		(net "M_G_CPU0_SA_DQ<6>")
	)
	(segment
		(start 379.896116 -274.26666)
		(end 379.895862 -274.266914)
		(width 0.20066)
		(layer "F.Cu")
		(net "M_G_CPU0_SA_DQ<6>")
	)
	(segment
		(start 443.455552 -309.948834)
		(end 443.462664 -309.941722)
		(width 0.1016)
		(layer "F.Cu")
		(net "M_G_CPU0_SA_DQ<6>")
	)
	(segment
		(start 445.482726 -309.953914)
		(end 446.163954 -309.953914)
		(width 0.20066)
		(layer "F.Cu")
		(net "M_G_CPU0_SA_DQ<6>")
	)
	(segment
		(start 446.163954 -309.953914)
		(end 446.367916 -309.749952)
		(width 0.20066)
		(layer "F.Cu")
		(net "M_G_CPU0_SA_DQ<6>")
	)
	(segment
		(start 442.726826 -309.51678)
		(end 443.15888 -309.948834)
		(width 0.20066)
		(layer "F.Cu")
		(net "M_G_CPU0_SA_DQ<6>")
	)
	(segment
		(start 439.923936 -309.51678)
		(end 441.028582 -309.51678)
		(width 0.20066)
		(layer "F.Cu")
		(net "M_G_CPU0_SA_DQ<6>")
	)
	(segment
		(start 446.367916 -309.749952)
		(end 446.367916 -309.499)
		(width 0.20066)
		(layer "F.Cu")
		(net "M_G_CPU0_SA_DQ<6>")
	)
	(segment
		(start 443.450726 -309.948834)
		(end 443.455552 -309.948834)
		(width 0.101854)
		(layer "F.Cu")
		(net "M_G_CPU0_SA_DQ<6>")
	)
	(segment
		(start 443.15888 -309.948834)
		(end 443.450726 -309.948834)
		(width 0.20066)
		(layer "F.Cu")
		(net "M_G_CPU0_SA_DQ<6>")
	)
	(segment
		(start 446.986152 -309.264812)
		(end 447.23812 -309.51678)
		(width 0.20066)
		(layer "F.Cu")
		(net "M_G_CPU0_SA_DQ<6>")
	)
	(segment
		(start 441.028582 -309.51678)
		(end 442.726826 -309.51678)
		(width 0.20066)
		(layer "F.Cu")
		(net "M_G_CPU0_SA_DQ<6>")
	)
	(segment
		(start 445.470534 -309.941722)
		(end 445.482726 -309.953914)
		(width 0.1016)
		(layer "F.Cu")
		(net "M_G_CPU0_SA_DQ<6>")
	)
	(segment
		(start 446.602104 -309.264812)
		(end 446.986152 -309.264812)
		(width 0.20066)
		(layer "F.Cu")
		(net "M_G_CPU0_SA_DQ<6>")
	)
	(segment
		(start 439.923682 -309.516526)
		(end 439.923936 -309.51678)
		(width 0.20066)
		(layer "F.Cu")
		(net "M_G_CPU0_SA_DQ<6>")
	)
	(segment
		(start 447.23812 -309.51678)
		(end 448.572382 -309.51678)
		(width 0.20066)
		(layer "F.Cu")
		(net "M_G_CPU0_SA_DQ<6>")
	)
	(segment
		(start 430.82464 -310.027574)
		(end 430.415192 -310.027574)
		(width 0.18288)
		(layer "In4.Cu")
		(net "M_G_CPU0_SA_DQ<6>")
	)
	(segment
		(start 424.483276 -309.942738)
		(end 423.637456 -310.788558)
		(width 0.18288)
		(layer "In4.Cu")
		(net "M_G_CPU0_SA_DQ<6>")
	)
	(segment
		(start 437.157876 -310.214772)
		(end 436.974996 -310.397652)
		(width 0.18288)
		(layer "In4.Cu")
		(net "M_G_CPU0_SA_DQ<6>")
	)
	(segment
		(start 403.069552 -303.636934)
		(end 397.740886 -295.662604)
		(width 0.18288)
		(layer "In4.Cu")
		(net "M_G_CPU0_SA_DQ<6>")
	)
	(segment
		(start 384.407664 -274.591272)
		(end 384.398774 -274.586192)
		(width 0.088646)
		(layer "In4.Cu")
		(net "M_G_CPU0_SA_DQ<6>")
	)
	(segment
		(start 387.784594 -276.949916)
		(end 387.238748 -276.40407)
		(width 0.088646)
		(layer "In4.Cu")
		(net "M_G_CPU0_SA_DQ<6>")
	)
	(segment
		(start 386.287264 -276.219158)
		(end 386.278374 -276.214078)
		(width 0.088646)
		(layer "In4.Cu")
		(net "M_G_CPU0_SA_DQ<6>")
	)
	(segment
		(start 382.058164 -273.777456)
		(end 382.052322 -273.774154)
		(width 0.088646)
		(layer "In4.Cu")
		(net "M_G_CPU0_SA_DQ<6>")
	)
	(segment
		(start 411.782514 -309.259986)
		(end 409.991814 -307.469286)
		(width 0.18288)
		(layer "In4.Cu")
		(net "M_G_CPU0_SA_DQ<6>")
	)
	(segment
		(start 391.55751 -280.722832)
		(end 387.784594 -276.949916)
		(width 0.18288)
		(layer "In4.Cu")
		(net "M_G_CPU0_SA_DQ<6>")
	)
	(segment
		(start 433.643278 -309.310786)
		(end 433.121308 -309.832756)
		(width 0.18288)
		(layer "In4.Cu")
		(net "M_G_CPU0_SA_DQ<6>")
	)
	(segment
		(start 430.415192 -310.027574)
		(end 430.18456 -310.258206)
		(width 0.18288)
		(layer "In4.Cu")
		(net "M_G_CPU0_SA_DQ<6>")
	)
	(segment
		(start 434.977286 -309.310786)
		(end 433.643278 -309.310786)
		(width 0.18288)
		(layer "In4.Cu")
		(net "M_G_CPU0_SA_DQ<6>")
	)
	(segment
		(start 437.538368 -309.091584)
		(end 437.340756 -309.091584)
		(width 0.18288)
		(layer "In4.Cu")
		(net "M_G_CPU0_SA_DQ<6>")
	)
	(segment
		(start 384.220212 -274.266914)
		(end 384.220212 -274.257008)
		(width 0.088646)
		(layer "In4.Cu")
		(net "M_G_CPU0_SA_DQ<6>")
	)
	(segment
		(start 431.055272 -310.258206)
		(end 430.82464 -310.027574)
		(width 0.18288)
		(layer "In4.Cu")
		(net "M_G_CPU0_SA_DQ<6>")
	)
	(segment
		(start 416.785552 -310.793384)
		(end 416.029394 -310.037226)
		(width 0.18288)
		(layer "In4.Cu")
		(net "M_G_CPU0_SA_DQ<6>")
	)
	(segment
		(start 439.290968 -308.883812)
		(end 437.74614 -308.883812)
		(width 0.18288)
		(layer "In4.Cu")
		(net "M_G_CPU0_SA_DQ<6>")
	)
	(segment
		(start 431.83683 -310.258206)
		(end 431.055272 -310.258206)
		(width 0.18288)
		(layer "In4.Cu")
		(net "M_G_CPU0_SA_DQ<6>")
	)
	(segment
		(start 423.637456 -310.788558)
		(end 419.937184 -310.788558)
		(width 0.18288)
		(layer "In4.Cu")
		(net "M_G_CPU0_SA_DQ<6>")
	)
	(segment
		(start 391.9728 -281.725878)
		(end 391.55751 -280.722832)
		(width 0.18288)
		(layer "In4.Cu")
		(net "M_G_CPU0_SA_DQ<6>")
	)
	(segment
		(start 436.281576 -309.091584)
		(end 435.196488 -309.091584)
		(width 0.18288)
		(layer "In4.Cu")
		(net "M_G_CPU0_SA_DQ<6>")
	)
	(segment
		(start 414.594802 -309.402226)
		(end 413.885634 -309.402226)
		(width 0.18288)
		(layer "In4.Cu")
		(net "M_G_CPU0_SA_DQ<6>")
	)
	(segment
		(start 428.987966 -310.17464)
		(end 428.411386 -310.17464)
		(width 0.18288)
		(layer "In4.Cu")
		(net "M_G_CPU0_SA_DQ<6>")
	)
	(segment
		(start 381.118364 -273.777456)
		(end 381.112522 -273.774154)
		(width 0.088646)
		(layer "In4.Cu")
		(net "M_G_CPU0_SA_DQ<6>")
	)
	(segment
		(start 416.029394 -310.037226)
		(end 415.229802 -310.037226)
		(width 0.18288)
		(layer "In4.Cu")
		(net "M_G_CPU0_SA_DQ<6>")
	)
	(segment
		(start 413.311594 -308.828186)
		(end 412.844234 -308.828186)
		(width 0.18288)
		(layer "In4.Cu")
		(net "M_G_CPU0_SA_DQ<6>")
	)
	(segment
		(start 385.347464 -274.591272)
		(end 385.332732 -274.582636)
		(width 0.088646)
		(layer "In4.Cu")
		(net "M_G_CPU0_SA_DQ<6>")
	)
	(segment
		(start 412.844234 -308.828186)
		(end 412.412434 -309.259986)
		(width 0.18288)
		(layer "In4.Cu")
		(net "M_G_CPU0_SA_DQ<6>")
	)
	(segment
		(start 380.553214 -273.77771)
		(end 380.474728 -273.822922)
		(width 0.088646)
		(layer "In4.Cu")
		(net "M_G_CPU0_SA_DQ<6>")
	)
	(segment
		(start 407.686002 -306.633626)
		(end 406.746456 -305.69408)
		(width 0.18288)
		(layer "In4.Cu")
		(net "M_G_CPU0_SA_DQ<6>")
	)
	(segment
		(start 385.630166 -275.080984)
		(end 385.630166 -275.06676)
		(width 0.088646)
		(layer "In4.Cu")
		(net "M_G_CPU0_SA_DQ<6>")
	)
	(segment
		(start 419.937184 -310.788558)
		(end 419.78834 -310.937402)
		(width 0.18288)
		(layer "In4.Cu")
		(net "M_G_CPU0_SA_DQ<6>")
	)
	(segment
		(start 383.001774 -273.779742)
		(end 382.997964 -273.777456)
		(width 0.088646)
		(layer "In4.Cu")
		(net "M_G_CPU0_SA_DQ<6>")
	)
	(segment
		(start 437.340756 -309.091584)
		(end 437.157876 -309.274464)
		(width 0.18288)
		(layer "In4.Cu")
		(net "M_G_CPU0_SA_DQ<6>")
	)
	(segment
		(start 432.26228 -309.832756)
		(end 431.83683 -310.258206)
		(width 0.18288)
		(layer "In4.Cu")
		(net "M_G_CPU0_SA_DQ<6>")
	)
	(segment
		(start 412.412434 -309.259986)
		(end 411.782514 -309.259986)
		(width 0.18288)
		(layer "In4.Cu")
		(net "M_G_CPU0_SA_DQ<6>")
	)
	(segment
		(start 413.885634 -309.402226)
		(end 413.311594 -308.828186)
		(width 0.18288)
		(layer "In4.Cu")
		(net "M_G_CPU0_SA_DQ<6>")
	)
	(segment
		(start 435.196488 -309.091584)
		(end 434.977286 -309.310786)
		(width 0.18288)
		(layer "In4.Cu")
		(net "M_G_CPU0_SA_DQ<6>")
	)
	(segment
		(start 405.33955 -305.69408)
		(end 403.069552 -303.636934)
		(width 0.18288)
		(layer "In4.Cu")
		(net "M_G_CPU0_SA_DQ<6>")
	)
	(segment
		(start 415.229802 -310.037226)
		(end 414.594802 -309.402226)
		(width 0.18288)
		(layer "In4.Cu")
		(net "M_G_CPU0_SA_DQ<6>")
	)
	(segment
		(start 408.625294 -306.633626)
		(end 407.686002 -306.633626)
		(width 0.18288)
		(layer "In4.Cu")
		(net "M_G_CPU0_SA_DQ<6>")
	)
	(segment
		(start 386.099812 -275.8948)
		(end 386.099812 -275.879306)
		(width 0.088646)
		(layer "In4.Cu")
		(net "M_G_CPU0_SA_DQ<6>")
	)
	(segment
		(start 409.991814 -307.469286)
		(end 409.460954 -307.469286)
		(width 0.18288)
		(layer "In4.Cu")
		(net "M_G_CPU0_SA_DQ<6>")
	)
	(segment
		(start 429.775112 -310.258206)
		(end 429.54448 -310.027574)
		(width 0.18288)
		(layer "In4.Cu")
		(net "M_G_CPU0_SA_DQ<6>")
	)
	(segment
		(start 385.817618 -275.405342)
		(end 385.808728 -275.400262)
		(width 0.088646)
		(layer "In4.Cu")
		(net "M_G_CPU0_SA_DQ<6>")
	)
	(segment
		(start 419.78834 -310.937402)
		(end 418.246052 -310.937402)
		(width 0.18288)
		(layer "In4.Cu")
		(net "M_G_CPU0_SA_DQ<6>")
	)
	(segment
		(start 433.121308 -309.832756)
		(end 432.26228 -309.832756)
		(width 0.18288)
		(layer "In4.Cu")
		(net "M_G_CPU0_SA_DQ<6>")
	)
	(segment
		(start 437.74614 -308.883812)
		(end 437.538368 -309.091584)
		(width 0.18288)
		(layer "In4.Cu")
		(net "M_G_CPU0_SA_DQ<6>")
	)
	(segment
		(start 409.460954 -307.469286)
		(end 408.625294 -306.633626)
		(width 0.18288)
		(layer "In4.Cu")
		(net "M_G_CPU0_SA_DQ<6>")
	)
	(segment
		(start 436.464456 -310.214772)
		(end 436.464456 -309.274464)
		(width 0.18288)
		(layer "In4.Cu")
		(net "M_G_CPU0_SA_DQ<6>")
	)
	(segment
		(start 387.238748 -276.40407)
		(end 386.449062 -276.268434)
		(width 0.088646)
		(layer "In4.Cu")
		(net "M_G_CPU0_SA_DQ<6>")
	)
	(segment
		(start 382.997964 -273.777456)
		(end 382.992122 -273.774154)
		(width 0.088646)
		(layer "In4.Cu")
		(net "M_G_CPU0_SA_DQ<6>")
	)
	(segment
		(start 418.102034 -310.793384)
		(end 416.785552 -310.793384)
		(width 0.18288)
		(layer "In4.Cu")
		(net "M_G_CPU0_SA_DQ<6>")
	)
	(segment
		(start 429.135032 -310.027574)
		(end 428.987966 -310.17464)
		(width 0.18288)
		(layer "In4.Cu")
		(net "M_G_CPU0_SA_DQ<6>")
	)
	(segment
		(start 406.746456 -305.69408)
		(end 405.33955 -305.69408)
		(width 0.18288)
		(layer "In4.Cu")
		(net "M_G_CPU0_SA_DQ<6>")
	)
	(segment
		(start 430.18456 -310.258206)
		(end 429.775112 -310.258206)
		(width 0.18288)
		(layer "In4.Cu")
		(net "M_G_CPU0_SA_DQ<6>")
	)
	(segment
		(start 429.54448 -310.027574)
		(end 429.135032 -310.027574)
		(width 0.18288)
		(layer "In4.Cu")
		(net "M_G_CPU0_SA_DQ<6>")
	)
	(segment
		(start 397.740886 -295.662604)
		(end 391.9728 -281.725878)
		(width 0.18288)
		(layer "In4.Cu")
		(net "M_G_CPU0_SA_DQ<6>")
	)
	(segment
		(start 428.411386 -310.17464)
		(end 428.179484 -309.942738)
		(width 0.18288)
		(layer "In4.Cu")
		(net "M_G_CPU0_SA_DQ<6>")
	)
	(segment
		(start 428.179484 -309.942738)
		(end 424.483276 -309.942738)
		(width 0.18288)
		(layer "In4.Cu")
		(net "M_G_CPU0_SA_DQ<6>")
	)
	(segment
		(start 381.124206 -273.781012)
		(end 381.118364 -273.777456)
		(width 0.088646)
		(layer "In4.Cu")
		(net "M_G_CPU0_SA_DQ<6>")
	)
	(segment
		(start 437.157876 -309.274464)
		(end 437.157876 -310.214772)
		(width 0.18288)
		(layer "In4.Cu")
		(net "M_G_CPU0_SA_DQ<6>")
	)
	(segment
		(start 382.064006 -273.781012)
		(end 382.058164 -273.777456)
		(width 0.088646)
		(layer "In4.Cu")
		(net "M_G_CPU0_SA_DQ<6>")
	)
	(segment
		(start 436.647336 -310.397652)
		(end 436.464456 -310.214772)
		(width 0.18288)
		(layer "In4.Cu")
		(net "M_G_CPU0_SA_DQ<6>")
	)
	(segment
		(start 418.246052 -310.937402)
		(end 418.102034 -310.793384)
		(width 0.18288)
		(layer "In4.Cu")
		(net "M_G_CPU0_SA_DQ<6>")
	)
	(segment
		(start 436.464456 -309.274464)
		(end 436.281576 -309.091584)
		(width 0.18288)
		(layer "In4.Cu")
		(net "M_G_CPU0_SA_DQ<6>")
	)
	(segment
		(start 436.974996 -310.397652)
		(end 436.647336 -310.397652)
		(width 0.18288)
		(layer "In4.Cu")
		(net "M_G_CPU0_SA_DQ<6>")
	)
	(segment
		(start 439.923682 -309.516526)
		(end 439.290968 -308.883812)
		(width 0.18288)
		(layer "In4.Cu")
		(net "M_G_CPU0_SA_DQ<6>")
	)
	(arc
		(start 381.112522 -273.774154)
		(mid 380.832387 -273.701838)
		(end 380.553214 -273.77771)
		(width 0.088646)
		(layer "In4.Cu")
		(net "M_G_CPU0_SA_DQ<6>")
	)
	(arc
		(start 382.432814 -273.77771)
		(mid 382.24886 -273.827805)
		(end 382.064006 -273.781012)
		(width 0.088646)
		(layer "In4.Cu")
		(net "M_G_CPU0_SA_DQ<6>")
	)
	(arc
		(start 381.493014 -273.77771)
		(mid 381.30906 -273.827805)
		(end 381.124206 -273.781012)
		(width 0.088646)
		(layer "In4.Cu")
		(net "M_G_CPU0_SA_DQ<6>")
	)
	(arc
		(start 386.449062 -276.268434)
		(mid 386.365346 -276.253047)
		(end 386.287264 -276.219158)
		(width 0.088646)
		(layer "In4.Cu")
		(net "M_G_CPU0_SA_DQ<6>")
	)
	(arc
		(start 383.937764 -273.777456)
		(mid 383.655206 -273.701807)
		(end 383.372614 -273.777456)
		(width 0.088646)
		(layer "In4.Cu")
		(net "M_G_CPU0_SA_DQ<6>")
	)
	(arc
		(start 383.372614 -273.777456)
		(mid 383.187493 -273.827719)
		(end 383.001774 -273.779742)
		(width 0.088646)
		(layer "In4.Cu")
		(net "M_G_CPU0_SA_DQ<6>")
	)
	(arc
		(start 384.78206 -274.591272)
		(mid 384.594862 -274.641415)
		(end 384.407664 -274.591272)
		(width 0.088646)
		(layer "In4.Cu")
		(net "M_G_CPU0_SA_DQ<6>")
	)
	(arc
		(start 384.398774 -274.586192)
		(mid 384.26786 -274.449832)
		(end 384.220212 -274.266914)
		(width 0.088646)
		(layer "In4.Cu")
		(net "M_G_CPU0_SA_DQ<6>")
	)
	(arc
		(start 385.630166 -275.06676)
		(mid 385.550947 -274.792075)
		(end 385.347464 -274.591272)
		(width 0.088646)
		(layer "In4.Cu")
		(net "M_G_CPU0_SA_DQ<6>")
	)
	(arc
		(start 384.220212 -274.257008)
		(mid 384.142101 -273.980059)
		(end 383.937764 -273.777456)
		(width 0.088646)
		(layer "In4.Cu")
		(net "M_G_CPU0_SA_DQ<6>")
	)
	(arc
		(start 382.052322 -273.774154)
		(mid 381.772187 -273.701838)
		(end 381.493014 -273.77771)
		(width 0.088646)
		(layer "In4.Cu")
		(net "M_G_CPU0_SA_DQ<6>")
	)
	(arc
		(start 380.474728 -273.822922)
		(mid 380.170662 -274.02584)
		(end 379.895862 -274.266914)
		(width 0.088646)
		(layer "In4.Cu")
		(net "M_G_CPU0_SA_DQ<6>")
	)
	(arc
		(start 385.332732 -274.582636)
		(mid 385.056291 -274.51547)
		(end 384.78206 -274.591272)
		(width 0.088646)
		(layer "In4.Cu")
		(net "M_G_CPU0_SA_DQ<6>")
	)
	(arc
		(start 386.278374 -276.214078)
		(mid 386.14746 -276.077718)
		(end 386.099812 -275.8948)
		(width 0.088646)
		(layer "In4.Cu")
		(net "M_G_CPU0_SA_DQ<6>")
	)
	(arc
		(start 386.099812 -275.879306)
		(mid 386.020442 -275.605572)
		(end 385.817618 -275.405342)
		(width 0.088646)
		(layer "In4.Cu")
		(net "M_G_CPU0_SA_DQ<6>")
	)
	(arc
		(start 385.808728 -275.400262)
		(mid 385.677814 -275.263902)
		(end 385.630166 -275.080984)
		(width 0.088646)
		(layer "In4.Cu")
		(net "M_G_CPU0_SA_DQ<6>")
	)
	(arc
		(start 382.992122 -273.774154)
		(mid 382.711987 -273.701838)
		(end 382.432814 -273.77771)
		(width 0.088646)
		(layer "In4.Cu")
		(net "M_G_CPU0_SA_DQ<6>")
	)
	(segment
		(start 439.843926 -308.2417)
		(end 439.82386 -308.2417)
		(width 0.101854)
		(layer "F.Cu")
		(net "M_G_CPU0_SA_DQ<5>")
	)
	(segment
		(start 442.032644 -308.2417)
		(end 439.843926 -308.2417)
		(width 0.1016)
		(layer "F.Cu")
		(net "M_G_CPU0_SA_DQ<5>")
	)
	(segment
		(start 442.038994 -308.23535)
		(end 442.032644 -308.2417)
		(width 0.1016)
		(layer "F.Cu")
		(net "M_G_CPU0_SA_DQ<5>")
	)
	(segment
		(start 439.173112 -308.915308)
		(end 438.697878 -308.915308)
		(width 0.20066)
		(layer "F.Cu")
		(net "M_G_CPU0_SA_DQ<5>")
	)
	(segment
		(start 378.486162 -273.452844)
		(end 378.486416 -273.453098)
		(width 0.20066)
		(layer "F.Cu")
		(net "M_G_CPU0_SA_DQ<5>")
	)
	(segment
		(start 378.486162 -272.917158)
		(end 378.486162 -273.452844)
		(width 0.20066)
		(layer "F.Cu")
		(net "M_G_CPU0_SA_DQ<5>")
	)
	(segment
		(start 439.82386 -308.2417)
		(end 439.479182 -308.2417)
		(width 0.20066)
		(layer "F.Cu")
		(net "M_G_CPU0_SA_DQ<5>")
	)
	(segment
		(start 438.697878 -308.915308)
		(end 438.449212 -308.666642)
		(width 0.20066)
		(layer "F.Cu")
		(net "M_G_CPU0_SA_DQ<5>")
	)
	(segment
		(start 444.47206 -308.666896)
		(end 442.880496 -308.666896)
		(width 0.20066)
		(layer "F.Cu")
		(net "M_G_CPU0_SA_DQ<5>")
	)
	(segment
		(start 442.44895 -308.23535)
		(end 442.038994 -308.23535)
		(width 0.20066)
		(layer "F.Cu")
		(net "M_G_CPU0_SA_DQ<5>")
	)
	(segment
		(start 439.361072 -308.727348)
		(end 439.173112 -308.915308)
		(width 0.20066)
		(layer "F.Cu")
		(net "M_G_CPU0_SA_DQ<5>")
	)
	(segment
		(start 442.880496 -308.666896)
		(end 442.44895 -308.23535)
		(width 0.20066)
		(layer "F.Cu")
		(net "M_G_CPU0_SA_DQ<5>")
	)
	(segment
		(start 439.479182 -308.2417)
		(end 439.361072 -308.35981)
		(width 0.20066)
		(layer "F.Cu")
		(net "M_G_CPU0_SA_DQ<5>")
	)
	(segment
		(start 439.361072 -308.35981)
		(end 439.361072 -308.727348)
		(width 0.20066)
		(layer "F.Cu")
		(net "M_G_CPU0_SA_DQ<5>")
	)
	(segment
		(start 436.928514 -308.666642)
		(end 435.823614 -308.666642)
		(width 0.20066)
		(layer "F.Cu")
		(net "M_G_CPU0_SA_DQ<5>")
	)
	(segment
		(start 444.472314 -308.666642)
		(end 444.47206 -308.666896)
		(width 0.20066)
		(layer "F.Cu")
		(net "M_G_CPU0_SA_DQ<5>")
	)
	(segment
		(start 438.449212 -308.666642)
		(end 436.928514 -308.666642)
		(width 0.20066)
		(layer "F.Cu")
		(net "M_G_CPU0_SA_DQ<5>")
	)
	(segment
		(start 423.380662 -309.944008)
		(end 422.34739 -309.944008)
		(width 0.18288)
		(layer "In4.Cu")
		(net "M_G_CPU0_SA_DQ<5>")
	)
	(segment
		(start 435.28615 -308.154578)
		(end 433.171854 -308.154578)
		(width 0.18288)
		(layer "In4.Cu")
		(net "M_G_CPU0_SA_DQ<5>")
	)
	(segment
		(start 398.326102 -295.629076)
		(end 392.392916 -281.305762)
		(width 0.18288)
		(layer "In4.Cu")
		(net "M_G_CPU0_SA_DQ<5>")
	)
	(segment
		(start 419.469316 -309.944008)
		(end 419.044628 -310.368696)
		(width 0.18288)
		(layer "In4.Cu")
		(net "M_G_CPU0_SA_DQ<5>")
	)
	(segment
		(start 433.171854 -308.154578)
		(end 432.9303 -308.396132)
		(width 0.18288)
		(layer "In4.Cu")
		(net "M_G_CPU0_SA_DQ<5>")
	)
	(segment
		(start 413.603694 -308.327806)
		(end 412.536894 -308.327806)
		(width 0.18288)
		(layer "In4.Cu")
		(net "M_G_CPU0_SA_DQ<5>")
	)
	(segment
		(start 421.65397 -308.912768)
		(end 421.47109 -309.095648)
		(width 0.18288)
		(layer "In4.Cu")
		(net "M_G_CPU0_SA_DQ<5>")
	)
	(segment
		(start 414.109154 -308.833266)
		(end 413.603694 -308.327806)
		(width 0.18288)
		(layer "In4.Cu")
		(net "M_G_CPU0_SA_DQ<5>")
	)
	(segment
		(start 384.499612 -273.463004)
		(end 384.499612 -273.453098)
		(width 0.088646)
		(layer "In4.Cu")
		(net "M_G_CPU0_SA_DQ<5>")
	)
	(segment
		(start 383.383028 -273.134836)
		(end 383.372614 -273.12874)
		(width 0.088646)
		(layer "In4.Cu")
		(net "M_G_CPU0_SA_DQ<5>")
	)
	(segment
		(start 418.41928 -310.368696)
		(end 417.91001 -309.859426)
		(width 0.18288)
		(layer "In4.Cu")
		(net "M_G_CPU0_SA_DQ<5>")
	)
	(segment
		(start 381.507746 -273.137376)
		(end 381.493014 -273.12874)
		(width 0.088646)
		(layer "In4.Cu")
		(net "M_G_CPU0_SA_DQ<5>")
	)
	(segment
		(start 425.949618 -308.239922)
		(end 424.54322 -308.239922)
		(width 0.18288)
		(layer "In4.Cu")
		(net "M_G_CPU0_SA_DQ<5>")
	)
	(segment
		(start 426.009816 -308.835044)
		(end 426.164248 -308.680612)
		(width 0.18288)
		(layer "In4.Cu")
		(net "M_G_CPU0_SA_DQ<5>")
	)
	(segment
		(start 406.885648 -304.842672)
		(end 405.348948 -304.842672)
		(width 0.18288)
		(layer "In4.Cu")
		(net "M_G_CPU0_SA_DQ<5>")
	)
	(segment
		(start 435.798214 -308.666642)
		(end 435.28615 -308.154578)
		(width 0.18288)
		(layer "In4.Cu")
		(net "M_G_CPU0_SA_DQ<5>")
	)
	(segment
		(start 421.47109 -309.761128)
		(end 421.28821 -309.944008)
		(width 0.18288)
		(layer "In4.Cu")
		(net "M_G_CPU0_SA_DQ<5>")
	)
	(segment
		(start 432.9303 -308.396132)
		(end 432.9303 -309.021226)
		(width 0.18288)
		(layer "In4.Cu")
		(net "M_G_CPU0_SA_DQ<5>")
	)
	(segment
		(start 432.8033 -309.148226)
		(end 432.034442 -309.148226)
		(width 0.18288)
		(layer "In4.Cu")
		(net "M_G_CPU0_SA_DQ<5>")
	)
	(segment
		(start 426.164248 -308.454552)
		(end 425.949618 -308.239922)
		(width 0.18288)
		(layer "In4.Cu")
		(net "M_G_CPU0_SA_DQ<5>")
	)
	(segment
		(start 422.34739 -309.944008)
		(end 422.16451 -309.761128)
		(width 0.18288)
		(layer "In4.Cu")
		(net "M_G_CPU0_SA_DQ<5>")
	)
	(segment
		(start 416.765994 -309.859426)
		(end 415.739834 -308.833266)
		(width 0.18288)
		(layer "In4.Cu")
		(net "M_G_CPU0_SA_DQ<5>")
	)
	(segment
		(start 424.209718 -309.114952)
		(end 423.380662 -309.944008)
		(width 0.18288)
		(layer "In4.Cu")
		(net "M_G_CPU0_SA_DQ<5>")
	)
	(segment
		(start 409.242768 -306.54244)
		(end 408.180794 -305.480466)
		(width 0.18288)
		(layer "In4.Cu")
		(net "M_G_CPU0_SA_DQ<5>")
	)
	(segment
		(start 430.865788 -308.885844)
		(end 427.889416 -308.885844)
		(width 0.18288)
		(layer "In4.Cu")
		(net "M_G_CPU0_SA_DQ<5>")
	)
	(segment
		(start 424.209718 -308.573424)
		(end 424.209718 -309.114952)
		(width 0.18288)
		(layer "In4.Cu")
		(net "M_G_CPU0_SA_DQ<5>")
	)
	(segment
		(start 385.909312 -274.281138)
		(end 385.909312 -274.266914)
		(width 0.088646)
		(layer "In4.Cu")
		(net "M_G_CPU0_SA_DQ<5>")
	)
	(segment
		(start 379.71476 -273.939)
		(end 379.708664 -273.942556)
		(width 0.088646)
		(layer "In4.Cu")
		(net "M_G_CPU0_SA_DQ<5>")
	)
	(segment
		(start 421.98163 -308.912768)
		(end 421.65397 -308.912768)
		(width 0.18288)
		(layer "In4.Cu")
		(net "M_G_CPU0_SA_DQ<5>")
	)
	(segment
		(start 386.785358 -275.72081)
		(end 386.559044 -275.494496)
		(width 0.088646)
		(layer "In4.Cu")
		(net "M_G_CPU0_SA_DQ<5>")
	)
	(segment
		(start 431.143156 -309.510176)
		(end 431.0126 -309.37962)
		(width 0.18288)
		(layer "In4.Cu")
		(net "M_G_CPU0_SA_DQ<5>")
	)
	(segment
		(start 387.28269 -275.91766)
		(end 387.08584 -275.72081)
		(width 0.088646)
		(layer "In4.Cu")
		(net "M_G_CPU0_SA_DQ<5>")
	)
	(segment
		(start 426.164248 -308.680612)
		(end 426.164248 -308.454552)
		(width 0.18288)
		(layer "In4.Cu")
		(net "M_G_CPU0_SA_DQ<5>")
	)
	(segment
		(start 382.447546 -273.137376)
		(end 382.432814 -273.12874)
		(width 0.088646)
		(layer "In4.Cu")
		(net "M_G_CPU0_SA_DQ<5>")
	)
	(segment
		(start 410.649674 -307.03266)
		(end 410.159454 -306.54244)
		(width 0.18288)
		(layer "In4.Cu")
		(net "M_G_CPU0_SA_DQ<5>")
	)
	(segment
		(start 419.044628 -310.368696)
		(end 418.41928 -310.368696)
		(width 0.18288)
		(layer "In4.Cu")
		(net "M_G_CPU0_SA_DQ<5>")
	)
	(segment
		(start 431.0126 -309.37962)
		(end 431.0126 -309.032656)
		(width 0.18288)
		(layer "In4.Cu")
		(net "M_G_CPU0_SA_DQ<5>")
	)
	(segment
		(start 426.203618 -309.254906)
		(end 426.009816 -309.061104)
		(width 0.18288)
		(layer "In4.Cu")
		(net "M_G_CPU0_SA_DQ<5>")
	)
	(segment
		(start 386.379466 -275.096478)
		(end 386.379466 -275.080984)
		(width 0.088646)
		(layer "In4.Cu")
		(net "M_G_CPU0_SA_DQ<5>")
	)
	(segment
		(start 421.28821 -309.944008)
		(end 419.469316 -309.944008)
		(width 0.18288)
		(layer "In4.Cu")
		(net "M_G_CPU0_SA_DQ<5>")
	)
	(segment
		(start 410.159454 -306.54244)
		(end 409.242768 -306.54244)
		(width 0.18288)
		(layer "In4.Cu")
		(net "M_G_CPU0_SA_DQ<5>")
	)
	(segment
		(start 427.520354 -309.254906)
		(end 426.203618 -309.254906)
		(width 0.18288)
		(layer "In4.Cu")
		(net "M_G_CPU0_SA_DQ<5>")
	)
	(segment
		(start 379.708664 -273.942556)
		(end 379.693932 -273.951192)
		(width 0.088646)
		(layer "In4.Cu")
		(net "M_G_CPU0_SA_DQ<5>")
	)
	(segment
		(start 386.200904 -274.761706)
		(end 386.192014 -274.756626)
		(width 0.088646)
		(layer "In4.Cu")
		(net "M_G_CPU0_SA_DQ<5>")
	)
	(segment
		(start 378.79909 -273.453098)
		(end 378.486416 -273.453098)
		(width 0.088646)
		(layer "In4.Cu")
		(net "M_G_CPU0_SA_DQ<5>")
	)
	(segment
		(start 421.47109 -309.095648)
		(end 421.47109 -309.761128)
		(width 0.18288)
		(layer "In4.Cu")
		(net "M_G_CPU0_SA_DQ<5>")
	)
	(segment
		(start 422.16451 -309.095648)
		(end 421.98163 -308.912768)
		(width 0.18288)
		(layer "In4.Cu")
		(net "M_G_CPU0_SA_DQ<5>")
	)
	(segment
		(start 427.889416 -308.885844)
		(end 427.520354 -309.254906)
		(width 0.18288)
		(layer "In4.Cu")
		(net "M_G_CPU0_SA_DQ<5>")
	)
	(segment
		(start 407.523442 -305.480466)
		(end 406.885648 -304.842672)
		(width 0.18288)
		(layer "In4.Cu")
		(net "M_G_CPU0_SA_DQ<5>")
	)
	(segment
		(start 385.73075 -273.947636)
		(end 385.72186 -273.942556)
		(width 0.088646)
		(layer "In4.Cu")
		(net "M_G_CPU0_SA_DQ<5>")
	)
	(segment
		(start 426.009816 -309.061104)
		(end 426.009816 -308.835044)
		(width 0.18288)
		(layer "In4.Cu")
		(net "M_G_CPU0_SA_DQ<5>")
	)
	(segment
		(start 384.32105 -273.13382)
		(end 384.31216 -273.12874)
		(width 0.088646)
		(layer "In4.Cu")
		(net "M_G_CPU0_SA_DQ<5>")
	)
	(segment
		(start 408.180794 -305.480466)
		(end 407.523442 -305.480466)
		(width 0.18288)
		(layer "In4.Cu")
		(net "M_G_CPU0_SA_DQ<5>")
	)
	(segment
		(start 405.348948 -304.842672)
		(end 403.15134 -302.850804)
		(width 0.18288)
		(layer "In4.Cu")
		(net "M_G_CPU0_SA_DQ<5>")
	)
	(segment
		(start 378.864622 -273.51863)
		(end 378.79909 -273.453098)
		(width 0.088646)
		(layer "In4.Cu")
		(net "M_G_CPU0_SA_DQ<5>")
	)
	(segment
		(start 392.19632 -280.83129)
		(end 387.28269 -275.91766)
		(width 0.18288)
		(layer "In4.Cu")
		(net "M_G_CPU0_SA_DQ<5>")
	)
	(segment
		(start 403.15134 -302.850804)
		(end 398.326102 -295.629076)
		(width 0.18288)
		(layer "In4.Cu")
		(net "M_G_CPU0_SA_DQ<5>")
	)
	(segment
		(start 417.91001 -309.859426)
		(end 416.765994 -309.859426)
		(width 0.18288)
		(layer "In4.Cu")
		(net "M_G_CPU0_SA_DQ<5>")
	)
	(segment
		(start 380.178818 -273.12874)
		(end 380.169928 -273.13382)
		(width 0.088646)
		(layer "In4.Cu")
		(net "M_G_CPU0_SA_DQ<5>")
	)
	(segment
		(start 422.16451 -309.761128)
		(end 422.16451 -309.095648)
		(width 0.18288)
		(layer "In4.Cu")
		(net "M_G_CPU0_SA_DQ<5>")
	)
	(segment
		(start 432.9303 -309.021226)
		(end 432.8033 -309.148226)
		(width 0.18288)
		(layer "In4.Cu")
		(net "M_G_CPU0_SA_DQ<5>")
	)
	(segment
		(start 412.536894 -308.327806)
		(end 412.326074 -308.116986)
		(width 0.18288)
		(layer "In4.Cu")
		(net "M_G_CPU0_SA_DQ<5>")
	)
	(segment
		(start 387.08584 -275.72081)
		(end 386.785358 -275.72081)
		(width 0.088646)
		(layer "In4.Cu")
		(net "M_G_CPU0_SA_DQ<5>")
	)
	(segment
		(start 392.392916 -281.305762)
		(end 392.19632 -280.83129)
		(width 0.18288)
		(layer "In4.Cu")
		(net "M_G_CPU0_SA_DQ<5>")
	)
	(segment
		(start 412.326074 -308.116986)
		(end 411.528514 -308.116986)
		(width 0.18288)
		(layer "In4.Cu")
		(net "M_G_CPU0_SA_DQ<5>")
	)
	(segment
		(start 431.0126 -309.032656)
		(end 430.865788 -308.885844)
		(width 0.18288)
		(layer "In4.Cu")
		(net "M_G_CPU0_SA_DQ<5>")
	)
	(segment
		(start 431.672492 -309.510176)
		(end 431.143156 -309.510176)
		(width 0.18288)
		(layer "In4.Cu")
		(net "M_G_CPU0_SA_DQ<5>")
	)
	(segment
		(start 411.528514 -308.116986)
		(end 410.649674 -307.238146)
		(width 0.18288)
		(layer "In4.Cu")
		(net "M_G_CPU0_SA_DQ<5>")
	)
	(segment
		(start 380.567946 -273.137376)
		(end 380.553214 -273.12874)
		(width 0.088646)
		(layer "In4.Cu")
		(net "M_G_CPU0_SA_DQ<5>")
	)
	(segment
		(start 432.034442 -309.148226)
		(end 431.672492 -309.510176)
		(width 0.18288)
		(layer "In4.Cu")
		(net "M_G_CPU0_SA_DQ<5>")
	)
	(segment
		(start 415.739834 -308.833266)
		(end 414.109154 -308.833266)
		(width 0.18288)
		(layer "In4.Cu")
		(net "M_G_CPU0_SA_DQ<5>")
	)
	(segment
		(start 410.649674 -307.238146)
		(end 410.649674 -307.03266)
		(width 0.18288)
		(layer "In4.Cu")
		(net "M_G_CPU0_SA_DQ<5>")
	)
	(segment
		(start 424.54322 -308.239922)
		(end 424.209718 -308.573424)
		(width 0.18288)
		(layer "In4.Cu")
		(net "M_G_CPU0_SA_DQ<5>")
	)
	(segment
		(start 435.823614 -308.666642)
		(end 435.798214 -308.666642)
		(width 0.18288)
		(layer "In4.Cu")
		(net "M_G_CPU0_SA_DQ<5>")
	)
	(arc
		(start 381.118618 -273.12874)
		(mid 380.844419 -273.204575)
		(end 380.567946 -273.137376)
		(width 0.088646)
		(layer "In4.Cu")
		(net "M_G_CPU0_SA_DQ<5>")
	)
	(arc
		(start 381.493014 -273.12874)
		(mid 381.305816 -273.078597)
		(end 381.118618 -273.12874)
		(width 0.088646)
		(layer "In4.Cu")
		(net "M_G_CPU0_SA_DQ<5>")
	)
	(arc
		(start 380.553214 -273.12874)
		(mid 380.366016 -273.078597)
		(end 380.178818 -273.12874)
		(width 0.088646)
		(layer "In4.Cu")
		(net "M_G_CPU0_SA_DQ<5>")
	)
	(arc
		(start 379.693932 -273.951192)
		(mid 379.417457 -274.018512)
		(end 379.14326 -273.942556)
		(width 0.088646)
		(layer "In4.Cu")
		(net "M_G_CPU0_SA_DQ<5>")
	)
	(arc
		(start 382.058418 -273.12874)
		(mid 381.784219 -273.204575)
		(end 381.507746 -273.137376)
		(width 0.088646)
		(layer "In4.Cu")
		(net "M_G_CPU0_SA_DQ<5>")
	)
	(arc
		(start 384.499612 -273.453098)
		(mid 384.451933 -273.270198)
		(end 384.32105 -273.13382)
		(width 0.088646)
		(layer "In4.Cu")
		(net "M_G_CPU0_SA_DQ<5>")
	)
	(arc
		(start 380.169928 -273.13382)
		(mid 380.039014 -273.27018)
		(end 379.991366 -273.453098)
		(width 0.088646)
		(layer "In4.Cu")
		(net "M_G_CPU0_SA_DQ<5>")
	)
	(arc
		(start 386.192014 -274.756626)
		(mid 385.988533 -274.555822)
		(end 385.909312 -274.281138)
		(width 0.088646)
		(layer "In4.Cu")
		(net "M_G_CPU0_SA_DQ<5>")
	)
	(arc
		(start 384.31216 -273.12874)
		(mid 384.124962 -273.078597)
		(end 383.937764 -273.12874)
		(width 0.088646)
		(layer "In4.Cu")
		(net "M_G_CPU0_SA_DQ<5>")
	)
	(arc
		(start 385.347464 -273.942556)
		(mid 385.064762 -274.018332)
		(end 384.78206 -273.942556)
		(width 0.088646)
		(layer "In4.Cu")
		(net "M_G_CPU0_SA_DQ<5>")
	)
	(arc
		(start 384.78206 -273.942556)
		(mid 384.577725 -273.739951)
		(end 384.499612 -273.463004)
		(width 0.088646)
		(layer "In4.Cu")
		(net "M_G_CPU0_SA_DQ<5>")
	)
	(arc
		(start 386.559044 -275.494496)
		(mid 386.429269 -275.313526)
		(end 386.379466 -275.096478)
		(width 0.088646)
		(layer "In4.Cu")
		(net "M_G_CPU0_SA_DQ<5>")
	)
	(arc
		(start 382.998218 -273.12874)
		(mid 382.724019 -273.204575)
		(end 382.447546 -273.137376)
		(width 0.088646)
		(layer "In4.Cu")
		(net "M_G_CPU0_SA_DQ<5>")
	)
	(arc
		(start 385.909312 -274.266914)
		(mid 385.861633 -274.084014)
		(end 385.73075 -273.947636)
		(width 0.088646)
		(layer "In4.Cu")
		(net "M_G_CPU0_SA_DQ<5>")
	)
	(arc
		(start 386.379466 -275.080984)
		(mid 386.331787 -274.898084)
		(end 386.200904 -274.761706)
		(width 0.088646)
		(layer "In4.Cu")
		(net "M_G_CPU0_SA_DQ<5>")
	)
	(arc
		(start 383.372614 -273.12874)
		(mid 383.185416 -273.078597)
		(end 382.998218 -273.12874)
		(width 0.088646)
		(layer "In4.Cu")
		(net "M_G_CPU0_SA_DQ<5>")
	)
	(arc
		(start 385.72186 -273.942556)
		(mid 385.534662 -273.892413)
		(end 385.347464 -273.942556)
		(width 0.088646)
		(layer "In4.Cu")
		(net "M_G_CPU0_SA_DQ<5>")
	)
	(arc
		(start 382.432814 -273.12874)
		(mid 382.245616 -273.078597)
		(end 382.058418 -273.12874)
		(width 0.088646)
		(layer "In4.Cu")
		(net "M_G_CPU0_SA_DQ<5>")
	)
	(arc
		(start 379.14326 -273.942556)
		(mid 378.953747 -273.763591)
		(end 378.864622 -273.51863)
		(width 0.088646)
		(layer "In4.Cu")
		(net "M_G_CPU0_SA_DQ<5>")
	)
	(arc
		(start 383.937764 -273.12874)
		(mid 383.661205 -273.204483)
		(end 383.383028 -273.134836)
		(width 0.088646)
		(layer "In4.Cu")
		(net "M_G_CPU0_SA_DQ<5>")
	)
	(arc
		(start 379.991366 -273.453098)
		(mid 379.917375 -273.732664)
		(end 379.71476 -273.939)
		(width 0.088646)
		(layer "In4.Cu")
		(net "M_G_CPU0_SA_DQ<5>")
	)
	(segment
		(start 378.016516 -274.26666)
		(end 378.016262 -274.266914)
		(width 0.20066)
		(layer "F.Cu")
		(net "M_G_CPU0_SA_DQ<4>")
	)
	(segment
		(start 439.479182 -309.941722)
		(end 439.361072 -310.059832)
		(width 0.20066)
		(layer "F.Cu")
		(net "M_G_CPU0_SA_DQ<4>")
	)
	(segment
		(start 444.472314 -310.366664)
		(end 444.47206 -310.366918)
		(width 0.20066)
		(layer "F.Cu")
		(net "M_G_CPU0_SA_DQ<4>")
	)
	(segment
		(start 444.47206 -310.366918)
		(end 442.880496 -310.366918)
		(width 0.20066)
		(layer "F.Cu")
		(net "M_G_CPU0_SA_DQ<4>")
	)
	(segment
		(start 438.697878 -310.61533)
		(end 438.449212 -310.366664)
		(width 0.20066)
		(layer "F.Cu")
		(net "M_G_CPU0_SA_DQ<4>")
	)
	(segment
		(start 439.361072 -310.059832)
		(end 439.361072 -310.42737)
		(width 0.20066)
		(layer "F.Cu")
		(net "M_G_CPU0_SA_DQ<4>")
	)
	(segment
		(start 439.82386 -309.941722)
		(end 439.479182 -309.941722)
		(width 0.20066)
		(layer "F.Cu")
		(net "M_G_CPU0_SA_DQ<4>")
	)
	(segment
		(start 436.928514 -310.366664)
		(end 435.823614 -310.366664)
		(width 0.20066)
		(layer "F.Cu")
		(net "M_G_CPU0_SA_DQ<4>")
	)
	(segment
		(start 442.44895 -309.935372)
		(end 442.038994 -309.935372)
		(width 0.20066)
		(layer "F.Cu")
		(net "M_G_CPU0_SA_DQ<4>")
	)
	(segment
		(start 442.880496 -310.366918)
		(end 442.44895 -309.935372)
		(width 0.20066)
		(layer "F.Cu")
		(net "M_G_CPU0_SA_DQ<4>")
	)
	(segment
		(start 439.173112 -310.61533)
		(end 438.697878 -310.61533)
		(width 0.20066)
		(layer "F.Cu")
		(net "M_G_CPU0_SA_DQ<4>")
	)
	(segment
		(start 438.449212 -310.366664)
		(end 436.928514 -310.366664)
		(width 0.20066)
		(layer "F.Cu")
		(net "M_G_CPU0_SA_DQ<4>")
	)
	(segment
		(start 439.361072 -310.42737)
		(end 439.173112 -310.61533)
		(width 0.20066)
		(layer "F.Cu")
		(net "M_G_CPU0_SA_DQ<4>")
	)
	(segment
		(start 439.87085 -309.941722)
		(end 439.82386 -309.941722)
		(width 0.101854)
		(layer "F.Cu")
		(net "M_G_CPU0_SA_DQ<4>")
	)
	(segment
		(start 442.038994 -309.935372)
		(end 442.032644 -309.941722)
		(width 0.1016)
		(layer "F.Cu")
		(net "M_G_CPU0_SA_DQ<4>")
	)
	(segment
		(start 378.016516 -273.730974)
		(end 378.016516 -274.26666)
		(width 0.20066)
		(layer "F.Cu")
		(net "M_G_CPU0_SA_DQ<4>")
	)
	(segment
		(start 442.032644 -309.941722)
		(end 439.87085 -309.941722)
		(width 0.1016)
		(layer "F.Cu")
		(net "M_G_CPU0_SA_DQ<4>")
	)
	(segment
		(start 424.021504 -311.458356)
		(end 423.838624 -311.641236)
		(width 0.18288)
		(layer "In4.Cu")
		(net "M_G_CPU0_SA_DQ<4>")
	)
	(segment
		(start 423.838624 -311.641236)
		(end 422.26738 -311.641236)
		(width 0.18288)
		(layer "In4.Cu")
		(net "M_G_CPU0_SA_DQ<4>")
	)
	(segment
		(start 421.39108 -312.628026)
		(end 421.39108 -311.824116)
		(width 0.18288)
		(layer "In4.Cu")
		(net "M_G_CPU0_SA_DQ<4>")
	)
	(segment
		(start 422.26738 -311.641236)
		(end 422.0845 -311.824116)
		(width 0.18288)
		(layer "In4.Cu")
		(net "M_G_CPU0_SA_DQ<4>")
	)
	(segment
		(start 414.017968 -310.519826)
		(end 413.74822 -310.519826)
		(width 0.18288)
		(layer "In4.Cu")
		(net "M_G_CPU0_SA_DQ<4>")
	)
	(segment
		(start 429.152304 -311.372504)
		(end 428.969424 -311.189624)
		(width 0.18288)
		(layer "In4.Cu")
		(net "M_G_CPU0_SA_DQ<4>")
	)
	(segment
		(start 419.901878 -311.824116)
		(end 419.901878 -312.306716)
		(width 0.18288)
		(layer "In4.Cu")
		(net "M_G_CPU0_SA_DQ<4>")
	)
	(segment
		(start 387.540246 -277.194264)
		(end 386.979922 -276.63394)
		(width 0.088646)
		(layer "In4.Cu")
		(net "M_G_CPU0_SA_DQ<4>")
	)
	(segment
		(start 435.823614 -310.366664)
		(end 435.324758 -309.869078)
		(width 0.18288)
		(layer "In4.Cu")
		(net "M_G_CPU0_SA_DQ<4>")
	)
	(segment
		(start 383.85115 -273.947636)
		(end 383.84226 -273.942556)
		(width 0.088646)
		(layer "In4.Cu")
		(net "M_G_CPU0_SA_DQ<4>")
	)
	(segment
		(start 420.084758 -311.641236)
		(end 419.901878 -311.824116)
		(width 0.18288)
		(layer "In4.Cu")
		(net "M_G_CPU0_SA_DQ<4>")
	)
	(segment
		(start 414.39465 -310.143144)
		(end 414.017968 -310.519826)
		(width 0.18288)
		(layer "In4.Cu")
		(net "M_G_CPU0_SA_DQ<4>")
	)
	(segment
		(start 419.391338 -312.489596)
		(end 419.208458 -312.306716)
		(width 0.18288)
		(layer "In4.Cu")
		(net "M_G_CPU0_SA_DQ<4>")
	)
	(segment
		(start 384.327146 -274.765262)
		(end 384.312414 -274.756626)
		(width 0.088646)
		(layer "In4.Cu")
		(net "M_G_CPU0_SA_DQ<4>")
	)
	(segment
		(start 384.029712 -274.281138)
		(end 384.029712 -274.266914)
		(width 0.088646)
		(layer "In4.Cu")
		(net "M_G_CPU0_SA_DQ<4>")
	)
	(segment
		(start 428.755048 -310.748426)
		(end 427.916594 -310.748426)
		(width 0.18288)
		(layer "In4.Cu")
		(net "M_G_CPU0_SA_DQ<4>")
	)
	(segment
		(start 410.418026 -308.601618)
		(end 410.021024 -308.204616)
		(width 0.18288)
		(layer "In4.Cu")
		(net "M_G_CPU0_SA_DQ<4>")
	)
	(segment
		(start 428.969424 -311.189624)
		(end 428.969424 -310.962802)
		(width 0.18288)
		(layer "In4.Cu")
		(net "M_G_CPU0_SA_DQ<4>")
	)
	(segment
		(start 383.84226 -273.942556)
		(end 383.842514 -273.942556)
		(width 0.088646)
		(layer "In4.Cu")
		(net "M_G_CPU0_SA_DQ<4>")
	)
	(segment
		(start 411.116526 -309.300118)
		(end 410.827474 -309.300118)
		(width 0.18288)
		(layer "In4.Cu")
		(net "M_G_CPU0_SA_DQ<4>")
	)
	(segment
		(start 391.564114 -282.134564)
		(end 390.915906 -280.569924)
		(width 0.18288)
		(layer "In4.Cu")
		(net "M_G_CPU0_SA_DQ<4>")
	)
	(segment
		(start 435.324758 -309.869078)
		(end 434.911754 -309.869586)
		(width 0.18288)
		(layer "In4.Cu")
		(net "M_G_CPU0_SA_DQ<4>")
	)
	(segment
		(start 429.662844 -310.962802)
		(end 429.662844 -311.189624)
		(width 0.18288)
		(layer "In4.Cu")
		(net "M_G_CPU0_SA_DQ<4>")
	)
	(segment
		(start 408.316176 -307.15204)
		(end 407.366216 -307.15204)
		(width 0.18288)
		(layer "In4.Cu")
		(net "M_G_CPU0_SA_DQ<4>")
	)
	(segment
		(start 421.57396 -312.810906)
		(end 421.39108 -312.628026)
		(width 0.18288)
		(layer "In4.Cu")
		(net "M_G_CPU0_SA_DQ<4>")
	)
	(segment
		(start 425.795186 -310.788812)
		(end 424.487848 -310.788812)
		(width 0.18288)
		(layer "In4.Cu")
		(net "M_G_CPU0_SA_DQ<4>")
	)
	(segment
		(start 415.921444 -310.665876)
		(end 415.143696 -310.665876)
		(width 0.18288)
		(layer "In4.Cu")
		(net "M_G_CPU0_SA_DQ<4>")
	)
	(segment
		(start 427.916594 -310.748426)
		(end 427.317408 -311.347612)
		(width 0.18288)
		(layer "In4.Cu")
		(net "M_G_CPU0_SA_DQ<4>")
	)
	(segment
		(start 421.39108 -311.824116)
		(end 421.2082 -311.641236)
		(width 0.18288)
		(layer "In4.Cu")
		(net "M_G_CPU0_SA_DQ<4>")
	)
	(segment
		(start 421.2082 -311.641236)
		(end 420.084758 -311.641236)
		(width 0.18288)
		(layer "In4.Cu")
		(net "M_G_CPU0_SA_DQ<4>")
	)
	(segment
		(start 413.74822 -310.519826)
		(end 413.168846 -309.940452)
		(width 0.18288)
		(layer "In4.Cu")
		(net "M_G_CPU0_SA_DQ<4>")
	)
	(segment
		(start 405.379174 -306.542186)
		(end 402.887688 -304.284634)
		(width 0.18288)
		(layer "In4.Cu")
		(net "M_G_CPU0_SA_DQ<4>")
	)
	(segment
		(start 428.969424 -310.962802)
		(end 428.755048 -310.748426)
		(width 0.18288)
		(layer "In4.Cu")
		(net "M_G_CPU0_SA_DQ<4>")
	)
	(segment
		(start 421.90162 -312.810906)
		(end 421.57396 -312.810906)
		(width 0.18288)
		(layer "In4.Cu")
		(net "M_G_CPU0_SA_DQ<4>")
	)
	(segment
		(start 402.887688 -304.284634)
		(end 397.236442 -295.827958)
		(width 0.18288)
		(layer "In4.Cu")
		(net "M_G_CPU0_SA_DQ<4>")
	)
	(segment
		(start 434.013102 -309.869586)
		(end 433.05603 -310.826658)
		(width 0.18288)
		(layer "In4.Cu")
		(net "M_G_CPU0_SA_DQ<4>")
	)
	(segment
		(start 424.487848 -310.788812)
		(end 424.021504 -311.255156)
		(width 0.18288)
		(layer "In4.Cu")
		(net "M_G_CPU0_SA_DQ<4>")
	)
	(segment
		(start 382.902714 -273.942556)
		(end 382.896872 -273.939254)
		(width 0.088646)
		(layer "In4.Cu")
		(net "M_G_CPU0_SA_DQ<4>")
	)
	(segment
		(start 390.915906 -280.569924)
		(end 387.540246 -277.194264)
		(width 0.18288)
		(layer "In4.Cu")
		(net "M_G_CPU0_SA_DQ<4>")
	)
	(segment
		(start 409.368752 -308.204616)
		(end 408.316176 -307.15204)
		(width 0.18288)
		(layer "In4.Cu")
		(net "M_G_CPU0_SA_DQ<4>")
	)
	(segment
		(start 418.256974 -311.641236)
		(end 418.037264 -311.421526)
		(width 0.18288)
		(layer "In4.Cu")
		(net "M_G_CPU0_SA_DQ<4>")
	)
	(segment
		(start 381.023114 -273.942556)
		(end 381.017272 -273.939254)
		(width 0.088646)
		(layer "In4.Cu")
		(net "M_G_CPU0_SA_DQ<4>")
	)
	(segment
		(start 419.208458 -311.824116)
		(end 419.025578 -311.641236)
		(width 0.18288)
		(layer "In4.Cu")
		(net "M_G_CPU0_SA_DQ<4>")
	)
	(segment
		(start 378.768864 -274.591526)
		(end 378.37237 -274.362418)
		(width 0.088646)
		(layer "In4.Cu")
		(net "M_G_CPU0_SA_DQ<4>")
	)
	(segment
		(start 418.037264 -311.421526)
		(end 416.677094 -311.421526)
		(width 0.18288)
		(layer "In4.Cu")
		(net "M_G_CPU0_SA_DQ<4>")
	)
	(segment
		(start 380.51613 -274.068286)
		(end 380.270512 -274.447762)
		(width 0.088646)
		(layer "In4.Cu")
		(net "M_G_CPU0_SA_DQ<4>")
	)
	(segment
		(start 419.208458 -312.306716)
		(end 419.208458 -311.824116)
		(width 0.18288)
		(layer "In4.Cu")
		(net "M_G_CPU0_SA_DQ<4>")
	)
	(segment
		(start 386.979922 -276.63394)
		(end 386.348478 -276.445726)
		(width 0.088646)
		(layer "In4.Cu")
		(net "M_G_CPU0_SA_DQ<4>")
	)
	(segment
		(start 422.0845 -311.824116)
		(end 422.0845 -312.628026)
		(width 0.18288)
		(layer "In4.Cu")
		(net "M_G_CPU0_SA_DQ<4>")
	)
	(segment
		(start 419.025578 -311.641236)
		(end 418.256974 -311.641236)
		(width 0.18288)
		(layer "In4.Cu")
		(net "M_G_CPU0_SA_DQ<4>")
	)
	(segment
		(start 407.366216 -307.15204)
		(end 406.756362 -306.542186)
		(width 0.18288)
		(layer "In4.Cu")
		(net "M_G_CPU0_SA_DQ<4>")
	)
	(segment
		(start 433.05603 -310.826658)
		(end 431.469038 -310.826658)
		(width 0.18288)
		(layer "In4.Cu")
		(net "M_G_CPU0_SA_DQ<4>")
	)
	(segment
		(start 410.827474 -309.300118)
		(end 410.418026 -308.89067)
		(width 0.18288)
		(layer "In4.Cu")
		(net "M_G_CPU0_SA_DQ<4>")
	)
	(segment
		(start 381.968756 -273.946112)
		(end 381.962914 -273.942556)
		(width 0.088646)
		(layer "In4.Cu")
		(net "M_G_CPU0_SA_DQ<4>")
	)
	(segment
		(start 413.168846 -309.940452)
		(end 411.75686 -309.940452)
		(width 0.18288)
		(layer "In4.Cu")
		(net "M_G_CPU0_SA_DQ<4>")
	)
	(segment
		(start 424.021504 -311.255156)
		(end 424.021504 -311.458356)
		(width 0.18288)
		(layer "In4.Cu")
		(net "M_G_CPU0_SA_DQ<4>")
	)
	(segment
		(start 427.317408 -311.347612)
		(end 426.353986 -311.347612)
		(width 0.18288)
		(layer "In4.Cu")
		(net "M_G_CPU0_SA_DQ<4>")
	)
	(segment
		(start 397.236442 -295.827958)
		(end 391.564114 -282.134564)
		(width 0.18288)
		(layer "In4.Cu")
		(net "M_G_CPU0_SA_DQ<4>")
	)
	(segment
		(start 431.469038 -310.826658)
		(end 431.422302 -310.779922)
		(width 0.18288)
		(layer "In4.Cu")
		(net "M_G_CPU0_SA_DQ<4>")
	)
	(segment
		(start 422.0845 -312.628026)
		(end 421.90162 -312.810906)
		(width 0.18288)
		(layer "In4.Cu")
		(net "M_G_CPU0_SA_DQ<4>")
	)
	(segment
		(start 410.021024 -308.204616)
		(end 409.368752 -308.204616)
		(width 0.18288)
		(layer "In4.Cu")
		(net "M_G_CPU0_SA_DQ<4>")
	)
	(segment
		(start 426.353986 -311.347612)
		(end 425.795186 -310.788812)
		(width 0.18288)
		(layer "In4.Cu")
		(net "M_G_CPU0_SA_DQ<4>")
	)
	(segment
		(start 419.901878 -312.306716)
		(end 419.718998 -312.489596)
		(width 0.18288)
		(layer "In4.Cu")
		(net "M_G_CPU0_SA_DQ<4>")
	)
	(segment
		(start 385.439666 -275.096478)
		(end 385.439666 -275.080984)
		(width 0.088646)
		(layer "In4.Cu")
		(net "M_G_CPU0_SA_DQ<4>")
	)
	(segment
		(start 411.75686 -309.940452)
		(end 411.116526 -309.300118)
		(width 0.18288)
		(layer "In4.Cu")
		(net "M_G_CPU0_SA_DQ<4>")
	)
	(segment
		(start 381.028956 -273.946112)
		(end 381.023114 -273.942556)
		(width 0.088646)
		(layer "In4.Cu")
		(net "M_G_CPU0_SA_DQ<4>")
	)
	(segment
		(start 379.143514 -274.591526)
		(end 379.138942 -274.594066)
		(width 0.088646)
		(layer "In4.Cu")
		(net "M_G_CPU0_SA_DQ<4>")
	)
	(segment
		(start 385.261104 -274.761706)
		(end 385.252214 -274.756626)
		(width 0.088646)
		(layer "In4.Cu")
		(net "M_G_CPU0_SA_DQ<4>")
	)
	(segment
		(start 385.909312 -275.904706)
		(end 385.909312 -275.8948)
		(width 0.088646)
		(layer "In4.Cu")
		(net "M_G_CPU0_SA_DQ<4>")
	)
	(segment
		(start 380.149354 -274.554696)
		(end 380.078742 -274.594066)
		(width 0.088646)
		(layer "In4.Cu")
		(net "M_G_CPU0_SA_DQ<4>")
	)
	(segment
		(start 379.15088 -274.587208)
		(end 379.143514 -274.591526)
		(width 0.088646)
		(layer "In4.Cu")
		(net "M_G_CPU0_SA_DQ<4>")
	)
	(segment
		(start 419.718998 -312.489596)
		(end 419.391338 -312.489596)
		(width 0.18288)
		(layer "In4.Cu")
		(net "M_G_CPU0_SA_DQ<4>")
	)
	(segment
		(start 406.756362 -306.542186)
		(end 405.379174 -306.542186)
		(width 0.18288)
		(layer "In4.Cu")
		(net "M_G_CPU0_SA_DQ<4>")
	)
	(segment
		(start 385.73075 -275.575522)
		(end 385.72186 -275.570442)
		(width 0.088646)
		(layer "In4.Cu")
		(net "M_G_CPU0_SA_DQ<4>")
	)
	(segment
		(start 429.845724 -310.779922)
		(end 429.662844 -310.962802)
		(width 0.18288)
		(layer "In4.Cu")
		(net "M_G_CPU0_SA_DQ<4>")
	)
	(segment
		(start 434.911754 -309.869586)
		(end 434.013102 -309.869586)
		(width 0.18288)
		(layer "In4.Cu")
		(net "M_G_CPU0_SA_DQ<4>")
	)
	(segment
		(start 429.662844 -311.189624)
		(end 429.479964 -311.372504)
		(width 0.18288)
		(layer "In4.Cu")
		(net "M_G_CPU0_SA_DQ<4>")
	)
	(segment
		(start 414.620964 -310.143144)
		(end 414.39465 -310.143144)
		(width 0.18288)
		(layer "In4.Cu")
		(net "M_G_CPU0_SA_DQ<4>")
	)
	(segment
		(start 431.422302 -310.779922)
		(end 429.845724 -310.779922)
		(width 0.18288)
		(layer "In4.Cu")
		(net "M_G_CPU0_SA_DQ<4>")
	)
	(segment
		(start 410.418026 -308.89067)
		(end 410.418026 -308.601618)
		(width 0.18288)
		(layer "In4.Cu")
		(net "M_G_CPU0_SA_DQ<4>")
	)
	(segment
		(start 382.907286 -273.94535)
		(end 382.902714 -273.942556)
		(width 0.088646)
		(layer "In4.Cu")
		(net "M_G_CPU0_SA_DQ<4>")
	)
	(segment
		(start 381.962914 -273.942556)
		(end 381.957072 -273.939254)
		(width 0.088646)
		(layer "In4.Cu")
		(net "M_G_CPU0_SA_DQ<4>")
	)
	(segment
		(start 415.143696 -310.665876)
		(end 414.620964 -310.143144)
		(width 0.18288)
		(layer "In4.Cu")
		(net "M_G_CPU0_SA_DQ<4>")
	)
	(segment
		(start 429.479964 -311.372504)
		(end 429.152304 -311.372504)
		(width 0.18288)
		(layer "In4.Cu")
		(net "M_G_CPU0_SA_DQ<4>")
	)
	(segment
		(start 416.677094 -311.421526)
		(end 415.921444 -310.665876)
		(width 0.18288)
		(layer "In4.Cu")
		(net "M_G_CPU0_SA_DQ<4>")
	)
	(arc
		(start 384.029712 -274.266914)
		(mid 383.982033 -274.084014)
		(end 383.85115 -273.947636)
		(width 0.088646)
		(layer "In4.Cu")
		(net "M_G_CPU0_SA_DQ<4>")
	)
	(arc
		(start 386.348478 -276.445726)
		(mid 386.267821 -276.420853)
		(end 386.19176 -276.384258)
		(width 0.088646)
		(layer "In4.Cu")
		(net "M_G_CPU0_SA_DQ<4>")
	)
	(arc
		(start 384.312414 -274.756626)
		(mid 384.108933 -274.555822)
		(end 384.029712 -274.281138)
		(width 0.088646)
		(layer "In4.Cu")
		(net "M_G_CPU0_SA_DQ<4>")
	)
	(arc
		(start 383.842514 -273.942556)
		(mid 383.655206 -273.892413)
		(end 383.467864 -273.942556)
		(width 0.088646)
		(layer "In4.Cu")
		(net "M_G_CPU0_SA_DQ<4>")
	)
	(arc
		(start 384.877818 -274.756626)
		(mid 384.603589 -274.832551)
		(end 384.327146 -274.765262)
		(width 0.088646)
		(layer "In4.Cu")
		(net "M_G_CPU0_SA_DQ<4>")
	)
	(arc
		(start 386.19176 -276.384258)
		(mid 385.987425 -276.181653)
		(end 385.909312 -275.904706)
		(width 0.088646)
		(layer "In4.Cu")
		(net "M_G_CPU0_SA_DQ<4>")
	)
	(arc
		(start 380.270512 -274.447762)
		(mid 380.251296 -274.471129)
		(end 380.230634 -274.493228)
		(width 0.088646)
		(layer "In4.Cu")
		(net "M_G_CPU0_SA_DQ<4>")
	)
	(arc
		(start 382.896872 -273.939254)
		(mid 382.712017 -273.892304)
		(end 382.528064 -273.942556)
		(width 0.088646)
		(layer "In4.Cu")
		(net "M_G_CPU0_SA_DQ<4>")
	)
	(arc
		(start 382.528064 -273.942556)
		(mid 382.24889 -274.018321)
		(end 381.968756 -273.946112)
		(width 0.088646)
		(layer "In4.Cu")
		(net "M_G_CPU0_SA_DQ<4>")
	)
	(arc
		(start 380.078742 -274.594066)
		(mid 379.893357 -274.641704)
		(end 379.708664 -274.591526)
		(width 0.088646)
		(layer "In4.Cu")
		(net "M_G_CPU0_SA_DQ<4>")
	)
	(arc
		(start 381.588264 -273.942556)
		(mid 381.30909 -274.018321)
		(end 381.028956 -273.946112)
		(width 0.088646)
		(layer "In4.Cu")
		(net "M_G_CPU0_SA_DQ<4>")
	)
	(arc
		(start 385.909312 -275.8948)
		(mid 385.861633 -275.7119)
		(end 385.73075 -275.575522)
		(width 0.088646)
		(layer "In4.Cu")
		(net "M_G_CPU0_SA_DQ<4>")
	)
	(arc
		(start 381.017272 -273.939254)
		(mid 380.832417 -273.892304)
		(end 380.648464 -273.942556)
		(width 0.088646)
		(layer "In4.Cu")
		(net "M_G_CPU0_SA_DQ<4>")
	)
	(arc
		(start 385.252214 -274.756626)
		(mid 385.065016 -274.706483)
		(end 384.877818 -274.756626)
		(width 0.088646)
		(layer "In4.Cu")
		(net "M_G_CPU0_SA_DQ<4>")
	)
	(arc
		(start 381.957072 -273.939254)
		(mid 381.772217 -273.892304)
		(end 381.588264 -273.942556)
		(width 0.088646)
		(layer "In4.Cu")
		(net "M_G_CPU0_SA_DQ<4>")
	)
	(arc
		(start 380.230634 -274.493228)
		(mid 380.192104 -274.52675)
		(end 380.149354 -274.554696)
		(width 0.088646)
		(layer "In4.Cu")
		(net "M_G_CPU0_SA_DQ<4>")
	)
	(arc
		(start 385.72186 -275.570442)
		(mid 385.519037 -275.370211)
		(end 385.439666 -275.096478)
		(width 0.088646)
		(layer "In4.Cu")
		(net "M_G_CPU0_SA_DQ<4>")
	)
	(arc
		(start 385.439666 -275.080984)
		(mid 385.391987 -274.898084)
		(end 385.261104 -274.761706)
		(width 0.088646)
		(layer "In4.Cu")
		(net "M_G_CPU0_SA_DQ<4>")
	)
	(arc
		(start 383.467864 -273.942556)
		(mid 383.18795 -274.018325)
		(end 382.907286 -273.94535)
		(width 0.088646)
		(layer "In4.Cu")
		(net "M_G_CPU0_SA_DQ<4>")
	)
	(arc
		(start 378.37237 -274.362418)
		(mid 378.200603 -274.291234)
		(end 378.016262 -274.266914)
		(width 0.088646)
		(layer "In4.Cu")
		(net "M_G_CPU0_SA_DQ<4>")
	)
	(arc
		(start 380.648464 -273.942556)
		(mid 380.574832 -273.997564)
		(end 380.51613 -274.068286)
		(width 0.088646)
		(layer "In4.Cu")
		(net "M_G_CPU0_SA_DQ<4>")
	)
	(arc
		(start 379.708664 -274.591526)
		(mid 379.430341 -274.515733)
		(end 379.15088 -274.587208)
		(width 0.088646)
		(layer "In4.Cu")
		(net "M_G_CPU0_SA_DQ<4>")
	)
	(arc
		(start 379.138942 -274.594066)
		(mid 378.953557 -274.641704)
		(end 378.768864 -274.591526)
		(width 0.088646)
		(layer "In4.Cu")
		(net "M_G_CPU0_SA_DQ<4>")
	)
	(segment
		(start 443.15888 -314.198762)
		(end 443.450726 -314.198762)
		(width 0.20066)
		(layer "F.Cu")
		(net "M_G_CPU0_SA_DQ<3>")
	)
	(segment
		(start 446.163954 -314.203842)
		(end 446.367916 -313.99988)
		(width 0.20066)
		(layer "F.Cu")
		(net "M_G_CPU0_SA_DQ<3>")
	)
	(segment
		(start 445.482726 -314.203842)
		(end 446.163954 -314.203842)
		(width 0.20066)
		(layer "F.Cu")
		(net "M_G_CPU0_SA_DQ<3>")
	)
	(segment
		(start 442.726826 -313.766708)
		(end 443.15888 -314.198762)
		(width 0.20066)
		(layer "F.Cu")
		(net "M_G_CPU0_SA_DQ<3>")
	)
	(segment
		(start 443.462664 -314.19165)
		(end 445.470534 -314.19165)
		(width 0.1016)
		(layer "F.Cu")
		(net "M_G_CPU0_SA_DQ<3>")
	)
	(segment
		(start 379.896116 -275.35886)
		(end 379.896116 -275.894546)
		(width 0.20066)
		(layer "F.Cu")
		(net "M_G_CPU0_SA_DQ<3>")
	)
	(segment
		(start 446.602104 -313.51474)
		(end 446.986152 -313.51474)
		(width 0.20066)
		(layer "F.Cu")
		(net "M_G_CPU0_SA_DQ<3>")
	)
	(segment
		(start 446.986152 -313.51474)
		(end 447.23812 -313.766708)
		(width 0.20066)
		(layer "F.Cu")
		(net "M_G_CPU0_SA_DQ<3>")
	)
	(segment
		(start 447.23812 -313.766708)
		(end 448.572382 -313.766708)
		(width 0.20066)
		(layer "F.Cu")
		(net "M_G_CPU0_SA_DQ<3>")
	)
	(segment
		(start 446.367916 -313.748928)
		(end 446.602104 -313.51474)
		(width 0.20066)
		(layer "F.Cu")
		(net "M_G_CPU0_SA_DQ<3>")
	)
	(segment
		(start 439.923682 -313.766708)
		(end 441.028582 -313.766708)
		(width 0.20066)
		(layer "F.Cu")
		(net "M_G_CPU0_SA_DQ<3>")
	)
	(segment
		(start 379.896116 -275.894546)
		(end 379.895862 -275.8948)
		(width 0.20066)
		(layer "F.Cu")
		(net "M_G_CPU0_SA_DQ<3>")
	)
	(segment
		(start 443.455552 -314.198762)
		(end 443.462664 -314.19165)
		(width 0.1016)
		(layer "F.Cu")
		(net "M_G_CPU0_SA_DQ<3>")
	)
	(segment
		(start 443.450726 -314.198762)
		(end 443.455552 -314.198762)
		(width 0.101854)
		(layer "F.Cu")
		(net "M_G_CPU0_SA_DQ<3>")
	)
	(segment
		(start 446.367916 -313.99988)
		(end 446.367916 -313.748928)
		(width 0.20066)
		(layer "F.Cu")
		(net "M_G_CPU0_SA_DQ<3>")
	)
	(segment
		(start 441.028582 -313.766708)
		(end 442.726826 -313.766708)
		(width 0.20066)
		(layer "F.Cu")
		(net "M_G_CPU0_SA_DQ<3>")
	)
	(segment
		(start 445.470534 -314.19165)
		(end 445.482726 -314.203842)
		(width 0.1016)
		(layer "F.Cu")
		(net "M_G_CPU0_SA_DQ<3>")
	)
	(segment
		(start 411.571694 -313.478926)
		(end 410.444442 -312.351674)
		(width 0.18288)
		(layer "In4.Cu")
		(net "M_G_CPU0_SA_DQ<3>")
	)
	(segment
		(start 426.289978 -315.142626)
		(end 425.540424 -315.89218)
		(width 0.18288)
		(layer "In4.Cu")
		(net "M_G_CPU0_SA_DQ<3>")
	)
	(segment
		(start 435.338728 -314.192412)
		(end 434.714142 -313.567826)
		(width 0.18288)
		(layer "In4.Cu")
		(net "M_G_CPU0_SA_DQ<3>")
	)
	(segment
		(start 404.694136 -310.11241)
		(end 402.531326 -307.9496)
		(width 0.18288)
		(layer "In4.Cu")
		(net "M_G_CPU0_SA_DQ<3>")
	)
	(segment
		(start 409.128214 -312.351674)
		(end 408.499818 -311.723278)
		(width 0.18288)
		(layer "In4.Cu")
		(net "M_G_CPU0_SA_DQ<3>")
	)
	(segment
		(start 415.272982 -314.329826)
		(end 414.701228 -313.758072)
		(width 0.18288)
		(layer "In4.Cu")
		(net "M_G_CPU0_SA_DQ<3>")
	)
	(segment
		(start 425.540424 -315.89218)
		(end 424.16984 -315.89218)
		(width 0.18288)
		(layer "In4.Cu")
		(net "M_G_CPU0_SA_DQ<3>")
	)
	(segment
		(start 427.205394 -315.142626)
		(end 426.289978 -315.142626)
		(width 0.18288)
		(layer "In4.Cu")
		(net "M_G_CPU0_SA_DQ<3>")
	)
	(segment
		(start 416.080194 -314.329826)
		(end 415.272982 -314.329826)
		(width 0.18288)
		(layer "In4.Cu")
		(net "M_G_CPU0_SA_DQ<3>")
	)
	(segment
		(start 407.641806 -311.723278)
		(end 406.030938 -310.11241)
		(width 0.18288)
		(layer "In4.Cu")
		(net "M_G_CPU0_SA_DQ<3>")
	)
	(segment
		(start 388.708646 -280.838656)
		(end 387.616954 -279.746964)
		(width 0.18288)
		(layer "In4.Cu")
		(net "M_G_CPU0_SA_DQ<3>")
	)
	(segment
		(start 386.555742 -279.371806)
		(end 385.934458 -278.750522)
		(width 0.088646)
		(layer "In4.Cu")
		(net "M_G_CPU0_SA_DQ<3>")
	)
	(segment
		(start 424.16984 -315.89218)
		(end 423.839894 -316.222126)
		(width 0.18288)
		(layer "In4.Cu")
		(net "M_G_CPU0_SA_DQ<3>")
	)
	(segment
		(start 437.718708 -314.469272)
		(end 437.441848 -314.192412)
		(width 0.18288)
		(layer "In4.Cu")
		(net "M_G_CPU0_SA_DQ<3>")
	)
	(segment
		(start 384.407664 -277.84679)
		(end 384.398774 -277.84171)
		(width 0.088646)
		(layer "In4.Cu")
		(net "M_G_CPU0_SA_DQ<3>")
	)
	(segment
		(start 421.440356 -316.742064)
		(end 419.179756 -316.742064)
		(width 0.18288)
		(layer "In4.Cu")
		(net "M_G_CPU0_SA_DQ<3>")
	)
	(segment
		(start 427.941994 -314.406026)
		(end 427.205394 -315.142626)
		(width 0.18288)
		(layer "In4.Cu")
		(net "M_G_CPU0_SA_DQ<3>")
	)
	(segment
		(start 431.472594 -313.567826)
		(end 430.634394 -314.406026)
		(width 0.18288)
		(layer "In4.Cu")
		(net "M_G_CPU0_SA_DQ<3>")
	)
	(segment
		(start 413.78124 -313.758072)
		(end 413.342582 -313.319414)
		(width 0.18288)
		(layer "In4.Cu")
		(net "M_G_CPU0_SA_DQ<3>")
	)
	(segment
		(start 382.528064 -276.219158)
		(end 382.513332 -276.210522)
		(width 0.088646)
		(layer "In4.Cu")
		(net "M_G_CPU0_SA_DQ<3>")
	)
	(segment
		(start 382.998218 -277.032974)
		(end 382.989328 -277.027894)
		(width 0.088646)
		(layer "In4.Cu")
		(net "M_G_CPU0_SA_DQ<3>")
	)
	(segment
		(start 382.53416 -276.222714)
		(end 382.528064 -276.219158)
		(width 0.088646)
		(layer "In4.Cu")
		(net "M_G_CPU0_SA_DQ<3>")
	)
	(segment
		(start 402.531326 -307.9496)
		(end 395.709394 -297.739816)
		(width 0.18288)
		(layer "In4.Cu")
		(net "M_G_CPU0_SA_DQ<3>")
	)
	(segment
		(start 410.444442 -312.351674)
		(end 409.128214 -312.351674)
		(width 0.18288)
		(layer "In4.Cu")
		(net "M_G_CPU0_SA_DQ<3>")
	)
	(segment
		(start 406.030938 -310.11241)
		(end 404.694136 -310.11241)
		(width 0.18288)
		(layer "In4.Cu")
		(net "M_G_CPU0_SA_DQ<3>")
	)
	(segment
		(start 423.839894 -316.222126)
		(end 421.960294 -316.222126)
		(width 0.18288)
		(layer "In4.Cu")
		(net "M_G_CPU0_SA_DQ<3>")
	)
	(segment
		(start 380.266448 -276.017482)
		(end 379.911864 -275.922486)
		(width 0.088646)
		(layer "In4.Cu")
		(net "M_G_CPU0_SA_DQ<3>")
	)
	(segment
		(start 413.342582 -313.319414)
		(end 412.671006 -313.319414)
		(width 0.18288)
		(layer "In4.Cu")
		(net "M_G_CPU0_SA_DQ<3>")
	)
	(segment
		(start 380.648464 -276.219158)
		(end 380.383034 -276.065996)
		(width 0.088646)
		(layer "In4.Cu")
		(net "M_G_CPU0_SA_DQ<3>")
	)
	(segment
		(start 379.911864 -275.922486)
		(end 379.895862 -275.8948)
		(width 0.088646)
		(layer "In4.Cu")
		(net "M_G_CPU0_SA_DQ<3>")
	)
	(segment
		(start 387.616954 -279.746964)
		(end 387.241796 -279.371806)
		(width 0.088646)
		(layer "In4.Cu")
		(net "M_G_CPU0_SA_DQ<3>")
	)
	(segment
		(start 408.499818 -311.723278)
		(end 407.641806 -311.723278)
		(width 0.18288)
		(layer "In4.Cu")
		(net "M_G_CPU0_SA_DQ<3>")
	)
	(segment
		(start 384.220212 -277.522432)
		(end 384.220212 -277.512526)
		(width 0.088646)
		(layer "In4.Cu")
		(net "M_G_CPU0_SA_DQ<3>")
	)
	(segment
		(start 414.701228 -313.758072)
		(end 413.78124 -313.758072)
		(width 0.18288)
		(layer "In4.Cu")
		(net "M_G_CPU0_SA_DQ<3>")
	)
	(segment
		(start 395.709394 -297.739816)
		(end 389.924544 -283.774134)
		(width 0.18288)
		(layer "In4.Cu")
		(net "M_G_CPU0_SA_DQ<3>")
	)
	(segment
		(start 430.634394 -314.406026)
		(end 427.941994 -314.406026)
		(width 0.18288)
		(layer "In4.Cu")
		(net "M_G_CPU0_SA_DQ<3>")
	)
	(segment
		(start 389.924544 -283.774134)
		(end 388.708646 -280.838656)
		(width 0.18288)
		(layer "In4.Cu")
		(net "M_G_CPU0_SA_DQ<3>")
	)
	(segment
		(start 387.241796 -279.371806)
		(end 386.555742 -279.371806)
		(width 0.088646)
		(layer "In4.Cu")
		(net "M_G_CPU0_SA_DQ<3>")
	)
	(segment
		(start 412.511494 -313.478926)
		(end 411.571694 -313.478926)
		(width 0.18288)
		(layer "In4.Cu")
		(net "M_G_CPU0_SA_DQ<3>")
	)
	(segment
		(start 421.960294 -316.222126)
		(end 421.440356 -316.742064)
		(width 0.18288)
		(layer "In4.Cu")
		(net "M_G_CPU0_SA_DQ<3>")
	)
	(segment
		(start 417.707318 -315.269626)
		(end 417.019994 -315.269626)
		(width 0.18288)
		(layer "In4.Cu")
		(net "M_G_CPU0_SA_DQ<3>")
	)
	(segment
		(start 417.019994 -315.269626)
		(end 416.080194 -314.329826)
		(width 0.18288)
		(layer "In4.Cu")
		(net "M_G_CPU0_SA_DQ<3>")
	)
	(segment
		(start 384.877564 -278.66086)
		(end 384.868674 -278.65578)
		(width 0.088646)
		(layer "In4.Cu")
		(net "M_G_CPU0_SA_DQ<3>")
	)
	(segment
		(start 439.221118 -314.469272)
		(end 437.718708 -314.469272)
		(width 0.18288)
		(layer "In4.Cu")
		(net "M_G_CPU0_SA_DQ<3>")
	)
	(segment
		(start 439.923682 -313.766708)
		(end 439.221118 -314.469272)
		(width 0.18288)
		(layer "In4.Cu")
		(net "M_G_CPU0_SA_DQ<3>")
	)
	(segment
		(start 384.690112 -278.336502)
		(end 384.690112 -278.31796)
		(width 0.088646)
		(layer "In4.Cu")
		(net "M_G_CPU0_SA_DQ<3>")
	)
	(segment
		(start 437.441848 -314.192412)
		(end 435.338728 -314.192412)
		(width 0.18288)
		(layer "In4.Cu")
		(net "M_G_CPU0_SA_DQ<3>")
	)
	(segment
		(start 381.588264 -276.219158)
		(end 381.573532 -276.210522)
		(width 0.088646)
		(layer "In4.Cu")
		(net "M_G_CPU0_SA_DQ<3>")
	)
	(segment
		(start 434.714142 -313.567826)
		(end 431.472594 -313.567826)
		(width 0.18288)
		(layer "In4.Cu")
		(net "M_G_CPU0_SA_DQ<3>")
	)
	(segment
		(start 383.383028 -277.026878)
		(end 383.372614 -277.032974)
		(width 0.088646)
		(layer "In4.Cu")
		(net "M_G_CPU0_SA_DQ<3>")
	)
	(segment
		(start 419.179756 -316.742064)
		(end 417.707318 -315.269626)
		(width 0.18288)
		(layer "In4.Cu")
		(net "M_G_CPU0_SA_DQ<3>")
	)
	(segment
		(start 412.671006 -313.319414)
		(end 412.511494 -313.478926)
		(width 0.18288)
		(layer "In4.Cu")
		(net "M_G_CPU0_SA_DQ<3>")
	)
	(arc
		(start 382.989328 -277.027894)
		(mid 382.858414 -276.891534)
		(end 382.810766 -276.708616)
		(width 0.088646)
		(layer "In4.Cu")
		(net "M_G_CPU0_SA_DQ<3>")
	)
	(arc
		(start 384.398774 -277.84171)
		(mid 384.26786 -277.70535)
		(end 384.220212 -277.522432)
		(width 0.088646)
		(layer "In4.Cu")
		(net "M_G_CPU0_SA_DQ<3>")
	)
	(arc
		(start 382.513332 -276.210522)
		(mid 382.236857 -276.143202)
		(end 381.96266 -276.219158)
		(width 0.088646)
		(layer "In4.Cu")
		(net "M_G_CPU0_SA_DQ<3>")
	)
	(arc
		(start 384.868674 -278.65578)
		(mid 384.73776 -278.51942)
		(end 384.690112 -278.336502)
		(width 0.088646)
		(layer "In4.Cu")
		(net "M_G_CPU0_SA_DQ<3>")
	)
	(arc
		(start 381.02286 -276.219158)
		(mid 380.835662 -276.269301)
		(end 380.648464 -276.219158)
		(width 0.088646)
		(layer "In4.Cu")
		(net "M_G_CPU0_SA_DQ<3>")
	)
	(arc
		(start 381.573532 -276.210522)
		(mid 381.297057 -276.143202)
		(end 381.02286 -276.219158)
		(width 0.088646)
		(layer "In4.Cu")
		(net "M_G_CPU0_SA_DQ<3>")
	)
	(arc
		(start 385.25196 -278.66086)
		(mid 385.064762 -278.711003)
		(end 384.877564 -278.66086)
		(width 0.088646)
		(layer "In4.Cu")
		(net "M_G_CPU0_SA_DQ<3>")
	)
	(arc
		(start 384.220212 -277.512526)
		(mid 384.142101 -277.235577)
		(end 383.937764 -277.032974)
		(width 0.088646)
		(layer "In4.Cu")
		(net "M_G_CPU0_SA_DQ<3>")
	)
	(arc
		(start 381.96266 -276.219158)
		(mid 381.775462 -276.269301)
		(end 381.588264 -276.219158)
		(width 0.088646)
		(layer "In4.Cu")
		(net "M_G_CPU0_SA_DQ<3>")
	)
	(arc
		(start 383.372614 -277.032974)
		(mid 383.185416 -277.083117)
		(end 382.998218 -277.032974)
		(width 0.088646)
		(layer "In4.Cu")
		(net "M_G_CPU0_SA_DQ<3>")
	)
	(arc
		(start 385.934458 -278.750522)
		(mid 385.878853 -278.701848)
		(end 385.817364 -278.66086)
		(width 0.088646)
		(layer "In4.Cu")
		(net "M_G_CPU0_SA_DQ<3>")
	)
	(arc
		(start 380.383034 -276.065996)
		(mid 380.326331 -276.037919)
		(end 380.266448 -276.017482)
		(width 0.088646)
		(layer "In4.Cu")
		(net "M_G_CPU0_SA_DQ<3>")
	)
	(arc
		(start 382.810766 -276.708616)
		(mid 382.736775 -276.42905)
		(end 382.53416 -276.222714)
		(width 0.088646)
		(layer "In4.Cu")
		(net "M_G_CPU0_SA_DQ<3>")
	)
	(arc
		(start 383.937764 -277.032974)
		(mid 383.661205 -276.957231)
		(end 383.383028 -277.026878)
		(width 0.088646)
		(layer "In4.Cu")
		(net "M_G_CPU0_SA_DQ<3>")
	)
	(arc
		(start 385.817364 -278.66086)
		(mid 385.534662 -278.585084)
		(end 385.25196 -278.66086)
		(width 0.088646)
		(layer "In4.Cu")
		(net "M_G_CPU0_SA_DQ<3>")
	)
	(arc
		(start 384.690112 -278.31796)
		(mid 384.60995 -278.045771)
		(end 384.407664 -277.84679)
		(width 0.088646)
		(layer "In4.Cu")
		(net "M_G_CPU0_SA_DQ<3>")
	)
	(segment
		(start 446.986152 -279.514808)
		(end 447.23812 -279.766776)
		(width 0.20066)
		(layer "F.Cu")
		(net "M_G_CPU0_SA_DQ<31>")
	)
	(segment
		(start 446.367916 -279.999948)
		(end 446.367916 -279.748996)
		(width 0.20066)
		(layer "F.Cu")
		(net "M_G_CPU0_SA_DQ<31>")
	)
	(segment
		(start 376.136916 -266.127992)
		(end 376.136662 -266.128246)
		(width 0.20066)
		(layer "F.Cu")
		(net "M_G_CPU0_SA_DQ<31>")
	)
	(segment
		(start 376.136916 -265.592306)
		(end 376.136916 -266.127992)
		(width 0.20066)
		(layer "F.Cu")
		(net "M_G_CPU0_SA_DQ<31>")
	)
	(segment
		(start 443.462664 -280.191718)
		(end 445.470534 -280.191718)
		(width 0.1016)
		(layer "F.Cu")
		(net "M_G_CPU0_SA_DQ<31>")
	)
	(segment
		(start 446.367916 -279.748996)
		(end 446.602104 -279.514808)
		(width 0.20066)
		(layer "F.Cu")
		(net "M_G_CPU0_SA_DQ<31>")
	)
	(segment
		(start 447.23812 -279.766776)
		(end 448.572382 -279.766776)
		(width 0.20066)
		(layer "F.Cu")
		(net "M_G_CPU0_SA_DQ<31>")
	)
	(segment
		(start 443.455552 -280.19883)
		(end 443.462664 -280.191718)
		(width 0.1016)
		(layer "F.Cu")
		(net "M_G_CPU0_SA_DQ<31>")
	)
	(segment
		(start 446.602104 -279.514808)
		(end 446.986152 -279.514808)
		(width 0.20066)
		(layer "F.Cu")
		(net "M_G_CPU0_SA_DQ<31>")
	)
	(segment
		(start 439.923682 -279.766776)
		(end 441.028582 -279.766776)
		(width 0.20066)
		(layer "F.Cu")
		(net "M_G_CPU0_SA_DQ<31>")
	)
	(segment
		(start 446.163954 -280.20391)
		(end 446.367916 -279.999948)
		(width 0.20066)
		(layer "F.Cu")
		(net "M_G_CPU0_SA_DQ<31>")
	)
	(segment
		(start 442.726826 -279.766776)
		(end 443.15888 -280.19883)
		(width 0.20066)
		(layer "F.Cu")
		(net "M_G_CPU0_SA_DQ<31>")
	)
	(segment
		(start 445.482726 -280.20391)
		(end 446.163954 -280.20391)
		(width 0.20066)
		(layer "F.Cu")
		(net "M_G_CPU0_SA_DQ<31>")
	)
	(segment
		(start 441.028582 -279.766776)
		(end 442.726826 -279.766776)
		(width 0.20066)
		(layer "F.Cu")
		(net "M_G_CPU0_SA_DQ<31>")
	)
	(segment
		(start 445.470534 -280.191718)
		(end 445.482726 -280.20391)
		(width 0.1016)
		(layer "F.Cu")
		(net "M_G_CPU0_SA_DQ<31>")
	)
	(segment
		(start 443.15888 -280.19883)
		(end 443.450726 -280.19883)
		(width 0.20066)
		(layer "F.Cu")
		(net "M_G_CPU0_SA_DQ<31>")
	)
	(segment
		(start 443.450726 -280.19883)
		(end 443.455552 -280.19883)
		(width 0.101854)
		(layer "F.Cu")
		(net "M_G_CPU0_SA_DQ<31>")
	)
	(segment
		(start 377.359164 -265.638788)
		(end 377.353322 -265.635232)
		(width 0.088646)
		(layer "In6.Cu")
		(net "M_G_CPU0_SA_DQ<31>")
	)
	(segment
		(start 438.897014 -279.125426)
		(end 438.736994 -279.285446)
		(width 0.18288)
		(layer "In6.Cu")
		(net "M_G_CPU0_SA_DQ<31>")
	)
	(segment
		(start 382.058164 -265.638788)
		(end 382.052322 -265.635232)
		(width 0.088646)
		(layer "In6.Cu")
		(net "M_G_CPU0_SA_DQ<31>")
	)
	(segment
		(start 390.32815 -265.46556)
		(end 388.535672 -265.46556)
		(width 0.18288)
		(layer "In6.Cu")
		(net "M_G_CPU0_SA_DQ<31>")
	)
	(segment
		(start 380.184406 -265.64209)
		(end 380.178564 -265.638788)
		(width 0.088646)
		(layer "In6.Cu")
		(net "M_G_CPU0_SA_DQ<31>")
	)
	(segment
		(start 392.937492 -265.984482)
		(end 390.32815 -265.46556)
		(width 0.18288)
		(layer "In6.Cu")
		(net "M_G_CPU0_SA_DQ<31>")
	)
	(segment
		(start 424.31716 -272.052796)
		(end 423.95521 -271.690846)
		(width 0.18288)
		(layer "In6.Cu")
		(net "M_G_CPU0_SA_DQ<31>")
	)
	(segment
		(start 431.187606 -278.675338)
		(end 427.733714 -278.675338)
		(width 0.18288)
		(layer "In6.Cu")
		(net "M_G_CPU0_SA_DQ<31>")
	)
	(segment
		(start 435.40807 -279.582626)
		(end 432.094894 -279.582626)
		(width 0.18288)
		(layer "In6.Cu")
		(net "M_G_CPU0_SA_DQ<31>")
	)
	(segment
		(start 388.535672 -265.46556)
		(end 388.244588 -265.46556)
		(width 0.088646)
		(layer "In6.Cu")
		(net "M_G_CPU0_SA_DQ<31>")
	)
	(segment
		(start 378.304806 -265.64209)
		(end 378.298964 -265.638788)
		(width 0.088646)
		(layer "In6.Cu")
		(net "M_G_CPU0_SA_DQ<31>")
	)
	(segment
		(start 378.298964 -265.638788)
		(end 378.293122 -265.635232)
		(width 0.088646)
		(layer "In6.Cu")
		(net "M_G_CPU0_SA_DQ<31>")
	)
	(segment
		(start 438.736994 -280.141426)
		(end 438.559194 -280.319226)
		(width 0.18288)
		(layer "In6.Cu")
		(net "M_G_CPU0_SA_DQ<31>")
	)
	(segment
		(start 381.124206 -265.64209)
		(end 381.118364 -265.638788)
		(width 0.088646)
		(layer "In6.Cu")
		(net "M_G_CPU0_SA_DQ<31>")
	)
	(segment
		(start 437.339994 -280.123392)
		(end 437.339994 -279.557226)
		(width 0.18288)
		(layer "In6.Cu")
		(net "M_G_CPU0_SA_DQ<31>")
	)
	(segment
		(start 382.064006 -265.64209)
		(end 382.058164 -265.638788)
		(width 0.088646)
		(layer "In6.Cu")
		(net "M_G_CPU0_SA_DQ<31>")
	)
	(segment
		(start 432.094894 -279.582626)
		(end 431.187606 -278.675338)
		(width 0.18288)
		(layer "In6.Cu")
		(net "M_G_CPU0_SA_DQ<31>")
	)
	(segment
		(start 426.599604 -277.342854)
		(end 425.19981 -275.94306)
		(width 0.18288)
		(layer "In6.Cu")
		(net "M_G_CPU0_SA_DQ<31>")
	)
	(segment
		(start 376.794014 -265.638788)
		(end 376.716036 -265.683746)
		(width 0.088646)
		(layer "In6.Cu")
		(net "M_G_CPU0_SA_DQ<31>")
	)
	(segment
		(start 379.244606 -265.64209)
		(end 379.238764 -265.638788)
		(width 0.088646)
		(layer "In6.Cu")
		(net "M_G_CPU0_SA_DQ<31>")
	)
	(segment
		(start 380.178564 -265.638788)
		(end 380.172722 -265.635232)
		(width 0.088646)
		(layer "In6.Cu")
		(net "M_G_CPU0_SA_DQ<31>")
	)
	(segment
		(start 437.12511 -279.342342)
		(end 435.648354 -279.342342)
		(width 0.18288)
		(layer "In6.Cu")
		(net "M_G_CPU0_SA_DQ<31>")
	)
	(segment
		(start 425.19981 -275.94306)
		(end 424.550586 -275.94306)
		(width 0.18288)
		(layer "In6.Cu")
		(net "M_G_CPU0_SA_DQ<31>")
	)
	(segment
		(start 438.559194 -280.319226)
		(end 437.535828 -280.319226)
		(width 0.18288)
		(layer "In6.Cu")
		(net "M_G_CPU0_SA_DQ<31>")
	)
	(segment
		(start 377.365006 -265.64209)
		(end 377.359164 -265.638788)
		(width 0.088646)
		(layer "In6.Cu")
		(net "M_G_CPU0_SA_DQ<31>")
	)
	(segment
		(start 387.146546 -265.629898)
		(end 387.131814 -265.638534)
		(width 0.088646)
		(layer "In6.Cu")
		(net "M_G_CPU0_SA_DQ<31>")
	)
	(segment
		(start 426.599604 -277.541228)
		(end 426.599604 -277.342854)
		(width 0.18288)
		(layer "In6.Cu")
		(net "M_G_CPU0_SA_DQ<31>")
	)
	(segment
		(start 379.238764 -265.638788)
		(end 379.232922 -265.635232)
		(width 0.088646)
		(layer "In6.Cu")
		(net "M_G_CPU0_SA_DQ<31>")
	)
	(segment
		(start 437.339994 -279.557226)
		(end 437.12511 -279.342342)
		(width 0.18288)
		(layer "In6.Cu")
		(net "M_G_CPU0_SA_DQ<31>")
	)
	(segment
		(start 439.923682 -279.766776)
		(end 439.282332 -279.125426)
		(width 0.18288)
		(layer "In6.Cu")
		(net "M_G_CPU0_SA_DQ<31>")
	)
	(segment
		(start 405.030686 -270.85671)
		(end 400.158458 -265.984482)
		(width 0.18288)
		(layer "In6.Cu")
		(net "M_G_CPU0_SA_DQ<31>")
	)
	(segment
		(start 382.998218 -265.638534)
		(end 382.992122 -265.635232)
		(width 0.088646)
		(layer "In6.Cu")
		(net "M_G_CPU0_SA_DQ<31>")
	)
	(segment
		(start 385.266946 -265.629898)
		(end 385.252214 -265.638534)
		(width 0.088646)
		(layer "In6.Cu")
		(net "M_G_CPU0_SA_DQ<31>")
	)
	(segment
		(start 384.327146 -265.629898)
		(end 384.312414 -265.638534)
		(width 0.088646)
		(layer "In6.Cu")
		(net "M_G_CPU0_SA_DQ<31>")
	)
	(segment
		(start 386.206746 -265.629898)
		(end 386.192014 -265.638534)
		(width 0.088646)
		(layer "In6.Cu")
		(net "M_G_CPU0_SA_DQ<31>")
	)
	(segment
		(start 423.95521 -271.690846)
		(end 418.75202 -271.690846)
		(width 0.18288)
		(layer "In6.Cu")
		(net "M_G_CPU0_SA_DQ<31>")
	)
	(segment
		(start 408.387296 -270.85671)
		(end 405.030686 -270.85671)
		(width 0.18288)
		(layer "In6.Cu")
		(net "M_G_CPU0_SA_DQ<31>")
	)
	(segment
		(start 439.282332 -279.125426)
		(end 438.897014 -279.125426)
		(width 0.18288)
		(layer "In6.Cu")
		(net "M_G_CPU0_SA_DQ<31>")
	)
	(segment
		(start 388.244588 -265.46556)
		(end 388.071614 -265.638534)
		(width 0.088646)
		(layer "In6.Cu")
		(net "M_G_CPU0_SA_DQ<31>")
	)
	(segment
		(start 418.75202 -271.690846)
		(end 417.74745 -270.686276)
		(width 0.18288)
		(layer "In6.Cu")
		(net "M_G_CPU0_SA_DQ<31>")
	)
	(segment
		(start 400.158458 -265.984482)
		(end 392.937492 -265.984482)
		(width 0.18288)
		(layer "In6.Cu")
		(net "M_G_CPU0_SA_DQ<31>")
	)
	(segment
		(start 376.13717 -266.127738)
		(end 376.136662 -266.128246)
		(width 0.088646)
		(layer "In6.Cu")
		(net "M_G_CPU0_SA_DQ<31>")
	)
	(segment
		(start 383.387346 -265.629898)
		(end 383.372614 -265.638534)
		(width 0.088646)
		(layer "In6.Cu")
		(net "M_G_CPU0_SA_DQ<31>")
	)
	(segment
		(start 409.015946 -270.22806)
		(end 408.387296 -270.85671)
		(width 0.18288)
		(layer "In6.Cu")
		(net "M_G_CPU0_SA_DQ<31>")
	)
	(segment
		(start 435.648354 -279.342342)
		(end 435.40807 -279.582626)
		(width 0.18288)
		(layer "In6.Cu")
		(net "M_G_CPU0_SA_DQ<31>")
	)
	(segment
		(start 427.733714 -278.675338)
		(end 426.599604 -277.541228)
		(width 0.18288)
		(layer "In6.Cu")
		(net "M_G_CPU0_SA_DQ<31>")
	)
	(segment
		(start 424.550586 -275.94306)
		(end 424.31716 -275.709634)
		(width 0.18288)
		(layer "In6.Cu")
		(net "M_G_CPU0_SA_DQ<31>")
	)
	(segment
		(start 438.736994 -279.285446)
		(end 438.736994 -280.141426)
		(width 0.18288)
		(layer "In6.Cu")
		(net "M_G_CPU0_SA_DQ<31>")
	)
	(segment
		(start 412.115508 -270.22806)
		(end 409.015946 -270.22806)
		(width 0.18288)
		(layer "In6.Cu")
		(net "M_G_CPU0_SA_DQ<31>")
	)
	(segment
		(start 424.31716 -275.709634)
		(end 424.31716 -272.052796)
		(width 0.18288)
		(layer "In6.Cu")
		(net "M_G_CPU0_SA_DQ<31>")
	)
	(segment
		(start 415.914586 -270.686276)
		(end 415.590228 -271.010634)
		(width 0.18288)
		(layer "In6.Cu")
		(net "M_G_CPU0_SA_DQ<31>")
	)
	(segment
		(start 417.74745 -270.686276)
		(end 415.914586 -270.686276)
		(width 0.18288)
		(layer "In6.Cu")
		(net "M_G_CPU0_SA_DQ<31>")
	)
	(segment
		(start 437.535828 -280.319226)
		(end 437.339994 -280.123392)
		(width 0.18288)
		(layer "In6.Cu")
		(net "M_G_CPU0_SA_DQ<31>")
	)
	(segment
		(start 415.590228 -271.010634)
		(end 412.898082 -271.010634)
		(width 0.18288)
		(layer "In6.Cu")
		(net "M_G_CPU0_SA_DQ<31>")
	)
	(segment
		(start 381.118364 -265.638788)
		(end 381.112522 -265.635232)
		(width 0.088646)
		(layer "In6.Cu")
		(net "M_G_CPU0_SA_DQ<31>")
	)
	(segment
		(start 412.898082 -271.010634)
		(end 412.115508 -270.22806)
		(width 0.18288)
		(layer "In6.Cu")
		(net "M_G_CPU0_SA_DQ<31>")
	)
	(arc
		(start 382.052322 -265.635232)
		(mid 381.772187 -265.562949)
		(end 381.493014 -265.638788)
		(width 0.088646)
		(layer "In6.Cu")
		(net "M_G_CPU0_SA_DQ<31>")
	)
	(arc
		(start 378.293122 -265.635232)
		(mid 378.012987 -265.562949)
		(end 377.733814 -265.638788)
		(width 0.088646)
		(layer "In6.Cu")
		(net "M_G_CPU0_SA_DQ<31>")
	)
	(arc
		(start 377.353322 -265.635232)
		(mid 377.073187 -265.562949)
		(end 376.794014 -265.638788)
		(width 0.088646)
		(layer "In6.Cu")
		(net "M_G_CPU0_SA_DQ<31>")
	)
	(arc
		(start 382.992122 -265.635232)
		(mid 382.711987 -265.562949)
		(end 382.432814 -265.638788)
		(width 0.088646)
		(layer "In6.Cu")
		(net "M_G_CPU0_SA_DQ<31>")
	)
	(arc
		(start 376.716036 -265.683746)
		(mid 376.41197 -265.886664)
		(end 376.13717 -266.127738)
		(width 0.088646)
		(layer "In6.Cu")
		(net "M_G_CPU0_SA_DQ<31>")
	)
	(arc
		(start 383.372614 -265.638534)
		(mid 383.185416 -265.688677)
		(end 382.998218 -265.638534)
		(width 0.088646)
		(layer "In6.Cu")
		(net "M_G_CPU0_SA_DQ<31>")
	)
	(arc
		(start 388.071614 -265.638534)
		(mid 387.884416 -265.688677)
		(end 387.697218 -265.638534)
		(width 0.088646)
		(layer "In6.Cu")
		(net "M_G_CPU0_SA_DQ<31>")
	)
	(arc
		(start 380.553214 -265.638788)
		(mid 380.36926 -265.688883)
		(end 380.184406 -265.64209)
		(width 0.088646)
		(layer "In6.Cu")
		(net "M_G_CPU0_SA_DQ<31>")
	)
	(arc
		(start 385.252214 -265.638534)
		(mid 385.065016 -265.688677)
		(end 384.877818 -265.638534)
		(width 0.088646)
		(layer "In6.Cu")
		(net "M_G_CPU0_SA_DQ<31>")
	)
	(arc
		(start 377.733814 -265.638788)
		(mid 377.54986 -265.688883)
		(end 377.365006 -265.64209)
		(width 0.088646)
		(layer "In6.Cu")
		(net "M_G_CPU0_SA_DQ<31>")
	)
	(arc
		(start 379.232922 -265.635232)
		(mid 378.952787 -265.562949)
		(end 378.673614 -265.638788)
		(width 0.088646)
		(layer "In6.Cu")
		(net "M_G_CPU0_SA_DQ<31>")
	)
	(arc
		(start 384.312414 -265.638534)
		(mid 384.125216 -265.688677)
		(end 383.938018 -265.638534)
		(width 0.088646)
		(layer "In6.Cu")
		(net "M_G_CPU0_SA_DQ<31>")
	)
	(arc
		(start 386.192014 -265.638534)
		(mid 386.004816 -265.688677)
		(end 385.817618 -265.638534)
		(width 0.088646)
		(layer "In6.Cu")
		(net "M_G_CPU0_SA_DQ<31>")
	)
	(arc
		(start 387.131814 -265.638534)
		(mid 386.944616 -265.688677)
		(end 386.757418 -265.638534)
		(width 0.088646)
		(layer "In6.Cu")
		(net "M_G_CPU0_SA_DQ<31>")
	)
	(arc
		(start 385.817618 -265.638534)
		(mid 385.543389 -265.562609)
		(end 385.266946 -265.629898)
		(width 0.088646)
		(layer "In6.Cu")
		(net "M_G_CPU0_SA_DQ<31>")
	)
	(arc
		(start 378.673614 -265.638788)
		(mid 378.48966 -265.688883)
		(end 378.304806 -265.64209)
		(width 0.088646)
		(layer "In6.Cu")
		(net "M_G_CPU0_SA_DQ<31>")
	)
	(arc
		(start 381.112522 -265.635232)
		(mid 380.832387 -265.562949)
		(end 380.553214 -265.638788)
		(width 0.088646)
		(layer "In6.Cu")
		(net "M_G_CPU0_SA_DQ<31>")
	)
	(arc
		(start 381.493014 -265.638788)
		(mid 381.30906 -265.688883)
		(end 381.124206 -265.64209)
		(width 0.088646)
		(layer "In6.Cu")
		(net "M_G_CPU0_SA_DQ<31>")
	)
	(arc
		(start 383.938018 -265.638534)
		(mid 383.663789 -265.562609)
		(end 383.387346 -265.629898)
		(width 0.088646)
		(layer "In6.Cu")
		(net "M_G_CPU0_SA_DQ<31>")
	)
	(arc
		(start 380.172722 -265.635232)
		(mid 379.892587 -265.562949)
		(end 379.613414 -265.638788)
		(width 0.088646)
		(layer "In6.Cu")
		(net "M_G_CPU0_SA_DQ<31>")
	)
	(arc
		(start 379.613414 -265.638788)
		(mid 379.42946 -265.688883)
		(end 379.244606 -265.64209)
		(width 0.088646)
		(layer "In6.Cu")
		(net "M_G_CPU0_SA_DQ<31>")
	)
	(arc
		(start 387.697218 -265.638534)
		(mid 387.422989 -265.562609)
		(end 387.146546 -265.629898)
		(width 0.088646)
		(layer "In6.Cu")
		(net "M_G_CPU0_SA_DQ<31>")
	)
	(arc
		(start 384.877818 -265.638534)
		(mid 384.603589 -265.562609)
		(end 384.327146 -265.629898)
		(width 0.088646)
		(layer "In6.Cu")
		(net "M_G_CPU0_SA_DQ<31>")
	)
	(arc
		(start 382.432814 -265.638788)
		(mid 382.24886 -265.688883)
		(end 382.064006 -265.64209)
		(width 0.088646)
		(layer "In6.Cu")
		(net "M_G_CPU0_SA_DQ<31>")
	)
	(arc
		(start 386.757418 -265.638534)
		(mid 386.483189 -265.562609)
		(end 386.206746 -265.629898)
		(width 0.088646)
		(layer "In6.Cu")
		(net "M_G_CPU0_SA_DQ<31>")
	)
	(segment
		(start 443.455552 -281.898852)
		(end 443.462664 -281.89174)
		(width 0.1016)
		(layer "F.Cu")
		(net "M_G_CPU0_SA_DQ<30>")
	)
	(segment
		(start 447.23812 -281.466798)
		(end 448.572382 -281.466798)
		(width 0.20066)
		(layer "F.Cu")
		(net "M_G_CPU0_SA_DQ<30>")
	)
	(segment
		(start 446.367916 -281.449018)
		(end 446.602104 -281.21483)
		(width 0.20066)
		(layer "F.Cu")
		(net "M_G_CPU0_SA_DQ<30>")
	)
	(segment
		(start 376.606562 -266.405868)
		(end 376.606562 -266.941554)
		(width 0.20066)
		(layer "F.Cu")
		(net "M_G_CPU0_SA_DQ<30>")
	)
	(segment
		(start 446.367916 -281.69997)
		(end 446.367916 -281.449018)
		(width 0.20066)
		(layer "F.Cu")
		(net "M_G_CPU0_SA_DQ<30>")
	)
	(segment
		(start 445.482726 -281.903932)
		(end 446.163954 -281.903932)
		(width 0.20066)
		(layer "F.Cu")
		(net "M_G_CPU0_SA_DQ<30>")
	)
	(segment
		(start 443.15888 -281.898852)
		(end 443.450726 -281.898852)
		(width 0.20066)
		(layer "F.Cu")
		(net "M_G_CPU0_SA_DQ<30>")
	)
	(segment
		(start 439.881772 -281.466798)
		(end 441.028582 -281.466798)
		(width 0.20066)
		(layer "F.Cu")
		(net "M_G_CPU0_SA_DQ<30>")
	)
	(segment
		(start 445.470534 -281.89174)
		(end 445.482726 -281.903932)
		(width 0.1016)
		(layer "F.Cu")
		(net "M_G_CPU0_SA_DQ<30>")
	)
	(segment
		(start 443.462664 -281.89174)
		(end 445.470534 -281.89174)
		(width 0.1016)
		(layer "F.Cu")
		(net "M_G_CPU0_SA_DQ<30>")
	)
	(segment
		(start 446.163954 -281.903932)
		(end 446.367916 -281.69997)
		(width 0.20066)
		(layer "F.Cu")
		(net "M_G_CPU0_SA_DQ<30>")
	)
	(segment
		(start 441.028582 -281.466798)
		(end 442.726826 -281.466798)
		(width 0.20066)
		(layer "F.Cu")
		(net "M_G_CPU0_SA_DQ<30>")
	)
	(segment
		(start 446.602104 -281.21483)
		(end 446.986152 -281.21483)
		(width 0.20066)
		(layer "F.Cu")
		(net "M_G_CPU0_SA_DQ<30>")
	)
	(segment
		(start 443.450726 -281.898852)
		(end 443.455552 -281.898852)
		(width 0.101854)
		(layer "F.Cu")
		(net "M_G_CPU0_SA_DQ<30>")
	)
	(segment
		(start 446.986152 -281.21483)
		(end 447.23812 -281.466798)
		(width 0.20066)
		(layer "F.Cu")
		(net "M_G_CPU0_SA_DQ<30>")
	)
	(segment
		(start 442.726826 -281.466798)
		(end 443.15888 -281.898852)
		(width 0.20066)
		(layer "F.Cu")
		(net "M_G_CPU0_SA_DQ<30>")
	)
	(segment
		(start 376.606562 -266.941554)
		(end 376.606816 -266.941808)
		(width 0.20066)
		(layer "F.Cu")
		(net "M_G_CPU0_SA_DQ<30>")
	)
	(segment
		(start 436.858664 -281.701748)
		(end 436.858664 -281.086306)
		(width 0.18288)
		(layer "In6.Cu")
		(net "M_G_CPU0_SA_DQ<30>")
	)
	(segment
		(start 412.955486 -272.659094)
		(end 412.720028 -272.423636)
		(width 0.18288)
		(layer "In6.Cu")
		(net "M_G_CPU0_SA_DQ<30>")
	)
	(segment
		(start 425.632372 -279.04821)
		(end 425.632372 -278.081232)
		(width 0.18288)
		(layer "In6.Cu")
		(net "M_G_CPU0_SA_DQ<30>")
	)
	(segment
		(start 429.707802 -280.263346)
		(end 429.707802 -279.973278)
		(width 0.18288)
		(layer "In6.Cu")
		(net "M_G_CPU0_SA_DQ<30>")
	)
	(segment
		(start 381.968756 -266.449048)
		(end 381.962914 -266.452604)
		(width 0.088646)
		(layer "In6.Cu")
		(net "M_G_CPU0_SA_DQ<30>")
	)
	(segment
		(start 436.675784 -280.903426)
		(end 436.24754 -280.903426)
		(width 0.18288)
		(layer "In6.Cu")
		(net "M_G_CPU0_SA_DQ<30>")
	)
	(segment
		(start 381.028956 -266.449048)
		(end 381.023114 -266.452604)
		(width 0.088646)
		(layer "In6.Cu")
		(net "M_G_CPU0_SA_DQ<30>")
	)
	(segment
		(start 421.630348 -273.392392)
		(end 420.364412 -273.392392)
		(width 0.18288)
		(layer "In6.Cu")
		(net "M_G_CPU0_SA_DQ<30>")
	)
	(segment
		(start 399.63344 -267.006832)
		(end 392.97229 -267.006832)
		(width 0.18288)
		(layer "In6.Cu")
		(net "M_G_CPU0_SA_DQ<30>")
	)
	(segment
		(start 383.467864 -266.45235)
		(end 383.453132 -266.443714)
		(width 0.088646)
		(layer "In6.Cu")
		(net "M_G_CPU0_SA_DQ<30>")
	)
	(segment
		(start 378.209556 -266.449048)
		(end 378.203714 -266.452604)
		(width 0.088646)
		(layer "In6.Cu")
		(net "M_G_CPU0_SA_DQ<30>")
	)
	(segment
		(start 429.707802 -279.973278)
		(end 429.524922 -279.790398)
		(width 0.18288)
		(layer "In6.Cu")
		(net "M_G_CPU0_SA_DQ<30>")
	)
	(segment
		(start 435.117494 -281.182826)
		(end 434.092858 -281.182826)
		(width 0.18288)
		(layer "In6.Cu")
		(net "M_G_CPU0_SA_DQ<30>")
	)
	(segment
		(start 415.806636 -272.659094)
		(end 412.955486 -272.659094)
		(width 0.18288)
		(layer "In6.Cu")
		(net "M_G_CPU0_SA_DQ<30>")
	)
	(segment
		(start 422.717468 -276.961092)
		(end 422.47566 -276.719284)
		(width 0.18288)
		(layer "In6.Cu")
		(net "M_G_CPU0_SA_DQ<30>")
	)
	(segment
		(start 437.041544 -281.884628)
		(end 436.858664 -281.701748)
		(width 0.18288)
		(layer "In6.Cu")
		(net "M_G_CPU0_SA_DQ<30>")
	)
	(segment
		(start 388.535672 -266.470892)
		(end 388.287768 -266.470892)
		(width 0.088646)
		(layer "In6.Cu")
		(net "M_G_CPU0_SA_DQ<30>")
	)
	(segment
		(start 382.90246 -266.45235)
		(end 382.896872 -266.455906)
		(width 0.088646)
		(layer "In6.Cu")
		(net "M_G_CPU0_SA_DQ<30>")
	)
	(segment
		(start 388.233412 -266.462764)
		(end 388.167372 -266.44219)
		(width 0.088646)
		(layer "In6.Cu")
		(net "M_G_CPU0_SA_DQ<30>")
	)
	(segment
		(start 423.60342 -276.961092)
		(end 422.717468 -276.961092)
		(width 0.18288)
		(layer "In6.Cu")
		(net "M_G_CPU0_SA_DQ<30>")
	)
	(segment
		(start 425.194476 -277.643336)
		(end 424.285664 -277.643336)
		(width 0.18288)
		(layer "In6.Cu")
		(net "M_G_CPU0_SA_DQ<30>")
	)
	(segment
		(start 427.863762 -280.446226)
		(end 427.446186 -280.02865)
		(width 0.18288)
		(layer "In6.Cu")
		(net "M_G_CPU0_SA_DQ<30>")
	)
	(segment
		(start 424.285664 -277.643336)
		(end 423.60342 -276.961092)
		(width 0.18288)
		(layer "In6.Cu")
		(net "M_G_CPU0_SA_DQ<30>")
	)
	(segment
		(start 418.93109 -273.639026)
		(end 417.639246 -272.347182)
		(width 0.18288)
		(layer "In6.Cu")
		(net "M_G_CPU0_SA_DQ<30>")
	)
	(segment
		(start 408.990546 -272.652744)
		(end 405.279352 -272.652744)
		(width 0.18288)
		(layer "In6.Cu")
		(net "M_G_CPU0_SA_DQ<30>")
	)
	(segment
		(start 438.686194 -281.375104)
		(end 438.686194 -281.081226)
		(width 0.18288)
		(layer "In6.Cu")
		(net "M_G_CPU0_SA_DQ<30>")
	)
	(segment
		(start 426.612812 -280.02865)
		(end 425.632372 -279.04821)
		(width 0.18288)
		(layer "In6.Cu")
		(net "M_G_CPU0_SA_DQ<30>")
	)
	(segment
		(start 420.117778 -273.639026)
		(end 418.93109 -273.639026)
		(width 0.18288)
		(layer "In6.Cu")
		(net "M_G_CPU0_SA_DQ<30>")
	)
	(segment
		(start 437.552084 -281.086306)
		(end 437.552084 -281.701748)
		(width 0.18288)
		(layer "In6.Cu")
		(net "M_G_CPU0_SA_DQ<30>")
	)
	(segment
		(start 433.909978 -280.999946)
		(end 433.909978 -280.822654)
		(width 0.18288)
		(layer "In6.Cu")
		(net "M_G_CPU0_SA_DQ<30>")
	)
	(segment
		(start 385.73202 -266.446254)
		(end 385.721606 -266.45235)
		(width 0.088646)
		(layer "In6.Cu")
		(net "M_G_CPU0_SA_DQ<30>")
	)
	(segment
		(start 380.089156 -266.449048)
		(end 380.083314 -266.452604)
		(width 0.088646)
		(layer "In6.Cu")
		(net "M_G_CPU0_SA_DQ<30>")
	)
	(segment
		(start 433.909978 -280.822654)
		(end 433.727098 -280.639774)
		(width 0.18288)
		(layer "In6.Cu")
		(net "M_G_CPU0_SA_DQ<30>")
	)
	(segment
		(start 405.279352 -272.652744)
		(end 399.63344 -267.006832)
		(width 0.18288)
		(layer "In6.Cu")
		(net "M_G_CPU0_SA_DQ<30>")
	)
	(segment
		(start 432.053238 -281.182826)
		(end 431.316638 -280.446226)
		(width 0.18288)
		(layer "In6.Cu")
		(net "M_G_CPU0_SA_DQ<30>")
	)
	(segment
		(start 417.639246 -272.347182)
		(end 416.118548 -272.347182)
		(width 0.18288)
		(layer "In6.Cu")
		(net "M_G_CPU0_SA_DQ<30>")
	)
	(segment
		(start 437.734964 -280.903426)
		(end 437.552084 -281.086306)
		(width 0.18288)
		(layer "In6.Cu")
		(net "M_G_CPU0_SA_DQ<30>")
	)
	(segment
		(start 438.777634 -281.466544)
		(end 438.686194 -281.375104)
		(width 0.18288)
		(layer "In6.Cu")
		(net "M_G_CPU0_SA_DQ<30>")
	)
	(segment
		(start 437.369204 -281.884628)
		(end 437.041544 -281.884628)
		(width 0.18288)
		(layer "In6.Cu")
		(net "M_G_CPU0_SA_DQ<30>")
	)
	(segment
		(start 416.118548 -272.347182)
		(end 415.806636 -272.659094)
		(width 0.18288)
		(layer "In6.Cu")
		(net "M_G_CPU0_SA_DQ<30>")
	)
	(segment
		(start 379.149356 -266.449048)
		(end 379.143514 -266.452604)
		(width 0.088646)
		(layer "In6.Cu")
		(net "M_G_CPU0_SA_DQ<30>")
	)
	(segment
		(start 433.399438 -280.639774)
		(end 433.216558 -280.822654)
		(width 0.18288)
		(layer "In6.Cu")
		(net "M_G_CPU0_SA_DQ<30>")
	)
	(segment
		(start 380.083314 -266.452604)
		(end 380.077472 -266.455906)
		(width 0.088646)
		(layer "In6.Cu")
		(net "M_G_CPU0_SA_DQ<30>")
	)
	(segment
		(start 429.014382 -280.263346)
		(end 428.831502 -280.446226)
		(width 0.18288)
		(layer "In6.Cu")
		(net "M_G_CPU0_SA_DQ<30>")
	)
	(segment
		(start 429.197262 -279.790398)
		(end 429.014382 -279.973278)
		(width 0.18288)
		(layer "In6.Cu")
		(net "M_G_CPU0_SA_DQ<30>")
	)
	(segment
		(start 378.203714 -266.452604)
		(end 378.197872 -266.455906)
		(width 0.088646)
		(layer "In6.Cu")
		(net "M_G_CPU0_SA_DQ<30>")
	)
	(segment
		(start 381.962914 -266.452604)
		(end 381.957072 -266.455906)
		(width 0.088646)
		(layer "In6.Cu")
		(net "M_G_CPU0_SA_DQ<30>")
	)
	(segment
		(start 433.033678 -281.182826)
		(end 432.053238 -281.182826)
		(width 0.18288)
		(layer "In6.Cu")
		(net "M_G_CPU0_SA_DQ<30>")
	)
	(segment
		(start 425.632372 -278.081232)
		(end 425.194476 -277.643336)
		(width 0.18288)
		(layer "In6.Cu")
		(net "M_G_CPU0_SA_DQ<30>")
	)
	(segment
		(start 436.858664 -281.086306)
		(end 436.675784 -280.903426)
		(width 0.18288)
		(layer "In6.Cu")
		(net "M_G_CPU0_SA_DQ<30>")
	)
	(segment
		(start 433.727098 -280.639774)
		(end 433.399438 -280.639774)
		(width 0.18288)
		(layer "In6.Cu")
		(net "M_G_CPU0_SA_DQ<30>")
	)
	(segment
		(start 422.47566 -274.237704)
		(end 421.630348 -273.392392)
		(width 0.18288)
		(layer "In6.Cu")
		(net "M_G_CPU0_SA_DQ<30>")
	)
	(segment
		(start 438.508394 -280.903426)
		(end 437.734964 -280.903426)
		(width 0.18288)
		(layer "In6.Cu")
		(net "M_G_CPU0_SA_DQ<30>")
	)
	(segment
		(start 379.143514 -266.452604)
		(end 379.137672 -266.455906)
		(width 0.088646)
		(layer "In6.Cu")
		(net "M_G_CPU0_SA_DQ<30>")
	)
	(segment
		(start 436.108602 -281.042364)
		(end 435.257956 -281.042364)
		(width 0.18288)
		(layer "In6.Cu")
		(net "M_G_CPU0_SA_DQ<30>")
	)
	(segment
		(start 429.524922 -279.790398)
		(end 429.197262 -279.790398)
		(width 0.18288)
		(layer "In6.Cu")
		(net "M_G_CPU0_SA_DQ<30>")
	)
	(segment
		(start 438.686194 -281.081226)
		(end 438.508394 -280.903426)
		(width 0.18288)
		(layer "In6.Cu")
		(net "M_G_CPU0_SA_DQ<30>")
	)
	(segment
		(start 434.092858 -281.182826)
		(end 433.909978 -280.999946)
		(width 0.18288)
		(layer "In6.Cu")
		(net "M_G_CPU0_SA_DQ<30>")
	)
	(segment
		(start 381.023114 -266.452604)
		(end 381.017272 -266.455906)
		(width 0.088646)
		(layer "In6.Cu")
		(net "M_G_CPU0_SA_DQ<30>")
	)
	(segment
		(start 429.890682 -280.446226)
		(end 429.707802 -280.263346)
		(width 0.18288)
		(layer "In6.Cu")
		(net "M_G_CPU0_SA_DQ<30>")
	)
	(segment
		(start 427.446186 -280.02865)
		(end 426.612812 -280.02865)
		(width 0.18288)
		(layer "In6.Cu")
		(net "M_G_CPU0_SA_DQ<30>")
	)
	(segment
		(start 433.216558 -280.999946)
		(end 433.033678 -281.182826)
		(width 0.18288)
		(layer "In6.Cu")
		(net "M_G_CPU0_SA_DQ<30>")
	)
	(segment
		(start 439.881772 -281.466798)
		(end 439.881518 -281.466544)
		(width 0.18288)
		(layer "In6.Cu")
		(net "M_G_CPU0_SA_DQ<30>")
	)
	(segment
		(start 428.831502 -280.446226)
		(end 427.863762 -280.446226)
		(width 0.18288)
		(layer "In6.Cu")
		(net "M_G_CPU0_SA_DQ<30>")
	)
	(segment
		(start 439.881518 -281.466544)
		(end 438.777634 -281.466544)
		(width 0.18288)
		(layer "In6.Cu")
		(net "M_G_CPU0_SA_DQ<30>")
	)
	(segment
		(start 435.257956 -281.042364)
		(end 435.117494 -281.182826)
		(width 0.18288)
		(layer "In6.Cu")
		(net "M_G_CPU0_SA_DQ<30>")
	)
	(segment
		(start 433.216558 -280.822654)
		(end 433.216558 -280.999946)
		(width 0.18288)
		(layer "In6.Cu")
		(net "M_G_CPU0_SA_DQ<30>")
	)
	(segment
		(start 436.24754 -280.903426)
		(end 436.108602 -281.042364)
		(width 0.18288)
		(layer "In6.Cu")
		(net "M_G_CPU0_SA_DQ<30>")
	)
	(segment
		(start 422.47566 -276.719284)
		(end 422.47566 -274.237704)
		(width 0.18288)
		(layer "In6.Cu")
		(net "M_G_CPU0_SA_DQ<30>")
	)
	(segment
		(start 392.97229 -267.006832)
		(end 390.277858 -266.470892)
		(width 0.18288)
		(layer "In6.Cu")
		(net "M_G_CPU0_SA_DQ<30>")
	)
	(segment
		(start 420.364412 -273.392392)
		(end 420.117778 -273.639026)
		(width 0.18288)
		(layer "In6.Cu")
		(net "M_G_CPU0_SA_DQ<30>")
	)
	(segment
		(start 386.671566 -266.446254)
		(end 386.661152 -266.45235)
		(width 0.088646)
		(layer "In6.Cu")
		(net "M_G_CPU0_SA_DQ<30>")
	)
	(segment
		(start 429.014382 -279.973278)
		(end 429.014382 -280.263346)
		(width 0.18288)
		(layer "In6.Cu")
		(net "M_G_CPU0_SA_DQ<30>")
	)
	(segment
		(start 431.316638 -280.446226)
		(end 429.890682 -280.446226)
		(width 0.18288)
		(layer "In6.Cu")
		(net "M_G_CPU0_SA_DQ<30>")
	)
	(segment
		(start 390.277858 -266.470892)
		(end 388.535672 -266.470892)
		(width 0.18288)
		(layer "In6.Cu")
		(net "M_G_CPU0_SA_DQ<30>")
	)
	(segment
		(start 409.219654 -272.423636)
		(end 408.990546 -272.652744)
		(width 0.18288)
		(layer "In6.Cu")
		(net "M_G_CPU0_SA_DQ<30>")
	)
	(segment
		(start 437.552084 -281.701748)
		(end 437.369204 -281.884628)
		(width 0.18288)
		(layer "In6.Cu")
		(net "M_G_CPU0_SA_DQ<30>")
	)
	(segment
		(start 412.720028 -272.423636)
		(end 409.219654 -272.423636)
		(width 0.18288)
		(layer "In6.Cu")
		(net "M_G_CPU0_SA_DQ<30>")
	)
	(segment
		(start 384.792474 -266.446254)
		(end 384.78206 -266.45235)
		(width 0.088646)
		(layer "In6.Cu")
		(net "M_G_CPU0_SA_DQ<30>")
	)
	(segment
		(start 377.269756 -266.449048)
		(end 377.220734 -266.476734)
		(width 0.088646)
		(layer "In6.Cu")
		(net "M_G_CPU0_SA_DQ<30>")
	)
	(arc
		(start 378.197872 -266.455906)
		(mid 378.013017 -266.502856)
		(end 377.829064 -266.452604)
		(width 0.088646)
		(layer "In6.Cu")
		(net "M_G_CPU0_SA_DQ<30>")
	)
	(arc
		(start 378.768864 -266.452604)
		(mid 378.48969 -266.376805)
		(end 378.209556 -266.449048)
		(width 0.088646)
		(layer "In6.Cu")
		(net "M_G_CPU0_SA_DQ<30>")
	)
	(arc
		(start 385.721606 -266.45235)
		(mid 385.534408 -266.502527)
		(end 385.34721 -266.45235)
		(width 0.088646)
		(layer "In6.Cu")
		(net "M_G_CPU0_SA_DQ<30>")
	)
	(arc
		(start 382.528064 -266.452604)
		(mid 382.24889 -266.376805)
		(end 381.968756 -266.449048)
		(width 0.088646)
		(layer "In6.Cu")
		(net "M_G_CPU0_SA_DQ<30>")
	)
	(arc
		(start 388.167372 -266.44219)
		(mid 388.125236 -266.428233)
		(end 388.083552 -266.41298)
		(width 0.088646)
		(layer "In6.Cu")
		(net "M_G_CPU0_SA_DQ<30>")
	)
	(arc
		(start 387.647942 -266.427458)
		(mid 387.413246 -266.478519)
		(end 387.17855 -266.427458)
		(width 0.088646)
		(layer "In6.Cu")
		(net "M_G_CPU0_SA_DQ<30>")
	)
	(arc
		(start 380.648464 -266.452604)
		(mid 380.36929 -266.376805)
		(end 380.089156 -266.449048)
		(width 0.088646)
		(layer "In6.Cu")
		(net "M_G_CPU0_SA_DQ<30>")
	)
	(arc
		(start 379.137672 -266.455906)
		(mid 378.952817 -266.502856)
		(end 378.768864 -266.452604)
		(width 0.088646)
		(layer "In6.Cu")
		(net "M_G_CPU0_SA_DQ<30>")
	)
	(arc
		(start 382.896872 -266.455906)
		(mid 382.712017 -266.502856)
		(end 382.528064 -266.452604)
		(width 0.088646)
		(layer "In6.Cu")
		(net "M_G_CPU0_SA_DQ<30>")
	)
	(arc
		(start 383.453132 -266.443714)
		(mid 383.176657 -266.376394)
		(end 382.90246 -266.45235)
		(width 0.088646)
		(layer "In6.Cu")
		(net "M_G_CPU0_SA_DQ<30>")
	)
	(arc
		(start 388.083552 -266.41298)
		(mid 387.864302 -266.376578)
		(end 387.647942 -266.427458)
		(width 0.088646)
		(layer "In6.Cu")
		(net "M_G_CPU0_SA_DQ<30>")
	)
	(arc
		(start 377.220734 -266.476734)
		(mid 376.898148 -266.688643)
		(end 376.606816 -266.941808)
		(width 0.088646)
		(layer "In6.Cu")
		(net "M_G_CPU0_SA_DQ<30>")
	)
	(arc
		(start 381.588264 -266.452604)
		(mid 381.30909 -266.376805)
		(end 381.028956 -266.449048)
		(width 0.088646)
		(layer "In6.Cu")
		(net "M_G_CPU0_SA_DQ<30>")
	)
	(arc
		(start 384.407664 -266.45235)
		(mid 384.124962 -266.376574)
		(end 383.84226 -266.45235)
		(width 0.088646)
		(layer "In6.Cu")
		(net "M_G_CPU0_SA_DQ<30>")
	)
	(arc
		(start 377.829064 -266.452604)
		(mid 377.54989 -266.376805)
		(end 377.269756 -266.449048)
		(width 0.088646)
		(layer "In6.Cu")
		(net "M_G_CPU0_SA_DQ<30>")
	)
	(arc
		(start 386.661152 -266.45235)
		(mid 386.473954 -266.502527)
		(end 386.286756 -266.45235)
		(width 0.088646)
		(layer "In6.Cu")
		(net "M_G_CPU0_SA_DQ<30>")
	)
	(arc
		(start 379.708664 -266.452604)
		(mid 379.42949 -266.376805)
		(end 379.149356 -266.449048)
		(width 0.088646)
		(layer "In6.Cu")
		(net "M_G_CPU0_SA_DQ<30>")
	)
	(arc
		(start 385.34721 -266.45235)
		(mid 385.070651 -266.376607)
		(end 384.792474 -266.446254)
		(width 0.088646)
		(layer "In6.Cu")
		(net "M_G_CPU0_SA_DQ<30>")
	)
	(arc
		(start 383.84226 -266.45235)
		(mid 383.655062 -266.502527)
		(end 383.467864 -266.45235)
		(width 0.088646)
		(layer "In6.Cu")
		(net "M_G_CPU0_SA_DQ<30>")
	)
	(arc
		(start 388.287768 -266.470892)
		(mid 388.260287 -266.46886)
		(end 388.233412 -266.462764)
		(width 0.088646)
		(layer "In6.Cu")
		(net "M_G_CPU0_SA_DQ<30>")
	)
	(arc
		(start 381.017272 -266.455906)
		(mid 380.832417 -266.502856)
		(end 380.648464 -266.452604)
		(width 0.088646)
		(layer "In6.Cu")
		(net "M_G_CPU0_SA_DQ<30>")
	)
	(arc
		(start 381.957072 -266.455906)
		(mid 381.772217 -266.502856)
		(end 381.588264 -266.452604)
		(width 0.088646)
		(layer "In6.Cu")
		(net "M_G_CPU0_SA_DQ<30>")
	)
	(arc
		(start 386.286756 -266.45235)
		(mid 386.010197 -266.376607)
		(end 385.73202 -266.446254)
		(width 0.088646)
		(layer "In6.Cu")
		(net "M_G_CPU0_SA_DQ<30>")
	)
	(arc
		(start 384.78206 -266.45235)
		(mid 384.594862 -266.502527)
		(end 384.407664 -266.45235)
		(width 0.088646)
		(layer "In6.Cu")
		(net "M_G_CPU0_SA_DQ<30>")
	)
	(arc
		(start 387.17855 -266.427458)
		(mid 386.922841 -266.376833)
		(end 386.671566 -266.446254)
		(width 0.088646)
		(layer "In6.Cu")
		(net "M_G_CPU0_SA_DQ<30>")
	)
	(arc
		(start 380.077472 -266.455906)
		(mid 379.892617 -266.502856)
		(end 379.708664 -266.452604)
		(width 0.088646)
		(layer "In6.Cu")
		(net "M_G_CPU0_SA_DQ<30>")
	)
	(segment
		(start 446.367916 -315.699902)
		(end 446.367916 -315.44895)
		(width 0.20066)
		(layer "F.Cu")
		(net "M_G_CPU0_SA_DQ<2>")
	)
	(segment
		(start 447.23812 -315.46673)
		(end 448.572382 -315.46673)
		(width 0.20066)
		(layer "F.Cu")
		(net "M_G_CPU0_SA_DQ<2>")
	)
	(segment
		(start 446.602104 -315.214762)
		(end 446.986152 -315.214762)
		(width 0.20066)
		(layer "F.Cu")
		(net "M_G_CPU0_SA_DQ<2>")
	)
	(segment
		(start 443.462664 -315.891672)
		(end 445.470534 -315.891672)
		(width 0.1016)
		(layer "F.Cu")
		(net "M_G_CPU0_SA_DQ<2>")
	)
	(segment
		(start 439.923682 -315.46673)
		(end 441.028582 -315.46673)
		(width 0.20066)
		(layer "F.Cu")
		(net "M_G_CPU0_SA_DQ<2>")
	)
	(segment
		(start 445.470534 -315.891672)
		(end 445.482726 -315.903864)
		(width 0.1016)
		(layer "F.Cu")
		(net "M_G_CPU0_SA_DQ<2>")
	)
	(segment
		(start 443.15888 -315.898784)
		(end 443.450726 -315.898784)
		(width 0.20066)
		(layer "F.Cu")
		(net "M_G_CPU0_SA_DQ<2>")
	)
	(segment
		(start 443.455552 -315.898784)
		(end 443.462664 -315.891672)
		(width 0.1016)
		(layer "F.Cu")
		(net "M_G_CPU0_SA_DQ<2>")
	)
	(segment
		(start 441.028582 -315.46673)
		(end 442.726826 -315.46673)
		(width 0.20066)
		(layer "F.Cu")
		(net "M_G_CPU0_SA_DQ<2>")
	)
	(segment
		(start 445.482726 -315.903864)
		(end 446.163954 -315.903864)
		(width 0.20066)
		(layer "F.Cu")
		(net "M_G_CPU0_SA_DQ<2>")
	)
	(segment
		(start 443.450726 -315.898784)
		(end 443.455552 -315.898784)
		(width 0.101854)
		(layer "F.Cu")
		(net "M_G_CPU0_SA_DQ<2>")
	)
	(segment
		(start 446.367916 -315.44895)
		(end 446.602104 -315.214762)
		(width 0.20066)
		(layer "F.Cu")
		(net "M_G_CPU0_SA_DQ<2>")
	)
	(segment
		(start 442.726826 -315.46673)
		(end 443.15888 -315.898784)
		(width 0.20066)
		(layer "F.Cu")
		(net "M_G_CPU0_SA_DQ<2>")
	)
	(segment
		(start 379.425962 -276.172676)
		(end 379.426216 -276.708616)
		(width 0.20066)
		(layer "F.Cu")
		(net "M_G_CPU0_SA_DQ<2>")
	)
	(segment
		(start 446.986152 -315.214762)
		(end 447.23812 -315.46673)
		(width 0.20066)
		(layer "F.Cu")
		(net "M_G_CPU0_SA_DQ<2>")
	)
	(segment
		(start 446.163954 -315.903864)
		(end 446.367916 -315.699902)
		(width 0.20066)
		(layer "F.Cu")
		(net "M_G_CPU0_SA_DQ<2>")
	)
	(segment
		(start 417.603432 -316.74308)
		(end 416.867848 -316.74308)
		(width 0.18288)
		(layer "In4.Cu")
		(net "M_G_CPU0_SA_DQ<2>")
	)
	(segment
		(start 430.093374 -316.049406)
		(end 428.356014 -317.786766)
		(width 0.18288)
		(layer "In4.Cu")
		(net "M_G_CPU0_SA_DQ<2>")
	)
	(segment
		(start 428.356014 -317.786766)
		(end 427.958758 -317.786766)
		(width 0.18288)
		(layer "In4.Cu")
		(net "M_G_CPU0_SA_DQ<2>")
	)
	(segment
		(start 382.528064 -277.84679)
		(end 382.519174 -277.84171)
		(width 0.088646)
		(layer "In4.Cu")
		(net "M_G_CPU0_SA_DQ<2>")
	)
	(segment
		(start 430.591214 -316.049406)
		(end 430.093374 -316.049406)
		(width 0.18288)
		(layer "In4.Cu")
		(net "M_G_CPU0_SA_DQ<2>")
	)
	(segment
		(start 427.958758 -317.786766)
		(end 427.764194 -317.592202)
		(width 0.18288)
		(layer "In4.Cu")
		(net "M_G_CPU0_SA_DQ<2>")
	)
	(segment
		(start 427.764194 -317.592202)
		(end 422.139618 -317.592202)
		(width 0.18288)
		(layer "In4.Cu")
		(net "M_G_CPU0_SA_DQ<2>")
	)
	(segment
		(start 386.88772 -279.99055)
		(end 386.128768 -279.99055)
		(width 0.088646)
		(layer "In4.Cu")
		(net "M_G_CPU0_SA_DQ<2>")
	)
	(segment
		(start 415.165286 -316.006226)
		(end 414.1978 -315.03874)
		(width 0.18288)
		(layer "In4.Cu")
		(net "M_G_CPU0_SA_DQ<2>")
	)
	(segment
		(start 382.340612 -277.522432)
		(end 382.340612 -277.506938)
		(width 0.088646)
		(layer "In4.Cu")
		(net "M_G_CPU0_SA_DQ<2>")
	)
	(segment
		(start 409.206954 -314.101226)
		(end 408.219656 -313.113928)
		(width 0.18288)
		(layer "In4.Cu")
		(net "M_G_CPU0_SA_DQ<2>")
	)
	(segment
		(start 439.923682 -315.46673)
		(end 438.968388 -315.891418)
		(width 0.18288)
		(layer "In4.Cu")
		(net "M_G_CPU0_SA_DQ<2>")
	)
	(segment
		(start 379.239018 -277.032974)
		(end 379.230128 -277.027894)
		(width 0.088646)
		(layer "In4.Cu")
		(net "M_G_CPU0_SA_DQ<2>")
	)
	(segment
		(start 383.467864 -279.474676)
		(end 383.458974 -279.469596)
		(width 0.088646)
		(layer "In4.Cu")
		(net "M_G_CPU0_SA_DQ<2>")
	)
	(segment
		(start 383.280412 -279.150318)
		(end 383.280412 -279.140412)
		(width 0.088646)
		(layer "In4.Cu")
		(net "M_G_CPU0_SA_DQ<2>")
	)
	(segment
		(start 382.810512 -278.336502)
		(end 382.810512 -278.31796)
		(width 0.088646)
		(layer "In4.Cu")
		(net "M_G_CPU0_SA_DQ<2>")
	)
	(segment
		(start 411.45714 -315.03874)
		(end 410.519626 -314.101226)
		(width 0.18288)
		(layer "In4.Cu")
		(net "M_G_CPU0_SA_DQ<2>")
	)
	(segment
		(start 382.997964 -278.66086)
		(end 382.989074 -278.65578)
		(width 0.088646)
		(layer "In4.Cu")
		(net "M_G_CPU0_SA_DQ<2>")
	)
	(segment
		(start 394.837412 -298.263564)
		(end 389.111744 -284.441392)
		(width 0.18288)
		(layer "In4.Cu")
		(net "M_G_CPU0_SA_DQ<2>")
	)
	(segment
		(start 416.130994 -316.006226)
		(end 415.165286 -316.006226)
		(width 0.18288)
		(layer "In4.Cu")
		(net "M_G_CPU0_SA_DQ<2>")
	)
	(segment
		(start 422.139618 -317.592202)
		(end 421.490394 -318.241426)
		(width 0.18288)
		(layer "In4.Cu")
		(net "M_G_CPU0_SA_DQ<2>")
	)
	(segment
		(start 379.056138 -276.76602)
		(end 379.113542 -276.708616)
		(width 0.088646)
		(layer "In4.Cu")
		(net "M_G_CPU0_SA_DQ<2>")
	)
	(segment
		(start 434.126386 -315.891418)
		(end 433.453794 -315.218826)
		(width 0.18288)
		(layer "In4.Cu")
		(net "M_G_CPU0_SA_DQ<2>")
	)
	(segment
		(start 405.1427 -312.021474)
		(end 401.789646 -308.66842)
		(width 0.18288)
		(layer "In4.Cu")
		(net "M_G_CPU0_SA_DQ<2>")
	)
	(segment
		(start 386.128768 -279.99055)
		(end 385.663694 -279.525476)
		(width 0.088646)
		(layer "In4.Cu")
		(net "M_G_CPU0_SA_DQ<2>")
	)
	(segment
		(start 438.968388 -315.891418)
		(end 434.126386 -315.891418)
		(width 0.18288)
		(layer "In4.Cu")
		(net "M_G_CPU0_SA_DQ<2>")
	)
	(segment
		(start 379.113542 -276.708616)
		(end 379.426216 -276.708616)
		(width 0.088646)
		(layer "In4.Cu")
		(net "M_G_CPU0_SA_DQ<2>")
	)
	(segment
		(start 401.789646 -308.66842)
		(end 394.837412 -298.263564)
		(width 0.18288)
		(layer "In4.Cu")
		(net "M_G_CPU0_SA_DQ<2>")
	)
	(segment
		(start 388.142988 -281.245818)
		(end 387.613398 -280.716228)
		(width 0.18288)
		(layer "In4.Cu")
		(net "M_G_CPU0_SA_DQ<2>")
	)
	(segment
		(start 387.613398 -280.716228)
		(end 386.88772 -279.99055)
		(width 0.088646)
		(layer "In4.Cu")
		(net "M_G_CPU0_SA_DQ<2>")
	)
	(segment
		(start 433.453794 -315.218826)
		(end 431.421794 -315.218826)
		(width 0.18288)
		(layer "In4.Cu")
		(net "M_G_CPU0_SA_DQ<2>")
	)
	(segment
		(start 414.1978 -315.03874)
		(end 411.45714 -315.03874)
		(width 0.18288)
		(layer "In4.Cu")
		(net "M_G_CPU0_SA_DQ<2>")
	)
	(segment
		(start 421.490394 -318.241426)
		(end 419.101778 -318.241426)
		(width 0.18288)
		(layer "In4.Cu")
		(net "M_G_CPU0_SA_DQ<2>")
	)
	(segment
		(start 380.563374 -277.026878)
		(end 380.55296 -277.032974)
		(width 0.088646)
		(layer "In4.Cu")
		(net "M_G_CPU0_SA_DQ<2>")
	)
	(segment
		(start 381.507746 -277.024338)
		(end 381.493014 -277.032974)
		(width 0.088646)
		(layer "In4.Cu")
		(net "M_G_CPU0_SA_DQ<2>")
	)
	(segment
		(start 416.867848 -316.74308)
		(end 416.130994 -316.006226)
		(width 0.18288)
		(layer "In4.Cu")
		(net "M_G_CPU0_SA_DQ<2>")
	)
	(segment
		(start 389.111744 -283.584142)
		(end 388.142988 -281.245818)
		(width 0.18288)
		(layer "In4.Cu")
		(net "M_G_CPU0_SA_DQ<2>")
	)
	(segment
		(start 389.111744 -284.441392)
		(end 389.111744 -283.584142)
		(width 0.18288)
		(layer "In4.Cu")
		(net "M_G_CPU0_SA_DQ<2>")
	)
	(segment
		(start 419.101778 -318.241426)
		(end 417.603432 -316.74308)
		(width 0.18288)
		(layer "In4.Cu")
		(net "M_G_CPU0_SA_DQ<2>")
	)
	(segment
		(start 379.623828 -277.026878)
		(end 379.613414 -277.032974)
		(width 0.088646)
		(layer "In4.Cu")
		(net "M_G_CPU0_SA_DQ<2>")
	)
	(segment
		(start 385.663694 -279.525476)
		(end 385.534916 -279.525476)
		(width 0.088646)
		(layer "In4.Cu")
		(net "M_G_CPU0_SA_DQ<2>")
	)
	(segment
		(start 407.256234 -313.113928)
		(end 406.16378 -312.021474)
		(width 0.18288)
		(layer "In4.Cu")
		(net "M_G_CPU0_SA_DQ<2>")
	)
	(segment
		(start 406.16378 -312.021474)
		(end 405.1427 -312.021474)
		(width 0.18288)
		(layer "In4.Cu")
		(net "M_G_CPU0_SA_DQ<2>")
	)
	(segment
		(start 408.219656 -313.113928)
		(end 407.256234 -313.113928)
		(width 0.18288)
		(layer "In4.Cu")
		(net "M_G_CPU0_SA_DQ<2>")
	)
	(segment
		(start 410.519626 -314.101226)
		(end 409.206954 -314.101226)
		(width 0.18288)
		(layer "In4.Cu")
		(net "M_G_CPU0_SA_DQ<2>")
	)
	(segment
		(start 431.421794 -315.218826)
		(end 430.591214 -316.049406)
		(width 0.18288)
		(layer "In4.Cu")
		(net "M_G_CPU0_SA_DQ<2>")
	)
	(arc
		(start 382.810512 -278.31796)
		(mid 382.73035 -278.045771)
		(end 382.528064 -277.84679)
		(width 0.088646)
		(layer "In4.Cu")
		(net "M_G_CPU0_SA_DQ<2>")
	)
	(arc
		(start 381.118618 -277.032974)
		(mid 380.841805 -276.957104)
		(end 380.563374 -277.026878)
		(width 0.088646)
		(layer "In4.Cu")
		(net "M_G_CPU0_SA_DQ<2>")
	)
	(arc
		(start 385.347464 -279.474676)
		(mid 385.064762 -279.3989)
		(end 384.78206 -279.474676)
		(width 0.088646)
		(layer "In4.Cu")
		(net "M_G_CPU0_SA_DQ<2>")
	)
	(arc
		(start 382.519174 -277.84171)
		(mid 382.38826 -277.70535)
		(end 382.340612 -277.522432)
		(width 0.088646)
		(layer "In4.Cu")
		(net "M_G_CPU0_SA_DQ<2>")
	)
	(arc
		(start 385.534916 -279.525476)
		(mid 385.437846 -279.512419)
		(end 385.347464 -279.474676)
		(width 0.088646)
		(layer "In4.Cu")
		(net "M_G_CPU0_SA_DQ<2>")
	)
	(arc
		(start 384.78206 -279.474676)
		(mid 384.594862 -279.524819)
		(end 384.407664 -279.474676)
		(width 0.088646)
		(layer "In4.Cu")
		(net "M_G_CPU0_SA_DQ<2>")
	)
	(arc
		(start 380.178564 -277.032974)
		(mid 379.902005 -276.957231)
		(end 379.623828 -277.026878)
		(width 0.088646)
		(layer "In4.Cu")
		(net "M_G_CPU0_SA_DQ<2>")
	)
	(arc
		(start 384.407664 -279.474676)
		(mid 384.124962 -279.3989)
		(end 383.84226 -279.474676)
		(width 0.088646)
		(layer "In4.Cu")
		(net "M_G_CPU0_SA_DQ<2>")
	)
	(arc
		(start 382.340612 -277.506938)
		(mid 382.261242 -277.233204)
		(end 382.058418 -277.032974)
		(width 0.088646)
		(layer "In4.Cu")
		(net "M_G_CPU0_SA_DQ<2>")
	)
	(arc
		(start 382.058418 -277.032974)
		(mid 381.784219 -276.957139)
		(end 381.507746 -277.024338)
		(width 0.088646)
		(layer "In4.Cu")
		(net "M_G_CPU0_SA_DQ<2>")
	)
	(arc
		(start 383.458974 -279.469596)
		(mid 383.32806 -279.333236)
		(end 383.280412 -279.150318)
		(width 0.088646)
		(layer "In4.Cu")
		(net "M_G_CPU0_SA_DQ<2>")
	)
	(arc
		(start 382.989074 -278.65578)
		(mid 382.85816 -278.51942)
		(end 382.810512 -278.336502)
		(width 0.088646)
		(layer "In4.Cu")
		(net "M_G_CPU0_SA_DQ<2>")
	)
	(arc
		(start 380.55296 -277.032974)
		(mid 380.365762 -277.083117)
		(end 380.178564 -277.032974)
		(width 0.088646)
		(layer "In4.Cu")
		(net "M_G_CPU0_SA_DQ<2>")
	)
	(arc
		(start 381.493014 -277.032974)
		(mid 381.305816 -277.083117)
		(end 381.118618 -277.032974)
		(width 0.088646)
		(layer "In4.Cu")
		(net "M_G_CPU0_SA_DQ<2>")
	)
	(arc
		(start 379.230128 -277.027894)
		(mid 379.114389 -276.91607)
		(end 379.056138 -276.76602)
		(width 0.088646)
		(layer "In4.Cu")
		(net "M_G_CPU0_SA_DQ<2>")
	)
	(arc
		(start 383.280412 -279.140412)
		(mid 383.202301 -278.863463)
		(end 382.997964 -278.66086)
		(width 0.088646)
		(layer "In4.Cu")
		(net "M_G_CPU0_SA_DQ<2>")
	)
	(arc
		(start 383.84226 -279.474676)
		(mid 383.655062 -279.524819)
		(end 383.467864 -279.474676)
		(width 0.088646)
		(layer "In4.Cu")
		(net "M_G_CPU0_SA_DQ<2>")
	)
	(arc
		(start 379.613414 -277.032974)
		(mid 379.426216 -277.083117)
		(end 379.239018 -277.032974)
		(width 0.088646)
		(layer "In4.Cu")
		(net "M_G_CPU0_SA_DQ<2>")
	)
	(segment
		(start 375.197116 -266.127992)
		(end 375.196862 -266.128246)
		(width 0.20066)
		(layer "F.Cu")
		(net "M_G_CPU0_SA_DQ<29>")
	)
	(segment
		(start 436.928514 -280.61666)
		(end 435.823614 -280.61666)
		(width 0.20066)
		(layer "F.Cu")
		(net "M_G_CPU0_SA_DQ<29>")
	)
	(segment
		(start 442.038994 -280.185368)
		(end 442.032644 -280.191718)
		(width 0.1016)
		(layer "F.Cu")
		(net "M_G_CPU0_SA_DQ<29>")
	)
	(segment
		(start 375.197116 -265.592306)
		(end 375.197116 -266.127992)
		(width 0.20066)
		(layer "F.Cu")
		(net "M_G_CPU0_SA_DQ<29>")
	)
	(segment
		(start 439.361072 -280.309828)
		(end 439.361072 -280.677366)
		(width 0.20066)
		(layer "F.Cu")
		(net "M_G_CPU0_SA_DQ<29>")
	)
	(segment
		(start 442.032644 -280.191718)
		(end 439.843926 -280.191718)
		(width 0.1016)
		(layer "F.Cu")
		(net "M_G_CPU0_SA_DQ<29>")
	)
	(segment
		(start 438.697878 -280.865326)
		(end 438.449212 -280.61666)
		(width 0.20066)
		(layer "F.Cu")
		(net "M_G_CPU0_SA_DQ<29>")
	)
	(segment
		(start 444.472314 -280.61666)
		(end 444.47206 -280.616914)
		(width 0.20066)
		(layer "F.Cu")
		(net "M_G_CPU0_SA_DQ<29>")
	)
	(segment
		(start 439.843926 -280.191718)
		(end 439.82386 -280.191718)
		(width 0.101854)
		(layer "F.Cu")
		(net "M_G_CPU0_SA_DQ<29>")
	)
	(segment
		(start 442.880496 -280.616914)
		(end 442.44895 -280.185368)
		(width 0.20066)
		(layer "F.Cu")
		(net "M_G_CPU0_SA_DQ<29>")
	)
	(segment
		(start 439.82386 -280.191718)
		(end 439.479182 -280.191718)
		(width 0.20066)
		(layer "F.Cu")
		(net "M_G_CPU0_SA_DQ<29>")
	)
	(segment
		(start 442.44895 -280.185368)
		(end 442.038994 -280.185368)
		(width 0.20066)
		(layer "F.Cu")
		(net "M_G_CPU0_SA_DQ<29>")
	)
	(segment
		(start 438.449212 -280.61666)
		(end 436.928514 -280.61666)
		(width 0.20066)
		(layer "F.Cu")
		(net "M_G_CPU0_SA_DQ<29>")
	)
	(segment
		(start 444.47206 -280.616914)
		(end 442.880496 -280.616914)
		(width 0.20066)
		(layer "F.Cu")
		(net "M_G_CPU0_SA_DQ<29>")
	)
	(segment
		(start 439.173112 -280.865326)
		(end 438.697878 -280.865326)
		(width 0.20066)
		(layer "F.Cu")
		(net "M_G_CPU0_SA_DQ<29>")
	)
	(segment
		(start 439.479182 -280.191718)
		(end 439.361072 -280.309828)
		(width 0.20066)
		(layer "F.Cu")
		(net "M_G_CPU0_SA_DQ<29>")
	)
	(segment
		(start 439.361072 -280.677366)
		(end 439.173112 -280.865326)
		(width 0.20066)
		(layer "F.Cu")
		(net "M_G_CPU0_SA_DQ<29>")
	)
	(segment
		(start 427.504606 -279.277826)
		(end 427.302422 -279.48001)
		(width 0.18288)
		(layer "In6.Cu")
		(net "M_G_CPU0_SA_DQ<29>")
	)
	(segment
		(start 431.002694 -279.277826)
		(end 427.504606 -279.277826)
		(width 0.18288)
		(layer "In6.Cu")
		(net "M_G_CPU0_SA_DQ<29>")
	)
	(segment
		(start 392.941556 -266.49299)
		(end 390.2964 -265.966956)
		(width 0.18288)
		(layer "In6.Cu")
		(net "M_G_CPU0_SA_DQ<29>")
	)
	(segment
		(start 410.531564 -270.940276)
		(end 410.531564 -271.622266)
		(width 0.18288)
		(layer "In6.Cu")
		(net "M_G_CPU0_SA_DQ<29>")
	)
	(segment
		(start 411.224984 -270.940276)
		(end 411.042104 -270.757396)
		(width 0.18288)
		(layer "In6.Cu")
		(net "M_G_CPU0_SA_DQ<29>")
	)
	(segment
		(start 422.010332 -272.229072)
		(end 421.630348 -272.229072)
		(width 0.18288)
		(layer "In6.Cu")
		(net "M_G_CPU0_SA_DQ<29>")
	)
	(segment
		(start 423.0624 -274.084542)
		(end 423.22242 -273.924522)
		(width 0.18288)
		(layer "In6.Cu")
		(net "M_G_CPU0_SA_DQ<29>")
	)
	(segment
		(start 408.37993 -271.379696)
		(end 406.458674 -271.379696)
		(width 0.18288)
		(layer "In6.Cu")
		(net "M_G_CPU0_SA_DQ<29>")
	)
	(segment
		(start 426.17136 -278.8158)
		(end 426.17136 -277.807674)
		(width 0.18288)
		(layer "In6.Cu")
		(net "M_G_CPU0_SA_DQ<29>")
	)
	(segment
		(start 381.968756 -265.80719)
		(end 381.962914 -265.803634)
		(width 0.088646)
		(layer "In6.Cu")
		(net "M_G_CPU0_SA_DQ<29>")
	)
	(segment
		(start 411.224984 -271.622266)
		(end 411.224984 -270.940276)
		(width 0.18288)
		(layer "In6.Cu")
		(net "M_G_CPU0_SA_DQ<29>")
	)
	(segment
		(start 423.028364 -275.844762)
		(end 423.028364 -275.471382)
		(width 0.18288)
		(layer "In6.Cu")
		(net "M_G_CPU0_SA_DQ<29>")
	)
	(segment
		(start 375.868946 -266.626086)
		(end 375.854214 -266.61745)
		(width 0.088646)
		(layer "In6.Cu")
		(net "M_G_CPU0_SA_DQ<29>")
	)
	(segment
		(start 411.042104 -270.757396)
		(end 410.714444 -270.757396)
		(width 0.18288)
		(layer "In6.Cu")
		(net "M_G_CPU0_SA_DQ<29>")
	)
	(segment
		(start 410.531564 -271.622266)
		(end 410.348684 -271.805146)
		(width 0.18288)
		(layer "In6.Cu")
		(net "M_G_CPU0_SA_DQ<29>")
	)
	(segment
		(start 425.154344 -276.790658)
		(end 424.419014 -276.790658)
		(width 0.18288)
		(layer "In6.Cu")
		(net "M_G_CPU0_SA_DQ<29>")
	)
	(segment
		(start 412.332678 -271.805146)
		(end 411.407864 -271.805146)
		(width 0.18288)
		(layer "In6.Cu")
		(net "M_G_CPU0_SA_DQ<29>")
	)
	(segment
		(start 418.67836 -272.542508)
		(end 417.978336 -271.842484)
		(width 0.18288)
		(layer "In6.Cu")
		(net "M_G_CPU0_SA_DQ<29>")
	)
	(segment
		(start 423.633138 -275.311362)
		(end 423.793158 -275.151342)
		(width 0.18288)
		(layer "In6.Cu")
		(net "M_G_CPU0_SA_DQ<29>")
	)
	(segment
		(start 423.22242 -274.617942)
		(end 423.0624 -274.457922)
		(width 0.18288)
		(layer "In6.Cu")
		(net "M_G_CPU0_SA_DQ<29>")
	)
	(segment
		(start 382.902714 -265.803634)
		(end 382.896872 -265.800332)
		(width 0.088646)
		(layer "In6.Cu")
		(net "M_G_CPU0_SA_DQ<29>")
	)
	(segment
		(start 435.32171 -280.114756)
		(end 431.839624 -280.114756)
		(width 0.18288)
		(layer "In6.Cu")
		(net "M_G_CPU0_SA_DQ<29>")
	)
	(segment
		(start 423.633138 -274.617942)
		(end 423.22242 -274.617942)
		(width 0.18288)
		(layer "In6.Cu")
		(net "M_G_CPU0_SA_DQ<29>")
	)
	(segment
		(start 406.458674 -271.379696)
		(end 406.197562 -271.640808)
		(width 0.18288)
		(layer "In6.Cu")
		(net "M_G_CPU0_SA_DQ<29>")
	)
	(segment
		(start 383.467864 -265.803888)
		(end 383.453132 -265.812524)
		(width 0.088646)
		(layer "In6.Cu")
		(net "M_G_CPU0_SA_DQ<29>")
	)
	(segment
		(start 406.197562 -271.640808)
		(end 405.052784 -271.640808)
		(width 0.18288)
		(layer "In6.Cu")
		(net "M_G_CPU0_SA_DQ<29>")
	)
	(segment
		(start 423.22242 -273.924522)
		(end 423.633138 -273.924522)
		(width 0.18288)
		(layer "In6.Cu")
		(net "M_G_CPU0_SA_DQ<29>")
	)
	(segment
		(start 423.793158 -274.777962)
		(end 423.633138 -274.617942)
		(width 0.18288)
		(layer "In6.Cu")
		(net "M_G_CPU0_SA_DQ<29>")
	)
	(segment
		(start 419.347904 -272.229072)
		(end 419.034468 -272.542508)
		(width 0.18288)
		(layer "In6.Cu")
		(net "M_G_CPU0_SA_DQ<29>")
	)
	(segment
		(start 412.484316 -271.653508)
		(end 412.332678 -271.805146)
		(width 0.18288)
		(layer "In6.Cu")
		(net "M_G_CPU0_SA_DQ<29>")
	)
	(segment
		(start 386.287264 -265.803888)
		(end 386.272532 -265.812524)
		(width 0.088646)
		(layer "In6.Cu")
		(net "M_G_CPU0_SA_DQ<29>")
	)
	(segment
		(start 423.793158 -275.151342)
		(end 423.793158 -274.777962)
		(width 0.18288)
		(layer "In6.Cu")
		(net "M_G_CPU0_SA_DQ<29>")
	)
	(segment
		(start 377.829064 -265.803634)
		(end 377.81865 -265.80973)
		(width 0.088646)
		(layer "In6.Cu")
		(net "M_G_CPU0_SA_DQ<29>")
	)
	(segment
		(start 431.839624 -280.114756)
		(end 431.002694 -279.277826)
		(width 0.18288)
		(layer "In6.Cu")
		(net "M_G_CPU0_SA_DQ<29>")
	)
	(segment
		(start 384.407664 -265.803888)
		(end 384.392932 -265.812524)
		(width 0.088646)
		(layer "In6.Cu")
		(net "M_G_CPU0_SA_DQ<29>")
	)
	(segment
		(start 408.80538 -271.805146)
		(end 408.37993 -271.379696)
		(width 0.18288)
		(layer "In6.Cu")
		(net "M_G_CPU0_SA_DQ<29>")
	)
	(segment
		(start 417.096448 -271.842484)
		(end 416.907472 -271.653508)
		(width 0.18288)
		(layer "In6.Cu")
		(net "M_G_CPU0_SA_DQ<29>")
	)
	(segment
		(start 388.182612 -265.893042)
		(end 387.933692 -265.893042)
		(width 0.088646)
		(layer "In6.Cu")
		(net "M_G_CPU0_SA_DQ<29>")
	)
	(segment
		(start 405.052784 -271.640808)
		(end 399.904966 -266.49299)
		(width 0.18288)
		(layer "In6.Cu")
		(net "M_G_CPU0_SA_DQ<29>")
	)
	(segment
		(start 419.034468 -272.542508)
		(end 418.67836 -272.542508)
		(width 0.18288)
		(layer "In6.Cu")
		(net "M_G_CPU0_SA_DQ<29>")
	)
	(segment
		(start 390.2964 -265.966956)
		(end 388.535672 -265.966956)
		(width 0.18288)
		(layer "In6.Cu")
		(net "M_G_CPU0_SA_DQ<29>")
	)
	(segment
		(start 378.209556 -265.80719)
		(end 378.203714 -265.803634)
		(width 0.088646)
		(layer "In6.Cu")
		(net "M_G_CPU0_SA_DQ<29>")
	)
	(segment
		(start 417.978336 -271.842484)
		(end 417.096448 -271.842484)
		(width 0.18288)
		(layer "In6.Cu")
		(net "M_G_CPU0_SA_DQ<29>")
	)
	(segment
		(start 410.348684 -271.805146)
		(end 408.80538 -271.805146)
		(width 0.18288)
		(layer "In6.Cu")
		(net "M_G_CPU0_SA_DQ<29>")
	)
	(segment
		(start 423.793158 -273.165062)
		(end 423.170604 -272.542508)
		(width 0.18288)
		(layer "In6.Cu")
		(net "M_G_CPU0_SA_DQ<29>")
	)
	(segment
		(start 411.407864 -271.805146)
		(end 411.224984 -271.622266)
		(width 0.18288)
		(layer "In6.Cu")
		(net "M_G_CPU0_SA_DQ<29>")
	)
	(segment
		(start 410.714444 -270.757396)
		(end 410.531564 -270.940276)
		(width 0.18288)
		(layer "In6.Cu")
		(net "M_G_CPU0_SA_DQ<29>")
	)
	(segment
		(start 388.256526 -265.966956)
		(end 388.182612 -265.893042)
		(width 0.088646)
		(layer "In6.Cu")
		(net "M_G_CPU0_SA_DQ<29>")
	)
	(segment
		(start 426.17136 -277.807674)
		(end 425.154344 -276.790658)
		(width 0.18288)
		(layer "In6.Cu")
		(net "M_G_CPU0_SA_DQ<29>")
	)
	(segment
		(start 379.143514 -265.803634)
		(end 379.137672 -265.800332)
		(width 0.088646)
		(layer "In6.Cu")
		(net "M_G_CPU0_SA_DQ<29>")
	)
	(segment
		(start 424.419014 -276.790658)
		(end 423.633138 -276.004782)
		(width 0.18288)
		(layer "In6.Cu")
		(net "M_G_CPU0_SA_DQ<29>")
	)
	(segment
		(start 419.727888 -272.229072)
		(end 419.347904 -272.229072)
		(width 0.18288)
		(layer "In6.Cu")
		(net "M_G_CPU0_SA_DQ<29>")
	)
	(segment
		(start 423.633138 -273.924522)
		(end 423.793158 -273.764502)
		(width 0.18288)
		(layer "In6.Cu")
		(net "M_G_CPU0_SA_DQ<29>")
	)
	(segment
		(start 423.188384 -275.311362)
		(end 423.633138 -275.311362)
		(width 0.18288)
		(layer "In6.Cu")
		(net "M_G_CPU0_SA_DQ<29>")
	)
	(segment
		(start 427.302422 -279.48001)
		(end 426.83557 -279.48001)
		(width 0.18288)
		(layer "In6.Cu")
		(net "M_G_CPU0_SA_DQ<29>")
	)
	(segment
		(start 376.425714 -266.613894)
		(end 376.419618 -266.61745)
		(width 0.088646)
		(layer "In6.Cu")
		(net "M_G_CPU0_SA_DQ<29>")
	)
	(segment
		(start 423.188384 -276.004782)
		(end 423.028364 -275.844762)
		(width 0.18288)
		(layer "In6.Cu")
		(net "M_G_CPU0_SA_DQ<29>")
	)
	(segment
		(start 388.535672 -265.966956)
		(end 388.256526 -265.966956)
		(width 0.088646)
		(layer "In6.Cu")
		(net "M_G_CPU0_SA_DQ<29>")
	)
	(segment
		(start 375.854214 -266.61745)
		(end 375.823988 -266.600178)
		(width 0.088646)
		(layer "In6.Cu")
		(net "M_G_CPU0_SA_DQ<29>")
	)
	(segment
		(start 423.0624 -274.457922)
		(end 423.0624 -274.084542)
		(width 0.18288)
		(layer "In6.Cu")
		(net "M_G_CPU0_SA_DQ<29>")
	)
	(segment
		(start 426.83557 -279.48001)
		(end 426.17136 -278.8158)
		(width 0.18288)
		(layer "In6.Cu")
		(net "M_G_CPU0_SA_DQ<29>")
	)
	(segment
		(start 382.90246 -265.803888)
		(end 382.902714 -265.803634)
		(width 0.088646)
		(layer "In6.Cu")
		(net "M_G_CPU0_SA_DQ<29>")
	)
	(segment
		(start 380.083314 -265.803634)
		(end 380.077472 -265.800332)
		(width 0.088646)
		(layer "In6.Cu")
		(net "M_G_CPU0_SA_DQ<29>")
	)
	(segment
		(start 375.823988 -266.600178)
		(end 375.196862 -266.128246)
		(width 0.088646)
		(layer "In6.Cu")
		(net "M_G_CPU0_SA_DQ<29>")
	)
	(segment
		(start 423.633138 -276.004782)
		(end 423.188384 -276.004782)
		(width 0.18288)
		(layer "In6.Cu")
		(net "M_G_CPU0_SA_DQ<29>")
	)
	(segment
		(start 423.028364 -275.471382)
		(end 423.188384 -275.311362)
		(width 0.18288)
		(layer "In6.Cu")
		(net "M_G_CPU0_SA_DQ<29>")
	)
	(segment
		(start 381.962914 -265.803634)
		(end 381.957072 -265.800332)
		(width 0.088646)
		(layer "In6.Cu")
		(net "M_G_CPU0_SA_DQ<29>")
	)
	(segment
		(start 381.028956 -265.80719)
		(end 381.023114 -265.803634)
		(width 0.088646)
		(layer "In6.Cu")
		(net "M_G_CPU0_SA_DQ<29>")
	)
	(segment
		(start 423.170604 -272.542508)
		(end 422.323768 -272.542508)
		(width 0.18288)
		(layer "In6.Cu")
		(net "M_G_CPU0_SA_DQ<29>")
	)
	(segment
		(start 387.227064 -265.803888)
		(end 387.212332 -265.812524)
		(width 0.088646)
		(layer "In6.Cu")
		(net "M_G_CPU0_SA_DQ<29>")
	)
	(segment
		(start 378.203714 -265.803634)
		(end 378.197872 -265.800332)
		(width 0.088646)
		(layer "In6.Cu")
		(net "M_G_CPU0_SA_DQ<29>")
	)
	(segment
		(start 423.793158 -273.764502)
		(end 423.793158 -273.165062)
		(width 0.18288)
		(layer "In6.Cu")
		(net "M_G_CPU0_SA_DQ<29>")
	)
	(segment
		(start 381.023114 -265.803634)
		(end 381.017272 -265.800332)
		(width 0.088646)
		(layer "In6.Cu")
		(net "M_G_CPU0_SA_DQ<29>")
	)
	(segment
		(start 379.149356 -265.80719)
		(end 379.143514 -265.803634)
		(width 0.088646)
		(layer "In6.Cu")
		(net "M_G_CPU0_SA_DQ<29>")
	)
	(segment
		(start 421.630348 -272.229072)
		(end 421.316912 -272.542508)
		(width 0.18288)
		(layer "In6.Cu")
		(net "M_G_CPU0_SA_DQ<29>")
	)
	(segment
		(start 380.089156 -265.80719)
		(end 380.083314 -265.803634)
		(width 0.088646)
		(layer "In6.Cu")
		(net "M_G_CPU0_SA_DQ<29>")
	)
	(segment
		(start 422.323768 -272.542508)
		(end 422.010332 -272.229072)
		(width 0.18288)
		(layer "In6.Cu")
		(net "M_G_CPU0_SA_DQ<29>")
	)
	(segment
		(start 420.041324 -272.542508)
		(end 419.727888 -272.229072)
		(width 0.18288)
		(layer "In6.Cu")
		(net "M_G_CPU0_SA_DQ<29>")
	)
	(segment
		(start 399.904966 -266.49299)
		(end 392.941556 -266.49299)
		(width 0.18288)
		(layer "In6.Cu")
		(net "M_G_CPU0_SA_DQ<29>")
	)
	(segment
		(start 435.823614 -280.61666)
		(end 435.32171 -280.114756)
		(width 0.18288)
		(layer "In6.Cu")
		(net "M_G_CPU0_SA_DQ<29>")
	)
	(segment
		(start 416.907472 -271.653508)
		(end 412.484316 -271.653508)
		(width 0.18288)
		(layer "In6.Cu")
		(net "M_G_CPU0_SA_DQ<29>")
	)
	(segment
		(start 385.347464 -265.803888)
		(end 385.332732 -265.812524)
		(width 0.088646)
		(layer "In6.Cu")
		(net "M_G_CPU0_SA_DQ<29>")
	)
	(segment
		(start 421.316912 -272.542508)
		(end 420.041324 -272.542508)
		(width 0.18288)
		(layer "In6.Cu")
		(net "M_G_CPU0_SA_DQ<29>")
	)
	(arc
		(start 378.768864 -265.803634)
		(mid 378.48969 -265.879399)
		(end 378.209556 -265.80719)
		(width 0.088646)
		(layer "In6.Cu")
		(net "M_G_CPU0_SA_DQ<29>")
	)
	(arc
		(start 376.419618 -266.61745)
		(mid 376.145419 -266.693285)
		(end 375.868946 -266.626086)
		(width 0.088646)
		(layer "In6.Cu")
		(net "M_G_CPU0_SA_DQ<29>")
	)
	(arc
		(start 380.648464 -265.803634)
		(mid 380.36929 -265.879399)
		(end 380.089156 -265.80719)
		(width 0.088646)
		(layer "In6.Cu")
		(net "M_G_CPU0_SA_DQ<29>")
	)
	(arc
		(start 386.272532 -265.812524)
		(mid 385.996091 -265.87969)
		(end 385.72186 -265.803888)
		(width 0.088646)
		(layer "In6.Cu")
		(net "M_G_CPU0_SA_DQ<29>")
	)
	(arc
		(start 385.72186 -265.803888)
		(mid 385.534662 -265.753745)
		(end 385.347464 -265.803888)
		(width 0.088646)
		(layer "In6.Cu")
		(net "M_G_CPU0_SA_DQ<29>")
	)
	(arc
		(start 387.60146 -265.803888)
		(mid 387.414262 -265.753745)
		(end 387.227064 -265.803888)
		(width 0.088646)
		(layer "In6.Cu")
		(net "M_G_CPU0_SA_DQ<29>")
	)
	(arc
		(start 381.017272 -265.800332)
		(mid 380.832417 -265.753382)
		(end 380.648464 -265.803634)
		(width 0.088646)
		(layer "In6.Cu")
		(net "M_G_CPU0_SA_DQ<29>")
	)
	(arc
		(start 383.84226 -265.803888)
		(mid 383.655062 -265.753745)
		(end 383.467864 -265.803888)
		(width 0.088646)
		(layer "In6.Cu")
		(net "M_G_CPU0_SA_DQ<29>")
	)
	(arc
		(start 379.708664 -265.803634)
		(mid 379.42949 -265.879399)
		(end 379.149356 -265.80719)
		(width 0.088646)
		(layer "In6.Cu")
		(net "M_G_CPU0_SA_DQ<29>")
	)
	(arc
		(start 385.332732 -265.812524)
		(mid 385.056291 -265.87969)
		(end 384.78206 -265.803888)
		(width 0.088646)
		(layer "In6.Cu")
		(net "M_G_CPU0_SA_DQ<29>")
	)
	(arc
		(start 377.263914 -265.803634)
		(mid 376.889439 -265.80368)
		(end 376.702066 -266.127992)
		(width 0.088646)
		(layer "In6.Cu")
		(net "M_G_CPU0_SA_DQ<29>")
	)
	(arc
		(start 387.933692 -265.893042)
		(mid 387.761693 -265.870377)
		(end 387.60146 -265.803888)
		(width 0.088646)
		(layer "In6.Cu")
		(net "M_G_CPU0_SA_DQ<29>")
	)
	(arc
		(start 383.453132 -265.812524)
		(mid 383.176691 -265.87969)
		(end 382.90246 -265.803888)
		(width 0.088646)
		(layer "In6.Cu")
		(net "M_G_CPU0_SA_DQ<29>")
	)
	(arc
		(start 387.212332 -265.812524)
		(mid 386.935891 -265.87969)
		(end 386.66166 -265.803888)
		(width 0.088646)
		(layer "In6.Cu")
		(net "M_G_CPU0_SA_DQ<29>")
	)
	(arc
		(start 377.81865 -265.80973)
		(mid 377.540472 -265.879453)
		(end 377.263914 -265.803634)
		(width 0.088646)
		(layer "In6.Cu")
		(net "M_G_CPU0_SA_DQ<29>")
	)
	(arc
		(start 382.896872 -265.800332)
		(mid 382.712017 -265.753382)
		(end 382.528064 -265.803634)
		(width 0.088646)
		(layer "In6.Cu")
		(net "M_G_CPU0_SA_DQ<29>")
	)
	(arc
		(start 378.197872 -265.800332)
		(mid 378.013017 -265.753382)
		(end 377.829064 -265.803634)
		(width 0.088646)
		(layer "In6.Cu")
		(net "M_G_CPU0_SA_DQ<29>")
	)
	(arc
		(start 381.588264 -265.803634)
		(mid 381.30909 -265.879399)
		(end 381.028956 -265.80719)
		(width 0.088646)
		(layer "In6.Cu")
		(net "M_G_CPU0_SA_DQ<29>")
	)
	(arc
		(start 384.392932 -265.812524)
		(mid 384.116491 -265.87969)
		(end 383.84226 -265.803888)
		(width 0.088646)
		(layer "In6.Cu")
		(net "M_G_CPU0_SA_DQ<29>")
	)
	(arc
		(start 381.957072 -265.800332)
		(mid 381.772217 -265.753382)
		(end 381.588264 -265.803634)
		(width 0.088646)
		(layer "In6.Cu")
		(net "M_G_CPU0_SA_DQ<29>")
	)
	(arc
		(start 379.137672 -265.800332)
		(mid 378.952817 -265.753382)
		(end 378.768864 -265.803634)
		(width 0.088646)
		(layer "In6.Cu")
		(net "M_G_CPU0_SA_DQ<29>")
	)
	(arc
		(start 382.528064 -265.803634)
		(mid 382.24889 -265.879399)
		(end 381.968756 -265.80719)
		(width 0.088646)
		(layer "In6.Cu")
		(net "M_G_CPU0_SA_DQ<29>")
	)
	(arc
		(start 380.077472 -265.800332)
		(mid 379.892617 -265.753382)
		(end 379.708664 -265.803634)
		(width 0.088646)
		(layer "In6.Cu")
		(net "M_G_CPU0_SA_DQ<29>")
	)
	(arc
		(start 376.702066 -266.127992)
		(mid 376.62815 -266.407494)
		(end 376.425714 -266.613894)
		(width 0.088646)
		(layer "In6.Cu")
		(net "M_G_CPU0_SA_DQ<29>")
	)
	(arc
		(start 386.66166 -265.803888)
		(mid 386.474462 -265.753745)
		(end 386.287264 -265.803888)
		(width 0.088646)
		(layer "In6.Cu")
		(net "M_G_CPU0_SA_DQ<29>")
	)
	(arc
		(start 384.78206 -265.803888)
		(mid 384.594862 -265.753745)
		(end 384.407664 -265.803888)
		(width 0.088646)
		(layer "In6.Cu")
		(net "M_G_CPU0_SA_DQ<29>")
	)
	(segment
		(start 374.726962 -266.941554)
		(end 374.727216 -266.941808)
		(width 0.20066)
		(layer "F.Cu")
		(net "M_G_CPU0_SA_DQ<28>")
	)
	(segment
		(start 442.880496 -282.316936)
		(end 442.44895 -281.88539)
		(width 0.20066)
		(layer "F.Cu")
		(net "M_G_CPU0_SA_DQ<28>")
	)
	(segment
		(start 436.928514 -282.316682)
		(end 435.823614 -282.316682)
		(width 0.20066)
		(layer "F.Cu")
		(net "M_G_CPU0_SA_DQ<28>")
	)
	(segment
		(start 439.361072 -282.00985)
		(end 439.361072 -282.377388)
		(width 0.20066)
		(layer "F.Cu")
		(net "M_G_CPU0_SA_DQ<28>")
	)
	(segment
		(start 438.697878 -282.565348)
		(end 438.449212 -282.316682)
		(width 0.20066)
		(layer "F.Cu")
		(net "M_G_CPU0_SA_DQ<28>")
	)
	(segment
		(start 439.87085 -281.89174)
		(end 439.71591 -281.89174)
		(width 0.101854)
		(layer "F.Cu")
		(net "M_G_CPU0_SA_DQ<28>")
	)
	(segment
		(start 444.472314 -282.316682)
		(end 444.47206 -282.316936)
		(width 0.20066)
		(layer "F.Cu")
		(net "M_G_CPU0_SA_DQ<28>")
	)
	(segment
		(start 442.44895 -281.88539)
		(end 442.038994 -281.88539)
		(width 0.20066)
		(layer "F.Cu")
		(net "M_G_CPU0_SA_DQ<28>")
	)
	(segment
		(start 444.47206 -282.316936)
		(end 442.880496 -282.316936)
		(width 0.20066)
		(layer "F.Cu")
		(net "M_G_CPU0_SA_DQ<28>")
	)
	(segment
		(start 439.173112 -282.565348)
		(end 438.697878 -282.565348)
		(width 0.20066)
		(layer "F.Cu")
		(net "M_G_CPU0_SA_DQ<28>")
	)
	(segment
		(start 438.449212 -282.316682)
		(end 436.928514 -282.316682)
		(width 0.20066)
		(layer "F.Cu")
		(net "M_G_CPU0_SA_DQ<28>")
	)
	(segment
		(start 439.71591 -281.89174)
		(end 439.479182 -281.89174)
		(width 0.20066)
		(layer "F.Cu")
		(net "M_G_CPU0_SA_DQ<28>")
	)
	(segment
		(start 439.479182 -281.89174)
		(end 439.361072 -282.00985)
		(width 0.20066)
		(layer "F.Cu")
		(net "M_G_CPU0_SA_DQ<28>")
	)
	(segment
		(start 442.038994 -281.88539)
		(end 442.032644 -281.89174)
		(width 0.1016)
		(layer "F.Cu")
		(net "M_G_CPU0_SA_DQ<28>")
	)
	(segment
		(start 439.361072 -282.377388)
		(end 439.173112 -282.565348)
		(width 0.20066)
		(layer "F.Cu")
		(net "M_G_CPU0_SA_DQ<28>")
	)
	(segment
		(start 442.032644 -281.89174)
		(end 439.87085 -281.89174)
		(width 0.1016)
		(layer "F.Cu")
		(net "M_G_CPU0_SA_DQ<28>")
	)
	(segment
		(start 374.726962 -266.405868)
		(end 374.726962 -266.941554)
		(width 0.20066)
		(layer "F.Cu")
		(net "M_G_CPU0_SA_DQ<28>")
	)
	(segment
		(start 419.804088 -274.874736)
		(end 419.621208 -275.057616)
		(width 0.18288)
		(layer "In6.Cu")
		(net "M_G_CPU0_SA_DQ<28>")
	)
	(segment
		(start 407.31694 -273.218402)
		(end 407.13406 -273.401282)
		(width 0.18288)
		(layer "In6.Cu")
		(net "M_G_CPU0_SA_DQ<28>")
	)
	(segment
		(start 422.397174 -277.565612)
		(end 421.93845 -277.106888)
		(width 0.18288)
		(layer "In6.Cu")
		(net "M_G_CPU0_SA_DQ<28>")
	)
	(segment
		(start 421.93845 -277.106888)
		(end 421.93845 -276.384258)
		(width 0.18288)
		(layer "In6.Cu")
		(net "M_G_CPU0_SA_DQ<28>")
	)
	(segment
		(start 431.70475 -281.732482)
		(end 431.003456 -281.031188)
		(width 0.18288)
		(layer "In6.Cu")
		(net "M_G_CPU0_SA_DQ<28>")
	)
	(segment
		(start 419.804088 -274.42541)
		(end 419.804088 -274.874736)
		(width 0.18288)
		(layer "In6.Cu")
		(net "M_G_CPU0_SA_DQ<28>")
	)
	(segment
		(start 405.055832 -273.218402)
		(end 399.30451 -267.504672)
		(width 0.18288)
		(layer "In6.Cu")
		(net "M_G_CPU0_SA_DQ<28>")
	)
	(segment
		(start 407.13406 -273.401282)
		(end 407.13406 -273.633438)
		(width 0.18288)
		(layer "In6.Cu")
		(net "M_G_CPU0_SA_DQ<28>")
	)
	(segment
		(start 410.535374 -273.105118)
		(end 410.535374 -273.391376)
		(width 0.18288)
		(layer "In6.Cu")
		(net "M_G_CPU0_SA_DQ<28>")
	)
	(segment
		(start 421.93845 -275.325078)
		(end 421.93845 -274.665694)
		(width 0.18288)
		(layer "In6.Cu")
		(net "M_G_CPU0_SA_DQ<28>")
	)
	(segment
		(start 382.064006 -266.614148)
		(end 382.058164 -266.61745)
		(width 0.088646)
		(layer "In6.Cu")
		(net "M_G_CPU0_SA_DQ<28>")
	)
	(segment
		(start 421.192452 -275.690838)
		(end 421.375332 -275.507958)
		(width 0.18288)
		(layer "In6.Cu")
		(net "M_G_CPU0_SA_DQ<28>")
	)
	(segment
		(start 406.44064 -273.401282)
		(end 406.25776 -273.218402)
		(width 0.18288)
		(layer "In6.Cu")
		(net "M_G_CPU0_SA_DQ<28>")
	)
	(segment
		(start 406.62352 -273.816318)
		(end 406.44064 -273.633438)
		(width 0.18288)
		(layer "In6.Cu")
		(net "M_G_CPU0_SA_DQ<28>")
	)
	(segment
		(start 418.927788 -274.24253)
		(end 417.724336 -274.24253)
		(width 0.18288)
		(layer "In6.Cu")
		(net "M_G_CPU0_SA_DQ<28>")
	)
	(segment
		(start 408.78379 -273.218402)
		(end 407.31694 -273.218402)
		(width 0.18288)
		(layer "In6.Cu")
		(net "M_G_CPU0_SA_DQ<28>")
	)
	(segment
		(start 388.29996 -266.97178)
		(end 387.940296 -266.612116)
		(width 0.088646)
		(layer "In6.Cu")
		(net "M_G_CPU0_SA_DQ<28>")
	)
	(segment
		(start 421.515286 -274.24253)
		(end 419.986968 -274.24253)
		(width 0.18288)
		(layer "In6.Cu")
		(net "M_G_CPU0_SA_DQ<28>")
	)
	(segment
		(start 419.621208 -275.057616)
		(end 419.293548 -275.057616)
		(width 0.18288)
		(layer "In6.Cu")
		(net "M_G_CPU0_SA_DQ<28>")
	)
	(segment
		(start 419.110668 -274.42541)
		(end 418.927788 -274.24253)
		(width 0.18288)
		(layer "In6.Cu")
		(net "M_G_CPU0_SA_DQ<28>")
	)
	(segment
		(start 411.045914 -272.922238)
		(end 410.718254 -272.922238)
		(width 0.18288)
		(layer "In6.Cu")
		(net "M_G_CPU0_SA_DQ<28>")
	)
	(segment
		(start 409.139644 -273.574256)
		(end 408.78379 -273.218402)
		(width 0.18288)
		(layer "In6.Cu")
		(net "M_G_CPU0_SA_DQ<28>")
	)
	(segment
		(start 427.444408 -281.221942)
		(end 426.920914 -281.221942)
		(width 0.18288)
		(layer "In6.Cu")
		(net "M_G_CPU0_SA_DQ<28>")
	)
	(segment
		(start 434.83149 -281.732482)
		(end 431.70475 -281.732482)
		(width 0.18288)
		(layer "In6.Cu")
		(net "M_G_CPU0_SA_DQ<28>")
	)
	(segment
		(start 426.472604 -280.773632)
		(end 426.214032 -280.773632)
		(width 0.18288)
		(layer "In6.Cu")
		(net "M_G_CPU0_SA_DQ<28>")
	)
	(segment
		(start 388.535672 -266.97178)
		(end 388.29996 -266.97178)
		(width 0.088646)
		(layer "In6.Cu")
		(net "M_G_CPU0_SA_DQ<28>")
	)
	(segment
		(start 415.24047 -273.332448)
		(end 414.85439 -273.718528)
		(width 0.18288)
		(layer "In6.Cu")
		(net "M_G_CPU0_SA_DQ<28>")
	)
	(segment
		(start 426.920914 -281.221942)
		(end 426.472604 -280.773632)
		(width 0.18288)
		(layer "In6.Cu")
		(net "M_G_CPU0_SA_DQ<28>")
	)
	(segment
		(start 421.75557 -275.507958)
		(end 421.93845 -275.325078)
		(width 0.18288)
		(layer "In6.Cu")
		(net "M_G_CPU0_SA_DQ<28>")
	)
	(segment
		(start 392.922506 -267.504672)
		(end 390.24306 -266.97178)
		(width 0.18288)
		(layer "In6.Cu")
		(net "M_G_CPU0_SA_DQ<28>")
	)
	(segment
		(start 411.228794 -273.105118)
		(end 411.045914 -272.922238)
		(width 0.18288)
		(layer "In6.Cu")
		(net "M_G_CPU0_SA_DQ<28>")
	)
	(segment
		(start 425.34078 -280.665936)
		(end 425.723558 -280.283158)
		(width 0.18288)
		(layer "In6.Cu")
		(net "M_G_CPU0_SA_DQ<28>")
	)
	(segment
		(start 379.238764 -266.61745)
		(end 379.232922 -266.621006)
		(width 0.088646)
		(layer "In6.Cu")
		(net "M_G_CPU0_SA_DQ<28>")
	)
	(segment
		(start 375.452132 -267.24991)
		(end 374.727216 -266.941808)
		(width 0.088646)
		(layer "In6.Cu")
		(net "M_G_CPU0_SA_DQ<28>")
	)
	(segment
		(start 411.228794 -273.391376)
		(end 411.228794 -273.105118)
		(width 0.18288)
		(layer "In6.Cu")
		(net "M_G_CPU0_SA_DQ<28>")
	)
	(segment
		(start 386.756402 -266.617704)
		(end 386.745988 -266.6238)
		(width 0.088646)
		(layer "In6.Cu")
		(net "M_G_CPU0_SA_DQ<28>")
	)
	(segment
		(start 410.352494 -273.574256)
		(end 409.139644 -273.574256)
		(width 0.18288)
		(layer "In6.Cu")
		(net "M_G_CPU0_SA_DQ<28>")
	)
	(segment
		(start 382.058164 -266.61745)
		(end 382.052322 -266.621006)
		(width 0.088646)
		(layer "In6.Cu")
		(net "M_G_CPU0_SA_DQ<28>")
	)
	(segment
		(start 385.816856 -266.617704)
		(end 385.806442 -266.6238)
		(width 0.088646)
		(layer "In6.Cu")
		(net "M_G_CPU0_SA_DQ<28>")
	)
	(segment
		(start 425.723558 -280.024586)
		(end 425.040552 -279.34158)
		(width 0.18288)
		(layer "In6.Cu")
		(net "M_G_CPU0_SA_DQ<28>")
	)
	(segment
		(start 425.040552 -279.34158)
		(end 424.52544 -279.34158)
		(width 0.18288)
		(layer "In6.Cu")
		(net "M_G_CPU0_SA_DQ<28>")
	)
	(segment
		(start 407.13406 -273.633438)
		(end 406.95118 -273.816318)
		(width 0.18288)
		(layer "In6.Cu")
		(net "M_G_CPU0_SA_DQ<28>")
	)
	(segment
		(start 412.49981 -273.574256)
		(end 411.411674 -273.574256)
		(width 0.18288)
		(layer "In6.Cu")
		(net "M_G_CPU0_SA_DQ<28>")
	)
	(segment
		(start 421.375332 -276.201378)
		(end 421.192452 -276.018498)
		(width 0.18288)
		(layer "In6.Cu")
		(net "M_G_CPU0_SA_DQ<28>")
	)
	(segment
		(start 425.831254 -281.15641)
		(end 425.572682 -281.15641)
		(width 0.18288)
		(layer "In6.Cu")
		(net "M_G_CPU0_SA_DQ<28>")
	)
	(segment
		(start 431.003456 -281.031188)
		(end 427.635162 -281.031188)
		(width 0.18288)
		(layer "In6.Cu")
		(net "M_G_CPU0_SA_DQ<28>")
	)
	(segment
		(start 413.804354 -273.718528)
		(end 413.418274 -273.332448)
		(width 0.18288)
		(layer "In6.Cu")
		(net "M_G_CPU0_SA_DQ<28>")
	)
	(segment
		(start 425.34078 -280.924508)
		(end 425.34078 -280.665936)
		(width 0.18288)
		(layer "In6.Cu")
		(net "M_G_CPU0_SA_DQ<28>")
	)
	(segment
		(start 412.741618 -273.332448)
		(end 412.49981 -273.574256)
		(width 0.18288)
		(layer "In6.Cu")
		(net "M_G_CPU0_SA_DQ<28>")
	)
	(segment
		(start 375.479818 -267.266166)
		(end 375.452132 -267.24991)
		(width 0.088646)
		(layer "In6.Cu")
		(net "M_G_CPU0_SA_DQ<28>")
	)
	(segment
		(start 423.362628 -277.565612)
		(end 422.397174 -277.565612)
		(width 0.18288)
		(layer "In6.Cu")
		(net "M_G_CPU0_SA_DQ<28>")
	)
	(segment
		(start 410.535374 -273.391376)
		(end 410.352494 -273.574256)
		(width 0.18288)
		(layer "In6.Cu")
		(net "M_G_CPU0_SA_DQ<28>")
	)
	(segment
		(start 424.308524 -279.124664)
		(end 424.308524 -278.511508)
		(width 0.18288)
		(layer "In6.Cu")
		(net "M_G_CPU0_SA_DQ<28>")
	)
	(segment
		(start 421.375332 -275.507958)
		(end 421.75557 -275.507958)
		(width 0.18288)
		(layer "In6.Cu")
		(net "M_G_CPU0_SA_DQ<28>")
	)
	(segment
		(start 413.418274 -273.332448)
		(end 412.741618 -273.332448)
		(width 0.18288)
		(layer "In6.Cu")
		(net "M_G_CPU0_SA_DQ<28>")
	)
	(segment
		(start 435.581806 -282.074874)
		(end 435.173882 -282.074874)
		(width 0.18288)
		(layer "In6.Cu")
		(net "M_G_CPU0_SA_DQ<28>")
	)
	(segment
		(start 378.304806 -266.614148)
		(end 378.298964 -266.61745)
		(width 0.088646)
		(layer "In6.Cu")
		(net "M_G_CPU0_SA_DQ<28>")
	)
	(segment
		(start 414.85439 -273.718528)
		(end 413.804354 -273.718528)
		(width 0.18288)
		(layer "In6.Cu")
		(net "M_G_CPU0_SA_DQ<28>")
	)
	(segment
		(start 406.44064 -273.633438)
		(end 406.44064 -273.401282)
		(width 0.18288)
		(layer "In6.Cu")
		(net "M_G_CPU0_SA_DQ<28>")
	)
	(segment
		(start 380.178564 -266.61745)
		(end 380.172722 -266.621006)
		(width 0.088646)
		(layer "In6.Cu")
		(net "M_G_CPU0_SA_DQ<28>")
	)
	(segment
		(start 419.293548 -275.057616)
		(end 419.110668 -274.874736)
		(width 0.18288)
		(layer "In6.Cu")
		(net "M_G_CPU0_SA_DQ<28>")
	)
	(segment
		(start 421.192452 -276.018498)
		(end 421.192452 -275.690838)
		(width 0.18288)
		(layer "In6.Cu")
		(net "M_G_CPU0_SA_DQ<28>")
	)
	(segment
		(start 425.723558 -280.283158)
		(end 425.723558 -280.024586)
		(width 0.18288)
		(layer "In6.Cu")
		(net "M_G_CPU0_SA_DQ<28>")
	)
	(segment
		(start 380.184406 -266.614148)
		(end 380.178564 -266.61745)
		(width 0.088646)
		(layer "In6.Cu")
		(net "M_G_CPU0_SA_DQ<28>")
	)
	(segment
		(start 426.214032 -280.773632)
		(end 425.831254 -281.15641)
		(width 0.18288)
		(layer "In6.Cu")
		(net "M_G_CPU0_SA_DQ<28>")
	)
	(segment
		(start 384.87731 -266.617704)
		(end 384.866896 -266.6238)
		(width 0.088646)
		(layer "In6.Cu")
		(net "M_G_CPU0_SA_DQ<28>")
	)
	(segment
		(start 419.110668 -274.874736)
		(end 419.110668 -274.42541)
		(width 0.18288)
		(layer "In6.Cu")
		(net "M_G_CPU0_SA_DQ<28>")
	)
	(segment
		(start 406.25776 -273.218402)
		(end 405.055832 -273.218402)
		(width 0.18288)
		(layer "In6.Cu")
		(net "M_G_CPU0_SA_DQ<28>")
	)
	(segment
		(start 419.986968 -274.24253)
		(end 419.804088 -274.42541)
		(width 0.18288)
		(layer "In6.Cu")
		(net "M_G_CPU0_SA_DQ<28>")
	)
	(segment
		(start 399.30451 -267.504672)
		(end 392.922506 -267.504672)
		(width 0.18288)
		(layer "In6.Cu")
		(net "M_G_CPU0_SA_DQ<28>")
	)
	(segment
		(start 382.998218 -266.617704)
		(end 382.992122 -266.621006)
		(width 0.088646)
		(layer "In6.Cu")
		(net "M_G_CPU0_SA_DQ<28>")
	)
	(segment
		(start 387.695948 -266.617704)
		(end 387.685534 -266.6238)
		(width 0.088646)
		(layer "In6.Cu")
		(net "M_G_CPU0_SA_DQ<28>")
	)
	(segment
		(start 383.383028 -266.6238)
		(end 383.372614 -266.617704)
		(width 0.088646)
		(layer "In6.Cu")
		(net "M_G_CPU0_SA_DQ<28>")
	)
	(segment
		(start 425.572682 -281.15641)
		(end 425.34078 -280.924508)
		(width 0.18288)
		(layer "In6.Cu")
		(net "M_G_CPU0_SA_DQ<28>")
	)
	(segment
		(start 410.718254 -272.922238)
		(end 410.535374 -273.105118)
		(width 0.18288)
		(layer "In6.Cu")
		(net "M_G_CPU0_SA_DQ<28>")
	)
	(segment
		(start 406.95118 -273.816318)
		(end 406.62352 -273.816318)
		(width 0.18288)
		(layer "In6.Cu")
		(net "M_G_CPU0_SA_DQ<28>")
	)
	(segment
		(start 411.411674 -273.574256)
		(end 411.228794 -273.391376)
		(width 0.18288)
		(layer "In6.Cu")
		(net "M_G_CPU0_SA_DQ<28>")
	)
	(segment
		(start 435.823614 -282.316682)
		(end 435.581806 -282.074874)
		(width 0.18288)
		(layer "In6.Cu")
		(net "M_G_CPU0_SA_DQ<28>")
	)
	(segment
		(start 390.24306 -266.97178)
		(end 388.535672 -266.97178)
		(width 0.18288)
		(layer "In6.Cu")
		(net "M_G_CPU0_SA_DQ<28>")
	)
	(segment
		(start 417.724336 -274.24253)
		(end 416.814254 -273.332448)
		(width 0.18288)
		(layer "In6.Cu")
		(net "M_G_CPU0_SA_DQ<28>")
	)
	(segment
		(start 375.868946 -267.25753)
		(end 375.854214 -267.266166)
		(width 0.088646)
		(layer "In6.Cu")
		(net "M_G_CPU0_SA_DQ<28>")
	)
	(segment
		(start 421.93845 -276.384258)
		(end 421.75557 -276.201378)
		(width 0.18288)
		(layer "In6.Cu")
		(net "M_G_CPU0_SA_DQ<28>")
	)
	(segment
		(start 421.93845 -274.665694)
		(end 421.515286 -274.24253)
		(width 0.18288)
		(layer "In6.Cu")
		(net "M_G_CPU0_SA_DQ<28>")
	)
	(segment
		(start 427.635162 -281.031188)
		(end 427.444408 -281.221942)
		(width 0.18288)
		(layer "In6.Cu")
		(net "M_G_CPU0_SA_DQ<28>")
	)
	(segment
		(start 424.308524 -278.511508)
		(end 423.362628 -277.565612)
		(width 0.18288)
		(layer "In6.Cu")
		(net "M_G_CPU0_SA_DQ<28>")
	)
	(segment
		(start 381.124206 -266.614148)
		(end 381.118364 -266.61745)
		(width 0.088646)
		(layer "In6.Cu")
		(net "M_G_CPU0_SA_DQ<28>")
	)
	(segment
		(start 381.118364 -266.61745)
		(end 381.112522 -266.621006)
		(width 0.088646)
		(layer "In6.Cu")
		(net "M_G_CPU0_SA_DQ<28>")
	)
	(segment
		(start 378.298964 -266.61745)
		(end 378.293122 -266.621006)
		(width 0.088646)
		(layer "In6.Cu")
		(net "M_G_CPU0_SA_DQ<28>")
	)
	(segment
		(start 416.814254 -273.332448)
		(end 415.24047 -273.332448)
		(width 0.18288)
		(layer "In6.Cu")
		(net "M_G_CPU0_SA_DQ<28>")
	)
	(segment
		(start 435.173882 -282.074874)
		(end 434.83149 -281.732482)
		(width 0.18288)
		(layer "In6.Cu")
		(net "M_G_CPU0_SA_DQ<28>")
	)
	(segment
		(start 424.52544 -279.34158)
		(end 424.308524 -279.124664)
		(width 0.18288)
		(layer "In6.Cu")
		(net "M_G_CPU0_SA_DQ<28>")
	)
	(segment
		(start 421.75557 -276.201378)
		(end 421.375332 -276.201378)
		(width 0.18288)
		(layer "In6.Cu")
		(net "M_G_CPU0_SA_DQ<28>")
	)
	(segment
		(start 379.244606 -266.614148)
		(end 379.238764 -266.61745)
		(width 0.088646)
		(layer "In6.Cu")
		(net "M_G_CPU0_SA_DQ<28>")
	)
	(arc
		(start 377.122182 -266.952984)
		(mid 377.084097 -267.043875)
		(end 377.017534 -267.11656)
		(width 0.088646)
		(layer "In6.Cu")
		(net "M_G_CPU0_SA_DQ<28>")
	)
	(arc
		(start 377.194572 -266.813538)
		(mid 377.162918 -266.885618)
		(end 377.122182 -266.952984)
		(width 0.088646)
		(layer "In6.Cu")
		(net "M_G_CPU0_SA_DQ<28>")
	)
	(arc
		(start 387.859016 -266.576556)
		(mid 387.774612 -266.58574)
		(end 387.695948 -266.617704)
		(width 0.088646)
		(layer "In6.Cu")
		(net "M_G_CPU0_SA_DQ<28>")
	)
	(arc
		(start 386.745988 -266.6238)
		(mid 386.46781 -266.693523)
		(end 386.191252 -266.617704)
		(width 0.088646)
		(layer "In6.Cu")
		(net "M_G_CPU0_SA_DQ<28>")
	)
	(arc
		(start 383.937764 -266.617704)
		(mid 383.661205 -266.693447)
		(end 383.383028 -266.6238)
		(width 0.088646)
		(layer "In6.Cu")
		(net "M_G_CPU0_SA_DQ<28>")
	)
	(arc
		(start 377.017534 -267.11656)
		(mid 376.908262 -267.19508)
		(end 376.794014 -267.266166)
		(width 0.088646)
		(layer "In6.Cu")
		(net "M_G_CPU0_SA_DQ<28>")
	)
	(arc
		(start 380.553214 -266.61745)
		(mid 380.36926 -266.567321)
		(end 380.184406 -266.614148)
		(width 0.088646)
		(layer "In6.Cu")
		(net "M_G_CPU0_SA_DQ<28>")
	)
	(arc
		(start 387.130798 -266.617704)
		(mid 386.9436 -266.567527)
		(end 386.756402 -266.617704)
		(width 0.088646)
		(layer "In6.Cu")
		(net "M_G_CPU0_SA_DQ<28>")
	)
	(arc
		(start 375.854214 -267.266166)
		(mid 375.667016 -267.316309)
		(end 375.479818 -267.266166)
		(width 0.088646)
		(layer "In6.Cu")
		(net "M_G_CPU0_SA_DQ<28>")
	)
	(arc
		(start 380.172722 -266.621006)
		(mid 379.892587 -266.693322)
		(end 379.613414 -266.61745)
		(width 0.088646)
		(layer "In6.Cu")
		(net "M_G_CPU0_SA_DQ<28>")
	)
	(arc
		(start 378.293122 -266.621006)
		(mid 378.012987 -266.693322)
		(end 377.733814 -266.61745)
		(width 0.088646)
		(layer "In6.Cu")
		(net "M_G_CPU0_SA_DQ<28>")
	)
	(arc
		(start 376.419618 -267.266166)
		(mid 376.145389 -267.190241)
		(end 375.868946 -267.25753)
		(width 0.088646)
		(layer "In6.Cu")
		(net "M_G_CPU0_SA_DQ<28>")
	)
	(arc
		(start 387.940296 -266.612116)
		(mid 387.903038 -266.586614)
		(end 387.859016 -266.576556)
		(width 0.088646)
		(layer "In6.Cu")
		(net "M_G_CPU0_SA_DQ<28>")
	)
	(arc
		(start 386.191252 -266.617704)
		(mid 386.004054 -266.567527)
		(end 385.816856 -266.617704)
		(width 0.088646)
		(layer "In6.Cu")
		(net "M_G_CPU0_SA_DQ<28>")
	)
	(arc
		(start 382.432814 -266.61745)
		(mid 382.24886 -266.567321)
		(end 382.064006 -266.614148)
		(width 0.088646)
		(layer "In6.Cu")
		(net "M_G_CPU0_SA_DQ<28>")
	)
	(arc
		(start 379.613414 -266.61745)
		(mid 379.42946 -266.567321)
		(end 379.244606 -266.614148)
		(width 0.088646)
		(layer "In6.Cu")
		(net "M_G_CPU0_SA_DQ<28>")
	)
	(arc
		(start 381.112522 -266.621006)
		(mid 380.832387 -266.693322)
		(end 380.553214 -266.61745)
		(width 0.088646)
		(layer "In6.Cu")
		(net "M_G_CPU0_SA_DQ<28>")
	)
	(arc
		(start 377.352052 -266.621514)
		(mid 377.25696 -266.704109)
		(end 377.194572 -266.813538)
		(width 0.088646)
		(layer "In6.Cu")
		(net "M_G_CPU0_SA_DQ<28>")
	)
	(arc
		(start 377.733814 -266.61745)
		(mid 377.542376 -266.567201)
		(end 377.352052 -266.621514)
		(width 0.088646)
		(layer "In6.Cu")
		(net "M_G_CPU0_SA_DQ<28>")
	)
	(arc
		(start 379.232922 -266.621006)
		(mid 378.952787 -266.693322)
		(end 378.673614 -266.61745)
		(width 0.088646)
		(layer "In6.Cu")
		(net "M_G_CPU0_SA_DQ<28>")
	)
	(arc
		(start 378.673614 -266.61745)
		(mid 378.48966 -266.567321)
		(end 378.304806 -266.614148)
		(width 0.088646)
		(layer "In6.Cu")
		(net "M_G_CPU0_SA_DQ<28>")
	)
	(arc
		(start 383.372614 -266.617704)
		(mid 383.185416 -266.567527)
		(end 382.998218 -266.617704)
		(width 0.088646)
		(layer "In6.Cu")
		(net "M_G_CPU0_SA_DQ<28>")
	)
	(arc
		(start 382.992122 -266.621006)
		(mid 382.711987 -266.693322)
		(end 382.432814 -266.61745)
		(width 0.088646)
		(layer "In6.Cu")
		(net "M_G_CPU0_SA_DQ<28>")
	)
	(arc
		(start 381.493014 -266.61745)
		(mid 381.30906 -266.567321)
		(end 381.124206 -266.614148)
		(width 0.088646)
		(layer "In6.Cu")
		(net "M_G_CPU0_SA_DQ<28>")
	)
	(arc
		(start 376.794014 -267.266166)
		(mid 376.606816 -267.316309)
		(end 376.419618 -267.266166)
		(width 0.088646)
		(layer "In6.Cu")
		(net "M_G_CPU0_SA_DQ<28>")
	)
	(arc
		(start 385.806442 -266.6238)
		(mid 385.528264 -266.693523)
		(end 385.251706 -266.617704)
		(width 0.088646)
		(layer "In6.Cu")
		(net "M_G_CPU0_SA_DQ<28>")
	)
	(arc
		(start 382.052322 -266.621006)
		(mid 381.772187 -266.693322)
		(end 381.493014 -266.61745)
		(width 0.088646)
		(layer "In6.Cu")
		(net "M_G_CPU0_SA_DQ<28>")
	)
	(arc
		(start 387.685534 -266.6238)
		(mid 387.407356 -266.693523)
		(end 387.130798 -266.617704)
		(width 0.088646)
		(layer "In6.Cu")
		(net "M_G_CPU0_SA_DQ<28>")
	)
	(arc
		(start 385.251706 -266.617704)
		(mid 385.064508 -266.567527)
		(end 384.87731 -266.617704)
		(width 0.088646)
		(layer "In6.Cu")
		(net "M_G_CPU0_SA_DQ<28>")
	)
	(arc
		(start 384.31216 -266.617704)
		(mid 384.124962 -266.567527)
		(end 383.937764 -266.617704)
		(width 0.088646)
		(layer "In6.Cu")
		(net "M_G_CPU0_SA_DQ<28>")
	)
	(arc
		(start 384.866896 -266.6238)
		(mid 384.588718 -266.693523)
		(end 384.31216 -266.617704)
		(width 0.088646)
		(layer "In6.Cu")
		(net "M_G_CPU0_SA_DQ<28>")
	)
	(segment
		(start 446.986152 -285.464758)
		(end 447.23812 -285.716726)
		(width 0.20066)
		(layer "F.Cu")
		(net "M_G_CPU0_SA_DQ<27>")
	)
	(segment
		(start 443.462664 -286.141668)
		(end 445.470534 -286.141668)
		(width 0.1016)
		(layer "F.Cu")
		(net "M_G_CPU0_SA_DQ<27>")
	)
	(segment
		(start 443.455552 -286.14878)
		(end 443.462664 -286.141668)
		(width 0.1016)
		(layer "F.Cu")
		(net "M_G_CPU0_SA_DQ<27>")
	)
	(segment
		(start 446.367916 -285.698946)
		(end 446.602104 -285.464758)
		(width 0.20066)
		(layer "F.Cu")
		(net "M_G_CPU0_SA_DQ<27>")
	)
	(segment
		(start 439.923682 -285.716726)
		(end 441.028582 -285.716726)
		(width 0.20066)
		(layer "F.Cu")
		(net "M_G_CPU0_SA_DQ<27>")
	)
	(segment
		(start 445.470534 -286.141668)
		(end 445.482726 -286.15386)
		(width 0.1016)
		(layer "F.Cu")
		(net "M_G_CPU0_SA_DQ<27>")
	)
	(segment
		(start 441.028582 -285.716726)
		(end 442.726826 -285.716726)
		(width 0.20066)
		(layer "F.Cu")
		(net "M_G_CPU0_SA_DQ<27>")
	)
	(segment
		(start 443.450726 -286.14878)
		(end 443.455552 -286.14878)
		(width 0.101854)
		(layer "F.Cu")
		(net "M_G_CPU0_SA_DQ<27>")
	)
	(segment
		(start 446.602104 -285.464758)
		(end 446.986152 -285.464758)
		(width 0.20066)
		(layer "F.Cu")
		(net "M_G_CPU0_SA_DQ<27>")
	)
	(segment
		(start 443.15888 -286.14878)
		(end 443.450726 -286.14878)
		(width 0.20066)
		(layer "F.Cu")
		(net "M_G_CPU0_SA_DQ<27>")
	)
	(segment
		(start 446.367916 -285.949898)
		(end 446.367916 -285.698946)
		(width 0.20066)
		(layer "F.Cu")
		(net "M_G_CPU0_SA_DQ<27>")
	)
	(segment
		(start 446.163954 -286.15386)
		(end 446.367916 -285.949898)
		(width 0.20066)
		(layer "F.Cu")
		(net "M_G_CPU0_SA_DQ<27>")
	)
	(segment
		(start 445.482726 -286.15386)
		(end 446.163954 -286.15386)
		(width 0.20066)
		(layer "F.Cu")
		(net "M_G_CPU0_SA_DQ<27>")
	)
	(segment
		(start 376.606562 -268.56944)
		(end 376.606816 -268.569694)
		(width 0.20066)
		(layer "F.Cu")
		(net "M_G_CPU0_SA_DQ<27>")
	)
	(segment
		(start 447.23812 -285.716726)
		(end 448.572382 -285.716726)
		(width 0.20066)
		(layer "F.Cu")
		(net "M_G_CPU0_SA_DQ<27>")
	)
	(segment
		(start 376.606562 -268.033754)
		(end 376.606562 -268.56944)
		(width 0.20066)
		(layer "F.Cu")
		(net "M_G_CPU0_SA_DQ<27>")
	)
	(segment
		(start 442.726826 -285.716726)
		(end 443.15888 -286.14878)
		(width 0.20066)
		(layer "F.Cu")
		(net "M_G_CPU0_SA_DQ<27>")
	)
	(segment
		(start 418.711634 -280.063194)
		(end 418.479732 -279.831292)
		(width 0.18288)
		(layer "In6.Cu")
		(net "M_G_CPU0_SA_DQ<27>")
	)
	(segment
		(start 392.67257 -269.61973)
		(end 390.040368 -269.096236)
		(width 0.18288)
		(layer "In6.Cu")
		(net "M_G_CPU0_SA_DQ<27>")
	)
	(segment
		(start 388.126224 -269.096236)
		(end 387.957822 -268.979396)
		(width 0.088646)
		(layer "In6.Cu")
		(net "M_G_CPU0_SA_DQ<27>")
	)
	(segment
		(start 416.059366 -278.508206)
		(end 413.03067 -278.508206)
		(width 0.18288)
		(layer "In6.Cu")
		(net "M_G_CPU0_SA_DQ<27>")
	)
	(segment
		(start 436.889398 -285.292292)
		(end 434.919882 -285.292292)
		(width 0.18288)
		(layer "In6.Cu")
		(net "M_G_CPU0_SA_DQ<27>")
	)
	(segment
		(start 413.03067 -278.508206)
		(end 412.195264 -277.6728)
		(width 0.18288)
		(layer "In6.Cu")
		(net "M_G_CPU0_SA_DQ<27>")
	)
	(segment
		(start 418.22116 -279.831292)
		(end 417.931092 -280.12136)
		(width 0.18288)
		(layer "In6.Cu")
		(net "M_G_CPU0_SA_DQ<27>")
	)
	(segment
		(start 439.923682 -285.716726)
		(end 439.240676 -286.399732)
		(width 0.18288)
		(layer "In6.Cu")
		(net "M_G_CPU0_SA_DQ<27>")
	)
	(segment
		(start 437.996838 -286.399732)
		(end 436.889398 -285.292292)
		(width 0.18288)
		(layer "In6.Cu")
		(net "M_G_CPU0_SA_DQ<27>")
	)
	(segment
		(start 382.447546 -268.885416)
		(end 382.432814 -268.894052)
		(width 0.088646)
		(layer "In6.Cu")
		(net "M_G_CPU0_SA_DQ<27>")
	)
	(segment
		(start 429.381412 -285.232348)
		(end 428.471838 -286.141922)
		(width 0.18288)
		(layer "In6.Cu")
		(net "M_G_CPU0_SA_DQ<27>")
	)
	(segment
		(start 377.359418 -268.894052)
		(end 377.330716 -268.877288)
		(width 0.088646)
		(layer "In6.Cu")
		(net "M_G_CPU0_SA_DQ<27>")
	)
	(segment
		(start 383.383028 -268.887956)
		(end 383.372614 -268.894052)
		(width 0.088646)
		(layer "In6.Cu")
		(net "M_G_CPU0_SA_DQ<27>")
	)
	(segment
		(start 386.201666 -268.887956)
		(end 386.191252 -268.894052)
		(width 0.088646)
		(layer "In6.Cu")
		(net "M_G_CPU0_SA_DQ<27>")
	)
	(segment
		(start 427.523402 -286.141922)
		(end 427.340522 -285.959042)
		(width 0.18288)
		(layer "In6.Cu")
		(net "M_G_CPU0_SA_DQ<27>")
	)
	(segment
		(start 377.748546 -268.885416)
		(end 377.733814 -268.894052)
		(width 0.088646)
		(layer "In6.Cu")
		(net "M_G_CPU0_SA_DQ<27>")
	)
	(segment
		(start 421.510968 -282.280106)
		(end 421.123872 -281.89301)
		(width 0.18288)
		(layer "In6.Cu")
		(net "M_G_CPU0_SA_DQ<27>")
	)
	(segment
		(start 427.157642 -285.323788)
		(end 426.829982 -285.323788)
		(width 0.18288)
		(layer "In6.Cu")
		(net "M_G_CPU0_SA_DQ<27>")
	)
	(segment
		(start 426.647102 -285.959042)
		(end 426.464222 -286.141922)
		(width 0.18288)
		(layer "In6.Cu")
		(net "M_G_CPU0_SA_DQ<27>")
	)
	(segment
		(start 434.919882 -285.292292)
		(end 434.678582 -285.533592)
		(width 0.18288)
		(layer "In6.Cu")
		(net "M_G_CPU0_SA_DQ<27>")
	)
	(segment
		(start 433.752244 -285.12262)
		(end 433.27955 -285.12262)
		(width 0.18288)
		(layer "In6.Cu")
		(net "M_G_CPU0_SA_DQ<27>")
	)
	(segment
		(start 427.340522 -285.506668)
		(end 427.157642 -285.323788)
		(width 0.18288)
		(layer "In6.Cu")
		(net "M_G_CPU0_SA_DQ<27>")
	)
	(segment
		(start 426.464222 -286.141922)
		(end 424.023536 -286.141922)
		(width 0.18288)
		(layer "In6.Cu")
		(net "M_G_CPU0_SA_DQ<27>")
	)
	(segment
		(start 418.421566 -280.870406)
		(end 418.421566 -280.611834)
		(width 0.18288)
		(layer "In6.Cu")
		(net "M_G_CPU0_SA_DQ<27>")
	)
	(segment
		(start 412.195264 -277.6728)
		(end 409.343352 -277.6728)
		(width 0.18288)
		(layer "In6.Cu")
		(net "M_G_CPU0_SA_DQ<27>")
	)
	(segment
		(start 432.995578 -285.406592)
		(end 432.119024 -285.406592)
		(width 0.18288)
		(layer "In6.Cu")
		(net "M_G_CPU0_SA_DQ<27>")
	)
	(segment
		(start 439.240676 -286.399732)
		(end 437.996838 -286.399732)
		(width 0.18288)
		(layer "In6.Cu")
		(net "M_G_CPU0_SA_DQ<27>")
	)
	(segment
		(start 387.141212 -268.887956)
		(end 387.130798 -268.894052)
		(width 0.088646)
		(layer "In6.Cu")
		(net "M_G_CPU0_SA_DQ<27>")
	)
	(segment
		(start 408.519376 -276.848824)
		(end 405.51608 -276.848824)
		(width 0.18288)
		(layer "In6.Cu")
		(net "M_G_CPU0_SA_DQ<27>")
	)
	(segment
		(start 418.479732 -279.831292)
		(end 418.22116 -279.831292)
		(width 0.18288)
		(layer "In6.Cu")
		(net "M_G_CPU0_SA_DQ<27>")
	)
	(segment
		(start 432.119024 -285.406592)
		(end 431.94478 -285.232348)
		(width 0.18288)
		(layer "In6.Cu")
		(net "M_G_CPU0_SA_DQ<27>")
	)
	(segment
		(start 420.245794 -281.89301)
		(end 419.640258 -281.287474)
		(width 0.18288)
		(layer "In6.Cu")
		(net "M_G_CPU0_SA_DQ<27>")
	)
	(segment
		(start 379.628146 -268.885416)
		(end 379.613414 -268.894052)
		(width 0.088646)
		(layer "In6.Cu")
		(net "M_G_CPU0_SA_DQ<27>")
	)
	(segment
		(start 378.688346 -268.885416)
		(end 378.673614 -268.894052)
		(width 0.088646)
		(layer "In6.Cu")
		(net "M_G_CPU0_SA_DQ<27>")
	)
	(segment
		(start 434.678582 -285.533592)
		(end 434.163216 -285.533592)
		(width 0.18288)
		(layer "In6.Cu")
		(net "M_G_CPU0_SA_DQ<27>")
	)
	(segment
		(start 417.67252 -280.12136)
		(end 416.059366 -278.508206)
		(width 0.18288)
		(layer "In6.Cu")
		(net "M_G_CPU0_SA_DQ<27>")
	)
	(segment
		(start 390.040368 -269.096236)
		(end 388.535672 -269.096236)
		(width 0.18288)
		(layer "In6.Cu")
		(net "M_G_CPU0_SA_DQ<27>")
	)
	(segment
		(start 419.640258 -281.287474)
		(end 418.838634 -281.287474)
		(width 0.18288)
		(layer "In6.Cu")
		(net "M_G_CPU0_SA_DQ<27>")
	)
	(segment
		(start 417.931092 -280.12136)
		(end 417.67252 -280.12136)
		(width 0.18288)
		(layer "In6.Cu")
		(net "M_G_CPU0_SA_DQ<27>")
	)
	(segment
		(start 405.51608 -276.848824)
		(end 398.286986 -269.61973)
		(width 0.18288)
		(layer "In6.Cu")
		(net "M_G_CPU0_SA_DQ<27>")
	)
	(segment
		(start 384.87731 -268.894052)
		(end 384.866896 -268.887956)
		(width 0.088646)
		(layer "In6.Cu")
		(net "M_G_CPU0_SA_DQ<27>")
	)
	(segment
		(start 409.343352 -277.6728)
		(end 408.519376 -276.848824)
		(width 0.18288)
		(layer "In6.Cu")
		(net "M_G_CPU0_SA_DQ<27>")
	)
	(segment
		(start 377.330716 -268.877288)
		(end 376.606816 -268.569694)
		(width 0.088646)
		(layer "In6.Cu")
		(net "M_G_CPU0_SA_DQ<27>")
	)
	(segment
		(start 388.535672 -269.096236)
		(end 388.126224 -269.096236)
		(width 0.088646)
		(layer "In6.Cu")
		(net "M_G_CPU0_SA_DQ<27>")
	)
	(segment
		(start 424.023536 -286.141922)
		(end 421.510968 -283.629354)
		(width 0.18288)
		(layer "In6.Cu")
		(net "M_G_CPU0_SA_DQ<27>")
	)
	(segment
		(start 426.647102 -285.506668)
		(end 426.647102 -285.959042)
		(width 0.18288)
		(layer "In6.Cu")
		(net "M_G_CPU0_SA_DQ<27>")
	)
	(segment
		(start 418.421566 -280.611834)
		(end 418.711634 -280.321766)
		(width 0.18288)
		(layer "In6.Cu")
		(net "M_G_CPU0_SA_DQ<27>")
	)
	(segment
		(start 428.471838 -286.141922)
		(end 427.523402 -286.141922)
		(width 0.18288)
		(layer "In6.Cu")
		(net "M_G_CPU0_SA_DQ<27>")
	)
	(segment
		(start 433.27955 -285.12262)
		(end 432.995578 -285.406592)
		(width 0.18288)
		(layer "In6.Cu")
		(net "M_G_CPU0_SA_DQ<27>")
	)
	(segment
		(start 431.94478 -285.232348)
		(end 429.381412 -285.232348)
		(width 0.18288)
		(layer "In6.Cu")
		(net "M_G_CPU0_SA_DQ<27>")
	)
	(segment
		(start 421.510968 -283.629354)
		(end 421.510968 -282.280106)
		(width 0.18288)
		(layer "In6.Cu")
		(net "M_G_CPU0_SA_DQ<27>")
	)
	(segment
		(start 426.829982 -285.323788)
		(end 426.647102 -285.506668)
		(width 0.18288)
		(layer "In6.Cu")
		(net "M_G_CPU0_SA_DQ<27>")
	)
	(segment
		(start 385.26212 -268.887956)
		(end 385.251706 -268.894052)
		(width 0.088646)
		(layer "In6.Cu")
		(net "M_G_CPU0_SA_DQ<27>")
	)
	(segment
		(start 418.838634 -281.287474)
		(end 418.421566 -280.870406)
		(width 0.18288)
		(layer "In6.Cu")
		(net "M_G_CPU0_SA_DQ<27>")
	)
	(segment
		(start 434.163216 -285.533592)
		(end 433.752244 -285.12262)
		(width 0.18288)
		(layer "In6.Cu")
		(net "M_G_CPU0_SA_DQ<27>")
	)
	(segment
		(start 381.507746 -268.885416)
		(end 381.493014 -268.894052)
		(width 0.088646)
		(layer "In6.Cu")
		(net "M_G_CPU0_SA_DQ<27>")
	)
	(segment
		(start 398.286986 -269.61973)
		(end 392.67257 -269.61973)
		(width 0.18288)
		(layer "In6.Cu")
		(net "M_G_CPU0_SA_DQ<27>")
	)
	(segment
		(start 427.340522 -285.959042)
		(end 427.340522 -285.506668)
		(width 0.18288)
		(layer "In6.Cu")
		(net "M_G_CPU0_SA_DQ<27>")
	)
	(segment
		(start 418.711634 -280.321766)
		(end 418.711634 -280.063194)
		(width 0.18288)
		(layer "In6.Cu")
		(net "M_G_CPU0_SA_DQ<27>")
	)
	(segment
		(start 421.123872 -281.89301)
		(end 420.245794 -281.89301)
		(width 0.18288)
		(layer "In6.Cu")
		(net "M_G_CPU0_SA_DQ<27>")
	)
	(arc
		(start 379.239018 -268.894052)
		(mid 378.964819 -268.818217)
		(end 378.688346 -268.885416)
		(width 0.088646)
		(layer "In6.Cu")
		(net "M_G_CPU0_SA_DQ<27>")
	)
	(arc
		(start 383.937764 -268.894052)
		(mid 383.661205 -268.818309)
		(end 383.383028 -268.887956)
		(width 0.088646)
		(layer "In6.Cu")
		(net "M_G_CPU0_SA_DQ<27>")
	)
	(arc
		(start 381.493014 -268.894052)
		(mid 381.305816 -268.944195)
		(end 381.118618 -268.894052)
		(width 0.088646)
		(layer "In6.Cu")
		(net "M_G_CPU0_SA_DQ<27>")
	)
	(arc
		(start 382.998218 -268.894052)
		(mid 382.724019 -268.818217)
		(end 382.447546 -268.885416)
		(width 0.088646)
		(layer "In6.Cu")
		(net "M_G_CPU0_SA_DQ<27>")
	)
	(arc
		(start 379.613414 -268.894052)
		(mid 379.426216 -268.944195)
		(end 379.239018 -268.894052)
		(width 0.088646)
		(layer "In6.Cu")
		(net "M_G_CPU0_SA_DQ<27>")
	)
	(arc
		(start 385.816856 -268.894052)
		(mid 385.540297 -268.818309)
		(end 385.26212 -268.887956)
		(width 0.088646)
		(layer "In6.Cu")
		(net "M_G_CPU0_SA_DQ<27>")
	)
	(arc
		(start 384.31216 -268.894052)
		(mid 384.124962 -268.944195)
		(end 383.937764 -268.894052)
		(width 0.088646)
		(layer "In6.Cu")
		(net "M_G_CPU0_SA_DQ<27>")
	)
	(arc
		(start 387.695948 -268.894052)
		(mid 387.419389 -268.818309)
		(end 387.141212 -268.887956)
		(width 0.088646)
		(layer "In6.Cu")
		(net "M_G_CPU0_SA_DQ<27>")
	)
	(arc
		(start 380.178818 -268.894052)
		(mid 379.904619 -268.818217)
		(end 379.628146 -268.885416)
		(width 0.088646)
		(layer "In6.Cu")
		(net "M_G_CPU0_SA_DQ<27>")
	)
	(arc
		(start 378.299218 -268.894052)
		(mid 378.025019 -268.818217)
		(end 377.748546 -268.885416)
		(width 0.088646)
		(layer "In6.Cu")
		(net "M_G_CPU0_SA_DQ<27>")
	)
	(arc
		(start 387.957822 -268.979396)
		(mid 387.913347 -268.976429)
		(end 387.869684 -268.967458)
		(width 0.088646)
		(layer "In6.Cu")
		(net "M_G_CPU0_SA_DQ<27>")
	)
	(arc
		(start 385.251706 -268.894052)
		(mid 385.064508 -268.944195)
		(end 384.87731 -268.894052)
		(width 0.088646)
		(layer "In6.Cu")
		(net "M_G_CPU0_SA_DQ<27>")
	)
	(arc
		(start 382.432814 -268.894052)
		(mid 382.245616 -268.944195)
		(end 382.058418 -268.894052)
		(width 0.088646)
		(layer "In6.Cu")
		(net "M_G_CPU0_SA_DQ<27>")
	)
	(arc
		(start 380.553214 -268.894052)
		(mid 380.366016 -268.944195)
		(end 380.178818 -268.894052)
		(width 0.088646)
		(layer "In6.Cu")
		(net "M_G_CPU0_SA_DQ<27>")
	)
	(arc
		(start 383.372614 -268.894052)
		(mid 383.185416 -268.944195)
		(end 382.998218 -268.894052)
		(width 0.088646)
		(layer "In6.Cu")
		(net "M_G_CPU0_SA_DQ<27>")
	)
	(arc
		(start 386.756402 -268.894052)
		(mid 386.479843 -268.818309)
		(end 386.201666 -268.887956)
		(width 0.088646)
		(layer "In6.Cu")
		(net "M_G_CPU0_SA_DQ<27>")
	)
	(arc
		(start 378.673614 -268.894052)
		(mid 378.486416 -268.944195)
		(end 378.299218 -268.894052)
		(width 0.088646)
		(layer "In6.Cu")
		(net "M_G_CPU0_SA_DQ<27>")
	)
	(arc
		(start 381.118618 -268.894052)
		(mid 380.835916 -268.818276)
		(end 380.553214 -268.894052)
		(width 0.088646)
		(layer "In6.Cu")
		(net "M_G_CPU0_SA_DQ<27>")
	)
	(arc
		(start 377.733814 -268.894052)
		(mid 377.546616 -268.944195)
		(end 377.359418 -268.894052)
		(width 0.088646)
		(layer "In6.Cu")
		(net "M_G_CPU0_SA_DQ<27>")
	)
	(arc
		(start 386.191252 -268.894052)
		(mid 386.004054 -268.944195)
		(end 385.816856 -268.894052)
		(width 0.088646)
		(layer "In6.Cu")
		(net "M_G_CPU0_SA_DQ<27>")
	)
	(arc
		(start 384.866896 -268.887956)
		(mid 384.588718 -268.818233)
		(end 384.31216 -268.894052)
		(width 0.088646)
		(layer "In6.Cu")
		(net "M_G_CPU0_SA_DQ<27>")
	)
	(arc
		(start 387.130798 -268.894052)
		(mid 386.9436 -268.944195)
		(end 386.756402 -268.894052)
		(width 0.088646)
		(layer "In6.Cu")
		(net "M_G_CPU0_SA_DQ<27>")
	)
	(arc
		(start 387.869684 -268.967458)
		(mid 387.780471 -268.936304)
		(end 387.695948 -268.894052)
		(width 0.088646)
		(layer "In6.Cu")
		(net "M_G_CPU0_SA_DQ<27>")
	)
	(arc
		(start 382.058418 -268.894052)
		(mid 381.784219 -268.818217)
		(end 381.507746 -268.885416)
		(width 0.088646)
		(layer "In6.Cu")
		(net "M_G_CPU0_SA_DQ<27>")
	)
	(segment
		(start 439.923682 -287.416748)
		(end 441.028582 -287.416748)
		(width 0.20066)
		(layer "F.Cu")
		(net "M_G_CPU0_SA_DQ<26>")
	)
	(segment
		(start 442.726826 -287.416748)
		(end 443.15888 -287.848802)
		(width 0.20066)
		(layer "F.Cu")
		(net "M_G_CPU0_SA_DQ<26>")
	)
	(segment
		(start 443.450726 -287.848802)
		(end 443.455552 -287.848802)
		(width 0.101854)
		(layer "F.Cu")
		(net "M_G_CPU0_SA_DQ<26>")
	)
	(segment
		(start 443.462664 -287.84169)
		(end 445.470534 -287.84169)
		(width 0.1016)
		(layer "F.Cu")
		(net "M_G_CPU0_SA_DQ<26>")
	)
	(segment
		(start 446.367916 -287.64992)
		(end 446.367916 -287.398968)
		(width 0.20066)
		(layer "F.Cu")
		(net "M_G_CPU0_SA_DQ<26>")
	)
	(segment
		(start 447.23812 -287.416748)
		(end 448.572382 -287.416748)
		(width 0.20066)
		(layer "F.Cu")
		(net "M_G_CPU0_SA_DQ<26>")
	)
	(segment
		(start 446.986152 -287.16478)
		(end 447.23812 -287.416748)
		(width 0.20066)
		(layer "F.Cu")
		(net "M_G_CPU0_SA_DQ<26>")
	)
	(segment
		(start 446.163954 -287.853882)
		(end 446.367916 -287.64992)
		(width 0.20066)
		(layer "F.Cu")
		(net "M_G_CPU0_SA_DQ<26>")
	)
	(segment
		(start 376.136916 -269.383256)
		(end 376.136662 -269.38351)
		(width 0.20066)
		(layer "F.Cu")
		(net "M_G_CPU0_SA_DQ<26>")
	)
	(segment
		(start 441.028582 -287.416748)
		(end 442.726826 -287.416748)
		(width 0.20066)
		(layer "F.Cu")
		(net "M_G_CPU0_SA_DQ<26>")
	)
	(segment
		(start 443.455552 -287.848802)
		(end 443.462664 -287.84169)
		(width 0.1016)
		(layer "F.Cu")
		(net "M_G_CPU0_SA_DQ<26>")
	)
	(segment
		(start 445.470534 -287.84169)
		(end 445.482726 -287.853882)
		(width 0.1016)
		(layer "F.Cu")
		(net "M_G_CPU0_SA_DQ<26>")
	)
	(segment
		(start 443.15888 -287.848802)
		(end 443.450726 -287.848802)
		(width 0.20066)
		(layer "F.Cu")
		(net "M_G_CPU0_SA_DQ<26>")
	)
	(segment
		(start 446.602104 -287.16478)
		(end 446.986152 -287.16478)
		(width 0.20066)
		(layer "F.Cu")
		(net "M_G_CPU0_SA_DQ<26>")
	)
	(segment
		(start 446.367916 -287.398968)
		(end 446.602104 -287.16478)
		(width 0.20066)
		(layer "F.Cu")
		(net "M_G_CPU0_SA_DQ<26>")
	)
	(segment
		(start 376.136916 -268.84757)
		(end 376.136916 -269.383256)
		(width 0.20066)
		(layer "F.Cu")
		(net "M_G_CPU0_SA_DQ<26>")
	)
	(segment
		(start 445.482726 -287.853882)
		(end 446.163954 -287.853882)
		(width 0.20066)
		(layer "F.Cu")
		(net "M_G_CPU0_SA_DQ<26>")
	)
	(segment
		(start 406.327102 -278.538178)
		(end 405.493474 -278.538178)
		(width 0.18288)
		(layer "In6.Cu")
		(net "M_G_CPU0_SA_DQ<26>")
	)
	(segment
		(start 416.245548 -281.187144)
		(end 415.539682 -280.481278)
		(width 0.18288)
		(layer "In6.Cu")
		(net "M_G_CPU0_SA_DQ<26>")
	)
	(segment
		(start 439.577734 -287.316672)
		(end 438.456578 -286.992314)
		(width 0.18288)
		(layer "In6.Cu")
		(net "M_G_CPU0_SA_DQ<26>")
	)
	(segment
		(start 427.404276 -287.676844)
		(end 425.310554 -287.676844)
		(width 0.18288)
		(layer "In6.Cu")
		(net "M_G_CPU0_SA_DQ<26>")
	)
	(segment
		(start 429.736504 -287.739328)
		(end 429.576484 -287.579308)
		(width 0.18288)
		(layer "In6.Cu")
		(net "M_G_CPU0_SA_DQ<26>")
	)
	(segment
		(start 418.001958 -282.8671)
		(end 417.022026 -282.8671)
		(width 0.18288)
		(layer "In6.Cu")
		(net "M_G_CPU0_SA_DQ<26>")
	)
	(segment
		(start 411.037532 -279.235408)
		(end 410.639514 -279.235408)
		(width 0.18288)
		(layer "In6.Cu")
		(net "M_G_CPU0_SA_DQ<26>")
	)
	(segment
		(start 387.906006 -269.758668)
		(end 387.414516 -269.758668)
		(width 0.088646)
		(layer "In6.Cu")
		(net "M_G_CPU0_SA_DQ<26>")
	)
	(segment
		(start 421.186356 -286.140398)
		(end 419.57498 -286.140398)
		(width 0.18288)
		(layer "In6.Cu")
		(net "M_G_CPU0_SA_DQ<26>")
	)
	(segment
		(start 390.053068 -270.123412)
		(end 388.535672 -270.123412)
		(width 0.18288)
		(layer "In6.Cu")
		(net "M_G_CPU0_SA_DQ<26>")
	)
	(segment
		(start 418.969444 -283.834586)
		(end 418.001958 -282.8671)
		(width 0.18288)
		(layer "In6.Cu")
		(net "M_G_CPU0_SA_DQ<26>")
	)
	(segment
		(start 410.369512 -279.50541)
		(end 409.521406 -279.50541)
		(width 0.18288)
		(layer "In6.Cu")
		(net "M_G_CPU0_SA_DQ<26>")
	)
	(segment
		(start 386.287264 -269.707868)
		(end 386.272532 -269.699232)
		(width 0.088646)
		(layer "In6.Cu")
		(net "M_G_CPU0_SA_DQ<26>")
	)
	(segment
		(start 417.022026 -282.8671)
		(end 416.245548 -282.090622)
		(width 0.18288)
		(layer "In6.Cu")
		(net "M_G_CPU0_SA_DQ<26>")
	)
	(segment
		(start 432.076352 -286.992314)
		(end 431.02784 -288.040826)
		(width 0.18288)
		(layer "In6.Cu")
		(net "M_G_CPU0_SA_DQ<26>")
	)
	(segment
		(start 429.043084 -287.739328)
		(end 429.043084 -287.880806)
		(width 0.18288)
		(layer "In6.Cu")
		(net "M_G_CPU0_SA_DQ<26>")
	)
	(segment
		(start 429.043084 -287.880806)
		(end 428.883064 -288.040826)
		(width 0.18288)
		(layer "In6.Cu")
		(net "M_G_CPU0_SA_DQ<26>")
	)
	(segment
		(start 376.860054 -269.69085)
		(end 376.136662 -269.38351)
		(width 0.088646)
		(layer "In6.Cu")
		(net "M_G_CPU0_SA_DQ<26>")
	)
	(segment
		(start 428.883064 -288.040826)
		(end 427.768258 -288.040826)
		(width 0.18288)
		(layer "In6.Cu")
		(net "M_G_CPU0_SA_DQ<26>")
	)
	(segment
		(start 416.245548 -282.090622)
		(end 416.245548 -281.187144)
		(width 0.18288)
		(layer "In6.Cu")
		(net "M_G_CPU0_SA_DQ<26>")
	)
	(segment
		(start 422.597072 -287.843722)
		(end 421.85209 -287.09874)
		(width 0.18288)
		(layer "In6.Cu")
		(net "M_G_CPU0_SA_DQ<26>")
	)
	(segment
		(start 425.310554 -287.676844)
		(end 425.143676 -287.843722)
		(width 0.18288)
		(layer "In6.Cu")
		(net "M_G_CPU0_SA_DQ<26>")
	)
	(segment
		(start 419.57498 -286.140398)
		(end 418.969444 -285.534862)
		(width 0.18288)
		(layer "In6.Cu")
		(net "M_G_CPU0_SA_DQ<26>")
	)
	(segment
		(start 407.020522 -277.847552)
		(end 406.692862 -277.847552)
		(width 0.18288)
		(layer "In6.Cu")
		(net "M_G_CPU0_SA_DQ<26>")
	)
	(segment
		(start 377.829064 -269.707868)
		(end 377.814332 -269.699232)
		(width 0.088646)
		(layer "In6.Cu")
		(net "M_G_CPU0_SA_DQ<26>")
	)
	(segment
		(start 392.750294 -270.65986)
		(end 390.053068 -270.123412)
		(width 0.18288)
		(layer "In6.Cu")
		(net "M_G_CPU0_SA_DQ<26>")
	)
	(segment
		(start 384.407664 -269.707868)
		(end 384.392932 -269.699232)
		(width 0.088646)
		(layer "In6.Cu")
		(net "M_G_CPU0_SA_DQ<26>")
	)
	(segment
		(start 388.535672 -270.123412)
		(end 388.27075 -270.123412)
		(width 0.088646)
		(layer "In6.Cu")
		(net "M_G_CPU0_SA_DQ<26>")
	)
	(segment
		(start 388.27075 -270.123412)
		(end 387.906006 -269.758668)
		(width 0.088646)
		(layer "In6.Cu")
		(net "M_G_CPU0_SA_DQ<26>")
	)
	(segment
		(start 397.615156 -270.65986)
		(end 392.750294 -270.65986)
		(width 0.18288)
		(layer "In6.Cu")
		(net "M_G_CPU0_SA_DQ<26>")
	)
	(segment
		(start 429.576484 -287.579308)
		(end 429.203104 -287.579308)
		(width 0.18288)
		(layer "In6.Cu")
		(net "M_G_CPU0_SA_DQ<26>")
	)
	(segment
		(start 438.456578 -286.992314)
		(end 432.076352 -286.992314)
		(width 0.18288)
		(layer "In6.Cu")
		(net "M_G_CPU0_SA_DQ<26>")
	)
	(segment
		(start 425.143676 -287.843722)
		(end 422.597072 -287.843722)
		(width 0.18288)
		(layer "In6.Cu")
		(net "M_G_CPU0_SA_DQ<26>")
	)
	(segment
		(start 410.639514 -279.235408)
		(end 410.369512 -279.50541)
		(width 0.18288)
		(layer "In6.Cu")
		(net "M_G_CPU0_SA_DQ<26>")
	)
	(segment
		(start 387.227064 -269.707868)
		(end 387.212332 -269.699232)
		(width 0.088646)
		(layer "In6.Cu")
		(net "M_G_CPU0_SA_DQ<26>")
	)
	(segment
		(start 421.85209 -286.806132)
		(end 421.186356 -286.140398)
		(width 0.18288)
		(layer "In6.Cu")
		(net "M_G_CPU0_SA_DQ<26>")
	)
	(segment
		(start 379.708664 -269.707868)
		(end 379.693932 -269.699232)
		(width 0.088646)
		(layer "In6.Cu")
		(net "M_G_CPU0_SA_DQ<26>")
	)
	(segment
		(start 380.648718 -269.707868)
		(end 380.638304 -269.701772)
		(width 0.088646)
		(layer "In6.Cu")
		(net "M_G_CPU0_SA_DQ<26>")
	)
	(segment
		(start 412.283402 -279.50541)
		(end 411.307534 -279.50541)
		(width 0.18288)
		(layer "In6.Cu")
		(net "M_G_CPU0_SA_DQ<26>")
	)
	(segment
		(start 382.528064 -269.707868)
		(end 382.513332 -269.699232)
		(width 0.088646)
		(layer "In6.Cu")
		(net "M_G_CPU0_SA_DQ<26>")
	)
	(segment
		(start 431.02784 -288.040826)
		(end 429.896524 -288.040826)
		(width 0.18288)
		(layer "In6.Cu")
		(net "M_G_CPU0_SA_DQ<26>")
	)
	(segment
		(start 406.509982 -278.355298)
		(end 406.327102 -278.538178)
		(width 0.18288)
		(layer "In6.Cu")
		(net "M_G_CPU0_SA_DQ<26>")
	)
	(segment
		(start 381.033528 -269.701772)
		(end 381.023114 -269.707868)
		(width 0.088646)
		(layer "In6.Cu")
		(net "M_G_CPU0_SA_DQ<26>")
	)
	(segment
		(start 413.25927 -280.481278)
		(end 412.283402 -279.50541)
		(width 0.18288)
		(layer "In6.Cu")
		(net "M_G_CPU0_SA_DQ<26>")
	)
	(segment
		(start 427.768258 -288.040826)
		(end 427.404276 -287.676844)
		(width 0.18288)
		(layer "In6.Cu")
		(net "M_G_CPU0_SA_DQ<26>")
	)
	(segment
		(start 439.923682 -287.416748)
		(end 439.577734 -287.316672)
		(width 0.18288)
		(layer "In6.Cu")
		(net "M_G_CPU0_SA_DQ<26>")
	)
	(segment
		(start 406.509982 -278.030432)
		(end 406.509982 -278.355298)
		(width 0.18288)
		(layer "In6.Cu")
		(net "M_G_CPU0_SA_DQ<26>")
	)
	(segment
		(start 407.386282 -278.538178)
		(end 407.203402 -278.355298)
		(width 0.18288)
		(layer "In6.Cu")
		(net "M_G_CPU0_SA_DQ<26>")
	)
	(segment
		(start 409.521406 -279.50541)
		(end 408.554174 -278.538178)
		(width 0.18288)
		(layer "In6.Cu")
		(net "M_G_CPU0_SA_DQ<26>")
	)
	(segment
		(start 407.203402 -278.355298)
		(end 407.203402 -278.030432)
		(width 0.18288)
		(layer "In6.Cu")
		(net "M_G_CPU0_SA_DQ<26>")
	)
	(segment
		(start 378.768864 -269.707868)
		(end 378.754132 -269.699232)
		(width 0.088646)
		(layer "In6.Cu")
		(net "M_G_CPU0_SA_DQ<26>")
	)
	(segment
		(start 429.736504 -287.880806)
		(end 429.736504 -287.739328)
		(width 0.18288)
		(layer "In6.Cu")
		(net "M_G_CPU0_SA_DQ<26>")
	)
	(segment
		(start 429.896524 -288.040826)
		(end 429.736504 -287.880806)
		(width 0.18288)
		(layer "In6.Cu")
		(net "M_G_CPU0_SA_DQ<26>")
	)
	(segment
		(start 415.539682 -280.481278)
		(end 413.25927 -280.481278)
		(width 0.18288)
		(layer "In6.Cu")
		(net "M_G_CPU0_SA_DQ<26>")
	)
	(segment
		(start 408.554174 -278.538178)
		(end 407.386282 -278.538178)
		(width 0.18288)
		(layer "In6.Cu")
		(net "M_G_CPU0_SA_DQ<26>")
	)
	(segment
		(start 376.889264 -269.707868)
		(end 376.860054 -269.69085)
		(width 0.088646)
		(layer "In6.Cu")
		(net "M_G_CPU0_SA_DQ<26>")
	)
	(segment
		(start 429.203104 -287.579308)
		(end 429.043084 -287.739328)
		(width 0.18288)
		(layer "In6.Cu")
		(net "M_G_CPU0_SA_DQ<26>")
	)
	(segment
		(start 421.85209 -287.09874)
		(end 421.85209 -286.806132)
		(width 0.18288)
		(layer "In6.Cu")
		(net "M_G_CPU0_SA_DQ<26>")
	)
	(segment
		(start 405.493474 -278.538178)
		(end 397.615156 -270.65986)
		(width 0.18288)
		(layer "In6.Cu")
		(net "M_G_CPU0_SA_DQ<26>")
	)
	(segment
		(start 407.203402 -278.030432)
		(end 407.020522 -277.847552)
		(width 0.18288)
		(layer "In6.Cu")
		(net "M_G_CPU0_SA_DQ<26>")
	)
	(segment
		(start 411.307534 -279.50541)
		(end 411.037532 -279.235408)
		(width 0.18288)
		(layer "In6.Cu")
		(net "M_G_CPU0_SA_DQ<26>")
	)
	(segment
		(start 406.692862 -277.847552)
		(end 406.509982 -278.030432)
		(width 0.18288)
		(layer "In6.Cu")
		(net "M_G_CPU0_SA_DQ<26>")
	)
	(segment
		(start 383.467864 -269.707868)
		(end 383.453132 -269.699232)
		(width 0.088646)
		(layer "In6.Cu")
		(net "M_G_CPU0_SA_DQ<26>")
	)
	(segment
		(start 385.347464 -269.707868)
		(end 385.332732 -269.699232)
		(width 0.088646)
		(layer "In6.Cu")
		(net "M_G_CPU0_SA_DQ<26>")
	)
	(segment
		(start 418.969444 -285.534862)
		(end 418.969444 -283.834586)
		(width 0.18288)
		(layer "In6.Cu")
		(net "M_G_CPU0_SA_DQ<26>")
	)
	(arc
		(start 383.84226 -269.707868)
		(mid 383.655062 -269.758011)
		(end 383.467864 -269.707868)
		(width 0.088646)
		(layer "In6.Cu")
		(net "M_G_CPU0_SA_DQ<26>")
	)
	(arc
		(start 386.66166 -269.707868)
		(mid 386.474462 -269.758011)
		(end 386.287264 -269.707868)
		(width 0.088646)
		(layer "In6.Cu")
		(net "M_G_CPU0_SA_DQ<26>")
	)
	(arc
		(start 377.26366 -269.707868)
		(mid 377.076462 -269.758011)
		(end 376.889264 -269.707868)
		(width 0.088646)
		(layer "In6.Cu")
		(net "M_G_CPU0_SA_DQ<26>")
	)
	(arc
		(start 384.392932 -269.699232)
		(mid 384.116491 -269.632066)
		(end 383.84226 -269.707868)
		(width 0.088646)
		(layer "In6.Cu")
		(net "M_G_CPU0_SA_DQ<26>")
	)
	(arc
		(start 378.754132 -269.699232)
		(mid 378.477691 -269.632066)
		(end 378.20346 -269.707868)
		(width 0.088646)
		(layer "In6.Cu")
		(net "M_G_CPU0_SA_DQ<26>")
	)
	(arc
		(start 382.513332 -269.699232)
		(mid 382.236891 -269.632066)
		(end 381.96266 -269.707868)
		(width 0.088646)
		(layer "In6.Cu")
		(net "M_G_CPU0_SA_DQ<26>")
	)
	(arc
		(start 387.414516 -269.758668)
		(mid 387.317441 -269.745619)
		(end 387.227064 -269.707868)
		(width 0.088646)
		(layer "In6.Cu")
		(net "M_G_CPU0_SA_DQ<26>")
	)
	(arc
		(start 383.453132 -269.699232)
		(mid 383.176691 -269.632066)
		(end 382.90246 -269.707868)
		(width 0.088646)
		(layer "In6.Cu")
		(net "M_G_CPU0_SA_DQ<26>")
	)
	(arc
		(start 380.08306 -269.707868)
		(mid 379.895862 -269.758011)
		(end 379.708664 -269.707868)
		(width 0.088646)
		(layer "In6.Cu")
		(net "M_G_CPU0_SA_DQ<26>")
	)
	(arc
		(start 386.272532 -269.699232)
		(mid 385.996091 -269.632066)
		(end 385.72186 -269.707868)
		(width 0.088646)
		(layer "In6.Cu")
		(net "M_G_CPU0_SA_DQ<26>")
	)
	(arc
		(start 384.78206 -269.707868)
		(mid 384.594862 -269.758011)
		(end 384.407664 -269.707868)
		(width 0.088646)
		(layer "In6.Cu")
		(net "M_G_CPU0_SA_DQ<26>")
	)
	(arc
		(start 385.332732 -269.699232)
		(mid 385.056291 -269.632066)
		(end 384.78206 -269.707868)
		(width 0.088646)
		(layer "In6.Cu")
		(net "M_G_CPU0_SA_DQ<26>")
	)
	(arc
		(start 387.212332 -269.699232)
		(mid 386.935891 -269.632066)
		(end 386.66166 -269.707868)
		(width 0.088646)
		(layer "In6.Cu")
		(net "M_G_CPU0_SA_DQ<26>")
	)
	(arc
		(start 377.814332 -269.699232)
		(mid 377.537891 -269.632066)
		(end 377.26366 -269.707868)
		(width 0.088646)
		(layer "In6.Cu")
		(net "M_G_CPU0_SA_DQ<26>")
	)
	(arc
		(start 385.72186 -269.707868)
		(mid 385.534662 -269.758011)
		(end 385.347464 -269.707868)
		(width 0.088646)
		(layer "In6.Cu")
		(net "M_G_CPU0_SA_DQ<26>")
	)
	(arc
		(start 380.638304 -269.701772)
		(mid 380.359872 -269.631958)
		(end 380.08306 -269.707868)
		(width 0.088646)
		(layer "In6.Cu")
		(net "M_G_CPU0_SA_DQ<26>")
	)
	(arc
		(start 382.90246 -269.707868)
		(mid 382.715262 -269.758011)
		(end 382.528064 -269.707868)
		(width 0.088646)
		(layer "In6.Cu")
		(net "M_G_CPU0_SA_DQ<26>")
	)
	(arc
		(start 381.023114 -269.707868)
		(mid 380.835916 -269.758011)
		(end 380.648718 -269.707868)
		(width 0.088646)
		(layer "In6.Cu")
		(net "M_G_CPU0_SA_DQ<26>")
	)
	(arc
		(start 381.96266 -269.707868)
		(mid 381.775462 -269.758011)
		(end 381.588264 -269.707868)
		(width 0.088646)
		(layer "In6.Cu")
		(net "M_G_CPU0_SA_DQ<26>")
	)
	(arc
		(start 381.588264 -269.707868)
		(mid 381.311705 -269.632159)
		(end 381.033528 -269.701772)
		(width 0.088646)
		(layer "In6.Cu")
		(net "M_G_CPU0_SA_DQ<26>")
	)
	(arc
		(start 378.20346 -269.707868)
		(mid 378.016262 -269.758011)
		(end 377.829064 -269.707868)
		(width 0.088646)
		(layer "In6.Cu")
		(net "M_G_CPU0_SA_DQ<26>")
	)
	(arc
		(start 379.14326 -269.707868)
		(mid 378.956062 -269.758011)
		(end 378.768864 -269.707868)
		(width 0.088646)
		(layer "In6.Cu")
		(net "M_G_CPU0_SA_DQ<26>")
	)
	(arc
		(start 379.693932 -269.699232)
		(mid 379.417491 -269.632066)
		(end 379.14326 -269.707868)
		(width 0.088646)
		(layer "In6.Cu")
		(net "M_G_CPU0_SA_DQ<26>")
	)
	(segment
		(start 436.928514 -286.56661)
		(end 435.823614 -286.56661)
		(width 0.20066)
		(layer "F.Cu")
		(net "M_G_CPU0_SA_DQ<25>")
	)
	(segment
		(start 442.032644 -286.141668)
		(end 439.843926 -286.141668)
		(width 0.1016)
		(layer "F.Cu")
		(net "M_G_CPU0_SA_DQ<25>")
	)
	(segment
		(start 442.038994 -286.135318)
		(end 442.032644 -286.141668)
		(width 0.1016)
		(layer "F.Cu")
		(net "M_G_CPU0_SA_DQ<25>")
	)
	(segment
		(start 438.449212 -286.56661)
		(end 436.928514 -286.56661)
		(width 0.20066)
		(layer "F.Cu")
		(net "M_G_CPU0_SA_DQ<25>")
	)
	(segment
		(start 442.44895 -286.135318)
		(end 442.038994 -286.135318)
		(width 0.20066)
		(layer "F.Cu")
		(net "M_G_CPU0_SA_DQ<25>")
	)
	(segment
		(start 439.361072 -286.627316)
		(end 439.173112 -286.815276)
		(width 0.20066)
		(layer "F.Cu")
		(net "M_G_CPU0_SA_DQ<25>")
	)
	(segment
		(start 439.361072 -286.259778)
		(end 439.361072 -286.627316)
		(width 0.20066)
		(layer "F.Cu")
		(net "M_G_CPU0_SA_DQ<25>")
	)
	(segment
		(start 444.47206 -286.566864)
		(end 442.880496 -286.566864)
		(width 0.20066)
		(layer "F.Cu")
		(net "M_G_CPU0_SA_DQ<25>")
	)
	(segment
		(start 374.726962 -268.56944)
		(end 374.727216 -268.569694)
		(width 0.20066)
		(layer "F.Cu")
		(net "M_G_CPU0_SA_DQ<25>")
	)
	(segment
		(start 442.880496 -286.566864)
		(end 442.44895 -286.135318)
		(width 0.20066)
		(layer "F.Cu")
		(net "M_G_CPU0_SA_DQ<25>")
	)
	(segment
		(start 444.472314 -286.56661)
		(end 444.47206 -286.566864)
		(width 0.20066)
		(layer "F.Cu")
		(net "M_G_CPU0_SA_DQ<25>")
	)
	(segment
		(start 439.82386 -286.141668)
		(end 439.479182 -286.141668)
		(width 0.20066)
		(layer "F.Cu")
		(net "M_G_CPU0_SA_DQ<25>")
	)
	(segment
		(start 439.173112 -286.815276)
		(end 438.697878 -286.815276)
		(width 0.20066)
		(layer "F.Cu")
		(net "M_G_CPU0_SA_DQ<25>")
	)
	(segment
		(start 439.479182 -286.141668)
		(end 439.361072 -286.259778)
		(width 0.20066)
		(layer "F.Cu")
		(net "M_G_CPU0_SA_DQ<25>")
	)
	(segment
		(start 374.726962 -268.033754)
		(end 374.726962 -268.56944)
		(width 0.20066)
		(layer "F.Cu")
		(net "M_G_CPU0_SA_DQ<25>")
	)
	(segment
		(start 438.697878 -286.815276)
		(end 438.449212 -286.56661)
		(width 0.20066)
		(layer "F.Cu")
		(net "M_G_CPU0_SA_DQ<25>")
	)
	(segment
		(start 439.843926 -286.141668)
		(end 439.82386 -286.141668)
		(width 0.101854)
		(layer "F.Cu")
		(net "M_G_CPU0_SA_DQ<25>")
	)
	(segment
		(start 425.29379 -286.99206)
		(end 423.094404 -286.99206)
		(width 0.18288)
		(layer "In6.Cu")
		(net "M_G_CPU0_SA_DQ<25>")
	)
	(segment
		(start 430.886362 -287.011872)
		(end 430.726342 -286.851852)
		(width 0.18288)
		(layer "In6.Cu")
		(net "M_G_CPU0_SA_DQ<25>")
	)
	(segment
		(start 431.79365 -286.29102)
		(end 431.579782 -286.29102)
		(width 0.18288)
		(layer "In6.Cu")
		(net "M_G_CPU0_SA_DQ<25>")
	)
	(segment
		(start 381.023114 -269.059152)
		(end 381.017272 -269.05585)
		(width 0.088646)
		(layer "In6.Cu")
		(net "M_G_CPU0_SA_DQ<25>")
	)
	(segment
		(start 431.579782 -286.29102)
		(end 431.419762 -286.45104)
		(width 0.18288)
		(layer "In6.Cu")
		(net "M_G_CPU0_SA_DQ<25>")
	)
	(segment
		(start 428.530258 -286.855916)
		(end 427.779434 -286.855916)
		(width 0.18288)
		(layer "In6.Cu")
		(net "M_G_CPU0_SA_DQ<25>")
	)
	(segment
		(start 429.095154 -286.29102)
		(end 428.530258 -286.855916)
		(width 0.18288)
		(layer "In6.Cu")
		(net "M_G_CPU0_SA_DQ<25>")
	)
	(segment
		(start 380.089156 -269.062708)
		(end 380.083314 -269.059152)
		(width 0.088646)
		(layer "In6.Cu")
		(net "M_G_CPU0_SA_DQ<25>")
	)
	(segment
		(start 409.372054 -278.431244)
		(end 408.28976 -277.34895)
		(width 0.18288)
		(layer "In6.Cu")
		(net "M_G_CPU0_SA_DQ<25>")
	)
	(segment
		(start 379.149356 -269.062708)
		(end 379.143514 -269.059152)
		(width 0.088646)
		(layer "In6.Cu")
		(net "M_G_CPU0_SA_DQ<25>")
	)
	(segment
		(start 413.878522 -279.20442)
		(end 413.695642 -279.02154)
		(width 0.18288)
		(layer "In6.Cu")
		(net "M_G_CPU0_SA_DQ<25>")
	)
	(segment
		(start 413.878522 -279.45207)
		(end 413.878522 -279.20442)
		(width 0.18288)
		(layer "In6.Cu")
		(net "M_G_CPU0_SA_DQ<25>")
	)
	(segment
		(start 429.339502 -286.45104)
		(end 429.179482 -286.29102)
		(width 0.18288)
		(layer "In6.Cu")
		(net "M_G_CPU0_SA_DQ<25>")
	)
	(segment
		(start 431.419762 -286.45104)
		(end 431.419762 -286.851852)
		(width 0.18288)
		(layer "In6.Cu")
		(net "M_G_CPU0_SA_DQ<25>")
	)
	(segment
		(start 427.470316 -287.165034)
		(end 425.466764 -287.165034)
		(width 0.18288)
		(layer "In6.Cu")
		(net "M_G_CPU0_SA_DQ<25>")
	)
	(segment
		(start 414.061402 -279.63495)
		(end 413.878522 -279.45207)
		(width 0.18288)
		(layer "In6.Cu")
		(net "M_G_CPU0_SA_DQ<25>")
	)
	(segment
		(start 433.396898 -286.399986)
		(end 432.909218 -285.912306)
		(width 0.18288)
		(layer "In6.Cu")
		(net "M_G_CPU0_SA_DQ<25>")
	)
	(segment
		(start 418.806122 -282.476956)
		(end 418.806122 -282.041092)
		(width 0.18288)
		(layer "In6.Cu")
		(net "M_G_CPU0_SA_DQ<25>")
	)
	(segment
		(start 429.499522 -287.011872)
		(end 429.339502 -286.851852)
		(width 0.18288)
		(layer "In6.Cu")
		(net "M_G_CPU0_SA_DQ<25>")
	)
	(segment
		(start 414.571942 -279.45207)
		(end 414.389062 -279.63495)
		(width 0.18288)
		(layer "In6.Cu")
		(net "M_G_CPU0_SA_DQ<25>")
	)
	(segment
		(start 416.165538 -280.390346)
		(end 416.165538 -279.861772)
		(width 0.18288)
		(layer "In6.Cu")
		(net "M_G_CPU0_SA_DQ<25>")
	)
	(segment
		(start 421.39489 -285.292546)
		(end 420.504112 -285.292546)
		(width 0.18288)
		(layer "In6.Cu")
		(net "M_G_CPU0_SA_DQ<25>")
	)
	(segment
		(start 420.283132 -283.953966)
		(end 420.025576 -283.69641)
		(width 0.18288)
		(layer "In6.Cu")
		(net "M_G_CPU0_SA_DQ<25>")
	)
	(segment
		(start 422.252902 -286.150558)
		(end 422.252902 -285.924498)
		(width 0.18288)
		(layer "In6.Cu")
		(net "M_G_CPU0_SA_DQ<25>")
	)
	(segment
		(start 410.492448 -278.431244)
		(end 409.372054 -278.431244)
		(width 0.18288)
		(layer "In6.Cu")
		(net "M_G_CPU0_SA_DQ<25>")
	)
	(segment
		(start 387.927596 -269.386304)
		(end 387.600444 -269.059152)
		(width 0.088646)
		(layer "In6.Cu")
		(net "M_G_CPU0_SA_DQ<25>")
	)
	(segment
		(start 423.094404 -286.99206)
		(end 422.252902 -286.150558)
		(width 0.18288)
		(layer "In6.Cu")
		(net "M_G_CPU0_SA_DQ<25>")
	)
	(segment
		(start 430.032922 -286.851852)
		(end 429.872902 -287.011872)
		(width 0.18288)
		(layer "In6.Cu")
		(net "M_G_CPU0_SA_DQ<25>")
	)
	(segment
		(start 430.192942 -286.29102)
		(end 430.032922 -286.45104)
		(width 0.18288)
		(layer "In6.Cu")
		(net "M_G_CPU0_SA_DQ<25>")
	)
	(segment
		(start 412.833312 -279.02154)
		(end 412.243016 -278.431244)
		(width 0.18288)
		(layer "In6.Cu")
		(net "M_G_CPU0_SA_DQ<25>")
	)
	(segment
		(start 431.419762 -286.851852)
		(end 431.259742 -287.011872)
		(width 0.18288)
		(layer "In6.Cu")
		(net "M_G_CPU0_SA_DQ<25>")
	)
	(segment
		(start 398.073372 -270.127476)
		(end 392.6332 -270.127476)
		(width 0.18288)
		(layer "In6.Cu")
		(net "M_G_CPU0_SA_DQ<25>")
	)
	(segment
		(start 380.083314 -269.059152)
		(end 380.077472 -269.05585)
		(width 0.088646)
		(layer "In6.Cu")
		(net "M_G_CPU0_SA_DQ<25>")
	)
	(segment
		(start 419.535102 -282.979876)
		(end 419.309042 -282.979876)
		(width 0.18288)
		(layer "In6.Cu")
		(net "M_G_CPU0_SA_DQ<25>")
	)
	(segment
		(start 420.25824 -283.011372)
		(end 419.993826 -282.746958)
		(width 0.18288)
		(layer "In6.Cu")
		(net "M_G_CPU0_SA_DQ<25>")
	)
	(segment
		(start 417.807394 -281.478228)
		(end 417.25342 -281.478228)
		(width 0.18288)
		(layer "In6.Cu")
		(net "M_G_CPU0_SA_DQ<25>")
	)
	(segment
		(start 379.143514 -269.059152)
		(end 379.137672 -269.05585)
		(width 0.088646)
		(layer "In6.Cu")
		(net "M_G_CPU0_SA_DQ<25>")
	)
	(segment
		(start 432.172364 -285.912306)
		(end 431.79365 -286.29102)
		(width 0.18288)
		(layer "In6.Cu")
		(net "M_G_CPU0_SA_DQ<25>")
	)
	(segment
		(start 408.28976 -277.34895)
		(end 405.294846 -277.34895)
		(width 0.18288)
		(layer "In6.Cu")
		(net "M_G_CPU0_SA_DQ<25>")
	)
	(segment
		(start 430.726342 -286.45104)
		(end 430.566322 -286.29102)
		(width 0.18288)
		(layer "In6.Cu")
		(net "M_G_CPU0_SA_DQ<25>")
	)
	(segment
		(start 420.025576 -283.69641)
		(end 420.025576 -283.47035)
		(width 0.18288)
		(layer "In6.Cu")
		(net "M_G_CPU0_SA_DQ<25>")
	)
	(segment
		(start 433.9082 -286.399986)
		(end 433.396898 -286.399986)
		(width 0.18288)
		(layer "In6.Cu")
		(net "M_G_CPU0_SA_DQ<25>")
	)
	(segment
		(start 434.258466 -286.04972)
		(end 433.9082 -286.399986)
		(width 0.18288)
		(layer "In6.Cu")
		(net "M_G_CPU0_SA_DQ<25>")
	)
	(segment
		(start 420.025576 -283.47035)
		(end 420.25824 -283.237432)
		(width 0.18288)
		(layer "In6.Cu")
		(net "M_G_CPU0_SA_DQ<25>")
	)
	(segment
		(start 405.294846 -277.34895)
		(end 398.073372 -270.127476)
		(width 0.18288)
		(layer "In6.Cu")
		(net "M_G_CPU0_SA_DQ<25>")
	)
	(segment
		(start 376.335798 -269.0622)
		(end 376.331734 -269.059914)
		(width 0.088646)
		(layer "In6.Cu")
		(net "M_G_CPU0_SA_DQ<25>")
	)
	(segment
		(start 429.179482 -286.29102)
		(end 429.095154 -286.29102)
		(width 0.18288)
		(layer "In6.Cu")
		(net "M_G_CPU0_SA_DQ<25>")
	)
	(segment
		(start 388.3025 -269.61719)
		(end 388.173468 -269.488158)
		(width 0.088646)
		(layer "In6.Cu")
		(net "M_G_CPU0_SA_DQ<25>")
	)
	(segment
		(start 431.259742 -287.011872)
		(end 430.886362 -287.011872)
		(width 0.18288)
		(layer "In6.Cu")
		(net "M_G_CPU0_SA_DQ<25>")
	)
	(segment
		(start 392.6332 -270.127476)
		(end 390.068054 -269.61719)
		(width 0.18288)
		(layer "In6.Cu")
		(net "M_G_CPU0_SA_DQ<25>")
	)
	(segment
		(start 422.252902 -285.924498)
		(end 422.472358 -285.705042)
		(width 0.18288)
		(layer "In6.Cu")
		(net "M_G_CPU0_SA_DQ<25>")
	)
	(segment
		(start 410.75229 -278.171402)
		(end 410.492448 -278.431244)
		(width 0.18288)
		(layer "In6.Cu")
		(net "M_G_CPU0_SA_DQ<25>")
	)
	(segment
		(start 419.993826 -282.746958)
		(end 419.767766 -282.746958)
		(width 0.18288)
		(layer "In6.Cu")
		(net "M_G_CPU0_SA_DQ<25>")
	)
	(segment
		(start 418.806122 -282.041092)
		(end 418.53358 -281.76855)
		(width 0.18288)
		(layer "In6.Cu")
		(net "M_G_CPU0_SA_DQ<25>")
	)
	(segment
		(start 411.162246 -278.171402)
		(end 410.75229 -278.171402)
		(width 0.18288)
		(layer "In6.Cu")
		(net "M_G_CPU0_SA_DQ<25>")
	)
	(segment
		(start 414.571942 -279.20442)
		(end 414.571942 -279.45207)
		(width 0.18288)
		(layer "In6.Cu")
		(net "M_G_CPU0_SA_DQ<25>")
	)
	(segment
		(start 422.207944 -285.214568)
		(end 421.981884 -285.214568)
		(width 0.18288)
		(layer "In6.Cu")
		(net "M_G_CPU0_SA_DQ<25>")
	)
	(segment
		(start 420.504112 -285.292546)
		(end 420.283132 -285.071566)
		(width 0.18288)
		(layer "In6.Cu")
		(net "M_G_CPU0_SA_DQ<25>")
	)
	(segment
		(start 413.695642 -279.02154)
		(end 412.833312 -279.02154)
		(width 0.18288)
		(layer "In6.Cu")
		(net "M_G_CPU0_SA_DQ<25>")
	)
	(segment
		(start 430.032922 -286.45104)
		(end 430.032922 -286.851852)
		(width 0.18288)
		(layer "In6.Cu")
		(net "M_G_CPU0_SA_DQ<25>")
	)
	(segment
		(start 422.472358 -285.478982)
		(end 422.207944 -285.214568)
		(width 0.18288)
		(layer "In6.Cu")
		(net "M_G_CPU0_SA_DQ<25>")
	)
	(segment
		(start 419.309042 -282.979876)
		(end 418.806122 -282.476956)
		(width 0.18288)
		(layer "In6.Cu")
		(net "M_G_CPU0_SA_DQ<25>")
	)
	(segment
		(start 420.25824 -283.237432)
		(end 420.25824 -283.011372)
		(width 0.18288)
		(layer "In6.Cu")
		(net "M_G_CPU0_SA_DQ<25>")
	)
	(segment
		(start 415.325306 -279.02154)
		(end 414.754822 -279.02154)
		(width 0.18288)
		(layer "In6.Cu")
		(net "M_G_CPU0_SA_DQ<25>")
	)
	(segment
		(start 377.263914 -269.059152)
		(end 377.258072 -269.05585)
		(width 0.088646)
		(layer "In6.Cu")
		(net "M_G_CPU0_SA_DQ<25>")
	)
	(segment
		(start 427.779434 -286.855916)
		(end 427.470316 -287.165034)
		(width 0.18288)
		(layer "In6.Cu")
		(net "M_G_CPU0_SA_DQ<25>")
	)
	(segment
		(start 417.25342 -281.478228)
		(end 416.165538 -280.390346)
		(width 0.18288)
		(layer "In6.Cu")
		(net "M_G_CPU0_SA_DQ<25>")
	)
	(segment
		(start 382.528064 -269.059152)
		(end 382.513332 -269.067788)
		(width 0.088646)
		(layer "In6.Cu")
		(net "M_G_CPU0_SA_DQ<25>")
	)
	(segment
		(start 412.243016 -278.431244)
		(end 411.422088 -278.431244)
		(width 0.18288)
		(layer "In6.Cu")
		(net "M_G_CPU0_SA_DQ<25>")
	)
	(segment
		(start 429.872902 -287.011872)
		(end 429.499522 -287.011872)
		(width 0.18288)
		(layer "In6.Cu")
		(net "M_G_CPU0_SA_DQ<25>")
	)
	(segment
		(start 377.269756 -269.062708)
		(end 377.263914 -269.059152)
		(width 0.088646)
		(layer "In6.Cu")
		(net "M_G_CPU0_SA_DQ<25>")
	)
	(segment
		(start 430.726342 -286.851852)
		(end 430.726342 -286.45104)
		(width 0.18288)
		(layer "In6.Cu")
		(net "M_G_CPU0_SA_DQ<25>")
	)
	(segment
		(start 435.823614 -286.56661)
		(end 435.306724 -286.04972)
		(width 0.18288)
		(layer "In6.Cu")
		(net "M_G_CPU0_SA_DQ<25>")
	)
	(segment
		(start 418.53358 -281.76855)
		(end 418.097716 -281.76855)
		(width 0.18288)
		(layer "In6.Cu")
		(net "M_G_CPU0_SA_DQ<25>")
	)
	(segment
		(start 429.339502 -286.851852)
		(end 429.339502 -286.45104)
		(width 0.18288)
		(layer "In6.Cu")
		(net "M_G_CPU0_SA_DQ<25>")
	)
	(segment
		(start 378.209556 -269.062708)
		(end 378.203714 -269.059152)
		(width 0.088646)
		(layer "In6.Cu")
		(net "M_G_CPU0_SA_DQ<25>")
	)
	(segment
		(start 425.466764 -287.165034)
		(end 425.29379 -286.99206)
		(width 0.18288)
		(layer "In6.Cu")
		(net "M_G_CPU0_SA_DQ<25>")
	)
	(segment
		(start 378.203714 -269.059152)
		(end 378.197872 -269.05585)
		(width 0.088646)
		(layer "In6.Cu")
		(net "M_G_CPU0_SA_DQ<25>")
	)
	(segment
		(start 387.226048 -269.059152)
		(end 387.215634 -269.065248)
		(width 0.088646)
		(layer "In6.Cu")
		(net "M_G_CPU0_SA_DQ<25>")
	)
	(segment
		(start 416.165538 -279.861772)
		(end 415.325306 -279.02154)
		(width 0.18288)
		(layer "In6.Cu")
		(net "M_G_CPU0_SA_DQ<25>")
	)
	(segment
		(start 386.286502 -269.059152)
		(end 386.276088 -269.065248)
		(width 0.088646)
		(layer "In6.Cu")
		(net "M_G_CPU0_SA_DQ<25>")
	)
	(segment
		(start 411.422088 -278.431244)
		(end 411.162246 -278.171402)
		(width 0.18288)
		(layer "In6.Cu")
		(net "M_G_CPU0_SA_DQ<25>")
	)
	(segment
		(start 383.467864 -269.059152)
		(end 383.453132 -269.067788)
		(width 0.088646)
		(layer "In6.Cu")
		(net "M_G_CPU0_SA_DQ<25>")
	)
	(segment
		(start 421.981884 -285.214568)
		(end 421.762428 -285.434024)
		(width 0.18288)
		(layer "In6.Cu")
		(net "M_G_CPU0_SA_DQ<25>")
	)
	(segment
		(start 390.068054 -269.61719)
		(end 388.535672 -269.61719)
		(width 0.18288)
		(layer "In6.Cu")
		(net "M_G_CPU0_SA_DQ<25>")
	)
	(segment
		(start 381.588264 -269.059152)
		(end 381.57785 -269.065248)
		(width 0.088646)
		(layer "In6.Cu")
		(net "M_G_CPU0_SA_DQ<25>")
	)
	(segment
		(start 376.069606 -268.960092)
		(end 375.669556 -268.960092)
		(width 0.088646)
		(layer "In6.Cu")
		(net "M_G_CPU0_SA_DQ<25>")
	)
	(segment
		(start 421.762428 -285.434024)
		(end 421.536368 -285.434024)
		(width 0.18288)
		(layer "In6.Cu")
		(net "M_G_CPU0_SA_DQ<25>")
	)
	(segment
		(start 422.472358 -285.705042)
		(end 422.472358 -285.478982)
		(width 0.18288)
		(layer "In6.Cu")
		(net "M_G_CPU0_SA_DQ<25>")
	)
	(segment
		(start 418.097716 -281.76855)
		(end 417.807394 -281.478228)
		(width 0.18288)
		(layer "In6.Cu")
		(net "M_G_CPU0_SA_DQ<25>")
	)
	(segment
		(start 414.754822 -279.02154)
		(end 414.571942 -279.20442)
		(width 0.18288)
		(layer "In6.Cu")
		(net "M_G_CPU0_SA_DQ<25>")
	)
	(segment
		(start 432.909218 -285.912306)
		(end 432.172364 -285.912306)
		(width 0.18288)
		(layer "In6.Cu")
		(net "M_G_CPU0_SA_DQ<25>")
	)
	(segment
		(start 419.767766 -282.746958)
		(end 419.535102 -282.979876)
		(width 0.18288)
		(layer "In6.Cu")
		(net "M_G_CPU0_SA_DQ<25>")
	)
	(segment
		(start 388.173468 -269.488158)
		(end 387.927596 -269.386304)
		(width 0.088646)
		(layer "In6.Cu")
		(net "M_G_CPU0_SA_DQ<25>")
	)
	(segment
		(start 430.566322 -286.29102)
		(end 430.192942 -286.29102)
		(width 0.18288)
		(layer "In6.Cu")
		(net "M_G_CPU0_SA_DQ<25>")
	)
	(segment
		(start 420.283132 -285.071566)
		(end 420.283132 -283.953966)
		(width 0.18288)
		(layer "In6.Cu")
		(net "M_G_CPU0_SA_DQ<25>")
	)
	(segment
		(start 435.306724 -286.04972)
		(end 434.258466 -286.04972)
		(width 0.18288)
		(layer "In6.Cu")
		(net "M_G_CPU0_SA_DQ<25>")
	)
	(segment
		(start 421.536368 -285.434024)
		(end 421.39489 -285.292546)
		(width 0.18288)
		(layer "In6.Cu")
		(net "M_G_CPU0_SA_DQ<25>")
	)
	(segment
		(start 388.535672 -269.61719)
		(end 388.3025 -269.61719)
		(width 0.088646)
		(layer "In6.Cu")
		(net "M_G_CPU0_SA_DQ<25>")
	)
	(segment
		(start 414.389062 -279.63495)
		(end 414.061402 -279.63495)
		(width 0.18288)
		(layer "In6.Cu")
		(net "M_G_CPU0_SA_DQ<25>")
	)
	(arc
		(start 376.20067 -268.990318)
		(mid 376.136859 -268.967758)
		(end 376.069606 -268.960092)
		(width 0.088646)
		(layer "In6.Cu")
		(net "M_G_CPU0_SA_DQ<25>")
	)
	(arc
		(start 386.276088 -269.065248)
		(mid 385.99791 -269.134971)
		(end 385.721352 -269.059152)
		(width 0.088646)
		(layer "In6.Cu")
		(net "M_G_CPU0_SA_DQ<25>")
	)
	(arc
		(start 378.768864 -269.059152)
		(mid 378.48969 -269.134917)
		(end 378.209556 -269.062708)
		(width 0.088646)
		(layer "In6.Cu")
		(net "M_G_CPU0_SA_DQ<25>")
	)
	(arc
		(start 384.407664 -269.059152)
		(mid 384.124962 -269.134928)
		(end 383.84226 -269.059152)
		(width 0.088646)
		(layer "In6.Cu")
		(net "M_G_CPU0_SA_DQ<25>")
	)
	(arc
		(start 384.78206 -269.059152)
		(mid 384.594862 -269.009009)
		(end 384.407664 -269.059152)
		(width 0.088646)
		(layer "In6.Cu")
		(net "M_G_CPU0_SA_DQ<25>")
	)
	(arc
		(start 385.721352 -269.059152)
		(mid 385.534154 -269.009009)
		(end 385.346956 -269.059152)
		(width 0.088646)
		(layer "In6.Cu")
		(net "M_G_CPU0_SA_DQ<25>")
	)
	(arc
		(start 381.57785 -269.065248)
		(mid 381.299672 -269.134971)
		(end 381.023114 -269.059152)
		(width 0.088646)
		(layer "In6.Cu")
		(net "M_G_CPU0_SA_DQ<25>")
	)
	(arc
		(start 385.346956 -269.059152)
		(mid 385.064508 -269.134801)
		(end 384.78206 -269.059152)
		(width 0.088646)
		(layer "In6.Cu")
		(net "M_G_CPU0_SA_DQ<25>")
	)
	(arc
		(start 383.453132 -269.067788)
		(mid 383.176657 -269.135108)
		(end 382.90246 -269.059152)
		(width 0.088646)
		(layer "In6.Cu")
		(net "M_G_CPU0_SA_DQ<25>")
	)
	(arc
		(start 377.258072 -269.05585)
		(mid 377.073217 -269.0089)
		(end 376.889264 -269.059152)
		(width 0.088646)
		(layer "In6.Cu")
		(net "M_G_CPU0_SA_DQ<25>")
	)
	(arc
		(start 387.215634 -269.065248)
		(mid 386.937456 -269.134971)
		(end 386.660898 -269.059152)
		(width 0.088646)
		(layer "In6.Cu")
		(net "M_G_CPU0_SA_DQ<25>")
	)
	(arc
		(start 377.829064 -269.059152)
		(mid 377.54989 -269.134917)
		(end 377.269756 -269.062708)
		(width 0.088646)
		(layer "In6.Cu")
		(net "M_G_CPU0_SA_DQ<25>")
	)
	(arc
		(start 379.708664 -269.059152)
		(mid 379.42949 -269.134917)
		(end 379.149356 -269.062708)
		(width 0.088646)
		(layer "In6.Cu")
		(net "M_G_CPU0_SA_DQ<25>")
	)
	(arc
		(start 386.660898 -269.059152)
		(mid 386.4737 -269.009009)
		(end 386.286502 -269.059152)
		(width 0.088646)
		(layer "In6.Cu")
		(net "M_G_CPU0_SA_DQ<25>")
	)
	(arc
		(start 375.669556 -268.960092)
		(mid 375.159553 -268.858628)
		(end 374.727216 -268.569694)
		(width 0.088646)
		(layer "In6.Cu")
		(net "M_G_CPU0_SA_DQ<25>")
	)
	(arc
		(start 387.600444 -269.059152)
		(mid 387.413246 -269.009009)
		(end 387.226048 -269.059152)
		(width 0.088646)
		(layer "In6.Cu")
		(net "M_G_CPU0_SA_DQ<25>")
	)
	(arc
		(start 378.197872 -269.05585)
		(mid 378.013017 -269.0089)
		(end 377.829064 -269.059152)
		(width 0.088646)
		(layer "In6.Cu")
		(net "M_G_CPU0_SA_DQ<25>")
	)
	(arc
		(start 381.96266 -269.059152)
		(mid 381.775462 -269.009009)
		(end 381.588264 -269.059152)
		(width 0.088646)
		(layer "In6.Cu")
		(net "M_G_CPU0_SA_DQ<25>")
	)
	(arc
		(start 376.889264 -269.059152)
		(mid 376.612936 -269.134051)
		(end 376.335798 -269.0622)
		(width 0.088646)
		(layer "In6.Cu")
		(net "M_G_CPU0_SA_DQ<25>")
	)
	(arc
		(start 382.90246 -269.059152)
		(mid 382.715262 -269.009009)
		(end 382.528064 -269.059152)
		(width 0.088646)
		(layer "In6.Cu")
		(net "M_G_CPU0_SA_DQ<25>")
	)
	(arc
		(start 380.077472 -269.05585)
		(mid 379.892617 -269.0089)
		(end 379.708664 -269.059152)
		(width 0.088646)
		(layer "In6.Cu")
		(net "M_G_CPU0_SA_DQ<25>")
	)
	(arc
		(start 381.017272 -269.05585)
		(mid 380.832417 -269.0089)
		(end 380.648464 -269.059152)
		(width 0.088646)
		(layer "In6.Cu")
		(net "M_G_CPU0_SA_DQ<25>")
	)
	(arc
		(start 379.137672 -269.05585)
		(mid 378.952817 -269.0089)
		(end 378.768864 -269.059152)
		(width 0.088646)
		(layer "In6.Cu")
		(net "M_G_CPU0_SA_DQ<25>")
	)
	(arc
		(start 380.648464 -269.059152)
		(mid 380.36929 -269.134917)
		(end 380.089156 -269.062708)
		(width 0.088646)
		(layer "In6.Cu")
		(net "M_G_CPU0_SA_DQ<25>")
	)
	(arc
		(start 376.331734 -269.059914)
		(mid 376.266631 -269.024309)
		(end 376.20067 -268.990318)
		(width 0.088646)
		(layer "In6.Cu")
		(net "M_G_CPU0_SA_DQ<25>")
	)
	(arc
		(start 383.84226 -269.059152)
		(mid 383.655062 -269.009009)
		(end 383.467864 -269.059152)
		(width 0.088646)
		(layer "In6.Cu")
		(net "M_G_CPU0_SA_DQ<25>")
	)
	(arc
		(start 382.513332 -269.067788)
		(mid 382.236857 -269.135108)
		(end 381.96266 -269.059152)
		(width 0.088646)
		(layer "In6.Cu")
		(net "M_G_CPU0_SA_DQ<25>")
	)
	(segment
		(start 375.197116 -269.383256)
		(end 375.196862 -269.38351)
		(width 0.20066)
		(layer "F.Cu")
		(net "M_G_CPU0_SA_DQ<24>")
	)
	(segment
		(start 439.173112 -288.515298)
		(end 438.697878 -288.515298)
		(width 0.20066)
		(layer "F.Cu")
		(net "M_G_CPU0_SA_DQ<24>")
	)
	(segment
		(start 439.361072 -288.327338)
		(end 439.173112 -288.515298)
		(width 0.20066)
		(layer "F.Cu")
		(net "M_G_CPU0_SA_DQ<24>")
	)
	(segment
		(start 444.472314 -288.266632)
		(end 444.47206 -288.266886)
		(width 0.20066)
		(layer "F.Cu")
		(net "M_G_CPU0_SA_DQ<24>")
	)
	(segment
		(start 439.87085 -287.84169)
		(end 439.82386 -287.84169)
		(width 0.101854)
		(layer "F.Cu")
		(net "M_G_CPU0_SA_DQ<24>")
	)
	(segment
		(start 442.038994 -287.83534)
		(end 442.032644 -287.84169)
		(width 0.1016)
		(layer "F.Cu")
		(net "M_G_CPU0_SA_DQ<24>")
	)
	(segment
		(start 375.197116 -268.84757)
		(end 375.197116 -269.383256)
		(width 0.20066)
		(layer "F.Cu")
		(net "M_G_CPU0_SA_DQ<24>")
	)
	(segment
		(start 438.697878 -288.515298)
		(end 438.449212 -288.266632)
		(width 0.20066)
		(layer "F.Cu")
		(net "M_G_CPU0_SA_DQ<24>")
	)
	(segment
		(start 439.361072 -287.9598)
		(end 439.361072 -288.327338)
		(width 0.20066)
		(layer "F.Cu")
		(net "M_G_CPU0_SA_DQ<24>")
	)
	(segment
		(start 442.880496 -288.266886)
		(end 442.44895 -287.83534)
		(width 0.20066)
		(layer "F.Cu")
		(net "M_G_CPU0_SA_DQ<24>")
	)
	(segment
		(start 439.479182 -287.84169)
		(end 439.361072 -287.9598)
		(width 0.20066)
		(layer "F.Cu")
		(net "M_G_CPU0_SA_DQ<24>")
	)
	(segment
		(start 444.47206 -288.266886)
		(end 442.880496 -288.266886)
		(width 0.20066)
		(layer "F.Cu")
		(net "M_G_CPU0_SA_DQ<24>")
	)
	(segment
		(start 438.449212 -288.266632)
		(end 436.928514 -288.266632)
		(width 0.20066)
		(layer "F.Cu")
		(net "M_G_CPU0_SA_DQ<24>")
	)
	(segment
		(start 442.032644 -287.84169)
		(end 439.87085 -287.84169)
		(width 0.1016)
		(layer "F.Cu")
		(net "M_G_CPU0_SA_DQ<24>")
	)
	(segment
		(start 439.82386 -287.84169)
		(end 439.479182 -287.84169)
		(width 0.20066)
		(layer "F.Cu")
		(net "M_G_CPU0_SA_DQ<24>")
	)
	(segment
		(start 436.928514 -288.266632)
		(end 435.823614 -288.266632)
		(width 0.20066)
		(layer "F.Cu")
		(net "M_G_CPU0_SA_DQ<24>")
	)
	(segment
		(start 442.44895 -287.83534)
		(end 442.038994 -287.83534)
		(width 0.20066)
		(layer "F.Cu")
		(net "M_G_CPU0_SA_DQ<24>")
	)
	(segment
		(start 392.455908 -271.161256)
		(end 389.760968 -270.625316)
		(width 0.18288)
		(layer "In6.Cu")
		(net "M_G_CPU0_SA_DQ<24>")
	)
	(segment
		(start 418.33927 -286.570674)
		(end 418.33927 -284.110176)
		(width 0.18288)
		(layer "In6.Cu")
		(net "M_G_CPU0_SA_DQ<24>")
	)
	(segment
		(start 411.07741 -281.099514)
		(end 410.89453 -281.282394)
		(width 0.18288)
		(layer "In6.Cu")
		(net "M_G_CPU0_SA_DQ<24>")
	)
	(segment
		(start 375.854214 -269.873222)
		(end 375.825258 -269.856712)
		(width 0.088646)
		(layer "In6.Cu")
		(net "M_G_CPU0_SA_DQ<24>")
	)
	(segment
		(start 388.535672 -270.625316)
		(end 388.335774 -270.625316)
		(width 0.088646)
		(layer "In6.Cu")
		(net "M_G_CPU0_SA_DQ<24>")
	)
	(segment
		(start 431.166778 -288.689542)
		(end 422.717468 -288.689542)
		(width 0.18288)
		(layer "In6.Cu")
		(net "M_G_CPU0_SA_DQ<24>")
	)
	(segment
		(start 407.038048 -280.469848)
		(end 406.710388 -280.469848)
		(width 0.18288)
		(layer "In6.Cu")
		(net "M_G_CPU0_SA_DQ<24>")
	)
	(segment
		(start 383.387346 -269.881858)
		(end 383.372614 -269.873222)
		(width 0.088646)
		(layer "In6.Cu")
		(net "M_G_CPU0_SA_DQ<24>")
	)
	(segment
		(start 416.5219 -283.438346)
		(end 414.109662 -281.026108)
		(width 0.18288)
		(layer "In6.Cu")
		(net "M_G_CPU0_SA_DQ<24>")
	)
	(segment
		(start 378.688346 -269.881858)
		(end 378.673614 -269.873222)
		(width 0.088646)
		(layer "In6.Cu")
		(net "M_G_CPU0_SA_DQ<24>")
	)
	(segment
		(start 406.527508 -279.396698)
		(end 406.344628 -279.213818)
		(width 0.18288)
		(layer "In6.Cu")
		(net "M_G_CPU0_SA_DQ<24>")
	)
	(segment
		(start 412.077916 -280.103834)
		(end 411.26029 -280.103834)
		(width 0.18288)
		(layer "In6.Cu")
		(net "M_G_CPU0_SA_DQ<24>")
	)
	(segment
		(start 381.503174 -269.879318)
		(end 381.49276 -269.873222)
		(width 0.088646)
		(layer "In6.Cu")
		(net "M_G_CPU0_SA_DQ<24>")
	)
	(segment
		(start 410.20111 -280.103834)
		(end 409.165044 -280.103834)
		(width 0.18288)
		(layer "In6.Cu")
		(net "M_G_CPU0_SA_DQ<24>")
	)
	(segment
		(start 414.109662 -281.026108)
		(end 413.00019 -281.026108)
		(width 0.18288)
		(layer "In6.Cu")
		(net "M_G_CPU0_SA_DQ<24>")
	)
	(segment
		(start 407.403808 -279.213818)
		(end 407.220928 -279.396698)
		(width 0.18288)
		(layer "In6.Cu")
		(net "M_G_CPU0_SA_DQ<24>")
	)
	(segment
		(start 410.38399 -281.099514)
		(end 410.38399 -280.286714)
		(width 0.18288)
		(layer "In6.Cu")
		(net "M_G_CPU0_SA_DQ<24>")
	)
	(segment
		(start 432.092608 -287.763712)
		(end 431.166778 -288.689542)
		(width 0.18288)
		(layer "In6.Cu")
		(net "M_G_CPU0_SA_DQ<24>")
	)
	(segment
		(start 411.26029 -280.103834)
		(end 411.07741 -280.286714)
		(width 0.18288)
		(layer "In6.Cu")
		(net "M_G_CPU0_SA_DQ<24>")
	)
	(segment
		(start 411.07741 -280.286714)
		(end 411.07741 -281.099514)
		(width 0.18288)
		(layer "In6.Cu")
		(net "M_G_CPU0_SA_DQ<24>")
	)
	(segment
		(start 375.868946 -269.881858)
		(end 375.854214 -269.873222)
		(width 0.088646)
		(layer "In6.Cu")
		(net "M_G_CPU0_SA_DQ<24>")
	)
	(segment
		(start 405.465026 -279.213818)
		(end 397.412464 -271.161256)
		(width 0.18288)
		(layer "In6.Cu")
		(net "M_G_CPU0_SA_DQ<24>")
	)
	(segment
		(start 418.762434 -286.993838)
		(end 418.33927 -286.570674)
		(width 0.18288)
		(layer "In6.Cu")
		(net "M_G_CPU0_SA_DQ<24>")
	)
	(segment
		(start 376.808746 -269.881858)
		(end 376.794014 -269.873222)
		(width 0.088646)
		(layer "In6.Cu")
		(net "M_G_CPU0_SA_DQ<24>")
	)
	(segment
		(start 407.220928 -280.286968)
		(end 407.038048 -280.469848)
		(width 0.18288)
		(layer "In6.Cu")
		(net "M_G_CPU0_SA_DQ<24>")
	)
	(segment
		(start 410.38399 -280.286714)
		(end 410.20111 -280.103834)
		(width 0.18288)
		(layer "In6.Cu")
		(net "M_G_CPU0_SA_DQ<24>")
	)
	(segment
		(start 381.118364 -269.873222)
		(end 381.10795 -269.879318)
		(width 0.088646)
		(layer "In6.Cu")
		(net "M_G_CPU0_SA_DQ<24>")
	)
	(segment
		(start 413.00019 -281.026108)
		(end 412.077916 -280.103834)
		(width 0.18288)
		(layer "In6.Cu")
		(net "M_G_CPU0_SA_DQ<24>")
	)
	(segment
		(start 387.760464 -269.948914)
		(end 387.414262 -269.948914)
		(width 0.088646)
		(layer "In6.Cu")
		(net "M_G_CPU0_SA_DQ<24>")
	)
	(segment
		(start 389.760968 -270.625316)
		(end 388.535672 -270.625316)
		(width 0.18288)
		(layer "In6.Cu")
		(net "M_G_CPU0_SA_DQ<24>")
	)
	(segment
		(start 385.266946 -269.881858)
		(end 385.252214 -269.873222)
		(width 0.088646)
		(layer "In6.Cu")
		(net "M_G_CPU0_SA_DQ<24>")
	)
	(segment
		(start 406.710388 -280.469848)
		(end 406.527508 -280.286968)
		(width 0.18288)
		(layer "In6.Cu")
		(net "M_G_CPU0_SA_DQ<24>")
	)
	(segment
		(start 386.206746 -269.881858)
		(end 386.192014 -269.873222)
		(width 0.088646)
		(layer "In6.Cu")
		(net "M_G_CPU0_SA_DQ<24>")
	)
	(segment
		(start 379.628146 -269.881858)
		(end 379.613414 -269.873222)
		(width 0.088646)
		(layer "In6.Cu")
		(net "M_G_CPU0_SA_DQ<24>")
	)
	(segment
		(start 418.33927 -284.110176)
		(end 417.66744 -283.438346)
		(width 0.18288)
		(layer "In6.Cu")
		(net "M_G_CPU0_SA_DQ<24>")
	)
	(segment
		(start 388.003034 -270.403066)
		(end 387.853428 -270.041878)
		(width 0.088646)
		(layer "In6.Cu")
		(net "M_G_CPU0_SA_DQ<24>")
	)
	(segment
		(start 417.66744 -283.438346)
		(end 416.5219 -283.438346)
		(width 0.18288)
		(layer "In6.Cu")
		(net "M_G_CPU0_SA_DQ<24>")
	)
	(segment
		(start 408.275028 -279.213818)
		(end 407.403808 -279.213818)
		(width 0.18288)
		(layer "In6.Cu")
		(net "M_G_CPU0_SA_DQ<24>")
	)
	(segment
		(start 397.412464 -271.161256)
		(end 392.455908 -271.161256)
		(width 0.18288)
		(layer "In6.Cu")
		(net "M_G_CPU0_SA_DQ<24>")
	)
	(segment
		(start 410.56687 -281.282394)
		(end 410.38399 -281.099514)
		(width 0.18288)
		(layer "In6.Cu")
		(net "M_G_CPU0_SA_DQ<24>")
	)
	(segment
		(start 377.748546 -269.881858)
		(end 377.733814 -269.873222)
		(width 0.088646)
		(layer "In6.Cu")
		(net "M_G_CPU0_SA_DQ<24>")
	)
	(segment
		(start 388.335774 -270.625316)
		(end 388.003034 -270.403066)
		(width 0.088646)
		(layer "In6.Cu")
		(net "M_G_CPU0_SA_DQ<24>")
	)
	(segment
		(start 421.021764 -286.993838)
		(end 418.762434 -286.993838)
		(width 0.18288)
		(layer "In6.Cu")
		(net "M_G_CPU0_SA_DQ<24>")
	)
	(segment
		(start 384.327146 -269.881858)
		(end 384.312414 -269.873222)
		(width 0.088646)
		(layer "In6.Cu")
		(net "M_G_CPU0_SA_DQ<24>")
	)
	(segment
		(start 410.89453 -281.282394)
		(end 410.56687 -281.282394)
		(width 0.18288)
		(layer "In6.Cu")
		(net "M_G_CPU0_SA_DQ<24>")
	)
	(segment
		(start 406.344628 -279.213818)
		(end 405.465026 -279.213818)
		(width 0.18288)
		(layer "In6.Cu")
		(net "M_G_CPU0_SA_DQ<24>")
	)
	(segment
		(start 387.853428 -270.041878)
		(end 387.760464 -269.948914)
		(width 0.088646)
		(layer "In6.Cu")
		(net "M_G_CPU0_SA_DQ<24>")
	)
	(segment
		(start 407.220928 -279.396698)
		(end 407.220928 -280.286968)
		(width 0.18288)
		(layer "In6.Cu")
		(net "M_G_CPU0_SA_DQ<24>")
	)
	(segment
		(start 406.527508 -280.286968)
		(end 406.527508 -279.396698)
		(width 0.18288)
		(layer "In6.Cu")
		(net "M_G_CPU0_SA_DQ<24>")
	)
	(segment
		(start 435.320694 -287.763712)
		(end 432.092608 -287.763712)
		(width 0.18288)
		(layer "In6.Cu")
		(net "M_G_CPU0_SA_DQ<24>")
	)
	(segment
		(start 375.825258 -269.856712)
		(end 375.196862 -269.38351)
		(width 0.088646)
		(layer "In6.Cu")
		(net "M_G_CPU0_SA_DQ<24>")
	)
	(segment
		(start 422.717468 -288.689542)
		(end 421.021764 -286.993838)
		(width 0.18288)
		(layer "In6.Cu")
		(net "M_G_CPU0_SA_DQ<24>")
	)
	(segment
		(start 382.447546 -269.881858)
		(end 382.432814 -269.873222)
		(width 0.088646)
		(layer "In6.Cu")
		(net "M_G_CPU0_SA_DQ<24>")
	)
	(segment
		(start 435.823614 -288.266632)
		(end 435.320694 -287.763712)
		(width 0.18288)
		(layer "In6.Cu")
		(net "M_G_CPU0_SA_DQ<24>")
	)
	(segment
		(start 409.165044 -280.103834)
		(end 408.275028 -279.213818)
		(width 0.18288)
		(layer "In6.Cu")
		(net "M_G_CPU0_SA_DQ<24>")
	)
	(arc
		(start 378.673614 -269.873222)
		(mid 378.486416 -269.823079)
		(end 378.299218 -269.873222)
		(width 0.088646)
		(layer "In6.Cu")
		(net "M_G_CPU0_SA_DQ<24>")
	)
	(arc
		(start 385.817618 -269.873222)
		(mid 385.543389 -269.949147)
		(end 385.266946 -269.881858)
		(width 0.088646)
		(layer "In6.Cu")
		(net "M_G_CPU0_SA_DQ<24>")
	)
	(arc
		(start 376.794014 -269.873222)
		(mid 376.606816 -269.823079)
		(end 376.419618 -269.873222)
		(width 0.088646)
		(layer "In6.Cu")
		(net "M_G_CPU0_SA_DQ<24>")
	)
	(arc
		(start 380.178818 -269.873222)
		(mid 379.904589 -269.949147)
		(end 379.628146 -269.881858)
		(width 0.088646)
		(layer "In6.Cu")
		(net "M_G_CPU0_SA_DQ<24>")
	)
	(arc
		(start 383.372614 -269.873222)
		(mid 383.185416 -269.823079)
		(end 382.998218 -269.873222)
		(width 0.088646)
		(layer "In6.Cu")
		(net "M_G_CPU0_SA_DQ<24>")
	)
	(arc
		(start 382.432814 -269.873222)
		(mid 382.245616 -269.823079)
		(end 382.058418 -269.873222)
		(width 0.088646)
		(layer "In6.Cu")
		(net "M_G_CPU0_SA_DQ<24>")
	)
	(arc
		(start 376.419618 -269.873222)
		(mid 376.145389 -269.949147)
		(end 375.868946 -269.881858)
		(width 0.088646)
		(layer "In6.Cu")
		(net "M_G_CPU0_SA_DQ<24>")
	)
	(arc
		(start 381.49276 -269.873222)
		(mid 381.305562 -269.823079)
		(end 381.118364 -269.873222)
		(width 0.088646)
		(layer "In6.Cu")
		(net "M_G_CPU0_SA_DQ<24>")
	)
	(arc
		(start 383.938018 -269.873222)
		(mid 383.663789 -269.949147)
		(end 383.387346 -269.881858)
		(width 0.088646)
		(layer "In6.Cu")
		(net "M_G_CPU0_SA_DQ<24>")
	)
	(arc
		(start 382.058418 -269.873222)
		(mid 381.781605 -269.949058)
		(end 381.503174 -269.879318)
		(width 0.088646)
		(layer "In6.Cu")
		(net "M_G_CPU0_SA_DQ<24>")
	)
	(arc
		(start 384.312414 -269.873222)
		(mid 384.125216 -269.823079)
		(end 383.938018 -269.873222)
		(width 0.088646)
		(layer "In6.Cu")
		(net "M_G_CPU0_SA_DQ<24>")
	)
	(arc
		(start 385.252214 -269.873222)
		(mid 385.065016 -269.823079)
		(end 384.877818 -269.873222)
		(width 0.088646)
		(layer "In6.Cu")
		(net "M_G_CPU0_SA_DQ<24>")
	)
	(arc
		(start 387.414262 -269.948914)
		(mid 387.268066 -269.929627)
		(end 387.131814 -269.873222)
		(width 0.088646)
		(layer "In6.Cu")
		(net "M_G_CPU0_SA_DQ<24>")
	)
	(arc
		(start 380.553214 -269.873222)
		(mid 380.366016 -269.823079)
		(end 380.178818 -269.873222)
		(width 0.088646)
		(layer "In6.Cu")
		(net "M_G_CPU0_SA_DQ<24>")
	)
	(arc
		(start 384.877818 -269.873222)
		(mid 384.603589 -269.949147)
		(end 384.327146 -269.881858)
		(width 0.088646)
		(layer "In6.Cu")
		(net "M_G_CPU0_SA_DQ<24>")
	)
	(arc
		(start 387.131814 -269.873222)
		(mid 386.944616 -269.823079)
		(end 386.757418 -269.873222)
		(width 0.088646)
		(layer "In6.Cu")
		(net "M_G_CPU0_SA_DQ<24>")
	)
	(arc
		(start 379.613414 -269.873222)
		(mid 379.426216 -269.823079)
		(end 379.239018 -269.873222)
		(width 0.088646)
		(layer "In6.Cu")
		(net "M_G_CPU0_SA_DQ<24>")
	)
	(arc
		(start 379.239018 -269.873222)
		(mid 378.964789 -269.949147)
		(end 378.688346 -269.881858)
		(width 0.088646)
		(layer "In6.Cu")
		(net "M_G_CPU0_SA_DQ<24>")
	)
	(arc
		(start 386.192014 -269.873222)
		(mid 386.004816 -269.823079)
		(end 385.817618 -269.873222)
		(width 0.088646)
		(layer "In6.Cu")
		(net "M_G_CPU0_SA_DQ<24>")
	)
	(arc
		(start 386.757418 -269.873222)
		(mid 386.483189 -269.949147)
		(end 386.206746 -269.881858)
		(width 0.088646)
		(layer "In6.Cu")
		(net "M_G_CPU0_SA_DQ<24>")
	)
	(arc
		(start 382.998218 -269.873222)
		(mid 382.723989 -269.949147)
		(end 382.447546 -269.881858)
		(width 0.088646)
		(layer "In6.Cu")
		(net "M_G_CPU0_SA_DQ<24>")
	)
	(arc
		(start 378.299218 -269.873222)
		(mid 378.024989 -269.949147)
		(end 377.748546 -269.881858)
		(width 0.088646)
		(layer "In6.Cu")
		(net "M_G_CPU0_SA_DQ<24>")
	)
	(arc
		(start 377.733814 -269.873222)
		(mid 377.546616 -269.823079)
		(end 377.359418 -269.873222)
		(width 0.088646)
		(layer "In6.Cu")
		(net "M_G_CPU0_SA_DQ<24>")
	)
	(arc
		(start 377.359418 -269.873222)
		(mid 377.085189 -269.949147)
		(end 376.808746 -269.881858)
		(width 0.088646)
		(layer "In6.Cu")
		(net "M_G_CPU0_SA_DQ<24>")
	)
	(arc
		(start 381.10795 -269.879318)
		(mid 380.829772 -269.94901)
		(end 380.553214 -269.873222)
		(width 0.088646)
		(layer "In6.Cu")
		(net "M_G_CPU0_SA_DQ<24>")
	)
	(segment
		(start 445.482726 -289.553904)
		(end 446.163954 -289.553904)
		(width 0.20066)
		(layer "F.Cu")
		(net "M_G_CPU0_SA_DQ<23>")
	)
	(segment
		(start 379.425962 -263.68629)
		(end 379.426216 -263.686544)
		(width 0.20066)
		(layer "F.Cu")
		(net "M_G_CPU0_SA_DQ<23>")
	)
	(segment
		(start 443.450726 -289.548824)
		(end 443.455552 -289.548824)
		(width 0.101854)
		(layer "F.Cu")
		(net "M_G_CPU0_SA_DQ<23>")
	)
	(segment
		(start 443.455552 -289.548824)
		(end 443.462664 -289.541712)
		(width 0.1016)
		(layer "F.Cu")
		(net "M_G_CPU0_SA_DQ<23>")
	)
	(segment
		(start 446.367916 -289.349942)
		(end 446.367916 -289.09899)
		(width 0.20066)
		(layer "F.Cu")
		(net "M_G_CPU0_SA_DQ<23>")
	)
	(segment
		(start 379.425962 -263.150604)
		(end 379.425962 -263.68629)
		(width 0.20066)
		(layer "F.Cu")
		(net "M_G_CPU0_SA_DQ<23>")
	)
	(segment
		(start 447.23812 -289.11677)
		(end 448.572382 -289.11677)
		(width 0.20066)
		(layer "F.Cu")
		(net "M_G_CPU0_SA_DQ<23>")
	)
	(segment
		(start 446.163954 -289.553904)
		(end 446.367916 -289.349942)
		(width 0.20066)
		(layer "F.Cu")
		(net "M_G_CPU0_SA_DQ<23>")
	)
	(segment
		(start 443.462664 -289.541712)
		(end 445.470534 -289.541712)
		(width 0.1016)
		(layer "F.Cu")
		(net "M_G_CPU0_SA_DQ<23>")
	)
	(segment
		(start 445.470534 -289.541712)
		(end 445.482726 -289.553904)
		(width 0.1016)
		(layer "F.Cu")
		(net "M_G_CPU0_SA_DQ<23>")
	)
	(segment
		(start 439.923682 -289.11677)
		(end 441.028582 -289.11677)
		(width 0.20066)
		(layer "F.Cu")
		(net "M_G_CPU0_SA_DQ<23>")
	)
	(segment
		(start 446.367916 -289.09899)
		(end 446.602104 -288.864802)
		(width 0.20066)
		(layer "F.Cu")
		(net "M_G_CPU0_SA_DQ<23>")
	)
	(segment
		(start 442.726826 -289.11677)
		(end 443.15888 -289.548824)
		(width 0.20066)
		(layer "F.Cu")
		(net "M_G_CPU0_SA_DQ<23>")
	)
	(segment
		(start 446.986152 -288.864802)
		(end 447.23812 -289.11677)
		(width 0.20066)
		(layer "F.Cu")
		(net "M_G_CPU0_SA_DQ<23>")
	)
	(segment
		(start 441.028582 -289.11677)
		(end 442.726826 -289.11677)
		(width 0.20066)
		(layer "F.Cu")
		(net "M_G_CPU0_SA_DQ<23>")
	)
	(segment
		(start 446.602104 -288.864802)
		(end 446.986152 -288.864802)
		(width 0.20066)
		(layer "F.Cu")
		(net "M_G_CPU0_SA_DQ<23>")
	)
	(segment
		(start 443.15888 -289.548824)
		(end 443.450726 -289.548824)
		(width 0.20066)
		(layer "F.Cu")
		(net "M_G_CPU0_SA_DQ<23>")
	)
	(segment
		(start 412.478728 -283.10078)
		(end 412.478728 -280.22296)
		(width 0.18288)
		(layer "In4.Cu")
		(net "M_G_CPU0_SA_DQ<23>")
	)
	(segment
		(start 385.827524 -263.244584)
		(end 385.576318 -263.244584)
		(width 0.088646)
		(layer "In4.Cu")
		(net "M_G_CPU0_SA_DQ<23>")
	)
	(segment
		(start 437.205374 -289.150806)
		(end 437.045354 -289.310826)
		(width 0.18288)
		(layer "In4.Cu")
		(net "M_G_CPU0_SA_DQ<23>")
	)
	(segment
		(start 438.653174 -288.519362)
		(end 437.552084 -288.519362)
		(width 0.18288)
		(layer "In4.Cu")
		(net "M_G_CPU0_SA_DQ<23>")
	)
	(segment
		(start 438.896252 -289.266884)
		(end 438.896252 -288.76244)
		(width 0.18288)
		(layer "In4.Cu")
		(net "M_G_CPU0_SA_DQ<23>")
	)
	(segment
		(start 381.968756 -263.19353)
		(end 381.962914 -263.196832)
		(width 0.088646)
		(layer "In4.Cu")
		(net "M_G_CPU0_SA_DQ<23>")
	)
	(segment
		(start 414.708594 -285.330646)
		(end 412.478728 -283.10078)
		(width 0.18288)
		(layer "In4.Cu")
		(net "M_G_CPU0_SA_DQ<23>")
	)
	(segment
		(start 384.407664 -263.196832)
		(end 384.407664 -263.197086)
		(width 0.088646)
		(layer "In4.Cu")
		(net "M_G_CPU0_SA_DQ<23>")
	)
	(segment
		(start 410.949394 -279.354026)
		(end 409.196794 -279.354026)
		(width 0.18288)
		(layer "In4.Cu")
		(net "M_G_CPU0_SA_DQ<23>")
	)
	(segment
		(start 414.708594 -285.61411)
		(end 414.708594 -285.330646)
		(width 0.18288)
		(layer "In4.Cu")
		(net "M_G_CPU0_SA_DQ<23>")
	)
	(segment
		(start 417.891722 -287.719008)
		(end 417.209732 -287.719008)
		(width 0.18288)
		(layer "In4.Cu")
		(net "M_G_CPU0_SA_DQ<23>")
	)
	(segment
		(start 420.651178 -288.692336)
		(end 420.225982 -288.868104)
		(width 0.18288)
		(layer "In4.Cu")
		(net "M_G_CPU0_SA_DQ<23>")
	)
	(segment
		(start 382.907286 -263.194292)
		(end 382.902714 -263.196832)
		(width 0.088646)
		(layer "In4.Cu")
		(net "M_G_CPU0_SA_DQ<23>")
	)
	(segment
		(start 417.209732 -287.719008)
		(end 415.667698 -286.176974)
		(width 0.18288)
		(layer "In4.Cu")
		(net "M_G_CPU0_SA_DQ<23>")
	)
	(segment
		(start 429.187864 -287.463484)
		(end 429.027844 -287.623504)
		(width 0.18288)
		(layer "In4.Cu")
		(net "M_G_CPU0_SA_DQ<23>")
	)
	(segment
		(start 426.760386 -287.842198)
		(end 424.62069 -287.842198)
		(width 0.18288)
		(layer "In4.Cu")
		(net "M_G_CPU0_SA_DQ<23>")
	)
	(segment
		(start 431.77333 -287.93059)
		(end 429.998886 -287.93059)
		(width 0.18288)
		(layer "In4.Cu")
		(net "M_G_CPU0_SA_DQ<23>")
	)
	(segment
		(start 389.253984 -263.531096)
		(end 386.605272 -263.531096)
		(width 0.18288)
		(layer "In4.Cu")
		(net "M_G_CPU0_SA_DQ<23>")
	)
	(segment
		(start 395.124686 -265.929872)
		(end 392.944604 -265.929872)
		(width 0.18288)
		(layer "In4.Cu")
		(net "M_G_CPU0_SA_DQ<23>")
	)
	(segment
		(start 429.998886 -287.93059)
		(end 429.838866 -287.77057)
		(width 0.18288)
		(layer "In4.Cu")
		(net "M_G_CPU0_SA_DQ<23>")
	)
	(segment
		(start 386.605272 -263.531096)
		(end 386.114036 -263.531096)
		(width 0.088646)
		(layer "In4.Cu")
		(net "M_G_CPU0_SA_DQ<23>")
	)
	(segment
		(start 427.916594 -287.93059)
		(end 427.662594 -287.67659)
		(width 0.18288)
		(layer "In4.Cu")
		(net "M_G_CPU0_SA_DQ<23>")
	)
	(segment
		(start 380.089156 -263.19353)
		(end 380.083314 -263.196832)
		(width 0.088646)
		(layer "In4.Cu")
		(net "M_G_CPU0_SA_DQ<23>")
	)
	(segment
		(start 437.205374 -288.866072)
		(end 437.205374 -289.150806)
		(width 0.18288)
		(layer "In4.Cu")
		(net "M_G_CPU0_SA_DQ<23>")
	)
	(segment
		(start 382.902714 -263.196832)
		(end 382.896872 -263.200388)
		(width 0.088646)
		(layer "In4.Cu")
		(net "M_G_CPU0_SA_DQ<23>")
	)
	(segment
		(start 405.493474 -277.094188)
		(end 404.929848 -275.735034)
		(width 0.18288)
		(layer "In4.Cu")
		(net "M_G_CPU0_SA_DQ<23>")
	)
	(segment
		(start 435.142894 -288.08426)
		(end 434.826156 -287.767522)
		(width 0.18288)
		(layer "In4.Cu")
		(net "M_G_CPU0_SA_DQ<23>")
	)
	(segment
		(start 436.473854 -288.851594)
		(end 436.313834 -288.691574)
		(width 0.18288)
		(layer "In4.Cu")
		(net "M_G_CPU0_SA_DQ<23>")
	)
	(segment
		(start 412.478728 -280.22296)
		(end 412.016194 -279.760426)
		(width 0.18288)
		(layer "In4.Cu")
		(net "M_G_CPU0_SA_DQ<23>")
	)
	(segment
		(start 406.25776 -277.604474)
		(end 405.493474 -277.094188)
		(width 0.18288)
		(layer "In4.Cu")
		(net "M_G_CPU0_SA_DQ<23>")
	)
	(segment
		(start 429.027844 -287.623504)
		(end 429.027844 -287.77057)
		(width 0.18288)
		(layer "In4.Cu")
		(net "M_G_CPU0_SA_DQ<23>")
	)
	(segment
		(start 412.016194 -279.760426)
		(end 411.355794 -279.760426)
		(width 0.18288)
		(layer "In4.Cu")
		(net "M_G_CPU0_SA_DQ<23>")
	)
	(segment
		(start 439.092594 -289.463226)
		(end 438.896252 -289.266884)
		(width 0.18288)
		(layer "In4.Cu")
		(net "M_G_CPU0_SA_DQ<23>")
	)
	(segment
		(start 421.236394 -288.692336)
		(end 420.651178 -288.692336)
		(width 0.18288)
		(layer "In4.Cu")
		(net "M_G_CPU0_SA_DQ<23>")
	)
	(segment
		(start 428.867824 -287.93059)
		(end 427.916594 -287.93059)
		(width 0.18288)
		(layer "In4.Cu")
		(net "M_G_CPU0_SA_DQ<23>")
	)
	(segment
		(start 383.84607 -263.1948)
		(end 383.842514 -263.196832)
		(width 0.088646)
		(layer "In4.Cu")
		(net "M_G_CPU0_SA_DQ<23>")
	)
	(segment
		(start 429.027844 -287.77057)
		(end 428.867824 -287.93059)
		(width 0.18288)
		(layer "In4.Cu")
		(net "M_G_CPU0_SA_DQ<23>")
	)
	(segment
		(start 429.838866 -287.77057)
		(end 429.838866 -287.623504)
		(width 0.18288)
		(layer "In4.Cu")
		(net "M_G_CPU0_SA_DQ<23>")
	)
	(segment
		(start 439.923682 -289.11677)
		(end 439.577226 -289.463226)
		(width 0.18288)
		(layer "In4.Cu")
		(net "M_G_CPU0_SA_DQ<23>")
	)
	(segment
		(start 435.142894 -288.391346)
		(end 435.142894 -288.08426)
		(width 0.18288)
		(layer "In4.Cu")
		(net "M_G_CPU0_SA_DQ<23>")
	)
	(segment
		(start 411.355794 -279.760426)
		(end 410.949394 -279.354026)
		(width 0.18288)
		(layer "In4.Cu")
		(net "M_G_CPU0_SA_DQ<23>")
	)
	(segment
		(start 424.498262 -287.964626)
		(end 421.964104 -287.964626)
		(width 0.18288)
		(layer "In4.Cu")
		(net "M_G_CPU0_SA_DQ<23>")
	)
	(segment
		(start 437.552084 -288.519362)
		(end 437.205374 -288.866072)
		(width 0.18288)
		(layer "In4.Cu")
		(net "M_G_CPU0_SA_DQ<23>")
	)
	(segment
		(start 435.443122 -288.691574)
		(end 435.142894 -288.391346)
		(width 0.18288)
		(layer "In4.Cu")
		(net "M_G_CPU0_SA_DQ<23>")
	)
	(segment
		(start 392.944604 -265.929872)
		(end 391.116566 -265.172698)
		(width 0.18288)
		(layer "In4.Cu")
		(net "M_G_CPU0_SA_DQ<23>")
	)
	(segment
		(start 386.114036 -263.531096)
		(end 385.827524 -263.244584)
		(width 0.088646)
		(layer "In4.Cu")
		(net "M_G_CPU0_SA_DQ<23>")
	)
	(segment
		(start 404.929848 -275.735034)
		(end 395.124686 -265.929872)
		(width 0.18288)
		(layer "In4.Cu")
		(net "M_G_CPU0_SA_DQ<23>")
	)
	(segment
		(start 431.936398 -287.767522)
		(end 431.77333 -287.93059)
		(width 0.18288)
		(layer "In4.Cu")
		(net "M_G_CPU0_SA_DQ<23>")
	)
	(segment
		(start 419.040818 -288.868104)
		(end 417.891722 -287.719008)
		(width 0.18288)
		(layer "In4.Cu")
		(net "M_G_CPU0_SA_DQ<23>")
	)
	(segment
		(start 415.667698 -286.176974)
		(end 415.271458 -286.176974)
		(width 0.18288)
		(layer "In4.Cu")
		(net "M_G_CPU0_SA_DQ<23>")
	)
	(segment
		(start 391.116566 -265.172698)
		(end 390.739376 -265.016488)
		(width 0.18288)
		(layer "In4.Cu")
		(net "M_G_CPU0_SA_DQ<23>")
	)
	(segment
		(start 381.023114 -263.196832)
		(end 381.017272 -263.200388)
		(width 0.088646)
		(layer "In4.Cu")
		(net "M_G_CPU0_SA_DQ<23>")
	)
	(segment
		(start 408.911044 -277.764494)
		(end 408.751024 -277.604474)
		(width 0.18288)
		(layer "In4.Cu")
		(net "M_G_CPU0_SA_DQ<23>")
	)
	(segment
		(start 408.911044 -279.068276)
		(end 408.911044 -277.764494)
		(width 0.18288)
		(layer "In4.Cu")
		(net "M_G_CPU0_SA_DQ<23>")
	)
	(segment
		(start 408.751024 -277.604474)
		(end 406.25776 -277.604474)
		(width 0.18288)
		(layer "In4.Cu")
		(net "M_G_CPU0_SA_DQ<23>")
	)
	(segment
		(start 426.925994 -287.67659)
		(end 426.760386 -287.842198)
		(width 0.18288)
		(layer "In4.Cu")
		(net "M_G_CPU0_SA_DQ<23>")
	)
	(segment
		(start 429.838866 -287.623504)
		(end 429.678846 -287.463484)
		(width 0.18288)
		(layer "In4.Cu")
		(net "M_G_CPU0_SA_DQ<23>")
	)
	(segment
		(start 424.62069 -287.842198)
		(end 424.498262 -287.964626)
		(width 0.18288)
		(layer "In4.Cu")
		(net "M_G_CPU0_SA_DQ<23>")
	)
	(segment
		(start 434.826156 -287.767522)
		(end 431.936398 -287.767522)
		(width 0.18288)
		(layer "In4.Cu")
		(net "M_G_CPU0_SA_DQ<23>")
	)
	(segment
		(start 438.896252 -288.76244)
		(end 438.653174 -288.519362)
		(width 0.18288)
		(layer "In4.Cu")
		(net "M_G_CPU0_SA_DQ<23>")
	)
	(segment
		(start 421.964104 -287.964626)
		(end 421.236394 -288.692336)
		(width 0.18288)
		(layer "In4.Cu")
		(net "M_G_CPU0_SA_DQ<23>")
	)
	(segment
		(start 436.473854 -289.150806)
		(end 436.473854 -288.851594)
		(width 0.18288)
		(layer "In4.Cu")
		(net "M_G_CPU0_SA_DQ<23>")
	)
	(segment
		(start 415.271458 -286.176974)
		(end 414.708594 -285.61411)
		(width 0.18288)
		(layer "In4.Cu")
		(net "M_G_CPU0_SA_DQ<23>")
	)
	(segment
		(start 436.313834 -288.691574)
		(end 435.443122 -288.691574)
		(width 0.18288)
		(layer "In4.Cu")
		(net "M_G_CPU0_SA_DQ<23>")
	)
	(segment
		(start 381.028956 -263.19353)
		(end 381.023114 -263.196832)
		(width 0.088646)
		(layer "In4.Cu")
		(net "M_G_CPU0_SA_DQ<23>")
	)
	(segment
		(start 390.739376 -265.016488)
		(end 389.253984 -263.531096)
		(width 0.18288)
		(layer "In4.Cu")
		(net "M_G_CPU0_SA_DQ<23>")
	)
	(segment
		(start 420.225982 -288.868104)
		(end 419.040818 -288.868104)
		(width 0.18288)
		(layer "In4.Cu")
		(net "M_G_CPU0_SA_DQ<23>")
	)
	(segment
		(start 437.045354 -289.310826)
		(end 436.633874 -289.310826)
		(width 0.18288)
		(layer "In4.Cu")
		(net "M_G_CPU0_SA_DQ<23>")
	)
	(segment
		(start 436.633874 -289.310826)
		(end 436.473854 -289.150806)
		(width 0.18288)
		(layer "In4.Cu")
		(net "M_G_CPU0_SA_DQ<23>")
	)
	(segment
		(start 429.678846 -287.463484)
		(end 429.187864 -287.463484)
		(width 0.18288)
		(layer "In4.Cu")
		(net "M_G_CPU0_SA_DQ<23>")
	)
	(segment
		(start 381.962914 -263.196832)
		(end 381.957072 -263.200388)
		(width 0.088646)
		(layer "In4.Cu")
		(net "M_G_CPU0_SA_DQ<23>")
	)
	(segment
		(start 439.577226 -289.463226)
		(end 439.092594 -289.463226)
		(width 0.18288)
		(layer "In4.Cu")
		(net "M_G_CPU0_SA_DQ<23>")
	)
	(segment
		(start 427.662594 -287.67659)
		(end 426.925994 -287.67659)
		(width 0.18288)
		(layer "In4.Cu")
		(net "M_G_CPU0_SA_DQ<23>")
	)
	(segment
		(start 380.083314 -263.196832)
		(end 380.081282 -263.198102)
		(width 0.088646)
		(layer "In4.Cu")
		(net "M_G_CPU0_SA_DQ<23>")
	)
	(segment
		(start 409.196794 -279.354026)
		(end 408.911044 -279.068276)
		(width 0.18288)
		(layer "In4.Cu")
		(net "M_G_CPU0_SA_DQ<23>")
	)
	(arc
		(start 383.842514 -263.196832)
		(mid 383.655206 -263.246975)
		(end 383.467864 -263.196832)
		(width 0.088646)
		(layer "In4.Cu")
		(net "M_G_CPU0_SA_DQ<23>")
	)
	(arc
		(start 380.648464 -263.197086)
		(mid 380.36929 -263.121287)
		(end 380.089156 -263.19353)
		(width 0.088646)
		(layer "In4.Cu")
		(net "M_G_CPU0_SA_DQ<23>")
	)
	(arc
		(start 382.528064 -263.197086)
		(mid 382.24889 -263.121287)
		(end 381.968756 -263.19353)
		(width 0.088646)
		(layer "In4.Cu")
		(net "M_G_CPU0_SA_DQ<23>")
	)
	(arc
		(start 383.467864 -263.196832)
		(mid 383.18792 -263.121188)
		(end 382.907286 -263.194292)
		(width 0.088646)
		(layer "In4.Cu")
		(net "M_G_CPU0_SA_DQ<23>")
	)
	(arc
		(start 381.017272 -263.200388)
		(mid 380.832417 -263.247306)
		(end 380.648464 -263.197086)
		(width 0.088646)
		(layer "In4.Cu")
		(net "M_G_CPU0_SA_DQ<23>")
	)
	(arc
		(start 381.588264 -263.197086)
		(mid 381.30909 -263.121287)
		(end 381.028956 -263.19353)
		(width 0.088646)
		(layer "In4.Cu")
		(net "M_G_CPU0_SA_DQ<23>")
	)
	(arc
		(start 384.407664 -263.197086)
		(mid 384.127183 -263.121314)
		(end 383.84607 -263.1948)
		(width 0.088646)
		(layer "In4.Cu")
		(net "M_G_CPU0_SA_DQ<23>")
	)
	(arc
		(start 382.896872 -263.200388)
		(mid 382.712017 -263.247306)
		(end 382.528064 -263.197086)
		(width 0.088646)
		(layer "In4.Cu")
		(net "M_G_CPU0_SA_DQ<23>")
	)
	(arc
		(start 385.347464 -263.196832)
		(mid 385.064762 -263.12109)
		(end 384.78206 -263.196832)
		(width 0.088646)
		(layer "In4.Cu")
		(net "M_G_CPU0_SA_DQ<23>")
	)
	(arc
		(start 380.081282 -263.198102)
		(mid 379.743717 -263.428869)
		(end 379.426216 -263.686544)
		(width 0.088646)
		(layer "In4.Cu")
		(net "M_G_CPU0_SA_DQ<23>")
	)
	(arc
		(start 381.957072 -263.200388)
		(mid 381.772217 -263.247306)
		(end 381.588264 -263.197086)
		(width 0.088646)
		(layer "In4.Cu")
		(net "M_G_CPU0_SA_DQ<23>")
	)
	(arc
		(start 385.576318 -263.244584)
		(mid 385.458081 -263.238993)
		(end 385.347464 -263.196832)
		(width 0.088646)
		(layer "In4.Cu")
		(net "M_G_CPU0_SA_DQ<23>")
	)
	(arc
		(start 384.78206 -263.196832)
		(mid 384.594862 -263.246975)
		(end 384.407664 -263.196832)
		(width 0.088646)
		(layer "In4.Cu")
		(net "M_G_CPU0_SA_DQ<23>")
	)
	(segment
		(start 446.602104 -290.564824)
		(end 446.986152 -290.564824)
		(width 0.20066)
		(layer "F.Cu")
		(net "M_G_CPU0_SA_DQ<22>")
	)
	(segment
		(start 446.367916 -291.049964)
		(end 446.367916 -290.799012)
		(width 0.20066)
		(layer "F.Cu")
		(net "M_G_CPU0_SA_DQ<22>")
	)
	(segment
		(start 443.462664 -291.241734)
		(end 445.470534 -291.241734)
		(width 0.1016)
		(layer "F.Cu")
		(net "M_G_CPU0_SA_DQ<22>")
	)
	(segment
		(start 447.23812 -290.816792)
		(end 448.572382 -290.816792)
		(width 0.20066)
		(layer "F.Cu")
		(net "M_G_CPU0_SA_DQ<22>")
	)
	(segment
		(start 439.923936 -290.816792)
		(end 441.028582 -290.816792)
		(width 0.20066)
		(layer "F.Cu")
		(net "M_G_CPU0_SA_DQ<22>")
	)
	(segment
		(start 443.455552 -291.248846)
		(end 443.462664 -291.241734)
		(width 0.1016)
		(layer "F.Cu")
		(net "M_G_CPU0_SA_DQ<22>")
	)
	(segment
		(start 443.15888 -291.248846)
		(end 443.450726 -291.248846)
		(width 0.20066)
		(layer "F.Cu")
		(net "M_G_CPU0_SA_DQ<22>")
	)
	(segment
		(start 442.726826 -290.816792)
		(end 443.15888 -291.248846)
		(width 0.20066)
		(layer "F.Cu")
		(net "M_G_CPU0_SA_DQ<22>")
	)
	(segment
		(start 379.896116 -264.500106)
		(end 379.895862 -264.50036)
		(width 0.20066)
		(layer "F.Cu")
		(net "M_G_CPU0_SA_DQ<22>")
	)
	(segment
		(start 446.163954 -291.253926)
		(end 446.367916 -291.049964)
		(width 0.20066)
		(layer "F.Cu")
		(net "M_G_CPU0_SA_DQ<22>")
	)
	(segment
		(start 446.986152 -290.564824)
		(end 447.23812 -290.816792)
		(width 0.20066)
		(layer "F.Cu")
		(net "M_G_CPU0_SA_DQ<22>")
	)
	(segment
		(start 445.470534 -291.241734)
		(end 445.482726 -291.253926)
		(width 0.1016)
		(layer "F.Cu")
		(net "M_G_CPU0_SA_DQ<22>")
	)
	(segment
		(start 441.028582 -290.816792)
		(end 442.726826 -290.816792)
		(width 0.20066)
		(layer "F.Cu")
		(net "M_G_CPU0_SA_DQ<22>")
	)
	(segment
		(start 443.450726 -291.248846)
		(end 443.455552 -291.248846)
		(width 0.101854)
		(layer "F.Cu")
		(net "M_G_CPU0_SA_DQ<22>")
	)
	(segment
		(start 379.896116 -263.96442)
		(end 379.896116 -264.500106)
		(width 0.20066)
		(layer "F.Cu")
		(net "M_G_CPU0_SA_DQ<22>")
	)
	(segment
		(start 439.923682 -290.816538)
		(end 439.923936 -290.816792)
		(width 0.20066)
		(layer "F.Cu")
		(net "M_G_CPU0_SA_DQ<22>")
	)
	(segment
		(start 445.482726 -291.253926)
		(end 446.163954 -291.253926)
		(width 0.20066)
		(layer "F.Cu")
		(net "M_G_CPU0_SA_DQ<22>")
	)
	(segment
		(start 446.367916 -290.799012)
		(end 446.602104 -290.564824)
		(width 0.20066)
		(layer "F.Cu")
		(net "M_G_CPU0_SA_DQ<22>")
	)
	(segment
		(start 414.34512 -287.447228)
		(end 414.34512 -286.953198)
		(width 0.18288)
		(layer "In4.Cu")
		(net "M_G_CPU0_SA_DQ<22>")
	)
	(segment
		(start 428.73549 -289.60699)
		(end 427.865794 -289.60699)
		(width 0.18288)
		(layer "In4.Cu")
		(net "M_G_CPU0_SA_DQ<22>")
	)
	(segment
		(start 382.443228 -264.004806)
		(end 382.432814 -264.010902)
		(width 0.088646)
		(layer "In4.Cu")
		(net "M_G_CPU0_SA_DQ<22>")
	)
	(segment
		(start 405.060404 -279.05202)
		(end 403.803612 -276.016974)
		(width 0.18288)
		(layer "In4.Cu")
		(net "M_G_CPU0_SA_DQ<22>")
	)
	(segment
		(start 426.427392 -289.825176)
		(end 425.367958 -289.825176)
		(width 0.18288)
		(layer "In4.Cu")
		(net "M_G_CPU0_SA_DQ<22>")
	)
	(segment
		(start 419.41115 -290.505642)
		(end 418.81552 -289.910012)
		(width 0.18288)
		(layer "In4.Cu")
		(net "M_G_CPU0_SA_DQ<22>")
	)
	(segment
		(start 388.923784 -264.215626)
		(end 386.605272 -264.215626)
		(width 0.18288)
		(layer "In4.Cu")
		(net "M_G_CPU0_SA_DQ<22>")
	)
	(segment
		(start 427.865794 -289.60699)
		(end 427.68012 -289.421316)
		(width 0.18288)
		(layer "In4.Cu")
		(net "M_G_CPU0_SA_DQ<22>")
	)
	(segment
		(start 406.907238 -280.344626)
		(end 405.80945 -279.246838)
		(width 0.18288)
		(layer "In4.Cu")
		(net "M_G_CPU0_SA_DQ<22>")
	)
	(segment
		(start 435.962044 -290.391596)
		(end 435.196488 -290.391596)
		(width 0.18288)
		(layer "In4.Cu")
		(net "M_G_CPU0_SA_DQ<22>")
	)
	(segment
		(start 381.124206 -264.014204)
		(end 381.118364 -264.010902)
		(width 0.088646)
		(layer "In4.Cu")
		(net "M_G_CPU0_SA_DQ<22>")
	)
	(segment
		(start 437.209692 -291.434774)
		(end 436.775098 -291.434774)
		(width 0.18288)
		(layer "In4.Cu")
		(net "M_G_CPU0_SA_DQ<22>")
	)
	(segment
		(start 410.868114 -283.349954)
		(end 410.868114 -281.708606)
		(width 0.18288)
		(layer "In4.Cu")
		(net "M_G_CPU0_SA_DQ<22>")
	)
	(segment
		(start 439.362596 -290.255452)
		(end 437.679846 -290.255452)
		(width 0.18288)
		(layer "In4.Cu")
		(net "M_G_CPU0_SA_DQ<22>")
	)
	(segment
		(start 422.089326 -289.666426)
		(end 421.363394 -290.392358)
		(width 0.18288)
		(layer "In4.Cu")
		(net "M_G_CPU0_SA_DQ<22>")
	)
	(segment
		(start 420.129462 -290.392358)
		(end 420.016178 -290.505642)
		(width 0.18288)
		(layer "In4.Cu")
		(net "M_G_CPU0_SA_DQ<22>")
	)
	(segment
		(start 434.252878 -290.52139)
		(end 433.830984 -290.099496)
		(width 0.18288)
		(layer "In4.Cu")
		(net "M_G_CPU0_SA_DQ<22>")
	)
	(segment
		(start 382.058164 -264.010902)
		(end 382.052322 -264.007346)
		(width 0.088646)
		(layer "In4.Cu")
		(net "M_G_CPU0_SA_DQ<22>")
	)
	(segment
		(start 423.115994 -289.666426)
		(end 422.089326 -289.666426)
		(width 0.18288)
		(layer "In4.Cu")
		(net "M_G_CPU0_SA_DQ<22>")
	)
	(segment
		(start 429.42891 -289.907472)
		(end 429.035972 -289.907472)
		(width 0.18288)
		(layer "In4.Cu")
		(net "M_G_CPU0_SA_DQ<22>")
	)
	(segment
		(start 412.164276 -284.430978)
		(end 411.949138 -284.430978)
		(width 0.18288)
		(layer "In4.Cu")
		(net "M_G_CPU0_SA_DQ<22>")
	)
	(segment
		(start 418.81552 -289.910012)
		(end 417.912804 -289.910012)
		(width 0.18288)
		(layer "In4.Cu")
		(net "M_G_CPU0_SA_DQ<22>")
	)
	(segment
		(start 433.268882 -290.099496)
		(end 432.872388 -290.49599)
		(width 0.18288)
		(layer "In4.Cu")
		(net "M_G_CPU0_SA_DQ<22>")
	)
	(segment
		(start 405.80945 -279.246838)
		(end 405.351996 -279.246838)
		(width 0.18288)
		(layer "In4.Cu")
		(net "M_G_CPU0_SA_DQ<22>")
	)
	(segment
		(start 432.872388 -290.49599)
		(end 431.744374 -290.49599)
		(width 0.18288)
		(layer "In4.Cu")
		(net "M_G_CPU0_SA_DQ<22>")
	)
	(segment
		(start 412.71698 -284.756098)
		(end 412.489396 -284.756098)
		(width 0.18288)
		(layer "In4.Cu")
		(net "M_G_CPU0_SA_DQ<22>")
	)
	(segment
		(start 414.75025 -287.852358)
		(end 414.34512 -287.447228)
		(width 0.18288)
		(layer "In4.Cu")
		(net "M_G_CPU0_SA_DQ<22>")
	)
	(segment
		(start 420.016178 -290.505642)
		(end 419.41115 -290.505642)
		(width 0.18288)
		(layer "In4.Cu")
		(net "M_G_CPU0_SA_DQ<22>")
	)
	(segment
		(start 437.369712 -290.565586)
		(end 437.369712 -291.274754)
		(width 0.18288)
		(layer "In4.Cu")
		(net "M_G_CPU0_SA_DQ<22>")
	)
	(segment
		(start 413.502094 -286.110172)
		(end 413.502094 -285.541212)
		(width 0.18288)
		(layer "In4.Cu")
		(net "M_G_CPU0_SA_DQ<22>")
	)
	(segment
		(start 392.745976 -266.925552)
		(end 391.00379 -266.203938)
		(width 0.18288)
		(layer "In4.Cu")
		(net "M_G_CPU0_SA_DQ<22>")
	)
	(segment
		(start 394.71219 -266.925552)
		(end 392.745976 -266.925552)
		(width 0.18288)
		(layer "In4.Cu")
		(net "M_G_CPU0_SA_DQ<22>")
	)
	(segment
		(start 435.066694 -290.52139)
		(end 434.252878 -290.52139)
		(width 0.18288)
		(layer "In4.Cu")
		(net "M_G_CPU0_SA_DQ<22>")
	)
	(segment
		(start 427.68012 -289.421316)
		(end 426.831252 -289.421316)
		(width 0.18288)
		(layer "In4.Cu")
		(net "M_G_CPU0_SA_DQ<22>")
	)
	(segment
		(start 390.847326 -266.139168)
		(end 388.923784 -264.215626)
		(width 0.18288)
		(layer "In4.Cu")
		(net "M_G_CPU0_SA_DQ<22>")
	)
	(segment
		(start 433.830984 -290.099496)
		(end 433.268882 -290.099496)
		(width 0.18288)
		(layer "In4.Cu")
		(net "M_G_CPU0_SA_DQ<22>")
	)
	(segment
		(start 409.018994 -281.081226)
		(end 408.282394 -280.344626)
		(width 0.18288)
		(layer "In4.Cu")
		(net "M_G_CPU0_SA_DQ<22>")
	)
	(segment
		(start 411.949138 -284.430978)
		(end 410.868114 -283.349954)
		(width 0.18288)
		(layer "In4.Cu")
		(net "M_G_CPU0_SA_DQ<22>")
	)
	(segment
		(start 436.775098 -291.434774)
		(end 436.615078 -291.274754)
		(width 0.18288)
		(layer "In4.Cu")
		(net "M_G_CPU0_SA_DQ<22>")
	)
	(segment
		(start 405.351996 -279.246838)
		(end 405.060404 -279.05202)
		(width 0.18288)
		(layer "In4.Cu")
		(net "M_G_CPU0_SA_DQ<22>")
	)
	(segment
		(start 436.455058 -290.392612)
		(end 435.96306 -290.392612)
		(width 0.18288)
		(layer "In4.Cu")
		(net "M_G_CPU0_SA_DQ<22>")
	)
	(segment
		(start 386.605272 -264.215626)
		(end 386.04825 -264.215626)
		(width 0.088646)
		(layer "In4.Cu")
		(net "M_G_CPU0_SA_DQ<22>")
	)
	(segment
		(start 429.035972 -289.907472)
		(end 428.73549 -289.60699)
		(width 0.18288)
		(layer "In4.Cu")
		(net "M_G_CPU0_SA_DQ<22>")
	)
	(segment
		(start 380.553214 -264.010902)
		(end 380.474728 -264.056114)
		(width 0.088646)
		(layer "In4.Cu")
		(net "M_G_CPU0_SA_DQ<22>")
	)
	(segment
		(start 436.615078 -290.552632)
		(end 436.455058 -290.392612)
		(width 0.18288)
		(layer "In4.Cu")
		(net "M_G_CPU0_SA_DQ<22>")
	)
	(segment
		(start 410.240734 -281.081226)
		(end 409.018994 -281.081226)
		(width 0.18288)
		(layer "In4.Cu")
		(net "M_G_CPU0_SA_DQ<22>")
	)
	(segment
		(start 431.744374 -290.49599)
		(end 430.855374 -289.60699)
		(width 0.18288)
		(layer "In4.Cu")
		(net "M_G_CPU0_SA_DQ<22>")
	)
	(segment
		(start 423.239946 -289.542474)
		(end 423.115994 -289.666426)
		(width 0.18288)
		(layer "In4.Cu")
		(net "M_G_CPU0_SA_DQ<22>")
	)
	(segment
		(start 430.855374 -289.60699)
		(end 429.729392 -289.60699)
		(width 0.18288)
		(layer "In4.Cu")
		(net "M_G_CPU0_SA_DQ<22>")
	)
	(segment
		(start 413.502094 -285.541212)
		(end 412.71698 -284.756098)
		(width 0.18288)
		(layer "In4.Cu")
		(net "M_G_CPU0_SA_DQ<22>")
	)
	(segment
		(start 425.085256 -289.542474)
		(end 423.239946 -289.542474)
		(width 0.18288)
		(layer "In4.Cu")
		(net "M_G_CPU0_SA_DQ<22>")
	)
	(segment
		(start 415.438082 -287.852358)
		(end 414.75025 -287.852358)
		(width 0.18288)
		(layer "In4.Cu")
		(net "M_G_CPU0_SA_DQ<22>")
	)
	(segment
		(start 439.923682 -290.816538)
		(end 439.362596 -290.255452)
		(width 0.18288)
		(layer "In4.Cu")
		(net "M_G_CPU0_SA_DQ<22>")
	)
	(segment
		(start 410.868114 -281.708606)
		(end 410.240734 -281.081226)
		(width 0.18288)
		(layer "In4.Cu")
		(net "M_G_CPU0_SA_DQ<22>")
	)
	(segment
		(start 408.282394 -280.344626)
		(end 406.907238 -280.344626)
		(width 0.18288)
		(layer "In4.Cu")
		(net "M_G_CPU0_SA_DQ<22>")
	)
	(segment
		(start 385.76758 -263.934956)
		(end 385.534916 -263.934956)
		(width 0.088646)
		(layer "In4.Cu")
		(net "M_G_CPU0_SA_DQ<22>")
	)
	(segment
		(start 437.369712 -291.274754)
		(end 437.209692 -291.434774)
		(width 0.18288)
		(layer "In4.Cu")
		(net "M_G_CPU0_SA_DQ<22>")
	)
	(segment
		(start 403.803612 -276.016974)
		(end 394.71219 -266.925552)
		(width 0.18288)
		(layer "In4.Cu")
		(net "M_G_CPU0_SA_DQ<22>")
	)
	(segment
		(start 435.96306 -290.392612)
		(end 435.962044 -290.391596)
		(width 0.18288)
		(layer "In4.Cu")
		(net "M_G_CPU0_SA_DQ<22>")
	)
	(segment
		(start 381.118364 -264.010902)
		(end 381.112522 -264.007346)
		(width 0.088646)
		(layer "In4.Cu")
		(net "M_G_CPU0_SA_DQ<22>")
	)
	(segment
		(start 421.363394 -290.392358)
		(end 420.129462 -290.392358)
		(width 0.18288)
		(layer "In4.Cu")
		(net "M_G_CPU0_SA_DQ<22>")
	)
	(segment
		(start 414.34512 -286.953198)
		(end 413.502094 -286.110172)
		(width 0.18288)
		(layer "In4.Cu")
		(net "M_G_CPU0_SA_DQ<22>")
	)
	(segment
		(start 417.085272 -289.499548)
		(end 415.438082 -287.852358)
		(width 0.18288)
		(layer "In4.Cu")
		(net "M_G_CPU0_SA_DQ<22>")
	)
	(segment
		(start 382.064006 -264.014204)
		(end 382.058164 -264.010902)
		(width 0.088646)
		(layer "In4.Cu")
		(net "M_G_CPU0_SA_DQ<22>")
	)
	(segment
		(start 386.04825 -264.215626)
		(end 385.76758 -263.934956)
		(width 0.088646)
		(layer "In4.Cu")
		(net "M_G_CPU0_SA_DQ<22>")
	)
	(segment
		(start 429.729392 -289.60699)
		(end 429.42891 -289.907472)
		(width 0.18288)
		(layer "In4.Cu")
		(net "M_G_CPU0_SA_DQ<22>")
	)
	(segment
		(start 417.912804 -289.910012)
		(end 417.50234 -289.499548)
		(width 0.18288)
		(layer "In4.Cu")
		(net "M_G_CPU0_SA_DQ<22>")
	)
	(segment
		(start 425.367958 -289.825176)
		(end 425.085256 -289.542474)
		(width 0.18288)
		(layer "In4.Cu")
		(net "M_G_CPU0_SA_DQ<22>")
	)
	(segment
		(start 412.489396 -284.756098)
		(end 412.164276 -284.430978)
		(width 0.18288)
		(layer "In4.Cu")
		(net "M_G_CPU0_SA_DQ<22>")
	)
	(segment
		(start 417.50234 -289.499548)
		(end 417.085272 -289.499548)
		(width 0.18288)
		(layer "In4.Cu")
		(net "M_G_CPU0_SA_DQ<22>")
	)
	(segment
		(start 436.615078 -291.274754)
		(end 436.615078 -290.552632)
		(width 0.18288)
		(layer "In4.Cu")
		(net "M_G_CPU0_SA_DQ<22>")
	)
	(segment
		(start 391.00379 -266.203938)
		(end 390.847326 -266.139168)
		(width 0.18288)
		(layer "In4.Cu")
		(net "M_G_CPU0_SA_DQ<22>")
	)
	(segment
		(start 435.196488 -290.391596)
		(end 435.066694 -290.52139)
		(width 0.18288)
		(layer "In4.Cu")
		(net "M_G_CPU0_SA_DQ<22>")
	)
	(segment
		(start 437.679846 -290.255452)
		(end 437.369712 -290.565586)
		(width 0.18288)
		(layer "In4.Cu")
		(net "M_G_CPU0_SA_DQ<22>")
	)
	(segment
		(start 426.831252 -289.421316)
		(end 426.427392 -289.825176)
		(width 0.18288)
		(layer "In4.Cu")
		(net "M_G_CPU0_SA_DQ<22>")
	)
	(arc
		(start 385.534916 -263.934956)
		(mid 385.388429 -263.954271)
		(end 385.25196 -264.010902)
		(width 0.088646)
		(layer "In4.Cu")
		(net "M_G_CPU0_SA_DQ<22>")
	)
	(arc
		(start 383.37236 -264.010902)
		(mid 383.185162 -264.061045)
		(end 382.997964 -264.010902)
		(width 0.088646)
		(layer "In4.Cu")
		(net "M_G_CPU0_SA_DQ<22>")
	)
	(arc
		(start 382.432814 -264.010902)
		(mid 382.24886 -264.061031)
		(end 382.064006 -264.014204)
		(width 0.088646)
		(layer "In4.Cu")
		(net "M_G_CPU0_SA_DQ<22>")
	)
	(arc
		(start 380.474728 -264.056114)
		(mid 380.17063 -264.259127)
		(end 379.895862 -264.50036)
		(width 0.088646)
		(layer "In4.Cu")
		(net "M_G_CPU0_SA_DQ<22>")
	)
	(arc
		(start 384.31216 -264.010902)
		(mid 384.124962 -264.061045)
		(end 383.937764 -264.010902)
		(width 0.088646)
		(layer "In4.Cu")
		(net "M_G_CPU0_SA_DQ<22>")
	)
	(arc
		(start 382.052322 -264.007346)
		(mid 381.772187 -263.935063)
		(end 381.493014 -264.010902)
		(width 0.088646)
		(layer "In4.Cu")
		(net "M_G_CPU0_SA_DQ<22>")
	)
	(arc
		(start 383.937764 -264.010902)
		(mid 383.655062 -263.935126)
		(end 383.37236 -264.010902)
		(width 0.088646)
		(layer "In4.Cu")
		(net "M_G_CPU0_SA_DQ<22>")
	)
	(arc
		(start 381.493014 -264.010902)
		(mid 381.30906 -264.061031)
		(end 381.124206 -264.014204)
		(width 0.088646)
		(layer "In4.Cu")
		(net "M_G_CPU0_SA_DQ<22>")
	)
	(arc
		(start 384.877564 -264.010902)
		(mid 384.594862 -263.935126)
		(end 384.31216 -264.010902)
		(width 0.088646)
		(layer "In4.Cu")
		(net "M_G_CPU0_SA_DQ<22>")
	)
	(arc
		(start 382.997964 -264.010902)
		(mid 382.721405 -263.935159)
		(end 382.443228 -264.004806)
		(width 0.088646)
		(layer "In4.Cu")
		(net "M_G_CPU0_SA_DQ<22>")
	)
	(arc
		(start 381.112522 -264.007346)
		(mid 380.832387 -263.935063)
		(end 380.553214 -264.010902)
		(width 0.088646)
		(layer "In4.Cu")
		(net "M_G_CPU0_SA_DQ<22>")
	)
	(arc
		(start 385.25196 -264.010902)
		(mid 385.064762 -264.061045)
		(end 384.877564 -264.010902)
		(width 0.088646)
		(layer "In4.Cu")
		(net "M_G_CPU0_SA_DQ<22>")
	)
	(segment
		(start 442.032644 -289.541712)
		(end 439.843926 -289.541712)
		(width 0.1016)
		(layer "F.Cu")
		(net "M_G_CPU0_SA_DQ<21>")
	)
	(segment
		(start 439.361072 -290.02736)
		(end 439.173112 -290.21532)
		(width 0.20066)
		(layer "F.Cu")
		(net "M_G_CPU0_SA_DQ<21>")
	)
	(segment
		(start 378.486162 -263.150604)
		(end 378.486162 -263.68629)
		(width 0.20066)
		(layer "F.Cu")
		(net "M_G_CPU0_SA_DQ<21>")
	)
	(segment
		(start 439.82386 -289.541712)
		(end 439.479182 -289.541712)
		(width 0.20066)
		(layer "F.Cu")
		(net "M_G_CPU0_SA_DQ<21>")
	)
	(segment
		(start 444.472314 -289.966654)
		(end 444.47206 -289.966908)
		(width 0.20066)
		(layer "F.Cu")
		(net "M_G_CPU0_SA_DQ<21>")
	)
	(segment
		(start 444.47206 -289.966908)
		(end 442.880496 -289.966908)
		(width 0.20066)
		(layer "F.Cu")
		(net "M_G_CPU0_SA_DQ<21>")
	)
	(segment
		(start 436.928514 -289.966654)
		(end 435.823614 -289.966654)
		(width 0.20066)
		(layer "F.Cu")
		(net "M_G_CPU0_SA_DQ<21>")
	)
	(segment
		(start 438.697878 -290.21532)
		(end 438.449212 -289.966654)
		(width 0.20066)
		(layer "F.Cu")
		(net "M_G_CPU0_SA_DQ<21>")
	)
	(segment
		(start 439.173112 -290.21532)
		(end 438.697878 -290.21532)
		(width 0.20066)
		(layer "F.Cu")
		(net "M_G_CPU0_SA_DQ<21>")
	)
	(segment
		(start 442.880496 -289.966908)
		(end 442.44895 -289.535362)
		(width 0.20066)
		(layer "F.Cu")
		(net "M_G_CPU0_SA_DQ<21>")
	)
	(segment
		(start 442.44895 -289.535362)
		(end 442.038994 -289.535362)
		(width 0.20066)
		(layer "F.Cu")
		(net "M_G_CPU0_SA_DQ<21>")
	)
	(segment
		(start 442.038994 -289.535362)
		(end 442.032644 -289.541712)
		(width 0.1016)
		(layer "F.Cu")
		(net "M_G_CPU0_SA_DQ<21>")
	)
	(segment
		(start 439.361072 -289.659822)
		(end 439.361072 -290.02736)
		(width 0.20066)
		(layer "F.Cu")
		(net "M_G_CPU0_SA_DQ<21>")
	)
	(segment
		(start 438.449212 -289.966654)
		(end 436.928514 -289.966654)
		(width 0.20066)
		(layer "F.Cu")
		(net "M_G_CPU0_SA_DQ<21>")
	)
	(segment
		(start 378.486162 -263.68629)
		(end 378.486416 -263.686544)
		(width 0.20066)
		(layer "F.Cu")
		(net "M_G_CPU0_SA_DQ<21>")
	)
	(segment
		(start 439.479182 -289.541712)
		(end 439.361072 -289.659822)
		(width 0.20066)
		(layer "F.Cu")
		(net "M_G_CPU0_SA_DQ<21>")
	)
	(segment
		(start 439.843926 -289.541712)
		(end 439.82386 -289.541712)
		(width 0.101854)
		(layer "F.Cu")
		(net "M_G_CPU0_SA_DQ<21>")
	)
	(segment
		(start 414.195514 -285.525718)
		(end 412.523686 -283.85389)
		(width 0.18288)
		(layer "In4.Cu")
		(net "M_G_CPU0_SA_DQ<21>")
	)
	(segment
		(start 427.668436 -288.915348)
		(end 426.983652 -288.915348)
		(width 0.18288)
		(layer "In4.Cu")
		(net "M_G_CPU0_SA_DQ<21>")
	)
	(segment
		(start 428.844964 -288.693098)
		(end 427.890686 -288.693098)
		(width 0.18288)
		(layer "In4.Cu")
		(net "M_G_CPU0_SA_DQ<21>")
	)
	(segment
		(start 379.991112 -263.686544)
		(end 379.991112 -263.692894)
		(width 0.088646)
		(layer "In4.Cu")
		(net "M_G_CPU0_SA_DQ<21>")
	)
	(segment
		(start 408.963114 -280.166826)
		(end 408.383994 -279.587706)
		(width 0.18288)
		(layer "In4.Cu")
		(net "M_G_CPU0_SA_DQ<21>")
	)
	(segment
		(start 425.348146 -288.692082)
		(end 424.499786 -288.692082)
		(width 0.18288)
		(layer "In4.Cu")
		(net "M_G_CPU0_SA_DQ<21>")
	)
	(segment
		(start 382.997964 -263.361932)
		(end 382.992122 -263.365488)
		(width 0.088646)
		(layer "In4.Cu")
		(net "M_G_CPU0_SA_DQ<21>")
	)
	(segment
		(start 414.195514 -285.990284)
		(end 414.195514 -285.525718)
		(width 0.18288)
		(layer "In4.Cu")
		(net "M_G_CPU0_SA_DQ<21>")
	)
	(segment
		(start 418.770308 -289.404044)
		(end 418.304218 -288.937954)
		(width 0.18288)
		(layer "In4.Cu")
		(net "M_G_CPU0_SA_DQ<21>")
	)
	(segment
		(start 426.254164 -289.115754)
		(end 426.066966 -289.302952)
		(width 0.18288)
		(layer "In4.Cu")
		(net "M_G_CPU0_SA_DQ<21>")
	)
	(segment
		(start 419.020498 -289.404044)
		(end 418.770308 -289.404044)
		(width 0.18288)
		(layer "In4.Cu")
		(net "M_G_CPU0_SA_DQ<21>")
	)
	(segment
		(start 433.75326 -289.450018)
		(end 433.613306 -289.310064)
		(width 0.18288)
		(layer "In4.Cu")
		(net "M_G_CPU0_SA_DQ<21>")
	)
	(segment
		(start 411.617414 -281.898344)
		(end 411.617414 -281.230324)
		(width 0.18288)
		(layer "In4.Cu")
		(net "M_G_CPU0_SA_DQ<21>")
	)
	(segment
		(start 382.064006 -263.35863)
		(end 382.058164 -263.361932)
		(width 0.088646)
		(layer "In4.Cu")
		(net "M_G_CPU0_SA_DQ<21>")
	)
	(segment
		(start 432.577748 -289.45459)
		(end 431.802794 -289.45459)
		(width 0.18288)
		(layer "In4.Cu")
		(net "M_G_CPU0_SA_DQ<21>")
	)
	(segment
		(start 411.457394 -280.557224)
		(end 411.066996 -280.166826)
		(width 0.18288)
		(layer "In4.Cu")
		(net "M_G_CPU0_SA_DQ<21>")
	)
	(segment
		(start 419.158928 -289.542474)
		(end 419.020498 -289.404044)
		(width 0.18288)
		(layer "In4.Cu")
		(net "M_G_CPU0_SA_DQ<21>")
	)
	(segment
		(start 429.928274 -288.66719)
		(end 429.768254 -288.82721)
		(width 0.18288)
		(layer "In4.Cu")
		(net "M_G_CPU0_SA_DQ<21>")
	)
	(segment
		(start 432.849274 -289.183064)
		(end 432.577748 -289.45459)
		(width 0.18288)
		(layer "In4.Cu")
		(net "M_G_CPU0_SA_DQ<21>")
	)
	(segment
		(start 423.671746 -288.738564)
		(end 423.511726 -288.578544)
		(width 0.18288)
		(layer "In4.Cu")
		(net "M_G_CPU0_SA_DQ<21>")
	)
	(segment
		(start 433.009294 -288.280348)
		(end 432.849274 -288.440368)
		(width 0.18288)
		(layer "In4.Cu")
		(net "M_G_CPU0_SA_DQ<21>")
	)
	(segment
		(start 433.372514 -288.280348)
		(end 433.009294 -288.280348)
		(width 0.18288)
		(layer "In4.Cu")
		(net "M_G_CPU0_SA_DQ<21>")
	)
	(segment
		(start 379.26645 -264.117582)
		(end 379.082046 -263.933178)
		(width 0.088646)
		(layer "In4.Cu")
		(net "M_G_CPU0_SA_DQ<21>")
	)
	(segment
		(start 386.605272 -263.87171)
		(end 386.514594 -263.87171)
		(width 0.088646)
		(layer "In4.Cu")
		(net "M_G_CPU0_SA_DQ<21>")
	)
	(segment
		(start 426.254164 -288.930842)
		(end 426.254164 -289.115754)
		(width 0.18288)
		(layer "In4.Cu")
		(net "M_G_CPU0_SA_DQ<21>")
	)
	(segment
		(start 418.304218 -288.937954)
		(end 417.235132 -288.937954)
		(width 0.18288)
		(layer "In4.Cu")
		(net "M_G_CPU0_SA_DQ<21>")
	)
	(segment
		(start 435.823614 -289.966654)
		(end 435.306978 -289.450018)
		(width 0.18288)
		(layer "In4.Cu")
		(net "M_G_CPU0_SA_DQ<21>")
	)
	(segment
		(start 416.245548 -287.94837)
		(end 416.245548 -287.46069)
		(width 0.18288)
		(layer "In4.Cu")
		(net "M_G_CPU0_SA_DQ<21>")
	)
	(segment
		(start 423.831766 -289.031172)
		(end 423.671746 -288.871152)
		(width 0.18288)
		(layer "In4.Cu")
		(net "M_G_CPU0_SA_DQ<21>")
	)
	(segment
		(start 427.890686 -288.693098)
		(end 427.668436 -288.915348)
		(width 0.18288)
		(layer "In4.Cu")
		(net "M_G_CPU0_SA_DQ<21>")
	)
	(segment
		(start 425.539662 -288.883598)
		(end 425.348146 -288.692082)
		(width 0.18288)
		(layer "In4.Cu")
		(net "M_G_CPU0_SA_DQ<21>")
	)
	(segment
		(start 429.768254 -288.82721)
		(end 429.768254 -288.92881)
		(width 0.18288)
		(layer "In4.Cu")
		(net "M_G_CPU0_SA_DQ<21>")
	)
	(segment
		(start 429.004984 -288.92881)
		(end 429.004984 -288.853118)
		(width 0.18288)
		(layer "In4.Cu")
		(net "M_G_CPU0_SA_DQ<21>")
	)
	(segment
		(start 386.154422 -263.871964)
		(end 385.720336 -263.437878)
		(width 0.088646)
		(layer "In4.Cu")
		(net "M_G_CPU0_SA_DQ<21>")
	)
	(segment
		(start 433.613306 -289.310064)
		(end 433.613306 -288.52114)
		(width 0.18288)
		(layer "In4.Cu")
		(net "M_G_CPU0_SA_DQ<21>")
	)
	(segment
		(start 435.306978 -289.450018)
		(end 433.75326 -289.450018)
		(width 0.18288)
		(layer "In4.Cu")
		(net "M_G_CPU0_SA_DQ<21>")
	)
	(segment
		(start 417.235132 -288.937954)
		(end 416.245548 -287.94837)
		(width 0.18288)
		(layer "In4.Cu")
		(net "M_G_CPU0_SA_DQ<21>")
	)
	(segment
		(start 394.918438 -266.427712)
		(end 392.84529 -266.427712)
		(width 0.18288)
		(layer "In4.Cu")
		(net "M_G_CPU0_SA_DQ<21>")
	)
	(segment
		(start 425.722542 -289.302952)
		(end 425.539662 -289.120072)
		(width 0.18288)
		(layer "In4.Cu")
		(net "M_G_CPU0_SA_DQ<21>")
	)
	(segment
		(start 389.074914 -263.87171)
		(end 386.605272 -263.87171)
		(width 0.18288)
		(layer "In4.Cu")
		(net "M_G_CPU0_SA_DQ<21>")
	)
	(segment
		(start 383.942082 -263.359392)
		(end 383.937764 -263.361932)
		(width 0.088646)
		(layer "In4.Cu")
		(net "M_G_CPU0_SA_DQ<21>")
	)
	(segment
		(start 426.983652 -288.915348)
		(end 426.760386 -288.692082)
		(width 0.18288)
		(layer "In4.Cu")
		(net "M_G_CPU0_SA_DQ<21>")
	)
	(segment
		(start 423.511726 -288.578544)
		(end 422.174924 -288.578544)
		(width 0.18288)
		(layer "In4.Cu")
		(net "M_G_CPU0_SA_DQ<21>")
	)
	(segment
		(start 412.20263 -283.85389)
		(end 411.457394 -283.108654)
		(width 0.18288)
		(layer "In4.Cu")
		(net "M_G_CPU0_SA_DQ<21>")
	)
	(segment
		(start 407.849324 -278.644096)
		(end 405.48179 -278.644096)
		(width 0.18288)
		(layer "In4.Cu")
		(net "M_G_CPU0_SA_DQ<21>")
	)
	(segment
		(start 383.001774 -263.3599)
		(end 382.997964 -263.361932)
		(width 0.088646)
		(layer "In4.Cu")
		(net "M_G_CPU0_SA_DQ<21>")
	)
	(segment
		(start 431.53584 -289.187636)
		(end 431.53584 -288.89452)
		(width 0.18288)
		(layer "In4.Cu")
		(net "M_G_CPU0_SA_DQ<21>")
	)
	(segment
		(start 386.514594 -263.87171)
		(end 386.51434 -263.871964)
		(width 0.088646)
		(layer "In4.Cu")
		(net "M_G_CPU0_SA_DQ<21>")
	)
	(segment
		(start 429.165004 -289.08883)
		(end 429.004984 -288.92881)
		(width 0.18288)
		(layer "In4.Cu")
		(net "M_G_CPU0_SA_DQ<21>")
	)
	(segment
		(start 429.004984 -288.853118)
		(end 428.844964 -288.693098)
		(width 0.18288)
		(layer "In4.Cu")
		(net "M_G_CPU0_SA_DQ<21>")
	)
	(segment
		(start 411.066996 -280.166826)
		(end 408.963114 -280.166826)
		(width 0.18288)
		(layer "In4.Cu")
		(net "M_G_CPU0_SA_DQ<21>")
	)
	(segment
		(start 411.457394 -282.058364)
		(end 411.617414 -281.898344)
		(width 0.18288)
		(layer "In4.Cu")
		(net "M_G_CPU0_SA_DQ<21>")
	)
	(segment
		(start 426.492924 -288.692082)
		(end 426.254164 -288.930842)
		(width 0.18288)
		(layer "In4.Cu")
		(net "M_G_CPU0_SA_DQ<21>")
	)
	(segment
		(start 429.768254 -288.92881)
		(end 429.608234 -289.08883)
		(width 0.18288)
		(layer "In4.Cu")
		(net "M_G_CPU0_SA_DQ<21>")
	)
	(segment
		(start 425.539662 -289.120072)
		(end 425.539662 -288.883598)
		(width 0.18288)
		(layer "In4.Cu")
		(net "M_G_CPU0_SA_DQ<21>")
	)
	(segment
		(start 381.118364 -263.361932)
		(end 381.112522 -263.365488)
		(width 0.088646)
		(layer "In4.Cu")
		(net "M_G_CPU0_SA_DQ<21>")
	)
	(segment
		(start 429.608234 -289.08883)
		(end 429.165004 -289.08883)
		(width 0.18288)
		(layer "In4.Cu")
		(net "M_G_CPU0_SA_DQ<21>")
	)
	(segment
		(start 408.383994 -279.178766)
		(end 407.849324 -278.644096)
		(width 0.18288)
		(layer "In4.Cu")
		(net "M_G_CPU0_SA_DQ<21>")
	)
	(segment
		(start 404.226014 -275.735288)
		(end 394.918438 -266.427712)
		(width 0.18288)
		(layer "In4.Cu")
		(net "M_G_CPU0_SA_DQ<21>")
	)
	(segment
		(start 385.720336 -263.437878)
		(end 385.546346 -263.437878)
		(width 0.088646)
		(layer "In4.Cu")
		(net "M_G_CPU0_SA_DQ<21>")
	)
	(segment
		(start 382.058164 -263.361932)
		(end 382.052322 -263.365488)
		(width 0.088646)
		(layer "In4.Cu")
		(net "M_G_CPU0_SA_DQ<21>")
	)
	(segment
		(start 424.179746 -289.031172)
		(end 423.831766 -289.031172)
		(width 0.18288)
		(layer "In4.Cu")
		(net "M_G_CPU0_SA_DQ<21>")
	)
	(segment
		(start 412.523686 -283.85389)
		(end 412.20263 -283.85389)
		(width 0.18288)
		(layer "In4.Cu")
		(net "M_G_CPU0_SA_DQ<21>")
	)
	(segment
		(start 405.48179 -278.644096)
		(end 405.395176 -278.557482)
		(width 0.18288)
		(layer "In4.Cu")
		(net "M_G_CPU0_SA_DQ<21>")
	)
	(segment
		(start 426.066966 -289.302952)
		(end 425.722542 -289.302952)
		(width 0.18288)
		(layer "In4.Cu")
		(net "M_G_CPU0_SA_DQ<21>")
	)
	(segment
		(start 431.30851 -288.66719)
		(end 429.928274 -288.66719)
		(width 0.18288)
		(layer "In4.Cu")
		(net "M_G_CPU0_SA_DQ<21>")
	)
	(segment
		(start 433.613306 -288.52114)
		(end 433.372514 -288.280348)
		(width 0.18288)
		(layer "In4.Cu")
		(net "M_G_CPU0_SA_DQ<21>")
	)
	(segment
		(start 431.802794 -289.45459)
		(end 431.53584 -289.187636)
		(width 0.18288)
		(layer "In4.Cu")
		(net "M_G_CPU0_SA_DQ<21>")
	)
	(segment
		(start 405.395176 -278.557482)
		(end 404.226014 -275.735288)
		(width 0.18288)
		(layer "In4.Cu")
		(net "M_G_CPU0_SA_DQ<21>")
	)
	(segment
		(start 380.178564 -263.361932)
		(end 380.173484 -263.36498)
		(width 0.088646)
		(layer "In4.Cu")
		(net "M_G_CPU0_SA_DQ<21>")
	)
	(segment
		(start 415.51606 -286.731202)
		(end 414.936432 -286.731202)
		(width 0.18288)
		(layer "In4.Cu")
		(net "M_G_CPU0_SA_DQ<21>")
	)
	(segment
		(start 416.245548 -287.46069)
		(end 415.51606 -286.731202)
		(width 0.18288)
		(layer "In4.Cu")
		(net "M_G_CPU0_SA_DQ<21>")
	)
	(segment
		(start 414.936432 -286.731202)
		(end 414.195514 -285.990284)
		(width 0.18288)
		(layer "In4.Cu")
		(net "M_G_CPU0_SA_DQ<21>")
	)
	(segment
		(start 422.174924 -288.578544)
		(end 421.210994 -289.542474)
		(width 0.18288)
		(layer "In4.Cu")
		(net "M_G_CPU0_SA_DQ<21>")
	)
	(segment
		(start 380.184406 -263.35863)
		(end 380.178564 -263.361932)
		(width 0.088646)
		(layer "In4.Cu")
		(net "M_G_CPU0_SA_DQ<21>")
	)
	(segment
		(start 423.671746 -288.871152)
		(end 423.671746 -288.738564)
		(width 0.18288)
		(layer "In4.Cu")
		(net "M_G_CPU0_SA_DQ<21>")
	)
	(segment
		(start 411.617414 -281.230324)
		(end 411.457394 -281.070304)
		(width 0.18288)
		(layer "In4.Cu")
		(net "M_G_CPU0_SA_DQ<21>")
	)
	(segment
		(start 431.53584 -288.89452)
		(end 431.30851 -288.66719)
		(width 0.18288)
		(layer "In4.Cu")
		(net "M_G_CPU0_SA_DQ<21>")
	)
	(segment
		(start 408.383994 -279.587706)
		(end 408.383994 -279.178766)
		(width 0.18288)
		(layer "In4.Cu")
		(net "M_G_CPU0_SA_DQ<21>")
	)
	(segment
		(start 426.760386 -288.692082)
		(end 426.492924 -288.692082)
		(width 0.18288)
		(layer "In4.Cu")
		(net "M_G_CPU0_SA_DQ<21>")
	)
	(segment
		(start 411.457394 -283.108654)
		(end 411.457394 -282.058364)
		(width 0.18288)
		(layer "In4.Cu")
		(net "M_G_CPU0_SA_DQ<21>")
	)
	(segment
		(start 381.124206 -263.35863)
		(end 381.118364 -263.361932)
		(width 0.088646)
		(layer "In4.Cu")
		(net "M_G_CPU0_SA_DQ<21>")
	)
	(segment
		(start 392.84529 -266.427712)
		(end 390.772142 -265.568938)
		(width 0.18288)
		(layer "In4.Cu")
		(net "M_G_CPU0_SA_DQ<21>")
	)
	(segment
		(start 432.849274 -288.440368)
		(end 432.849274 -289.183064)
		(width 0.18288)
		(layer "In4.Cu")
		(net "M_G_CPU0_SA_DQ<21>")
	)
	(segment
		(start 386.51434 -263.871964)
		(end 386.154422 -263.871964)
		(width 0.088646)
		(layer "In4.Cu")
		(net "M_G_CPU0_SA_DQ<21>")
	)
	(segment
		(start 411.457394 -281.070304)
		(end 411.457394 -280.557224)
		(width 0.18288)
		(layer "In4.Cu")
		(net "M_G_CPU0_SA_DQ<21>")
	)
	(segment
		(start 424.339766 -288.871152)
		(end 424.179746 -289.031172)
		(width 0.18288)
		(layer "In4.Cu")
		(net "M_G_CPU0_SA_DQ<21>")
	)
	(segment
		(start 424.339766 -288.852102)
		(end 424.339766 -288.871152)
		(width 0.18288)
		(layer "In4.Cu")
		(net "M_G_CPU0_SA_DQ<21>")
	)
	(segment
		(start 390.772142 -265.568938)
		(end 389.074914 -263.87171)
		(width 0.18288)
		(layer "In4.Cu")
		(net "M_G_CPU0_SA_DQ<21>")
	)
	(segment
		(start 384.31216 -263.362186)
		(end 384.312414 -263.361932)
		(width 0.088646)
		(layer "In4.Cu")
		(net "M_G_CPU0_SA_DQ<21>")
	)
	(segment
		(start 424.499786 -288.692082)
		(end 424.339766 -288.852102)
		(width 0.18288)
		(layer "In4.Cu")
		(net "M_G_CPU0_SA_DQ<21>")
	)
	(segment
		(start 421.210994 -289.542474)
		(end 419.158928 -289.542474)
		(width 0.18288)
		(layer "In4.Cu")
		(net "M_G_CPU0_SA_DQ<21>")
	)
	(arc
		(start 384.877564 -263.362186)
		(mid 384.594862 -263.437928)
		(end 384.31216 -263.362186)
		(width 0.088646)
		(layer "In4.Cu")
		(net "M_G_CPU0_SA_DQ<21>")
	)
	(arc
		(start 382.432814 -263.361932)
		(mid 382.24886 -263.311803)
		(end 382.064006 -263.35863)
		(width 0.088646)
		(layer "In4.Cu")
		(net "M_G_CPU0_SA_DQ<21>")
	)
	(arc
		(start 383.372614 -263.361932)
		(mid 383.187464 -263.311828)
		(end 383.001774 -263.3599)
		(width 0.088646)
		(layer "In4.Cu")
		(net "M_G_CPU0_SA_DQ<21>")
	)
	(arc
		(start 382.992122 -263.365488)
		(mid 382.711987 -263.437771)
		(end 382.432814 -263.361932)
		(width 0.088646)
		(layer "In4.Cu")
		(net "M_G_CPU0_SA_DQ<21>")
	)
	(arc
		(start 381.112522 -263.365488)
		(mid 380.832387 -263.437771)
		(end 380.553214 -263.361932)
		(width 0.088646)
		(layer "In4.Cu")
		(net "M_G_CPU0_SA_DQ<21>")
	)
	(arc
		(start 379.708664 -264.175748)
		(mid 379.477705 -264.221677)
		(end 379.26645 -264.117582)
		(width 0.088646)
		(layer "In4.Cu")
		(net "M_G_CPU0_SA_DQ<21>")
	)
	(arc
		(start 381.493014 -263.361932)
		(mid 381.30906 -263.311803)
		(end 381.124206 -263.35863)
		(width 0.088646)
		(layer "In4.Cu")
		(net "M_G_CPU0_SA_DQ<21>")
	)
	(arc
		(start 383.937764 -263.361932)
		(mid 383.655206 -263.437581)
		(end 383.372614 -263.361932)
		(width 0.088646)
		(layer "In4.Cu")
		(net "M_G_CPU0_SA_DQ<21>")
	)
	(arc
		(start 385.546346 -263.437878)
		(mid 385.393958 -263.420215)
		(end 385.25196 -263.362186)
		(width 0.088646)
		(layer "In4.Cu")
		(net "M_G_CPU0_SA_DQ<21>")
	)
	(arc
		(start 385.25196 -263.362186)
		(mid 385.064762 -263.312043)
		(end 384.877564 -263.362186)
		(width 0.088646)
		(layer "In4.Cu")
		(net "M_G_CPU0_SA_DQ<21>")
	)
	(arc
		(start 380.553214 -263.361932)
		(mid 380.36926 -263.311803)
		(end 380.184406 -263.35863)
		(width 0.088646)
		(layer "In4.Cu")
		(net "M_G_CPU0_SA_DQ<21>")
	)
	(arc
		(start 379.991112 -263.692894)
		(mid 379.913795 -263.971697)
		(end 379.708664 -264.175748)
		(width 0.088646)
		(layer "In4.Cu")
		(net "M_G_CPU0_SA_DQ<21>")
	)
	(arc
		(start 382.052322 -263.365488)
		(mid 381.772187 -263.437771)
		(end 381.493014 -263.361932)
		(width 0.088646)
		(layer "In4.Cu")
		(net "M_G_CPU0_SA_DQ<21>")
	)
	(arc
		(start 384.312414 -263.361932)
		(mid 384.127577 -263.311671)
		(end 383.942082 -263.359392)
		(width 0.088646)
		(layer "In4.Cu")
		(net "M_G_CPU0_SA_DQ<21>")
	)
	(arc
		(start 379.082046 -263.933178)
		(mid 378.808754 -263.750634)
		(end 378.486416 -263.686544)
		(width 0.088646)
		(layer "In4.Cu")
		(net "M_G_CPU0_SA_DQ<21>")
	)
	(arc
		(start 380.173484 -263.36498)
		(mid 380.039868 -263.5017)
		(end 379.991112 -263.686544)
		(width 0.088646)
		(layer "In4.Cu")
		(net "M_G_CPU0_SA_DQ<21>")
	)
	(segment
		(start 444.47206 -291.66693)
		(end 442.880496 -291.66693)
		(width 0.20066)
		(layer "F.Cu")
		(net "M_G_CPU0_SA_DQ<20>")
	)
	(segment
		(start 439.361072 -291.727382)
		(end 439.173112 -291.915342)
		(width 0.20066)
		(layer "F.Cu")
		(net "M_G_CPU0_SA_DQ<20>")
	)
	(segment
		(start 439.361072 -291.359844)
		(end 439.361072 -291.727382)
		(width 0.20066)
		(layer "F.Cu")
		(net "M_G_CPU0_SA_DQ<20>")
	)
	(segment
		(start 439.173112 -291.915342)
		(end 438.697878 -291.915342)
		(width 0.20066)
		(layer "F.Cu")
		(net "M_G_CPU0_SA_DQ<20>")
	)
	(segment
		(start 442.032644 -291.241734)
		(end 439.87085 -291.241734)
		(width 0.1016)
		(layer "F.Cu")
		(net "M_G_CPU0_SA_DQ<20>")
	)
	(segment
		(start 439.479182 -291.241734)
		(end 439.361072 -291.359844)
		(width 0.20066)
		(layer "F.Cu")
		(net "M_G_CPU0_SA_DQ<20>")
	)
	(segment
		(start 442.038994 -291.235384)
		(end 442.032644 -291.241734)
		(width 0.1016)
		(layer "F.Cu")
		(net "M_G_CPU0_SA_DQ<20>")
	)
	(segment
		(start 436.928514 -291.666676)
		(end 435.823614 -291.666676)
		(width 0.20066)
		(layer "F.Cu")
		(net "M_G_CPU0_SA_DQ<20>")
	)
	(segment
		(start 444.472314 -291.666676)
		(end 444.47206 -291.66693)
		(width 0.20066)
		(layer "F.Cu")
		(net "M_G_CPU0_SA_DQ<20>")
	)
	(segment
		(start 439.82386 -291.241734)
		(end 439.479182 -291.241734)
		(width 0.20066)
		(layer "F.Cu")
		(net "M_G_CPU0_SA_DQ<20>")
	)
	(segment
		(start 442.880496 -291.66693)
		(end 442.44895 -291.235384)
		(width 0.20066)
		(layer "F.Cu")
		(net "M_G_CPU0_SA_DQ<20>")
	)
	(segment
		(start 442.44895 -291.235384)
		(end 442.038994 -291.235384)
		(width 0.20066)
		(layer "F.Cu")
		(net "M_G_CPU0_SA_DQ<20>")
	)
	(segment
		(start 378.016516 -264.500106)
		(end 378.016262 -264.50036)
		(width 0.20066)
		(layer "F.Cu")
		(net "M_G_CPU0_SA_DQ<20>")
	)
	(segment
		(start 438.449212 -291.666676)
		(end 436.928514 -291.666676)
		(width 0.20066)
		(layer "F.Cu")
		(net "M_G_CPU0_SA_DQ<20>")
	)
	(segment
		(start 378.016516 -263.96442)
		(end 378.016516 -264.500106)
		(width 0.20066)
		(layer "F.Cu")
		(net "M_G_CPU0_SA_DQ<20>")
	)
	(segment
		(start 438.697878 -291.915342)
		(end 438.449212 -291.666676)
		(width 0.20066)
		(layer "F.Cu")
		(net "M_G_CPU0_SA_DQ<20>")
	)
	(segment
		(start 439.87085 -291.241734)
		(end 439.82386 -291.241734)
		(width 0.101854)
		(layer "F.Cu")
		(net "M_G_CPU0_SA_DQ<20>")
	)
	(segment
		(start 413.764222 -287.68167)
		(end 413.764222 -287.149032)
		(width 0.18288)
		(layer "In4.Cu")
		(net "M_G_CPU0_SA_DQ<20>")
	)
	(segment
		(start 427.560994 -290.34359)
		(end 427.220634 -290.68395)
		(width 0.18288)
		(layer "In4.Cu")
		(net "M_G_CPU0_SA_DQ<20>")
	)
	(segment
		(start 386.605272 -264.5537)
		(end 386.08889 -264.5537)
		(width 0.088646)
		(layer "In4.Cu")
		(net "M_G_CPU0_SA_DQ<20>")
	)
	(segment
		(start 420.193724 -291.114226)
		(end 419.534594 -291.114226)
		(width 0.18288)
		(layer "In4.Cu")
		(net "M_G_CPU0_SA_DQ<20>")
	)
	(segment
		(start 426.961554 -290.68395)
		(end 426.669962 -290.392358)
		(width 0.18288)
		(layer "In4.Cu")
		(net "M_G_CPU0_SA_DQ<20>")
	)
	(segment
		(start 421.925496 -291.574474)
		(end 421.479472 -291.574474)
		(width 0.18288)
		(layer "In4.Cu")
		(net "M_G_CPU0_SA_DQ<20>")
	)
	(segment
		(start 385.660392 -264.125202)
		(end 385.534916 -264.125202)
		(width 0.088646)
		(layer "In4.Cu")
		(net "M_G_CPU0_SA_DQ<20>")
	)
	(segment
		(start 426.322236 -290.392358)
		(end 426.162216 -290.552378)
		(width 0.18288)
		(layer "In4.Cu")
		(net "M_G_CPU0_SA_DQ<20>")
	)
	(segment
		(start 413.764222 -287.149032)
		(end 413.331406 -286.716216)
		(width 0.18288)
		(layer "In4.Cu")
		(net "M_G_CPU0_SA_DQ<20>")
	)
	(segment
		(start 421.479472 -291.574474)
		(end 421.147494 -291.242496)
		(width 0.18288)
		(layer "In4.Cu")
		(net "M_G_CPU0_SA_DQ<20>")
	)
	(segment
		(start 421.147494 -291.242496)
		(end 420.321994 -291.242496)
		(width 0.18288)
		(layer "In4.Cu")
		(net "M_G_CPU0_SA_DQ<20>")
	)
	(segment
		(start 415.405062 -288.523426)
		(end 414.605978 -288.523426)
		(width 0.18288)
		(layer "In4.Cu")
		(net "M_G_CPU0_SA_DQ<20>")
	)
	(segment
		(start 413.331406 -286.716216)
		(end 412.851092 -286.716216)
		(width 0.18288)
		(layer "In4.Cu")
		(net "M_G_CPU0_SA_DQ<20>")
	)
	(segment
		(start 381.028956 -264.179304)
		(end 381.023114 -264.175748)
		(width 0.088646)
		(layer "In4.Cu")
		(net "M_G_CPU0_SA_DQ<20>")
	)
	(segment
		(start 434.005736 -291.58692)
		(end 432.954684 -291.58692)
		(width 0.18288)
		(layer "In4.Cu")
		(net "M_G_CPU0_SA_DQ<20>")
	)
	(segment
		(start 429.481742 -290.975288)
		(end 428.977806 -290.975288)
		(width 0.18288)
		(layer "In4.Cu")
		(net "M_G_CPU0_SA_DQ<20>")
	)
	(segment
		(start 418.531294 -291.279326)
		(end 418.531294 -290.974526)
		(width 0.18288)
		(layer "In4.Cu")
		(net "M_G_CPU0_SA_DQ<20>")
	)
	(segment
		(start 431.726594 -291.20719)
		(end 430.85004 -290.330636)
		(width 0.18288)
		(layer "In4.Cu")
		(net "M_G_CPU0_SA_DQ<20>")
	)
	(segment
		(start 409.975812 -281.682444)
		(end 408.883612 -281.682444)
		(width 0.18288)
		(layer "In4.Cu")
		(net "M_G_CPU0_SA_DQ<20>")
	)
	(segment
		(start 423.613326 -290.392358)
		(end 423.446194 -290.225226)
		(width 0.18288)
		(layer "In4.Cu")
		(net "M_G_CPU0_SA_DQ<20>")
	)
	(segment
		(start 426.162216 -290.774882)
		(end 426.002196 -290.934902)
		(width 0.18288)
		(layer "In4.Cu")
		(net "M_G_CPU0_SA_DQ<20>")
	)
	(segment
		(start 428.817786 -290.815268)
		(end 428.817786 -290.50361)
		(width 0.18288)
		(layer "In4.Cu")
		(net "M_G_CPU0_SA_DQ<20>")
	)
	(segment
		(start 426.162216 -290.552378)
		(end 426.162216 -290.774882)
		(width 0.18288)
		(layer "In4.Cu")
		(net "M_G_CPU0_SA_DQ<20>")
	)
	(segment
		(start 422.404032 -290.225226)
		(end 422.293542 -290.335716)
		(width 0.18288)
		(layer "In4.Cu")
		(net "M_G_CPU0_SA_DQ<20>")
	)
	(segment
		(start 382.528064 -264.176002)
		(end 382.528064 -264.175748)
		(width 0.088646)
		(layer "In4.Cu")
		(net "M_G_CPU0_SA_DQ<20>")
	)
	(segment
		(start 420.321994 -291.242496)
		(end 420.193724 -291.114226)
		(width 0.18288)
		(layer "In4.Cu")
		(net "M_G_CPU0_SA_DQ<20>")
	)
	(segment
		(start 418.747194 -290.758626)
		(end 418.747194 -290.555426)
		(width 0.18288)
		(layer "In4.Cu")
		(net "M_G_CPU0_SA_DQ<20>")
	)
	(segment
		(start 408.079194 -280.878026)
		(end 406.26919 -280.878026)
		(width 0.18288)
		(layer "In4.Cu")
		(net "M_G_CPU0_SA_DQ<20>")
	)
	(segment
		(start 392.646154 -267.423392)
		(end 390.933686 -266.714224)
		(width 0.18288)
		(layer "In4.Cu")
		(net "M_G_CPU0_SA_DQ<20>")
	)
	(segment
		(start 432.574954 -291.20719)
		(end 431.726594 -291.20719)
		(width 0.18288)
		(layer "In4.Cu")
		(net "M_G_CPU0_SA_DQ<20>")
	)
	(segment
		(start 416.588194 -289.953446)
		(end 416.588194 -289.706558)
		(width 0.18288)
		(layer "In4.Cu")
		(net "M_G_CPU0_SA_DQ<20>")
	)
	(segment
		(start 423.446194 -290.225226)
		(end 422.404032 -290.225226)
		(width 0.18288)
		(layer "In4.Cu")
		(net "M_G_CPU0_SA_DQ<20>")
	)
	(segment
		(start 418.747194 -290.555426)
		(end 418.622734 -290.430966)
		(width 0.18288)
		(layer "In4.Cu")
		(net "M_G_CPU0_SA_DQ<20>")
	)
	(segment
		(start 381.023114 -264.175748)
		(end 381.017272 -264.172446)
		(width 0.088646)
		(layer "In4.Cu")
		(net "M_G_CPU0_SA_DQ<20>")
	)
	(segment
		(start 428.817786 -290.50361)
		(end 428.657766 -290.34359)
		(width 0.18288)
		(layer "In4.Cu")
		(net "M_G_CPU0_SA_DQ<20>")
	)
	(segment
		(start 418.622734 -290.430966)
		(end 417.065714 -290.430966)
		(width 0.18288)
		(layer "In4.Cu")
		(net "M_G_CPU0_SA_DQ<20>")
	)
	(segment
		(start 390.933686 -266.714224)
		(end 388.773162 -264.5537)
		(width 0.18288)
		(layer "In4.Cu")
		(net "M_G_CPU0_SA_DQ<20>")
	)
	(segment
		(start 378.117608 -264.50036)
		(end 378.016262 -264.50036)
		(width 0.088646)
		(layer "In4.Cu")
		(net "M_G_CPU0_SA_DQ<20>")
	)
	(segment
		(start 380.520702 -264.297668)
		(end 380.340362 -264.578084)
		(width 0.088646)
		(layer "In4.Cu")
		(net "M_G_CPU0_SA_DQ<20>")
	)
	(segment
		(start 428.977806 -290.975288)
		(end 428.817786 -290.815268)
		(width 0.18288)
		(layer "In4.Cu")
		(net "M_G_CPU0_SA_DQ<20>")
	)
	(segment
		(start 425.451016 -290.578286)
		(end 425.265088 -290.392358)
		(width 0.18288)
		(layer "In4.Cu")
		(net "M_G_CPU0_SA_DQ<20>")
	)
	(segment
		(start 380.126494 -264.799826)
		(end 380.083314 -264.824718)
		(width 0.088646)
		(layer "In4.Cu")
		(net "M_G_CPU0_SA_DQ<20>")
	)
	(segment
		(start 422.293542 -290.335716)
		(end 422.293542 -291.206428)
		(width 0.18288)
		(layer "In4.Cu")
		(net "M_G_CPU0_SA_DQ<20>")
	)
	(segment
		(start 388.773162 -264.5537)
		(end 386.605272 -264.5537)
		(width 0.18288)
		(layer "In4.Cu")
		(net "M_G_CPU0_SA_DQ<20>")
	)
	(segment
		(start 434.546756 -291.0459)
		(end 434.005736 -291.58692)
		(width 0.18288)
		(layer "In4.Cu")
		(net "M_G_CPU0_SA_DQ<20>")
	)
	(segment
		(start 427.220634 -290.68395)
		(end 426.961554 -290.68395)
		(width 0.18288)
		(layer "In4.Cu")
		(net "M_G_CPU0_SA_DQ<20>")
	)
	(segment
		(start 432.954684 -291.58692)
		(end 432.574954 -291.20719)
		(width 0.18288)
		(layer "In4.Cu")
		(net "M_G_CPU0_SA_DQ<20>")
	)
	(segment
		(start 425.265088 -290.392358)
		(end 423.613326 -290.392358)
		(width 0.18288)
		(layer "In4.Cu")
		(net "M_G_CPU0_SA_DQ<20>")
	)
	(segment
		(start 419.128194 -291.520626)
		(end 418.772594 -291.520626)
		(width 0.18288)
		(layer "In4.Cu")
		(net "M_G_CPU0_SA_DQ<20>")
	)
	(segment
		(start 410.362654 -283.702506)
		(end 410.362654 -282.069286)
		(width 0.18288)
		(layer "In4.Cu")
		(net "M_G_CPU0_SA_DQ<20>")
	)
	(segment
		(start 394.505942 -267.423392)
		(end 392.646154 -267.423392)
		(width 0.18288)
		(layer "In4.Cu")
		(net "M_G_CPU0_SA_DQ<20>")
	)
	(segment
		(start 426.002196 -290.934902)
		(end 425.611036 -290.934902)
		(width 0.18288)
		(layer "In4.Cu")
		(net "M_G_CPU0_SA_DQ<20>")
	)
	(segment
		(start 411.423612 -285.288736)
		(end 411.423612 -284.763464)
		(width 0.18288)
		(layer "In4.Cu")
		(net "M_G_CPU0_SA_DQ<20>")
	)
	(segment
		(start 428.657766 -290.34359)
		(end 427.560994 -290.34359)
		(width 0.18288)
		(layer "In4.Cu")
		(net "M_G_CPU0_SA_DQ<20>")
	)
	(segment
		(start 425.611036 -290.934902)
		(end 425.451016 -290.774882)
		(width 0.18288)
		(layer "In4.Cu")
		(net "M_G_CPU0_SA_DQ<20>")
	)
	(segment
		(start 403.322028 -276.239478)
		(end 394.505942 -267.423392)
		(width 0.18288)
		(layer "In4.Cu")
		(net "M_G_CPU0_SA_DQ<20>")
	)
	(segment
		(start 419.534594 -291.114226)
		(end 419.128194 -291.520626)
		(width 0.18288)
		(layer "In4.Cu")
		(net "M_G_CPU0_SA_DQ<20>")
	)
	(segment
		(start 380.083314 -264.824718)
		(end 380.078742 -264.827512)
		(width 0.088646)
		(layer "In4.Cu")
		(net "M_G_CPU0_SA_DQ<20>")
	)
	(segment
		(start 379.897386 -264.878566)
		(end 378.969778 -264.878566)
		(width 0.088646)
		(layer "In4.Cu")
		(net "M_G_CPU0_SA_DQ<20>")
	)
	(segment
		(start 426.669962 -290.392358)
		(end 426.322236 -290.392358)
		(width 0.18288)
		(layer "In4.Cu")
		(net "M_G_CPU0_SA_DQ<20>")
	)
	(segment
		(start 411.423612 -284.763464)
		(end 410.362654 -283.702506)
		(width 0.18288)
		(layer "In4.Cu")
		(net "M_G_CPU0_SA_DQ<20>")
	)
	(segment
		(start 429.654716 -290.802314)
		(end 429.481742 -290.975288)
		(width 0.18288)
		(layer "In4.Cu")
		(net "M_G_CPU0_SA_DQ<20>")
	)
	(segment
		(start 429.814736 -290.330636)
		(end 429.654716 -290.490656)
		(width 0.18288)
		(layer "In4.Cu")
		(net "M_G_CPU0_SA_DQ<20>")
	)
	(segment
		(start 422.293542 -291.206428)
		(end 421.925496 -291.574474)
		(width 0.18288)
		(layer "In4.Cu")
		(net "M_G_CPU0_SA_DQ<20>")
	)
	(segment
		(start 435.823614 -291.666676)
		(end 435.201314 -291.0459)
		(width 0.18288)
		(layer "In4.Cu")
		(net "M_G_CPU0_SA_DQ<20>")
	)
	(segment
		(start 418.772594 -291.520626)
		(end 418.531294 -291.279326)
		(width 0.18288)
		(layer "In4.Cu")
		(net "M_G_CPU0_SA_DQ<20>")
	)
	(segment
		(start 386.08889 -264.5537)
		(end 385.660392 -264.125202)
		(width 0.088646)
		(layer "In4.Cu")
		(net "M_G_CPU0_SA_DQ<20>")
	)
	(segment
		(start 410.362654 -282.069286)
		(end 409.975812 -281.682444)
		(width 0.18288)
		(layer "In4.Cu")
		(net "M_G_CPU0_SA_DQ<20>")
	)
	(segment
		(start 417.065714 -290.430966)
		(end 416.588194 -289.953446)
		(width 0.18288)
		(layer "In4.Cu")
		(net "M_G_CPU0_SA_DQ<20>")
	)
	(segment
		(start 381.968756 -264.179304)
		(end 381.962914 -264.175748)
		(width 0.088646)
		(layer "In4.Cu")
		(net "M_G_CPU0_SA_DQ<20>")
	)
	(segment
		(start 425.451016 -290.774882)
		(end 425.451016 -290.578286)
		(width 0.18288)
		(layer "In4.Cu")
		(net "M_G_CPU0_SA_DQ<20>")
	)
	(segment
		(start 435.201314 -291.0459)
		(end 434.546756 -291.0459)
		(width 0.18288)
		(layer "In4.Cu")
		(net "M_G_CPU0_SA_DQ<20>")
	)
	(segment
		(start 414.605978 -288.523426)
		(end 413.764222 -287.68167)
		(width 0.18288)
		(layer "In4.Cu")
		(net "M_G_CPU0_SA_DQ<20>")
	)
	(segment
		(start 429.654716 -290.490656)
		(end 429.654716 -290.802314)
		(width 0.18288)
		(layer "In4.Cu")
		(net "M_G_CPU0_SA_DQ<20>")
	)
	(segment
		(start 381.962914 -264.175748)
		(end 381.957072 -264.172446)
		(width 0.088646)
		(layer "In4.Cu")
		(net "M_G_CPU0_SA_DQ<20>")
	)
	(segment
		(start 418.531294 -290.974526)
		(end 418.747194 -290.758626)
		(width 0.18288)
		(layer "In4.Cu")
		(net "M_G_CPU0_SA_DQ<20>")
	)
	(segment
		(start 408.883612 -281.682444)
		(end 408.079194 -280.878026)
		(width 0.18288)
		(layer "In4.Cu")
		(net "M_G_CPU0_SA_DQ<20>")
	)
	(segment
		(start 406.26919 -280.878026)
		(end 404.8506 -279.930098)
		(width 0.18288)
		(layer "In4.Cu")
		(net "M_G_CPU0_SA_DQ<20>")
	)
	(segment
		(start 404.8506 -279.930098)
		(end 403.322028 -276.239478)
		(width 0.18288)
		(layer "In4.Cu")
		(net "M_G_CPU0_SA_DQ<20>")
	)
	(segment
		(start 412.851092 -286.716216)
		(end 411.423612 -285.288736)
		(width 0.18288)
		(layer "In4.Cu")
		(net "M_G_CPU0_SA_DQ<20>")
	)
	(segment
		(start 430.85004 -290.330636)
		(end 429.814736 -290.330636)
		(width 0.18288)
		(layer "In4.Cu")
		(net "M_G_CPU0_SA_DQ<20>")
	)
	(segment
		(start 416.588194 -289.706558)
		(end 415.405062 -288.523426)
		(width 0.18288)
		(layer "In4.Cu")
		(net "M_G_CPU0_SA_DQ<20>")
	)
	(arc
		(start 380.199392 -264.75309)
		(mid 380.163481 -264.777298)
		(end 380.126494 -264.799826)
		(width 0.088646)
		(layer "In4.Cu")
		(net "M_G_CPU0_SA_DQ<20>")
	)
	(arc
		(start 381.588264 -264.175748)
		(mid 381.30909 -264.251547)
		(end 381.028956 -264.179304)
		(width 0.088646)
		(layer "In4.Cu")
		(net "M_G_CPU0_SA_DQ<20>")
	)
	(arc
		(start 385.347464 -264.176002)
		(mid 385.064762 -264.251778)
		(end 384.78206 -264.176002)
		(width 0.088646)
		(layer "In4.Cu")
		(net "M_G_CPU0_SA_DQ<20>")
	)
	(arc
		(start 378.969778 -264.878566)
		(mid 378.904868 -264.873125)
		(end 378.841762 -264.856976)
		(width 0.088646)
		(layer "In4.Cu")
		(net "M_G_CPU0_SA_DQ<20>")
	)
	(arc
		(start 380.078742 -264.827512)
		(mid 379.991582 -264.865522)
		(end 379.897386 -264.878566)
		(width 0.088646)
		(layer "In4.Cu")
		(net "M_G_CPU0_SA_DQ<20>")
	)
	(arc
		(start 383.84226 -264.176002)
		(mid 383.655062 -264.125859)
		(end 383.467864 -264.176002)
		(width 0.088646)
		(layer "In4.Cu")
		(net "M_G_CPU0_SA_DQ<20>")
	)
	(arc
		(start 383.467864 -264.176002)
		(mid 383.185162 -264.251778)
		(end 382.90246 -264.176002)
		(width 0.088646)
		(layer "In4.Cu")
		(net "M_G_CPU0_SA_DQ<20>")
	)
	(arc
		(start 382.90246 -264.176002)
		(mid 382.715262 -264.125859)
		(end 382.528064 -264.176002)
		(width 0.088646)
		(layer "In4.Cu")
		(net "M_G_CPU0_SA_DQ<20>")
	)
	(arc
		(start 380.648464 -264.175748)
		(mid 380.577293 -264.22907)
		(end 380.520702 -264.297668)
		(width 0.088646)
		(layer "In4.Cu")
		(net "M_G_CPU0_SA_DQ<20>")
	)
	(arc
		(start 381.957072 -264.172446)
		(mid 381.772217 -264.125528)
		(end 381.588264 -264.175748)
		(width 0.088646)
		(layer "In4.Cu")
		(net "M_G_CPU0_SA_DQ<20>")
	)
	(arc
		(start 380.340362 -264.578084)
		(mid 380.274556 -264.669356)
		(end 380.199392 -264.75309)
		(width 0.088646)
		(layer "In4.Cu")
		(net "M_G_CPU0_SA_DQ<20>")
	)
	(arc
		(start 382.528064 -264.175748)
		(mid 382.24889 -264.251547)
		(end 381.968756 -264.179304)
		(width 0.088646)
		(layer "In4.Cu")
		(net "M_G_CPU0_SA_DQ<20>")
	)
	(arc
		(start 385.534916 -264.125202)
		(mid 385.437846 -264.138259)
		(end 385.347464 -264.176002)
		(width 0.088646)
		(layer "In4.Cu")
		(net "M_G_CPU0_SA_DQ<20>")
	)
	(arc
		(start 378.841762 -264.856976)
		(mid 378.752362 -264.814598)
		(end 378.67717 -264.750296)
		(width 0.088646)
		(layer "In4.Cu")
		(net "M_G_CPU0_SA_DQ<20>")
	)
	(arc
		(start 384.407664 -264.176002)
		(mid 384.124962 -264.251778)
		(end 383.84226 -264.176002)
		(width 0.088646)
		(layer "In4.Cu")
		(net "M_G_CPU0_SA_DQ<20>")
	)
	(arc
		(start 378.67717 -264.750296)
		(mid 378.424031 -264.56568)
		(end 378.117608 -264.50036)
		(width 0.088646)
		(layer "In4.Cu")
		(net "M_G_CPU0_SA_DQ<20>")
	)
	(arc
		(start 384.78206 -264.176002)
		(mid 384.594862 -264.125859)
		(end 384.407664 -264.176002)
		(width 0.088646)
		(layer "In4.Cu")
		(net "M_G_CPU0_SA_DQ<20>")
	)
	(arc
		(start 381.017272 -264.172446)
		(mid 380.832417 -264.125528)
		(end 380.648464 -264.175748)
		(width 0.088646)
		(layer "In4.Cu")
		(net "M_G_CPU0_SA_DQ<20>")
	)
	(segment
		(start 442.032644 -314.19165)
		(end 439.843926 -314.19165)
		(width 0.1016)
		(layer "F.Cu")
		(net "M_G_CPU0_SA_DQ<1>")
	)
	(segment
		(start 442.880496 -314.616846)
		(end 442.44895 -314.1853)
		(width 0.20066)
		(layer "F.Cu")
		(net "M_G_CPU0_SA_DQ<1>")
	)
	(segment
		(start 444.47206 -314.616846)
		(end 442.880496 -314.616846)
		(width 0.20066)
		(layer "F.Cu")
		(net "M_G_CPU0_SA_DQ<1>")
	)
	(segment
		(start 439.843926 -314.19165)
		(end 439.82386 -314.19165)
		(width 0.101854)
		(layer "F.Cu")
		(net "M_G_CPU0_SA_DQ<1>")
	)
	(segment
		(start 439.479182 -314.19165)
		(end 439.361072 -314.30976)
		(width 0.20066)
		(layer "F.Cu")
		(net "M_G_CPU0_SA_DQ<1>")
	)
	(segment
		(start 438.449212 -314.616592)
		(end 436.928514 -314.616592)
		(width 0.20066)
		(layer "F.Cu")
		(net "M_G_CPU0_SA_DQ<1>")
	)
	(segment
		(start 436.928514 -314.616592)
		(end 435.823614 -314.616592)
		(width 0.20066)
		(layer "F.Cu")
		(net "M_G_CPU0_SA_DQ<1>")
	)
	(segment
		(start 378.016516 -275.894546)
		(end 378.016262 -275.8948)
		(width 0.20066)
		(layer "F.Cu")
		(net "M_G_CPU0_SA_DQ<1>")
	)
	(segment
		(start 442.038994 -314.1853)
		(end 442.032644 -314.19165)
		(width 0.1016)
		(layer "F.Cu")
		(net "M_G_CPU0_SA_DQ<1>")
	)
	(segment
		(start 439.361072 -314.30976)
		(end 439.361072 -314.677298)
		(width 0.20066)
		(layer "F.Cu")
		(net "M_G_CPU0_SA_DQ<1>")
	)
	(segment
		(start 438.697878 -314.865258)
		(end 438.449212 -314.616592)
		(width 0.20066)
		(layer "F.Cu")
		(net "M_G_CPU0_SA_DQ<1>")
	)
	(segment
		(start 378.016516 -275.35886)
		(end 378.016516 -275.894546)
		(width 0.20066)
		(layer "F.Cu")
		(net "M_G_CPU0_SA_DQ<1>")
	)
	(segment
		(start 442.44895 -314.1853)
		(end 442.038994 -314.1853)
		(width 0.20066)
		(layer "F.Cu")
		(net "M_G_CPU0_SA_DQ<1>")
	)
	(segment
		(start 439.82386 -314.19165)
		(end 439.479182 -314.19165)
		(width 0.20066)
		(layer "F.Cu")
		(net "M_G_CPU0_SA_DQ<1>")
	)
	(segment
		(start 444.472314 -314.616592)
		(end 444.47206 -314.616846)
		(width 0.20066)
		(layer "F.Cu")
		(net "M_G_CPU0_SA_DQ<1>")
	)
	(segment
		(start 439.361072 -314.677298)
		(end 439.173112 -314.865258)
		(width 0.20066)
		(layer "F.Cu")
		(net "M_G_CPU0_SA_DQ<1>")
	)
	(segment
		(start 439.173112 -314.865258)
		(end 438.697878 -314.865258)
		(width 0.20066)
		(layer "F.Cu")
		(net "M_G_CPU0_SA_DQ<1>")
	)
	(segment
		(start 419.332664 -317.683896)
		(end 417.451794 -315.803026)
		(width 0.18288)
		(layer "In4.Cu")
		(net "M_G_CPU0_SA_DQ<1>")
	)
	(segment
		(start 408.318462 -312.384694)
		(end 407.574242 -312.384694)
		(width 0.18288)
		(layer "In4.Cu")
		(net "M_G_CPU0_SA_DQ<1>")
	)
	(segment
		(start 384.499612 -278.336756)
		(end 384.499612 -278.336502)
		(width 0.088646)
		(layer "In4.Cu")
		(net "M_G_CPU0_SA_DQ<1>")
	)
	(segment
		(start 433.853844 -314.75172)
		(end 433.853844 -314.312046)
		(width 0.18288)
		(layer "In4.Cu")
		(net "M_G_CPU0_SA_DQ<1>")
	)
	(segment
		(start 429.50003 -314.964826)
		(end 429.295052 -315.169804)
		(width 0.18288)
		(layer "In4.Cu")
		(net "M_G_CPU0_SA_DQ<1>")
	)
	(segment
		(start 378.673614 -276.384258)
		(end 378.595128 -276.338792)
		(width 0.088646)
		(layer "In4.Cu")
		(net "M_G_CPU0_SA_DQ<1>")
	)
	(segment
		(start 426.29201 -316.00521)
		(end 426.29201 -316.582044)
		(width 0.18288)
		(layer "In4.Cu")
		(net "M_G_CPU0_SA_DQ<1>")
	)
	(segment
		(start 435.823614 -314.616592)
		(end 435.29758 -315.142626)
		(width 0.18288)
		(layer "In4.Cu")
		(net "M_G_CPU0_SA_DQ<1>")
	)
	(segment
		(start 435.29758 -315.142626)
		(end 434.24475 -315.142626)
		(width 0.18288)
		(layer "In4.Cu")
		(net "M_G_CPU0_SA_DQ<1>")
	)
	(segment
		(start 381.507746 -276.392894)
		(end 381.493014 -276.384258)
		(width 0.088646)
		(layer "In4.Cu")
		(net "M_G_CPU0_SA_DQ<1>")
	)
	(segment
		(start 395.253972 -297.964098)
		(end 389.536686 -284.161992)
		(width 0.18288)
		(layer "In4.Cu")
		(net "M_G_CPU0_SA_DQ<1>")
	)
	(segment
		(start 380.178564 -276.384258)
		(end 380.172722 -276.38756)
		(width 0.088646)
		(layer "In4.Cu")
		(net "M_G_CPU0_SA_DQ<1>")
	)
	(segment
		(start 388.426706 -281.046936)
		(end 387.372098 -279.992328)
		(width 0.18288)
		(layer "In4.Cu")
		(net "M_G_CPU0_SA_DQ<1>")
	)
	(segment
		(start 426.13199 -316.742064)
		(end 422.253156 -316.742064)
		(width 0.18288)
		(layer "In4.Cu")
		(net "M_G_CPU0_SA_DQ<1>")
	)
	(segment
		(start 429.295052 -315.951108)
		(end 428.91583 -316.33033)
		(width 0.18288)
		(layer "In4.Cu")
		(net "M_G_CPU0_SA_DQ<1>")
	)
	(segment
		(start 382.441704 -276.389338)
		(end 382.432814 -276.384258)
		(width 0.088646)
		(layer "In4.Cu")
		(net "M_G_CPU0_SA_DQ<1>")
	)
	(segment
		(start 382.620266 -276.72411)
		(end 382.620266 -276.708616)
		(width 0.088646)
		(layer "In4.Cu")
		(net "M_G_CPU0_SA_DQ<1>")
	)
	(segment
		(start 402.154644 -308.292754)
		(end 395.253972 -297.964098)
		(width 0.18288)
		(layer "In4.Cu")
		(net "M_G_CPU0_SA_DQ<1>")
	)
	(segment
		(start 433.693824 -314.152026)
		(end 431.726594 -314.152026)
		(width 0.18288)
		(layer "In4.Cu")
		(net "M_G_CPU0_SA_DQ<1>")
	)
	(segment
		(start 404.544022 -310.682132)
		(end 402.154644 -308.292754)
		(width 0.18288)
		(layer "In4.Cu")
		(net "M_G_CPU0_SA_DQ<1>")
	)
	(segment
		(start 389.536686 -284.161992)
		(end 389.536686 -283.726636)
		(width 0.18288)
		(layer "In4.Cu")
		(net "M_G_CPU0_SA_DQ<1>")
	)
	(segment
		(start 412.359856 -314.114688)
		(end 411.396688 -314.114688)
		(width 0.18288)
		(layer "In4.Cu")
		(net "M_G_CPU0_SA_DQ<1>")
	)
	(segment
		(start 427.866048 -315.90488)
		(end 427.687994 -315.726826)
		(width 0.18288)
		(layer "In4.Cu")
		(net "M_G_CPU0_SA_DQ<1>")
	)
	(segment
		(start 434.24475 -315.142626)
		(end 433.853844 -314.75172)
		(width 0.18288)
		(layer "In4.Cu")
		(net "M_G_CPU0_SA_DQ<1>")
	)
	(segment
		(start 389.536686 -283.726636)
		(end 388.426706 -281.046936)
		(width 0.18288)
		(layer "In4.Cu")
		(net "M_G_CPU0_SA_DQ<1>")
	)
	(segment
		(start 412.600394 -314.355226)
		(end 412.359856 -314.114688)
		(width 0.18288)
		(layer "In4.Cu")
		(net "M_G_CPU0_SA_DQ<1>")
	)
	(segment
		(start 429.295052 -315.169804)
		(end 429.295052 -315.951108)
		(width 0.18288)
		(layer "In4.Cu")
		(net "M_G_CPU0_SA_DQ<1>")
	)
	(segment
		(start 409.430474 -313.496706)
		(end 408.318462 -312.384694)
		(width 0.18288)
		(layer "In4.Cu")
		(net "M_G_CPU0_SA_DQ<1>")
	)
	(segment
		(start 405.87168 -310.682132)
		(end 404.544022 -310.682132)
		(width 0.18288)
		(layer "In4.Cu")
		(net "M_G_CPU0_SA_DQ<1>")
	)
	(segment
		(start 387.372098 -279.992328)
		(end 387.01218 -279.63241)
		(width 0.088646)
		(layer "In4.Cu")
		(net "M_G_CPU0_SA_DQ<1>")
	)
	(segment
		(start 422.253156 -316.742064)
		(end 421.311324 -317.683896)
		(width 0.18288)
		(layer "In4.Cu")
		(net "M_G_CPU0_SA_DQ<1>")
	)
	(segment
		(start 380.563374 -276.390354)
		(end 380.55296 -276.384258)
		(width 0.088646)
		(layer "In4.Cu")
		(net "M_G_CPU0_SA_DQ<1>")
	)
	(segment
		(start 414.433766 -314.355226)
		(end 412.600394 -314.355226)
		(width 0.18288)
		(layer "In4.Cu")
		(net "M_G_CPU0_SA_DQ<1>")
	)
	(segment
		(start 383.85115 -277.203154)
		(end 383.84226 -277.198074)
		(width 0.088646)
		(layer "In4.Cu")
		(net "M_G_CPU0_SA_DQ<1>")
	)
	(segment
		(start 411.396688 -314.114688)
		(end 410.778706 -313.496706)
		(width 0.18288)
		(layer "In4.Cu")
		(net "M_G_CPU0_SA_DQ<1>")
	)
	(segment
		(start 384.029458 -277.530052)
		(end 384.029458 -277.522432)
		(width 0.088646)
		(layer "In4.Cu")
		(net "M_G_CPU0_SA_DQ<1>")
	)
	(segment
		(start 407.574242 -312.384694)
		(end 405.87168 -310.682132)
		(width 0.18288)
		(layer "In4.Cu")
		(net "M_G_CPU0_SA_DQ<1>")
	)
	(segment
		(start 415.005266 -314.926726)
		(end 414.433766 -314.355226)
		(width 0.18288)
		(layer "In4.Cu")
		(net "M_G_CPU0_SA_DQ<1>")
	)
	(segment
		(start 427.866048 -316.196472)
		(end 427.866048 -315.90488)
		(width 0.18288)
		(layer "In4.Cu")
		(net "M_G_CPU0_SA_DQ<1>")
	)
	(segment
		(start 427.687994 -315.726826)
		(end 426.570394 -315.726826)
		(width 0.18288)
		(layer "In4.Cu")
		(net "M_G_CPU0_SA_DQ<1>")
	)
	(segment
		(start 433.853844 -314.312046)
		(end 433.693824 -314.152026)
		(width 0.18288)
		(layer "In4.Cu")
		(net "M_G_CPU0_SA_DQ<1>")
	)
	(segment
		(start 410.778706 -313.496706)
		(end 409.430474 -313.496706)
		(width 0.18288)
		(layer "In4.Cu")
		(net "M_G_CPU0_SA_DQ<1>")
	)
	(segment
		(start 415.838894 -314.926726)
		(end 415.005266 -314.926726)
		(width 0.18288)
		(layer "In4.Cu")
		(net "M_G_CPU0_SA_DQ<1>")
	)
	(segment
		(start 421.311324 -317.683896)
		(end 419.332664 -317.683896)
		(width 0.18288)
		(layer "In4.Cu")
		(net "M_G_CPU0_SA_DQ<1>")
	)
	(segment
		(start 426.29201 -316.582044)
		(end 426.13199 -316.742064)
		(width 0.18288)
		(layer "In4.Cu")
		(net "M_G_CPU0_SA_DQ<1>")
	)
	(segment
		(start 426.570394 -315.726826)
		(end 426.29201 -316.00521)
		(width 0.18288)
		(layer "In4.Cu")
		(net "M_G_CPU0_SA_DQ<1>")
	)
	(segment
		(start 383.467864 -277.198074)
		(end 383.453132 -277.20671)
		(width 0.088646)
		(layer "In4.Cu")
		(net "M_G_CPU0_SA_DQ<1>")
	)
	(segment
		(start 416.715194 -315.803026)
		(end 415.838894 -314.926726)
		(width 0.18288)
		(layer "In4.Cu")
		(net "M_G_CPU0_SA_DQ<1>")
	)
	(segment
		(start 428.91583 -316.33033)
		(end 427.999906 -316.33033)
		(width 0.18288)
		(layer "In4.Cu")
		(net "M_G_CPU0_SA_DQ<1>")
	)
	(segment
		(start 384.029458 -277.522432)
		(end 384.029712 -277.522432)
		(width 0.088646)
		(layer "In4.Cu")
		(net "M_G_CPU0_SA_DQ<1>")
	)
	(segment
		(start 387.01218 -279.63241)
		(end 386.547106 -279.63241)
		(width 0.088646)
		(layer "In4.Cu")
		(net "M_G_CPU0_SA_DQ<1>")
	)
	(segment
		(start 417.451794 -315.803026)
		(end 416.715194 -315.803026)
		(width 0.18288)
		(layer "In4.Cu")
		(net "M_G_CPU0_SA_DQ<1>")
	)
	(segment
		(start 379.244606 -276.380956)
		(end 379.232922 -276.38756)
		(width 0.088646)
		(layer "In4.Cu")
		(net "M_G_CPU0_SA_DQ<1>")
	)
	(segment
		(start 386.547106 -279.63241)
		(end 385.799838 -278.885142)
		(width 0.088646)
		(layer "In4.Cu")
		(net "M_G_CPU0_SA_DQ<1>")
	)
	(segment
		(start 384.32105 -278.017224)
		(end 384.31216 -278.012144)
		(width 0.088646)
		(layer "In4.Cu")
		(net "M_G_CPU0_SA_DQ<1>")
	)
	(segment
		(start 430.913794 -314.964826)
		(end 429.50003 -314.964826)
		(width 0.18288)
		(layer "In4.Cu")
		(net "M_G_CPU0_SA_DQ<1>")
	)
	(segment
		(start 431.726594 -314.152026)
		(end 430.913794 -314.964826)
		(width 0.18288)
		(layer "In4.Cu")
		(net "M_G_CPU0_SA_DQ<1>")
	)
	(segment
		(start 427.999906 -316.33033)
		(end 427.866048 -316.196472)
		(width 0.18288)
		(layer "In4.Cu")
		(net "M_G_CPU0_SA_DQ<1>")
	)
	(arc
		(start 385.799838 -278.885142)
		(mid 385.762788 -278.852996)
		(end 385.72186 -278.82596)
		(width 0.088646)
		(layer "In4.Cu")
		(net "M_G_CPU0_SA_DQ<1>")
	)
	(arc
		(start 381.493014 -276.384258)
		(mid 381.305816 -276.334115)
		(end 381.118618 -276.384258)
		(width 0.088646)
		(layer "In4.Cu")
		(net "M_G_CPU0_SA_DQ<1>")
	)
	(arc
		(start 384.499612 -278.336502)
		(mid 384.451933 -278.153602)
		(end 384.32105 -278.017224)
		(width 0.088646)
		(layer "In4.Cu")
		(net "M_G_CPU0_SA_DQ<1>")
	)
	(arc
		(start 382.620266 -276.708616)
		(mid 382.572587 -276.525716)
		(end 382.441704 -276.389338)
		(width 0.088646)
		(layer "In4.Cu")
		(net "M_G_CPU0_SA_DQ<1>")
	)
	(arc
		(start 382.058418 -276.384258)
		(mid 381.784219 -276.460093)
		(end 381.507746 -276.392894)
		(width 0.088646)
		(layer "In4.Cu")
		(net "M_G_CPU0_SA_DQ<1>")
	)
	(arc
		(start 384.78206 -278.82596)
		(mid 384.5753 -278.619197)
		(end 384.499612 -278.336756)
		(width 0.088646)
		(layer "In4.Cu")
		(net "M_G_CPU0_SA_DQ<1>")
	)
	(arc
		(start 382.432814 -276.384258)
		(mid 382.245616 -276.334115)
		(end 382.058418 -276.384258)
		(width 0.088646)
		(layer "In4.Cu")
		(net "M_G_CPU0_SA_DQ<1>")
	)
	(arc
		(start 380.55296 -276.384258)
		(mid 380.365762 -276.334115)
		(end 380.178564 -276.384258)
		(width 0.088646)
		(layer "In4.Cu")
		(net "M_G_CPU0_SA_DQ<1>")
	)
	(arc
		(start 378.595128 -276.338792)
		(mid 378.29132 -276.135537)
		(end 378.016262 -275.8948)
		(width 0.088646)
		(layer "In4.Cu")
		(net "M_G_CPU0_SA_DQ<1>")
	)
	(arc
		(start 379.232922 -276.38756)
		(mid 378.952817 -276.460002)
		(end 378.673614 -276.384258)
		(width 0.088646)
		(layer "In4.Cu")
		(net "M_G_CPU0_SA_DQ<1>")
	)
	(arc
		(start 385.347464 -278.82596)
		(mid 385.064762 -278.901736)
		(end 384.78206 -278.82596)
		(width 0.088646)
		(layer "In4.Cu")
		(net "M_G_CPU0_SA_DQ<1>")
	)
	(arc
		(start 381.118618 -276.384258)
		(mid 380.841805 -276.460128)
		(end 380.563374 -276.390354)
		(width 0.088646)
		(layer "In4.Cu")
		(net "M_G_CPU0_SA_DQ<1>")
	)
	(arc
		(start 384.31216 -278.012144)
		(mid 384.107088 -277.808465)
		(end 384.029458 -277.530052)
		(width 0.088646)
		(layer "In4.Cu")
		(net "M_G_CPU0_SA_DQ<1>")
	)
	(arc
		(start 382.90246 -277.198074)
		(mid 382.699637 -276.997843)
		(end 382.620266 -276.72411)
		(width 0.088646)
		(layer "In4.Cu")
		(net "M_G_CPU0_SA_DQ<1>")
	)
	(arc
		(start 383.84226 -277.198074)
		(mid 383.655062 -277.147931)
		(end 383.467864 -277.198074)
		(width 0.088646)
		(layer "In4.Cu")
		(net "M_G_CPU0_SA_DQ<1>")
	)
	(arc
		(start 380.172722 -276.38756)
		(mid 379.892617 -276.460002)
		(end 379.613414 -276.384258)
		(width 0.088646)
		(layer "In4.Cu")
		(net "M_G_CPU0_SA_DQ<1>")
	)
	(arc
		(start 383.453132 -277.20671)
		(mid 383.176657 -277.27403)
		(end 382.90246 -277.198074)
		(width 0.088646)
		(layer "In4.Cu")
		(net "M_G_CPU0_SA_DQ<1>")
	)
	(arc
		(start 385.72186 -278.82596)
		(mid 385.534662 -278.775817)
		(end 385.347464 -278.82596)
		(width 0.088646)
		(layer "In4.Cu")
		(net "M_G_CPU0_SA_DQ<1>")
	)
	(arc
		(start 379.613414 -276.384258)
		(mid 379.42946 -276.334129)
		(end 379.244606 -276.380956)
		(width 0.088646)
		(layer "In4.Cu")
		(net "M_G_CPU0_SA_DQ<1>")
	)
	(arc
		(start 384.029712 -277.522432)
		(mid 383.982033 -277.339532)
		(end 383.85115 -277.203154)
		(width 0.088646)
		(layer "In4.Cu")
		(net "M_G_CPU0_SA_DQ<1>")
	)
	(segment
		(start 445.470534 -295.491662)
		(end 445.482726 -295.503854)
		(width 0.1016)
		(layer "F.Cu")
		(net "M_G_CPU0_SA_DQ<19>")
	)
	(segment
		(start 446.986152 -294.814752)
		(end 447.23812 -295.06672)
		(width 0.20066)
		(layer "F.Cu")
		(net "M_G_CPU0_SA_DQ<19>")
	)
	(segment
		(start 445.482726 -295.503854)
		(end 446.163954 -295.503854)
		(width 0.20066)
		(layer "F.Cu")
		(net "M_G_CPU0_SA_DQ<19>")
	)
	(segment
		(start 443.450726 -295.498774)
		(end 443.455552 -295.498774)
		(width 0.101854)
		(layer "F.Cu")
		(net "M_G_CPU0_SA_DQ<19>")
	)
	(segment
		(start 441.028582 -295.06672)
		(end 442.726826 -295.06672)
		(width 0.20066)
		(layer "F.Cu")
		(net "M_G_CPU0_SA_DQ<19>")
	)
	(segment
		(start 379.896116 -265.592306)
		(end 379.896116 -266.127992)
		(width 0.20066)
		(layer "F.Cu")
		(net "M_G_CPU0_SA_DQ<19>")
	)
	(segment
		(start 379.896116 -266.127992)
		(end 379.895862 -266.128246)
		(width 0.20066)
		(layer "F.Cu")
		(net "M_G_CPU0_SA_DQ<19>")
	)
	(segment
		(start 442.726826 -295.06672)
		(end 443.15888 -295.498774)
		(width 0.20066)
		(layer "F.Cu")
		(net "M_G_CPU0_SA_DQ<19>")
	)
	(segment
		(start 446.367916 -295.299892)
		(end 446.367916 -295.04894)
		(width 0.20066)
		(layer "F.Cu")
		(net "M_G_CPU0_SA_DQ<19>")
	)
	(segment
		(start 447.23812 -295.06672)
		(end 448.572382 -295.06672)
		(width 0.20066)
		(layer "F.Cu")
		(net "M_G_CPU0_SA_DQ<19>")
	)
	(segment
		(start 446.163954 -295.503854)
		(end 446.367916 -295.299892)
		(width 0.20066)
		(layer "F.Cu")
		(net "M_G_CPU0_SA_DQ<19>")
	)
	(segment
		(start 446.367916 -295.04894)
		(end 446.602104 -294.814752)
		(width 0.20066)
		(layer "F.Cu")
		(net "M_G_CPU0_SA_DQ<19>")
	)
	(segment
		(start 443.455552 -295.498774)
		(end 443.462664 -295.491662)
		(width 0.1016)
		(layer "F.Cu")
		(net "M_G_CPU0_SA_DQ<19>")
	)
	(segment
		(start 439.923682 -295.06672)
		(end 441.028582 -295.06672)
		(width 0.20066)
		(layer "F.Cu")
		(net "M_G_CPU0_SA_DQ<19>")
	)
	(segment
		(start 446.602104 -294.814752)
		(end 446.986152 -294.814752)
		(width 0.20066)
		(layer "F.Cu")
		(net "M_G_CPU0_SA_DQ<19>")
	)
	(segment
		(start 443.15888 -295.498774)
		(end 443.450726 -295.498774)
		(width 0.20066)
		(layer "F.Cu")
		(net "M_G_CPU0_SA_DQ<19>")
	)
	(segment
		(start 443.462664 -295.491662)
		(end 445.470534 -295.491662)
		(width 0.1016)
		(layer "F.Cu")
		(net "M_G_CPU0_SA_DQ<19>")
	)
	(segment
		(start 419.129972 -295.48074)
		(end 416.664394 -293.015162)
		(width 0.18288)
		(layer "In4.Cu")
		(net "M_G_CPU0_SA_DQ<19>")
	)
	(segment
		(start 381.023114 -266.452604)
		(end 381.017272 -266.455906)
		(width 0.088646)
		(layer "In4.Cu")
		(net "M_G_CPU0_SA_DQ<19>")
	)
	(segment
		(start 435.5846 -295.492424)
		(end 434.855366 -294.76319)
		(width 0.18288)
		(layer "In4.Cu")
		(net "M_G_CPU0_SA_DQ<19>")
	)
	(segment
		(start 439.923682 -295.06672)
		(end 439.497978 -295.492424)
		(width 0.18288)
		(layer "In4.Cu")
		(net "M_G_CPU0_SA_DQ<19>")
	)
	(segment
		(start 392.154156 -269.536672)
		(end 390.961626 -269.042642)
		(width 0.18288)
		(layer "In4.Cu")
		(net "M_G_CPU0_SA_DQ<19>")
	)
	(segment
		(start 438.043066 -296.221404)
		(end 437.715406 -296.221404)
		(width 0.18288)
		(layer "In4.Cu")
		(net "M_G_CPU0_SA_DQ<19>")
	)
	(segment
		(start 421.920416 -295.60139)
		(end 421.179498 -296.342308)
		(width 0.18288)
		(layer "In4.Cu")
		(net "M_G_CPU0_SA_DQ<19>")
	)
	(segment
		(start 383.84226 -266.45235)
		(end 383.842514 -266.452604)
		(width 0.088646)
		(layer "In4.Cu")
		(net "M_G_CPU0_SA_DQ<19>")
	)
	(segment
		(start 390.8171 -268.982698)
		(end 388.081774 -266.247372)
		(width 0.18288)
		(layer "In4.Cu")
		(net "M_G_CPU0_SA_DQ<19>")
	)
	(segment
		(start 380.03861 -266.166346)
		(end 379.895862 -266.128246)
		(width 0.088646)
		(layer "In4.Cu")
		(net "M_G_CPU0_SA_DQ<19>")
	)
	(segment
		(start 381.028956 -266.449048)
		(end 381.023114 -266.452604)
		(width 0.088646)
		(layer "In4.Cu")
		(net "M_G_CPU0_SA_DQ<19>")
	)
	(segment
		(start 438.408826 -295.492424)
		(end 438.225946 -295.675304)
		(width 0.18288)
		(layer "In4.Cu")
		(net "M_G_CPU0_SA_DQ<19>")
	)
	(segment
		(start 411.428438 -290.129214)
		(end 411.428438 -289.522662)
		(width 0.18288)
		(layer "In4.Cu")
		(net "M_G_CPU0_SA_DQ<19>")
	)
	(segment
		(start 381.968756 -266.449048)
		(end 381.962914 -266.452604)
		(width 0.088646)
		(layer "In4.Cu")
		(net "M_G_CPU0_SA_DQ<19>")
	)
	(segment
		(start 381.962914 -266.452604)
		(end 381.957072 -266.455906)
		(width 0.088646)
		(layer "In4.Cu")
		(net "M_G_CPU0_SA_DQ<19>")
	)
	(segment
		(start 412.346902 -290.479734)
		(end 411.778958 -290.479734)
		(width 0.18288)
		(layer "In4.Cu")
		(net "M_G_CPU0_SA_DQ<19>")
	)
	(segment
		(start 412.95701 -291.252402)
		(end 412.701994 -290.997386)
		(width 0.18288)
		(layer "In4.Cu")
		(net "M_G_CPU0_SA_DQ<19>")
	)
	(segment
		(start 390.961626 -269.042642)
		(end 390.8171 -268.982698)
		(width 0.18288)
		(layer "In4.Cu")
		(net "M_G_CPU0_SA_DQ<19>")
	)
	(segment
		(start 437.715406 -296.221404)
		(end 437.532526 -296.038524)
		(width 0.18288)
		(layer "In4.Cu")
		(net "M_G_CPU0_SA_DQ<19>")
	)
	(segment
		(start 382.902714 -266.452604)
		(end 382.896872 -266.455906)
		(width 0.088646)
		(layer "In4.Cu")
		(net "M_G_CPU0_SA_DQ<19>")
	)
	(segment
		(start 431.675794 -294.76319)
		(end 431.282094 -294.36949)
		(width 0.18288)
		(layer "In4.Cu")
		(net "M_G_CPU0_SA_DQ<19>")
	)
	(segment
		(start 412.701994 -290.834826)
		(end 412.346902 -290.479734)
		(width 0.18288)
		(layer "In4.Cu")
		(net "M_G_CPU0_SA_DQ<19>")
	)
	(segment
		(start 382.906524 -266.450318)
		(end 382.902714 -266.452604)
		(width 0.088646)
		(layer "In4.Cu")
		(net "M_G_CPU0_SA_DQ<19>")
	)
	(segment
		(start 437.532526 -296.038524)
		(end 437.532526 -295.675304)
		(width 0.18288)
		(layer "In4.Cu")
		(net "M_G_CPU0_SA_DQ<19>")
	)
	(segment
		(start 412.701994 -290.997386)
		(end 412.701994 -290.834826)
		(width 0.18288)
		(layer "In4.Cu")
		(net "M_G_CPU0_SA_DQ<19>")
	)
	(segment
		(start 416.664394 -293.015162)
		(end 415.637472 -293.015162)
		(width 0.18288)
		(layer "In4.Cu")
		(net "M_G_CPU0_SA_DQ<19>")
	)
	(segment
		(start 424.55719 -295.49344)
		(end 424.44924 -295.60139)
		(width 0.18288)
		(layer "In4.Cu")
		(net "M_G_CPU0_SA_DQ<19>")
	)
	(segment
		(start 413.50565 -291.252402)
		(end 412.95701 -291.252402)
		(width 0.18288)
		(layer "In4.Cu")
		(net "M_G_CPU0_SA_DQ<19>")
	)
	(segment
		(start 420.101522 -295.88714)
		(end 420.101522 -295.845738)
		(width 0.18288)
		(layer "In4.Cu")
		(net "M_G_CPU0_SA_DQ<19>")
	)
	(segment
		(start 385.926838 -266.247372)
		(end 385.72186 -266.45235)
		(width 0.088646)
		(layer "In4.Cu")
		(net "M_G_CPU0_SA_DQ<19>")
	)
	(segment
		(start 434.855366 -294.76319)
		(end 431.675794 -294.76319)
		(width 0.18288)
		(layer "In4.Cu")
		(net "M_G_CPU0_SA_DQ<19>")
	)
	(segment
		(start 393.629134 -269.536672)
		(end 392.154156 -269.536672)
		(width 0.18288)
		(layer "In4.Cu")
		(net "M_G_CPU0_SA_DQ<19>")
	)
	(segment
		(start 408.877008 -286.69234)
		(end 408.18435 -286.69234)
		(width 0.18288)
		(layer "In4.Cu")
		(net "M_G_CPU0_SA_DQ<19>")
	)
	(segment
		(start 427.687994 -294.86479)
		(end 426.570394 -294.86479)
		(width 0.18288)
		(layer "In4.Cu")
		(net "M_G_CPU0_SA_DQ<19>")
	)
	(segment
		(start 411.778958 -290.479734)
		(end 411.428438 -290.129214)
		(width 0.18288)
		(layer "In4.Cu")
		(net "M_G_CPU0_SA_DQ<19>")
	)
	(segment
		(start 420.101522 -295.845738)
		(end 419.83152 -295.575736)
		(width 0.18288)
		(layer "In4.Cu")
		(net "M_G_CPU0_SA_DQ<19>")
	)
	(segment
		(start 438.225946 -295.675304)
		(end 438.225946 -296.038524)
		(width 0.18288)
		(layer "In4.Cu")
		(net "M_G_CPU0_SA_DQ<19>")
	)
	(segment
		(start 421.179498 -296.342308)
		(end 420.55669 -296.342308)
		(width 0.18288)
		(layer "In4.Cu")
		(net "M_G_CPU0_SA_DQ<19>")
	)
	(segment
		(start 380.444756 -266.335002)
		(end 380.03861 -266.166346)
		(width 0.088646)
		(layer "In4.Cu")
		(net "M_G_CPU0_SA_DQ<19>")
	)
	(segment
		(start 428.183294 -294.36949)
		(end 427.687994 -294.86479)
		(width 0.18288)
		(layer "In4.Cu")
		(net "M_G_CPU0_SA_DQ<19>")
	)
	(segment
		(start 411.428438 -289.522662)
		(end 410.58719 -288.681414)
		(width 0.18288)
		(layer "In4.Cu")
		(net "M_G_CPU0_SA_DQ<19>")
	)
	(segment
		(start 431.282094 -294.36949)
		(end 428.183294 -294.36949)
		(width 0.18288)
		(layer "In4.Cu")
		(net "M_G_CPU0_SA_DQ<19>")
	)
	(segment
		(start 437.349646 -295.492424)
		(end 435.5846 -295.492424)
		(width 0.18288)
		(layer "In4.Cu")
		(net "M_G_CPU0_SA_DQ<19>")
	)
	(segment
		(start 405.151844 -284.662626)
		(end 404.099014 -283.959046)
		(width 0.18288)
		(layer "In4.Cu")
		(net "M_G_CPU0_SA_DQ<19>")
	)
	(segment
		(start 426.570394 -294.86479)
		(end 425.941744 -295.49344)
		(width 0.18288)
		(layer "In4.Cu")
		(net "M_G_CPU0_SA_DQ<19>")
	)
	(segment
		(start 380.648464 -266.452604)
		(end 380.444756 -266.335002)
		(width 0.088646)
		(layer "In4.Cu")
		(net "M_G_CPU0_SA_DQ<19>")
	)
	(segment
		(start 404.099014 -283.959046)
		(end 401.303236 -277.210774)
		(width 0.18288)
		(layer "In4.Cu")
		(net "M_G_CPU0_SA_DQ<19>")
	)
	(segment
		(start 401.303236 -277.210774)
		(end 393.629134 -269.536672)
		(width 0.18288)
		(layer "In4.Cu")
		(net "M_G_CPU0_SA_DQ<19>")
	)
	(segment
		(start 415.205926 -292.952678)
		(end 413.50565 -291.252402)
		(width 0.18288)
		(layer "In4.Cu")
		(net "M_G_CPU0_SA_DQ<19>")
	)
	(segment
		(start 420.55669 -296.342308)
		(end 420.101522 -295.88714)
		(width 0.18288)
		(layer "In4.Cu")
		(net "M_G_CPU0_SA_DQ<19>")
	)
	(segment
		(start 437.532526 -295.675304)
		(end 437.349646 -295.492424)
		(width 0.18288)
		(layer "In4.Cu")
		(net "M_G_CPU0_SA_DQ<19>")
	)
	(segment
		(start 419.601904 -295.48074)
		(end 419.129972 -295.48074)
		(width 0.18288)
		(layer "In4.Cu")
		(net "M_G_CPU0_SA_DQ<19>")
	)
	(segment
		(start 388.081774 -266.247372)
		(end 386.605272 -266.247372)
		(width 0.18288)
		(layer "In4.Cu")
		(net "M_G_CPU0_SA_DQ<19>")
	)
	(segment
		(start 415.637472 -293.015162)
		(end 415.574988 -292.952678)
		(width 0.18288)
		(layer "In4.Cu")
		(net "M_G_CPU0_SA_DQ<19>")
	)
	(segment
		(start 410.58719 -288.681414)
		(end 410.58719 -288.402522)
		(width 0.18288)
		(layer "In4.Cu")
		(net "M_G_CPU0_SA_DQ<19>")
	)
	(segment
		(start 406.154636 -284.662626)
		(end 405.151844 -284.662626)
		(width 0.18288)
		(layer "In4.Cu")
		(net "M_G_CPU0_SA_DQ<19>")
	)
	(segment
		(start 425.941744 -295.49344)
		(end 424.55719 -295.49344)
		(width 0.18288)
		(layer "In4.Cu")
		(net "M_G_CPU0_SA_DQ<19>")
	)
	(segment
		(start 408.18435 -286.69234)
		(end 406.154636 -284.662626)
		(width 0.18288)
		(layer "In4.Cu")
		(net "M_G_CPU0_SA_DQ<19>")
	)
	(segment
		(start 439.497978 -295.492424)
		(end 438.408826 -295.492424)
		(width 0.18288)
		(layer "In4.Cu")
		(net "M_G_CPU0_SA_DQ<19>")
	)
	(segment
		(start 424.44924 -295.60139)
		(end 421.920416 -295.60139)
		(width 0.18288)
		(layer "In4.Cu")
		(net "M_G_CPU0_SA_DQ<19>")
	)
	(segment
		(start 438.225946 -296.038524)
		(end 438.043066 -296.221404)
		(width 0.18288)
		(layer "In4.Cu")
		(net "M_G_CPU0_SA_DQ<19>")
	)
	(segment
		(start 415.574988 -292.952678)
		(end 415.205926 -292.952678)
		(width 0.18288)
		(layer "In4.Cu")
		(net "M_G_CPU0_SA_DQ<19>")
	)
	(segment
		(start 419.83152 -295.575736)
		(end 419.601904 -295.48074)
		(width 0.18288)
		(layer "In4.Cu")
		(net "M_G_CPU0_SA_DQ<19>")
	)
	(segment
		(start 386.605272 -266.247372)
		(end 385.926838 -266.247372)
		(width 0.088646)
		(layer "In4.Cu")
		(net "M_G_CPU0_SA_DQ<19>")
	)
	(segment
		(start 410.58719 -288.402522)
		(end 408.877008 -286.69234)
		(width 0.18288)
		(layer "In4.Cu")
		(net "M_G_CPU0_SA_DQ<19>")
	)
	(arc
		(start 383.467864 -266.452604)
		(mid 383.187493 -266.376799)
		(end 382.906524 -266.450318)
		(width 0.088646)
		(layer "In4.Cu")
		(net "M_G_CPU0_SA_DQ<19>")
	)
	(arc
		(start 383.842514 -266.452604)
		(mid 383.655206 -266.502713)
		(end 383.467864 -266.452604)
		(width 0.088646)
		(layer "In4.Cu")
		(net "M_G_CPU0_SA_DQ<19>")
	)
	(arc
		(start 381.017272 -266.455906)
		(mid 380.832417 -266.502856)
		(end 380.648464 -266.452604)
		(width 0.088646)
		(layer "In4.Cu")
		(net "M_G_CPU0_SA_DQ<19>")
	)
	(arc
		(start 381.588264 -266.452604)
		(mid 381.30909 -266.376805)
		(end 381.028956 -266.449048)
		(width 0.088646)
		(layer "In4.Cu")
		(net "M_G_CPU0_SA_DQ<19>")
	)
	(arc
		(start 384.407664 -266.45235)
		(mid 384.124962 -266.376574)
		(end 383.84226 -266.45235)
		(width 0.088646)
		(layer "In4.Cu")
		(net "M_G_CPU0_SA_DQ<19>")
	)
	(arc
		(start 384.78206 -266.45235)
		(mid 384.594862 -266.502527)
		(end 384.407664 -266.45235)
		(width 0.088646)
		(layer "In4.Cu")
		(net "M_G_CPU0_SA_DQ<19>")
	)
	(arc
		(start 385.347464 -266.45235)
		(mid 385.064762 -266.376574)
		(end 384.78206 -266.45235)
		(width 0.088646)
		(layer "In4.Cu")
		(net "M_G_CPU0_SA_DQ<19>")
	)
	(arc
		(start 382.896872 -266.455906)
		(mid 382.712017 -266.502856)
		(end 382.528064 -266.452604)
		(width 0.088646)
		(layer "In4.Cu")
		(net "M_G_CPU0_SA_DQ<19>")
	)
	(arc
		(start 382.528064 -266.452604)
		(mid 382.24889 -266.376805)
		(end 381.968756 -266.449048)
		(width 0.088646)
		(layer "In4.Cu")
		(net "M_G_CPU0_SA_DQ<19>")
	)
	(arc
		(start 381.957072 -266.455906)
		(mid 381.772217 -266.502856)
		(end 381.588264 -266.452604)
		(width 0.088646)
		(layer "In4.Cu")
		(net "M_G_CPU0_SA_DQ<19>")
	)
	(arc
		(start 385.72186 -266.45235)
		(mid 385.534662 -266.502527)
		(end 385.347464 -266.45235)
		(width 0.088646)
		(layer "In4.Cu")
		(net "M_G_CPU0_SA_DQ<19>")
	)
	(segment
		(start 443.450726 -297.198796)
		(end 443.455552 -297.198796)
		(width 0.101854)
		(layer "F.Cu")
		(net "M_G_CPU0_SA_DQ<18>")
	)
	(segment
		(start 445.470534 -297.191684)
		(end 445.482726 -297.203876)
		(width 0.1016)
		(layer "F.Cu")
		(net "M_G_CPU0_SA_DQ<18>")
	)
	(segment
		(start 446.163954 -297.203876)
		(end 446.367916 -296.999914)
		(width 0.20066)
		(layer "F.Cu")
		(net "M_G_CPU0_SA_DQ<18>")
	)
	(segment
		(start 379.425962 -266.405868)
		(end 379.425962 -266.941554)
		(width 0.20066)
		(layer "F.Cu")
		(net "M_G_CPU0_SA_DQ<18>")
	)
	(segment
		(start 441.028582 -296.766742)
		(end 442.726826 -296.766742)
		(width 0.20066)
		(layer "F.Cu")
		(net "M_G_CPU0_SA_DQ<18>")
	)
	(segment
		(start 446.367916 -296.748962)
		(end 446.602104 -296.514774)
		(width 0.20066)
		(layer "F.Cu")
		(net "M_G_CPU0_SA_DQ<18>")
	)
	(segment
		(start 446.986152 -296.514774)
		(end 447.23812 -296.766742)
		(width 0.20066)
		(layer "F.Cu")
		(net "M_G_CPU0_SA_DQ<18>")
	)
	(segment
		(start 443.15888 -297.198796)
		(end 443.450726 -297.198796)
		(width 0.20066)
		(layer "F.Cu")
		(net "M_G_CPU0_SA_DQ<18>")
	)
	(segment
		(start 443.462664 -297.191684)
		(end 445.470534 -297.191684)
		(width 0.1016)
		(layer "F.Cu")
		(net "M_G_CPU0_SA_DQ<18>")
	)
	(segment
		(start 439.923682 -296.766742)
		(end 441.028582 -296.766742)
		(width 0.20066)
		(layer "F.Cu")
		(net "M_G_CPU0_SA_DQ<18>")
	)
	(segment
		(start 442.726826 -296.766742)
		(end 443.15888 -297.198796)
		(width 0.20066)
		(layer "F.Cu")
		(net "M_G_CPU0_SA_DQ<18>")
	)
	(segment
		(start 446.367916 -296.999914)
		(end 446.367916 -296.748962)
		(width 0.20066)
		(layer "F.Cu")
		(net "M_G_CPU0_SA_DQ<18>")
	)
	(segment
		(start 443.455552 -297.198796)
		(end 443.462664 -297.191684)
		(width 0.1016)
		(layer "F.Cu")
		(net "M_G_CPU0_SA_DQ<18>")
	)
	(segment
		(start 446.602104 -296.514774)
		(end 446.986152 -296.514774)
		(width 0.20066)
		(layer "F.Cu")
		(net "M_G_CPU0_SA_DQ<18>")
	)
	(segment
		(start 379.425962 -266.941554)
		(end 379.426216 -266.941808)
		(width 0.20066)
		(layer "F.Cu")
		(net "M_G_CPU0_SA_DQ<18>")
	)
	(segment
		(start 447.23812 -296.766742)
		(end 448.572382 -296.766742)
		(width 0.20066)
		(layer "F.Cu")
		(net "M_G_CPU0_SA_DQ<18>")
	)
	(segment
		(start 445.482726 -297.203876)
		(end 446.163954 -297.203876)
		(width 0.20066)
		(layer "F.Cu")
		(net "M_G_CPU0_SA_DQ<18>")
	)
	(segment
		(start 416.584638 -295.330372)
		(end 415.846768 -294.592502)
		(width 0.18288)
		(layer "In4.Cu")
		(net "M_G_CPU0_SA_DQ<18>")
	)
	(segment
		(start 404.678388 -285.691072)
		(end 403.3774 -284.82163)
		(width 0.18288)
		(layer "In4.Cu")
		(net "M_G_CPU0_SA_DQ<18>")
	)
	(segment
		(start 419.20287 -297.057064)
		(end 417.894008 -295.748202)
		(width 0.18288)
		(layer "In4.Cu")
		(net "M_G_CPU0_SA_DQ<18>")
	)
	(segment
		(start 383.940304 -267.267944)
		(end 383.937764 -267.26642)
		(width 0.088646)
		(layer "In4.Cu")
		(net "M_G_CPU0_SA_DQ<18>")
	)
	(segment
		(start 393.294108 -270.609822)
		(end 392.119866 -270.609822)
		(width 0.18288)
		(layer "In4.Cu")
		(net "M_G_CPU0_SA_DQ<18>")
	)
	(segment
		(start 406.115266 -286.50438)
		(end 405.491696 -286.50438)
		(width 0.18288)
		(layer "In4.Cu")
		(net "M_G_CPU0_SA_DQ<18>")
	)
	(segment
		(start 382.997964 -267.26642)
		(end 382.990598 -267.262102)
		(width 0.088646)
		(layer "In4.Cu")
		(net "M_G_CPU0_SA_DQ<18>")
	)
	(segment
		(start 420.091108 -297.68673)
		(end 420.091108 -297.556936)
		(width 0.18288)
		(layer "In4.Cu")
		(net "M_G_CPU0_SA_DQ<18>")
	)
	(segment
		(start 380.183136 -267.26896)
		(end 380.178564 -267.26642)
		(width 0.088646)
		(layer "In4.Cu")
		(net "M_G_CPU0_SA_DQ<18>")
	)
	(segment
		(start 430.849024 -296.33164)
		(end 427.81728 -296.33164)
		(width 0.18288)
		(layer "In4.Cu")
		(net "M_G_CPU0_SA_DQ<18>")
	)
	(segment
		(start 408.076654 -288.593276)
		(end 407.293318 -288.593276)
		(width 0.18288)
		(layer "In4.Cu")
		(net "M_G_CPU0_SA_DQ<18>")
	)
	(segment
		(start 408.946604 -289.463226)
		(end 408.076654 -288.593276)
		(width 0.18288)
		(layer "In4.Cu")
		(net "M_G_CPU0_SA_DQ<18>")
	)
	(segment
		(start 426.529754 -296.972482)
		(end 425.239434 -297.192446)
		(width 0.18288)
		(layer "In4.Cu")
		(net "M_G_CPU0_SA_DQ<18>")
	)
	(segment
		(start 419.591236 -297.057064)
		(end 419.20287 -297.057064)
		(width 0.18288)
		(layer "In4.Cu")
		(net "M_G_CPU0_SA_DQ<18>")
	)
	(segment
		(start 381.118364 -267.26642)
		(end 381.110998 -267.262102)
		(width 0.088646)
		(layer "In4.Cu")
		(net "M_G_CPU0_SA_DQ<18>")
	)
	(segment
		(start 379.238764 -267.26642)
		(end 379.235208 -267.264388)
		(width 0.088646)
		(layer "In4.Cu")
		(net "M_G_CPU0_SA_DQ<18>")
	)
	(segment
		(start 382.062736 -267.26896)
		(end 382.058164 -267.26642)
		(width 0.088646)
		(layer "In4.Cu")
		(net "M_G_CPU0_SA_DQ<18>")
	)
	(segment
		(start 439.923682 -296.766742)
		(end 438.890664 -297.19143)
		(width 0.18288)
		(layer "In4.Cu")
		(net "M_G_CPU0_SA_DQ<18>")
	)
	(segment
		(start 410.051504 -290.419536)
		(end 409.525724 -290.419536)
		(width 0.18288)
		(layer "In4.Cu")
		(net "M_G_CPU0_SA_DQ<18>")
	)
	(segment
		(start 390.961626 -270.129762)
		(end 387.76275 -266.930886)
		(width 0.18288)
		(layer "In4.Cu")
		(net "M_G_CPU0_SA_DQ<18>")
	)
	(segment
		(start 382.058164 -267.26642)
		(end 382.050798 -267.262102)
		(width 0.088646)
		(layer "In4.Cu")
		(net "M_G_CPU0_SA_DQ<18>")
	)
	(segment
		(start 413.807402 -292.968426)
		(end 412.600394 -292.968426)
		(width 0.18288)
		(layer "In4.Cu")
		(net "M_G_CPU0_SA_DQ<18>")
	)
	(segment
		(start 386.009642 -266.930886)
		(end 385.92125 -267.019278)
		(width 0.088646)
		(layer "In4.Cu")
		(net "M_G_CPU0_SA_DQ<18>")
	)
	(segment
		(start 438.890664 -297.19143)
		(end 435.302914 -297.19143)
		(width 0.18288)
		(layer "In4.Cu")
		(net "M_G_CPU0_SA_DQ<18>")
	)
	(segment
		(start 417.153852 -295.330372)
		(end 416.584638 -295.330372)
		(width 0.18288)
		(layer "In4.Cu")
		(net "M_G_CPU0_SA_DQ<18>")
	)
	(segment
		(start 379.243336 -267.26896)
		(end 379.238764 -267.26642)
		(width 0.088646)
		(layer "In4.Cu")
		(net "M_G_CPU0_SA_DQ<18>")
	)
	(segment
		(start 406.630124 -287.019238)
		(end 406.115266 -286.50438)
		(width 0.18288)
		(layer "In4.Cu")
		(net "M_G_CPU0_SA_DQ<18>")
	)
	(segment
		(start 417.894008 -295.748202)
		(end 417.153852 -295.330372)
		(width 0.18288)
		(layer "In4.Cu")
		(net "M_G_CPU0_SA_DQ<18>")
	)
	(segment
		(start 403.3774 -284.82163)
		(end 400.457924 -277.773638)
		(width 0.18288)
		(layer "In4.Cu")
		(net "M_G_CPU0_SA_DQ<18>")
	)
	(segment
		(start 385.47929 -267.019278)
		(end 385.212336 -267.286232)
		(width 0.088646)
		(layer "In4.Cu")
		(net "M_G_CPU0_SA_DQ<18>")
	)
	(segment
		(start 421.077644 -298.038266)
		(end 420.442644 -298.038266)
		(width 0.18288)
		(layer "In4.Cu")
		(net "M_G_CPU0_SA_DQ<18>")
	)
	(segment
		(start 381.122936 -267.26896)
		(end 381.118364 -267.26642)
		(width 0.088646)
		(layer "In4.Cu")
		(net "M_G_CPU0_SA_DQ<18>")
	)
	(segment
		(start 380.178564 -267.26642)
		(end 380.171198 -267.262102)
		(width 0.088646)
		(layer "In4.Cu")
		(net "M_G_CPU0_SA_DQ<18>")
	)
	(segment
		(start 414.867598 -294.028622)
		(end 413.807402 -292.968426)
		(width 0.18288)
		(layer "In4.Cu")
		(net "M_G_CPU0_SA_DQ<18>")
	)
	(segment
		(start 400.457924 -277.773638)
		(end 393.294108 -270.609822)
		(width 0.18288)
		(layer "In4.Cu")
		(net "M_G_CPU0_SA_DQ<18>")
	)
	(segment
		(start 383.001774 -267.268452)
		(end 382.997964 -267.26642)
		(width 0.088646)
		(layer "In4.Cu")
		(net "M_G_CPU0_SA_DQ<18>")
	)
	(segment
		(start 405.491696 -286.50438)
		(end 404.678388 -285.691072)
		(width 0.18288)
		(layer "In4.Cu")
		(net "M_G_CPU0_SA_DQ<18>")
	)
	(segment
		(start 434.345334 -297.04919)
		(end 432.098958 -296.653966)
		(width 0.18288)
		(layer "In4.Cu")
		(net "M_G_CPU0_SA_DQ<18>")
	)
	(segment
		(start 392.119866 -270.609822)
		(end 390.961626 -270.129762)
		(width 0.18288)
		(layer "In4.Cu")
		(net "M_G_CPU0_SA_DQ<18>")
	)
	(segment
		(start 384.31216 -267.266166)
		(end 384.312414 -267.26642)
		(width 0.088646)
		(layer "In4.Cu")
		(net "M_G_CPU0_SA_DQ<18>")
	)
	(segment
		(start 427.81728 -296.33164)
		(end 426.529754 -296.972482)
		(width 0.18288)
		(layer "In4.Cu")
		(net "M_G_CPU0_SA_DQ<18>")
	)
	(segment
		(start 379.055884 -266.999212)
		(end 379.113288 -266.941808)
		(width 0.088646)
		(layer "In4.Cu")
		(net "M_G_CPU0_SA_DQ<18>")
	)
	(segment
		(start 385.92125 -267.019278)
		(end 385.47929 -267.019278)
		(width 0.088646)
		(layer "In4.Cu")
		(net "M_G_CPU0_SA_DQ<18>")
	)
	(segment
		(start 408.946604 -289.840416)
		(end 408.946604 -289.463226)
		(width 0.18288)
		(layer "In4.Cu")
		(net "M_G_CPU0_SA_DQ<18>")
	)
	(segment
		(start 379.113288 -266.941808)
		(end 379.426216 -266.941808)
		(width 0.088646)
		(layer "In4.Cu")
		(net "M_G_CPU0_SA_DQ<18>")
	)
	(segment
		(start 420.442644 -298.038266)
		(end 420.091108 -297.68673)
		(width 0.18288)
		(layer "In4.Cu")
		(net "M_G_CPU0_SA_DQ<18>")
	)
	(segment
		(start 387.76275 -266.930886)
		(end 386.605272 -266.930886)
		(width 0.18288)
		(layer "In4.Cu")
		(net "M_G_CPU0_SA_DQ<18>")
	)
	(segment
		(start 412.600394 -292.968426)
		(end 410.051504 -290.419536)
		(width 0.18288)
		(layer "In4.Cu")
		(net "M_G_CPU0_SA_DQ<18>")
	)
	(segment
		(start 421.923464 -297.192446)
		(end 421.077644 -298.038266)
		(width 0.18288)
		(layer "In4.Cu")
		(net "M_G_CPU0_SA_DQ<18>")
	)
	(segment
		(start 415.846768 -294.592502)
		(end 415.106612 -294.174672)
		(width 0.18288)
		(layer "In4.Cu")
		(net "M_G_CPU0_SA_DQ<18>")
	)
	(segment
		(start 407.293318 -288.593276)
		(end 406.630124 -287.930082)
		(width 0.18288)
		(layer "In4.Cu")
		(net "M_G_CPU0_SA_DQ<18>")
	)
	(segment
		(start 435.302914 -297.19143)
		(end 434.345334 -297.04919)
		(width 0.18288)
		(layer "In4.Cu")
		(net "M_G_CPU0_SA_DQ<18>")
	)
	(segment
		(start 432.098958 -296.653966)
		(end 430.849024 -296.33164)
		(width 0.18288)
		(layer "In4.Cu")
		(net "M_G_CPU0_SA_DQ<18>")
	)
	(segment
		(start 420.091108 -297.556936)
		(end 419.591236 -297.057064)
		(width 0.18288)
		(layer "In4.Cu")
		(net "M_G_CPU0_SA_DQ<18>")
	)
	(segment
		(start 415.106612 -294.174672)
		(end 414.867598 -294.028622)
		(width 0.18288)
		(layer "In4.Cu")
		(net "M_G_CPU0_SA_DQ<18>")
	)
	(segment
		(start 406.630124 -287.930082)
		(end 406.630124 -287.019238)
		(width 0.18288)
		(layer "In4.Cu")
		(net "M_G_CPU0_SA_DQ<18>")
	)
	(segment
		(start 425.239434 -297.192446)
		(end 421.923464 -297.192446)
		(width 0.18288)
		(layer "In4.Cu")
		(net "M_G_CPU0_SA_DQ<18>")
	)
	(segment
		(start 386.605272 -266.930886)
		(end 386.009642 -266.930886)
		(width 0.088646)
		(layer "In4.Cu")
		(net "M_G_CPU0_SA_DQ<18>")
	)
	(segment
		(start 409.525724 -290.419536)
		(end 408.946604 -289.840416)
		(width 0.18288)
		(layer "In4.Cu")
		(net "M_G_CPU0_SA_DQ<18>")
	)
	(arc
		(start 379.235208 -267.264388)
		(mid 379.115823 -267.151906)
		(end 379.055884 -266.999212)
		(width 0.088646)
		(layer "In4.Cu")
		(net "M_G_CPU0_SA_DQ<18>")
	)
	(arc
		(start 383.937764 -267.26642)
		(mid 383.655206 -267.190771)
		(end 383.372614 -267.26642)
		(width 0.088646)
		(layer "In4.Cu")
		(net "M_G_CPU0_SA_DQ<18>")
	)
	(arc
		(start 384.877564 -267.266166)
		(mid 384.594862 -267.190424)
		(end 384.31216 -267.266166)
		(width 0.088646)
		(layer "In4.Cu")
		(net "M_G_CPU0_SA_DQ<18>")
	)
	(arc
		(start 382.990598 -267.262102)
		(mid 382.711137 -267.190665)
		(end 382.432814 -267.26642)
		(width 0.088646)
		(layer "In4.Cu")
		(net "M_G_CPU0_SA_DQ<18>")
	)
	(arc
		(start 382.050798 -267.262102)
		(mid 381.771337 -267.190665)
		(end 381.493014 -267.26642)
		(width 0.088646)
		(layer "In4.Cu")
		(net "M_G_CPU0_SA_DQ<18>")
	)
	(arc
		(start 382.432814 -267.26642)
		(mid 382.24812 -267.316521)
		(end 382.062736 -267.26896)
		(width 0.088646)
		(layer "In4.Cu")
		(net "M_G_CPU0_SA_DQ<18>")
	)
	(arc
		(start 384.312414 -267.26642)
		(mid 384.126553 -267.316653)
		(end 383.940304 -267.267944)
		(width 0.088646)
		(layer "In4.Cu")
		(net "M_G_CPU0_SA_DQ<18>")
	)
	(arc
		(start 380.171198 -267.262102)
		(mid 379.891737 -267.190665)
		(end 379.613414 -267.26642)
		(width 0.088646)
		(layer "In4.Cu")
		(net "M_G_CPU0_SA_DQ<18>")
	)
	(arc
		(start 381.493014 -267.26642)
		(mid 381.30832 -267.316521)
		(end 381.122936 -267.26896)
		(width 0.088646)
		(layer "In4.Cu")
		(net "M_G_CPU0_SA_DQ<18>")
	)
	(arc
		(start 383.372614 -267.26642)
		(mid 383.187464 -267.316524)
		(end 383.001774 -267.268452)
		(width 0.088646)
		(layer "In4.Cu")
		(net "M_G_CPU0_SA_DQ<18>")
	)
	(arc
		(start 379.613414 -267.26642)
		(mid 379.42872 -267.316521)
		(end 379.243336 -267.26896)
		(width 0.088646)
		(layer "In4.Cu")
		(net "M_G_CPU0_SA_DQ<18>")
	)
	(arc
		(start 380.553214 -267.26642)
		(mid 380.36852 -267.316521)
		(end 380.183136 -267.26896)
		(width 0.088646)
		(layer "In4.Cu")
		(net "M_G_CPU0_SA_DQ<18>")
	)
	(arc
		(start 385.212336 -267.286232)
		(mid 385.042582 -267.315744)
		(end 384.877564 -267.266166)
		(width 0.088646)
		(layer "In4.Cu")
		(net "M_G_CPU0_SA_DQ<18>")
	)
	(arc
		(start 381.110998 -267.262102)
		(mid 380.831537 -267.190665)
		(end 380.553214 -267.26642)
		(width 0.088646)
		(layer "In4.Cu")
		(net "M_G_CPU0_SA_DQ<18>")
	)
	(segment
		(start 444.472314 -295.916604)
		(end 444.47206 -295.916858)
		(width 0.20066)
		(layer "F.Cu")
		(net "M_G_CPU0_SA_DQ<17>")
	)
	(segment
		(start 439.479182 -295.491662)
		(end 439.361072 -295.609772)
		(width 0.20066)
		(layer "F.Cu")
		(net "M_G_CPU0_SA_DQ<17>")
	)
	(segment
		(start 438.449212 -295.916604)
		(end 436.928514 -295.916604)
		(width 0.20066)
		(layer "F.Cu")
		(net "M_G_CPU0_SA_DQ<17>")
	)
	(segment
		(start 378.016516 -266.127992)
		(end 378.016262 -266.128246)
		(width 0.20066)
		(layer "F.Cu")
		(net "M_G_CPU0_SA_DQ<17>")
	)
	(segment
		(start 439.361072 -295.97731)
		(end 439.173112 -296.16527)
		(width 0.20066)
		(layer "F.Cu")
		(net "M_G_CPU0_SA_DQ<17>")
	)
	(segment
		(start 439.361072 -295.609772)
		(end 439.361072 -295.97731)
		(width 0.20066)
		(layer "F.Cu")
		(net "M_G_CPU0_SA_DQ<17>")
	)
	(segment
		(start 442.44895 -295.485312)
		(end 442.038994 -295.485312)
		(width 0.20066)
		(layer "F.Cu")
		(net "M_G_CPU0_SA_DQ<17>")
	)
	(segment
		(start 442.038994 -295.485312)
		(end 442.032644 -295.491662)
		(width 0.1016)
		(layer "F.Cu")
		(net "M_G_CPU0_SA_DQ<17>")
	)
	(segment
		(start 439.173112 -296.16527)
		(end 438.697878 -296.16527)
		(width 0.20066)
		(layer "F.Cu")
		(net "M_G_CPU0_SA_DQ<17>")
	)
	(segment
		(start 436.928514 -295.916604)
		(end 435.823614 -295.916604)
		(width 0.20066)
		(layer "F.Cu")
		(net "M_G_CPU0_SA_DQ<17>")
	)
	(segment
		(start 439.843926 -295.491662)
		(end 439.82386 -295.491662)
		(width 0.101854)
		(layer "F.Cu")
		(net "M_G_CPU0_SA_DQ<17>")
	)
	(segment
		(start 442.032644 -295.491662)
		(end 439.843926 -295.491662)
		(width 0.1016)
		(layer "F.Cu")
		(net "M_G_CPU0_SA_DQ<17>")
	)
	(segment
		(start 438.697878 -296.16527)
		(end 438.449212 -295.916604)
		(width 0.20066)
		(layer "F.Cu")
		(net "M_G_CPU0_SA_DQ<17>")
	)
	(segment
		(start 444.47206 -295.916858)
		(end 442.880496 -295.916858)
		(width 0.20066)
		(layer "F.Cu")
		(net "M_G_CPU0_SA_DQ<17>")
	)
	(segment
		(start 442.880496 -295.916858)
		(end 442.44895 -295.485312)
		(width 0.20066)
		(layer "F.Cu")
		(net "M_G_CPU0_SA_DQ<17>")
	)
	(segment
		(start 378.016516 -265.592306)
		(end 378.016516 -266.127992)
		(width 0.20066)
		(layer "F.Cu")
		(net "M_G_CPU0_SA_DQ<17>")
	)
	(segment
		(start 439.82386 -295.491662)
		(end 439.479182 -295.491662)
		(width 0.20066)
		(layer "F.Cu")
		(net "M_G_CPU0_SA_DQ<17>")
	)
	(segment
		(start 410.897578 -290.319714)
		(end 410.897578 -289.840162)
		(width 0.18288)
		(layer "In4.Cu")
		(net "M_G_CPU0_SA_DQ<17>")
	)
	(segment
		(start 429.573944 -294.89019)
		(end 429.13173 -294.89019)
		(width 0.18288)
		(layer "In4.Cu")
		(net "M_G_CPU0_SA_DQ<17>")
	)
	(segment
		(start 435.224428 -296.51579)
		(end 434.533294 -296.51579)
		(width 0.18288)
		(layer "In4.Cu")
		(net "M_G_CPU0_SA_DQ<17>")
	)
	(segment
		(start 433.291996 -295.32199)
		(end 432.157886 -295.32199)
		(width 0.18288)
		(layer "In4.Cu")
		(net "M_G_CPU0_SA_DQ<17>")
	)
	(segment
		(start 428.78883 -295.60139)
		(end 427.789594 -295.60139)
		(width 0.18288)
		(layer "In4.Cu")
		(net "M_G_CPU0_SA_DQ<17>")
	)
	(segment
		(start 378.016516 -266.128246)
		(end 378.016262 -266.128246)
		(width 0.088646)
		(layer "In4.Cu")
		(net "M_G_CPU0_SA_DQ<17>")
	)
	(segment
		(start 433.624482 -296.385234)
		(end 433.378102 -296.138854)
		(width 0.18288)
		(layer "In4.Cu")
		(net "M_G_CPU0_SA_DQ<17>")
	)
	(segment
		(start 424.141138 -296.679112)
		(end 423.793158 -296.679112)
		(width 0.18288)
		(layer "In4.Cu")
		(net "M_G_CPU0_SA_DQ<17>")
	)
	(segment
		(start 382.058164 -266.61745)
		(end 382.052322 -266.621006)
		(width 0.088646)
		(layer "In4.Cu")
		(net "M_G_CPU0_SA_DQ<17>")
	)
	(segment
		(start 434.23967 -296.222166)
		(end 434.01361 -296.222166)
		(width 0.18288)
		(layer "In4.Cu")
		(net "M_G_CPU0_SA_DQ<17>")
	)
	(segment
		(start 429.733964 -295.415462)
		(end 429.733964 -295.05021)
		(width 0.18288)
		(layer "In4.Cu")
		(net "M_G_CPU0_SA_DQ<17>")
	)
	(segment
		(start 381.118364 -266.61745)
		(end 381.112522 -266.621006)
		(width 0.088646)
		(layer "In4.Cu")
		(net "M_G_CPU0_SA_DQ<17>")
	)
	(segment
		(start 423.282872 -296.168826)
		(end 422.124124 -296.168826)
		(width 0.18288)
		(layer "In4.Cu")
		(net "M_G_CPU0_SA_DQ<17>")
	)
	(segment
		(start 419.801294 -296.531284)
		(end 419.400228 -296.531284)
		(width 0.18288)
		(layer "In4.Cu")
		(net "M_G_CPU0_SA_DQ<17>")
	)
	(segment
		(start 412.016702 -291.025326)
		(end 411.60319 -291.025326)
		(width 0.18288)
		(layer "In4.Cu")
		(net "M_G_CPU0_SA_DQ<17>")
	)
	(segment
		(start 426.519594 -295.72839)
		(end 426.519594 -295.95699)
		(width 0.18288)
		(layer "In4.Cu")
		(net "M_G_CPU0_SA_DQ<17>")
	)
	(segment
		(start 385.835398 -266.66952)
		(end 385.69773 -266.66952)
		(width 0.088646)
		(layer "In4.Cu")
		(net "M_G_CPU0_SA_DQ<17>")
	)
	(segment
		(start 434.533294 -296.51579)
		(end 434.23967 -296.222166)
		(width 0.18288)
		(layer "In4.Cu")
		(net "M_G_CPU0_SA_DQ<17>")
	)
	(segment
		(start 413.345122 -291.800026)
		(end 412.791402 -291.800026)
		(width 0.18288)
		(layer "In4.Cu")
		(net "M_G_CPU0_SA_DQ<17>")
	)
	(segment
		(start 385.912106 -266.592812)
		(end 385.835398 -266.66952)
		(width 0.088646)
		(layer "In4.Cu")
		(net "M_G_CPU0_SA_DQ<17>")
	)
	(segment
		(start 408.250898 -287.996376)
		(end 407.502868 -287.996376)
		(width 0.18288)
		(layer "In4.Cu")
		(net "M_G_CPU0_SA_DQ<17>")
	)
	(segment
		(start 433.378102 -295.839388)
		(end 433.480718 -295.736772)
		(width 0.18288)
		(layer "In4.Cu")
		(net "M_G_CPU0_SA_DQ<17>")
	)
	(segment
		(start 435.823614 -295.916604)
		(end 435.224428 -296.51579)
		(width 0.18288)
		(layer "In4.Cu")
		(net "M_G_CPU0_SA_DQ<17>")
	)
	(segment
		(start 403.708108 -284.316678)
		(end 400.880072 -277.491698)
		(width 0.18288)
		(layer "In4.Cu")
		(net "M_G_CPU0_SA_DQ<17>")
	)
	(segment
		(start 426.798994 -295.44899)
		(end 426.519594 -295.72839)
		(width 0.18288)
		(layer "In4.Cu")
		(net "M_G_CPU0_SA_DQ<17>")
	)
	(segment
		(start 405.920956 -285.181294)
		(end 405.002492 -285.181294)
		(width 0.18288)
		(layer "In4.Cu")
		(net "M_G_CPU0_SA_DQ<17>")
	)
	(segment
		(start 431.878486 -295.60139)
		(end 429.919892 -295.60139)
		(width 0.18288)
		(layer "In4.Cu")
		(net "M_G_CPU0_SA_DQ<17>")
	)
	(segment
		(start 428.94885 -295.07307)
		(end 428.94885 -295.44137)
		(width 0.18288)
		(layer "In4.Cu")
		(net "M_G_CPU0_SA_DQ<17>")
	)
	(segment
		(start 433.480718 -295.736772)
		(end 433.480718 -295.510712)
		(width 0.18288)
		(layer "In4.Cu")
		(net "M_G_CPU0_SA_DQ<17>")
	)
	(segment
		(start 433.480718 -295.510712)
		(end 433.291996 -295.32199)
		(width 0.18288)
		(layer "In4.Cu")
		(net "M_G_CPU0_SA_DQ<17>")
	)
	(segment
		(start 393.422886 -270.034512)
		(end 392.055096 -270.034512)
		(width 0.18288)
		(layer "In4.Cu")
		(net "M_G_CPU0_SA_DQ<17>")
	)
	(segment
		(start 417.97478 -295.105836)
		(end 417.0045 -294.7035)
		(width 0.18288)
		(layer "In4.Cu")
		(net "M_G_CPU0_SA_DQ<17>")
	)
	(segment
		(start 423.793158 -296.679112)
		(end 423.282872 -296.168826)
		(width 0.18288)
		(layer "In4.Cu")
		(net "M_G_CPU0_SA_DQ<17>")
	)
	(segment
		(start 422.124124 -296.168826)
		(end 421.100504 -297.192446)
		(width 0.18288)
		(layer "In4.Cu")
		(net "M_G_CPU0_SA_DQ<17>")
	)
	(segment
		(start 417.0045 -294.7035)
		(end 415.116772 -293.571676)
		(width 0.18288)
		(layer "In4.Cu")
		(net "M_G_CPU0_SA_DQ<17>")
	)
	(segment
		(start 400.880072 -277.491698)
		(end 393.422886 -270.034512)
		(width 0.18288)
		(layer "In4.Cu")
		(net "M_G_CPU0_SA_DQ<17>")
	)
	(segment
		(start 383.002282 -266.61491)
		(end 382.997964 -266.61745)
		(width 0.088646)
		(layer "In4.Cu")
		(net "M_G_CPU0_SA_DQ<17>")
	)
	(segment
		(start 409.065222 -288.8107)
		(end 408.250898 -287.996376)
		(width 0.18288)
		(layer "In4.Cu")
		(net "M_G_CPU0_SA_DQ<17>")
	)
	(segment
		(start 424.478196 -296.342054)
		(end 424.141138 -296.679112)
		(width 0.18288)
		(layer "In4.Cu")
		(net "M_G_CPU0_SA_DQ<17>")
	)
	(segment
		(start 410.897578 -289.840162)
		(end 409.868116 -288.8107)
		(width 0.18288)
		(layer "In4.Cu")
		(net "M_G_CPU0_SA_DQ<17>")
	)
	(segment
		(start 419.400228 -296.531284)
		(end 417.97478 -295.105836)
		(width 0.18288)
		(layer "In4.Cu")
		(net "M_G_CPU0_SA_DQ<17>")
	)
	(segment
		(start 421.100504 -297.192446)
		(end 420.462456 -297.192446)
		(width 0.18288)
		(layer "In4.Cu")
		(net "M_G_CPU0_SA_DQ<17>")
	)
	(segment
		(start 382.997964 -266.61745)
		(end 382.992122 -266.621006)
		(width 0.088646)
		(layer "In4.Cu")
		(net "M_G_CPU0_SA_DQ<17>")
	)
	(segment
		(start 433.850542 -296.385234)
		(end 433.624482 -296.385234)
		(width 0.18288)
		(layer "In4.Cu")
		(net "M_G_CPU0_SA_DQ<17>")
	)
	(segment
		(start 425.088304 -296.342054)
		(end 424.478196 -296.342054)
		(width 0.18288)
		(layer "In4.Cu")
		(net "M_G_CPU0_SA_DQ<17>")
	)
	(segment
		(start 420.462456 -297.192446)
		(end 419.801294 -296.531284)
		(width 0.18288)
		(layer "In4.Cu")
		(net "M_G_CPU0_SA_DQ<17>")
	)
	(segment
		(start 380.184406 -266.614148)
		(end 380.178564 -266.61745)
		(width 0.088646)
		(layer "In4.Cu")
		(net "M_G_CPU0_SA_DQ<17>")
	)
	(segment
		(start 428.94885 -295.44137)
		(end 428.78883 -295.60139)
		(width 0.18288)
		(layer "In4.Cu")
		(net "M_G_CPU0_SA_DQ<17>")
	)
	(segment
		(start 425.28744 -296.54119)
		(end 425.088304 -296.342054)
		(width 0.18288)
		(layer "In4.Cu")
		(net "M_G_CPU0_SA_DQ<17>")
	)
	(segment
		(start 429.919892 -295.60139)
		(end 429.733964 -295.415462)
		(width 0.18288)
		(layer "In4.Cu")
		(net "M_G_CPU0_SA_DQ<17>")
	)
	(segment
		(start 405.002492 -285.181294)
		(end 403.708108 -284.316678)
		(width 0.18288)
		(layer "In4.Cu")
		(net "M_G_CPU0_SA_DQ<17>")
	)
	(segment
		(start 409.868116 -288.8107)
		(end 409.065222 -288.8107)
		(width 0.18288)
		(layer "In4.Cu")
		(net "M_G_CPU0_SA_DQ<17>")
	)
	(segment
		(start 432.157886 -295.32199)
		(end 431.878486 -295.60139)
		(width 0.18288)
		(layer "In4.Cu")
		(net "M_G_CPU0_SA_DQ<17>")
	)
	(segment
		(start 390.853676 -269.536926)
		(end 387.909562 -266.592812)
		(width 0.18288)
		(layer "In4.Cu")
		(net "M_G_CPU0_SA_DQ<17>")
	)
	(segment
		(start 429.733964 -295.05021)
		(end 429.573944 -294.89019)
		(width 0.18288)
		(layer "In4.Cu")
		(net "M_G_CPU0_SA_DQ<17>")
	)
	(segment
		(start 426.519594 -295.95699)
		(end 425.935394 -296.54119)
		(width 0.18288)
		(layer "In4.Cu")
		(net "M_G_CPU0_SA_DQ<17>")
	)
	(segment
		(start 433.378102 -296.138854)
		(end 433.378102 -295.839388)
		(width 0.18288)
		(layer "In4.Cu")
		(net "M_G_CPU0_SA_DQ<17>")
	)
	(segment
		(start 434.01361 -296.222166)
		(end 433.850542 -296.385234)
		(width 0.18288)
		(layer "In4.Cu")
		(net "M_G_CPU0_SA_DQ<17>")
	)
	(segment
		(start 412.791402 -291.800026)
		(end 412.016702 -291.025326)
		(width 0.18288)
		(layer "In4.Cu")
		(net "M_G_CPU0_SA_DQ<17>")
	)
	(segment
		(start 379.238764 -266.61745)
		(end 379.232922 -266.621006)
		(width 0.088646)
		(layer "In4.Cu")
		(net "M_G_CPU0_SA_DQ<17>")
	)
	(segment
		(start 427.637194 -295.44899)
		(end 426.798994 -295.44899)
		(width 0.18288)
		(layer "In4.Cu")
		(net "M_G_CPU0_SA_DQ<17>")
	)
	(segment
		(start 380.178564 -266.61745)
		(end 380.172722 -266.621006)
		(width 0.088646)
		(layer "In4.Cu")
		(net "M_G_CPU0_SA_DQ<17>")
	)
	(segment
		(start 381.124206 -266.614148)
		(end 381.118364 -266.61745)
		(width 0.088646)
		(layer "In4.Cu")
		(net "M_G_CPU0_SA_DQ<17>")
	)
	(segment
		(start 407.502868 -287.996376)
		(end 407.342848 -287.836356)
		(width 0.18288)
		(layer "In4.Cu")
		(net "M_G_CPU0_SA_DQ<17>")
	)
	(segment
		(start 407.342848 -287.836356)
		(end 407.342848 -286.603186)
		(width 0.18288)
		(layer "In4.Cu")
		(net "M_G_CPU0_SA_DQ<17>")
	)
	(segment
		(start 390.961626 -269.58163)
		(end 390.853676 -269.536926)
		(width 0.18288)
		(layer "In4.Cu")
		(net "M_G_CPU0_SA_DQ<17>")
	)
	(segment
		(start 427.789594 -295.60139)
		(end 427.637194 -295.44899)
		(width 0.18288)
		(layer "In4.Cu")
		(net "M_G_CPU0_SA_DQ<17>")
	)
	(segment
		(start 407.342848 -286.603186)
		(end 405.920956 -285.181294)
		(width 0.18288)
		(layer "In4.Cu")
		(net "M_G_CPU0_SA_DQ<17>")
	)
	(segment
		(start 415.116772 -293.571676)
		(end 413.345122 -291.800026)
		(width 0.18288)
		(layer "In4.Cu")
		(net "M_G_CPU0_SA_DQ<17>")
	)
	(segment
		(start 379.244606 -266.614148)
		(end 379.238764 -266.61745)
		(width 0.088646)
		(layer "In4.Cu")
		(net "M_G_CPU0_SA_DQ<17>")
	)
	(segment
		(start 382.064006 -266.614148)
		(end 382.058164 -266.61745)
		(width 0.088646)
		(layer "In4.Cu")
		(net "M_G_CPU0_SA_DQ<17>")
	)
	(segment
		(start 378.598938 -266.574524)
		(end 378.016516 -266.128246)
		(width 0.088646)
		(layer "In4.Cu")
		(net "M_G_CPU0_SA_DQ<17>")
	)
	(segment
		(start 411.60319 -291.025326)
		(end 410.897578 -290.319714)
		(width 0.18288)
		(layer "In4.Cu")
		(net "M_G_CPU0_SA_DQ<17>")
	)
	(segment
		(start 429.13173 -294.89019)
		(end 428.94885 -295.07307)
		(width 0.18288)
		(layer "In4.Cu")
		(net "M_G_CPU0_SA_DQ<17>")
	)
	(segment
		(start 392.055096 -270.034512)
		(end 390.961626 -269.58163)
		(width 0.18288)
		(layer "In4.Cu")
		(net "M_G_CPU0_SA_DQ<17>")
	)
	(segment
		(start 425.935394 -296.54119)
		(end 425.28744 -296.54119)
		(width 0.18288)
		(layer "In4.Cu")
		(net "M_G_CPU0_SA_DQ<17>")
	)
	(segment
		(start 383.937764 -266.617704)
		(end 383.937764 -266.61745)
		(width 0.088646)
		(layer "In4.Cu")
		(net "M_G_CPU0_SA_DQ<17>")
	)
	(segment
		(start 386.605272 -266.592812)
		(end 385.912106 -266.592812)
		(width 0.088646)
		(layer "In4.Cu")
		(net "M_G_CPU0_SA_DQ<17>")
	)
	(segment
		(start 387.909562 -266.592812)
		(end 386.605272 -266.592812)
		(width 0.18288)
		(layer "In4.Cu")
		(net "M_G_CPU0_SA_DQ<17>")
	)
	(segment
		(start 378.673614 -266.61745)
		(end 378.598938 -266.574524)
		(width 0.088646)
		(layer "In4.Cu")
		(net "M_G_CPU0_SA_DQ<17>")
	)
	(arc
		(start 383.372614 -266.61745)
		(mid 383.187777 -266.567189)
		(end 383.002282 -266.61491)
		(width 0.088646)
		(layer "In4.Cu")
		(net "M_G_CPU0_SA_DQ<17>")
	)
	(arc
		(start 385.25196 -266.617704)
		(mid 385.064762 -266.567527)
		(end 384.877564 -266.617704)
		(width 0.088646)
		(layer "In4.Cu")
		(net "M_G_CPU0_SA_DQ<17>")
	)
	(arc
		(start 379.232922 -266.621006)
		(mid 378.952787 -266.693322)
		(end 378.673614 -266.61745)
		(width 0.088646)
		(layer "In4.Cu")
		(net "M_G_CPU0_SA_DQ<17>")
	)
	(arc
		(start 382.432814 -266.61745)
		(mid 382.24886 -266.567321)
		(end 382.064006 -266.614148)
		(width 0.088646)
		(layer "In4.Cu")
		(net "M_G_CPU0_SA_DQ<17>")
	)
	(arc
		(start 382.052322 -266.621006)
		(mid 381.772187 -266.693322)
		(end 381.493014 -266.61745)
		(width 0.088646)
		(layer "In4.Cu")
		(net "M_G_CPU0_SA_DQ<17>")
	)
	(arc
		(start 381.112522 -266.621006)
		(mid 380.832387 -266.693322)
		(end 380.553214 -266.61745)
		(width 0.088646)
		(layer "In4.Cu")
		(net "M_G_CPU0_SA_DQ<17>")
	)
	(arc
		(start 380.172722 -266.621006)
		(mid 379.892587 -266.693322)
		(end 379.613414 -266.61745)
		(width 0.088646)
		(layer "In4.Cu")
		(net "M_G_CPU0_SA_DQ<17>")
	)
	(arc
		(start 384.877564 -266.617704)
		(mid 384.594862 -266.69348)
		(end 384.31216 -266.617704)
		(width 0.088646)
		(layer "In4.Cu")
		(net "M_G_CPU0_SA_DQ<17>")
	)
	(arc
		(start 384.31216 -266.617704)
		(mid 384.124962 -266.567527)
		(end 383.937764 -266.617704)
		(width 0.088646)
		(layer "In4.Cu")
		(net "M_G_CPU0_SA_DQ<17>")
	)
	(arc
		(start 379.613414 -266.61745)
		(mid 379.42946 -266.567321)
		(end 379.244606 -266.614148)
		(width 0.088646)
		(layer "In4.Cu")
		(net "M_G_CPU0_SA_DQ<17>")
	)
	(arc
		(start 382.992122 -266.621006)
		(mid 382.711987 -266.693322)
		(end 382.432814 -266.61745)
		(width 0.088646)
		(layer "In4.Cu")
		(net "M_G_CPU0_SA_DQ<17>")
	)
	(arc
		(start 381.493014 -266.61745)
		(mid 381.30906 -266.567321)
		(end 381.124206 -266.614148)
		(width 0.088646)
		(layer "In4.Cu")
		(net "M_G_CPU0_SA_DQ<17>")
	)
	(arc
		(start 385.69773 -266.66952)
		(mid 385.469471 -266.689779)
		(end 385.25196 -266.617704)
		(width 0.088646)
		(layer "In4.Cu")
		(net "M_G_CPU0_SA_DQ<17>")
	)
	(arc
		(start 380.553214 -266.61745)
		(mid 380.36926 -266.567321)
		(end 380.184406 -266.614148)
		(width 0.088646)
		(layer "In4.Cu")
		(net "M_G_CPU0_SA_DQ<17>")
	)
	(arc
		(start 383.937764 -266.61745)
		(mid 383.655206 -266.693099)
		(end 383.372614 -266.61745)
		(width 0.088646)
		(layer "In4.Cu")
		(net "M_G_CPU0_SA_DQ<17>")
	)
	(segment
		(start 378.486162 -266.405868)
		(end 378.486162 -266.941554)
		(width 0.20066)
		(layer "F.Cu")
		(net "M_G_CPU0_SA_DQ<16>")
	)
	(segment
		(start 442.880496 -297.61688)
		(end 442.44895 -297.185334)
		(width 0.20066)
		(layer "F.Cu")
		(net "M_G_CPU0_SA_DQ<16>")
	)
	(segment
		(start 444.472314 -297.616626)
		(end 444.47206 -297.61688)
		(width 0.20066)
		(layer "F.Cu")
		(net "M_G_CPU0_SA_DQ<16>")
	)
	(segment
		(start 439.87085 -297.191684)
		(end 439.82386 -297.191684)
		(width 0.101854)
		(layer "F.Cu")
		(net "M_G_CPU0_SA_DQ<16>")
	)
	(segment
		(start 439.173112 -297.865292)
		(end 438.697878 -297.865292)
		(width 0.20066)
		(layer "F.Cu")
		(net "M_G_CPU0_SA_DQ<16>")
	)
	(segment
		(start 439.82386 -297.191684)
		(end 439.479182 -297.191684)
		(width 0.20066)
		(layer "F.Cu")
		(net "M_G_CPU0_SA_DQ<16>")
	)
	(segment
		(start 438.697878 -297.865292)
		(end 438.449212 -297.616626)
		(width 0.20066)
		(layer "F.Cu")
		(net "M_G_CPU0_SA_DQ<16>")
	)
	(segment
		(start 436.928514 -297.616626)
		(end 435.823614 -297.616626)
		(width 0.20066)
		(layer "F.Cu")
		(net "M_G_CPU0_SA_DQ<16>")
	)
	(segment
		(start 439.361072 -297.309794)
		(end 439.361072 -297.677332)
		(width 0.20066)
		(layer "F.Cu")
		(net "M_G_CPU0_SA_DQ<16>")
	)
	(segment
		(start 442.032644 -297.191684)
		(end 439.87085 -297.191684)
		(width 0.1016)
		(layer "F.Cu")
		(net "M_G_CPU0_SA_DQ<16>")
	)
	(segment
		(start 438.449212 -297.616626)
		(end 436.928514 -297.616626)
		(width 0.20066)
		(layer "F.Cu")
		(net "M_G_CPU0_SA_DQ<16>")
	)
	(segment
		(start 444.47206 -297.61688)
		(end 442.880496 -297.61688)
		(width 0.20066)
		(layer "F.Cu")
		(net "M_G_CPU0_SA_DQ<16>")
	)
	(segment
		(start 442.44895 -297.185334)
		(end 442.038994 -297.185334)
		(width 0.20066)
		(layer "F.Cu")
		(net "M_G_CPU0_SA_DQ<16>")
	)
	(segment
		(start 439.479182 -297.191684)
		(end 439.361072 -297.309794)
		(width 0.20066)
		(layer "F.Cu")
		(net "M_G_CPU0_SA_DQ<16>")
	)
	(segment
		(start 439.361072 -297.677332)
		(end 439.173112 -297.865292)
		(width 0.20066)
		(layer "F.Cu")
		(net "M_G_CPU0_SA_DQ<16>")
	)
	(segment
		(start 378.486162 -266.941554)
		(end 378.486416 -266.941808)
		(width 0.20066)
		(layer "F.Cu")
		(net "M_G_CPU0_SA_DQ<16>")
	)
	(segment
		(start 442.038994 -297.185334)
		(end 442.032644 -297.191684)
		(width 0.1016)
		(layer "F.Cu")
		(net "M_G_CPU0_SA_DQ<16>")
	)
	(segment
		(start 399.94586 -277.965662)
		(end 393.08786 -271.107662)
		(width 0.18288)
		(layer "In4.Cu")
		(net "M_G_CPU0_SA_DQ<16>")
	)
	(segment
		(start 404.032212 -286.252666)
		(end 403.128734 -285.649162)
		(width 0.18288)
		(layer "In4.Cu")
		(net "M_G_CPU0_SA_DQ<16>")
	)
	(segment
		(start 387.5786 -267.28293)
		(end 387.46938 -267.28293)
		(width 0.18288)
		(layer "In4.Cu")
		(net "M_G_CPU0_SA_DQ<16>")
	)
	(segment
		(start 406.15489 -288.18713)
		(end 405.412448 -288.18713)
		(width 0.18288)
		(layer "In4.Cu")
		(net "M_G_CPU0_SA_DQ<16>")
	)
	(segment
		(start 409.980384 -291.186616)
		(end 409.586176 -291.186616)
		(width 0.18288)
		(layer "In4.Cu")
		(net "M_G_CPU0_SA_DQ<16>")
	)
	(segment
		(start 429.837596 -297.36669)
		(end 429.677576 -297.52671)
		(width 0.18288)
		(layer "In4.Cu")
		(net "M_G_CPU0_SA_DQ<16>")
	)
	(segment
		(start 391.93597 -271.107662)
		(end 391.314686 -270.85036)
		(width 0.18288)
		(layer "In4.Cu")
		(net "M_G_CPU0_SA_DQ<16>")
	)
	(segment
		(start 433.847748 -298.096432)
		(end 433.847748 -297.645836)
		(width 0.18288)
		(layer "In4.Cu")
		(net "M_G_CPU0_SA_DQ<16>")
	)
	(segment
		(start 432.894232 -298.256452)
		(end 431.163476 -298.256452)
		(width 0.18288)
		(layer "In4.Cu")
		(net "M_G_CPU0_SA_DQ<16>")
	)
	(segment
		(start 434.007768 -298.256452)
		(end 433.847748 -298.096432)
		(width 0.18288)
		(layer "In4.Cu")
		(net "M_G_CPU0_SA_DQ<16>")
	)
	(segment
		(start 416.768026 -296.262806)
		(end 415.384742 -295.689782)
		(width 0.18288)
		(layer "In4.Cu")
		(net "M_G_CPU0_SA_DQ<16>")
	)
	(segment
		(start 433.227226 -297.485816)
		(end 433.054252 -297.65879)
		(width 0.18288)
		(layer "In4.Cu")
		(net "M_G_CPU0_SA_DQ<16>")
	)
	(segment
		(start 421.863012 -298.042584)
		(end 421.015922 -298.889674)
		(width 0.18288)
		(layer "In4.Cu")
		(net "M_G_CPU0_SA_DQ<16>")
	)
	(segment
		(start 381.97028 -267.435584)
		(end 381.962914 -267.431266)
		(width 0.088646)
		(layer "In4.Cu")
		(net "M_G_CPU0_SA_DQ<16>")
	)
	(segment
		(start 427.3169 -298.042584)
		(end 421.863012 -298.042584)
		(width 0.18288)
		(layer "In4.Cu")
		(net "M_G_CPU0_SA_DQ<16>")
	)
	(segment
		(start 378.79909 -266.941808)
		(end 378.486416 -266.941808)
		(width 0.088646)
		(layer "In4.Cu")
		(net "M_G_CPU0_SA_DQ<16>")
	)
	(segment
		(start 384.407664 -267.43152)
		(end 384.407664 -267.431266)
		(width 0.088646)
		(layer "In4.Cu")
		(net "M_G_CPU0_SA_DQ<16>")
	)
	(segment
		(start 419.747954 -298.141136)
		(end 418.646356 -298.141136)
		(width 0.18288)
		(layer "In4.Cu")
		(net "M_G_CPU0_SA_DQ<16>")
	)
	(segment
		(start 381.03048 -267.435584)
		(end 381.023114 -267.431266)
		(width 0.088646)
		(layer "In4.Cu")
		(net "M_G_CPU0_SA_DQ<16>")
	)
	(segment
		(start 378.864622 -267.007594)
		(end 378.79909 -266.941808)
		(width 0.088646)
		(layer "In4.Cu")
		(net "M_G_CPU0_SA_DQ<16>")
	)
	(segment
		(start 435.823614 -297.616626)
		(end 435.183788 -298.256452)
		(width 0.18288)
		(layer "In4.Cu")
		(net "M_G_CPU0_SA_DQ<16>")
	)
	(segment
		(start 414.963356 -295.268396)
		(end 414.664398 -294.546782)
		(width 0.18288)
		(layer "In4.Cu")
		(net "M_G_CPU0_SA_DQ<16>")
	)
	(segment
		(start 428.966122 -298.16044)
		(end 428.966122 -297.538394)
		(width 0.18288)
		(layer "In4.Cu")
		(net "M_G_CPU0_SA_DQ<16>")
	)
	(segment
		(start 405.412448 -288.18713)
		(end 404.957026 -287.731708)
		(width 0.18288)
		(layer "In4.Cu")
		(net "M_G_CPU0_SA_DQ<16>")
	)
	(segment
		(start 408.18435 -289.78479)
		(end 407.75255 -289.78479)
		(width 0.18288)
		(layer "In4.Cu")
		(net "M_G_CPU0_SA_DQ<16>")
	)
	(segment
		(start 429.677576 -297.52671)
		(end 429.677576 -298.223686)
		(width 0.18288)
		(layer "In4.Cu")
		(net "M_G_CPU0_SA_DQ<16>")
	)
	(segment
		(start 431.163476 -298.256452)
		(end 430.273714 -297.36669)
		(width 0.18288)
		(layer "In4.Cu")
		(net "M_G_CPU0_SA_DQ<16>")
	)
	(segment
		(start 421.015922 -298.889674)
		(end 420.496492 -298.889674)
		(width 0.18288)
		(layer "In4.Cu")
		(net "M_G_CPU0_SA_DQ<16>")
	)
	(segment
		(start 382.907286 -267.43406)
		(end 382.902714 -267.431266)
		(width 0.088646)
		(layer "In4.Cu")
		(net "M_G_CPU0_SA_DQ<16>")
	)
	(segment
		(start 429.179482 -298.3738)
		(end 428.966122 -298.16044)
		(width 0.18288)
		(layer "In4.Cu")
		(net "M_G_CPU0_SA_DQ<16>")
	)
	(segment
		(start 412.320994 -293.527226)
		(end 409.980384 -291.186616)
		(width 0.18288)
		(layer "In4.Cu")
		(net "M_G_CPU0_SA_DQ<16>")
	)
	(segment
		(start 391.02665 -270.73098)
		(end 387.5786 -267.28293)
		(width 0.18288)
		(layer "In4.Cu")
		(net "M_G_CPU0_SA_DQ<16>")
	)
	(segment
		(start 433.054252 -298.096432)
		(end 432.894232 -298.256452)
		(width 0.18288)
		(layer "In4.Cu")
		(net "M_G_CPU0_SA_DQ<16>")
	)
	(segment
		(start 415.384742 -295.689782)
		(end 414.963356 -295.268396)
		(width 0.18288)
		(layer "In4.Cu")
		(net "M_G_CPU0_SA_DQ<16>")
	)
	(segment
		(start 433.687728 -297.485816)
		(end 433.227226 -297.485816)
		(width 0.18288)
		(layer "In4.Cu")
		(net "M_G_CPU0_SA_DQ<16>")
	)
	(segment
		(start 418.646356 -298.141136)
		(end 416.768026 -296.262806)
		(width 0.18288)
		(layer "In4.Cu")
		(net "M_G_CPU0_SA_DQ<16>")
	)
	(segment
		(start 385.496308 -267.28293)
		(end 385.352544 -267.426694)
		(width 0.088646)
		(layer "In4.Cu")
		(net "M_G_CPU0_SA_DQ<16>")
	)
	(segment
		(start 391.314686 -270.85036)
		(end 391.02665 -270.73098)
		(width 0.18288)
		(layer "In4.Cu")
		(net "M_G_CPU0_SA_DQ<16>")
	)
	(segment
		(start 428.966122 -297.538394)
		(end 428.806102 -297.378374)
		(width 0.18288)
		(layer "In4.Cu")
		(net "M_G_CPU0_SA_DQ<16>")
	)
	(segment
		(start 393.08786 -271.107662)
		(end 391.93597 -271.107662)
		(width 0.18288)
		(layer "In4.Cu")
		(net "M_G_CPU0_SA_DQ<16>")
	)
	(segment
		(start 404.957026 -287.731708)
		(end 404.957026 -287.17748)
		(width 0.18288)
		(layer "In4.Cu")
		(net "M_G_CPU0_SA_DQ<16>")
	)
	(segment
		(start 428.806102 -297.378374)
		(end 427.98111 -297.378374)
		(width 0.18288)
		(layer "In4.Cu")
		(net "M_G_CPU0_SA_DQ<16>")
	)
	(segment
		(start 381.023114 -267.431266)
		(end 381.018542 -267.428726)
		(width 0.088646)
		(layer "In4.Cu")
		(net "M_G_CPU0_SA_DQ<16>")
	)
	(segment
		(start 379.15088 -267.435584)
		(end 379.143514 -267.431266)
		(width 0.088646)
		(layer "In4.Cu")
		(net "M_G_CPU0_SA_DQ<16>")
	)
	(segment
		(start 385.352544 -267.426694)
		(end 385.347464 -267.43152)
		(width 0.088646)
		(layer "In4.Cu")
		(net "M_G_CPU0_SA_DQ<16>")
	)
	(segment
		(start 433.847748 -297.645836)
		(end 433.687728 -297.485816)
		(width 0.18288)
		(layer "In4.Cu")
		(net "M_G_CPU0_SA_DQ<16>")
	)
	(segment
		(start 379.143514 -267.431266)
		(end 379.141482 -267.43025)
		(width 0.088646)
		(layer "In4.Cu")
		(net "M_G_CPU0_SA_DQ<16>")
	)
	(segment
		(start 403.128734 -285.649162)
		(end 399.94586 -277.965662)
		(width 0.18288)
		(layer "In4.Cu")
		(net "M_G_CPU0_SA_DQ<16>")
	)
	(segment
		(start 381.962914 -267.431266)
		(end 381.958342 -267.428726)
		(width 0.088646)
		(layer "In4.Cu")
		(net "M_G_CPU0_SA_DQ<16>")
	)
	(segment
		(start 433.054252 -297.65879)
		(end 433.054252 -298.096432)
		(width 0.18288)
		(layer "In4.Cu")
		(net "M_G_CPU0_SA_DQ<16>")
	)
	(segment
		(start 427.98111 -297.378374)
		(end 427.3169 -298.042584)
		(width 0.18288)
		(layer "In4.Cu")
		(net "M_G_CPU0_SA_DQ<16>")
	)
	(segment
		(start 380.09068 -267.435584)
		(end 380.083314 -267.431266)
		(width 0.088646)
		(layer "In4.Cu")
		(net "M_G_CPU0_SA_DQ<16>")
	)
	(segment
		(start 430.273714 -297.36669)
		(end 429.837596 -297.36669)
		(width 0.18288)
		(layer "In4.Cu")
		(net "M_G_CPU0_SA_DQ<16>")
	)
	(segment
		(start 387.46938 -267.28293)
		(end 385.496308 -267.28293)
		(width 0.088646)
		(layer "In4.Cu")
		(net "M_G_CPU0_SA_DQ<16>")
	)
	(segment
		(start 380.083314 -267.431266)
		(end 380.078742 -267.428726)
		(width 0.088646)
		(layer "In4.Cu")
		(net "M_G_CPU0_SA_DQ<16>")
	)
	(segment
		(start 409.586176 -291.186616)
		(end 408.18435 -289.78479)
		(width 0.18288)
		(layer "In4.Cu")
		(net "M_G_CPU0_SA_DQ<16>")
	)
	(segment
		(start 413.644842 -293.527226)
		(end 412.320994 -293.527226)
		(width 0.18288)
		(layer "In4.Cu")
		(net "M_G_CPU0_SA_DQ<16>")
	)
	(segment
		(start 429.527462 -298.3738)
		(end 429.179482 -298.3738)
		(width 0.18288)
		(layer "In4.Cu")
		(net "M_G_CPU0_SA_DQ<16>")
	)
	(segment
		(start 407.75255 -289.78479)
		(end 406.15489 -288.18713)
		(width 0.18288)
		(layer "In4.Cu")
		(net "M_G_CPU0_SA_DQ<16>")
	)
	(segment
		(start 420.496492 -298.889674)
		(end 419.747954 -298.141136)
		(width 0.18288)
		(layer "In4.Cu")
		(net "M_G_CPU0_SA_DQ<16>")
	)
	(segment
		(start 382.902714 -267.431266)
		(end 382.898142 -267.428726)
		(width 0.088646)
		(layer "In4.Cu")
		(net "M_G_CPU0_SA_DQ<16>")
	)
	(segment
		(start 383.848102 -267.434568)
		(end 383.842514 -267.431266)
		(width 0.088646)
		(layer "In4.Cu")
		(net "M_G_CPU0_SA_DQ<16>")
	)
	(segment
		(start 435.183788 -298.256452)
		(end 434.007768 -298.256452)
		(width 0.18288)
		(layer "In4.Cu")
		(net "M_G_CPU0_SA_DQ<16>")
	)
	(segment
		(start 429.677576 -298.223686)
		(end 429.527462 -298.3738)
		(width 0.18288)
		(layer "In4.Cu")
		(net "M_G_CPU0_SA_DQ<16>")
	)
	(segment
		(start 404.957026 -287.17748)
		(end 404.032212 -286.252666)
		(width 0.18288)
		(layer "In4.Cu")
		(net "M_G_CPU0_SA_DQ<16>")
	)
	(segment
		(start 414.664398 -294.546782)
		(end 413.644842 -293.527226)
		(width 0.18288)
		(layer "In4.Cu")
		(net "M_G_CPU0_SA_DQ<16>")
	)
	(arc
		(start 382.898142 -267.428726)
		(mid 382.712757 -267.381088)
		(end 382.528064 -267.431266)
		(width 0.088646)
		(layer "In4.Cu")
		(net "M_G_CPU0_SA_DQ<16>")
	)
	(arc
		(start 383.467864 -267.431266)
		(mid 383.18795 -267.507035)
		(end 382.907286 -267.43406)
		(width 0.088646)
		(layer "In4.Cu")
		(net "M_G_CPU0_SA_DQ<16>")
	)
	(arc
		(start 382.528064 -267.431266)
		(mid 382.249741 -267.507025)
		(end 381.97028 -267.435584)
		(width 0.088646)
		(layer "In4.Cu")
		(net "M_G_CPU0_SA_DQ<16>")
	)
	(arc
		(start 383.842514 -267.431266)
		(mid 383.655206 -267.381157)
		(end 383.467864 -267.431266)
		(width 0.088646)
		(layer "In4.Cu")
		(net "M_G_CPU0_SA_DQ<16>")
	)
	(arc
		(start 381.958342 -267.428726)
		(mid 381.772957 -267.381088)
		(end 381.588264 -267.431266)
		(width 0.088646)
		(layer "In4.Cu")
		(net "M_G_CPU0_SA_DQ<16>")
	)
	(arc
		(start 379.141482 -267.43025)
		(mid 378.953164 -267.251592)
		(end 378.864622 -267.007594)
		(width 0.088646)
		(layer "In4.Cu")
		(net "M_G_CPU0_SA_DQ<16>")
	)
	(arc
		(start 380.078742 -267.428726)
		(mid 379.893357 -267.381088)
		(end 379.708664 -267.431266)
		(width 0.088646)
		(layer "In4.Cu")
		(net "M_G_CPU0_SA_DQ<16>")
	)
	(arc
		(start 384.78206 -267.43152)
		(mid 384.594862 -267.381377)
		(end 384.407664 -267.43152)
		(width 0.088646)
		(layer "In4.Cu")
		(net "M_G_CPU0_SA_DQ<16>")
	)
	(arc
		(start 379.708664 -267.431266)
		(mid 379.430341 -267.507025)
		(end 379.15088 -267.435584)
		(width 0.088646)
		(layer "In4.Cu")
		(net "M_G_CPU0_SA_DQ<16>")
	)
	(arc
		(start 384.407664 -267.431266)
		(mid 384.128317 -267.507032)
		(end 383.848102 -267.434568)
		(width 0.088646)
		(layer "In4.Cu")
		(net "M_G_CPU0_SA_DQ<16>")
	)
	(arc
		(start 381.588264 -267.431266)
		(mid 381.309941 -267.507025)
		(end 381.03048 -267.435584)
		(width 0.088646)
		(layer "In4.Cu")
		(net "M_G_CPU0_SA_DQ<16>")
	)
	(arc
		(start 380.648464 -267.431266)
		(mid 380.370141 -267.507025)
		(end 380.09068 -267.435584)
		(width 0.088646)
		(layer "In4.Cu")
		(net "M_G_CPU0_SA_DQ<16>")
	)
	(arc
		(start 385.347464 -267.43152)
		(mid 385.064762 -267.507262)
		(end 384.78206 -267.43152)
		(width 0.088646)
		(layer "In4.Cu")
		(net "M_G_CPU0_SA_DQ<16>")
	)
	(arc
		(start 381.018542 -267.428726)
		(mid 380.833157 -267.381088)
		(end 380.648464 -267.431266)
		(width 0.088646)
		(layer "In4.Cu")
		(net "M_G_CPU0_SA_DQ<16>")
	)
	(segment
		(start 446.986152 -298.214796)
		(end 447.23812 -298.466764)
		(width 0.20066)
		(layer "F.Cu")
		(net "M_G_CPU0_SA_DQ<15>")
	)
	(segment
		(start 442.726826 -298.466764)
		(end 443.15888 -298.898818)
		(width 0.20066)
		(layer "F.Cu")
		(net "M_G_CPU0_SA_DQ<15>")
	)
	(segment
		(start 446.367916 -298.699936)
		(end 446.367916 -298.448984)
		(width 0.20066)
		(layer "F.Cu")
		(net "M_G_CPU0_SA_DQ<15>")
	)
	(segment
		(start 446.602104 -298.214796)
		(end 446.986152 -298.214796)
		(width 0.20066)
		(layer "F.Cu")
		(net "M_G_CPU0_SA_DQ<15>")
	)
	(segment
		(start 443.455552 -298.898818)
		(end 443.462664 -298.891706)
		(width 0.1016)
		(layer "F.Cu")
		(net "M_G_CPU0_SA_DQ<15>")
	)
	(segment
		(start 439.923682 -298.466764)
		(end 441.028582 -298.466764)
		(width 0.20066)
		(layer "F.Cu")
		(net "M_G_CPU0_SA_DQ<15>")
	)
	(segment
		(start 443.462664 -298.891706)
		(end 445.470534 -298.891706)
		(width 0.1016)
		(layer "F.Cu")
		(net "M_G_CPU0_SA_DQ<15>")
	)
	(segment
		(start 446.367916 -298.448984)
		(end 446.602104 -298.214796)
		(width 0.20066)
		(layer "F.Cu")
		(net "M_G_CPU0_SA_DQ<15>")
	)
	(segment
		(start 376.136916 -270.475456)
		(end 376.136916 -271.011142)
		(width 0.20066)
		(layer "F.Cu")
		(net "M_G_CPU0_SA_DQ<15>")
	)
	(segment
		(start 445.482726 -298.903898)
		(end 446.163954 -298.903898)
		(width 0.20066)
		(layer "F.Cu")
		(net "M_G_CPU0_SA_DQ<15>")
	)
	(segment
		(start 443.15888 -298.898818)
		(end 443.450726 -298.898818)
		(width 0.20066)
		(layer "F.Cu")
		(net "M_G_CPU0_SA_DQ<15>")
	)
	(segment
		(start 446.163954 -298.903898)
		(end 446.367916 -298.699936)
		(width 0.20066)
		(layer "F.Cu")
		(net "M_G_CPU0_SA_DQ<15>")
	)
	(segment
		(start 376.136916 -271.011142)
		(end 376.136662 -271.011396)
		(width 0.20066)
		(layer "F.Cu")
		(net "M_G_CPU0_SA_DQ<15>")
	)
	(segment
		(start 445.470534 -298.891706)
		(end 445.482726 -298.903898)
		(width 0.1016)
		(layer "F.Cu")
		(net "M_G_CPU0_SA_DQ<15>")
	)
	(segment
		(start 443.450726 -298.898818)
		(end 443.455552 -298.898818)
		(width 0.101854)
		(layer "F.Cu")
		(net "M_G_CPU0_SA_DQ<15>")
	)
	(segment
		(start 441.028582 -298.466764)
		(end 442.726826 -298.466764)
		(width 0.20066)
		(layer "F.Cu")
		(net "M_G_CPU0_SA_DQ<15>")
	)
	(segment
		(start 447.23812 -298.466764)
		(end 448.572382 -298.466764)
		(width 0.20066)
		(layer "F.Cu")
		(net "M_G_CPU0_SA_DQ<15>")
	)
	(segment
		(start 416.842194 -290.555426)
		(end 415.978594 -289.691826)
		(width 0.18288)
		(layer "In6.Cu")
		(net "M_G_CPU0_SA_DQ<15>")
	)
	(segment
		(start 421.073326 -290.392358)
		(end 420.421562 -290.392358)
		(width 0.18288)
		(layer "In6.Cu")
		(net "M_G_CPU0_SA_DQ<15>")
	)
	(segment
		(start 381.503174 -270.515842)
		(end 381.49276 -270.521938)
		(width 0.088646)
		(layer "In6.Cu")
		(net "M_G_CPU0_SA_DQ<15>")
	)
	(segment
		(start 383.387346 -270.513302)
		(end 383.372614 -270.521938)
		(width 0.088646)
		(layer "In6.Cu")
		(net "M_G_CPU0_SA_DQ<15>")
	)
	(segment
		(start 382.447546 -270.513302)
		(end 382.432814 -270.521938)
		(width 0.088646)
		(layer "In6.Cu")
		(net "M_G_CPU0_SA_DQ<15>")
	)
	(segment
		(start 415.978594 -289.691826)
		(end 414.487106 -289.691826)
		(width 0.18288)
		(layer "In6.Cu")
		(net "M_G_CPU0_SA_DQ<15>")
	)
	(segment
		(start 412.594806 -289.009328)
		(end 409.427934 -289.009328)
		(width 0.18288)
		(layer "In6.Cu")
		(net "M_G_CPU0_SA_DQ<15>")
	)
	(segment
		(start 387.776212 -270.883634)
		(end 387.308598 -270.883634)
		(width 0.088646)
		(layer "In6.Cu")
		(net "M_G_CPU0_SA_DQ<15>")
	)
	(segment
		(start 439.923682 -298.466764)
		(end 439.498232 -298.892214)
		(width 0.18288)
		(layer "In6.Cu")
		(net "M_G_CPU0_SA_DQ<15>")
	)
	(segment
		(start 387.308598 -270.883634)
		(end 386.87121 -270.446246)
		(width 0.088646)
		(layer "In6.Cu")
		(net "M_G_CPU0_SA_DQ<15>")
	)
	(segment
		(start 433.809394 -296.651426)
		(end 432.412394 -295.254426)
		(width 0.18288)
		(layer "In6.Cu")
		(net "M_G_CPU0_SA_DQ<15>")
	)
	(segment
		(start 413.452056 -288.656776)
		(end 412.947358 -288.656776)
		(width 0.18288)
		(layer "In6.Cu")
		(net "M_G_CPU0_SA_DQ<15>")
	)
	(segment
		(start 385.266946 -270.513302)
		(end 385.252214 -270.521938)
		(width 0.088646)
		(layer "In6.Cu")
		(net "M_G_CPU0_SA_DQ<15>")
	)
	(segment
		(start 375.949464 -271.335754)
		(end 375.940574 -271.330674)
		(width 0.088646)
		(layer "In6.Cu")
		(net "M_G_CPU0_SA_DQ<15>")
	)
	(segment
		(start 430.481994 -294.263826)
		(end 429.008794 -294.263826)
		(width 0.18288)
		(layer "In6.Cu")
		(net "M_G_CPU0_SA_DQ<15>")
	)
	(segment
		(start 408.464512 -288.045906)
		(end 405.66975 -288.045906)
		(width 0.18288)
		(layer "In6.Cu")
		(net "M_G_CPU0_SA_DQ<15>")
	)
	(segment
		(start 375.766584 -271.0688)
		(end 375.823988 -271.011396)
		(width 0.088646)
		(layer "In6.Cu")
		(net "M_G_CPU0_SA_DQ<15>")
	)
	(segment
		(start 377.748546 -270.513302)
		(end 377.733814 -270.521938)
		(width 0.088646)
		(layer "In6.Cu")
		(net "M_G_CPU0_SA_DQ<15>")
	)
	(segment
		(start 420.421562 -290.392358)
		(end 420.258494 -290.555426)
		(width 0.18288)
		(layer "In6.Cu")
		(net "M_G_CPU0_SA_DQ<15>")
	)
	(segment
		(start 376.33275 -271.330674)
		(end 376.32386 -271.335754)
		(width 0.088646)
		(layer "In6.Cu")
		(net "M_G_CPU0_SA_DQ<15>")
	)
	(segment
		(start 388.535672 -271.53108)
		(end 388.423658 -271.53108)
		(width 0.088646)
		(layer "In6.Cu")
		(net "M_G_CPU0_SA_DQ<15>")
	)
	(segment
		(start 427.129194 -293.019226)
		(end 425.35221 -291.242242)
		(width 0.18288)
		(layer "In6.Cu")
		(net "M_G_CPU0_SA_DQ<15>")
	)
	(segment
		(start 375.823988 -271.011396)
		(end 376.136662 -271.011396)
		(width 0.088646)
		(layer "In6.Cu")
		(net "M_G_CPU0_SA_DQ<15>")
	)
	(segment
		(start 386.87121 -270.446246)
		(end 386.474462 -270.446246)
		(width 0.088646)
		(layer "In6.Cu")
		(net "M_G_CPU0_SA_DQ<15>")
	)
	(segment
		(start 397.083788 -271.953736)
		(end 390.604502 -271.953736)
		(width 0.18288)
		(layer "In6.Cu")
		(net "M_G_CPU0_SA_DQ<15>")
	)
	(segment
		(start 384.327146 -270.513302)
		(end 384.312414 -270.521938)
		(width 0.088646)
		(layer "In6.Cu")
		(net "M_G_CPU0_SA_DQ<15>")
	)
	(segment
		(start 427.764194 -293.019226)
		(end 427.129194 -293.019226)
		(width 0.18288)
		(layer "In6.Cu")
		(net "M_G_CPU0_SA_DQ<15>")
	)
	(segment
		(start 376.794014 -270.521938)
		(end 376.787918 -270.525494)
		(width 0.088646)
		(layer "In6.Cu")
		(net "M_G_CPU0_SA_DQ<15>")
	)
	(segment
		(start 405.66975 -288.045906)
		(end 404.94839 -287.324546)
		(width 0.18288)
		(layer "In6.Cu")
		(net "M_G_CPU0_SA_DQ<15>")
	)
	(segment
		(start 404.94839 -287.324546)
		(end 404.94839 -279.818338)
		(width 0.18288)
		(layer "In6.Cu")
		(net "M_G_CPU0_SA_DQ<15>")
	)
	(segment
		(start 425.35221 -291.242242)
		(end 424.607736 -291.242242)
		(width 0.18288)
		(layer "In6.Cu")
		(net "M_G_CPU0_SA_DQ<15>")
	)
	(segment
		(start 434.21427 -298.10329)
		(end 433.809394 -297.698414)
		(width 0.18288)
		(layer "In6.Cu")
		(net "M_G_CPU0_SA_DQ<15>")
	)
	(segment
		(start 429.008794 -294.263826)
		(end 427.764194 -293.019226)
		(width 0.18288)
		(layer "In6.Cu")
		(net "M_G_CPU0_SA_DQ<15>")
	)
	(segment
		(start 412.947358 -288.656776)
		(end 412.594806 -289.009328)
		(width 0.18288)
		(layer "In6.Cu")
		(net "M_G_CPU0_SA_DQ<15>")
	)
	(segment
		(start 431.472594 -295.254426)
		(end 430.481994 -294.263826)
		(width 0.18288)
		(layer "In6.Cu")
		(net "M_G_CPU0_SA_DQ<15>")
	)
	(segment
		(start 433.809394 -297.698414)
		(end 433.809394 -296.651426)
		(width 0.18288)
		(layer "In6.Cu")
		(net "M_G_CPU0_SA_DQ<15>")
	)
	(segment
		(start 434.86197 -298.10329)
		(end 434.21427 -298.10329)
		(width 0.18288)
		(layer "In6.Cu")
		(net "M_G_CPU0_SA_DQ<15>")
	)
	(segment
		(start 409.427934 -289.009328)
		(end 408.464512 -288.045906)
		(width 0.18288)
		(layer "In6.Cu")
		(net "M_G_CPU0_SA_DQ<15>")
	)
	(segment
		(start 376.808746 -270.513302)
		(end 376.794014 -270.521938)
		(width 0.088646)
		(layer "In6.Cu")
		(net "M_G_CPU0_SA_DQ<15>")
	)
	(segment
		(start 424.256708 -291.59327)
		(end 422.274238 -291.59327)
		(width 0.18288)
		(layer "In6.Cu")
		(net "M_G_CPU0_SA_DQ<15>")
	)
	(segment
		(start 378.688346 -270.513302)
		(end 378.673614 -270.521938)
		(width 0.088646)
		(layer "In6.Cu")
		(net "M_G_CPU0_SA_DQ<15>")
	)
	(segment
		(start 404.94839 -279.818338)
		(end 397.083788 -271.953736)
		(width 0.18288)
		(layer "In6.Cu")
		(net "M_G_CPU0_SA_DQ<15>")
	)
	(segment
		(start 388.423658 -271.53108)
		(end 387.776212 -270.883634)
		(width 0.088646)
		(layer "In6.Cu")
		(net "M_G_CPU0_SA_DQ<15>")
	)
	(segment
		(start 432.412394 -295.254426)
		(end 431.472594 -295.254426)
		(width 0.18288)
		(layer "In6.Cu")
		(net "M_G_CPU0_SA_DQ<15>")
	)
	(segment
		(start 389.58393 -271.53108)
		(end 388.535672 -271.53108)
		(width 0.18288)
		(layer "In6.Cu")
		(net "M_G_CPU0_SA_DQ<15>")
	)
	(segment
		(start 439.498232 -298.892214)
		(end 435.650894 -298.892214)
		(width 0.18288)
		(layer "In6.Cu")
		(net "M_G_CPU0_SA_DQ<15>")
	)
	(segment
		(start 424.607736 -291.242242)
		(end 424.256708 -291.59327)
		(width 0.18288)
		(layer "In6.Cu")
		(net "M_G_CPU0_SA_DQ<15>")
	)
	(segment
		(start 390.604502 -271.953736)
		(end 389.58393 -271.53108)
		(width 0.18288)
		(layer "In6.Cu")
		(net "M_G_CPU0_SA_DQ<15>")
	)
	(segment
		(start 435.650894 -298.892214)
		(end 434.86197 -298.10329)
		(width 0.18288)
		(layer "In6.Cu")
		(net "M_G_CPU0_SA_DQ<15>")
	)
	(segment
		(start 380.563628 -270.515842)
		(end 380.553214 -270.521938)
		(width 0.088646)
		(layer "In6.Cu")
		(net "M_G_CPU0_SA_DQ<15>")
	)
	(segment
		(start 420.258494 -290.555426)
		(end 416.842194 -290.555426)
		(width 0.18288)
		(layer "In6.Cu")
		(net "M_G_CPU0_SA_DQ<15>")
	)
	(segment
		(start 379.628146 -270.513302)
		(end 379.613414 -270.521938)
		(width 0.088646)
		(layer "In6.Cu")
		(net "M_G_CPU0_SA_DQ<15>")
	)
	(segment
		(start 414.487106 -289.691826)
		(end 413.452056 -288.656776)
		(width 0.18288)
		(layer "In6.Cu")
		(net "M_G_CPU0_SA_DQ<15>")
	)
	(segment
		(start 422.274238 -291.59327)
		(end 421.073326 -290.392358)
		(width 0.18288)
		(layer "In6.Cu")
		(net "M_G_CPU0_SA_DQ<15>")
	)
	(arc
		(start 380.553214 -270.521938)
		(mid 380.366016 -270.572081)
		(end 380.178818 -270.521938)
		(width 0.088646)
		(layer "In6.Cu")
		(net "M_G_CPU0_SA_DQ<15>")
	)
	(arc
		(start 376.787918 -270.525494)
		(mid 376.585331 -270.731845)
		(end 376.511312 -271.011396)
		(width 0.088646)
		(layer "In6.Cu")
		(net "M_G_CPU0_SA_DQ<15>")
	)
	(arc
		(start 386.474462 -270.446246)
		(mid 386.328254 -270.465495)
		(end 386.192014 -270.521938)
		(width 0.088646)
		(layer "In6.Cu")
		(net "M_G_CPU0_SA_DQ<15>")
	)
	(arc
		(start 376.32386 -271.335754)
		(mid 376.136662 -271.385897)
		(end 375.949464 -271.335754)
		(width 0.088646)
		(layer "In6.Cu")
		(net "M_G_CPU0_SA_DQ<15>")
	)
	(arc
		(start 383.372614 -270.521938)
		(mid 383.185416 -270.572081)
		(end 382.998218 -270.521938)
		(width 0.088646)
		(layer "In6.Cu")
		(net "M_G_CPU0_SA_DQ<15>")
	)
	(arc
		(start 377.359418 -270.521938)
		(mid 377.085219 -270.446103)
		(end 376.808746 -270.513302)
		(width 0.088646)
		(layer "In6.Cu")
		(net "M_G_CPU0_SA_DQ<15>")
	)
	(arc
		(start 377.733814 -270.521938)
		(mid 377.546616 -270.572081)
		(end 377.359418 -270.521938)
		(width 0.088646)
		(layer "In6.Cu")
		(net "M_G_CPU0_SA_DQ<15>")
	)
	(arc
		(start 385.252214 -270.521938)
		(mid 385.065016 -270.572081)
		(end 384.877818 -270.521938)
		(width 0.088646)
		(layer "In6.Cu")
		(net "M_G_CPU0_SA_DQ<15>")
	)
	(arc
		(start 381.49276 -270.521938)
		(mid 381.305562 -270.572081)
		(end 381.118364 -270.521938)
		(width 0.088646)
		(layer "In6.Cu")
		(net "M_G_CPU0_SA_DQ<15>")
	)
	(arc
		(start 383.938018 -270.521938)
		(mid 383.663819 -270.446103)
		(end 383.387346 -270.513302)
		(width 0.088646)
		(layer "In6.Cu")
		(net "M_G_CPU0_SA_DQ<15>")
	)
	(arc
		(start 382.998218 -270.521938)
		(mid 382.724019 -270.446103)
		(end 382.447546 -270.513302)
		(width 0.088646)
		(layer "In6.Cu")
		(net "M_G_CPU0_SA_DQ<15>")
	)
	(arc
		(start 382.432814 -270.521938)
		(mid 382.245616 -270.572081)
		(end 382.058418 -270.521938)
		(width 0.088646)
		(layer "In6.Cu")
		(net "M_G_CPU0_SA_DQ<15>")
	)
	(arc
		(start 384.877818 -270.521938)
		(mid 384.603619 -270.446103)
		(end 384.327146 -270.513302)
		(width 0.088646)
		(layer "In6.Cu")
		(net "M_G_CPU0_SA_DQ<15>")
	)
	(arc
		(start 385.817618 -270.521938)
		(mid 385.543419 -270.446103)
		(end 385.266946 -270.513302)
		(width 0.088646)
		(layer "In6.Cu")
		(net "M_G_CPU0_SA_DQ<15>")
	)
	(arc
		(start 381.118364 -270.521938)
		(mid 380.841805 -270.446195)
		(end 380.563628 -270.515842)
		(width 0.088646)
		(layer "In6.Cu")
		(net "M_G_CPU0_SA_DQ<15>")
	)
	(arc
		(start 379.239018 -270.521938)
		(mid 378.964819 -270.446103)
		(end 378.688346 -270.513302)
		(width 0.088646)
		(layer "In6.Cu")
		(net "M_G_CPU0_SA_DQ<15>")
	)
	(arc
		(start 375.940574 -271.330674)
		(mid 375.824835 -271.21885)
		(end 375.766584 -271.0688)
		(width 0.088646)
		(layer "In6.Cu")
		(net "M_G_CPU0_SA_DQ<15>")
	)
	(arc
		(start 379.613414 -270.521938)
		(mid 379.426216 -270.572081)
		(end 379.239018 -270.521938)
		(width 0.088646)
		(layer "In6.Cu")
		(net "M_G_CPU0_SA_DQ<15>")
	)
	(arc
		(start 376.511312 -271.011396)
		(mid 376.463633 -271.194296)
		(end 376.33275 -271.330674)
		(width 0.088646)
		(layer "In6.Cu")
		(net "M_G_CPU0_SA_DQ<15>")
	)
	(arc
		(start 382.058418 -270.521938)
		(mid 381.781605 -270.446068)
		(end 381.503174 -270.515842)
		(width 0.088646)
		(layer "In6.Cu")
		(net "M_G_CPU0_SA_DQ<15>")
	)
	(arc
		(start 378.299218 -270.521938)
		(mid 378.025019 -270.446103)
		(end 377.748546 -270.513302)
		(width 0.088646)
		(layer "In6.Cu")
		(net "M_G_CPU0_SA_DQ<15>")
	)
	(arc
		(start 380.178818 -270.521938)
		(mid 379.904619 -270.446103)
		(end 379.628146 -270.513302)
		(width 0.088646)
		(layer "In6.Cu")
		(net "M_G_CPU0_SA_DQ<15>")
	)
	(arc
		(start 378.673614 -270.521938)
		(mid 378.486416 -270.572081)
		(end 378.299218 -270.521938)
		(width 0.088646)
		(layer "In6.Cu")
		(net "M_G_CPU0_SA_DQ<15>")
	)
	(arc
		(start 386.192014 -270.521938)
		(mid 386.004816 -270.572081)
		(end 385.817618 -270.521938)
		(width 0.088646)
		(layer "In6.Cu")
		(net "M_G_CPU0_SA_DQ<15>")
	)
	(arc
		(start 384.312414 -270.521938)
		(mid 384.125216 -270.572081)
		(end 383.938018 -270.521938)
		(width 0.088646)
		(layer "In6.Cu")
		(net "M_G_CPU0_SA_DQ<15>")
	)
	(segment
		(start 443.455552 -300.59884)
		(end 443.462664 -300.591728)
		(width 0.1016)
		(layer "F.Cu")
		(net "M_G_CPU0_SA_DQ<14>")
	)
	(segment
		(start 376.606562 -271.289272)
		(end 376.606816 -271.825212)
		(width 0.20066)
		(layer "F.Cu")
		(net "M_G_CPU0_SA_DQ<14>")
	)
	(segment
		(start 447.23812 -300.166786)
		(end 448.572382 -300.166786)
		(width 0.20066)
		(layer "F.Cu")
		(net "M_G_CPU0_SA_DQ<14>")
	)
	(segment
		(start 443.462664 -300.591728)
		(end 445.470534 -300.591728)
		(width 0.1016)
		(layer "F.Cu")
		(net "M_G_CPU0_SA_DQ<14>")
	)
	(segment
		(start 441.028582 -300.166786)
		(end 442.726826 -300.166786)
		(width 0.20066)
		(layer "F.Cu")
		(net "M_G_CPU0_SA_DQ<14>")
	)
	(segment
		(start 443.450726 -300.59884)
		(end 443.455552 -300.59884)
		(width 0.101854)
		(layer "F.Cu")
		(net "M_G_CPU0_SA_DQ<14>")
	)
	(segment
		(start 446.986152 -299.914818)
		(end 447.23812 -300.166786)
		(width 0.20066)
		(layer "F.Cu")
		(net "M_G_CPU0_SA_DQ<14>")
	)
	(segment
		(start 443.15888 -300.59884)
		(end 443.450726 -300.59884)
		(width 0.20066)
		(layer "F.Cu")
		(net "M_G_CPU0_SA_DQ<14>")
	)
	(segment
		(start 446.367916 -300.399958)
		(end 446.367916 -300.149006)
		(width 0.20066)
		(layer "F.Cu")
		(net "M_G_CPU0_SA_DQ<14>")
	)
	(segment
		(start 442.726826 -300.166786)
		(end 443.15888 -300.59884)
		(width 0.20066)
		(layer "F.Cu")
		(net "M_G_CPU0_SA_DQ<14>")
	)
	(segment
		(start 445.482726 -300.60392)
		(end 446.163954 -300.60392)
		(width 0.20066)
		(layer "F.Cu")
		(net "M_G_CPU0_SA_DQ<14>")
	)
	(segment
		(start 446.602104 -299.914818)
		(end 446.986152 -299.914818)
		(width 0.20066)
		(layer "F.Cu")
		(net "M_G_CPU0_SA_DQ<14>")
	)
	(segment
		(start 446.163954 -300.60392)
		(end 446.367916 -300.399958)
		(width 0.20066)
		(layer "F.Cu")
		(net "M_G_CPU0_SA_DQ<14>")
	)
	(segment
		(start 445.470534 -300.591728)
		(end 445.482726 -300.60392)
		(width 0.1016)
		(layer "F.Cu")
		(net "M_G_CPU0_SA_DQ<14>")
	)
	(segment
		(start 446.367916 -300.149006)
		(end 446.602104 -299.914818)
		(width 0.20066)
		(layer "F.Cu")
		(net "M_G_CPU0_SA_DQ<14>")
	)
	(segment
		(start 439.881772 -300.166786)
		(end 441.028582 -300.166786)
		(width 0.20066)
		(layer "F.Cu")
		(net "M_G_CPU0_SA_DQ<14>")
	)
	(segment
		(start 439.881772 -300.166786)
		(end 439.456068 -300.59249)
		(width 0.18288)
		(layer "In6.Cu")
		(net "M_G_CPU0_SA_DQ<14>")
	)
	(segment
		(start 437.397652 -300.43247)
		(end 437.397652 -300.125892)
		(width 0.18288)
		(layer "In6.Cu")
		(net "M_G_CPU0_SA_DQ<14>")
	)
	(segment
		(start 377.269756 -271.332452)
		(end 377.220734 -271.360138)
		(width 0.088646)
		(layer "In6.Cu")
		(net "M_G_CPU0_SA_DQ<14>")
	)
	(segment
		(start 378.203714 -271.336008)
		(end 378.197872 -271.33931)
		(width 0.088646)
		(layer "In6.Cu")
		(net "M_G_CPU0_SA_DQ<14>")
	)
	(segment
		(start 388.535672 -272.533364)
		(end 388.217918 -272.533364)
		(width 0.088646)
		(layer "In6.Cu")
		(net "M_G_CPU0_SA_DQ<14>")
	)
	(segment
		(start 419.636956 -292.942264)
		(end 417.340288 -292.942264)
		(width 0.18288)
		(layer "In6.Cu")
		(net "M_G_CPU0_SA_DQ<14>")
	)
	(segment
		(start 426.053758 -294.680894)
		(end 425.165012 -293.792148)
		(width 0.18288)
		(layer "In6.Cu")
		(net "M_G_CPU0_SA_DQ<14>")
	)
	(segment
		(start 388.217918 -272.533364)
		(end 387.509766 -271.825212)
		(width 0.088646)
		(layer "In6.Cu")
		(net "M_G_CPU0_SA_DQ<14>")
	)
	(segment
		(start 379.143514 -271.336008)
		(end 379.137672 -271.33931)
		(width 0.088646)
		(layer "In6.Cu")
		(net "M_G_CPU0_SA_DQ<14>")
	)
	(segment
		(start 421.020494 -292.092126)
		(end 420.487094 -292.092126)
		(width 0.18288)
		(layer "In6.Cu")
		(net "M_G_CPU0_SA_DQ<14>")
	)
	(segment
		(start 385.347464 -271.335754)
		(end 385.332732 -271.327118)
		(width 0.088646)
		(layer "In6.Cu")
		(net "M_G_CPU0_SA_DQ<14>")
	)
	(segment
		(start 408.172412 -289.649916)
		(end 407.29154 -289.649916)
		(width 0.18288)
		(layer "In6.Cu")
		(net "M_G_CPU0_SA_DQ<14>")
	)
	(segment
		(start 406.62352 -289.329622)
		(end 406.4635 -289.489642)
		(width 0.18288)
		(layer "In6.Cu")
		(net "M_G_CPU0_SA_DQ<14>")
	)
	(segment
		(start 381.962914 -271.336008)
		(end 381.957072 -271.33931)
		(width 0.088646)
		(layer "In6.Cu")
		(net "M_G_CPU0_SA_DQ<14>")
	)
	(segment
		(start 428.703994 -295.610026)
		(end 428.145194 -295.610026)
		(width 0.18288)
		(layer "In6.Cu")
		(net "M_G_CPU0_SA_DQ<14>")
	)
	(segment
		(start 408.976322 -290.453826)
		(end 408.172412 -289.649916)
		(width 0.18288)
		(layer "In6.Cu")
		(net "M_G_CPU0_SA_DQ<14>")
	)
	(segment
		(start 407.29154 -289.649916)
		(end 407.13152 -289.489896)
		(width 0.18288)
		(layer "In6.Cu")
		(net "M_G_CPU0_SA_DQ<14>")
	)
	(segment
		(start 422.720516 -293.792148)
		(end 421.020494 -292.092126)
		(width 0.18288)
		(layer "In6.Cu")
		(net "M_G_CPU0_SA_DQ<14>")
	)
	(segment
		(start 431.193194 -297.337226)
		(end 430.431194 -297.337226)
		(width 0.18288)
		(layer "In6.Cu")
		(net "M_G_CPU0_SA_DQ<14>")
	)
	(segment
		(start 428.145194 -295.610026)
		(end 427.216062 -294.680894)
		(width 0.18288)
		(layer "In6.Cu")
		(net "M_G_CPU0_SA_DQ<14>")
	)
	(segment
		(start 382.906524 -271.333722)
		(end 382.902714 -271.336008)
		(width 0.088646)
		(layer "In6.Cu")
		(net "M_G_CPU0_SA_DQ<14>")
	)
	(segment
		(start 417.340288 -292.942264)
		(end 415.71418 -291.316156)
		(width 0.18288)
		(layer "In6.Cu")
		(net "M_G_CPU0_SA_DQ<14>")
	)
	(segment
		(start 381.968756 -271.332452)
		(end 381.962914 -271.336008)
		(width 0.088646)
		(layer "In6.Cu")
		(net "M_G_CPU0_SA_DQ<14>")
	)
	(segment
		(start 406.9715 -289.329622)
		(end 406.62352 -289.329622)
		(width 0.18288)
		(layer "In6.Cu")
		(net "M_G_CPU0_SA_DQ<14>")
	)
	(segment
		(start 414.695894 -291.316156)
		(end 413.64281 -290.263072)
		(width 0.18288)
		(layer "In6.Cu")
		(net "M_G_CPU0_SA_DQ<14>")
	)
	(segment
		(start 380.083314 -271.336008)
		(end 380.077472 -271.33931)
		(width 0.088646)
		(layer "In6.Cu")
		(net "M_G_CPU0_SA_DQ<14>")
	)
	(segment
		(start 436.704232 -300.43247)
		(end 436.543196 -300.593506)
		(width 0.18288)
		(layer "In6.Cu")
		(net "M_G_CPU0_SA_DQ<14>")
	)
	(segment
		(start 437.237632 -299.965872)
		(end 436.864252 -299.965872)
		(width 0.18288)
		(layer "In6.Cu")
		(net "M_G_CPU0_SA_DQ<14>")
	)
	(segment
		(start 436.704232 -300.125892)
		(end 436.704232 -300.43247)
		(width 0.18288)
		(layer "In6.Cu")
		(net "M_G_CPU0_SA_DQ<14>")
	)
	(segment
		(start 383.84226 -271.335754)
		(end 383.842514 -271.336008)
		(width 0.088646)
		(layer "In6.Cu")
		(net "M_G_CPU0_SA_DQ<14>")
	)
	(segment
		(start 381.023114 -271.336008)
		(end 381.017272 -271.33931)
		(width 0.088646)
		(layer "In6.Cu")
		(net "M_G_CPU0_SA_DQ<14>")
	)
	(segment
		(start 406.4635 -289.489896)
		(end 406.3111 -289.642296)
		(width 0.18288)
		(layer "In6.Cu")
		(net "M_G_CPU0_SA_DQ<14>")
	)
	(segment
		(start 432.082194 -298.226226)
		(end 431.193194 -297.337226)
		(width 0.18288)
		(layer "In6.Cu")
		(net "M_G_CPU0_SA_DQ<14>")
	)
	(segment
		(start 390.398254 -272.949416)
		(end 389.393684 -272.533364)
		(width 0.18288)
		(layer "In6.Cu")
		(net "M_G_CPU0_SA_DQ<14>")
	)
	(segment
		(start 412.648908 -290.263072)
		(end 412.458154 -290.453826)
		(width 0.18288)
		(layer "In6.Cu")
		(net "M_G_CPU0_SA_DQ<14>")
	)
	(segment
		(start 412.458154 -290.453826)
		(end 408.976322 -290.453826)
		(width 0.18288)
		(layer "In6.Cu")
		(net "M_G_CPU0_SA_DQ<14>")
	)
	(segment
		(start 403.95271 -280.230834)
		(end 396.671292 -272.949416)
		(width 0.18288)
		(layer "In6.Cu")
		(net "M_G_CPU0_SA_DQ<14>")
	)
	(segment
		(start 435.651148 -300.593506)
		(end 434.940456 -299.882814)
		(width 0.18288)
		(layer "In6.Cu")
		(net "M_G_CPU0_SA_DQ<14>")
	)
	(segment
		(start 439.456068 -300.59249)
		(end 437.557672 -300.59249)
		(width 0.18288)
		(layer "In6.Cu")
		(net "M_G_CPU0_SA_DQ<14>")
	)
	(segment
		(start 434.940456 -299.882814)
		(end 434.348382 -299.882814)
		(width 0.18288)
		(layer "In6.Cu")
		(net "M_G_CPU0_SA_DQ<14>")
	)
	(segment
		(start 413.64281 -290.263072)
		(end 412.648908 -290.263072)
		(width 0.18288)
		(layer "In6.Cu")
		(net "M_G_CPU0_SA_DQ<14>")
	)
	(segment
		(start 425.165012 -293.792148)
		(end 422.720516 -293.792148)
		(width 0.18288)
		(layer "In6.Cu")
		(net "M_G_CPU0_SA_DQ<14>")
	)
	(segment
		(start 396.671292 -272.949416)
		(end 390.398254 -272.949416)
		(width 0.18288)
		(layer "In6.Cu")
		(net "M_G_CPU0_SA_DQ<14>")
	)
	(segment
		(start 436.864252 -299.965872)
		(end 436.704232 -300.125892)
		(width 0.18288)
		(layer "In6.Cu")
		(net "M_G_CPU0_SA_DQ<14>")
	)
	(segment
		(start 432.691794 -298.226226)
		(end 432.082194 -298.226226)
		(width 0.18288)
		(layer "In6.Cu")
		(net "M_G_CPU0_SA_DQ<14>")
	)
	(segment
		(start 427.216062 -294.680894)
		(end 426.053758 -294.680894)
		(width 0.18288)
		(layer "In6.Cu")
		(net "M_G_CPU0_SA_DQ<14>")
	)
	(segment
		(start 380.089156 -271.332452)
		(end 380.083314 -271.336008)
		(width 0.088646)
		(layer "In6.Cu")
		(net "M_G_CPU0_SA_DQ<14>")
	)
	(segment
		(start 415.71418 -291.316156)
		(end 414.695894 -291.316156)
		(width 0.18288)
		(layer "In6.Cu")
		(net "M_G_CPU0_SA_DQ<14>")
	)
	(segment
		(start 420.487094 -292.092126)
		(end 419.636956 -292.942264)
		(width 0.18288)
		(layer "In6.Cu")
		(net "M_G_CPU0_SA_DQ<14>")
	)
	(segment
		(start 382.902714 -271.336008)
		(end 382.896872 -271.33931)
		(width 0.088646)
		(layer "In6.Cu")
		(net "M_G_CPU0_SA_DQ<14>")
	)
	(segment
		(start 386.287264 -271.335754)
		(end 386.272532 -271.327118)
		(width 0.088646)
		(layer "In6.Cu")
		(net "M_G_CPU0_SA_DQ<14>")
	)
	(segment
		(start 407.13152 -289.489642)
		(end 406.9715 -289.329622)
		(width 0.18288)
		(layer "In6.Cu")
		(net "M_G_CPU0_SA_DQ<14>")
	)
	(segment
		(start 437.397652 -300.125892)
		(end 437.237632 -299.965872)
		(width 0.18288)
		(layer "In6.Cu")
		(net "M_G_CPU0_SA_DQ<14>")
	)
	(segment
		(start 436.543196 -300.593506)
		(end 435.651148 -300.593506)
		(width 0.18288)
		(layer "In6.Cu")
		(net "M_G_CPU0_SA_DQ<14>")
	)
	(segment
		(start 384.407664 -271.335754)
		(end 384.392932 -271.327118)
		(width 0.088646)
		(layer "In6.Cu")
		(net "M_G_CPU0_SA_DQ<14>")
	)
	(segment
		(start 389.393684 -272.533364)
		(end 388.535672 -272.533364)
		(width 0.18288)
		(layer "In6.Cu")
		(net "M_G_CPU0_SA_DQ<14>")
	)
	(segment
		(start 434.348382 -299.882814)
		(end 432.691794 -298.226226)
		(width 0.18288)
		(layer "In6.Cu")
		(net "M_G_CPU0_SA_DQ<14>")
	)
	(segment
		(start 437.557672 -300.59249)
		(end 437.397652 -300.43247)
		(width 0.18288)
		(layer "In6.Cu")
		(net "M_G_CPU0_SA_DQ<14>")
	)
	(segment
		(start 378.209556 -271.332452)
		(end 378.203714 -271.336008)
		(width 0.088646)
		(layer "In6.Cu")
		(net "M_G_CPU0_SA_DQ<14>")
	)
	(segment
		(start 379.149356 -271.332452)
		(end 379.143514 -271.336008)
		(width 0.088646)
		(layer "In6.Cu")
		(net "M_G_CPU0_SA_DQ<14>")
	)
	(segment
		(start 406.3111 -289.642296)
		(end 405.577548 -289.642296)
		(width 0.18288)
		(layer "In6.Cu")
		(net "M_G_CPU0_SA_DQ<14>")
	)
	(segment
		(start 381.028956 -271.332452)
		(end 381.023114 -271.336008)
		(width 0.088646)
		(layer "In6.Cu")
		(net "M_G_CPU0_SA_DQ<14>")
	)
	(segment
		(start 406.4635 -289.489642)
		(end 406.4635 -289.489896)
		(width 0.18288)
		(layer "In6.Cu")
		(net "M_G_CPU0_SA_DQ<14>")
	)
	(segment
		(start 403.95271 -288.017458)
		(end 403.95271 -280.230834)
		(width 0.18288)
		(layer "In6.Cu")
		(net "M_G_CPU0_SA_DQ<14>")
	)
	(segment
		(start 405.577548 -289.642296)
		(end 403.95271 -288.017458)
		(width 0.18288)
		(layer "In6.Cu")
		(net "M_G_CPU0_SA_DQ<14>")
	)
	(segment
		(start 430.431194 -297.337226)
		(end 428.703994 -295.610026)
		(width 0.18288)
		(layer "In6.Cu")
		(net "M_G_CPU0_SA_DQ<14>")
	)
	(segment
		(start 407.13152 -289.489896)
		(end 407.13152 -289.489642)
		(width 0.18288)
		(layer "In6.Cu")
		(net "M_G_CPU0_SA_DQ<14>")
	)
	(arc
		(start 385.332732 -271.327118)
		(mid 385.056257 -271.259798)
		(end 384.78206 -271.335754)
		(width 0.088646)
		(layer "In6.Cu")
		(net "M_G_CPU0_SA_DQ<14>")
	)
	(arc
		(start 386.272532 -271.327118)
		(mid 385.996057 -271.259798)
		(end 385.72186 -271.335754)
		(width 0.088646)
		(layer "In6.Cu")
		(net "M_G_CPU0_SA_DQ<14>")
	)
	(arc
		(start 384.392932 -271.327118)
		(mid 384.116457 -271.259798)
		(end 383.84226 -271.335754)
		(width 0.088646)
		(layer "In6.Cu")
		(net "M_G_CPU0_SA_DQ<14>")
	)
	(arc
		(start 385.72186 -271.335754)
		(mid 385.534662 -271.385897)
		(end 385.347464 -271.335754)
		(width 0.088646)
		(layer "In6.Cu")
		(net "M_G_CPU0_SA_DQ<14>")
	)
	(arc
		(start 378.197872 -271.33931)
		(mid 378.013017 -271.38626)
		(end 377.829064 -271.336008)
		(width 0.088646)
		(layer "In6.Cu")
		(net "M_G_CPU0_SA_DQ<14>")
	)
	(arc
		(start 379.137672 -271.33931)
		(mid 378.952817 -271.38626)
		(end 378.768864 -271.336008)
		(width 0.088646)
		(layer "In6.Cu")
		(net "M_G_CPU0_SA_DQ<14>")
	)
	(arc
		(start 383.467864 -271.336008)
		(mid 383.187493 -271.260203)
		(end 382.906524 -271.333722)
		(width 0.088646)
		(layer "In6.Cu")
		(net "M_G_CPU0_SA_DQ<14>")
	)
	(arc
		(start 387.509766 -271.825212)
		(mid 387.227053 -271.335698)
		(end 386.66166 -271.335754)
		(width 0.088646)
		(layer "In6.Cu")
		(net "M_G_CPU0_SA_DQ<14>")
	)
	(arc
		(start 377.829064 -271.336008)
		(mid 377.54989 -271.260209)
		(end 377.269756 -271.332452)
		(width 0.088646)
		(layer "In6.Cu")
		(net "M_G_CPU0_SA_DQ<14>")
	)
	(arc
		(start 381.588264 -271.336008)
		(mid 381.30909 -271.260209)
		(end 381.028956 -271.332452)
		(width 0.088646)
		(layer "In6.Cu")
		(net "M_G_CPU0_SA_DQ<14>")
	)
	(arc
		(start 381.017272 -271.33931)
		(mid 380.832417 -271.38626)
		(end 380.648464 -271.336008)
		(width 0.088646)
		(layer "In6.Cu")
		(net "M_G_CPU0_SA_DQ<14>")
	)
	(arc
		(start 380.077472 -271.33931)
		(mid 379.892617 -271.38626)
		(end 379.708664 -271.336008)
		(width 0.088646)
		(layer "In6.Cu")
		(net "M_G_CPU0_SA_DQ<14>")
	)
	(arc
		(start 382.896872 -271.33931)
		(mid 382.712017 -271.38626)
		(end 382.528064 -271.336008)
		(width 0.088646)
		(layer "In6.Cu")
		(net "M_G_CPU0_SA_DQ<14>")
	)
	(arc
		(start 383.842514 -271.336008)
		(mid 383.655206 -271.386151)
		(end 383.467864 -271.336008)
		(width 0.088646)
		(layer "In6.Cu")
		(net "M_G_CPU0_SA_DQ<14>")
	)
	(arc
		(start 380.648464 -271.336008)
		(mid 380.36929 -271.260209)
		(end 380.089156 -271.332452)
		(width 0.088646)
		(layer "In6.Cu")
		(net "M_G_CPU0_SA_DQ<14>")
	)
	(arc
		(start 382.528064 -271.336008)
		(mid 382.24889 -271.260209)
		(end 381.968756 -271.332452)
		(width 0.088646)
		(layer "In6.Cu")
		(net "M_G_CPU0_SA_DQ<14>")
	)
	(arc
		(start 386.66166 -271.335754)
		(mid 386.474462 -271.385897)
		(end 386.287264 -271.335754)
		(width 0.088646)
		(layer "In6.Cu")
		(net "M_G_CPU0_SA_DQ<14>")
	)
	(arc
		(start 381.957072 -271.33931)
		(mid 381.772217 -271.38626)
		(end 381.588264 -271.336008)
		(width 0.088646)
		(layer "In6.Cu")
		(net "M_G_CPU0_SA_DQ<14>")
	)
	(arc
		(start 384.78206 -271.335754)
		(mid 384.594862 -271.385897)
		(end 384.407664 -271.335754)
		(width 0.088646)
		(layer "In6.Cu")
		(net "M_G_CPU0_SA_DQ<14>")
	)
	(arc
		(start 379.708664 -271.336008)
		(mid 379.42949 -271.260209)
		(end 379.149356 -271.332452)
		(width 0.088646)
		(layer "In6.Cu")
		(net "M_G_CPU0_SA_DQ<14>")
	)
	(arc
		(start 378.768864 -271.336008)
		(mid 378.48969 -271.260209)
		(end 378.209556 -271.332452)
		(width 0.088646)
		(layer "In6.Cu")
		(net "M_G_CPU0_SA_DQ<14>")
	)
	(arc
		(start 377.220734 -271.360138)
		(mid 376.898148 -271.572047)
		(end 376.606816 -271.825212)
		(width 0.088646)
		(layer "In6.Cu")
		(net "M_G_CPU0_SA_DQ<14>")
	)
	(segment
		(start 438.697878 -299.565314)
		(end 438.449212 -299.316648)
		(width 0.20066)
		(layer "F.Cu")
		(net "M_G_CPU0_SA_DQ<13>")
	)
	(segment
		(start 375.197116 -270.475456)
		(end 375.197116 -271.011142)
		(width 0.20066)
		(layer "F.Cu")
		(net "M_G_CPU0_SA_DQ<13>")
	)
	(segment
		(start 439.82386 -298.891706)
		(end 439.479182 -298.891706)
		(width 0.20066)
		(layer "F.Cu")
		(net "M_G_CPU0_SA_DQ<13>")
	)
	(segment
		(start 444.47206 -299.316902)
		(end 442.880496 -299.316902)
		(width 0.20066)
		(layer "F.Cu")
		(net "M_G_CPU0_SA_DQ<13>")
	)
	(segment
		(start 439.361072 -299.377354)
		(end 439.173112 -299.565314)
		(width 0.20066)
		(layer "F.Cu")
		(net "M_G_CPU0_SA_DQ<13>")
	)
	(segment
		(start 442.032644 -298.891706)
		(end 439.843926 -298.891706)
		(width 0.1016)
		(layer "F.Cu")
		(net "M_G_CPU0_SA_DQ<13>")
	)
	(segment
		(start 439.361072 -299.009816)
		(end 439.361072 -299.377354)
		(width 0.20066)
		(layer "F.Cu")
		(net "M_G_CPU0_SA_DQ<13>")
	)
	(segment
		(start 438.449212 -299.316648)
		(end 436.928514 -299.316648)
		(width 0.20066)
		(layer "F.Cu")
		(net "M_G_CPU0_SA_DQ<13>")
	)
	(segment
		(start 442.038994 -298.885356)
		(end 442.032644 -298.891706)
		(width 0.1016)
		(layer "F.Cu")
		(net "M_G_CPU0_SA_DQ<13>")
	)
	(segment
		(start 439.173112 -299.565314)
		(end 438.697878 -299.565314)
		(width 0.20066)
		(layer "F.Cu")
		(net "M_G_CPU0_SA_DQ<13>")
	)
	(segment
		(start 436.928514 -299.316648)
		(end 435.823614 -299.316648)
		(width 0.20066)
		(layer "F.Cu")
		(net "M_G_CPU0_SA_DQ<13>")
	)
	(segment
		(start 444.472314 -299.316648)
		(end 444.47206 -299.316902)
		(width 0.20066)
		(layer "F.Cu")
		(net "M_G_CPU0_SA_DQ<13>")
	)
	(segment
		(start 442.880496 -299.316902)
		(end 442.44895 -298.885356)
		(width 0.20066)
		(layer "F.Cu")
		(net "M_G_CPU0_SA_DQ<13>")
	)
	(segment
		(start 442.44895 -298.885356)
		(end 442.038994 -298.885356)
		(width 0.20066)
		(layer "F.Cu")
		(net "M_G_CPU0_SA_DQ<13>")
	)
	(segment
		(start 439.479182 -298.891706)
		(end 439.361072 -299.009816)
		(width 0.20066)
		(layer "F.Cu")
		(net "M_G_CPU0_SA_DQ<13>")
	)
	(segment
		(start 375.197116 -271.011142)
		(end 375.196862 -271.011396)
		(width 0.20066)
		(layer "F.Cu")
		(net "M_G_CPU0_SA_DQ<13>")
	)
	(segment
		(start 439.843926 -298.891706)
		(end 439.82386 -298.891706)
		(width 0.101854)
		(layer "F.Cu")
		(net "M_G_CPU0_SA_DQ<13>")
	)
	(segment
		(start 376.701812 -271.011396)
		(end 376.701812 -271.02689)
		(width 0.088646)
		(layer "In6.Cu")
		(net "M_G_CPU0_SA_DQ<13>")
	)
	(segment
		(start 421.10787 -291.239702)
		(end 418.987732 -291.239702)
		(width 0.18288)
		(layer "In6.Cu")
		(net "M_G_CPU0_SA_DQ<13>")
	)
	(segment
		(start 387.229604 -271.07388)
		(end 386.792216 -270.636492)
		(width 0.088646)
		(layer "In6.Cu")
		(net "M_G_CPU0_SA_DQ<13>")
	)
	(segment
		(start 431.396394 -296.854626)
		(end 430.634394 -296.092626)
		(width 0.18288)
		(layer "In6.Cu")
		(net "M_G_CPU0_SA_DQ<13>")
	)
	(segment
		(start 388.535672 -272.029174)
		(end 388.376922 -272.029174)
		(width 0.088646)
		(layer "In6.Cu")
		(net "M_G_CPU0_SA_DQ<13>")
	)
	(segment
		(start 387.421628 -271.07388)
		(end 387.229604 -271.07388)
		(width 0.088646)
		(layer "In6.Cu")
		(net "M_G_CPU0_SA_DQ<13>")
	)
	(segment
		(start 435.823614 -299.316648)
		(end 435.249828 -299.316648)
		(width 0.18288)
		(layer "In6.Cu")
		(net "M_G_CPU0_SA_DQ<13>")
	)
	(segment
		(start 423.682414 -293.169086)
		(end 423.037254 -293.169086)
		(width 0.18288)
		(layer "In6.Cu")
		(net "M_G_CPU0_SA_DQ<13>")
	)
	(segment
		(start 378.768864 -270.687038)
		(end 378.754132 -270.695674)
		(width 0.088646)
		(layer "In6.Cu")
		(net "M_G_CPU0_SA_DQ<13>")
	)
	(segment
		(start 383.467864 -270.687038)
		(end 383.453132 -270.695674)
		(width 0.088646)
		(layer "In6.Cu")
		(net "M_G_CPU0_SA_DQ<13>")
	)
	(segment
		(start 426.23105 -293.170102)
		(end 425.868846 -293.532306)
		(width 0.18288)
		(layer "In6.Cu")
		(net "M_G_CPU0_SA_DQ<13>")
	)
	(segment
		(start 414.365694 -290.276026)
		(end 413.76854 -289.678872)
		(width 0.18288)
		(layer "In6.Cu")
		(net "M_G_CPU0_SA_DQ<13>")
	)
	(segment
		(start 433.250594 -297.388026)
		(end 432.717194 -296.854626)
		(width 0.18288)
		(layer "In6.Cu")
		(net "M_G_CPU0_SA_DQ<13>")
	)
	(segment
		(start 375.509536 -271.011396)
		(end 375.196862 -271.011396)
		(width 0.088646)
		(layer "In6.Cu")
		(net "M_G_CPU0_SA_DQ<13>")
	)
	(segment
		(start 404.45055 -280.024586)
		(end 396.87754 -272.451576)
		(width 0.18288)
		(layer "In6.Cu")
		(net "M_G_CPU0_SA_DQ<13>")
	)
	(segment
		(start 389.478012 -272.029174)
		(end 388.535672 -272.029174)
		(width 0.18288)
		(layer "In6.Cu")
		(net "M_G_CPU0_SA_DQ<13>")
	)
	(segment
		(start 418.621972 -292.377368)
		(end 418.294312 -292.377368)
		(width 0.18288)
		(layer "In6.Cu")
		(net "M_G_CPU0_SA_DQ<13>")
	)
	(segment
		(start 388.376922 -272.029174)
		(end 387.421628 -271.07388)
		(width 0.088646)
		(layer "In6.Cu")
		(net "M_G_CPU0_SA_DQ<13>")
	)
	(segment
		(start 379.708664 -270.687038)
		(end 379.693932 -270.695674)
		(width 0.088646)
		(layer "In6.Cu")
		(net "M_G_CPU0_SA_DQ<13>")
	)
	(segment
		(start 413.76854 -289.678872)
		(end 412.738824 -289.678872)
		(width 0.18288)
		(layer "In6.Cu")
		(net "M_G_CPU0_SA_DQ<13>")
	)
	(segment
		(start 425.378372 -293.041832)
		(end 425.740576 -292.679628)
		(width 0.18288)
		(layer "In6.Cu")
		(net "M_G_CPU0_SA_DQ<13>")
	)
	(segment
		(start 417.928552 -291.239702)
		(end 416.74415 -291.239702)
		(width 0.18288)
		(layer "In6.Cu")
		(net "M_G_CPU0_SA_DQ<13>")
	)
	(segment
		(start 412.575248 -289.515296)
		(end 409.030678 -289.515296)
		(width 0.18288)
		(layer "In6.Cu")
		(net "M_G_CPU0_SA_DQ<13>")
	)
	(segment
		(start 425.4119 -292.09238)
		(end 424.081448 -292.09238)
		(width 0.18288)
		(layer "In6.Cu")
		(net "M_G_CPU0_SA_DQ<13>")
	)
	(segment
		(start 386.792216 -270.636492)
		(end 386.474462 -270.636492)
		(width 0.088646)
		(layer "In6.Cu")
		(net "M_G_CPU0_SA_DQ<13>")
	)
	(segment
		(start 418.111432 -291.422582)
		(end 417.928552 -291.239702)
		(width 0.18288)
		(layer "In6.Cu")
		(net "M_G_CPU0_SA_DQ<13>")
	)
	(segment
		(start 430.126394 -296.092626)
		(end 427.611794 -293.578026)
		(width 0.18288)
		(layer "In6.Cu")
		(net "M_G_CPU0_SA_DQ<13>")
	)
	(segment
		(start 415.780474 -290.276026)
		(end 414.365694 -290.276026)
		(width 0.18288)
		(layer "In6.Cu")
		(net "M_G_CPU0_SA_DQ<13>")
	)
	(segment
		(start 424.081448 -292.09238)
		(end 423.921174 -292.252654)
		(width 0.18288)
		(layer "In6.Cu")
		(net "M_G_CPU0_SA_DQ<13>")
	)
	(segment
		(start 418.111432 -292.194488)
		(end 418.111432 -291.422582)
		(width 0.18288)
		(layer "In6.Cu")
		(net "M_G_CPU0_SA_DQ<13>")
	)
	(segment
		(start 425.740576 -292.421056)
		(end 425.4119 -292.09238)
		(width 0.18288)
		(layer "In6.Cu")
		(net "M_G_CPU0_SA_DQ<13>")
	)
	(segment
		(start 423.921174 -292.252654)
		(end 423.921174 -292.930326)
		(width 0.18288)
		(layer "In6.Cu")
		(net "M_G_CPU0_SA_DQ<13>")
	)
	(segment
		(start 375.575322 -271.077182)
		(end 375.509536 -271.011396)
		(width 0.088646)
		(layer "In6.Cu")
		(net "M_G_CPU0_SA_DQ<13>")
	)
	(segment
		(start 377.829064 -270.687038)
		(end 377.814332 -270.695674)
		(width 0.088646)
		(layer "In6.Cu")
		(net "M_G_CPU0_SA_DQ<13>")
	)
	(segment
		(start 435.249828 -299.316648)
		(end 434.774594 -298.841414)
		(width 0.18288)
		(layer "In6.Cu")
		(net "M_G_CPU0_SA_DQ<13>")
	)
	(segment
		(start 380.648464 -270.687038)
		(end 380.633732 -270.695674)
		(width 0.088646)
		(layer "In6.Cu")
		(net "M_G_CPU0_SA_DQ<13>")
	)
	(segment
		(start 426.897546 -293.578026)
		(end 426.489622 -293.170102)
		(width 0.18288)
		(layer "In6.Cu")
		(net "M_G_CPU0_SA_DQ<13>")
	)
	(segment
		(start 433.250594 -297.930062)
		(end 433.250594 -297.388026)
		(width 0.18288)
		(layer "In6.Cu")
		(net "M_G_CPU0_SA_DQ<13>")
	)
	(segment
		(start 405.487378 -288.567876)
		(end 404.45055 -287.531048)
		(width 0.18288)
		(layer "In6.Cu")
		(net "M_G_CPU0_SA_DQ<13>")
	)
	(segment
		(start 430.634394 -296.092626)
		(end 430.126394 -296.092626)
		(width 0.18288)
		(layer "In6.Cu")
		(net "M_G_CPU0_SA_DQ<13>")
	)
	(segment
		(start 418.804852 -291.422582)
		(end 418.804852 -292.194488)
		(width 0.18288)
		(layer "In6.Cu")
		(net "M_G_CPU0_SA_DQ<13>")
	)
	(segment
		(start 434.161946 -298.841414)
		(end 433.250594 -297.930062)
		(width 0.18288)
		(layer "In6.Cu")
		(net "M_G_CPU0_SA_DQ<13>")
	)
	(segment
		(start 418.987732 -291.239702)
		(end 418.804852 -291.422582)
		(width 0.18288)
		(layer "In6.Cu")
		(net "M_G_CPU0_SA_DQ<13>")
	)
	(segment
		(start 425.378372 -293.300404)
		(end 425.378372 -293.041832)
		(width 0.18288)
		(layer "In6.Cu")
		(net "M_G_CPU0_SA_DQ<13>")
	)
	(segment
		(start 382.528064 -270.687038)
		(end 382.513332 -270.695674)
		(width 0.088646)
		(layer "In6.Cu")
		(net "M_G_CPU0_SA_DQ<13>")
	)
	(segment
		(start 432.717194 -296.854626)
		(end 431.396394 -296.854626)
		(width 0.18288)
		(layer "In6.Cu")
		(net "M_G_CPU0_SA_DQ<13>")
	)
	(segment
		(start 408.083258 -288.567876)
		(end 405.487378 -288.567876)
		(width 0.18288)
		(layer "In6.Cu")
		(net "M_G_CPU0_SA_DQ<13>")
	)
	(segment
		(start 425.868846 -293.532306)
		(end 425.610274 -293.532306)
		(width 0.18288)
		(layer "In6.Cu")
		(net "M_G_CPU0_SA_DQ<13>")
	)
	(segment
		(start 434.774594 -298.841414)
		(end 434.161946 -298.841414)
		(width 0.18288)
		(layer "In6.Cu")
		(net "M_G_CPU0_SA_DQ<13>")
	)
	(segment
		(start 418.804852 -292.194488)
		(end 418.621972 -292.377368)
		(width 0.18288)
		(layer "In6.Cu")
		(net "M_G_CPU0_SA_DQ<13>")
	)
	(segment
		(start 423.921174 -292.930326)
		(end 423.682414 -293.169086)
		(width 0.18288)
		(layer "In6.Cu")
		(net "M_G_CPU0_SA_DQ<13>")
	)
	(segment
		(start 396.87754 -272.451576)
		(end 390.497822 -272.451576)
		(width 0.18288)
		(layer "In6.Cu")
		(net "M_G_CPU0_SA_DQ<13>")
	)
	(segment
		(start 390.497822 -272.451576)
		(end 389.478012 -272.029174)
		(width 0.18288)
		(layer "In6.Cu")
		(net "M_G_CPU0_SA_DQ<13>")
	)
	(segment
		(start 376.889264 -270.687038)
		(end 376.880374 -270.692118)
		(width 0.088646)
		(layer "In6.Cu")
		(net "M_G_CPU0_SA_DQ<13>")
	)
	(segment
		(start 385.347464 -270.687038)
		(end 385.332732 -270.695674)
		(width 0.088646)
		(layer "In6.Cu")
		(net "M_G_CPU0_SA_DQ<13>")
	)
	(segment
		(start 426.489622 -293.170102)
		(end 426.23105 -293.170102)
		(width 0.18288)
		(layer "In6.Cu")
		(net "M_G_CPU0_SA_DQ<13>")
	)
	(segment
		(start 412.738824 -289.678872)
		(end 412.575248 -289.515296)
		(width 0.18288)
		(layer "In6.Cu")
		(net "M_G_CPU0_SA_DQ<13>")
	)
	(segment
		(start 409.030678 -289.515296)
		(end 408.083258 -288.567876)
		(width 0.18288)
		(layer "In6.Cu")
		(net "M_G_CPU0_SA_DQ<13>")
	)
	(segment
		(start 416.74415 -291.239702)
		(end 415.780474 -290.276026)
		(width 0.18288)
		(layer "In6.Cu")
		(net "M_G_CPU0_SA_DQ<13>")
	)
	(segment
		(start 427.611794 -293.578026)
		(end 426.897546 -293.578026)
		(width 0.18288)
		(layer "In6.Cu")
		(net "M_G_CPU0_SA_DQ<13>")
	)
	(segment
		(start 418.294312 -292.377368)
		(end 418.111432 -292.194488)
		(width 0.18288)
		(layer "In6.Cu")
		(net "M_G_CPU0_SA_DQ<13>")
	)
	(segment
		(start 384.407664 -270.687038)
		(end 384.392932 -270.695674)
		(width 0.088646)
		(layer "In6.Cu")
		(net "M_G_CPU0_SA_DQ<13>")
	)
	(segment
		(start 404.45055 -287.531048)
		(end 404.45055 -280.024586)
		(width 0.18288)
		(layer "In6.Cu")
		(net "M_G_CPU0_SA_DQ<13>")
	)
	(segment
		(start 375.854214 -271.500854)
		(end 375.848118 -271.497298)
		(width 0.088646)
		(layer "In6.Cu")
		(net "M_G_CPU0_SA_DQ<13>")
	)
	(segment
		(start 375.868946 -271.50949)
		(end 375.854214 -271.500854)
		(width 0.088646)
		(layer "In6.Cu")
		(net "M_G_CPU0_SA_DQ<13>")
	)
	(segment
		(start 423.037254 -293.169086)
		(end 421.10787 -291.239702)
		(width 0.18288)
		(layer "In6.Cu")
		(net "M_G_CPU0_SA_DQ<13>")
	)
	(segment
		(start 425.740576 -292.679628)
		(end 425.740576 -292.421056)
		(width 0.18288)
		(layer "In6.Cu")
		(net "M_G_CPU0_SA_DQ<13>")
	)
	(segment
		(start 425.610274 -293.532306)
		(end 425.378372 -293.300404)
		(width 0.18288)
		(layer "In6.Cu")
		(net "M_G_CPU0_SA_DQ<13>")
	)
	(arc
		(start 383.84226 -270.687038)
		(mid 383.655062 -270.636895)
		(end 383.467864 -270.687038)
		(width 0.088646)
		(layer "In6.Cu")
		(net "M_G_CPU0_SA_DQ<13>")
	)
	(arc
		(start 384.392932 -270.695674)
		(mid 384.116457 -270.762994)
		(end 383.84226 -270.687038)
		(width 0.088646)
		(layer "In6.Cu")
		(net "M_G_CPU0_SA_DQ<13>")
	)
	(arc
		(start 381.02286 -270.687038)
		(mid 380.835662 -270.636895)
		(end 380.648464 -270.687038)
		(width 0.088646)
		(layer "In6.Cu")
		(net "M_G_CPU0_SA_DQ<13>")
	)
	(arc
		(start 377.26366 -270.687038)
		(mid 377.076462 -270.636895)
		(end 376.889264 -270.687038)
		(width 0.088646)
		(layer "In6.Cu")
		(net "M_G_CPU0_SA_DQ<13>")
	)
	(arc
		(start 380.08306 -270.687038)
		(mid 379.895862 -270.636895)
		(end 379.708664 -270.687038)
		(width 0.088646)
		(layer "In6.Cu")
		(net "M_G_CPU0_SA_DQ<13>")
	)
	(arc
		(start 381.96266 -270.687038)
		(mid 381.775462 -270.636895)
		(end 381.588264 -270.687038)
		(width 0.088646)
		(layer "In6.Cu")
		(net "M_G_CPU0_SA_DQ<13>")
	)
	(arc
		(start 383.453132 -270.695674)
		(mid 383.176657 -270.762994)
		(end 382.90246 -270.687038)
		(width 0.088646)
		(layer "In6.Cu")
		(net "M_G_CPU0_SA_DQ<13>")
	)
	(arc
		(start 385.72186 -270.687038)
		(mid 385.534662 -270.636895)
		(end 385.347464 -270.687038)
		(width 0.088646)
		(layer "In6.Cu")
		(net "M_G_CPU0_SA_DQ<13>")
	)
	(arc
		(start 376.701812 -271.02689)
		(mid 376.622442 -271.300624)
		(end 376.419618 -271.500854)
		(width 0.088646)
		(layer "In6.Cu")
		(net "M_G_CPU0_SA_DQ<13>")
	)
	(arc
		(start 380.633732 -270.695674)
		(mid 380.357257 -270.762994)
		(end 380.08306 -270.687038)
		(width 0.088646)
		(layer "In6.Cu")
		(net "M_G_CPU0_SA_DQ<13>")
	)
	(arc
		(start 379.693932 -270.695674)
		(mid 379.417457 -270.762994)
		(end 379.14326 -270.687038)
		(width 0.088646)
		(layer "In6.Cu")
		(net "M_G_CPU0_SA_DQ<13>")
	)
	(arc
		(start 379.14326 -270.687038)
		(mid 378.956062 -270.636895)
		(end 378.768864 -270.687038)
		(width 0.088646)
		(layer "In6.Cu")
		(net "M_G_CPU0_SA_DQ<13>")
	)
	(arc
		(start 377.814332 -270.695674)
		(mid 377.537857 -270.762994)
		(end 377.26366 -270.687038)
		(width 0.088646)
		(layer "In6.Cu")
		(net "M_G_CPU0_SA_DQ<13>")
	)
	(arc
		(start 381.588264 -270.687038)
		(mid 381.305562 -270.762814)
		(end 381.02286 -270.687038)
		(width 0.088646)
		(layer "In6.Cu")
		(net "M_G_CPU0_SA_DQ<13>")
	)
	(arc
		(start 376.880374 -270.692118)
		(mid 376.74946 -270.828478)
		(end 376.701812 -271.011396)
		(width 0.088646)
		(layer "In6.Cu")
		(net "M_G_CPU0_SA_DQ<13>")
	)
	(arc
		(start 375.848118 -271.497298)
		(mid 375.662663 -271.319103)
		(end 375.575322 -271.077182)
		(width 0.088646)
		(layer "In6.Cu")
		(net "M_G_CPU0_SA_DQ<13>")
	)
	(arc
		(start 378.20346 -270.687038)
		(mid 378.016262 -270.636895)
		(end 377.829064 -270.687038)
		(width 0.088646)
		(layer "In6.Cu")
		(net "M_G_CPU0_SA_DQ<13>")
	)
	(arc
		(start 378.754132 -270.695674)
		(mid 378.477657 -270.762994)
		(end 378.20346 -270.687038)
		(width 0.088646)
		(layer "In6.Cu")
		(net "M_G_CPU0_SA_DQ<13>")
	)
	(arc
		(start 386.272532 -270.695674)
		(mid 385.996057 -270.762994)
		(end 385.72186 -270.687038)
		(width 0.088646)
		(layer "In6.Cu")
		(net "M_G_CPU0_SA_DQ<13>")
	)
	(arc
		(start 385.332732 -270.695674)
		(mid 385.056257 -270.762994)
		(end 384.78206 -270.687038)
		(width 0.088646)
		(layer "In6.Cu")
		(net "M_G_CPU0_SA_DQ<13>")
	)
	(arc
		(start 386.474462 -270.636492)
		(mid 386.369261 -270.651629)
		(end 386.272532 -270.695674)
		(width 0.088646)
		(layer "In6.Cu")
		(net "M_G_CPU0_SA_DQ<13>")
	)
	(arc
		(start 382.513332 -270.695674)
		(mid 382.236857 -270.762994)
		(end 381.96266 -270.687038)
		(width 0.088646)
		(layer "In6.Cu")
		(net "M_G_CPU0_SA_DQ<13>")
	)
	(arc
		(start 376.419618 -271.500854)
		(mid 376.145419 -271.576689)
		(end 375.868946 -271.50949)
		(width 0.088646)
		(layer "In6.Cu")
		(net "M_G_CPU0_SA_DQ<13>")
	)
	(arc
		(start 384.78206 -270.687038)
		(mid 384.594862 -270.636895)
		(end 384.407664 -270.687038)
		(width 0.088646)
		(layer "In6.Cu")
		(net "M_G_CPU0_SA_DQ<13>")
	)
	(arc
		(start 382.90246 -270.687038)
		(mid 382.715262 -270.636895)
		(end 382.528064 -270.687038)
		(width 0.088646)
		(layer "In6.Cu")
		(net "M_G_CPU0_SA_DQ<13>")
	)
	(segment
		(start 444.47206 -301.016924)
		(end 442.880496 -301.016924)
		(width 0.20066)
		(layer "F.Cu")
		(net "M_G_CPU0_SA_DQ<12>")
	)
	(segment
		(start 436.928514 -301.01667)
		(end 435.823614 -301.01667)
		(width 0.20066)
		(layer "F.Cu")
		(net "M_G_CPU0_SA_DQ<12>")
	)
	(segment
		(start 439.112152 -301.077376)
		(end 438.924192 -301.265336)
		(width 0.20066)
		(layer "F.Cu")
		(net "M_G_CPU0_SA_DQ<12>")
	)
	(segment
		(start 374.726962 -271.289272)
		(end 374.727216 -271.825212)
		(width 0.20066)
		(layer "F.Cu")
		(net "M_G_CPU0_SA_DQ<12>")
	)
	(segment
		(start 442.44895 -300.585378)
		(end 442.038994 -300.585378)
		(width 0.20066)
		(layer "F.Cu")
		(net "M_G_CPU0_SA_DQ<12>")
	)
	(segment
		(start 438.448958 -301.265336)
		(end 438.200292 -301.01667)
		(width 0.20066)
		(layer "F.Cu")
		(net "M_G_CPU0_SA_DQ<12>")
	)
	(segment
		(start 442.032644 -300.591728)
		(end 439.775346 -300.591728)
		(width 0.1016)
		(layer "F.Cu")
		(net "M_G_CPU0_SA_DQ<12>")
	)
	(segment
		(start 438.924192 -301.265336)
		(end 438.448958 -301.265336)
		(width 0.20066)
		(layer "F.Cu")
		(net "M_G_CPU0_SA_DQ<12>")
	)
	(segment
		(start 444.472314 -301.01667)
		(end 444.47206 -301.016924)
		(width 0.20066)
		(layer "F.Cu")
		(net "M_G_CPU0_SA_DQ<12>")
	)
	(segment
		(start 439.230262 -300.591728)
		(end 439.112152 -300.709838)
		(width 0.20066)
		(layer "F.Cu")
		(net "M_G_CPU0_SA_DQ<12>")
	)
	(segment
		(start 439.775346 -300.591728)
		(end 439.757312 -300.591728)
		(width 0.101854)
		(layer "F.Cu")
		(net "M_G_CPU0_SA_DQ<12>")
	)
	(segment
		(start 442.038994 -300.585378)
		(end 442.032644 -300.591728)
		(width 0.1016)
		(layer "F.Cu")
		(net "M_G_CPU0_SA_DQ<12>")
	)
	(segment
		(start 442.880496 -301.016924)
		(end 442.44895 -300.585378)
		(width 0.20066)
		(layer "F.Cu")
		(net "M_G_CPU0_SA_DQ<12>")
	)
	(segment
		(start 438.200292 -301.01667)
		(end 436.928514 -301.01667)
		(width 0.20066)
		(layer "F.Cu")
		(net "M_G_CPU0_SA_DQ<12>")
	)
	(segment
		(start 439.757312 -300.591728)
		(end 439.230262 -300.591728)
		(width 0.20066)
		(layer "F.Cu")
		(net "M_G_CPU0_SA_DQ<12>")
	)
	(segment
		(start 439.112152 -300.709838)
		(end 439.112152 -301.077376)
		(width 0.20066)
		(layer "F.Cu")
		(net "M_G_CPU0_SA_DQ<12>")
	)
	(segment
		(start 410.596334 -291.783262)
		(end 410.413454 -291.600382)
		(width 0.18288)
		(layer "In6.Cu")
		(net "M_G_CPU0_SA_DQ<12>")
	)
	(segment
		(start 421.76827 -294.008302)
		(end 421.76827 -293.69512)
		(width 0.18288)
		(layer "In6.Cu")
		(net "M_G_CPU0_SA_DQ<12>")
	)
	(segment
		(start 380.184406 -271.497552)
		(end 380.178564 -271.500854)
		(width 0.088646)
		(layer "In6.Cu")
		(net "M_G_CPU0_SA_DQ<12>")
	)
	(segment
		(start 417.83381 -293.476426)
		(end 416.133534 -293.476426)
		(width 0.18288)
		(layer "In6.Cu")
		(net "M_G_CPU0_SA_DQ<12>")
	)
	(segment
		(start 430.939194 -297.909488)
		(end 430.089056 -297.909488)
		(width 0.18288)
		(layer "In6.Cu")
		(net "M_G_CPU0_SA_DQ<12>")
	)
	(segment
		(start 421.015414 -292.942264)
		(end 420.348918 -292.942264)
		(width 0.18288)
		(layer "In6.Cu")
		(net "M_G_CPU0_SA_DQ<12>")
	)
	(segment
		(start 388.352538 -273.035268)
		(end 387.319266 -272.001996)
		(width 0.088646)
		(layer "In6.Cu")
		(net "M_G_CPU0_SA_DQ<12>")
	)
	(segment
		(start 435.29885 -301.01667)
		(end 434.749194 -300.467014)
		(width 0.18288)
		(layer "In6.Cu")
		(net "M_G_CPU0_SA_DQ<12>")
	)
	(segment
		(start 383.002282 -271.498314)
		(end 382.997964 -271.500854)
		(width 0.088646)
		(layer "In6.Cu")
		(net "M_G_CPU0_SA_DQ<12>")
	)
	(segment
		(start 407.858214 -290.15055)
		(end 407.407364 -290.15055)
		(width 0.18288)
		(layer "In6.Cu")
		(net "M_G_CPU0_SA_DQ<12>")
	)
	(segment
		(start 405.38146 -290.15055)
		(end 403.45487 -288.22396)
		(width 0.18288)
		(layer "In6.Cu")
		(net "M_G_CPU0_SA_DQ<12>")
	)
	(segment
		(start 382.997964 -271.500854)
		(end 382.992122 -271.50441)
		(width 0.088646)
		(layer "In6.Cu")
		(net "M_G_CPU0_SA_DQ<12>")
	)
	(segment
		(start 378.304806 -271.497552)
		(end 378.298964 -271.500854)
		(width 0.088646)
		(layer "In6.Cu")
		(net "M_G_CPU0_SA_DQ<12>")
	)
	(segment
		(start 412.253938 -290.95573)
		(end 411.289754 -290.95573)
		(width 0.18288)
		(layer "In6.Cu")
		(net "M_G_CPU0_SA_DQ<12>")
	)
	(segment
		(start 407.041604 -290.989004)
		(end 406.713944 -290.989004)
		(width 0.18288)
		(layer "In6.Cu")
		(net "M_G_CPU0_SA_DQ<12>")
	)
	(segment
		(start 403.45487 -280.437336)
		(end 396.46479 -273.447256)
		(width 0.18288)
		(layer "In6.Cu")
		(net "M_G_CPU0_SA_DQ<12>")
	)
	(segment
		(start 384.327146 -271.50949)
		(end 384.312414 -271.500854)
		(width 0.088646)
		(layer "In6.Cu")
		(net "M_G_CPU0_SA_DQ<12>")
	)
	(segment
		(start 411.106874 -291.13861)
		(end 411.106874 -291.600382)
		(width 0.18288)
		(layer "In6.Cu")
		(net "M_G_CPU0_SA_DQ<12>")
	)
	(segment
		(start 406.531064 -290.806124)
		(end 406.531064 -290.33343)
		(width 0.18288)
		(layer "In6.Cu")
		(net "M_G_CPU0_SA_DQ<12>")
	)
	(segment
		(start 390.298686 -273.447256)
		(end 389.304022 -273.035268)
		(width 0.18288)
		(layer "In6.Cu")
		(net "M_G_CPU0_SA_DQ<12>")
	)
	(segment
		(start 426.981874 -295.183306)
		(end 425.851828 -295.183306)
		(width 0.18288)
		(layer "In6.Cu")
		(net "M_G_CPU0_SA_DQ<12>")
	)
	(segment
		(start 375.479818 -272.14957)
		(end 375.452132 -272.133314)
		(width 0.088646)
		(layer "In6.Cu")
		(net "M_G_CPU0_SA_DQ<12>")
	)
	(segment
		(start 427.967394 -296.168826)
		(end 426.981874 -295.183306)
		(width 0.18288)
		(layer "In6.Cu")
		(net "M_G_CPU0_SA_DQ<12>")
	)
	(segment
		(start 381.124206 -271.497552)
		(end 381.118364 -271.500854)
		(width 0.088646)
		(layer "In6.Cu")
		(net "M_G_CPU0_SA_DQ<12>")
	)
	(segment
		(start 418.52723 -294.403272)
		(end 418.15385 -294.403272)
		(width 0.18288)
		(layer "In6.Cu")
		(net "M_G_CPU0_SA_DQ<12>")
	)
	(segment
		(start 416.133534 -293.476426)
		(end 415.891726 -293.234618)
		(width 0.18288)
		(layer "In6.Cu")
		(net "M_G_CPU0_SA_DQ<12>")
	)
	(segment
		(start 375.452132 -272.133314)
		(end 374.727216 -271.825212)
		(width 0.088646)
		(layer "In6.Cu")
		(net "M_G_CPU0_SA_DQ<12>")
	)
	(segment
		(start 419.814756 -293.476426)
		(end 418.84727 -293.476426)
		(width 0.18288)
		(layer "In6.Cu")
		(net "M_G_CPU0_SA_DQ<12>")
	)
	(segment
		(start 410.413454 -291.13861)
		(end 410.230574 -290.95573)
		(width 0.18288)
		(layer "In6.Cu")
		(net "M_G_CPU0_SA_DQ<12>")
	)
	(segment
		(start 407.224484 -290.33343)
		(end 407.224484 -290.806124)
		(width 0.18288)
		(layer "In6.Cu")
		(net "M_G_CPU0_SA_DQ<12>")
	)
	(segment
		(start 410.413454 -291.600382)
		(end 410.413454 -291.13861)
		(width 0.18288)
		(layer "In6.Cu")
		(net "M_G_CPU0_SA_DQ<12>")
	)
	(segment
		(start 382.058164 -271.500854)
		(end 382.052322 -271.50441)
		(width 0.088646)
		(layer "In6.Cu")
		(net "M_G_CPU0_SA_DQ<12>")
	)
	(segment
		(start 422.402254 -294.642286)
		(end 421.76827 -294.008302)
		(width 0.18288)
		(layer "In6.Cu")
		(net "M_G_CPU0_SA_DQ<12>")
	)
	(segment
		(start 415.891726 -293.234618)
		(end 415.891726 -292.367208)
		(width 0.18288)
		(layer "In6.Cu")
		(net "M_G_CPU0_SA_DQ<12>")
	)
	(segment
		(start 410.923994 -291.783262)
		(end 410.596334 -291.783262)
		(width 0.18288)
		(layer "In6.Cu")
		(net "M_G_CPU0_SA_DQ<12>")
	)
	(segment
		(start 411.289754 -290.95573)
		(end 411.106874 -291.13861)
		(width 0.18288)
		(layer "In6.Cu")
		(net "M_G_CPU0_SA_DQ<12>")
	)
	(segment
		(start 415.891726 -292.367208)
		(end 415.366454 -291.841936)
		(width 0.18288)
		(layer "In6.Cu")
		(net "M_G_CPU0_SA_DQ<12>")
	)
	(segment
		(start 410.230574 -290.95573)
		(end 408.663394 -290.95573)
		(width 0.18288)
		(layer "In6.Cu")
		(net "M_G_CPU0_SA_DQ<12>")
	)
	(segment
		(start 389.304022 -273.035268)
		(end 388.535672 -273.035268)
		(width 0.18288)
		(layer "In6.Cu")
		(net "M_G_CPU0_SA_DQ<12>")
	)
	(segment
		(start 413.986472 -291.537898)
		(end 412.836106 -291.537898)
		(width 0.18288)
		(layer "In6.Cu")
		(net "M_G_CPU0_SA_DQ<12>")
	)
	(segment
		(start 407.224484 -290.806124)
		(end 407.041604 -290.989004)
		(width 0.18288)
		(layer "In6.Cu")
		(net "M_G_CPU0_SA_DQ<12>")
	)
	(segment
		(start 418.68725 -293.636446)
		(end 418.68725 -294.243252)
		(width 0.18288)
		(layer "In6.Cu")
		(net "M_G_CPU0_SA_DQ<12>")
	)
	(segment
		(start 388.535672 -273.035268)
		(end 388.352538 -273.035268)
		(width 0.088646)
		(layer "In6.Cu")
		(net "M_G_CPU0_SA_DQ<12>")
	)
	(segment
		(start 425.851828 -295.183306)
		(end 425.310808 -294.642286)
		(width 0.18288)
		(layer "In6.Cu")
		(net "M_G_CPU0_SA_DQ<12>")
	)
	(segment
		(start 375.868946 -272.140934)
		(end 375.854214 -272.14957)
		(width 0.088646)
		(layer "In6.Cu")
		(net "M_G_CPU0_SA_DQ<12>")
	)
	(segment
		(start 432.568096 -298.810426)
		(end 431.840132 -298.810426)
		(width 0.18288)
		(layer "In6.Cu")
		(net "M_G_CPU0_SA_DQ<12>")
	)
	(segment
		(start 417.99383 -293.636446)
		(end 417.83381 -293.476426)
		(width 0.18288)
		(layer "In6.Cu")
		(net "M_G_CPU0_SA_DQ<12>")
	)
	(segment
		(start 420.348918 -292.942264)
		(end 419.814756 -293.476426)
		(width 0.18288)
		(layer "In6.Cu")
		(net "M_G_CPU0_SA_DQ<12>")
	)
	(segment
		(start 417.99383 -294.243252)
		(end 417.99383 -293.636446)
		(width 0.18288)
		(layer "In6.Cu")
		(net "M_G_CPU0_SA_DQ<12>")
	)
	(segment
		(start 379.238764 -271.500854)
		(end 379.232922 -271.50441)
		(width 0.088646)
		(layer "In6.Cu")
		(net "M_G_CPU0_SA_DQ<12>")
	)
	(segment
		(start 415.366454 -291.841936)
		(end 414.29051 -291.841936)
		(width 0.18288)
		(layer "In6.Cu")
		(net "M_G_CPU0_SA_DQ<12>")
	)
	(segment
		(start 425.310808 -294.642286)
		(end 422.402254 -294.642286)
		(width 0.18288)
		(layer "In6.Cu")
		(net "M_G_CPU0_SA_DQ<12>")
	)
	(segment
		(start 434.749194 -300.467014)
		(end 434.224684 -300.467014)
		(width 0.18288)
		(layer "In6.Cu")
		(net "M_G_CPU0_SA_DQ<12>")
	)
	(segment
		(start 387.140704 -271.505934)
		(end 387.131814 -271.500854)
		(width 0.088646)
		(layer "In6.Cu")
		(net "M_G_CPU0_SA_DQ<12>")
	)
	(segment
		(start 382.064006 -271.497552)
		(end 382.058164 -271.500854)
		(width 0.088646)
		(layer "In6.Cu")
		(net "M_G_CPU0_SA_DQ<12>")
	)
	(segment
		(start 411.106874 -291.600382)
		(end 410.923994 -291.783262)
		(width 0.18288)
		(layer "In6.Cu")
		(net "M_G_CPU0_SA_DQ<12>")
	)
	(segment
		(start 407.407364 -290.15055)
		(end 407.224484 -290.33343)
		(width 0.18288)
		(layer "In6.Cu")
		(net "M_G_CPU0_SA_DQ<12>")
	)
	(segment
		(start 412.836106 -291.537898)
		(end 412.253938 -290.95573)
		(width 0.18288)
		(layer "In6.Cu")
		(net "M_G_CPU0_SA_DQ<12>")
	)
	(segment
		(start 406.713944 -290.989004)
		(end 406.531064 -290.806124)
		(width 0.18288)
		(layer "In6.Cu")
		(net "M_G_CPU0_SA_DQ<12>")
	)
	(segment
		(start 387.319266 -272.001996)
		(end 387.319266 -271.825212)
		(width 0.088646)
		(layer "In6.Cu")
		(net "M_G_CPU0_SA_DQ<12>")
	)
	(segment
		(start 435.823614 -301.01667)
		(end 435.29885 -301.01667)
		(width 0.18288)
		(layer "In6.Cu")
		(net "M_G_CPU0_SA_DQ<12>")
	)
	(segment
		(start 406.348184 -290.15055)
		(end 405.38146 -290.15055)
		(width 0.18288)
		(layer "In6.Cu")
		(net "M_G_CPU0_SA_DQ<12>")
	)
	(segment
		(start 383.938018 -271.500854)
		(end 383.937764 -271.500854)
		(width 0.088646)
		(layer "In6.Cu")
		(net "M_G_CPU0_SA_DQ<12>")
	)
	(segment
		(start 421.76827 -293.69512)
		(end 421.015414 -292.942264)
		(width 0.18288)
		(layer "In6.Cu")
		(net "M_G_CPU0_SA_DQ<12>")
	)
	(segment
		(start 418.84727 -293.476426)
		(end 418.68725 -293.636446)
		(width 0.18288)
		(layer "In6.Cu")
		(net "M_G_CPU0_SA_DQ<12>")
	)
	(segment
		(start 408.663394 -290.95573)
		(end 407.858214 -290.15055)
		(width 0.18288)
		(layer "In6.Cu")
		(net "M_G_CPU0_SA_DQ<12>")
	)
	(segment
		(start 414.29051 -291.841936)
		(end 413.986472 -291.537898)
		(width 0.18288)
		(layer "In6.Cu")
		(net "M_G_CPU0_SA_DQ<12>")
	)
	(segment
		(start 381.118364 -271.500854)
		(end 381.112522 -271.50441)
		(width 0.088646)
		(layer "In6.Cu")
		(net "M_G_CPU0_SA_DQ<12>")
	)
	(segment
		(start 380.178564 -271.500854)
		(end 380.172722 -271.50441)
		(width 0.088646)
		(layer "In6.Cu")
		(net "M_G_CPU0_SA_DQ<12>")
	)
	(segment
		(start 406.531064 -290.33343)
		(end 406.348184 -290.15055)
		(width 0.18288)
		(layer "In6.Cu")
		(net "M_G_CPU0_SA_DQ<12>")
	)
	(segment
		(start 385.266946 -271.50949)
		(end 385.252214 -271.500854)
		(width 0.088646)
		(layer "In6.Cu")
		(net "M_G_CPU0_SA_DQ<12>")
	)
	(segment
		(start 378.298964 -271.500854)
		(end 378.293122 -271.50441)
		(width 0.088646)
		(layer "In6.Cu")
		(net "M_G_CPU0_SA_DQ<12>")
	)
	(segment
		(start 403.45487 -288.22396)
		(end 403.45487 -280.437336)
		(width 0.18288)
		(layer "In6.Cu")
		(net "M_G_CPU0_SA_DQ<12>")
	)
	(segment
		(start 430.089056 -297.909488)
		(end 428.348394 -296.168826)
		(width 0.18288)
		(layer "In6.Cu")
		(net "M_G_CPU0_SA_DQ<12>")
	)
	(segment
		(start 379.244606 -271.497552)
		(end 379.238764 -271.500854)
		(width 0.088646)
		(layer "In6.Cu")
		(net "M_G_CPU0_SA_DQ<12>")
	)
	(segment
		(start 434.224684 -300.467014)
		(end 432.568096 -298.810426)
		(width 0.18288)
		(layer "In6.Cu")
		(net "M_G_CPU0_SA_DQ<12>")
	)
	(segment
		(start 418.15385 -294.403272)
		(end 417.99383 -294.243252)
		(width 0.18288)
		(layer "In6.Cu")
		(net "M_G_CPU0_SA_DQ<12>")
	)
	(segment
		(start 428.348394 -296.168826)
		(end 427.967394 -296.168826)
		(width 0.18288)
		(layer "In6.Cu")
		(net "M_G_CPU0_SA_DQ<12>")
	)
	(segment
		(start 431.840132 -298.810426)
		(end 430.939194 -297.909488)
		(width 0.18288)
		(layer "In6.Cu")
		(net "M_G_CPU0_SA_DQ<12>")
	)
	(segment
		(start 396.46479 -273.447256)
		(end 390.298686 -273.447256)
		(width 0.18288)
		(layer "In6.Cu")
		(net "M_G_CPU0_SA_DQ<12>")
	)
	(segment
		(start 386.206746 -271.50949)
		(end 386.192014 -271.500854)
		(width 0.088646)
		(layer "In6.Cu")
		(net "M_G_CPU0_SA_DQ<12>")
	)
	(segment
		(start 418.68725 -294.243252)
		(end 418.52723 -294.403272)
		(width 0.18288)
		(layer "In6.Cu")
		(net "M_G_CPU0_SA_DQ<12>")
	)
	(arc
		(start 378.673614 -271.500854)
		(mid 378.48966 -271.450725)
		(end 378.304806 -271.497552)
		(width 0.088646)
		(layer "In6.Cu")
		(net "M_G_CPU0_SA_DQ<12>")
	)
	(arc
		(start 383.937764 -271.500854)
		(mid 383.655206 -271.576503)
		(end 383.372614 -271.500854)
		(width 0.088646)
		(layer "In6.Cu")
		(net "M_G_CPU0_SA_DQ<12>")
	)
	(arc
		(start 379.232922 -271.50441)
		(mid 378.952787 -271.576726)
		(end 378.673614 -271.500854)
		(width 0.088646)
		(layer "In6.Cu")
		(net "M_G_CPU0_SA_DQ<12>")
	)
	(arc
		(start 380.172722 -271.50441)
		(mid 379.892587 -271.576726)
		(end 379.613414 -271.500854)
		(width 0.088646)
		(layer "In6.Cu")
		(net "M_G_CPU0_SA_DQ<12>")
	)
	(arc
		(start 381.493014 -271.500854)
		(mid 381.30906 -271.450725)
		(end 381.124206 -271.497552)
		(width 0.088646)
		(layer "In6.Cu")
		(net "M_G_CPU0_SA_DQ<12>")
	)
	(arc
		(start 376.419618 -272.14957)
		(mid 376.145389 -272.073645)
		(end 375.868946 -272.140934)
		(width 0.088646)
		(layer "In6.Cu")
		(net "M_G_CPU0_SA_DQ<12>")
	)
	(arc
		(start 385.817618 -271.500854)
		(mid 385.543419 -271.576689)
		(end 385.266946 -271.50949)
		(width 0.088646)
		(layer "In6.Cu")
		(net "M_G_CPU0_SA_DQ<12>")
	)
	(arc
		(start 377.733814 -271.500854)
		(mid 377.542376 -271.450605)
		(end 377.352052 -271.504918)
		(width 0.088646)
		(layer "In6.Cu")
		(net "M_G_CPU0_SA_DQ<12>")
	)
	(arc
		(start 377.352052 -271.504918)
		(mid 377.25696 -271.587513)
		(end 377.194572 -271.696942)
		(width 0.088646)
		(layer "In6.Cu")
		(net "M_G_CPU0_SA_DQ<12>")
	)
	(arc
		(start 383.372614 -271.500854)
		(mid 383.187777 -271.450593)
		(end 383.002282 -271.498314)
		(width 0.088646)
		(layer "In6.Cu")
		(net "M_G_CPU0_SA_DQ<12>")
	)
	(arc
		(start 384.877818 -271.500854)
		(mid 384.603619 -271.576689)
		(end 384.327146 -271.50949)
		(width 0.088646)
		(layer "In6.Cu")
		(net "M_G_CPU0_SA_DQ<12>")
	)
	(arc
		(start 382.992122 -271.50441)
		(mid 382.711987 -271.576726)
		(end 382.432814 -271.500854)
		(width 0.088646)
		(layer "In6.Cu")
		(net "M_G_CPU0_SA_DQ<12>")
	)
	(arc
		(start 386.757418 -271.500854)
		(mid 386.483219 -271.576689)
		(end 386.206746 -271.50949)
		(width 0.088646)
		(layer "In6.Cu")
		(net "M_G_CPU0_SA_DQ<12>")
	)
	(arc
		(start 376.794014 -272.14957)
		(mid 376.606816 -272.199713)
		(end 376.419618 -272.14957)
		(width 0.088646)
		(layer "In6.Cu")
		(net "M_G_CPU0_SA_DQ<12>")
	)
	(arc
		(start 377.122182 -271.836388)
		(mid 377.084097 -271.927279)
		(end 377.017534 -271.999964)
		(width 0.088646)
		(layer "In6.Cu")
		(net "M_G_CPU0_SA_DQ<12>")
	)
	(arc
		(start 379.613414 -271.500854)
		(mid 379.42946 -271.450725)
		(end 379.244606 -271.497552)
		(width 0.088646)
		(layer "In6.Cu")
		(net "M_G_CPU0_SA_DQ<12>")
	)
	(arc
		(start 385.252214 -271.500854)
		(mid 385.065016 -271.450711)
		(end 384.877818 -271.500854)
		(width 0.088646)
		(layer "In6.Cu")
		(net "M_G_CPU0_SA_DQ<12>")
	)
	(arc
		(start 377.017534 -271.999964)
		(mid 376.908262 -272.078484)
		(end 376.794014 -272.14957)
		(width 0.088646)
		(layer "In6.Cu")
		(net "M_G_CPU0_SA_DQ<12>")
	)
	(arc
		(start 387.319266 -271.825212)
		(mid 387.271587 -271.642312)
		(end 387.140704 -271.505934)
		(width 0.088646)
		(layer "In6.Cu")
		(net "M_G_CPU0_SA_DQ<12>")
	)
	(arc
		(start 378.293122 -271.50441)
		(mid 378.012987 -271.576726)
		(end 377.733814 -271.500854)
		(width 0.088646)
		(layer "In6.Cu")
		(net "M_G_CPU0_SA_DQ<12>")
	)
	(arc
		(start 382.052322 -271.50441)
		(mid 381.772187 -271.576726)
		(end 381.493014 -271.500854)
		(width 0.088646)
		(layer "In6.Cu")
		(net "M_G_CPU0_SA_DQ<12>")
	)
	(arc
		(start 381.112522 -271.50441)
		(mid 380.832387 -271.576726)
		(end 380.553214 -271.500854)
		(width 0.088646)
		(layer "In6.Cu")
		(net "M_G_CPU0_SA_DQ<12>")
	)
	(arc
		(start 384.312414 -271.500854)
		(mid 384.125216 -271.450711)
		(end 383.938018 -271.500854)
		(width 0.088646)
		(layer "In6.Cu")
		(net "M_G_CPU0_SA_DQ<12>")
	)
	(arc
		(start 382.432814 -271.500854)
		(mid 382.24886 -271.450725)
		(end 382.064006 -271.497552)
		(width 0.088646)
		(layer "In6.Cu")
		(net "M_G_CPU0_SA_DQ<12>")
	)
	(arc
		(start 380.553214 -271.500854)
		(mid 380.36926 -271.450725)
		(end 380.184406 -271.497552)
		(width 0.088646)
		(layer "In6.Cu")
		(net "M_G_CPU0_SA_DQ<12>")
	)
	(arc
		(start 387.131814 -271.500854)
		(mid 386.944616 -271.450711)
		(end 386.757418 -271.500854)
		(width 0.088646)
		(layer "In6.Cu")
		(net "M_G_CPU0_SA_DQ<12>")
	)
	(arc
		(start 375.854214 -272.14957)
		(mid 375.667016 -272.199713)
		(end 375.479818 -272.14957)
		(width 0.088646)
		(layer "In6.Cu")
		(net "M_G_CPU0_SA_DQ<12>")
	)
	(arc
		(start 386.192014 -271.500854)
		(mid 386.004816 -271.450711)
		(end 385.817618 -271.500854)
		(width 0.088646)
		(layer "In6.Cu")
		(net "M_G_CPU0_SA_DQ<12>")
	)
	(arc
		(start 377.194572 -271.696942)
		(mid 377.162918 -271.769022)
		(end 377.122182 -271.836388)
		(width 0.088646)
		(layer "In6.Cu")
		(net "M_G_CPU0_SA_DQ<12>")
	)
	(segment
		(start 376.606562 -273.452844)
		(end 376.606816 -273.453098)
		(width 0.20066)
		(layer "F.Cu")
		(net "M_G_CPU0_SA_DQ<11>")
	)
	(segment
		(start 445.482726 -304.853848)
		(end 446.163954 -304.853848)
		(width 0.20066)
		(layer "F.Cu")
		(net "M_G_CPU0_SA_DQ<11>")
	)
	(segment
		(start 446.602104 -304.164746)
		(end 446.986152 -304.164746)
		(width 0.20066)
		(layer "F.Cu")
		(net "M_G_CPU0_SA_DQ<11>")
	)
	(segment
		(start 442.726826 -304.416714)
		(end 443.15888 -304.848768)
		(width 0.20066)
		(layer "F.Cu")
		(net "M_G_CPU0_SA_DQ<11>")
	)
	(segment
		(start 376.606562 -272.917158)
		(end 376.606562 -273.452844)
		(width 0.20066)
		(layer "F.Cu")
		(net "M_G_CPU0_SA_DQ<11>")
	)
	(segment
		(start 446.986152 -304.164746)
		(end 447.23812 -304.416714)
		(width 0.20066)
		(layer "F.Cu")
		(net "M_G_CPU0_SA_DQ<11>")
	)
	(segment
		(start 447.23812 -304.416714)
		(end 448.572382 -304.416714)
		(width 0.20066)
		(layer "F.Cu")
		(net "M_G_CPU0_SA_DQ<11>")
	)
	(segment
		(start 446.367916 -304.649886)
		(end 446.367916 -304.398934)
		(width 0.20066)
		(layer "F.Cu")
		(net "M_G_CPU0_SA_DQ<11>")
	)
	(segment
		(start 441.028582 -304.416714)
		(end 442.726826 -304.416714)
		(width 0.20066)
		(layer "F.Cu")
		(net "M_G_CPU0_SA_DQ<11>")
	)
	(segment
		(start 445.470534 -304.841656)
		(end 445.482726 -304.853848)
		(width 0.1016)
		(layer "F.Cu")
		(net "M_G_CPU0_SA_DQ<11>")
	)
	(segment
		(start 446.163954 -304.853848)
		(end 446.367916 -304.649886)
		(width 0.20066)
		(layer "F.Cu")
		(net "M_G_CPU0_SA_DQ<11>")
	)
	(segment
		(start 443.455552 -304.848768)
		(end 443.462664 -304.841656)
		(width 0.1016)
		(layer "F.Cu")
		(net "M_G_CPU0_SA_DQ<11>")
	)
	(segment
		(start 443.462664 -304.841656)
		(end 445.470534 -304.841656)
		(width 0.1016)
		(layer "F.Cu")
		(net "M_G_CPU0_SA_DQ<11>")
	)
	(segment
		(start 443.450726 -304.848768)
		(end 443.455552 -304.848768)
		(width 0.101854)
		(layer "F.Cu")
		(net "M_G_CPU0_SA_DQ<11>")
	)
	(segment
		(start 446.367916 -304.398934)
		(end 446.602104 -304.164746)
		(width 0.20066)
		(layer "F.Cu")
		(net "M_G_CPU0_SA_DQ<11>")
	)
	(segment
		(start 443.15888 -304.848768)
		(end 443.450726 -304.848768)
		(width 0.20066)
		(layer "F.Cu")
		(net "M_G_CPU0_SA_DQ<11>")
	)
	(segment
		(start 439.923682 -304.416714)
		(end 441.028582 -304.416714)
		(width 0.20066)
		(layer "F.Cu")
		(net "M_G_CPU0_SA_DQ<11>")
	)
	(segment
		(start 405.238712 -294.03548)
		(end 401.34159 -290.138358)
		(width 0.18288)
		(layer "In6.Cu")
		(net "M_G_CPU0_SA_DQ<11>")
	)
	(segment
		(start 439.499248 -303.99228)
		(end 437.353964 -303.99228)
		(width 0.18288)
		(layer "In6.Cu")
		(net "M_G_CPU0_SA_DQ<11>")
	)
	(segment
		(start 429.7299 -301.439072)
		(end 428.917354 -300.626526)
		(width 0.18288)
		(layer "In6.Cu")
		(net "M_G_CPU0_SA_DQ<11>")
	)
	(segment
		(start 427.319694 -299.889926)
		(end 426.964094 -299.889926)
		(width 0.18288)
		(layer "In6.Cu")
		(net "M_G_CPU0_SA_DQ<11>")
	)
	(segment
		(start 378.304806 -273.781012)
		(end 378.298964 -273.777456)
		(width 0.088646)
		(layer "In6.Cu")
		(net "M_G_CPU0_SA_DQ<11>")
	)
	(segment
		(start 401.34159 -290.138358)
		(end 401.34159 -281.314652)
		(width 0.18288)
		(layer "In6.Cu")
		(net "M_G_CPU0_SA_DQ<11>")
	)
	(segment
		(start 422.53535 -298.892468)
		(end 421.685466 -298.042584)
		(width 0.18288)
		(layer "In6.Cu")
		(net "M_G_CPU0_SA_DQ<11>")
	)
	(segment
		(start 437.193944 -304.1523)
		(end 437.193944 -304.682652)
		(width 0.18288)
		(layer "In6.Cu")
		(net "M_G_CPU0_SA_DQ<11>")
	)
	(segment
		(start 418.03701 -297.995848)
		(end 417.87699 -298.155868)
		(width 0.18288)
		(layer "In6.Cu")
		(net "M_G_CPU0_SA_DQ<11>")
	)
	(segment
		(start 381.507746 -273.76882)
		(end 381.493014 -273.777456)
		(width 0.088646)
		(layer "In6.Cu")
		(net "M_G_CPU0_SA_DQ<11>")
	)
	(segment
		(start 421.685466 -298.042584)
		(end 419.756336 -298.042584)
		(width 0.18288)
		(layer "In6.Cu")
		(net "M_G_CPU0_SA_DQ<11>")
	)
	(segment
		(start 436.340504 -303.99228)
		(end 434.919882 -303.99228)
		(width 0.18288)
		(layer "In6.Cu")
		(net "M_G_CPU0_SA_DQ<11>")
	)
	(segment
		(start 436.500524 -304.1523)
		(end 436.340504 -303.99228)
		(width 0.18288)
		(layer "In6.Cu")
		(net "M_G_CPU0_SA_DQ<11>")
	)
	(segment
		(start 418.73043 -297.995848)
		(end 418.73043 -297.712892)
		(width 0.18288)
		(layer "In6.Cu")
		(net "M_G_CPU0_SA_DQ<11>")
	)
	(segment
		(start 377.359164 -273.777456)
		(end 376.9614 -273.548094)
		(width 0.088646)
		(layer "In6.Cu")
		(net "M_G_CPU0_SA_DQ<11>")
	)
	(segment
		(start 383.383028 -273.77136)
		(end 383.372614 -273.777456)
		(width 0.088646)
		(layer "In6.Cu")
		(net "M_G_CPU0_SA_DQ<11>")
	)
	(segment
		(start 411.14218 -295.491408)
		(end 410.321506 -294.670734)
		(width 0.18288)
		(layer "In6.Cu")
		(net "M_G_CPU0_SA_DQ<11>")
	)
	(segment
		(start 418.03701 -297.712892)
		(end 418.03701 -297.995848)
		(width 0.18288)
		(layer "In6.Cu")
		(net "M_G_CPU0_SA_DQ<11>")
	)
	(segment
		(start 437.353964 -303.99228)
		(end 437.193944 -304.1523)
		(width 0.18288)
		(layer "In6.Cu")
		(net "M_G_CPU0_SA_DQ<11>")
	)
	(segment
		(start 419.756336 -298.042584)
		(end 419.643052 -298.155868)
		(width 0.18288)
		(layer "In6.Cu")
		(net "M_G_CPU0_SA_DQ<11>")
	)
	(segment
		(start 378.688346 -273.76882)
		(end 378.673614 -273.777456)
		(width 0.088646)
		(layer "In6.Cu")
		(net "M_G_CPU0_SA_DQ<11>")
	)
	(segment
		(start 434.919882 -303.99228)
		(end 434.805582 -304.10658)
		(width 0.18288)
		(layer "In6.Cu")
		(net "M_G_CPU0_SA_DQ<11>")
	)
	(segment
		(start 418.89045 -298.155868)
		(end 418.73043 -297.995848)
		(width 0.18288)
		(layer "In6.Cu")
		(net "M_G_CPU0_SA_DQ<11>")
	)
	(segment
		(start 425.966636 -298.892468)
		(end 422.53535 -298.892468)
		(width 0.18288)
		(layer "In6.Cu")
		(net "M_G_CPU0_SA_DQ<11>")
	)
	(segment
		(start 419.643052 -298.155868)
		(end 418.89045 -298.155868)
		(width 0.18288)
		(layer "In6.Cu")
		(net "M_G_CPU0_SA_DQ<11>")
	)
	(segment
		(start 378.298964 -273.777456)
		(end 378.293122 -273.774154)
		(width 0.088646)
		(layer "In6.Cu")
		(net "M_G_CPU0_SA_DQ<11>")
	)
	(segment
		(start 418.73043 -297.712892)
		(end 418.57041 -297.552872)
		(width 0.18288)
		(layer "In6.Cu")
		(net "M_G_CPU0_SA_DQ<11>")
	)
	(segment
		(start 439.923682 -304.416714)
		(end 439.499248 -303.99228)
		(width 0.18288)
		(layer "In6.Cu")
		(net "M_G_CPU0_SA_DQ<11>")
	)
	(segment
		(start 388.139686 -274.819364)
		(end 387.022086 -273.701764)
		(width 0.088646)
		(layer "In6.Cu")
		(net "M_G_CPU0_SA_DQ<11>")
	)
	(segment
		(start 388.97306 -275.18614)
		(end 388.535672 -275.18614)
		(width 0.18288)
		(layer "In6.Cu")
		(net "M_G_CPU0_SA_DQ<11>")
	)
	(segment
		(start 379.628146 -273.76882)
		(end 379.613414 -273.777456)
		(width 0.088646)
		(layer "In6.Cu")
		(net "M_G_CPU0_SA_DQ<11>")
	)
	(segment
		(start 426.964094 -299.889926)
		(end 425.966636 -298.892468)
		(width 0.18288)
		(layer "In6.Cu")
		(net "M_G_CPU0_SA_DQ<11>")
	)
	(segment
		(start 437.033924 -304.842672)
		(end 436.660544 -304.842672)
		(width 0.18288)
		(layer "In6.Cu")
		(net "M_G_CPU0_SA_DQ<11>")
	)
	(segment
		(start 387.022086 -273.701764)
		(end 386.474462 -273.701764)
		(width 0.088646)
		(layer "In6.Cu")
		(net "M_G_CPU0_SA_DQ<11>")
	)
	(segment
		(start 417.87699 -298.155868)
		(end 416.886136 -298.155868)
		(width 0.18288)
		(layer "In6.Cu")
		(net "M_G_CPU0_SA_DQ<11>")
	)
	(segment
		(start 389.877046 -275.560536)
		(end 388.97306 -275.18614)
		(width 0.18288)
		(layer "In6.Cu")
		(net "M_G_CPU0_SA_DQ<11>")
	)
	(segment
		(start 436.500524 -304.682652)
		(end 436.500524 -304.1523)
		(width 0.18288)
		(layer "In6.Cu")
		(net "M_G_CPU0_SA_DQ<11>")
	)
	(segment
		(start 410.321506 -294.670734)
		(end 409.327096 -294.670734)
		(width 0.18288)
		(layer "In6.Cu")
		(net "M_G_CPU0_SA_DQ<11>")
	)
	(segment
		(start 401.34159 -281.314652)
		(end 395.58849 -275.560536)
		(width 0.18288)
		(layer "In6.Cu")
		(net "M_G_CPU0_SA_DQ<11>")
	)
	(segment
		(start 382.447546 -273.76882)
		(end 382.432814 -273.777456)
		(width 0.088646)
		(layer "In6.Cu")
		(net "M_G_CPU0_SA_DQ<11>")
	)
	(segment
		(start 430.8729 -301.439072)
		(end 429.7299 -301.439072)
		(width 0.18288)
		(layer "In6.Cu")
		(net "M_G_CPU0_SA_DQ<11>")
	)
	(segment
		(start 434.368194 -304.10658)
		(end 433.84978 -303.588166)
		(width 0.18288)
		(layer "In6.Cu")
		(net "M_G_CPU0_SA_DQ<11>")
	)
	(segment
		(start 388.139686 -274.968716)
		(end 388.139686 -274.819364)
		(width 0.088646)
		(layer "In6.Cu")
		(net "M_G_CPU0_SA_DQ<11>")
	)
	(segment
		(start 408.691842 -294.03548)
		(end 405.238712 -294.03548)
		(width 0.18288)
		(layer "In6.Cu")
		(net "M_G_CPU0_SA_DQ<11>")
	)
	(segment
		(start 415.31413 -297.320716)
		(end 413.484822 -295.491408)
		(width 0.18288)
		(layer "In6.Cu")
		(net "M_G_CPU0_SA_DQ<11>")
	)
	(segment
		(start 418.57041 -297.552872)
		(end 418.19703 -297.552872)
		(width 0.18288)
		(layer "In6.Cu")
		(net "M_G_CPU0_SA_DQ<11>")
	)
	(segment
		(start 433.021994 -303.588166)
		(end 430.8729 -301.439072)
		(width 0.18288)
		(layer "In6.Cu")
		(net "M_G_CPU0_SA_DQ<11>")
	)
	(segment
		(start 418.19703 -297.552872)
		(end 418.03701 -297.712892)
		(width 0.18288)
		(layer "In6.Cu")
		(net "M_G_CPU0_SA_DQ<11>")
	)
	(segment
		(start 428.917354 -300.626526)
		(end 428.056294 -300.626526)
		(width 0.18288)
		(layer "In6.Cu")
		(net "M_G_CPU0_SA_DQ<11>")
	)
	(segment
		(start 409.327096 -294.670734)
		(end 408.691842 -294.03548)
		(width 0.18288)
		(layer "In6.Cu")
		(net "M_G_CPU0_SA_DQ<11>")
	)
	(segment
		(start 377.365006 -273.781012)
		(end 377.359164 -273.777456)
		(width 0.088646)
		(layer "In6.Cu")
		(net "M_G_CPU0_SA_DQ<11>")
	)
	(segment
		(start 437.193944 -304.682652)
		(end 437.033924 -304.842672)
		(width 0.18288)
		(layer "In6.Cu")
		(net "M_G_CPU0_SA_DQ<11>")
	)
	(segment
		(start 388.535672 -275.18614)
		(end 388.35711 -275.18614)
		(width 0.088646)
		(layer "In6.Cu")
		(net "M_G_CPU0_SA_DQ<11>")
	)
	(segment
		(start 434.805582 -304.10658)
		(end 434.368194 -304.10658)
		(width 0.18288)
		(layer "In6.Cu")
		(net "M_G_CPU0_SA_DQ<11>")
	)
	(segment
		(start 395.58849 -275.560536)
		(end 389.877046 -275.560536)
		(width 0.18288)
		(layer "In6.Cu")
		(net "M_G_CPU0_SA_DQ<11>")
	)
	(segment
		(start 436.660544 -304.842672)
		(end 436.500524 -304.682652)
		(width 0.18288)
		(layer "In6.Cu")
		(net "M_G_CPU0_SA_DQ<11>")
	)
	(segment
		(start 428.056294 -300.626526)
		(end 427.319694 -299.889926)
		(width 0.18288)
		(layer "In6.Cu")
		(net "M_G_CPU0_SA_DQ<11>")
	)
	(segment
		(start 413.484822 -295.491408)
		(end 411.14218 -295.491408)
		(width 0.18288)
		(layer "In6.Cu")
		(net "M_G_CPU0_SA_DQ<11>")
	)
	(segment
		(start 416.050984 -297.320716)
		(end 415.31413 -297.320716)
		(width 0.18288)
		(layer "In6.Cu")
		(net "M_G_CPU0_SA_DQ<11>")
	)
	(segment
		(start 416.886136 -298.155868)
		(end 416.050984 -297.320716)
		(width 0.18288)
		(layer "In6.Cu")
		(net "M_G_CPU0_SA_DQ<11>")
	)
	(segment
		(start 388.35711 -275.18614)
		(end 388.139686 -274.968716)
		(width 0.088646)
		(layer "In6.Cu")
		(net "M_G_CPU0_SA_DQ<11>")
	)
	(segment
		(start 433.84978 -303.588166)
		(end 433.021994 -303.588166)
		(width 0.18288)
		(layer "In6.Cu")
		(net "M_G_CPU0_SA_DQ<11>")
	)
	(arc
		(start 386.19176 -273.777456)
		(mid 386.004562 -273.827599)
		(end 385.817364 -273.777456)
		(width 0.088646)
		(layer "In6.Cu")
		(net "M_G_CPU0_SA_DQ<11>")
	)
	(arc
		(start 381.118618 -273.777456)
		(mid 380.835916 -273.70168)
		(end 380.553214 -273.777456)
		(width 0.088646)
		(layer "In6.Cu")
		(net "M_G_CPU0_SA_DQ<11>")
	)
	(arc
		(start 383.372614 -273.777456)
		(mid 383.185416 -273.827599)
		(end 382.998218 -273.777456)
		(width 0.088646)
		(layer "In6.Cu")
		(net "M_G_CPU0_SA_DQ<11>")
	)
	(arc
		(start 378.293122 -273.774154)
		(mid 378.013017 -273.701712)
		(end 377.733814 -273.777456)
		(width 0.088646)
		(layer "In6.Cu")
		(net "M_G_CPU0_SA_DQ<11>")
	)
	(arc
		(start 380.553214 -273.777456)
		(mid 380.366016 -273.827599)
		(end 380.178818 -273.777456)
		(width 0.088646)
		(layer "In6.Cu")
		(net "M_G_CPU0_SA_DQ<11>")
	)
	(arc
		(start 385.817364 -273.777456)
		(mid 385.534662 -273.70168)
		(end 385.25196 -273.777456)
		(width 0.088646)
		(layer "In6.Cu")
		(net "M_G_CPU0_SA_DQ<11>")
	)
	(arc
		(start 378.673614 -273.777456)
		(mid 378.48969 -273.82771)
		(end 378.304806 -273.781012)
		(width 0.088646)
		(layer "In6.Cu")
		(net "M_G_CPU0_SA_DQ<11>")
	)
	(arc
		(start 384.877564 -273.777456)
		(mid 384.594862 -273.70168)
		(end 384.31216 -273.777456)
		(width 0.088646)
		(layer "In6.Cu")
		(net "M_G_CPU0_SA_DQ<11>")
	)
	(arc
		(start 383.937764 -273.777456)
		(mid 383.661205 -273.701713)
		(end 383.383028 -273.77136)
		(width 0.088646)
		(layer "In6.Cu")
		(net "M_G_CPU0_SA_DQ<11>")
	)
	(arc
		(start 377.733814 -273.777456)
		(mid 377.54989 -273.82771)
		(end 377.365006 -273.781012)
		(width 0.088646)
		(layer "In6.Cu")
		(net "M_G_CPU0_SA_DQ<11>")
	)
	(arc
		(start 384.31216 -273.777456)
		(mid 384.124962 -273.827599)
		(end 383.937764 -273.777456)
		(width 0.088646)
		(layer "In6.Cu")
		(net "M_G_CPU0_SA_DQ<11>")
	)
	(arc
		(start 379.613414 -273.777456)
		(mid 379.426216 -273.827599)
		(end 379.239018 -273.777456)
		(width 0.088646)
		(layer "In6.Cu")
		(net "M_G_CPU0_SA_DQ<11>")
	)
	(arc
		(start 380.178818 -273.777456)
		(mid 379.904619 -273.701621)
		(end 379.628146 -273.76882)
		(width 0.088646)
		(layer "In6.Cu")
		(net "M_G_CPU0_SA_DQ<11>")
	)
	(arc
		(start 386.474462 -273.701764)
		(mid 386.328139 -273.721026)
		(end 386.19176 -273.777456)
		(width 0.088646)
		(layer "In6.Cu")
		(net "M_G_CPU0_SA_DQ<11>")
	)
	(arc
		(start 376.9614 -273.548094)
		(mid 376.790348 -273.477313)
		(end 376.606816 -273.453098)
		(width 0.088646)
		(layer "In6.Cu")
		(net "M_G_CPU0_SA_DQ<11>")
	)
	(arc
		(start 379.239018 -273.777456)
		(mid 378.964819 -273.701621)
		(end 378.688346 -273.76882)
		(width 0.088646)
		(layer "In6.Cu")
		(net "M_G_CPU0_SA_DQ<11>")
	)
	(arc
		(start 381.493014 -273.777456)
		(mid 381.305816 -273.827599)
		(end 381.118618 -273.777456)
		(width 0.088646)
		(layer "In6.Cu")
		(net "M_G_CPU0_SA_DQ<11>")
	)
	(arc
		(start 385.25196 -273.777456)
		(mid 385.064762 -273.827599)
		(end 384.877564 -273.777456)
		(width 0.088646)
		(layer "In6.Cu")
		(net "M_G_CPU0_SA_DQ<11>")
	)
	(arc
		(start 382.998218 -273.777456)
		(mid 382.724019 -273.701621)
		(end 382.447546 -273.76882)
		(width 0.088646)
		(layer "In6.Cu")
		(net "M_G_CPU0_SA_DQ<11>")
	)
	(arc
		(start 382.432814 -273.777456)
		(mid 382.245616 -273.827599)
		(end 382.058418 -273.777456)
		(width 0.088646)
		(layer "In6.Cu")
		(net "M_G_CPU0_SA_DQ<11>")
	)
	(arc
		(start 382.058418 -273.777456)
		(mid 381.784219 -273.701621)
		(end 381.507746 -273.76882)
		(width 0.088646)
		(layer "In6.Cu")
		(net "M_G_CPU0_SA_DQ<11>")
	)
	(segment
		(start 443.450726 -306.54879)
		(end 443.455552 -306.54879)
		(width 0.101854)
		(layer "F.Cu")
		(net "M_G_CPU0_SA_DQ<10>")
	)
	(segment
		(start 376.136916 -274.26666)
		(end 376.136662 -274.266914)
		(width 0.20066)
		(layer "F.Cu")
		(net "M_G_CPU0_SA_DQ<10>")
	)
	(segment
		(start 446.986152 -305.864768)
		(end 447.23812 -306.116736)
		(width 0.20066)
		(layer "F.Cu")
		(net "M_G_CPU0_SA_DQ<10>")
	)
	(segment
		(start 446.367916 -306.098956)
		(end 446.602104 -305.864768)
		(width 0.20066)
		(layer "F.Cu")
		(net "M_G_CPU0_SA_DQ<10>")
	)
	(segment
		(start 446.163954 -306.55387)
		(end 446.367916 -306.349908)
		(width 0.20066)
		(layer "F.Cu")
		(net "M_G_CPU0_SA_DQ<10>")
	)
	(segment
		(start 442.726826 -306.116736)
		(end 443.15888 -306.54879)
		(width 0.20066)
		(layer "F.Cu")
		(net "M_G_CPU0_SA_DQ<10>")
	)
	(segment
		(start 443.455552 -306.54879)
		(end 443.462664 -306.541678)
		(width 0.1016)
		(layer "F.Cu")
		(net "M_G_CPU0_SA_DQ<10>")
	)
	(segment
		(start 446.367916 -306.349908)
		(end 446.367916 -306.098956)
		(width 0.20066)
		(layer "F.Cu")
		(net "M_G_CPU0_SA_DQ<10>")
	)
	(segment
		(start 446.602104 -305.864768)
		(end 446.986152 -305.864768)
		(width 0.20066)
		(layer "F.Cu")
		(net "M_G_CPU0_SA_DQ<10>")
	)
	(segment
		(start 445.470534 -306.541678)
		(end 445.482726 -306.55387)
		(width 0.1016)
		(layer "F.Cu")
		(net "M_G_CPU0_SA_DQ<10>")
	)
	(segment
		(start 447.23812 -306.116736)
		(end 448.572382 -306.116736)
		(width 0.20066)
		(layer "F.Cu")
		(net "M_G_CPU0_SA_DQ<10>")
	)
	(segment
		(start 443.15888 -306.54879)
		(end 443.450726 -306.54879)
		(width 0.20066)
		(layer "F.Cu")
		(net "M_G_CPU0_SA_DQ<10>")
	)
	(segment
		(start 439.923682 -306.116736)
		(end 441.028582 -306.116736)
		(width 0.20066)
		(layer "F.Cu")
		(net "M_G_CPU0_SA_DQ<10>")
	)
	(segment
		(start 443.462664 -306.541678)
		(end 445.470534 -306.541678)
		(width 0.1016)
		(layer "F.Cu")
		(net "M_G_CPU0_SA_DQ<10>")
	)
	(segment
		(start 376.136916 -273.730974)
		(end 376.136916 -274.26666)
		(width 0.20066)
		(layer "F.Cu")
		(net "M_G_CPU0_SA_DQ<10>")
	)
	(segment
		(start 441.028582 -306.116736)
		(end 442.726826 -306.116736)
		(width 0.20066)
		(layer "F.Cu")
		(net "M_G_CPU0_SA_DQ<10>")
	)
	(segment
		(start 445.482726 -306.55387)
		(end 446.163954 -306.55387)
		(width 0.20066)
		(layer "F.Cu")
		(net "M_G_CPU0_SA_DQ<10>")
	)
	(segment
		(start 438.81548 -305.647598)
		(end 438.657746 -305.489864)
		(width 0.18288)
		(layer "In6.Cu")
		(net "M_G_CPU0_SA_DQ<10>")
	)
	(segment
		(start 421.696896 -299.742352)
		(end 419.758368 -299.742352)
		(width 0.18288)
		(layer "In6.Cu")
		(net "M_G_CPU0_SA_DQ<10>")
	)
	(segment
		(start 387.555486 -275.28139)
		(end 387.555486 -274.844764)
		(width 0.088646)
		(layer "In6.Cu")
		(net "M_G_CPU0_SA_DQ<10>")
	)
	(segment
		(start 419.57244 -299.92828)
		(end 417.033202 -299.92828)
		(width 0.18288)
		(layer "In6.Cu")
		(net "M_G_CPU0_SA_DQ<10>")
	)
	(segment
		(start 388.821676 -276.201378)
		(end 387.956552 -276.201378)
		(width 0.18288)
		(layer "In6.Cu")
		(net "M_G_CPU0_SA_DQ<10>")
	)
	(segment
		(start 432.11877 -304.790094)
		(end 431.256948 -303.928272)
		(width 0.18288)
		(layer "In6.Cu")
		(net "M_G_CPU0_SA_DQ<10>")
	)
	(segment
		(start 431.256948 -303.928272)
		(end 430.297336 -303.928272)
		(width 0.18288)
		(layer "In6.Cu")
		(net "M_G_CPU0_SA_DQ<10>")
	)
	(segment
		(start 400.34591 -281.727402)
		(end 395.175994 -276.556216)
		(width 0.18288)
		(layer "In6.Cu")
		(net "M_G_CPU0_SA_DQ<10>")
	)
	(segment
		(start 409.092654 -296.40911)
		(end 408.39263 -295.709086)
		(width 0.18288)
		(layer "In6.Cu")
		(net "M_G_CPU0_SA_DQ<10>")
	)
	(segment
		(start 430.297336 -303.928272)
		(end 428.698914 -302.32985)
		(width 0.18288)
		(layer "In6.Cu")
		(net "M_G_CPU0_SA_DQ<10>")
	)
	(segment
		(start 428.698914 -302.32985)
		(end 427.673516 -302.32985)
		(width 0.18288)
		(layer "In6.Cu")
		(net "M_G_CPU0_SA_DQ<10>")
	)
	(segment
		(start 410.468064 -296.409872)
		(end 409.880816 -296.409872)
		(width 0.18288)
		(layer "In6.Cu")
		(net "M_G_CPU0_SA_DQ<10>")
	)
	(segment
		(start 387.497066 -275.422614)
		(end 387.555486 -275.28139)
		(width 0.088646)
		(layer "In6.Cu")
		(net "M_G_CPU0_SA_DQ<10>")
	)
	(segment
		(start 427.673516 -302.32985)
		(end 425.935902 -300.592236)
		(width 0.18288)
		(layer "In6.Cu")
		(net "M_G_CPU0_SA_DQ<10>")
	)
	(segment
		(start 387.591046 -275.835872)
		(end 387.497066 -275.741892)
		(width 0.088646)
		(layer "In6.Cu")
		(net "M_G_CPU0_SA_DQ<10>")
	)
	(segment
		(start 413.33928 -297.190668)
		(end 411.24886 -297.190668)
		(width 0.18288)
		(layer "In6.Cu")
		(net "M_G_CPU0_SA_DQ<10>")
	)
	(segment
		(start 378.768864 -274.591272)
		(end 378.754132 -274.582636)
		(width 0.088646)
		(layer "In6.Cu")
		(net "M_G_CPU0_SA_DQ<10>")
	)
	(segment
		(start 382.528064 -274.591272)
		(end 382.513332 -274.582636)
		(width 0.088646)
		(layer "In6.Cu")
		(net "M_G_CPU0_SA_DQ<10>")
	)
	(segment
		(start 425.935902 -300.592236)
		(end 422.54678 -300.592236)
		(width 0.18288)
		(layer "In6.Cu")
		(net "M_G_CPU0_SA_DQ<10>")
	)
	(segment
		(start 439.923682 -306.116736)
		(end 439.923682 -305.830478)
		(width 0.18288)
		(layer "In6.Cu")
		(net "M_G_CPU0_SA_DQ<10>")
	)
	(segment
		(start 387.226048 -274.515326)
		(end 386.004816 -274.515326)
		(width 0.088646)
		(layer "In6.Cu")
		(net "M_G_CPU0_SA_DQ<10>")
	)
	(segment
		(start 400.34591 -290.550854)
		(end 400.34591 -281.727402)
		(width 0.18288)
		(layer "In6.Cu")
		(net "M_G_CPU0_SA_DQ<10>")
	)
	(segment
		(start 405.504142 -295.709086)
		(end 400.34591 -290.550854)
		(width 0.18288)
		(layer "In6.Cu")
		(net "M_G_CPU0_SA_DQ<10>")
	)
	(segment
		(start 385.347464 -274.591272)
		(end 385.332732 -274.582636)
		(width 0.088646)
		(layer "In6.Cu")
		(net "M_G_CPU0_SA_DQ<10>")
	)
	(segment
		(start 381.033528 -274.585176)
		(end 381.023114 -274.591272)
		(width 0.088646)
		(layer "In6.Cu")
		(net "M_G_CPU0_SA_DQ<10>")
	)
	(segment
		(start 417.033202 -299.92828)
		(end 416.220148 -299.115226)
		(width 0.18288)
		(layer "In6.Cu")
		(net "M_G_CPU0_SA_DQ<10>")
	)
	(segment
		(start 437.935878 -305.692302)
		(end 433.822856 -305.692302)
		(width 0.18288)
		(layer "In6.Cu")
		(net "M_G_CPU0_SA_DQ<10>")
	)
	(segment
		(start 395.175994 -276.556216)
		(end 389.678418 -276.556216)
		(width 0.18288)
		(layer "In6.Cu")
		(net "M_G_CPU0_SA_DQ<10>")
	)
	(segment
		(start 439.740802 -305.647598)
		(end 438.81548 -305.647598)
		(width 0.18288)
		(layer "In6.Cu")
		(net "M_G_CPU0_SA_DQ<10>")
	)
	(segment
		(start 416.220148 -299.115226)
		(end 415.263838 -299.115226)
		(width 0.18288)
		(layer "In6.Cu")
		(net "M_G_CPU0_SA_DQ<10>")
	)
	(segment
		(start 387.555486 -274.844764)
		(end 387.226048 -274.515326)
		(width 0.088646)
		(layer "In6.Cu")
		(net "M_G_CPU0_SA_DQ<10>")
	)
	(segment
		(start 375.949464 -274.591272)
		(end 375.940574 -274.586192)
		(width 0.088646)
		(layer "In6.Cu")
		(net "M_G_CPU0_SA_DQ<10>")
	)
	(segment
		(start 432.920648 -304.790094)
		(end 432.11877 -304.790094)
		(width 0.18288)
		(layer "In6.Cu")
		(net "M_G_CPU0_SA_DQ<10>")
	)
	(segment
		(start 375.766584 -274.324318)
		(end 375.823988 -274.266914)
		(width 0.088646)
		(layer "In6.Cu")
		(net "M_G_CPU0_SA_DQ<10>")
	)
	(segment
		(start 409.880816 -296.409872)
		(end 409.880054 -296.40911)
		(width 0.18288)
		(layer "In6.Cu")
		(net "M_G_CPU0_SA_DQ<10>")
	)
	(segment
		(start 389.678418 -276.556216)
		(end 388.821676 -276.201378)
		(width 0.18288)
		(layer "In6.Cu")
		(net "M_G_CPU0_SA_DQ<10>")
	)
	(segment
		(start 377.829064 -274.591272)
		(end 377.814332 -274.582636)
		(width 0.088646)
		(layer "In6.Cu")
		(net "M_G_CPU0_SA_DQ<10>")
	)
	(segment
		(start 387.956552 -276.201378)
		(end 387.591046 -275.835872)
		(width 0.18288)
		(layer "In6.Cu")
		(net "M_G_CPU0_SA_DQ<10>")
	)
	(segment
		(start 438.138316 -305.489864)
		(end 437.935878 -305.692302)
		(width 0.18288)
		(layer "In6.Cu")
		(net "M_G_CPU0_SA_DQ<10>")
	)
	(segment
		(start 384.407664 -274.591272)
		(end 384.392932 -274.582636)
		(width 0.088646)
		(layer "In6.Cu")
		(net "M_G_CPU0_SA_DQ<10>")
	)
	(segment
		(start 411.24886 -297.190668)
		(end 410.468064 -296.409872)
		(width 0.18288)
		(layer "In6.Cu")
		(net "M_G_CPU0_SA_DQ<10>")
	)
	(segment
		(start 379.708664 -274.591272)
		(end 379.693932 -274.582636)
		(width 0.088646)
		(layer "In6.Cu")
		(net "M_G_CPU0_SA_DQ<10>")
	)
	(segment
		(start 387.497066 -275.741892)
		(end 387.497066 -275.422614)
		(width 0.088646)
		(layer "In6.Cu")
		(net "M_G_CPU0_SA_DQ<10>")
	)
	(segment
		(start 419.758368 -299.742352)
		(end 419.57244 -299.92828)
		(width 0.18288)
		(layer "In6.Cu")
		(net "M_G_CPU0_SA_DQ<10>")
	)
	(segment
		(start 375.823988 -274.266914)
		(end 376.136662 -274.266914)
		(width 0.088646)
		(layer "In6.Cu")
		(net "M_G_CPU0_SA_DQ<10>")
	)
	(segment
		(start 380.648718 -274.591272)
		(end 380.638304 -274.585176)
		(width 0.088646)
		(layer "In6.Cu")
		(net "M_G_CPU0_SA_DQ<10>")
	)
	(segment
		(start 415.263838 -299.115226)
		(end 413.33928 -297.190668)
		(width 0.18288)
		(layer "In6.Cu")
		(net "M_G_CPU0_SA_DQ<10>")
	)
	(segment
		(start 408.39263 -295.709086)
		(end 405.504142 -295.709086)
		(width 0.18288)
		(layer "In6.Cu")
		(net "M_G_CPU0_SA_DQ<10>")
	)
	(segment
		(start 422.54678 -300.592236)
		(end 421.696896 -299.742352)
		(width 0.18288)
		(layer "In6.Cu")
		(net "M_G_CPU0_SA_DQ<10>")
	)
	(segment
		(start 433.822856 -305.692302)
		(end 432.920648 -304.790094)
		(width 0.18288)
		(layer "In6.Cu")
		(net "M_G_CPU0_SA_DQ<10>")
	)
	(segment
		(start 439.923682 -305.830478)
		(end 439.740802 -305.647598)
		(width 0.18288)
		(layer "In6.Cu")
		(net "M_G_CPU0_SA_DQ<10>")
	)
	(segment
		(start 409.880054 -296.40911)
		(end 409.092654 -296.40911)
		(width 0.18288)
		(layer "In6.Cu")
		(net "M_G_CPU0_SA_DQ<10>")
	)
	(segment
		(start 383.467864 -274.591272)
		(end 383.453132 -274.582636)
		(width 0.088646)
		(layer "In6.Cu")
		(net "M_G_CPU0_SA_DQ<10>")
	)
	(segment
		(start 376.889264 -274.591272)
		(end 376.874532 -274.582636)
		(width 0.088646)
		(layer "In6.Cu")
		(net "M_G_CPU0_SA_DQ<10>")
	)
	(segment
		(start 438.657746 -305.489864)
		(end 438.138316 -305.489864)
		(width 0.18288)
		(layer "In6.Cu")
		(net "M_G_CPU0_SA_DQ<10>")
	)
	(arc
		(start 375.940574 -274.586192)
		(mid 375.824835 -274.474368)
		(end 375.766584 -274.324318)
		(width 0.088646)
		(layer "In6.Cu")
		(net "M_G_CPU0_SA_DQ<10>")
	)
	(arc
		(start 385.72186 -274.591272)
		(mid 385.534662 -274.641415)
		(end 385.347464 -274.591272)
		(width 0.088646)
		(layer "In6.Cu")
		(net "M_G_CPU0_SA_DQ<10>")
	)
	(arc
		(start 382.513332 -274.582636)
		(mid 382.236857 -274.515316)
		(end 381.96266 -274.591272)
		(width 0.088646)
		(layer "In6.Cu")
		(net "M_G_CPU0_SA_DQ<10>")
	)
	(arc
		(start 377.814332 -274.582636)
		(mid 377.537857 -274.515316)
		(end 377.26366 -274.591272)
		(width 0.088646)
		(layer "In6.Cu")
		(net "M_G_CPU0_SA_DQ<10>")
	)
	(arc
		(start 381.96266 -274.591272)
		(mid 381.775462 -274.641415)
		(end 381.588264 -274.591272)
		(width 0.088646)
		(layer "In6.Cu")
		(net "M_G_CPU0_SA_DQ<10>")
	)
	(arc
		(start 383.84226 -274.591272)
		(mid 383.655062 -274.641415)
		(end 383.467864 -274.591272)
		(width 0.088646)
		(layer "In6.Cu")
		(net "M_G_CPU0_SA_DQ<10>")
	)
	(arc
		(start 378.20346 -274.591272)
		(mid 378.016262 -274.641415)
		(end 377.829064 -274.591272)
		(width 0.088646)
		(layer "In6.Cu")
		(net "M_G_CPU0_SA_DQ<10>")
	)
	(arc
		(start 379.693932 -274.582636)
		(mid 379.417457 -274.515316)
		(end 379.14326 -274.591272)
		(width 0.088646)
		(layer "In6.Cu")
		(net "M_G_CPU0_SA_DQ<10>")
	)
	(arc
		(start 384.392932 -274.582636)
		(mid 384.116491 -274.51547)
		(end 383.84226 -274.591272)
		(width 0.088646)
		(layer "In6.Cu")
		(net "M_G_CPU0_SA_DQ<10>")
	)
	(arc
		(start 376.32386 -274.591272)
		(mid 376.136662 -274.641415)
		(end 375.949464 -274.591272)
		(width 0.088646)
		(layer "In6.Cu")
		(net "M_G_CPU0_SA_DQ<10>")
	)
	(arc
		(start 384.78206 -274.591272)
		(mid 384.594862 -274.641415)
		(end 384.407664 -274.591272)
		(width 0.088646)
		(layer "In6.Cu")
		(net "M_G_CPU0_SA_DQ<10>")
	)
	(arc
		(start 378.754132 -274.582636)
		(mid 378.477657 -274.515316)
		(end 378.20346 -274.591272)
		(width 0.088646)
		(layer "In6.Cu")
		(net "M_G_CPU0_SA_DQ<10>")
	)
	(arc
		(start 377.26366 -274.591272)
		(mid 377.076462 -274.641415)
		(end 376.889264 -274.591272)
		(width 0.088646)
		(layer "In6.Cu")
		(net "M_G_CPU0_SA_DQ<10>")
	)
	(arc
		(start 380.08306 -274.591272)
		(mid 379.895862 -274.641415)
		(end 379.708664 -274.591272)
		(width 0.088646)
		(layer "In6.Cu")
		(net "M_G_CPU0_SA_DQ<10>")
	)
	(arc
		(start 382.90246 -274.591272)
		(mid 382.715262 -274.641415)
		(end 382.528064 -274.591272)
		(width 0.088646)
		(layer "In6.Cu")
		(net "M_G_CPU0_SA_DQ<10>")
	)
	(arc
		(start 381.023114 -274.591272)
		(mid 380.835916 -274.641415)
		(end 380.648718 -274.591272)
		(width 0.088646)
		(layer "In6.Cu")
		(net "M_G_CPU0_SA_DQ<10>")
	)
	(arc
		(start 376.874532 -274.582636)
		(mid 376.598057 -274.515316)
		(end 376.32386 -274.591272)
		(width 0.088646)
		(layer "In6.Cu")
		(net "M_G_CPU0_SA_DQ<10>")
	)
	(arc
		(start 380.638304 -274.585176)
		(mid 380.359872 -274.51533)
		(end 380.08306 -274.591272)
		(width 0.088646)
		(layer "In6.Cu")
		(net "M_G_CPU0_SA_DQ<10>")
	)
	(arc
		(start 379.14326 -274.591272)
		(mid 378.956062 -274.641415)
		(end 378.768864 -274.591272)
		(width 0.088646)
		(layer "In6.Cu")
		(net "M_G_CPU0_SA_DQ<10>")
	)
	(arc
		(start 381.588264 -274.591272)
		(mid 381.311705 -274.515529)
		(end 381.033528 -274.585176)
		(width 0.088646)
		(layer "In6.Cu")
		(net "M_G_CPU0_SA_DQ<10>")
	)
	(arc
		(start 386.004816 -274.515326)
		(mid 385.858341 -274.534679)
		(end 385.72186 -274.591272)
		(width 0.088646)
		(layer "In6.Cu")
		(net "M_G_CPU0_SA_DQ<10>")
	)
	(arc
		(start 383.453132 -274.582636)
		(mid 383.176691 -274.51547)
		(end 382.90246 -274.591272)
		(width 0.088646)
		(layer "In6.Cu")
		(net "M_G_CPU0_SA_DQ<10>")
	)
	(arc
		(start 385.332732 -274.582636)
		(mid 385.056291 -274.51547)
		(end 384.78206 -274.591272)
		(width 0.088646)
		(layer "In6.Cu")
		(net "M_G_CPU0_SA_DQ<10>")
	)
	(segment
		(start 378.486162 -276.172676)
		(end 378.486416 -276.708616)
		(width 0.20066)
		(layer "F.Cu")
		(net "M_G_CPU0_SA_DQ<0>")
	)
	(segment
		(start 444.47206 -316.316868)
		(end 442.880496 -316.316868)
		(width 0.20066)
		(layer "F.Cu")
		(net "M_G_CPU0_SA_DQ<0>")
	)
	(segment
		(start 444.472314 -316.316614)
		(end 444.47206 -316.316868)
		(width 0.20066)
		(layer "F.Cu")
		(net "M_G_CPU0_SA_DQ<0>")
	)
	(segment
		(start 436.928514 -316.316614)
		(end 435.823614 -316.316614)
		(width 0.20066)
		(layer "F.Cu")
		(net "M_G_CPU0_SA_DQ<0>")
	)
	(segment
		(start 442.44895 -315.885322)
		(end 442.038994 -315.885322)
		(width 0.20066)
		(layer "F.Cu")
		(net "M_G_CPU0_SA_DQ<0>")
	)
	(segment
		(start 439.361072 -316.37732)
		(end 439.173112 -316.56528)
		(width 0.20066)
		(layer "F.Cu")
		(net "M_G_CPU0_SA_DQ<0>")
	)
	(segment
		(start 439.173112 -316.56528)
		(end 438.697878 -316.56528)
		(width 0.20066)
		(layer "F.Cu")
		(net "M_G_CPU0_SA_DQ<0>")
	)
	(segment
		(start 438.697878 -316.56528)
		(end 438.449212 -316.316614)
		(width 0.20066)
		(layer "F.Cu")
		(net "M_G_CPU0_SA_DQ<0>")
	)
	(segment
		(start 439.87085 -315.891672)
		(end 439.82386 -315.891672)
		(width 0.101854)
		(layer "F.Cu")
		(net "M_G_CPU0_SA_DQ<0>")
	)
	(segment
		(start 442.038994 -315.885322)
		(end 442.032644 -315.891672)
		(width 0.1016)
		(layer "F.Cu")
		(net "M_G_CPU0_SA_DQ<0>")
	)
	(segment
		(start 442.880496 -316.316868)
		(end 442.44895 -315.885322)
		(width 0.20066)
		(layer "F.Cu")
		(net "M_G_CPU0_SA_DQ<0>")
	)
	(segment
		(start 442.032644 -315.891672)
		(end 439.87085 -315.891672)
		(width 0.1016)
		(layer "F.Cu")
		(net "M_G_CPU0_SA_DQ<0>")
	)
	(segment
		(start 439.82386 -315.891672)
		(end 439.479182 -315.891672)
		(width 0.20066)
		(layer "F.Cu")
		(net "M_G_CPU0_SA_DQ<0>")
	)
	(segment
		(start 438.449212 -316.316614)
		(end 436.928514 -316.316614)
		(width 0.20066)
		(layer "F.Cu")
		(net "M_G_CPU0_SA_DQ<0>")
	)
	(segment
		(start 439.479182 -315.891672)
		(end 439.361072 -316.009782)
		(width 0.20066)
		(layer "F.Cu")
		(net "M_G_CPU0_SA_DQ<0>")
	)
	(segment
		(start 439.361072 -316.009782)
		(end 439.361072 -316.37732)
		(width 0.20066)
		(layer "F.Cu")
		(net "M_G_CPU0_SA_DQ<0>")
	)
	(segment
		(start 382.91135 -278.83104)
		(end 382.90246 -278.82596)
		(width 0.088646)
		(layer "In4.Cu")
		(net "M_G_CPU0_SA_DQ<0>")
	)
	(segment
		(start 388.593584 -283.311346)
		(end 387.787896 -281.36596)
		(width 0.18288)
		(layer "In4.Cu")
		(net "M_G_CPU0_SA_DQ<0>")
	)
	(segment
		(start 426.23867 -318.610996)
		(end 426.070522 -318.442848)
		(width 0.18288)
		(layer "In4.Cu")
		(net "M_G_CPU0_SA_DQ<0>")
	)
	(segment
		(start 378.79909 -276.708616)
		(end 378.486416 -276.708616)
		(width 0.088646)
		(layer "In4.Cu")
		(net "M_G_CPU0_SA_DQ<0>")
	)
	(segment
		(start 409.164282 -315.10859)
		(end 408.305 -314.249308)
		(width 0.18288)
		(layer "In4.Cu")
		(net "M_G_CPU0_SA_DQ<0>")
	)
	(segment
		(start 381.588264 -277.198074)
		(end 381.573532 -277.20671)
		(width 0.088646)
		(layer "In4.Cu")
		(net "M_G_CPU0_SA_DQ<0>")
	)
	(segment
		(start 378.864622 -276.774148)
		(end 378.79909 -276.708616)
		(width 0.088646)
		(layer "In4.Cu")
		(net "M_G_CPU0_SA_DQ<0>")
	)
	(segment
		(start 417.00577 -317.59271)
		(end 415.978086 -316.565026)
		(width 0.18288)
		(layer "In4.Cu")
		(net "M_G_CPU0_SA_DQ<0>")
	)
	(segment
		(start 434.235606 -317.268606)
		(end 432.770026 -315.803026)
		(width 0.18288)
		(layer "In4.Cu")
		(net "M_G_CPU0_SA_DQ<0>")
	)
	(segment
		(start 423.17543 -318.812926)
		(end 423.17543 -318.371474)
		(width 0.18288)
		(layer "In4.Cu")
		(net "M_G_CPU0_SA_DQ<0>")
	)
	(segment
		(start 413.503618 -316.565026)
		(end 412.801816 -315.863224)
		(width 0.18288)
		(layer "In4.Cu")
		(net "M_G_CPU0_SA_DQ<0>")
	)
	(segment
		(start 422.411398 -318.856868)
		(end 418.949378 -318.856868)
		(width 0.18288)
		(layer "In4.Cu")
		(net "M_G_CPU0_SA_DQ<0>")
	)
	(segment
		(start 434.871622 -317.268606)
		(end 434.235606 -317.268606)
		(width 0.18288)
		(layer "In4.Cu")
		(net "M_G_CPU0_SA_DQ<0>")
	)
	(segment
		(start 422.45534 -318.812926)
		(end 422.411398 -318.856868)
		(width 0.18288)
		(layer "In4.Cu")
		(net "M_G_CPU0_SA_DQ<0>")
	)
	(segment
		(start 424.252898 -318.442848)
		(end 423.7228 -318.972946)
		(width 0.18288)
		(layer "In4.Cu")
		(net "M_G_CPU0_SA_DQ<0>")
	)
	(segment
		(start 411.315154 -315.863224)
		(end 410.56052 -315.10859)
		(width 0.18288)
		(layer "In4.Cu")
		(net "M_G_CPU0_SA_DQ<0>")
	)
	(segment
		(start 382.150112 -277.540974)
		(end 382.150112 -277.522432)
		(width 0.088646)
		(layer "In4.Cu")
		(net "M_G_CPU0_SA_DQ<0>")
	)
	(segment
		(start 408.305 -314.249308)
		(end 406.648666 -314.249308)
		(width 0.18288)
		(layer "In4.Cu")
		(net "M_G_CPU0_SA_DQ<0>")
	)
	(segment
		(start 422.45534 -318.371474)
		(end 422.45534 -318.812926)
		(width 0.18288)
		(layer "In4.Cu")
		(net "M_G_CPU0_SA_DQ<0>")
	)
	(segment
		(start 387.375654 -280.953718)
		(end 386.608066 -280.18613)
		(width 0.088646)
		(layer "In4.Cu")
		(net "M_G_CPU0_SA_DQ<0>")
	)
	(segment
		(start 427.941232 -319.084452)
		(end 426.39869 -319.084452)
		(width 0.18288)
		(layer "In4.Cu")
		(net "M_G_CPU0_SA_DQ<0>")
	)
	(segment
		(start 435.823614 -316.316614)
		(end 434.871622 -317.268606)
		(width 0.18288)
		(layer "In4.Cu")
		(net "M_G_CPU0_SA_DQ<0>")
	)
	(segment
		(start 383.089912 -279.165812)
		(end 383.089912 -279.150318)
		(width 0.088646)
		(layer "In4.Cu")
		(net "M_G_CPU0_SA_DQ<0>")
	)
	(segment
		(start 422.61536 -318.211454)
		(end 422.45534 -318.371474)
		(width 0.18288)
		(layer "In4.Cu")
		(net "M_G_CPU0_SA_DQ<0>")
	)
	(segment
		(start 394.370306 -298.479464)
		(end 388.593584 -284.535372)
		(width 0.18288)
		(layer "In4.Cu")
		(net "M_G_CPU0_SA_DQ<0>")
	)
	(segment
		(start 387.787896 -281.36596)
		(end 387.375654 -280.953718)
		(width 0.18288)
		(layer "In4.Cu")
		(net "M_G_CPU0_SA_DQ<0>")
	)
	(segment
		(start 426.23867 -318.924432)
		(end 426.23867 -318.610996)
		(width 0.18288)
		(layer "In4.Cu")
		(net "M_G_CPU0_SA_DQ<0>")
	)
	(segment
		(start 423.17543 -318.371474)
		(end 423.01541 -318.211454)
		(width 0.18288)
		(layer "In4.Cu")
		(net "M_G_CPU0_SA_DQ<0>")
	)
	(segment
		(start 423.01541 -318.211454)
		(end 422.61536 -318.211454)
		(width 0.18288)
		(layer "In4.Cu")
		(net "M_G_CPU0_SA_DQ<0>")
	)
	(segment
		(start 418.949378 -318.856868)
		(end 417.68522 -317.59271)
		(width 0.18288)
		(layer "In4.Cu")
		(net "M_G_CPU0_SA_DQ<0>")
	)
	(segment
		(start 412.801816 -315.863224)
		(end 411.315154 -315.863224)
		(width 0.18288)
		(layer "In4.Cu")
		(net "M_G_CPU0_SA_DQ<0>")
	)
	(segment
		(start 423.7228 -318.972946)
		(end 423.33545 -318.972946)
		(width 0.18288)
		(layer "In4.Cu")
		(net "M_G_CPU0_SA_DQ<0>")
	)
	(segment
		(start 382.620012 -278.346408)
		(end 382.620012 -278.336502)
		(width 0.088646)
		(layer "In4.Cu")
		(net "M_G_CPU0_SA_DQ<0>")
	)
	(segment
		(start 379.708664 -277.198074)
		(end 379.69825 -277.20417)
		(width 0.088646)
		(layer "In4.Cu")
		(net "M_G_CPU0_SA_DQ<0>")
	)
	(segment
		(start 382.44145 -278.017224)
		(end 382.43256 -278.012144)
		(width 0.088646)
		(layer "In4.Cu")
		(net "M_G_CPU0_SA_DQ<0>")
	)
	(segment
		(start 426.070522 -318.442848)
		(end 424.252898 -318.442848)
		(width 0.18288)
		(layer "In4.Cu")
		(net "M_G_CPU0_SA_DQ<0>")
	)
	(segment
		(start 431.574194 -315.803026)
		(end 430.786794 -316.590426)
		(width 0.18288)
		(layer "In4.Cu")
		(net "M_G_CPU0_SA_DQ<0>")
	)
	(segment
		(start 383.937764 -279.639776)
		(end 383.92735 -279.645872)
		(width 0.088646)
		(layer "In4.Cu")
		(net "M_G_CPU0_SA_DQ<0>")
	)
	(segment
		(start 386.055108 -280.18613)
		(end 385.5847 -279.715722)
		(width 0.088646)
		(layer "In4.Cu")
		(net "M_G_CPU0_SA_DQ<0>")
	)
	(segment
		(start 406.648666 -314.249308)
		(end 401.401788 -309.00243)
		(width 0.18288)
		(layer "In4.Cu")
		(net "M_G_CPU0_SA_DQ<0>")
	)
	(segment
		(start 423.33545 -318.972946)
		(end 423.17543 -318.812926)
		(width 0.18288)
		(layer "In4.Cu")
		(net "M_G_CPU0_SA_DQ<0>")
	)
	(segment
		(start 426.39869 -319.084452)
		(end 426.23867 -318.924432)
		(width 0.18288)
		(layer "In4.Cu")
		(net "M_G_CPU0_SA_DQ<0>")
	)
	(segment
		(start 432.770026 -315.803026)
		(end 431.574194 -315.803026)
		(width 0.18288)
		(layer "In4.Cu")
		(net "M_G_CPU0_SA_DQ<0>")
	)
	(segment
		(start 386.608066 -280.18613)
		(end 386.055108 -280.18613)
		(width 0.088646)
		(layer "In4.Cu")
		(net "M_G_CPU0_SA_DQ<0>")
	)
	(segment
		(start 385.5847 -279.715722)
		(end 385.534662 -279.715722)
		(width 0.088646)
		(layer "In4.Cu")
		(net "M_G_CPU0_SA_DQ<0>")
	)
	(segment
		(start 381.97155 -277.203154)
		(end 381.96266 -277.198074)
		(width 0.088646)
		(layer "In4.Cu")
		(net "M_G_CPU0_SA_DQ<0>")
	)
	(segment
		(start 410.56052 -315.10859)
		(end 409.164282 -315.10859)
		(width 0.18288)
		(layer "In4.Cu")
		(net "M_G_CPU0_SA_DQ<0>")
	)
	(segment
		(start 417.68522 -317.59271)
		(end 417.00577 -317.59271)
		(width 0.18288)
		(layer "In4.Cu")
		(net "M_G_CPU0_SA_DQ<0>")
	)
	(segment
		(start 430.435258 -316.590426)
		(end 427.941232 -319.084452)
		(width 0.18288)
		(layer "In4.Cu")
		(net "M_G_CPU0_SA_DQ<0>")
	)
	(segment
		(start 415.978086 -316.565026)
		(end 413.503618 -316.565026)
		(width 0.18288)
		(layer "In4.Cu")
		(net "M_G_CPU0_SA_DQ<0>")
	)
	(segment
		(start 430.786794 -316.590426)
		(end 430.435258 -316.590426)
		(width 0.18288)
		(layer "In4.Cu")
		(net "M_G_CPU0_SA_DQ<0>")
	)
	(segment
		(start 388.593584 -284.535372)
		(end 388.593584 -283.311346)
		(width 0.18288)
		(layer "In4.Cu")
		(net "M_G_CPU0_SA_DQ<0>")
	)
	(segment
		(start 401.401788 -309.00243)
		(end 394.370306 -298.479464)
		(width 0.18288)
		(layer "In4.Cu")
		(net "M_G_CPU0_SA_DQ<0>")
	)
	(arc
		(start 380.08306 -277.198074)
		(mid 379.895862 -277.147931)
		(end 379.708664 -277.198074)
		(width 0.088646)
		(layer "In4.Cu")
		(net "M_G_CPU0_SA_DQ<0>")
	)
	(arc
		(start 379.143514 -277.198074)
		(mid 378.953834 -277.019165)
		(end 378.864622 -276.774148)
		(width 0.088646)
		(layer "In4.Cu")
		(net "M_G_CPU0_SA_DQ<0>")
	)
	(arc
		(start 384.31216 -279.639776)
		(mid 384.124962 -279.589633)
		(end 383.937764 -279.639776)
		(width 0.088646)
		(layer "In4.Cu")
		(net "M_G_CPU0_SA_DQ<0>")
	)
	(arc
		(start 384.877564 -279.639776)
		(mid 384.594862 -279.715552)
		(end 384.31216 -279.639776)
		(width 0.088646)
		(layer "In4.Cu")
		(net "M_G_CPU0_SA_DQ<0>")
	)
	(arc
		(start 385.48564 -279.71369)
		(mid 385.364741 -279.689561)
		(end 385.25196 -279.639776)
		(width 0.088646)
		(layer "In4.Cu")
		(net "M_G_CPU0_SA_DQ<0>")
	)
	(arc
		(start 383.372106 -279.639776)
		(mid 383.169283 -279.439545)
		(end 383.089912 -279.165812)
		(width 0.088646)
		(layer "In4.Cu")
		(net "M_G_CPU0_SA_DQ<0>")
	)
	(arc
		(start 382.620012 -278.336502)
		(mid 382.572333 -278.153602)
		(end 382.44145 -278.017224)
		(width 0.088646)
		(layer "In4.Cu")
		(net "M_G_CPU0_SA_DQ<0>")
	)
	(arc
		(start 381.02286 -277.198074)
		(mid 380.835662 -277.147931)
		(end 380.648464 -277.198074)
		(width 0.088646)
		(layer "In4.Cu")
		(net "M_G_CPU0_SA_DQ<0>")
	)
	(arc
		(start 383.92735 -279.645872)
		(mid 383.648918 -279.715718)
		(end 383.372106 -279.639776)
		(width 0.088646)
		(layer "In4.Cu")
		(net "M_G_CPU0_SA_DQ<0>")
	)
	(arc
		(start 382.43256 -278.012144)
		(mid 382.230274 -277.813163)
		(end 382.150112 -277.540974)
		(width 0.088646)
		(layer "In4.Cu")
		(net "M_G_CPU0_SA_DQ<0>")
	)
	(arc
		(start 385.534662 -279.715722)
		(mid 385.510129 -279.715234)
		(end 385.48564 -279.71369)
		(width 0.088646)
		(layer "In4.Cu")
		(net "M_G_CPU0_SA_DQ<0>")
	)
	(arc
		(start 382.90246 -278.82596)
		(mid 382.698125 -278.623355)
		(end 382.620012 -278.346408)
		(width 0.088646)
		(layer "In4.Cu")
		(net "M_G_CPU0_SA_DQ<0>")
	)
	(arc
		(start 380.648464 -277.198074)
		(mid 380.365762 -277.27385)
		(end 380.08306 -277.198074)
		(width 0.088646)
		(layer "In4.Cu")
		(net "M_G_CPU0_SA_DQ<0>")
	)
	(arc
		(start 381.96266 -277.198074)
		(mid 381.775462 -277.147931)
		(end 381.588264 -277.198074)
		(width 0.088646)
		(layer "In4.Cu")
		(net "M_G_CPU0_SA_DQ<0>")
	)
	(arc
		(start 383.089912 -279.150318)
		(mid 383.042233 -278.967418)
		(end 382.91135 -278.83104)
		(width 0.088646)
		(layer "In4.Cu")
		(net "M_G_CPU0_SA_DQ<0>")
	)
	(arc
		(start 381.573532 -277.20671)
		(mid 381.297057 -277.27403)
		(end 381.02286 -277.198074)
		(width 0.088646)
		(layer "In4.Cu")
		(net "M_G_CPU0_SA_DQ<0>")
	)
	(arc
		(start 379.69825 -277.20417)
		(mid 379.420072 -277.273893)
		(end 379.143514 -277.198074)
		(width 0.088646)
		(layer "In4.Cu")
		(net "M_G_CPU0_SA_DQ<0>")
	)
	(arc
		(start 382.150112 -277.522432)
		(mid 382.102433 -277.339532)
		(end 381.97155 -277.203154)
		(width 0.088646)
		(layer "In4.Cu")
		(net "M_G_CPU0_SA_DQ<0>")
	)
	(arc
		(start 385.25196 -279.639776)
		(mid 385.064762 -279.589633)
		(end 384.877564 -279.639776)
		(width 0.088646)
		(layer "In4.Cu")
		(net "M_G_CPU0_SA_DQ<0>")
	)
	(segment
		(start 374.726962 -258.2672)
		(end 374.727216 -258.267454)
		(width 0.20066)
		(layer "F.Cu")
		(net "M_G_CPU0_SA_CS_N<3>")
	)
	(segment
		(start 374.727216 -258.267454)
		(end 374.727216 -258.80314)
		(width 0.20066)
		(layer "F.Cu")
		(net "M_G_CPU0_SA_CS_N<3>")
	)
	(segment
		(start 439.923682 -267.016738)
		(end 441.028582 -267.016738)
		(width 0.20066)
		(layer "F.Cu")
		(net "M_G_CPU0_SA_CS_N<3>")
	)
	(segment
		(start 430.215294 -264.802366)
		(end 430.050956 -264.638028)
		(width 0.18288)
		(layer "In4.Cu")
		(net "M_G_CPU0_SA_CS_N<3>")
	)
	(segment
		(start 384.94208 -256.33299)
		(end 384.730244 -256.544826)
		(width 0.088646)
		(layer "In4.Cu")
		(net "M_G_CPU0_SA_CS_N<3>")
	)
	(segment
		(start 407.531824 -263.018524)
		(end 406.935178 -262.421878)
		(width 0.18288)
		(layer "In4.Cu")
		(net "M_G_CPU0_SA_CS_N<3>")
	)
	(segment
		(start 434.250084 -267.31341)
		(end 432.51882 -265.582146)
		(width 0.18288)
		(layer "In4.Cu")
		(net "M_G_CPU0_SA_CS_N<3>")
	)
	(segment
		(start 377.27255 -258.308348)
		(end 377.26366 -258.313428)
		(width 0.088646)
		(layer "In4.Cu")
		(net "M_G_CPU0_SA_CS_N<3>")
	)
	(segment
		(start 427.622462 -264.890758)
		(end 423.98823 -264.890758)
		(width 0.18288)
		(layer "In4.Cu")
		(net "M_G_CPU0_SA_CS_N<3>")
	)
	(segment
		(start 395.40434 -257.578606)
		(end 392.807952 -257.578606)
		(width 0.18288)
		(layer "In4.Cu")
		(net "M_G_CPU0_SA_CS_N<3>")
	)
	(segment
		(start 392.807952 -257.578606)
		(end 389.800592 -256.33299)
		(width 0.18288)
		(layer "In4.Cu")
		(net "M_G_CPU0_SA_CS_N<3>")
	)
	(segment
		(start 430.890934 -264.802366)
		(end 430.215294 -264.802366)
		(width 0.18288)
		(layer "In4.Cu")
		(net "M_G_CPU0_SA_CS_N<3>")
	)
	(segment
		(start 409.528772 -263.312402)
		(end 409.234894 -263.018524)
		(width 0.18288)
		(layer "In4.Cu")
		(net "M_G_CPU0_SA_CS_N<3>")
	)
	(segment
		(start 432.51882 -265.582146)
		(end 431.670714 -265.582146)
		(width 0.18288)
		(layer "In4.Cu")
		(net "M_G_CPU0_SA_CS_N<3>")
	)
	(segment
		(start 378.768864 -256.685796)
		(end 378.754132 -256.67716)
		(width 0.088646)
		(layer "In4.Cu")
		(net "M_G_CPU0_SA_CS_N<3>")
	)
	(segment
		(start 409.234894 -263.018524)
		(end 407.531824 -263.018524)
		(width 0.18288)
		(layer "In4.Cu")
		(net "M_G_CPU0_SA_CS_N<3>")
	)
	(segment
		(start 376.041666 -258.781042)
		(end 376.041666 -258.80314)
		(width 0.088646)
		(layer "In4.Cu")
		(net "M_G_CPU0_SA_CS_N<3>")
	)
	(segment
		(start 437.720994 -266.552426)
		(end 436.830724 -267.442696)
		(width 0.18288)
		(layer "In4.Cu")
		(net "M_G_CPU0_SA_CS_N<3>")
	)
	(segment
		(start 374.88368 -259.074158)
		(end 374.727216 -258.80314)
		(width 0.088646)
		(layer "In4.Cu")
		(net "M_G_CPU0_SA_CS_N<3>")
	)
	(segment
		(start 439.45937 -266.552426)
		(end 437.720994 -266.552426)
		(width 0.18288)
		(layer "In4.Cu")
		(net "M_G_CPU0_SA_CS_N<3>")
	)
	(segment
		(start 410.986478 -264.042652)
		(end 410.256228 -263.312402)
		(width 0.18288)
		(layer "In4.Cu")
		(net "M_G_CPU0_SA_CS_N<3>")
	)
	(segment
		(start 374.97258 -259.09778)
		(end 374.88368 -259.074158)
		(width 0.088646)
		(layer "In4.Cu")
		(net "M_G_CPU0_SA_CS_N<3>")
	)
	(segment
		(start 435.942994 -267.440918)
		(end 435.612794 -267.440918)
		(width 0.18288)
		(layer "In4.Cu")
		(net "M_G_CPU0_SA_CS_N<3>")
	)
	(segment
		(start 439.923682 -267.016738)
		(end 439.45937 -266.552426)
		(width 0.18288)
		(layer "In4.Cu")
		(net "M_G_CPU0_SA_CS_N<3>")
	)
	(segment
		(start 381.588264 -256.685796)
		(end 381.573532 -256.67716)
		(width 0.088646)
		(layer "In4.Cu")
		(net "M_G_CPU0_SA_CS_N<3>")
	)
	(segment
		(start 379.708664 -256.685796)
		(end 379.693932 -256.67716)
		(width 0.088646)
		(layer "In4.Cu")
		(net "M_G_CPU0_SA_CS_N<3>")
	)
	(segment
		(start 406.935178 -262.421878)
		(end 405.018494 -262.421878)
		(width 0.18288)
		(layer "In4.Cu")
		(net "M_G_CPU0_SA_CS_N<3>")
	)
	(segment
		(start 435.942994 -267.442696)
		(end 435.942994 -267.440918)
		(width 0.18288)
		(layer "In4.Cu")
		(net "M_G_CPU0_SA_CS_N<3>")
	)
	(segment
		(start 389.800592 -256.33299)
		(end 385.233418 -256.33299)
		(width 0.18288)
		(layer "In4.Cu")
		(net "M_G_CPU0_SA_CS_N<3>")
	)
	(segment
		(start 435.512718 -267.38707)
		(end 435.376066 -267.31341)
		(width 0.18288)
		(layer "In4.Cu")
		(net "M_G_CPU0_SA_CS_N<3>")
	)
	(segment
		(start 410.256228 -263.312402)
		(end 409.528772 -263.312402)
		(width 0.18288)
		(layer "In4.Cu")
		(net "M_G_CPU0_SA_CS_N<3>")
	)
	(segment
		(start 399.983452 -257.386836)
		(end 395.86789 -257.386836)
		(width 0.18288)
		(layer "In4.Cu")
		(net "M_G_CPU0_SA_CS_N<3>")
	)
	(segment
		(start 385.233418 -256.33299)
		(end 384.94208 -256.33299)
		(width 0.088646)
		(layer "In4.Cu")
		(net "M_G_CPU0_SA_CS_N<3>")
	)
	(segment
		(start 377.921266 -257.15976)
		(end 377.921266 -257.175254)
		(width 0.088646)
		(layer "In4.Cu")
		(net "M_G_CPU0_SA_CS_N<3>")
	)
	(segment
		(start 405.018494 -262.421878)
		(end 399.983452 -257.386836)
		(width 0.18288)
		(layer "In4.Cu")
		(net "M_G_CPU0_SA_CS_N<3>")
	)
	(segment
		(start 427.875192 -264.638028)
		(end 427.622462 -264.890758)
		(width 0.18288)
		(layer "In4.Cu")
		(net "M_G_CPU0_SA_CS_N<3>")
	)
	(segment
		(start 436.830724 -267.442696)
		(end 435.942994 -267.442696)
		(width 0.18288)
		(layer "In4.Cu")
		(net "M_G_CPU0_SA_CS_N<3>")
	)
	(segment
		(start 430.050956 -264.638028)
		(end 427.875192 -264.638028)
		(width 0.18288)
		(layer "In4.Cu")
		(net "M_G_CPU0_SA_CS_N<3>")
	)
	(segment
		(start 423.140124 -264.042652)
		(end 410.986478 -264.042652)
		(width 0.18288)
		(layer "In4.Cu")
		(net "M_G_CPU0_SA_CS_N<3>")
	)
	(segment
		(start 377.733814 -257.499612)
		(end 377.727718 -257.503168)
		(width 0.088646)
		(layer "In4.Cu")
		(net "M_G_CPU0_SA_CS_N<3>")
	)
	(segment
		(start 423.98823 -264.890758)
		(end 423.140124 -264.042652)
		(width 0.18288)
		(layer "In4.Cu")
		(net "M_G_CPU0_SA_CS_N<3>")
	)
	(segment
		(start 384.730244 -256.544826)
		(end 384.368548 -256.544826)
		(width 0.088646)
		(layer "In4.Cu")
		(net "M_G_CPU0_SA_CS_N<3>")
	)
	(segment
		(start 376.889264 -258.313428)
		(end 376.874532 -258.304792)
		(width 0.088646)
		(layer "In4.Cu")
		(net "M_G_CPU0_SA_CS_N<3>")
	)
	(segment
		(start 435.612794 -267.440918)
		(end 435.512718 -267.38707)
		(width 0.18288)
		(layer "In4.Cu")
		(net "M_G_CPU0_SA_CS_N<3>")
	)
	(segment
		(start 377.742704 -257.494532)
		(end 377.733814 -257.499612)
		(width 0.088646)
		(layer "In4.Cu")
		(net "M_G_CPU0_SA_CS_N<3>")
	)
	(segment
		(start 395.86789 -257.386836)
		(end 395.40434 -257.578606)
		(width 0.18288)
		(layer "In4.Cu")
		(net "M_G_CPU0_SA_CS_N<3>")
	)
	(segment
		(start 431.670714 -265.582146)
		(end 430.890934 -264.802366)
		(width 0.18288)
		(layer "In4.Cu")
		(net "M_G_CPU0_SA_CS_N<3>")
	)
	(segment
		(start 435.376066 -267.31341)
		(end 434.250084 -267.31341)
		(width 0.18288)
		(layer "In4.Cu")
		(net "M_G_CPU0_SA_CS_N<3>")
	)
	(segment
		(start 375.863104 -259.122418)
		(end 375.854214 -259.127498)
		(width 0.088646)
		(layer "In4.Cu")
		(net "M_G_CPU0_SA_CS_N<3>")
	)
	(arc
		(start 375.479818 -259.127498)
		(mid 375.229721 -259.052438)
		(end 374.97258 -259.09778)
		(width 0.088646)
		(layer "In4.Cu")
		(net "M_G_CPU0_SA_CS_N<3>")
	)
	(arc
		(start 376.041666 -258.80314)
		(mid 375.993987 -258.98604)
		(end 375.863104 -259.122418)
		(width 0.088646)
		(layer "In4.Cu")
		(net "M_G_CPU0_SA_CS_N<3>")
	)
	(arc
		(start 383.467864 -256.685796)
		(mid 383.185162 -256.61002)
		(end 382.90246 -256.685796)
		(width 0.088646)
		(layer "In4.Cu")
		(net "M_G_CPU0_SA_CS_N<3>")
	)
	(arc
		(start 377.451112 -257.98907)
		(mid 377.403433 -258.17197)
		(end 377.27255 -258.308348)
		(width 0.088646)
		(layer "In4.Cu")
		(net "M_G_CPU0_SA_CS_N<3>")
	)
	(arc
		(start 376.874532 -258.304792)
		(mid 376.598091 -258.237626)
		(end 376.32386 -258.313428)
		(width 0.088646)
		(layer "In4.Cu")
		(net "M_G_CPU0_SA_CS_N<3>")
	)
	(arc
		(start 376.32386 -258.313428)
		(mid 376.122578 -258.510915)
		(end 376.041666 -258.781042)
		(width 0.088646)
		(layer "In4.Cu")
		(net "M_G_CPU0_SA_CS_N<3>")
	)
	(arc
		(start 377.26366 -258.313428)
		(mid 377.076462 -258.363571)
		(end 376.889264 -258.313428)
		(width 0.088646)
		(layer "In4.Cu")
		(net "M_G_CPU0_SA_CS_N<3>")
	)
	(arc
		(start 381.573532 -256.67716)
		(mid 381.297057 -256.60984)
		(end 381.02286 -256.685796)
		(width 0.088646)
		(layer "In4.Cu")
		(net "M_G_CPU0_SA_CS_N<3>")
	)
	(arc
		(start 377.921266 -257.175254)
		(mid 377.873587 -257.358154)
		(end 377.742704 -257.494532)
		(width 0.088646)
		(layer "In4.Cu")
		(net "M_G_CPU0_SA_CS_N<3>")
	)
	(arc
		(start 375.854214 -259.127498)
		(mid 375.667016 -259.177641)
		(end 375.479818 -259.127498)
		(width 0.088646)
		(layer "In4.Cu")
		(net "M_G_CPU0_SA_CS_N<3>")
	)
	(arc
		(start 379.14326 -256.685796)
		(mid 378.956062 -256.735939)
		(end 378.768864 -256.685796)
		(width 0.088646)
		(layer "In4.Cu")
		(net "M_G_CPU0_SA_CS_N<3>")
	)
	(arc
		(start 383.84226 -256.685796)
		(mid 383.655062 -256.735939)
		(end 383.467864 -256.685796)
		(width 0.088646)
		(layer "In4.Cu")
		(net "M_G_CPU0_SA_CS_N<3>")
	)
	(arc
		(start 380.648464 -256.685796)
		(mid 380.365762 -256.61002)
		(end 380.08306 -256.685796)
		(width 0.088646)
		(layer "In4.Cu")
		(net "M_G_CPU0_SA_CS_N<3>")
	)
	(arc
		(start 379.693932 -256.67716)
		(mid 379.417457 -256.60984)
		(end 379.14326 -256.685796)
		(width 0.088646)
		(layer "In4.Cu")
		(net "M_G_CPU0_SA_CS_N<3>")
	)
	(arc
		(start 381.02286 -256.685796)
		(mid 380.835662 -256.735939)
		(end 380.648464 -256.685796)
		(width 0.088646)
		(layer "In4.Cu")
		(net "M_G_CPU0_SA_CS_N<3>")
	)
	(arc
		(start 378.20346 -256.685796)
		(mid 378.000637 -256.886027)
		(end 377.921266 -257.15976)
		(width 0.088646)
		(layer "In4.Cu")
		(net "M_G_CPU0_SA_CS_N<3>")
	)
	(arc
		(start 381.96266 -256.685796)
		(mid 381.775462 -256.735939)
		(end 381.588264 -256.685796)
		(width 0.088646)
		(layer "In4.Cu")
		(net "M_G_CPU0_SA_CS_N<3>")
	)
	(arc
		(start 382.528064 -256.685796)
		(mid 382.245362 -256.61002)
		(end 381.96266 -256.685796)
		(width 0.088646)
		(layer "In4.Cu")
		(net "M_G_CPU0_SA_CS_N<3>")
	)
	(arc
		(start 377.727718 -257.503168)
		(mid 377.525131 -257.709519)
		(end 377.451112 -257.98907)
		(width 0.088646)
		(layer "In4.Cu")
		(net "M_G_CPU0_SA_CS_N<3>")
	)
	(arc
		(start 384.368548 -256.544826)
		(mid 384.096133 -256.580689)
		(end 383.84226 -256.685796)
		(width 0.088646)
		(layer "In4.Cu")
		(net "M_G_CPU0_SA_CS_N<3>")
	)
	(arc
		(start 382.90246 -256.685796)
		(mid 382.715262 -256.735939)
		(end 382.528064 -256.685796)
		(width 0.088646)
		(layer "In4.Cu")
		(net "M_G_CPU0_SA_CS_N<3>")
	)
	(arc
		(start 380.08306 -256.685796)
		(mid 379.895862 -256.735939)
		(end 379.708664 -256.685796)
		(width 0.088646)
		(layer "In4.Cu")
		(net "M_G_CPU0_SA_CS_N<3>")
	)
	(arc
		(start 378.754132 -256.67716)
		(mid 378.477657 -256.60984)
		(end 378.20346 -256.685796)
		(width 0.088646)
		(layer "In4.Cu")
		(net "M_G_CPU0_SA_CS_N<3>")
	)
	(segment
		(start 375.197116 -259.093462)
		(end 375.196862 -259.616956)
		(width 0.20066)
		(layer "F.Cu")
		(net "M_G_CPU0_SA_CS_N<2>")
	)
	(segment
		(start 375.197116 -259.081016)
		(end 375.197116 -259.093462)
		(width 0.20066)
		(layer "F.Cu")
		(net "M_G_CPU0_SA_CS_N<2>")
	)
	(segment
		(start 435.823614 -267.866622)
		(end 436.928514 -267.866622)
		(width 0.20066)
		(layer "F.Cu")
		(net "M_G_CPU0_SA_CS_N<2>")
	)
	(segment
		(start 377.641612 -257.98907)
		(end 377.641612 -258.007612)
		(width 0.088646)
		(layer "In4.Cu")
		(net "M_G_CPU0_SA_CS_N<2>")
	)
	(segment
		(start 392.73988 -257.913886)
		(end 389.764778 -256.681732)
		(width 0.18288)
		(layer "In4.Cu")
		(net "M_G_CPU0_SA_CS_N<2>")
	)
	(segment
		(start 410.993336 -264.892536)
		(end 410.026866 -263.926066)
		(width 0.18288)
		(layer "In4.Cu")
		(net "M_G_CPU0_SA_CS_N<2>")
	)
	(segment
		(start 384.885692 -256.681732)
		(end 384.767074 -256.80035)
		(width 0.088646)
		(layer "In4.Cu")
		(net "M_G_CPU0_SA_CS_N<2>")
	)
	(segment
		(start 423.248074 -264.890758)
		(end 420.542974 -264.890758)
		(width 0.18288)
		(layer "In4.Cu")
		(net "M_G_CPU0_SA_CS_N<2>")
	)
	(segment
		(start 396.040356 -257.77063)
		(end 395.824456 -257.77063)
		(width 0.18288)
		(layer "In4.Cu")
		(net "M_G_CPU0_SA_CS_N<2>")
	)
	(segment
		(start 426.73905 -265.485626)
		(end 426.48378 -265.740896)
		(width 0.18288)
		(layer "In4.Cu")
		(net "M_G_CPU0_SA_CS_N<2>")
	)
	(segment
		(start 375.949464 -259.292598)
		(end 375.934732 -259.301234)
		(width 0.088646)
		(layer "In4.Cu")
		(net "M_G_CPU0_SA_CS_N<2>")
	)
	(segment
		(start 434.723794 -268.398498)
		(end 434.427122 -268.398498)
		(width 0.18288)
		(layer "In4.Cu")
		(net "M_G_CPU0_SA_CS_N<2>")
	)
	(segment
		(start 429.76927 -265.58875)
		(end 428.70247 -265.58875)
		(width 0.18288)
		(layer "In4.Cu")
		(net "M_G_CPU0_SA_CS_N<2>")
	)
	(segment
		(start 381.503428 -256.856992)
		(end 381.493014 -256.850896)
		(width 0.088646)
		(layer "In4.Cu")
		(net "M_G_CPU0_SA_CS_N<2>")
	)
	(segment
		(start 406.654254 -263.107678)
		(end 404.995126 -263.107678)
		(width 0.18288)
		(layer "In4.Cu")
		(net "M_G_CPU0_SA_CS_N<2>")
	)
	(segment
		(start 424.098212 -265.740896)
		(end 423.248074 -264.890758)
		(width 0.18288)
		(layer "In4.Cu")
		(net "M_G_CPU0_SA_CS_N<2>")
	)
	(segment
		(start 378.688346 -256.859532)
		(end 378.673614 -256.850896)
		(width 0.088646)
		(layer "In4.Cu")
		(net "M_G_CPU0_SA_CS_N<2>")
	)
	(segment
		(start 395.824456 -257.77063)
		(end 395.478762 -257.913886)
		(width 0.18288)
		(layer "In4.Cu")
		(net "M_G_CPU0_SA_CS_N<2>")
	)
	(segment
		(start 376.804428 -258.484878)
		(end 376.794014 -258.478782)
		(width 0.088646)
		(layer "In4.Cu")
		(net "M_G_CPU0_SA_CS_N<2>")
	)
	(segment
		(start 384.767074 -256.80035)
		(end 384.124962 -256.80035)
		(width 0.088646)
		(layer "In4.Cu")
		(net "M_G_CPU0_SA_CS_N<2>")
	)
	(segment
		(start 385.233418 -256.681732)
		(end 384.885692 -256.681732)
		(width 0.088646)
		(layer "In4.Cu")
		(net "M_G_CPU0_SA_CS_N<2>")
	)
	(segment
		(start 435.25567 -267.866622)
		(end 434.723794 -268.398498)
		(width 0.18288)
		(layer "In4.Cu")
		(net "M_G_CPU0_SA_CS_N<2>")
	)
	(segment
		(start 395.478762 -257.913886)
		(end 392.73988 -257.913886)
		(width 0.18288)
		(layer "In4.Cu")
		(net "M_G_CPU0_SA_CS_N<2>")
	)
	(segment
		(start 410.026866 -263.926066)
		(end 409.199842 -263.926066)
		(width 0.18288)
		(layer "In4.Cu")
		(net "M_G_CPU0_SA_CS_N<2>")
	)
	(segment
		(start 399.772124 -257.884676)
		(end 396.315692 -257.884676)
		(width 0.18288)
		(layer "In4.Cu")
		(net "M_G_CPU0_SA_CS_N<2>")
	)
	(segment
		(start 432.619912 -266.591288)
		(end 430.771808 -266.591288)
		(width 0.18288)
		(layer "In4.Cu")
		(net "M_G_CPU0_SA_CS_N<2>")
	)
	(segment
		(start 434.427122 -268.398498)
		(end 432.619912 -266.591288)
		(width 0.18288)
		(layer "In4.Cu")
		(net "M_G_CPU0_SA_CS_N<2>")
	)
	(segment
		(start 380.563374 -256.856992)
		(end 380.55296 -256.850896)
		(width 0.088646)
		(layer "In4.Cu")
		(net "M_G_CPU0_SA_CS_N<2>")
	)
	(segment
		(start 430.771808 -266.591288)
		(end 429.76927 -265.58875)
		(width 0.18288)
		(layer "In4.Cu")
		(net "M_G_CPU0_SA_CS_N<2>")
	)
	(segment
		(start 407.636472 -264.089896)
		(end 406.654254 -263.107678)
		(width 0.18288)
		(layer "In4.Cu")
		(net "M_G_CPU0_SA_CS_N<2>")
	)
	(segment
		(start 377.83516 -257.661156)
		(end 377.829064 -257.664712)
		(width 0.088646)
		(layer "In4.Cu")
		(net "M_G_CPU0_SA_CS_N<2>")
	)
	(segment
		(start 375.040398 -259.345938)
		(end 375.196862 -259.616956)
		(width 0.088646)
		(layer "In4.Cu")
		(net "M_G_CPU0_SA_CS_N<2>")
	)
	(segment
		(start 376.419618 -258.478782)
		(end 376.410728 -258.483862)
		(width 0.088646)
		(layer "In4.Cu")
		(net "M_G_CPU0_SA_CS_N<2>")
	)
	(segment
		(start 426.48378 -265.740896)
		(end 424.098212 -265.740896)
		(width 0.18288)
		(layer "In4.Cu")
		(net "M_G_CPU0_SA_CS_N<2>")
	)
	(segment
		(start 428.70247 -265.58875)
		(end 428.424594 -265.866626)
		(width 0.18288)
		(layer "In4.Cu")
		(net "M_G_CPU0_SA_CS_N<2>")
	)
	(segment
		(start 396.158974 -257.819652)
		(end 396.040356 -257.77063)
		(width 0.18288)
		(layer "In4.Cu")
		(net "M_G_CPU0_SA_CS_N<2>")
	)
	(segment
		(start 428.424594 -265.866626)
		(end 427.560994 -265.866626)
		(width 0.18288)
		(layer "In4.Cu")
		(net "M_G_CPU0_SA_CS_N<2>")
	)
	(segment
		(start 377.829064 -257.664712)
		(end 377.820174 -257.669792)
		(width 0.088646)
		(layer "In4.Cu")
		(net "M_G_CPU0_SA_CS_N<2>")
	)
	(segment
		(start 379.623828 -256.856992)
		(end 379.613414 -256.850896)
		(width 0.088646)
		(layer "In4.Cu")
		(net "M_G_CPU0_SA_CS_N<2>")
	)
	(segment
		(start 427.179994 -265.485626)
		(end 426.73905 -265.485626)
		(width 0.18288)
		(layer "In4.Cu")
		(net "M_G_CPU0_SA_CS_N<2>")
	)
	(segment
		(start 435.823614 -267.866622)
		(end 435.25567 -267.866622)
		(width 0.18288)
		(layer "In4.Cu")
		(net "M_G_CPU0_SA_CS_N<2>")
	)
	(segment
		(start 420.542974 -264.892536)
		(end 410.993336 -264.892536)
		(width 0.18288)
		(layer "In4.Cu")
		(net "M_G_CPU0_SA_CS_N<2>")
	)
	(segment
		(start 375.95556 -259.289042)
		(end 375.949464 -259.292598)
		(width 0.088646)
		(layer "In4.Cu")
		(net "M_G_CPU0_SA_CS_N<2>")
	)
	(segment
		(start 409.036012 -264.089896)
		(end 407.636472 -264.089896)
		(width 0.18288)
		(layer "In4.Cu")
		(net "M_G_CPU0_SA_CS_N<2>")
	)
	(segment
		(start 378.299218 -256.850896)
		(end 378.290328 -256.855976)
		(width 0.088646)
		(layer "In4.Cu")
		(net "M_G_CPU0_SA_CS_N<2>")
	)
	(segment
		(start 375.06148 -259.26796)
		(end 375.040398 -259.345938)
		(width 0.088646)
		(layer "In4.Cu")
		(net "M_G_CPU0_SA_CS_N<2>")
	)
	(segment
		(start 396.315692 -257.884676)
		(end 396.158974 -257.819652)
		(width 0.18288)
		(layer "In4.Cu")
		(net "M_G_CPU0_SA_CS_N<2>")
	)
	(segment
		(start 427.560994 -265.866626)
		(end 427.179994 -265.485626)
		(width 0.18288)
		(layer "In4.Cu")
		(net "M_G_CPU0_SA_CS_N<2>")
	)
	(segment
		(start 409.199842 -263.926066)
		(end 409.036012 -264.089896)
		(width 0.18288)
		(layer "In4.Cu")
		(net "M_G_CPU0_SA_CS_N<2>")
	)
	(segment
		(start 404.995126 -263.107678)
		(end 399.772124 -257.884676)
		(width 0.18288)
		(layer "In4.Cu")
		(net "M_G_CPU0_SA_CS_N<2>")
	)
	(segment
		(start 420.542974 -264.890758)
		(end 420.542974 -264.892536)
		(width 0.18288)
		(layer "In4.Cu")
		(net "M_G_CPU0_SA_CS_N<2>")
	)
	(segment
		(start 389.764778 -256.681732)
		(end 385.233418 -256.681732)
		(width 0.18288)
		(layer "In4.Cu")
		(net "M_G_CPU0_SA_CS_N<2>")
	)
	(arc
		(start 377.641612 -258.007612)
		(mid 377.56145 -258.279801)
		(end 377.359164 -258.478782)
		(width 0.088646)
		(layer "In4.Cu")
		(net "M_G_CPU0_SA_CS_N<2>")
	)
	(arc
		(start 381.118618 -256.850896)
		(mid 380.841805 -256.926766)
		(end 380.563374 -256.856992)
		(width 0.088646)
		(layer "In4.Cu")
		(net "M_G_CPU0_SA_CS_N<2>")
	)
	(arc
		(start 379.239018 -256.850896)
		(mid 378.964819 -256.926731)
		(end 378.688346 -256.859532)
		(width 0.088646)
		(layer "In4.Cu")
		(net "M_G_CPU0_SA_CS_N<2>")
	)
	(arc
		(start 376.794014 -258.478782)
		(mid 376.606816 -258.428639)
		(end 376.419618 -258.478782)
		(width 0.088646)
		(layer "In4.Cu")
		(net "M_G_CPU0_SA_CS_N<2>")
	)
	(arc
		(start 378.111766 -257.175254)
		(mid 378.037775 -257.45482)
		(end 377.83516 -257.661156)
		(width 0.088646)
		(layer "In4.Cu")
		(net "M_G_CPU0_SA_CS_N<2>")
	)
	(arc
		(start 382.43256 -256.850896)
		(mid 382.245362 -256.800753)
		(end 382.058164 -256.850896)
		(width 0.088646)
		(layer "In4.Cu")
		(net "M_G_CPU0_SA_CS_N<2>")
	)
	(arc
		(start 382.997964 -256.850896)
		(mid 382.715262 -256.926672)
		(end 382.43256 -256.850896)
		(width 0.088646)
		(layer "In4.Cu")
		(net "M_G_CPU0_SA_CS_N<2>")
	)
	(arc
		(start 378.673614 -256.850896)
		(mid 378.486416 -256.800753)
		(end 378.299218 -256.850896)
		(width 0.088646)
		(layer "In4.Cu")
		(net "M_G_CPU0_SA_CS_N<2>")
	)
	(arc
		(start 379.613414 -256.850896)
		(mid 379.426216 -256.800753)
		(end 379.239018 -256.850896)
		(width 0.088646)
		(layer "In4.Cu")
		(net "M_G_CPU0_SA_CS_N<2>")
	)
	(arc
		(start 381.493014 -256.850896)
		(mid 381.305816 -256.800753)
		(end 381.118618 -256.850896)
		(width 0.088646)
		(layer "In4.Cu")
		(net "M_G_CPU0_SA_CS_N<2>")
	)
	(arc
		(start 378.290328 -256.855976)
		(mid 378.159414 -256.992336)
		(end 378.111766 -257.175254)
		(width 0.088646)
		(layer "In4.Cu")
		(net "M_G_CPU0_SA_CS_N<2>")
	)
	(arc
		(start 376.410728 -258.483862)
		(mid 376.279814 -258.620222)
		(end 376.232166 -258.80314)
		(width 0.088646)
		(layer "In4.Cu")
		(net "M_G_CPU0_SA_CS_N<2>")
	)
	(arc
		(start 377.359164 -258.478782)
		(mid 377.082605 -258.554491)
		(end 376.804428 -258.484878)
		(width 0.088646)
		(layer "In4.Cu")
		(net "M_G_CPU0_SA_CS_N<2>")
	)
	(arc
		(start 384.124962 -256.80035)
		(mid 384.028039 -256.813308)
		(end 383.937764 -256.850896)
		(width 0.088646)
		(layer "In4.Cu")
		(net "M_G_CPU0_SA_CS_N<2>")
	)
	(arc
		(start 375.38406 -259.292598)
		(mid 375.225572 -259.243665)
		(end 375.06148 -259.26796)
		(width 0.088646)
		(layer "In4.Cu")
		(net "M_G_CPU0_SA_CS_N<2>")
	)
	(arc
		(start 383.37236 -256.850896)
		(mid 383.185162 -256.800753)
		(end 382.997964 -256.850896)
		(width 0.088646)
		(layer "In4.Cu")
		(net "M_G_CPU0_SA_CS_N<2>")
	)
	(arc
		(start 375.934732 -259.301234)
		(mid 375.658257 -259.368554)
		(end 375.38406 -259.292598)
		(width 0.088646)
		(layer "In4.Cu")
		(net "M_G_CPU0_SA_CS_N<2>")
	)
	(arc
		(start 377.820174 -257.669792)
		(mid 377.68926 -257.806152)
		(end 377.641612 -257.98907)
		(width 0.088646)
		(layer "In4.Cu")
		(net "M_G_CPU0_SA_CS_N<2>")
	)
	(arc
		(start 376.232166 -258.80314)
		(mid 376.158175 -259.082706)
		(end 375.95556 -259.289042)
		(width 0.088646)
		(layer "In4.Cu")
		(net "M_G_CPU0_SA_CS_N<2>")
	)
	(arc
		(start 380.55296 -256.850896)
		(mid 380.365762 -256.800753)
		(end 380.178564 -256.850896)
		(width 0.088646)
		(layer "In4.Cu")
		(net "M_G_CPU0_SA_CS_N<2>")
	)
	(arc
		(start 382.058164 -256.850896)
		(mid 381.781605 -256.926639)
		(end 381.503428 -256.856992)
		(width 0.088646)
		(layer "In4.Cu")
		(net "M_G_CPU0_SA_CS_N<2>")
	)
	(arc
		(start 380.178564 -256.850896)
		(mid 379.902005 -256.926639)
		(end 379.623828 -256.856992)
		(width 0.088646)
		(layer "In4.Cu")
		(net "M_G_CPU0_SA_CS_N<2>")
	)
	(arc
		(start 383.937764 -256.850896)
		(mid 383.655062 -256.926672)
		(end 383.37236 -256.850896)
		(width 0.088646)
		(layer "In4.Cu")
		(net "M_G_CPU0_SA_CS_N<2>")
	)
	(segment
		(start 376.606816 -258.267454)
		(end 376.606816 -258.80314)
		(width 0.20066)
		(layer "F.Cu")
		(net "M_G_CPU0_SA_CS_N<1>")
	)
	(segment
		(start 447.467482 -267.016738)
		(end 448.572382 -267.016738)
		(width 0.20066)
		(layer "F.Cu")
		(net "M_G_CPU0_SA_CS_N<1>")
	)
	(segment
		(start 376.606562 -258.2672)
		(end 376.606816 -258.267454)
		(width 0.20066)
		(layer "F.Cu")
		(net "M_G_CPU0_SA_CS_N<1>")
	)
	(segment
		(start 426.222922 -266.589002)
		(end 423.453052 -266.589002)
		(width 0.18288)
		(layer "In4.Cu")
		(net "M_G_CPU0_SA_CS_N<1>")
	)
	(segment
		(start 378.673614 -257.499612)
		(end 378.667518 -257.503168)
		(width 0.088646)
		(layer "In4.Cu")
		(net "M_G_CPU0_SA_CS_N<1>")
	)
	(segment
		(start 399.558256 -258.382516)
		(end 396.02791 -258.382516)
		(width 0.18288)
		(layer "In4.Cu")
		(net "M_G_CPU0_SA_CS_N<1>")
	)
	(segment
		(start 392.69035 -258.256532)
		(end 389.743188 -257.035808)
		(width 0.18288)
		(layer "In4.Cu")
		(net "M_G_CPU0_SA_CS_N<1>")
	)
	(segment
		(start 442.698124 -266.573762)
		(end 441.830714 -267.441172)
		(width 0.18288)
		(layer "In4.Cu")
		(net "M_G_CPU0_SA_CS_N<1>")
	)
	(segment
		(start 396.02791 -258.382516)
		(end 395.722094 -258.256532)
		(width 0.18288)
		(layer "In4.Cu")
		(net "M_G_CPU0_SA_CS_N<1>")
	)
	(segment
		(start 378.21235 -258.308348)
		(end 378.20346 -258.313428)
		(width 0.088646)
		(layer "In4.Cu")
		(net "M_G_CPU0_SA_CS_N<1>")
	)
	(segment
		(start 385.096004 -257.035808)
		(end 384.788156 -257.343656)
		(width 0.088646)
		(layer "In4.Cu")
		(net "M_G_CPU0_SA_CS_N<1>")
	)
	(segment
		(start 447.467482 -267.016738)
		(end 447.024506 -266.573762)
		(width 0.18288)
		(layer "In4.Cu")
		(net "M_G_CPU0_SA_CS_N<1>")
	)
	(segment
		(start 434.157882 -268.985746)
		(end 432.612292 -267.440156)
		(width 0.18288)
		(layer "In4.Cu")
		(net "M_G_CPU0_SA_CS_N<1>")
	)
	(segment
		(start 426.389546 -266.755626)
		(end 426.222922 -266.589002)
		(width 0.18288)
		(layer "In4.Cu")
		(net "M_G_CPU0_SA_CS_N<1>")
	)
	(segment
		(start 405.460454 -264.284714)
		(end 399.558256 -258.382516)
		(width 0.18288)
		(layer "In4.Cu")
		(net "M_G_CPU0_SA_CS_N<1>")
	)
	(segment
		(start 380.178564 -257.499612)
		(end 380.16815 -257.493516)
		(width 0.088646)
		(layer "In4.Cu")
		(net "M_G_CPU0_SA_CS_N<1>")
	)
	(segment
		(start 376.455686 -259.093462)
		(end 376.450352 -259.074158)
		(width 0.088646)
		(layer "In4.Cu")
		(net "M_G_CPU0_SA_CS_N<1>")
	)
	(segment
		(start 389.743188 -257.035808)
		(end 385.233418 -257.035808)
		(width 0.18288)
		(layer "In4.Cu")
		(net "M_G_CPU0_SA_CS_N<1>")
	)
	(segment
		(start 376.471434 -259.152136)
		(end 376.455686 -259.093462)
		(width 0.088646)
		(layer "In4.Cu")
		(net "M_G_CPU0_SA_CS_N<1>")
	)
	(segment
		(start 437.60898 -267.441172)
		(end 436.757572 -268.29258)
		(width 0.18288)
		(layer "In4.Cu")
		(net "M_G_CPU0_SA_CS_N<1>")
	)
	(segment
		(start 407.043636 -264.284714)
		(end 405.460454 -264.284714)
		(width 0.18288)
		(layer "In4.Cu")
		(net "M_G_CPU0_SA_CS_N<1>")
	)
	(segment
		(start 378.688346 -257.490976)
		(end 378.673614 -257.499612)
		(width 0.088646)
		(layer "In4.Cu")
		(net "M_G_CPU0_SA_CS_N<1>")
	)
	(segment
		(start 385.233418 -257.035808)
		(end 385.096004 -257.035808)
		(width 0.088646)
		(layer "In4.Cu")
		(net "M_G_CPU0_SA_CS_N<1>")
	)
	(segment
		(start 410.179774 -264.990072)
		(end 408.46756 -264.990072)
		(width 0.18288)
		(layer "In4.Cu")
		(net "M_G_CPU0_SA_CS_N<1>")
	)
	(segment
		(start 427.804834 -266.460986)
		(end 427.510194 -266.755626)
		(width 0.18288)
		(layer "In4.Cu")
		(net "M_G_CPU0_SA_CS_N<1>")
	)
	(segment
		(start 376.450352 -259.074158)
		(end 376.606816 -258.80314)
		(width 0.088646)
		(layer "In4.Cu")
		(net "M_G_CPU0_SA_CS_N<1>")
	)
	(segment
		(start 435.665626 -268.290802)
		(end 435.490366 -268.383004)
		(width 0.18288)
		(layer "In4.Cu")
		(net "M_G_CPU0_SA_CS_N<1>")
	)
	(segment
		(start 377.74245 -259.122418)
		(end 377.73356 -259.127498)
		(width 0.088646)
		(layer "In4.Cu")
		(net "M_G_CPU0_SA_CS_N<1>")
	)
	(segment
		(start 441.830714 -267.441172)
		(end 437.60898 -267.441172)
		(width 0.18288)
		(layer "In4.Cu")
		(net "M_G_CPU0_SA_CS_N<1>")
	)
	(segment
		(start 376.804428 -259.121402)
		(end 376.794014 -259.127498)
		(width 0.088646)
		(layer "In4.Cu")
		(net "M_G_CPU0_SA_CS_N<1>")
	)
	(segment
		(start 447.024506 -266.573762)
		(end 442.698124 -266.573762)
		(width 0.18288)
		(layer "In4.Cu")
		(net "M_G_CPU0_SA_CS_N<1>")
	)
	(segment
		(start 435.42204 -268.418818)
		(end 434.855112 -268.985746)
		(width 0.18288)
		(layer "In4.Cu")
		(net "M_G_CPU0_SA_CS_N<1>")
	)
	(segment
		(start 435.490366 -268.383004)
		(end 435.42204 -268.418818)
		(width 0.18288)
		(layer "In4.Cu")
		(net "M_G_CPU0_SA_CS_N<1>")
	)
	(segment
		(start 423.453052 -266.589002)
		(end 422.604946 -265.740896)
		(width 0.18288)
		(layer "In4.Cu")
		(net "M_G_CPU0_SA_CS_N<1>")
	)
	(segment
		(start 395.722094 -258.256532)
		(end 392.69035 -258.256532)
		(width 0.18288)
		(layer "In4.Cu")
		(net "M_G_CPU0_SA_CS_N<1>")
	)
	(segment
		(start 407.454354 -264.695432)
		(end 407.043636 -264.284714)
		(width 0.18288)
		(layer "In4.Cu")
		(net "M_G_CPU0_SA_CS_N<1>")
	)
	(segment
		(start 420.530274 -265.740896)
		(end 420.530274 -265.742674)
		(width 0.18288)
		(layer "In4.Cu")
		(net "M_G_CPU0_SA_CS_N<1>")
	)
	(segment
		(start 434.855112 -268.985746)
		(end 434.157882 -268.985746)
		(width 0.18288)
		(layer "In4.Cu")
		(net "M_G_CPU0_SA_CS_N<1>")
	)
	(segment
		(start 432.612292 -267.440156)
		(end 429.850804 -267.440156)
		(width 0.18288)
		(layer "In4.Cu")
		(net "M_G_CPU0_SA_CS_N<1>")
	)
	(segment
		(start 377.921012 -258.788916)
		(end 377.921012 -258.80314)
		(width 0.088646)
		(layer "In4.Cu")
		(net "M_G_CPU0_SA_CS_N<1>")
	)
	(segment
		(start 436.044594 -268.29258)
		(end 436.044594 -268.290802)
		(width 0.18288)
		(layer "In4.Cu")
		(net "M_G_CPU0_SA_CS_N<1>")
	)
	(segment
		(start 436.044594 -268.290802)
		(end 435.665626 -268.290802)
		(width 0.18288)
		(layer "In4.Cu")
		(net "M_G_CPU0_SA_CS_N<1>")
	)
	(segment
		(start 408.17292 -264.695432)
		(end 407.454354 -264.695432)
		(width 0.18288)
		(layer "In4.Cu")
		(net "M_G_CPU0_SA_CS_N<1>")
	)
	(segment
		(start 420.530274 -265.742674)
		(end 410.932376 -265.742674)
		(width 0.18288)
		(layer "In4.Cu")
		(net "M_G_CPU0_SA_CS_N<1>")
	)
	(segment
		(start 410.932376 -265.742674)
		(end 410.179774 -264.990072)
		(width 0.18288)
		(layer "In4.Cu")
		(net "M_G_CPU0_SA_CS_N<1>")
	)
	(segment
		(start 384.788156 -257.343656)
		(end 384.595116 -257.423666)
		(width 0.088646)
		(layer "In4.Cu")
		(net "M_G_CPU0_SA_CS_N<1>")
	)
	(segment
		(start 408.46756 -264.990072)
		(end 408.17292 -264.695432)
		(width 0.18288)
		(layer "In4.Cu")
		(net "M_G_CPU0_SA_CS_N<1>")
	)
	(segment
		(start 422.604946 -265.740896)
		(end 420.530274 -265.740896)
		(width 0.18288)
		(layer "In4.Cu")
		(net "M_G_CPU0_SA_CS_N<1>")
	)
	(segment
		(start 380.563374 -257.493516)
		(end 380.55296 -257.499612)
		(width 0.088646)
		(layer "In4.Cu")
		(net "M_G_CPU0_SA_CS_N<1>")
	)
	(segment
		(start 429.850804 -267.440156)
		(end 428.871634 -266.460986)
		(width 0.18288)
		(layer "In4.Cu")
		(net "M_G_CPU0_SA_CS_N<1>")
	)
	(segment
		(start 382.058164 -257.499612)
		(end 382.04775 -257.493516)
		(width 0.088646)
		(layer "In4.Cu")
		(net "M_G_CPU0_SA_CS_N<1>")
	)
	(segment
		(start 427.510194 -266.755626)
		(end 426.389546 -266.755626)
		(width 0.18288)
		(layer "In4.Cu")
		(net "M_G_CPU0_SA_CS_N<1>")
	)
	(segment
		(start 436.757572 -268.29258)
		(end 436.044594 -268.29258)
		(width 0.18288)
		(layer "In4.Cu")
		(net "M_G_CPU0_SA_CS_N<1>")
	)
	(segment
		(start 428.871634 -266.460986)
		(end 427.804834 -266.460986)
		(width 0.18288)
		(layer "In4.Cu")
		(net "M_G_CPU0_SA_CS_N<1>")
	)
	(arc
		(start 380.55296 -257.499612)
		(mid 380.365762 -257.549755)
		(end 380.178564 -257.499612)
		(width 0.088646)
		(layer "In4.Cu")
		(net "M_G_CPU0_SA_CS_N<1>")
	)
	(arc
		(start 382.04775 -257.493516)
		(mid 381.769572 -257.423793)
		(end 381.493014 -257.499612)
		(width 0.088646)
		(layer "In4.Cu")
		(net "M_G_CPU0_SA_CS_N<1>")
	)
	(arc
		(start 378.20346 -258.313428)
		(mid 378.000155 -258.514294)
		(end 377.921012 -258.788916)
		(width 0.088646)
		(layer "In4.Cu")
		(net "M_G_CPU0_SA_CS_N<1>")
	)
	(arc
		(start 378.667518 -257.503168)
		(mid 378.464931 -257.709519)
		(end 378.390912 -257.98907)
		(width 0.088646)
		(layer "In4.Cu")
		(net "M_G_CPU0_SA_CS_N<1>")
	)
	(arc
		(start 381.493014 -257.499612)
		(mid 381.305816 -257.549755)
		(end 381.118618 -257.499612)
		(width 0.088646)
		(layer "In4.Cu")
		(net "M_G_CPU0_SA_CS_N<1>")
	)
	(arc
		(start 384.595116 -257.423666)
		(mid 384.448629 -257.442981)
		(end 384.31216 -257.499612)
		(width 0.088646)
		(layer "In4.Cu")
		(net "M_G_CPU0_SA_CS_N<1>")
	)
	(arc
		(start 379.613414 -257.499612)
		(mid 379.426216 -257.549755)
		(end 379.239018 -257.499612)
		(width 0.088646)
		(layer "In4.Cu")
		(net "M_G_CPU0_SA_CS_N<1>")
	)
	(arc
		(start 377.921012 -258.80314)
		(mid 377.873333 -258.98604)
		(end 377.74245 -259.122418)
		(width 0.088646)
		(layer "In4.Cu")
		(net "M_G_CPU0_SA_CS_N<1>")
	)
	(arc
		(start 377.73356 -259.127498)
		(mid 377.546362 -259.177641)
		(end 377.359164 -259.127498)
		(width 0.088646)
		(layer "In4.Cu")
		(net "M_G_CPU0_SA_CS_N<1>")
	)
	(arc
		(start 383.937764 -257.499612)
		(mid 383.655062 -257.423836)
		(end 383.37236 -257.499612)
		(width 0.088646)
		(layer "In4.Cu")
		(net "M_G_CPU0_SA_CS_N<1>")
	)
	(arc
		(start 376.794014 -259.127498)
		(mid 376.635526 -259.176431)
		(end 376.471434 -259.152136)
		(width 0.088646)
		(layer "In4.Cu")
		(net "M_G_CPU0_SA_CS_N<1>")
	)
	(arc
		(start 384.31216 -257.499612)
		(mid 384.124962 -257.549755)
		(end 383.937764 -257.499612)
		(width 0.088646)
		(layer "In4.Cu")
		(net "M_G_CPU0_SA_CS_N<1>")
	)
	(arc
		(start 381.118618 -257.499612)
		(mid 380.841805 -257.423742)
		(end 380.563374 -257.493516)
		(width 0.088646)
		(layer "In4.Cu")
		(net "M_G_CPU0_SA_CS_N<1>")
	)
	(arc
		(start 380.16815 -257.493516)
		(mid 379.889972 -257.423793)
		(end 379.613414 -257.499612)
		(width 0.088646)
		(layer "In4.Cu")
		(net "M_G_CPU0_SA_CS_N<1>")
	)
	(arc
		(start 382.43256 -257.499612)
		(mid 382.245362 -257.549755)
		(end 382.058164 -257.499612)
		(width 0.088646)
		(layer "In4.Cu")
		(net "M_G_CPU0_SA_CS_N<1>")
	)
	(arc
		(start 379.239018 -257.499612)
		(mid 378.964819 -257.423777)
		(end 378.688346 -257.490976)
		(width 0.088646)
		(layer "In4.Cu")
		(net "M_G_CPU0_SA_CS_N<1>")
	)
	(arc
		(start 377.359164 -259.127498)
		(mid 377.082605 -259.051755)
		(end 376.804428 -259.121402)
		(width 0.088646)
		(layer "In4.Cu")
		(net "M_G_CPU0_SA_CS_N<1>")
	)
	(arc
		(start 383.37236 -257.499612)
		(mid 383.185162 -257.549755)
		(end 382.997964 -257.499612)
		(width 0.088646)
		(layer "In4.Cu")
		(net "M_G_CPU0_SA_CS_N<1>")
	)
	(arc
		(start 382.997964 -257.499612)
		(mid 382.715262 -257.423836)
		(end 382.43256 -257.499612)
		(width 0.088646)
		(layer "In4.Cu")
		(net "M_G_CPU0_SA_CS_N<1>")
	)
	(arc
		(start 378.390912 -257.98907)
		(mid 378.343233 -258.17197)
		(end 378.21235 -258.308348)
		(width 0.088646)
		(layer "In4.Cu")
		(net "M_G_CPU0_SA_CS_N<1>")
	)
	(segment
		(start 376.136916 -259.093462)
		(end 376.136662 -259.616956)
		(width 0.20066)
		(layer "F.Cu")
		(net "M_G_CPU0_SA_CS_N<0>")
	)
	(segment
		(start 443.367414 -267.866622)
		(end 444.472314 -267.866622)
		(width 0.20066)
		(layer "F.Cu")
		(net "M_G_CPU0_SA_CS_N<0>")
	)
	(segment
		(start 376.136916 -259.081016)
		(end 376.136916 -259.093462)
		(width 0.20066)
		(layer "F.Cu")
		(net "M_G_CPU0_SA_CS_N<0>")
	)
	(segment
		(start 399.408142 -258.939538)
		(end 395.92504 -258.939538)
		(width 0.18288)
		(layer "In4.Cu")
		(net "M_G_CPU0_SA_CS_N<0>")
	)
	(segment
		(start 378.581412 -257.98907)
		(end 378.581412 -258.011168)
		(width 0.088646)
		(layer "In4.Cu")
		(net "M_G_CPU0_SA_CS_N<0>")
	)
	(segment
		(start 381.973328 -257.670808)
		(end 381.962914 -257.664712)
		(width 0.088646)
		(layer "In4.Cu")
		(net "M_G_CPU0_SA_CS_N<0>")
	)
	(segment
		(start 431.094642 -270.037306)
		(end 428.500286 -267.44295)
		(width 0.18288)
		(layer "In4.Cu")
		(net "M_G_CPU0_SA_CS_N<0>")
	)
	(segment
		(start 381.588518 -257.664712)
		(end 381.578104 -257.670808)
		(width 0.088646)
		(layer "In4.Cu")
		(net "M_G_CPU0_SA_CS_N<0>")
	)
	(segment
		(start 395.92504 -258.939538)
		(end 395.298422 -258.680204)
		(width 0.18288)
		(layer "In4.Cu")
		(net "M_G_CPU0_SA_CS_N<0>")
	)
	(segment
		(start 422.685464 -267.44295)
		(end 421.833294 -266.59078)
		(width 0.18288)
		(layer "In4.Cu")
		(net "M_G_CPU0_SA_CS_N<0>")
	)
	(segment
		(start 435.104794 -269.879826)
		(end 434.947314 -270.037306)
		(width 0.18288)
		(layer "In4.Cu")
		(net "M_G_CPU0_SA_CS_N<0>")
	)
	(segment
		(start 435.661816 -269.142718)
		(end 435.548786 -269.142718)
		(width 0.18288)
		(layer "In4.Cu")
		(net "M_G_CPU0_SA_CS_N<0>")
	)
	(segment
		(start 386.782818 -257.378962)
		(end 385.300728 -257.378962)
		(width 0.088646)
		(layer "In4.Cu")
		(net "M_G_CPU0_SA_CS_N<0>")
	)
	(segment
		(start 395.107668 -258.60121)
		(end 392.6459 -258.60121)
		(width 0.18288)
		(layer "In4.Cu")
		(net "M_G_CPU0_SA_CS_N<0>")
	)
	(segment
		(start 437.637174 -268.288262)
		(end 436.782718 -269.142718)
		(width 0.18288)
		(layer "In4.Cu")
		(net "M_G_CPU0_SA_CS_N<0>")
	)
	(segment
		(start 378.768864 -257.664712)
		(end 378.759974 -257.669792)
		(width 0.088646)
		(layer "In4.Cu")
		(net "M_G_CPU0_SA_CS_N<0>")
	)
	(segment
		(start 443.367414 -267.866622)
		(end 442.945774 -268.288262)
		(width 0.18288)
		(layer "In4.Cu")
		(net "M_G_CPU0_SA_CS_N<0>")
	)
	(segment
		(start 420.537894 -266.59078)
		(end 420.537894 -266.592558)
		(width 0.18288)
		(layer "In4.Cu")
		(net "M_G_CPU0_SA_CS_N<0>")
	)
	(segment
		(start 410.86786 -266.592558)
		(end 409.948634 -265.673332)
		(width 0.18288)
		(layer "In4.Cu")
		(net "M_G_CPU0_SA_CS_N<0>")
	)
	(segment
		(start 434.947314 -270.037306)
		(end 431.094642 -270.037306)
		(width 0.18288)
		(layer "In4.Cu")
		(net "M_G_CPU0_SA_CS_N<0>")
	)
	(segment
		(start 395.298422 -258.680204)
		(end 395.107668 -258.60121)
		(width 0.18288)
		(layer "In4.Cu")
		(net "M_G_CPU0_SA_CS_N<0>")
	)
	(segment
		(start 435.663594 -269.14094)
		(end 435.661816 -269.142718)
		(width 0.18288)
		(layer "In4.Cu")
		(net "M_G_CPU0_SA_CS_N<0>")
	)
	(segment
		(start 376.889264 -259.292598)
		(end 376.874532 -259.301234)
		(width 0.088646)
		(layer "In4.Cu")
		(net "M_G_CPU0_SA_CS_N<0>")
	)
	(segment
		(start 380.093728 -257.670808)
		(end 380.083314 -257.664712)
		(width 0.088646)
		(layer "In4.Cu")
		(net "M_G_CPU0_SA_CS_N<0>")
	)
	(segment
		(start 383.852674 -257.670808)
		(end 383.84226 -257.664712)
		(width 0.088646)
		(layer "In4.Cu")
		(net "M_G_CPU0_SA_CS_N<0>")
	)
	(segment
		(start 405.358854 -264.89025)
		(end 399.408142 -258.939538)
		(width 0.18288)
		(layer "In4.Cu")
		(net "M_G_CPU0_SA_CS_N<0>")
	)
	(segment
		(start 435.104794 -269.58671)
		(end 435.104794 -269.879826)
		(width 0.18288)
		(layer "In4.Cu")
		(net "M_G_CPU0_SA_CS_N<0>")
	)
	(segment
		(start 389.695182 -257.378962)
		(end 386.782818 -257.378962)
		(width 0.18288)
		(layer "In4.Cu")
		(net "M_G_CPU0_SA_CS_N<0>")
	)
	(segment
		(start 435.970426 -269.142718)
		(end 435.968648 -269.14094)
		(width 0.18288)
		(layer "In4.Cu")
		(net "M_G_CPU0_SA_CS_N<0>")
	)
	(segment
		(start 436.782718 -269.142718)
		(end 435.970426 -269.142718)
		(width 0.18288)
		(layer "In4.Cu")
		(net "M_G_CPU0_SA_CS_N<0>")
	)
	(segment
		(start 435.968648 -269.14094)
		(end 435.663594 -269.14094)
		(width 0.18288)
		(layer "In4.Cu")
		(net "M_G_CPU0_SA_CS_N<0>")
	)
	(segment
		(start 408.265122 -265.845544)
		(end 407.58364 -265.845544)
		(width 0.18288)
		(layer "In4.Cu")
		(net "M_G_CPU0_SA_CS_N<0>")
	)
	(segment
		(start 384.7338 -257.613912)
		(end 384.595116 -257.613912)
		(width 0.088646)
		(layer "In4.Cu")
		(net "M_G_CPU0_SA_CS_N<0>")
	)
	(segment
		(start 421.833294 -266.59078)
		(end 420.537894 -266.59078)
		(width 0.18288)
		(layer "In4.Cu")
		(net "M_G_CPU0_SA_CS_N<0>")
	)
	(segment
		(start 376.38228 -259.322062)
		(end 376.293126 -259.345938)
		(width 0.088646)
		(layer "In4.Cu")
		(net "M_G_CPU0_SA_CS_N<0>")
	)
	(segment
		(start 385.300728 -257.378962)
		(end 384.7338 -257.613912)
		(width 0.088646)
		(layer "In4.Cu")
		(net "M_G_CPU0_SA_CS_N<0>")
	)
	(segment
		(start 435.548786 -269.142718)
		(end 435.104794 -269.58671)
		(width 0.18288)
		(layer "In4.Cu")
		(net "M_G_CPU0_SA_CS_N<0>")
	)
	(segment
		(start 379.708918 -257.664712)
		(end 379.698504 -257.670808)
		(width 0.088646)
		(layer "In4.Cu")
		(net "M_G_CPU0_SA_CS_N<0>")
	)
	(segment
		(start 407.58364 -265.845544)
		(end 406.628346 -264.89025)
		(width 0.18288)
		(layer "In4.Cu")
		(net "M_G_CPU0_SA_CS_N<0>")
	)
	(segment
		(start 442.945774 -268.288262)
		(end 437.637174 -268.288262)
		(width 0.18288)
		(layer "In4.Cu")
		(net "M_G_CPU0_SA_CS_N<0>")
	)
	(segment
		(start 409.948634 -265.673332)
		(end 408.437334 -265.673332)
		(width 0.18288)
		(layer "In4.Cu")
		(net "M_G_CPU0_SA_CS_N<0>")
	)
	(segment
		(start 428.500286 -267.44295)
		(end 422.685464 -267.44295)
		(width 0.18288)
		(layer "In4.Cu")
		(net "M_G_CPU0_SA_CS_N<0>")
	)
	(segment
		(start 392.6459 -258.60121)
		(end 389.695182 -257.378962)
		(width 0.18288)
		(layer "In4.Cu")
		(net "M_G_CPU0_SA_CS_N<0>")
	)
	(segment
		(start 408.437334 -265.673332)
		(end 408.265122 -265.845544)
		(width 0.18288)
		(layer "In4.Cu")
		(net "M_G_CPU0_SA_CS_N<0>")
	)
	(segment
		(start 377.841256 -259.285486)
		(end 377.829064 -259.292598)
		(width 0.088646)
		(layer "In4.Cu")
		(net "M_G_CPU0_SA_CS_N<0>")
	)
	(segment
		(start 420.537894 -266.592558)
		(end 410.86786 -266.592558)
		(width 0.18288)
		(layer "In4.Cu")
		(net "M_G_CPU0_SA_CS_N<0>")
	)
	(segment
		(start 406.628346 -264.89025)
		(end 405.358854 -264.89025)
		(width 0.18288)
		(layer "In4.Cu")
		(net "M_G_CPU0_SA_CS_N<0>")
	)
	(segment
		(start 378.299218 -258.478782)
		(end 378.290328 -258.483862)
		(width 0.088646)
		(layer "In4.Cu")
		(net "M_G_CPU0_SA_CS_N<0>")
	)
	(segment
		(start 376.293126 -259.345938)
		(end 376.136662 -259.616956)
		(width 0.088646)
		(layer "In4.Cu")
		(net "M_G_CPU0_SA_CS_N<0>")
	)
	(arc
		(start 379.698504 -257.670808)
		(mid 379.420072 -257.740654)
		(end 379.14326 -257.664712)
		(width 0.088646)
		(layer "In4.Cu")
		(net "M_G_CPU0_SA_CS_N<0>")
	)
	(arc
		(start 379.14326 -257.664712)
		(mid 378.956062 -257.614569)
		(end 378.768864 -257.664712)
		(width 0.088646)
		(layer "In4.Cu")
		(net "M_G_CPU0_SA_CS_N<0>")
	)
	(arc
		(start 381.962914 -257.664712)
		(mid 381.775716 -257.614569)
		(end 381.588518 -257.664712)
		(width 0.088646)
		(layer "In4.Cu")
		(net "M_G_CPU0_SA_CS_N<0>")
	)
	(arc
		(start 377.829064 -259.292598)
		(mid 377.546362 -259.368374)
		(end 377.26366 -259.292598)
		(width 0.088646)
		(layer "In4.Cu")
		(net "M_G_CPU0_SA_CS_N<0>")
	)
	(arc
		(start 380.648464 -257.664712)
		(mid 380.371905 -257.740455)
		(end 380.093728 -257.670808)
		(width 0.088646)
		(layer "In4.Cu")
		(net "M_G_CPU0_SA_CS_N<0>")
	)
	(arc
		(start 378.290328 -258.483862)
		(mid 378.159414 -258.620222)
		(end 378.111766 -258.80314)
		(width 0.088646)
		(layer "In4.Cu")
		(net "M_G_CPU0_SA_CS_N<0>")
	)
	(arc
		(start 377.26366 -259.292598)
		(mid 377.076462 -259.242455)
		(end 376.889264 -259.292598)
		(width 0.088646)
		(layer "In4.Cu")
		(net "M_G_CPU0_SA_CS_N<0>")
	)
	(arc
		(start 376.874532 -259.301234)
		(mid 376.630788 -259.368113)
		(end 376.38228 -259.322062)
		(width 0.088646)
		(layer "In4.Cu")
		(net "M_G_CPU0_SA_CS_N<0>")
	)
	(arc
		(start 383.467864 -257.664712)
		(mid 383.185162 -257.740488)
		(end 382.90246 -257.664712)
		(width 0.088646)
		(layer "In4.Cu")
		(net "M_G_CPU0_SA_CS_N<0>")
	)
	(arc
		(start 378.111766 -258.80314)
		(mid 378.039531 -259.079664)
		(end 377.841256 -259.285486)
		(width 0.088646)
		(layer "In4.Cu")
		(net "M_G_CPU0_SA_CS_N<0>")
	)
	(arc
		(start 380.083314 -257.664712)
		(mid 379.896116 -257.614569)
		(end 379.708918 -257.664712)
		(width 0.088646)
		(layer "In4.Cu")
		(net "M_G_CPU0_SA_CS_N<0>")
	)
	(arc
		(start 384.407918 -257.664712)
		(mid 384.131105 -257.740582)
		(end 383.852674 -257.670808)
		(width 0.088646)
		(layer "In4.Cu")
		(net "M_G_CPU0_SA_CS_N<0>")
	)
	(arc
		(start 381.02286 -257.664712)
		(mid 380.835662 -257.614569)
		(end 380.648464 -257.664712)
		(width 0.088646)
		(layer "In4.Cu")
		(net "M_G_CPU0_SA_CS_N<0>")
	)
	(arc
		(start 378.581412 -258.011168)
		(mid 378.500501 -258.281296)
		(end 378.299218 -258.478782)
		(width 0.088646)
		(layer "In4.Cu")
		(net "M_G_CPU0_SA_CS_N<0>")
	)
	(arc
		(start 383.84226 -257.664712)
		(mid 383.655062 -257.614569)
		(end 383.467864 -257.664712)
		(width 0.088646)
		(layer "In4.Cu")
		(net "M_G_CPU0_SA_CS_N<0>")
	)
	(arc
		(start 381.578104 -257.670808)
		(mid 381.299672 -257.740654)
		(end 381.02286 -257.664712)
		(width 0.088646)
		(layer "In4.Cu")
		(net "M_G_CPU0_SA_CS_N<0>")
	)
	(arc
		(start 378.759974 -257.669792)
		(mid 378.62906 -257.806152)
		(end 378.581412 -257.98907)
		(width 0.088646)
		(layer "In4.Cu")
		(net "M_G_CPU0_SA_CS_N<0>")
	)
	(arc
		(start 384.595116 -257.613912)
		(mid 384.498177 -257.627002)
		(end 384.407918 -257.664712)
		(width 0.088646)
		(layer "In4.Cu")
		(net "M_G_CPU0_SA_CS_N<0>")
	)
	(arc
		(start 382.90246 -257.664712)
		(mid 382.715262 -257.614569)
		(end 382.528064 -257.664712)
		(width 0.088646)
		(layer "In4.Cu")
		(net "M_G_CPU0_SA_CS_N<0>")
	)
	(arc
		(start 382.528064 -257.664712)
		(mid 382.251505 -257.740455)
		(end 381.973328 -257.670808)
		(width 0.088646)
		(layer "In4.Cu")
		(net "M_G_CPU0_SA_CS_N<0>")
	)
	(segment
		(start 443.283086 -270.841724)
		(end 443.462664 -270.841724)
		(width 0.101854)
		(layer "F.Cu")
		(net "M_G_CPU0_SA_CB<7>")
	)
	(segment
		(start 439.898282 -270.416782)
		(end 441.028582 -270.416782)
		(width 0.20066)
		(layer "F.Cu")
		(net "M_G_CPU0_SA_CB<7>")
	)
	(segment
		(start 446.568576 -270.143224)
		(end 446.964562 -270.143224)
		(width 0.20066)
		(layer "F.Cu")
		(net "M_G_CPU0_SA_CB<7>")
	)
	(segment
		(start 442.733938 -270.416782)
		(end 443.15888 -270.841724)
		(width 0.20066)
		(layer "F.Cu")
		(net "M_G_CPU0_SA_CB<7>")
	)
	(segment
		(start 445.774572 -270.841724)
		(end 446.167256 -270.841724)
		(width 0.20066)
		(layer "F.Cu")
		(net "M_G_CPU0_SA_CB<7>")
	)
	(segment
		(start 445.470534 -270.841724)
		(end 445.774572 -270.841724)
		(width 0.101854)
		(layer "F.Cu")
		(net "M_G_CPU0_SA_CB<7>")
	)
	(segment
		(start 376.136662 -261.244588)
		(end 376.136662 -261.244842)
		(width 0.20066)
		(layer "F.Cu")
		(net "M_G_CPU0_SA_CB<7>")
	)
	(segment
		(start 447.23812 -270.416782)
		(end 448.572382 -270.416782)
		(width 0.20066)
		(layer "F.Cu")
		(net "M_G_CPU0_SA_CB<7>")
	)
	(segment
		(start 446.367916 -270.343884)
		(end 446.568576 -270.143224)
		(width 0.20066)
		(layer "F.Cu")
		(net "M_G_CPU0_SA_CB<7>")
	)
	(segment
		(start 376.136916 -261.244334)
		(end 376.136662 -261.244588)
		(width 0.20066)
		(layer "F.Cu")
		(net "M_G_CPU0_SA_CB<7>")
	)
	(segment
		(start 441.028582 -270.416782)
		(end 442.733938 -270.416782)
		(width 0.20066)
		(layer "F.Cu")
		(net "M_G_CPU0_SA_CB<7>")
	)
	(segment
		(start 376.136916 -260.708902)
		(end 376.136916 -261.244334)
		(width 0.20066)
		(layer "F.Cu")
		(net "M_G_CPU0_SA_CB<7>")
	)
	(segment
		(start 446.167256 -270.841724)
		(end 446.367916 -270.641064)
		(width 0.20066)
		(layer "F.Cu")
		(net "M_G_CPU0_SA_CB<7>")
	)
	(segment
		(start 443.462664 -270.841724)
		(end 445.470534 -270.841724)
		(width 0.1016)
		(layer "F.Cu")
		(net "M_G_CPU0_SA_CB<7>")
	)
	(segment
		(start 443.15888 -270.841724)
		(end 443.283086 -270.841724)
		(width 0.20066)
		(layer "F.Cu")
		(net "M_G_CPU0_SA_CB<7>")
	)
	(segment
		(start 446.367916 -270.641064)
		(end 446.367916 -270.343884)
		(width 0.20066)
		(layer "F.Cu")
		(net "M_G_CPU0_SA_CB<7>")
	)
	(segment
		(start 446.964562 -270.143224)
		(end 447.23812 -270.416782)
		(width 0.20066)
		(layer "F.Cu")
		(net "M_G_CPU0_SA_CB<7>")
	)
	(segment
		(start 376.33275 -261.56412)
		(end 376.32386 -261.5692)
		(width 0.088646)
		(layer "In6.Cu")
		(net "M_G_CPU0_SA_CB<7>")
	)
	(segment
		(start 435.325266 -262.504936)
		(end 434.553868 -261.733538)
		(width 0.18288)
		(layer "In6.Cu")
		(net "M_G_CPU0_SA_CB<7>")
	)
	(segment
		(start 386.379212 -260.415278)
		(end 386.379212 -260.430772)
		(width 0.088646)
		(layer "In6.Cu")
		(net "M_G_CPU0_SA_CB<7>")
	)
	(segment
		(start 434.553868 -261.733538)
		(end 432.323494 -261.733538)
		(width 0.18288)
		(layer "In6.Cu")
		(net "M_G_CPU0_SA_CB<7>")
	)
	(segment
		(start 390.984994 -259.510022)
		(end 387.646418 -259.510022)
		(width 0.18288)
		(layer "In6.Cu")
		(net "M_G_CPU0_SA_CB<7>")
	)
	(segment
		(start 439.473848 -269.992348)
		(end 435.508146 -269.992348)
		(width 0.18288)
		(layer "In6.Cu")
		(net "M_G_CPU0_SA_CB<7>")
	)
	(segment
		(start 382.443228 -260.749034)
		(end 382.432814 -260.75513)
		(width 0.088646)
		(layer "In6.Cu")
		(net "M_G_CPU0_SA_CB<7>")
	)
	(segment
		(start 380.563628 -260.749034)
		(end 380.553214 -260.75513)
		(width 0.088646)
		(layer "In6.Cu")
		(net "M_G_CPU0_SA_CB<7>")
	)
	(segment
		(start 420.944294 -259.792216)
		(end 417.771072 -259.792216)
		(width 0.18288)
		(layer "In6.Cu")
		(net "M_G_CPU0_SA_CB<7>")
	)
	(segment
		(start 432.323494 -261.733538)
		(end 431.383694 -260.793738)
		(width 0.18288)
		(layer "In6.Cu")
		(net "M_G_CPU0_SA_CB<7>")
	)
	(segment
		(start 377.748546 -260.746494)
		(end 377.733814 -260.75513)
		(width 0.088646)
		(layer "In6.Cu")
		(net "M_G_CPU0_SA_CB<7>")
	)
	(segment
		(start 435.508146 -269.992348)
		(end 435.325266 -269.809468)
		(width 0.18288)
		(layer "In6.Cu")
		(net "M_G_CPU0_SA_CB<7>")
	)
	(segment
		(start 399.654268 -259.501894)
		(end 399.173446 -259.982716)
		(width 0.18288)
		(layer "In6.Cu")
		(net "M_G_CPU0_SA_CB<7>")
	)
	(segment
		(start 387.646418 -259.510022)
		(end 387.194806 -259.510022)
		(width 0.088646)
		(layer "In6.Cu")
		(net "M_G_CPU0_SA_CB<7>")
	)
	(segment
		(start 417.771072 -259.792216)
		(end 417.48075 -259.501894)
		(width 0.18288)
		(layer "In6.Cu")
		(net "M_G_CPU0_SA_CB<7>")
	)
	(segment
		(start 387.194806 -259.510022)
		(end 386.843016 -259.861812)
		(width 0.088646)
		(layer "In6.Cu")
		(net "M_G_CPU0_SA_CB<7>")
	)
	(segment
		(start 381.503174 -260.749034)
		(end 381.49276 -260.75513)
		(width 0.088646)
		(layer "In6.Cu")
		(net "M_G_CPU0_SA_CB<7>")
	)
	(segment
		(start 439.898282 -270.416782)
		(end 439.473848 -269.992348)
		(width 0.18288)
		(layer "In6.Cu")
		(net "M_G_CPU0_SA_CB<7>")
	)
	(segment
		(start 426.06214 -258.9403)
		(end 421.79621 -258.9403)
		(width 0.18288)
		(layer "In6.Cu")
		(net "M_G_CPU0_SA_CB<7>")
	)
	(segment
		(start 435.325266 -269.809468)
		(end 435.325266 -262.504936)
		(width 0.18288)
		(layer "In6.Cu")
		(net "M_G_CPU0_SA_CB<7>")
	)
	(segment
		(start 393.350242 -259.982716)
		(end 390.995408 -259.51434)
		(width 0.18288)
		(layer "In6.Cu")
		(net "M_G_CPU0_SA_CB<7>")
	)
	(segment
		(start 431.383694 -260.793738)
		(end 427.915578 -260.793738)
		(width 0.18288)
		(layer "In6.Cu")
		(net "M_G_CPU0_SA_CB<7>")
	)
	(segment
		(start 375.766584 -261.302246)
		(end 375.823988 -261.244842)
		(width 0.088646)
		(layer "In6.Cu")
		(net "M_G_CPU0_SA_CB<7>")
	)
	(segment
		(start 378.688346 -260.746494)
		(end 378.673614 -260.75513)
		(width 0.088646)
		(layer "In6.Cu")
		(net "M_G_CPU0_SA_CB<7>")
	)
	(segment
		(start 376.808746 -260.746494)
		(end 376.794014 -260.75513)
		(width 0.088646)
		(layer "In6.Cu")
		(net "M_G_CPU0_SA_CB<7>")
	)
	(segment
		(start 379.628146 -260.746494)
		(end 379.613414 -260.75513)
		(width 0.088646)
		(layer "In6.Cu")
		(net "M_G_CPU0_SA_CB<7>")
	)
	(segment
		(start 421.79621 -258.9403)
		(end 420.944294 -259.792216)
		(width 0.18288)
		(layer "In6.Cu")
		(net "M_G_CPU0_SA_CB<7>")
	)
	(segment
		(start 375.949464 -261.5692)
		(end 375.940574 -261.56412)
		(width 0.088646)
		(layer "In6.Cu")
		(net "M_G_CPU0_SA_CB<7>")
	)
	(segment
		(start 427.915578 -260.793738)
		(end 426.06214 -258.9403)
		(width 0.18288)
		(layer "In6.Cu")
		(net "M_G_CPU0_SA_CB<7>")
	)
	(segment
		(start 417.48075 -259.501894)
		(end 399.654268 -259.501894)
		(width 0.18288)
		(layer "In6.Cu")
		(net "M_G_CPU0_SA_CB<7>")
	)
	(segment
		(start 376.511312 -261.230618)
		(end 376.511312 -261.244842)
		(width 0.088646)
		(layer "In6.Cu")
		(net "M_G_CPU0_SA_CB<7>")
	)
	(segment
		(start 386.20065 -260.75005)
		(end 386.19176 -260.75513)
		(width 0.088646)
		(layer "In6.Cu")
		(net "M_G_CPU0_SA_CB<7>")
	)
	(segment
		(start 399.173446 -259.982716)
		(end 393.350242 -259.982716)
		(width 0.18288)
		(layer "In6.Cu")
		(net "M_G_CPU0_SA_CB<7>")
	)
	(segment
		(start 390.995408 -259.51434)
		(end 390.984994 -259.510022)
		(width 0.18288)
		(layer "In6.Cu")
		(net "M_G_CPU0_SA_CB<7>")
	)
	(segment
		(start 375.823988 -261.244842)
		(end 376.136662 -261.244842)
		(width 0.088646)
		(layer "In6.Cu")
		(net "M_G_CPU0_SA_CB<7>")
	)
	(arc
		(start 384.31216 -260.75513)
		(mid 384.124962 -260.805273)
		(end 383.937764 -260.75513)
		(width 0.088646)
		(layer "In6.Cu")
		(net "M_G_CPU0_SA_CB<7>")
	)
	(arc
		(start 377.733814 -260.75513)
		(mid 377.546616 -260.805273)
		(end 377.359418 -260.75513)
		(width 0.088646)
		(layer "In6.Cu")
		(net "M_G_CPU0_SA_CB<7>")
	)
	(arc
		(start 376.32386 -261.5692)
		(mid 376.136662 -261.619343)
		(end 375.949464 -261.5692)
		(width 0.088646)
		(layer "In6.Cu")
		(net "M_G_CPU0_SA_CB<7>")
	)
	(arc
		(start 376.511312 -261.244842)
		(mid 376.463633 -261.427742)
		(end 376.33275 -261.56412)
		(width 0.088646)
		(layer "In6.Cu")
		(net "M_G_CPU0_SA_CB<7>")
	)
	(arc
		(start 378.673614 -260.75513)
		(mid 378.486416 -260.805273)
		(end 378.299218 -260.75513)
		(width 0.088646)
		(layer "In6.Cu")
		(net "M_G_CPU0_SA_CB<7>")
	)
	(arc
		(start 384.877564 -260.75513)
		(mid 384.594862 -260.679388)
		(end 384.31216 -260.75513)
		(width 0.088646)
		(layer "In6.Cu")
		(net "M_G_CPU0_SA_CB<7>")
	)
	(arc
		(start 382.058418 -260.75513)
		(mid 381.781605 -260.679294)
		(end 381.503174 -260.749034)
		(width 0.088646)
		(layer "In6.Cu")
		(net "M_G_CPU0_SA_CB<7>")
	)
	(arc
		(start 375.940574 -261.56412)
		(mid 375.824835 -261.452296)
		(end 375.766584 -261.302246)
		(width 0.088646)
		(layer "In6.Cu")
		(net "M_G_CPU0_SA_CB<7>")
	)
	(arc
		(start 382.432814 -260.75513)
		(mid 382.245616 -260.805273)
		(end 382.058418 -260.75513)
		(width 0.088646)
		(layer "In6.Cu")
		(net "M_G_CPU0_SA_CB<7>")
	)
	(arc
		(start 386.19176 -260.75513)
		(mid 386.004562 -260.805273)
		(end 385.817364 -260.75513)
		(width 0.088646)
		(layer "In6.Cu")
		(net "M_G_CPU0_SA_CB<7>")
	)
	(arc
		(start 377.359418 -260.75513)
		(mid 377.085189 -260.679205)
		(end 376.808746 -260.746494)
		(width 0.088646)
		(layer "In6.Cu")
		(net "M_G_CPU0_SA_CB<7>")
	)
	(arc
		(start 380.553214 -260.75513)
		(mid 380.366016 -260.805273)
		(end 380.178818 -260.75513)
		(width 0.088646)
		(layer "In6.Cu")
		(net "M_G_CPU0_SA_CB<7>")
	)
	(arc
		(start 381.118364 -260.75513)
		(mid 380.841805 -260.679421)
		(end 380.563628 -260.749034)
		(width 0.088646)
		(layer "In6.Cu")
		(net "M_G_CPU0_SA_CB<7>")
	)
	(arc
		(start 385.25196 -260.75513)
		(mid 385.064762 -260.805273)
		(end 384.877564 -260.75513)
		(width 0.088646)
		(layer "In6.Cu")
		(net "M_G_CPU0_SA_CB<7>")
	)
	(arc
		(start 383.37236 -260.75513)
		(mid 383.185162 -260.805273)
		(end 382.997964 -260.75513)
		(width 0.088646)
		(layer "In6.Cu")
		(net "M_G_CPU0_SA_CB<7>")
	)
	(arc
		(start 381.49276 -260.75513)
		(mid 381.305562 -260.805273)
		(end 381.118364 -260.75513)
		(width 0.088646)
		(layer "In6.Cu")
		(net "M_G_CPU0_SA_CB<7>")
	)
	(arc
		(start 383.937764 -260.75513)
		(mid 383.655062 -260.679388)
		(end 383.37236 -260.75513)
		(width 0.088646)
		(layer "In6.Cu")
		(net "M_G_CPU0_SA_CB<7>")
	)
	(arc
		(start 380.178818 -260.75513)
		(mid 379.904589 -260.679205)
		(end 379.628146 -260.746494)
		(width 0.088646)
		(layer "In6.Cu")
		(net "M_G_CPU0_SA_CB<7>")
	)
	(arc
		(start 386.843016 -259.861812)
		(mid 386.514744 -260.057801)
		(end 386.379212 -260.415278)
		(width 0.088646)
		(layer "In6.Cu")
		(net "M_G_CPU0_SA_CB<7>")
	)
	(arc
		(start 378.299218 -260.75513)
		(mid 378.024989 -260.679205)
		(end 377.748546 -260.746494)
		(width 0.088646)
		(layer "In6.Cu")
		(net "M_G_CPU0_SA_CB<7>")
	)
	(arc
		(start 379.239018 -260.75513)
		(mid 378.964789 -260.679205)
		(end 378.688346 -260.746494)
		(width 0.088646)
		(layer "In6.Cu")
		(net "M_G_CPU0_SA_CB<7>")
	)
	(arc
		(start 386.379212 -260.430772)
		(mid 386.331533 -260.613672)
		(end 386.20065 -260.75005)
		(width 0.088646)
		(layer "In6.Cu")
		(net "M_G_CPU0_SA_CB<7>")
	)
	(arc
		(start 382.997964 -260.75513)
		(mid 382.721405 -260.679421)
		(end 382.443228 -260.749034)
		(width 0.088646)
		(layer "In6.Cu")
		(net "M_G_CPU0_SA_CB<7>")
	)
	(arc
		(start 385.817364 -260.75513)
		(mid 385.534662 -260.679388)
		(end 385.25196 -260.75513)
		(width 0.088646)
		(layer "In6.Cu")
		(net "M_G_CPU0_SA_CB<7>")
	)
	(arc
		(start 376.794014 -260.75513)
		(mid 376.590533 -260.955934)
		(end 376.511312 -261.230618)
		(width 0.088646)
		(layer "In6.Cu")
		(net "M_G_CPU0_SA_CB<7>")
	)
	(arc
		(start 379.613414 -260.75513)
		(mid 379.426216 -260.805273)
		(end 379.239018 -260.75513)
		(width 0.088646)
		(layer "In6.Cu")
		(net "M_G_CPU0_SA_CB<7>")
	)
	(segment
		(start 443.050168 -272.541746)
		(end 443.283086 -272.541746)
		(width 0.20066)
		(layer "F.Cu")
		(net "M_G_CPU0_SA_CB<6>")
	)
	(segment
		(start 445.428878 -272.541746)
		(end 445.774572 -272.541746)
		(width 0.101854)
		(layer "F.Cu")
		(net "M_G_CPU0_SA_CB<6>")
	)
	(segment
		(start 443.462664 -272.541746)
		(end 445.428878 -272.541746)
		(width 0.1016)
		(layer "F.Cu")
		(net "M_G_CPU0_SA_CB<6>")
	)
	(segment
		(start 376.606562 -261.522718)
		(end 376.606816 -261.522972)
		(width 0.20066)
		(layer "F.Cu")
		(net "M_G_CPU0_SA_CB<6>")
	)
	(segment
		(start 441.028582 -272.116804)
		(end 442.625226 -272.116804)
		(width 0.20066)
		(layer "F.Cu")
		(net "M_G_CPU0_SA_CB<6>")
	)
	(segment
		(start 443.283086 -272.541746)
		(end 443.462664 -272.541746)
		(width 0.101854)
		(layer "F.Cu")
		(net "M_G_CPU0_SA_CB<6>")
	)
	(segment
		(start 442.625226 -272.116804)
		(end 443.050168 -272.541746)
		(width 0.20066)
		(layer "F.Cu")
		(net "M_G_CPU0_SA_CB<6>")
	)
	(segment
		(start 446.367916 -272.02257)
		(end 446.568576 -271.82191)
		(width 0.20066)
		(layer "F.Cu")
		(net "M_G_CPU0_SA_CB<6>")
	)
	(segment
		(start 447.23812 -272.116804)
		(end 448.572382 -272.116804)
		(width 0.20066)
		(layer "F.Cu")
		(net "M_G_CPU0_SA_CB<6>")
	)
	(segment
		(start 446.167256 -272.541746)
		(end 446.367916 -272.341086)
		(width 0.20066)
		(layer "F.Cu")
		(net "M_G_CPU0_SA_CB<6>")
	)
	(segment
		(start 446.367916 -272.341086)
		(end 446.367916 -272.02257)
		(width 0.20066)
		(layer "F.Cu")
		(net "M_G_CPU0_SA_CB<6>")
	)
	(segment
		(start 446.943226 -271.82191)
		(end 447.23812 -272.116804)
		(width 0.20066)
		(layer "F.Cu")
		(net "M_G_CPU0_SA_CB<6>")
	)
	(segment
		(start 439.881772 -272.116804)
		(end 441.028582 -272.116804)
		(width 0.20066)
		(layer "F.Cu")
		(net "M_G_CPU0_SA_CB<6>")
	)
	(segment
		(start 376.606816 -261.522972)
		(end 376.606816 -262.058658)
		(width 0.20066)
		(layer "F.Cu")
		(net "M_G_CPU0_SA_CB<6>")
	)
	(segment
		(start 446.568576 -271.82191)
		(end 446.943226 -271.82191)
		(width 0.20066)
		(layer "F.Cu")
		(net "M_G_CPU0_SA_CB<6>")
	)
	(segment
		(start 445.774572 -272.541746)
		(end 446.167256 -272.541746)
		(width 0.20066)
		(layer "F.Cu")
		(net "M_G_CPU0_SA_CB<6>")
	)
	(segment
		(start 429.814228 -262.035544)
		(end 429.631348 -261.852664)
		(width 0.18288)
		(layer "In6.Cu")
		(net "M_G_CPU0_SA_CB<6>")
	)
	(segment
		(start 436.679848 -271.50949)
		(end 436.496968 -271.69237)
		(width 0.18288)
		(layer "In6.Cu")
		(net "M_G_CPU0_SA_CB<6>")
	)
	(segment
		(start 429.997108 -262.495538)
		(end 429.814228 -262.312658)
		(width 0.18288)
		(layer "In6.Cu")
		(net "M_G_CPU0_SA_CB<6>")
	)
	(segment
		(start 437.373268 -271.083024)
		(end 437.190388 -270.900144)
		(width 0.18288)
		(layer "In6.Cu")
		(net "M_G_CPU0_SA_CB<6>")
	)
	(segment
		(start 433.471066 -264.011156)
		(end 432.933602 -263.473692)
		(width 0.18288)
		(layer "In6.Cu")
		(net "M_G_CPU0_SA_CB<6>")
	)
	(segment
		(start 426.352462 -262.292338)
		(end 425.552362 -261.492238)
		(width 0.18288)
		(layer "In6.Cu")
		(net "M_G_CPU0_SA_CB<6>")
	)
	(segment
		(start 436.679848 -271.083024)
		(end 436.679848 -271.50949)
		(width 0.18288)
		(layer "In6.Cu")
		(net "M_G_CPU0_SA_CB<6>")
	)
	(segment
		(start 437.556148 -271.69237)
		(end 437.373268 -271.50949)
		(width 0.18288)
		(layer "In6.Cu")
		(net "M_G_CPU0_SA_CB<6>")
	)
	(segment
		(start 379.708664 -261.5692)
		(end 379.693932 -261.560564)
		(width 0.088646)
		(layer "In6.Cu")
		(net "M_G_CPU0_SA_CB<6>")
	)
	(segment
		(start 416.114738 -261.342632)
		(end 412.677864 -261.342632)
		(width 0.18288)
		(layer "In6.Cu")
		(net "M_G_CPU0_SA_CB<6>")
	)
	(segment
		(start 388.408418 -260.521196)
		(end 387.915912 -260.521196)
		(width 0.088646)
		(layer "In6.Cu")
		(net "M_G_CPU0_SA_CB<6>")
	)
	(segment
		(start 429.120808 -262.312658)
		(end 428.937928 -262.495538)
		(width 0.18288)
		(layer "In6.Cu")
		(net "M_G_CPU0_SA_CB<6>")
	)
	(segment
		(start 408.093418 -261.375906)
		(end 405.485092 -261.375906)
		(width 0.18288)
		(layer "In6.Cu")
		(net "M_G_CPU0_SA_CB<6>")
	)
	(segment
		(start 410.57576 -261.01548)
		(end 410.57576 -261.445502)
		(width 0.18288)
		(layer "In6.Cu")
		(net "M_G_CPU0_SA_CB<6>")
	)
	(segment
		(start 411.15234 -260.78688)
		(end 410.80436 -260.78688)
		(width 0.18288)
		(layer "In6.Cu")
		(net "M_G_CPU0_SA_CB<6>")
	)
	(segment
		(start 421.498014 -261.492238)
		(end 416.264344 -261.492238)
		(width 0.18288)
		(layer "In6.Cu")
		(net "M_G_CPU0_SA_CB<6>")
	)
	(segment
		(start 382.528064 -261.5692)
		(end 382.513332 -261.560564)
		(width 0.088646)
		(layer "In6.Cu")
		(net "M_G_CPU0_SA_CB<6>")
	)
	(segment
		(start 423.420794 -262.419338)
		(end 422.705276 -262.419338)
		(width 0.18288)
		(layer "In6.Cu")
		(net "M_G_CPU0_SA_CB<6>")
	)
	(segment
		(start 386.849112 -261.2263)
		(end 386.849112 -261.244842)
		(width 0.088646)
		(layer "In6.Cu")
		(net "M_G_CPU0_SA_CB<6>")
	)
	(segment
		(start 412.677864 -261.342632)
		(end 412.397956 -261.62254)
		(width 0.18288)
		(layer "In6.Cu")
		(net "M_G_CPU0_SA_CB<6>")
	)
	(segment
		(start 411.333188 -260.967728)
		(end 411.15234 -260.78688)
		(width 0.18288)
		(layer "In6.Cu")
		(net "M_G_CPU0_SA_CB<6>")
	)
	(segment
		(start 381.588264 -261.5692)
		(end 381.573532 -261.560564)
		(width 0.088646)
		(layer "In6.Cu")
		(net "M_G_CPU0_SA_CB<6>")
	)
	(segment
		(start 411.493208 -261.62254)
		(end 411.333188 -261.46252)
		(width 0.18288)
		(layer "In6.Cu")
		(net "M_G_CPU0_SA_CB<6>")
	)
	(segment
		(start 434.212492 -271.69237)
		(end 433.471066 -270.950944)
		(width 0.18288)
		(layer "In6.Cu")
		(net "M_G_CPU0_SA_CB<6>")
	)
	(segment
		(start 432.235102 -263.473692)
		(end 431.256948 -262.495538)
		(width 0.18288)
		(layer "In6.Cu")
		(net "M_G_CPU0_SA_CB<6>")
	)
	(segment
		(start 439.491374 -271.69237)
		(end 437.556148 -271.69237)
		(width 0.18288)
		(layer "In6.Cu")
		(net "M_G_CPU0_SA_CB<6>")
	)
	(segment
		(start 437.190388 -270.900144)
		(end 436.862728 -270.900144)
		(width 0.18288)
		(layer "In6.Cu")
		(net "M_G_CPU0_SA_CB<6>")
	)
	(segment
		(start 439.881772 -272.116804)
		(end 439.881772 -272.082768)
		(width 0.18288)
		(layer "In6.Cu")
		(net "M_G_CPU0_SA_CB<6>")
	)
	(segment
		(start 425.552362 -261.492238)
		(end 424.347894 -261.492238)
		(width 0.18288)
		(layer "In6.Cu")
		(net "M_G_CPU0_SA_CB<6>")
	)
	(segment
		(start 377.829064 -261.5692)
		(end 377.814332 -261.560564)
		(width 0.088646)
		(layer "In6.Cu")
		(net "M_G_CPU0_SA_CB<6>")
	)
	(segment
		(start 429.303688 -261.852664)
		(end 429.120808 -262.035544)
		(width 0.18288)
		(layer "In6.Cu")
		(net "M_G_CPU0_SA_CB<6>")
	)
	(segment
		(start 416.264344 -261.492238)
		(end 416.114738 -261.342632)
		(width 0.18288)
		(layer "In6.Cu")
		(net "M_G_CPU0_SA_CB<6>")
	)
	(segment
		(start 412.397956 -261.62254)
		(end 411.493208 -261.62254)
		(width 0.18288)
		(layer "In6.Cu")
		(net "M_G_CPU0_SA_CB<6>")
	)
	(segment
		(start 411.333188 -261.46252)
		(end 411.333188 -260.967728)
		(width 0.18288)
		(layer "In6.Cu")
		(net "M_G_CPU0_SA_CB<6>")
	)
	(segment
		(start 387.915912 -260.521196)
		(end 387.758178 -260.67893)
		(width 0.088646)
		(layer "In6.Cu")
		(net "M_G_CPU0_SA_CB<6>")
	)
	(segment
		(start 422.705276 -262.419338)
		(end 421.777922 -261.491984)
		(width 0.18288)
		(layer "In6.Cu")
		(net "M_G_CPU0_SA_CB<6>")
	)
	(segment
		(start 429.631348 -261.852664)
		(end 429.303688 -261.852664)
		(width 0.18288)
		(layer "In6.Cu")
		(net "M_G_CPU0_SA_CB<6>")
	)
	(segment
		(start 421.777922 -261.491984)
		(end 421.498014 -261.492238)
		(width 0.18288)
		(layer "In6.Cu")
		(net "M_G_CPU0_SA_CB<6>")
	)
	(segment
		(start 428.937928 -262.495538)
		(end 427.827694 -262.495538)
		(width 0.18288)
		(layer "In6.Cu")
		(net "M_G_CPU0_SA_CB<6>")
	)
	(segment
		(start 437.373268 -271.50949)
		(end 437.373268 -271.083024)
		(width 0.18288)
		(layer "In6.Cu")
		(net "M_G_CPU0_SA_CB<6>")
	)
	(segment
		(start 429.814228 -262.312658)
		(end 429.814228 -262.035544)
		(width 0.18288)
		(layer "In6.Cu")
		(net "M_G_CPU0_SA_CB<6>")
	)
	(segment
		(start 393.249912 -260.978396)
		(end 390.950958 -260.521196)
		(width 0.18288)
		(layer "In6.Cu")
		(net "M_G_CPU0_SA_CB<6>")
	)
	(segment
		(start 436.496968 -271.69237)
		(end 434.212492 -271.69237)
		(width 0.18288)
		(layer "In6.Cu")
		(net "M_G_CPU0_SA_CB<6>")
	)
	(segment
		(start 424.347894 -261.492238)
		(end 423.420794 -262.419338)
		(width 0.18288)
		(layer "In6.Cu")
		(net "M_G_CPU0_SA_CB<6>")
	)
	(segment
		(start 439.881772 -272.082768)
		(end 439.491374 -271.69237)
		(width 0.18288)
		(layer "In6.Cu")
		(net "M_G_CPU0_SA_CB<6>")
	)
	(segment
		(start 433.471066 -270.950944)
		(end 433.471066 -264.011156)
		(width 0.18288)
		(layer "In6.Cu")
		(net "M_G_CPU0_SA_CB<6>")
	)
	(segment
		(start 410.57576 -261.445502)
		(end 410.41574 -261.605522)
		(width 0.18288)
		(layer "In6.Cu")
		(net "M_G_CPU0_SA_CB<6>")
	)
	(segment
		(start 386.67055 -261.56412)
		(end 386.66166 -261.5692)
		(width 0.088646)
		(layer "In6.Cu")
		(net "M_G_CPU0_SA_CB<6>")
	)
	(segment
		(start 427.827694 -262.495538)
		(end 427.624494 -262.292338)
		(width 0.18288)
		(layer "In6.Cu")
		(net "M_G_CPU0_SA_CB<6>")
	)
	(segment
		(start 410.41574 -261.605522)
		(end 408.323034 -261.605522)
		(width 0.18288)
		(layer "In6.Cu")
		(net "M_G_CPU0_SA_CB<6>")
	)
	(segment
		(start 405.485092 -261.375906)
		(end 405.087582 -260.978396)
		(width 0.18288)
		(layer "In6.Cu")
		(net "M_G_CPU0_SA_CB<6>")
	)
	(segment
		(start 405.087582 -260.978396)
		(end 393.249912 -260.978396)
		(width 0.18288)
		(layer "In6.Cu")
		(net "M_G_CPU0_SA_CB<6>")
	)
	(segment
		(start 378.768864 -261.5692)
		(end 378.754132 -261.560564)
		(width 0.088646)
		(layer "In6.Cu")
		(net "M_G_CPU0_SA_CB<6>")
	)
	(segment
		(start 432.933602 -263.473692)
		(end 432.235102 -263.473692)
		(width 0.18288)
		(layer "In6.Cu")
		(net "M_G_CPU0_SA_CB<6>")
	)
	(segment
		(start 408.323034 -261.605522)
		(end 408.093418 -261.375906)
		(width 0.18288)
		(layer "In6.Cu")
		(net "M_G_CPU0_SA_CB<6>")
	)
	(segment
		(start 427.624494 -262.292338)
		(end 426.352462 -262.292338)
		(width 0.18288)
		(layer "In6.Cu")
		(net "M_G_CPU0_SA_CB<6>")
	)
	(segment
		(start 387.758178 -260.67893)
		(end 387.415024 -260.67893)
		(width 0.088646)
		(layer "In6.Cu")
		(net "M_G_CPU0_SA_CB<6>")
	)
	(segment
		(start 436.862728 -270.900144)
		(end 436.679848 -271.083024)
		(width 0.18288)
		(layer "In6.Cu")
		(net "M_G_CPU0_SA_CB<6>")
	)
	(segment
		(start 429.120808 -262.035544)
		(end 429.120808 -262.312658)
		(width 0.18288)
		(layer "In6.Cu")
		(net "M_G_CPU0_SA_CB<6>")
	)
	(segment
		(start 431.256948 -262.495538)
		(end 429.997108 -262.495538)
		(width 0.18288)
		(layer "In6.Cu")
		(net "M_G_CPU0_SA_CB<6>")
	)
	(segment
		(start 410.80436 -260.78688)
		(end 410.57576 -261.01548)
		(width 0.18288)
		(layer "In6.Cu")
		(net "M_G_CPU0_SA_CB<6>")
	)
	(segment
		(start 390.950958 -260.521196)
		(end 388.408418 -260.521196)
		(width 0.18288)
		(layer "In6.Cu")
		(net "M_G_CPU0_SA_CB<6>")
	)
	(arc
		(start 387.13156 -260.75513)
		(mid 386.929274 -260.954111)
		(end 386.849112 -261.2263)
		(width 0.088646)
		(layer "In6.Cu")
		(net "M_G_CPU0_SA_CB<6>")
	)
	(arc
		(start 378.20346 -261.5692)
		(mid 378.016262 -261.619343)
		(end 377.829064 -261.5692)
		(width 0.088646)
		(layer "In6.Cu")
		(net "M_G_CPU0_SA_CB<6>")
	)
	(arc
		(start 381.02286 -261.5692)
		(mid 380.835662 -261.619343)
		(end 380.648464 -261.5692)
		(width 0.088646)
		(layer "In6.Cu")
		(net "M_G_CPU0_SA_CB<6>")
	)
	(arc
		(start 385.347464 -261.5692)
		(mid 385.064762 -261.493424)
		(end 384.78206 -261.5692)
		(width 0.088646)
		(layer "In6.Cu")
		(net "M_G_CPU0_SA_CB<6>")
	)
	(arc
		(start 386.287264 -261.5692)
		(mid 386.004562 -261.493424)
		(end 385.72186 -261.5692)
		(width 0.088646)
		(layer "In6.Cu")
		(net "M_G_CPU0_SA_CB<6>")
	)
	(arc
		(start 386.66166 -261.5692)
		(mid 386.474462 -261.619343)
		(end 386.287264 -261.5692)
		(width 0.088646)
		(layer "In6.Cu")
		(net "M_G_CPU0_SA_CB<6>")
	)
	(arc
		(start 383.467864 -261.5692)
		(mid 383.185162 -261.493424)
		(end 382.90246 -261.5692)
		(width 0.088646)
		(layer "In6.Cu")
		(net "M_G_CPU0_SA_CB<6>")
	)
	(arc
		(start 384.78206 -261.5692)
		(mid 384.594862 -261.619343)
		(end 384.407664 -261.5692)
		(width 0.088646)
		(layer "In6.Cu")
		(net "M_G_CPU0_SA_CB<6>")
	)
	(arc
		(start 380.08306 -261.5692)
		(mid 379.895862 -261.619343)
		(end 379.708664 -261.5692)
		(width 0.088646)
		(layer "In6.Cu")
		(net "M_G_CPU0_SA_CB<6>")
	)
	(arc
		(start 386.849112 -261.244842)
		(mid 386.801433 -261.427742)
		(end 386.67055 -261.56412)
		(width 0.088646)
		(layer "In6.Cu")
		(net "M_G_CPU0_SA_CB<6>")
	)
	(arc
		(start 384.407664 -261.5692)
		(mid 384.124962 -261.493424)
		(end 383.84226 -261.5692)
		(width 0.088646)
		(layer "In6.Cu")
		(net "M_G_CPU0_SA_CB<6>")
	)
	(arc
		(start 380.648464 -261.5692)
		(mid 380.365762 -261.493424)
		(end 380.08306 -261.5692)
		(width 0.088646)
		(layer "In6.Cu")
		(net "M_G_CPU0_SA_CB<6>")
	)
	(arc
		(start 381.573532 -261.560564)
		(mid 381.297057 -261.493244)
		(end 381.02286 -261.5692)
		(width 0.088646)
		(layer "In6.Cu")
		(net "M_G_CPU0_SA_CB<6>")
	)
	(arc
		(start 379.693932 -261.560564)
		(mid 379.417457 -261.493244)
		(end 379.14326 -261.5692)
		(width 0.088646)
		(layer "In6.Cu")
		(net "M_G_CPU0_SA_CB<6>")
	)
	(arc
		(start 381.96266 -261.5692)
		(mid 381.775462 -261.619343)
		(end 381.588264 -261.5692)
		(width 0.088646)
		(layer "In6.Cu")
		(net "M_G_CPU0_SA_CB<6>")
	)
	(arc
		(start 385.72186 -261.5692)
		(mid 385.534662 -261.619343)
		(end 385.347464 -261.5692)
		(width 0.088646)
		(layer "In6.Cu")
		(net "M_G_CPU0_SA_CB<6>")
	)
	(arc
		(start 378.754132 -261.560564)
		(mid 378.477657 -261.493244)
		(end 378.20346 -261.5692)
		(width 0.088646)
		(layer "In6.Cu")
		(net "M_G_CPU0_SA_CB<6>")
	)
	(arc
		(start 377.26366 -261.5692)
		(mid 376.921005 -261.794827)
		(end 376.606816 -262.058658)
		(width 0.088646)
		(layer "In6.Cu")
		(net "M_G_CPU0_SA_CB<6>")
	)
	(arc
		(start 382.90246 -261.5692)
		(mid 382.715262 -261.619343)
		(end 382.528064 -261.5692)
		(width 0.088646)
		(layer "In6.Cu")
		(net "M_G_CPU0_SA_CB<6>")
	)
	(arc
		(start 377.814332 -261.560564)
		(mid 377.537857 -261.493244)
		(end 377.26366 -261.5692)
		(width 0.088646)
		(layer "In6.Cu")
		(net "M_G_CPU0_SA_CB<6>")
	)
	(arc
		(start 379.14326 -261.5692)
		(mid 378.956062 -261.619343)
		(end 378.768864 -261.5692)
		(width 0.088646)
		(layer "In6.Cu")
		(net "M_G_CPU0_SA_CB<6>")
	)
	(arc
		(start 387.415024 -260.67893)
		(mid 387.268259 -260.69831)
		(end 387.13156 -260.75513)
		(width 0.088646)
		(layer "In6.Cu")
		(net "M_G_CPU0_SA_CB<6>")
	)
	(arc
		(start 382.513332 -261.560564)
		(mid 382.236857 -261.493244)
		(end 381.96266 -261.5692)
		(width 0.088646)
		(layer "In6.Cu")
		(net "M_G_CPU0_SA_CB<6>")
	)
	(arc
		(start 383.84226 -261.5692)
		(mid 383.655062 -261.619343)
		(end 383.467864 -261.5692)
		(width 0.088646)
		(layer "In6.Cu")
		(net "M_G_CPU0_SA_CB<6>")
	)
	(segment
		(start 438.449212 -271.266666)
		(end 436.928514 -271.266666)
		(width 0.20066)
		(layer "F.Cu")
		(net "M_G_CPU0_SA_CB<5>")
	)
	(segment
		(start 439.361072 -271.327372)
		(end 439.173112 -271.515332)
		(width 0.20066)
		(layer "F.Cu")
		(net "M_G_CPU0_SA_CB<5>")
	)
	(segment
		(start 444.47206 -271.26692)
		(end 442.84138 -271.26692)
		(width 0.20066)
		(layer "F.Cu")
		(net "M_G_CPU0_SA_CB<5>")
	)
	(segment
		(start 375.197116 -260.708902)
		(end 375.197116 -261.244334)
		(width 0.20066)
		(layer "F.Cu")
		(net "M_G_CPU0_SA_CB<5>")
	)
	(segment
		(start 439.361072 -270.959834)
		(end 439.361072 -271.327372)
		(width 0.20066)
		(layer "F.Cu")
		(net "M_G_CPU0_SA_CB<5>")
	)
	(segment
		(start 444.472314 -271.266666)
		(end 444.47206 -271.26692)
		(width 0.20066)
		(layer "F.Cu")
		(net "M_G_CPU0_SA_CB<5>")
	)
	(segment
		(start 438.697878 -271.515332)
		(end 438.449212 -271.266666)
		(width 0.20066)
		(layer "F.Cu")
		(net "M_G_CPU0_SA_CB<5>")
	)
	(segment
		(start 442.21781 -270.841724)
		(end 442.181234 -270.841724)
		(width 0.101854)
		(layer "F.Cu")
		(net "M_G_CPU0_SA_CB<5>")
	)
	(segment
		(start 439.173112 -271.515332)
		(end 438.697878 -271.515332)
		(width 0.20066)
		(layer "F.Cu")
		(net "M_G_CPU0_SA_CB<5>")
	)
	(segment
		(start 436.928514 -271.266666)
		(end 435.823614 -271.266666)
		(width 0.20066)
		(layer "F.Cu")
		(net "M_G_CPU0_SA_CB<5>")
	)
	(segment
		(start 439.726324 -270.841724)
		(end 439.479182 -270.841724)
		(width 0.20066)
		(layer "F.Cu")
		(net "M_G_CPU0_SA_CB<5>")
	)
	(segment
		(start 442.416184 -270.841724)
		(end 442.21781 -270.841724)
		(width 0.20066)
		(layer "F.Cu")
		(net "M_G_CPU0_SA_CB<5>")
	)
	(segment
		(start 442.84138 -271.26692)
		(end 442.416184 -270.841724)
		(width 0.20066)
		(layer "F.Cu")
		(net "M_G_CPU0_SA_CB<5>")
	)
	(segment
		(start 442.181234 -270.841724)
		(end 439.87085 -270.841724)
		(width 0.1016)
		(layer "F.Cu")
		(net "M_G_CPU0_SA_CB<5>")
	)
	(segment
		(start 439.479182 -270.841724)
		(end 439.361072 -270.959834)
		(width 0.20066)
		(layer "F.Cu")
		(net "M_G_CPU0_SA_CB<5>")
	)
	(segment
		(start 439.87085 -270.841724)
		(end 439.726324 -270.841724)
		(width 0.101854)
		(layer "F.Cu")
		(net "M_G_CPU0_SA_CB<5>")
	)
	(segment
		(start 375.196862 -261.244588)
		(end 375.196862 -261.244842)
		(width 0.20066)
		(layer "F.Cu")
		(net "M_G_CPU0_SA_CB<5>")
	)
	(segment
		(start 375.197116 -261.244334)
		(end 375.196862 -261.244588)
		(width 0.20066)
		(layer "F.Cu")
		(net "M_G_CPU0_SA_CB<5>")
	)
	(segment
		(start 375.854214 -261.7343)
		(end 375.848118 -261.730744)
		(width 0.088646)
		(layer "In6.Cu")
		(net "M_G_CPU0_SA_CB<5>")
	)
	(segment
		(start 387.01853 -260.007862)
		(end 386.980938 -260.045454)
		(width 0.088646)
		(layer "In6.Cu")
		(net "M_G_CPU0_SA_CB<5>")
	)
	(segment
		(start 379.708664 -260.920484)
		(end 379.693932 -260.92912)
		(width 0.088646)
		(layer "In6.Cu")
		(net "M_G_CPU0_SA_CB<5>")
	)
	(segment
		(start 422.12641 -259.701538)
		(end 421.185594 -260.642354)
		(width 0.18288)
		(layer "In6.Cu")
		(net "M_G_CPU0_SA_CB<5>")
	)
	(segment
		(start 434.345588 -270.78432)
		(end 433.980844 -270.419576)
		(width 0.18288)
		(layer "In6.Cu")
		(net "M_G_CPU0_SA_CB<5>")
	)
	(segment
		(start 434.797962 -266.815316)
		(end 434.615082 -266.632436)
		(width 0.18288)
		(layer "In6.Cu")
		(net "M_G_CPU0_SA_CB<5>")
	)
	(segment
		(start 406.510998 -260.599682)
		(end 406.328118 -260.782562)
		(width 0.18288)
		(layer "In6.Cu")
		(net "M_G_CPU0_SA_CB<5>")
	)
	(segment
		(start 399.20291 -260.480556)
		(end 393.29995 -260.480556)
		(width 0.18288)
		(layer "In6.Cu")
		(net "M_G_CPU0_SA_CB<5>")
	)
	(segment
		(start 378.768864 -260.920484)
		(end 378.754132 -260.92912)
		(width 0.088646)
		(layer "In6.Cu")
		(net "M_G_CPU0_SA_CB<5>")
	)
	(segment
		(start 423.217594 -259.701538)
		(end 422.12641 -259.701538)
		(width 0.18288)
		(layer "In6.Cu")
		(net "M_G_CPU0_SA_CB<5>")
	)
	(segment
		(start 390.923272 -260.007862)
		(end 387.646418 -260.007862)
		(width 0.18288)
		(layer "In6.Cu")
		(net "M_G_CPU0_SA_CB<5>")
	)
	(segment
		(start 434.615082 -267.325856)
		(end 434.797962 -267.142976)
		(width 0.18288)
		(layer "In6.Cu")
		(net "M_G_CPU0_SA_CB<5>")
	)
	(segment
		(start 399.203672 -260.479794)
		(end 399.20291 -260.480556)
		(width 0.18288)
		(layer "In6.Cu")
		(net "M_G_CPU0_SA_CB<5>")
	)
	(segment
		(start 407.204418 -260.599682)
		(end 407.204418 -260.186678)
		(width 0.18288)
		(layer "In6.Cu")
		(net "M_G_CPU0_SA_CB<5>")
	)
	(segment
		(start 433.980844 -267.508736)
		(end 434.163724 -267.325856)
		(width 0.18288)
		(layer "In6.Cu")
		(net "M_G_CPU0_SA_CB<5>")
	)
	(segment
		(start 434.640228 -268.303756)
		(end 434.163724 -268.303756)
		(width 0.18288)
		(layer "In6.Cu")
		(net "M_G_CPU0_SA_CB<5>")
	)
	(segment
		(start 434.163724 -267.325856)
		(end 434.615082 -267.325856)
		(width 0.18288)
		(layer "In6.Cu")
		(net "M_G_CPU0_SA_CB<5>")
	)
	(segment
		(start 408.77617 -260.114796)
		(end 408.108404 -260.782562)
		(width 0.18288)
		(layer "In6.Cu")
		(net "M_G_CPU0_SA_CB<5>")
	)
	(segment
		(start 433.980844 -268.120876)
		(end 433.980844 -267.508736)
		(width 0.18288)
		(layer "In6.Cu")
		(net "M_G_CPU0_SA_CB<5>")
	)
	(segment
		(start 425.428664 -260.642354)
		(end 424.15841 -260.642354)
		(width 0.18288)
		(layer "In6.Cu")
		(net "M_G_CPU0_SA_CB<5>")
	)
	(segment
		(start 434.797962 -267.142976)
		(end 434.797962 -266.815316)
		(width 0.18288)
		(layer "In6.Cu")
		(net "M_G_CPU0_SA_CB<5>")
	)
	(segment
		(start 411.934152 -260.114796)
		(end 408.77617 -260.114796)
		(width 0.18288)
		(layer "In6.Cu")
		(net "M_G_CPU0_SA_CB<5>")
	)
	(segment
		(start 434.823108 -268.814296)
		(end 434.823108 -268.486636)
		(width 0.18288)
		(layer "In6.Cu")
		(net "M_G_CPU0_SA_CB<5>")
	)
	(segment
		(start 386.569712 -260.430772)
		(end 386.569712 -260.449314)
		(width 0.088646)
		(layer "In6.Cu")
		(net "M_G_CPU0_SA_CB<5>")
	)
	(segment
		(start 375.575322 -261.310628)
		(end 375.509536 -261.244842)
		(width 0.088646)
		(layer "In6.Cu")
		(net "M_G_CPU0_SA_CB<5>")
	)
	(segment
		(start 434.163724 -266.632436)
		(end 433.980844 -266.449556)
		(width 0.18288)
		(layer "In6.Cu")
		(net "M_G_CPU0_SA_CB<5>")
	)
	(segment
		(start 421.185594 -260.642354)
		(end 412.46171 -260.642354)
		(width 0.18288)
		(layer "In6.Cu")
		(net "M_G_CPU0_SA_CB<5>")
	)
	(segment
		(start 433.534312 -262.241538)
		(end 432.069494 -262.241538)
		(width 0.18288)
		(layer "In6.Cu")
		(net "M_G_CPU0_SA_CB<5>")
	)
	(segment
		(start 433.980844 -262.68807)
		(end 433.534312 -262.241538)
		(width 0.18288)
		(layer "In6.Cu")
		(net "M_G_CPU0_SA_CB<5>")
	)
	(segment
		(start 433.980844 -266.449556)
		(end 433.980844 -262.68807)
		(width 0.18288)
		(layer "In6.Cu")
		(net "M_G_CPU0_SA_CB<5>")
	)
	(segment
		(start 406.328118 -260.782562)
		(end 405.595836 -260.782562)
		(width 0.18288)
		(layer "In6.Cu")
		(net "M_G_CPU0_SA_CB<5>")
	)
	(segment
		(start 406.693878 -260.003798)
		(end 406.510998 -260.186678)
		(width 0.18288)
		(layer "In6.Cu")
		(net "M_G_CPU0_SA_CB<5>")
	)
	(segment
		(start 435.823614 -271.266666)
		(end 435.341268 -270.78432)
		(width 0.18288)
		(layer "In6.Cu")
		(net "M_G_CPU0_SA_CB<5>")
	)
	(segment
		(start 393.29995 -260.480556)
		(end 390.923272 -260.007862)
		(width 0.18288)
		(layer "In6.Cu")
		(net "M_G_CPU0_SA_CB<5>")
	)
	(segment
		(start 434.640228 -268.997176)
		(end 434.823108 -268.814296)
		(width 0.18288)
		(layer "In6.Cu")
		(net "M_G_CPU0_SA_CB<5>")
	)
	(segment
		(start 434.163724 -268.303756)
		(end 433.980844 -268.120876)
		(width 0.18288)
		(layer "In6.Cu")
		(net "M_G_CPU0_SA_CB<5>")
	)
	(segment
		(start 433.980844 -270.419576)
		(end 433.980844 -269.180056)
		(width 0.18288)
		(layer "In6.Cu")
		(net "M_G_CPU0_SA_CB<5>")
	)
	(segment
		(start 405.293068 -260.479794)
		(end 399.203672 -260.479794)
		(width 0.18288)
		(layer "In6.Cu")
		(net "M_G_CPU0_SA_CB<5>")
	)
	(segment
		(start 375.509536 -261.244842)
		(end 375.196862 -261.244842)
		(width 0.088646)
		(layer "In6.Cu")
		(net "M_G_CPU0_SA_CB<5>")
	)
	(segment
		(start 434.615082 -266.632436)
		(end 434.163724 -266.632436)
		(width 0.18288)
		(layer "In6.Cu")
		(net "M_G_CPU0_SA_CB<5>")
	)
	(segment
		(start 375.868946 -261.742936)
		(end 375.854214 -261.7343)
		(width 0.088646)
		(layer "In6.Cu")
		(net "M_G_CPU0_SA_CB<5>")
	)
	(segment
		(start 434.823108 -268.486636)
		(end 434.640228 -268.303756)
		(width 0.18288)
		(layer "In6.Cu")
		(net "M_G_CPU0_SA_CB<5>")
	)
	(segment
		(start 408.108404 -260.782562)
		(end 407.387298 -260.782562)
		(width 0.18288)
		(layer "In6.Cu")
		(net "M_G_CPU0_SA_CB<5>")
	)
	(segment
		(start 431.175414 -261.347458)
		(end 427.731174 -261.347458)
		(width 0.18288)
		(layer "In6.Cu")
		(net "M_G_CPU0_SA_CB<5>")
	)
	(segment
		(start 432.069494 -262.241538)
		(end 431.175414 -261.347458)
		(width 0.18288)
		(layer "In6.Cu")
		(net "M_G_CPU0_SA_CB<5>")
	)
	(segment
		(start 387.646418 -260.007862)
		(end 387.01853 -260.007862)
		(width 0.088646)
		(layer "In6.Cu")
		(net "M_G_CPU0_SA_CB<5>")
	)
	(segment
		(start 406.510998 -260.186678)
		(end 406.510998 -260.599682)
		(width 0.18288)
		(layer "In6.Cu")
		(net "M_G_CPU0_SA_CB<5>")
	)
	(segment
		(start 412.46171 -260.642354)
		(end 411.934152 -260.114796)
		(width 0.18288)
		(layer "In6.Cu")
		(net "M_G_CPU0_SA_CB<5>")
	)
	(segment
		(start 377.829064 -260.920484)
		(end 377.814332 -260.92912)
		(width 0.088646)
		(layer "In6.Cu")
		(net "M_G_CPU0_SA_CB<5>")
	)
	(segment
		(start 376.701812 -261.244842)
		(end 376.701812 -261.260336)
		(width 0.088646)
		(layer "In6.Cu")
		(net "M_G_CPU0_SA_CB<5>")
	)
	(segment
		(start 435.341268 -270.78432)
		(end 434.345588 -270.78432)
		(width 0.18288)
		(layer "In6.Cu")
		(net "M_G_CPU0_SA_CB<5>")
	)
	(segment
		(start 427.345094 -261.733538)
		(end 426.519848 -261.733538)
		(width 0.18288)
		(layer "In6.Cu")
		(net "M_G_CPU0_SA_CB<5>")
	)
	(segment
		(start 434.163724 -268.997176)
		(end 434.640228 -268.997176)
		(width 0.18288)
		(layer "In6.Cu")
		(net "M_G_CPU0_SA_CB<5>")
	)
	(segment
		(start 426.519848 -261.733538)
		(end 425.428664 -260.642354)
		(width 0.18288)
		(layer "In6.Cu")
		(net "M_G_CPU0_SA_CB<5>")
	)
	(segment
		(start 407.387298 -260.782562)
		(end 407.204418 -260.599682)
		(width 0.18288)
		(layer "In6.Cu")
		(net "M_G_CPU0_SA_CB<5>")
	)
	(segment
		(start 424.15841 -260.642354)
		(end 423.217594 -259.701538)
		(width 0.18288)
		(layer "In6.Cu")
		(net "M_G_CPU0_SA_CB<5>")
	)
	(segment
		(start 382.528064 -260.920484)
		(end 382.513332 -260.92912)
		(width 0.088646)
		(layer "In6.Cu")
		(net "M_G_CPU0_SA_CB<5>")
	)
	(segment
		(start 376.889264 -260.920484)
		(end 376.880374 -260.925564)
		(width 0.088646)
		(layer "In6.Cu")
		(net "M_G_CPU0_SA_CB<5>")
	)
	(segment
		(start 407.021538 -260.003798)
		(end 406.693878 -260.003798)
		(width 0.18288)
		(layer "In6.Cu")
		(net "M_G_CPU0_SA_CB<5>")
	)
	(segment
		(start 380.648464 -260.920484)
		(end 380.633732 -260.92912)
		(width 0.088646)
		(layer "In6.Cu")
		(net "M_G_CPU0_SA_CB<5>")
	)
	(segment
		(start 405.595836 -260.782562)
		(end 405.293068 -260.479794)
		(width 0.18288)
		(layer "In6.Cu")
		(net "M_G_CPU0_SA_CB<5>")
	)
	(segment
		(start 427.731174 -261.347458)
		(end 427.345094 -261.733538)
		(width 0.18288)
		(layer "In6.Cu")
		(net "M_G_CPU0_SA_CB<5>")
	)
	(segment
		(start 407.204418 -260.186678)
		(end 407.021538 -260.003798)
		(width 0.18288)
		(layer "In6.Cu")
		(net "M_G_CPU0_SA_CB<5>")
	)
	(segment
		(start 433.980844 -269.180056)
		(end 434.163724 -268.997176)
		(width 0.18288)
		(layer "In6.Cu")
		(net "M_G_CPU0_SA_CB<5>")
	)
	(arc
		(start 379.14326 -260.920484)
		(mid 378.956062 -260.870341)
		(end 378.768864 -260.920484)
		(width 0.088646)
		(layer "In6.Cu")
		(net "M_G_CPU0_SA_CB<5>")
	)
	(arc
		(start 377.814332 -260.92912)
		(mid 377.537891 -260.996286)
		(end 377.26366 -260.920484)
		(width 0.088646)
		(layer "In6.Cu")
		(net "M_G_CPU0_SA_CB<5>")
	)
	(arc
		(start 378.20346 -260.920484)
		(mid 378.016262 -260.870341)
		(end 377.829064 -260.920484)
		(width 0.088646)
		(layer "In6.Cu")
		(net "M_G_CPU0_SA_CB<5>")
	)
	(arc
		(start 383.467864 -260.920484)
		(mid 383.185162 -260.996226)
		(end 382.90246 -260.920484)
		(width 0.088646)
		(layer "In6.Cu")
		(net "M_G_CPU0_SA_CB<5>")
	)
	(arc
		(start 384.78206 -260.920484)
		(mid 384.594862 -260.870341)
		(end 384.407664 -260.920484)
		(width 0.088646)
		(layer "In6.Cu")
		(net "M_G_CPU0_SA_CB<5>")
	)
	(arc
		(start 376.419618 -261.7343)
		(mid 376.145419 -261.810135)
		(end 375.868946 -261.742936)
		(width 0.088646)
		(layer "In6.Cu")
		(net "M_G_CPU0_SA_CB<5>")
	)
	(arc
		(start 386.287264 -260.920484)
		(mid 386.004562 -260.996226)
		(end 385.72186 -260.920484)
		(width 0.088646)
		(layer "In6.Cu")
		(net "M_G_CPU0_SA_CB<5>")
	)
	(arc
		(start 375.848118 -261.730744)
		(mid 375.662663 -261.552549)
		(end 375.575322 -261.310628)
		(width 0.088646)
		(layer "In6.Cu")
		(net "M_G_CPU0_SA_CB<5>")
	)
	(arc
		(start 376.880374 -260.925564)
		(mid 376.74946 -261.061924)
		(end 376.701812 -261.244842)
		(width 0.088646)
		(layer "In6.Cu")
		(net "M_G_CPU0_SA_CB<5>")
	)
	(arc
		(start 382.513332 -260.92912)
		(mid 382.236891 -260.996286)
		(end 381.96266 -260.920484)
		(width 0.088646)
		(layer "In6.Cu")
		(net "M_G_CPU0_SA_CB<5>")
	)
	(arc
		(start 380.633732 -260.92912)
		(mid 380.357291 -260.996286)
		(end 380.08306 -260.920484)
		(width 0.088646)
		(layer "In6.Cu")
		(net "M_G_CPU0_SA_CB<5>")
	)
	(arc
		(start 382.90246 -260.920484)
		(mid 382.715262 -260.870341)
		(end 382.528064 -260.920484)
		(width 0.088646)
		(layer "In6.Cu")
		(net "M_G_CPU0_SA_CB<5>")
	)
	(arc
		(start 383.84226 -260.920484)
		(mid 383.655062 -260.870341)
		(end 383.467864 -260.920484)
		(width 0.088646)
		(layer "In6.Cu")
		(net "M_G_CPU0_SA_CB<5>")
	)
	(arc
		(start 386.569712 -260.449314)
		(mid 386.48955 -260.721503)
		(end 386.287264 -260.920484)
		(width 0.088646)
		(layer "In6.Cu")
		(net "M_G_CPU0_SA_CB<5>")
	)
	(arc
		(start 384.407664 -260.920484)
		(mid 384.124962 -260.996226)
		(end 383.84226 -260.920484)
		(width 0.088646)
		(layer "In6.Cu")
		(net "M_G_CPU0_SA_CB<5>")
	)
	(arc
		(start 381.02286 -260.920484)
		(mid 380.835662 -260.870341)
		(end 380.648464 -260.920484)
		(width 0.088646)
		(layer "In6.Cu")
		(net "M_G_CPU0_SA_CB<5>")
	)
	(arc
		(start 381.588264 -260.920484)
		(mid 381.305562 -260.996226)
		(end 381.02286 -260.920484)
		(width 0.088646)
		(layer "In6.Cu")
		(net "M_G_CPU0_SA_CB<5>")
	)
	(arc
		(start 378.754132 -260.92912)
		(mid 378.477691 -260.996286)
		(end 378.20346 -260.920484)
		(width 0.088646)
		(layer "In6.Cu")
		(net "M_G_CPU0_SA_CB<5>")
	)
	(arc
		(start 385.347464 -260.920484)
		(mid 385.064762 -260.996226)
		(end 384.78206 -260.920484)
		(width 0.088646)
		(layer "In6.Cu")
		(net "M_G_CPU0_SA_CB<5>")
	)
	(arc
		(start 386.748274 -260.111494)
		(mid 386.61736 -260.247854)
		(end 386.569712 -260.430772)
		(width 0.088646)
		(layer "In6.Cu")
		(net "M_G_CPU0_SA_CB<5>")
	)
	(arc
		(start 379.693932 -260.92912)
		(mid 379.417491 -260.996286)
		(end 379.14326 -260.920484)
		(width 0.088646)
		(layer "In6.Cu")
		(net "M_G_CPU0_SA_CB<5>")
	)
	(arc
		(start 381.96266 -260.920484)
		(mid 381.775462 -260.870341)
		(end 381.588264 -260.920484)
		(width 0.088646)
		(layer "In6.Cu")
		(net "M_G_CPU0_SA_CB<5>")
	)
	(arc
		(start 376.701812 -261.260336)
		(mid 376.622442 -261.53407)
		(end 376.419618 -261.7343)
		(width 0.088646)
		(layer "In6.Cu")
		(net "M_G_CPU0_SA_CB<5>")
	)
	(arc
		(start 385.72186 -260.920484)
		(mid 385.534662 -260.870341)
		(end 385.347464 -260.920484)
		(width 0.088646)
		(layer "In6.Cu")
		(net "M_G_CPU0_SA_CB<5>")
	)
	(arc
		(start 380.08306 -260.920484)
		(mid 379.895862 -260.870341)
		(end 379.708664 -260.920484)
		(width 0.088646)
		(layer "In6.Cu")
		(net "M_G_CPU0_SA_CB<5>")
	)
	(arc
		(start 386.980938 -260.045454)
		(mid 386.860008 -260.06228)
		(end 386.748274 -260.111494)
		(width 0.088646)
		(layer "In6.Cu")
		(net "M_G_CPU0_SA_CB<5>")
	)
	(arc
		(start 377.26366 -260.920484)
		(mid 377.076462 -260.870341)
		(end 376.889264 -260.920484)
		(width 0.088646)
		(layer "In6.Cu")
		(net "M_G_CPU0_SA_CB<5>")
	)
	(segment
		(start 438.449212 -272.966688)
		(end 436.928514 -272.966688)
		(width 0.20066)
		(layer "F.Cu")
		(net "M_G_CPU0_SA_CB<4>")
	)
	(segment
		(start 442.21781 -272.541746)
		(end 442.181234 -272.541746)
		(width 0.101854)
		(layer "F.Cu")
		(net "M_G_CPU0_SA_CB<4>")
	)
	(segment
		(start 439.361072 -272.659856)
		(end 439.361072 -273.027394)
		(width 0.20066)
		(layer "F.Cu")
		(net "M_G_CPU0_SA_CB<4>")
	)
	(segment
		(start 442.84138 -272.966942)
		(end 442.416184 -272.541746)
		(width 0.20066)
		(layer "F.Cu")
		(net "M_G_CPU0_SA_CB<4>")
	)
	(segment
		(start 374.727216 -261.522972)
		(end 374.727216 -262.058658)
		(width 0.20066)
		(layer "F.Cu")
		(net "M_G_CPU0_SA_CB<4>")
	)
	(segment
		(start 442.181234 -272.541746)
		(end 439.87085 -272.541746)
		(width 0.1016)
		(layer "F.Cu")
		(net "M_G_CPU0_SA_CB<4>")
	)
	(segment
		(start 374.726962 -261.522718)
		(end 374.727216 -261.522972)
		(width 0.20066)
		(layer "F.Cu")
		(net "M_G_CPU0_SA_CB<4>")
	)
	(segment
		(start 439.726324 -272.541746)
		(end 439.479182 -272.541746)
		(width 0.20066)
		(layer "F.Cu")
		(net "M_G_CPU0_SA_CB<4>")
	)
	(segment
		(start 439.361072 -273.027394)
		(end 439.173112 -273.215354)
		(width 0.20066)
		(layer "F.Cu")
		(net "M_G_CPU0_SA_CB<4>")
	)
	(segment
		(start 442.416184 -272.541746)
		(end 442.21781 -272.541746)
		(width 0.20066)
		(layer "F.Cu")
		(net "M_G_CPU0_SA_CB<4>")
	)
	(segment
		(start 439.173112 -273.215354)
		(end 438.697878 -273.215354)
		(width 0.20066)
		(layer "F.Cu")
		(net "M_G_CPU0_SA_CB<4>")
	)
	(segment
		(start 444.472314 -272.966688)
		(end 444.47206 -272.966942)
		(width 0.20066)
		(layer "F.Cu")
		(net "M_G_CPU0_SA_CB<4>")
	)
	(segment
		(start 439.479182 -272.541746)
		(end 439.361072 -272.659856)
		(width 0.20066)
		(layer "F.Cu")
		(net "M_G_CPU0_SA_CB<4>")
	)
	(segment
		(start 438.697878 -273.215354)
		(end 438.449212 -272.966688)
		(width 0.20066)
		(layer "F.Cu")
		(net "M_G_CPU0_SA_CB<4>")
	)
	(segment
		(start 444.47206 -272.966942)
		(end 442.84138 -272.966942)
		(width 0.20066)
		(layer "F.Cu")
		(net "M_G_CPU0_SA_CB<4>")
	)
	(segment
		(start 439.87085 -272.541746)
		(end 439.726324 -272.541746)
		(width 0.101854)
		(layer "F.Cu")
		(net "M_G_CPU0_SA_CB<4>")
	)
	(segment
		(start 436.928514 -272.966688)
		(end 435.823614 -272.966688)
		(width 0.20066)
		(layer "F.Cu")
		(net "M_G_CPU0_SA_CB<4>")
	)
	(segment
		(start 413.925004 -262.178038)
		(end 413.742124 -262.360918)
		(width 0.18288)
		(layer "In6.Cu")
		(net "M_G_CPU0_SA_CB<4>")
	)
	(segment
		(start 432.960018 -264.308336)
		(end 432.68265 -264.030968)
		(width 0.18288)
		(layer "In6.Cu")
		(net "M_G_CPU0_SA_CB<4>")
	)
	(segment
		(start 387.757162 -260.869176)
		(end 387.415024 -260.869176)
		(width 0.088646)
		(layer "In6.Cu")
		(net "M_G_CPU0_SA_CB<4>")
	)
	(segment
		(start 390.92886 -261.024624)
		(end 388.408672 -261.024624)
		(width 0.18288)
		(layer "In6.Cu")
		(net "M_G_CPU0_SA_CB<4>")
	)
	(segment
		(start 379.623828 -261.740396)
		(end 379.613414 -261.7343)
		(width 0.088646)
		(layer "In6.Cu")
		(net "M_G_CPU0_SA_CB<4>")
	)
	(segment
		(start 426.519848 -263.422892)
		(end 425.439332 -262.342376)
		(width 0.18288)
		(layer "In6.Cu")
		(net "M_G_CPU0_SA_CB<4>")
	)
	(segment
		(start 411.24378 -262.305292)
		(end 411.24378 -262.69569)
		(width 0.18288)
		(layer "In6.Cu")
		(net "M_G_CPU0_SA_CB<4>")
	)
	(segment
		(start 427.56074 -263.422892)
		(end 426.519848 -263.422892)
		(width 0.18288)
		(layer "In6.Cu")
		(net "M_G_CPU0_SA_CB<4>")
	)
	(segment
		(start 381.507746 -261.742936)
		(end 381.493014 -261.7343)
		(width 0.088646)
		(layer "In6.Cu")
		(net "M_G_CPU0_SA_CB<4>")
	)
	(segment
		(start 377.218448 -261.877556)
		(end 377.124468 -262.047482)
		(width 0.088646)
		(layer "In6.Cu")
		(net "M_G_CPU0_SA_CB<4>")
	)
	(segment
		(start 375.451116 -262.366252)
		(end 374.727216 -262.058658)
		(width 0.088646)
		(layer "In6.Cu")
		(net "M_G_CPU0_SA_CB<4>")
	)
	(segment
		(start 375.479818 -262.383016)
		(end 375.451116 -262.366252)
		(width 0.088646)
		(layer "In6.Cu")
		(net "M_G_CPU0_SA_CB<4>")
	)
	(segment
		(start 375.868946 -262.37438)
		(end 375.854214 -262.383016)
		(width 0.088646)
		(layer "In6.Cu")
		(net "M_G_CPU0_SA_CB<4>")
	)
	(segment
		(start 414.435544 -261.841996)
		(end 414.107884 -261.841996)
		(width 0.18288)
		(layer "In6.Cu")
		(net "M_G_CPU0_SA_CB<4>")
	)
	(segment
		(start 410.471874 -262.69569)
		(end 410.471874 -262.27913)
		(width 0.18288)
		(layer "In6.Cu")
		(net "M_G_CPU0_SA_CB<4>")
	)
	(segment
		(start 429.71593 -263.718294)
		(end 429.53305 -263.901174)
		(width 0.18288)
		(layer "In6.Cu")
		(net "M_G_CPU0_SA_CB<4>")
	)
	(segment
		(start 425.439332 -262.342376)
		(end 424.361356 -262.342376)
		(width 0.18288)
		(layer "In6.Cu")
		(net "M_G_CPU0_SA_CB<4>")
	)
	(segment
		(start 412.424118 -262.145272)
		(end 411.4038 -262.145272)
		(width 0.18288)
		(layer "In6.Cu")
		(net "M_G_CPU0_SA_CB<4>")
	)
	(segment
		(start 378.688346 -261.742936)
		(end 378.673614 -261.7343)
		(width 0.088646)
		(layer "In6.Cu")
		(net "M_G_CPU0_SA_CB<4>")
	)
	(segment
		(start 405.412448 -262.374888)
		(end 404.519384 -261.481824)
		(width 0.18288)
		(layer "In6.Cu")
		(net "M_G_CPU0_SA_CB<4>")
	)
	(segment
		(start 410.631894 -262.85571)
		(end 410.471874 -262.69569)
		(width 0.18288)
		(layer "In6.Cu")
		(net "M_G_CPU0_SA_CB<4>")
	)
	(segment
		(start 377.124468 -262.047482)
		(end 376.94362 -262.2931)
		(width 0.088646)
		(layer "In6.Cu")
		(net "M_G_CPU0_SA_CB<4>")
	)
	(segment
		(start 410.471874 -262.27913)
		(end 410.311854 -262.11911)
		(width 0.18288)
		(layer "In6.Cu")
		(net "M_G_CPU0_SA_CB<4>")
	)
	(segment
		(start 429.20539 -263.901174)
		(end 429.02251 -263.718294)
		(width 0.18288)
		(layer "In6.Cu")
		(net "M_G_CPU0_SA_CB<4>")
	)
	(segment
		(start 414.801304 -262.360918)
		(end 414.618424 -262.178038)
		(width 0.18288)
		(layer "In6.Cu")
		(net "M_G_CPU0_SA_CB<4>")
	)
	(segment
		(start 387.039612 -261.244842)
		(end 387.039612 -261.254748)
		(width 0.088646)
		(layer "In6.Cu")
		(net "M_G_CPU0_SA_CB<4>")
	)
	(segment
		(start 377.748546 -261.742936)
		(end 377.733814 -261.7343)
		(width 0.088646)
		(layer "In6.Cu")
		(net "M_G_CPU0_SA_CB<4>")
	)
	(segment
		(start 393.22756 -261.481824)
		(end 390.92886 -261.024624)
		(width 0.18288)
		(layer "In6.Cu")
		(net "M_G_CPU0_SA_CB<4>")
	)
	(segment
		(start 430.972214 -263.023604)
		(end 429.89881 -263.023604)
		(width 0.18288)
		(layer "In6.Cu")
		(net "M_G_CPU0_SA_CB<4>")
	)
	(segment
		(start 414.107884 -261.841996)
		(end 413.925004 -262.024876)
		(width 0.18288)
		(layer "In6.Cu")
		(net "M_G_CPU0_SA_CB<4>")
	)
	(segment
		(start 415.859976 -262.360918)
		(end 414.801304 -262.360918)
		(width 0.18288)
		(layer "In6.Cu")
		(net "M_G_CPU0_SA_CB<4>")
	)
	(segment
		(start 423.700194 -263.003538)
		(end 422.354248 -263.003538)
		(width 0.18288)
		(layer "In6.Cu")
		(net "M_G_CPU0_SA_CB<4>")
	)
	(segment
		(start 429.71593 -263.206484)
		(end 429.71593 -263.718294)
		(width 0.18288)
		(layer "In6.Cu")
		(net "M_G_CPU0_SA_CB<4>")
	)
	(segment
		(start 429.53305 -263.901174)
		(end 429.20539 -263.901174)
		(width 0.18288)
		(layer "In6.Cu")
		(net "M_G_CPU0_SA_CB<4>")
	)
	(segment
		(start 376.94362 -262.2931)
		(end 376.794014 -262.383016)
		(width 0.088646)
		(layer "In6.Cu")
		(net "M_G_CPU0_SA_CB<4>")
	)
	(segment
		(start 419.62705 -261.995412)
		(end 416.225482 -261.995412)
		(width 0.18288)
		(layer "In6.Cu")
		(net "M_G_CPU0_SA_CB<4>")
	)
	(segment
		(start 382.443228 -261.740396)
		(end 382.432814 -261.7343)
		(width 0.088646)
		(layer "In6.Cu")
		(net "M_G_CPU0_SA_CB<4>")
	)
	(segment
		(start 435.823614 -272.966688)
		(end 435.200552 -272.343626)
		(width 0.18288)
		(layer "In6.Cu")
		(net "M_G_CPU0_SA_CB<4>")
	)
	(segment
		(start 422.354248 -263.003538)
		(end 421.693086 -262.342376)
		(width 0.18288)
		(layer "In6.Cu")
		(net "M_G_CPU0_SA_CB<4>")
	)
	(segment
		(start 427.960028 -263.023604)
		(end 427.56074 -263.422892)
		(width 0.18288)
		(layer "In6.Cu")
		(net "M_G_CPU0_SA_CB<4>")
	)
	(segment
		(start 408.827224 -262.374888)
		(end 405.412448 -262.374888)
		(width 0.18288)
		(layer "In6.Cu")
		(net "M_G_CPU0_SA_CB<4>")
	)
	(segment
		(start 413.742124 -262.360918)
		(end 412.639764 -262.360918)
		(width 0.18288)
		(layer "In6.Cu")
		(net "M_G_CPU0_SA_CB<4>")
	)
	(segment
		(start 416.225482 -261.995412)
		(end 415.859976 -262.360918)
		(width 0.18288)
		(layer "In6.Cu")
		(net "M_G_CPU0_SA_CB<4>")
	)
	(segment
		(start 413.925004 -262.024876)
		(end 413.925004 -262.178038)
		(width 0.18288)
		(layer "In6.Cu")
		(net "M_G_CPU0_SA_CB<4>")
	)
	(segment
		(start 421.693086 -262.342376)
		(end 419.974014 -262.342376)
		(width 0.18288)
		(layer "In6.Cu")
		(net "M_G_CPU0_SA_CB<4>")
	)
	(segment
		(start 411.4038 -262.145272)
		(end 411.24378 -262.305292)
		(width 0.18288)
		(layer "In6.Cu")
		(net "M_G_CPU0_SA_CB<4>")
	)
	(segment
		(start 428.83963 -263.023604)
		(end 427.960028 -263.023604)
		(width 0.18288)
		(layer "In6.Cu")
		(net "M_G_CPU0_SA_CB<4>")
	)
	(segment
		(start 434.12664 -272.343626)
		(end 432.960018 -271.177004)
		(width 0.18288)
		(layer "In6.Cu")
		(net "M_G_CPU0_SA_CB<4>")
	)
	(segment
		(start 432.960018 -271.177004)
		(end 432.960018 -264.308336)
		(width 0.18288)
		(layer "In6.Cu")
		(net "M_G_CPU0_SA_CB<4>")
	)
	(segment
		(start 388.408672 -261.024624)
		(end 387.91261 -261.024624)
		(width 0.088646)
		(layer "In6.Cu")
		(net "M_G_CPU0_SA_CB<4>")
	)
	(segment
		(start 404.519384 -261.481824)
		(end 393.22756 -261.481824)
		(width 0.18288)
		(layer "In6.Cu")
		(net "M_G_CPU0_SA_CB<4>")
	)
	(segment
		(start 380.563374 -261.740396)
		(end 380.55296 -261.7343)
		(width 0.088646)
		(layer "In6.Cu")
		(net "M_G_CPU0_SA_CB<4>")
	)
	(segment
		(start 387.91261 -261.024624)
		(end 387.757162 -260.869176)
		(width 0.088646)
		(layer "In6.Cu")
		(net "M_G_CPU0_SA_CB<4>")
	)
	(segment
		(start 412.639764 -262.360918)
		(end 412.424118 -262.145272)
		(width 0.18288)
		(layer "In6.Cu")
		(net "M_G_CPU0_SA_CB<4>")
	)
	(segment
		(start 429.02251 -263.206484)
		(end 428.83963 -263.023604)
		(width 0.18288)
		(layer "In6.Cu")
		(net "M_G_CPU0_SA_CB<4>")
	)
	(segment
		(start 429.89881 -263.023604)
		(end 429.71593 -263.206484)
		(width 0.18288)
		(layer "In6.Cu")
		(net "M_G_CPU0_SA_CB<4>")
	)
	(segment
		(start 424.361356 -262.342376)
		(end 423.700194 -263.003538)
		(width 0.18288)
		(layer "In6.Cu")
		(net "M_G_CPU0_SA_CB<4>")
	)
	(segment
		(start 411.08376 -262.85571)
		(end 410.631894 -262.85571)
		(width 0.18288)
		(layer "In6.Cu")
		(net "M_G_CPU0_SA_CB<4>")
	)
	(segment
		(start 387.227064 -260.920484)
		(end 387.218174 -260.925564)
		(width 0.088646)
		(layer "In6.Cu")
		(net "M_G_CPU0_SA_CB<4>")
	)
	(segment
		(start 411.24378 -262.69569)
		(end 411.08376 -262.85571)
		(width 0.18288)
		(layer "In6.Cu")
		(net "M_G_CPU0_SA_CB<4>")
	)
	(segment
		(start 414.618424 -262.178038)
		(end 414.618424 -262.024876)
		(width 0.18288)
		(layer "In6.Cu")
		(net "M_G_CPU0_SA_CB<4>")
	)
	(segment
		(start 419.974014 -262.342376)
		(end 419.62705 -261.995412)
		(width 0.18288)
		(layer "In6.Cu")
		(net "M_G_CPU0_SA_CB<4>")
	)
	(segment
		(start 432.68265 -264.030968)
		(end 431.979578 -264.030968)
		(width 0.18288)
		(layer "In6.Cu")
		(net "M_G_CPU0_SA_CB<4>")
	)
	(segment
		(start 429.02251 -263.718294)
		(end 429.02251 -263.206484)
		(width 0.18288)
		(layer "In6.Cu")
		(net "M_G_CPU0_SA_CB<4>")
	)
	(segment
		(start 414.618424 -262.024876)
		(end 414.435544 -261.841996)
		(width 0.18288)
		(layer "In6.Cu")
		(net "M_G_CPU0_SA_CB<4>")
	)
	(segment
		(start 435.200552 -272.343626)
		(end 434.12664 -272.343626)
		(width 0.18288)
		(layer "In6.Cu")
		(net "M_G_CPU0_SA_CB<4>")
	)
	(segment
		(start 410.311854 -262.11911)
		(end 409.083002 -262.11911)
		(width 0.18288)
		(layer "In6.Cu")
		(net "M_G_CPU0_SA_CB<4>")
	)
	(segment
		(start 431.979578 -264.030968)
		(end 430.972214 -263.023604)
		(width 0.18288)
		(layer "In6.Cu")
		(net "M_G_CPU0_SA_CB<4>")
	)
	(segment
		(start 409.083002 -262.11911)
		(end 408.827224 -262.374888)
		(width 0.18288)
		(layer "In6.Cu")
		(net "M_G_CPU0_SA_CB<4>")
	)
	(arc
		(start 377.359418 -261.7343)
		(mid 377.279174 -261.796332)
		(end 377.218448 -261.877556)
		(width 0.088646)
		(layer "In6.Cu")
		(net "M_G_CPU0_SA_CB<4>")
	)
	(arc
		(start 386.757164 -261.7343)
		(mid 386.474462 -261.810076)
		(end 386.19176 -261.7343)
		(width 0.088646)
		(layer "In6.Cu")
		(net "M_G_CPU0_SA_CB<4>")
	)
	(arc
		(start 382.432814 -261.7343)
		(mid 382.245616 -261.684157)
		(end 382.058418 -261.7343)
		(width 0.088646)
		(layer "In6.Cu")
		(net "M_G_CPU0_SA_CB<4>")
	)
	(arc
		(start 383.37236 -261.7343)
		(mid 383.185162 -261.684157)
		(end 382.997964 -261.7343)
		(width 0.088646)
		(layer "In6.Cu")
		(net "M_G_CPU0_SA_CB<4>")
	)
	(arc
		(start 378.299218 -261.7343)
		(mid 378.025019 -261.810135)
		(end 377.748546 -261.742936)
		(width 0.088646)
		(layer "In6.Cu")
		(net "M_G_CPU0_SA_CB<4>")
	)
	(arc
		(start 384.31216 -261.7343)
		(mid 384.124962 -261.684157)
		(end 383.937764 -261.7343)
		(width 0.088646)
		(layer "In6.Cu")
		(net "M_G_CPU0_SA_CB<4>")
	)
	(arc
		(start 379.239018 -261.7343)
		(mid 378.964819 -261.810135)
		(end 378.688346 -261.742936)
		(width 0.088646)
		(layer "In6.Cu")
		(net "M_G_CPU0_SA_CB<4>")
	)
	(arc
		(start 387.218174 -260.925564)
		(mid 387.08726 -261.061924)
		(end 387.039612 -261.244842)
		(width 0.088646)
		(layer "In6.Cu")
		(net "M_G_CPU0_SA_CB<4>")
	)
	(arc
		(start 384.877564 -261.7343)
		(mid 384.594862 -261.810076)
		(end 384.31216 -261.7343)
		(width 0.088646)
		(layer "In6.Cu")
		(net "M_G_CPU0_SA_CB<4>")
	)
	(arc
		(start 382.058418 -261.7343)
		(mid 381.784219 -261.810135)
		(end 381.507746 -261.742936)
		(width 0.088646)
		(layer "In6.Cu")
		(net "M_G_CPU0_SA_CB<4>")
	)
	(arc
		(start 379.613414 -261.7343)
		(mid 379.426216 -261.684157)
		(end 379.239018 -261.7343)
		(width 0.088646)
		(layer "In6.Cu")
		(net "M_G_CPU0_SA_CB<4>")
	)
	(arc
		(start 376.794014 -262.383016)
		(mid 376.606816 -262.433159)
		(end 376.419618 -262.383016)
		(width 0.088646)
		(layer "In6.Cu")
		(net "M_G_CPU0_SA_CB<4>")
	)
	(arc
		(start 386.19176 -261.7343)
		(mid 386.004562 -261.684157)
		(end 385.817364 -261.7343)
		(width 0.088646)
		(layer "In6.Cu")
		(net "M_G_CPU0_SA_CB<4>")
	)
	(arc
		(start 377.733814 -261.7343)
		(mid 377.546616 -261.684157)
		(end 377.359418 -261.7343)
		(width 0.088646)
		(layer "In6.Cu")
		(net "M_G_CPU0_SA_CB<4>")
	)
	(arc
		(start 381.118618 -261.7343)
		(mid 380.841805 -261.81017)
		(end 380.563374 -261.740396)
		(width 0.088646)
		(layer "In6.Cu")
		(net "M_G_CPU0_SA_CB<4>")
	)
	(arc
		(start 385.817364 -261.7343)
		(mid 385.534662 -261.810076)
		(end 385.25196 -261.7343)
		(width 0.088646)
		(layer "In6.Cu")
		(net "M_G_CPU0_SA_CB<4>")
	)
	(arc
		(start 378.673614 -261.7343)
		(mid 378.486416 -261.684157)
		(end 378.299218 -261.7343)
		(width 0.088646)
		(layer "In6.Cu")
		(net "M_G_CPU0_SA_CB<4>")
	)
	(arc
		(start 380.178564 -261.7343)
		(mid 379.902005 -261.810043)
		(end 379.623828 -261.740396)
		(width 0.088646)
		(layer "In6.Cu")
		(net "M_G_CPU0_SA_CB<4>")
	)
	(arc
		(start 387.039612 -261.254748)
		(mid 386.961501 -261.531697)
		(end 386.757164 -261.7343)
		(width 0.088646)
		(layer "In6.Cu")
		(net "M_G_CPU0_SA_CB<4>")
	)
	(arc
		(start 380.55296 -261.7343)
		(mid 380.365762 -261.684157)
		(end 380.178564 -261.7343)
		(width 0.088646)
		(layer "In6.Cu")
		(net "M_G_CPU0_SA_CB<4>")
	)
	(arc
		(start 376.419618 -262.383016)
		(mid 376.145419 -262.307181)
		(end 375.868946 -262.37438)
		(width 0.088646)
		(layer "In6.Cu")
		(net "M_G_CPU0_SA_CB<4>")
	)
	(arc
		(start 385.25196 -261.7343)
		(mid 385.064762 -261.684157)
		(end 384.877564 -261.7343)
		(width 0.088646)
		(layer "In6.Cu")
		(net "M_G_CPU0_SA_CB<4>")
	)
	(arc
		(start 387.415024 -260.869176)
		(mid 387.317644 -260.882386)
		(end 387.227064 -260.920484)
		(width 0.088646)
		(layer "In6.Cu")
		(net "M_G_CPU0_SA_CB<4>")
	)
	(arc
		(start 382.997964 -261.7343)
		(mid 382.721405 -261.810043)
		(end 382.443228 -261.740396)
		(width 0.088646)
		(layer "In6.Cu")
		(net "M_G_CPU0_SA_CB<4>")
	)
	(arc
		(start 383.937764 -261.7343)
		(mid 383.655062 -261.810076)
		(end 383.37236 -261.7343)
		(width 0.088646)
		(layer "In6.Cu")
		(net "M_G_CPU0_SA_CB<4>")
	)
	(arc
		(start 375.854214 -262.383016)
		(mid 375.667016 -262.433159)
		(end 375.479818 -262.383016)
		(width 0.088646)
		(layer "In6.Cu")
		(net "M_G_CPU0_SA_CB<4>")
	)
	(arc
		(start 381.493014 -261.7343)
		(mid 381.305816 -261.684157)
		(end 381.118618 -261.7343)
		(width 0.088646)
		(layer "In6.Cu")
		(net "M_G_CPU0_SA_CB<4>")
	)
	(segment
		(start 443.462664 -276.791674)
		(end 445.470534 -276.791674)
		(width 0.1016)
		(layer "F.Cu")
		(net "M_G_CPU0_SA_CB<3>")
	)
	(segment
		(start 446.964562 -276.093174)
		(end 447.23812 -276.366732)
		(width 0.20066)
		(layer "F.Cu")
		(net "M_G_CPU0_SA_CB<3>")
	)
	(segment
		(start 447.23812 -276.366732)
		(end 448.572382 -276.366732)
		(width 0.20066)
		(layer "F.Cu")
		(net "M_G_CPU0_SA_CB<3>")
	)
	(segment
		(start 376.606562 -263.150604)
		(end 376.606562 -263.68629)
		(width 0.20066)
		(layer "F.Cu")
		(net "M_G_CPU0_SA_CB<3>")
	)
	(segment
		(start 439.923682 -276.366732)
		(end 441.028582 -276.366732)
		(width 0.20066)
		(layer "F.Cu")
		(net "M_G_CPU0_SA_CB<3>")
	)
	(segment
		(start 443.283086 -276.791674)
		(end 443.462664 -276.791674)
		(width 0.101854)
		(layer "F.Cu")
		(net "M_G_CPU0_SA_CB<3>")
	)
	(segment
		(start 446.167256 -276.791674)
		(end 446.367916 -276.591014)
		(width 0.20066)
		(layer "F.Cu")
		(net "M_G_CPU0_SA_CB<3>")
	)
	(segment
		(start 442.733938 -276.366732)
		(end 443.15888 -276.791674)
		(width 0.20066)
		(layer "F.Cu")
		(net "M_G_CPU0_SA_CB<3>")
	)
	(segment
		(start 441.028582 -276.366732)
		(end 442.733938 -276.366732)
		(width 0.20066)
		(layer "F.Cu")
		(net "M_G_CPU0_SA_CB<3>")
	)
	(segment
		(start 445.774572 -276.791674)
		(end 446.167256 -276.791674)
		(width 0.20066)
		(layer "F.Cu")
		(net "M_G_CPU0_SA_CB<3>")
	)
	(segment
		(start 446.568576 -276.093174)
		(end 446.964562 -276.093174)
		(width 0.20066)
		(layer "F.Cu")
		(net "M_G_CPU0_SA_CB<3>")
	)
	(segment
		(start 443.15888 -276.791674)
		(end 443.283086 -276.791674)
		(width 0.20066)
		(layer "F.Cu")
		(net "M_G_CPU0_SA_CB<3>")
	)
	(segment
		(start 445.470534 -276.791674)
		(end 445.774572 -276.791674)
		(width 0.101854)
		(layer "F.Cu")
		(net "M_G_CPU0_SA_CB<3>")
	)
	(segment
		(start 446.367916 -276.293834)
		(end 446.568576 -276.093174)
		(width 0.20066)
		(layer "F.Cu")
		(net "M_G_CPU0_SA_CB<3>")
	)
	(segment
		(start 376.606562 -263.68629)
		(end 376.606816 -263.686544)
		(width 0.20066)
		(layer "F.Cu")
		(net "M_G_CPU0_SA_CB<3>")
	)
	(segment
		(start 446.367916 -276.591014)
		(end 446.367916 -276.293834)
		(width 0.20066)
		(layer "F.Cu")
		(net "M_G_CPU0_SA_CB<3>")
	)
	(segment
		(start 386.206746 -264.002266)
		(end 386.192014 -264.010902)
		(width 0.088646)
		(layer "In6.Cu")
		(net "M_G_CPU0_SA_CB<3>")
	)
	(segment
		(start 438.366154 -275.310346)
		(end 438.366154 -274.696174)
		(width 0.18288)
		(layer "In6.Cu")
		(net "M_G_CPU0_SA_CB<3>")
	)
	(segment
		(start 382.443228 -264.004806)
		(end 382.432814 -264.010902)
		(width 0.088646)
		(layer "In6.Cu")
		(net "M_G_CPU0_SA_CB<3>")
	)
	(segment
		(start 390.670034 -263.166352)
		(end 388.535672 -263.166352)
		(width 0.18288)
		(layer "In6.Cu")
		(net "M_G_CPU0_SA_CB<3>")
	)
	(segment
		(start 412.958534 -265.77417)
		(end 412.120588 -266.612116)
		(width 0.18288)
		(layer "In6.Cu")
		(net "M_G_CPU0_SA_CB<3>")
	)
	(segment
		(start 381.118364 -264.010902)
		(end 381.112522 -264.007346)
		(width 0.088646)
		(layer "In6.Cu")
		(net "M_G_CPU0_SA_CB<3>")
	)
	(segment
		(start 377.365006 -264.014204)
		(end 377.359164 -264.010902)
		(width 0.088646)
		(layer "In6.Cu")
		(net "M_G_CPU0_SA_CB<3>")
	)
	(segment
		(start 439.287158 -275.662898)
		(end 439.117486 -275.493226)
		(width 0.18288)
		(layer "In6.Cu")
		(net "M_G_CPU0_SA_CB<3>")
	)
	(segment
		(start 380.178564 -264.010902)
		(end 380.172722 -264.007346)
		(width 0.088646)
		(layer "In6.Cu")
		(net "M_G_CPU0_SA_CB<3>")
	)
	(segment
		(start 429.948848 -274.438618)
		(end 429.24222 -273.73199)
		(width 0.18288)
		(layer "In6.Cu")
		(net "M_G_CPU0_SA_CB<3>")
	)
	(segment
		(start 436.53964 -275.941282)
		(end 433.938172 -275.941282)
		(width 0.18288)
		(layer "In6.Cu")
		(net "M_G_CPU0_SA_CB<3>")
	)
	(segment
		(start 437.489854 -275.493226)
		(end 436.987696 -275.493226)
		(width 0.18288)
		(layer "In6.Cu")
		(net "M_G_CPU0_SA_CB<3>")
	)
	(segment
		(start 416.576256 -266.781026)
		(end 415.5694 -265.77417)
		(width 0.18288)
		(layer "In6.Cu")
		(net "M_G_CPU0_SA_CB<3>")
	)
	(segment
		(start 407.663142 -265.899138)
		(end 405.533098 -265.899138)
		(width 0.18288)
		(layer "In6.Cu")
		(net "M_G_CPU0_SA_CB<3>")
	)
	(segment
		(start 385.262374 -264.004806)
		(end 385.25196 -264.010902)
		(width 0.088646)
		(layer "In6.Cu")
		(net "M_G_CPU0_SA_CB<3>")
	)
	(segment
		(start 420.072058 -266.781026)
		(end 416.576256 -266.781026)
		(width 0.18288)
		(layer "In6.Cu")
		(net "M_G_CPU0_SA_CB<3>")
	)
	(segment
		(start 439.117486 -275.493226)
		(end 438.549034 -275.493226)
		(width 0.18288)
		(layer "In6.Cu")
		(net "M_G_CPU0_SA_CB<3>")
	)
	(segment
		(start 422.373552 -266.872212)
		(end 422.093644 -266.592304)
		(width 0.18288)
		(layer "In6.Cu")
		(net "M_G_CPU0_SA_CB<3>")
	)
	(segment
		(start 378.304806 -264.014204)
		(end 378.298964 -264.010902)
		(width 0.088646)
		(layer "In6.Cu")
		(net "M_G_CPU0_SA_CB<3>")
	)
	(segment
		(start 429.24222 -268.857476)
		(end 428.67834 -268.293596)
		(width 0.18288)
		(layer "In6.Cu")
		(net "M_G_CPU0_SA_CB<3>")
	)
	(segment
		(start 412.120588 -266.612116)
		(end 408.37612 -266.612116)
		(width 0.18288)
		(layer "In6.Cu")
		(net "M_G_CPU0_SA_CB<3>")
	)
	(segment
		(start 379.238764 -264.010902)
		(end 379.232922 -264.007346)
		(width 0.088646)
		(layer "In6.Cu")
		(net "M_G_CPU0_SA_CB<3>")
	)
	(segment
		(start 393.1539 -263.660382)
		(end 390.670034 -263.166352)
		(width 0.18288)
		(layer "In6.Cu")
		(net "M_G_CPU0_SA_CB<3>")
	)
	(segment
		(start 379.244606 -264.014204)
		(end 379.238764 -264.010902)
		(width 0.088646)
		(layer "In6.Cu")
		(net "M_G_CPU0_SA_CB<3>")
	)
	(segment
		(start 381.124206 -264.014204)
		(end 381.118364 -264.010902)
		(width 0.088646)
		(layer "In6.Cu")
		(net "M_G_CPU0_SA_CB<3>")
	)
	(segment
		(start 422.373552 -268.110716)
		(end 422.373552 -266.872212)
		(width 0.18288)
		(layer "In6.Cu")
		(net "M_G_CPU0_SA_CB<3>")
	)
	(segment
		(start 428.67834 -268.293596)
		(end 422.556432 -268.293596)
		(width 0.18288)
		(layer "In6.Cu")
		(net "M_G_CPU0_SA_CB<3>")
	)
	(segment
		(start 437.672734 -274.696174)
		(end 437.672734 -275.310346)
		(width 0.18288)
		(layer "In6.Cu")
		(net "M_G_CPU0_SA_CB<3>")
	)
	(segment
		(start 388.535672 -263.166352)
		(end 388.341108 -263.166352)
		(width 0.088646)
		(layer "In6.Cu")
		(net "M_G_CPU0_SA_CB<3>")
	)
	(segment
		(start 403.294342 -263.660382)
		(end 393.1539 -263.660382)
		(width 0.18288)
		(layer "In6.Cu")
		(net "M_G_CPU0_SA_CB<3>")
	)
	(segment
		(start 439.478674 -276.366732)
		(end 439.287158 -276.175216)
		(width 0.18288)
		(layer "In6.Cu")
		(net "M_G_CPU0_SA_CB<3>")
	)
	(segment
		(start 408.37612 -266.612116)
		(end 407.663142 -265.899138)
		(width 0.18288)
		(layer "In6.Cu")
		(net "M_G_CPU0_SA_CB<3>")
	)
	(segment
		(start 422.556432 -268.293596)
		(end 422.373552 -268.110716)
		(width 0.18288)
		(layer "In6.Cu")
		(net "M_G_CPU0_SA_CB<3>")
	)
	(segment
		(start 437.855614 -274.513294)
		(end 437.672734 -274.696174)
		(width 0.18288)
		(layer "In6.Cu")
		(net "M_G_CPU0_SA_CB<3>")
	)
	(segment
		(start 438.549034 -275.493226)
		(end 438.366154 -275.310346)
		(width 0.18288)
		(layer "In6.Cu")
		(net "M_G_CPU0_SA_CB<3>")
	)
	(segment
		(start 415.5694 -265.77417)
		(end 412.958534 -265.77417)
		(width 0.18288)
		(layer "In6.Cu")
		(net "M_G_CPU0_SA_CB<3>")
	)
	(segment
		(start 438.366154 -274.696174)
		(end 438.183274 -274.513294)
		(width 0.18288)
		(layer "In6.Cu")
		(net "M_G_CPU0_SA_CB<3>")
	)
	(segment
		(start 437.672734 -275.310346)
		(end 437.489854 -275.493226)
		(width 0.18288)
		(layer "In6.Cu")
		(net "M_G_CPU0_SA_CB<3>")
	)
	(segment
		(start 429.24222 -273.73199)
		(end 429.24222 -268.857476)
		(width 0.18288)
		(layer "In6.Cu")
		(net "M_G_CPU0_SA_CB<3>")
	)
	(segment
		(start 405.533098 -265.899138)
		(end 403.294342 -263.660382)
		(width 0.18288)
		(layer "In6.Cu")
		(net "M_G_CPU0_SA_CB<3>")
	)
	(segment
		(start 438.183274 -274.513294)
		(end 437.855614 -274.513294)
		(width 0.18288)
		(layer "In6.Cu")
		(net "M_G_CPU0_SA_CB<3>")
	)
	(segment
		(start 387.57225 -263.93521)
		(end 387.414008 -263.93521)
		(width 0.088646)
		(layer "In6.Cu")
		(net "M_G_CPU0_SA_CB<3>")
	)
	(segment
		(start 381.507746 -264.002266)
		(end 381.493014 -264.010902)
		(width 0.088646)
		(layer "In6.Cu")
		(net "M_G_CPU0_SA_CB<3>")
	)
	(segment
		(start 439.287158 -276.175216)
		(end 439.287158 -275.662898)
		(width 0.18288)
		(layer "In6.Cu")
		(net "M_G_CPU0_SA_CB<3>")
	)
	(segment
		(start 432.435508 -274.438618)
		(end 429.948848 -274.438618)
		(width 0.18288)
		(layer "In6.Cu")
		(net "M_G_CPU0_SA_CB<3>")
	)
	(segment
		(start 378.298964 -264.010902)
		(end 378.293122 -264.007346)
		(width 0.088646)
		(layer "In6.Cu")
		(net "M_G_CPU0_SA_CB<3>")
	)
	(segment
		(start 436.987696 -275.493226)
		(end 436.53964 -275.941282)
		(width 0.18288)
		(layer "In6.Cu")
		(net "M_G_CPU0_SA_CB<3>")
	)
	(segment
		(start 439.923682 -276.366732)
		(end 439.478674 -276.366732)
		(width 0.18288)
		(layer "In6.Cu")
		(net "M_G_CPU0_SA_CB<3>")
	)
	(segment
		(start 433.938172 -275.941282)
		(end 432.435508 -274.438618)
		(width 0.18288)
		(layer "In6.Cu")
		(net "M_G_CPU0_SA_CB<3>")
	)
	(segment
		(start 377.359164 -264.010902)
		(end 376.9614 -263.78154)
		(width 0.088646)
		(layer "In6.Cu")
		(net "M_G_CPU0_SA_CB<3>")
	)
	(segment
		(start 380.184406 -264.014204)
		(end 380.178564 -264.010902)
		(width 0.088646)
		(layer "In6.Cu")
		(net "M_G_CPU0_SA_CB<3>")
	)
	(segment
		(start 420.26078 -266.592304)
		(end 420.072058 -266.781026)
		(width 0.18288)
		(layer "In6.Cu")
		(net "M_G_CPU0_SA_CB<3>")
	)
	(segment
		(start 422.093644 -266.592304)
		(end 420.26078 -266.592304)
		(width 0.18288)
		(layer "In6.Cu")
		(net "M_G_CPU0_SA_CB<3>")
	)
	(segment
		(start 388.341108 -263.166352)
		(end 387.57225 -263.93521)
		(width 0.088646)
		(layer "In6.Cu")
		(net "M_G_CPU0_SA_CB<3>")
	)
	(arc
		(start 385.25196 -264.010902)
		(mid 385.064762 -264.061045)
		(end 384.877564 -264.010902)
		(width 0.088646)
		(layer "In6.Cu")
		(net "M_G_CPU0_SA_CB<3>")
	)
	(arc
		(start 383.937764 -264.010902)
		(mid 383.655062 -263.935126)
		(end 383.37236 -264.010902)
		(width 0.088646)
		(layer "In6.Cu")
		(net "M_G_CPU0_SA_CB<3>")
	)
	(arc
		(start 382.432814 -264.010902)
		(mid 382.245616 -264.061045)
		(end 382.058418 -264.010902)
		(width 0.088646)
		(layer "In6.Cu")
		(net "M_G_CPU0_SA_CB<3>")
	)
	(arc
		(start 380.553214 -264.010902)
		(mid 380.36926 -264.061031)
		(end 380.184406 -264.014204)
		(width 0.088646)
		(layer "In6.Cu")
		(net "M_G_CPU0_SA_CB<3>")
	)
	(arc
		(start 376.9614 -263.78154)
		(mid 376.790348 -263.710759)
		(end 376.606816 -263.686544)
		(width 0.088646)
		(layer "In6.Cu")
		(net "M_G_CPU0_SA_CB<3>")
	)
	(arc
		(start 386.757418 -264.010902)
		(mid 386.483219 -263.935067)
		(end 386.206746 -264.002266)
		(width 0.088646)
		(layer "In6.Cu")
		(net "M_G_CPU0_SA_CB<3>")
	)
	(arc
		(start 378.673614 -264.010902)
		(mid 378.48966 -264.061031)
		(end 378.304806 -264.014204)
		(width 0.088646)
		(layer "In6.Cu")
		(net "M_G_CPU0_SA_CB<3>")
	)
	(arc
		(start 384.31216 -264.010902)
		(mid 384.124962 -264.061045)
		(end 383.937764 -264.010902)
		(width 0.088646)
		(layer "In6.Cu")
		(net "M_G_CPU0_SA_CB<3>")
	)
	(arc
		(start 381.112522 -264.007346)
		(mid 380.832387 -263.935063)
		(end 380.553214 -264.010902)
		(width 0.088646)
		(layer "In6.Cu")
		(net "M_G_CPU0_SA_CB<3>")
	)
	(arc
		(start 378.293122 -264.007346)
		(mid 378.012987 -263.935063)
		(end 377.733814 -264.010902)
		(width 0.088646)
		(layer "In6.Cu")
		(net "M_G_CPU0_SA_CB<3>")
	)
	(arc
		(start 383.37236 -264.010902)
		(mid 383.185162 -264.061045)
		(end 382.997964 -264.010902)
		(width 0.088646)
		(layer "In6.Cu")
		(net "M_G_CPU0_SA_CB<3>")
	)
	(arc
		(start 380.172722 -264.007346)
		(mid 379.892587 -263.935063)
		(end 379.613414 -264.010902)
		(width 0.088646)
		(layer "In6.Cu")
		(net "M_G_CPU0_SA_CB<3>")
	)
	(arc
		(start 379.613414 -264.010902)
		(mid 379.42946 -264.061031)
		(end 379.244606 -264.014204)
		(width 0.088646)
		(layer "In6.Cu")
		(net "M_G_CPU0_SA_CB<3>")
	)
	(arc
		(start 384.877564 -264.010902)
		(mid 384.594862 -263.935126)
		(end 384.31216 -264.010902)
		(width 0.088646)
		(layer "In6.Cu")
		(net "M_G_CPU0_SA_CB<3>")
	)
	(arc
		(start 387.414008 -263.93521)
		(mid 387.395839 -263.935429)
		(end 387.377686 -263.936226)
		(width 0.088646)
		(layer "In6.Cu")
		(net "M_G_CPU0_SA_CB<3>")
	)
	(arc
		(start 377.733814 -264.010902)
		(mid 377.54986 -264.061031)
		(end 377.365006 -264.014204)
		(width 0.088646)
		(layer "In6.Cu")
		(net "M_G_CPU0_SA_CB<3>")
	)
	(arc
		(start 382.058418 -264.010902)
		(mid 381.784219 -263.935067)
		(end 381.507746 -264.002266)
		(width 0.088646)
		(layer "In6.Cu")
		(net "M_G_CPU0_SA_CB<3>")
	)
	(arc
		(start 386.192014 -264.010902)
		(mid 386.004816 -264.061045)
		(end 385.817618 -264.010902)
		(width 0.088646)
		(layer "In6.Cu")
		(net "M_G_CPU0_SA_CB<3>")
	)
	(arc
		(start 387.377686 -263.936226)
		(mid 387.250458 -263.959424)
		(end 387.131814 -264.010902)
		(width 0.088646)
		(layer "In6.Cu")
		(net "M_G_CPU0_SA_CB<3>")
	)
	(arc
		(start 387.131814 -264.010902)
		(mid 386.944616 -264.061045)
		(end 386.757418 -264.010902)
		(width 0.088646)
		(layer "In6.Cu")
		(net "M_G_CPU0_SA_CB<3>")
	)
	(arc
		(start 385.817618 -264.010902)
		(mid 385.540805 -263.935032)
		(end 385.262374 -264.004806)
		(width 0.088646)
		(layer "In6.Cu")
		(net "M_G_CPU0_SA_CB<3>")
	)
	(arc
		(start 381.493014 -264.010902)
		(mid 381.30906 -264.061031)
		(end 381.124206 -264.014204)
		(width 0.088646)
		(layer "In6.Cu")
		(net "M_G_CPU0_SA_CB<3>")
	)
	(arc
		(start 382.997964 -264.010902)
		(mid 382.721405 -263.935159)
		(end 382.443228 -264.004806)
		(width 0.088646)
		(layer "In6.Cu")
		(net "M_G_CPU0_SA_CB<3>")
	)
	(arc
		(start 379.232922 -264.007346)
		(mid 378.952787 -263.935063)
		(end 378.673614 -264.010902)
		(width 0.088646)
		(layer "In6.Cu")
		(net "M_G_CPU0_SA_CB<3>")
	)
	(segment
		(start 446.167256 -278.491696)
		(end 446.367916 -278.291036)
		(width 0.20066)
		(layer "F.Cu")
		(net "M_G_CPU0_SA_CB<2>")
	)
	(segment
		(start 445.428878 -278.491696)
		(end 445.774572 -278.491696)
		(width 0.101854)
		(layer "F.Cu")
		(net "M_G_CPU0_SA_CB<2>")
	)
	(segment
		(start 443.050168 -278.491696)
		(end 443.283086 -278.491696)
		(width 0.20066)
		(layer "F.Cu")
		(net "M_G_CPU0_SA_CB<2>")
	)
	(segment
		(start 439.923682 -278.066754)
		(end 441.028582 -278.066754)
		(width 0.20066)
		(layer "F.Cu")
		(net "M_G_CPU0_SA_CB<2>")
	)
	(segment
		(start 442.625226 -278.066754)
		(end 443.050168 -278.491696)
		(width 0.20066)
		(layer "F.Cu")
		(net "M_G_CPU0_SA_CB<2>")
	)
	(segment
		(start 441.028582 -278.066754)
		(end 442.625226 -278.066754)
		(width 0.20066)
		(layer "F.Cu")
		(net "M_G_CPU0_SA_CB<2>")
	)
	(segment
		(start 446.568576 -277.77186)
		(end 446.943226 -277.77186)
		(width 0.20066)
		(layer "F.Cu")
		(net "M_G_CPU0_SA_CB<2>")
	)
	(segment
		(start 446.943226 -277.77186)
		(end 447.23812 -278.066754)
		(width 0.20066)
		(layer "F.Cu")
		(net "M_G_CPU0_SA_CB<2>")
	)
	(segment
		(start 445.774572 -278.491696)
		(end 446.167256 -278.491696)
		(width 0.20066)
		(layer "F.Cu")
		(net "M_G_CPU0_SA_CB<2>")
	)
	(segment
		(start 443.462664 -278.491696)
		(end 445.428878 -278.491696)
		(width 0.1016)
		(layer "F.Cu")
		(net "M_G_CPU0_SA_CB<2>")
	)
	(segment
		(start 443.283086 -278.491696)
		(end 443.462664 -278.491696)
		(width 0.101854)
		(layer "F.Cu")
		(net "M_G_CPU0_SA_CB<2>")
	)
	(segment
		(start 447.23812 -278.066754)
		(end 448.572382 -278.066754)
		(width 0.20066)
		(layer "F.Cu")
		(net "M_G_CPU0_SA_CB<2>")
	)
	(segment
		(start 376.136916 -264.500106)
		(end 376.136662 -264.50036)
		(width 0.20066)
		(layer "F.Cu")
		(net "M_G_CPU0_SA_CB<2>")
	)
	(segment
		(start 376.136916 -263.96442)
		(end 376.136916 -264.500106)
		(width 0.20066)
		(layer "F.Cu")
		(net "M_G_CPU0_SA_CB<2>")
	)
	(segment
		(start 446.367916 -278.291036)
		(end 446.367916 -277.97252)
		(width 0.20066)
		(layer "F.Cu")
		(net "M_G_CPU0_SA_CB<2>")
	)
	(segment
		(start 446.367916 -277.97252)
		(end 446.568576 -277.77186)
		(width 0.20066)
		(layer "F.Cu")
		(net "M_G_CPU0_SA_CB<2>")
	)
	(segment
		(start 429.784764 -276.391116)
		(end 429.601884 -276.573996)
		(width 0.18288)
		(layer "In6.Cu")
		(net "M_G_CPU0_SA_CB<2>")
	)
	(segment
		(start 436.809896 -277.640796)
		(end 435.15407 -277.640796)
		(width 0.18288)
		(layer "In6.Cu")
		(net "M_G_CPU0_SA_CB<2>")
	)
	(segment
		(start 416.280092 -267.91031)
		(end 414.536382 -267.91031)
		(width 0.18288)
		(layer "In6.Cu")
		(net "M_G_CPU0_SA_CB<2>")
	)
	(segment
		(start 386.287264 -264.824718)
		(end 386.272532 -264.816082)
		(width 0.088646)
		(layer "In6.Cu")
		(net "M_G_CPU0_SA_CB<2>")
	)
	(segment
		(start 426.635164 -272.443956)
		(end 427.037754 -272.443956)
		(width 0.18288)
		(layer "In6.Cu")
		(net "M_G_CPU0_SA_CB<2>")
	)
	(segment
		(start 377.27128 -264.8204)
		(end 377.263914 -264.824718)
		(width 0.088646)
		(layer "In6.Cu")
		(net "M_G_CPU0_SA_CB<2>")
	)
	(segment
		(start 406.539954 -267.563346)
		(end 405.57577 -267.563346)
		(width 0.18288)
		(layer "In6.Cu")
		(net "M_G_CPU0_SA_CB<2>")
	)
	(segment
		(start 385.347464 -264.824718)
		(end 385.332732 -264.816082)
		(width 0.088646)
		(layer "In6.Cu")
		(net "M_G_CPU0_SA_CB<2>")
	)
	(segment
		(start 402.69668 -264.684256)
		(end 393.040362 -264.684256)
		(width 0.18288)
		(layer "In6.Cu")
		(net "M_G_CPU0_SA_CB<2>")
	)
	(segment
		(start 437.175656 -276.75332)
		(end 436.992776 -276.9362)
		(width 0.18288)
		(layer "In6.Cu")
		(net "M_G_CPU0_SA_CB<2>")
	)
	(segment
		(start 427.220634 -271.933416)
		(end 427.037754 -271.750536)
		(width 0.18288)
		(layer "In6.Cu")
		(net "M_G_CPU0_SA_CB<2>")
	)
	(segment
		(start 426.452284 -272.626836)
		(end 426.635164 -272.443956)
		(width 0.18288)
		(layer "In6.Cu")
		(net "M_G_CPU0_SA_CB<2>")
	)
	(segment
		(start 426.635164 -271.750536)
		(end 426.452284 -271.567656)
		(width 0.18288)
		(layer "In6.Cu")
		(net "M_G_CPU0_SA_CB<2>")
	)
	(segment
		(start 426.452284 -270.471138)
		(end 425.973494 -269.992348)
		(width 0.18288)
		(layer "In6.Cu")
		(net "M_G_CPU0_SA_CB<2>")
	)
	(segment
		(start 434.462682 -277.792434)
		(end 432.299618 -276.629368)
		(width 0.18288)
		(layer "In6.Cu")
		(net "M_G_CPU0_SA_CB<2>")
	)
	(segment
		(start 419.463474 -268.33195)
		(end 416.701732 -268.33195)
		(width 0.18288)
		(layer "In6.Cu")
		(net "M_G_CPU0_SA_CB<2>")
	)
	(segment
		(start 422.166796 -269.776194)
		(end 422.149524 -269.758922)
		(width 0.18288)
		(layer "In6.Cu")
		(net "M_G_CPU0_SA_CB<2>")
	)
	(segment
		(start 381.97028 -264.8204)
		(end 381.962914 -264.824718)
		(width 0.088646)
		(layer "In6.Cu")
		(net "M_G_CPU0_SA_CB<2>")
	)
	(segment
		(start 388.535672 -264.171684)
		(end 388.27329 -264.171684)
		(width 0.088646)
		(layer "In6.Cu")
		(net "M_G_CPU0_SA_CB<2>")
	)
	(segment
		(start 422.149524 -269.758922)
		(end 421.045894 -269.142464)
		(width 0.18288)
		(layer "In6.Cu")
		(net "M_G_CPU0_SA_CB<2>")
	)
	(segment
		(start 436.992776 -277.457916)
		(end 436.809896 -277.640796)
		(width 0.18288)
		(layer "In6.Cu")
		(net "M_G_CPU0_SA_CB<2>")
	)
	(segment
		(start 436.992776 -276.9362)
		(end 436.992776 -277.457916)
		(width 0.18288)
		(layer "In6.Cu")
		(net "M_G_CPU0_SA_CB<2>")
	)
	(segment
		(start 423.805858 -269.776194)
		(end 422.166796 -269.776194)
		(width 0.18288)
		(layer "In6.Cu")
		(net "M_G_CPU0_SA_CB<2>")
	)
	(segment
		(start 414.536382 -267.91031)
		(end 414.358074 -268.088618)
		(width 0.18288)
		(layer "In6.Cu")
		(net "M_G_CPU0_SA_CB<2>")
	)
	(segment
		(start 427.786292 -275.598128)
		(end 426.452284 -274.26412)
		(width 0.18288)
		(layer "In6.Cu")
		(net "M_G_CPU0_SA_CB<2>")
	)
	(segment
		(start 431.706528 -276.629368)
		(end 430.675288 -275.598128)
		(width 0.18288)
		(layer "In6.Cu")
		(net "M_G_CPU0_SA_CB<2>")
	)
	(segment
		(start 432.299618 -276.629368)
		(end 431.706528 -276.629368)
		(width 0.18288)
		(layer "In6.Cu")
		(net "M_G_CPU0_SA_CB<2>")
	)
	(segment
		(start 427.037754 -271.750536)
		(end 426.635164 -271.750536)
		(width 0.18288)
		(layer "In6.Cu")
		(net "M_G_CPU0_SA_CB<2>")
	)
	(segment
		(start 435.002432 -277.792434)
		(end 434.462682 -277.792434)
		(width 0.18288)
		(layer "In6.Cu")
		(net "M_G_CPU0_SA_CB<2>")
	)
	(segment
		(start 425.973494 -269.992348)
		(end 424.022012 -269.992348)
		(width 0.18288)
		(layer "In6.Cu")
		(net "M_G_CPU0_SA_CB<2>")
	)
	(segment
		(start 377.263914 -264.824718)
		(end 377.259342 -264.827512)
		(width 0.088646)
		(layer "In6.Cu")
		(net "M_G_CPU0_SA_CB<2>")
	)
	(segment
		(start 429.601884 -276.573996)
		(end 429.274224 -276.573996)
		(width 0.18288)
		(layer "In6.Cu")
		(net "M_G_CPU0_SA_CB<2>")
	)
	(segment
		(start 416.701732 -268.33195)
		(end 416.280092 -267.91031)
		(width 0.18288)
		(layer "In6.Cu")
		(net "M_G_CPU0_SA_CB<2>")
	)
	(segment
		(start 381.962914 -264.824718)
		(end 381.958342 -264.827512)
		(width 0.088646)
		(layer "In6.Cu")
		(net "M_G_CPU0_SA_CB<2>")
	)
	(segment
		(start 437.869076 -277.640796)
		(end 437.686196 -277.457916)
		(width 0.18288)
		(layer "In6.Cu")
		(net "M_G_CPU0_SA_CB<2>")
	)
	(segment
		(start 421.045894 -269.142464)
		(end 420.273988 -269.142464)
		(width 0.18288)
		(layer "In6.Cu")
		(net "M_G_CPU0_SA_CB<2>")
	)
	(segment
		(start 381.03048 -264.8204)
		(end 381.023114 -264.824718)
		(width 0.088646)
		(layer "In6.Cu")
		(net "M_G_CPU0_SA_CB<2>")
	)
	(segment
		(start 412.678118 -268.088618)
		(end 412.298642 -268.468094)
		(width 0.18288)
		(layer "In6.Cu")
		(net "M_G_CPU0_SA_CB<2>")
	)
	(segment
		(start 429.784764 -275.781008)
		(end 429.784764 -276.391116)
		(width 0.18288)
		(layer "In6.Cu")
		(net "M_G_CPU0_SA_CB<2>")
	)
	(segment
		(start 429.967644 -275.598128)
		(end 429.784764 -275.781008)
		(width 0.18288)
		(layer "In6.Cu")
		(net "M_G_CPU0_SA_CB<2>")
	)
	(segment
		(start 439.923682 -278.066754)
		(end 439.497724 -277.640796)
		(width 0.18288)
		(layer "In6.Cu")
		(net "M_G_CPU0_SA_CB<2>")
	)
	(segment
		(start 390.463278 -264.171684)
		(end 388.535672 -264.171684)
		(width 0.18288)
		(layer "In6.Cu")
		(net "M_G_CPU0_SA_CB<2>")
	)
	(segment
		(start 379.15088 -264.8204)
		(end 379.143514 -264.824718)
		(width 0.088646)
		(layer "In6.Cu")
		(net "M_G_CPU0_SA_CB<2>")
	)
	(segment
		(start 426.452284 -274.26412)
		(end 426.452284 -272.626836)
		(width 0.18288)
		(layer "In6.Cu")
		(net "M_G_CPU0_SA_CB<2>")
	)
	(segment
		(start 411.3657 -268.292072)
		(end 407.26868 -268.292072)
		(width 0.18288)
		(layer "In6.Cu")
		(net "M_G_CPU0_SA_CB<2>")
	)
	(segment
		(start 411.541722 -268.468094)
		(end 411.3657 -268.292072)
		(width 0.18288)
		(layer "In6.Cu")
		(net "M_G_CPU0_SA_CB<2>")
	)
	(segment
		(start 437.503316 -276.75332)
		(end 437.175656 -276.75332)
		(width 0.18288)
		(layer "In6.Cu")
		(net "M_G_CPU0_SA_CB<2>")
	)
	(segment
		(start 429.091344 -276.391116)
		(end 429.091344 -275.781008)
		(width 0.18288)
		(layer "In6.Cu")
		(net "M_G_CPU0_SA_CB<2>")
	)
	(segment
		(start 405.57577 -267.563346)
		(end 402.69668 -264.684256)
		(width 0.18288)
		(layer "In6.Cu")
		(net "M_G_CPU0_SA_CB<2>")
	)
	(segment
		(start 437.686196 -277.457916)
		(end 437.686196 -276.9362)
		(width 0.18288)
		(layer "In6.Cu")
		(net "M_G_CPU0_SA_CB<2>")
	)
	(segment
		(start 380.083314 -264.824718)
		(end 380.078742 -264.827512)
		(width 0.088646)
		(layer "In6.Cu")
		(net "M_G_CPU0_SA_CB<2>")
	)
	(segment
		(start 384.407664 -264.824718)
		(end 384.392932 -264.816082)
		(width 0.088646)
		(layer "In6.Cu")
		(net "M_G_CPU0_SA_CB<2>")
	)
	(segment
		(start 428.908464 -275.598128)
		(end 427.786292 -275.598128)
		(width 0.18288)
		(layer "In6.Cu")
		(net "M_G_CPU0_SA_CB<2>")
	)
	(segment
		(start 439.497724 -277.640796)
		(end 437.869076 -277.640796)
		(width 0.18288)
		(layer "In6.Cu")
		(net "M_G_CPU0_SA_CB<2>")
	)
	(segment
		(start 393.040362 -264.684256)
		(end 390.463278 -264.171684)
		(width 0.18288)
		(layer "In6.Cu")
		(net "M_G_CPU0_SA_CB<2>")
	)
	(segment
		(start 429.091344 -275.781008)
		(end 428.908464 -275.598128)
		(width 0.18288)
		(layer "In6.Cu")
		(net "M_G_CPU0_SA_CB<2>")
	)
	(segment
		(start 412.298642 -268.468094)
		(end 411.541722 -268.468094)
		(width 0.18288)
		(layer "In6.Cu")
		(net "M_G_CPU0_SA_CB<2>")
	)
	(segment
		(start 426.452284 -271.567656)
		(end 426.452284 -270.471138)
		(width 0.18288)
		(layer "In6.Cu")
		(net "M_G_CPU0_SA_CB<2>")
	)
	(segment
		(start 437.686196 -276.9362)
		(end 437.503316 -276.75332)
		(width 0.18288)
		(layer "In6.Cu")
		(net "M_G_CPU0_SA_CB<2>")
	)
	(segment
		(start 381.023114 -264.824718)
		(end 381.018542 -264.827512)
		(width 0.088646)
		(layer "In6.Cu")
		(net "M_G_CPU0_SA_CB<2>")
	)
	(segment
		(start 424.022012 -269.992348)
		(end 423.805858 -269.776194)
		(width 0.18288)
		(layer "In6.Cu")
		(net "M_G_CPU0_SA_CB<2>")
	)
	(segment
		(start 429.274224 -276.573996)
		(end 429.091344 -276.391116)
		(width 0.18288)
		(layer "In6.Cu")
		(net "M_G_CPU0_SA_CB<2>")
	)
	(segment
		(start 383.467864 -264.824718)
		(end 383.453132 -264.816082)
		(width 0.088646)
		(layer "In6.Cu")
		(net "M_G_CPU0_SA_CB<2>")
	)
	(segment
		(start 378.203714 -264.824718)
		(end 378.199142 -264.827512)
		(width 0.088646)
		(layer "In6.Cu")
		(net "M_G_CPU0_SA_CB<2>")
	)
	(segment
		(start 407.26868 -268.292072)
		(end 406.539954 -267.563346)
		(width 0.18288)
		(layer "In6.Cu")
		(net "M_G_CPU0_SA_CB<2>")
	)
	(segment
		(start 427.220634 -272.261076)
		(end 427.220634 -271.933416)
		(width 0.18288)
		(layer "In6.Cu")
		(net "M_G_CPU0_SA_CB<2>")
	)
	(segment
		(start 387.227064 -264.824718)
		(end 387.212332 -264.816082)
		(width 0.088646)
		(layer "In6.Cu")
		(net "M_G_CPU0_SA_CB<2>")
	)
	(segment
		(start 427.037754 -272.443956)
		(end 427.220634 -272.261076)
		(width 0.18288)
		(layer "In6.Cu")
		(net "M_G_CPU0_SA_CB<2>")
	)
	(segment
		(start 380.09068 -264.8204)
		(end 380.083314 -264.824718)
		(width 0.088646)
		(layer "In6.Cu")
		(net "M_G_CPU0_SA_CB<2>")
	)
	(segment
		(start 420.273988 -269.142464)
		(end 419.463474 -268.33195)
		(width 0.18288)
		(layer "In6.Cu")
		(net "M_G_CPU0_SA_CB<2>")
	)
	(segment
		(start 435.15407 -277.640796)
		(end 435.002432 -277.792434)
		(width 0.18288)
		(layer "In6.Cu")
		(net "M_G_CPU0_SA_CB<2>")
	)
	(segment
		(start 388.27329 -264.171684)
		(end 387.679438 -264.765536)
		(width 0.088646)
		(layer "In6.Cu")
		(net "M_G_CPU0_SA_CB<2>")
	)
	(segment
		(start 430.675288 -275.598128)
		(end 429.967644 -275.598128)
		(width 0.18288)
		(layer "In6.Cu")
		(net "M_G_CPU0_SA_CB<2>")
	)
	(segment
		(start 378.21108 -264.8204)
		(end 378.203714 -264.824718)
		(width 0.088646)
		(layer "In6.Cu")
		(net "M_G_CPU0_SA_CB<2>")
	)
	(segment
		(start 379.143514 -264.824718)
		(end 379.138942 -264.827512)
		(width 0.088646)
		(layer "In6.Cu")
		(net "M_G_CPU0_SA_CB<2>")
	)
	(segment
		(start 414.358074 -268.088618)
		(end 412.678118 -268.088618)
		(width 0.18288)
		(layer "In6.Cu")
		(net "M_G_CPU0_SA_CB<2>")
	)
	(arc
		(start 376.608594 -264.749026)
		(mid 376.341866 -264.683064)
		(end 376.136662 -264.50036)
		(width 0.088646)
		(layer "In6.Cu")
		(net "M_G_CPU0_SA_CB<2>")
	)
	(arc
		(start 387.679438 -264.765536)
		(mid 387.642388 -264.797682)
		(end 387.60146 -264.824718)
		(width 0.088646)
		(layer "In6.Cu")
		(net "M_G_CPU0_SA_CB<2>")
	)
	(arc
		(start 378.199142 -264.827512)
		(mid 378.013728 -264.875024)
		(end 377.829064 -264.824718)
		(width 0.088646)
		(layer "In6.Cu")
		(net "M_G_CPU0_SA_CB<2>")
	)
	(arc
		(start 385.332732 -264.816082)
		(mid 385.056257 -264.748762)
		(end 384.78206 -264.824718)
		(width 0.088646)
		(layer "In6.Cu")
		(net "M_G_CPU0_SA_CB<2>")
	)
	(arc
		(start 381.958342 -264.827512)
		(mid 381.772928 -264.875024)
		(end 381.588264 -264.824718)
		(width 0.088646)
		(layer "In6.Cu")
		(net "M_G_CPU0_SA_CB<2>")
	)
	(arc
		(start 384.78206 -264.824718)
		(mid 384.594862 -264.874861)
		(end 384.407664 -264.824718)
		(width 0.088646)
		(layer "In6.Cu")
		(net "M_G_CPU0_SA_CB<2>")
	)
	(arc
		(start 380.648464 -264.824718)
		(mid 380.370141 -264.748959)
		(end 380.09068 -264.8204)
		(width 0.088646)
		(layer "In6.Cu")
		(net "M_G_CPU0_SA_CB<2>")
	)
	(arc
		(start 386.66166 -264.824718)
		(mid 386.474462 -264.874861)
		(end 386.287264 -264.824718)
		(width 0.088646)
		(layer "In6.Cu")
		(net "M_G_CPU0_SA_CB<2>")
	)
	(arc
		(start 385.72186 -264.824718)
		(mid 385.534662 -264.874861)
		(end 385.347464 -264.824718)
		(width 0.088646)
		(layer "In6.Cu")
		(net "M_G_CPU0_SA_CB<2>")
	)
	(arc
		(start 377.259342 -264.827512)
		(mid 377.073928 -264.875024)
		(end 376.889264 -264.824718)
		(width 0.088646)
		(layer "In6.Cu")
		(net "M_G_CPU0_SA_CB<2>")
	)
	(arc
		(start 382.528064 -264.824718)
		(mid 382.249741 -264.748959)
		(end 381.97028 -264.8204)
		(width 0.088646)
		(layer "In6.Cu")
		(net "M_G_CPU0_SA_CB<2>")
	)
	(arc
		(start 378.768864 -264.824718)
		(mid 378.490541 -264.748959)
		(end 378.21108 -264.8204)
		(width 0.088646)
		(layer "In6.Cu")
		(net "M_G_CPU0_SA_CB<2>")
	)
	(arc
		(start 380.078742 -264.827512)
		(mid 379.893328 -264.875024)
		(end 379.708664 -264.824718)
		(width 0.088646)
		(layer "In6.Cu")
		(net "M_G_CPU0_SA_CB<2>")
	)
	(arc
		(start 387.60146 -264.824718)
		(mid 387.414262 -264.874861)
		(end 387.227064 -264.824718)
		(width 0.088646)
		(layer "In6.Cu")
		(net "M_G_CPU0_SA_CB<2>")
	)
	(arc
		(start 379.708664 -264.824718)
		(mid 379.430341 -264.748959)
		(end 379.15088 -264.8204)
		(width 0.088646)
		(layer "In6.Cu")
		(net "M_G_CPU0_SA_CB<2>")
	)
	(arc
		(start 379.138942 -264.827512)
		(mid 378.953528 -264.875024)
		(end 378.768864 -264.824718)
		(width 0.088646)
		(layer "In6.Cu")
		(net "M_G_CPU0_SA_CB<2>")
	)
	(arc
		(start 376.889264 -264.824718)
		(mid 376.753876 -264.768539)
		(end 376.608594 -264.749026)
		(width 0.088646)
		(layer "In6.Cu")
		(net "M_G_CPU0_SA_CB<2>")
	)
	(arc
		(start 381.588264 -264.824718)
		(mid 381.309941 -264.748959)
		(end 381.03048 -264.8204)
		(width 0.088646)
		(layer "In6.Cu")
		(net "M_G_CPU0_SA_CB<2>")
	)
	(arc
		(start 382.90246 -264.824718)
		(mid 382.715262 -264.874861)
		(end 382.528064 -264.824718)
		(width 0.088646)
		(layer "In6.Cu")
		(net "M_G_CPU0_SA_CB<2>")
	)
	(arc
		(start 386.272532 -264.816082)
		(mid 385.996057 -264.748762)
		(end 385.72186 -264.824718)
		(width 0.088646)
		(layer "In6.Cu")
		(net "M_G_CPU0_SA_CB<2>")
	)
	(arc
		(start 387.212332 -264.816082)
		(mid 386.935857 -264.748762)
		(end 386.66166 -264.824718)
		(width 0.088646)
		(layer "In6.Cu")
		(net "M_G_CPU0_SA_CB<2>")
	)
	(arc
		(start 381.018542 -264.827512)
		(mid 380.833128 -264.875024)
		(end 380.648464 -264.824718)
		(width 0.088646)
		(layer "In6.Cu")
		(net "M_G_CPU0_SA_CB<2>")
	)
	(arc
		(start 383.453132 -264.816082)
		(mid 383.176657 -264.748762)
		(end 382.90246 -264.824718)
		(width 0.088646)
		(layer "In6.Cu")
		(net "M_G_CPU0_SA_CB<2>")
	)
	(arc
		(start 383.84226 -264.824718)
		(mid 383.655062 -264.874861)
		(end 383.467864 -264.824718)
		(width 0.088646)
		(layer "In6.Cu")
		(net "M_G_CPU0_SA_CB<2>")
	)
	(arc
		(start 384.392932 -264.816082)
		(mid 384.116457 -264.748762)
		(end 383.84226 -264.824718)
		(width 0.088646)
		(layer "In6.Cu")
		(net "M_G_CPU0_SA_CB<2>")
	)
	(arc
		(start 377.829064 -264.824718)
		(mid 377.550741 -264.748959)
		(end 377.27128 -264.8204)
		(width 0.088646)
		(layer "In6.Cu")
		(net "M_G_CPU0_SA_CB<2>")
	)
	(segment
		(start 439.361072 -276.909784)
		(end 439.361072 -277.277322)
		(width 0.20066)
		(layer "F.Cu")
		(net "M_G_CPU0_SA_CB<1>")
	)
	(segment
		(start 436.928514 -277.216616)
		(end 435.823614 -277.216616)
		(width 0.20066)
		(layer "F.Cu")
		(net "M_G_CPU0_SA_CB<1>")
	)
	(segment
		(start 442.416184 -276.791674)
		(end 442.21781 -276.791674)
		(width 0.20066)
		(layer "F.Cu")
		(net "M_G_CPU0_SA_CB<1>")
	)
	(segment
		(start 438.697878 -277.465282)
		(end 438.449212 -277.216616)
		(width 0.20066)
		(layer "F.Cu")
		(net "M_G_CPU0_SA_CB<1>")
	)
	(segment
		(start 442.181234 -276.791674)
		(end 439.87085 -276.791674)
		(width 0.1016)
		(layer "F.Cu")
		(net "M_G_CPU0_SA_CB<1>")
	)
	(segment
		(start 444.47206 -277.21687)
		(end 442.84138 -277.21687)
		(width 0.20066)
		(layer "F.Cu")
		(net "M_G_CPU0_SA_CB<1>")
	)
	(segment
		(start 442.84138 -277.21687)
		(end 442.416184 -276.791674)
		(width 0.20066)
		(layer "F.Cu")
		(net "M_G_CPU0_SA_CB<1>")
	)
	(segment
		(start 374.726962 -263.68629)
		(end 374.727216 -263.686544)
		(width 0.20066)
		(layer "F.Cu")
		(net "M_G_CPU0_SA_CB<1>")
	)
	(segment
		(start 444.472314 -277.216616)
		(end 444.47206 -277.21687)
		(width 0.20066)
		(layer "F.Cu")
		(net "M_G_CPU0_SA_CB<1>")
	)
	(segment
		(start 438.449212 -277.216616)
		(end 436.928514 -277.216616)
		(width 0.20066)
		(layer "F.Cu")
		(net "M_G_CPU0_SA_CB<1>")
	)
	(segment
		(start 442.21781 -276.791674)
		(end 442.181234 -276.791674)
		(width 0.101854)
		(layer "F.Cu")
		(net "M_G_CPU0_SA_CB<1>")
	)
	(segment
		(start 439.173112 -277.465282)
		(end 438.697878 -277.465282)
		(width 0.20066)
		(layer "F.Cu")
		(net "M_G_CPU0_SA_CB<1>")
	)
	(segment
		(start 439.479182 -276.791674)
		(end 439.361072 -276.909784)
		(width 0.20066)
		(layer "F.Cu")
		(net "M_G_CPU0_SA_CB<1>")
	)
	(segment
		(start 374.726962 -263.150604)
		(end 374.726962 -263.68629)
		(width 0.20066)
		(layer "F.Cu")
		(net "M_G_CPU0_SA_CB<1>")
	)
	(segment
		(start 439.87085 -276.791674)
		(end 439.726324 -276.791674)
		(width 0.101854)
		(layer "F.Cu")
		(net "M_G_CPU0_SA_CB<1>")
	)
	(segment
		(start 439.361072 -277.277322)
		(end 439.173112 -277.465282)
		(width 0.20066)
		(layer "F.Cu")
		(net "M_G_CPU0_SA_CB<1>")
	)
	(segment
		(start 439.726324 -276.791674)
		(end 439.479182 -276.791674)
		(width 0.20066)
		(layer "F.Cu")
		(net "M_G_CPU0_SA_CB<1>")
	)
	(segment
		(start 423.344594 -269.276576)
		(end 422.373044 -269.276576)
		(width 0.18288)
		(layer "In6.Cu")
		(net "M_G_CPU0_SA_CB<1>")
	)
	(segment
		(start 412.525464 -267.541502)
		(end 412.105348 -267.121386)
		(width 0.18288)
		(layer "In6.Cu")
		(net "M_G_CPU0_SA_CB<1>")
	)
	(segment
		(start 410.525976 -267.546836)
		(end 410.525976 -267.304266)
		(width 0.18288)
		(layer "In6.Cu")
		(net "M_G_CPU0_SA_CB<1>")
	)
	(segment
		(start 427.918118 -270.956024)
		(end 427.735238 -270.773144)
		(width 0.18288)
		(layer "In6.Cu")
		(net "M_G_CPU0_SA_CB<1>")
	)
	(segment
		(start 418.066982 -267.751052)
		(end 417.625022 -267.309092)
		(width 0.18288)
		(layer "In6.Cu")
		(net "M_G_CPU0_SA_CB<1>")
	)
	(segment
		(start 426.302424 -269.13205)
		(end 423.48912 -269.13205)
		(width 0.18288)
		(layer "In6.Cu")
		(net "M_G_CPU0_SA_CB<1>")
	)
	(segment
		(start 423.48912 -269.13205)
		(end 423.344594 -269.276576)
		(width 0.18288)
		(layer "In6.Cu")
		(net "M_G_CPU0_SA_CB<1>")
	)
	(segment
		(start 421.677084 -268.580616)
		(end 421.677084 -268.164564)
		(width 0.18288)
		(layer "In6.Cu")
		(net "M_G_CPU0_SA_CB<1>")
	)
	(segment
		(start 433.236116 -276.077426)
		(end 431.956718 -276.077426)
		(width 0.18288)
		(layer "In6.Cu")
		(net "M_G_CPU0_SA_CB<1>")
	)
	(segment
		(start 378.209556 -264.179304)
		(end 378.203714 -264.175748)
		(width 0.088646)
		(layer "In6.Cu")
		(net "M_G_CPU0_SA_CB<1>")
	)
	(segment
		(start 427.229016 -268.829536)
		(end 426.604938 -268.829536)
		(width 0.18288)
		(layer "In6.Cu")
		(net "M_G_CPU0_SA_CB<1>")
	)
	(segment
		(start 428.709328 -271.466564)
		(end 428.709328 -271.138904)
		(width 0.18288)
		(layer "In6.Cu")
		(net "M_G_CPU0_SA_CB<1>")
	)
	(segment
		(start 427.918118 -271.649444)
		(end 428.526448 -271.649444)
		(width 0.18288)
		(layer "In6.Cu")
		(net "M_G_CPU0_SA_CB<1>")
	)
	(segment
		(start 387.778244 -264.125456)
		(end 387.414262 -264.125456)
		(width 0.088646)
		(layer "In6.Cu")
		(net "M_G_CPU0_SA_CB<1>")
	)
	(segment
		(start 382.528064 -264.176002)
		(end 382.513332 -264.184638)
		(width 0.088646)
		(layer "In6.Cu")
		(net "M_G_CPU0_SA_CB<1>")
	)
	(segment
		(start 411.219396 -267.546836)
		(end 411.036516 -267.729716)
		(width 0.18288)
		(layer "In6.Cu")
		(net "M_G_CPU0_SA_CB<1>")
	)
	(segment
		(start 421.677084 -268.164564)
		(end 421.842946 -267.998702)
		(width 0.18288)
		(layer "In6.Cu")
		(net "M_G_CPU0_SA_CB<1>")
	)
	(segment
		(start 427.918118 -273.333972)
		(end 428.54118 -273.333972)
		(width 0.18288)
		(layer "In6.Cu")
		(net "M_G_CPU0_SA_CB<1>")
	)
	(segment
		(start 377.263914 -264.175748)
		(end 377.258072 -264.172446)
		(width 0.088646)
		(layer "In6.Cu")
		(net "M_G_CPU0_SA_CB<1>")
	)
	(segment
		(start 416.353244 -267.309092)
		(end 415.529014 -266.484862)
		(width 0.18288)
		(layer "In6.Cu")
		(net "M_G_CPU0_SA_CB<1>")
	)
	(segment
		(start 427.735238 -272.457672)
		(end 427.735238 -271.832324)
		(width 0.18288)
		(layer "In6.Cu")
		(net "M_G_CPU0_SA_CB<1>")
	)
	(segment
		(start 415.529014 -266.484862)
		(end 414.41497 -266.484862)
		(width 0.18288)
		(layer "In6.Cu")
		(net "M_G_CPU0_SA_CB<1>")
	)
	(segment
		(start 421.842946 -267.674598)
		(end 421.609774 -267.441426)
		(width 0.18288)
		(layer "In6.Cu")
		(net "M_G_CPU0_SA_CB<1>")
	)
	(segment
		(start 427.735238 -274.210526)
		(end 427.735238 -273.516852)
		(width 0.18288)
		(layer "In6.Cu")
		(net "M_G_CPU0_SA_CB<1>")
	)
	(segment
		(start 410.343096 -267.121386)
		(end 409.076144 -267.121386)
		(width 0.18288)
		(layer "In6.Cu")
		(net "M_G_CPU0_SA_CB<1>")
	)
	(segment
		(start 375.962672 -264.083292)
		(end 375.483882 -264.083292)
		(width 0.088646)
		(layer "In6.Cu")
		(net "M_G_CPU0_SA_CB<1>")
	)
	(segment
		(start 390.504172 -263.672066)
		(end 388.535672 -263.672066)
		(width 0.18288)
		(layer "In6.Cu")
		(net "M_G_CPU0_SA_CB<1>")
	)
	(segment
		(start 408.541474 -267.656056)
		(end 407.713942 -267.656056)
		(width 0.18288)
		(layer "In6.Cu")
		(net "M_G_CPU0_SA_CB<1>")
	)
	(segment
		(start 427.735238 -270.773144)
		(end 427.735238 -269.335758)
		(width 0.18288)
		(layer "In6.Cu")
		(net "M_G_CPU0_SA_CB<1>")
	)
	(segment
		(start 380.083314 -264.175748)
		(end 380.077472 -264.172446)
		(width 0.088646)
		(layer "In6.Cu")
		(net "M_G_CPU0_SA_CB<1>")
	)
	(segment
		(start 411.219396 -267.304266)
		(end 411.219396 -267.546836)
		(width 0.18288)
		(layer "In6.Cu")
		(net "M_G_CPU0_SA_CB<1>")
	)
	(segment
		(start 378.203714 -264.175748)
		(end 378.197872 -264.172446)
		(width 0.088646)
		(layer "In6.Cu")
		(net "M_G_CPU0_SA_CB<1>")
	)
	(segment
		(start 422.373044 -269.276576)
		(end 421.677084 -268.580616)
		(width 0.18288)
		(layer "In6.Cu")
		(net "M_G_CPU0_SA_CB<1>")
	)
	(segment
		(start 410.525976 -267.304266)
		(end 410.343096 -267.121386)
		(width 0.18288)
		(layer "In6.Cu")
		(net "M_G_CPU0_SA_CB<1>")
	)
	(segment
		(start 411.036516 -267.729716)
		(end 410.708856 -267.729716)
		(width 0.18288)
		(layer "In6.Cu")
		(net "M_G_CPU0_SA_CB<1>")
	)
	(segment
		(start 428.54118 -272.640552)
		(end 427.918118 -272.640552)
		(width 0.18288)
		(layer "In6.Cu")
		(net "M_G_CPU0_SA_CB<1>")
	)
	(segment
		(start 427.735238 -273.516852)
		(end 427.918118 -273.333972)
		(width 0.18288)
		(layer "In6.Cu")
		(net "M_G_CPU0_SA_CB<1>")
	)
	(segment
		(start 428.526448 -270.956024)
		(end 427.918118 -270.956024)
		(width 0.18288)
		(layer "In6.Cu")
		(net "M_G_CPU0_SA_CB<1>")
	)
	(segment
		(start 428.72406 -273.151092)
		(end 428.72406 -272.823432)
		(width 0.18288)
		(layer "In6.Cu")
		(net "M_G_CPU0_SA_CB<1>")
	)
	(segment
		(start 431.956718 -276.077426)
		(end 430.84623 -274.966938)
		(width 0.18288)
		(layer "In6.Cu")
		(net "M_G_CPU0_SA_CB<1>")
	)
	(segment
		(start 428.72406 -272.823432)
		(end 428.54118 -272.640552)
		(width 0.18288)
		(layer "In6.Cu")
		(net "M_G_CPU0_SA_CB<1>")
	)
	(segment
		(start 418.746686 -267.751052)
		(end 418.066982 -267.751052)
		(width 0.18288)
		(layer "In6.Cu")
		(net "M_G_CPU0_SA_CB<1>")
	)
	(segment
		(start 411.402276 -267.121386)
		(end 411.219396 -267.304266)
		(width 0.18288)
		(layer "In6.Cu")
		(net "M_G_CPU0_SA_CB<1>")
	)
	(segment
		(start 379.149356 -264.179304)
		(end 379.143514 -264.175748)
		(width 0.088646)
		(layer "In6.Cu")
		(net "M_G_CPU0_SA_CB<1>")
	)
	(segment
		(start 388.231634 -263.672066)
		(end 387.778244 -264.125456)
		(width 0.088646)
		(layer "In6.Cu")
		(net "M_G_CPU0_SA_CB<1>")
	)
	(segment
		(start 419.056312 -267.441426)
		(end 418.746686 -267.751052)
		(width 0.18288)
		(layer "In6.Cu")
		(net "M_G_CPU0_SA_CB<1>")
	)
	(segment
		(start 421.609774 -267.441426)
		(end 419.056312 -267.441426)
		(width 0.18288)
		(layer "In6.Cu")
		(net "M_G_CPU0_SA_CB<1>")
	)
	(segment
		(start 403.069044 -264.16)
		(end 392.957558 -264.16)
		(width 0.18288)
		(layer "In6.Cu")
		(net "M_G_CPU0_SA_CB<1>")
	)
	(segment
		(start 410.708856 -267.729716)
		(end 410.525976 -267.546836)
		(width 0.18288)
		(layer "In6.Cu")
		(net "M_G_CPU0_SA_CB<1>")
	)
	(segment
		(start 387.227064 -264.176002)
		(end 387.212332 -264.184638)
		(width 0.088646)
		(layer "In6.Cu")
		(net "M_G_CPU0_SA_CB<1>")
	)
	(segment
		(start 392.957558 -264.16)
		(end 390.504172 -263.672066)
		(width 0.18288)
		(layer "In6.Cu")
		(net "M_G_CPU0_SA_CB<1>")
	)
	(segment
		(start 430.84623 -274.966938)
		(end 428.49165 -274.966938)
		(width 0.18288)
		(layer "In6.Cu")
		(net "M_G_CPU0_SA_CB<1>")
	)
	(segment
		(start 426.604938 -268.829536)
		(end 426.302424 -269.13205)
		(width 0.18288)
		(layer "In6.Cu")
		(net "M_G_CPU0_SA_CB<1>")
	)
	(segment
		(start 386.287264 -264.176002)
		(end 386.272532 -264.184638)
		(width 0.088646)
		(layer "In6.Cu")
		(net "M_G_CPU0_SA_CB<1>")
	)
	(segment
		(start 428.709328 -271.138904)
		(end 428.526448 -270.956024)
		(width 0.18288)
		(layer "In6.Cu")
		(net "M_G_CPU0_SA_CB<1>")
	)
	(segment
		(start 421.842946 -267.998702)
		(end 421.842946 -267.674598)
		(width 0.18288)
		(layer "In6.Cu")
		(net "M_G_CPU0_SA_CB<1>")
	)
	(segment
		(start 381.588264 -264.176002)
		(end 381.588264 -264.175748)
		(width 0.088646)
		(layer "In6.Cu")
		(net "M_G_CPU0_SA_CB<1>")
	)
	(segment
		(start 388.535672 -263.672066)
		(end 388.231634 -263.672066)
		(width 0.088646)
		(layer "In6.Cu")
		(net "M_G_CPU0_SA_CB<1>")
	)
	(segment
		(start 379.143514 -264.175748)
		(end 379.137672 -264.172446)
		(width 0.088646)
		(layer "In6.Cu")
		(net "M_G_CPU0_SA_CB<1>")
	)
	(segment
		(start 412.105348 -267.121386)
		(end 411.402276 -267.121386)
		(width 0.18288)
		(layer "In6.Cu")
		(net "M_G_CPU0_SA_CB<1>")
	)
	(segment
		(start 380.089156 -264.179304)
		(end 380.083314 -264.175748)
		(width 0.088646)
		(layer "In6.Cu")
		(net "M_G_CPU0_SA_CB<1>")
	)
	(segment
		(start 428.526448 -271.649444)
		(end 428.709328 -271.466564)
		(width 0.18288)
		(layer "In6.Cu")
		(net "M_G_CPU0_SA_CB<1>")
	)
	(segment
		(start 427.735238 -269.335758)
		(end 427.229016 -268.829536)
		(width 0.18288)
		(layer "In6.Cu")
		(net "M_G_CPU0_SA_CB<1>")
	)
	(segment
		(start 427.735238 -271.832324)
		(end 427.918118 -271.649444)
		(width 0.18288)
		(layer "In6.Cu")
		(net "M_G_CPU0_SA_CB<1>")
	)
	(segment
		(start 405.324056 -266.415012)
		(end 403.069044 -264.16)
		(width 0.18288)
		(layer "In6.Cu")
		(net "M_G_CPU0_SA_CB<1>")
	)
	(segment
		(start 377.269756 -264.179304)
		(end 377.263914 -264.175748)
		(width 0.088646)
		(layer "In6.Cu")
		(net "M_G_CPU0_SA_CB<1>")
	)
	(segment
		(start 435.294024 -276.687026)
		(end 433.845716 -276.687026)
		(width 0.18288)
		(layer "In6.Cu")
		(net "M_G_CPU0_SA_CB<1>")
	)
	(segment
		(start 435.823614 -277.216616)
		(end 435.294024 -276.687026)
		(width 0.18288)
		(layer "In6.Cu")
		(net "M_G_CPU0_SA_CB<1>")
	)
	(segment
		(start 428.49165 -274.966938)
		(end 427.735238 -274.210526)
		(width 0.18288)
		(layer "In6.Cu")
		(net "M_G_CPU0_SA_CB<1>")
	)
	(segment
		(start 427.918118 -272.640552)
		(end 427.735238 -272.457672)
		(width 0.18288)
		(layer "In6.Cu")
		(net "M_G_CPU0_SA_CB<1>")
	)
	(segment
		(start 409.076144 -267.121386)
		(end 408.541474 -267.656056)
		(width 0.18288)
		(layer "In6.Cu")
		(net "M_G_CPU0_SA_CB<1>")
	)
	(segment
		(start 413.35833 -267.541502)
		(end 412.525464 -267.541502)
		(width 0.18288)
		(layer "In6.Cu")
		(net "M_G_CPU0_SA_CB<1>")
	)
	(segment
		(start 417.625022 -267.309092)
		(end 416.353244 -267.309092)
		(width 0.18288)
		(layer "In6.Cu")
		(net "M_G_CPU0_SA_CB<1>")
	)
	(segment
		(start 407.713942 -267.656056)
		(end 406.472898 -266.415012)
		(width 0.18288)
		(layer "In6.Cu")
		(net "M_G_CPU0_SA_CB<1>")
	)
	(segment
		(start 381.023114 -264.175748)
		(end 381.017272 -264.172446)
		(width 0.088646)
		(layer "In6.Cu")
		(net "M_G_CPU0_SA_CB<1>")
	)
	(segment
		(start 414.41497 -266.484862)
		(end 413.35833 -267.541502)
		(width 0.18288)
		(layer "In6.Cu")
		(net "M_G_CPU0_SA_CB<1>")
	)
	(segment
		(start 428.54118 -273.333972)
		(end 428.72406 -273.151092)
		(width 0.18288)
		(layer "In6.Cu")
		(net "M_G_CPU0_SA_CB<1>")
	)
	(segment
		(start 406.472898 -266.415012)
		(end 405.324056 -266.415012)
		(width 0.18288)
		(layer "In6.Cu")
		(net "M_G_CPU0_SA_CB<1>")
	)
	(segment
		(start 381.028956 -264.179304)
		(end 381.023114 -264.175748)
		(width 0.088646)
		(layer "In6.Cu")
		(net "M_G_CPU0_SA_CB<1>")
	)
	(segment
		(start 433.845716 -276.687026)
		(end 433.236116 -276.077426)
		(width 0.18288)
		(layer "In6.Cu")
		(net "M_G_CPU0_SA_CB<1>")
	)
	(arc
		(start 379.137672 -264.172446)
		(mid 378.952817 -264.125528)
		(end 378.768864 -264.175748)
		(width 0.088646)
		(layer "In6.Cu")
		(net "M_G_CPU0_SA_CB<1>")
	)
	(arc
		(start 381.588264 -264.175748)
		(mid 381.30909 -264.251513)
		(end 381.028956 -264.179304)
		(width 0.088646)
		(layer "In6.Cu")
		(net "M_G_CPU0_SA_CB<1>")
	)
	(arc
		(start 384.407664 -264.176002)
		(mid 384.124962 -264.251778)
		(end 383.84226 -264.176002)
		(width 0.088646)
		(layer "In6.Cu")
		(net "M_G_CPU0_SA_CB<1>")
	)
	(arc
		(start 382.90246 -264.176002)
		(mid 382.715262 -264.125859)
		(end 382.528064 -264.176002)
		(width 0.088646)
		(layer "In6.Cu")
		(net "M_G_CPU0_SA_CB<1>")
	)
	(arc
		(start 386.66166 -264.176002)
		(mid 386.474462 -264.125859)
		(end 386.287264 -264.176002)
		(width 0.088646)
		(layer "In6.Cu")
		(net "M_G_CPU0_SA_CB<1>")
	)
	(arc
		(start 387.212332 -264.184638)
		(mid 386.935857 -264.251958)
		(end 386.66166 -264.176002)
		(width 0.088646)
		(layer "In6.Cu")
		(net "M_G_CPU0_SA_CB<1>")
	)
	(arc
		(start 385.72186 -264.176002)
		(mid 385.534662 -264.125859)
		(end 385.347464 -264.176002)
		(width 0.088646)
		(layer "In6.Cu")
		(net "M_G_CPU0_SA_CB<1>")
	)
	(arc
		(start 387.414262 -264.125456)
		(mid 387.317339 -264.138414)
		(end 387.227064 -264.176002)
		(width 0.088646)
		(layer "In6.Cu")
		(net "M_G_CPU0_SA_CB<1>")
	)
	(arc
		(start 383.84226 -264.176002)
		(mid 383.655062 -264.125859)
		(end 383.467864 -264.176002)
		(width 0.088646)
		(layer "In6.Cu")
		(net "M_G_CPU0_SA_CB<1>")
	)
	(arc
		(start 381.96266 -264.176002)
		(mid 381.775462 -264.125859)
		(end 381.588264 -264.176002)
		(width 0.088646)
		(layer "In6.Cu")
		(net "M_G_CPU0_SA_CB<1>")
	)
	(arc
		(start 379.708664 -264.175748)
		(mid 379.42949 -264.251513)
		(end 379.149356 -264.179304)
		(width 0.088646)
		(layer "In6.Cu")
		(net "M_G_CPU0_SA_CB<1>")
	)
	(arc
		(start 385.347464 -264.176002)
		(mid 385.064762 -264.251778)
		(end 384.78206 -264.176002)
		(width 0.088646)
		(layer "In6.Cu")
		(net "M_G_CPU0_SA_CB<1>")
	)
	(arc
		(start 376.889264 -264.175748)
		(mid 376.61009 -264.251513)
		(end 376.329956 -264.179304)
		(width 0.088646)
		(layer "In6.Cu")
		(net "M_G_CPU0_SA_CB<1>")
	)
	(arc
		(start 380.648464 -264.175748)
		(mid 380.36929 -264.251513)
		(end 380.089156 -264.179304)
		(width 0.088646)
		(layer "In6.Cu")
		(net "M_G_CPU0_SA_CB<1>")
	)
	(arc
		(start 386.272532 -264.184638)
		(mid 385.996057 -264.251958)
		(end 385.72186 -264.176002)
		(width 0.088646)
		(layer "In6.Cu")
		(net "M_G_CPU0_SA_CB<1>")
	)
	(arc
		(start 378.768864 -264.175748)
		(mid 378.48969 -264.251513)
		(end 378.209556 -264.179304)
		(width 0.088646)
		(layer "In6.Cu")
		(net "M_G_CPU0_SA_CB<1>")
	)
	(arc
		(start 383.467864 -264.176002)
		(mid 383.185162 -264.251778)
		(end 382.90246 -264.176002)
		(width 0.088646)
		(layer "In6.Cu")
		(net "M_G_CPU0_SA_CB<1>")
	)
	(arc
		(start 377.258072 -264.172446)
		(mid 377.073217 -264.125528)
		(end 376.889264 -264.175748)
		(width 0.088646)
		(layer "In6.Cu")
		(net "M_G_CPU0_SA_CB<1>")
	)
	(arc
		(start 384.78206 -264.176002)
		(mid 384.594862 -264.125859)
		(end 384.407664 -264.176002)
		(width 0.088646)
		(layer "In6.Cu")
		(net "M_G_CPU0_SA_CB<1>")
	)
	(arc
		(start 380.077472 -264.172446)
		(mid 379.892617 -264.125528)
		(end 379.708664 -264.175748)
		(width 0.088646)
		(layer "In6.Cu")
		(net "M_G_CPU0_SA_CB<1>")
	)
	(arc
		(start 376.329956 -264.179304)
		(mid 376.15248 -264.107721)
		(end 375.962672 -264.083292)
		(width 0.088646)
		(layer "In6.Cu")
		(net "M_G_CPU0_SA_CB<1>")
	)
	(arc
		(start 378.197872 -264.172446)
		(mid 378.013017 -264.125528)
		(end 377.829064 -264.175748)
		(width 0.088646)
		(layer "In6.Cu")
		(net "M_G_CPU0_SA_CB<1>")
	)
	(arc
		(start 377.829064 -264.175748)
		(mid 377.54989 -264.251513)
		(end 377.269756 -264.179304)
		(width 0.088646)
		(layer "In6.Cu")
		(net "M_G_CPU0_SA_CB<1>")
	)
	(arc
		(start 381.017272 -264.172446)
		(mid 380.832417 -264.125528)
		(end 380.648464 -264.175748)
		(width 0.088646)
		(layer "In6.Cu")
		(net "M_G_CPU0_SA_CB<1>")
	)
	(arc
		(start 375.483882 -264.083292)
		(mid 375.056689 -263.978095)
		(end 374.727216 -263.686544)
		(width 0.088646)
		(layer "In6.Cu")
		(net "M_G_CPU0_SA_CB<1>")
	)
	(arc
		(start 382.513332 -264.184638)
		(mid 382.236857 -264.251958)
		(end 381.96266 -264.176002)
		(width 0.088646)
		(layer "In6.Cu")
		(net "M_G_CPU0_SA_CB<1>")
	)
	(segment
		(start 442.21781 -278.491696)
		(end 442.181234 -278.491696)
		(width 0.101854)
		(layer "F.Cu")
		(net "M_G_CPU0_SA_CB<0>")
	)
	(segment
		(start 444.472314 -278.916638)
		(end 444.47206 -278.916892)
		(width 0.20066)
		(layer "F.Cu")
		(net "M_G_CPU0_SA_CB<0>")
	)
	(segment
		(start 438.697878 -279.165304)
		(end 438.449212 -278.916638)
		(width 0.20066)
		(layer "F.Cu")
		(net "M_G_CPU0_SA_CB<0>")
	)
	(segment
		(start 439.479182 -278.491696)
		(end 439.361072 -278.609806)
		(width 0.20066)
		(layer "F.Cu")
		(net "M_G_CPU0_SA_CB<0>")
	)
	(segment
		(start 442.181234 -278.491696)
		(end 439.87085 -278.491696)
		(width 0.1016)
		(layer "F.Cu")
		(net "M_G_CPU0_SA_CB<0>")
	)
	(segment
		(start 439.361072 -278.609806)
		(end 439.361072 -278.977344)
		(width 0.20066)
		(layer "F.Cu")
		(net "M_G_CPU0_SA_CB<0>")
	)
	(segment
		(start 375.197116 -263.96442)
		(end 375.197116 -264.500106)
		(width 0.20066)
		(layer "F.Cu")
		(net "M_G_CPU0_SA_CB<0>")
	)
	(segment
		(start 439.173112 -279.165304)
		(end 438.697878 -279.165304)
		(width 0.20066)
		(layer "F.Cu")
		(net "M_G_CPU0_SA_CB<0>")
	)
	(segment
		(start 442.84138 -278.916892)
		(end 442.416184 -278.491696)
		(width 0.20066)
		(layer "F.Cu")
		(net "M_G_CPU0_SA_CB<0>")
	)
	(segment
		(start 439.726324 -278.491696)
		(end 439.479182 -278.491696)
		(width 0.20066)
		(layer "F.Cu")
		(net "M_G_CPU0_SA_CB<0>")
	)
	(segment
		(start 442.416184 -278.491696)
		(end 442.21781 -278.491696)
		(width 0.20066)
		(layer "F.Cu")
		(net "M_G_CPU0_SA_CB<0>")
	)
	(segment
		(start 438.449212 -278.916638)
		(end 436.928514 -278.916638)
		(width 0.20066)
		(layer "F.Cu")
		(net "M_G_CPU0_SA_CB<0>")
	)
	(segment
		(start 375.197116 -264.500106)
		(end 375.196862 -264.50036)
		(width 0.20066)
		(layer "F.Cu")
		(net "M_G_CPU0_SA_CB<0>")
	)
	(segment
		(start 439.87085 -278.491696)
		(end 439.726324 -278.491696)
		(width 0.101854)
		(layer "F.Cu")
		(net "M_G_CPU0_SA_CB<0>")
	)
	(segment
		(start 439.361072 -278.977344)
		(end 439.173112 -279.165304)
		(width 0.20066)
		(layer "F.Cu")
		(net "M_G_CPU0_SA_CB<0>")
	)
	(segment
		(start 436.928514 -278.916638)
		(end 435.823614 -278.916638)
		(width 0.20066)
		(layer "F.Cu")
		(net "M_G_CPU0_SA_CB<0>")
	)
	(segment
		(start 444.47206 -278.916892)
		(end 442.84138 -278.916892)
		(width 0.20066)
		(layer "F.Cu")
		(net "M_G_CPU0_SA_CB<0>")
	)
	(segment
		(start 379.243336 -264.987024)
		(end 379.238764 -264.989818)
		(width 0.088646)
		(layer "In6.Cu")
		(net "M_G_CPU0_SA_CB<0>")
	)
	(segment
		(start 384.327146 -264.998454)
		(end 384.312414 -264.989818)
		(width 0.088646)
		(layer "In6.Cu")
		(net "M_G_CPU0_SA_CB<0>")
	)
	(segment
		(start 416.50666 -269.140178)
		(end 416.32378 -269.323058)
		(width 0.18288)
		(layer "In6.Cu")
		(net "M_G_CPU0_SA_CB<0>")
	)
	(segment
		(start 387.146546 -264.998454)
		(end 387.131814 -264.989818)
		(width 0.088646)
		(layer "In6.Cu")
		(net "M_G_CPU0_SA_CB<0>")
	)
	(segment
		(start 402.500338 -265.192002)
		(end 393.01674 -265.192002)
		(width 0.18288)
		(layer "In6.Cu")
		(net "M_G_CPU0_SA_CB<0>")
	)
	(segment
		(start 425.326048 -272.298922)
		(end 425.486068 -272.138902)
		(width 0.18288)
		(layer "In6.Cu")
		(net "M_G_CPU0_SA_CB<0>")
	)
	(segment
		(start 405.543766 -268.23543)
		(end 402.500338 -265.192002)
		(width 0.18288)
		(layer "In6.Cu")
		(net "M_G_CPU0_SA_CB<0>")
	)
	(segment
		(start 388.535672 -264.671556)
		(end 388.042658 -264.671556)
		(width 0.088646)
		(layer "In6.Cu")
		(net "M_G_CPU0_SA_CB<0>")
	)
	(segment
		(start 425.486068 -274.219162)
		(end 425.326048 -274.059142)
		(width 0.18288)
		(layer "In6.Cu")
		(net "M_G_CPU0_SA_CB<0>")
	)
	(segment
		(start 408.232864 -269.312644)
		(end 408.232864 -269.808452)
		(width 0.18288)
		(layer "In6.Cu")
		(net "M_G_CPU0_SA_CB<0>")
	)
	(segment
		(start 407.539444 -269.312644)
		(end 407.379424 -269.152624)
		(width 0.18288)
		(layer "In6.Cu")
		(net "M_G_CPU0_SA_CB<0>")
	)
	(segment
		(start 415.81324 -269.860522)
		(end 415.63036 -269.677642)
		(width 0.18288)
		(layer "In6.Cu")
		(net "M_G_CPU0_SA_CB<0>")
	)
	(segment
		(start 425.326048 -273.685762)
		(end 425.486068 -273.525742)
		(width 0.18288)
		(layer "In6.Cu")
		(net "M_G_CPU0_SA_CB<0>")
	)
	(segment
		(start 377.359164 -264.989818)
		(end 377.351798 -264.994136)
		(width 0.088646)
		(layer "In6.Cu")
		(net "M_G_CPU0_SA_CB<0>")
	)
	(segment
		(start 408.40533 -269.140178)
		(end 408.232864 -269.312644)
		(width 0.18288)
		(layer "In6.Cu")
		(net "M_G_CPU0_SA_CB<0>")
	)
	(segment
		(start 425.768008 -272.138902)
		(end 425.928028 -271.978882)
		(width 0.18288)
		(layer "In6.Cu")
		(net "M_G_CPU0_SA_CB<0>")
	)
	(segment
		(start 381.118364 -264.989818)
		(end 381.110998 -264.994136)
		(width 0.088646)
		(layer "In6.Cu")
		(net "M_G_CPU0_SA_CB<0>")
	)
	(segment
		(start 427.862492 -277.08733)
		(end 425.928028 -275.152866)
		(width 0.18288)
		(layer "In6.Cu")
		(net "M_G_CPU0_SA_CB<0>")
	)
	(segment
		(start 376.419364 -264.989818)
		(end 376.411998 -264.994136)
		(width 0.088646)
		(layer "In6.Cu")
		(net "M_G_CPU0_SA_CB<0>")
	)
	(segment
		(start 431.733198 -277.999444)
		(end 431.733198 -277.334218)
		(width 0.18288)
		(layer "In6.Cu")
		(net "M_G_CPU0_SA_CB<0>")
	)
	(segment
		(start 408.072844 -269.968472)
		(end 407.699464 -269.968472)
		(width 0.18288)
		(layer "In6.Cu")
		(net "M_G_CPU0_SA_CB<0>")
	)
	(segment
		(start 420.169086 -270.649192)
		(end 419.986206 -270.832072)
		(width 0.18288)
		(layer "In6.Cu")
		(net "M_G_CPU0_SA_CB<0>")
	)
	(segment
		(start 425.768008 -273.525742)
		(end 425.928028 -273.365722)
		(width 0.18288)
		(layer "In6.Cu")
		(net "M_G_CPU0_SA_CB<0>")
	)
	(segment
		(start 390.399778 -264.671556)
		(end 388.535672 -264.671556)
		(width 0.18288)
		(layer "In6.Cu")
		(net "M_G_CPU0_SA_CB<0>")
	)
	(segment
		(start 406.409906 -268.23543)
		(end 405.543766 -268.23543)
		(width 0.18288)
		(layer "In6.Cu")
		(net "M_G_CPU0_SA_CB<0>")
	)
	(segment
		(start 418.964618 -269.992602)
		(end 418.112194 -269.140178)
		(width 0.18288)
		(layer "In6.Cu")
		(net "M_G_CPU0_SA_CB<0>")
	)
	(segment
		(start 425.928028 -274.379182)
		(end 425.768008 -274.219162)
		(width 0.18288)
		(layer "In6.Cu")
		(net "M_G_CPU0_SA_CB<0>")
	)
	(segment
		(start 380.183136 -264.987024)
		(end 380.178564 -264.989818)
		(width 0.088646)
		(layer "In6.Cu")
		(net "M_G_CPU0_SA_CB<0>")
	)
	(segment
		(start 414.233106 -269.965932)
		(end 414.050226 -270.148812)
		(width 0.18288)
		(layer "In6.Cu")
		(net "M_G_CPU0_SA_CB<0>")
	)
	(segment
		(start 376.423936 -264.987024)
		(end 376.419364 -264.989818)
		(width 0.088646)
		(layer "In6.Cu")
		(net "M_G_CPU0_SA_CB<0>")
	)
	(segment
		(start 382.062736 -264.987024)
		(end 382.058164 -264.989818)
		(width 0.088646)
		(layer "In6.Cu")
		(net "M_G_CPU0_SA_CB<0>")
	)
	(segment
		(start 425.326048 -274.059142)
		(end 425.326048 -273.685762)
		(width 0.18288)
		(layer "In6.Cu")
		(net "M_G_CPU0_SA_CB<0>")
	)
	(segment
		(start 382.058164 -264.989818)
		(end 382.050798 -264.994136)
		(width 0.088646)
		(layer "In6.Cu")
		(net "M_G_CPU0_SA_CB<0>")
	)
	(segment
		(start 425.928028 -275.152866)
		(end 425.928028 -274.379182)
		(width 0.18288)
		(layer "In6.Cu")
		(net "M_G_CPU0_SA_CB<0>")
	)
	(segment
		(start 419.658546 -270.832072)
		(end 419.475666 -270.649192)
		(width 0.18288)
		(layer "In6.Cu")
		(net "M_G_CPU0_SA_CB<0>")
	)
	(segment
		(start 435.823614 -278.916638)
		(end 435.823614 -278.667718)
		(width 0.18288)
		(layer "In6.Cu")
		(net "M_G_CPU0_SA_CB<0>")
	)
	(segment
		(start 415.63036 -269.323058)
		(end 415.44748 -269.140178)
		(width 0.18288)
		(layer "In6.Cu")
		(net "M_G_CPU0_SA_CB<0>")
	)
	(segment
		(start 415.63036 -269.677642)
		(end 415.63036 -269.323058)
		(width 0.18288)
		(layer "In6.Cu")
		(net "M_G_CPU0_SA_CB<0>")
	)
	(segment
		(start 425.928028 -271.978882)
		(end 425.928028 -271.295368)
		(width 0.18288)
		(layer "In6.Cu")
		(net "M_G_CPU0_SA_CB<0>")
	)
	(segment
		(start 425.928028 -271.295368)
		(end 425.474384 -270.841724)
		(width 0.18288)
		(layer "In6.Cu")
		(net "M_G_CPU0_SA_CB<0>")
	)
	(segment
		(start 414.233106 -269.323058)
		(end 414.233106 -269.965932)
		(width 0.18288)
		(layer "In6.Cu")
		(net "M_G_CPU0_SA_CB<0>")
	)
	(segment
		(start 413.356806 -269.140178)
		(end 408.40533 -269.140178)
		(width 0.18288)
		(layer "In6.Cu")
		(net "M_G_CPU0_SA_CB<0>")
	)
	(segment
		(start 408.232864 -269.808452)
		(end 408.072844 -269.968472)
		(width 0.18288)
		(layer "In6.Cu")
		(net "M_G_CPU0_SA_CB<0>")
	)
	(segment
		(start 379.238764 -264.989818)
		(end 379.231398 -264.994136)
		(width 0.088646)
		(layer "In6.Cu")
		(net "M_G_CPU0_SA_CB<0>")
	)
	(segment
		(start 378.303536 -264.987024)
		(end 378.298964 -264.989818)
		(width 0.088646)
		(layer "In6.Cu")
		(net "M_G_CPU0_SA_CB<0>")
	)
	(segment
		(start 421.339264 -269.992602)
		(end 420.351966 -269.992602)
		(width 0.18288)
		(layer "In6.Cu")
		(net "M_G_CPU0_SA_CB<0>")
	)
	(segment
		(start 419.475666 -270.175482)
		(end 419.292786 -269.992602)
		(width 0.18288)
		(layer "In6.Cu")
		(net "M_G_CPU0_SA_CB<0>")
	)
	(segment
		(start 431.48631 -277.08733)
		(end 427.862492 -277.08733)
		(width 0.18288)
		(layer "In6.Cu")
		(net "M_G_CPU0_SA_CB<0>")
	)
	(segment
		(start 435.48173 -278.325834)
		(end 432.059588 -278.325834)
		(width 0.18288)
		(layer "In6.Cu")
		(net "M_G_CPU0_SA_CB<0>")
	)
	(segment
		(start 385.266946 -264.998454)
		(end 385.252214 -264.989818)
		(width 0.088646)
		(layer "In6.Cu")
		(net "M_G_CPU0_SA_CB<0>")
	)
	(segment
		(start 386.206746 -264.998454)
		(end 386.192014 -264.989818)
		(width 0.088646)
		(layer "In6.Cu")
		(net "M_G_CPU0_SA_CB<0>")
	)
	(segment
		(start 407.3271 -269.152624)
		(end 406.409906 -268.23543)
		(width 0.18288)
		(layer "In6.Cu")
		(net "M_G_CPU0_SA_CB<0>")
	)
	(segment
		(start 422.188386 -270.841724)
		(end 421.339264 -269.992602)
		(width 0.18288)
		(layer "In6.Cu")
		(net "M_G_CPU0_SA_CB<0>")
	)
	(segment
		(start 388.042658 -264.671556)
		(end 387.814058 -264.900156)
		(width 0.088646)
		(layer "In6.Cu")
		(net "M_G_CPU0_SA_CB<0>")
	)
	(segment
		(start 415.44748 -269.140178)
		(end 414.415986 -269.140178)
		(width 0.18288)
		(layer "In6.Cu")
		(net "M_G_CPU0_SA_CB<0>")
	)
	(segment
		(start 425.768008 -272.832322)
		(end 425.486068 -272.832322)
		(width 0.18288)
		(layer "In6.Cu")
		(net "M_G_CPU0_SA_CB<0>")
	)
	(segment
		(start 425.474384 -270.841724)
		(end 422.188386 -270.841724)
		(width 0.18288)
		(layer "In6.Cu")
		(net "M_G_CPU0_SA_CB<0>")
	)
	(segment
		(start 383.387346 -264.998454)
		(end 383.372614 -264.989818)
		(width 0.088646)
		(layer "In6.Cu")
		(net "M_G_CPU0_SA_CB<0>")
	)
	(segment
		(start 380.178564 -264.989818)
		(end 380.171198 -264.994136)
		(width 0.088646)
		(layer "In6.Cu")
		(net "M_G_CPU0_SA_CB<0>")
	)
	(segment
		(start 425.486068 -272.138902)
		(end 425.768008 -272.138902)
		(width 0.18288)
		(layer "In6.Cu")
		(net "M_G_CPU0_SA_CB<0>")
	)
	(segment
		(start 413.539686 -269.323058)
		(end 413.356806 -269.140178)
		(width 0.18288)
		(layer "In6.Cu")
		(net "M_G_CPU0_SA_CB<0>")
	)
	(segment
		(start 381.122936 -264.987024)
		(end 381.118364 -264.989818)
		(width 0.088646)
		(layer "In6.Cu")
		(net "M_G_CPU0_SA_CB<0>")
	)
	(segment
		(start 425.928028 -272.992342)
		(end 425.768008 -272.832322)
		(width 0.18288)
		(layer "In6.Cu")
		(net "M_G_CPU0_SA_CB<0>")
	)
	(segment
		(start 407.699464 -269.968472)
		(end 407.539444 -269.808452)
		(width 0.18288)
		(layer "In6.Cu")
		(net "M_G_CPU0_SA_CB<0>")
	)
	(segment
		(start 435.823614 -278.667718)
		(end 435.48173 -278.325834)
		(width 0.18288)
		(layer "In6.Cu")
		(net "M_G_CPU0_SA_CB<0>")
	)
	(segment
		(start 416.32378 -269.323058)
		(end 416.32378 -269.677642)
		(width 0.18288)
		(layer "In6.Cu")
		(net "M_G_CPU0_SA_CB<0>")
	)
	(segment
		(start 418.112194 -269.140178)
		(end 416.50666 -269.140178)
		(width 0.18288)
		(layer "In6.Cu")
		(net "M_G_CPU0_SA_CB<0>")
	)
	(segment
		(start 425.486068 -273.525742)
		(end 425.768008 -273.525742)
		(width 0.18288)
		(layer "In6.Cu")
		(net "M_G_CPU0_SA_CB<0>")
	)
	(segment
		(start 431.733198 -277.334218)
		(end 431.48631 -277.08733)
		(width 0.18288)
		(layer "In6.Cu")
		(net "M_G_CPU0_SA_CB<0>")
	)
	(segment
		(start 413.539686 -269.965932)
		(end 413.539686 -269.323058)
		(width 0.18288)
		(layer "In6.Cu")
		(net "M_G_CPU0_SA_CB<0>")
	)
	(segment
		(start 414.415986 -269.140178)
		(end 414.233106 -269.323058)
		(width 0.18288)
		(layer "In6.Cu")
		(net "M_G_CPU0_SA_CB<0>")
	)
	(segment
		(start 416.1409 -269.860522)
		(end 415.81324 -269.860522)
		(width 0.18288)
		(layer "In6.Cu")
		(net "M_G_CPU0_SA_CB<0>")
	)
	(segment
		(start 432.059588 -278.325834)
		(end 431.733198 -277.999444)
		(width 0.18288)
		(layer "In6.Cu")
		(net "M_G_CPU0_SA_CB<0>")
	)
	(segment
		(start 419.475666 -270.649192)
		(end 419.475666 -270.175482)
		(width 0.18288)
		(layer "In6.Cu")
		(net "M_G_CPU0_SA_CB<0>")
	)
	(segment
		(start 425.486068 -272.832322)
		(end 425.326048 -272.672302)
		(width 0.18288)
		(layer "In6.Cu")
		(net "M_G_CPU0_SA_CB<0>")
	)
	(segment
		(start 413.722566 -270.148812)
		(end 413.539686 -269.965932)
		(width 0.18288)
		(layer "In6.Cu")
		(net "M_G_CPU0_SA_CB<0>")
	)
	(segment
		(start 425.928028 -273.365722)
		(end 425.928028 -272.992342)
		(width 0.18288)
		(layer "In6.Cu")
		(net "M_G_CPU0_SA_CB<0>")
	)
	(segment
		(start 420.351966 -269.992602)
		(end 420.169086 -270.175482)
		(width 0.18288)
		(layer "In6.Cu")
		(net "M_G_CPU0_SA_CB<0>")
	)
	(segment
		(start 382.447546 -264.998454)
		(end 382.432814 -264.989818)
		(width 0.088646)
		(layer "In6.Cu")
		(net "M_G_CPU0_SA_CB<0>")
	)
	(segment
		(start 407.539444 -269.808452)
		(end 407.539444 -269.312644)
		(width 0.18288)
		(layer "In6.Cu")
		(net "M_G_CPU0_SA_CB<0>")
	)
	(segment
		(start 414.050226 -270.148812)
		(end 413.722566 -270.148812)
		(width 0.18288)
		(layer "In6.Cu")
		(net "M_G_CPU0_SA_CB<0>")
	)
	(segment
		(start 419.986206 -270.832072)
		(end 419.658546 -270.832072)
		(width 0.18288)
		(layer "In6.Cu")
		(net "M_G_CPU0_SA_CB<0>")
	)
	(segment
		(start 419.292786 -269.992602)
		(end 418.964618 -269.992602)
		(width 0.18288)
		(layer "In6.Cu")
		(net "M_G_CPU0_SA_CB<0>")
	)
	(segment
		(start 377.363736 -264.987024)
		(end 377.359164 -264.989818)
		(width 0.088646)
		(layer "In6.Cu")
		(net "M_G_CPU0_SA_CB<0>")
	)
	(segment
		(start 425.326048 -272.672302)
		(end 425.326048 -272.298922)
		(width 0.18288)
		(layer "In6.Cu")
		(net "M_G_CPU0_SA_CB<0>")
	)
	(segment
		(start 407.379424 -269.152624)
		(end 407.3271 -269.152624)
		(width 0.18288)
		(layer "In6.Cu")
		(net "M_G_CPU0_SA_CB<0>")
	)
	(segment
		(start 378.298964 -264.989818)
		(end 378.291598 -264.994136)
		(width 0.088646)
		(layer "In6.Cu")
		(net "M_G_CPU0_SA_CB<0>")
	)
	(segment
		(start 425.768008 -274.219162)
		(end 425.486068 -274.219162)
		(width 0.18288)
		(layer "In6.Cu")
		(net "M_G_CPU0_SA_CB<0>")
	)
	(segment
		(start 416.32378 -269.677642)
		(end 416.1409 -269.860522)
		(width 0.18288)
		(layer "In6.Cu")
		(net "M_G_CPU0_SA_CB<0>")
	)
	(segment
		(start 420.169086 -270.175482)
		(end 420.169086 -270.649192)
		(width 0.18288)
		(layer "In6.Cu")
		(net "M_G_CPU0_SA_CB<0>")
	)
	(segment
		(start 393.01674 -265.192002)
		(end 390.399778 -264.671556)
		(width 0.18288)
		(layer "In6.Cu")
		(net "M_G_CPU0_SA_CB<0>")
	)
	(arc
		(start 377.733814 -264.989818)
		(mid 377.54915 -264.939558)
		(end 377.363736 -264.987024)
		(width 0.088646)
		(layer "In6.Cu")
		(net "M_G_CPU0_SA_CB<0>")
	)
	(arc
		(start 386.192014 -264.989818)
		(mid 386.004816 -264.939675)
		(end 385.817618 -264.989818)
		(width 0.088646)
		(layer "In6.Cu")
		(net "M_G_CPU0_SA_CB<0>")
	)
	(arc
		(start 386.757418 -264.989818)
		(mid 386.483219 -265.065653)
		(end 386.206746 -264.998454)
		(width 0.088646)
		(layer "In6.Cu")
		(net "M_G_CPU0_SA_CB<0>")
	)
	(arc
		(start 380.553214 -264.989818)
		(mid 380.36855 -264.939558)
		(end 380.183136 -264.987024)
		(width 0.088646)
		(layer "In6.Cu")
		(net "M_G_CPU0_SA_CB<0>")
	)
	(arc
		(start 382.998218 -264.989818)
		(mid 382.724019 -265.065653)
		(end 382.447546 -264.998454)
		(width 0.088646)
		(layer "In6.Cu")
		(net "M_G_CPU0_SA_CB<0>")
	)
	(arc
		(start 376.794014 -264.989818)
		(mid 376.60935 -264.939558)
		(end 376.423936 -264.987024)
		(width 0.088646)
		(layer "In6.Cu")
		(net "M_G_CPU0_SA_CB<0>")
	)
	(arc
		(start 383.938018 -264.989818)
		(mid 383.663819 -265.065653)
		(end 383.387346 -264.998454)
		(width 0.088646)
		(layer "In6.Cu")
		(net "M_G_CPU0_SA_CB<0>")
	)
	(arc
		(start 382.432814 -264.989818)
		(mid 382.24815 -264.939558)
		(end 382.062736 -264.987024)
		(width 0.088646)
		(layer "In6.Cu")
		(net "M_G_CPU0_SA_CB<0>")
	)
	(arc
		(start 385.817618 -264.989818)
		(mid 385.543419 -265.065653)
		(end 385.266946 -264.998454)
		(width 0.088646)
		(layer "In6.Cu")
		(net "M_G_CPU0_SA_CB<0>")
	)
	(arc
		(start 378.291598 -264.994136)
		(mid 378.012137 -265.065573)
		(end 377.733814 -264.989818)
		(width 0.088646)
		(layer "In6.Cu")
		(net "M_G_CPU0_SA_CB<0>")
	)
	(arc
		(start 384.312414 -264.989818)
		(mid 384.125216 -264.939675)
		(end 383.938018 -264.989818)
		(width 0.088646)
		(layer "In6.Cu")
		(net "M_G_CPU0_SA_CB<0>")
	)
	(arc
		(start 384.877818 -264.989818)
		(mid 384.603619 -265.065653)
		(end 384.327146 -264.998454)
		(width 0.088646)
		(layer "In6.Cu")
		(net "M_G_CPU0_SA_CB<0>")
	)
	(arc
		(start 381.110998 -264.994136)
		(mid 380.831537 -265.065573)
		(end 380.553214 -264.989818)
		(width 0.088646)
		(layer "In6.Cu")
		(net "M_G_CPU0_SA_CB<0>")
	)
	(arc
		(start 383.372614 -264.989818)
		(mid 383.185416 -264.939675)
		(end 382.998218 -264.989818)
		(width 0.088646)
		(layer "In6.Cu")
		(net "M_G_CPU0_SA_CB<0>")
	)
	(arc
		(start 379.613414 -264.989818)
		(mid 379.42875 -264.939558)
		(end 379.243336 -264.987024)
		(width 0.088646)
		(layer "In6.Cu")
		(net "M_G_CPU0_SA_CB<0>")
	)
	(arc
		(start 381.493014 -264.989818)
		(mid 381.30835 -264.939558)
		(end 381.122936 -264.987024)
		(width 0.088646)
		(layer "In6.Cu")
		(net "M_G_CPU0_SA_CB<0>")
	)
	(arc
		(start 380.171198 -264.994136)
		(mid 379.891737 -265.065573)
		(end 379.613414 -264.989818)
		(width 0.088646)
		(layer "In6.Cu")
		(net "M_G_CPU0_SA_CB<0>")
	)
	(arc
		(start 378.673614 -264.989818)
		(mid 378.48895 -264.939558)
		(end 378.303536 -264.987024)
		(width 0.088646)
		(layer "In6.Cu")
		(net "M_G_CPU0_SA_CB<0>")
	)
	(arc
		(start 376.411998 -264.994136)
		(mid 376.132537 -265.065573)
		(end 375.854214 -264.989818)
		(width 0.088646)
		(layer "In6.Cu")
		(net "M_G_CPU0_SA_CB<0>")
	)
	(arc
		(start 375.7295 -264.892028)
		(mid 375.480032 -264.673278)
		(end 375.196862 -264.50036)
		(width 0.088646)
		(layer "In6.Cu")
		(net "M_G_CPU0_SA_CB<0>")
	)
	(arc
		(start 387.814058 -264.900156)
		(mid 387.496578 -265.059733)
		(end 387.146546 -264.998454)
		(width 0.088646)
		(layer "In6.Cu")
		(net "M_G_CPU0_SA_CB<0>")
	)
	(arc
		(start 377.351798 -264.994136)
		(mid 377.072337 -265.065573)
		(end 376.794014 -264.989818)
		(width 0.088646)
		(layer "In6.Cu")
		(net "M_G_CPU0_SA_CB<0>")
	)
	(arc
		(start 375.854214 -264.989818)
		(mid 375.788417 -264.945311)
		(end 375.7295 -264.892028)
		(width 0.088646)
		(layer "In6.Cu")
		(net "M_G_CPU0_SA_CB<0>")
	)
	(arc
		(start 387.131814 -264.989818)
		(mid 386.944616 -264.939675)
		(end 386.757418 -264.989818)
		(width 0.088646)
		(layer "In6.Cu")
		(net "M_G_CPU0_SA_CB<0>")
	)
	(arc
		(start 385.252214 -264.989818)
		(mid 385.065016 -264.939675)
		(end 384.877818 -264.989818)
		(width 0.088646)
		(layer "In6.Cu")
		(net "M_G_CPU0_SA_CB<0>")
	)
	(arc
		(start 379.231398 -264.994136)
		(mid 378.951937 -265.065573)
		(end 378.673614 -264.989818)
		(width 0.088646)
		(layer "In6.Cu")
		(net "M_G_CPU0_SA_CB<0>")
	)
	(arc
		(start 382.050798 -264.994136)
		(mid 381.771337 -265.065573)
		(end 381.493014 -264.989818)
		(width 0.088646)
		(layer "In6.Cu")
		(net "M_G_CPU0_SA_CB<0>")
	)
	(segment
		(start 442.455046 -261.504176)
		(end 442.892688 -261.066534)
		(width 0.20066)
		(layer "F.Cu")
		(net "M_G_CPU0_SA_CA<6>")
	)
	(segment
		(start 439.854086 -261.49173)
		(end 442.026548 -261.49173)
		(width 0.1016)
		(layer "F.Cu")
		(net "M_G_CPU0_SA_CA<6>")
	)
	(segment
		(start 439.84037 -261.49173)
		(end 439.854086 -261.49173)
		(width 0.101854)
		(layer "F.Cu")
		(net "M_G_CPU0_SA_CA<6>")
	)
	(segment
		(start 436.928514 -261.066788)
		(end 437.994044 -261.066788)
		(width 0.20066)
		(layer "F.Cu")
		(net "M_G_CPU0_SA_CA<6>")
	)
	(segment
		(start 438.813702 -260.572504)
		(end 439.732928 -261.49173)
		(width 0.20066)
		(layer "F.Cu")
		(net "M_G_CPU0_SA_CA<6>")
	)
	(segment
		(start 439.732928 -261.49173)
		(end 439.84037 -261.49173)
		(width 0.20066)
		(layer "F.Cu")
		(net "M_G_CPU0_SA_CA<6>")
	)
	(segment
		(start 374.61698 -249.342148)
		(end 374.617234 -249.341894)
		(width 0.20066)
		(layer "F.Cu")
		(net "M_G_CPU0_SA_CA<6>")
	)
	(segment
		(start 444.47206 -261.066534)
		(end 444.472314 -261.066788)
		(width 0.20066)
		(layer "F.Cu")
		(net "M_G_CPU0_SA_CA<6>")
	)
	(segment
		(start 442.026548 -261.49173)
		(end 442.038994 -261.504176)
		(width 0.1016)
		(layer "F.Cu")
		(net "M_G_CPU0_SA_CA<6>")
	)
	(segment
		(start 442.892688 -261.066534)
		(end 444.47206 -261.066534)
		(width 0.20066)
		(layer "F.Cu")
		(net "M_G_CPU0_SA_CA<6>")
	)
	(segment
		(start 437.994044 -261.066788)
		(end 438.488328 -260.572504)
		(width 0.20066)
		(layer "F.Cu")
		(net "M_G_CPU0_SA_CA<6>")
	)
	(segment
		(start 374.617234 -249.341894)
		(end 374.617234 -248.806208)
		(width 0.20066)
		(layer "F.Cu")
		(net "M_G_CPU0_SA_CA<6>")
	)
	(segment
		(start 435.823614 -261.066788)
		(end 436.928514 -261.066788)
		(width 0.20066)
		(layer "F.Cu")
		(net "M_G_CPU0_SA_CA<6>")
	)
	(segment
		(start 442.038994 -261.504176)
		(end 442.455046 -261.504176)
		(width 0.20066)
		(layer "F.Cu")
		(net "M_G_CPU0_SA_CA<6>")
	)
	(segment
		(start 438.488328 -260.572504)
		(end 438.813702 -260.572504)
		(width 0.20066)
		(layer "F.Cu")
		(net "M_G_CPU0_SA_CA<6>")
	)
	(segment
		(start 396.89913 -253.863094)
		(end 396.223998 -254.538226)
		(width 0.18288)
		(layer "In4.Cu")
		(net "M_G_CPU0_SA_CA<6>")
	)
	(segment
		(start 391.80135 -254.61976)
		(end 389.924798 -252.743208)
		(width 0.18288)
		(layer "In4.Cu")
		(net "M_G_CPU0_SA_CA<6>")
	)
	(segment
		(start 373.864632 -249.130566)
		(end 373.876316 -249.123708)
		(width 0.088646)
		(layer "In4.Cu")
		(net "M_G_CPU0_SA_CA<6>")
	)
	(segment
		(start 373.858536 -249.134122)
		(end 373.864632 -249.130566)
		(width 0.088646)
		(layer "In4.Cu")
		(net "M_G_CPU0_SA_CA<6>")
	)
	(segment
		(start 373.34952 -250.392692)
		(end 373.34952 -250.135136)
		(width 0.088646)
		(layer "In4.Cu")
		(net "M_G_CPU0_SA_CA<6>")
	)
	(segment
		(start 433.672234 -258.414266)
		(end 433.275994 -258.018026)
		(width 0.18288)
		(layer "In4.Cu")
		(net "M_G_CPU0_SA_CA<6>")
	)
	(segment
		(start 389.924798 -252.743208)
		(end 374.805956 -252.743208)
		(width 0.18288)
		(layer "In4.Cu")
		(net "M_G_CPU0_SA_CA<6>")
	)
	(segment
		(start 374.805956 -252.743208)
		(end 373.34952 -251.286772)
		(width 0.18288)
		(layer "In4.Cu")
		(net "M_G_CPU0_SA_CA<6>")
	)
	(segment
		(start 433.275994 -258.018026)
		(end 411.001464 -258.018026)
		(width 0.18288)
		(layer "In4.Cu")
		(net "M_G_CPU0_SA_CA<6>")
	)
	(segment
		(start 435.823614 -261.066788)
		(end 433.672234 -258.915408)
		(width 0.18288)
		(layer "In4.Cu")
		(net "M_G_CPU0_SA_CA<6>")
	)
	(segment
		(start 373.34952 -250.135136)
		(end 373.58193 -249.902726)
		(width 0.088646)
		(layer "In4.Cu")
		(net "M_G_CPU0_SA_CA<6>")
	)
	(segment
		(start 394.550392 -255.231392)
		(end 393.277852 -255.231392)
		(width 0.18288)
		(layer "In4.Cu")
		(net "M_G_CPU0_SA_CA<6>")
	)
	(segment
		(start 396.223998 -254.538226)
		(end 394.550392 -255.231392)
		(width 0.18288)
		(layer "In4.Cu")
		(net "M_G_CPU0_SA_CA<6>")
	)
	(segment
		(start 403.774402 -255.853692)
		(end 401.783804 -253.863094)
		(width 0.18288)
		(layer "In4.Cu")
		(net "M_G_CPU0_SA_CA<6>")
	)
	(segment
		(start 373.876316 -249.123708)
		(end 374.155462 -248.934224)
		(width 0.088646)
		(layer "In4.Cu")
		(net "M_G_CPU0_SA_CA<6>")
	)
	(segment
		(start 374.572022 -248.806208)
		(end 374.617234 -248.806208)
		(width 0.088646)
		(layer "In4.Cu")
		(net "M_G_CPU0_SA_CA<6>")
	)
	(segment
		(start 373.58193 -249.902726)
		(end 373.58193 -249.620024)
		(width 0.088646)
		(layer "In4.Cu")
		(net "M_G_CPU0_SA_CA<6>")
	)
	(segment
		(start 373.34952 -251.286772)
		(end 373.34952 -250.392692)
		(width 0.18288)
		(layer "In4.Cu")
		(net "M_G_CPU0_SA_CA<6>")
	)
	(segment
		(start 433.672234 -258.915408)
		(end 433.672234 -258.414266)
		(width 0.18288)
		(layer "In4.Cu")
		(net "M_G_CPU0_SA_CA<6>")
	)
	(segment
		(start 401.783804 -253.863094)
		(end 396.89913 -253.863094)
		(width 0.18288)
		(layer "In4.Cu")
		(net "M_G_CPU0_SA_CA<6>")
	)
	(segment
		(start 407.152602 -257.252724)
		(end 403.774402 -255.853692)
		(width 0.18288)
		(layer "In4.Cu")
		(net "M_G_CPU0_SA_CA<6>")
	)
	(segment
		(start 393.277852 -255.231392)
		(end 391.80135 -254.61976)
		(width 0.18288)
		(layer "In4.Cu")
		(net "M_G_CPU0_SA_CA<6>")
	)
	(segment
		(start 411.001464 -258.018026)
		(end 407.152602 -257.252724)
		(width 0.18288)
		(layer "In4.Cu")
		(net "M_G_CPU0_SA_CA<6>")
	)
	(arc
		(start 374.155462 -248.934224)
		(mid 374.35412 -248.838894)
		(end 374.572022 -248.806208)
		(width 0.088646)
		(layer "In4.Cu")
		(net "M_G_CPU0_SA_CA<6>")
	)
	(arc
		(start 373.58193 -249.620024)
		(mid 373.655921 -249.340458)
		(end 373.858536 -249.134122)
		(width 0.088646)
		(layer "In4.Cu")
		(net "M_G_CPU0_SA_CA<6>")
	)
	(segment
		(start 441.028582 -261.916672)
		(end 442.664342 -261.916672)
		(width 0.20066)
		(layer "F.Cu")
		(net "M_G_CPU0_SA_CA<5>")
	)
	(segment
		(start 376.136916 -255.825498)
		(end 376.136916 -256.361184)
		(width 0.20066)
		(layer "F.Cu")
		(net "M_G_CPU0_SA_CA<5>")
	)
	(segment
		(start 445.756792 -262.34898)
		(end 446.621662 -261.48411)
		(width 0.20066)
		(layer "F.Cu")
		(net "M_G_CPU0_SA_CA<5>")
	)
	(segment
		(start 439.923682 -261.916672)
		(end 441.028582 -261.916672)
		(width 0.20066)
		(layer "F.Cu")
		(net "M_G_CPU0_SA_CA<5>")
	)
	(segment
		(start 443.450726 -262.352282)
		(end 443.455552 -262.352282)
		(width 0.101854)
		(layer "F.Cu")
		(net "M_G_CPU0_SA_CA<5>")
	)
	(segment
		(start 442.664342 -261.916672)
		(end 443.099952 -262.352282)
		(width 0.20066)
		(layer "F.Cu")
		(net "M_G_CPU0_SA_CA<5>")
	)
	(segment
		(start 376.136916 -256.361184)
		(end 376.136662 -256.361438)
		(width 0.20066)
		(layer "F.Cu")
		(net "M_G_CPU0_SA_CA<5>")
	)
	(segment
		(start 445.482726 -262.34898)
		(end 445.756792 -262.34898)
		(width 0.20066)
		(layer "F.Cu")
		(net "M_G_CPU0_SA_CA<5>")
	)
	(segment
		(start 443.099952 -262.352282)
		(end 443.450726 -262.352282)
		(width 0.20066)
		(layer "F.Cu")
		(net "M_G_CPU0_SA_CA<5>")
	)
	(segment
		(start 443.455552 -262.352282)
		(end 443.46622 -262.341614)
		(width 0.1016)
		(layer "F.Cu")
		(net "M_G_CPU0_SA_CA<5>")
	)
	(segment
		(start 445.47536 -262.341614)
		(end 445.482726 -262.34898)
		(width 0.1016)
		(layer "F.Cu")
		(net "M_G_CPU0_SA_CA<5>")
	)
	(segment
		(start 447.025268 -261.48411)
		(end 447.45783 -261.916672)
		(width 0.20066)
		(layer "F.Cu")
		(net "M_G_CPU0_SA_CA<5>")
	)
	(segment
		(start 447.45783 -261.916672)
		(end 448.572382 -261.916672)
		(width 0.20066)
		(layer "F.Cu")
		(net "M_G_CPU0_SA_CA<5>")
	)
	(segment
		(start 446.621662 -261.48411)
		(end 447.025268 -261.48411)
		(width 0.20066)
		(layer "F.Cu")
		(net "M_G_CPU0_SA_CA<5>")
	)
	(segment
		(start 443.46622 -262.341614)
		(end 445.47536 -262.341614)
		(width 0.1016)
		(layer "F.Cu")
		(net "M_G_CPU0_SA_CA<5>")
	)
	(segment
		(start 375.949464 -256.03708)
		(end 375.940574 -256.04216)
		(width 0.088646)
		(layer "In4.Cu")
		(net "M_G_CPU0_SA_CA<5>")
	)
	(segment
		(start 397.012922 -254.858774)
		(end 396.789402 -255.082294)
		(width 0.18288)
		(layer "In4.Cu")
		(net "M_G_CPU0_SA_CA<5>")
	)
	(segment
		(start 407.677366 -259.016754)
		(end 407.45283 -258.792218)
		(width 0.18288)
		(layer "In4.Cu")
		(net "M_G_CPU0_SA_CA<5>")
	)
	(segment
		(start 377.322588 -253.471426)
		(end 377.171712 -253.622302)
		(width 0.088646)
		(layer "In4.Cu")
		(net "M_G_CPU0_SA_CA<5>")
	)
	(segment
		(start 396.789402 -255.082294)
		(end 394.810742 -255.901952)
		(width 0.18288)
		(layer "In4.Cu")
		(net "M_G_CPU0_SA_CA<5>")
	)
	(segment
		(start 376.701812 -254.733552)
		(end 376.701812 -254.75565)
		(width 0.088646)
		(layer "In4.Cu")
		(net "M_G_CPU0_SA_CA<5>")
	)
	(segment
		(start 435.621176 -263.19226)
		(end 435.620922 -263.192514)
		(width 0.18288)
		(layer "In4.Cu")
		(net "M_G_CPU0_SA_CA<5>")
	)
	(segment
		(start 393.143486 -255.901952)
		(end 391.399522 -255.179576)
		(width 0.18288)
		(layer "In4.Cu")
		(net "M_G_CPU0_SA_CA<5>")
	)
	(segment
		(start 432.026314 -261.581646)
		(end 431.085244 -260.640576)
		(width 0.18288)
		(layer "In4.Cu")
		(net "M_G_CPU0_SA_CA<5>")
	)
	(segment
		(start 408.454352 -259.016754)
		(end 407.677366 -259.016754)
		(width 0.18288)
		(layer "In4.Cu")
		(net "M_G_CPU0_SA_CA<5>")
	)
	(segment
		(start 434.206142 -263.192514)
		(end 432.595274 -261.581646)
		(width 0.18288)
		(layer "In4.Cu")
		(net "M_G_CPU0_SA_CA<5>")
	)
	(segment
		(start 376.889264 -254.409194)
		(end 376.880374 -254.414274)
		(width 0.088646)
		(layer "In4.Cu")
		(net "M_G_CPU0_SA_CA<5>")
	)
	(segment
		(start 394.810742 -255.901952)
		(end 393.143486 -255.901952)
		(width 0.18288)
		(layer "In4.Cu")
		(net "M_G_CPU0_SA_CA<5>")
	)
	(segment
		(start 439.923682 -261.916672)
		(end 438.648094 -263.19226)
		(width 0.18288)
		(layer "In4.Cu")
		(net "M_G_CPU0_SA_CA<5>")
	)
	(segment
		(start 376.419618 -255.223264)
		(end 376.410728 -255.228344)
		(width 0.088646)
		(layer "In4.Cu")
		(net "M_G_CPU0_SA_CA<5>")
	)
	(segment
		(start 420.885112 -259.79247)
		(end 411.312614 -259.79247)
		(width 0.18288)
		(layer "In4.Cu")
		(net "M_G_CPU0_SA_CA<5>")
	)
	(segment
		(start 432.595274 -261.581646)
		(end 432.026314 -261.581646)
		(width 0.18288)
		(layer "In4.Cu")
		(net "M_G_CPU0_SA_CA<5>")
	)
	(segment
		(start 423.642282 -259.792724)
		(end 420.885366 -259.792724)
		(width 0.18288)
		(layer "In4.Cu")
		(net "M_G_CPU0_SA_CA<5>")
	)
	(segment
		(start 431.085244 -260.640576)
		(end 424.490134 -260.640576)
		(width 0.18288)
		(layer "In4.Cu")
		(net "M_G_CPU0_SA_CA<5>")
	)
	(segment
		(start 389.691372 -253.471426)
		(end 378.781818 -253.471426)
		(width 0.18288)
		(layer "In4.Cu")
		(net "M_G_CPU0_SA_CA<5>")
	)
	(segment
		(start 375.766584 -256.304288)
		(end 375.823734 -256.361438)
		(width 0.088646)
		(layer "In4.Cu")
		(net "M_G_CPU0_SA_CA<5>")
	)
	(segment
		(start 407.45283 -258.792218)
		(end 403.60219 -257.197352)
		(width 0.18288)
		(layer "In4.Cu")
		(net "M_G_CPU0_SA_CA<5>")
	)
	(segment
		(start 420.885366 -259.792724)
		(end 420.885112 -259.79247)
		(width 0.18288)
		(layer "In4.Cu")
		(net "M_G_CPU0_SA_CA<5>")
	)
	(segment
		(start 378.781818 -253.471426)
		(end 377.322588 -253.471426)
		(width 0.088646)
		(layer "In4.Cu")
		(net "M_G_CPU0_SA_CA<5>")
	)
	(segment
		(start 424.490134 -260.640576)
		(end 423.642282 -259.792724)
		(width 0.18288)
		(layer "In4.Cu")
		(net "M_G_CPU0_SA_CA<5>")
	)
	(segment
		(start 435.620922 -263.192514)
		(end 434.206142 -263.192514)
		(width 0.18288)
		(layer "In4.Cu")
		(net "M_G_CPU0_SA_CA<5>")
	)
	(segment
		(start 391.399522 -255.179576)
		(end 389.691372 -253.471426)
		(width 0.18288)
		(layer "In4.Cu")
		(net "M_G_CPU0_SA_CA<5>")
	)
	(segment
		(start 438.648094 -263.19226)
		(end 435.621176 -263.19226)
		(width 0.18288)
		(layer "In4.Cu")
		(net "M_G_CPU0_SA_CA<5>")
	)
	(segment
		(start 377.171712 -253.622302)
		(end 377.171712 -253.929642)
		(width 0.088646)
		(layer "In4.Cu")
		(net "M_G_CPU0_SA_CA<5>")
	)
	(segment
		(start 375.95556 -256.033524)
		(end 375.949464 -256.03708)
		(width 0.088646)
		(layer "In4.Cu")
		(net "M_G_CPU0_SA_CA<5>")
	)
	(segment
		(start 401.263612 -254.858774)
		(end 397.012922 -254.858774)
		(width 0.18288)
		(layer "In4.Cu")
		(net "M_G_CPU0_SA_CA<5>")
	)
	(segment
		(start 411.312614 -259.79247)
		(end 410.964634 -259.44449)
		(width 0.18288)
		(layer "In4.Cu")
		(net "M_G_CPU0_SA_CA<5>")
	)
	(segment
		(start 375.823734 -256.361438)
		(end 376.136662 -256.361438)
		(width 0.088646)
		(layer "In4.Cu")
		(net "M_G_CPU0_SA_CA<5>")
	)
	(segment
		(start 410.964634 -259.44449)
		(end 408.882088 -259.44449)
		(width 0.18288)
		(layer "In4.Cu")
		(net "M_G_CPU0_SA_CA<5>")
	)
	(segment
		(start 403.60219 -257.197352)
		(end 401.263612 -254.858774)
		(width 0.18288)
		(layer "In4.Cu")
		(net "M_G_CPU0_SA_CA<5>")
	)
	(segment
		(start 408.882088 -259.44449)
		(end 408.454352 -259.016754)
		(width 0.18288)
		(layer "In4.Cu")
		(net "M_G_CPU0_SA_CA<5>")
	)
	(arc
		(start 375.940574 -256.04216)
		(mid 375.824765 -256.154089)
		(end 375.766584 -256.304288)
		(width 0.088646)
		(layer "In4.Cu")
		(net "M_G_CPU0_SA_CA<5>")
	)
	(arc
		(start 376.880374 -254.414274)
		(mid 376.74946 -254.550634)
		(end 376.701812 -254.733552)
		(width 0.088646)
		(layer "In4.Cu")
		(net "M_G_CPU0_SA_CA<5>")
	)
	(arc
		(start 376.232166 -255.547622)
		(mid 376.158175 -255.827188)
		(end 375.95556 -256.033524)
		(width 0.088646)
		(layer "In4.Cu")
		(net "M_G_CPU0_SA_CA<5>")
	)
	(arc
		(start 377.171712 -253.929642)
		(mid 377.093601 -254.206591)
		(end 376.889264 -254.409194)
		(width 0.088646)
		(layer "In4.Cu")
		(net "M_G_CPU0_SA_CA<5>")
	)
	(arc
		(start 376.410728 -255.228344)
		(mid 376.279814 -255.364704)
		(end 376.232166 -255.547622)
		(width 0.088646)
		(layer "In4.Cu")
		(net "M_G_CPU0_SA_CA<5>")
	)
	(arc
		(start 376.701812 -254.75565)
		(mid 376.620901 -255.025778)
		(end 376.419618 -255.223264)
		(width 0.088646)
		(layer "In4.Cu")
		(net "M_G_CPU0_SA_CA<5>")
	)
	(segment
		(start 438.575704 -262.294116)
		(end 439.47334 -263.191752)
		(width 0.20066)
		(layer "F.Cu")
		(net "M_G_CPU0_SA_CA<4>")
	)
	(segment
		(start 439.47334 -263.191752)
		(end 439.742834 -263.191752)
		(width 0.20066)
		(layer "F.Cu")
		(net "M_G_CPU0_SA_CA<4>")
	)
	(segment
		(start 438.291478 -262.294116)
		(end 438.575704 -262.294116)
		(width 0.20066)
		(layer "F.Cu")
		(net "M_G_CPU0_SA_CA<4>")
	)
	(segment
		(start 442.038994 -263.204198)
		(end 442.455046 -263.204198)
		(width 0.20066)
		(layer "F.Cu")
		(net "M_G_CPU0_SA_CA<4>")
	)
	(segment
		(start 442.892688 -262.766556)
		(end 444.47206 -262.766556)
		(width 0.20066)
		(layer "F.Cu")
		(net "M_G_CPU0_SA_CA<4>")
	)
	(segment
		(start 442.026548 -263.191752)
		(end 442.038994 -263.204198)
		(width 0.1016)
		(layer "F.Cu")
		(net "M_G_CPU0_SA_CA<4>")
	)
	(segment
		(start 435.823614 -262.766556)
		(end 435.823868 -262.76681)
		(width 0.20066)
		(layer "F.Cu")
		(net "M_G_CPU0_SA_CA<4>")
	)
	(segment
		(start 375.197116 -255.825498)
		(end 375.196862 -255.825752)
		(width 0.20066)
		(layer "F.Cu")
		(net "M_G_CPU0_SA_CA<4>")
	)
	(segment
		(start 439.772044 -263.191752)
		(end 442.026548 -263.191752)
		(width 0.1016)
		(layer "F.Cu")
		(net "M_G_CPU0_SA_CA<4>")
	)
	(segment
		(start 435.823868 -262.76681)
		(end 436.928514 -262.76681)
		(width 0.20066)
		(layer "F.Cu")
		(net "M_G_CPU0_SA_CA<4>")
	)
	(segment
		(start 437.818784 -262.76681)
		(end 438.291478 -262.294116)
		(width 0.20066)
		(layer "F.Cu")
		(net "M_G_CPU0_SA_CA<4>")
	)
	(segment
		(start 375.196862 -255.825752)
		(end 375.196862 -256.361438)
		(width 0.20066)
		(layer "F.Cu")
		(net "M_G_CPU0_SA_CA<4>")
	)
	(segment
		(start 439.742834 -263.191752)
		(end 439.772044 -263.191752)
		(width 0.101854)
		(layer "F.Cu")
		(net "M_G_CPU0_SA_CA<4>")
	)
	(segment
		(start 444.47206 -262.766556)
		(end 444.472314 -262.76681)
		(width 0.20066)
		(layer "F.Cu")
		(net "M_G_CPU0_SA_CA<4>")
	)
	(segment
		(start 436.928514 -262.76681)
		(end 437.818784 -262.76681)
		(width 0.20066)
		(layer "F.Cu")
		(net "M_G_CPU0_SA_CA<4>")
	)
	(segment
		(start 442.455046 -263.204198)
		(end 442.892688 -262.766556)
		(width 0.20066)
		(layer "F.Cu")
		(net "M_G_CPU0_SA_CA<4>")
	)
	(segment
		(start 433.019454 -260.392164)
		(end 433.019454 -259.180584)
		(width 0.18288)
		(layer "In4.Cu")
		(net "M_G_CPU0_SA_CA<4>")
	)
	(segment
		(start 375.854214 -255.87198)
		(end 375.85142 -255.873504)
		(width 0.088646)
		(layer "In4.Cu")
		(net "M_G_CPU0_SA_CA<4>")
	)
	(segment
		(start 376.981212 -253.543308)
		(end 376.981212 -253.919736)
		(width 0.088646)
		(layer "In4.Cu")
		(net "M_G_CPU0_SA_CA<4>")
	)
	(segment
		(start 394.641832 -255.566672)
		(end 393.210542 -255.566672)
		(width 0.18288)
		(layer "In4.Cu")
		(net "M_G_CPU0_SA_CA<4>")
	)
	(segment
		(start 433.019454 -259.180584)
		(end 432.782726 -258.943856)
		(width 0.18288)
		(layer "In4.Cu")
		(net "M_G_CPU0_SA_CA<4>")
	)
	(segment
		(start 396.39748 -254.839216)
		(end 394.641832 -255.566672)
		(width 0.18288)
		(layer "In4.Cu")
		(net "M_G_CPU0_SA_CA<4>")
	)
	(segment
		(start 408.384756 -258.064508)
		(end 407.705814 -258.064508)
		(width 0.18288)
		(layer "In4.Cu")
		(net "M_G_CPU0_SA_CA<4>")
	)
	(segment
		(start 435.823614 -262.766556)
		(end 435.08549 -262.028432)
		(width 0.18288)
		(layer "In4.Cu")
		(net "M_G_CPU0_SA_CA<4>")
	)
	(segment
		(start 377.243594 -253.280926)
		(end 376.981212 -253.543308)
		(width 0.088646)
		(layer "In4.Cu")
		(net "M_G_CPU0_SA_CA<4>")
	)
	(segment
		(start 375.85142 -255.873504)
		(end 375.848118 -255.875536)
		(width 0.088646)
		(layer "In4.Cu")
		(net "M_G_CPU0_SA_CA<4>")
	)
	(segment
		(start 378.781818 -253.099062)
		(end 378.518928 -253.099062)
		(width 0.088646)
		(layer "In4.Cu")
		(net "M_G_CPU0_SA_CA<4>")
	)
	(segment
		(start 376.80265 -254.239014)
		(end 376.79376 -254.244094)
		(width 0.088646)
		(layer "In4.Cu")
		(net "M_G_CPU0_SA_CA<4>")
	)
	(segment
		(start 378.518928 -253.099062)
		(end 378.337064 -253.280926)
		(width 0.088646)
		(layer "In4.Cu")
		(net "M_G_CPU0_SA_CA<4>")
	)
	(segment
		(start 376.511312 -254.723646)
		(end 376.511312 -254.733552)
		(width 0.088646)
		(layer "In4.Cu")
		(net "M_G_CPU0_SA_CA<4>")
	)
	(segment
		(start 376.041666 -255.525524)
		(end 376.041666 -255.547622)
		(width 0.088646)
		(layer "In4.Cu")
		(net "M_G_CPU0_SA_CA<4>")
	)
	(segment
		(start 432.782726 -258.943856)
		(end 409.264104 -258.943856)
		(width 0.18288)
		(layer "In4.Cu")
		(net "M_G_CPU0_SA_CA<4>")
	)
	(segment
		(start 393.210542 -255.566672)
		(end 391.589514 -254.895096)
		(width 0.18288)
		(layer "In4.Cu")
		(net "M_G_CPU0_SA_CA<4>")
	)
	(segment
		(start 375.863104 -255.8669)
		(end 375.854214 -255.87198)
		(width 0.088646)
		(layer "In4.Cu")
		(net "M_G_CPU0_SA_CA<4>")
	)
	(segment
		(start 435.08549 -262.028432)
		(end 434.655722 -262.028432)
		(width 0.18288)
		(layer "In4.Cu")
		(net "M_G_CPU0_SA_CA<4>")
	)
	(segment
		(start 391.589514 -254.895096)
		(end 389.79348 -253.099062)
		(width 0.18288)
		(layer "In4.Cu")
		(net "M_G_CPU0_SA_CA<4>")
	)
	(segment
		(start 396.875762 -254.360934)
		(end 396.39748 -254.839216)
		(width 0.18288)
		(layer "In4.Cu")
		(net "M_G_CPU0_SA_CA<4>")
	)
	(segment
		(start 378.337064 -253.280926)
		(end 377.243594 -253.280926)
		(width 0.088646)
		(layer "In4.Cu")
		(net "M_G_CPU0_SA_CA<4>")
	)
	(segment
		(start 375.50979 -256.361438)
		(end 375.196862 -256.361438)
		(width 0.088646)
		(layer "In4.Cu")
		(net "M_G_CPU0_SA_CA<4>")
	)
	(segment
		(start 409.264104 -258.943856)
		(end 408.384756 -258.064508)
		(width 0.18288)
		(layer "In4.Cu")
		(net "M_G_CPU0_SA_CA<4>")
	)
	(segment
		(start 403.467824 -256.309114)
		(end 401.519644 -254.360934)
		(width 0.18288)
		(layer "In4.Cu")
		(net "M_G_CPU0_SA_CA<4>")
	)
	(segment
		(start 401.519644 -254.360934)
		(end 396.875762 -254.360934)
		(width 0.18288)
		(layer "In4.Cu")
		(net "M_G_CPU0_SA_CA<4>")
	)
	(segment
		(start 434.655722 -262.028432)
		(end 433.019454 -260.392164)
		(width 0.18288)
		(layer "In4.Cu")
		(net "M_G_CPU0_SA_CA<4>")
	)
	(segment
		(start 389.79348 -253.099062)
		(end 378.781818 -253.099062)
		(width 0.18288)
		(layer "In4.Cu")
		(net "M_G_CPU0_SA_CA<4>")
	)
	(segment
		(start 407.705814 -258.064508)
		(end 403.467824 -256.309114)
		(width 0.18288)
		(layer "In4.Cu")
		(net "M_G_CPU0_SA_CA<4>")
	)
	(segment
		(start 376.33275 -255.05283)
		(end 376.32386 -255.05791)
		(width 0.088646)
		(layer "In4.Cu")
		(net "M_G_CPU0_SA_CA<4>")
	)
	(segment
		(start 375.575322 -256.295906)
		(end 375.50979 -256.361438)
		(width 0.088646)
		(layer "In4.Cu")
		(net "M_G_CPU0_SA_CA<4>")
	)
	(arc
		(start 376.981212 -253.919736)
		(mid 376.933533 -254.102636)
		(end 376.80265 -254.239014)
		(width 0.088646)
		(layer "In4.Cu")
		(net "M_G_CPU0_SA_CA<4>")
	)
	(arc
		(start 376.511312 -254.733552)
		(mid 376.463633 -254.916452)
		(end 376.33275 -255.05283)
		(width 0.088646)
		(layer "In4.Cu")
		(net "M_G_CPU0_SA_CA<4>")
	)
	(arc
		(start 376.041666 -255.547622)
		(mid 375.993987 -255.730522)
		(end 375.863104 -255.8669)
		(width 0.088646)
		(layer "In4.Cu")
		(net "M_G_CPU0_SA_CA<4>")
	)
	(arc
		(start 376.79376 -254.244094)
		(mid 376.589425 -254.446699)
		(end 376.511312 -254.723646)
		(width 0.088646)
		(layer "In4.Cu")
		(net "M_G_CPU0_SA_CA<4>")
	)
	(arc
		(start 375.848118 -255.875536)
		(mid 375.662595 -256.053837)
		(end 375.575322 -256.295906)
		(width 0.088646)
		(layer "In4.Cu")
		(net "M_G_CPU0_SA_CA<4>")
	)
	(arc
		(start 376.32386 -255.05791)
		(mid 376.122578 -255.255397)
		(end 376.041666 -255.525524)
		(width 0.088646)
		(layer "In4.Cu")
		(net "M_G_CPU0_SA_CA<4>")
	)
	(segment
		(start 447.45783 -263.616694)
		(end 448.572382 -263.616694)
		(width 0.20066)
		(layer "F.Cu")
		(net "M_G_CPU0_SA_CA<3>")
	)
	(segment
		(start 376.606562 -256.639314)
		(end 376.606562 -257.175)
		(width 0.20066)
		(layer "F.Cu")
		(net "M_G_CPU0_SA_CA<3>")
	)
	(segment
		(start 443.455552 -264.052304)
		(end 443.46622 -264.041636)
		(width 0.1016)
		(layer "F.Cu")
		(net "M_G_CPU0_SA_CA<3>")
	)
	(segment
		(start 439.847482 -263.616694)
		(end 441.028582 -263.616694)
		(width 0.20066)
		(layer "F.Cu")
		(net "M_G_CPU0_SA_CA<3>")
	)
	(segment
		(start 445.756792 -264.049002)
		(end 446.621662 -263.184132)
		(width 0.20066)
		(layer "F.Cu")
		(net "M_G_CPU0_SA_CA<3>")
	)
	(segment
		(start 443.450726 -264.052304)
		(end 443.455552 -264.052304)
		(width 0.101854)
		(layer "F.Cu")
		(net "M_G_CPU0_SA_CA<3>")
	)
	(segment
		(start 445.482726 -264.049002)
		(end 445.756792 -264.049002)
		(width 0.20066)
		(layer "F.Cu")
		(net "M_G_CPU0_SA_CA<3>")
	)
	(segment
		(start 376.606562 -257.175)
		(end 376.606816 -257.175254)
		(width 0.20066)
		(layer "F.Cu")
		(net "M_G_CPU0_SA_CA<3>")
	)
	(segment
		(start 443.46622 -264.041636)
		(end 445.47536 -264.041636)
		(width 0.1016)
		(layer "F.Cu")
		(net "M_G_CPU0_SA_CA<3>")
	)
	(segment
		(start 441.028582 -263.616694)
		(end 442.664342 -263.616694)
		(width 0.20066)
		(layer "F.Cu")
		(net "M_G_CPU0_SA_CA<3>")
	)
	(segment
		(start 446.621662 -263.184132)
		(end 447.025268 -263.184132)
		(width 0.20066)
		(layer "F.Cu")
		(net "M_G_CPU0_SA_CA<3>")
	)
	(segment
		(start 445.47536 -264.041636)
		(end 445.482726 -264.049002)
		(width 0.1016)
		(layer "F.Cu")
		(net "M_G_CPU0_SA_CA<3>")
	)
	(segment
		(start 443.099952 -264.052304)
		(end 443.450726 -264.052304)
		(width 0.20066)
		(layer "F.Cu")
		(net "M_G_CPU0_SA_CA<3>")
	)
	(segment
		(start 442.664342 -263.616694)
		(end 443.099952 -264.052304)
		(width 0.20066)
		(layer "F.Cu")
		(net "M_G_CPU0_SA_CA<3>")
	)
	(segment
		(start 447.025268 -263.184132)
		(end 447.45783 -263.616694)
		(width 0.20066)
		(layer "F.Cu")
		(net "M_G_CPU0_SA_CA<3>")
	)
	(segment
		(start 379.628146 -255.2319)
		(end 379.613414 -255.223264)
		(width 0.088646)
		(layer "In4.Cu")
		(net "M_G_CPU0_SA_CA<3>")
	)
	(segment
		(start 406.745186 -259.729478)
		(end 404.48357 -259.729478)
		(width 0.18288)
		(layer "In4.Cu")
		(net "M_G_CPU0_SA_CA<3>")
	)
	(segment
		(start 439.847482 -263.616694)
		(end 438.571894 -264.892282)
		(width 0.18288)
		(layer "In4.Cu")
		(net "M_G_CPU0_SA_CA<3>")
	)
	(segment
		(start 384.584448 -254.855472)
		(end 384.267456 -255.172464)
		(width 0.088646)
		(layer "In4.Cu")
		(net "M_G_CPU0_SA_CA<3>")
	)
	(segment
		(start 384.920236 -254.855472)
		(end 384.584448 -254.855472)
		(width 0.088646)
		(layer "In4.Cu")
		(net "M_G_CPU0_SA_CA<3>")
	)
	(segment
		(start 380.553468 -255.223264)
		(end 380.545086 -255.218438)
		(width 0.088646)
		(layer "In4.Cu")
		(net "M_G_CPU0_SA_CA<3>")
	)
	(segment
		(start 438.571894 -264.892282)
		(end 434.36413 -264.892282)
		(width 0.18288)
		(layer "In4.Cu")
		(net "M_G_CPU0_SA_CA<3>")
	)
	(segment
		(start 400.608546 -255.854454)
		(end 396.867634 -255.854454)
		(width 0.18288)
		(layer "In4.Cu")
		(net "M_G_CPU0_SA_CA<3>")
	)
	(segment
		(start 432.811174 -263.349486)
		(end 431.922174 -263.349486)
		(width 0.18288)
		(layer "In4.Cu")
		(net "M_G_CPU0_SA_CA<3>")
	)
	(segment
		(start 424.436286 -262.340852)
		(end 423.587926 -261.492492)
		(width 0.18288)
		(layer "In4.Cu")
		(net "M_G_CPU0_SA_CA<3>")
	)
	(segment
		(start 426.1993 -262.340852)
		(end 424.436286 -262.340852)
		(width 0.18288)
		(layer "In4.Cu")
		(net "M_G_CPU0_SA_CA<3>")
	)
	(segment
		(start 396.867634 -255.854454)
		(end 395.133322 -256.572766)
		(width 0.18288)
		(layer "In4.Cu")
		(net "M_G_CPU0_SA_CA<3>")
	)
	(segment
		(start 423.587926 -261.492492)
		(end 411.169104 -261.492492)
		(width 0.18288)
		(layer "In4.Cu")
		(net "M_G_CPU0_SA_CA<3>")
	)
	(segment
		(start 430.913794 -262.341106)
		(end 426.199554 -262.341106)
		(width 0.18288)
		(layer "In4.Cu")
		(net "M_G_CPU0_SA_CA<3>")
	)
	(segment
		(start 376.889518 -256.03708)
		(end 376.880628 -256.04216)
		(width 0.088646)
		(layer "In4.Cu")
		(net "M_G_CPU0_SA_CA<3>")
	)
	(segment
		(start 395.133322 -256.572766)
		(end 393.009374 -256.572766)
		(width 0.18288)
		(layer "In4.Cu")
		(net "M_G_CPU0_SA_CA<3>")
	)
	(segment
		(start 382.443228 -255.22936)
		(end 382.432814 -255.223264)
		(width 0.088646)
		(layer "In4.Cu")
		(net "M_G_CPU0_SA_CA<3>")
	)
	(segment
		(start 389.023098 -254.921766)
		(end 386.896356 -254.921766)
		(width 0.18288)
		(layer "In4.Cu")
		(net "M_G_CPU0_SA_CA<3>")
	)
	(segment
		(start 433.237894 -263.766046)
		(end 433.227734 -263.766046)
		(width 0.18288)
		(layer "In4.Cu")
		(net "M_G_CPU0_SA_CA<3>")
	)
	(segment
		(start 381.503174 -255.22936)
		(end 381.49276 -255.223264)
		(width 0.088646)
		(layer "In4.Cu")
		(net "M_G_CPU0_SA_CA<3>")
	)
	(segment
		(start 404.48357 -259.729478)
		(end 400.608546 -255.854454)
		(width 0.18288)
		(layer "In4.Cu")
		(net "M_G_CPU0_SA_CA<3>")
	)
	(segment
		(start 376.702066 -256.361438)
		(end 376.702066 -256.945384)
		(width 0.088646)
		(layer "In4.Cu")
		(net "M_G_CPU0_SA_CA<3>")
	)
	(segment
		(start 378.688346 -255.2319)
		(end 378.673614 -255.223264)
		(width 0.088646)
		(layer "In4.Cu")
		(net "M_G_CPU0_SA_CA<3>")
	)
	(segment
		(start 431.922174 -263.349486)
		(end 430.913794 -262.341106)
		(width 0.18288)
		(layer "In4.Cu")
		(net "M_G_CPU0_SA_CA<3>")
	)
	(segment
		(start 384.267456 -255.172464)
		(end 384.124962 -255.172464)
		(width 0.088646)
		(layer "In4.Cu")
		(net "M_G_CPU0_SA_CA<3>")
	)
	(segment
		(start 410.32049 -260.643878)
		(end 407.659586 -260.643878)
		(width 0.18288)
		(layer "In4.Cu")
		(net "M_G_CPU0_SA_CA<3>")
	)
	(segment
		(start 386.830062 -254.855472)
		(end 384.920236 -254.855472)
		(width 0.18288)
		(layer "In4.Cu")
		(net "M_G_CPU0_SA_CA<3>")
	)
	(segment
		(start 393.009374 -256.572766)
		(end 389.023098 -254.921766)
		(width 0.18288)
		(layer "In4.Cu")
		(net "M_G_CPU0_SA_CA<3>")
	)
	(segment
		(start 377.171966 -255.547622)
		(end 377.171966 -255.557528)
		(width 0.088646)
		(layer "In4.Cu")
		(net "M_G_CPU0_SA_CA<3>")
	)
	(segment
		(start 411.169104 -261.492492)
		(end 410.32049 -260.643878)
		(width 0.18288)
		(layer "In4.Cu")
		(net "M_G_CPU0_SA_CA<3>")
	)
	(segment
		(start 434.36413 -264.892282)
		(end 433.237894 -263.766046)
		(width 0.18288)
		(layer "In4.Cu")
		(net "M_G_CPU0_SA_CA<3>")
	)
	(segment
		(start 407.659586 -260.643878)
		(end 406.745186 -259.729478)
		(width 0.18288)
		(layer "In4.Cu")
		(net "M_G_CPU0_SA_CA<3>")
	)
	(segment
		(start 386.896356 -254.921766)
		(end 386.830062 -254.855472)
		(width 0.18288)
		(layer "In4.Cu")
		(net "M_G_CPU0_SA_CA<3>")
	)
	(segment
		(start 433.227734 -263.766046)
		(end 432.811174 -263.349486)
		(width 0.18288)
		(layer "In4.Cu")
		(net "M_G_CPU0_SA_CA<3>")
	)
	(segment
		(start 377.359418 -255.223264)
		(end 377.350528 -255.228344)
		(width 0.088646)
		(layer "In4.Cu")
		(net "M_G_CPU0_SA_CA<3>")
	)
	(segment
		(start 377.748546 -255.2319)
		(end 377.733814 -255.223264)
		(width 0.088646)
		(layer "In4.Cu")
		(net "M_G_CPU0_SA_CA<3>")
	)
	(segment
		(start 426.199554 -262.341106)
		(end 426.1993 -262.340852)
		(width 0.18288)
		(layer "In4.Cu")
		(net "M_G_CPU0_SA_CA<3>")
	)
	(arc
		(start 380.178818 -255.223264)
		(mid 379.904589 -255.299189)
		(end 379.628146 -255.2319)
		(width 0.088646)
		(layer "In4.Cu")
		(net "M_G_CPU0_SA_CA<3>")
	)
	(arc
		(start 377.171966 -255.557528)
		(mid 377.093855 -255.834477)
		(end 376.889518 -256.03708)
		(width 0.088646)
		(layer "In4.Cu")
		(net "M_G_CPU0_SA_CA<3>")
	)
	(arc
		(start 382.432814 -255.223264)
		(mid 382.245616 -255.173121)
		(end 382.058418 -255.223264)
		(width 0.088646)
		(layer "In4.Cu")
		(net "M_G_CPU0_SA_CA<3>")
	)
	(arc
		(start 377.350528 -255.228344)
		(mid 377.219614 -255.364704)
		(end 377.171966 -255.547622)
		(width 0.088646)
		(layer "In4.Cu")
		(net "M_G_CPU0_SA_CA<3>")
	)
	(arc
		(start 379.239018 -255.223264)
		(mid 378.964789 -255.299189)
		(end 378.688346 -255.2319)
		(width 0.088646)
		(layer "In4.Cu")
		(net "M_G_CPU0_SA_CA<3>")
	)
	(arc
		(start 378.299218 -255.223264)
		(mid 378.024989 -255.299189)
		(end 377.748546 -255.2319)
		(width 0.088646)
		(layer "In4.Cu")
		(net "M_G_CPU0_SA_CA<3>")
	)
	(arc
		(start 383.937764 -255.223264)
		(mid 383.655062 -255.299006)
		(end 383.37236 -255.223264)
		(width 0.088646)
		(layer "In4.Cu")
		(net "M_G_CPU0_SA_CA<3>")
	)
	(arc
		(start 383.37236 -255.223264)
		(mid 383.185162 -255.173121)
		(end 382.997964 -255.223264)
		(width 0.088646)
		(layer "In4.Cu")
		(net "M_G_CPU0_SA_CA<3>")
	)
	(arc
		(start 379.613414 -255.223264)
		(mid 379.426216 -255.173121)
		(end 379.239018 -255.223264)
		(width 0.088646)
		(layer "In4.Cu")
		(net "M_G_CPU0_SA_CA<3>")
	)
	(arc
		(start 376.702066 -256.945384)
		(mid 376.677318 -257.069802)
		(end 376.606816 -257.175254)
		(width 0.088646)
		(layer "In4.Cu")
		(net "M_G_CPU0_SA_CA<3>")
	)
	(arc
		(start 377.733814 -255.223264)
		(mid 377.546616 -255.173121)
		(end 377.359418 -255.223264)
		(width 0.088646)
		(layer "In4.Cu")
		(net "M_G_CPU0_SA_CA<3>")
	)
	(arc
		(start 378.673614 -255.223264)
		(mid 378.486416 -255.173121)
		(end 378.299218 -255.223264)
		(width 0.088646)
		(layer "In4.Cu")
		(net "M_G_CPU0_SA_CA<3>")
	)
	(arc
		(start 381.118364 -255.223264)
		(mid 380.835916 -255.298879)
		(end 380.553468 -255.223264)
		(width 0.088646)
		(layer "In4.Cu")
		(net "M_G_CPU0_SA_CA<3>")
	)
	(arc
		(start 384.124962 -255.172464)
		(mid 384.028023 -255.185554)
		(end 383.937764 -255.223264)
		(width 0.088646)
		(layer "In4.Cu")
		(net "M_G_CPU0_SA_CA<3>")
	)
	(arc
		(start 382.058418 -255.223264)
		(mid 381.781605 -255.2991)
		(end 381.503174 -255.22936)
		(width 0.088646)
		(layer "In4.Cu")
		(net "M_G_CPU0_SA_CA<3>")
	)
	(arc
		(start 376.880628 -256.04216)
		(mid 376.749714 -256.17852)
		(end 376.702066 -256.361438)
		(width 0.088646)
		(layer "In4.Cu")
		(net "M_G_CPU0_SA_CA<3>")
	)
	(arc
		(start 380.545086 -255.218438)
		(mid 380.361324 -255.173038)
		(end 380.178818 -255.223264)
		(width 0.088646)
		(layer "In4.Cu")
		(net "M_G_CPU0_SA_CA<3>")
	)
	(arc
		(start 381.49276 -255.223264)
		(mid 381.305562 -255.173121)
		(end 381.118364 -255.223264)
		(width 0.088646)
		(layer "In4.Cu")
		(net "M_G_CPU0_SA_CA<3>")
	)
	(arc
		(start 382.997964 -255.223264)
		(mid 382.721405 -255.298973)
		(end 382.443228 -255.22936)
		(width 0.088646)
		(layer "In4.Cu")
		(net "M_G_CPU0_SA_CA<3>")
	)
	(segment
		(start 374.726962 -257.175)
		(end 374.727216 -257.175254)
		(width 0.20066)
		(layer "F.Cu")
		(net "M_G_CPU0_SA_CA<2>")
	)
	(segment
		(start 439.498232 -264.89152)
		(end 439.718704 -264.89152)
		(width 0.20066)
		(layer "F.Cu")
		(net "M_G_CPU0_SA_CA<2>")
	)
	(segment
		(start 442.038994 -264.903966)
		(end 442.455046 -264.903966)
		(width 0.20066)
		(layer "F.Cu")
		(net "M_G_CPU0_SA_CA<2>")
	)
	(segment
		(start 439.761122 -264.89152)
		(end 442.026548 -264.89152)
		(width 0.1016)
		(layer "F.Cu")
		(net "M_G_CPU0_SA_CA<2>")
	)
	(segment
		(start 374.726962 -256.639314)
		(end 374.726962 -257.175)
		(width 0.20066)
		(layer "F.Cu")
		(net "M_G_CPU0_SA_CA<2>")
	)
	(segment
		(start 438.31891 -263.996424)
		(end 438.603136 -263.996424)
		(width 0.20066)
		(layer "F.Cu")
		(net "M_G_CPU0_SA_CA<2>")
	)
	(segment
		(start 438.603136 -263.996424)
		(end 439.498232 -264.89152)
		(width 0.20066)
		(layer "F.Cu")
		(net "M_G_CPU0_SA_CA<2>")
	)
	(segment
		(start 436.928514 -264.466578)
		(end 437.848756 -264.466578)
		(width 0.20066)
		(layer "F.Cu")
		(net "M_G_CPU0_SA_CA<2>")
	)
	(segment
		(start 437.848756 -264.466578)
		(end 438.31891 -263.996424)
		(width 0.20066)
		(layer "F.Cu")
		(net "M_G_CPU0_SA_CA<2>")
	)
	(segment
		(start 444.47206 -264.466324)
		(end 444.472314 -264.466578)
		(width 0.20066)
		(layer "F.Cu")
		(net "M_G_CPU0_SA_CA<2>")
	)
	(segment
		(start 435.823614 -264.466578)
		(end 436.928514 -264.466578)
		(width 0.20066)
		(layer "F.Cu")
		(net "M_G_CPU0_SA_CA<2>")
	)
	(segment
		(start 442.455046 -264.903966)
		(end 442.892688 -264.466324)
		(width 0.20066)
		(layer "F.Cu")
		(net "M_G_CPU0_SA_CA<2>")
	)
	(segment
		(start 439.718704 -264.89152)
		(end 439.761122 -264.89152)
		(width 0.101854)
		(layer "F.Cu")
		(net "M_G_CPU0_SA_CA<2>")
	)
	(segment
		(start 442.026548 -264.89152)
		(end 442.038994 -264.903966)
		(width 0.1016)
		(layer "F.Cu")
		(net "M_G_CPU0_SA_CA<2>")
	)
	(segment
		(start 442.892688 -264.466324)
		(end 444.47206 -264.466324)
		(width 0.20066)
		(layer "F.Cu")
		(net "M_G_CPU0_SA_CA<2>")
	)
	(segment
		(start 378.768864 -255.05791)
		(end 378.754132 -255.049274)
		(width 0.088646)
		(layer "In4.Cu")
		(net "M_G_CPU0_SA_CA<2>")
	)
	(segment
		(start 385.4958 -254.089408)
		(end 385.250182 -254.335026)
		(width 0.18288)
		(layer "In4.Cu")
		(net "M_G_CPU0_SA_CA<2>")
	)
	(segment
		(start 424.373802 -261.492492)
		(end 423.521886 -260.640576)
		(width 0.18288)
		(layer "In4.Cu")
		(net "M_G_CPU0_SA_CA<2>")
	)
	(segment
		(start 376.33275 -256.680716)
		(end 376.32386 -256.685796)
		(width 0.088646)
		(layer "In4.Cu")
		(net "M_G_CPU0_SA_CA<2>")
	)
	(segment
		(start 431.637694 -262.249666)
		(end 430.880774 -261.492746)
		(width 0.18288)
		(layer "In4.Cu")
		(net "M_G_CPU0_SA_CA<2>")
	)
	(segment
		(start 387.275578 -254.586232)
		(end 386.778754 -254.089408)
		(width 0.18288)
		(layer "In4.Cu")
		(net "M_G_CPU0_SA_CA<2>")
	)
	(segment
		(start 394.93825 -256.237486)
		(end 393.076684 -256.237486)
		(width 0.18288)
		(layer "In4.Cu")
		(net "M_G_CPU0_SA_CA<2>")
	)
	(segment
		(start 406.91816 -259.119878)
		(end 404.779734 -259.119878)
		(width 0.18288)
		(layer "In4.Cu")
		(net "M_G_CPU0_SA_CA<2>")
	)
	(segment
		(start 380.648718 -255.05791)
		(end 380.633986 -255.049274)
		(width 0.088646)
		(layer "In4.Cu")
		(net "M_G_CPU0_SA_CA<2>")
	)
	(segment
		(start 386.778754 -254.089408)
		(end 385.4958 -254.089408)
		(width 0.18288)
		(layer "In4.Cu")
		(net "M_G_CPU0_SA_CA<2>")
	)
	(segment
		(start 423.521886 -260.640576)
		(end 411.297882 -260.640576)
		(width 0.18288)
		(layer "In4.Cu")
		(net "M_G_CPU0_SA_CA<2>")
	)
	(segment
		(start 379.717046 -255.062736)
		(end 379.708664 -255.05791)
		(width 0.088646)
		(layer "In4.Cu")
		(net "M_G_CPU0_SA_CA<2>")
	)
	(segment
		(start 377.829064 -255.05791)
		(end 377.814332 -255.049274)
		(width 0.088646)
		(layer "In4.Cu")
		(net "M_G_CPU0_SA_CA<2>")
	)
	(segment
		(start 384.636772 -254.335026)
		(end 383.966974 -255.004824)
		(width 0.088646)
		(layer "In4.Cu")
		(net "M_G_CPU0_SA_CA<2>")
	)
	(segment
		(start 376.981466 -255.525524)
		(end 376.981466 -255.547622)
		(width 0.088646)
		(layer "In4.Cu")
		(net "M_G_CPU0_SA_CA<2>")
	)
	(segment
		(start 435.823614 -264.466578)
		(end 435.190392 -263.833356)
		(width 0.18288)
		(layer "In4.Cu")
		(net "M_G_CPU0_SA_CA<2>")
	)
	(segment
		(start 430.880774 -261.492746)
		(end 426.900086 -261.492746)
		(width 0.18288)
		(layer "In4.Cu")
		(net "M_G_CPU0_SA_CA<2>")
	)
	(segment
		(start 407.45537 -259.657088)
		(end 406.91816 -259.119878)
		(width 0.18288)
		(layer "In4.Cu")
		(net "M_G_CPU0_SA_CA<2>")
	)
	(segment
		(start 376.802904 -255.8669)
		(end 376.794014 -255.87198)
		(width 0.088646)
		(layer "In4.Cu")
		(net "M_G_CPU0_SA_CA<2>")
	)
	(segment
		(start 404.779734 -259.119878)
		(end 401.01647 -255.356614)
		(width 0.18288)
		(layer "In4.Cu")
		(net "M_G_CPU0_SA_CA<2>")
	)
	(segment
		(start 435.190392 -263.833356)
		(end 434.087524 -263.833356)
		(width 0.18288)
		(layer "In4.Cu")
		(net "M_G_CPU0_SA_CA<2>")
	)
	(segment
		(start 408.628088 -259.948426)
		(end 408.33675 -259.657088)
		(width 0.18288)
		(layer "In4.Cu")
		(net "M_G_CPU0_SA_CA<2>")
	)
	(segment
		(start 397.064992 -255.356614)
		(end 394.93825 -256.237486)
		(width 0.18288)
		(layer "In4.Cu")
		(net "M_G_CPU0_SA_CA<2>")
	)
	(segment
		(start 389.0899 -254.586232)
		(end 387.275578 -254.586232)
		(width 0.18288)
		(layer "In4.Cu")
		(net "M_G_CPU0_SA_CA<2>")
	)
	(segment
		(start 410.605732 -259.948426)
		(end 408.628088 -259.948426)
		(width 0.18288)
		(layer "In4.Cu")
		(net "M_G_CPU0_SA_CA<2>")
	)
	(segment
		(start 375.38406 -256.685796)
		(end 375.306844 -256.730246)
		(width 0.088646)
		(layer "In4.Cu")
		(net "M_G_CPU0_SA_CA<2>")
	)
	(segment
		(start 432.503834 -262.249666)
		(end 431.637694 -262.249666)
		(width 0.18288)
		(layer "In4.Cu")
		(net "M_G_CPU0_SA_CA<2>")
	)
	(segment
		(start 408.33675 -259.657088)
		(end 407.45537 -259.657088)
		(width 0.18288)
		(layer "In4.Cu")
		(net "M_G_CPU0_SA_CA<2>")
	)
	(segment
		(start 381.033528 -255.051814)
		(end 381.023114 -255.05791)
		(width 0.088646)
		(layer "In4.Cu")
		(net "M_G_CPU0_SA_CA<2>")
	)
	(segment
		(start 376.794014 -255.87198)
		(end 376.781822 -255.879092)
		(width 0.088646)
		(layer "In4.Cu")
		(net "M_G_CPU0_SA_CA<2>")
	)
	(segment
		(start 401.01647 -255.356614)
		(end 397.064992 -255.356614)
		(width 0.18288)
		(layer "In4.Cu")
		(net "M_G_CPU0_SA_CA<2>")
	)
	(segment
		(start 426.899832 -261.492492)
		(end 424.373802 -261.492492)
		(width 0.18288)
		(layer "In4.Cu")
		(net "M_G_CPU0_SA_CA<2>")
	)
	(segment
		(start 385.250182 -254.335026)
		(end 384.920236 -254.335026)
		(width 0.18288)
		(layer "In4.Cu")
		(net "M_G_CPU0_SA_CA<2>")
	)
	(segment
		(start 411.297882 -260.640576)
		(end 410.605732 -259.948426)
		(width 0.18288)
		(layer "In4.Cu")
		(net "M_G_CPU0_SA_CA<2>")
	)
	(segment
		(start 379.708664 -255.05791)
		(end 379.693932 -255.049274)
		(width 0.088646)
		(layer "In4.Cu")
		(net "M_G_CPU0_SA_CA<2>")
	)
	(segment
		(start 434.087524 -263.833356)
		(end 432.503834 -262.249666)
		(width 0.18288)
		(layer "In4.Cu")
		(net "M_G_CPU0_SA_CA<2>")
	)
	(segment
		(start 384.920236 -254.335026)
		(end 384.636772 -254.335026)
		(width 0.088646)
		(layer "In4.Cu")
		(net "M_G_CPU0_SA_CA<2>")
	)
	(segment
		(start 382.528064 -255.05791)
		(end 382.513332 -255.049274)
		(width 0.088646)
		(layer "In4.Cu")
		(net "M_G_CPU0_SA_CA<2>")
	)
	(segment
		(start 426.900086 -261.492746)
		(end 426.899832 -261.492492)
		(width 0.18288)
		(layer "In4.Cu")
		(net "M_G_CPU0_SA_CA<2>")
	)
	(segment
		(start 393.076684 -256.237486)
		(end 389.0899 -254.586232)
		(width 0.18288)
		(layer "In4.Cu")
		(net "M_G_CPU0_SA_CA<2>")
	)
	(arc
		(start 376.32386 -256.685796)
		(mid 376.136662 -256.735939)
		(end 375.949464 -256.685796)
		(width 0.088646)
		(layer "In4.Cu")
		(net "M_G_CPU0_SA_CA<2>")
	)
	(arc
		(start 383.467864 -255.05791)
		(mid 383.185162 -254.982168)
		(end 382.90246 -255.05791)
		(width 0.088646)
		(layer "In4.Cu")
		(net "M_G_CPU0_SA_CA<2>")
	)
	(arc
		(start 376.781822 -255.879092)
		(mid 376.583594 -256.08494)
		(end 376.511312 -256.361438)
		(width 0.088646)
		(layer "In4.Cu")
		(net "M_G_CPU0_SA_CA<2>")
	)
	(arc
		(start 379.14326 -255.05791)
		(mid 378.956062 -255.108053)
		(end 378.768864 -255.05791)
		(width 0.088646)
		(layer "In4.Cu")
		(net "M_G_CPU0_SA_CA<2>")
	)
	(arc
		(start 381.023114 -255.05791)
		(mid 380.835916 -255.108053)
		(end 380.648718 -255.05791)
		(width 0.088646)
		(layer "In4.Cu")
		(net "M_G_CPU0_SA_CA<2>")
	)
	(arc
		(start 376.981466 -255.547622)
		(mid 376.933787 -255.730522)
		(end 376.802904 -255.8669)
		(width 0.088646)
		(layer "In4.Cu")
		(net "M_G_CPU0_SA_CA<2>")
	)
	(arc
		(start 376.511312 -256.361438)
		(mid 376.463633 -256.544338)
		(end 376.33275 -256.680716)
		(width 0.088646)
		(layer "In4.Cu")
		(net "M_G_CPU0_SA_CA<2>")
	)
	(arc
		(start 380.083314 -255.05791)
		(mid 379.900809 -255.108148)
		(end 379.717046 -255.062736)
		(width 0.088646)
		(layer "In4.Cu")
		(net "M_G_CPU0_SA_CA<2>")
	)
	(arc
		(start 381.588264 -255.05791)
		(mid 381.311705 -254.982201)
		(end 381.033528 -255.051814)
		(width 0.088646)
		(layer "In4.Cu")
		(net "M_G_CPU0_SA_CA<2>")
	)
	(arc
		(start 377.26366 -255.05791)
		(mid 377.062378 -255.255397)
		(end 376.981466 -255.525524)
		(width 0.088646)
		(layer "In4.Cu")
		(net "M_G_CPU0_SA_CA<2>")
	)
	(arc
		(start 380.633986 -255.049274)
		(mid 380.357545 -254.982108)
		(end 380.083314 -255.05791)
		(width 0.088646)
		(layer "In4.Cu")
		(net "M_G_CPU0_SA_CA<2>")
	)
	(arc
		(start 378.754132 -255.049274)
		(mid 378.477691 -254.982108)
		(end 378.20346 -255.05791)
		(width 0.088646)
		(layer "In4.Cu")
		(net "M_G_CPU0_SA_CA<2>")
	)
	(arc
		(start 383.966974 -255.004824)
		(mid 383.903019 -255.027614)
		(end 383.84226 -255.05791)
		(width 0.088646)
		(layer "In4.Cu")
		(net "M_G_CPU0_SA_CA<2>")
	)
	(arc
		(start 383.84226 -255.05791)
		(mid 383.655062 -255.108053)
		(end 383.467864 -255.05791)
		(width 0.088646)
		(layer "In4.Cu")
		(net "M_G_CPU0_SA_CA<2>")
	)
	(arc
		(start 375.306844 -256.730246)
		(mid 375.002463 -256.933775)
		(end 374.727216 -257.175254)
		(width 0.088646)
		(layer "In4.Cu")
		(net "M_G_CPU0_SA_CA<2>")
	)
	(arc
		(start 382.90246 -255.05791)
		(mid 382.715262 -255.108053)
		(end 382.528064 -255.05791)
		(width 0.088646)
		(layer "In4.Cu")
		(net "M_G_CPU0_SA_CA<2>")
	)
	(arc
		(start 379.693932 -255.049274)
		(mid 379.417491 -254.982108)
		(end 379.14326 -255.05791)
		(width 0.088646)
		(layer "In4.Cu")
		(net "M_G_CPU0_SA_CA<2>")
	)
	(arc
		(start 377.814332 -255.049274)
		(mid 377.537891 -254.982108)
		(end 377.26366 -255.05791)
		(width 0.088646)
		(layer "In4.Cu")
		(net "M_G_CPU0_SA_CA<2>")
	)
	(arc
		(start 375.949464 -256.685796)
		(mid 375.666762 -256.61002)
		(end 375.38406 -256.685796)
		(width 0.088646)
		(layer "In4.Cu")
		(net "M_G_CPU0_SA_CA<2>")
	)
	(arc
		(start 378.20346 -255.05791)
		(mid 378.016262 -255.108053)
		(end 377.829064 -255.05791)
		(width 0.088646)
		(layer "In4.Cu")
		(net "M_G_CPU0_SA_CA<2>")
	)
	(arc
		(start 381.96266 -255.05791)
		(mid 381.775462 -255.108053)
		(end 381.588264 -255.05791)
		(width 0.088646)
		(layer "In4.Cu")
		(net "M_G_CPU0_SA_CA<2>")
	)
	(arc
		(start 382.513332 -255.049274)
		(mid 382.236891 -254.982108)
		(end 381.96266 -255.05791)
		(width 0.088646)
		(layer "In4.Cu")
		(net "M_G_CPU0_SA_CA<2>")
	)
	(segment
		(start 447.025268 -264.884154)
		(end 447.45783 -265.316716)
		(width 0.20066)
		(layer "F.Cu")
		(net "M_G_CPU0_SA_CA<1>")
	)
	(segment
		(start 443.450726 -265.752326)
		(end 443.455552 -265.752326)
		(width 0.101854)
		(layer "F.Cu")
		(net "M_G_CPU0_SA_CA<1>")
	)
	(segment
		(start 443.455552 -265.752326)
		(end 443.46622 -265.741658)
		(width 0.1016)
		(layer "F.Cu")
		(net "M_G_CPU0_SA_CA<1>")
	)
	(segment
		(start 445.47536 -265.741658)
		(end 445.482726 -265.749024)
		(width 0.1016)
		(layer "F.Cu")
		(net "M_G_CPU0_SA_CA<1>")
	)
	(segment
		(start 377.076716 -257.45313)
		(end 377.076462 -257.98907)
		(width 0.20066)
		(layer "F.Cu")
		(net "M_G_CPU0_SA_CA<1>")
	)
	(segment
		(start 445.482726 -265.749024)
		(end 445.756792 -265.749024)
		(width 0.20066)
		(layer "F.Cu")
		(net "M_G_CPU0_SA_CA<1>")
	)
	(segment
		(start 447.45783 -265.316716)
		(end 448.572382 -265.316716)
		(width 0.20066)
		(layer "F.Cu")
		(net "M_G_CPU0_SA_CA<1>")
	)
	(segment
		(start 446.621662 -264.884154)
		(end 447.025268 -264.884154)
		(width 0.20066)
		(layer "F.Cu")
		(net "M_G_CPU0_SA_CA<1>")
	)
	(segment
		(start 442.664342 -265.316716)
		(end 443.099952 -265.752326)
		(width 0.20066)
		(layer "F.Cu")
		(net "M_G_CPU0_SA_CA<1>")
	)
	(segment
		(start 443.46622 -265.741658)
		(end 445.47536 -265.741658)
		(width 0.1016)
		(layer "F.Cu")
		(net "M_G_CPU0_SA_CA<1>")
	)
	(segment
		(start 439.847482 -265.316716)
		(end 441.028582 -265.316716)
		(width 0.20066)
		(layer "F.Cu")
		(net "M_G_CPU0_SA_CA<1>")
	)
	(segment
		(start 445.756792 -265.749024)
		(end 446.621662 -264.884154)
		(width 0.20066)
		(layer "F.Cu")
		(net "M_G_CPU0_SA_CA<1>")
	)
	(segment
		(start 443.099952 -265.752326)
		(end 443.450726 -265.752326)
		(width 0.20066)
		(layer "F.Cu")
		(net "M_G_CPU0_SA_CA<1>")
	)
	(segment
		(start 441.028582 -265.316716)
		(end 442.664342 -265.316716)
		(width 0.20066)
		(layer "F.Cu")
		(net "M_G_CPU0_SA_CA<1>")
	)
	(segment
		(start 407.774394 -262.460994)
		(end 406.80386 -261.49046)
		(width 0.18288)
		(layer "In4.Cu")
		(net "M_G_CPU0_SA_CA<1>")
	)
	(segment
		(start 395.316456 -257.243326)
		(end 392.875262 -257.243326)
		(width 0.18288)
		(layer "In4.Cu")
		(net "M_G_CPU0_SA_CA<1>")
	)
	(segment
		(start 428.836074 -263.829546)
		(end 428.526194 -264.139426)
		(width 0.18288)
		(layer "In4.Cu")
		(net "M_G_CPU0_SA_CA<1>")
	)
	(segment
		(start 400.15668 -256.850134)
		(end 396.265654 -256.850134)
		(width 0.18288)
		(layer "In4.Cu")
		(net "M_G_CPU0_SA_CA<1>")
	)
	(segment
		(start 377.359418 -256.850896)
		(end 377.350528 -256.855976)
		(width 0.088646)
		(layer "In4.Cu")
		(net "M_G_CPU0_SA_CA<1>")
	)
	(segment
		(start 424.198796 -264.042652)
		(end 423.344594 -263.18845)
		(width 0.18288)
		(layer "In4.Cu")
		(net "M_G_CPU0_SA_CA<1>")
	)
	(segment
		(start 429.979074 -263.829546)
		(end 428.836074 -263.829546)
		(width 0.18288)
		(layer "In4.Cu")
		(net "M_G_CPU0_SA_CA<1>")
	)
	(segment
		(start 389.1534 -255.7018)
		(end 387.671818 -255.7018)
		(width 0.18288)
		(layer "In4.Cu")
		(net "M_G_CPU0_SA_CA<1>")
	)
	(segment
		(start 396.265654 -256.850134)
		(end 395.316456 -257.243326)
		(width 0.18288)
		(layer "In4.Cu")
		(net "M_G_CPU0_SA_CA<1>")
	)
	(segment
		(start 420.05504 -263.18845)
		(end 419.84676 -263.39673)
		(width 0.18288)
		(layer "In4.Cu")
		(net "M_G_CPU0_SA_CA<1>")
	)
	(segment
		(start 387.304788 -255.7018)
		(end 387.056376 -255.950212)
		(width 0.088646)
		(layer "In4.Cu")
		(net "M_G_CPU0_SA_CA<1>")
	)
	(segment
		(start 436.857394 -265.942826)
		(end 436.207916 -266.592304)
		(width 0.18288)
		(layer "In4.Cu")
		(net "M_G_CPU0_SA_CA<1>")
	)
	(segment
		(start 428.526194 -264.139426)
		(end 427.441106 -264.139426)
		(width 0.18288)
		(layer "In4.Cu")
		(net "M_G_CPU0_SA_CA<1>")
	)
	(segment
		(start 432.646074 -264.985246)
		(end 431.904394 -264.985246)
		(width 0.18288)
		(layer "In4.Cu")
		(net "M_G_CPU0_SA_CA<1>")
	)
	(segment
		(start 408.843226 -262.179054)
		(end 408.561286 -262.460994)
		(width 0.18288)
		(layer "In4.Cu")
		(net "M_G_CPU0_SA_CA<1>")
	)
	(segment
		(start 416.389566 -263.157716)
		(end 412.667958 -263.157716)
		(width 0.18288)
		(layer "In4.Cu")
		(net "M_G_CPU0_SA_CA<1>")
	)
	(segment
		(start 427.20895 -263.90727)
		(end 425.98975 -263.90727)
		(width 0.18288)
		(layer "In4.Cu")
		(net "M_G_CPU0_SA_CA<1>")
	)
	(segment
		(start 384.672078 -256.112772)
		(end 384.124962 -256.112772)
		(width 0.088646)
		(layer "In4.Cu")
		(net "M_G_CPU0_SA_CA<1>")
	)
	(segment
		(start 423.344594 -263.18845)
		(end 420.05504 -263.18845)
		(width 0.18288)
		(layer "In4.Cu")
		(net "M_G_CPU0_SA_CA<1>")
	)
	(segment
		(start 377.171966 -257.485642)
		(end 377.076462 -257.98907)
		(width 0.088646)
		(layer "In4.Cu")
		(net "M_G_CPU0_SA_CA<1>")
	)
	(segment
		(start 439.847482 -265.316716)
		(end 439.221372 -265.942826)
		(width 0.18288)
		(layer "In4.Cu")
		(net "M_G_CPU0_SA_CA<1>")
	)
	(segment
		(start 431.904394 -264.985246)
		(end 431.063654 -264.144506)
		(width 0.18288)
		(layer "In4.Cu")
		(net "M_G_CPU0_SA_CA<1>")
	)
	(segment
		(start 404.797006 -261.49046)
		(end 400.15668 -256.850134)
		(width 0.18288)
		(layer "In4.Cu")
		(net "M_G_CPU0_SA_CA<1>")
	)
	(segment
		(start 378.768864 -256.03708)
		(end 378.754132 -256.045716)
		(width 0.088646)
		(layer "In4.Cu")
		(net "M_G_CPU0_SA_CA<1>")
	)
	(segment
		(start 434.253132 -266.592304)
		(end 432.646074 -264.985246)
		(width 0.18288)
		(layer "In4.Cu")
		(net "M_G_CPU0_SA_CA<1>")
	)
	(segment
		(start 431.063654 -264.144506)
		(end 430.294034 -264.144506)
		(width 0.18288)
		(layer "In4.Cu")
		(net "M_G_CPU0_SA_CA<1>")
	)
	(segment
		(start 379.708664 -256.03708)
		(end 379.693932 -256.045716)
		(width 0.088646)
		(layer "In4.Cu")
		(net "M_G_CPU0_SA_CA<1>")
	)
	(segment
		(start 436.207916 -266.592304)
		(end 434.253132 -266.592304)
		(width 0.18288)
		(layer "In4.Cu")
		(net "M_G_CPU0_SA_CA<1>")
	)
	(segment
		(start 416.62858 -263.39673)
		(end 416.389566 -263.157716)
		(width 0.18288)
		(layer "In4.Cu")
		(net "M_G_CPU0_SA_CA<1>")
	)
	(segment
		(start 439.221372 -265.942826)
		(end 436.857394 -265.942826)
		(width 0.18288)
		(layer "In4.Cu")
		(net "M_G_CPU0_SA_CA<1>")
	)
	(segment
		(start 425.98975 -263.90727)
		(end 425.854368 -264.042652)
		(width 0.18288)
		(layer "In4.Cu")
		(net "M_G_CPU0_SA_CA<1>")
	)
	(segment
		(start 382.528064 -256.03708)
		(end 382.513332 -256.045716)
		(width 0.088646)
		(layer "In4.Cu")
		(net "M_G_CPU0_SA_CA<1>")
	)
	(segment
		(start 419.84676 -263.39673)
		(end 416.62858 -263.39673)
		(width 0.18288)
		(layer "In4.Cu")
		(net "M_G_CPU0_SA_CA<1>")
	)
	(segment
		(start 427.441106 -264.139426)
		(end 427.20895 -263.90727)
		(width 0.18288)
		(layer "In4.Cu")
		(net "M_G_CPU0_SA_CA<1>")
	)
	(segment
		(start 387.056376 -255.950212)
		(end 384.834638 -255.950212)
		(width 0.088646)
		(layer "In4.Cu")
		(net "M_G_CPU0_SA_CA<1>")
	)
	(segment
		(start 377.641866 -256.352802)
		(end 377.641866 -256.371344)
		(width 0.088646)
		(layer "In4.Cu")
		(net "M_G_CPU0_SA_CA<1>")
	)
	(segment
		(start 408.561286 -262.460994)
		(end 407.774394 -262.460994)
		(width 0.18288)
		(layer "In4.Cu")
		(net "M_G_CPU0_SA_CA<1>")
	)
	(segment
		(start 409.993846 -262.179054)
		(end 408.843226 -262.179054)
		(width 0.18288)
		(layer "In4.Cu")
		(net "M_G_CPU0_SA_CA<1>")
	)
	(segment
		(start 392.875262 -257.243326)
		(end 389.1534 -255.7018)
		(width 0.18288)
		(layer "In4.Cu")
		(net "M_G_CPU0_SA_CA<1>")
	)
	(segment
		(start 412.667958 -263.157716)
		(end 412.39567 -263.430004)
		(width 0.18288)
		(layer "In4.Cu")
		(net "M_G_CPU0_SA_CA<1>")
	)
	(segment
		(start 425.854368 -264.042652)
		(end 424.198796 -264.042652)
		(width 0.18288)
		(layer "In4.Cu")
		(net "M_G_CPU0_SA_CA<1>")
	)
	(segment
		(start 430.294034 -264.144506)
		(end 429.979074 -263.829546)
		(width 0.18288)
		(layer "In4.Cu")
		(net "M_G_CPU0_SA_CA<1>")
	)
	(segment
		(start 384.834638 -255.950212)
		(end 384.672078 -256.112772)
		(width 0.088646)
		(layer "In4.Cu")
		(net "M_G_CPU0_SA_CA<1>")
	)
	(segment
		(start 377.171966 -257.175254)
		(end 377.171966 -257.485642)
		(width 0.088646)
		(layer "In4.Cu")
		(net "M_G_CPU0_SA_CA<1>")
	)
	(segment
		(start 387.671818 -255.7018)
		(end 387.304788 -255.7018)
		(width 0.088646)
		(layer "In4.Cu")
		(net "M_G_CPU0_SA_CA<1>")
	)
	(segment
		(start 406.80386 -261.49046)
		(end 404.797006 -261.49046)
		(width 0.18288)
		(layer "In4.Cu")
		(net "M_G_CPU0_SA_CA<1>")
	)
	(segment
		(start 412.39567 -263.430004)
		(end 411.244796 -263.430004)
		(width 0.18288)
		(layer "In4.Cu")
		(net "M_G_CPU0_SA_CA<1>")
	)
	(segment
		(start 411.244796 -263.430004)
		(end 409.993846 -262.179054)
		(width 0.18288)
		(layer "In4.Cu")
		(net "M_G_CPU0_SA_CA<1>")
	)
	(arc
		(start 380.08306 -256.03708)
		(mid 379.895862 -255.986937)
		(end 379.708664 -256.03708)
		(width 0.088646)
		(layer "In4.Cu")
		(net "M_G_CPU0_SA_CA<1>")
	)
	(arc
		(start 382.90246 -256.03708)
		(mid 382.715262 -255.986937)
		(end 382.528064 -256.03708)
		(width 0.088646)
		(layer "In4.Cu")
		(net "M_G_CPU0_SA_CA<1>")
	)
	(arc
		(start 378.20346 -256.03708)
		(mid 378.016262 -255.986937)
		(end 377.829064 -256.03708)
		(width 0.088646)
		(layer "In4.Cu")
		(net "M_G_CPU0_SA_CA<1>")
	)
	(arc
		(start 377.350528 -256.855976)
		(mid 377.219614 -256.992336)
		(end 377.171966 -257.175254)
		(width 0.088646)
		(layer "In4.Cu")
		(net "M_G_CPU0_SA_CA<1>")
	)
	(arc
		(start 377.641866 -256.371344)
		(mid 377.563755 -256.648293)
		(end 377.359418 -256.850896)
		(width 0.088646)
		(layer "In4.Cu")
		(net "M_G_CPU0_SA_CA<1>")
	)
	(arc
		(start 381.588264 -256.03708)
		(mid 381.305562 -256.112856)
		(end 381.02286 -256.03708)
		(width 0.088646)
		(layer "In4.Cu")
		(net "M_G_CPU0_SA_CA<1>")
	)
	(arc
		(start 381.96266 -256.03708)
		(mid 381.775462 -255.986937)
		(end 381.588264 -256.03708)
		(width 0.088646)
		(layer "In4.Cu")
		(net "M_G_CPU0_SA_CA<1>")
	)
	(arc
		(start 384.124962 -256.112772)
		(mid 383.978618 -256.093564)
		(end 383.84226 -256.03708)
		(width 0.088646)
		(layer "In4.Cu")
		(net "M_G_CPU0_SA_CA<1>")
	)
	(arc
		(start 383.84226 -256.03708)
		(mid 383.655062 -255.986937)
		(end 383.467864 -256.03708)
		(width 0.088646)
		(layer "In4.Cu")
		(net "M_G_CPU0_SA_CA<1>")
	)
	(arc
		(start 380.648464 -256.03708)
		(mid 380.365762 -256.112856)
		(end 380.08306 -256.03708)
		(width 0.088646)
		(layer "In4.Cu")
		(net "M_G_CPU0_SA_CA<1>")
	)
	(arc
		(start 381.02286 -256.03708)
		(mid 380.835662 -255.986937)
		(end 380.648464 -256.03708)
		(width 0.088646)
		(layer "In4.Cu")
		(net "M_G_CPU0_SA_CA<1>")
	)
	(arc
		(start 379.693932 -256.045716)
		(mid 379.417457 -256.113036)
		(end 379.14326 -256.03708)
		(width 0.088646)
		(layer "In4.Cu")
		(net "M_G_CPU0_SA_CA<1>")
	)
	(arc
		(start 383.467864 -256.03708)
		(mid 383.185162 -256.112856)
		(end 382.90246 -256.03708)
		(width 0.088646)
		(layer "In4.Cu")
		(net "M_G_CPU0_SA_CA<1>")
	)
	(arc
		(start 382.513332 -256.045716)
		(mid 382.236857 -256.113036)
		(end 381.96266 -256.03708)
		(width 0.088646)
		(layer "In4.Cu")
		(net "M_G_CPU0_SA_CA<1>")
	)
	(arc
		(start 378.754132 -256.045716)
		(mid 378.477657 -256.113036)
		(end 378.20346 -256.03708)
		(width 0.088646)
		(layer "In4.Cu")
		(net "M_G_CPU0_SA_CA<1>")
	)
	(arc
		(start 379.14326 -256.03708)
		(mid 378.956062 -255.986937)
		(end 378.768864 -256.03708)
		(width 0.088646)
		(layer "In4.Cu")
		(net "M_G_CPU0_SA_CA<1>")
	)
	(arc
		(start 377.829064 -256.03708)
		(mid 377.694131 -256.170434)
		(end 377.641866 -256.352802)
		(width 0.088646)
		(layer "In4.Cu")
		(net "M_G_CPU0_SA_CA<1>")
	)
	(segment
		(start 438.488328 -265.672316)
		(end 438.813702 -265.672316)
		(width 0.20066)
		(layer "F.Cu")
		(net "M_G_CPU0_SA_CA<0>")
	)
	(segment
		(start 374.257316 -257.45313)
		(end 374.257062 -257.98907)
		(width 0.20066)
		(layer "F.Cu")
		(net "M_G_CPU0_SA_CA<0>")
	)
	(segment
		(start 438.813702 -265.672316)
		(end 439.732928 -266.591542)
		(width 0.20066)
		(layer "F.Cu")
		(net "M_G_CPU0_SA_CA<0>")
	)
	(segment
		(start 439.84037 -266.591542)
		(end 439.854086 -266.591542)
		(width 0.101854)
		(layer "F.Cu")
		(net "M_G_CPU0_SA_CA<0>")
	)
	(segment
		(start 442.455046 -266.603988)
		(end 442.892688 -266.166346)
		(width 0.20066)
		(layer "F.Cu")
		(net "M_G_CPU0_SA_CA<0>")
	)
	(segment
		(start 436.928514 -266.1666)
		(end 437.994044 -266.1666)
		(width 0.20066)
		(layer "F.Cu")
		(net "M_G_CPU0_SA_CA<0>")
	)
	(segment
		(start 439.732928 -266.591542)
		(end 439.84037 -266.591542)
		(width 0.20066)
		(layer "F.Cu")
		(net "M_G_CPU0_SA_CA<0>")
	)
	(segment
		(start 444.47206 -266.166346)
		(end 444.472314 -266.1666)
		(width 0.20066)
		(layer "F.Cu")
		(net "M_G_CPU0_SA_CA<0>")
	)
	(segment
		(start 442.892688 -266.166346)
		(end 444.47206 -266.166346)
		(width 0.20066)
		(layer "F.Cu")
		(net "M_G_CPU0_SA_CA<0>")
	)
	(segment
		(start 435.823614 -266.1666)
		(end 436.928514 -266.1666)
		(width 0.20066)
		(layer "F.Cu")
		(net "M_G_CPU0_SA_CA<0>")
	)
	(segment
		(start 442.026548 -266.591542)
		(end 442.038994 -266.603988)
		(width 0.1016)
		(layer "F.Cu")
		(net "M_G_CPU0_SA_CA<0>")
	)
	(segment
		(start 439.854086 -266.591542)
		(end 442.026548 -266.591542)
		(width 0.1016)
		(layer "F.Cu")
		(net "M_G_CPU0_SA_CA<0>")
	)
	(segment
		(start 442.038994 -266.603988)
		(end 442.455046 -266.603988)
		(width 0.20066)
		(layer "F.Cu")
		(net "M_G_CPU0_SA_CA<0>")
	)
	(segment
		(start 437.994044 -266.1666)
		(end 438.488328 -265.672316)
		(width 0.20066)
		(layer "F.Cu")
		(net "M_G_CPU0_SA_CA<0>")
	)
	(segment
		(start 379.623828 -255.865884)
		(end 379.613414 -255.87198)
		(width 0.088646)
		(layer "In4.Cu")
		(net "M_G_CPU0_SA_CA<0>")
	)
	(segment
		(start 381.503174 -255.865884)
		(end 381.49276 -255.87198)
		(width 0.088646)
		(layer "In4.Cu")
		(net "M_G_CPU0_SA_CA<0>")
	)
	(segment
		(start 409.487116 -261.565136)
		(end 409.23464 -261.31266)
		(width 0.18288)
		(layer "In4.Cu")
		(net "M_G_CPU0_SA_CA<0>")
	)
	(segment
		(start 427.484794 -263.326626)
		(end 426.25899 -263.326626)
		(width 0.18288)
		(layer "In4.Cu")
		(net "M_G_CPU0_SA_CA<0>")
	)
	(segment
		(start 378.688346 -255.863344)
		(end 378.673614 -255.87198)
		(width 0.088646)
		(layer "In4.Cu")
		(net "M_G_CPU0_SA_CA<0>")
	)
	(segment
		(start 427.763686 -263.047734)
		(end 427.484794 -263.326626)
		(width 0.18288)
		(layer "In4.Cu")
		(net "M_G_CPU0_SA_CA<0>")
	)
	(segment
		(start 409.23464 -261.31266)
		(end 407.622756 -261.31266)
		(width 0.18288)
		(layer "In4.Cu")
		(net "M_G_CPU0_SA_CA<0>")
	)
	(segment
		(start 384.93065 -255.154684)
		(end 384.800094 -255.28524)
		(width 0.088646)
		(layer "In4.Cu")
		(net "M_G_CPU0_SA_CA<0>")
	)
	(segment
		(start 434.358034 -265.612626)
		(end 433.557934 -264.812526)
		(width 0.18288)
		(layer "In4.Cu")
		(net "M_G_CPU0_SA_CA<0>")
	)
	(segment
		(start 411.16885 -262.340852)
		(end 410.393134 -261.565136)
		(width 0.18288)
		(layer "In4.Cu")
		(net "M_G_CPU0_SA_CA<0>")
	)
	(segment
		(start 435.823614 -266.1666)
		(end 435.26964 -265.612626)
		(width 0.18288)
		(layer "In4.Cu")
		(net "M_G_CPU0_SA_CA<0>")
	)
	(segment
		(start 426.25899 -263.326626)
		(end 426.127418 -263.195054)
		(width 0.18288)
		(layer "In4.Cu")
		(net "M_G_CPU0_SA_CA<0>")
	)
	(segment
		(start 377.748546 -255.863344)
		(end 377.733814 -255.87198)
		(width 0.088646)
		(layer "In4.Cu")
		(net "M_G_CPU0_SA_CA<0>")
	)
	(segment
		(start 407.199592 -260.889496)
		(end 404.907242 -260.889496)
		(width 0.18288)
		(layer "In4.Cu")
		(net "M_G_CPU0_SA_CA<0>")
	)
	(segment
		(start 386.690108 -255.366266)
		(end 386.478526 -255.154684)
		(width 0.088646)
		(layer "In4.Cu")
		(net "M_G_CPU0_SA_CA<0>")
	)
	(segment
		(start 384.785108 -255.305052)
		(end 384.531616 -255.761744)
		(width 0.088646)
		(layer "In4.Cu")
		(net "M_G_CPU0_SA_CA<0>")
	)
	(segment
		(start 400.37004 -256.352294)
		(end 396.55623 -256.352294)
		(width 0.18288)
		(layer "In4.Cu")
		(net "M_G_CPU0_SA_CA<0>")
	)
	(segment
		(start 376.802904 -257.494532)
		(end 376.794014 -257.499612)
		(width 0.088646)
		(layer "In4.Cu")
		(net "M_G_CPU0_SA_CA<0>")
	)
	(segment
		(start 430.778666 -263.047734)
		(end 427.763686 -263.047734)
		(width 0.18288)
		(layer "In4.Cu")
		(net "M_G_CPU0_SA_CA<0>")
	)
	(segment
		(start 407.622756 -261.31266)
		(end 407.199592 -260.889496)
		(width 0.18288)
		(layer "In4.Cu")
		(net "M_G_CPU0_SA_CA<0>")
	)
	(segment
		(start 435.26964 -265.612626)
		(end 434.358034 -265.612626)
		(width 0.18288)
		(layer "In4.Cu")
		(net "M_G_CPU0_SA_CA<0>")
	)
	(segment
		(start 431.667158 -263.936226)
		(end 430.778666 -263.047734)
		(width 0.18288)
		(layer "In4.Cu")
		(net "M_G_CPU0_SA_CA<0>")
	)
	(segment
		(start 410.393134 -261.565136)
		(end 409.487116 -261.565136)
		(width 0.18288)
		(layer "In4.Cu")
		(net "M_G_CPU0_SA_CA<0>")
	)
	(segment
		(start 404.907242 -260.889496)
		(end 400.37004 -256.352294)
		(width 0.18288)
		(layer "In4.Cu")
		(net "M_G_CPU0_SA_CA<0>")
	)
	(segment
		(start 374.599962 -257.646678)
		(end 374.257062 -257.98907)
		(width 0.088646)
		(layer "In4.Cu")
		(net "M_G_CPU0_SA_CA<0>")
	)
	(segment
		(start 376.981466 -257.165348)
		(end 376.981466 -257.175254)
		(width 0.088646)
		(layer "In4.Cu")
		(net "M_G_CPU0_SA_CA<0>")
	)
	(segment
		(start 424.394122 -263.195054)
		(end 423.53992 -262.340852)
		(width 0.18288)
		(layer "In4.Cu")
		(net "M_G_CPU0_SA_CA<0>")
	)
	(segment
		(start 386.478526 -255.154684)
		(end 384.93065 -255.154684)
		(width 0.088646)
		(layer "In4.Cu")
		(net "M_G_CPU0_SA_CA<0>")
	)
	(segment
		(start 377.733814 -255.87198)
		(end 377.727718 -255.875536)
		(width 0.088646)
		(layer "In4.Cu")
		(net "M_G_CPU0_SA_CA<0>")
	)
	(segment
		(start 426.127418 -263.195054)
		(end 424.394122 -263.195054)
		(width 0.18288)
		(layer "In4.Cu")
		(net "M_G_CPU0_SA_CA<0>")
	)
	(segment
		(start 396.55623 -256.352294)
		(end 395.214856 -256.908046)
		(width 0.18288)
		(layer "In4.Cu")
		(net "M_G_CPU0_SA_CA<0>")
	)
	(segment
		(start 433.557934 -264.802874)
		(end 432.691286 -263.936226)
		(width 0.18288)
		(layer "In4.Cu")
		(net "M_G_CPU0_SA_CA<0>")
	)
	(segment
		(start 377.451112 -256.361438)
		(end 377.451112 -256.370074)
		(width 0.088646)
		(layer "In4.Cu")
		(net "M_G_CPU0_SA_CA<0>")
	)
	(segment
		(start 382.443228 -255.865884)
		(end 382.432814 -255.87198)
		(width 0.088646)
		(layer "In4.Cu")
		(net "M_G_CPU0_SA_CA<0>")
	)
	(segment
		(start 423.53992 -262.340852)
		(end 411.16885 -262.340852)
		(width 0.18288)
		(layer "In4.Cu")
		(net "M_G_CPU0_SA_CA<0>")
	)
	(segment
		(start 433.557934 -264.812526)
		(end 433.557934 -264.802874)
		(width 0.18288)
		(layer "In4.Cu")
		(net "M_G_CPU0_SA_CA<0>")
	)
	(segment
		(start 384.26517 -255.919478)
		(end 384.16865 -255.919478)
		(width 0.088646)
		(layer "In4.Cu")
		(net "M_G_CPU0_SA_CA<0>")
	)
	(segment
		(start 432.691286 -263.936226)
		(end 431.667158 -263.936226)
		(width 0.18288)
		(layer "In4.Cu")
		(net "M_G_CPU0_SA_CA<0>")
	)
	(segment
		(start 387.671818 -255.366266)
		(end 386.690108 -255.366266)
		(width 0.088646)
		(layer "In4.Cu")
		(net "M_G_CPU0_SA_CA<0>")
	)
	(segment
		(start 389.219948 -255.366266)
		(end 387.671818 -255.366266)
		(width 0.18288)
		(layer "In4.Cu")
		(net "M_G_CPU0_SA_CA<0>")
	)
	(segment
		(start 392.942064 -256.908046)
		(end 389.219948 -255.366266)
		(width 0.18288)
		(layer "In4.Cu")
		(net "M_G_CPU0_SA_CA<0>")
	)
	(segment
		(start 395.214856 -256.908046)
		(end 392.942064 -256.908046)
		(width 0.18288)
		(layer "In4.Cu")
		(net "M_G_CPU0_SA_CA<0>")
	)
	(arc
		(start 375.391426 -257.449066)
		(mid 375.242844 -257.39996)
		(end 375.086372 -257.398012)
		(width 0.088646)
		(layer "In4.Cu")
		(net "M_G_CPU0_SA_CA<0>")
	)
	(arc
		(start 378.673614 -255.87198)
		(mid 378.486416 -255.922123)
		(end 378.299218 -255.87198)
		(width 0.088646)
		(layer "In4.Cu")
		(net "M_G_CPU0_SA_CA<0>")
	)
	(arc
		(start 381.118364 -255.87198)
		(mid 380.835662 -255.796204)
		(end 380.55296 -255.87198)
		(width 0.088646)
		(layer "In4.Cu")
		(net "M_G_CPU0_SA_CA<0>")
	)
	(arc
		(start 376.794014 -257.499612)
		(mid 376.606816 -257.549755)
		(end 376.419618 -257.499612)
		(width 0.088646)
		(layer "In4.Cu")
		(net "M_G_CPU0_SA_CA<0>")
	)
	(arc
		(start 383.37236 -255.87198)
		(mid 383.185162 -255.922123)
		(end 382.997964 -255.87198)
		(width 0.088646)
		(layer "In4.Cu")
		(net "M_G_CPU0_SA_CA<0>")
	)
	(arc
		(start 384.800094 -255.28524)
		(mid 384.791926 -255.294633)
		(end 384.785108 -255.305052)
		(width 0.088646)
		(layer "In4.Cu")
		(net "M_G_CPU0_SA_CA<0>")
	)
	(arc
		(start 378.299218 -255.87198)
		(mid 378.025019 -255.796145)
		(end 377.748546 -255.863344)
		(width 0.088646)
		(layer "In4.Cu")
		(net "M_G_CPU0_SA_CA<0>")
	)
	(arc
		(start 375.086372 -257.398012)
		(mid 375.031625 -257.414912)
		(end 374.984518 -257.447542)
		(width 0.088646)
		(layer "In4.Cu")
		(net "M_G_CPU0_SA_CA<0>")
	)
	(arc
		(start 382.997964 -255.87198)
		(mid 382.721405 -255.796237)
		(end 382.443228 -255.865884)
		(width 0.088646)
		(layer "In4.Cu")
		(net "M_G_CPU0_SA_CA<0>")
	)
	(arc
		(start 380.178564 -255.87198)
		(mid 379.902005 -255.796237)
		(end 379.623828 -255.865884)
		(width 0.088646)
		(layer "In4.Cu")
		(net "M_G_CPU0_SA_CA<0>")
	)
	(arc
		(start 383.911856 -255.857756)
		(mid 383.640317 -255.796386)
		(end 383.37236 -255.87198)
		(width 0.088646)
		(layer "In4.Cu")
		(net "M_G_CPU0_SA_CA<0>")
	)
	(arc
		(start 374.79605 -257.5433)
		(mid 374.690196 -257.580166)
		(end 374.599962 -257.646678)
		(width 0.088646)
		(layer "In4.Cu")
		(net "M_G_CPU0_SA_CA<0>")
	)
	(arc
		(start 377.263914 -256.685796)
		(mid 377.059579 -256.888401)
		(end 376.981466 -257.165348)
		(width 0.088646)
		(layer "In4.Cu")
		(net "M_G_CPU0_SA_CA<0>")
	)
	(arc
		(start 381.49276 -255.87198)
		(mid 381.305562 -255.922123)
		(end 381.118364 -255.87198)
		(width 0.088646)
		(layer "In4.Cu")
		(net "M_G_CPU0_SA_CA<0>")
	)
	(arc
		(start 384.531616 -255.761744)
		(mid 384.419958 -255.877045)
		(end 384.26517 -255.919478)
		(width 0.088646)
		(layer "In4.Cu")
		(net "M_G_CPU0_SA_CA<0>")
	)
	(arc
		(start 377.451112 -256.370074)
		(mid 377.398842 -256.552439)
		(end 377.263914 -256.685796)
		(width 0.088646)
		(layer "In4.Cu")
		(net "M_G_CPU0_SA_CA<0>")
	)
	(arc
		(start 382.058418 -255.87198)
		(mid 381.781605 -255.79611)
		(end 381.503174 -255.865884)
		(width 0.088646)
		(layer "In4.Cu")
		(net "M_G_CPU0_SA_CA<0>")
	)
	(arc
		(start 384.16865 -255.919478)
		(mid 384.036595 -255.903833)
		(end 383.911856 -255.857756)
		(width 0.088646)
		(layer "In4.Cu")
		(net "M_G_CPU0_SA_CA<0>")
	)
	(arc
		(start 379.613414 -255.87198)
		(mid 379.426216 -255.922123)
		(end 379.239018 -255.87198)
		(width 0.088646)
		(layer "In4.Cu")
		(net "M_G_CPU0_SA_CA<0>")
	)
	(arc
		(start 375.468642 -257.493008)
		(mid 375.4305 -257.470218)
		(end 375.391426 -257.449066)
		(width 0.088646)
		(layer "In4.Cu")
		(net "M_G_CPU0_SA_CA<0>")
	)
	(arc
		(start 375.891552 -257.479292)
		(mid 375.882197 -257.483704)
		(end 375.872756 -257.487928)
		(width 0.088646)
		(layer "In4.Cu")
		(net "M_G_CPU0_SA_CA<0>")
	)
	(arc
		(start 375.872756 -257.487928)
		(mid 375.671447 -257.549656)
		(end 375.468642 -257.493008)
		(width 0.088646)
		(layer "In4.Cu")
		(net "M_G_CPU0_SA_CA<0>")
	)
	(arc
		(start 380.55296 -255.87198)
		(mid 380.365762 -255.922123)
		(end 380.178564 -255.87198)
		(width 0.088646)
		(layer "In4.Cu")
		(net "M_G_CPU0_SA_CA<0>")
	)
	(arc
		(start 374.984518 -257.447542)
		(mid 374.897194 -257.509033)
		(end 374.79605 -257.5433)
		(width 0.088646)
		(layer "In4.Cu")
		(net "M_G_CPU0_SA_CA<0>")
	)
	(arc
		(start 376.981466 -257.175254)
		(mid 376.933787 -257.358154)
		(end 376.802904 -257.494532)
		(width 0.088646)
		(layer "In4.Cu")
		(net "M_G_CPU0_SA_CA<0>")
	)
	(arc
		(start 376.419618 -257.499612)
		(mid 376.158109 -257.423998)
		(end 375.891552 -257.479292)
		(width 0.088646)
		(layer "In4.Cu")
		(net "M_G_CPU0_SA_CA<0>")
	)
	(arc
		(start 382.432814 -255.87198)
		(mid 382.245616 -255.922123)
		(end 382.058418 -255.87198)
		(width 0.088646)
		(layer "In4.Cu")
		(net "M_G_CPU0_SA_CA<0>")
	)
	(arc
		(start 379.239018 -255.87198)
		(mid 378.964819 -255.796145)
		(end 378.688346 -255.863344)
		(width 0.088646)
		(layer "In4.Cu")
		(net "M_G_CPU0_SA_CA<0>")
	)
	(arc
		(start 377.727718 -255.875536)
		(mid 377.525131 -256.081887)
		(end 377.451112 -256.361438)
		(width 0.088646)
		(layer "In4.Cu")
		(net "M_G_CPU0_SA_CA<0>")
	)
	(segment
		(start 439.923682 -260.21665)
		(end 441.028582 -260.21665)
		(width 0.20066)
		(layer "F.Cu")
		(net "M_G_CPU0_CLK_DP<1>")
	)
	(segment
		(start 374.14708 -250.15571)
		(end 374.14708 -249.620024)
		(width 0.20066)
		(layer "F.Cu")
		(net "M_G_CPU0_CLK_DP<1>")
	)
	(segment
		(start 374.147334 -250.155964)
		(end 374.14708 -250.15571)
		(width 0.20066)
		(layer "F.Cu")
		(net "M_G_CPU0_CLK_DP<1>")
	)
	(segment
		(start 434.00218 -256.905506)
		(end 413.461708 -256.905506)
		(width 0.18288)
		(layer "In4.Cu")
		(net "M_G_CPU0_CLK_DP<1>")
	)
	(segment
		(start 393.412472 -254.560832)
		(end 392.251184 -254.079756)
		(width 0.18288)
		(layer "In4.Cu")
		(net "M_G_CPU0_CLK_DP<1>")
	)
	(segment
		(start 404.744428 -255.162812)
		(end 402.44903 -252.867414)
		(width 0.18288)
		(layer "In4.Cu")
		(net "M_G_CPU0_CLK_DP<1>")
	)
	(segment
		(start 374.472708 -250.78817)
		(end 374.472708 -249.945652)
		(width 0.18288)
		(layer "In4.Cu")
		(net "M_G_CPU0_CLK_DP<1>")
	)
	(segment
		(start 407.3271 -256.232152)
		(end 404.744428 -255.162812)
		(width 0.18288)
		(layer "In4.Cu")
		(net "M_G_CPU0_CLK_DP<1>")
	)
	(segment
		(start 390.177528 -252.0061)
		(end 375.690638 -252.0061)
		(width 0.18288)
		(layer "In4.Cu")
		(net "M_G_CPU0_CLK_DP<1>")
	)
	(segment
		(start 439.64225 -259.935218)
		(end 439.215784 -259.935218)
		(width 0.18288)
		(layer "In4.Cu")
		(net "M_G_CPU0_CLK_DP<1>")
	)
	(segment
		(start 438.68467 -259.404104)
		(end 438.68467 -258.320286)
		(width 0.18288)
		(layer "In4.Cu")
		(net "M_G_CPU0_CLK_DP<1>")
	)
	(segment
		(start 439.923682 -260.21665)
		(end 439.64225 -259.935218)
		(width 0.18288)
		(layer "In4.Cu")
		(net "M_G_CPU0_CLK_DP<1>")
	)
	(segment
		(start 396.92072 -252.867414)
		(end 396.364714 -253.423674)
		(width 0.18288)
		(layer "In4.Cu")
		(net "M_G_CPU0_CLK_DP<1>")
	)
	(segment
		(start 396.364714 -253.423674)
		(end 396.36446 -253.423674)
		(width 0.18288)
		(layer "In4.Cu")
		(net "M_G_CPU0_CLK_DP<1>")
	)
	(segment
		(start 395.8082 -253.980188)
		(end 394.406374 -254.560832)
		(width 0.18288)
		(layer "In4.Cu")
		(net "M_G_CPU0_CLK_DP<1>")
	)
	(segment
		(start 402.44903 -252.867414)
		(end 396.92072 -252.867414)
		(width 0.18288)
		(layer "In4.Cu")
		(net "M_G_CPU0_CLK_DP<1>")
	)
	(segment
		(start 439.215784 -259.935218)
		(end 438.68467 -259.404104)
		(width 0.18288)
		(layer "In4.Cu")
		(net "M_G_CPU0_CLK_DP<1>")
	)
	(segment
		(start 392.251184 -254.079756)
		(end 390.177528 -252.0061)
		(width 0.18288)
		(layer "In4.Cu")
		(net "M_G_CPU0_CLK_DP<1>")
	)
	(segment
		(start 374.472708 -249.945652)
		(end 374.14708 -249.620024)
		(width 0.18288)
		(layer "In4.Cu")
		(net "M_G_CPU0_CLK_DP<1>")
	)
	(segment
		(start 375.690638 -252.0061)
		(end 374.472708 -250.78817)
		(width 0.18288)
		(layer "In4.Cu")
		(net "M_G_CPU0_CLK_DP<1>")
	)
	(segment
		(start 394.406374 -254.560832)
		(end 393.412472 -254.560832)
		(width 0.18288)
		(layer "In4.Cu")
		(net "M_G_CPU0_CLK_DP<1>")
	)
	(segment
		(start 436.484522 -257.399282)
		(end 434.00218 -256.905506)
		(width 0.18288)
		(layer "In4.Cu")
		(net "M_G_CPU0_CLK_DP<1>")
	)
	(segment
		(start 438.68467 -258.320286)
		(end 438.667906 -258.303522)
		(width 0.18288)
		(layer "In4.Cu")
		(net "M_G_CPU0_CLK_DP<1>")
	)
	(segment
		(start 413.461708 -256.905506)
		(end 408.009598 -256.368804)
		(width 0.18288)
		(layer "In4.Cu")
		(net "M_G_CPU0_CLK_DP<1>")
	)
	(segment
		(start 438.667906 -258.303522)
		(end 436.484522 -257.399282)
		(width 0.18288)
		(layer "In4.Cu")
		(net "M_G_CPU0_CLK_DP<1>")
	)
	(segment
		(start 396.36446 -253.423674)
		(end 395.8082 -253.980188)
		(width 0.18288)
		(layer "In4.Cu")
		(net "M_G_CPU0_CLK_DP<1>")
	)
	(segment
		(start 408.009598 -256.368804)
		(end 407.3271 -256.232152)
		(width 0.18288)
		(layer "In4.Cu")
		(net "M_G_CPU0_CLK_DP<1>")
	)
	(segment
		(start 376.02668 -250.15571)
		(end 376.02668 -249.620024)
		(width 0.20066)
		(layer "F.Cu")
		(net "M_G_CPU0_CLK_DP<0>")
	)
	(segment
		(start 376.026934 -250.155964)
		(end 376.02668 -250.15571)
		(width 0.20066)
		(layer "F.Cu")
		(net "M_G_CPU0_CLK_DP<0>")
	)
	(segment
		(start 447.467482 -260.21665)
		(end 448.572382 -260.21665)
		(width 0.20066)
		(layer "F.Cu")
		(net "M_G_CPU0_CLK_DP<0>")
	)
	(segment
		(start 405.892 -254.717804)
		(end 404.988776 -254.196342)
		(width 0.18288)
		(layer "In4.Cu")
		(net "M_G_CPU0_CLK_DP<0>")
	)
	(segment
		(start 376.33529 -250.71197)
		(end 376.33529 -249.928634)
		(width 0.18288)
		(layer "In4.Cu")
		(net "M_G_CPU0_CLK_DP<0>")
	)
	(segment
		(start 376.33529 -249.928634)
		(end 376.02668 -249.620024)
		(width 0.18288)
		(layer "In4.Cu")
		(net "M_G_CPU0_CLK_DP<0>")
	)
	(segment
		(start 406.68829 -255.089406)
		(end 405.892 -254.717804)
		(width 0.18288)
		(layer "In4.Cu")
		(net "M_G_CPU0_CLK_DP<0>")
	)
	(segment
		(start 433.668678 -255.919732)
		(end 412.527242 -255.919732)
		(width 0.18288)
		(layer "In4.Cu")
		(net "M_G_CPU0_CLK_DP<0>")
	)
	(segment
		(start 412.527242 -255.919732)
		(end 407.840688 -255.509522)
		(width 0.18288)
		(layer "In4.Cu")
		(net "M_G_CPU0_CLK_DP<0>")
	)
	(segment
		(start 442.46673 -259.648706)
		(end 438.218072 -256.797302)
		(width 0.18288)
		(layer "In4.Cu")
		(net "M_G_CPU0_CLK_DP<0>")
	)
	(segment
		(start 402.960078 -252.167644)
		(end 400.93646 -251.329444)
		(width 0.18288)
		(layer "In4.Cu")
		(net "M_G_CPU0_CLK_DP<0>")
	)
	(segment
		(start 447.467482 -260.21665)
		(end 447.18605 -259.935218)
		(width 0.18288)
		(layer "In4.Cu")
		(net "M_G_CPU0_CLK_DP<0>")
	)
	(segment
		(start 390.033002 -251.335032)
		(end 376.958352 -251.335032)
		(width 0.18288)
		(layer "In4.Cu")
		(net "M_G_CPU0_CLK_DP<0>")
	)
	(segment
		(start 447.18605 -259.935218)
		(end 446.249552 -259.935218)
		(width 0.18288)
		(layer "In4.Cu")
		(net "M_G_CPU0_CLK_DP<0>")
	)
	(segment
		(start 376.958352 -251.335032)
		(end 376.33529 -250.71197)
		(width 0.18288)
		(layer "In4.Cu")
		(net "M_G_CPU0_CLK_DP<0>")
	)
	(segment
		(start 404.988776 -254.196342)
		(end 402.960078 -252.167644)
		(width 0.18288)
		(layer "In4.Cu")
		(net "M_G_CPU0_CLK_DP<0>")
	)
	(segment
		(start 407.840688 -255.509522)
		(end 406.68829 -255.089406)
		(width 0.18288)
		(layer "In4.Cu")
		(net "M_G_CPU0_CLK_DP<0>")
	)
	(segment
		(start 400.93646 -251.329444)
		(end 396.981426 -251.329444)
		(width 0.18288)
		(layer "In4.Cu")
		(net "M_G_CPU0_CLK_DP<0>")
	)
	(segment
		(start 393.03833 -249.3264)
		(end 390.033002 -251.335032)
		(width 0.18288)
		(layer "In4.Cu")
		(net "M_G_CPU0_CLK_DP<0>")
	)
	(segment
		(start 438.218072 -256.797302)
		(end 433.668678 -255.919732)
		(width 0.18288)
		(layer "In4.Cu")
		(net "M_G_CPU0_CLK_DP<0>")
	)
	(segment
		(start 445.96304 -259.648706)
		(end 442.46673 -259.648706)
		(width 0.18288)
		(layer "In4.Cu")
		(net "M_G_CPU0_CLK_DP<0>")
	)
	(segment
		(start 396.981426 -251.329444)
		(end 394.978382 -249.3264)
		(width 0.18288)
		(layer "In4.Cu")
		(net "M_G_CPU0_CLK_DP<0>")
	)
	(segment
		(start 446.249552 -259.935218)
		(end 445.96304 -259.648706)
		(width 0.18288)
		(layer "In4.Cu")
		(net "M_G_CPU0_CLK_DP<0>")
	)
	(segment
		(start 394.978382 -249.3264)
		(end 393.03833 -249.3264)
		(width 0.18288)
		(layer "In4.Cu")
		(net "M_G_CPU0_CLK_DP<0>")
	)
	(segment
		(start 375.08688 -250.15571)
		(end 375.08688 -249.620024)
		(width 0.20066)
		(layer "F.Cu")
		(net "M_G_CPU0_CLK_DN<1>")
	)
	(segment
		(start 441.028582 -259.366766)
		(end 439.923682 -259.366766)
		(width 0.20066)
		(layer "F.Cu")
		(net "M_G_CPU0_CLK_DN<1>")
	)
	(segment
		(start 375.087134 -250.155964)
		(end 375.08688 -250.15571)
		(width 0.20066)
		(layer "F.Cu")
		(net "M_G_CPU0_CLK_DN<1>")
	)
	(segment
		(start 430.638204 -256.471166)
		(end 430.092104 -256.471166)
		(width 0.18288)
		(layer "In4.Cu")
		(net "M_G_CPU0_CLK_DN<1>")
	)
	(segment
		(start 394.344652 -254.250952)
		(end 393.474194 -254.250952)
		(width 0.18288)
		(layer "In4.Cu")
		(net "M_G_CPU0_CLK_DN<1>")
	)
	(segment
		(start 407.417778 -255.933956)
		(end 404.920196 -254.899922)
		(width 0.18288)
		(layer "In4.Cu")
		(net "M_G_CPU0_CLK_DN<1>")
	)
	(segment
		(start 375.819162 -251.69622)
		(end 374.782588 -250.659646)
		(width 0.18288)
		(layer "In4.Cu")
		(net "M_G_CPU0_CLK_DN<1>")
	)
	(segment
		(start 402.577554 -252.557534)
		(end 396.792196 -252.557534)
		(width 0.18288)
		(layer "In4.Cu")
		(net "M_G_CPU0_CLK_DN<1>")
	)
	(segment
		(start 434.032914 -256.595626)
		(end 430.762664 -256.595626)
		(width 0.18288)
		(layer "In4.Cu")
		(net "M_G_CPU0_CLK_DN<1>")
	)
	(segment
		(start 428.705264 -256.595626)
		(end 427.309026 -256.595626)
		(width 0.18288)
		(layer "In4.Cu")
		(net "M_G_CPU0_CLK_DN<1>")
	)
	(segment
		(start 438.99455 -258.191508)
		(end 438.843166 -258.040632)
		(width 0.18288)
		(layer "In4.Cu")
		(net "M_G_CPU0_CLK_DN<1>")
	)
	(segment
		(start 395.632432 -253.717298)
		(end 394.344652 -254.250952)
		(width 0.18288)
		(layer "In4.Cu")
		(net "M_G_CPU0_CLK_DN<1>")
	)
	(segment
		(start 425.10202 -256.471166)
		(end 424.97756 -256.595626)
		(width 0.18288)
		(layer "In4.Cu")
		(net "M_G_CPU0_CLK_DN<1>")
	)
	(segment
		(start 404.919688 -254.899668)
		(end 402.577554 -252.557534)
		(width 0.18288)
		(layer "In4.Cu")
		(net "M_G_CPU0_CLK_DN<1>")
	)
	(segment
		(start 374.782588 -249.924316)
		(end 375.08688 -249.620024)
		(width 0.18288)
		(layer "In4.Cu")
		(net "M_G_CPU0_CLK_DN<1>")
	)
	(segment
		(start 413.47898 -256.595626)
		(end 408.055318 -256.061718)
		(width 0.18288)
		(layer "In4.Cu")
		(net "M_G_CPU0_CLK_DN<1>")
	)
	(segment
		(start 426.514006 -256.595626)
		(end 425.77258 -256.595626)
		(width 0.18288)
		(layer "In4.Cu")
		(net "M_G_CPU0_CLK_DN<1>")
	)
	(segment
		(start 439.66511 -259.625338)
		(end 439.344308 -259.625338)
		(width 0.18288)
		(layer "In4.Cu")
		(net "M_G_CPU0_CLK_DN<1>")
	)
	(segment
		(start 426.638466 -256.471166)
		(end 426.514006 -256.595626)
		(width 0.18288)
		(layer "In4.Cu")
		(net "M_G_CPU0_CLK_DN<1>")
	)
	(segment
		(start 404.920196 -254.899922)
		(end 404.919688 -254.899668)
		(width 0.18288)
		(layer "In4.Cu")
		(net "M_G_CPU0_CLK_DN<1>")
	)
	(segment
		(start 436.574946 -257.101086)
		(end 434.032914 -256.595626)
		(width 0.18288)
		(layer "In4.Cu")
		(net "M_G_CPU0_CLK_DN<1>")
	)
	(segment
		(start 430.092104 -256.471166)
		(end 429.967644 -256.595626)
		(width 0.18288)
		(layer "In4.Cu")
		(net "M_G_CPU0_CLK_DN<1>")
	)
	(segment
		(start 439.344308 -259.625338)
		(end 438.99455 -259.27558)
		(width 0.18288)
		(layer "In4.Cu")
		(net "M_G_CPU0_CLK_DN<1>")
	)
	(segment
		(start 396.792196 -252.557534)
		(end 395.632432 -253.717298)
		(width 0.18288)
		(layer "In4.Cu")
		(net "M_G_CPU0_CLK_DN<1>")
	)
	(segment
		(start 430.762664 -256.595626)
		(end 430.638204 -256.471166)
		(width 0.18288)
		(layer "In4.Cu")
		(net "M_G_CPU0_CLK_DN<1>")
	)
	(segment
		(start 429.421544 -256.595626)
		(end 429.299624 -256.473706)
		(width 0.18288)
		(layer "In4.Cu")
		(net "M_G_CPU0_CLK_DN<1>")
	)
	(segment
		(start 390.306052 -251.69622)
		(end 375.819162 -251.69622)
		(width 0.18288)
		(layer "In4.Cu")
		(net "M_G_CPU0_CLK_DN<1>")
	)
	(segment
		(start 427.184566 -256.471166)
		(end 426.638466 -256.471166)
		(width 0.18288)
		(layer "In4.Cu")
		(net "M_G_CPU0_CLK_DN<1>")
	)
	(segment
		(start 425.77258 -256.595626)
		(end 425.64812 -256.471166)
		(width 0.18288)
		(layer "In4.Cu")
		(net "M_G_CPU0_CLK_DN<1>")
	)
	(segment
		(start 424.97756 -256.595626)
		(end 413.47898 -256.595626)
		(width 0.18288)
		(layer "In4.Cu")
		(net "M_G_CPU0_CLK_DN<1>")
	)
	(segment
		(start 427.309026 -256.595626)
		(end 427.184566 -256.471166)
		(width 0.18288)
		(layer "In4.Cu")
		(net "M_G_CPU0_CLK_DN<1>")
	)
	(segment
		(start 374.782588 -250.659646)
		(end 374.782588 -249.924316)
		(width 0.18288)
		(layer "In4.Cu")
		(net "M_G_CPU0_CLK_DN<1>")
	)
	(segment
		(start 392.426952 -253.816866)
		(end 390.306052 -251.69622)
		(width 0.18288)
		(layer "In4.Cu")
		(net "M_G_CPU0_CLK_DN<1>")
	)
	(segment
		(start 425.64812 -256.471166)
		(end 425.10202 -256.471166)
		(width 0.18288)
		(layer "In4.Cu")
		(net "M_G_CPU0_CLK_DN<1>")
	)
	(segment
		(start 438.99455 -259.27558)
		(end 438.99455 -258.191508)
		(width 0.18288)
		(layer "In4.Cu")
		(net "M_G_CPU0_CLK_DN<1>")
	)
	(segment
		(start 428.827184 -256.473706)
		(end 428.705264 -256.595626)
		(width 0.18288)
		(layer "In4.Cu")
		(net "M_G_CPU0_CLK_DN<1>")
	)
	(segment
		(start 429.967644 -256.595626)
		(end 429.421544 -256.595626)
		(width 0.18288)
		(layer "In4.Cu")
		(net "M_G_CPU0_CLK_DN<1>")
	)
	(segment
		(start 429.299624 -256.473706)
		(end 428.827184 -256.473706)
		(width 0.18288)
		(layer "In4.Cu")
		(net "M_G_CPU0_CLK_DN<1>")
	)
	(segment
		(start 439.923682 -259.366766)
		(end 439.66511 -259.625338)
		(width 0.18288)
		(layer "In4.Cu")
		(net "M_G_CPU0_CLK_DN<1>")
	)
	(segment
		(start 438.843166 -258.040632)
		(end 436.574946 -257.101086)
		(width 0.18288)
		(layer "In4.Cu")
		(net "M_G_CPU0_CLK_DN<1>")
	)
	(segment
		(start 408.055318 -256.061718)
		(end 407.417778 -255.933956)
		(width 0.18288)
		(layer "In4.Cu")
		(net "M_G_CPU0_CLK_DN<1>")
	)
	(segment
		(start 393.474194 -254.250952)
		(end 392.426952 -253.816866)
		(width 0.18288)
		(layer "In4.Cu")
		(net "M_G_CPU0_CLK_DN<1>")
	)
	(segment
		(start 448.572382 -259.366766)
		(end 447.467482 -259.366766)
		(width 0.20066)
		(layer "F.Cu")
		(net "M_G_CPU0_CLK_DN<0>")
	)
	(segment
		(start 376.96648 -250.15571)
		(end 376.96648 -249.620024)
		(width 0.20066)
		(layer "F.Cu")
		(net "M_G_CPU0_CLK_DN<0>")
	)
	(segment
		(start 376.966734 -250.155964)
		(end 376.96648 -250.15571)
		(width 0.20066)
		(layer "F.Cu")
		(net "M_G_CPU0_CLK_DN<0>")
	)
	(segment
		(start 397.10995 -251.019564)
		(end 395.106906 -249.01652)
		(width 0.18288)
		(layer "In4.Cu")
		(net "M_G_CPU0_CLK_DN<0>")
	)
	(segment
		(start 433.698396 -255.609852)
		(end 412.540958 -255.609852)
		(width 0.18288)
		(layer "In4.Cu")
		(net "M_G_CPU0_CLK_DN<0>")
	)
	(segment
		(start 403.135846 -251.904754)
		(end 400.998182 -251.019564)
		(width 0.18288)
		(layer "In4.Cu")
		(net "M_G_CPU0_CLK_DN<0>")
	)
	(segment
		(start 389.938768 -251.025152)
		(end 377.086876 -251.025152)
		(width 0.18288)
		(layer "In4.Cu")
		(net "M_G_CPU0_CLK_DN<0>")
	)
	(segment
		(start 441.160662 -258.398772)
		(end 441.126626 -258.226052)
		(width 0.18288)
		(layer "In4.Cu")
		(net "M_G_CPU0_CLK_DN<0>")
	)
	(segment
		(start 406.035256 -254.442468)
		(end 405.179276 -253.948184)
		(width 0.18288)
		(layer "In4.Cu")
		(net "M_G_CPU0_CLK_DN<0>")
	)
	(segment
		(start 447.20891 -259.625338)
		(end 446.378076 -259.625338)
		(width 0.18288)
		(layer "In4.Cu")
		(net "M_G_CPU0_CLK_DN<0>")
	)
	(segment
		(start 407.908506 -255.204214)
		(end 406.807162 -254.802894)
		(width 0.18288)
		(layer "In4.Cu")
		(net "M_G_CPU0_CLK_DN<0>")
	)
	(segment
		(start 405.179276 -253.948184)
		(end 403.135846 -251.904754)
		(width 0.18288)
		(layer "In4.Cu")
		(net "M_G_CPU0_CLK_DN<0>")
	)
	(segment
		(start 444.450216 -259.214366)
		(end 443.904116 -259.214366)
		(width 0.18288)
		(layer "In4.Cu")
		(net "M_G_CPU0_CLK_DN<0>")
	)
	(segment
		(start 440.01309 -257.47853)
		(end 439.559192 -257.173984)
		(width 0.18288)
		(layer "In4.Cu")
		(net "M_G_CPU0_CLK_DN<0>")
	)
	(segment
		(start 376.64517 -250.583446)
		(end 376.64517 -249.941334)
		(width 0.18288)
		(layer "In4.Cu")
		(net "M_G_CPU0_CLK_DN<0>")
	)
	(segment
		(start 438.338722 -256.504694)
		(end 437.802528 -256.401316)
		(width 0.18288)
		(layer "In4.Cu")
		(net "M_G_CPU0_CLK_DN<0>")
	)
	(segment
		(start 392.944096 -249.01652)
		(end 389.938768 -251.025152)
		(width 0.18288)
		(layer "In4.Cu")
		(net "M_G_CPU0_CLK_DN<0>")
	)
	(segment
		(start 412.540958 -255.609852)
		(end 407.908506 -255.204214)
		(width 0.18288)
		(layer "In4.Cu")
		(net "M_G_CPU0_CLK_DN<0>")
	)
	(segment
		(start 444.574676 -259.338826)
		(end 444.450216 -259.214366)
		(width 0.18288)
		(layer "In4.Cu")
		(net "M_G_CPU0_CLK_DN<0>")
	)
	(segment
		(start 446.091564 -259.338826)
		(end 444.574676 -259.338826)
		(width 0.18288)
		(layer "In4.Cu")
		(net "M_G_CPU0_CLK_DN<0>")
	)
	(segment
		(start 443.904116 -259.214366)
		(end 443.779656 -259.338826)
		(width 0.18288)
		(layer "In4.Cu")
		(net "M_G_CPU0_CLK_DN<0>")
	)
	(segment
		(start 437.021732 -256.250694)
		(end 433.698396 -255.609852)
		(width 0.18288)
		(layer "In4.Cu")
		(net "M_G_CPU0_CLK_DN<0>")
	)
	(segment
		(start 440.046872 -257.65125)
		(end 440.01309 -257.47853)
		(width 0.18288)
		(layer "In4.Cu")
		(net "M_G_CPU0_CLK_DN<0>")
	)
	(segment
		(start 377.086876 -251.025152)
		(end 376.64517 -250.583446)
		(width 0.18288)
		(layer "In4.Cu")
		(net "M_G_CPU0_CLK_DN<0>")
	)
	(segment
		(start 406.807162 -254.802894)
		(end 406.035256 -254.442468)
		(width 0.18288)
		(layer "In4.Cu")
		(net "M_G_CPU0_CLK_DN<0>")
	)
	(segment
		(start 440.500262 -257.955542)
		(end 440.046872 -257.65125)
		(width 0.18288)
		(layer "In4.Cu")
		(net "M_G_CPU0_CLK_DN<0>")
	)
	(segment
		(start 395.106906 -249.01652)
		(end 392.944096 -249.01652)
		(width 0.18288)
		(layer "In4.Cu")
		(net "M_G_CPU0_CLK_DN<0>")
	)
	(segment
		(start 443.779656 -259.338826)
		(end 442.561218 -259.338826)
		(width 0.18288)
		(layer "In4.Cu")
		(net "M_G_CPU0_CLK_DN<0>")
	)
	(segment
		(start 376.64517 -249.941334)
		(end 376.96648 -249.620024)
		(width 0.18288)
		(layer "In4.Cu")
		(net "M_G_CPU0_CLK_DN<0>")
	)
	(segment
		(start 437.167528 -256.151888)
		(end 437.021732 -256.250694)
		(width 0.18288)
		(layer "In4.Cu")
		(net "M_G_CPU0_CLK_DN<0>")
	)
	(segment
		(start 400.998182 -251.019564)
		(end 397.10995 -251.019564)
		(width 0.18288)
		(layer "In4.Cu")
		(net "M_G_CPU0_CLK_DN<0>")
	)
	(segment
		(start 437.802528 -256.401316)
		(end 437.703976 -256.255266)
		(width 0.18288)
		(layer "In4.Cu")
		(net "M_G_CPU0_CLK_DN<0>")
	)
	(segment
		(start 437.703976 -256.255266)
		(end 437.167528 -256.151888)
		(width 0.18288)
		(layer "In4.Cu")
		(net "M_G_CPU0_CLK_DN<0>")
	)
	(segment
		(start 441.126626 -258.226052)
		(end 440.672982 -257.921506)
		(width 0.18288)
		(layer "In4.Cu")
		(net "M_G_CPU0_CLK_DN<0>")
	)
	(segment
		(start 440.672982 -257.921506)
		(end 440.500262 -257.955542)
		(width 0.18288)
		(layer "In4.Cu")
		(net "M_G_CPU0_CLK_DN<0>")
	)
	(segment
		(start 439.386472 -257.20802)
		(end 438.338722 -256.504694)
		(width 0.18288)
		(layer "In4.Cu")
		(net "M_G_CPU0_CLK_DN<0>")
	)
	(segment
		(start 442.561218 -259.338826)
		(end 441.160662 -258.398772)
		(width 0.18288)
		(layer "In4.Cu")
		(net "M_G_CPU0_CLK_DN<0>")
	)
	(segment
		(start 439.559192 -257.173984)
		(end 439.386472 -257.20802)
		(width 0.18288)
		(layer "In4.Cu")
		(net "M_G_CPU0_CLK_DN<0>")
	)
	(segment
		(start 446.378076 -259.625338)
		(end 446.091564 -259.338826)
		(width 0.18288)
		(layer "In4.Cu")
		(net "M_G_CPU0_CLK_DN<0>")
	)
	(segment
		(start 447.467482 -259.366766)
		(end 447.20891 -259.625338)
		(width 0.18288)
		(layer "In4.Cu")
		(net "M_G_CPU0_CLK_DN<0>")
	)
	(segment
		(start 439.726324 -269.141702)
		(end 439.28792 -269.141702)
		(width 0.20066)
		(layer "F.Cu")
		(net "M_G_CPU0_ALERT_N")
	)
	(segment
		(start 439.16981 -269.62735)
		(end 438.98185 -269.81531)
		(width 0.20066)
		(layer "F.Cu")
		(net "M_G_CPU0_ALERT_N")
	)
	(segment
		(start 369.558316 -255.825498)
		(end 369.558316 -256.36093)
		(width 0.20066)
		(layer "F.Cu")
		(net "M_G_CPU0_ALERT_N")
	)
	(segment
		(start 444.472314 -269.566644)
		(end 444.47206 -269.566898)
		(width 0.20066)
		(layer "F.Cu")
		(net "M_G_CPU0_ALERT_N")
	)
	(segment
		(start 438.697878 -269.81531)
		(end 438.449212 -269.566644)
		(width 0.20066)
		(layer "F.Cu")
		(net "M_G_CPU0_ALERT_N")
	)
	(segment
		(start 439.16981 -269.259812)
		(end 439.16981 -269.62735)
		(width 0.20066)
		(layer "F.Cu")
		(net "M_G_CPU0_ALERT_N")
	)
	(segment
		(start 439.28792 -269.141702)
		(end 439.16981 -269.259812)
		(width 0.20066)
		(layer "F.Cu")
		(net "M_G_CPU0_ALERT_N")
	)
	(segment
		(start 442.84138 -269.566898)
		(end 442.416184 -269.141702)
		(width 0.20066)
		(layer "F.Cu")
		(net "M_G_CPU0_ALERT_N")
	)
	(segment
		(start 436.928514 -269.566644)
		(end 435.823614 -269.566644)
		(width 0.20066)
		(layer "F.Cu")
		(net "M_G_CPU0_ALERT_N")
	)
	(segment
		(start 444.47206 -269.566898)
		(end 442.84138 -269.566898)
		(width 0.20066)
		(layer "F.Cu")
		(net "M_G_CPU0_ALERT_N")
	)
	(segment
		(start 442.416184 -269.141702)
		(end 442.21781 -269.141702)
		(width 0.20066)
		(layer "F.Cu")
		(net "M_G_CPU0_ALERT_N")
	)
	(segment
		(start 438.449212 -269.566644)
		(end 436.928514 -269.566644)
		(width 0.20066)
		(layer "F.Cu")
		(net "M_G_CPU0_ALERT_N")
	)
	(segment
		(start 442.181234 -269.141702)
		(end 439.87085 -269.141702)
		(width 0.1016)
		(layer "F.Cu")
		(net "M_G_CPU0_ALERT_N")
	)
	(segment
		(start 439.87085 -269.141702)
		(end 439.726324 -269.141702)
		(width 0.101854)
		(layer "F.Cu")
		(net "M_G_CPU0_ALERT_N")
	)
	(segment
		(start 442.21781 -269.141702)
		(end 442.181234 -269.141702)
		(width 0.101854)
		(layer "F.Cu")
		(net "M_G_CPU0_ALERT_N")
	)
	(segment
		(start 438.98185 -269.81531)
		(end 438.697878 -269.81531)
		(width 0.20066)
		(layer "F.Cu")
		(net "M_G_CPU0_ALERT_N")
	)
	(via
		(at 435.823614 -269.566644)
		(size 0.4572)
		(drill 0.2032)
		(layers "F.Cu" "B.Cu")
		(net "M_G_CPU0_ALERT_N")
	)
	(via
		(at 369.558062 -256.361438)
		(size 0.4572)
		(drill 0.2032)
		(layers "F.Cu" "B.Cu")
		(net "M_G_CPU0_ALERT_N")
	)
	(arc
		(start 369.558316 -256.36093)
		(mid 369.558258 -256.361222)
		(end 369.558062 -256.361438)
		(width 0.20066)
		(layer "F.Cu")
		(net "M_G_CPU0_ALERT_N")
	)
	(segment
		(start 436.173626 -257.880358)
		(end 399.91665 -257.880358)
		(width 0.18288)
		(layer "In6.Cu")
		(net "M_G_CPU0_ALERT_N")
	)
	(segment
		(start 372.142512 -256.768346)
		(end 372.12905 -256.760472)
		(width 0.18288)
		(layer "In6.Cu")
		(net "M_G_CPU0_ALERT_N")
	)
	(segment
		(start 374.961912 -256.768346)
		(end 374.94845 -256.760472)
		(width 0.18288)
		(layer "In6.Cu")
		(net "M_G_CPU0_ALERT_N")
	)
	(segment
		(start 436.41137 -258.118102)
		(end 436.173626 -257.880358)
		(width 0.18288)
		(layer "In6.Cu")
		(net "M_G_CPU0_ALERT_N")
	)
	(segment
		(start 369.560094 -256.36855)
		(end 369.558062 -256.361438)
		(width 0.18288)
		(layer "In6.Cu")
		(net "M_G_CPU0_ALERT_N")
	)
	(segment
		(start 379.660912 -256.768346)
		(end 379.64745 -256.760472)
		(width 0.18288)
		(layer "In6.Cu")
		(net "M_G_CPU0_ALERT_N")
	)
	(segment
		(start 384.830066 -256.768346)
		(end 384.820414 -256.773934)
		(width 0.18288)
		(layer "In6.Cu")
		(net "M_G_CPU0_ALERT_N")
	)
	(segment
		(start 370.252752 -256.768346)
		(end 369.560094 -256.36855)
		(width 0.18288)
		(layer "In6.Cu")
		(net "M_G_CPU0_ALERT_N")
	)
	(segment
		(start 436.41137 -268.978888)
		(end 436.41137 -258.118102)
		(width 0.18288)
		(layer "In6.Cu")
		(net "M_G_CPU0_ALERT_N")
	)
	(segment
		(start 381.540512 -256.768346)
		(end 381.52705 -256.760472)
		(width 0.18288)
		(layer "In6.Cu")
		(net "M_G_CPU0_ALERT_N")
	)
	(segment
		(start 378.721112 -256.768346)
		(end 378.70765 -256.760472)
		(width 0.18288)
		(layer "In6.Cu")
		(net "M_G_CPU0_ALERT_N")
	)
	(segment
		(start 391.27684 -258.606544)
		(end 388.242048 -257.349752)
		(width 0.18288)
		(layer "In6.Cu")
		(net "M_G_CPU0_ALERT_N")
	)
	(segment
		(start 386.821172 -257.349752)
		(end 386.239766 -256.768346)
		(width 0.18288)
		(layer "In6.Cu")
		(net "M_G_CPU0_ALERT_N")
	)
	(segment
		(start 399.91665 -257.880358)
		(end 398.759172 -259.037836)
		(width 0.18288)
		(layer "In6.Cu")
		(net "M_G_CPU0_ALERT_N")
	)
	(segment
		(start 371.202712 -256.768346)
		(end 371.19306 -256.762758)
		(width 0.18288)
		(layer "In6.Cu")
		(net "M_G_CPU0_ALERT_N")
	)
	(segment
		(start 398.759172 -259.037836)
		(end 393.444476 -259.037836)
		(width 0.18288)
		(layer "In6.Cu")
		(net "M_G_CPU0_ALERT_N")
	)
	(segment
		(start 435.823614 -269.566644)
		(end 436.41137 -268.978888)
		(width 0.18288)
		(layer "In6.Cu")
		(net "M_G_CPU0_ALERT_N")
	)
	(segment
		(start 377.781312 -256.768346)
		(end 377.77166 -256.762758)
		(width 0.18288)
		(layer "In6.Cu")
		(net "M_G_CPU0_ALERT_N")
	)
	(segment
		(start 388.242048 -257.349752)
		(end 386.821172 -257.349752)
		(width 0.18288)
		(layer "In6.Cu")
		(net "M_G_CPU0_ALERT_N")
	)
	(segment
		(start 376.841766 -256.768346)
		(end 376.832114 -256.762758)
		(width 0.18288)
		(layer "In6.Cu")
		(net "M_G_CPU0_ALERT_N")
	)
	(segment
		(start 393.444476 -259.037836)
		(end 391.27684 -258.606544)
		(width 0.18288)
		(layer "In6.Cu")
		(net "M_G_CPU0_ALERT_N")
	)
	(arc
		(start 375.431812 -256.768346)
		(mid 375.196862 -256.831306)
		(end 374.961912 -256.768346)
		(width 0.18288)
		(layer "In6.Cu")
		(net "M_G_CPU0_ALERT_N")
	)
	(arc
		(start 376.371612 -256.768346)
		(mid 376.136662 -256.831306)
		(end 375.901712 -256.768346)
		(width 0.18288)
		(layer "In6.Cu")
		(net "M_G_CPU0_ALERT_N")
	)
	(arc
		(start 374.94845 -256.760472)
		(mid 374.719197 -256.705228)
		(end 374.492012 -256.768346)
		(width 0.18288)
		(layer "In6.Cu")
		(net "M_G_CPU0_ALERT_N")
	)
	(arc
		(start 379.64745 -256.760472)
		(mid 379.418197 -256.705228)
		(end 379.191012 -256.768346)
		(width 0.18288)
		(layer "In6.Cu")
		(net "M_G_CPU0_ALERT_N")
	)
	(arc
		(start 374.022112 -256.768346)
		(mid 373.787162 -256.705386)
		(end 373.552212 -256.768346)
		(width 0.18288)
		(layer "In6.Cu")
		(net "M_G_CPU0_ALERT_N")
	)
	(arc
		(start 371.19306 -256.762758)
		(mid 370.962329 -256.705397)
		(end 370.733066 -256.768346)
		(width 0.18288)
		(layer "In6.Cu")
		(net "M_G_CPU0_ALERT_N")
	)
	(arc
		(start 374.492012 -256.768346)
		(mid 374.257062 -256.831306)
		(end 374.022112 -256.768346)
		(width 0.18288)
		(layer "In6.Cu")
		(net "M_G_CPU0_ALERT_N")
	)
	(arc
		(start 377.77166 -256.762758)
		(mid 377.540929 -256.705397)
		(end 377.311666 -256.768346)
		(width 0.18288)
		(layer "In6.Cu")
		(net "M_G_CPU0_ALERT_N")
	)
	(arc
		(start 371.672612 -256.768346)
		(mid 371.437662 -256.831306)
		(end 371.202712 -256.768346)
		(width 0.18288)
		(layer "In6.Cu")
		(net "M_G_CPU0_ALERT_N")
	)
	(arc
		(start 381.52705 -256.760472)
		(mid 381.297797 -256.705228)
		(end 381.070612 -256.768346)
		(width 0.18288)
		(layer "In6.Cu")
		(net "M_G_CPU0_ALERT_N")
	)
	(arc
		(start 380.130812 -256.768346)
		(mid 379.895862 -256.831306)
		(end 379.660912 -256.768346)
		(width 0.18288)
		(layer "In6.Cu")
		(net "M_G_CPU0_ALERT_N")
	)
	(arc
		(start 378.70765 -256.760472)
		(mid 378.478397 -256.705228)
		(end 378.251212 -256.768346)
		(width 0.18288)
		(layer "In6.Cu")
		(net "M_G_CPU0_ALERT_N")
	)
	(arc
		(start 377.311666 -256.768346)
		(mid 377.076716 -256.831306)
		(end 376.841766 -256.768346)
		(width 0.18288)
		(layer "In6.Cu")
		(net "M_G_CPU0_ALERT_N")
	)
	(arc
		(start 386.239766 -256.768346)
		(mid 386.004816 -256.705386)
		(end 385.769866 -256.768346)
		(width 0.18288)
		(layer "In6.Cu")
		(net "M_G_CPU0_ALERT_N")
	)
	(arc
		(start 382.010412 -256.768346)
		(mid 381.775462 -256.831306)
		(end 381.540512 -256.768346)
		(width 0.18288)
		(layer "In6.Cu")
		(net "M_G_CPU0_ALERT_N")
	)
	(arc
		(start 380.600712 -256.768346)
		(mid 380.365762 -256.705386)
		(end 380.130812 -256.768346)
		(width 0.18288)
		(layer "In6.Cu")
		(net "M_G_CPU0_ALERT_N")
	)
	(arc
		(start 373.552212 -256.768346)
		(mid 373.317262 -256.831306)
		(end 373.082312 -256.768346)
		(width 0.18288)
		(layer "In6.Cu")
		(net "M_G_CPU0_ALERT_N")
	)
	(arc
		(start 384.359912 -256.768346)
		(mid 384.124962 -256.705386)
		(end 383.890012 -256.768346)
		(width 0.18288)
		(layer "In6.Cu")
		(net "M_G_CPU0_ALERT_N")
	)
	(arc
		(start 384.820414 -256.773934)
		(mid 384.589429 -256.831417)
		(end 384.359912 -256.768346)
		(width 0.18288)
		(layer "In6.Cu")
		(net "M_G_CPU0_ALERT_N")
	)
	(arc
		(start 382.950212 -256.768346)
		(mid 382.715262 -256.831306)
		(end 382.480312 -256.768346)
		(width 0.18288)
		(layer "In6.Cu")
		(net "M_G_CPU0_ALERT_N")
	)
	(arc
		(start 372.12905 -256.760472)
		(mid 371.899797 -256.705228)
		(end 371.672612 -256.768346)
		(width 0.18288)
		(layer "In6.Cu")
		(net "M_G_CPU0_ALERT_N")
	)
	(arc
		(start 372.612412 -256.768346)
		(mid 372.377462 -256.831306)
		(end 372.142512 -256.768346)
		(width 0.18288)
		(layer "In6.Cu")
		(net "M_G_CPU0_ALERT_N")
	)
	(arc
		(start 385.299966 -256.768346)
		(mid 385.065016 -256.705386)
		(end 384.830066 -256.768346)
		(width 0.18288)
		(layer "In6.Cu")
		(net "M_G_CPU0_ALERT_N")
	)
	(arc
		(start 382.480312 -256.768346)
		(mid 382.245362 -256.705386)
		(end 382.010412 -256.768346)
		(width 0.18288)
		(layer "In6.Cu")
		(net "M_G_CPU0_ALERT_N")
	)
	(arc
		(start 381.070612 -256.768346)
		(mid 380.835662 -256.831306)
		(end 380.600712 -256.768346)
		(width 0.18288)
		(layer "In6.Cu")
		(net "M_G_CPU0_ALERT_N")
	)
	(arc
		(start 376.832114 -256.762758)
		(mid 376.601129 -256.705275)
		(end 376.371612 -256.768346)
		(width 0.18288)
		(layer "In6.Cu")
		(net "M_G_CPU0_ALERT_N")
	)
	(arc
		(start 385.769866 -256.768346)
		(mid 385.534916 -256.831306)
		(end 385.299966 -256.768346)
		(width 0.18288)
		(layer "In6.Cu")
		(net "M_G_CPU0_ALERT_N")
	)
	(arc
		(start 383.890012 -256.768346)
		(mid 383.655062 -256.831306)
		(end 383.420112 -256.768346)
		(width 0.18288)
		(layer "In6.Cu")
		(net "M_G_CPU0_ALERT_N")
	)
	(arc
		(start 375.901712 -256.768346)
		(mid 375.666762 -256.705386)
		(end 375.431812 -256.768346)
		(width 0.18288)
		(layer "In6.Cu")
		(net "M_G_CPU0_ALERT_N")
	)
	(arc
		(start 378.251212 -256.768346)
		(mid 378.016262 -256.831306)
		(end 377.781312 -256.768346)
		(width 0.18288)
		(layer "In6.Cu")
		(net "M_G_CPU0_ALERT_N")
	)
	(arc
		(start 373.082312 -256.768346)
		(mid 372.847362 -256.705386)
		(end 372.612412 -256.768346)
		(width 0.18288)
		(layer "In6.Cu")
		(net "M_G_CPU0_ALERT_N")
	)
	(arc
		(start 370.733066 -256.768346)
		(mid 370.492926 -256.832621)
		(end 370.252752 -256.768346)
		(width 0.18288)
		(layer "In6.Cu")
		(net "M_G_CPU0_ALERT_N")
	)
	(arc
		(start 383.420112 -256.768346)
		(mid 383.185162 -256.705386)
		(end 382.950212 -256.768346)
		(width 0.18288)
		(layer "In6.Cu")
		(net "M_G_CPU0_ALERT_N")
	)
	(arc
		(start 379.191012 -256.768346)
		(mid 378.956062 -256.831306)
		(end 378.721112 -256.768346)
		(width 0.18288)
		(layer "In6.Cu")
		(net "M_G_CPU0_ALERT_N")
	)
	(segment
		(start 173.900846 -243.216684)
		(end 172.795946 -243.216684)
		(width 0.20066)
		(layer "F.Cu")
		(net "M_F_CPU1_SB_RSP<1>")
	)
	(segment
		(start 126.786894 -253.383796)
		(end 126.786894 -253.919482)
		(width 0.20066)
		(layer "F.Cu")
		(net "M_F_CPU1_SB_RSP<1>")
	)
	(segment
		(start 126.786894 -253.919482)
		(end 126.787148 -253.919736)
		(width 0.20066)
		(layer "F.Cu")
		(net "M_F_CPU1_SB_RSP<1>")
	)
	(segment
		(start 156.582364 -247.55094)
		(end 152.883616 -247.55094)
		(width 0.18288)
		(layer "In6.Cu")
		(net "M_F_CPU1_SB_RSP<1>")
	)
	(segment
		(start 157.798516 -247.047258)
		(end 156.582364 -247.55094)
		(width 0.18288)
		(layer "In6.Cu")
		(net "M_F_CPU1_SB_RSP<1>")
	)
	(segment
		(start 170.625262 -243.53901)
		(end 169.622978 -244.541294)
		(width 0.18288)
		(layer "In6.Cu")
		(net "M_F_CPU1_SB_RSP<1>")
	)
	(segment
		(start 169.004234 -244.38864)
		(end 167.606726 -244.38864)
		(width 0.18288)
		(layer "In6.Cu")
		(net "M_F_CPU1_SB_RSP<1>")
	)
	(segment
		(start 169.156888 -244.541294)
		(end 169.004234 -244.38864)
		(width 0.18288)
		(layer "In6.Cu")
		(net "M_F_CPU1_SB_RSP<1>")
	)
	(segment
		(start 162.530536 -245.814596)
		(end 162.530536 -246.210074)
		(width 0.18288)
		(layer "In6.Cu")
		(net "M_F_CPU1_SB_RSP<1>")
	)
	(segment
		(start 151.97963 -247.925336)
		(end 143.44015 -247.925336)
		(width 0.18288)
		(layer "In6.Cu")
		(net "M_F_CPU1_SB_RSP<1>")
	)
	(segment
		(start 165.314884 -245.453154)
		(end 164.984938 -245.453154)
		(width 0.18288)
		(layer "In6.Cu")
		(net "M_F_CPU1_SB_RSP<1>")
	)
	(segment
		(start 167.423846 -242.920266)
		(end 167.240966 -242.737386)
		(width 0.18288)
		(layer "In6.Cu")
		(net "M_F_CPU1_SB_RSP<1>")
	)
	(segment
		(start 160.215834 -247.047258)
		(end 157.798516 -247.047258)
		(width 0.18288)
		(layer "In6.Cu")
		(net "M_F_CPU1_SB_RSP<1>")
	)
	(segment
		(start 167.423846 -244.20576)
		(end 167.423846 -242.920266)
		(width 0.18288)
		(layer "In6.Cu")
		(net "M_F_CPU1_SB_RSP<1>")
	)
	(segment
		(start 164.045138 -246.392954)
		(end 163.406836 -246.392954)
		(width 0.18288)
		(layer "In6.Cu")
		(net "M_F_CPU1_SB_RSP<1>")
	)
	(segment
		(start 163.041076 -245.631716)
		(end 162.713416 -245.631716)
		(width 0.18288)
		(layer "In6.Cu")
		(net "M_F_CPU1_SB_RSP<1>")
	)
	(segment
		(start 163.223956 -245.814596)
		(end 163.041076 -245.631716)
		(width 0.18288)
		(layer "In6.Cu")
		(net "M_F_CPU1_SB_RSP<1>")
	)
	(segment
		(start 172.770546 -243.216684)
		(end 172.44822 -243.53901)
		(width 0.18288)
		(layer "In6.Cu")
		(net "M_F_CPU1_SB_RSP<1>")
	)
	(segment
		(start 166.730426 -242.920266)
		(end 166.730426 -244.20576)
		(width 0.18288)
		(layer "In6.Cu")
		(net "M_F_CPU1_SB_RSP<1>")
	)
	(segment
		(start 162.713416 -245.631716)
		(end 162.530536 -245.814596)
		(width 0.18288)
		(layer "In6.Cu")
		(net "M_F_CPU1_SB_RSP<1>")
	)
	(segment
		(start 126.787148 -252.3617)
		(end 126.787148 -253.919736)
		(width 0.088646)
		(layer "In6.Cu")
		(net "M_F_CPU1_SB_RSP<1>")
	)
	(segment
		(start 166.379398 -244.38864)
		(end 165.314884 -245.453154)
		(width 0.18288)
		(layer "In6.Cu")
		(net "M_F_CPU1_SB_RSP<1>")
	)
	(segment
		(start 166.547546 -244.38864)
		(end 166.379398 -244.38864)
		(width 0.18288)
		(layer "In6.Cu")
		(net "M_F_CPU1_SB_RSP<1>")
	)
	(segment
		(start 140.84173 -250.523756)
		(end 138.657838 -250.523756)
		(width 0.18288)
		(layer "In6.Cu")
		(net "M_F_CPU1_SB_RSP<1>")
	)
	(segment
		(start 167.240966 -242.737386)
		(end 166.913306 -242.737386)
		(width 0.18288)
		(layer "In6.Cu")
		(net "M_F_CPU1_SB_RSP<1>")
	)
	(segment
		(start 138.325098 -250.523756)
		(end 138.276584 -250.57227)
		(width 0.088646)
		(layer "In6.Cu")
		(net "M_F_CPU1_SB_RSP<1>")
	)
	(segment
		(start 163.406836 -246.392954)
		(end 163.223956 -246.210074)
		(width 0.18288)
		(layer "In6.Cu")
		(net "M_F_CPU1_SB_RSP<1>")
	)
	(segment
		(start 162.530536 -246.210074)
		(end 162.347656 -246.392954)
		(width 0.18288)
		(layer "In6.Cu")
		(net "M_F_CPU1_SB_RSP<1>")
	)
	(segment
		(start 138.657838 -250.523756)
		(end 138.325098 -250.523756)
		(width 0.088646)
		(layer "In6.Cu")
		(net "M_F_CPU1_SB_RSP<1>")
	)
	(segment
		(start 143.44015 -247.925336)
		(end 140.84173 -250.523756)
		(width 0.18288)
		(layer "In6.Cu")
		(net "M_F_CPU1_SB_RSP<1>")
	)
	(segment
		(start 167.606726 -244.38864)
		(end 167.423846 -244.20576)
		(width 0.18288)
		(layer "In6.Cu")
		(net "M_F_CPU1_SB_RSP<1>")
	)
	(segment
		(start 166.730426 -244.20576)
		(end 166.547546 -244.38864)
		(width 0.18288)
		(layer "In6.Cu")
		(net "M_F_CPU1_SB_RSP<1>")
	)
	(segment
		(start 172.44822 -243.53901)
		(end 170.625262 -243.53901)
		(width 0.18288)
		(layer "In6.Cu")
		(net "M_F_CPU1_SB_RSP<1>")
	)
	(segment
		(start 160.870138 -246.392954)
		(end 160.215834 -247.047258)
		(width 0.18288)
		(layer "In6.Cu")
		(net "M_F_CPU1_SB_RSP<1>")
	)
	(segment
		(start 152.883616 -247.55094)
		(end 151.97963 -247.925336)
		(width 0.18288)
		(layer "In6.Cu")
		(net "M_F_CPU1_SB_RSP<1>")
	)
	(segment
		(start 169.622978 -244.541294)
		(end 169.156888 -244.541294)
		(width 0.18288)
		(layer "In6.Cu")
		(net "M_F_CPU1_SB_RSP<1>")
	)
	(segment
		(start 164.984938 -245.453154)
		(end 164.045138 -246.392954)
		(width 0.18288)
		(layer "In6.Cu")
		(net "M_F_CPU1_SB_RSP<1>")
	)
	(segment
		(start 138.276584 -250.57227)
		(end 128.576578 -250.57227)
		(width 0.088646)
		(layer "In6.Cu")
		(net "M_F_CPU1_SB_RSP<1>")
	)
	(segment
		(start 128.576578 -250.57227)
		(end 126.787148 -252.3617)
		(width 0.088646)
		(layer "In6.Cu")
		(net "M_F_CPU1_SB_RSP<1>")
	)
	(segment
		(start 172.795946 -243.216684)
		(end 172.770546 -243.216684)
		(width 0.18288)
		(layer "In6.Cu")
		(net "M_F_CPU1_SB_RSP<1>")
	)
	(segment
		(start 162.347656 -246.392954)
		(end 160.870138 -246.392954)
		(width 0.18288)
		(layer "In6.Cu")
		(net "M_F_CPU1_SB_RSP<1>")
	)
	(segment
		(start 163.223956 -246.210074)
		(end 163.223956 -245.814596)
		(width 0.18288)
		(layer "In6.Cu")
		(net "M_F_CPU1_SB_RSP<1>")
	)
	(segment
		(start 166.913306 -242.737386)
		(end 166.730426 -242.920266)
		(width 0.18288)
		(layer "In6.Cu")
		(net "M_F_CPU1_SB_RSP<1>")
	)
	(segment
		(start 127.256794 -254.197866)
		(end 127.256794 -254.733552)
		(width 0.20066)
		(layer "F.Cu")
		(net "M_F_CPU1_SB_RSP<0>")
	)
	(segment
		(start 127.257048 -254.197612)
		(end 127.256794 -254.197866)
		(width 0.20066)
		(layer "F.Cu")
		(net "M_F_CPU1_SB_RSP<0>")
	)
	(segment
		(start 181.444646 -243.216684)
		(end 180.314346 -243.216684)
		(width 0.20066)
		(layer "F.Cu")
		(net "M_F_CPU1_SB_RSP<0>")
	)
	(segment
		(start 180.107844 -243.423186)
		(end 179.23637 -243.423186)
		(width 0.18288)
		(layer "In6.Cu")
		(net "M_F_CPU1_SB_RSP<0>")
	)
	(segment
		(start 164.874702 -247.228614)
		(end 163.95319 -248.150126)
		(width 0.18288)
		(layer "In6.Cu")
		(net "M_F_CPU1_SB_RSP<0>")
	)
	(segment
		(start 169.462196 -246.304054)
		(end 168.44899 -246.304054)
		(width 0.18288)
		(layer "In6.Cu")
		(net "M_F_CPU1_SB_RSP<0>")
	)
	(segment
		(start 177.941732 -243.95938)
		(end 177.40884 -244.492272)
		(width 0.18288)
		(layer "In6.Cu")
		(net "M_F_CPU1_SB_RSP<0>")
	)
	(segment
		(start 177.40884 -244.492272)
		(end 176.734216 -244.492272)
		(width 0.18288)
		(layer "In6.Cu")
		(net "M_F_CPU1_SB_RSP<0>")
	)
	(segment
		(start 175.170846 -244.492526)
		(end 174.730918 -244.492526)
		(width 0.18288)
		(layer "In6.Cu")
		(net "M_F_CPU1_SB_RSP<0>")
	)
	(segment
		(start 173.559216 -244.97792)
		(end 173.194726 -245.34241)
		(width 0.18288)
		(layer "In6.Cu")
		(net "M_F_CPU1_SB_RSP<0>")
	)
	(segment
		(start 144.295114 -248.87809)
		(end 141.96568 -251.207524)
		(width 0.18288)
		(layer "In6.Cu")
		(net "M_F_CPU1_SB_RSP<0>")
	)
	(segment
		(start 175.183546 -244.479826)
		(end 175.170846 -244.492526)
		(width 0.18288)
		(layer "In6.Cu")
		(net "M_F_CPU1_SB_RSP<0>")
	)
	(segment
		(start 129.041144 -252.520196)
		(end 129.041144 -253.2126)
		(width 0.18288)
		(layer "In6.Cu")
		(net "M_F_CPU1_SB_RSP<0>")
	)
	(segment
		(start 149.16785 -249.562874)
		(end 148.483066 -248.87809)
		(width 0.18288)
		(layer "In6.Cu")
		(net "M_F_CPU1_SB_RSP<0>")
	)
	(segment
		(start 170.234864 -245.787672)
		(end 169.462196 -246.304054)
		(width 0.18288)
		(layer "In6.Cu")
		(net "M_F_CPU1_SB_RSP<0>")
	)
	(segment
		(start 171.3103 -245.34241)
		(end 170.234864 -245.787672)
		(width 0.18288)
		(layer "In6.Cu")
		(net "M_F_CPU1_SB_RSP<0>")
	)
	(segment
		(start 168.44899 -246.304054)
		(end 167.52443 -247.228614)
		(width 0.18288)
		(layer "In6.Cu")
		(net "M_F_CPU1_SB_RSP<0>")
	)
	(segment
		(start 176.72177 -244.479826)
		(end 175.183546 -244.479826)
		(width 0.18288)
		(layer "In6.Cu")
		(net "M_F_CPU1_SB_RSP<0>")
	)
	(segment
		(start 179.23637 -243.423186)
		(end 177.941732 -243.95938)
		(width 0.18288)
		(layer "In6.Cu")
		(net "M_F_CPU1_SB_RSP<0>")
	)
	(segment
		(start 163.95319 -248.150126)
		(end 160.781238 -248.150126)
		(width 0.18288)
		(layer "In6.Cu")
		(net "M_F_CPU1_SB_RSP<0>")
	)
	(segment
		(start 148.483066 -248.87809)
		(end 144.295114 -248.87809)
		(width 0.18288)
		(layer "In6.Cu")
		(net "M_F_CPU1_SB_RSP<0>")
	)
	(segment
		(start 160.024572 -248.906792)
		(end 155.593034 -248.906792)
		(width 0.18288)
		(layer "In6.Cu")
		(net "M_F_CPU1_SB_RSP<0>")
	)
	(segment
		(start 173.194726 -245.34241)
		(end 171.3103 -245.34241)
		(width 0.18288)
		(layer "In6.Cu")
		(net "M_F_CPU1_SB_RSP<0>")
	)
	(segment
		(start 141.96568 -251.207524)
		(end 130.353816 -251.207524)
		(width 0.18288)
		(layer "In6.Cu")
		(net "M_F_CPU1_SB_RSP<0>")
	)
	(segment
		(start 176.734216 -244.492272)
		(end 176.72177 -244.479826)
		(width 0.18288)
		(layer "In6.Cu")
		(net "M_F_CPU1_SB_RSP<0>")
	)
	(segment
		(start 155.593034 -248.906792)
		(end 154.936952 -249.562874)
		(width 0.18288)
		(layer "In6.Cu")
		(net "M_F_CPU1_SB_RSP<0>")
	)
	(segment
		(start 128.588008 -254.335026)
		(end 128.218946 -254.335026)
		(width 0.088646)
		(layer "In6.Cu")
		(net "M_F_CPU1_SB_RSP<0>")
	)
	(segment
		(start 129.041144 -253.2126)
		(end 129.041144 -253.928372)
		(width 0.088646)
		(layer "In6.Cu")
		(net "M_F_CPU1_SB_RSP<0>")
	)
	(segment
		(start 130.353816 -251.207524)
		(end 129.041144 -252.520196)
		(width 0.18288)
		(layer "In6.Cu")
		(net "M_F_CPU1_SB_RSP<0>")
	)
	(segment
		(start 160.781238 -248.150126)
		(end 160.024572 -248.906792)
		(width 0.18288)
		(layer "In6.Cu")
		(net "M_F_CPU1_SB_RSP<0>")
	)
	(segment
		(start 174.730918 -244.492526)
		(end 173.559216 -244.97792)
		(width 0.18288)
		(layer "In6.Cu")
		(net "M_F_CPU1_SB_RSP<0>")
	)
	(segment
		(start 180.314346 -243.216684)
		(end 180.107844 -243.423186)
		(width 0.18288)
		(layer "In6.Cu")
		(net "M_F_CPU1_SB_RSP<0>")
	)
	(segment
		(start 154.936952 -249.562874)
		(end 149.16785 -249.562874)
		(width 0.18288)
		(layer "In6.Cu")
		(net "M_F_CPU1_SB_RSP<0>")
	)
	(segment
		(start 167.52443 -247.228614)
		(end 164.874702 -247.228614)
		(width 0.18288)
		(layer "In6.Cu")
		(net "M_F_CPU1_SB_RSP<0>")
	)
	(arc
		(start 129.041144 -253.928372)
		(mid 128.988874 -254.110737)
		(end 128.853946 -254.244094)
		(width 0.088646)
		(layer "In6.Cu")
		(net "M_F_CPU1_SB_RSP<0>")
	)
	(arc
		(start 128.676146 -254.321818)
		(mid 128.632572 -254.331713)
		(end 128.588008 -254.335026)
		(width 0.088646)
		(layer "In6.Cu")
		(net "M_F_CPU1_SB_RSP<0>")
	)
	(arc
		(start 128.853946 -254.244094)
		(mid 128.767225 -254.287942)
		(end 128.676146 -254.321818)
		(width 0.088646)
		(layer "In6.Cu")
		(net "M_F_CPU1_SB_RSP<0>")
	)
	(arc
		(start 128.218946 -254.335026)
		(mid 127.698251 -254.438616)
		(end 127.256794 -254.733552)
		(width 0.088646)
		(layer "In6.Cu")
		(net "M_F_CPU1_SB_RSP<0>")
	)
	(segment
		(start 180.072284 -247.052338)
		(end 180.423058 -247.052338)
		(width 0.20066)
		(layer "F.Cu")
		(net "M_F_CPU1_SB_PAR")
	)
	(segment
		(start 184.430162 -246.616728)
		(end 185.544714 -246.616728)
		(width 0.20066)
		(layer "F.Cu")
		(net "M_F_CPU1_SB_PAR")
	)
	(segment
		(start 182.447692 -247.04167)
		(end 182.455058 -247.049036)
		(width 0.1016)
		(layer "F.Cu")
		(net "M_F_CPU1_SB_PAR")
	)
	(segment
		(start 135.605266 -245.27256)
		(end 135.605266 -244.73662)
		(width 0.20066)
		(layer "F.Cu")
		(net "M_F_CPU1_SB_PAR")
	)
	(segment
		(start 176.896014 -246.616728)
		(end 178.000914 -246.616728)
		(width 0.20066)
		(layer "F.Cu")
		(net "M_F_CPU1_SB_PAR")
	)
	(segment
		(start 183.593994 -246.184166)
		(end 183.9976 -246.184166)
		(width 0.20066)
		(layer "F.Cu")
		(net "M_F_CPU1_SB_PAR")
	)
	(segment
		(start 180.438552 -247.04167)
		(end 182.447692 -247.04167)
		(width 0.1016)
		(layer "F.Cu")
		(net "M_F_CPU1_SB_PAR")
	)
	(segment
		(start 180.423058 -247.052338)
		(end 180.427884 -247.052338)
		(width 0.101854)
		(layer "F.Cu")
		(net "M_F_CPU1_SB_PAR")
	)
	(segment
		(start 183.9976 -246.184166)
		(end 184.430162 -246.616728)
		(width 0.20066)
		(layer "F.Cu")
		(net "M_F_CPU1_SB_PAR")
	)
	(segment
		(start 182.455058 -247.049036)
		(end 182.729124 -247.049036)
		(width 0.20066)
		(layer "F.Cu")
		(net "M_F_CPU1_SB_PAR")
	)
	(segment
		(start 178.000914 -246.616728)
		(end 179.636674 -246.616728)
		(width 0.20066)
		(layer "F.Cu")
		(net "M_F_CPU1_SB_PAR")
	)
	(segment
		(start 179.636674 -246.616728)
		(end 180.072284 -247.052338)
		(width 0.20066)
		(layer "F.Cu")
		(net "M_F_CPU1_SB_PAR")
	)
	(segment
		(start 182.729124 -247.049036)
		(end 183.593994 -246.184166)
		(width 0.20066)
		(layer "F.Cu")
		(net "M_F_CPU1_SB_PAR")
	)
	(segment
		(start 180.427884 -247.052338)
		(end 180.438552 -247.04167)
		(width 0.1016)
		(layer "F.Cu")
		(net "M_F_CPU1_SB_PAR")
	)
	(segment
		(start 150.6347 -247.401842)
		(end 150.104348 -246.87149)
		(width 0.18288)
		(layer "In2.Cu")
		(net "M_F_CPU1_SB_PAR")
	)
	(segment
		(start 135.700516 -245.516654)
		(end 135.605266 -244.73662)
		(width 0.088646)
		(layer "In2.Cu")
		(net "M_F_CPU1_SB_PAR")
	)
	(segment
		(start 159.619696 -246.996204)
		(end 158.049214 -246.996204)
		(width 0.18288)
		(layer "In2.Cu")
		(net "M_F_CPU1_SB_PAR")
	)
	(segment
		(start 173.987206 -246.468392)
		(end 173.585124 -246.468392)
		(width 0.18288)
		(layer "In2.Cu")
		(net "M_F_CPU1_SB_PAR")
	)
	(segment
		(start 174.342552 -247.070626)
		(end 174.147226 -246.8753)
		(width 0.18288)
		(layer "In2.Cu")
		(net "M_F_CPU1_SB_PAR")
	)
	(segment
		(start 159.844486 -247.220994)
		(end 159.619696 -246.996204)
		(width 0.18288)
		(layer "In2.Cu")
		(net "M_F_CPU1_SB_PAR")
	)
	(segment
		(start 165.50132 -247.034812)
		(end 165.236906 -247.299226)
		(width 0.18288)
		(layer "In2.Cu")
		(net "M_F_CPU1_SB_PAR")
	)
	(segment
		(start 175.949356 -246.314214)
		(end 175.601376 -246.314214)
		(width 0.18288)
		(layer "In2.Cu")
		(net "M_F_CPU1_SB_PAR")
	)
	(segment
		(start 153.773378 -247.401842)
		(end 150.6347 -247.401842)
		(width 0.18288)
		(layer "In2.Cu")
		(net "M_F_CPU1_SB_PAR")
	)
	(segment
		(start 176.147476 -246.89435)
		(end 176.147476 -246.512334)
		(width 0.18288)
		(layer "In2.Cu")
		(net "M_F_CPU1_SB_PAR")
	)
	(segment
		(start 171.546266 -246.717058)
		(end 171.237148 -247.026176)
		(width 0.18288)
		(layer "In2.Cu")
		(net "M_F_CPU1_SB_PAR")
	)
	(segment
		(start 176.307496 -247.05437)
		(end 176.147476 -246.89435)
		(width 0.18288)
		(layer "In2.Cu")
		(net "M_F_CPU1_SB_PAR")
	)
	(segment
		(start 169.184828 -247.026176)
		(end 168.71442 -246.555768)
		(width 0.18288)
		(layer "In2.Cu")
		(net "M_F_CPU1_SB_PAR")
	)
	(segment
		(start 175.601376 -246.314214)
		(end 175.441356 -246.474234)
		(width 0.18288)
		(layer "In2.Cu")
		(net "M_F_CPU1_SB_PAR")
	)
	(segment
		(start 175.441356 -246.910606)
		(end 175.281336 -247.070626)
		(width 0.18288)
		(layer "In2.Cu")
		(net "M_F_CPU1_SB_PAR")
	)
	(segment
		(start 168.30294 -246.555768)
		(end 167.684196 -247.174512)
		(width 0.18288)
		(layer "In2.Cu")
		(net "M_F_CPU1_SB_PAR")
	)
	(segment
		(start 138.370056 -246.763286)
		(end 138.050016 -246.443246)
		(width 0.088646)
		(layer "In2.Cu")
		(net "M_F_CPU1_SB_PAR")
	)
	(segment
		(start 171.237148 -247.026176)
		(end 169.184828 -247.026176)
		(width 0.18288)
		(layer "In2.Cu")
		(net "M_F_CPU1_SB_PAR")
	)
	(segment
		(start 168.71442 -246.555768)
		(end 168.30294 -246.555768)
		(width 0.18288)
		(layer "In2.Cu")
		(net "M_F_CPU1_SB_PAR")
	)
	(segment
		(start 174.147226 -246.8753)
		(end 174.147226 -246.628412)
		(width 0.18288)
		(layer "In2.Cu")
		(net "M_F_CPU1_SB_PAR")
	)
	(segment
		(start 172.34789 -247.040908)
		(end 172.02404 -246.717058)
		(width 0.18288)
		(layer "In2.Cu")
		(net "M_F_CPU1_SB_PAR")
	)
	(segment
		(start 157.894782 -247.150636)
		(end 157.362906 -247.150636)
		(width 0.18288)
		(layer "In2.Cu")
		(net "M_F_CPU1_SB_PAR")
	)
	(segment
		(start 164.649912 -247.034812)
		(end 160.749234 -247.034812)
		(width 0.18288)
		(layer "In2.Cu")
		(net "M_F_CPU1_SB_PAR")
	)
	(segment
		(start 154.37866 -248.007124)
		(end 153.773378 -247.401842)
		(width 0.18288)
		(layer "In2.Cu")
		(net "M_F_CPU1_SB_PAR")
	)
	(segment
		(start 138.050016 -246.443246)
		(end 138.050016 -246.130064)
		(width 0.088646)
		(layer "In2.Cu")
		(net "M_F_CPU1_SB_PAR")
	)
	(segment
		(start 173.265084 -247.040908)
		(end 172.34789 -247.040908)
		(width 0.18288)
		(layer "In2.Cu")
		(net "M_F_CPU1_SB_PAR")
	)
	(segment
		(start 158.049214 -246.996204)
		(end 157.894782 -247.150636)
		(width 0.18288)
		(layer "In2.Cu")
		(net "M_F_CPU1_SB_PAR")
	)
	(segment
		(start 156.506418 -248.007124)
		(end 154.37866 -248.007124)
		(width 0.18288)
		(layer "In2.Cu")
		(net "M_F_CPU1_SB_PAR")
	)
	(segment
		(start 167.684196 -247.174512)
		(end 167.410892 -247.174512)
		(width 0.18288)
		(layer "In2.Cu")
		(net "M_F_CPU1_SB_PAR")
	)
	(segment
		(start 173.425104 -246.628412)
		(end 173.425104 -246.880888)
		(width 0.18288)
		(layer "In2.Cu")
		(net "M_F_CPU1_SB_PAR")
	)
	(segment
		(start 174.147226 -246.628412)
		(end 173.987206 -246.468392)
		(width 0.18288)
		(layer "In2.Cu")
		(net "M_F_CPU1_SB_PAR")
	)
	(segment
		(start 173.585124 -246.468392)
		(end 173.425104 -246.628412)
		(width 0.18288)
		(layer "In2.Cu")
		(net "M_F_CPU1_SB_PAR")
	)
	(segment
		(start 165.236906 -247.299226)
		(end 164.914326 -247.299226)
		(width 0.18288)
		(layer "In2.Cu")
		(net "M_F_CPU1_SB_PAR")
	)
	(segment
		(start 175.441356 -246.474234)
		(end 175.441356 -246.910606)
		(width 0.18288)
		(layer "In2.Cu")
		(net "M_F_CPU1_SB_PAR")
	)
	(segment
		(start 176.147476 -246.512334)
		(end 175.949356 -246.314214)
		(width 0.18288)
		(layer "In2.Cu")
		(net "M_F_CPU1_SB_PAR")
	)
	(segment
		(start 176.896014 -246.616728)
		(end 176.896014 -246.868696)
		(width 0.18288)
		(layer "In2.Cu")
		(net "M_F_CPU1_SB_PAR")
	)
	(segment
		(start 176.896014 -246.868696)
		(end 176.71034 -247.05437)
		(width 0.18288)
		(layer "In2.Cu")
		(net "M_F_CPU1_SB_PAR")
	)
	(segment
		(start 167.410892 -247.174512)
		(end 167.271192 -247.034812)
		(width 0.18288)
		(layer "In2.Cu")
		(net "M_F_CPU1_SB_PAR")
	)
	(segment
		(start 167.271192 -247.034812)
		(end 165.50132 -247.034812)
		(width 0.18288)
		(layer "In2.Cu")
		(net "M_F_CPU1_SB_PAR")
	)
	(segment
		(start 175.281336 -247.070626)
		(end 174.342552 -247.070626)
		(width 0.18288)
		(layer "In2.Cu")
		(net "M_F_CPU1_SB_PAR")
	)
	(segment
		(start 139.096242 -247.489472)
		(end 138.370056 -246.763286)
		(width 0.18288)
		(layer "In2.Cu")
		(net "M_F_CPU1_SB_PAR")
	)
	(segment
		(start 150.104348 -246.87149)
		(end 140.957808 -246.87149)
		(width 0.18288)
		(layer "In2.Cu")
		(net "M_F_CPU1_SB_PAR")
	)
	(segment
		(start 160.749234 -247.034812)
		(end 160.563052 -247.220994)
		(width 0.18288)
		(layer "In2.Cu")
		(net "M_F_CPU1_SB_PAR")
	)
	(segment
		(start 135.700516 -245.55069)
		(end 135.700516 -245.516654)
		(width 0.088646)
		(layer "In2.Cu")
		(net "M_F_CPU1_SB_PAR")
	)
	(segment
		(start 140.339826 -247.489472)
		(end 139.096242 -247.489472)
		(width 0.18288)
		(layer "In2.Cu")
		(net "M_F_CPU1_SB_PAR")
	)
	(segment
		(start 138.050016 -246.130064)
		(end 137.884662 -245.96471)
		(width 0.088646)
		(layer "In2.Cu")
		(net "M_F_CPU1_SB_PAR")
	)
	(segment
		(start 172.02404 -246.717058)
		(end 171.546266 -246.717058)
		(width 0.18288)
		(layer "In2.Cu")
		(net "M_F_CPU1_SB_PAR")
	)
	(segment
		(start 160.563052 -247.220994)
		(end 159.844486 -247.220994)
		(width 0.18288)
		(layer "In2.Cu")
		(net "M_F_CPU1_SB_PAR")
	)
	(segment
		(start 164.914326 -247.299226)
		(end 164.649912 -247.034812)
		(width 0.18288)
		(layer "In2.Cu")
		(net "M_F_CPU1_SB_PAR")
	)
	(segment
		(start 135.887968 -245.875048)
		(end 135.879078 -245.869968)
		(width 0.088646)
		(layer "In2.Cu")
		(net "M_F_CPU1_SB_PAR")
	)
	(segment
		(start 140.957808 -246.87149)
		(end 140.339826 -247.489472)
		(width 0.18288)
		(layer "In2.Cu")
		(net "M_F_CPU1_SB_PAR")
	)
	(segment
		(start 173.425104 -246.880888)
		(end 173.265084 -247.040908)
		(width 0.18288)
		(layer "In2.Cu")
		(net "M_F_CPU1_SB_PAR")
	)
	(segment
		(start 157.362906 -247.150636)
		(end 156.506418 -248.007124)
		(width 0.18288)
		(layer "In2.Cu")
		(net "M_F_CPU1_SB_PAR")
	)
	(segment
		(start 176.71034 -247.05437)
		(end 176.307496 -247.05437)
		(width 0.18288)
		(layer "In2.Cu")
		(net "M_F_CPU1_SB_PAR")
	)
	(arc
		(start 136.827768 -245.875048)
		(mid 136.545066 -245.799272)
		(end 136.262364 -245.875048)
		(width 0.088646)
		(layer "In2.Cu")
		(net "M_F_CPU1_SB_PAR")
	)
	(arc
		(start 137.767568 -245.875048)
		(mid 137.484866 -245.799272)
		(end 137.202164 -245.875048)
		(width 0.088646)
		(layer "In2.Cu")
		(net "M_F_CPU1_SB_PAR")
	)
	(arc
		(start 135.879078 -245.869968)
		(mid 135.748164 -245.733608)
		(end 135.700516 -245.55069)
		(width 0.088646)
		(layer "In2.Cu")
		(net "M_F_CPU1_SB_PAR")
	)
	(arc
		(start 136.262364 -245.875048)
		(mid 136.075166 -245.925191)
		(end 135.887968 -245.875048)
		(width 0.088646)
		(layer "In2.Cu")
		(net "M_F_CPU1_SB_PAR")
	)
	(arc
		(start 137.202164 -245.875048)
		(mid 137.014966 -245.925191)
		(end 136.827768 -245.875048)
		(width 0.088646)
		(layer "In2.Cu")
		(net "M_F_CPU1_SB_PAR")
	)
	(arc
		(start 137.884662 -245.96471)
		(mid 137.829057 -245.916036)
		(end 137.767568 -245.875048)
		(width 0.088646)
		(layer "In2.Cu")
		(net "M_F_CPU1_SB_PAR")
	)
	(segment
		(start 180.61432 -237.834932)
		(end 180.896006 -238.116618)
		(width 0.20066)
		(layer "F.Cu")
		(net "M_F_CPU1_SB_DQS_DP<9>")
	)
	(segment
		(start 132.785866 -240.389156)
		(end 132.785866 -239.85347)
		(width 0.20066)
		(layer "F.Cu")
		(net "M_F_CPU1_SB_DQS_DP<9>")
	)
	(segment
		(start 176.8221 -238.541814)
		(end 176.848008 -238.541814)
		(width 0.101854)
		(layer "F.Cu")
		(net "M_F_CPU1_SB_DQS_DP<9>")
	)
	(segment
		(start 176.431448 -238.290608)
		(end 176.682654 -238.541814)
		(width 0.20066)
		(layer "F.Cu")
		(net "M_F_CPU1_SB_DQS_DP<9>")
	)
	(segment
		(start 179.00523 -238.541814)
		(end 179.011326 -238.54791)
		(width 0.1016)
		(layer "F.Cu")
		(net "M_F_CPU1_SB_DQS_DP<9>")
	)
	(segment
		(start 175.745648 -238.290608)
		(end 176.431448 -238.290608)
		(width 0.20066)
		(layer "F.Cu")
		(net "M_F_CPU1_SB_DQS_DP<9>")
	)
	(segment
		(start 180.007768 -238.245396)
		(end 180.418232 -237.834932)
		(width 0.20066)
		(layer "F.Cu")
		(net "M_F_CPU1_SB_DQS_DP<9>")
	)
	(segment
		(start 174.490126 -238.116618)
		(end 174.730664 -237.87608)
		(width 0.20066)
		(layer "F.Cu")
		(net "M_F_CPU1_SB_DQS_DP<9>")
	)
	(segment
		(start 176.848008 -238.541814)
		(end 179.00523 -238.541814)
		(width 0.1016)
		(layer "F.Cu")
		(net "M_F_CPU1_SB_DQS_DP<9>")
	)
	(segment
		(start 179.011326 -238.54791)
		(end 179.334668 -238.54791)
		(width 0.20066)
		(layer "F.Cu")
		(net "M_F_CPU1_SB_DQS_DP<9>")
	)
	(segment
		(start 176.682654 -238.541814)
		(end 176.8221 -238.541814)
		(width 0.20066)
		(layer "F.Cu")
		(net "M_F_CPU1_SB_DQS_DP<9>")
	)
	(segment
		(start 180.418232 -237.834932)
		(end 180.61432 -237.834932)
		(width 0.20066)
		(layer "F.Cu")
		(net "M_F_CPU1_SB_DQS_DP<9>")
	)
	(segment
		(start 172.795946 -238.116618)
		(end 173.900846 -238.116618)
		(width 0.20066)
		(layer "F.Cu")
		(net "M_F_CPU1_SB_DQS_DP<9>")
	)
	(segment
		(start 132.785866 -239.85347)
		(end 132.785612 -239.853216)
		(width 0.20066)
		(layer "F.Cu")
		(net "M_F_CPU1_SB_DQS_DP<9>")
	)
	(segment
		(start 175.33112 -237.87608)
		(end 175.745648 -238.290608)
		(width 0.20066)
		(layer "F.Cu")
		(net "M_F_CPU1_SB_DQS_DP<9>")
	)
	(segment
		(start 179.637182 -238.245396)
		(end 180.007768 -238.245396)
		(width 0.20066)
		(layer "F.Cu")
		(net "M_F_CPU1_SB_DQS_DP<9>")
	)
	(segment
		(start 180.896006 -238.116618)
		(end 181.444646 -238.116618)
		(width 0.20066)
		(layer "F.Cu")
		(net "M_F_CPU1_SB_DQS_DP<9>")
	)
	(segment
		(start 174.730664 -237.87608)
		(end 175.33112 -237.87608)
		(width 0.20066)
		(layer "F.Cu")
		(net "M_F_CPU1_SB_DQS_DP<9>")
	)
	(segment
		(start 173.900846 -238.116618)
		(end 174.490126 -238.116618)
		(width 0.20066)
		(layer "F.Cu")
		(net "M_F_CPU1_SB_DQS_DP<9>")
	)
	(segment
		(start 179.334668 -238.54791)
		(end 179.637182 -238.245396)
		(width 0.20066)
		(layer "F.Cu")
		(net "M_F_CPU1_SB_DQS_DP<9>")
	)
	(segment
		(start 167.196008 -236.998256)
		(end 167.196008 -236.982508)
		(width 0.16002)
		(layer "In2.Cu")
		(net "M_F_CPU1_SB_DQS_DP<9>")
	)
	(segment
		(start 161.643568 -237.544102)
		(end 161.3662 -237.544102)
		(width 0.18288)
		(layer "In2.Cu")
		(net "M_F_CPU1_SB_DQS_DP<9>")
	)
	(segment
		(start 163.900104 -237.831376)
		(end 163.900104 -237.847632)
		(width 0.16002)
		(layer "In2.Cu")
		(net "M_F_CPU1_SB_DQS_DP<9>")
	)
	(segment
		(start 157.679644 -238.537496)
		(end 157.65145 -238.509302)
		(width 0.16002)
		(layer "In2.Cu")
		(net "M_F_CPU1_SB_DQS_DP<9>")
	)
	(segment
		(start 165.623748 -236.87659)
		(end 165.595554 -236.904784)
		(width 0.16002)
		(layer "In2.Cu")
		(net "M_F_CPU1_SB_DQS_DP<9>")
	)
	(segment
		(start 169.273728 -237.629192)
		(end 169.245534 -237.600998)
		(width 0.16002)
		(layer "In2.Cu")
		(net "M_F_CPU1_SB_DQS_DP<9>")
	)
	(segment
		(start 140.080746 -241.684302)
		(end 139.693142 -241.84483)
		(width 0.088646)
		(layer "In2.Cu")
		(net "M_F_CPU1_SB_DQS_DP<9>")
	)
	(segment
		(start 169.289984 -237.629192)
		(end 169.273728 -237.629192)
		(width 0.16002)
		(layer "In2.Cu")
		(net "M_F_CPU1_SB_DQS_DP<9>")
	)
	(segment
		(start 165.052248 -237.44809)
		(end 164.299646 -237.44809)
		(width 0.18288)
		(layer "In2.Cu")
		(net "M_F_CPU1_SB_DQS_DP<9>")
	)
	(segment
		(start 171.413932 -237.857284)
		(end 171.214542 -238.056674)
		(width 0.18288)
		(layer "In2.Cu")
		(net "M_F_CPU1_SB_DQS_DP<9>")
	)
	(segment
		(start 166.995602 -236.79785)
		(end 166.967408 -236.769656)
		(width 0.16002)
		(layer "In2.Cu")
		(net "M_F_CPU1_SB_DQS_DP<9>")
	)
	(segment
		(start 164.10051 -237.647226)
		(end 164.084254 -237.647226)
		(width 0.16002)
		(layer "In2.Cu")
		(net "M_F_CPU1_SB_DQS_DP<9>")
	)
	(segment
		(start 172.795946 -238.116618)
		(end 172.795946 -238.114586)
		(width 0.18288)
		(layer "In2.Cu")
		(net "M_F_CPU1_SB_DQS_DP<9>")
	)
	(segment
		(start 163.682426 -238.06531)
		(end 162.164776 -238.06531)
		(width 0.18288)
		(layer "In2.Cu")
		(net "M_F_CPU1_SB_DQS_DP<9>")
	)
	(segment
		(start 165.395148 -237.089442)
		(end 165.395148 -237.10519)
		(width 0.16002)
		(layer "In2.Cu")
		(net "M_F_CPU1_SB_DQS_DP<9>")
	)
	(segment
		(start 163.87191 -237.875826)
		(end 163.682426 -238.06531)
		(width 0.18288)
		(layer "In2.Cu")
		(net "M_F_CPU1_SB_DQS_DP<9>")
	)
	(segment
		(start 165.872668 -236.62767)
		(end 165.623748 -236.87659)
		(width 0.18288)
		(layer "In2.Cu")
		(net "M_F_CPU1_SB_DQS_DP<9>")
	)
	(segment
		(start 161.706052 -237.606586)
		(end 161.643568 -237.544102)
		(width 0.18288)
		(layer "In2.Cu")
		(net "M_F_CPU1_SB_DQS_DP<9>")
	)
	(segment
		(start 169.474134 -237.813342)
		(end 169.289984 -237.629192)
		(width 0.16002)
		(layer "In2.Cu")
		(net "M_F_CPU1_SB_DQS_DP<9>")
	)
	(segment
		(start 158.038038 -238.89589)
		(end 157.862524 -238.720376)
		(width 0.18288)
		(layer "In2.Cu")
		(net "M_F_CPU1_SB_DQS_DP<9>")
	)
	(segment
		(start 165.595554 -236.904784)
		(end 165.579806 -236.904784)
		(width 0.16002)
		(layer "In2.Cu")
		(net "M_F_CPU1_SB_DQS_DP<9>")
	)
	(segment
		(start 157.65145 -238.509302)
		(end 157.557978 -238.41583)
		(width 0.18288)
		(layer "In2.Cu")
		(net "M_F_CPU1_SB_DQS_DP<9>")
	)
	(segment
		(start 133.09854 -239.853216)
		(end 132.785612 -239.853216)
		(width 0.088646)
		(layer "In2.Cu")
		(net "M_F_CPU1_SB_DQS_DP<9>")
	)
	(segment
		(start 162.164776 -238.06531)
		(end 161.962846 -237.86338)
		(width 0.18288)
		(layer "In2.Cu")
		(net "M_F_CPU1_SB_DQS_DP<9>")
	)
	(segment
		(start 172.795946 -238.114586)
		(end 172.523912 -237.842552)
		(width 0.18288)
		(layer "In2.Cu")
		(net "M_F_CPU1_SB_DQS_DP<9>")
	)
	(segment
		(start 140.518896 -241.744246)
		(end 140.458952 -241.684302)
		(width 0.088646)
		(layer "In2.Cu")
		(net "M_F_CPU1_SB_DQS_DP<9>")
	)
	(segment
		(start 171.580556 -237.674404)
		(end 171.442126 -237.812834)
		(width 0.16002)
		(layer "In2.Cu")
		(net "M_F_CPU1_SB_DQS_DP<9>")
	)
	(segment
		(start 157.83433 -238.692182)
		(end 157.83433 -238.675926)
		(width 0.16002)
		(layer "In2.Cu")
		(net "M_F_CPU1_SB_DQS_DP<9>")
	)
	(segment
		(start 153.918158 -241.744246)
		(end 140.518896 -241.744246)
		(width 0.18288)
		(layer "In2.Cu")
		(net "M_F_CPU1_SB_DQS_DP<9>")
	)
	(segment
		(start 165.395148 -237.10519)
		(end 165.366954 -237.133384)
		(width 0.16002)
		(layer "In2.Cu")
		(net "M_F_CPU1_SB_DQS_DP<9>")
	)
	(segment
		(start 169.70121 -238.056674)
		(end 169.502328 -237.857792)
		(width 0.18288)
		(layer "In2.Cu")
		(net "M_F_CPU1_SB_DQS_DP<9>")
	)
	(segment
		(start 171.442126 -237.812834)
		(end 171.442126 -237.82909)
		(width 0.16002)
		(layer "In2.Cu")
		(net "M_F_CPU1_SB_DQS_DP<9>")
	)
	(segment
		(start 161.750502 -237.63478)
		(end 161.734246 -237.63478)
		(width 0.16002)
		(layer "In2.Cu")
		(net "M_F_CPU1_SB_DQS_DP<9>")
	)
	(segment
		(start 169.502328 -237.857792)
		(end 169.474134 -237.829598)
		(width 0.16002)
		(layer "In2.Cu")
		(net "M_F_CPU1_SB_DQS_DP<9>")
	)
	(segment
		(start 161.3662 -237.544102)
		(end 160.958784 -237.951518)
		(width 0.18288)
		(layer "In2.Cu")
		(net "M_F_CPU1_SB_DQS_DP<9>")
	)
	(segment
		(start 160.958784 -237.951518)
		(end 159.92729 -238.641128)
		(width 0.18288)
		(layer "In2.Cu")
		(net "M_F_CPU1_SB_DQS_DP<9>")
	)
	(segment
		(start 164.299646 -237.44809)
		(end 164.128704 -237.619032)
		(width 0.18288)
		(layer "In2.Cu")
		(net "M_F_CPU1_SB_DQS_DP<9>")
	)
	(segment
		(start 166.825422 -236.62767)
		(end 165.872668 -236.62767)
		(width 0.18288)
		(layer "In2.Cu")
		(net "M_F_CPU1_SB_DQS_DP<9>")
	)
	(segment
		(start 171.214542 -238.056674)
		(end 169.70121 -238.056674)
		(width 0.18288)
		(layer "In2.Cu")
		(net "M_F_CPU1_SB_DQS_DP<9>")
	)
	(segment
		(start 167.01135 -236.79785)
		(end 166.995602 -236.79785)
		(width 0.16002)
		(layer "In2.Cu")
		(net "M_F_CPU1_SB_DQS_DP<9>")
	)
	(segment
		(start 157.83433 -238.675926)
		(end 157.6959 -238.537496)
		(width 0.16002)
		(layer "In2.Cu")
		(net "M_F_CPU1_SB_DQS_DP<9>")
	)
	(segment
		(start 167.196008 -236.982508)
		(end 167.01135 -236.79785)
		(width 0.16002)
		(layer "In2.Cu")
		(net "M_F_CPU1_SB_DQS_DP<9>")
	)
	(segment
		(start 171.982892 -237.565438)
		(end 171.705778 -237.565438)
		(width 0.18288)
		(layer "In2.Cu")
		(net "M_F_CPU1_SB_DQS_DP<9>")
	)
	(segment
		(start 165.366954 -237.133384)
		(end 165.052248 -237.44809)
		(width 0.18288)
		(layer "In2.Cu")
		(net "M_F_CPU1_SB_DQS_DP<9>")
	)
	(segment
		(start 171.625006 -237.64621)
		(end 171.596812 -237.674404)
		(width 0.16002)
		(layer "In2.Cu")
		(net "M_F_CPU1_SB_DQS_DP<9>")
	)
	(segment
		(start 171.596812 -237.674404)
		(end 171.580556 -237.674404)
		(width 0.16002)
		(layer "In2.Cu")
		(net "M_F_CPU1_SB_DQS_DP<9>")
	)
	(segment
		(start 137.859516 -241.616484)
		(end 137.859516 -241.481102)
		(width 0.088646)
		(layer "In2.Cu")
		(net "M_F_CPU1_SB_DQS_DP<9>")
	)
	(segment
		(start 171.442126 -237.82909)
		(end 171.413932 -237.857284)
		(width 0.16002)
		(layer "In2.Cu")
		(net "M_F_CPU1_SB_DQS_DP<9>")
	)
	(segment
		(start 164.128704 -237.619032)
		(end 164.10051 -237.647226)
		(width 0.16002)
		(layer "In2.Cu")
		(net "M_F_CPU1_SB_DQS_DP<9>")
	)
	(segment
		(start 166.967408 -236.769656)
		(end 166.825422 -236.62767)
		(width 0.18288)
		(layer "In2.Cu")
		(net "M_F_CPU1_SB_DQS_DP<9>")
	)
	(segment
		(start 138.087862 -241.84483)
		(end 137.859516 -241.616484)
		(width 0.088646)
		(layer "In2.Cu")
		(net "M_F_CPU1_SB_DQS_DP<9>")
	)
	(segment
		(start 161.934652 -237.835186)
		(end 161.934652 -237.81893)
		(width 0.16002)
		(layer "In2.Cu")
		(net "M_F_CPU1_SB_DQS_DP<9>")
	)
	(segment
		(start 161.734246 -237.63478)
		(end 161.706052 -237.606586)
		(width 0.16002)
		(layer "In2.Cu")
		(net "M_F_CPU1_SB_DQS_DP<9>")
	)
	(segment
		(start 167.224202 -237.02645)
		(end 167.196008 -236.998256)
		(width 0.16002)
		(layer "In2.Cu")
		(net "M_F_CPU1_SB_DQS_DP<9>")
	)
	(segment
		(start 136.271254 -240.348008)
		(end 136.262364 -240.342928)
		(width 0.088646)
		(layer "In2.Cu")
		(net "M_F_CPU1_SB_DQS_DP<9>")
	)
	(segment
		(start 157.246574 -238.41583)
		(end 153.918158 -241.744246)
		(width 0.18288)
		(layer "In2.Cu")
		(net "M_F_CPU1_SB_DQS_DP<9>")
	)
	(segment
		(start 157.862524 -238.720376)
		(end 157.83433 -238.692182)
		(width 0.16002)
		(layer "In2.Cu")
		(net "M_F_CPU1_SB_DQS_DP<9>")
	)
	(segment
		(start 140.458952 -241.684302)
		(end 140.080746 -241.684302)
		(width 0.088646)
		(layer "In2.Cu")
		(net "M_F_CPU1_SB_DQS_DP<9>")
	)
	(segment
		(start 161.962846 -237.86338)
		(end 161.934652 -237.835186)
		(width 0.16002)
		(layer "In2.Cu")
		(net "M_F_CPU1_SB_DQS_DP<9>")
	)
	(segment
		(start 169.474134 -237.829598)
		(end 169.474134 -237.813342)
		(width 0.16002)
		(layer "In2.Cu")
		(net "M_F_CPU1_SB_DQS_DP<9>")
	)
	(segment
		(start 172.260006 -237.842552)
		(end 171.982892 -237.565438)
		(width 0.18288)
		(layer "In2.Cu")
		(net "M_F_CPU1_SB_DQS_DP<9>")
	)
	(segment
		(start 164.084254 -237.647226)
		(end 163.900104 -237.831376)
		(width 0.16002)
		(layer "In2.Cu")
		(net "M_F_CPU1_SB_DQS_DP<9>")
	)
	(segment
		(start 133.163818 -239.918494)
		(end 133.09854 -239.853216)
		(width 0.088646)
		(layer "In2.Cu")
		(net "M_F_CPU1_SB_DQS_DP<9>")
	)
	(segment
		(start 163.900104 -237.847632)
		(end 163.87191 -237.875826)
		(width 0.16002)
		(layer "In2.Cu")
		(net "M_F_CPU1_SB_DQS_DP<9>")
	)
	(segment
		(start 136.449816 -240.677192)
		(end 136.449816 -240.667286)
		(width 0.088646)
		(layer "In2.Cu")
		(net "M_F_CPU1_SB_DQS_DP<9>")
	)
	(segment
		(start 159.672528 -238.89589)
		(end 158.038038 -238.89589)
		(width 0.18288)
		(layer "In2.Cu")
		(net "M_F_CPU1_SB_DQS_DP<9>")
	)
	(segment
		(start 171.705778 -237.565438)
		(end 171.625006 -237.64621)
		(width 0.18288)
		(layer "In2.Cu")
		(net "M_F_CPU1_SB_DQS_DP<9>")
	)
	(segment
		(start 157.557978 -238.41583)
		(end 157.246574 -238.41583)
		(width 0.18288)
		(layer "In2.Cu")
		(net "M_F_CPU1_SB_DQS_DP<9>")
	)
	(segment
		(start 137.680954 -241.161824)
		(end 137.672064 -241.156744)
		(width 0.088646)
		(layer "In2.Cu")
		(net "M_F_CPU1_SB_DQS_DP<9>")
	)
	(segment
		(start 157.6959 -238.537496)
		(end 157.679644 -238.537496)
		(width 0.16002)
		(layer "In2.Cu")
		(net "M_F_CPU1_SB_DQS_DP<9>")
	)
	(segment
		(start 159.92729 -238.641128)
		(end 159.672528 -238.89589)
		(width 0.18288)
		(layer "In2.Cu")
		(net "M_F_CPU1_SB_DQS_DP<9>")
	)
	(segment
		(start 134.383018 -240.342928)
		(end 134.382764 -240.342928)
		(width 0.088646)
		(layer "In2.Cu")
		(net "M_F_CPU1_SB_DQS_DP<9>")
	)
	(segment
		(start 139.693142 -241.84483)
		(end 138.087862 -241.84483)
		(width 0.088646)
		(layer "In2.Cu")
		(net "M_F_CPU1_SB_DQS_DP<9>")
	)
	(segment
		(start 165.579806 -236.904784)
		(end 165.395148 -237.089442)
		(width 0.16002)
		(layer "In2.Cu")
		(net "M_F_CPU1_SB_DQS_DP<9>")
	)
	(segment
		(start 172.523912 -237.842552)
		(end 172.260006 -237.842552)
		(width 0.18288)
		(layer "In2.Cu")
		(net "M_F_CPU1_SB_DQS_DP<9>")
	)
	(segment
		(start 169.245534 -237.600998)
		(end 169.089578 -237.445042)
		(width 0.18288)
		(layer "In2.Cu")
		(net "M_F_CPU1_SB_DQS_DP<9>")
	)
	(segment
		(start 161.934652 -237.81893)
		(end 161.750502 -237.63478)
		(width 0.16002)
		(layer "In2.Cu")
		(net "M_F_CPU1_SB_DQS_DP<9>")
	)
	(segment
		(start 167.642794 -237.445042)
		(end 167.224202 -237.02645)
		(width 0.18288)
		(layer "In2.Cu")
		(net "M_F_CPU1_SB_DQS_DP<9>")
	)
	(segment
		(start 169.089578 -237.445042)
		(end 167.642794 -237.445042)
		(width 0.18288)
		(layer "In2.Cu")
		(net "M_F_CPU1_SB_DQS_DP<9>")
	)
	(arc
		(start 135.322564 -240.342928)
		(mid 135.135366 -240.292785)
		(end 134.948168 -240.342928)
		(width 0.088646)
		(layer "In2.Cu")
		(net "M_F_CPU1_SB_DQS_DP<9>")
	)
	(arc
		(start 137.859516 -241.481102)
		(mid 137.811837 -241.298202)
		(end 137.680954 -241.161824)
		(width 0.088646)
		(layer "In2.Cu")
		(net "M_F_CPU1_SB_DQS_DP<9>")
	)
	(arc
		(start 134.382764 -240.342928)
		(mid 134.195566 -240.292785)
		(end 134.008368 -240.342928)
		(width 0.088646)
		(layer "In2.Cu")
		(net "M_F_CPU1_SB_DQS_DP<9>")
	)
	(arc
		(start 133.442964 -240.342928)
		(mid 133.258908 -240.172676)
		(end 133.166612 -239.939576)
		(width 0.088646)
		(layer "In2.Cu")
		(net "M_F_CPU1_SB_DQS_DP<9>")
	)
	(arc
		(start 137.297668 -241.156744)
		(mid 137.014966 -241.23252)
		(end 136.732264 -241.156744)
		(width 0.088646)
		(layer "In2.Cu")
		(net "M_F_CPU1_SB_DQS_DP<9>")
	)
	(arc
		(start 136.732264 -241.156744)
		(mid 136.527929 -240.954139)
		(end 136.449816 -240.677192)
		(width 0.088646)
		(layer "In2.Cu")
		(net "M_F_CPU1_SB_DQS_DP<9>")
	)
	(arc
		(start 135.887968 -240.342928)
		(mid 135.605266 -240.41867)
		(end 135.322564 -240.342928)
		(width 0.088646)
		(layer "In2.Cu")
		(net "M_F_CPU1_SB_DQS_DP<9>")
	)
	(arc
		(start 134.948168 -240.342928)
		(mid 134.66561 -240.418577)
		(end 134.383018 -240.342928)
		(width 0.088646)
		(layer "In2.Cu")
		(net "M_F_CPU1_SB_DQS_DP<9>")
	)
	(arc
		(start 137.672064 -241.156744)
		(mid 137.484866 -241.106601)
		(end 137.297668 -241.156744)
		(width 0.088646)
		(layer "In2.Cu")
		(net "M_F_CPU1_SB_DQS_DP<9>")
	)
	(arc
		(start 136.262364 -240.342928)
		(mid 136.075166 -240.292785)
		(end 135.887968 -240.342928)
		(width 0.088646)
		(layer "In2.Cu")
		(net "M_F_CPU1_SB_DQS_DP<9>")
	)
	(arc
		(start 136.449816 -240.667286)
		(mid 136.402137 -240.484386)
		(end 136.271254 -240.348008)
		(width 0.088646)
		(layer "In2.Cu")
		(net "M_F_CPU1_SB_DQS_DP<9>")
	)
	(arc
		(start 134.008368 -240.342928)
		(mid 133.725666 -240.41867)
		(end 133.442964 -240.342928)
		(width 0.088646)
		(layer "In2.Cu")
		(net "M_F_CPU1_SB_DQS_DP<9>")
	)
	(arc
		(start 133.166612 -239.939576)
		(mid 133.165116 -239.929048)
		(end 133.163818 -239.918494)
		(width 0.088646)
		(layer "In2.Cu")
		(net "M_F_CPU1_SB_DQS_DP<9>")
	)
	(segment
		(start 179.85359 -198.842884)
		(end 180.111908 -198.584566)
		(width 0.20066)
		(layer "F.Cu")
		(net "M_F_CPU1_SB_DQS_DP<8>")
	)
	(segment
		(start 184.97677 -199.01662)
		(end 185.544714 -199.01662)
		(width 0.20066)
		(layer "F.Cu")
		(net "M_F_CPU1_SB_DQS_DP<8>")
	)
	(segment
		(start 183.031892 -198.839328)
		(end 183.685434 -198.839328)
		(width 0.20066)
		(layer "F.Cu")
		(net "M_F_CPU1_SB_DQS_DP<8>")
	)
	(segment
		(start 182.455058 -198.584312)
		(end 182.776876 -198.584312)
		(width 0.20066)
		(layer "F.Cu")
		(net "M_F_CPU1_SB_DQS_DP<8>")
	)
	(segment
		(start 182.447692 -198.591678)
		(end 182.455058 -198.584312)
		(width 0.1016)
		(layer "F.Cu")
		(net "M_F_CPU1_SB_DQS_DP<8>")
	)
	(segment
		(start 179.575206 -198.842884)
		(end 179.85359 -198.842884)
		(width 0.20066)
		(layer "F.Cu")
		(net "M_F_CPU1_SB_DQS_DP<8>")
	)
	(segment
		(start 178.594258 -199.01662)
		(end 178.845464 -199.267826)
		(width 0.20066)
		(layer "F.Cu")
		(net "M_F_CPU1_SB_DQS_DP<8>")
	)
	(segment
		(start 182.776876 -198.584312)
		(end 183.031892 -198.839328)
		(width 0.20066)
		(layer "F.Cu")
		(net "M_F_CPU1_SB_DQS_DP<8>")
	)
	(segment
		(start 178.000914 -199.01662)
		(end 178.594258 -199.01662)
		(width 0.20066)
		(layer "F.Cu")
		(net "M_F_CPU1_SB_DQS_DP<8>")
	)
	(segment
		(start 180.427884 -198.584566)
		(end 180.434996 -198.591678)
		(width 0.1016)
		(layer "F.Cu")
		(net "M_F_CPU1_SB_DQS_DP<8>")
	)
	(segment
		(start 180.423058 -198.584566)
		(end 180.427884 -198.584566)
		(width 0.101854)
		(layer "F.Cu")
		(net "M_F_CPU1_SB_DQS_DP<8>")
	)
	(segment
		(start 184.708546 -199.284844)
		(end 184.97677 -199.01662)
		(width 0.20066)
		(layer "F.Cu")
		(net "M_F_CPU1_SB_DQS_DP<8>")
	)
	(segment
		(start 180.434996 -198.591678)
		(end 182.447692 -198.591678)
		(width 0.1016)
		(layer "F.Cu")
		(net "M_F_CPU1_SB_DQS_DP<8>")
	)
	(segment
		(start 132.315966 -228.180646)
		(end 132.315966 -227.64496)
		(width 0.20066)
		(layer "F.Cu")
		(net "M_F_CPU1_SB_DQS_DP<8>")
	)
	(segment
		(start 183.685434 -198.839328)
		(end 184.13095 -199.284844)
		(width 0.20066)
		(layer "F.Cu")
		(net "M_F_CPU1_SB_DQS_DP<8>")
	)
	(segment
		(start 180.111908 -198.584566)
		(end 180.423058 -198.584566)
		(width 0.20066)
		(layer "F.Cu")
		(net "M_F_CPU1_SB_DQS_DP<8>")
	)
	(segment
		(start 178.845464 -199.267826)
		(end 179.150264 -199.267826)
		(width 0.20066)
		(layer "F.Cu")
		(net "M_F_CPU1_SB_DQS_DP<8>")
	)
	(segment
		(start 184.13095 -199.284844)
		(end 184.708546 -199.284844)
		(width 0.20066)
		(layer "F.Cu")
		(net "M_F_CPU1_SB_DQS_DP<8>")
	)
	(segment
		(start 179.150264 -199.267826)
		(end 179.575206 -198.842884)
		(width 0.20066)
		(layer "F.Cu")
		(net "M_F_CPU1_SB_DQS_DP<8>")
	)
	(segment
		(start 176.896014 -199.01662)
		(end 178.000914 -199.01662)
		(width 0.20066)
		(layer "F.Cu")
		(net "M_F_CPU1_SB_DQS_DP<8>")
	)
	(segment
		(start 132.315712 -228.1809)
		(end 132.315966 -228.180646)
		(width 0.20066)
		(layer "F.Cu")
		(net "M_F_CPU1_SB_DQS_DP<8>")
	)
	(segment
		(start 152.681686 -206.701136)
		(end 152.715976 -206.873602)
		(width 0.18288)
		(layer "In4.Cu")
		(net "M_F_CPU1_SB_DQS_DP<8>")
	)
	(segment
		(start 163.535868 -200.58253)
		(end 162.294824 -200.58253)
		(width 0.18288)
		(layer "In4.Cu")
		(net "M_F_CPU1_SB_DQS_DP<8>")
	)
	(segment
		(start 153.74493 -205.109826)
		(end 153.4414 -205.564232)
		(width 0.18288)
		(layer "In4.Cu")
		(net "M_F_CPU1_SB_DQS_DP<8>")
	)
	(segment
		(start 136.735312 -222.270066)
		(end 136.73455 -222.270574)
		(width 0.088646)
		(layer "In4.Cu")
		(net "M_F_CPU1_SB_DQS_DP<8>")
	)
	(segment
		(start 156.601414 -201.501248)
		(end 155.711398 -202.391264)
		(width 0.18288)
		(layer "In4.Cu")
		(net "M_F_CPU1_SB_DQS_DP<8>")
	)
	(segment
		(start 170.759374 -201.095102)
		(end 169.793666 -201.095102)
		(width 0.18288)
		(layer "In4.Cu")
		(net "M_F_CPU1_SB_DQS_DP<8>")
	)
	(segment
		(start 155.711398 -202.391264)
		(end 155.408122 -202.845162)
		(width 0.18288)
		(layer "In4.Cu")
		(net "M_F_CPU1_SB_DQS_DP<8>")
	)
	(segment
		(start 135.323326 -224.713292)
		(end 135.32231 -224.7138)
		(width 0.088646)
		(layer "In4.Cu")
		(net "M_F_CPU1_SB_DQS_DP<8>")
	)
	(segment
		(start 161.990786 -200.278492)
		(end 161.628074 -200.278492)
		(width 0.18288)
		(layer "In4.Cu")
		(net "M_F_CPU1_SB_DQS_DP<8>")
	)
	(segment
		(start 133.630416 -227.635054)
		(end 133.630416 -227.64496)
		(width 0.088646)
		(layer "In4.Cu")
		(net "M_F_CPU1_SB_DQS_DP<8>")
	)
	(segment
		(start 163.842192 -200.276206)
		(end 163.535868 -200.58253)
		(width 0.18288)
		(layer "In4.Cu")
		(net "M_F_CPU1_SB_DQS_DP<8>")
	)
	(segment
		(start 160.137094 -200.428352)
		(end 160.012634 -200.552812)
		(width 0.18288)
		(layer "In4.Cu")
		(net "M_F_CPU1_SB_DQS_DP<8>")
	)
	(segment
		(start 157.16377 -200.938892)
		(end 156.987748 -200.938892)
		(width 0.18288)
		(layer "In4.Cu")
		(net "M_F_CPU1_SB_DQS_DP<8>")
	)
	(segment
		(start 157.54985 -200.552812)
		(end 157.16377 -200.938892)
		(width 0.18288)
		(layer "In4.Cu")
		(net "M_F_CPU1_SB_DQS_DP<8>")
	)
	(segment
		(start 162.294824 -200.58253)
		(end 161.990786 -200.278492)
		(width 0.18288)
		(layer "In4.Cu")
		(net "M_F_CPU1_SB_DQS_DP<8>")
	)
	(segment
		(start 166.600632 -200.427082)
		(end 166.054532 -200.427082)
		(width 0.18288)
		(layer "In4.Cu")
		(net "M_F_CPU1_SB_DQS_DP<8>")
	)
	(segment
		(start 139.23899 -221.369382)
		(end 139.099544 -221.508828)
		(width 0.088646)
		(layer "In4.Cu")
		(net "M_F_CPU1_SB_DQS_DP<8>")
	)
	(segment
		(start 135.792464 -223.899984)
		(end 135.780272 -223.907096)
		(width 0.088646)
		(layer "In4.Cu")
		(net "M_F_CPU1_SB_DQS_DP<8>")
	)
	(segment
		(start 136.357614 -222.272098)
		(end 136.3472 -222.266002)
		(width 0.088646)
		(layer "In4.Cu")
		(net "M_F_CPU1_SB_DQS_DP<8>")
	)
	(segment
		(start 154.186636 -204.449172)
		(end 154.220926 -204.621638)
		(width 0.18288)
		(layer "In4.Cu")
		(net "M_F_CPU1_SB_DQS_DP<8>")
	)
	(segment
		(start 153.157936 -206.21244)
		(end 152.98547 -206.24673)
		(width 0.18288)
		(layer "In4.Cu")
		(net "M_F_CPU1_SB_DQS_DP<8>")
	)
	(segment
		(start 132.315966 -227.777802)
		(end 132.315966 -227.64496)
		(width 0.088646)
		(layer "In4.Cu")
		(net "M_F_CPU1_SB_DQS_DP<8>")
	)
	(segment
		(start 139.099544 -221.508828)
		(end 138.894312 -221.508828)
		(width 0.088646)
		(layer "In4.Cu")
		(net "M_F_CPU1_SB_DQS_DP<8>")
	)
	(segment
		(start 176.625504 -199.30999)
		(end 176.025556 -199.30999)
		(width 0.18288)
		(layer "In4.Cu")
		(net "M_F_CPU1_SB_DQS_DP<8>")
	)
	(segment
		(start 138.142218 -221.458536)
		(end 138.141964 -221.458282)
		(width 0.088646)
		(layer "In4.Cu")
		(net "M_F_CPU1_SB_DQS_DP<8>")
	)
	(segment
		(start 172.989748 -201.1426)
		(end 172.584872 -201.1426)
		(width 0.18288)
		(layer "In4.Cu")
		(net "M_F_CPU1_SB_DQS_DP<8>")
	)
	(segment
		(start 155.235402 -202.879452)
		(end 154.931872 -203.333858)
		(width 0.18288)
		(layer "In4.Cu")
		(net "M_F_CPU1_SB_DQS_DP<8>")
	)
	(segment
		(start 160.807654 -200.552812)
		(end 160.683194 -200.428352)
		(width 0.18288)
		(layer "In4.Cu")
		(net "M_F_CPU1_SB_DQS_DP<8>")
	)
	(segment
		(start 133.451854 -227.964238)
		(end 133.442964 -227.969318)
		(width 0.088646)
		(layer "In4.Cu")
		(net "M_F_CPU1_SB_DQS_DP<8>")
	)
	(segment
		(start 169.520362 -201.368406)
		(end 168.83761 -201.368406)
		(width 0.18288)
		(layer "In4.Cu")
		(net "M_F_CPU1_SB_DQS_DP<8>")
	)
	(segment
		(start 176.896014 -199.03948)
		(end 176.625504 -199.30999)
		(width 0.18288)
		(layer "In4.Cu")
		(net "M_F_CPU1_SB_DQS_DP<8>")
	)
	(segment
		(start 139.673584 -221.369382)
		(end 139.23899 -221.369382)
		(width 0.088646)
		(layer "In4.Cu")
		(net "M_F_CPU1_SB_DQS_DP<8>")
	)
	(segment
		(start 158.671514 -200.552812)
		(end 157.54985 -200.552812)
		(width 0.18288)
		(layer "In4.Cu")
		(net "M_F_CPU1_SB_DQS_DP<8>")
	)
	(segment
		(start 140.571982 -221.309692)
		(end 139.756642 -221.309692)
		(width 0.18288)
		(layer "In4.Cu")
		(net "M_F_CPU1_SB_DQS_DP<8>")
	)
	(segment
		(start 134.384288 -226.340924)
		(end 134.382764 -226.341686)
		(width 0.088646)
		(layer "In4.Cu")
		(net "M_F_CPU1_SB_DQS_DP<8>")
	)
	(segment
		(start 134.100062 -226.831144)
		(end 134.100062 -226.83978)
		(width 0.088646)
		(layer "In4.Cu")
		(net "M_F_CPU1_SB_DQS_DP<8>")
	)
	(segment
		(start 135.040116 -225.187764)
		(end 135.040116 -225.203258)
		(width 0.088646)
		(layer "In4.Cu")
		(net "M_F_CPU1_SB_DQS_DP<8>")
	)
	(segment
		(start 132.781802 -227.852224)
		(end 132.390388 -227.852224)
		(width 0.088646)
		(layer "In4.Cu")
		(net "M_F_CPU1_SB_DQS_DP<8>")
	)
	(segment
		(start 135.979662 -223.56699)
		(end 135.979662 -223.584262)
		(width 0.088646)
		(layer "In4.Cu")
		(net "M_F_CPU1_SB_DQS_DP<8>")
	)
	(segment
		(start 136.740138 -222.267526)
		(end 136.735312 -222.270066)
		(width 0.088646)
		(layer "In4.Cu")
		(net "M_F_CPU1_SB_DQS_DP<8>")
	)
	(segment
		(start 132.936742 -227.893626)
		(end 132.781802 -227.852224)
		(width 0.088646)
		(layer "In4.Cu")
		(net "M_F_CPU1_SB_DQS_DP<8>")
	)
	(segment
		(start 137.200894 -221.459044)
		(end 137.189972 -221.465394)
		(width 0.088646)
		(layer "In4.Cu")
		(net "M_F_CPU1_SB_DQS_DP<8>")
	)
	(segment
		(start 172.334936 -201.392536)
		(end 171.056808 -201.392536)
		(width 0.18288)
		(layer "In4.Cu")
		(net "M_F_CPU1_SB_DQS_DP<8>")
	)
	(segment
		(start 166.725092 -200.551542)
		(end 166.600632 -200.427082)
		(width 0.18288)
		(layer "In4.Cu")
		(net "M_F_CPU1_SB_DQS_DP<8>")
	)
	(segment
		(start 150.678896 -211.202524)
		(end 140.571982 -221.309692)
		(width 0.18288)
		(layer "In4.Cu")
		(net "M_F_CPU1_SB_DQS_DP<8>")
	)
	(segment
		(start 173.917102 -201.418444)
		(end 173.265592 -201.418444)
		(width 0.18288)
		(layer "In4.Cu")
		(net "M_F_CPU1_SB_DQS_DP<8>")
	)
	(segment
		(start 172.584872 -201.1426)
		(end 172.334936 -201.392536)
		(width 0.18288)
		(layer "In4.Cu")
		(net "M_F_CPU1_SB_DQS_DP<8>")
	)
	(segment
		(start 134.391654 -226.336606)
		(end 134.384288 -226.340924)
		(width 0.088646)
		(layer "In4.Cu")
		(net "M_F_CPU1_SB_DQS_DP<8>")
	)
	(segment
		(start 134.382764 -226.341686)
		(end 134.37997 -226.34321)
		(width 0.088646)
		(layer "In4.Cu")
		(net "M_F_CPU1_SB_DQS_DP<8>")
	)
	(segment
		(start 175.463454 -199.69607)
		(end 175.07712 -200.082404)
		(width 0.18288)
		(layer "In4.Cu")
		(net "M_F_CPU1_SB_DQS_DP<8>")
	)
	(segment
		(start 135.510016 -222.75165)
		(end 135.510016 -222.780098)
		(width 0.088646)
		(layer "In4.Cu")
		(net "M_F_CPU1_SB_DQS_DP<8>")
	)
	(segment
		(start 153.4414 -205.564232)
		(end 153.47569 -205.736952)
		(width 0.18288)
		(layer "In4.Cu")
		(net "M_F_CPU1_SB_DQS_DP<8>")
	)
	(segment
		(start 165.930072 -200.551542)
		(end 164.471604 -200.551542)
		(width 0.18288)
		(layer "In4.Cu")
		(net "M_F_CPU1_SB_DQS_DP<8>")
	)
	(segment
		(start 169.793666 -201.095102)
		(end 169.520362 -201.368406)
		(width 0.18288)
		(layer "In4.Cu")
		(net "M_F_CPU1_SB_DQS_DP<8>")
	)
	(segment
		(start 176.025556 -199.30999)
		(end 175.639476 -199.69607)
		(width 0.18288)
		(layer "In4.Cu")
		(net "M_F_CPU1_SB_DQS_DP<8>")
	)
	(segment
		(start 152.98547 -206.24673)
		(end 152.681686 -206.701136)
		(width 0.18288)
		(layer "In4.Cu")
		(net "M_F_CPU1_SB_DQS_DP<8>")
	)
	(segment
		(start 156.987748 -200.938892)
		(end 156.601414 -201.325226)
		(width 0.18288)
		(layer "In4.Cu")
		(net "M_F_CPU1_SB_DQS_DP<8>")
	)
	(segment
		(start 161.628074 -200.278492)
		(end 161.353754 -200.552812)
		(width 0.18288)
		(layer "In4.Cu")
		(net "M_F_CPU1_SB_DQS_DP<8>")
	)
	(segment
		(start 153.47569 -205.736952)
		(end 153.157936 -206.21244)
		(width 0.18288)
		(layer "In4.Cu")
		(net "M_F_CPU1_SB_DQS_DP<8>")
	)
	(segment
		(start 156.601414 -201.325226)
		(end 156.601414 -201.501248)
		(width 0.18288)
		(layer "In4.Cu")
		(net "M_F_CPU1_SB_DQS_DP<8>")
	)
	(segment
		(start 168.83761 -201.368406)
		(end 168.020746 -200.551542)
		(width 0.18288)
		(layer "In4.Cu")
		(net "M_F_CPU1_SB_DQS_DP<8>")
	)
	(segment
		(start 134.861554 -225.522536)
		(end 134.852664 -225.527616)
		(width 0.088646)
		(layer "In4.Cu")
		(net "M_F_CPU1_SB_DQS_DP<8>")
	)
	(segment
		(start 154.220926 -204.621638)
		(end 153.91765 -205.075536)
		(width 0.18288)
		(layer "In4.Cu")
		(net "M_F_CPU1_SB_DQS_DP<8>")
	)
	(segment
		(start 152.715976 -206.873602)
		(end 152.074626 -207.833468)
		(width 0.18288)
		(layer "In4.Cu")
		(net "M_F_CPU1_SB_DQS_DP<8>")
	)
	(segment
		(start 173.265592 -201.418444)
		(end 172.989748 -201.1426)
		(width 0.18288)
		(layer "In4.Cu")
		(net "M_F_CPU1_SB_DQS_DP<8>")
	)
	(segment
		(start 136.732772 -222.27159)
		(end 136.73201 -222.272098)
		(width 0.088646)
		(layer "In4.Cu")
		(net "M_F_CPU1_SB_DQS_DP<8>")
	)
	(segment
		(start 171.056808 -201.392536)
		(end 170.759374 -201.095102)
		(width 0.18288)
		(layer "In4.Cu")
		(net "M_F_CPU1_SB_DQS_DP<8>")
	)
	(segment
		(start 134.37997 -226.34321)
		(end 134.376668 -226.345242)
		(width 0.088646)
		(layer "In4.Cu")
		(net "M_F_CPU1_SB_DQS_DP<8>")
	)
	(segment
		(start 166.054532 -200.427082)
		(end 165.930072 -200.551542)
		(width 0.18288)
		(layer "In4.Cu")
		(net "M_F_CPU1_SB_DQS_DP<8>")
	)
	(segment
		(start 154.966162 -203.506578)
		(end 154.662886 -203.960476)
		(width 0.18288)
		(layer "In4.Cu")
		(net "M_F_CPU1_SB_DQS_DP<8>")
	)
	(segment
		(start 152.074626 -207.833468)
		(end 150.678896 -211.202524)
		(width 0.18288)
		(layer "In4.Cu")
		(net "M_F_CPU1_SB_DQS_DP<8>")
	)
	(segment
		(start 133.068568 -227.969318)
		(end 132.936742 -227.893626)
		(width 0.088646)
		(layer "In4.Cu")
		(net "M_F_CPU1_SB_DQS_DP<8>")
	)
	(segment
		(start 158.795974 -200.428352)
		(end 158.671514 -200.552812)
		(width 0.18288)
		(layer "In4.Cu")
		(net "M_F_CPU1_SB_DQS_DP<8>")
	)
	(segment
		(start 139.756642 -221.309692)
		(end 139.733274 -221.309692)
		(width 0.088646)
		(layer "In4.Cu")
		(net "M_F_CPU1_SB_DQS_DP<8>")
	)
	(segment
		(start 160.012634 -200.552812)
		(end 159.466534 -200.552812)
		(width 0.18288)
		(layer "In4.Cu")
		(net "M_F_CPU1_SB_DQS_DP<8>")
	)
	(segment
		(start 134.570216 -225.998786)
		(end 134.570216 -226.017328)
		(width 0.088646)
		(layer "In4.Cu")
		(net "M_F_CPU1_SB_DQS_DP<8>")
	)
	(segment
		(start 139.733274 -221.309692)
		(end 139.673584 -221.369382)
		(width 0.088646)
		(layer "In4.Cu")
		(net "M_F_CPU1_SB_DQS_DP<8>")
	)
	(segment
		(start 175.07712 -200.082404)
		(end 175.07712 -200.258426)
		(width 0.18288)
		(layer "In4.Cu")
		(net "M_F_CPU1_SB_DQS_DP<8>")
	)
	(segment
		(start 175.07712 -200.258426)
		(end 173.917102 -201.418444)
		(width 0.18288)
		(layer "In4.Cu")
		(net "M_F_CPU1_SB_DQS_DP<8>")
	)
	(segment
		(start 159.342074 -200.428352)
		(end 158.795974 -200.428352)
		(width 0.18288)
		(layer "In4.Cu")
		(net "M_F_CPU1_SB_DQS_DP<8>")
	)
	(segment
		(start 175.639476 -199.69607)
		(end 175.463454 -199.69607)
		(width 0.18288)
		(layer "In4.Cu")
		(net "M_F_CPU1_SB_DQS_DP<8>")
	)
	(segment
		(start 159.466534 -200.552812)
		(end 159.342074 -200.428352)
		(width 0.18288)
		(layer "In4.Cu")
		(net "M_F_CPU1_SB_DQS_DP<8>")
	)
	(segment
		(start 155.408122 -202.845162)
		(end 155.235402 -202.879452)
		(width 0.18288)
		(layer "In4.Cu")
		(net "M_F_CPU1_SB_DQS_DP<8>")
	)
	(segment
		(start 176.896014 -199.01662)
		(end 176.896014 -199.03948)
		(width 0.18288)
		(layer "In4.Cu")
		(net "M_F_CPU1_SB_DQS_DP<8>")
	)
	(segment
		(start 154.662886 -203.960476)
		(end 154.490166 -203.994766)
		(width 0.18288)
		(layer "In4.Cu")
		(net "M_F_CPU1_SB_DQS_DP<8>")
	)
	(segment
		(start 136.7409 -222.267018)
		(end 136.740138 -222.267526)
		(width 0.088646)
		(layer "In4.Cu")
		(net "M_F_CPU1_SB_DQS_DP<8>")
	)
	(segment
		(start 154.490166 -203.994766)
		(end 154.186636 -204.449172)
		(width 0.18288)
		(layer "In4.Cu")
		(net "M_F_CPU1_SB_DQS_DP<8>")
	)
	(segment
		(start 136.73455 -222.270574)
		(end 136.732772 -222.27159)
		(width 0.088646)
		(layer "In4.Cu")
		(net "M_F_CPU1_SB_DQS_DP<8>")
	)
	(segment
		(start 161.353754 -200.552812)
		(end 160.807654 -200.552812)
		(width 0.18288)
		(layer "In4.Cu")
		(net "M_F_CPU1_SB_DQS_DP<8>")
	)
	(segment
		(start 164.471604 -200.551542)
		(end 164.196268 -200.276206)
		(width 0.18288)
		(layer "In4.Cu")
		(net "M_F_CPU1_SB_DQS_DP<8>")
	)
	(segment
		(start 168.020746 -200.551542)
		(end 166.725092 -200.551542)
		(width 0.18288)
		(layer "In4.Cu")
		(net "M_F_CPU1_SB_DQS_DP<8>")
	)
	(segment
		(start 160.683194 -200.428352)
		(end 160.137094 -200.428352)
		(width 0.18288)
		(layer "In4.Cu")
		(net "M_F_CPU1_SB_DQS_DP<8>")
	)
	(segment
		(start 135.3312 -224.70872)
		(end 135.323326 -224.713292)
		(width 0.088646)
		(layer "In4.Cu")
		(net "M_F_CPU1_SB_DQS_DP<8>")
	)
	(segment
		(start 137.202164 -221.458282)
		(end 137.200894 -221.459044)
		(width 0.088646)
		(layer "In4.Cu")
		(net "M_F_CPU1_SB_DQS_DP<8>")
	)
	(segment
		(start 153.91765 -205.075536)
		(end 153.74493 -205.109826)
		(width 0.18288)
		(layer "In4.Cu")
		(net "M_F_CPU1_SB_DQS_DP<8>")
	)
	(segment
		(start 154.931872 -203.333858)
		(end 154.966162 -203.506578)
		(width 0.18288)
		(layer "In4.Cu")
		(net "M_F_CPU1_SB_DQS_DP<8>")
	)
	(segment
		(start 164.196268 -200.276206)
		(end 163.842192 -200.276206)
		(width 0.18288)
		(layer "In4.Cu")
		(net "M_F_CPU1_SB_DQS_DP<8>")
	)
	(arc
		(start 135.040116 -225.203258)
		(mid 134.992437 -225.386158)
		(end 134.861554 -225.522536)
		(width 0.088646)
		(layer "In4.Cu")
		(net "M_F_CPU1_SB_DQS_DP<8>")
	)
	(arc
		(start 137.189972 -221.465394)
		(mid 136.991744 -221.671242)
		(end 136.919462 -221.94774)
		(width 0.088646)
		(layer "In4.Cu")
		(net "M_F_CPU1_SB_DQS_DP<8>")
	)
	(arc
		(start 138.70686 -221.458536)
		(mid 138.424556 -221.38298)
		(end 138.142218 -221.458536)
		(width 0.088646)
		(layer "In4.Cu")
		(net "M_F_CPU1_SB_DQS_DP<8>")
	)
	(arc
		(start 133.912864 -227.155502)
		(mid 133.708529 -227.358107)
		(end 133.630416 -227.635054)
		(width 0.088646)
		(layer "In4.Cu")
		(net "M_F_CPU1_SB_DQS_DP<8>")
	)
	(arc
		(start 133.442964 -227.969318)
		(mid 133.255766 -228.019461)
		(end 133.068568 -227.969318)
		(width 0.088646)
		(layer "In4.Cu")
		(net "M_F_CPU1_SB_DQS_DP<8>")
	)
	(arc
		(start 134.852664 -225.527616)
		(mid 134.650378 -225.726597)
		(end 134.570216 -225.998786)
		(width 0.088646)
		(layer "In4.Cu")
		(net "M_F_CPU1_SB_DQS_DP<8>")
	)
	(arc
		(start 134.100062 -226.83978)
		(mid 134.047792 -227.022145)
		(end 133.912864 -227.155502)
		(width 0.088646)
		(layer "In4.Cu")
		(net "M_F_CPU1_SB_DQS_DP<8>")
	)
	(arc
		(start 135.792464 -223.251268)
		(mid 135.927397 -223.384622)
		(end 135.979662 -223.56699)
		(width 0.088646)
		(layer "In4.Cu")
		(net "M_F_CPU1_SB_DQS_DP<8>")
	)
	(arc
		(start 133.630416 -227.64496)
		(mid 133.582737 -227.82786)
		(end 133.451854 -227.964238)
		(width 0.088646)
		(layer "In4.Cu")
		(net "M_F_CPU1_SB_DQS_DP<8>")
	)
	(arc
		(start 134.570216 -226.017328)
		(mid 134.522537 -226.200228)
		(end 134.391654 -226.336606)
		(width 0.088646)
		(layer "In4.Cu")
		(net "M_F_CPU1_SB_DQS_DP<8>")
	)
	(arc
		(start 135.510016 -222.780098)
		(mid 135.590178 -223.052287)
		(end 135.792464 -223.251268)
		(width 0.088646)
		(layer "In4.Cu")
		(net "M_F_CPU1_SB_DQS_DP<8>")
	)
	(arc
		(start 134.376668 -226.345242)
		(mid 134.174081 -226.551593)
		(end 134.100062 -226.831144)
		(width 0.088646)
		(layer "In4.Cu")
		(net "M_F_CPU1_SB_DQS_DP<8>")
	)
	(arc
		(start 135.780272 -223.907096)
		(mid 135.582044 -224.112944)
		(end 135.509762 -224.389442)
		(width 0.088646)
		(layer "In4.Cu")
		(net "M_F_CPU1_SB_DQS_DP<8>")
	)
	(arc
		(start 137.767568 -221.458282)
		(mid 137.484866 -221.382506)
		(end 137.202164 -221.458282)
		(width 0.088646)
		(layer "In4.Cu")
		(net "M_F_CPU1_SB_DQS_DP<8>")
	)
	(arc
		(start 138.141964 -221.458282)
		(mid 137.954766 -221.508425)
		(end 137.767568 -221.458282)
		(width 0.088646)
		(layer "In4.Cu")
		(net "M_F_CPU1_SB_DQS_DP<8>")
	)
	(arc
		(start 136.73201 -222.272098)
		(mid 136.544812 -222.322241)
		(end 136.357614 -222.272098)
		(width 0.088646)
		(layer "In4.Cu")
		(net "M_F_CPU1_SB_DQS_DP<8>")
	)
	(arc
		(start 135.979662 -223.584262)
		(mid 135.927392 -223.766627)
		(end 135.792464 -223.899984)
		(width 0.088646)
		(layer "In4.Cu")
		(net "M_F_CPU1_SB_DQS_DP<8>")
	)
	(arc
		(start 135.32231 -224.7138)
		(mid 135.119487 -224.914031)
		(end 135.040116 -225.187764)
		(width 0.088646)
		(layer "In4.Cu")
		(net "M_F_CPU1_SB_DQS_DP<8>")
	)
	(arc
		(start 136.919462 -221.94774)
		(mid 136.871783 -222.13064)
		(end 136.7409 -222.267018)
		(width 0.088646)
		(layer "In4.Cu")
		(net "M_F_CPU1_SB_DQS_DP<8>")
	)
	(arc
		(start 135.509762 -224.389442)
		(mid 135.462083 -224.572342)
		(end 135.3312 -224.70872)
		(width 0.088646)
		(layer "In4.Cu")
		(net "M_F_CPU1_SB_DQS_DP<8>")
	)
	(arc
		(start 132.390388 -227.852224)
		(mid 132.337764 -227.830426)
		(end 132.315966 -227.777802)
		(width 0.088646)
		(layer "In4.Cu")
		(net "M_F_CPU1_SB_DQS_DP<8>")
	)
	(arc
		(start 138.894312 -221.508828)
		(mid 138.797264 -221.496049)
		(end 138.70686 -221.458536)
		(width 0.088646)
		(layer "In4.Cu")
		(net "M_F_CPU1_SB_DQS_DP<8>")
	)
	(arc
		(start 135.792464 -222.272098)
		(mid 135.588129 -222.474703)
		(end 135.510016 -222.75165)
		(width 0.088646)
		(layer "In4.Cu")
		(net "M_F_CPU1_SB_DQS_DP<8>")
	)
	(arc
		(start 136.3472 -222.266002)
		(mid 136.069022 -222.196279)
		(end 135.792464 -222.272098)
		(width 0.088646)
		(layer "In4.Cu")
		(net "M_F_CPU1_SB_DQS_DP<8>")
	)
	(segment
		(start 179.575206 -208.192878)
		(end 179.85359 -208.192878)
		(width 0.20066)
		(layer "F.Cu")
		(net "M_F_CPU1_SB_DQS_DP<7>")
	)
	(segment
		(start 182.455058 -207.934306)
		(end 182.776876 -207.934306)
		(width 0.20066)
		(layer "F.Cu")
		(net "M_F_CPU1_SB_DQS_DP<7>")
	)
	(segment
		(start 178.000914 -208.366614)
		(end 178.594258 -208.366614)
		(width 0.20066)
		(layer "F.Cu")
		(net "M_F_CPU1_SB_DQS_DP<7>")
	)
	(segment
		(start 184.97677 -208.366614)
		(end 185.544714 -208.366614)
		(width 0.20066)
		(layer "F.Cu")
		(net "M_F_CPU1_SB_DQS_DP<7>")
	)
	(segment
		(start 182.447692 -207.941672)
		(end 182.455058 -207.934306)
		(width 0.1016)
		(layer "F.Cu")
		(net "M_F_CPU1_SB_DQS_DP<7>")
	)
	(segment
		(start 180.427884 -207.93456)
		(end 180.434996 -207.941672)
		(width 0.1016)
		(layer "F.Cu")
		(net "M_F_CPU1_SB_DQS_DP<7>")
	)
	(segment
		(start 183.031892 -208.189322)
		(end 183.685434 -208.189322)
		(width 0.20066)
		(layer "F.Cu")
		(net "M_F_CPU1_SB_DQS_DP<7>")
	)
	(segment
		(start 179.85359 -208.192878)
		(end 180.111908 -207.93456)
		(width 0.20066)
		(layer "F.Cu")
		(net "M_F_CPU1_SB_DQS_DP<7>")
	)
	(segment
		(start 137.954766 -223.297496)
		(end 137.954766 -222.761556)
		(width 0.20066)
		(layer "F.Cu")
		(net "M_F_CPU1_SB_DQS_DP<7>")
	)
	(segment
		(start 178.594258 -208.366614)
		(end 178.845464 -208.61782)
		(width 0.20066)
		(layer "F.Cu")
		(net "M_F_CPU1_SB_DQS_DP<7>")
	)
	(segment
		(start 176.896014 -208.366614)
		(end 178.000914 -208.366614)
		(width 0.20066)
		(layer "F.Cu")
		(net "M_F_CPU1_SB_DQS_DP<7>")
	)
	(segment
		(start 183.685434 -208.189322)
		(end 184.13095 -208.634838)
		(width 0.20066)
		(layer "F.Cu")
		(net "M_F_CPU1_SB_DQS_DP<7>")
	)
	(segment
		(start 180.423058 -207.93456)
		(end 180.427884 -207.93456)
		(width 0.101854)
		(layer "F.Cu")
		(net "M_F_CPU1_SB_DQS_DP<7>")
	)
	(segment
		(start 180.111908 -207.93456)
		(end 180.423058 -207.93456)
		(width 0.20066)
		(layer "F.Cu")
		(net "M_F_CPU1_SB_DQS_DP<7>")
	)
	(segment
		(start 180.434996 -207.941672)
		(end 182.447692 -207.941672)
		(width 0.1016)
		(layer "F.Cu")
		(net "M_F_CPU1_SB_DQS_DP<7>")
	)
	(segment
		(start 179.150264 -208.61782)
		(end 179.575206 -208.192878)
		(width 0.20066)
		(layer "F.Cu")
		(net "M_F_CPU1_SB_DQS_DP<7>")
	)
	(segment
		(start 184.708546 -208.634838)
		(end 184.97677 -208.366614)
		(width 0.20066)
		(layer "F.Cu")
		(net "M_F_CPU1_SB_DQS_DP<7>")
	)
	(segment
		(start 182.776876 -207.934306)
		(end 183.031892 -208.189322)
		(width 0.20066)
		(layer "F.Cu")
		(net "M_F_CPU1_SB_DQS_DP<7>")
	)
	(segment
		(start 178.845464 -208.61782)
		(end 179.150264 -208.61782)
		(width 0.20066)
		(layer "F.Cu")
		(net "M_F_CPU1_SB_DQS_DP<7>")
	)
	(segment
		(start 184.13095 -208.634838)
		(end 184.708546 -208.634838)
		(width 0.20066)
		(layer "F.Cu")
		(net "M_F_CPU1_SB_DQS_DP<7>")
	)
	(segment
		(start 165.028626 -206.229204)
		(end 164.72662 -206.53121)
		(width 0.18288)
		(layer "In2.Cu")
		(net "M_F_CPU1_SB_DQS_DP<7>")
	)
	(segment
		(start 138.677396 -222.45447)
		(end 137.954766 -222.761556)
		(width 0.088646)
		(layer "In2.Cu")
		(net "M_F_CPU1_SB_DQS_DP<7>")
	)
	(segment
		(start 141.03985 -221.398592)
		(end 141.039342 -221.398846)
		(width 0.088646)
		(layer "In2.Cu")
		(net "M_F_CPU1_SB_DQS_DP<7>")
	)
	(segment
		(start 171.630848 -207.974184)
		(end 171.602654 -207.94599)
		(width 0.16002)
		(layer "In2.Cu")
		(net "M_F_CPU1_SB_DQS_DP<7>")
	)
	(segment
		(start 169.68851 -207.57769)
		(end 169.500296 -207.765904)
		(width 0.18288)
		(layer "In2.Cu")
		(net "M_F_CPU1_SB_DQS_DP<7>")
	)
	(segment
		(start 173.093888 -207.942688)
		(end 172.49013 -207.942688)
		(width 0.18288)
		(layer "In2.Cu")
		(net "M_F_CPU1_SB_DQS_DP<7>")
	)
	(segment
		(start 139.551664 -222.272098)
		(end 139.55141 -222.272352)
		(width 0.088646)
		(layer "In2.Cu")
		(net "M_F_CPU1_SB_DQS_DP<7>")
	)
	(segment
		(start 174.812198 -208.567528)
		(end 174.784004 -208.539334)
		(width 0.16002)
		(layer "In2.Cu")
		(net "M_F_CPU1_SB_DQS_DP<7>")
	)
	(segment
		(start 169.500296 -207.765904)
		(end 169.472102 -207.794098)
		(width 0.16002)
		(layer "In2.Cu")
		(net "M_F_CPU1_SB_DQS_DP<7>")
	)
	(segment
		(start 171.419774 -207.76311)
		(end 171.234354 -207.57769)
		(width 0.18288)
		(layer "In2.Cu")
		(net "M_F_CPU1_SB_DQS_DP<7>")
	)
	(segment
		(start 138.707114 -222.437198)
		(end 138.677396 -222.45447)
		(width 0.088646)
		(layer "In2.Cu")
		(net "M_F_CPU1_SB_DQS_DP<7>")
	)
	(segment
		(start 139.553188 -222.271336)
		(end 139.551664 -222.272098)
		(width 0.088646)
		(layer "In2.Cu")
		(net "M_F_CPU1_SB_DQS_DP<7>")
	)
	(segment
		(start 174.950628 -208.722214)
		(end 174.812198 -208.583784)
		(width 0.16002)
		(layer "In2.Cu")
		(net "M_F_CPU1_SB_DQS_DP<7>")
	)
	(segment
		(start 176.896014 -208.366614)
		(end 176.642522 -208.620106)
		(width 0.18288)
		(layer "In2.Cu")
		(net "M_F_CPU1_SB_DQS_DP<7>")
	)
	(segment
		(start 176.642522 -208.620106)
		(end 176.389792 -208.620106)
		(width 0.18288)
		(layer "In2.Cu")
		(net "M_F_CPU1_SB_DQS_DP<7>")
	)
	(segment
		(start 171.234354 -207.57769)
		(end 169.68851 -207.57769)
		(width 0.18288)
		(layer "In2.Cu")
		(net "M_F_CPU1_SB_DQS_DP<7>")
	)
	(segment
		(start 164.72662 -206.53121)
		(end 164.398706 -206.53121)
		(width 0.18288)
		(layer "In2.Cu")
		(net "M_F_CPU1_SB_DQS_DP<7>")
	)
	(segment
		(start 169.317416 -207.948784)
		(end 169.289222 -207.976978)
		(width 0.16002)
		(layer "In2.Cu")
		(net "M_F_CPU1_SB_DQS_DP<7>")
	)
	(segment
		(start 139.739116 -221.937834)
		(end 139.739116 -221.94774)
		(width 0.088646)
		(layer "In2.Cu")
		(net "M_F_CPU1_SB_DQS_DP<7>")
	)
	(segment
		(start 175.1457 -208.90103)
		(end 174.995078 -208.750408)
		(width 0.18288)
		(layer "In2.Cu")
		(net "M_F_CPU1_SB_DQS_DP<7>")
	)
	(segment
		(start 171.831508 -208.174844)
		(end 171.630848 -207.974184)
		(width 0.18288)
		(layer "In2.Cu")
		(net "M_F_CPU1_SB_DQS_DP<7>")
	)
	(segment
		(start 172.49013 -207.942688)
		(end 172.257974 -208.174844)
		(width 0.18288)
		(layer "In2.Cu")
		(net "M_F_CPU1_SB_DQS_DP<7>")
	)
	(segment
		(start 165.776402 -206.513176)
		(end 165.49243 -206.229204)
		(width 0.18288)
		(layer "In2.Cu")
		(net "M_F_CPU1_SB_DQS_DP<7>")
	)
	(segment
		(start 175.711104 -208.90103)
		(end 175.1457 -208.90103)
		(width 0.18288)
		(layer "In2.Cu")
		(net "M_F_CPU1_SB_DQS_DP<7>")
	)
	(segment
		(start 161.376614 -205.37932)
		(end 161.088324 -205.66761)
		(width 0.18288)
		(layer "In2.Cu")
		(net "M_F_CPU1_SB_DQS_DP<7>")
	)
	(segment
		(start 139.531344 -222.283782)
		(end 139.170918 -222.43669)
		(width 0.088646)
		(layer "In2.Cu")
		(net "M_F_CPU1_SB_DQS_DP<7>")
	)
	(segment
		(start 169.472102 -207.810354)
		(end 169.333672 -207.948784)
		(width 0.16002)
		(layer "In2.Cu")
		(net "M_F_CPU1_SB_DQS_DP<7>")
	)
	(segment
		(start 169.23893 -208.02727)
		(end 168.483534 -208.02727)
		(width 0.18288)
		(layer "In2.Cu")
		(net "M_F_CPU1_SB_DQS_DP<7>")
	)
	(segment
		(start 169.472102 -207.794098)
		(end 169.472102 -207.810354)
		(width 0.16002)
		(layer "In2.Cu")
		(net "M_F_CPU1_SB_DQS_DP<7>")
	)
	(segment
		(start 159.697674 -205.073758)
		(end 158.012638 -205.073758)
		(width 0.18288)
		(layer "In2.Cu")
		(net "M_F_CPU1_SB_DQS_DP<7>")
	)
	(segment
		(start 173.374558 -208.223358)
		(end 173.093888 -207.942688)
		(width 0.18288)
		(layer "In2.Cu")
		(net "M_F_CPU1_SB_DQS_DP<7>")
	)
	(segment
		(start 164.398706 -206.53121)
		(end 163.530788 -205.663292)
		(width 0.18288)
		(layer "In2.Cu")
		(net "M_F_CPU1_SB_DQS_DP<7>")
	)
	(segment
		(start 174.468028 -208.223358)
		(end 173.374558 -208.223358)
		(width 0.18288)
		(layer "In2.Cu")
		(net "M_F_CPU1_SB_DQS_DP<7>")
	)
	(segment
		(start 176.389792 -208.620106)
		(end 175.711104 -208.90103)
		(width 0.18288)
		(layer "In2.Cu")
		(net "M_F_CPU1_SB_DQS_DP<7>")
	)
	(segment
		(start 142.082266 -220.736922)
		(end 141.70152 -220.736922)
		(width 0.088646)
		(layer "In2.Cu")
		(net "M_F_CPU1_SB_DQS_DP<7>")
	)
	(segment
		(start 166.96944 -206.513176)
		(end 165.776402 -206.513176)
		(width 0.18288)
		(layer "In2.Cu")
		(net "M_F_CPU1_SB_DQS_DP<7>")
	)
	(segment
		(start 171.602654 -207.94599)
		(end 171.586398 -207.94599)
		(width 0.16002)
		(layer "In2.Cu")
		(net "M_F_CPU1_SB_DQS_DP<7>")
	)
	(segment
		(start 139.17041 -222.437198)
		(end 139.08151 -222.437198)
		(width 0.088646)
		(layer "In2.Cu")
		(net "M_F_CPU1_SB_DQS_DP<7>")
	)
	(segment
		(start 156.96184 -205.775814)
		(end 142.66037 -220.074998)
		(width 0.18288)
		(layer "In2.Cu")
		(net "M_F_CPU1_SB_DQS_DP<7>")
	)
	(segment
		(start 142.66037 -220.158818)
		(end 142.082266 -220.736922)
		(width 0.088646)
		(layer "In2.Cu")
		(net "M_F_CPU1_SB_DQS_DP<7>")
	)
	(segment
		(start 174.812198 -208.583784)
		(end 174.812198 -208.567528)
		(width 0.16002)
		(layer "In2.Cu")
		(net "M_F_CPU1_SB_DQS_DP<7>")
	)
	(segment
		(start 171.447968 -207.791304)
		(end 171.419774 -207.76311)
		(width 0.16002)
		(layer "In2.Cu")
		(net "M_F_CPU1_SB_DQS_DP<7>")
	)
	(segment
		(start 171.447968 -207.80756)
		(end 171.447968 -207.791304)
		(width 0.16002)
		(layer "In2.Cu")
		(net "M_F_CPU1_SB_DQS_DP<7>")
	)
	(segment
		(start 172.257974 -208.174844)
		(end 171.831508 -208.174844)
		(width 0.18288)
		(layer "In2.Cu")
		(net "M_F_CPU1_SB_DQS_DP<7>")
	)
	(segment
		(start 174.784004 -208.539334)
		(end 174.468028 -208.223358)
		(width 0.18288)
		(layer "In2.Cu")
		(net "M_F_CPU1_SB_DQS_DP<7>")
	)
	(segment
		(start 174.995078 -208.750408)
		(end 174.966884 -208.722214)
		(width 0.16002)
		(layer "In2.Cu")
		(net "M_F_CPU1_SB_DQS_DP<7>")
	)
	(segment
		(start 139.55141 -222.272352)
		(end 139.531344 -222.283782)
		(width 0.088646)
		(layer "In2.Cu")
		(net "M_F_CPU1_SB_DQS_DP<7>")
	)
	(segment
		(start 139.170918 -222.43669)
		(end 139.17041 -222.437198)
		(width 0.088646)
		(layer "In2.Cu")
		(net "M_F_CPU1_SB_DQS_DP<7>")
	)
	(segment
		(start 139.560554 -222.267018)
		(end 139.553188 -222.271336)
		(width 0.088646)
		(layer "In2.Cu")
		(net "M_F_CPU1_SB_DQS_DP<7>")
	)
	(segment
		(start 161.840418 -205.37932)
		(end 161.376614 -205.37932)
		(width 0.18288)
		(layer "In2.Cu")
		(net "M_F_CPU1_SB_DQS_DP<7>")
	)
	(segment
		(start 162.12439 -205.663292)
		(end 161.840418 -205.37932)
		(width 0.18288)
		(layer "In2.Cu")
		(net "M_F_CPU1_SB_DQS_DP<7>")
	)
	(segment
		(start 141.70152 -220.736922)
		(end 141.03985 -221.398592)
		(width 0.088646)
		(layer "In2.Cu")
		(net "M_F_CPU1_SB_DQS_DP<7>")
	)
	(segment
		(start 165.49243 -206.229204)
		(end 165.028626 -206.229204)
		(width 0.18288)
		(layer "In2.Cu")
		(net "M_F_CPU1_SB_DQS_DP<7>")
	)
	(segment
		(start 174.966884 -208.722214)
		(end 174.950628 -208.722214)
		(width 0.16002)
		(layer "In2.Cu")
		(net "M_F_CPU1_SB_DQS_DP<7>")
	)
	(segment
		(start 142.66037 -220.074998)
		(end 142.66037 -220.158818)
		(width 0.088646)
		(layer "In2.Cu")
		(net "M_F_CPU1_SB_DQS_DP<7>")
	)
	(segment
		(start 163.530788 -205.663292)
		(end 162.12439 -205.663292)
		(width 0.18288)
		(layer "In2.Cu")
		(net "M_F_CPU1_SB_DQS_DP<7>")
	)
	(segment
		(start 171.586398 -207.94599)
		(end 171.447968 -207.80756)
		(width 0.16002)
		(layer "In2.Cu")
		(net "M_F_CPU1_SB_DQS_DP<7>")
	)
	(segment
		(start 158.012638 -205.073758)
		(end 156.96184 -205.775814)
		(width 0.18288)
		(layer "In2.Cu")
		(net "M_F_CPU1_SB_DQS_DP<7>")
	)
	(segment
		(start 161.088324 -205.66761)
		(end 160.291526 -205.66761)
		(width 0.18288)
		(layer "In2.Cu")
		(net "M_F_CPU1_SB_DQS_DP<7>")
	)
	(segment
		(start 160.291526 -205.66761)
		(end 159.697674 -205.073758)
		(width 0.18288)
		(layer "In2.Cu")
		(net "M_F_CPU1_SB_DQS_DP<7>")
	)
	(segment
		(start 168.483534 -208.02727)
		(end 166.96944 -206.513176)
		(width 0.18288)
		(layer "In2.Cu")
		(net "M_F_CPU1_SB_DQS_DP<7>")
	)
	(segment
		(start 169.333672 -207.948784)
		(end 169.317416 -207.948784)
		(width 0.16002)
		(layer "In2.Cu")
		(net "M_F_CPU1_SB_DQS_DP<7>")
	)
	(segment
		(start 169.289222 -207.976978)
		(end 169.23893 -208.02727)
		(width 0.18288)
		(layer "In2.Cu")
		(net "M_F_CPU1_SB_DQS_DP<7>")
	)
	(arc
		(start 140.586968 -221.458282)
		(mid 140.025992 -221.455751)
		(end 139.739116 -221.937834)
		(width 0.088646)
		(layer "In2.Cu")
		(net "M_F_CPU1_SB_DQS_DP<7>")
	)
	(arc
		(start 141.039342 -221.398846)
		(mid 141.022419 -221.414751)
		(end 141.004544 -221.42958)
		(width 0.088646)
		(layer "In2.Cu")
		(net "M_F_CPU1_SB_DQS_DP<7>")
	)
	(arc
		(start 140.961364 -221.458282)
		(mid 140.774166 -221.508425)
		(end 140.586968 -221.458282)
		(width 0.088646)
		(layer "In2.Cu")
		(net "M_F_CPU1_SB_DQS_DP<7>")
	)
	(arc
		(start 141.004544 -221.42958)
		(mid 140.983454 -221.444684)
		(end 140.961364 -221.458282)
		(width 0.088646)
		(layer "In2.Cu")
		(net "M_F_CPU1_SB_DQS_DP<7>")
	)
	(arc
		(start 139.739116 -221.94774)
		(mid 139.691437 -222.13064)
		(end 139.560554 -222.267018)
		(width 0.088646)
		(layer "In2.Cu")
		(net "M_F_CPU1_SB_DQS_DP<7>")
	)
	(arc
		(start 139.08151 -222.437198)
		(mid 138.894312 -222.387055)
		(end 138.707114 -222.437198)
		(width 0.088646)
		(layer "In2.Cu")
		(net "M_F_CPU1_SB_DQS_DP<7>")
	)
	(segment
		(start 180.423058 -217.284554)
		(end 180.427884 -217.284554)
		(width 0.101854)
		(layer "F.Cu")
		(net "M_F_CPU1_SB_DQS_DP<6>")
	)
	(segment
		(start 179.150264 -217.967814)
		(end 179.575206 -217.542872)
		(width 0.20066)
		(layer "F.Cu")
		(net "M_F_CPU1_SB_DQS_DP<6>")
	)
	(segment
		(start 180.111908 -217.284554)
		(end 180.423058 -217.284554)
		(width 0.20066)
		(layer "F.Cu")
		(net "M_F_CPU1_SB_DQS_DP<6>")
	)
	(segment
		(start 178.594258 -217.716608)
		(end 178.845464 -217.967814)
		(width 0.20066)
		(layer "F.Cu")
		(net "M_F_CPU1_SB_DQS_DP<6>")
	)
	(segment
		(start 183.685434 -217.539316)
		(end 184.13095 -217.984832)
		(width 0.20066)
		(layer "F.Cu")
		(net "M_F_CPU1_SB_DQS_DP<6>")
	)
	(segment
		(start 180.434996 -217.291666)
		(end 182.447692 -217.291666)
		(width 0.1016)
		(layer "F.Cu")
		(net "M_F_CPU1_SB_DQS_DP<6>")
	)
	(segment
		(start 182.455058 -217.2843)
		(end 182.776876 -217.2843)
		(width 0.20066)
		(layer "F.Cu")
		(net "M_F_CPU1_SB_DQS_DP<6>")
	)
	(segment
		(start 182.776876 -217.2843)
		(end 183.031892 -217.539316)
		(width 0.20066)
		(layer "F.Cu")
		(net "M_F_CPU1_SB_DQS_DP<6>")
	)
	(segment
		(start 178.000914 -217.716608)
		(end 178.594258 -217.716608)
		(width 0.20066)
		(layer "F.Cu")
		(net "M_F_CPU1_SB_DQS_DP<6>")
	)
	(segment
		(start 183.031892 -217.539316)
		(end 183.685434 -217.539316)
		(width 0.20066)
		(layer "F.Cu")
		(net "M_F_CPU1_SB_DQS_DP<6>")
	)
	(segment
		(start 176.896014 -217.716608)
		(end 178.000914 -217.716608)
		(width 0.20066)
		(layer "F.Cu")
		(net "M_F_CPU1_SB_DQS_DP<6>")
	)
	(segment
		(start 184.13095 -217.984832)
		(end 184.708546 -217.984832)
		(width 0.20066)
		(layer "F.Cu")
		(net "M_F_CPU1_SB_DQS_DP<6>")
	)
	(segment
		(start 178.845464 -217.967814)
		(end 179.150264 -217.967814)
		(width 0.20066)
		(layer "F.Cu")
		(net "M_F_CPU1_SB_DQS_DP<6>")
	)
	(segment
		(start 179.575206 -217.542872)
		(end 179.85359 -217.542872)
		(width 0.20066)
		(layer "F.Cu")
		(net "M_F_CPU1_SB_DQS_DP<6>")
	)
	(segment
		(start 184.97677 -217.716608)
		(end 185.544714 -217.716608)
		(width 0.20066)
		(layer "F.Cu")
		(net "M_F_CPU1_SB_DQS_DP<6>")
	)
	(segment
		(start 184.708546 -217.984832)
		(end 184.97677 -217.716608)
		(width 0.20066)
		(layer "F.Cu")
		(net "M_F_CPU1_SB_DQS_DP<6>")
	)
	(segment
		(start 182.447692 -217.291666)
		(end 182.455058 -217.2843)
		(width 0.1016)
		(layer "F.Cu")
		(net "M_F_CPU1_SB_DQS_DP<6>")
	)
	(segment
		(start 180.427884 -217.284554)
		(end 180.434996 -217.291666)
		(width 0.1016)
		(layer "F.Cu")
		(net "M_F_CPU1_SB_DQS_DP<6>")
	)
	(segment
		(start 179.85359 -217.542872)
		(end 180.111908 -217.284554)
		(width 0.20066)
		(layer "F.Cu")
		(net "M_F_CPU1_SB_DQS_DP<6>")
	)
	(segment
		(start 134.665466 -230.086662)
		(end 134.665466 -230.622602)
		(width 0.20066)
		(layer "F.Cu")
		(net "M_F_CPU1_SB_DQS_DP<6>")
	)
	(segment
		(start 159.660336 -216.08161)
		(end 158.023814 -216.08161)
		(width 0.18288)
		(layer "In2.Cu")
		(net "M_F_CPU1_SB_DQS_DP<6>")
	)
	(segment
		(start 151.369268 -221.50959)
		(end 145.60931 -227.269548)
		(width 0.18288)
		(layer "In2.Cu")
		(net "M_F_CPU1_SB_DQS_DP<6>")
	)
	(segment
		(start 135.178038 -230.086662)
		(end 134.665466 -230.086662)
		(width 0.088646)
		(layer "In2.Cu")
		(net "M_F_CPU1_SB_DQS_DP<6>")
	)
	(segment
		(start 157.806644 -216.315036)
		(end 157.668214 -216.453466)
		(width 0.16002)
		(layer "In2.Cu")
		(net "M_F_CPU1_SB_DQS_DP<6>")
	)
	(segment
		(start 136.271254 -229.592124)
		(end 136.262364 -229.597204)
		(width 0.088646)
		(layer "In2.Cu")
		(net "M_F_CPU1_SB_DQS_DP<6>")
	)
	(segment
		(start 176.896014 -217.716608)
		(end 176.642522 -217.9701)
		(width 0.18288)
		(layer "In2.Cu")
		(net "M_F_CPU1_SB_DQS_DP<6>")
	)
	(segment
		(start 157.806644 -216.29878)
		(end 157.806644 -216.315036)
		(width 0.16002)
		(layer "In2.Cu")
		(net "M_F_CPU1_SB_DQS_DP<6>")
	)
	(segment
		(start 165.46068 -217.251026)
		(end 165.054026 -217.251026)
		(width 0.18288)
		(layer "In2.Cu")
		(net "M_F_CPU1_SB_DQS_DP<6>")
	)
	(segment
		(start 135.57758 -229.66553)
		(end 135.486648 -229.73157)
		(width 0.088646)
		(layer "In2.Cu")
		(net "M_F_CPU1_SB_DQS_DP<6>")
	)
	(segment
		(start 156.59354 -216.76487)
		(end 151.84882 -221.50959)
		(width 0.18288)
		(layer "In2.Cu")
		(net "M_F_CPU1_SB_DQS_DP<6>")
	)
	(segment
		(start 157.834838 -216.270586)
		(end 157.806644 -216.29878)
		(width 0.16002)
		(layer "In2.Cu")
		(net "M_F_CPU1_SB_DQS_DP<6>")
	)
	(segment
		(start 172.99305 -217.294968)
		(end 172.581824 -217.294968)
		(width 0.18288)
		(layer "In2.Cu")
		(net "M_F_CPU1_SB_DQS_DP<6>")
	)
	(segment
		(start 158.023814 -216.08161)
		(end 157.834838 -216.270586)
		(width 0.18288)
		(layer "In2.Cu")
		(net "M_F_CPU1_SB_DQS_DP<6>")
	)
	(segment
		(start 136.262364 -229.597204)
		(end 136.187942 -229.639876)
		(width 0.088646)
		(layer "In2.Cu")
		(net "M_F_CPU1_SB_DQS_DP<6>")
	)
	(segment
		(start 157.340554 -216.76487)
		(end 156.59354 -216.76487)
		(width 0.18288)
		(layer "In2.Cu")
		(net "M_F_CPU1_SB_DQS_DP<6>")
	)
	(segment
		(start 169.718482 -216.89695)
		(end 169.486834 -217.128598)
		(width 0.18288)
		(layer "In2.Cu")
		(net "M_F_CPU1_SB_DQS_DP<6>")
	)
	(segment
		(start 136.187942 -229.639876)
		(end 136.151874 -229.649274)
		(width 0.088646)
		(layer "In2.Cu")
		(net "M_F_CPU1_SB_DQS_DP<6>")
	)
	(segment
		(start 176.642522 -217.9701)
		(end 176.04867 -217.9701)
		(width 0.18288)
		(layer "In2.Cu")
		(net "M_F_CPU1_SB_DQS_DP<6>")
	)
	(segment
		(start 171.436284 -217.148918)
		(end 171.40809 -217.120724)
		(width 0.16002)
		(layer "In2.Cu")
		(net "M_F_CPU1_SB_DQS_DP<6>")
	)
	(segment
		(start 175.136556 -218.239848)
		(end 174.99711 -218.100402)
		(width 0.18288)
		(layer "In2.Cu")
		(net "M_F_CPU1_SB_DQS_DP<6>")
	)
	(segment
		(start 161.430208 -216.438988)
		(end 161.112708 -216.756488)
		(width 0.18288)
		(layer "In2.Cu")
		(net "M_F_CPU1_SB_DQS_DP<6>")
	)
	(segment
		(start 171.184316 -216.89695)
		(end 169.718482 -216.89695)
		(width 0.18288)
		(layer "In2.Cu")
		(net "M_F_CPU1_SB_DQS_DP<6>")
	)
	(segment
		(start 174.81423 -217.917522)
		(end 174.786036 -217.889328)
		(width 0.16002)
		(layer "In2.Cu")
		(net "M_F_CPU1_SB_DQS_DP<6>")
	)
	(segment
		(start 167.264842 -217.276426)
		(end 166.97833 -217.562938)
		(width 0.18288)
		(layer "In2.Cu")
		(net "M_F_CPU1_SB_DQS_DP<6>")
	)
	(segment
		(start 169.077132 -217.5383)
		(end 167.929306 -217.5383)
		(width 0.18288)
		(layer "In2.Cu")
		(net "M_F_CPU1_SB_DQS_DP<6>")
	)
	(segment
		(start 165.054026 -217.251026)
		(end 164.736526 -217.568526)
		(width 0.18288)
		(layer "In2.Cu")
		(net "M_F_CPU1_SB_DQS_DP<6>")
	)
	(segment
		(start 164.36975 -217.568526)
		(end 163.552124 -216.7509)
		(width 0.18288)
		(layer "In2.Cu")
		(net "M_F_CPU1_SB_DQS_DP<6>")
	)
	(segment
		(start 172.338492 -217.5383)
		(end 171.825666 -217.5383)
		(width 0.18288)
		(layer "In2.Cu")
		(net "M_F_CPU1_SB_DQS_DP<6>")
	)
	(segment
		(start 161.112708 -216.756488)
		(end 160.335214 -216.756488)
		(width 0.18288)
		(layer "In2.Cu")
		(net "M_F_CPU1_SB_DQS_DP<6>")
	)
	(segment
		(start 174.420784 -217.524076)
		(end 173.222158 -217.524076)
		(width 0.18288)
		(layer "In2.Cu")
		(net "M_F_CPU1_SB_DQS_DP<6>")
	)
	(segment
		(start 169.32021 -217.311478)
		(end 169.303954 -217.311478)
		(width 0.16002)
		(layer "In2.Cu")
		(net "M_F_CPU1_SB_DQS_DP<6>")
	)
	(segment
		(start 167.667432 -217.276426)
		(end 167.264842 -217.276426)
		(width 0.18288)
		(layer "In2.Cu")
		(net "M_F_CPU1_SB_DQS_DP<6>")
	)
	(segment
		(start 169.303954 -217.311478)
		(end 169.27576 -217.339672)
		(width 0.16002)
		(layer "In2.Cu")
		(net "M_F_CPU1_SB_DQS_DP<6>")
	)
	(segment
		(start 165.772592 -217.562938)
		(end 165.46068 -217.251026)
		(width 0.18288)
		(layer "In2.Cu")
		(net "M_F_CPU1_SB_DQS_DP<6>")
	)
	(segment
		(start 171.574714 -217.303604)
		(end 171.436284 -217.165174)
		(width 0.16002)
		(layer "In2.Cu")
		(net "M_F_CPU1_SB_DQS_DP<6>")
	)
	(segment
		(start 175.39716 -218.239848)
		(end 175.136556 -218.239848)
		(width 0.18288)
		(layer "In2.Cu")
		(net "M_F_CPU1_SB_DQS_DP<6>")
	)
	(segment
		(start 160.335214 -216.756488)
		(end 159.660336 -216.08161)
		(width 0.18288)
		(layer "In2.Cu")
		(net "M_F_CPU1_SB_DQS_DP<6>")
	)
	(segment
		(start 161.836862 -216.438988)
		(end 161.430208 -216.438988)
		(width 0.18288)
		(layer "In2.Cu")
		(net "M_F_CPU1_SB_DQS_DP<6>")
	)
	(segment
		(start 174.968916 -218.072208)
		(end 174.95266 -218.072208)
		(width 0.16002)
		(layer "In2.Cu")
		(net "M_F_CPU1_SB_DQS_DP<6>")
	)
	(segment
		(start 174.81423 -217.933778)
		(end 174.81423 -217.917522)
		(width 0.16002)
		(layer "In2.Cu")
		(net "M_F_CPU1_SB_DQS_DP<6>")
	)
	(segment
		(start 166.97833 -217.562938)
		(end 165.772592 -217.562938)
		(width 0.18288)
		(layer "In2.Cu")
		(net "M_F_CPU1_SB_DQS_DP<6>")
	)
	(segment
		(start 136.449816 -229.26294)
		(end 136.449816 -229.272846)
		(width 0.088646)
		(layer "In2.Cu")
		(net "M_F_CPU1_SB_DQS_DP<6>")
	)
	(segment
		(start 171.59097 -217.303604)
		(end 171.574714 -217.303604)
		(width 0.16002)
		(layer "In2.Cu")
		(net "M_F_CPU1_SB_DQS_DP<6>")
	)
	(segment
		(start 157.651958 -216.453466)
		(end 157.623764 -216.48166)
		(width 0.16002)
		(layer "In2.Cu")
		(net "M_F_CPU1_SB_DQS_DP<6>")
	)
	(segment
		(start 164.736526 -217.568526)
		(end 164.36975 -217.568526)
		(width 0.18288)
		(layer "In2.Cu")
		(net "M_F_CPU1_SB_DQS_DP<6>")
	)
	(segment
		(start 163.552124 -216.7509)
		(end 162.148774 -216.7509)
		(width 0.18288)
		(layer "In2.Cu")
		(net "M_F_CPU1_SB_DQS_DP<6>")
	)
	(segment
		(start 174.95266 -218.072208)
		(end 174.81423 -217.933778)
		(width 0.16002)
		(layer "In2.Cu")
		(net "M_F_CPU1_SB_DQS_DP<6>")
	)
	(segment
		(start 135.235188 -230.029512)
		(end 135.178038 -230.086662)
		(width 0.088646)
		(layer "In2.Cu")
		(net "M_F_CPU1_SB_DQS_DP<6>")
	)
	(segment
		(start 162.148774 -216.7509)
		(end 161.836862 -216.438988)
		(width 0.18288)
		(layer "In2.Cu")
		(net "M_F_CPU1_SB_DQS_DP<6>")
	)
	(segment
		(start 157.668214 -216.453466)
		(end 157.651958 -216.453466)
		(width 0.16002)
		(layer "In2.Cu")
		(net "M_F_CPU1_SB_DQS_DP<6>")
	)
	(segment
		(start 169.486834 -217.128598)
		(end 169.45864 -217.156792)
		(width 0.16002)
		(layer "In2.Cu")
		(net "M_F_CPU1_SB_DQS_DP<6>")
	)
	(segment
		(start 169.27576 -217.339672)
		(end 169.077132 -217.5383)
		(width 0.18288)
		(layer "In2.Cu")
		(net "M_F_CPU1_SB_DQS_DP<6>")
	)
	(segment
		(start 171.825666 -217.5383)
		(end 171.619164 -217.331798)
		(width 0.18288)
		(layer "In2.Cu")
		(net "M_F_CPU1_SB_DQS_DP<6>")
	)
	(segment
		(start 171.619164 -217.331798)
		(end 171.59097 -217.303604)
		(width 0.16002)
		(layer "In2.Cu")
		(net "M_F_CPU1_SB_DQS_DP<6>")
	)
	(segment
		(start 169.45864 -217.156792)
		(end 169.45864 -217.173048)
		(width 0.16002)
		(layer "In2.Cu")
		(net "M_F_CPU1_SB_DQS_DP<6>")
	)
	(segment
		(start 141.010386 -227.269548)
		(end 140.194792 -228.085142)
		(width 0.18288)
		(layer "In2.Cu")
		(net "M_F_CPU1_SB_DQS_DP<6>")
	)
	(segment
		(start 176.04867 -217.9701)
		(end 175.39716 -218.239848)
		(width 0.18288)
		(layer "In2.Cu")
		(net "M_F_CPU1_SB_DQS_DP<6>")
	)
	(segment
		(start 172.581824 -217.294968)
		(end 172.338492 -217.5383)
		(width 0.18288)
		(layer "In2.Cu")
		(net "M_F_CPU1_SB_DQS_DP<6>")
	)
	(segment
		(start 135.418068 -229.762304)
		(end 135.409178 -229.767384)
		(width 0.088646)
		(layer "In2.Cu")
		(net "M_F_CPU1_SB_DQS_DP<6>")
	)
	(segment
		(start 136.151874 -229.649274)
		(end 136.023604 -229.649274)
		(width 0.088646)
		(layer "In2.Cu")
		(net "M_F_CPU1_SB_DQS_DP<6>")
	)
	(segment
		(start 145.60931 -227.269548)
		(end 141.010386 -227.269548)
		(width 0.18288)
		(layer "In2.Cu")
		(net "M_F_CPU1_SB_DQS_DP<6>")
	)
	(segment
		(start 135.872474 -229.605586)
		(end 135.722614 -229.605586)
		(width 0.088646)
		(layer "In2.Cu")
		(net "M_F_CPU1_SB_DQS_DP<6>")
	)
	(segment
		(start 139.594844 -228.75494)
		(end 139.594844 -228.754686)
		(width 0.088646)
		(layer "In2.Cu")
		(net "M_F_CPU1_SB_DQS_DP<6>")
	)
	(segment
		(start 167.929306 -217.5383)
		(end 167.667432 -217.276426)
		(width 0.18288)
		(layer "In2.Cu")
		(net "M_F_CPU1_SB_DQS_DP<6>")
	)
	(segment
		(start 140.194792 -228.16947)
		(end 139.716764 -228.647498)
		(width 0.088646)
		(layer "In2.Cu")
		(net "M_F_CPU1_SB_DQS_DP<6>")
	)
	(segment
		(start 151.84882 -221.50959)
		(end 151.369268 -221.50959)
		(width 0.18288)
		(layer "In2.Cu")
		(net "M_F_CPU1_SB_DQS_DP<6>")
	)
	(segment
		(start 171.40809 -217.120724)
		(end 171.184316 -216.89695)
		(width 0.18288)
		(layer "In2.Cu")
		(net "M_F_CPU1_SB_DQS_DP<6>")
	)
	(segment
		(start 169.45864 -217.173048)
		(end 169.32021 -217.311478)
		(width 0.16002)
		(layer "In2.Cu")
		(net "M_F_CPU1_SB_DQS_DP<6>")
	)
	(segment
		(start 174.786036 -217.889328)
		(end 174.420784 -217.524076)
		(width 0.18288)
		(layer "In2.Cu")
		(net "M_F_CPU1_SB_DQS_DP<6>")
	)
	(segment
		(start 171.436284 -217.165174)
		(end 171.436284 -217.148918)
		(width 0.16002)
		(layer "In2.Cu")
		(net "M_F_CPU1_SB_DQS_DP<6>")
	)
	(segment
		(start 174.99711 -218.100402)
		(end 174.968916 -218.072208)
		(width 0.16002)
		(layer "In2.Cu")
		(net "M_F_CPU1_SB_DQS_DP<6>")
	)
	(segment
		(start 157.623764 -216.48166)
		(end 157.340554 -216.76487)
		(width 0.18288)
		(layer "In2.Cu")
		(net "M_F_CPU1_SB_DQS_DP<6>")
	)
	(segment
		(start 140.194792 -228.085142)
		(end 140.194792 -228.16947)
		(width 0.088646)
		(layer "In2.Cu")
		(net "M_F_CPU1_SB_DQS_DP<6>")
	)
	(segment
		(start 136.023604 -229.649274)
		(end 135.872474 -229.605586)
		(width 0.088646)
		(layer "In2.Cu")
		(net "M_F_CPU1_SB_DQS_DP<6>")
	)
	(segment
		(start 135.722614 -229.605586)
		(end 135.57758 -229.66553)
		(width 0.088646)
		(layer "In2.Cu")
		(net "M_F_CPU1_SB_DQS_DP<6>")
	)
	(segment
		(start 173.222158 -217.524076)
		(end 172.99305 -217.294968)
		(width 0.18288)
		(layer "In2.Cu")
		(net "M_F_CPU1_SB_DQS_DP<6>")
	)
	(arc
		(start 135.409178 -229.767384)
		(mid 135.293369 -229.879313)
		(end 135.235188 -230.029512)
		(width 0.088646)
		(layer "In2.Cu")
		(net "M_F_CPU1_SB_DQS_DP<6>")
	)
	(arc
		(start 136.449816 -229.272846)
		(mid 136.402137 -229.455746)
		(end 136.271254 -229.592124)
		(width 0.088646)
		(layer "In2.Cu")
		(net "M_F_CPU1_SB_DQS_DP<6>")
	)
	(arc
		(start 137.672064 -228.783388)
		(mid 137.484866 -228.833531)
		(end 137.297668 -228.783388)
		(width 0.088646)
		(layer "In2.Cu")
		(net "M_F_CPU1_SB_DQS_DP<6>")
	)
	(arc
		(start 139.716764 -228.647498)
		(mid 139.657547 -228.703197)
		(end 139.594844 -228.75494)
		(width 0.088646)
		(layer "In2.Cu")
		(net "M_F_CPU1_SB_DQS_DP<6>")
	)
	(arc
		(start 136.732264 -228.783388)
		(mid 136.527929 -228.985993)
		(end 136.449816 -229.26294)
		(width 0.088646)
		(layer "In2.Cu")
		(net "M_F_CPU1_SB_DQS_DP<6>")
	)
	(arc
		(start 139.177268 -228.783388)
		(mid 138.894566 -228.707612)
		(end 138.611864 -228.783388)
		(width 0.088646)
		(layer "In2.Cu")
		(net "M_F_CPU1_SB_DQS_DP<6>")
	)
	(arc
		(start 138.237468 -228.783388)
		(mid 137.954766 -228.707612)
		(end 137.672064 -228.783388)
		(width 0.088646)
		(layer "In2.Cu")
		(net "M_F_CPU1_SB_DQS_DP<6>")
	)
	(arc
		(start 135.486648 -229.73157)
		(mid 135.451587 -229.745215)
		(end 135.418068 -229.762304)
		(width 0.088646)
		(layer "In2.Cu")
		(net "M_F_CPU1_SB_DQS_DP<6>")
	)
	(arc
		(start 138.611864 -228.783388)
		(mid 138.424666 -228.833531)
		(end 138.237468 -228.783388)
		(width 0.088646)
		(layer "In2.Cu")
		(net "M_F_CPU1_SB_DQS_DP<6>")
	)
	(arc
		(start 139.551664 -228.783388)
		(mid 139.364466 -228.833531)
		(end 139.177268 -228.783388)
		(width 0.088646)
		(layer "In2.Cu")
		(net "M_F_CPU1_SB_DQS_DP<6>")
	)
	(arc
		(start 137.297668 -228.783388)
		(mid 137.014966 -228.707612)
		(end 136.732264 -228.783388)
		(width 0.088646)
		(layer "In2.Cu")
		(net "M_F_CPU1_SB_DQS_DP<6>")
	)
	(arc
		(start 139.594844 -228.754686)
		(mid 139.573754 -228.76979)
		(end 139.551664 -228.783388)
		(width 0.088646)
		(layer "In2.Cu")
		(net "M_F_CPU1_SB_DQS_DP<6>")
	)
	(segment
		(start 184.13095 -227.334826)
		(end 184.708546 -227.334826)
		(width 0.20066)
		(layer "F.Cu")
		(net "M_F_CPU1_SB_DQS_DP<5>")
	)
	(segment
		(start 179.575206 -226.892866)
		(end 179.85359 -226.892866)
		(width 0.20066)
		(layer "F.Cu")
		(net "M_F_CPU1_SB_DQS_DP<5>")
	)
	(segment
		(start 131.376166 -237.947454)
		(end 131.376166 -237.411514)
		(width 0.20066)
		(layer "F.Cu")
		(net "M_F_CPU1_SB_DQS_DP<5>")
	)
	(segment
		(start 176.896014 -227.066602)
		(end 178.000914 -227.066602)
		(width 0.20066)
		(layer "F.Cu")
		(net "M_F_CPU1_SB_DQS_DP<5>")
	)
	(segment
		(start 183.031892 -226.88931)
		(end 183.685434 -226.88931)
		(width 0.20066)
		(layer "F.Cu")
		(net "M_F_CPU1_SB_DQS_DP<5>")
	)
	(segment
		(start 180.427884 -226.634548)
		(end 180.434996 -226.64166)
		(width 0.1016)
		(layer "F.Cu")
		(net "M_F_CPU1_SB_DQS_DP<5>")
	)
	(segment
		(start 183.685434 -226.88931)
		(end 184.13095 -227.334826)
		(width 0.20066)
		(layer "F.Cu")
		(net "M_F_CPU1_SB_DQS_DP<5>")
	)
	(segment
		(start 184.708546 -227.334826)
		(end 184.97677 -227.066602)
		(width 0.20066)
		(layer "F.Cu")
		(net "M_F_CPU1_SB_DQS_DP<5>")
	)
	(segment
		(start 180.111908 -226.634548)
		(end 180.423058 -226.634548)
		(width 0.20066)
		(layer "F.Cu")
		(net "M_F_CPU1_SB_DQS_DP<5>")
	)
	(segment
		(start 182.455058 -226.634294)
		(end 182.776876 -226.634294)
		(width 0.20066)
		(layer "F.Cu")
		(net "M_F_CPU1_SB_DQS_DP<5>")
	)
	(segment
		(start 180.423058 -226.634548)
		(end 180.427884 -226.634548)
		(width 0.101854)
		(layer "F.Cu")
		(net "M_F_CPU1_SB_DQS_DP<5>")
	)
	(segment
		(start 182.776876 -226.634294)
		(end 183.031892 -226.88931)
		(width 0.20066)
		(layer "F.Cu")
		(net "M_F_CPU1_SB_DQS_DP<5>")
	)
	(segment
		(start 184.97677 -227.066602)
		(end 185.544714 -227.066602)
		(width 0.20066)
		(layer "F.Cu")
		(net "M_F_CPU1_SB_DQS_DP<5>")
	)
	(segment
		(start 131.375912 -237.947454)
		(end 131.376166 -237.947454)
		(width 0.20066)
		(layer "F.Cu")
		(net "M_F_CPU1_SB_DQS_DP<5>")
	)
	(segment
		(start 179.150264 -227.317808)
		(end 179.575206 -226.892866)
		(width 0.20066)
		(layer "F.Cu")
		(net "M_F_CPU1_SB_DQS_DP<5>")
	)
	(segment
		(start 182.447692 -226.64166)
		(end 182.455058 -226.634294)
		(width 0.1016)
		(layer "F.Cu")
		(net "M_F_CPU1_SB_DQS_DP<5>")
	)
	(segment
		(start 178.000914 -227.066602)
		(end 178.594258 -227.066602)
		(width 0.20066)
		(layer "F.Cu")
		(net "M_F_CPU1_SB_DQS_DP<5>")
	)
	(segment
		(start 179.85359 -226.892866)
		(end 180.111908 -226.634548)
		(width 0.20066)
		(layer "F.Cu")
		(net "M_F_CPU1_SB_DQS_DP<5>")
	)
	(segment
		(start 180.434996 -226.64166)
		(end 182.447692 -226.64166)
		(width 0.1016)
		(layer "F.Cu")
		(net "M_F_CPU1_SB_DQS_DP<5>")
	)
	(segment
		(start 178.845464 -227.317808)
		(end 179.150264 -227.317808)
		(width 0.20066)
		(layer "F.Cu")
		(net "M_F_CPU1_SB_DQS_DP<5>")
	)
	(segment
		(start 178.594258 -227.066602)
		(end 178.845464 -227.317808)
		(width 0.20066)
		(layer "F.Cu")
		(net "M_F_CPU1_SB_DQS_DP<5>")
	)
	(segment
		(start 158.351982 -225.217482)
		(end 158.17723 -225.217482)
		(width 0.18288)
		(layer "In4.Cu")
		(net "M_F_CPU1_SB_DQS_DP<5>")
	)
	(segment
		(start 172.989748 -226.642422)
		(end 172.584872 -226.642422)
		(width 0.18288)
		(layer "In4.Cu")
		(net "M_F_CPU1_SB_DQS_DP<5>")
	)
	(segment
		(start 165.337744 -224.603056)
		(end 164.986208 -224.603056)
		(width 0.18288)
		(layer "In4.Cu")
		(net "M_F_CPU1_SB_DQS_DP<5>")
	)
	(segment
		(start 137.67181 -236.922056)
		(end 137.672064 -236.922056)
		(width 0.088646)
		(layer "In4.Cu")
		(net "M_F_CPU1_SB_DQS_DP<5>")
	)
	(segment
		(start 168.261538 -225.828606)
		(end 166.932864 -225.828606)
		(width 0.18288)
		(layer "In4.Cu")
		(net "M_F_CPU1_SB_DQS_DP<5>")
	)
	(segment
		(start 140.918438 -235.1405)
		(end 140.515848 -235.1405)
		(width 0.088646)
		(layer "In4.Cu")
		(net "M_F_CPU1_SB_DQS_DP<5>")
	)
	(segment
		(start 132.756656 -237.014258)
		(end 132.322062 -237.014258)
		(width 0.088646)
		(layer "In4.Cu")
		(net "M_F_CPU1_SB_DQS_DP<5>")
	)
	(segment
		(start 176.024286 -226.68992)
		(end 175.827182 -226.493578)
		(width 0.18288)
		(layer "In4.Cu")
		(net "M_F_CPU1_SB_DQS_DP<5>")
	)
	(segment
		(start 132.863336 -236.985556)
		(end 132.756656 -237.014258)
		(width 0.088646)
		(layer "In4.Cu")
		(net "M_F_CPU1_SB_DQS_DP<5>")
	)
	(segment
		(start 139.535154 -236.972856)
		(end 139.364212 -236.972856)
		(width 0.088646)
		(layer "In4.Cu")
		(net "M_F_CPU1_SB_DQS_DP<5>")
	)
	(segment
		(start 170.315382 -225.753676)
		(end 169.600626 -225.457766)
		(width 0.18288)
		(layer "In4.Cu")
		(net "M_F_CPU1_SB_DQS_DP<5>")
	)
	(segment
		(start 131.888738 -237.411514)
		(end 131.376166 -237.411514)
		(width 0.088646)
		(layer "In4.Cu")
		(net "M_F_CPU1_SB_DQS_DP<5>")
	)
	(segment
		(start 172.584872 -226.642422)
		(end 172.312076 -226.915218)
		(width 0.18288)
		(layer "In4.Cu")
		(net "M_F_CPU1_SB_DQS_DP<5>")
	)
	(segment
		(start 154.739086 -225.170746)
		(end 147.180808 -232.729024)
		(width 0.18288)
		(layer "In4.Cu")
		(net "M_F_CPU1_SB_DQS_DP<5>")
	)
	(segment
		(start 132.97281 -236.922056)
		(end 132.928868 -236.94771)
		(width 0.088646)
		(layer "In4.Cu")
		(net "M_F_CPU1_SB_DQS_DP<5>")
	)
	(segment
		(start 166.932864 -225.828606)
		(end 165.967156 -224.862898)
		(width 0.18288)
		(layer "In4.Cu")
		(net "M_F_CPU1_SB_DQS_DP<5>")
	)
	(segment
		(start 143.78432 -232.729024)
		(end 141.432534 -235.08081)
		(width 0.18288)
		(layer "In4.Cu")
		(net "M_F_CPU1_SB_DQS_DP<5>")
	)
	(segment
		(start 169.600626 -225.457766)
		(end 169.156634 -225.457766)
		(width 0.18288)
		(layer "In4.Cu")
		(net "M_F_CPU1_SB_DQS_DP<5>")
	)
	(segment
		(start 176.896014 -227.066602)
		(end 176.61636 -227.346256)
		(width 0.18288)
		(layer "In4.Cu")
		(net "M_F_CPU1_SB_DQS_DP<5>")
	)
	(segment
		(start 139.691618 -236.816392)
		(end 139.535154 -236.972856)
		(width 0.088646)
		(layer "In4.Cu")
		(net "M_F_CPU1_SB_DQS_DP<5>")
	)
	(segment
		(start 136.357614 -236.922056)
		(end 136.342882 -236.91342)
		(width 0.088646)
		(layer "In4.Cu")
		(net "M_F_CPU1_SB_DQS_DP<5>")
	)
	(segment
		(start 176.375568 -227.346256)
		(end 176.24171 -227.212398)
		(width 0.18288)
		(layer "In4.Cu")
		(net "M_F_CPU1_SB_DQS_DP<5>")
	)
	(segment
		(start 164.986208 -224.603056)
		(end 164.079428 -224.978722)
		(width 0.18288)
		(layer "In4.Cu")
		(net "M_F_CPU1_SB_DQS_DP<5>")
	)
	(segment
		(start 175.827182 -226.493578)
		(end 175.369982 -226.30384)
		(width 0.18288)
		(layer "In4.Cu")
		(net "M_F_CPU1_SB_DQS_DP<5>")
	)
	(segment
		(start 141.001496 -235.08081)
		(end 140.978128 -235.08081)
		(width 0.088646)
		(layer "In4.Cu")
		(net "M_F_CPU1_SB_DQS_DP<5>")
	)
	(segment
		(start 141.432534 -235.08081)
		(end 141.001496 -235.08081)
		(width 0.18288)
		(layer "In4.Cu")
		(net "M_F_CPU1_SB_DQS_DP<5>")
	)
	(segment
		(start 164.006022 -224.978722)
		(end 162.490658 -224.351088)
		(width 0.18288)
		(layer "In4.Cu")
		(net "M_F_CPU1_SB_DQS_DP<5>")
	)
	(segment
		(start 172.312076 -226.915218)
		(end 171.476924 -226.915218)
		(width 0.18288)
		(layer "In4.Cu")
		(net "M_F_CPU1_SB_DQS_DP<5>")
	)
	(segment
		(start 173.934882 -226.919536)
		(end 173.266862 -226.919536)
		(width 0.18288)
		(layer "In4.Cu")
		(net "M_F_CPU1_SB_DQS_DP<5>")
	)
	(segment
		(start 132.128768 -237.087156)
		(end 132.119878 -237.092236)
		(width 0.088646)
		(layer "In4.Cu")
		(net "M_F_CPU1_SB_DQS_DP<5>")
	)
	(segment
		(start 162.490658 -224.351088)
		(end 162.260788 -224.351088)
		(width 0.18288)
		(layer "In4.Cu")
		(net "M_F_CPU1_SB_DQS_DP<5>")
	)
	(segment
		(start 131.945888 -237.354364)
		(end 131.888738 -237.411514)
		(width 0.088646)
		(layer "In4.Cu")
		(net "M_F_CPU1_SB_DQS_DP<5>")
	)
	(segment
		(start 176.24171 -227.212398)
		(end 176.024286 -226.68992)
		(width 0.18288)
		(layer "In4.Cu")
		(net "M_F_CPU1_SB_DQS_DP<5>")
	)
	(segment
		(start 174.550578 -226.30384)
		(end 173.934882 -226.919536)
		(width 0.18288)
		(layer "In4.Cu")
		(net "M_F_CPU1_SB_DQS_DP<5>")
	)
	(segment
		(start 157.268926 -225.170746)
		(end 154.739086 -225.170746)
		(width 0.18288)
		(layer "In4.Cu")
		(net "M_F_CPU1_SB_DQS_DP<5>")
	)
	(segment
		(start 139.956032 -236.420914)
		(end 139.691618 -236.816392)
		(width 0.088646)
		(layer "In4.Cu")
		(net "M_F_CPU1_SB_DQS_DP<5>")
	)
	(segment
		(start 162.260788 -224.351088)
		(end 162.002216 -224.092516)
		(width 0.18288)
		(layer "In4.Cu")
		(net "M_F_CPU1_SB_DQS_DP<5>")
	)
	(segment
		(start 158.17723 -225.217482)
		(end 157.902148 -224.9424)
		(width 0.18288)
		(layer "In4.Cu")
		(net "M_F_CPU1_SB_DQS_DP<5>")
	)
	(segment
		(start 139.956032 -235.700316)
		(end 139.956032 -236.420914)
		(width 0.088646)
		(layer "In4.Cu")
		(net "M_F_CPU1_SB_DQS_DP<5>")
	)
	(segment
		(start 161.347404 -224.342452)
		(end 160.465262 -224.342452)
		(width 0.18288)
		(layer "In4.Cu")
		(net "M_F_CPU1_SB_DQS_DP<5>")
	)
	(segment
		(start 157.497272 -224.9424)
		(end 157.268926 -225.170746)
		(width 0.18288)
		(layer "In4.Cu")
		(net "M_F_CPU1_SB_DQS_DP<5>")
	)
	(segment
		(start 175.369982 -226.30384)
		(end 174.550578 -226.30384)
		(width 0.18288)
		(layer "In4.Cu")
		(net "M_F_CPU1_SB_DQS_DP<5>")
	)
	(segment
		(start 132.928868 -236.94771)
		(end 132.863336 -236.985556)
		(width 0.088646)
		(layer "In4.Cu")
		(net "M_F_CPU1_SB_DQS_DP<5>")
	)
	(segment
		(start 157.902148 -224.9424)
		(end 157.497272 -224.9424)
		(width 0.18288)
		(layer "In4.Cu")
		(net "M_F_CPU1_SB_DQS_DP<5>")
	)
	(segment
		(start 138.237214 -236.922056)
		(end 138.222482 -236.91342)
		(width 0.088646)
		(layer "In4.Cu")
		(net "M_F_CPU1_SB_DQS_DP<5>")
	)
	(segment
		(start 169.156634 -225.457766)
		(end 168.261538 -225.828606)
		(width 0.18288)
		(layer "In4.Cu")
		(net "M_F_CPU1_SB_DQS_DP<5>")
	)
	(segment
		(start 137.297668 -236.922056)
		(end 137.287254 -236.91596)
		(width 0.088646)
		(layer "In4.Cu")
		(net "M_F_CPU1_SB_DQS_DP<5>")
	)
	(segment
		(start 140.978128 -235.08081)
		(end 140.918438 -235.1405)
		(width 0.088646)
		(layer "In4.Cu")
		(net "M_F_CPU1_SB_DQS_DP<5>")
	)
	(segment
		(start 132.983224 -236.91596)
		(end 132.97281 -236.922056)
		(width 0.088646)
		(layer "In4.Cu")
		(net "M_F_CPU1_SB_DQS_DP<5>")
	)
	(segment
		(start 160.465262 -224.342452)
		(end 158.351982 -225.217482)
		(width 0.18288)
		(layer "In4.Cu")
		(net "M_F_CPU1_SB_DQS_DP<5>")
	)
	(segment
		(start 139.177014 -236.922056)
		(end 139.162282 -236.91342)
		(width 0.088646)
		(layer "In4.Cu")
		(net "M_F_CPU1_SB_DQS_DP<5>")
	)
	(segment
		(start 147.180808 -232.729024)
		(end 143.78432 -232.729024)
		(width 0.18288)
		(layer "In4.Cu")
		(net "M_F_CPU1_SB_DQS_DP<5>")
	)
	(segment
		(start 171.476924 -226.915218)
		(end 170.315382 -225.753676)
		(width 0.18288)
		(layer "In4.Cu")
		(net "M_F_CPU1_SB_DQS_DP<5>")
	)
	(segment
		(start 164.079428 -224.978722)
		(end 164.006022 -224.978722)
		(width 0.18288)
		(layer "In4.Cu")
		(net "M_F_CPU1_SB_DQS_DP<5>")
	)
	(segment
		(start 135.417814 -236.922056)
		(end 135.4074 -236.91596)
		(width 0.088646)
		(layer "In4.Cu")
		(net "M_F_CPU1_SB_DQS_DP<5>")
	)
	(segment
		(start 161.59734 -224.092516)
		(end 161.347404 -224.342452)
		(width 0.18288)
		(layer "In4.Cu")
		(net "M_F_CPU1_SB_DQS_DP<5>")
	)
	(segment
		(start 140.515848 -235.1405)
		(end 139.956032 -235.700316)
		(width 0.088646)
		(layer "In4.Cu")
		(net "M_F_CPU1_SB_DQS_DP<5>")
	)
	(segment
		(start 162.002216 -224.092516)
		(end 161.59734 -224.092516)
		(width 0.18288)
		(layer "In4.Cu")
		(net "M_F_CPU1_SB_DQS_DP<5>")
	)
	(segment
		(start 165.967156 -224.862898)
		(end 165.337744 -224.603056)
		(width 0.18288)
		(layer "In4.Cu")
		(net "M_F_CPU1_SB_DQS_DP<5>")
	)
	(segment
		(start 173.266862 -226.919536)
		(end 172.989748 -226.642422)
		(width 0.18288)
		(layer "In4.Cu")
		(net "M_F_CPU1_SB_DQS_DP<5>")
	)
	(segment
		(start 176.61636 -227.346256)
		(end 176.375568 -227.346256)
		(width 0.18288)
		(layer "In4.Cu")
		(net "M_F_CPU1_SB_DQS_DP<5>")
	)
	(arc
		(start 135.4074 -236.91596)
		(mid 135.129222 -236.846237)
		(end 134.852664 -236.922056)
		(width 0.088646)
		(layer "In4.Cu")
		(net "M_F_CPU1_SB_DQS_DP<5>")
	)
	(arc
		(start 132.178806 -237.063026)
		(mid 132.153337 -237.074159)
		(end 132.128768 -237.087156)
		(width 0.088646)
		(layer "In4.Cu")
		(net "M_F_CPU1_SB_DQS_DP<5>")
	)
	(arc
		(start 136.73201 -236.922056)
		(mid 136.544812 -236.972233)
		(end 136.357614 -236.922056)
		(width 0.088646)
		(layer "In4.Cu")
		(net "M_F_CPU1_SB_DQS_DP<5>")
	)
	(arc
		(start 132.322062 -237.014258)
		(mid 132.273948 -237.020614)
		(end 132.229098 -237.03915)
		(width 0.088646)
		(layer "In4.Cu")
		(net "M_F_CPU1_SB_DQS_DP<5>")
	)
	(arc
		(start 132.229098 -237.03915)
		(mid 132.204393 -237.052017)
		(end 132.178806 -237.063026)
		(width 0.088646)
		(layer "In4.Cu")
		(net "M_F_CPU1_SB_DQS_DP<5>")
	)
	(arc
		(start 134.852664 -236.922056)
		(mid 134.665466 -236.972233)
		(end 134.478268 -236.922056)
		(width 0.088646)
		(layer "In4.Cu")
		(net "M_F_CPU1_SB_DQS_DP<5>")
	)
	(arc
		(start 136.342882 -236.91342)
		(mid 136.066407 -236.8461)
		(end 135.79221 -236.922056)
		(width 0.088646)
		(layer "In4.Cu")
		(net "M_F_CPU1_SB_DQS_DP<5>")
	)
	(arc
		(start 138.61161 -236.922056)
		(mid 138.424412 -236.972233)
		(end 138.237214 -236.922056)
		(width 0.088646)
		(layer "In4.Cu")
		(net "M_F_CPU1_SB_DQS_DP<5>")
	)
	(arc
		(start 134.478268 -236.922056)
		(mid 134.195566 -236.84628)
		(end 133.912864 -236.922056)
		(width 0.088646)
		(layer "In4.Cu")
		(net "M_F_CPU1_SB_DQS_DP<5>")
	)
	(arc
		(start 137.287254 -236.91596)
		(mid 137.008822 -236.846114)
		(end 136.73201 -236.922056)
		(width 0.088646)
		(layer "In4.Cu")
		(net "M_F_CPU1_SB_DQS_DP<5>")
	)
	(arc
		(start 139.162282 -236.91342)
		(mid 138.885807 -236.8461)
		(end 138.61161 -236.922056)
		(width 0.088646)
		(layer "In4.Cu")
		(net "M_F_CPU1_SB_DQS_DP<5>")
	)
	(arc
		(start 139.364212 -236.972856)
		(mid 139.267278 -236.959758)
		(end 139.177014 -236.922056)
		(width 0.088646)
		(layer "In4.Cu")
		(net "M_F_CPU1_SB_DQS_DP<5>")
	)
	(arc
		(start 137.672064 -236.922056)
		(mid 137.484866 -236.972233)
		(end 137.297668 -236.922056)
		(width 0.088646)
		(layer "In4.Cu")
		(net "M_F_CPU1_SB_DQS_DP<5>")
	)
	(arc
		(start 138.222482 -236.91342)
		(mid 137.946007 -236.8461)
		(end 137.67181 -236.922056)
		(width 0.088646)
		(layer "In4.Cu")
		(net "M_F_CPU1_SB_DQS_DP<5>")
	)
	(arc
		(start 133.538468 -236.922056)
		(mid 133.261655 -236.846186)
		(end 132.983224 -236.91596)
		(width 0.088646)
		(layer "In4.Cu")
		(net "M_F_CPU1_SB_DQS_DP<5>")
	)
	(arc
		(start 133.912864 -236.922056)
		(mid 133.725666 -236.972233)
		(end 133.538468 -236.922056)
		(width 0.088646)
		(layer "In4.Cu")
		(net "M_F_CPU1_SB_DQS_DP<5>")
	)
	(arc
		(start 135.79221 -236.922056)
		(mid 135.605012 -236.972233)
		(end 135.417814 -236.922056)
		(width 0.088646)
		(layer "In4.Cu")
		(net "M_F_CPU1_SB_DQS_DP<5>")
	)
	(arc
		(start 132.119878 -237.092236)
		(mid 132.004069 -237.204165)
		(end 131.945888 -237.354364)
		(width 0.088646)
		(layer "In4.Cu")
		(net "M_F_CPU1_SB_DQS_DP<5>")
	)
	(segment
		(start 183.685434 -236.239304)
		(end 184.13095 -236.68482)
		(width 0.20066)
		(layer "F.Cu")
		(net "M_F_CPU1_SB_DQS_DP<4>")
	)
	(segment
		(start 180.427884 -235.984542)
		(end 180.434996 -235.991654)
		(width 0.1016)
		(layer "F.Cu")
		(net "M_F_CPU1_SB_DQS_DP<4>")
	)
	(segment
		(start 184.708546 -236.68482)
		(end 184.97677 -236.416596)
		(width 0.20066)
		(layer "F.Cu")
		(net "M_F_CPU1_SB_DQS_DP<4>")
	)
	(segment
		(start 180.434996 -235.991654)
		(end 182.447692 -235.991654)
		(width 0.1016)
		(layer "F.Cu")
		(net "M_F_CPU1_SB_DQS_DP<4>")
	)
	(segment
		(start 180.111908 -235.984542)
		(end 180.423058 -235.984542)
		(width 0.20066)
		(layer "F.Cu")
		(net "M_F_CPU1_SB_DQS_DP<4>")
	)
	(segment
		(start 176.896014 -236.416596)
		(end 178.000914 -236.416596)
		(width 0.20066)
		(layer "F.Cu")
		(net "M_F_CPU1_SB_DQS_DP<4>")
	)
	(segment
		(start 178.594258 -236.416596)
		(end 178.845464 -236.667802)
		(width 0.20066)
		(layer "F.Cu")
		(net "M_F_CPU1_SB_DQS_DP<4>")
	)
	(segment
		(start 183.031892 -236.239304)
		(end 183.685434 -236.239304)
		(width 0.20066)
		(layer "F.Cu")
		(net "M_F_CPU1_SB_DQS_DP<4>")
	)
	(segment
		(start 180.423058 -235.984542)
		(end 180.427884 -235.984542)
		(width 0.101854)
		(layer "F.Cu")
		(net "M_F_CPU1_SB_DQS_DP<4>")
	)
	(segment
		(start 134.665466 -239.85347)
		(end 134.665212 -239.853216)
		(width 0.20066)
		(layer "F.Cu")
		(net "M_F_CPU1_SB_DQS_DP<4>")
	)
	(segment
		(start 179.150264 -236.667802)
		(end 179.575206 -236.24286)
		(width 0.20066)
		(layer "F.Cu")
		(net "M_F_CPU1_SB_DQS_DP<4>")
	)
	(segment
		(start 178.000914 -236.416596)
		(end 178.594258 -236.416596)
		(width 0.20066)
		(layer "F.Cu")
		(net "M_F_CPU1_SB_DQS_DP<4>")
	)
	(segment
		(start 179.85359 -236.24286)
		(end 180.111908 -235.984542)
		(width 0.20066)
		(layer "F.Cu")
		(net "M_F_CPU1_SB_DQS_DP<4>")
	)
	(segment
		(start 182.776876 -235.984288)
		(end 183.031892 -236.239304)
		(width 0.20066)
		(layer "F.Cu")
		(net "M_F_CPU1_SB_DQS_DP<4>")
	)
	(segment
		(start 179.575206 -236.24286)
		(end 179.85359 -236.24286)
		(width 0.20066)
		(layer "F.Cu")
		(net "M_F_CPU1_SB_DQS_DP<4>")
	)
	(segment
		(start 134.665466 -240.389156)
		(end 134.665466 -239.85347)
		(width 0.20066)
		(layer "F.Cu")
		(net "M_F_CPU1_SB_DQS_DP<4>")
	)
	(segment
		(start 178.845464 -236.667802)
		(end 179.150264 -236.667802)
		(width 0.20066)
		(layer "F.Cu")
		(net "M_F_CPU1_SB_DQS_DP<4>")
	)
	(segment
		(start 182.447692 -235.991654)
		(end 182.455058 -235.984288)
		(width 0.1016)
		(layer "F.Cu")
		(net "M_F_CPU1_SB_DQS_DP<4>")
	)
	(segment
		(start 184.13095 -236.68482)
		(end 184.708546 -236.68482)
		(width 0.20066)
		(layer "F.Cu")
		(net "M_F_CPU1_SB_DQS_DP<4>")
	)
	(segment
		(start 182.455058 -235.984288)
		(end 182.776876 -235.984288)
		(width 0.20066)
		(layer "F.Cu")
		(net "M_F_CPU1_SB_DQS_DP<4>")
	)
	(segment
		(start 184.97677 -236.416596)
		(end 185.544714 -236.416596)
		(width 0.20066)
		(layer "F.Cu")
		(net "M_F_CPU1_SB_DQS_DP<4>")
	)
	(segment
		(start 135.887968 -239.363758)
		(end 135.811768 -239.363758)
		(width 0.088646)
		(layer "In2.Cu")
		(net "M_F_CPU1_SB_DQS_DP<4>")
	)
	(segment
		(start 139.300204 -240.269776)
		(end 139.297918 -240.266982)
		(width 0.088646)
		(layer "In2.Cu")
		(net "M_F_CPU1_SB_DQS_DP<4>")
	)
	(segment
		(start 139.55776 -240.527332)
		(end 139.300204 -240.269776)
		(width 0.088646)
		(layer "In2.Cu")
		(net "M_F_CPU1_SB_DQS_DP<4>")
	)
	(segment
		(start 139.237466 -240.214658)
		(end 139.186666 -240.18367)
		(width 0.088646)
		(layer "In2.Cu")
		(net "M_F_CPU1_SB_DQS_DP<4>")
	)
	(segment
		(start 176.896014 -236.416596)
		(end 176.666906 -236.64291)
		(width 0.18288)
		(layer "In2.Cu")
		(net "M_F_CPU1_SB_DQS_DP<4>")
	)
	(segment
		(start 159.767778 -236.656118)
		(end 159.58185 -236.47019)
		(width 0.18288)
		(layer "In2.Cu")
		(net "M_F_CPU1_SB_DQS_DP<4>")
	)
	(segment
		(start 135.235188 -239.796066)
		(end 135.178038 -239.853216)
		(width 0.088646)
		(layer "In2.Cu")
		(net "M_F_CPU1_SB_DQS_DP<4>")
	)
	(segment
		(start 172.9994 -235.990892)
		(end 172.600874 -235.990892)
		(width 0.18288)
		(layer "In2.Cu")
		(net "M_F_CPU1_SB_DQS_DP<4>")
	)
	(segment
		(start 175.020224 -236.778546)
		(end 174.728124 -236.486446)
		(width 0.18288)
		(layer "In2.Cu")
		(net "M_F_CPU1_SB_DQS_DP<4>")
	)
	(segment
		(start 135.178038 -239.853216)
		(end 134.665212 -239.853216)
		(width 0.088646)
		(layer "In2.Cu")
		(net "M_F_CPU1_SB_DQS_DP<4>")
	)
	(segment
		(start 161.027364 -236.261148)
		(end 160.33877 -236.949996)
		(width 0.18288)
		(layer "In2.Cu")
		(net "M_F_CPU1_SB_DQS_DP<4>")
	)
	(segment
		(start 140.459206 -240.527332)
		(end 139.55776 -240.527332)
		(width 0.088646)
		(layer "In2.Cu")
		(net "M_F_CPU1_SB_DQS_DP<4>")
	)
	(segment
		(start 176.666906 -236.64291)
		(end 176.233328 -236.64291)
		(width 0.18288)
		(layer "In2.Cu")
		(net "M_F_CPU1_SB_DQS_DP<4>")
	)
	(segment
		(start 169.344594 -235.991146)
		(end 169.328338 -235.991146)
		(width 0.16002)
		(layer "In2.Cu")
		(net "M_F_CPU1_SB_DQS_DP<4>")
	)
	(segment
		(start 158.018734 -236.47019)
		(end 157.708854 -236.78007)
		(width 0.18288)
		(layer "In2.Cu")
		(net "M_F_CPU1_SB_DQS_DP<4>")
	)
	(segment
		(start 169.202354 -236.11713)
		(end 168.538652 -236.11713)
		(width 0.18288)
		(layer "In2.Cu")
		(net "M_F_CPU1_SB_DQS_DP<4>")
	)
	(segment
		(start 165.429692 -234.28071)
		(end 164.947092 -234.28071)
		(width 0.18288)
		(layer "In2.Cu")
		(net "M_F_CPU1_SB_DQS_DP<4>")
	)
	(segment
		(start 163.604194 -235.163868)
		(end 163.588446 -235.163868)
		(width 0.16002)
		(layer "In2.Cu")
		(net "M_F_CPU1_SB_DQS_DP<4>")
	)
	(segment
		(start 164.947092 -234.28071)
		(end 164.753798 -234.474004)
		(width 0.18288)
		(layer "In2.Cu")
		(net "M_F_CPU1_SB_DQS_DP<4>")
	)
	(segment
		(start 175.249586 -236.873796)
		(end 175.020224 -236.778546)
		(width 0.18288)
		(layer "In2.Cu")
		(net "M_F_CPU1_SB_DQS_DP<4>")
	)
	(segment
		(start 169.511218 -235.808266)
		(end 169.483024 -235.83646)
		(width 0.16002)
		(layer "In2.Cu")
		(net "M_F_CPU1_SB_DQS_DP<4>")
	)
	(segment
		(start 162.225228 -235.506006)
		(end 161.78276 -235.94822)
		(width 0.18288)
		(layer "In2.Cu")
		(net "M_F_CPU1_SB_DQS_DP<4>")
	)
	(segment
		(start 169.483024 -235.852716)
		(end 169.344594 -235.991146)
		(width 0.16002)
		(layer "In2.Cu")
		(net "M_F_CPU1_SB_DQS_DP<4>")
	)
	(segment
		(start 163.771326 -234.980988)
		(end 163.743132 -235.009182)
		(width 0.16002)
		(layer "In2.Cu")
		(net "M_F_CPU1_SB_DQS_DP<4>")
	)
	(segment
		(start 159.950658 -236.838998)
		(end 159.934402 -236.838998)
		(width 0.16002)
		(layer "In2.Cu")
		(net "M_F_CPU1_SB_DQS_DP<4>")
	)
	(segment
		(start 157.708854 -236.78007)
		(end 156.65704 -237.216188)
		(width 0.18288)
		(layer "In2.Cu")
		(net "M_F_CPU1_SB_DQS_DP<4>")
	)
	(segment
		(start 165.688518 -234.539536)
		(end 165.429692 -234.28071)
		(width 0.18288)
		(layer "In2.Cu")
		(net "M_F_CPU1_SB_DQS_DP<4>")
	)
	(segment
		(start 166.620698 -234.539536)
		(end 165.688518 -234.539536)
		(width 0.18288)
		(layer "In2.Cu")
		(net "M_F_CPU1_SB_DQS_DP<4>")
	)
	(segment
		(start 160.061656 -236.949996)
		(end 159.978852 -236.867192)
		(width 0.18288)
		(layer "In2.Cu")
		(net "M_F_CPU1_SB_DQS_DP<4>")
	)
	(segment
		(start 139.185396 -240.182654)
		(end 139.18438 -240.182146)
		(width 0.088646)
		(layer "In2.Cu")
		(net "M_F_CPU1_SB_DQS_DP<4>")
	)
	(segment
		(start 139.240006 -240.215674)
		(end 139.236196 -240.213388)
		(width 0.088646)
		(layer "In2.Cu")
		(net "M_F_CPU1_SB_DQS_DP<4>")
	)
	(segment
		(start 169.300144 -236.01934)
		(end 169.202354 -236.11713)
		(width 0.18288)
		(layer "In2.Cu")
		(net "M_F_CPU1_SB_DQS_DP<4>")
	)
	(segment
		(start 172.600874 -235.990892)
		(end 172.34916 -236.242606)
		(width 0.18288)
		(layer "In2.Cu")
		(net "M_F_CPU1_SB_DQS_DP<4>")
	)
	(segment
		(start 135.418068 -239.528858)
		(end 135.409178 -239.533938)
		(width 0.088646)
		(layer "In2.Cu")
		(net "M_F_CPU1_SB_DQS_DP<4>")
	)
	(segment
		(start 159.934402 -236.838998)
		(end 159.795972 -236.700568)
		(width 0.16002)
		(layer "In2.Cu")
		(net "M_F_CPU1_SB_DQS_DP<4>")
	)
	(segment
		(start 163.919916 -234.832398)
		(end 163.771326 -234.980988)
		(width 0.18288)
		(layer "In2.Cu")
		(net "M_F_CPU1_SB_DQS_DP<4>")
	)
	(segment
		(start 163.246308 -235.506006)
		(end 162.225228 -235.506006)
		(width 0.18288)
		(layer "In2.Cu")
		(net "M_F_CPU1_SB_DQS_DP<4>")
	)
	(segment
		(start 140.518896 -240.467642)
		(end 140.459206 -240.527332)
		(width 0.088646)
		(layer "In2.Cu")
		(net "M_F_CPU1_SB_DQS_DP<4>")
	)
	(segment
		(start 174.728124 -236.486446)
		(end 174.270416 -236.296962)
		(width 0.18288)
		(layer "In2.Cu")
		(net "M_F_CPU1_SB_DQS_DP<4>")
	)
	(segment
		(start 167.201596 -234.77982)
		(end 166.620698 -234.539536)
		(width 0.18288)
		(layer "In2.Cu")
		(net "M_F_CPU1_SB_DQS_DP<4>")
	)
	(segment
		(start 176.233328 -236.64291)
		(end 175.675544 -236.873796)
		(width 0.18288)
		(layer "In2.Cu")
		(net "M_F_CPU1_SB_DQS_DP<4>")
	)
	(segment
		(start 161.78276 -235.94822)
		(end 161.027364 -236.261148)
		(width 0.18288)
		(layer "In2.Cu")
		(net "M_F_CPU1_SB_DQS_DP<4>")
	)
	(segment
		(start 153.405586 -240.467642)
		(end 140.518896 -240.467642)
		(width 0.18288)
		(layer "In2.Cu")
		(net "M_F_CPU1_SB_DQS_DP<4>")
	)
	(segment
		(start 164.753798 -234.634024)
		(end 164.555424 -234.832398)
		(width 0.18288)
		(layer "In2.Cu")
		(net "M_F_CPU1_SB_DQS_DP<4>")
	)
	(segment
		(start 139.182348 -240.180876)
		(end 139.172442 -240.17478)
		(width 0.088646)
		(layer "In2.Cu")
		(net "M_F_CPU1_SB_DQS_DP<4>")
	)
	(segment
		(start 163.743132 -235.02493)
		(end 163.604194 -235.163868)
		(width 0.16002)
		(layer "In2.Cu")
		(net "M_F_CPU1_SB_DQS_DP<4>")
	)
	(segment
		(start 139.18311 -240.181384)
		(end 139.182348 -240.180876)
		(width 0.088646)
		(layer "In2.Cu")
		(net "M_F_CPU1_SB_DQS_DP<4>")
	)
	(segment
		(start 164.555424 -234.832398)
		(end 163.919916 -234.832398)
		(width 0.18288)
		(layer "In2.Cu")
		(net "M_F_CPU1_SB_DQS_DP<4>")
	)
	(segment
		(start 160.33877 -236.949996)
		(end 160.061656 -236.949996)
		(width 0.18288)
		(layer "In2.Cu")
		(net "M_F_CPU1_SB_DQS_DP<4>")
	)
	(segment
		(start 173.30547 -236.296962)
		(end 172.9994 -235.990892)
		(width 0.18288)
		(layer "In2.Cu")
		(net "M_F_CPU1_SB_DQS_DP<4>")
	)
	(segment
		(start 172.077888 -236.242606)
		(end 171.734988 -236.100366)
		(width 0.18288)
		(layer "In2.Cu")
		(net "M_F_CPU1_SB_DQS_DP<4>")
	)
	(segment
		(start 136.277096 -239.355122)
		(end 136.262364 -239.363758)
		(width 0.088646)
		(layer "In2.Cu")
		(net "M_F_CPU1_SB_DQS_DP<4>")
	)
	(segment
		(start 168.538652 -236.11713)
		(end 167.201596 -234.77982)
		(width 0.18288)
		(layer "In2.Cu")
		(net "M_F_CPU1_SB_DQS_DP<4>")
	)
	(segment
		(start 169.328338 -235.991146)
		(end 169.300144 -236.01934)
		(width 0.16002)
		(layer "In2.Cu")
		(net "M_F_CPU1_SB_DQS_DP<4>")
	)
	(segment
		(start 169.705274 -235.61421)
		(end 169.511218 -235.808266)
		(width 0.18288)
		(layer "In2.Cu")
		(net "M_F_CPU1_SB_DQS_DP<4>")
	)
	(segment
		(start 163.743132 -235.009182)
		(end 163.743132 -235.02493)
		(width 0.16002)
		(layer "In2.Cu")
		(net "M_F_CPU1_SB_DQS_DP<4>")
	)
	(segment
		(start 164.753798 -234.474004)
		(end 164.753798 -234.634024)
		(width 0.18288)
		(layer "In2.Cu")
		(net "M_F_CPU1_SB_DQS_DP<4>")
	)
	(segment
		(start 172.34916 -236.242606)
		(end 172.077888 -236.242606)
		(width 0.18288)
		(layer "In2.Cu")
		(net "M_F_CPU1_SB_DQS_DP<4>")
	)
	(segment
		(start 138.237214 -240.177574)
		(end 138.222482 -240.168938)
		(width 0.088646)
		(layer "In2.Cu")
		(net "M_F_CPU1_SB_DQS_DP<4>")
	)
	(segment
		(start 159.58185 -236.47019)
		(end 158.018734 -236.47019)
		(width 0.18288)
		(layer "In2.Cu")
		(net "M_F_CPU1_SB_DQS_DP<4>")
	)
	(segment
		(start 139.172442 -240.17478)
		(end 139.162282 -240.168938)
		(width 0.088646)
		(layer "In2.Cu")
		(net "M_F_CPU1_SB_DQS_DP<4>")
	)
	(segment
		(start 169.483024 -235.83646)
		(end 169.483024 -235.852716)
		(width 0.16002)
		(layer "In2.Cu")
		(net "M_F_CPU1_SB_DQS_DP<4>")
	)
	(segment
		(start 137.297414 -240.177574)
		(end 137.288524 -240.172494)
		(width 0.088646)
		(layer "In2.Cu")
		(net "M_F_CPU1_SB_DQS_DP<4>")
	)
	(segment
		(start 159.795972 -236.700568)
		(end 159.795972 -236.684312)
		(width 0.16002)
		(layer "In2.Cu")
		(net "M_F_CPU1_SB_DQS_DP<4>")
	)
	(segment
		(start 163.588446 -235.163868)
		(end 163.560252 -235.192062)
		(width 0.16002)
		(layer "In2.Cu")
		(net "M_F_CPU1_SB_DQS_DP<4>")
	)
	(segment
		(start 171.734988 -236.100366)
		(end 171.248832 -235.61421)
		(width 0.18288)
		(layer "In2.Cu")
		(net "M_F_CPU1_SB_DQS_DP<4>")
	)
	(segment
		(start 139.18438 -240.182146)
		(end 139.18311 -240.181384)
		(width 0.088646)
		(layer "In2.Cu")
		(net "M_F_CPU1_SB_DQS_DP<4>")
	)
	(segment
		(start 171.248832 -235.61421)
		(end 169.705274 -235.61421)
		(width 0.18288)
		(layer "In2.Cu")
		(net "M_F_CPU1_SB_DQS_DP<4>")
	)
	(segment
		(start 175.675544 -236.873796)
		(end 175.249586 -236.873796)
		(width 0.18288)
		(layer "In2.Cu")
		(net "M_F_CPU1_SB_DQS_DP<4>")
	)
	(segment
		(start 159.978852 -236.867192)
		(end 159.950658 -236.838998)
		(width 0.16002)
		(layer "In2.Cu")
		(net "M_F_CPU1_SB_DQS_DP<4>")
	)
	(segment
		(start 163.560252 -235.192062)
		(end 163.246308 -235.506006)
		(width 0.18288)
		(layer "In2.Cu")
		(net "M_F_CPU1_SB_DQS_DP<4>")
	)
	(segment
		(start 139.186666 -240.18367)
		(end 139.185396 -240.182654)
		(width 0.088646)
		(layer "In2.Cu")
		(net "M_F_CPU1_SB_DQS_DP<4>")
	)
	(segment
		(start 137.109962 -239.853216)
		(end 137.109962 -239.837722)
		(width 0.088646)
		(layer "In2.Cu")
		(net "M_F_CPU1_SB_DQS_DP<4>")
	)
	(segment
		(start 159.795972 -236.684312)
		(end 159.767778 -236.656118)
		(width 0.16002)
		(layer "In2.Cu")
		(net "M_F_CPU1_SB_DQS_DP<4>")
	)
	(segment
		(start 139.297918 -240.266982)
		(end 139.29741 -240.26622)
		(width 0.088646)
		(layer "In2.Cu")
		(net "M_F_CPU1_SB_DQS_DP<4>")
	)
	(segment
		(start 156.65704 -237.216188)
		(end 153.405586 -240.467642)
		(width 0.18288)
		(layer "In2.Cu")
		(net "M_F_CPU1_SB_DQS_DP<4>")
	)
	(segment
		(start 135.811768 -239.363758)
		(end 135.486648 -239.498124)
		(width 0.088646)
		(layer "In2.Cu")
		(net "M_F_CPU1_SB_DQS_DP<4>")
	)
	(segment
		(start 174.270416 -236.296962)
		(end 173.30547 -236.296962)
		(width 0.18288)
		(layer "In2.Cu")
		(net "M_F_CPU1_SB_DQS_DP<4>")
	)
	(arc
		(start 136.262364 -239.363758)
		(mid 136.183072 -239.398075)
		(end 136.098026 -239.413288)
		(width 0.088646)
		(layer "In2.Cu")
		(net "M_F_CPU1_SB_DQS_DP<4>")
	)
	(arc
		(start 135.486648 -239.498124)
		(mid 135.451587 -239.511769)
		(end 135.418068 -239.528858)
		(width 0.088646)
		(layer "In2.Cu")
		(net "M_F_CPU1_SB_DQS_DP<4>")
	)
	(arc
		(start 136.098026 -239.413288)
		(mid 136.008607 -239.407964)
		(end 135.92302 -239.381538)
		(width 0.088646)
		(layer "In2.Cu")
		(net "M_F_CPU1_SB_DQS_DP<4>")
	)
	(arc
		(start 139.236196 -240.213388)
		(mid 139.236832 -240.214022)
		(end 139.237466 -240.214658)
		(width 0.088646)
		(layer "In2.Cu")
		(net "M_F_CPU1_SB_DQS_DP<4>")
	)
	(arc
		(start 138.222482 -240.168938)
		(mid 137.946041 -240.101772)
		(end 137.67181 -240.177574)
		(width 0.088646)
		(layer "In2.Cu")
		(net "M_F_CPU1_SB_DQS_DP<4>")
	)
	(arc
		(start 135.409178 -239.533938)
		(mid 135.293369 -239.645867)
		(end 135.235188 -239.796066)
		(width 0.088646)
		(layer "In2.Cu")
		(net "M_F_CPU1_SB_DQS_DP<4>")
	)
	(arc
		(start 137.67181 -240.177574)
		(mid 137.484612 -240.227717)
		(end 137.297414 -240.177574)
		(width 0.088646)
		(layer "In2.Cu")
		(net "M_F_CPU1_SB_DQS_DP<4>")
	)
	(arc
		(start 135.92302 -239.381538)
		(mid 135.90526 -239.373108)
		(end 135.887968 -239.363758)
		(width 0.088646)
		(layer "In2.Cu")
		(net "M_F_CPU1_SB_DQS_DP<4>")
	)
	(arc
		(start 138.61161 -240.177574)
		(mid 138.424412 -240.227717)
		(end 138.237214 -240.177574)
		(width 0.088646)
		(layer "In2.Cu")
		(net "M_F_CPU1_SB_DQS_DP<4>")
	)
	(arc
		(start 137.288524 -240.172494)
		(mid 137.15761 -240.036134)
		(end 137.109962 -239.853216)
		(width 0.088646)
		(layer "In2.Cu")
		(net "M_F_CPU1_SB_DQS_DP<4>")
	)
	(arc
		(start 139.162282 -240.168938)
		(mid 138.885841 -240.101772)
		(end 138.61161 -240.177574)
		(width 0.088646)
		(layer "In2.Cu")
		(net "M_F_CPU1_SB_DQS_DP<4>")
	)
	(arc
		(start 139.29741 -240.26622)
		(mid 139.270953 -240.238399)
		(end 139.240006 -240.215674)
		(width 0.088646)
		(layer "In2.Cu")
		(net "M_F_CPU1_SB_DQS_DP<4>")
	)
	(arc
		(start 136.827768 -239.363758)
		(mid 136.553569 -239.287923)
		(end 136.277096 -239.355122)
		(width 0.088646)
		(layer "In2.Cu")
		(net "M_F_CPU1_SB_DQS_DP<4>")
	)
	(arc
		(start 137.109962 -239.837722)
		(mid 137.030592 -239.563988)
		(end 136.827768 -239.363758)
		(width 0.088646)
		(layer "In2.Cu")
		(net "M_F_CPU1_SB_DQS_DP<4>")
	)
	(segment
		(start 174.490126 -200.716642)
		(end 174.730664 -200.476104)
		(width 0.20066)
		(layer "F.Cu")
		(net "M_F_CPU1_SB_DQS_DP<3>")
	)
	(segment
		(start 179.011326 -201.147934)
		(end 179.334668 -201.147934)
		(width 0.20066)
		(layer "F.Cu")
		(net "M_F_CPU1_SB_DQS_DP<3>")
	)
	(segment
		(start 173.900846 -200.716642)
		(end 174.490126 -200.716642)
		(width 0.20066)
		(layer "F.Cu")
		(net "M_F_CPU1_SB_DQS_DP<3>")
	)
	(segment
		(start 176.8221 -201.141838)
		(end 176.848008 -201.141838)
		(width 0.101854)
		(layer "F.Cu")
		(net "M_F_CPU1_SB_DQS_DP<3>")
	)
	(segment
		(start 130.436112 -228.1809)
		(end 130.436366 -228.180646)
		(width 0.20066)
		(layer "F.Cu")
		(net "M_F_CPU1_SB_DQS_DP<3>")
	)
	(segment
		(start 179.334668 -201.147934)
		(end 179.637182 -200.84542)
		(width 0.20066)
		(layer "F.Cu")
		(net "M_F_CPU1_SB_DQS_DP<3>")
	)
	(segment
		(start 180.61432 -200.434956)
		(end 180.896006 -200.716642)
		(width 0.20066)
		(layer "F.Cu")
		(net "M_F_CPU1_SB_DQS_DP<3>")
	)
	(segment
		(start 176.431448 -200.890632)
		(end 176.682654 -201.141838)
		(width 0.20066)
		(layer "F.Cu")
		(net "M_F_CPU1_SB_DQS_DP<3>")
	)
	(segment
		(start 180.418232 -200.434956)
		(end 180.61432 -200.434956)
		(width 0.20066)
		(layer "F.Cu")
		(net "M_F_CPU1_SB_DQS_DP<3>")
	)
	(segment
		(start 176.682654 -201.141838)
		(end 176.8221 -201.141838)
		(width 0.20066)
		(layer "F.Cu")
		(net "M_F_CPU1_SB_DQS_DP<3>")
	)
	(segment
		(start 174.730664 -200.476104)
		(end 175.33112 -200.476104)
		(width 0.20066)
		(layer "F.Cu")
		(net "M_F_CPU1_SB_DQS_DP<3>")
	)
	(segment
		(start 175.33112 -200.476104)
		(end 175.745648 -200.890632)
		(width 0.20066)
		(layer "F.Cu")
		(net "M_F_CPU1_SB_DQS_DP<3>")
	)
	(segment
		(start 175.745648 -200.890632)
		(end 176.431448 -200.890632)
		(width 0.20066)
		(layer "F.Cu")
		(net "M_F_CPU1_SB_DQS_DP<3>")
	)
	(segment
		(start 179.637182 -200.84542)
		(end 180.007768 -200.84542)
		(width 0.20066)
		(layer "F.Cu")
		(net "M_F_CPU1_SB_DQS_DP<3>")
	)
	(segment
		(start 179.00523 -201.141838)
		(end 179.011326 -201.147934)
		(width 0.1016)
		(layer "F.Cu")
		(net "M_F_CPU1_SB_DQS_DP<3>")
	)
	(segment
		(start 180.007768 -200.84542)
		(end 180.418232 -200.434956)
		(width 0.20066)
		(layer "F.Cu")
		(net "M_F_CPU1_SB_DQS_DP<3>")
	)
	(segment
		(start 176.848008 -201.141838)
		(end 179.00523 -201.141838)
		(width 0.1016)
		(layer "F.Cu")
		(net "M_F_CPU1_SB_DQS_DP<3>")
	)
	(segment
		(start 130.436366 -228.180646)
		(end 130.436366 -227.64496)
		(width 0.20066)
		(layer "F.Cu")
		(net "M_F_CPU1_SB_DQS_DP<3>")
	)
	(segment
		(start 172.795946 -200.716642)
		(end 173.900846 -200.716642)
		(width 0.20066)
		(layer "F.Cu")
		(net "M_F_CPU1_SB_DQS_DP<3>")
	)
	(segment
		(start 180.896006 -200.716642)
		(end 181.444646 -200.716642)
		(width 0.20066)
		(layer "F.Cu")
		(net "M_F_CPU1_SB_DQS_DP<3>")
	)
	(segment
		(start 133.538468 -226.506786)
		(end 133.537706 -226.507294)
		(width 0.088646)
		(layer "In4.Cu")
		(net "M_F_CPU1_SB_DQS_DP<3>")
	)
	(segment
		(start 170.706796 -199.971914)
		(end 170.582336 -200.096374)
		(width 0.18288)
		(layer "In4.Cu")
		(net "M_F_CPU1_SB_DQS_DP<3>")
	)
	(segment
		(start 139.673584 -220.684344)
		(end 139.09167 -220.684344)
		(width 0.088646)
		(layer "In4.Cu")
		(net "M_F_CPU1_SB_DQS_DP<3>")
	)
	(segment
		(start 160.826196 -199.812402)
		(end 157.214316 -199.812402)
		(width 0.18288)
		(layer "In4.Cu")
		(net "M_F_CPU1_SB_DQS_DP<3>")
	)
	(segment
		(start 131.578096 -227.329238)
		(end 131.563364 -227.320602)
		(width 0.088646)
		(layer "In4.Cu")
		(net "M_F_CPU1_SB_DQS_DP<3>")
	)
	(segment
		(start 134.007606 -224.065592)
		(end 133.999478 -224.070164)
		(width 0.088646)
		(layer "In4.Cu")
		(net "M_F_CPU1_SB_DQS_DP<3>")
	)
	(segment
		(start 133.537706 -226.507294)
		(end 133.529578 -226.511866)
		(width 0.088646)
		(layer "In4.Cu")
		(net "M_F_CPU1_SB_DQS_DP<3>")
	)
	(segment
		(start 167.149272 -199.971914)
		(end 166.580058 -199.4027)
		(width 0.18288)
		(layer "In4.Cu")
		(net "M_F_CPU1_SB_DQS_DP<3>")
	)
	(segment
		(start 135.418068 -221.623382)
		(end 135.409178 -221.628462)
		(width 0.088646)
		(layer "In4.Cu")
		(net "M_F_CPU1_SB_DQS_DP<3>")
	)
	(segment
		(start 134.760716 -222.761556)
		(end 134.760716 -222.780098)
		(width 0.088646)
		(layer "In4.Cu")
		(net "M_F_CPU1_SB_DQS_DP<3>")
	)
	(segment
		(start 172.504862 -200.425558)
		(end 171.982638 -200.425558)
		(width 0.18288)
		(layer "In4.Cu")
		(net "M_F_CPU1_SB_DQS_DP<3>")
	)
	(segment
		(start 134.478268 -223.251268)
		(end 134.469378 -223.256348)
		(width 0.088646)
		(layer "In4.Cu")
		(net "M_F_CPU1_SB_DQS_DP<3>")
	)
	(segment
		(start 133.999478 -224.70872)
		(end 134.008368 -224.7138)
		(width 0.088646)
		(layer "In4.Cu")
		(net "M_F_CPU1_SB_DQS_DP<3>")
	)
	(segment
		(start 134.290816 -223.575626)
		(end 134.290816 -223.585532)
		(width 0.088646)
		(layer "In4.Cu")
		(net "M_F_CPU1_SB_DQS_DP<3>")
	)
	(segment
		(start 136.36371 -221.619826)
		(end 136.358376 -221.622874)
		(width 0.088646)
		(layer "In4.Cu")
		(net "M_F_CPU1_SB_DQS_DP<3>")
	)
	(segment
		(start 136.357614 -221.623382)
		(end 136.3472 -221.629478)
		(width 0.088646)
		(layer "In4.Cu")
		(net "M_F_CPU1_SB_DQS_DP<3>")
	)
	(segment
		(start 171.528994 -199.971914)
		(end 170.706796 -199.971914)
		(width 0.18288)
		(layer "In4.Cu")
		(net "M_F_CPU1_SB_DQS_DP<3>")
	)
	(segment
		(start 152.293066 -205.988666)
		(end 150.245572 -210.931506)
		(width 0.18288)
		(layer "In4.Cu")
		(net "M_F_CPU1_SB_DQS_DP<3>")
	)
	(segment
		(start 140.43279 -220.744034)
		(end 139.756642 -220.744034)
		(width 0.18288)
		(layer "In4.Cu")
		(net "M_F_CPU1_SB_DQS_DP<3>")
	)
	(segment
		(start 164.7571 -199.961246)
		(end 164.20973 -199.413876)
		(width 0.18288)
		(layer "In4.Cu")
		(net "M_F_CPU1_SB_DQS_DP<3>")
	)
	(segment
		(start 130.249168 -227.320602)
		(end 130.240278 -227.325682)
		(width 0.088646)
		(layer "In4.Cu")
		(net "M_F_CPU1_SB_DQS_DP<3>")
	)
	(segment
		(start 171.982638 -200.425558)
		(end 171.528994 -199.971914)
		(width 0.18288)
		(layer "In4.Cu")
		(net "M_F_CPU1_SB_DQS_DP<3>")
	)
	(segment
		(start 169.911776 -199.971914)
		(end 167.149272 -199.971914)
		(width 0.18288)
		(layer "In4.Cu")
		(net "M_F_CPU1_SB_DQS_DP<3>")
	)
	(segment
		(start 133.820916 -226.017328)
		(end 133.820916 -226.027234)
		(width 0.088646)
		(layer "In4.Cu")
		(net "M_F_CPU1_SB_DQS_DP<3>")
	)
	(segment
		(start 139.017248 -220.758766)
		(end 138.894566 -220.758766)
		(width 0.088646)
		(layer "In4.Cu")
		(net "M_F_CPU1_SB_DQS_DP<3>")
	)
	(segment
		(start 157.214316 -199.812402)
		(end 154.820366 -202.206352)
		(width 0.18288)
		(layer "In4.Cu")
		(net "M_F_CPU1_SB_DQS_DP<3>")
	)
	(segment
		(start 166.580058 -199.4027)
		(end 166.185088 -199.4027)
		(width 0.18288)
		(layer "In4.Cu")
		(net "M_F_CPU1_SB_DQS_DP<3>")
	)
	(segment
		(start 136.358376 -221.622874)
		(end 136.357614 -221.623382)
		(width 0.088646)
		(layer "In4.Cu")
		(net "M_F_CPU1_SB_DQS_DP<3>")
	)
	(segment
		(start 134.008368 -225.69297)
		(end 134.007606 -225.693478)
		(width 0.088646)
		(layer "In4.Cu")
		(net "M_F_CPU1_SB_DQS_DP<3>")
	)
	(segment
		(start 134.008368 -224.065084)
		(end 134.007606 -224.065592)
		(width 0.088646)
		(layer "In4.Cu")
		(net "M_F_CPU1_SB_DQS_DP<3>")
	)
	(segment
		(start 165.626542 -199.961246)
		(end 164.7571 -199.961246)
		(width 0.18288)
		(layer "In4.Cu")
		(net "M_F_CPU1_SB_DQS_DP<3>")
	)
	(segment
		(start 133.074664 -227.317046)
		(end 133.068568 -227.320602)
		(width 0.088646)
		(layer "In4.Cu")
		(net "M_F_CPU1_SB_DQS_DP<3>")
	)
	(segment
		(start 139.756642 -220.744034)
		(end 139.733274 -220.744034)
		(width 0.088646)
		(layer "In4.Cu")
		(net "M_F_CPU1_SB_DQS_DP<3>")
	)
	(segment
		(start 136.827768 -220.809566)
		(end 136.818878 -220.814646)
		(width 0.088646)
		(layer "In4.Cu")
		(net "M_F_CPU1_SB_DQS_DP<3>")
	)
	(segment
		(start 134.948168 -222.437198)
		(end 134.939278 -222.442278)
		(width 0.088646)
		(layer "In4.Cu")
		(net "M_F_CPU1_SB_DQS_DP<3>")
	)
	(segment
		(start 161.224722 -199.413876)
		(end 160.826196 -199.812402)
		(width 0.18288)
		(layer "In4.Cu")
		(net "M_F_CPU1_SB_DQS_DP<3>")
	)
	(segment
		(start 154.820366 -202.206352)
		(end 152.293066 -205.988666)
		(width 0.18288)
		(layer "In4.Cu")
		(net "M_F_CPU1_SB_DQS_DP<3>")
	)
	(segment
		(start 134.007606 -225.693478)
		(end 133.999478 -225.69805)
		(width 0.088646)
		(layer "In4.Cu")
		(net "M_F_CPU1_SB_DQS_DP<3>")
	)
	(segment
		(start 139.09167 -220.684344)
		(end 139.017248 -220.758766)
		(width 0.088646)
		(layer "In4.Cu")
		(net "M_F_CPU1_SB_DQS_DP<3>")
	)
	(segment
		(start 134.954264 -222.433642)
		(end 134.948168 -222.437198)
		(width 0.088646)
		(layer "In4.Cu")
		(net "M_F_CPU1_SB_DQS_DP<3>")
	)
	(segment
		(start 166.185088 -199.4027)
		(end 165.626542 -199.961246)
		(width 0.18288)
		(layer "In4.Cu")
		(net "M_F_CPU1_SB_DQS_DP<3>")
	)
	(segment
		(start 134.290816 -225.193352)
		(end 134.290816 -225.2218)
		(width 0.088646)
		(layer "In4.Cu")
		(net "M_F_CPU1_SB_DQS_DP<3>")
	)
	(segment
		(start 130.066288 -227.587556)
		(end 130.123692 -227.64496)
		(width 0.088646)
		(layer "In4.Cu")
		(net "M_F_CPU1_SB_DQS_DP<3>")
	)
	(segment
		(start 170.036236 -200.096374)
		(end 169.911776 -199.971914)
		(width 0.18288)
		(layer "In4.Cu")
		(net "M_F_CPU1_SB_DQS_DP<3>")
	)
	(segment
		(start 150.245572 -210.931506)
		(end 140.43279 -220.744034)
		(width 0.18288)
		(layer "In4.Cu")
		(net "M_F_CPU1_SB_DQS_DP<3>")
	)
	(segment
		(start 132.517896 -227.329238)
		(end 132.503164 -227.320602)
		(width 0.088646)
		(layer "In4.Cu")
		(net "M_F_CPU1_SB_DQS_DP<3>")
	)
	(segment
		(start 170.582336 -200.096374)
		(end 170.036236 -200.096374)
		(width 0.18288)
		(layer "In4.Cu")
		(net "M_F_CPU1_SB_DQS_DP<3>")
	)
	(segment
		(start 130.123692 -227.64496)
		(end 130.436366 -227.64496)
		(width 0.088646)
		(layer "In4.Cu")
		(net "M_F_CPU1_SB_DQS_DP<3>")
	)
	(segment
		(start 139.733274 -220.744034)
		(end 139.673584 -220.684344)
		(width 0.088646)
		(layer "In4.Cu")
		(net "M_F_CPU1_SB_DQS_DP<3>")
	)
	(segment
		(start 172.795946 -200.716642)
		(end 172.504862 -200.425558)
		(width 0.18288)
		(layer "In4.Cu")
		(net "M_F_CPU1_SB_DQS_DP<3>")
	)
	(segment
		(start 164.20973 -199.413876)
		(end 161.224722 -199.413876)
		(width 0.18288)
		(layer "In4.Cu")
		(net "M_F_CPU1_SB_DQS_DP<3>")
	)
	(arc
		(start 134.290816 -223.585532)
		(mid 134.212705 -223.862481)
		(end 134.008368 -224.065084)
		(width 0.088646)
		(layer "In4.Cu")
		(net "M_F_CPU1_SB_DQS_DP<3>")
	)
	(arc
		(start 131.188968 -227.320602)
		(mid 130.906266 -227.396378)
		(end 130.623564 -227.320602)
		(width 0.088646)
		(layer "In4.Cu")
		(net "M_F_CPU1_SB_DQS_DP<3>")
	)
	(arc
		(start 138.894566 -220.758766)
		(mid 138.797627 -220.771856)
		(end 138.707368 -220.809566)
		(width 0.088646)
		(layer "In4.Cu")
		(net "M_F_CPU1_SB_DQS_DP<3>")
	)
	(arc
		(start 137.202164 -220.809566)
		(mid 137.014966 -220.759423)
		(end 136.827768 -220.809566)
		(width 0.088646)
		(layer "In4.Cu")
		(net "M_F_CPU1_SB_DQS_DP<3>")
	)
	(arc
		(start 137.767568 -220.809566)
		(mid 137.484866 -220.885308)
		(end 137.202164 -220.809566)
		(width 0.088646)
		(layer "In4.Cu")
		(net "M_F_CPU1_SB_DQS_DP<3>")
	)
	(arc
		(start 134.469378 -223.256348)
		(mid 134.338464 -223.392708)
		(end 134.290816 -223.575626)
		(width 0.088646)
		(layer "In4.Cu")
		(net "M_F_CPU1_SB_DQS_DP<3>")
	)
	(arc
		(start 133.999478 -225.69805)
		(mid 133.868564 -225.83441)
		(end 133.820916 -226.017328)
		(width 0.088646)
		(layer "In4.Cu")
		(net "M_F_CPU1_SB_DQS_DP<3>")
	)
	(arc
		(start 136.818878 -220.814646)
		(mid 136.687964 -220.951006)
		(end 136.640316 -221.133924)
		(width 0.088646)
		(layer "In4.Cu")
		(net "M_F_CPU1_SB_DQS_DP<3>")
	)
	(arc
		(start 134.008368 -224.7138)
		(mid 134.212703 -224.916405)
		(end 134.290816 -225.193352)
		(width 0.088646)
		(layer "In4.Cu")
		(net "M_F_CPU1_SB_DQS_DP<3>")
	)
	(arc
		(start 133.820916 -226.027234)
		(mid 133.742805 -226.304183)
		(end 133.538468 -226.506786)
		(width 0.088646)
		(layer "In4.Cu")
		(net "M_F_CPU1_SB_DQS_DP<3>")
	)
	(arc
		(start 133.068568 -227.320602)
		(mid 132.794369 -227.396437)
		(end 132.517896 -227.329238)
		(width 0.088646)
		(layer "In4.Cu")
		(net "M_F_CPU1_SB_DQS_DP<3>")
	)
	(arc
		(start 134.939278 -222.442278)
		(mid 134.808364 -222.578638)
		(end 134.760716 -222.761556)
		(width 0.088646)
		(layer "In4.Cu")
		(net "M_F_CPU1_SB_DQS_DP<3>")
	)
	(arc
		(start 135.409178 -221.628462)
		(mid 135.278264 -221.764822)
		(end 135.230616 -221.94774)
		(width 0.088646)
		(layer "In4.Cu")
		(net "M_F_CPU1_SB_DQS_DP<3>")
	)
	(arc
		(start 136.3472 -221.629478)
		(mid 136.069022 -221.699201)
		(end 135.792464 -221.623382)
		(width 0.088646)
		(layer "In4.Cu")
		(net "M_F_CPU1_SB_DQS_DP<3>")
	)
	(arc
		(start 136.640316 -221.133924)
		(mid 136.566325 -221.41349)
		(end 136.36371 -221.619826)
		(width 0.088646)
		(layer "In4.Cu")
		(net "M_F_CPU1_SB_DQS_DP<3>")
	)
	(arc
		(start 138.141964 -220.809566)
		(mid 137.954766 -220.759423)
		(end 137.767568 -220.809566)
		(width 0.088646)
		(layer "In4.Cu")
		(net "M_F_CPU1_SB_DQS_DP<3>")
	)
	(arc
		(start 132.128768 -227.320602)
		(mid 131.854569 -227.396437)
		(end 131.578096 -227.329238)
		(width 0.088646)
		(layer "In4.Cu")
		(net "M_F_CPU1_SB_DQS_DP<3>")
	)
	(arc
		(start 135.792464 -221.623382)
		(mid 135.605266 -221.573239)
		(end 135.418068 -221.623382)
		(width 0.088646)
		(layer "In4.Cu")
		(net "M_F_CPU1_SB_DQS_DP<3>")
	)
	(arc
		(start 130.623564 -227.320602)
		(mid 130.436366 -227.270459)
		(end 130.249168 -227.320602)
		(width 0.088646)
		(layer "In4.Cu")
		(net "M_F_CPU1_SB_DQS_DP<3>")
	)
	(arc
		(start 130.240278 -227.325682)
		(mid 130.148779 -227.404981)
		(end 130.08737 -227.509324)
		(width 0.088646)
		(layer "In4.Cu")
		(net "M_F_CPU1_SB_DQS_DP<3>")
	)
	(arc
		(start 133.999478 -224.070164)
		(mid 133.820881 -224.389442)
		(end 133.999478 -224.70872)
		(width 0.088646)
		(layer "In4.Cu")
		(net "M_F_CPU1_SB_DQS_DP<3>")
	)
	(arc
		(start 133.529578 -226.511866)
		(mid 133.398664 -226.648226)
		(end 133.351016 -226.831144)
		(width 0.088646)
		(layer "In4.Cu")
		(net "M_F_CPU1_SB_DQS_DP<3>")
	)
	(arc
		(start 130.08737 -227.509324)
		(mid 130.074702 -227.547867)
		(end 130.066288 -227.587556)
		(width 0.088646)
		(layer "In4.Cu")
		(net "M_F_CPU1_SB_DQS_DP<3>")
	)
	(arc
		(start 134.760716 -222.780098)
		(mid 134.680554 -223.052287)
		(end 134.478268 -223.251268)
		(width 0.088646)
		(layer "In4.Cu")
		(net "M_F_CPU1_SB_DQS_DP<3>")
	)
	(arc
		(start 132.503164 -227.320602)
		(mid 132.315966 -227.270459)
		(end 132.128768 -227.320602)
		(width 0.088646)
		(layer "In4.Cu")
		(net "M_F_CPU1_SB_DQS_DP<3>")
	)
	(arc
		(start 135.230616 -221.94774)
		(mid 135.1567 -222.227242)
		(end 134.954264 -222.433642)
		(width 0.088646)
		(layer "In4.Cu")
		(net "M_F_CPU1_SB_DQS_DP<3>")
	)
	(arc
		(start 133.351016 -226.831144)
		(mid 133.2771 -227.110646)
		(end 133.074664 -227.317046)
		(width 0.088646)
		(layer "In4.Cu")
		(net "M_F_CPU1_SB_DQS_DP<3>")
	)
	(arc
		(start 131.563364 -227.320602)
		(mid 131.376166 -227.270459)
		(end 131.188968 -227.320602)
		(width 0.088646)
		(layer "In4.Cu")
		(net "M_F_CPU1_SB_DQS_DP<3>")
	)
	(arc
		(start 134.290816 -225.2218)
		(mid 134.210654 -225.493989)
		(end 134.008368 -225.69297)
		(width 0.088646)
		(layer "In4.Cu")
		(net "M_F_CPU1_SB_DQS_DP<3>")
	)
	(arc
		(start 138.707368 -220.809566)
		(mid 138.424666 -220.885308)
		(end 138.141964 -220.809566)
		(width 0.088646)
		(layer "In4.Cu")
		(net "M_F_CPU1_SB_DQS_DP<3>")
	)
	(segment
		(start 176.682654 -210.491832)
		(end 176.8221 -210.491832)
		(width 0.20066)
		(layer "F.Cu")
		(net "M_F_CPU1_SB_DQS_DP<2>")
	)
	(segment
		(start 175.33112 -209.826098)
		(end 175.745648 -210.240626)
		(width 0.20066)
		(layer "F.Cu")
		(net "M_F_CPU1_SB_DQS_DP<2>")
	)
	(segment
		(start 179.334668 -210.497928)
		(end 179.637182 -210.195414)
		(width 0.20066)
		(layer "F.Cu")
		(net "M_F_CPU1_SB_DQS_DP<2>")
	)
	(segment
		(start 180.418232 -209.78495)
		(end 180.61432 -209.78495)
		(width 0.20066)
		(layer "F.Cu")
		(net "M_F_CPU1_SB_DQS_DP<2>")
	)
	(segment
		(start 174.490126 -210.066636)
		(end 174.730664 -209.826098)
		(width 0.20066)
		(layer "F.Cu")
		(net "M_F_CPU1_SB_DQS_DP<2>")
	)
	(segment
		(start 176.848008 -210.491832)
		(end 179.00523 -210.491832)
		(width 0.1016)
		(layer "F.Cu")
		(net "M_F_CPU1_SB_DQS_DP<2>")
	)
	(segment
		(start 136.075166 -223.297496)
		(end 136.075166 -222.761556)
		(width 0.20066)
		(layer "F.Cu")
		(net "M_F_CPU1_SB_DQS_DP<2>")
	)
	(segment
		(start 180.61432 -209.78495)
		(end 180.896006 -210.066636)
		(width 0.20066)
		(layer "F.Cu")
		(net "M_F_CPU1_SB_DQS_DP<2>")
	)
	(segment
		(start 179.637182 -210.195414)
		(end 180.007768 -210.195414)
		(width 0.20066)
		(layer "F.Cu")
		(net "M_F_CPU1_SB_DQS_DP<2>")
	)
	(segment
		(start 179.00523 -210.491832)
		(end 179.011326 -210.497928)
		(width 0.1016)
		(layer "F.Cu")
		(net "M_F_CPU1_SB_DQS_DP<2>")
	)
	(segment
		(start 176.431448 -210.240626)
		(end 176.682654 -210.491832)
		(width 0.20066)
		(layer "F.Cu")
		(net "M_F_CPU1_SB_DQS_DP<2>")
	)
	(segment
		(start 179.011326 -210.497928)
		(end 179.334668 -210.497928)
		(width 0.20066)
		(layer "F.Cu")
		(net "M_F_CPU1_SB_DQS_DP<2>")
	)
	(segment
		(start 174.730664 -209.826098)
		(end 175.33112 -209.826098)
		(width 0.20066)
		(layer "F.Cu")
		(net "M_F_CPU1_SB_DQS_DP<2>")
	)
	(segment
		(start 173.900846 -210.066636)
		(end 174.490126 -210.066636)
		(width 0.20066)
		(layer "F.Cu")
		(net "M_F_CPU1_SB_DQS_DP<2>")
	)
	(segment
		(start 176.8221 -210.491832)
		(end 176.848008 -210.491832)
		(width 0.101854)
		(layer "F.Cu")
		(net "M_F_CPU1_SB_DQS_DP<2>")
	)
	(segment
		(start 180.007768 -210.195414)
		(end 180.418232 -209.78495)
		(width 0.20066)
		(layer "F.Cu")
		(net "M_F_CPU1_SB_DQS_DP<2>")
	)
	(segment
		(start 172.795946 -210.066636)
		(end 173.900846 -210.066636)
		(width 0.20066)
		(layer "F.Cu")
		(net "M_F_CPU1_SB_DQS_DP<2>")
	)
	(segment
		(start 180.896006 -210.066636)
		(end 181.444646 -210.066636)
		(width 0.20066)
		(layer "F.Cu")
		(net "M_F_CPU1_SB_DQS_DP<2>")
	)
	(segment
		(start 175.745648 -210.240626)
		(end 176.431448 -210.240626)
		(width 0.20066)
		(layer "F.Cu")
		(net "M_F_CPU1_SB_DQS_DP<2>")
	)
	(segment
		(start 163.375848 -207.673194)
		(end 162.286442 -207.673194)
		(width 0.18288)
		(layer "In2.Cu")
		(net "M_F_CPU1_SB_DQS_DP<2>")
	)
	(segment
		(start 166.785798 -208.523078)
		(end 165.730174 -208.523078)
		(width 0.18288)
		(layer "In2.Cu")
		(net "M_F_CPU1_SB_DQS_DP<2>")
	)
	(segment
		(start 169.315892 -209.629756)
		(end 169.287698 -209.601562)
		(width 0.16002)
		(layer "In2.Cu")
		(net "M_F_CPU1_SB_DQS_DP<2>")
	)
	(segment
		(start 158.355538 -206.84363)
		(end 158.1023 -207.096868)
		(width 0.18288)
		(layer "In2.Cu")
		(net "M_F_CPU1_SB_DQS_DP<2>")
	)
	(segment
		(start 171.323762 -209.99069)
		(end 169.676826 -209.99069)
		(width 0.18288)
		(layer "In2.Cu")
		(net "M_F_CPU1_SB_DQS_DP<2>")
	)
	(segment
		(start 136.742424 -223.257364)
		(end 136.73201 -223.251268)
		(width 0.088646)
		(layer "In2.Cu")
		(net "M_F_CPU1_SB_DQS_DP<2>")
	)
	(segment
		(start 161.991294 -207.968342)
		(end 161.55924 -207.968342)
		(width 0.18288)
		(layer "In2.Cu")
		(net "M_F_CPU1_SB_DQS_DP<2>")
	)
	(segment
		(start 167.057578 -208.77911)
		(end 167.04183 -208.77911)
		(width 0.16002)
		(layer "In2.Cu")
		(net "M_F_CPU1_SB_DQS_DP<2>")
	)
	(segment
		(start 138.626596 -223.259904)
		(end 138.611864 -223.251268)
		(width 0.088646)
		(layer "In2.Cu")
		(net "M_F_CPU1_SB_DQS_DP<2>")
	)
	(segment
		(start 157.891226 -207.307942)
		(end 157.763718 -207.43545)
		(width 0.18288)
		(layer "In2.Cu")
		(net "M_F_CPU1_SB_DQS_DP<2>")
	)
	(segment
		(start 140.688314 -222.376238)
		(end 140.624814 -222.414338)
		(width 0.088646)
		(layer "In2.Cu")
		(net "M_F_CPU1_SB_DQS_DP<2>")
	)
	(segment
		(start 140.624814 -222.414338)
		(end 140.62329 -222.415354)
		(width 0.088646)
		(layer "In2.Cu")
		(net "M_F_CPU1_SB_DQS_DP<2>")
	)
	(segment
		(start 140.619226 -222.417894)
		(end 140.615162 -222.42018)
		(width 0.088646)
		(layer "In2.Cu")
		(net "M_F_CPU1_SB_DQS_DP<2>")
	)
	(segment
		(start 140.606018 -222.425514)
		(end 140.582142 -222.439738)
		(width 0.088646)
		(layer "In2.Cu")
		(net "M_F_CPU1_SB_DQS_DP<2>")
	)
	(segment
		(start 172.795946 -210.066636)
		(end 172.541692 -209.812382)
		(width 0.18288)
		(layer "In2.Cu")
		(net "M_F_CPU1_SB_DQS_DP<2>")
	)
	(segment
		(start 167.196516 -208.933796)
		(end 167.196516 -208.918048)
		(width 0.16002)
		(layer "In2.Cu")
		(net "M_F_CPU1_SB_DQS_DP<2>")
	)
	(segment
		(start 167.47363 -209.21091)
		(end 167.22471 -208.96199)
		(width 0.18288)
		(layer "In2.Cu")
		(net "M_F_CPU1_SB_DQS_DP<2>")
	)
	(segment
		(start 169.332148 -209.629756)
		(end 169.315892 -209.629756)
		(width 0.16002)
		(layer "In2.Cu")
		(net "M_F_CPU1_SB_DQS_DP<2>")
	)
	(segment
		(start 157.91942 -207.264)
		(end 157.91942 -207.279748)
		(width 0.16002)
		(layer "In2.Cu")
		(net "M_F_CPU1_SB_DQS_DP<2>")
	)
	(segment
		(start 165.435026 -208.818226)
		(end 165.002972 -208.818226)
		(width 0.18288)
		(layer "In2.Cu")
		(net "M_F_CPU1_SB_DQS_DP<2>")
	)
	(segment
		(start 140.62329 -222.415354)
		(end 140.622274 -222.416116)
		(width 0.088646)
		(layer "In2.Cu")
		(net "M_F_CPU1_SB_DQS_DP<2>")
	)
	(segment
		(start 167.013636 -208.750916)
		(end 166.785798 -208.523078)
		(width 0.18288)
		(layer "In2.Cu")
		(net "M_F_CPU1_SB_DQS_DP<2>")
	)
	(segment
		(start 162.286442 -207.673194)
		(end 161.991294 -207.968342)
		(width 0.18288)
		(layer "In2.Cu")
		(net "M_F_CPU1_SB_DQS_DP<2>")
	)
	(segment
		(start 171.698666 -209.615786)
		(end 171.323762 -209.99069)
		(width 0.18288)
		(layer "In2.Cu")
		(net "M_F_CPU1_SB_DQS_DP<2>")
	)
	(segment
		(start 140.615162 -222.42018)
		(end 140.614146 -222.420688)
		(width 0.088646)
		(layer "In2.Cu")
		(net "M_F_CPU1_SB_DQS_DP<2>")
	)
	(segment
		(start 136.38784 -222.761556)
		(end 136.075166 -222.761556)
		(width 0.088646)
		(layer "In2.Cu")
		(net "M_F_CPU1_SB_DQS_DP<2>")
	)
	(segment
		(start 140.622274 -222.416116)
		(end 140.620242 -222.417386)
		(width 0.088646)
		(layer "In2.Cu")
		(net "M_F_CPU1_SB_DQS_DP<2>")
	)
	(segment
		(start 136.452864 -222.82658)
		(end 136.38784 -222.761556)
		(width 0.088646)
		(layer "In2.Cu")
		(net "M_F_CPU1_SB_DQS_DP<2>")
	)
	(segment
		(start 140.399262 -222.761556)
		(end 140.399262 -222.783654)
		(width 0.088646)
		(layer "In2.Cu")
		(net "M_F_CPU1_SB_DQS_DP<2>")
	)
	(segment
		(start 140.399008 -222.761556)
		(end 140.399262 -222.761556)
		(width 0.088646)
		(layer "In2.Cu")
		(net "M_F_CPU1_SB_DQS_DP<2>")
	)
	(segment
		(start 157.91942 -207.279748)
		(end 157.891226 -207.307942)
		(width 0.16002)
		(layer "In2.Cu")
		(net "M_F_CPU1_SB_DQS_DP<2>")
	)
	(segment
		(start 141.76375 -222.209868)
		(end 141.251432 -222.209868)
		(width 0.088646)
		(layer "In2.Cu")
		(net "M_F_CPU1_SB_DQS_DP<2>")
	)
	(segment
		(start 164.232844 -208.53019)
		(end 163.375848 -207.673194)
		(width 0.18288)
		(layer "In2.Cu")
		(net "M_F_CPU1_SB_DQS_DP<2>")
	)
	(segment
		(start 141.251432 -222.209868)
		(end 140.930884 -222.34271)
		(width 0.088646)
		(layer "In2.Cu")
		(net "M_F_CPU1_SB_DQS_DP<2>")
	)
	(segment
		(start 167.196516 -208.918048)
		(end 167.057578 -208.77911)
		(width 0.16002)
		(layer "In2.Cu")
		(net "M_F_CPU1_SB_DQS_DP<2>")
	)
	(segment
		(start 169.287698 -209.601562)
		(end 168.897046 -209.21091)
		(width 0.18288)
		(layer "In2.Cu")
		(net "M_F_CPU1_SB_DQS_DP<2>")
	)
	(segment
		(start 165.730174 -208.523078)
		(end 165.435026 -208.818226)
		(width 0.18288)
		(layer "In2.Cu")
		(net "M_F_CPU1_SB_DQS_DP<2>")
	)
	(segment
		(start 168.897046 -209.21091)
		(end 167.47363 -209.21091)
		(width 0.18288)
		(layer "In2.Cu")
		(net "M_F_CPU1_SB_DQS_DP<2>")
	)
	(segment
		(start 155.45562 -209.877152)
		(end 154.64917 -209.877152)
		(width 0.18288)
		(layer "In2.Cu")
		(net "M_F_CPU1_SB_DQS_DP<2>")
	)
	(segment
		(start 172.541692 -209.812382)
		(end 172.273214 -209.812382)
		(width 0.18288)
		(layer "In2.Cu")
		(net "M_F_CPU1_SB_DQS_DP<2>")
	)
	(segment
		(start 140.60678 -222.425006)
		(end 140.606018 -222.425514)
		(width 0.088646)
		(layer "In2.Cu")
		(net "M_F_CPU1_SB_DQS_DP<2>")
	)
	(segment
		(start 169.470578 -209.768186)
		(end 169.332148 -209.629756)
		(width 0.16002)
		(layer "In2.Cu")
		(net "M_F_CPU1_SB_DQS_DP<2>")
	)
	(segment
		(start 158.058358 -207.125062)
		(end 157.91942 -207.264)
		(width 0.16002)
		(layer "In2.Cu")
		(net "M_F_CPU1_SB_DQS_DP<2>")
	)
	(segment
		(start 161.55924 -207.968342)
		(end 161.300668 -207.70977)
		(width 0.18288)
		(layer "In2.Cu")
		(net "M_F_CPU1_SB_DQS_DP<2>")
	)
	(segment
		(start 157.763718 -207.569054)
		(end 155.45562 -209.877152)
		(width 0.18288)
		(layer "In2.Cu")
		(net "M_F_CPU1_SB_DQS_DP<2>")
	)
	(segment
		(start 140.620242 -222.417386)
		(end 140.619226 -222.417894)
		(width 0.088646)
		(layer "In2.Cu")
		(net "M_F_CPU1_SB_DQS_DP<2>")
	)
	(segment
		(start 169.498772 -209.812636)
		(end 169.470578 -209.784442)
		(width 0.16002)
		(layer "In2.Cu")
		(net "M_F_CPU1_SB_DQS_DP<2>")
	)
	(segment
		(start 172.076618 -209.615786)
		(end 171.698666 -209.615786)
		(width 0.18288)
		(layer "In2.Cu")
		(net "M_F_CPU1_SB_DQS_DP<2>")
	)
	(segment
		(start 154.64917 -209.877152)
		(end 142.256764 -222.269558)
		(width 0.18288)
		(layer "In2.Cu")
		(net "M_F_CPU1_SB_DQS_DP<2>")
	)
	(segment
		(start 140.92301 -222.34398)
		(end 140.688314 -222.376238)
		(width 0.088646)
		(layer "In2.Cu")
		(net "M_F_CPU1_SB_DQS_DP<2>")
	)
	(segment
		(start 140.614146 -222.420688)
		(end 140.60678 -222.425006)
		(width 0.088646)
		(layer "In2.Cu")
		(net "M_F_CPU1_SB_DQS_DP<2>")
	)
	(segment
		(start 160.162748 -207.70977)
		(end 159.296608 -206.84363)
		(width 0.18288)
		(layer "In2.Cu")
		(net "M_F_CPU1_SB_DQS_DP<2>")
	)
	(segment
		(start 140.930884 -222.34271)
		(end 140.92301 -222.34398)
		(width 0.088646)
		(layer "In2.Cu")
		(net "M_F_CPU1_SB_DQS_DP<2>")
	)
	(segment
		(start 158.1023 -207.096868)
		(end 158.074106 -207.125062)
		(width 0.16002)
		(layer "In2.Cu")
		(net "M_F_CPU1_SB_DQS_DP<2>")
	)
	(segment
		(start 139.566396 -223.259904)
		(end 139.551664 -223.251268)
		(width 0.088646)
		(layer "In2.Cu")
		(net "M_F_CPU1_SB_DQS_DP<2>")
	)
	(segment
		(start 142.256764 -222.269558)
		(end 141.82344 -222.269558)
		(width 0.18288)
		(layer "In2.Cu")
		(net "M_F_CPU1_SB_DQS_DP<2>")
	)
	(segment
		(start 169.470578 -209.784442)
		(end 169.470578 -209.768186)
		(width 0.16002)
		(layer "In2.Cu")
		(net "M_F_CPU1_SB_DQS_DP<2>")
	)
	(segment
		(start 158.074106 -207.125062)
		(end 158.058358 -207.125062)
		(width 0.16002)
		(layer "In2.Cu")
		(net "M_F_CPU1_SB_DQS_DP<2>")
	)
	(segment
		(start 172.273214 -209.812382)
		(end 172.076618 -209.615786)
		(width 0.18288)
		(layer "In2.Cu")
		(net "M_F_CPU1_SB_DQS_DP<2>")
	)
	(segment
		(start 167.04183 -208.77911)
		(end 167.013636 -208.750916)
		(width 0.16002)
		(layer "In2.Cu")
		(net "M_F_CPU1_SB_DQS_DP<2>")
	)
	(segment
		(start 141.82344 -222.269558)
		(end 141.76375 -222.209868)
		(width 0.088646)
		(layer "In2.Cu")
		(net "M_F_CPU1_SB_DQS_DP<2>")
	)
	(segment
		(start 165.002972 -208.818226)
		(end 164.714936 -208.53019)
		(width 0.18288)
		(layer "In2.Cu")
		(net "M_F_CPU1_SB_DQS_DP<2>")
	)
	(segment
		(start 169.676826 -209.99069)
		(end 169.498772 -209.812636)
		(width 0.18288)
		(layer "In2.Cu")
		(net "M_F_CPU1_SB_DQS_DP<2>")
	)
	(segment
		(start 167.22471 -208.96199)
		(end 167.196516 -208.933796)
		(width 0.16002)
		(layer "In2.Cu")
		(net "M_F_CPU1_SB_DQS_DP<2>")
	)
	(segment
		(start 157.763718 -207.43545)
		(end 157.763718 -207.569054)
		(width 0.18288)
		(layer "In2.Cu")
		(net "M_F_CPU1_SB_DQS_DP<2>")
	)
	(segment
		(start 159.296608 -206.84363)
		(end 158.355538 -206.84363)
		(width 0.18288)
		(layer "In2.Cu")
		(net "M_F_CPU1_SB_DQS_DP<2>")
	)
	(segment
		(start 161.300668 -207.70977)
		(end 160.162748 -207.70977)
		(width 0.18288)
		(layer "In2.Cu")
		(net "M_F_CPU1_SB_DQS_DP<2>")
	)
	(segment
		(start 164.714936 -208.53019)
		(end 164.232844 -208.53019)
		(width 0.18288)
		(layer "In2.Cu")
		(net "M_F_CPU1_SB_DQS_DP<2>")
	)
	(arc
		(start 139.177268 -223.251268)
		(mid 138.903039 -223.327193)
		(end 138.626596 -223.259904)
		(width 0.088646)
		(layer "In2.Cu")
		(net "M_F_CPU1_SB_DQS_DP<2>")
	)
	(arc
		(start 140.399262 -222.783654)
		(mid 140.114831 -223.252555)
		(end 139.566396 -223.259904)
		(width 0.088646)
		(layer "In2.Cu")
		(net "M_F_CPU1_SB_DQS_DP<2>")
	)
	(arc
		(start 137.672064 -223.251268)
		(mid 137.484866 -223.201125)
		(end 137.297668 -223.251268)
		(width 0.088646)
		(layer "In2.Cu")
		(net "M_F_CPU1_SB_DQS_DP<2>")
	)
	(arc
		(start 136.73201 -223.251268)
		(mid 136.547954 -223.081016)
		(end 136.455658 -222.847916)
		(width 0.088646)
		(layer "In2.Cu")
		(net "M_F_CPU1_SB_DQS_DP<2>")
	)
	(arc
		(start 138.237468 -223.251268)
		(mid 137.954766 -223.32701)
		(end 137.672064 -223.251268)
		(width 0.088646)
		(layer "In2.Cu")
		(net "M_F_CPU1_SB_DQS_DP<2>")
	)
	(arc
		(start 136.455658 -222.847916)
		(mid 136.45416 -222.837261)
		(end 136.452864 -222.82658)
		(width 0.088646)
		(layer "In2.Cu")
		(net "M_F_CPU1_SB_DQS_DP<2>")
	)
	(arc
		(start 138.611864 -223.251268)
		(mid 138.424666 -223.201125)
		(end 138.237468 -223.251268)
		(width 0.088646)
		(layer "In2.Cu")
		(net "M_F_CPU1_SB_DQS_DP<2>")
	)
	(arc
		(start 140.582142 -222.439738)
		(mid 140.448012 -222.576436)
		(end 140.399008 -222.761556)
		(width 0.088646)
		(layer "In2.Cu")
		(net "M_F_CPU1_SB_DQS_DP<2>")
	)
	(arc
		(start 137.297668 -223.251268)
		(mid 137.020855 -223.327104)
		(end 136.742424 -223.257364)
		(width 0.088646)
		(layer "In2.Cu")
		(net "M_F_CPU1_SB_DQS_DP<2>")
	)
	(arc
		(start 139.551664 -223.251268)
		(mid 139.364466 -223.201125)
		(end 139.177268 -223.251268)
		(width 0.088646)
		(layer "In2.Cu")
		(net "M_F_CPU1_SB_DQS_DP<2>")
	)
	(segment
		(start 173.900846 -219.41663)
		(end 174.490126 -219.41663)
		(width 0.20066)
		(layer "F.Cu")
		(net "M_F_CPU1_SB_DQS_DP<1>")
	)
	(segment
		(start 172.795946 -219.41663)
		(end 173.900846 -219.41663)
		(width 0.20066)
		(layer "F.Cu")
		(net "M_F_CPU1_SB_DQS_DP<1>")
	)
	(segment
		(start 179.637182 -219.545408)
		(end 180.007768 -219.545408)
		(width 0.20066)
		(layer "F.Cu")
		(net "M_F_CPU1_SB_DQS_DP<1>")
	)
	(segment
		(start 180.61432 -219.134944)
		(end 180.896006 -219.41663)
		(width 0.20066)
		(layer "F.Cu")
		(net "M_F_CPU1_SB_DQS_DP<1>")
	)
	(segment
		(start 132.785866 -230.622602)
		(end 132.785612 -230.622348)
		(width 0.20066)
		(layer "F.Cu")
		(net "M_F_CPU1_SB_DQS_DP<1>")
	)
	(segment
		(start 175.745648 -219.59062)
		(end 176.431448 -219.59062)
		(width 0.20066)
		(layer "F.Cu")
		(net "M_F_CPU1_SB_DQS_DP<1>")
	)
	(segment
		(start 180.007768 -219.545408)
		(end 180.418232 -219.134944)
		(width 0.20066)
		(layer "F.Cu")
		(net "M_F_CPU1_SB_DQS_DP<1>")
	)
	(segment
		(start 176.848008 -219.841826)
		(end 179.00523 -219.841826)
		(width 0.1016)
		(layer "F.Cu")
		(net "M_F_CPU1_SB_DQS_DP<1>")
	)
	(segment
		(start 179.334668 -219.847922)
		(end 179.637182 -219.545408)
		(width 0.20066)
		(layer "F.Cu")
		(net "M_F_CPU1_SB_DQS_DP<1>")
	)
	(segment
		(start 176.682654 -219.841826)
		(end 176.8221 -219.841826)
		(width 0.20066)
		(layer "F.Cu")
		(net "M_F_CPU1_SB_DQS_DP<1>")
	)
	(segment
		(start 174.730664 -219.176092)
		(end 175.33112 -219.176092)
		(width 0.20066)
		(layer "F.Cu")
		(net "M_F_CPU1_SB_DQS_DP<1>")
	)
	(segment
		(start 174.490126 -219.41663)
		(end 174.730664 -219.176092)
		(width 0.20066)
		(layer "F.Cu")
		(net "M_F_CPU1_SB_DQS_DP<1>")
	)
	(segment
		(start 176.431448 -219.59062)
		(end 176.682654 -219.841826)
		(width 0.20066)
		(layer "F.Cu")
		(net "M_F_CPU1_SB_DQS_DP<1>")
	)
	(segment
		(start 179.00523 -219.841826)
		(end 179.011326 -219.847922)
		(width 0.1016)
		(layer "F.Cu")
		(net "M_F_CPU1_SB_DQS_DP<1>")
	)
	(segment
		(start 132.785612 -230.622348)
		(end 132.785612 -230.086662)
		(width 0.20066)
		(layer "F.Cu")
		(net "M_F_CPU1_SB_DQS_DP<1>")
	)
	(segment
		(start 179.011326 -219.847922)
		(end 179.334668 -219.847922)
		(width 0.20066)
		(layer "F.Cu")
		(net "M_F_CPU1_SB_DQS_DP<1>")
	)
	(segment
		(start 175.33112 -219.176092)
		(end 175.745648 -219.59062)
		(width 0.20066)
		(layer "F.Cu")
		(net "M_F_CPU1_SB_DQS_DP<1>")
	)
	(segment
		(start 176.8221 -219.841826)
		(end 176.848008 -219.841826)
		(width 0.101854)
		(layer "F.Cu")
		(net "M_F_CPU1_SB_DQS_DP<1>")
	)
	(segment
		(start 180.896006 -219.41663)
		(end 181.444646 -219.41663)
		(width 0.20066)
		(layer "F.Cu")
		(net "M_F_CPU1_SB_DQS_DP<1>")
	)
	(segment
		(start 180.418232 -219.134944)
		(end 180.61432 -219.134944)
		(width 0.20066)
		(layer "F.Cu")
		(net "M_F_CPU1_SB_DQS_DP<1>")
	)
	(segment
		(start 172.48378 -219.104464)
		(end 172.286676 -219.104464)
		(width 0.18288)
		(layer "In2.Cu")
		(net "M_F_CPU1_SB_DQS_DP<1>")
	)
	(segment
		(start 172.286676 -219.104464)
		(end 172.119544 -218.937332)
		(width 0.18288)
		(layer "In2.Cu")
		(net "M_F_CPU1_SB_DQS_DP<1>")
	)
	(segment
		(start 169.329608 -218.97975)
		(end 169.313352 -218.97975)
		(width 0.16002)
		(layer "In2.Cu")
		(net "M_F_CPU1_SB_DQS_DP<1>")
	)
	(segment
		(start 137.110216 -230.086662)
		(end 137.110216 -230.096568)
		(width 0.088646)
		(layer "In2.Cu")
		(net "M_F_CPU1_SB_DQS_DP<1>")
	)
	(segment
		(start 133.442964 -230.57612)
		(end 133.430772 -230.569008)
		(width 0.088646)
		(layer "In2.Cu")
		(net "M_F_CPU1_SB_DQS_DP<1>")
	)
	(segment
		(start 172.795946 -219.41663)
		(end 172.48378 -219.104464)
		(width 0.18288)
		(layer "In2.Cu")
		(net "M_F_CPU1_SB_DQS_DP<1>")
	)
	(segment
		(start 163.88842 -219.867226)
		(end 163.570666 -219.549472)
		(width 0.18288)
		(layer "In2.Cu")
		(net "M_F_CPU1_SB_DQS_DP<1>")
	)
	(segment
		(start 165.443408 -220.10497)
		(end 164.88791 -219.549472)
		(width 0.18288)
		(layer "In2.Cu")
		(net "M_F_CPU1_SB_DQS_DP<1>")
	)
	(segment
		(start 157.856428 -218.400884)
		(end 157.559502 -218.69781)
		(width 0.18288)
		(layer "In2.Cu")
		(net "M_F_CPU1_SB_DQS_DP<1>")
	)
	(segment
		(start 164.54882 -219.549472)
		(end 164.231066 -219.867226)
		(width 0.18288)
		(layer "In2.Cu")
		(net "M_F_CPU1_SB_DQS_DP<1>")
	)
	(segment
		(start 140.950188 -228.925374)
		(end 140.20419 -229.671372)
		(width 0.088646)
		(layer "In2.Cu")
		(net "M_F_CPU1_SB_DQS_DP<1>")
	)
	(segment
		(start 162.351974 -219.549472)
		(end 161.965132 -219.16263)
		(width 0.18288)
		(layer "In2.Cu")
		(net "M_F_CPU1_SB_DQS_DP<1>")
	)
	(segment
		(start 139.17676 -229.76205)
		(end 139.177014 -229.762558)
		(width 0.088646)
		(layer "In2.Cu")
		(net "M_F_CPU1_SB_DQS_DP<1>")
	)
	(segment
		(start 161.782252 -218.97975)
		(end 161.754058 -218.951556)
		(width 0.16002)
		(layer "In2.Cu")
		(net "M_F_CPU1_SB_DQS_DP<1>")
	)
	(segment
		(start 169.145712 -218.81211)
		(end 168.55948 -218.81211)
		(width 0.18288)
		(layer "In2.Cu")
		(net "M_F_CPU1_SB_DQS_DP<1>")
	)
	(segment
		(start 159.752284 -218.356942)
		(end 159.613346 -218.218004)
		(width 0.16002)
		(layer "In2.Cu")
		(net "M_F_CPU1_SB_DQS_DP<1>")
	)
	(segment
		(start 153.959052 -221.015052)
		(end 146.301714 -228.67239)
		(width 0.18288)
		(layer "In2.Cu")
		(net "M_F_CPU1_SB_DQS_DP<1>")
	)
	(segment
		(start 137.297668 -229.762304)
		(end 137.288778 -229.767384)
		(width 0.088646)
		(layer "In2.Cu")
		(net "M_F_CPU1_SB_DQS_DP<1>")
	)
	(segment
		(start 169.285158 -218.951556)
		(end 169.145712 -218.81211)
		(width 0.18288)
		(layer "In2.Cu")
		(net "M_F_CPU1_SB_DQS_DP<1>")
	)
	(segment
		(start 146.301714 -228.67239)
		(end 141.288008 -228.67239)
		(width 0.18288)
		(layer "In2.Cu")
		(net "M_F_CPU1_SB_DQS_DP<1>")
	)
	(segment
		(start 161.798508 -218.97975)
		(end 161.782252 -218.97975)
		(width 0.16002)
		(layer "In2.Cu")
		(net "M_F_CPU1_SB_DQS_DP<1>")
	)
	(segment
		(start 157.884622 -218.37269)
		(end 157.856428 -218.400884)
		(width 0.16002)
		(layer "In2.Cu")
		(net "M_F_CPU1_SB_DQS_DP<1>")
	)
	(segment
		(start 164.231066 -219.867226)
		(end 163.88842 -219.867226)
		(width 0.18288)
		(layer "In2.Cu")
		(net "M_F_CPU1_SB_DQS_DP<1>")
	)
	(segment
		(start 159.780478 -218.400884)
		(end 159.752284 -218.37269)
		(width 0.16002)
		(layer "In2.Cu")
		(net "M_F_CPU1_SB_DQS_DP<1>")
	)
	(segment
		(start 161.936938 -219.11818)
		(end 161.798508 -218.97975)
		(width 0.16002)
		(layer "In2.Cu")
		(net "M_F_CPU1_SB_DQS_DP<1>")
	)
	(segment
		(start 159.613346 -218.218004)
		(end 159.597598 -218.218004)
		(width 0.16002)
		(layer "In2.Cu")
		(net "M_F_CPU1_SB_DQS_DP<1>")
	)
	(segment
		(start 158.067502 -218.18981)
		(end 158.039308 -218.218004)
		(width 0.16002)
		(layer "In2.Cu")
		(net "M_F_CPU1_SB_DQS_DP<1>")
	)
	(segment
		(start 163.570666 -219.549472)
		(end 162.351974 -219.549472)
		(width 0.18288)
		(layer "In2.Cu")
		(net "M_F_CPU1_SB_DQS_DP<1>")
	)
	(segment
		(start 169.313352 -218.97975)
		(end 169.285158 -218.951556)
		(width 0.16002)
		(layer "In2.Cu")
		(net "M_F_CPU1_SB_DQS_DP<1>")
	)
	(segment
		(start 161.936938 -219.134436)
		(end 161.936938 -219.11818)
		(width 0.16002)
		(layer "In2.Cu")
		(net "M_F_CPU1_SB_DQS_DP<1>")
	)
	(segment
		(start 154.81808 -221.015052)
		(end 153.959052 -221.015052)
		(width 0.18288)
		(layer "In2.Cu")
		(net "M_F_CPU1_SB_DQS_DP<1>")
	)
	(segment
		(start 167.26662 -220.10497)
		(end 165.443408 -220.10497)
		(width 0.18288)
		(layer "In2.Cu")
		(net "M_F_CPU1_SB_DQS_DP<1>")
	)
	(segment
		(start 157.884622 -218.356942)
		(end 157.884622 -218.37269)
		(width 0.16002)
		(layer "In2.Cu")
		(net "M_F_CPU1_SB_DQS_DP<1>")
	)
	(segment
		(start 159.942784 -218.56319)
		(end 159.780478 -218.400884)
		(width 0.18288)
		(layer "In2.Cu")
		(net "M_F_CPU1_SB_DQS_DP<1>")
	)
	(segment
		(start 169.496232 -219.16263)
		(end 169.468038 -219.134436)
		(width 0.16002)
		(layer "In2.Cu")
		(net "M_F_CPU1_SB_DQS_DP<1>")
	)
	(segment
		(start 161.754058 -218.951556)
		(end 161.365692 -218.56319)
		(width 0.18288)
		(layer "In2.Cu")
		(net "M_F_CPU1_SB_DQS_DP<1>")
	)
	(segment
		(start 172.119544 -218.937332)
		(end 171.708572 -218.937332)
		(width 0.18288)
		(layer "In2.Cu")
		(net "M_F_CPU1_SB_DQS_DP<1>")
	)
	(segment
		(start 159.752284 -218.37269)
		(end 159.752284 -218.356942)
		(width 0.16002)
		(layer "In2.Cu")
		(net "M_F_CPU1_SB_DQS_DP<1>")
	)
	(segment
		(start 157.135322 -218.69781)
		(end 154.81808 -221.015052)
		(width 0.18288)
		(layer "In2.Cu")
		(net "M_F_CPU1_SB_DQS_DP<1>")
	)
	(segment
		(start 157.559502 -218.69781)
		(end 157.135322 -218.69781)
		(width 0.18288)
		(layer "In2.Cu")
		(net "M_F_CPU1_SB_DQS_DP<1>")
	)
	(segment
		(start 169.468038 -219.134436)
		(end 169.468038 -219.11818)
		(width 0.16002)
		(layer "In2.Cu")
		(net "M_F_CPU1_SB_DQS_DP<1>")
	)
	(segment
		(start 141.035024 -228.925374)
		(end 140.950188 -228.925374)
		(width 0.088646)
		(layer "In2.Cu")
		(net "M_F_CPU1_SB_DQS_DP<1>")
	)
	(segment
		(start 169.681652 -219.34805)
		(end 169.496232 -219.16263)
		(width 0.18288)
		(layer "In2.Cu")
		(net "M_F_CPU1_SB_DQS_DP<1>")
	)
	(segment
		(start 161.965132 -219.16263)
		(end 161.936938 -219.134436)
		(width 0.16002)
		(layer "In2.Cu")
		(net "M_F_CPU1_SB_DQS_DP<1>")
	)
	(segment
		(start 158.02356 -218.218004)
		(end 157.884622 -218.356942)
		(width 0.16002)
		(layer "In2.Cu")
		(net "M_F_CPU1_SB_DQS_DP<1>")
	)
	(segment
		(start 159.569404 -218.18981)
		(end 159.292544 -217.91295)
		(width 0.18288)
		(layer "In2.Cu")
		(net "M_F_CPU1_SB_DQS_DP<1>")
	)
	(segment
		(start 171.297854 -219.34805)
		(end 169.681652 -219.34805)
		(width 0.18288)
		(layer "In2.Cu")
		(net "M_F_CPU1_SB_DQS_DP<1>")
	)
	(segment
		(start 159.597598 -218.218004)
		(end 159.569404 -218.18981)
		(width 0.16002)
		(layer "In2.Cu")
		(net "M_F_CPU1_SB_DQS_DP<1>")
	)
	(segment
		(start 164.88791 -219.549472)
		(end 164.54882 -219.549472)
		(width 0.18288)
		(layer "In2.Cu")
		(net "M_F_CPU1_SB_DQS_DP<1>")
	)
	(segment
		(start 133.09854 -230.086662)
		(end 132.785612 -230.086662)
		(width 0.088646)
		(layer "In2.Cu")
		(net "M_F_CPU1_SB_DQS_DP<1>")
	)
	(segment
		(start 158.039308 -218.218004)
		(end 158.02356 -218.218004)
		(width 0.16002)
		(layer "In2.Cu")
		(net "M_F_CPU1_SB_DQS_DP<1>")
	)
	(segment
		(start 168.55948 -218.81211)
		(end 167.26662 -220.10497)
		(width 0.18288)
		(layer "In2.Cu")
		(net "M_F_CPU1_SB_DQS_DP<1>")
	)
	(segment
		(start 133.164072 -230.152194)
		(end 133.09854 -230.086662)
		(width 0.088646)
		(layer "In2.Cu")
		(net "M_F_CPU1_SB_DQS_DP<1>")
	)
	(segment
		(start 169.468038 -219.11818)
		(end 169.329608 -218.97975)
		(width 0.16002)
		(layer "In2.Cu")
		(net "M_F_CPU1_SB_DQS_DP<1>")
	)
	(segment
		(start 171.708572 -218.937332)
		(end 171.297854 -219.34805)
		(width 0.18288)
		(layer "In2.Cu")
		(net "M_F_CPU1_SB_DQS_DP<1>")
	)
	(segment
		(start 158.344362 -217.91295)
		(end 158.067502 -218.18981)
		(width 0.18288)
		(layer "In2.Cu")
		(net "M_F_CPU1_SB_DQS_DP<1>")
	)
	(segment
		(start 140.20419 -229.671372)
		(end 139.515088 -229.671372)
		(width 0.088646)
		(layer "In2.Cu")
		(net "M_F_CPU1_SB_DQS_DP<1>")
	)
	(segment
		(start 141.288008 -228.67239)
		(end 141.035024 -228.925374)
		(width 0.18288)
		(layer "In2.Cu")
		(net "M_F_CPU1_SB_DQS_DP<1>")
	)
	(segment
		(start 161.365692 -218.56319)
		(end 159.942784 -218.56319)
		(width 0.18288)
		(layer "In2.Cu")
		(net "M_F_CPU1_SB_DQS_DP<1>")
	)
	(segment
		(start 159.292544 -217.91295)
		(end 158.344362 -217.91295)
		(width 0.18288)
		(layer "In2.Cu")
		(net "M_F_CPU1_SB_DQS_DP<1>")
	)
	(arc
		(start 134.382764 -230.57612)
		(mid 134.195566 -230.525977)
		(end 134.008368 -230.57612)
		(width 0.088646)
		(layer "In2.Cu")
		(net "M_F_CPU1_SB_DQS_DP<1>")
	)
	(arc
		(start 135.322564 -230.57612)
		(mid 135.135366 -230.525977)
		(end 134.948168 -230.57612)
		(width 0.088646)
		(layer "In2.Cu")
		(net "M_F_CPU1_SB_DQS_DP<1>")
	)
	(arc
		(start 134.008368 -230.57612)
		(mid 133.725666 -230.651896)
		(end 133.442964 -230.57612)
		(width 0.088646)
		(layer "In2.Cu")
		(net "M_F_CPU1_SB_DQS_DP<1>")
	)
	(arc
		(start 139.515088 -229.671372)
		(mid 139.339955 -229.694438)
		(end 139.17676 -229.76205)
		(width 0.088646)
		(layer "In2.Cu")
		(net "M_F_CPU1_SB_DQS_DP<1>")
	)
	(arc
		(start 135.887968 -230.57612)
		(mid 135.605266 -230.651896)
		(end 135.322564 -230.57612)
		(width 0.088646)
		(layer "In2.Cu")
		(net "M_F_CPU1_SB_DQS_DP<1>")
	)
	(arc
		(start 134.948168 -230.57612)
		(mid 134.665466 -230.651896)
		(end 134.382764 -230.57612)
		(width 0.088646)
		(layer "In2.Cu")
		(net "M_F_CPU1_SB_DQS_DP<1>")
	)
	(arc
		(start 138.611864 -229.762304)
		(mid 138.424666 -229.712161)
		(end 138.237468 -229.762304)
		(width 0.088646)
		(layer "In2.Cu")
		(net "M_F_CPU1_SB_DQS_DP<1>")
	)
	(arc
		(start 137.672064 -229.762304)
		(mid 137.484866 -229.712161)
		(end 137.297668 -229.762304)
		(width 0.088646)
		(layer "In2.Cu")
		(net "M_F_CPU1_SB_DQS_DP<1>")
	)
	(arc
		(start 136.262364 -230.57612)
		(mid 136.075166 -230.525977)
		(end 135.887968 -230.57612)
		(width 0.088646)
		(layer "In2.Cu")
		(net "M_F_CPU1_SB_DQS_DP<1>")
	)
	(arc
		(start 138.237468 -229.762304)
		(mid 137.954766 -229.83808)
		(end 137.672064 -229.762304)
		(width 0.088646)
		(layer "In2.Cu")
		(net "M_F_CPU1_SB_DQS_DP<1>")
	)
	(arc
		(start 133.430772 -230.569008)
		(mid 133.25517 -230.400116)
		(end 133.166866 -230.173022)
		(width 0.088646)
		(layer "In2.Cu")
		(net "M_F_CPU1_SB_DQS_DP<1>")
	)
	(arc
		(start 139.177014 -229.762558)
		(mid 138.894393 -229.838173)
		(end 138.611864 -229.762304)
		(width 0.088646)
		(layer "In2.Cu")
		(net "M_F_CPU1_SB_DQS_DP<1>")
	)
	(arc
		(start 137.110216 -230.096568)
		(mid 137.032105 -230.373517)
		(end 136.827768 -230.57612)
		(width 0.088646)
		(layer "In2.Cu")
		(net "M_F_CPU1_SB_DQS_DP<1>")
	)
	(arc
		(start 137.288778 -229.767384)
		(mid 137.157864 -229.903744)
		(end 137.110216 -230.086662)
		(width 0.088646)
		(layer "In2.Cu")
		(net "M_F_CPU1_SB_DQS_DP<1>")
	)
	(arc
		(start 136.827768 -230.57612)
		(mid 136.545066 -230.651896)
		(end 136.262364 -230.57612)
		(width 0.088646)
		(layer "In2.Cu")
		(net "M_F_CPU1_SB_DQS_DP<1>")
	)
	(arc
		(start 133.166866 -230.173022)
		(mid 133.165372 -230.162621)
		(end 133.164072 -230.152194)
		(width 0.088646)
		(layer "In2.Cu")
		(net "M_F_CPU1_SB_DQS_DP<1>")
	)
	(segment
		(start 176.8221 -229.19182)
		(end 176.848008 -229.19182)
		(width 0.101854)
		(layer "F.Cu")
		(net "M_F_CPU1_SB_DQS_DP<0>")
	)
	(segment
		(start 129.496312 -237.947454)
		(end 129.496566 -237.947454)
		(width 0.20066)
		(layer "F.Cu")
		(net "M_F_CPU1_SB_DQS_DP<0>")
	)
	(segment
		(start 180.896006 -228.766624)
		(end 181.444646 -228.766624)
		(width 0.20066)
		(layer "F.Cu")
		(net "M_F_CPU1_SB_DQS_DP<0>")
	)
	(segment
		(start 176.848008 -229.19182)
		(end 179.00523 -229.19182)
		(width 0.1016)
		(layer "F.Cu")
		(net "M_F_CPU1_SB_DQS_DP<0>")
	)
	(segment
		(start 129.496566 -237.947454)
		(end 129.496566 -237.411514)
		(width 0.20066)
		(layer "F.Cu")
		(net "M_F_CPU1_SB_DQS_DP<0>")
	)
	(segment
		(start 174.730664 -228.526086)
		(end 175.33112 -228.526086)
		(width 0.20066)
		(layer "F.Cu")
		(net "M_F_CPU1_SB_DQS_DP<0>")
	)
	(segment
		(start 179.334668 -229.197916)
		(end 179.637182 -228.895402)
		(width 0.20066)
		(layer "F.Cu")
		(net "M_F_CPU1_SB_DQS_DP<0>")
	)
	(segment
		(start 179.637182 -228.895402)
		(end 180.007768 -228.895402)
		(width 0.20066)
		(layer "F.Cu")
		(net "M_F_CPU1_SB_DQS_DP<0>")
	)
	(segment
		(start 175.33112 -228.526086)
		(end 175.745648 -228.940614)
		(width 0.20066)
		(layer "F.Cu")
		(net "M_F_CPU1_SB_DQS_DP<0>")
	)
	(segment
		(start 172.795946 -228.766624)
		(end 173.900846 -228.766624)
		(width 0.20066)
		(layer "F.Cu")
		(net "M_F_CPU1_SB_DQS_DP<0>")
	)
	(segment
		(start 180.007768 -228.895402)
		(end 180.418232 -228.484938)
		(width 0.20066)
		(layer "F.Cu")
		(net "M_F_CPU1_SB_DQS_DP<0>")
	)
	(segment
		(start 176.431448 -228.940614)
		(end 176.682654 -229.19182)
		(width 0.20066)
		(layer "F.Cu")
		(net "M_F_CPU1_SB_DQS_DP<0>")
	)
	(segment
		(start 173.900846 -228.766624)
		(end 174.490126 -228.766624)
		(width 0.20066)
		(layer "F.Cu")
		(net "M_F_CPU1_SB_DQS_DP<0>")
	)
	(segment
		(start 179.00523 -229.19182)
		(end 179.011326 -229.197916)
		(width 0.1016)
		(layer "F.Cu")
		(net "M_F_CPU1_SB_DQS_DP<0>")
	)
	(segment
		(start 175.745648 -228.940614)
		(end 176.431448 -228.940614)
		(width 0.20066)
		(layer "F.Cu")
		(net "M_F_CPU1_SB_DQS_DP<0>")
	)
	(segment
		(start 176.682654 -229.19182)
		(end 176.8221 -229.19182)
		(width 0.20066)
		(layer "F.Cu")
		(net "M_F_CPU1_SB_DQS_DP<0>")
	)
	(segment
		(start 180.418232 -228.484938)
		(end 180.61432 -228.484938)
		(width 0.20066)
		(layer "F.Cu")
		(net "M_F_CPU1_SB_DQS_DP<0>")
	)
	(segment
		(start 180.61432 -228.484938)
		(end 180.896006 -228.766624)
		(width 0.20066)
		(layer "F.Cu")
		(net "M_F_CPU1_SB_DQS_DP<0>")
	)
	(segment
		(start 179.011326 -229.197916)
		(end 179.334668 -229.197916)
		(width 0.20066)
		(layer "F.Cu")
		(net "M_F_CPU1_SB_DQS_DP<0>")
	)
	(segment
		(start 174.490126 -228.766624)
		(end 174.730664 -228.526086)
		(width 0.20066)
		(layer "F.Cu")
		(net "M_F_CPU1_SB_DQS_DP<0>")
	)
	(segment
		(start 162.453574 -226.38385)
		(end 162.260788 -226.38385)
		(width 0.18288)
		(layer "In4.Cu")
		(net "M_F_CPU1_SB_DQS_DP<0>")
	)
	(segment
		(start 169.756328 -227.86086)
		(end 166.961312 -227.86086)
		(width 0.18288)
		(layer "In4.Cu")
		(net "M_F_CPU1_SB_DQS_DP<0>")
	)
	(segment
		(start 172.795946 -228.766624)
		(end 172.517054 -228.487732)
		(width 0.18288)
		(layer "In4.Cu")
		(net "M_F_CPU1_SB_DQS_DP<0>")
	)
	(segment
		(start 157.900624 -227.49383)
		(end 157.516576 -227.49383)
		(width 0.18288)
		(layer "In4.Cu")
		(net "M_F_CPU1_SB_DQS_DP<0>")
	)
	(segment
		(start 163.859464 -226.966526)
		(end 162.453574 -226.38385)
		(width 0.18288)
		(layer "In4.Cu")
		(net "M_F_CPU1_SB_DQS_DP<0>")
	)
	(segment
		(start 162.260788 -226.38385)
		(end 162.000692 -226.643946)
		(width 0.18288)
		(layer "In4.Cu")
		(net "M_F_CPU1_SB_DQS_DP<0>")
	)
	(segment
		(start 161.347912 -226.375214)
		(end 159.551878 -226.375214)
		(width 0.18288)
		(layer "In4.Cu")
		(net "M_F_CPU1_SB_DQS_DP<0>")
	)
	(segment
		(start 171.909994 -228.487732)
		(end 171.66209 -228.239828)
		(width 0.18288)
		(layer "In4.Cu")
		(net "M_F_CPU1_SB_DQS_DP<0>")
	)
	(segment
		(start 140.631418 -236.247432)
		(end 140.631418 -236.479588)
		(width 0.088646)
		(layer "In4.Cu")
		(net "M_F_CPU1_SB_DQS_DP<0>")
	)
	(segment
		(start 140.918184 -236.158786)
		(end 140.720064 -236.158786)
		(width 0.088646)
		(layer "In4.Cu")
		(net "M_F_CPU1_SB_DQS_DP<0>")
	)
	(segment
		(start 161.616644 -226.643946)
		(end 161.347912 -226.375214)
		(width 0.18288)
		(layer "In4.Cu")
		(net "M_F_CPU1_SB_DQS_DP<0>")
	)
	(segment
		(start 171.66209 -228.239828)
		(end 169.756328 -227.86086)
		(width 0.18288)
		(layer "In4.Cu")
		(net "M_F_CPU1_SB_DQS_DP<0>")
	)
	(segment
		(start 129.808986 -237.411514)
		(end 129.496566 -237.411514)
		(width 0.088646)
		(layer "In4.Cu")
		(net "M_F_CPU1_SB_DQS_DP<0>")
	)
	(segment
		(start 155.00985 -227.215446)
		(end 148.378672 -233.846624)
		(width 0.18288)
		(layer "In4.Cu")
		(net "M_F_CPU1_SB_DQS_DP<0>")
	)
	(segment
		(start 140.42644 -236.974634)
		(end 139.55014 -237.850172)
		(width 0.088646)
		(layer "In4.Cu")
		(net "M_F_CPU1_SB_DQS_DP<0>")
	)
	(segment
		(start 129.874772 -237.4773)
		(end 129.808986 -237.411514)
		(width 0.088646)
		(layer "In4.Cu")
		(net "M_F_CPU1_SB_DQS_DP<0>")
	)
	(segment
		(start 172.517054 -228.487732)
		(end 171.909994 -228.487732)
		(width 0.18288)
		(layer "In4.Cu")
		(net "M_F_CPU1_SB_DQS_DP<0>")
	)
	(segment
		(start 158.18358 -227.210874)
		(end 157.900624 -227.49383)
		(width 0.18288)
		(layer "In4.Cu")
		(net "M_F_CPU1_SB_DQS_DP<0>")
	)
	(segment
		(start 132.598668 -237.901226)
		(end 132.588254 -237.907322)
		(width 0.088646)
		(layer "In4.Cu")
		(net "M_F_CPU1_SB_DQS_DP<0>")
	)
	(segment
		(start 159.551878 -226.375214)
		(end 158.89859 -227.028502)
		(width 0.18288)
		(layer "In4.Cu")
		(net "M_F_CPU1_SB_DQS_DP<0>")
	)
	(segment
		(start 140.720064 -236.158786)
		(end 140.631418 -236.247432)
		(width 0.088646)
		(layer "In4.Cu")
		(net "M_F_CPU1_SB_DQS_DP<0>")
	)
	(segment
		(start 165.640004 -226.539552)
		(end 165.220396 -226.539552)
		(width 0.18288)
		(layer "In4.Cu")
		(net "M_F_CPU1_SB_DQS_DP<0>")
	)
	(segment
		(start 157.238192 -227.215446)
		(end 155.00985 -227.215446)
		(width 0.18288)
		(layer "In4.Cu")
		(net "M_F_CPU1_SB_DQS_DP<0>")
	)
	(segment
		(start 144.292574 -233.846624)
		(end 141.920468 -236.21873)
		(width 0.18288)
		(layer "In4.Cu")
		(net "M_F_CPU1_SB_DQS_DP<0>")
	)
	(segment
		(start 157.516576 -227.49383)
		(end 157.238192 -227.215446)
		(width 0.18288)
		(layer "In4.Cu")
		(net "M_F_CPU1_SB_DQS_DP<0>")
	)
	(segment
		(start 162.000692 -226.643946)
		(end 161.616644 -226.643946)
		(width 0.18288)
		(layer "In4.Cu")
		(net "M_F_CPU1_SB_DQS_DP<0>")
	)
	(segment
		(start 148.378672 -233.846624)
		(end 144.292574 -233.846624)
		(width 0.18288)
		(layer "In4.Cu")
		(net "M_F_CPU1_SB_DQS_DP<0>")
	)
	(segment
		(start 140.631418 -236.479588)
		(end 140.42644 -236.974634)
		(width 0.088646)
		(layer "In4.Cu")
		(net "M_F_CPU1_SB_DQS_DP<0>")
	)
	(segment
		(start 165.220396 -226.539552)
		(end 164.190934 -226.966526)
		(width 0.18288)
		(layer "In4.Cu")
		(net "M_F_CPU1_SB_DQS_DP<0>")
	)
	(segment
		(start 166.961312 -227.86086)
		(end 165.640004 -226.539552)
		(width 0.18288)
		(layer "In4.Cu")
		(net "M_F_CPU1_SB_DQS_DP<0>")
	)
	(segment
		(start 164.190934 -226.966526)
		(end 163.859464 -226.966526)
		(width 0.18288)
		(layer "In4.Cu")
		(net "M_F_CPU1_SB_DQS_DP<0>")
	)
	(segment
		(start 140.978128 -236.21873)
		(end 140.918184 -236.158786)
		(width 0.088646)
		(layer "In4.Cu")
		(net "M_F_CPU1_SB_DQS_DP<0>")
	)
	(segment
		(start 131.658614 -237.901226)
		(end 131.643882 -237.909862)
		(width 0.088646)
		(layer "In4.Cu")
		(net "M_F_CPU1_SB_DQS_DP<0>")
	)
	(segment
		(start 139.55014 -237.850172)
		(end 139.36472 -237.850172)
		(width 0.088646)
		(layer "In4.Cu")
		(net "M_F_CPU1_SB_DQS_DP<0>")
	)
	(segment
		(start 132.987796 -237.909862)
		(end 132.973064 -237.901226)
		(width 0.088646)
		(layer "In4.Cu")
		(net "M_F_CPU1_SB_DQS_DP<0>")
	)
	(segment
		(start 141.001496 -236.21873)
		(end 140.978128 -236.21873)
		(width 0.088646)
		(layer "In4.Cu")
		(net "M_F_CPU1_SB_DQS_DP<0>")
	)
	(segment
		(start 158.89859 -227.028502)
		(end 158.459678 -227.210874)
		(width 0.18288)
		(layer "In4.Cu")
		(net "M_F_CPU1_SB_DQS_DP<0>")
	)
	(segment
		(start 141.920468 -236.21873)
		(end 141.001496 -236.21873)
		(width 0.18288)
		(layer "In4.Cu")
		(net "M_F_CPU1_SB_DQS_DP<0>")
	)
	(segment
		(start 130.718814 -237.901226)
		(end 130.704082 -237.909862)
		(width 0.088646)
		(layer "In4.Cu")
		(net "M_F_CPU1_SB_DQS_DP<0>")
	)
	(segment
		(start 158.459678 -227.210874)
		(end 158.18358 -227.210874)
		(width 0.18288)
		(layer "In4.Cu")
		(net "M_F_CPU1_SB_DQS_DP<0>")
	)
	(arc
		(start 139.36472 -237.850172)
		(mid 139.267639 -237.863368)
		(end 139.177268 -237.901226)
		(width 0.088646)
		(layer "In4.Cu")
		(net "M_F_CPU1_SB_DQS_DP<0>")
	)
	(arc
		(start 135.418068 -237.901226)
		(mid 135.135366 -237.977002)
		(end 134.852664 -237.901226)
		(width 0.088646)
		(layer "In4.Cu")
		(net "M_F_CPU1_SB_DQS_DP<0>")
	)
	(arc
		(start 131.09321 -237.901226)
		(mid 130.906012 -237.851083)
		(end 130.718814 -237.901226)
		(width 0.088646)
		(layer "In4.Cu")
		(net "M_F_CPU1_SB_DQS_DP<0>")
	)
	(arc
		(start 132.588254 -237.907322)
		(mid 132.309822 -237.977168)
		(end 132.03301 -237.901226)
		(width 0.088646)
		(layer "In4.Cu")
		(net "M_F_CPU1_SB_DQS_DP<0>")
	)
	(arc
		(start 138.237468 -237.901226)
		(mid 137.954766 -237.976968)
		(end 137.672064 -237.901226)
		(width 0.088646)
		(layer "In4.Cu")
		(net "M_F_CPU1_SB_DQS_DP<0>")
	)
	(arc
		(start 136.732264 -237.901226)
		(mid 136.545066 -237.851083)
		(end 136.357868 -237.901226)
		(width 0.088646)
		(layer "In4.Cu")
		(net "M_F_CPU1_SB_DQS_DP<0>")
	)
	(arc
		(start 131.643882 -237.909862)
		(mid 131.367407 -237.977182)
		(end 131.09321 -237.901226)
		(width 0.088646)
		(layer "In4.Cu")
		(net "M_F_CPU1_SB_DQS_DP<0>")
	)
	(arc
		(start 129.877566 -237.498382)
		(mid 129.87607 -237.487854)
		(end 129.874772 -237.4773)
		(width 0.088646)
		(layer "In4.Cu")
		(net "M_F_CPU1_SB_DQS_DP<0>")
	)
	(arc
		(start 137.297668 -237.901226)
		(mid 137.014966 -237.976968)
		(end 136.732264 -237.901226)
		(width 0.088646)
		(layer "In4.Cu")
		(net "M_F_CPU1_SB_DQS_DP<0>")
	)
	(arc
		(start 138.611864 -237.901226)
		(mid 138.424666 -237.851083)
		(end 138.237468 -237.901226)
		(width 0.088646)
		(layer "In4.Cu")
		(net "M_F_CPU1_SB_DQS_DP<0>")
	)
	(arc
		(start 135.792464 -237.901226)
		(mid 135.605266 -237.851083)
		(end 135.418068 -237.901226)
		(width 0.088646)
		(layer "In4.Cu")
		(net "M_F_CPU1_SB_DQS_DP<0>")
	)
	(arc
		(start 137.672064 -237.901226)
		(mid 137.484866 -237.851083)
		(end 137.297668 -237.901226)
		(width 0.088646)
		(layer "In4.Cu")
		(net "M_F_CPU1_SB_DQS_DP<0>")
	)
	(arc
		(start 136.357868 -237.901226)
		(mid 136.075166 -237.976968)
		(end 135.792464 -237.901226)
		(width 0.088646)
		(layer "In4.Cu")
		(net "M_F_CPU1_SB_DQS_DP<0>")
	)
	(arc
		(start 133.912864 -237.901226)
		(mid 133.725666 -237.851083)
		(end 133.538468 -237.901226)
		(width 0.088646)
		(layer "In4.Cu")
		(net "M_F_CPU1_SB_DQS_DP<0>")
	)
	(arc
		(start 139.177268 -237.901226)
		(mid 138.894566 -237.976968)
		(end 138.611864 -237.901226)
		(width 0.088646)
		(layer "In4.Cu")
		(net "M_F_CPU1_SB_DQS_DP<0>")
	)
	(arc
		(start 133.538468 -237.901226)
		(mid 133.264269 -237.977061)
		(end 132.987796 -237.909862)
		(width 0.088646)
		(layer "In4.Cu")
		(net "M_F_CPU1_SB_DQS_DP<0>")
	)
	(arc
		(start 134.478268 -237.901226)
		(mid 134.195566 -237.977002)
		(end 133.912864 -237.901226)
		(width 0.088646)
		(layer "In4.Cu")
		(net "M_F_CPU1_SB_DQS_DP<0>")
	)
	(arc
		(start 130.15341 -237.901226)
		(mid 129.969819 -237.731091)
		(end 129.877566 -237.498382)
		(width 0.088646)
		(layer "In4.Cu")
		(net "M_F_CPU1_SB_DQS_DP<0>")
	)
	(arc
		(start 130.704082 -237.909862)
		(mid 130.427607 -237.977182)
		(end 130.15341 -237.901226)
		(width 0.088646)
		(layer "In4.Cu")
		(net "M_F_CPU1_SB_DQS_DP<0>")
	)
	(arc
		(start 132.03301 -237.901226)
		(mid 131.845812 -237.851083)
		(end 131.658614 -237.901226)
		(width 0.088646)
		(layer "In4.Cu")
		(net "M_F_CPU1_SB_DQS_DP<0>")
	)
	(arc
		(start 132.973064 -237.901226)
		(mid 132.785866 -237.851083)
		(end 132.598668 -237.901226)
		(width 0.088646)
		(layer "In4.Cu")
		(net "M_F_CPU1_SB_DQS_DP<0>")
	)
	(arc
		(start 134.852664 -237.901226)
		(mid 134.665466 -237.851083)
		(end 134.478268 -237.901226)
		(width 0.088646)
		(layer "In4.Cu")
		(net "M_F_CPU1_SB_DQS_DP<0>")
	)
	(segment
		(start 179.566824 -237.917736)
		(end 179.871878 -237.917736)
		(width 0.20066)
		(layer "F.Cu")
		(net "M_F_CPU1_SB_DQS_DN<9>")
	)
	(segment
		(start 175.881538 -237.962948)
		(end 176.403254 -237.962948)
		(width 0.20066)
		(layer "F.Cu")
		(net "M_F_CPU1_SB_DQS_DN<9>")
	)
	(segment
		(start 175.46701 -237.54842)
		(end 175.881538 -237.962948)
		(width 0.20066)
		(layer "F.Cu")
		(net "M_F_CPU1_SB_DQS_DN<9>")
	)
	(segment
		(start 133.725666 -240.389156)
		(end 133.725666 -239.853216)
		(width 0.20066)
		(layer "F.Cu")
		(net "M_F_CPU1_SB_DQS_DN<9>")
	)
	(segment
		(start 174.731172 -237.54842)
		(end 175.46701 -237.54842)
		(width 0.20066)
		(layer "F.Cu")
		(net "M_F_CPU1_SB_DQS_DN<9>")
	)
	(segment
		(start 180.614828 -237.507272)
		(end 180.855366 -237.266734)
		(width 0.20066)
		(layer "F.Cu")
		(net "M_F_CPU1_SB_DQS_DN<9>")
	)
	(segment
		(start 173.900846 -237.266734)
		(end 174.449486 -237.266734)
		(width 0.20066)
		(layer "F.Cu")
		(net "M_F_CPU1_SB_DQS_DN<9>")
	)
	(segment
		(start 176.8221 -237.691676)
		(end 176.826418 -237.691676)
		(width 0.101854)
		(layer "F.Cu")
		(net "M_F_CPU1_SB_DQS_DN<9>")
	)
	(segment
		(start 179.011326 -237.686342)
		(end 179.33543 -237.686342)
		(width 0.20066)
		(layer "F.Cu")
		(net "M_F_CPU1_SB_DQS_DN<9>")
	)
	(segment
		(start 179.33543 -237.686342)
		(end 179.566824 -237.917736)
		(width 0.20066)
		(layer "F.Cu")
		(net "M_F_CPU1_SB_DQS_DN<9>")
	)
	(segment
		(start 179.005992 -237.691676)
		(end 179.011326 -237.686342)
		(width 0.1016)
		(layer "F.Cu")
		(net "M_F_CPU1_SB_DQS_DN<9>")
	)
	(segment
		(start 174.449486 -237.266734)
		(end 174.731172 -237.54842)
		(width 0.20066)
		(layer "F.Cu")
		(net "M_F_CPU1_SB_DQS_DN<9>")
	)
	(segment
		(start 179.871878 -237.917736)
		(end 180.282342 -237.507272)
		(width 0.20066)
		(layer "F.Cu")
		(net "M_F_CPU1_SB_DQS_DN<9>")
	)
	(segment
		(start 176.674526 -237.691676)
		(end 176.8221 -237.691676)
		(width 0.20066)
		(layer "F.Cu")
		(net "M_F_CPU1_SB_DQS_DN<9>")
	)
	(segment
		(start 176.403254 -237.962948)
		(end 176.674526 -237.691676)
		(width 0.20066)
		(layer "F.Cu")
		(net "M_F_CPU1_SB_DQS_DN<9>")
	)
	(segment
		(start 176.826418 -237.691676)
		(end 179.005992 -237.691676)
		(width 0.1016)
		(layer "F.Cu")
		(net "M_F_CPU1_SB_DQS_DN<9>")
	)
	(segment
		(start 180.282342 -237.507272)
		(end 180.614828 -237.507272)
		(width 0.20066)
		(layer "F.Cu")
		(net "M_F_CPU1_SB_DQS_DN<9>")
	)
	(segment
		(start 172.795946 -237.266734)
		(end 173.900846 -237.266734)
		(width 0.20066)
		(layer "F.Cu")
		(net "M_F_CPU1_SB_DQS_DN<9>")
	)
	(segment
		(start 180.855366 -237.266734)
		(end 181.444646 -237.266734)
		(width 0.20066)
		(layer "F.Cu")
		(net "M_F_CPU1_SB_DQS_DN<9>")
	)
	(segment
		(start 169.464736 -237.381796)
		(end 169.218102 -237.135162)
		(width 0.18288)
		(layer "In2.Cu")
		(net "M_F_CPU1_SB_DQS_DN<9>")
	)
	(segment
		(start 153.789634 -241.434366)
		(end 153.240994 -241.434366)
		(width 0.18288)
		(layer "In2.Cu")
		(net "M_F_CPU1_SB_DQS_DN<9>")
	)
	(segment
		(start 139.655296 -241.654584)
		(end 138.166856 -241.654584)
		(width 0.088646)
		(layer "In2.Cu")
		(net "M_F_CPU1_SB_DQS_DN<9>")
	)
	(segment
		(start 169.218102 -237.135162)
		(end 167.771318 -237.135162)
		(width 0.18288)
		(layer "In2.Cu")
		(net "M_F_CPU1_SB_DQS_DN<9>")
	)
	(segment
		(start 135.41756 -240.178082)
		(end 135.418068 -240.177574)
		(width 0.088646)
		(layer "In2.Cu")
		(net "M_F_CPU1_SB_DQS_DN<9>")
	)
	(segment
		(start 162.153854 -237.615984)
		(end 162.138106 -237.615984)
		(width 0.16002)
		(layer "In2.Cu")
		(net "M_F_CPU1_SB_DQS_DN<9>")
	)
	(segment
		(start 157.686502 -238.10595)
		(end 157.11805 -238.10595)
		(width 0.18288)
		(layer "In2.Cu")
		(net "M_F_CPU1_SB_DQS_DN<9>")
	)
	(segment
		(start 151.894794 -241.434366)
		(end 151.770334 -241.309906)
		(width 0.18288)
		(layer "In2.Cu")
		(net "M_F_CPU1_SB_DQS_DN<9>")
	)
	(segment
		(start 163.881308 -237.428024)
		(end 163.881308 -237.443772)
		(width 0.16002)
		(layer "In2.Cu")
		(net "M_F_CPU1_SB_DQS_DN<9>")
	)
	(segment
		(start 135.418068 -240.177574)
		(end 135.407654 -240.171478)
		(width 0.088646)
		(layer "In2.Cu")
		(net "M_F_CPU1_SB_DQS_DN<9>")
	)
	(segment
		(start 157.870652 -238.2901)
		(end 157.686502 -238.10595)
		(width 0.18288)
		(layer "In2.Cu")
		(net "M_F_CPU1_SB_DQS_DN<9>")
	)
	(segment
		(start 163.69665 -237.62843)
		(end 163.680902 -237.62843)
		(width 0.16002)
		(layer "In2.Cu")
		(net "M_F_CPU1_SB_DQS_DN<9>")
	)
	(segment
		(start 151.097234 -241.434366)
		(end 140.518896 -241.434366)
		(width 0.18288)
		(layer "In2.Cu")
		(net "M_F_CPU1_SB_DQS_DN<9>")
	)
	(segment
		(start 136.640316 -240.667286)
		(end 136.640316 -240.653062)
		(width 0.088646)
		(layer "In2.Cu")
		(net "M_F_CPU1_SB_DQS_DN<9>")
	)
	(segment
		(start 164.923724 -237.13821)
		(end 164.171122 -237.13821)
		(width 0.18288)
		(layer "In2.Cu")
		(net "M_F_CPU1_SB_DQS_DN<9>")
	)
	(segment
		(start 151.770334 -241.309906)
		(end 151.221694 -241.309906)
		(width 0.18288)
		(layer "In2.Cu")
		(net "M_F_CPU1_SB_DQS_DN<9>")
	)
	(segment
		(start 140.518896 -241.434366)
		(end 140.459206 -241.494056)
		(width 0.088646)
		(layer "In2.Cu")
		(net "M_F_CPU1_SB_DQS_DN<9>")
	)
	(segment
		(start 167.398954 -236.779054)
		(end 167.214804 -236.594904)
		(width 0.16002)
		(layer "In2.Cu")
		(net "M_F_CPU1_SB_DQS_DN<9>")
	)
	(segment
		(start 138.049762 -241.53749)
		(end 138.049762 -241.481102)
		(width 0.088646)
		(layer "In2.Cu")
		(net "M_F_CPU1_SB_DQS_DN<9>")
	)
	(segment
		(start 167.214804 -236.578648)
		(end 167.18661 -236.550454)
		(width 0.16002)
		(layer "In2.Cu")
		(net "M_F_CPU1_SB_DQS_DN<9>")
	)
	(segment
		(start 157.898846 -238.334042)
		(end 157.898846 -238.318294)
		(width 0.16002)
		(layer "In2.Cu")
		(net "M_F_CPU1_SB_DQS_DN<9>")
	)
	(segment
		(start 171.19473 -237.638082)
		(end 171.086018 -237.746794)
		(width 0.18288)
		(layer "In2.Cu")
		(net "M_F_CPU1_SB_DQS_DN<9>")
	)
	(segment
		(start 169.829734 -237.746794)
		(end 169.72153 -237.63859)
		(width 0.18288)
		(layer "In2.Cu")
		(net "M_F_CPU1_SB_DQS_DN<9>")
	)
	(segment
		(start 162.138106 -237.615984)
		(end 161.953448 -237.431326)
		(width 0.16002)
		(layer "In2.Cu")
		(net "M_F_CPU1_SB_DQS_DN<9>")
	)
	(segment
		(start 169.72153 -237.63859)
		(end 169.693336 -237.610396)
		(width 0.16002)
		(layer "In2.Cu")
		(net "M_F_CPU1_SB_DQS_DN<9>")
	)
	(segment
		(start 138.166856 -241.654584)
		(end 138.049762 -241.53749)
		(width 0.088646)
		(layer "In2.Cu")
		(net "M_F_CPU1_SB_DQS_DN<9>")
	)
	(segment
		(start 164.171122 -237.13821)
		(end 163.909502 -237.39983)
		(width 0.18288)
		(layer "In2.Cu")
		(net "M_F_CPU1_SB_DQS_DN<9>")
	)
	(segment
		(start 158.081726 -238.501174)
		(end 158.053532 -238.47298)
		(width 0.16002)
		(layer "In2.Cu")
		(net "M_F_CPU1_SB_DQS_DN<9>")
	)
	(segment
		(start 152.443434 -241.434366)
		(end 151.894794 -241.434366)
		(width 0.18288)
		(layer "In2.Cu")
		(net "M_F_CPU1_SB_DQS_DN<9>")
	)
	(segment
		(start 172.795946 -237.266734)
		(end 172.795946 -237.334298)
		(width 0.18288)
		(layer "In2.Cu")
		(net "M_F_CPU1_SB_DQS_DN<9>")
	)
	(segment
		(start 171.37761 -237.47095)
		(end 171.238672 -237.609888)
		(width 0.16002)
		(layer "In2.Cu")
		(net "M_F_CPU1_SB_DQS_DN<9>")
	)
	(segment
		(start 136.827768 -240.991644)
		(end 136.818878 -240.986564)
		(width 0.088646)
		(layer "In2.Cu")
		(net "M_F_CPU1_SB_DQS_DN<9>")
	)
	(segment
		(start 162.182048 -237.644178)
		(end 162.153854 -237.615984)
		(width 0.16002)
		(layer "In2.Cu")
		(net "M_F_CPU1_SB_DQS_DN<9>")
	)
	(segment
		(start 153.116534 -241.309906)
		(end 152.567894 -241.309906)
		(width 0.18288)
		(layer "In2.Cu")
		(net "M_F_CPU1_SB_DQS_DN<9>")
	)
	(segment
		(start 133.538468 -240.177574)
		(end 133.529578 -240.172494)
		(width 0.088646)
		(layer "In2.Cu")
		(net "M_F_CPU1_SB_DQS_DN<9>")
	)
	(segment
		(start 169.49293 -237.425738)
		(end 169.49293 -237.40999)
		(width 0.16002)
		(layer "In2.Cu")
		(net "M_F_CPU1_SB_DQS_DN<9>")
	)
	(segment
		(start 135.792464 -240.177574)
		(end 135.792972 -240.178082)
		(width 0.088646)
		(layer "In2.Cu")
		(net "M_F_CPU1_SB_DQS_DN<9>")
	)
	(segment
		(start 140.0429 -241.494056)
		(end 139.655296 -241.654584)
		(width 0.088646)
		(layer "In2.Cu")
		(net "M_F_CPU1_SB_DQS_DN<9>")
	)
	(segment
		(start 171.238672 -237.609888)
		(end 171.222924 -237.609888)
		(width 0.16002)
		(layer "In2.Cu")
		(net "M_F_CPU1_SB_DQS_DN<9>")
	)
	(segment
		(start 165.376352 -236.701838)
		(end 165.192202 -236.885988)
		(width 0.16002)
		(layer "In2.Cu")
		(net "M_F_CPU1_SB_DQS_DN<9>")
	)
	(segment
		(start 161.772092 -237.234222)
		(end 161.237676 -237.234222)
		(width 0.18288)
		(layer "In2.Cu")
		(net "M_F_CPU1_SB_DQS_DN<9>")
	)
	(segment
		(start 153.240994 -241.434366)
		(end 153.116534 -241.309906)
		(width 0.18288)
		(layer "In2.Cu")
		(net "M_F_CPU1_SB_DQS_DN<9>")
	)
	(segment
		(start 152.567894 -241.309906)
		(end 152.443434 -241.434366)
		(width 0.18288)
		(layer "In2.Cu")
		(net "M_F_CPU1_SB_DQS_DN<9>")
	)
	(segment
		(start 169.677588 -237.610396)
		(end 169.49293 -237.425738)
		(width 0.16002)
		(layer "In2.Cu")
		(net "M_F_CPU1_SB_DQS_DN<9>")
	)
	(segment
		(start 171.222924 -237.609888)
		(end 171.19473 -237.638082)
		(width 0.16002)
		(layer "In2.Cu")
		(net "M_F_CPU1_SB_DQS_DN<9>")
	)
	(segment
		(start 137.777728 -240.997994)
		(end 137.777982 -240.99774)
		(width 0.088646)
		(layer "In2.Cu")
		(net "M_F_CPU1_SB_DQS_DN<9>")
	)
	(segment
		(start 158.166562 -238.58601)
		(end 158.081726 -238.501174)
		(width 0.18288)
		(layer "In2.Cu")
		(net "M_F_CPU1_SB_DQS_DN<9>")
	)
	(segment
		(start 134.478014 -240.177574)
		(end 134.4676 -240.171478)
		(width 0.088646)
		(layer "In2.Cu")
		(net "M_F_CPU1_SB_DQS_DN<9>")
	)
	(segment
		(start 133.412738 -239.853216)
		(end 133.725666 -239.853216)
		(width 0.088646)
		(layer "In2.Cu")
		(net "M_F_CPU1_SB_DQS_DN<9>")
	)
	(segment
		(start 157.11805 -238.10595)
		(end 153.789634 -241.434366)
		(width 0.18288)
		(layer "In2.Cu")
		(net "M_F_CPU1_SB_DQS_DN<9>")
	)
	(segment
		(start 161.237676 -237.234222)
		(end 160.761934 -237.709964)
		(width 0.18288)
		(layer "In2.Cu")
		(net "M_F_CPU1_SB_DQS_DN<9>")
	)
	(segment
		(start 171.37761 -237.455202)
		(end 171.37761 -237.47095)
		(width 0.16002)
		(layer "In2.Cu")
		(net "M_F_CPU1_SB_DQS_DN<9>")
	)
	(segment
		(start 167.443404 -236.807248)
		(end 167.41521 -236.779054)
		(width 0.16002)
		(layer "In2.Cu")
		(net "M_F_CPU1_SB_DQS_DN<9>")
	)
	(segment
		(start 167.41521 -236.779054)
		(end 167.398954 -236.779054)
		(width 0.16002)
		(layer "In2.Cu")
		(net "M_F_CPU1_SB_DQS_DN<9>")
	)
	(segment
		(start 161.925254 -237.387384)
		(end 161.772092 -237.234222)
		(width 0.18288)
		(layer "In2.Cu")
		(net "M_F_CPU1_SB_DQS_DN<9>")
	)
	(segment
		(start 133.355588 -239.910366)
		(end 133.412738 -239.853216)
		(width 0.088646)
		(layer "In2.Cu")
		(net "M_F_CPU1_SB_DQS_DN<9>")
	)
	(segment
		(start 161.953448 -237.415578)
		(end 161.925254 -237.387384)
		(width 0.16002)
		(layer "In2.Cu")
		(net "M_F_CPU1_SB_DQS_DN<9>")
	)
	(segment
		(start 172.111416 -237.255558)
		(end 171.577254 -237.255558)
		(width 0.18288)
		(layer "In2.Cu")
		(net "M_F_CPU1_SB_DQS_DN<9>")
	)
	(segment
		(start 172.38853 -237.532672)
		(end 172.111416 -237.255558)
		(width 0.18288)
		(layer "In2.Cu")
		(net "M_F_CPU1_SB_DQS_DN<9>")
	)
	(segment
		(start 157.898846 -238.318294)
		(end 157.870652 -238.2901)
		(width 0.16002)
		(layer "In2.Cu")
		(net "M_F_CPU1_SB_DQS_DN<9>")
	)
	(segment
		(start 163.680902 -237.62843)
		(end 163.652708 -237.656624)
		(width 0.16002)
		(layer "In2.Cu")
		(net "M_F_CPU1_SB_DQS_DN<9>")
	)
	(segment
		(start 165.376352 -236.685582)
		(end 165.376352 -236.701838)
		(width 0.16002)
		(layer "In2.Cu")
		(net "M_F_CPU1_SB_DQS_DN<9>")
	)
	(segment
		(start 167.214804 -236.594904)
		(end 167.214804 -236.578648)
		(width 0.16002)
		(layer "In2.Cu")
		(net "M_F_CPU1_SB_DQS_DN<9>")
	)
	(segment
		(start 159.73044 -238.399574)
		(end 159.544004 -238.58601)
		(width 0.18288)
		(layer "In2.Cu")
		(net "M_F_CPU1_SB_DQS_DN<9>")
	)
	(segment
		(start 163.881308 -237.443772)
		(end 163.69665 -237.62843)
		(width 0.16002)
		(layer "In2.Cu")
		(net "M_F_CPU1_SB_DQS_DN<9>")
	)
	(segment
		(start 165.147752 -236.914182)
		(end 164.923724 -237.13821)
		(width 0.18288)
		(layer "In2.Cu")
		(net "M_F_CPU1_SB_DQS_DN<9>")
	)
	(segment
		(start 162.2933 -237.75543)
		(end 162.182048 -237.644178)
		(width 0.18288)
		(layer "In2.Cu")
		(net "M_F_CPU1_SB_DQS_DN<9>")
	)
	(segment
		(start 171.086018 -237.746794)
		(end 169.829734 -237.746794)
		(width 0.18288)
		(layer "In2.Cu")
		(net "M_F_CPU1_SB_DQS_DN<9>")
	)
	(segment
		(start 167.771318 -237.135162)
		(end 167.443404 -236.807248)
		(width 0.18288)
		(layer "In2.Cu")
		(net "M_F_CPU1_SB_DQS_DN<9>")
	)
	(segment
		(start 165.404546 -236.657388)
		(end 165.376352 -236.685582)
		(width 0.16002)
		(layer "In2.Cu")
		(net "M_F_CPU1_SB_DQS_DN<9>")
	)
	(segment
		(start 140.459206 -241.494056)
		(end 140.0429 -241.494056)
		(width 0.088646)
		(layer "In2.Cu")
		(net "M_F_CPU1_SB_DQS_DN<9>")
	)
	(segment
		(start 163.553902 -237.75543)
		(end 162.2933 -237.75543)
		(width 0.18288)
		(layer "In2.Cu")
		(net "M_F_CPU1_SB_DQS_DN<9>")
	)
	(segment
		(start 136.357614 -240.177574)
		(end 136.3472 -240.171478)
		(width 0.088646)
		(layer "In2.Cu")
		(net "M_F_CPU1_SB_DQS_DN<9>")
	)
	(segment
		(start 163.909502 -237.39983)
		(end 163.881308 -237.428024)
		(width 0.16002)
		(layer "In2.Cu")
		(net "M_F_CPU1_SB_DQS_DN<9>")
	)
	(segment
		(start 172.795946 -237.334298)
		(end 172.597572 -237.532672)
		(width 0.18288)
		(layer "In2.Cu")
		(net "M_F_CPU1_SB_DQS_DN<9>")
	)
	(segment
		(start 158.053532 -238.47298)
		(end 158.037784 -238.47298)
		(width 0.16002)
		(layer "In2.Cu")
		(net "M_F_CPU1_SB_DQS_DN<9>")
	)
	(segment
		(start 166.953946 -236.31779)
		(end 165.744144 -236.31779)
		(width 0.18288)
		(layer "In2.Cu")
		(net "M_F_CPU1_SB_DQS_DN<9>")
	)
	(segment
		(start 159.544004 -238.58601)
		(end 158.166562 -238.58601)
		(width 0.18288)
		(layer "In2.Cu")
		(net "M_F_CPU1_SB_DQS_DN<9>")
	)
	(segment
		(start 161.953448 -237.431326)
		(end 161.953448 -237.415578)
		(width 0.16002)
		(layer "In2.Cu")
		(net "M_F_CPU1_SB_DQS_DN<9>")
	)
	(segment
		(start 169.49293 -237.40999)
		(end 169.464736 -237.381796)
		(width 0.16002)
		(layer "In2.Cu")
		(net "M_F_CPU1_SB_DQS_DN<9>")
	)
	(segment
		(start 160.761934 -237.709964)
		(end 159.73044 -238.399574)
		(width 0.18288)
		(layer "In2.Cu")
		(net "M_F_CPU1_SB_DQS_DN<9>")
	)
	(segment
		(start 167.18661 -236.550454)
		(end 166.953946 -236.31779)
		(width 0.18288)
		(layer "In2.Cu")
		(net "M_F_CPU1_SB_DQS_DN<9>")
	)
	(segment
		(start 163.652708 -237.656624)
		(end 163.553902 -237.75543)
		(width 0.18288)
		(layer "In2.Cu")
		(net "M_F_CPU1_SB_DQS_DN<9>")
	)
	(segment
		(start 171.405804 -237.427008)
		(end 171.37761 -237.455202)
		(width 0.16002)
		(layer "In2.Cu")
		(net "M_F_CPU1_SB_DQS_DN<9>")
	)
	(segment
		(start 165.744144 -236.31779)
		(end 165.404546 -236.657388)
		(width 0.18288)
		(layer "In2.Cu")
		(net "M_F_CPU1_SB_DQS_DN<9>")
	)
	(segment
		(start 158.037784 -238.47298)
		(end 157.898846 -238.334042)
		(width 0.16002)
		(layer "In2.Cu")
		(net "M_F_CPU1_SB_DQS_DN<9>")
	)
	(segment
		(start 171.577254 -237.255558)
		(end 171.405804 -237.427008)
		(width 0.18288)
		(layer "In2.Cu")
		(net "M_F_CPU1_SB_DQS_DN<9>")
	)
	(segment
		(start 165.175946 -236.885988)
		(end 165.147752 -236.914182)
		(width 0.16002)
		(layer "In2.Cu")
		(net "M_F_CPU1_SB_DQS_DN<9>")
	)
	(segment
		(start 165.192202 -236.885988)
		(end 165.175946 -236.885988)
		(width 0.16002)
		(layer "In2.Cu")
		(net "M_F_CPU1_SB_DQS_DN<9>")
	)
	(segment
		(start 151.221694 -241.309906)
		(end 151.097234 -241.434366)
		(width 0.18288)
		(layer "In2.Cu")
		(net "M_F_CPU1_SB_DQS_DN<9>")
	)
	(segment
		(start 169.693336 -237.610396)
		(end 169.677588 -237.610396)
		(width 0.16002)
		(layer "In2.Cu")
		(net "M_F_CPU1_SB_DQS_DN<9>")
	)
	(segment
		(start 172.597572 -237.532672)
		(end 172.38853 -237.532672)
		(width 0.18288)
		(layer "In2.Cu")
		(net "M_F_CPU1_SB_DQS_DN<9>")
	)
	(arc
		(start 136.3472 -240.171478)
		(mid 136.069022 -240.101786)
		(end 135.792464 -240.177574)
		(width 0.088646)
		(layer "In2.Cu")
		(net "M_F_CPU1_SB_DQS_DN<9>")
	)
	(arc
		(start 137.202164 -240.991644)
		(mid 137.014966 -241.041787)
		(end 136.827768 -240.991644)
		(width 0.088646)
		(layer "In2.Cu")
		(net "M_F_CPU1_SB_DQS_DN<9>")
	)
	(arc
		(start 138.049762 -241.481102)
		(mid 137.97707 -241.203897)
		(end 137.777728 -240.997994)
		(width 0.088646)
		(layer "In2.Cu")
		(net "M_F_CPU1_SB_DQS_DN<9>")
	)
	(arc
		(start 137.767568 -240.991644)
		(mid 137.484866 -240.915868)
		(end 137.202164 -240.991644)
		(width 0.088646)
		(layer "In2.Cu")
		(net "M_F_CPU1_SB_DQS_DN<9>")
	)
	(arc
		(start 134.4676 -240.171478)
		(mid 134.189422 -240.101786)
		(end 133.912864 -240.177574)
		(width 0.088646)
		(layer "In2.Cu")
		(net "M_F_CPU1_SB_DQS_DN<9>")
	)
	(arc
		(start 136.640316 -240.653062)
		(mid 136.561097 -240.378377)
		(end 136.357614 -240.177574)
		(width 0.088646)
		(layer "In2.Cu")
		(net "M_F_CPU1_SB_DQS_DN<9>")
	)
	(arc
		(start 135.792972 -240.178082)
		(mid 135.605266 -240.228411)
		(end 135.41756 -240.178082)
		(width 0.088646)
		(layer "In2.Cu")
		(net "M_F_CPU1_SB_DQS_DN<9>")
	)
	(arc
		(start 137.777982 -240.99774)
		(mid 137.772792 -240.994663)
		(end 137.767568 -240.991644)
		(width 0.088646)
		(layer "In2.Cu")
		(net "M_F_CPU1_SB_DQS_DN<9>")
	)
	(arc
		(start 133.529578 -240.172494)
		(mid 133.413769 -240.060565)
		(end 133.355588 -239.910366)
		(width 0.088646)
		(layer "In2.Cu")
		(net "M_F_CPU1_SB_DQS_DN<9>")
	)
	(arc
		(start 135.407654 -240.171478)
		(mid 135.129222 -240.101664)
		(end 134.85241 -240.177574)
		(width 0.088646)
		(layer "In2.Cu")
		(net "M_F_CPU1_SB_DQS_DN<9>")
	)
	(arc
		(start 134.85241 -240.177574)
		(mid 134.665212 -240.227717)
		(end 134.478014 -240.177574)
		(width 0.088646)
		(layer "In2.Cu")
		(net "M_F_CPU1_SB_DQS_DN<9>")
	)
	(arc
		(start 133.912864 -240.177574)
		(mid 133.725666 -240.227717)
		(end 133.538468 -240.177574)
		(width 0.088646)
		(layer "In2.Cu")
		(net "M_F_CPU1_SB_DQS_DN<9>")
	)
	(arc
		(start 136.818878 -240.986564)
		(mid 136.687964 -240.850204)
		(end 136.640316 -240.667286)
		(width 0.088646)
		(layer "In2.Cu")
		(net "M_F_CPU1_SB_DQS_DN<9>")
	)
	(segment
		(start 180.43398 -199.441816)
		(end 182.444136 -199.441816)
		(width 0.1016)
		(layer "F.Cu")
		(net "M_F_CPU1_SB_DQS_DN<8>")
	)
	(segment
		(start 178.53152 -199.866758)
		(end 178.802792 -199.595486)
		(width 0.20066)
		(layer "F.Cu")
		(net "M_F_CPU1_SB_DQS_DN<8>")
	)
	(segment
		(start 183.549544 -199.166988)
		(end 183.99506 -199.612504)
		(width 0.20066)
		(layer "F.Cu")
		(net "M_F_CPU1_SB_DQS_DN<8>")
	)
	(segment
		(start 185.041032 -199.866758)
		(end 185.544714 -199.866758)
		(width 0.20066)
		(layer "F.Cu")
		(net "M_F_CPU1_SB_DQS_DN<8>")
	)
	(segment
		(start 183.99506 -199.612504)
		(end 184.786778 -199.612504)
		(width 0.20066)
		(layer "F.Cu")
		(net "M_F_CPU1_SB_DQS_DN<8>")
	)
	(segment
		(start 176.896014 -199.866758)
		(end 178.000914 -199.866758)
		(width 0.20066)
		(layer "F.Cu")
		(net "M_F_CPU1_SB_DQS_DN<8>")
	)
	(segment
		(start 184.786778 -199.612504)
		(end 185.041032 -199.866758)
		(width 0.20066)
		(layer "F.Cu")
		(net "M_F_CPU1_SB_DQS_DN<8>")
	)
	(segment
		(start 180.427884 -199.447912)
		(end 180.43398 -199.441816)
		(width 0.1016)
		(layer "F.Cu")
		(net "M_F_CPU1_SB_DQS_DN<8>")
	)
	(segment
		(start 182.444136 -199.441816)
		(end 182.455058 -199.452738)
		(width 0.1016)
		(layer "F.Cu")
		(net "M_F_CPU1_SB_DQS_DN<8>")
	)
	(segment
		(start 131.376166 -228.180646)
		(end 131.376166 -227.64496)
		(width 0.20066)
		(layer "F.Cu")
		(net "M_F_CPU1_SB_DQS_DN<8>")
	)
	(segment
		(start 178.000914 -199.866758)
		(end 178.53152 -199.866758)
		(width 0.20066)
		(layer "F.Cu")
		(net "M_F_CPU1_SB_DQS_DN<8>")
	)
	(segment
		(start 178.802792 -199.595486)
		(end 179.286154 -199.595486)
		(width 0.20066)
		(layer "F.Cu")
		(net "M_F_CPU1_SB_DQS_DN<8>")
	)
	(segment
		(start 179.711096 -199.170544)
		(end 179.833524 -199.170544)
		(width 0.20066)
		(layer "F.Cu")
		(net "M_F_CPU1_SB_DQS_DN<8>")
	)
	(segment
		(start 182.773828 -199.452738)
		(end 183.059578 -199.166988)
		(width 0.20066)
		(layer "F.Cu")
		(net "M_F_CPU1_SB_DQS_DN<8>")
	)
	(segment
		(start 131.375912 -228.1809)
		(end 131.376166 -228.180646)
		(width 0.20066)
		(layer "F.Cu")
		(net "M_F_CPU1_SB_DQS_DN<8>")
	)
	(segment
		(start 180.423058 -199.447912)
		(end 180.427884 -199.447912)
		(width 0.101854)
		(layer "F.Cu")
		(net "M_F_CPU1_SB_DQS_DN<8>")
	)
	(segment
		(start 179.833524 -199.170544)
		(end 180.110892 -199.447912)
		(width 0.20066)
		(layer "F.Cu")
		(net "M_F_CPU1_SB_DQS_DN<8>")
	)
	(segment
		(start 180.110892 -199.447912)
		(end 180.423058 -199.447912)
		(width 0.20066)
		(layer "F.Cu")
		(net "M_F_CPU1_SB_DQS_DN<8>")
	)
	(segment
		(start 183.059578 -199.166988)
		(end 183.549544 -199.166988)
		(width 0.20066)
		(layer "F.Cu")
		(net "M_F_CPU1_SB_DQS_DN<8>")
	)
	(segment
		(start 179.286154 -199.595486)
		(end 179.711096 -199.170544)
		(width 0.20066)
		(layer "F.Cu")
		(net "M_F_CPU1_SB_DQS_DN<8>")
	)
	(segment
		(start 182.455058 -199.452738)
		(end 182.773828 -199.452738)
		(width 0.20066)
		(layer "F.Cu")
		(net "M_F_CPU1_SB_DQS_DN<8>")
	)
	(segment
		(start 136.272778 -222.443294)
		(end 136.262364 -222.437198)
		(width 0.088646)
		(layer "In4.Cu")
		(net "M_F_CPU1_SB_DQS_DN<8>")
	)
	(segment
		(start 150.941786 -211.378292)
		(end 140.700506 -221.619572)
		(width 0.18288)
		(layer "In4.Cu")
		(net "M_F_CPU1_SB_DQS_DN<8>")
	)
	(segment
		(start 136.170416 -223.557084)
		(end 136.170416 -223.585532)
		(width 0.088646)
		(layer "In4.Cu")
		(net "M_F_CPU1_SB_DQS_DN<8>")
	)
	(segment
		(start 161.614866 -201.152252)
		(end 161.325306 -200.862692)
		(width 0.18288)
		(layer "In4.Cu")
		(net "M_F_CPU1_SB_DQS_DN<8>")
	)
	(segment
		(start 164.494464 -200.861422)
		(end 164.201094 -201.154792)
		(width 0.18288)
		(layer "In4.Cu")
		(net "M_F_CPU1_SB_DQS_DN<8>")
	)
	(segment
		(start 136.839706 -222.430086)
		(end 136.827514 -222.437198)
		(width 0.088646)
		(layer "In4.Cu")
		(net "M_F_CPU1_SB_DQS_DN<8>")
	)
	(segment
		(start 131.3815 -227.639626)
		(end 131.376166 -227.64496)
		(width 0.088646)
		(layer "In4.Cu")
		(net "M_F_CPU1_SB_DQS_DN<8>")
	)
	(segment
		(start 139.317984 -221.559628)
		(end 139.178538 -221.699074)
		(width 0.088646)
		(layer "In4.Cu")
		(net "M_F_CPU1_SB_DQS_DN<8>")
	)
	(segment
		(start 173.253908 -201.728324)
		(end 172.988224 -201.994008)
		(width 0.18288)
		(layer "In4.Cu")
		(net "M_F_CPU1_SB_DQS_DN<8>")
	)
	(segment
		(start 170.63085 -201.404982)
		(end 169.92219 -201.404982)
		(width 0.18288)
		(layer "In4.Cu")
		(net "M_F_CPU1_SB_DQS_DN<8>")
	)
	(segment
		(start 152.349454 -207.98028)
		(end 150.941786 -211.378292)
		(width 0.18288)
		(layer "In4.Cu")
		(net "M_F_CPU1_SB_DQS_DN<8>")
	)
	(segment
		(start 163.572952 -200.89241)
		(end 162.253676 -200.89241)
		(width 0.18288)
		(layer "In4.Cu")
		(net "M_F_CPU1_SB_DQS_DN<8>")
	)
	(segment
		(start 139.67333 -221.559628)
		(end 139.317984 -221.559628)
		(width 0.088646)
		(layer "In4.Cu")
		(net "M_F_CPU1_SB_DQS_DN<8>")
	)
	(segment
		(start 172.604176 -201.994008)
		(end 172.312584 -201.702416)
		(width 0.18288)
		(layer "In4.Cu")
		(net "M_F_CPU1_SB_DQS_DN<8>")
	)
	(segment
		(start 135.879078 -223.080834)
		(end 135.887968 -223.085914)
		(width 0.088646)
		(layer "In4.Cu")
		(net "M_F_CPU1_SB_DQS_DN<8>")
	)
	(segment
		(start 139.756642 -221.619572)
		(end 139.733274 -221.619572)
		(width 0.088646)
		(layer "In4.Cu")
		(net "M_F_CPU1_SB_DQS_DN<8>")
	)
	(segment
		(start 134.947406 -225.693478)
		(end 134.939278 -225.69805)
		(width 0.088646)
		(layer "In4.Cu")
		(net "M_F_CPU1_SB_DQS_DN<8>")
	)
	(segment
		(start 167.892222 -200.861422)
		(end 164.494464 -200.861422)
		(width 0.18288)
		(layer "In4.Cu")
		(net "M_F_CPU1_SB_DQS_DN<8>")
	)
	(segment
		(start 140.700506 -221.619572)
		(end 139.756642 -221.619572)
		(width 0.18288)
		(layer "In4.Cu")
		(net "M_F_CPU1_SB_DQS_DN<8>")
	)
	(segment
		(start 176.649126 -199.61987)
		(end 176.15408 -199.61987)
		(width 0.18288)
		(layer "In4.Cu")
		(net "M_F_CPU1_SB_DQS_DN<8>")
	)
	(segment
		(start 176.15408 -199.61987)
		(end 174.045626 -201.728324)
		(width 0.18288)
		(layer "In4.Cu")
		(net "M_F_CPU1_SB_DQS_DN<8>")
	)
	(segment
		(start 176.896014 -199.866758)
		(end 176.649126 -199.61987)
		(width 0.18288)
		(layer "In4.Cu")
		(net "M_F_CPU1_SB_DQS_DN<8>")
	)
	(segment
		(start 169.92219 -201.404982)
		(end 169.648886 -201.678286)
		(width 0.18288)
		(layer "In4.Cu")
		(net "M_F_CPU1_SB_DQS_DN<8>")
	)
	(segment
		(start 155.95219 -202.588876)
		(end 152.349454 -207.98028)
		(width 0.18288)
		(layer "In4.Cu")
		(net "M_F_CPU1_SB_DQS_DN<8>")
	)
	(segment
		(start 132.756656 -228.04247)
		(end 132.322062 -228.04247)
		(width 0.088646)
		(layer "In4.Cu")
		(net "M_F_CPU1_SB_DQS_DN<8>")
	)
	(segment
		(start 132.973064 -228.134672)
		(end 132.863336 -228.071172)
		(width 0.088646)
		(layer "In4.Cu")
		(net "M_F_CPU1_SB_DQS_DN<8>")
	)
	(segment
		(start 172.988224 -201.994008)
		(end 172.604176 -201.994008)
		(width 0.18288)
		(layer "In4.Cu")
		(net "M_F_CPU1_SB_DQS_DN<8>")
	)
	(segment
		(start 174.045626 -201.728324)
		(end 173.253908 -201.728324)
		(width 0.18288)
		(layer "In4.Cu")
		(net "M_F_CPU1_SB_DQS_DN<8>")
	)
	(segment
		(start 135.887968 -224.065084)
		(end 135.879078 -224.070164)
		(width 0.088646)
		(layer "In4.Cu")
		(net "M_F_CPU1_SB_DQS_DN<8>")
	)
	(segment
		(start 164.201094 -201.154792)
		(end 163.835334 -201.154792)
		(width 0.18288)
		(layer "In4.Cu")
		(net "M_F_CPU1_SB_DQS_DN<8>")
	)
	(segment
		(start 134.48411 -226.50323)
		(end 134.478776 -226.506278)
		(width 0.088646)
		(layer "In4.Cu")
		(net "M_F_CPU1_SB_DQS_DN<8>")
	)
	(segment
		(start 134.290816 -226.822508)
		(end 134.290816 -226.84105)
		(width 0.088646)
		(layer "In4.Cu")
		(net "M_F_CPU1_SB_DQS_DN<8>")
	)
	(segment
		(start 135.887968 -222.437198)
		(end 135.879078 -222.442278)
		(width 0.088646)
		(layer "In4.Cu")
		(net "M_F_CPU1_SB_DQS_DN<8>")
	)
	(segment
		(start 139.733274 -221.619572)
		(end 139.67333 -221.559628)
		(width 0.088646)
		(layer "In4.Cu")
		(net "M_F_CPU1_SB_DQS_DN<8>")
	)
	(segment
		(start 131.945888 -227.702364)
		(end 131.88315 -227.639626)
		(width 0.088646)
		(layer "In4.Cu")
		(net "M_F_CPU1_SB_DQS_DN<8>")
	)
	(segment
		(start 168.709086 -201.678286)
		(end 167.892222 -200.861422)
		(width 0.18288)
		(layer "In4.Cu")
		(net "M_F_CPU1_SB_DQS_DN<8>")
	)
	(segment
		(start 161.325306 -200.862692)
		(end 157.678374 -200.862692)
		(width 0.18288)
		(layer "In4.Cu")
		(net "M_F_CPU1_SB_DQS_DN<8>")
	)
	(segment
		(start 170.928284 -201.702416)
		(end 170.63085 -201.404982)
		(width 0.18288)
		(layer "In4.Cu")
		(net "M_F_CPU1_SB_DQS_DN<8>")
	)
	(segment
		(start 134.948168 -225.69297)
		(end 134.947406 -225.693478)
		(width 0.088646)
		(layer "In4.Cu")
		(net "M_F_CPU1_SB_DQS_DN<8>")
	)
	(segment
		(start 163.835334 -201.154792)
		(end 163.572952 -200.89241)
		(width 0.18288)
		(layer "In4.Cu")
		(net "M_F_CPU1_SB_DQS_DN<8>")
	)
	(segment
		(start 134.478776 -226.506278)
		(end 134.478014 -226.506786)
		(width 0.088646)
		(layer "In4.Cu")
		(net "M_F_CPU1_SB_DQS_DN<8>")
	)
	(segment
		(start 134.008368 -227.320602)
		(end 133.999478 -227.325682)
		(width 0.088646)
		(layer "In4.Cu")
		(net "M_F_CPU1_SB_DQS_DN<8>")
	)
	(segment
		(start 132.863336 -228.071172)
		(end 132.756656 -228.04247)
		(width 0.088646)
		(layer "In4.Cu")
		(net "M_F_CPU1_SB_DQS_DN<8>")
	)
	(segment
		(start 139.178538 -221.699074)
		(end 138.894566 -221.699074)
		(width 0.088646)
		(layer "In4.Cu")
		(net "M_F_CPU1_SB_DQS_DN<8>")
	)
	(segment
		(start 161.993834 -201.152252)
		(end 161.614866 -201.152252)
		(width 0.18288)
		(layer "In4.Cu")
		(net "M_F_CPU1_SB_DQS_DN<8>")
	)
	(segment
		(start 131.88315 -227.639626)
		(end 131.3815 -227.639626)
		(width 0.088646)
		(layer "In4.Cu")
		(net "M_F_CPU1_SB_DQS_DN<8>")
	)
	(segment
		(start 157.678374 -200.862692)
		(end 155.95219 -202.588876)
		(width 0.18288)
		(layer "In4.Cu")
		(net "M_F_CPU1_SB_DQS_DN<8>")
	)
	(segment
		(start 133.820916 -227.64496)
		(end 133.820916 -227.663502)
		(width 0.088646)
		(layer "In4.Cu")
		(net "M_F_CPU1_SB_DQS_DN<8>")
	)
	(segment
		(start 172.312584 -201.702416)
		(end 170.928284 -201.702416)
		(width 0.18288)
		(layer "In4.Cu")
		(net "M_F_CPU1_SB_DQS_DN<8>")
	)
	(segment
		(start 162.253676 -200.89241)
		(end 161.993834 -201.152252)
		(width 0.18288)
		(layer "In4.Cu")
		(net "M_F_CPU1_SB_DQS_DN<8>")
	)
	(segment
		(start 135.230616 -225.203258)
		(end 135.230616 -225.2218)
		(width 0.088646)
		(layer "In4.Cu")
		(net "M_F_CPU1_SB_DQS_DN<8>")
	)
	(segment
		(start 137.297668 -221.623382)
		(end 137.288778 -221.628462)
		(width 0.088646)
		(layer "In4.Cu")
		(net "M_F_CPU1_SB_DQS_DN<8>")
	)
	(segment
		(start 135.418068 -224.8789)
		(end 135.409178 -224.88398)
		(width 0.088646)
		(layer "In4.Cu")
		(net "M_F_CPU1_SB_DQS_DN<8>")
	)
	(segment
		(start 169.648886 -201.678286)
		(end 168.709086 -201.678286)
		(width 0.18288)
		(layer "In4.Cu")
		(net "M_F_CPU1_SB_DQS_DN<8>")
	)
	(segment
		(start 135.424164 -224.875344)
		(end 135.418068 -224.8789)
		(width 0.088646)
		(layer "In4.Cu")
		(net "M_F_CPU1_SB_DQS_DN<8>")
	)
	(arc
		(start 137.288778 -221.628462)
		(mid 137.157864 -221.764822)
		(end 137.110216 -221.94774)
		(width 0.088646)
		(layer "In4.Cu")
		(net "M_F_CPU1_SB_DQS_DN<8>")
	)
	(arc
		(start 136.262364 -222.437198)
		(mid 136.075166 -222.387055)
		(end 135.887968 -222.437198)
		(width 0.088646)
		(layer "In4.Cu")
		(net "M_F_CPU1_SB_DQS_DN<8>")
	)
	(arc
		(start 135.70077 -222.773748)
		(mid 135.751263 -222.949726)
		(end 135.879078 -223.080834)
		(width 0.088646)
		(layer "In4.Cu")
		(net "M_F_CPU1_SB_DQS_DN<8>")
	)
	(arc
		(start 135.700516 -224.389442)
		(mid 135.6266 -224.668944)
		(end 135.424164 -224.875344)
		(width 0.088646)
		(layer "In4.Cu")
		(net "M_F_CPU1_SB_DQS_DN<8>")
	)
	(arc
		(start 135.879078 -224.070164)
		(mid 135.748164 -224.206524)
		(end 135.700516 -224.389442)
		(width 0.088646)
		(layer "In4.Cu")
		(net "M_F_CPU1_SB_DQS_DN<8>")
	)
	(arc
		(start 138.611864 -221.623382)
		(mid 138.424666 -221.573239)
		(end 138.237468 -221.623382)
		(width 0.088646)
		(layer "In4.Cu")
		(net "M_F_CPU1_SB_DQS_DN<8>")
	)
	(arc
		(start 133.538468 -228.134672)
		(mid 133.255766 -228.210414)
		(end 132.973064 -228.134672)
		(width 0.088646)
		(layer "In4.Cu")
		(net "M_F_CPU1_SB_DQS_DN<8>")
	)
	(arc
		(start 134.939278 -225.69805)
		(mid 134.808364 -225.83441)
		(end 134.760716 -226.017328)
		(width 0.088646)
		(layer "In4.Cu")
		(net "M_F_CPU1_SB_DQS_DN<8>")
	)
	(arc
		(start 138.237468 -221.623382)
		(mid 137.954766 -221.699158)
		(end 137.672064 -221.623382)
		(width 0.088646)
		(layer "In4.Cu")
		(net "M_F_CPU1_SB_DQS_DN<8>")
	)
	(arc
		(start 136.170416 -223.585532)
		(mid 136.092305 -223.862481)
		(end 135.887968 -224.065084)
		(width 0.088646)
		(layer "In4.Cu")
		(net "M_F_CPU1_SB_DQS_DN<8>")
	)
	(arc
		(start 132.178806 -227.993702)
		(mid 132.023473 -227.879104)
		(end 131.945888 -227.702364)
		(width 0.088646)
		(layer "In4.Cu")
		(net "M_F_CPU1_SB_DQS_DN<8>")
	)
	(arc
		(start 137.110216 -221.94774)
		(mid 137.037981 -222.224264)
		(end 136.839706 -222.430086)
		(width 0.088646)
		(layer "In4.Cu")
		(net "M_F_CPU1_SB_DQS_DN<8>")
	)
	(arc
		(start 135.887968 -223.085914)
		(mid 136.090254 -223.284895)
		(end 136.170416 -223.557084)
		(width 0.088646)
		(layer "In4.Cu")
		(net "M_F_CPU1_SB_DQS_DN<8>")
	)
	(arc
		(start 134.290816 -226.84105)
		(mid 134.212705 -227.117999)
		(end 134.008368 -227.320602)
		(width 0.088646)
		(layer "In4.Cu")
		(net "M_F_CPU1_SB_DQS_DN<8>")
	)
	(arc
		(start 135.700516 -222.754952)
		(mid 135.700526 -222.764352)
		(end 135.70077 -222.773748)
		(width 0.088646)
		(layer "In4.Cu")
		(net "M_F_CPU1_SB_DQS_DN<8>")
	)
	(arc
		(start 135.409178 -224.88398)
		(mid 135.278264 -225.02034)
		(end 135.230616 -225.203258)
		(width 0.088646)
		(layer "In4.Cu")
		(net "M_F_CPU1_SB_DQS_DN<8>")
	)
	(arc
		(start 134.478014 -226.506786)
		(mid 134.343081 -226.64014)
		(end 134.290816 -226.822508)
		(width 0.088646)
		(layer "In4.Cu")
		(net "M_F_CPU1_SB_DQS_DN<8>")
	)
	(arc
		(start 138.894566 -221.699074)
		(mid 138.748222 -221.679866)
		(end 138.611864 -221.623382)
		(width 0.088646)
		(layer "In4.Cu")
		(net "M_F_CPU1_SB_DQS_DN<8>")
	)
	(arc
		(start 134.760716 -226.017328)
		(mid 134.686725 -226.296894)
		(end 134.48411 -226.50323)
		(width 0.088646)
		(layer "In4.Cu")
		(net "M_F_CPU1_SB_DQS_DN<8>")
	)
	(arc
		(start 135.230616 -225.2218)
		(mid 135.150454 -225.493989)
		(end 134.948168 -225.69297)
		(width 0.088646)
		(layer "In4.Cu")
		(net "M_F_CPU1_SB_DQS_DN<8>")
	)
	(arc
		(start 132.229098 -228.017578)
		(mid 132.204393 -228.004711)
		(end 132.178806 -227.993702)
		(width 0.088646)
		(layer "In4.Cu")
		(net "M_F_CPU1_SB_DQS_DN<8>")
	)
	(arc
		(start 137.672064 -221.623382)
		(mid 137.484866 -221.573239)
		(end 137.297668 -221.623382)
		(width 0.088646)
		(layer "In4.Cu")
		(net "M_F_CPU1_SB_DQS_DN<8>")
	)
	(arc
		(start 132.322062 -228.04247)
		(mid 132.273948 -228.036114)
		(end 132.229098 -228.017578)
		(width 0.088646)
		(layer "In4.Cu")
		(net "M_F_CPU1_SB_DQS_DN<8>")
	)
	(arc
		(start 136.827514 -222.437198)
		(mid 136.550955 -222.512941)
		(end 136.272778 -222.443294)
		(width 0.088646)
		(layer "In4.Cu")
		(net "M_F_CPU1_SB_DQS_DN<8>")
	)
	(arc
		(start 135.879078 -222.442278)
		(mid 135.749789 -222.575764)
		(end 135.700516 -222.754952)
		(width 0.088646)
		(layer "In4.Cu")
		(net "M_F_CPU1_SB_DQS_DN<8>")
	)
	(arc
		(start 133.820916 -227.663502)
		(mid 133.740754 -227.935691)
		(end 133.538468 -228.134672)
		(width 0.088646)
		(layer "In4.Cu")
		(net "M_F_CPU1_SB_DQS_DN<8>")
	)
	(arc
		(start 133.999478 -227.325682)
		(mid 133.868564 -227.462042)
		(end 133.820916 -227.64496)
		(width 0.088646)
		(layer "In4.Cu")
		(net "M_F_CPU1_SB_DQS_DN<8>")
	)
	(segment
		(start 138.894312 -223.297496)
		(end 138.894312 -222.761556)
		(width 0.20066)
		(layer "F.Cu")
		(net "M_F_CPU1_SB_DQS_DN<7>")
	)
	(segment
		(start 180.43398 -208.79181)
		(end 182.444136 -208.79181)
		(width 0.1016)
		(layer "F.Cu")
		(net "M_F_CPU1_SB_DQS_DN<7>")
	)
	(segment
		(start 183.99506 -208.962498)
		(end 184.786778 -208.962498)
		(width 0.20066)
		(layer "F.Cu")
		(net "M_F_CPU1_SB_DQS_DN<7>")
	)
	(segment
		(start 180.110892 -208.797906)
		(end 180.423058 -208.797906)
		(width 0.20066)
		(layer "F.Cu")
		(net "M_F_CPU1_SB_DQS_DN<7>")
	)
	(segment
		(start 184.786778 -208.962498)
		(end 185.041032 -209.216752)
		(width 0.20066)
		(layer "F.Cu")
		(net "M_F_CPU1_SB_DQS_DN<7>")
	)
	(segment
		(start 179.286154 -208.94548)
		(end 179.711096 -208.520538)
		(width 0.20066)
		(layer "F.Cu")
		(net "M_F_CPU1_SB_DQS_DN<7>")
	)
	(segment
		(start 180.423058 -208.797906)
		(end 180.427884 -208.797906)
		(width 0.101854)
		(layer "F.Cu")
		(net "M_F_CPU1_SB_DQS_DN<7>")
	)
	(segment
		(start 179.833524 -208.520538)
		(end 180.110892 -208.797906)
		(width 0.20066)
		(layer "F.Cu")
		(net "M_F_CPU1_SB_DQS_DN<7>")
	)
	(segment
		(start 178.53152 -209.216752)
		(end 178.802792 -208.94548)
		(width 0.20066)
		(layer "F.Cu")
		(net "M_F_CPU1_SB_DQS_DN<7>")
	)
	(segment
		(start 182.773828 -208.802732)
		(end 183.059578 -208.516982)
		(width 0.20066)
		(layer "F.Cu")
		(net "M_F_CPU1_SB_DQS_DN<7>")
	)
	(segment
		(start 176.896014 -209.216752)
		(end 178.000914 -209.216752)
		(width 0.20066)
		(layer "F.Cu")
		(net "M_F_CPU1_SB_DQS_DN<7>")
	)
	(segment
		(start 180.427884 -208.797906)
		(end 180.43398 -208.79181)
		(width 0.1016)
		(layer "F.Cu")
		(net "M_F_CPU1_SB_DQS_DN<7>")
	)
	(segment
		(start 182.455058 -208.802732)
		(end 182.773828 -208.802732)
		(width 0.20066)
		(layer "F.Cu")
		(net "M_F_CPU1_SB_DQS_DN<7>")
	)
	(segment
		(start 183.549544 -208.516982)
		(end 183.99506 -208.962498)
		(width 0.20066)
		(layer "F.Cu")
		(net "M_F_CPU1_SB_DQS_DN<7>")
	)
	(segment
		(start 178.000914 -209.216752)
		(end 178.53152 -209.216752)
		(width 0.20066)
		(layer "F.Cu")
		(net "M_F_CPU1_SB_DQS_DN<7>")
	)
	(segment
		(start 183.059578 -208.516982)
		(end 183.549544 -208.516982)
		(width 0.20066)
		(layer "F.Cu")
		(net "M_F_CPU1_SB_DQS_DN<7>")
	)
	(segment
		(start 178.802792 -208.94548)
		(end 179.286154 -208.94548)
		(width 0.20066)
		(layer "F.Cu")
		(net "M_F_CPU1_SB_DQS_DN<7>")
	)
	(segment
		(start 182.444136 -208.79181)
		(end 182.455058 -208.802732)
		(width 0.1016)
		(layer "F.Cu")
		(net "M_F_CPU1_SB_DQS_DN<7>")
	)
	(segment
		(start 185.041032 -209.216752)
		(end 185.544714 -209.216752)
		(width 0.20066)
		(layer "F.Cu")
		(net "M_F_CPU1_SB_DQS_DN<7>")
	)
	(segment
		(start 179.711096 -208.520538)
		(end 179.833524 -208.520538)
		(width 0.20066)
		(layer "F.Cu")
		(net "M_F_CPU1_SB_DQS_DN<7>")
	)
	(segment
		(start 165.435026 -207.118204)
		(end 165.002972 -207.118204)
		(width 0.18288)
		(layer "In2.Cu")
		(net "M_F_CPU1_SB_DQS_DN<7>")
	)
	(segment
		(start 151.623522 -211.728812)
		(end 151.4475 -211.728812)
		(width 0.18288)
		(layer "In2.Cu")
		(net "M_F_CPU1_SB_DQS_DN<7>")
	)
	(segment
		(start 175.773842 -209.21091)
		(end 175.017176 -209.21091)
		(width 0.18288)
		(layer "In2.Cu")
		(net "M_F_CPU1_SB_DQS_DN<7>")
	)
	(segment
		(start 171.411646 -208.193386)
		(end 171.383452 -208.165192)
		(width 0.16002)
		(layer "In2.Cu")
		(net "M_F_CPU1_SB_DQS_DN<7>")
	)
	(segment
		(start 155.255468 -207.920844)
		(end 154.86761 -208.308702)
		(width 0.18288)
		(layer "In2.Cu")
		(net "M_F_CPU1_SB_DQS_DN<7>")
	)
	(segment
		(start 173.092872 -208.793588)
		(end 172.491654 -208.793588)
		(width 0.18288)
		(layer "In2.Cu")
		(net "M_F_CPU1_SB_DQS_DN<7>")
	)
	(segment
		(start 151.059642 -212.11667)
		(end 151.059642 -212.292692)
		(width 0.18288)
		(layer "In2.Cu")
		(net "M_F_CPU1_SB_DQS_DN<7>")
	)
	(segment
		(start 141.120876 -221.580202)
		(end 141.120876 -221.580456)
		(width 0.088646)
		(layer "In2.Cu")
		(net "M_F_CPU1_SB_DQS_DN<7>")
	)
	(segment
		(start 161.06013 -205.97749)
		(end 160.163002 -205.97749)
		(width 0.18288)
		(layer "In2.Cu")
		(net "M_F_CPU1_SB_DQS_DN<7>")
	)
	(segment
		(start 149.543516 -213.632796)
		(end 149.155658 -214.020654)
		(width 0.18288)
		(layer "In2.Cu")
		(net "M_F_CPU1_SB_DQS_DN<7>")
	)
	(segment
		(start 169.367454 -208.33715)
		(end 168.35501 -208.33715)
		(width 0.18288)
		(layer "In2.Cu")
		(net "M_F_CPU1_SB_DQS_DN<7>")
	)
	(segment
		(start 150.67153 -212.680804)
		(end 150.495508 -212.680804)
		(width 0.18288)
		(layer "In2.Cu")
		(net "M_F_CPU1_SB_DQS_DN<7>")
	)
	(segment
		(start 153.351484 -209.824828)
		(end 152.963626 -210.212686)
		(width 0.18288)
		(layer "In2.Cu")
		(net "M_F_CPU1_SB_DQS_DN<7>")
	)
	(segment
		(start 151.059642 -212.292692)
		(end 150.67153 -212.680804)
		(width 0.18288)
		(layer "In2.Cu")
		(net "M_F_CPU1_SB_DQS_DN<7>")
	)
	(segment
		(start 150.10765 -213.068662)
		(end 150.10765 -213.244684)
		(width 0.18288)
		(layer "In2.Cu")
		(net "M_F_CPU1_SB_DQS_DN<7>")
	)
	(segment
		(start 172.491654 -208.793588)
		(end 172.18279 -208.484724)
		(width 0.18288)
		(layer "In2.Cu")
		(net "M_F_CPU1_SB_DQS_DN<7>")
	)
	(segment
		(start 169.536618 -208.152238)
		(end 169.536618 -208.167986)
		(width 0.16002)
		(layer "In2.Cu")
		(net "M_F_CPU1_SB_DQS_DN<7>")
	)
	(segment
		(start 176.896014 -209.216752)
		(end 176.609248 -208.929986)
		(width 0.18288)
		(layer "In2.Cu")
		(net "M_F_CPU1_SB_DQS_DN<7>")
	)
	(segment
		(start 172.18279 -208.484724)
		(end 171.702984 -208.484724)
		(width 0.18288)
		(layer "In2.Cu")
		(net "M_F_CPU1_SB_DQS_DN<7>")
	)
	(segment
		(start 174.608744 -208.78673)
		(end 174.592996 -208.78673)
		(width 0.16002)
		(layer "In2.Cu")
		(net "M_F_CPU1_SB_DQS_DN<7>")
	)
	(segment
		(start 165.002972 -207.118204)
		(end 164.725858 -206.84109)
		(width 0.18288)
		(layer "In2.Cu")
		(net "M_F_CPU1_SB_DQS_DN<7>")
	)
	(segment
		(start 149.155658 -214.020654)
		(end 149.155658 -214.196676)
		(width 0.18288)
		(layer "In2.Cu")
		(net "M_F_CPU1_SB_DQS_DN<7>")
	)
	(segment
		(start 161.35096 -206.26832)
		(end 161.06013 -205.97749)
		(width 0.18288)
		(layer "In2.Cu")
		(net "M_F_CPU1_SB_DQS_DN<7>")
	)
	(segment
		(start 141.780514 -220.927168)
		(end 141.173708 -221.533974)
		(width 0.088646)
		(layer "In2.Cu")
		(net "M_F_CPU1_SB_DQS_DN<7>")
	)
	(segment
		(start 152.011634 -211.164678)
		(end 152.011634 -211.3407)
		(width 0.18288)
		(layer "In2.Cu")
		(net "M_F_CPU1_SB_DQS_DN<7>")
	)
	(segment
		(start 154.86761 -208.484724)
		(end 154.479498 -208.872836)
		(width 0.18288)
		(layer "In2.Cu")
		(net "M_F_CPU1_SB_DQS_DN<7>")
	)
	(segment
		(start 171.702984 -208.484724)
		(end 171.411646 -208.193386)
		(width 0.18288)
		(layer "In2.Cu")
		(net "M_F_CPU1_SB_DQS_DN<7>")
	)
	(segment
		(start 171.200572 -207.982312)
		(end 171.10583 -207.88757)
		(width 0.18288)
		(layer "In2.Cu")
		(net "M_F_CPU1_SB_DQS_DN<7>")
	)
	(segment
		(start 139.647676 -222.43669)
		(end 139.646914 -222.437198)
		(width 0.088646)
		(layer "In2.Cu")
		(net "M_F_CPU1_SB_DQS_DN<7>")
	)
	(segment
		(start 142.16126 -220.927168)
		(end 141.780514 -220.927168)
		(width 0.088646)
		(layer "In2.Cu")
		(net "M_F_CPU1_SB_DQS_DN<7>")
	)
	(segment
		(start 148.203666 -215.148668)
		(end 147.815554 -215.53678)
		(width 0.18288)
		(layer "In2.Cu")
		(net "M_F_CPU1_SB_DQS_DN<7>")
	)
	(segment
		(start 160.163002 -205.97749)
		(end 159.56915 -205.383638)
		(width 0.18288)
		(layer "In2.Cu")
		(net "M_F_CPU1_SB_DQS_DN<7>")
	)
	(segment
		(start 149.155658 -214.196676)
		(end 148.767546 -214.584788)
		(width 0.18288)
		(layer "In2.Cu")
		(net "M_F_CPU1_SB_DQS_DN<7>")
	)
	(segment
		(start 169.536618 -208.167986)
		(end 169.508424 -208.19618)
		(width 0.16002)
		(layer "In2.Cu")
		(net "M_F_CPU1_SB_DQS_DN<7>")
	)
	(segment
		(start 147.815554 -215.53678)
		(end 147.637754 -215.53678)
		(width 0.18288)
		(layer "In2.Cu")
		(net "M_F_CPU1_SB_DQS_DN<7>")
	)
	(segment
		(start 174.592996 -208.78673)
		(end 174.564802 -208.758536)
		(width 0.16002)
		(layer "In2.Cu")
		(net "M_F_CPU1_SB_DQS_DN<7>")
	)
	(segment
		(start 139.65301 -222.433642)
		(end 139.647676 -222.43669)
		(width 0.088646)
		(layer "In2.Cu")
		(net "M_F_CPU1_SB_DQS_DN<7>")
	)
	(segment
		(start 174.564802 -208.758536)
		(end 174.339504 -208.533238)
		(width 0.18288)
		(layer "In2.Cu")
		(net "M_F_CPU1_SB_DQS_DN<7>")
	)
	(segment
		(start 169.817034 -207.88757)
		(end 169.719498 -207.985106)
		(width 0.18288)
		(layer "In2.Cu")
		(net "M_F_CPU1_SB_DQS_DN<7>")
	)
	(segment
		(start 169.675556 -208.0133)
		(end 169.536618 -208.152238)
		(width 0.16002)
		(layer "In2.Cu")
		(net "M_F_CPU1_SB_DQS_DN<7>")
	)
	(segment
		(start 153.915618 -209.260694)
		(end 153.915618 -209.436716)
		(width 0.18288)
		(layer "In2.Cu")
		(net "M_F_CPU1_SB_DQS_DN<7>")
	)
	(segment
		(start 152.963626 -210.388708)
		(end 152.575514 -210.77682)
		(width 0.18288)
		(layer "In2.Cu")
		(net "M_F_CPU1_SB_DQS_DN<7>")
	)
	(segment
		(start 174.775876 -208.96961)
		(end 174.747682 -208.941416)
		(width 0.16002)
		(layer "In2.Cu")
		(net "M_F_CPU1_SB_DQS_DN<7>")
	)
	(segment
		(start 164.725858 -206.84109)
		(end 164.270182 -206.84109)
		(width 0.18288)
		(layer "In2.Cu")
		(net "M_F_CPU1_SB_DQS_DN<7>")
	)
	(segment
		(start 161.783014 -206.26832)
		(end 161.35096 -206.26832)
		(width 0.18288)
		(layer "In2.Cu")
		(net "M_F_CPU1_SB_DQS_DN<7>")
	)
	(segment
		(start 149.719538 -213.632796)
		(end 149.543516 -213.632796)
		(width 0.18288)
		(layer "In2.Cu")
		(net "M_F_CPU1_SB_DQS_DN<7>")
	)
	(segment
		(start 174.747682 -208.941416)
		(end 174.747682 -208.925668)
		(width 0.16002)
		(layer "In2.Cu")
		(net "M_F_CPU1_SB_DQS_DN<7>")
	)
	(segment
		(start 152.963626 -210.212686)
		(end 152.963626 -210.388708)
		(width 0.18288)
		(layer "In2.Cu")
		(net "M_F_CPU1_SB_DQS_DN<7>")
	)
	(segment
		(start 162.078162 -205.973172)
		(end 161.783014 -206.26832)
		(width 0.18288)
		(layer "In2.Cu")
		(net "M_F_CPU1_SB_DQS_DN<7>")
	)
	(segment
		(start 157.159452 -206.01686)
		(end 156.771594 -206.404718)
		(width 0.18288)
		(layer "In2.Cu")
		(net "M_F_CPU1_SB_DQS_DN<7>")
	)
	(segment
		(start 153.915618 -209.436716)
		(end 153.527506 -209.824828)
		(width 0.18288)
		(layer "In2.Cu")
		(net "M_F_CPU1_SB_DQS_DN<7>")
	)
	(segment
		(start 151.4475 -211.728812)
		(end 151.059642 -212.11667)
		(width 0.18288)
		(layer "In2.Cu")
		(net "M_F_CPU1_SB_DQS_DN<7>")
	)
	(segment
		(start 174.747682 -208.925668)
		(end 174.608744 -208.78673)
		(width 0.16002)
		(layer "In2.Cu")
		(net "M_F_CPU1_SB_DQS_DN<7>")
	)
	(segment
		(start 142.794228 -220.2942)
		(end 142.16126 -220.927168)
		(width 0.088646)
		(layer "In2.Cu")
		(net "M_F_CPU1_SB_DQS_DN<7>")
	)
	(segment
		(start 148.767546 -214.584788)
		(end 148.59 -214.584788)
		(width 0.18288)
		(layer "In2.Cu")
		(net "M_F_CPU1_SB_DQS_DN<7>")
	)
	(segment
		(start 169.691304 -208.0133)
		(end 169.675556 -208.0133)
		(width 0.16002)
		(layer "In2.Cu")
		(net "M_F_CPU1_SB_DQS_DN<7>")
	)
	(segment
		(start 163.402264 -205.973172)
		(end 162.078162 -205.973172)
		(width 0.18288)
		(layer "In2.Cu")
		(net "M_F_CPU1_SB_DQS_DN<7>")
	)
	(segment
		(start 176.45253 -208.929986)
		(end 175.773842 -209.21091)
		(width 0.18288)
		(layer "In2.Cu")
		(net "M_F_CPU1_SB_DQS_DN<7>")
	)
	(segment
		(start 153.527506 -209.824828)
		(end 153.351484 -209.824828)
		(width 0.18288)
		(layer "In2.Cu")
		(net "M_F_CPU1_SB_DQS_DN<7>")
	)
	(segment
		(start 139.646914 -222.437198)
		(end 139.616688 -222.454724)
		(width 0.088646)
		(layer "In2.Cu")
		(net "M_F_CPU1_SB_DQS_DN<7>")
	)
	(segment
		(start 175.017176 -209.21091)
		(end 174.775876 -208.96961)
		(width 0.18288)
		(layer "In2.Cu")
		(net "M_F_CPU1_SB_DQS_DN<7>")
	)
	(segment
		(start 152.399492 -210.77682)
		(end 152.011634 -211.164678)
		(width 0.18288)
		(layer "In2.Cu")
		(net "M_F_CPU1_SB_DQS_DN<7>")
	)
	(segment
		(start 154.479498 -208.872836)
		(end 154.303476 -208.872836)
		(width 0.18288)
		(layer "In2.Cu")
		(net "M_F_CPU1_SB_DQS_DN<7>")
	)
	(segment
		(start 150.10765 -213.244684)
		(end 149.719538 -213.632796)
		(width 0.18288)
		(layer "In2.Cu")
		(net "M_F_CPU1_SB_DQS_DN<7>")
	)
	(segment
		(start 154.86761 -208.308702)
		(end 154.86761 -208.484724)
		(width 0.18288)
		(layer "In2.Cu")
		(net "M_F_CPU1_SB_DQS_DN<7>")
	)
	(segment
		(start 150.495508 -212.680804)
		(end 150.10765 -213.068662)
		(width 0.18288)
		(layer "In2.Cu")
		(net "M_F_CPU1_SB_DQS_DN<7>")
	)
	(segment
		(start 171.10583 -207.88757)
		(end 169.817034 -207.88757)
		(width 0.18288)
		(layer "In2.Cu")
		(net "M_F_CPU1_SB_DQS_DN<7>")
	)
	(segment
		(start 148.59 -214.584788)
		(end 148.203666 -214.970868)
		(width 0.18288)
		(layer "In2.Cu")
		(net "M_F_CPU1_SB_DQS_DN<7>")
	)
	(segment
		(start 156.383482 -206.968852)
		(end 156.20746 -206.968852)
		(width 0.18288)
		(layer "In2.Cu")
		(net "M_F_CPU1_SB_DQS_DN<7>")
	)
	(segment
		(start 152.575514 -210.77682)
		(end 152.399492 -210.77682)
		(width 0.18288)
		(layer "In2.Cu")
		(net "M_F_CPU1_SB_DQS_DN<7>")
	)
	(segment
		(start 165.730174 -206.823056)
		(end 165.435026 -207.118204)
		(width 0.18288)
		(layer "In2.Cu")
		(net "M_F_CPU1_SB_DQS_DN<7>")
	)
	(segment
		(start 155.819602 -207.532732)
		(end 155.43149 -207.920844)
		(width 0.18288)
		(layer "In2.Cu")
		(net "M_F_CPU1_SB_DQS_DN<7>")
	)
	(segment
		(start 166.840916 -206.823056)
		(end 165.730174 -206.823056)
		(width 0.18288)
		(layer "In2.Cu")
		(net "M_F_CPU1_SB_DQS_DN<7>")
	)
	(segment
		(start 158.10738 -205.383638)
		(end 157.159452 -206.01686)
		(width 0.18288)
		(layer "In2.Cu")
		(net "M_F_CPU1_SB_DQS_DN<7>")
	)
	(segment
		(start 148.203666 -214.970868)
		(end 148.203666 -215.148668)
		(width 0.18288)
		(layer "In2.Cu")
		(net "M_F_CPU1_SB_DQS_DN<7>")
	)
	(segment
		(start 169.508424 -208.19618)
		(end 169.367454 -208.33715)
		(width 0.18288)
		(layer "In2.Cu")
		(net "M_F_CPU1_SB_DQS_DN<7>")
	)
	(segment
		(start 169.719498 -207.985106)
		(end 169.691304 -208.0133)
		(width 0.16002)
		(layer "In2.Cu")
		(net "M_F_CPU1_SB_DQS_DN<7>")
	)
	(segment
		(start 168.35501 -208.33715)
		(end 166.840916 -206.823056)
		(width 0.18288)
		(layer "In2.Cu")
		(net "M_F_CPU1_SB_DQS_DN<7>")
	)
	(segment
		(start 142.879572 -220.2942)
		(end 142.794228 -220.2942)
		(width 0.088646)
		(layer "In2.Cu")
		(net "M_F_CPU1_SB_DQS_DN<7>")
	)
	(segment
		(start 139.616688 -222.454724)
		(end 138.894312 -222.761556)
		(width 0.088646)
		(layer "In2.Cu")
		(net "M_F_CPU1_SB_DQS_DN<7>")
	)
	(segment
		(start 171.244514 -208.010506)
		(end 171.228766 -208.010506)
		(width 0.16002)
		(layer "In2.Cu")
		(net "M_F_CPU1_SB_DQS_DN<7>")
	)
	(segment
		(start 156.771594 -206.404718)
		(end 156.771594 -206.58074)
		(width 0.18288)
		(layer "In2.Cu")
		(net "M_F_CPU1_SB_DQS_DN<7>")
	)
	(segment
		(start 171.383452 -208.149444)
		(end 171.244514 -208.010506)
		(width 0.16002)
		(layer "In2.Cu")
		(net "M_F_CPU1_SB_DQS_DN<7>")
	)
	(segment
		(start 154.303476 -208.872836)
		(end 153.915618 -209.260694)
		(width 0.18288)
		(layer "In2.Cu")
		(net "M_F_CPU1_SB_DQS_DN<7>")
	)
	(segment
		(start 152.011634 -211.3407)
		(end 151.623522 -211.728812)
		(width 0.18288)
		(layer "In2.Cu")
		(net "M_F_CPU1_SB_DQS_DN<7>")
	)
	(segment
		(start 164.270182 -206.84109)
		(end 163.402264 -205.973172)
		(width 0.18288)
		(layer "In2.Cu")
		(net "M_F_CPU1_SB_DQS_DN<7>")
	)
	(segment
		(start 173.353222 -208.533238)
		(end 173.092872 -208.793588)
		(width 0.18288)
		(layer "In2.Cu")
		(net "M_F_CPU1_SB_DQS_DN<7>")
	)
	(segment
		(start 156.20746 -206.968852)
		(end 155.819602 -207.35671)
		(width 0.18288)
		(layer "In2.Cu")
		(net "M_F_CPU1_SB_DQS_DN<7>")
	)
	(segment
		(start 159.56915 -205.383638)
		(end 158.10738 -205.383638)
		(width 0.18288)
		(layer "In2.Cu")
		(net "M_F_CPU1_SB_DQS_DN<7>")
	)
	(segment
		(start 147.637754 -215.53678)
		(end 142.879572 -220.2942)
		(width 0.18288)
		(layer "In2.Cu")
		(net "M_F_CPU1_SB_DQS_DN<7>")
	)
	(segment
		(start 156.771594 -206.58074)
		(end 156.383482 -206.968852)
		(width 0.18288)
		(layer "In2.Cu")
		(net "M_F_CPU1_SB_DQS_DN<7>")
	)
	(segment
		(start 176.609248 -208.929986)
		(end 176.45253 -208.929986)
		(width 0.18288)
		(layer "In2.Cu")
		(net "M_F_CPU1_SB_DQS_DN<7>")
	)
	(segment
		(start 171.383452 -208.165192)
		(end 171.383452 -208.149444)
		(width 0.16002)
		(layer "In2.Cu")
		(net "M_F_CPU1_SB_DQS_DN<7>")
	)
	(segment
		(start 155.819602 -207.35671)
		(end 155.819602 -207.532732)
		(width 0.18288)
		(layer "In2.Cu")
		(net "M_F_CPU1_SB_DQS_DN<7>")
	)
	(segment
		(start 171.228766 -208.010506)
		(end 171.200572 -207.982312)
		(width 0.16002)
		(layer "In2.Cu")
		(net "M_F_CPU1_SB_DQS_DN<7>")
	)
	(segment
		(start 155.43149 -207.920844)
		(end 155.255468 -207.920844)
		(width 0.18288)
		(layer "In2.Cu")
		(net "M_F_CPU1_SB_DQS_DN<7>")
	)
	(segment
		(start 174.339504 -208.533238)
		(end 173.353222 -208.533238)
		(width 0.18288)
		(layer "In2.Cu")
		(net "M_F_CPU1_SB_DQS_DN<7>")
	)
	(arc
		(start 141.173708 -221.533974)
		(mid 141.14801 -221.557908)
		(end 141.120876 -221.580202)
		(width 0.088646)
		(layer "In2.Cu")
		(net "M_F_CPU1_SB_DQS_DN<7>")
	)
	(arc
		(start 141.120876 -221.580456)
		(mid 141.089604 -221.603011)
		(end 141.056868 -221.623382)
		(width 0.088646)
		(layer "In2.Cu")
		(net "M_F_CPU1_SB_DQS_DN<7>")
	)
	(arc
		(start 139.929616 -221.94774)
		(mid 139.855625 -222.227306)
		(end 139.65301 -222.433642)
		(width 0.088646)
		(layer "In2.Cu")
		(net "M_F_CPU1_SB_DQS_DN<7>")
	)
	(arc
		(start 140.491464 -221.623382)
		(mid 140.116989 -221.623428)
		(end 139.929616 -221.94774)
		(width 0.088646)
		(layer "In2.Cu")
		(net "M_F_CPU1_SB_DQS_DN<7>")
	)
	(arc
		(start 141.056868 -221.623382)
		(mid 140.774166 -221.699158)
		(end 140.491464 -221.623382)
		(width 0.088646)
		(layer "In2.Cu")
		(net "M_F_CPU1_SB_DQS_DN<7>")
	)
	(segment
		(start 184.786778 -218.312492)
		(end 185.041032 -218.566746)
		(width 0.20066)
		(layer "F.Cu")
		(net "M_F_CPU1_SB_DQS_DN<6>")
	)
	(segment
		(start 183.059578 -217.866976)
		(end 183.549544 -217.866976)
		(width 0.20066)
		(layer "F.Cu")
		(net "M_F_CPU1_SB_DQS_DN<6>")
	)
	(segment
		(start 179.833524 -217.870532)
		(end 180.110892 -218.1479)
		(width 0.20066)
		(layer "F.Cu")
		(net "M_F_CPU1_SB_DQS_DN<6>")
	)
	(segment
		(start 178.802792 -218.295474)
		(end 179.286154 -218.295474)
		(width 0.20066)
		(layer "F.Cu")
		(net "M_F_CPU1_SB_DQS_DN<6>")
	)
	(segment
		(start 176.896014 -218.566746)
		(end 178.000914 -218.566746)
		(width 0.20066)
		(layer "F.Cu")
		(net "M_F_CPU1_SB_DQS_DN<6>")
	)
	(segment
		(start 179.711096 -217.870532)
		(end 179.833524 -217.870532)
		(width 0.20066)
		(layer "F.Cu")
		(net "M_F_CPU1_SB_DQS_DN<6>")
	)
	(segment
		(start 183.99506 -218.312492)
		(end 184.786778 -218.312492)
		(width 0.20066)
		(layer "F.Cu")
		(net "M_F_CPU1_SB_DQS_DN<6>")
	)
	(segment
		(start 178.53152 -218.566746)
		(end 178.802792 -218.295474)
		(width 0.20066)
		(layer "F.Cu")
		(net "M_F_CPU1_SB_DQS_DN<6>")
	)
	(segment
		(start 180.423058 -218.1479)
		(end 180.427884 -218.1479)
		(width 0.101854)
		(layer "F.Cu")
		(net "M_F_CPU1_SB_DQS_DN<6>")
	)
	(segment
		(start 185.041032 -218.566746)
		(end 185.544714 -218.566746)
		(width 0.20066)
		(layer "F.Cu")
		(net "M_F_CPU1_SB_DQS_DN<6>")
	)
	(segment
		(start 180.43398 -218.141804)
		(end 182.444136 -218.141804)
		(width 0.1016)
		(layer "F.Cu")
		(net "M_F_CPU1_SB_DQS_DN<6>")
	)
	(segment
		(start 179.286154 -218.295474)
		(end 179.711096 -217.870532)
		(width 0.20066)
		(layer "F.Cu")
		(net "M_F_CPU1_SB_DQS_DN<6>")
	)
	(segment
		(start 182.455058 -218.152726)
		(end 182.773828 -218.152726)
		(width 0.20066)
		(layer "F.Cu")
		(net "M_F_CPU1_SB_DQS_DN<6>")
	)
	(segment
		(start 183.549544 -217.866976)
		(end 183.99506 -218.312492)
		(width 0.20066)
		(layer "F.Cu")
		(net "M_F_CPU1_SB_DQS_DN<6>")
	)
	(segment
		(start 182.773828 -218.152726)
		(end 183.059578 -217.866976)
		(width 0.20066)
		(layer "F.Cu")
		(net "M_F_CPU1_SB_DQS_DN<6>")
	)
	(segment
		(start 178.000914 -218.566746)
		(end 178.53152 -218.566746)
		(width 0.20066)
		(layer "F.Cu")
		(net "M_F_CPU1_SB_DQS_DN<6>")
	)
	(segment
		(start 135.605266 -230.622602)
		(end 135.605266 -230.086662)
		(width 0.20066)
		(layer "F.Cu")
		(net "M_F_CPU1_SB_DQS_DN<6>")
	)
	(segment
		(start 180.110892 -218.1479)
		(end 180.423058 -218.1479)
		(width 0.20066)
		(layer "F.Cu")
		(net "M_F_CPU1_SB_DQS_DN<6>")
	)
	(segment
		(start 182.444136 -218.141804)
		(end 182.455058 -218.152726)
		(width 0.1016)
		(layer "F.Cu")
		(net "M_F_CPU1_SB_DQS_DN<6>")
	)
	(segment
		(start 180.427884 -218.1479)
		(end 180.43398 -218.141804)
		(width 0.1016)
		(layer "F.Cu")
		(net "M_F_CPU1_SB_DQS_DN<6>")
	)
	(segment
		(start 150.5458 -222.771462)
		(end 150.157942 -223.15932)
		(width 0.18288)
		(layer "In2.Cu")
		(net "M_F_CPU1_SB_DQS_DN<6>")
	)
	(segment
		(start 147.689824 -225.627438)
		(end 147.301966 -226.015296)
		(width 0.18288)
		(layer "In2.Cu")
		(net "M_F_CPU1_SB_DQS_DN<6>")
	)
	(segment
		(start 143.70685 -227.703888)
		(end 143.15821 -227.703888)
		(width 0.18288)
		(layer "In2.Cu")
		(net "M_F_CPU1_SB_DQS_DN<6>")
	)
	(segment
		(start 149.20595 -224.287334)
		(end 148.817838 -224.675446)
		(width 0.18288)
		(layer "In2.Cu")
		(net "M_F_CPU1_SB_DQS_DN<6>")
	)
	(segment
		(start 157.87116 -216.65692)
		(end 157.87116 -216.672668)
		(width 0.16002)
		(layer "In2.Cu")
		(net "M_F_CPU1_SB_DQS_DN<6>")
	)
	(segment
		(start 148.253958 -225.063304)
		(end 148.253958 -225.239326)
		(width 0.18288)
		(layer "In2.Cu")
		(net "M_F_CPU1_SB_DQS_DN<6>")
	)
	(segment
		(start 146.913854 -226.57943)
		(end 146.737832 -226.57943)
		(width 0.18288)
		(layer "In2.Cu")
		(net "M_F_CPU1_SB_DQS_DN<6>")
	)
	(segment
		(start 135.622792 -229.868222)
		(end 135.605266 -230.086662)
		(width 0.088646)
		(layer "In2.Cu")
		(net "M_F_CPU1_SB_DQS_DN<6>")
	)
	(segment
		(start 176.609248 -218.27998)
		(end 176.111408 -218.27998)
		(width 0.18288)
		(layer "In2.Cu")
		(net "M_F_CPU1_SB_DQS_DN<6>")
	)
	(segment
		(start 149.20595 -224.111312)
		(end 149.20595 -224.287334)
		(width 0.18288)
		(layer "In2.Cu")
		(net "M_F_CPU1_SB_DQS_DN<6>")
	)
	(segment
		(start 165.079426 -218.165426)
		(end 164.792406 -217.878406)
		(width 0.18288)
		(layer "In2.Cu")
		(net "M_F_CPU1_SB_DQS_DN<6>")
	)
	(segment
		(start 171.217082 -217.36812)
		(end 171.188888 -217.339926)
		(width 0.16002)
		(layer "In2.Cu")
		(net "M_F_CPU1_SB_DQS_DN<6>")
	)
	(segment
		(start 140.413994 -228.304344)
		(end 140.329412 -228.304344)
		(width 0.088646)
		(layer "In2.Cu")
		(net "M_F_CPU1_SB_DQS_DN<6>")
	)
	(segment
		(start 161.810954 -217.353388)
		(end 161.455608 -217.353388)
		(width 0.18288)
		(layer "In2.Cu")
		(net "M_F_CPU1_SB_DQS_DN<6>")
	)
	(segment
		(start 156.334206 -217.462608)
		(end 156.334206 -217.63863)
		(width 0.18288)
		(layer "In2.Cu")
		(net "M_F_CPU1_SB_DQS_DN<6>")
	)
	(segment
		(start 150.157942 -223.335342)
		(end 149.76983 -223.723454)
		(width 0.18288)
		(layer "In2.Cu")
		(net "M_F_CPU1_SB_DQS_DN<6>")
	)
	(segment
		(start 147.301966 -226.015296)
		(end 147.301966 -226.191318)
		(width 0.18288)
		(layer "In2.Cu")
		(net "M_F_CPU1_SB_DQS_DN<6>")
	)
	(segment
		(start 147.301966 -226.191318)
		(end 146.913854 -226.57943)
		(width 0.18288)
		(layer "In2.Cu")
		(net "M_F_CPU1_SB_DQS_DN<6>")
	)
	(segment
		(start 135.845296 -229.795832)
		(end 135.76046 -229.795832)
		(width 0.088646)
		(layer "In2.Cu")
		(net "M_F_CPU1_SB_DQS_DN<6>")
	)
	(segment
		(start 175.008032 -218.549728)
		(end 174.777908 -218.319604)
		(width 0.18288)
		(layer "In2.Cu")
		(net "M_F_CPU1_SB_DQS_DN<6>")
	)
	(segment
		(start 169.662094 -217.375994)
		(end 169.523156 -217.514932)
		(width 0.16002)
		(layer "In2.Cu")
		(net "M_F_CPU1_SB_DQS_DN<6>")
	)
	(segment
		(start 155.382214 -218.590622)
		(end 154.994102 -218.978734)
		(width 0.18288)
		(layer "In2.Cu")
		(net "M_F_CPU1_SB_DQS_DN<6>")
	)
	(segment
		(start 136.640316 -229.272846)
		(end 136.640316 -229.282752)
		(width 0.088646)
		(layer "In2.Cu")
		(net "M_F_CPU1_SB_DQS_DN<6>")
	)
	(segment
		(start 171.23283 -217.36812)
		(end 171.217082 -217.36812)
		(width 0.16002)
		(layer "In2.Cu")
		(net "M_F_CPU1_SB_DQS_DN<6>")
	)
	(segment
		(start 142.36065 -227.703888)
		(end 141.81201 -227.703888)
		(width 0.18288)
		(layer "In2.Cu")
		(net "M_F_CPU1_SB_DQS_DN<6>")
	)
	(segment
		(start 169.205656 -217.84818)
		(end 167.97401 -217.84818)
		(width 0.18288)
		(layer "In2.Cu")
		(net "M_F_CPU1_SB_DQS_DN<6>")
	)
	(segment
		(start 136.264142 -229.816406)
		(end 136.235948 -229.824026)
		(width 0.088646)
		(layer "In2.Cu")
		(net "M_F_CPU1_SB_DQS_DN<6>")
	)
	(segment
		(start 172.303948 -217.84818)
		(end 171.697142 -217.84818)
		(width 0.18288)
		(layer "In2.Cu")
		(net "M_F_CPU1_SB_DQS_DN<6>")
	)
	(segment
		(start 148.817838 -224.675446)
		(end 148.641816 -224.675446)
		(width 0.18288)
		(layer "In2.Cu")
		(net "M_F_CPU1_SB_DQS_DN<6>")
	)
	(segment
		(start 157.469078 -217.07475)
		(end 156.722064 -217.07475)
		(width 0.18288)
		(layer "In2.Cu")
		(net "M_F_CPU1_SB_DQS_DN<6>")
	)
	(segment
		(start 135.76046 -229.795832)
		(end 135.671306 -229.832916)
		(width 0.088646)
		(layer "In2.Cu")
		(net "M_F_CPU1_SB_DQS_DN<6>")
	)
	(segment
		(start 140.329412 -228.304344)
		(end 139.851638 -228.782118)
		(width 0.088646)
		(layer "In2.Cu")
		(net "M_F_CPU1_SB_DQS_DN<6>")
	)
	(segment
		(start 171.055792 -217.20683)
		(end 169.847006 -217.20683)
		(width 0.18288)
		(layer "In2.Cu")
		(net "M_F_CPU1_SB_DQS_DN<6>")
	)
	(segment
		(start 176.896014 -218.566746)
		(end 176.609248 -218.27998)
		(width 0.18288)
		(layer "In2.Cu")
		(net "M_F_CPU1_SB_DQS_DN<6>")
	)
	(segment
		(start 169.677842 -217.375994)
		(end 169.662094 -217.375994)
		(width 0.16002)
		(layer "In2.Cu")
		(net "M_F_CPU1_SB_DQS_DN<6>")
	)
	(segment
		(start 154.430222 -219.542614)
		(end 154.04211 -219.930726)
		(width 0.18288)
		(layer "In2.Cu")
		(net "M_F_CPU1_SB_DQS_DN<6>")
	)
	(segment
		(start 136.827768 -228.948488)
		(end 136.818878 -228.953568)
		(width 0.088646)
		(layer "In2.Cu")
		(net "M_F_CPU1_SB_DQS_DN<6>")
	)
	(segment
		(start 172.596556 -218.140788)
		(end 172.303948 -217.84818)
		(width 0.18288)
		(layer "In2.Cu")
		(net "M_F_CPU1_SB_DQS_DN<6>")
	)
	(segment
		(start 154.994102 -218.978734)
		(end 154.81808 -218.978734)
		(width 0.18288)
		(layer "In2.Cu")
		(net "M_F_CPU1_SB_DQS_DN<6>")
	)
	(segment
		(start 165.72738 -217.872818)
		(end 165.434772 -218.165426)
		(width 0.18288)
		(layer "In2.Cu")
		(net "M_F_CPU1_SB_DQS_DN<6>")
	)
	(segment
		(start 171.399962 -217.551)
		(end 171.371768 -217.522806)
		(width 0.16002)
		(layer "In2.Cu")
		(net "M_F_CPU1_SB_DQS_DN<6>")
	)
	(segment
		(start 164.792406 -217.878406)
		(end 164.241226 -217.878406)
		(width 0.18288)
		(layer "In2.Cu")
		(net "M_F_CPU1_SB_DQS_DN<6>")
	)
	(segment
		(start 150.721822 -222.771462)
		(end 150.5458 -222.771462)
		(width 0.18288)
		(layer "In2.Cu")
		(net "M_F_CPU1_SB_DQS_DN<6>")
	)
	(segment
		(start 169.523156 -217.514932)
		(end 169.523156 -217.53068)
		(width 0.16002)
		(layer "In2.Cu")
		(net "M_F_CPU1_SB_DQS_DN<6>")
	)
	(segment
		(start 169.706036 -217.3478)
		(end 169.677842 -217.375994)
		(width 0.16002)
		(layer "In2.Cu")
		(net "M_F_CPU1_SB_DQS_DN<6>")
	)
	(segment
		(start 171.188888 -217.339926)
		(end 171.055792 -217.20683)
		(width 0.18288)
		(layer "In2.Cu")
		(net "M_F_CPU1_SB_DQS_DN<6>")
	)
	(segment
		(start 159.531812 -216.39149)
		(end 158.152338 -216.39149)
		(width 0.18288)
		(layer "In2.Cu")
		(net "M_F_CPU1_SB_DQS_DN<6>")
	)
	(segment
		(start 169.847006 -217.20683)
		(end 169.706036 -217.3478)
		(width 0.18288)
		(layer "In2.Cu")
		(net "M_F_CPU1_SB_DQS_DN<6>")
	)
	(segment
		(start 171.371768 -217.522806)
		(end 171.371768 -217.507058)
		(width 0.16002)
		(layer "In2.Cu")
		(net "M_F_CPU1_SB_DQS_DN<6>")
	)
	(segment
		(start 141.13891 -227.579428)
		(end 140.413994 -228.304344)
		(width 0.18288)
		(layer "In2.Cu")
		(net "M_F_CPU1_SB_DQS_DN<6>")
	)
	(segment
		(start 145.737834 -227.579428)
		(end 143.83131 -227.579428)
		(width 0.18288)
		(layer "In2.Cu")
		(net "M_F_CPU1_SB_DQS_DN<6>")
	)
	(segment
		(start 155.770072 -218.026742)
		(end 155.382214 -218.4146)
		(width 0.18288)
		(layer "In2.Cu")
		(net "M_F_CPU1_SB_DQS_DN<6>")
	)
	(segment
		(start 160.20669 -217.066368)
		(end 159.531812 -216.39149)
		(width 0.18288)
		(layer "In2.Cu")
		(net "M_F_CPU1_SB_DQS_DN<6>")
	)
	(segment
		(start 164.241226 -217.878406)
		(end 163.4236 -217.06078)
		(width 0.18288)
		(layer "In2.Cu")
		(net "M_F_CPU1_SB_DQS_DN<6>")
	)
	(segment
		(start 171.697142 -217.84818)
		(end 171.399962 -217.551)
		(width 0.18288)
		(layer "In2.Cu")
		(net "M_F_CPU1_SB_DQS_DN<6>")
	)
	(segment
		(start 167.255698 -218.165426)
		(end 166.96309 -217.872818)
		(width 0.18288)
		(layer "In2.Cu")
		(net "M_F_CPU1_SB_DQS_DN<6>")
	)
	(segment
		(start 167.97401 -217.84818)
		(end 167.656764 -218.165426)
		(width 0.18288)
		(layer "In2.Cu")
		(net "M_F_CPU1_SB_DQS_DN<6>")
	)
	(segment
		(start 172.990764 -218.140788)
		(end 172.596556 -218.140788)
		(width 0.18288)
		(layer "In2.Cu")
		(net "M_F_CPU1_SB_DQS_DN<6>")
	)
	(segment
		(start 166.96309 -217.872818)
		(end 165.72738 -217.872818)
		(width 0.18288)
		(layer "In2.Cu")
		(net "M_F_CPU1_SB_DQS_DN<6>")
	)
	(segment
		(start 158.025846 -216.517982)
		(end 158.010098 -216.517982)
		(width 0.16002)
		(layer "In2.Cu")
		(net "M_F_CPU1_SB_DQS_DN<6>")
	)
	(segment
		(start 143.83131 -227.579428)
		(end 143.70685 -227.703888)
		(width 0.18288)
		(layer "In2.Cu")
		(net "M_F_CPU1_SB_DQS_DN<6>")
	)
	(segment
		(start 156.722064 -217.07475)
		(end 156.334206 -217.462608)
		(width 0.18288)
		(layer "In2.Cu")
		(net "M_F_CPU1_SB_DQS_DN<6>")
	)
	(segment
		(start 169.494962 -217.558874)
		(end 169.205656 -217.84818)
		(width 0.18288)
		(layer "In2.Cu")
		(net "M_F_CPU1_SB_DQS_DN<6>")
	)
	(segment
		(start 161.455608 -217.353388)
		(end 161.168588 -217.066368)
		(width 0.18288)
		(layer "In2.Cu")
		(net "M_F_CPU1_SB_DQS_DN<6>")
	)
	(segment
		(start 174.610776 -218.136724)
		(end 174.595028 -218.136724)
		(width 0.16002)
		(layer "In2.Cu")
		(net "M_F_CPU1_SB_DQS_DN<6>")
	)
	(segment
		(start 174.566834 -218.10853)
		(end 174.29226 -217.833956)
		(width 0.18288)
		(layer "In2.Cu")
		(net "M_F_CPU1_SB_DQS_DN<6>")
	)
	(segment
		(start 148.641816 -224.675446)
		(end 148.253958 -225.063304)
		(width 0.18288)
		(layer "In2.Cu")
		(net "M_F_CPU1_SB_DQS_DN<6>")
	)
	(segment
		(start 155.946094 -218.026742)
		(end 155.770072 -218.026742)
		(width 0.18288)
		(layer "In2.Cu")
		(net "M_F_CPU1_SB_DQS_DN<6>")
	)
	(segment
		(start 135.671306 -229.832916)
		(end 135.622792 -229.868222)
		(width 0.088646)
		(layer "In2.Cu")
		(net "M_F_CPU1_SB_DQS_DN<6>")
	)
	(segment
		(start 149.76983 -223.723454)
		(end 149.593808 -223.723454)
		(width 0.18288)
		(layer "In2.Cu")
		(net "M_F_CPU1_SB_DQS_DN<6>")
	)
	(segment
		(start 174.595028 -218.136724)
		(end 174.566834 -218.10853)
		(width 0.16002)
		(layer "In2.Cu")
		(net "M_F_CPU1_SB_DQS_DN<6>")
	)
	(segment
		(start 151.497792 -221.81947)
		(end 151.109934 -222.207328)
		(width 0.18288)
		(layer "In2.Cu")
		(net "M_F_CPU1_SB_DQS_DN<6>")
	)
	(segment
		(start 173.297596 -217.833956)
		(end 172.990764 -218.140788)
		(width 0.18288)
		(layer "In2.Cu")
		(net "M_F_CPU1_SB_DQS_DN<6>")
	)
	(segment
		(start 163.4236 -217.06078)
		(end 162.103562 -217.06078)
		(width 0.18288)
		(layer "In2.Cu")
		(net "M_F_CPU1_SB_DQS_DN<6>")
	)
	(segment
		(start 171.371768 -217.507058)
		(end 171.23283 -217.36812)
		(width 0.16002)
		(layer "In2.Cu")
		(net "M_F_CPU1_SB_DQS_DN<6>")
	)
	(segment
		(start 153.866088 -219.930726)
		(end 151.977344 -221.81947)
		(width 0.18288)
		(layer "In2.Cu")
		(net "M_F_CPU1_SB_DQS_DN<6>")
	)
	(segment
		(start 162.103562 -217.06078)
		(end 161.810954 -217.353388)
		(width 0.18288)
		(layer "In2.Cu")
		(net "M_F_CPU1_SB_DQS_DN<6>")
	)
	(segment
		(start 158.05404 -216.489788)
		(end 158.025846 -216.517982)
		(width 0.16002)
		(layer "In2.Cu")
		(net "M_F_CPU1_SB_DQS_DN<6>")
	)
	(segment
		(start 156.334206 -217.63863)
		(end 155.946094 -218.026742)
		(width 0.18288)
		(layer "In2.Cu")
		(net "M_F_CPU1_SB_DQS_DN<6>")
	)
	(segment
		(start 174.29226 -217.833956)
		(end 173.297596 -217.833956)
		(width 0.18288)
		(layer "In2.Cu")
		(net "M_F_CPU1_SB_DQS_DN<6>")
	)
	(segment
		(start 151.109934 -222.38335)
		(end 150.721822 -222.771462)
		(width 0.18288)
		(layer "In2.Cu")
		(net "M_F_CPU1_SB_DQS_DN<6>")
	)
	(segment
		(start 161.168588 -217.066368)
		(end 160.20669 -217.066368)
		(width 0.18288)
		(layer "In2.Cu")
		(net "M_F_CPU1_SB_DQS_DN<6>")
	)
	(segment
		(start 165.434772 -218.165426)
		(end 165.079426 -218.165426)
		(width 0.18288)
		(layer "In2.Cu")
		(net "M_F_CPU1_SB_DQS_DN<6>")
	)
	(segment
		(start 167.656764 -218.165426)
		(end 167.255698 -218.165426)
		(width 0.18288)
		(layer "In2.Cu")
		(net "M_F_CPU1_SB_DQS_DN<6>")
	)
	(segment
		(start 141.68755 -227.579428)
		(end 141.13891 -227.579428)
		(width 0.18288)
		(layer "In2.Cu")
		(net "M_F_CPU1_SB_DQS_DN<6>")
	)
	(segment
		(start 155.382214 -218.4146)
		(end 155.382214 -218.590622)
		(width 0.18288)
		(layer "In2.Cu")
		(net "M_F_CPU1_SB_DQS_DN<6>")
	)
	(segment
		(start 136.357868 -229.762304)
		(end 136.264142 -229.816406)
		(width 0.088646)
		(layer "In2.Cu")
		(net "M_F_CPU1_SB_DQS_DN<6>")
	)
	(segment
		(start 143.03375 -227.579428)
		(end 142.48511 -227.579428)
		(width 0.18288)
		(layer "In2.Cu")
		(net "M_F_CPU1_SB_DQS_DN<6>")
	)
	(segment
		(start 142.48511 -227.579428)
		(end 142.36065 -227.703888)
		(width 0.18288)
		(layer "In2.Cu")
		(net "M_F_CPU1_SB_DQS_DN<6>")
	)
	(segment
		(start 136.235948 -229.824026)
		(end 136.176766 -229.83952)
		(width 0.088646)
		(layer "In2.Cu")
		(net "M_F_CPU1_SB_DQS_DN<6>")
	)
	(segment
		(start 150.157942 -223.15932)
		(end 150.157942 -223.335342)
		(width 0.18288)
		(layer "In2.Cu")
		(net "M_F_CPU1_SB_DQS_DN<6>")
	)
	(segment
		(start 176.111408 -218.27998)
		(end 175.459898 -218.549728)
		(width 0.18288)
		(layer "In2.Cu")
		(net "M_F_CPU1_SB_DQS_DN<6>")
	)
	(segment
		(start 157.842966 -216.700862)
		(end 157.469078 -217.07475)
		(width 0.18288)
		(layer "In2.Cu")
		(net "M_F_CPU1_SB_DQS_DN<6>")
	)
	(segment
		(start 146.737832 -226.57943)
		(end 145.737834 -227.579428)
		(width 0.18288)
		(layer "In2.Cu")
		(net "M_F_CPU1_SB_DQS_DN<6>")
	)
	(segment
		(start 136.176766 -229.83952)
		(end 135.995664 -229.83952)
		(width 0.088646)
		(layer "In2.Cu")
		(net "M_F_CPU1_SB_DQS_DN<6>")
	)
	(segment
		(start 154.04211 -219.930726)
		(end 153.866088 -219.930726)
		(width 0.18288)
		(layer "In2.Cu")
		(net "M_F_CPU1_SB_DQS_DN<6>")
	)
	(segment
		(start 148.253958 -225.239326)
		(end 147.865846 -225.627438)
		(width 0.18288)
		(layer "In2.Cu")
		(net "M_F_CPU1_SB_DQS_DN<6>")
	)
	(segment
		(start 151.109934 -222.207328)
		(end 151.109934 -222.38335)
		(width 0.18288)
		(layer "In2.Cu")
		(net "M_F_CPU1_SB_DQS_DN<6>")
	)
	(segment
		(start 135.995664 -229.83952)
		(end 135.845296 -229.795832)
		(width 0.088646)
		(layer "In2.Cu")
		(net "M_F_CPU1_SB_DQS_DN<6>")
	)
	(segment
		(start 174.749714 -218.275662)
		(end 174.610776 -218.136724)
		(width 0.16002)
		(layer "In2.Cu")
		(net "M_F_CPU1_SB_DQS_DN<6>")
	)
	(segment
		(start 169.523156 -217.53068)
		(end 169.494962 -217.558874)
		(width 0.16002)
		(layer "In2.Cu")
		(net "M_F_CPU1_SB_DQS_DN<6>")
	)
	(segment
		(start 175.459898 -218.549728)
		(end 175.008032 -218.549728)
		(width 0.18288)
		(layer "In2.Cu")
		(net "M_F_CPU1_SB_DQS_DN<6>")
	)
	(segment
		(start 174.777908 -218.319604)
		(end 174.749714 -218.29141)
		(width 0.16002)
		(layer "In2.Cu")
		(net "M_F_CPU1_SB_DQS_DN<6>")
	)
	(segment
		(start 154.430222 -219.366592)
		(end 154.430222 -219.542614)
		(width 0.18288)
		(layer "In2.Cu")
		(net "M_F_CPU1_SB_DQS_DN<6>")
	)
	(segment
		(start 141.81201 -227.703888)
		(end 141.68755 -227.579428)
		(width 0.18288)
		(layer "In2.Cu")
		(net "M_F_CPU1_SB_DQS_DN<6>")
	)
	(segment
		(start 151.977344 -221.81947)
		(end 151.497792 -221.81947)
		(width 0.18288)
		(layer "In2.Cu")
		(net "M_F_CPU1_SB_DQS_DN<6>")
	)
	(segment
		(start 158.152338 -216.39149)
		(end 158.05404 -216.489788)
		(width 0.18288)
		(layer "In2.Cu")
		(net "M_F_CPU1_SB_DQS_DN<6>")
	)
	(segment
		(start 147.865846 -225.627438)
		(end 147.689824 -225.627438)
		(width 0.18288)
		(layer "In2.Cu")
		(net "M_F_CPU1_SB_DQS_DN<6>")
	)
	(segment
		(start 143.15821 -227.703888)
		(end 143.03375 -227.579428)
		(width 0.18288)
		(layer "In2.Cu")
		(net "M_F_CPU1_SB_DQS_DN<6>")
	)
	(segment
		(start 157.87116 -216.672668)
		(end 157.842966 -216.700862)
		(width 0.16002)
		(layer "In2.Cu")
		(net "M_F_CPU1_SB_DQS_DN<6>")
	)
	(segment
		(start 154.81808 -218.978734)
		(end 154.430222 -219.366592)
		(width 0.18288)
		(layer "In2.Cu")
		(net "M_F_CPU1_SB_DQS_DN<6>")
	)
	(segment
		(start 174.749714 -218.29141)
		(end 174.749714 -218.275662)
		(width 0.16002)
		(layer "In2.Cu")
		(net "M_F_CPU1_SB_DQS_DN<6>")
	)
	(segment
		(start 149.593808 -223.723454)
		(end 149.20595 -224.111312)
		(width 0.18288)
		(layer "In2.Cu")
		(net "M_F_CPU1_SB_DQS_DN<6>")
	)
	(segment
		(start 158.010098 -216.517982)
		(end 157.87116 -216.65692)
		(width 0.16002)
		(layer "In2.Cu")
		(net "M_F_CPU1_SB_DQS_DN<6>")
	)
	(arc
		(start 139.081764 -228.948488)
		(mid 138.894566 -228.898345)
		(end 138.707368 -228.948488)
		(width 0.088646)
		(layer "In2.Cu")
		(net "M_F_CPU1_SB_DQS_DN<6>")
	)
	(arc
		(start 136.818878 -228.953568)
		(mid 136.687964 -229.089928)
		(end 136.640316 -229.272846)
		(width 0.088646)
		(layer "In2.Cu")
		(net "M_F_CPU1_SB_DQS_DN<6>")
	)
	(arc
		(start 138.707368 -228.948488)
		(mid 138.424666 -229.024264)
		(end 138.141964 -228.948488)
		(width 0.088646)
		(layer "In2.Cu")
		(net "M_F_CPU1_SB_DQS_DN<6>")
	)
	(arc
		(start 139.851638 -228.782118)
		(mid 139.783404 -228.846112)
		(end 139.711176 -228.905562)
		(width 0.088646)
		(layer "In2.Cu")
		(net "M_F_CPU1_SB_DQS_DN<6>")
	)
	(arc
		(start 138.141964 -228.948488)
		(mid 137.954766 -228.898345)
		(end 137.767568 -228.948488)
		(width 0.088646)
		(layer "In2.Cu")
		(net "M_F_CPU1_SB_DQS_DN<6>")
	)
	(arc
		(start 137.767568 -228.948488)
		(mid 137.484866 -229.024264)
		(end 137.202164 -228.948488)
		(width 0.088646)
		(layer "In2.Cu")
		(net "M_F_CPU1_SB_DQS_DN<6>")
	)
	(arc
		(start 136.640316 -229.282752)
		(mid 136.562205 -229.559701)
		(end 136.357868 -229.762304)
		(width 0.088646)
		(layer "In2.Cu")
		(net "M_F_CPU1_SB_DQS_DN<6>")
	)
	(arc
		(start 137.202164 -228.948488)
		(mid 137.014966 -228.898345)
		(end 136.827768 -228.948488)
		(width 0.088646)
		(layer "In2.Cu")
		(net "M_F_CPU1_SB_DQS_DN<6>")
	)
	(arc
		(start 139.647168 -228.948488)
		(mid 139.364466 -229.024264)
		(end 139.081764 -228.948488)
		(width 0.088646)
		(layer "In2.Cu")
		(net "M_F_CPU1_SB_DQS_DN<6>")
	)
	(arc
		(start 139.711176 -228.905562)
		(mid 139.679904 -228.928117)
		(end 139.647168 -228.948488)
		(width 0.088646)
		(layer "In2.Cu")
		(net "M_F_CPU1_SB_DQS_DN<6>")
	)
	(segment
		(start 179.711096 -227.220526)
		(end 179.833524 -227.220526)
		(width 0.20066)
		(layer "F.Cu")
		(net "M_F_CPU1_SB_DQS_DN<5>")
	)
	(segment
		(start 178.000914 -227.91674)
		(end 178.53152 -227.91674)
		(width 0.20066)
		(layer "F.Cu")
		(net "M_F_CPU1_SB_DQS_DN<5>")
	)
	(segment
		(start 179.833524 -227.220526)
		(end 180.110892 -227.497894)
		(width 0.20066)
		(layer "F.Cu")
		(net "M_F_CPU1_SB_DQS_DN<5>")
	)
	(segment
		(start 183.059578 -227.21697)
		(end 183.549544 -227.21697)
		(width 0.20066)
		(layer "F.Cu")
		(net "M_F_CPU1_SB_DQS_DN<5>")
	)
	(segment
		(start 182.455058 -227.50272)
		(end 182.773828 -227.50272)
		(width 0.20066)
		(layer "F.Cu")
		(net "M_F_CPU1_SB_DQS_DN<5>")
	)
	(segment
		(start 180.43398 -227.491798)
		(end 182.444136 -227.491798)
		(width 0.1016)
		(layer "F.Cu")
		(net "M_F_CPU1_SB_DQS_DN<5>")
	)
	(segment
		(start 179.286154 -227.645468)
		(end 179.711096 -227.220526)
		(width 0.20066)
		(layer "F.Cu")
		(net "M_F_CPU1_SB_DQS_DN<5>")
	)
	(segment
		(start 185.041032 -227.91674)
		(end 185.544714 -227.91674)
		(width 0.20066)
		(layer "F.Cu")
		(net "M_F_CPU1_SB_DQS_DN<5>")
	)
	(segment
		(start 183.99506 -227.662486)
		(end 184.786778 -227.662486)
		(width 0.20066)
		(layer "F.Cu")
		(net "M_F_CPU1_SB_DQS_DN<5>")
	)
	(segment
		(start 132.315712 -237.947454)
		(end 132.315966 -237.411514)
		(width 0.20066)
		(layer "F.Cu")
		(net "M_F_CPU1_SB_DQS_DN<5>")
	)
	(segment
		(start 182.444136 -227.491798)
		(end 182.455058 -227.50272)
		(width 0.1016)
		(layer "F.Cu")
		(net "M_F_CPU1_SB_DQS_DN<5>")
	)
	(segment
		(start 176.896014 -227.91674)
		(end 178.000914 -227.91674)
		(width 0.20066)
		(layer "F.Cu")
		(net "M_F_CPU1_SB_DQS_DN<5>")
	)
	(segment
		(start 178.53152 -227.91674)
		(end 178.802792 -227.645468)
		(width 0.20066)
		(layer "F.Cu")
		(net "M_F_CPU1_SB_DQS_DN<5>")
	)
	(segment
		(start 184.786778 -227.662486)
		(end 185.041032 -227.91674)
		(width 0.20066)
		(layer "F.Cu")
		(net "M_F_CPU1_SB_DQS_DN<5>")
	)
	(segment
		(start 180.427884 -227.497894)
		(end 180.43398 -227.491798)
		(width 0.1016)
		(layer "F.Cu")
		(net "M_F_CPU1_SB_DQS_DN<5>")
	)
	(segment
		(start 182.773828 -227.50272)
		(end 183.059578 -227.21697)
		(width 0.20066)
		(layer "F.Cu")
		(net "M_F_CPU1_SB_DQS_DN<5>")
	)
	(segment
		(start 178.802792 -227.645468)
		(end 179.286154 -227.645468)
		(width 0.20066)
		(layer "F.Cu")
		(net "M_F_CPU1_SB_DQS_DN<5>")
	)
	(segment
		(start 183.549544 -227.21697)
		(end 183.99506 -227.662486)
		(width 0.20066)
		(layer "F.Cu")
		(net "M_F_CPU1_SB_DQS_DN<5>")
	)
	(segment
		(start 180.110892 -227.497894)
		(end 180.423058 -227.497894)
		(width 0.20066)
		(layer "F.Cu")
		(net "M_F_CPU1_SB_DQS_DN<5>")
	)
	(segment
		(start 180.423058 -227.497894)
		(end 180.427884 -227.497894)
		(width 0.101854)
		(layer "F.Cu")
		(net "M_F_CPU1_SB_DQS_DN<5>")
	)
	(segment
		(start 169.538904 -225.767646)
		(end 169.218356 -225.767646)
		(width 0.18288)
		(layer "In4.Cu")
		(net "M_F_CPU1_SB_DQS_DN<5>")
	)
	(segment
		(start 152.437592 -227.910644)
		(end 152.051512 -228.296724)
		(width 0.18288)
		(layer "In4.Cu")
		(net "M_F_CPU1_SB_DQS_DN<5>")
	)
	(segment
		(start 140.146278 -235.77931)
		(end 140.146278 -236.478826)
		(width 0.088646)
		(layer "In4.Cu")
		(net "M_F_CPU1_SB_DQS_DN<5>")
	)
	(segment
		(start 157.900624 -225.793808)
		(end 157.516576 -225.793808)
		(width 0.18288)
		(layer "In4.Cu")
		(net "M_F_CPU1_SB_DQS_DN<5>")
	)
	(segment
		(start 141.561058 -235.39069)
		(end 141.001496 -235.39069)
		(width 0.18288)
		(layer "In4.Cu")
		(net "M_F_CPU1_SB_DQS_DN<5>")
	)
	(segment
		(start 153.386028 -226.962208)
		(end 152.999948 -227.348288)
		(width 0.18288)
		(layer "In4.Cu")
		(net "M_F_CPU1_SB_DQS_DN<5>")
	)
	(segment
		(start 150.716742 -229.807516)
		(end 150.54072 -229.807516)
		(width 0.18288)
		(layer "In4.Cu")
		(net "M_F_CPU1_SB_DQS_DN<5>")
	)
	(segment
		(start 163.9443 -225.288602)
		(end 162.428936 -224.660968)
		(width 0.18288)
		(layer "In4.Cu")
		(net "M_F_CPU1_SB_DQS_DN<5>")
	)
	(segment
		(start 161.325052 -224.652332)
		(end 160.526984 -224.652332)
		(width 0.18288)
		(layer "In4.Cu")
		(net "M_F_CPU1_SB_DQS_DN<5>")
	)
	(segment
		(start 162.428936 -224.660968)
		(end 162.283648 -224.660968)
		(width 0.18288)
		(layer "In4.Cu")
		(net "M_F_CPU1_SB_DQS_DN<5>")
	)
	(segment
		(start 149.206204 -231.142032)
		(end 149.206204 -231.318054)
		(width 0.18288)
		(layer "In4.Cu")
		(net "M_F_CPU1_SB_DQS_DN<5>")
	)
	(segment
		(start 151.103076 -229.421182)
		(end 150.716742 -229.807516)
		(width 0.18288)
		(layer "In4.Cu")
		(net "M_F_CPU1_SB_DQS_DN<5>")
	)
	(segment
		(start 155.53817 -225.605086)
		(end 155.41371 -225.480626)
		(width 0.18288)
		(layer "In4.Cu")
		(net "M_F_CPU1_SB_DQS_DN<5>")
	)
	(segment
		(start 141.001496 -235.39069)
		(end 140.978128 -235.39069)
		(width 0.088646)
		(layer "In4.Cu")
		(net "M_F_CPU1_SB_DQS_DN<5>")
	)
	(segment
		(start 169.218356 -225.767646)
		(end 168.32326 -226.138486)
		(width 0.18288)
		(layer "In4.Cu")
		(net "M_F_CPU1_SB_DQS_DN<5>")
	)
	(segment
		(start 155.41371 -225.480626)
		(end 154.86761 -225.480626)
		(width 0.18288)
		(layer "In4.Cu")
		(net "M_F_CPU1_SB_DQS_DN<5>")
	)
	(segment
		(start 153.948384 -226.399852)
		(end 153.948384 -226.575874)
		(width 0.18288)
		(layer "In4.Cu")
		(net "M_F_CPU1_SB_DQS_DN<5>")
	)
	(segment
		(start 148.257768 -232.090468)
		(end 148.257768 -232.26649)
		(width 0.18288)
		(layer "In4.Cu")
		(net "M_F_CPU1_SB_DQS_DN<5>")
	)
	(segment
		(start 157.516576 -225.793808)
		(end 157.203394 -225.480626)
		(width 0.18288)
		(layer "In4.Cu")
		(net "M_F_CPU1_SB_DQS_DN<5>")
	)
	(segment
		(start 132.936742 -237.163102)
		(end 132.781802 -237.204504)
		(width 0.088646)
		(layer "In4.Cu")
		(net "M_F_CPU1_SB_DQS_DN<5>")
	)
	(segment
		(start 162.000692 -224.943924)
		(end 161.616644 -224.943924)
		(width 0.18288)
		(layer "In4.Cu")
		(net "M_F_CPU1_SB_DQS_DN<5>")
	)
	(segment
		(start 138.156696 -237.096046)
		(end 138.141964 -237.08741)
		(width 0.088646)
		(layer "In4.Cu")
		(net "M_F_CPU1_SB_DQS_DN<5>")
	)
	(segment
		(start 150.15464 -230.369618)
		(end 149.768306 -230.755952)
		(width 0.18288)
		(layer "In4.Cu")
		(net "M_F_CPU1_SB_DQS_DN<5>")
	)
	(segment
		(start 139.839446 -236.937804)
		(end 139.614148 -237.163102)
		(width 0.088646)
		(layer "In4.Cu")
		(net "M_F_CPU1_SB_DQS_DN<5>")
	)
	(segment
		(start 151.489156 -228.85908)
		(end 151.103076 -229.24516)
		(width 0.18288)
		(layer "In4.Cu")
		(net "M_F_CPU1_SB_DQS_DN<5>")
	)
	(segment
		(start 165.04793 -224.912936)
		(end 164.14115 -225.288602)
		(width 0.18288)
		(layer "In4.Cu")
		(net "M_F_CPU1_SB_DQS_DN<5>")
	)
	(segment
		(start 150.54072 -229.807516)
		(end 150.15464 -230.193596)
		(width 0.18288)
		(layer "In4.Cu")
		(net "M_F_CPU1_SB_DQS_DN<5>")
	)
	(segment
		(start 133.062218 -237.090712)
		(end 132.936742 -237.163102)
		(width 0.088646)
		(layer "In4.Cu")
		(net "M_F_CPU1_SB_DQS_DN<5>")
	)
	(segment
		(start 164.14115 -225.288602)
		(end 163.9443 -225.288602)
		(width 0.18288)
		(layer "In4.Cu")
		(net "M_F_CPU1_SB_DQS_DN<5>")
	)
	(segment
		(start 158.16707 -225.527362)
		(end 157.900624 -225.793808)
		(width 0.18288)
		(layer "In4.Cu")
		(net "M_F_CPU1_SB_DQS_DN<5>")
	)
	(segment
		(start 160.526984 -224.652332)
		(end 158.413704 -225.527362)
		(width 0.18288)
		(layer "In4.Cu")
		(net "M_F_CPU1_SB_DQS_DN<5>")
	)
	(segment
		(start 156.08427 -225.605086)
		(end 155.53817 -225.605086)
		(width 0.18288)
		(layer "In4.Cu")
		(net "M_F_CPU1_SB_DQS_DN<5>")
	)
	(segment
		(start 137.767568 -237.08741)
		(end 137.767314 -237.087664)
		(width 0.088646)
		(layer "In4.Cu")
		(net "M_F_CPU1_SB_DQS_DN<5>")
	)
	(segment
		(start 172.604176 -227.49383)
		(end 172.335444 -227.225098)
		(width 0.18288)
		(layer "In4.Cu")
		(net "M_F_CPU1_SB_DQS_DN<5>")
	)
	(segment
		(start 176.247044 -227.656136)
		(end 175.979074 -227.388166)
		(width 0.18288)
		(layer "In4.Cu")
		(net "M_F_CPU1_SB_DQS_DN<5>")
	)
	(segment
		(start 176.896014 -227.91674)
		(end 176.63541 -227.656136)
		(width 0.18288)
		(layer "In4.Cu")
		(net "M_F_CPU1_SB_DQS_DN<5>")
	)
	(segment
		(start 175.76165 -226.866196)
		(end 175.651668 -226.756468)
		(width 0.18288)
		(layer "In4.Cu")
		(net "M_F_CPU1_SB_DQS_DN<5>")
	)
	(segment
		(start 136.277096 -237.096046)
		(end 136.262364 -237.08741)
		(width 0.088646)
		(layer "In4.Cu")
		(net "M_F_CPU1_SB_DQS_DN<5>")
	)
	(segment
		(start 139.614148 -237.163102)
		(end 139.364212 -237.163102)
		(width 0.088646)
		(layer "In4.Cu")
		(net "M_F_CPU1_SB_DQS_DN<5>")
	)
	(segment
		(start 170.139614 -226.016566)
		(end 169.538904 -225.767646)
		(width 0.18288)
		(layer "In4.Cu")
		(net "M_F_CPU1_SB_DQS_DN<5>")
	)
	(segment
		(start 171.3484 -227.225098)
		(end 170.139614 -226.016566)
		(width 0.18288)
		(layer "In4.Cu")
		(net "M_F_CPU1_SB_DQS_DN<5>")
	)
	(segment
		(start 149.768306 -230.755952)
		(end 149.592284 -230.755952)
		(width 0.18288)
		(layer "In4.Cu")
		(net "M_F_CPU1_SB_DQS_DN<5>")
	)
	(segment
		(start 176.63541 -227.656136)
		(end 176.247044 -227.656136)
		(width 0.18288)
		(layer "In4.Cu")
		(net "M_F_CPU1_SB_DQS_DN<5>")
	)
	(segment
		(start 148.257768 -232.26649)
		(end 147.871434 -232.652824)
		(width 0.18288)
		(layer "In4.Cu")
		(net "M_F_CPU1_SB_DQS_DN<5>")
	)
	(segment
		(start 148.643848 -231.704388)
		(end 148.257768 -232.090468)
		(width 0.18288)
		(layer "In4.Cu")
		(net "M_F_CPU1_SB_DQS_DN<5>")
	)
	(segment
		(start 175.308006 -226.61372)
		(end 174.679102 -226.61372)
		(width 0.18288)
		(layer "In4.Cu")
		(net "M_F_CPU1_SB_DQS_DN<5>")
	)
	(segment
		(start 133.068314 -237.08741)
		(end 133.062218 -237.090712)
		(width 0.088646)
		(layer "In4.Cu")
		(net "M_F_CPU1_SB_DQS_DN<5>")
	)
	(segment
		(start 174.679102 -226.61372)
		(end 174.063406 -227.229416)
		(width 0.18288)
		(layer "In4.Cu")
		(net "M_F_CPU1_SB_DQS_DN<5>")
	)
	(segment
		(start 147.871434 -232.652824)
		(end 147.695412 -232.652824)
		(width 0.18288)
		(layer "In4.Cu")
		(net "M_F_CPU1_SB_DQS_DN<5>")
	)
	(segment
		(start 175.979074 -227.388166)
		(end 175.76165 -226.866196)
		(width 0.18288)
		(layer "In4.Cu")
		(net "M_F_CPU1_SB_DQS_DN<5>")
	)
	(segment
		(start 152.999948 -227.52431)
		(end 152.613614 -227.910644)
		(width 0.18288)
		(layer "In4.Cu")
		(net "M_F_CPU1_SB_DQS_DN<5>")
	)
	(segment
		(start 151.665178 -228.85908)
		(end 151.489156 -228.85908)
		(width 0.18288)
		(layer "In4.Cu")
		(net "M_F_CPU1_SB_DQS_DN<5>")
	)
	(segment
		(start 174.063406 -227.229416)
		(end 173.252638 -227.229416)
		(width 0.18288)
		(layer "In4.Cu")
		(net "M_F_CPU1_SB_DQS_DN<5>")
	)
	(segment
		(start 153.56205 -226.962208)
		(end 153.386028 -226.962208)
		(width 0.18288)
		(layer "In4.Cu")
		(net "M_F_CPU1_SB_DQS_DN<5>")
	)
	(segment
		(start 166.80434 -226.138486)
		(end 165.791642 -225.126042)
		(width 0.18288)
		(layer "In4.Cu")
		(net "M_F_CPU1_SB_DQS_DN<5>")
	)
	(segment
		(start 165.276022 -224.912936)
		(end 165.04793 -224.912936)
		(width 0.18288)
		(layer "In4.Cu")
		(net "M_F_CPU1_SB_DQS_DN<5>")
	)
	(segment
		(start 147.695412 -232.652824)
		(end 147.309332 -233.038904)
		(width 0.18288)
		(layer "In4.Cu")
		(net "M_F_CPU1_SB_DQS_DN<5>")
	)
	(segment
		(start 152.051512 -228.296724)
		(end 152.051512 -228.472746)
		(width 0.18288)
		(layer "In4.Cu")
		(net "M_F_CPU1_SB_DQS_DN<5>")
	)
	(segment
		(start 143.912844 -233.038904)
		(end 141.561058 -235.39069)
		(width 0.18288)
		(layer "In4.Cu")
		(net "M_F_CPU1_SB_DQS_DN<5>")
	)
	(segment
		(start 153.948384 -226.575874)
		(end 153.56205 -226.962208)
		(width 0.18288)
		(layer "In4.Cu")
		(net "M_F_CPU1_SB_DQS_DN<5>")
	)
	(segment
		(start 148.81987 -231.704388)
		(end 148.643848 -231.704388)
		(width 0.18288)
		(layer "In4.Cu")
		(net "M_F_CPU1_SB_DQS_DN<5>")
	)
	(segment
		(start 134.008368 -237.08741)
		(end 133.997954 -237.093506)
		(width 0.088646)
		(layer "In4.Cu")
		(net "M_F_CPU1_SB_DQS_DN<5>")
	)
	(segment
		(start 149.206204 -231.318054)
		(end 148.81987 -231.704388)
		(width 0.18288)
		(layer "In4.Cu")
		(net "M_F_CPU1_SB_DQS_DN<5>")
	)
	(segment
		(start 150.15464 -230.193596)
		(end 150.15464 -230.369618)
		(width 0.18288)
		(layer "In4.Cu")
		(net "M_F_CPU1_SB_DQS_DN<5>")
	)
	(segment
		(start 165.791642 -225.126042)
		(end 165.276022 -224.912936)
		(width 0.18288)
		(layer "In4.Cu")
		(net "M_F_CPU1_SB_DQS_DN<5>")
	)
	(segment
		(start 162.283648 -224.660968)
		(end 162.000692 -224.943924)
		(width 0.18288)
		(layer "In4.Cu")
		(net "M_F_CPU1_SB_DQS_DN<5>")
	)
	(segment
		(start 172.988224 -227.49383)
		(end 172.604176 -227.49383)
		(width 0.18288)
		(layer "In4.Cu")
		(net "M_F_CPU1_SB_DQS_DN<5>")
	)
	(segment
		(start 147.309332 -233.038904)
		(end 143.912844 -233.038904)
		(width 0.18288)
		(layer "In4.Cu")
		(net "M_F_CPU1_SB_DQS_DN<5>")
	)
	(segment
		(start 152.613614 -227.910644)
		(end 152.437592 -227.910644)
		(width 0.18288)
		(layer "In4.Cu")
		(net "M_F_CPU1_SB_DQS_DN<5>")
	)
	(segment
		(start 154.86761 -225.480626)
		(end 153.948384 -226.399852)
		(width 0.18288)
		(layer "In4.Cu")
		(net "M_F_CPU1_SB_DQS_DN<5>")
	)
	(segment
		(start 140.918184 -235.330746)
		(end 140.594842 -235.330746)
		(width 0.088646)
		(layer "In4.Cu")
		(net "M_F_CPU1_SB_DQS_DN<5>")
	)
	(segment
		(start 135.337296 -237.096046)
		(end 135.322564 -237.08741)
		(width 0.088646)
		(layer "In4.Cu")
		(net "M_F_CPU1_SB_DQS_DN<5>")
	)
	(segment
		(start 149.592284 -230.755952)
		(end 149.206204 -231.142032)
		(width 0.18288)
		(layer "In4.Cu")
		(net "M_F_CPU1_SB_DQS_DN<5>")
	)
	(segment
		(start 132.781802 -237.204504)
		(end 132.390388 -237.204504)
		(width 0.088646)
		(layer "In4.Cu")
		(net "M_F_CPU1_SB_DQS_DN<5>")
	)
	(segment
		(start 140.594842 -235.330746)
		(end 140.146278 -235.77931)
		(width 0.088646)
		(layer "In4.Cu")
		(net "M_F_CPU1_SB_DQS_DN<5>")
	)
	(segment
		(start 152.999948 -227.348288)
		(end 152.999948 -227.52431)
		(width 0.18288)
		(layer "In4.Cu")
		(net "M_F_CPU1_SB_DQS_DN<5>")
	)
	(segment
		(start 157.203394 -225.480626)
		(end 156.20873 -225.480626)
		(width 0.18288)
		(layer "In4.Cu")
		(net "M_F_CPU1_SB_DQS_DN<5>")
	)
	(segment
		(start 173.252638 -227.229416)
		(end 172.988224 -227.49383)
		(width 0.18288)
		(layer "In4.Cu")
		(net "M_F_CPU1_SB_DQS_DN<5>")
	)
	(segment
		(start 158.413704 -225.527362)
		(end 158.16707 -225.527362)
		(width 0.18288)
		(layer "In4.Cu")
		(net "M_F_CPU1_SB_DQS_DN<5>")
	)
	(segment
		(start 161.616644 -224.943924)
		(end 161.325052 -224.652332)
		(width 0.18288)
		(layer "In4.Cu")
		(net "M_F_CPU1_SB_DQS_DN<5>")
	)
	(segment
		(start 152.051512 -228.472746)
		(end 151.665178 -228.85908)
		(width 0.18288)
		(layer "In4.Cu")
		(net "M_F_CPU1_SB_DQS_DN<5>")
	)
	(segment
		(start 175.651668 -226.756468)
		(end 175.308006 -226.61372)
		(width 0.18288)
		(layer "In4.Cu")
		(net "M_F_CPU1_SB_DQS_DN<5>")
	)
	(segment
		(start 156.20873 -225.480626)
		(end 156.08427 -225.605086)
		(width 0.18288)
		(layer "In4.Cu")
		(net "M_F_CPU1_SB_DQS_DN<5>")
	)
	(segment
		(start 140.978128 -235.39069)
		(end 140.918184 -235.330746)
		(width 0.088646)
		(layer "In4.Cu")
		(net "M_F_CPU1_SB_DQS_DN<5>")
	)
	(segment
		(start 172.335444 -227.225098)
		(end 171.3484 -227.225098)
		(width 0.18288)
		(layer "In4.Cu")
		(net "M_F_CPU1_SB_DQS_DN<5>")
	)
	(segment
		(start 132.327904 -237.262162)
		(end 132.315966 -237.411514)
		(width 0.088646)
		(layer "In4.Cu")
		(net "M_F_CPU1_SB_DQS_DN<5>")
	)
	(segment
		(start 140.146278 -236.478826)
		(end 139.839446 -236.937804)
		(width 0.088646)
		(layer "In4.Cu")
		(net "M_F_CPU1_SB_DQS_DN<5>")
	)
	(segment
		(start 168.32326 -226.138486)
		(end 166.80434 -226.138486)
		(width 0.18288)
		(layer "In4.Cu")
		(net "M_F_CPU1_SB_DQS_DN<5>")
	)
	(segment
		(start 151.103076 -229.24516)
		(end 151.103076 -229.421182)
		(width 0.18288)
		(layer "In4.Cu")
		(net "M_F_CPU1_SB_DQS_DN<5>")
	)
	(arc
		(start 134.948168 -237.08741)
		(mid 134.665466 -237.163186)
		(end 134.382764 -237.08741)
		(width 0.088646)
		(layer "In4.Cu")
		(net "M_F_CPU1_SB_DQS_DN<5>")
	)
	(arc
		(start 138.707368 -237.08741)
		(mid 138.433169 -237.163245)
		(end 138.156696 -237.096046)
		(width 0.088646)
		(layer "In4.Cu")
		(net "M_F_CPU1_SB_DQS_DN<5>")
	)
	(arc
		(start 133.997954 -237.093506)
		(mid 133.719522 -237.163352)
		(end 133.44271 -237.08741)
		(width 0.088646)
		(layer "In4.Cu")
		(net "M_F_CPU1_SB_DQS_DN<5>")
	)
	(arc
		(start 139.081764 -237.08741)
		(mid 138.894566 -237.037233)
		(end 138.707368 -237.08741)
		(width 0.088646)
		(layer "In4.Cu")
		(net "M_F_CPU1_SB_DQS_DN<5>")
	)
	(arc
		(start 136.827768 -237.08741)
		(mid 136.553569 -237.163245)
		(end 136.277096 -237.096046)
		(width 0.088646)
		(layer "In4.Cu")
		(net "M_F_CPU1_SB_DQS_DN<5>")
	)
	(arc
		(start 135.322564 -237.08741)
		(mid 135.135366 -237.037233)
		(end 134.948168 -237.08741)
		(width 0.088646)
		(layer "In4.Cu")
		(net "M_F_CPU1_SB_DQS_DN<5>")
	)
	(arc
		(start 132.390388 -237.204504)
		(mid 132.347861 -237.221117)
		(end 132.327904 -237.262162)
		(width 0.088646)
		(layer "In4.Cu")
		(net "M_F_CPU1_SB_DQS_DN<5>")
	)
	(arc
		(start 138.141964 -237.08741)
		(mid 137.954766 -237.037233)
		(end 137.767568 -237.08741)
		(width 0.088646)
		(layer "In4.Cu")
		(net "M_F_CPU1_SB_DQS_DN<5>")
	)
	(arc
		(start 139.364212 -237.163102)
		(mid 139.218004 -237.143853)
		(end 139.081764 -237.08741)
		(width 0.088646)
		(layer "In4.Cu")
		(net "M_F_CPU1_SB_DQS_DN<5>")
	)
	(arc
		(start 133.44271 -237.08741)
		(mid 133.255512 -237.037233)
		(end 133.068314 -237.08741)
		(width 0.088646)
		(layer "In4.Cu")
		(net "M_F_CPU1_SB_DQS_DN<5>")
	)
	(arc
		(start 137.202164 -237.08741)
		(mid 137.014966 -237.037233)
		(end 136.827768 -237.08741)
		(width 0.088646)
		(layer "In4.Cu")
		(net "M_F_CPU1_SB_DQS_DN<5>")
	)
	(arc
		(start 137.767314 -237.087664)
		(mid 137.484693 -237.163279)
		(end 137.202164 -237.08741)
		(width 0.088646)
		(layer "In4.Cu")
		(net "M_F_CPU1_SB_DQS_DN<5>")
	)
	(arc
		(start 135.887968 -237.08741)
		(mid 135.613769 -237.163245)
		(end 135.337296 -237.096046)
		(width 0.088646)
		(layer "In4.Cu")
		(net "M_F_CPU1_SB_DQS_DN<5>")
	)
	(arc
		(start 134.382764 -237.08741)
		(mid 134.195566 -237.037233)
		(end 134.008368 -237.08741)
		(width 0.088646)
		(layer "In4.Cu")
		(net "M_F_CPU1_SB_DQS_DN<5>")
	)
	(arc
		(start 136.262364 -237.08741)
		(mid 136.075166 -237.037233)
		(end 135.887968 -237.08741)
		(width 0.088646)
		(layer "In4.Cu")
		(net "M_F_CPU1_SB_DQS_DN<5>")
	)
	(segment
		(start 183.549544 -236.566964)
		(end 183.99506 -237.01248)
		(width 0.20066)
		(layer "F.Cu")
		(net "M_F_CPU1_SB_DQS_DN<4>")
	)
	(segment
		(start 182.773828 -236.852714)
		(end 183.059578 -236.566964)
		(width 0.20066)
		(layer "F.Cu")
		(net "M_F_CPU1_SB_DQS_DN<4>")
	)
	(segment
		(start 184.786778 -237.01248)
		(end 185.041032 -237.266734)
		(width 0.20066)
		(layer "F.Cu")
		(net "M_F_CPU1_SB_DQS_DN<4>")
	)
	(segment
		(start 135.605266 -240.389156)
		(end 135.605266 -239.853216)
		(width 0.20066)
		(layer "F.Cu")
		(net "M_F_CPU1_SB_DQS_DN<4>")
	)
	(segment
		(start 180.43398 -236.841792)
		(end 182.444136 -236.841792)
		(width 0.1016)
		(layer "F.Cu")
		(net "M_F_CPU1_SB_DQS_DN<4>")
	)
	(segment
		(start 179.833524 -236.57052)
		(end 180.110892 -236.847888)
		(width 0.20066)
		(layer "F.Cu")
		(net "M_F_CPU1_SB_DQS_DN<4>")
	)
	(segment
		(start 176.896014 -237.266734)
		(end 178.000914 -237.266734)
		(width 0.20066)
		(layer "F.Cu")
		(net "M_F_CPU1_SB_DQS_DN<4>")
	)
	(segment
		(start 183.99506 -237.01248)
		(end 184.786778 -237.01248)
		(width 0.20066)
		(layer "F.Cu")
		(net "M_F_CPU1_SB_DQS_DN<4>")
	)
	(segment
		(start 185.041032 -237.266734)
		(end 185.544714 -237.266734)
		(width 0.20066)
		(layer "F.Cu")
		(net "M_F_CPU1_SB_DQS_DN<4>")
	)
	(segment
		(start 179.711096 -236.57052)
		(end 179.833524 -236.57052)
		(width 0.20066)
		(layer "F.Cu")
		(net "M_F_CPU1_SB_DQS_DN<4>")
	)
	(segment
		(start 180.423058 -236.847888)
		(end 180.427884 -236.847888)
		(width 0.101854)
		(layer "F.Cu")
		(net "M_F_CPU1_SB_DQS_DN<4>")
	)
	(segment
		(start 180.427884 -236.847888)
		(end 180.43398 -236.841792)
		(width 0.1016)
		(layer "F.Cu")
		(net "M_F_CPU1_SB_DQS_DN<4>")
	)
	(segment
		(start 182.455058 -236.852714)
		(end 182.773828 -236.852714)
		(width 0.20066)
		(layer "F.Cu")
		(net "M_F_CPU1_SB_DQS_DN<4>")
	)
	(segment
		(start 183.059578 -236.566964)
		(end 183.549544 -236.566964)
		(width 0.20066)
		(layer "F.Cu")
		(net "M_F_CPU1_SB_DQS_DN<4>")
	)
	(segment
		(start 182.444136 -236.841792)
		(end 182.455058 -236.852714)
		(width 0.1016)
		(layer "F.Cu")
		(net "M_F_CPU1_SB_DQS_DN<4>")
	)
	(segment
		(start 180.110892 -236.847888)
		(end 180.423058 -236.847888)
		(width 0.20066)
		(layer "F.Cu")
		(net "M_F_CPU1_SB_DQS_DN<4>")
	)
	(segment
		(start 178.802792 -236.995462)
		(end 179.286154 -236.995462)
		(width 0.20066)
		(layer "F.Cu")
		(net "M_F_CPU1_SB_DQS_DN<4>")
	)
	(segment
		(start 178.53152 -237.266734)
		(end 178.802792 -236.995462)
		(width 0.20066)
		(layer "F.Cu")
		(net "M_F_CPU1_SB_DQS_DN<4>")
	)
	(segment
		(start 179.286154 -236.995462)
		(end 179.711096 -236.57052)
		(width 0.20066)
		(layer "F.Cu")
		(net "M_F_CPU1_SB_DQS_DN<4>")
	)
	(segment
		(start 178.000914 -237.266734)
		(end 178.53152 -237.266734)
		(width 0.20066)
		(layer "F.Cu")
		(net "M_F_CPU1_SB_DQS_DN<4>")
	)
	(segment
		(start 139.086844 -240.345976)
		(end 139.084812 -240.34496)
		(width 0.088646)
		(layer "In2.Cu")
		(net "M_F_CPU1_SB_DQS_DN<4>")
	)
	(segment
		(start 142.102078 -240.777522)
		(end 140.518896 -240.777522)
		(width 0.18288)
		(layer "In2.Cu")
		(net "M_F_CPU1_SB_DQS_DN<4>")
	)
	(segment
		(start 148.284438 -240.777522)
		(end 148.159978 -240.901982)
		(width 0.18288)
		(layer "In2.Cu")
		(net "M_F_CPU1_SB_DQS_DN<4>")
	)
	(segment
		(start 150.179278 -240.777522)
		(end 149.630638 -240.777522)
		(width 0.18288)
		(layer "In2.Cu")
		(net "M_F_CPU1_SB_DQS_DN<4>")
	)
	(segment
		(start 171.559728 -236.36351)
		(end 171.120308 -235.92409)
		(width 0.18288)
		(layer "In2.Cu")
		(net "M_F_CPU1_SB_DQS_DN<4>")
	)
	(segment
		(start 175.186848 -237.183676)
		(end 174.844964 -237.041944)
		(width 0.18288)
		(layer "In2.Cu")
		(net "M_F_CPU1_SB_DQS_DN<4>")
	)
	(segment
		(start 156.8323 -237.479332)
		(end 156.8323 -237.479586)
		(width 0.18288)
		(layer "In2.Cu")
		(net "M_F_CPU1_SB_DQS_DN<4>")
	)
	(segment
		(start 144.121378 -240.901982)
		(end 143.572738 -240.901982)
		(width 0.18288)
		(layer "In2.Cu")
		(net "M_F_CPU1_SB_DQS_DN<4>")
	)
	(segment
		(start 138.156696 -240.351564)
		(end 138.141964 -240.342928)
		(width 0.088646)
		(layer "In2.Cu")
		(net "M_F_CPU1_SB_DQS_DN<4>")
	)
	(segment
		(start 167.802306 -235.99521)
		(end 167.414194 -235.607098)
		(width 0.18288)
		(layer "In2.Cu")
		(net "M_F_CPU1_SB_DQS_DN<4>")
	)
	(segment
		(start 144.245838 -240.777522)
		(end 144.121378 -240.901982)
		(width 0.18288)
		(layer "In2.Cu")
		(net "M_F_CPU1_SB_DQS_DN<4>")
	)
	(segment
		(start 165.472364 -235.142278)
		(end 164.04844 -235.142278)
		(width 0.18288)
		(layer "In2.Cu")
		(net "M_F_CPU1_SB_DQS_DN<4>")
	)
	(segment
		(start 159.548576 -236.87532)
		(end 159.453326 -236.78007)
		(width 0.18288)
		(layer "In2.Cu")
		(net "M_F_CPU1_SB_DQS_DN<4>")
	)
	(segment
		(start 139.478766 -240.717578)
		(end 139.157456 -240.396522)
		(width 0.088646)
		(layer "In2.Cu")
		(net "M_F_CPU1_SB_DQS_DN<4>")
	)
	(segment
		(start 150.976838 -240.777522)
		(end 150.852378 -240.901982)
		(width 0.18288)
		(layer "In2.Cu")
		(net "M_F_CPU1_SB_DQS_DN<4>")
	)
	(segment
		(start 155.438094 -239.04956)
		(end 155.049982 -239.437672)
		(width 0.18288)
		(layer "In2.Cu")
		(net "M_F_CPU1_SB_DQS_DN<4>")
	)
	(segment
		(start 176.296066 -236.95279)
		(end 175.738282 -237.183676)
		(width 0.18288)
		(layer "In2.Cu")
		(net "M_F_CPU1_SB_DQS_DN<4>")
	)
	(segment
		(start 154.09799 -240.389664)
		(end 153.921968 -240.389664)
		(width 0.18288)
		(layer "In2.Cu")
		(net "M_F_CPU1_SB_DQS_DN<4>")
	)
	(segment
		(start 163.990528 -235.20019)
		(end 163.962334 -235.228384)
		(width 0.16002)
		(layer "In2.Cu")
		(net "M_F_CPU1_SB_DQS_DN<4>")
	)
	(segment
		(start 165.765226 -234.849416)
		(end 165.472364 -235.142278)
		(width 0.18288)
		(layer "In2.Cu")
		(net "M_F_CPU1_SB_DQS_DN<4>")
	)
	(segment
		(start 146.140678 -240.777522)
		(end 145.592038 -240.777522)
		(width 0.18288)
		(layer "In2.Cu")
		(net "M_F_CPU1_SB_DQS_DN<4>")
	)
	(segment
		(start 172.582078 -236.840776)
		(end 172.293788 -236.552486)
		(width 0.18288)
		(layer "In2.Cu")
		(net "M_F_CPU1_SB_DQS_DN<4>")
	)
	(segment
		(start 171.120308 -235.92409)
		(end 169.833798 -235.92409)
		(width 0.18288)
		(layer "In2.Cu")
		(net "M_F_CPU1_SB_DQS_DN<4>")
	)
	(segment
		(start 159.731456 -237.042452)
		(end 159.592518 -236.903514)
		(width 0.16002)
		(layer "In2.Cu")
		(net "M_F_CPU1_SB_DQS_DN<4>")
	)
	(segment
		(start 169.519346 -236.238542)
		(end 169.330878 -236.42701)
		(width 0.18288)
		(layer "In2.Cu")
		(net "M_F_CPU1_SB_DQS_DN<4>")
	)
	(segment
		(start 140.518896 -240.777522)
		(end 140.458952 -240.717578)
		(width 0.088646)
		(layer "In2.Cu")
		(net "M_F_CPU1_SB_DQS_DN<4>")
	)
	(segment
		(start 137.216896 -240.351564)
		(end 137.202164 -240.342928)
		(width 0.088646)
		(layer "In2.Cu")
		(net "M_F_CPU1_SB_DQS_DN<4>")
	)
	(segment
		(start 143.448278 -240.777522)
		(end 142.899638 -240.777522)
		(width 0.18288)
		(layer "In2.Cu")
		(net "M_F_CPU1_SB_DQS_DN<4>")
	)
	(segment
		(start 148.833078 -240.777522)
		(end 148.284438 -240.777522)
		(width 0.18288)
		(layer "In2.Cu")
		(net "M_F_CPU1_SB_DQS_DN<4>")
	)
	(segment
		(start 154.486102 -240.001552)
		(end 154.09799 -240.389664)
		(width 0.18288)
		(layer "In2.Cu")
		(net "M_F_CPU1_SB_DQS_DN<4>")
	)
	(segment
		(start 150.852378 -240.901982)
		(end 150.303738 -240.901982)
		(width 0.18288)
		(layer "In2.Cu")
		(net "M_F_CPU1_SB_DQS_DN<4>")
	)
	(segment
		(start 136.7409 -239.533938)
		(end 136.73201 -239.528858)
		(width 0.088646)
		(layer "In2.Cu")
		(net "M_F_CPU1_SB_DQS_DN<4>")
	)
	(segment
		(start 173.25721 -236.606842)
		(end 173.023276 -236.840776)
		(width 0.18288)
		(layer "In2.Cu")
		(net "M_F_CPU1_SB_DQS_DN<4>")
	)
	(segment
		(start 143.572738 -240.901982)
		(end 143.448278 -240.777522)
		(width 0.18288)
		(layer "In2.Cu")
		(net "M_F_CPU1_SB_DQS_DN<4>")
	)
	(segment
		(start 135.621776 -239.648492)
		(end 135.605266 -239.665002)
		(width 0.088646)
		(layer "In2.Cu")
		(net "M_F_CPU1_SB_DQS_DN<4>")
	)
	(segment
		(start 176.58207 -236.95279)
		(end 176.296066 -236.95279)
		(width 0.18288)
		(layer "In2.Cu")
		(net "M_F_CPU1_SB_DQS_DN<4>")
	)
	(segment
		(start 161.202624 -236.524546)
		(end 160.467294 -237.259876)
		(width 0.18288)
		(layer "In2.Cu")
		(net "M_F_CPU1_SB_DQS_DN<4>")
	)
	(segment
		(start 136.919462 -239.86744)
		(end 136.919462 -239.853216)
		(width 0.088646)
		(layer "In2.Cu")
		(net "M_F_CPU1_SB_DQS_DN<4>")
	)
	(segment
		(start 163.779454 -235.411264)
		(end 163.374832 -235.815886)
		(width 0.18288)
		(layer "In2.Cu")
		(net "M_F_CPU1_SB_DQS_DN<4>")
	)
	(segment
		(start 174.844964 -237.041944)
		(end 174.552864 -236.749844)
		(width 0.18288)
		(layer "In2.Cu")
		(net "M_F_CPU1_SB_DQS_DN<4>")
	)
	(segment
		(start 154.486102 -239.82553)
		(end 154.486102 -240.001552)
		(width 0.18288)
		(layer "In2.Cu")
		(net "M_F_CPU1_SB_DQS_DN<4>")
	)
	(segment
		(start 159.75965 -237.086394)
		(end 159.731456 -237.0582)
		(width 0.16002)
		(layer "In2.Cu")
		(net "M_F_CPU1_SB_DQS_DN<4>")
	)
	(segment
		(start 163.962334 -235.228384)
		(end 163.946078 -235.228384)
		(width 0.16002)
		(layer "In2.Cu")
		(net "M_F_CPU1_SB_DQS_DN<4>")
	)
	(segment
		(start 172.293788 -236.552486)
		(end 172.014896 -236.552486)
		(width 0.18288)
		(layer "In2.Cu")
		(net "M_F_CPU1_SB_DQS_DN<4>")
	)
	(segment
		(start 140.458952 -240.717578)
		(end 139.478766 -240.717578)
		(width 0.088646)
		(layer "In2.Cu")
		(net "M_F_CPU1_SB_DQS_DN<4>")
	)
	(segment
		(start 156.8323 -237.479586)
		(end 156.39034 -237.921546)
		(width 0.18288)
		(layer "In2.Cu")
		(net "M_F_CPU1_SB_DQS_DN<4>")
	)
	(segment
		(start 146.265138 -240.901982)
		(end 146.140678 -240.777522)
		(width 0.18288)
		(layer "In2.Cu")
		(net "M_F_CPU1_SB_DQS_DN<4>")
	)
	(segment
		(start 136.352534 -239.531906)
		(end 136.35228 -239.531906)
		(width 0.088646)
		(layer "In2.Cu")
		(net "M_F_CPU1_SB_DQS_DN<4>")
	)
	(segment
		(start 167.978328 -235.99521)
		(end 167.802306 -235.99521)
		(width 0.18288)
		(layer "In2.Cu")
		(net "M_F_CPU1_SB_DQS_DN<4>")
	)
	(segment
		(start 159.592518 -236.903514)
		(end 159.57677 -236.903514)
		(width 0.16002)
		(layer "In2.Cu")
		(net "M_F_CPU1_SB_DQS_DN<4>")
	)
	(segment
		(start 169.54754 -236.1946)
		(end 169.54754 -236.210348)
		(width 0.16002)
		(layer "In2.Cu")
		(net "M_F_CPU1_SB_DQS_DN<4>")
	)
	(segment
		(start 142.899638 -240.777522)
		(end 142.775178 -240.901982)
		(width 0.18288)
		(layer "In2.Cu")
		(net "M_F_CPU1_SB_DQS_DN<4>")
	)
	(segment
		(start 148.957538 -240.901982)
		(end 148.833078 -240.777522)
		(width 0.18288)
		(layer "In2.Cu")
		(net "M_F_CPU1_SB_DQS_DN<4>")
	)
	(segment
		(start 175.738282 -237.183676)
		(end 175.186848 -237.183676)
		(width 0.18288)
		(layer "In2.Cu")
		(net "M_F_CPU1_SB_DQS_DN<4>")
	)
	(segment
		(start 169.833798 -235.92409)
		(end 169.73042 -236.027468)
		(width 0.18288)
		(layer "In2.Cu")
		(net "M_F_CPU1_SB_DQS_DN<4>")
	)
	(segment
		(start 144.918938 -240.901982)
		(end 144.794478 -240.777522)
		(width 0.18288)
		(layer "In2.Cu")
		(net "M_F_CPU1_SB_DQS_DN<4>")
	)
	(segment
		(start 169.54754 -236.210348)
		(end 169.519346 -236.238542)
		(width 0.16002)
		(layer "In2.Cu")
		(net "M_F_CPU1_SB_DQS_DN<4>")
	)
	(segment
		(start 166.558214 -234.849416)
		(end 165.765226 -234.849416)
		(width 0.18288)
		(layer "In2.Cu")
		(net "M_F_CPU1_SB_DQS_DN<4>")
	)
	(segment
		(start 135.845804 -239.555782)
		(end 135.621776 -239.648492)
		(width 0.088646)
		(layer "In2.Cu")
		(net "M_F_CPU1_SB_DQS_DN<4>")
	)
	(segment
		(start 174.207678 -236.606842)
		(end 173.25721 -236.606842)
		(width 0.18288)
		(layer "In2.Cu")
		(net "M_F_CPU1_SB_DQS_DN<4>")
	)
	(segment
		(start 139.087352 -240.345976)
		(end 139.087098 -240.34623)
		(width 0.088646)
		(layer "In2.Cu")
		(net "M_F_CPU1_SB_DQS_DN<4>")
	)
	(segment
		(start 156.001974 -238.48568)
		(end 155.825952 -238.48568)
		(width 0.18288)
		(layer "In2.Cu")
		(net "M_F_CPU1_SB_DQS_DN<4>")
	)
	(segment
		(start 145.592038 -240.777522)
		(end 145.467578 -240.901982)
		(width 0.18288)
		(layer "In2.Cu")
		(net "M_F_CPU1_SB_DQS_DN<4>")
	)
	(segment
		(start 139.142978 -240.380012)
		(end 139.087352 -240.345976)
		(width 0.088646)
		(layer "In2.Cu")
		(net "M_F_CPU1_SB_DQS_DN<4>")
	)
	(segment
		(start 153.921968 -240.389664)
		(end 153.53411 -240.777522)
		(width 0.18288)
		(layer "In2.Cu")
		(net "M_F_CPU1_SB_DQS_DN<4>")
	)
	(segment
		(start 155.438094 -238.873538)
		(end 155.438094 -239.04956)
		(width 0.18288)
		(layer "In2.Cu")
		(net "M_F_CPU1_SB_DQS_DN<4>")
	)
	(segment
		(start 160.467294 -237.259876)
		(end 159.933132 -237.259876)
		(width 0.18288)
		(layer "In2.Cu")
		(net "M_F_CPU1_SB_DQS_DN<4>")
	)
	(segment
		(start 159.933132 -237.259876)
		(end 159.75965 -237.086394)
		(width 0.18288)
		(layer "In2.Cu")
		(net "M_F_CPU1_SB_DQS_DN<4>")
	)
	(segment
		(start 157.884114 -237.043214)
		(end 156.8323 -237.479332)
		(width 0.18288)
		(layer "In2.Cu")
		(net "M_F_CPU1_SB_DQS_DN<4>")
	)
	(segment
		(start 149.506178 -240.901982)
		(end 148.957538 -240.901982)
		(width 0.18288)
		(layer "In2.Cu")
		(net "M_F_CPU1_SB_DQS_DN<4>")
	)
	(segment
		(start 169.330878 -236.42701)
		(end 168.410128 -236.42701)
		(width 0.18288)
		(layer "In2.Cu")
		(net "M_F_CPU1_SB_DQS_DN<4>")
	)
	(segment
		(start 167.414194 -235.431076)
		(end 167.026336 -235.043218)
		(width 0.18288)
		(layer "In2.Cu")
		(net "M_F_CPU1_SB_DQS_DN<4>")
	)
	(segment
		(start 153.53411 -240.777522)
		(end 150.976838 -240.777522)
		(width 0.18288)
		(layer "In2.Cu")
		(net "M_F_CPU1_SB_DQS_DN<4>")
	)
	(segment
		(start 136.357614 -239.528858)
		(end 136.352534 -239.531906)
		(width 0.088646)
		(layer "In2.Cu")
		(net "M_F_CPU1_SB_DQS_DN<4>")
	)
	(segment
		(start 148.159978 -240.901982)
		(end 147.611338 -240.901982)
		(width 0.18288)
		(layer "In2.Cu")
		(net "M_F_CPU1_SB_DQS_DN<4>")
	)
	(segment
		(start 139.087098 -240.34623)
		(end 139.086844 -240.345976)
		(width 0.088646)
		(layer "In2.Cu")
		(net "M_F_CPU1_SB_DQS_DN<4>")
	)
	(segment
		(start 150.303738 -240.901982)
		(end 150.179278 -240.777522)
		(width 0.18288)
		(layer "In2.Cu")
		(net "M_F_CPU1_SB_DQS_DN<4>")
	)
	(segment
		(start 147.611338 -240.901982)
		(end 147.486878 -240.777522)
		(width 0.18288)
		(layer "In2.Cu")
		(net "M_F_CPU1_SB_DQS_DN<4>")
	)
	(segment
		(start 146.813778 -240.901982)
		(end 146.265138 -240.901982)
		(width 0.18288)
		(layer "In2.Cu")
		(net "M_F_CPU1_SB_DQS_DN<4>")
	)
	(segment
		(start 155.049982 -239.437672)
		(end 154.87396 -239.437672)
		(width 0.18288)
		(layer "In2.Cu")
		(net "M_F_CPU1_SB_DQS_DN<4>")
	)
	(segment
		(start 173.023276 -236.840776)
		(end 172.582078 -236.840776)
		(width 0.18288)
		(layer "In2.Cu")
		(net "M_F_CPU1_SB_DQS_DN<4>")
	)
	(segment
		(start 156.390086 -238.097568)
		(end 156.001974 -238.48568)
		(width 0.18288)
		(layer "In2.Cu")
		(net "M_F_CPU1_SB_DQS_DN<4>")
	)
	(segment
		(start 147.486878 -240.777522)
		(end 146.938238 -240.777522)
		(width 0.18288)
		(layer "In2.Cu")
		(net "M_F_CPU1_SB_DQS_DN<4>")
	)
	(segment
		(start 176.896014 -237.266734)
		(end 176.58207 -236.95279)
		(width 0.18288)
		(layer "In2.Cu")
		(net "M_F_CPU1_SB_DQS_DN<4>")
	)
	(segment
		(start 154.87396 -239.437672)
		(end 154.486102 -239.82553)
		(width 0.18288)
		(layer "In2.Cu")
		(net "M_F_CPU1_SB_DQS_DN<4>")
	)
	(segment
		(start 135.605266 -239.665002)
		(end 135.605266 -239.853216)
		(width 0.088646)
		(layer "In2.Cu")
		(net "M_F_CPU1_SB_DQS_DN<4>")
	)
	(segment
		(start 144.794478 -240.777522)
		(end 144.245838 -240.777522)
		(width 0.18288)
		(layer "In2.Cu")
		(net "M_F_CPU1_SB_DQS_DN<4>")
	)
	(segment
		(start 139.148058 -240.384584)
		(end 139.142978 -240.380012)
		(width 0.088646)
		(layer "In2.Cu")
		(net "M_F_CPU1_SB_DQS_DN<4>")
	)
	(segment
		(start 169.686478 -236.055662)
		(end 169.54754 -236.1946)
		(width 0.16002)
		(layer "In2.Cu")
		(net "M_F_CPU1_SB_DQS_DN<4>")
	)
	(segment
		(start 164.04844 -235.142278)
		(end 163.990528 -235.20019)
		(width 0.18288)
		(layer "In2.Cu")
		(net "M_F_CPU1_SB_DQS_DN<4>")
	)
	(segment
		(start 169.702226 -236.055662)
		(end 169.686478 -236.055662)
		(width 0.16002)
		(layer "In2.Cu")
		(net "M_F_CPU1_SB_DQS_DN<4>")
	)
	(segment
		(start 172.014896 -236.552486)
		(end 171.559728 -236.36351)
		(width 0.18288)
		(layer "In2.Cu")
		(net "M_F_CPU1_SB_DQS_DN<4>")
	)
	(segment
		(start 163.807648 -235.38307)
		(end 163.779454 -235.411264)
		(width 0.16002)
		(layer "In2.Cu")
		(net "M_F_CPU1_SB_DQS_DN<4>")
	)
	(segment
		(start 158.147258 -236.78007)
		(end 157.884114 -237.043214)
		(width 0.18288)
		(layer "In2.Cu")
		(net "M_F_CPU1_SB_DQS_DN<4>")
	)
	(segment
		(start 159.57677 -236.903514)
		(end 159.548576 -236.87532)
		(width 0.16002)
		(layer "In2.Cu")
		(net "M_F_CPU1_SB_DQS_DN<4>")
	)
	(segment
		(start 149.630638 -240.777522)
		(end 149.506178 -240.901982)
		(width 0.18288)
		(layer "In2.Cu")
		(net "M_F_CPU1_SB_DQS_DN<4>")
	)
	(segment
		(start 139.083288 -240.343944)
		(end 139.081256 -240.342674)
		(width 0.088646)
		(layer "In2.Cu")
		(net "M_F_CPU1_SB_DQS_DN<4>")
	)
	(segment
		(start 169.73042 -236.027468)
		(end 169.702226 -236.055662)
		(width 0.16002)
		(layer "In2.Cu")
		(net "M_F_CPU1_SB_DQS_DN<4>")
	)
	(segment
		(start 168.410128 -236.42701)
		(end 167.978328 -235.99521)
		(width 0.18288)
		(layer "In2.Cu")
		(net "M_F_CPU1_SB_DQS_DN<4>")
	)
	(segment
		(start 142.775178 -240.901982)
		(end 142.226538 -240.901982)
		(width 0.18288)
		(layer "In2.Cu")
		(net "M_F_CPU1_SB_DQS_DN<4>")
	)
	(segment
		(start 139.157456 -240.396522)
		(end 139.148058 -240.384584)
		(width 0.088646)
		(layer "In2.Cu")
		(net "M_F_CPU1_SB_DQS_DN<4>")
	)
	(segment
		(start 163.374832 -235.815886)
		(end 162.353752 -235.815886)
		(width 0.18288)
		(layer "In2.Cu")
		(net "M_F_CPU1_SB_DQS_DN<4>")
	)
	(segment
		(start 174.552864 -236.749844)
		(end 174.207678 -236.606842)
		(width 0.18288)
		(layer "In2.Cu")
		(net "M_F_CPU1_SB_DQS_DN<4>")
	)
	(segment
		(start 159.731456 -237.0582)
		(end 159.731456 -237.042452)
		(width 0.16002)
		(layer "In2.Cu")
		(net "M_F_CPU1_SB_DQS_DN<4>")
	)
	(segment
		(start 139.084812 -240.34496)
		(end 139.083288 -240.343944)
		(width 0.088646)
		(layer "In2.Cu")
		(net "M_F_CPU1_SB_DQS_DN<4>")
	)
	(segment
		(start 145.467578 -240.901982)
		(end 144.918938 -240.901982)
		(width 0.18288)
		(layer "In2.Cu")
		(net "M_F_CPU1_SB_DQS_DN<4>")
	)
	(segment
		(start 156.39034 -237.921546)
		(end 156.390086 -238.097568)
		(width 0.18288)
		(layer "In2.Cu")
		(net "M_F_CPU1_SB_DQS_DN<4>")
	)
	(segment
		(start 146.938238 -240.777522)
		(end 146.813778 -240.901982)
		(width 0.18288)
		(layer "In2.Cu")
		(net "M_F_CPU1_SB_DQS_DN<4>")
	)
	(segment
		(start 163.946078 -235.228384)
		(end 163.807648 -235.366814)
		(width 0.16002)
		(layer "In2.Cu")
		(net "M_F_CPU1_SB_DQS_DN<4>")
	)
	(segment
		(start 155.825952 -238.48568)
		(end 155.438094 -238.873538)
		(width 0.18288)
		(layer "In2.Cu")
		(net "M_F_CPU1_SB_DQS_DN<4>")
	)
	(segment
		(start 142.226538 -240.901982)
		(end 142.102078 -240.777522)
		(width 0.18288)
		(layer "In2.Cu")
		(net "M_F_CPU1_SB_DQS_DN<4>")
	)
	(segment
		(start 161.95802 -236.211618)
		(end 161.202624 -236.524546)
		(width 0.18288)
		(layer "In2.Cu")
		(net "M_F_CPU1_SB_DQS_DN<4>")
	)
	(segment
		(start 163.807648 -235.366814)
		(end 163.807648 -235.38307)
		(width 0.16002)
		(layer "In2.Cu")
		(net "M_F_CPU1_SB_DQS_DN<4>")
	)
	(segment
		(start 162.353752 -235.815886)
		(end 161.95802 -236.211618)
		(width 0.18288)
		(layer "In2.Cu")
		(net "M_F_CPU1_SB_DQS_DN<4>")
	)
	(segment
		(start 167.026336 -235.043218)
		(end 166.558214 -234.849416)
		(width 0.18288)
		(layer "In2.Cu")
		(net "M_F_CPU1_SB_DQS_DN<4>")
	)
	(segment
		(start 159.453326 -236.78007)
		(end 158.147258 -236.78007)
		(width 0.18288)
		(layer "In2.Cu")
		(net "M_F_CPU1_SB_DQS_DN<4>")
	)
	(segment
		(start 167.414194 -235.607098)
		(end 167.414194 -235.431076)
		(width 0.18288)
		(layer "In2.Cu")
		(net "M_F_CPU1_SB_DQS_DN<4>")
	)
	(arc
		(start 139.081256 -240.342674)
		(mid 139.076576 -240.339974)
		(end 139.071858 -240.33734)
		(width 0.088646)
		(layer "In2.Cu")
		(net "M_F_CPU1_SB_DQS_DN<4>")
	)
	(arc
		(start 137.202164 -240.342928)
		(mid 136.998683 -240.142124)
		(end 136.919462 -239.86744)
		(width 0.088646)
		(layer "In2.Cu")
		(net "M_F_CPU1_SB_DQS_DN<4>")
	)
	(arc
		(start 136.73201 -239.528858)
		(mid 136.544812 -239.478715)
		(end 136.357614 -239.528858)
		(width 0.088646)
		(layer "In2.Cu")
		(net "M_F_CPU1_SB_DQS_DN<4>")
	)
	(arc
		(start 136.919462 -239.853216)
		(mid 136.871783 -239.670316)
		(end 136.7409 -239.533938)
		(width 0.088646)
		(layer "In2.Cu")
		(net "M_F_CPU1_SB_DQS_DN<4>")
	)
	(arc
		(start 138.141964 -240.342928)
		(mid 137.954766 -240.292785)
		(end 137.767568 -240.342928)
		(width 0.088646)
		(layer "In2.Cu")
		(net "M_F_CPU1_SB_DQS_DN<4>")
	)
	(arc
		(start 138.707368 -240.342928)
		(mid 138.433139 -240.418853)
		(end 138.156696 -240.351564)
		(width 0.088646)
		(layer "In2.Cu")
		(net "M_F_CPU1_SB_DQS_DN<4>")
	)
	(arc
		(start 136.10971 -239.60328)
		(mid 135.974894 -239.595429)
		(end 135.845804 -239.555782)
		(width 0.088646)
		(layer "In2.Cu")
		(net "M_F_CPU1_SB_DQS_DN<4>")
	)
	(arc
		(start 139.071858 -240.33734)
		(mid 138.888879 -240.292767)
		(end 138.707368 -240.342928)
		(width 0.088646)
		(layer "In2.Cu")
		(net "M_F_CPU1_SB_DQS_DN<4>")
	)
	(arc
		(start 136.35228 -239.531906)
		(mid 136.235036 -239.581319)
		(end 136.10971 -239.60328)
		(width 0.088646)
		(layer "In2.Cu")
		(net "M_F_CPU1_SB_DQS_DN<4>")
	)
	(arc
		(start 137.767568 -240.342928)
		(mid 137.493339 -240.418853)
		(end 137.216896 -240.351564)
		(width 0.088646)
		(layer "In2.Cu")
		(net "M_F_CPU1_SB_DQS_DN<4>")
	)
	(segment
		(start 174.449486 -199.866758)
		(end 174.731172 -200.148444)
		(width 0.20066)
		(layer "F.Cu")
		(net "M_F_CPU1_SB_DQS_DN<3>")
	)
	(segment
		(start 179.33543 -200.286366)
		(end 179.566824 -200.51776)
		(width 0.20066)
		(layer "F.Cu")
		(net "M_F_CPU1_SB_DQS_DN<3>")
	)
	(segment
		(start 174.731172 -200.148444)
		(end 175.46701 -200.148444)
		(width 0.20066)
		(layer "F.Cu")
		(net "M_F_CPU1_SB_DQS_DN<3>")
	)
	(segment
		(start 176.674526 -200.2917)
		(end 176.8221 -200.2917)
		(width 0.20066)
		(layer "F.Cu")
		(net "M_F_CPU1_SB_DQS_DN<3>")
	)
	(segment
		(start 129.496312 -228.1809)
		(end 129.496566 -228.180646)
		(width 0.20066)
		(layer "F.Cu")
		(net "M_F_CPU1_SB_DQS_DN<3>")
	)
	(segment
		(start 180.282342 -200.107296)
		(end 180.614828 -200.107296)
		(width 0.20066)
		(layer "F.Cu")
		(net "M_F_CPU1_SB_DQS_DN<3>")
	)
	(segment
		(start 179.011326 -200.286366)
		(end 179.33543 -200.286366)
		(width 0.20066)
		(layer "F.Cu")
		(net "M_F_CPU1_SB_DQS_DN<3>")
	)
	(segment
		(start 175.46701 -200.148444)
		(end 175.881538 -200.562972)
		(width 0.20066)
		(layer "F.Cu")
		(net "M_F_CPU1_SB_DQS_DN<3>")
	)
	(segment
		(start 175.881538 -200.562972)
		(end 176.403254 -200.562972)
		(width 0.20066)
		(layer "F.Cu")
		(net "M_F_CPU1_SB_DQS_DN<3>")
	)
	(segment
		(start 176.8221 -200.2917)
		(end 176.826418 -200.2917)
		(width 0.101854)
		(layer "F.Cu")
		(net "M_F_CPU1_SB_DQS_DN<3>")
	)
	(segment
		(start 176.826418 -200.2917)
		(end 179.005992 -200.2917)
		(width 0.1016)
		(layer "F.Cu")
		(net "M_F_CPU1_SB_DQS_DN<3>")
	)
	(segment
		(start 173.900846 -199.866758)
		(end 174.449486 -199.866758)
		(width 0.20066)
		(layer "F.Cu")
		(net "M_F_CPU1_SB_DQS_DN<3>")
	)
	(segment
		(start 180.855366 -199.866758)
		(end 181.444646 -199.866758)
		(width 0.20066)
		(layer "F.Cu")
		(net "M_F_CPU1_SB_DQS_DN<3>")
	)
	(segment
		(start 179.005992 -200.2917)
		(end 179.011326 -200.286366)
		(width 0.1016)
		(layer "F.Cu")
		(net "M_F_CPU1_SB_DQS_DN<3>")
	)
	(segment
		(start 176.403254 -200.562972)
		(end 176.674526 -200.2917)
		(width 0.20066)
		(layer "F.Cu")
		(net "M_F_CPU1_SB_DQS_DN<3>")
	)
	(segment
		(start 172.795946 -199.866758)
		(end 173.900846 -199.866758)
		(width 0.20066)
		(layer "F.Cu")
		(net "M_F_CPU1_SB_DQS_DN<3>")
	)
	(segment
		(start 179.566824 -200.51776)
		(end 179.871878 -200.51776)
		(width 0.20066)
		(layer "F.Cu")
		(net "M_F_CPU1_SB_DQS_DN<3>")
	)
	(segment
		(start 179.871878 -200.51776)
		(end 180.282342 -200.107296)
		(width 0.20066)
		(layer "F.Cu")
		(net "M_F_CPU1_SB_DQS_DN<3>")
	)
	(segment
		(start 180.614828 -200.107296)
		(end 180.855366 -199.866758)
		(width 0.20066)
		(layer "F.Cu")
		(net "M_F_CPU1_SB_DQS_DN<3>")
	)
	(segment
		(start 129.496566 -228.180646)
		(end 129.496566 -227.64496)
		(width 0.20066)
		(layer "F.Cu")
		(net "M_F_CPU1_SB_DQS_DN<3>")
	)
	(segment
		(start 172.795946 -199.866758)
		(end 172.547026 -200.115678)
		(width 0.18288)
		(layer "In4.Cu")
		(net "M_F_CPU1_SB_DQS_DN<3>")
	)
	(segment
		(start 134.391654 -223.080834)
		(end 134.382764 -223.085914)
		(width 0.088646)
		(layer "In4.Cu")
		(net "M_F_CPU1_SB_DQS_DN<3>")
	)
	(segment
		(start 132.9817 -227.150422)
		(end 132.973826 -227.154994)
		(width 0.088646)
		(layer "In4.Cu")
		(net "M_F_CPU1_SB_DQS_DN<3>")
	)
	(segment
		(start 140.304266 -220.434154)
		(end 139.756642 -220.434154)
		(width 0.18288)
		(layer "In4.Cu")
		(net "M_F_CPU1_SB_DQS_DN<3>")
	)
	(segment
		(start 136.271254 -221.453202)
		(end 136.263888 -221.45752)
		(width 0.088646)
		(layer "In4.Cu")
		(net "M_F_CPU1_SB_DQS_DN<3>")
	)
	(segment
		(start 133.921754 -223.894904)
		(end 133.912864 -223.899984)
		(width 0.088646)
		(layer "In4.Cu")
		(net "M_F_CPU1_SB_DQS_DN<3>")
	)
	(segment
		(start 132.61086 -227.163122)
		(end 132.598922 -227.15601)
		(width 0.088646)
		(layer "In4.Cu")
		(net "M_F_CPU1_SB_DQS_DN<3>")
	)
	(segment
		(start 131.67106 -227.163122)
		(end 131.659122 -227.15601)
		(width 0.088646)
		(layer "In4.Cu")
		(net "M_F_CPU1_SB_DQS_DN<3>")
	)
	(segment
		(start 164.338254 -199.103996)
		(end 161.096198 -199.103996)
		(width 0.18288)
		(layer "In4.Cu")
		(net "M_F_CPU1_SB_DQS_DN<3>")
	)
	(segment
		(start 133.451854 -226.336606)
		(end 133.442964 -226.341686)
		(width 0.088646)
		(layer "In4.Cu")
		(net "M_F_CPU1_SB_DQS_DN<3>")
	)
	(segment
		(start 138.938254 -220.56852)
		(end 138.894058 -220.56852)
		(width 0.088646)
		(layer "In4.Cu")
		(net "M_F_CPU1_SB_DQS_DN<3>")
	)
	(segment
		(start 149.982682 -210.755738)
		(end 140.304266 -220.434154)
		(width 0.18288)
		(layer "In4.Cu")
		(net "M_F_CPU1_SB_DQS_DN<3>")
	)
	(segment
		(start 164.885624 -199.651366)
		(end 164.338254 -199.103996)
		(width 0.18288)
		(layer "In4.Cu")
		(net "M_F_CPU1_SB_DQS_DN<3>")
	)
	(segment
		(start 136.263888 -221.45752)
		(end 136.262364 -221.458282)
		(width 0.088646)
		(layer "In4.Cu")
		(net "M_F_CPU1_SB_DQS_DN<3>")
	)
	(segment
		(start 134.8613 -222.267018)
		(end 134.853426 -222.27159)
		(width 0.088646)
		(layer "In4.Cu")
		(net "M_F_CPU1_SB_DQS_DN<3>")
	)
	(segment
		(start 139.756642 -220.434154)
		(end 139.733274 -220.434154)
		(width 0.088646)
		(layer "In4.Cu")
		(net "M_F_CPU1_SB_DQS_DN<3>")
	)
	(segment
		(start 165.498018 -199.651366)
		(end 164.885624 -199.651366)
		(width 0.18288)
		(layer "In4.Cu")
		(net "M_F_CPU1_SB_DQS_DN<3>")
	)
	(segment
		(start 135.312404 -221.464124)
		(end 135.310372 -221.465394)
		(width 0.088646)
		(layer "In4.Cu")
		(net "M_F_CPU1_SB_DQS_DN<3>")
	)
	(segment
		(start 172.547026 -200.115678)
		(end 172.111162 -200.115678)
		(width 0.18288)
		(layer "In4.Cu")
		(net "M_F_CPU1_SB_DQS_DN<3>")
	)
	(segment
		(start 166.708582 -199.09282)
		(end 166.056564 -199.09282)
		(width 0.18288)
		(layer "In4.Cu")
		(net "M_F_CPU1_SB_DQS_DN<3>")
	)
	(segment
		(start 129.909824 -227.440236)
		(end 129.909316 -227.439982)
		(width 0.088646)
		(layer "In4.Cu")
		(net "M_F_CPU1_SB_DQS_DN<3>")
	)
	(segment
		(start 134.100316 -223.557084)
		(end 134.100316 -223.575626)
		(width 0.088646)
		(layer "In4.Cu")
		(net "M_F_CPU1_SB_DQS_DN<3>")
	)
	(segment
		(start 157.085792 -199.502522)
		(end 154.579574 -202.00874)
		(width 0.18288)
		(layer "In4.Cu")
		(net "M_F_CPU1_SB_DQS_DN<3>")
	)
	(segment
		(start 171.657518 -199.662034)
		(end 167.277796 -199.662034)
		(width 0.18288)
		(layer "In4.Cu")
		(net "M_F_CPU1_SB_DQS_DN<3>")
	)
	(segment
		(start 172.111162 -200.115678)
		(end 171.657518 -199.662034)
		(width 0.18288)
		(layer "In4.Cu")
		(net "M_F_CPU1_SB_DQS_DN<3>")
	)
	(segment
		(start 133.921754 -225.522536)
		(end 133.912864 -225.527616)
		(width 0.088646)
		(layer "In4.Cu")
		(net "M_F_CPU1_SB_DQS_DN<3>")
	)
	(segment
		(start 134.570216 -222.746062)
		(end 134.570216 -222.761556)
		(width 0.088646)
		(layer "In4.Cu")
		(net "M_F_CPU1_SB_DQS_DN<3>")
	)
	(segment
		(start 152.018238 -205.841854)
		(end 149.982682 -210.755738)
		(width 0.18288)
		(layer "In4.Cu")
		(net "M_F_CPU1_SB_DQS_DN<3>")
	)
	(segment
		(start 133.442964 -226.341686)
		(end 133.430772 -226.348798)
		(width 0.088646)
		(layer "In4.Cu")
		(net "M_F_CPU1_SB_DQS_DN<3>")
	)
	(segment
		(start 154.579574 -202.00874)
		(end 152.018238 -205.841854)
		(width 0.18288)
		(layer "In4.Cu")
		(net "M_F_CPU1_SB_DQS_DN<3>")
	)
	(segment
		(start 132.97281 -227.155502)
		(end 132.973318 -227.155756)
		(width 0.088646)
		(layer "In4.Cu")
		(net "M_F_CPU1_SB_DQS_DN<3>")
	)
	(segment
		(start 136.449816 -221.115382)
		(end 136.449816 -221.133924)
		(width 0.088646)
		(layer "In4.Cu")
		(net "M_F_CPU1_SB_DQS_DN<3>")
	)
	(segment
		(start 139.012676 -220.494098)
		(end 138.938254 -220.56852)
		(width 0.088646)
		(layer "In4.Cu")
		(net "M_F_CPU1_SB_DQS_DN<3>")
	)
	(segment
		(start 130.154426 -227.155502)
		(end 130.143504 -227.161852)
		(width 0.088646)
		(layer "In4.Cu")
		(net "M_F_CPU1_SB_DQS_DN<3>")
	)
	(segment
		(start 133.630416 -224.379536)
		(end 133.630416 -224.399348)
		(width 0.088646)
		(layer "In4.Cu")
		(net "M_F_CPU1_SB_DQS_DN<3>")
	)
	(segment
		(start 167.277796 -199.662034)
		(end 166.708582 -199.09282)
		(width 0.18288)
		(layer "In4.Cu")
		(net "M_F_CPU1_SB_DQS_DN<3>")
	)
	(segment
		(start 160.697672 -199.502522)
		(end 157.085792 -199.502522)
		(width 0.18288)
		(layer "In4.Cu")
		(net "M_F_CPU1_SB_DQS_DN<3>")
	)
	(segment
		(start 139.67333 -220.494098)
		(end 139.012676 -220.494098)
		(width 0.088646)
		(layer "In4.Cu")
		(net "M_F_CPU1_SB_DQS_DN<3>")
	)
	(segment
		(start 135.322564 -221.458282)
		(end 135.312404 -221.464124)
		(width 0.088646)
		(layer "In4.Cu")
		(net "M_F_CPU1_SB_DQS_DN<3>")
	)
	(segment
		(start 133.912864 -224.8789)
		(end 133.913626 -224.879408)
		(width 0.088646)
		(layer "In4.Cu")
		(net "M_F_CPU1_SB_DQS_DN<3>")
	)
	(segment
		(start 139.733274 -220.434154)
		(end 139.67333 -220.494098)
		(width 0.088646)
		(layer "In4.Cu")
		(net "M_F_CPU1_SB_DQS_DN<3>")
	)
	(segment
		(start 133.913626 -224.879408)
		(end 133.921754 -224.88398)
		(width 0.088646)
		(layer "In4.Cu")
		(net "M_F_CPU1_SB_DQS_DN<3>")
	)
	(segment
		(start 134.853426 -222.27159)
		(end 134.85241 -222.272098)
		(width 0.088646)
		(layer "In4.Cu")
		(net "M_F_CPU1_SB_DQS_DN<3>")
	)
	(segment
		(start 133.630416 -225.998786)
		(end 133.630416 -226.017328)
		(width 0.088646)
		(layer "In4.Cu")
		(net "M_F_CPU1_SB_DQS_DN<3>")
	)
	(segment
		(start 161.096198 -199.103996)
		(end 160.697672 -199.502522)
		(width 0.18288)
		(layer "In4.Cu")
		(net "M_F_CPU1_SB_DQS_DN<3>")
	)
	(segment
		(start 132.973826 -227.154994)
		(end 132.97281 -227.155502)
		(width 0.088646)
		(layer "In4.Cu")
		(net "M_F_CPU1_SB_DQS_DN<3>")
	)
	(segment
		(start 166.056564 -199.09282)
		(end 165.498018 -199.651366)
		(width 0.18288)
		(layer "In4.Cu")
		(net "M_F_CPU1_SB_DQS_DN<3>")
	)
	(arc
		(start 130.143504 -227.161852)
		(mid 130.00367 -227.281745)
		(end 129.909824 -227.440236)
		(width 0.088646)
		(layer "In4.Cu")
		(net "M_F_CPU1_SB_DQS_DN<3>")
	)
	(arc
		(start 134.85241 -222.272098)
		(mid 134.649587 -222.472329)
		(end 134.570216 -222.746062)
		(width 0.088646)
		(layer "In4.Cu")
		(net "M_F_CPU1_SB_DQS_DN<3>")
	)
	(arc
		(start 138.894058 -220.56852)
		(mid 138.747997 -220.587848)
		(end 138.611864 -220.644212)
		(width 0.088646)
		(layer "In4.Cu")
		(net "M_F_CPU1_SB_DQS_DN<3>")
	)
	(arc
		(start 133.430772 -226.348798)
		(mid 133.232544 -226.554646)
		(end 133.160262 -226.831144)
		(width 0.088646)
		(layer "In4.Cu")
		(net "M_F_CPU1_SB_DQS_DN<3>")
	)
	(arc
		(start 134.382764 -223.085914)
		(mid 134.180478 -223.284895)
		(end 134.100316 -223.557084)
		(width 0.088646)
		(layer "In4.Cu")
		(net "M_F_CPU1_SB_DQS_DN<3>")
	)
	(arc
		(start 130.718814 -227.155756)
		(mid 130.436649 -227.080073)
		(end 130.154426 -227.155502)
		(width 0.088646)
		(layer "In4.Cu")
		(net "M_F_CPU1_SB_DQS_DN<3>")
	)
	(arc
		(start 134.100062 -225.21545)
		(mid 134.049569 -225.391428)
		(end 133.921754 -225.522536)
		(width 0.088646)
		(layer "In4.Cu")
		(net "M_F_CPU1_SB_DQS_DN<3>")
	)
	(arc
		(start 134.100316 -223.575626)
		(mid 134.052637 -223.758526)
		(end 133.921754 -223.894904)
		(width 0.088646)
		(layer "In4.Cu")
		(net "M_F_CPU1_SB_DQS_DN<3>")
	)
	(arc
		(start 138.611864 -220.644212)
		(mid 138.424666 -220.694355)
		(end 138.237468 -220.644212)
		(width 0.088646)
		(layer "In4.Cu")
		(net "M_F_CPU1_SB_DQS_DN<3>")
	)
	(arc
		(start 132.973318 -227.155756)
		(mid 132.793031 -227.206168)
		(end 132.61086 -227.163122)
		(width 0.088646)
		(layer "In4.Cu")
		(net "M_F_CPU1_SB_DQS_DN<3>")
	)
	(arc
		(start 133.912864 -225.527616)
		(mid 133.710578 -225.726597)
		(end 133.630416 -225.998786)
		(width 0.088646)
		(layer "In4.Cu")
		(net "M_F_CPU1_SB_DQS_DN<3>")
	)
	(arc
		(start 136.262364 -221.458282)
		(mid 136.075166 -221.508425)
		(end 135.887968 -221.458282)
		(width 0.088646)
		(layer "In4.Cu")
		(net "M_F_CPU1_SB_DQS_DN<3>")
	)
	(arc
		(start 133.160262 -226.831144)
		(mid 133.112583 -227.014044)
		(end 132.9817 -227.150422)
		(width 0.088646)
		(layer "In4.Cu")
		(net "M_F_CPU1_SB_DQS_DN<3>")
	)
	(arc
		(start 133.921754 -224.88398)
		(mid 134.051043 -225.017466)
		(end 134.100316 -225.196654)
		(width 0.088646)
		(layer "In4.Cu")
		(net "M_F_CPU1_SB_DQS_DN<3>")
	)
	(arc
		(start 133.630416 -224.399348)
		(mid 133.708527 -224.676297)
		(end 133.912864 -224.8789)
		(width 0.088646)
		(layer "In4.Cu")
		(net "M_F_CPU1_SB_DQS_DN<3>")
	)
	(arc
		(start 137.297668 -220.644212)
		(mid 137.014966 -220.56847)
		(end 136.732264 -220.644212)
		(width 0.088646)
		(layer "In4.Cu")
		(net "M_F_CPU1_SB_DQS_DN<3>")
	)
	(arc
		(start 138.237468 -220.644212)
		(mid 137.954766 -220.56847)
		(end 137.672064 -220.644212)
		(width 0.088646)
		(layer "In4.Cu")
		(net "M_F_CPU1_SB_DQS_DN<3>")
	)
	(arc
		(start 132.598922 -227.15601)
		(mid 132.316249 -227.080039)
		(end 132.033518 -227.155756)
		(width 0.088646)
		(layer "In4.Cu")
		(net "M_F_CPU1_SB_DQS_DN<3>")
	)
	(arc
		(start 134.570216 -222.761556)
		(mid 134.522537 -222.944456)
		(end 134.391654 -223.080834)
		(width 0.088646)
		(layer "In4.Cu")
		(net "M_F_CPU1_SB_DQS_DN<3>")
	)
	(arc
		(start 136.732264 -220.644212)
		(mid 136.529978 -220.843193)
		(end 136.449816 -221.115382)
		(width 0.088646)
		(layer "In4.Cu")
		(net "M_F_CPU1_SB_DQS_DN<3>")
	)
	(arc
		(start 131.659122 -227.15601)
		(mid 131.376449 -227.080039)
		(end 131.093718 -227.155756)
		(width 0.088646)
		(layer "In4.Cu")
		(net "M_F_CPU1_SB_DQS_DN<3>")
	)
	(arc
		(start 135.310372 -221.465394)
		(mid 135.112144 -221.671242)
		(end 135.039862 -221.94774)
		(width 0.088646)
		(layer "In4.Cu")
		(net "M_F_CPU1_SB_DQS_DN<3>")
	)
	(arc
		(start 137.672064 -220.644212)
		(mid 137.484866 -220.694355)
		(end 137.297668 -220.644212)
		(width 0.088646)
		(layer "In4.Cu")
		(net "M_F_CPU1_SB_DQS_DN<3>")
	)
	(arc
		(start 136.449816 -221.133924)
		(mid 136.402137 -221.316824)
		(end 136.271254 -221.453202)
		(width 0.088646)
		(layer "In4.Cu")
		(net "M_F_CPU1_SB_DQS_DN<3>")
	)
	(arc
		(start 133.630416 -226.017328)
		(mid 133.582737 -226.200228)
		(end 133.451854 -226.336606)
		(width 0.088646)
		(layer "In4.Cu")
		(net "M_F_CPU1_SB_DQS_DN<3>")
	)
	(arc
		(start 129.909316 -227.439982)
		(mid 129.726979 -227.590864)
		(end 129.496566 -227.64496)
		(width 0.088646)
		(layer "In4.Cu")
		(net "M_F_CPU1_SB_DQS_DN<3>")
	)
	(arc
		(start 131.093718 -227.155756)
		(mid 130.906266 -227.205992)
		(end 130.718814 -227.155756)
		(width 0.088646)
		(layer "In4.Cu")
		(net "M_F_CPU1_SB_DQS_DN<3>")
	)
	(arc
		(start 135.887968 -221.458282)
		(mid 135.605266 -221.382506)
		(end 135.322564 -221.458282)
		(width 0.088646)
		(layer "In4.Cu")
		(net "M_F_CPU1_SB_DQS_DN<3>")
	)
	(arc
		(start 134.100316 -225.196654)
		(mid 134.100306 -225.206054)
		(end 134.100062 -225.21545)
		(width 0.088646)
		(layer "In4.Cu")
		(net "M_F_CPU1_SB_DQS_DN<3>")
	)
	(arc
		(start 133.912864 -223.899984)
		(mid 133.708529 -224.102589)
		(end 133.630416 -224.379536)
		(width 0.088646)
		(layer "In4.Cu")
		(net "M_F_CPU1_SB_DQS_DN<3>")
	)
	(arc
		(start 132.033518 -227.155756)
		(mid 131.853231 -227.206168)
		(end 131.67106 -227.163122)
		(width 0.088646)
		(layer "In4.Cu")
		(net "M_F_CPU1_SB_DQS_DN<3>")
	)
	(arc
		(start 135.039862 -221.94774)
		(mid 134.992183 -222.13064)
		(end 134.8613 -222.267018)
		(width 0.088646)
		(layer "In4.Cu")
		(net "M_F_CPU1_SB_DQS_DN<3>")
	)
	(segment
		(start 176.674526 -209.641694)
		(end 176.8221 -209.641694)
		(width 0.20066)
		(layer "F.Cu")
		(net "M_F_CPU1_SB_DQS_DN<2>")
	)
	(segment
		(start 179.33543 -209.63636)
		(end 179.566824 -209.867754)
		(width 0.20066)
		(layer "F.Cu")
		(net "M_F_CPU1_SB_DQS_DN<2>")
	)
	(segment
		(start 174.731172 -209.498438)
		(end 175.46701 -209.498438)
		(width 0.20066)
		(layer "F.Cu")
		(net "M_F_CPU1_SB_DQS_DN<2>")
	)
	(segment
		(start 173.900846 -209.216752)
		(end 174.449486 -209.216752)
		(width 0.20066)
		(layer "F.Cu")
		(net "M_F_CPU1_SB_DQS_DN<2>")
	)
	(segment
		(start 176.826418 -209.641694)
		(end 179.005992 -209.641694)
		(width 0.1016)
		(layer "F.Cu")
		(net "M_F_CPU1_SB_DQS_DN<2>")
	)
	(segment
		(start 175.881538 -209.912966)
		(end 176.403254 -209.912966)
		(width 0.20066)
		(layer "F.Cu")
		(net "M_F_CPU1_SB_DQS_DN<2>")
	)
	(segment
		(start 175.46701 -209.498438)
		(end 175.881538 -209.912966)
		(width 0.20066)
		(layer "F.Cu")
		(net "M_F_CPU1_SB_DQS_DN<2>")
	)
	(segment
		(start 179.005992 -209.641694)
		(end 179.011326 -209.63636)
		(width 0.1016)
		(layer "F.Cu")
		(net "M_F_CPU1_SB_DQS_DN<2>")
	)
	(segment
		(start 176.403254 -209.912966)
		(end 176.674526 -209.641694)
		(width 0.20066)
		(layer "F.Cu")
		(net "M_F_CPU1_SB_DQS_DN<2>")
	)
	(segment
		(start 137.014712 -223.297496)
		(end 137.014712 -222.761556)
		(width 0.20066)
		(layer "F.Cu")
		(net "M_F_CPU1_SB_DQS_DN<2>")
	)
	(segment
		(start 180.614828 -209.45729)
		(end 180.855366 -209.216752)
		(width 0.20066)
		(layer "F.Cu")
		(net "M_F_CPU1_SB_DQS_DN<2>")
	)
	(segment
		(start 180.282342 -209.45729)
		(end 180.614828 -209.45729)
		(width 0.20066)
		(layer "F.Cu")
		(net "M_F_CPU1_SB_DQS_DN<2>")
	)
	(segment
		(start 179.011326 -209.63636)
		(end 179.33543 -209.63636)
		(width 0.20066)
		(layer "F.Cu")
		(net "M_F_CPU1_SB_DQS_DN<2>")
	)
	(segment
		(start 176.8221 -209.641694)
		(end 176.826418 -209.641694)
		(width 0.101854)
		(layer "F.Cu")
		(net "M_F_CPU1_SB_DQS_DN<2>")
	)
	(segment
		(start 174.449486 -209.216752)
		(end 174.731172 -209.498438)
		(width 0.20066)
		(layer "F.Cu")
		(net "M_F_CPU1_SB_DQS_DN<2>")
	)
	(segment
		(start 179.566824 -209.867754)
		(end 179.871878 -209.867754)
		(width 0.20066)
		(layer "F.Cu")
		(net "M_F_CPU1_SB_DQS_DN<2>")
	)
	(segment
		(start 180.855366 -209.216752)
		(end 181.444646 -209.216752)
		(width 0.20066)
		(layer "F.Cu")
		(net "M_F_CPU1_SB_DQS_DN<2>")
	)
	(segment
		(start 172.795946 -209.216752)
		(end 173.900846 -209.216752)
		(width 0.20066)
		(layer "F.Cu")
		(net "M_F_CPU1_SB_DQS_DN<2>")
	)
	(segment
		(start 179.871878 -209.867754)
		(end 180.282342 -209.45729)
		(width 0.20066)
		(layer "F.Cu")
		(net "M_F_CPU1_SB_DQS_DN<2>")
	)
	(segment
		(start 169.5069 -209.38236)
		(end 169.02557 -208.90103)
		(width 0.18288)
		(layer "In2.Cu")
		(net "M_F_CPU1_SB_DQS_DN<2>")
	)
	(segment
		(start 141.82344 -221.959678)
		(end 141.763496 -222.019622)
		(width 0.088646)
		(layer "In2.Cu")
		(net "M_F_CPU1_SB_DQS_DN<2>")
	)
	(segment
		(start 167.399462 -208.714594)
		(end 167.261032 -208.576164)
		(width 0.16002)
		(layer "In2.Cu")
		(net "M_F_CPU1_SB_DQS_DN<2>")
	)
	(segment
		(start 167.415718 -208.714594)
		(end 167.399462 -208.714594)
		(width 0.16002)
		(layer "In2.Cu")
		(net "M_F_CPU1_SB_DQS_DN<2>")
	)
	(segment
		(start 146.58975 -217.498168)
		(end 146.413728 -217.498168)
		(width 0.18288)
		(layer "In2.Cu")
		(net "M_F_CPU1_SB_DQS_DN<2>")
	)
	(segment
		(start 169.717974 -209.593434)
		(end 169.68978 -209.56524)
		(width 0.16002)
		(layer "In2.Cu")
		(net "M_F_CPU1_SB_DQS_DN<2>")
	)
	(segment
		(start 140.6271 -222.191072)
		(end 140.52296 -222.253556)
		(width 0.088646)
		(layer "In2.Cu")
		(net "M_F_CPU1_SB_DQS_DN<2>")
	)
	(segment
		(start 141.763496 -222.019622)
		(end 141.213332 -222.019622)
		(width 0.088646)
		(layer "In2.Cu")
		(net "M_F_CPU1_SB_DQS_DN<2>")
	)
	(segment
		(start 139.646914 -223.085914)
		(end 139.632182 -223.077278)
		(width 0.088646)
		(layer "In2.Cu")
		(net "M_F_CPU1_SB_DQS_DN<2>")
	)
	(segment
		(start 161.264346 -207.39989)
		(end 160.291272 -207.39989)
		(width 0.18288)
		(layer "In2.Cu")
		(net "M_F_CPU1_SB_DQS_DN<2>")
	)
	(segment
		(start 158.227014 -206.53375)
		(end 157.883098 -206.877666)
		(width 0.18288)
		(layer "In2.Cu")
		(net "M_F_CPU1_SB_DQS_DN<2>")
	)
	(segment
		(start 141.213332 -222.019622)
		(end 140.880846 -222.15729)
		(width 0.088646)
		(layer "In2.Cu")
		(net "M_F_CPU1_SB_DQS_DN<2>")
	)
	(segment
		(start 140.208762 -222.769938)
		(end 140.208508 -222.776288)
		(width 0.088646)
		(layer "In2.Cu")
		(net "M_F_CPU1_SB_DQS_DN<2>")
	)
	(segment
		(start 162.048698 -207.079342)
		(end 161.584894 -207.079342)
		(width 0.18288)
		(layer "In2.Cu")
		(net "M_F_CPU1_SB_DQS_DN<2>")
	)
	(segment
		(start 165.776402 -208.213198)
		(end 165.49243 -207.929226)
		(width 0.18288)
		(layer "In2.Cu")
		(net "M_F_CPU1_SB_DQS_DN<2>")
	)
	(segment
		(start 171.195238 -209.68081)
		(end 169.80535 -209.68081)
		(width 0.18288)
		(layer "In2.Cu")
		(net "M_F_CPU1_SB_DQS_DN<2>")
	)
	(segment
		(start 157.453838 -207.306926)
		(end 157.453838 -207.44053)
		(width 0.18288)
		(layer "In2.Cu")
		(net "M_F_CPU1_SB_DQS_DN<2>")
	)
	(segment
		(start 169.02557 -208.90103)
		(end 167.602154 -208.90103)
		(width 0.18288)
		(layer "In2.Cu")
		(net "M_F_CPU1_SB_DQS_DN<2>")
	)
	(segment
		(start 140.50899 -222.261684)
		(end 140.485368 -222.275654)
		(width 0.088646)
		(layer "In2.Cu")
		(net "M_F_CPU1_SB_DQS_DN<2>")
	)
	(segment
		(start 169.68978 -209.56524)
		(end 169.674032 -209.56524)
		(width 0.16002)
		(layer "In2.Cu")
		(net "M_F_CPU1_SB_DQS_DN<2>")
	)
	(segment
		(start 172.205142 -209.305906)
		(end 171.570142 -209.305906)
		(width 0.18288)
		(layer "In2.Cu")
		(net "M_F_CPU1_SB_DQS_DN<2>")
	)
	(segment
		(start 140.208762 -222.761556)
		(end 140.208762 -222.769938)
		(width 0.088646)
		(layer "In2.Cu")
		(net "M_F_CPU1_SB_DQS_DN<2>")
	)
	(segment
		(start 138.707114 -223.085914)
		(end 138.707368 -223.085914)
		(width 0.088646)
		(layer "In2.Cu")
		(net "M_F_CPU1_SB_DQS_DN<2>")
	)
	(segment
		(start 157.700218 -207.060546)
		(end 157.672024 -207.08874)
		(width 0.16002)
		(layer "In2.Cu")
		(net "M_F_CPU1_SB_DQS_DN<2>")
	)
	(segment
		(start 162.33267 -207.363314)
		(end 162.048698 -207.079342)
		(width 0.18288)
		(layer "In2.Cu")
		(net "M_F_CPU1_SB_DQS_DN<2>")
	)
	(segment
		(start 172.510196 -209.502502)
		(end 172.401738 -209.502502)
		(width 0.18288)
		(layer "In2.Cu")
		(net "M_F_CPU1_SB_DQS_DN<2>")
	)
	(segment
		(start 164.737542 -208.22031)
		(end 164.361368 -208.22031)
		(width 0.18288)
		(layer "In2.Cu")
		(net "M_F_CPU1_SB_DQS_DN<2>")
	)
	(segment
		(start 140.520928 -222.254572)
		(end 140.519404 -222.255588)
		(width 0.088646)
		(layer "In2.Cu")
		(net "M_F_CPU1_SB_DQS_DN<2>")
	)
	(segment
		(start 169.674032 -209.56524)
		(end 169.535094 -209.426302)
		(width 0.16002)
		(layer "In2.Cu")
		(net "M_F_CPU1_SB_DQS_DN<2>")
	)
	(segment
		(start 146.413728 -217.498168)
		(end 146.025616 -217.88628)
		(width 0.18288)
		(layer "In2.Cu")
		(net "M_F_CPU1_SB_DQS_DN<2>")
	)
	(segment
		(start 155.327096 -209.567272)
		(end 154.520646 -209.567272)
		(width 0.18288)
		(layer "In2.Cu")
		(net "M_F_CPU1_SB_DQS_DN<2>")
	)
	(segment
		(start 137.202164 -223.085914)
		(end 137.20191 -223.085914)
		(width 0.088646)
		(layer "In2.Cu")
		(net "M_F_CPU1_SB_DQS_DN<2>")
	)
	(segment
		(start 147.36572 -216.546176)
		(end 146.977608 -216.934288)
		(width 0.18288)
		(layer "In2.Cu")
		(net "M_F_CPU1_SB_DQS_DN<2>")
	)
	(segment
		(start 169.535094 -209.426302)
		(end 169.535094 -209.410554)
		(width 0.16002)
		(layer "In2.Cu")
		(net "M_F_CPU1_SB_DQS_DN<2>")
	)
	(segment
		(start 147.541742 -216.546176)
		(end 147.36572 -216.546176)
		(width 0.18288)
		(layer "In2.Cu")
		(net "M_F_CPU1_SB_DQS_DN<2>")
	)
	(segment
		(start 167.261032 -208.559908)
		(end 167.232838 -208.531714)
		(width 0.16002)
		(layer "In2.Cu")
		(net "M_F_CPU1_SB_DQS_DN<2>")
	)
	(segment
		(start 160.291272 -207.39989)
		(end 159.425132 -206.53375)
		(width 0.18288)
		(layer "In2.Cu")
		(net "M_F_CPU1_SB_DQS_DN<2>")
	)
	(segment
		(start 140.880846 -222.15729)
		(end 140.6271 -222.191072)
		(width 0.088646)
		(layer "In2.Cu")
		(net "M_F_CPU1_SB_DQS_DN<2>")
	)
	(segment
		(start 157.716474 -207.060546)
		(end 157.700218 -207.060546)
		(width 0.16002)
		(layer "In2.Cu")
		(net "M_F_CPU1_SB_DQS_DN<2>")
	)
	(segment
		(start 157.453838 -207.44053)
		(end 155.327096 -209.567272)
		(width 0.18288)
		(layer "In2.Cu")
		(net "M_F_CPU1_SB_DQS_DN<2>")
	)
	(segment
		(start 142.12824 -221.959678)
		(end 141.82344 -221.959678)
		(width 0.18288)
		(layer "In2.Cu")
		(net "M_F_CPU1_SB_DQS_DN<2>")
	)
	(segment
		(start 140.509244 -222.261684)
		(end 140.50899 -222.261684)
		(width 0.088646)
		(layer "In2.Cu")
		(net "M_F_CPU1_SB_DQS_DN<2>")
	)
	(segment
		(start 165.028626 -207.929226)
		(end 164.737542 -208.22031)
		(width 0.18288)
		(layer "In2.Cu")
		(net "M_F_CPU1_SB_DQS_DN<2>")
	)
	(segment
		(start 165.49243 -207.929226)
		(end 165.028626 -207.929226)
		(width 0.18288)
		(layer "In2.Cu")
		(net "M_F_CPU1_SB_DQS_DN<2>")
	)
	(segment
		(start 140.510768 -222.260668)
		(end 140.509244 -222.261684)
		(width 0.088646)
		(layer "In2.Cu")
		(net "M_F_CPU1_SB_DQS_DN<2>")
	)
	(segment
		(start 167.261032 -208.576164)
		(end 167.261032 -208.559908)
		(width 0.16002)
		(layer "In2.Cu")
		(net "M_F_CPU1_SB_DQS_DN<2>")
	)
	(segment
		(start 167.443912 -208.742788)
		(end 167.415718 -208.714594)
		(width 0.16002)
		(layer "In2.Cu")
		(net "M_F_CPU1_SB_DQS_DN<2>")
	)
	(segment
		(start 157.672024 -207.08874)
		(end 157.453838 -207.306926)
		(width 0.18288)
		(layer "In2.Cu")
		(net "M_F_CPU1_SB_DQS_DN<2>")
	)
	(segment
		(start 136.702038 -222.761556)
		(end 137.014712 -222.761556)
		(width 0.088646)
		(layer "In2.Cu")
		(net "M_F_CPU1_SB_DQS_DN<2>")
	)
	(segment
		(start 167.602154 -208.90103)
		(end 167.443912 -208.742788)
		(width 0.18288)
		(layer "In2.Cu")
		(net "M_F_CPU1_SB_DQS_DN<2>")
	)
	(segment
		(start 169.535094 -209.410554)
		(end 169.5069 -209.38236)
		(width 0.16002)
		(layer "In2.Cu")
		(net "M_F_CPU1_SB_DQS_DN<2>")
	)
	(segment
		(start 159.425132 -206.53375)
		(end 158.227014 -206.53375)
		(width 0.18288)
		(layer "In2.Cu")
		(net "M_F_CPU1_SB_DQS_DN<2>")
	)
	(segment
		(start 164.361368 -208.22031)
		(end 163.504372 -207.363314)
		(width 0.18288)
		(layer "In2.Cu")
		(net "M_F_CPU1_SB_DQS_DN<2>")
	)
	(segment
		(start 157.854904 -206.922116)
		(end 157.716474 -207.060546)
		(width 0.16002)
		(layer "In2.Cu")
		(net "M_F_CPU1_SB_DQS_DN<2>")
	)
	(segment
		(start 166.914322 -208.213198)
		(end 165.776402 -208.213198)
		(width 0.18288)
		(layer "In2.Cu")
		(net "M_F_CPU1_SB_DQS_DN<2>")
	)
	(segment
		(start 136.644888 -222.818706)
		(end 136.702038 -222.761556)
		(width 0.088646)
		(layer "In2.Cu")
		(net "M_F_CPU1_SB_DQS_DN<2>")
	)
	(segment
		(start 172.795946 -209.216752)
		(end 172.510196 -209.502502)
		(width 0.18288)
		(layer "In2.Cu")
		(net "M_F_CPU1_SB_DQS_DN<2>")
	)
	(segment
		(start 146.025616 -218.062302)
		(end 142.12824 -221.959678)
		(width 0.18288)
		(layer "In2.Cu")
		(net "M_F_CPU1_SB_DQS_DN<2>")
	)
	(segment
		(start 157.883098 -206.877666)
		(end 157.854904 -206.90586)
		(width 0.16002)
		(layer "In2.Cu")
		(net "M_F_CPU1_SB_DQS_DN<2>")
	)
	(segment
		(start 140.52296 -222.253556)
		(end 140.520928 -222.254572)
		(width 0.088646)
		(layer "In2.Cu")
		(net "M_F_CPU1_SB_DQS_DN<2>")
	)
	(segment
		(start 146.025616 -217.88628)
		(end 146.025616 -218.062302)
		(width 0.18288)
		(layer "In2.Cu")
		(net "M_F_CPU1_SB_DQS_DN<2>")
	)
	(segment
		(start 171.570142 -209.305906)
		(end 171.195238 -209.68081)
		(width 0.18288)
		(layer "In2.Cu")
		(net "M_F_CPU1_SB_DQS_DN<2>")
	)
	(segment
		(start 172.401738 -209.502502)
		(end 172.205142 -209.305906)
		(width 0.18288)
		(layer "In2.Cu")
		(net "M_F_CPU1_SB_DQS_DN<2>")
	)
	(segment
		(start 146.977608 -217.11031)
		(end 146.58975 -217.498168)
		(width 0.18288)
		(layer "In2.Cu")
		(net "M_F_CPU1_SB_DQS_DN<2>")
	)
	(segment
		(start 169.80535 -209.68081)
		(end 169.717974 -209.593434)
		(width 0.18288)
		(layer "In2.Cu")
		(net "M_F_CPU1_SB_DQS_DN<2>")
	)
	(segment
		(start 140.519404 -222.255588)
		(end 140.510768 -222.260668)
		(width 0.088646)
		(layer "In2.Cu")
		(net "M_F_CPU1_SB_DQS_DN<2>")
	)
	(segment
		(start 161.584894 -207.079342)
		(end 161.264346 -207.39989)
		(width 0.18288)
		(layer "In2.Cu")
		(net "M_F_CPU1_SB_DQS_DN<2>")
	)
	(segment
		(start 167.232838 -208.531714)
		(end 166.914322 -208.213198)
		(width 0.18288)
		(layer "In2.Cu")
		(net "M_F_CPU1_SB_DQS_DN<2>")
	)
	(segment
		(start 163.504372 -207.363314)
		(end 162.33267 -207.363314)
		(width 0.18288)
		(layer "In2.Cu")
		(net "M_F_CPU1_SB_DQS_DN<2>")
	)
	(segment
		(start 154.520646 -209.567272)
		(end 147.541742 -216.546176)
		(width 0.18288)
		(layer "In2.Cu")
		(net "M_F_CPU1_SB_DQS_DN<2>")
	)
	(segment
		(start 157.854904 -206.90586)
		(end 157.854904 -206.922116)
		(width 0.16002)
		(layer "In2.Cu")
		(net "M_F_CPU1_SB_DQS_DN<2>")
	)
	(segment
		(start 146.977608 -216.934288)
		(end 146.977608 -217.11031)
		(width 0.18288)
		(layer "In2.Cu")
		(net "M_F_CPU1_SB_DQS_DN<2>")
	)
	(arc
		(start 137.20191 -223.085914)
		(mid 137.014712 -223.136057)
		(end 136.827514 -223.085914)
		(width 0.088646)
		(layer "In2.Cu")
		(net "M_F_CPU1_SB_DQS_DN<2>")
	)
	(arc
		(start 139.08151 -223.085914)
		(mid 138.894312 -223.136057)
		(end 138.707114 -223.085914)
		(width 0.088646)
		(layer "In2.Cu")
		(net "M_F_CPU1_SB_DQS_DN<2>")
	)
	(arc
		(start 137.767568 -223.085914)
		(mid 137.484866 -223.010172)
		(end 137.202164 -223.085914)
		(width 0.088646)
		(layer "In2.Cu")
		(net "M_F_CPU1_SB_DQS_DN<2>")
	)
	(arc
		(start 138.141964 -223.085914)
		(mid 137.954766 -223.136057)
		(end 137.767568 -223.085914)
		(width 0.088646)
		(layer "In2.Cu")
		(net "M_F_CPU1_SB_DQS_DN<2>")
	)
	(arc
		(start 140.485368 -222.275654)
		(mid 140.282781 -222.482005)
		(end 140.208762 -222.761556)
		(width 0.088646)
		(layer "In2.Cu")
		(net "M_F_CPU1_SB_DQS_DN<2>")
	)
	(arc
		(start 139.632182 -223.077278)
		(mid 139.355741 -223.010112)
		(end 139.08151 -223.085914)
		(width 0.088646)
		(layer "In2.Cu")
		(net "M_F_CPU1_SB_DQS_DN<2>")
	)
	(arc
		(start 140.208508 -222.776288)
		(mid 140.015065 -223.08965)
		(end 139.646914 -223.085914)
		(width 0.088646)
		(layer "In2.Cu")
		(net "M_F_CPU1_SB_DQS_DN<2>")
	)
	(arc
		(start 136.827514 -223.085914)
		(mid 136.705846 -222.973059)
		(end 136.644888 -222.818706)
		(width 0.088646)
		(layer "In2.Cu")
		(net "M_F_CPU1_SB_DQS_DN<2>")
	)
	(arc
		(start 138.707368 -223.085914)
		(mid 138.424666 -223.010172)
		(end 138.141964 -223.085914)
		(width 0.088646)
		(layer "In2.Cu")
		(net "M_F_CPU1_SB_DQS_DN<2>")
	)
	(segment
		(start 180.855366 -218.566746)
		(end 181.444646 -218.566746)
		(width 0.20066)
		(layer "F.Cu")
		(net "M_F_CPU1_SB_DQS_DN<1>")
	)
	(segment
		(start 176.403254 -219.26296)
		(end 176.674526 -218.991688)
		(width 0.20066)
		(layer "F.Cu")
		(net "M_F_CPU1_SB_DQS_DN<1>")
	)
	(segment
		(start 176.826418 -218.991688)
		(end 179.005992 -218.991688)
		(width 0.1016)
		(layer "F.Cu")
		(net "M_F_CPU1_SB_DQS_DN<1>")
	)
	(segment
		(start 175.881538 -219.26296)
		(end 176.403254 -219.26296)
		(width 0.20066)
		(layer "F.Cu")
		(net "M_F_CPU1_SB_DQS_DN<1>")
	)
	(segment
		(start 133.725666 -230.622602)
		(end 133.725666 -230.086662)
		(width 0.20066)
		(layer "F.Cu")
		(net "M_F_CPU1_SB_DQS_DN<1>")
	)
	(segment
		(start 172.795946 -218.566746)
		(end 173.900846 -218.566746)
		(width 0.20066)
		(layer "F.Cu")
		(net "M_F_CPU1_SB_DQS_DN<1>")
	)
	(segment
		(start 176.674526 -218.991688)
		(end 176.8221 -218.991688)
		(width 0.20066)
		(layer "F.Cu")
		(net "M_F_CPU1_SB_DQS_DN<1>")
	)
	(segment
		(start 180.614828 -218.807284)
		(end 180.855366 -218.566746)
		(width 0.20066)
		(layer "F.Cu")
		(net "M_F_CPU1_SB_DQS_DN<1>")
	)
	(segment
		(start 179.566824 -219.217748)
		(end 179.871878 -219.217748)
		(width 0.20066)
		(layer "F.Cu")
		(net "M_F_CPU1_SB_DQS_DN<1>")
	)
	(segment
		(start 179.871878 -219.217748)
		(end 180.282342 -218.807284)
		(width 0.20066)
		(layer "F.Cu")
		(net "M_F_CPU1_SB_DQS_DN<1>")
	)
	(segment
		(start 179.33543 -218.986354)
		(end 179.566824 -219.217748)
		(width 0.20066)
		(layer "F.Cu")
		(net "M_F_CPU1_SB_DQS_DN<1>")
	)
	(segment
		(start 176.8221 -218.991688)
		(end 176.826418 -218.991688)
		(width 0.101854)
		(layer "F.Cu")
		(net "M_F_CPU1_SB_DQS_DN<1>")
	)
	(segment
		(start 174.449486 -218.566746)
		(end 174.731172 -218.848432)
		(width 0.20066)
		(layer "F.Cu")
		(net "M_F_CPU1_SB_DQS_DN<1>")
	)
	(segment
		(start 179.005992 -218.991688)
		(end 179.011326 -218.986354)
		(width 0.1016)
		(layer "F.Cu")
		(net "M_F_CPU1_SB_DQS_DN<1>")
	)
	(segment
		(start 179.011326 -218.986354)
		(end 179.33543 -218.986354)
		(width 0.20066)
		(layer "F.Cu")
		(net "M_F_CPU1_SB_DQS_DN<1>")
	)
	(segment
		(start 173.900846 -218.566746)
		(end 174.449486 -218.566746)
		(width 0.20066)
		(layer "F.Cu")
		(net "M_F_CPU1_SB_DQS_DN<1>")
	)
	(segment
		(start 175.46701 -218.848432)
		(end 175.881538 -219.26296)
		(width 0.20066)
		(layer "F.Cu")
		(net "M_F_CPU1_SB_DQS_DN<1>")
	)
	(segment
		(start 174.731172 -218.848432)
		(end 175.46701 -218.848432)
		(width 0.20066)
		(layer "F.Cu")
		(net "M_F_CPU1_SB_DQS_DN<1>")
	)
	(segment
		(start 180.282342 -218.807284)
		(end 180.614828 -218.807284)
		(width 0.20066)
		(layer "F.Cu")
		(net "M_F_CPU1_SB_DQS_DN<1>")
	)
	(segment
		(start 159.421068 -217.60307)
		(end 158.215838 -217.60307)
		(width 0.18288)
		(layer "In2.Cu")
		(net "M_F_CPU1_SB_DQS_DN<1>")
	)
	(segment
		(start 171.580048 -218.627452)
		(end 171.16933 -219.03817)
		(width 0.18288)
		(layer "In2.Cu")
		(net "M_F_CPU1_SB_DQS_DN<1>")
	)
	(segment
		(start 159.99968 -218.181682)
		(end 159.971486 -218.153488)
		(width 0.16002)
		(layer "In2.Cu")
		(net "M_F_CPU1_SB_DQS_DN<1>")
	)
	(segment
		(start 157.637226 -218.181682)
		(end 157.430978 -218.38793)
		(width 0.18288)
		(layer "In2.Cu")
		(net "M_F_CPU1_SB_DQS_DN<1>")
	)
	(segment
		(start 162.15614 -218.915234)
		(end 162.140392 -218.915234)
		(width 0.16002)
		(layer "In2.Cu")
		(net "M_F_CPU1_SB_DQS_DN<1>")
	)
	(segment
		(start 169.274236 -218.50223)
		(end 168.430956 -218.50223)
		(width 0.18288)
		(layer "In2.Cu")
		(net "M_F_CPU1_SB_DQS_DN<1>")
	)
	(segment
		(start 155.918916 -219.475812)
		(end 154.689556 -220.705172)
		(width 0.18288)
		(layer "In2.Cu")
		(net "M_F_CPU1_SB_DQS_DN<1>")
	)
	(segment
		(start 133.412738 -230.086662)
		(end 133.725666 -230.086662)
		(width 0.088646)
		(layer "In2.Cu")
		(net "M_F_CPU1_SB_DQS_DN<1>")
	)
	(segment
		(start 169.671492 -218.915234)
		(end 169.532554 -218.776296)
		(width 0.16002)
		(layer "In2.Cu")
		(net "M_F_CPU1_SB_DQS_DN<1>")
	)
	(segment
		(start 164.249354 -218.978226)
		(end 163.880292 -218.978226)
		(width 0.18288)
		(layer "In2.Cu")
		(net "M_F_CPU1_SB_DQS_DN<1>")
	)
	(segment
		(start 133.355588 -230.143812)
		(end 133.412738 -230.086662)
		(width 0.088646)
		(layer "In2.Cu")
		(net "M_F_CPU1_SB_DQS_DN<1>")
	)
	(segment
		(start 162.140392 -218.915234)
		(end 162.001454 -218.776296)
		(width 0.16002)
		(layer "In2.Cu")
		(net "M_F_CPU1_SB_DQS_DN<1>")
	)
	(segment
		(start 162.001454 -218.760548)
		(end 161.97326 -218.732354)
		(width 0.16002)
		(layer "In2.Cu")
		(net "M_F_CPU1_SB_DQS_DN<1>")
	)
	(segment
		(start 156.483304 -218.911424)
		(end 156.307282 -218.911424)
		(width 0.18288)
		(layer "In2.Cu")
		(net "M_F_CPU1_SB_DQS_DN<1>")
	)
	(segment
		(start 162.184334 -218.943428)
		(end 162.15614 -218.915234)
		(width 0.16002)
		(layer "In2.Cu")
		(net "M_F_CPU1_SB_DQS_DN<1>")
	)
	(segment
		(start 154.689556 -220.705172)
		(end 153.830528 -220.705172)
		(width 0.18288)
		(layer "In2.Cu")
		(net "M_F_CPU1_SB_DQS_DN<1>")
	)
	(segment
		(start 159.95523 -218.153488)
		(end 159.8168 -218.015058)
		(width 0.16002)
		(layer "In2.Cu")
		(net "M_F_CPU1_SB_DQS_DN<1>")
	)
	(segment
		(start 172.4152 -218.794584)
		(end 172.248068 -218.627452)
		(width 0.18288)
		(layer "In2.Cu")
		(net "M_F_CPU1_SB_DQS_DN<1>")
	)
	(segment
		(start 161.494216 -218.25331)
		(end 160.071308 -218.25331)
		(width 0.18288)
		(layer "In2.Cu")
		(net "M_F_CPU1_SB_DQS_DN<1>")
	)
	(segment
		(start 140.815822 -228.7905)
		(end 140.125196 -229.481126)
		(width 0.088646)
		(layer "In2.Cu")
		(net "M_F_CPU1_SB_DQS_DN<1>")
	)
	(segment
		(start 172.568108 -218.794584)
		(end 172.4152 -218.794584)
		(width 0.18288)
		(layer "In2.Cu")
		(net "M_F_CPU1_SB_DQS_DN<1>")
	)
	(segment
		(start 145.50009 -228.23805)
		(end 144.95145 -228.23805)
		(width 0.18288)
		(layer "In2.Cu")
		(net "M_F_CPU1_SB_DQS_DN<1>")
	)
	(segment
		(start 144.82699 -228.36251)
		(end 141.159484 -228.36251)
		(width 0.18288)
		(layer "In2.Cu")
		(net "M_F_CPU1_SB_DQS_DN<1>")
	)
	(segment
		(start 169.532554 -218.760548)
		(end 169.50436 -218.732354)
		(width 0.16002)
		(layer "In2.Cu")
		(net "M_F_CPU1_SB_DQS_DN<1>")
	)
	(segment
		(start 159.8168 -217.998802)
		(end 159.788606 -217.970608)
		(width 0.16002)
		(layer "In2.Cu")
		(net "M_F_CPU1_SB_DQS_DN<1>")
	)
	(segment
		(start 140.815822 -228.706172)
		(end 140.815822 -228.7905)
		(width 0.088646)
		(layer "In2.Cu")
		(net "M_F_CPU1_SB_DQS_DN<1>")
	)
	(segment
		(start 136.919716 -230.076756)
		(end 136.919716 -230.086662)
		(width 0.088646)
		(layer "In2.Cu")
		(net "M_F_CPU1_SB_DQS_DN<1>")
	)
	(segment
		(start 169.68724 -218.915234)
		(end 169.671492 -218.915234)
		(width 0.16002)
		(layer "In2.Cu")
		(net "M_F_CPU1_SB_DQS_DN<1>")
	)
	(segment
		(start 144.95145 -228.23805)
		(end 144.82699 -228.36251)
		(width 0.18288)
		(layer "In2.Cu")
		(net "M_F_CPU1_SB_DQS_DN<1>")
	)
	(segment
		(start 146.17319 -228.36251)
		(end 145.62455 -228.36251)
		(width 0.18288)
		(layer "In2.Cu")
		(net "M_F_CPU1_SB_DQS_DN<1>")
	)
	(segment
		(start 165.571932 -219.79509)
		(end 165.016434 -219.239592)
		(width 0.18288)
		(layer "In2.Cu")
		(net "M_F_CPU1_SB_DQS_DN<1>")
	)
	(segment
		(start 140.125196 -229.481126)
		(end 139.515342 -229.481126)
		(width 0.088646)
		(layer "In2.Cu")
		(net "M_F_CPU1_SB_DQS_DN<1>")
	)
	(segment
		(start 158.215838 -217.60307)
		(end 157.8483 -217.970608)
		(width 0.18288)
		(layer "In2.Cu")
		(net "M_F_CPU1_SB_DQS_DN<1>")
	)
	(segment
		(start 172.248068 -218.627452)
		(end 171.580048 -218.627452)
		(width 0.18288)
		(layer "In2.Cu")
		(net "M_F_CPU1_SB_DQS_DN<1>")
	)
	(segment
		(start 133.538468 -230.41102)
		(end 133.529578 -230.40594)
		(width 0.088646)
		(layer "In2.Cu")
		(net "M_F_CPU1_SB_DQS_DN<1>")
	)
	(segment
		(start 163.880292 -218.978226)
		(end 163.618926 -219.239592)
		(width 0.18288)
		(layer "In2.Cu")
		(net "M_F_CPU1_SB_DQS_DN<1>")
	)
	(segment
		(start 157.820106 -218.015058)
		(end 157.681676 -218.153488)
		(width 0.16002)
		(layer "In2.Cu")
		(net "M_F_CPU1_SB_DQS_DN<1>")
	)
	(segment
		(start 162.480498 -219.239592)
		(end 162.184334 -218.943428)
		(width 0.18288)
		(layer "In2.Cu")
		(net "M_F_CPU1_SB_DQS_DN<1>")
	)
	(segment
		(start 155.918916 -219.29979)
		(end 155.918916 -219.475812)
		(width 0.18288)
		(layer "In2.Cu")
		(net "M_F_CPU1_SB_DQS_DN<1>")
	)
	(segment
		(start 157.006798 -218.38793)
		(end 156.483304 -218.911424)
		(width 0.18288)
		(layer "In2.Cu")
		(net "M_F_CPU1_SB_DQS_DN<1>")
	)
	(segment
		(start 162.001454 -218.776296)
		(end 162.001454 -218.760548)
		(width 0.16002)
		(layer "In2.Cu")
		(net "M_F_CPU1_SB_DQS_DN<1>")
	)
	(segment
		(start 156.307282 -218.911424)
		(end 155.918916 -219.29979)
		(width 0.18288)
		(layer "In2.Cu")
		(net "M_F_CPU1_SB_DQS_DN<1>")
	)
	(segment
		(start 159.8168 -218.015058)
		(end 159.8168 -217.998802)
		(width 0.16002)
		(layer "In2.Cu")
		(net "M_F_CPU1_SB_DQS_DN<1>")
	)
	(segment
		(start 157.430978 -218.38793)
		(end 157.006798 -218.38793)
		(width 0.18288)
		(layer "In2.Cu")
		(net "M_F_CPU1_SB_DQS_DN<1>")
	)
	(segment
		(start 165.016434 -219.239592)
		(end 164.51072 -219.239592)
		(width 0.18288)
		(layer "In2.Cu")
		(net "M_F_CPU1_SB_DQS_DN<1>")
	)
	(segment
		(start 169.810176 -219.03817)
		(end 169.715434 -218.943428)
		(width 0.18288)
		(layer "In2.Cu")
		(net "M_F_CPU1_SB_DQS_DN<1>")
	)
	(segment
		(start 157.681676 -218.153488)
		(end 157.66542 -218.153488)
		(width 0.16002)
		(layer "In2.Cu")
		(net "M_F_CPU1_SB_DQS_DN<1>")
	)
	(segment
		(start 157.820106 -217.998802)
		(end 157.820106 -218.015058)
		(width 0.16002)
		(layer "In2.Cu")
		(net "M_F_CPU1_SB_DQS_DN<1>")
	)
	(segment
		(start 169.715434 -218.943428)
		(end 169.68724 -218.915234)
		(width 0.16002)
		(layer "In2.Cu")
		(net "M_F_CPU1_SB_DQS_DN<1>")
	)
	(segment
		(start 136.741154 -230.40594)
		(end 136.732264 -230.41102)
		(width 0.088646)
		(layer "In2.Cu")
		(net "M_F_CPU1_SB_DQS_DN<1>")
	)
	(segment
		(start 160.071308 -218.25331)
		(end 159.99968 -218.181682)
		(width 0.18288)
		(layer "In2.Cu")
		(net "M_F_CPU1_SB_DQS_DN<1>")
	)
	(segment
		(start 141.159484 -228.36251)
		(end 140.815822 -228.706172)
		(width 0.18288)
		(layer "In2.Cu")
		(net "M_F_CPU1_SB_DQS_DN<1>")
	)
	(segment
		(start 172.795946 -218.566746)
		(end 172.568108 -218.794584)
		(width 0.18288)
		(layer "In2.Cu")
		(net "M_F_CPU1_SB_DQS_DN<1>")
	)
	(segment
		(start 159.971486 -218.153488)
		(end 159.95523 -218.153488)
		(width 0.16002)
		(layer "In2.Cu")
		(net "M_F_CPU1_SB_DQS_DN<1>")
	)
	(segment
		(start 145.62455 -228.36251)
		(end 145.50009 -228.23805)
		(width 0.18288)
		(layer "In2.Cu")
		(net "M_F_CPU1_SB_DQS_DN<1>")
	)
	(segment
		(start 171.16933 -219.03817)
		(end 169.810176 -219.03817)
		(width 0.18288)
		(layer "In2.Cu")
		(net "M_F_CPU1_SB_DQS_DN<1>")
	)
	(segment
		(start 159.788606 -217.970608)
		(end 159.421068 -217.60307)
		(width 0.18288)
		(layer "In2.Cu")
		(net "M_F_CPU1_SB_DQS_DN<1>")
	)
	(segment
		(start 153.830528 -220.705172)
		(end 146.17319 -228.36251)
		(width 0.18288)
		(layer "In2.Cu")
		(net "M_F_CPU1_SB_DQS_DN<1>")
	)
	(segment
		(start 169.532554 -218.776296)
		(end 169.532554 -218.760548)
		(width 0.16002)
		(layer "In2.Cu")
		(net "M_F_CPU1_SB_DQS_DN<1>")
	)
	(segment
		(start 164.51072 -219.239592)
		(end 164.249354 -218.978226)
		(width 0.18288)
		(layer "In2.Cu")
		(net "M_F_CPU1_SB_DQS_DN<1>")
	)
	(segment
		(start 168.430956 -218.50223)
		(end 167.138096 -219.79509)
		(width 0.18288)
		(layer "In2.Cu")
		(net "M_F_CPU1_SB_DQS_DN<1>")
	)
	(segment
		(start 161.97326 -218.732354)
		(end 161.494216 -218.25331)
		(width 0.18288)
		(layer "In2.Cu")
		(net "M_F_CPU1_SB_DQS_DN<1>")
	)
	(segment
		(start 157.8483 -217.970608)
		(end 157.820106 -217.998802)
		(width 0.16002)
		(layer "In2.Cu")
		(net "M_F_CPU1_SB_DQS_DN<1>")
	)
	(segment
		(start 169.50436 -218.732354)
		(end 169.274236 -218.50223)
		(width 0.18288)
		(layer "In2.Cu")
		(net "M_F_CPU1_SB_DQS_DN<1>")
	)
	(segment
		(start 167.138096 -219.79509)
		(end 165.571932 -219.79509)
		(width 0.18288)
		(layer "In2.Cu")
		(net "M_F_CPU1_SB_DQS_DN<1>")
	)
	(segment
		(start 157.66542 -218.153488)
		(end 157.637226 -218.181682)
		(width 0.16002)
		(layer "In2.Cu")
		(net "M_F_CPU1_SB_DQS_DN<1>")
	)
	(segment
		(start 163.618926 -219.239592)
		(end 162.480498 -219.239592)
		(width 0.18288)
		(layer "In2.Cu")
		(net "M_F_CPU1_SB_DQS_DN<1>")
	)
	(arc
		(start 137.767568 -229.597204)
		(mid 137.484866 -229.521428)
		(end 137.202164 -229.597204)
		(width 0.088646)
		(layer "In2.Cu")
		(net "M_F_CPU1_SB_DQS_DN<1>")
	)
	(arc
		(start 137.202164 -229.597204)
		(mid 136.997829 -229.799809)
		(end 136.919716 -230.076756)
		(width 0.088646)
		(layer "In2.Cu")
		(net "M_F_CPU1_SB_DQS_DN<1>")
	)
	(arc
		(start 135.418068 -230.41102)
		(mid 135.135366 -230.335244)
		(end 134.852664 -230.41102)
		(width 0.088646)
		(layer "In2.Cu")
		(net "M_F_CPU1_SB_DQS_DN<1>")
	)
	(arc
		(start 133.912864 -230.41102)
		(mid 133.725666 -230.461163)
		(end 133.538468 -230.41102)
		(width 0.088646)
		(layer "In2.Cu")
		(net "M_F_CPU1_SB_DQS_DN<1>")
	)
	(arc
		(start 134.852664 -230.41102)
		(mid 134.665466 -230.461163)
		(end 134.478268 -230.41102)
		(width 0.088646)
		(layer "In2.Cu")
		(net "M_F_CPU1_SB_DQS_DN<1>")
	)
	(arc
		(start 139.515342 -229.481126)
		(mid 139.290913 -229.510621)
		(end 139.081764 -229.597204)
		(width 0.088646)
		(layer "In2.Cu")
		(net "M_F_CPU1_SB_DQS_DN<1>")
	)
	(arc
		(start 133.529578 -230.40594)
		(mid 133.413769 -230.294011)
		(end 133.355588 -230.143812)
		(width 0.088646)
		(layer "In2.Cu")
		(net "M_F_CPU1_SB_DQS_DN<1>")
	)
	(arc
		(start 139.081764 -229.597204)
		(mid 138.894566 -229.647347)
		(end 138.707368 -229.597204)
		(width 0.088646)
		(layer "In2.Cu")
		(net "M_F_CPU1_SB_DQS_DN<1>")
	)
	(arc
		(start 136.357868 -230.41102)
		(mid 136.075166 -230.335244)
		(end 135.792464 -230.41102)
		(width 0.088646)
		(layer "In2.Cu")
		(net "M_F_CPU1_SB_DQS_DN<1>")
	)
	(arc
		(start 135.792464 -230.41102)
		(mid 135.605266 -230.461163)
		(end 135.418068 -230.41102)
		(width 0.088646)
		(layer "In2.Cu")
		(net "M_F_CPU1_SB_DQS_DN<1>")
	)
	(arc
		(start 136.732264 -230.41102)
		(mid 136.545066 -230.461163)
		(end 136.357868 -230.41102)
		(width 0.088646)
		(layer "In2.Cu")
		(net "M_F_CPU1_SB_DQS_DN<1>")
	)
	(arc
		(start 138.707368 -229.597204)
		(mid 138.424666 -229.521428)
		(end 138.141964 -229.597204)
		(width 0.088646)
		(layer "In2.Cu")
		(net "M_F_CPU1_SB_DQS_DN<1>")
	)
	(arc
		(start 138.141964 -229.597204)
		(mid 137.954766 -229.647347)
		(end 137.767568 -229.597204)
		(width 0.088646)
		(layer "In2.Cu")
		(net "M_F_CPU1_SB_DQS_DN<1>")
	)
	(arc
		(start 136.919716 -230.086662)
		(mid 136.872037 -230.269562)
		(end 136.741154 -230.40594)
		(width 0.088646)
		(layer "In2.Cu")
		(net "M_F_CPU1_SB_DQS_DN<1>")
	)
	(arc
		(start 134.478268 -230.41102)
		(mid 134.195566 -230.335244)
		(end 133.912864 -230.41102)
		(width 0.088646)
		(layer "In2.Cu")
		(net "M_F_CPU1_SB_DQS_DN<1>")
	)
	(segment
		(start 176.674526 -228.341682)
		(end 176.8221 -228.341682)
		(width 0.20066)
		(layer "F.Cu")
		(net "M_F_CPU1_SB_DQS_DN<0>")
	)
	(segment
		(start 172.795946 -227.91674)
		(end 173.900846 -227.91674)
		(width 0.20066)
		(layer "F.Cu")
		(net "M_F_CPU1_SB_DQS_DN<0>")
	)
	(segment
		(start 179.33543 -228.336348)
		(end 179.566824 -228.567742)
		(width 0.20066)
		(layer "F.Cu")
		(net "M_F_CPU1_SB_DQS_DN<0>")
	)
	(segment
		(start 175.46701 -228.198426)
		(end 175.881538 -228.612954)
		(width 0.20066)
		(layer "F.Cu")
		(net "M_F_CPU1_SB_DQS_DN<0>")
	)
	(segment
		(start 130.436112 -237.947454)
		(end 130.436366 -237.947454)
		(width 0.20066)
		(layer "F.Cu")
		(net "M_F_CPU1_SB_DQS_DN<0>")
	)
	(segment
		(start 176.403254 -228.612954)
		(end 176.674526 -228.341682)
		(width 0.20066)
		(layer "F.Cu")
		(net "M_F_CPU1_SB_DQS_DN<0>")
	)
	(segment
		(start 175.881538 -228.612954)
		(end 176.403254 -228.612954)
		(width 0.20066)
		(layer "F.Cu")
		(net "M_F_CPU1_SB_DQS_DN<0>")
	)
	(segment
		(start 180.614828 -228.157278)
		(end 180.855366 -227.91674)
		(width 0.20066)
		(layer "F.Cu")
		(net "M_F_CPU1_SB_DQS_DN<0>")
	)
	(segment
		(start 174.731172 -228.198426)
		(end 175.46701 -228.198426)
		(width 0.20066)
		(layer "F.Cu")
		(net "M_F_CPU1_SB_DQS_DN<0>")
	)
	(segment
		(start 179.566824 -228.567742)
		(end 179.871878 -228.567742)
		(width 0.20066)
		(layer "F.Cu")
		(net "M_F_CPU1_SB_DQS_DN<0>")
	)
	(segment
		(start 130.436366 -237.947454)
		(end 130.436366 -237.411514)
		(width 0.20066)
		(layer "F.Cu")
		(net "M_F_CPU1_SB_DQS_DN<0>")
	)
	(segment
		(start 179.011326 -228.336348)
		(end 179.33543 -228.336348)
		(width 0.20066)
		(layer "F.Cu")
		(net "M_F_CPU1_SB_DQS_DN<0>")
	)
	(segment
		(start 179.871878 -228.567742)
		(end 180.282342 -228.157278)
		(width 0.20066)
		(layer "F.Cu")
		(net "M_F_CPU1_SB_DQS_DN<0>")
	)
	(segment
		(start 179.005992 -228.341682)
		(end 179.011326 -228.336348)
		(width 0.1016)
		(layer "F.Cu")
		(net "M_F_CPU1_SB_DQS_DN<0>")
	)
	(segment
		(start 180.282342 -228.157278)
		(end 180.614828 -228.157278)
		(width 0.20066)
		(layer "F.Cu")
		(net "M_F_CPU1_SB_DQS_DN<0>")
	)
	(segment
		(start 176.826418 -228.341682)
		(end 179.005992 -228.341682)
		(width 0.1016)
		(layer "F.Cu")
		(net "M_F_CPU1_SB_DQS_DN<0>")
	)
	(segment
		(start 176.8221 -228.341682)
		(end 176.826418 -228.341682)
		(width 0.101854)
		(layer "F.Cu")
		(net "M_F_CPU1_SB_DQS_DN<0>")
	)
	(segment
		(start 180.855366 -227.91674)
		(end 181.444646 -227.91674)
		(width 0.20066)
		(layer "F.Cu")
		(net "M_F_CPU1_SB_DQS_DN<0>")
	)
	(segment
		(start 174.449486 -227.91674)
		(end 174.731172 -228.198426)
		(width 0.20066)
		(layer "F.Cu")
		(net "M_F_CPU1_SB_DQS_DN<0>")
	)
	(segment
		(start 173.900846 -227.91674)
		(end 174.449486 -227.91674)
		(width 0.20066)
		(layer "F.Cu")
		(net "M_F_CPU1_SB_DQS_DN<0>")
	)
	(segment
		(start 130.123946 -237.411514)
		(end 130.436366 -237.411514)
		(width 0.088646)
		(layer "In4.Cu")
		(net "M_F_CPU1_SB_DQS_DN<0>")
	)
	(segment
		(start 172.795946 -227.91674)
		(end 172.534834 -228.177852)
		(width 0.18288)
		(layer "In4.Cu")
		(net "M_F_CPU1_SB_DQS_DN<0>")
	)
	(segment
		(start 130.249168 -237.736126)
		(end 130.240278 -237.731046)
		(width 0.088646)
		(layer "In4.Cu")
		(net "M_F_CPU1_SB_DQS_DN<0>")
	)
	(segment
		(start 144.16405 -233.536744)
		(end 141.791944 -235.90885)
		(width 0.18288)
		(layer "In4.Cu")
		(net "M_F_CPU1_SB_DQS_DN<0>")
	)
	(segment
		(start 140.64107 -235.96854)
		(end 140.440918 -236.168692)
		(width 0.088646)
		(layer "In4.Cu")
		(net "M_F_CPU1_SB_DQS_DN<0>")
	)
	(segment
		(start 158.722822 -226.765866)
		(end 158.397702 -226.900994)
		(width 0.18288)
		(layer "In4.Cu")
		(net "M_F_CPU1_SB_DQS_DN<0>")
	)
	(segment
		(start 152.6032 -229.183692)
		(end 152.427178 -229.183692)
		(width 0.18288)
		(layer "In4.Cu")
		(net "M_F_CPU1_SB_DQS_DN<0>")
	)
	(segment
		(start 133.068314 -237.736126)
		(end 133.0579 -237.73003)
		(width 0.088646)
		(layer "In4.Cu")
		(net "M_F_CPU1_SB_DQS_DN<0>")
	)
	(segment
		(start 158.397702 -226.900994)
		(end 158.16072 -226.900994)
		(width 0.18288)
		(layer "In4.Cu")
		(net "M_F_CPU1_SB_DQS_DN<0>")
	)
	(segment
		(start 171.814744 -227.954078)
		(end 169.787062 -227.55098)
		(width 0.18288)
		(layer "In4.Cu")
		(net "M_F_CPU1_SB_DQS_DN<0>")
	)
	(segment
		(start 161.324544 -226.065334)
		(end 159.423354 -226.065334)
		(width 0.18288)
		(layer "In4.Cu")
		(net "M_F_CPU1_SB_DQS_DN<0>")
	)
	(segment
		(start 150.6982 -230.91267)
		(end 150.311866 -231.299004)
		(width 0.18288)
		(layer "In4.Cu")
		(net "M_F_CPU1_SB_DQS_DN<0>")
	)
	(segment
		(start 150.311866 -231.475026)
		(end 148.250148 -233.536744)
		(width 0.18288)
		(layer "In4.Cu")
		(net "M_F_CPU1_SB_DQS_DN<0>")
	)
	(segment
		(start 172.038518 -228.177852)
		(end 171.814744 -227.954078)
		(width 0.18288)
		(layer "In4.Cu")
		(net "M_F_CPU1_SB_DQS_DN<0>")
	)
	(segment
		(start 157.902148 -226.642422)
		(end 157.497272 -226.642422)
		(width 0.18288)
		(layer "In4.Cu")
		(net "M_F_CPU1_SB_DQS_DN<0>")
	)
	(segment
		(start 157.234128 -226.905566)
		(end 154.881326 -226.905566)
		(width 0.18288)
		(layer "In4.Cu")
		(net "M_F_CPU1_SB_DQS_DN<0>")
	)
	(segment
		(start 140.440918 -236.44225)
		(end 140.264896 -236.866684)
		(width 0.088646)
		(layer "In4.Cu")
		(net "M_F_CPU1_SB_DQS_DN<0>")
	)
	(segment
		(start 162.515296 -226.07397)
		(end 162.283648 -226.07397)
		(width 0.18288)
		(layer "In4.Cu")
		(net "M_F_CPU1_SB_DQS_DN<0>")
	)
	(segment
		(start 140.264896 -236.866684)
		(end 139.471146 -237.659926)
		(width 0.088646)
		(layer "In4.Cu")
		(net "M_F_CPU1_SB_DQS_DN<0>")
	)
	(segment
		(start 141.791944 -235.90885)
		(end 141.001496 -235.90885)
		(width 0.18288)
		(layer "In4.Cu")
		(net "M_F_CPU1_SB_DQS_DN<0>")
	)
	(segment
		(start 161.59734 -225.792538)
		(end 161.324544 -226.065334)
		(width 0.18288)
		(layer "In4.Cu")
		(net "M_F_CPU1_SB_DQS_DN<0>")
	)
	(segment
		(start 159.423354 -226.065334)
		(end 158.722822 -226.765866)
		(width 0.18288)
		(layer "In4.Cu")
		(net "M_F_CPU1_SB_DQS_DN<0>")
	)
	(segment
		(start 169.787062 -227.55098)
		(end 167.089836 -227.55098)
		(width 0.18288)
		(layer "In4.Cu")
		(net "M_F_CPU1_SB_DQS_DN<0>")
	)
	(segment
		(start 130.638296 -237.72749)
		(end 130.623564 -237.736126)
		(width 0.088646)
		(layer "In4.Cu")
		(net "M_F_CPU1_SB_DQS_DN<0>")
	)
	(segment
		(start 154.881326 -226.905566)
		(end 152.6032 -229.183692)
		(width 0.18288)
		(layer "In4.Cu")
		(net "M_F_CPU1_SB_DQS_DN<0>")
	)
	(segment
		(start 140.440918 -236.168692)
		(end 140.440918 -236.44225)
		(width 0.088646)
		(layer "In4.Cu")
		(net "M_F_CPU1_SB_DQS_DN<0>")
	)
	(segment
		(start 152.04059 -229.746302)
		(end 150.874222 -230.91267)
		(width 0.18288)
		(layer "In4.Cu")
		(net "M_F_CPU1_SB_DQS_DN<0>")
	)
	(segment
		(start 152.427178 -229.183692)
		(end 152.04059 -229.57028)
		(width 0.18288)
		(layer "In4.Cu")
		(net "M_F_CPU1_SB_DQS_DN<0>")
	)
	(segment
		(start 172.534834 -228.177852)
		(end 172.038518 -228.177852)
		(width 0.18288)
		(layer "In4.Cu")
		(net "M_F_CPU1_SB_DQS_DN<0>")
	)
	(segment
		(start 141.001496 -235.90885)
		(end 140.978128 -235.90885)
		(width 0.088646)
		(layer "In4.Cu")
		(net "M_F_CPU1_SB_DQS_DN<0>")
	)
	(segment
		(start 165.768528 -226.229672)
		(end 165.158674 -226.229672)
		(width 0.18288)
		(layer "In4.Cu")
		(net "M_F_CPU1_SB_DQS_DN<0>")
	)
	(segment
		(start 150.874222 -230.91267)
		(end 150.6982 -230.91267)
		(width 0.18288)
		(layer "In4.Cu")
		(net "M_F_CPU1_SB_DQS_DN<0>")
	)
	(segment
		(start 130.066288 -237.469172)
		(end 130.123946 -237.411514)
		(width 0.088646)
		(layer "In4.Cu")
		(net "M_F_CPU1_SB_DQS_DN<0>")
	)
	(segment
		(start 139.471146 -237.659926)
		(end 139.363958 -237.659926)
		(width 0.088646)
		(layer "In4.Cu")
		(net "M_F_CPU1_SB_DQS_DN<0>")
	)
	(segment
		(start 162.283648 -226.07397)
		(end 162.002216 -225.792538)
		(width 0.18288)
		(layer "In4.Cu")
		(net "M_F_CPU1_SB_DQS_DN<0>")
	)
	(segment
		(start 148.250148 -233.536744)
		(end 144.16405 -233.536744)
		(width 0.18288)
		(layer "In4.Cu")
		(net "M_F_CPU1_SB_DQS_DN<0>")
	)
	(segment
		(start 134.008368 -237.736126)
		(end 133.997954 -237.73003)
		(width 0.088646)
		(layer "In4.Cu")
		(net "M_F_CPU1_SB_DQS_DN<0>")
	)
	(segment
		(start 150.311866 -231.299004)
		(end 150.311866 -231.475026)
		(width 0.18288)
		(layer "In4.Cu")
		(net "M_F_CPU1_SB_DQS_DN<0>")
	)
	(segment
		(start 135.322564 -237.735872)
		(end 135.322564 -237.736126)
		(width 0.088646)
		(layer "In4.Cu")
		(net "M_F_CPU1_SB_DQS_DN<0>")
	)
	(segment
		(start 140.918438 -235.96854)
		(end 140.64107 -235.96854)
		(width 0.088646)
		(layer "In4.Cu")
		(net "M_F_CPU1_SB_DQS_DN<0>")
	)
	(segment
		(start 131.578096 -237.72749)
		(end 131.563364 -237.736126)
		(width 0.088646)
		(layer "In4.Cu")
		(net "M_F_CPU1_SB_DQS_DN<0>")
	)
	(segment
		(start 152.04059 -229.57028)
		(end 152.04059 -229.746302)
		(width 0.18288)
		(layer "In4.Cu")
		(net "M_F_CPU1_SB_DQS_DN<0>")
	)
	(segment
		(start 163.921186 -226.656646)
		(end 162.515296 -226.07397)
		(width 0.18288)
		(layer "In4.Cu")
		(net "M_F_CPU1_SB_DQS_DN<0>")
	)
	(segment
		(start 140.978128 -235.90885)
		(end 140.918438 -235.96854)
		(width 0.088646)
		(layer "In4.Cu")
		(net "M_F_CPU1_SB_DQS_DN<0>")
	)
	(segment
		(start 157.497272 -226.642422)
		(end 157.234128 -226.905566)
		(width 0.18288)
		(layer "In4.Cu")
		(net "M_F_CPU1_SB_DQS_DN<0>")
	)
	(segment
		(start 162.002216 -225.792538)
		(end 161.59734 -225.792538)
		(width 0.18288)
		(layer "In4.Cu")
		(net "M_F_CPU1_SB_DQS_DN<0>")
	)
	(segment
		(start 165.158674 -226.229672)
		(end 164.129212 -226.656646)
		(width 0.18288)
		(layer "In4.Cu")
		(net "M_F_CPU1_SB_DQS_DN<0>")
	)
	(segment
		(start 167.089836 -227.55098)
		(end 165.768528 -226.229672)
		(width 0.18288)
		(layer "In4.Cu")
		(net "M_F_CPU1_SB_DQS_DN<0>")
	)
	(segment
		(start 164.129212 -226.656646)
		(end 163.921186 -226.656646)
		(width 0.18288)
		(layer "In4.Cu")
		(net "M_F_CPU1_SB_DQS_DN<0>")
	)
	(segment
		(start 158.16072 -226.900994)
		(end 157.902148 -226.642422)
		(width 0.18288)
		(layer "In4.Cu")
		(net "M_F_CPU1_SB_DQS_DN<0>")
	)
	(arc
		(start 130.623564 -237.736126)
		(mid 130.436366 -237.786269)
		(end 130.249168 -237.736126)
		(width 0.088646)
		(layer "In4.Cu")
		(net "M_F_CPU1_SB_DQS_DN<0>")
	)
	(arc
		(start 133.44271 -237.736126)
		(mid 133.255512 -237.786269)
		(end 133.068314 -237.736126)
		(width 0.088646)
		(layer "In4.Cu")
		(net "M_F_CPU1_SB_DQS_DN<0>")
	)
	(arc
		(start 136.262364 -237.735872)
		(mid 136.075166 -237.786015)
		(end 135.887968 -237.735872)
		(width 0.088646)
		(layer "In4.Cu")
		(net "M_F_CPU1_SB_DQS_DN<0>")
	)
	(arc
		(start 139.081764 -237.735872)
		(mid 138.894566 -237.786015)
		(end 138.707368 -237.735872)
		(width 0.088646)
		(layer "In4.Cu")
		(net "M_F_CPU1_SB_DQS_DN<0>")
	)
	(arc
		(start 134.948168 -237.736126)
		(mid 134.665466 -237.66035)
		(end 134.382764 -237.736126)
		(width 0.088646)
		(layer "In4.Cu")
		(net "M_F_CPU1_SB_DQS_DN<0>")
	)
	(arc
		(start 138.707368 -237.735872)
		(mid 138.424666 -237.66013)
		(end 138.141964 -237.735872)
		(width 0.088646)
		(layer "In4.Cu")
		(net "M_F_CPU1_SB_DQS_DN<0>")
	)
	(arc
		(start 131.563364 -237.736126)
		(mid 131.376166 -237.786269)
		(end 131.188968 -237.736126)
		(width 0.088646)
		(layer "In4.Cu")
		(net "M_F_CPU1_SB_DQS_DN<0>")
	)
	(arc
		(start 137.202164 -237.735872)
		(mid 137.014966 -237.786015)
		(end 136.827768 -237.735872)
		(width 0.088646)
		(layer "In4.Cu")
		(net "M_F_CPU1_SB_DQS_DN<0>")
	)
	(arc
		(start 139.363958 -237.659926)
		(mid 139.217882 -237.679385)
		(end 139.081764 -237.735872)
		(width 0.088646)
		(layer "In4.Cu")
		(net "M_F_CPU1_SB_DQS_DN<0>")
	)
	(arc
		(start 132.503164 -237.736126)
		(mid 132.315966 -237.786269)
		(end 132.128768 -237.736126)
		(width 0.088646)
		(layer "In4.Cu")
		(net "M_F_CPU1_SB_DQS_DN<0>")
	)
	(arc
		(start 133.0579 -237.73003)
		(mid 132.779722 -237.660307)
		(end 132.503164 -237.736126)
		(width 0.088646)
		(layer "In4.Cu")
		(net "M_F_CPU1_SB_DQS_DN<0>")
	)
	(arc
		(start 132.128768 -237.736126)
		(mid 131.854569 -237.660291)
		(end 131.578096 -237.72749)
		(width 0.088646)
		(layer "In4.Cu")
		(net "M_F_CPU1_SB_DQS_DN<0>")
	)
	(arc
		(start 136.827768 -237.735872)
		(mid 136.545066 -237.66013)
		(end 136.262364 -237.735872)
		(width 0.088646)
		(layer "In4.Cu")
		(net "M_F_CPU1_SB_DQS_DN<0>")
	)
	(arc
		(start 134.382764 -237.736126)
		(mid 134.195566 -237.786269)
		(end 134.008368 -237.736126)
		(width 0.088646)
		(layer "In4.Cu")
		(net "M_F_CPU1_SB_DQS_DN<0>")
	)
	(arc
		(start 133.997954 -237.73003)
		(mid 133.719522 -237.660184)
		(end 133.44271 -237.736126)
		(width 0.088646)
		(layer "In4.Cu")
		(net "M_F_CPU1_SB_DQS_DN<0>")
	)
	(arc
		(start 130.240278 -237.731046)
		(mid 130.124539 -237.619222)
		(end 130.066288 -237.469172)
		(width 0.088646)
		(layer "In4.Cu")
		(net "M_F_CPU1_SB_DQS_DN<0>")
	)
	(arc
		(start 135.322564 -237.736126)
		(mid 135.135366 -237.786269)
		(end 134.948168 -237.736126)
		(width 0.088646)
		(layer "In4.Cu")
		(net "M_F_CPU1_SB_DQS_DN<0>")
	)
	(arc
		(start 135.887968 -237.735872)
		(mid 135.605266 -237.66013)
		(end 135.322564 -237.735872)
		(width 0.088646)
		(layer "In4.Cu")
		(net "M_F_CPU1_SB_DQS_DN<0>")
	)
	(arc
		(start 138.141964 -237.735872)
		(mid 137.954766 -237.786015)
		(end 137.767568 -237.735872)
		(width 0.088646)
		(layer "In4.Cu")
		(net "M_F_CPU1_SB_DQS_DN<0>")
	)
	(arc
		(start 137.767568 -237.735872)
		(mid 137.484866 -237.66013)
		(end 137.202164 -237.735872)
		(width 0.088646)
		(layer "In4.Cu")
		(net "M_F_CPU1_SB_DQS_DN<0>")
	)
	(arc
		(start 131.188968 -237.736126)
		(mid 130.914769 -237.660291)
		(end 130.638296 -237.72749)
		(width 0.088646)
		(layer "In4.Cu")
		(net "M_F_CPU1_SB_DQS_DN<0>")
	)
	(segment
		(start 181.444646 -221.116652)
		(end 181.444392 -221.116906)
		(width 0.20066)
		(layer "F.Cu")
		(net "M_F_CPU1_SB_DQ<9>")
	)
	(segment
		(start 179.011326 -220.68536)
		(end 179.004976 -220.69171)
		(width 0.1016)
		(layer "F.Cu")
		(net "M_F_CPU1_SB_DQ<9>")
	)
	(segment
		(start 181.444392 -221.116906)
		(end 179.852828 -221.116906)
		(width 0.20066)
		(layer "F.Cu")
		(net "M_F_CPU1_SB_DQ<9>")
	)
	(segment
		(start 176.333404 -220.80982)
		(end 176.333404 -221.177358)
		(width 0.20066)
		(layer "F.Cu")
		(net "M_F_CPU1_SB_DQ<9>")
	)
	(segment
		(start 176.333404 -221.177358)
		(end 176.145444 -221.365318)
		(width 0.20066)
		(layer "F.Cu")
		(net "M_F_CPU1_SB_DQ<9>")
	)
	(segment
		(start 176.816258 -220.69171)
		(end 176.796192 -220.69171)
		(width 0.101854)
		(layer "F.Cu")
		(net "M_F_CPU1_SB_DQ<9>")
	)
	(segment
		(start 179.852828 -221.116906)
		(end 179.421282 -220.68536)
		(width 0.20066)
		(layer "F.Cu")
		(net "M_F_CPU1_SB_DQ<9>")
	)
	(segment
		(start 176.451514 -220.69171)
		(end 176.333404 -220.80982)
		(width 0.20066)
		(layer "F.Cu")
		(net "M_F_CPU1_SB_DQ<9>")
	)
	(segment
		(start 179.004976 -220.69171)
		(end 176.816258 -220.69171)
		(width 0.1016)
		(layer "F.Cu")
		(net "M_F_CPU1_SB_DQ<9>")
	)
	(segment
		(start 175.421544 -221.116652)
		(end 173.900846 -221.116652)
		(width 0.20066)
		(layer "F.Cu")
		(net "M_F_CPU1_SB_DQ<9>")
	)
	(segment
		(start 176.796192 -220.69171)
		(end 176.451514 -220.69171)
		(width 0.20066)
		(layer "F.Cu")
		(net "M_F_CPU1_SB_DQ<9>")
	)
	(segment
		(start 175.67021 -221.365318)
		(end 175.421544 -221.116652)
		(width 0.20066)
		(layer "F.Cu")
		(net "M_F_CPU1_SB_DQ<9>")
	)
	(segment
		(start 179.421282 -220.68536)
		(end 179.011326 -220.68536)
		(width 0.20066)
		(layer "F.Cu")
		(net "M_F_CPU1_SB_DQ<9>")
	)
	(segment
		(start 133.255512 -231.436418)
		(end 133.255512 -230.900732)
		(width 0.20066)
		(layer "F.Cu")
		(net "M_F_CPU1_SB_DQ<9>")
	)
	(segment
		(start 173.900846 -221.116652)
		(end 172.795946 -221.116652)
		(width 0.20066)
		(layer "F.Cu")
		(net "M_F_CPU1_SB_DQ<9>")
	)
	(segment
		(start 176.145444 -221.365318)
		(end 175.67021 -221.365318)
		(width 0.20066)
		(layer "F.Cu")
		(net "M_F_CPU1_SB_DQ<9>")
	)
	(segment
		(start 133.255512 -230.900732)
		(end 133.255766 -230.900478)
		(width 0.20066)
		(layer "F.Cu")
		(net "M_F_CPU1_SB_DQ<9>")
	)
	(segment
		(start 137.580116 -230.900478)
		(end 137.580116 -230.91902)
		(width 0.088646)
		(layer "In2.Cu")
		(net "M_F_CPU1_SB_DQ<9>")
	)
	(segment
		(start 164.60216 -221.614492)
		(end 163.844732 -221.614492)
		(width 0.18288)
		(layer "In2.Cu")
		(net "M_F_CPU1_SB_DQ<9>")
	)
	(segment
		(start 170.041316 -221.592902)
		(end 169.848276 -221.399862)
		(width 0.18288)
		(layer "In2.Cu")
		(net "M_F_CPU1_SB_DQ<9>")
	)
	(segment
		(start 141.246352 -229.81412)
		(end 140.534898 -230.525574)
		(width 0.088646)
		(layer "In2.Cu")
		(net "M_F_CPU1_SB_DQ<9>")
	)
	(segment
		(start 158.926022 -220.461332)
		(end 158.52775 -220.461332)
		(width 0.18288)
		(layer "In2.Cu")
		(net "M_F_CPU1_SB_DQ<9>")
	)
	(segment
		(start 168.244266 -222.198946)
		(end 168.051226 -222.005906)
		(width 0.18288)
		(layer "In2.Cu")
		(net "M_F_CPU1_SB_DQ<9>")
	)
	(segment
		(start 168.864026 -221.93123)
		(end 168.59631 -222.198946)
		(width 0.18288)
		(layer "In2.Cu")
		(net "M_F_CPU1_SB_DQ<9>")
	)
	(segment
		(start 161.449512 -221.545912)
		(end 161.10458 -221.20098)
		(width 0.18288)
		(layer "In2.Cu")
		(net "M_F_CPU1_SB_DQ<9>")
	)
	(segment
		(start 172.795946 -221.116652)
		(end 172.795946 -221.455996)
		(width 0.18288)
		(layer "In2.Cu")
		(net "M_F_CPU1_SB_DQ<9>")
	)
	(segment
		(start 137.767568 -230.57612)
		(end 137.758678 -230.5812)
		(width 0.088646)
		(layer "In2.Cu")
		(net "M_F_CPU1_SB_DQ<9>")
	)
	(segment
		(start 133.320536 -230.950262)
		(end 133.255766 -230.900478)
		(width 0.088646)
		(layer "In2.Cu")
		(net "M_F_CPU1_SB_DQ<9>")
	)
	(segment
		(start 162.589464 -221.545912)
		(end 161.449512 -221.545912)
		(width 0.18288)
		(layer "In2.Cu")
		(net "M_F_CPU1_SB_DQ<9>")
	)
	(segment
		(start 133.835648 -231.34574)
		(end 133.320536 -230.950262)
		(width 0.088646)
		(layer "In2.Cu")
		(net "M_F_CPU1_SB_DQ<9>")
	)
	(segment
		(start 172.795946 -221.455996)
		(end 172.712634 -221.539308)
		(width 0.18288)
		(layer "In2.Cu")
		(net "M_F_CPU1_SB_DQ<9>")
	)
	(segment
		(start 166.80942 -221.896432)
		(end 165.856666 -221.896432)
		(width 0.18288)
		(layer "In2.Cu")
		(net "M_F_CPU1_SB_DQ<9>")
	)
	(segment
		(start 161.10458 -221.20098)
		(end 161.10458 -220.727778)
		(width 0.18288)
		(layer "In2.Cu")
		(net "M_F_CPU1_SB_DQ<9>")
	)
	(segment
		(start 168.051226 -221.381828)
		(end 167.949626 -221.280228)
		(width 0.18288)
		(layer "In2.Cu")
		(net "M_F_CPU1_SB_DQ<9>")
	)
	(segment
		(start 168.864026 -220.620844)
		(end 168.864026 -221.93123)
		(width 0.18288)
		(layer "In2.Cu")
		(net "M_F_CPU1_SB_DQ<9>")
	)
	(segment
		(start 160.2105 -220.697552)
		(end 159.162242 -220.697552)
		(width 0.18288)
		(layer "In2.Cu")
		(net "M_F_CPU1_SB_DQ<9>")
	)
	(segment
		(start 141.679422 -229.81412)
		(end 141.246352 -229.81412)
		(width 0.088646)
		(layer "In2.Cu")
		(net "M_F_CPU1_SB_DQ<9>")
	)
	(segment
		(start 162.965384 -221.169992)
		(end 162.589464 -221.545912)
		(width 0.18288)
		(layer "In2.Cu")
		(net "M_F_CPU1_SB_DQ<9>")
	)
	(segment
		(start 169.848276 -220.934026)
		(end 169.342054 -220.427804)
		(width 0.18288)
		(layer "In2.Cu")
		(net "M_F_CPU1_SB_DQ<9>")
	)
	(segment
		(start 163.684712 -221.454472)
		(end 163.684712 -221.436184)
		(width 0.18288)
		(layer "In2.Cu")
		(net "M_F_CPU1_SB_DQ<9>")
	)
	(segment
		(start 172.193966 -221.61627)
		(end 172.000926 -221.42323)
		(width 0.18288)
		(layer "In2.Cu")
		(net "M_F_CPU1_SB_DQ<9>")
	)
	(segment
		(start 172.526706 -221.61627)
		(end 172.193966 -221.61627)
		(width 0.18288)
		(layer "In2.Cu")
		(net "M_F_CPU1_SB_DQ<9>")
	)
	(segment
		(start 156.142944 -222.036132)
		(end 154.38755 -222.036132)
		(width 0.18288)
		(layer "In2.Cu")
		(net "M_F_CPU1_SB_DQ<9>")
	)
	(segment
		(start 167.425624 -221.280228)
		(end 166.80942 -221.896432)
		(width 0.18288)
		(layer "In2.Cu")
		(net "M_F_CPU1_SB_DQ<9>")
	)
	(segment
		(start 172.000926 -220.888814)
		(end 171.792138 -220.680026)
		(width 0.18288)
		(layer "In2.Cu")
		(net "M_F_CPU1_SB_DQ<9>")
	)
	(segment
		(start 140.534898 -230.525574)
		(end 139.834366 -230.525574)
		(width 0.088646)
		(layer "In2.Cu")
		(net "M_F_CPU1_SB_DQ<9>")
	)
	(segment
		(start 163.684712 -221.436184)
		(end 163.41852 -221.169992)
		(width 0.18288)
		(layer "In2.Cu")
		(net "M_F_CPU1_SB_DQ<9>")
	)
	(segment
		(start 159.162242 -220.697552)
		(end 158.926022 -220.461332)
		(width 0.18288)
		(layer "In2.Cu")
		(net "M_F_CPU1_SB_DQ<9>")
	)
	(segment
		(start 171.792138 -220.680026)
		(end 171.071794 -220.680026)
		(width 0.18288)
		(layer "In2.Cu")
		(net "M_F_CPU1_SB_DQ<9>")
	)
	(segment
		(start 172.712634 -221.539308)
		(end 172.526706 -221.61627)
		(width 0.18288)
		(layer "In2.Cu")
		(net "M_F_CPU1_SB_DQ<9>")
	)
	(segment
		(start 170.747944 -221.592902)
		(end 170.041316 -221.592902)
		(width 0.18288)
		(layer "In2.Cu")
		(net "M_F_CPU1_SB_DQ<9>")
	)
	(segment
		(start 170.911774 -220.840046)
		(end 170.911774 -221.429072)
		(width 0.18288)
		(layer "In2.Cu")
		(net "M_F_CPU1_SB_DQ<9>")
	)
	(segment
		(start 168.051226 -222.005906)
		(end 168.051226 -221.381828)
		(width 0.18288)
		(layer "In2.Cu")
		(net "M_F_CPU1_SB_DQ<9>")
	)
	(segment
		(start 172.000926 -221.42323)
		(end 172.000926 -220.888814)
		(width 0.18288)
		(layer "In2.Cu")
		(net "M_F_CPU1_SB_DQ<9>")
	)
	(segment
		(start 158.52775 -220.461332)
		(end 158.275274 -220.713808)
		(width 0.18288)
		(layer "In2.Cu")
		(net "M_F_CPU1_SB_DQ<9>")
	)
	(segment
		(start 154.38755 -222.036132)
		(end 146.609562 -229.81412)
		(width 0.18288)
		(layer "In2.Cu")
		(net "M_F_CPU1_SB_DQ<9>")
	)
	(segment
		(start 157.465268 -220.713808)
		(end 156.142944 -222.036132)
		(width 0.18288)
		(layer "In2.Cu")
		(net "M_F_CPU1_SB_DQ<9>")
	)
	(segment
		(start 158.275274 -220.713808)
		(end 157.465268 -220.713808)
		(width 0.18288)
		(layer "In2.Cu")
		(net "M_F_CPU1_SB_DQ<9>")
	)
	(segment
		(start 168.59631 -222.198946)
		(end 168.244266 -222.198946)
		(width 0.18288)
		(layer "In2.Cu")
		(net "M_F_CPU1_SB_DQ<9>")
	)
	(segment
		(start 161.10458 -220.727778)
		(end 160.91154 -220.534738)
		(width 0.18288)
		(layer "In2.Cu")
		(net "M_F_CPU1_SB_DQ<9>")
	)
	(segment
		(start 146.609562 -229.81412)
		(end 141.679422 -229.81412)
		(width 0.18288)
		(layer "In2.Cu")
		(net "M_F_CPU1_SB_DQ<9>")
	)
	(segment
		(start 167.949626 -221.280228)
		(end 167.425624 -221.280228)
		(width 0.18288)
		(layer "In2.Cu")
		(net "M_F_CPU1_SB_DQ<9>")
	)
	(segment
		(start 169.342054 -220.427804)
		(end 169.057066 -220.427804)
		(width 0.18288)
		(layer "In2.Cu")
		(net "M_F_CPU1_SB_DQ<9>")
	)
	(segment
		(start 165.243764 -221.28353)
		(end 164.933122 -221.28353)
		(width 0.18288)
		(layer "In2.Cu")
		(net "M_F_CPU1_SB_DQ<9>")
	)
	(segment
		(start 160.373314 -220.534738)
		(end 160.2105 -220.697552)
		(width 0.18288)
		(layer "In2.Cu")
		(net "M_F_CPU1_SB_DQ<9>")
	)
	(segment
		(start 163.844732 -221.614492)
		(end 163.684712 -221.454472)
		(width 0.18288)
		(layer "In2.Cu")
		(net "M_F_CPU1_SB_DQ<9>")
	)
	(segment
		(start 169.057066 -220.427804)
		(end 168.864026 -220.620844)
		(width 0.18288)
		(layer "In2.Cu")
		(net "M_F_CPU1_SB_DQ<9>")
	)
	(segment
		(start 165.856666 -221.896432)
		(end 165.243764 -221.28353)
		(width 0.18288)
		(layer "In2.Cu")
		(net "M_F_CPU1_SB_DQ<9>")
	)
	(segment
		(start 170.911774 -221.429072)
		(end 170.747944 -221.592902)
		(width 0.18288)
		(layer "In2.Cu")
		(net "M_F_CPU1_SB_DQ<9>")
	)
	(segment
		(start 169.848276 -221.399862)
		(end 169.848276 -220.934026)
		(width 0.18288)
		(layer "In2.Cu")
		(net "M_F_CPU1_SB_DQ<9>")
	)
	(segment
		(start 134.867396 -231.398826)
		(end 134.852664 -231.39019)
		(width 0.088646)
		(layer "In2.Cu")
		(net "M_F_CPU1_SB_DQ<9>")
	)
	(segment
		(start 133.912864 -231.39019)
		(end 133.835648 -231.34574)
		(width 0.088646)
		(layer "In2.Cu")
		(net "M_F_CPU1_SB_DQ<9>")
	)
	(segment
		(start 163.41852 -221.169992)
		(end 162.965384 -221.169992)
		(width 0.18288)
		(layer "In2.Cu")
		(net "M_F_CPU1_SB_DQ<9>")
	)
	(segment
		(start 171.071794 -220.680026)
		(end 170.911774 -220.840046)
		(width 0.18288)
		(layer "In2.Cu")
		(net "M_F_CPU1_SB_DQ<9>")
	)
	(segment
		(start 160.91154 -220.534738)
		(end 160.373314 -220.534738)
		(width 0.18288)
		(layer "In2.Cu")
		(net "M_F_CPU1_SB_DQ<9>")
	)
	(segment
		(start 164.933122 -221.28353)
		(end 164.60216 -221.614492)
		(width 0.18288)
		(layer "In2.Cu")
		(net "M_F_CPU1_SB_DQ<9>")
	)
	(arc
		(start 135.418068 -231.39019)
		(mid 135.143839 -231.466115)
		(end 134.867396 -231.398826)
		(width 0.088646)
		(layer "In2.Cu")
		(net "M_F_CPU1_SB_DQ<9>")
	)
	(arc
		(start 136.732264 -231.39019)
		(mid 136.545066 -231.340047)
		(end 136.357868 -231.39019)
		(width 0.088646)
		(layer "In2.Cu")
		(net "M_F_CPU1_SB_DQ<9>")
	)
	(arc
		(start 139.647168 -230.57612)
		(mid 139.364466 -230.651896)
		(end 139.081764 -230.57612)
		(width 0.088646)
		(layer "In2.Cu")
		(net "M_F_CPU1_SB_DQ<9>")
	)
	(arc
		(start 137.297668 -231.39019)
		(mid 137.014966 -231.465932)
		(end 136.732264 -231.39019)
		(width 0.088646)
		(layer "In2.Cu")
		(net "M_F_CPU1_SB_DQ<9>")
	)
	(arc
		(start 139.834366 -230.525574)
		(mid 139.737438 -230.538525)
		(end 139.647168 -230.57612)
		(width 0.088646)
		(layer "In2.Cu")
		(net "M_F_CPU1_SB_DQ<9>")
	)
	(arc
		(start 137.580116 -230.91902)
		(mid 137.499954 -231.191209)
		(end 137.297668 -231.39019)
		(width 0.088646)
		(layer "In2.Cu")
		(net "M_F_CPU1_SB_DQ<9>")
	)
	(arc
		(start 139.081764 -230.57612)
		(mid 138.894566 -230.525977)
		(end 138.707368 -230.57612)
		(width 0.088646)
		(layer "In2.Cu")
		(net "M_F_CPU1_SB_DQ<9>")
	)
	(arc
		(start 136.357868 -231.39019)
		(mid 136.075166 -231.465932)
		(end 135.792464 -231.39019)
		(width 0.088646)
		(layer "In2.Cu")
		(net "M_F_CPU1_SB_DQ<9>")
	)
	(arc
		(start 135.792464 -231.39019)
		(mid 135.605266 -231.340047)
		(end 135.418068 -231.39019)
		(width 0.088646)
		(layer "In2.Cu")
		(net "M_F_CPU1_SB_DQ<9>")
	)
	(arc
		(start 134.478268 -231.39019)
		(mid 134.195566 -231.465932)
		(end 133.912864 -231.39019)
		(width 0.088646)
		(layer "In2.Cu")
		(net "M_F_CPU1_SB_DQ<9>")
	)
	(arc
		(start 137.758678 -230.5812)
		(mid 137.627764 -230.71756)
		(end 137.580116 -230.900478)
		(width 0.088646)
		(layer "In2.Cu")
		(net "M_F_CPU1_SB_DQ<9>")
	)
	(arc
		(start 138.707368 -230.57612)
		(mid 138.424666 -230.651896)
		(end 138.141964 -230.57612)
		(width 0.088646)
		(layer "In2.Cu")
		(net "M_F_CPU1_SB_DQ<9>")
	)
	(arc
		(start 134.852664 -231.39019)
		(mid 134.665466 -231.340047)
		(end 134.478268 -231.39019)
		(width 0.088646)
		(layer "In2.Cu")
		(net "M_F_CPU1_SB_DQ<9>")
	)
	(arc
		(start 138.141964 -230.57612)
		(mid 137.954766 -230.525977)
		(end 137.767568 -230.57612)
		(width 0.088646)
		(layer "In2.Cu")
		(net "M_F_CPU1_SB_DQ<9>")
	)
	(segment
		(start 133.725666 -232.250488)
		(end 133.725666 -231.714548)
		(width 0.20066)
		(layer "F.Cu")
		(net "M_F_CPU1_SB_DQ<8>")
	)
	(segment
		(start 175.67021 -223.06534)
		(end 175.421544 -222.816674)
		(width 0.20066)
		(layer "F.Cu")
		(net "M_F_CPU1_SB_DQ<8>")
	)
	(segment
		(start 175.421544 -222.816674)
		(end 173.900846 -222.816674)
		(width 0.20066)
		(layer "F.Cu")
		(net "M_F_CPU1_SB_DQ<8>")
	)
	(segment
		(start 181.444646 -222.816674)
		(end 181.444392 -222.816928)
		(width 0.20066)
		(layer "F.Cu")
		(net "M_F_CPU1_SB_DQ<8>")
	)
	(segment
		(start 176.333404 -222.509842)
		(end 176.333404 -222.87738)
		(width 0.20066)
		(layer "F.Cu")
		(net "M_F_CPU1_SB_DQ<8>")
	)
	(segment
		(start 176.843182 -222.391732)
		(end 176.796192 -222.391732)
		(width 0.101854)
		(layer "F.Cu")
		(net "M_F_CPU1_SB_DQ<8>")
	)
	(segment
		(start 173.900846 -222.816674)
		(end 172.795946 -222.816674)
		(width 0.20066)
		(layer "F.Cu")
		(net "M_F_CPU1_SB_DQ<8>")
	)
	(segment
		(start 176.145444 -223.06534)
		(end 175.67021 -223.06534)
		(width 0.20066)
		(layer "F.Cu")
		(net "M_F_CPU1_SB_DQ<8>")
	)
	(segment
		(start 176.451514 -222.391732)
		(end 176.333404 -222.509842)
		(width 0.20066)
		(layer "F.Cu")
		(net "M_F_CPU1_SB_DQ<8>")
	)
	(segment
		(start 179.421282 -222.385382)
		(end 179.011326 -222.385382)
		(width 0.20066)
		(layer "F.Cu")
		(net "M_F_CPU1_SB_DQ<8>")
	)
	(segment
		(start 179.852828 -222.816928)
		(end 179.421282 -222.385382)
		(width 0.20066)
		(layer "F.Cu")
		(net "M_F_CPU1_SB_DQ<8>")
	)
	(segment
		(start 179.011326 -222.385382)
		(end 179.004976 -222.391732)
		(width 0.1016)
		(layer "F.Cu")
		(net "M_F_CPU1_SB_DQ<8>")
	)
	(segment
		(start 179.004976 -222.391732)
		(end 176.843182 -222.391732)
		(width 0.1016)
		(layer "F.Cu")
		(net "M_F_CPU1_SB_DQ<8>")
	)
	(segment
		(start 181.444392 -222.816928)
		(end 179.852828 -222.816928)
		(width 0.20066)
		(layer "F.Cu")
		(net "M_F_CPU1_SB_DQ<8>")
	)
	(segment
		(start 176.796192 -222.391732)
		(end 176.451514 -222.391732)
		(width 0.20066)
		(layer "F.Cu")
		(net "M_F_CPU1_SB_DQ<8>")
	)
	(segment
		(start 176.333404 -222.87738)
		(end 176.145444 -223.06534)
		(width 0.20066)
		(layer "F.Cu")
		(net "M_F_CPU1_SB_DQ<8>")
	)
	(segment
		(start 162.622738 -223.265238)
		(end 162.597592 -223.240092)
		(width 0.18288)
		(layer "In2.Cu")
		(net "M_F_CPU1_SB_DQ<8>")
	)
	(segment
		(start 162.597592 -223.240092)
		(end 161.86404 -223.240092)
		(width 0.18288)
		(layer "In2.Cu")
		(net "M_F_CPU1_SB_DQ<8>")
	)
	(segment
		(start 168.71569 -224.854262)
		(end 168.546272 -225.02368)
		(width 0.18288)
		(layer "In2.Cu")
		(net "M_F_CPU1_SB_DQ<8>")
	)
	(segment
		(start 168.546272 -225.02368)
		(end 168.232328 -225.02368)
		(width 0.18288)
		(layer "In2.Cu")
		(net "M_F_CPU1_SB_DQ<8>")
	)
	(segment
		(start 172.293026 -223.898206)
		(end 172.12564 -224.065592)
		(width 0.18288)
		(layer "In2.Cu")
		(net "M_F_CPU1_SB_DQ<8>")
	)
	(segment
		(start 165.181534 -222.912432)
		(end 164.689282 -222.912432)
		(width 0.18288)
		(layer "In2.Cu")
		(net "M_F_CPU1_SB_DQ<8>")
	)
	(segment
		(start 157.874208 -222.445072)
		(end 157.267148 -223.052132)
		(width 0.18288)
		(layer "In2.Cu")
		(net "M_F_CPU1_SB_DQ<8>")
	)
	(segment
		(start 140.923772 -230.841296)
		(end 140.759942 -231.005126)
		(width 0.088646)
		(layer "In2.Cu")
		(net "M_F_CPU1_SB_DQ<8>")
	)
	(segment
		(start 169.30751 -223.326198)
		(end 168.822878 -223.326198)
		(width 0.18288)
		(layer "In2.Cu")
		(net "M_F_CPU1_SB_DQ<8>")
	)
	(segment
		(start 164.336476 -223.265238)
		(end 162.622738 -223.265238)
		(width 0.18288)
		(layer "In2.Cu")
		(net "M_F_CPU1_SB_DQ<8>")
	)
	(segment
		(start 172.12564 -224.065592)
		(end 171.050966 -224.065592)
		(width 0.18288)
		(layer "In2.Cu")
		(net "M_F_CPU1_SB_DQ<8>")
	)
	(segment
		(start 165.958012 -223.68891)
		(end 165.181534 -222.912432)
		(width 0.18288)
		(layer "In2.Cu")
		(net "M_F_CPU1_SB_DQ<8>")
	)
	(segment
		(start 139.65047 -231.33939)
		(end 139.364466 -231.33939)
		(width 0.088646)
		(layer "In2.Cu")
		(net "M_F_CPU1_SB_DQ<8>")
	)
	(segment
		(start 134.290054 -232.137204)
		(end 133.725666 -231.714548)
		(width 0.088646)
		(layer "In2.Cu")
		(net "M_F_CPU1_SB_DQ<8>")
	)
	(segment
		(start 171.050966 -224.065592)
		(end 170.890946 -224.225612)
		(width 0.18288)
		(layer "In2.Cu")
		(net "M_F_CPU1_SB_DQ<8>")
	)
	(segment
		(start 140.759942 -231.005126)
		(end 139.984734 -231.005126)
		(width 0.088646)
		(layer "In2.Cu")
		(net "M_F_CPU1_SB_DQ<8>")
	)
	(segment
		(start 172.293026 -223.318324)
		(end 172.293026 -223.898206)
		(width 0.18288)
		(layer "In2.Cu")
		(net "M_F_CPU1_SB_DQ<8>")
	)
	(segment
		(start 169.473626 -223.492314)
		(end 169.30751 -223.326198)
		(width 0.18288)
		(layer "In2.Cu")
		(net "M_F_CPU1_SB_DQ<8>")
	)
	(segment
		(start 167.777668 -223.23171)
		(end 167.190928 -223.23171)
		(width 0.18288)
		(layer "In2.Cu")
		(net "M_F_CPU1_SB_DQ<8>")
	)
	(segment
		(start 168.71569 -223.433386)
		(end 168.71569 -224.854262)
		(width 0.18288)
		(layer "In2.Cu")
		(net "M_F_CPU1_SB_DQ<8>")
	)
	(segment
		(start 161.86404 -223.240092)
		(end 161.863278 -223.240854)
		(width 0.18288)
		(layer "In2.Cu")
		(net "M_F_CPU1_SB_DQ<8>")
	)
	(segment
		(start 138.050016 -231.714548)
		(end 138.050016 -231.724454)
		(width 0.088646)
		(layer "In2.Cu")
		(net "M_F_CPU1_SB_DQ<8>")
	)
	(segment
		(start 170.168824 -224.787714)
		(end 170.168824 -224.218246)
		(width 0.18288)
		(layer "In2.Cu")
		(net "M_F_CPU1_SB_DQ<8>")
	)
	(segment
		(start 170.890946 -224.787714)
		(end 170.730926 -224.947734)
		(width 0.18288)
		(layer "In2.Cu")
		(net "M_F_CPU1_SB_DQ<8>")
	)
	(segment
		(start 167.971978 -223.42602)
		(end 167.777668 -223.23171)
		(width 0.18288)
		(layer "In2.Cu")
		(net "M_F_CPU1_SB_DQ<8>")
	)
	(segment
		(start 138.237468 -231.39019)
		(end 138.228578 -231.39527)
		(width 0.088646)
		(layer "In2.Cu")
		(net "M_F_CPU1_SB_DQ<8>")
	)
	(segment
		(start 169.633646 -224.058226)
		(end 169.473626 -223.898206)
		(width 0.18288)
		(layer "In2.Cu")
		(net "M_F_CPU1_SB_DQ<8>")
	)
	(segment
		(start 147.085812 -230.841296)
		(end 141.679422 -230.841296)
		(width 0.18288)
		(layer "In2.Cu")
		(net "M_F_CPU1_SB_DQ<8>")
	)
	(segment
		(start 154.874976 -223.052132)
		(end 147.085812 -230.841296)
		(width 0.18288)
		(layer "In2.Cu")
		(net "M_F_CPU1_SB_DQ<8>")
	)
	(segment
		(start 166.747444 -224.110296)
		(end 166.1668 -224.110296)
		(width 0.18288)
		(layer "In2.Cu")
		(net "M_F_CPU1_SB_DQ<8>")
	)
	(segment
		(start 170.008804 -224.058226)
		(end 169.633646 -224.058226)
		(width 0.18288)
		(layer "In2.Cu")
		(net "M_F_CPU1_SB_DQ<8>")
	)
	(segment
		(start 166.940738 -223.4819)
		(end 166.940738 -223.917002)
		(width 0.18288)
		(layer "In2.Cu")
		(net "M_F_CPU1_SB_DQ<8>")
	)
	(segment
		(start 166.1668 -224.110296)
		(end 165.958012 -223.901508)
		(width 0.18288)
		(layer "In2.Cu")
		(net "M_F_CPU1_SB_DQ<8>")
	)
	(segment
		(start 172.794676 -222.816674)
		(end 172.293026 -223.318324)
		(width 0.18288)
		(layer "In2.Cu")
		(net "M_F_CPU1_SB_DQ<8>")
	)
	(segment
		(start 139.984734 -231.005126)
		(end 139.65047 -231.33939)
		(width 0.088646)
		(layer "In2.Cu")
		(net "M_F_CPU1_SB_DQ<8>")
	)
	(segment
		(start 170.890946 -224.225612)
		(end 170.890946 -224.787714)
		(width 0.18288)
		(layer "In2.Cu")
		(net "M_F_CPU1_SB_DQ<8>")
	)
	(segment
		(start 172.795946 -222.816674)
		(end 172.794676 -222.816674)
		(width 0.18288)
		(layer "In2.Cu")
		(net "M_F_CPU1_SB_DQ<8>")
	)
	(segment
		(start 165.958012 -223.901508)
		(end 165.958012 -223.68891)
		(width 0.18288)
		(layer "In2.Cu")
		(net "M_F_CPU1_SB_DQ<8>")
	)
	(segment
		(start 170.168824 -224.218246)
		(end 170.008804 -224.058226)
		(width 0.18288)
		(layer "In2.Cu")
		(net "M_F_CPU1_SB_DQ<8>")
	)
	(segment
		(start 168.822878 -223.326198)
		(end 168.71569 -223.433386)
		(width 0.18288)
		(layer "In2.Cu")
		(net "M_F_CPU1_SB_DQ<8>")
	)
	(segment
		(start 166.940738 -223.917002)
		(end 166.747444 -224.110296)
		(width 0.18288)
		(layer "In2.Cu")
		(net "M_F_CPU1_SB_DQ<8>")
	)
	(segment
		(start 161.863278 -223.240854)
		(end 161.495994 -223.240854)
		(width 0.18288)
		(layer "In2.Cu")
		(net "M_F_CPU1_SB_DQ<8>")
	)
	(segment
		(start 170.730926 -224.947734)
		(end 170.328844 -224.947734)
		(width 0.18288)
		(layer "In2.Cu")
		(net "M_F_CPU1_SB_DQ<8>")
	)
	(segment
		(start 157.267148 -223.052132)
		(end 154.874976 -223.052132)
		(width 0.18288)
		(layer "In2.Cu")
		(net "M_F_CPU1_SB_DQ<8>")
	)
	(segment
		(start 164.689282 -222.912432)
		(end 164.336476 -223.265238)
		(width 0.18288)
		(layer "In2.Cu")
		(net "M_F_CPU1_SB_DQ<8>")
	)
	(segment
		(start 167.190928 -223.23171)
		(end 166.940738 -223.4819)
		(width 0.18288)
		(layer "In2.Cu")
		(net "M_F_CPU1_SB_DQ<8>")
	)
	(segment
		(start 161.495994 -223.240854)
		(end 160.700212 -222.445072)
		(width 0.18288)
		(layer "In2.Cu")
		(net "M_F_CPU1_SB_DQ<8>")
	)
	(segment
		(start 167.971978 -224.76333)
		(end 167.971978 -223.42602)
		(width 0.18288)
		(layer "In2.Cu")
		(net "M_F_CPU1_SB_DQ<8>")
	)
	(segment
		(start 141.679422 -230.841296)
		(end 140.923772 -230.841296)
		(width 0.088646)
		(layer "In2.Cu")
		(net "M_F_CPU1_SB_DQ<8>")
	)
	(segment
		(start 169.473626 -223.898206)
		(end 169.473626 -223.492314)
		(width 0.18288)
		(layer "In2.Cu")
		(net "M_F_CPU1_SB_DQ<8>")
	)
	(segment
		(start 160.700212 -222.445072)
		(end 157.874208 -222.445072)
		(width 0.18288)
		(layer "In2.Cu")
		(net "M_F_CPU1_SB_DQ<8>")
	)
	(segment
		(start 168.232328 -225.02368)
		(end 167.971978 -224.76333)
		(width 0.18288)
		(layer "In2.Cu")
		(net "M_F_CPU1_SB_DQ<8>")
	)
	(segment
		(start 170.328844 -224.947734)
		(end 170.168824 -224.787714)
		(width 0.18288)
		(layer "In2.Cu")
		(net "M_F_CPU1_SB_DQ<8>")
	)
	(arc
		(start 137.202164 -232.204006)
		(mid 137.014966 -232.153863)
		(end 136.827768 -232.204006)
		(width 0.088646)
		(layer "In2.Cu")
		(net "M_F_CPU1_SB_DQ<8>")
	)
	(arc
		(start 135.322564 -232.204006)
		(mid 135.135366 -232.153863)
		(end 134.948168 -232.204006)
		(width 0.088646)
		(layer "In2.Cu")
		(net "M_F_CPU1_SB_DQ<8>")
	)
	(arc
		(start 136.827768 -232.204006)
		(mid 136.545066 -232.279782)
		(end 136.262364 -232.204006)
		(width 0.088646)
		(layer "In2.Cu")
		(net "M_F_CPU1_SB_DQ<8>")
	)
	(arc
		(start 135.887968 -232.204006)
		(mid 135.605266 -232.279782)
		(end 135.322564 -232.204006)
		(width 0.088646)
		(layer "In2.Cu")
		(net "M_F_CPU1_SB_DQ<8>")
	)
	(arc
		(start 138.611864 -231.39019)
		(mid 138.424666 -231.340047)
		(end 138.237468 -231.39019)
		(width 0.088646)
		(layer "In2.Cu")
		(net "M_F_CPU1_SB_DQ<8>")
	)
	(arc
		(start 138.050016 -231.724454)
		(mid 137.971905 -232.001403)
		(end 137.767568 -232.204006)
		(width 0.088646)
		(layer "In2.Cu")
		(net "M_F_CPU1_SB_DQ<8>")
	)
	(arc
		(start 137.767568 -232.204006)
		(mid 137.484866 -232.279782)
		(end 137.202164 -232.204006)
		(width 0.088646)
		(layer "In2.Cu")
		(net "M_F_CPU1_SB_DQ<8>")
	)
	(arc
		(start 136.262364 -232.204006)
		(mid 136.075166 -232.153863)
		(end 135.887968 -232.204006)
		(width 0.088646)
		(layer "In2.Cu")
		(net "M_F_CPU1_SB_DQ<8>")
	)
	(arc
		(start 138.228578 -231.39527)
		(mid 138.097664 -231.53163)
		(end 138.050016 -231.714548)
		(width 0.088646)
		(layer "In2.Cu")
		(net "M_F_CPU1_SB_DQ<8>")
	)
	(arc
		(start 134.948168 -232.204006)
		(mid 134.665466 -232.279782)
		(end 134.382764 -232.204006)
		(width 0.088646)
		(layer "In2.Cu")
		(net "M_F_CPU1_SB_DQ<8>")
	)
	(arc
		(start 134.382764 -232.204006)
		(mid 134.334717 -232.172953)
		(end 134.290054 -232.137204)
		(width 0.088646)
		(layer "In2.Cu")
		(net "M_F_CPU1_SB_DQ<8>")
	)
	(arc
		(start 139.364466 -231.33939)
		(mid 139.267527 -231.35248)
		(end 139.177268 -231.39019)
		(width 0.088646)
		(layer "In2.Cu")
		(net "M_F_CPU1_SB_DQ<8>")
	)
	(arc
		(start 139.177268 -231.39019)
		(mid 138.894566 -231.465932)
		(end 138.611864 -231.39019)
		(width 0.088646)
		(layer "In2.Cu")
		(net "M_F_CPU1_SB_DQ<8>")
	)
	(segment
		(start 179.699158 -223.666558)
		(end 180.131212 -224.098612)
		(width 0.20066)
		(layer "F.Cu")
		(net "M_F_CPU1_SB_DQ<7>")
	)
	(segment
		(start 176.896014 -223.666558)
		(end 178.000914 -223.666558)
		(width 0.20066)
		(layer "F.Cu")
		(net "M_F_CPU1_SB_DQ<7>")
	)
	(segment
		(start 183.340248 -223.89973)
		(end 183.340248 -223.648778)
		(width 0.20066)
		(layer "F.Cu")
		(net "M_F_CPU1_SB_DQ<7>")
	)
	(segment
		(start 180.427884 -224.098612)
		(end 180.434996 -224.0915)
		(width 0.1016)
		(layer "F.Cu")
		(net "M_F_CPU1_SB_DQ<7>")
	)
	(segment
		(start 180.434996 -224.0915)
		(end 182.442866 -224.0915)
		(width 0.1016)
		(layer "F.Cu")
		(net "M_F_CPU1_SB_DQ<7>")
	)
	(segment
		(start 180.423058 -224.098612)
		(end 180.427884 -224.098612)
		(width 0.101854)
		(layer "F.Cu")
		(net "M_F_CPU1_SB_DQ<7>")
	)
	(segment
		(start 182.455058 -224.103692)
		(end 183.136286 -224.103692)
		(width 0.20066)
		(layer "F.Cu")
		(net "M_F_CPU1_SB_DQ<7>")
	)
	(segment
		(start 183.340248 -223.648778)
		(end 183.574436 -223.41459)
		(width 0.20066)
		(layer "F.Cu")
		(net "M_F_CPU1_SB_DQ<7>")
	)
	(segment
		(start 183.574436 -223.41459)
		(end 183.958484 -223.41459)
		(width 0.20066)
		(layer "F.Cu")
		(net "M_F_CPU1_SB_DQ<7>")
	)
	(segment
		(start 180.131212 -224.098612)
		(end 180.423058 -224.098612)
		(width 0.20066)
		(layer "F.Cu")
		(net "M_F_CPU1_SB_DQ<7>")
	)
	(segment
		(start 183.958484 -223.41459)
		(end 184.210452 -223.666558)
		(width 0.20066)
		(layer "F.Cu")
		(net "M_F_CPU1_SB_DQ<7>")
	)
	(segment
		(start 182.442866 -224.0915)
		(end 182.455058 -224.103692)
		(width 0.1016)
		(layer "F.Cu")
		(net "M_F_CPU1_SB_DQ<7>")
	)
	(segment
		(start 183.136286 -224.103692)
		(end 183.340248 -223.89973)
		(width 0.20066)
		(layer "F.Cu")
		(net "M_F_CPU1_SB_DQ<7>")
	)
	(segment
		(start 131.376166 -236.319568)
		(end 131.376166 -235.783882)
		(width 0.20066)
		(layer "F.Cu")
		(net "M_F_CPU1_SB_DQ<7>")
	)
	(segment
		(start 131.375912 -236.319822)
		(end 131.376166 -236.319568)
		(width 0.20066)
		(layer "F.Cu")
		(net "M_F_CPU1_SB_DQ<7>")
	)
	(segment
		(start 178.000914 -223.666558)
		(end 179.699158 -223.666558)
		(width 0.20066)
		(layer "F.Cu")
		(net "M_F_CPU1_SB_DQ<7>")
	)
	(segment
		(start 184.210452 -223.666558)
		(end 185.544714 -223.666558)
		(width 0.20066)
		(layer "F.Cu")
		(net "M_F_CPU1_SB_DQ<7>")
	)
	(segment
		(start 132.039106 -235.291122)
		(end 132.033264 -235.294424)
		(width 0.088646)
		(layer "In4.Cu")
		(net "M_F_CPU1_SB_DQ<7>")
	)
	(segment
		(start 140.234162 -232.658158)
		(end 140.168376 -232.724198)
		(width 0.088646)
		(layer "In4.Cu")
		(net "M_F_CPU1_SB_DQ<7>")
	)
	(segment
		(start 174.332646 -222.745554)
		(end 174.149766 -222.562674)
		(width 0.18288)
		(layer "In4.Cu")
		(net "M_F_CPU1_SB_DQ<7>")
	)
	(segment
		(start 174.332646 -223.058736)
		(end 174.332646 -222.745554)
		(width 0.18288)
		(layer "In4.Cu")
		(net "M_F_CPU1_SB_DQ<7>")
	)
	(segment
		(start 173.822106 -222.562674)
		(end 173.639226 -222.745554)
		(width 0.18288)
		(layer "In4.Cu")
		(net "M_F_CPU1_SB_DQ<7>")
	)
	(segment
		(start 138.6205 -235.289344)
		(end 138.61161 -235.294424)
		(width 0.088646)
		(layer "In4.Cu")
		(net "M_F_CPU1_SB_DQ<7>")
	)
	(segment
		(start 138.237214 -235.294424)
		(end 138.222482 -235.285788)
		(width 0.088646)
		(layer "In4.Cu")
		(net "M_F_CPU1_SB_DQ<7>")
	)
	(segment
		(start 135.792464 -235.294424)
		(end 135.788146 -235.296964)
		(width 0.088646)
		(layer "In4.Cu")
		(net "M_F_CPU1_SB_DQ<7>")
	)
	(segment
		(start 173.456346 -223.241616)
		(end 172.53585 -223.241616)
		(width 0.18288)
		(layer "In4.Cu")
		(net "M_F_CPU1_SB_DQ<7>")
	)
	(segment
		(start 170.08856 -220.692472)
		(end 156.27223 -220.692472)
		(width 0.18288)
		(layer "In4.Cu")
		(net "M_F_CPU1_SB_DQ<7>")
	)
	(segment
		(start 134.858506 -235.291122)
		(end 134.852664 -235.294424)
		(width 0.088646)
		(layer "In4.Cu")
		(net "M_F_CPU1_SB_DQ<7>")
	)
	(segment
		(start 176.896014 -223.666558)
		(end 175.65116 -223.241616)
		(width 0.18288)
		(layer "In4.Cu")
		(net "M_F_CPU1_SB_DQ<7>")
	)
	(segment
		(start 139.081764 -234.480608)
		(end 139.075668 -234.484164)
		(width 0.088646)
		(layer "In4.Cu")
		(net "M_F_CPU1_SB_DQ<7>")
	)
	(segment
		(start 146.227038 -230.737664)
		(end 142.955518 -230.737664)
		(width 0.18288)
		(layer "In4.Cu")
		(net "M_F_CPU1_SB_DQ<7>")
	)
	(segment
		(start 139.269216 -234.137708)
		(end 139.269216 -234.15625)
		(width 0.088646)
		(layer "In4.Cu")
		(net "M_F_CPU1_SB_DQ<7>")
	)
	(segment
		(start 132.978906 -235.291122)
		(end 132.967222 -235.297726)
		(width 0.088646)
		(layer "In4.Cu")
		(net "M_F_CPU1_SB_DQ<7>")
	)
	(segment
		(start 172.115226 -222.719138)
		(end 170.08856 -220.692472)
		(width 0.18288)
		(layer "In4.Cu")
		(net "M_F_CPU1_SB_DQ<7>")
	)
	(segment
		(start 132.033264 -235.294424)
		(end 131.92887 -235.355892)
		(width 0.088646)
		(layer "In4.Cu")
		(net "M_F_CPU1_SB_DQ<7>")
	)
	(segment
		(start 141.035024 -232.658158)
		(end 140.493496 -232.658158)
		(width 0.18288)
		(layer "In4.Cu")
		(net "M_F_CPU1_SB_DQ<7>")
	)
	(segment
		(start 139.739116 -233.332274)
		(end 139.739116 -233.34218)
		(width 0.088646)
		(layer "In4.Cu")
		(net "M_F_CPU1_SB_DQ<7>")
	)
	(segment
		(start 173.639226 -222.745554)
		(end 173.639226 -223.058736)
		(width 0.18288)
		(layer "In4.Cu")
		(net "M_F_CPU1_SB_DQ<7>")
	)
	(segment
		(start 137.297414 -235.294424)
		(end 137.282682 -235.285788)
		(width 0.088646)
		(layer "In4.Cu")
		(net "M_F_CPU1_SB_DQ<7>")
	)
	(segment
		(start 174.515526 -223.241616)
		(end 174.332646 -223.058736)
		(width 0.18288)
		(layer "In4.Cu")
		(net "M_F_CPU1_SB_DQ<7>")
	)
	(segment
		(start 142.955518 -230.737664)
		(end 141.035024 -232.658158)
		(width 0.18288)
		(layer "In4.Cu")
		(net "M_F_CPU1_SB_DQ<7>")
	)
	(segment
		(start 140.493496 -232.658158)
		(end 140.234162 -232.658158)
		(width 0.088646)
		(layer "In4.Cu")
		(net "M_F_CPU1_SB_DQ<7>")
	)
	(segment
		(start 139.560554 -233.661458)
		(end 139.551664 -233.666538)
		(width 0.088646)
		(layer "In4.Cu")
		(net "M_F_CPU1_SB_DQ<7>")
	)
	(segment
		(start 172.115226 -222.820992)
		(end 172.115226 -222.719138)
		(width 0.18288)
		(layer "In4.Cu")
		(net "M_F_CPU1_SB_DQ<7>")
	)
	(segment
		(start 131.376166 -235.783628)
		(end 131.376166 -235.783882)
		(width 0.088646)
		(layer "In4.Cu")
		(net "M_F_CPU1_SB_DQ<7>")
	)
	(segment
		(start 174.149766 -222.562674)
		(end 173.822106 -222.562674)
		(width 0.18288)
		(layer "In4.Cu")
		(net "M_F_CPU1_SB_DQ<7>")
	)
	(segment
		(start 140.168376 -232.724198)
		(end 140.099288 -232.793286)
		(width 0.088646)
		(layer "In4.Cu")
		(net "M_F_CPU1_SB_DQ<7>")
	)
	(segment
		(start 172.53585 -223.241616)
		(end 172.115226 -222.820992)
		(width 0.18288)
		(layer "In4.Cu")
		(net "M_F_CPU1_SB_DQ<7>")
	)
	(segment
		(start 173.639226 -223.058736)
		(end 173.456346 -223.241616)
		(width 0.18288)
		(layer "In4.Cu")
		(net "M_F_CPU1_SB_DQ<7>")
	)
	(segment
		(start 134.852664 -235.294424)
		(end 134.848854 -235.29671)
		(width 0.088646)
		(layer "In4.Cu")
		(net "M_F_CPU1_SB_DQ<7>")
	)
	(segment
		(start 139.090654 -234.475528)
		(end 139.081764 -234.480608)
		(width 0.088646)
		(layer "In4.Cu")
		(net "M_F_CPU1_SB_DQ<7>")
	)
	(segment
		(start 133.912864 -235.294424)
		(end 133.908546 -235.296964)
		(width 0.088646)
		(layer "In4.Cu")
		(net "M_F_CPU1_SB_DQ<7>")
	)
	(segment
		(start 175.65116 -223.241616)
		(end 174.515526 -223.241616)
		(width 0.18288)
		(layer "In4.Cu")
		(net "M_F_CPU1_SB_DQ<7>")
	)
	(segment
		(start 156.27223 -220.692472)
		(end 146.227038 -230.737664)
		(width 0.18288)
		(layer "In4.Cu")
		(net "M_F_CPU1_SB_DQ<7>")
	)
	(arc
		(start 138.222482 -235.285788)
		(mid 137.946007 -235.218468)
		(end 137.67181 -235.294424)
		(width 0.088646)
		(layer "In4.Cu")
		(net "M_F_CPU1_SB_DQ<7>")
	)
	(arc
		(start 131.92887 -235.355892)
		(mid 131.638987 -235.552276)
		(end 131.376166 -235.783628)
		(width 0.088646)
		(layer "In4.Cu")
		(net "M_F_CPU1_SB_DQ<7>")
	)
	(arc
		(start 133.538214 -235.294424)
		(mid 133.259011 -235.218784)
		(end 132.978906 -235.291122)
		(width 0.088646)
		(layer "In4.Cu")
		(net "M_F_CPU1_SB_DQ<7>")
	)
	(arc
		(start 136.357614 -235.294424)
		(mid 136.075056 -235.218775)
		(end 135.792464 -235.294424)
		(width 0.088646)
		(layer "In4.Cu")
		(net "M_F_CPU1_SB_DQ<7>")
	)
	(arc
		(start 132.967222 -235.297726)
		(mid 132.782367 -235.344676)
		(end 132.598414 -235.294424)
		(width 0.088646)
		(layer "In4.Cu")
		(net "M_F_CPU1_SB_DQ<7>")
	)
	(arc
		(start 139.269216 -234.15625)
		(mid 139.221537 -234.33915)
		(end 139.090654 -234.475528)
		(width 0.088646)
		(layer "In4.Cu")
		(net "M_F_CPU1_SB_DQ<7>")
	)
	(arc
		(start 135.788146 -235.296964)
		(mid 135.602651 -235.344633)
		(end 135.417814 -235.294424)
		(width 0.088646)
		(layer "In4.Cu")
		(net "M_F_CPU1_SB_DQ<7>")
	)
	(arc
		(start 140.099288 -232.793286)
		(mid 140.062378 -232.825557)
		(end 140.021564 -232.852722)
		(width 0.088646)
		(layer "In4.Cu")
		(net "M_F_CPU1_SB_DQ<7>")
	)
	(arc
		(start 135.417814 -235.294424)
		(mid 135.138611 -235.218784)
		(end 134.858506 -235.291122)
		(width 0.088646)
		(layer "In4.Cu")
		(net "M_F_CPU1_SB_DQ<7>")
	)
	(arc
		(start 134.848854 -235.29671)
		(mid 134.663135 -235.344662)
		(end 134.478014 -235.294424)
		(width 0.088646)
		(layer "In4.Cu")
		(net "M_F_CPU1_SB_DQ<7>")
	)
	(arc
		(start 139.739116 -233.34218)
		(mid 139.691437 -233.52508)
		(end 139.560554 -233.661458)
		(width 0.088646)
		(layer "In4.Cu")
		(net "M_F_CPU1_SB_DQ<7>")
	)
	(arc
		(start 139.551664 -233.666538)
		(mid 139.349378 -233.865519)
		(end 139.269216 -234.137708)
		(width 0.088646)
		(layer "In4.Cu")
		(net "M_F_CPU1_SB_DQ<7>")
	)
	(arc
		(start 132.598414 -235.294424)
		(mid 132.319211 -235.218784)
		(end 132.039106 -235.291122)
		(width 0.088646)
		(layer "In4.Cu")
		(net "M_F_CPU1_SB_DQ<7>")
	)
	(arc
		(start 138.799062 -234.970066)
		(mid 138.751383 -235.152966)
		(end 138.6205 -235.289344)
		(width 0.088646)
		(layer "In4.Cu")
		(net "M_F_CPU1_SB_DQ<7>")
	)
	(arc
		(start 133.908546 -235.296964)
		(mid 133.723051 -235.344633)
		(end 133.538214 -235.294424)
		(width 0.088646)
		(layer "In4.Cu")
		(net "M_F_CPU1_SB_DQ<7>")
	)
	(arc
		(start 138.61161 -235.294424)
		(mid 138.424412 -235.344567)
		(end 138.237214 -235.294424)
		(width 0.088646)
		(layer "In4.Cu")
		(net "M_F_CPU1_SB_DQ<7>")
	)
	(arc
		(start 139.075668 -234.484164)
		(mid 138.873081 -234.690515)
		(end 138.799062 -234.970066)
		(width 0.088646)
		(layer "In4.Cu")
		(net "M_F_CPU1_SB_DQ<7>")
	)
	(arc
		(start 136.73201 -235.294424)
		(mid 136.544812 -235.344567)
		(end 136.357614 -235.294424)
		(width 0.088646)
		(layer "In4.Cu")
		(net "M_F_CPU1_SB_DQ<7>")
	)
	(arc
		(start 140.021564 -232.852722)
		(mid 139.817229 -233.055327)
		(end 139.739116 -233.332274)
		(width 0.088646)
		(layer "In4.Cu")
		(net "M_F_CPU1_SB_DQ<7>")
	)
	(arc
		(start 137.67181 -235.294424)
		(mid 137.484612 -235.344567)
		(end 137.297414 -235.294424)
		(width 0.088646)
		(layer "In4.Cu")
		(net "M_F_CPU1_SB_DQ<7>")
	)
	(arc
		(start 134.478014 -235.294424)
		(mid 134.195456 -235.218775)
		(end 133.912864 -235.294424)
		(width 0.088646)
		(layer "In4.Cu")
		(net "M_F_CPU1_SB_DQ<7>")
	)
	(arc
		(start 137.282682 -235.285788)
		(mid 137.006207 -235.218468)
		(end 136.73201 -235.294424)
		(width 0.088646)
		(layer "In4.Cu")
		(net "M_F_CPU1_SB_DQ<7>")
	)
	(segment
		(start 131.846066 -237.133892)
		(end 131.845812 -237.133638)
		(width 0.20066)
		(layer "F.Cu")
		(net "M_F_CPU1_SB_DQ<6>")
	)
	(segment
		(start 180.427884 -225.798634)
		(end 180.434996 -225.791522)
		(width 0.1016)
		(layer "F.Cu")
		(net "M_F_CPU1_SB_DQ<6>")
	)
	(segment
		(start 184.210452 -225.36658)
		(end 185.544714 -225.36658)
		(width 0.20066)
		(layer "F.Cu")
		(net "M_F_CPU1_SB_DQ<6>")
	)
	(segment
		(start 183.340248 -225.3488)
		(end 183.574436 -225.114612)
		(width 0.20066)
		(layer "F.Cu")
		(net "M_F_CPU1_SB_DQ<6>")
	)
	(segment
		(start 182.442866 -225.791522)
		(end 182.455058 -225.803714)
		(width 0.1016)
		(layer "F.Cu")
		(net "M_F_CPU1_SB_DQ<6>")
	)
	(segment
		(start 176.896014 -225.36658)
		(end 178.000914 -225.36658)
		(width 0.20066)
		(layer "F.Cu")
		(net "M_F_CPU1_SB_DQ<6>")
	)
	(segment
		(start 178.000914 -225.36658)
		(end 179.699158 -225.36658)
		(width 0.20066)
		(layer "F.Cu")
		(net "M_F_CPU1_SB_DQ<6>")
	)
	(segment
		(start 180.434996 -225.791522)
		(end 182.442866 -225.791522)
		(width 0.1016)
		(layer "F.Cu")
		(net "M_F_CPU1_SB_DQ<6>")
	)
	(segment
		(start 180.131212 -225.798634)
		(end 180.423058 -225.798634)
		(width 0.20066)
		(layer "F.Cu")
		(net "M_F_CPU1_SB_DQ<6>")
	)
	(segment
		(start 180.423058 -225.798634)
		(end 180.427884 -225.798634)
		(width 0.101854)
		(layer "F.Cu")
		(net "M_F_CPU1_SB_DQ<6>")
	)
	(segment
		(start 183.340248 -225.599752)
		(end 183.340248 -225.3488)
		(width 0.20066)
		(layer "F.Cu")
		(net "M_F_CPU1_SB_DQ<6>")
	)
	(segment
		(start 183.136286 -225.803714)
		(end 183.340248 -225.599752)
		(width 0.20066)
		(layer "F.Cu")
		(net "M_F_CPU1_SB_DQ<6>")
	)
	(segment
		(start 182.455058 -225.803714)
		(end 183.136286 -225.803714)
		(width 0.20066)
		(layer "F.Cu")
		(net "M_F_CPU1_SB_DQ<6>")
	)
	(segment
		(start 183.958484 -225.114612)
		(end 184.210452 -225.36658)
		(width 0.20066)
		(layer "F.Cu")
		(net "M_F_CPU1_SB_DQ<6>")
	)
	(segment
		(start 183.574436 -225.114612)
		(end 183.958484 -225.114612)
		(width 0.20066)
		(layer "F.Cu")
		(net "M_F_CPU1_SB_DQ<6>")
	)
	(segment
		(start 131.845812 -237.133638)
		(end 131.845812 -236.597952)
		(width 0.20066)
		(layer "F.Cu")
		(net "M_F_CPU1_SB_DQ<6>")
	)
	(segment
		(start 179.699158 -225.36658)
		(end 180.131212 -225.798634)
		(width 0.20066)
		(layer "F.Cu")
		(net "M_F_CPU1_SB_DQ<6>")
	)
	(segment
		(start 170.353736 -224.443544)
		(end 170.170856 -224.260664)
		(width 0.18288)
		(layer "In4.Cu")
		(net "M_F_CPU1_SB_DQ<6>")
	)
	(segment
		(start 175.864266 -225.562922)
		(end 175.518826 -225.41992)
		(width 0.18288)
		(layer "In4.Cu")
		(net "M_F_CPU1_SB_DQ<6>")
	)
	(segment
		(start 134.008114 -236.108494)
		(end 134.002526 -236.105192)
		(width 0.088646)
		(layer "In4.Cu")
		(net "M_F_CPU1_SB_DQ<6>")
	)
	(segment
		(start 139.090654 -236.10316)
		(end 139.081764 -236.10824)
		(width 0.088646)
		(layer "In4.Cu")
		(net "M_F_CPU1_SB_DQ<6>")
	)
	(segment
		(start 174.380652 -224.9424)
		(end 172.389546 -224.9424)
		(width 0.18288)
		(layer "In4.Cu")
		(net "M_F_CPU1_SB_DQ<6>")
	)
	(segment
		(start 134.952486 -236.111034)
		(end 134.943342 -236.1057)
		(width 0.088646)
		(layer "In4.Cu")
		(net "M_F_CPU1_SB_DQ<6>")
	)
	(segment
		(start 133.072886 -236.111034)
		(end 133.060948 -236.104176)
		(width 0.088646)
		(layer "In4.Cu")
		(net "M_F_CPU1_SB_DQ<6>")
	)
	(segment
		(start 146.738594 -231.733344)
		(end 143.368014 -231.733344)
		(width 0.18288)
		(layer "In4.Cu")
		(net "M_F_CPU1_SB_DQ<6>")
	)
	(segment
		(start 174.741332 -224.58172)
		(end 174.380652 -224.9424)
		(width 0.18288)
		(layer "In4.Cu")
		(net "M_F_CPU1_SB_DQ<6>")
	)
	(segment
		(start 139.269216 -235.768388)
		(end 139.269216 -235.783882)
		(width 0.088646)
		(layer "In4.Cu")
		(net "M_F_CPU1_SB_DQ<6>")
	)
	(segment
		(start 170.681396 -224.443544)
		(end 170.353736 -224.443544)
		(width 0.18288)
		(layer "In4.Cu")
		(net "M_F_CPU1_SB_DQ<6>")
	)
	(segment
		(start 164.69487 -222.378524)
		(end 161.382964 -222.378524)
		(width 0.18288)
		(layer "In4.Cu")
		(net "M_F_CPU1_SB_DQ<6>")
	)
	(segment
		(start 143.368014 -231.733344)
		(end 141.209522 -233.891836)
		(width 0.18288)
		(layer "In4.Cu")
		(net "M_F_CPU1_SB_DQ<6>")
	)
	(segment
		(start 140.493496 -233.891836)
		(end 140.389102 -233.891836)
		(width 0.088646)
		(layer "In4.Cu")
		(net "M_F_CPU1_SB_DQ<6>")
	)
	(segment
		(start 175.431958 -225.210878)
		(end 175.504094 -225.037142)
		(width 0.18288)
		(layer "In4.Cu")
		(net "M_F_CPU1_SB_DQ<6>")
	)
	(segment
		(start 175.518826 -225.41992)
		(end 175.431958 -225.210878)
		(width 0.18288)
		(layer "In4.Cu")
		(net "M_F_CPU1_SB_DQ<6>")
	)
	(segment
		(start 166.448486 -223.194626)
		(end 165.911276 -222.657416)
		(width 0.18288)
		(layer "In4.Cu")
		(net "M_F_CPU1_SB_DQ<6>")
	)
	(segment
		(start 171.047156 -223.771206)
		(end 170.864276 -223.954086)
		(width 0.18288)
		(layer "In4.Cu")
		(net "M_F_CPU1_SB_DQ<6>")
	)
	(segment
		(start 140.389102 -233.891836)
		(end 139.739116 -234.541822)
		(width 0.088646)
		(layer "In4.Cu")
		(net "M_F_CPU1_SB_DQ<6>")
	)
	(segment
		(start 170.864276 -223.954086)
		(end 170.864276 -224.260664)
		(width 0.18288)
		(layer "In4.Cu")
		(net "M_F_CPU1_SB_DQ<6>")
	)
	(segment
		(start 169.987976 -223.771206)
		(end 168.500552 -223.771206)
		(width 0.18288)
		(layer "In4.Cu")
		(net "M_F_CPU1_SB_DQ<6>")
	)
	(segment
		(start 155.942538 -222.5294)
		(end 146.738594 -231.733344)
		(width 0.18288)
		(layer "In4.Cu")
		(net "M_F_CPU1_SB_DQ<6>")
	)
	(segment
		(start 176.171098 -225.239326)
		(end 176.0728 -225.476308)
		(width 0.18288)
		(layer "In4.Cu")
		(net "M_F_CPU1_SB_DQ<6>")
	)
	(segment
		(start 175.001174 -224.58172)
		(end 174.741332 -224.58172)
		(width 0.18288)
		(layer "In4.Cu")
		(net "M_F_CPU1_SB_DQ<6>")
	)
	(segment
		(start 172.389546 -224.9424)
		(end 172.139356 -224.69221)
		(width 0.18288)
		(layer "In4.Cu")
		(net "M_F_CPU1_SB_DQ<6>")
	)
	(segment
		(start 175.504094 -225.037142)
		(end 175.380396 -224.738946)
		(width 0.18288)
		(layer "In4.Cu")
		(net "M_F_CPU1_SB_DQ<6>")
	)
	(segment
		(start 171.472606 -223.771206)
		(end 171.047156 -223.771206)
		(width 0.18288)
		(layer "In4.Cu")
		(net "M_F_CPU1_SB_DQ<6>")
	)
	(segment
		(start 138.156696 -236.099604)
		(end 138.141964 -236.10824)
		(width 0.088646)
		(layer "In4.Cu")
		(net "M_F_CPU1_SB_DQ<6>")
	)
	(segment
		(start 170.170856 -224.260664)
		(end 170.170856 -223.954086)
		(width 0.18288)
		(layer "In4.Cu")
		(net "M_F_CPU1_SB_DQ<6>")
	)
	(segment
		(start 170.170856 -223.954086)
		(end 169.987976 -223.771206)
		(width 0.18288)
		(layer "In4.Cu")
		(net "M_F_CPU1_SB_DQ<6>")
	)
	(segment
		(start 176.896014 -225.36658)
		(end 176.379886 -225.152966)
		(width 0.18288)
		(layer "In4.Cu")
		(net "M_F_CPU1_SB_DQ<6>")
	)
	(segment
		(start 139.566396 -235.285788)
		(end 139.55141 -235.294424)
		(width 0.088646)
		(layer "In4.Cu")
		(net "M_F_CPU1_SB_DQ<6>")
	)
	(segment
		(start 165.911276 -222.657416)
		(end 164.973762 -222.657416)
		(width 0.18288)
		(layer "In4.Cu")
		(net "M_F_CPU1_SB_DQ<6>")
	)
	(segment
		(start 132.503164 -236.108494)
		(end 132.46354 -236.131354)
		(width 0.088646)
		(layer "In4.Cu")
		(net "M_F_CPU1_SB_DQ<6>")
	)
	(segment
		(start 170.864276 -224.260664)
		(end 170.681396 -224.443544)
		(width 0.18288)
		(layer "In4.Cu")
		(net "M_F_CPU1_SB_DQ<6>")
	)
	(segment
		(start 168.500552 -223.771206)
		(end 167.923972 -223.194626)
		(width 0.18288)
		(layer "In4.Cu")
		(net "M_F_CPU1_SB_DQ<6>")
	)
	(segment
		(start 172.139356 -224.69221)
		(end 172.139356 -224.437956)
		(width 0.18288)
		(layer "In4.Cu")
		(net "M_F_CPU1_SB_DQ<6>")
	)
	(segment
		(start 141.209522 -233.891836)
		(end 140.493496 -233.891836)
		(width 0.18288)
		(layer "In4.Cu")
		(net "M_F_CPU1_SB_DQ<6>")
	)
	(segment
		(start 139.739116 -234.541822)
		(end 139.739116 -234.970066)
		(width 0.088646)
		(layer "In4.Cu")
		(net "M_F_CPU1_SB_DQ<6>")
	)
	(segment
		(start 135.887968 -236.10824)
		(end 135.882126 -236.105192)
		(width 0.088646)
		(layer "In4.Cu")
		(net "M_F_CPU1_SB_DQ<6>")
	)
	(segment
		(start 137.216896 -236.099604)
		(end 137.202164 -236.10824)
		(width 0.088646)
		(layer "In4.Cu")
		(net "M_F_CPU1_SB_DQ<6>")
	)
	(segment
		(start 172.139356 -224.437956)
		(end 171.472606 -223.771206)
		(width 0.18288)
		(layer "In4.Cu")
		(net "M_F_CPU1_SB_DQ<6>")
	)
	(segment
		(start 136.277096 -236.099604)
		(end 136.262364 -236.10824)
		(width 0.088646)
		(layer "In4.Cu")
		(net "M_F_CPU1_SB_DQ<6>")
	)
	(segment
		(start 167.923972 -223.194626)
		(end 166.448486 -223.194626)
		(width 0.18288)
		(layer "In4.Cu")
		(net "M_F_CPU1_SB_DQ<6>")
	)
	(segment
		(start 164.973762 -222.657416)
		(end 164.69487 -222.378524)
		(width 0.18288)
		(layer "In4.Cu")
		(net "M_F_CPU1_SB_DQ<6>")
	)
	(segment
		(start 132.389626 -236.18063)
		(end 131.845812 -236.597952)
		(width 0.088646)
		(layer "In4.Cu")
		(net "M_F_CPU1_SB_DQ<6>")
	)
	(segment
		(start 175.380396 -224.738946)
		(end 175.001174 -224.58172)
		(width 0.18288)
		(layer "In4.Cu")
		(net "M_F_CPU1_SB_DQ<6>")
	)
	(segment
		(start 176.379886 -225.152966)
		(end 176.171098 -225.239326)
		(width 0.18288)
		(layer "In4.Cu")
		(net "M_F_CPU1_SB_DQ<6>")
	)
	(segment
		(start 161.382964 -222.378524)
		(end 161.232088 -222.5294)
		(width 0.18288)
		(layer "In4.Cu")
		(net "M_F_CPU1_SB_DQ<6>")
	)
	(segment
		(start 161.232088 -222.5294)
		(end 155.942538 -222.5294)
		(width 0.18288)
		(layer "In4.Cu")
		(net "M_F_CPU1_SB_DQ<6>")
	)
	(segment
		(start 176.0728 -225.476308)
		(end 175.864266 -225.562922)
		(width 0.18288)
		(layer "In4.Cu")
		(net "M_F_CPU1_SB_DQ<6>")
	)
	(arc
		(start 135.322564 -236.108494)
		(mid 135.13787 -236.158595)
		(end 134.952486 -236.111034)
		(width 0.088646)
		(layer "In4.Cu")
		(net "M_F_CPU1_SB_DQ<6>")
	)
	(arc
		(start 134.002526 -236.105192)
		(mid 133.722311 -236.032751)
		(end 133.442964 -236.108494)
		(width 0.088646)
		(layer "In4.Cu")
		(net "M_F_CPU1_SB_DQ<6>")
	)
	(arc
		(start 136.262364 -236.10824)
		(mid 136.075166 -236.158383)
		(end 135.887968 -236.10824)
		(width 0.088646)
		(layer "In4.Cu")
		(net "M_F_CPU1_SB_DQ<6>")
	)
	(arc
		(start 139.269216 -235.783882)
		(mid 139.221537 -235.966782)
		(end 139.090654 -236.10316)
		(width 0.088646)
		(layer "In4.Cu")
		(net "M_F_CPU1_SB_DQ<6>")
	)
	(arc
		(start 137.202164 -236.10824)
		(mid 137.014966 -236.158383)
		(end 136.827768 -236.10824)
		(width 0.088646)
		(layer "In4.Cu")
		(net "M_F_CPU1_SB_DQ<6>")
	)
	(arc
		(start 134.943342 -236.1057)
		(mid 134.662678 -236.032692)
		(end 134.382764 -236.108494)
		(width 0.088646)
		(layer "In4.Cu")
		(net "M_F_CPU1_SB_DQ<6>")
	)
	(arc
		(start 139.081764 -236.10824)
		(mid 138.894566 -236.158383)
		(end 138.707368 -236.10824)
		(width 0.088646)
		(layer "In4.Cu")
		(net "M_F_CPU1_SB_DQ<6>")
	)
	(arc
		(start 139.739116 -234.970066)
		(mid 139.693112 -235.150003)
		(end 139.566396 -235.285788)
		(width 0.088646)
		(layer "In4.Cu")
		(net "M_F_CPU1_SB_DQ<6>")
	)
	(arc
		(start 136.827768 -236.10824)
		(mid 136.553539 -236.032315)
		(end 136.277096 -236.099604)
		(width 0.088646)
		(layer "In4.Cu")
		(net "M_F_CPU1_SB_DQ<6>")
	)
	(arc
		(start 132.46354 -236.131354)
		(mid 132.425759 -236.154756)
		(end 132.389626 -236.18063)
		(width 0.088646)
		(layer "In4.Cu")
		(net "M_F_CPU1_SB_DQ<6>")
	)
	(arc
		(start 134.382764 -236.108494)
		(mid 134.195456 -236.158603)
		(end 134.008114 -236.108494)
		(width 0.088646)
		(layer "In4.Cu")
		(net "M_F_CPU1_SB_DQ<6>")
	)
	(arc
		(start 135.882126 -236.105192)
		(mid 135.601911 -236.032751)
		(end 135.322564 -236.108494)
		(width 0.088646)
		(layer "In4.Cu")
		(net "M_F_CPU1_SB_DQ<6>")
	)
	(arc
		(start 137.767568 -236.10824)
		(mid 137.493339 -236.032315)
		(end 137.216896 -236.099604)
		(width 0.088646)
		(layer "In4.Cu")
		(net "M_F_CPU1_SB_DQ<6>")
	)
	(arc
		(start 139.55141 -235.294424)
		(mid 139.348587 -235.494655)
		(end 139.269216 -235.768388)
		(width 0.088646)
		(layer "In4.Cu")
		(net "M_F_CPU1_SB_DQ<6>")
	)
	(arc
		(start 138.141964 -236.10824)
		(mid 137.954766 -236.158383)
		(end 137.767568 -236.10824)
		(width 0.088646)
		(layer "In4.Cu")
		(net "M_F_CPU1_SB_DQ<6>")
	)
	(arc
		(start 133.060948 -236.104176)
		(mid 132.781487 -236.032739)
		(end 132.503164 -236.108494)
		(width 0.088646)
		(layer "In4.Cu")
		(net "M_F_CPU1_SB_DQ<6>")
	)
	(arc
		(start 133.442964 -236.108494)
		(mid 133.25827 -236.158595)
		(end 133.072886 -236.111034)
		(width 0.088646)
		(layer "In4.Cu")
		(net "M_F_CPU1_SB_DQ<6>")
	)
	(arc
		(start 138.707368 -236.10824)
		(mid 138.433139 -236.032315)
		(end 138.156696 -236.099604)
		(width 0.088646)
		(layer "In4.Cu")
		(net "M_F_CPU1_SB_DQ<6>")
	)
	(segment
		(start 173.900846 -224.516696)
		(end 172.795946 -224.516696)
		(width 0.20066)
		(layer "F.Cu")
		(net "M_F_CPU1_SB_DQ<5>")
	)
	(segment
		(start 176.145444 -224.765362)
		(end 175.67021 -224.765362)
		(width 0.20066)
		(layer "F.Cu")
		(net "M_F_CPU1_SB_DQ<5>")
	)
	(segment
		(start 179.011326 -224.085404)
		(end 179.004976 -224.091754)
		(width 0.1016)
		(layer "F.Cu")
		(net "M_F_CPU1_SB_DQ<5>")
	)
	(segment
		(start 179.852828 -224.51695)
		(end 179.421282 -224.085404)
		(width 0.20066)
		(layer "F.Cu")
		(net "M_F_CPU1_SB_DQ<5>")
	)
	(segment
		(start 176.451514 -224.091754)
		(end 176.333404 -224.209864)
		(width 0.20066)
		(layer "F.Cu")
		(net "M_F_CPU1_SB_DQ<5>")
	)
	(segment
		(start 179.421282 -224.085404)
		(end 179.011326 -224.085404)
		(width 0.20066)
		(layer "F.Cu")
		(net "M_F_CPU1_SB_DQ<5>")
	)
	(segment
		(start 130.436366 -236.319568)
		(end 130.436366 -235.783882)
		(width 0.20066)
		(layer "F.Cu")
		(net "M_F_CPU1_SB_DQ<5>")
	)
	(segment
		(start 176.333404 -224.577402)
		(end 176.145444 -224.765362)
		(width 0.20066)
		(layer "F.Cu")
		(net "M_F_CPU1_SB_DQ<5>")
	)
	(segment
		(start 179.004976 -224.091754)
		(end 176.816258 -224.091754)
		(width 0.1016)
		(layer "F.Cu")
		(net "M_F_CPU1_SB_DQ<5>")
	)
	(segment
		(start 176.816258 -224.091754)
		(end 176.796192 -224.091754)
		(width 0.101854)
		(layer "F.Cu")
		(net "M_F_CPU1_SB_DQ<5>")
	)
	(segment
		(start 130.436112 -236.319822)
		(end 130.436366 -236.319568)
		(width 0.20066)
		(layer "F.Cu")
		(net "M_F_CPU1_SB_DQ<5>")
	)
	(segment
		(start 175.67021 -224.765362)
		(end 175.421544 -224.516696)
		(width 0.20066)
		(layer "F.Cu")
		(net "M_F_CPU1_SB_DQ<5>")
	)
	(segment
		(start 181.444646 -224.516696)
		(end 181.444392 -224.51695)
		(width 0.20066)
		(layer "F.Cu")
		(net "M_F_CPU1_SB_DQ<5>")
	)
	(segment
		(start 181.444392 -224.51695)
		(end 179.852828 -224.51695)
		(width 0.20066)
		(layer "F.Cu")
		(net "M_F_CPU1_SB_DQ<5>")
	)
	(segment
		(start 175.421544 -224.516696)
		(end 173.900846 -224.516696)
		(width 0.20066)
		(layer "F.Cu")
		(net "M_F_CPU1_SB_DQ<5>")
	)
	(segment
		(start 176.333404 -224.209864)
		(end 176.333404 -224.577402)
		(width 0.20066)
		(layer "F.Cu")
		(net "M_F_CPU1_SB_DQ<5>")
	)
	(segment
		(start 176.796192 -224.091754)
		(end 176.451514 -224.091754)
		(width 0.20066)
		(layer "F.Cu")
		(net "M_F_CPU1_SB_DQ<5>")
	)
	(segment
		(start 172.60316 -224.19056)
		(end 171.683426 -223.270826)
		(width 0.18288)
		(layer "In4.Cu")
		(net "M_F_CPU1_SB_DQ<5>")
	)
	(segment
		(start 134.953756 -235.456222)
		(end 134.943342 -235.462064)
		(width 0.088646)
		(layer "In4.Cu")
		(net "M_F_CPU1_SB_DQ<5>")
	)
	(segment
		(start 170.022774 -223.110806)
		(end 169.862754 -223.270826)
		(width 0.18288)
		(layer "In4.Cu")
		(net "M_F_CPU1_SB_DQ<5>")
	)
	(segment
		(start 168.00576 -221.449392)
		(end 167.84574 -221.289372)
		(width 0.18288)
		(layer "In4.Cu")
		(net "M_F_CPU1_SB_DQ<5>")
	)
	(segment
		(start 170.876214 -223.270826)
		(end 170.716194 -223.110806)
		(width 0.18288)
		(layer "In4.Cu")
		(net "M_F_CPU1_SB_DQ<5>")
	)
	(segment
		(start 172.795946 -224.516696)
		(end 172.60316 -224.32391)
		(width 0.18288)
		(layer "In4.Cu")
		(net "M_F_CPU1_SB_DQ<5>")
	)
	(segment
		(start 164.825426 -221.416626)
		(end 164.416232 -221.82582)
		(width 0.18288)
		(layer "In4.Cu")
		(net "M_F_CPU1_SB_DQ<5>")
	)
	(segment
		(start 162.596068 -221.500192)
		(end 162.596068 -221.66326)
		(width 0.18288)
		(layer "In4.Cu")
		(net "M_F_CPU1_SB_DQ<5>")
	)
	(segment
		(start 135.887714 -235.459524)
		(end 135.884158 -235.461556)
		(width 0.088646)
		(layer "In4.Cu")
		(net "M_F_CPU1_SB_DQ<5>")
	)
	(segment
		(start 165.688772 -221.85884)
		(end 165.688772 -221.619572)
		(width 0.18288)
		(layer "In4.Cu")
		(net "M_F_CPU1_SB_DQ<5>")
	)
	(segment
		(start 170.022774 -222.648272)
		(end 170.022774 -223.110806)
		(width 0.18288)
		(layer "In4.Cu")
		(net "M_F_CPU1_SB_DQ<5>")
	)
	(segment
		(start 168.16578 -222.427292)
		(end 168.00576 -222.267272)
		(width 0.18288)
		(layer "In4.Cu")
		(net "M_F_CPU1_SB_DQ<5>")
	)
	(segment
		(start 143.161766 -231.235504)
		(end 141.227302 -233.169968)
		(width 0.18288)
		(layer "In4.Cu")
		(net "M_F_CPU1_SB_DQ<5>")
	)
	(segment
		(start 165.871652 -222.04172)
		(end 165.688772 -221.85884)
		(width 0.18288)
		(layer "In4.Cu")
		(net "M_F_CPU1_SB_DQ<5>")
	)
	(segment
		(start 163.289488 -221.6658)
		(end 163.289488 -221.500192)
		(width 0.18288)
		(layer "In4.Cu")
		(net "M_F_CPU1_SB_DQ<5>")
	)
	(segment
		(start 139.177014 -234.645708)
		(end 139.168124 -234.650788)
		(width 0.088646)
		(layer "In4.Cu")
		(net "M_F_CPU1_SB_DQ<5>")
	)
	(segment
		(start 138.989562 -234.970066)
		(end 138.989562 -234.98556)
		(width 0.088646)
		(layer "In4.Cu")
		(net "M_F_CPU1_SB_DQ<5>")
	)
	(segment
		(start 131.941062 -235.783882)
		(end 131.941062 -235.79201)
		(width 0.088646)
		(layer "In4.Cu")
		(net "M_F_CPU1_SB_DQ<5>")
	)
	(segment
		(start 137.216896 -235.46816)
		(end 137.202164 -235.459524)
		(width 0.088646)
		(layer "In4.Cu")
		(net "M_F_CPU1_SB_DQ<5>")
	)
	(segment
		(start 163.289488 -221.500192)
		(end 163.072318 -221.283022)
		(width 0.18288)
		(layer "In4.Cu")
		(net "M_F_CPU1_SB_DQ<5>")
	)
	(segment
		(start 138.156696 -235.46816)
		(end 138.141964 -235.459524)
		(width 0.088646)
		(layer "In4.Cu")
		(net "M_F_CPU1_SB_DQ<5>")
	)
	(segment
		(start 134.008114 -235.459524)
		(end 134.004558 -235.461556)
		(width 0.088646)
		(layer "In4.Cu")
		(net "M_F_CPU1_SB_DQ<5>")
	)
	(segment
		(start 168.88968 -223.270826)
		(end 168.72966 -223.110806)
		(width 0.18288)
		(layer "In4.Cu")
		(net "M_F_CPU1_SB_DQ<5>")
	)
	(segment
		(start 170.182794 -222.488252)
		(end 170.022774 -222.648272)
		(width 0.18288)
		(layer "In4.Cu")
		(net "M_F_CPU1_SB_DQ<5>")
	)
	(segment
		(start 166.815516 -222.04172)
		(end 165.871652 -222.04172)
		(width 0.18288)
		(layer "In4.Cu")
		(net "M_F_CPU1_SB_DQ<5>")
	)
	(segment
		(start 131.10083 -236.277658)
		(end 130.99542 -236.215936)
		(width 0.088646)
		(layer "In4.Cu")
		(net "M_F_CPU1_SB_DQ<5>")
	)
	(segment
		(start 165.485826 -221.416626)
		(end 164.825426 -221.416626)
		(width 0.18288)
		(layer "In4.Cu")
		(net "M_F_CPU1_SB_DQ<5>")
	)
	(segment
		(start 168.72966 -223.110806)
		(end 168.72966 -222.587312)
		(width 0.18288)
		(layer "In4.Cu")
		(net "M_F_CPU1_SB_DQ<5>")
	)
	(segment
		(start 133.074156 -235.456222)
		(end 133.062472 -235.462826)
		(width 0.088646)
		(layer "In4.Cu")
		(net "M_F_CPU1_SB_DQ<5>")
	)
	(segment
		(start 171.683426 -223.270826)
		(end 170.876214 -223.270826)
		(width 0.18288)
		(layer "In4.Cu")
		(net "M_F_CPU1_SB_DQ<5>")
	)
	(segment
		(start 168.72966 -222.587312)
		(end 168.56964 -222.427292)
		(width 0.18288)
		(layer "In4.Cu")
		(net "M_F_CPU1_SB_DQ<5>")
	)
	(segment
		(start 161.53384 -221.82582)
		(end 161.226246 -221.518226)
		(width 0.18288)
		(layer "In4.Cu")
		(net "M_F_CPU1_SB_DQ<5>")
	)
	(segment
		(start 165.688772 -221.619572)
		(end 165.485826 -221.416626)
		(width 0.18288)
		(layer "In4.Cu")
		(net "M_F_CPU1_SB_DQ<5>")
	)
	(segment
		(start 167.84574 -221.289372)
		(end 167.135556 -221.289372)
		(width 0.18288)
		(layer "In4.Cu")
		(net "M_F_CPU1_SB_DQ<5>")
	)
	(segment
		(start 168.56964 -222.427292)
		(end 168.16578 -222.427292)
		(width 0.18288)
		(layer "In4.Cu")
		(net "M_F_CPU1_SB_DQ<5>")
	)
	(segment
		(start 162.433508 -221.82582)
		(end 161.53384 -221.82582)
		(width 0.18288)
		(layer "In4.Cu")
		(net "M_F_CPU1_SB_DQ<5>")
	)
	(segment
		(start 166.975536 -221.449392)
		(end 166.975536 -221.8817)
		(width 0.18288)
		(layer "In4.Cu")
		(net "M_F_CPU1_SB_DQ<5>")
	)
	(segment
		(start 130.43662 -235.784136)
		(end 130.436366 -235.783882)
		(width 0.088646)
		(layer "In4.Cu")
		(net "M_F_CPU1_SB_DQ<5>")
	)
	(segment
		(start 166.975536 -221.8817)
		(end 166.815516 -222.04172)
		(width 0.18288)
		(layer "In4.Cu")
		(net "M_F_CPU1_SB_DQ<5>")
	)
	(segment
		(start 170.716194 -222.648272)
		(end 170.556174 -222.488252)
		(width 0.18288)
		(layer "In4.Cu")
		(net "M_F_CPU1_SB_DQ<5>")
	)
	(segment
		(start 162.596068 -221.66326)
		(end 162.433508 -221.82582)
		(width 0.18288)
		(layer "In4.Cu")
		(net "M_F_CPU1_SB_DQ<5>")
	)
	(segment
		(start 170.716194 -223.110806)
		(end 170.716194 -222.648272)
		(width 0.18288)
		(layer "In4.Cu")
		(net "M_F_CPU1_SB_DQ<5>")
	)
	(segment
		(start 156.229304 -221.518226)
		(end 146.512026 -231.235504)
		(width 0.18288)
		(layer "In4.Cu")
		(net "M_F_CPU1_SB_DQ<5>")
	)
	(segment
		(start 136.277096 -235.46816)
		(end 136.262364 -235.459524)
		(width 0.088646)
		(layer "In4.Cu")
		(net "M_F_CPU1_SB_DQ<5>")
	)
	(segment
		(start 161.226246 -221.518226)
		(end 156.229304 -221.518226)
		(width 0.18288)
		(layer "In4.Cu")
		(net "M_F_CPU1_SB_DQ<5>")
	)
	(segment
		(start 162.813238 -221.283022)
		(end 162.596068 -221.500192)
		(width 0.18288)
		(layer "In4.Cu")
		(net "M_F_CPU1_SB_DQ<5>")
	)
	(segment
		(start 139.18311 -234.642152)
		(end 139.177014 -234.645708)
		(width 0.088646)
		(layer "In4.Cu")
		(net "M_F_CPU1_SB_DQ<5>")
	)
	(segment
		(start 163.449508 -221.82582)
		(end 163.289488 -221.6658)
		(width 0.18288)
		(layer "In4.Cu")
		(net "M_F_CPU1_SB_DQ<5>")
	)
	(segment
		(start 132.134356 -235.456222)
		(end 132.123434 -235.462318)
		(width 0.088646)
		(layer "In4.Cu")
		(net "M_F_CPU1_SB_DQ<5>")
	)
	(segment
		(start 139.647168 -233.831892)
		(end 139.638278 -233.836972)
		(width 0.088646)
		(layer "In4.Cu")
		(net "M_F_CPU1_SB_DQ<5>")
	)
	(segment
		(start 169.862754 -223.270826)
		(end 168.88968 -223.270826)
		(width 0.18288)
		(layer "In4.Cu")
		(net "M_F_CPU1_SB_DQ<5>")
	)
	(segment
		(start 172.60316 -224.32391)
		(end 172.60316 -224.19056)
		(width 0.18288)
		(layer "In4.Cu")
		(net "M_F_CPU1_SB_DQ<5>")
	)
	(segment
		(start 167.135556 -221.289372)
		(end 166.975536 -221.449392)
		(width 0.18288)
		(layer "In4.Cu")
		(net "M_F_CPU1_SB_DQ<5>")
	)
	(segment
		(start 164.416232 -221.82582)
		(end 163.449508 -221.82582)
		(width 0.18288)
		(layer "In4.Cu")
		(net "M_F_CPU1_SB_DQ<5>")
	)
	(segment
		(start 146.512026 -231.235504)
		(end 143.161766 -231.235504)
		(width 0.18288)
		(layer "In4.Cu")
		(net "M_F_CPU1_SB_DQ<5>")
	)
	(segment
		(start 141.227302 -233.169968)
		(end 140.493496 -233.169968)
		(width 0.18288)
		(layer "In4.Cu")
		(net "M_F_CPU1_SB_DQ<5>")
	)
	(segment
		(start 168.00576 -222.267272)
		(end 168.00576 -221.449392)
		(width 0.18288)
		(layer "In4.Cu")
		(net "M_F_CPU1_SB_DQ<5>")
	)
	(segment
		(start 170.556174 -222.488252)
		(end 170.182794 -222.488252)
		(width 0.18288)
		(layer "In4.Cu")
		(net "M_F_CPU1_SB_DQ<5>")
	)
	(segment
		(start 140.493496 -233.169968)
		(end 140.20546 -233.169968)
		(width 0.088646)
		(layer "In4.Cu")
		(net "M_F_CPU1_SB_DQ<5>")
	)
	(segment
		(start 163.072318 -221.283022)
		(end 162.813238 -221.283022)
		(width 0.18288)
		(layer "In4.Cu")
		(net "M_F_CPU1_SB_DQ<5>")
	)
	(arc
		(start 137.202164 -235.459524)
		(mid 137.014966 -235.409381)
		(end 136.827768 -235.459524)
		(width 0.088646)
		(layer "In4.Cu")
		(net "M_F_CPU1_SB_DQ<5>")
	)
	(arc
		(start 138.141964 -235.459524)
		(mid 137.954766 -235.409381)
		(end 137.767568 -235.459524)
		(width 0.088646)
		(layer "In4.Cu")
		(net "M_F_CPU1_SB_DQ<5>")
	)
	(arc
		(start 134.382764 -235.459524)
		(mid 134.195456 -235.409381)
		(end 134.008114 -235.459524)
		(width 0.088646)
		(layer "In4.Cu")
		(net "M_F_CPU1_SB_DQ<5>")
	)
	(arc
		(start 139.459716 -234.15625)
		(mid 139.385725 -234.435816)
		(end 139.18311 -234.642152)
		(width 0.088646)
		(layer "In4.Cu")
		(net "M_F_CPU1_SB_DQ<5>")
	)
	(arc
		(start 138.707368 -235.459524)
		(mid 138.433169 -235.535359)
		(end 138.156696 -235.46816)
		(width 0.088646)
		(layer "In4.Cu")
		(net "M_F_CPU1_SB_DQ<5>")
	)
	(arc
		(start 140.20546 -233.169968)
		(mid 140.018947 -233.240224)
		(end 139.925298 -233.416094)
		(width 0.088646)
		(layer "In4.Cu")
		(net "M_F_CPU1_SB_DQ<5>")
	)
	(arc
		(start 137.767568 -235.459524)
		(mid 137.493369 -235.535359)
		(end 137.216896 -235.46816)
		(width 0.088646)
		(layer "In4.Cu")
		(net "M_F_CPU1_SB_DQ<5>")
	)
	(arc
		(start 139.925298 -233.416094)
		(mid 139.83468 -233.656388)
		(end 139.647168 -233.831892)
		(width 0.088646)
		(layer "In4.Cu")
		(net "M_F_CPU1_SB_DQ<5>")
	)
	(arc
		(start 135.322564 -235.459524)
		(mid 135.13861 -235.409395)
		(end 134.953756 -235.456222)
		(width 0.088646)
		(layer "In4.Cu")
		(net "M_F_CPU1_SB_DQ<5>")
	)
	(arc
		(start 132.123434 -235.462318)
		(mid 131.989818 -235.599038)
		(end 131.941062 -235.783882)
		(width 0.088646)
		(layer "In4.Cu")
		(net "M_F_CPU1_SB_DQ<5>")
	)
	(arc
		(start 133.062472 -235.462826)
		(mid 132.782367 -235.535268)
		(end 132.503164 -235.459524)
		(width 0.088646)
		(layer "In4.Cu")
		(net "M_F_CPU1_SB_DQ<5>")
	)
	(arc
		(start 136.827768 -235.459524)
		(mid 136.553569 -235.535359)
		(end 136.277096 -235.46816)
		(width 0.088646)
		(layer "In4.Cu")
		(net "M_F_CPU1_SB_DQ<5>")
	)
	(arc
		(start 133.442964 -235.459524)
		(mid 133.25901 -235.409395)
		(end 133.074156 -235.456222)
		(width 0.088646)
		(layer "In4.Cu")
		(net "M_F_CPU1_SB_DQ<5>")
	)
	(arc
		(start 132.503164 -235.459524)
		(mid 132.31921 -235.409395)
		(end 132.134356 -235.456222)
		(width 0.088646)
		(layer "In4.Cu")
		(net "M_F_CPU1_SB_DQ<5>")
	)
	(arc
		(start 131.941062 -235.79201)
		(mid 131.658746 -236.273234)
		(end 131.10083 -236.277658)
		(width 0.088646)
		(layer "In4.Cu")
		(net "M_F_CPU1_SB_DQ<5>")
	)
	(arc
		(start 134.943342 -235.462064)
		(mid 134.662707 -235.535232)
		(end 134.382764 -235.459524)
		(width 0.088646)
		(layer "In4.Cu")
		(net "M_F_CPU1_SB_DQ<5>")
	)
	(arc
		(start 135.884158 -235.461556)
		(mid 135.603074 -235.535293)
		(end 135.322564 -235.459524)
		(width 0.088646)
		(layer "In4.Cu")
		(net "M_F_CPU1_SB_DQ<5>")
	)
	(arc
		(start 136.262364 -235.459524)
		(mid 136.075056 -235.409381)
		(end 135.887714 -235.459524)
		(width 0.088646)
		(layer "In4.Cu")
		(net "M_F_CPU1_SB_DQ<5>")
	)
	(arc
		(start 134.004558 -235.461556)
		(mid 133.723474 -235.535293)
		(end 133.442964 -235.459524)
		(width 0.088646)
		(layer "In4.Cu")
		(net "M_F_CPU1_SB_DQ<5>")
	)
	(arc
		(start 139.638278 -233.836972)
		(mid 139.507364 -233.973332)
		(end 139.459716 -234.15625)
		(width 0.088646)
		(layer "In4.Cu")
		(net "M_F_CPU1_SB_DQ<5>")
	)
	(arc
		(start 139.168124 -234.650788)
		(mid 139.03721 -234.787148)
		(end 138.989562 -234.970066)
		(width 0.088646)
		(layer "In4.Cu")
		(net "M_F_CPU1_SB_DQ<5>")
	)
	(arc
		(start 130.99542 -236.215936)
		(mid 130.702216 -236.017899)
		(end 130.43662 -235.784136)
		(width 0.088646)
		(layer "In4.Cu")
		(net "M_F_CPU1_SB_DQ<5>")
	)
	(arc
		(start 138.989562 -234.98556)
		(mid 138.910192 -235.259294)
		(end 138.707368 -235.459524)
		(width 0.088646)
		(layer "In4.Cu")
		(net "M_F_CPU1_SB_DQ<5>")
	)
	(segment
		(start 179.011326 -225.785426)
		(end 179.004976 -225.791776)
		(width 0.1016)
		(layer "F.Cu")
		(net "M_F_CPU1_SB_DQ<4>")
	)
	(segment
		(start 179.421282 -225.785426)
		(end 179.011326 -225.785426)
		(width 0.20066)
		(layer "F.Cu")
		(net "M_F_CPU1_SB_DQ<4>")
	)
	(segment
		(start 176.145444 -226.465384)
		(end 175.67021 -226.465384)
		(width 0.20066)
		(layer "F.Cu")
		(net "M_F_CPU1_SB_DQ<4>")
	)
	(segment
		(start 175.67021 -226.465384)
		(end 175.421544 -226.216718)
		(width 0.20066)
		(layer "F.Cu")
		(net "M_F_CPU1_SB_DQ<4>")
	)
	(segment
		(start 175.421544 -226.216718)
		(end 173.900846 -226.216718)
		(width 0.20066)
		(layer "F.Cu")
		(net "M_F_CPU1_SB_DQ<4>")
	)
	(segment
		(start 176.796192 -225.791776)
		(end 176.451514 -225.791776)
		(width 0.20066)
		(layer "F.Cu")
		(net "M_F_CPU1_SB_DQ<4>")
	)
	(segment
		(start 129.966212 -237.133638)
		(end 129.966212 -236.597952)
		(width 0.20066)
		(layer "F.Cu")
		(net "M_F_CPU1_SB_DQ<4>")
	)
	(segment
		(start 176.451514 -225.791776)
		(end 176.333404 -225.909886)
		(width 0.20066)
		(layer "F.Cu")
		(net "M_F_CPU1_SB_DQ<4>")
	)
	(segment
		(start 176.333404 -226.277424)
		(end 176.145444 -226.465384)
		(width 0.20066)
		(layer "F.Cu")
		(net "M_F_CPU1_SB_DQ<4>")
	)
	(segment
		(start 176.333404 -225.909886)
		(end 176.333404 -226.277424)
		(width 0.20066)
		(layer "F.Cu")
		(net "M_F_CPU1_SB_DQ<4>")
	)
	(segment
		(start 129.966466 -237.133892)
		(end 129.966212 -237.133638)
		(width 0.20066)
		(layer "F.Cu")
		(net "M_F_CPU1_SB_DQ<4>")
	)
	(segment
		(start 181.444392 -226.216972)
		(end 179.852828 -226.216972)
		(width 0.20066)
		(layer "F.Cu")
		(net "M_F_CPU1_SB_DQ<4>")
	)
	(segment
		(start 176.843182 -225.791776)
		(end 176.796192 -225.791776)
		(width 0.101854)
		(layer "F.Cu")
		(net "M_F_CPU1_SB_DQ<4>")
	)
	(segment
		(start 179.004976 -225.791776)
		(end 176.843182 -225.791776)
		(width 0.1016)
		(layer "F.Cu")
		(net "M_F_CPU1_SB_DQ<4>")
	)
	(segment
		(start 173.900846 -226.216718)
		(end 172.795946 -226.216718)
		(width 0.20066)
		(layer "F.Cu")
		(net "M_F_CPU1_SB_DQ<4>")
	)
	(segment
		(start 179.852828 -226.216972)
		(end 179.421282 -225.785426)
		(width 0.20066)
		(layer "F.Cu")
		(net "M_F_CPU1_SB_DQ<4>")
	)
	(segment
		(start 181.444646 -226.216718)
		(end 181.444392 -226.216972)
		(width 0.20066)
		(layer "F.Cu")
		(net "M_F_CPU1_SB_DQ<4>")
	)
	(segment
		(start 138.237214 -236.273594)
		(end 138.222482 -236.28223)
		(width 0.088646)
		(layer "In4.Cu")
		(net "M_F_CPU1_SB_DQ<4>")
	)
	(segment
		(start 141.40942 -234.396026)
		(end 140.493496 -234.396026)
		(width 0.18288)
		(layer "In4.Cu")
		(net "M_F_CPU1_SB_DQ<4>")
	)
	(segment
		(start 136.357614 -236.273594)
		(end 136.342882 -236.28223)
		(width 0.088646)
		(layer "In4.Cu")
		(net "M_F_CPU1_SB_DQ<4>")
	)
	(segment
		(start 167.73017 -224.109026)
		(end 166.445438 -224.109026)
		(width 0.18288)
		(layer "In4.Cu")
		(net "M_F_CPU1_SB_DQ<4>")
	)
	(segment
		(start 159.265366 -224.171256)
		(end 159.082486 -224.354136)
		(width 0.18288)
		(layer "In4.Cu")
		(net "M_F_CPU1_SB_DQ<4>")
	)
	(segment
		(start 159.448246 -223.242378)
		(end 159.265366 -223.425258)
		(width 0.18288)
		(layer "In4.Cu")
		(net "M_F_CPU1_SB_DQ<4>")
	)
	(segment
		(start 164.393626 -223.53397)
		(end 163.884102 -223.53397)
		(width 0.18288)
		(layer "In4.Cu")
		(net "M_F_CPU1_SB_DQ<4>")
	)
	(segment
		(start 130.660648 -236.897164)
		(end 129.966212 -236.597952)
		(width 0.088646)
		(layer "In4.Cu")
		(net "M_F_CPU1_SB_DQ<4>")
	)
	(segment
		(start 139.647168 -235.459524)
		(end 139.638278 -235.464604)
		(width 0.088646)
		(layer "In4.Cu")
		(net "M_F_CPU1_SB_DQ<4>")
	)
	(segment
		(start 155.952952 -223.242378)
		(end 146.964146 -232.231184)
		(width 0.18288)
		(layer "In4.Cu")
		(net "M_F_CPU1_SB_DQ<4>")
	)
	(segment
		(start 157.00883 -223.425258)
		(end 157.00883 -224.383092)
		(width 0.18288)
		(layer "In4.Cu")
		(net "M_F_CPU1_SB_DQ<4>")
	)
	(segment
		(start 137.297414 -236.273594)
		(end 137.282682 -236.28223)
		(width 0.088646)
		(layer "In4.Cu")
		(net "M_F_CPU1_SB_DQ<4>")
	)
	(segment
		(start 131.099306 -236.918754)
		(end 131.087622 -236.925612)
		(width 0.088646)
		(layer "In4.Cu")
		(net "M_F_CPU1_SB_DQ<4>")
	)
	(segment
		(start 165.518338 -223.181926)
		(end 164.74567 -223.181926)
		(width 0.18288)
		(layer "In4.Cu")
		(net "M_F_CPU1_SB_DQ<4>")
	)
	(segment
		(start 158.389066 -223.242378)
		(end 157.19171 -223.242378)
		(width 0.18288)
		(layer "In4.Cu")
		(net "M_F_CPU1_SB_DQ<4>")
	)
	(segment
		(start 132.457952 -236.416596)
		(end 132.371338 -236.573314)
		(width 0.088646)
		(layer "In4.Cu")
		(net "M_F_CPU1_SB_DQ<4>")
	)
	(segment
		(start 156.31541 -224.383092)
		(end 156.31541 -223.425258)
		(width 0.18288)
		(layer "In4.Cu")
		(net "M_F_CPU1_SB_DQ<4>")
	)
	(segment
		(start 146.964146 -232.231184)
		(end 143.574262 -232.231184)
		(width 0.18288)
		(layer "In4.Cu")
		(net "M_F_CPU1_SB_DQ<4>")
	)
	(segment
		(start 140.493496 -234.396026)
		(end 140.236702 -234.396026)
		(width 0.088646)
		(layer "In4.Cu")
		(net "M_F_CPU1_SB_DQ<4>")
	)
	(segment
		(start 157.19171 -223.242378)
		(end 157.00883 -223.425258)
		(width 0.18288)
		(layer "In4.Cu")
		(net "M_F_CPU1_SB_DQ<4>")
	)
	(segment
		(start 172.795946 -226.216718)
		(end 171.821602 -225.242374)
		(width 0.18288)
		(layer "In4.Cu")
		(net "M_F_CPU1_SB_DQ<4>")
	)
	(segment
		(start 157.00883 -224.383092)
		(end 156.82595 -224.565972)
		(width 0.18288)
		(layer "In4.Cu")
		(net "M_F_CPU1_SB_DQ<4>")
	)
	(segment
		(start 139.459716 -235.783882)
		(end 139.459716 -235.798106)
		(width 0.088646)
		(layer "In4.Cu")
		(net "M_F_CPU1_SB_DQ<4>")
	)
	(segment
		(start 135.79221 -236.273594)
		(end 135.789924 -236.271816)
		(width 0.088646)
		(layer "In4.Cu")
		(net "M_F_CPU1_SB_DQ<4>")
	)
	(segment
		(start 134.86003 -236.277658)
		(end 134.848854 -236.271308)
		(width 0.088646)
		(layer "In4.Cu")
		(net "M_F_CPU1_SB_DQ<4>")
	)
	(segment
		(start 158.571946 -223.425258)
		(end 158.389066 -223.242378)
		(width 0.18288)
		(layer "In4.Cu")
		(net "M_F_CPU1_SB_DQ<4>")
	)
	(segment
		(start 159.082486 -224.354136)
		(end 158.754826 -224.354136)
		(width 0.18288)
		(layer "In4.Cu")
		(net "M_F_CPU1_SB_DQ<4>")
	)
	(segment
		(start 133.912864 -236.27334)
		(end 133.910324 -236.271816)
		(width 0.088646)
		(layer "In4.Cu")
		(net "M_F_CPU1_SB_DQ<4>")
	)
	(segment
		(start 156.31541 -223.425258)
		(end 156.13253 -223.242378)
		(width 0.18288)
		(layer "In4.Cu")
		(net "M_F_CPU1_SB_DQ<4>")
	)
	(segment
		(start 166.445438 -224.109026)
		(end 165.518338 -223.181926)
		(width 0.18288)
		(layer "In4.Cu")
		(net "M_F_CPU1_SB_DQ<4>")
	)
	(segment
		(start 139.929616 -234.703112)
		(end 139.929616 -234.970066)
		(width 0.088646)
		(layer "In4.Cu")
		(net "M_F_CPU1_SB_DQ<4>")
	)
	(segment
		(start 168.573196 -224.952052)
		(end 167.73017 -224.109026)
		(width 0.18288)
		(layer "In4.Cu")
		(net "M_F_CPU1_SB_DQ<4>")
	)
	(segment
		(start 163.59251 -223.242378)
		(end 159.448246 -223.242378)
		(width 0.18288)
		(layer "In4.Cu")
		(net "M_F_CPU1_SB_DQ<4>")
	)
	(segment
		(start 171.546774 -225.242374)
		(end 171.256452 -224.952052)
		(width 0.18288)
		(layer "In4.Cu")
		(net "M_F_CPU1_SB_DQ<4>")
	)
	(segment
		(start 132.98043 -236.277658)
		(end 132.968492 -236.2708)
		(width 0.088646)
		(layer "In4.Cu")
		(net "M_F_CPU1_SB_DQ<4>")
	)
	(segment
		(start 143.574262 -232.231184)
		(end 141.40942 -234.396026)
		(width 0.18288)
		(layer "In4.Cu")
		(net "M_F_CPU1_SB_DQ<4>")
	)
	(segment
		(start 139.177014 -236.273594)
		(end 139.162282 -236.28223)
		(width 0.088646)
		(layer "In4.Cu")
		(net "M_F_CPU1_SB_DQ<4>")
	)
	(segment
		(start 171.821602 -225.242374)
		(end 171.546774 -225.242374)
		(width 0.18288)
		(layer "In4.Cu")
		(net "M_F_CPU1_SB_DQ<4>")
	)
	(segment
		(start 156.49829 -224.565972)
		(end 156.31541 -224.383092)
		(width 0.18288)
		(layer "In4.Cu")
		(net "M_F_CPU1_SB_DQ<4>")
	)
	(segment
		(start 164.74567 -223.181926)
		(end 164.393626 -223.53397)
		(width 0.18288)
		(layer "In4.Cu")
		(net "M_F_CPU1_SB_DQ<4>")
	)
	(segment
		(start 132.040376 -236.918246)
		(end 132.027422 -236.925612)
		(width 0.088646)
		(layer "In4.Cu")
		(net "M_F_CPU1_SB_DQ<4>")
	)
	(segment
		(start 158.571946 -224.171256)
		(end 158.571946 -223.425258)
		(width 0.18288)
		(layer "In4.Cu")
		(net "M_F_CPU1_SB_DQ<4>")
	)
	(segment
		(start 156.13253 -223.242378)
		(end 155.952952 -223.242378)
		(width 0.18288)
		(layer "In4.Cu")
		(net "M_F_CPU1_SB_DQ<4>")
	)
	(segment
		(start 163.884102 -223.53397)
		(end 163.59251 -223.242378)
		(width 0.18288)
		(layer "In4.Cu")
		(net "M_F_CPU1_SB_DQ<4>")
	)
	(segment
		(start 159.265366 -223.425258)
		(end 159.265366 -224.171256)
		(width 0.18288)
		(layer "In4.Cu")
		(net "M_F_CPU1_SB_DQ<4>")
	)
	(segment
		(start 139.653264 -235.455968)
		(end 139.647168 -235.459524)
		(width 0.088646)
		(layer "In4.Cu")
		(net "M_F_CPU1_SB_DQ<4>")
	)
	(segment
		(start 158.754826 -224.354136)
		(end 158.571946 -224.171256)
		(width 0.18288)
		(layer "In4.Cu")
		(net "M_F_CPU1_SB_DQ<4>")
	)
	(segment
		(start 171.256452 -224.952052)
		(end 168.573196 -224.952052)
		(width 0.18288)
		(layer "In4.Cu")
		(net "M_F_CPU1_SB_DQ<4>")
	)
	(segment
		(start 156.82595 -224.565972)
		(end 156.49829 -224.565972)
		(width 0.18288)
		(layer "In4.Cu")
		(net "M_F_CPU1_SB_DQ<4>")
	)
	(segment
		(start 140.236702 -234.396026)
		(end 139.929616 -234.703112)
		(width 0.088646)
		(layer "In4.Cu")
		(net "M_F_CPU1_SB_DQ<4>")
	)
	(arc
		(start 139.459716 -235.798106)
		(mid 139.380497 -236.072791)
		(end 139.177014 -236.273594)
		(width 0.088646)
		(layer "In4.Cu")
		(net "M_F_CPU1_SB_DQ<4>")
	)
	(arc
		(start 138.222482 -236.28223)
		(mid 137.946041 -236.349396)
		(end 137.67181 -236.273594)
		(width 0.088646)
		(layer "In4.Cu")
		(net "M_F_CPU1_SB_DQ<4>")
	)
	(arc
		(start 133.538214 -236.27334)
		(mid 133.259891 -236.349099)
		(end 132.98043 -236.277658)
		(width 0.088646)
		(layer "In4.Cu")
		(net "M_F_CPU1_SB_DQ<4>")
	)
	(arc
		(start 133.910324 -236.271816)
		(mid 133.724075 -236.223171)
		(end 133.538214 -236.27334)
		(width 0.088646)
		(layer "In4.Cu")
		(net "M_F_CPU1_SB_DQ<4>")
	)
	(arc
		(start 139.638278 -235.464604)
		(mid 139.507364 -235.600964)
		(end 139.459716 -235.783882)
		(width 0.088646)
		(layer "In4.Cu")
		(net "M_F_CPU1_SB_DQ<4>")
	)
	(arc
		(start 131.658614 -236.92231)
		(mid 131.379379 -236.855786)
		(end 131.099306 -236.918754)
		(width 0.088646)
		(layer "In4.Cu")
		(net "M_F_CPU1_SB_DQ<4>")
	)
	(arc
		(start 139.929616 -234.970066)
		(mid 139.8557 -235.249568)
		(end 139.653264 -235.455968)
		(width 0.088646)
		(layer "In4.Cu")
		(net "M_F_CPU1_SB_DQ<4>")
	)
	(arc
		(start 137.67181 -236.273594)
		(mid 137.484612 -236.223451)
		(end 137.297414 -236.273594)
		(width 0.088646)
		(layer "In4.Cu")
		(net "M_F_CPU1_SB_DQ<4>")
	)
	(arc
		(start 132.371338 -236.573314)
		(mid 132.289688 -236.699264)
		(end 132.191252 -236.812582)
		(width 0.088646)
		(layer "In4.Cu")
		(net "M_F_CPU1_SB_DQ<4>")
	)
	(arc
		(start 136.73201 -236.273594)
		(mid 136.544812 -236.223451)
		(end 136.357614 -236.273594)
		(width 0.088646)
		(layer "In4.Cu")
		(net "M_F_CPU1_SB_DQ<4>")
	)
	(arc
		(start 135.789924 -236.271816)
		(mid 135.603675 -236.223171)
		(end 135.417814 -236.27334)
		(width 0.088646)
		(layer "In4.Cu")
		(net "M_F_CPU1_SB_DQ<4>")
	)
	(arc
		(start 132.968492 -236.2708)
		(mid 132.682959 -236.237687)
		(end 132.457952 -236.416596)
		(width 0.088646)
		(layer "In4.Cu")
		(net "M_F_CPU1_SB_DQ<4>")
	)
	(arc
		(start 132.027422 -236.925612)
		(mid 131.842567 -236.972562)
		(end 131.658614 -236.92231)
		(width 0.088646)
		(layer "In4.Cu")
		(net "M_F_CPU1_SB_DQ<4>")
	)
	(arc
		(start 131.087622 -236.925612)
		(mid 130.915612 -236.972453)
		(end 130.74142 -236.934502)
		(width 0.088646)
		(layer "In4.Cu")
		(net "M_F_CPU1_SB_DQ<4>")
	)
	(arc
		(start 135.417814 -236.27334)
		(mid 135.139491 -236.349099)
		(end 134.86003 -236.277658)
		(width 0.088646)
		(layer "In4.Cu")
		(net "M_F_CPU1_SB_DQ<4>")
	)
	(arc
		(start 137.282682 -236.28223)
		(mid 137.006241 -236.349396)
		(end 136.73201 -236.273594)
		(width 0.088646)
		(layer "In4.Cu")
		(net "M_F_CPU1_SB_DQ<4>")
	)
	(arc
		(start 134.478014 -236.27334)
		(mid 134.195456 -236.348989)
		(end 133.912864 -236.27334)
		(width 0.088646)
		(layer "In4.Cu")
		(net "M_F_CPU1_SB_DQ<4>")
	)
	(arc
		(start 130.74142 -236.934502)
		(mid 130.701258 -236.915348)
		(end 130.660648 -236.897164)
		(width 0.088646)
		(layer "In4.Cu")
		(net "M_F_CPU1_SB_DQ<4>")
	)
	(arc
		(start 139.162282 -236.28223)
		(mid 138.885841 -236.349396)
		(end 138.61161 -236.273594)
		(width 0.088646)
		(layer "In4.Cu")
		(net "M_F_CPU1_SB_DQ<4>")
	)
	(arc
		(start 132.191252 -236.812582)
		(mid 132.118093 -236.868667)
		(end 132.040376 -236.918246)
		(width 0.088646)
		(layer "In4.Cu")
		(net "M_F_CPU1_SB_DQ<4>")
	)
	(arc
		(start 134.848854 -236.271308)
		(mid 134.663164 -236.22323)
		(end 134.478014 -236.27334)
		(width 0.088646)
		(layer "In4.Cu")
		(net "M_F_CPU1_SB_DQ<4>")
	)
	(arc
		(start 136.342882 -236.28223)
		(mid 136.066441 -236.349396)
		(end 135.79221 -236.273594)
		(width 0.088646)
		(layer "In4.Cu")
		(net "M_F_CPU1_SB_DQ<4>")
	)
	(arc
		(start 138.61161 -236.273594)
		(mid 138.424412 -236.223451)
		(end 138.237214 -236.273594)
		(width 0.088646)
		(layer "In4.Cu")
		(net "M_F_CPU1_SB_DQ<4>")
	)
	(segment
		(start 178.000914 -229.616762)
		(end 179.699158 -229.616762)
		(width 0.20066)
		(layer "F.Cu")
		(net "M_F_CPU1_SB_DQ<3>")
	)
	(segment
		(start 183.136286 -230.053896)
		(end 183.340248 -229.849934)
		(width 0.20066)
		(layer "F.Cu")
		(net "M_F_CPU1_SB_DQ<3>")
	)
	(segment
		(start 183.340248 -229.598982)
		(end 183.574436 -229.364794)
		(width 0.20066)
		(layer "F.Cu")
		(net "M_F_CPU1_SB_DQ<3>")
	)
	(segment
		(start 183.958484 -229.364794)
		(end 184.210452 -229.616762)
		(width 0.20066)
		(layer "F.Cu")
		(net "M_F_CPU1_SB_DQ<3>")
	)
	(segment
		(start 180.131212 -230.048816)
		(end 180.423058 -230.048816)
		(width 0.20066)
		(layer "F.Cu")
		(net "M_F_CPU1_SB_DQ<3>")
	)
	(segment
		(start 131.846066 -238.761524)
		(end 131.845812 -238.76127)
		(width 0.20066)
		(layer "F.Cu")
		(net "M_F_CPU1_SB_DQ<3>")
	)
	(segment
		(start 182.455058 -230.053896)
		(end 183.136286 -230.053896)
		(width 0.20066)
		(layer "F.Cu")
		(net "M_F_CPU1_SB_DQ<3>")
	)
	(segment
		(start 180.427884 -230.048816)
		(end 180.434996 -230.041704)
		(width 0.1016)
		(layer "F.Cu")
		(net "M_F_CPU1_SB_DQ<3>")
	)
	(segment
		(start 180.423058 -230.048816)
		(end 180.427884 -230.048816)
		(width 0.101854)
		(layer "F.Cu")
		(net "M_F_CPU1_SB_DQ<3>")
	)
	(segment
		(start 184.210452 -229.616762)
		(end 185.544714 -229.616762)
		(width 0.20066)
		(layer "F.Cu")
		(net "M_F_CPU1_SB_DQ<3>")
	)
	(segment
		(start 180.434996 -230.041704)
		(end 182.442866 -230.041704)
		(width 0.1016)
		(layer "F.Cu")
		(net "M_F_CPU1_SB_DQ<3>")
	)
	(segment
		(start 183.574436 -229.364794)
		(end 183.958484 -229.364794)
		(width 0.20066)
		(layer "F.Cu")
		(net "M_F_CPU1_SB_DQ<3>")
	)
	(segment
		(start 179.699158 -229.616762)
		(end 180.131212 -230.048816)
		(width 0.20066)
		(layer "F.Cu")
		(net "M_F_CPU1_SB_DQ<3>")
	)
	(segment
		(start 183.340248 -229.849934)
		(end 183.340248 -229.598982)
		(width 0.20066)
		(layer "F.Cu")
		(net "M_F_CPU1_SB_DQ<3>")
	)
	(segment
		(start 131.845812 -238.76127)
		(end 131.845812 -238.225584)
		(width 0.20066)
		(layer "F.Cu")
		(net "M_F_CPU1_SB_DQ<3>")
	)
	(segment
		(start 176.896014 -229.616762)
		(end 178.000914 -229.616762)
		(width 0.20066)
		(layer "F.Cu")
		(net "M_F_CPU1_SB_DQ<3>")
	)
	(segment
		(start 182.442866 -230.041704)
		(end 182.455058 -230.053896)
		(width 0.1016)
		(layer "F.Cu")
		(net "M_F_CPU1_SB_DQ<3>")
	)
	(segment
		(start 167.626284 -228.624384)
		(end 166.224204 -228.624384)
		(width 0.18288)
		(layer "In4.Cu")
		(net "M_F_CPU1_SB_DQ<3>")
	)
	(segment
		(start 164.911786 -228.325426)
		(end 164.218366 -228.325426)
		(width 0.18288)
		(layer "In4.Cu")
		(net "M_F_CPU1_SB_DQ<3>")
	)
	(segment
		(start 165.071806 -228.165406)
		(end 164.911786 -228.325426)
		(width 0.18288)
		(layer "In4.Cu")
		(net "M_F_CPU1_SB_DQ<3>")
	)
	(segment
		(start 155.502864 -229.011226)
		(end 155.319984 -229.194106)
		(width 0.18288)
		(layer "In4.Cu")
		(net "M_F_CPU1_SB_DQ<3>")
	)
	(segment
		(start 148.965158 -234.344464)
		(end 144.498822 -234.344464)
		(width 0.18288)
		(layer "In4.Cu")
		(net "M_F_CPU1_SB_DQ<3>")
	)
	(segment
		(start 174.420276 -229.192074)
		(end 174.237396 -229.374954)
		(width 0.18288)
		(layer "In4.Cu")
		(net "M_F_CPU1_SB_DQ<3>")
	)
	(segment
		(start 156.379164 -229.194106)
		(end 156.196284 -229.011226)
		(width 0.18288)
		(layer "In4.Cu")
		(net "M_F_CPU1_SB_DQ<3>")
	)
	(segment
		(start 165.605206 -227.537772)
		(end 165.231826 -227.537772)
		(width 0.18288)
		(layer "In4.Cu")
		(net "M_F_CPU1_SB_DQ<3>")
	)
	(segment
		(start 165.231826 -227.537772)
		(end 165.071806 -227.697792)
		(width 0.18288)
		(layer "In4.Cu")
		(net "M_F_CPU1_SB_DQ<3>")
	)
	(segment
		(start 155.319984 -229.194106)
		(end 154.115516 -229.194106)
		(width 0.18288)
		(layer "In4.Cu")
		(net "M_F_CPU1_SB_DQ<3>")
	)
	(segment
		(start 173.361096 -229.192074)
		(end 168.193974 -229.192074)
		(width 0.18288)
		(layer "In4.Cu")
		(net "M_F_CPU1_SB_DQ<3>")
	)
	(segment
		(start 134.852664 -238.549942)
		(end 134.848854 -238.552228)
		(width 0.088646)
		(layer "In4.Cu")
		(net "M_F_CPU1_SB_DQ<3>")
	)
	(segment
		(start 173.726856 -229.720902)
		(end 173.543976 -229.538022)
		(width 0.18288)
		(layer "In4.Cu")
		(net "M_F_CPU1_SB_DQ<3>")
	)
	(segment
		(start 132.973064 -238.549942)
		(end 132.968492 -238.552736)
		(width 0.088646)
		(layer "In4.Cu")
		(net "M_F_CPU1_SB_DQ<3>")
	)
	(segment
		(start 133.912864 -238.549942)
		(end 133.910324 -238.551466)
		(width 0.088646)
		(layer "In4.Cu")
		(net "M_F_CPU1_SB_DQ<3>")
	)
	(segment
		(start 165.765226 -227.697792)
		(end 165.605206 -227.537772)
		(width 0.18288)
		(layer "In4.Cu")
		(net "M_F_CPU1_SB_DQ<3>")
	)
	(segment
		(start 163.364926 -228.165406)
		(end 163.188396 -228.341936)
		(width 0.18288)
		(layer "In4.Cu")
		(net "M_F_CPU1_SB_DQ<3>")
	)
	(segment
		(start 144.498822 -234.344464)
		(end 142.061184 -236.782102)
		(width 0.18288)
		(layer "In4.Cu")
		(net "M_F_CPU1_SB_DQ<3>")
	)
	(segment
		(start 155.502864 -228.487478)
		(end 155.502864 -229.011226)
		(width 0.18288)
		(layer "In4.Cu")
		(net "M_F_CPU1_SB_DQ<3>")
	)
	(segment
		(start 174.237396 -229.374954)
		(end 174.237396 -229.538022)
		(width 0.18288)
		(layer "In4.Cu")
		(net "M_F_CPU1_SB_DQ<3>")
	)
	(segment
		(start 165.071806 -227.697792)
		(end 165.071806 -228.165406)
		(width 0.18288)
		(layer "In4.Cu")
		(net "M_F_CPU1_SB_DQ<3>")
	)
	(segment
		(start 140.890752 -236.782102)
		(end 139.282932 -238.389922)
		(width 0.088646)
		(layer "In4.Cu")
		(net "M_F_CPU1_SB_DQ<3>")
	)
	(segment
		(start 156.196284 -228.487478)
		(end 156.013404 -228.304598)
		(width 0.18288)
		(layer "In4.Cu")
		(net "M_F_CPU1_SB_DQ<3>")
	)
	(segment
		(start 174.237396 -229.538022)
		(end 174.054516 -229.720902)
		(width 0.18288)
		(layer "In4.Cu")
		(net "M_F_CPU1_SB_DQ<3>")
	)
	(segment
		(start 164.218366 -228.325426)
		(end 164.058346 -228.165406)
		(width 0.18288)
		(layer "In4.Cu")
		(net "M_F_CPU1_SB_DQ<3>")
	)
	(segment
		(start 157.88513 -229.194106)
		(end 156.379164 -229.194106)
		(width 0.18288)
		(layer "In4.Cu")
		(net "M_F_CPU1_SB_DQ<3>")
	)
	(segment
		(start 160.811972 -227.588826)
		(end 159.49041 -227.588826)
		(width 0.18288)
		(layer "In4.Cu")
		(net "M_F_CPU1_SB_DQ<3>")
	)
	(segment
		(start 168.193974 -229.192074)
		(end 167.626284 -228.624384)
		(width 0.18288)
		(layer "In4.Cu")
		(net "M_F_CPU1_SB_DQ<3>")
	)
	(segment
		(start 142.061184 -236.782102)
		(end 141.001496 -236.782102)
		(width 0.18288)
		(layer "In4.Cu")
		(net "M_F_CPU1_SB_DQ<3>")
	)
	(segment
		(start 155.685744 -228.304598)
		(end 155.502864 -228.487478)
		(width 0.18288)
		(layer "In4.Cu")
		(net "M_F_CPU1_SB_DQ<3>")
	)
	(segment
		(start 165.765226 -228.165406)
		(end 165.765226 -227.697792)
		(width 0.18288)
		(layer "In4.Cu")
		(net "M_F_CPU1_SB_DQ<3>")
	)
	(segment
		(start 159.49041 -227.588826)
		(end 157.88513 -229.194106)
		(width 0.18288)
		(layer "In4.Cu")
		(net "M_F_CPU1_SB_DQ<3>")
	)
	(segment
		(start 173.543976 -229.538022)
		(end 173.543976 -229.374954)
		(width 0.18288)
		(layer "In4.Cu")
		(net "M_F_CPU1_SB_DQ<3>")
	)
	(segment
		(start 161.565082 -228.341936)
		(end 160.811972 -227.588826)
		(width 0.18288)
		(layer "In4.Cu")
		(net "M_F_CPU1_SB_DQ<3>")
	)
	(segment
		(start 175.515016 -229.192074)
		(end 174.420276 -229.192074)
		(width 0.18288)
		(layer "In4.Cu")
		(net "M_F_CPU1_SB_DQ<3>")
	)
	(segment
		(start 141.001496 -236.782102)
		(end 140.890752 -236.782102)
		(width 0.088646)
		(layer "In4.Cu")
		(net "M_F_CPU1_SB_DQ<3>")
	)
	(segment
		(start 132.98043 -238.545624)
		(end 132.973064 -238.549942)
		(width 0.088646)
		(layer "In4.Cu")
		(net "M_F_CPU1_SB_DQ<3>")
	)
	(segment
		(start 175.939704 -229.616762)
		(end 175.515016 -229.192074)
		(width 0.18288)
		(layer "In4.Cu")
		(net "M_F_CPU1_SB_DQ<3>")
	)
	(segment
		(start 174.054516 -229.720902)
		(end 173.726856 -229.720902)
		(width 0.18288)
		(layer "In4.Cu")
		(net "M_F_CPU1_SB_DQ<3>")
	)
	(segment
		(start 156.196284 -229.011226)
		(end 156.196284 -228.487478)
		(width 0.18288)
		(layer "In4.Cu")
		(net "M_F_CPU1_SB_DQ<3>")
	)
	(segment
		(start 164.058346 -227.636832)
		(end 163.898326 -227.476812)
		(width 0.18288)
		(layer "In4.Cu")
		(net "M_F_CPU1_SB_DQ<3>")
	)
	(segment
		(start 132.598414 -238.549942)
		(end 132.201412 -238.320834)
		(width 0.088646)
		(layer "In4.Cu")
		(net "M_F_CPU1_SB_DQ<3>")
	)
	(segment
		(start 163.364926 -227.636832)
		(end 163.364926 -228.165406)
		(width 0.18288)
		(layer "In4.Cu")
		(net "M_F_CPU1_SB_DQ<3>")
	)
	(segment
		(start 166.224204 -228.624384)
		(end 165.765226 -228.165406)
		(width 0.18288)
		(layer "In4.Cu")
		(net "M_F_CPU1_SB_DQ<3>")
	)
	(segment
		(start 176.896014 -229.616762)
		(end 175.939704 -229.616762)
		(width 0.18288)
		(layer "In4.Cu")
		(net "M_F_CPU1_SB_DQ<3>")
	)
	(segment
		(start 163.188396 -228.341936)
		(end 161.565082 -228.341936)
		(width 0.18288)
		(layer "In4.Cu")
		(net "M_F_CPU1_SB_DQ<3>")
	)
	(segment
		(start 163.524946 -227.476812)
		(end 163.364926 -227.636832)
		(width 0.18288)
		(layer "In4.Cu")
		(net "M_F_CPU1_SB_DQ<3>")
	)
	(segment
		(start 139.282932 -238.389922)
		(end 139.007596 -238.48568)
		(width 0.088646)
		(layer "In4.Cu")
		(net "M_F_CPU1_SB_DQ<3>")
	)
	(segment
		(start 164.058346 -228.165406)
		(end 164.058346 -227.636832)
		(width 0.18288)
		(layer "In4.Cu")
		(net "M_F_CPU1_SB_DQ<3>")
	)
	(segment
		(start 163.898326 -227.476812)
		(end 163.524946 -227.476812)
		(width 0.18288)
		(layer "In4.Cu")
		(net "M_F_CPU1_SB_DQ<3>")
	)
	(segment
		(start 173.543976 -229.374954)
		(end 173.361096 -229.192074)
		(width 0.18288)
		(layer "In4.Cu")
		(net "M_F_CPU1_SB_DQ<3>")
	)
	(segment
		(start 135.792464 -238.549942)
		(end 135.789924 -238.551466)
		(width 0.088646)
		(layer "In4.Cu")
		(net "M_F_CPU1_SB_DQ<3>")
	)
	(segment
		(start 134.86003 -238.545624)
		(end 134.852664 -238.549942)
		(width 0.088646)
		(layer "In4.Cu")
		(net "M_F_CPU1_SB_DQ<3>")
	)
	(segment
		(start 154.115516 -229.194106)
		(end 148.965158 -234.344464)
		(width 0.18288)
		(layer "In4.Cu")
		(net "M_F_CPU1_SB_DQ<3>")
	)
	(segment
		(start 156.013404 -228.304598)
		(end 155.685744 -228.304598)
		(width 0.18288)
		(layer "In4.Cu")
		(net "M_F_CPU1_SB_DQ<3>")
	)
	(arc
		(start 134.478014 -238.549942)
		(mid 134.195456 -238.474293)
		(end 133.912864 -238.549942)
		(width 0.088646)
		(layer "In4.Cu")
		(net "M_F_CPU1_SB_DQ<3>")
	)
	(arc
		(start 132.201412 -238.320834)
		(mid 132.029875 -238.249838)
		(end 131.845812 -238.225584)
		(width 0.088646)
		(layer "In4.Cu")
		(net "M_F_CPU1_SB_DQ<3>")
	)
	(arc
		(start 132.968492 -238.552736)
		(mid 132.783078 -238.600248)
		(end 132.598414 -238.549942)
		(width 0.088646)
		(layer "In4.Cu")
		(net "M_F_CPU1_SB_DQ<3>")
	)
	(arc
		(start 135.417814 -238.549942)
		(mid 135.139491 -238.474183)
		(end 134.86003 -238.545624)
		(width 0.088646)
		(layer "In4.Cu")
		(net "M_F_CPU1_SB_DQ<3>")
	)
	(arc
		(start 133.538214 -238.549942)
		(mid 133.259891 -238.474183)
		(end 132.98043 -238.545624)
		(width 0.088646)
		(layer "In4.Cu")
		(net "M_F_CPU1_SB_DQ<3>")
	)
	(arc
		(start 136.732264 -238.549942)
		(mid 136.545066 -238.600085)
		(end 136.357868 -238.549942)
		(width 0.088646)
		(layer "In4.Cu")
		(net "M_F_CPU1_SB_DQ<3>")
	)
	(arc
		(start 136.357868 -238.549942)
		(mid 136.075166 -238.474166)
		(end 135.792464 -238.549942)
		(width 0.088646)
		(layer "In4.Cu")
		(net "M_F_CPU1_SB_DQ<3>")
	)
	(arc
		(start 138.237468 -238.549942)
		(mid 137.954766 -238.474166)
		(end 137.672064 -238.549942)
		(width 0.088646)
		(layer "In4.Cu")
		(net "M_F_CPU1_SB_DQ<3>")
	)
	(arc
		(start 139.007596 -238.48568)
		(mid 138.803826 -238.481501)
		(end 138.611864 -238.549942)
		(width 0.088646)
		(layer "In4.Cu")
		(net "M_F_CPU1_SB_DQ<3>")
	)
	(arc
		(start 137.297668 -238.549942)
		(mid 137.014966 -238.474166)
		(end 136.732264 -238.549942)
		(width 0.088646)
		(layer "In4.Cu")
		(net "M_F_CPU1_SB_DQ<3>")
	)
	(arc
		(start 134.848854 -238.552228)
		(mid 134.663135 -238.60018)
		(end 134.478014 -238.549942)
		(width 0.088646)
		(layer "In4.Cu")
		(net "M_F_CPU1_SB_DQ<3>")
	)
	(arc
		(start 133.910324 -238.551466)
		(mid 133.724075 -238.600144)
		(end 133.538214 -238.549942)
		(width 0.088646)
		(layer "In4.Cu")
		(net "M_F_CPU1_SB_DQ<3>")
	)
	(arc
		(start 138.611864 -238.549942)
		(mid 138.424666 -238.600085)
		(end 138.237468 -238.549942)
		(width 0.088646)
		(layer "In4.Cu")
		(net "M_F_CPU1_SB_DQ<3>")
	)
	(arc
		(start 135.789924 -238.551466)
		(mid 135.603675 -238.600144)
		(end 135.417814 -238.549942)
		(width 0.088646)
		(layer "In4.Cu")
		(net "M_F_CPU1_SB_DQ<3>")
	)
	(arc
		(start 137.672064 -238.549942)
		(mid 137.484866 -238.600085)
		(end 137.297668 -238.549942)
		(width 0.088646)
		(layer "In4.Cu")
		(net "M_F_CPU1_SB_DQ<3>")
	)
	(segment
		(start 180.423058 -196.04863)
		(end 180.427884 -196.04863)
		(width 0.101854)
		(layer "F.Cu")
		(net "M_F_CPU1_SB_DQ<31>")
	)
	(segment
		(start 179.699158 -195.616576)
		(end 180.131212 -196.04863)
		(width 0.20066)
		(layer "F.Cu")
		(net "M_F_CPU1_SB_DQ<31>")
	)
	(segment
		(start 182.455058 -196.05371)
		(end 183.136286 -196.05371)
		(width 0.20066)
		(layer "F.Cu")
		(net "M_F_CPU1_SB_DQ<31>")
	)
	(segment
		(start 183.340248 -195.598796)
		(end 183.574436 -195.364608)
		(width 0.20066)
		(layer "F.Cu")
		(net "M_F_CPU1_SB_DQ<31>")
	)
	(segment
		(start 129.026412 -227.36683)
		(end 129.026412 -226.831144)
		(width 0.20066)
		(layer "F.Cu")
		(net "M_F_CPU1_SB_DQ<31>")
	)
	(segment
		(start 178.000914 -195.616576)
		(end 179.699158 -195.616576)
		(width 0.20066)
		(layer "F.Cu")
		(net "M_F_CPU1_SB_DQ<31>")
	)
	(segment
		(start 183.958484 -195.364608)
		(end 184.210452 -195.616576)
		(width 0.20066)
		(layer "F.Cu")
		(net "M_F_CPU1_SB_DQ<31>")
	)
	(segment
		(start 182.442866 -196.041518)
		(end 182.455058 -196.05371)
		(width 0.1016)
		(layer "F.Cu")
		(net "M_F_CPU1_SB_DQ<31>")
	)
	(segment
		(start 129.026666 -227.367084)
		(end 129.026412 -227.36683)
		(width 0.20066)
		(layer "F.Cu")
		(net "M_F_CPU1_SB_DQ<31>")
	)
	(segment
		(start 184.210452 -195.616576)
		(end 185.544714 -195.616576)
		(width 0.20066)
		(layer "F.Cu")
		(net "M_F_CPU1_SB_DQ<31>")
	)
	(segment
		(start 180.434996 -196.041518)
		(end 182.442866 -196.041518)
		(width 0.1016)
		(layer "F.Cu")
		(net "M_F_CPU1_SB_DQ<31>")
	)
	(segment
		(start 180.427884 -196.04863)
		(end 180.434996 -196.041518)
		(width 0.1016)
		(layer "F.Cu")
		(net "M_F_CPU1_SB_DQ<31>")
	)
	(segment
		(start 183.574436 -195.364608)
		(end 183.958484 -195.364608)
		(width 0.20066)
		(layer "F.Cu")
		(net "M_F_CPU1_SB_DQ<31>")
	)
	(segment
		(start 183.340248 -195.849748)
		(end 183.340248 -195.598796)
		(width 0.20066)
		(layer "F.Cu")
		(net "M_F_CPU1_SB_DQ<31>")
	)
	(segment
		(start 180.131212 -196.04863)
		(end 180.423058 -196.04863)
		(width 0.20066)
		(layer "F.Cu")
		(net "M_F_CPU1_SB_DQ<31>")
	)
	(segment
		(start 176.896014 -195.616576)
		(end 178.000914 -195.616576)
		(width 0.20066)
		(layer "F.Cu")
		(net "M_F_CPU1_SB_DQ<31>")
	)
	(segment
		(start 183.136286 -196.05371)
		(end 183.340248 -195.849748)
		(width 0.20066)
		(layer "F.Cu")
		(net "M_F_CPU1_SB_DQ<31>")
	)
	(segment
		(start 147.673568 -210.211162)
		(end 147.673568 -210.212178)
		(width 0.18288)
		(layer "In4.Cu")
		(net "M_F_CPU1_SB_DQ<31>")
	)
	(segment
		(start 130.811016 -222.746062)
		(end 130.811016 -222.761556)
		(width 0.088646)
		(layer "In4.Cu")
		(net "M_F_CPU1_SB_DQ<31>")
	)
	(segment
		(start 162.383978 -195.135754)
		(end 160.073594 -196.026786)
		(width 0.18288)
		(layer "In4.Cu")
		(net "M_F_CPU1_SB_DQ<31>")
	)
	(segment
		(start 129.404872 -226.765612)
		(end 129.33934 -226.831144)
		(width 0.088646)
		(layer "In4.Cu")
		(net "M_F_CPU1_SB_DQ<31>")
	)
	(segment
		(start 132.690616 -221.115382)
		(end 132.690616 -221.133924)
		(width 0.088646)
		(layer "In4.Cu")
		(net "M_F_CPU1_SB_DQ<31>")
	)
	(segment
		(start 139.422124 -218.093544)
		(end 139.16914 -218.346528)
		(width 0.088646)
		(layer "In4.Cu")
		(net "M_F_CPU1_SB_DQ<31>")
	)
	(segment
		(start 132.981954 -220.639132)
		(end 132.973064 -220.644212)
		(width 0.088646)
		(layer "In4.Cu")
		(net "M_F_CPU1_SB_DQ<31>")
	)
	(segment
		(start 157.632654 -196.266054)
		(end 157.011878 -196.524118)
		(width 0.18288)
		(layer "In4.Cu")
		(net "M_F_CPU1_SB_DQ<31>")
	)
	(segment
		(start 132.512054 -221.453202)
		(end 132.503164 -221.458282)
		(width 0.088646)
		(layer "In4.Cu")
		(net "M_F_CPU1_SB_DQ<31>")
	)
	(segment
		(start 130.340862 -223.568006)
		(end 130.340862 -223.575626)
		(width 0.088646)
		(layer "In4.Cu")
		(net "M_F_CPU1_SB_DQ<31>")
	)
	(segment
		(start 132.50037 -221.459806)
		(end 132.497068 -221.461838)
		(width 0.088646)
		(layer "In4.Cu")
		(net "M_F_CPU1_SB_DQ<31>")
	)
	(segment
		(start 129.692654 -226.336606)
		(end 129.683764 -226.341686)
		(width 0.088646)
		(layer "In4.Cu")
		(net "M_F_CPU1_SB_DQ<31>")
	)
	(segment
		(start 137.686796 -219.007944)
		(end 137.672064 -219.01658)
		(width 0.088646)
		(layer "In4.Cu")
		(net "M_F_CPU1_SB_DQ<31>")
	)
	(segment
		(start 163.789106 -194.38493)
		(end 162.383978 -195.135754)
		(width 0.18288)
		(layer "In4.Cu")
		(net "M_F_CPU1_SB_DQ<31>")
	)
	(segment
		(start 130.1623 -223.894904)
		(end 130.15341 -223.899984)
		(width 0.088646)
		(layer "In4.Cu")
		(net "M_F_CPU1_SB_DQ<31>")
	)
	(segment
		(start 130.15341 -224.8789)
		(end 130.1623 -224.88398)
		(width 0.088646)
		(layer "In4.Cu")
		(net "M_F_CPU1_SB_DQ<31>")
	)
	(segment
		(start 170.175682 -194.531488)
		(end 169.441622 -194.347592)
		(width 0.18288)
		(layer "In4.Cu")
		(net "M_F_CPU1_SB_DQ<31>")
	)
	(segment
		(start 164.286184 -194.26047)
		(end 163.789106 -194.38493)
		(width 0.18288)
		(layer "In4.Cu")
		(net "M_F_CPU1_SB_DQ<31>")
	)
	(segment
		(start 138.90498 -218.741752)
		(end 138.689588 -218.957144)
		(width 0.088646)
		(layer "In4.Cu")
		(net "M_F_CPU1_SB_DQ<31>")
	)
	(segment
		(start 136.746996 -219.007944)
		(end 136.732264 -219.01658)
		(width 0.088646)
		(layer "In4.Cu")
		(net "M_F_CPU1_SB_DQ<31>")
	)
	(segment
		(start 149.444964 -205.935326)
		(end 147.673568 -210.211162)
		(width 0.18288)
		(layer "In4.Cu")
		(net "M_F_CPU1_SB_DQ<31>")
	)
	(segment
		(start 176.896014 -195.616576)
		(end 175.687736 -195.273676)
		(width 0.18288)
		(layer "In4.Cu")
		(net "M_F_CPU1_SB_DQ<31>")
	)
	(segment
		(start 168.734232 -194.26047)
		(end 164.286184 -194.26047)
		(width 0.18288)
		(layer "In4.Cu")
		(net "M_F_CPU1_SB_DQ<31>")
	)
	(segment
		(start 129.683764 -226.341686)
		(end 129.677668 -226.345242)
		(width 0.088646)
		(layer "In4.Cu")
		(net "M_F_CPU1_SB_DQ<31>")
	)
	(segment
		(start 158.632906 -196.204586)
		(end 157.632654 -196.266054)
		(width 0.18288)
		(layer "In4.Cu")
		(net "M_F_CPU1_SB_DQ<31>")
	)
	(segment
		(start 129.33934 -226.831144)
		(end 129.026412 -226.831144)
		(width 0.088646)
		(layer "In4.Cu")
		(net "M_F_CPU1_SB_DQ<31>")
	)
	(segment
		(start 132.0419 -222.267018)
		(end 132.03301 -222.272098)
		(width 0.088646)
		(layer "In4.Cu")
		(net "M_F_CPU1_SB_DQ<31>")
	)
	(segment
		(start 134.570216 -219.496132)
		(end 134.570216 -219.506038)
		(width 0.088646)
		(layer "In4.Cu")
		(net "M_F_CPU1_SB_DQ<31>")
	)
	(segment
		(start 131.658614 -222.272098)
		(end 131.643882 -222.263462)
		(width 0.088646)
		(layer "In4.Cu")
		(net "M_F_CPU1_SB_DQ<31>")
	)
	(segment
		(start 169.441622 -194.347592)
		(end 168.734232 -194.26047)
		(width 0.18288)
		(layer "In4.Cu")
		(net "M_F_CPU1_SB_DQ<31>")
	)
	(segment
		(start 171.409868 -195.190872)
		(end 170.175682 -194.531488)
		(width 0.18288)
		(layer "In4.Cu")
		(net "M_F_CPU1_SB_DQ<31>")
	)
	(segment
		(start 175.687736 -195.273676)
		(end 175.091852 -195.190872)
		(width 0.18288)
		(layer "In4.Cu")
		(net "M_F_CPU1_SB_DQ<31>")
	)
	(segment
		(start 130.1623 -225.522536)
		(end 130.15341 -225.527616)
		(width 0.088646)
		(layer "In4.Cu")
		(net "M_F_CPU1_SB_DQ<31>")
	)
	(segment
		(start 175.091852 -195.190872)
		(end 171.409868 -195.190872)
		(width 0.18288)
		(layer "In4.Cu")
		(net "M_F_CPU1_SB_DQ<31>")
	)
	(segment
		(start 139.553188 -218.093544)
		(end 139.422124 -218.093544)
		(width 0.088646)
		(layer "In4.Cu")
		(net "M_F_CPU1_SB_DQ<31>")
	)
	(segment
		(start 147.673568 -210.212178)
		(end 139.792202 -218.093544)
		(width 0.18288)
		(layer "In4.Cu")
		(net "M_F_CPU1_SB_DQ<31>")
	)
	(segment
		(start 132.503164 -221.458282)
		(end 132.50037 -221.459806)
		(width 0.088646)
		(layer "In4.Cu")
		(net "M_F_CPU1_SB_DQ<31>")
	)
	(segment
		(start 153.114756 -200.442322)
		(end 149.444964 -205.935326)
		(width 0.18288)
		(layer "In4.Cu")
		(net "M_F_CPU1_SB_DQ<31>")
	)
	(segment
		(start 129.871216 -224.373948)
		(end 129.871216 -224.404936)
		(width 0.088646)
		(layer "In4.Cu")
		(net "M_F_CPU1_SB_DQ<31>")
	)
	(segment
		(start 139.792202 -218.093544)
		(end 139.553188 -218.093544)
		(width 0.18288)
		(layer "In4.Cu")
		(net "M_F_CPU1_SB_DQ<31>")
	)
	(segment
		(start 133.160516 -220.309948)
		(end 133.160516 -220.319854)
		(width 0.088646)
		(layer "In4.Cu")
		(net "M_F_CPU1_SB_DQ<31>")
	)
	(segment
		(start 134.391654 -219.825316)
		(end 134.382764 -219.830396)
		(width 0.088646)
		(layer "In4.Cu")
		(net "M_F_CPU1_SB_DQ<31>")
	)
	(segment
		(start 160.073594 -196.026786)
		(end 158.632906 -196.204586)
		(width 0.18288)
		(layer "In4.Cu")
		(net "M_F_CPU1_SB_DQ<31>")
	)
	(segment
		(start 157.011878 -196.524118)
		(end 153.114756 -200.442322)
		(width 0.18288)
		(layer "In4.Cu")
		(net "M_F_CPU1_SB_DQ<31>")
	)
	(segment
		(start 139.16914 -218.346528)
		(end 138.90498 -218.741752)
		(width 0.088646)
		(layer "In4.Cu")
		(net "M_F_CPU1_SB_DQ<31>")
	)
	(segment
		(start 130.632454 -223.080834)
		(end 130.623564 -223.085914)
		(width 0.088646)
		(layer "In4.Cu")
		(net "M_F_CPU1_SB_DQ<31>")
	)
	(segment
		(start 129.871216 -225.99523)
		(end 129.871216 -226.017328)
		(width 0.088646)
		(layer "In4.Cu")
		(net "M_F_CPU1_SB_DQ<31>")
	)
	(arc
		(start 130.1623 -224.88398)
		(mid 130.340897 -225.203258)
		(end 130.1623 -225.522536)
		(width 0.088646)
		(layer "In4.Cu")
		(net "M_F_CPU1_SB_DQ<31>")
	)
	(arc
		(start 130.623564 -223.085914)
		(mid 130.418492 -223.289593)
		(end 130.340862 -223.568006)
		(width 0.088646)
		(layer "In4.Cu")
		(net "M_F_CPU1_SB_DQ<31>")
	)
	(arc
		(start 132.497068 -221.461838)
		(mid 132.294481 -221.668189)
		(end 132.220462 -221.94774)
		(width 0.088646)
		(layer "In4.Cu")
		(net "M_F_CPU1_SB_DQ<31>")
	)
	(arc
		(start 135.792464 -219.01658)
		(mid 135.605266 -219.066723)
		(end 135.418068 -219.01658)
		(width 0.088646)
		(layer "In4.Cu")
		(net "M_F_CPU1_SB_DQ<31>")
	)
	(arc
		(start 136.357868 -219.01658)
		(mid 136.075166 -218.940804)
		(end 135.792464 -219.01658)
		(width 0.088646)
		(layer "In4.Cu")
		(net "M_F_CPU1_SB_DQ<31>")
	)
	(arc
		(start 138.689588 -218.957144)
		(mid 138.652678 -218.989415)
		(end 138.611864 -219.01658)
		(width 0.088646)
		(layer "In4.Cu")
		(net "M_F_CPU1_SB_DQ<31>")
	)
	(arc
		(start 134.570216 -219.506038)
		(mid 134.522537 -219.688938)
		(end 134.391654 -219.825316)
		(width 0.088646)
		(layer "In4.Cu")
		(net "M_F_CPU1_SB_DQ<31>")
	)
	(arc
		(start 133.442964 -219.830396)
		(mid 133.238629 -220.033001)
		(end 133.160516 -220.309948)
		(width 0.088646)
		(layer "In4.Cu")
		(net "M_F_CPU1_SB_DQ<31>")
	)
	(arc
		(start 131.09321 -222.272098)
		(mid 130.890387 -222.472329)
		(end 130.811016 -222.746062)
		(width 0.088646)
		(layer "In4.Cu")
		(net "M_F_CPU1_SB_DQ<31>")
	)
	(arc
		(start 137.297668 -219.01658)
		(mid 137.023469 -218.940745)
		(end 136.746996 -219.007944)
		(width 0.088646)
		(layer "In4.Cu")
		(net "M_F_CPU1_SB_DQ<31>")
	)
	(arc
		(start 130.15341 -225.527616)
		(mid 129.952128 -225.725103)
		(end 129.871216 -225.99523)
		(width 0.088646)
		(layer "In4.Cu")
		(net "M_F_CPU1_SB_DQ<31>")
	)
	(arc
		(start 137.672064 -219.01658)
		(mid 137.484866 -219.066723)
		(end 137.297668 -219.01658)
		(width 0.088646)
		(layer "In4.Cu")
		(net "M_F_CPU1_SB_DQ<31>")
	)
	(arc
		(start 133.160516 -220.319854)
		(mid 133.112837 -220.502754)
		(end 132.981954 -220.639132)
		(width 0.088646)
		(layer "In4.Cu")
		(net "M_F_CPU1_SB_DQ<31>")
	)
	(arc
		(start 136.732264 -219.01658)
		(mid 136.545066 -219.066723)
		(end 136.357868 -219.01658)
		(width 0.088646)
		(layer "In4.Cu")
		(net "M_F_CPU1_SB_DQ<31>")
	)
	(arc
		(start 130.340862 -223.575626)
		(mid 130.293183 -223.758526)
		(end 130.1623 -223.894904)
		(width 0.088646)
		(layer "In4.Cu")
		(net "M_F_CPU1_SB_DQ<31>")
	)
	(arc
		(start 135.418068 -219.01658)
		(mid 135.135366 -218.940804)
		(end 134.852664 -219.01658)
		(width 0.088646)
		(layer "In4.Cu")
		(net "M_F_CPU1_SB_DQ<31>")
	)
	(arc
		(start 129.871216 -226.017328)
		(mid 129.823537 -226.200228)
		(end 129.692654 -226.336606)
		(width 0.088646)
		(layer "In4.Cu")
		(net "M_F_CPU1_SB_DQ<31>")
	)
	(arc
		(start 138.611864 -219.01658)
		(mid 138.424666 -219.066723)
		(end 138.237468 -219.01658)
		(width 0.088646)
		(layer "In4.Cu")
		(net "M_F_CPU1_SB_DQ<31>")
	)
	(arc
		(start 132.220462 -221.94774)
		(mid 132.172783 -222.13064)
		(end 132.0419 -222.267018)
		(width 0.088646)
		(layer "In4.Cu")
		(net "M_F_CPU1_SB_DQ<31>")
	)
	(arc
		(start 134.852664 -219.01658)
		(mid 134.648329 -219.219185)
		(end 134.570216 -219.496132)
		(width 0.088646)
		(layer "In4.Cu")
		(net "M_F_CPU1_SB_DQ<31>")
	)
	(arc
		(start 132.03301 -222.272098)
		(mid 131.845812 -222.322241)
		(end 131.658614 -222.272098)
		(width 0.088646)
		(layer "In4.Cu")
		(net "M_F_CPU1_SB_DQ<31>")
	)
	(arc
		(start 130.15341 -223.899984)
		(mid 129.950587 -224.100215)
		(end 129.871216 -224.373948)
		(width 0.088646)
		(layer "In4.Cu")
		(net "M_F_CPU1_SB_DQ<31>")
	)
	(arc
		(start 129.677668 -226.345242)
		(mid 129.492145 -226.523543)
		(end 129.404872 -226.765612)
		(width 0.088646)
		(layer "In4.Cu")
		(net "M_F_CPU1_SB_DQ<31>")
	)
	(arc
		(start 132.690616 -221.133924)
		(mid 132.642937 -221.316824)
		(end 132.512054 -221.453202)
		(width 0.088646)
		(layer "In4.Cu")
		(net "M_F_CPU1_SB_DQ<31>")
	)
	(arc
		(start 130.811016 -222.761556)
		(mid 130.763337 -222.944456)
		(end 130.632454 -223.080834)
		(width 0.088646)
		(layer "In4.Cu")
		(net "M_F_CPU1_SB_DQ<31>")
	)
	(arc
		(start 134.008368 -219.830396)
		(mid 133.725666 -219.75462)
		(end 133.442964 -219.830396)
		(width 0.088646)
		(layer "In4.Cu")
		(net "M_F_CPU1_SB_DQ<31>")
	)
	(arc
		(start 138.237468 -219.01658)
		(mid 137.963269 -218.940745)
		(end 137.686796 -219.007944)
		(width 0.088646)
		(layer "In4.Cu")
		(net "M_F_CPU1_SB_DQ<31>")
	)
	(arc
		(start 134.382764 -219.830396)
		(mid 134.195566 -219.880539)
		(end 134.008368 -219.830396)
		(width 0.088646)
		(layer "In4.Cu")
		(net "M_F_CPU1_SB_DQ<31>")
	)
	(arc
		(start 131.643882 -222.263462)
		(mid 131.367407 -222.196142)
		(end 131.09321 -222.272098)
		(width 0.088646)
		(layer "In4.Cu")
		(net "M_F_CPU1_SB_DQ<31>")
	)
	(arc
		(start 132.973064 -220.644212)
		(mid 132.770778 -220.843193)
		(end 132.690616 -221.115382)
		(width 0.088646)
		(layer "In4.Cu")
		(net "M_F_CPU1_SB_DQ<31>")
	)
	(arc
		(start 129.871216 -224.404936)
		(mid 129.950586 -224.67867)
		(end 130.15341 -224.8789)
		(width 0.088646)
		(layer "In4.Cu")
		(net "M_F_CPU1_SB_DQ<31>")
	)
	(segment
		(start 180.423058 -197.748652)
		(end 180.427884 -197.748652)
		(width 0.101854)
		(layer "F.Cu")
		(net "M_F_CPU1_SB_DQ<30>")
	)
	(segment
		(start 183.340248 -197.298818)
		(end 183.574436 -197.06463)
		(width 0.20066)
		(layer "F.Cu")
		(net "M_F_CPU1_SB_DQ<30>")
	)
	(segment
		(start 180.131212 -197.748652)
		(end 180.423058 -197.748652)
		(width 0.20066)
		(layer "F.Cu")
		(net "M_F_CPU1_SB_DQ<30>")
	)
	(segment
		(start 183.958484 -197.06463)
		(end 184.210452 -197.316598)
		(width 0.20066)
		(layer "F.Cu")
		(net "M_F_CPU1_SB_DQ<30>")
	)
	(segment
		(start 184.210452 -197.316598)
		(end 185.544714 -197.316598)
		(width 0.20066)
		(layer "F.Cu")
		(net "M_F_CPU1_SB_DQ<30>")
	)
	(segment
		(start 180.427884 -197.748652)
		(end 180.434996 -197.74154)
		(width 0.1016)
		(layer "F.Cu")
		(net "M_F_CPU1_SB_DQ<30>")
	)
	(segment
		(start 182.442866 -197.74154)
		(end 182.455058 -197.753732)
		(width 0.1016)
		(layer "F.Cu")
		(net "M_F_CPU1_SB_DQ<30>")
	)
	(segment
		(start 183.136286 -197.753732)
		(end 183.340248 -197.54977)
		(width 0.20066)
		(layer "F.Cu")
		(net "M_F_CPU1_SB_DQ<30>")
	)
	(segment
		(start 183.574436 -197.06463)
		(end 183.958484 -197.06463)
		(width 0.20066)
		(layer "F.Cu")
		(net "M_F_CPU1_SB_DQ<30>")
	)
	(segment
		(start 132.785612 -227.36683)
		(end 132.785612 -226.831144)
		(width 0.20066)
		(layer "F.Cu")
		(net "M_F_CPU1_SB_DQ<30>")
	)
	(segment
		(start 176.896014 -197.316598)
		(end 178.000914 -197.316598)
		(width 0.20066)
		(layer "F.Cu")
		(net "M_F_CPU1_SB_DQ<30>")
	)
	(segment
		(start 178.000914 -197.316598)
		(end 179.699158 -197.316598)
		(width 0.20066)
		(layer "F.Cu")
		(net "M_F_CPU1_SB_DQ<30>")
	)
	(segment
		(start 183.340248 -197.54977)
		(end 183.340248 -197.298818)
		(width 0.20066)
		(layer "F.Cu")
		(net "M_F_CPU1_SB_DQ<30>")
	)
	(segment
		(start 179.699158 -197.316598)
		(end 180.131212 -197.748652)
		(width 0.20066)
		(layer "F.Cu")
		(net "M_F_CPU1_SB_DQ<30>")
	)
	(segment
		(start 182.455058 -197.753732)
		(end 183.136286 -197.753732)
		(width 0.20066)
		(layer "F.Cu")
		(net "M_F_CPU1_SB_DQ<30>")
	)
	(segment
		(start 132.785866 -227.367084)
		(end 132.785612 -227.36683)
		(width 0.20066)
		(layer "F.Cu")
		(net "M_F_CPU1_SB_DQ<30>")
	)
	(segment
		(start 180.434996 -197.74154)
		(end 182.442866 -197.74154)
		(width 0.1016)
		(layer "F.Cu")
		(net "M_F_CPU1_SB_DQ<30>")
	)
	(segment
		(start 173.41977 -198.177658)
		(end 173.41977 -198.432166)
		(width 0.18288)
		(layer "In4.Cu")
		(net "M_F_CPU1_SB_DQ<30>")
	)
	(segment
		(start 176.896014 -197.316598)
		(end 176.485042 -196.905626)
		(width 0.18288)
		(layer "In4.Cu")
		(net "M_F_CPU1_SB_DQ<30>")
	)
	(segment
		(start 175.518826 -198.227442)
		(end 175.154082 -198.592186)
		(width 0.18288)
		(layer "In4.Cu")
		(net "M_F_CPU1_SB_DQ<30>")
	)
	(segment
		(start 174.041562 -197.994778)
		(end 173.60265 -197.994778)
		(width 0.18288)
		(layer "In4.Cu")
		(net "M_F_CPU1_SB_DQ<30>")
	)
	(segment
		(start 151.365712 -205.909164)
		(end 149.414738 -210.619594)
		(width 0.18288)
		(layer "In4.Cu")
		(net "M_F_CPU1_SB_DQ<30>")
	)
	(segment
		(start 132.407406 -226.765866)
		(end 132.472684 -226.831144)
		(width 0.088646)
		(layer "In4.Cu")
		(net "M_F_CPU1_SB_DQ<30>")
	)
	(segment
		(start 174.41037 -198.592186)
		(end 174.224442 -198.406258)
		(width 0.18288)
		(layer "In4.Cu")
		(net "M_F_CPU1_SB_DQ<30>")
	)
	(segment
		(start 173.41977 -198.432166)
		(end 173.25975 -198.592186)
		(width 0.18288)
		(layer "In4.Cu")
		(net "M_F_CPU1_SB_DQ<30>")
	)
	(segment
		(start 132.128768 -224.065084)
		(end 132.119878 -224.070164)
		(width 0.088646)
		(layer "In4.Cu")
		(net "M_F_CPU1_SB_DQ<30>")
	)
	(segment
		(start 137.686796 -220.004132)
		(end 137.672064 -219.995496)
		(width 0.088646)
		(layer "In4.Cu")
		(net "M_F_CPU1_SB_DQ<30>")
	)
	(segment
		(start 132.134864 -224.061528)
		(end 132.128768 -224.065084)
		(width 0.088646)
		(layer "In4.Cu")
		(net "M_F_CPU1_SB_DQ<30>")
	)
	(segment
		(start 175.154082 -198.592186)
		(end 174.41037 -198.592186)
		(width 0.18288)
		(layer "In4.Cu")
		(net "M_F_CPU1_SB_DQ<30>")
	)
	(segment
		(start 132.119878 -224.70872)
		(end 132.128768 -224.7138)
		(width 0.088646)
		(layer "In4.Cu")
		(net "M_F_CPU1_SB_DQ<30>")
	)
	(segment
		(start 134.948168 -220.809566)
		(end 134.939278 -220.814646)
		(width 0.088646)
		(layer "In4.Cu")
		(net "M_F_CPU1_SB_DQ<30>")
	)
	(segment
		(start 139.756642 -219.791788)
		(end 139.536678 -219.791788)
		(width 0.088646)
		(layer "In4.Cu")
		(net "M_F_CPU1_SB_DQ<30>")
	)
	(segment
		(start 140.24229 -219.791788)
		(end 139.756642 -219.791788)
		(width 0.18288)
		(layer "In4.Cu")
		(net "M_F_CPU1_SB_DQ<30>")
	)
	(segment
		(start 154.245818 -201.599038)
		(end 151.365712 -205.909164)
		(width 0.18288)
		(layer "In4.Cu")
		(net "M_F_CPU1_SB_DQ<30>")
	)
	(segment
		(start 136.746996 -220.004132)
		(end 136.732264 -219.995496)
		(width 0.088646)
		(layer "In4.Cu")
		(net "M_F_CPU1_SB_DQ<30>")
	)
	(segment
		(start 139.33297 -219.995496)
		(end 139.177268 -219.995496)
		(width 0.088646)
		(layer "In4.Cu")
		(net "M_F_CPU1_SB_DQ<30>")
	)
	(segment
		(start 133.068568 -222.437198)
		(end 133.059678 -222.442278)
		(width 0.088646)
		(layer "In4.Cu")
		(net "M_F_CPU1_SB_DQ<30>")
	)
	(segment
		(start 149.336506 -210.697572)
		(end 140.24229 -219.791788)
		(width 0.18288)
		(layer "In4.Cu")
		(net "M_F_CPU1_SB_DQ<30>")
	)
	(segment
		(start 174.224442 -198.406258)
		(end 174.224442 -198.177658)
		(width 0.18288)
		(layer "In4.Cu")
		(net "M_F_CPU1_SB_DQ<30>")
	)
	(segment
		(start 134.290816 -221.939104)
		(end 134.290816 -221.957646)
		(width 0.088646)
		(layer "In4.Cu")
		(net "M_F_CPU1_SB_DQ<30>")
	)
	(segment
		(start 138.626596 -220.004132)
		(end 138.611864 -219.995496)
		(width 0.088646)
		(layer "In4.Cu")
		(net "M_F_CPU1_SB_DQ<30>")
	)
	(segment
		(start 175.930814 -196.905626)
		(end 175.518826 -197.317614)
		(width 0.18288)
		(layer "In4.Cu")
		(net "M_F_CPU1_SB_DQ<30>")
	)
	(segment
		(start 134.48411 -221.619826)
		(end 134.478014 -221.623382)
		(width 0.088646)
		(layer "In4.Cu")
		(net "M_F_CPU1_SB_DQ<30>")
	)
	(segment
		(start 174.224442 -198.177658)
		(end 174.041562 -197.994778)
		(width 0.18288)
		(layer "In4.Cu")
		(net "M_F_CPU1_SB_DQ<30>")
	)
	(segment
		(start 132.119878 -226.336606)
		(end 132.128768 -226.341686)
		(width 0.088646)
		(layer "In4.Cu")
		(net "M_F_CPU1_SB_DQ<30>")
	)
	(segment
		(start 135.230616 -220.319854)
		(end 135.230616 -220.334078)
		(width 0.088646)
		(layer "In4.Cu")
		(net "M_F_CPU1_SB_DQ<30>")
	)
	(segment
		(start 173.60265 -197.994778)
		(end 173.41977 -198.177658)
		(width 0.18288)
		(layer "In4.Cu")
		(net "M_F_CPU1_SB_DQ<30>")
	)
	(segment
		(start 132.472684 -226.831144)
		(end 132.785612 -226.831144)
		(width 0.088646)
		(layer "In4.Cu")
		(net "M_F_CPU1_SB_DQ<30>")
	)
	(segment
		(start 176.485042 -196.905626)
		(end 175.930814 -196.905626)
		(width 0.18288)
		(layer "In4.Cu")
		(net "M_F_CPU1_SB_DQ<30>")
	)
	(segment
		(start 149.336506 -210.697826)
		(end 149.336506 -210.697572)
		(width 0.18288)
		(layer "In4.Cu")
		(net "M_F_CPU1_SB_DQ<30>")
	)
	(segment
		(start 149.414738 -210.619594)
		(end 149.336506 -210.697826)
		(width 0.18288)
		(layer "In4.Cu")
		(net "M_F_CPU1_SB_DQ<30>")
	)
	(segment
		(start 135.418068 -219.995496)
		(end 135.409178 -220.000576)
		(width 0.088646)
		(layer "In4.Cu")
		(net "M_F_CPU1_SB_DQ<30>")
	)
	(segment
		(start 132.410962 -225.187764)
		(end 132.410962 -225.225356)
		(width 0.088646)
		(layer "In4.Cu")
		(net "M_F_CPU1_SB_DQ<30>")
	)
	(segment
		(start 132.128768 -225.69297)
		(end 132.119878 -225.69805)
		(width 0.088646)
		(layer "In4.Cu")
		(net "M_F_CPU1_SB_DQ<30>")
	)
	(segment
		(start 173.25975 -198.592186)
		(end 157.25267 -198.592186)
		(width 0.18288)
		(layer "In4.Cu")
		(net "M_F_CPU1_SB_DQ<30>")
	)
	(segment
		(start 175.518826 -197.317614)
		(end 175.518826 -198.227442)
		(width 0.18288)
		(layer "In4.Cu")
		(net "M_F_CPU1_SB_DQ<30>")
	)
	(segment
		(start 157.25267 -198.592186)
		(end 154.245818 -201.599038)
		(width 0.18288)
		(layer "In4.Cu")
		(net "M_F_CPU1_SB_DQ<30>")
	)
	(segment
		(start 132.881116 -222.761556)
		(end 132.881116 -222.780098)
		(width 0.088646)
		(layer "In4.Cu")
		(net "M_F_CPU1_SB_DQ<30>")
	)
	(segment
		(start 132.598668 -223.251268)
		(end 132.589778 -223.256348)
		(width 0.088646)
		(layer "In4.Cu")
		(net "M_F_CPU1_SB_DQ<30>")
	)
	(segment
		(start 139.536678 -219.791788)
		(end 139.33297 -219.995496)
		(width 0.088646)
		(layer "In4.Cu")
		(net "M_F_CPU1_SB_DQ<30>")
	)
	(arc
		(start 134.939278 -220.814646)
		(mid 134.808364 -220.951006)
		(end 134.760716 -221.133924)
		(width 0.088646)
		(layer "In4.Cu")
		(net "M_F_CPU1_SB_DQ<30>")
	)
	(arc
		(start 138.611864 -219.995496)
		(mid 138.424666 -219.945353)
		(end 138.237468 -219.995496)
		(width 0.088646)
		(layer "In4.Cu")
		(net "M_F_CPU1_SB_DQ<30>")
	)
	(arc
		(start 139.177268 -219.995496)
		(mid 138.903069 -220.071331)
		(end 138.626596 -220.004132)
		(width 0.088646)
		(layer "In4.Cu")
		(net "M_F_CPU1_SB_DQ<30>")
	)
	(arc
		(start 134.478014 -221.623382)
		(mid 134.343081 -221.756736)
		(end 134.290816 -221.939104)
		(width 0.088646)
		(layer "In4.Cu")
		(net "M_F_CPU1_SB_DQ<30>")
	)
	(arc
		(start 134.290816 -221.957646)
		(mid 134.212705 -222.234595)
		(end 134.008368 -222.437198)
		(width 0.088646)
		(layer "In4.Cu")
		(net "M_F_CPU1_SB_DQ<30>")
	)
	(arc
		(start 137.672064 -219.995496)
		(mid 137.484866 -219.945353)
		(end 137.297668 -219.995496)
		(width 0.088646)
		(layer "In4.Cu")
		(net "M_F_CPU1_SB_DQ<30>")
	)
	(arc
		(start 135.792464 -219.995496)
		(mid 135.605266 -219.945353)
		(end 135.418068 -219.995496)
		(width 0.088646)
		(layer "In4.Cu")
		(net "M_F_CPU1_SB_DQ<30>")
	)
	(arc
		(start 133.059678 -222.442278)
		(mid 132.928764 -222.578638)
		(end 132.881116 -222.761556)
		(width 0.088646)
		(layer "In4.Cu")
		(net "M_F_CPU1_SB_DQ<30>")
	)
	(arc
		(start 132.410962 -225.225356)
		(mid 132.330051 -225.495484)
		(end 132.128768 -225.69297)
		(width 0.088646)
		(layer "In4.Cu")
		(net "M_F_CPU1_SB_DQ<30>")
	)
	(arc
		(start 132.128768 -226.341686)
		(mid 132.318351 -226.520756)
		(end 132.407406 -226.765866)
		(width 0.088646)
		(layer "In4.Cu")
		(net "M_F_CPU1_SB_DQ<30>")
	)
	(arc
		(start 132.119878 -224.070164)
		(mid 131.941281 -224.389442)
		(end 132.119878 -224.70872)
		(width 0.088646)
		(layer "In4.Cu")
		(net "M_F_CPU1_SB_DQ<30>")
	)
	(arc
		(start 135.230616 -220.334078)
		(mid 135.151475 -220.608701)
		(end 134.948168 -220.809566)
		(width 0.088646)
		(layer "In4.Cu")
		(net "M_F_CPU1_SB_DQ<30>")
	)
	(arc
		(start 138.237468 -219.995496)
		(mid 137.963269 -220.071331)
		(end 137.686796 -220.004132)
		(width 0.088646)
		(layer "In4.Cu")
		(net "M_F_CPU1_SB_DQ<30>")
	)
	(arc
		(start 137.297668 -219.995496)
		(mid 137.023469 -220.071331)
		(end 136.746996 -220.004132)
		(width 0.088646)
		(layer "In4.Cu")
		(net "M_F_CPU1_SB_DQ<30>")
	)
	(arc
		(start 136.357868 -219.995496)
		(mid 136.075166 -220.071272)
		(end 135.792464 -219.995496)
		(width 0.088646)
		(layer "In4.Cu")
		(net "M_F_CPU1_SB_DQ<30>")
	)
	(arc
		(start 132.119878 -225.69805)
		(mid 131.941281 -226.017328)
		(end 132.119878 -226.336606)
		(width 0.088646)
		(layer "In4.Cu")
		(net "M_F_CPU1_SB_DQ<30>")
	)
	(arc
		(start 135.409178 -220.000576)
		(mid 135.278264 -220.136936)
		(end 135.230616 -220.319854)
		(width 0.088646)
		(layer "In4.Cu")
		(net "M_F_CPU1_SB_DQ<30>")
	)
	(arc
		(start 136.732264 -219.995496)
		(mid 136.545066 -219.945353)
		(end 136.357868 -219.995496)
		(width 0.088646)
		(layer "In4.Cu")
		(net "M_F_CPU1_SB_DQ<30>")
	)
	(arc
		(start 132.128768 -224.7138)
		(mid 132.331591 -224.914031)
		(end 132.410962 -225.187764)
		(width 0.088646)
		(layer "In4.Cu")
		(net "M_F_CPU1_SB_DQ<30>")
	)
	(arc
		(start 133.442964 -222.437198)
		(mid 133.255766 -222.387055)
		(end 133.068568 -222.437198)
		(width 0.088646)
		(layer "In4.Cu")
		(net "M_F_CPU1_SB_DQ<30>")
	)
	(arc
		(start 134.008368 -222.437198)
		(mid 133.725666 -222.512974)
		(end 133.442964 -222.437198)
		(width 0.088646)
		(layer "In4.Cu")
		(net "M_F_CPU1_SB_DQ<30>")
	)
	(arc
		(start 132.881116 -222.780098)
		(mid 132.800954 -223.052287)
		(end 132.598668 -223.251268)
		(width 0.088646)
		(layer "In4.Cu")
		(net "M_F_CPU1_SB_DQ<30>")
	)
	(arc
		(start 132.589778 -223.256348)
		(mid 132.458864 -223.392708)
		(end 132.411216 -223.575626)
		(width 0.088646)
		(layer "In4.Cu")
		(net "M_F_CPU1_SB_DQ<30>")
	)
	(arc
		(start 132.411216 -223.575626)
		(mid 132.3373 -223.855128)
		(end 132.134864 -224.061528)
		(width 0.088646)
		(layer "In4.Cu")
		(net "M_F_CPU1_SB_DQ<30>")
	)
	(arc
		(start 134.760716 -221.133924)
		(mid 134.686725 -221.41349)
		(end 134.48411 -221.619826)
		(width 0.088646)
		(layer "In4.Cu")
		(net "M_F_CPU1_SB_DQ<30>")
	)
	(segment
		(start 183.136286 -231.753918)
		(end 183.340248 -231.549956)
		(width 0.20066)
		(layer "F.Cu")
		(net "M_F_CPU1_SB_DQ<2>")
	)
	(segment
		(start 184.210452 -231.316784)
		(end 185.544714 -231.316784)
		(width 0.20066)
		(layer "F.Cu")
		(net "M_F_CPU1_SB_DQ<2>")
	)
	(segment
		(start 180.423058 -231.748838)
		(end 180.427884 -231.748838)
		(width 0.101854)
		(layer "F.Cu")
		(net "M_F_CPU1_SB_DQ<2>")
	)
	(segment
		(start 179.699158 -231.316784)
		(end 180.131212 -231.748838)
		(width 0.20066)
		(layer "F.Cu")
		(net "M_F_CPU1_SB_DQ<2>")
	)
	(segment
		(start 182.455058 -231.753918)
		(end 183.136286 -231.753918)
		(width 0.20066)
		(layer "F.Cu")
		(net "M_F_CPU1_SB_DQ<2>")
	)
	(segment
		(start 183.574436 -231.064816)
		(end 183.958484 -231.064816)
		(width 0.20066)
		(layer "F.Cu")
		(net "M_F_CPU1_SB_DQ<2>")
	)
	(segment
		(start 180.427884 -231.748838)
		(end 180.434996 -231.741726)
		(width 0.1016)
		(layer "F.Cu")
		(net "M_F_CPU1_SB_DQ<2>")
	)
	(segment
		(start 178.000914 -231.316784)
		(end 179.699158 -231.316784)
		(width 0.20066)
		(layer "F.Cu")
		(net "M_F_CPU1_SB_DQ<2>")
	)
	(segment
		(start 183.340248 -231.299004)
		(end 183.574436 -231.064816)
		(width 0.20066)
		(layer "F.Cu")
		(net "M_F_CPU1_SB_DQ<2>")
	)
	(segment
		(start 176.896014 -231.316784)
		(end 178.000914 -231.316784)
		(width 0.20066)
		(layer "F.Cu")
		(net "M_F_CPU1_SB_DQ<2>")
	)
	(segment
		(start 131.375912 -239.57534)
		(end 131.376166 -239.575086)
		(width 0.20066)
		(layer "F.Cu")
		(net "M_F_CPU1_SB_DQ<2>")
	)
	(segment
		(start 131.376166 -239.575086)
		(end 131.376166 -239.0394)
		(width 0.20066)
		(layer "F.Cu")
		(net "M_F_CPU1_SB_DQ<2>")
	)
	(segment
		(start 183.340248 -231.549956)
		(end 183.340248 -231.299004)
		(width 0.20066)
		(layer "F.Cu")
		(net "M_F_CPU1_SB_DQ<2>")
	)
	(segment
		(start 183.958484 -231.064816)
		(end 184.210452 -231.316784)
		(width 0.20066)
		(layer "F.Cu")
		(net "M_F_CPU1_SB_DQ<2>")
	)
	(segment
		(start 182.442866 -231.741726)
		(end 182.455058 -231.753918)
		(width 0.1016)
		(layer "F.Cu")
		(net "M_F_CPU1_SB_DQ<2>")
	)
	(segment
		(start 180.131212 -231.748838)
		(end 180.423058 -231.748838)
		(width 0.20066)
		(layer "F.Cu")
		(net "M_F_CPU1_SB_DQ<2>")
	)
	(segment
		(start 180.434996 -231.741726)
		(end 182.442866 -231.741726)
		(width 0.1016)
		(layer "F.Cu")
		(net "M_F_CPU1_SB_DQ<2>")
	)
	(segment
		(start 136.277096 -239.355122)
		(end 136.262364 -239.363758)
		(width 0.088646)
		(layer "In4.Cu")
		(net "M_F_CPU1_SB_DQ<2>")
	)
	(segment
		(start 166.355014 -231.961944)
		(end 166.027354 -231.961944)
		(width 0.18288)
		(layer "In4.Cu")
		(net "M_F_CPU1_SB_DQ<2>")
	)
	(segment
		(start 134.008114 -239.364012)
		(end 134.004558 -239.361726)
		(width 0.088646)
		(layer "In4.Cu")
		(net "M_F_CPU1_SB_DQ<2>")
	)
	(segment
		(start 149.377654 -235.340144)
		(end 144.911318 -235.340144)
		(width 0.18288)
		(layer "In4.Cu")
		(net "M_F_CPU1_SB_DQ<2>")
	)
	(segment
		(start 161.073846 -230.41102)
		(end 160.913826 -230.57104)
		(width 0.18288)
		(layer "In4.Cu")
		(net "M_F_CPU1_SB_DQ<2>")
	)
	(segment
		(start 160.687258 -230.57104)
		(end 160.21304 -230.096822)
		(width 0.18288)
		(layer "In4.Cu")
		(net "M_F_CPU1_SB_DQ<2>")
	)
	(segment
		(start 174.914814 -230.5685)
		(end 174.731934 -230.75138)
		(width 0.18288)
		(layer "In4.Cu")
		(net "M_F_CPU1_SB_DQ<2>")
	)
	(segment
		(start 159.646366 -230.89235)
		(end 153.825448 -230.89235)
		(width 0.18288)
		(layer "In4.Cu")
		(net "M_F_CPU1_SB_DQ<2>")
	)
	(segment
		(start 176.33061 -230.75138)
		(end 175.791114 -230.75138)
		(width 0.18288)
		(layer "In4.Cu")
		(net "M_F_CPU1_SB_DQ<2>")
	)
	(segment
		(start 161.073846 -230.202232)
		(end 161.073846 -230.41102)
		(width 0.18288)
		(layer "In4.Cu")
		(net "M_F_CPU1_SB_DQ<2>")
	)
	(segment
		(start 175.425354 -230.050086)
		(end 175.097694 -230.050086)
		(width 0.18288)
		(layer "In4.Cu")
		(net "M_F_CPU1_SB_DQ<2>")
	)
	(segment
		(start 167.619172 -230.814626)
		(end 166.720774 -230.814626)
		(width 0.18288)
		(layer "In4.Cu")
		(net "M_F_CPU1_SB_DQ<2>")
	)
	(segment
		(start 139.55522 -239.080294)
		(end 139.081764 -239.363758)
		(width 0.088646)
		(layer "In4.Cu")
		(net "M_F_CPU1_SB_DQ<2>")
	)
	(segment
		(start 153.825448 -230.89235)
		(end 149.377654 -235.340144)
		(width 0.18288)
		(layer "In4.Cu")
		(net "M_F_CPU1_SB_DQ<2>")
	)
	(segment
		(start 135.887714 -239.364012)
		(end 135.884158 -239.361726)
		(width 0.088646)
		(layer "In4.Cu")
		(net "M_F_CPU1_SB_DQ<2>")
	)
	(segment
		(start 167.799766 -230.99522)
		(end 167.619172 -230.814626)
		(width 0.18288)
		(layer "In4.Cu")
		(net "M_F_CPU1_SB_DQ<2>")
	)
	(segment
		(start 174.914814 -230.232966)
		(end 174.914814 -230.5685)
		(width 0.18288)
		(layer "In4.Cu")
		(net "M_F_CPU1_SB_DQ<2>")
	)
	(segment
		(start 175.608234 -230.232966)
		(end 175.425354 -230.050086)
		(width 0.18288)
		(layer "In4.Cu")
		(net "M_F_CPU1_SB_DQ<2>")
	)
	(segment
		(start 175.097694 -230.050086)
		(end 174.914814 -230.232966)
		(width 0.18288)
		(layer "In4.Cu")
		(net "M_F_CPU1_SB_DQ<2>")
	)
	(segment
		(start 131.063238 -239.0394)
		(end 131.376166 -239.0394)
		(width 0.088646)
		(layer "In4.Cu")
		(net "M_F_CPU1_SB_DQ<2>")
	)
	(segment
		(start 131.188714 -239.364012)
		(end 131.183634 -239.360964)
		(width 0.088646)
		(layer "In4.Cu")
		(net "M_F_CPU1_SB_DQ<2>")
	)
	(segment
		(start 137.216896 -239.355122)
		(end 137.202164 -239.363758)
		(width 0.088646)
		(layer "In4.Cu")
		(net "M_F_CPU1_SB_DQ<2>")
	)
	(segment
		(start 176.896014 -231.316784)
		(end 176.33061 -230.75138)
		(width 0.18288)
		(layer "In4.Cu")
		(net "M_F_CPU1_SB_DQ<2>")
	)
	(segment
		(start 174.731934 -230.75138)
		(end 173.788832 -230.75138)
		(width 0.18288)
		(layer "In4.Cu")
		(net "M_F_CPU1_SB_DQ<2>")
	)
	(segment
		(start 161.233866 -230.042212)
		(end 161.073846 -230.202232)
		(width 0.18288)
		(layer "In4.Cu")
		(net "M_F_CPU1_SB_DQ<2>")
	)
	(segment
		(start 160.21304 -230.096822)
		(end 159.986726 -230.096822)
		(width 0.18288)
		(layer "In4.Cu")
		(net "M_F_CPU1_SB_DQ<2>")
	)
	(segment
		(start 173.788832 -230.75138)
		(end 173.647608 -230.892604)
		(width 0.18288)
		(layer "In4.Cu")
		(net "M_F_CPU1_SB_DQ<2>")
	)
	(segment
		(start 135.887968 -239.363758)
		(end 135.887714 -239.364012)
		(width 0.088646)
		(layer "In4.Cu")
		(net "M_F_CPU1_SB_DQ<2>")
	)
	(segment
		(start 166.537894 -231.779064)
		(end 166.355014 -231.961944)
		(width 0.18288)
		(layer "In4.Cu")
		(net "M_F_CPU1_SB_DQ<2>")
	)
	(segment
		(start 165.844474 -230.997506)
		(end 165.661594 -230.814626)
		(width 0.18288)
		(layer "In4.Cu")
		(net "M_F_CPU1_SB_DQ<2>")
	)
	(segment
		(start 133.074156 -239.367314)
		(end 133.068314 -239.364012)
		(width 0.088646)
		(layer "In4.Cu")
		(net "M_F_CPU1_SB_DQ<2>")
	)
	(segment
		(start 133.068314 -239.364012)
		(end 133.062472 -239.360456)
		(width 0.088646)
		(layer "In4.Cu")
		(net "M_F_CPU1_SB_DQ<2>")
	)
	(segment
		(start 141.001496 -237.789212)
		(end 140.846302 -237.789212)
		(width 0.088646)
		(layer "In4.Cu")
		(net "M_F_CPU1_SB_DQ<2>")
	)
	(segment
		(start 132.134356 -239.367314)
		(end 132.128514 -239.364012)
		(width 0.088646)
		(layer "In4.Cu")
		(net "M_F_CPU1_SB_DQ<2>")
	)
	(segment
		(start 131.194556 -239.367314)
		(end 131.188714 -239.364012)
		(width 0.088646)
		(layer "In4.Cu")
		(net "M_F_CPU1_SB_DQ<2>")
	)
	(segment
		(start 165.661594 -230.814626)
		(end 165.054026 -230.814626)
		(width 0.18288)
		(layer "In4.Cu")
		(net "M_F_CPU1_SB_DQ<2>")
	)
	(segment
		(start 160.913826 -230.57104)
		(end 160.687258 -230.57104)
		(width 0.18288)
		(layer "In4.Cu")
		(net "M_F_CPU1_SB_DQ<2>")
	)
	(segment
		(start 175.791114 -230.75138)
		(end 175.608234 -230.5685)
		(width 0.18288)
		(layer "In4.Cu")
		(net "M_F_CPU1_SB_DQ<2>")
	)
	(segment
		(start 132.128514 -239.364012)
		(end 132.122672 -239.360456)
		(width 0.088646)
		(layer "In4.Cu")
		(net "M_F_CPU1_SB_DQ<2>")
	)
	(segment
		(start 166.537894 -230.997506)
		(end 166.537894 -231.779064)
		(width 0.18288)
		(layer "In4.Cu")
		(net "M_F_CPU1_SB_DQ<2>")
	)
	(segment
		(start 172.506894 -230.892604)
		(end 172.404278 -230.99522)
		(width 0.18288)
		(layer "In4.Cu")
		(net "M_F_CPU1_SB_DQ<2>")
	)
	(segment
		(start 165.054026 -230.814626)
		(end 164.281612 -230.042212)
		(width 0.18288)
		(layer "In4.Cu")
		(net "M_F_CPU1_SB_DQ<2>")
	)
	(segment
		(start 175.608234 -230.5685)
		(end 175.608234 -230.232966)
		(width 0.18288)
		(layer "In4.Cu")
		(net "M_F_CPU1_SB_DQ<2>")
	)
	(segment
		(start 134.953756 -239.367314)
		(end 134.947914 -239.364012)
		(width 0.088646)
		(layer "In4.Cu")
		(net "M_F_CPU1_SB_DQ<2>")
	)
	(segment
		(start 134.947914 -239.364012)
		(end 134.943342 -239.361218)
		(width 0.088646)
		(layer "In4.Cu")
		(net "M_F_CPU1_SB_DQ<2>")
	)
	(segment
		(start 138.156696 -239.355122)
		(end 138.141964 -239.363758)
		(width 0.088646)
		(layer "In4.Cu")
		(net "M_F_CPU1_SB_DQ<2>")
	)
	(segment
		(start 131.005834 -239.096804)
		(end 131.063238 -239.0394)
		(width 0.088646)
		(layer "In4.Cu")
		(net "M_F_CPU1_SB_DQ<2>")
	)
	(segment
		(start 172.404278 -230.99522)
		(end 167.799766 -230.99522)
		(width 0.18288)
		(layer "In4.Cu")
		(net "M_F_CPU1_SB_DQ<2>")
	)
	(segment
		(start 159.826706 -230.71201)
		(end 159.646366 -230.89235)
		(width 0.18288)
		(layer "In4.Cu")
		(net "M_F_CPU1_SB_DQ<2>")
	)
	(segment
		(start 173.647608 -230.892604)
		(end 172.506894 -230.892604)
		(width 0.18288)
		(layer "In4.Cu")
		(net "M_F_CPU1_SB_DQ<2>")
	)
	(segment
		(start 166.027354 -231.961944)
		(end 165.844474 -231.779064)
		(width 0.18288)
		(layer "In4.Cu")
		(net "M_F_CPU1_SB_DQ<2>")
	)
	(segment
		(start 165.844474 -231.779064)
		(end 165.844474 -230.997506)
		(width 0.18288)
		(layer "In4.Cu")
		(net "M_F_CPU1_SB_DQ<2>")
	)
	(segment
		(start 159.826706 -230.256842)
		(end 159.826706 -230.71201)
		(width 0.18288)
		(layer "In4.Cu")
		(net "M_F_CPU1_SB_DQ<2>")
	)
	(segment
		(start 164.281612 -230.042212)
		(end 161.233866 -230.042212)
		(width 0.18288)
		(layer "In4.Cu")
		(net "M_F_CPU1_SB_DQ<2>")
	)
	(segment
		(start 166.720774 -230.814626)
		(end 166.537894 -230.997506)
		(width 0.18288)
		(layer "In4.Cu")
		(net "M_F_CPU1_SB_DQ<2>")
	)
	(segment
		(start 144.911318 -235.340144)
		(end 142.46225 -237.789212)
		(width 0.18288)
		(layer "In4.Cu")
		(net "M_F_CPU1_SB_DQ<2>")
	)
	(segment
		(start 142.46225 -237.789212)
		(end 141.001496 -237.789212)
		(width 0.18288)
		(layer "In4.Cu")
		(net "M_F_CPU1_SB_DQ<2>")
	)
	(segment
		(start 159.986726 -230.096822)
		(end 159.826706 -230.256842)
		(width 0.18288)
		(layer "In4.Cu")
		(net "M_F_CPU1_SB_DQ<2>")
	)
	(segment
		(start 140.846302 -237.789212)
		(end 139.55522 -239.080294)
		(width 0.088646)
		(layer "In4.Cu")
		(net "M_F_CPU1_SB_DQ<2>")
	)
	(arc
		(start 132.503164 -239.364012)
		(mid 132.31921 -239.414107)
		(end 132.134356 -239.367314)
		(width 0.088646)
		(layer "In4.Cu")
		(net "M_F_CPU1_SB_DQ<2>")
	)
	(arc
		(start 131.183634 -239.360964)
		(mid 131.065339 -239.248688)
		(end 131.005834 -239.096804)
		(width 0.088646)
		(layer "In4.Cu")
		(net "M_F_CPU1_SB_DQ<2>")
	)
	(arc
		(start 134.382764 -239.364012)
		(mid 134.195456 -239.414121)
		(end 134.008114 -239.364012)
		(width 0.088646)
		(layer "In4.Cu")
		(net "M_F_CPU1_SB_DQ<2>")
	)
	(arc
		(start 137.767568 -239.363758)
		(mid 137.493369 -239.287923)
		(end 137.216896 -239.355122)
		(width 0.088646)
		(layer "In4.Cu")
		(net "M_F_CPU1_SB_DQ<2>")
	)
	(arc
		(start 135.322564 -239.364012)
		(mid 135.13861 -239.414107)
		(end 134.953756 -239.367314)
		(width 0.088646)
		(layer "In4.Cu")
		(net "M_F_CPU1_SB_DQ<2>")
	)
	(arc
		(start 134.004558 -239.361726)
		(mid 133.723445 -239.288149)
		(end 133.442964 -239.364012)
		(width 0.088646)
		(layer "In4.Cu")
		(net "M_F_CPU1_SB_DQ<2>")
	)
	(arc
		(start 134.943342 -239.361218)
		(mid 134.662678 -239.288177)
		(end 134.382764 -239.364012)
		(width 0.088646)
		(layer "In4.Cu")
		(net "M_F_CPU1_SB_DQ<2>")
	)
	(arc
		(start 136.262364 -239.363758)
		(mid 136.075166 -239.413901)
		(end 135.887968 -239.363758)
		(width 0.088646)
		(layer "In4.Cu")
		(net "M_F_CPU1_SB_DQ<2>")
	)
	(arc
		(start 138.707368 -239.363758)
		(mid 138.433169 -239.287923)
		(end 138.156696 -239.355122)
		(width 0.088646)
		(layer "In4.Cu")
		(net "M_F_CPU1_SB_DQ<2>")
	)
	(arc
		(start 138.141964 -239.363758)
		(mid 137.954766 -239.413901)
		(end 137.767568 -239.363758)
		(width 0.088646)
		(layer "In4.Cu")
		(net "M_F_CPU1_SB_DQ<2>")
	)
	(arc
		(start 132.122672 -239.360456)
		(mid 131.842537 -239.28814)
		(end 131.563364 -239.364012)
		(width 0.088646)
		(layer "In4.Cu")
		(net "M_F_CPU1_SB_DQ<2>")
	)
	(arc
		(start 136.827768 -239.363758)
		(mid 136.553569 -239.287923)
		(end 136.277096 -239.355122)
		(width 0.088646)
		(layer "In4.Cu")
		(net "M_F_CPU1_SB_DQ<2>")
	)
	(arc
		(start 139.081764 -239.363758)
		(mid 138.894566 -239.413901)
		(end 138.707368 -239.363758)
		(width 0.088646)
		(layer "In4.Cu")
		(net "M_F_CPU1_SB_DQ<2>")
	)
	(arc
		(start 131.563364 -239.364012)
		(mid 131.37941 -239.414107)
		(end 131.194556 -239.367314)
		(width 0.088646)
		(layer "In4.Cu")
		(net "M_F_CPU1_SB_DQ<2>")
	)
	(arc
		(start 133.062472 -239.360456)
		(mid 132.782337 -239.28814)
		(end 132.503164 -239.364012)
		(width 0.088646)
		(layer "In4.Cu")
		(net "M_F_CPU1_SB_DQ<2>")
	)
	(arc
		(start 133.442964 -239.364012)
		(mid 133.25901 -239.414107)
		(end 133.074156 -239.367314)
		(width 0.088646)
		(layer "In4.Cu")
		(net "M_F_CPU1_SB_DQ<2>")
	)
	(arc
		(start 137.202164 -239.363758)
		(mid 137.014966 -239.413901)
		(end 136.827768 -239.363758)
		(width 0.088646)
		(layer "In4.Cu")
		(net "M_F_CPU1_SB_DQ<2>")
	)
	(arc
		(start 135.884158 -239.361726)
		(mid 135.603045 -239.288149)
		(end 135.322564 -239.364012)
		(width 0.088646)
		(layer "In4.Cu")
		(net "M_F_CPU1_SB_DQ<2>")
	)
	(segment
		(start 179.004976 -196.041772)
		(end 176.816258 -196.041772)
		(width 0.1016)
		(layer "F.Cu")
		(net "M_F_CPU1_SB_DQ<29>")
	)
	(segment
		(start 179.011326 -196.035422)
		(end 179.004976 -196.041772)
		(width 0.1016)
		(layer "F.Cu")
		(net "M_F_CPU1_SB_DQ<29>")
	)
	(segment
		(start 175.421544 -196.466714)
		(end 173.900846 -196.466714)
		(width 0.20066)
		(layer "F.Cu")
		(net "M_F_CPU1_SB_DQ<29>")
	)
	(segment
		(start 176.333404 -196.159882)
		(end 176.333404 -196.52742)
		(width 0.20066)
		(layer "F.Cu")
		(net "M_F_CPU1_SB_DQ<29>")
	)
	(segment
		(start 175.67021 -196.71538)
		(end 175.421544 -196.466714)
		(width 0.20066)
		(layer "F.Cu")
		(net "M_F_CPU1_SB_DQ<29>")
	)
	(segment
		(start 176.451514 -196.041772)
		(end 176.333404 -196.159882)
		(width 0.20066)
		(layer "F.Cu")
		(net "M_F_CPU1_SB_DQ<29>")
	)
	(segment
		(start 181.444646 -196.466714)
		(end 181.444392 -196.466968)
		(width 0.20066)
		(layer "F.Cu")
		(net "M_F_CPU1_SB_DQ<29>")
	)
	(segment
		(start 173.900846 -196.466714)
		(end 172.795946 -196.466714)
		(width 0.20066)
		(layer "F.Cu")
		(net "M_F_CPU1_SB_DQ<29>")
	)
	(segment
		(start 176.816258 -196.041772)
		(end 176.796192 -196.041772)
		(width 0.101854)
		(layer "F.Cu")
		(net "M_F_CPU1_SB_DQ<29>")
	)
	(segment
		(start 129.966212 -227.36683)
		(end 129.966212 -226.831144)
		(width 0.20066)
		(layer "F.Cu")
		(net "M_F_CPU1_SB_DQ<29>")
	)
	(segment
		(start 129.966466 -227.367084)
		(end 129.966212 -227.36683)
		(width 0.20066)
		(layer "F.Cu")
		(net "M_F_CPU1_SB_DQ<29>")
	)
	(segment
		(start 181.444392 -196.466968)
		(end 179.852828 -196.466968)
		(width 0.20066)
		(layer "F.Cu")
		(net "M_F_CPU1_SB_DQ<29>")
	)
	(segment
		(start 176.796192 -196.041772)
		(end 176.451514 -196.041772)
		(width 0.20066)
		(layer "F.Cu")
		(net "M_F_CPU1_SB_DQ<29>")
	)
	(segment
		(start 176.145444 -196.71538)
		(end 175.67021 -196.71538)
		(width 0.20066)
		(layer "F.Cu")
		(net "M_F_CPU1_SB_DQ<29>")
	)
	(segment
		(start 179.852828 -196.466968)
		(end 179.421282 -196.035422)
		(width 0.20066)
		(layer "F.Cu")
		(net "M_F_CPU1_SB_DQ<29>")
	)
	(segment
		(start 176.333404 -196.52742)
		(end 176.145444 -196.71538)
		(width 0.20066)
		(layer "F.Cu")
		(net "M_F_CPU1_SB_DQ<29>")
	)
	(segment
		(start 179.421282 -196.035422)
		(end 179.011326 -196.035422)
		(width 0.20066)
		(layer "F.Cu")
		(net "M_F_CPU1_SB_DQ<29>")
	)
	(segment
		(start 172.795946 -196.466714)
		(end 172.244258 -195.915026)
		(width 0.18288)
		(layer "In4.Cu")
		(net "M_F_CPU1_SB_DQ<29>")
	)
	(segment
		(start 169.986452 -195.732146)
		(end 169.986452 -195.380356)
		(width 0.18288)
		(layer "In4.Cu")
		(net "M_F_CPU1_SB_DQ<29>")
	)
	(segment
		(start 130.719068 -223.251268)
		(end 130.710178 -223.256348)
		(width 0.088646)
		(layer "In4.Cu")
		(net "M_F_CPU1_SB_DQ<29>")
	)
	(segment
		(start 164.952426 -196.245226)
		(end 164.520626 -195.813426)
		(width 0.18288)
		(layer "In4.Cu")
		(net "M_F_CPU1_SB_DQ<29>")
	)
	(segment
		(start 170.169332 -195.915026)
		(end 169.986452 -195.732146)
		(width 0.18288)
		(layer "In4.Cu")
		(net "M_F_CPU1_SB_DQ<29>")
	)
	(segment
		(start 165.96233 -195.32727)
		(end 165.96233 -196.085206)
		(width 0.18288)
		(layer "In4.Cu")
		(net "M_F_CPU1_SB_DQ<29>")
	)
	(segment
		(start 130.531362 -225.187764)
		(end 130.531362 -225.225356)
		(width 0.088646)
		(layer "In4.Cu")
		(net "M_F_CPU1_SB_DQ<29>")
	)
	(segment
		(start 129.78511 -226.50323)
		(end 129.779014 -226.506786)
		(width 0.088646)
		(layer "In4.Cu")
		(net "M_F_CPU1_SB_DQ<29>")
	)
	(segment
		(start 165.80231 -196.245226)
		(end 164.952426 -196.245226)
		(width 0.18288)
		(layer "In4.Cu")
		(net "M_F_CPU1_SB_DQ<29>")
	)
	(segment
		(start 150.320756 -205.540356)
		(end 148.366226 -210.259676)
		(width 0.18288)
		(layer "In4.Cu")
		(net "M_F_CPU1_SB_DQ<29>")
	)
	(segment
		(start 131.001516 -222.761556)
		(end 131.001516 -222.780098)
		(width 0.088646)
		(layer "In4.Cu")
		(net "M_F_CPU1_SB_DQ<29>")
	)
	(segment
		(start 162.451034 -196.93128)
		(end 160.711896 -196.93128)
		(width 0.18288)
		(layer "In4.Cu")
		(net "M_F_CPU1_SB_DQ<29>")
	)
	(segment
		(start 169.986452 -195.380356)
		(end 169.803572 -195.197476)
		(width 0.18288)
		(layer "In4.Cu")
		(net "M_F_CPU1_SB_DQ<29>")
	)
	(segment
		(start 157.717998 -196.772022)
		(end 157.36951 -196.916548)
		(width 0.18288)
		(layer "In4.Cu")
		(net "M_F_CPU1_SB_DQ<29>")
	)
	(segment
		(start 133.538468 -219.995496)
		(end 133.529578 -220.000576)
		(width 0.088646)
		(layer "In4.Cu")
		(net "M_F_CPU1_SB_DQ<29>")
	)
	(segment
		(start 166.55415 -195.14439)
		(end 166.14521 -195.14439)
		(width 0.18288)
		(layer "In4.Cu")
		(net "M_F_CPU1_SB_DQ<29>")
	)
	(segment
		(start 136.827514 -219.18168)
		(end 136.8171 -219.187776)
		(width 0.088646)
		(layer "In4.Cu")
		(net "M_F_CPU1_SB_DQ<29>")
	)
	(segment
		(start 129.653284 -226.831144)
		(end 129.966212 -226.831144)
		(width 0.088646)
		(layer "In4.Cu")
		(net "M_F_CPU1_SB_DQ<29>")
	)
	(segment
		(start 143.767048 -214.8586)
		(end 139.903962 -218.721686)
		(width 0.18288)
		(layer "In4.Cu")
		(net "M_F_CPU1_SB_DQ<29>")
	)
	(segment
		(start 134.948168 -219.18168)
		(end 134.939278 -219.18676)
		(width 0.088646)
		(layer "In4.Cu")
		(net "M_F_CPU1_SB_DQ<29>")
	)
	(segment
		(start 168.432226 -195.915026)
		(end 168.102026 -196.245226)
		(width 0.18288)
		(layer "In4.Cu")
		(net "M_F_CPU1_SB_DQ<29>")
	)
	(segment
		(start 130.240278 -224.70872)
		(end 130.249168 -224.7138)
		(width 0.088646)
		(layer "In4.Cu")
		(net "M_F_CPU1_SB_DQ<29>")
	)
	(segment
		(start 132.410962 -221.94774)
		(end 132.410962 -221.963234)
		(width 0.088646)
		(layer "In4.Cu")
		(net "M_F_CPU1_SB_DQ<29>")
	)
	(segment
		(start 139.553442 -218.721686)
		(end 139.19454 -218.721686)
		(width 0.088646)
		(layer "In4.Cu")
		(net "M_F_CPU1_SB_DQ<29>")
	)
	(segment
		(start 139.19454 -218.721686)
		(end 138.824208 -219.092018)
		(width 0.088646)
		(layer "In4.Cu")
		(net "M_F_CPU1_SB_DQ<29>")
	)
	(segment
		(start 166.751762 -196.080126)
		(end 166.751762 -195.342002)
		(width 0.18288)
		(layer "In4.Cu")
		(net "M_F_CPU1_SB_DQ<29>")
	)
	(segment
		(start 169.475912 -195.197476)
		(end 169.293032 -195.380356)
		(width 0.18288)
		(layer "In4.Cu")
		(net "M_F_CPU1_SB_DQ<29>")
	)
	(segment
		(start 166.916862 -196.245226)
		(end 166.751762 -196.080126)
		(width 0.18288)
		(layer "In4.Cu")
		(net "M_F_CPU1_SB_DQ<29>")
	)
	(segment
		(start 130.255264 -224.061528)
		(end 130.249168 -224.065084)
		(width 0.088646)
		(layer "In4.Cu")
		(net "M_F_CPU1_SB_DQ<29>")
	)
	(segment
		(start 157.36951 -196.916548)
		(end 153.478738 -200.815702)
		(width 0.18288)
		(layer "In4.Cu")
		(net "M_F_CPU1_SB_DQ<29>")
	)
	(segment
		(start 153.478738 -200.815702)
		(end 150.320756 -205.540356)
		(width 0.18288)
		(layer "In4.Cu")
		(net "M_F_CPU1_SB_DQ<29>")
	)
	(segment
		(start 139.903962 -218.721686)
		(end 139.553442 -218.721686)
		(width 0.18288)
		(layer "In4.Cu")
		(net "M_F_CPU1_SB_DQ<29>")
	)
	(segment
		(start 134.478014 -219.995496)
		(end 134.4676 -220.001592)
		(width 0.088646)
		(layer "In4.Cu")
		(net "M_F_CPU1_SB_DQ<29>")
	)
	(segment
		(start 133.068568 -220.809566)
		(end 133.059678 -220.814646)
		(width 0.088646)
		(layer "In4.Cu")
		(net "M_F_CPU1_SB_DQ<29>")
	)
	(segment
		(start 164.520626 -195.813426)
		(end 163.568888 -195.813426)
		(width 0.18288)
		(layer "In4.Cu")
		(net "M_F_CPU1_SB_DQ<29>")
	)
	(segment
		(start 130.249168 -224.065084)
		(end 130.240278 -224.070164)
		(width 0.088646)
		(layer "In4.Cu")
		(net "M_F_CPU1_SB_DQ<29>")
	)
	(segment
		(start 169.293032 -195.732146)
		(end 169.110152 -195.915026)
		(width 0.18288)
		(layer "In4.Cu")
		(net "M_F_CPU1_SB_DQ<29>")
	)
	(segment
		(start 130.249168 -225.69297)
		(end 130.240278 -225.69805)
		(width 0.088646)
		(layer "In4.Cu")
		(net "M_F_CPU1_SB_DQ<29>")
	)
	(segment
		(start 131.578096 -222.445834)
		(end 131.563364 -222.437198)
		(width 0.088646)
		(layer "In4.Cu")
		(net "M_F_CPU1_SB_DQ<29>")
	)
	(segment
		(start 169.110152 -195.915026)
		(end 168.432226 -195.915026)
		(width 0.18288)
		(layer "In4.Cu")
		(net "M_F_CPU1_SB_DQ<29>")
	)
	(segment
		(start 138.707114 -219.18168)
		(end 138.692382 -219.190316)
		(width 0.088646)
		(layer "In4.Cu")
		(net "M_F_CPU1_SB_DQ<29>")
	)
	(segment
		(start 132.60451 -221.619826)
		(end 132.598414 -221.623382)
		(width 0.088646)
		(layer "In4.Cu")
		(net "M_F_CPU1_SB_DQ<29>")
	)
	(segment
		(start 166.14521 -195.14439)
		(end 165.96233 -195.32727)
		(width 0.18288)
		(layer "In4.Cu")
		(net "M_F_CPU1_SB_DQ<29>")
	)
	(segment
		(start 132.598414 -221.623382)
		(end 132.589524 -221.628462)
		(width 0.088646)
		(layer "In4.Cu")
		(net "M_F_CPU1_SB_DQ<29>")
	)
	(segment
		(start 134.48411 -219.99194)
		(end 134.478014 -219.995496)
		(width 0.088646)
		(layer "In4.Cu")
		(net "M_F_CPU1_SB_DQ<29>")
	)
	(segment
		(start 143.767048 -214.858854)
		(end 143.767048 -214.8586)
		(width 0.18288)
		(layer "In4.Cu")
		(net "M_F_CPU1_SB_DQ<29>")
	)
	(segment
		(start 169.293032 -195.380356)
		(end 169.293032 -195.732146)
		(width 0.18288)
		(layer "In4.Cu")
		(net "M_F_CPU1_SB_DQ<29>")
	)
	(segment
		(start 163.568888 -195.813426)
		(end 162.451034 -196.93128)
		(width 0.18288)
		(layer "In4.Cu")
		(net "M_F_CPU1_SB_DQ<29>")
	)
	(segment
		(start 148.366226 -210.259676)
		(end 143.767048 -214.858854)
		(width 0.18288)
		(layer "In4.Cu")
		(net "M_F_CPU1_SB_DQ<29>")
	)
	(segment
		(start 129.596134 -226.773994)
		(end 129.653284 -226.831144)
		(width 0.088646)
		(layer "In4.Cu")
		(net "M_F_CPU1_SB_DQ<29>")
	)
	(segment
		(start 160.711896 -196.93128)
		(end 160.552638 -196.772022)
		(width 0.18288)
		(layer "In4.Cu")
		(net "M_F_CPU1_SB_DQ<29>")
	)
	(segment
		(start 137.767314 -219.18168)
		(end 137.752582 -219.190316)
		(width 0.088646)
		(layer "In4.Cu")
		(net "M_F_CPU1_SB_DQ<29>")
	)
	(segment
		(start 172.244258 -195.915026)
		(end 170.169332 -195.915026)
		(width 0.18288)
		(layer "In4.Cu")
		(net "M_F_CPU1_SB_DQ<29>")
	)
	(segment
		(start 165.96233 -196.085206)
		(end 165.80231 -196.245226)
		(width 0.18288)
		(layer "In4.Cu")
		(net "M_F_CPU1_SB_DQ<29>")
	)
	(segment
		(start 168.102026 -196.245226)
		(end 166.916862 -196.245226)
		(width 0.18288)
		(layer "In4.Cu")
		(net "M_F_CPU1_SB_DQ<29>")
	)
	(segment
		(start 133.351016 -220.319854)
		(end 133.351016 -220.338396)
		(width 0.088646)
		(layer "In4.Cu")
		(net "M_F_CPU1_SB_DQ<29>")
	)
	(segment
		(start 169.803572 -195.197476)
		(end 169.475912 -195.197476)
		(width 0.18288)
		(layer "In4.Cu")
		(net "M_F_CPU1_SB_DQ<29>")
	)
	(segment
		(start 129.779014 -226.506786)
		(end 129.770124 -226.511866)
		(width 0.088646)
		(layer "In4.Cu")
		(net "M_F_CPU1_SB_DQ<29>")
	)
	(segment
		(start 160.552638 -196.772022)
		(end 157.717998 -196.772022)
		(width 0.18288)
		(layer "In4.Cu")
		(net "M_F_CPU1_SB_DQ<29>")
	)
	(segment
		(start 131.188968 -222.437198)
		(end 131.180078 -222.442278)
		(width 0.088646)
		(layer "In4.Cu")
		(net "M_F_CPU1_SB_DQ<29>")
	)
	(segment
		(start 166.751762 -195.342002)
		(end 166.55415 -195.14439)
		(width 0.18288)
		(layer "In4.Cu")
		(net "M_F_CPU1_SB_DQ<29>")
	)
	(arc
		(start 136.8171 -219.187776)
		(mid 136.538922 -219.257499)
		(end 136.262364 -219.18168)
		(width 0.088646)
		(layer "In4.Cu")
		(net "M_F_CPU1_SB_DQ<29>")
	)
	(arc
		(start 132.410962 -221.963234)
		(mid 132.331592 -222.236968)
		(end 132.128768 -222.437198)
		(width 0.088646)
		(layer "In4.Cu")
		(net "M_F_CPU1_SB_DQ<29>")
	)
	(arc
		(start 131.180078 -222.442278)
		(mid 131.049164 -222.578638)
		(end 131.001516 -222.761556)
		(width 0.088646)
		(layer "In4.Cu")
		(net "M_F_CPU1_SB_DQ<29>")
	)
	(arc
		(start 131.001516 -222.780098)
		(mid 130.921354 -223.052287)
		(end 130.719068 -223.251268)
		(width 0.088646)
		(layer "In4.Cu")
		(net "M_F_CPU1_SB_DQ<29>")
	)
	(arc
		(start 129.770124 -226.511866)
		(mid 129.654315 -226.623795)
		(end 129.596134 -226.773994)
		(width 0.088646)
		(layer "In4.Cu")
		(net "M_F_CPU1_SB_DQ<29>")
	)
	(arc
		(start 130.061716 -226.017328)
		(mid 129.987725 -226.296894)
		(end 129.78511 -226.50323)
		(width 0.088646)
		(layer "In4.Cu")
		(net "M_F_CPU1_SB_DQ<29>")
	)
	(arc
		(start 130.710178 -223.256348)
		(mid 130.579264 -223.392708)
		(end 130.531616 -223.575626)
		(width 0.088646)
		(layer "In4.Cu")
		(net "M_F_CPU1_SB_DQ<29>")
	)
	(arc
		(start 134.760716 -219.506038)
		(mid 134.686725 -219.785604)
		(end 134.48411 -219.99194)
		(width 0.088646)
		(layer "In4.Cu")
		(net "M_F_CPU1_SB_DQ<29>")
	)
	(arc
		(start 130.249168 -224.7138)
		(mid 130.451991 -224.914031)
		(end 130.531362 -225.187764)
		(width 0.088646)
		(layer "In4.Cu")
		(net "M_F_CPU1_SB_DQ<29>")
	)
	(arc
		(start 131.563364 -222.437198)
		(mid 131.376166 -222.387055)
		(end 131.188968 -222.437198)
		(width 0.088646)
		(layer "In4.Cu")
		(net "M_F_CPU1_SB_DQ<29>")
	)
	(arc
		(start 133.351016 -220.338396)
		(mid 133.270854 -220.610585)
		(end 133.068568 -220.809566)
		(width 0.088646)
		(layer "In4.Cu")
		(net "M_F_CPU1_SB_DQ<29>")
	)
	(arc
		(start 132.589524 -221.628462)
		(mid 132.45861 -221.764822)
		(end 132.410962 -221.94774)
		(width 0.088646)
		(layer "In4.Cu")
		(net "M_F_CPU1_SB_DQ<29>")
	)
	(arc
		(start 135.887968 -219.18168)
		(mid 135.605266 -219.257456)
		(end 135.322564 -219.18168)
		(width 0.088646)
		(layer "In4.Cu")
		(net "M_F_CPU1_SB_DQ<29>")
	)
	(arc
		(start 134.4676 -220.001592)
		(mid 134.189422 -220.071315)
		(end 133.912864 -219.995496)
		(width 0.088646)
		(layer "In4.Cu")
		(net "M_F_CPU1_SB_DQ<29>")
	)
	(arc
		(start 135.322564 -219.18168)
		(mid 135.135366 -219.131537)
		(end 134.948168 -219.18168)
		(width 0.088646)
		(layer "In4.Cu")
		(net "M_F_CPU1_SB_DQ<29>")
	)
	(arc
		(start 130.240278 -224.070164)
		(mid 130.061681 -224.389442)
		(end 130.240278 -224.70872)
		(width 0.088646)
		(layer "In4.Cu")
		(net "M_F_CPU1_SB_DQ<29>")
	)
	(arc
		(start 130.531362 -225.225356)
		(mid 130.450451 -225.495484)
		(end 130.249168 -225.69297)
		(width 0.088646)
		(layer "In4.Cu")
		(net "M_F_CPU1_SB_DQ<29>")
	)
	(arc
		(start 138.7983 -219.116402)
		(mid 138.754325 -219.151301)
		(end 138.707114 -219.18168)
		(width 0.088646)
		(layer "In4.Cu")
		(net "M_F_CPU1_SB_DQ<29>")
	)
	(arc
		(start 134.939278 -219.18676)
		(mid 134.808364 -219.32312)
		(end 134.760716 -219.506038)
		(width 0.088646)
		(layer "In4.Cu")
		(net "M_F_CPU1_SB_DQ<29>")
	)
	(arc
		(start 132.128768 -222.437198)
		(mid 131.854569 -222.513033)
		(end 131.578096 -222.445834)
		(width 0.088646)
		(layer "In4.Cu")
		(net "M_F_CPU1_SB_DQ<29>")
	)
	(arc
		(start 136.262364 -219.18168)
		(mid 136.075166 -219.131537)
		(end 135.887968 -219.18168)
		(width 0.088646)
		(layer "In4.Cu")
		(net "M_F_CPU1_SB_DQ<29>")
	)
	(arc
		(start 130.531616 -223.575626)
		(mid 130.4577 -223.855128)
		(end 130.255264 -224.061528)
		(width 0.088646)
		(layer "In4.Cu")
		(net "M_F_CPU1_SB_DQ<29>")
	)
	(arc
		(start 138.824208 -219.092018)
		(mid 138.811447 -219.104415)
		(end 138.7983 -219.116402)
		(width 0.088646)
		(layer "In4.Cu")
		(net "M_F_CPU1_SB_DQ<29>")
	)
	(arc
		(start 132.881116 -221.133924)
		(mid 132.807125 -221.41349)
		(end 132.60451 -221.619826)
		(width 0.088646)
		(layer "In4.Cu")
		(net "M_F_CPU1_SB_DQ<29>")
	)
	(arc
		(start 137.752582 -219.190316)
		(mid 137.476107 -219.257636)
		(end 137.20191 -219.18168)
		(width 0.088646)
		(layer "In4.Cu")
		(net "M_F_CPU1_SB_DQ<29>")
	)
	(arc
		(start 130.240278 -225.69805)
		(mid 130.109364 -225.83441)
		(end 130.061716 -226.017328)
		(width 0.088646)
		(layer "In4.Cu")
		(net "M_F_CPU1_SB_DQ<29>")
	)
	(arc
		(start 137.20191 -219.18168)
		(mid 137.014712 -219.131537)
		(end 136.827514 -219.18168)
		(width 0.088646)
		(layer "In4.Cu")
		(net "M_F_CPU1_SB_DQ<29>")
	)
	(arc
		(start 133.059678 -220.814646)
		(mid 132.928764 -220.951006)
		(end 132.881116 -221.133924)
		(width 0.088646)
		(layer "In4.Cu")
		(net "M_F_CPU1_SB_DQ<29>")
	)
	(arc
		(start 138.692382 -219.190316)
		(mid 138.415907 -219.257636)
		(end 138.14171 -219.18168)
		(width 0.088646)
		(layer "In4.Cu")
		(net "M_F_CPU1_SB_DQ<29>")
	)
	(arc
		(start 133.529578 -220.000576)
		(mid 133.398664 -220.136936)
		(end 133.351016 -220.319854)
		(width 0.088646)
		(layer "In4.Cu")
		(net "M_F_CPU1_SB_DQ<29>")
	)
	(arc
		(start 138.14171 -219.18168)
		(mid 137.954512 -219.131537)
		(end 137.767314 -219.18168)
		(width 0.088646)
		(layer "In4.Cu")
		(net "M_F_CPU1_SB_DQ<29>")
	)
	(arc
		(start 133.912864 -219.995496)
		(mid 133.725666 -219.945353)
		(end 133.538468 -219.995496)
		(width 0.088646)
		(layer "In4.Cu")
		(net "M_F_CPU1_SB_DQ<29>")
	)
	(segment
		(start 179.011326 -197.735444)
		(end 179.004976 -197.741794)
		(width 0.1016)
		(layer "F.Cu")
		(net "M_F_CPU1_SB_DQ<28>")
	)
	(segment
		(start 176.843182 -197.741794)
		(end 176.796192 -197.741794)
		(width 0.101854)
		(layer "F.Cu")
		(net "M_F_CPU1_SB_DQ<28>")
	)
	(segment
		(start 176.333404 -198.227442)
		(end 176.145444 -198.415402)
		(width 0.20066)
		(layer "F.Cu")
		(net "M_F_CPU1_SB_DQ<28>")
	)
	(segment
		(start 179.852828 -198.16699)
		(end 179.421282 -197.735444)
		(width 0.20066)
		(layer "F.Cu")
		(net "M_F_CPU1_SB_DQ<28>")
	)
	(segment
		(start 175.421544 -198.166736)
		(end 173.900846 -198.166736)
		(width 0.20066)
		(layer "F.Cu")
		(net "M_F_CPU1_SB_DQ<28>")
	)
	(segment
		(start 181.444392 -198.16699)
		(end 179.852828 -198.16699)
		(width 0.20066)
		(layer "F.Cu")
		(net "M_F_CPU1_SB_DQ<28>")
	)
	(segment
		(start 176.451514 -197.741794)
		(end 176.333404 -197.859904)
		(width 0.20066)
		(layer "F.Cu")
		(net "M_F_CPU1_SB_DQ<28>")
	)
	(segment
		(start 176.145444 -198.415402)
		(end 175.67021 -198.415402)
		(width 0.20066)
		(layer "F.Cu")
		(net "M_F_CPU1_SB_DQ<28>")
	)
	(segment
		(start 131.846066 -227.367084)
		(end 131.845812 -227.36683)
		(width 0.20066)
		(layer "F.Cu")
		(net "M_F_CPU1_SB_DQ<28>")
	)
	(segment
		(start 176.333404 -197.859904)
		(end 176.333404 -198.227442)
		(width 0.20066)
		(layer "F.Cu")
		(net "M_F_CPU1_SB_DQ<28>")
	)
	(segment
		(start 131.845812 -227.36683)
		(end 131.845812 -226.831144)
		(width 0.20066)
		(layer "F.Cu")
		(net "M_F_CPU1_SB_DQ<28>")
	)
	(segment
		(start 181.444646 -198.166736)
		(end 181.444392 -198.16699)
		(width 0.20066)
		(layer "F.Cu")
		(net "M_F_CPU1_SB_DQ<28>")
	)
	(segment
		(start 179.421282 -197.735444)
		(end 179.011326 -197.735444)
		(width 0.20066)
		(layer "F.Cu")
		(net "M_F_CPU1_SB_DQ<28>")
	)
	(segment
		(start 173.900846 -198.166736)
		(end 172.795946 -198.166736)
		(width 0.20066)
		(layer "F.Cu")
		(net "M_F_CPU1_SB_DQ<28>")
	)
	(segment
		(start 175.67021 -198.415402)
		(end 175.421544 -198.166736)
		(width 0.20066)
		(layer "F.Cu")
		(net "M_F_CPU1_SB_DQ<28>")
	)
	(segment
		(start 176.796192 -197.741794)
		(end 176.451514 -197.741794)
		(width 0.20066)
		(layer "F.Cu")
		(net "M_F_CPU1_SB_DQ<28>")
	)
	(segment
		(start 179.004976 -197.741794)
		(end 176.843182 -197.741794)
		(width 0.1016)
		(layer "F.Cu")
		(net "M_F_CPU1_SB_DQ<28>")
	)
	(segment
		(start 167.68191 -196.880988)
		(end 166.821612 -196.880988)
		(width 0.18288)
		(layer "In4.Cu")
		(net "M_F_CPU1_SB_DQ<28>")
	)
	(segment
		(start 164.314124 -196.887592)
		(end 163.730686 -197.47103)
		(width 0.18288)
		(layer "In4.Cu")
		(net "M_F_CPU1_SB_DQ<28>")
	)
	(segment
		(start 169.599864 -197.742048)
		(end 169.272204 -197.742048)
		(width 0.18288)
		(layer "In4.Cu")
		(net "M_F_CPU1_SB_DQ<28>")
	)
	(segment
		(start 172.293026 -197.663816)
		(end 172.293026 -197.1929)
		(width 0.18288)
		(layer "In4.Cu")
		(net "M_F_CPU1_SB_DQ<28>")
	)
	(segment
		(start 132.0419 -225.522536)
		(end 132.03301 -225.527616)
		(width 0.088646)
		(layer "In4.Cu")
		(net "M_F_CPU1_SB_DQ<28>")
	)
	(segment
		(start 165.922198 -197.047612)
		(end 165.762178 -196.887592)
		(width 0.18288)
		(layer "In4.Cu")
		(net "M_F_CPU1_SB_DQ<28>")
	)
	(segment
		(start 132.03301 -224.8789)
		(end 132.0419 -224.88398)
		(width 0.088646)
		(layer "In4.Cu")
		(net "M_F_CPU1_SB_DQ<28>")
	)
	(segment
		(start 168.906444 -197.0151)
		(end 168.00576 -197.0151)
		(width 0.18288)
		(layer "In4.Cu")
		(net "M_F_CPU1_SB_DQ<28>")
	)
	(segment
		(start 134.382764 -221.458282)
		(end 134.37997 -221.459806)
		(width 0.088646)
		(layer "In4.Cu")
		(net "M_F_CPU1_SB_DQ<28>")
	)
	(segment
		(start 168.00576 -197.0151)
		(end 167.68191 -196.880988)
		(width 0.18288)
		(layer "In4.Cu")
		(net "M_F_CPU1_SB_DQ<28>")
	)
	(segment
		(start 137.767314 -219.830396)
		(end 137.752582 -219.82176)
		(width 0.088646)
		(layer "In4.Cu")
		(net "M_F_CPU1_SB_DQ<28>")
	)
	(segment
		(start 166.471092 -197.819264)
		(end 166.105332 -197.819264)
		(width 0.18288)
		(layer "In4.Cu")
		(net "M_F_CPU1_SB_DQ<28>")
	)
	(segment
		(start 148.984462 -210.345528)
		(end 140.10894 -219.22105)
		(width 0.18288)
		(layer "In4.Cu")
		(net "M_F_CPU1_SB_DQ<28>")
	)
	(segment
		(start 133.538468 -222.272098)
		(end 133.528054 -222.266002)
		(width 0.088646)
		(layer "In4.Cu")
		(net "M_F_CPU1_SB_DQ<28>")
	)
	(segment
		(start 138.707114 -219.830396)
		(end 138.692382 -219.82176)
		(width 0.088646)
		(layer "In4.Cu")
		(net "M_F_CPU1_SB_DQ<28>")
	)
	(segment
		(start 172.795946 -198.166736)
		(end 172.293026 -197.663816)
		(width 0.18288)
		(layer "In4.Cu")
		(net "M_F_CPU1_SB_DQ<28>")
	)
	(segment
		(start 165.922198 -197.63613)
		(end 165.922198 -197.047612)
		(width 0.18288)
		(layer "In4.Cu")
		(net "M_F_CPU1_SB_DQ<28>")
	)
	(segment
		(start 139.27328 -219.365322)
		(end 139.27328 -219.665042)
		(width 0.088646)
		(layer "In4.Cu")
		(net "M_F_CPU1_SB_DQ<28>")
	)
	(segment
		(start 170.986704 -198.070724)
		(end 170.659044 -198.070724)
		(width 0.18288)
		(layer "In4.Cu")
		(net "M_F_CPU1_SB_DQ<28>")
	)
	(segment
		(start 131.750816 -224.373948)
		(end 131.750816 -224.404936)
		(width 0.088646)
		(layer "In4.Cu")
		(net "M_F_CPU1_SB_DQ<28>")
	)
	(segment
		(start 139.143994 -219.794328)
		(end 139.08151 -219.830396)
		(width 0.088646)
		(layer "In4.Cu")
		(net "M_F_CPU1_SB_DQ<28>")
	)
	(segment
		(start 140.10894 -219.22105)
		(end 139.553442 -219.22105)
		(width 0.18288)
		(layer "In4.Cu")
		(net "M_F_CPU1_SB_DQ<28>")
	)
	(segment
		(start 166.821612 -196.880988)
		(end 166.661592 -197.041008)
		(width 0.18288)
		(layer "In4.Cu")
		(net "M_F_CPU1_SB_DQ<28>")
	)
	(segment
		(start 171.169584 -197.19798)
		(end 171.169584 -197.887844)
		(width 0.18288)
		(layer "In4.Cu")
		(net "M_F_CPU1_SB_DQ<28>")
	)
	(segment
		(start 132.15874 -226.831144)
		(end 131.845812 -226.831144)
		(width 0.088646)
		(layer "In4.Cu")
		(net "M_F_CPU1_SB_DQ<28>")
	)
	(segment
		(start 132.03301 -226.506786)
		(end 132.0419 -226.511866)
		(width 0.088646)
		(layer "In4.Cu")
		(net "M_F_CPU1_SB_DQ<28>")
	)
	(segment
		(start 172.293026 -197.1929)
		(end 172.115226 -197.0151)
		(width 0.18288)
		(layer "In4.Cu")
		(net "M_F_CPU1_SB_DQ<28>")
	)
	(segment
		(start 169.782744 -197.19798)
		(end 169.782744 -197.559168)
		(width 0.18288)
		(layer "In4.Cu")
		(net "M_F_CPU1_SB_DQ<28>")
	)
	(segment
		(start 170.476164 -197.19798)
		(end 170.293284 -197.0151)
		(width 0.18288)
		(layer "In4.Cu")
		(net "M_F_CPU1_SB_DQ<28>")
	)
	(segment
		(start 132.512054 -223.080834)
		(end 132.503164 -223.085914)
		(width 0.088646)
		(layer "In4.Cu")
		(net "M_F_CPU1_SB_DQ<28>")
	)
	(segment
		(start 131.750816 -225.99523)
		(end 131.750816 -226.032822)
		(width 0.088646)
		(layer "In4.Cu")
		(net "M_F_CPU1_SB_DQ<28>")
	)
	(segment
		(start 153.922476 -201.17181)
		(end 150.92934 -205.650846)
		(width 0.18288)
		(layer "In4.Cu")
		(net "M_F_CPU1_SB_DQ<28>")
	)
	(segment
		(start 172.115226 -197.0151)
		(end 171.352464 -197.0151)
		(width 0.18288)
		(layer "In4.Cu")
		(net "M_F_CPU1_SB_DQ<28>")
	)
	(segment
		(start 150.92934 -205.650846)
		(end 148.984462 -210.345528)
		(width 0.18288)
		(layer "In4.Cu")
		(net "M_F_CPU1_SB_DQ<28>")
	)
	(segment
		(start 134.100062 -221.94774)
		(end 134.100062 -221.956376)
		(width 0.088646)
		(layer "In4.Cu")
		(net "M_F_CPU1_SB_DQ<28>")
	)
	(segment
		(start 171.352464 -197.0151)
		(end 171.169584 -197.19798)
		(width 0.18288)
		(layer "In4.Cu")
		(net "M_F_CPU1_SB_DQ<28>")
	)
	(segment
		(start 169.272204 -197.742048)
		(end 169.089324 -197.559168)
		(width 0.18288)
		(layer "In4.Cu")
		(net "M_F_CPU1_SB_DQ<28>")
	)
	(segment
		(start 139.27328 -219.665042)
		(end 139.143994 -219.794328)
		(width 0.088646)
		(layer "In4.Cu")
		(net "M_F_CPU1_SB_DQ<28>")
	)
	(segment
		(start 166.661592 -197.041008)
		(end 166.661592 -197.628764)
		(width 0.18288)
		(layer "In4.Cu")
		(net "M_F_CPU1_SB_DQ<28>")
	)
	(segment
		(start 166.105332 -197.819264)
		(end 165.922198 -197.63613)
		(width 0.18288)
		(layer "In4.Cu")
		(net "M_F_CPU1_SB_DQ<28>")
	)
	(segment
		(start 132.0419 -223.894904)
		(end 132.03301 -223.899984)
		(width 0.088646)
		(layer "In4.Cu")
		(net "M_F_CPU1_SB_DQ<28>")
	)
	(segment
		(start 170.476164 -197.887844)
		(end 170.476164 -197.19798)
		(width 0.18288)
		(layer "In4.Cu")
		(net "M_F_CPU1_SB_DQ<28>")
	)
	(segment
		(start 134.8613 -220.639132)
		(end 134.85241 -220.644212)
		(width 0.088646)
		(layer "In4.Cu")
		(net "M_F_CPU1_SB_DQ<28>")
	)
	(segment
		(start 163.730686 -197.47103)
		(end 160.834832 -197.47103)
		(width 0.18288)
		(layer "In4.Cu")
		(net "M_F_CPU1_SB_DQ<28>")
	)
	(segment
		(start 157.21838 -197.875906)
		(end 153.922476 -201.17181)
		(width 0.18288)
		(layer "In4.Cu")
		(net "M_F_CPU1_SB_DQ<28>")
	)
	(segment
		(start 139.417552 -219.22105)
		(end 139.27328 -219.365322)
		(width 0.088646)
		(layer "In4.Cu")
		(net "M_F_CPU1_SB_DQ<28>")
	)
	(segment
		(start 171.169584 -197.887844)
		(end 170.986704 -198.070724)
		(width 0.18288)
		(layer "In4.Cu")
		(net "M_F_CPU1_SB_DQ<28>")
	)
	(segment
		(start 135.322564 -219.830396)
		(end 135.310372 -219.837508)
		(width 0.088646)
		(layer "In4.Cu")
		(net "M_F_CPU1_SB_DQ<28>")
	)
	(segment
		(start 169.089324 -197.559168)
		(end 169.089324 -197.19798)
		(width 0.18288)
		(layer "In4.Cu")
		(net "M_F_CPU1_SB_DQ<28>")
	)
	(segment
		(start 134.570216 -221.111826)
		(end 134.570216 -221.133924)
		(width 0.088646)
		(layer "In4.Cu")
		(net "M_F_CPU1_SB_DQ<28>")
	)
	(segment
		(start 170.659044 -198.070724)
		(end 170.476164 -197.887844)
		(width 0.18288)
		(layer "In4.Cu")
		(net "M_F_CPU1_SB_DQ<28>")
	)
	(segment
		(start 169.965624 -197.0151)
		(end 169.782744 -197.19798)
		(width 0.18288)
		(layer "In4.Cu")
		(net "M_F_CPU1_SB_DQ<28>")
	)
	(segment
		(start 134.391654 -221.453202)
		(end 134.382764 -221.458282)
		(width 0.088646)
		(layer "In4.Cu")
		(net "M_F_CPU1_SB_DQ<28>")
	)
	(segment
		(start 160.834832 -197.47103)
		(end 160.429956 -197.875906)
		(width 0.18288)
		(layer "In4.Cu")
		(net "M_F_CPU1_SB_DQ<28>")
	)
	(segment
		(start 136.827514 -219.830396)
		(end 136.8171 -219.8243)
		(width 0.088646)
		(layer "In4.Cu")
		(net "M_F_CPU1_SB_DQ<28>")
	)
	(segment
		(start 169.782744 -197.559168)
		(end 169.599864 -197.742048)
		(width 0.18288)
		(layer "In4.Cu")
		(net "M_F_CPU1_SB_DQ<28>")
	)
	(segment
		(start 134.37997 -221.459806)
		(end 134.376668 -221.461838)
		(width 0.088646)
		(layer "In4.Cu")
		(net "M_F_CPU1_SB_DQ<28>")
	)
	(segment
		(start 169.089324 -197.19798)
		(end 168.906444 -197.0151)
		(width 0.18288)
		(layer "In4.Cu")
		(net "M_F_CPU1_SB_DQ<28>")
	)
	(segment
		(start 170.293284 -197.0151)
		(end 169.965624 -197.0151)
		(width 0.18288)
		(layer "In4.Cu")
		(net "M_F_CPU1_SB_DQ<28>")
	)
	(segment
		(start 160.429956 -197.875906)
		(end 157.21838 -197.875906)
		(width 0.18288)
		(layer "In4.Cu")
		(net "M_F_CPU1_SB_DQ<28>")
	)
	(segment
		(start 139.553442 -219.22105)
		(end 139.417552 -219.22105)
		(width 0.088646)
		(layer "In4.Cu")
		(net "M_F_CPU1_SB_DQ<28>")
	)
	(segment
		(start 132.220462 -223.568006)
		(end 132.220462 -223.575626)
		(width 0.088646)
		(layer "In4.Cu")
		(net "M_F_CPU1_SB_DQ<28>")
	)
	(segment
		(start 166.661592 -197.628764)
		(end 166.471092 -197.819264)
		(width 0.18288)
		(layer "In4.Cu")
		(net "M_F_CPU1_SB_DQ<28>")
	)
	(segment
		(start 132.21589 -226.773994)
		(end 132.15874 -226.831144)
		(width 0.088646)
		(layer "In4.Cu")
		(net "M_F_CPU1_SB_DQ<28>")
	)
	(segment
		(start 132.690616 -222.746062)
		(end 132.690616 -222.761556)
		(width 0.088646)
		(layer "In4.Cu")
		(net "M_F_CPU1_SB_DQ<28>")
	)
	(segment
		(start 165.762178 -196.887592)
		(end 164.314124 -196.887592)
		(width 0.18288)
		(layer "In4.Cu")
		(net "M_F_CPU1_SB_DQ<28>")
	)
	(arc
		(start 131.750816 -224.404936)
		(mid 131.830186 -224.67867)
		(end 132.03301 -224.8789)
		(width 0.088646)
		(layer "In4.Cu")
		(net "M_F_CPU1_SB_DQ<28>")
	)
	(arc
		(start 137.20191 -219.830396)
		(mid 137.014712 -219.880539)
		(end 136.827514 -219.830396)
		(width 0.088646)
		(layer "In4.Cu")
		(net "M_F_CPU1_SB_DQ<28>")
	)
	(arc
		(start 132.690616 -222.761556)
		(mid 132.642937 -222.944456)
		(end 132.512054 -223.080834)
		(width 0.088646)
		(layer "In4.Cu")
		(net "M_F_CPU1_SB_DQ<28>")
	)
	(arc
		(start 135.310372 -219.837508)
		(mid 135.112144 -220.043356)
		(end 135.039862 -220.319854)
		(width 0.088646)
		(layer "In4.Cu")
		(net "M_F_CPU1_SB_DQ<28>")
	)
	(arc
		(start 134.376668 -221.461838)
		(mid 134.174081 -221.668189)
		(end 134.100062 -221.94774)
		(width 0.088646)
		(layer "In4.Cu")
		(net "M_F_CPU1_SB_DQ<28>")
	)
	(arc
		(start 134.100062 -221.956376)
		(mid 134.047792 -222.138741)
		(end 133.912864 -222.272098)
		(width 0.088646)
		(layer "In4.Cu")
		(net "M_F_CPU1_SB_DQ<28>")
	)
	(arc
		(start 138.692382 -219.82176)
		(mid 138.415907 -219.75444)
		(end 138.14171 -219.830396)
		(width 0.088646)
		(layer "In4.Cu")
		(net "M_F_CPU1_SB_DQ<28>")
	)
	(arc
		(start 133.912864 -222.272098)
		(mid 133.725666 -222.322241)
		(end 133.538468 -222.272098)
		(width 0.088646)
		(layer "In4.Cu")
		(net "M_F_CPU1_SB_DQ<28>")
	)
	(arc
		(start 138.14171 -219.830396)
		(mid 137.954512 -219.880539)
		(end 137.767314 -219.830396)
		(width 0.088646)
		(layer "In4.Cu")
		(net "M_F_CPU1_SB_DQ<28>")
	)
	(arc
		(start 132.0419 -226.511866)
		(mid 132.157709 -226.623795)
		(end 132.21589 -226.773994)
		(width 0.088646)
		(layer "In4.Cu")
		(net "M_F_CPU1_SB_DQ<28>")
	)
	(arc
		(start 132.97281 -222.272098)
		(mid 132.769987 -222.472329)
		(end 132.690616 -222.746062)
		(width 0.088646)
		(layer "In4.Cu")
		(net "M_F_CPU1_SB_DQ<28>")
	)
	(arc
		(start 136.8171 -219.8243)
		(mid 136.538922 -219.754577)
		(end 136.262364 -219.830396)
		(width 0.088646)
		(layer "In4.Cu")
		(net "M_F_CPU1_SB_DQ<28>")
	)
	(arc
		(start 132.0419 -224.88398)
		(mid 132.220497 -225.203258)
		(end 132.0419 -225.522536)
		(width 0.088646)
		(layer "In4.Cu")
		(net "M_F_CPU1_SB_DQ<28>")
	)
	(arc
		(start 134.570216 -221.133924)
		(mid 134.522537 -221.316824)
		(end 134.391654 -221.453202)
		(width 0.088646)
		(layer "In4.Cu")
		(net "M_F_CPU1_SB_DQ<28>")
	)
	(arc
		(start 133.528054 -222.266002)
		(mid 133.249622 -222.196156)
		(end 132.97281 -222.272098)
		(width 0.088646)
		(layer "In4.Cu")
		(net "M_F_CPU1_SB_DQ<28>")
	)
	(arc
		(start 139.08151 -219.830396)
		(mid 138.894312 -219.880539)
		(end 138.707114 -219.830396)
		(width 0.088646)
		(layer "In4.Cu")
		(net "M_F_CPU1_SB_DQ<28>")
	)
	(arc
		(start 131.750816 -226.032822)
		(mid 131.830186 -226.306556)
		(end 132.03301 -226.506786)
		(width 0.088646)
		(layer "In4.Cu")
		(net "M_F_CPU1_SB_DQ<28>")
	)
	(arc
		(start 132.220462 -223.575626)
		(mid 132.172783 -223.758526)
		(end 132.0419 -223.894904)
		(width 0.088646)
		(layer "In4.Cu")
		(net "M_F_CPU1_SB_DQ<28>")
	)
	(arc
		(start 132.03301 -225.527616)
		(mid 131.831728 -225.725103)
		(end 131.750816 -225.99523)
		(width 0.088646)
		(layer "In4.Cu")
		(net "M_F_CPU1_SB_DQ<28>")
	)
	(arc
		(start 135.039862 -220.319854)
		(mid 134.992183 -220.502754)
		(end 134.8613 -220.639132)
		(width 0.088646)
		(layer "In4.Cu")
		(net "M_F_CPU1_SB_DQ<28>")
	)
	(arc
		(start 134.85241 -220.644212)
		(mid 134.651128 -220.841699)
		(end 134.570216 -221.111826)
		(width 0.088646)
		(layer "In4.Cu")
		(net "M_F_CPU1_SB_DQ<28>")
	)
	(arc
		(start 135.887968 -219.830396)
		(mid 135.605266 -219.75462)
		(end 135.322564 -219.830396)
		(width 0.088646)
		(layer "In4.Cu")
		(net "M_F_CPU1_SB_DQ<28>")
	)
	(arc
		(start 137.752582 -219.82176)
		(mid 137.476107 -219.75444)
		(end 137.20191 -219.830396)
		(width 0.088646)
		(layer "In4.Cu")
		(net "M_F_CPU1_SB_DQ<28>")
	)
	(arc
		(start 132.503164 -223.085914)
		(mid 132.298092 -223.289593)
		(end 132.220462 -223.568006)
		(width 0.088646)
		(layer "In4.Cu")
		(net "M_F_CPU1_SB_DQ<28>")
	)
	(arc
		(start 136.262364 -219.830396)
		(mid 136.075166 -219.880539)
		(end 135.887968 -219.830396)
		(width 0.088646)
		(layer "In4.Cu")
		(net "M_F_CPU1_SB_DQ<28>")
	)
	(arc
		(start 132.03301 -223.899984)
		(mid 131.830187 -224.100215)
		(end 131.750816 -224.373948)
		(width 0.088646)
		(layer "In4.Cu")
		(net "M_F_CPU1_SB_DQ<28>")
	)
	(segment
		(start 183.340248 -201.549)
		(end 183.574436 -201.314812)
		(width 0.20066)
		(layer "F.Cu")
		(net "M_F_CPU1_SB_DQ<27>")
	)
	(segment
		(start 183.340248 -201.799952)
		(end 183.340248 -201.549)
		(width 0.20066)
		(layer "F.Cu")
		(net "M_F_CPU1_SB_DQ<27>")
	)
	(segment
		(start 182.455058 -202.003914)
		(end 183.136286 -202.003914)
		(width 0.20066)
		(layer "F.Cu")
		(net "M_F_CPU1_SB_DQ<27>")
	)
	(segment
		(start 184.210452 -201.56678)
		(end 185.544714 -201.56678)
		(width 0.20066)
		(layer "F.Cu")
		(net "M_F_CPU1_SB_DQ<27>")
	)
	(segment
		(start 183.958484 -201.314812)
		(end 184.210452 -201.56678)
		(width 0.20066)
		(layer "F.Cu")
		(net "M_F_CPU1_SB_DQ<27>")
	)
	(segment
		(start 182.442866 -201.991722)
		(end 182.455058 -202.003914)
		(width 0.1016)
		(layer "F.Cu")
		(net "M_F_CPU1_SB_DQ<27>")
	)
	(segment
		(start 183.574436 -201.314812)
		(end 183.958484 -201.314812)
		(width 0.20066)
		(layer "F.Cu")
		(net "M_F_CPU1_SB_DQ<27>")
	)
	(segment
		(start 180.434996 -201.991722)
		(end 182.442866 -201.991722)
		(width 0.1016)
		(layer "F.Cu")
		(net "M_F_CPU1_SB_DQ<27>")
	)
	(segment
		(start 180.423058 -201.998834)
		(end 180.427884 -201.998834)
		(width 0.101854)
		(layer "F.Cu")
		(net "M_F_CPU1_SB_DQ<27>")
	)
	(segment
		(start 180.131212 -201.998834)
		(end 180.423058 -201.998834)
		(width 0.20066)
		(layer "F.Cu")
		(net "M_F_CPU1_SB_DQ<27>")
	)
	(segment
		(start 176.896014 -201.56678)
		(end 178.000914 -201.56678)
		(width 0.20066)
		(layer "F.Cu")
		(net "M_F_CPU1_SB_DQ<27>")
	)
	(segment
		(start 131.846066 -228.99497)
		(end 131.845812 -228.994716)
		(width 0.20066)
		(layer "F.Cu")
		(net "M_F_CPU1_SB_DQ<27>")
	)
	(segment
		(start 180.427884 -201.998834)
		(end 180.434996 -201.991722)
		(width 0.1016)
		(layer "F.Cu")
		(net "M_F_CPU1_SB_DQ<27>")
	)
	(segment
		(start 183.136286 -202.003914)
		(end 183.340248 -201.799952)
		(width 0.20066)
		(layer "F.Cu")
		(net "M_F_CPU1_SB_DQ<27>")
	)
	(segment
		(start 179.699158 -201.56678)
		(end 180.131212 -201.998834)
		(width 0.20066)
		(layer "F.Cu")
		(net "M_F_CPU1_SB_DQ<27>")
	)
	(segment
		(start 178.000914 -201.56678)
		(end 179.699158 -201.56678)
		(width 0.20066)
		(layer "F.Cu")
		(net "M_F_CPU1_SB_DQ<27>")
	)
	(segment
		(start 131.845812 -228.994716)
		(end 131.845812 -228.45903)
		(width 0.20066)
		(layer "F.Cu")
		(net "M_F_CPU1_SB_DQ<27>")
	)
	(segment
		(start 132.503164 -228.948234)
		(end 132.463286 -228.92512)
		(width 0.088646)
		(layer "In4.Cu")
		(net "M_F_CPU1_SB_DQ<27>")
	)
	(segment
		(start 157.424374 -202.831192)
		(end 157.236922 -203.018644)
		(width 0.18288)
		(layer "In4.Cu")
		(net "M_F_CPU1_SB_DQ<27>")
	)
	(segment
		(start 139.756642 -222.631)
		(end 139.447016 -222.631)
		(width 0.088646)
		(layer "In4.Cu")
		(net "M_F_CPU1_SB_DQ<27>")
	)
	(segment
		(start 132.389372 -228.875844)
		(end 132.041138 -228.60889)
		(width 0.088646)
		(layer "In4.Cu")
		(net "M_F_CPU1_SB_DQ<27>")
	)
	(segment
		(start 176.433226 -202.885294)
		(end 176.088294 -203.230226)
		(width 0.18288)
		(layer "In4.Cu")
		(net "M_F_CPU1_SB_DQ<27>")
	)
	(segment
		(start 139.202668 -222.386652)
		(end 138.894312 -222.386652)
		(width 0.088646)
		(layer "In4.Cu")
		(net "M_F_CPU1_SB_DQ<27>")
	)
	(segment
		(start 176.433226 -202.138026)
		(end 176.433226 -202.885294)
		(width 0.18288)
		(layer "In4.Cu")
		(net "M_F_CPU1_SB_DQ<27>")
	)
	(segment
		(start 175.308006 -202.27163)
		(end 174.826422 -202.27163)
		(width 0.18288)
		(layer "In4.Cu")
		(net "M_F_CPU1_SB_DQ<27>")
	)
	(segment
		(start 136.827768 -224.065084)
		(end 136.818878 -224.070164)
		(width 0.088646)
		(layer "In4.Cu")
		(net "M_F_CPU1_SB_DQ<27>")
	)
	(segment
		(start 141.097508 -222.631)
		(end 139.756642 -222.631)
		(width 0.18288)
		(layer "In4.Cu")
		(net "M_F_CPU1_SB_DQ<27>")
	)
	(segment
		(start 137.767568 -222.437198)
		(end 137.758678 -222.442278)
		(width 0.088646)
		(layer "In4.Cu")
		(net "M_F_CPU1_SB_DQ<27>")
	)
	(segment
		(start 176.077626 -201.782426)
		(end 176.433226 -202.138026)
		(width 0.18288)
		(layer "In4.Cu")
		(net "M_F_CPU1_SB_DQ<27>")
	)
	(segment
		(start 176.088294 -203.230226)
		(end 175.628046 -203.230226)
		(width 0.18288)
		(layer "In4.Cu")
		(net "M_F_CPU1_SB_DQ<27>")
	)
	(segment
		(start 134.954264 -227.317046)
		(end 134.948168 -227.320602)
		(width 0.088646)
		(layer "In4.Cu")
		(net "M_F_CPU1_SB_DQ<27>")
	)
	(segment
		(start 137.580116 -222.761556)
		(end 137.580116 -222.77578)
		(width 0.088646)
		(layer "In4.Cu")
		(net "M_F_CPU1_SB_DQ<27>")
	)
	(segment
		(start 157.236922 -204.413866)
		(end 153.43886 -208.211928)
		(width 0.18288)
		(layer "In4.Cu")
		(net "M_F_CPU1_SB_DQ<27>")
	)
	(segment
		(start 133.072886 -228.945694)
		(end 133.068314 -228.948234)
		(width 0.088646)
		(layer "In4.Cu")
		(net "M_F_CPU1_SB_DQ<27>")
	)
	(segment
		(start 151.969724 -211.75853)
		(end 151.96947 -211.759038)
		(width 0.18288)
		(layer "In4.Cu")
		(net "M_F_CPU1_SB_DQ<27>")
	)
	(segment
		(start 176.077626 -201.325226)
		(end 176.077626 -201.782426)
		(width 0.18288)
		(layer "In4.Cu")
		(net "M_F_CPU1_SB_DQ<27>")
	)
	(segment
		(start 174.826422 -202.27163)
		(end 174.541942 -202.55611)
		(width 0.18288)
		(layer "In4.Cu")
		(net "M_F_CPU1_SB_DQ<27>")
	)
	(segment
		(start 169.667936 -203.528676)
		(end 168.502076 -203.528676)
		(width 0.18288)
		(layer "In4.Cu")
		(net "M_F_CPU1_SB_DQ<27>")
	)
	(segment
		(start 161.270188 -202.831192)
		(end 157.424374 -202.831192)
		(width 0.18288)
		(layer "In4.Cu")
		(net "M_F_CPU1_SB_DQ<27>")
	)
	(segment
		(start 132.041138 -228.60889)
		(end 131.845812 -228.45903)
		(width 0.088646)
		(layer "In4.Cu")
		(net "M_F_CPU1_SB_DQ<27>")
	)
	(segment
		(start 135.887968 -225.69297)
		(end 135.879078 -225.69805)
		(width 0.088646)
		(layer "In4.Cu")
		(net "M_F_CPU1_SB_DQ<27>")
	)
	(segment
		(start 176.230026 -201.172826)
		(end 176.077626 -201.325226)
		(width 0.18288)
		(layer "In4.Cu")
		(net "M_F_CPU1_SB_DQ<27>")
	)
	(segment
		(start 151.96947 -211.759038)
		(end 141.097508 -222.631)
		(width 0.18288)
		(layer "In4.Cu")
		(net "M_F_CPU1_SB_DQ<27>")
	)
	(segment
		(start 157.236922 -203.018644)
		(end 157.236922 -204.413866)
		(width 0.18288)
		(layer "In4.Cu")
		(net "M_F_CPU1_SB_DQ<27>")
	)
	(segment
		(start 167.804592 -202.831192)
		(end 164.674804 -202.831192)
		(width 0.18288)
		(layer "In4.Cu")
		(net "M_F_CPU1_SB_DQ<27>")
	)
	(segment
		(start 161.417508 -202.978512)
		(end 161.270188 -202.831192)
		(width 0.18288)
		(layer "In4.Cu")
		(net "M_F_CPU1_SB_DQ<27>")
	)
	(segment
		(start 136.833864 -224.061528)
		(end 136.827768 -224.065084)
		(width 0.088646)
		(layer "In4.Cu")
		(net "M_F_CPU1_SB_DQ<27>")
	)
	(segment
		(start 175.468026 -202.43165)
		(end 175.308006 -202.27163)
		(width 0.18288)
		(layer "In4.Cu")
		(net "M_F_CPU1_SB_DQ<27>")
	)
	(segment
		(start 176.896014 -201.56678)
		(end 176.50206 -201.172826)
		(width 0.18288)
		(layer "In4.Cu")
		(net "M_F_CPU1_SB_DQ<27>")
	)
	(segment
		(start 171.264834 -203.571602)
		(end 170.909742 -203.926694)
		(width 0.18288)
		(layer "In4.Cu")
		(net "M_F_CPU1_SB_DQ<27>")
	)
	(segment
		(start 136.170416 -225.203258)
		(end 136.170416 -225.2218)
		(width 0.088646)
		(layer "In4.Cu")
		(net "M_F_CPU1_SB_DQ<27>")
	)
	(segment
		(start 176.50206 -201.172826)
		(end 176.230026 -201.172826)
		(width 0.18288)
		(layer "In4.Cu")
		(net "M_F_CPU1_SB_DQ<27>")
	)
	(segment
		(start 164.674804 -202.844146)
		(end 164.540438 -202.978512)
		(width 0.18288)
		(layer "In4.Cu")
		(net "M_F_CPU1_SB_DQ<27>")
	)
	(segment
		(start 134.760716 -227.64496)
		(end 134.760716 -227.659184)
		(width 0.088646)
		(layer "In4.Cu")
		(net "M_F_CPU1_SB_DQ<27>")
	)
	(segment
		(start 175.628046 -203.230226)
		(end 175.468026 -203.070206)
		(width 0.18288)
		(layer "In4.Cu")
		(net "M_F_CPU1_SB_DQ<27>")
	)
	(segment
		(start 133.442964 -228.948488)
		(end 133.442964 -228.948234)
		(width 0.088646)
		(layer "In4.Cu")
		(net "M_F_CPU1_SB_DQ<27>")
	)
	(segment
		(start 164.674804 -202.831192)
		(end 164.674804 -202.844146)
		(width 0.18288)
		(layer "In4.Cu")
		(net "M_F_CPU1_SB_DQ<27>")
	)
	(segment
		(start 139.447016 -222.631)
		(end 139.202668 -222.386652)
		(width 0.088646)
		(layer "In4.Cu")
		(net "M_F_CPU1_SB_DQ<27>")
	)
	(segment
		(start 174.381922 -203.692252)
		(end 172.216826 -203.692252)
		(width 0.18288)
		(layer "In4.Cu")
		(net "M_F_CPU1_SB_DQ<27>")
	)
	(segment
		(start 172.096176 -203.571602)
		(end 171.264834 -203.571602)
		(width 0.18288)
		(layer "In4.Cu")
		(net "M_F_CPU1_SB_DQ<27>")
	)
	(segment
		(start 170.065954 -203.926694)
		(end 169.667936 -203.528676)
		(width 0.18288)
		(layer "In4.Cu")
		(net "M_F_CPU1_SB_DQ<27>")
	)
	(segment
		(start 136.640316 -224.389442)
		(end 136.640316 -224.399348)
		(width 0.088646)
		(layer "In4.Cu")
		(net "M_F_CPU1_SB_DQ<27>")
	)
	(segment
		(start 164.540438 -202.978512)
		(end 161.417508 -202.978512)
		(width 0.18288)
		(layer "In4.Cu")
		(net "M_F_CPU1_SB_DQ<27>")
	)
	(segment
		(start 172.216826 -203.692252)
		(end 172.096176 -203.571602)
		(width 0.18288)
		(layer "In4.Cu")
		(net "M_F_CPU1_SB_DQ<27>")
	)
	(segment
		(start 136.357868 -224.8789)
		(end 136.348978 -224.88398)
		(width 0.088646)
		(layer "In4.Cu")
		(net "M_F_CPU1_SB_DQ<27>")
	)
	(segment
		(start 134.948168 -227.320602)
		(end 134.939278 -227.325682)
		(width 0.088646)
		(layer "In4.Cu")
		(net "M_F_CPU1_SB_DQ<27>")
	)
	(segment
		(start 137.297668 -223.251268)
		(end 137.288778 -223.256348)
		(width 0.088646)
		(layer "In4.Cu")
		(net "M_F_CPU1_SB_DQ<27>")
	)
	(segment
		(start 174.541942 -203.532232)
		(end 174.381922 -203.692252)
		(width 0.18288)
		(layer "In4.Cu")
		(net "M_F_CPU1_SB_DQ<27>")
	)
	(segment
		(start 135.700516 -226.017328)
		(end 135.700516 -226.027234)
		(width 0.088646)
		(layer "In4.Cu")
		(net "M_F_CPU1_SB_DQ<27>")
	)
	(segment
		(start 175.468026 -203.070206)
		(end 175.468026 -202.43165)
		(width 0.18288)
		(layer "In4.Cu")
		(net "M_F_CPU1_SB_DQ<27>")
	)
	(segment
		(start 174.541942 -202.55611)
		(end 174.541942 -203.532232)
		(width 0.18288)
		(layer "In4.Cu")
		(net "M_F_CPU1_SB_DQ<27>")
	)
	(segment
		(start 133.068314 -228.948234)
		(end 133.060948 -228.952552)
		(width 0.088646)
		(layer "In4.Cu")
		(net "M_F_CPU1_SB_DQ<27>")
	)
	(segment
		(start 153.43886 -208.211928)
		(end 151.969724 -211.75853)
		(width 0.18288)
		(layer "In4.Cu")
		(net "M_F_CPU1_SB_DQ<27>")
	)
	(segment
		(start 135.418068 -226.506786)
		(end 135.409178 -226.511866)
		(width 0.088646)
		(layer "In4.Cu")
		(net "M_F_CPU1_SB_DQ<27>")
	)
	(segment
		(start 168.502076 -203.528676)
		(end 167.804592 -202.831192)
		(width 0.18288)
		(layer "In4.Cu")
		(net "M_F_CPU1_SB_DQ<27>")
	)
	(segment
		(start 134.290816 -228.450394)
		(end 134.290816 -228.468936)
		(width 0.088646)
		(layer "In4.Cu")
		(net "M_F_CPU1_SB_DQ<27>")
	)
	(segment
		(start 170.909742 -203.926694)
		(end 170.065954 -203.926694)
		(width 0.18288)
		(layer "In4.Cu")
		(net "M_F_CPU1_SB_DQ<27>")
	)
	(arc
		(start 135.879078 -225.69805)
		(mid 135.748164 -225.83441)
		(end 135.700516 -226.017328)
		(width 0.088646)
		(layer "In4.Cu")
		(net "M_F_CPU1_SB_DQ<27>")
	)
	(arc
		(start 134.760716 -227.659184)
		(mid 134.681497 -227.933869)
		(end 134.478014 -228.134672)
		(width 0.088646)
		(layer "In4.Cu")
		(net "M_F_CPU1_SB_DQ<27>")
	)
	(arc
		(start 137.288778 -223.256348)
		(mid 137.157864 -223.392708)
		(end 137.110216 -223.575626)
		(width 0.088646)
		(layer "In4.Cu")
		(net "M_F_CPU1_SB_DQ<27>")
	)
	(arc
		(start 138.141964 -222.437198)
		(mid 137.954766 -222.387055)
		(end 137.767568 -222.437198)
		(width 0.088646)
		(layer "In4.Cu")
		(net "M_F_CPU1_SB_DQ<27>")
	)
	(arc
		(start 136.818878 -224.070164)
		(mid 136.687964 -224.206524)
		(end 136.640316 -224.389442)
		(width 0.088646)
		(layer "In4.Cu")
		(net "M_F_CPU1_SB_DQ<27>")
	)
	(arc
		(start 137.758678 -222.442278)
		(mid 137.627764 -222.578638)
		(end 137.580116 -222.761556)
		(width 0.088646)
		(layer "In4.Cu")
		(net "M_F_CPU1_SB_DQ<27>")
	)
	(arc
		(start 135.700516 -226.027234)
		(mid 135.622405 -226.304183)
		(end 135.418068 -226.506786)
		(width 0.088646)
		(layer "In4.Cu")
		(net "M_F_CPU1_SB_DQ<27>")
	)
	(arc
		(start 136.640316 -224.399348)
		(mid 136.562205 -224.676297)
		(end 136.357868 -224.8789)
		(width 0.088646)
		(layer "In4.Cu")
		(net "M_F_CPU1_SB_DQ<27>")
	)
	(arc
		(start 136.170416 -225.2218)
		(mid 136.090254 -225.493989)
		(end 135.887968 -225.69297)
		(width 0.088646)
		(layer "In4.Cu")
		(net "M_F_CPU1_SB_DQ<27>")
	)
	(arc
		(start 137.580116 -222.77578)
		(mid 137.500975 -223.050403)
		(end 137.297668 -223.251268)
		(width 0.088646)
		(layer "In4.Cu")
		(net "M_F_CPU1_SB_DQ<27>")
	)
	(arc
		(start 135.230616 -226.831144)
		(mid 135.1567 -227.110646)
		(end 134.954264 -227.317046)
		(width 0.088646)
		(layer "In4.Cu")
		(net "M_F_CPU1_SB_DQ<27>")
	)
	(arc
		(start 132.463286 -228.92512)
		(mid 132.425519 -228.901697)
		(end 132.389372 -228.875844)
		(width 0.088646)
		(layer "In4.Cu")
		(net "M_F_CPU1_SB_DQ<27>")
	)
	(arc
		(start 134.290816 -228.468936)
		(mid 134.212705 -228.745885)
		(end 134.008368 -228.948488)
		(width 0.088646)
		(layer "In4.Cu")
		(net "M_F_CPU1_SB_DQ<27>")
	)
	(arc
		(start 137.110216 -223.575626)
		(mid 137.0363 -223.855128)
		(end 136.833864 -224.061528)
		(width 0.088646)
		(layer "In4.Cu")
		(net "M_F_CPU1_SB_DQ<27>")
	)
	(arc
		(start 134.939278 -227.325682)
		(mid 134.808364 -227.462042)
		(end 134.760716 -227.64496)
		(width 0.088646)
		(layer "In4.Cu")
		(net "M_F_CPU1_SB_DQ<27>")
	)
	(arc
		(start 134.008368 -228.948488)
		(mid 133.725666 -229.024264)
		(end 133.442964 -228.948488)
		(width 0.088646)
		(layer "In4.Cu")
		(net "M_F_CPU1_SB_DQ<27>")
	)
	(arc
		(start 133.060948 -228.952552)
		(mid 132.781487 -229.024021)
		(end 132.503164 -228.948234)
		(width 0.088646)
		(layer "In4.Cu")
		(net "M_F_CPU1_SB_DQ<27>")
	)
	(arc
		(start 135.409178 -226.511866)
		(mid 135.278264 -226.648226)
		(end 135.230616 -226.831144)
		(width 0.088646)
		(layer "In4.Cu")
		(net "M_F_CPU1_SB_DQ<27>")
	)
	(arc
		(start 136.348978 -224.88398)
		(mid 136.218064 -225.02034)
		(end 136.170416 -225.203258)
		(width 0.088646)
		(layer "In4.Cu")
		(net "M_F_CPU1_SB_DQ<27>")
	)
	(arc
		(start 138.6967 -222.443294)
		(mid 138.418522 -222.513017)
		(end 138.141964 -222.437198)
		(width 0.088646)
		(layer "In4.Cu")
		(net "M_F_CPU1_SB_DQ<27>")
	)
	(arc
		(start 138.894312 -222.386652)
		(mid 138.79155 -222.401166)
		(end 138.6967 -222.443294)
		(width 0.088646)
		(layer "In4.Cu")
		(net "M_F_CPU1_SB_DQ<27>")
	)
	(arc
		(start 134.478014 -228.134672)
		(mid 134.343081 -228.268026)
		(end 134.290816 -228.450394)
		(width 0.088646)
		(layer "In4.Cu")
		(net "M_F_CPU1_SB_DQ<27>")
	)
	(arc
		(start 133.442964 -228.948234)
		(mid 133.25827 -228.898133)
		(end 133.072886 -228.945694)
		(width 0.088646)
		(layer "In4.Cu")
		(net "M_F_CPU1_SB_DQ<27>")
	)
	(segment
		(start 183.574436 -203.014834)
		(end 183.958484 -203.014834)
		(width 0.20066)
		(layer "F.Cu")
		(net "M_F_CPU1_SB_DQ<26>")
	)
	(segment
		(start 179.699158 -203.266802)
		(end 180.131212 -203.698856)
		(width 0.20066)
		(layer "F.Cu")
		(net "M_F_CPU1_SB_DQ<26>")
	)
	(segment
		(start 183.340248 -203.499974)
		(end 183.340248 -203.249022)
		(width 0.20066)
		(layer "F.Cu")
		(net "M_F_CPU1_SB_DQ<26>")
	)
	(segment
		(start 182.455058 -203.703936)
		(end 183.136286 -203.703936)
		(width 0.20066)
		(layer "F.Cu")
		(net "M_F_CPU1_SB_DQ<26>")
	)
	(segment
		(start 180.423058 -203.698856)
		(end 180.427884 -203.698856)
		(width 0.101854)
		(layer "F.Cu")
		(net "M_F_CPU1_SB_DQ<26>")
	)
	(segment
		(start 178.000914 -203.266802)
		(end 179.699158 -203.266802)
		(width 0.20066)
		(layer "F.Cu")
		(net "M_F_CPU1_SB_DQ<26>")
	)
	(segment
		(start 131.375912 -229.808786)
		(end 131.376166 -229.808532)
		(width 0.20066)
		(layer "F.Cu")
		(net "M_F_CPU1_SB_DQ<26>")
	)
	(segment
		(start 183.958484 -203.014834)
		(end 184.210452 -203.266802)
		(width 0.20066)
		(layer "F.Cu")
		(net "M_F_CPU1_SB_DQ<26>")
	)
	(segment
		(start 180.131212 -203.698856)
		(end 180.423058 -203.698856)
		(width 0.20066)
		(layer "F.Cu")
		(net "M_F_CPU1_SB_DQ<26>")
	)
	(segment
		(start 176.896014 -203.266802)
		(end 178.000914 -203.266802)
		(width 0.20066)
		(layer "F.Cu")
		(net "M_F_CPU1_SB_DQ<26>")
	)
	(segment
		(start 180.434996 -203.691744)
		(end 182.442866 -203.691744)
		(width 0.1016)
		(layer "F.Cu")
		(net "M_F_CPU1_SB_DQ<26>")
	)
	(segment
		(start 184.210452 -203.266802)
		(end 185.544714 -203.266802)
		(width 0.20066)
		(layer "F.Cu")
		(net "M_F_CPU1_SB_DQ<26>")
	)
	(segment
		(start 183.340248 -203.249022)
		(end 183.574436 -203.014834)
		(width 0.20066)
		(layer "F.Cu")
		(net "M_F_CPU1_SB_DQ<26>")
	)
	(segment
		(start 183.136286 -203.703936)
		(end 183.340248 -203.499974)
		(width 0.20066)
		(layer "F.Cu")
		(net "M_F_CPU1_SB_DQ<26>")
	)
	(segment
		(start 180.427884 -203.698856)
		(end 180.434996 -203.691744)
		(width 0.1016)
		(layer "F.Cu")
		(net "M_F_CPU1_SB_DQ<26>")
	)
	(segment
		(start 131.376166 -229.808532)
		(end 131.376166 -229.272846)
		(width 0.20066)
		(layer "F.Cu")
		(net "M_F_CPU1_SB_DQ<26>")
	)
	(segment
		(start 182.442866 -203.691744)
		(end 182.455058 -203.703936)
		(width 0.1016)
		(layer "F.Cu")
		(net "M_F_CPU1_SB_DQ<26>")
	)
	(segment
		(start 172.988732 -205.39202)
		(end 172.609764 -205.39202)
		(width 0.18288)
		(layer "In4.Cu")
		(net "M_F_CPU1_SB_DQ<26>")
	)
	(segment
		(start 158.36773 -206.218028)
		(end 156.91739 -206.218028)
		(width 0.18288)
		(layer "In4.Cu")
		(net "M_F_CPU1_SB_DQ<26>")
	)
	(segment
		(start 136.640316 -226.008692)
		(end 136.640316 -226.027234)
		(width 0.088646)
		(layer "In4.Cu")
		(net "M_F_CPU1_SB_DQ<26>")
	)
	(segment
		(start 132.978906 -229.765606)
		(end 132.973064 -229.762304)
		(width 0.088646)
		(layer "In4.Cu")
		(net "M_F_CPU1_SB_DQ<26>")
	)
	(segment
		(start 154.66441 -208.471008)
		(end 153.248868 -211.887816)
		(width 0.18288)
		(layer "In4.Cu")
		(net "M_F_CPU1_SB_DQ<26>")
	)
	(segment
		(start 138.796268 -223.359218)
		(end 138.611864 -223.251268)
		(width 0.088646)
		(layer "In4.Cu")
		(net "M_F_CPU1_SB_DQ<26>")
	)
	(segment
		(start 172.609764 -205.39202)
		(end 172.53077 -205.313026)
		(width 0.18288)
		(layer "In4.Cu")
		(net "M_F_CPU1_SB_DQ<26>")
	)
	(segment
		(start 131.896612 -229.675436)
		(end 131.376166 -229.272846)
		(width 0.088646)
		(layer "In4.Cu")
		(net "M_F_CPU1_SB_DQ<26>")
	)
	(segment
		(start 138.237468 -223.251268)
		(end 138.228578 -223.256348)
		(width 0.088646)
		(layer "In4.Cu")
		(net "M_F_CPU1_SB_DQ<26>")
	)
	(segment
		(start 137.297668 -224.8789)
		(end 137.288778 -224.88398)
		(width 0.088646)
		(layer "In4.Cu")
		(net "M_F_CPU1_SB_DQ<26>")
	)
	(segment
		(start 136.357868 -226.506786)
		(end 136.348978 -226.511866)
		(width 0.088646)
		(layer "In4.Cu")
		(net "M_F_CPU1_SB_DQ<26>")
	)
	(segment
		(start 141.493748 -223.642936)
		(end 139.756642 -223.642936)
		(width 0.18288)
		(layer "In4.Cu")
		(net "M_F_CPU1_SB_DQ<26>")
	)
	(segment
		(start 176.896014 -203.266802)
		(end 176.3903 -203.772516)
		(width 0.18288)
		(layer "In4.Cu")
		(net "M_F_CPU1_SB_DQ<26>")
	)
	(segment
		(start 167.188134 -205.567026)
		(end 166.799514 -205.178406)
		(width 0.18288)
		(layer "In4.Cu")
		(net "M_F_CPU1_SB_DQ<26>")
	)
	(segment
		(start 166.799514 -205.178406)
		(end 166.799514 -204.552042)
		(width 0.18288)
		(layer "In4.Cu")
		(net "M_F_CPU1_SB_DQ<26>")
	)
	(segment
		(start 133.912864 -229.762304)
		(end 133.908546 -229.759764)
		(width 0.088646)
		(layer "In4.Cu")
		(net "M_F_CPU1_SB_DQ<26>")
	)
	(segment
		(start 137.767568 -224.065084)
		(end 137.758678 -224.070164)
		(width 0.088646)
		(layer "In4.Cu")
		(net "M_F_CPU1_SB_DQ<26>")
	)
	(segment
		(start 176.3903 -203.772516)
		(end 176.3903 -205.19517)
		(width 0.18288)
		(layer "In4.Cu")
		(net "M_F_CPU1_SB_DQ<26>")
	)
	(segment
		(start 160.964626 -205.668626)
		(end 158.917132 -205.668626)
		(width 0.18288)
		(layer "In4.Cu")
		(net "M_F_CPU1_SB_DQ<26>")
	)
	(segment
		(start 175.716438 -205.360778)
		(end 175.544226 -205.188566)
		(width 0.18288)
		(layer "In4.Cu")
		(net "M_F_CPU1_SB_DQ<26>")
	)
	(segment
		(start 166.799514 -204.552042)
		(end 166.616634 -204.369162)
		(width 0.18288)
		(layer "In4.Cu")
		(net "M_F_CPU1_SB_DQ<26>")
	)
	(segment
		(start 175.544226 -205.188566)
		(end 175.544226 -204.482446)
		(width 0.18288)
		(layer "In4.Cu")
		(net "M_F_CPU1_SB_DQ<26>")
	)
	(segment
		(start 166.242238 -204.369162)
		(end 166.059358 -204.552042)
		(width 0.18288)
		(layer "In4.Cu")
		(net "M_F_CPU1_SB_DQ<26>")
	)
	(segment
		(start 139.756642 -223.642936)
		(end 139.079986 -223.642936)
		(width 0.088646)
		(layer "In4.Cu")
		(net "M_F_CPU1_SB_DQ<26>")
	)
	(segment
		(start 156.91739 -206.218028)
		(end 154.66441 -208.471008)
		(width 0.18288)
		(layer "In4.Cu")
		(net "M_F_CPU1_SB_DQ<26>")
	)
	(segment
		(start 139.079986 -223.642936)
		(end 138.796268 -223.359218)
		(width 0.088646)
		(layer "In4.Cu")
		(net "M_F_CPU1_SB_DQ<26>")
	)
	(segment
		(start 176.3903 -205.19517)
		(end 176.224692 -205.360778)
		(width 0.18288)
		(layer "In4.Cu")
		(net "M_F_CPU1_SB_DQ<26>")
	)
	(segment
		(start 136.170416 -226.831144)
		(end 136.170416 -226.84105)
		(width 0.088646)
		(layer "In4.Cu")
		(net "M_F_CPU1_SB_DQ<26>")
	)
	(segment
		(start 134.948168 -228.948488)
		(end 134.939278 -228.953568)
		(width 0.088646)
		(layer "In4.Cu")
		(net "M_F_CPU1_SB_DQ<26>")
	)
	(segment
		(start 163.509452 -205.313026)
		(end 163.160202 -205.662276)
		(width 0.18288)
		(layer "In4.Cu")
		(net "M_F_CPU1_SB_DQ<26>")
	)
	(segment
		(start 132.973064 -229.762304)
		(end 132.967222 -229.758748)
		(width 0.088646)
		(layer "In4.Cu")
		(net "M_F_CPU1_SB_DQ<26>")
	)
	(segment
		(start 162.466782 -205.313026)
		(end 161.320226 -205.313026)
		(width 0.18288)
		(layer "In4.Cu")
		(net "M_F_CPU1_SB_DQ<26>")
	)
	(segment
		(start 166.616634 -204.369162)
		(end 166.242238 -204.369162)
		(width 0.18288)
		(layer "In4.Cu")
		(net "M_F_CPU1_SB_DQ<26>")
	)
	(segment
		(start 162.816032 -205.662276)
		(end 162.466782 -205.313026)
		(width 0.18288)
		(layer "In4.Cu")
		(net "M_F_CPU1_SB_DQ<26>")
	)
	(segment
		(start 135.887968 -227.320602)
		(end 135.879078 -227.325682)
		(width 0.088646)
		(layer "In4.Cu")
		(net "M_F_CPU1_SB_DQ<26>")
	)
	(segment
		(start 176.224692 -205.360778)
		(end 175.716438 -205.360778)
		(width 0.18288)
		(layer "In4.Cu")
		(net "M_F_CPU1_SB_DQ<26>")
	)
	(segment
		(start 132.039106 -229.765606)
		(end 132.033264 -229.762304)
		(width 0.088646)
		(layer "In4.Cu")
		(net "M_F_CPU1_SB_DQ<26>")
	)
	(segment
		(start 165.717474 -205.592426)
		(end 164.920422 -205.592426)
		(width 0.18288)
		(layer "In4.Cu")
		(net "M_F_CPU1_SB_DQ<26>")
	)
	(segment
		(start 134.478268 -229.762304)
		(end 134.478014 -229.762304)
		(width 0.088646)
		(layer "In4.Cu")
		(net "M_F_CPU1_SB_DQ<26>")
	)
	(segment
		(start 135.418068 -228.134672)
		(end 135.409178 -228.139752)
		(width 0.088646)
		(layer "In4.Cu")
		(net "M_F_CPU1_SB_DQ<26>")
	)
	(segment
		(start 137.580116 -224.389442)
		(end 137.580116 -224.399348)
		(width 0.088646)
		(layer "In4.Cu")
		(net "M_F_CPU1_SB_DQ<26>")
	)
	(segment
		(start 172.53077 -205.313026)
		(end 168.330626 -205.313026)
		(width 0.18288)
		(layer "In4.Cu")
		(net "M_F_CPU1_SB_DQ<26>")
	)
	(segment
		(start 164.920422 -205.592426)
		(end 164.641022 -205.313026)
		(width 0.18288)
		(layer "In4.Cu")
		(net "M_F_CPU1_SB_DQ<26>")
	)
	(segment
		(start 138.050016 -223.575626)
		(end 138.050016 -223.585532)
		(width 0.088646)
		(layer "In4.Cu")
		(net "M_F_CPU1_SB_DQ<26>")
	)
	(segment
		(start 164.641022 -205.313026)
		(end 163.509452 -205.313026)
		(width 0.18288)
		(layer "In4.Cu")
		(net "M_F_CPU1_SB_DQ<26>")
	)
	(segment
		(start 135.700516 -227.64496)
		(end 135.700516 -227.663502)
		(width 0.088646)
		(layer "In4.Cu")
		(net "M_F_CPU1_SB_DQ<26>")
	)
	(segment
		(start 166.059358 -205.250542)
		(end 165.717474 -205.592426)
		(width 0.18288)
		(layer "In4.Cu")
		(net "M_F_CPU1_SB_DQ<26>")
	)
	(segment
		(start 137.110216 -225.203258)
		(end 137.110216 -225.217482)
		(width 0.088646)
		(layer "In4.Cu")
		(net "M_F_CPU1_SB_DQ<26>")
	)
	(segment
		(start 174.177706 -204.203046)
		(end 172.988732 -205.39202)
		(width 0.18288)
		(layer "In4.Cu")
		(net "M_F_CPU1_SB_DQ<26>")
	)
	(segment
		(start 158.917132 -205.668626)
		(end 158.36773 -206.218028)
		(width 0.18288)
		(layer "In4.Cu")
		(net "M_F_CPU1_SB_DQ<26>")
	)
	(segment
		(start 168.330626 -205.313026)
		(end 168.076626 -205.567026)
		(width 0.18288)
		(layer "In4.Cu")
		(net "M_F_CPU1_SB_DQ<26>")
	)
	(segment
		(start 163.160202 -205.662276)
		(end 162.816032 -205.662276)
		(width 0.18288)
		(layer "In4.Cu")
		(net "M_F_CPU1_SB_DQ<26>")
	)
	(segment
		(start 132.033264 -229.762304)
		(end 131.970272 -229.72522)
		(width 0.088646)
		(layer "In4.Cu")
		(net "M_F_CPU1_SB_DQ<26>")
	)
	(segment
		(start 134.954264 -228.944932)
		(end 134.948168 -228.948488)
		(width 0.088646)
		(layer "In4.Cu")
		(net "M_F_CPU1_SB_DQ<26>")
	)
	(segment
		(start 175.544226 -204.482446)
		(end 175.264826 -204.203046)
		(width 0.18288)
		(layer "In4.Cu")
		(net "M_F_CPU1_SB_DQ<26>")
	)
	(segment
		(start 175.264826 -204.203046)
		(end 174.177706 -204.203046)
		(width 0.18288)
		(layer "In4.Cu")
		(net "M_F_CPU1_SB_DQ<26>")
	)
	(segment
		(start 153.248868 -211.887816)
		(end 141.493748 -223.642936)
		(width 0.18288)
		(layer "In4.Cu")
		(net "M_F_CPU1_SB_DQ<26>")
	)
	(segment
		(start 134.760716 -229.272846)
		(end 134.760716 -229.282752)
		(width 0.088646)
		(layer "In4.Cu")
		(net "M_F_CPU1_SB_DQ<26>")
	)
	(segment
		(start 161.320226 -205.313026)
		(end 160.964626 -205.668626)
		(width 0.18288)
		(layer "In4.Cu")
		(net "M_F_CPU1_SB_DQ<26>")
	)
	(segment
		(start 166.059358 -204.552042)
		(end 166.059358 -205.250542)
		(width 0.18288)
		(layer "In4.Cu")
		(net "M_F_CPU1_SB_DQ<26>")
	)
	(segment
		(start 168.076626 -205.567026)
		(end 167.188134 -205.567026)
		(width 0.18288)
		(layer "In4.Cu")
		(net "M_F_CPU1_SB_DQ<26>")
	)
	(arc
		(start 136.170416 -226.84105)
		(mid 136.092305 -227.117999)
		(end 135.887968 -227.320602)
		(width 0.088646)
		(layer "In4.Cu")
		(net "M_F_CPU1_SB_DQ<26>")
	)
	(arc
		(start 137.580116 -224.399348)
		(mid 137.502005 -224.676297)
		(end 137.297668 -224.8789)
		(width 0.088646)
		(layer "In4.Cu")
		(net "M_F_CPU1_SB_DQ<26>")
	)
	(arc
		(start 135.409178 -228.139752)
		(mid 135.278264 -228.276112)
		(end 135.230616 -228.45903)
		(width 0.088646)
		(layer "In4.Cu")
		(net "M_F_CPU1_SB_DQ<26>")
	)
	(arc
		(start 135.879078 -227.325682)
		(mid 135.748164 -227.462042)
		(end 135.700516 -227.64496)
		(width 0.088646)
		(layer "In4.Cu")
		(net "M_F_CPU1_SB_DQ<26>")
	)
	(arc
		(start 134.478014 -229.762304)
		(mid 134.195456 -229.837953)
		(end 133.912864 -229.762304)
		(width 0.088646)
		(layer "In4.Cu")
		(net "M_F_CPU1_SB_DQ<26>")
	)
	(arc
		(start 132.598414 -229.762304)
		(mid 132.319211 -229.837944)
		(end 132.039106 -229.765606)
		(width 0.088646)
		(layer "In4.Cu")
		(net "M_F_CPU1_SB_DQ<26>")
	)
	(arc
		(start 132.967222 -229.758748)
		(mid 132.782337 -229.711955)
		(end 132.598414 -229.762304)
		(width 0.088646)
		(layer "In4.Cu")
		(net "M_F_CPU1_SB_DQ<26>")
	)
	(arc
		(start 134.939278 -228.953568)
		(mid 134.808364 -229.089928)
		(end 134.760716 -229.272846)
		(width 0.088646)
		(layer "In4.Cu")
		(net "M_F_CPU1_SB_DQ<26>")
	)
	(arc
		(start 136.640316 -226.027234)
		(mid 136.562205 -226.304183)
		(end 136.357868 -226.506786)
		(width 0.088646)
		(layer "In4.Cu")
		(net "M_F_CPU1_SB_DQ<26>")
	)
	(arc
		(start 135.700516 -227.663502)
		(mid 135.620354 -227.935691)
		(end 135.418068 -228.134672)
		(width 0.088646)
		(layer "In4.Cu")
		(net "M_F_CPU1_SB_DQ<26>")
	)
	(arc
		(start 138.611864 -223.251268)
		(mid 138.424666 -223.201125)
		(end 138.237468 -223.251268)
		(width 0.088646)
		(layer "In4.Cu")
		(net "M_F_CPU1_SB_DQ<26>")
	)
	(arc
		(start 136.827514 -225.69297)
		(mid 136.692581 -225.826324)
		(end 136.640316 -226.008692)
		(width 0.088646)
		(layer "In4.Cu")
		(net "M_F_CPU1_SB_DQ<26>")
	)
	(arc
		(start 135.230616 -228.45903)
		(mid 135.1567 -228.738532)
		(end 134.954264 -228.944932)
		(width 0.088646)
		(layer "In4.Cu")
		(net "M_F_CPU1_SB_DQ<26>")
	)
	(arc
		(start 134.760716 -229.282752)
		(mid 134.682605 -229.559701)
		(end 134.478268 -229.762304)
		(width 0.088646)
		(layer "In4.Cu")
		(net "M_F_CPU1_SB_DQ<26>")
	)
	(arc
		(start 136.348978 -226.511866)
		(mid 136.218064 -226.648226)
		(end 136.170416 -226.831144)
		(width 0.088646)
		(layer "In4.Cu")
		(net "M_F_CPU1_SB_DQ<26>")
	)
	(arc
		(start 137.288778 -224.88398)
		(mid 137.157864 -225.02034)
		(end 137.110216 -225.203258)
		(width 0.088646)
		(layer "In4.Cu")
		(net "M_F_CPU1_SB_DQ<26>")
	)
	(arc
		(start 138.050016 -223.585532)
		(mid 137.971905 -223.862481)
		(end 137.767568 -224.065084)
		(width 0.088646)
		(layer "In4.Cu")
		(net "M_F_CPU1_SB_DQ<26>")
	)
	(arc
		(start 133.538214 -229.762304)
		(mid 133.259011 -229.837944)
		(end 132.978906 -229.765606)
		(width 0.088646)
		(layer "In4.Cu")
		(net "M_F_CPU1_SB_DQ<26>")
	)
	(arc
		(start 138.228578 -223.256348)
		(mid 138.097664 -223.392708)
		(end 138.050016 -223.575626)
		(width 0.088646)
		(layer "In4.Cu")
		(net "M_F_CPU1_SB_DQ<26>")
	)
	(arc
		(start 137.758678 -224.070164)
		(mid 137.627764 -224.206524)
		(end 137.580116 -224.389442)
		(width 0.088646)
		(layer "In4.Cu")
		(net "M_F_CPU1_SB_DQ<26>")
	)
	(arc
		(start 131.970272 -229.72522)
		(mid 131.932661 -229.701483)
		(end 131.896612 -229.675436)
		(width 0.088646)
		(layer "In4.Cu")
		(net "M_F_CPU1_SB_DQ<26>")
	)
	(arc
		(start 133.908546 -229.759764)
		(mid 133.723051 -229.712095)
		(end 133.538214 -229.762304)
		(width 0.088646)
		(layer "In4.Cu")
		(net "M_F_CPU1_SB_DQ<26>")
	)
	(arc
		(start 137.110216 -225.217482)
		(mid 137.030997 -225.492167)
		(end 136.827514 -225.69297)
		(width 0.088646)
		(layer "In4.Cu")
		(net "M_F_CPU1_SB_DQ<26>")
	)
	(segment
		(start 176.451514 -201.991722)
		(end 176.333404 -202.109832)
		(width 0.20066)
		(layer "F.Cu")
		(net "M_F_CPU1_SB_DQ<25>")
	)
	(segment
		(start 176.796192 -201.991722)
		(end 176.451514 -201.991722)
		(width 0.20066)
		(layer "F.Cu")
		(net "M_F_CPU1_SB_DQ<25>")
	)
	(segment
		(start 175.421544 -202.416664)
		(end 173.900846 -202.416664)
		(width 0.20066)
		(layer "F.Cu")
		(net "M_F_CPU1_SB_DQ<25>")
	)
	(segment
		(start 129.966466 -228.99497)
		(end 129.966212 -228.994716)
		(width 0.20066)
		(layer "F.Cu")
		(net "M_F_CPU1_SB_DQ<25>")
	)
	(segment
		(start 176.816258 -201.991722)
		(end 176.796192 -201.991722)
		(width 0.101854)
		(layer "F.Cu")
		(net "M_F_CPU1_SB_DQ<25>")
	)
	(segment
		(start 179.011326 -201.985372)
		(end 179.004976 -201.991722)
		(width 0.1016)
		(layer "F.Cu")
		(net "M_F_CPU1_SB_DQ<25>")
	)
	(segment
		(start 179.852828 -202.416918)
		(end 179.421282 -201.985372)
		(width 0.20066)
		(layer "F.Cu")
		(net "M_F_CPU1_SB_DQ<25>")
	)
	(segment
		(start 176.145444 -202.66533)
		(end 175.67021 -202.66533)
		(width 0.20066)
		(layer "F.Cu")
		(net "M_F_CPU1_SB_DQ<25>")
	)
	(segment
		(start 179.004976 -201.991722)
		(end 176.816258 -201.991722)
		(width 0.1016)
		(layer "F.Cu")
		(net "M_F_CPU1_SB_DQ<25>")
	)
	(segment
		(start 176.333404 -202.109832)
		(end 176.333404 -202.47737)
		(width 0.20066)
		(layer "F.Cu")
		(net "M_F_CPU1_SB_DQ<25>")
	)
	(segment
		(start 176.333404 -202.47737)
		(end 176.145444 -202.66533)
		(width 0.20066)
		(layer "F.Cu")
		(net "M_F_CPU1_SB_DQ<25>")
	)
	(segment
		(start 179.421282 -201.985372)
		(end 179.011326 -201.985372)
		(width 0.20066)
		(layer "F.Cu")
		(net "M_F_CPU1_SB_DQ<25>")
	)
	(segment
		(start 181.444392 -202.416918)
		(end 179.852828 -202.416918)
		(width 0.20066)
		(layer "F.Cu")
		(net "M_F_CPU1_SB_DQ<25>")
	)
	(segment
		(start 173.900846 -202.416664)
		(end 172.795946 -202.416664)
		(width 0.20066)
		(layer "F.Cu")
		(net "M_F_CPU1_SB_DQ<25>")
	)
	(segment
		(start 175.67021 -202.66533)
		(end 175.421544 -202.416664)
		(width 0.20066)
		(layer "F.Cu")
		(net "M_F_CPU1_SB_DQ<25>")
	)
	(segment
		(start 129.966212 -228.994716)
		(end 129.966212 -228.45903)
		(width 0.20066)
		(layer "F.Cu")
		(net "M_F_CPU1_SB_DQ<25>")
	)
	(segment
		(start 181.444646 -202.416664)
		(end 181.444392 -202.416918)
		(width 0.20066)
		(layer "F.Cu")
		(net "M_F_CPU1_SB_DQ<25>")
	)
	(segment
		(start 166.679372 -201.54519)
		(end 166.496492 -201.36231)
		(width 0.18288)
		(layer "In4.Cu")
		(net "M_F_CPU1_SB_DQ<25>")
	)
	(segment
		(start 135.979916 -225.193352)
		(end 135.979916 -225.203258)
		(width 0.088646)
		(layer "In4.Cu")
		(net "M_F_CPU1_SB_DQ<25>")
	)
	(segment
		(start 154.778456 -205.589886)
		(end 154.524964 -205.640432)
		(width 0.18288)
		(layer "In4.Cu")
		(net "M_F_CPU1_SB_DQ<25>")
	)
	(segment
		(start 135.801354 -225.522536)
		(end 135.792464 -225.527616)
		(width 0.088646)
		(layer "In4.Cu")
		(net "M_F_CPU1_SB_DQ<25>")
	)
	(segment
		(start 130.660648 -228.159564)
		(end 129.966212 -228.45903)
		(width 0.088646)
		(layer "In4.Cu")
		(net "M_F_CPU1_SB_DQ<25>")
	)
	(segment
		(start 170.937682 -203.038456)
		(end 170.777662 -202.878436)
		(width 0.18288)
		(layer "In4.Cu")
		(net "M_F_CPU1_SB_DQ<25>")
	)
	(segment
		(start 164.671248 -202.136248)
		(end 164.193474 -201.658474)
		(width 0.18288)
		(layer "In4.Cu")
		(net "M_F_CPU1_SB_DQ<25>")
	)
	(segment
		(start 165.985952 -201.953368)
		(end 165.803072 -202.136248)
		(width 0.18288)
		(layer "In4.Cu")
		(net "M_F_CPU1_SB_DQ<25>")
	)
	(segment
		(start 155.370276 -205.151482)
		(end 155.420822 -205.40472)
		(width 0.18288)
		(layer "In4.Cu")
		(net "M_F_CPU1_SB_DQ<25>")
	)
	(segment
		(start 134.570216 -227.629466)
		(end 134.570216 -227.64496)
		(width 0.088646)
		(layer "In4.Cu")
		(net "M_F_CPU1_SB_DQ<25>")
	)
	(segment
		(start 136.919462 -223.561402)
		(end 136.919462 -223.575626)
		(width 0.088646)
		(layer "In4.Cu")
		(net "M_F_CPU1_SB_DQ<25>")
	)
	(segment
		(start 167.897048 -202.136248)
		(end 166.862252 -202.136248)
		(width 0.18288)
		(layer "In4.Cu")
		(net "M_F_CPU1_SB_DQ<25>")
	)
	(segment
		(start 137.2108 -223.080834)
		(end 137.20191 -223.085914)
		(width 0.088646)
		(layer "In4.Cu")
		(net "M_F_CPU1_SB_DQ<25>")
	)
	(segment
		(start 137.661904 -222.27794)
		(end 137.659872 -222.27921)
		(width 0.088646)
		(layer "In4.Cu")
		(net "M_F_CPU1_SB_DQ<25>")
	)
	(segment
		(start 155.93441 -203.8604)
		(end 156.367988 -204.14996)
		(width 0.18288)
		(layer "In4.Cu")
		(net "M_F_CPU1_SB_DQ<25>")
	)
	(segment
		(start 133.538468 -228.783388)
		(end 133.537452 -228.78288)
		(width 0.088646)
		(layer "In4.Cu")
		(net "M_F_CPU1_SB_DQ<25>")
	)
	(segment
		(start 132.039106 -228.137974)
		(end 132.033264 -228.134418)
		(width 0.088646)
		(layer "In4.Cu")
		(net "M_F_CPU1_SB_DQ<25>")
	)
	(segment
		(start 162.451542 -201.658474)
		(end 161.69767 -201.658474)
		(width 0.18288)
		(layer "In4.Cu")
		(net "M_F_CPU1_SB_DQ<25>")
	)
	(segment
		(start 139.44346 -222.196406)
		(end 138.894312 -222.196406)
		(width 0.088646)
		(layer "In4.Cu")
		(net "M_F_CPU1_SB_DQ<25>")
	)
	(segment
		(start 165.985952 -201.54519)
		(end 165.985952 -201.953368)
		(width 0.18288)
		(layer "In4.Cu")
		(net "M_F_CPU1_SB_DQ<25>")
	)
	(segment
		(start 162.634422 -202.290426)
		(end 162.634422 -201.841354)
		(width 0.18288)
		(layer "In4.Cu")
		(net "M_F_CPU1_SB_DQ<25>")
	)
	(segment
		(start 132.598414 -228.783388)
		(end 132.59689 -228.782372)
		(width 0.088646)
		(layer "In4.Cu")
		(net "M_F_CPU1_SB_DQ<25>")
	)
	(segment
		(start 131.099306 -228.137974)
		(end 131.093464 -228.134418)
		(width 0.088646)
		(layer "In4.Cu")
		(net "M_F_CPU1_SB_DQ<25>")
	)
	(segment
		(start 156.418534 -204.403198)
		(end 156.236162 -204.675994)
		(width 0.18288)
		(layer "In4.Cu")
		(net "M_F_CPU1_SB_DQ<25>")
	)
	(segment
		(start 155.295854 -204.487272)
		(end 155.113482 -204.760068)
		(width 0.18288)
		(layer "In4.Cu")
		(net "M_F_CPU1_SB_DQ<25>")
	)
	(segment
		(start 135.331454 -226.336606)
		(end 135.322564 -226.341686)
		(width 0.088646)
		(layer "In4.Cu")
		(net "M_F_CPU1_SB_DQ<25>")
	)
	(segment
		(start 168.752266 -202.991466)
		(end 167.897048 -202.136248)
		(width 0.18288)
		(layer "In4.Cu")
		(net "M_F_CPU1_SB_DQ<25>")
	)
	(segment
		(start 156.367988 -204.14996)
		(end 156.418534 -204.403198)
		(width 0.18288)
		(layer "In4.Cu")
		(net "M_F_CPU1_SB_DQ<25>")
	)
	(segment
		(start 161.201354 -202.15479)
		(end 157.165294 -202.15479)
		(width 0.18288)
		(layer "In4.Cu")
		(net "M_F_CPU1_SB_DQ<25>")
	)
	(segment
		(start 154.524964 -205.640432)
		(end 152.991058 -207.935576)
		(width 0.18288)
		(layer "In4.Cu")
		(net "M_F_CPU1_SB_DQ<25>")
	)
	(segment
		(start 163.327842 -201.841354)
		(end 163.327842 -202.290426)
		(width 0.18288)
		(layer "In4.Cu")
		(net "M_F_CPU1_SB_DQ<25>")
	)
	(segment
		(start 152.991058 -207.935576)
		(end 151.507698 -211.516468)
		(width 0.18288)
		(layer "In4.Cu")
		(net "M_F_CPU1_SB_DQ<25>")
	)
	(segment
		(start 157.165294 -202.15479)
		(end 156.22651 -203.093574)
		(width 0.18288)
		(layer "In4.Cu")
		(net "M_F_CPU1_SB_DQ<25>")
	)
	(segment
		(start 166.862252 -202.136248)
		(end 166.679372 -201.953368)
		(width 0.18288)
		(layer "In4.Cu")
		(net "M_F_CPU1_SB_DQ<25>")
	)
	(segment
		(start 136.449816 -224.373948)
		(end 136.449816 -224.389442)
		(width 0.088646)
		(layer "In4.Cu")
		(net "M_F_CPU1_SB_DQ<25>")
	)
	(segment
		(start 166.168832 -201.36231)
		(end 165.985952 -201.54519)
		(width 0.18288)
		(layer "In4.Cu")
		(net "M_F_CPU1_SB_DQ<25>")
	)
	(segment
		(start 170.617642 -202.102212)
		(end 170.204638 -202.102212)
		(width 0.18288)
		(layer "In4.Cu")
		(net "M_F_CPU1_SB_DQ<25>")
	)
	(segment
		(start 161.69767 -201.658474)
		(end 161.201354 -202.15479)
		(width 0.18288)
		(layer "In4.Cu")
		(net "M_F_CPU1_SB_DQ<25>")
	)
	(segment
		(start 151.507444 -211.516976)
		(end 140.90523 -222.11919)
		(width 0.18288)
		(layer "In4.Cu")
		(net "M_F_CPU1_SB_DQ<25>")
	)
	(segment
		(start 170.031664 -202.831446)
		(end 169.871644 -202.991466)
		(width 0.18288)
		(layer "In4.Cu")
		(net "M_F_CPU1_SB_DQ<25>")
	)
	(segment
		(start 162.817302 -202.473306)
		(end 162.634422 -202.290426)
		(width 0.18288)
		(layer "In4.Cu")
		(net "M_F_CPU1_SB_DQ<25>")
	)
	(segment
		(start 155.163774 -205.01356)
		(end 155.370276 -205.151482)
		(width 0.18288)
		(layer "In4.Cu")
		(net "M_F_CPU1_SB_DQ<25>")
	)
	(segment
		(start 155.420822 -205.40472)
		(end 155.23845 -205.677516)
		(width 0.18288)
		(layer "In4.Cu")
		(net "M_F_CPU1_SB_DQ<25>")
	)
	(segment
		(start 151.507698 -211.516468)
		(end 151.507444 -211.516976)
		(width 0.18288)
		(layer "In4.Cu")
		(net "M_F_CPU1_SB_DQ<25>")
	)
	(segment
		(start 155.98267 -204.726286)
		(end 155.549092 -204.436726)
		(width 0.18288)
		(layer "In4.Cu")
		(net "M_F_CPU1_SB_DQ<25>")
	)
	(segment
		(start 137.672064 -222.272098)
		(end 137.661904 -222.27794)
		(width 0.088646)
		(layer "In4.Cu")
		(net "M_F_CPU1_SB_DQ<25>")
	)
	(segment
		(start 165.803072 -202.136248)
		(end 164.671248 -202.136248)
		(width 0.18288)
		(layer "In4.Cu")
		(net "M_F_CPU1_SB_DQ<25>")
	)
	(segment
		(start 169.871644 -202.991466)
		(end 168.752266 -202.991466)
		(width 0.18288)
		(layer "In4.Cu")
		(net "M_F_CPU1_SB_DQ<25>")
	)
	(segment
		(start 136.271254 -224.70872)
		(end 136.262364 -224.7138)
		(width 0.088646)
		(layer "In4.Cu")
		(net "M_F_CPU1_SB_DQ<25>")
	)
	(segment
		(start 156.22651 -203.093574)
		(end 155.883864 -203.606654)
		(width 0.18288)
		(layer "In4.Cu")
		(net "M_F_CPU1_SB_DQ<25>")
	)
	(segment
		(start 164.193474 -201.658474)
		(end 163.510722 -201.658474)
		(width 0.18288)
		(layer "In4.Cu")
		(net "M_F_CPU1_SB_DQ<25>")
	)
	(segment
		(start 155.549092 -204.436726)
		(end 155.295854 -204.487272)
		(width 0.18288)
		(layer "In4.Cu")
		(net "M_F_CPU1_SB_DQ<25>")
	)
	(segment
		(start 135.322564 -226.341686)
		(end 135.310372 -226.348798)
		(width 0.088646)
		(layer "In4.Cu")
		(net "M_F_CPU1_SB_DQ<25>")
	)
	(segment
		(start 139.520676 -222.11919)
		(end 139.44346 -222.196406)
		(width 0.088646)
		(layer "In4.Cu")
		(net "M_F_CPU1_SB_DQ<25>")
	)
	(segment
		(start 166.679372 -201.953368)
		(end 166.679372 -201.54519)
		(width 0.18288)
		(layer "In4.Cu")
		(net "M_F_CPU1_SB_DQ<25>")
	)
	(segment
		(start 134.391654 -227.964238)
		(end 134.382764 -227.969318)
		(width 0.088646)
		(layer "In4.Cu")
		(net "M_F_CPU1_SB_DQ<25>")
	)
	(segment
		(start 154.984958 -205.727808)
		(end 154.778456 -205.589886)
		(width 0.18288)
		(layer "In4.Cu")
		(net "M_F_CPU1_SB_DQ<25>")
	)
	(segment
		(start 155.23845 -205.677516)
		(end 154.984958 -205.727808)
		(width 0.18288)
		(layer "In4.Cu")
		(net "M_F_CPU1_SB_DQ<25>")
	)
	(segment
		(start 170.777662 -202.878436)
		(end 170.777662 -202.262232)
		(width 0.18288)
		(layer "In4.Cu")
		(net "M_F_CPU1_SB_DQ<25>")
	)
	(segment
		(start 132.97408 -228.78288)
		(end 132.966714 -228.787198)
		(width 0.088646)
		(layer "In4.Cu")
		(net "M_F_CPU1_SB_DQ<25>")
	)
	(segment
		(start 156.236162 -204.675994)
		(end 155.98267 -204.726286)
		(width 0.18288)
		(layer "In4.Cu")
		(net "M_F_CPU1_SB_DQ<25>")
	)
	(segment
		(start 172.795946 -202.416664)
		(end 172.174154 -203.038456)
		(width 0.18288)
		(layer "In4.Cu")
		(net "M_F_CPU1_SB_DQ<25>")
	)
	(segment
		(start 132.033264 -228.134418)
		(end 132.027422 -228.131116)
		(width 0.088646)
		(layer "In4.Cu")
		(net "M_F_CPU1_SB_DQ<25>")
	)
	(segment
		(start 163.510722 -201.658474)
		(end 163.327842 -201.841354)
		(width 0.18288)
		(layer "In4.Cu")
		(net "M_F_CPU1_SB_DQ<25>")
	)
	(segment
		(start 155.883864 -203.606654)
		(end 155.93441 -203.8604)
		(width 0.18288)
		(layer "In4.Cu")
		(net "M_F_CPU1_SB_DQ<25>")
	)
	(segment
		(start 172.174154 -203.038456)
		(end 170.937682 -203.038456)
		(width 0.18288)
		(layer "In4.Cu")
		(net "M_F_CPU1_SB_DQ<25>")
	)
	(segment
		(start 166.496492 -201.36231)
		(end 166.168832 -201.36231)
		(width 0.18288)
		(layer "In4.Cu")
		(net "M_F_CPU1_SB_DQ<25>")
	)
	(segment
		(start 140.90523 -222.11919)
		(end 139.756642 -222.11919)
		(width 0.18288)
		(layer "In4.Cu")
		(net "M_F_CPU1_SB_DQ<25>")
	)
	(segment
		(start 134.8613 -227.150422)
		(end 134.85241 -227.155502)
		(width 0.088646)
		(layer "In4.Cu")
		(net "M_F_CPU1_SB_DQ<25>")
	)
	(segment
		(start 132.980176 -228.779324)
		(end 132.97408 -228.78288)
		(width 0.088646)
		(layer "In4.Cu")
		(net "M_F_CPU1_SB_DQ<25>")
	)
	(segment
		(start 170.204638 -202.102212)
		(end 170.031664 -202.275186)
		(width 0.18288)
		(layer "In4.Cu")
		(net "M_F_CPU1_SB_DQ<25>")
	)
	(segment
		(start 163.327842 -202.290426)
		(end 163.144962 -202.473306)
		(width 0.18288)
		(layer "In4.Cu")
		(net "M_F_CPU1_SB_DQ<25>")
	)
	(segment
		(start 134.100062 -228.444806)
		(end 134.100062 -228.467666)
		(width 0.088646)
		(layer "In4.Cu")
		(net "M_F_CPU1_SB_DQ<25>")
	)
	(segment
		(start 139.756642 -222.11919)
		(end 139.520676 -222.11919)
		(width 0.088646)
		(layer "In4.Cu")
		(net "M_F_CPU1_SB_DQ<25>")
	)
	(segment
		(start 131.093464 -228.134418)
		(end 131.087622 -228.131116)
		(width 0.088646)
		(layer "In4.Cu")
		(net "M_F_CPU1_SB_DQ<25>")
	)
	(segment
		(start 132.36575 -228.518212)
		(end 132.33781 -228.450648)
		(width 0.088646)
		(layer "In4.Cu")
		(net "M_F_CPU1_SB_DQ<25>")
	)
	(segment
		(start 136.7409 -223.894904)
		(end 136.73201 -223.899984)
		(width 0.088646)
		(layer "In4.Cu")
		(net "M_F_CPU1_SB_DQ<25>")
	)
	(segment
		(start 135.510016 -225.998786)
		(end 135.510016 -226.017328)
		(width 0.088646)
		(layer "In4.Cu")
		(net "M_F_CPU1_SB_DQ<25>")
	)
	(segment
		(start 162.634422 -201.841354)
		(end 162.451542 -201.658474)
		(width 0.18288)
		(layer "In4.Cu")
		(net "M_F_CPU1_SB_DQ<25>")
	)
	(segment
		(start 163.144962 -202.473306)
		(end 162.817302 -202.473306)
		(width 0.18288)
		(layer "In4.Cu")
		(net "M_F_CPU1_SB_DQ<25>")
	)
	(segment
		(start 170.777662 -202.262232)
		(end 170.617642 -202.102212)
		(width 0.18288)
		(layer "In4.Cu")
		(net "M_F_CPU1_SB_DQ<25>")
	)
	(segment
		(start 155.113482 -204.760068)
		(end 155.163774 -205.01356)
		(width 0.18288)
		(layer "In4.Cu")
		(net "M_F_CPU1_SB_DQ<25>")
	)
	(segment
		(start 170.031664 -202.275186)
		(end 170.031664 -202.831446)
		(width 0.18288)
		(layer "In4.Cu")
		(net "M_F_CPU1_SB_DQ<25>")
	)
	(arc
		(start 137.389362 -222.761556)
		(mid 137.341683 -222.944456)
		(end 137.2108 -223.080834)
		(width 0.088646)
		(layer "In4.Cu")
		(net "M_F_CPU1_SB_DQ<25>")
	)
	(arc
		(start 130.74142 -228.122226)
		(mid 130.701255 -228.141374)
		(end 130.660648 -228.159564)
		(width 0.088646)
		(layer "In4.Cu")
		(net "M_F_CPU1_SB_DQ<25>")
	)
	(arc
		(start 135.039862 -226.831144)
		(mid 134.992183 -227.014044)
		(end 134.8613 -227.150422)
		(width 0.088646)
		(layer "In4.Cu")
		(net "M_F_CPU1_SB_DQ<25>")
	)
	(arc
		(start 136.919462 -223.575626)
		(mid 136.871783 -223.758526)
		(end 136.7409 -223.894904)
		(width 0.088646)
		(layer "In4.Cu")
		(net "M_F_CPU1_SB_DQ<25>")
	)
	(arc
		(start 138.611864 -222.272098)
		(mid 138.424666 -222.322241)
		(end 138.237468 -222.272098)
		(width 0.088646)
		(layer "In4.Cu")
		(net "M_F_CPU1_SB_DQ<25>")
	)
	(arc
		(start 136.262364 -224.7138)
		(mid 136.058029 -224.916405)
		(end 135.979916 -225.193352)
		(width 0.088646)
		(layer "In4.Cu")
		(net "M_F_CPU1_SB_DQ<25>")
	)
	(arc
		(start 134.570216 -227.64496)
		(mid 134.522537 -227.82786)
		(end 134.391654 -227.964238)
		(width 0.088646)
		(layer "In4.Cu")
		(net "M_F_CPU1_SB_DQ<25>")
	)
	(arc
		(start 132.966714 -228.787198)
		(mid 132.782054 -228.833711)
		(end 132.598414 -228.783388)
		(width 0.088646)
		(layer "In4.Cu")
		(net "M_F_CPU1_SB_DQ<25>")
	)
	(arc
		(start 132.223002 -228.278944)
		(mid 132.135684 -228.202418)
		(end 132.039106 -228.137974)
		(width 0.088646)
		(layer "In4.Cu")
		(net "M_F_CPU1_SB_DQ<25>")
	)
	(arc
		(start 136.449816 -224.389442)
		(mid 136.402137 -224.572342)
		(end 136.271254 -224.70872)
		(width 0.088646)
		(layer "In4.Cu")
		(net "M_F_CPU1_SB_DQ<25>")
	)
	(arc
		(start 135.510016 -226.017328)
		(mid 135.462337 -226.200228)
		(end 135.331454 -226.336606)
		(width 0.088646)
		(layer "In4.Cu")
		(net "M_F_CPU1_SB_DQ<25>")
	)
	(arc
		(start 134.85241 -227.155502)
		(mid 134.649587 -227.355733)
		(end 134.570216 -227.629466)
		(width 0.088646)
		(layer "In4.Cu")
		(net "M_F_CPU1_SB_DQ<25>")
	)
	(arc
		(start 138.237468 -222.272098)
		(mid 137.954766 -222.196322)
		(end 137.672064 -222.272098)
		(width 0.088646)
		(layer "In4.Cu")
		(net "M_F_CPU1_SB_DQ<25>")
	)
	(arc
		(start 136.73201 -223.899984)
		(mid 136.529187 -224.100215)
		(end 136.449816 -224.373948)
		(width 0.088646)
		(layer "In4.Cu")
		(net "M_F_CPU1_SB_DQ<25>")
	)
	(arc
		(start 132.33781 -228.450648)
		(mid 132.288849 -228.359151)
		(end 132.223002 -228.278944)
		(width 0.088646)
		(layer "In4.Cu")
		(net "M_F_CPU1_SB_DQ<25>")
	)
	(arc
		(start 135.792464 -225.527616)
		(mid 135.590178 -225.726597)
		(end 135.510016 -225.998786)
		(width 0.088646)
		(layer "In4.Cu")
		(net "M_F_CPU1_SB_DQ<25>")
	)
	(arc
		(start 135.310372 -226.348798)
		(mid 135.112144 -226.554646)
		(end 135.039862 -226.831144)
		(width 0.088646)
		(layer "In4.Cu")
		(net "M_F_CPU1_SB_DQ<25>")
	)
	(arc
		(start 131.087622 -228.131116)
		(mid 130.915612 -228.084275)
		(end 130.74142 -228.122226)
		(width 0.088646)
		(layer "In4.Cu")
		(net "M_F_CPU1_SB_DQ<25>")
	)
	(arc
		(start 134.100062 -228.467666)
		(mid 134.047792 -228.650031)
		(end 133.912864 -228.783388)
		(width 0.088646)
		(layer "In4.Cu")
		(net "M_F_CPU1_SB_DQ<25>")
	)
	(arc
		(start 137.659872 -222.27921)
		(mid 137.461644 -222.485058)
		(end 137.389362 -222.761556)
		(width 0.088646)
		(layer "In4.Cu")
		(net "M_F_CPU1_SB_DQ<25>")
	)
	(arc
		(start 132.59689 -228.782372)
		(mid 132.459661 -228.669247)
		(end 132.36575 -228.518212)
		(width 0.088646)
		(layer "In4.Cu")
		(net "M_F_CPU1_SB_DQ<25>")
	)
	(arc
		(start 137.20191 -223.085914)
		(mid 136.998605 -223.28678)
		(end 136.919462 -223.561402)
		(width 0.088646)
		(layer "In4.Cu")
		(net "M_F_CPU1_SB_DQ<25>")
	)
	(arc
		(start 133.912864 -228.783388)
		(mid 133.725666 -228.833531)
		(end 133.538468 -228.783388)
		(width 0.088646)
		(layer "In4.Cu")
		(net "M_F_CPU1_SB_DQ<25>")
	)
	(arc
		(start 131.658614 -228.134418)
		(mid 131.37944 -228.210183)
		(end 131.099306 -228.137974)
		(width 0.088646)
		(layer "In4.Cu")
		(net "M_F_CPU1_SB_DQ<25>")
	)
	(arc
		(start 134.382764 -227.969318)
		(mid 134.179283 -228.170122)
		(end 134.100062 -228.444806)
		(width 0.088646)
		(layer "In4.Cu")
		(net "M_F_CPU1_SB_DQ<25>")
	)
	(arc
		(start 138.894312 -222.196406)
		(mid 138.748104 -222.215655)
		(end 138.611864 -222.272098)
		(width 0.088646)
		(layer "In4.Cu")
		(net "M_F_CPU1_SB_DQ<25>")
	)
	(arc
		(start 132.027422 -228.131116)
		(mid 131.842567 -228.084198)
		(end 131.658614 -228.134418)
		(width 0.088646)
		(layer "In4.Cu")
		(net "M_F_CPU1_SB_DQ<25>")
	)
	(arc
		(start 135.979916 -225.203258)
		(mid 135.932237 -225.386158)
		(end 135.801354 -225.522536)
		(width 0.088646)
		(layer "In4.Cu")
		(net "M_F_CPU1_SB_DQ<25>")
	)
	(arc
		(start 133.537452 -228.78288)
		(mid 133.259294 -228.707656)
		(end 132.980176 -228.779324)
		(width 0.088646)
		(layer "In4.Cu")
		(net "M_F_CPU1_SB_DQ<25>")
	)
	(segment
		(start 175.421544 -204.116686)
		(end 173.900846 -204.116686)
		(width 0.20066)
		(layer "F.Cu")
		(net "M_F_CPU1_SB_DQ<24>")
	)
	(segment
		(start 176.333404 -203.809854)
		(end 176.333404 -204.177392)
		(width 0.20066)
		(layer "F.Cu")
		(net "M_F_CPU1_SB_DQ<24>")
	)
	(segment
		(start 176.451514 -203.691744)
		(end 176.333404 -203.809854)
		(width 0.20066)
		(layer "F.Cu")
		(net "M_F_CPU1_SB_DQ<24>")
	)
	(segment
		(start 173.900846 -204.116686)
		(end 172.795946 -204.116686)
		(width 0.20066)
		(layer "F.Cu")
		(net "M_F_CPU1_SB_DQ<24>")
	)
	(segment
		(start 176.843182 -203.691744)
		(end 176.796192 -203.691744)
		(width 0.101854)
		(layer "F.Cu")
		(net "M_F_CPU1_SB_DQ<24>")
	)
	(segment
		(start 179.011326 -203.685394)
		(end 179.004976 -203.691744)
		(width 0.1016)
		(layer "F.Cu")
		(net "M_F_CPU1_SB_DQ<24>")
	)
	(segment
		(start 176.145444 -204.365352)
		(end 175.67021 -204.365352)
		(width 0.20066)
		(layer "F.Cu")
		(net "M_F_CPU1_SB_DQ<24>")
	)
	(segment
		(start 176.333404 -204.177392)
		(end 176.145444 -204.365352)
		(width 0.20066)
		(layer "F.Cu")
		(net "M_F_CPU1_SB_DQ<24>")
	)
	(segment
		(start 175.67021 -204.365352)
		(end 175.421544 -204.116686)
		(width 0.20066)
		(layer "F.Cu")
		(net "M_F_CPU1_SB_DQ<24>")
	)
	(segment
		(start 176.796192 -203.691744)
		(end 176.451514 -203.691744)
		(width 0.20066)
		(layer "F.Cu")
		(net "M_F_CPU1_SB_DQ<24>")
	)
	(segment
		(start 130.436366 -229.808532)
		(end 130.436366 -229.272846)
		(width 0.20066)
		(layer "F.Cu")
		(net "M_F_CPU1_SB_DQ<24>")
	)
	(segment
		(start 181.444392 -204.11694)
		(end 179.852828 -204.11694)
		(width 0.20066)
		(layer "F.Cu")
		(net "M_F_CPU1_SB_DQ<24>")
	)
	(segment
		(start 179.421282 -203.685394)
		(end 179.011326 -203.685394)
		(width 0.20066)
		(layer "F.Cu")
		(net "M_F_CPU1_SB_DQ<24>")
	)
	(segment
		(start 179.852828 -204.11694)
		(end 179.421282 -203.685394)
		(width 0.20066)
		(layer "F.Cu")
		(net "M_F_CPU1_SB_DQ<24>")
	)
	(segment
		(start 179.004976 -203.691744)
		(end 176.843182 -203.691744)
		(width 0.1016)
		(layer "F.Cu")
		(net "M_F_CPU1_SB_DQ<24>")
	)
	(segment
		(start 130.436112 -229.808786)
		(end 130.436366 -229.808532)
		(width 0.20066)
		(layer "F.Cu")
		(net "M_F_CPU1_SB_DQ<24>")
	)
	(segment
		(start 181.444646 -204.116686)
		(end 181.444392 -204.11694)
		(width 0.20066)
		(layer "F.Cu")
		(net "M_F_CPU1_SB_DQ<24>")
	)
	(segment
		(start 156.734256 -205.639924)
		(end 154.189684 -208.184496)
		(width 0.18288)
		(layer "In4.Cu")
		(net "M_F_CPU1_SB_DQ<24>")
	)
	(segment
		(start 159.993584 -203.789026)
		(end 159.532066 -203.789026)
		(width 0.18288)
		(layer "In4.Cu")
		(net "M_F_CPU1_SB_DQ<24>")
	)
	(segment
		(start 169.56913 -204.704696)
		(end 168.338246 -204.704696)
		(width 0.18288)
		(layer "In4.Cu")
		(net "M_F_CPU1_SB_DQ<24>")
	)
	(segment
		(start 137.680954 -223.894904)
		(end 137.672064 -223.899984)
		(width 0.088646)
		(layer "In4.Cu")
		(net "M_F_CPU1_SB_DQ<24>")
	)
	(segment
		(start 162.439858 -204.352652)
		(end 162.279838 -204.192632)
		(width 0.18288)
		(layer "In4.Cu")
		(net "M_F_CPU1_SB_DQ<24>")
	)
	(segment
		(start 160.153604 -204.338936)
		(end 160.153604 -203.949046)
		(width 0.18288)
		(layer "In4.Cu")
		(net "M_F_CPU1_SB_DQ<24>")
	)
	(segment
		(start 163.133278 -203.528676)
		(end 162.973258 -203.688696)
		(width 0.18288)
		(layer "In4.Cu")
		(net "M_F_CPU1_SB_DQ<24>")
	)
	(segment
		(start 136.449562 -226.003104)
		(end 136.449562 -226.025964)
		(width 0.088646)
		(layer "In4.Cu")
		(net "M_F_CPU1_SB_DQ<24>")
	)
	(segment
		(start 138.707114 -223.085914)
		(end 138.6967 -223.079818)
		(width 0.088646)
		(layer "In4.Cu")
		(net "M_F_CPU1_SB_DQ<24>")
	)
	(segment
		(start 160.313624 -204.498956)
		(end 160.153604 -204.338936)
		(width 0.18288)
		(layer "In4.Cu")
		(net "M_F_CPU1_SB_DQ<24>")
	)
	(segment
		(start 162.973258 -204.192632)
		(end 162.813238 -204.352652)
		(width 0.18288)
		(layer "In4.Cu")
		(net "M_F_CPU1_SB_DQ<24>")
	)
	(segment
		(start 158.647892 -203.979526)
		(end 158.487872 -203.819506)
		(width 0.18288)
		(layer "In4.Cu")
		(net "M_F_CPU1_SB_DQ<24>")
	)
	(segment
		(start 161.267394 -203.528676)
		(end 160.847024 -203.949046)
		(width 0.18288)
		(layer "In4.Cu")
		(net "M_F_CPU1_SB_DQ<24>")
	)
	(segment
		(start 172.770546 -204.116686)
		(end 172.209206 -204.678026)
		(width 0.18288)
		(layer "In4.Cu")
		(net "M_F_CPU1_SB_DQ<24>")
	)
	(segment
		(start 169.600626 -204.703426)
		(end 169.5704 -204.703426)
		(width 0.18288)
		(layer "In4.Cu")
		(net "M_F_CPU1_SB_DQ<24>")
	)
	(segment
		(start 134.008114 -229.597204)
		(end 134.004558 -229.595172)
		(width 0.088646)
		(layer "In4.Cu")
		(net "M_F_CPU1_SB_DQ<24>")
	)
	(segment
		(start 134.570216 -229.257352)
		(end 134.570216 -229.272846)
		(width 0.088646)
		(layer "In4.Cu")
		(net "M_F_CPU1_SB_DQ<24>")
	)
	(segment
		(start 164.698426 -204.365606)
		(end 164.698426 -203.688696)
		(width 0.18288)
		(layer "In4.Cu")
		(net "M_F_CPU1_SB_DQ<24>")
	)
	(segment
		(start 164.858446 -204.525626)
		(end 164.698426 -204.365606)
		(width 0.18288)
		(layer "In4.Cu")
		(net "M_F_CPU1_SB_DQ<24>")
	)
	(segment
		(start 168.338246 -204.704696)
		(end 168.178226 -204.544676)
		(width 0.18288)
		(layer "In4.Cu")
		(net "M_F_CPU1_SB_DQ<24>")
	)
	(segment
		(start 133.074156 -229.600506)
		(end 133.068314 -229.597204)
		(width 0.088646)
		(layer "In4.Cu")
		(net "M_F_CPU1_SB_DQ<24>")
	)
	(segment
		(start 159.372046 -203.949046)
		(end 159.372046 -204.92212)
		(width 0.18288)
		(layer "In4.Cu")
		(net "M_F_CPU1_SB_DQ<24>")
	)
	(segment
		(start 160.153604 -203.949046)
		(end 159.993584 -203.789026)
		(width 0.18288)
		(layer "In4.Cu")
		(net "M_F_CPU1_SB_DQ<24>")
	)
	(segment
		(start 131.10083 -228.77907)
		(end 131.0513 -228.807518)
		(width 0.088646)
		(layer "In4.Cu")
		(net "M_F_CPU1_SB_DQ<24>")
	)
	(segment
		(start 164.538406 -203.528676)
		(end 163.133278 -203.528676)
		(width 0.18288)
		(layer "In4.Cu")
		(net "M_F_CPU1_SB_DQ<24>")
	)
	(segment
		(start 162.279838 -203.688696)
		(end 162.119818 -203.528676)
		(width 0.18288)
		(layer "In4.Cu")
		(net "M_F_CPU1_SB_DQ<24>")
	)
	(segment
		(start 135.510016 -227.635054)
		(end 135.510016 -227.64496)
		(width 0.088646)
		(layer "In4.Cu")
		(net "M_F_CPU1_SB_DQ<24>")
	)
	(segment
		(start 136.919716 -225.193352)
		(end 136.919716 -225.203258)
		(width 0.088646)
		(layer "In4.Cu")
		(net "M_F_CPU1_SB_DQ<24>")
	)
	(segment
		(start 134.8613 -228.778308)
		(end 134.85241 -228.783388)
		(width 0.088646)
		(layer "In4.Cu")
		(net "M_F_CPU1_SB_DQ<24>")
	)
	(segment
		(start 152.734264 -211.698078)
		(end 152.73401 -211.698586)
		(width 0.18288)
		(layer "In4.Cu")
		(net "M_F_CPU1_SB_DQ<24>")
	)
	(segment
		(start 168.178226 -203.941426)
		(end 167.975026 -203.738226)
		(width 0.18288)
		(layer "In4.Cu")
		(net "M_F_CPU1_SB_DQ<24>")
	)
	(segment
		(start 157.526482 -205.639924)
		(end 156.734256 -205.639924)
		(width 0.18288)
		(layer "In4.Cu")
		(net "M_F_CPU1_SB_DQ<24>")
	)
	(segment
		(start 167.975026 -203.738226)
		(end 167.314626 -203.738226)
		(width 0.18288)
		(layer "In4.Cu")
		(net "M_F_CPU1_SB_DQ<24>")
	)
	(segment
		(start 162.279838 -204.192632)
		(end 162.279838 -203.688696)
		(width 0.18288)
		(layer "In4.Cu")
		(net "M_F_CPU1_SB_DQ<24>")
	)
	(segment
		(start 135.331454 -227.964238)
		(end 135.322564 -227.969318)
		(width 0.088646)
		(layer "In4.Cu")
		(net "M_F_CPU1_SB_DQ<24>")
	)
	(segment
		(start 165.485826 -204.365606)
		(end 165.325806 -204.525626)
		(width 0.18288)
		(layer "In4.Cu")
		(net "M_F_CPU1_SB_DQ<24>")
	)
	(segment
		(start 130.977386 -228.857048)
		(end 130.436366 -229.272846)
		(width 0.088646)
		(layer "In4.Cu")
		(net "M_F_CPU1_SB_DQ<24>")
	)
	(segment
		(start 158.11373 -203.819506)
		(end 157.85465 -204.078586)
		(width 0.18288)
		(layer "In4.Cu")
		(net "M_F_CPU1_SB_DQ<24>")
	)
	(segment
		(start 157.85465 -204.078586)
		(end 157.85465 -205.311756)
		(width 0.18288)
		(layer "In4.Cu")
		(net "M_F_CPU1_SB_DQ<24>")
	)
	(segment
		(start 162.813238 -204.352652)
		(end 162.439858 -204.352652)
		(width 0.18288)
		(layer "In4.Cu")
		(net "M_F_CPU1_SB_DQ<24>")
	)
	(segment
		(start 159.189166 -205.105)
		(end 158.830772 -205.105)
		(width 0.18288)
		(layer "In4.Cu")
		(net "M_F_CPU1_SB_DQ<24>")
	)
	(segment
		(start 136.741154 -225.522536)
		(end 136.732264 -225.527616)
		(width 0.088646)
		(layer "In4.Cu")
		(net "M_F_CPU1_SB_DQ<24>")
	)
	(segment
		(start 171.200826 -204.500226)
		(end 169.803826 -204.500226)
		(width 0.18288)
		(layer "In4.Cu")
		(net "M_F_CPU1_SB_DQ<24>")
	)
	(segment
		(start 160.847024 -203.949046)
		(end 160.847024 -204.338936)
		(width 0.18288)
		(layer "In4.Cu")
		(net "M_F_CPU1_SB_DQ<24>")
	)
	(segment
		(start 167.314626 -203.738226)
		(end 166.959026 -203.382626)
		(width 0.18288)
		(layer "In4.Cu")
		(net "M_F_CPU1_SB_DQ<24>")
	)
	(segment
		(start 168.178226 -204.544676)
		(end 168.178226 -203.941426)
		(width 0.18288)
		(layer "In4.Cu")
		(net "M_F_CPU1_SB_DQ<24>")
	)
	(segment
		(start 135.039862 -228.45141)
		(end 135.039862 -228.45903)
		(width 0.088646)
		(layer "In4.Cu")
		(net "M_F_CPU1_SB_DQ<24>")
	)
	(segment
		(start 169.803826 -204.500226)
		(end 169.600626 -204.703426)
		(width 0.18288)
		(layer "In4.Cu")
		(net "M_F_CPU1_SB_DQ<24>")
	)
	(segment
		(start 159.532066 -203.789026)
		(end 159.372046 -203.949046)
		(width 0.18288)
		(layer "In4.Cu")
		(net "M_F_CPU1_SB_DQ<24>")
	)
	(segment
		(start 137.211054 -224.70872)
		(end 137.202164 -224.7138)
		(width 0.088646)
		(layer "In4.Cu")
		(net "M_F_CPU1_SB_DQ<24>")
	)
	(segment
		(start 165.325806 -204.525626)
		(end 164.858446 -204.525626)
		(width 0.18288)
		(layer "In4.Cu")
		(net "M_F_CPU1_SB_DQ<24>")
	)
	(segment
		(start 162.973258 -203.688696)
		(end 162.973258 -204.192632)
		(width 0.18288)
		(layer "In4.Cu")
		(net "M_F_CPU1_SB_DQ<24>")
	)
	(segment
		(start 135.801354 -227.150422)
		(end 135.792464 -227.155502)
		(width 0.088646)
		(layer "In4.Cu")
		(net "M_F_CPU1_SB_DQ<24>")
	)
	(segment
		(start 137.859516 -223.557084)
		(end 137.859516 -223.575626)
		(width 0.088646)
		(layer "In4.Cu")
		(net "M_F_CPU1_SB_DQ<24>")
	)
	(segment
		(start 157.85465 -205.311756)
		(end 157.526482 -205.639924)
		(width 0.18288)
		(layer "In4.Cu")
		(net "M_F_CPU1_SB_DQ<24>")
	)
	(segment
		(start 133.068314 -229.597204)
		(end 133.062472 -229.593648)
		(width 0.088646)
		(layer "In4.Cu")
		(net "M_F_CPU1_SB_DQ<24>")
	)
	(segment
		(start 134.391654 -229.592124)
		(end 134.382764 -229.597204)
		(width 0.088646)
		(layer "In4.Cu")
		(net "M_F_CPU1_SB_DQ<24>")
	)
	(segment
		(start 165.485826 -203.743306)
		(end 165.485826 -204.365606)
		(width 0.18288)
		(layer "In4.Cu")
		(net "M_F_CPU1_SB_DQ<24>")
	)
	(segment
		(start 164.698426 -203.688696)
		(end 164.538406 -203.528676)
		(width 0.18288)
		(layer "In4.Cu")
		(net "M_F_CPU1_SB_DQ<24>")
	)
	(segment
		(start 131.941062 -229.272846)
		(end 131.941062 -229.268528)
		(width 0.088646)
		(layer "In4.Cu")
		(net "M_F_CPU1_SB_DQ<24>")
	)
	(segment
		(start 141.291818 -223.140778)
		(end 139.756642 -223.140778)
		(width 0.18288)
		(layer "In4.Cu")
		(net "M_F_CPU1_SB_DQ<24>")
	)
	(segment
		(start 169.5704 -204.703426)
		(end 169.56913 -204.704696)
		(width 0.18288)
		(layer "In4.Cu")
		(net "M_F_CPU1_SB_DQ<24>")
	)
	(segment
		(start 160.847024 -204.338936)
		(end 160.687004 -204.498956)
		(width 0.18288)
		(layer "In4.Cu")
		(net "M_F_CPU1_SB_DQ<24>")
	)
	(segment
		(start 154.189684 -208.184496)
		(end 152.734264 -211.698078)
		(width 0.18288)
		(layer "In4.Cu")
		(net "M_F_CPU1_SB_DQ<24>")
	)
	(segment
		(start 152.73401 -211.698586)
		(end 141.291818 -223.140778)
		(width 0.18288)
		(layer "In4.Cu")
		(net "M_F_CPU1_SB_DQ<24>")
	)
	(segment
		(start 158.487872 -203.819506)
		(end 158.11373 -203.819506)
		(width 0.18288)
		(layer "In4.Cu")
		(net "M_F_CPU1_SB_DQ<24>")
	)
	(segment
		(start 172.795946 -204.116686)
		(end 172.770546 -204.116686)
		(width 0.18288)
		(layer "In4.Cu")
		(net "M_F_CPU1_SB_DQ<24>")
	)
	(segment
		(start 135.979916 -226.821238)
		(end 135.979916 -226.831144)
		(width 0.088646)
		(layer "In4.Cu")
		(net "M_F_CPU1_SB_DQ<24>")
	)
	(segment
		(start 160.687004 -204.498956)
		(end 160.313624 -204.498956)
		(width 0.18288)
		(layer "In4.Cu")
		(net "M_F_CPU1_SB_DQ<24>")
	)
	(segment
		(start 158.647892 -204.92212)
		(end 158.647892 -203.979526)
		(width 0.18288)
		(layer "In4.Cu")
		(net "M_F_CPU1_SB_DQ<24>")
	)
	(segment
		(start 159.372046 -204.92212)
		(end 159.189166 -205.105)
		(width 0.18288)
		(layer "In4.Cu")
		(net "M_F_CPU1_SB_DQ<24>")
	)
	(segment
		(start 172.209206 -204.678026)
		(end 171.378626 -204.678026)
		(width 0.18288)
		(layer "In4.Cu")
		(net "M_F_CPU1_SB_DQ<24>")
	)
	(segment
		(start 158.830772 -205.105)
		(end 158.647892 -204.92212)
		(width 0.18288)
		(layer "In4.Cu")
		(net "M_F_CPU1_SB_DQ<24>")
	)
	(segment
		(start 165.846506 -203.382626)
		(end 165.485826 -203.743306)
		(width 0.18288)
		(layer "In4.Cu")
		(net "M_F_CPU1_SB_DQ<24>")
	)
	(segment
		(start 137.389616 -224.379536)
		(end 137.389616 -224.389442)
		(width 0.088646)
		(layer "In4.Cu")
		(net "M_F_CPU1_SB_DQ<24>")
	)
	(segment
		(start 171.378626 -204.678026)
		(end 171.200826 -204.500226)
		(width 0.18288)
		(layer "In4.Cu")
		(net "M_F_CPU1_SB_DQ<24>")
	)
	(segment
		(start 162.119818 -203.528676)
		(end 161.267394 -203.528676)
		(width 0.18288)
		(layer "In4.Cu")
		(net "M_F_CPU1_SB_DQ<24>")
	)
	(segment
		(start 166.959026 -203.382626)
		(end 165.846506 -203.382626)
		(width 0.18288)
		(layer "In4.Cu")
		(net "M_F_CPU1_SB_DQ<24>")
	)
	(segment
		(start 139.756642 -223.140778)
		(end 138.912092 -223.140778)
		(width 0.088646)
		(layer "In4.Cu")
		(net "M_F_CPU1_SB_DQ<24>")
	)
	(arc
		(start 134.004558 -229.595172)
		(mid 133.723474 -229.521435)
		(end 133.442964 -229.597204)
		(width 0.088646)
		(layer "In4.Cu")
		(net "M_F_CPU1_SB_DQ<24>")
	)
	(arc
		(start 138.141964 -223.085914)
		(mid 137.939678 -223.284895)
		(end 137.859516 -223.557084)
		(width 0.088646)
		(layer "In4.Cu")
		(net "M_F_CPU1_SB_DQ<24>")
	)
	(arc
		(start 133.062472 -229.593648)
		(mid 132.782337 -229.521365)
		(end 132.503164 -229.597204)
		(width 0.088646)
		(layer "In4.Cu")
		(net "M_F_CPU1_SB_DQ<24>")
	)
	(arc
		(start 137.389616 -224.389442)
		(mid 137.341937 -224.572342)
		(end 137.211054 -224.70872)
		(width 0.088646)
		(layer "In4.Cu")
		(net "M_F_CPU1_SB_DQ<24>")
	)
	(arc
		(start 136.262364 -226.341686)
		(mid 136.058029 -226.544291)
		(end 135.979916 -226.821238)
		(width 0.088646)
		(layer "In4.Cu")
		(net "M_F_CPU1_SB_DQ<24>")
	)
	(arc
		(start 134.382764 -229.597204)
		(mid 134.195456 -229.647347)
		(end 134.008114 -229.597204)
		(width 0.088646)
		(layer "In4.Cu")
		(net "M_F_CPU1_SB_DQ<24>")
	)
	(arc
		(start 135.792464 -227.155502)
		(mid 135.588129 -227.358107)
		(end 135.510016 -227.635054)
		(width 0.088646)
		(layer "In4.Cu")
		(net "M_F_CPU1_SB_DQ<24>")
	)
	(arc
		(start 137.202164 -224.7138)
		(mid 136.997829 -224.916405)
		(end 136.919716 -225.193352)
		(width 0.088646)
		(layer "In4.Cu")
		(net "M_F_CPU1_SB_DQ<24>")
	)
	(arc
		(start 133.442964 -229.597204)
		(mid 133.25901 -229.647333)
		(end 133.074156 -229.600506)
		(width 0.088646)
		(layer "In4.Cu")
		(net "M_F_CPU1_SB_DQ<24>")
	)
	(arc
		(start 137.672064 -223.899984)
		(mid 137.467729 -224.102589)
		(end 137.389616 -224.379536)
		(width 0.088646)
		(layer "In4.Cu")
		(net "M_F_CPU1_SB_DQ<24>")
	)
	(arc
		(start 138.6967 -223.079818)
		(mid 138.418522 -223.010126)
		(end 138.141964 -223.085914)
		(width 0.088646)
		(layer "In4.Cu")
		(net "M_F_CPU1_SB_DQ<24>")
	)
	(arc
		(start 131.0513 -228.807518)
		(mid 131.013518 -228.831053)
		(end 130.977386 -228.857048)
		(width 0.088646)
		(layer "In4.Cu")
		(net "M_F_CPU1_SB_DQ<24>")
	)
	(arc
		(start 136.919716 -225.203258)
		(mid 136.872037 -225.386158)
		(end 136.741154 -225.522536)
		(width 0.088646)
		(layer "In4.Cu")
		(net "M_F_CPU1_SB_DQ<24>")
	)
	(arc
		(start 135.979916 -226.831144)
		(mid 135.932237 -227.014044)
		(end 135.801354 -227.150422)
		(width 0.088646)
		(layer "In4.Cu")
		(net "M_F_CPU1_SB_DQ<24>")
	)
	(arc
		(start 135.322564 -227.969318)
		(mid 135.117492 -228.172997)
		(end 135.039862 -228.45141)
		(width 0.088646)
		(layer "In4.Cu")
		(net "M_F_CPU1_SB_DQ<24>")
	)
	(arc
		(start 138.912092 -223.140778)
		(mid 138.805993 -223.126828)
		(end 138.707114 -223.085914)
		(width 0.088646)
		(layer "In4.Cu")
		(net "M_F_CPU1_SB_DQ<24>")
	)
	(arc
		(start 135.039862 -228.45903)
		(mid 134.992183 -228.64193)
		(end 134.8613 -228.778308)
		(width 0.088646)
		(layer "In4.Cu")
		(net "M_F_CPU1_SB_DQ<24>")
	)
	(arc
		(start 135.510016 -227.64496)
		(mid 135.462337 -227.82786)
		(end 135.331454 -227.964238)
		(width 0.088646)
		(layer "In4.Cu")
		(net "M_F_CPU1_SB_DQ<24>")
	)
	(arc
		(start 136.732264 -225.527616)
		(mid 136.528783 -225.72842)
		(end 136.449562 -226.003104)
		(width 0.088646)
		(layer "In4.Cu")
		(net "M_F_CPU1_SB_DQ<24>")
	)
	(arc
		(start 132.503164 -229.597204)
		(mid 132.128467 -229.597323)
		(end 131.941062 -229.272846)
		(width 0.088646)
		(layer "In4.Cu")
		(net "M_F_CPU1_SB_DQ<24>")
	)
	(arc
		(start 131.941062 -229.268528)
		(mid 131.660428 -228.784267)
		(end 131.10083 -228.77907)
		(width 0.088646)
		(layer "In4.Cu")
		(net "M_F_CPU1_SB_DQ<24>")
	)
	(arc
		(start 136.449562 -226.025964)
		(mid 136.397292 -226.208329)
		(end 136.262364 -226.341686)
		(width 0.088646)
		(layer "In4.Cu")
		(net "M_F_CPU1_SB_DQ<24>")
	)
	(arc
		(start 134.570216 -229.272846)
		(mid 134.522537 -229.455746)
		(end 134.391654 -229.592124)
		(width 0.088646)
		(layer "In4.Cu")
		(net "M_F_CPU1_SB_DQ<24>")
	)
	(arc
		(start 137.859516 -223.575626)
		(mid 137.811837 -223.758526)
		(end 137.680954 -223.894904)
		(width 0.088646)
		(layer "In4.Cu")
		(net "M_F_CPU1_SB_DQ<24>")
	)
	(arc
		(start 134.85241 -228.783388)
		(mid 134.649587 -228.983619)
		(end 134.570216 -229.257352)
		(width 0.088646)
		(layer "In4.Cu")
		(net "M_F_CPU1_SB_DQ<24>")
	)
	(segment
		(start 176.896014 -204.96657)
		(end 178.000914 -204.96657)
		(width 0.20066)
		(layer "F.Cu")
		(net "M_F_CPU1_SB_DQ<23>")
	)
	(segment
		(start 180.427884 -205.398624)
		(end 180.434996 -205.391512)
		(width 0.1016)
		(layer "F.Cu")
		(net "M_F_CPU1_SB_DQ<23>")
	)
	(segment
		(start 180.131212 -205.398624)
		(end 180.423058 -205.398624)
		(width 0.20066)
		(layer "F.Cu")
		(net "M_F_CPU1_SB_DQ<23>")
	)
	(segment
		(start 179.699158 -204.96657)
		(end 180.131212 -205.398624)
		(width 0.20066)
		(layer "F.Cu")
		(net "M_F_CPU1_SB_DQ<23>")
	)
	(segment
		(start 180.434996 -205.391512)
		(end 182.442866 -205.391512)
		(width 0.1016)
		(layer "F.Cu")
		(net "M_F_CPU1_SB_DQ<23>")
	)
	(segment
		(start 183.958484 -204.714602)
		(end 184.210452 -204.96657)
		(width 0.20066)
		(layer "F.Cu")
		(net "M_F_CPU1_SB_DQ<23>")
	)
	(segment
		(start 184.210452 -204.96657)
		(end 185.544714 -204.96657)
		(width 0.20066)
		(layer "F.Cu")
		(net "M_F_CPU1_SB_DQ<23>")
	)
	(segment
		(start 178.000914 -204.96657)
		(end 179.699158 -204.96657)
		(width 0.20066)
		(layer "F.Cu")
		(net "M_F_CPU1_SB_DQ<23>")
	)
	(segment
		(start 182.455058 -205.403704)
		(end 183.136286 -205.403704)
		(width 0.20066)
		(layer "F.Cu")
		(net "M_F_CPU1_SB_DQ<23>")
	)
	(segment
		(start 182.442866 -205.391512)
		(end 182.455058 -205.403704)
		(width 0.1016)
		(layer "F.Cu")
		(net "M_F_CPU1_SB_DQ<23>")
	)
	(segment
		(start 183.574436 -204.714602)
		(end 183.958484 -204.714602)
		(width 0.20066)
		(layer "F.Cu")
		(net "M_F_CPU1_SB_DQ<23>")
	)
	(segment
		(start 183.136286 -205.403704)
		(end 183.340248 -205.199742)
		(width 0.20066)
		(layer "F.Cu")
		(net "M_F_CPU1_SB_DQ<23>")
	)
	(segment
		(start 183.340248 -205.199742)
		(end 183.340248 -204.94879)
		(width 0.20066)
		(layer "F.Cu")
		(net "M_F_CPU1_SB_DQ<23>")
	)
	(segment
		(start 180.423058 -205.398624)
		(end 180.427884 -205.398624)
		(width 0.101854)
		(layer "F.Cu")
		(net "M_F_CPU1_SB_DQ<23>")
	)
	(segment
		(start 137.954766 -221.133924)
		(end 137.954766 -221.669864)
		(width 0.20066)
		(layer "F.Cu")
		(net "M_F_CPU1_SB_DQ<23>")
	)
	(segment
		(start 183.340248 -204.94879)
		(end 183.574436 -204.714602)
		(width 0.20066)
		(layer "F.Cu")
		(net "M_F_CPU1_SB_DQ<23>")
	)
	(segment
		(start 175.692562 -205.715616)
		(end 174.653702 -206.242412)
		(width 0.18288)
		(layer "In2.Cu")
		(net "M_F_CPU1_SB_DQ<23>")
	)
	(segment
		(start 161.389822 -202.766676)
		(end 160.070038 -202.766676)
		(width 0.18288)
		(layer "In2.Cu")
		(net "M_F_CPU1_SB_DQ<23>")
	)
	(segment
		(start 165.295834 -202.700128)
		(end 164.536882 -202.700128)
		(width 0.18288)
		(layer "In2.Cu")
		(net "M_F_CPU1_SB_DQ<23>")
	)
	(segment
		(start 155.439618 -204.422502)
		(end 155.439618 -204.597)
		(width 0.18288)
		(layer "In2.Cu")
		(net "M_F_CPU1_SB_DQ<23>")
	)
	(segment
		(start 141.305534 -218.731084)
		(end 140.776198 -219.26042)
		(width 0.088646)
		(layer "In2.Cu")
		(net "M_F_CPU1_SB_DQ<23>")
	)
	(segment
		(start 157.033468 -202.828652)
		(end 155.439618 -204.422502)
		(width 0.18288)
		(layer "In2.Cu")
		(net "M_F_CPU1_SB_DQ<23>")
	)
	(segment
		(start 138.050016 -220.319854)
		(end 138.050016 -220.338396)
		(width 0.088646)
		(layer "In2.Cu")
		(net "M_F_CPU1_SB_DQ<23>")
	)
	(segment
		(start 155.439618 -204.597)
		(end 141.305534 -218.731084)
		(width 0.18288)
		(layer "In2.Cu")
		(net "M_F_CPU1_SB_DQ<23>")
	)
	(segment
		(start 138.237468 -219.995496)
		(end 138.228578 -220.000576)
		(width 0.088646)
		(layer "In2.Cu")
		(net "M_F_CPU1_SB_DQ<23>")
	)
	(segment
		(start 137.641838 -221.133924)
		(end 137.954766 -221.133924)
		(width 0.088646)
		(layer "In2.Cu")
		(net "M_F_CPU1_SB_DQ<23>")
	)
	(segment
		(start 170.36669 -203.654914)
		(end 168.397428 -203.654914)
		(width 0.18288)
		(layer "In2.Cu")
		(net "M_F_CPU1_SB_DQ<23>")
	)
	(segment
		(start 172.15104 -205.876144)
		(end 171.269152 -204.557376)
		(width 0.18288)
		(layer "In2.Cu")
		(net "M_F_CPU1_SB_DQ<23>")
	)
	(segment
		(start 167.343582 -203.699872)
		(end 166.555928 -203.373736)
		(width 0.18288)
		(layer "In2.Cu")
		(net "M_F_CPU1_SB_DQ<23>")
	)
	(segment
		(start 160.008062 -202.828652)
		(end 157.033468 -202.828652)
		(width 0.18288)
		(layer "In2.Cu")
		(net "M_F_CPU1_SB_DQ<23>")
	)
	(segment
		(start 175.746664 -205.549754)
		(end 175.692562 -205.715616)
		(width 0.18288)
		(layer "In2.Cu")
		(net "M_F_CPU1_SB_DQ<23>")
	)
	(segment
		(start 140.776198 -219.26042)
		(end 140.311378 -219.26042)
		(width 0.088646)
		(layer "In2.Cu")
		(net "M_F_CPU1_SB_DQ<23>")
	)
	(segment
		(start 139.646914 -219.18168)
		(end 139.632182 -219.190316)
		(width 0.088646)
		(layer "In2.Cu")
		(net "M_F_CPU1_SB_DQ<23>")
	)
	(segment
		(start 137.767568 -220.809566)
		(end 137.758678 -220.814646)
		(width 0.088646)
		(layer "In2.Cu")
		(net "M_F_CPU1_SB_DQ<23>")
	)
	(segment
		(start 164.387022 -202.849988)
		(end 161.473134 -202.849988)
		(width 0.18288)
		(layer "In2.Cu")
		(net "M_F_CPU1_SB_DQ<23>")
	)
	(segment
		(start 161.473134 -202.849988)
		(end 161.389822 -202.766676)
		(width 0.18288)
		(layer "In2.Cu")
		(net "M_F_CPU1_SB_DQ<23>")
	)
	(segment
		(start 164.536882 -202.700128)
		(end 164.387022 -202.849988)
		(width 0.18288)
		(layer "In2.Cu")
		(net "M_F_CPU1_SB_DQ<23>")
	)
	(segment
		(start 137.584688 -221.076774)
		(end 137.641838 -221.133924)
		(width 0.088646)
		(layer "In2.Cu")
		(net "M_F_CPU1_SB_DQ<23>")
	)
	(segment
		(start 160.070038 -202.766676)
		(end 160.008062 -202.828652)
		(width 0.18288)
		(layer "In2.Cu")
		(net "M_F_CPU1_SB_DQ<23>")
	)
	(segment
		(start 176.896014 -204.96657)
		(end 175.746664 -205.549754)
		(width 0.18288)
		(layer "In2.Cu")
		(net "M_F_CPU1_SB_DQ<23>")
	)
	(segment
		(start 140.311378 -219.26042)
		(end 140.311378 -219.257626)
		(width 0.088646)
		(layer "In2.Cu")
		(net "M_F_CPU1_SB_DQ<23>")
	)
	(segment
		(start 166.555928 -203.373736)
		(end 165.295834 -202.700128)
		(width 0.18288)
		(layer "In2.Cu")
		(net "M_F_CPU1_SB_DQ<23>")
	)
	(segment
		(start 171.269152 -204.557376)
		(end 170.36669 -203.654914)
		(width 0.18288)
		(layer "In2.Cu")
		(net "M_F_CPU1_SB_DQ<23>")
	)
	(segment
		(start 168.35247 -203.699872)
		(end 167.343582 -203.699872)
		(width 0.18288)
		(layer "In2.Cu")
		(net "M_F_CPU1_SB_DQ<23>")
	)
	(segment
		(start 168.397428 -203.654914)
		(end 168.35247 -203.699872)
		(width 0.18288)
		(layer "In2.Cu")
		(net "M_F_CPU1_SB_DQ<23>")
	)
	(segment
		(start 138.707114 -219.18168)
		(end 138.698224 -219.18676)
		(width 0.088646)
		(layer "In2.Cu")
		(net "M_F_CPU1_SB_DQ<23>")
	)
	(segment
		(start 172.517308 -206.242412)
		(end 172.15104 -205.876144)
		(width 0.18288)
		(layer "In2.Cu")
		(net "M_F_CPU1_SB_DQ<23>")
	)
	(segment
		(start 138.519662 -219.506038)
		(end 138.519662 -219.521532)
		(width 0.088646)
		(layer "In2.Cu")
		(net "M_F_CPU1_SB_DQ<23>")
	)
	(segment
		(start 174.653702 -206.242412)
		(end 172.517308 -206.242412)
		(width 0.18288)
		(layer "In2.Cu")
		(net "M_F_CPU1_SB_DQ<23>")
	)
	(arc
		(start 138.698224 -219.18676)
		(mid 138.56731 -219.32312)
		(end 138.519662 -219.506038)
		(width 0.088646)
		(layer "In2.Cu")
		(net "M_F_CPU1_SB_DQ<23>")
	)
	(arc
		(start 139.632182 -219.190316)
		(mid 139.355707 -219.257636)
		(end 139.08151 -219.18168)
		(width 0.088646)
		(layer "In2.Cu")
		(net "M_F_CPU1_SB_DQ<23>")
	)
	(arc
		(start 138.228578 -220.000576)
		(mid 138.097664 -220.136936)
		(end 138.050016 -220.319854)
		(width 0.088646)
		(layer "In2.Cu")
		(net "M_F_CPU1_SB_DQ<23>")
	)
	(arc
		(start 140.311378 -219.257626)
		(mid 140.161227 -219.23921)
		(end 140.02131 -219.18168)
		(width 0.088646)
		(layer "In2.Cu")
		(net "M_F_CPU1_SB_DQ<23>")
	)
	(arc
		(start 138.050016 -220.338396)
		(mid 137.969854 -220.610585)
		(end 137.767568 -220.809566)
		(width 0.088646)
		(layer "In2.Cu")
		(net "M_F_CPU1_SB_DQ<23>")
	)
	(arc
		(start 137.758678 -220.814646)
		(mid 137.642869 -220.926575)
		(end 137.584688 -221.076774)
		(width 0.088646)
		(layer "In2.Cu")
		(net "M_F_CPU1_SB_DQ<23>")
	)
	(arc
		(start 138.519662 -219.521532)
		(mid 138.440292 -219.795266)
		(end 138.237468 -219.995496)
		(width 0.088646)
		(layer "In2.Cu")
		(net "M_F_CPU1_SB_DQ<23>")
	)
	(arc
		(start 139.08151 -219.18168)
		(mid 138.894312 -219.131537)
		(end 138.707114 -219.18168)
		(width 0.088646)
		(layer "In2.Cu")
		(net "M_F_CPU1_SB_DQ<23>")
	)
	(arc
		(start 140.02131 -219.18168)
		(mid 139.834112 -219.131537)
		(end 139.646914 -219.18168)
		(width 0.088646)
		(layer "In2.Cu")
		(net "M_F_CPU1_SB_DQ<23>")
	)
	(segment
		(start 180.131212 -207.098646)
		(end 180.423058 -207.098646)
		(width 0.20066)
		(layer "F.Cu")
		(net "M_F_CPU1_SB_DQ<22>")
	)
	(segment
		(start 183.340248 -206.899764)
		(end 183.340248 -206.648812)
		(width 0.20066)
		(layer "F.Cu")
		(net "M_F_CPU1_SB_DQ<22>")
	)
	(segment
		(start 180.427884 -207.098646)
		(end 180.434996 -207.091534)
		(width 0.1016)
		(layer "F.Cu")
		(net "M_F_CPU1_SB_DQ<22>")
	)
	(segment
		(start 178.000914 -206.666592)
		(end 179.699158 -206.666592)
		(width 0.20066)
		(layer "F.Cu")
		(net "M_F_CPU1_SB_DQ<22>")
	)
	(segment
		(start 180.434996 -207.091534)
		(end 182.442866 -207.091534)
		(width 0.1016)
		(layer "F.Cu")
		(net "M_F_CPU1_SB_DQ<22>")
	)
	(segment
		(start 183.340248 -206.648812)
		(end 183.574436 -206.414624)
		(width 0.20066)
		(layer "F.Cu")
		(net "M_F_CPU1_SB_DQ<22>")
	)
	(segment
		(start 180.423058 -207.098646)
		(end 180.427884 -207.098646)
		(width 0.101854)
		(layer "F.Cu")
		(net "M_F_CPU1_SB_DQ<22>")
	)
	(segment
		(start 182.455058 -207.103726)
		(end 183.136286 -207.103726)
		(width 0.20066)
		(layer "F.Cu")
		(net "M_F_CPU1_SB_DQ<22>")
	)
	(segment
		(start 183.136286 -207.103726)
		(end 183.340248 -206.899764)
		(width 0.20066)
		(layer "F.Cu")
		(net "M_F_CPU1_SB_DQ<22>")
	)
	(segment
		(start 183.958484 -206.414624)
		(end 184.210452 -206.666592)
		(width 0.20066)
		(layer "F.Cu")
		(net "M_F_CPU1_SB_DQ<22>")
	)
	(segment
		(start 184.210452 -206.666592)
		(end 185.544714 -206.666592)
		(width 0.20066)
		(layer "F.Cu")
		(net "M_F_CPU1_SB_DQ<22>")
	)
	(segment
		(start 179.699158 -206.666592)
		(end 180.131212 -207.098646)
		(width 0.20066)
		(layer "F.Cu")
		(net "M_F_CPU1_SB_DQ<22>")
	)
	(segment
		(start 176.896014 -206.666592)
		(end 178.000914 -206.666592)
		(width 0.20066)
		(layer "F.Cu")
		(net "M_F_CPU1_SB_DQ<22>")
	)
	(segment
		(start 183.574436 -206.414624)
		(end 183.958484 -206.414624)
		(width 0.20066)
		(layer "F.Cu")
		(net "M_F_CPU1_SB_DQ<22>")
	)
	(segment
		(start 138.424666 -222.48368)
		(end 138.424666 -221.94774)
		(width 0.20066)
		(layer "F.Cu")
		(net "M_F_CPU1_SB_DQ<22>")
	)
	(segment
		(start 182.442866 -207.091534)
		(end 182.455058 -207.103726)
		(width 0.1016)
		(layer "F.Cu")
		(net "M_F_CPU1_SB_DQ<22>")
	)
	(segment
		(start 162.006534 -203.689966)
		(end 161.818828 -203.50226)
		(width 0.18288)
		(layer "In2.Cu")
		(net "M_F_CPU1_SB_DQ<22>")
	)
	(segment
		(start 176.42332 -207.601058)
		(end 176.23028 -207.794098)
		(width 0.18288)
		(layer "In2.Cu")
		(net "M_F_CPU1_SB_DQ<22>")
	)
	(segment
		(start 159.384238 -203.336652)
		(end 158.228538 -203.336652)
		(width 0.18288)
		(layer "In2.Cu")
		(net "M_F_CPU1_SB_DQ<22>")
	)
	(segment
		(start 158.228538 -203.336652)
		(end 157.862778 -203.702412)
		(width 0.18288)
		(layer "In2.Cu")
		(net "M_F_CPU1_SB_DQ<22>")
	)
	(segment
		(start 139.090654 -221.453202)
		(end 139.081764 -221.458282)
		(width 0.088646)
		(layer "In2.Cu")
		(net "M_F_CPU1_SB_DQ<22>")
	)
	(segment
		(start 156.034994 -204.591412)
		(end 156.034994 -204.852016)
		(width 0.18288)
		(layer "In2.Cu")
		(net "M_F_CPU1_SB_DQ<22>")
	)
	(segment
		(start 157.862778 -203.702412)
		(end 156.923994 -203.702412)
		(width 0.18288)
		(layer "In2.Cu")
		(net "M_F_CPU1_SB_DQ<22>")
	)
	(segment
		(start 140.678916 -220.208094)
		(end 140.678916 -220.319854)
		(width 0.088646)
		(layer "In2.Cu")
		(net "M_F_CPU1_SB_DQ<22>")
	)
	(segment
		(start 168.796208 -204.283056)
		(end 167.620696 -204.283056)
		(width 0.18288)
		(layer "In2.Cu")
		(net "M_F_CPU1_SB_DQ<22>")
	)
	(segment
		(start 139.081764 -221.458282)
		(end 139.053062 -221.474792)
		(width 0.088646)
		(layer "In2.Cu")
		(net "M_F_CPU1_SB_DQ<22>")
	)
	(segment
		(start 170.51147 -206.252826)
		(end 169.480738 -205.222094)
		(width 0.18288)
		(layer "In2.Cu")
		(net "M_F_CPU1_SB_DQ<22>")
	)
	(segment
		(start 156.923994 -203.702412)
		(end 156.034994 -204.591412)
		(width 0.18288)
		(layer "In2.Cu")
		(net "M_F_CPU1_SB_DQ<22>")
	)
	(segment
		(start 159.782256 -203.73467)
		(end 159.384238 -203.336652)
		(width 0.18288)
		(layer "In2.Cu")
		(net "M_F_CPU1_SB_DQ<22>")
	)
	(segment
		(start 141.73073 -219.15628)
		(end 140.678916 -220.208094)
		(width 0.088646)
		(layer "In2.Cu")
		(net "M_F_CPU1_SB_DQ<22>")
	)
	(segment
		(start 176.23028 -207.794098)
		(end 175.510698 -207.794098)
		(width 0.18288)
		(layer "In2.Cu")
		(net "M_F_CPU1_SB_DQ<22>")
	)
	(segment
		(start 167.365934 -204.537818)
		(end 165.443916 -204.537818)
		(width 0.18288)
		(layer "In2.Cu")
		(net "M_F_CPU1_SB_DQ<22>")
	)
	(segment
		(start 175.510698 -207.794098)
		(end 174.807626 -207.091026)
		(width 0.18288)
		(layer "In2.Cu")
		(net "M_F_CPU1_SB_DQ<22>")
	)
	(segment
		(start 161.818828 -203.50226)
		(end 160.370774 -203.50226)
		(width 0.18288)
		(layer "In2.Cu")
		(net "M_F_CPU1_SB_DQ<22>")
	)
	(segment
		(start 172.61586 -207.090772)
		(end 171.777914 -206.252826)
		(width 0.18288)
		(layer "In2.Cu")
		(net "M_F_CPU1_SB_DQ<22>")
	)
	(segment
		(start 164.167058 -203.689966)
		(end 162.006534 -203.689966)
		(width 0.18288)
		(layer "In2.Cu")
		(net "M_F_CPU1_SB_DQ<22>")
	)
	(segment
		(start 165.443916 -204.537818)
		(end 164.167058 -203.689966)
		(width 0.18288)
		(layer "In2.Cu")
		(net "M_F_CPU1_SB_DQ<22>")
	)
	(segment
		(start 160.370774 -203.50226)
		(end 160.138364 -203.73467)
		(width 0.18288)
		(layer "In2.Cu")
		(net "M_F_CPU1_SB_DQ<22>")
	)
	(segment
		(start 171.777914 -206.252826)
		(end 170.51147 -206.252826)
		(width 0.18288)
		(layer "In2.Cu")
		(net "M_F_CPU1_SB_DQ<22>")
	)
	(segment
		(start 169.480738 -205.222094)
		(end 169.480738 -204.967586)
		(width 0.18288)
		(layer "In2.Cu")
		(net "M_F_CPU1_SB_DQ<22>")
	)
	(segment
		(start 167.620696 -204.283056)
		(end 167.365934 -204.537818)
		(width 0.18288)
		(layer "In2.Cu")
		(net "M_F_CPU1_SB_DQ<22>")
	)
	(segment
		(start 156.034994 -204.852016)
		(end 141.73073 -219.15628)
		(width 0.18288)
		(layer "In2.Cu")
		(net "M_F_CPU1_SB_DQ<22>")
	)
	(segment
		(start 174.807626 -207.091026)
		(end 172.749718 -207.091026)
		(width 0.18288)
		(layer "In2.Cu")
		(net "M_F_CPU1_SB_DQ<22>")
	)
	(segment
		(start 139.269216 -221.115382)
		(end 139.269216 -221.133924)
		(width 0.088646)
		(layer "In2.Cu")
		(net "M_F_CPU1_SB_DQ<22>")
	)
	(segment
		(start 176.42332 -207.139286)
		(end 176.42332 -207.601058)
		(width 0.18288)
		(layer "In2.Cu")
		(net "M_F_CPU1_SB_DQ<22>")
	)
	(segment
		(start 140.500354 -220.639132)
		(end 140.491464 -220.644212)
		(width 0.088646)
		(layer "In2.Cu")
		(net "M_F_CPU1_SB_DQ<22>")
	)
	(segment
		(start 139.053062 -221.474792)
		(end 138.424666 -221.94774)
		(width 0.088646)
		(layer "In2.Cu")
		(net "M_F_CPU1_SB_DQ<22>")
	)
	(segment
		(start 172.749718 -207.091026)
		(end 172.61586 -207.090772)
		(width 0.18288)
		(layer "In2.Cu")
		(net "M_F_CPU1_SB_DQ<22>")
	)
	(segment
		(start 169.480738 -204.967586)
		(end 168.796208 -204.283056)
		(width 0.18288)
		(layer "In2.Cu")
		(net "M_F_CPU1_SB_DQ<22>")
	)
	(segment
		(start 160.138364 -203.73467)
		(end 159.782256 -203.73467)
		(width 0.18288)
		(layer "In2.Cu")
		(net "M_F_CPU1_SB_DQ<22>")
	)
	(segment
		(start 176.896014 -206.666592)
		(end 176.42332 -207.139286)
		(width 0.18288)
		(layer "In2.Cu")
		(net "M_F_CPU1_SB_DQ<22>")
	)
	(arc
		(start 140.678916 -220.319854)
		(mid 140.631237 -220.502754)
		(end 140.500354 -220.639132)
		(width 0.088646)
		(layer "In2.Cu")
		(net "M_F_CPU1_SB_DQ<22>")
	)
	(arc
		(start 139.269216 -221.133924)
		(mid 139.221537 -221.316824)
		(end 139.090654 -221.453202)
		(width 0.088646)
		(layer "In2.Cu")
		(net "M_F_CPU1_SB_DQ<22>")
	)
	(arc
		(start 140.117068 -220.644212)
		(mid 139.834366 -220.56847)
		(end 139.551664 -220.644212)
		(width 0.088646)
		(layer "In2.Cu")
		(net "M_F_CPU1_SB_DQ<22>")
	)
	(arc
		(start 140.491464 -220.644212)
		(mid 140.304266 -220.694355)
		(end 140.117068 -220.644212)
		(width 0.088646)
		(layer "In2.Cu")
		(net "M_F_CPU1_SB_DQ<22>")
	)
	(arc
		(start 139.551664 -220.644212)
		(mid 139.349378 -220.843193)
		(end 139.269216 -221.115382)
		(width 0.088646)
		(layer "In2.Cu")
		(net "M_F_CPU1_SB_DQ<22>")
	)
	(segment
		(start 176.796192 -205.391766)
		(end 176.451514 -205.391766)
		(width 0.20066)
		(layer "F.Cu")
		(net "M_F_CPU1_SB_DQ<21>")
	)
	(segment
		(start 176.145444 -206.065374)
		(end 175.67021 -206.065374)
		(width 0.20066)
		(layer "F.Cu")
		(net "M_F_CPU1_SB_DQ<21>")
	)
	(segment
		(start 176.333404 -205.877414)
		(end 176.145444 -206.065374)
		(width 0.20066)
		(layer "F.Cu")
		(net "M_F_CPU1_SB_DQ<21>")
	)
	(segment
		(start 137.014712 -221.669864)
		(end 137.014712 -221.134178)
		(width 0.20066)
		(layer "F.Cu")
		(net "M_F_CPU1_SB_DQ<21>")
	)
	(segment
		(start 176.816258 -205.391766)
		(end 176.796192 -205.391766)
		(width 0.101854)
		(layer "F.Cu")
		(net "M_F_CPU1_SB_DQ<21>")
	)
	(segment
		(start 179.011326 -205.385416)
		(end 179.004976 -205.391766)
		(width 0.1016)
		(layer "F.Cu")
		(net "M_F_CPU1_SB_DQ<21>")
	)
	(segment
		(start 175.421544 -205.816708)
		(end 173.900846 -205.816708)
		(width 0.20066)
		(layer "F.Cu")
		(net "M_F_CPU1_SB_DQ<21>")
	)
	(segment
		(start 179.004976 -205.391766)
		(end 176.816258 -205.391766)
		(width 0.1016)
		(layer "F.Cu")
		(net "M_F_CPU1_SB_DQ<21>")
	)
	(segment
		(start 176.451514 -205.391766)
		(end 176.333404 -205.509876)
		(width 0.20066)
		(layer "F.Cu")
		(net "M_F_CPU1_SB_DQ<21>")
	)
	(segment
		(start 179.852828 -205.816962)
		(end 179.421282 -205.385416)
		(width 0.20066)
		(layer "F.Cu")
		(net "M_F_CPU1_SB_DQ<21>")
	)
	(segment
		(start 181.444392 -205.816962)
		(end 179.852828 -205.816962)
		(width 0.20066)
		(layer "F.Cu")
		(net "M_F_CPU1_SB_DQ<21>")
	)
	(segment
		(start 137.014712 -221.134178)
		(end 137.014966 -221.133924)
		(width 0.20066)
		(layer "F.Cu")
		(net "M_F_CPU1_SB_DQ<21>")
	)
	(segment
		(start 173.900846 -205.816708)
		(end 172.795946 -205.816708)
		(width 0.20066)
		(layer "F.Cu")
		(net "M_F_CPU1_SB_DQ<21>")
	)
	(segment
		(start 175.67021 -206.065374)
		(end 175.421544 -205.816708)
		(width 0.20066)
		(layer "F.Cu")
		(net "M_F_CPU1_SB_DQ<21>")
	)
	(segment
		(start 179.421282 -205.385416)
		(end 179.011326 -205.385416)
		(width 0.20066)
		(layer "F.Cu")
		(net "M_F_CPU1_SB_DQ<21>")
	)
	(segment
		(start 176.333404 -205.509876)
		(end 176.333404 -205.877414)
		(width 0.20066)
		(layer "F.Cu")
		(net "M_F_CPU1_SB_DQ<21>")
	)
	(segment
		(start 181.444646 -205.816708)
		(end 181.444392 -205.816962)
		(width 0.20066)
		(layer "F.Cu")
		(net "M_F_CPU1_SB_DQ<21>")
	)
	(segment
		(start 137.859516 -220.30436)
		(end 137.859516 -220.319854)
		(width 0.088646)
		(layer "In2.Cu")
		(net "M_F_CPU1_SB_DQ<21>")
	)
	(segment
		(start 167.549576 -202.650852)
		(end 167.549576 -202.311762)
		(width 0.18288)
		(layer "In2.Cu")
		(net "M_F_CPU1_SB_DQ<21>")
	)
	(segment
		(start 138.626596 -219.007944)
		(end 138.611864 -219.01658)
		(width 0.088646)
		(layer "In2.Cu")
		(net "M_F_CPU1_SB_DQ<21>")
	)
	(segment
		(start 164.877496 -201.995278)
		(end 164.771324 -201.889106)
		(width 0.18288)
		(layer "In2.Cu")
		(net "M_F_CPU1_SB_DQ<21>")
	)
	(segment
		(start 139.566396 -219.007944)
		(end 139.551664 -219.01658)
		(width 0.088646)
		(layer "In2.Cu")
		(net "M_F_CPU1_SB_DQ<21>")
	)
	(segment
		(start 159.73679 -202.039982)
		(end 159.145986 -201.449178)
		(width 0.18288)
		(layer "In2.Cu")
		(net "M_F_CPU1_SB_DQ<21>")
	)
	(segment
		(start 170.836844 -202.843892)
		(end 170.643804 -202.650852)
		(width 0.18288)
		(layer "In2.Cu")
		(net "M_F_CPU1_SB_DQ<21>")
	)
	(segment
		(start 169.939716 -202.367896)
		(end 169.939716 -202.650852)
		(width 0.18288)
		(layer "In2.Cu")
		(net "M_F_CPU1_SB_DQ<21>")
	)
	(segment
		(start 138.611864 -219.01658)
		(end 138.605768 -219.020136)
		(width 0.088646)
		(layer "In2.Cu")
		(net "M_F_CPU1_SB_DQ<21>")
	)
	(segment
		(start 140.695426 -218.494864)
		(end 140.695426 -218.771724)
		(width 0.088646)
		(layer "In2.Cu")
		(net "M_F_CPU1_SB_DQ<21>")
	)
	(segment
		(start 137.327894 -221.133924)
		(end 137.014966 -221.133924)
		(width 0.088646)
		(layer "In2.Cu")
		(net "M_F_CPU1_SB_DQ<21>")
	)
	(segment
		(start 172.214032 -203.684632)
		(end 171.373292 -202.843892)
		(width 0.18288)
		(layer "In2.Cu")
		(net "M_F_CPU1_SB_DQ<21>")
	)
	(segment
		(start 138.1506 -219.825316)
		(end 138.14171 -219.830396)
		(width 0.088646)
		(layer "In2.Cu")
		(net "M_F_CPU1_SB_DQ<21>")
	)
	(segment
		(start 172.628306 -205.41234)
		(end 172.327316 -205.11135)
		(width 0.18288)
		(layer "In2.Cu")
		(net "M_F_CPU1_SB_DQ<21>")
	)
	(segment
		(start 164.771324 -201.889106)
		(end 163.861496 -201.889106)
		(width 0.18288)
		(layer "In2.Cu")
		(net "M_F_CPU1_SB_DQ<21>")
	)
	(segment
		(start 162.238944 -202.155044)
		(end 161.502852 -201.418952)
		(width 0.18288)
		(layer "In2.Cu")
		(net "M_F_CPU1_SB_DQ<21>")
	)
	(segment
		(start 170.4213 -202.145392)
		(end 170.16222 -202.145392)
		(width 0.18288)
		(layer "In2.Cu")
		(net "M_F_CPU1_SB_DQ<21>")
	)
	(segment
		(start 169.939716 -202.650852)
		(end 169.746676 -202.843892)
		(width 0.18288)
		(layer "In2.Cu")
		(net "M_F_CPU1_SB_DQ<21>")
	)
	(segment
		(start 137.392918 -221.0689)
		(end 137.327894 -221.133924)
		(width 0.088646)
		(layer "In2.Cu")
		(net "M_F_CPU1_SB_DQ<21>")
	)
	(segment
		(start 163.595558 -202.155044)
		(end 162.238944 -202.155044)
		(width 0.18288)
		(layer "In2.Cu")
		(net "M_F_CPU1_SB_DQ<21>")
	)
	(segment
		(start 170.643804 -202.650852)
		(end 170.643804 -202.367896)
		(width 0.18288)
		(layer "In2.Cu")
		(net "M_F_CPU1_SB_DQ<21>")
	)
	(segment
		(start 167.233092 -201.995278)
		(end 164.877496 -201.995278)
		(width 0.18288)
		(layer "In2.Cu")
		(net "M_F_CPU1_SB_DQ<21>")
	)
	(segment
		(start 156.754322 -202.02652)
		(end 154.917648 -203.863194)
		(width 0.18288)
		(layer "In2.Cu")
		(net "M_F_CPU1_SB_DQ<21>")
	)
	(segment
		(start 172.795946 -205.816708)
		(end 172.683678 -205.546198)
		(width 0.18288)
		(layer "In2.Cu")
		(net "M_F_CPU1_SB_DQ<21>")
	)
	(segment
		(start 169.746676 -202.843892)
		(end 167.742616 -202.843892)
		(width 0.18288)
		(layer "In2.Cu")
		(net "M_F_CPU1_SB_DQ<21>")
	)
	(segment
		(start 170.16222 -202.145392)
		(end 169.939716 -202.367896)
		(width 0.18288)
		(layer "In2.Cu")
		(net "M_F_CPU1_SB_DQ<21>")
	)
	(segment
		(start 160.26765 -202.039982)
		(end 159.73679 -202.039982)
		(width 0.18288)
		(layer "In2.Cu")
		(net "M_F_CPU1_SB_DQ<21>")
	)
	(segment
		(start 172.683678 -205.546198)
		(end 172.628306 -205.41234)
		(width 0.18288)
		(layer "In2.Cu")
		(net "M_F_CPU1_SB_DQ<21>")
	)
	(segment
		(start 157.859984 -202.02652)
		(end 156.754322 -202.02652)
		(width 0.18288)
		(layer "In2.Cu")
		(net "M_F_CPU1_SB_DQ<21>")
	)
	(segment
		(start 172.214032 -204.838046)
		(end 172.214032 -203.684632)
		(width 0.18288)
		(layer "In2.Cu")
		(net "M_F_CPU1_SB_DQ<21>")
	)
	(segment
		(start 161.502852 -201.418952)
		(end 160.88868 -201.418952)
		(width 0.18288)
		(layer "In2.Cu")
		(net "M_F_CPU1_SB_DQ<21>")
	)
	(segment
		(start 160.88868 -201.418952)
		(end 160.26765 -202.039982)
		(width 0.18288)
		(layer "In2.Cu")
		(net "M_F_CPU1_SB_DQ<21>")
	)
	(segment
		(start 172.327316 -205.11135)
		(end 172.214032 -204.838046)
		(width 0.18288)
		(layer "In2.Cu")
		(net "M_F_CPU1_SB_DQ<21>")
	)
	(segment
		(start 170.643804 -202.367896)
		(end 170.4213 -202.145392)
		(width 0.18288)
		(layer "In2.Cu")
		(net "M_F_CPU1_SB_DQ<21>")
	)
	(segment
		(start 167.549576 -202.311762)
		(end 167.233092 -201.995278)
		(width 0.18288)
		(layer "In2.Cu")
		(net "M_F_CPU1_SB_DQ<21>")
	)
	(segment
		(start 171.373292 -202.843892)
		(end 170.836844 -202.843892)
		(width 0.18288)
		(layer "In2.Cu")
		(net "M_F_CPU1_SB_DQ<21>")
	)
	(segment
		(start 140.88237 -218.30792)
		(end 140.695426 -218.494864)
		(width 0.088646)
		(layer "In2.Cu")
		(net "M_F_CPU1_SB_DQ<21>")
	)
	(segment
		(start 154.917648 -203.863194)
		(end 154.917648 -204.272642)
		(width 0.18288)
		(layer "In2.Cu")
		(net "M_F_CPU1_SB_DQ<21>")
	)
	(segment
		(start 163.861496 -201.889106)
		(end 163.595558 -202.155044)
		(width 0.18288)
		(layer "In2.Cu")
		(net "M_F_CPU1_SB_DQ<21>")
	)
	(segment
		(start 167.742616 -202.843892)
		(end 167.549576 -202.650852)
		(width 0.18288)
		(layer "In2.Cu")
		(net "M_F_CPU1_SB_DQ<21>")
	)
	(segment
		(start 154.917648 -204.272642)
		(end 140.88237 -218.30792)
		(width 0.18288)
		(layer "In2.Cu")
		(net "M_F_CPU1_SB_DQ<21>")
	)
	(segment
		(start 140.400532 -219.066618)
		(end 140.311378 -219.066618)
		(width 0.088646)
		(layer "In2.Cu")
		(net "M_F_CPU1_SB_DQ<21>")
	)
	(segment
		(start 140.695426 -218.771724)
		(end 140.400532 -219.066618)
		(width 0.088646)
		(layer "In2.Cu")
		(net "M_F_CPU1_SB_DQ<21>")
	)
	(segment
		(start 159.145986 -201.449178)
		(end 158.437326 -201.449178)
		(width 0.18288)
		(layer "In2.Cu")
		(net "M_F_CPU1_SB_DQ<21>")
	)
	(segment
		(start 158.437326 -201.449178)
		(end 157.859984 -202.02652)
		(width 0.18288)
		(layer "In2.Cu")
		(net "M_F_CPU1_SB_DQ<21>")
	)
	(segment
		(start 137.680954 -220.639132)
		(end 137.672064 -220.644212)
		(width 0.088646)
		(layer "In2.Cu")
		(net "M_F_CPU1_SB_DQ<21>")
	)
	(arc
		(start 138.14171 -219.830396)
		(mid 137.938887 -220.030627)
		(end 137.859516 -220.30436)
		(width 0.088646)
		(layer "In2.Cu")
		(net "M_F_CPU1_SB_DQ<21>")
	)
	(arc
		(start 138.605768 -219.020136)
		(mid 138.403181 -219.226487)
		(end 138.329162 -219.506038)
		(width 0.088646)
		(layer "In2.Cu")
		(net "M_F_CPU1_SB_DQ<21>")
	)
	(arc
		(start 137.859516 -220.319854)
		(mid 137.811837 -220.502754)
		(end 137.680954 -220.639132)
		(width 0.088646)
		(layer "In2.Cu")
		(net "M_F_CPU1_SB_DQ<21>")
	)
	(arc
		(start 138.329162 -219.506038)
		(mid 138.281483 -219.688938)
		(end 138.1506 -219.825316)
		(width 0.088646)
		(layer "In2.Cu")
		(net "M_F_CPU1_SB_DQ<21>")
	)
	(arc
		(start 139.177268 -219.01658)
		(mid 138.903069 -218.940745)
		(end 138.626596 -219.007944)
		(width 0.088646)
		(layer "In2.Cu")
		(net "M_F_CPU1_SB_DQ<21>")
	)
	(arc
		(start 140.117068 -219.01658)
		(mid 139.842869 -218.940745)
		(end 139.566396 -219.007944)
		(width 0.088646)
		(layer "In2.Cu")
		(net "M_F_CPU1_SB_DQ<21>")
	)
	(arc
		(start 139.551664 -219.01658)
		(mid 139.364466 -219.066723)
		(end 139.177268 -219.01658)
		(width 0.088646)
		(layer "In2.Cu")
		(net "M_F_CPU1_SB_DQ<21>")
	)
	(arc
		(start 140.311378 -219.066618)
		(mid 140.210816 -219.054838)
		(end 140.117068 -219.01658)
		(width 0.088646)
		(layer "In2.Cu")
		(net "M_F_CPU1_SB_DQ<21>")
	)
	(arc
		(start 137.672064 -220.644212)
		(mid 137.482088 -220.823424)
		(end 137.392918 -221.0689)
		(width 0.088646)
		(layer "In2.Cu")
		(net "M_F_CPU1_SB_DQ<21>")
	)
	(segment
		(start 181.444646 -207.51673)
		(end 181.444392 -207.516984)
		(width 0.20066)
		(layer "F.Cu")
		(net "M_F_CPU1_SB_DQ<20>")
	)
	(segment
		(start 179.004976 -207.091788)
		(end 176.843182 -207.091788)
		(width 0.1016)
		(layer "F.Cu")
		(net "M_F_CPU1_SB_DQ<20>")
	)
	(segment
		(start 176.145444 -207.765396)
		(end 175.67021 -207.765396)
		(width 0.20066)
		(layer "F.Cu")
		(net "M_F_CPU1_SB_DQ<20>")
	)
	(segment
		(start 176.333404 -207.209898)
		(end 176.333404 -207.577436)
		(width 0.20066)
		(layer "F.Cu")
		(net "M_F_CPU1_SB_DQ<20>")
	)
	(segment
		(start 176.796192 -207.091788)
		(end 176.451514 -207.091788)
		(width 0.20066)
		(layer "F.Cu")
		(net "M_F_CPU1_SB_DQ<20>")
	)
	(segment
		(start 136.545066 -221.947994)
		(end 136.544812 -221.94774)
		(width 0.20066)
		(layer "F.Cu")
		(net "M_F_CPU1_SB_DQ<20>")
	)
	(segment
		(start 179.011326 -207.085438)
		(end 179.004976 -207.091788)
		(width 0.1016)
		(layer "F.Cu")
		(net "M_F_CPU1_SB_DQ<20>")
	)
	(segment
		(start 176.451514 -207.091788)
		(end 176.333404 -207.209898)
		(width 0.20066)
		(layer "F.Cu")
		(net "M_F_CPU1_SB_DQ<20>")
	)
	(segment
		(start 179.852828 -207.516984)
		(end 179.421282 -207.085438)
		(width 0.20066)
		(layer "F.Cu")
		(net "M_F_CPU1_SB_DQ<20>")
	)
	(segment
		(start 136.545066 -222.48368)
		(end 136.545066 -221.947994)
		(width 0.20066)
		(layer "F.Cu")
		(net "M_F_CPU1_SB_DQ<20>")
	)
	(segment
		(start 175.421544 -207.51673)
		(end 173.900846 -207.51673)
		(width 0.20066)
		(layer "F.Cu")
		(net "M_F_CPU1_SB_DQ<20>")
	)
	(segment
		(start 181.444392 -207.516984)
		(end 179.852828 -207.516984)
		(width 0.20066)
		(layer "F.Cu")
		(net "M_F_CPU1_SB_DQ<20>")
	)
	(segment
		(start 176.843182 -207.091788)
		(end 176.796192 -207.091788)
		(width 0.101854)
		(layer "F.Cu")
		(net "M_F_CPU1_SB_DQ<20>")
	)
	(segment
		(start 173.900846 -207.51673)
		(end 172.795946 -207.51673)
		(width 0.20066)
		(layer "F.Cu")
		(net "M_F_CPU1_SB_DQ<20>")
	)
	(segment
		(start 175.67021 -207.765396)
		(end 175.421544 -207.51673)
		(width 0.20066)
		(layer "F.Cu")
		(net "M_F_CPU1_SB_DQ<20>")
	)
	(segment
		(start 179.421282 -207.085438)
		(end 179.011326 -207.085438)
		(width 0.20066)
		(layer "F.Cu")
		(net "M_F_CPU1_SB_DQ<20>")
	)
	(segment
		(start 176.333404 -207.577436)
		(end 176.145444 -207.765396)
		(width 0.20066)
		(layer "F.Cu")
		(net "M_F_CPU1_SB_DQ<20>")
	)
	(segment
		(start 172.795946 -207.51673)
		(end 172.44314 -207.51673)
		(width 0.18288)
		(layer "In2.Cu")
		(net "M_F_CPU1_SB_DQ<20>")
	)
	(segment
		(start 142.100046 -219.52585)
		(end 141.62913 -219.996766)
		(width 0.088646)
		(layer "In2.Cu")
		(net "M_F_CPU1_SB_DQ<20>")
	)
	(segment
		(start 160.618932 -204.059028)
		(end 160.1724 -204.50556)
		(width 0.18288)
		(layer "In2.Cu")
		(net "M_F_CPU1_SB_DQ<20>")
	)
	(segment
		(start 165.75659 -205.127352)
		(end 165.463982 -205.41996)
		(width 0.18288)
		(layer "In2.Cu")
		(net "M_F_CPU1_SB_DQ<20>")
	)
	(segment
		(start 169.02811 -206.743808)
		(end 168.769284 -207.002634)
		(width 0.18288)
		(layer "In2.Cu")
		(net "M_F_CPU1_SB_DQ<20>")
	)
	(segment
		(start 161.396934 -204.767434)
		(end 161.283904 -204.654404)
		(width 0.18288)
		(layer "In2.Cu")
		(net "M_F_CPU1_SB_DQ<20>")
	)
	(segment
		(start 167.677846 -205.628494)
		(end 167.404796 -205.628494)
		(width 0.18288)
		(layer "In2.Cu")
		(net "M_F_CPU1_SB_DQ<20>")
	)
	(segment
		(start 139.177268 -221.623382)
		(end 139.177014 -221.623636)
		(width 0.088646)
		(layer "In2.Cu")
		(net "M_F_CPU1_SB_DQ<20>")
	)
	(segment
		(start 172.44314 -207.51673)
		(end 171.98213 -207.05572)
		(width 0.18288)
		(layer "In2.Cu")
		(net "M_F_CPU1_SB_DQ<20>")
	)
	(segment
		(start 141.164056 -219.996766)
		(end 140.869416 -220.291406)
		(width 0.088646)
		(layer "In2.Cu")
		(net "M_F_CPU1_SB_DQ<20>")
	)
	(segment
		(start 138.897868 -222.106744)
		(end 138.61161 -222.272098)
		(width 0.088646)
		(layer "In2.Cu")
		(net "M_F_CPU1_SB_DQ<20>")
	)
	(segment
		(start 164.088826 -204.906626)
		(end 163.529772 -204.347572)
		(width 0.18288)
		(layer "In2.Cu")
		(net "M_F_CPU1_SB_DQ<20>")
	)
	(segment
		(start 156.58973 -204.939392)
		(end 156.58973 -205.036166)
		(width 0.18288)
		(layer "In2.Cu")
		(net "M_F_CPU1_SB_DQ<20>")
	)
	(segment
		(start 137.297414 -222.272098)
		(end 137.268966 -222.255588)
		(width 0.088646)
		(layer "In2.Cu")
		(net "M_F_CPU1_SB_DQ<20>")
	)
	(segment
		(start 161.283904 -204.291692)
		(end 161.05124 -204.059028)
		(width 0.18288)
		(layer "In2.Cu")
		(net "M_F_CPU1_SB_DQ<20>")
	)
	(segment
		(start 161.283904 -204.654404)
		(end 161.283904 -204.291692)
		(width 0.18288)
		(layer "In2.Cu")
		(net "M_F_CPU1_SB_DQ<20>")
	)
	(segment
		(start 156.58973 -205.036166)
		(end 142.100046 -219.52585)
		(width 0.18288)
		(layer "In2.Cu")
		(net "M_F_CPU1_SB_DQ<20>")
	)
	(segment
		(start 139.647168 -220.809566)
		(end 139.638278 -220.814646)
		(width 0.088646)
		(layer "In2.Cu")
		(net "M_F_CPU1_SB_DQ<20>")
	)
	(segment
		(start 162.25774 -204.347572)
		(end 161.837878 -204.767434)
		(width 0.18288)
		(layer "In2.Cu")
		(net "M_F_CPU1_SB_DQ<20>")
	)
	(segment
		(start 141.62913 -219.996766)
		(end 141.164056 -219.996766)
		(width 0.088646)
		(layer "In2.Cu")
		(net "M_F_CPU1_SB_DQ<20>")
	)
	(segment
		(start 137.672064 -222.272098)
		(end 137.67181 -222.272098)
		(width 0.088646)
		(layer "In2.Cu")
		(net "M_F_CPU1_SB_DQ<20>")
	)
	(segment
		(start 165.463982 -205.41996)
		(end 165.08476 -205.41996)
		(width 0.18288)
		(layer "In2.Cu")
		(net "M_F_CPU1_SB_DQ<20>")
	)
	(segment
		(start 171.98213 -207.05572)
		(end 169.613326 -207.05572)
		(width 0.18288)
		(layer "In2.Cu")
		(net "M_F_CPU1_SB_DQ<20>")
	)
	(segment
		(start 168.71442 -204.927962)
		(end 168.378378 -204.927962)
		(width 0.18288)
		(layer "In2.Cu")
		(net "M_F_CPU1_SB_DQ<20>")
	)
	(segment
		(start 169.301414 -206.743808)
		(end 169.02811 -206.743808)
		(width 0.18288)
		(layer "In2.Cu")
		(net "M_F_CPU1_SB_DQ<20>")
	)
	(segment
		(start 168.952672 -205.166214)
		(end 168.71442 -204.927962)
		(width 0.18288)
		(layer "In2.Cu")
		(net "M_F_CPU1_SB_DQ<20>")
	)
	(segment
		(start 168.217088 -206.723742)
		(end 168.217088 -206.1845)
		(width 0.18288)
		(layer "In2.Cu")
		(net "M_F_CPU1_SB_DQ<20>")
	)
	(segment
		(start 168.217088 -206.1845)
		(end 168.952672 -205.448916)
		(width 0.18288)
		(layer "In2.Cu")
		(net "M_F_CPU1_SB_DQ<20>")
	)
	(segment
		(start 169.613326 -207.05572)
		(end 169.301414 -206.743808)
		(width 0.18288)
		(layer "In2.Cu")
		(net "M_F_CPU1_SB_DQ<20>")
	)
	(segment
		(start 161.05124 -204.059028)
		(end 160.618932 -204.059028)
		(width 0.18288)
		(layer "In2.Cu")
		(net "M_F_CPU1_SB_DQ<20>")
	)
	(segment
		(start 160.1724 -204.50556)
		(end 157.023562 -204.50556)
		(width 0.18288)
		(layer "In2.Cu")
		(net "M_F_CPU1_SB_DQ<20>")
	)
	(segment
		(start 161.837878 -204.767434)
		(end 161.396934 -204.767434)
		(width 0.18288)
		(layer "In2.Cu")
		(net "M_F_CPU1_SB_DQ<20>")
	)
	(segment
		(start 137.268966 -222.255588)
		(end 136.544812 -221.94774)
		(width 0.088646)
		(layer "In2.Cu")
		(net "M_F_CPU1_SB_DQ<20>")
	)
	(segment
		(start 168.952672 -205.448916)
		(end 168.952672 -205.166214)
		(width 0.18288)
		(layer "In2.Cu")
		(net "M_F_CPU1_SB_DQ<20>")
	)
	(segment
		(start 164.571426 -204.906626)
		(end 164.088826 -204.906626)
		(width 0.18288)
		(layer "In2.Cu")
		(net "M_F_CPU1_SB_DQ<20>")
	)
	(segment
		(start 157.023562 -204.50556)
		(end 156.58973 -204.939392)
		(width 0.18288)
		(layer "In2.Cu")
		(net "M_F_CPU1_SB_DQ<20>")
	)
	(segment
		(start 163.529772 -204.347572)
		(end 162.25774 -204.347572)
		(width 0.18288)
		(layer "In2.Cu")
		(net "M_F_CPU1_SB_DQ<20>")
	)
	(segment
		(start 166.903654 -205.127352)
		(end 165.75659 -205.127352)
		(width 0.18288)
		(layer "In2.Cu")
		(net "M_F_CPU1_SB_DQ<20>")
	)
	(segment
		(start 140.869416 -220.291406)
		(end 140.869416 -220.338396)
		(width 0.088646)
		(layer "In2.Cu")
		(net "M_F_CPU1_SB_DQ<20>")
	)
	(segment
		(start 168.378378 -204.927962)
		(end 167.677846 -205.628494)
		(width 0.18288)
		(layer "In2.Cu")
		(net "M_F_CPU1_SB_DQ<20>")
	)
	(segment
		(start 139.459716 -221.133924)
		(end 139.459716 -221.14383)
		(width 0.088646)
		(layer "In2.Cu")
		(net "M_F_CPU1_SB_DQ<20>")
	)
	(segment
		(start 168.769284 -207.002634)
		(end 168.49598 -207.002634)
		(width 0.18288)
		(layer "In2.Cu")
		(net "M_F_CPU1_SB_DQ<20>")
	)
	(segment
		(start 167.404796 -205.628494)
		(end 166.903654 -205.127352)
		(width 0.18288)
		(layer "In2.Cu")
		(net "M_F_CPU1_SB_DQ<20>")
	)
	(segment
		(start 165.08476 -205.41996)
		(end 164.571426 -204.906626)
		(width 0.18288)
		(layer "In2.Cu")
		(net "M_F_CPU1_SB_DQ<20>")
	)
	(segment
		(start 168.49598 -207.002634)
		(end 168.217088 -206.723742)
		(width 0.18288)
		(layer "In2.Cu")
		(net "M_F_CPU1_SB_DQ<20>")
	)
	(arc
		(start 140.586968 -220.809566)
		(mid 140.304266 -220.885308)
		(end 140.021564 -220.809566)
		(width 0.088646)
		(layer "In2.Cu")
		(net "M_F_CPU1_SB_DQ<20>")
	)
	(arc
		(start 137.67181 -222.272098)
		(mid 137.484612 -222.322275)
		(end 137.297414 -222.272098)
		(width 0.088646)
		(layer "In2.Cu")
		(net "M_F_CPU1_SB_DQ<20>")
	)
	(arc
		(start 139.459716 -221.14383)
		(mid 139.381605 -221.420779)
		(end 139.177268 -221.623382)
		(width 0.088646)
		(layer "In2.Cu")
		(net "M_F_CPU1_SB_DQ<20>")
	)
	(arc
		(start 138.989816 -221.94774)
		(mid 138.965168 -222.039569)
		(end 138.897868 -222.106744)
		(width 0.088646)
		(layer "In2.Cu")
		(net "M_F_CPU1_SB_DQ<20>")
	)
	(arc
		(start 138.237468 -222.272098)
		(mid 137.954766 -222.196322)
		(end 137.672064 -222.272098)
		(width 0.088646)
		(layer "In2.Cu")
		(net "M_F_CPU1_SB_DQ<20>")
	)
	(arc
		(start 139.177014 -221.623636)
		(mid 139.039969 -221.760596)
		(end 138.989816 -221.94774)
		(width 0.088646)
		(layer "In2.Cu")
		(net "M_F_CPU1_SB_DQ<20>")
	)
	(arc
		(start 138.61161 -222.272098)
		(mid 138.424556 -222.322148)
		(end 138.237468 -222.272098)
		(width 0.088646)
		(layer "In2.Cu")
		(net "M_F_CPU1_SB_DQ<20>")
	)
	(arc
		(start 140.021564 -220.809566)
		(mid 139.834366 -220.759423)
		(end 139.647168 -220.809566)
		(width 0.088646)
		(layer "In2.Cu")
		(net "M_F_CPU1_SB_DQ<20>")
	)
	(arc
		(start 140.869416 -220.338396)
		(mid 140.789254 -220.610585)
		(end 140.586968 -220.809566)
		(width 0.088646)
		(layer "In2.Cu")
		(net "M_F_CPU1_SB_DQ<20>")
	)
	(arc
		(start 139.638278 -220.814646)
		(mid 139.507364 -220.951006)
		(end 139.459716 -221.133924)
		(width 0.088646)
		(layer "In2.Cu")
		(net "M_F_CPU1_SB_DQ<20>")
	)
	(segment
		(start 181.444392 -230.4669)
		(end 179.852828 -230.4669)
		(width 0.20066)
		(layer "F.Cu")
		(net "M_F_CPU1_SB_DQ<1>")
	)
	(segment
		(start 176.333404 -230.159814)
		(end 176.333404 -230.527352)
		(width 0.20066)
		(layer "F.Cu")
		(net "M_F_CPU1_SB_DQ<1>")
	)
	(segment
		(start 129.966466 -238.761524)
		(end 129.966212 -238.76127)
		(width 0.20066)
		(layer "F.Cu")
		(net "M_F_CPU1_SB_DQ<1>")
	)
	(segment
		(start 175.421544 -230.466646)
		(end 173.900846 -230.466646)
		(width 0.20066)
		(layer "F.Cu")
		(net "M_F_CPU1_SB_DQ<1>")
	)
	(segment
		(start 173.900846 -230.466646)
		(end 172.795946 -230.466646)
		(width 0.20066)
		(layer "F.Cu")
		(net "M_F_CPU1_SB_DQ<1>")
	)
	(segment
		(start 176.816258 -230.041704)
		(end 176.796192 -230.041704)
		(width 0.101854)
		(layer "F.Cu")
		(net "M_F_CPU1_SB_DQ<1>")
	)
	(segment
		(start 179.421282 -230.035354)
		(end 179.011326 -230.035354)
		(width 0.20066)
		(layer "F.Cu")
		(net "M_F_CPU1_SB_DQ<1>")
	)
	(segment
		(start 175.67021 -230.715312)
		(end 175.421544 -230.466646)
		(width 0.20066)
		(layer "F.Cu")
		(net "M_F_CPU1_SB_DQ<1>")
	)
	(segment
		(start 176.451514 -230.041704)
		(end 176.333404 -230.159814)
		(width 0.20066)
		(layer "F.Cu")
		(net "M_F_CPU1_SB_DQ<1>")
	)
	(segment
		(start 181.444646 -230.466646)
		(end 181.444392 -230.4669)
		(width 0.20066)
		(layer "F.Cu")
		(net "M_F_CPU1_SB_DQ<1>")
	)
	(segment
		(start 176.333404 -230.527352)
		(end 176.145444 -230.715312)
		(width 0.20066)
		(layer "F.Cu")
		(net "M_F_CPU1_SB_DQ<1>")
	)
	(segment
		(start 176.796192 -230.041704)
		(end 176.451514 -230.041704)
		(width 0.20066)
		(layer "F.Cu")
		(net "M_F_CPU1_SB_DQ<1>")
	)
	(segment
		(start 176.145444 -230.715312)
		(end 175.67021 -230.715312)
		(width 0.20066)
		(layer "F.Cu")
		(net "M_F_CPU1_SB_DQ<1>")
	)
	(segment
		(start 179.004976 -230.041704)
		(end 176.816258 -230.041704)
		(width 0.1016)
		(layer "F.Cu")
		(net "M_F_CPU1_SB_DQ<1>")
	)
	(segment
		(start 129.966212 -238.76127)
		(end 129.966212 -238.225584)
		(width 0.20066)
		(layer "F.Cu")
		(net "M_F_CPU1_SB_DQ<1>")
	)
	(segment
		(start 179.011326 -230.035354)
		(end 179.004976 -230.041704)
		(width 0.1016)
		(layer "F.Cu")
		(net "M_F_CPU1_SB_DQ<1>")
	)
	(segment
		(start 179.852828 -230.4669)
		(end 179.421282 -230.035354)
		(width 0.20066)
		(layer "F.Cu")
		(net "M_F_CPU1_SB_DQ<1>")
	)
	(segment
		(start 160.259776 -229.009194)
		(end 160.259776 -228.340158)
		(width 0.18288)
		(layer "In4.Cu")
		(net "M_F_CPU1_SB_DQ<1>")
	)
	(segment
		(start 170.383962 -230.493062)
		(end 170.201082 -230.310182)
		(width 0.18288)
		(layer "In4.Cu")
		(net "M_F_CPU1_SB_DQ<1>")
	)
	(segment
		(start 160.442656 -229.192074)
		(end 160.259776 -229.009194)
		(width 0.18288)
		(layer "In4.Cu")
		(net "M_F_CPU1_SB_DQ<1>")
	)
	(segment
		(start 158.877254 -229.352094)
		(end 158.877254 -229.879652)
		(width 0.18288)
		(layer "In4.Cu")
		(net "M_F_CPU1_SB_DQ<1>")
	)
	(segment
		(start 159.037274 -229.192074)
		(end 158.877254 -229.352094)
		(width 0.18288)
		(layer "In4.Cu")
		(net "M_F_CPU1_SB_DQ<1>")
	)
	(segment
		(start 144.70507 -234.842304)
		(end 142.264892 -237.282482)
		(width 0.18288)
		(layer "In4.Cu")
		(net "M_F_CPU1_SB_DQ<1>")
	)
	(segment
		(start 156.760672 -229.8827)
		(end 156.760672 -230.144828)
		(width 0.18288)
		(layer "In4.Cu")
		(net "M_F_CPU1_SB_DQ<1>")
	)
	(segment
		(start 163.93287 -229.192074)
		(end 160.442656 -229.192074)
		(width 0.18288)
		(layer "In4.Cu")
		(net "M_F_CPU1_SB_DQ<1>")
	)
	(segment
		(start 130.623564 -238.715042)
		(end 130.543554 -238.668814)
		(width 0.088646)
		(layer "In4.Cu")
		(net "M_F_CPU1_SB_DQ<1>")
	)
	(segment
		(start 170.894502 -230.310182)
		(end 170.711622 -230.493062)
		(width 0.18288)
		(layer "In4.Cu")
		(net "M_F_CPU1_SB_DQ<1>")
	)
	(segment
		(start 168.847516 -229.968298)
		(end 168.847516 -230.19258)
		(width 0.18288)
		(layer "In4.Cu")
		(net "M_F_CPU1_SB_DQ<1>")
	)
	(segment
		(start 133.072886 -238.712248)
		(end 133.068314 -238.715042)
		(width 0.088646)
		(layer "In4.Cu")
		(net "M_F_CPU1_SB_DQ<1>")
	)
	(segment
		(start 170.201082 -229.878128)
		(end 170.018202 -229.695248)
		(width 0.18288)
		(layer "In4.Cu")
		(net "M_F_CPU1_SB_DQ<1>")
	)
	(segment
		(start 154.31389 -229.69982)
		(end 149.171406 -234.842304)
		(width 0.18288)
		(layer "In4.Cu")
		(net "M_F_CPU1_SB_DQ<1>")
	)
	(segment
		(start 170.201082 -230.310182)
		(end 170.201082 -229.878128)
		(width 0.18288)
		(layer "In4.Cu")
		(net "M_F_CPU1_SB_DQ<1>")
	)
	(segment
		(start 135.887714 -238.715042)
		(end 135.882126 -238.718344)
		(width 0.088646)
		(layer "In4.Cu")
		(net "M_F_CPU1_SB_DQ<1>")
	)
	(segment
		(start 166.783258 -229.315264)
		(end 166.600378 -229.132384)
		(width 0.18288)
		(layer "In4.Cu")
		(net "M_F_CPU1_SB_DQ<1>")
	)
	(segment
		(start 165.906958 -230.078026)
		(end 165.028626 -230.078026)
		(width 0.18288)
		(layer "In4.Cu")
		(net "M_F_CPU1_SB_DQ<1>")
	)
	(segment
		(start 170.894502 -229.878128)
		(end 170.894502 -230.310182)
		(width 0.18288)
		(layer "In4.Cu")
		(net "M_F_CPU1_SB_DQ<1>")
	)
	(segment
		(start 156.943552 -229.69982)
		(end 156.760672 -229.8827)
		(width 0.18288)
		(layer "In4.Cu")
		(net "M_F_CPU1_SB_DQ<1>")
	)
	(segment
		(start 171.077382 -229.695248)
		(end 170.894502 -229.878128)
		(width 0.18288)
		(layer "In4.Cu")
		(net "M_F_CPU1_SB_DQ<1>")
	)
	(segment
		(start 156.067252 -229.8827)
		(end 155.884372 -229.69982)
		(width 0.18288)
		(layer "In4.Cu")
		(net "M_F_CPU1_SB_DQ<1>")
	)
	(segment
		(start 159.383476 -229.192074)
		(end 159.037274 -229.192074)
		(width 0.18288)
		(layer "In4.Cu")
		(net "M_F_CPU1_SB_DQ<1>")
	)
	(segment
		(start 160.076896 -228.157278)
		(end 159.749236 -228.157278)
		(width 0.18288)
		(layer "In4.Cu")
		(net "M_F_CPU1_SB_DQ<1>")
	)
	(segment
		(start 154.497532 -229.69982)
		(end 154.31389 -229.69982)
		(width 0.18288)
		(layer "In4.Cu")
		(net "M_F_CPU1_SB_DQ<1>")
	)
	(segment
		(start 155.190952 -230.327708)
		(end 154.863292 -230.327708)
		(width 0.18288)
		(layer "In4.Cu")
		(net "M_F_CPU1_SB_DQ<1>")
	)
	(segment
		(start 159.566356 -228.340158)
		(end 159.566356 -229.009194)
		(width 0.18288)
		(layer "In4.Cu")
		(net "M_F_CPU1_SB_DQ<1>")
	)
	(segment
		(start 134.947914 -238.715042)
		(end 134.943342 -238.717582)
		(width 0.088646)
		(layer "In4.Cu")
		(net "M_F_CPU1_SB_DQ<1>")
	)
	(segment
		(start 160.259776 -228.340158)
		(end 160.076896 -228.157278)
		(width 0.18288)
		(layer "In4.Cu")
		(net "M_F_CPU1_SB_DQ<1>")
	)
	(segment
		(start 133.068314 -238.715042)
		(end 133.060948 -238.71936)
		(width 0.088646)
		(layer "In4.Cu")
		(net "M_F_CPU1_SB_DQ<1>")
	)
	(segment
		(start 156.577792 -230.327708)
		(end 156.250132 -230.327708)
		(width 0.18288)
		(layer "In4.Cu")
		(net "M_F_CPU1_SB_DQ<1>")
	)
	(segment
		(start 165.028626 -230.078026)
		(end 164.141404 -229.190804)
		(width 0.18288)
		(layer "In4.Cu")
		(net "M_F_CPU1_SB_DQ<1>")
	)
	(segment
		(start 170.711622 -230.493062)
		(end 170.383962 -230.493062)
		(width 0.18288)
		(layer "In4.Cu")
		(net "M_F_CPU1_SB_DQ<1>")
	)
	(segment
		(start 140.875512 -237.282482)
		(end 139.631166 -238.526828)
		(width 0.088646)
		(layer "In4.Cu")
		(net "M_F_CPU1_SB_DQ<1>")
	)
	(segment
		(start 157.171898 -229.69982)
		(end 156.943552 -229.69982)
		(width 0.18288)
		(layer "In4.Cu")
		(net "M_F_CPU1_SB_DQ<1>")
	)
	(segment
		(start 155.373832 -230.144828)
		(end 155.190952 -230.327708)
		(width 0.18288)
		(layer "In4.Cu")
		(net "M_F_CPU1_SB_DQ<1>")
	)
	(segment
		(start 139.631166 -238.526828)
		(end 139.010644 -238.683292)
		(width 0.088646)
		(layer "In4.Cu")
		(net "M_F_CPU1_SB_DQ<1>")
	)
	(segment
		(start 168.664636 -230.37546)
		(end 167.940228 -230.37546)
		(width 0.18288)
		(layer "In4.Cu")
		(net "M_F_CPU1_SB_DQ<1>")
	)
	(segment
		(start 154.863292 -230.327708)
		(end 154.680412 -230.144828)
		(width 0.18288)
		(layer "In4.Cu")
		(net "M_F_CPU1_SB_DQ<1>")
	)
	(segment
		(start 156.067252 -230.144828)
		(end 156.067252 -229.8827)
		(width 0.18288)
		(layer "In4.Cu")
		(net "M_F_CPU1_SB_DQ<1>")
	)
	(segment
		(start 170.018202 -229.695248)
		(end 169.120566 -229.695248)
		(width 0.18288)
		(layer "In4.Cu")
		(net "M_F_CPU1_SB_DQ<1>")
	)
	(segment
		(start 156.760672 -230.144828)
		(end 156.577792 -230.327708)
		(width 0.18288)
		(layer "In4.Cu")
		(net "M_F_CPU1_SB_DQ<1>")
	)
	(segment
		(start 163.93414 -229.190804)
		(end 163.93287 -229.192074)
		(width 0.18288)
		(layer "In4.Cu")
		(net "M_F_CPU1_SB_DQ<1>")
	)
	(segment
		(start 154.680412 -229.8827)
		(end 154.497532 -229.69982)
		(width 0.18288)
		(layer "In4.Cu")
		(net "M_F_CPU1_SB_DQ<1>")
	)
	(segment
		(start 156.250132 -230.327708)
		(end 156.067252 -230.144828)
		(width 0.18288)
		(layer "In4.Cu")
		(net "M_F_CPU1_SB_DQ<1>")
	)
	(segment
		(start 132.133086 -238.712248)
		(end 132.128514 -238.715042)
		(width 0.088646)
		(layer "In4.Cu")
		(net "M_F_CPU1_SB_DQ<1>")
	)
	(segment
		(start 149.171406 -234.842304)
		(end 144.70507 -234.842304)
		(width 0.18288)
		(layer "In4.Cu")
		(net "M_F_CPU1_SB_DQ<1>")
	)
	(segment
		(start 168.847516 -230.19258)
		(end 168.664636 -230.37546)
		(width 0.18288)
		(layer "In4.Cu")
		(net "M_F_CPU1_SB_DQ<1>")
	)
	(segment
		(start 172.795946 -230.466646)
		(end 172.024548 -229.695248)
		(width 0.18288)
		(layer "In4.Cu")
		(net "M_F_CPU1_SB_DQ<1>")
	)
	(segment
		(start 134.008114 -238.715042)
		(end 134.002526 -238.718344)
		(width 0.088646)
		(layer "In4.Cu")
		(net "M_F_CPU1_SB_DQ<1>")
	)
	(segment
		(start 135.887968 -238.715042)
		(end 135.887714 -238.715042)
		(width 0.088646)
		(layer "In4.Cu")
		(net "M_F_CPU1_SB_DQ<1>")
	)
	(segment
		(start 142.264892 -237.282482)
		(end 141.001496 -237.282482)
		(width 0.18288)
		(layer "In4.Cu")
		(net "M_F_CPU1_SB_DQ<1>")
	)
	(segment
		(start 166.089838 -229.895146)
		(end 165.906958 -230.078026)
		(width 0.18288)
		(layer "In4.Cu")
		(net "M_F_CPU1_SB_DQ<1>")
	)
	(segment
		(start 132.128514 -238.715042)
		(end 132.121148 -238.71936)
		(width 0.088646)
		(layer "In4.Cu")
		(net "M_F_CPU1_SB_DQ<1>")
	)
	(segment
		(start 158.877254 -229.879652)
		(end 158.717234 -230.039672)
		(width 0.18288)
		(layer "In4.Cu")
		(net "M_F_CPU1_SB_DQ<1>")
	)
	(segment
		(start 155.556712 -229.69982)
		(end 155.373832 -229.8827)
		(width 0.18288)
		(layer "In4.Cu")
		(net "M_F_CPU1_SB_DQ<1>")
	)
	(segment
		(start 169.120566 -229.695248)
		(end 168.847516 -229.968298)
		(width 0.18288)
		(layer "In4.Cu")
		(net "M_F_CPU1_SB_DQ<1>")
	)
	(segment
		(start 154.680412 -230.144828)
		(end 154.680412 -229.8827)
		(width 0.18288)
		(layer "In4.Cu")
		(net "M_F_CPU1_SB_DQ<1>")
	)
	(segment
		(start 159.566356 -229.009194)
		(end 159.383476 -229.192074)
		(width 0.18288)
		(layer "In4.Cu")
		(net "M_F_CPU1_SB_DQ<1>")
	)
	(segment
		(start 134.952486 -238.712248)
		(end 134.947914 -238.715042)
		(width 0.088646)
		(layer "In4.Cu")
		(net "M_F_CPU1_SB_DQ<1>")
	)
	(segment
		(start 157.51175 -230.039672)
		(end 157.171898 -229.69982)
		(width 0.18288)
		(layer "In4.Cu")
		(net "M_F_CPU1_SB_DQ<1>")
	)
	(segment
		(start 172.024548 -229.695248)
		(end 171.077382 -229.695248)
		(width 0.18288)
		(layer "In4.Cu")
		(net "M_F_CPU1_SB_DQ<1>")
	)
	(segment
		(start 164.141404 -229.190804)
		(end 163.93414 -229.190804)
		(width 0.18288)
		(layer "In4.Cu")
		(net "M_F_CPU1_SB_DQ<1>")
	)
	(segment
		(start 167.642794 -230.078026)
		(end 166.966138 -230.078026)
		(width 0.18288)
		(layer "In4.Cu")
		(net "M_F_CPU1_SB_DQ<1>")
	)
	(segment
		(start 166.272718 -229.132384)
		(end 166.089838 -229.315264)
		(width 0.18288)
		(layer "In4.Cu")
		(net "M_F_CPU1_SB_DQ<1>")
	)
	(segment
		(start 131.186428 -238.716312)
		(end 131.181348 -238.71936)
		(width 0.088646)
		(layer "In4.Cu")
		(net "M_F_CPU1_SB_DQ<1>")
	)
	(segment
		(start 166.600378 -229.132384)
		(end 166.272718 -229.132384)
		(width 0.18288)
		(layer "In4.Cu")
		(net "M_F_CPU1_SB_DQ<1>")
	)
	(segment
		(start 167.940228 -230.37546)
		(end 167.642794 -230.078026)
		(width 0.18288)
		(layer "In4.Cu")
		(net "M_F_CPU1_SB_DQ<1>")
	)
	(segment
		(start 166.783258 -229.895146)
		(end 166.783258 -229.315264)
		(width 0.18288)
		(layer "In4.Cu")
		(net "M_F_CPU1_SB_DQ<1>")
	)
	(segment
		(start 159.749236 -228.157278)
		(end 159.566356 -228.340158)
		(width 0.18288)
		(layer "In4.Cu")
		(net "M_F_CPU1_SB_DQ<1>")
	)
	(segment
		(start 166.089838 -229.315264)
		(end 166.089838 -229.895146)
		(width 0.18288)
		(layer "In4.Cu")
		(net "M_F_CPU1_SB_DQ<1>")
	)
	(segment
		(start 166.966138 -230.078026)
		(end 166.783258 -229.895146)
		(width 0.18288)
		(layer "In4.Cu")
		(net "M_F_CPU1_SB_DQ<1>")
	)
	(segment
		(start 155.884372 -229.69982)
		(end 155.556712 -229.69982)
		(width 0.18288)
		(layer "In4.Cu")
		(net "M_F_CPU1_SB_DQ<1>")
	)
	(segment
		(start 141.001496 -237.282482)
		(end 140.875512 -237.282482)
		(width 0.088646)
		(layer "In4.Cu")
		(net "M_F_CPU1_SB_DQ<1>")
	)
	(segment
		(start 155.373832 -229.8827)
		(end 155.373832 -230.144828)
		(width 0.18288)
		(layer "In4.Cu")
		(net "M_F_CPU1_SB_DQ<1>")
	)
	(segment
		(start 158.717234 -230.039672)
		(end 157.51175 -230.039672)
		(width 0.18288)
		(layer "In4.Cu")
		(net "M_F_CPU1_SB_DQ<1>")
	)
	(arc
		(start 133.060948 -238.71936)
		(mid 132.781487 -238.790797)
		(end 132.503164 -238.715042)
		(width 0.088646)
		(layer "In4.Cu")
		(net "M_F_CPU1_SB_DQ<1>")
	)
	(arc
		(start 131.563364 -238.715042)
		(mid 131.374714 -238.664774)
		(end 131.186428 -238.716312)
		(width 0.088646)
		(layer "In4.Cu")
		(net "M_F_CPU1_SB_DQ<1>")
	)
	(arc
		(start 139.010644 -238.683292)
		(mid 138.855621 -238.666881)
		(end 138.707368 -238.715042)
		(width 0.088646)
		(layer "In4.Cu")
		(net "M_F_CPU1_SB_DQ<1>")
	)
	(arc
		(start 135.882126 -238.718344)
		(mid 135.601911 -238.790785)
		(end 135.322564 -238.715042)
		(width 0.088646)
		(layer "In4.Cu")
		(net "M_F_CPU1_SB_DQ<1>")
	)
	(arc
		(start 132.121148 -238.71936)
		(mid 131.841687 -238.790797)
		(end 131.563364 -238.715042)
		(width 0.088646)
		(layer "In4.Cu")
		(net "M_F_CPU1_SB_DQ<1>")
	)
	(arc
		(start 136.827768 -238.715042)
		(mid 136.545066 -238.790818)
		(end 136.262364 -238.715042)
		(width 0.088646)
		(layer "In4.Cu")
		(net "M_F_CPU1_SB_DQ<1>")
	)
	(arc
		(start 131.181348 -238.71936)
		(mid 130.901887 -238.790797)
		(end 130.623564 -238.715042)
		(width 0.088646)
		(layer "In4.Cu")
		(net "M_F_CPU1_SB_DQ<1>")
	)
	(arc
		(start 137.202164 -238.715042)
		(mid 137.014966 -238.664899)
		(end 136.827768 -238.715042)
		(width 0.088646)
		(layer "In4.Cu")
		(net "M_F_CPU1_SB_DQ<1>")
	)
	(arc
		(start 130.543554 -238.668814)
		(mid 130.240384 -238.466085)
		(end 129.966212 -238.225584)
		(width 0.088646)
		(layer "In4.Cu")
		(net "M_F_CPU1_SB_DQ<1>")
	)
	(arc
		(start 138.141964 -238.715042)
		(mid 137.954766 -238.664899)
		(end 137.767568 -238.715042)
		(width 0.088646)
		(layer "In4.Cu")
		(net "M_F_CPU1_SB_DQ<1>")
	)
	(arc
		(start 134.382764 -238.715042)
		(mid 134.195456 -238.664899)
		(end 134.008114 -238.715042)
		(width 0.088646)
		(layer "In4.Cu")
		(net "M_F_CPU1_SB_DQ<1>")
	)
	(arc
		(start 134.943342 -238.717582)
		(mid 134.662707 -238.79075)
		(end 134.382764 -238.715042)
		(width 0.088646)
		(layer "In4.Cu")
		(net "M_F_CPU1_SB_DQ<1>")
	)
	(arc
		(start 132.503164 -238.715042)
		(mid 132.3185 -238.664782)
		(end 132.133086 -238.712248)
		(width 0.088646)
		(layer "In4.Cu")
		(net "M_F_CPU1_SB_DQ<1>")
	)
	(arc
		(start 138.707368 -238.715042)
		(mid 138.424666 -238.790818)
		(end 138.141964 -238.715042)
		(width 0.088646)
		(layer "In4.Cu")
		(net "M_F_CPU1_SB_DQ<1>")
	)
	(arc
		(start 136.262364 -238.715042)
		(mid 136.075166 -238.664899)
		(end 135.887968 -238.715042)
		(width 0.088646)
		(layer "In4.Cu")
		(net "M_F_CPU1_SB_DQ<1>")
	)
	(arc
		(start 133.442964 -238.715042)
		(mid 133.2583 -238.664782)
		(end 133.072886 -238.712248)
		(width 0.088646)
		(layer "In4.Cu")
		(net "M_F_CPU1_SB_DQ<1>")
	)
	(arc
		(start 135.322564 -238.715042)
		(mid 135.1379 -238.664782)
		(end 134.952486 -238.712248)
		(width 0.088646)
		(layer "In4.Cu")
		(net "M_F_CPU1_SB_DQ<1>")
	)
	(arc
		(start 134.002526 -238.718344)
		(mid 133.722311 -238.790785)
		(end 133.442964 -238.715042)
		(width 0.088646)
		(layer "In4.Cu")
		(net "M_F_CPU1_SB_DQ<1>")
	)
	(arc
		(start 137.767568 -238.715042)
		(mid 137.484866 -238.790818)
		(end 137.202164 -238.715042)
		(width 0.088646)
		(layer "In4.Cu")
		(net "M_F_CPU1_SB_DQ<1>")
	)
	(segment
		(start 138.424666 -224.111566)
		(end 138.424666 -223.575626)
		(width 0.20066)
		(layer "F.Cu")
		(net "M_F_CPU1_SB_DQ<19>")
	)
	(segment
		(start 180.131212 -211.348828)
		(end 180.423058 -211.348828)
		(width 0.20066)
		(layer "F.Cu")
		(net "M_F_CPU1_SB_DQ<19>")
	)
	(segment
		(start 176.896014 -210.916774)
		(end 178.000914 -210.916774)
		(width 0.20066)
		(layer "F.Cu")
		(net "M_F_CPU1_SB_DQ<19>")
	)
	(segment
		(start 179.699158 -210.916774)
		(end 180.131212 -211.348828)
		(width 0.20066)
		(layer "F.Cu")
		(net "M_F_CPU1_SB_DQ<19>")
	)
	(segment
		(start 183.340248 -210.898994)
		(end 183.574436 -210.664806)
		(width 0.20066)
		(layer "F.Cu")
		(net "M_F_CPU1_SB_DQ<19>")
	)
	(segment
		(start 183.136286 -211.353908)
		(end 183.340248 -211.149946)
		(width 0.20066)
		(layer "F.Cu")
		(net "M_F_CPU1_SB_DQ<19>")
	)
	(segment
		(start 183.574436 -210.664806)
		(end 183.958484 -210.664806)
		(width 0.20066)
		(layer "F.Cu")
		(net "M_F_CPU1_SB_DQ<19>")
	)
	(segment
		(start 180.423058 -211.348828)
		(end 180.427884 -211.348828)
		(width 0.101854)
		(layer "F.Cu")
		(net "M_F_CPU1_SB_DQ<19>")
	)
	(segment
		(start 180.427884 -211.348828)
		(end 180.434996 -211.341716)
		(width 0.1016)
		(layer "F.Cu")
		(net "M_F_CPU1_SB_DQ<19>")
	)
	(segment
		(start 180.434996 -211.341716)
		(end 182.442866 -211.341716)
		(width 0.1016)
		(layer "F.Cu")
		(net "M_F_CPU1_SB_DQ<19>")
	)
	(segment
		(start 184.210452 -210.916774)
		(end 185.544714 -210.916774)
		(width 0.20066)
		(layer "F.Cu")
		(net "M_F_CPU1_SB_DQ<19>")
	)
	(segment
		(start 182.442866 -211.341716)
		(end 182.455058 -211.353908)
		(width 0.1016)
		(layer "F.Cu")
		(net "M_F_CPU1_SB_DQ<19>")
	)
	(segment
		(start 183.958484 -210.664806)
		(end 184.210452 -210.916774)
		(width 0.20066)
		(layer "F.Cu")
		(net "M_F_CPU1_SB_DQ<19>")
	)
	(segment
		(start 178.000914 -210.916774)
		(end 179.699158 -210.916774)
		(width 0.20066)
		(layer "F.Cu")
		(net "M_F_CPU1_SB_DQ<19>")
	)
	(segment
		(start 182.455058 -211.353908)
		(end 183.136286 -211.353908)
		(width 0.20066)
		(layer "F.Cu")
		(net "M_F_CPU1_SB_DQ<19>")
	)
	(segment
		(start 183.340248 -211.149946)
		(end 183.340248 -210.898994)
		(width 0.20066)
		(layer "F.Cu")
		(net "M_F_CPU1_SB_DQ<19>")
	)
	(segment
		(start 157.871668 -208.818226)
		(end 157.271212 -208.818226)
		(width 0.18288)
		(layer "In2.Cu")
		(net "M_F_CPU1_SB_DQ<19>")
	)
	(segment
		(start 159.83077 -208.944464)
		(end 159.139382 -208.253076)
		(width 0.18288)
		(layer "In2.Cu")
		(net "M_F_CPU1_SB_DQ<19>")
	)
	(segment
		(start 172.299122 -210.51393)
		(end 168.83253 -210.51393)
		(width 0.18288)
		(layer "In2.Cu")
		(net "M_F_CPU1_SB_DQ<19>")
	)
	(segment
		(start 161.886392 -209.41665)
		(end 161.693352 -209.60969)
		(width 0.18288)
		(layer "In2.Cu")
		(net "M_F_CPU1_SB_DQ<19>")
	)
	(segment
		(start 175.80483 -210.328256)
		(end 175.66513 -210.188556)
		(width 0.18288)
		(layer "In2.Cu")
		(net "M_F_CPU1_SB_DQ<19>")
	)
	(segment
		(start 165.630098 -209.662522)
		(end 165.319202 -209.351626)
		(width 0.18288)
		(layer "In2.Cu")
		(net "M_F_CPU1_SB_DQ<19>")
	)
	(segment
		(start 175.80483 -211.000086)
		(end 175.80483 -210.328256)
		(width 0.18288)
		(layer "In2.Cu")
		(net "M_F_CPU1_SB_DQ<19>")
	)
	(segment
		(start 142.493746 -222.78467)
		(end 141.814042 -222.78467)
		(width 0.18288)
		(layer "In2.Cu")
		(net "M_F_CPU1_SB_DQ<19>")
	)
	(segment
		(start 176.041304 -211.23656)
		(end 175.80483 -211.000086)
		(width 0.18288)
		(layer "In2.Cu")
		(net "M_F_CPU1_SB_DQ<19>")
	)
	(segment
		(start 140.500354 -223.894904)
		(end 140.491464 -223.899984)
		(width 0.088646)
		(layer "In2.Cu")
		(net "M_F_CPU1_SB_DQ<19>")
	)
	(segment
		(start 167.182038 -209.662522)
		(end 165.630098 -209.662522)
		(width 0.18288)
		(layer "In2.Cu")
		(net "M_F_CPU1_SB_DQ<19>")
	)
	(segment
		(start 174.524416 -211.158582)
		(end 174.398686 -211.284312)
		(width 0.18288)
		(layer "In2.Cu")
		(net "M_F_CPU1_SB_DQ<19>")
	)
	(segment
		(start 141.136878 -222.78467)
		(end 140.92047 -223.001078)
		(width 0.088646)
		(layer "In2.Cu")
		(net "M_F_CPU1_SB_DQ<19>")
	)
	(segment
		(start 164.239194 -209.351626)
		(end 163.69919 -208.811622)
		(width 0.18288)
		(layer "In2.Cu")
		(net "M_F_CPU1_SB_DQ<19>")
	)
	(segment
		(start 141.814042 -222.78467)
		(end 141.136878 -222.78467)
		(width 0.088646)
		(layer "In2.Cu")
		(net "M_F_CPU1_SB_DQ<19>")
	)
	(segment
		(start 157.271212 -208.818226)
		(end 155.668472 -210.420966)
		(width 0.18288)
		(layer "In2.Cu")
		(net "M_F_CPU1_SB_DQ<19>")
	)
	(segment
		(start 159.139382 -208.253076)
		(end 158.436818 -208.253076)
		(width 0.18288)
		(layer "In2.Cu")
		(net "M_F_CPU1_SB_DQ<19>")
	)
	(segment
		(start 161.693352 -209.60969)
		(end 161.360358 -209.60969)
		(width 0.18288)
		(layer "In2.Cu")
		(net "M_F_CPU1_SB_DQ<19>")
	)
	(segment
		(start 176.896014 -210.916774)
		(end 176.576228 -211.23656)
		(width 0.18288)
		(layer "In2.Cu")
		(net "M_F_CPU1_SB_DQ<19>")
	)
	(segment
		(start 160.695132 -208.944464)
		(end 159.83077 -208.944464)
		(width 0.18288)
		(layer "In2.Cu")
		(net "M_F_CPU1_SB_DQ<19>")
	)
	(segment
		(start 174.524416 -210.621372)
		(end 174.524416 -211.158582)
		(width 0.18288)
		(layer "In2.Cu")
		(net "M_F_CPU1_SB_DQ<19>")
	)
	(segment
		(start 173.61662 -210.62696)
		(end 173.48073 -210.49107)
		(width 0.18288)
		(layer "In2.Cu")
		(net "M_F_CPU1_SB_DQ<19>")
	)
	(segment
		(start 139.177268 -223.899984)
		(end 139.149328 -223.883728)
		(width 0.088646)
		(layer "In2.Cu")
		(net "M_F_CPU1_SB_DQ<19>")
	)
	(segment
		(start 168.83253 -210.51393)
		(end 168.07561 -209.75701)
		(width 0.18288)
		(layer "In2.Cu")
		(net "M_F_CPU1_SB_DQ<19>")
	)
	(segment
		(start 173.48073 -210.49107)
		(end 172.321982 -210.49107)
		(width 0.18288)
		(layer "In2.Cu")
		(net "M_F_CPU1_SB_DQ<19>")
	)
	(segment
		(start 161.360358 -209.60969)
		(end 160.695132 -208.944464)
		(width 0.18288)
		(layer "In2.Cu")
		(net "M_F_CPU1_SB_DQ<19>")
	)
	(segment
		(start 176.576228 -211.23656)
		(end 176.041304 -211.23656)
		(width 0.18288)
		(layer "In2.Cu")
		(net "M_F_CPU1_SB_DQ<19>")
	)
	(segment
		(start 173.79823 -211.284312)
		(end 173.61662 -211.102702)
		(width 0.18288)
		(layer "In2.Cu")
		(net "M_F_CPU1_SB_DQ<19>")
	)
	(segment
		(start 162.078924 -208.811622)
		(end 161.886392 -209.004154)
		(width 0.18288)
		(layer "In2.Cu")
		(net "M_F_CPU1_SB_DQ<19>")
	)
	(segment
		(start 163.69919 -208.811622)
		(end 162.078924 -208.811622)
		(width 0.18288)
		(layer "In2.Cu")
		(net "M_F_CPU1_SB_DQ<19>")
	)
	(segment
		(start 172.321982 -210.49107)
		(end 172.299122 -210.51393)
		(width 0.18288)
		(layer "In2.Cu")
		(net "M_F_CPU1_SB_DQ<19>")
	)
	(segment
		(start 165.319202 -209.351626)
		(end 164.239194 -209.351626)
		(width 0.18288)
		(layer "In2.Cu")
		(net "M_F_CPU1_SB_DQ<19>")
	)
	(segment
		(start 174.398686 -211.284312)
		(end 173.79823 -211.284312)
		(width 0.18288)
		(layer "In2.Cu")
		(net "M_F_CPU1_SB_DQ<19>")
	)
	(segment
		(start 174.957232 -210.188556)
		(end 174.524416 -210.621372)
		(width 0.18288)
		(layer "In2.Cu")
		(net "M_F_CPU1_SB_DQ<19>")
	)
	(segment
		(start 161.886392 -209.004154)
		(end 161.886392 -209.41665)
		(width 0.18288)
		(layer "In2.Cu")
		(net "M_F_CPU1_SB_DQ<19>")
	)
	(segment
		(start 154.85745 -210.420966)
		(end 142.493746 -222.78467)
		(width 0.18288)
		(layer "In2.Cu")
		(net "M_F_CPU1_SB_DQ<19>")
	)
	(segment
		(start 140.678916 -223.553528)
		(end 140.678916 -223.575626)
		(width 0.088646)
		(layer "In2.Cu")
		(net "M_F_CPU1_SB_DQ<19>")
	)
	(segment
		(start 158.436818 -208.253076)
		(end 157.871668 -208.818226)
		(width 0.18288)
		(layer "In2.Cu")
		(net "M_F_CPU1_SB_DQ<19>")
	)
	(segment
		(start 168.07561 -209.75701)
		(end 167.276526 -209.75701)
		(width 0.18288)
		(layer "In2.Cu")
		(net "M_F_CPU1_SB_DQ<19>")
	)
	(segment
		(start 139.149328 -223.883728)
		(end 138.424666 -223.575626)
		(width 0.088646)
		(layer "In2.Cu")
		(net "M_F_CPU1_SB_DQ<19>")
	)
	(segment
		(start 167.276526 -209.75701)
		(end 167.182038 -209.662522)
		(width 0.18288)
		(layer "In2.Cu")
		(net "M_F_CPU1_SB_DQ<19>")
	)
	(segment
		(start 175.66513 -210.188556)
		(end 174.957232 -210.188556)
		(width 0.18288)
		(layer "In2.Cu")
		(net "M_F_CPU1_SB_DQ<19>")
	)
	(segment
		(start 173.61662 -211.102702)
		(end 173.61662 -210.62696)
		(width 0.18288)
		(layer "In2.Cu")
		(net "M_F_CPU1_SB_DQ<19>")
	)
	(segment
		(start 155.668472 -210.420966)
		(end 154.85745 -210.420966)
		(width 0.18288)
		(layer "In2.Cu")
		(net "M_F_CPU1_SB_DQ<19>")
	)
	(arc
		(start 140.92047 -223.001078)
		(mid 140.747591 -223.254515)
		(end 140.678916 -223.553528)
		(width 0.088646)
		(layer "In2.Cu")
		(net "M_F_CPU1_SB_DQ<19>")
	)
	(arc
		(start 140.678916 -223.575626)
		(mid 140.631237 -223.758526)
		(end 140.500354 -223.894904)
		(width 0.088646)
		(layer "In2.Cu")
		(net "M_F_CPU1_SB_DQ<19>")
	)
	(arc
		(start 140.117068 -223.899984)
		(mid 139.834366 -223.824208)
		(end 139.551664 -223.899984)
		(width 0.088646)
		(layer "In2.Cu")
		(net "M_F_CPU1_SB_DQ<19>")
	)
	(arc
		(start 140.491464 -223.899984)
		(mid 140.304266 -223.950127)
		(end 140.117068 -223.899984)
		(width 0.088646)
		(layer "In2.Cu")
		(net "M_F_CPU1_SB_DQ<19>")
	)
	(arc
		(start 139.551664 -223.899984)
		(mid 139.364466 -223.950161)
		(end 139.177268 -223.899984)
		(width 0.088646)
		(layer "In2.Cu")
		(net "M_F_CPU1_SB_DQ<19>")
	)
	(segment
		(start 180.427884 -213.04885)
		(end 180.434996 -213.041738)
		(width 0.1016)
		(layer "F.Cu")
		(net "M_F_CPU1_SB_DQ<18>")
	)
	(segment
		(start 183.574436 -212.364828)
		(end 183.958484 -212.364828)
		(width 0.20066)
		(layer "F.Cu")
		(net "M_F_CPU1_SB_DQ<18>")
	)
	(segment
		(start 183.340248 -212.599016)
		(end 183.574436 -212.364828)
		(width 0.20066)
		(layer "F.Cu")
		(net "M_F_CPU1_SB_DQ<18>")
	)
	(segment
		(start 179.699158 -212.616796)
		(end 180.131212 -213.04885)
		(width 0.20066)
		(layer "F.Cu")
		(net "M_F_CPU1_SB_DQ<18>")
	)
	(segment
		(start 180.131212 -213.04885)
		(end 180.423058 -213.04885)
		(width 0.20066)
		(layer "F.Cu")
		(net "M_F_CPU1_SB_DQ<18>")
	)
	(segment
		(start 178.000914 -212.616796)
		(end 179.699158 -212.616796)
		(width 0.20066)
		(layer "F.Cu")
		(net "M_F_CPU1_SB_DQ<18>")
	)
	(segment
		(start 183.958484 -212.364828)
		(end 184.210452 -212.616796)
		(width 0.20066)
		(layer "F.Cu")
		(net "M_F_CPU1_SB_DQ<18>")
	)
	(segment
		(start 137.954766 -224.925382)
		(end 137.954766 -224.389442)
		(width 0.20066)
		(layer "F.Cu")
		(net "M_F_CPU1_SB_DQ<18>")
	)
	(segment
		(start 183.340248 -212.849968)
		(end 183.340248 -212.599016)
		(width 0.20066)
		(layer "F.Cu")
		(net "M_F_CPU1_SB_DQ<18>")
	)
	(segment
		(start 183.136286 -213.05393)
		(end 183.340248 -212.849968)
		(width 0.20066)
		(layer "F.Cu")
		(net "M_F_CPU1_SB_DQ<18>")
	)
	(segment
		(start 182.455058 -213.05393)
		(end 183.136286 -213.05393)
		(width 0.20066)
		(layer "F.Cu")
		(net "M_F_CPU1_SB_DQ<18>")
	)
	(segment
		(start 180.434996 -213.041738)
		(end 182.442866 -213.041738)
		(width 0.1016)
		(layer "F.Cu")
		(net "M_F_CPU1_SB_DQ<18>")
	)
	(segment
		(start 182.442866 -213.041738)
		(end 182.455058 -213.05393)
		(width 0.1016)
		(layer "F.Cu")
		(net "M_F_CPU1_SB_DQ<18>")
	)
	(segment
		(start 176.896014 -212.616796)
		(end 178.000914 -212.616796)
		(width 0.20066)
		(layer "F.Cu")
		(net "M_F_CPU1_SB_DQ<18>")
	)
	(segment
		(start 180.423058 -213.04885)
		(end 180.427884 -213.04885)
		(width 0.101854)
		(layer "F.Cu")
		(net "M_F_CPU1_SB_DQ<18>")
	)
	(segment
		(start 184.210452 -212.616796)
		(end 185.544714 -212.616796)
		(width 0.20066)
		(layer "F.Cu")
		(net "M_F_CPU1_SB_DQ<18>")
	)
	(segment
		(start 175.441356 -213.434422)
		(end 175.441356 -212.230462)
		(width 0.18288)
		(layer "In2.Cu")
		(net "M_F_CPU1_SB_DQ<18>")
	)
	(segment
		(start 163.763198 -211.332064)
		(end 162.046158 -211.332064)
		(width 0.18288)
		(layer "In2.Cu")
		(net "M_F_CPU1_SB_DQ<18>")
	)
	(segment
		(start 175.250094 -212.0392)
		(end 174.891192 -212.0392)
		(width 0.18288)
		(layer "In2.Cu")
		(net "M_F_CPU1_SB_DQ<18>")
	)
	(segment
		(start 168.237408 -211.412328)
		(end 164.719762 -211.412328)
		(width 0.18288)
		(layer "In2.Cu")
		(net "M_F_CPU1_SB_DQ<18>")
	)
	(segment
		(start 176.492916 -212.213698)
		(end 176.290986 -212.213698)
		(width 0.18288)
		(layer "In2.Cu")
		(net "M_F_CPU1_SB_DQ<18>")
	)
	(segment
		(start 175.441356 -212.230462)
		(end 175.250094 -212.0392)
		(width 0.18288)
		(layer "In2.Cu")
		(net "M_F_CPU1_SB_DQ<18>")
	)
	(segment
		(start 169.819574 -211.930488)
		(end 169.502836 -212.247226)
		(width 0.18288)
		(layer "In2.Cu")
		(net "M_F_CPU1_SB_DQ<18>")
	)
	(segment
		(start 175.940212 -213.585298)
		(end 175.592232 -213.585298)
		(width 0.18288)
		(layer "In2.Cu")
		(net "M_F_CPU1_SB_DQ<18>")
	)
	(segment
		(start 163.953952 -211.14131)
		(end 163.763198 -211.332064)
		(width 0.18288)
		(layer "In2.Cu")
		(net "M_F_CPU1_SB_DQ<18>")
	)
	(segment
		(start 176.148238 -212.356446)
		(end 176.148238 -213.377272)
		(width 0.18288)
		(layer "In2.Cu")
		(net "M_F_CPU1_SB_DQ<18>")
	)
	(segment
		(start 152.4 -215.205564)
		(end 151.535638 -215.205564)
		(width 0.18288)
		(layer "In2.Cu")
		(net "M_F_CPU1_SB_DQ<18>")
	)
	(segment
		(start 141.562074 -223.802448)
		(end 140.734796 -224.629726)
		(width 0.088646)
		(layer "In2.Cu")
		(net "M_F_CPU1_SB_DQ<18>")
	)
	(segment
		(start 161.939478 -211.225384)
		(end 160.389824 -211.225384)
		(width 0.18288)
		(layer "In2.Cu")
		(net "M_F_CPU1_SB_DQ<18>")
	)
	(segment
		(start 174.7393 -212.191092)
		(end 174.292768 -212.191092)
		(width 0.18288)
		(layer "In2.Cu")
		(net "M_F_CPU1_SB_DQ<18>")
	)
	(segment
		(start 169.072306 -212.247226)
		(end 168.237408 -211.412328)
		(width 0.18288)
		(layer "In2.Cu")
		(net "M_F_CPU1_SB_DQ<18>")
	)
	(segment
		(start 159.11957 -210.746594)
		(end 158.541466 -210.746594)
		(width 0.18288)
		(layer "In2.Cu")
		(net "M_F_CPU1_SB_DQ<18>")
	)
	(segment
		(start 151.535638 -215.205564)
		(end 142.938754 -223.802448)
		(width 0.18288)
		(layer "In2.Cu")
		(net "M_F_CPU1_SB_DQ<18>")
	)
	(segment
		(start 164.448744 -211.14131)
		(end 163.953952 -211.14131)
		(width 0.18288)
		(layer "In2.Cu")
		(net "M_F_CPU1_SB_DQ<18>")
	)
	(segment
		(start 176.148238 -213.377272)
		(end 175.940212 -213.585298)
		(width 0.18288)
		(layer "In2.Cu")
		(net "M_F_CPU1_SB_DQ<18>")
	)
	(segment
		(start 173.414182 -212.69452)
		(end 173.414182 -212.354668)
		(width 0.18288)
		(layer "In2.Cu")
		(net "M_F_CPU1_SB_DQ<18>")
	)
	(segment
		(start 157.40507 -211.365084)
		(end 156.24048 -211.365084)
		(width 0.18288)
		(layer "In2.Cu")
		(net "M_F_CPU1_SB_DQ<18>")
	)
	(segment
		(start 160.130744 -211.484464)
		(end 159.85744 -211.484464)
		(width 0.18288)
		(layer "In2.Cu")
		(net "M_F_CPU1_SB_DQ<18>")
	)
	(segment
		(start 157.777688 -211.510372)
		(end 157.550358 -211.510372)
		(width 0.18288)
		(layer "In2.Cu")
		(net "M_F_CPU1_SB_DQ<18>")
	)
	(segment
		(start 174.132748 -212.351112)
		(end 174.132748 -212.69452)
		(width 0.18288)
		(layer "In2.Cu")
		(net "M_F_CPU1_SB_DQ<18>")
	)
	(segment
		(start 171.087288 -211.930488)
		(end 169.819574 -211.930488)
		(width 0.18288)
		(layer "In2.Cu")
		(net "M_F_CPU1_SB_DQ<18>")
	)
	(segment
		(start 138.707368 -224.7138)
		(end 138.679428 -224.697544)
		(width 0.088646)
		(layer "In2.Cu")
		(net "M_F_CPU1_SB_DQ<18>")
	)
	(segment
		(start 142.938754 -223.802448)
		(end 141.814042 -223.802448)
		(width 0.18288)
		(layer "In2.Cu")
		(net "M_F_CPU1_SB_DQ<18>")
	)
	(segment
		(start 173.972728 -212.85454)
		(end 173.574202 -212.85454)
		(width 0.18288)
		(layer "In2.Cu")
		(net "M_F_CPU1_SB_DQ<18>")
	)
	(segment
		(start 173.254162 -212.194648)
		(end 171.351448 -212.194648)
		(width 0.18288)
		(layer "In2.Cu")
		(net "M_F_CPU1_SB_DQ<18>")
	)
	(segment
		(start 159.85744 -211.484464)
		(end 159.11957 -210.746594)
		(width 0.18288)
		(layer "In2.Cu")
		(net "M_F_CPU1_SB_DQ<18>")
	)
	(segment
		(start 138.679428 -224.697544)
		(end 137.954766 -224.389442)
		(width 0.088646)
		(layer "In2.Cu")
		(net "M_F_CPU1_SB_DQ<18>")
	)
	(segment
		(start 173.414182 -212.354668)
		(end 173.254162 -212.194648)
		(width 0.18288)
		(layer "In2.Cu")
		(net "M_F_CPU1_SB_DQ<18>")
	)
	(segment
		(start 160.389824 -211.225384)
		(end 160.130744 -211.484464)
		(width 0.18288)
		(layer "In2.Cu")
		(net "M_F_CPU1_SB_DQ<18>")
	)
	(segment
		(start 171.351448 -212.194648)
		(end 171.087288 -211.930488)
		(width 0.18288)
		(layer "In2.Cu")
		(net "M_F_CPU1_SB_DQ<18>")
	)
	(segment
		(start 174.292768 -212.191092)
		(end 174.132748 -212.351112)
		(width 0.18288)
		(layer "In2.Cu")
		(net "M_F_CPU1_SB_DQ<18>")
	)
	(segment
		(start 174.132748 -212.69452)
		(end 173.972728 -212.85454)
		(width 0.18288)
		(layer "In2.Cu")
		(net "M_F_CPU1_SB_DQ<18>")
	)
	(segment
		(start 140.734796 -224.629726)
		(end 140.335254 -224.629726)
		(width 0.088646)
		(layer "In2.Cu")
		(net "M_F_CPU1_SB_DQ<18>")
	)
	(segment
		(start 157.550358 -211.510372)
		(end 157.40507 -211.365084)
		(width 0.18288)
		(layer "In2.Cu")
		(net "M_F_CPU1_SB_DQ<18>")
	)
	(segment
		(start 176.896014 -212.616796)
		(end 176.492916 -212.213698)
		(width 0.18288)
		(layer "In2.Cu")
		(net "M_F_CPU1_SB_DQ<18>")
	)
	(segment
		(start 158.541466 -210.746594)
		(end 157.777688 -211.510372)
		(width 0.18288)
		(layer "In2.Cu")
		(net "M_F_CPU1_SB_DQ<18>")
	)
	(segment
		(start 156.24048 -211.365084)
		(end 152.4 -215.205564)
		(width 0.18288)
		(layer "In2.Cu")
		(net "M_F_CPU1_SB_DQ<18>")
	)
	(segment
		(start 173.574202 -212.85454)
		(end 173.414182 -212.69452)
		(width 0.18288)
		(layer "In2.Cu")
		(net "M_F_CPU1_SB_DQ<18>")
	)
	(segment
		(start 141.814042 -223.802448)
		(end 141.562074 -223.802448)
		(width 0.088646)
		(layer "In2.Cu")
		(net "M_F_CPU1_SB_DQ<18>")
	)
	(segment
		(start 169.502836 -212.247226)
		(end 169.072306 -212.247226)
		(width 0.18288)
		(layer "In2.Cu")
		(net "M_F_CPU1_SB_DQ<18>")
	)
	(segment
		(start 164.719762 -211.412328)
		(end 164.448744 -211.14131)
		(width 0.18288)
		(layer "In2.Cu")
		(net "M_F_CPU1_SB_DQ<18>")
	)
	(segment
		(start 176.290986 -212.213698)
		(end 176.148238 -212.356446)
		(width 0.18288)
		(layer "In2.Cu")
		(net "M_F_CPU1_SB_DQ<18>")
	)
	(segment
		(start 175.592232 -213.585298)
		(end 175.441356 -213.434422)
		(width 0.18288)
		(layer "In2.Cu")
		(net "M_F_CPU1_SB_DQ<18>")
	)
	(segment
		(start 174.891192 -212.0392)
		(end 174.7393 -212.191092)
		(width 0.18288)
		(layer "In2.Cu")
		(net "M_F_CPU1_SB_DQ<18>")
	)
	(segment
		(start 162.046158 -211.332064)
		(end 161.939478 -211.225384)
		(width 0.18288)
		(layer "In2.Cu")
		(net "M_F_CPU1_SB_DQ<18>")
	)
	(arc
		(start 139.081764 -224.7138)
		(mid 138.894566 -224.763977)
		(end 138.707368 -224.7138)
		(width 0.088646)
		(layer "In2.Cu")
		(net "M_F_CPU1_SB_DQ<18>")
	)
	(arc
		(start 140.335254 -224.629726)
		(mid 140.172875 -224.651113)
		(end 140.021564 -224.7138)
		(width 0.088646)
		(layer "In2.Cu")
		(net "M_F_CPU1_SB_DQ<18>")
	)
	(arc
		(start 139.647168 -224.7138)
		(mid 139.364466 -224.638024)
		(end 139.081764 -224.7138)
		(width 0.088646)
		(layer "In2.Cu")
		(net "M_F_CPU1_SB_DQ<18>")
	)
	(arc
		(start 140.021564 -224.7138)
		(mid 139.834366 -224.763943)
		(end 139.647168 -224.7138)
		(width 0.088646)
		(layer "In2.Cu")
		(net "M_F_CPU1_SB_DQ<18>")
	)
	(segment
		(start 176.145444 -212.015324)
		(end 175.67021 -212.015324)
		(width 0.20066)
		(layer "F.Cu")
		(net "M_F_CPU1_SB_DQ<17>")
	)
	(segment
		(start 175.421544 -211.766658)
		(end 173.900846 -211.766658)
		(width 0.20066)
		(layer "F.Cu")
		(net "M_F_CPU1_SB_DQ<17>")
	)
	(segment
		(start 176.333404 -211.459826)
		(end 176.333404 -211.827364)
		(width 0.20066)
		(layer "F.Cu")
		(net "M_F_CPU1_SB_DQ<17>")
	)
	(segment
		(start 176.796192 -211.341716)
		(end 176.451514 -211.341716)
		(width 0.20066)
		(layer "F.Cu")
		(net "M_F_CPU1_SB_DQ<17>")
	)
	(segment
		(start 175.67021 -212.015324)
		(end 175.421544 -211.766658)
		(width 0.20066)
		(layer "F.Cu")
		(net "M_F_CPU1_SB_DQ<17>")
	)
	(segment
		(start 136.545066 -223.57588)
		(end 136.544812 -223.575626)
		(width 0.20066)
		(layer "F.Cu")
		(net "M_F_CPU1_SB_DQ<17>")
	)
	(segment
		(start 179.852828 -211.766912)
		(end 179.421282 -211.335366)
		(width 0.20066)
		(layer "F.Cu")
		(net "M_F_CPU1_SB_DQ<17>")
	)
	(segment
		(start 179.004976 -211.341716)
		(end 176.816258 -211.341716)
		(width 0.1016)
		(layer "F.Cu")
		(net "M_F_CPU1_SB_DQ<17>")
	)
	(segment
		(start 176.451514 -211.341716)
		(end 176.333404 -211.459826)
		(width 0.20066)
		(layer "F.Cu")
		(net "M_F_CPU1_SB_DQ<17>")
	)
	(segment
		(start 181.444392 -211.766912)
		(end 179.852828 -211.766912)
		(width 0.20066)
		(layer "F.Cu")
		(net "M_F_CPU1_SB_DQ<17>")
	)
	(segment
		(start 136.545066 -224.111566)
		(end 136.545066 -223.57588)
		(width 0.20066)
		(layer "F.Cu")
		(net "M_F_CPU1_SB_DQ<17>")
	)
	(segment
		(start 173.900846 -211.766658)
		(end 172.795946 -211.766658)
		(width 0.20066)
		(layer "F.Cu")
		(net "M_F_CPU1_SB_DQ<17>")
	)
	(segment
		(start 181.444646 -211.766658)
		(end 181.444392 -211.766912)
		(width 0.20066)
		(layer "F.Cu")
		(net "M_F_CPU1_SB_DQ<17>")
	)
	(segment
		(start 176.333404 -211.827364)
		(end 176.145444 -212.015324)
		(width 0.20066)
		(layer "F.Cu")
		(net "M_F_CPU1_SB_DQ<17>")
	)
	(segment
		(start 179.421282 -211.335366)
		(end 179.011326 -211.335366)
		(width 0.20066)
		(layer "F.Cu")
		(net "M_F_CPU1_SB_DQ<17>")
	)
	(segment
		(start 176.816258 -211.341716)
		(end 176.796192 -211.341716)
		(width 0.101854)
		(layer "F.Cu")
		(net "M_F_CPU1_SB_DQ<17>")
	)
	(segment
		(start 179.011326 -211.335366)
		(end 179.004976 -211.341716)
		(width 0.1016)
		(layer "F.Cu")
		(net "M_F_CPU1_SB_DQ<17>")
	)
	(segment
		(start 162.451542 -210.062318)
		(end 161.979864 -210.533996)
		(width 0.18288)
		(layer "In2.Cu")
		(net "M_F_CPU1_SB_DQ<17>")
	)
	(segment
		(start 163.343336 -210.062318)
		(end 162.451542 -210.062318)
		(width 0.18288)
		(layer "In2.Cu")
		(net "M_F_CPU1_SB_DQ<17>")
	)
	(segment
		(start 142.708884 -223.294448)
		(end 141.814042 -223.294448)
		(width 0.18288)
		(layer "In2.Cu")
		(net "M_F_CPU1_SB_DQ<17>")
	)
	(segment
		(start 164.546026 -210.045046)
		(end 164.546026 -210.354164)
		(width 0.18288)
		(layer "In2.Cu")
		(net "M_F_CPU1_SB_DQ<17>")
	)
	(segment
		(start 172.361352 -211.332064)
		(end 168.916604 -211.332064)
		(width 0.18288)
		(layer "In2.Cu")
		(net "M_F_CPU1_SB_DQ<17>")
	)
	(segment
		(start 161.979864 -210.533996)
		(end 160.819846 -210.533996)
		(width 0.18288)
		(layer "In2.Cu")
		(net "M_F_CPU1_SB_DQ<17>")
	)
	(segment
		(start 152.672288 -214.188548)
		(end 152.399492 -214.188548)
		(width 0.18288)
		(layer "In2.Cu")
		(net "M_F_CPU1_SB_DQ<17>")
	)
	(segment
		(start 157.396942 -210.56092)
		(end 157.171644 -210.786218)
		(width 0.18288)
		(layer "In2.Cu")
		(net "M_F_CPU1_SB_DQ<17>")
	)
	(segment
		(start 155.063698 -210.939634)
		(end 154.734006 -211.269326)
		(width 0.18288)
		(layer "In2.Cu")
		(net "M_F_CPU1_SB_DQ<17>")
	)
	(segment
		(start 157.171644 -210.786218)
		(end 156.898848 -210.786218)
		(width 0.18288)
		(layer "In2.Cu")
		(net "M_F_CPU1_SB_DQ<17>")
	)
	(segment
		(start 160.626806 -210.340956)
		(end 160.626806 -209.797142)
		(width 0.18288)
		(layer "In2.Cu")
		(net "M_F_CPU1_SB_DQ<17>")
	)
	(segment
		(start 152.897586 -213.690454)
		(end 152.897586 -213.96325)
		(width 0.18288)
		(layer "In2.Cu")
		(net "M_F_CPU1_SB_DQ<17>")
	)
	(segment
		(start 160.492186 -209.662522)
		(end 158.089092 -209.662522)
		(width 0.18288)
		(layer "In2.Cu")
		(net "M_F_CPU1_SB_DQ<17>")
	)
	(segment
		(start 152.74163 -213.261702)
		(end 152.74163 -213.534498)
		(width 0.18288)
		(layer "In2.Cu")
		(net "M_F_CPU1_SB_DQ<17>")
	)
	(segment
		(start 165.834314 -210.864958)
		(end 165.32098 -210.351624)
		(width 0.18288)
		(layer "In2.Cu")
		(net "M_F_CPU1_SB_DQ<17>")
	)
	(segment
		(start 167.877236 -210.292696)
		(end 167.38092 -210.292696)
		(width 0.18288)
		(layer "In2.Cu")
		(net "M_F_CPU1_SB_DQ<17>")
	)
	(segment
		(start 152.966928 -213.036404)
		(end 152.74163 -213.261702)
		(width 0.18288)
		(layer "In2.Cu")
		(net "M_F_CPU1_SB_DQ<17>")
	)
	(segment
		(start 164.546026 -210.354164)
		(end 164.352986 -210.547204)
		(width 0.18288)
		(layer "In2.Cu")
		(net "M_F_CPU1_SB_DQ<17>")
	)
	(segment
		(start 172.795946 -211.766658)
		(end 172.361352 -211.332064)
		(width 0.18288)
		(layer "In2.Cu")
		(net "M_F_CPU1_SB_DQ<17>")
	)
	(segment
		(start 154.889962 -211.970874)
		(end 154.664664 -212.196172)
		(width 0.18288)
		(layer "In2.Cu")
		(net "M_F_CPU1_SB_DQ<17>")
	)
	(segment
		(start 155.881324 -210.939634)
		(end 155.063698 -210.939634)
		(width 0.18288)
		(layer "In2.Cu")
		(net "M_F_CPU1_SB_DQ<17>")
	)
	(segment
		(start 136.923272 -223.641412)
		(end 136.857486 -223.575626)
		(width 0.088646)
		(layer "In2.Cu")
		(net "M_F_CPU1_SB_DQ<17>")
	)
	(segment
		(start 160.626806 -209.797142)
		(end 160.492186 -209.662522)
		(width 0.18288)
		(layer "In2.Cu")
		(net "M_F_CPU1_SB_DQ<17>")
	)
	(segment
		(start 156.898848 -210.786218)
		(end 156.603192 -210.490562)
		(width 0.18288)
		(layer "In2.Cu")
		(net "M_F_CPU1_SB_DQ<17>")
	)
	(segment
		(start 152.399492 -214.188548)
		(end 152.243536 -214.032592)
		(width 0.18288)
		(layer "In2.Cu")
		(net "M_F_CPU1_SB_DQ<17>")
	)
	(segment
		(start 163.828222 -210.547204)
		(end 163.343336 -210.062318)
		(width 0.18288)
		(layer "In2.Cu")
		(net "M_F_CPU1_SB_DQ<17>")
	)
	(segment
		(start 157.487112 -209.333846)
		(end 157.101286 -209.719672)
		(width 0.18288)
		(layer "In2.Cu")
		(net "M_F_CPU1_SB_DQ<17>")
	)
	(segment
		(start 141.814042 -223.294448)
		(end 141.15161 -223.294448)
		(width 0.088646)
		(layer "In2.Cu")
		(net "M_F_CPU1_SB_DQ<17>")
	)
	(segment
		(start 153.668476 -213.19236)
		(end 153.39568 -213.19236)
		(width 0.18288)
		(layer "In2.Cu")
		(net "M_F_CPU1_SB_DQ<17>")
	)
	(segment
		(start 157.396942 -210.288124)
		(end 157.396942 -210.56092)
		(width 0.18288)
		(layer "In2.Cu")
		(net "M_F_CPU1_SB_DQ<17>")
	)
	(segment
		(start 158.089092 -209.662522)
		(end 157.760416 -209.333846)
		(width 0.18288)
		(layer "In2.Cu")
		(net "M_F_CPU1_SB_DQ<17>")
	)
	(segment
		(start 154.235912 -212.040216)
		(end 153.963116 -212.040216)
		(width 0.18288)
		(layer "In2.Cu")
		(net "M_F_CPU1_SB_DQ<17>")
	)
	(segment
		(start 153.963116 -212.040216)
		(end 153.737818 -212.265514)
		(width 0.18288)
		(layer "In2.Cu")
		(net "M_F_CPU1_SB_DQ<17>")
	)
	(segment
		(start 156.603192 -210.490562)
		(end 156.330396 -210.490562)
		(width 0.18288)
		(layer "In2.Cu")
		(net "M_F_CPU1_SB_DQ<17>")
	)
	(segment
		(start 152.897586 -213.96325)
		(end 152.672288 -214.188548)
		(width 0.18288)
		(layer "In2.Cu")
		(net "M_F_CPU1_SB_DQ<17>")
	)
	(segment
		(start 153.893774 -212.694266)
		(end 153.893774 -212.967062)
		(width 0.18288)
		(layer "In2.Cu")
		(net "M_F_CPU1_SB_DQ<17>")
	)
	(segment
		(start 160.819846 -210.533996)
		(end 160.626806 -210.340956)
		(width 0.18288)
		(layer "In2.Cu")
		(net "M_F_CPU1_SB_DQ<17>")
	)
	(segment
		(start 153.39568 -213.19236)
		(end 153.239724 -213.036404)
		(width 0.18288)
		(layer "In2.Cu")
		(net "M_F_CPU1_SB_DQ<17>")
	)
	(segment
		(start 141.15161 -223.294448)
		(end 140.869416 -223.585532)
		(width 0.088646)
		(layer "In2.Cu")
		(net "M_F_CPU1_SB_DQ<17>")
	)
	(segment
		(start 136.857486 -223.575626)
		(end 136.544812 -223.575626)
		(width 0.088646)
		(layer "In2.Cu")
		(net "M_F_CPU1_SB_DQ<17>")
	)
	(segment
		(start 167.38092 -210.292696)
		(end 166.808658 -210.864958)
		(width 0.18288)
		(layer "In2.Cu")
		(net "M_F_CPU1_SB_DQ<17>")
	)
	(segment
		(start 152.74163 -213.534498)
		(end 152.897586 -213.690454)
		(width 0.18288)
		(layer "In2.Cu")
		(net "M_F_CPU1_SB_DQ<17>")
	)
	(segment
		(start 156.330396 -210.490562)
		(end 155.881324 -210.939634)
		(width 0.18288)
		(layer "In2.Cu")
		(net "M_F_CPU1_SB_DQ<17>")
	)
	(segment
		(start 166.808658 -210.864958)
		(end 165.834314 -210.864958)
		(width 0.18288)
		(layer "In2.Cu")
		(net "M_F_CPU1_SB_DQ<17>")
	)
	(segment
		(start 168.916604 -211.332064)
		(end 167.877236 -210.292696)
		(width 0.18288)
		(layer "In2.Cu")
		(net "M_F_CPU1_SB_DQ<17>")
	)
	(segment
		(start 164.352986 -210.547204)
		(end 163.828222 -210.547204)
		(width 0.18288)
		(layer "In2.Cu")
		(net "M_F_CPU1_SB_DQ<17>")
	)
	(segment
		(start 151.97074 -214.032592)
		(end 142.708884 -223.294448)
		(width 0.18288)
		(layer "In2.Cu")
		(net "M_F_CPU1_SB_DQ<17>")
	)
	(segment
		(start 157.101286 -209.992468)
		(end 157.396942 -210.288124)
		(width 0.18288)
		(layer "In2.Cu")
		(net "M_F_CPU1_SB_DQ<17>")
	)
	(segment
		(start 154.391868 -212.196172)
		(end 154.235912 -212.040216)
		(width 0.18288)
		(layer "In2.Cu")
		(net "M_F_CPU1_SB_DQ<17>")
	)
	(segment
		(start 154.734006 -211.269326)
		(end 154.734006 -211.542122)
		(width 0.18288)
		(layer "In2.Cu")
		(net "M_F_CPU1_SB_DQ<17>")
	)
	(segment
		(start 153.893774 -212.967062)
		(end 153.668476 -213.19236)
		(width 0.18288)
		(layer "In2.Cu")
		(net "M_F_CPU1_SB_DQ<17>")
	)
	(segment
		(start 153.737818 -212.53831)
		(end 153.893774 -212.694266)
		(width 0.18288)
		(layer "In2.Cu")
		(net "M_F_CPU1_SB_DQ<17>")
	)
	(segment
		(start 157.101286 -209.719672)
		(end 157.101286 -209.992468)
		(width 0.18288)
		(layer "In2.Cu")
		(net "M_F_CPU1_SB_DQ<17>")
	)
	(segment
		(start 153.737818 -212.265514)
		(end 153.737818 -212.53831)
		(width 0.18288)
		(layer "In2.Cu")
		(net "M_F_CPU1_SB_DQ<17>")
	)
	(segment
		(start 164.706046 -209.885026)
		(end 164.546026 -210.045046)
		(width 0.18288)
		(layer "In2.Cu")
		(net "M_F_CPU1_SB_DQ<17>")
	)
	(segment
		(start 157.760416 -209.333846)
		(end 157.487112 -209.333846)
		(width 0.18288)
		(layer "In2.Cu")
		(net "M_F_CPU1_SB_DQ<17>")
	)
	(segment
		(start 152.243536 -214.032592)
		(end 151.97074 -214.032592)
		(width 0.18288)
		(layer "In2.Cu")
		(net "M_F_CPU1_SB_DQ<17>")
	)
	(segment
		(start 165.32098 -210.078066)
		(end 165.12794 -209.885026)
		(width 0.18288)
		(layer "In2.Cu")
		(net "M_F_CPU1_SB_DQ<17>")
	)
	(segment
		(start 165.32098 -210.351624)
		(end 165.32098 -210.078066)
		(width 0.18288)
		(layer "In2.Cu")
		(net "M_F_CPU1_SB_DQ<17>")
	)
	(segment
		(start 154.664664 -212.196172)
		(end 154.391868 -212.196172)
		(width 0.18288)
		(layer "In2.Cu")
		(net "M_F_CPU1_SB_DQ<17>")
	)
	(segment
		(start 154.734006 -211.542122)
		(end 154.889962 -211.698078)
		(width 0.18288)
		(layer "In2.Cu")
		(net "M_F_CPU1_SB_DQ<17>")
	)
	(segment
		(start 153.239724 -213.036404)
		(end 152.966928 -213.036404)
		(width 0.18288)
		(layer "In2.Cu")
		(net "M_F_CPU1_SB_DQ<17>")
	)
	(segment
		(start 154.889962 -211.698078)
		(end 154.889962 -211.970874)
		(width 0.18288)
		(layer "In2.Cu")
		(net "M_F_CPU1_SB_DQ<17>")
	)
	(segment
		(start 165.12794 -209.885026)
		(end 164.706046 -209.885026)
		(width 0.18288)
		(layer "In2.Cu")
		(net "M_F_CPU1_SB_DQ<17>")
	)
	(arc
		(start 140.021564 -224.065084)
		(mid 139.834366 -224.014941)
		(end 139.647168 -224.065084)
		(width 0.088646)
		(layer "In2.Cu")
		(net "M_F_CPU1_SB_DQ<17>")
	)
	(arc
		(start 139.647168 -224.065084)
		(mid 139.364466 -224.140826)
		(end 139.081764 -224.065084)
		(width 0.088646)
		(layer "In2.Cu")
		(net "M_F_CPU1_SB_DQ<17>")
	)
	(arc
		(start 137.767568 -224.065084)
		(mid 137.231098 -224.080961)
		(end 136.923272 -223.641412)
		(width 0.088646)
		(layer "In2.Cu")
		(net "M_F_CPU1_SB_DQ<17>")
	)
	(arc
		(start 138.141964 -224.065084)
		(mid 137.954766 -224.014941)
		(end 137.767568 -224.065084)
		(width 0.088646)
		(layer "In2.Cu")
		(net "M_F_CPU1_SB_DQ<17>")
	)
	(arc
		(start 139.081764 -224.065084)
		(mid 138.894566 -224.014907)
		(end 138.707368 -224.065084)
		(width 0.088646)
		(layer "In2.Cu")
		(net "M_F_CPU1_SB_DQ<17>")
	)
	(arc
		(start 140.869416 -223.585532)
		(mid 140.582541 -224.067617)
		(end 140.021564 -224.065084)
		(width 0.088646)
		(layer "In2.Cu")
		(net "M_F_CPU1_SB_DQ<17>")
	)
	(arc
		(start 138.707368 -224.065084)
		(mid 138.424666 -224.14086)
		(end 138.141964 -224.065084)
		(width 0.088646)
		(layer "In2.Cu")
		(net "M_F_CPU1_SB_DQ<17>")
	)
	(segment
		(start 137.014712 -224.389696)
		(end 137.014966 -224.389442)
		(width 0.20066)
		(layer "F.Cu")
		(net "M_F_CPU1_SB_DQ<16>")
	)
	(segment
		(start 173.900846 -213.46668)
		(end 172.795946 -213.46668)
		(width 0.20066)
		(layer "F.Cu")
		(net "M_F_CPU1_SB_DQ<16>")
	)
	(segment
		(start 179.852828 -213.466934)
		(end 179.421282 -213.035388)
		(width 0.20066)
		(layer "F.Cu")
		(net "M_F_CPU1_SB_DQ<16>")
	)
	(segment
		(start 176.333404 -213.159848)
		(end 176.333404 -213.527386)
		(width 0.20066)
		(layer "F.Cu")
		(net "M_F_CPU1_SB_DQ<16>")
	)
	(segment
		(start 176.451514 -213.041738)
		(end 176.333404 -213.159848)
		(width 0.20066)
		(layer "F.Cu")
		(net "M_F_CPU1_SB_DQ<16>")
	)
	(segment
		(start 176.333404 -213.527386)
		(end 176.145444 -213.715346)
		(width 0.20066)
		(layer "F.Cu")
		(net "M_F_CPU1_SB_DQ<16>")
	)
	(segment
		(start 179.011326 -213.035388)
		(end 179.004976 -213.041738)
		(width 0.1016)
		(layer "F.Cu")
		(net "M_F_CPU1_SB_DQ<16>")
	)
	(segment
		(start 179.004976 -213.041738)
		(end 176.843182 -213.041738)
		(width 0.1016)
		(layer "F.Cu")
		(net "M_F_CPU1_SB_DQ<16>")
	)
	(segment
		(start 175.67021 -213.715346)
		(end 175.421544 -213.46668)
		(width 0.20066)
		(layer "F.Cu")
		(net "M_F_CPU1_SB_DQ<16>")
	)
	(segment
		(start 176.796192 -213.041738)
		(end 176.451514 -213.041738)
		(width 0.20066)
		(layer "F.Cu")
		(net "M_F_CPU1_SB_DQ<16>")
	)
	(segment
		(start 181.444646 -213.46668)
		(end 181.444392 -213.466934)
		(width 0.20066)
		(layer "F.Cu")
		(net "M_F_CPU1_SB_DQ<16>")
	)
	(segment
		(start 181.444392 -213.466934)
		(end 179.852828 -213.466934)
		(width 0.20066)
		(layer "F.Cu")
		(net "M_F_CPU1_SB_DQ<16>")
	)
	(segment
		(start 175.421544 -213.46668)
		(end 173.900846 -213.46668)
		(width 0.20066)
		(layer "F.Cu")
		(net "M_F_CPU1_SB_DQ<16>")
	)
	(segment
		(start 137.014712 -224.925382)
		(end 137.014712 -224.389696)
		(width 0.20066)
		(layer "F.Cu")
		(net "M_F_CPU1_SB_DQ<16>")
	)
	(segment
		(start 176.843182 -213.041738)
		(end 176.796192 -213.041738)
		(width 0.101854)
		(layer "F.Cu")
		(net "M_F_CPU1_SB_DQ<16>")
	)
	(segment
		(start 176.145444 -213.715346)
		(end 175.67021 -213.715346)
		(width 0.20066)
		(layer "F.Cu")
		(net "M_F_CPU1_SB_DQ<16>")
	)
	(segment
		(start 179.421282 -213.035388)
		(end 179.011326 -213.035388)
		(width 0.20066)
		(layer "F.Cu")
		(net "M_F_CPU1_SB_DQ<16>")
	)
	(segment
		(start 146.187414 -221.552262)
		(end 146.375628 -221.74073)
		(width 0.18288)
		(layer "In2.Cu")
		(net "M_F_CPU1_SB_DQ<16>")
	)
	(segment
		(start 147.4089 -220.05798)
		(end 147.183602 -220.283278)
		(width 0.18288)
		(layer "In2.Cu")
		(net "M_F_CPU1_SB_DQ<16>")
	)
	(segment
		(start 147.183602 -220.283278)
		(end 147.183602 -220.556074)
		(width 0.18288)
		(layer "In2.Cu")
		(net "M_F_CPU1_SB_DQ<16>")
	)
	(segment
		(start 151.168354 -216.571322)
		(end 151.356568 -216.75979)
		(width 0.18288)
		(layer "In2.Cu")
		(net "M_F_CPU1_SB_DQ<16>")
	)
	(segment
		(start 137.64387 -224.862644)
		(end 137.014966 -224.389442)
		(width 0.088646)
		(layer "In2.Cu")
		(net "M_F_CPU1_SB_DQ<16>")
	)
	(segment
		(start 171.465748 -212.88121)
		(end 171.326048 -213.02091)
		(width 0.18288)
		(layer "In2.Cu")
		(net "M_F_CPU1_SB_DQ<16>")
	)
	(segment
		(start 159.686498 -212.221572)
		(end 157.994858 -212.221572)
		(width 0.18288)
		(layer "In2.Cu")
		(net "M_F_CPU1_SB_DQ<16>")
	)
	(segment
		(start 148.368004 -219.748354)
		(end 148.368004 -220.02115)
		(width 0.18288)
		(layer "In2.Cu")
		(net "M_F_CPU1_SB_DQ<16>")
	)
	(segment
		(start 163.804346 -212.225382)
		(end 163.442904 -211.86394)
		(width 0.18288)
		(layer "In2.Cu")
		(net "M_F_CPU1_SB_DQ<16>")
	)
	(segment
		(start 144.076928 -224.312226)
		(end 141.814042 -224.312226)
		(width 0.18288)
		(layer "In2.Cu")
		(net "M_F_CPU1_SB_DQ<16>")
	)
	(segment
		(start 156.226002 -212.163152)
		(end 152.127458 -216.261696)
		(width 0.18288)
		(layer "In2.Cu")
		(net "M_F_CPU1_SB_DQ<16>")
	)
	(segment
		(start 149.175978 -218.563698)
		(end 149.364192 -218.752166)
		(width 0.18288)
		(layer "In2.Cu")
		(net "M_F_CPU1_SB_DQ<16>")
	)
	(segment
		(start 145.154142 -223.235012)
		(end 144.881346 -223.235012)
		(width 0.18288)
		(layer "In2.Cu")
		(net "M_F_CPU1_SB_DQ<16>")
	)
	(segment
		(start 169.517822 -212.958426)
		(end 168.864026 -212.958426)
		(width 0.18288)
		(layer "In2.Cu")
		(net "M_F_CPU1_SB_DQ<16>")
	)
	(segment
		(start 151.356568 -216.75979)
		(end 151.356568 -217.032586)
		(width 0.18288)
		(layer "In2.Cu")
		(net "M_F_CPU1_SB_DQ<16>")
	)
	(segment
		(start 149.862286 -218.254072)
		(end 149.674072 -218.065604)
		(width 0.18288)
		(layer "In2.Cu")
		(net "M_F_CPU1_SB_DQ<16>")
	)
	(segment
		(start 150.172166 -217.56751)
		(end 150.36038 -217.755978)
		(width 0.18288)
		(layer "In2.Cu")
		(net "M_F_CPU1_SB_DQ<16>")
	)
	(segment
		(start 146.187414 -221.279466)
		(end 146.187414 -221.552262)
		(width 0.18288)
		(layer "In2.Cu")
		(net "M_F_CPU1_SB_DQ<16>")
	)
	(segment
		(start 150.858474 -217.257884)
		(end 150.67026 -217.069416)
		(width 0.18288)
		(layer "In2.Cu")
		(net "M_F_CPU1_SB_DQ<16>")
	)
	(segment
		(start 161.536126 -212.225382)
		(end 161.068258 -211.757514)
		(width 0.18288)
		(layer "In2.Cu")
		(net "M_F_CPU1_SB_DQ<16>")
	)
	(segment
		(start 161.983674 -212.225382)
		(end 161.536126 -212.225382)
		(width 0.18288)
		(layer "In2.Cu")
		(net "M_F_CPU1_SB_DQ<16>")
	)
	(segment
		(start 151.168354 -216.298526)
		(end 151.168354 -216.571322)
		(width 0.18288)
		(layer "In2.Cu")
		(net "M_F_CPU1_SB_DQ<16>")
	)
	(segment
		(start 157.994858 -212.221572)
		(end 157.936438 -212.163152)
		(width 0.18288)
		(layer "In2.Cu")
		(net "M_F_CPU1_SB_DQ<16>")
	)
	(segment
		(start 144.383252 -223.733106)
		(end 144.383252 -224.005902)
		(width 0.18288)
		(layer "In2.Cu")
		(net "M_F_CPU1_SB_DQ<16>")
	)
	(segment
		(start 164.313616 -212.225382)
		(end 163.804346 -212.225382)
		(width 0.18288)
		(layer "In2.Cu")
		(net "M_F_CPU1_SB_DQ<16>")
	)
	(segment
		(start 147.183602 -220.556074)
		(end 147.371816 -220.744542)
		(width 0.18288)
		(layer "In2.Cu")
		(net "M_F_CPU1_SB_DQ<16>")
	)
	(segment
		(start 145.37944 -222.736918)
		(end 145.37944 -223.009714)
		(width 0.18288)
		(layer "In2.Cu")
		(net "M_F_CPU1_SB_DQ<16>")
	)
	(segment
		(start 146.375628 -221.74073)
		(end 146.375628 -222.013526)
		(width 0.18288)
		(layer "In2.Cu")
		(net "M_F_CPU1_SB_DQ<16>")
	)
	(segment
		(start 172.210476 -212.88121)
		(end 171.465748 -212.88121)
		(width 0.18288)
		(layer "In2.Cu")
		(net "M_F_CPU1_SB_DQ<16>")
	)
	(segment
		(start 147.86991 -220.246448)
		(end 147.681696 -220.05798)
		(width 0.18288)
		(layer "In2.Cu")
		(net "M_F_CPU1_SB_DQ<16>")
	)
	(segment
		(start 151.356568 -217.032586)
		(end 151.13127 -217.257884)
		(width 0.18288)
		(layer "In2.Cu")
		(net "M_F_CPU1_SB_DQ<16>")
	)
	(segment
		(start 140.836396 -224.832926)
		(end 140.288772 -224.832926)
		(width 0.088646)
		(layer "In2.Cu")
		(net "M_F_CPU1_SB_DQ<16>")
	)
	(segment
		(start 141.814042 -224.312226)
		(end 141.357096 -224.312226)
		(width 0.088646)
		(layer "In2.Cu")
		(net "M_F_CPU1_SB_DQ<16>")
	)
	(segment
		(start 137.672064 -224.8789)
		(end 137.64387 -224.862644)
		(width 0.088646)
		(layer "In2.Cu")
		(net "M_F_CPU1_SB_DQ<16>")
	)
	(segment
		(start 164.601906 -211.937092)
		(end 164.313616 -212.225382)
		(width 0.18288)
		(layer "In2.Cu")
		(net "M_F_CPU1_SB_DQ<16>")
	)
	(segment
		(start 146.15033 -222.238824)
		(end 145.877534 -222.238824)
		(width 0.18288)
		(layer "In2.Cu")
		(net "M_F_CPU1_SB_DQ<16>")
	)
	(segment
		(start 160.338008 -212.015578)
		(end 159.892492 -212.015578)
		(width 0.18288)
		(layer "In2.Cu")
		(net "M_F_CPU1_SB_DQ<16>")
	)
	(segment
		(start 168.864026 -212.958426)
		(end 168.69156 -212.78596)
		(width 0.18288)
		(layer "In2.Cu")
		(net "M_F_CPU1_SB_DQ<16>")
	)
	(segment
		(start 144.195038 -223.271842)
		(end 144.195038 -223.544638)
		(width 0.18288)
		(layer "In2.Cu")
		(net "M_F_CPU1_SB_DQ<16>")
	)
	(segment
		(start 149.175978 -218.290902)
		(end 149.175978 -218.563698)
		(width 0.18288)
		(layer "In2.Cu")
		(net "M_F_CPU1_SB_DQ<16>")
	)
	(segment
		(start 151.666448 -216.073228)
		(end 151.393652 -216.073228)
		(width 0.18288)
		(layer "In2.Cu")
		(net "M_F_CPU1_SB_DQ<16>")
	)
	(segment
		(start 165.47338 -212.186012)
		(end 165.22446 -211.937092)
		(width 0.18288)
		(layer "In2.Cu")
		(net "M_F_CPU1_SB_DQ<16>")
	)
	(segment
		(start 161.068258 -211.757514)
		(end 160.596072 -211.757514)
		(width 0.18288)
		(layer "In2.Cu")
		(net "M_F_CPU1_SB_DQ<16>")
	)
	(segment
		(start 147.681696 -220.05798)
		(end 147.4089 -220.05798)
		(width 0.18288)
		(layer "In2.Cu")
		(net "M_F_CPU1_SB_DQ<16>")
	)
	(segment
		(start 144.693132 -223.046544)
		(end 144.420336 -223.046544)
		(width 0.18288)
		(layer "In2.Cu")
		(net "M_F_CPU1_SB_DQ<16>")
	)
	(segment
		(start 168.69156 -212.78596)
		(end 168.304464 -212.78596)
		(width 0.18288)
		(layer "In2.Cu")
		(net "M_F_CPU1_SB_DQ<16>")
	)
	(segment
		(start 145.191226 -222.275654)
		(end 145.191226 -222.54845)
		(width 0.18288)
		(layer "In2.Cu")
		(net "M_F_CPU1_SB_DQ<16>")
	)
	(segment
		(start 148.17979 -219.28709)
		(end 148.17979 -219.559886)
		(width 0.18288)
		(layer "In2.Cu")
		(net "M_F_CPU1_SB_DQ<16>")
	)
	(segment
		(start 169.580306 -213.02091)
		(end 169.517822 -212.958426)
		(width 0.18288)
		(layer "In2.Cu")
		(net "M_F_CPU1_SB_DQ<16>")
	)
	(segment
		(start 149.364192 -218.752166)
		(end 149.364192 -219.024962)
		(width 0.18288)
		(layer "In2.Cu")
		(net "M_F_CPU1_SB_DQ<16>")
	)
	(segment
		(start 165.22446 -211.937092)
		(end 164.601906 -211.937092)
		(width 0.18288)
		(layer "In2.Cu")
		(net "M_F_CPU1_SB_DQ<16>")
	)
	(segment
		(start 150.397464 -217.069416)
		(end 150.172166 -217.294714)
		(width 0.18288)
		(layer "In2.Cu")
		(net "M_F_CPU1_SB_DQ<16>")
	)
	(segment
		(start 172.795946 -213.46668)
		(end 172.210476 -212.88121)
		(width 0.18288)
		(layer "In2.Cu")
		(net "M_F_CPU1_SB_DQ<16>")
	)
	(segment
		(start 146.375628 -222.013526)
		(end 146.15033 -222.238824)
		(width 0.18288)
		(layer "In2.Cu")
		(net "M_F_CPU1_SB_DQ<16>")
	)
	(segment
		(start 148.866098 -219.25026)
		(end 148.677884 -219.061792)
		(width 0.18288)
		(layer "In2.Cu")
		(net "M_F_CPU1_SB_DQ<16>")
	)
	(segment
		(start 167.133016 -212.186012)
		(end 165.47338 -212.186012)
		(width 0.18288)
		(layer "In2.Cu")
		(net "M_F_CPU1_SB_DQ<16>")
	)
	(segment
		(start 149.364192 -219.024962)
		(end 149.138894 -219.25026)
		(width 0.18288)
		(layer "In2.Cu")
		(net "M_F_CPU1_SB_DQ<16>")
	)
	(segment
		(start 150.36038 -217.755978)
		(end 150.36038 -218.028774)
		(width 0.18288)
		(layer "In2.Cu")
		(net "M_F_CPU1_SB_DQ<16>")
	)
	(segment
		(start 150.67026 -217.069416)
		(end 150.397464 -217.069416)
		(width 0.18288)
		(layer "In2.Cu")
		(net "M_F_CPU1_SB_DQ<16>")
	)
	(segment
		(start 168.084754 -212.56625)
		(end 168.084754 -212.125814)
		(width 0.18288)
		(layer "In2.Cu")
		(net "M_F_CPU1_SB_DQ<16>")
	)
	(segment
		(start 148.142706 -220.246448)
		(end 147.86991 -220.246448)
		(width 0.18288)
		(layer "In2.Cu")
		(net "M_F_CPU1_SB_DQ<16>")
	)
	(segment
		(start 145.68932 -222.050356)
		(end 145.416524 -222.050356)
		(width 0.18288)
		(layer "In2.Cu")
		(net "M_F_CPU1_SB_DQ<16>")
	)
	(segment
		(start 144.383252 -224.005902)
		(end 144.076928 -224.312226)
		(width 0.18288)
		(layer "In2.Cu")
		(net "M_F_CPU1_SB_DQ<16>")
	)
	(segment
		(start 146.685508 -221.054168)
		(end 146.412712 -221.054168)
		(width 0.18288)
		(layer "In2.Cu")
		(net "M_F_CPU1_SB_DQ<16>")
	)
	(segment
		(start 162.345116 -211.86394)
		(end 161.983674 -212.225382)
		(width 0.18288)
		(layer "In2.Cu")
		(net "M_F_CPU1_SB_DQ<16>")
	)
	(segment
		(start 145.877534 -222.238824)
		(end 145.68932 -222.050356)
		(width 0.18288)
		(layer "In2.Cu")
		(net "M_F_CPU1_SB_DQ<16>")
	)
	(segment
		(start 150.172166 -217.294714)
		(end 150.172166 -217.56751)
		(width 0.18288)
		(layer "In2.Cu")
		(net "M_F_CPU1_SB_DQ<16>")
	)
	(segment
		(start 163.442904 -211.86394)
		(end 162.345116 -211.86394)
		(width 0.18288)
		(layer "In2.Cu")
		(net "M_F_CPU1_SB_DQ<16>")
	)
	(segment
		(start 147.146518 -221.242636)
		(end 146.873722 -221.242636)
		(width 0.18288)
		(layer "In2.Cu")
		(net "M_F_CPU1_SB_DQ<16>")
	)
	(segment
		(start 141.357096 -224.312226)
		(end 140.836396 -224.832926)
		(width 0.088646)
		(layer "In2.Cu")
		(net "M_F_CPU1_SB_DQ<16>")
	)
	(segment
		(start 145.416524 -222.050356)
		(end 145.191226 -222.275654)
		(width 0.18288)
		(layer "In2.Cu")
		(net "M_F_CPU1_SB_DQ<16>")
	)
	(segment
		(start 149.138894 -219.25026)
		(end 148.866098 -219.25026)
		(width 0.18288)
		(layer "In2.Cu")
		(net "M_F_CPU1_SB_DQ<16>")
	)
	(segment
		(start 144.881346 -223.235012)
		(end 144.693132 -223.046544)
		(width 0.18288)
		(layer "In2.Cu")
		(net "M_F_CPU1_SB_DQ<16>")
	)
	(segment
		(start 157.936438 -212.163152)
		(end 156.226002 -212.163152)
		(width 0.18288)
		(layer "In2.Cu")
		(net "M_F_CPU1_SB_DQ<16>")
	)
	(segment
		(start 168.084754 -212.125814)
		(end 167.885872 -211.926932)
		(width 0.18288)
		(layer "In2.Cu")
		(net "M_F_CPU1_SB_DQ<16>")
	)
	(segment
		(start 148.368004 -220.02115)
		(end 148.142706 -220.246448)
		(width 0.18288)
		(layer "In2.Cu")
		(net "M_F_CPU1_SB_DQ<16>")
	)
	(segment
		(start 147.371816 -221.017338)
		(end 147.146518 -221.242636)
		(width 0.18288)
		(layer "In2.Cu")
		(net "M_F_CPU1_SB_DQ<16>")
	)
	(segment
		(start 144.195038 -223.544638)
		(end 144.383252 -223.733106)
		(width 0.18288)
		(layer "In2.Cu")
		(net "M_F_CPU1_SB_DQ<16>")
	)
	(segment
		(start 150.135082 -218.254072)
		(end 149.862286 -218.254072)
		(width 0.18288)
		(layer "In2.Cu")
		(net "M_F_CPU1_SB_DQ<16>")
	)
	(segment
		(start 146.412712 -221.054168)
		(end 146.187414 -221.279466)
		(width 0.18288)
		(layer "In2.Cu")
		(net "M_F_CPU1_SB_DQ<16>")
	)
	(segment
		(start 149.674072 -218.065604)
		(end 149.401276 -218.065604)
		(width 0.18288)
		(layer "In2.Cu")
		(net "M_F_CPU1_SB_DQ<16>")
	)
	(segment
		(start 144.420336 -223.046544)
		(end 144.195038 -223.271842)
		(width 0.18288)
		(layer "In2.Cu")
		(net "M_F_CPU1_SB_DQ<16>")
	)
	(segment
		(start 168.304464 -212.78596)
		(end 168.084754 -212.56625)
		(width 0.18288)
		(layer "In2.Cu")
		(net "M_F_CPU1_SB_DQ<16>")
	)
	(segment
		(start 148.677884 -219.061792)
		(end 148.405088 -219.061792)
		(width 0.18288)
		(layer "In2.Cu")
		(net "M_F_CPU1_SB_DQ<16>")
	)
	(segment
		(start 148.405088 -219.061792)
		(end 148.17979 -219.28709)
		(width 0.18288)
		(layer "In2.Cu")
		(net "M_F_CPU1_SB_DQ<16>")
	)
	(segment
		(start 147.371816 -220.744542)
		(end 147.371816 -221.017338)
		(width 0.18288)
		(layer "In2.Cu")
		(net "M_F_CPU1_SB_DQ<16>")
	)
	(segment
		(start 148.17979 -219.559886)
		(end 148.368004 -219.748354)
		(width 0.18288)
		(layer "In2.Cu")
		(net "M_F_CPU1_SB_DQ<16>")
	)
	(segment
		(start 167.392096 -211.926932)
		(end 167.133016 -212.186012)
		(width 0.18288)
		(layer "In2.Cu")
		(net "M_F_CPU1_SB_DQ<16>")
	)
	(segment
		(start 149.401276 -218.065604)
		(end 149.175978 -218.290902)
		(width 0.18288)
		(layer "In2.Cu")
		(net "M_F_CPU1_SB_DQ<16>")
	)
	(segment
		(start 152.127458 -216.261696)
		(end 151.854662 -216.261696)
		(width 0.18288)
		(layer "In2.Cu")
		(net "M_F_CPU1_SB_DQ<16>")
	)
	(segment
		(start 159.892492 -212.015578)
		(end 159.686498 -212.221572)
		(width 0.18288)
		(layer "In2.Cu")
		(net "M_F_CPU1_SB_DQ<16>")
	)
	(segment
		(start 145.191226 -222.54845)
		(end 145.37944 -222.736918)
		(width 0.18288)
		(layer "In2.Cu")
		(net "M_F_CPU1_SB_DQ<16>")
	)
	(segment
		(start 151.13127 -217.257884)
		(end 150.858474 -217.257884)
		(width 0.18288)
		(layer "In2.Cu")
		(net "M_F_CPU1_SB_DQ<16>")
	)
	(segment
		(start 151.854662 -216.261696)
		(end 151.666448 -216.073228)
		(width 0.18288)
		(layer "In2.Cu")
		(net "M_F_CPU1_SB_DQ<16>")
	)
	(segment
		(start 150.36038 -218.028774)
		(end 150.135082 -218.254072)
		(width 0.18288)
		(layer "In2.Cu")
		(net "M_F_CPU1_SB_DQ<16>")
	)
	(segment
		(start 151.393652 -216.073228)
		(end 151.168354 -216.298526)
		(width 0.18288)
		(layer "In2.Cu")
		(net "M_F_CPU1_SB_DQ<16>")
	)
	(segment
		(start 145.37944 -223.009714)
		(end 145.154142 -223.235012)
		(width 0.18288)
		(layer "In2.Cu")
		(net "M_F_CPU1_SB_DQ<16>")
	)
	(segment
		(start 167.885872 -211.926932)
		(end 167.392096 -211.926932)
		(width 0.18288)
		(layer "In2.Cu")
		(net "M_F_CPU1_SB_DQ<16>")
	)
	(segment
		(start 160.596072 -211.757514)
		(end 160.338008 -212.015578)
		(width 0.18288)
		(layer "In2.Cu")
		(net "M_F_CPU1_SB_DQ<16>")
	)
	(segment
		(start 146.873722 -221.242636)
		(end 146.685508 -221.054168)
		(width 0.18288)
		(layer "In2.Cu")
		(net "M_F_CPU1_SB_DQ<16>")
	)
	(segment
		(start 171.326048 -213.02091)
		(end 169.580306 -213.02091)
		(width 0.18288)
		(layer "In2.Cu")
		(net "M_F_CPU1_SB_DQ<16>")
	)
	(arc
		(start 138.237468 -224.8789)
		(mid 137.954766 -224.954642)
		(end 137.672064 -224.8789)
		(width 0.088646)
		(layer "In2.Cu")
		(net "M_F_CPU1_SB_DQ<16>")
	)
	(arc
		(start 138.611864 -224.8789)
		(mid 138.424666 -224.828757)
		(end 138.237468 -224.8789)
		(width 0.088646)
		(layer "In2.Cu")
		(net "M_F_CPU1_SB_DQ<16>")
	)
	(arc
		(start 140.288772 -224.832926)
		(mid 140.1999 -224.844625)
		(end 140.117068 -224.8789)
		(width 0.088646)
		(layer "In2.Cu")
		(net "M_F_CPU1_SB_DQ<16>")
	)
	(arc
		(start 140.117068 -224.8789)
		(mid 139.834366 -224.954676)
		(end 139.551664 -224.8789)
		(width 0.088646)
		(layer "In2.Cu")
		(net "M_F_CPU1_SB_DQ<16>")
	)
	(arc
		(start 139.177268 -224.8789)
		(mid 138.894566 -224.954676)
		(end 138.611864 -224.8789)
		(width 0.088646)
		(layer "In2.Cu")
		(net "M_F_CPU1_SB_DQ<16>")
	)
	(arc
		(start 139.551664 -224.8789)
		(mid 139.364466 -224.828723)
		(end 139.177268 -224.8789)
		(width 0.088646)
		(layer "In2.Cu")
		(net "M_F_CPU1_SB_DQ<16>")
	)
	(segment
		(start 134.665466 -228.99497)
		(end 134.665212 -228.994716)
		(width 0.20066)
		(layer "F.Cu")
		(net "M_F_CPU1_SB_DQ<15>")
	)
	(segment
		(start 182.442866 -214.741506)
		(end 182.455058 -214.753698)
		(width 0.1016)
		(layer "F.Cu")
		(net "M_F_CPU1_SB_DQ<15>")
	)
	(segment
		(start 134.665212 -228.994716)
		(end 134.665212 -228.45903)
		(width 0.20066)
		(layer "F.Cu")
		(net "M_F_CPU1_SB_DQ<15>")
	)
	(segment
		(start 180.427884 -214.748618)
		(end 180.434996 -214.741506)
		(width 0.1016)
		(layer "F.Cu")
		(net "M_F_CPU1_SB_DQ<15>")
	)
	(segment
		(start 183.340248 -214.549736)
		(end 183.340248 -214.298784)
		(width 0.20066)
		(layer "F.Cu")
		(net "M_F_CPU1_SB_DQ<15>")
	)
	(segment
		(start 183.574436 -214.064596)
		(end 183.958484 -214.064596)
		(width 0.20066)
		(layer "F.Cu")
		(net "M_F_CPU1_SB_DQ<15>")
	)
	(segment
		(start 176.896014 -214.316564)
		(end 178.000914 -214.316564)
		(width 0.20066)
		(layer "F.Cu")
		(net "M_F_CPU1_SB_DQ<15>")
	)
	(segment
		(start 183.340248 -214.298784)
		(end 183.574436 -214.064596)
		(width 0.20066)
		(layer "F.Cu")
		(net "M_F_CPU1_SB_DQ<15>")
	)
	(segment
		(start 180.423058 -214.748618)
		(end 180.427884 -214.748618)
		(width 0.101854)
		(layer "F.Cu")
		(net "M_F_CPU1_SB_DQ<15>")
	)
	(segment
		(start 184.210452 -214.316564)
		(end 185.544714 -214.316564)
		(width 0.20066)
		(layer "F.Cu")
		(net "M_F_CPU1_SB_DQ<15>")
	)
	(segment
		(start 183.958484 -214.064596)
		(end 184.210452 -214.316564)
		(width 0.20066)
		(layer "F.Cu")
		(net "M_F_CPU1_SB_DQ<15>")
	)
	(segment
		(start 180.434996 -214.741506)
		(end 182.442866 -214.741506)
		(width 0.1016)
		(layer "F.Cu")
		(net "M_F_CPU1_SB_DQ<15>")
	)
	(segment
		(start 183.136286 -214.753698)
		(end 183.340248 -214.549736)
		(width 0.20066)
		(layer "F.Cu")
		(net "M_F_CPU1_SB_DQ<15>")
	)
	(segment
		(start 180.131212 -214.748618)
		(end 180.423058 -214.748618)
		(width 0.20066)
		(layer "F.Cu")
		(net "M_F_CPU1_SB_DQ<15>")
	)
	(segment
		(start 178.000914 -214.316564)
		(end 179.699158 -214.316564)
		(width 0.20066)
		(layer "F.Cu")
		(net "M_F_CPU1_SB_DQ<15>")
	)
	(segment
		(start 179.699158 -214.316564)
		(end 180.131212 -214.748618)
		(width 0.20066)
		(layer "F.Cu")
		(net "M_F_CPU1_SB_DQ<15>")
	)
	(segment
		(start 182.455058 -214.753698)
		(end 183.136286 -214.753698)
		(width 0.20066)
		(layer "F.Cu")
		(net "M_F_CPU1_SB_DQ<15>")
	)
	(segment
		(start 173.380654 -214.159846)
		(end 173.380654 -214.580724)
		(width 0.18288)
		(layer "In2.Cu")
		(net "M_F_CPU1_SB_DQ<15>")
	)
	(segment
		(start 141.443964 -225.129598)
		(end 141.121892 -225.45167)
		(width 0.088646)
		(layer "In2.Cu")
		(net "M_F_CPU1_SB_DQ<15>")
	)
	(segment
		(start 141.814042 -225.129598)
		(end 141.443964 -225.129598)
		(width 0.088646)
		(layer "In2.Cu")
		(net "M_F_CPU1_SB_DQ<15>")
	)
	(segment
		(start 165.510464 -213.073996)
		(end 165.435534 -213.148926)
		(width 0.18288)
		(layer "In2.Cu")
		(net "M_F_CPU1_SB_DQ<15>")
	)
	(segment
		(start 173.220634 -214.740744)
		(end 172.55109 -214.740744)
		(width 0.18288)
		(layer "In2.Cu")
		(net "M_F_CPU1_SB_DQ<15>")
	)
	(segment
		(start 168.706546 -213.923626)
		(end 167.35425 -213.303866)
		(width 0.18288)
		(layer "In2.Cu")
		(net "M_F_CPU1_SB_DQ<15>")
	)
	(segment
		(start 165.435534 -213.148926)
		(end 164.862764 -213.148926)
		(width 0.18288)
		(layer "In2.Cu")
		(net "M_F_CPU1_SB_DQ<15>")
	)
	(segment
		(start 175.580548 -214.753444)
		(end 174.34052 -214.753444)
		(width 0.18288)
		(layer "In2.Cu")
		(net "M_F_CPU1_SB_DQ<15>")
	)
	(segment
		(start 135.510016 -227.635054)
		(end 135.510016 -227.64496)
		(width 0.088646)
		(layer "In2.Cu")
		(net "M_F_CPU1_SB_DQ<15>")
	)
	(segment
		(start 174.097442 -214.198962)
		(end 173.898306 -213.999826)
		(width 0.18288)
		(layer "In2.Cu")
		(net "M_F_CPU1_SB_DQ<15>")
	)
	(segment
		(start 135.331454 -227.964238)
		(end 135.322564 -227.969318)
		(width 0.088646)
		(layer "In2.Cu")
		(net "M_F_CPU1_SB_DQ<15>")
	)
	(segment
		(start 173.898306 -213.999826)
		(end 173.540674 -213.999826)
		(width 0.18288)
		(layer "In2.Cu")
		(net "M_F_CPU1_SB_DQ<15>")
	)
	(segment
		(start 173.380654 -214.580724)
		(end 173.220634 -214.740744)
		(width 0.18288)
		(layer "In2.Cu")
		(net "M_F_CPU1_SB_DQ<15>")
	)
	(segment
		(start 164.748718 -213.03488)
		(end 161.428938 -213.03488)
		(width 0.18288)
		(layer "In2.Cu")
		(net "M_F_CPU1_SB_DQ<15>")
	)
	(segment
		(start 173.540674 -213.999826)
		(end 173.380654 -214.159846)
		(width 0.18288)
		(layer "In2.Cu")
		(net "M_F_CPU1_SB_DQ<15>")
	)
	(segment
		(start 139.269216 -225.998786)
		(end 139.269216 -226.017328)
		(width 0.088646)
		(layer "In2.Cu")
		(net "M_F_CPU1_SB_DQ<15>")
	)
	(segment
		(start 167.12438 -213.073996)
		(end 165.510464 -213.073996)
		(width 0.18288)
		(layer "In2.Cu")
		(net "M_F_CPU1_SB_DQ<15>")
	)
	(segment
		(start 172.22978 -214.15248)
		(end 172.000926 -213.923626)
		(width 0.18288)
		(layer "In2.Cu")
		(net "M_F_CPU1_SB_DQ<15>")
	)
	(segment
		(start 156.538422 -213.087458)
		(end 144.496282 -225.129598)
		(width 0.18288)
		(layer "In2.Cu")
		(net "M_F_CPU1_SB_DQ<15>")
	)
	(segment
		(start 172.55109 -214.740744)
		(end 172.22978 -214.419434)
		(width 0.18288)
		(layer "In2.Cu")
		(net "M_F_CPU1_SB_DQ<15>")
	)
	(segment
		(start 164.862764 -213.148926)
		(end 164.748718 -213.03488)
		(width 0.18288)
		(layer "In2.Cu")
		(net "M_F_CPU1_SB_DQ<15>")
	)
	(segment
		(start 161.428938 -213.03488)
		(end 161.37636 -213.087458)
		(width 0.18288)
		(layer "In2.Cu")
		(net "M_F_CPU1_SB_DQ<15>")
	)
	(segment
		(start 174.34052 -214.753444)
		(end 174.097442 -214.510366)
		(width 0.18288)
		(layer "In2.Cu")
		(net "M_F_CPU1_SB_DQ<15>")
	)
	(segment
		(start 144.496282 -225.129598)
		(end 141.814042 -225.129598)
		(width 0.18288)
		(layer "In2.Cu")
		(net "M_F_CPU1_SB_DQ<15>")
	)
	(segment
		(start 167.35425 -213.303866)
		(end 167.12438 -213.073996)
		(width 0.18288)
		(layer "In2.Cu")
		(net "M_F_CPU1_SB_DQ<15>")
	)
	(segment
		(start 139.090654 -226.336606)
		(end 139.081764 -226.341686)
		(width 0.088646)
		(layer "In2.Cu")
		(net "M_F_CPU1_SB_DQ<15>")
	)
	(segment
		(start 176.896014 -214.316564)
		(end 175.580548 -214.753444)
		(width 0.18288)
		(layer "In2.Cu")
		(net "M_F_CPU1_SB_DQ<15>")
	)
	(segment
		(start 172.22978 -214.419434)
		(end 172.22978 -214.15248)
		(width 0.18288)
		(layer "In2.Cu")
		(net "M_F_CPU1_SB_DQ<15>")
	)
	(segment
		(start 134.933436 -228.45903)
		(end 134.665212 -228.45903)
		(width 0.088646)
		(layer "In2.Cu")
		(net "M_F_CPU1_SB_DQ<15>")
	)
	(segment
		(start 174.097442 -214.510366)
		(end 174.097442 -214.198962)
		(width 0.18288)
		(layer "In2.Cu")
		(net "M_F_CPU1_SB_DQ<15>")
	)
	(segment
		(start 161.37636 -213.087458)
		(end 156.538422 -213.087458)
		(width 0.18288)
		(layer "In2.Cu")
		(net "M_F_CPU1_SB_DQ<15>")
	)
	(segment
		(start 141.121892 -225.45167)
		(end 140.77442 -225.45167)
		(width 0.088646)
		(layer "In2.Cu")
		(net "M_F_CPU1_SB_DQ<15>")
	)
	(segment
		(start 138.620754 -227.150422)
		(end 138.611864 -227.155502)
		(width 0.088646)
		(layer "In2.Cu")
		(net "M_F_CPU1_SB_DQ<15>")
	)
	(segment
		(start 172.000926 -213.923626)
		(end 168.706546 -213.923626)
		(width 0.18288)
		(layer "In2.Cu")
		(net "M_F_CPU1_SB_DQ<15>")
	)
	(segment
		(start 138.799316 -226.821238)
		(end 138.799316 -226.831144)
		(width 0.088646)
		(layer "In2.Cu")
		(net "M_F_CPU1_SB_DQ<15>")
	)
	(arc
		(start 135.510016 -227.64496)
		(mid 135.462337 -227.82786)
		(end 135.331454 -227.964238)
		(width 0.088646)
		(layer "In2.Cu")
		(net "M_F_CPU1_SB_DQ<15>")
	)
	(arc
		(start 138.799316 -226.831144)
		(mid 138.751637 -227.014044)
		(end 138.620754 -227.150422)
		(width 0.088646)
		(layer "In2.Cu")
		(net "M_F_CPU1_SB_DQ<15>")
	)
	(arc
		(start 139.269216 -226.017328)
		(mid 139.221537 -226.200228)
		(end 139.090654 -226.336606)
		(width 0.088646)
		(layer "In2.Cu")
		(net "M_F_CPU1_SB_DQ<15>")
	)
	(arc
		(start 137.297668 -227.155502)
		(mid 137.014966 -227.079726)
		(end 136.732264 -227.155502)
		(width 0.088646)
		(layer "In2.Cu")
		(net "M_F_CPU1_SB_DQ<15>")
	)
	(arc
		(start 135.792464 -227.155502)
		(mid 135.588129 -227.358107)
		(end 135.510016 -227.635054)
		(width 0.088646)
		(layer "In2.Cu")
		(net "M_F_CPU1_SB_DQ<15>")
	)
	(arc
		(start 135.04799 -228.36251)
		(mid 135.008309 -228.431632)
		(end 134.933436 -228.45903)
		(width 0.088646)
		(layer "In2.Cu")
		(net "M_F_CPU1_SB_DQ<15>")
	)
	(arc
		(start 138.611864 -227.155502)
		(mid 138.424666 -227.205645)
		(end 138.237468 -227.155502)
		(width 0.088646)
		(layer "In2.Cu")
		(net "M_F_CPU1_SB_DQ<15>")
	)
	(arc
		(start 138.237468 -227.155502)
		(mid 137.954766 -227.079726)
		(end 137.672064 -227.155502)
		(width 0.088646)
		(layer "In2.Cu")
		(net "M_F_CPU1_SB_DQ<15>")
	)
	(arc
		(start 136.732264 -227.155502)
		(mid 136.545066 -227.205645)
		(end 136.357868 -227.155502)
		(width 0.088646)
		(layer "In2.Cu")
		(net "M_F_CPU1_SB_DQ<15>")
	)
	(arc
		(start 139.551664 -225.527616)
		(mid 139.349378 -225.726597)
		(end 139.269216 -225.998786)
		(width 0.088646)
		(layer "In2.Cu")
		(net "M_F_CPU1_SB_DQ<15>")
	)
	(arc
		(start 140.117068 -225.527616)
		(mid 139.834366 -225.451874)
		(end 139.551664 -225.527616)
		(width 0.088646)
		(layer "In2.Cu")
		(net "M_F_CPU1_SB_DQ<15>")
	)
	(arc
		(start 135.322564 -227.969318)
		(mid 135.14159 -228.13539)
		(end 135.04799 -228.36251)
		(width 0.088646)
		(layer "In2.Cu")
		(net "M_F_CPU1_SB_DQ<15>")
	)
	(arc
		(start 140.491464 -225.527616)
		(mid 140.304266 -225.577759)
		(end 140.117068 -225.527616)
		(width 0.088646)
		(layer "In2.Cu")
		(net "M_F_CPU1_SB_DQ<15>")
	)
	(arc
		(start 136.357868 -227.155502)
		(mid 136.075166 -227.079726)
		(end 135.792464 -227.155502)
		(width 0.088646)
		(layer "In2.Cu")
		(net "M_F_CPU1_SB_DQ<15>")
	)
	(arc
		(start 140.77442 -225.45167)
		(mid 140.62795 -225.47103)
		(end 140.491464 -225.527616)
		(width 0.088646)
		(layer "In2.Cu")
		(net "M_F_CPU1_SB_DQ<15>")
	)
	(arc
		(start 139.081764 -226.341686)
		(mid 138.877429 -226.544291)
		(end 138.799316 -226.821238)
		(width 0.088646)
		(layer "In2.Cu")
		(net "M_F_CPU1_SB_DQ<15>")
	)
	(arc
		(start 137.672064 -227.155502)
		(mid 137.484866 -227.205645)
		(end 137.297668 -227.155502)
		(width 0.088646)
		(layer "In2.Cu")
		(net "M_F_CPU1_SB_DQ<15>")
	)
	(segment
		(start 183.958484 -215.764618)
		(end 184.210452 -216.016586)
		(width 0.20066)
		(layer "F.Cu")
		(net "M_F_CPU1_SB_DQ<14>")
	)
	(segment
		(start 180.423058 -216.44864)
		(end 180.427884 -216.44864)
		(width 0.101854)
		(layer "F.Cu")
		(net "M_F_CPU1_SB_DQ<14>")
	)
	(segment
		(start 180.131212 -216.44864)
		(end 180.423058 -216.44864)
		(width 0.20066)
		(layer "F.Cu")
		(net "M_F_CPU1_SB_DQ<14>")
	)
	(segment
		(start 179.699158 -216.016586)
		(end 180.131212 -216.44864)
		(width 0.20066)
		(layer "F.Cu")
		(net "M_F_CPU1_SB_DQ<14>")
	)
	(segment
		(start 183.340248 -216.249758)
		(end 183.340248 -215.998806)
		(width 0.20066)
		(layer "F.Cu")
		(net "M_F_CPU1_SB_DQ<14>")
	)
	(segment
		(start 182.442866 -216.441528)
		(end 182.455058 -216.45372)
		(width 0.1016)
		(layer "F.Cu")
		(net "M_F_CPU1_SB_DQ<14>")
	)
	(segment
		(start 135.135366 -229.808532)
		(end 135.135366 -229.272846)
		(width 0.20066)
		(layer "F.Cu")
		(net "M_F_CPU1_SB_DQ<14>")
	)
	(segment
		(start 183.574436 -215.764618)
		(end 183.958484 -215.764618)
		(width 0.20066)
		(layer "F.Cu")
		(net "M_F_CPU1_SB_DQ<14>")
	)
	(segment
		(start 135.135112 -229.808786)
		(end 135.135366 -229.808532)
		(width 0.20066)
		(layer "F.Cu")
		(net "M_F_CPU1_SB_DQ<14>")
	)
	(segment
		(start 176.896014 -216.016586)
		(end 178.000914 -216.016586)
		(width 0.20066)
		(layer "F.Cu")
		(net "M_F_CPU1_SB_DQ<14>")
	)
	(segment
		(start 178.000914 -216.016586)
		(end 179.699158 -216.016586)
		(width 0.20066)
		(layer "F.Cu")
		(net "M_F_CPU1_SB_DQ<14>")
	)
	(segment
		(start 184.210452 -216.016586)
		(end 185.544714 -216.016586)
		(width 0.20066)
		(layer "F.Cu")
		(net "M_F_CPU1_SB_DQ<14>")
	)
	(segment
		(start 180.427884 -216.44864)
		(end 180.434996 -216.441528)
		(width 0.1016)
		(layer "F.Cu")
		(net "M_F_CPU1_SB_DQ<14>")
	)
	(segment
		(start 182.455058 -216.45372)
		(end 183.136286 -216.45372)
		(width 0.20066)
		(layer "F.Cu")
		(net "M_F_CPU1_SB_DQ<14>")
	)
	(segment
		(start 183.340248 -215.998806)
		(end 183.574436 -215.764618)
		(width 0.20066)
		(layer "F.Cu")
		(net "M_F_CPU1_SB_DQ<14>")
	)
	(segment
		(start 183.136286 -216.45372)
		(end 183.340248 -216.249758)
		(width 0.20066)
		(layer "F.Cu")
		(net "M_F_CPU1_SB_DQ<14>")
	)
	(segment
		(start 180.434996 -216.441528)
		(end 182.442866 -216.441528)
		(width 0.1016)
		(layer "F.Cu")
		(net "M_F_CPU1_SB_DQ<14>")
	)
	(segment
		(start 159.94888 -214.973662)
		(end 159.397192 -214.421974)
		(width 0.18288)
		(layer "In2.Cu")
		(net "M_F_CPU1_SB_DQ<14>")
	)
	(segment
		(start 167.15105 -215.594692)
		(end 165.582092 -215.594692)
		(width 0.18288)
		(layer "In2.Cu")
		(net "M_F_CPU1_SB_DQ<14>")
	)
	(segment
		(start 169.590466 -215.57107)
		(end 169.464482 -215.697054)
		(width 0.18288)
		(layer "In2.Cu")
		(net "M_F_CPU1_SB_DQ<14>")
	)
	(segment
		(start 140.472414 -226.19462)
		(end 139.794742 -226.872292)
		(width 0.18288)
		(layer "In2.Cu")
		(net "M_F_CPU1_SB_DQ<14>")
	)
	(segment
		(start 159.397192 -214.421974)
		(end 158.799276 -214.421974)
		(width 0.18288)
		(layer "In2.Cu")
		(net "M_F_CPU1_SB_DQ<14>")
	)
	(segment
		(start 160.89757 -215.179402)
		(end 160.69183 -214.973662)
		(width 0.18288)
		(layer "In2.Cu")
		(net "M_F_CPU1_SB_DQ<14>")
	)
	(segment
		(start 173.50486 -215.791796)
		(end 173.303946 -215.590882)
		(width 0.18288)
		(layer "In2.Cu")
		(net "M_F_CPU1_SB_DQ<14>")
	)
	(segment
		(start 145.206212 -226.19462)
		(end 140.472414 -226.19462)
		(width 0.18288)
		(layer "In2.Cu")
		(net "M_F_CPU1_SB_DQ<14>")
	)
	(segment
		(start 165.582092 -215.594692)
		(end 164.64915 -214.66175)
		(width 0.18288)
		(layer "In2.Cu")
		(net "M_F_CPU1_SB_DQ<14>")
	)
	(segment
		(start 164.64915 -214.66175)
		(end 163.903406 -214.66175)
		(width 0.18288)
		(layer "In2.Cu")
		(net "M_F_CPU1_SB_DQ<14>")
	)
	(segment
		(start 174.066962 -216.338404)
		(end 173.718982 -216.338404)
		(width 0.18288)
		(layer "In2.Cu")
		(net "M_F_CPU1_SB_DQ<14>")
	)
	(segment
		(start 171.394374 -215.676226)
		(end 171.289218 -215.57107)
		(width 0.18288)
		(layer "In2.Cu")
		(net "M_F_CPU1_SB_DQ<14>")
	)
	(segment
		(start 158.799276 -214.421974)
		(end 158.4706 -214.75065)
		(width 0.18288)
		(layer "In2.Cu")
		(net "M_F_CPU1_SB_DQ<14>")
	)
	(segment
		(start 163.903406 -214.66175)
		(end 163.77539 -214.789766)
		(width 0.18288)
		(layer "In2.Cu")
		(net "M_F_CPU1_SB_DQ<14>")
	)
	(segment
		(start 139.326366 -227.743512)
		(end 139.257278 -227.8126)
		(width 0.088646)
		(layer "In2.Cu")
		(net "M_F_CPU1_SB_DQ<14>")
	)
	(segment
		(start 139.326366 -227.340668)
		(end 139.326366 -227.743512)
		(width 0.088646)
		(layer "In2.Cu")
		(net "M_F_CPU1_SB_DQ<14>")
	)
	(segment
		(start 169.191432 -215.697054)
		(end 168.874694 -215.380316)
		(width 0.18288)
		(layer "In2.Cu")
		(net "M_F_CPU1_SB_DQ<14>")
	)
	(segment
		(start 158.4706 -214.75065)
		(end 157.09519 -214.75065)
		(width 0.18288)
		(layer "In2.Cu")
		(net "M_F_CPU1_SB_DQ<14>")
	)
	(segment
		(start 160.69183 -214.973662)
		(end 159.94888 -214.973662)
		(width 0.18288)
		(layer "In2.Cu")
		(net "M_F_CPU1_SB_DQ<14>")
	)
	(segment
		(start 151.284432 -219.77858)
		(end 151.284432 -220.1164)
		(width 0.18288)
		(layer "In2.Cu")
		(net "M_F_CPU1_SB_DQ<14>")
	)
	(segment
		(start 176.132998 -216.34069)
		(end 175.366934 -215.574626)
		(width 0.18288)
		(layer "In2.Cu")
		(net "M_F_CPU1_SB_DQ<14>")
	)
	(segment
		(start 139.256516 -227.8126)
		(end 139.15263 -227.916486)
		(width 0.088646)
		(layer "In2.Cu")
		(net "M_F_CPU1_SB_DQ<14>")
	)
	(segment
		(start 173.303946 -215.590882)
		(end 172.54347 -215.590882)
		(width 0.18288)
		(layer "In2.Cu")
		(net "M_F_CPU1_SB_DQ<14>")
	)
	(segment
		(start 139.257278 -227.8126)
		(end 139.256516 -227.8126)
		(width 0.088646)
		(layer "In2.Cu")
		(net "M_F_CPU1_SB_DQ<14>")
	)
	(segment
		(start 176.57191 -216.34069)
		(end 176.132998 -216.34069)
		(width 0.18288)
		(layer "In2.Cu")
		(net "M_F_CPU1_SB_DQ<14>")
	)
	(segment
		(start 172.54347 -215.590882)
		(end 172.458126 -215.676226)
		(width 0.18288)
		(layer "In2.Cu")
		(net "M_F_CPU1_SB_DQ<14>")
	)
	(segment
		(start 168.874694 -215.380316)
		(end 167.365426 -215.380316)
		(width 0.18288)
		(layer "In2.Cu")
		(net "M_F_CPU1_SB_DQ<14>")
	)
	(segment
		(start 135.674862 -228.827076)
		(end 135.135366 -229.272846)
		(width 0.088646)
		(layer "In2.Cu")
		(net "M_F_CPU1_SB_DQ<14>")
	)
	(segment
		(start 157.09519 -214.75065)
		(end 156.553916 -215.291924)
		(width 0.18288)
		(layer "In2.Cu")
		(net "M_F_CPU1_SB_DQ<14>")
	)
	(segment
		(start 162.085782 -214.789766)
		(end 161.959798 -214.663782)
		(width 0.18288)
		(layer "In2.Cu")
		(net "M_F_CPU1_SB_DQ<14>")
	)
	(segment
		(start 174.226982 -216.178384)
		(end 174.066962 -216.338404)
		(width 0.18288)
		(layer "In2.Cu")
		(net "M_F_CPU1_SB_DQ<14>")
	)
	(segment
		(start 155.771088 -215.291924)
		(end 151.284432 -219.77858)
		(width 0.18288)
		(layer "In2.Cu")
		(net "M_F_CPU1_SB_DQ<14>")
	)
	(segment
		(start 161.686494 -214.663782)
		(end 161.170874 -215.179402)
		(width 0.18288)
		(layer "In2.Cu")
		(net "M_F_CPU1_SB_DQ<14>")
	)
	(segment
		(start 171.289218 -215.57107)
		(end 169.590466 -215.57107)
		(width 0.18288)
		(layer "In2.Cu")
		(net "M_F_CPU1_SB_DQ<14>")
	)
	(segment
		(start 175.366934 -215.574626)
		(end 174.403258 -215.574626)
		(width 0.18288)
		(layer "In2.Cu")
		(net "M_F_CPU1_SB_DQ<14>")
	)
	(segment
		(start 172.458126 -215.676226)
		(end 171.394374 -215.676226)
		(width 0.18288)
		(layer "In2.Cu")
		(net "M_F_CPU1_SB_DQ<14>")
	)
	(segment
		(start 176.896014 -216.016586)
		(end 176.57191 -216.34069)
		(width 0.18288)
		(layer "In2.Cu")
		(net "M_F_CPU1_SB_DQ<14>")
	)
	(segment
		(start 169.464482 -215.697054)
		(end 169.191432 -215.697054)
		(width 0.18288)
		(layer "In2.Cu")
		(net "M_F_CPU1_SB_DQ<14>")
	)
	(segment
		(start 173.50486 -216.124282)
		(end 173.50486 -215.791796)
		(width 0.18288)
		(layer "In2.Cu")
		(net "M_F_CPU1_SB_DQ<14>")
	)
	(segment
		(start 174.226982 -215.750902)
		(end 174.226982 -216.178384)
		(width 0.18288)
		(layer "In2.Cu")
		(net "M_F_CPU1_SB_DQ<14>")
	)
	(segment
		(start 163.77539 -214.789766)
		(end 162.085782 -214.789766)
		(width 0.18288)
		(layer "In2.Cu")
		(net "M_F_CPU1_SB_DQ<14>")
	)
	(segment
		(start 151.284432 -220.1164)
		(end 145.206212 -226.19462)
		(width 0.18288)
		(layer "In2.Cu")
		(net "M_F_CPU1_SB_DQ<14>")
	)
	(segment
		(start 161.170874 -215.179402)
		(end 160.89757 -215.179402)
		(width 0.18288)
		(layer "In2.Cu")
		(net "M_F_CPU1_SB_DQ<14>")
	)
	(segment
		(start 139.794742 -226.872292)
		(end 139.326366 -227.340668)
		(width 0.088646)
		(layer "In2.Cu")
		(net "M_F_CPU1_SB_DQ<14>")
	)
	(segment
		(start 167.365426 -215.380316)
		(end 167.15105 -215.594692)
		(width 0.18288)
		(layer "In2.Cu")
		(net "M_F_CPU1_SB_DQ<14>")
	)
	(segment
		(start 135.979916 -228.440488)
		(end 135.979916 -228.45903)
		(width 0.088646)
		(layer "In2.Cu")
		(net "M_F_CPU1_SB_DQ<14>")
	)
	(segment
		(start 156.553916 -215.291924)
		(end 155.771088 -215.291924)
		(width 0.18288)
		(layer "In2.Cu")
		(net "M_F_CPU1_SB_DQ<14>")
	)
	(segment
		(start 174.403258 -215.574626)
		(end 174.226982 -215.750902)
		(width 0.18288)
		(layer "In2.Cu")
		(net "M_F_CPU1_SB_DQ<14>")
	)
	(segment
		(start 161.959798 -214.663782)
		(end 161.686494 -214.663782)
		(width 0.18288)
		(layer "In2.Cu")
		(net "M_F_CPU1_SB_DQ<14>")
	)
	(segment
		(start 173.718982 -216.338404)
		(end 173.50486 -216.124282)
		(width 0.18288)
		(layer "In2.Cu")
		(net "M_F_CPU1_SB_DQ<14>")
	)
	(segment
		(start 135.801354 -228.778308)
		(end 135.792464 -228.783388)
		(width 0.088646)
		(layer "In2.Cu")
		(net "M_F_CPU1_SB_DQ<14>")
	)
	(arc
		(start 139.15263 -227.916486)
		(mid 139.118764 -227.945005)
		(end 139.081764 -227.969318)
		(width 0.088646)
		(layer "In2.Cu")
		(net "M_F_CPU1_SB_DQ<14>")
	)
	(arc
		(start 138.707368 -227.969318)
		(mid 138.424666 -227.893576)
		(end 138.141964 -227.969318)
		(width 0.088646)
		(layer "In2.Cu")
		(net "M_F_CPU1_SB_DQ<14>")
	)
	(arc
		(start 138.141964 -227.969318)
		(mid 137.954766 -228.019461)
		(end 137.767568 -227.969318)
		(width 0.088646)
		(layer "In2.Cu")
		(net "M_F_CPU1_SB_DQ<14>")
	)
	(arc
		(start 136.827768 -227.969318)
		(mid 136.545066 -227.893576)
		(end 136.262364 -227.969318)
		(width 0.088646)
		(layer "In2.Cu")
		(net "M_F_CPU1_SB_DQ<14>")
	)
	(arc
		(start 137.767568 -227.969318)
		(mid 137.484866 -227.893576)
		(end 137.202164 -227.969318)
		(width 0.088646)
		(layer "In2.Cu")
		(net "M_F_CPU1_SB_DQ<14>")
	)
	(arc
		(start 137.202164 -227.969318)
		(mid 137.014966 -228.019461)
		(end 136.827768 -227.969318)
		(width 0.088646)
		(layer "In2.Cu")
		(net "M_F_CPU1_SB_DQ<14>")
	)
	(arc
		(start 135.792464 -228.783388)
		(mid 135.735507 -228.810196)
		(end 135.674862 -228.827076)
		(width 0.088646)
		(layer "In2.Cu")
		(net "M_F_CPU1_SB_DQ<14>")
	)
	(arc
		(start 139.081764 -227.969318)
		(mid 138.894566 -228.019461)
		(end 138.707368 -227.969318)
		(width 0.088646)
		(layer "In2.Cu")
		(net "M_F_CPU1_SB_DQ<14>")
	)
	(arc
		(start 136.262364 -227.969318)
		(mid 136.060078 -228.168299)
		(end 135.979916 -228.440488)
		(width 0.088646)
		(layer "In2.Cu")
		(net "M_F_CPU1_SB_DQ<14>")
	)
	(arc
		(start 135.979916 -228.45903)
		(mid 135.932237 -228.64193)
		(end 135.801354 -228.778308)
		(width 0.088646)
		(layer "In2.Cu")
		(net "M_F_CPU1_SB_DQ<14>")
	)
	(segment
		(start 181.444646 -215.166702)
		(end 181.444392 -215.166956)
		(width 0.20066)
		(layer "F.Cu")
		(net "M_F_CPU1_SB_DQ<13>")
	)
	(segment
		(start 176.796192 -214.74176)
		(end 176.451514 -214.74176)
		(width 0.20066)
		(layer "F.Cu")
		(net "M_F_CPU1_SB_DQ<13>")
	)
	(segment
		(start 175.67021 -215.415368)
		(end 175.421544 -215.166702)
		(width 0.20066)
		(layer "F.Cu")
		(net "M_F_CPU1_SB_DQ<13>")
	)
	(segment
		(start 176.816258 -214.74176)
		(end 176.796192 -214.74176)
		(width 0.101854)
		(layer "F.Cu")
		(net "M_F_CPU1_SB_DQ<13>")
	)
	(segment
		(start 176.451514 -214.74176)
		(end 176.333404 -214.85987)
		(width 0.20066)
		(layer "F.Cu")
		(net "M_F_CPU1_SB_DQ<13>")
	)
	(segment
		(start 179.004976 -214.74176)
		(end 176.816258 -214.74176)
		(width 0.1016)
		(layer "F.Cu")
		(net "M_F_CPU1_SB_DQ<13>")
	)
	(segment
		(start 179.421282 -214.73541)
		(end 179.011326 -214.73541)
		(width 0.20066)
		(layer "F.Cu")
		(net "M_F_CPU1_SB_DQ<13>")
	)
	(segment
		(start 176.333404 -214.85987)
		(end 176.333404 -215.227408)
		(width 0.20066)
		(layer "F.Cu")
		(net "M_F_CPU1_SB_DQ<13>")
	)
	(segment
		(start 179.852828 -215.166956)
		(end 179.421282 -214.73541)
		(width 0.20066)
		(layer "F.Cu")
		(net "M_F_CPU1_SB_DQ<13>")
	)
	(segment
		(start 181.444392 -215.166956)
		(end 179.852828 -215.166956)
		(width 0.20066)
		(layer "F.Cu")
		(net "M_F_CPU1_SB_DQ<13>")
	)
	(segment
		(start 173.900846 -215.166702)
		(end 172.795946 -215.166702)
		(width 0.20066)
		(layer "F.Cu")
		(net "M_F_CPU1_SB_DQ<13>")
	)
	(segment
		(start 133.725666 -228.45903)
		(end 133.725666 -228.99497)
		(width 0.20066)
		(layer "F.Cu")
		(net "M_F_CPU1_SB_DQ<13>")
	)
	(segment
		(start 179.011326 -214.73541)
		(end 179.004976 -214.74176)
		(width 0.1016)
		(layer "F.Cu")
		(net "M_F_CPU1_SB_DQ<13>")
	)
	(segment
		(start 175.421544 -215.166702)
		(end 173.900846 -215.166702)
		(width 0.20066)
		(layer "F.Cu")
		(net "M_F_CPU1_SB_DQ<13>")
	)
	(segment
		(start 176.333404 -215.227408)
		(end 176.145444 -215.415368)
		(width 0.20066)
		(layer "F.Cu")
		(net "M_F_CPU1_SB_DQ<13>")
	)
	(segment
		(start 176.145444 -215.415368)
		(end 175.67021 -215.415368)
		(width 0.20066)
		(layer "F.Cu")
		(net "M_F_CPU1_SB_DQ<13>")
	)
	(segment
		(start 134.397496 -228.957124)
		(end 134.382764 -228.948488)
		(width 0.088646)
		(layer "In2.Cu")
		(net "M_F_CPU1_SB_DQ<13>")
	)
	(segment
		(start 159.594296 -213.870032)
		(end 157.834838 -213.870032)
		(width 0.18288)
		(layer "In2.Cu")
		(net "M_F_CPU1_SB_DQ<13>")
	)
	(segment
		(start 135.887968 -227.320602)
		(end 135.879078 -227.325682)
		(width 0.088646)
		(layer "In2.Cu")
		(net "M_F_CPU1_SB_DQ<13>")
	)
	(segment
		(start 160.599628 -213.788498)
		(end 160.406588 -213.595458)
		(width 0.18288)
		(layer "In2.Cu")
		(net "M_F_CPU1_SB_DQ<13>")
	)
	(segment
		(start 139.177268 -226.506786)
		(end 139.168378 -226.511866)
		(width 0.088646)
		(layer "In2.Cu")
		(net "M_F_CPU1_SB_DQ<13>")
	)
	(segment
		(start 157.560264 -213.595458)
		(end 156.748988 -213.595458)
		(width 0.18288)
		(layer "In2.Cu")
		(net "M_F_CPU1_SB_DQ<13>")
	)
	(segment
		(start 172.240702 -215.166702)
		(end 171.693332 -214.619332)
		(width 0.18288)
		(layer "In2.Cu")
		(net "M_F_CPU1_SB_DQ<13>")
	)
	(segment
		(start 148.184616 -222.15983)
		(end 147.855686 -222.48876)
		(width 0.18288)
		(layer "In2.Cu")
		(net "M_F_CPU1_SB_DQ<13>")
	)
	(segment
		(start 149.84603 -220.835728)
		(end 149.5171 -221.164658)
		(width 0.18288)
		(layer "In2.Cu")
		(net "M_F_CPU1_SB_DQ<13>")
	)
	(segment
		(start 156.447744 -213.896702)
		(end 156.447744 -214.095076)
		(width 0.18288)
		(layer "In2.Cu")
		(net "M_F_CPU1_SB_DQ<13>")
	)
	(segment
		(start 167.625522 -214.756746)
		(end 167.174418 -214.756746)
		(width 0.18288)
		(layer "In2.Cu")
		(net "M_F_CPU1_SB_DQ<13>")
	)
	(segment
		(start 167.174418 -214.756746)
		(end 166.981378 -214.563706)
		(width 0.18288)
		(layer "In2.Cu")
		(net "M_F_CPU1_SB_DQ<13>")
	)
	(segment
		(start 146.194272 -224.150174)
		(end 145.865342 -224.479104)
		(width 0.18288)
		(layer "In2.Cu")
		(net "M_F_CPU1_SB_DQ<13>")
	)
	(segment
		(start 149.179788 -221.164658)
		(end 148.850858 -221.493588)
		(width 0.18288)
		(layer "In2.Cu")
		(net "M_F_CPU1_SB_DQ<13>")
	)
	(segment
		(start 166.788338 -213.926674)
		(end 166.515034 -213.926674)
		(width 0.18288)
		(layer "In2.Cu")
		(net "M_F_CPU1_SB_DQ<13>")
	)
	(segment
		(start 147.189444 -223.155002)
		(end 146.860514 -223.483932)
		(width 0.18288)
		(layer "In2.Cu")
		(net "M_F_CPU1_SB_DQ<13>")
	)
	(segment
		(start 134.03834 -228.45903)
		(end 133.725666 -228.45903)
		(width 0.088646)
		(layer "In2.Cu")
		(net "M_F_CPU1_SB_DQ<13>")
	)
	(segment
		(start 134.103872 -228.524562)
		(end 134.03834 -228.45903)
		(width 0.088646)
		(layer "In2.Cu")
		(net "M_F_CPU1_SB_DQ<13>")
	)
	(segment
		(start 149.5171 -221.164658)
		(end 149.179788 -221.164658)
		(width 0.18288)
		(layer "In2.Cu")
		(net "M_F_CPU1_SB_DQ<13>")
	)
	(segment
		(start 139.647168 -225.69297)
		(end 139.638278 -225.69805)
		(width 0.088646)
		(layer "In2.Cu")
		(net "M_F_CPU1_SB_DQ<13>")
	)
	(segment
		(start 145.1991 -225.145346)
		(end 144.70253 -225.641916)
		(width 0.18288)
		(layer "In2.Cu")
		(net "M_F_CPU1_SB_DQ<13>")
	)
	(segment
		(start 165.845236 -214.30615)
		(end 165.202362 -213.663276)
		(width 0.18288)
		(layer "In2.Cu")
		(net "M_F_CPU1_SB_DQ<13>")
	)
	(segment
		(start 145.536412 -225.145346)
		(end 145.1991 -225.145346)
		(width 0.18288)
		(layer "In2.Cu")
		(net "M_F_CPU1_SB_DQ<13>")
	)
	(segment
		(start 135.418068 -228.134672)
		(end 135.409178 -228.139752)
		(width 0.088646)
		(layer "In2.Cu")
		(net "M_F_CPU1_SB_DQ<13>")
	)
	(segment
		(start 134.954264 -228.944932)
		(end 134.948168 -228.948488)
		(width 0.088646)
		(layer "In2.Cu")
		(net "M_F_CPU1_SB_DQ<13>")
	)
	(segment
		(start 146.860514 -223.821244)
		(end 146.531584 -224.150174)
		(width 0.18288)
		(layer "In2.Cu")
		(net "M_F_CPU1_SB_DQ<13>")
	)
	(segment
		(start 165.202362 -213.663276)
		(end 164.929312 -213.663276)
		(width 0.18288)
		(layer "In2.Cu")
		(net "M_F_CPU1_SB_DQ<13>")
	)
	(segment
		(start 156.608018 -214.51697)
		(end 156.341064 -214.783924)
		(width 0.18288)
		(layer "In2.Cu")
		(net "M_F_CPU1_SB_DQ<13>")
	)
	(segment
		(start 134.382764 -228.948488)
		(end 134.376668 -228.944932)
		(width 0.088646)
		(layer "In2.Cu")
		(net "M_F_CPU1_SB_DQ<13>")
	)
	(segment
		(start 170.976544 -215.06307)
		(end 169.927524 -215.06307)
		(width 0.18288)
		(layer "In2.Cu")
		(net "M_F_CPU1_SB_DQ<13>")
	)
	(segment
		(start 163.448746 -213.545928)
		(end 162.411918 -213.545928)
		(width 0.18288)
		(layer "In2.Cu")
		(net "M_F_CPU1_SB_DQ<13>")
	)
	(segment
		(start 148.521928 -222.15983)
		(end 148.184616 -222.15983)
		(width 0.18288)
		(layer "In2.Cu")
		(net "M_F_CPU1_SB_DQ<13>")
	)
	(segment
		(start 135.700516 -227.64496)
		(end 135.700516 -227.663502)
		(width 0.088646)
		(layer "In2.Cu")
		(net "M_F_CPU1_SB_DQ<13>")
	)
	(segment
		(start 160.406588 -213.595458)
		(end 159.86887 -213.595458)
		(width 0.18288)
		(layer "In2.Cu")
		(net "M_F_CPU1_SB_DQ<13>")
	)
	(segment
		(start 166.135558 -214.30615)
		(end 165.845236 -214.30615)
		(width 0.18288)
		(layer "In2.Cu")
		(net "M_F_CPU1_SB_DQ<13>")
	)
	(segment
		(start 162.037014 -213.920832)
		(end 161.710878 -213.920832)
		(width 0.18288)
		(layer "In2.Cu")
		(net "M_F_CPU1_SB_DQ<13>")
	)
	(segment
		(start 164.438838 -214.15375)
		(end 164.056568 -214.15375)
		(width 0.18288)
		(layer "In2.Cu")
		(net "M_F_CPU1_SB_DQ<13>")
	)
	(segment
		(start 148.850858 -221.8309)
		(end 148.521928 -222.15983)
		(width 0.18288)
		(layer "In2.Cu")
		(net "M_F_CPU1_SB_DQ<13>")
	)
	(segment
		(start 156.608018 -214.25535)
		(end 156.608018 -214.51697)
		(width 0.18288)
		(layer "In2.Cu")
		(net "M_F_CPU1_SB_DQ<13>")
	)
	(segment
		(start 166.515034 -213.926674)
		(end 166.135558 -214.30615)
		(width 0.18288)
		(layer "In2.Cu")
		(net "M_F_CPU1_SB_DQ<13>")
	)
	(segment
		(start 141.814042 -225.641916)
		(end 140.774674 -225.641916)
		(width 0.088646)
		(layer "In2.Cu")
		(net "M_F_CPU1_SB_DQ<13>")
	)
	(segment
		(start 167.950642 -214.431626)
		(end 167.625522 -214.756746)
		(width 0.18288)
		(layer "In2.Cu")
		(net "M_F_CPU1_SB_DQ<13>")
	)
	(segment
		(start 139.459716 -226.017328)
		(end 139.459716 -226.027234)
		(width 0.088646)
		(layer "In2.Cu")
		(net "M_F_CPU1_SB_DQ<13>")
	)
	(segment
		(start 169.29608 -214.431626)
		(end 167.950642 -214.431626)
		(width 0.18288)
		(layer "In2.Cu")
		(net "M_F_CPU1_SB_DQ<13>")
	)
	(segment
		(start 148.850858 -221.493588)
		(end 148.850858 -221.8309)
		(width 0.18288)
		(layer "In2.Cu")
		(net "M_F_CPU1_SB_DQ<13>")
	)
	(segment
		(start 156.447744 -214.095076)
		(end 156.608018 -214.25535)
		(width 0.18288)
		(layer "In2.Cu")
		(net "M_F_CPU1_SB_DQ<13>")
	)
	(segment
		(start 146.531584 -224.150174)
		(end 146.194272 -224.150174)
		(width 0.18288)
		(layer "In2.Cu")
		(net "M_F_CPU1_SB_DQ<13>")
	)
	(segment
		(start 149.84603 -220.498416)
		(end 149.84603 -220.835728)
		(width 0.18288)
		(layer "In2.Cu")
		(net "M_F_CPU1_SB_DQ<13>")
	)
	(segment
		(start 144.70253 -225.641916)
		(end 141.814042 -225.641916)
		(width 0.18288)
		(layer "In2.Cu")
		(net "M_F_CPU1_SB_DQ<13>")
	)
	(segment
		(start 159.86887 -213.595458)
		(end 159.594296 -213.870032)
		(width 0.18288)
		(layer "In2.Cu")
		(net "M_F_CPU1_SB_DQ<13>")
	)
	(segment
		(start 171.420282 -214.619332)
		(end 170.976544 -215.06307)
		(width 0.18288)
		(layer "In2.Cu")
		(net "M_F_CPU1_SB_DQ<13>")
	)
	(segment
		(start 147.526756 -223.155002)
		(end 147.189444 -223.155002)
		(width 0.18288)
		(layer "In2.Cu")
		(net "M_F_CPU1_SB_DQ<13>")
	)
	(segment
		(start 155.560522 -214.783924)
		(end 149.84603 -220.498416)
		(width 0.18288)
		(layer "In2.Cu")
		(net "M_F_CPU1_SB_DQ<13>")
	)
	(segment
		(start 156.748988 -213.595458)
		(end 156.447744 -213.896702)
		(width 0.18288)
		(layer "In2.Cu")
		(net "M_F_CPU1_SB_DQ<13>")
	)
	(segment
		(start 157.834838 -213.870032)
		(end 157.560264 -213.595458)
		(width 0.18288)
		(layer "In2.Cu")
		(net "M_F_CPU1_SB_DQ<13>")
	)
	(segment
		(start 146.860514 -223.483932)
		(end 146.860514 -223.821244)
		(width 0.18288)
		(layer "In2.Cu")
		(net "M_F_CPU1_SB_DQ<13>")
	)
	(segment
		(start 164.056568 -214.15375)
		(end 163.448746 -213.545928)
		(width 0.18288)
		(layer "In2.Cu")
		(net "M_F_CPU1_SB_DQ<13>")
	)
	(segment
		(start 138.989816 -226.831144)
		(end 138.989816 -226.84105)
		(width 0.088646)
		(layer "In2.Cu")
		(net "M_F_CPU1_SB_DQ<13>")
	)
	(segment
		(start 161.710878 -213.920832)
		(end 161.149538 -214.482172)
		(width 0.18288)
		(layer "In2.Cu")
		(net "M_F_CPU1_SB_DQ<13>")
	)
	(segment
		(start 172.795946 -215.166702)
		(end 172.240702 -215.166702)
		(width 0.18288)
		(layer "In2.Cu")
		(net "M_F_CPU1_SB_DQ<13>")
	)
	(segment
		(start 161.149538 -214.482172)
		(end 160.820354 -214.482172)
		(width 0.18288)
		(layer "In2.Cu")
		(net "M_F_CPU1_SB_DQ<13>")
	)
	(segment
		(start 166.981378 -214.119714)
		(end 166.788338 -213.926674)
		(width 0.18288)
		(layer "In2.Cu")
		(net "M_F_CPU1_SB_DQ<13>")
	)
	(segment
		(start 160.599628 -214.261446)
		(end 160.599628 -213.788498)
		(width 0.18288)
		(layer "In2.Cu")
		(net "M_F_CPU1_SB_DQ<13>")
	)
	(segment
		(start 166.981378 -214.563706)
		(end 166.981378 -214.119714)
		(width 0.18288)
		(layer "In2.Cu")
		(net "M_F_CPU1_SB_DQ<13>")
	)
	(segment
		(start 171.693332 -214.619332)
		(end 171.420282 -214.619332)
		(width 0.18288)
		(layer "In2.Cu")
		(net "M_F_CPU1_SB_DQ<13>")
	)
	(segment
		(start 162.411918 -213.545928)
		(end 162.037014 -213.920832)
		(width 0.18288)
		(layer "In2.Cu")
		(net "M_F_CPU1_SB_DQ<13>")
	)
	(segment
		(start 169.927524 -215.06307)
		(end 169.29608 -214.431626)
		(width 0.18288)
		(layer "In2.Cu")
		(net "M_F_CPU1_SB_DQ<13>")
	)
	(segment
		(start 147.855686 -222.826072)
		(end 147.526756 -223.155002)
		(width 0.18288)
		(layer "In2.Cu")
		(net "M_F_CPU1_SB_DQ<13>")
	)
	(segment
		(start 147.855686 -222.48876)
		(end 147.855686 -222.826072)
		(width 0.18288)
		(layer "In2.Cu")
		(net "M_F_CPU1_SB_DQ<13>")
	)
	(segment
		(start 145.865342 -224.479104)
		(end 145.865342 -224.816416)
		(width 0.18288)
		(layer "In2.Cu")
		(net "M_F_CPU1_SB_DQ<13>")
	)
	(segment
		(start 160.820354 -214.482172)
		(end 160.599628 -214.261446)
		(width 0.18288)
		(layer "In2.Cu")
		(net "M_F_CPU1_SB_DQ<13>")
	)
	(segment
		(start 164.929312 -213.663276)
		(end 164.438838 -214.15375)
		(width 0.18288)
		(layer "In2.Cu")
		(net "M_F_CPU1_SB_DQ<13>")
	)
	(segment
		(start 156.341064 -214.783924)
		(end 155.560522 -214.783924)
		(width 0.18288)
		(layer "In2.Cu")
		(net "M_F_CPU1_SB_DQ<13>")
	)
	(segment
		(start 145.865342 -224.816416)
		(end 145.536412 -225.145346)
		(width 0.18288)
		(layer "In2.Cu")
		(net "M_F_CPU1_SB_DQ<13>")
	)
	(arc
		(start 136.262364 -227.320602)
		(mid 136.075166 -227.270459)
		(end 135.887968 -227.320602)
		(width 0.088646)
		(layer "In2.Cu")
		(net "M_F_CPU1_SB_DQ<13>")
	)
	(arc
		(start 139.459716 -226.027234)
		(mid 139.381605 -226.304183)
		(end 139.177268 -226.506786)
		(width 0.088646)
		(layer "In2.Cu")
		(net "M_F_CPU1_SB_DQ<13>")
	)
	(arc
		(start 135.230616 -228.45903)
		(mid 135.1567 -228.738532)
		(end 134.954264 -228.944932)
		(width 0.088646)
		(layer "In2.Cu")
		(net "M_F_CPU1_SB_DQ<13>")
	)
	(arc
		(start 140.586968 -225.69297)
		(mid 140.304266 -225.768712)
		(end 140.021564 -225.69297)
		(width 0.088646)
		(layer "In2.Cu")
		(net "M_F_CPU1_SB_DQ<13>")
	)
	(arc
		(start 138.707368 -227.320602)
		(mid 138.424666 -227.396378)
		(end 138.141964 -227.320602)
		(width 0.088646)
		(layer "In2.Cu")
		(net "M_F_CPU1_SB_DQ<13>")
	)
	(arc
		(start 140.021564 -225.69297)
		(mid 139.834366 -225.642827)
		(end 139.647168 -225.69297)
		(width 0.088646)
		(layer "In2.Cu")
		(net "M_F_CPU1_SB_DQ<13>")
	)
	(arc
		(start 135.879078 -227.325682)
		(mid 135.748164 -227.462042)
		(end 135.700516 -227.64496)
		(width 0.088646)
		(layer "In2.Cu")
		(net "M_F_CPU1_SB_DQ<13>")
	)
	(arc
		(start 137.202164 -227.320602)
		(mid 137.014966 -227.270459)
		(end 136.827768 -227.320602)
		(width 0.088646)
		(layer "In2.Cu")
		(net "M_F_CPU1_SB_DQ<13>")
	)
	(arc
		(start 134.948168 -228.948488)
		(mid 134.673969 -229.024323)
		(end 134.397496 -228.957124)
		(width 0.088646)
		(layer "In2.Cu")
		(net "M_F_CPU1_SB_DQ<13>")
	)
	(arc
		(start 135.700516 -227.663502)
		(mid 135.620354 -227.935691)
		(end 135.418068 -228.134672)
		(width 0.088646)
		(layer "In2.Cu")
		(net "M_F_CPU1_SB_DQ<13>")
	)
	(arc
		(start 138.141964 -227.320602)
		(mid 137.954766 -227.270459)
		(end 137.767568 -227.320602)
		(width 0.088646)
		(layer "In2.Cu")
		(net "M_F_CPU1_SB_DQ<13>")
	)
	(arc
		(start 138.989816 -226.84105)
		(mid 138.911705 -227.117999)
		(end 138.707368 -227.320602)
		(width 0.088646)
		(layer "In2.Cu")
		(net "M_F_CPU1_SB_DQ<13>")
	)
	(arc
		(start 139.168378 -226.511866)
		(mid 139.037464 -226.648226)
		(end 138.989816 -226.831144)
		(width 0.088646)
		(layer "In2.Cu")
		(net "M_F_CPU1_SB_DQ<13>")
	)
	(arc
		(start 139.638278 -225.69805)
		(mid 139.507364 -225.83441)
		(end 139.459716 -226.017328)
		(width 0.088646)
		(layer "In2.Cu")
		(net "M_F_CPU1_SB_DQ<13>")
	)
	(arc
		(start 137.767568 -227.320602)
		(mid 137.484866 -227.396378)
		(end 137.202164 -227.320602)
		(width 0.088646)
		(layer "In2.Cu")
		(net "M_F_CPU1_SB_DQ<13>")
	)
	(arc
		(start 134.376668 -228.944932)
		(mid 134.191145 -228.766631)
		(end 134.103872 -228.524562)
		(width 0.088646)
		(layer "In2.Cu")
		(net "M_F_CPU1_SB_DQ<13>")
	)
	(arc
		(start 140.774674 -225.641916)
		(mid 140.677462 -225.65508)
		(end 140.586968 -225.69297)
		(width 0.088646)
		(layer "In2.Cu")
		(net "M_F_CPU1_SB_DQ<13>")
	)
	(arc
		(start 136.827768 -227.320602)
		(mid 136.545066 -227.396378)
		(end 136.262364 -227.320602)
		(width 0.088646)
		(layer "In2.Cu")
		(net "M_F_CPU1_SB_DQ<13>")
	)
	(arc
		(start 135.409178 -228.139752)
		(mid 135.278264 -228.276112)
		(end 135.230616 -228.45903)
		(width 0.088646)
		(layer "In2.Cu")
		(net "M_F_CPU1_SB_DQ<13>")
	)
	(segment
		(start 175.421544 -216.866724)
		(end 173.900846 -216.866724)
		(width 0.20066)
		(layer "F.Cu")
		(net "M_F_CPU1_SB_DQ<12>")
	)
	(segment
		(start 179.421282 -216.435432)
		(end 179.011326 -216.435432)
		(width 0.20066)
		(layer "F.Cu")
		(net "M_F_CPU1_SB_DQ<12>")
	)
	(segment
		(start 176.145444 -217.11539)
		(end 175.67021 -217.11539)
		(width 0.20066)
		(layer "F.Cu")
		(net "M_F_CPU1_SB_DQ<12>")
	)
	(segment
		(start 179.852828 -216.866978)
		(end 179.421282 -216.435432)
		(width 0.20066)
		(layer "F.Cu")
		(net "M_F_CPU1_SB_DQ<12>")
	)
	(segment
		(start 181.444392 -216.866978)
		(end 179.852828 -216.866978)
		(width 0.20066)
		(layer "F.Cu")
		(net "M_F_CPU1_SB_DQ<12>")
	)
	(segment
		(start 181.444646 -216.866724)
		(end 181.444392 -216.866978)
		(width 0.20066)
		(layer "F.Cu")
		(net "M_F_CPU1_SB_DQ<12>")
	)
	(segment
		(start 176.796192 -216.441782)
		(end 176.451514 -216.441782)
		(width 0.20066)
		(layer "F.Cu")
		(net "M_F_CPU1_SB_DQ<12>")
	)
	(segment
		(start 176.843182 -216.441782)
		(end 176.796192 -216.441782)
		(width 0.101854)
		(layer "F.Cu")
		(net "M_F_CPU1_SB_DQ<12>")
	)
	(segment
		(start 175.67021 -217.11539)
		(end 175.421544 -216.866724)
		(width 0.20066)
		(layer "F.Cu")
		(net "M_F_CPU1_SB_DQ<12>")
	)
	(segment
		(start 173.900846 -216.866724)
		(end 172.795946 -216.866724)
		(width 0.20066)
		(layer "F.Cu")
		(net "M_F_CPU1_SB_DQ<12>")
	)
	(segment
		(start 176.451514 -216.441782)
		(end 176.333404 -216.559892)
		(width 0.20066)
		(layer "F.Cu")
		(net "M_F_CPU1_SB_DQ<12>")
	)
	(segment
		(start 133.255766 -229.808532)
		(end 133.255766 -229.272846)
		(width 0.20066)
		(layer "F.Cu")
		(net "M_F_CPU1_SB_DQ<12>")
	)
	(segment
		(start 176.333404 -216.559892)
		(end 176.333404 -216.92743)
		(width 0.20066)
		(layer "F.Cu")
		(net "M_F_CPU1_SB_DQ<12>")
	)
	(segment
		(start 176.333404 -216.92743)
		(end 176.145444 -217.11539)
		(width 0.20066)
		(layer "F.Cu")
		(net "M_F_CPU1_SB_DQ<12>")
	)
	(segment
		(start 133.255512 -229.808786)
		(end 133.255766 -229.808532)
		(width 0.20066)
		(layer "F.Cu")
		(net "M_F_CPU1_SB_DQ<12>")
	)
	(segment
		(start 179.011326 -216.435432)
		(end 179.004976 -216.441782)
		(width 0.1016)
		(layer "F.Cu")
		(net "M_F_CPU1_SB_DQ<12>")
	)
	(segment
		(start 179.004976 -216.441782)
		(end 176.843182 -216.441782)
		(width 0.1016)
		(layer "F.Cu")
		(net "M_F_CPU1_SB_DQ<12>")
	)
	(segment
		(start 171.607226 -216.209626)
		(end 171.432982 -216.38387)
		(width 0.18288)
		(layer "In2.Cu")
		(net "M_F_CPU1_SB_DQ<12>")
	)
	(segment
		(start 152.902666 -219.66174)
		(end 152.679654 -219.884752)
		(width 0.18288)
		(layer "In2.Cu")
		(net "M_F_CPU1_SB_DQ<12>")
	)
	(segment
		(start 135.720328 -229.152958)
		(end 135.546084 -229.403148)
		(width 0.088646)
		(layer "In2.Cu")
		(net "M_F_CPU1_SB_DQ<12>")
	)
	(segment
		(start 168.065196 -216.10447)
		(end 168.065196 -216.459562)
		(width 0.18288)
		(layer "In2.Cu")
		(net "M_F_CPU1_SB_DQ<12>")
	)
	(segment
		(start 135.887968 -228.948488)
		(end 135.887714 -228.948742)
		(width 0.088646)
		(layer "In2.Cu")
		(net "M_F_CPU1_SB_DQ<12>")
	)
	(segment
		(start 135.326882 -229.594664)
		(end 135.322564 -229.597204)
		(width 0.088646)
		(layer "In2.Cu")
		(net "M_F_CPU1_SB_DQ<12>")
	)
	(segment
		(start 153.00706 -218.774772)
		(end 152.784048 -218.997784)
		(width 0.18288)
		(layer "In2.Cu")
		(net "M_F_CPU1_SB_DQ<12>")
	)
	(segment
		(start 152.902666 -219.389198)
		(end 152.902666 -219.66174)
		(width 0.18288)
		(layer "In2.Cu")
		(net "M_F_CPU1_SB_DQ<12>")
	)
	(segment
		(start 158.025338 -215.54821)
		(end 157.738318 -215.26119)
		(width 0.18288)
		(layer "In2.Cu")
		(net "M_F_CPU1_SB_DQ<12>")
	)
	(segment
		(start 152.784048 -218.997784)
		(end 152.784048 -219.27058)
		(width 0.18288)
		(layer "In2.Cu")
		(net "M_F_CPU1_SB_DQ<12>")
	)
	(segment
		(start 168.550336 -215.94445)
		(end 168.225216 -215.94445)
		(width 0.18288)
		(layer "In2.Cu")
		(net "M_F_CPU1_SB_DQ<12>")
	)
	(segment
		(start 154.885898 -217.405966)
		(end 154.885898 -217.678508)
		(width 0.18288)
		(layer "In2.Cu")
		(net "M_F_CPU1_SB_DQ<12>")
	)
	(segment
		(start 154.885898 -217.678508)
		(end 154.662886 -217.90152)
		(width 0.18288)
		(layer "In2.Cu")
		(net "M_F_CPU1_SB_DQ<12>")
	)
	(segment
		(start 154.76728 -217.014552)
		(end 154.76728 -217.287348)
		(width 0.18288)
		(layer "In2.Cu")
		(net "M_F_CPU1_SB_DQ<12>")
	)
	(segment
		(start 154.76728 -217.287348)
		(end 154.885898 -217.405966)
		(width 0.18288)
		(layer "In2.Cu")
		(net "M_F_CPU1_SB_DQ<12>")
	)
	(segment
		(start 165.731698 -216.201244)
		(end 165.443916 -216.489026)
		(width 0.18288)
		(layer "In2.Cu")
		(net "M_F_CPU1_SB_DQ<12>")
	)
	(segment
		(start 159.817562 -215.54821)
		(end 158.025338 -215.54821)
		(width 0.18288)
		(layer "In2.Cu")
		(net "M_F_CPU1_SB_DQ<12>")
	)
	(segment
		(start 151.792432 -219.9894)
		(end 151.792432 -220.262196)
		(width 0.18288)
		(layer "In2.Cu")
		(net "M_F_CPU1_SB_DQ<12>")
	)
	(segment
		(start 153.775664 -218.278964)
		(end 153.894282 -218.397582)
		(width 0.18288)
		(layer "In2.Cu")
		(net "M_F_CPU1_SB_DQ<12>")
	)
	(segment
		(start 136.357868 -228.134672)
		(end 136.348978 -228.139752)
		(width 0.088646)
		(layer "In2.Cu")
		(net "M_F_CPU1_SB_DQ<12>")
	)
	(segment
		(start 157.303216 -215.26119)
		(end 156.646118 -215.918288)
		(width 0.18288)
		(layer "In2.Cu")
		(net "M_F_CPU1_SB_DQ<12>")
	)
	(segment
		(start 153.398474 -218.893136)
		(end 153.279856 -218.774772)
		(width 0.18288)
		(layer "In2.Cu")
		(net "M_F_CPU1_SB_DQ<12>")
	)
	(segment
		(start 134.953756 -229.600506)
		(end 134.947914 -229.597204)
		(width 0.088646)
		(layer "In2.Cu")
		(net "M_F_CPU1_SB_DQ<12>")
	)
	(segment
		(start 155.654502 -216.909904)
		(end 155.381706 -216.909904)
		(width 0.18288)
		(layer "In2.Cu")
		(net "M_F_CPU1_SB_DQ<12>")
	)
	(segment
		(start 152.015444 -219.766388)
		(end 151.792432 -219.9894)
		(width 0.18288)
		(layer "In2.Cu")
		(net "M_F_CPU1_SB_DQ<12>")
	)
	(segment
		(start 168.065196 -216.459562)
		(end 167.872156 -216.652602)
		(width 0.18288)
		(layer "In2.Cu")
		(net "M_F_CPU1_SB_DQ<12>")
	)
	(segment
		(start 151.593296 -220.97111)
		(end 151.148288 -220.97111)
		(width 0.18288)
		(layer "In2.Cu")
		(net "M_F_CPU1_SB_DQ<12>")
	)
	(segment
		(start 155.758896 -216.295732)
		(end 155.877514 -216.41435)
		(width 0.18288)
		(layer "In2.Cu")
		(net "M_F_CPU1_SB_DQ<12>")
	)
	(segment
		(start 153.279856 -218.774772)
		(end 153.00706 -218.774772)
		(width 0.18288)
		(layer "In2.Cu")
		(net "M_F_CPU1_SB_DQ<12>")
	)
	(segment
		(start 163.522152 -215.308688)
		(end 162.324796 -215.308688)
		(width 0.18288)
		(layer "In2.Cu")
		(net "M_F_CPU1_SB_DQ<12>")
	)
	(segment
		(start 134.947914 -229.597204)
		(end 134.943342 -229.59441)
		(width 0.088646)
		(layer "In2.Cu")
		(net "M_F_CPU1_SB_DQ<12>")
	)
	(segment
		(start 167.872156 -216.652602)
		(end 167.468296 -216.652602)
		(width 0.18288)
		(layer "In2.Cu")
		(net "M_F_CPU1_SB_DQ<12>")
	)
	(segment
		(start 155.877514 -216.41435)
		(end 155.877514 -216.686892)
		(width 0.18288)
		(layer "In2.Cu")
		(net "M_F_CPU1_SB_DQ<12>")
	)
	(segment
		(start 167.468296 -216.652602)
		(end 167.016938 -216.201244)
		(width 0.18288)
		(layer "In2.Cu")
		(net "M_F_CPU1_SB_DQ<12>")
	)
	(segment
		(start 167.016938 -216.201244)
		(end 165.731698 -216.201244)
		(width 0.18288)
		(layer "In2.Cu")
		(net "M_F_CPU1_SB_DQ<12>")
	)
	(segment
		(start 164.004498 -215.791034)
		(end 163.522152 -215.308688)
		(width 0.18288)
		(layer "In2.Cu")
		(net "M_F_CPU1_SB_DQ<12>")
	)
	(segment
		(start 162.324796 -215.308688)
		(end 161.702496 -215.930988)
		(width 0.18288)
		(layer "In2.Cu")
		(net "M_F_CPU1_SB_DQ<12>")
	)
	(segment
		(start 155.381706 -216.909904)
		(end 155.263088 -216.79154)
		(width 0.18288)
		(layer "In2.Cu")
		(net "M_F_CPU1_SB_DQ<12>")
	)
	(segment
		(start 153.67127 -218.893136)
		(end 153.398474 -218.893136)
		(width 0.18288)
		(layer "In2.Cu")
		(net "M_F_CPU1_SB_DQ<12>")
	)
	(segment
		(start 152.406858 -219.884752)
		(end 152.28824 -219.766388)
		(width 0.18288)
		(layer "In2.Cu")
		(net "M_F_CPU1_SB_DQ<12>")
	)
	(segment
		(start 154.271472 -217.783156)
		(end 153.998676 -217.783156)
		(width 0.18288)
		(layer "In2.Cu")
		(net "M_F_CPU1_SB_DQ<12>")
	)
	(segment
		(start 156.254704 -215.799924)
		(end 155.981908 -215.799924)
		(width 0.18288)
		(layer "In2.Cu")
		(net "M_F_CPU1_SB_DQ<12>")
	)
	(segment
		(start 156.373322 -215.918288)
		(end 156.254704 -215.799924)
		(width 0.18288)
		(layer "In2.Cu")
		(net "M_F_CPU1_SB_DQ<12>")
	)
	(segment
		(start 155.758896 -216.022936)
		(end 155.758896 -216.295732)
		(width 0.18288)
		(layer "In2.Cu")
		(net "M_F_CPU1_SB_DQ<12>")
	)
	(segment
		(start 155.263088 -216.79154)
		(end 154.990292 -216.79154)
		(width 0.18288)
		(layer "In2.Cu")
		(net "M_F_CPU1_SB_DQ<12>")
	)
	(segment
		(start 171.432982 -216.38387)
		(end 168.989756 -216.38387)
		(width 0.18288)
		(layer "In2.Cu")
		(net "M_F_CPU1_SB_DQ<12>")
	)
	(segment
		(start 135.546084 -229.403148)
		(end 135.445754 -229.503478)
		(width 0.088646)
		(layer "In2.Cu")
		(net "M_F_CPU1_SB_DQ<12>")
	)
	(segment
		(start 164.300662 -215.791034)
		(end 164.004498 -215.791034)
		(width 0.18288)
		(layer "In2.Cu")
		(net "M_F_CPU1_SB_DQ<12>")
	)
	(segment
		(start 155.877514 -216.686892)
		(end 155.654502 -216.909904)
		(width 0.18288)
		(layer "In2.Cu")
		(net "M_F_CPU1_SB_DQ<12>")
	)
	(segment
		(start 154.39009 -217.90152)
		(end 154.271472 -217.783156)
		(width 0.18288)
		(layer "In2.Cu")
		(net "M_F_CPU1_SB_DQ<12>")
	)
	(segment
		(start 151.91105 -220.380814)
		(end 151.91105 -220.653356)
		(width 0.18288)
		(layer "In2.Cu")
		(net "M_F_CPU1_SB_DQ<12>")
	)
	(segment
		(start 154.990292 -216.79154)
		(end 154.76728 -217.014552)
		(width 0.18288)
		(layer "In2.Cu")
		(net "M_F_CPU1_SB_DQ<12>")
	)
	(segment
		(start 159.88411 -215.481662)
		(end 159.817562 -215.54821)
		(width 0.18288)
		(layer "In2.Cu")
		(net "M_F_CPU1_SB_DQ<12>")
	)
	(segment
		(start 168.989756 -216.38387)
		(end 168.550336 -215.94445)
		(width 0.18288)
		(layer "In2.Cu")
		(net "M_F_CPU1_SB_DQ<12>")
	)
	(segment
		(start 140.72235 -226.706684)
		(end 140.175742 -227.253292)
		(width 0.18288)
		(layer "In2.Cu")
		(net "M_F_CPU1_SB_DQ<12>")
	)
	(segment
		(start 153.894282 -218.670124)
		(end 153.67127 -218.893136)
		(width 0.18288)
		(layer "In2.Cu")
		(net "M_F_CPU1_SB_DQ<12>")
	)
	(segment
		(start 153.998676 -217.783156)
		(end 153.775664 -218.006168)
		(width 0.18288)
		(layer "In2.Cu")
		(net "M_F_CPU1_SB_DQ<12>")
	)
	(segment
		(start 140.175742 -227.253292)
		(end 139.678918 -227.750116)
		(width 0.088646)
		(layer "In2.Cu")
		(net "M_F_CPU1_SB_DQ<12>")
	)
	(segment
		(start 133.755384 -229.460044)
		(end 133.255766 -229.272846)
		(width 0.088646)
		(layer "In2.Cu")
		(net "M_F_CPU1_SB_DQ<12>")
	)
	(segment
		(start 161.702496 -215.930988)
		(end 160.821116 -215.930988)
		(width 0.18288)
		(layer "In2.Cu")
		(net "M_F_CPU1_SB_DQ<12>")
	)
	(segment
		(start 164.998654 -216.489026)
		(end 164.300662 -215.791034)
		(width 0.18288)
		(layer "In2.Cu")
		(net "M_F_CPU1_SB_DQ<12>")
	)
	(segment
		(start 153.894282 -218.397582)
		(end 153.894282 -218.670124)
		(width 0.18288)
		(layer "In2.Cu")
		(net "M_F_CPU1_SB_DQ<12>")
	)
	(segment
		(start 157.738318 -215.26119)
		(end 157.303216 -215.26119)
		(width 0.18288)
		(layer "In2.Cu")
		(net "M_F_CPU1_SB_DQ<12>")
	)
	(segment
		(start 160.37179 -215.481662)
		(end 159.88411 -215.481662)
		(width 0.18288)
		(layer "In2.Cu")
		(net "M_F_CPU1_SB_DQ<12>")
	)
	(segment
		(start 156.646118 -215.918288)
		(end 156.373322 -215.918288)
		(width 0.18288)
		(layer "In2.Cu")
		(net "M_F_CPU1_SB_DQ<12>")
	)
	(segment
		(start 136.170416 -228.45903)
		(end 136.170416 -228.468936)
		(width 0.088646)
		(layer "In2.Cu")
		(net "M_F_CPU1_SB_DQ<12>")
	)
	(segment
		(start 165.443916 -216.489026)
		(end 164.998654 -216.489026)
		(width 0.18288)
		(layer "In2.Cu")
		(net "M_F_CPU1_SB_DQ<12>")
	)
	(segment
		(start 151.792432 -220.262196)
		(end 151.91105 -220.380814)
		(width 0.18288)
		(layer "In2.Cu")
		(net "M_F_CPU1_SB_DQ<12>")
	)
	(segment
		(start 145.412714 -226.706684)
		(end 140.72235 -226.706684)
		(width 0.18288)
		(layer "In2.Cu")
		(net "M_F_CPU1_SB_DQ<12>")
	)
	(segment
		(start 152.28824 -219.766388)
		(end 152.015444 -219.766388)
		(width 0.18288)
		(layer "In2.Cu")
		(net "M_F_CPU1_SB_DQ<12>")
	)
	(segment
		(start 172.795946 -216.866724)
		(end 172.138848 -216.209626)
		(width 0.18288)
		(layer "In2.Cu")
		(net "M_F_CPU1_SB_DQ<12>")
	)
	(segment
		(start 152.679654 -219.884752)
		(end 152.406858 -219.884752)
		(width 0.18288)
		(layer "In2.Cu")
		(net "M_F_CPU1_SB_DQ<12>")
	)
	(segment
		(start 134.008114 -229.597204)
		(end 133.835648 -229.49789)
		(width 0.088646)
		(layer "In2.Cu")
		(net "M_F_CPU1_SB_DQ<12>")
	)
	(segment
		(start 160.821116 -215.930988)
		(end 160.37179 -215.481662)
		(width 0.18288)
		(layer "In2.Cu")
		(net "M_F_CPU1_SB_DQ<12>")
	)
	(segment
		(start 151.91105 -220.653356)
		(end 151.593296 -220.97111)
		(width 0.18288)
		(layer "In2.Cu")
		(net "M_F_CPU1_SB_DQ<12>")
	)
	(segment
		(start 154.662886 -217.90152)
		(end 154.39009 -217.90152)
		(width 0.18288)
		(layer "In2.Cu")
		(net "M_F_CPU1_SB_DQ<12>")
	)
	(segment
		(start 152.784048 -219.27058)
		(end 152.902666 -219.389198)
		(width 0.18288)
		(layer "In2.Cu")
		(net "M_F_CPU1_SB_DQ<12>")
	)
	(segment
		(start 153.775664 -218.006168)
		(end 153.775664 -218.278964)
		(width 0.18288)
		(layer "In2.Cu")
		(net "M_F_CPU1_SB_DQ<12>")
	)
	(segment
		(start 155.981908 -215.799924)
		(end 155.758896 -216.022936)
		(width 0.18288)
		(layer "In2.Cu")
		(net "M_F_CPU1_SB_DQ<12>")
	)
	(segment
		(start 172.138848 -216.209626)
		(end 171.607226 -216.209626)
		(width 0.18288)
		(layer "In2.Cu")
		(net "M_F_CPU1_SB_DQ<12>")
	)
	(segment
		(start 168.225216 -215.94445)
		(end 168.065196 -216.10447)
		(width 0.18288)
		(layer "In2.Cu")
		(net "M_F_CPU1_SB_DQ<12>")
	)
	(segment
		(start 151.148288 -220.97111)
		(end 145.412714 -226.706684)
		(width 0.18288)
		(layer "In2.Cu")
		(net "M_F_CPU1_SB_DQ<12>")
	)
	(arc
		(start 136.732264 -228.134672)
		(mid 136.545066 -228.084529)
		(end 136.357868 -228.134672)
		(width 0.088646)
		(layer "In2.Cu")
		(net "M_F_CPU1_SB_DQ<12>")
	)
	(arc
		(start 135.887714 -228.948742)
		(mid 135.785364 -229.035569)
		(end 135.720328 -229.152958)
		(width 0.088646)
		(layer "In2.Cu")
		(net "M_F_CPU1_SB_DQ<12>")
	)
	(arc
		(start 135.322564 -229.597204)
		(mid 135.13861 -229.647333)
		(end 134.953756 -229.600506)
		(width 0.088646)
		(layer "In2.Cu")
		(net "M_F_CPU1_SB_DQ<12>")
	)
	(arc
		(start 139.177268 -228.134672)
		(mid 138.894566 -228.210414)
		(end 138.611864 -228.134672)
		(width 0.088646)
		(layer "In2.Cu")
		(net "M_F_CPU1_SB_DQ<12>")
	)
	(arc
		(start 137.672064 -228.134672)
		(mid 137.484866 -228.084529)
		(end 137.297668 -228.134672)
		(width 0.088646)
		(layer "In2.Cu")
		(net "M_F_CPU1_SB_DQ<12>")
	)
	(arc
		(start 134.382764 -229.597204)
		(mid 134.195456 -229.647347)
		(end 134.008114 -229.597204)
		(width 0.088646)
		(layer "In2.Cu")
		(net "M_F_CPU1_SB_DQ<12>")
	)
	(arc
		(start 137.297668 -228.134672)
		(mid 137.014966 -228.210414)
		(end 136.732264 -228.134672)
		(width 0.088646)
		(layer "In2.Cu")
		(net "M_F_CPU1_SB_DQ<12>")
	)
	(arc
		(start 136.348978 -228.139752)
		(mid 136.218064 -228.276112)
		(end 136.170416 -228.45903)
		(width 0.088646)
		(layer "In2.Cu")
		(net "M_F_CPU1_SB_DQ<12>")
	)
	(arc
		(start 134.943342 -229.59441)
		(mid 134.662678 -229.521402)
		(end 134.382764 -229.597204)
		(width 0.088646)
		(layer "In2.Cu")
		(net "M_F_CPU1_SB_DQ<12>")
	)
	(arc
		(start 139.678918 -227.750116)
		(mid 139.44075 -227.958907)
		(end 139.177268 -228.134672)
		(width 0.088646)
		(layer "In2.Cu")
		(net "M_F_CPU1_SB_DQ<12>")
	)
	(arc
		(start 135.445754 -229.503478)
		(mid 135.389321 -229.552987)
		(end 135.326882 -229.594664)
		(width 0.088646)
		(layer "In2.Cu")
		(net "M_F_CPU1_SB_DQ<12>")
	)
	(arc
		(start 138.611864 -228.134672)
		(mid 138.424666 -228.084529)
		(end 138.237468 -228.134672)
		(width 0.088646)
		(layer "In2.Cu")
		(net "M_F_CPU1_SB_DQ<12>")
	)
	(arc
		(start 133.835648 -229.49789)
		(mid 133.796287 -229.477333)
		(end 133.755384 -229.460044)
		(width 0.088646)
		(layer "In2.Cu")
		(net "M_F_CPU1_SB_DQ<12>")
	)
	(arc
		(start 138.237468 -228.134672)
		(mid 137.954766 -228.210414)
		(end 137.672064 -228.134672)
		(width 0.088646)
		(layer "In2.Cu")
		(net "M_F_CPU1_SB_DQ<12>")
	)
	(arc
		(start 136.170416 -228.468936)
		(mid 136.092305 -228.745885)
		(end 135.887968 -228.948488)
		(width 0.088646)
		(layer "In2.Cu")
		(net "M_F_CPU1_SB_DQ<12>")
	)
	(segment
		(start 135.135112 -230.900732)
		(end 135.135366 -230.900478)
		(width 0.20066)
		(layer "F.Cu")
		(net "M_F_CPU1_SB_DQ<11>")
	)
	(segment
		(start 180.427884 -220.698822)
		(end 180.434996 -220.69171)
		(width 0.1016)
		(layer "F.Cu")
		(net "M_F_CPU1_SB_DQ<11>")
	)
	(segment
		(start 183.574436 -220.0148)
		(end 183.958484 -220.0148)
		(width 0.20066)
		(layer "F.Cu")
		(net "M_F_CPU1_SB_DQ<11>")
	)
	(segment
		(start 179.699158 -220.266768)
		(end 180.131212 -220.698822)
		(width 0.20066)
		(layer "F.Cu")
		(net "M_F_CPU1_SB_DQ<11>")
	)
	(segment
		(start 184.210452 -220.266768)
		(end 185.544714 -220.266768)
		(width 0.20066)
		(layer "F.Cu")
		(net "M_F_CPU1_SB_DQ<11>")
	)
	(segment
		(start 182.442866 -220.69171)
		(end 182.455058 -220.703902)
		(width 0.1016)
		(layer "F.Cu")
		(net "M_F_CPU1_SB_DQ<11>")
	)
	(segment
		(start 183.340248 -220.49994)
		(end 183.340248 -220.248988)
		(width 0.20066)
		(layer "F.Cu")
		(net "M_F_CPU1_SB_DQ<11>")
	)
	(segment
		(start 178.000914 -220.266768)
		(end 179.699158 -220.266768)
		(width 0.20066)
		(layer "F.Cu")
		(net "M_F_CPU1_SB_DQ<11>")
	)
	(segment
		(start 180.131212 -220.698822)
		(end 180.423058 -220.698822)
		(width 0.20066)
		(layer "F.Cu")
		(net "M_F_CPU1_SB_DQ<11>")
	)
	(segment
		(start 180.423058 -220.698822)
		(end 180.427884 -220.698822)
		(width 0.101854)
		(layer "F.Cu")
		(net "M_F_CPU1_SB_DQ<11>")
	)
	(segment
		(start 176.896014 -220.266768)
		(end 178.000914 -220.266768)
		(width 0.20066)
		(layer "F.Cu")
		(net "M_F_CPU1_SB_DQ<11>")
	)
	(segment
		(start 180.434996 -220.69171)
		(end 182.442866 -220.69171)
		(width 0.1016)
		(layer "F.Cu")
		(net "M_F_CPU1_SB_DQ<11>")
	)
	(segment
		(start 182.455058 -220.703902)
		(end 183.136286 -220.703902)
		(width 0.20066)
		(layer "F.Cu")
		(net "M_F_CPU1_SB_DQ<11>")
	)
	(segment
		(start 183.136286 -220.703902)
		(end 183.340248 -220.49994)
		(width 0.20066)
		(layer "F.Cu")
		(net "M_F_CPU1_SB_DQ<11>")
	)
	(segment
		(start 183.340248 -220.248988)
		(end 183.574436 -220.0148)
		(width 0.20066)
		(layer "F.Cu")
		(net "M_F_CPU1_SB_DQ<11>")
	)
	(segment
		(start 135.135112 -231.436418)
		(end 135.135112 -230.900732)
		(width 0.20066)
		(layer "F.Cu")
		(net "M_F_CPU1_SB_DQ<11>")
	)
	(segment
		(start 183.958484 -220.0148)
		(end 184.210452 -220.266768)
		(width 0.20066)
		(layer "F.Cu")
		(net "M_F_CPU1_SB_DQ<11>")
	)
	(segment
		(start 169.469562 -219.88145)
		(end 169.450258 -219.900754)
		(width 0.18288)
		(layer "In2.Cu")
		(net "M_F_CPU1_SB_DQ<11>")
	)
	(segment
		(start 165.297612 -220.768672)
		(end 164.736272 -220.768672)
		(width 0.18288)
		(layer "In2.Cu")
		(net "M_F_CPU1_SB_DQ<11>")
	)
	(segment
		(start 171.937426 -220.070426)
		(end 171.505626 -220.070426)
		(width 0.18288)
		(layer "In2.Cu")
		(net "M_F_CPU1_SB_DQ<11>")
	)
	(segment
		(start 171.31665 -219.88145)
		(end 169.469562 -219.88145)
		(width 0.18288)
		(layer "In2.Cu")
		(net "M_F_CPU1_SB_DQ<11>")
	)
	(segment
		(start 174.284132 -220.689932)
		(end 173.996858 -220.402658)
		(width 0.18288)
		(layer "In2.Cu")
		(net "M_F_CPU1_SB_DQ<11>")
	)
	(segment
		(start 164.629592 -220.661992)
		(end 161.933128 -220.661992)
		(width 0.18288)
		(layer "In2.Cu")
		(net "M_F_CPU1_SB_DQ<11>")
	)
	(segment
		(start 137.211054 -231.219756)
		(end 137.202164 -231.224836)
		(width 0.088646)
		(layer "In2.Cu")
		(net "M_F_CPU1_SB_DQ<11>")
	)
	(segment
		(start 167.415972 -220.768672)
		(end 167.319198 -220.671898)
		(width 0.18288)
		(layer "In2.Cu")
		(net "M_F_CPU1_SB_DQ<11>")
	)
	(segment
		(start 135.325358 -231.09047)
		(end 135.135366 -230.900478)
		(width 0.088646)
		(layer "In2.Cu")
		(net "M_F_CPU1_SB_DQ<11>")
	)
	(segment
		(start 135.725154 -231.133142)
		(end 135.566658 -231.09047)
		(width 0.088646)
		(layer "In2.Cu")
		(net "M_F_CPU1_SB_DQ<11>")
	)
	(segment
		(start 173.225714 -220.689932)
		(end 172.556932 -220.689932)
		(width 0.18288)
		(layer "In2.Cu")
		(net "M_F_CPU1_SB_DQ<11>")
	)
	(segment
		(start 135.887968 -231.224836)
		(end 135.74776 -231.142794)
		(width 0.088646)
		(layer "In2.Cu")
		(net "M_F_CPU1_SB_DQ<11>")
	)
	(segment
		(start 174.817278 -220.689932)
		(end 174.284132 -220.689932)
		(width 0.18288)
		(layer "In2.Cu")
		(net "M_F_CPU1_SB_DQ<11>")
	)
	(segment
		(start 157.974792 -219.869512)
		(end 157.5308 -219.42552)
		(width 0.18288)
		(layer "In2.Cu")
		(net "M_F_CPU1_SB_DQ<11>")
	)
	(segment
		(start 176.138078 -221.226888)
		(end 175.944784 -221.420182)
		(width 0.18288)
		(layer "In2.Cu")
		(net "M_F_CPU1_SB_DQ<11>")
	)
	(segment
		(start 160.108646 -219.081858)
		(end 159.948626 -219.241878)
		(width 0.18288)
		(layer "In2.Cu")
		(net "M_F_CPU1_SB_DQ<11>")
	)
	(segment
		(start 169.450258 -219.900754)
		(end 168.754298 -219.900754)
		(width 0.18288)
		(layer "In2.Cu")
		(net "M_F_CPU1_SB_DQ<11>")
	)
	(segment
		(start 154.176984 -221.528132)
		(end 146.417792 -229.287324)
		(width 0.18288)
		(layer "In2.Cu")
		(net "M_F_CPU1_SB_DQ<11>")
	)
	(segment
		(start 160.525206 -219.081858)
		(end 160.108646 -219.081858)
		(width 0.18288)
		(layer "In2.Cu")
		(net "M_F_CPU1_SB_DQ<11>")
	)
	(segment
		(start 159.948626 -219.511626)
		(end 159.59074 -219.869512)
		(width 0.18288)
		(layer "In2.Cu")
		(net "M_F_CPU1_SB_DQ<11>")
	)
	(segment
		(start 164.736272 -220.768672)
		(end 164.629592 -220.661992)
		(width 0.18288)
		(layer "In2.Cu")
		(net "M_F_CPU1_SB_DQ<11>")
	)
	(segment
		(start 161.291016 -220.01988)
		(end 160.85058 -220.01988)
		(width 0.18288)
		(layer "In2.Cu")
		(net "M_F_CPU1_SB_DQ<11>")
	)
	(segment
		(start 168.754298 -219.900754)
		(end 167.88638 -220.768672)
		(width 0.18288)
		(layer "In2.Cu")
		(net "M_F_CPU1_SB_DQ<11>")
	)
	(segment
		(start 137.389616 -230.890572)
		(end 137.389616 -230.900478)
		(width 0.088646)
		(layer "In2.Cu")
		(net "M_F_CPU1_SB_DQ<11>")
	)
	(segment
		(start 160.685226 -219.854526)
		(end 160.685226 -219.241878)
		(width 0.18288)
		(layer "In2.Cu")
		(net "M_F_CPU1_SB_DQ<11>")
	)
	(segment
		(start 161.933128 -220.661992)
		(end 161.291016 -220.01988)
		(width 0.18288)
		(layer "In2.Cu")
		(net "M_F_CPU1_SB_DQ<11>")
	)
	(segment
		(start 146.417792 -229.287324)
		(end 141.679422 -229.287324)
		(width 0.18288)
		(layer "In2.Cu")
		(net "M_F_CPU1_SB_DQ<11>")
	)
	(segment
		(start 171.505626 -220.070426)
		(end 171.31665 -219.88145)
		(width 0.18288)
		(layer "In2.Cu")
		(net "M_F_CPU1_SB_DQ<11>")
	)
	(segment
		(start 156.290772 -221.040452)
		(end 155.803092 -221.528132)
		(width 0.18288)
		(layer "In2.Cu")
		(net "M_F_CPU1_SB_DQ<11>")
	)
	(segment
		(start 159.59074 -219.869512)
		(end 157.974792 -219.869512)
		(width 0.18288)
		(layer "In2.Cu")
		(net "M_F_CPU1_SB_DQ<11>")
	)
	(segment
		(start 160.685226 -219.241878)
		(end 160.525206 -219.081858)
		(width 0.18288)
		(layer "In2.Cu")
		(net "M_F_CPU1_SB_DQ<11>")
	)
	(segment
		(start 176.27473 -220.266768)
		(end 176.138078 -220.40342)
		(width 0.18288)
		(layer "In2.Cu")
		(net "M_F_CPU1_SB_DQ<11>")
	)
	(segment
		(start 157.257496 -219.42552)
		(end 156.290772 -220.392244)
		(width 0.18288)
		(layer "In2.Cu")
		(net "M_F_CPU1_SB_DQ<11>")
	)
	(segment
		(start 156.290772 -220.392244)
		(end 156.290772 -221.040452)
		(width 0.18288)
		(layer "In2.Cu")
		(net "M_F_CPU1_SB_DQ<11>")
	)
	(segment
		(start 141.679422 -229.287324)
		(end 141.2875 -229.287324)
		(width 0.088646)
		(layer "In2.Cu")
		(net "M_F_CPU1_SB_DQ<11>")
	)
	(segment
		(start 167.88638 -220.768672)
		(end 167.415972 -220.768672)
		(width 0.18288)
		(layer "In2.Cu")
		(net "M_F_CPU1_SB_DQ<11>")
	)
	(segment
		(start 176.138078 -220.40342)
		(end 176.138078 -221.226888)
		(width 0.18288)
		(layer "In2.Cu")
		(net "M_F_CPU1_SB_DQ<11>")
	)
	(segment
		(start 141.2875 -229.287324)
		(end 140.239496 -230.335328)
		(width 0.088646)
		(layer "In2.Cu")
		(net "M_F_CPU1_SB_DQ<11>")
	)
	(segment
		(start 173.996858 -220.402658)
		(end 173.512988 -220.402658)
		(width 0.18288)
		(layer "In2.Cu")
		(net "M_F_CPU1_SB_DQ<11>")
	)
	(segment
		(start 175.944784 -221.420182)
		(end 175.547528 -221.420182)
		(width 0.18288)
		(layer "In2.Cu")
		(net "M_F_CPU1_SB_DQ<11>")
	)
	(segment
		(start 135.566658 -231.09047)
		(end 135.325358 -231.09047)
		(width 0.088646)
		(layer "In2.Cu")
		(net "M_F_CPU1_SB_DQ<11>")
	)
	(segment
		(start 159.948626 -219.241878)
		(end 159.948626 -219.511626)
		(width 0.18288)
		(layer "In2.Cu")
		(net "M_F_CPU1_SB_DQ<11>")
	)
	(segment
		(start 175.547528 -221.420182)
		(end 174.817278 -220.689932)
		(width 0.18288)
		(layer "In2.Cu")
		(net "M_F_CPU1_SB_DQ<11>")
	)
	(segment
		(start 160.85058 -220.01988)
		(end 160.685226 -219.854526)
		(width 0.18288)
		(layer "In2.Cu")
		(net "M_F_CPU1_SB_DQ<11>")
	)
	(segment
		(start 140.239496 -230.335328)
		(end 139.834366 -230.335328)
		(width 0.088646)
		(layer "In2.Cu")
		(net "M_F_CPU1_SB_DQ<11>")
	)
	(segment
		(start 155.803092 -221.528132)
		(end 154.176984 -221.528132)
		(width 0.18288)
		(layer "In2.Cu")
		(net "M_F_CPU1_SB_DQ<11>")
	)
	(segment
		(start 165.394386 -220.671898)
		(end 165.297612 -220.768672)
		(width 0.18288)
		(layer "In2.Cu")
		(net "M_F_CPU1_SB_DQ<11>")
	)
	(segment
		(start 173.512988 -220.402658)
		(end 173.225714 -220.689932)
		(width 0.18288)
		(layer "In2.Cu")
		(net "M_F_CPU1_SB_DQ<11>")
	)
	(segment
		(start 157.5308 -219.42552)
		(end 157.257496 -219.42552)
		(width 0.18288)
		(layer "In2.Cu")
		(net "M_F_CPU1_SB_DQ<11>")
	)
	(segment
		(start 167.319198 -220.671898)
		(end 165.394386 -220.671898)
		(width 0.18288)
		(layer "In2.Cu")
		(net "M_F_CPU1_SB_DQ<11>")
	)
	(segment
		(start 176.896014 -220.266768)
		(end 176.27473 -220.266768)
		(width 0.18288)
		(layer "In2.Cu")
		(net "M_F_CPU1_SB_DQ<11>")
	)
	(segment
		(start 172.556932 -220.689932)
		(end 171.937426 -220.070426)
		(width 0.18288)
		(layer "In2.Cu")
		(net "M_F_CPU1_SB_DQ<11>")
	)
	(arc
		(start 139.177268 -230.41102)
		(mid 138.894566 -230.335244)
		(end 138.611864 -230.41102)
		(width 0.088646)
		(layer "In2.Cu")
		(net "M_F_CPU1_SB_DQ<11>")
	)
	(arc
		(start 139.834366 -230.335328)
		(mid 139.688043 -230.35459)
		(end 139.551664 -230.41102)
		(width 0.088646)
		(layer "In2.Cu")
		(net "M_F_CPU1_SB_DQ<11>")
	)
	(arc
		(start 137.202164 -231.224836)
		(mid 137.014966 -231.274979)
		(end 136.827768 -231.224836)
		(width 0.088646)
		(layer "In2.Cu")
		(net "M_F_CPU1_SB_DQ<11>")
	)
	(arc
		(start 136.262364 -231.224836)
		(mid 136.075166 -231.274979)
		(end 135.887968 -231.224836)
		(width 0.088646)
		(layer "In2.Cu")
		(net "M_F_CPU1_SB_DQ<11>")
	)
	(arc
		(start 139.551664 -230.41102)
		(mid 139.364466 -230.461163)
		(end 139.177268 -230.41102)
		(width 0.088646)
		(layer "In2.Cu")
		(net "M_F_CPU1_SB_DQ<11>")
	)
	(arc
		(start 135.74776 -231.142794)
		(mid 135.736776 -231.137221)
		(end 135.725154 -231.133142)
		(width 0.088646)
		(layer "In2.Cu")
		(net "M_F_CPU1_SB_DQ<11>")
	)
	(arc
		(start 138.611864 -230.41102)
		(mid 138.424666 -230.461163)
		(end 138.237468 -230.41102)
		(width 0.088646)
		(layer "In2.Cu")
		(net "M_F_CPU1_SB_DQ<11>")
	)
	(arc
		(start 137.672064 -230.41102)
		(mid 137.467729 -230.613625)
		(end 137.389616 -230.890572)
		(width 0.088646)
		(layer "In2.Cu")
		(net "M_F_CPU1_SB_DQ<11>")
	)
	(arc
		(start 137.389616 -230.900478)
		(mid 137.341937 -231.083378)
		(end 137.211054 -231.219756)
		(width 0.088646)
		(layer "In2.Cu")
		(net "M_F_CPU1_SB_DQ<11>")
	)
	(arc
		(start 138.237468 -230.41102)
		(mid 137.954766 -230.335244)
		(end 137.672064 -230.41102)
		(width 0.088646)
		(layer "In2.Cu")
		(net "M_F_CPU1_SB_DQ<11>")
	)
	(arc
		(start 136.827768 -231.224836)
		(mid 136.545066 -231.149094)
		(end 136.262364 -231.224836)
		(width 0.088646)
		(layer "In2.Cu")
		(net "M_F_CPU1_SB_DQ<11>")
	)
	(segment
		(start 184.210452 -221.96679)
		(end 185.544714 -221.96679)
		(width 0.20066)
		(layer "F.Cu")
		(net "M_F_CPU1_SB_DQ<10>")
	)
	(segment
		(start 176.896014 -221.96679)
		(end 178.000914 -221.96679)
		(width 0.20066)
		(layer "F.Cu")
		(net "M_F_CPU1_SB_DQ<10>")
	)
	(segment
		(start 183.136286 -222.403924)
		(end 183.340248 -222.199962)
		(width 0.20066)
		(layer "F.Cu")
		(net "M_F_CPU1_SB_DQ<10>")
	)
	(segment
		(start 178.000914 -221.96679)
		(end 179.699158 -221.96679)
		(width 0.20066)
		(layer "F.Cu")
		(net "M_F_CPU1_SB_DQ<10>")
	)
	(segment
		(start 183.340248 -222.199962)
		(end 183.340248 -221.94901)
		(width 0.20066)
		(layer "F.Cu")
		(net "M_F_CPU1_SB_DQ<10>")
	)
	(segment
		(start 180.131212 -222.398844)
		(end 180.423058 -222.398844)
		(width 0.20066)
		(layer "F.Cu")
		(net "M_F_CPU1_SB_DQ<10>")
	)
	(segment
		(start 183.340248 -221.94901)
		(end 183.574436 -221.714822)
		(width 0.20066)
		(layer "F.Cu")
		(net "M_F_CPU1_SB_DQ<10>")
	)
	(segment
		(start 182.455058 -222.403924)
		(end 183.136286 -222.403924)
		(width 0.20066)
		(layer "F.Cu")
		(net "M_F_CPU1_SB_DQ<10>")
	)
	(segment
		(start 180.427884 -222.398844)
		(end 180.434996 -222.391732)
		(width 0.1016)
		(layer "F.Cu")
		(net "M_F_CPU1_SB_DQ<10>")
	)
	(segment
		(start 180.423058 -222.398844)
		(end 180.427884 -222.398844)
		(width 0.101854)
		(layer "F.Cu")
		(net "M_F_CPU1_SB_DQ<10>")
	)
	(segment
		(start 183.574436 -221.714822)
		(end 183.958484 -221.714822)
		(width 0.20066)
		(layer "F.Cu")
		(net "M_F_CPU1_SB_DQ<10>")
	)
	(segment
		(start 179.699158 -221.96679)
		(end 180.131212 -222.398844)
		(width 0.20066)
		(layer "F.Cu")
		(net "M_F_CPU1_SB_DQ<10>")
	)
	(segment
		(start 183.958484 -221.714822)
		(end 184.210452 -221.96679)
		(width 0.20066)
		(layer "F.Cu")
		(net "M_F_CPU1_SB_DQ<10>")
	)
	(segment
		(start 180.434996 -222.391732)
		(end 182.442866 -222.391732)
		(width 0.1016)
		(layer "F.Cu")
		(net "M_F_CPU1_SB_DQ<10>")
	)
	(segment
		(start 182.442866 -222.391732)
		(end 182.455058 -222.403924)
		(width 0.1016)
		(layer "F.Cu")
		(net "M_F_CPU1_SB_DQ<10>")
	)
	(segment
		(start 134.665466 -232.250488)
		(end 134.665466 -231.714548)
		(width 0.20066)
		(layer "F.Cu")
		(net "M_F_CPU1_SB_DQ<10>")
	)
	(segment
		(start 163.53155 -222.658432)
		(end 162.340798 -222.658432)
		(width 0.18288)
		(layer "In2.Cu")
		(net "M_F_CPU1_SB_DQ<10>")
	)
	(segment
		(start 170.050968 -223.286828)
		(end 169.857928 -223.093788)
		(width 0.18288)
		(layer "In2.Cu")
		(net "M_F_CPU1_SB_DQ<10>")
	)
	(segment
		(start 162.340798 -222.658432)
		(end 161.950146 -222.26778)
		(width 0.18288)
		(layer "In2.Cu")
		(net "M_F_CPU1_SB_DQ<10>")
	)
	(segment
		(start 135.302752 -231.988614)
		(end 135.001254 -231.895396)
		(width 0.088646)
		(layer "In2.Cu")
		(net "M_F_CPU1_SB_DQ<10>")
	)
	(segment
		(start 139.535916 -231.149144)
		(end 139.364466 -231.149144)
		(width 0.088646)
		(layer "In2.Cu")
		(net "M_F_CPU1_SB_DQ<10>")
	)
	(segment
		(start 141.679422 -230.323136)
		(end 141.15034 -230.323136)
		(width 0.088646)
		(layer "In2.Cu")
		(net "M_F_CPU1_SB_DQ<10>")
	)
	(segment
		(start 159.36341 -221.530672)
		(end 159.18307 -221.711012)
		(width 0.18288)
		(layer "In2.Cu")
		(net "M_F_CPU1_SB_DQ<10>")
	)
	(segment
		(start 161.950146 -222.26778)
		(end 161.33318 -222.26778)
		(width 0.18288)
		(layer "In2.Cu")
		(net "M_F_CPU1_SB_DQ<10>")
	)
	(segment
		(start 146.832066 -230.323136)
		(end 141.679422 -230.323136)
		(width 0.18288)
		(layer "In2.Cu")
		(net "M_F_CPU1_SB_DQ<10>")
	)
	(segment
		(start 164.509958 -222.141542)
		(end 164.04844 -222.141542)
		(width 0.18288)
		(layer "In2.Cu")
		(net "M_F_CPU1_SB_DQ<10>")
	)
	(segment
		(start 154.61107 -222.544132)
		(end 146.832066 -230.323136)
		(width 0.18288)
		(layer "In2.Cu")
		(net "M_F_CPU1_SB_DQ<10>")
	)
	(segment
		(start 135.001254 -231.895396)
		(end 134.665466 -231.714548)
		(width 0.088646)
		(layer "In2.Cu")
		(net "M_F_CPU1_SB_DQ<10>")
	)
	(segment
		(start 176.333658 -223.158304)
		(end 176.032668 -223.459294)
		(width 0.18288)
		(layer "In2.Cu")
		(net "M_F_CPU1_SB_DQ<10>")
	)
	(segment
		(start 169.181272 -222.33255)
		(end 168.790112 -222.72371)
		(width 0.18288)
		(layer "In2.Cu")
		(net "M_F_CPU1_SB_DQ<10>")
	)
	(segment
		(start 169.857928 -223.093788)
		(end 169.857928 -222.561404)
		(width 0.18288)
		(layer "In2.Cu")
		(net "M_F_CPU1_SB_DQ<10>")
	)
	(segment
		(start 160.596072 -221.530672)
		(end 159.36341 -221.530672)
		(width 0.18288)
		(layer "In2.Cu")
		(net "M_F_CPU1_SB_DQ<10>")
	)
	(segment
		(start 169.629074 -222.33255)
		(end 169.181272 -222.33255)
		(width 0.18288)
		(layer "In2.Cu")
		(net "M_F_CPU1_SB_DQ<10>")
	)
	(segment
		(start 164.772848 -222.404432)
		(end 164.509958 -222.141542)
		(width 0.18288)
		(layer "In2.Cu")
		(net "M_F_CPU1_SB_DQ<10>")
	)
	(segment
		(start 156.433266 -222.544132)
		(end 154.61107 -222.544132)
		(width 0.18288)
		(layer "In2.Cu")
		(net "M_F_CPU1_SB_DQ<10>")
	)
	(segment
		(start 139.87018 -230.81488)
		(end 139.535916 -231.149144)
		(width 0.088646)
		(layer "In2.Cu")
		(net "M_F_CPU1_SB_DQ<10>")
	)
	(segment
		(start 176.333658 -222.15983)
		(end 176.333658 -223.158304)
		(width 0.18288)
		(layer "In2.Cu")
		(net "M_F_CPU1_SB_DQ<10>")
	)
	(segment
		(start 176.896014 -221.96679)
		(end 176.526698 -221.96679)
		(width 0.18288)
		(layer "In2.Cu")
		(net "M_F_CPU1_SB_DQ<10>")
	)
	(segment
		(start 171.009056 -223.093788)
		(end 170.816016 -223.286828)
		(width 0.18288)
		(layer "In2.Cu")
		(net "M_F_CPU1_SB_DQ<10>")
	)
	(segment
		(start 176.526698 -221.96679)
		(end 176.333658 -222.15983)
		(width 0.18288)
		(layer "In2.Cu")
		(net "M_F_CPU1_SB_DQ<10>")
	)
	(segment
		(start 137.859516 -231.696006)
		(end 137.859516 -231.714548)
		(width 0.088646)
		(layer "In2.Cu")
		(net "M_F_CPU1_SB_DQ<10>")
	)
	(segment
		(start 172.317664 -222.389954)
		(end 172.155866 -222.228156)
		(width 0.18288)
		(layer "In2.Cu")
		(net "M_F_CPU1_SB_DQ<10>")
	)
	(segment
		(start 169.857928 -222.561404)
		(end 169.629074 -222.33255)
		(width 0.18288)
		(layer "In2.Cu")
		(net "M_F_CPU1_SB_DQ<10>")
	)
	(segment
		(start 158.53537 -221.711012)
		(end 158.320486 -221.496128)
		(width 0.18288)
		(layer "In2.Cu")
		(net "M_F_CPU1_SB_DQ<10>")
	)
	(segment
		(start 141.15034 -230.323136)
		(end 140.658596 -230.81488)
		(width 0.088646)
		(layer "In2.Cu")
		(net "M_F_CPU1_SB_DQ<10>")
	)
	(segment
		(start 167.537638 -222.72371)
		(end 167.21836 -222.404432)
		(width 0.18288)
		(layer "In2.Cu")
		(net "M_F_CPU1_SB_DQ<10>")
	)
	(segment
		(start 168.790112 -222.72371)
		(end 167.537638 -222.72371)
		(width 0.18288)
		(layer "In2.Cu")
		(net "M_F_CPU1_SB_DQ<10>")
	)
	(segment
		(start 170.816016 -223.286828)
		(end 170.050968 -223.286828)
		(width 0.18288)
		(layer "In2.Cu")
		(net "M_F_CPU1_SB_DQ<10>")
	)
	(segment
		(start 171.40809 -222.228156)
		(end 171.009056 -222.62719)
		(width 0.18288)
		(layer "In2.Cu")
		(net "M_F_CPU1_SB_DQ<10>")
	)
	(segment
		(start 171.009056 -222.62719)
		(end 171.009056 -223.093788)
		(width 0.18288)
		(layer "In2.Cu")
		(net "M_F_CPU1_SB_DQ<10>")
	)
	(segment
		(start 159.18307 -221.711012)
		(end 158.53537 -221.711012)
		(width 0.18288)
		(layer "In2.Cu")
		(net "M_F_CPU1_SB_DQ<10>")
	)
	(segment
		(start 175.525684 -223.459294)
		(end 175.283622 -223.217232)
		(width 0.18288)
		(layer "In2.Cu")
		(net "M_F_CPU1_SB_DQ<10>")
	)
	(segment
		(start 158.320486 -221.496128)
		(end 157.48127 -221.496128)
		(width 0.18288)
		(layer "In2.Cu")
		(net "M_F_CPU1_SB_DQ<10>")
	)
	(segment
		(start 164.04844 -222.141542)
		(end 163.53155 -222.658432)
		(width 0.18288)
		(layer "In2.Cu")
		(net "M_F_CPU1_SB_DQ<10>")
	)
	(segment
		(start 140.658596 -230.81488)
		(end 139.87018 -230.81488)
		(width 0.088646)
		(layer "In2.Cu")
		(net "M_F_CPU1_SB_DQ<10>")
	)
	(segment
		(start 175.283622 -223.217232)
		(end 175.283622 -222.722948)
		(width 0.18288)
		(layer "In2.Cu")
		(net "M_F_CPU1_SB_DQ<10>")
	)
	(segment
		(start 157.48127 -221.496128)
		(end 156.433266 -222.544132)
		(width 0.18288)
		(layer "In2.Cu")
		(net "M_F_CPU1_SB_DQ<10>")
	)
	(segment
		(start 175.283622 -222.722948)
		(end 174.950628 -222.389954)
		(width 0.18288)
		(layer "In2.Cu")
		(net "M_F_CPU1_SB_DQ<10>")
	)
	(segment
		(start 172.155866 -222.228156)
		(end 171.40809 -222.228156)
		(width 0.18288)
		(layer "In2.Cu")
		(net "M_F_CPU1_SB_DQ<10>")
	)
	(segment
		(start 174.950628 -222.389954)
		(end 172.317664 -222.389954)
		(width 0.18288)
		(layer "In2.Cu")
		(net "M_F_CPU1_SB_DQ<10>")
	)
	(segment
		(start 167.21836 -222.404432)
		(end 164.772848 -222.404432)
		(width 0.18288)
		(layer "In2.Cu")
		(net "M_F_CPU1_SB_DQ<10>")
	)
	(segment
		(start 161.33318 -222.26778)
		(end 160.596072 -221.530672)
		(width 0.18288)
		(layer "In2.Cu")
		(net "M_F_CPU1_SB_DQ<10>")
	)
	(segment
		(start 176.032668 -223.459294)
		(end 175.525684 -223.459294)
		(width 0.18288)
		(layer "In2.Cu")
		(net "M_F_CPU1_SB_DQ<10>")
	)
	(arc
		(start 139.081764 -231.224836)
		(mid 138.894566 -231.274979)
		(end 138.707368 -231.224836)
		(width 0.088646)
		(layer "In2.Cu")
		(net "M_F_CPU1_SB_DQ<10>")
	)
	(arc
		(start 135.418068 -232.038906)
		(mid 135.361813 -232.010542)
		(end 135.302752 -231.988614)
		(width 0.088646)
		(layer "In2.Cu")
		(net "M_F_CPU1_SB_DQ<10>")
	)
	(arc
		(start 136.357868 -232.038906)
		(mid 136.075166 -231.96313)
		(end 135.792464 -232.038906)
		(width 0.088646)
		(layer "In2.Cu")
		(net "M_F_CPU1_SB_DQ<10>")
	)
	(arc
		(start 136.732264 -232.038906)
		(mid 136.545066 -232.089049)
		(end 136.357868 -232.038906)
		(width 0.088646)
		(layer "In2.Cu")
		(net "M_F_CPU1_SB_DQ<10>")
	)
	(arc
		(start 137.859516 -231.714548)
		(mid 137.672217 -232.038989)
		(end 137.297668 -232.038906)
		(width 0.088646)
		(layer "In2.Cu")
		(net "M_F_CPU1_SB_DQ<10>")
	)
	(arc
		(start 139.364466 -231.149144)
		(mid 139.218143 -231.168406)
		(end 139.081764 -231.224836)
		(width 0.088646)
		(layer "In2.Cu")
		(net "M_F_CPU1_SB_DQ<10>")
	)
	(arc
		(start 137.297668 -232.038906)
		(mid 137.014966 -231.96313)
		(end 136.732264 -232.038906)
		(width 0.088646)
		(layer "In2.Cu")
		(net "M_F_CPU1_SB_DQ<10>")
	)
	(arc
		(start 138.707368 -231.224836)
		(mid 138.149994 -231.220287)
		(end 137.859516 -231.696006)
		(width 0.088646)
		(layer "In2.Cu")
		(net "M_F_CPU1_SB_DQ<10>")
	)
	(arc
		(start 135.792464 -232.038906)
		(mid 135.605266 -232.089049)
		(end 135.418068 -232.038906)
		(width 0.088646)
		(layer "In2.Cu")
		(net "M_F_CPU1_SB_DQ<10>")
	)
	(segment
		(start 175.421544 -232.166668)
		(end 173.900846 -232.166668)
		(width 0.20066)
		(layer "F.Cu")
		(net "M_F_CPU1_SB_DQ<0>")
	)
	(segment
		(start 179.004976 -231.741726)
		(end 176.843182 -231.741726)
		(width 0.1016)
		(layer "F.Cu")
		(net "M_F_CPU1_SB_DQ<0>")
	)
	(segment
		(start 176.451514 -231.741726)
		(end 176.333404 -231.859836)
		(width 0.20066)
		(layer "F.Cu")
		(net "M_F_CPU1_SB_DQ<0>")
	)
	(segment
		(start 179.421282 -231.735376)
		(end 179.011326 -231.735376)
		(width 0.20066)
		(layer "F.Cu")
		(net "M_F_CPU1_SB_DQ<0>")
	)
	(segment
		(start 176.843182 -231.741726)
		(end 176.796192 -231.741726)
		(width 0.101854)
		(layer "F.Cu")
		(net "M_F_CPU1_SB_DQ<0>")
	)
	(segment
		(start 175.67021 -232.415334)
		(end 175.421544 -232.166668)
		(width 0.20066)
		(layer "F.Cu")
		(net "M_F_CPU1_SB_DQ<0>")
	)
	(segment
		(start 179.852828 -232.166922)
		(end 179.421282 -231.735376)
		(width 0.20066)
		(layer "F.Cu")
		(net "M_F_CPU1_SB_DQ<0>")
	)
	(segment
		(start 176.333404 -231.859836)
		(end 176.333404 -232.227374)
		(width 0.20066)
		(layer "F.Cu")
		(net "M_F_CPU1_SB_DQ<0>")
	)
	(segment
		(start 176.145444 -232.415334)
		(end 175.67021 -232.415334)
		(width 0.20066)
		(layer "F.Cu")
		(net "M_F_CPU1_SB_DQ<0>")
	)
	(segment
		(start 179.011326 -231.735376)
		(end 179.004976 -231.741726)
		(width 0.1016)
		(layer "F.Cu")
		(net "M_F_CPU1_SB_DQ<0>")
	)
	(segment
		(start 130.436366 -239.575086)
		(end 130.436366 -239.0394)
		(width 0.20066)
		(layer "F.Cu")
		(net "M_F_CPU1_SB_DQ<0>")
	)
	(segment
		(start 173.900846 -232.166668)
		(end 172.795946 -232.166668)
		(width 0.20066)
		(layer "F.Cu")
		(net "M_F_CPU1_SB_DQ<0>")
	)
	(segment
		(start 181.444646 -232.166668)
		(end 181.444392 -232.166922)
		(width 0.20066)
		(layer "F.Cu")
		(net "M_F_CPU1_SB_DQ<0>")
	)
	(segment
		(start 176.796192 -231.741726)
		(end 176.451514 -231.741726)
		(width 0.20066)
		(layer "F.Cu")
		(net "M_F_CPU1_SB_DQ<0>")
	)
	(segment
		(start 176.333404 -232.227374)
		(end 176.145444 -232.415334)
		(width 0.20066)
		(layer "F.Cu")
		(net "M_F_CPU1_SB_DQ<0>")
	)
	(segment
		(start 130.436112 -239.57534)
		(end 130.436366 -239.575086)
		(width 0.20066)
		(layer "F.Cu")
		(net "M_F_CPU1_SB_DQ<0>")
	)
	(segment
		(start 181.444392 -232.166922)
		(end 179.852828 -232.166922)
		(width 0.20066)
		(layer "F.Cu")
		(net "M_F_CPU1_SB_DQ<0>")
	)
	(segment
		(start 158.52648 -232.549446)
		(end 158.52648 -231.926384)
		(width 0.18288)
		(layer "In4.Cu")
		(net "M_F_CPU1_SB_DQ<0>")
	)
	(segment
		(start 141.001496 -238.313468)
		(end 140.899134 -238.313468)
		(width 0.088646)
		(layer "In4.Cu")
		(net "M_F_CPU1_SB_DQ<0>")
	)
	(segment
		(start 138.237214 -239.528858)
		(end 138.222482 -239.537494)
		(width 0.088646)
		(layer "In4.Cu")
		(net "M_F_CPU1_SB_DQ<0>")
	)
	(segment
		(start 156.845762 -232.543604)
		(end 156.662882 -232.726484)
		(width 0.18288)
		(layer "In4.Cu")
		(net "M_F_CPU1_SB_DQ<0>")
	)
	(segment
		(start 160.7312 -231.743504)
		(end 159.40278 -231.743504)
		(width 0.18288)
		(layer "In4.Cu")
		(net "M_F_CPU1_SB_DQ<0>")
	)
	(segment
		(start 155.969462 -231.743504)
		(end 155.641802 -231.743504)
		(width 0.18288)
		(layer "In4.Cu")
		(net "M_F_CPU1_SB_DQ<0>")
	)
	(segment
		(start 132.978906 -239.532414)
		(end 132.973064 -239.528858)
		(width 0.088646)
		(layer "In4.Cu")
		(net "M_F_CPU1_SB_DQ<0>")
	)
	(segment
		(start 154.765502 -231.926384)
		(end 154.582622 -231.743504)
		(width 0.18288)
		(layer "In4.Cu")
		(net "M_F_CPU1_SB_DQ<0>")
	)
	(segment
		(start 145.117566 -235.837984)
		(end 142.642082 -238.313468)
		(width 0.18288)
		(layer "In4.Cu")
		(net "M_F_CPU1_SB_DQ<0>")
	)
	(segment
		(start 130.701542 -239.304576)
		(end 130.436366 -239.0394)
		(width 0.088646)
		(layer "In4.Cu")
		(net "M_F_CPU1_SB_DQ<0>")
	)
	(segment
		(start 169.75709 -231.50322)
		(end 168.561512 -231.50322)
		(width 0.18288)
		(layer "In4.Cu")
		(net "M_F_CPU1_SB_DQ<0>")
	)
	(segment
		(start 170.185334 -231.931718)
		(end 169.971212 -231.717596)
		(width 0.18288)
		(layer "In4.Cu")
		(net "M_F_CPU1_SB_DQ<0>")
	)
	(segment
		(start 172.795946 -231.915208)
		(end 172.383958 -231.50322)
		(width 0.18288)
		(layer "In4.Cu")
		(net "M_F_CPU1_SB_DQ<0>")
	)
	(segment
		(start 158.52648 -231.926384)
		(end 158.3436 -231.743504)
		(width 0.18288)
		(layer "In4.Cu")
		(net "M_F_CPU1_SB_DQ<0>")
	)
	(segment
		(start 159.2199 -231.926384)
		(end 159.2199 -232.549446)
		(width 0.18288)
		(layer "In4.Cu")
		(net "M_F_CPU1_SB_DQ<0>")
	)
	(segment
		(start 162.938968 -231.76484)
		(end 162.756088 -231.58196)
		(width 0.18288)
		(layer "In4.Cu")
		(net "M_F_CPU1_SB_DQ<0>")
	)
	(segment
		(start 172.795946 -232.166668)
		(end 172.795946 -231.915208)
		(width 0.18288)
		(layer "In4.Cu")
		(net "M_F_CPU1_SB_DQ<0>")
	)
	(segment
		(start 168.239186 -232.19791)
		(end 167.933624 -232.503472)
		(width 0.18288)
		(layer "In4.Cu")
		(net "M_F_CPU1_SB_DQ<0>")
	)
	(segment
		(start 149.583902 -235.837984)
		(end 145.117566 -235.837984)
		(width 0.18288)
		(layer "In4.Cu")
		(net "M_F_CPU1_SB_DQ<0>")
	)
	(segment
		(start 162.573208 -230.892096)
		(end 161.582608 -230.892096)
		(width 0.18288)
		(layer "In4.Cu")
		(net "M_F_CPU1_SB_DQ<0>")
	)
	(segment
		(start 169.971212 -231.717342)
		(end 169.75709 -231.50322)
		(width 0.18288)
		(layer "In4.Cu")
		(net "M_F_CPU1_SB_DQ<0>")
	)
	(segment
		(start 162.756088 -231.074976)
		(end 162.573208 -230.892096)
		(width 0.18288)
		(layer "In4.Cu")
		(net "M_F_CPU1_SB_DQ<0>")
	)
	(segment
		(start 139.916408 -239.095534)
		(end 139.162282 -239.537494)
		(width 0.088646)
		(layer "In4.Cu")
		(net "M_F_CPU1_SB_DQ<0>")
	)
	(segment
		(start 171.306998 -231.50322)
		(end 171.092876 -231.717342)
		(width 0.18288)
		(layer "In4.Cu")
		(net "M_F_CPU1_SB_DQ<0>")
	)
	(segment
		(start 135.792464 -239.528858)
		(end 135.788146 -239.526318)
		(width 0.088646)
		(layer "In4.Cu")
		(net "M_F_CPU1_SB_DQ<0>")
	)
	(segment
		(start 155.458922 -231.926384)
		(end 155.458922 -232.543604)
		(width 0.18288)
		(layer "In4.Cu")
		(net "M_F_CPU1_SB_DQ<0>")
	)
	(segment
		(start 156.335222 -232.726484)
		(end 156.152342 -232.543604)
		(width 0.18288)
		(layer "In4.Cu")
		(net "M_F_CPU1_SB_DQ<0>")
	)
	(segment
		(start 134.852664 -239.528858)
		(end 134.848854 -239.526826)
		(width 0.088646)
		(layer "In4.Cu")
		(net "M_F_CPU1_SB_DQ<0>")
	)
	(segment
		(start 156.662882 -232.726484)
		(end 156.335222 -232.726484)
		(width 0.18288)
		(layer "In4.Cu")
		(net "M_F_CPU1_SB_DQ<0>")
	)
	(segment
		(start 162.756088 -231.58196)
		(end 162.756088 -231.074976)
		(width 0.18288)
		(layer "In4.Cu")
		(net "M_F_CPU1_SB_DQ<0>")
	)
	(segment
		(start 163.449508 -231.58196)
		(end 163.266628 -231.76484)
		(width 0.18288)
		(layer "In4.Cu")
		(net "M_F_CPU1_SB_DQ<0>")
	)
	(segment
		(start 156.845762 -231.926384)
		(end 156.845762 -232.543604)
		(width 0.18288)
		(layer "In4.Cu")
		(net "M_F_CPU1_SB_DQ<0>")
	)
	(segment
		(start 163.902136 -230.892096)
		(end 163.632388 -230.892096)
		(width 0.18288)
		(layer "In4.Cu")
		(net "M_F_CPU1_SB_DQ<0>")
	)
	(segment
		(start 161.582608 -230.892096)
		(end 160.7312 -231.743504)
		(width 0.18288)
		(layer "In4.Cu")
		(net "M_F_CPU1_SB_DQ<0>")
	)
	(segment
		(start 132.039106 -239.532414)
		(end 132.033264 -239.528858)
		(width 0.088646)
		(layer "In4.Cu")
		(net "M_F_CPU1_SB_DQ<0>")
	)
	(segment
		(start 170.878754 -231.931718)
		(end 170.185334 -231.931718)
		(width 0.18288)
		(layer "In4.Cu")
		(net "M_F_CPU1_SB_DQ<0>")
	)
	(segment
		(start 155.458922 -232.543604)
		(end 155.276042 -232.726484)
		(width 0.18288)
		(layer "In4.Cu")
		(net "M_F_CPU1_SB_DQ<0>")
	)
	(segment
		(start 172.383958 -231.50322)
		(end 171.306998 -231.50322)
		(width 0.18288)
		(layer "In4.Cu")
		(net "M_F_CPU1_SB_DQ<0>")
	)
	(segment
		(start 154.582622 -231.743504)
		(end 153.678382 -231.743504)
		(width 0.18288)
		(layer "In4.Cu")
		(net "M_F_CPU1_SB_DQ<0>")
	)
	(segment
		(start 140.326364 -238.886238)
		(end 139.916408 -239.095534)
		(width 0.088646)
		(layer "In4.Cu")
		(net "M_F_CPU1_SB_DQ<0>")
	)
	(segment
		(start 156.152342 -232.543604)
		(end 156.152342 -231.926384)
		(width 0.18288)
		(layer "In4.Cu")
		(net "M_F_CPU1_SB_DQ<0>")
	)
	(segment
		(start 136.357614 -239.528858)
		(end 136.3472 -239.534954)
		(width 0.088646)
		(layer "In4.Cu")
		(net "M_F_CPU1_SB_DQ<0>")
	)
	(segment
		(start 163.266628 -231.76484)
		(end 162.938968 -231.76484)
		(width 0.18288)
		(layer "In4.Cu")
		(net "M_F_CPU1_SB_DQ<0>")
	)
	(segment
		(start 167.933624 -232.503472)
		(end 165.186106 -232.503472)
		(width 0.18288)
		(layer "In4.Cu")
		(net "M_F_CPU1_SB_DQ<0>")
	)
	(segment
		(start 168.239186 -231.825546)
		(end 168.239186 -232.19791)
		(width 0.18288)
		(layer "In4.Cu")
		(net "M_F_CPU1_SB_DQ<0>")
	)
	(segment
		(start 165.026086 -232.016046)
		(end 163.902136 -230.892096)
		(width 0.18288)
		(layer "In4.Cu")
		(net "M_F_CPU1_SB_DQ<0>")
	)
	(segment
		(start 153.678382 -231.743504)
		(end 149.583902 -235.837984)
		(width 0.18288)
		(layer "In4.Cu")
		(net "M_F_CPU1_SB_DQ<0>")
	)
	(segment
		(start 159.40278 -231.743504)
		(end 159.2199 -231.926384)
		(width 0.18288)
		(layer "In4.Cu")
		(net "M_F_CPU1_SB_DQ<0>")
	)
	(segment
		(start 165.026086 -232.343452)
		(end 165.026086 -232.016046)
		(width 0.18288)
		(layer "In4.Cu")
		(net "M_F_CPU1_SB_DQ<0>")
	)
	(segment
		(start 133.912864 -239.528858)
		(end 133.908546 -239.526318)
		(width 0.088646)
		(layer "In4.Cu")
		(net "M_F_CPU1_SB_DQ<0>")
	)
	(segment
		(start 157.028642 -231.743504)
		(end 156.845762 -231.926384)
		(width 0.18288)
		(layer "In4.Cu")
		(net "M_F_CPU1_SB_DQ<0>")
	)
	(segment
		(start 159.03702 -232.732326)
		(end 158.70936 -232.732326)
		(width 0.18288)
		(layer "In4.Cu")
		(net "M_F_CPU1_SB_DQ<0>")
	)
	(segment
		(start 159.2199 -232.549446)
		(end 159.03702 -232.732326)
		(width 0.18288)
		(layer "In4.Cu")
		(net "M_F_CPU1_SB_DQ<0>")
	)
	(segment
		(start 137.297414 -239.528858)
		(end 137.282682 -239.537494)
		(width 0.088646)
		(layer "In4.Cu")
		(net "M_F_CPU1_SB_DQ<0>")
	)
	(segment
		(start 155.641802 -231.743504)
		(end 155.458922 -231.926384)
		(width 0.18288)
		(layer "In4.Cu")
		(net "M_F_CPU1_SB_DQ<0>")
	)
	(segment
		(start 134.858506 -239.532414)
		(end 134.852664 -239.528858)
		(width 0.088646)
		(layer "In4.Cu")
		(net "M_F_CPU1_SB_DQ<0>")
	)
	(segment
		(start 163.632388 -230.892096)
		(end 163.449508 -231.074976)
		(width 0.18288)
		(layer "In4.Cu")
		(net "M_F_CPU1_SB_DQ<0>")
	)
	(segment
		(start 132.033264 -239.528858)
		(end 132.027422 -239.525556)
		(width 0.088646)
		(layer "In4.Cu")
		(net "M_F_CPU1_SB_DQ<0>")
	)
	(segment
		(start 158.3436 -231.743504)
		(end 157.028642 -231.743504)
		(width 0.18288)
		(layer "In4.Cu")
		(net "M_F_CPU1_SB_DQ<0>")
	)
	(segment
		(start 163.449508 -231.074976)
		(end 163.449508 -231.58196)
		(width 0.18288)
		(layer "In4.Cu")
		(net "M_F_CPU1_SB_DQ<0>")
	)
	(segment
		(start 142.642082 -238.313468)
		(end 141.001496 -238.313468)
		(width 0.18288)
		(layer "In4.Cu")
		(net "M_F_CPU1_SB_DQ<0>")
	)
	(segment
		(start 155.276042 -232.726484)
		(end 154.948382 -232.726484)
		(width 0.18288)
		(layer "In4.Cu")
		(net "M_F_CPU1_SB_DQ<0>")
	)
	(segment
		(start 171.092876 -231.717342)
		(end 171.092876 -231.717596)
		(width 0.18288)
		(layer "In4.Cu")
		(net "M_F_CPU1_SB_DQ<0>")
	)
	(segment
		(start 130.876802 -239.304576)
		(end 130.701542 -239.304576)
		(width 0.088646)
		(layer "In4.Cu")
		(net "M_F_CPU1_SB_DQ<0>")
	)
	(segment
		(start 154.765502 -232.543604)
		(end 154.765502 -231.926384)
		(width 0.18288)
		(layer "In4.Cu")
		(net "M_F_CPU1_SB_DQ<0>")
	)
	(segment
		(start 156.152342 -231.926384)
		(end 155.969462 -231.743504)
		(width 0.18288)
		(layer "In4.Cu")
		(net "M_F_CPU1_SB_DQ<0>")
	)
	(segment
		(start 165.186106 -232.503472)
		(end 165.026086 -232.343452)
		(width 0.18288)
		(layer "In4.Cu")
		(net "M_F_CPU1_SB_DQ<0>")
	)
	(segment
		(start 169.971212 -231.717596)
		(end 169.971212 -231.717342)
		(width 0.18288)
		(layer "In4.Cu")
		(net "M_F_CPU1_SB_DQ<0>")
	)
	(segment
		(start 132.973064 -239.528858)
		(end 132.967222 -239.525556)
		(width 0.088646)
		(layer "In4.Cu")
		(net "M_F_CPU1_SB_DQ<0>")
	)
	(segment
		(start 158.70936 -232.732326)
		(end 158.52648 -232.549446)
		(width 0.18288)
		(layer "In4.Cu")
		(net "M_F_CPU1_SB_DQ<0>")
	)
	(segment
		(start 168.561512 -231.50322)
		(end 168.239186 -231.825546)
		(width 0.18288)
		(layer "In4.Cu")
		(net "M_F_CPU1_SB_DQ<0>")
	)
	(segment
		(start 171.092876 -231.717596)
		(end 170.878754 -231.931718)
		(width 0.18288)
		(layer "In4.Cu")
		(net "M_F_CPU1_SB_DQ<0>")
	)
	(segment
		(start 140.899134 -238.313468)
		(end 140.326364 -238.886238)
		(width 0.088646)
		(layer "In4.Cu")
		(net "M_F_CPU1_SB_DQ<0>")
	)
	(segment
		(start 154.948382 -232.726484)
		(end 154.765502 -232.543604)
		(width 0.18288)
		(layer "In4.Cu")
		(net "M_F_CPU1_SB_DQ<0>")
	)
	(arc
		(start 134.478014 -239.528858)
		(mid 134.195456 -239.604507)
		(end 133.912864 -239.528858)
		(width 0.088646)
		(layer "In4.Cu")
		(net "M_F_CPU1_SB_DQ<0>")
	)
	(arc
		(start 132.967222 -239.525556)
		(mid 132.782367 -239.478606)
		(end 132.598414 -239.528858)
		(width 0.088646)
		(layer "In4.Cu")
		(net "M_F_CPU1_SB_DQ<0>")
	)
	(arc
		(start 139.162282 -239.537494)
		(mid 138.885807 -239.604814)
		(end 138.61161 -239.528858)
		(width 0.088646)
		(layer "In4.Cu")
		(net "M_F_CPU1_SB_DQ<0>")
	)
	(arc
		(start 138.222482 -239.537494)
		(mid 137.946007 -239.604814)
		(end 137.67181 -239.528858)
		(width 0.088646)
		(layer "In4.Cu")
		(net "M_F_CPU1_SB_DQ<0>")
	)
	(arc
		(start 137.67181 -239.528858)
		(mid 137.484612 -239.478715)
		(end 137.297414 -239.528858)
		(width 0.088646)
		(layer "In4.Cu")
		(net "M_F_CPU1_SB_DQ<0>")
	)
	(arc
		(start 138.61161 -239.528858)
		(mid 138.424412 -239.478715)
		(end 138.237214 -239.528858)
		(width 0.088646)
		(layer "In4.Cu")
		(net "M_F_CPU1_SB_DQ<0>")
	)
	(arc
		(start 136.73201 -239.528858)
		(mid 136.544812 -239.478715)
		(end 136.357614 -239.528858)
		(width 0.088646)
		(layer "In4.Cu")
		(net "M_F_CPU1_SB_DQ<0>")
	)
	(arc
		(start 133.908546 -239.526318)
		(mid 133.723051 -239.478649)
		(end 133.538214 -239.528858)
		(width 0.088646)
		(layer "In4.Cu")
		(net "M_F_CPU1_SB_DQ<0>")
	)
	(arc
		(start 135.417814 -239.528858)
		(mid 135.13864 -239.604623)
		(end 134.858506 -239.532414)
		(width 0.088646)
		(layer "In4.Cu")
		(net "M_F_CPU1_SB_DQ<0>")
	)
	(arc
		(start 135.788146 -239.526318)
		(mid 135.602651 -239.478649)
		(end 135.417814 -239.528858)
		(width 0.088646)
		(layer "In4.Cu")
		(net "M_F_CPU1_SB_DQ<0>")
	)
	(arc
		(start 132.027422 -239.525556)
		(mid 131.842567 -239.478606)
		(end 131.658614 -239.528858)
		(width 0.088646)
		(layer "In4.Cu")
		(net "M_F_CPU1_SB_DQ<0>")
	)
	(arc
		(start 134.848854 -239.526826)
		(mid 134.663164 -239.478748)
		(end 134.478014 -239.528858)
		(width 0.088646)
		(layer "In4.Cu")
		(net "M_F_CPU1_SB_DQ<0>")
	)
	(arc
		(start 137.282682 -239.537494)
		(mid 137.006207 -239.604814)
		(end 136.73201 -239.528858)
		(width 0.088646)
		(layer "In4.Cu")
		(net "M_F_CPU1_SB_DQ<0>")
	)
	(arc
		(start 132.598414 -239.528858)
		(mid 132.31924 -239.604623)
		(end 132.039106 -239.532414)
		(width 0.088646)
		(layer "In4.Cu")
		(net "M_F_CPU1_SB_DQ<0>")
	)
	(arc
		(start 133.538214 -239.528858)
		(mid 133.25904 -239.604623)
		(end 132.978906 -239.532414)
		(width 0.088646)
		(layer "In4.Cu")
		(net "M_F_CPU1_SB_DQ<0>")
	)
	(arc
		(start 136.3472 -239.534954)
		(mid 136.069022 -239.604677)
		(end 135.792464 -239.528858)
		(width 0.088646)
		(layer "In4.Cu")
		(net "M_F_CPU1_SB_DQ<0>")
	)
	(arc
		(start 131.658614 -239.528858)
		(mid 131.220072 -239.582726)
		(end 130.876802 -239.304576)
		(width 0.088646)
		(layer "In4.Cu")
		(net "M_F_CPU1_SB_DQ<0>")
	)
	(segment
		(start 133.725666 -243.644928)
		(end 133.725666 -243.108988)
		(width 0.20066)
		(layer "F.Cu")
		(net "M_F_CPU1_SB_CS_N<3>")
	)
	(segment
		(start 178.000914 -244.916706)
		(end 176.896014 -244.916706)
		(width 0.20066)
		(layer "F.Cu")
		(net "M_F_CPU1_SB_CS_N<3>")
	)
	(segment
		(start 176.159922 -244.976396)
		(end 175.949356 -245.186962)
		(width 0.18288)
		(layer "In2.Cu")
		(net "M_F_CPU1_SB_CS_N<3>")
	)
	(segment
		(start 150.792688 -245.352316)
		(end 140.144246 -245.352316)
		(width 0.18288)
		(layer "In2.Cu")
		(net "M_F_CPU1_SB_CS_N<3>")
	)
	(segment
		(start 169.080688 -243.640864)
		(end 168.749726 -243.971826)
		(width 0.18288)
		(layer "In2.Cu")
		(net "M_F_CPU1_SB_CS_N<3>")
	)
	(segment
		(start 134.382764 -243.598446)
		(end 134.376668 -243.59489)
		(width 0.088646)
		(layer "In2.Cu")
		(net "M_F_CPU1_SB_CS_N<3>")
	)
	(segment
		(start 136.271254 -243.603526)
		(end 136.262364 -243.598446)
		(width 0.088646)
		(layer "In2.Cu")
		(net "M_F_CPU1_SB_CS_N<3>")
	)
	(segment
		(start 170.514518 -243.423186)
		(end 170.29684 -243.640864)
		(width 0.18288)
		(layer "In2.Cu")
		(net "M_F_CPU1_SB_CS_N<3>")
	)
	(segment
		(start 139.759436 -245.737126)
		(end 139.121896 -245.737126)
		(width 0.18288)
		(layer "In2.Cu")
		(net "M_F_CPU1_SB_CS_N<3>")
	)
	(segment
		(start 159.583374 -244.491002)
		(end 156.783532 -244.491002)
		(width 0.18288)
		(layer "In2.Cu")
		(net "M_F_CPU1_SB_CS_N<3>")
	)
	(segment
		(start 175.441356 -244.650768)
		(end 175.270668 -244.48008)
		(width 0.18288)
		(layer "In2.Cu")
		(net "M_F_CPU1_SB_CS_N<3>")
	)
	(segment
		(start 176.159922 -244.650768)
		(end 176.159922 -244.976396)
		(width 0.18288)
		(layer "In2.Cu")
		(net "M_F_CPU1_SB_CS_N<3>")
	)
	(segment
		(start 175.270668 -244.48008)
		(end 174.540926 -244.48008)
		(width 0.18288)
		(layer "In2.Cu")
		(net "M_F_CPU1_SB_CS_N<3>")
	)
	(segment
		(start 172.519594 -244.490748)
		(end 172.22978 -244.200934)
		(width 0.18288)
		(layer "In2.Cu")
		(net "M_F_CPU1_SB_CS_N<3>")
	)
	(segment
		(start 151.26716 -245.826788)
		(end 150.792688 -245.352316)
		(width 0.18288)
		(layer "In2.Cu")
		(net "M_F_CPU1_SB_CS_N<3>")
	)
	(segment
		(start 155.447746 -245.826788)
		(end 151.26716 -245.826788)
		(width 0.18288)
		(layer "In2.Cu")
		(net "M_F_CPU1_SB_CS_N<3>")
	)
	(segment
		(start 162.358324 -243.318538)
		(end 162.03422 -243.642642)
		(width 0.18288)
		(layer "In2.Cu")
		(net "M_F_CPU1_SB_CS_N<3>")
	)
	(segment
		(start 167.354504 -243.642642)
		(end 164.692584 -243.642642)
		(width 0.18288)
		(layer "In2.Cu")
		(net "M_F_CPU1_SB_CS_N<3>")
	)
	(segment
		(start 170.29684 -243.640864)
		(end 169.080688 -243.640864)
		(width 0.18288)
		(layer "In2.Cu")
		(net "M_F_CPU1_SB_CS_N<3>")
	)
	(segment
		(start 134.103872 -243.17452)
		(end 134.03834 -243.108988)
		(width 0.088646)
		(layer "In2.Cu")
		(net "M_F_CPU1_SB_CS_N<3>")
	)
	(segment
		(start 172.22978 -243.94668)
		(end 171.706286 -243.423186)
		(width 0.18288)
		(layer "In2.Cu")
		(net "M_F_CPU1_SB_CS_N<3>")
	)
	(segment
		(start 156.783532 -244.491002)
		(end 155.447746 -245.826788)
		(width 0.18288)
		(layer "In2.Cu")
		(net "M_F_CPU1_SB_CS_N<3>")
	)
	(segment
		(start 173.359826 -244.490748)
		(end 172.519594 -244.490748)
		(width 0.18288)
		(layer "In2.Cu")
		(net "M_F_CPU1_SB_CS_N<3>")
	)
	(segment
		(start 138.74623 -244.52834)
		(end 138.689588 -244.471698)
		(width 0.088646)
		(layer "In2.Cu")
		(net "M_F_CPU1_SB_CS_N<3>")
	)
	(segment
		(start 134.397496 -243.607082)
		(end 134.382764 -243.598446)
		(width 0.088646)
		(layer "In2.Cu")
		(net "M_F_CPU1_SB_CS_N<3>")
	)
	(segment
		(start 175.949356 -245.186962)
		(end 175.601376 -245.186962)
		(width 0.18288)
		(layer "In2.Cu")
		(net "M_F_CPU1_SB_CS_N<3>")
	)
	(segment
		(start 176.665636 -244.490748)
		(end 176.319942 -244.490748)
		(width 0.18288)
		(layer "In2.Cu")
		(net "M_F_CPU1_SB_CS_N<3>")
	)
	(segment
		(start 140.144246 -245.352316)
		(end 139.759436 -245.737126)
		(width 0.18288)
		(layer "In2.Cu")
		(net "M_F_CPU1_SB_CS_N<3>")
	)
	(segment
		(start 139.121896 -245.737126)
		(end 138.935714 -245.737126)
		(width 0.088646)
		(layer "In2.Cu")
		(net "M_F_CPU1_SB_CS_N<3>")
	)
	(segment
		(start 174.540926 -244.48008)
		(end 174.213012 -244.807994)
		(width 0.18288)
		(layer "In2.Cu")
		(net "M_F_CPU1_SB_CS_N<3>")
	)
	(segment
		(start 176.319942 -244.490748)
		(end 176.159922 -244.650768)
		(width 0.18288)
		(layer "In2.Cu")
		(net "M_F_CPU1_SB_CS_N<3>")
	)
	(segment
		(start 138.74623 -245.547642)
		(end 138.74623 -244.52834)
		(width 0.088646)
		(layer "In2.Cu")
		(net "M_F_CPU1_SB_CS_N<3>")
	)
	(segment
		(start 136.449816 -243.93271)
		(end 136.449816 -243.922804)
		(width 0.088646)
		(layer "In2.Cu")
		(net "M_F_CPU1_SB_CS_N<3>")
	)
	(segment
		(start 162.03422 -243.642642)
		(end 160.431734 -243.642642)
		(width 0.18288)
		(layer "In2.Cu")
		(net "M_F_CPU1_SB_CS_N<3>")
	)
	(segment
		(start 134.03834 -243.108988)
		(end 133.725666 -243.108988)
		(width 0.088646)
		(layer "In2.Cu")
		(net "M_F_CPU1_SB_CS_N<3>")
	)
	(segment
		(start 160.431734 -243.642642)
		(end 159.583374 -244.491002)
		(width 0.18288)
		(layer "In2.Cu")
		(net "M_F_CPU1_SB_CS_N<3>")
	)
	(segment
		(start 164.36848 -243.318538)
		(end 162.358324 -243.318538)
		(width 0.18288)
		(layer "In2.Cu")
		(net "M_F_CPU1_SB_CS_N<3>")
	)
	(segment
		(start 174.213012 -244.807994)
		(end 173.677072 -244.807994)
		(width 0.18288)
		(layer "In2.Cu")
		(net "M_F_CPU1_SB_CS_N<3>")
	)
	(segment
		(start 167.683688 -243.971826)
		(end 167.354504 -243.642642)
		(width 0.18288)
		(layer "In2.Cu")
		(net "M_F_CPU1_SB_CS_N<3>")
	)
	(segment
		(start 164.692584 -243.642642)
		(end 164.36848 -243.318538)
		(width 0.18288)
		(layer "In2.Cu")
		(net "M_F_CPU1_SB_CS_N<3>")
	)
	(segment
		(start 175.601376 -245.186962)
		(end 175.441356 -245.026942)
		(width 0.18288)
		(layer "In2.Cu")
		(net "M_F_CPU1_SB_CS_N<3>")
	)
	(segment
		(start 175.441356 -245.026942)
		(end 175.441356 -244.650768)
		(width 0.18288)
		(layer "In2.Cu")
		(net "M_F_CPU1_SB_CS_N<3>")
	)
	(segment
		(start 176.896014 -244.916706)
		(end 176.757584 -244.582696)
		(width 0.18288)
		(layer "In2.Cu")
		(net "M_F_CPU1_SB_CS_N<3>")
	)
	(segment
		(start 171.706286 -243.423186)
		(end 170.514518 -243.423186)
		(width 0.18288)
		(layer "In2.Cu")
		(net "M_F_CPU1_SB_CS_N<3>")
	)
	(segment
		(start 173.677072 -244.807994)
		(end 173.359826 -244.490748)
		(width 0.18288)
		(layer "In2.Cu")
		(net "M_F_CPU1_SB_CS_N<3>")
	)
	(segment
		(start 172.22978 -244.200934)
		(end 172.22978 -243.94668)
		(width 0.18288)
		(layer "In2.Cu")
		(net "M_F_CPU1_SB_CS_N<3>")
	)
	(segment
		(start 176.757584 -244.582696)
		(end 176.665636 -244.490748)
		(width 0.18288)
		(layer "In2.Cu")
		(net "M_F_CPU1_SB_CS_N<3>")
	)
	(segment
		(start 138.935714 -245.737126)
		(end 138.74623 -245.547642)
		(width 0.088646)
		(layer "In2.Cu")
		(net "M_F_CPU1_SB_CS_N<3>")
	)
	(segment
		(start 168.749726 -243.971826)
		(end 167.683688 -243.971826)
		(width 0.18288)
		(layer "In2.Cu")
		(net "M_F_CPU1_SB_CS_N<3>")
	)
	(arc
		(start 138.611864 -244.412262)
		(mid 138.424666 -244.362119)
		(end 138.237468 -244.412262)
		(width 0.088646)
		(layer "In2.Cu")
		(net "M_F_CPU1_SB_CS_N<3>")
	)
	(arc
		(start 136.262364 -243.598446)
		(mid 136.075166 -243.548303)
		(end 135.887968 -243.598446)
		(width 0.088646)
		(layer "In2.Cu")
		(net "M_F_CPU1_SB_CS_N<3>")
	)
	(arc
		(start 138.237468 -244.412262)
		(mid 137.954766 -244.488038)
		(end 137.672064 -244.412262)
		(width 0.088646)
		(layer "In2.Cu")
		(net "M_F_CPU1_SB_CS_N<3>")
	)
	(arc
		(start 135.887968 -243.598446)
		(mid 135.605266 -243.674222)
		(end 135.322564 -243.598446)
		(width 0.088646)
		(layer "In2.Cu")
		(net "M_F_CPU1_SB_CS_N<3>")
	)
	(arc
		(start 138.689588 -244.471698)
		(mid 138.652678 -244.439427)
		(end 138.611864 -244.412262)
		(width 0.088646)
		(layer "In2.Cu")
		(net "M_F_CPU1_SB_CS_N<3>")
	)
	(arc
		(start 136.732264 -244.412262)
		(mid 136.527929 -244.209657)
		(end 136.449816 -243.93271)
		(width 0.088646)
		(layer "In2.Cu")
		(net "M_F_CPU1_SB_CS_N<3>")
	)
	(arc
		(start 134.948168 -243.598446)
		(mid 134.673969 -243.674281)
		(end 134.397496 -243.607082)
		(width 0.088646)
		(layer "In2.Cu")
		(net "M_F_CPU1_SB_CS_N<3>")
	)
	(arc
		(start 137.672064 -244.412262)
		(mid 137.484866 -244.362119)
		(end 137.297668 -244.412262)
		(width 0.088646)
		(layer "In2.Cu")
		(net "M_F_CPU1_SB_CS_N<3>")
	)
	(arc
		(start 137.297668 -244.412262)
		(mid 137.014966 -244.488038)
		(end 136.732264 -244.412262)
		(width 0.088646)
		(layer "In2.Cu")
		(net "M_F_CPU1_SB_CS_N<3>")
	)
	(arc
		(start 135.322564 -243.598446)
		(mid 135.135366 -243.548303)
		(end 134.948168 -243.598446)
		(width 0.088646)
		(layer "In2.Cu")
		(net "M_F_CPU1_SB_CS_N<3>")
	)
	(arc
		(start 136.449816 -243.922804)
		(mid 136.402137 -243.739904)
		(end 136.271254 -243.603526)
		(width 0.088646)
		(layer "In2.Cu")
		(net "M_F_CPU1_SB_CS_N<3>")
	)
	(arc
		(start 134.376668 -243.59489)
		(mid 134.191145 -243.416589)
		(end 134.103872 -243.17452)
		(width 0.088646)
		(layer "In2.Cu")
		(net "M_F_CPU1_SB_CS_N<3>")
	)
	(segment
		(start 133.255766 -244.45849)
		(end 133.255766 -243.922804)
		(width 0.20066)
		(layer "F.Cu")
		(net "M_F_CPU1_SB_CS_N<2>")
	)
	(segment
		(start 133.255512 -244.458744)
		(end 133.255766 -244.45849)
		(width 0.20066)
		(layer "F.Cu")
		(net "M_F_CPU1_SB_CS_N<2>")
	)
	(segment
		(start 172.795946 -245.76659)
		(end 173.900846 -245.76659)
		(width 0.20066)
		(layer "F.Cu")
		(net "M_F_CPU1_SB_CS_N<2>")
	)
	(segment
		(start 167.546782 -245.851426)
		(end 167.165782 -246.232426)
		(width 0.18288)
		(layer "In2.Cu")
		(net "M_F_CPU1_SB_CS_N<2>")
	)
	(segment
		(start 162.536124 -245.292626)
		(end 162.244024 -245.584726)
		(width 0.18288)
		(layer "In2.Cu")
		(net "M_F_CPU1_SB_CS_N<2>")
	)
	(segment
		(start 155.369514 -246.869712)
		(end 155.176474 -247.062752)
		(width 0.18288)
		(layer "In2.Cu")
		(net "M_F_CPU1_SB_CS_N<2>")
	)
	(segment
		(start 150.850854 -246.886984)
		(end 150.39848 -246.43461)
		(width 0.18288)
		(layer "In2.Cu")
		(net "M_F_CPU1_SB_CS_N<2>")
	)
	(segment
		(start 171.229274 -246.207534)
		(end 170.488864 -245.467124)
		(width 0.18288)
		(layer "In2.Cu")
		(net "M_F_CPU1_SB_CS_N<2>")
	)
	(segment
		(start 169.886376 -245.660164)
		(end 169.886376 -246.004842)
		(width 0.18288)
		(layer "In2.Cu")
		(net "M_F_CPU1_SB_CS_N<2>")
	)
	(segment
		(start 164.485574 -245.966742)
		(end 164.485574 -245.53037)
		(width 0.18288)
		(layer "In2.Cu")
		(net "M_F_CPU1_SB_CS_N<2>")
	)
	(segment
		(start 138.815826 -246.61241)
		(end 138.490706 -246.28729)
		(width 0.18288)
		(layer "In2.Cu")
		(net "M_F_CPU1_SB_CS_N<2>")
	)
	(segment
		(start 155.176474 -247.062752)
		(end 155.176474 -247.255284)
		(width 0.18288)
		(layer "In2.Cu")
		(net "M_F_CPU1_SB_CS_N<2>")
	)
	(segment
		(start 155.880562 -247.062752)
		(end 155.687522 -246.869712)
		(width 0.18288)
		(layer "In2.Cu")
		(net "M_F_CPU1_SB_CS_N<2>")
	)
	(segment
		(start 156.905706 -246.098568)
		(end 156.905706 -246.836438)
		(width 0.18288)
		(layer "In2.Cu")
		(net "M_F_CPU1_SB_CS_N<2>")
	)
	(segment
		(start 138.356086 -246.15267)
		(end 138.356086 -245.421658)
		(width 0.088646)
		(layer "In2.Cu")
		(net "M_F_CPU1_SB_CS_N<2>")
	)
	(segment
		(start 140.23848 -246.61241)
		(end 138.815826 -246.61241)
		(width 0.18288)
		(layer "In2.Cu")
		(net "M_F_CPU1_SB_CS_N<2>")
	)
	(segment
		(start 135.792718 -244.412516)
		(end 135.792464 -244.412262)
		(width 0.088646)
		(layer "In2.Cu")
		(net "M_F_CPU1_SB_CS_N<2>")
	)
	(segment
		(start 169.258234 -246.359934)
		(end 168.749726 -245.851426)
		(width 0.18288)
		(layer "In2.Cu")
		(net "M_F_CPU1_SB_CS_N<2>")
	)
	(segment
		(start 162.244024 -246.006874)
		(end 161.727642 -246.523256)
		(width 0.18288)
		(layer "In2.Cu")
		(net "M_F_CPU1_SB_CS_N<2>")
	)
	(segment
		(start 170.079416 -245.467124)
		(end 169.886376 -245.660164)
		(width 0.18288)
		(layer "In2.Cu")
		(net "M_F_CPU1_SB_CS_N<2>")
	)
	(segment
		(start 172.355002 -246.207534)
		(end 171.229274 -246.207534)
		(width 0.18288)
		(layer "In2.Cu")
		(net "M_F_CPU1_SB_CS_N<2>")
	)
	(segment
		(start 165.574726 -246.232426)
		(end 165.422326 -246.080026)
		(width 0.18288)
		(layer "In2.Cu")
		(net "M_F_CPU1_SB_CS_N<2>")
	)
	(segment
		(start 156.073602 -247.448324)
		(end 155.880562 -247.255284)
		(width 0.18288)
		(layer "In2.Cu")
		(net "M_F_CPU1_SB_CS_N<2>")
	)
	(segment
		(start 169.886376 -246.004842)
		(end 169.531284 -246.359934)
		(width 0.18288)
		(layer "In2.Cu")
		(net "M_F_CPU1_SB_CS_N<2>")
	)
	(segment
		(start 135.418068 -244.412262)
		(end 135.407654 -244.418358)
		(width 0.088646)
		(layer "In2.Cu")
		(net "M_F_CPU1_SB_CS_N<2>")
	)
	(segment
		(start 159.917892 -245.978934)
		(end 159.414464 -246.482362)
		(width 0.18288)
		(layer "In2.Cu")
		(net "M_F_CPU1_SB_CS_N<2>")
	)
	(segment
		(start 140.41628 -246.43461)
		(end 140.23848 -246.61241)
		(width 0.18288)
		(layer "In2.Cu")
		(net "M_F_CPU1_SB_CS_N<2>")
	)
	(segment
		(start 168.749726 -245.851426)
		(end 167.546782 -245.851426)
		(width 0.18288)
		(layer "In2.Cu")
		(net "M_F_CPU1_SB_CS_N<2>")
	)
	(segment
		(start 172.795946 -245.76659)
		(end 172.355002 -246.207534)
		(width 0.18288)
		(layer "In2.Cu")
		(net "M_F_CPU1_SB_CS_N<2>")
	)
	(segment
		(start 156.29382 -247.448324)
		(end 156.073602 -247.448324)
		(width 0.18288)
		(layer "In2.Cu")
		(net "M_F_CPU1_SB_CS_N<2>")
	)
	(segment
		(start 164.488622 -245.527322)
		(end 164.253926 -245.292626)
		(width 0.18288)
		(layer "In2.Cu")
		(net "M_F_CPU1_SB_CS_N<2>")
	)
	(segment
		(start 164.485574 -245.53037)
		(end 164.488622 -245.527322)
		(width 0.18288)
		(layer "In2.Cu")
		(net "M_F_CPU1_SB_CS_N<2>")
	)
	(segment
		(start 160.776158 -245.978934)
		(end 159.917892 -245.978934)
		(width 0.18288)
		(layer "In2.Cu")
		(net "M_F_CPU1_SB_CS_N<2>")
	)
	(segment
		(start 157.610302 -245.905528)
		(end 157.098746 -245.905528)
		(width 0.18288)
		(layer "In2.Cu")
		(net "M_F_CPU1_SB_CS_N<2>")
	)
	(segment
		(start 133.912864 -244.412262)
		(end 133.88467 -244.396006)
		(width 0.088646)
		(layer "In2.Cu")
		(net "M_F_CPU1_SB_CS_N<2>")
	)
	(segment
		(start 157.098746 -245.905528)
		(end 156.905706 -246.098568)
		(width 0.18288)
		(layer "In2.Cu")
		(net "M_F_CPU1_SB_CS_N<2>")
	)
	(segment
		(start 155.687522 -246.869712)
		(end 155.369514 -246.869712)
		(width 0.18288)
		(layer "In2.Cu")
		(net "M_F_CPU1_SB_CS_N<2>")
	)
	(segment
		(start 135.979916 -244.737128)
		(end 135.979916 -244.73662)
		(width 0.088646)
		(layer "In2.Cu")
		(net "M_F_CPU1_SB_CS_N<2>")
	)
	(segment
		(start 159.414464 -246.482362)
		(end 158.187136 -246.482362)
		(width 0.18288)
		(layer "In2.Cu")
		(net "M_F_CPU1_SB_CS_N<2>")
	)
	(segment
		(start 164.253926 -245.292626)
		(end 162.536124 -245.292626)
		(width 0.18288)
		(layer "In2.Cu")
		(net "M_F_CPU1_SB_CS_N<2>")
	)
	(segment
		(start 161.727642 -246.523256)
		(end 161.103818 -246.523256)
		(width 0.18288)
		(layer "In2.Cu")
		(net "M_F_CPU1_SB_CS_N<2>")
	)
	(segment
		(start 162.244024 -245.584726)
		(end 162.244024 -246.006874)
		(width 0.18288)
		(layer "In2.Cu")
		(net "M_F_CPU1_SB_CS_N<2>")
	)
	(segment
		(start 158.187136 -246.482362)
		(end 157.610302 -245.905528)
		(width 0.18288)
		(layer "In2.Cu")
		(net "M_F_CPU1_SB_CS_N<2>")
	)
	(segment
		(start 150.39848 -246.43461)
		(end 140.41628 -246.43461)
		(width 0.18288)
		(layer "In2.Cu")
		(net "M_F_CPU1_SB_CS_N<2>")
	)
	(segment
		(start 170.488864 -245.467124)
		(end 170.079416 -245.467124)
		(width 0.18288)
		(layer "In2.Cu")
		(net "M_F_CPU1_SB_CS_N<2>")
	)
	(segment
		(start 167.165782 -246.232426)
		(end 165.574726 -246.232426)
		(width 0.18288)
		(layer "In2.Cu")
		(net "M_F_CPU1_SB_CS_N<2>")
	)
	(segment
		(start 133.88467 -244.396006)
		(end 133.255766 -243.922804)
		(width 0.088646)
		(layer "In2.Cu")
		(net "M_F_CPU1_SB_CS_N<2>")
	)
	(segment
		(start 154.564588 -247.448324)
		(end 154.003248 -246.886984)
		(width 0.18288)
		(layer "In2.Cu")
		(net "M_F_CPU1_SB_CS_N<2>")
	)
	(segment
		(start 164.598858 -246.080026)
		(end 164.485574 -245.966742)
		(width 0.18288)
		(layer "In2.Cu")
		(net "M_F_CPU1_SB_CS_N<2>")
	)
	(segment
		(start 160.969452 -246.38889)
		(end 160.969452 -246.172228)
		(width 0.18288)
		(layer "In2.Cu")
		(net "M_F_CPU1_SB_CS_N<2>")
	)
	(segment
		(start 138.490706 -246.28729)
		(end 138.356086 -246.15267)
		(width 0.088646)
		(layer "In2.Cu")
		(net "M_F_CPU1_SB_CS_N<2>")
	)
	(segment
		(start 169.531284 -246.359934)
		(end 169.258234 -246.359934)
		(width 0.18288)
		(layer "In2.Cu")
		(net "M_F_CPU1_SB_CS_N<2>")
	)
	(segment
		(start 138.356086 -245.421658)
		(end 138.219942 -245.285514)
		(width 0.088646)
		(layer "In2.Cu")
		(net "M_F_CPU1_SB_CS_N<2>")
	)
	(segment
		(start 155.176474 -247.255284)
		(end 154.983434 -247.448324)
		(width 0.18288)
		(layer "In2.Cu")
		(net "M_F_CPU1_SB_CS_N<2>")
	)
	(segment
		(start 165.422326 -246.080026)
		(end 164.598858 -246.080026)
		(width 0.18288)
		(layer "In2.Cu")
		(net "M_F_CPU1_SB_CS_N<2>")
	)
	(segment
		(start 155.880562 -247.255284)
		(end 155.880562 -247.062752)
		(width 0.18288)
		(layer "In2.Cu")
		(net "M_F_CPU1_SB_CS_N<2>")
	)
	(segment
		(start 134.478014 -244.412262)
		(end 134.47776 -244.412262)
		(width 0.088646)
		(layer "In2.Cu")
		(net "M_F_CPU1_SB_CS_N<2>")
	)
	(segment
		(start 161.103818 -246.523256)
		(end 160.969452 -246.38889)
		(width 0.18288)
		(layer "In2.Cu")
		(net "M_F_CPU1_SB_CS_N<2>")
	)
	(segment
		(start 154.003248 -246.886984)
		(end 150.850854 -246.886984)
		(width 0.18288)
		(layer "In2.Cu")
		(net "M_F_CPU1_SB_CS_N<2>")
	)
	(segment
		(start 160.969452 -246.172228)
		(end 160.776158 -245.978934)
		(width 0.18288)
		(layer "In2.Cu")
		(net "M_F_CPU1_SB_CS_N<2>")
	)
	(segment
		(start 156.905706 -246.836438)
		(end 156.29382 -247.448324)
		(width 0.18288)
		(layer "In2.Cu")
		(net "M_F_CPU1_SB_CS_N<2>")
	)
	(segment
		(start 154.983434 -247.448324)
		(end 154.564588 -247.448324)
		(width 0.18288)
		(layer "In2.Cu")
		(net "M_F_CPU1_SB_CS_N<2>")
	)
	(arc
		(start 134.85241 -244.412262)
		(mid 134.665212 -244.362119)
		(end 134.478014 -244.412262)
		(width 0.088646)
		(layer "In2.Cu")
		(net "M_F_CPU1_SB_CS_N<2>")
	)
	(arc
		(start 135.792464 -244.412262)
		(mid 135.605266 -244.362119)
		(end 135.418068 -244.412262)
		(width 0.088646)
		(layer "In2.Cu")
		(net "M_F_CPU1_SB_CS_N<2>")
	)
	(arc
		(start 137.767568 -245.226332)
		(mid 137.484866 -245.302074)
		(end 137.202164 -245.226332)
		(width 0.088646)
		(layer "In2.Cu")
		(net "M_F_CPU1_SB_CS_N<2>")
	)
	(arc
		(start 138.141964 -245.226332)
		(mid 137.954766 -245.176189)
		(end 137.767568 -245.226332)
		(width 0.088646)
		(layer "In2.Cu")
		(net "M_F_CPU1_SB_CS_N<2>")
	)
	(arc
		(start 135.407654 -244.418358)
		(mid 135.129222 -244.488204)
		(end 134.85241 -244.412262)
		(width 0.088646)
		(layer "In2.Cu")
		(net "M_F_CPU1_SB_CS_N<2>")
	)
	(arc
		(start 134.47776 -244.412262)
		(mid 134.195312 -244.487945)
		(end 133.912864 -244.412262)
		(width 0.088646)
		(layer "In2.Cu")
		(net "M_F_CPU1_SB_CS_N<2>")
	)
	(arc
		(start 135.979916 -244.73662)
		(mid 135.929752 -244.549482)
		(end 135.792718 -244.412516)
		(width 0.088646)
		(layer "In2.Cu")
		(net "M_F_CPU1_SB_CS_N<2>")
	)
	(arc
		(start 138.219942 -245.285514)
		(mid 138.182892 -245.253368)
		(end 138.141964 -245.226332)
		(width 0.088646)
		(layer "In2.Cu")
		(net "M_F_CPU1_SB_CS_N<2>")
	)
	(arc
		(start 136.827768 -245.226332)
		(mid 136.545066 -245.302074)
		(end 136.262364 -245.226332)
		(width 0.088646)
		(layer "In2.Cu")
		(net "M_F_CPU1_SB_CS_N<2>")
	)
	(arc
		(start 136.262364 -245.226332)
		(mid 136.055604 -245.019569)
		(end 135.979916 -244.737128)
		(width 0.088646)
		(layer "In2.Cu")
		(net "M_F_CPU1_SB_CS_N<2>")
	)
	(arc
		(start 137.202164 -245.226332)
		(mid 137.014966 -245.176189)
		(end 136.827768 -245.226332)
		(width 0.088646)
		(layer "In2.Cu")
		(net "M_F_CPU1_SB_CS_N<2>")
	)
	(segment
		(start 134.665212 -243.644674)
		(end 134.665212 -243.108988)
		(width 0.20066)
		(layer "F.Cu")
		(net "M_F_CPU1_SB_CS_N<1>")
	)
	(segment
		(start 184.439814 -244.916706)
		(end 185.544714 -244.916706)
		(width 0.20066)
		(layer "F.Cu")
		(net "M_F_CPU1_SB_CS_N<1>")
	)
	(segment
		(start 134.665466 -243.644928)
		(end 134.665212 -243.644674)
		(width 0.20066)
		(layer "F.Cu")
		(net "M_F_CPU1_SB_CS_N<1>")
	)
	(segment
		(start 179.075588 -242.007136)
		(end 178.915568 -242.167156)
		(width 0.18288)
		(layer "In2.Cu")
		(net "M_F_CPU1_SB_CS_N<1>")
	)
	(segment
		(start 151.45639 -245.290848)
		(end 150.927308 -244.761766)
		(width 0.18288)
		(layer "In2.Cu")
		(net "M_F_CPU1_SB_CS_N<1>")
	)
	(segment
		(start 168.539668 -242.79098)
		(end 168.276524 -243.054124)
		(width 0.18288)
		(layer "In2.Cu")
		(net "M_F_CPU1_SB_CS_N<1>")
	)
	(segment
		(start 174.799244 -242.79225)
		(end 172.315632 -242.79225)
		(width 0.18288)
		(layer "In2.Cu")
		(net "M_F_CPU1_SB_CS_N<1>")
	)
	(segment
		(start 175.743616 -242.79479)
		(end 175.631348 -242.907058)
		(width 0.18288)
		(layer "In2.Cu")
		(net "M_F_CPU1_SB_CS_N<1>")
	)
	(segment
		(start 167.420544 -243.054124)
		(end 167.1574 -242.79098)
		(width 0.18288)
		(layer "In2.Cu")
		(net "M_F_CPU1_SB_CS_N<1>")
	)
	(segment
		(start 179.71008 -242.167156)
		(end 179.55006 -242.007136)
		(width 0.18288)
		(layer "In2.Cu")
		(net "M_F_CPU1_SB_CS_N<1>")
	)
	(segment
		(start 159.5755 -243.640864)
		(end 157.603698 -243.640864)
		(width 0.18288)
		(layer "In2.Cu")
		(net "M_F_CPU1_SB_CS_N<1>")
	)
	(segment
		(start 168.276524 -243.054124)
		(end 167.420544 -243.054124)
		(width 0.18288)
		(layer "In2.Cu")
		(net "M_F_CPU1_SB_CS_N<1>")
	)
	(segment
		(start 178.915568 -242.62207)
		(end 178.742848 -242.79479)
		(width 0.18288)
		(layer "In2.Cu")
		(net "M_F_CPU1_SB_CS_N<1>")
	)
	(segment
		(start 136.640316 -243.922804)
		(end 136.640316 -243.912898)
		(width 0.088646)
		(layer "In2.Cu")
		(net "M_F_CPU1_SB_CS_N<1>")
	)
	(segment
		(start 135.418068 -243.433346)
		(end 135.407654 -243.42725)
		(width 0.088646)
		(layer "In2.Cu")
		(net "M_F_CPU1_SB_CS_N<1>")
	)
	(segment
		(start 172.315632 -242.79225)
		(end 172.141642 -242.61826)
		(width 0.18288)
		(layer "In2.Cu")
		(net "M_F_CPU1_SB_CS_N<1>")
	)
	(segment
		(start 175.631348 -242.907058)
		(end 174.914052 -242.907058)
		(width 0.18288)
		(layer "In2.Cu")
		(net "M_F_CPU1_SB_CS_N<1>")
	)
	(segment
		(start 156.898594 -243.642388)
		(end 155.250134 -245.290848)
		(width 0.18288)
		(layer "In2.Cu")
		(net "M_F_CPU1_SB_CS_N<1>")
	)
	(segment
		(start 172.141642 -242.213384)
		(end 171.981622 -242.053364)
		(width 0.18288)
		(layer "In2.Cu")
		(net "M_F_CPU1_SB_CS_N<1>")
	)
	(segment
		(start 139.400534 -244.912896)
		(end 138.824462 -244.336824)
		(width 0.088646)
		(layer "In2.Cu")
		(net "M_F_CPU1_SB_CS_N<1>")
	)
	(segment
		(start 174.914052 -242.907058)
		(end 174.799244 -242.79225)
		(width 0.18288)
		(layer "In2.Cu")
		(net "M_F_CPU1_SB_CS_N<1>")
	)
	(segment
		(start 139.846558 -244.912896)
		(end 139.579096 -244.912896)
		(width 0.18288)
		(layer "In2.Cu")
		(net "M_F_CPU1_SB_CS_N<1>")
	)
	(segment
		(start 160.425384 -242.79098)
		(end 159.5755 -243.640864)
		(width 0.18288)
		(layer "In2.Cu")
		(net "M_F_CPU1_SB_CS_N<1>")
	)
	(segment
		(start 139.997688 -244.761766)
		(end 139.846558 -244.912896)
		(width 0.18288)
		(layer "In2.Cu")
		(net "M_F_CPU1_SB_CS_N<1>")
	)
	(segment
		(start 179.71008 -242.62207)
		(end 179.71008 -242.167156)
		(width 0.18288)
		(layer "In2.Cu")
		(net "M_F_CPU1_SB_CS_N<1>")
	)
	(segment
		(start 182.317898 -242.79479)
		(end 179.8828 -242.79479)
		(width 0.18288)
		(layer "In2.Cu")
		(net "M_F_CPU1_SB_CS_N<1>")
	)
	(segment
		(start 171.401232 -242.63096)
		(end 171.241212 -242.79098)
		(width 0.18288)
		(layer "In2.Cu")
		(net "M_F_CPU1_SB_CS_N<1>")
	)
	(segment
		(start 178.742848 -242.79479)
		(end 175.743616 -242.79479)
		(width 0.18288)
		(layer "In2.Cu")
		(net "M_F_CPU1_SB_CS_N<1>")
	)
	(segment
		(start 171.241212 -242.79098)
		(end 168.539668 -242.79098)
		(width 0.18288)
		(layer "In2.Cu")
		(net "M_F_CPU1_SB_CS_N<1>")
	)
	(segment
		(start 167.1574 -242.79098)
		(end 160.425384 -242.79098)
		(width 0.18288)
		(layer "In2.Cu")
		(net "M_F_CPU1_SB_CS_N<1>")
	)
	(segment
		(start 150.927308 -244.761766)
		(end 139.997688 -244.761766)
		(width 0.18288)
		(layer "In2.Cu")
		(net "M_F_CPU1_SB_CS_N<1>")
	)
	(segment
		(start 171.401232 -242.351052)
		(end 171.401232 -242.63096)
		(width 0.18288)
		(layer "In2.Cu")
		(net "M_F_CPU1_SB_CS_N<1>")
	)
	(segment
		(start 136.827768 -244.247162)
		(end 136.818878 -244.242082)
		(width 0.088646)
		(layer "In2.Cu")
		(net "M_F_CPU1_SB_CS_N<1>")
	)
	(segment
		(start 139.579096 -244.912896)
		(end 139.400534 -244.912896)
		(width 0.088646)
		(layer "In2.Cu")
		(net "M_F_CPU1_SB_CS_N<1>")
	)
	(segment
		(start 155.250134 -245.290848)
		(end 151.45639 -245.290848)
		(width 0.18288)
		(layer "In2.Cu")
		(net "M_F_CPU1_SB_CS_N<1>")
	)
	(segment
		(start 134.352538 -243.108988)
		(end 134.665212 -243.108988)
		(width 0.088646)
		(layer "In2.Cu")
		(net "M_F_CPU1_SB_CS_N<1>")
	)
	(segment
		(start 184.439814 -244.916706)
		(end 182.317898 -242.79479)
		(width 0.18288)
		(layer "In2.Cu")
		(net "M_F_CPU1_SB_CS_N<1>")
	)
	(segment
		(start 178.915568 -242.167156)
		(end 178.915568 -242.62207)
		(width 0.18288)
		(layer "In2.Cu")
		(net "M_F_CPU1_SB_CS_N<1>")
	)
	(segment
		(start 172.141642 -242.61826)
		(end 172.141642 -242.213384)
		(width 0.18288)
		(layer "In2.Cu")
		(net "M_F_CPU1_SB_CS_N<1>")
	)
	(segment
		(start 134.295388 -243.166138)
		(end 134.352538 -243.108988)
		(width 0.088646)
		(layer "In2.Cu")
		(net "M_F_CPU1_SB_CS_N<1>")
	)
	(segment
		(start 179.55006 -242.007136)
		(end 179.075588 -242.007136)
		(width 0.18288)
		(layer "In2.Cu")
		(net "M_F_CPU1_SB_CS_N<1>")
	)
	(segment
		(start 179.8828 -242.79479)
		(end 179.71008 -242.62207)
		(width 0.18288)
		(layer "In2.Cu")
		(net "M_F_CPU1_SB_CS_N<1>")
	)
	(segment
		(start 157.603698 -243.640864)
		(end 157.602174 -243.642388)
		(width 0.18288)
		(layer "In2.Cu")
		(net "M_F_CPU1_SB_CS_N<1>")
	)
	(segment
		(start 171.981622 -242.053364)
		(end 171.69892 -242.053364)
		(width 0.18288)
		(layer "In2.Cu")
		(net "M_F_CPU1_SB_CS_N<1>")
	)
	(segment
		(start 171.69892 -242.053364)
		(end 171.401232 -242.351052)
		(width 0.18288)
		(layer "In2.Cu")
		(net "M_F_CPU1_SB_CS_N<1>")
	)
	(segment
		(start 157.602174 -243.642388)
		(end 156.898594 -243.642388)
		(width 0.18288)
		(layer "In2.Cu")
		(net "M_F_CPU1_SB_CS_N<1>")
	)
	(arc
		(start 138.141964 -244.247162)
		(mid 137.954766 -244.297305)
		(end 137.767568 -244.247162)
		(width 0.088646)
		(layer "In2.Cu")
		(net "M_F_CPU1_SB_CS_N<1>")
	)
	(arc
		(start 136.640316 -243.912898)
		(mid 136.562205 -243.635949)
		(end 136.357868 -243.433346)
		(width 0.088646)
		(layer "In2.Cu")
		(net "M_F_CPU1_SB_CS_N<1>")
	)
	(arc
		(start 137.767568 -244.247162)
		(mid 137.484866 -244.171386)
		(end 137.202164 -244.247162)
		(width 0.088646)
		(layer "In2.Cu")
		(net "M_F_CPU1_SB_CS_N<1>")
	)
	(arc
		(start 138.707368 -244.247162)
		(mid 138.424666 -244.171386)
		(end 138.141964 -244.247162)
		(width 0.088646)
		(layer "In2.Cu")
		(net "M_F_CPU1_SB_CS_N<1>")
	)
	(arc
		(start 136.357868 -243.433346)
		(mid 136.075166 -243.35757)
		(end 135.792464 -243.433346)
		(width 0.088646)
		(layer "In2.Cu")
		(net "M_F_CPU1_SB_CS_N<1>")
	)
	(arc
		(start 137.202164 -244.247162)
		(mid 137.014966 -244.297305)
		(end 136.827768 -244.247162)
		(width 0.088646)
		(layer "In2.Cu")
		(net "M_F_CPU1_SB_CS_N<1>")
	)
	(arc
		(start 138.824462 -244.336824)
		(mid 138.768857 -244.28815)
		(end 138.707368 -244.247162)
		(width 0.088646)
		(layer "In2.Cu")
		(net "M_F_CPU1_SB_CS_N<1>")
	)
	(arc
		(start 135.407654 -243.42725)
		(mid 135.129222 -243.357404)
		(end 134.85241 -243.433346)
		(width 0.088646)
		(layer "In2.Cu")
		(net "M_F_CPU1_SB_CS_N<1>")
	)
	(arc
		(start 134.85241 -243.433346)
		(mid 134.665212 -243.483489)
		(end 134.478014 -243.433346)
		(width 0.088646)
		(layer "In2.Cu")
		(net "M_F_CPU1_SB_CS_N<1>")
	)
	(arc
		(start 136.818878 -244.242082)
		(mid 136.687964 -244.105722)
		(end 136.640316 -243.922804)
		(width 0.088646)
		(layer "In2.Cu")
		(net "M_F_CPU1_SB_CS_N<1>")
	)
	(arc
		(start 135.792464 -243.433346)
		(mid 135.605266 -243.483489)
		(end 135.418068 -243.433346)
		(width 0.088646)
		(layer "In2.Cu")
		(net "M_F_CPU1_SB_CS_N<1>")
	)
	(arc
		(start 134.478014 -243.433346)
		(mid 134.356346 -243.320491)
		(end 134.295388 -243.166138)
		(width 0.088646)
		(layer "In2.Cu")
		(net "M_F_CPU1_SB_CS_N<1>")
	)
	(segment
		(start 135.135112 -244.458744)
		(end 135.135112 -243.923058)
		(width 0.20066)
		(layer "F.Cu")
		(net "M_F_CPU1_SB_CS_N<0>")
	)
	(segment
		(start 180.339746 -245.76659)
		(end 181.444646 -245.76659)
		(width 0.20066)
		(layer "F.Cu")
		(net "M_F_CPU1_SB_CS_N<0>")
	)
	(segment
		(start 135.135112 -243.923058)
		(end 135.135366 -243.922804)
		(width 0.20066)
		(layer "F.Cu")
		(net "M_F_CPU1_SB_CS_N<0>")
	)
	(segment
		(start 161.266632 -244.84584)
		(end 161.266632 -244.346984)
		(width 0.18288)
		(layer "In2.Cu")
		(net "M_F_CPU1_SB_CS_N<0>")
	)
	(segment
		(start 159.286956 -244.999256)
		(end 158.324042 -244.999256)
		(width 0.18288)
		(layer "In2.Cu")
		(net "M_F_CPU1_SB_CS_N<0>")
	)
	(segment
		(start 156.632402 -245.380256)
		(end 155.661868 -246.35079)
		(width 0.18288)
		(layer "In2.Cu")
		(net "M_F_CPU1_SB_CS_N<0>")
	)
	(segment
		(start 179.879244 -245.306088)
		(end 178.638708 -245.306088)
		(width 0.18288)
		(layer "In2.Cu")
		(net "M_F_CPU1_SB_CS_N<0>")
	)
	(segment
		(start 165.447726 -245.394226)
		(end 165.079426 -245.394226)
		(width 0.18288)
		(layer "In2.Cu")
		(net "M_F_CPU1_SB_CS_N<0>")
	)
	(segment
		(start 169.516552 -244.556026)
		(end 169.112946 -244.556026)
		(width 0.18288)
		(layer "In2.Cu")
		(net "M_F_CPU1_SB_CS_N<0>")
	)
	(segment
		(start 165.753542 -244.623844)
		(end 165.753542 -245.08841)
		(width 0.18288)
		(layer "In2.Cu")
		(net "M_F_CPU1_SB_CS_N<0>")
	)
	(segment
		(start 177.7492 -246.028718)
		(end 177.7492 -245.503192)
		(width 0.18288)
		(layer "In2.Cu")
		(net "M_F_CPU1_SB_CS_N<0>")
	)
	(segment
		(start 150.635716 -245.92661)
		(end 140.304012 -245.92661)
		(width 0.18288)
		(layer "In2.Cu")
		(net "M_F_CPU1_SB_CS_N<0>")
	)
	(segment
		(start 162.172142 -244.505226)
		(end 161.704274 -244.973094)
		(width 0.18288)
		(layer "In2.Cu")
		(net "M_F_CPU1_SB_CS_N<0>")
	)
	(segment
		(start 138.950954 -246.22633)
		(end 138.75131 -246.026686)
		(width 0.18288)
		(layer "In2.Cu")
		(net "M_F_CPU1_SB_CS_N<0>")
	)
	(segment
		(start 169.112946 -244.556026)
		(end 168.927526 -244.741446)
		(width 0.18288)
		(layer "In2.Cu")
		(net "M_F_CPU1_SB_CS_N<0>")
	)
	(segment
		(start 177.7492 -245.503192)
		(end 177.58918 -245.343172)
		(width 0.18288)
		(layer "In2.Cu")
		(net "M_F_CPU1_SB_CS_N<0>")
	)
	(segment
		(start 165.89756 -244.479826)
		(end 165.753542 -244.623844)
		(width 0.18288)
		(layer "In2.Cu")
		(net "M_F_CPU1_SB_CS_N<0>")
	)
	(segment
		(start 161.266632 -244.346984)
		(end 161.073592 -244.153944)
		(width 0.18288)
		(layer "In2.Cu")
		(net "M_F_CPU1_SB_CS_N<0>")
	)
	(segment
		(start 158.324042 -244.999256)
		(end 157.943042 -245.380256)
		(width 0.18288)
		(layer "In2.Cu")
		(net "M_F_CPU1_SB_CS_N<0>")
	)
	(segment
		(start 161.393886 -244.973094)
		(end 161.266632 -244.84584)
		(width 0.18288)
		(layer "In2.Cu")
		(net "M_F_CPU1_SB_CS_N<0>")
	)
	(segment
		(start 135.860028 -244.230906)
		(end 135.135366 -243.922804)
		(width 0.088646)
		(layer "In2.Cu")
		(net "M_F_CPU1_SB_CS_N<0>")
	)
	(segment
		(start 164.601906 -244.58295)
		(end 163.907978 -244.58295)
		(width 0.18288)
		(layer "In2.Cu")
		(net "M_F_CPU1_SB_CS_N<0>")
	)
	(segment
		(start 138.546332 -245.342664)
		(end 138.354562 -245.150894)
		(width 0.088646)
		(layer "In2.Cu")
		(net "M_F_CPU1_SB_CS_N<0>")
	)
	(segment
		(start 168.063926 -245.15318)
		(end 168.063926 -244.639846)
		(width 0.18288)
		(layer "In2.Cu")
		(net "M_F_CPU1_SB_CS_N<0>")
	)
	(segment
		(start 176.515268 -245.343172)
		(end 176.091596 -245.766844)
		(width 0.18288)
		(layer "In2.Cu")
		(net "M_F_CPU1_SB_CS_N<0>")
	)
	(segment
		(start 174.789846 -245.344696)
		(end 172.525436 -245.344696)
		(width 0.18288)
		(layer "In2.Cu")
		(net "M_F_CPU1_SB_CS_N<0>")
	)
	(segment
		(start 161.073592 -244.153944)
		(end 160.656778 -244.153944)
		(width 0.18288)
		(layer "In2.Cu")
		(net "M_F_CPU1_SB_CS_N<0>")
	)
	(segment
		(start 164.761926 -244.74297)
		(end 164.601906 -244.58295)
		(width 0.18288)
		(layer "In2.Cu")
		(net "M_F_CPU1_SB_CS_N<0>")
	)
	(segment
		(start 163.830254 -244.505226)
		(end 163.478464 -244.505226)
		(width 0.18288)
		(layer "In2.Cu")
		(net "M_F_CPU1_SB_CS_N<0>")
	)
	(segment
		(start 136.170416 -244.73662)
		(end 136.170416 -244.736366)
		(width 0.088646)
		(layer "In2.Cu")
		(net "M_F_CPU1_SB_CS_N<0>")
	)
	(segment
		(start 159.692086 -245.404386)
		(end 159.286956 -244.999256)
		(width 0.18288)
		(layer "In2.Cu")
		(net "M_F_CPU1_SB_CS_N<0>")
	)
	(segment
		(start 171.365672 -244.556026)
		(end 170.970702 -244.161056)
		(width 0.18288)
		(layer "In2.Cu")
		(net "M_F_CPU1_SB_CS_N<0>")
	)
	(segment
		(start 162.388296 -244.505226)
		(end 162.172142 -244.505226)
		(width 0.18288)
		(layer "In2.Cu")
		(net "M_F_CPU1_SB_CS_N<0>")
	)
	(segment
		(start 175.211994 -245.766844)
		(end 174.789846 -245.344696)
		(width 0.18288)
		(layer "In2.Cu")
		(net "M_F_CPU1_SB_CS_N<0>")
	)
	(segment
		(start 140.304012 -245.92661)
		(end 140.004292 -246.22633)
		(width 0.18288)
		(layer "In2.Cu")
		(net "M_F_CPU1_SB_CS_N<0>")
	)
	(segment
		(start 164.761926 -245.076726)
		(end 164.761926 -244.74297)
		(width 0.18288)
		(layer "In2.Cu")
		(net "M_F_CPU1_SB_CS_N<0>")
	)
	(segment
		(start 160.477454 -245.056406)
		(end 160.129474 -245.404386)
		(width 0.18288)
		(layer "In2.Cu")
		(net "M_F_CPU1_SB_CS_N<0>")
	)
	(segment
		(start 138.546332 -245.821708)
		(end 138.546332 -245.342664)
		(width 0.088646)
		(layer "In2.Cu")
		(net "M_F_CPU1_SB_CS_N<0>")
	)
	(segment
		(start 172.525436 -245.344696)
		(end 171.736766 -244.556026)
		(width 0.18288)
		(layer "In2.Cu")
		(net "M_F_CPU1_SB_CS_N<0>")
	)
	(segment
		(start 176.091596 -245.766844)
		(end 175.211994 -245.766844)
		(width 0.18288)
		(layer "In2.Cu")
		(net "M_F_CPU1_SB_CS_N<0>")
	)
	(segment
		(start 161.704274 -244.973094)
		(end 161.393886 -244.973094)
		(width 0.18288)
		(layer "In2.Cu")
		(net "M_F_CPU1_SB_CS_N<0>")
	)
	(segment
		(start 135.887968 -244.247162)
		(end 135.860028 -244.230906)
		(width 0.088646)
		(layer "In2.Cu")
		(net "M_F_CPU1_SB_CS_N<0>")
	)
	(segment
		(start 163.285424 -244.02034)
		(end 163.092384 -243.8273)
		(width 0.18288)
		(layer "In2.Cu")
		(net "M_F_CPU1_SB_CS_N<0>")
	)
	(segment
		(start 178.478688 -246.014748)
		(end 178.29022 -246.203216)
		(width 0.18288)
		(layer "In2.Cu")
		(net "M_F_CPU1_SB_CS_N<0>")
	)
	(segment
		(start 160.129474 -245.404386)
		(end 159.692086 -245.404386)
		(width 0.18288)
		(layer "In2.Cu")
		(net "M_F_CPU1_SB_CS_N<0>")
	)
	(segment
		(start 163.907978 -244.58295)
		(end 163.830254 -244.505226)
		(width 0.18288)
		(layer "In2.Cu")
		(net "M_F_CPU1_SB_CS_N<0>")
	)
	(segment
		(start 160.477454 -244.333268)
		(end 160.477454 -245.056406)
		(width 0.18288)
		(layer "In2.Cu")
		(net "M_F_CPU1_SB_CS_N<0>")
	)
	(segment
		(start 136.357868 -245.060978)
		(end 136.357868 -245.060724)
		(width 0.088646)
		(layer "In2.Cu")
		(net "M_F_CPU1_SB_CS_N<0>")
	)
	(segment
		(start 168.223946 -245.3132)
		(end 168.063926 -245.15318)
		(width 0.18288)
		(layer "In2.Cu")
		(net "M_F_CPU1_SB_CS_N<0>")
	)
	(segment
		(start 160.656778 -244.153944)
		(end 160.477454 -244.333268)
		(width 0.18288)
		(layer "In2.Cu")
		(net "M_F_CPU1_SB_CS_N<0>")
	)
	(segment
		(start 162.581336 -244.312186)
		(end 162.388296 -244.505226)
		(width 0.18288)
		(layer "In2.Cu")
		(net "M_F_CPU1_SB_CS_N<0>")
	)
	(segment
		(start 178.29022 -246.203216)
		(end 177.923698 -246.203216)
		(width 0.18288)
		(layer "In2.Cu")
		(net "M_F_CPU1_SB_CS_N<0>")
	)
	(segment
		(start 168.767506 -245.3132)
		(end 168.223946 -245.3132)
		(width 0.18288)
		(layer "In2.Cu")
		(net "M_F_CPU1_SB_CS_N<0>")
	)
	(segment
		(start 155.661868 -246.35079)
		(end 151.059896 -246.35079)
		(width 0.18288)
		(layer "In2.Cu")
		(net "M_F_CPU1_SB_CS_N<0>")
	)
	(segment
		(start 165.079426 -245.394226)
		(end 164.761926 -245.076726)
		(width 0.18288)
		(layer "In2.Cu")
		(net "M_F_CPU1_SB_CS_N<0>")
	)
	(segment
		(start 167.903906 -244.479826)
		(end 165.89756 -244.479826)
		(width 0.18288)
		(layer "In2.Cu")
		(net "M_F_CPU1_SB_CS_N<0>")
	)
	(segment
		(start 177.923698 -246.203216)
		(end 177.7492 -246.028718)
		(width 0.18288)
		(layer "In2.Cu")
		(net "M_F_CPU1_SB_CS_N<0>")
	)
	(segment
		(start 162.78098 -243.8273)
		(end 162.581336 -244.026944)
		(width 0.18288)
		(layer "In2.Cu")
		(net "M_F_CPU1_SB_CS_N<0>")
	)
	(segment
		(start 170.970702 -244.161056)
		(end 169.911522 -244.161056)
		(width 0.18288)
		(layer "In2.Cu")
		(net "M_F_CPU1_SB_CS_N<0>")
	)
	(segment
		(start 178.638708 -245.306088)
		(end 178.478688 -245.466108)
		(width 0.18288)
		(layer "In2.Cu")
		(net "M_F_CPU1_SB_CS_N<0>")
	)
	(segment
		(start 163.478464 -244.505226)
		(end 163.285424 -244.312186)
		(width 0.18288)
		(layer "In2.Cu")
		(net "M_F_CPU1_SB_CS_N<0>")
	)
	(segment
		(start 180.339746 -245.76659)
		(end 179.879244 -245.306088)
		(width 0.18288)
		(layer "In2.Cu")
		(net "M_F_CPU1_SB_CS_N<0>")
	)
	(segment
		(start 177.58918 -245.343172)
		(end 176.515268 -245.343172)
		(width 0.18288)
		(layer "In2.Cu")
		(net "M_F_CPU1_SB_CS_N<0>")
	)
	(segment
		(start 151.059896 -246.35079)
		(end 150.635716 -245.92661)
		(width 0.18288)
		(layer "In2.Cu")
		(net "M_F_CPU1_SB_CS_N<0>")
	)
	(segment
		(start 168.927526 -244.741446)
		(end 168.927526 -245.15318)
		(width 0.18288)
		(layer "In2.Cu")
		(net "M_F_CPU1_SB_CS_N<0>")
	)
	(segment
		(start 168.063926 -244.639846)
		(end 167.903906 -244.479826)
		(width 0.18288)
		(layer "In2.Cu")
		(net "M_F_CPU1_SB_CS_N<0>")
	)
	(segment
		(start 140.004292 -246.22633)
		(end 138.950954 -246.22633)
		(width 0.18288)
		(layer "In2.Cu")
		(net "M_F_CPU1_SB_CS_N<0>")
	)
	(segment
		(start 138.75131 -246.026686)
		(end 138.546332 -245.821708)
		(width 0.088646)
		(layer "In2.Cu")
		(net "M_F_CPU1_SB_CS_N<0>")
	)
	(segment
		(start 163.285424 -244.312186)
		(end 163.285424 -244.02034)
		(width 0.18288)
		(layer "In2.Cu")
		(net "M_F_CPU1_SB_CS_N<0>")
	)
	(segment
		(start 162.581336 -244.026944)
		(end 162.581336 -244.312186)
		(width 0.18288)
		(layer "In2.Cu")
		(net "M_F_CPU1_SB_CS_N<0>")
	)
	(segment
		(start 168.927526 -245.15318)
		(end 168.767506 -245.3132)
		(width 0.18288)
		(layer "In2.Cu")
		(net "M_F_CPU1_SB_CS_N<0>")
	)
	(segment
		(start 178.478688 -245.466108)
		(end 178.478688 -246.014748)
		(width 0.18288)
		(layer "In2.Cu")
		(net "M_F_CPU1_SB_CS_N<0>")
	)
	(segment
		(start 163.092384 -243.8273)
		(end 162.78098 -243.8273)
		(width 0.18288)
		(layer "In2.Cu")
		(net "M_F_CPU1_SB_CS_N<0>")
	)
	(segment
		(start 169.911522 -244.161056)
		(end 169.516552 -244.556026)
		(width 0.18288)
		(layer "In2.Cu")
		(net "M_F_CPU1_SB_CS_N<0>")
	)
	(segment
		(start 165.753542 -245.08841)
		(end 165.447726 -245.394226)
		(width 0.18288)
		(layer "In2.Cu")
		(net "M_F_CPU1_SB_CS_N<0>")
	)
	(segment
		(start 157.943042 -245.380256)
		(end 156.632402 -245.380256)
		(width 0.18288)
		(layer "In2.Cu")
		(net "M_F_CPU1_SB_CS_N<0>")
	)
	(segment
		(start 171.736766 -244.556026)
		(end 171.365672 -244.556026)
		(width 0.18288)
		(layer "In2.Cu")
		(net "M_F_CPU1_SB_CS_N<0>")
	)
	(arc
		(start 137.672064 -245.060978)
		(mid 137.484866 -245.111121)
		(end 137.297668 -245.060978)
		(width 0.088646)
		(layer "In2.Cu")
		(net "M_F_CPU1_SB_CS_N<0>")
	)
	(arc
		(start 136.357868 -245.060724)
		(mid 136.220645 -244.923827)
		(end 136.170416 -244.73662)
		(width 0.088646)
		(layer "In2.Cu")
		(net "M_F_CPU1_SB_CS_N<0>")
	)
	(arc
		(start 138.354562 -245.150894)
		(mid 138.29896 -245.102101)
		(end 138.237468 -245.060978)
		(width 0.088646)
		(layer "In2.Cu")
		(net "M_F_CPU1_SB_CS_N<0>")
	)
	(arc
		(start 137.297668 -245.060978)
		(mid 137.014966 -244.985236)
		(end 136.732264 -245.060978)
		(width 0.088646)
		(layer "In2.Cu")
		(net "M_F_CPU1_SB_CS_N<0>")
	)
	(arc
		(start 138.237468 -245.060978)
		(mid 137.954766 -244.985236)
		(end 137.672064 -245.060978)
		(width 0.088646)
		(layer "In2.Cu")
		(net "M_F_CPU1_SB_CS_N<0>")
	)
	(arc
		(start 136.732264 -245.060978)
		(mid 136.545066 -245.111121)
		(end 136.357868 -245.060978)
		(width 0.088646)
		(layer "In2.Cu")
		(net "M_F_CPU1_SB_CS_N<0>")
	)
	(arc
		(start 136.170416 -244.736366)
		(mid 136.094736 -244.45392)
		(end 135.887968 -244.247162)
		(width 0.088646)
		(layer "In2.Cu")
		(net "M_F_CPU1_SB_CS_N<0>")
	)
	(segment
		(start 183.136286 -239.40389)
		(end 183.340248 -239.199928)
		(width 0.20066)
		(layer "F.Cu")
		(net "M_F_CPU1_SB_CB<7>")
	)
	(segment
		(start 176.896014 -238.966756)
		(end 178.000914 -238.966756)
		(width 0.20066)
		(layer "F.Cu")
		(net "M_F_CPU1_SB_CB<7>")
	)
	(segment
		(start 183.340248 -239.199928)
		(end 183.340248 -238.948976)
		(width 0.20066)
		(layer "F.Cu")
		(net "M_F_CPU1_SB_CB<7>")
	)
	(segment
		(start 183.958484 -238.714788)
		(end 184.210452 -238.966756)
		(width 0.20066)
		(layer "F.Cu")
		(net "M_F_CPU1_SB_CB<7>")
	)
	(segment
		(start 182.455058 -239.40389)
		(end 183.136286 -239.40389)
		(width 0.20066)
		(layer "F.Cu")
		(net "M_F_CPU1_SB_CB<7>")
	)
	(segment
		(start 183.340248 -238.948976)
		(end 183.574436 -238.714788)
		(width 0.20066)
		(layer "F.Cu")
		(net "M_F_CPU1_SB_CB<7>")
	)
	(segment
		(start 184.210452 -238.966756)
		(end 185.544714 -238.966756)
		(width 0.20066)
		(layer "F.Cu")
		(net "M_F_CPU1_SB_CB<7>")
	)
	(segment
		(start 135.135112 -240.66754)
		(end 135.135366 -240.667286)
		(width 0.20066)
		(layer "F.Cu")
		(net "M_F_CPU1_SB_CB<7>")
	)
	(segment
		(start 180.423058 -239.39881)
		(end 180.427884 -239.39881)
		(width 0.101854)
		(layer "F.Cu")
		(net "M_F_CPU1_SB_CB<7>")
	)
	(segment
		(start 180.434996 -239.391698)
		(end 182.442866 -239.391698)
		(width 0.1016)
		(layer "F.Cu")
		(net "M_F_CPU1_SB_CB<7>")
	)
	(segment
		(start 180.131212 -239.39881)
		(end 180.423058 -239.39881)
		(width 0.20066)
		(layer "F.Cu")
		(net "M_F_CPU1_SB_CB<7>")
	)
	(segment
		(start 182.442866 -239.391698)
		(end 182.455058 -239.40389)
		(width 0.1016)
		(layer "F.Cu")
		(net "M_F_CPU1_SB_CB<7>")
	)
	(segment
		(start 135.135112 -241.203226)
		(end 135.135112 -240.66754)
		(width 0.20066)
		(layer "F.Cu")
		(net "M_F_CPU1_SB_CB<7>")
	)
	(segment
		(start 179.699158 -238.966756)
		(end 180.131212 -239.39881)
		(width 0.20066)
		(layer "F.Cu")
		(net "M_F_CPU1_SB_CB<7>")
	)
	(segment
		(start 180.427884 -239.39881)
		(end 180.434996 -239.391698)
		(width 0.1016)
		(layer "F.Cu")
		(net "M_F_CPU1_SB_CB<7>")
	)
	(segment
		(start 178.000914 -238.966756)
		(end 179.699158 -238.966756)
		(width 0.20066)
		(layer "F.Cu")
		(net "M_F_CPU1_SB_CB<7>")
	)
	(segment
		(start 183.574436 -238.714788)
		(end 183.958484 -238.714788)
		(width 0.20066)
		(layer "F.Cu")
		(net "M_F_CPU1_SB_CB<7>")
	)
	(segment
		(start 175.968406 -238.966756)
		(end 175.775366 -238.773716)
		(width 0.18288)
		(layer "In2.Cu")
		(net "M_F_CPU1_SB_CB<7>")
	)
	(segment
		(start 167.116506 -237.69955)
		(end 165.569138 -237.69955)
		(width 0.18288)
		(layer "In2.Cu")
		(net "M_F_CPU1_SB_CB<7>")
	)
	(segment
		(start 173.226984 -238.542576)
		(end 172.388022 -238.542576)
		(width 0.18288)
		(layer "In2.Cu")
		(net "M_F_CPU1_SB_CB<7>")
	)
	(segment
		(start 173.546516 -239.382046)
		(end 173.353476 -239.189006)
		(width 0.18288)
		(layer "In2.Cu")
		(net "M_F_CPU1_SB_CB<7>")
	)
	(segment
		(start 174.966376 -238.090456)
		(end 174.966376 -238.351568)
		(width 0.18288)
		(layer "In2.Cu")
		(net "M_F_CPU1_SB_CB<7>")
	)
	(segment
		(start 175.775366 -238.773716)
		(end 175.775366 -238.128556)
		(width 0.18288)
		(layer "In2.Cu")
		(net "M_F_CPU1_SB_CB<7>")
	)
	(segment
		(start 172.216826 -238.714026)
		(end 171.632626 -238.714026)
		(width 0.18288)
		(layer "In2.Cu")
		(net "M_F_CPU1_SB_CB<7>")
	)
	(segment
		(start 171.505626 -238.587026)
		(end 168.003982 -238.587026)
		(width 0.18288)
		(layer "In2.Cu")
		(net "M_F_CPU1_SB_CB<7>")
	)
	(segment
		(start 164.681662 -238.587026)
		(end 161.344102 -238.587026)
		(width 0.18288)
		(layer "In2.Cu")
		(net "M_F_CPU1_SB_CB<7>")
	)
	(segment
		(start 156.965142 -239.435386)
		(end 154.142694 -242.257834)
		(width 0.18288)
		(layer "In2.Cu")
		(net "M_F_CPU1_SB_CB<7>")
	)
	(segment
		(start 174.114968 -238.667798)
		(end 174.114968 -239.189006)
		(width 0.18288)
		(layer "In2.Cu")
		(net "M_F_CPU1_SB_CB<7>")
	)
	(segment
		(start 172.343572 -238.587026)
		(end 172.343572 -238.58728)
		(width 0.18288)
		(layer "In2.Cu")
		(net "M_F_CPU1_SB_CB<7>")
	)
	(segment
		(start 137.580116 -242.294918)
		(end 137.580116 -242.294664)
		(width 0.088646)
		(layer "In2.Cu")
		(net "M_F_CPU1_SB_CB<7>")
	)
	(segment
		(start 172.343572 -238.58728)
		(end 172.216826 -238.714026)
		(width 0.18288)
		(layer "In2.Cu")
		(net "M_F_CPU1_SB_CB<7>")
	)
	(segment
		(start 159.98444 -239.66043)
		(end 159.759396 -239.435386)
		(width 0.18288)
		(layer "In2.Cu")
		(net "M_F_CPU1_SB_CB<7>")
	)
	(segment
		(start 168.003982 -238.587026)
		(end 167.116506 -237.69955)
		(width 0.18288)
		(layer "In2.Cu")
		(net "M_F_CPU1_SB_CB<7>")
	)
	(segment
		(start 174.7901 -238.527844)
		(end 174.254922 -238.527844)
		(width 0.18288)
		(layer "In2.Cu")
		(net "M_F_CPU1_SB_CB<7>")
	)
	(segment
		(start 172.388022 -238.542576)
		(end 172.343572 -238.587026)
		(width 0.18288)
		(layer "In2.Cu")
		(net "M_F_CPU1_SB_CB<7>")
	)
	(segment
		(start 173.353476 -238.669068)
		(end 173.226984 -238.542576)
		(width 0.18288)
		(layer "In2.Cu")
		(net "M_F_CPU1_SB_CB<7>")
	)
	(segment
		(start 175.577246 -237.930436)
		(end 175.126396 -237.930436)
		(width 0.18288)
		(layer "In2.Cu")
		(net "M_F_CPU1_SB_CB<7>")
	)
	(segment
		(start 138.656568 -242.257834)
		(end 138.368024 -242.546378)
		(width 0.088646)
		(layer "In2.Cu")
		(net "M_F_CPU1_SB_CB<7>")
	)
	(segment
		(start 174.254922 -238.527844)
		(end 174.114968 -238.667798)
		(width 0.18288)
		(layer "In2.Cu")
		(net "M_F_CPU1_SB_CB<7>")
	)
	(segment
		(start 174.966376 -238.351568)
		(end 174.7901 -238.527844)
		(width 0.18288)
		(layer "In2.Cu")
		(net "M_F_CPU1_SB_CB<7>")
	)
	(segment
		(start 175.126396 -237.930436)
		(end 174.966376 -238.090456)
		(width 0.18288)
		(layer "In2.Cu")
		(net "M_F_CPU1_SB_CB<7>")
	)
	(segment
		(start 136.170416 -241.481102)
		(end 136.170416 -241.471196)
		(width 0.088646)
		(layer "In2.Cu")
		(net "M_F_CPU1_SB_CB<7>")
	)
	(segment
		(start 176.896014 -238.966756)
		(end 175.968406 -238.966756)
		(width 0.18288)
		(layer "In2.Cu")
		(net "M_F_CPU1_SB_CB<7>")
	)
	(segment
		(start 136.358122 -241.80546)
		(end 136.357614 -241.805206)
		(width 0.088646)
		(layer "In2.Cu")
		(net "M_F_CPU1_SB_CB<7>")
	)
	(segment
		(start 135.887968 -240.991644)
		(end 135.840978 -240.964466)
		(width 0.088646)
		(layer "In2.Cu")
		(net "M_F_CPU1_SB_CB<7>")
	)
	(segment
		(start 173.353476 -239.189006)
		(end 173.353476 -238.669068)
		(width 0.18288)
		(layer "In2.Cu")
		(net "M_F_CPU1_SB_CB<7>")
	)
	(segment
		(start 161.344102 -238.587026)
		(end 160.270698 -239.66043)
		(width 0.18288)
		(layer "In2.Cu")
		(net "M_F_CPU1_SB_CB<7>")
	)
	(segment
		(start 160.270698 -239.66043)
		(end 159.98444 -239.66043)
		(width 0.18288)
		(layer "In2.Cu")
		(net "M_F_CPU1_SB_CB<7>")
	)
	(segment
		(start 154.142694 -242.257834)
		(end 139.325096 -242.257834)
		(width 0.18288)
		(layer "In2.Cu")
		(net "M_F_CPU1_SB_CB<7>")
	)
	(segment
		(start 159.759396 -239.435386)
		(end 156.965142 -239.435386)
		(width 0.18288)
		(layer "In2.Cu")
		(net "M_F_CPU1_SB_CB<7>")
	)
	(segment
		(start 137.767568 -242.619276)
		(end 137.758678 -242.614196)
		(width 0.088646)
		(layer "In2.Cu")
		(net "M_F_CPU1_SB_CB<7>")
	)
	(segment
		(start 165.569138 -237.69955)
		(end 164.681662 -238.587026)
		(width 0.18288)
		(layer "In2.Cu")
		(net "M_F_CPU1_SB_CB<7>")
	)
	(segment
		(start 171.632626 -238.714026)
		(end 171.505626 -238.587026)
		(width 0.18288)
		(layer "In2.Cu")
		(net "M_F_CPU1_SB_CB<7>")
	)
	(segment
		(start 175.775366 -238.128556)
		(end 175.577246 -237.930436)
		(width 0.18288)
		(layer "In2.Cu")
		(net "M_F_CPU1_SB_CB<7>")
	)
	(segment
		(start 135.801608 -240.943638)
		(end 135.30707 -240.706402)
		(width 0.088646)
		(layer "In2.Cu")
		(net "M_F_CPU1_SB_CB<7>")
	)
	(segment
		(start 174.114968 -239.189006)
		(end 173.921928 -239.382046)
		(width 0.18288)
		(layer "In2.Cu")
		(net "M_F_CPU1_SB_CB<7>")
	)
	(segment
		(start 173.921928 -239.382046)
		(end 173.546516 -239.382046)
		(width 0.18288)
		(layer "In2.Cu")
		(net "M_F_CPU1_SB_CB<7>")
	)
	(segment
		(start 139.325096 -242.257834)
		(end 138.656568 -242.257834)
		(width 0.088646)
		(layer "In2.Cu")
		(net "M_F_CPU1_SB_CB<7>")
	)
	(arc
		(start 135.840978 -240.964466)
		(mid 135.821495 -240.95367)
		(end 135.801608 -240.943638)
		(width 0.088646)
		(layer "In2.Cu")
		(net "M_F_CPU1_SB_CB<7>")
	)
	(arc
		(start 136.732264 -241.80546)
		(mid 136.54521 -241.85551)
		(end 136.358122 -241.80546)
		(width 0.088646)
		(layer "In2.Cu")
		(net "M_F_CPU1_SB_CB<7>")
	)
	(arc
		(start 137.580116 -242.294664)
		(mid 137.504436 -242.012218)
		(end 137.297668 -241.80546)
		(width 0.088646)
		(layer "In2.Cu")
		(net "M_F_CPU1_SB_CB<7>")
	)
	(arc
		(start 138.368024 -242.546378)
		(mid 138.251123 -242.570823)
		(end 138.141964 -242.619276)
		(width 0.088646)
		(layer "In2.Cu")
		(net "M_F_CPU1_SB_CB<7>")
	)
	(arc
		(start 136.170416 -241.471196)
		(mid 136.092305 -241.194247)
		(end 135.887968 -240.991644)
		(width 0.088646)
		(layer "In2.Cu")
		(net "M_F_CPU1_SB_CB<7>")
	)
	(arc
		(start 136.357614 -241.805206)
		(mid 136.220569 -241.668246)
		(end 136.170416 -241.481102)
		(width 0.088646)
		(layer "In2.Cu")
		(net "M_F_CPU1_SB_CB<7>")
	)
	(arc
		(start 137.758678 -242.614196)
		(mid 137.627764 -242.477836)
		(end 137.580116 -242.294918)
		(width 0.088646)
		(layer "In2.Cu")
		(net "M_F_CPU1_SB_CB<7>")
	)
	(arc
		(start 135.222488 -240.67897)
		(mid 135.179043 -240.672265)
		(end 135.135366 -240.667286)
		(width 0.088646)
		(layer "In2.Cu")
		(net "M_F_CPU1_SB_CB<7>")
	)
	(arc
		(start 138.141964 -242.619276)
		(mid 137.954766 -242.669419)
		(end 137.767568 -242.619276)
		(width 0.088646)
		(layer "In2.Cu")
		(net "M_F_CPU1_SB_CB<7>")
	)
	(arc
		(start 137.297668 -241.80546)
		(mid 137.014966 -241.729718)
		(end 136.732264 -241.80546)
		(width 0.088646)
		(layer "In2.Cu")
		(net "M_F_CPU1_SB_CB<7>")
	)
	(arc
		(start 135.30707 -240.706402)
		(mid 135.265721 -240.689782)
		(end 135.222488 -240.67897)
		(width 0.088646)
		(layer "In2.Cu")
		(net "M_F_CPU1_SB_CB<7>")
	)
	(segment
		(start 180.423058 -241.098832)
		(end 180.427884 -241.098832)
		(width 0.101854)
		(layer "F.Cu")
		(net "M_F_CPU1_SB_CB<6>")
	)
	(segment
		(start 180.434996 -241.09172)
		(end 182.442866 -241.09172)
		(width 0.1016)
		(layer "F.Cu")
		(net "M_F_CPU1_SB_CB<6>")
	)
	(segment
		(start 184.210452 -240.666778)
		(end 185.544714 -240.666778)
		(width 0.20066)
		(layer "F.Cu")
		(net "M_F_CPU1_SB_CB<6>")
	)
	(segment
		(start 183.136286 -241.103912)
		(end 183.340248 -240.89995)
		(width 0.20066)
		(layer "F.Cu")
		(net "M_F_CPU1_SB_CB<6>")
	)
	(segment
		(start 183.340248 -240.89995)
		(end 183.340248 -240.648998)
		(width 0.20066)
		(layer "F.Cu")
		(net "M_F_CPU1_SB_CB<6>")
	)
	(segment
		(start 180.131212 -241.098832)
		(end 180.423058 -241.098832)
		(width 0.20066)
		(layer "F.Cu")
		(net "M_F_CPU1_SB_CB<6>")
	)
	(segment
		(start 183.958484 -240.41481)
		(end 184.210452 -240.666778)
		(width 0.20066)
		(layer "F.Cu")
		(net "M_F_CPU1_SB_CB<6>")
	)
	(segment
		(start 176.896014 -240.666778)
		(end 178.000914 -240.666778)
		(width 0.20066)
		(layer "F.Cu")
		(net "M_F_CPU1_SB_CB<6>")
	)
	(segment
		(start 180.427884 -241.098832)
		(end 180.434996 -241.09172)
		(width 0.1016)
		(layer "F.Cu")
		(net "M_F_CPU1_SB_CB<6>")
	)
	(segment
		(start 183.574436 -240.41481)
		(end 183.958484 -240.41481)
		(width 0.20066)
		(layer "F.Cu")
		(net "M_F_CPU1_SB_CB<6>")
	)
	(segment
		(start 182.442866 -241.09172)
		(end 182.455058 -241.103912)
		(width 0.1016)
		(layer "F.Cu")
		(net "M_F_CPU1_SB_CB<6>")
	)
	(segment
		(start 134.665466 -242.017042)
		(end 134.665212 -242.016788)
		(width 0.20066)
		(layer "F.Cu")
		(net "M_F_CPU1_SB_CB<6>")
	)
	(segment
		(start 179.699158 -240.666778)
		(end 180.131212 -241.098832)
		(width 0.20066)
		(layer "F.Cu")
		(net "M_F_CPU1_SB_CB<6>")
	)
	(segment
		(start 178.000914 -240.666778)
		(end 179.699158 -240.666778)
		(width 0.20066)
		(layer "F.Cu")
		(net "M_F_CPU1_SB_CB<6>")
	)
	(segment
		(start 183.340248 -240.648998)
		(end 183.574436 -240.41481)
		(width 0.20066)
		(layer "F.Cu")
		(net "M_F_CPU1_SB_CB<6>")
	)
	(segment
		(start 134.665212 -242.016788)
		(end 134.665212 -241.481102)
		(width 0.20066)
		(layer "F.Cu")
		(net "M_F_CPU1_SB_CB<6>")
	)
	(segment
		(start 182.455058 -241.103912)
		(end 183.136286 -241.103912)
		(width 0.20066)
		(layer "F.Cu")
		(net "M_F_CPU1_SB_CB<6>")
	)
	(segment
		(start 152.057354 -243.664486)
		(end 151.6761 -243.283232)
		(width 0.18288)
		(layer "In2.Cu")
		(net "M_F_CPU1_SB_CB<6>")
	)
	(segment
		(start 137.297668 -243.433346)
		(end 137.288778 -243.428266)
		(width 0.088646)
		(layer "In2.Cu")
		(net "M_F_CPU1_SB_CB<6>")
	)
	(segment
		(start 159.618172 -241.126772)
		(end 157.870906 -241.126772)
		(width 0.18288)
		(layer "In2.Cu")
		(net "M_F_CPU1_SB_CB<6>")
	)
	(segment
		(start 157.870906 -241.126772)
		(end 157.67304 -241.324638)
		(width 0.18288)
		(layer "In2.Cu")
		(net "M_F_CPU1_SB_CB<6>")
	)
	(segment
		(start 134.295388 -241.538252)
		(end 134.352538 -241.481102)
		(width 0.088646)
		(layer "In2.Cu")
		(net "M_F_CPU1_SB_CB<6>")
	)
	(segment
		(start 176.50079 -241.062002)
		(end 175.91913 -241.062002)
		(width 0.18288)
		(layer "In2.Cu")
		(net "M_F_CPU1_SB_CB<6>")
	)
	(segment
		(start 174.182786 -240.764568)
		(end 173.721014 -240.764568)
		(width 0.18288)
		(layer "In2.Cu")
		(net "M_F_CPU1_SB_CB<6>")
	)
	(segment
		(start 134.948168 -242.619276)
		(end 134.939278 -242.614196)
		(width 0.088646)
		(layer "In2.Cu")
		(net "M_F_CPU1_SB_CB<6>")
	)
	(segment
		(start 164.008562 -240.46688)
		(end 163.807902 -240.26622)
		(width 0.18288)
		(layer "In2.Cu")
		(net "M_F_CPU1_SB_CB<6>")
	)
	(segment
		(start 172.314362 -240.441226)
		(end 171.581826 -240.441226)
		(width 0.18288)
		(layer "In2.Cu")
		(net "M_F_CPU1_SB_CB<6>")
	)
	(segment
		(start 151.6761 -243.283232)
		(end 139.325096 -243.283232)
		(width 0.18288)
		(layer "In2.Cu")
		(net "M_F_CPU1_SB_CB<6>")
	)
	(segment
		(start 164.478716 -240.46688)
		(end 164.008562 -240.46688)
		(width 0.18288)
		(layer "In2.Cu")
		(net "M_F_CPU1_SB_CB<6>")
	)
	(segment
		(start 172.51299 -240.242598)
		(end 172.314362 -240.441226)
		(width 0.18288)
		(layer "In2.Cu")
		(net "M_F_CPU1_SB_CB<6>")
	)
	(segment
		(start 156.916628 -241.505232)
		(end 154.757374 -243.664486)
		(width 0.18288)
		(layer "In2.Cu")
		(net "M_F_CPU1_SB_CB<6>")
	)
	(segment
		(start 167.877744 -240.452148)
		(end 167.663876 -240.23828)
		(width 0.18288)
		(layer "In2.Cu")
		(net "M_F_CPU1_SB_CB<6>")
	)
	(segment
		(start 175.552354 -239.947196)
		(end 175.000158 -239.947196)
		(width 0.18288)
		(layer "In2.Cu")
		(net "M_F_CPU1_SB_CB<6>")
	)
	(segment
		(start 139.325096 -243.283232)
		(end 138.761978 -243.283232)
		(width 0.088646)
		(layer "In2.Cu")
		(net "M_F_CPU1_SB_CB<6>")
	)
	(segment
		(start 171.581826 -240.441226)
		(end 171.413424 -240.272824)
		(width 0.18288)
		(layer "In2.Cu")
		(net "M_F_CPU1_SB_CB<6>")
	)
	(segment
		(start 167.878506 -240.452402)
		(end 167.877744 -240.452148)
		(width 0.18288)
		(layer "In2.Cu")
		(net "M_F_CPU1_SB_CB<6>")
	)
	(segment
		(start 167.663876 -240.23828)
		(end 164.707316 -240.23828)
		(width 0.18288)
		(layer "In2.Cu")
		(net "M_F_CPU1_SB_CB<6>")
	)
	(segment
		(start 169.237152 -240.272824)
		(end 169.057574 -240.452402)
		(width 0.18288)
		(layer "In2.Cu")
		(net "M_F_CPU1_SB_CB<6>")
	)
	(segment
		(start 161.355532 -240.26622)
		(end 160.367726 -241.254026)
		(width 0.18288)
		(layer "In2.Cu")
		(net "M_F_CPU1_SB_CB<6>")
	)
	(segment
		(start 171.413424 -240.272824)
		(end 169.237152 -240.272824)
		(width 0.18288)
		(layer "In2.Cu")
		(net "M_F_CPU1_SB_CB<6>")
	)
	(segment
		(start 154.757374 -243.664486)
		(end 152.057354 -243.664486)
		(width 0.18288)
		(layer "In2.Cu")
		(net "M_F_CPU1_SB_CB<6>")
	)
	(segment
		(start 175.745394 -240.888266)
		(end 175.745394 -240.140236)
		(width 0.18288)
		(layer "In2.Cu")
		(net "M_F_CPU1_SB_CB<6>")
	)
	(segment
		(start 160.367726 -241.254026)
		(end 159.745426 -241.254026)
		(width 0.18288)
		(layer "In2.Cu")
		(net "M_F_CPU1_SB_CB<6>")
	)
	(segment
		(start 163.807902 -240.26622)
		(end 161.355532 -240.26622)
		(width 0.18288)
		(layer "In2.Cu")
		(net "M_F_CPU1_SB_CB<6>")
	)
	(segment
		(start 138.761978 -243.283232)
		(end 138.611864 -243.433346)
		(width 0.088646)
		(layer "In2.Cu")
		(net "M_F_CPU1_SB_CB<6>")
	)
	(segment
		(start 159.745426 -241.254026)
		(end 159.618172 -241.126772)
		(width 0.18288)
		(layer "In2.Cu")
		(net "M_F_CPU1_SB_CB<6>")
	)
	(segment
		(start 164.707316 -240.23828)
		(end 164.478716 -240.46688)
		(width 0.18288)
		(layer "In2.Cu")
		(net "M_F_CPU1_SB_CB<6>")
	)
	(segment
		(start 134.48411 -241.809016)
		(end 134.478014 -241.80546)
		(width 0.088646)
		(layer "In2.Cu")
		(net "M_F_CPU1_SB_CB<6>")
	)
	(segment
		(start 175.745394 -240.140236)
		(end 175.552354 -239.947196)
		(width 0.18288)
		(layer "In2.Cu")
		(net "M_F_CPU1_SB_CB<6>")
	)
	(segment
		(start 175.91913 -241.062002)
		(end 175.745394 -240.888266)
		(width 0.18288)
		(layer "In2.Cu")
		(net "M_F_CPU1_SB_CB<6>")
	)
	(segment
		(start 134.352538 -241.481102)
		(end 134.665212 -241.481102)
		(width 0.088646)
		(layer "In2.Cu")
		(net "M_F_CPU1_SB_CB<6>")
	)
	(segment
		(start 137.110216 -243.108988)
		(end 137.110216 -243.090446)
		(width 0.088646)
		(layer "In2.Cu")
		(net "M_F_CPU1_SB_CB<6>")
	)
	(segment
		(start 175.000158 -239.947196)
		(end 174.182786 -240.764568)
		(width 0.18288)
		(layer "In2.Cu")
		(net "M_F_CPU1_SB_CB<6>")
	)
	(segment
		(start 176.896014 -240.666778)
		(end 176.50079 -241.062002)
		(width 0.18288)
		(layer "In2.Cu")
		(net "M_F_CPU1_SB_CB<6>")
	)
	(segment
		(start 157.67304 -241.324638)
		(end 156.916628 -241.505232)
		(width 0.18288)
		(layer "In2.Cu")
		(net "M_F_CPU1_SB_CB<6>")
	)
	(segment
		(start 173.199044 -240.242598)
		(end 172.51299 -240.242598)
		(width 0.18288)
		(layer "In2.Cu")
		(net "M_F_CPU1_SB_CB<6>")
	)
	(segment
		(start 173.721014 -240.764568)
		(end 173.199044 -240.242598)
		(width 0.18288)
		(layer "In2.Cu")
		(net "M_F_CPU1_SB_CB<6>")
	)
	(segment
		(start 169.057574 -240.452402)
		(end 167.878506 -240.452402)
		(width 0.18288)
		(layer "In2.Cu")
		(net "M_F_CPU1_SB_CB<6>")
	)
	(arc
		(start 134.760716 -242.294918)
		(mid 134.686725 -242.015352)
		(end 134.48411 -241.809016)
		(width 0.088646)
		(layer "In2.Cu")
		(net "M_F_CPU1_SB_CB<6>")
	)
	(arc
		(start 135.322564 -242.619276)
		(mid 135.135366 -242.669419)
		(end 134.948168 -242.619276)
		(width 0.088646)
		(layer "In2.Cu")
		(net "M_F_CPU1_SB_CB<6>")
	)
	(arc
		(start 138.611864 -243.433346)
		(mid 138.424666 -243.483489)
		(end 138.237468 -243.433346)
		(width 0.088646)
		(layer "In2.Cu")
		(net "M_F_CPU1_SB_CB<6>")
	)
	(arc
		(start 134.478014 -241.80546)
		(mid 134.356346 -241.692605)
		(end 134.295388 -241.538252)
		(width 0.088646)
		(layer "In2.Cu")
		(net "M_F_CPU1_SB_CB<6>")
	)
	(arc
		(start 136.262364 -242.619276)
		(mid 136.075166 -242.669419)
		(end 135.887968 -242.619276)
		(width 0.088646)
		(layer "In2.Cu")
		(net "M_F_CPU1_SB_CB<6>")
	)
	(arc
		(start 136.827768 -242.619276)
		(mid 136.545066 -242.543534)
		(end 136.262364 -242.619276)
		(width 0.088646)
		(layer "In2.Cu")
		(net "M_F_CPU1_SB_CB<6>")
	)
	(arc
		(start 138.237468 -243.433346)
		(mid 137.954766 -243.35757)
		(end 137.672064 -243.433346)
		(width 0.088646)
		(layer "In2.Cu")
		(net "M_F_CPU1_SB_CB<6>")
	)
	(arc
		(start 137.288778 -243.428266)
		(mid 137.157864 -243.291906)
		(end 137.110216 -243.108988)
		(width 0.088646)
		(layer "In2.Cu")
		(net "M_F_CPU1_SB_CB<6>")
	)
	(arc
		(start 134.939278 -242.614196)
		(mid 134.808364 -242.477836)
		(end 134.760716 -242.294918)
		(width 0.088646)
		(layer "In2.Cu")
		(net "M_F_CPU1_SB_CB<6>")
	)
	(arc
		(start 137.672064 -243.433346)
		(mid 137.484866 -243.483489)
		(end 137.297668 -243.433346)
		(width 0.088646)
		(layer "In2.Cu")
		(net "M_F_CPU1_SB_CB<6>")
	)
	(arc
		(start 135.887968 -242.619276)
		(mid 135.605266 -242.543534)
		(end 135.322564 -242.619276)
		(width 0.088646)
		(layer "In2.Cu")
		(net "M_F_CPU1_SB_CB<6>")
	)
	(arc
		(start 137.110216 -243.090446)
		(mid 137.030054 -242.818257)
		(end 136.827768 -242.619276)
		(width 0.088646)
		(layer "In2.Cu")
		(net "M_F_CPU1_SB_CB<6>")
	)
	(segment
		(start 176.145444 -240.065306)
		(end 175.67021 -240.065306)
		(width 0.20066)
		(layer "F.Cu")
		(net "M_F_CPU1_SB_CB<5>")
	)
	(segment
		(start 175.67021 -240.065306)
		(end 175.421544 -239.81664)
		(width 0.20066)
		(layer "F.Cu")
		(net "M_F_CPU1_SB_CB<5>")
	)
	(segment
		(start 179.011326 -239.385348)
		(end 179.004976 -239.391698)
		(width 0.1016)
		(layer "F.Cu")
		(net "M_F_CPU1_SB_CB<5>")
	)
	(segment
		(start 175.421544 -239.81664)
		(end 173.900846 -239.81664)
		(width 0.20066)
		(layer "F.Cu")
		(net "M_F_CPU1_SB_CB<5>")
	)
	(segment
		(start 133.255512 -240.66754)
		(end 133.255766 -240.667286)
		(width 0.20066)
		(layer "F.Cu")
		(net "M_F_CPU1_SB_CB<5>")
	)
	(segment
		(start 176.816258 -239.391698)
		(end 176.796192 -239.391698)
		(width 0.101854)
		(layer "F.Cu")
		(net "M_F_CPU1_SB_CB<5>")
	)
	(segment
		(start 176.451514 -239.391698)
		(end 176.333404 -239.509808)
		(width 0.20066)
		(layer "F.Cu")
		(net "M_F_CPU1_SB_CB<5>")
	)
	(segment
		(start 176.333404 -239.877346)
		(end 176.145444 -240.065306)
		(width 0.20066)
		(layer "F.Cu")
		(net "M_F_CPU1_SB_CB<5>")
	)
	(segment
		(start 173.900846 -239.81664)
		(end 172.795946 -239.81664)
		(width 0.20066)
		(layer "F.Cu")
		(net "M_F_CPU1_SB_CB<5>")
	)
	(segment
		(start 133.255512 -241.203226)
		(end 133.255512 -240.66754)
		(width 0.20066)
		(layer "F.Cu")
		(net "M_F_CPU1_SB_CB<5>")
	)
	(segment
		(start 179.852828 -239.816894)
		(end 179.421282 -239.385348)
		(width 0.20066)
		(layer "F.Cu")
		(net "M_F_CPU1_SB_CB<5>")
	)
	(segment
		(start 181.444392 -239.816894)
		(end 179.852828 -239.816894)
		(width 0.20066)
		(layer "F.Cu")
		(net "M_F_CPU1_SB_CB<5>")
	)
	(segment
		(start 181.444646 -239.81664)
		(end 181.444392 -239.816894)
		(width 0.20066)
		(layer "F.Cu")
		(net "M_F_CPU1_SB_CB<5>")
	)
	(segment
		(start 176.796192 -239.391698)
		(end 176.451514 -239.391698)
		(width 0.20066)
		(layer "F.Cu")
		(net "M_F_CPU1_SB_CB<5>")
	)
	(segment
		(start 179.004976 -239.391698)
		(end 176.816258 -239.391698)
		(width 0.1016)
		(layer "F.Cu")
		(net "M_F_CPU1_SB_CB<5>")
	)
	(segment
		(start 176.333404 -239.509808)
		(end 176.333404 -239.877346)
		(width 0.20066)
		(layer "F.Cu")
		(net "M_F_CPU1_SB_CB<5>")
	)
	(segment
		(start 179.421282 -239.385348)
		(end 179.011326 -239.385348)
		(width 0.20066)
		(layer "F.Cu")
		(net "M_F_CPU1_SB_CB<5>")
	)
	(segment
		(start 156.20746 -241.031268)
		(end 155.34513 -241.893598)
		(width 0.18288)
		(layer "In2.Cu")
		(net "M_F_CPU1_SB_CB<5>")
	)
	(segment
		(start 155.34513 -241.893598)
		(end 155.34513 -242.331494)
		(width 0.18288)
		(layer "In2.Cu")
		(net "M_F_CPU1_SB_CB<5>")
	)
	(segment
		(start 159.352488 -240.618772)
		(end 158.38932 -240.618772)
		(width 0.18288)
		(layer "In2.Cu")
		(net "M_F_CPU1_SB_CB<5>")
	)
	(segment
		(start 163.9951 -239.095026)
		(end 163.331906 -239.75822)
		(width 0.18288)
		(layer "In2.Cu")
		(net "M_F_CPU1_SB_CB<5>")
	)
	(segment
		(start 161.813494 -239.143032)
		(end 161.526728 -239.143032)
		(width 0.18288)
		(layer "In2.Cu")
		(net "M_F_CPU1_SB_CB<5>")
	)
	(segment
		(start 151.901652 -242.770152)
		(end 139.325096 -242.770152)
		(width 0.18288)
		(layer "In2.Cu")
		(net "M_F_CPU1_SB_CB<5>")
	)
	(segment
		(start 137.202418 -241.970814)
		(end 137.202164 -241.97056)
		(width 0.088646)
		(layer "In2.Cu")
		(net "M_F_CPU1_SB_CB<5>")
	)
	(segment
		(start 133.56844 -240.667286)
		(end 133.255766 -240.667286)
		(width 0.088646)
		(layer "In2.Cu")
		(net "M_F_CPU1_SB_CB<5>")
	)
	(segment
		(start 162.428682 -239.75822)
		(end 161.813494 -239.143032)
		(width 0.18288)
		(layer "In2.Cu")
		(net "M_F_CPU1_SB_CB<5>")
	)
	(segment
		(start 134.852664 -241.156744)
		(end 134.848854 -241.154458)
		(width 0.088646)
		(layer "In2.Cu")
		(net "M_F_CPU1_SB_CB<5>")
	)
	(segment
		(start 135.792464 -241.156744)
		(end 135.788146 -241.154204)
		(width 0.088646)
		(layer "In2.Cu")
		(net "M_F_CPU1_SB_CB<5>")
	)
	(segment
		(start 133.634226 -240.733072)
		(end 133.56844 -240.667286)
		(width 0.088646)
		(layer "In2.Cu")
		(net "M_F_CPU1_SB_CB<5>")
	)
	(segment
		(start 157.028642 -240.136426)
		(end 157.028642 -240.70183)
		(width 0.18288)
		(layer "In2.Cu")
		(net "M_F_CPU1_SB_CB<5>")
	)
	(segment
		(start 166.52748 -239.215422)
		(end 166.52748 -238.736632)
		(width 0.18288)
		(layer "In2.Cu")
		(net "M_F_CPU1_SB_CB<5>")
	)
	(segment
		(start 155.065984 -242.61064)
		(end 154.628088 -242.61064)
		(width 0.18288)
		(layer "In2.Cu")
		(net "M_F_CPU1_SB_CB<5>")
	)
	(segment
		(start 166.32682 -238.535972)
		(end 166.016432 -238.535972)
		(width 0.18288)
		(layer "In2.Cu")
		(net "M_F_CPU1_SB_CB<5>")
	)
	(segment
		(start 165.823392 -238.729012)
		(end 165.823392 -239.129062)
		(width 0.18288)
		(layer "In2.Cu")
		(net "M_F_CPU1_SB_CB<5>")
	)
	(segment
		(start 134.858506 -241.160046)
		(end 134.852664 -241.156744)
		(width 0.088646)
		(layer "In2.Cu")
		(net "M_F_CPU1_SB_CB<5>")
	)
	(segment
		(start 164.335714 -239.095026)
		(end 163.9951 -239.095026)
		(width 0.18288)
		(layer "In2.Cu")
		(net "M_F_CPU1_SB_CB<5>")
	)
	(segment
		(start 154.628088 -242.61064)
		(end 154.086306 -243.152422)
		(width 0.18288)
		(layer "In2.Cu")
		(net "M_F_CPU1_SB_CB<5>")
	)
	(segment
		(start 166.72052 -239.408462)
		(end 166.52748 -239.215422)
		(width 0.18288)
		(layer "In2.Cu")
		(net "M_F_CPU1_SB_CB<5>")
	)
	(segment
		(start 164.960046 -239.719358)
		(end 164.335714 -239.095026)
		(width 0.18288)
		(layer "In2.Cu")
		(net "M_F_CPU1_SB_CB<5>")
	)
	(segment
		(start 161.526728 -239.143032)
		(end 160.481518 -240.188242)
		(width 0.18288)
		(layer "In2.Cu")
		(net "M_F_CPU1_SB_CB<5>")
	)
	(segment
		(start 170.88866 -239.76076)
		(end 169.972736 -239.76076)
		(width 0.18288)
		(layer "In2.Cu")
		(net "M_F_CPU1_SB_CB<5>")
	)
	(segment
		(start 169.02176 -239.117378)
		(end 168.875456 -239.263682)
		(width 0.18288)
		(layer "In2.Cu")
		(net "M_F_CPU1_SB_CB<5>")
	)
	(segment
		(start 172.795946 -239.81664)
		(end 172.201332 -239.222026)
		(width 0.18288)
		(layer "In2.Cu")
		(net "M_F_CPU1_SB_CB<5>")
	)
	(segment
		(start 157.221682 -239.943386)
		(end 157.028642 -240.136426)
		(width 0.18288)
		(layer "In2.Cu")
		(net "M_F_CPU1_SB_CB<5>")
	)
	(segment
		(start 152.509728 -243.152422)
		(end 152.283922 -243.152422)
		(width 0.18288)
		(layer "In2.Cu")
		(net "M_F_CPU1_SB_CB<5>")
	)
	(segment
		(start 152.868884 -242.793266)
		(end 152.509728 -243.152422)
		(width 0.18288)
		(layer "In2.Cu")
		(net "M_F_CPU1_SB_CB<5>")
	)
	(segment
		(start 163.331906 -239.75822)
		(end 162.428682 -239.75822)
		(width 0.18288)
		(layer "In2.Cu")
		(net "M_F_CPU1_SB_CB<5>")
	)
	(segment
		(start 153.213816 -242.793266)
		(end 152.868884 -242.793266)
		(width 0.18288)
		(layer "In2.Cu")
		(net "M_F_CPU1_SB_CB<5>")
	)
	(segment
		(start 168.682416 -239.933734)
		(end 168.184068 -239.933734)
		(width 0.18288)
		(layer "In2.Cu")
		(net "M_F_CPU1_SB_CB<5>")
	)
	(segment
		(start 172.201332 -239.222026)
		(end 171.427394 -239.222026)
		(width 0.18288)
		(layer "In2.Cu")
		(net "M_F_CPU1_SB_CB<5>")
	)
	(segment
		(start 157.028642 -240.70183)
		(end 156.699204 -241.031268)
		(width 0.18288)
		(layer "In2.Cu")
		(net "M_F_CPU1_SB_CB<5>")
	)
	(segment
		(start 157.713934 -239.943386)
		(end 157.221682 -239.943386)
		(width 0.18288)
		(layer "In2.Cu")
		(net "M_F_CPU1_SB_CB<5>")
	)
	(segment
		(start 169.972736 -239.76076)
		(end 169.329354 -239.117378)
		(width 0.18288)
		(layer "In2.Cu")
		(net "M_F_CPU1_SB_CB<5>")
	)
	(segment
		(start 154.086306 -243.152422)
		(end 153.572972 -243.152422)
		(width 0.18288)
		(layer "In2.Cu")
		(net "M_F_CPU1_SB_CB<5>")
	)
	(segment
		(start 135.979916 -241.491008)
		(end 135.979916 -241.481102)
		(width 0.088646)
		(layer "In2.Cu")
		(net "M_F_CPU1_SB_CB<5>")
	)
	(segment
		(start 158.38932 -240.618772)
		(end 157.713934 -239.943386)
		(width 0.18288)
		(layer "In2.Cu")
		(net "M_F_CPU1_SB_CB<5>")
	)
	(segment
		(start 156.699204 -241.031268)
		(end 156.20746 -241.031268)
		(width 0.18288)
		(layer "In2.Cu")
		(net "M_F_CPU1_SB_CB<5>")
	)
	(segment
		(start 139.325096 -242.770152)
		(end 138.954002 -242.770152)
		(width 0.088646)
		(layer "In2.Cu")
		(net "M_F_CPU1_SB_CB<5>")
	)
	(segment
		(start 137.389616 -242.31346)
		(end 137.389616 -242.294918)
		(width 0.088646)
		(layer "In2.Cu")
		(net "M_F_CPU1_SB_CB<5>")
	)
	(segment
		(start 168.875456 -239.740694)
		(end 168.682416 -239.933734)
		(width 0.18288)
		(layer "In2.Cu")
		(net "M_F_CPU1_SB_CB<5>")
	)
	(segment
		(start 138.954002 -242.770152)
		(end 138.920474 -242.736624)
		(width 0.088646)
		(layer "In2.Cu")
		(net "M_F_CPU1_SB_CB<5>")
	)
	(segment
		(start 159.783018 -240.188242)
		(end 159.352488 -240.618772)
		(width 0.18288)
		(layer "In2.Cu")
		(net "M_F_CPU1_SB_CB<5>")
	)
	(segment
		(start 166.016432 -238.535972)
		(end 165.823392 -238.729012)
		(width 0.18288)
		(layer "In2.Cu")
		(net "M_F_CPU1_SB_CB<5>")
	)
	(segment
		(start 165.233096 -239.719358)
		(end 164.960046 -239.719358)
		(width 0.18288)
		(layer "In2.Cu")
		(net "M_F_CPU1_SB_CB<5>")
	)
	(segment
		(start 153.572972 -243.152422)
		(end 153.213816 -242.793266)
		(width 0.18288)
		(layer "In2.Cu")
		(net "M_F_CPU1_SB_CB<5>")
	)
	(segment
		(start 152.283922 -243.152422)
		(end 151.901652 -242.770152)
		(width 0.18288)
		(layer "In2.Cu")
		(net "M_F_CPU1_SB_CB<5>")
	)
	(segment
		(start 138.920474 -242.736624)
		(end 138.464036 -242.736624)
		(width 0.088646)
		(layer "In2.Cu")
		(net "M_F_CPU1_SB_CB<5>")
	)
	(segment
		(start 167.658796 -239.408462)
		(end 166.72052 -239.408462)
		(width 0.18288)
		(layer "In2.Cu")
		(net "M_F_CPU1_SB_CB<5>")
	)
	(segment
		(start 171.427394 -239.222026)
		(end 170.88866 -239.76076)
		(width 0.18288)
		(layer "In2.Cu")
		(net "M_F_CPU1_SB_CB<5>")
	)
	(segment
		(start 160.481518 -240.188242)
		(end 159.783018 -240.188242)
		(width 0.18288)
		(layer "In2.Cu")
		(net "M_F_CPU1_SB_CB<5>")
	)
	(segment
		(start 168.184068 -239.933734)
		(end 167.658796 -239.408462)
		(width 0.18288)
		(layer "In2.Cu")
		(net "M_F_CPU1_SB_CB<5>")
	)
	(segment
		(start 155.34513 -242.331494)
		(end 155.065984 -242.61064)
		(width 0.18288)
		(layer "In2.Cu")
		(net "M_F_CPU1_SB_CB<5>")
	)
	(segment
		(start 168.875456 -239.263682)
		(end 168.875456 -239.740694)
		(width 0.18288)
		(layer "In2.Cu")
		(net "M_F_CPU1_SB_CB<5>")
	)
	(segment
		(start 165.823392 -239.129062)
		(end 165.233096 -239.719358)
		(width 0.18288)
		(layer "In2.Cu")
		(net "M_F_CPU1_SB_CB<5>")
	)
	(segment
		(start 135.801354 -241.161824)
		(end 135.792464 -241.156744)
		(width 0.088646)
		(layer "In2.Cu")
		(net "M_F_CPU1_SB_CB<5>")
	)
	(segment
		(start 166.52748 -238.736632)
		(end 166.32682 -238.535972)
		(width 0.18288)
		(layer "In2.Cu")
		(net "M_F_CPU1_SB_CB<5>")
	)
	(segment
		(start 169.329354 -239.117378)
		(end 169.02176 -239.117378)
		(width 0.18288)
		(layer "In2.Cu")
		(net "M_F_CPU1_SB_CB<5>")
	)
	(arc
		(start 135.417814 -241.156744)
		(mid 135.138611 -241.232384)
		(end 134.858506 -241.160046)
		(width 0.088646)
		(layer "In2.Cu")
		(net "M_F_CPU1_SB_CB<5>")
	)
	(arc
		(start 138.237468 -242.78463)
		(mid 137.954766 -242.860372)
		(end 137.672064 -242.78463)
		(width 0.088646)
		(layer "In2.Cu")
		(net "M_F_CPU1_SB_CB<5>")
	)
	(arc
		(start 136.262364 -241.97056)
		(mid 136.058029 -241.767955)
		(end 135.979916 -241.491008)
		(width 0.088646)
		(layer "In2.Cu")
		(net "M_F_CPU1_SB_CB<5>")
	)
	(arc
		(start 135.979916 -241.481102)
		(mid 135.932237 -241.298202)
		(end 135.801354 -241.161824)
		(width 0.088646)
		(layer "In2.Cu")
		(net "M_F_CPU1_SB_CB<5>")
	)
	(arc
		(start 137.672064 -242.78463)
		(mid 137.469778 -242.585649)
		(end 137.389616 -242.31346)
		(width 0.088646)
		(layer "In2.Cu")
		(net "M_F_CPU1_SB_CB<5>")
	)
	(arc
		(start 134.848854 -241.154458)
		(mid 134.663135 -241.106506)
		(end 134.478014 -241.156744)
		(width 0.088646)
		(layer "In2.Cu")
		(net "M_F_CPU1_SB_CB<5>")
	)
	(arc
		(start 136.827768 -241.97056)
		(mid 136.545066 -242.046302)
		(end 136.262364 -241.97056)
		(width 0.088646)
		(layer "In2.Cu")
		(net "M_F_CPU1_SB_CB<5>")
	)
	(arc
		(start 137.389616 -242.294918)
		(mid 137.339452 -242.10778)
		(end 137.202418 -241.970814)
		(width 0.088646)
		(layer "In2.Cu")
		(net "M_F_CPU1_SB_CB<5>")
	)
	(arc
		(start 135.788146 -241.154204)
		(mid 135.602651 -241.106535)
		(end 135.417814 -241.156744)
		(width 0.088646)
		(layer "In2.Cu")
		(net "M_F_CPU1_SB_CB<5>")
	)
	(arc
		(start 134.478014 -241.156744)
		(mid 133.94197 -241.172296)
		(end 133.634226 -240.733072)
		(width 0.088646)
		(layer "In2.Cu")
		(net "M_F_CPU1_SB_CB<5>")
	)
	(arc
		(start 137.202164 -241.97056)
		(mid 137.014966 -241.920417)
		(end 136.827768 -241.97056)
		(width 0.088646)
		(layer "In2.Cu")
		(net "M_F_CPU1_SB_CB<5>")
	)
	(arc
		(start 138.464036 -242.736624)
		(mid 138.346959 -242.742701)
		(end 138.237468 -242.78463)
		(width 0.088646)
		(layer "In2.Cu")
		(net "M_F_CPU1_SB_CB<5>")
	)
	(segment
		(start 176.145444 -241.765328)
		(end 175.67021 -241.765328)
		(width 0.20066)
		(layer "F.Cu")
		(net "M_F_CPU1_SB_CB<4>")
	)
	(segment
		(start 179.004976 -241.09172)
		(end 176.843182 -241.09172)
		(width 0.1016)
		(layer "F.Cu")
		(net "M_F_CPU1_SB_CB<4>")
	)
	(segment
		(start 176.796192 -241.09172)
		(end 176.451514 -241.09172)
		(width 0.20066)
		(layer "F.Cu")
		(net "M_F_CPU1_SB_CB<4>")
	)
	(segment
		(start 133.725666 -242.017042)
		(end 133.725666 -241.481102)
		(width 0.20066)
		(layer "F.Cu")
		(net "M_F_CPU1_SB_CB<4>")
	)
	(segment
		(start 176.333404 -241.577368)
		(end 176.145444 -241.765328)
		(width 0.20066)
		(layer "F.Cu")
		(net "M_F_CPU1_SB_CB<4>")
	)
	(segment
		(start 176.451514 -241.09172)
		(end 176.333404 -241.20983)
		(width 0.20066)
		(layer "F.Cu")
		(net "M_F_CPU1_SB_CB<4>")
	)
	(segment
		(start 176.333404 -241.20983)
		(end 176.333404 -241.577368)
		(width 0.20066)
		(layer "F.Cu")
		(net "M_F_CPU1_SB_CB<4>")
	)
	(segment
		(start 175.67021 -241.765328)
		(end 175.421544 -241.516662)
		(width 0.20066)
		(layer "F.Cu")
		(net "M_F_CPU1_SB_CB<4>")
	)
	(segment
		(start 179.011326 -241.08537)
		(end 179.004976 -241.09172)
		(width 0.1016)
		(layer "F.Cu")
		(net "M_F_CPU1_SB_CB<4>")
	)
	(segment
		(start 173.900846 -241.516662)
		(end 172.795946 -241.516662)
		(width 0.20066)
		(layer "F.Cu")
		(net "M_F_CPU1_SB_CB<4>")
	)
	(segment
		(start 175.421544 -241.516662)
		(end 173.900846 -241.516662)
		(width 0.20066)
		(layer "F.Cu")
		(net "M_F_CPU1_SB_CB<4>")
	)
	(segment
		(start 179.852828 -241.516916)
		(end 179.421282 -241.08537)
		(width 0.20066)
		(layer "F.Cu")
		(net "M_F_CPU1_SB_CB<4>")
	)
	(segment
		(start 181.444392 -241.516916)
		(end 179.852828 -241.516916)
		(width 0.20066)
		(layer "F.Cu")
		(net "M_F_CPU1_SB_CB<4>")
	)
	(segment
		(start 181.444646 -241.516662)
		(end 181.444392 -241.516916)
		(width 0.20066)
		(layer "F.Cu")
		(net "M_F_CPU1_SB_CB<4>")
	)
	(segment
		(start 176.843182 -241.09172)
		(end 176.796192 -241.09172)
		(width 0.101854)
		(layer "F.Cu")
		(net "M_F_CPU1_SB_CB<4>")
	)
	(segment
		(start 179.421282 -241.08537)
		(end 179.011326 -241.08537)
		(width 0.20066)
		(layer "F.Cu")
		(net "M_F_CPU1_SB_CB<4>")
	)
	(segment
		(start 158.892494 -242.634516)
		(end 158.47949 -242.634516)
		(width 0.18288)
		(layer "In2.Cu")
		(net "M_F_CPU1_SB_CB<4>")
	)
	(segment
		(start 162.433 -241.061748)
		(end 161.296604 -241.061748)
		(width 0.18288)
		(layer "In2.Cu")
		(net "M_F_CPU1_SB_CB<4>")
	)
	(segment
		(start 163.386262 -241.622326)
		(end 163.221162 -241.787426)
		(width 0.18288)
		(layer "In2.Cu")
		(net "M_F_CPU1_SB_CB<4>")
	)
	(segment
		(start 162.786314 -241.787426)
		(end 162.626294 -241.627406)
		(width 0.18288)
		(layer "In2.Cu")
		(net "M_F_CPU1_SB_CB<4>")
	)
	(segment
		(start 151.83485 -244.173248)
		(end 151.462486 -243.800884)
		(width 0.18288)
		(layer "In2.Cu")
		(net "M_F_CPU1_SB_CB<4>")
	)
	(segment
		(start 134.382764 -241.97056)
		(end 134.37997 -241.969036)
		(width 0.088646)
		(layer "In2.Cu")
		(net "M_F_CPU1_SB_CB<4>")
	)
	(segment
		(start 162.626294 -241.627406)
		(end 162.626294 -241.255042)
		(width 0.18288)
		(layer "In2.Cu")
		(net "M_F_CPU1_SB_CB<4>")
	)
	(segment
		(start 154.983942 -244.173248)
		(end 151.83485 -244.173248)
		(width 0.18288)
		(layer "In2.Cu")
		(net "M_F_CPU1_SB_CB<4>")
	)
	(segment
		(start 158.31947 -242.13185)
		(end 158.056834 -241.869214)
		(width 0.18288)
		(layer "In2.Cu")
		(net "M_F_CPU1_SB_CB<4>")
	)
	(segment
		(start 158.056834 -241.869214)
		(end 157.609794 -241.869214)
		(width 0.18288)
		(layer "In2.Cu")
		(net "M_F_CPU1_SB_CB<4>")
	)
	(segment
		(start 169.382948 -240.960402)
		(end 168.694354 -240.960402)
		(width 0.18288)
		(layer "In2.Cu")
		(net "M_F_CPU1_SB_CB<4>")
	)
	(segment
		(start 169.508678 -241.086132)
		(end 169.382948 -240.960402)
		(width 0.18288)
		(layer "In2.Cu")
		(net "M_F_CPU1_SB_CB<4>")
	)
	(segment
		(start 159.052514 -242.474496)
		(end 158.892494 -242.634516)
		(width 0.18288)
		(layer "In2.Cu")
		(net "M_F_CPU1_SB_CB<4>")
	)
	(segment
		(start 134.103872 -241.546634)
		(end 134.03834 -241.481102)
		(width 0.088646)
		(layer "In2.Cu")
		(net "M_F_CPU1_SB_CB<4>")
	)
	(segment
		(start 134.391654 -241.97564)
		(end 134.382764 -241.97056)
		(width 0.088646)
		(layer "In2.Cu")
		(net "M_F_CPU1_SB_CB<4>")
	)
	(segment
		(start 163.386262 -241.32413)
		(end 163.386262 -241.622326)
		(width 0.18288)
		(layer "In2.Cu")
		(net "M_F_CPU1_SB_CB<4>")
	)
	(segment
		(start 169.770044 -241.086132)
		(end 169.508678 -241.086132)
		(width 0.18288)
		(layer "In2.Cu")
		(net "M_F_CPU1_SB_CB<4>")
	)
	(segment
		(start 169.930064 -241.621564)
		(end 169.930064 -241.246152)
		(width 0.18288)
		(layer "In2.Cu")
		(net "M_F_CPU1_SB_CB<4>")
	)
	(segment
		(start 168.694354 -240.960402)
		(end 168.501314 -241.153442)
		(width 0.18288)
		(layer "In2.Cu")
		(net "M_F_CPU1_SB_CB<4>")
	)
	(segment
		(start 159.212534 -241.982752)
		(end 159.052514 -242.142772)
		(width 0.18288)
		(layer "In2.Cu")
		(net "M_F_CPU1_SB_CB<4>")
	)
	(segment
		(start 161.13252 -241.225832)
		(end 161.13252 -241.657632)
		(width 0.18288)
		(layer "In2.Cu")
		(net "M_F_CPU1_SB_CB<4>")
	)
	(segment
		(start 159.052514 -242.142772)
		(end 159.052514 -242.474496)
		(width 0.18288)
		(layer "In2.Cu")
		(net "M_F_CPU1_SB_CB<4>")
	)
	(segment
		(start 134.37997 -241.969036)
		(end 134.376668 -241.967004)
		(width 0.088646)
		(layer "In2.Cu")
		(net "M_F_CPU1_SB_CB<4>")
	)
	(segment
		(start 167.346122 -241.077496)
		(end 166.854378 -241.077496)
		(width 0.18288)
		(layer "In2.Cu")
		(net "M_F_CPU1_SB_CB<4>")
	)
	(segment
		(start 164.471858 -241.243866)
		(end 164.278818 -241.050826)
		(width 0.18288)
		(layer "In2.Cu")
		(net "M_F_CPU1_SB_CB<4>")
	)
	(segment
		(start 163.659566 -241.050826)
		(end 163.386262 -241.32413)
		(width 0.18288)
		(layer "In2.Cu")
		(net "M_F_CPU1_SB_CB<4>")
	)
	(segment
		(start 164.471858 -241.691668)
		(end 164.471858 -241.243866)
		(width 0.18288)
		(layer "In2.Cu")
		(net "M_F_CPU1_SB_CB<4>")
	)
	(segment
		(start 159.74568 -241.787172)
		(end 159.5501 -241.982752)
		(width 0.18288)
		(layer "In2.Cu")
		(net "M_F_CPU1_SB_CB<4>")
	)
	(segment
		(start 167.557196 -241.28857)
		(end 167.346122 -241.077496)
		(width 0.18288)
		(layer "In2.Cu")
		(net "M_F_CPU1_SB_CB<4>")
	)
	(segment
		(start 166.523162 -240.74628)
		(end 165.841172 -240.74628)
		(width 0.18288)
		(layer "In2.Cu")
		(net "M_F_CPU1_SB_CB<4>")
	)
	(segment
		(start 170.898312 -241.200686)
		(end 170.705272 -241.393726)
		(width 0.18288)
		(layer "In2.Cu")
		(net "M_F_CPU1_SB_CB<4>")
	)
	(segment
		(start 159.5501 -241.982752)
		(end 159.212534 -241.982752)
		(width 0.18288)
		(layer "In2.Cu")
		(net "M_F_CPU1_SB_CB<4>")
	)
	(segment
		(start 168.501314 -241.153442)
		(end 168.501314 -241.690144)
		(width 0.18288)
		(layer "In2.Cu")
		(net "M_F_CPU1_SB_CB<4>")
	)
	(segment
		(start 166.854378 -241.077496)
		(end 166.523162 -240.74628)
		(width 0.18288)
		(layer "In2.Cu")
		(net "M_F_CPU1_SB_CB<4>")
	)
	(segment
		(start 170.705272 -241.652298)
		(end 170.542712 -241.814858)
		(width 0.18288)
		(layer "In2.Cu")
		(net "M_F_CPU1_SB_CB<4>")
	)
	(segment
		(start 167.557196 -241.665506)
		(end 167.557196 -241.28857)
		(width 0.18288)
		(layer "In2.Cu")
		(net "M_F_CPU1_SB_CB<4>")
	)
	(segment
		(start 168.501314 -241.690144)
		(end 168.332912 -241.858546)
		(width 0.18288)
		(layer "In2.Cu")
		(net "M_F_CPU1_SB_CB<4>")
	)
	(segment
		(start 168.332912 -241.858546)
		(end 167.750236 -241.858546)
		(width 0.18288)
		(layer "In2.Cu")
		(net "M_F_CPU1_SB_CB<4>")
	)
	(segment
		(start 170.123358 -241.814858)
		(end 169.930064 -241.621564)
		(width 0.18288)
		(layer "In2.Cu")
		(net "M_F_CPU1_SB_CB<4>")
	)
	(segment
		(start 172.795946 -241.516662)
		(end 172.293026 -241.013742)
		(width 0.18288)
		(layer "In2.Cu")
		(net "M_F_CPU1_SB_CB<4>")
	)
	(segment
		(start 165.20033 -241.825018)
		(end 164.605208 -241.825018)
		(width 0.18288)
		(layer "In2.Cu")
		(net "M_F_CPU1_SB_CB<4>")
	)
	(segment
		(start 171.398946 -241.013742)
		(end 171.212002 -241.200686)
		(width 0.18288)
		(layer "In2.Cu")
		(net "M_F_CPU1_SB_CB<4>")
	)
	(segment
		(start 165.841172 -240.74628)
		(end 165.39337 -241.194082)
		(width 0.18288)
		(layer "In2.Cu")
		(net "M_F_CPU1_SB_CB<4>")
	)
	(segment
		(start 172.293026 -241.013742)
		(end 171.398946 -241.013742)
		(width 0.18288)
		(layer "In2.Cu")
		(net "M_F_CPU1_SB_CB<4>")
	)
	(segment
		(start 167.750236 -241.858546)
		(end 167.557196 -241.665506)
		(width 0.18288)
		(layer "In2.Cu")
		(net "M_F_CPU1_SB_CB<4>")
	)
	(segment
		(start 158.31947 -242.474496)
		(end 158.31947 -242.13185)
		(width 0.18288)
		(layer "In2.Cu")
		(net "M_F_CPU1_SB_CB<4>")
	)
	(segment
		(start 136.919716 -243.118894)
		(end 136.919716 -243.108988)
		(width 0.088646)
		(layer "In2.Cu")
		(net "M_F_CPU1_SB_CB<4>")
	)
	(segment
		(start 139.230354 -243.800884)
		(end 138.97737 -243.5479)
		(width 0.088646)
		(layer "In2.Cu")
		(net "M_F_CPU1_SB_CB<4>")
	)
	(segment
		(start 165.39337 -241.194082)
		(end 165.39337 -241.631978)
		(width 0.18288)
		(layer "In2.Cu")
		(net "M_F_CPU1_SB_CB<4>")
	)
	(segment
		(start 157.609794 -241.869214)
		(end 157.060392 -242.096798)
		(width 0.18288)
		(layer "In2.Cu")
		(net "M_F_CPU1_SB_CB<4>")
	)
	(segment
		(start 134.570216 -242.317016)
		(end 134.570216 -242.294918)
		(width 0.088646)
		(layer "In2.Cu")
		(net "M_F_CPU1_SB_CB<4>")
	)
	(segment
		(start 138.97737 -243.5479)
		(end 138.894312 -243.5479)
		(width 0.088646)
		(layer "In2.Cu")
		(net "M_F_CPU1_SB_CB<4>")
	)
	(segment
		(start 161.13252 -241.657632)
		(end 161.00298 -241.787172)
		(width 0.18288)
		(layer "In2.Cu")
		(net "M_F_CPU1_SB_CB<4>")
	)
	(segment
		(start 151.462486 -243.800884)
		(end 139.579096 -243.800884)
		(width 0.18288)
		(layer "In2.Cu")
		(net "M_F_CPU1_SB_CB<4>")
	)
	(segment
		(start 158.47949 -242.634516)
		(end 158.31947 -242.474496)
		(width 0.18288)
		(layer "In2.Cu")
		(net "M_F_CPU1_SB_CB<4>")
	)
	(segment
		(start 164.278818 -241.050826)
		(end 163.659566 -241.050826)
		(width 0.18288)
		(layer "In2.Cu")
		(net "M_F_CPU1_SB_CB<4>")
	)
	(segment
		(start 171.212002 -241.200686)
		(end 170.898312 -241.200686)
		(width 0.18288)
		(layer "In2.Cu")
		(net "M_F_CPU1_SB_CB<4>")
	)
	(segment
		(start 170.705272 -241.393726)
		(end 170.705272 -241.652298)
		(width 0.18288)
		(layer "In2.Cu")
		(net "M_F_CPU1_SB_CB<4>")
	)
	(segment
		(start 135.418068 -242.78463)
		(end 135.407654 -242.790726)
		(width 0.088646)
		(layer "In2.Cu")
		(net "M_F_CPU1_SB_CB<4>")
	)
	(segment
		(start 139.579096 -243.800884)
		(end 139.230354 -243.800884)
		(width 0.088646)
		(layer "In2.Cu")
		(net "M_F_CPU1_SB_CB<4>")
	)
	(segment
		(start 161.296604 -241.061748)
		(end 161.13252 -241.225832)
		(width 0.18288)
		(layer "In2.Cu")
		(net "M_F_CPU1_SB_CB<4>")
	)
	(segment
		(start 162.626294 -241.255042)
		(end 162.433 -241.061748)
		(width 0.18288)
		(layer "In2.Cu")
		(net "M_F_CPU1_SB_CB<4>")
	)
	(segment
		(start 165.39337 -241.631978)
		(end 165.20033 -241.825018)
		(width 0.18288)
		(layer "In2.Cu")
		(net "M_F_CPU1_SB_CB<4>")
	)
	(segment
		(start 157.060392 -242.096798)
		(end 154.983942 -244.173248)
		(width 0.18288)
		(layer "In2.Cu")
		(net "M_F_CPU1_SB_CB<4>")
	)
	(segment
		(start 161.00298 -241.787172)
		(end 159.74568 -241.787172)
		(width 0.18288)
		(layer "In2.Cu")
		(net "M_F_CPU1_SB_CB<4>")
	)
	(segment
		(start 169.930064 -241.246152)
		(end 169.770044 -241.086132)
		(width 0.18288)
		(layer "In2.Cu")
		(net "M_F_CPU1_SB_CB<4>")
	)
	(segment
		(start 134.03834 -241.481102)
		(end 133.725666 -241.481102)
		(width 0.088646)
		(layer "In2.Cu")
		(net "M_F_CPU1_SB_CB<4>")
	)
	(segment
		(start 170.542712 -241.814858)
		(end 170.123358 -241.814858)
		(width 0.18288)
		(layer "In2.Cu")
		(net "M_F_CPU1_SB_CB<4>")
	)
	(segment
		(start 136.741154 -242.78971)
		(end 136.732264 -242.78463)
		(width 0.088646)
		(layer "In2.Cu")
		(net "M_F_CPU1_SB_CB<4>")
	)
	(segment
		(start 163.221162 -241.787426)
		(end 162.786314 -241.787426)
		(width 0.18288)
		(layer "In2.Cu")
		(net "M_F_CPU1_SB_CB<4>")
	)
	(segment
		(start 164.605208 -241.825018)
		(end 164.471858 -241.691668)
		(width 0.18288)
		(layer "In2.Cu")
		(net "M_F_CPU1_SB_CB<4>")
	)
	(arc
		(start 138.707368 -243.598446)
		(mid 138.424666 -243.674222)
		(end 138.141964 -243.598446)
		(width 0.088646)
		(layer "In2.Cu")
		(net "M_F_CPU1_SB_CB<4>")
	)
	(arc
		(start 138.141964 -243.598446)
		(mid 137.954766 -243.548303)
		(end 137.767568 -243.598446)
		(width 0.088646)
		(layer "In2.Cu")
		(net "M_F_CPU1_SB_CB<4>")
	)
	(arc
		(start 136.732264 -242.78463)
		(mid 136.545066 -242.734487)
		(end 136.357868 -242.78463)
		(width 0.088646)
		(layer "In2.Cu")
		(net "M_F_CPU1_SB_CB<4>")
	)
	(arc
		(start 134.376668 -241.967004)
		(mid 134.191145 -241.788703)
		(end 134.103872 -241.546634)
		(width 0.088646)
		(layer "In2.Cu")
		(net "M_F_CPU1_SB_CB<4>")
	)
	(arc
		(start 137.202164 -243.598446)
		(mid 136.997829 -243.395841)
		(end 136.919716 -243.118894)
		(width 0.088646)
		(layer "In2.Cu")
		(net "M_F_CPU1_SB_CB<4>")
	)
	(arc
		(start 136.919716 -243.108988)
		(mid 136.872037 -242.926088)
		(end 136.741154 -242.78971)
		(width 0.088646)
		(layer "In2.Cu")
		(net "M_F_CPU1_SB_CB<4>")
	)
	(arc
		(start 137.767568 -243.598446)
		(mid 137.484866 -243.674222)
		(end 137.202164 -243.598446)
		(width 0.088646)
		(layer "In2.Cu")
		(net "M_F_CPU1_SB_CB<4>")
	)
	(arc
		(start 135.792464 -242.78463)
		(mid 135.605266 -242.734487)
		(end 135.418068 -242.78463)
		(width 0.088646)
		(layer "In2.Cu")
		(net "M_F_CPU1_SB_CB<4>")
	)
	(arc
		(start 135.407654 -242.790726)
		(mid 135.129222 -242.86054)
		(end 134.85241 -242.78463)
		(width 0.088646)
		(layer "In2.Cu")
		(net "M_F_CPU1_SB_CB<4>")
	)
	(arc
		(start 138.894312 -243.5479)
		(mid 138.79752 -243.560891)
		(end 138.707368 -243.598446)
		(width 0.088646)
		(layer "In2.Cu")
		(net "M_F_CPU1_SB_CB<4>")
	)
	(arc
		(start 136.357868 -242.78463)
		(mid 136.075166 -242.860372)
		(end 135.792464 -242.78463)
		(width 0.088646)
		(layer "In2.Cu")
		(net "M_F_CPU1_SB_CB<4>")
	)
	(arc
		(start 134.570216 -242.294918)
		(mid 134.522537 -242.112018)
		(end 134.391654 -241.97564)
		(width 0.088646)
		(layer "In2.Cu")
		(net "M_F_CPU1_SB_CB<4>")
	)
	(arc
		(start 134.85241 -242.78463)
		(mid 134.651128 -242.587143)
		(end 134.570216 -242.317016)
		(width 0.088646)
		(layer "In2.Cu")
		(net "M_F_CPU1_SB_CB<4>")
	)
	(segment
		(start 183.136286 -233.45394)
		(end 183.340248 -233.249978)
		(width 0.20066)
		(layer "F.Cu")
		(net "M_F_CPU1_SB_CB<3>")
	)
	(segment
		(start 178.000914 -233.016806)
		(end 179.699158 -233.016806)
		(width 0.20066)
		(layer "F.Cu")
		(net "M_F_CPU1_SB_CB<3>")
	)
	(segment
		(start 179.699158 -233.016806)
		(end 180.131212 -233.44886)
		(width 0.20066)
		(layer "F.Cu")
		(net "M_F_CPU1_SB_CB<3>")
	)
	(segment
		(start 134.665466 -238.761524)
		(end 134.665466 -238.225584)
		(width 0.20066)
		(layer "F.Cu")
		(net "M_F_CPU1_SB_CB<3>")
	)
	(segment
		(start 180.423058 -233.44886)
		(end 180.427884 -233.44886)
		(width 0.101854)
		(layer "F.Cu")
		(net "M_F_CPU1_SB_CB<3>")
	)
	(segment
		(start 180.131212 -233.44886)
		(end 180.423058 -233.44886)
		(width 0.20066)
		(layer "F.Cu")
		(net "M_F_CPU1_SB_CB<3>")
	)
	(segment
		(start 180.434996 -233.441748)
		(end 182.442866 -233.441748)
		(width 0.1016)
		(layer "F.Cu")
		(net "M_F_CPU1_SB_CB<3>")
	)
	(segment
		(start 184.210452 -233.016806)
		(end 185.544714 -233.016806)
		(width 0.20066)
		(layer "F.Cu")
		(net "M_F_CPU1_SB_CB<3>")
	)
	(segment
		(start 182.442866 -233.441748)
		(end 182.455058 -233.45394)
		(width 0.1016)
		(layer "F.Cu")
		(net "M_F_CPU1_SB_CB<3>")
	)
	(segment
		(start 183.574436 -232.764838)
		(end 183.958484 -232.764838)
		(width 0.20066)
		(layer "F.Cu")
		(net "M_F_CPU1_SB_CB<3>")
	)
	(segment
		(start 183.340248 -233.249978)
		(end 183.340248 -232.999026)
		(width 0.20066)
		(layer "F.Cu")
		(net "M_F_CPU1_SB_CB<3>")
	)
	(segment
		(start 183.340248 -232.999026)
		(end 183.574436 -232.764838)
		(width 0.20066)
		(layer "F.Cu")
		(net "M_F_CPU1_SB_CB<3>")
	)
	(segment
		(start 182.455058 -233.45394)
		(end 183.136286 -233.45394)
		(width 0.20066)
		(layer "F.Cu")
		(net "M_F_CPU1_SB_CB<3>")
	)
	(segment
		(start 176.896014 -233.016806)
		(end 178.000914 -233.016806)
		(width 0.20066)
		(layer "F.Cu")
		(net "M_F_CPU1_SB_CB<3>")
	)
	(segment
		(start 180.427884 -233.44886)
		(end 180.434996 -233.441748)
		(width 0.1016)
		(layer "F.Cu")
		(net "M_F_CPU1_SB_CB<3>")
	)
	(segment
		(start 183.958484 -232.764838)
		(end 184.210452 -233.016806)
		(width 0.20066)
		(layer "F.Cu")
		(net "M_F_CPU1_SB_CB<3>")
	)
	(segment
		(start 171.421298 -231.67467)
		(end 171.282106 -231.813862)
		(width 0.18288)
		(layer "In2.Cu")
		(net "M_F_CPU1_SB_CB<3>")
	)
	(segment
		(start 157.848046 -233.668824)
		(end 157.258512 -233.668824)
		(width 0.18288)
		(layer "In2.Cu")
		(net "M_F_CPU1_SB_CB<3>")
	)
	(segment
		(start 163.335716 -231.742488)
		(end 161.23412 -231.742488)
		(width 0.18288)
		(layer "In2.Cu")
		(net "M_F_CPU1_SB_CB<3>")
	)
	(segment
		(start 176.38014 -233.53268)
		(end 174.726854 -233.53268)
		(width 0.18288)
		(layer "In2.Cu")
		(net "M_F_CPU1_SB_CB<3>")
	)
	(segment
		(start 172.170598 -232.16235)
		(end 172.170598 -231.86771)
		(width 0.18288)
		(layer "In2.Cu")
		(net "M_F_CPU1_SB_CB<3>")
	)
	(segment
		(start 134.352538 -238.225584)
		(end 134.665466 -238.225584)
		(width 0.088646)
		(layer "In2.Cu")
		(net "M_F_CPU1_SB_CB<3>")
	)
	(segment
		(start 157.258512 -233.668824)
		(end 152.56129 -238.366046)
		(width 0.18288)
		(layer "In2.Cu")
		(net "M_F_CPU1_SB_CB<3>")
	)
	(segment
		(start 138.050016 -238.225584)
		(end 138.050016 -238.207042)
		(width 0.088646)
		(layer "In2.Cu")
		(net "M_F_CPU1_SB_CB<3>")
	)
	(segment
		(start 139.958572 -238.600488)
		(end 139.364466 -238.600488)
		(width 0.088646)
		(layer "In2.Cu")
		(net "M_F_CPU1_SB_CB<3>")
	)
	(segment
		(start 158.02102 -233.49585)
		(end 157.848046 -233.668824)
		(width 0.18288)
		(layer "In2.Cu")
		(net "M_F_CPU1_SB_CB<3>")
	)
	(segment
		(start 140.518896 -238.366046)
		(end 140.193014 -238.366046)
		(width 0.088646)
		(layer "In2.Cu")
		(net "M_F_CPU1_SB_CB<3>")
	)
	(segment
		(start 161.23412 -231.742488)
		(end 160.966912 -231.865678)
		(width 0.18288)
		(layer "In2.Cu")
		(net "M_F_CPU1_SB_CB<3>")
	)
	(segment
		(start 172.600874 -232.592626)
		(end 172.170598 -232.16235)
		(width 0.18288)
		(layer "In2.Cu")
		(net "M_F_CPU1_SB_CB<3>")
	)
	(segment
		(start 174.726854 -233.53268)
		(end 173.7868 -232.592626)
		(width 0.18288)
		(layer "In2.Cu")
		(net "M_F_CPU1_SB_CB<3>")
	)
	(segment
		(start 168.77157 -230.852726)
		(end 164.941758 -230.852726)
		(width 0.18288)
		(layer "In2.Cu")
		(net "M_F_CPU1_SB_CB<3>")
	)
	(segment
		(start 134.295388 -238.282734)
		(end 134.352538 -238.225584)
		(width 0.088646)
		(layer "In2.Cu")
		(net "M_F_CPU1_SB_CB<3>")
	)
	(segment
		(start 163.852352 -231.70007)
		(end 163.335716 -231.742488)
		(width 0.18288)
		(layer "In2.Cu")
		(net "M_F_CPU1_SB_CB<3>")
	)
	(segment
		(start 164.30371 -231.490774)
		(end 163.852352 -231.70007)
		(width 0.18288)
		(layer "In2.Cu")
		(net "M_F_CPU1_SB_CB<3>")
	)
	(segment
		(start 171.977558 -231.67467)
		(end 171.421298 -231.67467)
		(width 0.18288)
		(layer "In2.Cu")
		(net "M_F_CPU1_SB_CB<3>")
	)
	(segment
		(start 164.941758 -230.852726)
		(end 164.30371 -231.490774)
		(width 0.18288)
		(layer "In2.Cu")
		(net "M_F_CPU1_SB_CB<3>")
	)
	(segment
		(start 135.040116 -238.207042)
		(end 135.040116 -238.225584)
		(width 0.088646)
		(layer "In2.Cu")
		(net "M_F_CPU1_SB_CB<3>")
	)
	(segment
		(start 172.170598 -231.86771)
		(end 171.977558 -231.67467)
		(width 0.18288)
		(layer "In2.Cu")
		(net "M_F_CPU1_SB_CB<3>")
	)
	(segment
		(start 171.282106 -231.813862)
		(end 169.732706 -231.813862)
		(width 0.18288)
		(layer "In2.Cu")
		(net "M_F_CPU1_SB_CB<3>")
	)
	(segment
		(start 169.732706 -231.813862)
		(end 168.77157 -230.852726)
		(width 0.18288)
		(layer "In2.Cu")
		(net "M_F_CPU1_SB_CB<3>")
	)
	(segment
		(start 140.193014 -238.366046)
		(end 139.958572 -238.600488)
		(width 0.088646)
		(layer "In2.Cu")
		(net "M_F_CPU1_SB_CB<3>")
	)
	(segment
		(start 160.966912 -231.865678)
		(end 158.02102 -233.49585)
		(width 0.18288)
		(layer "In2.Cu")
		(net "M_F_CPU1_SB_CB<3>")
	)
	(segment
		(start 173.7868 -232.592626)
		(end 172.600874 -232.592626)
		(width 0.18288)
		(layer "In2.Cu")
		(net "M_F_CPU1_SB_CB<3>")
	)
	(segment
		(start 152.56129 -238.366046)
		(end 140.518896 -238.366046)
		(width 0.18288)
		(layer "In2.Cu")
		(net "M_F_CPU1_SB_CB<3>")
	)
	(segment
		(start 176.896014 -233.016806)
		(end 176.38014 -233.53268)
		(width 0.18288)
		(layer "In2.Cu")
		(net "M_F_CPU1_SB_CB<3>")
	)
	(arc
		(start 138.050016 -238.207042)
		(mid 137.759538 -237.731323)
		(end 137.202164 -237.735872)
		(width 0.088646)
		(layer "In2.Cu")
		(net "M_F_CPU1_SB_CB<3>")
	)
	(arc
		(start 139.177268 -238.549942)
		(mid 138.894566 -238.474166)
		(end 138.611864 -238.549942)
		(width 0.088646)
		(layer "In2.Cu")
		(net "M_F_CPU1_SB_CB<3>")
	)
	(arc
		(start 136.827768 -237.735872)
		(mid 136.545066 -237.66013)
		(end 136.262364 -237.735872)
		(width 0.088646)
		(layer "In2.Cu")
		(net "M_F_CPU1_SB_CB<3>")
	)
	(arc
		(start 138.611864 -238.549942)
		(mid 138.237389 -238.549896)
		(end 138.050016 -238.225584)
		(width 0.088646)
		(layer "In2.Cu")
		(net "M_F_CPU1_SB_CB<3>")
	)
	(arc
		(start 136.262364 -237.735872)
		(mid 136.075166 -237.786015)
		(end 135.887968 -237.735872)
		(width 0.088646)
		(layer "In2.Cu")
		(net "M_F_CPU1_SB_CB<3>")
	)
	(arc
		(start 135.887968 -237.735872)
		(mid 135.330594 -237.731323)
		(end 135.040116 -238.207042)
		(width 0.088646)
		(layer "In2.Cu")
		(net "M_F_CPU1_SB_CB<3>")
	)
	(arc
		(start 137.202164 -237.735872)
		(mid 137.014966 -237.786015)
		(end 136.827768 -237.735872)
		(width 0.088646)
		(layer "In2.Cu")
		(net "M_F_CPU1_SB_CB<3>")
	)
	(arc
		(start 139.364466 -238.600488)
		(mid 139.267538 -238.587537)
		(end 139.177268 -238.549942)
		(width 0.088646)
		(layer "In2.Cu")
		(net "M_F_CPU1_SB_CB<3>")
	)
	(arc
		(start 135.040116 -238.225584)
		(mid 134.694141 -238.599389)
		(end 134.295388 -238.282734)
		(width 0.088646)
		(layer "In2.Cu")
		(net "M_F_CPU1_SB_CB<3>")
	)
	(segment
		(start 135.135112 -239.039654)
		(end 135.135366 -239.0394)
		(width 0.20066)
		(layer "F.Cu")
		(net "M_F_CPU1_SB_CB<2>")
	)
	(segment
		(start 183.574436 -234.464606)
		(end 183.958484 -234.464606)
		(width 0.20066)
		(layer "F.Cu")
		(net "M_F_CPU1_SB_CB<2>")
	)
	(segment
		(start 184.210452 -234.716574)
		(end 185.544714 -234.716574)
		(width 0.20066)
		(layer "F.Cu")
		(net "M_F_CPU1_SB_CB<2>")
	)
	(segment
		(start 182.455058 -235.153708)
		(end 183.136286 -235.153708)
		(width 0.20066)
		(layer "F.Cu")
		(net "M_F_CPU1_SB_CB<2>")
	)
	(segment
		(start 183.958484 -234.464606)
		(end 184.210452 -234.716574)
		(width 0.20066)
		(layer "F.Cu")
		(net "M_F_CPU1_SB_CB<2>")
	)
	(segment
		(start 180.131212 -235.148628)
		(end 180.423058 -235.148628)
		(width 0.20066)
		(layer "F.Cu")
		(net "M_F_CPU1_SB_CB<2>")
	)
	(segment
		(start 178.000914 -234.716574)
		(end 179.699158 -234.716574)
		(width 0.20066)
		(layer "F.Cu")
		(net "M_F_CPU1_SB_CB<2>")
	)
	(segment
		(start 180.427884 -235.148628)
		(end 180.434996 -235.141516)
		(width 0.1016)
		(layer "F.Cu")
		(net "M_F_CPU1_SB_CB<2>")
	)
	(segment
		(start 176.896014 -234.716574)
		(end 178.000914 -234.716574)
		(width 0.20066)
		(layer "F.Cu")
		(net "M_F_CPU1_SB_CB<2>")
	)
	(segment
		(start 183.340248 -234.949746)
		(end 183.340248 -234.698794)
		(width 0.20066)
		(layer "F.Cu")
		(net "M_F_CPU1_SB_CB<2>")
	)
	(segment
		(start 183.340248 -234.698794)
		(end 183.574436 -234.464606)
		(width 0.20066)
		(layer "F.Cu")
		(net "M_F_CPU1_SB_CB<2>")
	)
	(segment
		(start 183.136286 -235.153708)
		(end 183.340248 -234.949746)
		(width 0.20066)
		(layer "F.Cu")
		(net "M_F_CPU1_SB_CB<2>")
	)
	(segment
		(start 180.423058 -235.148628)
		(end 180.427884 -235.148628)
		(width 0.101854)
		(layer "F.Cu")
		(net "M_F_CPU1_SB_CB<2>")
	)
	(segment
		(start 135.135112 -239.57534)
		(end 135.135112 -239.039654)
		(width 0.20066)
		(layer "F.Cu")
		(net "M_F_CPU1_SB_CB<2>")
	)
	(segment
		(start 182.442866 -235.141516)
		(end 182.455058 -235.153708)
		(width 0.1016)
		(layer "F.Cu")
		(net "M_F_CPU1_SB_CB<2>")
	)
	(segment
		(start 180.434996 -235.141516)
		(end 182.442866 -235.141516)
		(width 0.1016)
		(layer "F.Cu")
		(net "M_F_CPU1_SB_CB<2>")
	)
	(segment
		(start 179.699158 -234.716574)
		(end 180.131212 -235.148628)
		(width 0.20066)
		(layer "F.Cu")
		(net "M_F_CPU1_SB_CB<2>")
	)
	(segment
		(start 135.792464 -238.549942)
		(end 135.743696 -238.578136)
		(width 0.088646)
		(layer "In2.Cu")
		(net "M_F_CPU1_SB_CB<2>")
	)
	(segment
		(start 174.276004 -234.81919)
		(end 173.963584 -234.81919)
		(width 0.18288)
		(layer "In2.Cu")
		(net "M_F_CPU1_SB_CB<2>")
	)
	(segment
		(start 152.973024 -239.40389)
		(end 140.518896 -239.40389)
		(width 0.18288)
		(layer "In2.Cu")
		(net "M_F_CPU1_SB_CB<2>")
	)
	(segment
		(start 167.674798 -232.559098)
		(end 165.222428 -232.559098)
		(width 0.18288)
		(layer "In2.Cu")
		(net "M_F_CPU1_SB_CB<2>")
	)
	(segment
		(start 159.716216 -235.20527)
		(end 159.626046 -235.1151)
		(width 0.18288)
		(layer "In2.Cu")
		(net "M_F_CPU1_SB_CB<2>")
	)
	(segment
		(start 137.580116 -239.0394)
		(end 137.580116 -239.029494)
		(width 0.088646)
		(layer "In2.Cu")
		(net "M_F_CPU1_SB_CB<2>")
	)
	(segment
		(start 175.757078 -235.09859)
		(end 175.594518 -234.93603)
		(width 0.18288)
		(layer "In2.Cu")
		(net "M_F_CPU1_SB_CB<2>")
	)
	(segment
		(start 161.939478 -233.354626)
		(end 160.973262 -233.354626)
		(width 0.18288)
		(layer "In2.Cu")
		(net "M_F_CPU1_SB_CB<2>")
	)
	(segment
		(start 138.156696 -239.355122)
		(end 138.141964 -239.363758)
		(width 0.088646)
		(layer "In2.Cu")
		(net "M_F_CPU1_SB_CB<2>")
	)
	(segment
		(start 159.626046 -235.1151)
		(end 157.991302 -235.1151)
		(width 0.18288)
		(layer "In2.Cu")
		(net "M_F_CPU1_SB_CB<2>")
	)
	(segment
		(start 157.991302 -235.1151)
		(end 157.79623 -235.310172)
		(width 0.18288)
		(layer "In2.Cu")
		(net "M_F_CPU1_SB_CB<2>")
	)
	(segment
		(start 172.879512 -234.292648)
		(end 172.879258 -234.292394)
		(width 0.18288)
		(layer "In2.Cu")
		(net "M_F_CPU1_SB_CB<2>")
	)
	(segment
		(start 157.79623 -235.310172)
		(end 157.066742 -235.310172)
		(width 0.18288)
		(layer "In2.Cu")
		(net "M_F_CPU1_SB_CB<2>")
	)
	(segment
		(start 139.79779 -239.40389)
		(end 139.681966 -239.288066)
		(width 0.088646)
		(layer "In2.Cu")
		(net "M_F_CPU1_SB_CB<2>")
	)
	(segment
		(start 172.43552 -234.292394)
		(end 172.302678 -234.159552)
		(width 0.18288)
		(layer "In2.Cu")
		(net "M_F_CPU1_SB_CB<2>")
	)
	(segment
		(start 140.518896 -239.40389)
		(end 139.79779 -239.40389)
		(width 0.088646)
		(layer "In2.Cu")
		(net "M_F_CPU1_SB_CB<2>")
	)
	(segment
		(start 164.42182 -233.212132)
		(end 163.983924 -233.212132)
		(width 0.18288)
		(layer "In2.Cu")
		(net "M_F_CPU1_SB_CB<2>")
	)
	(segment
		(start 162.122866 -233.538014)
		(end 161.939478 -233.354626)
		(width 0.18288)
		(layer "In2.Cu")
		(net "M_F_CPU1_SB_CB<2>")
	)
	(segment
		(start 160.973262 -233.354626)
		(end 160.344866 -233.983022)
		(width 0.18288)
		(layer "In2.Cu")
		(net "M_F_CPU1_SB_CB<2>")
	)
	(segment
		(start 168.051226 -232.935526)
		(end 167.674798 -232.559098)
		(width 0.18288)
		(layer "In2.Cu")
		(net "M_F_CPU1_SB_CB<2>")
	)
	(segment
		(start 168.476676 -233.534204)
		(end 168.051226 -232.935526)
		(width 0.18288)
		(layer "In2.Cu")
		(net "M_F_CPU1_SB_CB<2>")
	)
	(segment
		(start 163.983924 -233.212132)
		(end 163.658042 -233.538014)
		(width 0.18288)
		(layer "In2.Cu")
		(net "M_F_CPU1_SB_CB<2>")
	)
	(segment
		(start 135.743696 -238.578136)
		(end 135.382254 -238.89589)
		(width 0.088646)
		(layer "In2.Cu")
		(net "M_F_CPU1_SB_CB<2>")
	)
	(segment
		(start 165.222428 -232.559098)
		(end 164.990526 -232.643426)
		(width 0.18288)
		(layer "In2.Cu")
		(net "M_F_CPU1_SB_CB<2>")
	)
	(segment
		(start 172.879258 -234.292394)
		(end 172.43552 -234.292394)
		(width 0.18288)
		(layer "In2.Cu")
		(net "M_F_CPU1_SB_CB<2>")
	)
	(segment
		(start 176.257458 -235.09859)
		(end 175.757078 -235.09859)
		(width 0.18288)
		(layer "In2.Cu")
		(net "M_F_CPU1_SB_CB<2>")
	)
	(segment
		(start 157.066742 -235.310172)
		(end 152.973024 -239.40389)
		(width 0.18288)
		(layer "In2.Cu")
		(net "M_F_CPU1_SB_CB<2>")
	)
	(segment
		(start 160.344866 -233.983022)
		(end 160.344866 -235.01223)
		(width 0.18288)
		(layer "In2.Cu")
		(net "M_F_CPU1_SB_CB<2>")
	)
	(segment
		(start 135.382254 -238.89589)
		(end 135.135366 -239.0394)
		(width 0.088646)
		(layer "In2.Cu")
		(net "M_F_CPU1_SB_CB<2>")
	)
	(segment
		(start 175.594518 -234.93603)
		(end 175.594518 -234.38739)
		(width 0.18288)
		(layer "In2.Cu")
		(net "M_F_CPU1_SB_CB<2>")
	)
	(segment
		(start 169.035476 -234.195366)
		(end 168.476676 -233.534204)
		(width 0.18288)
		(layer "In2.Cu")
		(net "M_F_CPU1_SB_CB<2>")
	)
	(segment
		(start 160.151826 -235.20527)
		(end 159.716216 -235.20527)
		(width 0.18288)
		(layer "In2.Cu")
		(net "M_F_CPU1_SB_CB<2>")
	)
	(segment
		(start 163.658042 -233.538014)
		(end 162.122866 -233.538014)
		(width 0.18288)
		(layer "In2.Cu")
		(net "M_F_CPU1_SB_CB<2>")
	)
	(segment
		(start 175.375316 -234.168188)
		(end 174.927006 -234.168188)
		(width 0.18288)
		(layer "In2.Cu")
		(net "M_F_CPU1_SB_CB<2>")
	)
	(segment
		(start 176.896014 -234.716574)
		(end 176.639474 -234.716574)
		(width 0.18288)
		(layer "In2.Cu")
		(net "M_F_CPU1_SB_CB<2>")
	)
	(segment
		(start 171.89577 -234.159552)
		(end 171.754038 -234.301284)
		(width 0.18288)
		(layer "In2.Cu")
		(net "M_F_CPU1_SB_CB<2>")
	)
	(segment
		(start 173.963584 -234.81919)
		(end 173.437042 -234.292648)
		(width 0.18288)
		(layer "In2.Cu")
		(net "M_F_CPU1_SB_CB<2>")
	)
	(segment
		(start 160.344866 -235.01223)
		(end 160.151826 -235.20527)
		(width 0.18288)
		(layer "In2.Cu")
		(net "M_F_CPU1_SB_CB<2>")
	)
	(segment
		(start 169.263568 -234.301284)
		(end 169.035476 -234.195366)
		(width 0.18288)
		(layer "In2.Cu")
		(net "M_F_CPU1_SB_CB<2>")
	)
	(segment
		(start 174.927006 -234.168188)
		(end 174.276004 -234.81919)
		(width 0.18288)
		(layer "In2.Cu")
		(net "M_F_CPU1_SB_CB<2>")
	)
	(segment
		(start 173.437042 -234.292648)
		(end 172.879512 -234.292648)
		(width 0.18288)
		(layer "In2.Cu")
		(net "M_F_CPU1_SB_CB<2>")
	)
	(segment
		(start 175.594518 -234.38739)
		(end 175.375316 -234.168188)
		(width 0.18288)
		(layer "In2.Cu")
		(net "M_F_CPU1_SB_CB<2>")
	)
	(segment
		(start 171.754038 -234.301284)
		(end 169.263568 -234.301284)
		(width 0.18288)
		(layer "In2.Cu")
		(net "M_F_CPU1_SB_CB<2>")
	)
	(segment
		(start 164.990526 -232.643426)
		(end 164.42182 -233.212132)
		(width 0.18288)
		(layer "In2.Cu")
		(net "M_F_CPU1_SB_CB<2>")
	)
	(segment
		(start 172.302678 -234.159552)
		(end 171.89577 -234.159552)
		(width 0.18288)
		(layer "In2.Cu")
		(net "M_F_CPU1_SB_CB<2>")
	)
	(segment
		(start 139.681966 -239.288066)
		(end 139.364212 -239.288066)
		(width 0.088646)
		(layer "In2.Cu")
		(net "M_F_CPU1_SB_CB<2>")
	)
	(segment
		(start 176.639474 -234.716574)
		(end 176.257458 -235.09859)
		(width 0.18288)
		(layer "In2.Cu")
		(net "M_F_CPU1_SB_CB<2>")
	)
	(arc
		(start 137.580116 -239.029494)
		(mid 137.293241 -238.547409)
		(end 136.732264 -238.549942)
		(width 0.088646)
		(layer "In2.Cu")
		(net "M_F_CPU1_SB_CB<2>")
	)
	(arc
		(start 136.357868 -238.549942)
		(mid 136.075166 -238.474166)
		(end 135.792464 -238.549942)
		(width 0.088646)
		(layer "In2.Cu")
		(net "M_F_CPU1_SB_CB<2>")
	)
	(arc
		(start 139.364212 -239.288066)
		(mid 139.218004 -239.307315)
		(end 139.081764 -239.363758)
		(width 0.088646)
		(layer "In2.Cu")
		(net "M_F_CPU1_SB_CB<2>")
	)
	(arc
		(start 139.081764 -239.363758)
		(mid 138.894566 -239.413901)
		(end 138.707368 -239.363758)
		(width 0.088646)
		(layer "In2.Cu")
		(net "M_F_CPU1_SB_CB<2>")
	)
	(arc
		(start 138.141964 -239.363758)
		(mid 137.767489 -239.363712)
		(end 137.580116 -239.0394)
		(width 0.088646)
		(layer "In2.Cu")
		(net "M_F_CPU1_SB_CB<2>")
	)
	(arc
		(start 138.707368 -239.363758)
		(mid 138.433169 -239.287923)
		(end 138.156696 -239.355122)
		(width 0.088646)
		(layer "In2.Cu")
		(net "M_F_CPU1_SB_CB<2>")
	)
	(arc
		(start 136.732264 -238.549942)
		(mid 136.545066 -238.600085)
		(end 136.357868 -238.549942)
		(width 0.088646)
		(layer "In2.Cu")
		(net "M_F_CPU1_SB_CB<2>")
	)
	(segment
		(start 179.421282 -233.435398)
		(end 179.011326 -233.435398)
		(width 0.20066)
		(layer "F.Cu")
		(net "M_F_CPU1_SB_CB<1>")
	)
	(segment
		(start 179.011326 -233.435398)
		(end 179.004976 -233.441748)
		(width 0.1016)
		(layer "F.Cu")
		(net "M_F_CPU1_SB_CB<1>")
	)
	(segment
		(start 181.444646 -233.86669)
		(end 181.444392 -233.866944)
		(width 0.20066)
		(layer "F.Cu")
		(net "M_F_CPU1_SB_CB<1>")
	)
	(segment
		(start 181.444392 -233.866944)
		(end 179.852828 -233.866944)
		(width 0.20066)
		(layer "F.Cu")
		(net "M_F_CPU1_SB_CB<1>")
	)
	(segment
		(start 176.333404 -233.927396)
		(end 176.145444 -234.115356)
		(width 0.20066)
		(layer "F.Cu")
		(net "M_F_CPU1_SB_CB<1>")
	)
	(segment
		(start 176.333404 -233.559858)
		(end 176.333404 -233.927396)
		(width 0.20066)
		(layer "F.Cu")
		(net "M_F_CPU1_SB_CB<1>")
	)
	(segment
		(start 173.900846 -233.86669)
		(end 172.795946 -233.86669)
		(width 0.20066)
		(layer "F.Cu")
		(net "M_F_CPU1_SB_CB<1>")
	)
	(segment
		(start 179.004976 -233.441748)
		(end 176.816258 -233.441748)
		(width 0.1016)
		(layer "F.Cu")
		(net "M_F_CPU1_SB_CB<1>")
	)
	(segment
		(start 179.852828 -233.866944)
		(end 179.421282 -233.435398)
		(width 0.20066)
		(layer "F.Cu")
		(net "M_F_CPU1_SB_CB<1>")
	)
	(segment
		(start 175.67021 -234.115356)
		(end 175.421544 -233.86669)
		(width 0.20066)
		(layer "F.Cu")
		(net "M_F_CPU1_SB_CB<1>")
	)
	(segment
		(start 176.816258 -233.441748)
		(end 176.796192 -233.441748)
		(width 0.101854)
		(layer "F.Cu")
		(net "M_F_CPU1_SB_CB<1>")
	)
	(segment
		(start 176.796192 -233.441748)
		(end 176.451514 -233.441748)
		(width 0.20066)
		(layer "F.Cu")
		(net "M_F_CPU1_SB_CB<1>")
	)
	(segment
		(start 176.451514 -233.441748)
		(end 176.333404 -233.559858)
		(width 0.20066)
		(layer "F.Cu")
		(net "M_F_CPU1_SB_CB<1>")
	)
	(segment
		(start 175.421544 -233.86669)
		(end 173.900846 -233.86669)
		(width 0.20066)
		(layer "F.Cu")
		(net "M_F_CPU1_SB_CB<1>")
	)
	(segment
		(start 133.725666 -238.761524)
		(end 133.725666 -238.225584)
		(width 0.20066)
		(layer "F.Cu")
		(net "M_F_CPU1_SB_CB<1>")
	)
	(segment
		(start 176.145444 -234.115356)
		(end 175.67021 -234.115356)
		(width 0.20066)
		(layer "F.Cu")
		(net "M_F_CPU1_SB_CB<1>")
	)
	(segment
		(start 159.803338 -234.109514)
		(end 159.389318 -234.523534)
		(width 0.18288)
		(layer "In2.Cu")
		(net "M_F_CPU1_SB_CB<1>")
	)
	(segment
		(start 169.829988 -233.67619)
		(end 169.144442 -232.990644)
		(width 0.18288)
		(layer "In2.Cu")
		(net "M_F_CPU1_SB_CB<1>")
	)
	(segment
		(start 171.936918 -232.662476)
		(end 171.581318 -232.662476)
		(width 0.18288)
		(layer "In2.Cu")
		(net "M_F_CPU1_SB_CB<1>")
	)
	(segment
		(start 134.038594 -238.225584)
		(end 133.725666 -238.225584)
		(width 0.088646)
		(layer "In2.Cu")
		(net "M_F_CPU1_SB_CB<1>")
	)
	(segment
		(start 169.144442 -232.990644)
		(end 168.884092 -232.990644)
		(width 0.18288)
		(layer "In2.Cu")
		(net "M_F_CPU1_SB_CB<1>")
	)
	(segment
		(start 168.895522 -231.780842)
		(end 168.503092 -231.388412)
		(width 0.18288)
		(layer "In2.Cu")
		(net "M_F_CPU1_SB_CB<1>")
	)
	(segment
		(start 166.135304 -231.489504)
		(end 165.870382 -231.754426)
		(width 0.18288)
		(layer "In2.Cu")
		(net "M_F_CPU1_SB_CB<1>")
	)
	(segment
		(start 162.01644 -232.62971)
		(end 160.74771 -232.62971)
		(width 0.18288)
		(layer "In2.Cu")
		(net "M_F_CPU1_SB_CB<1>")
	)
	(segment
		(start 166.858442 -231.754426)
		(end 166.59352 -231.489504)
		(width 0.18288)
		(layer "In2.Cu")
		(net "M_F_CPU1_SB_CB<1>")
	)
	(segment
		(start 158.174182 -234.273598)
		(end 157.378146 -234.273598)
		(width 0.18288)
		(layer "In2.Cu")
		(net "M_F_CPU1_SB_CB<1>")
	)
	(segment
		(start 160.74771 -232.62971)
		(end 160.474914 -232.902506)
		(width 0.18288)
		(layer "In2.Cu")
		(net "M_F_CPU1_SB_CB<1>")
	)
	(segment
		(start 171.388278 -233.38663)
		(end 171.098718 -233.67619)
		(width 0.18288)
		(layer "In2.Cu")
		(net "M_F_CPU1_SB_CB<1>")
	)
	(segment
		(start 168.503092 -231.388412)
		(end 168.137332 -231.388412)
		(width 0.18288)
		(layer "In2.Cu")
		(net "M_F_CPU1_SB_CB<1>")
	)
	(segment
		(start 172.170598 -233.241342)
		(end 172.170598 -232.896156)
		(width 0.18288)
		(layer "In2.Cu")
		(net "M_F_CPU1_SB_CB<1>")
	)
	(segment
		(start 135.230616 -238.225584)
		(end 135.230616 -238.23549)
		(width 0.088646)
		(layer "In2.Cu")
		(net "M_F_CPU1_SB_CB<1>")
	)
	(segment
		(start 157.378146 -234.273598)
		(end 152.775412 -238.876332)
		(width 0.18288)
		(layer "In2.Cu")
		(net "M_F_CPU1_SB_CB<1>")
	)
	(segment
		(start 168.137332 -231.388412)
		(end 167.771318 -231.754426)
		(width 0.18288)
		(layer "In2.Cu")
		(net "M_F_CPU1_SB_CB<1>")
	)
	(segment
		(start 164.229542 -232.62971)
		(end 163.857432 -232.62971)
		(width 0.18288)
		(layer "In2.Cu")
		(net "M_F_CPU1_SB_CB<1>")
	)
	(segment
		(start 171.388278 -232.855516)
		(end 171.388278 -233.38663)
		(width 0.18288)
		(layer "In2.Cu")
		(net "M_F_CPU1_SB_CB<1>")
	)
	(segment
		(start 168.604946 -232.711498)
		(end 168.604946 -232.485438)
		(width 0.18288)
		(layer "In2.Cu")
		(net "M_F_CPU1_SB_CB<1>")
	)
	(segment
		(start 152.775412 -238.876332)
		(end 140.518896 -238.876332)
		(width 0.18288)
		(layer "In2.Cu")
		(net "M_F_CPU1_SB_CB<1>")
	)
	(segment
		(start 168.884092 -232.990644)
		(end 168.604946 -232.711498)
		(width 0.18288)
		(layer "In2.Cu")
		(net "M_F_CPU1_SB_CB<1>")
	)
	(segment
		(start 158.424118 -234.523534)
		(end 158.174182 -234.273598)
		(width 0.18288)
		(layer "In2.Cu")
		(net "M_F_CPU1_SB_CB<1>")
	)
	(segment
		(start 171.581318 -232.662476)
		(end 171.388278 -232.855516)
		(width 0.18288)
		(layer "In2.Cu")
		(net "M_F_CPU1_SB_CB<1>")
	)
	(segment
		(start 160.474914 -233.11231)
		(end 159.803338 -233.783886)
		(width 0.18288)
		(layer "In2.Cu")
		(net "M_F_CPU1_SB_CB<1>")
	)
	(segment
		(start 140.518896 -238.876332)
		(end 140.006832 -238.876332)
		(width 0.088646)
		(layer "In2.Cu")
		(net "M_F_CPU1_SB_CB<1>")
	)
	(segment
		(start 134.103872 -238.290862)
		(end 134.038594 -238.225584)
		(width 0.088646)
		(layer "In2.Cu")
		(net "M_F_CPU1_SB_CB<1>")
	)
	(segment
		(start 171.098718 -233.67619)
		(end 169.829988 -233.67619)
		(width 0.18288)
		(layer "In2.Cu")
		(net "M_F_CPU1_SB_CB<1>")
	)
	(segment
		(start 172.795946 -233.86669)
		(end 172.170598 -233.241342)
		(width 0.18288)
		(layer "In2.Cu")
		(net "M_F_CPU1_SB_CB<1>")
	)
	(segment
		(start 163.857432 -232.62971)
		(end 163.5887 -232.360978)
		(width 0.18288)
		(layer "In2.Cu")
		(net "M_F_CPU1_SB_CB<1>")
	)
	(segment
		(start 159.803338 -233.783886)
		(end 159.803338 -234.109514)
		(width 0.18288)
		(layer "In2.Cu")
		(net "M_F_CPU1_SB_CB<1>")
	)
	(segment
		(start 165.104826 -231.754426)
		(end 164.229542 -232.62971)
		(width 0.18288)
		(layer "In2.Cu")
		(net "M_F_CPU1_SB_CB<1>")
	)
	(segment
		(start 159.389318 -234.523534)
		(end 158.424118 -234.523534)
		(width 0.18288)
		(layer "In2.Cu")
		(net "M_F_CPU1_SB_CB<1>")
	)
	(segment
		(start 162.285172 -232.360978)
		(end 162.01644 -232.62971)
		(width 0.18288)
		(layer "In2.Cu")
		(net "M_F_CPU1_SB_CB<1>")
	)
	(segment
		(start 172.170598 -232.896156)
		(end 171.936918 -232.662476)
		(width 0.18288)
		(layer "In2.Cu")
		(net "M_F_CPU1_SB_CB<1>")
	)
	(segment
		(start 166.59352 -231.489504)
		(end 166.135304 -231.489504)
		(width 0.18288)
		(layer "In2.Cu")
		(net "M_F_CPU1_SB_CB<1>")
	)
	(segment
		(start 137.859516 -238.23549)
		(end 137.859516 -238.225584)
		(width 0.088646)
		(layer "In2.Cu")
		(net "M_F_CPU1_SB_CB<1>")
	)
	(segment
		(start 168.604946 -232.485438)
		(end 168.895522 -232.194862)
		(width 0.18288)
		(layer "In2.Cu")
		(net "M_F_CPU1_SB_CB<1>")
	)
	(segment
		(start 163.5887 -232.360978)
		(end 162.285172 -232.360978)
		(width 0.18288)
		(layer "In2.Cu")
		(net "M_F_CPU1_SB_CB<1>")
	)
	(segment
		(start 168.895522 -232.194862)
		(end 168.895522 -231.780842)
		(width 0.18288)
		(layer "In2.Cu")
		(net "M_F_CPU1_SB_CB<1>")
	)
	(segment
		(start 139.921234 -238.790734)
		(end 139.364466 -238.790734)
		(width 0.088646)
		(layer "In2.Cu")
		(net "M_F_CPU1_SB_CB<1>")
	)
	(segment
		(start 167.771318 -231.754426)
		(end 166.858442 -231.754426)
		(width 0.18288)
		(layer "In2.Cu")
		(net "M_F_CPU1_SB_CB<1>")
	)
	(segment
		(start 165.870382 -231.754426)
		(end 165.104826 -231.754426)
		(width 0.18288)
		(layer "In2.Cu")
		(net "M_F_CPU1_SB_CB<1>")
	)
	(segment
		(start 160.474914 -232.902506)
		(end 160.474914 -233.11231)
		(width 0.18288)
		(layer "In2.Cu")
		(net "M_F_CPU1_SB_CB<1>")
	)
	(segment
		(start 140.006832 -238.876332)
		(end 139.921234 -238.790734)
		(width 0.088646)
		(layer "In2.Cu")
		(net "M_F_CPU1_SB_CB<1>")
	)
	(arc
		(start 139.364466 -238.790734)
		(mid 139.218143 -238.771472)
		(end 139.081764 -238.715042)
		(width 0.088646)
		(layer "In2.Cu")
		(net "M_F_CPU1_SB_CB<1>")
	)
	(arc
		(start 137.297668 -237.901226)
		(mid 137.014966 -237.976968)
		(end 136.732264 -237.901226)
		(width 0.088646)
		(layer "In2.Cu")
		(net "M_F_CPU1_SB_CB<1>")
	)
	(arc
		(start 135.792464 -237.901226)
		(mid 135.417989 -237.901272)
		(end 135.230616 -238.225584)
		(width 0.088646)
		(layer "In2.Cu")
		(net "M_F_CPU1_SB_CB<1>")
	)
	(arc
		(start 136.732264 -237.901226)
		(mid 136.545066 -237.851083)
		(end 136.357868 -237.901226)
		(width 0.088646)
		(layer "In2.Cu")
		(net "M_F_CPU1_SB_CB<1>")
	)
	(arc
		(start 138.707368 -238.715042)
		(mid 138.146392 -238.717573)
		(end 137.859516 -238.23549)
		(width 0.088646)
		(layer "In2.Cu")
		(net "M_F_CPU1_SB_CB<1>")
	)
	(arc
		(start 137.859516 -238.225584)
		(mid 137.672217 -237.901143)
		(end 137.297668 -237.901226)
		(width 0.088646)
		(layer "In2.Cu")
		(net "M_F_CPU1_SB_CB<1>")
	)
	(arc
		(start 136.357868 -237.901226)
		(mid 136.075166 -237.976968)
		(end 135.792464 -237.901226)
		(width 0.088646)
		(layer "In2.Cu")
		(net "M_F_CPU1_SB_CB<1>")
	)
	(arc
		(start 135.230616 -238.23549)
		(mid 134.693206 -238.79014)
		(end 134.103872 -238.290862)
		(width 0.088646)
		(layer "In2.Cu")
		(net "M_F_CPU1_SB_CB<1>")
	)
	(arc
		(start 139.081764 -238.715042)
		(mid 138.894566 -238.664899)
		(end 138.707368 -238.715042)
		(width 0.088646)
		(layer "In2.Cu")
		(net "M_F_CPU1_SB_CB<1>")
	)
	(segment
		(start 176.333404 -235.627418)
		(end 176.145444 -235.815378)
		(width 0.20066)
		(layer "F.Cu")
		(net "M_F_CPU1_SB_CB<0>")
	)
	(segment
		(start 133.255512 -239.57534)
		(end 133.255766 -239.575086)
		(width 0.20066)
		(layer "F.Cu")
		(net "M_F_CPU1_SB_CB<0>")
	)
	(segment
		(start 181.444392 -235.566966)
		(end 179.852828 -235.566966)
		(width 0.20066)
		(layer "F.Cu")
		(net "M_F_CPU1_SB_CB<0>")
	)
	(segment
		(start 179.004976 -235.14177)
		(end 176.843182 -235.14177)
		(width 0.1016)
		(layer "F.Cu")
		(net "M_F_CPU1_SB_CB<0>")
	)
	(segment
		(start 176.796192 -235.14177)
		(end 176.451514 -235.14177)
		(width 0.20066)
		(layer "F.Cu")
		(net "M_F_CPU1_SB_CB<0>")
	)
	(segment
		(start 179.421282 -235.13542)
		(end 179.011326 -235.13542)
		(width 0.20066)
		(layer "F.Cu")
		(net "M_F_CPU1_SB_CB<0>")
	)
	(segment
		(start 176.145444 -235.815378)
		(end 175.67021 -235.815378)
		(width 0.20066)
		(layer "F.Cu")
		(net "M_F_CPU1_SB_CB<0>")
	)
	(segment
		(start 176.843182 -235.14177)
		(end 176.796192 -235.14177)
		(width 0.101854)
		(layer "F.Cu")
		(net "M_F_CPU1_SB_CB<0>")
	)
	(segment
		(start 176.333404 -235.25988)
		(end 176.333404 -235.627418)
		(width 0.20066)
		(layer "F.Cu")
		(net "M_F_CPU1_SB_CB<0>")
	)
	(segment
		(start 176.451514 -235.14177)
		(end 176.333404 -235.25988)
		(width 0.20066)
		(layer "F.Cu")
		(net "M_F_CPU1_SB_CB<0>")
	)
	(segment
		(start 175.67021 -235.815378)
		(end 175.421544 -235.566712)
		(width 0.20066)
		(layer "F.Cu")
		(net "M_F_CPU1_SB_CB<0>")
	)
	(segment
		(start 173.900846 -235.566712)
		(end 172.795946 -235.566712)
		(width 0.20066)
		(layer "F.Cu")
		(net "M_F_CPU1_SB_CB<0>")
	)
	(segment
		(start 179.011326 -235.13542)
		(end 179.004976 -235.14177)
		(width 0.1016)
		(layer "F.Cu")
		(net "M_F_CPU1_SB_CB<0>")
	)
	(segment
		(start 133.255766 -239.575086)
		(end 133.255766 -239.0394)
		(width 0.20066)
		(layer "F.Cu")
		(net "M_F_CPU1_SB_CB<0>")
	)
	(segment
		(start 175.421544 -235.566712)
		(end 173.900846 -235.566712)
		(width 0.20066)
		(layer "F.Cu")
		(net "M_F_CPU1_SB_CB<0>")
	)
	(segment
		(start 181.444646 -235.566712)
		(end 181.444392 -235.566966)
		(width 0.20066)
		(layer "F.Cu")
		(net "M_F_CPU1_SB_CB<0>")
	)
	(segment
		(start 179.852828 -235.566966)
		(end 179.421282 -235.13542)
		(width 0.20066)
		(layer "F.Cu")
		(net "M_F_CPU1_SB_CB<0>")
	)
	(segment
		(start 139.5984 -239.478312)
		(end 139.364212 -239.478312)
		(width 0.088646)
		(layer "In2.Cu")
		(net "M_F_CPU1_SB_CB<0>")
	)
	(segment
		(start 160.32734 -235.858812)
		(end 160.186878 -235.71835)
		(width 0.18288)
		(layer "In2.Cu")
		(net "M_F_CPU1_SB_CB<0>")
	)
	(segment
		(start 166.883334 -233.067098)
		(end 165.913054 -233.067098)
		(width 0.18288)
		(layer "In2.Cu")
		(net "M_F_CPU1_SB_CB<0>")
	)
	(segment
		(start 164.205158 -234.30357)
		(end 163.834318 -234.30357)
		(width 0.18288)
		(layer "In2.Cu")
		(net "M_F_CPU1_SB_CB<0>")
	)
	(segment
		(start 169.645584 -235.09859)
		(end 169.417746 -234.870752)
		(width 0.18288)
		(layer "In2.Cu")
		(net "M_F_CPU1_SB_CB<0>")
	)
	(segment
		(start 168.759632 -235.255816)
		(end 168.421304 -235.255816)
		(width 0.18288)
		(layer "In2.Cu")
		(net "M_F_CPU1_SB_CB<0>")
	)
	(segment
		(start 163.215066 -234.046014)
		(end 163.068 -234.19308)
		(width 0.18288)
		(layer "In2.Cu")
		(net "M_F_CPU1_SB_CB<0>")
	)
	(segment
		(start 168.194736 -235.029248)
		(end 168.194736 -234.668568)
		(width 0.18288)
		(layer "In2.Cu")
		(net "M_F_CPU1_SB_CB<0>")
	)
	(segment
		(start 162.070034 -234.29341)
		(end 161.573718 -234.29341)
		(width 0.18288)
		(layer "In2.Cu")
		(net "M_F_CPU1_SB_CB<0>")
	)
	(segment
		(start 160.852866 -234.60329)
		(end 161.217864 -234.968288)
		(width 0.18288)
		(layer "In2.Cu")
		(net "M_F_CPU1_SB_CB<0>")
	)
	(segment
		(start 167.452294 -233.636058)
		(end 166.883334 -233.067098)
		(width 0.18288)
		(layer "In2.Cu")
		(net "M_F_CPU1_SB_CB<0>")
	)
	(segment
		(start 172.795946 -235.266738)
		(end 172.663866 -235.134912)
		(width 0.18288)
		(layer "In2.Cu")
		(net "M_F_CPU1_SB_CB<0>")
	)
	(segment
		(start 135.887714 -238.715042)
		(end 135.882634 -238.71809)
		(width 0.088646)
		(layer "In2.Cu")
		(net "M_F_CPU1_SB_CB<0>")
	)
	(segment
		(start 135.326882 -239.361472)
		(end 135.322564 -239.364012)
		(width 0.088646)
		(layer "In2.Cu")
		(net "M_F_CPU1_SB_CB<0>")
	)
	(segment
		(start 169.144696 -234.870752)
		(end 168.759632 -235.255816)
		(width 0.18288)
		(layer "In2.Cu")
		(net "M_F_CPU1_SB_CB<0>")
	)
	(segment
		(start 168.194736 -234.668568)
		(end 168.374314 -234.48899)
		(width 0.18288)
		(layer "In2.Cu")
		(net "M_F_CPU1_SB_CB<0>")
	)
	(segment
		(start 167.794686 -233.636058)
		(end 167.452294 -233.636058)
		(width 0.18288)
		(layer "In2.Cu")
		(net "M_F_CPU1_SB_CB<0>")
	)
	(segment
		(start 153.190956 -239.917478)
		(end 140.518896 -239.917478)
		(width 0.18288)
		(layer "In2.Cu")
		(net "M_F_CPU1_SB_CB<0>")
	)
	(segment
		(start 134.953756 -239.367314)
		(end 134.947914 -239.364012)
		(width 0.088646)
		(layer "In2.Cu")
		(net "M_F_CPU1_SB_CB<0>")
	)
	(segment
		(start 163.834318 -234.30357)
		(end 163.576762 -234.046014)
		(width 0.18288)
		(layer "In2.Cu")
		(net "M_F_CPU1_SB_CB<0>")
	)
	(segment
		(start 171.702222 -234.809284)
		(end 171.412916 -235.09859)
		(width 0.18288)
		(layer "In2.Cu")
		(net "M_F_CPU1_SB_CB<0>")
	)
	(segment
		(start 164.874702 -233.634026)
		(end 164.205158 -234.30357)
		(width 0.18288)
		(layer "In2.Cu")
		(net "M_F_CPU1_SB_CB<0>")
	)
	(segment
		(start 159.892492 -235.71835)
		(end 159.658812 -235.95203)
		(width 0.18288)
		(layer "In2.Cu")
		(net "M_F_CPU1_SB_CB<0>")
	)
	(segment
		(start 160.60039 -235.858812)
		(end 160.32734 -235.858812)
		(width 0.18288)
		(layer "In2.Cu")
		(net "M_F_CPU1_SB_CB<0>")
	)
	(segment
		(start 134.008114 -239.364012)
		(end 133.607048 -239.13338)
		(width 0.088646)
		(layer "In2.Cu")
		(net "M_F_CPU1_SB_CB<0>")
	)
	(segment
		(start 162.31743 -234.046014)
		(end 162.070034 -234.29341)
		(width 0.18288)
		(layer "In2.Cu")
		(net "M_F_CPU1_SB_CB<0>")
	)
	(segment
		(start 165.913054 -233.067098)
		(end 165.346126 -233.634026)
		(width 0.18288)
		(layer "In2.Cu")
		(net "M_F_CPU1_SB_CB<0>")
	)
	(segment
		(start 172.795946 -235.566712)
		(end 172.795946 -235.266738)
		(width 0.18288)
		(layer "In2.Cu")
		(net "M_F_CPU1_SB_CB<0>")
	)
	(segment
		(start 163.576762 -234.046014)
		(end 163.215066 -234.046014)
		(width 0.18288)
		(layer "In2.Cu")
		(net "M_F_CPU1_SB_CB<0>")
	)
	(segment
		(start 168.374314 -234.215686)
		(end 167.794686 -233.636058)
		(width 0.18288)
		(layer "In2.Cu")
		(net "M_F_CPU1_SB_CB<0>")
	)
	(segment
		(start 161.573718 -234.29341)
		(end 161.318702 -234.038394)
		(width 0.18288)
		(layer "In2.Cu")
		(net "M_F_CPU1_SB_CB<0>")
	)
	(segment
		(start 161.318702 -234.038394)
		(end 161.045906 -234.038394)
		(width 0.18288)
		(layer "In2.Cu")
		(net "M_F_CPU1_SB_CB<0>")
	)
	(segment
		(start 172.166026 -234.809284)
		(end 171.702222 -234.809284)
		(width 0.18288)
		(layer "In2.Cu")
		(net "M_F_CPU1_SB_CB<0>")
	)
	(segment
		(start 168.421304 -235.255816)
		(end 168.194736 -235.029248)
		(width 0.18288)
		(layer "In2.Cu")
		(net "M_F_CPU1_SB_CB<0>")
	)
	(segment
		(start 162.64763 -234.046014)
		(end 162.31743 -234.046014)
		(width 0.18288)
		(layer "In2.Cu")
		(net "M_F_CPU1_SB_CB<0>")
	)
	(segment
		(start 137.211054 -238.720122)
		(end 137.202164 -238.715042)
		(width 0.088646)
		(layer "In2.Cu")
		(net "M_F_CPU1_SB_CB<0>")
	)
	(segment
		(start 140.518896 -239.917478)
		(end 140.037566 -239.917478)
		(width 0.088646)
		(layer "In2.Cu")
		(net "M_F_CPU1_SB_CB<0>")
	)
	(segment
		(start 157.283404 -235.82503)
		(end 153.190956 -239.917478)
		(width 0.18288)
		(layer "In2.Cu")
		(net "M_F_CPU1_SB_CB<0>")
	)
	(segment
		(start 140.037566 -239.917478)
		(end 139.5984 -239.478312)
		(width 0.088646)
		(layer "In2.Cu")
		(net "M_F_CPU1_SB_CB<0>")
	)
	(segment
		(start 138.237214 -239.528858)
		(end 138.222482 -239.537494)
		(width 0.088646)
		(layer "In2.Cu")
		(net "M_F_CPU1_SB_CB<0>")
	)
	(segment
		(start 172.491654 -235.134912)
		(end 172.166026 -234.809284)
		(width 0.18288)
		(layer "In2.Cu")
		(net "M_F_CPU1_SB_CB<0>")
	)
	(segment
		(start 160.186878 -235.71835)
		(end 159.892492 -235.71835)
		(width 0.18288)
		(layer "In2.Cu")
		(net "M_F_CPU1_SB_CB<0>")
	)
	(segment
		(start 165.346126 -233.634026)
		(end 164.874702 -233.634026)
		(width 0.18288)
		(layer "In2.Cu")
		(net "M_F_CPU1_SB_CB<0>")
	)
	(segment
		(start 157.850078 -235.95203)
		(end 157.723078 -235.82503)
		(width 0.18288)
		(layer "In2.Cu")
		(net "M_F_CPU1_SB_CB<0>")
	)
	(segment
		(start 161.217864 -234.968288)
		(end 161.217864 -235.241338)
		(width 0.18288)
		(layer "In2.Cu")
		(net "M_F_CPU1_SB_CB<0>")
	)
	(segment
		(start 159.658812 -235.95203)
		(end 157.850078 -235.95203)
		(width 0.18288)
		(layer "In2.Cu")
		(net "M_F_CPU1_SB_CB<0>")
	)
	(segment
		(start 135.887968 -238.715042)
		(end 135.887714 -238.715042)
		(width 0.088646)
		(layer "In2.Cu")
		(net "M_F_CPU1_SB_CB<0>")
	)
	(segment
		(start 137.389616 -239.054894)
		(end 137.389616 -239.0394)
		(width 0.088646)
		(layer "In2.Cu")
		(net "M_F_CPU1_SB_CB<0>")
	)
	(segment
		(start 171.412916 -235.09859)
		(end 169.645584 -235.09859)
		(width 0.18288)
		(layer "In2.Cu")
		(net "M_F_CPU1_SB_CB<0>")
	)
	(segment
		(start 161.045906 -234.038394)
		(end 160.852866 -234.231434)
		(width 0.18288)
		(layer "In2.Cu")
		(net "M_F_CPU1_SB_CB<0>")
	)
	(segment
		(start 157.723078 -235.82503)
		(end 157.283404 -235.82503)
		(width 0.18288)
		(layer "In2.Cu")
		(net "M_F_CPU1_SB_CB<0>")
	)
	(segment
		(start 161.217864 -235.241338)
		(end 160.60039 -235.858812)
		(width 0.18288)
		(layer "In2.Cu")
		(net "M_F_CPU1_SB_CB<0>")
	)
	(segment
		(start 163.068 -234.19308)
		(end 162.794696 -234.19308)
		(width 0.18288)
		(layer "In2.Cu")
		(net "M_F_CPU1_SB_CB<0>")
	)
	(segment
		(start 172.663866 -235.134912)
		(end 172.491654 -235.134912)
		(width 0.18288)
		(layer "In2.Cu")
		(net "M_F_CPU1_SB_CB<0>")
	)
	(segment
		(start 162.794696 -234.19308)
		(end 162.64763 -234.046014)
		(width 0.18288)
		(layer "In2.Cu")
		(net "M_F_CPU1_SB_CB<0>")
	)
	(segment
		(start 134.947914 -239.364012)
		(end 134.943342 -239.361218)
		(width 0.088646)
		(layer "In2.Cu")
		(net "M_F_CPU1_SB_CB<0>")
	)
	(segment
		(start 135.609584 -239.101122)
		(end 135.423148 -239.287558)
		(width 0.088646)
		(layer "In2.Cu")
		(net "M_F_CPU1_SB_CB<0>")
	)
	(segment
		(start 169.417746 -234.870752)
		(end 169.144696 -234.870752)
		(width 0.18288)
		(layer "In2.Cu")
		(net "M_F_CPU1_SB_CB<0>")
	)
	(segment
		(start 168.374314 -234.48899)
		(end 168.374314 -234.215686)
		(width 0.18288)
		(layer "In2.Cu")
		(net "M_F_CPU1_SB_CB<0>")
	)
	(segment
		(start 160.852866 -234.231434)
		(end 160.852866 -234.60329)
		(width 0.18288)
		(layer "In2.Cu")
		(net "M_F_CPU1_SB_CB<0>")
	)
	(arc
		(start 135.322564 -239.364012)
		(mid 135.13861 -239.414107)
		(end 134.953756 -239.367314)
		(width 0.088646)
		(layer "In2.Cu")
		(net "M_F_CPU1_SB_CB<0>")
	)
	(arc
		(start 139.364212 -239.478312)
		(mid 139.259011 -239.493449)
		(end 139.162282 -239.537494)
		(width 0.088646)
		(layer "In2.Cu")
		(net "M_F_CPU1_SB_CB<0>")
	)
	(arc
		(start 137.67181 -239.528858)
		(mid 137.468987 -239.328627)
		(end 137.389616 -239.054894)
		(width 0.088646)
		(layer "In2.Cu")
		(net "M_F_CPU1_SB_CB<0>")
	)
	(arc
		(start 135.423148 -239.287558)
		(mid 135.377437 -239.327669)
		(end 135.326882 -239.361472)
		(width 0.088646)
		(layer "In2.Cu")
		(net "M_F_CPU1_SB_CB<0>")
	)
	(arc
		(start 136.262364 -238.715042)
		(mid 136.075166 -238.664899)
		(end 135.887968 -238.715042)
		(width 0.088646)
		(layer "In2.Cu")
		(net "M_F_CPU1_SB_CB<0>")
	)
	(arc
		(start 134.382764 -239.364012)
		(mid 134.195456 -239.414121)
		(end 134.008114 -239.364012)
		(width 0.088646)
		(layer "In2.Cu")
		(net "M_F_CPU1_SB_CB<0>")
	)
	(arc
		(start 138.222482 -239.537494)
		(mid 137.946007 -239.604814)
		(end 137.67181 -239.528858)
		(width 0.088646)
		(layer "In2.Cu")
		(net "M_F_CPU1_SB_CB<0>")
	)
	(arc
		(start 135.882634 -238.71809)
		(mid 135.782207 -238.805778)
		(end 135.718804 -238.923068)
		(width 0.088646)
		(layer "In2.Cu")
		(net "M_F_CPU1_SB_CB<0>")
	)
	(arc
		(start 137.202164 -238.715042)
		(mid 137.014966 -238.664899)
		(end 136.827768 -238.715042)
		(width 0.088646)
		(layer "In2.Cu")
		(net "M_F_CPU1_SB_CB<0>")
	)
	(arc
		(start 134.943342 -239.361218)
		(mid 134.662678 -239.28821)
		(end 134.382764 -239.364012)
		(width 0.088646)
		(layer "In2.Cu")
		(net "M_F_CPU1_SB_CB<0>")
	)
	(arc
		(start 138.61161 -239.528858)
		(mid 138.424412 -239.478715)
		(end 138.237214 -239.528858)
		(width 0.088646)
		(layer "In2.Cu")
		(net "M_F_CPU1_SB_CB<0>")
	)
	(arc
		(start 135.718804 -238.923068)
		(mid 135.674725 -239.018559)
		(end 135.609584 -239.101122)
		(width 0.088646)
		(layer "In2.Cu")
		(net "M_F_CPU1_SB_CB<0>")
	)
	(arc
		(start 139.162282 -239.537494)
		(mid 138.885807 -239.604814)
		(end 138.61161 -239.528858)
		(width 0.088646)
		(layer "In2.Cu")
		(net "M_F_CPU1_SB_CB<0>")
	)
	(arc
		(start 137.389616 -239.0394)
		(mid 137.341937 -238.8565)
		(end 137.211054 -238.720122)
		(width 0.088646)
		(layer "In2.Cu")
		(net "M_F_CPU1_SB_CB<0>")
	)
	(arc
		(start 133.607048 -239.13338)
		(mid 133.437572 -239.063336)
		(end 133.255766 -239.0394)
		(width 0.088646)
		(layer "In2.Cu")
		(net "M_F_CPU1_SB_CB<0>")
	)
	(arc
		(start 136.827768 -238.715042)
		(mid 136.545066 -238.790818)
		(end 136.262364 -238.715042)
		(width 0.088646)
		(layer "In2.Cu")
		(net "M_F_CPU1_SB_CB<0>")
	)
	(segment
		(start 176.826418 -247.891554)
		(end 178.99888 -247.891554)
		(width 0.1016)
		(layer "F.Cu")
		(net "M_F_CPU1_SB_CA<6>")
	)
	(segment
		(start 175.46066 -246.972328)
		(end 175.786034 -246.972328)
		(width 0.20066)
		(layer "F.Cu")
		(net "M_F_CPU1_SB_CA<6>")
	)
	(segment
		(start 179.011326 -247.904)
		(end 179.427378 -247.904)
		(width 0.20066)
		(layer "F.Cu")
		(net "M_F_CPU1_SB_CA<6>")
	)
	(segment
		(start 179.427378 -247.904)
		(end 179.86502 -247.466358)
		(width 0.20066)
		(layer "F.Cu")
		(net "M_F_CPU1_SB_CA<6>")
	)
	(segment
		(start 132.785866 -245.27256)
		(end 132.785612 -245.272306)
		(width 0.20066)
		(layer "F.Cu")
		(net "M_F_CPU1_SB_CA<6>")
	)
	(segment
		(start 173.900846 -247.466612)
		(end 174.966376 -247.466612)
		(width 0.20066)
		(layer "F.Cu")
		(net "M_F_CPU1_SB_CA<6>")
	)
	(segment
		(start 132.785612 -245.272306)
		(end 132.785612 -244.73662)
		(width 0.20066)
		(layer "F.Cu")
		(net "M_F_CPU1_SB_CA<6>")
	)
	(segment
		(start 176.70526 -247.891554)
		(end 176.812702 -247.891554)
		(width 0.20066)
		(layer "F.Cu")
		(net "M_F_CPU1_SB_CA<6>")
	)
	(segment
		(start 181.444392 -247.466358)
		(end 181.444646 -247.466612)
		(width 0.20066)
		(layer "F.Cu")
		(net "M_F_CPU1_SB_CA<6>")
	)
	(segment
		(start 175.786034 -246.972328)
		(end 176.70526 -247.891554)
		(width 0.20066)
		(layer "F.Cu")
		(net "M_F_CPU1_SB_CA<6>")
	)
	(segment
		(start 178.99888 -247.891554)
		(end 179.011326 -247.904)
		(width 0.1016)
		(layer "F.Cu")
		(net "M_F_CPU1_SB_CA<6>")
	)
	(segment
		(start 174.966376 -247.466612)
		(end 175.46066 -246.972328)
		(width 0.20066)
		(layer "F.Cu")
		(net "M_F_CPU1_SB_CA<6>")
	)
	(segment
		(start 179.86502 -247.466358)
		(end 181.444392 -247.466358)
		(width 0.20066)
		(layer "F.Cu")
		(net "M_F_CPU1_SB_CA<6>")
	)
	(segment
		(start 172.795946 -247.466612)
		(end 173.900846 -247.466612)
		(width 0.20066)
		(layer "F.Cu")
		(net "M_F_CPU1_SB_CA<6>")
	)
	(segment
		(start 176.812702 -247.891554)
		(end 176.826418 -247.891554)
		(width 0.101854)
		(layer "F.Cu")
		(net "M_F_CPU1_SB_CA<6>")
	)
	(segment
		(start 140.73251 -247.845834)
		(end 138.885422 -247.845834)
		(width 0.18288)
		(layer "In2.Cu")
		(net "M_F_CPU1_SB_CA<6>")
	)
	(segment
		(start 168.851326 -247.967246)
		(end 168.851326 -247.42775)
		(width 0.18288)
		(layer "In2.Cu")
		(net "M_F_CPU1_SB_CA<6>")
	)
	(segment
		(start 134.397496 -245.234968)
		(end 134.382764 -245.226332)
		(width 0.088646)
		(layer "In2.Cu")
		(net "M_F_CPU1_SB_CA<6>")
	)
	(segment
		(start 166.854124 -248.213118)
		(end 165.763448 -248.213118)
		(width 0.18288)
		(layer "In2.Cu")
		(net "M_F_CPU1_SB_CA<6>")
	)
	(segment
		(start 133.443472 -245.226078)
		(end 133.442964 -245.226078)
		(width 0.088646)
		(layer "In2.Cu")
		(net "M_F_CPU1_SB_CA<6>")
	)
	(segment
		(start 169.902886 -247.631204)
		(end 169.373804 -248.160286)
		(width 0.18288)
		(layer "In2.Cu")
		(net "M_F_CPU1_SB_CA<6>")
	)
	(segment
		(start 157.45714 -247.847612)
		(end 156.772356 -248.532396)
		(width 0.18288)
		(layer "In2.Cu")
		(net "M_F_CPU1_SB_CA<6>")
	)
	(segment
		(start 153.72461 -248.11355)
		(end 153.53157 -247.92051)
		(width 0.18288)
		(layer "In2.Cu")
		(net "M_F_CPU1_SB_CA<6>")
	)
	(segment
		(start 153.020522 -248.11355)
		(end 153.020522 -248.339356)
		(width 0.18288)
		(layer "In2.Cu")
		(net "M_F_CPU1_SB_CA<6>")
	)
	(segment
		(start 153.020522 -248.339356)
		(end 152.827482 -248.532396)
		(width 0.18288)
		(layer "In2.Cu")
		(net "M_F_CPU1_SB_CA<6>")
	)
	(segment
		(start 153.72461 -248.339356)
		(end 153.72461 -248.11355)
		(width 0.18288)
		(layer "In2.Cu")
		(net "M_F_CPU1_SB_CA<6>")
	)
	(segment
		(start 135.322564 -245.226586)
		(end 135.322564 -245.226332)
		(width 0.088646)
		(layer "In2.Cu")
		(net "M_F_CPU1_SB_CA<6>")
	)
	(segment
		(start 168.851326 -247.42775)
		(end 168.691306 -247.26773)
		(width 0.18288)
		(layer "In2.Cu")
		(net "M_F_CPU1_SB_CA<6>")
	)
	(segment
		(start 157.95879 -247.847612)
		(end 157.45714 -247.847612)
		(width 0.18288)
		(layer "In2.Cu")
		(net "M_F_CPU1_SB_CA<6>")
	)
	(segment
		(start 151.805386 -247.92051)
		(end 151.612346 -248.11355)
		(width 0.18288)
		(layer "In2.Cu")
		(net "M_F_CPU1_SB_CA<6>")
	)
	(segment
		(start 137.859516 -246.364506)
		(end 137.85977 -246.364252)
		(width 0.088646)
		(layer "In2.Cu")
		(net "M_F_CPU1_SB_CA<6>")
	)
	(segment
		(start 153.213562 -247.92051)
		(end 153.020522 -248.11355)
		(width 0.18288)
		(layer "In2.Cu")
		(net "M_F_CPU1_SB_CA<6>")
	)
	(segment
		(start 165.436042 -247.885712)
		(end 164.896546 -247.885712)
		(width 0.18288)
		(layer "In2.Cu")
		(net "M_F_CPU1_SB_CA<6>")
	)
	(segment
		(start 168.335706 -247.26773)
		(end 168.150286 -247.45315)
		(width 0.18288)
		(layer "In2.Cu")
		(net "M_F_CPU1_SB_CA<6>")
	)
	(segment
		(start 137.85977 -246.209058)
		(end 137.750042 -246.099584)
		(width 0.088646)
		(layer "In2.Cu")
		(net "M_F_CPU1_SB_CA<6>")
	)
	(segment
		(start 172.092874 -248.169684)
		(end 171.551854 -248.169684)
		(width 0.18288)
		(layer "In2.Cu")
		(net "M_F_CPU1_SB_CA<6>")
	)
	(segment
		(start 160.333944 -247.848628)
		(end 159.776922 -247.848628)
		(width 0.18288)
		(layer "In2.Cu")
		(net "M_F_CPU1_SB_CA<6>")
	)
	(segment
		(start 137.750042 -246.099584)
		(end 137.750042 -246.09933)
		(width 0.088646)
		(layer "In2.Cu")
		(net "M_F_CPU1_SB_CA<6>")
	)
	(segment
		(start 168.691306 -247.26773)
		(end 168.335706 -247.26773)
		(width 0.18288)
		(layer "In2.Cu")
		(net "M_F_CPU1_SB_CA<6>")
	)
	(segment
		(start 153.53157 -247.92051)
		(end 153.213562 -247.92051)
		(width 0.18288)
		(layer "In2.Cu")
		(net "M_F_CPU1_SB_CA<6>")
	)
	(segment
		(start 138.086592 -247.047004)
		(end 137.859516 -246.819928)
		(width 0.088646)
		(layer "In2.Cu")
		(net "M_F_CPU1_SB_CA<6>")
	)
	(segment
		(start 152.316434 -248.339356)
		(end 152.316434 -248.11355)
		(width 0.18288)
		(layer "In2.Cu")
		(net "M_F_CPU1_SB_CA<6>")
	)
	(segment
		(start 168.150286 -247.696482)
		(end 167.990266 -247.856502)
		(width 0.18288)
		(layer "In2.Cu")
		(net "M_F_CPU1_SB_CA<6>")
	)
	(segment
		(start 164.896546 -247.885712)
		(end 164.588698 -248.19356)
		(width 0.18288)
		(layer "In2.Cu")
		(net "M_F_CPU1_SB_CA<6>")
	)
	(segment
		(start 158.30423 -248.193052)
		(end 157.95879 -247.847612)
		(width 0.18288)
		(layer "In2.Cu")
		(net "M_F_CPU1_SB_CA<6>")
	)
	(segment
		(start 167.21074 -247.856502)
		(end 166.854124 -248.213118)
		(width 0.18288)
		(layer "In2.Cu")
		(net "M_F_CPU1_SB_CA<6>")
	)
	(segment
		(start 159.776922 -247.848628)
		(end 159.432498 -248.193052)
		(width 0.18288)
		(layer "In2.Cu")
		(net "M_F_CPU1_SB_CA<6>")
	)
	(segment
		(start 160.653222 -248.167906)
		(end 160.333944 -247.848628)
		(width 0.18288)
		(layer "In2.Cu")
		(net "M_F_CPU1_SB_CA<6>")
	)
	(segment
		(start 152.316434 -248.11355)
		(end 152.123394 -247.92051)
		(width 0.18288)
		(layer "In2.Cu")
		(net "M_F_CPU1_SB_CA<6>")
	)
	(segment
		(start 135.510016 -245.560596)
		(end 135.510016 -245.55069)
		(width 0.088646)
		(layer "In2.Cu")
		(net "M_F_CPU1_SB_CA<6>")
	)
	(segment
		(start 138.885422 -247.845834)
		(end 138.086592 -247.047004)
		(width 0.18288)
		(layer "In2.Cu")
		(net "M_F_CPU1_SB_CA<6>")
	)
	(segment
		(start 152.827482 -248.532396)
		(end 152.509474 -248.532396)
		(width 0.18288)
		(layer "In2.Cu")
		(net "M_F_CPU1_SB_CA<6>")
	)
	(segment
		(start 159.432498 -248.193052)
		(end 158.30423 -248.193052)
		(width 0.18288)
		(layer "In2.Cu")
		(net "M_F_CPU1_SB_CA<6>")
	)
	(segment
		(start 151.612346 -248.11355)
		(end 151.612346 -248.339356)
		(width 0.18288)
		(layer "In2.Cu")
		(net "M_F_CPU1_SB_CA<6>")
	)
	(segment
		(start 156.772356 -248.532396)
		(end 153.91765 -248.532396)
		(width 0.18288)
		(layer "In2.Cu")
		(net "M_F_CPU1_SB_CA<6>")
	)
	(segment
		(start 152.123394 -247.92051)
		(end 151.805386 -247.92051)
		(width 0.18288)
		(layer "In2.Cu")
		(net "M_F_CPU1_SB_CA<6>")
	)
	(segment
		(start 169.373804 -248.160286)
		(end 169.044366 -248.160286)
		(width 0.18288)
		(layer "In2.Cu")
		(net "M_F_CPU1_SB_CA<6>")
	)
	(segment
		(start 162.370008 -247.583452)
		(end 161.785554 -248.167906)
		(width 0.18288)
		(layer "In2.Cu")
		(net "M_F_CPU1_SB_CA<6>")
	)
	(segment
		(start 152.509474 -248.532396)
		(end 152.316434 -248.339356)
		(width 0.18288)
		(layer "In2.Cu")
		(net "M_F_CPU1_SB_CA<6>")
	)
	(segment
		(start 137.85977 -246.364252)
		(end 137.85977 -246.209058)
		(width 0.088646)
		(layer "In2.Cu")
		(net "M_F_CPU1_SB_CA<6>")
	)
	(segment
		(start 151.419306 -248.532396)
		(end 150.987252 -248.532396)
		(width 0.18288)
		(layer "In2.Cu")
		(net "M_F_CPU1_SB_CA<6>")
	)
	(segment
		(start 169.044366 -248.160286)
		(end 168.851326 -247.967246)
		(width 0.18288)
		(layer "In2.Cu")
		(net "M_F_CPU1_SB_CA<6>")
	)
	(segment
		(start 151.612346 -248.339356)
		(end 151.419306 -248.532396)
		(width 0.18288)
		(layer "In2.Cu")
		(net "M_F_CPU1_SB_CA<6>")
	)
	(segment
		(start 133.413754 -245.209568)
		(end 132.785612 -244.73662)
		(width 0.088646)
		(layer "In2.Cu")
		(net "M_F_CPU1_SB_CA<6>")
	)
	(segment
		(start 167.990266 -247.856502)
		(end 167.21074 -247.856502)
		(width 0.18288)
		(layer "In2.Cu")
		(net "M_F_CPU1_SB_CA<6>")
	)
	(segment
		(start 172.795946 -247.466612)
		(end 172.092874 -248.169684)
		(width 0.18288)
		(layer "In2.Cu")
		(net "M_F_CPU1_SB_CA<6>")
	)
	(segment
		(start 141.354048 -247.224296)
		(end 140.73251 -247.845834)
		(width 0.18288)
		(layer "In2.Cu")
		(net "M_F_CPU1_SB_CA<6>")
	)
	(segment
		(start 168.150286 -247.45315)
		(end 168.150286 -247.696482)
		(width 0.18288)
		(layer "In2.Cu")
		(net "M_F_CPU1_SB_CA<6>")
	)
	(segment
		(start 161.785554 -248.167906)
		(end 160.653222 -248.167906)
		(width 0.18288)
		(layer "In2.Cu")
		(net "M_F_CPU1_SB_CA<6>")
	)
	(segment
		(start 133.442964 -245.226078)
		(end 133.413754 -245.209568)
		(width 0.088646)
		(layer "In2.Cu")
		(net "M_F_CPU1_SB_CA<6>")
	)
	(segment
		(start 163.451286 -247.583452)
		(end 162.370008 -247.583452)
		(width 0.18288)
		(layer "In2.Cu")
		(net "M_F_CPU1_SB_CA<6>")
	)
	(segment
		(start 165.763448 -248.213118)
		(end 165.436042 -247.885712)
		(width 0.18288)
		(layer "In2.Cu")
		(net "M_F_CPU1_SB_CA<6>")
	)
	(segment
		(start 149.679152 -247.224296)
		(end 141.354048 -247.224296)
		(width 0.18288)
		(layer "In2.Cu")
		(net "M_F_CPU1_SB_CA<6>")
	)
	(segment
		(start 137.859516 -246.819928)
		(end 137.859516 -246.364506)
		(width 0.088646)
		(layer "In2.Cu")
		(net "M_F_CPU1_SB_CA<6>")
	)
	(segment
		(start 150.987252 -248.532396)
		(end 149.679152 -247.224296)
		(width 0.18288)
		(layer "In2.Cu")
		(net "M_F_CPU1_SB_CA<6>")
	)
	(segment
		(start 171.013374 -247.631204)
		(end 169.902886 -247.631204)
		(width 0.18288)
		(layer "In2.Cu")
		(net "M_F_CPU1_SB_CA<6>")
	)
	(segment
		(start 164.588698 -248.19356)
		(end 164.061394 -248.19356)
		(width 0.18288)
		(layer "In2.Cu")
		(net "M_F_CPU1_SB_CA<6>")
	)
	(segment
		(start 171.551854 -248.169684)
		(end 171.013374 -247.631204)
		(width 0.18288)
		(layer "In2.Cu")
		(net "M_F_CPU1_SB_CA<6>")
	)
	(segment
		(start 153.91765 -248.532396)
		(end 153.72461 -248.339356)
		(width 0.18288)
		(layer "In2.Cu")
		(net "M_F_CPU1_SB_CA<6>")
	)
	(segment
		(start 164.061394 -248.19356)
		(end 163.451286 -247.583452)
		(width 0.18288)
		(layer "In2.Cu")
		(net "M_F_CPU1_SB_CA<6>")
	)
	(arc
		(start 134.948168 -245.226332)
		(mid 134.673939 -245.302257)
		(end 134.397496 -245.234968)
		(width 0.088646)
		(layer "In2.Cu")
		(net "M_F_CPU1_SB_CA<6>")
	)
	(arc
		(start 135.792464 -246.040148)
		(mid 135.588129 -245.837543)
		(end 135.510016 -245.560596)
		(width 0.088646)
		(layer "In2.Cu")
		(net "M_F_CPU1_SB_CA<6>")
	)
	(arc
		(start 137.750042 -246.09933)
		(mid 137.712992 -246.067184)
		(end 137.672064 -246.040148)
		(width 0.088646)
		(layer "In2.Cu")
		(net "M_F_CPU1_SB_CA<6>")
	)
	(arc
		(start 135.322564 -245.226332)
		(mid 135.135366 -245.176189)
		(end 134.948168 -245.226332)
		(width 0.088646)
		(layer "In2.Cu")
		(net "M_F_CPU1_SB_CA<6>")
	)
	(arc
		(start 134.008368 -245.226332)
		(mid 133.725891 -245.301854)
		(end 133.443472 -245.226078)
		(width 0.088646)
		(layer "In2.Cu")
		(net "M_F_CPU1_SB_CA<6>")
	)
	(arc
		(start 135.510016 -245.55069)
		(mid 135.459776 -245.363489)
		(end 135.322564 -245.226586)
		(width 0.088646)
		(layer "In2.Cu")
		(net "M_F_CPU1_SB_CA<6>")
	)
	(arc
		(start 136.732264 -246.040148)
		(mid 136.545066 -245.990005)
		(end 136.357868 -246.040148)
		(width 0.088646)
		(layer "In2.Cu")
		(net "M_F_CPU1_SB_CA<6>")
	)
	(arc
		(start 136.357868 -246.040148)
		(mid 136.075166 -246.115924)
		(end 135.792464 -246.040148)
		(width 0.088646)
		(layer "In2.Cu")
		(net "M_F_CPU1_SB_CA<6>")
	)
	(arc
		(start 137.297668 -246.040148)
		(mid 137.014966 -246.115924)
		(end 136.732264 -246.040148)
		(width 0.088646)
		(layer "In2.Cu")
		(net "M_F_CPU1_SB_CA<6>")
	)
	(arc
		(start 137.672064 -246.040148)
		(mid 137.484866 -245.990005)
		(end 137.297668 -246.040148)
		(width 0.088646)
		(layer "In2.Cu")
		(net "M_F_CPU1_SB_CA<6>")
	)
	(arc
		(start 134.382764 -245.226332)
		(mid 134.195566 -245.176189)
		(end 134.008368 -245.226332)
		(width 0.088646)
		(layer "In2.Cu")
		(net "M_F_CPU1_SB_CA<6>")
	)
	(segment
		(start 176.896014 -248.31675)
		(end 178.000914 -248.31675)
		(width 0.20066)
		(layer "F.Cu")
		(net "M_F_CPU1_SB_CA<5>")
	)
	(segment
		(start 178.000914 -248.31675)
		(end 179.636674 -248.31675)
		(width 0.20066)
		(layer "F.Cu")
		(net "M_F_CPU1_SB_CA<5>")
	)
	(segment
		(start 135.135112 -246.08663)
		(end 135.135366 -246.086376)
		(width 0.20066)
		(layer "F.Cu")
		(net "M_F_CPU1_SB_CA<5>")
	)
	(segment
		(start 179.636674 -248.31675)
		(end 180.072284 -248.75236)
		(width 0.20066)
		(layer "F.Cu")
		(net "M_F_CPU1_SB_CA<5>")
	)
	(segment
		(start 182.729124 -248.749058)
		(end 183.593994 -247.884188)
		(width 0.20066)
		(layer "F.Cu")
		(net "M_F_CPU1_SB_CA<5>")
	)
	(segment
		(start 183.9976 -247.884188)
		(end 184.430162 -248.31675)
		(width 0.20066)
		(layer "F.Cu")
		(net "M_F_CPU1_SB_CA<5>")
	)
	(segment
		(start 180.423058 -248.75236)
		(end 180.427884 -248.75236)
		(width 0.101854)
		(layer "F.Cu")
		(net "M_F_CPU1_SB_CA<5>")
	)
	(segment
		(start 182.455058 -248.749058)
		(end 182.729124 -248.749058)
		(width 0.20066)
		(layer "F.Cu")
		(net "M_F_CPU1_SB_CA<5>")
	)
	(segment
		(start 180.072284 -248.75236)
		(end 180.423058 -248.75236)
		(width 0.20066)
		(layer "F.Cu")
		(net "M_F_CPU1_SB_CA<5>")
	)
	(segment
		(start 182.447692 -248.741692)
		(end 182.455058 -248.749058)
		(width 0.1016)
		(layer "F.Cu")
		(net "M_F_CPU1_SB_CA<5>")
	)
	(segment
		(start 135.135366 -246.086376)
		(end 135.135366 -245.55069)
		(width 0.20066)
		(layer "F.Cu")
		(net "M_F_CPU1_SB_CA<5>")
	)
	(segment
		(start 184.430162 -248.31675)
		(end 185.544714 -248.31675)
		(width 0.20066)
		(layer "F.Cu")
		(net "M_F_CPU1_SB_CA<5>")
	)
	(segment
		(start 180.438552 -248.741692)
		(end 182.447692 -248.741692)
		(width 0.1016)
		(layer "F.Cu")
		(net "M_F_CPU1_SB_CA<5>")
	)
	(segment
		(start 183.593994 -247.884188)
		(end 183.9976 -247.884188)
		(width 0.20066)
		(layer "F.Cu")
		(net "M_F_CPU1_SB_CA<5>")
	)
	(segment
		(start 180.427884 -248.75236)
		(end 180.438552 -248.741692)
		(width 0.1016)
		(layer "F.Cu")
		(net "M_F_CPU1_SB_CA<5>")
	)
	(segment
		(start 165.480492 -248.735596)
		(end 165.363398 -248.85269)
		(width 0.18288)
		(layer "In2.Cu")
		(net "M_F_CPU1_SB_CA<5>")
	)
	(segment
		(start 135.230616 -246.364506)
		(end 135.230616 -246.330978)
		(width 0.088646)
		(layer "In2.Cu")
		(net "M_F_CPU1_SB_CA<5>")
	)
	(segment
		(start 171.394374 -248.70537)
		(end 168.25214 -248.70537)
		(width 0.18288)
		(layer "In2.Cu")
		(net "M_F_CPU1_SB_CA<5>")
	)
	(segment
		(start 149.266656 -247.569736)
		(end 141.948408 -247.569736)
		(width 0.18288)
		(layer "In2.Cu")
		(net "M_F_CPU1_SB_CA<5>")
	)
	(segment
		(start 175.516032 -249.40387)
		(end 175.516032 -247.8532)
		(width 0.18288)
		(layer "In2.Cu")
		(net "M_F_CPU1_SB_CA<5>")
	)
	(segment
		(start 159.73171 -248.851928)
		(end 159.611568 -248.731786)
		(width 0.18288)
		(layer "In2.Cu")
		(net "M_F_CPU1_SB_CA<5>")
	)
	(segment
		(start 160.791398 -248.851928)
		(end 159.73171 -248.851928)
		(width 0.18288)
		(layer "In2.Cu")
		(net "M_F_CPU1_SB_CA<5>")
	)
	(segment
		(start 174.888652 -247.69318)
		(end 174.566326 -248.015506)
		(width 0.18288)
		(layer "In2.Cu")
		(net "M_F_CPU1_SB_CA<5>")
	)
	(segment
		(start 135.230616 -246.330978)
		(end 135.135366 -245.55069)
		(width 0.088646)
		(layer "In2.Cu")
		(net "M_F_CPU1_SB_CA<5>")
	)
	(segment
		(start 164.460936 -248.735596)
		(end 160.90773 -248.735596)
		(width 0.18288)
		(layer "In2.Cu")
		(net "M_F_CPU1_SB_CA<5>")
	)
	(segment
		(start 141.293088 -248.225056)
		(end 138.53033 -248.225056)
		(width 0.18288)
		(layer "In2.Cu")
		(net "M_F_CPU1_SB_CA<5>")
	)
	(segment
		(start 176.268126 -248.47677)
		(end 176.268126 -249.37085)
		(width 0.18288)
		(layer "In2.Cu")
		(net "M_F_CPU1_SB_CA<5>")
	)
	(segment
		(start 167.156638 -248.735596)
		(end 165.480492 -248.735596)
		(width 0.18288)
		(layer "In2.Cu")
		(net "M_F_CPU1_SB_CA<5>")
	)
	(segment
		(start 168.08831 -248.8692)
		(end 167.290242 -248.8692)
		(width 0.18288)
		(layer "In2.Cu")
		(net "M_F_CPU1_SB_CA<5>")
	)
	(segment
		(start 167.290242 -248.8692)
		(end 167.156638 -248.735596)
		(width 0.18288)
		(layer "In2.Cu")
		(net "M_F_CPU1_SB_CA<5>")
	)
	(segment
		(start 176.896014 -248.31675)
		(end 176.428146 -248.31675)
		(width 0.18288)
		(layer "In2.Cu")
		(net "M_F_CPU1_SB_CA<5>")
	)
	(segment
		(start 157.903418 -248.731786)
		(end 157.58414 -249.051064)
		(width 0.18288)
		(layer "In2.Cu")
		(net "M_F_CPU1_SB_CA<5>")
	)
	(segment
		(start 176.075086 -249.56389)
		(end 175.676052 -249.56389)
		(width 0.18288)
		(layer "In2.Cu")
		(net "M_F_CPU1_SB_CA<5>")
	)
	(segment
		(start 174.566326 -248.417334)
		(end 174.240444 -248.743216)
		(width 0.18288)
		(layer "In2.Cu")
		(net "M_F_CPU1_SB_CA<5>")
	)
	(segment
		(start 157.58414 -249.051064)
		(end 150.747984 -249.051064)
		(width 0.18288)
		(layer "In2.Cu")
		(net "M_F_CPU1_SB_CA<5>")
	)
	(segment
		(start 176.268126 -249.37085)
		(end 176.075086 -249.56389)
		(width 0.18288)
		(layer "In2.Cu")
		(net "M_F_CPU1_SB_CA<5>")
	)
	(segment
		(start 137.580116 -246.94388)
		(end 137.414762 -246.778526)
		(width 0.088646)
		(layer "In2.Cu")
		(net "M_F_CPU1_SB_CA<5>")
	)
	(segment
		(start 165.363398 -248.85269)
		(end 164.57803 -248.85269)
		(width 0.18288)
		(layer "In2.Cu")
		(net "M_F_CPU1_SB_CA<5>")
	)
	(segment
		(start 137.910062 -247.604788)
		(end 137.580116 -247.274842)
		(width 0.088646)
		(layer "In2.Cu")
		(net "M_F_CPU1_SB_CA<5>")
	)
	(segment
		(start 174.566326 -248.015506)
		(end 174.566326 -248.417334)
		(width 0.18288)
		(layer "In2.Cu")
		(net "M_F_CPU1_SB_CA<5>")
	)
	(segment
		(start 175.516032 -247.8532)
		(end 175.356012 -247.69318)
		(width 0.18288)
		(layer "In2.Cu")
		(net "M_F_CPU1_SB_CA<5>")
	)
	(segment
		(start 175.676052 -249.56389)
		(end 175.516032 -249.40387)
		(width 0.18288)
		(layer "In2.Cu")
		(net "M_F_CPU1_SB_CA<5>")
	)
	(segment
		(start 160.90773 -248.735596)
		(end 160.791398 -248.851928)
		(width 0.18288)
		(layer "In2.Cu")
		(net "M_F_CPU1_SB_CA<5>")
	)
	(segment
		(start 138.53033 -248.225056)
		(end 137.910062 -247.604788)
		(width 0.18288)
		(layer "In2.Cu")
		(net "M_F_CPU1_SB_CA<5>")
	)
	(segment
		(start 150.747984 -249.051064)
		(end 149.266656 -247.569736)
		(width 0.18288)
		(layer "In2.Cu")
		(net "M_F_CPU1_SB_CA<5>")
	)
	(segment
		(start 175.356012 -247.69318)
		(end 174.888652 -247.69318)
		(width 0.18288)
		(layer "In2.Cu")
		(net "M_F_CPU1_SB_CA<5>")
	)
	(segment
		(start 159.611568 -248.731786)
		(end 157.903418 -248.731786)
		(width 0.18288)
		(layer "In2.Cu")
		(net "M_F_CPU1_SB_CA<5>")
	)
	(segment
		(start 171.876974 -248.743216)
		(end 171.394374 -248.70537)
		(width 0.18288)
		(layer "In2.Cu")
		(net "M_F_CPU1_SB_CA<5>")
	)
	(segment
		(start 174.240444 -248.743216)
		(end 171.876974 -248.743216)
		(width 0.18288)
		(layer "In2.Cu")
		(net "M_F_CPU1_SB_CA<5>")
	)
	(segment
		(start 141.948408 -247.569736)
		(end 141.293088 -248.225056)
		(width 0.18288)
		(layer "In2.Cu")
		(net "M_F_CPU1_SB_CA<5>")
	)
	(segment
		(start 135.418068 -246.688864)
		(end 135.417814 -246.68861)
		(width 0.088646)
		(layer "In2.Cu")
		(net "M_F_CPU1_SB_CA<5>")
	)
	(segment
		(start 168.25214 -248.70537)
		(end 168.08831 -248.8692)
		(width 0.18288)
		(layer "In2.Cu")
		(net "M_F_CPU1_SB_CA<5>")
	)
	(segment
		(start 137.580116 -247.274842)
		(end 137.580116 -246.94388)
		(width 0.088646)
		(layer "In2.Cu")
		(net "M_F_CPU1_SB_CA<5>")
	)
	(segment
		(start 164.57803 -248.85269)
		(end 164.460936 -248.735596)
		(width 0.18288)
		(layer "In2.Cu")
		(net "M_F_CPU1_SB_CA<5>")
	)
	(segment
		(start 176.428146 -248.31675)
		(end 176.268126 -248.47677)
		(width 0.18288)
		(layer "In2.Cu")
		(net "M_F_CPU1_SB_CA<5>")
	)
	(arc
		(start 136.357868 -246.688864)
		(mid 136.075166 -246.613088)
		(end 135.792464 -246.688864)
		(width 0.088646)
		(layer "In2.Cu")
		(net "M_F_CPU1_SB_CA<5>")
	)
	(arc
		(start 137.297668 -246.688864)
		(mid 137.014966 -246.613088)
		(end 136.732264 -246.688864)
		(width 0.088646)
		(layer "In2.Cu")
		(net "M_F_CPU1_SB_CA<5>")
	)
	(arc
		(start 137.414762 -246.778526)
		(mid 137.359157 -246.729852)
		(end 137.297668 -246.688864)
		(width 0.088646)
		(layer "In2.Cu")
		(net "M_F_CPU1_SB_CA<5>")
	)
	(arc
		(start 136.732264 -246.688864)
		(mid 136.545066 -246.739007)
		(end 136.357868 -246.688864)
		(width 0.088646)
		(layer "In2.Cu")
		(net "M_F_CPU1_SB_CA<5>")
	)
	(arc
		(start 135.792464 -246.688864)
		(mid 135.605266 -246.739007)
		(end 135.418068 -246.688864)
		(width 0.088646)
		(layer "In2.Cu")
		(net "M_F_CPU1_SB_CA<5>")
	)
	(arc
		(start 135.417814 -246.68861)
		(mid 135.280769 -246.55165)
		(end 135.230616 -246.364506)
		(width 0.088646)
		(layer "In2.Cu")
		(net "M_F_CPU1_SB_CA<5>")
	)
	(segment
		(start 176.70526 -249.591576)
		(end 176.812702 -249.591576)
		(width 0.20066)
		(layer "F.Cu")
		(net "M_F_CPU1_SB_CA<4>")
	)
	(segment
		(start 179.011326 -249.604022)
		(end 179.427378 -249.604022)
		(width 0.20066)
		(layer "F.Cu")
		(net "M_F_CPU1_SB_CA<4>")
	)
	(segment
		(start 175.46066 -248.67235)
		(end 175.786034 -248.67235)
		(width 0.20066)
		(layer "F.Cu")
		(net "M_F_CPU1_SB_CA<4>")
	)
	(segment
		(start 181.444392 -249.16638)
		(end 181.444646 -249.166634)
		(width 0.20066)
		(layer "F.Cu")
		(net "M_F_CPU1_SB_CA<4>")
	)
	(segment
		(start 179.427378 -249.604022)
		(end 179.86502 -249.16638)
		(width 0.20066)
		(layer "F.Cu")
		(net "M_F_CPU1_SB_CA<4>")
	)
	(segment
		(start 173.900846 -249.166634)
		(end 174.966376 -249.166634)
		(width 0.20066)
		(layer "F.Cu")
		(net "M_F_CPU1_SB_CA<4>")
	)
	(segment
		(start 176.812702 -249.591576)
		(end 176.826418 -249.591576)
		(width 0.101854)
		(layer "F.Cu")
		(net "M_F_CPU1_SB_CA<4>")
	)
	(segment
		(start 178.99888 -249.591576)
		(end 179.011326 -249.604022)
		(width 0.1016)
		(layer "F.Cu")
		(net "M_F_CPU1_SB_CA<4>")
	)
	(segment
		(start 174.966376 -249.166634)
		(end 175.46066 -248.67235)
		(width 0.20066)
		(layer "F.Cu")
		(net "M_F_CPU1_SB_CA<4>")
	)
	(segment
		(start 176.826418 -249.591576)
		(end 178.99888 -249.591576)
		(width 0.1016)
		(layer "F.Cu")
		(net "M_F_CPU1_SB_CA<4>")
	)
	(segment
		(start 133.255766 -246.086376)
		(end 133.255766 -245.55069)
		(width 0.20066)
		(layer "F.Cu")
		(net "M_F_CPU1_SB_CA<4>")
	)
	(segment
		(start 179.86502 -249.16638)
		(end 181.444392 -249.16638)
		(width 0.20066)
		(layer "F.Cu")
		(net "M_F_CPU1_SB_CA<4>")
	)
	(segment
		(start 133.255512 -246.08663)
		(end 133.255766 -246.086376)
		(width 0.20066)
		(layer "F.Cu")
		(net "M_F_CPU1_SB_CA<4>")
	)
	(segment
		(start 172.795946 -249.166634)
		(end 173.900846 -249.166634)
		(width 0.20066)
		(layer "F.Cu")
		(net "M_F_CPU1_SB_CA<4>")
	)
	(segment
		(start 175.786034 -248.67235)
		(end 176.70526 -249.591576)
		(width 0.20066)
		(layer "F.Cu")
		(net "M_F_CPU1_SB_CA<4>")
	)
	(segment
		(start 150.628096 -249.682762)
		(end 148.861018 -247.915684)
		(width 0.18288)
		(layer "In2.Cu")
		(net "M_F_CPU1_SB_CA<4>")
	)
	(segment
		(start 135.040116 -246.374412)
		(end 135.040116 -246.364506)
		(width 0.088646)
		(layer "In2.Cu")
		(net "M_F_CPU1_SB_CA<4>")
	)
	(segment
		(start 160.512506 -249.371612)
		(end 159.898334 -249.371612)
		(width 0.18288)
		(layer "In2.Cu")
		(net "M_F_CPU1_SB_CA<4>")
	)
	(segment
		(start 155.786836 -249.760232)
		(end 155.593796 -249.567192)
		(width 0.18288)
		(layer "In2.Cu")
		(net "M_F_CPU1_SB_CA<4>")
	)
	(segment
		(start 167.18534 -249.607832)
		(end 166.877238 -249.607832)
		(width 0.18288)
		(layer "In2.Cu")
		(net "M_F_CPU1_SB_CA<4>")
	)
	(segment
		(start 137.38987 -247.178068)
		(end 137.38987 -247.022874)
		(width 0.088646)
		(layer "In2.Cu")
		(net "M_F_CPU1_SB_CA<4>")
	)
	(segment
		(start 154.145742 -249.682762)
		(end 150.628096 -249.682762)
		(width 0.18288)
		(layer "In2.Cu")
		(net "M_F_CPU1_SB_CA<4>")
	)
	(segment
		(start 169.324274 -249.865642)
		(end 168.73347 -249.865642)
		(width 0.18288)
		(layer "In2.Cu")
		(net "M_F_CPU1_SB_CA<4>")
	)
	(segment
		(start 140.414756 -249.207274)
		(end 139.0142 -249.207274)
		(width 0.18288)
		(layer "In2.Cu")
		(net "M_F_CPU1_SB_CA<4>")
	)
	(segment
		(start 171.483528 -249.753628)
		(end 170.974766 -249.244866)
		(width 0.18288)
		(layer "In2.Cu")
		(net "M_F_CPU1_SB_CA<4>")
	)
	(segment
		(start 156.490924 -250.168156)
		(end 156.297884 -250.361196)
		(width 0.18288)
		(layer "In2.Cu")
		(net "M_F_CPU1_SB_CA<4>")
	)
	(segment
		(start 160.672526 -249.864626)
		(end 160.672526 -249.531632)
		(width 0.18288)
		(layer "In2.Cu")
		(net "M_F_CPU1_SB_CA<4>")
	)
	(segment
		(start 165.015164 -249.371866)
		(end 164.513768 -249.873262)
		(width 0.18288)
		(layer "In2.Cu")
		(net "M_F_CPU1_SB_CA<4>")
	)
	(segment
		(start 165.34638 -249.371866)
		(end 165.015164 -249.371866)
		(width 0.18288)
		(layer "In2.Cu")
		(net "M_F_CPU1_SB_CA<4>")
	)
	(segment
		(start 163.936172 -249.873262)
		(end 163.314126 -249.251216)
		(width 0.18288)
		(layer "In2.Cu")
		(net "M_F_CPU1_SB_CA<4>")
	)
	(segment
		(start 161.428684 -249.80392)
		(end 161.215578 -250.017026)
		(width 0.18288)
		(layer "In2.Cu")
		(net "M_F_CPU1_SB_CA<4>")
	)
	(segment
		(start 154.5717 -250.361196)
		(end 154.37866 -250.168156)
		(width 0.18288)
		(layer "In2.Cu")
		(net "M_F_CPU1_SB_CA<4>")
	)
	(segment
		(start 161.884614 -249.80392)
		(end 161.428684 -249.80392)
		(width 0.18288)
		(layer "In2.Cu")
		(net "M_F_CPU1_SB_CA<4>")
	)
	(segment
		(start 156.683964 -249.567192)
		(end 156.490924 -249.760232)
		(width 0.18288)
		(layer "In2.Cu")
		(net "M_F_CPU1_SB_CA<4>")
	)
	(segment
		(start 166.877238 -249.607832)
		(end 166.570406 -249.914664)
		(width 0.18288)
		(layer "In2.Cu")
		(net "M_F_CPU1_SB_CA<4>")
	)
	(segment
		(start 155.593796 -249.567192)
		(end 155.275788 -249.567192)
		(width 0.18288)
		(layer "In2.Cu")
		(net "M_F_CPU1_SB_CA<4>")
	)
	(segment
		(start 133.88467 -246.023892)
		(end 133.255766 -245.55069)
		(width 0.088646)
		(layer "In2.Cu")
		(net "M_F_CPU1_SB_CA<4>")
	)
	(segment
		(start 170.974766 -249.244866)
		(end 169.94505 -249.244866)
		(width 0.18288)
		(layer "In2.Cu")
		(net "M_F_CPU1_SB_CA<4>")
	)
	(segment
		(start 148.861018 -247.915684)
		(end 142.250668 -247.915684)
		(width 0.18288)
		(layer "In2.Cu")
		(net "M_F_CPU1_SB_CA<4>")
	)
	(segment
		(start 154.889708 -250.361196)
		(end 154.5717 -250.361196)
		(width 0.18288)
		(layer "In2.Cu")
		(net "M_F_CPU1_SB_CA<4>")
	)
	(segment
		(start 155.082748 -250.168156)
		(end 154.889708 -250.361196)
		(width 0.18288)
		(layer "In2.Cu")
		(net "M_F_CPU1_SB_CA<4>")
	)
	(segment
		(start 167.784526 -249.385328)
		(end 167.407844 -249.385328)
		(width 0.18288)
		(layer "In2.Cu")
		(net "M_F_CPU1_SB_CA<4>")
	)
	(segment
		(start 155.786836 -250.168156)
		(end 155.786836 -249.760232)
		(width 0.18288)
		(layer "In2.Cu")
		(net "M_F_CPU1_SB_CA<4>")
	)
	(segment
		(start 169.94505 -249.244866)
		(end 169.324274 -249.865642)
		(width 0.18288)
		(layer "In2.Cu")
		(net "M_F_CPU1_SB_CA<4>")
	)
	(segment
		(start 141.343888 -248.822464)
		(end 140.414756 -249.207274)
		(width 0.18288)
		(layer "In2.Cu")
		(net "M_F_CPU1_SB_CA<4>")
	)
	(segment
		(start 168.73347 -249.865642)
		(end 168.607486 -249.991626)
		(width 0.18288)
		(layer "In2.Cu")
		(net "M_F_CPU1_SB_CA<4>")
	)
	(segment
		(start 137.660634 -247.853708)
		(end 137.389616 -247.58269)
		(width 0.088646)
		(layer "In2.Cu")
		(net "M_F_CPU1_SB_CA<4>")
	)
	(segment
		(start 167.964612 -249.565414)
		(end 167.784526 -249.385328)
		(width 0.18288)
		(layer "In2.Cu")
		(net "M_F_CPU1_SB_CA<4>")
	)
	(segment
		(start 137.389616 -247.58269)
		(end 137.389616 -247.178322)
		(width 0.088646)
		(layer "In2.Cu")
		(net "M_F_CPU1_SB_CA<4>")
	)
	(segment
		(start 160.672526 -249.531632)
		(end 160.512506 -249.371612)
		(width 0.18288)
		(layer "In2.Cu")
		(net "M_F_CPU1_SB_CA<4>")
	)
	(segment
		(start 155.082748 -249.760232)
		(end 155.082748 -250.168156)
		(width 0.18288)
		(layer "In2.Cu")
		(net "M_F_CPU1_SB_CA<4>")
	)
	(segment
		(start 154.37866 -249.91568)
		(end 154.145742 -249.682762)
		(width 0.18288)
		(layer "In2.Cu")
		(net "M_F_CPU1_SB_CA<4>")
	)
	(segment
		(start 168.607486 -249.991626)
		(end 168.124632 -249.991626)
		(width 0.18288)
		(layer "In2.Cu")
		(net "M_F_CPU1_SB_CA<4>")
	)
	(segment
		(start 142.250668 -247.915684)
		(end 141.343888 -248.822464)
		(width 0.18288)
		(layer "In2.Cu")
		(net "M_F_CPU1_SB_CA<4>")
	)
	(segment
		(start 172.208952 -249.753628)
		(end 171.483528 -249.753628)
		(width 0.18288)
		(layer "In2.Cu")
		(net "M_F_CPU1_SB_CA<4>")
	)
	(segment
		(start 139.0142 -249.207274)
		(end 137.660634 -247.853708)
		(width 0.18288)
		(layer "In2.Cu")
		(net "M_F_CPU1_SB_CA<4>")
	)
	(segment
		(start 161.215578 -250.017026)
		(end 160.824926 -250.017026)
		(width 0.18288)
		(layer "In2.Cu")
		(net "M_F_CPU1_SB_CA<4>")
	)
	(segment
		(start 162.437318 -249.251216)
		(end 161.884614 -249.80392)
		(width 0.18288)
		(layer "In2.Cu")
		(net "M_F_CPU1_SB_CA<4>")
	)
	(segment
		(start 155.979876 -250.361196)
		(end 155.786836 -250.168156)
		(width 0.18288)
		(layer "In2.Cu")
		(net "M_F_CPU1_SB_CA<4>")
	)
	(segment
		(start 158.391352 -249.971052)
		(end 157.987492 -249.567192)
		(width 0.18288)
		(layer "In2.Cu")
		(net "M_F_CPU1_SB_CA<4>")
	)
	(segment
		(start 164.513768 -249.873262)
		(end 163.936172 -249.873262)
		(width 0.18288)
		(layer "In2.Cu")
		(net "M_F_CPU1_SB_CA<4>")
	)
	(segment
		(start 172.795946 -249.166634)
		(end 172.208952 -249.753628)
		(width 0.18288)
		(layer "In2.Cu")
		(net "M_F_CPU1_SB_CA<4>")
	)
	(segment
		(start 160.824926 -250.017026)
		(end 160.672526 -249.864626)
		(width 0.18288)
		(layer "In2.Cu")
		(net "M_F_CPU1_SB_CA<4>")
	)
	(segment
		(start 134.852918 -246.040402)
		(end 134.852664 -246.040148)
		(width 0.088646)
		(layer "In2.Cu")
		(net "M_F_CPU1_SB_CA<4>")
	)
	(segment
		(start 159.298894 -249.971052)
		(end 158.391352 -249.971052)
		(width 0.18288)
		(layer "In2.Cu")
		(net "M_F_CPU1_SB_CA<4>")
	)
	(segment
		(start 137.280142 -246.9134)
		(end 137.280142 -246.913146)
		(width 0.088646)
		(layer "In2.Cu")
		(net "M_F_CPU1_SB_CA<4>")
	)
	(segment
		(start 168.124632 -249.991626)
		(end 167.964612 -249.831606)
		(width 0.18288)
		(layer "In2.Cu")
		(net "M_F_CPU1_SB_CA<4>")
	)
	(segment
		(start 165.889178 -249.914664)
		(end 165.34638 -249.371866)
		(width 0.18288)
		(layer "In2.Cu")
		(net "M_F_CPU1_SB_CA<4>")
	)
	(segment
		(start 156.490924 -249.760232)
		(end 156.490924 -250.168156)
		(width 0.18288)
		(layer "In2.Cu")
		(net "M_F_CPU1_SB_CA<4>")
	)
	(segment
		(start 159.898334 -249.371612)
		(end 159.298894 -249.971052)
		(width 0.18288)
		(layer "In2.Cu")
		(net "M_F_CPU1_SB_CA<4>")
	)
	(segment
		(start 166.570406 -249.914664)
		(end 165.889178 -249.914664)
		(width 0.18288)
		(layer "In2.Cu")
		(net "M_F_CPU1_SB_CA<4>")
	)
	(segment
		(start 163.314126 -249.251216)
		(end 162.437318 -249.251216)
		(width 0.18288)
		(layer "In2.Cu")
		(net "M_F_CPU1_SB_CA<4>")
	)
	(segment
		(start 137.389616 -247.178322)
		(end 137.38987 -247.178068)
		(width 0.088646)
		(layer "In2.Cu")
		(net "M_F_CPU1_SB_CA<4>")
	)
	(segment
		(start 156.297884 -250.361196)
		(end 155.979876 -250.361196)
		(width 0.18288)
		(layer "In2.Cu")
		(net "M_F_CPU1_SB_CA<4>")
	)
	(segment
		(start 154.37866 -250.168156)
		(end 154.37866 -249.91568)
		(width 0.18288)
		(layer "In2.Cu")
		(net "M_F_CPU1_SB_CA<4>")
	)
	(segment
		(start 133.912864 -246.040148)
		(end 133.88467 -246.023892)
		(width 0.088646)
		(layer "In2.Cu")
		(net "M_F_CPU1_SB_CA<4>")
	)
	(segment
		(start 157.987492 -249.567192)
		(end 156.683964 -249.567192)
		(width 0.18288)
		(layer "In2.Cu")
		(net "M_F_CPU1_SB_CA<4>")
	)
	(segment
		(start 155.275788 -249.567192)
		(end 155.082748 -249.760232)
		(width 0.18288)
		(layer "In2.Cu")
		(net "M_F_CPU1_SB_CA<4>")
	)
	(segment
		(start 137.38987 -247.022874)
		(end 137.280142 -246.9134)
		(width 0.088646)
		(layer "In2.Cu")
		(net "M_F_CPU1_SB_CA<4>")
	)
	(segment
		(start 167.964612 -249.831606)
		(end 167.964612 -249.565414)
		(width 0.18288)
		(layer "In2.Cu")
		(net "M_F_CPU1_SB_CA<4>")
	)
	(segment
		(start 167.407844 -249.385328)
		(end 167.18534 -249.607832)
		(width 0.18288)
		(layer "In2.Cu")
		(net "M_F_CPU1_SB_CA<4>")
	)
	(arc
		(start 135.040116 -246.364506)
		(mid 134.989952 -246.177368)
		(end 134.852918 -246.040402)
		(width 0.088646)
		(layer "In2.Cu")
		(net "M_F_CPU1_SB_CA<4>")
	)
	(arc
		(start 134.852664 -246.040148)
		(mid 134.665466 -245.990005)
		(end 134.478268 -246.040148)
		(width 0.088646)
		(layer "In2.Cu")
		(net "M_F_CPU1_SB_CA<4>")
	)
	(arc
		(start 137.280142 -246.913146)
		(mid 137.243092 -246.881)
		(end 137.202164 -246.853964)
		(width 0.088646)
		(layer "In2.Cu")
		(net "M_F_CPU1_SB_CA<4>")
	)
	(arc
		(start 136.262364 -246.853964)
		(mid 136.075166 -246.803821)
		(end 135.887968 -246.853964)
		(width 0.088646)
		(layer "In2.Cu")
		(net "M_F_CPU1_SB_CA<4>")
	)
	(arc
		(start 135.887968 -246.853964)
		(mid 135.605266 -246.92974)
		(end 135.322564 -246.853964)
		(width 0.088646)
		(layer "In2.Cu")
		(net "M_F_CPU1_SB_CA<4>")
	)
	(arc
		(start 136.827768 -246.853964)
		(mid 136.545066 -246.92974)
		(end 136.262364 -246.853964)
		(width 0.088646)
		(layer "In2.Cu")
		(net "M_F_CPU1_SB_CA<4>")
	)
	(arc
		(start 134.478268 -246.040148)
		(mid 134.195566 -246.11589)
		(end 133.912864 -246.040148)
		(width 0.088646)
		(layer "In2.Cu")
		(net "M_F_CPU1_SB_CA<4>")
	)
	(arc
		(start 135.322564 -246.853964)
		(mid 135.118229 -246.651359)
		(end 135.040116 -246.374412)
		(width 0.088646)
		(layer "In2.Cu")
		(net "M_F_CPU1_SB_CA<4>")
	)
	(arc
		(start 137.202164 -246.853964)
		(mid 137.014966 -246.803821)
		(end 136.827768 -246.853964)
		(width 0.088646)
		(layer "In2.Cu")
		(net "M_F_CPU1_SB_CA<4>")
	)
	(segment
		(start 183.593994 -249.58421)
		(end 183.9976 -249.58421)
		(width 0.20066)
		(layer "F.Cu")
		(net "M_F_CPU1_SB_CA<3>")
	)
	(segment
		(start 134.665466 -246.900446)
		(end 134.665466 -246.364506)
		(width 0.20066)
		(layer "F.Cu")
		(net "M_F_CPU1_SB_CA<3>")
	)
	(segment
		(start 184.430162 -250.016772)
		(end 185.544714 -250.016772)
		(width 0.20066)
		(layer "F.Cu")
		(net "M_F_CPU1_SB_CA<3>")
	)
	(segment
		(start 183.9976 -249.58421)
		(end 184.430162 -250.016772)
		(width 0.20066)
		(layer "F.Cu")
		(net "M_F_CPU1_SB_CA<3>")
	)
	(segment
		(start 180.072284 -250.452382)
		(end 180.423058 -250.452382)
		(width 0.20066)
		(layer "F.Cu")
		(net "M_F_CPU1_SB_CA<3>")
	)
	(segment
		(start 176.896014 -250.016772)
		(end 178.000914 -250.016772)
		(width 0.20066)
		(layer "F.Cu")
		(net "M_F_CPU1_SB_CA<3>")
	)
	(segment
		(start 180.438552 -250.441714)
		(end 182.447692 -250.441714)
		(width 0.1016)
		(layer "F.Cu")
		(net "M_F_CPU1_SB_CA<3>")
	)
	(segment
		(start 180.423058 -250.452382)
		(end 180.427884 -250.452382)
		(width 0.101854)
		(layer "F.Cu")
		(net "M_F_CPU1_SB_CA<3>")
	)
	(segment
		(start 178.000914 -250.016772)
		(end 179.636674 -250.016772)
		(width 0.20066)
		(layer "F.Cu")
		(net "M_F_CPU1_SB_CA<3>")
	)
	(segment
		(start 182.447692 -250.441714)
		(end 182.455058 -250.44908)
		(width 0.1016)
		(layer "F.Cu")
		(net "M_F_CPU1_SB_CA<3>")
	)
	(segment
		(start 182.455058 -250.44908)
		(end 182.729124 -250.44908)
		(width 0.20066)
		(layer "F.Cu")
		(net "M_F_CPU1_SB_CA<3>")
	)
	(segment
		(start 182.729124 -250.44908)
		(end 183.593994 -249.58421)
		(width 0.20066)
		(layer "F.Cu")
		(net "M_F_CPU1_SB_CA<3>")
	)
	(segment
		(start 179.636674 -250.016772)
		(end 180.072284 -250.452382)
		(width 0.20066)
		(layer "F.Cu")
		(net "M_F_CPU1_SB_CA<3>")
	)
	(segment
		(start 180.427884 -250.452382)
		(end 180.438552 -250.441714)
		(width 0.1016)
		(layer "F.Cu")
		(net "M_F_CPU1_SB_CA<3>")
	)
	(segment
		(start 139.009882 -249.701558)
		(end 137.41146 -248.103136)
		(width 0.18288)
		(layer "In2.Cu")
		(net "M_F_CPU1_SB_CA<3>")
	)
	(segment
		(start 164.252402 -250.448572)
		(end 164.221922 -250.418092)
		(width 0.18288)
		(layer "In2.Cu")
		(net "M_F_CPU1_SB_CA<3>")
	)
	(segment
		(start 136.378442 -247.553226)
		(end 136.075166 -247.553226)
		(width 0.088646)
		(layer "In2.Cu")
		(net "M_F_CPU1_SB_CA<3>")
	)
	(segment
		(start 134.309104 -246.480076)
		(end 134.302246 -246.450358)
		(width 0.088646)
		(layer "In2.Cu")
		(net "M_F_CPU1_SB_CA<3>")
	)
	(segment
		(start 134.478268 -246.688864)
		(end 134.478014 -246.68861)
		(width 0.088646)
		(layer "In2.Cu")
		(net "M_F_CPU1_SB_CA<3>")
	)
	(segment
		(start 167.676068 -250.448572)
		(end 164.252402 -250.448572)
		(width 0.18288)
		(layer "In2.Cu")
		(net "M_F_CPU1_SB_CA<3>")
	)
	(segment
		(start 161.32048 -250.65863)
		(end 159.91713 -250.65863)
		(width 0.18288)
		(layer "In2.Cu")
		(net "M_F_CPU1_SB_CA<3>")
	)
	(segment
		(start 176.456594 -250.456192)
		(end 174.573438 -250.456192)
		(width 0.18288)
		(layer "In2.Cu")
		(net "M_F_CPU1_SB_CA<3>")
	)
	(segment
		(start 154.172158 -250.879864)
		(end 153.518616 -250.226322)
		(width 0.18288)
		(layer "In2.Cu")
		(net "M_F_CPU1_SB_CA<3>")
	)
	(segment
		(start 164.221922 -250.418092)
		(end 161.561018 -250.418092)
		(width 0.18288)
		(layer "In2.Cu")
		(net "M_F_CPU1_SB_CA<3>")
	)
	(segment
		(start 134.302246 -246.450358)
		(end 134.388098 -246.364506)
		(width 0.088646)
		(layer "In2.Cu")
		(net "M_F_CPU1_SB_CA<3>")
	)
	(segment
		(start 150.44674 -250.226322)
		(end 148.486368 -248.26595)
		(width 0.18288)
		(layer "In2.Cu")
		(net "M_F_CPU1_SB_CA<3>")
	)
	(segment
		(start 159.738568 -250.480068)
		(end 157.504892 -250.480068)
		(width 0.18288)
		(layer "In2.Cu")
		(net "M_F_CPU1_SB_CA<3>")
	)
	(segment
		(start 134.948168 -247.50268)
		(end 134.939278 -247.4976)
		(width 0.088646)
		(layer "In2.Cu")
		(net "M_F_CPU1_SB_CA<3>")
	)
	(segment
		(start 172.125132 -250.264422)
		(end 171.442634 -250.264422)
		(width 0.18288)
		(layer "In2.Cu")
		(net "M_F_CPU1_SB_CA<3>")
	)
	(segment
		(start 137.41146 -248.103136)
		(end 137.22985 -247.921526)
		(width 0.088646)
		(layer "In2.Cu")
		(net "M_F_CPU1_SB_CA<3>")
	)
	(segment
		(start 134.760716 -247.178322)
		(end 134.760716 -247.168416)
		(width 0.088646)
		(layer "In2.Cu")
		(net "M_F_CPU1_SB_CA<3>")
	)
	(segment
		(start 137.22985 -247.921526)
		(end 136.746742 -247.921526)
		(width 0.088646)
		(layer "In2.Cu")
		(net "M_F_CPU1_SB_CA<3>")
	)
	(segment
		(start 141.861032 -249.12574)
		(end 140.470382 -249.701558)
		(width 0.18288)
		(layer "In2.Cu")
		(net "M_F_CPU1_SB_CA<3>")
	)
	(segment
		(start 168.15562 -250.928124)
		(end 167.676068 -250.448572)
		(width 0.18288)
		(layer "In2.Cu")
		(net "M_F_CPU1_SB_CA<3>")
	)
	(segment
		(start 161.561018 -250.418092)
		(end 161.32048 -250.65863)
		(width 0.18288)
		(layer "In2.Cu")
		(net "M_F_CPU1_SB_CA<3>")
	)
	(segment
		(start 174.240952 -249.73407)
		(end 173.862238 -249.73407)
		(width 0.18288)
		(layer "In2.Cu")
		(net "M_F_CPU1_SB_CA<3>")
	)
	(segment
		(start 159.91713 -250.65863)
		(end 159.738568 -250.480068)
		(width 0.18288)
		(layer "In2.Cu")
		(net "M_F_CPU1_SB_CA<3>")
	)
	(segment
		(start 153.518616 -250.226322)
		(end 150.44674 -250.226322)
		(width 0.18288)
		(layer "In2.Cu")
		(net "M_F_CPU1_SB_CA<3>")
	)
	(segment
		(start 173.862238 -249.73407)
		(end 173.154848 -250.44146)
		(width 0.18288)
		(layer "In2.Cu")
		(net "M_F_CPU1_SB_CA<3>")
	)
	(segment
		(start 174.573438 -250.456192)
		(end 174.400972 -250.283726)
		(width 0.18288)
		(layer "In2.Cu")
		(net "M_F_CPU1_SB_CA<3>")
	)
	(segment
		(start 173.154848 -250.44146)
		(end 172.30217 -250.44146)
		(width 0.18288)
		(layer "In2.Cu")
		(net "M_F_CPU1_SB_CA<3>")
	)
	(segment
		(start 157.105096 -250.879864)
		(end 154.172158 -250.879864)
		(width 0.18288)
		(layer "In2.Cu")
		(net "M_F_CPU1_SB_CA<3>")
	)
	(segment
		(start 134.388098 -246.364506)
		(end 134.665466 -246.364506)
		(width 0.088646)
		(layer "In2.Cu")
		(net "M_F_CPU1_SB_CA<3>")
	)
	(segment
		(start 169.184066 -250.395994)
		(end 168.651936 -250.928124)
		(width 0.18288)
		(layer "In2.Cu")
		(net "M_F_CPU1_SB_CA<3>")
	)
	(segment
		(start 136.746742 -247.921526)
		(end 136.378442 -247.553226)
		(width 0.088646)
		(layer "In2.Cu")
		(net "M_F_CPU1_SB_CA<3>")
	)
	(segment
		(start 169.969688 -250.754388)
		(end 169.611294 -250.395994)
		(width 0.18288)
		(layer "In2.Cu")
		(net "M_F_CPU1_SB_CA<3>")
	)
	(segment
		(start 148.486368 -248.26595)
		(end 142.720822 -248.26595)
		(width 0.18288)
		(layer "In2.Cu")
		(net "M_F_CPU1_SB_CA<3>")
	)
	(segment
		(start 172.30217 -250.44146)
		(end 172.125132 -250.264422)
		(width 0.18288)
		(layer "In2.Cu")
		(net "M_F_CPU1_SB_CA<3>")
	)
	(segment
		(start 142.720822 -248.26595)
		(end 141.861032 -249.12574)
		(width 0.18288)
		(layer "In2.Cu")
		(net "M_F_CPU1_SB_CA<3>")
	)
	(segment
		(start 174.400972 -249.89409)
		(end 174.240952 -249.73407)
		(width 0.18288)
		(layer "In2.Cu")
		(net "M_F_CPU1_SB_CA<3>")
	)
	(segment
		(start 176.896014 -250.016772)
		(end 176.456594 -250.456192)
		(width 0.18288)
		(layer "In2.Cu")
		(net "M_F_CPU1_SB_CA<3>")
	)
	(segment
		(start 170.952668 -250.754388)
		(end 169.969688 -250.754388)
		(width 0.18288)
		(layer "In2.Cu")
		(net "M_F_CPU1_SB_CA<3>")
	)
	(segment
		(start 174.400972 -250.283726)
		(end 174.400972 -249.89409)
		(width 0.18288)
		(layer "In2.Cu")
		(net "M_F_CPU1_SB_CA<3>")
	)
	(segment
		(start 157.504892 -250.480068)
		(end 157.105096 -250.879864)
		(width 0.18288)
		(layer "In2.Cu")
		(net "M_F_CPU1_SB_CA<3>")
	)
	(segment
		(start 168.651936 -250.928124)
		(end 168.15562 -250.928124)
		(width 0.18288)
		(layer "In2.Cu")
		(net "M_F_CPU1_SB_CA<3>")
	)
	(segment
		(start 140.470382 -249.701558)
		(end 139.009882 -249.701558)
		(width 0.18288)
		(layer "In2.Cu")
		(net "M_F_CPU1_SB_CA<3>")
	)
	(segment
		(start 169.611294 -250.395994)
		(end 169.184066 -250.395994)
		(width 0.18288)
		(layer "In2.Cu")
		(net "M_F_CPU1_SB_CA<3>")
	)
	(segment
		(start 171.442634 -250.264422)
		(end 170.952668 -250.754388)
		(width 0.18288)
		(layer "In2.Cu")
		(net "M_F_CPU1_SB_CA<3>")
	)
	(arc
		(start 136.075166 -247.553226)
		(mid 135.978243 -247.540268)
		(end 135.887968 -247.50268)
		(width 0.088646)
		(layer "In2.Cu")
		(net "M_F_CPU1_SB_CA<3>")
	)
	(arc
		(start 134.760716 -247.168416)
		(mid 134.682605 -246.891467)
		(end 134.478268 -246.688864)
		(width 0.088646)
		(layer "In2.Cu")
		(net "M_F_CPU1_SB_CA<3>")
	)
	(arc
		(start 135.322564 -247.50268)
		(mid 135.135366 -247.552823)
		(end 134.948168 -247.50268)
		(width 0.088646)
		(layer "In2.Cu")
		(net "M_F_CPU1_SB_CA<3>")
	)
	(arc
		(start 135.887968 -247.50268)
		(mid 135.605266 -247.426904)
		(end 135.322564 -247.50268)
		(width 0.088646)
		(layer "In2.Cu")
		(net "M_F_CPU1_SB_CA<3>")
	)
	(arc
		(start 134.939278 -247.4976)
		(mid 134.808364 -247.36124)
		(end 134.760716 -247.178322)
		(width 0.088646)
		(layer "In2.Cu")
		(net "M_F_CPU1_SB_CA<3>")
	)
	(arc
		(start 134.478014 -246.68861)
		(mid 134.374218 -246.600009)
		(end 134.309104 -246.480076)
		(width 0.088646)
		(layer "In2.Cu")
		(net "M_F_CPU1_SB_CA<3>")
	)
	(segment
		(start 179.86502 -250.866402)
		(end 181.444392 -250.866402)
		(width 0.20066)
		(layer "F.Cu")
		(net "M_F_CPU1_SB_CA<2>")
	)
	(segment
		(start 179.011326 -251.304044)
		(end 179.427378 -251.304044)
		(width 0.20066)
		(layer "F.Cu")
		(net "M_F_CPU1_SB_CA<2>")
	)
	(segment
		(start 175.786034 -250.372372)
		(end 176.70526 -251.291598)
		(width 0.20066)
		(layer "F.Cu")
		(net "M_F_CPU1_SB_CA<2>")
	)
	(segment
		(start 133.725666 -246.900446)
		(end 133.725666 -246.364506)
		(width 0.20066)
		(layer "F.Cu")
		(net "M_F_CPU1_SB_CA<2>")
	)
	(segment
		(start 172.795946 -250.866656)
		(end 173.900846 -250.866656)
		(width 0.20066)
		(layer "F.Cu")
		(net "M_F_CPU1_SB_CA<2>")
	)
	(segment
		(start 173.900846 -250.866656)
		(end 174.966376 -250.866656)
		(width 0.20066)
		(layer "F.Cu")
		(net "M_F_CPU1_SB_CA<2>")
	)
	(segment
		(start 174.966376 -250.866656)
		(end 175.46066 -250.372372)
		(width 0.20066)
		(layer "F.Cu")
		(net "M_F_CPU1_SB_CA<2>")
	)
	(segment
		(start 178.99888 -251.291598)
		(end 179.011326 -251.304044)
		(width 0.1016)
		(layer "F.Cu")
		(net "M_F_CPU1_SB_CA<2>")
	)
	(segment
		(start 176.812702 -251.291598)
		(end 176.826418 -251.291598)
		(width 0.101854)
		(layer "F.Cu")
		(net "M_F_CPU1_SB_CA<2>")
	)
	(segment
		(start 181.444392 -250.866402)
		(end 181.444646 -250.866656)
		(width 0.20066)
		(layer "F.Cu")
		(net "M_F_CPU1_SB_CA<2>")
	)
	(segment
		(start 176.826418 -251.291598)
		(end 178.99888 -251.291598)
		(width 0.1016)
		(layer "F.Cu")
		(net "M_F_CPU1_SB_CA<2>")
	)
	(segment
		(start 176.70526 -251.291598)
		(end 176.812702 -251.291598)
		(width 0.20066)
		(layer "F.Cu")
		(net "M_F_CPU1_SB_CA<2>")
	)
	(segment
		(start 179.427378 -251.304044)
		(end 179.86502 -250.866402)
		(width 0.20066)
		(layer "F.Cu")
		(net "M_F_CPU1_SB_CA<2>")
	)
	(segment
		(start 175.46066 -250.372372)
		(end 175.786034 -250.372372)
		(width 0.20066)
		(layer "F.Cu")
		(net "M_F_CPU1_SB_CA<2>")
	)
	(segment
		(start 142.373858 -249.424698)
		(end 140.755624 -250.095004)
		(width 0.18288)
		(layer "In2.Cu")
		(net "M_F_CPU1_SB_CA<2>")
	)
	(segment
		(start 134.103872 -246.429784)
		(end 134.038594 -246.364506)
		(width 0.088646)
		(layer "In2.Cu")
		(net "M_F_CPU1_SB_CA<2>")
	)
	(segment
		(start 163.087304 -250.939046)
		(end 162.53968 -250.939046)
		(width 0.18288)
		(layer "In2.Cu")
		(net "M_F_CPU1_SB_CA<2>")
	)
	(segment
		(start 151.412702 -250.953016)
		(end 151.412702 -251.2187)
		(width 0.18288)
		(layer "In2.Cu")
		(net "M_F_CPU1_SB_CA<2>")
	)
	(segment
		(start 165.297104 -251.005594)
		(end 164.974778 -251.005594)
		(width 0.18288)
		(layer "In2.Cu")
		(net "M_F_CPU1_SB_CA<2>")
	)
	(segment
		(start 164.596318 -251.906024)
		(end 164.216334 -251.906024)
		(width 0.18288)
		(layer "In2.Cu")
		(net "M_F_CPU1_SB_CA<2>")
	)
	(segment
		(start 164.023294 -251.712984)
		(end 164.023294 -251.59716)
		(width 0.18288)
		(layer "In2.Cu")
		(net "M_F_CPU1_SB_CA<2>")
	)
	(segment
		(start 152.820878 -250.953016)
		(end 152.820878 -251.2187)
		(width 0.18288)
		(layer "In2.Cu")
		(net "M_F_CPU1_SB_CA<2>")
	)
	(segment
		(start 163.498784 -251.350526)
		(end 163.087304 -250.939046)
		(width 0.18288)
		(layer "In2.Cu")
		(net "M_F_CPU1_SB_CA<2>")
	)
	(segment
		(start 164.974778 -251.005594)
		(end 164.756338 -251.224034)
		(width 0.18288)
		(layer "In2.Cu")
		(net "M_F_CPU1_SB_CA<2>")
	)
	(segment
		(start 171.176188 -251.265436)
		(end 169.584116 -251.265436)
		(width 0.18288)
		(layer "In2.Cu")
		(net "M_F_CPU1_SB_CA<2>")
	)
	(segment
		(start 147.900644 -248.61139)
		(end 143.187166 -248.61139)
		(width 0.18288)
		(layer "In2.Cu")
		(net "M_F_CPU1_SB_CA<2>")
	)
	(segment
		(start 172.795946 -250.866656)
		(end 172.301154 -251.361448)
		(width 0.18288)
		(layer "In2.Cu")
		(net "M_F_CPU1_SB_CA<2>")
	)
	(segment
		(start 164.756338 -251.224034)
		(end 164.756338 -251.746004)
		(width 0.18288)
		(layer "In2.Cu")
		(net "M_F_CPU1_SB_CA<2>")
	)
	(segment
		(start 164.216334 -251.906024)
		(end 164.023294 -251.712984)
		(width 0.18288)
		(layer "In2.Cu")
		(net "M_F_CPU1_SB_CA<2>")
	)
	(segment
		(start 138.824208 -250.00458)
		(end 137.167112 -248.347484)
		(width 0.18288)
		(layer "In2.Cu")
		(net "M_F_CPU1_SB_CA<2>")
	)
	(segment
		(start 160.675828 -251.487686)
		(end 160.314386 -251.487686)
		(width 0.18288)
		(layer "In2.Cu")
		(net "M_F_CPU1_SB_CA<2>")
	)
	(segment
		(start 152.11679 -251.2187)
		(end 152.11679 -250.953016)
		(width 0.18288)
		(layer "In2.Cu")
		(net "M_F_CPU1_SB_CA<2>")
	)
	(segment
		(start 171.676314 -251.765562)
		(end 171.176188 -251.265436)
		(width 0.18288)
		(layer "In2.Cu")
		(net "M_F_CPU1_SB_CA<2>")
	)
	(segment
		(start 165.889432 -251.597922)
		(end 165.297104 -251.005594)
		(width 0.18288)
		(layer "In2.Cu")
		(net "M_F_CPU1_SB_CA<2>")
	)
	(segment
		(start 163.77666 -251.350526)
		(end 163.498784 -251.350526)
		(width 0.18288)
		(layer "In2.Cu")
		(net "M_F_CPU1_SB_CA<2>")
	)
	(segment
		(start 172.301154 -251.361448)
		(end 172.301154 -251.602748)
		(width 0.18288)
		(layer "In2.Cu")
		(net "M_F_CPU1_SB_CA<2>")
	)
	(segment
		(start 161.932874 -251.545852)
		(end 161.591752 -251.545852)
		(width 0.18288)
		(layer "In2.Cu")
		(net "M_F_CPU1_SB_CA<2>")
	)
	(segment
		(start 164.023294 -251.59716)
		(end 163.77666 -251.350526)
		(width 0.18288)
		(layer "In2.Cu")
		(net "M_F_CPU1_SB_CA<2>")
	)
	(segment
		(start 161.27603 -251.23013)
		(end 160.933384 -251.23013)
		(width 0.18288)
		(layer "In2.Cu")
		(net "M_F_CPU1_SB_CA<2>")
	)
	(segment
		(start 157.813502 -251.189236)
		(end 157.540452 -251.189236)
		(width 0.18288)
		(layer "In2.Cu")
		(net "M_F_CPU1_SB_CA<2>")
	)
	(segment
		(start 157.540452 -251.189236)
		(end 157.317948 -251.41174)
		(width 0.18288)
		(layer "In2.Cu")
		(net "M_F_CPU1_SB_CA<2>")
	)
	(segment
		(start 152.11679 -250.953016)
		(end 151.92375 -250.759976)
		(width 0.18288)
		(layer "In2.Cu")
		(net "M_F_CPU1_SB_CA<2>")
	)
	(segment
		(start 136.944354 -248.124726)
		(end 136.64565 -248.124726)
		(width 0.088646)
		(layer "In2.Cu")
		(net "M_F_CPU1_SB_CA<2>")
	)
	(segment
		(start 158.236666 -251.6124)
		(end 157.813502 -251.189236)
		(width 0.18288)
		(layer "In2.Cu")
		(net "M_F_CPU1_SB_CA<2>")
	)
	(segment
		(start 164.756338 -251.746004)
		(end 164.596318 -251.906024)
		(width 0.18288)
		(layer "In2.Cu")
		(net "M_F_CPU1_SB_CA<2>")
	)
	(segment
		(start 160.314386 -251.487686)
		(end 160.028382 -251.201682)
		(width 0.18288)
		(layer "In2.Cu")
		(net "M_F_CPU1_SB_CA<2>")
	)
	(segment
		(start 152.627838 -251.41174)
		(end 152.30983 -251.41174)
		(width 0.18288)
		(layer "In2.Cu")
		(net "M_F_CPU1_SB_CA<2>")
	)
	(segment
		(start 153.524966 -251.2187)
		(end 153.524966 -250.953016)
		(width 0.18288)
		(layer "In2.Cu")
		(net "M_F_CPU1_SB_CA<2>")
	)
	(segment
		(start 162.53968 -250.939046)
		(end 161.932874 -251.545852)
		(width 0.18288)
		(layer "In2.Cu")
		(net "M_F_CPU1_SB_CA<2>")
	)
	(segment
		(start 151.219662 -251.41174)
		(end 150.700994 -251.41174)
		(width 0.18288)
		(layer "In2.Cu")
		(net "M_F_CPU1_SB_CA<2>")
	)
	(segment
		(start 136.64565 -248.124726)
		(end 136.264396 -247.743472)
		(width 0.088646)
		(layer "In2.Cu")
		(net "M_F_CPU1_SB_CA<2>")
	)
	(segment
		(start 134.391654 -246.859044)
		(end 134.382764 -246.853964)
		(width 0.088646)
		(layer "In2.Cu")
		(net "M_F_CPU1_SB_CA<2>")
	)
	(segment
		(start 140.755624 -250.095004)
		(end 139.042648 -250.095004)
		(width 0.18288)
		(layer "In2.Cu")
		(net "M_F_CPU1_SB_CA<2>")
	)
	(segment
		(start 172.301154 -251.602748)
		(end 172.13834 -251.765562)
		(width 0.18288)
		(layer "In2.Cu")
		(net "M_F_CPU1_SB_CA<2>")
	)
	(segment
		(start 167.298116 -251.175266)
		(end 166.87546 -251.597922)
		(width 0.18288)
		(layer "In2.Cu")
		(net "M_F_CPU1_SB_CA<2>")
	)
	(segment
		(start 166.87546 -251.597922)
		(end 165.889432 -251.597922)
		(width 0.18288)
		(layer "In2.Cu")
		(net "M_F_CPU1_SB_CA<2>")
	)
	(segment
		(start 153.718006 -251.41174)
		(end 153.524966 -251.2187)
		(width 0.18288)
		(layer "In2.Cu")
		(net "M_F_CPU1_SB_CA<2>")
	)
	(segment
		(start 169.584116 -251.265436)
		(end 169.105834 -251.743718)
		(width 0.18288)
		(layer "In2.Cu")
		(net "M_F_CPU1_SB_CA<2>")
	)
	(segment
		(start 161.591752 -251.545852)
		(end 161.27603 -251.23013)
		(width 0.18288)
		(layer "In2.Cu")
		(net "M_F_CPU1_SB_CA<2>")
	)
	(segment
		(start 134.114286 -246.489474)
		(end 134.103872 -246.429784)
		(width 0.088646)
		(layer "In2.Cu")
		(net "M_F_CPU1_SB_CA<2>")
	)
	(segment
		(start 160.933384 -251.23013)
		(end 160.675828 -251.487686)
		(width 0.18288)
		(layer "In2.Cu")
		(net "M_F_CPU1_SB_CA<2>")
	)
	(segment
		(start 159.298386 -251.6124)
		(end 158.236666 -251.6124)
		(width 0.18288)
		(layer "In2.Cu")
		(net "M_F_CPU1_SB_CA<2>")
	)
	(segment
		(start 137.167112 -248.347484)
		(end 136.944354 -248.124726)
		(width 0.088646)
		(layer "In2.Cu")
		(net "M_F_CPU1_SB_CA<2>")
	)
	(segment
		(start 151.412702 -251.2187)
		(end 151.219662 -251.41174)
		(width 0.18288)
		(layer "In2.Cu")
		(net "M_F_CPU1_SB_CA<2>")
	)
	(segment
		(start 157.317948 -251.41174)
		(end 153.718006 -251.41174)
		(width 0.18288)
		(layer "In2.Cu")
		(net "M_F_CPU1_SB_CA<2>")
	)
	(segment
		(start 168.139872 -251.743718)
		(end 167.57142 -251.175266)
		(width 0.18288)
		(layer "In2.Cu")
		(net "M_F_CPU1_SB_CA<2>")
	)
	(segment
		(start 152.820878 -251.2187)
		(end 152.627838 -251.41174)
		(width 0.18288)
		(layer "In2.Cu")
		(net "M_F_CPU1_SB_CA<2>")
	)
	(segment
		(start 150.700994 -251.41174)
		(end 147.900644 -248.61139)
		(width 0.18288)
		(layer "In2.Cu")
		(net "M_F_CPU1_SB_CA<2>")
	)
	(segment
		(start 151.605742 -250.759976)
		(end 151.412702 -250.953016)
		(width 0.18288)
		(layer "In2.Cu")
		(net "M_F_CPU1_SB_CA<2>")
	)
	(segment
		(start 143.187166 -248.61139)
		(end 142.373858 -249.424698)
		(width 0.18288)
		(layer "In2.Cu")
		(net "M_F_CPU1_SB_CA<2>")
	)
	(segment
		(start 153.331926 -250.759976)
		(end 153.013918 -250.759976)
		(width 0.18288)
		(layer "In2.Cu")
		(net "M_F_CPU1_SB_CA<2>")
	)
	(segment
		(start 160.028382 -251.201682)
		(end 159.709104 -251.201682)
		(width 0.18288)
		(layer "In2.Cu")
		(net "M_F_CPU1_SB_CA<2>")
	)
	(segment
		(start 134.570216 -247.188228)
		(end 134.570216 -247.178322)
		(width 0.088646)
		(layer "In2.Cu")
		(net "M_F_CPU1_SB_CA<2>")
	)
	(segment
		(start 134.038594 -246.364506)
		(end 133.725666 -246.364506)
		(width 0.088646)
		(layer "In2.Cu")
		(net "M_F_CPU1_SB_CA<2>")
	)
	(segment
		(start 152.30983 -251.41174)
		(end 152.11679 -251.2187)
		(width 0.18288)
		(layer "In2.Cu")
		(net "M_F_CPU1_SB_CA<2>")
	)
	(segment
		(start 153.524966 -250.953016)
		(end 153.331926 -250.759976)
		(width 0.18288)
		(layer "In2.Cu")
		(net "M_F_CPU1_SB_CA<2>")
	)
	(segment
		(start 169.105834 -251.743718)
		(end 168.139872 -251.743718)
		(width 0.18288)
		(layer "In2.Cu")
		(net "M_F_CPU1_SB_CA<2>")
	)
	(segment
		(start 159.709104 -251.201682)
		(end 159.298386 -251.6124)
		(width 0.18288)
		(layer "In2.Cu")
		(net "M_F_CPU1_SB_CA<2>")
	)
	(segment
		(start 172.13834 -251.765562)
		(end 171.676314 -251.765562)
		(width 0.18288)
		(layer "In2.Cu")
		(net "M_F_CPU1_SB_CA<2>")
	)
	(segment
		(start 136.264396 -247.743472)
		(end 136.074912 -247.743472)
		(width 0.088646)
		(layer "In2.Cu")
		(net "M_F_CPU1_SB_CA<2>")
	)
	(segment
		(start 167.57142 -251.175266)
		(end 167.298116 -251.175266)
		(width 0.18288)
		(layer "In2.Cu")
		(net "M_F_CPU1_SB_CA<2>")
	)
	(segment
		(start 151.92375 -250.759976)
		(end 151.605742 -250.759976)
		(width 0.18288)
		(layer "In2.Cu")
		(net "M_F_CPU1_SB_CA<2>")
	)
	(segment
		(start 153.013918 -250.759976)
		(end 152.820878 -250.953016)
		(width 0.18288)
		(layer "In2.Cu")
		(net "M_F_CPU1_SB_CA<2>")
	)
	(arc
		(start 135.792464 -247.66778)
		(mid 135.605266 -247.617637)
		(end 135.418068 -247.66778)
		(width 0.088646)
		(layer "In2.Cu")
		(net "M_F_CPU1_SB_CA<2>")
	)
	(arc
		(start 134.382764 -246.853964)
		(mid 134.210409 -246.699786)
		(end 134.114286 -246.489474)
		(width 0.088646)
		(layer "In2.Cu")
		(net "M_F_CPU1_SB_CA<2>")
	)
	(arc
		(start 134.570216 -247.178322)
		(mid 134.522537 -246.995422)
		(end 134.391654 -246.859044)
		(width 0.088646)
		(layer "In2.Cu")
		(net "M_F_CPU1_SB_CA<2>")
	)
	(arc
		(start 136.074912 -247.743472)
		(mid 135.928699 -247.724231)
		(end 135.792464 -247.66778)
		(width 0.088646)
		(layer "In2.Cu")
		(net "M_F_CPU1_SB_CA<2>")
	)
	(arc
		(start 135.418068 -247.66778)
		(mid 135.135366 -247.743556)
		(end 134.852664 -247.66778)
		(width 0.088646)
		(layer "In2.Cu")
		(net "M_F_CPU1_SB_CA<2>")
	)
	(arc
		(start 134.852664 -247.66778)
		(mid 134.648329 -247.465175)
		(end 134.570216 -247.188228)
		(width 0.088646)
		(layer "In2.Cu")
		(net "M_F_CPU1_SB_CA<2>")
	)
	(arc
		(start 139.042648 -250.095004)
		(mid 138.924437 -250.071508)
		(end 138.824208 -250.00458)
		(width 0.18288)
		(layer "In2.Cu")
		(net "M_F_CPU1_SB_CA<2>")
	)
	(segment
		(start 180.072284 -252.152404)
		(end 180.423058 -252.152404)
		(width 0.20066)
		(layer "F.Cu")
		(net "M_F_CPU1_SB_CA<1>")
	)
	(segment
		(start 183.593994 -251.284232)
		(end 183.9976 -251.284232)
		(width 0.20066)
		(layer "F.Cu")
		(net "M_F_CPU1_SB_CA<1>")
	)
	(segment
		(start 130.076448 -255.825498)
		(end 130.076194 -255.825752)
		(width 0.20066)
		(layer "F.Cu")
		(net "M_F_CPU1_SB_CA<1>")
	)
	(segment
		(start 184.430162 -251.716794)
		(end 185.544714 -251.716794)
		(width 0.20066)
		(layer "F.Cu")
		(net "M_F_CPU1_SB_CA<1>")
	)
	(segment
		(start 180.427884 -252.152404)
		(end 180.438552 -252.141736)
		(width 0.1016)
		(layer "F.Cu")
		(net "M_F_CPU1_SB_CA<1>")
	)
	(segment
		(start 176.896014 -251.716794)
		(end 178.000914 -251.716794)
		(width 0.20066)
		(layer "F.Cu")
		(net "M_F_CPU1_SB_CA<1>")
	)
	(segment
		(start 180.423058 -252.152404)
		(end 180.427884 -252.152404)
		(width 0.101854)
		(layer "F.Cu")
		(net "M_F_CPU1_SB_CA<1>")
	)
	(segment
		(start 178.000914 -251.716794)
		(end 179.636674 -251.716794)
		(width 0.20066)
		(layer "F.Cu")
		(net "M_F_CPU1_SB_CA<1>")
	)
	(segment
		(start 180.438552 -252.141736)
		(end 182.447692 -252.141736)
		(width 0.1016)
		(layer "F.Cu")
		(net "M_F_CPU1_SB_CA<1>")
	)
	(segment
		(start 182.455058 -252.149102)
		(end 182.729124 -252.149102)
		(width 0.20066)
		(layer "F.Cu")
		(net "M_F_CPU1_SB_CA<1>")
	)
	(segment
		(start 130.076194 -255.825752)
		(end 130.076194 -256.361438)
		(width 0.20066)
		(layer "F.Cu")
		(net "M_F_CPU1_SB_CA<1>")
	)
	(segment
		(start 183.9976 -251.284232)
		(end 184.430162 -251.716794)
		(width 0.20066)
		(layer "F.Cu")
		(net "M_F_CPU1_SB_CA<1>")
	)
	(segment
		(start 179.636674 -251.716794)
		(end 180.072284 -252.152404)
		(width 0.20066)
		(layer "F.Cu")
		(net "M_F_CPU1_SB_CA<1>")
	)
	(segment
		(start 182.729124 -252.149102)
		(end 183.593994 -251.284232)
		(width 0.20066)
		(layer "F.Cu")
		(net "M_F_CPU1_SB_CA<1>")
	)
	(segment
		(start 182.447692 -252.141736)
		(end 182.455058 -252.149102)
		(width 0.1016)
		(layer "F.Cu")
		(net "M_F_CPU1_SB_CA<1>")
	)
	(segment
		(start 147.111974 -249.30227)
		(end 144.311878 -249.30227)
		(width 0.18288)
		(layer "In2.Cu")
		(net "M_F_CPU1_SB_CA<1>")
	)
	(segment
		(start 130.171698 -253.7333)
		(end 130.171698 -253.919736)
		(width 0.088646)
		(layer "In2.Cu")
		(net "M_F_CPU1_SB_CA<1>")
	)
	(segment
		(start 131.401312 -253.068074)
		(end 130.947922 -253.256034)
		(width 0.18288)
		(layer "In2.Cu")
		(net "M_F_CPU1_SB_CA<1>")
	)
	(segment
		(start 158.082742 -253.00813)
		(end 155.574492 -252.509274)
		(width 0.18288)
		(layer "In2.Cu")
		(net "M_F_CPU1_SB_CA<1>")
	)
	(segment
		(start 129.701798 -256.351532)
		(end 129.701798 -256.370074)
		(width 0.088646)
		(layer "In2.Cu")
		(net "M_F_CPU1_SB_CA<1>")
	)
	(segment
		(start 130.682746 -253.52121)
		(end 130.477514 -253.52121)
		(width 0.088646)
		(layer "In2.Cu")
		(net "M_F_CPU1_SB_CA<1>")
	)
	(segment
		(start 176.896014 -251.716794)
		(end 174.883064 -253.052072)
		(width 0.18288)
		(layer "In2.Cu")
		(net "M_F_CPU1_SB_CA<1>")
	)
	(segment
		(start 129.41935 -255.223264)
		(end 129.41046 -255.228344)
		(width 0.088646)
		(layer "In2.Cu")
		(net "M_F_CPU1_SB_CA<1>")
	)
	(segment
		(start 143.628872 -249.985276)
		(end 141.423644 -251.027946)
		(width 0.18288)
		(layer "In2.Cu")
		(net "M_F_CPU1_SB_CA<1>")
	)
	(segment
		(start 130.211576 -256.710434)
		(end 130.232658 -256.632456)
		(width 0.088646)
		(layer "In2.Cu")
		(net "M_F_CPU1_SB_CA<1>")
	)
	(segment
		(start 130.317494 -253.587504)
		(end 130.171698 -253.7333)
		(width 0.088646)
		(layer "In2.Cu")
		(net "M_F_CPU1_SB_CA<1>")
	)
	(segment
		(start 135.165592 -252.124718)
		(end 131.401312 -253.068074)
		(width 0.18288)
		(layer "In2.Cu")
		(net "M_F_CPU1_SB_CA<1>")
	)
	(segment
		(start 138.808206 -251.766324)
		(end 135.165592 -252.124718)
		(width 0.18288)
		(layer "In2.Cu")
		(net "M_F_CPU1_SB_CA<1>")
	)
	(segment
		(start 130.140202 -256.472182)
		(end 130.076194 -256.361438)
		(width 0.088646)
		(layer "In2.Cu")
		(net "M_F_CPU1_SB_CA<1>")
	)
	(segment
		(start 141.423644 -251.027946)
		(end 140.852144 -251.298202)
		(width 0.18288)
		(layer "In2.Cu")
		(net "M_F_CPU1_SB_CA<1>")
	)
	(segment
		(start 169.627804 -253.00813)
		(end 158.082742 -253.00813)
		(width 0.18288)
		(layer "In2.Cu")
		(net "M_F_CPU1_SB_CA<1>")
	)
	(segment
		(start 130.947922 -253.256034)
		(end 130.83413 -253.369826)
		(width 0.18288)
		(layer "In2.Cu")
		(net "M_F_CPU1_SB_CA<1>")
	)
	(segment
		(start 129.901188 -254.402082)
		(end 129.880106 -254.414274)
		(width 0.088646)
		(layer "In2.Cu")
		(net "M_F_CPU1_SB_CA<1>")
	)
	(segment
		(start 155.574492 -252.509274)
		(end 150.318978 -252.509274)
		(width 0.18288)
		(layer "In2.Cu")
		(net "M_F_CPU1_SB_CA<1>")
	)
	(segment
		(start 174.883064 -253.052072)
		(end 169.671746 -253.052072)
		(width 0.18288)
		(layer "In2.Cu")
		(net "M_F_CPU1_SB_CA<1>")
	)
	(segment
		(start 144.311878 -249.30227)
		(end 143.628872 -249.985276)
		(width 0.18288)
		(layer "In2.Cu")
		(net "M_F_CPU1_SB_CA<1>")
	)
	(segment
		(start 130.477514 -253.52121)
		(end 130.317494 -253.587504)
		(width 0.088646)
		(layer "In2.Cu")
		(net "M_F_CPU1_SB_CA<1>")
	)
	(segment
		(start 139.886944 -251.56541)
		(end 138.808206 -251.766324)
		(width 0.18288)
		(layer "In2.Cu")
		(net "M_F_CPU1_SB_CA<1>")
	)
	(segment
		(start 130.232658 -256.632456)
		(end 130.140202 -256.472182)
		(width 0.088646)
		(layer "In2.Cu")
		(net "M_F_CPU1_SB_CA<1>")
	)
	(segment
		(start 130.83413 -253.369826)
		(end 130.682746 -253.52121)
		(width 0.088646)
		(layer "In2.Cu")
		(net "M_F_CPU1_SB_CA<1>")
	)
	(segment
		(start 169.671746 -253.052072)
		(end 169.627804 -253.00813)
		(width 0.18288)
		(layer "In2.Cu")
		(net "M_F_CPU1_SB_CA<1>")
	)
	(segment
		(start 140.852144 -251.298202)
		(end 140.85189 -251.298202)
		(width 0.18288)
		(layer "In2.Cu")
		(net "M_F_CPU1_SB_CA<1>")
	)
	(segment
		(start 150.318978 -252.509274)
		(end 147.111974 -249.30227)
		(width 0.18288)
		(layer "In2.Cu")
		(net "M_F_CPU1_SB_CA<1>")
	)
	(segment
		(start 129.701544 -254.733552)
		(end 129.701544 -254.734314)
		(width 0.088646)
		(layer "In2.Cu")
		(net "M_F_CPU1_SB_CA<1>")
	)
	(segment
		(start 140.85189 -251.298202)
		(end 139.886944 -251.56541)
		(width 0.18288)
		(layer "In2.Cu")
		(net "M_F_CPU1_SB_CA<1>")
	)
	(segment
		(start 129.41046 -255.8669)
		(end 129.41935 -255.87198)
		(width 0.088646)
		(layer "In2.Cu")
		(net "M_F_CPU1_SB_CA<1>")
	)
	(arc
		(start 129.701798 -256.370074)
		(mid 129.754068 -256.552439)
		(end 129.888996 -256.685796)
		(width 0.088646)
		(layer "In2.Cu")
		(net "M_F_CPU1_SB_CA<1>")
	)
	(arc
		(start 129.880106 -254.414274)
		(mid 129.749192 -254.550634)
		(end 129.701544 -254.733552)
		(width 0.088646)
		(layer "In2.Cu")
		(net "M_F_CPU1_SB_CA<1>")
	)
	(arc
		(start 129.701544 -254.734314)
		(mid 129.625929 -255.016578)
		(end 129.41935 -255.223264)
		(width 0.088646)
		(layer "In2.Cu")
		(net "M_F_CPU1_SB_CA<1>")
	)
	(arc
		(start 129.41046 -255.228344)
		(mid 129.231863 -255.547622)
		(end 129.41046 -255.8669)
		(width 0.088646)
		(layer "In2.Cu")
		(net "M_F_CPU1_SB_CA<1>")
	)
	(arc
		(start 129.41935 -255.87198)
		(mid 129.623685 -256.074585)
		(end 129.701798 -256.351532)
		(width 0.088646)
		(layer "In2.Cu")
		(net "M_F_CPU1_SB_CA<1>")
	)
	(arc
		(start 129.888996 -256.685796)
		(mid 130.047484 -256.734729)
		(end 130.211576 -256.710434)
		(width 0.088646)
		(layer "In2.Cu")
		(net "M_F_CPU1_SB_CA<1>")
	)
	(arc
		(start 130.171698 -253.919736)
		(mid 130.099463 -254.19626)
		(end 129.901188 -254.402082)
		(width 0.088646)
		(layer "In2.Cu")
		(net "M_F_CPU1_SB_CA<1>")
	)
	(segment
		(start 130.546094 -256.639314)
		(end 130.546094 -257.175)
		(width 0.20066)
		(layer "F.Cu")
		(net "M_F_CPU1_SB_CA<0>")
	)
	(segment
		(start 178.052476 -253.185168)
		(end 178.60518 -253.737872)
		(width 0.20066)
		(layer "F.Cu")
		(net "M_F_CPU1_SB_CA<0>")
	)
	(segment
		(start 179.299362 -253.737872)
		(end 180.470556 -252.566678)
		(width 0.20066)
		(layer "F.Cu")
		(net "M_F_CPU1_SB_CA<0>")
	)
	(segment
		(start 176.683416 -253.185168)
		(end 178.052476 -253.185168)
		(width 0.20066)
		(layer "F.Cu")
		(net "M_F_CPU1_SB_CA<0>")
	)
	(segment
		(start 176.064926 -252.566678)
		(end 176.683416 -253.185168)
		(width 0.20066)
		(layer "F.Cu")
		(net "M_F_CPU1_SB_CA<0>")
	)
	(segment
		(start 178.60518 -253.737872)
		(end 179.299362 -253.737872)
		(width 0.20066)
		(layer "F.Cu")
		(net "M_F_CPU1_SB_CA<0>")
	)
	(segment
		(start 180.470556 -252.566678)
		(end 181.444646 -252.566678)
		(width 0.20066)
		(layer "F.Cu")
		(net "M_F_CPU1_SB_CA<0>")
	)
	(segment
		(start 173.900846 -252.566678)
		(end 176.064926 -252.566678)
		(width 0.20066)
		(layer "F.Cu")
		(net "M_F_CPU1_SB_CA<0>")
	)
	(segment
		(start 130.546094 -257.175)
		(end 130.546348 -257.175254)
		(width 0.20066)
		(layer "F.Cu")
		(net "M_F_CPU1_SB_CA<0>")
	)
	(segment
		(start 172.795946 -252.566678)
		(end 173.900846 -252.566678)
		(width 0.20066)
		(layer "F.Cu")
		(net "M_F_CPU1_SB_CA<0>")
	)
	(segment
		(start 129.980944 -253.416308)
		(end 129.980944 -253.919736)
		(width 0.088646)
		(layer "In2.Cu")
		(net "M_F_CPU1_SB_CA<0>")
	)
	(segment
		(start 136.18591 -251.266198)
		(end 134.684262 -251.414026)
		(width 0.18288)
		(layer "In2.Cu")
		(net "M_F_CPU1_SB_CA<0>")
	)
	(segment
		(start 147.504658 -248.95683)
		(end 143.68653 -248.95683)
		(width 0.18288)
		(layer "In2.Cu")
		(net "M_F_CPU1_SB_CA<0>")
	)
	(segment
		(start 156.88056 -251.926598)
		(end 150.474426 -251.926598)
		(width 0.18288)
		(layer "In2.Cu")
		(net "M_F_CPU1_SB_CA<0>")
	)
	(segment
		(start 139.524994 -250.937268)
		(end 136.18591 -251.266198)
		(width 0.18288)
		(layer "In2.Cu")
		(net "M_F_CPU1_SB_CA<0>")
	)
	(segment
		(start 130.389884 -256.904236)
		(end 130.546348 -257.175254)
		(width 0.088646)
		(layer "In2.Cu")
		(net "M_F_CPU1_SB_CA<0>")
	)
	(segment
		(start 129.511044 -256.352802)
		(end 129.511044 -256.361438)
		(width 0.088646)
		(layer "In2.Cu")
		(net "M_F_CPU1_SB_CA<0>")
	)
	(segment
		(start 165.46703 -252.14326)
		(end 165.13048 -252.47981)
		(width 0.18288)
		(layer "In2.Cu")
		(net "M_F_CPU1_SB_CA<0>")
	)
	(segment
		(start 129.332482 -255.05283)
		(end 129.323592 -255.05791)
		(width 0.088646)
		(layer "In2.Cu")
		(net "M_F_CPU1_SB_CA<0>")
	)
	(segment
		(start 163.945062 -252.47981)
		(end 163.641532 -252.17628)
		(width 0.18288)
		(layer "In2.Cu")
		(net "M_F_CPU1_SB_CA<0>")
	)
	(segment
		(start 167.408606 -252.14326)
		(end 165.46703 -252.14326)
		(width 0.18288)
		(layer "In2.Cu")
		(net "M_F_CPU1_SB_CA<0>")
	)
	(segment
		(start 133.78053 -251.414026)
		(end 130.712464 -252.684788)
		(width 0.18288)
		(layer "In2.Cu")
		(net "M_F_CPU1_SB_CA<0>")
	)
	(segment
		(start 167.565324 -252.299978)
		(end 167.408606 -252.14326)
		(width 0.18288)
		(layer "In2.Cu")
		(net "M_F_CPU1_SB_CA<0>")
	)
	(segment
		(start 163.641532 -252.17628)
		(end 157.130242 -252.17628)
		(width 0.18288)
		(layer "In2.Cu")
		(net "M_F_CPU1_SB_CA<0>")
	)
	(segment
		(start 130.712464 -252.684788)
		(end 130.430778 -252.966474)
		(width 0.18288)
		(layer "In2.Cu")
		(net "M_F_CPU1_SB_CA<0>")
	)
	(segment
		(start 134.684262 -251.414026)
		(end 133.78053 -251.414026)
		(width 0.18288)
		(layer "In2.Cu")
		(net "M_F_CPU1_SB_CA<0>")
	)
	(segment
		(start 140.592556 -250.724924)
		(end 139.524994 -250.937268)
		(width 0.18288)
		(layer "In2.Cu")
		(net "M_F_CPU1_SB_CA<0>")
	)
	(segment
		(start 130.430778 -252.966474)
		(end 129.980944 -253.416308)
		(width 0.088646)
		(layer "In2.Cu")
		(net "M_F_CPU1_SB_CA<0>")
	)
	(segment
		(start 129.793746 -256.850896)
		(end 129.808478 -256.859532)
		(width 0.088646)
		(layer "In2.Cu")
		(net "M_F_CPU1_SB_CA<0>")
	)
	(segment
		(start 129.78765 -256.84734)
		(end 129.793746 -256.850896)
		(width 0.088646)
		(layer "In2.Cu")
		(net "M_F_CPU1_SB_CA<0>")
	)
	(segment
		(start 142.856458 -249.786902)
		(end 142.529052 -249.922538)
		(width 0.18288)
		(layer "In2.Cu")
		(net "M_F_CPU1_SB_CA<0>")
	)
	(segment
		(start 130.30073 -256.88036)
		(end 130.389884 -256.904236)
		(width 0.088646)
		(layer "In2.Cu")
		(net "M_F_CPU1_SB_CA<0>")
	)
	(segment
		(start 129.041398 -255.525524)
		(end 129.041398 -255.557528)
		(width 0.088646)
		(layer "In2.Cu")
		(net "M_F_CPU1_SB_CA<0>")
	)
	(segment
		(start 157.130242 -252.17628)
		(end 156.88056 -251.926598)
		(width 0.18288)
		(layer "In2.Cu")
		(net "M_F_CPU1_SB_CA<0>")
	)
	(segment
		(start 172.795946 -252.566678)
		(end 172.529246 -252.299978)
		(width 0.18288)
		(layer "In2.Cu")
		(net "M_F_CPU1_SB_CA<0>")
	)
	(segment
		(start 165.13048 -252.47981)
		(end 163.945062 -252.47981)
		(width 0.18288)
		(layer "In2.Cu")
		(net "M_F_CPU1_SB_CA<0>")
	)
	(segment
		(start 129.511044 -254.723646)
		(end 129.511044 -254.733552)
		(width 0.088646)
		(layer "In2.Cu")
		(net "M_F_CPU1_SB_CA<0>")
	)
	(segment
		(start 129.802382 -254.239014)
		(end 129.793492 -254.244094)
		(width 0.088646)
		(layer "In2.Cu")
		(net "M_F_CPU1_SB_CA<0>")
	)
	(segment
		(start 150.474426 -251.926598)
		(end 147.504658 -248.95683)
		(width 0.18288)
		(layer "In2.Cu")
		(net "M_F_CPU1_SB_CA<0>")
	)
	(segment
		(start 172.529246 -252.299978)
		(end 167.565324 -252.299978)
		(width 0.18288)
		(layer "In2.Cu")
		(net "M_F_CPU1_SB_CA<0>")
	)
	(segment
		(start 142.529052 -249.922538)
		(end 140.592556 -250.724924)
		(width 0.18288)
		(layer "In2.Cu")
		(net "M_F_CPU1_SB_CA<0>")
	)
	(segment
		(start 143.68653 -248.95683)
		(end 142.856458 -249.786902)
		(width 0.18288)
		(layer "In2.Cu")
		(net "M_F_CPU1_SB_CA<0>")
	)
	(arc
		(start 129.323846 -256.03708)
		(mid 129.458779 -256.170434)
		(end 129.511044 -256.352802)
		(width 0.088646)
		(layer "In2.Cu")
		(net "M_F_CPU1_SB_CA<0>")
	)
	(arc
		(start 129.793492 -254.244094)
		(mid 129.589157 -254.446699)
		(end 129.511044 -254.723646)
		(width 0.088646)
		(layer "In2.Cu")
		(net "M_F_CPU1_SB_CA<0>")
	)
	(arc
		(start 129.980944 -253.919736)
		(mid 129.933265 -254.102636)
		(end 129.802382 -254.239014)
		(width 0.088646)
		(layer "In2.Cu")
		(net "M_F_CPU1_SB_CA<0>")
	)
	(arc
		(start 129.808478 -256.859532)
		(mid 130.052222 -256.926411)
		(end 130.30073 -256.88036)
		(width 0.088646)
		(layer "In2.Cu")
		(net "M_F_CPU1_SB_CA<0>")
	)
	(arc
		(start 129.511044 -254.733552)
		(mid 129.463365 -254.916452)
		(end 129.332482 -255.05283)
		(width 0.088646)
		(layer "In2.Cu")
		(net "M_F_CPU1_SB_CA<0>")
	)
	(arc
		(start 129.323592 -255.05791)
		(mid 129.12231 -255.255397)
		(end 129.041398 -255.525524)
		(width 0.088646)
		(layer "In2.Cu")
		(net "M_F_CPU1_SB_CA<0>")
	)
	(arc
		(start 129.041398 -255.557528)
		(mid 129.119509 -255.834477)
		(end 129.323846 -256.03708)
		(width 0.088646)
		(layer "In2.Cu")
		(net "M_F_CPU1_SB_CA<0>")
	)
	(arc
		(start 129.511044 -256.361438)
		(mid 129.585035 -256.641004)
		(end 129.78765 -256.84734)
		(width 0.088646)
		(layer "In2.Cu")
		(net "M_F_CPU1_SB_CA<0>")
	)
	(segment
		(start 128.666494 -253.383796)
		(end 128.666494 -253.919736)
		(width 0.20066)
		(layer "F.Cu")
		(net "M_F_CPU1_SA_RSP<1>")
	)
	(segment
		(start 172.795946 -244.066568)
		(end 173.900846 -244.066568)
		(width 0.20066)
		(layer "F.Cu")
		(net "M_F_CPU1_SA_RSP<1>")
	)
	(segment
		(start 171.739306 -244.578886)
		(end 170.410886 -244.578886)
		(width 0.18288)
		(layer "In6.Cu")
		(net "M_F_CPU1_SA_RSP<1>")
	)
	(segment
		(start 152.037542 -248.428002)
		(end 151.709882 -248.428002)
		(width 0.18288)
		(layer "In6.Cu")
		(net "M_F_CPU1_SA_RSP<1>")
	)
	(segment
		(start 150.140162 -248.880122)
		(end 149.957282 -249.063002)
		(width 0.18288)
		(layer "In6.Cu")
		(net "M_F_CPU1_SA_RSP<1>")
	)
	(segment
		(start 153.607262 -248.610882)
		(end 153.424382 -248.428002)
		(width 0.18288)
		(layer "In6.Cu")
		(net "M_F_CPU1_SA_RSP<1>")
	)
	(segment
		(start 163.26358 -247.159526)
		(end 163.26358 -247.468644)
		(width 0.18288)
		(layer "In6.Cu")
		(net "M_F_CPU1_SA_RSP<1>")
	)
	(segment
		(start 154.483562 -248.428002)
		(end 154.300682 -248.610882)
		(width 0.18288)
		(layer "In6.Cu")
		(net "M_F_CPU1_SA_RSP<1>")
	)
	(segment
		(start 154.117802 -249.063002)
		(end 153.790142 -249.063002)
		(width 0.18288)
		(layer "In6.Cu")
		(net "M_F_CPU1_SA_RSP<1>")
	)
	(segment
		(start 166.735252 -246.384572)
		(end 166.552372 -246.201692)
		(width 0.18288)
		(layer "In6.Cu")
		(net "M_F_CPU1_SA_RSP<1>")
	)
	(segment
		(start 162.38728 -246.976646)
		(end 160.994598 -246.976646)
		(width 0.18288)
		(layer "In6.Cu")
		(net "M_F_CPU1_SA_RSP<1>")
	)
	(segment
		(start 151.016462 -249.063002)
		(end 150.833582 -248.880122)
		(width 0.18288)
		(layer "In6.Cu")
		(net "M_F_CPU1_SA_RSP<1>")
	)
	(segment
		(start 150.650702 -248.428002)
		(end 150.323042 -248.428002)
		(width 0.18288)
		(layer "In6.Cu")
		(net "M_F_CPU1_SA_RSP<1>")
	)
	(segment
		(start 168.424352 -245.387114)
		(end 167.428672 -245.387114)
		(width 0.18288)
		(layer "In6.Cu")
		(net "M_F_CPU1_SA_RSP<1>")
	)
	(segment
		(start 159.413448 -247.660414)
		(end 159.230568 -247.843294)
		(width 0.18288)
		(layer "In6.Cu")
		(net "M_F_CPU1_SA_RSP<1>")
	)
	(segment
		(start 154.300682 -248.610882)
		(end 154.300682 -248.880122)
		(width 0.18288)
		(layer "In6.Cu")
		(net "M_F_CPU1_SA_RSP<1>")
	)
	(segment
		(start 155.140406 -248.431812)
		(end 154.793442 -248.431812)
		(width 0.18288)
		(layer "In6.Cu")
		(net "M_F_CPU1_SA_RSP<1>")
	)
	(segment
		(start 149.446742 -248.880122)
		(end 149.446742 -248.610882)
		(width 0.18288)
		(layer "In6.Cu")
		(net "M_F_CPU1_SA_RSP<1>")
	)
	(segment
		(start 128.601724 -253.854966)
		(end 128.666494 -253.919736)
		(width 0.18288)
		(layer "In6.Cu")
		(net "M_F_CPU1_SA_RSP<1>")
	)
	(segment
		(start 158.537148 -248.222516)
		(end 158.537148 -247.843294)
		(width 0.18288)
		(layer "In6.Cu")
		(net "M_F_CPU1_SA_RSP<1>")
	)
	(segment
		(start 170.410886 -244.578886)
		(end 169.949114 -245.040658)
		(width 0.18288)
		(layer "In6.Cu")
		(net "M_F_CPU1_SA_RSP<1>")
	)
	(segment
		(start 130.066796 -250.872244)
		(end 128.601724 -252.337316)
		(width 0.18288)
		(layer "In6.Cu")
		(net "M_F_CPU1_SA_RSP<1>")
	)
	(segment
		(start 154.300682 -248.880122)
		(end 154.117802 -249.063002)
		(width 0.18288)
		(layer "In6.Cu")
		(net "M_F_CPU1_SA_RSP<1>")
	)
	(segment
		(start 167.245792 -245.569994)
		(end 167.245792 -246.201692)
		(width 0.18288)
		(layer "In6.Cu")
		(net "M_F_CPU1_SA_RSP<1>")
	)
	(segment
		(start 150.833582 -248.880122)
		(end 150.833582 -248.610882)
		(width 0.18288)
		(layer "In6.Cu")
		(net "M_F_CPU1_SA_RSP<1>")
	)
	(segment
		(start 160.31083 -247.660414)
		(end 159.413448 -247.660414)
		(width 0.18288)
		(layer "In6.Cu")
		(net "M_F_CPU1_SA_RSP<1>")
	)
	(segment
		(start 153.096722 -248.428002)
		(end 152.913842 -248.610882)
		(width 0.18288)
		(layer "In6.Cu")
		(net "M_F_CPU1_SA_RSP<1>")
	)
	(segment
		(start 166.552372 -246.201692)
		(end 166.552372 -245.569994)
		(width 0.18288)
		(layer "In6.Cu")
		(net "M_F_CPU1_SA_RSP<1>")
	)
	(segment
		(start 151.527002 -248.880122)
		(end 151.344122 -249.063002)
		(width 0.18288)
		(layer "In6.Cu")
		(net "M_F_CPU1_SA_RSP<1>")
	)
	(segment
		(start 153.790142 -249.063002)
		(end 153.607262 -248.880122)
		(width 0.18288)
		(layer "In6.Cu")
		(net "M_F_CPU1_SA_RSP<1>")
	)
	(segment
		(start 163.0807 -247.651524)
		(end 162.75304 -247.651524)
		(width 0.18288)
		(layer "In6.Cu")
		(net "M_F_CPU1_SA_RSP<1>")
	)
	(segment
		(start 169.949114 -245.040658)
		(end 168.770808 -245.040658)
		(width 0.18288)
		(layer "In6.Cu")
		(net "M_F_CPU1_SA_RSP<1>")
	)
	(segment
		(start 159.230568 -248.222516)
		(end 159.047688 -248.405396)
		(width 0.18288)
		(layer "In6.Cu")
		(net "M_F_CPU1_SA_RSP<1>")
	)
	(segment
		(start 165.490398 -246.036846)
		(end 165.137846 -246.036846)
		(width 0.18288)
		(layer "In6.Cu")
		(net "M_F_CPU1_SA_RSP<1>")
	)
	(segment
		(start 157.271466 -248.11101)
		(end 155.461208 -248.11101)
		(width 0.18288)
		(layer "In6.Cu")
		(net "M_F_CPU1_SA_RSP<1>")
	)
	(segment
		(start 150.833582 -248.610882)
		(end 150.650702 -248.428002)
		(width 0.18288)
		(layer "In6.Cu")
		(net "M_F_CPU1_SA_RSP<1>")
	)
	(segment
		(start 154.789632 -248.428002)
		(end 154.483562 -248.428002)
		(width 0.18288)
		(layer "In6.Cu")
		(net "M_F_CPU1_SA_RSP<1>")
	)
	(segment
		(start 158.537148 -247.843294)
		(end 158.354268 -247.660414)
		(width 0.18288)
		(layer "In6.Cu")
		(net "M_F_CPU1_SA_RSP<1>")
	)
	(segment
		(start 149.957282 -249.063002)
		(end 149.629622 -249.063002)
		(width 0.18288)
		(layer "In6.Cu")
		(net "M_F_CPU1_SA_RSP<1>")
	)
	(segment
		(start 152.220422 -248.610882)
		(end 152.037542 -248.428002)
		(width 0.18288)
		(layer "In6.Cu")
		(net "M_F_CPU1_SA_RSP<1>")
	)
	(segment
		(start 166.14013 -245.387114)
		(end 165.490398 -246.036846)
		(width 0.18288)
		(layer "In6.Cu")
		(net "M_F_CPU1_SA_RSP<1>")
	)
	(segment
		(start 153.607262 -248.880122)
		(end 153.607262 -248.610882)
		(width 0.18288)
		(layer "In6.Cu")
		(net "M_F_CPU1_SA_RSP<1>")
	)
	(segment
		(start 152.913842 -248.880122)
		(end 152.730962 -249.063002)
		(width 0.18288)
		(layer "In6.Cu")
		(net "M_F_CPU1_SA_RSP<1>")
	)
	(segment
		(start 168.770808 -245.040658)
		(end 168.424352 -245.387114)
		(width 0.18288)
		(layer "In6.Cu")
		(net "M_F_CPU1_SA_RSP<1>")
	)
	(segment
		(start 151.344122 -249.063002)
		(end 151.016462 -249.063002)
		(width 0.18288)
		(layer "In6.Cu")
		(net "M_F_CPU1_SA_RSP<1>")
	)
	(segment
		(start 167.428672 -245.387114)
		(end 167.245792 -245.569994)
		(width 0.18288)
		(layer "In6.Cu")
		(net "M_F_CPU1_SA_RSP<1>")
	)
	(segment
		(start 143.975328 -248.428002)
		(end 141.531086 -250.872244)
		(width 0.18288)
		(layer "In6.Cu")
		(net "M_F_CPU1_SA_RSP<1>")
	)
	(segment
		(start 152.220422 -248.880122)
		(end 152.220422 -248.610882)
		(width 0.18288)
		(layer "In6.Cu")
		(net "M_F_CPU1_SA_RSP<1>")
	)
	(segment
		(start 128.601724 -252.337316)
		(end 128.601724 -253.854966)
		(width 0.18288)
		(layer "In6.Cu")
		(net "M_F_CPU1_SA_RSP<1>")
	)
	(segment
		(start 152.403302 -249.063002)
		(end 152.220422 -248.880122)
		(width 0.18288)
		(layer "In6.Cu")
		(net "M_F_CPU1_SA_RSP<1>")
	)
	(segment
		(start 155.461208 -248.11101)
		(end 155.140406 -248.431812)
		(width 0.18288)
		(layer "In6.Cu")
		(net "M_F_CPU1_SA_RSP<1>")
	)
	(segment
		(start 172.795946 -244.066568)
		(end 172.251624 -244.066568)
		(width 0.18288)
		(layer "In6.Cu")
		(net "M_F_CPU1_SA_RSP<1>")
	)
	(segment
		(start 151.527002 -248.610882)
		(end 151.527002 -248.880122)
		(width 0.18288)
		(layer "In6.Cu")
		(net "M_F_CPU1_SA_RSP<1>")
	)
	(segment
		(start 162.57016 -247.468644)
		(end 162.57016 -247.159526)
		(width 0.18288)
		(layer "In6.Cu")
		(net "M_F_CPU1_SA_RSP<1>")
	)
	(segment
		(start 167.062912 -246.384572)
		(end 166.735252 -246.384572)
		(width 0.18288)
		(layer "In6.Cu")
		(net "M_F_CPU1_SA_RSP<1>")
	)
	(segment
		(start 166.369492 -245.387114)
		(end 166.14013 -245.387114)
		(width 0.18288)
		(layer "In6.Cu")
		(net "M_F_CPU1_SA_RSP<1>")
	)
	(segment
		(start 163.26358 -247.468644)
		(end 163.0807 -247.651524)
		(width 0.18288)
		(layer "In6.Cu")
		(net "M_F_CPU1_SA_RSP<1>")
	)
	(segment
		(start 149.629622 -249.063002)
		(end 149.446742 -248.880122)
		(width 0.18288)
		(layer "In6.Cu")
		(net "M_F_CPU1_SA_RSP<1>")
	)
	(segment
		(start 162.57016 -247.159526)
		(end 162.38728 -246.976646)
		(width 0.18288)
		(layer "In6.Cu")
		(net "M_F_CPU1_SA_RSP<1>")
	)
	(segment
		(start 154.793442 -248.431812)
		(end 154.789632 -248.428002)
		(width 0.18288)
		(layer "In6.Cu")
		(net "M_F_CPU1_SA_RSP<1>")
	)
	(segment
		(start 172.251624 -244.066568)
		(end 171.739306 -244.578886)
		(width 0.18288)
		(layer "In6.Cu")
		(net "M_F_CPU1_SA_RSP<1>")
	)
	(segment
		(start 151.709882 -248.428002)
		(end 151.527002 -248.610882)
		(width 0.18288)
		(layer "In6.Cu")
		(net "M_F_CPU1_SA_RSP<1>")
	)
	(segment
		(start 158.720028 -248.405396)
		(end 158.537148 -248.222516)
		(width 0.18288)
		(layer "In6.Cu")
		(net "M_F_CPU1_SA_RSP<1>")
	)
	(segment
		(start 149.263862 -248.428002)
		(end 143.975328 -248.428002)
		(width 0.18288)
		(layer "In6.Cu")
		(net "M_F_CPU1_SA_RSP<1>")
	)
	(segment
		(start 159.230568 -247.843294)
		(end 159.230568 -248.222516)
		(width 0.18288)
		(layer "In6.Cu")
		(net "M_F_CPU1_SA_RSP<1>")
	)
	(segment
		(start 141.531086 -250.872244)
		(end 130.066796 -250.872244)
		(width 0.18288)
		(layer "In6.Cu")
		(net "M_F_CPU1_SA_RSP<1>")
	)
	(segment
		(start 159.047688 -248.405396)
		(end 158.720028 -248.405396)
		(width 0.18288)
		(layer "In6.Cu")
		(net "M_F_CPU1_SA_RSP<1>")
	)
	(segment
		(start 166.552372 -245.569994)
		(end 166.369492 -245.387114)
		(width 0.18288)
		(layer "In6.Cu")
		(net "M_F_CPU1_SA_RSP<1>")
	)
	(segment
		(start 150.323042 -248.428002)
		(end 150.140162 -248.610882)
		(width 0.18288)
		(layer "In6.Cu")
		(net "M_F_CPU1_SA_RSP<1>")
	)
	(segment
		(start 160.994598 -246.976646)
		(end 160.31083 -247.660414)
		(width 0.18288)
		(layer "In6.Cu")
		(net "M_F_CPU1_SA_RSP<1>")
	)
	(segment
		(start 163.44646 -246.976646)
		(end 163.26358 -247.159526)
		(width 0.18288)
		(layer "In6.Cu")
		(net "M_F_CPU1_SA_RSP<1>")
	)
	(segment
		(start 150.140162 -248.610882)
		(end 150.140162 -248.880122)
		(width 0.18288)
		(layer "In6.Cu")
		(net "M_F_CPU1_SA_RSP<1>")
	)
	(segment
		(start 157.722062 -247.660414)
		(end 157.271466 -248.11101)
		(width 0.18288)
		(layer "In6.Cu")
		(net "M_F_CPU1_SA_RSP<1>")
	)
	(segment
		(start 165.137846 -246.036846)
		(end 164.198046 -246.976646)
		(width 0.18288)
		(layer "In6.Cu")
		(net "M_F_CPU1_SA_RSP<1>")
	)
	(segment
		(start 167.245792 -246.201692)
		(end 167.062912 -246.384572)
		(width 0.18288)
		(layer "In6.Cu")
		(net "M_F_CPU1_SA_RSP<1>")
	)
	(segment
		(start 153.424382 -248.428002)
		(end 153.096722 -248.428002)
		(width 0.18288)
		(layer "In6.Cu")
		(net "M_F_CPU1_SA_RSP<1>")
	)
	(segment
		(start 162.75304 -247.651524)
		(end 162.57016 -247.468644)
		(width 0.18288)
		(layer "In6.Cu")
		(net "M_F_CPU1_SA_RSP<1>")
	)
	(segment
		(start 152.913842 -248.610882)
		(end 152.913842 -248.880122)
		(width 0.18288)
		(layer "In6.Cu")
		(net "M_F_CPU1_SA_RSP<1>")
	)
	(segment
		(start 158.354268 -247.660414)
		(end 157.722062 -247.660414)
		(width 0.18288)
		(layer "In6.Cu")
		(net "M_F_CPU1_SA_RSP<1>")
	)
	(segment
		(start 149.446742 -248.610882)
		(end 149.263862 -248.428002)
		(width 0.18288)
		(layer "In6.Cu")
		(net "M_F_CPU1_SA_RSP<1>")
	)
	(segment
		(start 152.730962 -249.063002)
		(end 152.403302 -249.063002)
		(width 0.18288)
		(layer "In6.Cu")
		(net "M_F_CPU1_SA_RSP<1>")
	)
	(segment
		(start 164.198046 -246.976646)
		(end 163.44646 -246.976646)
		(width 0.18288)
		(layer "In6.Cu")
		(net "M_F_CPU1_SA_RSP<1>")
	)
	(segment
		(start 181.444646 -244.066568)
		(end 180.314346 -244.066568)
		(width 0.20066)
		(layer "F.Cu")
		(net "M_F_CPU1_SA_RSP<0>")
	)
	(segment
		(start 128.196848 -254.733298)
		(end 128.196594 -254.733552)
		(width 0.20066)
		(layer "F.Cu")
		(net "M_F_CPU1_SA_RSP<0>")
	)
	(segment
		(start 128.196848 -254.197612)
		(end 128.196848 -254.733298)
		(width 0.20066)
		(layer "F.Cu")
		(net "M_F_CPU1_SA_RSP<0>")
	)
	(segment
		(start 178.737006 -244.627146)
		(end 178.021742 -245.34241)
		(width 0.18288)
		(layer "In6.Cu")
		(net "M_F_CPU1_SA_RSP<0>")
	)
	(segment
		(start 129.231898 -253.746762)
		(end 129.231898 -253.919736)
		(width 0.088646)
		(layer "In6.Cu")
		(net "M_F_CPU1_SA_RSP<0>")
	)
	(segment
		(start 163.547298 -248.820432)
		(end 162.417252 -248.820432)
		(width 0.18288)
		(layer "In6.Cu")
		(net "M_F_CPU1_SA_RSP<0>")
	)
	(segment
		(start 167.741346 -247.789954)
		(end 165.078918 -247.789954)
		(width 0.18288)
		(layer "In6.Cu")
		(net "M_F_CPU1_SA_RSP<0>")
	)
	(segment
		(start 171.884086 -246.392446)
		(end 170.448986 -246.392446)
		(width 0.18288)
		(layer "In6.Cu")
		(net "M_F_CPU1_SA_RSP<0>")
	)
	(segment
		(start 165.078918 -247.789954)
		(end 164.199062 -248.66981)
		(width 0.18288)
		(layer "In6.Cu")
		(net "M_F_CPU1_SA_RSP<0>")
	)
	(segment
		(start 155.429966 -250.072906)
		(end 148.722842 -250.072906)
		(width 0.18288)
		(layer "In6.Cu")
		(net "M_F_CPU1_SA_RSP<0>")
	)
	(segment
		(start 156.053028 -249.449844)
		(end 155.429966 -250.072906)
		(width 0.18288)
		(layer "In6.Cu")
		(net "M_F_CPU1_SA_RSP<0>")
	)
	(segment
		(start 129.566924 -253.2126)
		(end 129.566924 -253.411736)
		(width 0.088646)
		(layer "In6.Cu")
		(net "M_F_CPU1_SA_RSP<0>")
	)
	(segment
		(start 160.321244 -249.449844)
		(end 156.053028 -249.449844)
		(width 0.18288)
		(layer "In6.Cu")
		(net "M_F_CPU1_SA_RSP<0>")
	)
	(segment
		(start 162.244786 -248.647966)
		(end 161.123122 -248.647966)
		(width 0.18288)
		(layer "In6.Cu")
		(net "M_F_CPU1_SA_RSP<0>")
	)
	(segment
		(start 174.478442 -245.34241)
		(end 173.628558 -246.192294)
		(width 0.18288)
		(layer "In6.Cu")
		(net "M_F_CPU1_SA_RSP<0>")
	)
	(segment
		(start 178.021742 -245.34241)
		(end 174.478442 -245.34241)
		(width 0.18288)
		(layer "In6.Cu")
		(net "M_F_CPU1_SA_RSP<0>")
	)
	(segment
		(start 147.919186 -249.26925)
		(end 144.878044 -249.26925)
		(width 0.18288)
		(layer "In6.Cu")
		(net "M_F_CPU1_SA_RSP<0>")
	)
	(segment
		(start 129.566924 -252.477016)
		(end 129.566924 -253.2126)
		(width 0.18288)
		(layer "In6.Cu")
		(net "M_F_CPU1_SA_RSP<0>")
	)
	(segment
		(start 142.60449 -251.542804)
		(end 130.501136 -251.542804)
		(width 0.18288)
		(layer "In6.Cu")
		(net "M_F_CPU1_SA_RSP<0>")
	)
	(segment
		(start 144.878044 -249.26925)
		(end 142.60449 -251.542804)
		(width 0.18288)
		(layer "In6.Cu")
		(net "M_F_CPU1_SA_RSP<0>")
	)
	(segment
		(start 173.628558 -246.192294)
		(end 172.084238 -246.192294)
		(width 0.18288)
		(layer "In6.Cu")
		(net "M_F_CPU1_SA_RSP<0>")
	)
	(segment
		(start 161.123122 -248.647966)
		(end 160.321244 -249.449844)
		(width 0.18288)
		(layer "In6.Cu")
		(net "M_F_CPU1_SA_RSP<0>")
	)
	(segment
		(start 129.566924 -253.411736)
		(end 129.231898 -253.746762)
		(width 0.088646)
		(layer "In6.Cu")
		(net "M_F_CPU1_SA_RSP<0>")
	)
	(segment
		(start 164.199062 -248.66981)
		(end 163.69792 -248.66981)
		(width 0.18288)
		(layer "In6.Cu")
		(net "M_F_CPU1_SA_RSP<0>")
	)
	(segment
		(start 179.753768 -244.627146)
		(end 178.737006 -244.627146)
		(width 0.18288)
		(layer "In6.Cu")
		(net "M_F_CPU1_SA_RSP<0>")
	)
	(segment
		(start 162.417252 -248.820432)
		(end 162.244786 -248.647966)
		(width 0.18288)
		(layer "In6.Cu")
		(net "M_F_CPU1_SA_RSP<0>")
	)
	(segment
		(start 128.955292 -254.405638)
		(end 128.562862 -254.634492)
		(width 0.088646)
		(layer "In6.Cu")
		(net "M_F_CPU1_SA_RSP<0>")
	)
	(segment
		(start 180.314346 -244.066568)
		(end 179.753768 -244.627146)
		(width 0.18288)
		(layer "In6.Cu")
		(net "M_F_CPU1_SA_RSP<0>")
	)
	(segment
		(start 168.637966 -246.893334)
		(end 167.741346 -247.789954)
		(width 0.18288)
		(layer "In6.Cu")
		(net "M_F_CPU1_SA_RSP<0>")
	)
	(segment
		(start 169.948098 -246.893334)
		(end 168.637966 -246.893334)
		(width 0.18288)
		(layer "In6.Cu")
		(net "M_F_CPU1_SA_RSP<0>")
	)
	(segment
		(start 148.722842 -250.072906)
		(end 147.919186 -249.26925)
		(width 0.18288)
		(layer "In6.Cu")
		(net "M_F_CPU1_SA_RSP<0>")
	)
	(segment
		(start 130.501136 -251.542804)
		(end 129.566924 -252.477016)
		(width 0.18288)
		(layer "In6.Cu")
		(net "M_F_CPU1_SA_RSP<0>")
	)
	(segment
		(start 163.69792 -248.66981)
		(end 163.547298 -248.820432)
		(width 0.18288)
		(layer "In6.Cu")
		(net "M_F_CPU1_SA_RSP<0>")
	)
	(segment
		(start 170.448986 -246.392446)
		(end 169.948098 -246.893334)
		(width 0.18288)
		(layer "In6.Cu")
		(net "M_F_CPU1_SA_RSP<0>")
	)
	(segment
		(start 172.084238 -246.192294)
		(end 171.884086 -246.392446)
		(width 0.18288)
		(layer "In6.Cu")
		(net "M_F_CPU1_SA_RSP<0>")
	)
	(arc
		(start 129.231898 -253.919736)
		(mid 129.157907 -254.199302)
		(end 128.955292 -254.405638)
		(width 0.088646)
		(layer "In6.Cu")
		(net "M_F_CPU1_SA_RSP<0>")
	)
	(arc
		(start 128.562862 -254.634492)
		(mid 128.386302 -254.708321)
		(end 128.196594 -254.733552)
		(width 0.088646)
		(layer "In6.Cu")
		(net "M_F_CPU1_SA_RSP<0>")
	)
	(segment
		(start 178.99888 -258.941824)
		(end 179.011326 -258.95427)
		(width 0.1016)
		(layer "F.Cu")
		(net "M_F_CPU1_SA_PAR")
	)
	(segment
		(start 176.524666 -258.941824)
		(end 176.803558 -258.941824)
		(width 0.20066)
		(layer "F.Cu")
		(net "M_F_CPU1_SA_PAR")
	)
	(segment
		(start 176.803558 -258.941824)
		(end 176.823878 -258.941824)
		(width 0.101854)
		(layer "F.Cu")
		(net "M_F_CPU1_SA_PAR")
	)
	(segment
		(start 174.788576 -259.366766)
		(end 175.680878 -258.474464)
		(width 0.20066)
		(layer "F.Cu")
		(net "M_F_CPU1_SA_PAR")
	)
	(segment
		(start 176.057306 -258.474464)
		(end 176.524666 -258.941824)
		(width 0.20066)
		(layer "F.Cu")
		(net "M_F_CPU1_SA_PAR")
	)
	(segment
		(start 179.011326 -258.95427)
		(end 179.565808 -258.95427)
		(width 0.20066)
		(layer "F.Cu")
		(net "M_F_CPU1_SA_PAR")
	)
	(segment
		(start 173.900846 -259.366766)
		(end 174.788576 -259.366766)
		(width 0.20066)
		(layer "F.Cu")
		(net "M_F_CPU1_SA_PAR")
	)
	(segment
		(start 172.795946 -259.366766)
		(end 173.900846 -259.366766)
		(width 0.20066)
		(layer "F.Cu")
		(net "M_F_CPU1_SA_PAR")
	)
	(segment
		(start 179.565808 -258.95427)
		(end 179.978304 -259.366766)
		(width 0.20066)
		(layer "F.Cu")
		(net "M_F_CPU1_SA_PAR")
	)
	(segment
		(start 176.823878 -258.941824)
		(end 178.99888 -258.941824)
		(width 0.1016)
		(layer "F.Cu")
		(net "M_F_CPU1_SA_PAR")
	)
	(segment
		(start 175.680878 -258.474464)
		(end 176.057306 -258.474464)
		(width 0.20066)
		(layer "F.Cu")
		(net "M_F_CPU1_SA_PAR")
	)
	(segment
		(start 179.978304 -259.366766)
		(end 181.444646 -259.366766)
		(width 0.20066)
		(layer "F.Cu")
		(net "M_F_CPU1_SA_PAR")
	)
	(segment
		(start 131.956048 -256.361184)
		(end 131.955794 -256.361438)
		(width 0.20066)
		(layer "F.Cu")
		(net "M_F_CPU1_SA_PAR")
	)
	(segment
		(start 131.956048 -255.825498)
		(end 131.956048 -256.361184)
		(width 0.20066)
		(layer "F.Cu")
		(net "M_F_CPU1_SA_PAR")
	)
	(segment
		(start 147.462748 -255.585722)
		(end 143.942054 -255.585722)
		(width 0.18288)
		(layer "In2.Cu")
		(net "M_F_CPU1_SA_PAR")
	)
	(segment
		(start 133.561582 -255.8669)
		(end 133.552692 -255.87198)
		(width 0.088646)
		(layer "In2.Cu")
		(net "M_F_CPU1_SA_PAR")
	)
	(segment
		(start 174.96028 -259.132324)
		(end 174.501048 -258.673092)
		(width 0.18288)
		(layer "In2.Cu")
		(net "M_F_CPU1_SA_PAR")
	)
	(segment
		(start 131.799584 -256.632456)
		(end 131.89204 -256.472182)
		(width 0.088646)
		(layer "In2.Cu")
		(net "M_F_CPU1_SA_PAR")
	)
	(segment
		(start 172.560488 -257.960114)
		(end 167.922194 -257.070352)
		(width 0.18288)
		(layer "In2.Cu")
		(net "M_F_CPU1_SA_PAR")
	)
	(segment
		(start 132.142992 -256.685796)
		(end 132.142992 -256.68605)
		(width 0.088646)
		(layer "In2.Cu")
		(net "M_F_CPU1_SA_PAR")
	)
	(segment
		(start 172.795946 -259.366766)
		(end 172.93971 -259.71373)
		(width 0.18288)
		(layer "In2.Cu")
		(net "M_F_CPU1_SA_PAR")
	)
	(segment
		(start 172.93971 -259.71373)
		(end 173.176184 -259.950204)
		(width 0.18288)
		(layer "In2.Cu")
		(net "M_F_CPU1_SA_PAR")
	)
	(segment
		(start 133.740144 -255.533398)
		(end 133.740144 -255.547622)
		(width 0.088646)
		(layer "In2.Cu")
		(net "M_F_CPU1_SA_PAR")
	)
	(segment
		(start 167.922194 -257.070352)
		(end 159.647128 -257.070352)
		(width 0.18288)
		(layer "In2.Cu")
		(net "M_F_CPU1_SA_PAR")
	)
	(segment
		(start 140.51915 -255.084326)
		(end 140.054584 -255.084326)
		(width 0.088646)
		(layer "In2.Cu")
		(net "M_F_CPU1_SA_PAR")
	)
	(segment
		(start 173.176184 -259.950204)
		(end 174.601124 -259.950204)
		(width 0.18288)
		(layer "In2.Cu")
		(net "M_F_CPU1_SA_PAR")
	)
	(segment
		(start 155.18511 -255.222248)
		(end 148.340318 -255.222248)
		(width 0.18288)
		(layer "In2.Cu")
		(net "M_F_CPU1_SA_PAR")
	)
	(segment
		(start 138.67765 -255.10998)
		(end 138.549634 -254.981964)
		(width 0.088646)
		(layer "In2.Cu")
		(net "M_F_CPU1_SA_PAR")
	)
	(segment
		(start 140.02893 -255.10998)
		(end 138.67765 -255.10998)
		(width 0.088646)
		(layer "In2.Cu")
		(net "M_F_CPU1_SA_PAR")
	)
	(segment
		(start 133.091682 -256.680716)
		(end 133.082792 -256.685796)
		(width 0.088646)
		(layer "In2.Cu")
		(net "M_F_CPU1_SA_PAR")
	)
	(segment
		(start 140.054584 -255.084326)
		(end 140.02893 -255.10998)
		(width 0.088646)
		(layer "In2.Cu")
		(net "M_F_CPU1_SA_PAR")
	)
	(segment
		(start 131.820666 -256.710434)
		(end 131.799584 -256.632456)
		(width 0.088646)
		(layer "In2.Cu")
		(net "M_F_CPU1_SA_PAR")
	)
	(segment
		(start 148.340318 -255.222248)
		(end 147.462748 -255.585722)
		(width 0.18288)
		(layer "In2.Cu")
		(net "M_F_CPU1_SA_PAR")
	)
	(segment
		(start 137.407396 -255.05791)
		(end 137.392664 -255.049274)
		(width 0.088646)
		(layer "In2.Cu")
		(net "M_F_CPU1_SA_PAR")
	)
	(segment
		(start 131.89204 -256.472182)
		(end 131.955794 -256.361438)
		(width 0.088646)
		(layer "In2.Cu")
		(net "M_F_CPU1_SA_PAR")
	)
	(segment
		(start 159.647128 -257.070352)
		(end 155.18511 -255.222248)
		(width 0.18288)
		(layer "In2.Cu")
		(net "M_F_CPU1_SA_PAR")
	)
	(segment
		(start 174.601124 -259.950204)
		(end 174.96028 -259.591048)
		(width 0.18288)
		(layer "In2.Cu")
		(net "M_F_CPU1_SA_PAR")
	)
	(segment
		(start 141.420596 -255.084326)
		(end 140.51915 -255.084326)
		(width 0.18288)
		(layer "In2.Cu")
		(net "M_F_CPU1_SA_PAR")
	)
	(segment
		(start 134.587996 -255.05791)
		(end 134.573264 -255.049274)
		(width 0.088646)
		(layer "In2.Cu")
		(net "M_F_CPU1_SA_PAR")
	)
	(segment
		(start 143.942054 -255.585722)
		(end 141.420596 -255.084326)
		(width 0.18288)
		(layer "In2.Cu")
		(net "M_F_CPU1_SA_PAR")
	)
	(segment
		(start 138.549634 -254.981964)
		(end 138.064748 -254.981964)
		(width 0.088646)
		(layer "In2.Cu")
		(net "M_F_CPU1_SA_PAR")
	)
	(segment
		(start 174.501048 -258.673092)
		(end 172.560488 -257.960114)
		(width 0.18288)
		(layer "In2.Cu")
		(net "M_F_CPU1_SA_PAR")
	)
	(segment
		(start 133.270244 -256.351532)
		(end 133.270244 -256.361438)
		(width 0.088646)
		(layer "In2.Cu")
		(net "M_F_CPU1_SA_PAR")
	)
	(segment
		(start 174.96028 -259.591048)
		(end 174.96028 -259.132324)
		(width 0.18288)
		(layer "In2.Cu")
		(net "M_F_CPU1_SA_PAR")
	)
	(arc
		(start 136.467596 -255.05791)
		(mid 136.184894 -254.982168)
		(end 135.902192 -255.05791)
		(width 0.088646)
		(layer "In2.Cu")
		(net "M_F_CPU1_SA_PAR")
	)
	(arc
		(start 135.527796 -255.05791)
		(mid 135.245094 -254.982168)
		(end 134.962392 -255.05791)
		(width 0.088646)
		(layer "In2.Cu")
		(net "M_F_CPU1_SA_PAR")
	)
	(arc
		(start 132.142992 -256.68605)
		(mid 131.984593 -256.734836)
		(end 131.820666 -256.710434)
		(width 0.088646)
		(layer "In2.Cu")
		(net "M_F_CPU1_SA_PAR")
	)
	(arc
		(start 132.708396 -256.685796)
		(mid 132.425694 -256.61002)
		(end 132.142992 -256.685796)
		(width 0.088646)
		(layer "In2.Cu")
		(net "M_F_CPU1_SA_PAR")
	)
	(arc
		(start 133.270244 -256.361438)
		(mid 133.222565 -256.544338)
		(end 133.091682 -256.680716)
		(width 0.088646)
		(layer "In2.Cu")
		(net "M_F_CPU1_SA_PAR")
	)
	(arc
		(start 137.781792 -255.05791)
		(mid 137.594594 -255.108053)
		(end 137.407396 -255.05791)
		(width 0.088646)
		(layer "In2.Cu")
		(net "M_F_CPU1_SA_PAR")
	)
	(arc
		(start 134.573264 -255.049274)
		(mid 134.296823 -254.982108)
		(end 134.022592 -255.05791)
		(width 0.088646)
		(layer "In2.Cu")
		(net "M_F_CPU1_SA_PAR")
	)
	(arc
		(start 134.962392 -255.05791)
		(mid 134.775194 -255.108053)
		(end 134.587996 -255.05791)
		(width 0.088646)
		(layer "In2.Cu")
		(net "M_F_CPU1_SA_PAR")
	)
	(arc
		(start 134.022592 -255.05791)
		(mid 133.819287 -255.258776)
		(end 133.740144 -255.533398)
		(width 0.088646)
		(layer "In2.Cu")
		(net "M_F_CPU1_SA_PAR")
	)
	(arc
		(start 135.902192 -255.05791)
		(mid 135.714994 -255.108053)
		(end 135.527796 -255.05791)
		(width 0.088646)
		(layer "In2.Cu")
		(net "M_F_CPU1_SA_PAR")
	)
	(arc
		(start 137.392664 -255.049274)
		(mid 137.116189 -254.981954)
		(end 136.841992 -255.05791)
		(width 0.088646)
		(layer "In2.Cu")
		(net "M_F_CPU1_SA_PAR")
	)
	(arc
		(start 138.064748 -254.981964)
		(mid 137.918261 -255.001279)
		(end 137.781792 -255.05791)
		(width 0.088646)
		(layer "In2.Cu")
		(net "M_F_CPU1_SA_PAR")
	)
	(arc
		(start 136.841992 -255.05791)
		(mid 136.654794 -255.108053)
		(end 136.467596 -255.05791)
		(width 0.088646)
		(layer "In2.Cu")
		(net "M_F_CPU1_SA_PAR")
	)
	(arc
		(start 133.740144 -255.547622)
		(mid 133.692465 -255.730522)
		(end 133.561582 -255.8669)
		(width 0.088646)
		(layer "In2.Cu")
		(net "M_F_CPU1_SA_PAR")
	)
	(arc
		(start 133.552692 -255.87198)
		(mid 133.348357 -256.074585)
		(end 133.270244 -256.351532)
		(width 0.088646)
		(layer "In2.Cu")
		(net "M_F_CPU1_SA_PAR")
	)
	(arc
		(start 133.082792 -256.685796)
		(mid 132.895594 -256.735939)
		(end 132.708396 -256.685796)
		(width 0.088646)
		(layer "In2.Cu")
		(net "M_F_CPU1_SA_PAR")
	)
	(segment
		(start 180.434996 -273.39163)
		(end 182.447692 -273.39163)
		(width 0.1016)
		(layer "F.Cu")
		(net "M_F_CPU1_SA_DQS_DP<9>")
	)
	(segment
		(start 183.031892 -273.63928)
		(end 183.685434 -273.63928)
		(width 0.20066)
		(layer "F.Cu")
		(net "M_F_CPU1_SA_DQS_DP<9>")
	)
	(segment
		(start 183.685434 -273.63928)
		(end 184.13095 -274.084796)
		(width 0.20066)
		(layer "F.Cu")
		(net "M_F_CPU1_SA_DQS_DP<9>")
	)
	(segment
		(start 179.150264 -274.067778)
		(end 179.575206 -273.642836)
		(width 0.20066)
		(layer "F.Cu")
		(net "M_F_CPU1_SA_DQS_DP<9>")
	)
	(segment
		(start 134.775448 -262.87222)
		(end 134.775194 -262.872474)
		(width 0.20066)
		(layer "F.Cu")
		(net "M_F_CPU1_SA_DQS_DP<9>")
	)
	(segment
		(start 178.000914 -273.816572)
		(end 178.594258 -273.816572)
		(width 0.20066)
		(layer "F.Cu")
		(net "M_F_CPU1_SA_DQS_DP<9>")
	)
	(segment
		(start 184.708546 -274.084796)
		(end 184.97677 -273.816572)
		(width 0.20066)
		(layer "F.Cu")
		(net "M_F_CPU1_SA_DQS_DP<9>")
	)
	(segment
		(start 179.85359 -273.642836)
		(end 180.111908 -273.384518)
		(width 0.20066)
		(layer "F.Cu")
		(net "M_F_CPU1_SA_DQS_DP<9>")
	)
	(segment
		(start 179.575206 -273.642836)
		(end 179.85359 -273.642836)
		(width 0.20066)
		(layer "F.Cu")
		(net "M_F_CPU1_SA_DQS_DP<9>")
	)
	(segment
		(start 182.776876 -273.384264)
		(end 183.031892 -273.63928)
		(width 0.20066)
		(layer "F.Cu")
		(net "M_F_CPU1_SA_DQS_DP<9>")
	)
	(segment
		(start 178.845464 -274.067778)
		(end 179.150264 -274.067778)
		(width 0.20066)
		(layer "F.Cu")
		(net "M_F_CPU1_SA_DQS_DP<9>")
	)
	(segment
		(start 176.896014 -273.816572)
		(end 178.000914 -273.816572)
		(width 0.20066)
		(layer "F.Cu")
		(net "M_F_CPU1_SA_DQS_DP<9>")
	)
	(segment
		(start 134.775448 -262.336534)
		(end 134.775448 -262.87222)
		(width 0.20066)
		(layer "F.Cu")
		(net "M_F_CPU1_SA_DQS_DP<9>")
	)
	(segment
		(start 180.427884 -273.384518)
		(end 180.434996 -273.39163)
		(width 0.1016)
		(layer "F.Cu")
		(net "M_F_CPU1_SA_DQS_DP<9>")
	)
	(segment
		(start 180.423058 -273.384518)
		(end 180.427884 -273.384518)
		(width 0.101854)
		(layer "F.Cu")
		(net "M_F_CPU1_SA_DQS_DP<9>")
	)
	(segment
		(start 184.97677 -273.816572)
		(end 185.544714 -273.816572)
		(width 0.20066)
		(layer "F.Cu")
		(net "M_F_CPU1_SA_DQS_DP<9>")
	)
	(segment
		(start 182.447692 -273.39163)
		(end 182.455058 -273.384264)
		(width 0.1016)
		(layer "F.Cu")
		(net "M_F_CPU1_SA_DQS_DP<9>")
	)
	(segment
		(start 178.594258 -273.816572)
		(end 178.845464 -274.067778)
		(width 0.20066)
		(layer "F.Cu")
		(net "M_F_CPU1_SA_DQS_DP<9>")
	)
	(segment
		(start 184.13095 -274.084796)
		(end 184.708546 -274.084796)
		(width 0.20066)
		(layer "F.Cu")
		(net "M_F_CPU1_SA_DQS_DP<9>")
	)
	(segment
		(start 182.455058 -273.384264)
		(end 182.776876 -273.384264)
		(width 0.20066)
		(layer "F.Cu")
		(net "M_F_CPU1_SA_DQS_DP<9>")
	)
	(segment
		(start 180.111908 -273.384518)
		(end 180.423058 -273.384518)
		(width 0.20066)
		(layer "F.Cu")
		(net "M_F_CPU1_SA_DQS_DP<9>")
	)
	(segment
		(start 169.704766 -273.021552)
		(end 169.500296 -273.226022)
		(width 0.18288)
		(layer "In2.Cu")
		(net "M_F_CPU1_SA_DQS_DP<9>")
	)
	(segment
		(start 157.695392 -271.67967)
		(end 157.299914 -271.67967)
		(width 0.18288)
		(layer "In2.Cu")
		(net "M_F_CPU1_SA_DQS_DP<9>")
	)
	(segment
		(start 159.648652 -272.24609)
		(end 159.347408 -271.944846)
		(width 0.18288)
		(layer "In2.Cu")
		(net "M_F_CPU1_SA_DQS_DP<9>")
	)
	(segment
		(start 161.7599 -272.529554)
		(end 161.399982 -272.529554)
		(width 0.18288)
		(layer "In2.Cu")
		(net "M_F_CPU1_SA_DQS_DP<9>")
	)
	(segment
		(start 176.675288 -274.037298)
		(end 174.83328 -274.037298)
		(width 0.18288)
		(layer "In2.Cu")
		(net "M_F_CPU1_SA_DQS_DP<9>")
	)
	(segment
		(start 173.021244 -273.391122)
		(end 173.020482 -273.392138)
		(width 0.18288)
		(layer "In2.Cu")
		(net "M_F_CPU1_SA_DQS_DP<9>")
	)
	(segment
		(start 167.187118 -273.672554)
		(end 165.617144 -273.672554)
		(width 0.18288)
		(layer "In2.Cu")
		(net "M_F_CPU1_SA_DQS_DP<9>")
	)
	(segment
		(start 171.648374 -273.451828)
		(end 171.62018 -273.423634)
		(width 0.16002)
		(layer "In2.Cu")
		(net "M_F_CPU1_SA_DQS_DP<9>")
	)
	(segment
		(start 159.676846 -272.29054)
		(end 159.676846 -272.274284)
		(width 0.16002)
		(layer "In2.Cu")
		(net "M_F_CPU1_SA_DQS_DP<9>")
	)
	(segment
		(start 168.200324 -273.639534)
		(end 167.938958 -273.378168)
		(width 0.18288)
		(layer "In2.Cu")
		(net "M_F_CPU1_SA_DQS_DP<9>")
	)
	(segment
		(start 171.603924 -273.423634)
		(end 171.419774 -273.239484)
		(width 0.16002)
		(layer "In2.Cu")
		(net "M_F_CPU1_SA_DQS_DP<9>")
	)
	(segment
		(start 156.680408 -271.820894)
		(end 155.987496 -270.149828)
		(width 0.18288)
		(layer "In2.Cu")
		(net "M_F_CPU1_SA_DQS_DP<9>")
	)
	(segment
		(start 159.860996 -272.47469)
		(end 159.676846 -272.29054)
		(width 0.16002)
		(layer "In2.Cu")
		(net "M_F_CPU1_SA_DQS_DP<9>")
	)
	(segment
		(start 157.299914 -271.67967)
		(end 157.073092 -271.906492)
		(width 0.18288)
		(layer "In2.Cu")
		(net "M_F_CPU1_SA_DQS_DP<9>")
	)
	(segment
		(start 171.218098 -273.021552)
		(end 169.704766 -273.021552)
		(width 0.18288)
		(layer "In2.Cu")
		(net "M_F_CPU1_SA_DQS_DP<9>")
	)
	(segment
		(start 136.206992 -262.47852)
		(end 136.120124 -262.552434)
		(width 0.088646)
		(layer "In2.Cu")
		(net "M_F_CPU1_SA_DQS_DP<9>")
	)
	(segment
		(start 155.987496 -270.149828)
		(end 150.746714 -264.909046)
		(width 0.18288)
		(layer "In2.Cu")
		(net "M_F_CPU1_SA_DQS_DP<9>")
	)
	(segment
		(start 163.74872 -273.095974)
		(end 163.481004 -272.828258)
		(width 0.18288)
		(layer "In2.Cu")
		(net "M_F_CPU1_SA_DQS_DP<9>")
	)
	(segment
		(start 160.467294 -272.55343)
		(end 159.955992 -272.55343)
		(width 0.18288)
		(layer "In2.Cu")
		(net "M_F_CPU1_SA_DQS_DP<9>")
	)
	(segment
		(start 157.960568 -271.944846)
		(end 157.695392 -271.67967)
		(width 0.18288)
		(layer "In2.Cu")
		(net "M_F_CPU1_SA_DQS_DP<9>")
	)
	(segment
		(start 163.97732 -273.324574)
		(end 163.961064 -273.324574)
		(width 0.16002)
		(layer "In2.Cu")
		(net "M_F_CPU1_SA_DQS_DP<9>")
	)
	(segment
		(start 172.320966 -273.62404)
		(end 171.820586 -273.62404)
		(width 0.18288)
		(layer "In2.Cu")
		(net "M_F_CPU1_SA_DQS_DP<9>")
	)
	(segment
		(start 161.399982 -272.529554)
		(end 161.134806 -272.79473)
		(width 0.18288)
		(layer "In2.Cu")
		(net "M_F_CPU1_SA_DQS_DP<9>")
	)
	(segment
		(start 164.005514 -273.352768)
		(end 163.97732 -273.324574)
		(width 0.16002)
		(layer "In2.Cu")
		(net "M_F_CPU1_SA_DQS_DP<9>")
	)
	(segment
		(start 164.30625 -273.653504)
		(end 164.005514 -273.352768)
		(width 0.18288)
		(layer "In2.Cu")
		(net "M_F_CPU1_SA_DQS_DP<9>")
	)
	(segment
		(start 138.817096 -262.383016)
		(end 138.802364 -262.37438)
		(width 0.088646)
		(layer "In2.Cu")
		(net "M_F_CPU1_SA_DQS_DP<9>")
	)
	(segment
		(start 169.287952 -273.454622)
		(end 169.271696 -273.454622)
		(width 0.16002)
		(layer "In2.Cu")
		(net "M_F_CPU1_SA_DQS_DP<9>")
	)
	(segment
		(start 164.865304 -273.378168)
		(end 164.589968 -273.653504)
		(width 0.18288)
		(layer "In2.Cu")
		(net "M_F_CPU1_SA_DQS_DP<9>")
	)
	(segment
		(start 159.347408 -271.944846)
		(end 157.960568 -271.944846)
		(width 0.18288)
		(layer "In2.Cu")
		(net "M_F_CPU1_SA_DQS_DP<9>")
	)
	(segment
		(start 159.905446 -272.502884)
		(end 159.877252 -272.47469)
		(width 0.16002)
		(layer "In2.Cu")
		(net "M_F_CPU1_SA_DQS_DP<9>")
	)
	(segment
		(start 164.589968 -273.653504)
		(end 164.30625 -273.653504)
		(width 0.18288)
		(layer "In2.Cu")
		(net "M_F_CPU1_SA_DQS_DP<9>")
	)
	(segment
		(start 163.776914 -273.124168)
		(end 163.74872 -273.095974)
		(width 0.16002)
		(layer "In2.Cu")
		(net "M_F_CPU1_SA_DQS_DP<9>")
	)
	(segment
		(start 169.086784 -273.639534)
		(end 168.200324 -273.639534)
		(width 0.18288)
		(layer "In2.Cu")
		(net "M_F_CPU1_SA_DQS_DP<9>")
	)
	(segment
		(start 173.797214 -273.608038)
		(end 173.244256 -273.608038)
		(width 0.18288)
		(layer "In2.Cu")
		(net "M_F_CPU1_SA_DQS_DP<9>")
	)
	(segment
		(start 159.877252 -272.47469)
		(end 159.860996 -272.47469)
		(width 0.16002)
		(layer "In2.Cu")
		(net "M_F_CPU1_SA_DQS_DP<9>")
	)
	(segment
		(start 169.271696 -273.454622)
		(end 169.243502 -273.482816)
		(width 0.16002)
		(layer "In2.Cu")
		(net "M_F_CPU1_SA_DQS_DP<9>")
	)
	(segment
		(start 169.500296 -273.226022)
		(end 169.472102 -273.254216)
		(width 0.16002)
		(layer "In2.Cu")
		(net "M_F_CPU1_SA_DQS_DP<9>")
	)
	(segment
		(start 173.244256 -273.608038)
		(end 173.021244 -273.391122)
		(width 0.18288)
		(layer "In2.Cu")
		(net "M_F_CPU1_SA_DQS_DP<9>")
	)
	(segment
		(start 147.202144 -264.909046)
		(end 145.118836 -262.825484)
		(width 0.18288)
		(layer "In2.Cu")
		(net "M_F_CPU1_SA_DQS_DP<9>")
	)
	(segment
		(start 150.746714 -264.909046)
		(end 147.202144 -264.909046)
		(width 0.18288)
		(layer "In2.Cu")
		(net "M_F_CPU1_SA_DQS_DP<9>")
	)
	(segment
		(start 136.372092 -262.383016)
		(end 136.206992 -262.47852)
		(width 0.088646)
		(layer "In2.Cu")
		(net "M_F_CPU1_SA_DQS_DP<9>")
	)
	(segment
		(start 162.058604 -272.828258)
		(end 161.7599 -272.529554)
		(width 0.18288)
		(layer "In2.Cu")
		(net "M_F_CPU1_SA_DQS_DP<9>")
	)
	(segment
		(start 171.39158 -273.195034)
		(end 171.218098 -273.021552)
		(width 0.18288)
		(layer "In2.Cu")
		(net "M_F_CPU1_SA_DQS_DP<9>")
	)
	(segment
		(start 144.027652 -262.373618)
		(end 140.900404 -262.373618)
		(width 0.18288)
		(layer "In2.Cu")
		(net "M_F_CPU1_SA_DQS_DP<9>")
	)
	(segment
		(start 160.708594 -272.79473)
		(end 160.467294 -272.55343)
		(width 0.18288)
		(layer "In2.Cu")
		(net "M_F_CPU1_SA_DQS_DP<9>")
	)
	(segment
		(start 159.676846 -272.274284)
		(end 159.648652 -272.24609)
		(width 0.16002)
		(layer "In2.Cu")
		(net "M_F_CPU1_SA_DQS_DP<9>")
	)
	(segment
		(start 169.472102 -273.254216)
		(end 169.472102 -273.270472)
		(width 0.16002)
		(layer "In2.Cu")
		(net "M_F_CPU1_SA_DQS_DP<9>")
	)
	(segment
		(start 136.120124 -262.552434)
		(end 135.9281 -262.552434)
		(width 0.088646)
		(layer "In2.Cu")
		(net "M_F_CPU1_SA_DQS_DP<9>")
	)
	(segment
		(start 135.923782 -262.548116)
		(end 135.902192 -262.548116)
		(width 0.088646)
		(layer "In2.Cu")
		(net "M_F_CPU1_SA_DQS_DP<9>")
	)
	(segment
		(start 135.499856 -262.564372)
		(end 134.775194 -262.872474)
		(width 0.088646)
		(layer "In2.Cu")
		(net "M_F_CPU1_SA_DQS_DP<9>")
	)
	(segment
		(start 163.776914 -273.140424)
		(end 163.776914 -273.124168)
		(width 0.16002)
		(layer "In2.Cu")
		(net "M_F_CPU1_SA_DQS_DP<9>")
	)
	(segment
		(start 135.527796 -262.548116)
		(end 135.499856 -262.564372)
		(width 0.088646)
		(layer "In2.Cu")
		(net "M_F_CPU1_SA_DQS_DP<9>")
	)
	(segment
		(start 173.020482 -273.392138)
		(end 172.552868 -273.392138)
		(width 0.18288)
		(layer "In2.Cu")
		(net "M_F_CPU1_SA_DQS_DP<9>")
	)
	(segment
		(start 156.765752 -271.906492)
		(end 156.680408 -271.820894)
		(width 0.18288)
		(layer "In2.Cu")
		(net "M_F_CPU1_SA_DQS_DP<9>")
	)
	(segment
		(start 167.481504 -273.378168)
		(end 167.187118 -273.672554)
		(width 0.18288)
		(layer "In2.Cu")
		(net "M_F_CPU1_SA_DQS_DP<9>")
	)
	(segment
		(start 157.073092 -271.906492)
		(end 156.765752 -271.906492)
		(width 0.18288)
		(layer "In2.Cu")
		(net "M_F_CPU1_SA_DQS_DP<9>")
	)
	(segment
		(start 174.83328 -274.037298)
		(end 173.797214 -273.608038)
		(width 0.18288)
		(layer "In2.Cu")
		(net "M_F_CPU1_SA_DQS_DP<9>")
	)
	(segment
		(start 140.900404 -262.373618)
		(end 140.84046 -262.433562)
		(width 0.088646)
		(layer "In2.Cu")
		(net "M_F_CPU1_SA_DQS_DP<9>")
	)
	(segment
		(start 169.472102 -273.270472)
		(end 169.287952 -273.454622)
		(width 0.16002)
		(layer "In2.Cu")
		(net "M_F_CPU1_SA_DQS_DP<9>")
	)
	(segment
		(start 172.552868 -273.392138)
		(end 172.320966 -273.62404)
		(width 0.18288)
		(layer "In2.Cu")
		(net "M_F_CPU1_SA_DQS_DP<9>")
	)
	(segment
		(start 165.617144 -273.672554)
		(end 165.322758 -273.378168)
		(width 0.18288)
		(layer "In2.Cu")
		(net "M_F_CPU1_SA_DQS_DP<9>")
	)
	(segment
		(start 171.419774 -273.223228)
		(end 171.39158 -273.195034)
		(width 0.16002)
		(layer "In2.Cu")
		(net "M_F_CPU1_SA_DQS_DP<9>")
	)
	(segment
		(start 140.84046 -262.433562)
		(end 139.944094 -262.433562)
		(width 0.088646)
		(layer "In2.Cu")
		(net "M_F_CPU1_SA_DQS_DP<9>")
	)
	(segment
		(start 176.896014 -273.816572)
		(end 176.675288 -274.037298)
		(width 0.18288)
		(layer "In2.Cu")
		(net "M_F_CPU1_SA_DQS_DP<9>")
	)
	(segment
		(start 161.134806 -272.79473)
		(end 160.708594 -272.79473)
		(width 0.18288)
		(layer "In2.Cu")
		(net "M_F_CPU1_SA_DQS_DP<9>")
	)
	(segment
		(start 145.118836 -262.825484)
		(end 144.027652 -262.373618)
		(width 0.18288)
		(layer "In2.Cu")
		(net "M_F_CPU1_SA_DQS_DP<9>")
	)
	(segment
		(start 171.62018 -273.423634)
		(end 171.603924 -273.423634)
		(width 0.16002)
		(layer "In2.Cu")
		(net "M_F_CPU1_SA_DQS_DP<9>")
	)
	(segment
		(start 135.9281 -262.552434)
		(end 135.923782 -262.548116)
		(width 0.088646)
		(layer "In2.Cu")
		(net "M_F_CPU1_SA_DQS_DP<9>")
	)
	(segment
		(start 167.938958 -273.378168)
		(end 167.481504 -273.378168)
		(width 0.18288)
		(layer "In2.Cu")
		(net "M_F_CPU1_SA_DQS_DP<9>")
	)
	(segment
		(start 171.419774 -273.239484)
		(end 171.419774 -273.223228)
		(width 0.16002)
		(layer "In2.Cu")
		(net "M_F_CPU1_SA_DQS_DP<9>")
	)
	(segment
		(start 159.955992 -272.55343)
		(end 159.905446 -272.502884)
		(width 0.18288)
		(layer "In2.Cu")
		(net "M_F_CPU1_SA_DQS_DP<9>")
	)
	(segment
		(start 165.322758 -273.378168)
		(end 164.865304 -273.378168)
		(width 0.18288)
		(layer "In2.Cu")
		(net "M_F_CPU1_SA_DQS_DP<9>")
	)
	(segment
		(start 163.961064 -273.324574)
		(end 163.776914 -273.140424)
		(width 0.16002)
		(layer "In2.Cu")
		(net "M_F_CPU1_SA_DQS_DP<9>")
	)
	(segment
		(start 171.820586 -273.62404)
		(end 171.648374 -273.451828)
		(width 0.18288)
		(layer "In2.Cu")
		(net "M_F_CPU1_SA_DQS_DP<9>")
	)
	(segment
		(start 169.243502 -273.482816)
		(end 169.086784 -273.639534)
		(width 0.18288)
		(layer "In2.Cu")
		(net "M_F_CPU1_SA_DQS_DP<9>")
	)
	(segment
		(start 163.481004 -272.828258)
		(end 162.058604 -272.828258)
		(width 0.18288)
		(layer "In2.Cu")
		(net "M_F_CPU1_SA_DQS_DP<9>")
	)
	(arc
		(start 137.311892 -262.383016)
		(mid 137.124694 -262.433159)
		(end 136.937496 -262.383016)
		(width 0.088646)
		(layer "In2.Cu")
		(net "M_F_CPU1_SA_DQS_DP<9>")
	)
	(arc
		(start 138.251692 -262.383016)
		(mid 138.064494 -262.433159)
		(end 137.877296 -262.383016)
		(width 0.088646)
		(layer "In2.Cu")
		(net "M_F_CPU1_SA_DQS_DP<9>")
	)
	(arc
		(start 139.944094 -262.433562)
		(mid 139.838893 -262.418425)
		(end 139.742164 -262.37438)
		(width 0.088646)
		(layer "In2.Cu")
		(net "M_F_CPU1_SA_DQS_DP<9>")
	)
	(arc
		(start 137.877296 -262.383016)
		(mid 137.594594 -262.30724)
		(end 137.311892 -262.383016)
		(width 0.088646)
		(layer "In2.Cu")
		(net "M_F_CPU1_SA_DQS_DP<9>")
	)
	(arc
		(start 138.802364 -262.37438)
		(mid 138.525889 -262.30706)
		(end 138.251692 -262.383016)
		(width 0.088646)
		(layer "In2.Cu")
		(net "M_F_CPU1_SA_DQS_DP<9>")
	)
	(arc
		(start 139.191492 -262.383016)
		(mid 139.004294 -262.433159)
		(end 138.817096 -262.383016)
		(width 0.088646)
		(layer "In2.Cu")
		(net "M_F_CPU1_SA_DQS_DP<9>")
	)
	(arc
		(start 136.937496 -262.383016)
		(mid 136.654794 -262.30724)
		(end 136.372092 -262.383016)
		(width 0.088646)
		(layer "In2.Cu")
		(net "M_F_CPU1_SA_DQS_DP<9>")
	)
	(arc
		(start 139.742164 -262.37438)
		(mid 139.465689 -262.30706)
		(end 139.191492 -262.383016)
		(width 0.088646)
		(layer "In2.Cu")
		(net "M_F_CPU1_SA_DQS_DP<9>")
	)
	(arc
		(start 135.902192 -262.548116)
		(mid 135.714994 -262.497973)
		(end 135.527796 -262.548116)
		(width 0.088646)
		(layer "In2.Cu")
		(net "M_F_CPU1_SA_DQS_DP<9>")
	)
	(segment
		(start 182.447692 -282.741624)
		(end 182.455058 -282.734258)
		(width 0.1016)
		(layer "F.Cu")
		(net "M_F_CPU1_SA_DQS_DP<8>")
	)
	(segment
		(start 184.708546 -283.43479)
		(end 184.97677 -283.166566)
		(width 0.20066)
		(layer "F.Cu")
		(net "M_F_CPU1_SA_DQS_DP<8>")
	)
	(segment
		(start 183.031892 -282.989274)
		(end 183.685434 -282.989274)
		(width 0.20066)
		(layer "F.Cu")
		(net "M_F_CPU1_SA_DQS_DP<8>")
	)
	(segment
		(start 180.423058 -282.734512)
		(end 180.427884 -282.734512)
		(width 0.101854)
		(layer "F.Cu")
		(net "M_F_CPU1_SA_DQS_DP<8>")
	)
	(segment
		(start 131.485894 -259.894832)
		(end 131.486148 -259.895086)
		(width 0.20066)
		(layer "F.Cu")
		(net "M_F_CPU1_SA_DQS_DP<8>")
	)
	(segment
		(start 179.150264 -283.417772)
		(end 179.575206 -282.99283)
		(width 0.20066)
		(layer "F.Cu")
		(net "M_F_CPU1_SA_DQS_DP<8>")
	)
	(segment
		(start 131.486148 -259.895086)
		(end 131.486148 -260.430772)
		(width 0.20066)
		(layer "F.Cu")
		(net "M_F_CPU1_SA_DQS_DP<8>")
	)
	(segment
		(start 179.575206 -282.99283)
		(end 179.85359 -282.99283)
		(width 0.20066)
		(layer "F.Cu")
		(net "M_F_CPU1_SA_DQS_DP<8>")
	)
	(segment
		(start 182.776876 -282.734258)
		(end 183.031892 -282.989274)
		(width 0.20066)
		(layer "F.Cu")
		(net "M_F_CPU1_SA_DQS_DP<8>")
	)
	(segment
		(start 180.427884 -282.734512)
		(end 180.434996 -282.741624)
		(width 0.1016)
		(layer "F.Cu")
		(net "M_F_CPU1_SA_DQS_DP<8>")
	)
	(segment
		(start 178.594258 -283.166566)
		(end 178.845464 -283.417772)
		(width 0.20066)
		(layer "F.Cu")
		(net "M_F_CPU1_SA_DQS_DP<8>")
	)
	(segment
		(start 176.896014 -283.166566)
		(end 178.000914 -283.166566)
		(width 0.20066)
		(layer "F.Cu")
		(net "M_F_CPU1_SA_DQS_DP<8>")
	)
	(segment
		(start 180.111908 -282.734512)
		(end 180.423058 -282.734512)
		(width 0.20066)
		(layer "F.Cu")
		(net "M_F_CPU1_SA_DQS_DP<8>")
	)
	(segment
		(start 178.845464 -283.417772)
		(end 179.150264 -283.417772)
		(width 0.20066)
		(layer "F.Cu")
		(net "M_F_CPU1_SA_DQS_DP<8>")
	)
	(segment
		(start 182.455058 -282.734258)
		(end 182.776876 -282.734258)
		(width 0.20066)
		(layer "F.Cu")
		(net "M_F_CPU1_SA_DQS_DP<8>")
	)
	(segment
		(start 184.13095 -283.43479)
		(end 184.708546 -283.43479)
		(width 0.20066)
		(layer "F.Cu")
		(net "M_F_CPU1_SA_DQS_DP<8>")
	)
	(segment
		(start 183.685434 -282.989274)
		(end 184.13095 -283.43479)
		(width 0.20066)
		(layer "F.Cu")
		(net "M_F_CPU1_SA_DQS_DP<8>")
	)
	(segment
		(start 179.85359 -282.99283)
		(end 180.111908 -282.734512)
		(width 0.20066)
		(layer "F.Cu")
		(net "M_F_CPU1_SA_DQS_DP<8>")
	)
	(segment
		(start 178.000914 -283.166566)
		(end 178.594258 -283.166566)
		(width 0.20066)
		(layer "F.Cu")
		(net "M_F_CPU1_SA_DQS_DP<8>")
	)
	(segment
		(start 184.97677 -283.166566)
		(end 185.544714 -283.166566)
		(width 0.20066)
		(layer "F.Cu")
		(net "M_F_CPU1_SA_DQS_DP<8>")
	)
	(segment
		(start 180.434996 -282.741624)
		(end 182.447692 -282.741624)
		(width 0.1016)
		(layer "F.Cu")
		(net "M_F_CPU1_SA_DQS_DP<8>")
	)
	(segment
		(start 158.17596 -270.265906)
		(end 157.903164 -269.99311)
		(width 0.18288)
		(layer "In4.Cu")
		(net "M_F_CPU1_SA_DQS_DP<8>")
	)
	(segment
		(start 176.896014 -283.166566)
		(end 176.625758 -283.436822)
		(width 0.18288)
		(layer "In4.Cu")
		(net "M_F_CPU1_SA_DQS_DP<8>")
	)
	(segment
		(start 170.05681 -275.783802)
		(end 169.756836 -275.060918)
		(width 0.18288)
		(layer "In4.Cu")
		(net "M_F_CPU1_SA_DQS_DP<8>")
	)
	(segment
		(start 135.539988 -259.948934)
		(end 135.52805 -259.941822)
		(width 0.088646)
		(layer "In4.Cu")
		(net "M_F_CPU1_SA_DQS_DP<8>")
	)
	(segment
		(start 134.596886 -259.946648)
		(end 134.588504 -259.941822)
		(width 0.088646)
		(layer "In4.Cu")
		(net "M_F_CPU1_SA_DQS_DP<8>")
	)
	(segment
		(start 141.71676 -259.93217)
		(end 138.86815 -259.93217)
		(width 0.18288)
		(layer "In4.Cu")
		(net "M_F_CPU1_SA_DQS_DP<8>")
	)
	(segment
		(start 132.973318 -260.004814)
		(end 132.866638 -260.033516)
		(width 0.088646)
		(layer "In4.Cu")
		(net "M_F_CPU1_SA_DQS_DP<8>")
	)
	(segment
		(start 169.756836 -275.060918)
		(end 169.587926 -274.892008)
		(width 0.18288)
		(layer "In4.Cu")
		(net "M_F_CPU1_SA_DQS_DP<8>")
	)
	(segment
		(start 171.815252 -283.019246)
		(end 171.485306 -282.882086)
		(width 0.18288)
		(layer "In4.Cu")
		(net "M_F_CPU1_SA_DQS_DP<8>")
	)
	(segment
		(start 172.902626 -282.742386)
		(end 172.674026 -282.742386)
		(width 0.18288)
		(layer "In4.Cu")
		(net "M_F_CPU1_SA_DQS_DP<8>")
	)
	(segment
		(start 137.782046 -259.941568)
		(end 137.781792 -259.941568)
		(width 0.088646)
		(layer "In4.Cu")
		(net "M_F_CPU1_SA_DQS_DP<8>")
	)
	(segment
		(start 168.755822 -274.547076)
		(end 167.505888 -274.298156)
		(width 0.18288)
		(layer "In4.Cu")
		(net "M_F_CPU1_SA_DQS_DP<8>")
	)
	(segment
		(start 132.23875 -260.106414)
		(end 132.22986 -260.111494)
		(width 0.088646)
		(layer "In4.Cu")
		(net "M_F_CPU1_SA_DQS_DP<8>")
	)
	(segment
		(start 172.902626 -282.74264)
		(end 172.902626 -282.742386)
		(width 0.18288)
		(layer "In4.Cu")
		(net "M_F_CPU1_SA_DQS_DP<8>")
	)
	(segment
		(start 172.992034 -282.74264)
		(end 172.902626 -282.74264)
		(width 0.18288)
		(layer "In4.Cu")
		(net "M_F_CPU1_SA_DQS_DP<8>")
	)
	(segment
		(start 136.479534 -259.948934)
		(end 136.467342 -259.941822)
		(width 0.088646)
		(layer "In4.Cu")
		(net "M_F_CPU1_SA_DQS_DP<8>")
	)
	(segment
		(start 165.636448 -272.757392)
		(end 165.636448 -272.757138)
		(width 0.18288)
		(layer "In4.Cu")
		(net "M_F_CPU1_SA_DQS_DP<8>")
	)
	(segment
		(start 132.866638 -260.033516)
		(end 132.432044 -260.033516)
		(width 0.088646)
		(layer "In4.Cu")
		(net "M_F_CPU1_SA_DQS_DP<8>")
	)
	(segment
		(start 131.99872 -260.430772)
		(end 131.486148 -260.430772)
		(width 0.088646)
		(layer "In4.Cu")
		(net "M_F_CPU1_SA_DQS_DP<8>")
	)
	(segment
		(start 144.745456 -261.190232)
		(end 141.71676 -259.93217)
		(width 0.18288)
		(layer "In4.Cu")
		(net "M_F_CPU1_SA_DQS_DP<8>")
	)
	(segment
		(start 172.674026 -282.74264)
		(end 172.585126 -282.74264)
		(width 0.18288)
		(layer "In4.Cu")
		(net "M_F_CPU1_SA_DQS_DP<8>")
	)
	(segment
		(start 138.844782 -259.93217)
		(end 138.785092 -259.99186)
		(width 0.088646)
		(layer "In4.Cu")
		(net "M_F_CPU1_SA_DQS_DP<8>")
	)
	(segment
		(start 167.505888 -274.298156)
		(end 166.197534 -272.989802)
		(width 0.18288)
		(layer "In4.Cu")
		(net "M_F_CPU1_SA_DQS_DP<8>")
	)
	(segment
		(start 157.903164 -269.99311)
		(end 157.235906 -269.99311)
		(width 0.18288)
		(layer "In4.Cu")
		(net "M_F_CPU1_SA_DQS_DP<8>")
	)
	(segment
		(start 160.732216 -271.295368)
		(end 158.74492 -270.4719)
		(width 0.18288)
		(layer "In4.Cu")
		(net "M_F_CPU1_SA_DQS_DP<8>")
	)
	(segment
		(start 161.41573 -271.979136)
		(end 160.732216 -271.295368)
		(width 0.18288)
		(layer "In4.Cu")
		(net "M_F_CPU1_SA_DQS_DP<8>")
	)
	(segment
		(start 165.636448 -272.757138)
		(end 163.760658 -271.979136)
		(width 0.18288)
		(layer "In4.Cu")
		(net "M_F_CPU1_SA_DQS_DP<8>")
	)
	(segment
		(start 133.647688 -259.941314)
		(end 133.647688 -259.941568)
		(width 0.088646)
		(layer "In4.Cu")
		(net "M_F_CPU1_SA_DQS_DP<8>")
	)
	(segment
		(start 132.05587 -260.373622)
		(end 131.99872 -260.430772)
		(width 0.088646)
		(layer "In4.Cu")
		(net "M_F_CPU1_SA_DQS_DP<8>")
	)
	(segment
		(start 170.439334 -277.705312)
		(end 170.05681 -275.783802)
		(width 0.18288)
		(layer "In4.Cu")
		(net "M_F_CPU1_SA_DQS_DP<8>")
	)
	(segment
		(start 157.235906 -269.99311)
		(end 149.118828 -261.876032)
		(width 0.18288)
		(layer "In4.Cu")
		(net "M_F_CPU1_SA_DQS_DP<8>")
	)
	(segment
		(start 158.538672 -270.265906)
		(end 158.17596 -270.265906)
		(width 0.18288)
		(layer "In4.Cu")
		(net "M_F_CPU1_SA_DQS_DP<8>")
	)
	(segment
		(start 163.760658 -271.979136)
		(end 161.41573 -271.979136)
		(width 0.18288)
		(layer "In4.Cu")
		(net "M_F_CPU1_SA_DQS_DP<8>")
	)
	(segment
		(start 172.30852 -283.019246)
		(end 171.815252 -283.019246)
		(width 0.18288)
		(layer "In4.Cu")
		(net "M_F_CPU1_SA_DQS_DP<8>")
	)
	(segment
		(start 176.005744 -283.589476)
		(end 174.141638 -283.589476)
		(width 0.18288)
		(layer "In4.Cu")
		(net "M_F_CPU1_SA_DQS_DP<8>")
	)
	(segment
		(start 149.118828 -261.876032)
		(end 145.92681 -261.876032)
		(width 0.18288)
		(layer "In4.Cu")
		(net "M_F_CPU1_SA_DQS_DP<8>")
	)
	(segment
		(start 145.078196 -261.522972)
		(end 144.745456 -261.190232)
		(width 0.18288)
		(layer "In4.Cu")
		(net "M_F_CPU1_SA_DQS_DP<8>")
	)
	(segment
		(start 176.625758 -283.436822)
		(end 176.374298 -283.436822)
		(width 0.18288)
		(layer "In4.Cu")
		(net "M_F_CPU1_SA_DQS_DP<8>")
	)
	(segment
		(start 166.197534 -272.989802)
		(end 165.636448 -272.757392)
		(width 0.18288)
		(layer "In4.Cu")
		(net "M_F_CPU1_SA_DQS_DP<8>")
	)
	(segment
		(start 133.0833 -259.941568)
		(end 132.973318 -260.004814)
		(width 0.088646)
		(layer "In4.Cu")
		(net "M_F_CPU1_SA_DQS_DP<8>")
	)
	(segment
		(start 133.656832 -259.946648)
		(end 133.64845 -259.941822)
		(width 0.088646)
		(layer "In4.Cu")
		(net "M_F_CPU1_SA_DQS_DP<8>")
	)
	(segment
		(start 138.86815 -259.93217)
		(end 138.844782 -259.93217)
		(width 0.088646)
		(layer "In4.Cu")
		(net "M_F_CPU1_SA_DQS_DP<8>")
	)
	(segment
		(start 171.202858 -282.599638)
		(end 170.439334 -280.757122)
		(width 0.18288)
		(layer "In4.Cu")
		(net "M_F_CPU1_SA_DQS_DP<8>")
	)
	(segment
		(start 145.92681 -261.876032)
		(end 145.078196 -261.522972)
		(width 0.18288)
		(layer "In4.Cu")
		(net "M_F_CPU1_SA_DQS_DP<8>")
	)
	(segment
		(start 174.141638 -283.589476)
		(end 173.573694 -283.021532)
		(width 0.18288)
		(layer "In4.Cu")
		(net "M_F_CPU1_SA_DQS_DP<8>")
	)
	(segment
		(start 136.467342 -259.941822)
		(end 136.456674 -259.935472)
		(width 0.088646)
		(layer "In4.Cu")
		(net "M_F_CPU1_SA_DQS_DP<8>")
	)
	(segment
		(start 173.573694 -283.021532)
		(end 173.270926 -283.021532)
		(width 0.18288)
		(layer "In4.Cu")
		(net "M_F_CPU1_SA_DQS_DP<8>")
	)
	(segment
		(start 173.270926 -283.021532)
		(end 172.992034 -282.74264)
		(width 0.18288)
		(layer "In4.Cu")
		(net "M_F_CPU1_SA_DQS_DP<8>")
	)
	(segment
		(start 176.374298 -283.436822)
		(end 176.005744 -283.589476)
		(width 0.18288)
		(layer "In4.Cu")
		(net "M_F_CPU1_SA_DQS_DP<8>")
	)
	(segment
		(start 169.587926 -274.892008)
		(end 168.755822 -274.547076)
		(width 0.18288)
		(layer "In4.Cu")
		(net "M_F_CPU1_SA_DQS_DP<8>")
	)
	(segment
		(start 172.585126 -282.74264)
		(end 172.30852 -283.019246)
		(width 0.18288)
		(layer "In4.Cu")
		(net "M_F_CPU1_SA_DQS_DP<8>")
	)
	(segment
		(start 170.439334 -280.757122)
		(end 170.439334 -277.705312)
		(width 0.18288)
		(layer "In4.Cu")
		(net "M_F_CPU1_SA_DQS_DP<8>")
	)
	(segment
		(start 158.74492 -270.4719)
		(end 158.538672 -270.265906)
		(width 0.18288)
		(layer "In4.Cu")
		(net "M_F_CPU1_SA_DQS_DP<8>")
	)
	(segment
		(start 172.674026 -282.742386)
		(end 172.674026 -282.74264)
		(width 0.18288)
		(layer "In4.Cu")
		(net "M_F_CPU1_SA_DQS_DP<8>")
	)
	(segment
		(start 171.485306 -282.882086)
		(end 171.202858 -282.599638)
		(width 0.18288)
		(layer "In4.Cu")
		(net "M_F_CPU1_SA_DQS_DP<8>")
	)
	(segment
		(start 138.785092 -259.99186)
		(end 138.533886 -259.99186)
		(width 0.088646)
		(layer "In4.Cu")
		(net "M_F_CPU1_SA_DQS_DP<8>")
	)
	(segment
		(start 137.419334 -259.948934)
		(end 137.407396 -259.941822)
		(width 0.088646)
		(layer "In4.Cu")
		(net "M_F_CPU1_SA_DQS_DP<8>")
	)
	(arc
		(start 136.456674 -259.935472)
		(mid 136.17875 -259.86584)
		(end 135.902446 -259.941568)
		(width 0.088646)
		(layer "In4.Cu")
		(net "M_F_CPU1_SA_DQS_DP<8>")
	)
	(arc
		(start 132.22986 -260.111494)
		(mid 132.114051 -260.223423)
		(end 132.05587 -260.373622)
		(width 0.088646)
		(layer "In4.Cu")
		(net "M_F_CPU1_SA_DQS_DP<8>")
	)
	(arc
		(start 134.0231 -259.941568)
		(mid 134.019934 -259.943362)
		(end 134.01675 -259.945124)
		(width 0.088646)
		(layer "In4.Cu")
		(net "M_F_CPU1_SA_DQS_DP<8>")
	)
	(arc
		(start 134.01675 -259.945124)
		(mid 133.836985 -259.991898)
		(end 133.656832 -259.946648)
		(width 0.088646)
		(layer "In4.Cu")
		(net "M_F_CPU1_SA_DQS_DP<8>")
	)
	(arc
		(start 135.52805 -259.941822)
		(mid 135.245377 -259.865851)
		(end 134.962646 -259.941568)
		(width 0.088646)
		(layer "In4.Cu")
		(net "M_F_CPU1_SA_DQS_DP<8>")
	)
	(arc
		(start 132.33908 -260.058408)
		(mid 132.314375 -260.071275)
		(end 132.288788 -260.082284)
		(width 0.088646)
		(layer "In4.Cu")
		(net "M_F_CPU1_SA_DQS_DP<8>")
	)
	(arc
		(start 137.407396 -259.941822)
		(mid 137.124723 -259.865851)
		(end 136.841992 -259.941568)
		(width 0.088646)
		(layer "In4.Cu")
		(net "M_F_CPU1_SA_DQS_DP<8>")
	)
	(arc
		(start 138.533886 -259.99186)
		(mid 138.436847 -259.979066)
		(end 138.346434 -259.941568)
		(width 0.088646)
		(layer "In4.Cu")
		(net "M_F_CPU1_SA_DQS_DP<8>")
	)
	(arc
		(start 134.588504 -259.941822)
		(mid 134.305831 -259.865851)
		(end 134.0231 -259.941568)
		(width 0.088646)
		(layer "In4.Cu")
		(net "M_F_CPU1_SA_DQS_DP<8>")
	)
	(arc
		(start 132.432044 -260.033516)
		(mid 132.38393 -260.039872)
		(end 132.33908 -260.058408)
		(width 0.088646)
		(layer "In4.Cu")
		(net "M_F_CPU1_SA_DQS_DP<8>")
	)
	(arc
		(start 134.962646 -259.941568)
		(mid 134.780424 -259.991768)
		(end 134.596886 -259.946648)
		(width 0.088646)
		(layer "In4.Cu")
		(net "M_F_CPU1_SA_DQS_DP<8>")
	)
	(arc
		(start 136.841992 -259.941568)
		(mid 136.661705 -259.99198)
		(end 136.479534 -259.948934)
		(width 0.088646)
		(layer "In4.Cu")
		(net "M_F_CPU1_SA_DQS_DP<8>")
	)
	(arc
		(start 137.781792 -259.941568)
		(mid 137.601505 -259.99198)
		(end 137.419334 -259.948934)
		(width 0.088646)
		(layer "In4.Cu")
		(net "M_F_CPU1_SA_DQS_DP<8>")
	)
	(arc
		(start 135.902446 -259.941568)
		(mid 135.722159 -259.99198)
		(end 135.539988 -259.948934)
		(width 0.088646)
		(layer "In4.Cu")
		(net "M_F_CPU1_SA_DQS_DP<8>")
	)
	(arc
		(start 133.64845 -259.941822)
		(mid 133.648069 -259.941568)
		(end 133.647688 -259.941314)
		(width 0.088646)
		(layer "In4.Cu")
		(net "M_F_CPU1_SA_DQS_DP<8>")
	)
	(arc
		(start 133.647688 -259.941568)
		(mid 133.365494 -259.866012)
		(end 133.0833 -259.941568)
		(width 0.088646)
		(layer "In4.Cu")
		(net "M_F_CPU1_SA_DQS_DP<8>")
	)
	(arc
		(start 138.346434 -259.941568)
		(mid 138.06424 -259.866012)
		(end 137.782046 -259.941568)
		(width 0.088646)
		(layer "In4.Cu")
		(net "M_F_CPU1_SA_DQS_DP<8>")
	)
	(arc
		(start 132.288788 -260.082284)
		(mid 132.263319 -260.093417)
		(end 132.23875 -260.106414)
		(width 0.088646)
		(layer "In4.Cu")
		(net "M_F_CPU1_SA_DQS_DP<8>")
	)
	(segment
		(start 184.708546 -292.784784)
		(end 184.976516 -292.516814)
		(width 0.20066)
		(layer "F.Cu")
		(net "M_F_CPU1_SA_DQS_DP<7>")
	)
	(segment
		(start 178.594512 -292.516814)
		(end 178.845464 -292.767766)
		(width 0.20066)
		(layer "F.Cu")
		(net "M_F_CPU1_SA_DQS_DP<7>")
	)
	(segment
		(start 180.434996 -292.091872)
		(end 182.447692 -292.091872)
		(width 0.1016)
		(layer "F.Cu")
		(net "M_F_CPU1_SA_DQS_DP<7>")
	)
	(segment
		(start 180.427884 -292.08476)
		(end 180.434996 -292.091872)
		(width 0.1016)
		(layer "F.Cu")
		(net "M_F_CPU1_SA_DQS_DP<7>")
	)
	(segment
		(start 134.775448 -267.755624)
		(end 134.775194 -267.755878)
		(width 0.20066)
		(layer "F.Cu")
		(net "M_F_CPU1_SA_DQS_DP<7>")
	)
	(segment
		(start 183.685434 -292.339268)
		(end 184.13095 -292.784784)
		(width 0.20066)
		(layer "F.Cu")
		(net "M_F_CPU1_SA_DQS_DP<7>")
	)
	(segment
		(start 134.775448 -267.219938)
		(end 134.775448 -267.755624)
		(width 0.20066)
		(layer "F.Cu")
		(net "M_F_CPU1_SA_DQS_DP<7>")
	)
	(segment
		(start 179.85359 -292.342824)
		(end 180.111654 -292.08476)
		(width 0.20066)
		(layer "F.Cu")
		(net "M_F_CPU1_SA_DQS_DP<7>")
	)
	(segment
		(start 182.455058 -292.084506)
		(end 182.77713 -292.084506)
		(width 0.20066)
		(layer "F.Cu")
		(net "M_F_CPU1_SA_DQS_DP<7>")
	)
	(segment
		(start 179.575206 -292.342824)
		(end 179.85359 -292.342824)
		(width 0.20066)
		(layer "F.Cu")
		(net "M_F_CPU1_SA_DQS_DP<7>")
	)
	(segment
		(start 178.000914 -292.516814)
		(end 178.594512 -292.516814)
		(width 0.20066)
		(layer "F.Cu")
		(net "M_F_CPU1_SA_DQS_DP<7>")
	)
	(segment
		(start 182.447692 -292.091872)
		(end 182.455058 -292.084506)
		(width 0.1016)
		(layer "F.Cu")
		(net "M_F_CPU1_SA_DQS_DP<7>")
	)
	(segment
		(start 178.845464 -292.767766)
		(end 179.150264 -292.767766)
		(width 0.20066)
		(layer "F.Cu")
		(net "M_F_CPU1_SA_DQS_DP<7>")
	)
	(segment
		(start 182.77713 -292.084506)
		(end 183.031892 -292.339268)
		(width 0.20066)
		(layer "F.Cu")
		(net "M_F_CPU1_SA_DQS_DP<7>")
	)
	(segment
		(start 184.13095 -292.784784)
		(end 184.708546 -292.784784)
		(width 0.20066)
		(layer "F.Cu")
		(net "M_F_CPU1_SA_DQS_DP<7>")
	)
	(segment
		(start 183.031892 -292.339268)
		(end 183.685434 -292.339268)
		(width 0.20066)
		(layer "F.Cu")
		(net "M_F_CPU1_SA_DQS_DP<7>")
	)
	(segment
		(start 180.423058 -292.08476)
		(end 180.427884 -292.08476)
		(width 0.101854)
		(layer "F.Cu")
		(net "M_F_CPU1_SA_DQS_DP<7>")
	)
	(segment
		(start 180.111654 -292.08476)
		(end 180.423058 -292.08476)
		(width 0.20066)
		(layer "F.Cu")
		(net "M_F_CPU1_SA_DQS_DP<7>")
	)
	(segment
		(start 179.150264 -292.767766)
		(end 179.575206 -292.342824)
		(width 0.20066)
		(layer "F.Cu")
		(net "M_F_CPU1_SA_DQS_DP<7>")
	)
	(segment
		(start 184.976516 -292.516814)
		(end 185.544714 -292.516814)
		(width 0.20066)
		(layer "F.Cu")
		(net "M_F_CPU1_SA_DQS_DP<7>")
	)
	(segment
		(start 176.896014 -292.51656)
		(end 178.00066 -292.51656)
		(width 0.20066)
		(layer "F.Cu")
		(net "M_F_CPU1_SA_DQS_DP<7>")
	)
	(segment
		(start 178.00066 -292.51656)
		(end 178.000914 -292.516814)
		(width 0.20066)
		(layer "F.Cu")
		(net "M_F_CPU1_SA_DQS_DP<7>")
	)
	(segment
		(start 150.993856 -274.02028)
		(end 150.998428 -274.017232)
		(width 0.18288)
		(layer "In2.Cu")
		(net "M_F_CPU1_SA_DQS_DP<7>")
	)
	(segment
		(start 139.770104 -267.274294)
		(end 139.756642 -267.266674)
		(width 0.088646)
		(layer "In2.Cu")
		(net "M_F_CPU1_SA_DQS_DP<7>")
	)
	(segment
		(start 159.968946 -283.578046)
		(end 159.940752 -283.549852)
		(width 0.16002)
		(layer "In2.Cu")
		(net "M_F_CPU1_SA_DQS_DP<7>")
	)
	(segment
		(start 156.253942 -280.665936)
		(end 151.982932 -276.394164)
		(width 0.18288)
		(layer "In2.Cu")
		(net "M_F_CPU1_SA_DQS_DP<7>")
	)
	(segment
		(start 167.291512 -285.945072)
		(end 167.11803 -285.77159)
		(width 0.18288)
		(layer "In2.Cu")
		(net "M_F_CPU1_SA_DQS_DP<7>")
	)
	(segment
		(start 159.740346 -283.349446)
		(end 159.712152 -283.321252)
		(width 0.16002)
		(layer "In2.Cu")
		(net "M_F_CPU1_SA_DQS_DP<7>")
	)
	(segment
		(start 135.527796 -267.43152)
		(end 135.518906 -267.4366)
		(width 0.088646)
		(layer "In2.Cu")
		(net "M_F_CPU1_SA_DQS_DP<7>")
	)
	(segment
		(start 164.48278 -286.402272)
		(end 164.20084 -286.120332)
		(width 0.18288)
		(layer "In2.Cu")
		(net "M_F_CPU1_SA_DQS_DP<7>")
	)
	(segment
		(start 135.344916 -267.698728)
		(end 135.287766 -267.755878)
		(width 0.088646)
		(layer "In2.Cu")
		(net "M_F_CPU1_SA_DQS_DP<7>")
	)
	(segment
		(start 174.75327 -292.621208)
		(end 174.138082 -292.3667)
		(width 0.18288)
		(layer "In2.Cu")
		(net "M_F_CPU1_SA_DQS_DP<7>")
	)
	(segment
		(start 138.816588 -267.266674)
		(end 138.816842 -267.265912)
		(width 0.088646)
		(layer "In2.Cu")
		(net "M_F_CPU1_SA_DQS_DP<7>")
	)
	(segment
		(start 175.60417 -292.982142)
		(end 175.228504 -292.982142)
		(width 0.18288)
		(layer "In2.Cu")
		(net "M_F_CPU1_SA_DQS_DP<7>")
	)
	(segment
		(start 157.740096 -282.739846)
		(end 157.327854 -282.739846)
		(width 0.18288)
		(layer "In2.Cu")
		(net "M_F_CPU1_SA_DQS_DP<7>")
	)
	(segment
		(start 172.284136 -292.355524)
		(end 171.893992 -292.355524)
		(width 0.18288)
		(layer "In2.Cu")
		(net "M_F_CPU1_SA_DQS_DP<7>")
	)
	(segment
		(start 167.520112 -286.173672)
		(end 167.503856 -286.173672)
		(width 0.16002)
		(layer "In2.Cu")
		(net "M_F_CPU1_SA_DQS_DP<7>")
	)
	(segment
		(start 139.771374 -267.275056)
		(end 139.770104 -267.274294)
		(width 0.088646)
		(layer "In2.Cu")
		(net "M_F_CPU1_SA_DQS_DP<7>")
	)
	(segment
		(start 140.840714 -267.48867)
		(end 140.34643 -267.48867)
		(width 0.088646)
		(layer "In2.Cu")
		(net "M_F_CPU1_SA_DQS_DP<7>")
	)
	(segment
		(start 170.66641 -291.499544)
		(end 169.869612 -291.361876)
		(width 0.18288)
		(layer "In2.Cu")
		(net "M_F_CPU1_SA_DQS_DP<7>")
	)
	(segment
		(start 173.307502 -292.3667)
		(end 173.032928 -292.092126)
		(width 0.18288)
		(layer "In2.Cu")
		(net "M_F_CPU1_SA_DQS_DP<7>")
	)
	(segment
		(start 159.407352 -283.016452)
		(end 158.016702 -283.016452)
		(width 0.18288)
		(layer "In2.Cu")
		(net "M_F_CPU1_SA_DQS_DP<7>")
	)
	(segment
		(start 160.390332 -283.999432)
		(end 159.968946 -283.578046)
		(width 0.18288)
		(layer "In2.Cu")
		(net "M_F_CPU1_SA_DQS_DP<7>")
	)
	(segment
		(start 157.327854 -282.739846)
		(end 157.062424 -283.005276)
		(width 0.18288)
		(layer "In2.Cu")
		(net "M_F_CPU1_SA_DQS_DP<7>")
	)
	(segment
		(start 163.543742 -286.309816)
		(end 162.698938 -286.309816)
		(width 0.18288)
		(layer "In2.Cu")
		(net "M_F_CPU1_SA_DQS_DP<7>")
	)
	(segment
		(start 167.319706 -285.989522)
		(end 167.319706 -285.973266)
		(width 0.16002)
		(layer "In2.Cu")
		(net "M_F_CPU1_SA_DQS_DP<7>")
	)
	(segment
		(start 167.548306 -286.201866)
		(end 167.520112 -286.173672)
		(width 0.16002)
		(layer "In2.Cu")
		(net "M_F_CPU1_SA_DQS_DP<7>")
	)
	(segment
		(start 176.705514 -292.70706)
		(end 176.268634 -292.70706)
		(width 0.18288)
		(layer "In2.Cu")
		(net "M_F_CPU1_SA_DQS_DP<7>")
	)
	(segment
		(start 142.685008 -267.42898)
		(end 140.900404 -267.42898)
		(width 0.18288)
		(layer "In2.Cu")
		(net "M_F_CPU1_SA_DQS_DP<7>")
	)
	(segment
		(start 165.187884 -286.20466)
		(end 165.171628 -286.20466)
		(width 0.16002)
		(layer "In2.Cu")
		(net "M_F_CPU1_SA_DQS_DP<7>")
	)
	(segment
		(start 174.138082 -292.3667)
		(end 173.307502 -292.3667)
		(width 0.18288)
		(layer "In2.Cu")
		(net "M_F_CPU1_SA_DQS_DP<7>")
	)
	(segment
		(start 139.771374 -267.27531)
		(end 139.771374 -267.275056)
		(width 0.088646)
		(layer "In2.Cu")
		(net "M_F_CPU1_SA_DQS_DP<7>")
	)
	(segment
		(start 150.94839 -273.946112)
		(end 148.389086 -271.386808)
		(width 0.18288)
		(layer "In2.Cu")
		(net "M_F_CPU1_SA_DQS_DP<7>")
	)
	(segment
		(start 164.20084 -286.120332)
		(end 163.733226 -286.120332)
		(width 0.18288)
		(layer "In2.Cu")
		(net "M_F_CPU1_SA_DQS_DP<7>")
	)
	(segment
		(start 158.016702 -283.016452)
		(end 157.740096 -282.739846)
		(width 0.18288)
		(layer "In2.Cu")
		(net "M_F_CPU1_SA_DQS_DP<7>")
	)
	(segment
		(start 135.688578 -267.342874)
		(end 135.656574 -267.365226)
		(width 0.088646)
		(layer "In2.Cu")
		(net "M_F_CPU1_SA_DQS_DP<7>")
	)
	(segment
		(start 167.11803 -285.77159)
		(end 165.604698 -285.77159)
		(width 0.18288)
		(layer "In2.Cu")
		(net "M_F_CPU1_SA_DQS_DP<7>")
	)
	(segment
		(start 157.062424 -283.005276)
		(end 156.97581 -283.005276)
		(width 0.18288)
		(layer "In2.Cu")
		(net "M_F_CPU1_SA_DQS_DP<7>")
	)
	(segment
		(start 159.712152 -283.321252)
		(end 159.407352 -283.016452)
		(width 0.18288)
		(layer "In2.Cu")
		(net "M_F_CPU1_SA_DQS_DP<7>")
	)
	(segment
		(start 169.072814 -289.489134)
		(end 169.072814 -288.823146)
		(width 0.18288)
		(layer "In2.Cu")
		(net "M_F_CPU1_SA_DQS_DP<7>")
	)
	(segment
		(start 140.194538 -267.336778)
		(end 139.98067 -267.336778)
		(width 0.088646)
		(layer "In2.Cu")
		(net "M_F_CPU1_SA_DQS_DP<7>")
	)
	(segment
		(start 169.869612 -291.361876)
		(end 169.217594 -290.826444)
		(width 0.18288)
		(layer "In2.Cu")
		(net "M_F_CPU1_SA_DQS_DP<7>")
	)
	(segment
		(start 156.712158 -282.741624)
		(end 156.712158 -281.771344)
		(width 0.18288)
		(layer "In2.Cu")
		(net "M_F_CPU1_SA_DQS_DP<7>")
	)
	(segment
		(start 146.981164 -271.386808)
		(end 143.262858 -267.668248)
		(width 0.18288)
		(layer "In2.Cu")
		(net "M_F_CPU1_SA_DQS_DP<7>")
	)
	(segment
		(start 167.319706 -285.973266)
		(end 167.291512 -285.945072)
		(width 0.16002)
		(layer "In2.Cu")
		(net "M_F_CPU1_SA_DQS_DP<7>")
	)
	(segment
		(start 163.733226 -286.120332)
		(end 163.543742 -286.309816)
		(width 0.18288)
		(layer "In2.Cu")
		(net "M_F_CPU1_SA_DQS_DP<7>")
	)
	(segment
		(start 156.712158 -281.771344)
		(end 156.253942 -280.665936)
		(width 0.18288)
		(layer "In2.Cu")
		(net "M_F_CPU1_SA_DQS_DP<7>")
	)
	(segment
		(start 168.297352 -286.950658)
		(end 167.548306 -286.201866)
		(width 0.18288)
		(layer "In2.Cu")
		(net "M_F_CPU1_SA_DQS_DP<7>")
	)
	(segment
		(start 172.547534 -292.092126)
		(end 172.284136 -292.355524)
		(width 0.18288)
		(layer "In2.Cu")
		(net "M_F_CPU1_SA_DQS_DP<7>")
	)
	(segment
		(start 165.400228 -285.97606)
		(end 165.372034 -286.004254)
		(width 0.16002)
		(layer "In2.Cu")
		(net "M_F_CPU1_SA_DQS_DP<7>")
	)
	(segment
		(start 164.974016 -286.402272)
		(end 164.48278 -286.402272)
		(width 0.18288)
		(layer "In2.Cu")
		(net "M_F_CPU1_SA_DQS_DP<7>")
	)
	(segment
		(start 165.171628 -286.20466)
		(end 165.143434 -286.232854)
		(width 0.16002)
		(layer "In2.Cu")
		(net "M_F_CPU1_SA_DQS_DP<7>")
	)
	(segment
		(start 150.998428 -274.017232)
		(end 150.94839 -273.946112)
		(width 0.18288)
		(layer "In2.Cu")
		(net "M_F_CPU1_SA_DQS_DP<7>")
	)
	(segment
		(start 135.287766 -267.755878)
		(end 134.775194 -267.755878)
		(width 0.088646)
		(layer "In2.Cu")
		(net "M_F_CPU1_SA_DQS_DP<7>")
	)
	(segment
		(start 140.34643 -267.48867)
		(end 140.194538 -267.336778)
		(width 0.088646)
		(layer "In2.Cu")
		(net "M_F_CPU1_SA_DQS_DP<7>")
	)
	(segment
		(start 175.033178 -292.901116)
		(end 174.75327 -292.621208)
		(width 0.18288)
		(layer "In2.Cu")
		(net "M_F_CPU1_SA_DQS_DP<7>")
	)
	(segment
		(start 136.113266 -267.335508)
		(end 135.711692 -267.335508)
		(width 0.088646)
		(layer "In2.Cu")
		(net "M_F_CPU1_SA_DQS_DP<7>")
	)
	(segment
		(start 168.868598 -289.98291)
		(end 169.072814 -289.489134)
		(width 0.18288)
		(layer "In2.Cu")
		(net "M_F_CPU1_SA_DQS_DP<7>")
	)
	(segment
		(start 175.228504 -292.982142)
		(end 175.033178 -292.901116)
		(width 0.18288)
		(layer "In2.Cu")
		(net "M_F_CPU1_SA_DQS_DP<7>")
	)
	(segment
		(start 169.217594 -290.826444)
		(end 168.868598 -289.98291)
		(width 0.18288)
		(layer "In2.Cu")
		(net "M_F_CPU1_SA_DQS_DP<7>")
	)
	(segment
		(start 176.268634 -292.70706)
		(end 175.60417 -292.982142)
		(width 0.18288)
		(layer "In2.Cu")
		(net "M_F_CPU1_SA_DQS_DP<7>")
	)
	(segment
		(start 148.389086 -271.386808)
		(end 146.981164 -271.386808)
		(width 0.18288)
		(layer "In2.Cu")
		(net "M_F_CPU1_SA_DQS_DP<7>")
	)
	(segment
		(start 165.143434 -286.232854)
		(end 164.974016 -286.402272)
		(width 0.18288)
		(layer "In2.Cu")
		(net "M_F_CPU1_SA_DQS_DP<7>")
	)
	(segment
		(start 176.896014 -292.51656)
		(end 176.705514 -292.70706)
		(width 0.18288)
		(layer "In2.Cu")
		(net "M_F_CPU1_SA_DQS_DP<7>")
	)
	(segment
		(start 140.900404 -267.42898)
		(end 140.840714 -267.48867)
		(width 0.088646)
		(layer "In2.Cu")
		(net "M_F_CPU1_SA_DQS_DP<7>")
	)
	(segment
		(start 151.964898 -276.37613)
		(end 150.993856 -274.02028)
		(width 0.18288)
		(layer "In2.Cu")
		(net "M_F_CPU1_SA_DQS_DP<7>")
	)
	(segment
		(start 169.072814 -288.823146)
		(end 168.297352 -286.950658)
		(width 0.18288)
		(layer "In2.Cu")
		(net "M_F_CPU1_SA_DQS_DP<7>")
	)
	(segment
		(start 171.301664 -291.76345)
		(end 170.66641 -291.499544)
		(width 0.18288)
		(layer "In2.Cu")
		(net "M_F_CPU1_SA_DQS_DP<7>")
	)
	(segment
		(start 151.982932 -276.394164)
		(end 151.964898 -276.37613)
		(width 0.18288)
		(layer "In2.Cu")
		(net "M_F_CPU1_SA_DQS_DP<7>")
	)
	(segment
		(start 167.503856 -286.173672)
		(end 167.319706 -285.989522)
		(width 0.16002)
		(layer "In2.Cu")
		(net "M_F_CPU1_SA_DQS_DP<7>")
	)
	(segment
		(start 171.893992 -292.355524)
		(end 171.301664 -291.76345)
		(width 0.18288)
		(layer "In2.Cu")
		(net "M_F_CPU1_SA_DQS_DP<7>")
	)
	(segment
		(start 162.698938 -286.309816)
		(end 162.074098 -286.05099)
		(width 0.18288)
		(layer "In2.Cu")
		(net "M_F_CPU1_SA_DQS_DP<7>")
	)
	(segment
		(start 173.032928 -292.092126)
		(end 172.547534 -292.092126)
		(width 0.18288)
		(layer "In2.Cu")
		(net "M_F_CPU1_SA_DQS_DP<7>")
	)
	(segment
		(start 165.372034 -286.004254)
		(end 165.372034 -286.02051)
		(width 0.16002)
		(layer "In2.Cu")
		(net "M_F_CPU1_SA_DQS_DP<7>")
	)
	(segment
		(start 165.604698 -285.77159)
		(end 165.400228 -285.97606)
		(width 0.18288)
		(layer "In2.Cu")
		(net "M_F_CPU1_SA_DQS_DP<7>")
	)
	(segment
		(start 165.372034 -286.02051)
		(end 165.187884 -286.20466)
		(width 0.16002)
		(layer "In2.Cu")
		(net "M_F_CPU1_SA_DQS_DP<7>")
	)
	(segment
		(start 159.740346 -283.365702)
		(end 159.740346 -283.349446)
		(width 0.16002)
		(layer "In2.Cu")
		(net "M_F_CPU1_SA_DQS_DP<7>")
	)
	(segment
		(start 156.97581 -283.005276)
		(end 156.712158 -282.741624)
		(width 0.18288)
		(layer "In2.Cu")
		(net "M_F_CPU1_SA_DQS_DP<7>")
	)
	(segment
		(start 159.940752 -283.549852)
		(end 159.924496 -283.549852)
		(width 0.16002)
		(layer "In2.Cu")
		(net "M_F_CPU1_SA_DQS_DP<7>")
	)
	(segment
		(start 159.924496 -283.549852)
		(end 159.740346 -283.365702)
		(width 0.16002)
		(layer "In2.Cu")
		(net "M_F_CPU1_SA_DQS_DP<7>")
	)
	(segment
		(start 143.262858 -267.668248)
		(end 142.685008 -267.42898)
		(width 0.18288)
		(layer "In2.Cu")
		(net "M_F_CPU1_SA_DQS_DP<7>")
	)
	(segment
		(start 162.074098 -286.05099)
		(end 160.390332 -283.999432)
		(width 0.18288)
		(layer "In2.Cu")
		(net "M_F_CPU1_SA_DQS_DP<7>")
	)
	(arc
		(start 136.372092 -267.266166)
		(mid 136.24724 -267.317854)
		(end 136.113266 -267.335508)
		(width 0.088646)
		(layer "In2.Cu")
		(net "M_F_CPU1_SA_DQS_DP<7>")
	)
	(arc
		(start 136.937496 -267.266166)
		(mid 136.654794 -267.190424)
		(end 136.372092 -267.266166)
		(width 0.088646)
		(layer "In2.Cu")
		(net "M_F_CPU1_SA_DQS_DP<7>")
	)
	(arc
		(start 135.656574 -267.365226)
		(mid 135.618468 -267.38867)
		(end 135.577834 -267.40739)
		(width 0.088646)
		(layer "In2.Cu")
		(net "M_F_CPU1_SA_DQS_DP<7>")
	)
	(arc
		(start 137.877296 -267.266166)
		(mid 137.594594 -267.190424)
		(end 137.311892 -267.266166)
		(width 0.088646)
		(layer "In2.Cu")
		(net "M_F_CPU1_SA_DQS_DP<7>")
	)
	(arc
		(start 135.711692 -267.335508)
		(mid 135.699577 -267.337435)
		(end 135.688578 -267.342874)
		(width 0.088646)
		(layer "In2.Cu")
		(net "M_F_CPU1_SA_DQS_DP<7>")
	)
	(arc
		(start 137.311892 -267.266166)
		(mid 137.124694 -267.316309)
		(end 136.937496 -267.266166)
		(width 0.088646)
		(layer "In2.Cu")
		(net "M_F_CPU1_SA_DQS_DP<7>")
	)
	(arc
		(start 138.816842 -267.265912)
		(mid 138.534221 -267.190331)
		(end 138.251692 -267.266166)
		(width 0.088646)
		(layer "In2.Cu")
		(net "M_F_CPU1_SA_DQS_DP<7>")
	)
	(arc
		(start 139.892532 -267.325602)
		(mid 139.830267 -267.304516)
		(end 139.771374 -267.27531)
		(width 0.088646)
		(layer "In2.Cu")
		(net "M_F_CPU1_SA_DQS_DP<7>")
	)
	(arc
		(start 139.98067 -267.336778)
		(mid 139.93624 -267.334037)
		(end 139.892532 -267.325602)
		(width 0.088646)
		(layer "In2.Cu")
		(net "M_F_CPU1_SA_DQS_DP<7>")
	)
	(arc
		(start 139.756642 -267.266674)
		(mid 139.474338 -267.191118)
		(end 139.192 -267.266674)
		(width 0.088646)
		(layer "In2.Cu")
		(net "M_F_CPU1_SA_DQS_DP<7>")
	)
	(arc
		(start 135.577834 -267.40739)
		(mid 135.552365 -267.418523)
		(end 135.527796 -267.43152)
		(width 0.088646)
		(layer "In2.Cu")
		(net "M_F_CPU1_SA_DQS_DP<7>")
	)
	(arc
		(start 135.518906 -267.4366)
		(mid 135.403097 -267.548529)
		(end 135.344916 -267.698728)
		(width 0.088646)
		(layer "In2.Cu")
		(net "M_F_CPU1_SA_DQS_DP<7>")
	)
	(arc
		(start 139.192 -267.266674)
		(mid 139.004294 -267.317003)
		(end 138.816588 -267.266674)
		(width 0.088646)
		(layer "In2.Cu")
		(net "M_F_CPU1_SA_DQS_DP<7>")
	)
	(arc
		(start 138.251692 -267.266166)
		(mid 138.064494 -267.316309)
		(end 137.877296 -267.266166)
		(width 0.088646)
		(layer "In2.Cu")
		(net "M_F_CPU1_SA_DQS_DP<7>")
	)
	(segment
		(start 178.594512 -301.866808)
		(end 178.845464 -302.11776)
		(width 0.20066)
		(layer "F.Cu")
		(net "M_F_CPU1_SA_DQS_DP<6>")
	)
	(segment
		(start 131.485894 -269.66164)
		(end 131.486148 -270.167862)
		(width 0.20066)
		(layer "F.Cu")
		(net "M_F_CPU1_SA_DQS_DP<6>")
	)
	(segment
		(start 131.486148 -270.167862)
		(end 131.486148 -270.19758)
		(width 0.20066)
		(layer "F.Cu")
		(net "M_F_CPU1_SA_DQS_DP<6>")
	)
	(segment
		(start 182.77713 -301.4345)
		(end 183.031892 -301.689262)
		(width 0.20066)
		(layer "F.Cu")
		(net "M_F_CPU1_SA_DQS_DP<6>")
	)
	(segment
		(start 179.150264 -302.11776)
		(end 179.575206 -301.692818)
		(width 0.20066)
		(layer "F.Cu")
		(net "M_F_CPU1_SA_DQS_DP<6>")
	)
	(segment
		(start 178.845464 -302.11776)
		(end 179.150264 -302.11776)
		(width 0.20066)
		(layer "F.Cu")
		(net "M_F_CPU1_SA_DQS_DP<6>")
	)
	(segment
		(start 176.896014 -301.866554)
		(end 178.00066 -301.866554)
		(width 0.20066)
		(layer "F.Cu")
		(net "M_F_CPU1_SA_DQS_DP<6>")
	)
	(segment
		(start 180.427884 -301.434754)
		(end 180.434996 -301.441866)
		(width 0.1016)
		(layer "F.Cu")
		(net "M_F_CPU1_SA_DQS_DP<6>")
	)
	(segment
		(start 183.685434 -301.689262)
		(end 184.13095 -302.134778)
		(width 0.20066)
		(layer "F.Cu")
		(net "M_F_CPU1_SA_DQS_DP<6>")
	)
	(segment
		(start 179.575206 -301.692818)
		(end 179.85359 -301.692818)
		(width 0.20066)
		(layer "F.Cu")
		(net "M_F_CPU1_SA_DQS_DP<6>")
	)
	(segment
		(start 184.13095 -302.134778)
		(end 184.708546 -302.134778)
		(width 0.20066)
		(layer "F.Cu")
		(net "M_F_CPU1_SA_DQS_DP<6>")
	)
	(segment
		(start 178.00066 -301.866554)
		(end 178.000914 -301.866808)
		(width 0.20066)
		(layer "F.Cu")
		(net "M_F_CPU1_SA_DQS_DP<6>")
	)
	(segment
		(start 184.708546 -302.134778)
		(end 184.976516 -301.866808)
		(width 0.20066)
		(layer "F.Cu")
		(net "M_F_CPU1_SA_DQS_DP<6>")
	)
	(segment
		(start 180.423058 -301.434754)
		(end 180.427884 -301.434754)
		(width 0.101854)
		(layer "F.Cu")
		(net "M_F_CPU1_SA_DQS_DP<6>")
	)
	(segment
		(start 180.434996 -301.441866)
		(end 182.447692 -301.441866)
		(width 0.1016)
		(layer "F.Cu")
		(net "M_F_CPU1_SA_DQS_DP<6>")
	)
	(segment
		(start 183.031892 -301.689262)
		(end 183.685434 -301.689262)
		(width 0.20066)
		(layer "F.Cu")
		(net "M_F_CPU1_SA_DQS_DP<6>")
	)
	(segment
		(start 182.455058 -301.4345)
		(end 182.77713 -301.4345)
		(width 0.20066)
		(layer "F.Cu")
		(net "M_F_CPU1_SA_DQS_DP<6>")
	)
	(segment
		(start 179.85359 -301.692818)
		(end 180.111654 -301.434754)
		(width 0.20066)
		(layer "F.Cu")
		(net "M_F_CPU1_SA_DQS_DP<6>")
	)
	(segment
		(start 184.976516 -301.866808)
		(end 185.544714 -301.866808)
		(width 0.20066)
		(layer "F.Cu")
		(net "M_F_CPU1_SA_DQS_DP<6>")
	)
	(segment
		(start 182.447692 -301.441866)
		(end 182.455058 -301.4345)
		(width 0.1016)
		(layer "F.Cu")
		(net "M_F_CPU1_SA_DQS_DP<6>")
	)
	(segment
		(start 178.000914 -301.866808)
		(end 178.594512 -301.866808)
		(width 0.20066)
		(layer "F.Cu")
		(net "M_F_CPU1_SA_DQS_DP<6>")
	)
	(segment
		(start 180.111654 -301.434754)
		(end 180.423058 -301.434754)
		(width 0.20066)
		(layer "F.Cu")
		(net "M_F_CPU1_SA_DQS_DP<6>")
	)
	(segment
		(start 163.274502 -297.953684)
		(end 162.519106 -297.198542)
		(width 0.18288)
		(layer "In4.Cu")
		(net "M_F_CPU1_SA_DQS_DP<6>")
	)
	(segment
		(start 160.2994 -295.810432)
		(end 159.318706 -295.229534)
		(width 0.18288)
		(layer "In4.Cu")
		(net "M_F_CPU1_SA_DQS_DP<6>")
	)
	(segment
		(start 140.488924 -271.535906)
		(end 140.404596 -271.535906)
		(width 0.088646)
		(layer "In4.Cu")
		(net "M_F_CPU1_SA_DQS_DP<6>")
	)
	(segment
		(start 139.460986 -270.846804)
		(end 139.384278 -270.82115)
		(width 0.088646)
		(layer "In4.Cu")
		(net "M_F_CPU1_SA_DQS_DP<6>")
	)
	(segment
		(start 156.58592 -293.734744)
		(end 153.636472 -290.785296)
		(width 0.18288)
		(layer "In4.Cu")
		(net "M_F_CPU1_SA_DQS_DP<6>")
	)
	(segment
		(start 168.643808 -301.985426)
		(end 167.83177 -301.173388)
		(width 0.18288)
		(layer "In4.Cu")
		(net "M_F_CPU1_SA_DQS_DP<6>")
	)
	(segment
		(start 176.896014 -301.866554)
		(end 176.650904 -302.111664)
		(width 0.18288)
		(layer "In4.Cu")
		(net "M_F_CPU1_SA_DQS_DP<6>")
	)
	(segment
		(start 172.076618 -301.686976)
		(end 171.778168 -301.985426)
		(width 0.18288)
		(layer "In4.Cu")
		(net "M_F_CPU1_SA_DQS_DP<6>")
	)
	(segment
		(start 148.76272 -279.013412)
		(end 143.172942 -273.423634)
		(width 0.18288)
		(layer "In4.Cu")
		(net "M_F_CPU1_SA_DQS_DP<6>")
	)
	(segment
		(start 131.99872 -270.19758)
		(end 131.486148 -270.19758)
		(width 0.088646)
		(layer "In4.Cu")
		(net "M_F_CPU1_SA_DQS_DP<6>")
	)
	(segment
		(start 171.778168 -301.985426)
		(end 168.643808 -301.985426)
		(width 0.18288)
		(layer "In4.Cu")
		(net "M_F_CPU1_SA_DQS_DP<6>")
	)
	(segment
		(start 172.317664 -301.686976)
		(end 172.076618 -301.686976)
		(width 0.18288)
		(layer "In4.Cu")
		(net "M_F_CPU1_SA_DQS_DP<6>")
	)
	(segment
		(start 159.318706 -295.229534)
		(end 158.189168 -294.48633)
		(width 0.18288)
		(layer "In4.Cu")
		(net "M_F_CPU1_SA_DQS_DP<6>")
	)
	(segment
		(start 173.522132 -301.71644)
		(end 173.287944 -301.71644)
		(width 0.18288)
		(layer "In4.Cu")
		(net "M_F_CPU1_SA_DQS_DP<6>")
	)
	(segment
		(start 143.172942 -273.423634)
		(end 142.376652 -273.423634)
		(width 0.18288)
		(layer "In4.Cu")
		(net "M_F_CPU1_SA_DQS_DP<6>")
	)
	(segment
		(start 173.013878 -301.442374)
		(end 172.562266 -301.442374)
		(width 0.18288)
		(layer "In4.Cu")
		(net "M_F_CPU1_SA_DQS_DP<6>")
	)
	(segment
		(start 176.650904 -302.111664)
		(end 176.163478 -302.111664)
		(width 0.18288)
		(layer "In4.Cu")
		(net "M_F_CPU1_SA_DQS_DP<6>")
	)
	(segment
		(start 135.527796 -269.707868)
		(end 135.527796 -269.708122)
		(width 0.088646)
		(layer "In4.Cu")
		(net "M_F_CPU1_SA_DQS_DP<6>")
	)
	(segment
		(start 133.083046 -269.708376)
		(end 133.011672 -269.749778)
		(width 0.088646)
		(layer "In4.Cu")
		(net "M_F_CPU1_SA_DQS_DP<6>")
	)
	(segment
		(start 163.68776 -298.366942)
		(end 163.274502 -297.953938)
		(width 0.18288)
		(layer "In4.Cu")
		(net "M_F_CPU1_SA_DQS_DP<6>")
	)
	(segment
		(start 134.967218 -269.705328)
		(end 134.962646 -269.708122)
		(width 0.088646)
		(layer "In4.Cu")
		(net "M_F_CPU1_SA_DQS_DP<6>")
	)
	(segment
		(start 163.274502 -297.953938)
		(end 163.274502 -297.953684)
		(width 0.18288)
		(layer "In4.Cu")
		(net "M_F_CPU1_SA_DQS_DP<6>")
	)
	(segment
		(start 140.505434 -271.552416)
		(end 140.488924 -271.535906)
		(width 0.088646)
		(layer "In4.Cu")
		(net "M_F_CPU1_SA_DQS_DP<6>")
	)
	(segment
		(start 162.053016 -296.732452)
		(end 160.2994 -295.810432)
		(width 0.18288)
		(layer "In4.Cu")
		(net "M_F_CPU1_SA_DQS_DP<6>")
	)
	(segment
		(start 167.83177 -301.173388)
		(end 167.203882 -300.913038)
		(width 0.18288)
		(layer "In4.Cu")
		(net "M_F_CPU1_SA_DQS_DP<6>")
	)
	(segment
		(start 138.9888 -270.665956)
		(end 138.93419 -270.611092)
		(width 0.088646)
		(layer "In4.Cu")
		(net "M_F_CPU1_SA_DQS_DP<6>")
	)
	(segment
		(start 174.916338 -302.294036)
		(end 173.522132 -301.71644)
		(width 0.18288)
		(layer "In4.Cu")
		(net "M_F_CPU1_SA_DQS_DP<6>")
	)
	(segment
		(start 162.519106 -297.198542)
		(end 162.053016 -296.732452)
		(width 0.18288)
		(layer "In4.Cu")
		(net "M_F_CPU1_SA_DQS_DP<6>")
	)
	(segment
		(start 176.163478 -302.111664)
		(end 175.72228 -302.294036)
		(width 0.18288)
		(layer "In4.Cu")
		(net "M_F_CPU1_SA_DQS_DP<6>")
	)
	(segment
		(start 175.72228 -302.294036)
		(end 174.916338 -302.294036)
		(width 0.18288)
		(layer "In4.Cu")
		(net "M_F_CPU1_SA_DQS_DP<6>")
	)
	(segment
		(start 132.05587 -270.14043)
		(end 131.99872 -270.19758)
		(width 0.088646)
		(layer "In4.Cu")
		(net "M_F_CPU1_SA_DQS_DP<6>")
	)
	(segment
		(start 136.467596 -269.707868)
		(end 136.452864 -269.699232)
		(width 0.088646)
		(layer "In4.Cu")
		(net "M_F_CPU1_SA_DQS_DP<6>")
	)
	(segment
		(start 158.189168 -294.48633)
		(end 156.58592 -293.734744)
		(width 0.18288)
		(layer "In4.Cu")
		(net "M_F_CPU1_SA_DQS_DP<6>")
	)
	(segment
		(start 139.384278 -270.82115)
		(end 138.9888 -270.665956)
		(width 0.088646)
		(layer "In4.Cu")
		(net "M_F_CPU1_SA_DQS_DP<6>")
	)
	(segment
		(start 137.407396 -269.707868)
		(end 137.392664 -269.699232)
		(width 0.088646)
		(layer "In4.Cu")
		(net "M_F_CPU1_SA_DQS_DP<6>")
	)
	(segment
		(start 172.562266 -301.442374)
		(end 172.317664 -301.686976)
		(width 0.18288)
		(layer "In4.Cu")
		(net "M_F_CPU1_SA_DQS_DP<6>")
	)
	(segment
		(start 134.962646 -269.708122)
		(end 134.958074 -269.710662)
		(width 0.088646)
		(layer "In4.Cu")
		(net "M_F_CPU1_SA_DQS_DP<6>")
	)
	(segment
		(start 173.287944 -301.71644)
		(end 173.013878 -301.442374)
		(width 0.18288)
		(layer "In4.Cu")
		(net "M_F_CPU1_SA_DQS_DP<6>")
	)
	(segment
		(start 133.648196 -269.707868)
		(end 133.647942 -269.708122)
		(width 0.088646)
		(layer "In4.Cu")
		(net "M_F_CPU1_SA_DQS_DP<6>")
	)
	(segment
		(start 153.636472 -290.785296)
		(end 148.76272 -279.013412)
		(width 0.18288)
		(layer "In4.Cu")
		(net "M_F_CPU1_SA_DQS_DP<6>")
	)
	(segment
		(start 142.376652 -273.423634)
		(end 140.505434 -271.552416)
		(width 0.18288)
		(layer "In4.Cu")
		(net "M_F_CPU1_SA_DQS_DP<6>")
	)
	(segment
		(start 165.344094 -299.05325)
		(end 163.68776 -298.366942)
		(width 0.18288)
		(layer "In4.Cu")
		(net "M_F_CPU1_SA_DQS_DP<6>")
	)
	(segment
		(start 139.715494 -270.846804)
		(end 139.460986 -270.846804)
		(width 0.088646)
		(layer "In4.Cu")
		(net "M_F_CPU1_SA_DQS_DP<6>")
	)
	(segment
		(start 138.81735 -270.521938)
		(end 138.80846 -270.516858)
		(width 0.088646)
		(layer "In4.Cu")
		(net "M_F_CPU1_SA_DQS_DP<6>")
	)
	(segment
		(start 140.404596 -271.535906)
		(end 139.715494 -270.846804)
		(width 0.088646)
		(layer "In4.Cu")
		(net "M_F_CPU1_SA_DQS_DP<6>")
	)
	(segment
		(start 132.822442 -269.800324)
		(end 132.432044 -269.800324)
		(width 0.088646)
		(layer "In4.Cu")
		(net "M_F_CPU1_SA_DQS_DP<6>")
	)
	(segment
		(start 138.629898 -270.19758)
		(end 138.629898 -270.183356)
		(width 0.088646)
		(layer "In4.Cu")
		(net "M_F_CPU1_SA_DQS_DP<6>")
	)
	(segment
		(start 134.030212 -269.703804)
		(end 134.022592 -269.707868)
		(width 0.088646)
		(layer "In4.Cu")
		(net "M_F_CPU1_SA_DQS_DP<6>")
	)
	(segment
		(start 167.203882 -300.913038)
		(end 165.344094 -299.05325)
		(width 0.18288)
		(layer "In4.Cu")
		(net "M_F_CPU1_SA_DQS_DP<6>")
	)
	(arc
		(start 133.011672 -269.749778)
		(mid 132.92038 -269.787484)
		(end 132.822442 -269.800324)
		(width 0.088646)
		(layer "In4.Cu")
		(net "M_F_CPU1_SA_DQS_DP<6>")
	)
	(arc
		(start 137.781792 -269.707868)
		(mid 137.594594 -269.758011)
		(end 137.407396 -269.707868)
		(width 0.088646)
		(layer "In4.Cu")
		(net "M_F_CPU1_SA_DQS_DP<6>")
	)
	(arc
		(start 138.898884 -270.579088)
		(mid 138.859377 -270.548715)
		(end 138.81735 -270.521938)
		(width 0.088646)
		(layer "In4.Cu")
		(net "M_F_CPU1_SA_DQS_DP<6>")
	)
	(arc
		(start 136.452864 -269.699232)
		(mid 136.176423 -269.632066)
		(end 135.902192 -269.707868)
		(width 0.088646)
		(layer "In4.Cu")
		(net "M_F_CPU1_SA_DQS_DP<6>")
	)
	(arc
		(start 133.647942 -269.708122)
		(mid 133.365465 -269.6326)
		(end 133.083046 -269.708376)
		(width 0.088646)
		(layer "In4.Cu")
		(net "M_F_CPU1_SA_DQS_DP<6>")
	)
	(arc
		(start 135.902192 -269.707868)
		(mid 135.714994 -269.758011)
		(end 135.527796 -269.707868)
		(width 0.088646)
		(layer "In4.Cu")
		(net "M_F_CPU1_SA_DQS_DP<6>")
	)
	(arc
		(start 134.958074 -269.710662)
		(mid 134.772689 -269.7583)
		(end 134.587996 -269.708122)
		(width 0.088646)
		(layer "In4.Cu")
		(net "M_F_CPU1_SA_DQS_DP<6>")
	)
	(arc
		(start 135.527796 -269.708122)
		(mid 135.247882 -269.632353)
		(end 134.967218 -269.705328)
		(width 0.088646)
		(layer "In4.Cu")
		(net "M_F_CPU1_SA_DQS_DP<6>")
	)
	(arc
		(start 132.288788 -269.849092)
		(mid 132.133455 -269.96369)
		(end 132.05587 -270.14043)
		(width 0.088646)
		(layer "In4.Cu")
		(net "M_F_CPU1_SA_DQS_DP<6>")
	)
	(arc
		(start 132.33908 -269.825216)
		(mid 132.314375 -269.838083)
		(end 132.288788 -269.849092)
		(width 0.088646)
		(layer "In4.Cu")
		(net "M_F_CPU1_SA_DQS_DP<6>")
	)
	(arc
		(start 138.629898 -270.183356)
		(mid 138.341116 -269.70426)
		(end 137.781792 -269.707868)
		(width 0.088646)
		(layer "In4.Cu")
		(net "M_F_CPU1_SA_DQS_DP<6>")
	)
	(arc
		(start 132.432044 -269.800324)
		(mid 132.38393 -269.80668)
		(end 132.33908 -269.825216)
		(width 0.088646)
		(layer "In4.Cu")
		(net "M_F_CPU1_SA_DQS_DP<6>")
	)
	(arc
		(start 134.587996 -269.708122)
		(mid 134.309673 -269.632363)
		(end 134.030212 -269.703804)
		(width 0.088646)
		(layer "In4.Cu")
		(net "M_F_CPU1_SA_DQS_DP<6>")
	)
	(arc
		(start 138.93419 -270.611092)
		(mid 138.916872 -270.59472)
		(end 138.898884 -270.579088)
		(width 0.088646)
		(layer "In4.Cu")
		(net "M_F_CPU1_SA_DQS_DP<6>")
	)
	(arc
		(start 138.80846 -270.516858)
		(mid 138.677546 -270.380498)
		(end 138.629898 -270.19758)
		(width 0.088646)
		(layer "In4.Cu")
		(net "M_F_CPU1_SA_DQS_DP<6>")
	)
	(arc
		(start 136.841992 -269.707868)
		(mid 136.654794 -269.758011)
		(end 136.467596 -269.707868)
		(width 0.088646)
		(layer "In4.Cu")
		(net "M_F_CPU1_SA_DQS_DP<6>")
	)
	(arc
		(start 137.392664 -269.699232)
		(mid 137.116223 -269.632066)
		(end 136.841992 -269.707868)
		(width 0.088646)
		(layer "In4.Cu")
		(net "M_F_CPU1_SA_DQS_DP<6>")
	)
	(arc
		(start 134.022592 -269.707868)
		(mid 133.835394 -269.758011)
		(end 133.648196 -269.707868)
		(width 0.088646)
		(layer "In4.Cu")
		(net "M_F_CPU1_SA_DQS_DP<6>")
	)
	(segment
		(start 182.447692 -310.79186)
		(end 182.455058 -310.784494)
		(width 0.1016)
		(layer "F.Cu")
		(net "M_F_CPU1_SA_DQS_DP<5>")
	)
	(segment
		(start 183.031892 -311.039256)
		(end 183.685434 -311.039256)
		(width 0.20066)
		(layer "F.Cu")
		(net "M_F_CPU1_SA_DQS_DP<5>")
	)
	(segment
		(start 182.77713 -310.784494)
		(end 183.031892 -311.039256)
		(width 0.20066)
		(layer "F.Cu")
		(net "M_F_CPU1_SA_DQS_DP<5>")
	)
	(segment
		(start 183.685434 -311.039256)
		(end 184.13095 -311.484772)
		(width 0.20066)
		(layer "F.Cu")
		(net "M_F_CPU1_SA_DQS_DP<5>")
	)
	(segment
		(start 176.896268 -311.216802)
		(end 178.000914 -311.216802)
		(width 0.20066)
		(layer "F.Cu")
		(net "M_F_CPU1_SA_DQS_DP<5>")
	)
	(segment
		(start 178.594512 -311.216802)
		(end 178.845464 -311.467754)
		(width 0.20066)
		(layer "F.Cu")
		(net "M_F_CPU1_SA_DQS_DP<5>")
	)
	(segment
		(start 184.13095 -311.484772)
		(end 184.708546 -311.484772)
		(width 0.20066)
		(layer "F.Cu")
		(net "M_F_CPU1_SA_DQS_DP<5>")
	)
	(segment
		(start 184.708546 -311.484772)
		(end 184.976516 -311.216802)
		(width 0.20066)
		(layer "F.Cu")
		(net "M_F_CPU1_SA_DQS_DP<5>")
	)
	(segment
		(start 182.455058 -310.784494)
		(end 182.77713 -310.784494)
		(width 0.20066)
		(layer "F.Cu")
		(net "M_F_CPU1_SA_DQS_DP<5>")
	)
	(segment
		(start 180.434996 -310.79186)
		(end 182.447692 -310.79186)
		(width 0.1016)
		(layer "F.Cu")
		(net "M_F_CPU1_SA_DQS_DP<5>")
	)
	(segment
		(start 134.775448 -277.522178)
		(end 134.775194 -277.522432)
		(width 0.20066)
		(layer "F.Cu")
		(net "M_F_CPU1_SA_DQS_DP<5>")
	)
	(segment
		(start 180.423058 -310.784748)
		(end 180.427884 -310.784748)
		(width 0.101854)
		(layer "F.Cu")
		(net "M_F_CPU1_SA_DQS_DP<5>")
	)
	(segment
		(start 134.775448 -276.986492)
		(end 134.775448 -277.522178)
		(width 0.20066)
		(layer "F.Cu")
		(net "M_F_CPU1_SA_DQS_DP<5>")
	)
	(segment
		(start 180.111654 -310.784748)
		(end 180.423058 -310.784748)
		(width 0.20066)
		(layer "F.Cu")
		(net "M_F_CPU1_SA_DQS_DP<5>")
	)
	(segment
		(start 179.85359 -311.042812)
		(end 180.111654 -310.784748)
		(width 0.20066)
		(layer "F.Cu")
		(net "M_F_CPU1_SA_DQS_DP<5>")
	)
	(segment
		(start 178.845464 -311.467754)
		(end 179.150264 -311.467754)
		(width 0.20066)
		(layer "F.Cu")
		(net "M_F_CPU1_SA_DQS_DP<5>")
	)
	(segment
		(start 179.575206 -311.042812)
		(end 179.85359 -311.042812)
		(width 0.20066)
		(layer "F.Cu")
		(net "M_F_CPU1_SA_DQS_DP<5>")
	)
	(segment
		(start 179.150264 -311.467754)
		(end 179.575206 -311.042812)
		(width 0.20066)
		(layer "F.Cu")
		(net "M_F_CPU1_SA_DQS_DP<5>")
	)
	(segment
		(start 176.896014 -311.216548)
		(end 176.896268 -311.216802)
		(width 0.20066)
		(layer "F.Cu")
		(net "M_F_CPU1_SA_DQS_DP<5>")
	)
	(segment
		(start 184.976516 -311.216802)
		(end 185.544714 -311.216802)
		(width 0.20066)
		(layer "F.Cu")
		(net "M_F_CPU1_SA_DQS_DP<5>")
	)
	(segment
		(start 180.427884 -310.784748)
		(end 180.434996 -310.79186)
		(width 0.1016)
		(layer "F.Cu")
		(net "M_F_CPU1_SA_DQS_DP<5>")
	)
	(segment
		(start 178.000914 -311.216802)
		(end 178.594512 -311.216802)
		(width 0.20066)
		(layer "F.Cu")
		(net "M_F_CPU1_SA_DQS_DP<5>")
	)
	(segment
		(start 136.467596 -277.84679)
		(end 136.405112 -277.810722)
		(width 0.088646)
		(layer "In2.Cu")
		(net "M_F_CPU1_SA_DQS_DP<5>")
	)
	(segment
		(start 161.705544 -310.826658)
		(end 161.191194 -311.039764)
		(width 0.18288)
		(layer "In2.Cu")
		(net "M_F_CPU1_SA_DQS_DP<5>")
	)
	(segment
		(start 175.065182 -311.67832)
		(end 175.049434 -311.67832)
		(width 0.16002)
		(layer "In2.Cu")
		(net "M_F_CPU1_SA_DQS_DP<5>")
	)
	(segment
		(start 163.684458 -310.40959)
		(end 162.122866 -310.40959)
		(width 0.18288)
		(layer "In2.Cu")
		(net "M_F_CPU1_SA_DQS_DP<5>")
	)
	(segment
		(start 176.605692 -311.50687)
		(end 176.326038 -311.50687)
		(width 0.18288)
		(layer "In2.Cu")
		(net "M_F_CPU1_SA_DQS_DP<5>")
	)
	(segment
		(start 147.619466 -294.383206)
		(end 144.851374 -291.615114)
		(width 0.18288)
		(layer "In2.Cu")
		(net "M_F_CPU1_SA_DQS_DP<5>")
	)
	(segment
		(start 171.898056 -311.067704)
		(end 171.31157 -310.481218)
		(width 0.18288)
		(layer "In2.Cu")
		(net "M_F_CPU1_SA_DQS_DP<5>")
	)
	(segment
		(start 163.86937 -310.594502)
		(end 163.841176 -310.566308)
		(width 0.16002)
		(layer "In2.Cu")
		(net "M_F_CPU1_SA_DQS_DP<5>")
	)
	(segment
		(start 139.677902 -277.771098)
		(end 139.003786 -277.771098)
		(width 0.088646)
		(layer "In2.Cu")
		(net "M_F_CPU1_SA_DQS_DP<5>")
	)
	(segment
		(start 135.450326 -277.257256)
		(end 135.18515 -277.522432)
		(width 0.088646)
		(layer "In2.Cu")
		(net "M_F_CPU1_SA_DQS_DP<5>")
	)
	(segment
		(start 164.069776 -310.794908)
		(end 164.05352 -310.794908)
		(width 0.16002)
		(layer "In2.Cu")
		(net "M_F_CPU1_SA_DQS_DP<5>")
	)
	(segment
		(start 164.09797 -310.823102)
		(end 164.069776 -310.794908)
		(width 0.16002)
		(layer "In2.Cu")
		(net "M_F_CPU1_SA_DQS_DP<5>")
	)
	(segment
		(start 165.27526 -310.744108)
		(end 164.90315 -310.744108)
		(width 0.18288)
		(layer "In2.Cu")
		(net "M_F_CPU1_SA_DQS_DP<5>")
	)
	(segment
		(start 149.079966 -303.69637)
		(end 149.079966 -298.168822)
		(width 0.18288)
		(layer "In2.Cu")
		(net "M_F_CPU1_SA_DQS_DP<5>")
	)
	(segment
		(start 165.56482 -311.033668)
		(end 165.27526 -310.744108)
		(width 0.18288)
		(layer "In2.Cu")
		(net "M_F_CPU1_SA_DQS_DP<5>")
	)
	(segment
		(start 157.887416 -310.766714)
		(end 157.524704 -310.766714)
		(width 0.18288)
		(layer "In2.Cu")
		(net "M_F_CPU1_SA_DQS_DP<5>")
	)
	(segment
		(start 140.093192 -278.186388)
		(end 139.677902 -277.771098)
		(width 0.088646)
		(layer "In2.Cu")
		(net "M_F_CPU1_SA_DQS_DP<5>")
	)
	(segment
		(start 168.556178 -311.069482)
		(end 168.144698 -311.069482)
		(width 0.18288)
		(layer "In2.Cu")
		(net "M_F_CPU1_SA_DQS_DP<5>")
	)
	(segment
		(start 174.821088 -311.434226)
		(end 174.459392 -311.07253)
		(width 0.18288)
		(layer "In2.Cu")
		(net "M_F_CPU1_SA_DQS_DP<5>")
	)
	(segment
		(start 144.036034 -289.646868)
		(end 144.036034 -283.768038)
		(width 0.18288)
		(layer "In2.Cu")
		(net "M_F_CPU1_SA_DQS_DP<5>")
	)
	(segment
		(start 175.59655 -311.80913)
		(end 175.195992 -311.80913)
		(width 0.18288)
		(layer "In2.Cu")
		(net "M_F_CPU1_SA_DQS_DP<5>")
	)
	(segment
		(start 176.896014 -311.216548)
		(end 176.605692 -311.50687)
		(width 0.18288)
		(layer "In2.Cu")
		(net "M_F_CPU1_SA_DQS_DP<5>")
	)
	(segment
		(start 160.453324 -311.039764)
		(end 160.191958 -310.778398)
		(width 0.18288)
		(layer "In2.Cu")
		(net "M_F_CPU1_SA_DQS_DP<5>")
	)
	(segment
		(start 136.405112 -277.810722)
		(end 136.40308 -277.808436)
		(width 0.088646)
		(layer "In2.Cu")
		(net "M_F_CPU1_SA_DQS_DP<5>")
	)
	(segment
		(start 156.407612 -311.024016)
		(end 149.079966 -303.69637)
		(width 0.18288)
		(layer "In2.Cu")
		(net "M_F_CPU1_SA_DQS_DP<5>")
	)
	(segment
		(start 173.313344 -311.07253)
		(end 173.032928 -310.792114)
		(width 0.18288)
		(layer "In2.Cu")
		(net "M_F_CPU1_SA_DQS_DP<5>")
	)
	(segment
		(start 159.734504 -310.778398)
		(end 159.45866 -311.054242)
		(width 0.18288)
		(layer "In2.Cu")
		(net "M_F_CPU1_SA_DQS_DP<5>")
	)
	(segment
		(start 163.841176 -310.566308)
		(end 163.684458 -310.40959)
		(width 0.18288)
		(layer "In2.Cu")
		(net "M_F_CPU1_SA_DQS_DP<5>")
	)
	(segment
		(start 164.599112 -311.048146)
		(end 164.323014 -311.048146)
		(width 0.18288)
		(layer "In2.Cu")
		(net "M_F_CPU1_SA_DQS_DP<5>")
	)
	(segment
		(start 164.05352 -310.794908)
		(end 163.86937 -310.610758)
		(width 0.16002)
		(layer "In2.Cu")
		(net "M_F_CPU1_SA_DQS_DP<5>")
	)
	(segment
		(start 175.049434 -311.67832)
		(end 174.849282 -311.478168)
		(width 0.16002)
		(layer "In2.Cu")
		(net "M_F_CPU1_SA_DQS_DP<5>")
	)
	(segment
		(start 167.483028 -310.779922)
		(end 167.229282 -311.033668)
		(width 0.18288)
		(layer "In2.Cu")
		(net "M_F_CPU1_SA_DQS_DP<5>")
	)
	(segment
		(start 136.40308 -277.808436)
		(end 136.076436 -277.398988)
		(width 0.088646)
		(layer "In2.Cu")
		(net "M_F_CPU1_SA_DQS_DP<5>")
	)
	(segment
		(start 157.267402 -311.024016)
		(end 156.407612 -311.024016)
		(width 0.18288)
		(layer "In2.Cu")
		(net "M_F_CPU1_SA_DQS_DP<5>")
	)
	(segment
		(start 167.229282 -311.033668)
		(end 165.56482 -311.033668)
		(width 0.18288)
		(layer "In2.Cu")
		(net "M_F_CPU1_SA_DQS_DP<5>")
	)
	(segment
		(start 141.369034 -279.377902)
		(end 140.17752 -278.186388)
		(width 0.18288)
		(layer "In2.Cu")
		(net "M_F_CPU1_SA_DQS_DP<5>")
	)
	(segment
		(start 158.174944 -311.054242)
		(end 157.887416 -310.766714)
		(width 0.18288)
		(layer "In2.Cu")
		(net "M_F_CPU1_SA_DQS_DP<5>")
	)
	(segment
		(start 172.898816 -310.792114)
		(end 172.668184 -310.792114)
		(width 0.16002)
		(layer "In2.Cu")
		(net "M_F_CPU1_SA_DQS_DP<5>")
	)
	(segment
		(start 142.588488 -282.320492)
		(end 141.369034 -279.377902)
		(width 0.18288)
		(layer "In2.Cu")
		(net "M_F_CPU1_SA_DQS_DP<5>")
	)
	(segment
		(start 161.191194 -311.039764)
		(end 160.453324 -311.039764)
		(width 0.18288)
		(layer "In2.Cu")
		(net "M_F_CPU1_SA_DQS_DP<5>")
	)
	(segment
		(start 157.524704 -310.766714)
		(end 157.267402 -311.024016)
		(width 0.18288)
		(layer "In2.Cu")
		(net "M_F_CPU1_SA_DQS_DP<5>")
	)
	(segment
		(start 140.17752 -278.186388)
		(end 140.093192 -278.186388)
		(width 0.088646)
		(layer "In2.Cu")
		(net "M_F_CPU1_SA_DQS_DP<5>")
	)
	(segment
		(start 136.076436 -277.398988)
		(end 136.03859 -277.333456)
		(width 0.088646)
		(layer "In2.Cu")
		(net "M_F_CPU1_SA_DQS_DP<5>")
	)
	(segment
		(start 172.547534 -310.792114)
		(end 172.271944 -311.067704)
		(width 0.18288)
		(layer "In2.Cu")
		(net "M_F_CPU1_SA_DQS_DP<5>")
	)
	(segment
		(start 172.668184 -310.792114)
		(end 172.547534 -310.792114)
		(width 0.18288)
		(layer "In2.Cu")
		(net "M_F_CPU1_SA_DQS_DP<5>")
	)
	(segment
		(start 175.093376 -311.706514)
		(end 175.065182 -311.67832)
		(width 0.16002)
		(layer "In2.Cu")
		(net "M_F_CPU1_SA_DQS_DP<5>")
	)
	(segment
		(start 169.57548 -310.481218)
		(end 169.291762 -310.764682)
		(width 0.18288)
		(layer "In2.Cu")
		(net "M_F_CPU1_SA_DQS_DP<5>")
	)
	(segment
		(start 160.191958 -310.778398)
		(end 159.734504 -310.778398)
		(width 0.18288)
		(layer "In2.Cu")
		(net "M_F_CPU1_SA_DQS_DP<5>")
	)
	(segment
		(start 174.849282 -311.46242)
		(end 174.821088 -311.434226)
		(width 0.16002)
		(layer "In2.Cu")
		(net "M_F_CPU1_SA_DQS_DP<5>")
	)
	(segment
		(start 173.032928 -310.792114)
		(end 172.898816 -310.792114)
		(width 0.18288)
		(layer "In2.Cu")
		(net "M_F_CPU1_SA_DQS_DP<5>")
	)
	(segment
		(start 135.18515 -277.522432)
		(end 134.775194 -277.522432)
		(width 0.088646)
		(layer "In2.Cu")
		(net "M_F_CPU1_SA_DQS_DP<5>")
	)
	(segment
		(start 174.849282 -311.478168)
		(end 174.849282 -311.46242)
		(width 0.16002)
		(layer "In2.Cu")
		(net "M_F_CPU1_SA_DQS_DP<5>")
	)
	(segment
		(start 163.86937 -310.610758)
		(end 163.86937 -310.594502)
		(width 0.16002)
		(layer "In2.Cu")
		(net "M_F_CPU1_SA_DQS_DP<5>")
	)
	(segment
		(start 149.079966 -298.168822)
		(end 147.619466 -294.383206)
		(width 0.18288)
		(layer "In2.Cu")
		(net "M_F_CPU1_SA_DQS_DP<5>")
	)
	(segment
		(start 176.326038 -311.50687)
		(end 175.59655 -311.80913)
		(width 0.18288)
		(layer "In2.Cu")
		(net "M_F_CPU1_SA_DQS_DP<5>")
	)
	(segment
		(start 175.195992 -311.80913)
		(end 175.093376 -311.706514)
		(width 0.18288)
		(layer "In2.Cu")
		(net "M_F_CPU1_SA_DQS_DP<5>")
	)
	(segment
		(start 164.323014 -311.048146)
		(end 164.09797 -310.823102)
		(width 0.18288)
		(layer "In2.Cu")
		(net "M_F_CPU1_SA_DQS_DP<5>")
	)
	(segment
		(start 169.291762 -310.764682)
		(end 168.556178 -311.069482)
		(width 0.18288)
		(layer "In2.Cu")
		(net "M_F_CPU1_SA_DQS_DP<5>")
	)
	(segment
		(start 171.31157 -310.481218)
		(end 169.57548 -310.481218)
		(width 0.18288)
		(layer "In2.Cu")
		(net "M_F_CPU1_SA_DQS_DP<5>")
	)
	(segment
		(start 159.45866 -311.054242)
		(end 158.174944 -311.054242)
		(width 0.18288)
		(layer "In2.Cu")
		(net "M_F_CPU1_SA_DQS_DP<5>")
	)
	(segment
		(start 162.122866 -310.40959)
		(end 161.705544 -310.826658)
		(width 0.18288)
		(layer "In2.Cu")
		(net "M_F_CPU1_SA_DQS_DP<5>")
	)
	(segment
		(start 167.855138 -310.779922)
		(end 167.483028 -310.779922)
		(width 0.18288)
		(layer "In2.Cu")
		(net "M_F_CPU1_SA_DQS_DP<5>")
	)
	(segment
		(start 172.271944 -311.067704)
		(end 171.898056 -311.067704)
		(width 0.18288)
		(layer "In2.Cu")
		(net "M_F_CPU1_SA_DQS_DP<5>")
	)
	(segment
		(start 168.144698 -311.069482)
		(end 167.855138 -310.779922)
		(width 0.18288)
		(layer "In2.Cu")
		(net "M_F_CPU1_SA_DQS_DP<5>")
	)
	(segment
		(start 144.036034 -283.768038)
		(end 142.588488 -282.320492)
		(width 0.18288)
		(layer "In2.Cu")
		(net "M_F_CPU1_SA_DQS_DP<5>")
	)
	(segment
		(start 164.90315 -310.744108)
		(end 164.599112 -311.048146)
		(width 0.18288)
		(layer "In2.Cu")
		(net "M_F_CPU1_SA_DQS_DP<5>")
	)
	(segment
		(start 144.851374 -291.615114)
		(end 144.036034 -289.646868)
		(width 0.18288)
		(layer "In2.Cu")
		(net "M_F_CPU1_SA_DQS_DP<5>")
	)
	(segment
		(start 174.459392 -311.07253)
		(end 173.313344 -311.07253)
		(width 0.18288)
		(layer "In2.Cu")
		(net "M_F_CPU1_SA_DQS_DP<5>")
	)
	(arc
		(start 135.886698 -277.189184)
		(mid 135.657441 -277.152126)
		(end 135.450326 -277.257256)
		(width 0.088646)
		(layer "In2.Cu")
		(net "M_F_CPU1_SA_DQS_DP<5>")
	)
	(arc
		(start 137.407396 -277.84679)
		(mid 137.124694 -277.771048)
		(end 136.841992 -277.84679)
		(width 0.088646)
		(layer "In2.Cu")
		(net "M_F_CPU1_SA_DQS_DP<5>")
	)
	(arc
		(start 138.721592 -277.84679)
		(mid 138.534394 -277.896933)
		(end 138.347196 -277.84679)
		(width 0.088646)
		(layer "In2.Cu")
		(net "M_F_CPU1_SA_DQS_DP<5>")
	)
	(arc
		(start 139.003786 -277.771098)
		(mid 138.857725 -277.790426)
		(end 138.721592 -277.84679)
		(width 0.088646)
		(layer "In2.Cu")
		(net "M_F_CPU1_SA_DQS_DP<5>")
	)
	(arc
		(start 138.347196 -277.84679)
		(mid 138.064494 -277.771048)
		(end 137.781792 -277.84679)
		(width 0.088646)
		(layer "In2.Cu")
		(net "M_F_CPU1_SA_DQS_DP<5>")
	)
	(arc
		(start 137.781792 -277.84679)
		(mid 137.594594 -277.896933)
		(end 137.407396 -277.84679)
		(width 0.088646)
		(layer "In2.Cu")
		(net "M_F_CPU1_SA_DQS_DP<5>")
	)
	(arc
		(start 136.03859 -277.333456)
		(mid 135.972995 -277.25042)
		(end 135.886698 -277.189184)
		(width 0.088646)
		(layer "In2.Cu")
		(net "M_F_CPU1_SA_DQS_DP<5>")
	)
	(arc
		(start 136.841992 -277.84679)
		(mid 136.654794 -277.896933)
		(end 136.467596 -277.84679)
		(width 0.088646)
		(layer "In2.Cu")
		(net "M_F_CPU1_SA_DQS_DP<5>")
	)
	(segment
		(start 179.00523 -275.94179)
		(end 179.011326 -275.947886)
		(width 0.1016)
		(layer "F.Cu")
		(net "M_F_CPU1_SA_DQS_DP<4>")
	)
	(segment
		(start 179.334668 -275.947886)
		(end 179.637182 -275.645372)
		(width 0.20066)
		(layer "F.Cu")
		(net "M_F_CPU1_SA_DQS_DP<4>")
	)
	(segment
		(start 180.418232 -275.234908)
		(end 180.61432 -275.234908)
		(width 0.20066)
		(layer "F.Cu")
		(net "M_F_CPU1_SA_DQS_DP<4>")
	)
	(segment
		(start 132.895848 -262.87222)
		(end 132.895594 -262.872474)
		(width 0.20066)
		(layer "F.Cu")
		(net "M_F_CPU1_SA_DQS_DP<4>")
	)
	(segment
		(start 176.682654 -275.94179)
		(end 176.8221 -275.94179)
		(width 0.20066)
		(layer "F.Cu")
		(net "M_F_CPU1_SA_DQS_DP<4>")
	)
	(segment
		(start 176.848008 -275.94179)
		(end 179.00523 -275.94179)
		(width 0.1016)
		(layer "F.Cu")
		(net "M_F_CPU1_SA_DQS_DP<4>")
	)
	(segment
		(start 173.900846 -275.516594)
		(end 174.490126 -275.516594)
		(width 0.20066)
		(layer "F.Cu")
		(net "M_F_CPU1_SA_DQS_DP<4>")
	)
	(segment
		(start 179.637182 -275.645372)
		(end 180.007768 -275.645372)
		(width 0.20066)
		(layer "F.Cu")
		(net "M_F_CPU1_SA_DQS_DP<4>")
	)
	(segment
		(start 180.896006 -275.516594)
		(end 181.444646 -275.516594)
		(width 0.20066)
		(layer "F.Cu")
		(net "M_F_CPU1_SA_DQS_DP<4>")
	)
	(segment
		(start 132.895848 -262.336534)
		(end 132.895848 -262.87222)
		(width 0.20066)
		(layer "F.Cu")
		(net "M_F_CPU1_SA_DQS_DP<4>")
	)
	(segment
		(start 180.007768 -275.645372)
		(end 180.418232 -275.234908)
		(width 0.20066)
		(layer "F.Cu")
		(net "M_F_CPU1_SA_DQS_DP<4>")
	)
	(segment
		(start 172.795946 -275.516594)
		(end 173.900846 -275.516594)
		(width 0.20066)
		(layer "F.Cu")
		(net "M_F_CPU1_SA_DQS_DP<4>")
	)
	(segment
		(start 179.011326 -275.947886)
		(end 179.334668 -275.947886)
		(width 0.20066)
		(layer "F.Cu")
		(net "M_F_CPU1_SA_DQS_DP<4>")
	)
	(segment
		(start 180.61432 -275.234908)
		(end 180.896006 -275.516594)
		(width 0.20066)
		(layer "F.Cu")
		(net "M_F_CPU1_SA_DQS_DP<4>")
	)
	(segment
		(start 176.8221 -275.94179)
		(end 176.848008 -275.94179)
		(width 0.101854)
		(layer "F.Cu")
		(net "M_F_CPU1_SA_DQS_DP<4>")
	)
	(segment
		(start 176.431448 -275.690584)
		(end 176.682654 -275.94179)
		(width 0.20066)
		(layer "F.Cu")
		(net "M_F_CPU1_SA_DQS_DP<4>")
	)
	(segment
		(start 174.490126 -275.516594)
		(end 174.730664 -275.276056)
		(width 0.20066)
		(layer "F.Cu")
		(net "M_F_CPU1_SA_DQS_DP<4>")
	)
	(segment
		(start 175.33112 -275.276056)
		(end 175.745648 -275.690584)
		(width 0.20066)
		(layer "F.Cu")
		(net "M_F_CPU1_SA_DQS_DP<4>")
	)
	(segment
		(start 174.730664 -275.276056)
		(end 175.33112 -275.276056)
		(width 0.20066)
		(layer "F.Cu")
		(net "M_F_CPU1_SA_DQS_DP<4>")
	)
	(segment
		(start 175.745648 -275.690584)
		(end 176.431448 -275.690584)
		(width 0.20066)
		(layer "F.Cu")
		(net "M_F_CPU1_SA_DQS_DP<4>")
	)
	(segment
		(start 171.727622 -274.94357)
		(end 171.625006 -275.046186)
		(width 0.18288)
		(layer "In2.Cu")
		(net "M_F_CPU1_SA_DQS_DP<4>")
	)
	(segment
		(start 161.729928 -275.029168)
		(end 161.701734 -275.000974)
		(width 0.16002)
		(layer "In2.Cu")
		(net "M_F_CPU1_SA_DQS_DP<4>")
	)
	(segment
		(start 169.122852 -274.878292)
		(end 168.542716 -274.878292)
		(width 0.18288)
		(layer "In2.Cu")
		(net "M_F_CPU1_SA_DQS_DP<4>")
	)
	(segment
		(start 167.342058 -276.07895)
		(end 167.313864 -276.107144)
		(width 0.16002)
		(layer "In2.Cu")
		(net "M_F_CPU1_SA_DQS_DP<4>")
	)
	(segment
		(start 140.900404 -263.385554)
		(end 140.840714 -263.325864)
		(width 0.088646)
		(layer "In2.Cu")
		(net "M_F_CPU1_SA_DQS_DP<4>")
	)
	(segment
		(start 161.930334 -275.213318)
		(end 161.746184 -275.029168)
		(width 0.16002)
		(layer "In2.Cu")
		(net "M_F_CPU1_SA_DQS_DP<4>")
	)
	(segment
		(start 133.208268 -262.872474)
		(end 132.895594 -262.872474)
		(width 0.088646)
		(layer "In2.Cu")
		(net "M_F_CPU1_SA_DQS_DP<4>")
	)
	(segment
		(start 168.542716 -274.878292)
		(end 167.524938 -275.89607)
		(width 0.18288)
		(layer "In2.Cu")
		(net "M_F_CPU1_SA_DQS_DP<4>")
	)
	(segment
		(start 165.374066 -276.079458)
		(end 165.374066 -276.063202)
		(width 0.16002)
		(layer "In2.Cu")
		(net "M_F_CPU1_SA_DQS_DP<4>")
	)
	(segment
		(start 158.189168 -273.954494)
		(end 157.876494 -274.267168)
		(width 0.18288)
		(layer "In2.Cu")
		(net "M_F_CPU1_SA_DQS_DP<4>")
	)
	(segment
		(start 169.70121 -275.45665)
		(end 169.502328 -275.257768)
		(width 0.18288)
		(layer "In2.Cu")
		(net "M_F_CPU1_SA_DQS_DP<4>")
	)
	(segment
		(start 167.342058 -276.062694)
		(end 167.342058 -276.07895)
		(width 0.16002)
		(layer "In2.Cu")
		(net "M_F_CPU1_SA_DQS_DP<4>")
	)
	(segment
		(start 138.817096 -263.362186)
		(end 138.802364 -263.370822)
		(width 0.088646)
		(layer "In2.Cu")
		(net "M_F_CPU1_SA_DQS_DP<4>")
	)
	(segment
		(start 171.596812 -275.07438)
		(end 171.580556 -275.07438)
		(width 0.16002)
		(layer "In2.Cu")
		(net "M_F_CPU1_SA_DQS_DP<4>")
	)
	(segment
		(start 157.190948 -273.91614)
		(end 156.619956 -273.91614)
		(width 0.18288)
		(layer "In2.Cu")
		(net "M_F_CPU1_SA_DQS_DP<4>")
	)
	(segment
		(start 163.549838 -275.682456)
		(end 162.383216 -275.682456)
		(width 0.18288)
		(layer "In2.Cu")
		(net "M_F_CPU1_SA_DQS_DP<4>")
	)
	(segment
		(start 171.442126 -275.229066)
		(end 171.413932 -275.25726)
		(width 0.16002)
		(layer "In2.Cu")
		(net "M_F_CPU1_SA_DQS_DP<4>")
	)
	(segment
		(start 171.442126 -275.21281)
		(end 171.442126 -275.229066)
		(width 0.16002)
		(layer "In2.Cu")
		(net "M_F_CPU1_SA_DQS_DP<4>")
	)
	(segment
		(start 171.898564 -274.94357)
		(end 171.727622 -274.94357)
		(width 0.18288)
		(layer "In2.Cu")
		(net "M_F_CPU1_SA_DQS_DP<4>")
	)
	(segment
		(start 171.580556 -275.07438)
		(end 171.442126 -275.21281)
		(width 0.16002)
		(layer "In2.Cu")
		(net "M_F_CPU1_SA_DQS_DP<4>")
	)
	(segment
		(start 143.85925 -263.385554)
		(end 140.900404 -263.385554)
		(width 0.18288)
		(layer "In2.Cu")
		(net "M_F_CPU1_SA_DQS_DP<4>")
	)
	(segment
		(start 157.541976 -274.267168)
		(end 157.190948 -273.91614)
		(width 0.18288)
		(layer "In2.Cu")
		(net "M_F_CPU1_SA_DQS_DP<4>")
	)
	(segment
		(start 169.502328 -275.257768)
		(end 169.474134 -275.229574)
		(width 0.16002)
		(layer "In2.Cu")
		(net "M_F_CPU1_SA_DQS_DP<4>")
	)
	(segment
		(start 140.840714 -263.325864)
		(end 139.91971 -263.325864)
		(width 0.088646)
		(layer "In2.Cu")
		(net "M_F_CPU1_SA_DQS_DP<4>")
	)
	(segment
		(start 162.383216 -275.682456)
		(end 161.958528 -275.257768)
		(width 0.18288)
		(layer "In2.Cu")
		(net "M_F_CPU1_SA_DQS_DP<4>")
	)
	(segment
		(start 163.834572 -275.96719)
		(end 163.549838 -275.682456)
		(width 0.18288)
		(layer "In2.Cu")
		(net "M_F_CPU1_SA_DQS_DP<4>")
	)
	(segment
		(start 161.746184 -275.029168)
		(end 161.729928 -275.029168)
		(width 0.16002)
		(layer "In2.Cu")
		(net "M_F_CPU1_SA_DQS_DP<4>")
	)
	(segment
		(start 164.266626 -275.96719)
		(end 163.834572 -275.96719)
		(width 0.18288)
		(layer "In2.Cu")
		(net "M_F_CPU1_SA_DQS_DP<4>")
	)
	(segment
		(start 167.313864 -276.107144)
		(end 167.114474 -276.306534)
		(width 0.18288)
		(layer "In2.Cu")
		(net "M_F_CPU1_SA_DQS_DP<4>")
	)
	(segment
		(start 165.374066 -276.063202)
		(end 165.189916 -275.879052)
		(width 0.16002)
		(layer "In2.Cu")
		(net "M_F_CPU1_SA_DQS_DP<4>")
	)
	(segment
		(start 147.10283 -266.19073)
		(end 144.608296 -263.696196)
		(width 0.18288)
		(layer "In2.Cu")
		(net "M_F_CPU1_SA_DQS_DP<4>")
	)
	(segment
		(start 172.269912 -275.314918)
		(end 171.898564 -274.94357)
		(width 0.18288)
		(layer "In2.Cu")
		(net "M_F_CPU1_SA_DQS_DP<4>")
	)
	(segment
		(start 169.474134 -275.213318)
		(end 169.289984 -275.029168)
		(width 0.16002)
		(layer "In2.Cu")
		(net "M_F_CPU1_SA_DQS_DP<4>")
	)
	(segment
		(start 171.214542 -275.45665)
		(end 169.70121 -275.45665)
		(width 0.18288)
		(layer "In2.Cu")
		(net "M_F_CPU1_SA_DQS_DP<4>")
	)
	(segment
		(start 167.480488 -275.924264)
		(end 167.342058 -276.062694)
		(width 0.16002)
		(layer "In2.Cu")
		(net "M_F_CPU1_SA_DQS_DP<4>")
	)
	(segment
		(start 164.944044 -275.649436)
		(end 164.58438 -275.649436)
		(width 0.18288)
		(layer "In2.Cu")
		(net "M_F_CPU1_SA_DQS_DP<4>")
	)
	(segment
		(start 159.439102 -273.954494)
		(end 158.189168 -273.954494)
		(width 0.18288)
		(layer "In2.Cu")
		(net "M_F_CPU1_SA_DQS_DP<4>")
	)
	(segment
		(start 160.688782 -273.988022)
		(end 160.36544 -273.988022)
		(width 0.18288)
		(layer "In2.Cu")
		(net "M_F_CPU1_SA_DQS_DP<4>")
	)
	(segment
		(start 164.58438 -275.649436)
		(end 164.266626 -275.96719)
		(width 0.18288)
		(layer "In2.Cu")
		(net "M_F_CPU1_SA_DQS_DP<4>")
	)
	(segment
		(start 171.625006 -275.046186)
		(end 171.596812 -275.07438)
		(width 0.16002)
		(layer "In2.Cu")
		(net "M_F_CPU1_SA_DQS_DP<4>")
	)
	(segment
		(start 165.17366 -275.879052)
		(end 165.145466 -275.850858)
		(width 0.16002)
		(layer "In2.Cu")
		(net "M_F_CPU1_SA_DQS_DP<4>")
	)
	(segment
		(start 167.114474 -276.306534)
		(end 165.601142 -276.306534)
		(width 0.18288)
		(layer "In2.Cu")
		(net "M_F_CPU1_SA_DQS_DP<4>")
	)
	(segment
		(start 169.474134 -275.229574)
		(end 169.474134 -275.213318)
		(width 0.16002)
		(layer "In2.Cu")
		(net "M_F_CPU1_SA_DQS_DP<4>")
	)
	(segment
		(start 159.751776 -274.267168)
		(end 159.439102 -273.954494)
		(width 0.18288)
		(layer "In2.Cu")
		(net "M_F_CPU1_SA_DQS_DP<4>")
	)
	(segment
		(start 133.2738 -262.938006)
		(end 133.208268 -262.872474)
		(width 0.088646)
		(layer "In2.Cu")
		(net "M_F_CPU1_SA_DQS_DP<4>")
	)
	(segment
		(start 156.10205 -273.398234)
		(end 155.239466 -271.31772)
		(width 0.18288)
		(layer "In2.Cu")
		(net "M_F_CPU1_SA_DQS_DP<4>")
	)
	(segment
		(start 144.608296 -263.696196)
		(end 143.85925 -263.385554)
		(width 0.18288)
		(layer "In2.Cu")
		(net "M_F_CPU1_SA_DQS_DP<4>")
	)
	(segment
		(start 165.145466 -275.850858)
		(end 164.944044 -275.649436)
		(width 0.18288)
		(layer "In2.Cu")
		(net "M_F_CPU1_SA_DQS_DP<4>")
	)
	(segment
		(start 165.189916 -275.879052)
		(end 165.17366 -275.879052)
		(width 0.16002)
		(layer "In2.Cu")
		(net "M_F_CPU1_SA_DQS_DP<4>")
	)
	(segment
		(start 161.930334 -275.229574)
		(end 161.930334 -275.213318)
		(width 0.16002)
		(layer "In2.Cu")
		(net "M_F_CPU1_SA_DQS_DP<4>")
	)
	(segment
		(start 167.496744 -275.924264)
		(end 167.480488 -275.924264)
		(width 0.16002)
		(layer "In2.Cu")
		(net "M_F_CPU1_SA_DQS_DP<4>")
	)
	(segment
		(start 160.36544 -273.988022)
		(end 160.086294 -274.267168)
		(width 0.18288)
		(layer "In2.Cu")
		(net "M_F_CPU1_SA_DQS_DP<4>")
	)
	(segment
		(start 165.40226 -276.107652)
		(end 165.374066 -276.079458)
		(width 0.16002)
		(layer "In2.Cu")
		(net "M_F_CPU1_SA_DQS_DP<4>")
	)
	(segment
		(start 165.601142 -276.306534)
		(end 165.40226 -276.107652)
		(width 0.18288)
		(layer "In2.Cu")
		(net "M_F_CPU1_SA_DQS_DP<4>")
	)
	(segment
		(start 161.958528 -275.257768)
		(end 161.930334 -275.229574)
		(width 0.16002)
		(layer "In2.Cu")
		(net "M_F_CPU1_SA_DQS_DP<4>")
	)
	(segment
		(start 150.112476 -266.19073)
		(end 147.10283 -266.19073)
		(width 0.18288)
		(layer "In2.Cu")
		(net "M_F_CPU1_SA_DQS_DP<4>")
	)
	(segment
		(start 169.289984 -275.029168)
		(end 169.273728 -275.029168)
		(width 0.16002)
		(layer "In2.Cu")
		(net "M_F_CPU1_SA_DQS_DP<4>")
	)
	(segment
		(start 156.619956 -273.91614)
		(end 156.10205 -273.398234)
		(width 0.18288)
		(layer "In2.Cu")
		(net "M_F_CPU1_SA_DQS_DP<4>")
	)
	(segment
		(start 161.701734 -275.000974)
		(end 160.688782 -273.988022)
		(width 0.18288)
		(layer "In2.Cu")
		(net "M_F_CPU1_SA_DQS_DP<4>")
	)
	(segment
		(start 172.795946 -275.516594)
		(end 172.59427 -275.314918)
		(width 0.18288)
		(layer "In2.Cu")
		(net "M_F_CPU1_SA_DQS_DP<4>")
	)
	(segment
		(start 155.239466 -271.31772)
		(end 150.112476 -266.19073)
		(width 0.18288)
		(layer "In2.Cu")
		(net "M_F_CPU1_SA_DQS_DP<4>")
	)
	(segment
		(start 157.876494 -274.267168)
		(end 157.541976 -274.267168)
		(width 0.18288)
		(layer "In2.Cu")
		(net "M_F_CPU1_SA_DQS_DP<4>")
	)
	(segment
		(start 171.413932 -275.25726)
		(end 171.214542 -275.45665)
		(width 0.18288)
		(layer "In2.Cu")
		(net "M_F_CPU1_SA_DQS_DP<4>")
	)
	(segment
		(start 134.50316 -263.368282)
		(end 134.492746 -263.362186)
		(width 0.088646)
		(layer "In2.Cu")
		(net "M_F_CPU1_SA_DQS_DP<4>")
	)
	(segment
		(start 160.086294 -274.267168)
		(end 159.751776 -274.267168)
		(width 0.18288)
		(layer "In2.Cu")
		(net "M_F_CPU1_SA_DQS_DP<4>")
	)
	(segment
		(start 172.59427 -275.314918)
		(end 172.269912 -275.314918)
		(width 0.18288)
		(layer "In2.Cu")
		(net "M_F_CPU1_SA_DQS_DP<4>")
	)
	(segment
		(start 169.245534 -275.000974)
		(end 169.122852 -274.878292)
		(width 0.18288)
		(layer "In2.Cu")
		(net "M_F_CPU1_SA_DQS_DP<4>")
	)
	(segment
		(start 169.273728 -275.029168)
		(end 169.245534 -275.000974)
		(width 0.16002)
		(layer "In2.Cu")
		(net "M_F_CPU1_SA_DQS_DP<4>")
	)
	(segment
		(start 167.524938 -275.89607)
		(end 167.496744 -275.924264)
		(width 0.16002)
		(layer "In2.Cu")
		(net "M_F_CPU1_SA_DQS_DP<4>")
	)
	(arc
		(start 137.877296 -263.362186)
		(mid 137.594594 -263.437928)
		(end 137.311892 -263.362186)
		(width 0.088646)
		(layer "In2.Cu")
		(net "M_F_CPU1_SA_DQS_DP<4>")
	)
	(arc
		(start 135.997696 -263.362186)
		(mid 135.714994 -263.437928)
		(end 135.432292 -263.362186)
		(width 0.088646)
		(layer "In2.Cu")
		(net "M_F_CPU1_SA_DQS_DP<4>")
	)
	(arc
		(start 138.802364 -263.370822)
		(mid 138.525923 -263.437988)
		(end 138.251692 -263.362186)
		(width 0.088646)
		(layer "In2.Cu")
		(net "M_F_CPU1_SA_DQS_DP<4>")
	)
	(arc
		(start 134.492746 -263.362186)
		(mid 134.305548 -263.312043)
		(end 134.11835 -263.362186)
		(width 0.088646)
		(layer "In2.Cu")
		(net "M_F_CPU1_SA_DQS_DP<4>")
	)
	(arc
		(start 136.372092 -263.362186)
		(mid 136.184894 -263.312043)
		(end 135.997696 -263.362186)
		(width 0.088646)
		(layer "In2.Cu")
		(net "M_F_CPU1_SA_DQS_DP<4>")
	)
	(arc
		(start 135.057896 -263.362186)
		(mid 134.781337 -263.437895)
		(end 134.50316 -263.368282)
		(width 0.088646)
		(layer "In2.Cu")
		(net "M_F_CPU1_SA_DQS_DP<4>")
	)
	(arc
		(start 133.276594 -262.959088)
		(mid 133.275098 -262.94856)
		(end 133.2738 -262.938006)
		(width 0.088646)
		(layer "In2.Cu")
		(net "M_F_CPU1_SA_DQS_DP<4>")
	)
	(arc
		(start 137.311892 -263.362186)
		(mid 137.124694 -263.312043)
		(end 136.937496 -263.362186)
		(width 0.088646)
		(layer "In2.Cu")
		(net "M_F_CPU1_SA_DQS_DP<4>")
	)
	(arc
		(start 134.11835 -263.362186)
		(mid 133.591148 -263.382598)
		(end 133.276594 -262.959088)
		(width 0.088646)
		(layer "In2.Cu")
		(net "M_F_CPU1_SA_DQS_DP<4>")
	)
	(arc
		(start 139.91971 -263.325864)
		(mid 139.828149 -263.337337)
		(end 139.742164 -263.370822)
		(width 0.088646)
		(layer "In2.Cu")
		(net "M_F_CPU1_SA_DQS_DP<4>")
	)
	(arc
		(start 136.937496 -263.362186)
		(mid 136.654794 -263.437928)
		(end 136.372092 -263.362186)
		(width 0.088646)
		(layer "In2.Cu")
		(net "M_F_CPU1_SA_DQS_DP<4>")
	)
	(arc
		(start 139.742164 -263.370822)
		(mid 139.465723 -263.437988)
		(end 139.191492 -263.362186)
		(width 0.088646)
		(layer "In2.Cu")
		(net "M_F_CPU1_SA_DQS_DP<4>")
	)
	(arc
		(start 139.191492 -263.362186)
		(mid 139.004294 -263.312043)
		(end 138.817096 -263.362186)
		(width 0.088646)
		(layer "In2.Cu")
		(net "M_F_CPU1_SA_DQS_DP<4>")
	)
	(arc
		(start 138.251692 -263.362186)
		(mid 138.064494 -263.312043)
		(end 137.877296 -263.362186)
		(width 0.088646)
		(layer "In2.Cu")
		(net "M_F_CPU1_SA_DQS_DP<4>")
	)
	(arc
		(start 135.432292 -263.362186)
		(mid 135.245094 -263.312043)
		(end 135.057896 -263.362186)
		(width 0.088646)
		(layer "In2.Cu")
		(net "M_F_CPU1_SA_DQS_DP<4>")
	)
	(segment
		(start 180.418232 -284.584902)
		(end 180.61432 -284.584902)
		(width 0.20066)
		(layer "F.Cu")
		(net "M_F_CPU1_SA_DQS_DP<3>")
	)
	(segment
		(start 129.606294 -259.894832)
		(end 129.606294 -260.430518)
		(width 0.20066)
		(layer "F.Cu")
		(net "M_F_CPU1_SA_DQS_DP<3>")
	)
	(segment
		(start 180.007768 -284.995366)
		(end 180.418232 -284.584902)
		(width 0.20066)
		(layer "F.Cu")
		(net "M_F_CPU1_SA_DQS_DP<3>")
	)
	(segment
		(start 176.8221 -285.291784)
		(end 176.848008 -285.291784)
		(width 0.101854)
		(layer "F.Cu")
		(net "M_F_CPU1_SA_DQS_DP<3>")
	)
	(segment
		(start 172.795946 -284.866588)
		(end 173.900846 -284.866588)
		(width 0.20066)
		(layer "F.Cu")
		(net "M_F_CPU1_SA_DQS_DP<3>")
	)
	(segment
		(start 179.00523 -285.291784)
		(end 179.011326 -285.29788)
		(width 0.1016)
		(layer "F.Cu")
		(net "M_F_CPU1_SA_DQS_DP<3>")
	)
	(segment
		(start 129.606294 -260.430518)
		(end 129.606548 -260.430772)
		(width 0.20066)
		(layer "F.Cu")
		(net "M_F_CPU1_SA_DQS_DP<3>")
	)
	(segment
		(start 179.637182 -284.995366)
		(end 180.007768 -284.995366)
		(width 0.20066)
		(layer "F.Cu")
		(net "M_F_CPU1_SA_DQS_DP<3>")
	)
	(segment
		(start 179.011326 -285.29788)
		(end 179.334668 -285.29788)
		(width 0.20066)
		(layer "F.Cu")
		(net "M_F_CPU1_SA_DQS_DP<3>")
	)
	(segment
		(start 176.682654 -285.291784)
		(end 176.8221 -285.291784)
		(width 0.20066)
		(layer "F.Cu")
		(net "M_F_CPU1_SA_DQS_DP<3>")
	)
	(segment
		(start 180.896006 -284.866588)
		(end 181.444646 -284.866588)
		(width 0.20066)
		(layer "F.Cu")
		(net "M_F_CPU1_SA_DQS_DP<3>")
	)
	(segment
		(start 173.900846 -284.866588)
		(end 174.490126 -284.866588)
		(width 0.20066)
		(layer "F.Cu")
		(net "M_F_CPU1_SA_DQS_DP<3>")
	)
	(segment
		(start 179.334668 -285.29788)
		(end 179.637182 -284.995366)
		(width 0.20066)
		(layer "F.Cu")
		(net "M_F_CPU1_SA_DQS_DP<3>")
	)
	(segment
		(start 174.490126 -284.866588)
		(end 174.730664 -284.62605)
		(width 0.20066)
		(layer "F.Cu")
		(net "M_F_CPU1_SA_DQS_DP<3>")
	)
	(segment
		(start 180.61432 -284.584902)
		(end 180.896006 -284.866588)
		(width 0.20066)
		(layer "F.Cu")
		(net "M_F_CPU1_SA_DQS_DP<3>")
	)
	(segment
		(start 175.745648 -285.040578)
		(end 176.431448 -285.040578)
		(width 0.20066)
		(layer "F.Cu")
		(net "M_F_CPU1_SA_DQS_DP<3>")
	)
	(segment
		(start 176.848008 -285.291784)
		(end 179.00523 -285.291784)
		(width 0.1016)
		(layer "F.Cu")
		(net "M_F_CPU1_SA_DQS_DP<3>")
	)
	(segment
		(start 174.730664 -284.62605)
		(end 175.33112 -284.62605)
		(width 0.20066)
		(layer "F.Cu")
		(net "M_F_CPU1_SA_DQS_DP<3>")
	)
	(segment
		(start 175.33112 -284.62605)
		(end 175.745648 -285.040578)
		(width 0.20066)
		(layer "F.Cu")
		(net "M_F_CPU1_SA_DQS_DP<3>")
	)
	(segment
		(start 176.431448 -285.040578)
		(end 176.682654 -285.291784)
		(width 0.20066)
		(layer "F.Cu")
		(net "M_F_CPU1_SA_DQS_DP<3>")
	)
	(segment
		(start 137.782046 -260.919976)
		(end 137.781538 -260.920484)
		(width 0.088646)
		(layer "In4.Cu")
		(net "M_F_CPU1_SA_DQS_DP<3>")
	)
	(segment
		(start 129.9845 -260.49605)
		(end 129.919222 -260.430772)
		(width 0.088646)
		(layer "In4.Cu")
		(net "M_F_CPU1_SA_DQS_DP<3>")
	)
	(segment
		(start 138.784838 -260.887972)
		(end 138.378692 -260.887972)
		(width 0.088646)
		(layer "In4.Cu")
		(net "M_F_CPU1_SA_DQS_DP<3>")
	)
	(segment
		(start 165.752018 -275.66493)
		(end 163.812474 -273.725386)
		(width 0.18288)
		(layer "In4.Cu")
		(net "M_F_CPU1_SA_DQS_DP<3>")
	)
	(segment
		(start 157.225492 -271.673828)
		(end 148.545296 -262.993632)
		(width 0.18288)
		(layer "In4.Cu")
		(net "M_F_CPU1_SA_DQS_DP<3>")
	)
	(segment
		(start 172.515784 -284.586426)
		(end 172.1866 -284.586426)
		(width 0.18288)
		(layer "In4.Cu")
		(net "M_F_CPU1_SA_DQS_DP<3>")
	)
	(segment
		(start 172.795946 -284.866588)
		(end 172.515784 -284.586426)
		(width 0.18288)
		(layer "In4.Cu")
		(net "M_F_CPU1_SA_DQS_DP<3>")
	)
	(segment
		(start 158.637986 -271.673828)
		(end 157.225492 -271.673828)
		(width 0.18288)
		(layer "In4.Cu")
		(net "M_F_CPU1_SA_DQS_DP<3>")
	)
	(segment
		(start 138.844782 -260.947916)
		(end 138.784838 -260.887972)
		(width 0.088646)
		(layer "In4.Cu")
		(net "M_F_CPU1_SA_DQS_DP<3>")
	)
	(segment
		(start 160.689544 -273.725386)
		(end 158.637986 -271.673828)
		(width 0.18288)
		(layer "In4.Cu")
		(net "M_F_CPU1_SA_DQS_DP<3>")
	)
	(segment
		(start 143.938752 -261.968996)
		(end 141.473682 -260.947916)
		(width 0.18288)
		(layer "In4.Cu")
		(net "M_F_CPU1_SA_DQS_DP<3>")
	)
	(segment
		(start 130.828796 -260.920484)
		(end 130.814064 -260.92912)
		(width 0.088646)
		(layer "In4.Cu")
		(net "M_F_CPU1_SA_DQS_DP<3>")
	)
	(segment
		(start 168.435274 -280.78811)
		(end 168.435274 -276.347428)
		(width 0.18288)
		(layer "In4.Cu")
		(net "M_F_CPU1_SA_DQS_DP<3>")
	)
	(segment
		(start 171.267374 -284.275022)
		(end 170.199304 -283.207206)
		(width 0.18288)
		(layer "In4.Cu")
		(net "M_F_CPU1_SA_DQS_DP<3>")
	)
	(segment
		(start 136.467342 -260.920484)
		(end 136.456928 -260.92658)
		(width 0.088646)
		(layer "In4.Cu")
		(net "M_F_CPU1_SA_DQS_DP<3>")
	)
	(segment
		(start 129.919222 -260.430772)
		(end 129.606548 -260.430772)
		(width 0.088646)
		(layer "In4.Cu")
		(net "M_F_CPU1_SA_DQS_DP<3>")
	)
	(segment
		(start 163.812474 -273.725386)
		(end 160.689544 -273.725386)
		(width 0.18288)
		(layer "In4.Cu")
		(net "M_F_CPU1_SA_DQS_DP<3>")
	)
	(segment
		(start 134.587996 -260.920484)
		(end 134.573264 -260.92912)
		(width 0.088646)
		(layer "In4.Cu")
		(net "M_F_CPU1_SA_DQS_DP<3>")
	)
	(segment
		(start 171.875196 -284.275022)
		(end 171.267374 -284.275022)
		(width 0.18288)
		(layer "In4.Cu")
		(net "M_F_CPU1_SA_DQS_DP<3>")
	)
	(segment
		(start 141.473682 -260.947916)
		(end 138.86815 -260.947916)
		(width 0.18288)
		(layer "In4.Cu")
		(net "M_F_CPU1_SA_DQS_DP<3>")
	)
	(segment
		(start 167.752776 -275.66493)
		(end 165.752018 -275.66493)
		(width 0.18288)
		(layer "In4.Cu")
		(net "M_F_CPU1_SA_DQS_DP<3>")
	)
	(segment
		(start 145.680176 -262.993632)
		(end 144.456404 -262.486648)
		(width 0.18288)
		(layer "In4.Cu")
		(net "M_F_CPU1_SA_DQS_DP<3>")
	)
	(segment
		(start 148.545296 -262.993632)
		(end 145.680176 -262.993632)
		(width 0.18288)
		(layer "In4.Cu")
		(net "M_F_CPU1_SA_DQS_DP<3>")
	)
	(segment
		(start 170.199304 -283.207206)
		(end 169.777156 -282.130246)
		(width 0.18288)
		(layer "In4.Cu")
		(net "M_F_CPU1_SA_DQS_DP<3>")
	)
	(segment
		(start 168.435274 -276.347428)
		(end 167.752776 -275.66493)
		(width 0.18288)
		(layer "In4.Cu")
		(net "M_F_CPU1_SA_DQS_DP<3>")
	)
	(segment
		(start 144.456404 -262.486648)
		(end 143.938752 -261.968996)
		(width 0.18288)
		(layer "In4.Cu")
		(net "M_F_CPU1_SA_DQS_DP<3>")
	)
	(segment
		(start 172.1866 -284.586426)
		(end 171.875196 -284.275022)
		(width 0.18288)
		(layer "In4.Cu")
		(net "M_F_CPU1_SA_DQS_DP<3>")
	)
	(segment
		(start 131.768596 -260.920484)
		(end 131.753864 -260.92912)
		(width 0.088646)
		(layer "In4.Cu")
		(net "M_F_CPU1_SA_DQS_DP<3>")
	)
	(segment
		(start 169.777156 -282.130246)
		(end 168.435274 -280.78811)
		(width 0.18288)
		(layer "In4.Cu")
		(net "M_F_CPU1_SA_DQS_DP<3>")
	)
	(segment
		(start 138.378692 -260.887972)
		(end 138.346688 -260.919976)
		(width 0.088646)
		(layer "In4.Cu")
		(net "M_F_CPU1_SA_DQS_DP<3>")
	)
	(segment
		(start 138.86815 -260.947916)
		(end 138.844782 -260.947916)
		(width 0.088646)
		(layer "In4.Cu")
		(net "M_F_CPU1_SA_DQS_DP<3>")
	)
	(segment
		(start 132.708396 -260.920484)
		(end 132.693664 -260.92912)
		(width 0.088646)
		(layer "In4.Cu")
		(net "M_F_CPU1_SA_DQS_DP<3>")
	)
	(arc
		(start 134.962392 -260.920484)
		(mid 134.775194 -260.870341)
		(end 134.587996 -260.920484)
		(width 0.088646)
		(layer "In4.Cu")
		(net "M_F_CPU1_SA_DQS_DP<3>")
	)
	(arc
		(start 131.203192 -260.920484)
		(mid 131.015994 -260.870341)
		(end 130.828796 -260.920484)
		(width 0.088646)
		(layer "In4.Cu")
		(net "M_F_CPU1_SA_DQS_DP<3>")
	)
	(arc
		(start 130.814064 -260.92912)
		(mid 130.29416 -260.937155)
		(end 129.987294 -260.517386)
		(width 0.088646)
		(layer "In4.Cu")
		(net "M_F_CPU1_SA_DQS_DP<3>")
	)
	(arc
		(start 132.142992 -260.920484)
		(mid 131.955794 -260.870341)
		(end 131.768596 -260.920484)
		(width 0.088646)
		(layer "In4.Cu")
		(net "M_F_CPU1_SA_DQS_DP<3>")
	)
	(arc
		(start 132.693664 -260.92912)
		(mid 132.417223 -260.996286)
		(end 132.142992 -260.920484)
		(width 0.088646)
		(layer "In4.Cu")
		(net "M_F_CPU1_SA_DQS_DP<3>")
	)
	(arc
		(start 131.753864 -260.92912)
		(mid 131.477423 -260.996286)
		(end 131.203192 -260.920484)
		(width 0.088646)
		(layer "In4.Cu")
		(net "M_F_CPU1_SA_DQS_DP<3>")
	)
	(arc
		(start 135.902192 -260.920484)
		(mid 135.714994 -260.870341)
		(end 135.527796 -260.920484)
		(width 0.088646)
		(layer "In4.Cu")
		(net "M_F_CPU1_SA_DQS_DP<3>")
	)
	(arc
		(start 137.407142 -260.920484)
		(mid 137.12444 -260.996226)
		(end 136.841738 -260.920484)
		(width 0.088646)
		(layer "In4.Cu")
		(net "M_F_CPU1_SA_DQS_DP<3>")
	)
	(arc
		(start 135.527796 -260.920484)
		(mid 135.245094 -260.996226)
		(end 134.962392 -260.920484)
		(width 0.088646)
		(layer "In4.Cu")
		(net "M_F_CPU1_SA_DQS_DP<3>")
	)
	(arc
		(start 129.987294 -260.517386)
		(mid 129.985796 -260.506731)
		(end 129.9845 -260.49605)
		(width 0.088646)
		(layer "In4.Cu")
		(net "M_F_CPU1_SA_DQS_DP<3>")
	)
	(arc
		(start 136.841738 -260.920484)
		(mid 136.65454 -260.870341)
		(end 136.467342 -260.920484)
		(width 0.088646)
		(layer "In4.Cu")
		(net "M_F_CPU1_SA_DQS_DP<3>")
	)
	(arc
		(start 136.456928 -260.92658)
		(mid 136.17875 -260.996272)
		(end 135.902192 -260.920484)
		(width 0.088646)
		(layer "In4.Cu")
		(net "M_F_CPU1_SA_DQS_DP<3>")
	)
	(arc
		(start 137.781538 -260.920484)
		(mid 137.59434 -260.870341)
		(end 137.407142 -260.920484)
		(width 0.088646)
		(layer "In4.Cu")
		(net "M_F_CPU1_SA_DQS_DP<3>")
	)
	(arc
		(start 134.573264 -260.92912)
		(mid 134.296823 -260.996286)
		(end 134.022592 -260.920484)
		(width 0.088646)
		(layer "In4.Cu")
		(net "M_F_CPU1_SA_DQS_DP<3>")
	)
	(arc
		(start 133.648196 -260.920484)
		(mid 133.365494 -260.996226)
		(end 133.082792 -260.920484)
		(width 0.088646)
		(layer "In4.Cu")
		(net "M_F_CPU1_SA_DQS_DP<3>")
	)
	(arc
		(start 134.022592 -260.920484)
		(mid 133.835394 -260.870341)
		(end 133.648196 -260.920484)
		(width 0.088646)
		(layer "In4.Cu")
		(net "M_F_CPU1_SA_DQS_DP<3>")
	)
	(arc
		(start 138.346688 -260.919976)
		(mid 138.064384 -260.995532)
		(end 137.782046 -260.919976)
		(width 0.088646)
		(layer "In4.Cu")
		(net "M_F_CPU1_SA_DQS_DP<3>")
	)
	(arc
		(start 133.082792 -260.920484)
		(mid 132.895594 -260.870341)
		(end 132.708396 -260.920484)
		(width 0.088646)
		(layer "In4.Cu")
		(net "M_F_CPU1_SA_DQS_DP<3>")
	)
	(segment
		(start 176.682654 -294.641778)
		(end 176.8221 -294.641778)
		(width 0.20066)
		(layer "F.Cu")
		(net "M_F_CPU1_SA_DQS_DP<2>")
	)
	(segment
		(start 174.730664 -293.976044)
		(end 175.33112 -293.976044)
		(width 0.20066)
		(layer "F.Cu")
		(net "M_F_CPU1_SA_DQS_DP<2>")
	)
	(segment
		(start 180.61432 -293.934896)
		(end 180.896006 -294.216582)
		(width 0.20066)
		(layer "F.Cu")
		(net "M_F_CPU1_SA_DQS_DP<2>")
	)
	(segment
		(start 173.900846 -294.216582)
		(end 174.490126 -294.216582)
		(width 0.20066)
		(layer "F.Cu")
		(net "M_F_CPU1_SA_DQS_DP<2>")
	)
	(segment
		(start 180.418232 -293.934896)
		(end 180.61432 -293.934896)
		(width 0.20066)
		(layer "F.Cu")
		(net "M_F_CPU1_SA_DQS_DP<2>")
	)
	(segment
		(start 179.00523 -294.641778)
		(end 179.011326 -294.647874)
		(width 0.1016)
		(layer "F.Cu")
		(net "M_F_CPU1_SA_DQS_DP<2>")
	)
	(segment
		(start 176.8221 -294.641778)
		(end 176.848008 -294.641778)
		(width 0.101854)
		(layer "F.Cu")
		(net "M_F_CPU1_SA_DQS_DP<2>")
	)
	(segment
		(start 176.431448 -294.390572)
		(end 176.682654 -294.641778)
		(width 0.20066)
		(layer "F.Cu")
		(net "M_F_CPU1_SA_DQS_DP<2>")
	)
	(segment
		(start 133.835648 -267.755624)
		(end 133.835394 -267.755878)
		(width 0.20066)
		(layer "F.Cu")
		(net "M_F_CPU1_SA_DQS_DP<2>")
	)
	(segment
		(start 176.848008 -294.641778)
		(end 179.00523 -294.641778)
		(width 0.1016)
		(layer "F.Cu")
		(net "M_F_CPU1_SA_DQS_DP<2>")
	)
	(segment
		(start 180.007768 -294.34536)
		(end 180.418232 -293.934896)
		(width 0.20066)
		(layer "F.Cu")
		(net "M_F_CPU1_SA_DQS_DP<2>")
	)
	(segment
		(start 180.896006 -294.216582)
		(end 181.444646 -294.216582)
		(width 0.20066)
		(layer "F.Cu")
		(net "M_F_CPU1_SA_DQS_DP<2>")
	)
	(segment
		(start 179.011326 -294.647874)
		(end 179.334668 -294.647874)
		(width 0.20066)
		(layer "F.Cu")
		(net "M_F_CPU1_SA_DQS_DP<2>")
	)
	(segment
		(start 179.334668 -294.647874)
		(end 179.637182 -294.34536)
		(width 0.20066)
		(layer "F.Cu")
		(net "M_F_CPU1_SA_DQS_DP<2>")
	)
	(segment
		(start 179.637182 -294.34536)
		(end 180.007768 -294.34536)
		(width 0.20066)
		(layer "F.Cu")
		(net "M_F_CPU1_SA_DQS_DP<2>")
	)
	(segment
		(start 174.490126 -294.216582)
		(end 174.730664 -293.976044)
		(width 0.20066)
		(layer "F.Cu")
		(net "M_F_CPU1_SA_DQS_DP<2>")
	)
	(segment
		(start 133.835648 -267.219938)
		(end 133.835648 -267.755624)
		(width 0.20066)
		(layer "F.Cu")
		(net "M_F_CPU1_SA_DQS_DP<2>")
	)
	(segment
		(start 172.795946 -294.216582)
		(end 173.900846 -294.216582)
		(width 0.20066)
		(layer "F.Cu")
		(net "M_F_CPU1_SA_DQS_DP<2>")
	)
	(segment
		(start 175.33112 -293.976044)
		(end 175.745648 -294.390572)
		(width 0.20066)
		(layer "F.Cu")
		(net "M_F_CPU1_SA_DQS_DP<2>")
	)
	(segment
		(start 175.745648 -294.390572)
		(end 176.431448 -294.390572)
		(width 0.20066)
		(layer "F.Cu")
		(net "M_F_CPU1_SA_DQS_DP<2>")
	)
	(segment
		(start 154.812746 -281.202384)
		(end 154.424634 -280.814272)
		(width 0.18288)
		(layer "In2.Cu")
		(net "M_F_CPU1_SA_DQS_DP<2>")
	)
	(segment
		(start 134.070598 -267.779754)
		(end 134.046722 -267.755878)
		(width 0.088646)
		(layer "In2.Cu")
		(net "M_F_CPU1_SA_DQS_DP<2>")
	)
	(segment
		(start 171.329604 -294.06088)
		(end 171.206414 -294.18407)
		(width 0.18288)
		(layer "In2.Cu")
		(net "M_F_CPU1_SA_DQS_DP<2>")
	)
	(segment
		(start 155.566618 -283.310584)
		(end 155.566618 -282.047442)
		(width 0.18288)
		(layer "In2.Cu")
		(net "M_F_CPU1_SA_DQS_DP<2>")
	)
	(segment
		(start 171.357798 -294.032686)
		(end 171.329604 -294.06088)
		(width 0.16002)
		(layer "In2.Cu")
		(net "M_F_CPU1_SA_DQS_DP<2>")
	)
	(segment
		(start 167.905176 -289.015932)
		(end 167.609266 -288.301684)
		(width 0.18288)
		(layer "In2.Cu")
		(net "M_F_CPU1_SA_DQS_DP<2>")
	)
	(segment
		(start 169.533316 -293.993316)
		(end 169.349166 -293.809166)
		(width 0.16002)
		(layer "In2.Cu")
		(net "M_F_CPU1_SA_DQS_DP<2>")
	)
	(segment
		(start 169.533316 -294.009572)
		(end 169.533316 -293.993316)
		(width 0.16002)
		(layer "In2.Cu")
		(net "M_F_CPU1_SA_DQS_DP<2>")
	)
	(segment
		(start 167.62984 -289.958526)
		(end 167.905176 -289.293808)
		(width 0.18288)
		(layer "In2.Cu")
		(net "M_F_CPU1_SA_DQS_DP<2>")
	)
	(segment
		(start 135.44296 -268.251432)
		(end 135.432546 -268.245336)
		(width 0.088646)
		(layer "In2.Cu")
		(net "M_F_CPU1_SA_DQS_DP<2>")
	)
	(segment
		(start 157.954726 -285.559246)
		(end 157.954726 -285.54299)
		(width 0.16002)
		(layer "In2.Cu")
		(net "M_F_CPU1_SA_DQS_DP<2>")
	)
	(segment
		(start 149.89556 -274.701254)
		(end 149.895306 -274.701254)
		(width 0.18288)
		(layer "In2.Cu")
		(net "M_F_CPU1_SA_DQS_DP<2>")
	)
	(segment
		(start 160.966658 -287.104328)
		(end 160.30956 -286.44723)
		(width 0.18288)
		(layer "In2.Cu")
		(net "M_F_CPU1_SA_DQS_DP<2>")
	)
	(segment
		(start 156.647896 -284.567884)
		(end 156.259784 -284.179772)
		(width 0.18288)
		(layer "In2.Cu")
		(net "M_F_CPU1_SA_DQS_DP<2>")
	)
	(segment
		(start 169.707814 -294.18407)
		(end 169.56151 -294.037766)
		(width 0.18288)
		(layer "In2.Cu")
		(net "M_F_CPU1_SA_DQS_DP<2>")
	)
	(segment
		(start 160.966658 -287.28035)
		(end 160.966658 -287.104328)
		(width 0.18288)
		(layer "In2.Cu")
		(net "M_F_CPU1_SA_DQS_DP<2>")
	)
	(segment
		(start 140.900404 -268.470126)
		(end 140.84046 -268.410182)
		(width 0.088646)
		(layer "In2.Cu")
		(net "M_F_CPU1_SA_DQS_DP<2>")
	)
	(segment
		(start 158.227268 -285.831788)
		(end 157.98292 -285.58744)
		(width 0.18288)
		(layer "In2.Cu")
		(net "M_F_CPU1_SA_DQS_DP<2>")
	)
	(segment
		(start 163.19881 -288.2392)
		(end 162.65017 -288.2392)
		(width 0.18288)
		(layer "In2.Cu")
		(net "M_F_CPU1_SA_DQS_DP<2>")
	)
	(segment
		(start 157.770576 -285.35884)
		(end 157.75432 -285.35884)
		(width 0.16002)
		(layer "In2.Cu")
		(net "M_F_CPU1_SA_DQS_DP<2>")
	)
	(segment
		(start 172.10151 -293.88943)
		(end 171.930314 -293.718234)
		(width 0.18288)
		(layer "In2.Cu")
		(net "M_F_CPU1_SA_DQS_DP<2>")
	)
	(segment
		(start 163.32327 -288.11474)
		(end 163.19881 -288.2392)
		(width 0.18288)
		(layer "In2.Cu")
		(net "M_F_CPU1_SA_DQS_DP<2>")
	)
	(segment
		(start 159.501332 -286.070294)
		(end 159.485584 -286.070294)
		(width 0.16002)
		(layer "In2.Cu")
		(net "M_F_CPU1_SA_DQS_DP<2>")
	)
	(segment
		(start 163.829746 -288.11474)
		(end 163.32327 -288.11474)
		(width 0.18288)
		(layer "In2.Cu")
		(net "M_F_CPU1_SA_DQS_DP<2>")
	)
	(segment
		(start 169.33291 -293.809166)
		(end 169.304716 -293.780972)
		(width 0.16002)
		(layer "In2.Cu")
		(net "M_F_CPU1_SA_DQS_DP<2>")
	)
	(segment
		(start 146.617436 -272.528284)
		(end 142.630398 -268.540992)
		(width 0.18288)
		(layer "In2.Cu")
		(net "M_F_CPU1_SA_DQS_DP<2>")
	)
	(segment
		(start 168.825418 -293.301674)
		(end 168.64076 -292.785292)
		(width 0.18288)
		(layer "In2.Cu")
		(net "M_F_CPU1_SA_DQS_DP<2>")
	)
	(segment
		(start 159.68599 -286.2707)
		(end 159.68599 -286.254952)
		(width 0.16002)
		(layer "In2.Cu")
		(net "M_F_CPU1_SA_DQS_DP<2>")
	)
	(segment
		(start 152.52065 -278.910034)
		(end 152.52065 -278.734012)
		(width 0.18288)
		(layer "In2.Cu")
		(net "M_F_CPU1_SA_DQS_DP<2>")
	)
	(segment
		(start 171.930314 -293.718234)
		(end 171.67225 -293.718234)
		(width 0.18288)
		(layer "In2.Cu")
		(net "M_F_CPU1_SA_DQS_DP<2>")
	)
	(segment
		(start 156.259784 -284.179772)
		(end 156.259784 -284.00375)
		(width 0.18288)
		(layer "In2.Cu")
		(net "M_F_CPU1_SA_DQS_DP<2>")
	)
	(segment
		(start 153.860754 -280.250392)
		(end 153.472642 -279.86228)
		(width 0.18288)
		(layer "In2.Cu")
		(net "M_F_CPU1_SA_DQS_DP<2>")
	)
	(segment
		(start 167.242236 -287.9344)
		(end 166.945564 -287.811464)
		(width 0.18288)
		(layer "In2.Cu")
		(net "M_F_CPU1_SA_DQS_DP<2>")
	)
	(segment
		(start 157.726126 -285.330646)
		(end 157.453076 -285.057596)
		(width 0.18288)
		(layer "In2.Cu")
		(net "M_F_CPU1_SA_DQS_DP<2>")
	)
	(segment
		(start 154.424634 -280.63825)
		(end 154.036776 -280.250392)
		(width 0.18288)
		(layer "In2.Cu")
		(net "M_F_CPU1_SA_DQS_DP<2>")
	)
	(segment
		(start 142.630398 -268.540992)
		(end 142.459456 -268.470126)
		(width 0.18288)
		(layer "In2.Cu")
		(net "M_F_CPU1_SA_DQS_DP<2>")
	)
	(segment
		(start 140.46581 -268.410182)
		(end 140.250418 -268.19479)
		(width 0.088646)
		(layer "In2.Cu")
		(net "M_F_CPU1_SA_DQS_DP<2>")
	)
	(segment
		(start 168.372028 -292.03396)
		(end 167.62984 -289.958526)
		(width 0.18288)
		(layer "In2.Cu")
		(net "M_F_CPU1_SA_DQS_DP<2>")
	)
	(segment
		(start 142.459456 -268.470126)
		(end 140.900404 -268.470126)
		(width 0.18288)
		(layer "In2.Cu")
		(net "M_F_CPU1_SA_DQS_DP<2>")
	)
	(segment
		(start 154.424634 -280.814272)
		(end 154.424634 -280.63825)
		(width 0.18288)
		(layer "In2.Cu")
		(net "M_F_CPU1_SA_DQS_DP<2>")
	)
	(segment
		(start 152.908762 -279.2984)
		(end 152.52065 -278.910034)
		(width 0.18288)
		(layer "In2.Cu")
		(net "M_F_CPU1_SA_DQS_DP<2>")
	)
	(segment
		(start 159.714184 -286.298894)
		(end 159.68599 -286.2707)
		(width 0.16002)
		(layer "In2.Cu")
		(net "M_F_CPU1_SA_DQS_DP<2>")
	)
	(segment
		(start 169.56151 -294.037766)
		(end 169.533316 -294.009572)
		(width 0.16002)
		(layer "In2.Cu")
		(net "M_F_CPU1_SA_DQS_DP<2>")
	)
	(segment
		(start 161.531046 -287.668716)
		(end 161.355024 -287.668716)
		(width 0.18288)
		(layer "In2.Cu")
		(net "M_F_CPU1_SA_DQS_DP<2>")
	)
	(segment
		(start 155.376626 -281.590242)
		(end 154.988768 -281.202384)
		(width 0.18288)
		(layer "In2.Cu")
		(net "M_F_CPU1_SA_DQS_DP<2>")
	)
	(segment
		(start 161.97707 -288.11474)
		(end 161.531046 -287.668716)
		(width 0.18288)
		(layer "In2.Cu")
		(net "M_F_CPU1_SA_DQS_DP<2>")
	)
	(segment
		(start 171.538392 -293.835836)
		(end 171.357798 -294.01643)
		(width 0.16002)
		(layer "In2.Cu")
		(net "M_F_CPU1_SA_DQS_DP<2>")
	)
	(segment
		(start 167.905176 -289.293808)
		(end 167.905176 -289.015932)
		(width 0.18288)
		(layer "In2.Cu")
		(net "M_F_CPU1_SA_DQS_DP<2>")
	)
	(segment
		(start 172.468794 -293.88943)
		(end 172.10151 -293.88943)
		(width 0.18288)
		(layer "In2.Cu")
		(net "M_F_CPU1_SA_DQS_DP<2>")
	)
	(segment
		(start 171.554648 -293.835836)
		(end 171.538392 -293.835836)
		(width 0.16002)
		(layer "In2.Cu")
		(net "M_F_CPU1_SA_DQS_DP<2>")
	)
	(segment
		(start 164.471604 -287.855914)
		(end 164.088572 -287.855914)
		(width 0.18288)
		(layer "In2.Cu")
		(net "M_F_CPU1_SA_DQS_DP<2>")
	)
	(segment
		(start 165.414198 -287.961324)
		(end 164.577014 -287.961324)
		(width 0.18288)
		(layer "In2.Cu")
		(net "M_F_CPU1_SA_DQS_DP<2>")
	)
	(segment
		(start 157.98292 -285.58744)
		(end 157.954726 -285.559246)
		(width 0.16002)
		(layer "In2.Cu")
		(net "M_F_CPU1_SA_DQS_DP<2>")
	)
	(segment
		(start 159.45739 -286.0421)
		(end 159.247078 -285.831788)
		(width 0.18288)
		(layer "In2.Cu")
		(net "M_F_CPU1_SA_DQS_DP<2>")
	)
	(segment
		(start 156.259784 -284.00375)
		(end 155.566618 -283.310584)
		(width 0.18288)
		(layer "In2.Cu")
		(net "M_F_CPU1_SA_DQS_DP<2>")
	)
	(segment
		(start 168.481502 -292.709854)
		(end 168.29659 -292.192964)
		(width 0.18288)
		(layer "In2.Cu")
		(net "M_F_CPU1_SA_DQS_DP<2>")
	)
	(segment
		(start 167.609266 -288.301684)
		(end 167.242236 -287.9344)
		(width 0.18288)
		(layer "In2.Cu")
		(net "M_F_CPU1_SA_DQS_DP<2>")
	)
	(segment
		(start 168.64076 -292.785292)
		(end 168.481502 -292.709854)
		(width 0.18288)
		(layer "In2.Cu")
		(net "M_F_CPU1_SA_DQS_DP<2>")
	)
	(segment
		(start 153.084784 -279.2984)
		(end 152.908762 -279.2984)
		(width 0.18288)
		(layer "In2.Cu")
		(net "M_F_CPU1_SA_DQS_DP<2>")
	)
	(segment
		(start 153.472642 -279.686258)
		(end 153.084784 -279.2984)
		(width 0.18288)
		(layer "In2.Cu")
		(net "M_F_CPU1_SA_DQS_DP<2>")
	)
	(segment
		(start 150.377398 -276.19071)
		(end 150.167594 -275.683472)
		(width 0.18288)
		(layer "In2.Cu")
		(net "M_F_CPU1_SA_DQS_DP<2>")
	)
	(segment
		(start 159.247078 -285.831788)
		(end 158.227268 -285.831788)
		(width 0.18288)
		(layer "In2.Cu")
		(net "M_F_CPU1_SA_DQS_DP<2>")
	)
	(segment
		(start 148.829776 -273.811492)
		(end 148.829776 -273.63547)
		(width 0.18288)
		(layer "In2.Cu")
		(net "M_F_CPU1_SA_DQS_DP<2>")
	)
	(segment
		(start 149.895306 -274.701254)
		(end 149.39391 -274.199858)
		(width 0.18288)
		(layer "In2.Cu")
		(net "M_F_CPU1_SA_DQS_DP<2>")
	)
	(segment
		(start 169.304716 -293.780972)
		(end 168.825418 -293.301674)
		(width 0.18288)
		(layer "In2.Cu")
		(net "M_F_CPU1_SA_DQS_DP<2>")
	)
	(segment
		(start 160.30956 -286.44723)
		(end 159.86252 -286.44723)
		(width 0.18288)
		(layer "In2.Cu")
		(net "M_F_CPU1_SA_DQS_DP<2>")
	)
	(segment
		(start 134.046722 -267.755878)
		(end 133.835394 -267.755878)
		(width 0.088646)
		(layer "In2.Cu")
		(net "M_F_CPU1_SA_DQS_DP<2>")
	)
	(segment
		(start 152.132792 -278.346154)
		(end 151.95677 -278.346154)
		(width 0.18288)
		(layer "In2.Cu")
		(net "M_F_CPU1_SA_DQS_DP<2>")
	)
	(segment
		(start 159.86252 -286.44723)
		(end 159.714184 -286.298894)
		(width 0.18288)
		(layer "In2.Cu")
		(net "M_F_CPU1_SA_DQS_DP<2>")
	)
	(segment
		(start 165.776148 -287.811464)
		(end 165.414198 -287.961324)
		(width 0.18288)
		(layer "In2.Cu")
		(net "M_F_CPU1_SA_DQS_DP<2>")
	)
	(segment
		(start 140.84046 -268.410182)
		(end 140.46581 -268.410182)
		(width 0.088646)
		(layer "In2.Cu")
		(net "M_F_CPU1_SA_DQS_DP<2>")
	)
	(segment
		(start 169.349166 -293.809166)
		(end 169.33291 -293.809166)
		(width 0.16002)
		(layer "In2.Cu")
		(net "M_F_CPU1_SA_DQS_DP<2>")
	)
	(segment
		(start 157.31363 -285.057596)
		(end 156.823918 -284.567884)
		(width 0.18288)
		(layer "In2.Cu")
		(net "M_F_CPU1_SA_DQS_DP<2>")
	)
	(segment
		(start 159.68599 -286.254952)
		(end 159.501332 -286.070294)
		(width 0.16002)
		(layer "In2.Cu")
		(net "M_F_CPU1_SA_DQS_DP<2>")
	)
	(segment
		(start 134.399274 -268.191234)
		(end 134.070598 -267.779754)
		(width 0.088646)
		(layer "In2.Cu")
		(net "M_F_CPU1_SA_DQS_DP<2>")
	)
	(segment
		(start 166.945564 -287.811464)
		(end 165.776148 -287.811464)
		(width 0.18288)
		(layer "In2.Cu")
		(net "M_F_CPU1_SA_DQS_DP<2>")
	)
	(segment
		(start 164.088572 -287.855914)
		(end 163.829746 -288.11474)
		(width 0.18288)
		(layer "In2.Cu")
		(net "M_F_CPU1_SA_DQS_DP<2>")
	)
	(segment
		(start 155.37688 -281.590242)
		(end 155.376626 -281.590242)
		(width 0.18288)
		(layer "In2.Cu")
		(net "M_F_CPU1_SA_DQS_DP<2>")
	)
	(segment
		(start 150.234904 -275.520912)
		(end 149.89556 -274.701254)
		(width 0.18288)
		(layer "In2.Cu")
		(net "M_F_CPU1_SA_DQS_DP<2>")
	)
	(segment
		(start 140.250418 -268.19479)
		(end 139.944094 -268.19479)
		(width 0.088646)
		(layer "In2.Cu")
		(net "M_F_CPU1_SA_DQS_DP<2>")
	)
	(segment
		(start 150.540212 -276.25802)
		(end 150.377398 -276.19071)
		(width 0.18288)
		(layer "In2.Cu")
		(net "M_F_CPU1_SA_DQS_DP<2>")
	)
	(segment
		(start 151.568658 -277.957788)
		(end 151.568658 -277.78202)
		(width 0.18288)
		(layer "In2.Cu")
		(net "M_F_CPU1_SA_DQS_DP<2>")
	)
	(segment
		(start 134.507478 -268.253972)
		(end 134.399274 -268.191234)
		(width 0.088646)
		(layer "In2.Cu")
		(net "M_F_CPU1_SA_DQS_DP<2>")
	)
	(segment
		(start 148.829776 -273.63547)
		(end 147.802346 -272.60804)
		(width 0.18288)
		(layer "In2.Cu")
		(net "M_F_CPU1_SA_DQS_DP<2>")
	)
	(segment
		(start 157.453076 -285.057596)
		(end 157.31363 -285.057596)
		(width 0.18288)
		(layer "In2.Cu")
		(net "M_F_CPU1_SA_DQS_DP<2>")
	)
	(segment
		(start 157.954726 -285.54299)
		(end 157.770576 -285.35884)
		(width 0.16002)
		(layer "In2.Cu")
		(net "M_F_CPU1_SA_DQS_DP<2>")
	)
	(segment
		(start 159.485584 -286.070294)
		(end 159.45739 -286.0421)
		(width 0.16002)
		(layer "In2.Cu")
		(net "M_F_CPU1_SA_DQS_DP<2>")
	)
	(segment
		(start 155.566618 -282.047442)
		(end 155.37688 -281.590242)
		(width 0.18288)
		(layer "In2.Cu")
		(net "M_F_CPU1_SA_DQS_DP<2>")
	)
	(segment
		(start 162.52571 -288.11474)
		(end 161.97707 -288.11474)
		(width 0.18288)
		(layer "In2.Cu")
		(net "M_F_CPU1_SA_DQS_DP<2>")
	)
	(segment
		(start 172.795946 -294.216582)
		(end 172.468794 -293.88943)
		(width 0.18288)
		(layer "In2.Cu")
		(net "M_F_CPU1_SA_DQS_DP<2>")
	)
	(segment
		(start 157.75432 -285.35884)
		(end 157.726126 -285.330646)
		(width 0.16002)
		(layer "In2.Cu")
		(net "M_F_CPU1_SA_DQS_DP<2>")
	)
	(segment
		(start 156.823918 -284.567884)
		(end 156.647896 -284.567884)
		(width 0.18288)
		(layer "In2.Cu")
		(net "M_F_CPU1_SA_DQS_DP<2>")
	)
	(segment
		(start 162.65017 -288.2392)
		(end 162.52571 -288.11474)
		(width 0.18288)
		(layer "In2.Cu")
		(net "M_F_CPU1_SA_DQS_DP<2>")
	)
	(segment
		(start 171.357798 -294.01643)
		(end 171.357798 -294.032686)
		(width 0.16002)
		(layer "In2.Cu")
		(net "M_F_CPU1_SA_DQS_DP<2>")
	)
	(segment
		(start 150.890478 -277.103586)
		(end 150.540212 -276.25802)
		(width 0.18288)
		(layer "In2.Cu")
		(net "M_F_CPU1_SA_DQS_DP<2>")
	)
	(segment
		(start 153.472642 -279.86228)
		(end 153.472642 -279.686258)
		(width 0.18288)
		(layer "In2.Cu")
		(net "M_F_CPU1_SA_DQS_DP<2>")
	)
	(segment
		(start 150.93442 -277.147528)
		(end 150.890478 -277.103586)
		(width 0.18288)
		(layer "In2.Cu")
		(net "M_F_CPU1_SA_DQS_DP<2>")
	)
	(segment
		(start 171.206414 -294.18407)
		(end 169.707814 -294.18407)
		(width 0.18288)
		(layer "In2.Cu")
		(net "M_F_CPU1_SA_DQS_DP<2>")
	)
	(segment
		(start 151.95677 -278.346154)
		(end 151.568658 -277.957788)
		(width 0.18288)
		(layer "In2.Cu")
		(net "M_F_CPU1_SA_DQS_DP<2>")
	)
	(segment
		(start 149.39391 -274.199858)
		(end 149.217888 -274.199858)
		(width 0.18288)
		(layer "In2.Cu")
		(net "M_F_CPU1_SA_DQS_DP<2>")
	)
	(segment
		(start 151.568658 -277.78202)
		(end 150.93442 -277.147528)
		(width 0.18288)
		(layer "In2.Cu")
		(net "M_F_CPU1_SA_DQS_DP<2>")
	)
	(segment
		(start 152.52065 -278.734012)
		(end 152.132792 -278.346154)
		(width 0.18288)
		(layer "In2.Cu")
		(net "M_F_CPU1_SA_DQS_DP<2>")
	)
	(segment
		(start 147.802346 -272.60804)
		(end 147.60956 -272.528284)
		(width 0.18288)
		(layer "In2.Cu")
		(net "M_F_CPU1_SA_DQS_DP<2>")
	)
	(segment
		(start 147.60956 -272.528284)
		(end 146.617436 -272.528284)
		(width 0.18288)
		(layer "In2.Cu")
		(net "M_F_CPU1_SA_DQS_DP<2>")
	)
	(segment
		(start 154.988768 -281.202384)
		(end 154.812746 -281.202384)
		(width 0.18288)
		(layer "In2.Cu")
		(net "M_F_CPU1_SA_DQS_DP<2>")
	)
	(segment
		(start 150.167594 -275.683472)
		(end 150.234904 -275.520912)
		(width 0.18288)
		(layer "In2.Cu")
		(net "M_F_CPU1_SA_DQS_DP<2>")
	)
	(segment
		(start 161.355024 -287.668716)
		(end 160.966658 -287.28035)
		(width 0.18288)
		(layer "In2.Cu")
		(net "M_F_CPU1_SA_DQS_DP<2>")
	)
	(segment
		(start 164.577014 -287.961324)
		(end 164.471604 -287.855914)
		(width 0.18288)
		(layer "In2.Cu")
		(net "M_F_CPU1_SA_DQS_DP<2>")
	)
	(segment
		(start 171.67225 -293.718234)
		(end 171.554648 -293.835836)
		(width 0.18288)
		(layer "In2.Cu")
		(net "M_F_CPU1_SA_DQS_DP<2>")
	)
	(segment
		(start 149.217888 -274.199858)
		(end 148.829776 -273.811492)
		(width 0.18288)
		(layer "In2.Cu")
		(net "M_F_CPU1_SA_DQS_DP<2>")
	)
	(segment
		(start 168.29659 -292.192964)
		(end 168.372028 -292.03396)
		(width 0.18288)
		(layer "In2.Cu")
		(net "M_F_CPU1_SA_DQS_DP<2>")
	)
	(segment
		(start 154.036776 -280.250392)
		(end 153.860754 -280.250392)
		(width 0.18288)
		(layer "In2.Cu")
		(net "M_F_CPU1_SA_DQS_DP<2>")
	)
	(arc
		(start 135.432546 -268.245336)
		(mid 135.245348 -268.195193)
		(end 135.05815 -268.245336)
		(width 0.088646)
		(layer "In2.Cu")
		(net "M_F_CPU1_SA_DQS_DP<2>")
	)
	(arc
		(start 136.372092 -268.245336)
		(mid 136.184894 -268.195193)
		(end 135.997696 -268.245336)
		(width 0.088646)
		(layer "In2.Cu")
		(net "M_F_CPU1_SA_DQS_DP<2>")
	)
	(arc
		(start 139.756896 -268.245336)
		(mid 139.474194 -268.321112)
		(end 139.191492 -268.245336)
		(width 0.088646)
		(layer "In2.Cu")
		(net "M_F_CPU1_SA_DQS_DP<2>")
	)
	(arc
		(start 139.191492 -268.245336)
		(mid 139.004294 -268.195193)
		(end 138.817096 -268.245336)
		(width 0.088646)
		(layer "In2.Cu")
		(net "M_F_CPU1_SA_DQS_DP<2>")
	)
	(arc
		(start 137.311892 -268.245336)
		(mid 137.124694 -268.195193)
		(end 136.937496 -268.245336)
		(width 0.088646)
		(layer "In2.Cu")
		(net "M_F_CPU1_SA_DQS_DP<2>")
	)
	(arc
		(start 139.944094 -268.19479)
		(mid 139.847166 -268.207741)
		(end 139.756896 -268.245336)
		(width 0.088646)
		(layer "In2.Cu")
		(net "M_F_CPU1_SA_DQS_DP<2>")
	)
	(arc
		(start 135.997696 -268.245336)
		(mid 135.721137 -268.321079)
		(end 135.44296 -268.251432)
		(width 0.088646)
		(layer "In2.Cu")
		(net "M_F_CPU1_SA_DQS_DP<2>")
	)
	(arc
		(start 137.877296 -268.245336)
		(mid 137.594594 -268.321112)
		(end 137.311892 -268.245336)
		(width 0.088646)
		(layer "In2.Cu")
		(net "M_F_CPU1_SA_DQS_DP<2>")
	)
	(arc
		(start 138.251692 -268.245336)
		(mid 138.064494 -268.195193)
		(end 137.877296 -268.245336)
		(width 0.088646)
		(layer "In2.Cu")
		(net "M_F_CPU1_SA_DQS_DP<2>")
	)
	(arc
		(start 136.937496 -268.245336)
		(mid 136.654794 -268.321112)
		(end 136.372092 -268.245336)
		(width 0.088646)
		(layer "In2.Cu")
		(net "M_F_CPU1_SA_DQS_DP<2>")
	)
	(arc
		(start 135.05815 -268.245336)
		(mid 134.783951 -268.321171)
		(end 134.507478 -268.253972)
		(width 0.088646)
		(layer "In2.Cu")
		(net "M_F_CPU1_SA_DQS_DP<2>")
	)
	(arc
		(start 138.817096 -268.245336)
		(mid 138.534394 -268.321112)
		(end 138.251692 -268.245336)
		(width 0.088646)
		(layer "In2.Cu")
		(net "M_F_CPU1_SA_DQS_DP<2>")
	)
	(segment
		(start 180.896006 -303.566576)
		(end 181.444646 -303.566576)
		(width 0.20066)
		(layer "F.Cu")
		(net "M_F_CPU1_SA_DQS_DP<1>")
	)
	(segment
		(start 180.007768 -303.695354)
		(end 180.418232 -303.28489)
		(width 0.20066)
		(layer "F.Cu")
		(net "M_F_CPU1_SA_DQS_DP<1>")
	)
	(segment
		(start 176.848008 -303.991772)
		(end 179.00523 -303.991772)
		(width 0.1016)
		(layer "F.Cu")
		(net "M_F_CPU1_SA_DQS_DP<1>")
	)
	(segment
		(start 130.546094 -269.66164)
		(end 130.546348 -270.167862)
		(width 0.20066)
		(layer "F.Cu")
		(net "M_F_CPU1_SA_DQS_DP<1>")
	)
	(segment
		(start 175.33112 -303.326038)
		(end 175.745648 -303.740566)
		(width 0.20066)
		(layer "F.Cu")
		(net "M_F_CPU1_SA_DQS_DP<1>")
	)
	(segment
		(start 130.546348 -270.167862)
		(end 130.546348 -270.19758)
		(width 0.20066)
		(layer "F.Cu")
		(net "M_F_CPU1_SA_DQS_DP<1>")
	)
	(segment
		(start 176.8221 -303.991772)
		(end 176.848008 -303.991772)
		(width 0.101854)
		(layer "F.Cu")
		(net "M_F_CPU1_SA_DQS_DP<1>")
	)
	(segment
		(start 172.795946 -303.566576)
		(end 173.900846 -303.566576)
		(width 0.20066)
		(layer "F.Cu")
		(net "M_F_CPU1_SA_DQS_DP<1>")
	)
	(segment
		(start 173.900846 -303.566576)
		(end 174.490126 -303.566576)
		(width 0.20066)
		(layer "F.Cu")
		(net "M_F_CPU1_SA_DQS_DP<1>")
	)
	(segment
		(start 180.61432 -303.28489)
		(end 180.896006 -303.566576)
		(width 0.20066)
		(layer "F.Cu")
		(net "M_F_CPU1_SA_DQS_DP<1>")
	)
	(segment
		(start 179.637182 -303.695354)
		(end 180.007768 -303.695354)
		(width 0.20066)
		(layer "F.Cu")
		(net "M_F_CPU1_SA_DQS_DP<1>")
	)
	(segment
		(start 179.334668 -303.997868)
		(end 179.637182 -303.695354)
		(width 0.20066)
		(layer "F.Cu")
		(net "M_F_CPU1_SA_DQS_DP<1>")
	)
	(segment
		(start 175.745648 -303.740566)
		(end 176.431448 -303.740566)
		(width 0.20066)
		(layer "F.Cu")
		(net "M_F_CPU1_SA_DQS_DP<1>")
	)
	(segment
		(start 176.682654 -303.991772)
		(end 176.8221 -303.991772)
		(width 0.20066)
		(layer "F.Cu")
		(net "M_F_CPU1_SA_DQS_DP<1>")
	)
	(segment
		(start 180.418232 -303.28489)
		(end 180.61432 -303.28489)
		(width 0.20066)
		(layer "F.Cu")
		(net "M_F_CPU1_SA_DQS_DP<1>")
	)
	(segment
		(start 179.011326 -303.997868)
		(end 179.334668 -303.997868)
		(width 0.20066)
		(layer "F.Cu")
		(net "M_F_CPU1_SA_DQS_DP<1>")
	)
	(segment
		(start 179.00523 -303.991772)
		(end 179.011326 -303.997868)
		(width 0.1016)
		(layer "F.Cu")
		(net "M_F_CPU1_SA_DQS_DP<1>")
	)
	(segment
		(start 176.431448 -303.740566)
		(end 176.682654 -303.991772)
		(width 0.20066)
		(layer "F.Cu")
		(net "M_F_CPU1_SA_DQS_DP<1>")
	)
	(segment
		(start 174.730664 -303.326038)
		(end 175.33112 -303.326038)
		(width 0.20066)
		(layer "F.Cu")
		(net "M_F_CPU1_SA_DQS_DP<1>")
	)
	(segment
		(start 174.490126 -303.566576)
		(end 174.730664 -303.326038)
		(width 0.20066)
		(layer "F.Cu")
		(net "M_F_CPU1_SA_DQS_DP<1>")
	)
	(segment
		(start 153.364438 -292.281356)
		(end 152.793192 -291.710364)
		(width 0.18288)
		(layer "In4.Cu")
		(net "M_F_CPU1_SA_DQS_DP<1>")
	)
	(segment
		(start 142.663164 -274.499832)
		(end 142.55115 -274.387818)
		(width 0.18288)
		(layer "In4.Cu")
		(net "M_F_CPU1_SA_DQS_DP<1>")
	)
	(segment
		(start 168.751758 -303.23282)
		(end 168.205658 -303.23282)
		(width 0.18288)
		(layer "In4.Cu")
		(net "M_F_CPU1_SA_DQS_DP<1>")
	)
	(segment
		(start 172.795946 -303.566576)
		(end 172.516546 -303.287176)
		(width 0.18288)
		(layer "In4.Cu")
		(net "M_F_CPU1_SA_DQS_DP<1>")
	)
	(segment
		(start 165.150546 -301.367698)
		(end 164.69614 -301.064168)
		(width 0.18288)
		(layer "In4.Cu")
		(net "M_F_CPU1_SA_DQS_DP<1>")
	)
	(segment
		(start 171.230798 -303.23282)
		(end 170.684698 -303.23282)
		(width 0.18288)
		(layer "In4.Cu")
		(net "M_F_CPU1_SA_DQS_DP<1>")
	)
	(segment
		(start 160.885886 -299.480986)
		(end 160.520126 -299.115226)
		(width 0.18288)
		(layer "In4.Cu")
		(net "M_F_CPU1_SA_DQS_DP<1>")
	)
	(segment
		(start 139.523724 -271.83715)
		(end 139.523724 -271.667224)
		(width 0.088646)
		(layer "In4.Cu")
		(net "M_F_CPU1_SA_DQS_DP<1>")
	)
	(segment
		(start 141.989556 -274.387818)
		(end 139.829794 -272.228056)
		(width 0.18288)
		(layer "In4.Cu")
		(net "M_F_CPU1_SA_DQS_DP<1>")
	)
	(segment
		(start 166.300404 -302.335946)
		(end 166.300404 -302.159924)
		(width 0.18288)
		(layer "In4.Cu")
		(net "M_F_CPU1_SA_DQS_DP<1>")
	)
	(segment
		(start 131.153916 -270.65859)
		(end 131.089146 -270.607536)
		(width 0.088646)
		(layer "In4.Cu")
		(net "M_F_CPU1_SA_DQS_DP<1>")
	)
	(segment
		(start 170.684698 -303.23282)
		(end 170.560238 -303.10836)
		(width 0.18288)
		(layer "In4.Cu")
		(net "M_F_CPU1_SA_DQS_DP<1>")
	)
	(segment
		(start 161.376106 -299.480986)
		(end 160.885886 -299.480986)
		(width 0.18288)
		(layer "In4.Cu")
		(net "M_F_CPU1_SA_DQS_DP<1>")
	)
	(segment
		(start 138.247628 -271.498314)
		(end 138.24585 -271.497298)
		(width 0.088646)
		(layer "In4.Cu")
		(net "M_F_CPU1_SA_DQS_DP<1>")
	)
	(segment
		(start 132.155946 -270.69415)
		(end 132.145024 -270.688308)
		(width 0.088646)
		(layer "In4.Cu")
		(net "M_F_CPU1_SA_DQS_DP<1>")
	)
	(segment
		(start 131.767072 -270.688054)
		(end 131.757166 -270.693642)
		(width 0.088646)
		(layer "In4.Cu")
		(net "M_F_CPU1_SA_DQS_DP<1>")
	)
	(segment
		(start 160.520126 -298.466256)
		(end 159.81426 -297.76039)
		(width 0.18288)
		(layer "In4.Cu")
		(net "M_F_CPU1_SA_DQS_DP<1>")
	)
	(segment
		(start 135.527796 -270.687038)
		(end 135.513064 -270.695674)
		(width 0.088646)
		(layer "In4.Cu")
		(net "M_F_CPU1_SA_DQS_DP<1>")
	)
	(segment
		(start 136.467596 -270.687038)
		(end 136.452864 -270.695674)
		(width 0.088646)
		(layer "In4.Cu")
		(net "M_F_CPU1_SA_DQS_DP<1>")
	)
	(segment
		(start 153.926794 -292.843712)
		(end 153.750772 -292.843712)
		(width 0.18288)
		(layer "In4.Cu")
		(net "M_F_CPU1_SA_DQS_DP<1>")
	)
	(segment
		(start 166.686738 -302.72228)
		(end 166.300404 -302.335946)
		(width 0.18288)
		(layer "In4.Cu")
		(net "M_F_CPU1_SA_DQS_DP<1>")
	)
	(segment
		(start 142.55115 -274.387818)
		(end 141.989556 -274.387818)
		(width 0.18288)
		(layer "In4.Cu")
		(net "M_F_CPU1_SA_DQS_DP<1>")
	)
	(segment
		(start 156.209746 -295.302686)
		(end 156.209746 -295.126664)
		(width 0.18288)
		(layer "In4.Cu")
		(net "M_F_CPU1_SA_DQS_DP<1>")
	)
	(segment
		(start 159.81426 -297.76039)
		(end 159.638238 -297.76039)
		(width 0.18288)
		(layer "In4.Cu")
		(net "M_F_CPU1_SA_DQS_DP<1>")
	)
	(segment
		(start 139.813284 -272.12671)
		(end 139.523724 -271.83715)
		(width 0.088646)
		(layer "In4.Cu")
		(net "M_F_CPU1_SA_DQS_DP<1>")
	)
	(segment
		(start 159.251904 -297.198034)
		(end 158.815024 -296.761154)
		(width 0.18288)
		(layer "In4.Cu")
		(net "M_F_CPU1_SA_DQS_DP<1>")
	)
	(segment
		(start 159.251904 -297.374056)
		(end 159.251904 -297.198034)
		(width 0.18288)
		(layer "In4.Cu")
		(net "M_F_CPU1_SA_DQS_DP<1>")
	)
	(segment
		(start 164.66185 -300.891702)
		(end 163.874704 -300.365922)
		(width 0.18288)
		(layer "In4.Cu")
		(net "M_F_CPU1_SA_DQS_DP<1>")
	)
	(segment
		(start 132.145024 -270.688308)
		(end 132.142992 -270.687038)
		(width 0.088646)
		(layer "In4.Cu")
		(net "M_F_CPU1_SA_DQS_DP<1>")
	)
	(segment
		(start 131.203192 -270.687038)
		(end 131.153916 -270.65859)
		(width 0.088646)
		(layer "In4.Cu")
		(net "M_F_CPU1_SA_DQS_DP<1>")
	)
	(segment
		(start 171.355258 -303.10836)
		(end 171.230798 -303.23282)
		(width 0.18288)
		(layer "In4.Cu")
		(net "M_F_CPU1_SA_DQS_DP<1>")
	)
	(segment
		(start 139.523724 -271.667224)
		(end 139.307316 -271.450816)
		(width 0.088646)
		(layer "In4.Cu")
		(net "M_F_CPU1_SA_DQS_DP<1>")
	)
	(segment
		(start 131.757166 -270.693642)
		(end 131.73329 -270.706596)
		(width 0.088646)
		(layer "In4.Cu")
		(net "M_F_CPU1_SA_DQS_DP<1>")
	)
	(segment
		(start 163.874704 -300.365922)
		(end 163.701984 -300.400212)
		(width 0.18288)
		(layer "In4.Cu")
		(net "M_F_CPU1_SA_DQS_DP<1>")
	)
	(segment
		(start 163.213288 -299.923962)
		(end 162.54603 -299.478192)
		(width 0.18288)
		(layer "In4.Cu")
		(net "M_F_CPU1_SA_DQS_DP<1>")
	)
	(segment
		(start 155.823666 -294.740584)
		(end 155.647644 -294.740584)
		(width 0.18288)
		(layer "In4.Cu")
		(net "M_F_CPU1_SA_DQS_DP<1>")
	)
	(segment
		(start 162.005264 -299.741082)
		(end 161.636202 -299.741082)
		(width 0.18288)
		(layer "In4.Cu")
		(net "M_F_CPU1_SA_DQS_DP<1>")
	)
	(segment
		(start 155.647644 -294.740584)
		(end 155.26131 -294.35425)
		(width 0.18288)
		(layer "In4.Cu")
		(net "M_F_CPU1_SA_DQS_DP<1>")
	)
	(segment
		(start 156.59608 -295.68902)
		(end 156.209746 -295.302686)
		(width 0.18288)
		(layer "In4.Cu")
		(net "M_F_CPU1_SA_DQS_DP<1>")
	)
	(segment
		(start 156.772102 -295.68902)
		(end 156.59608 -295.68902)
		(width 0.18288)
		(layer "In4.Cu")
		(net "M_F_CPU1_SA_DQS_DP<1>")
	)
	(segment
		(start 164.69614 -301.064168)
		(end 164.66185 -300.891702)
		(width 0.18288)
		(layer "In4.Cu")
		(net "M_F_CPU1_SA_DQS_DP<1>")
	)
	(segment
		(start 168.876218 -303.10836)
		(end 168.751758 -303.23282)
		(width 0.18288)
		(layer "In4.Cu")
		(net "M_F_CPU1_SA_DQS_DP<1>")
	)
	(segment
		(start 154.312874 -293.405814)
		(end 154.312874 -293.229792)
		(width 0.18288)
		(layer "In4.Cu")
		(net "M_F_CPU1_SA_DQS_DP<1>")
	)
	(segment
		(start 152.793192 -291.710364)
		(end 147.785836 -279.622758)
		(width 0.18288)
		(layer "In4.Cu")
		(net "M_F_CPU1_SA_DQS_DP<1>")
	)
	(segment
		(start 154.699208 -293.792148)
		(end 154.312874 -293.405814)
		(width 0.18288)
		(layer "In4.Cu")
		(net "M_F_CPU1_SA_DQS_DP<1>")
	)
	(segment
		(start 139.829794 -272.228056)
		(end 139.813284 -272.12671)
		(width 0.088646)
		(layer "In4.Cu")
		(net "M_F_CPU1_SA_DQS_DP<1>")
	)
	(segment
		(start 172.080174 -303.287176)
		(end 171.901358 -303.10836)
		(width 0.18288)
		(layer "In4.Cu")
		(net "M_F_CPU1_SA_DQS_DP<1>")
	)
	(segment
		(start 154.87523 -293.792148)
		(end 154.699208 -293.792148)
		(width 0.18288)
		(layer "In4.Cu")
		(net "M_F_CPU1_SA_DQS_DP<1>")
	)
	(segment
		(start 162.268154 -299.478192)
		(end 162.005264 -299.741082)
		(width 0.18288)
		(layer "In4.Cu")
		(net "M_F_CPU1_SA_DQS_DP<1>")
	)
	(segment
		(start 138.266678 -271.50949)
		(end 138.251946 -271.500854)
		(width 0.088646)
		(layer "In4.Cu")
		(net "M_F_CPU1_SA_DQS_DP<1>")
	)
	(segment
		(start 168.081198 -303.10836)
		(end 167.24884 -303.10836)
		(width 0.18288)
		(layer "In4.Cu")
		(net "M_F_CPU1_SA_DQS_DP<1>")
	)
	(segment
		(start 153.364438 -292.457378)
		(end 153.364438 -292.281356)
		(width 0.18288)
		(layer "In4.Cu")
		(net "M_F_CPU1_SA_DQS_DP<1>")
	)
	(segment
		(start 147.785836 -279.622758)
		(end 142.663164 -274.499832)
		(width 0.18288)
		(layer "In4.Cu")
		(net "M_F_CPU1_SA_DQS_DP<1>")
	)
	(segment
		(start 156.209746 -295.126664)
		(end 155.823666 -294.740584)
		(width 0.18288)
		(layer "In4.Cu")
		(net "M_F_CPU1_SA_DQS_DP<1>")
	)
	(segment
		(start 131.700778 -270.721074)
		(end 131.67995 -270.728694)
		(width 0.088646)
		(layer "In4.Cu")
		(net "M_F_CPU1_SA_DQS_DP<1>")
	)
	(segment
		(start 133.088888 -270.69034)
		(end 133.077204 -270.683736)
		(width 0.088646)
		(layer "In4.Cu")
		(net "M_F_CPU1_SA_DQS_DP<1>")
	)
	(segment
		(start 157.158182 -296.0751)
		(end 156.772102 -295.68902)
		(width 0.18288)
		(layer "In4.Cu")
		(net "M_F_CPU1_SA_DQS_DP<1>")
	)
	(segment
		(start 163.247578 -300.096682)
		(end 163.213288 -299.923962)
		(width 0.18288)
		(layer "In4.Cu")
		(net "M_F_CPU1_SA_DQS_DP<1>")
	)
	(segment
		(start 166.86276 -302.72228)
		(end 166.686738 -302.72228)
		(width 0.18288)
		(layer "In4.Cu")
		(net "M_F_CPU1_SA_DQS_DP<1>")
	)
	(segment
		(start 139.307316 -271.450816)
		(end 139.003532 -271.450816)
		(width 0.088646)
		(layer "In4.Cu")
		(net "M_F_CPU1_SA_DQS_DP<1>")
	)
	(segment
		(start 155.26131 -294.178228)
		(end 154.87523 -293.792148)
		(width 0.18288)
		(layer "In4.Cu")
		(net "M_F_CPU1_SA_DQS_DP<1>")
	)
	(segment
		(start 163.701984 -300.400212)
		(end 163.247578 -300.096682)
		(width 0.18288)
		(layer "In4.Cu")
		(net "M_F_CPU1_SA_DQS_DP<1>")
	)
	(segment
		(start 153.750772 -292.843712)
		(end 153.364438 -292.457378)
		(width 0.18288)
		(layer "In4.Cu")
		(net "M_F_CPU1_SA_DQS_DP<1>")
	)
	(segment
		(start 162.54603 -299.478192)
		(end 162.268154 -299.478192)
		(width 0.18288)
		(layer "In4.Cu")
		(net "M_F_CPU1_SA_DQS_DP<1>")
	)
	(segment
		(start 137.790682 -270.692118)
		(end 137.781792 -270.687038)
		(width 0.088646)
		(layer "In4.Cu")
		(net "M_F_CPU1_SA_DQS_DP<1>")
	)
	(segment
		(start 159.638238 -297.76039)
		(end 159.251904 -297.374056)
		(width 0.18288)
		(layer "In4.Cu")
		(net "M_F_CPU1_SA_DQS_DP<1>")
	)
	(segment
		(start 160.520126 -299.115226)
		(end 160.520126 -298.466256)
		(width 0.18288)
		(layer "In4.Cu")
		(net "M_F_CPU1_SA_DQS_DP<1>")
	)
	(segment
		(start 137.407396 -270.687038)
		(end 137.392664 -270.695674)
		(width 0.088646)
		(layer "In4.Cu")
		(net "M_F_CPU1_SA_DQS_DP<1>")
	)
	(segment
		(start 131.089146 -270.607536)
		(end 130.760216 -270.195548)
		(width 0.088646)
		(layer "In4.Cu")
		(net "M_F_CPU1_SA_DQS_DP<1>")
	)
	(segment
		(start 167.24884 -303.10836)
		(end 166.86276 -302.72228)
		(width 0.18288)
		(layer "In4.Cu")
		(net "M_F_CPU1_SA_DQS_DP<1>")
	)
	(segment
		(start 130.757676 -270.19758)
		(end 130.546348 -270.19758)
		(width 0.088646)
		(layer "In4.Cu")
		(net "M_F_CPU1_SA_DQS_DP<1>")
	)
	(segment
		(start 161.636202 -299.741082)
		(end 161.376106 -299.480986)
		(width 0.18288)
		(layer "In4.Cu")
		(net "M_F_CPU1_SA_DQS_DP<1>")
	)
	(segment
		(start 138.24966 -271.499584)
		(end 138.247628 -271.498314)
		(width 0.088646)
		(layer "In4.Cu")
		(net "M_F_CPU1_SA_DQS_DP<1>")
	)
	(segment
		(start 158.815024 -296.761154)
		(end 157.158182 -296.0751)
		(width 0.18288)
		(layer "In4.Cu")
		(net "M_F_CPU1_SA_DQS_DP<1>")
	)
	(segment
		(start 134.587996 -270.687038)
		(end 134.573264 -270.695674)
		(width 0.088646)
		(layer "In4.Cu")
		(net "M_F_CPU1_SA_DQS_DP<1>")
	)
	(segment
		(start 168.205658 -303.23282)
		(end 168.081198 -303.10836)
		(width 0.18288)
		(layer "In4.Cu")
		(net "M_F_CPU1_SA_DQS_DP<1>")
	)
	(segment
		(start 172.516546 -303.287176)
		(end 172.080174 -303.287176)
		(width 0.18288)
		(layer "In4.Cu")
		(net "M_F_CPU1_SA_DQS_DP<1>")
	)
	(segment
		(start 138.251946 -271.500854)
		(end 138.24966 -271.499584)
		(width 0.088646)
		(layer "In4.Cu")
		(net "M_F_CPU1_SA_DQS_DP<1>")
	)
	(segment
		(start 165.777164 -301.636684)
		(end 165.323266 -301.333408)
		(width 0.18288)
		(layer "In4.Cu")
		(net "M_F_CPU1_SA_DQS_DP<1>")
	)
	(segment
		(start 165.323266 -301.333408)
		(end 165.150546 -301.367698)
		(width 0.18288)
		(layer "In4.Cu")
		(net "M_F_CPU1_SA_DQS_DP<1>")
	)
	(segment
		(start 170.560238 -303.10836)
		(end 168.876218 -303.10836)
		(width 0.18288)
		(layer "In4.Cu")
		(net "M_F_CPU1_SA_DQS_DP<1>")
	)
	(segment
		(start 171.901358 -303.10836)
		(end 171.355258 -303.10836)
		(width 0.18288)
		(layer "In4.Cu")
		(net "M_F_CPU1_SA_DQS_DP<1>")
	)
	(segment
		(start 131.768596 -270.687038)
		(end 131.767072 -270.688054)
		(width 0.088646)
		(layer "In4.Cu")
		(net "M_F_CPU1_SA_DQS_DP<1>")
	)
	(segment
		(start 130.760216 -270.195548)
		(end 130.757676 -270.19758)
		(width 0.088646)
		(layer "In4.Cu")
		(net "M_F_CPU1_SA_DQS_DP<1>")
	)
	(segment
		(start 155.26131 -294.35425)
		(end 155.26131 -294.178228)
		(width 0.18288)
		(layer "In4.Cu")
		(net "M_F_CPU1_SA_DQS_DP<1>")
	)
	(segment
		(start 154.312874 -293.229792)
		(end 153.926794 -292.843712)
		(width 0.18288)
		(layer "In4.Cu")
		(net "M_F_CPU1_SA_DQS_DP<1>")
	)
	(segment
		(start 166.300404 -302.159924)
		(end 165.777164 -301.636684)
		(width 0.18288)
		(layer "In4.Cu")
		(net "M_F_CPU1_SA_DQS_DP<1>")
	)
	(segment
		(start 131.701794 -270.72082)
		(end 131.700778 -270.721074)
		(width 0.088646)
		(layer "In4.Cu")
		(net "M_F_CPU1_SA_DQS_DP<1>")
	)
	(arc
		(start 136.841992 -270.687038)
		(mid 136.654794 -270.636895)
		(end 136.467596 -270.687038)
		(width 0.088646)
		(layer "In4.Cu")
		(net "M_F_CPU1_SA_DQS_DP<1>")
	)
	(arc
		(start 138.24585 -271.497298)
		(mid 138.043263 -271.290947)
		(end 137.969244 -271.011396)
		(width 0.088646)
		(layer "In4.Cu")
		(net "M_F_CPU1_SA_DQS_DP<1>")
	)
	(arc
		(start 137.781792 -270.687038)
		(mid 137.594594 -270.636895)
		(end 137.407396 -270.687038)
		(width 0.088646)
		(layer "In4.Cu")
		(net "M_F_CPU1_SA_DQS_DP<1>")
	)
	(arc
		(start 131.67995 -270.728694)
		(mid 131.436945 -270.760803)
		(end 131.203192 -270.687038)
		(width 0.088646)
		(layer "In4.Cu")
		(net "M_F_CPU1_SA_DQS_DP<1>")
	)
	(arc
		(start 135.513064 -270.695674)
		(mid 135.236589 -270.762994)
		(end 134.962392 -270.687038)
		(width 0.088646)
		(layer "In4.Cu")
		(net "M_F_CPU1_SA_DQS_DP<1>")
	)
	(arc
		(start 138.81735 -271.500854)
		(mid 138.543151 -271.576689)
		(end 138.266678 -271.50949)
		(width 0.088646)
		(layer "In4.Cu")
		(net "M_F_CPU1_SA_DQS_DP<1>")
	)
	(arc
		(start 136.452864 -270.695674)
		(mid 136.176389 -270.762994)
		(end 135.902192 -270.687038)
		(width 0.088646)
		(layer "In4.Cu")
		(net "M_F_CPU1_SA_DQS_DP<1>")
	)
	(arc
		(start 133.648196 -270.687038)
		(mid 133.368993 -270.762678)
		(end 133.088888 -270.69034)
		(width 0.088646)
		(layer "In4.Cu")
		(net "M_F_CPU1_SA_DQS_DP<1>")
	)
	(arc
		(start 135.902192 -270.687038)
		(mid 135.714994 -270.636895)
		(end 135.527796 -270.687038)
		(width 0.088646)
		(layer "In4.Cu")
		(net "M_F_CPU1_SA_DQS_DP<1>")
	)
	(arc
		(start 134.962392 -270.687038)
		(mid 134.775194 -270.636895)
		(end 134.587996 -270.687038)
		(width 0.088646)
		(layer "In4.Cu")
		(net "M_F_CPU1_SA_DQS_DP<1>")
	)
	(arc
		(start 134.573264 -270.695674)
		(mid 134.296789 -270.762994)
		(end 134.022592 -270.687038)
		(width 0.088646)
		(layer "In4.Cu")
		(net "M_F_CPU1_SA_DQS_DP<1>")
	)
	(arc
		(start 132.142992 -270.687038)
		(mid 131.955794 -270.636895)
		(end 131.768596 -270.687038)
		(width 0.088646)
		(layer "In4.Cu")
		(net "M_F_CPU1_SA_DQS_DP<1>")
	)
	(arc
		(start 132.708396 -270.687038)
		(mid 132.433114 -270.762642)
		(end 132.155946 -270.69415)
		(width 0.088646)
		(layer "In4.Cu")
		(net "M_F_CPU1_SA_DQS_DP<1>")
	)
	(arc
		(start 139.003532 -271.450816)
		(mid 138.907161 -271.463635)
		(end 138.81735 -271.500854)
		(width 0.088646)
		(layer "In4.Cu")
		(net "M_F_CPU1_SA_DQS_DP<1>")
	)
	(arc
		(start 137.392664 -270.695674)
		(mid 137.116189 -270.762994)
		(end 136.841992 -270.687038)
		(width 0.088646)
		(layer "In4.Cu")
		(net "M_F_CPU1_SA_DQS_DP<1>")
	)
	(arc
		(start 134.022592 -270.687038)
		(mid 133.835394 -270.636895)
		(end 133.648196 -270.687038)
		(width 0.088646)
		(layer "In4.Cu")
		(net "M_F_CPU1_SA_DQS_DP<1>")
	)
	(arc
		(start 133.077204 -270.683736)
		(mid 132.892349 -270.636786)
		(end 132.708396 -270.687038)
		(width 0.088646)
		(layer "In4.Cu")
		(net "M_F_CPU1_SA_DQS_DP<1>")
	)
	(arc
		(start 131.73329 -270.706596)
		(mid 131.717796 -270.714269)
		(end 131.701794 -270.72082)
		(width 0.088646)
		(layer "In4.Cu")
		(net "M_F_CPU1_SA_DQS_DP<1>")
	)
	(arc
		(start 137.969244 -271.011396)
		(mid 137.921565 -270.828496)
		(end 137.790682 -270.692118)
		(width 0.088646)
		(layer "In4.Cu")
		(net "M_F_CPU1_SA_DQS_DP<1>")
	)
	(segment
		(start 174.490126 -312.91657)
		(end 174.730664 -312.676032)
		(width 0.20066)
		(layer "F.Cu")
		(net "M_F_CPU1_SA_DQS_DP<0>")
	)
	(segment
		(start 176.848008 -313.341766)
		(end 179.00523 -313.341766)
		(width 0.1016)
		(layer "F.Cu")
		(net "M_F_CPU1_SA_DQS_DP<0>")
	)
	(segment
		(start 180.007768 -313.045348)
		(end 180.418232 -312.634884)
		(width 0.20066)
		(layer "F.Cu")
		(net "M_F_CPU1_SA_DQS_DP<0>")
	)
	(segment
		(start 179.00523 -313.341766)
		(end 179.011326 -313.347862)
		(width 0.1016)
		(layer "F.Cu")
		(net "M_F_CPU1_SA_DQS_DP<0>")
	)
	(segment
		(start 179.011326 -313.347862)
		(end 179.334668 -313.347862)
		(width 0.20066)
		(layer "F.Cu")
		(net "M_F_CPU1_SA_DQS_DP<0>")
	)
	(segment
		(start 175.33112 -312.676032)
		(end 175.745648 -313.09056)
		(width 0.20066)
		(layer "F.Cu")
		(net "M_F_CPU1_SA_DQS_DP<0>")
	)
	(segment
		(start 174.730664 -312.676032)
		(end 175.33112 -312.676032)
		(width 0.20066)
		(layer "F.Cu")
		(net "M_F_CPU1_SA_DQS_DP<0>")
	)
	(segment
		(start 176.8221 -313.341766)
		(end 176.848008 -313.341766)
		(width 0.101854)
		(layer "F.Cu")
		(net "M_F_CPU1_SA_DQS_DP<0>")
	)
	(segment
		(start 179.334668 -313.347862)
		(end 179.637182 -313.045348)
		(width 0.20066)
		(layer "F.Cu")
		(net "M_F_CPU1_SA_DQS_DP<0>")
	)
	(segment
		(start 176.431448 -313.09056)
		(end 176.682654 -313.341766)
		(width 0.20066)
		(layer "F.Cu")
		(net "M_F_CPU1_SA_DQS_DP<0>")
	)
	(segment
		(start 172.795946 -312.91657)
		(end 173.900846 -312.91657)
		(width 0.20066)
		(layer "F.Cu")
		(net "M_F_CPU1_SA_DQS_DP<0>")
	)
	(segment
		(start 132.895848 -276.986492)
		(end 132.895848 -277.522178)
		(width 0.20066)
		(layer "F.Cu")
		(net "M_F_CPU1_SA_DQS_DP<0>")
	)
	(segment
		(start 179.637182 -313.045348)
		(end 180.007768 -313.045348)
		(width 0.20066)
		(layer "F.Cu")
		(net "M_F_CPU1_SA_DQS_DP<0>")
	)
	(segment
		(start 180.61432 -312.634884)
		(end 180.896006 -312.91657)
		(width 0.20066)
		(layer "F.Cu")
		(net "M_F_CPU1_SA_DQS_DP<0>")
	)
	(segment
		(start 176.682654 -313.341766)
		(end 176.8221 -313.341766)
		(width 0.20066)
		(layer "F.Cu")
		(net "M_F_CPU1_SA_DQS_DP<0>")
	)
	(segment
		(start 180.896006 -312.91657)
		(end 181.444646 -312.91657)
		(width 0.20066)
		(layer "F.Cu")
		(net "M_F_CPU1_SA_DQS_DP<0>")
	)
	(segment
		(start 180.418232 -312.634884)
		(end 180.61432 -312.634884)
		(width 0.20066)
		(layer "F.Cu")
		(net "M_F_CPU1_SA_DQS_DP<0>")
	)
	(segment
		(start 132.895848 -277.522178)
		(end 132.895594 -277.522432)
		(width 0.20066)
		(layer "F.Cu")
		(net "M_F_CPU1_SA_DQS_DP<0>")
	)
	(segment
		(start 173.900846 -312.91657)
		(end 174.490126 -312.91657)
		(width 0.20066)
		(layer "F.Cu")
		(net "M_F_CPU1_SA_DQS_DP<0>")
	)
	(segment
		(start 175.745648 -313.09056)
		(end 176.431448 -313.09056)
		(width 0.20066)
		(layer "F.Cu")
		(net "M_F_CPU1_SA_DQS_DP<0>")
	)
	(segment
		(start 161.889694 -312.635138)
		(end 161.889694 -312.618882)
		(width 0.16002)
		(layer "In2.Cu")
		(net "M_F_CPU1_SA_DQS_DP<0>")
	)
	(segment
		(start 157.836108 -313.492642)
		(end 157.651958 -313.308492)
		(width 0.16002)
		(layer "In2.Cu")
		(net "M_F_CPU1_SA_DQS_DP<0>")
	)
	(segment
		(start 138.7221 -278.82596)
		(end 138.711178 -278.81961)
		(width 0.088646)
		(layer "In2.Cu")
		(net "M_F_CPU1_SA_DQS_DP<0>")
	)
	(segment
		(start 165.142418 -313.280298)
		(end 164.911532 -313.049412)
		(width 0.18288)
		(layer "In2.Cu")
		(net "M_F_CPU1_SA_DQS_DP<0>")
	)
	(segment
		(start 167.581072 -313.280298)
		(end 167.552878 -313.308492)
		(width 0.16002)
		(layer "In2.Cu")
		(net "M_F_CPU1_SA_DQS_DP<0>")
	)
	(segment
		(start 165.170612 -313.308492)
		(end 165.142418 -313.280298)
		(width 0.16002)
		(layer "In2.Cu")
		(net "M_F_CPU1_SA_DQS_DP<0>")
	)
	(segment
		(start 139.516358 -278.912066)
		(end 139.043664 -278.912066)
		(width 0.088646)
		(layer "In2.Cu")
		(net "M_F_CPU1_SA_DQS_DP<0>")
	)
	(segment
		(start 157.651958 -313.308492)
		(end 157.635702 -313.308492)
		(width 0.16002)
		(layer "In2.Cu")
		(net "M_F_CPU1_SA_DQS_DP<0>")
	)
	(segment
		(start 161.661094 -312.406538)
		(end 161.551366 -312.29681)
		(width 0.18288)
		(layer "In2.Cu")
		(net "M_F_CPU1_SA_DQS_DP<0>")
	)
	(segment
		(start 161.551366 -312.29681)
		(end 161.077148 -312.29681)
		(width 0.18288)
		(layer "In2.Cu")
		(net "M_F_CPU1_SA_DQS_DP<0>")
	)
	(segment
		(start 140.603986 -280.085038)
		(end 140.09878 -279.579324)
		(width 0.18288)
		(layer "In2.Cu")
		(net "M_F_CPU1_SA_DQS_DP<0>")
	)
	(segment
		(start 147.684998 -304.116232)
		(end 147.684998 -297.951906)
		(width 0.18288)
		(layer "In2.Cu")
		(net "M_F_CPU1_SA_DQS_DP<0>")
	)
	(segment
		(start 143.888206 -292.264846)
		(end 142.898114 -289.873944)
		(width 0.18288)
		(layer "In2.Cu")
		(net "M_F_CPU1_SA_DQS_DP<0>")
	)
	(segment
		(start 157.1371 -312.80989)
		(end 156.378656 -312.80989)
		(width 0.18288)
		(layer "In2.Cu")
		(net "M_F_CPU1_SA_DQS_DP<0>")
	)
	(segment
		(start 169.546016 -312.715656)
		(end 169.546016 -312.699908)
		(width 0.16002)
		(layer "In2.Cu")
		(net "M_F_CPU1_SA_DQS_DP<0>")
	)
	(segment
		(start 161.917888 -312.663332)
		(end 161.889694 -312.635138)
		(width 0.16002)
		(layer "In2.Cu")
		(net "M_F_CPU1_SA_DQS_DP<0>")
	)
	(segment
		(start 164.395658 -313.35345)
		(end 164.023548 -313.35345)
		(width 0.18288)
		(layer "In2.Cu")
		(net "M_F_CPU1_SA_DQS_DP<0>")
	)
	(segment
		(start 169.704258 -312.873898)
		(end 169.57421 -312.74385)
		(width 0.18288)
		(layer "In2.Cu")
		(net "M_F_CPU1_SA_DQS_DP<0>")
	)
	(segment
		(start 169.546016 -312.699908)
		(end 169.403014 -312.556906)
		(width 0.16002)
		(layer "In2.Cu")
		(net "M_F_CPU1_SA_DQS_DP<0>")
	)
	(segment
		(start 169.403014 -312.556906)
		(end 169.387266 -312.556906)
		(width 0.16002)
		(layer "In2.Cu")
		(net "M_F_CPU1_SA_DQS_DP<0>")
	)
	(segment
		(start 172.795946 -312.91657)
		(end 172.510958 -312.631582)
		(width 0.18288)
		(layer "In2.Cu")
		(net "M_F_CPU1_SA_DQS_DP<0>")
	)
	(segment
		(start 146.34845 -294.724836)
		(end 143.888206 -292.264846)
		(width 0.18288)
		(layer "In2.Cu")
		(net "M_F_CPU1_SA_DQS_DP<0>")
	)
	(segment
		(start 142.898114 -289.873944)
		(end 142.898114 -284.026102)
		(width 0.18288)
		(layer "In2.Cu")
		(net "M_F_CPU1_SA_DQS_DP<0>")
	)
	(segment
		(start 168.204642 -313.102244)
		(end 167.759126 -313.102244)
		(width 0.18288)
		(layer "In2.Cu")
		(net "M_F_CPU1_SA_DQS_DP<0>")
	)
	(segment
		(start 138.711178 -278.81961)
		(end 138.710162 -278.819102)
		(width 0.088646)
		(layer "In2.Cu")
		(net "M_F_CPU1_SA_DQS_DP<0>")
	)
	(segment
		(start 169.223182 -312.392822)
		(end 168.914064 -312.392822)
		(width 0.18288)
		(layer "In2.Cu")
		(net "M_F_CPU1_SA_DQS_DP<0>")
	)
	(segment
		(start 168.914064 -312.392822)
		(end 168.204642 -313.102244)
		(width 0.18288)
		(layer "In2.Cu")
		(net "M_F_CPU1_SA_DQS_DP<0>")
	)
	(segment
		(start 164.023548 -313.35345)
		(end 163.733988 -313.06389)
		(width 0.18288)
		(layer "In2.Cu")
		(net "M_F_CPU1_SA_DQS_DP<0>")
	)
	(segment
		(start 169.387266 -312.556906)
		(end 169.359072 -312.528712)
		(width 0.16002)
		(layer "In2.Cu")
		(net "M_F_CPU1_SA_DQS_DP<0>")
	)
	(segment
		(start 161.689288 -312.434732)
		(end 161.661094 -312.406538)
		(width 0.16002)
		(layer "In2.Cu")
		(net "M_F_CPU1_SA_DQS_DP<0>")
	)
	(segment
		(start 141.769338 -282.89758)
		(end 140.603986 -280.085038)
		(width 0.18288)
		(layer "In2.Cu")
		(net "M_F_CPU1_SA_DQS_DP<0>")
	)
	(segment
		(start 157.635702 -313.308492)
		(end 157.607508 -313.280298)
		(width 0.16002)
		(layer "In2.Cu")
		(net "M_F_CPU1_SA_DQS_DP<0>")
	)
	(segment
		(start 165.186868 -313.308492)
		(end 165.170612 -313.308492)
		(width 0.16002)
		(layer "In2.Cu")
		(net "M_F_CPU1_SA_DQS_DP<0>")
	)
	(segment
		(start 156.378656 -312.80989)
		(end 147.684998 -304.116232)
		(width 0.18288)
		(layer "In2.Cu")
		(net "M_F_CPU1_SA_DQS_DP<0>")
	)
	(segment
		(start 165.371018 -313.508898)
		(end 165.371018 -313.492642)
		(width 0.16002)
		(layer "In2.Cu")
		(net "M_F_CPU1_SA_DQS_DP<0>")
	)
	(segment
		(start 137.781538 -278.825452)
		(end 137.7696 -278.81834)
		(width 0.088646)
		(layer "In2.Cu")
		(net "M_F_CPU1_SA_DQS_DP<0>")
	)
	(segment
		(start 167.552878 -313.308492)
		(end 167.536622 -313.308492)
		(width 0.16002)
		(layer "In2.Cu")
		(net "M_F_CPU1_SA_DQS_DP<0>")
	)
	(segment
		(start 167.536622 -313.308492)
		(end 167.352472 -313.492642)
		(width 0.16002)
		(layer "In2.Cu")
		(net "M_F_CPU1_SA_DQS_DP<0>")
	)
	(segment
		(start 135.619998 -278.336502)
		(end 135.619998 -278.325072)
		(width 0.088646)
		(layer "In2.Cu")
		(net "M_F_CPU1_SA_DQS_DP<0>")
	)
	(segment
		(start 162.318446 -313.06389)
		(end 161.917888 -312.663332)
		(width 0.18288)
		(layer "In2.Cu")
		(net "M_F_CPU1_SA_DQS_DP<0>")
	)
	(segment
		(start 161.889694 -312.618882)
		(end 161.705544 -312.434732)
		(width 0.16002)
		(layer "In2.Cu")
		(net "M_F_CPU1_SA_DQS_DP<0>")
	)
	(segment
		(start 142.898114 -284.026102)
		(end 141.769338 -282.89758)
		(width 0.18288)
		(layer "In2.Cu")
		(net "M_F_CPU1_SA_DQS_DP<0>")
	)
	(segment
		(start 161.705544 -312.434732)
		(end 161.689288 -312.434732)
		(width 0.16002)
		(layer "In2.Cu")
		(net "M_F_CPU1_SA_DQS_DP<0>")
	)
	(segment
		(start 169.57421 -312.74385)
		(end 169.546016 -312.715656)
		(width 0.16002)
		(layer "In2.Cu")
		(net "M_F_CPU1_SA_DQS_DP<0>")
	)
	(segment
		(start 140.09878 -279.494488)
		(end 139.516358 -278.912066)
		(width 0.088646)
		(layer "In2.Cu")
		(net "M_F_CPU1_SA_DQS_DP<0>")
	)
	(segment
		(start 163.733988 -313.06389)
		(end 162.318446 -313.06389)
		(width 0.18288)
		(layer "In2.Cu")
		(net "M_F_CPU1_SA_DQS_DP<0>")
	)
	(segment
		(start 172.510958 -312.631582)
		(end 172.228002 -312.631582)
		(width 0.18288)
		(layer "In2.Cu")
		(net "M_F_CPU1_SA_DQS_DP<0>")
	)
	(segment
		(start 138.710162 -278.819102)
		(end 138.709908 -278.818848)
		(width 0.088646)
		(layer "In2.Cu")
		(net "M_F_CPU1_SA_DQS_DP<0>")
	)
	(segment
		(start 164.699696 -313.049412)
		(end 164.395658 -313.35345)
		(width 0.18288)
		(layer "In2.Cu")
		(net "M_F_CPU1_SA_DQS_DP<0>")
	)
	(segment
		(start 167.352472 -313.492642)
		(end 167.352472 -313.508898)
		(width 0.16002)
		(layer "In2.Cu")
		(net "M_F_CPU1_SA_DQS_DP<0>")
	)
	(segment
		(start 140.09878 -279.579324)
		(end 140.09878 -279.494488)
		(width 0.088646)
		(layer "In2.Cu")
		(net "M_F_CPU1_SA_DQS_DP<0>")
	)
	(segment
		(start 167.759126 -313.102244)
		(end 167.581072 -313.280298)
		(width 0.18288)
		(layer "In2.Cu")
		(net "M_F_CPU1_SA_DQS_DP<0>")
	)
	(segment
		(start 165.371018 -313.492642)
		(end 165.186868 -313.308492)
		(width 0.16002)
		(layer "In2.Cu")
		(net "M_F_CPU1_SA_DQS_DP<0>")
	)
	(segment
		(start 135.902954 -278.82596)
		(end 135.892032 -278.81961)
		(width 0.088646)
		(layer "In2.Cu")
		(net "M_F_CPU1_SA_DQS_DP<0>")
	)
	(segment
		(start 172.070268 -312.473848)
		(end 171.650406 -312.473848)
		(width 0.18288)
		(layer "In2.Cu")
		(net "M_F_CPU1_SA_DQS_DP<0>")
	)
	(segment
		(start 157.864302 -313.537092)
		(end 157.836108 -313.508898)
		(width 0.16002)
		(layer "In2.Cu")
		(net "M_F_CPU1_SA_DQS_DP<0>")
	)
	(segment
		(start 167.352472 -313.508898)
		(end 167.324278 -313.537092)
		(width 0.16002)
		(layer "In2.Cu")
		(net "M_F_CPU1_SA_DQS_DP<0>")
	)
	(segment
		(start 161.077148 -312.29681)
		(end 159.677608 -313.69635)
		(width 0.18288)
		(layer "In2.Cu")
		(net "M_F_CPU1_SA_DQS_DP<0>")
	)
	(segment
		(start 157.836108 -313.508898)
		(end 157.836108 -313.492642)
		(width 0.16002)
		(layer "In2.Cu")
		(net "M_F_CPU1_SA_DQS_DP<0>")
	)
	(segment
		(start 133.56336 -278.01824)
		(end 133.552946 -278.012144)
		(width 0.088646)
		(layer "In2.Cu")
		(net "M_F_CPU1_SA_DQS_DP<0>")
	)
	(segment
		(start 165.58641 -313.72429)
		(end 165.399212 -313.537092)
		(width 0.18288)
		(layer "In2.Cu")
		(net "M_F_CPU1_SA_DQS_DP<0>")
	)
	(segment
		(start 133.208522 -277.522432)
		(end 132.895594 -277.522432)
		(width 0.088646)
		(layer "In2.Cu")
		(net "M_F_CPU1_SA_DQS_DP<0>")
	)
	(segment
		(start 147.684998 -297.951906)
		(end 146.34845 -294.724836)
		(width 0.18288)
		(layer "In2.Cu")
		(net "M_F_CPU1_SA_DQS_DP<0>")
	)
	(segment
		(start 133.2738 -277.58771)
		(end 133.208522 -277.522432)
		(width 0.088646)
		(layer "In2.Cu")
		(net "M_F_CPU1_SA_DQS_DP<0>")
	)
	(segment
		(start 135.432292 -278.01189)
		(end 135.432292 -278.012144)
		(width 0.088646)
		(layer "In2.Cu")
		(net "M_F_CPU1_SA_DQS_DP<0>")
	)
	(segment
		(start 157.607508 -313.280298)
		(end 157.1371 -312.80989)
		(width 0.18288)
		(layer "In2.Cu")
		(net "M_F_CPU1_SA_DQS_DP<0>")
	)
	(segment
		(start 171.650406 -312.473848)
		(end 171.250356 -312.873898)
		(width 0.18288)
		(layer "In2.Cu")
		(net "M_F_CPU1_SA_DQS_DP<0>")
	)
	(segment
		(start 158.02356 -313.69635)
		(end 157.864302 -313.537092)
		(width 0.18288)
		(layer "In2.Cu")
		(net "M_F_CPU1_SA_DQS_DP<0>")
	)
	(segment
		(start 167.13708 -313.72429)
		(end 165.58641 -313.72429)
		(width 0.18288)
		(layer "In2.Cu")
		(net "M_F_CPU1_SA_DQS_DP<0>")
	)
	(segment
		(start 136.841738 -278.825452)
		(end 136.8298 -278.81834)
		(width 0.088646)
		(layer "In2.Cu")
		(net "M_F_CPU1_SA_DQS_DP<0>")
	)
	(segment
		(start 171.250356 -312.873898)
		(end 169.704258 -312.873898)
		(width 0.18288)
		(layer "In2.Cu")
		(net "M_F_CPU1_SA_DQS_DP<0>")
	)
	(segment
		(start 165.399212 -313.537092)
		(end 165.371018 -313.508898)
		(width 0.16002)
		(layer "In2.Cu")
		(net "M_F_CPU1_SA_DQS_DP<0>")
	)
	(segment
		(start 159.677608 -313.69635)
		(end 158.02356 -313.69635)
		(width 0.18288)
		(layer "In2.Cu")
		(net "M_F_CPU1_SA_DQS_DP<0>")
	)
	(segment
		(start 167.324278 -313.537092)
		(end 167.13708 -313.72429)
		(width 0.18288)
		(layer "In2.Cu")
		(net "M_F_CPU1_SA_DQS_DP<0>")
	)
	(segment
		(start 164.911532 -313.049412)
		(end 164.699696 -313.049412)
		(width 0.18288)
		(layer "In2.Cu")
		(net "M_F_CPU1_SA_DQS_DP<0>")
	)
	(segment
		(start 172.228002 -312.631582)
		(end 172.070268 -312.473848)
		(width 0.18288)
		(layer "In2.Cu")
		(net "M_F_CPU1_SA_DQS_DP<0>")
	)
	(segment
		(start 169.359072 -312.528712)
		(end 169.223182 -312.392822)
		(width 0.18288)
		(layer "In2.Cu")
		(net "M_F_CPU1_SA_DQS_DP<0>")
	)
	(arc
		(start 139.043664 -278.912066)
		(mid 138.877223 -278.890141)
		(end 138.7221 -278.82596)
		(width 0.088646)
		(layer "In2.Cu")
		(net "M_F_CPU1_SA_DQS_DP<0>")
	)
	(arc
		(start 135.432292 -278.012144)
		(mid 135.245094 -277.962001)
		(end 135.057896 -278.012144)
		(width 0.088646)
		(layer "In2.Cu")
		(net "M_F_CPU1_SA_DQS_DP<0>")
	)
	(arc
		(start 138.346942 -278.825706)
		(mid 138.064211 -278.901389)
		(end 137.781538 -278.825452)
		(width 0.088646)
		(layer "In2.Cu")
		(net "M_F_CPU1_SA_DQS_DP<0>")
	)
	(arc
		(start 134.492492 -278.012144)
		(mid 134.305294 -277.962001)
		(end 134.118096 -278.012144)
		(width 0.088646)
		(layer "In2.Cu")
		(net "M_F_CPU1_SA_DQS_DP<0>")
	)
	(arc
		(start 134.118096 -278.012144)
		(mid 133.841537 -278.087853)
		(end 133.56336 -278.01824)
		(width 0.088646)
		(layer "In2.Cu")
		(net "M_F_CPU1_SA_DQS_DP<0>")
	)
	(arc
		(start 136.467342 -278.825706)
		(mid 136.185177 -278.901389)
		(end 135.902954 -278.82596)
		(width 0.088646)
		(layer "In2.Cu")
		(net "M_F_CPU1_SA_DQS_DP<0>")
	)
	(arc
		(start 133.276594 -277.608792)
		(mid 133.275098 -277.598264)
		(end 133.2738 -277.58771)
		(width 0.088646)
		(layer "In2.Cu")
		(net "M_F_CPU1_SA_DQS_DP<0>")
	)
	(arc
		(start 135.619998 -278.325072)
		(mid 135.566864 -278.144073)
		(end 135.432292 -278.01189)
		(width 0.088646)
		(layer "In2.Cu")
		(net "M_F_CPU1_SA_DQS_DP<0>")
	)
	(arc
		(start 138.709908 -278.818848)
		(mid 138.527543 -278.775434)
		(end 138.346942 -278.825706)
		(width 0.088646)
		(layer "In2.Cu")
		(net "M_F_CPU1_SA_DQS_DP<0>")
	)
	(arc
		(start 133.552946 -278.012144)
		(mid 133.368964 -277.841866)
		(end 133.276594 -277.608792)
		(width 0.088646)
		(layer "In2.Cu")
		(net "M_F_CPU1_SA_DQS_DP<0>")
	)
	(arc
		(start 135.057896 -278.012144)
		(mid 134.775194 -278.087886)
		(end 134.492492 -278.012144)
		(width 0.088646)
		(layer "In2.Cu")
		(net "M_F_CPU1_SA_DQS_DP<0>")
	)
	(arc
		(start 136.8298 -278.81834)
		(mid 136.64763 -278.775351)
		(end 136.467342 -278.825706)
		(width 0.088646)
		(layer "In2.Cu")
		(net "M_F_CPU1_SA_DQS_DP<0>")
	)
	(arc
		(start 137.7696 -278.81834)
		(mid 137.58743 -278.775351)
		(end 137.407142 -278.825706)
		(width 0.088646)
		(layer "In2.Cu")
		(net "M_F_CPU1_SA_DQS_DP<0>")
	)
	(arc
		(start 137.407142 -278.825706)
		(mid 137.124411 -278.901389)
		(end 136.841738 -278.825452)
		(width 0.088646)
		(layer "In2.Cu")
		(net "M_F_CPU1_SA_DQS_DP<0>")
	)
	(arc
		(start 135.892032 -278.81961)
		(mid 135.692648 -278.61373)
		(end 135.619998 -278.336502)
		(width 0.088646)
		(layer "In2.Cu")
		(net "M_F_CPU1_SA_DQS_DP<0>")
	)
	(segment
		(start 183.549544 -273.96694)
		(end 183.99506 -274.412456)
		(width 0.20066)
		(layer "F.Cu")
		(net "M_F_CPU1_SA_DQS_DN<9>")
	)
	(segment
		(start 180.427884 -274.247864)
		(end 180.43398 -274.241768)
		(width 0.1016)
		(layer "F.Cu")
		(net "M_F_CPU1_SA_DQS_DN<9>")
	)
	(segment
		(start 178.802792 -274.395438)
		(end 179.286154 -274.395438)
		(width 0.20066)
		(layer "F.Cu")
		(net "M_F_CPU1_SA_DQS_DN<9>")
	)
	(segment
		(start 179.833524 -273.970496)
		(end 180.110892 -274.247864)
		(width 0.20066)
		(layer "F.Cu")
		(net "M_F_CPU1_SA_DQS_DN<9>")
	)
	(segment
		(start 184.786778 -274.412456)
		(end 185.041032 -274.66671)
		(width 0.20066)
		(layer "F.Cu")
		(net "M_F_CPU1_SA_DQS_DN<9>")
	)
	(segment
		(start 178.53152 -274.66671)
		(end 178.802792 -274.395438)
		(width 0.20066)
		(layer "F.Cu")
		(net "M_F_CPU1_SA_DQS_DN<9>")
	)
	(segment
		(start 183.99506 -274.412456)
		(end 184.786778 -274.412456)
		(width 0.20066)
		(layer "F.Cu")
		(net "M_F_CPU1_SA_DQS_DN<9>")
	)
	(segment
		(start 182.455058 -274.25269)
		(end 182.773828 -274.25269)
		(width 0.20066)
		(layer "F.Cu")
		(net "M_F_CPU1_SA_DQS_DN<9>")
	)
	(segment
		(start 179.286154 -274.395438)
		(end 179.711096 -273.970496)
		(width 0.20066)
		(layer "F.Cu")
		(net "M_F_CPU1_SA_DQS_DN<9>")
	)
	(segment
		(start 182.444136 -274.241768)
		(end 182.455058 -274.25269)
		(width 0.1016)
		(layer "F.Cu")
		(net "M_F_CPU1_SA_DQS_DN<9>")
	)
	(segment
		(start 179.711096 -273.970496)
		(end 179.833524 -273.970496)
		(width 0.20066)
		(layer "F.Cu")
		(net "M_F_CPU1_SA_DQS_DN<9>")
	)
	(segment
		(start 185.041032 -274.66671)
		(end 185.544714 -274.66671)
		(width 0.20066)
		(layer "F.Cu")
		(net "M_F_CPU1_SA_DQS_DN<9>")
	)
	(segment
		(start 180.110892 -274.247864)
		(end 180.423058 -274.247864)
		(width 0.20066)
		(layer "F.Cu")
		(net "M_F_CPU1_SA_DQS_DN<9>")
	)
	(segment
		(start 180.423058 -274.247864)
		(end 180.427884 -274.247864)
		(width 0.101854)
		(layer "F.Cu")
		(net "M_F_CPU1_SA_DQS_DN<9>")
	)
	(segment
		(start 176.896014 -274.66671)
		(end 178.000914 -274.66671)
		(width 0.20066)
		(layer "F.Cu")
		(net "M_F_CPU1_SA_DQS_DN<9>")
	)
	(segment
		(start 180.43398 -274.241768)
		(end 182.444136 -274.241768)
		(width 0.1016)
		(layer "F.Cu")
		(net "M_F_CPU1_SA_DQS_DN<9>")
	)
	(segment
		(start 182.773828 -274.25269)
		(end 183.059578 -273.96694)
		(width 0.20066)
		(layer "F.Cu")
		(net "M_F_CPU1_SA_DQS_DN<9>")
	)
	(segment
		(start 178.000914 -274.66671)
		(end 178.53152 -274.66671)
		(width 0.20066)
		(layer "F.Cu")
		(net "M_F_CPU1_SA_DQS_DN<9>")
	)
	(segment
		(start 135.714994 -262.336534)
		(end 135.714994 -262.872474)
		(width 0.20066)
		(layer "F.Cu")
		(net "M_F_CPU1_SA_DQS_DN<9>")
	)
	(segment
		(start 183.059578 -273.96694)
		(end 183.549544 -273.96694)
		(width 0.20066)
		(layer "F.Cu")
		(net "M_F_CPU1_SA_DQS_DN<9>")
	)
	(segment
		(start 153.820114 -268.597126)
		(end 153.820114 -268.421104)
		(width 0.18288)
		(layer "In2.Cu")
		(net "M_F_CPU1_SA_DQS_DN<9>")
	)
	(segment
		(start 164.865304 -274.267168)
		(end 164.56152 -273.963384)
		(width 0.18288)
		(layer "In2.Cu")
		(net "M_F_CPU1_SA_DQS_DN<9>")
	)
	(segment
		(start 160.33877 -272.86331)
		(end 159.827468 -272.86331)
		(width 0.18288)
		(layer "In2.Cu")
		(net "M_F_CPU1_SA_DQS_DN<9>")
	)
	(segment
		(start 153.820114 -268.421104)
		(end 153.432256 -268.033246)
		(width 0.18288)
		(layer "In2.Cu")
		(net "M_F_CPU1_SA_DQS_DN<9>")
	)
	(segment
		(start 151.91613 -266.693142)
		(end 151.91613 -266.51712)
		(width 0.18288)
		(layer "In2.Cu")
		(net "M_F_CPU1_SA_DQS_DN<9>")
	)
	(segment
		(start 152.868122 -267.645134)
		(end 152.868122 -267.469112)
		(width 0.18288)
		(layer "In2.Cu")
		(net "M_F_CPU1_SA_DQS_DN<9>")
	)
	(segment
		(start 169.215308 -273.949414)
		(end 168.231312 -273.949414)
		(width 0.18288)
		(layer "In2.Cu")
		(net "M_F_CPU1_SA_DQS_DN<9>")
	)
	(segment
		(start 174.771558 -274.347178)
		(end 173.735492 -273.917918)
		(width 0.18288)
		(layer "In2.Cu")
		(net "M_F_CPU1_SA_DQS_DN<9>")
	)
	(segment
		(start 152.480264 -267.081254)
		(end 152.304242 -267.081254)
		(width 0.18288)
		(layer "In2.Cu")
		(net "M_F_CPU1_SA_DQS_DN<9>")
	)
	(segment
		(start 159.686244 -272.722086)
		(end 159.65805 -272.693892)
		(width 0.16002)
		(layer "In2.Cu")
		(net "M_F_CPU1_SA_DQS_DN<9>")
	)
	(segment
		(start 169.719498 -273.445224)
		(end 169.691304 -273.473418)
		(width 0.16002)
		(layer "In2.Cu")
		(net "M_F_CPU1_SA_DQS_DN<9>")
	)
	(segment
		(start 143.964914 -262.683498)
		(end 140.900404 -262.683498)
		(width 0.18288)
		(layer "In2.Cu")
		(net "M_F_CPU1_SA_DQS_DN<9>")
	)
	(segment
		(start 171.400978 -273.627088)
		(end 171.21632 -273.44243)
		(width 0.16002)
		(layer "In2.Cu")
		(net "M_F_CPU1_SA_DQS_DN<9>")
	)
	(segment
		(start 161.413444 -273.417284)
		(end 161.10077 -273.10461)
		(width 0.18288)
		(layer "In2.Cu")
		(net "M_F_CPU1_SA_DQS_DN<9>")
	)
	(segment
		(start 162.027108 -273.138138)
		(end 161.747962 -273.417284)
		(width 0.18288)
		(layer "In2.Cu")
		(net "M_F_CPU1_SA_DQS_DN<9>")
	)
	(segment
		(start 164.56152 -273.963384)
		(end 164.177726 -273.963384)
		(width 0.18288)
		(layer "In2.Cu")
		(net "M_F_CPU1_SA_DQS_DN<9>")
	)
	(segment
		(start 147.07362 -265.218926)
		(end 144.943576 -263.088882)
		(width 0.18288)
		(layer "In2.Cu")
		(net "M_F_CPU1_SA_DQS_DN<9>")
	)
	(segment
		(start 171.429172 -273.67103)
		(end 171.400978 -273.642836)
		(width 0.16002)
		(layer "In2.Cu")
		(net "M_F_CPU1_SA_DQS_DN<9>")
	)
	(segment
		(start 147.74672 -265.343386)
		(end 147.62226 -265.218926)
		(width 0.18288)
		(layer "In2.Cu")
		(net "M_F_CPU1_SA_DQS_DN<9>")
	)
	(segment
		(start 136.190228 -262.74268)
		(end 135.844788 -262.74268)
		(width 0.088646)
		(layer "In2.Cu")
		(net "M_F_CPU1_SA_DQS_DN<9>")
	)
	(segment
		(start 163.758118 -273.528028)
		(end 163.57346 -273.34337)
		(width 0.16002)
		(layer "In2.Cu")
		(net "M_F_CPU1_SA_DQS_DN<9>")
	)
	(segment
		(start 135.844788 -262.74268)
		(end 135.714994 -262.872474)
		(width 0.088646)
		(layer "In2.Cu")
		(net "M_F_CPU1_SA_DQS_DN<9>")
	)
	(segment
		(start 155.724352 -270.325088)
		(end 155.724098 -270.325088)
		(width 0.18288)
		(layer "In2.Cu")
		(net "M_F_CPU1_SA_DQS_DN<9>")
	)
	(segment
		(start 155.724098 -270.325088)
		(end 155.33624 -269.93723)
		(width 0.18288)
		(layer "In2.Cu")
		(net "M_F_CPU1_SA_DQS_DN<9>")
	)
	(segment
		(start 155.160218 -269.93723)
		(end 154.772106 -269.549118)
		(width 0.18288)
		(layer "In2.Cu")
		(net "M_F_CPU1_SA_DQS_DN<9>")
	)
	(segment
		(start 171.089574 -273.331432)
		(end 169.83329 -273.331432)
		(width 0.18288)
		(layer "In2.Cu")
		(net "M_F_CPU1_SA_DQS_DN<9>")
	)
	(segment
		(start 171.692062 -273.93392)
		(end 171.429172 -273.67103)
		(width 0.18288)
		(layer "In2.Cu")
		(net "M_F_CPU1_SA_DQS_DN<9>")
	)
	(segment
		(start 169.490898 -273.673824)
		(end 169.462704 -273.702018)
		(width 0.16002)
		(layer "In2.Cu")
		(net "M_F_CPU1_SA_DQS_DN<9>")
	)
	(segment
		(start 159.827468 -272.86331)
		(end 159.686244 -272.722086)
		(width 0.18288)
		(layer "In2.Cu")
		(net "M_F_CPU1_SA_DQS_DN<9>")
	)
	(segment
		(start 160.58007 -273.10461)
		(end 160.33877 -272.86331)
		(width 0.18288)
		(layer "In2.Cu")
		(net "M_F_CPU1_SA_DQS_DN<9>")
	)
	(segment
		(start 159.473392 -272.493486)
		(end 159.457644 -272.493486)
		(width 0.16002)
		(layer "In2.Cu")
		(net "M_F_CPU1_SA_DQS_DN<9>")
	)
	(segment
		(start 148.29536 -265.343386)
		(end 147.74672 -265.343386)
		(width 0.18288)
		(layer "In2.Cu")
		(net "M_F_CPU1_SA_DQS_DN<9>")
	)
	(segment
		(start 159.65805 -272.693892)
		(end 159.65805 -272.678144)
		(width 0.16002)
		(layer "In2.Cu")
		(net "M_F_CPU1_SA_DQS_DN<9>")
	)
	(segment
		(start 163.786312 -273.57197)
		(end 163.758118 -273.543776)
		(width 0.16002)
		(layer "In2.Cu")
		(net "M_F_CPU1_SA_DQS_DN<9>")
	)
	(segment
		(start 147.62226 -265.218926)
		(end 147.07362 -265.218926)
		(width 0.18288)
		(layer "In2.Cu")
		(net "M_F_CPU1_SA_DQS_DN<9>")
	)
	(segment
		(start 171.400978 -273.642836)
		(end 171.400978 -273.627088)
		(width 0.16002)
		(layer "In2.Cu")
		(net "M_F_CPU1_SA_DQS_DN<9>")
	)
	(segment
		(start 171.172378 -273.414236)
		(end 171.089574 -273.331432)
		(width 0.18288)
		(layer "In2.Cu")
		(net "M_F_CPU1_SA_DQS_DN<9>")
	)
	(segment
		(start 140.900404 -262.683498)
		(end 140.840714 -262.623808)
		(width 0.088646)
		(layer "In2.Cu")
		(net "M_F_CPU1_SA_DQS_DN<9>")
	)
	(segment
		(start 154.772106 -269.549118)
		(end 154.772106 -269.373096)
		(width 0.18288)
		(layer "In2.Cu")
		(net "M_F_CPU1_SA_DQS_DN<9>")
	)
	(segment
		(start 169.691304 -273.473418)
		(end 169.675556 -273.473418)
		(width 0.16002)
		(layer "In2.Cu")
		(net "M_F_CPU1_SA_DQS_DN<9>")
	)
	(segment
		(start 153.256234 -268.033246)
		(end 152.868122 -267.645134)
		(width 0.18288)
		(layer "In2.Cu")
		(net "M_F_CPU1_SA_DQS_DN<9>")
	)
	(segment
		(start 157.960568 -272.254726)
		(end 157.647894 -272.5674)
		(width 0.18288)
		(layer "In2.Cu")
		(net "M_F_CPU1_SA_DQS_DN<9>")
	)
	(segment
		(start 175.139096 -274.347178)
		(end 174.771558 -274.347178)
		(width 0.18288)
		(layer "In2.Cu")
		(net "M_F_CPU1_SA_DQS_DN<9>")
	)
	(segment
		(start 163.35248 -273.138138)
		(end 162.027108 -273.138138)
		(width 0.18288)
		(layer "In2.Cu")
		(net "M_F_CPU1_SA_DQS_DN<9>")
	)
	(segment
		(start 167.481504 -274.267168)
		(end 167.19677 -273.982434)
		(width 0.18288)
		(layer "In2.Cu")
		(net "M_F_CPU1_SA_DQS_DN<9>")
	)
	(segment
		(start 144.943576 -263.088882)
		(end 143.964914 -262.683498)
		(width 0.18288)
		(layer "In2.Cu")
		(net "M_F_CPU1_SA_DQS_DN<9>")
	)
	(segment
		(start 151.91613 -266.51712)
		(end 150.61819 -265.218926)
		(width 0.18288)
		(layer "In2.Cu")
		(net "M_F_CPU1_SA_DQS_DN<9>")
	)
	(segment
		(start 172.996352 -274.242022)
		(end 172.995336 -274.241006)
		(width 0.18288)
		(layer "In2.Cu")
		(net "M_F_CPU1_SA_DQS_DN<9>")
	)
	(segment
		(start 154.384248 -268.985238)
		(end 154.208226 -268.985238)
		(width 0.18288)
		(layer "In2.Cu")
		(net "M_F_CPU1_SA_DQS_DN<9>")
	)
	(segment
		(start 152.304242 -267.081254)
		(end 151.91613 -266.693142)
		(width 0.18288)
		(layer "In2.Cu")
		(net "M_F_CPU1_SA_DQS_DN<9>")
	)
	(segment
		(start 159.65805 -272.678144)
		(end 159.473392 -272.493486)
		(width 0.16002)
		(layer "In2.Cu")
		(net "M_F_CPU1_SA_DQS_DN<9>")
	)
	(segment
		(start 172.995336 -274.241006)
		(end 172.577252 -274.241006)
		(width 0.18288)
		(layer "In2.Cu")
		(net "M_F_CPU1_SA_DQS_DN<9>")
	)
	(segment
		(start 153.432256 -268.033246)
		(end 153.256234 -268.033246)
		(width 0.18288)
		(layer "In2.Cu")
		(net "M_F_CPU1_SA_DQS_DN<9>")
	)
	(segment
		(start 173.320456 -273.917918)
		(end 172.996352 -274.242022)
		(width 0.18288)
		(layer "In2.Cu")
		(net "M_F_CPU1_SA_DQS_DN<9>")
	)
	(segment
		(start 175.812196 -274.471638)
		(end 175.263556 -274.471638)
		(width 0.18288)
		(layer "In2.Cu")
		(net "M_F_CPU1_SA_DQS_DN<9>")
	)
	(segment
		(start 137.792206 -262.554212)
		(end 137.781792 -262.548116)
		(width 0.088646)
		(layer "In2.Cu")
		(net "M_F_CPU1_SA_DQS_DN<9>")
	)
	(segment
		(start 155.33624 -269.93723)
		(end 155.160218 -269.93723)
		(width 0.18288)
		(layer "In2.Cu")
		(net "M_F_CPU1_SA_DQS_DN<9>")
	)
	(segment
		(start 138.736578 -262.556752)
		(end 138.721846 -262.548116)
		(width 0.088646)
		(layer "In2.Cu")
		(net "M_F_CPU1_SA_DQS_DN<9>")
	)
	(segment
		(start 169.83329 -273.331432)
		(end 169.719498 -273.445224)
		(width 0.18288)
		(layer "In2.Cu")
		(net "M_F_CPU1_SA_DQS_DN<9>")
	)
	(segment
		(start 161.10077 -273.10461)
		(end 160.58007 -273.10461)
		(width 0.18288)
		(layer "In2.Cu")
		(net "M_F_CPU1_SA_DQS_DN<9>")
	)
	(segment
		(start 136.31672 -262.635238)
		(end 136.190228 -262.74268)
		(width 0.088646)
		(layer "In2.Cu")
		(net "M_F_CPU1_SA_DQS_DN<9>")
	)
	(segment
		(start 148.41982 -265.218926)
		(end 148.29536 -265.343386)
		(width 0.18288)
		(layer "In2.Cu")
		(net "M_F_CPU1_SA_DQS_DN<9>")
	)
	(segment
		(start 172.577252 -274.241006)
		(end 172.270166 -273.93392)
		(width 0.18288)
		(layer "In2.Cu")
		(net "M_F_CPU1_SA_DQS_DN<9>")
	)
	(segment
		(start 163.529518 -273.315176)
		(end 163.35248 -273.138138)
		(width 0.18288)
		(layer "In2.Cu")
		(net "M_F_CPU1_SA_DQS_DN<9>")
	)
	(segment
		(start 156.41701 -271.995646)
		(end 155.724352 -270.325088)
		(width 0.18288)
		(layer "In2.Cu")
		(net "M_F_CPU1_SA_DQS_DN<9>")
	)
	(segment
		(start 136.467596 -262.548116)
		(end 136.31672 -262.635238)
		(width 0.088646)
		(layer "In2.Cu")
		(net "M_F_CPU1_SA_DQS_DN<9>")
	)
	(segment
		(start 169.675556 -273.473418)
		(end 169.490898 -273.658076)
		(width 0.16002)
		(layer "In2.Cu")
		(net "M_F_CPU1_SA_DQS_DN<9>")
	)
	(segment
		(start 176.896014 -274.66671)
		(end 176.576482 -274.347178)
		(width 0.18288)
		(layer "In2.Cu")
		(net "M_F_CPU1_SA_DQS_DN<9>")
	)
	(segment
		(start 157.647894 -272.5674)
		(end 157.313376 -272.5674)
		(width 0.18288)
		(layer "In2.Cu")
		(net "M_F_CPU1_SA_DQS_DN<9>")
	)
	(segment
		(start 159.457644 -272.493486)
		(end 159.42945 -272.465292)
		(width 0.16002)
		(layer "In2.Cu")
		(net "M_F_CPU1_SA_DQS_DN<9>")
	)
	(segment
		(start 164.177726 -273.963384)
		(end 163.786312 -273.57197)
		(width 0.18288)
		(layer "In2.Cu")
		(net "M_F_CPU1_SA_DQS_DN<9>")
	)
	(segment
		(start 168.231312 -273.949414)
		(end 167.913558 -274.267168)
		(width 0.18288)
		(layer "In2.Cu")
		(net "M_F_CPU1_SA_DQS_DN<9>")
	)
	(segment
		(start 165.297358 -274.267168)
		(end 164.865304 -274.267168)
		(width 0.18288)
		(layer "In2.Cu")
		(net "M_F_CPU1_SA_DQS_DN<9>")
	)
	(segment
		(start 163.57346 -273.34337)
		(end 163.557712 -273.34337)
		(width 0.16002)
		(layer "In2.Cu")
		(net "M_F_CPU1_SA_DQS_DN<9>")
	)
	(segment
		(start 154.208226 -268.985238)
		(end 153.820114 -268.597126)
		(width 0.18288)
		(layer "In2.Cu")
		(net "M_F_CPU1_SA_DQS_DN<9>")
	)
	(segment
		(start 169.462704 -273.702018)
		(end 169.215308 -273.949414)
		(width 0.18288)
		(layer "In2.Cu")
		(net "M_F_CPU1_SA_DQS_DN<9>")
	)
	(segment
		(start 175.936656 -274.347178)
		(end 175.812196 -274.471638)
		(width 0.18288)
		(layer "In2.Cu")
		(net "M_F_CPU1_SA_DQS_DN<9>")
	)
	(segment
		(start 156.962348 -272.216372)
		(end 156.636466 -272.216372)
		(width 0.18288)
		(layer "In2.Cu")
		(net "M_F_CPU1_SA_DQS_DN<9>")
	)
	(segment
		(start 165.582092 -273.982434)
		(end 165.297358 -274.267168)
		(width 0.18288)
		(layer "In2.Cu")
		(net "M_F_CPU1_SA_DQS_DN<9>")
	)
	(segment
		(start 167.19677 -273.982434)
		(end 165.582092 -273.982434)
		(width 0.18288)
		(layer "In2.Cu")
		(net "M_F_CPU1_SA_DQS_DN<9>")
	)
	(segment
		(start 167.913558 -274.267168)
		(end 167.481504 -274.267168)
		(width 0.18288)
		(layer "In2.Cu")
		(net "M_F_CPU1_SA_DQS_DN<9>")
	)
	(segment
		(start 150.61819 -265.218926)
		(end 148.41982 -265.218926)
		(width 0.18288)
		(layer "In2.Cu")
		(net "M_F_CPU1_SA_DQS_DN<9>")
	)
	(segment
		(start 159.218884 -272.254726)
		(end 157.960568 -272.254726)
		(width 0.18288)
		(layer "In2.Cu")
		(net "M_F_CPU1_SA_DQS_DN<9>")
	)
	(segment
		(start 173.735492 -273.917918)
		(end 173.320456 -273.917918)
		(width 0.18288)
		(layer "In2.Cu")
		(net "M_F_CPU1_SA_DQS_DN<9>")
	)
	(segment
		(start 161.747962 -273.417284)
		(end 161.413444 -273.417284)
		(width 0.18288)
		(layer "In2.Cu")
		(net "M_F_CPU1_SA_DQS_DN<9>")
	)
	(segment
		(start 154.772106 -269.373096)
		(end 154.384248 -268.985238)
		(width 0.18288)
		(layer "In2.Cu")
		(net "M_F_CPU1_SA_DQS_DN<9>")
	)
	(segment
		(start 163.557712 -273.34337)
		(end 163.529518 -273.315176)
		(width 0.16002)
		(layer "In2.Cu")
		(net "M_F_CPU1_SA_DQS_DN<9>")
	)
	(segment
		(start 171.200572 -273.44243)
		(end 171.172378 -273.414236)
		(width 0.16002)
		(layer "In2.Cu")
		(net "M_F_CPU1_SA_DQS_DN<9>")
	)
	(segment
		(start 159.42945 -272.465292)
		(end 159.218884 -272.254726)
		(width 0.18288)
		(layer "In2.Cu")
		(net "M_F_CPU1_SA_DQS_DN<9>")
	)
	(segment
		(start 169.490898 -273.658076)
		(end 169.490898 -273.673824)
		(width 0.16002)
		(layer "In2.Cu")
		(net "M_F_CPU1_SA_DQS_DN<9>")
	)
	(segment
		(start 152.868122 -267.469112)
		(end 152.480264 -267.081254)
		(width 0.18288)
		(layer "In2.Cu")
		(net "M_F_CPU1_SA_DQS_DN<9>")
	)
	(segment
		(start 163.758118 -273.543776)
		(end 163.758118 -273.528028)
		(width 0.16002)
		(layer "In2.Cu")
		(net "M_F_CPU1_SA_DQS_DN<9>")
	)
	(segment
		(start 176.576482 -274.347178)
		(end 175.936656 -274.347178)
		(width 0.18288)
		(layer "In2.Cu")
		(net "M_F_CPU1_SA_DQS_DN<9>")
	)
	(segment
		(start 175.263556 -274.471638)
		(end 175.139096 -274.347178)
		(width 0.18288)
		(layer "In2.Cu")
		(net "M_F_CPU1_SA_DQS_DN<9>")
	)
	(segment
		(start 171.21632 -273.44243)
		(end 171.200572 -273.44243)
		(width 0.16002)
		(layer "In2.Cu")
		(net "M_F_CPU1_SA_DQS_DN<9>")
	)
	(segment
		(start 157.313376 -272.5674)
		(end 156.962348 -272.216372)
		(width 0.18288)
		(layer "In2.Cu")
		(net "M_F_CPU1_SA_DQS_DN<9>")
	)
	(segment
		(start 172.270166 -273.93392)
		(end 171.692062 -273.93392)
		(width 0.18288)
		(layer "In2.Cu")
		(net "M_F_CPU1_SA_DQS_DN<9>")
	)
	(segment
		(start 156.636466 -272.216372)
		(end 156.41701 -271.995646)
		(width 0.18288)
		(layer "In2.Cu")
		(net "M_F_CPU1_SA_DQS_DN<9>")
	)
	(segment
		(start 140.840714 -262.623808)
		(end 139.944094 -262.623808)
		(width 0.088646)
		(layer "In2.Cu")
		(net "M_F_CPU1_SA_DQS_DN<9>")
	)
	(arc
		(start 138.721846 -262.548116)
		(mid 138.534648 -262.497973)
		(end 138.34745 -262.548116)
		(width 0.088646)
		(layer "In2.Cu")
		(net "M_F_CPU1_SA_DQS_DN<9>")
	)
	(arc
		(start 137.407396 -262.548116)
		(mid 137.124694 -262.623892)
		(end 136.841992 -262.548116)
		(width 0.088646)
		(layer "In2.Cu")
		(net "M_F_CPU1_SA_DQS_DN<9>")
	)
	(arc
		(start 139.944094 -262.623808)
		(mid 139.797886 -262.604559)
		(end 139.661646 -262.548116)
		(width 0.088646)
		(layer "In2.Cu")
		(net "M_F_CPU1_SA_DQS_DN<9>")
	)
	(arc
		(start 138.34745 -262.548116)
		(mid 138.070637 -262.623986)
		(end 137.792206 -262.554212)
		(width 0.088646)
		(layer "In2.Cu")
		(net "M_F_CPU1_SA_DQS_DN<9>")
	)
	(arc
		(start 139.661646 -262.548116)
		(mid 139.474448 -262.497973)
		(end 139.28725 -262.548116)
		(width 0.088646)
		(layer "In2.Cu")
		(net "M_F_CPU1_SA_DQS_DN<9>")
	)
	(arc
		(start 139.28725 -262.548116)
		(mid 139.013051 -262.623951)
		(end 138.736578 -262.556752)
		(width 0.088646)
		(layer "In2.Cu")
		(net "M_F_CPU1_SA_DQS_DN<9>")
	)
	(arc
		(start 136.841992 -262.548116)
		(mid 136.654794 -262.497973)
		(end 136.467596 -262.548116)
		(width 0.088646)
		(layer "In2.Cu")
		(net "M_F_CPU1_SA_DQS_DN<9>")
	)
	(arc
		(start 137.781792 -262.548116)
		(mid 137.594594 -262.497973)
		(end 137.407396 -262.548116)
		(width 0.088646)
		(layer "In2.Cu")
		(net "M_F_CPU1_SA_DQS_DN<9>")
	)
	(segment
		(start 179.711096 -283.32049)
		(end 179.833524 -283.32049)
		(width 0.20066)
		(layer "F.Cu")
		(net "M_F_CPU1_SA_DQS_DN<8>")
	)
	(segment
		(start 183.549544 -283.316934)
		(end 183.99506 -283.76245)
		(width 0.20066)
		(layer "F.Cu")
		(net "M_F_CPU1_SA_DQS_DN<8>")
	)
	(segment
		(start 182.455058 -283.602684)
		(end 182.773828 -283.602684)
		(width 0.20066)
		(layer "F.Cu")
		(net "M_F_CPU1_SA_DQS_DN<8>")
	)
	(segment
		(start 182.773828 -283.602684)
		(end 183.059578 -283.316934)
		(width 0.20066)
		(layer "F.Cu")
		(net "M_F_CPU1_SA_DQS_DN<8>")
	)
	(segment
		(start 178.802792 -283.745432)
		(end 179.286154 -283.745432)
		(width 0.20066)
		(layer "F.Cu")
		(net "M_F_CPU1_SA_DQS_DN<8>")
	)
	(segment
		(start 183.99506 -283.76245)
		(end 184.786778 -283.76245)
		(width 0.20066)
		(layer "F.Cu")
		(net "M_F_CPU1_SA_DQS_DN<8>")
	)
	(segment
		(start 180.423058 -283.597858)
		(end 180.427884 -283.597858)
		(width 0.101854)
		(layer "F.Cu")
		(net "M_F_CPU1_SA_DQS_DN<8>")
	)
	(segment
		(start 132.425694 -259.894832)
		(end 132.425948 -259.895086)
		(width 0.20066)
		(layer "F.Cu")
		(net "M_F_CPU1_SA_DQS_DN<8>")
	)
	(segment
		(start 178.53152 -284.016704)
		(end 178.802792 -283.745432)
		(width 0.20066)
		(layer "F.Cu")
		(net "M_F_CPU1_SA_DQS_DN<8>")
	)
	(segment
		(start 182.444136 -283.591762)
		(end 182.455058 -283.602684)
		(width 0.1016)
		(layer "F.Cu")
		(net "M_F_CPU1_SA_DQS_DN<8>")
	)
	(segment
		(start 180.43398 -283.591762)
		(end 182.444136 -283.591762)
		(width 0.1016)
		(layer "F.Cu")
		(net "M_F_CPU1_SA_DQS_DN<8>")
	)
	(segment
		(start 180.110892 -283.597858)
		(end 180.423058 -283.597858)
		(width 0.20066)
		(layer "F.Cu")
		(net "M_F_CPU1_SA_DQS_DN<8>")
	)
	(segment
		(start 179.833524 -283.32049)
		(end 180.110892 -283.597858)
		(width 0.20066)
		(layer "F.Cu")
		(net "M_F_CPU1_SA_DQS_DN<8>")
	)
	(segment
		(start 176.896014 -284.016704)
		(end 178.000914 -284.016704)
		(width 0.20066)
		(layer "F.Cu")
		(net "M_F_CPU1_SA_DQS_DN<8>")
	)
	(segment
		(start 183.059578 -283.316934)
		(end 183.549544 -283.316934)
		(width 0.20066)
		(layer "F.Cu")
		(net "M_F_CPU1_SA_DQS_DN<8>")
	)
	(segment
		(start 179.286154 -283.745432)
		(end 179.711096 -283.32049)
		(width 0.20066)
		(layer "F.Cu")
		(net "M_F_CPU1_SA_DQS_DN<8>")
	)
	(segment
		(start 178.000914 -284.016704)
		(end 178.53152 -284.016704)
		(width 0.20066)
		(layer "F.Cu")
		(net "M_F_CPU1_SA_DQS_DN<8>")
	)
	(segment
		(start 180.427884 -283.597858)
		(end 180.43398 -283.591762)
		(width 0.1016)
		(layer "F.Cu")
		(net "M_F_CPU1_SA_DQS_DN<8>")
	)
	(segment
		(start 132.425948 -259.895086)
		(end 132.425948 -260.430772)
		(width 0.20066)
		(layer "F.Cu")
		(net "M_F_CPU1_SA_DQS_DN<8>")
	)
	(segment
		(start 184.786778 -283.76245)
		(end 185.041032 -284.016704)
		(width 0.20066)
		(layer "F.Cu")
		(net "M_F_CPU1_SA_DQS_DN<8>")
	)
	(segment
		(start 185.041032 -284.016704)
		(end 185.544714 -284.016704)
		(width 0.20066)
		(layer "F.Cu")
		(net "M_F_CPU1_SA_DQS_DN<8>")
	)
	(segment
		(start 159.317436 -271.04467)
		(end 158.569152 -270.73479)
		(width 0.18288)
		(layer "In4.Cu")
		(net "M_F_CPU1_SA_DQS_DN<8>")
	)
	(segment
		(start 135.447024 -260.11505)
		(end 135.432292 -260.106414)
		(width 0.088646)
		(layer "In4.Cu")
		(net "M_F_CPU1_SA_DQS_DN<8>")
	)
	(segment
		(start 132.891784 -260.223762)
		(end 132.50037 -260.223762)
		(width 0.088646)
		(layer "In4.Cu")
		(net "M_F_CPU1_SA_DQS_DN<8>")
	)
	(segment
		(start 172.992034 -283.592524)
		(end 172.577252 -283.592524)
		(width 0.18288)
		(layer "In4.Cu")
		(net "M_F_CPU1_SA_DQS_DN<8>")
	)
	(segment
		(start 165.517576 -273.04365)
		(end 165.354762 -273.11096)
		(width 0.18288)
		(layer "In4.Cu")
		(net "M_F_CPU1_SA_DQS_DN<8>")
	)
	(segment
		(start 167.35298 -274.583906)
		(end 166.021766 -273.252692)
		(width 0.18288)
		(layer "In4.Cu")
		(net "M_F_CPU1_SA_DQS_DN<8>")
	)
	(segment
		(start 175.229774 -284.023816)
		(end 174.683674 -284.023816)
		(width 0.18288)
		(layer "In4.Cu")
		(net "M_F_CPU1_SA_DQS_DN<8>")
	)
	(segment
		(start 173.253146 -283.331412)
		(end 172.992034 -283.592524)
		(width 0.18288)
		(layer "In4.Cu")
		(net "M_F_CPU1_SA_DQS_DN<8>")
	)
	(segment
		(start 144.569688 -261.452868)
		(end 141.654784 -260.24205)
		(width 0.18288)
		(layer "In4.Cu")
		(net "M_F_CPU1_SA_DQS_DN<8>")
	)
	(segment
		(start 169.758614 -275.87448)
		(end 169.493946 -275.236686)
		(width 0.18288)
		(layer "In4.Cu")
		(net "M_F_CPU1_SA_DQS_DN<8>")
	)
	(segment
		(start 164.850064 -272.901664)
		(end 164.782754 -272.738596)
		(width 0.18288)
		(layer "In4.Cu")
		(net "M_F_CPU1_SA_DQS_DN<8>")
	)
	(segment
		(start 158.410148 -270.575786)
		(end 158.185612 -270.575786)
		(width 0.18288)
		(layer "In4.Cu")
		(net "M_F_CPU1_SA_DQS_DN<8>")
	)
	(segment
		(start 170.129454 -278.072596)
		(end 170.129454 -277.736046)
		(width 0.18288)
		(layer "In4.Cu")
		(net "M_F_CPU1_SA_DQS_DN<8>")
	)
	(segment
		(start 163.152582 -272.289016)
		(end 163.028122 -272.413476)
		(width 0.18288)
		(layer "In4.Cu")
		(net "M_F_CPU1_SA_DQS_DN<8>")
	)
	(segment
		(start 174.559214 -283.899356)
		(end 174.013114 -283.899356)
		(width 0.18288)
		(layer "In4.Cu")
		(net "M_F_CPU1_SA_DQS_DN<8>")
	)
	(segment
		(start 157.551628 -270.857472)
		(end 157.187138 -270.492982)
		(width 0.18288)
		(layer "In4.Cu")
		(net "M_F_CPU1_SA_DQS_DN<8>")
	)
	(segment
		(start 148.990304 -262.185912)
		(end 145.864834 -262.185912)
		(width 0.18288)
		(layer "In4.Cu")
		(net "M_F_CPU1_SA_DQS_DN<8>")
	)
	(segment
		(start 169.493946 -275.236686)
		(end 169.412158 -275.154898)
		(width 0.18288)
		(layer "In4.Cu")
		(net "M_F_CPU1_SA_DQS_DN<8>")
	)
	(segment
		(start 157.187138 -270.492982)
		(end 157.187138 -270.382746)
		(width 0.18288)
		(layer "In4.Cu")
		(net "M_F_CPU1_SA_DQS_DN<8>")
	)
	(segment
		(start 169.412158 -275.154898)
		(end 168.665398 -274.845272)
		(width 0.18288)
		(layer "In4.Cu")
		(net "M_F_CPU1_SA_DQS_DN<8>")
	)
	(segment
		(start 163.028122 -272.413476)
		(end 162.482022 -272.413476)
		(width 0.18288)
		(layer "In4.Cu")
		(net "M_F_CPU1_SA_DQS_DN<8>")
	)
	(segment
		(start 176.43602 -283.746702)
		(end 176.067466 -283.899356)
		(width 0.18288)
		(layer "In4.Cu")
		(net "M_F_CPU1_SA_DQS_DN<8>")
	)
	(segment
		(start 145.864834 -262.185912)
		(end 144.902428 -261.785608)
		(width 0.18288)
		(layer "In4.Cu")
		(net "M_F_CPU1_SA_DQS_DN<8>")
	)
	(segment
		(start 136.38657 -260.11505)
		(end 136.371838 -260.106414)
		(width 0.088646)
		(layer "In4.Cu")
		(net "M_F_CPU1_SA_DQS_DN<8>")
	)
	(segment
		(start 162.357562 -272.289016)
		(end 161.287206 -272.289016)
		(width 0.18288)
		(layer "In4.Cu")
		(net "M_F_CPU1_SA_DQS_DN<8>")
	)
	(segment
		(start 138.844782 -260.24205)
		(end 138.784838 -260.182106)
		(width 0.088646)
		(layer "In4.Cu")
		(net "M_F_CPU1_SA_DQS_DN<8>")
	)
	(segment
		(start 174.683674 -284.023816)
		(end 174.559214 -283.899356)
		(width 0.18288)
		(layer "In4.Cu")
		(net "M_F_CPU1_SA_DQS_DN<8>")
	)
	(segment
		(start 164.782754 -272.738596)
		(end 163.698682 -272.289016)
		(width 0.18288)
		(layer "In4.Cu")
		(net "M_F_CPU1_SA_DQS_DN<8>")
	)
	(segment
		(start 176.896014 -284.016704)
		(end 176.626012 -283.746702)
		(width 0.18288)
		(layer "In4.Cu")
		(net "M_F_CPU1_SA_DQS_DN<8>")
	)
	(segment
		(start 134.50316 -260.11251)
		(end 134.492746 -260.106414)
		(width 0.088646)
		(layer "In4.Cu")
		(net "M_F_CPU1_SA_DQS_DN<8>")
	)
	(segment
		(start 170.004994 -279.602184)
		(end 170.129454 -279.477724)
		(width 0.18288)
		(layer "In4.Cu")
		(net "M_F_CPU1_SA_DQS_DN<8>")
	)
	(segment
		(start 170.004994 -280.148284)
		(end 170.004994 -279.602184)
		(width 0.18288)
		(layer "In4.Cu")
		(net "M_F_CPU1_SA_DQS_DN<8>")
	)
	(segment
		(start 166.021766 -273.252692)
		(end 165.517576 -273.04365)
		(width 0.18288)
		(layer "In4.Cu")
		(net "M_F_CPU1_SA_DQS_DN<8>")
	)
	(segment
		(start 144.902428 -261.785608)
		(end 144.569688 -261.452868)
		(width 0.18288)
		(layer "In4.Cu")
		(net "M_F_CPU1_SA_DQS_DN<8>")
	)
	(segment
		(start 158.185612 -270.575786)
		(end 157.903926 -270.857472)
		(width 0.18288)
		(layer "In4.Cu")
		(net "M_F_CPU1_SA_DQS_DN<8>")
	)
	(segment
		(start 174.013114 -283.899356)
		(end 173.44517 -283.331412)
		(width 0.18288)
		(layer "In4.Cu")
		(net "M_F_CPU1_SA_DQS_DN<8>")
	)
	(segment
		(start 170.129454 -278.867616)
		(end 170.004994 -278.743156)
		(width 0.18288)
		(layer "In4.Cu")
		(net "M_F_CPU1_SA_DQS_DN<8>")
	)
	(segment
		(start 171.309538 -283.144976)
		(end 170.939968 -282.775152)
		(width 0.18288)
		(layer "In4.Cu")
		(net "M_F_CPU1_SA_DQS_DN<8>")
	)
	(segment
		(start 170.004994 -278.743156)
		(end 170.004994 -278.197056)
		(width 0.18288)
		(layer "In4.Cu")
		(net "M_F_CPU1_SA_DQS_DN<8>")
	)
	(segment
		(start 176.067466 -283.899356)
		(end 175.354234 -283.899356)
		(width 0.18288)
		(layer "In4.Cu")
		(net "M_F_CPU1_SA_DQS_DN<8>")
	)
	(segment
		(start 157.187138 -270.382746)
		(end 148.990304 -262.185912)
		(width 0.18288)
		(layer "In4.Cu")
		(net "M_F_CPU1_SA_DQS_DN<8>")
	)
	(segment
		(start 170.129454 -280.818844)
		(end 170.129454 -280.272744)
		(width 0.18288)
		(layer "In4.Cu")
		(net "M_F_CPU1_SA_DQS_DN<8>")
	)
	(segment
		(start 133.563106 -260.11251)
		(end 133.552692 -260.106414)
		(width 0.088646)
		(layer "In4.Cu")
		(net "M_F_CPU1_SA_DQS_DN<8>")
	)
	(segment
		(start 163.698682 -272.289016)
		(end 163.152582 -272.289016)
		(width 0.18288)
		(layer "In4.Cu")
		(net "M_F_CPU1_SA_DQS_DN<8>")
	)
	(segment
		(start 172.577252 -283.592524)
		(end 172.313854 -283.329126)
		(width 0.18288)
		(layer "In4.Cu")
		(net "M_F_CPU1_SA_DQS_DN<8>")
	)
	(segment
		(start 165.354762 -273.11096)
		(end 164.850064 -272.901664)
		(width 0.18288)
		(layer "In4.Cu")
		(net "M_F_CPU1_SA_DQS_DN<8>")
	)
	(segment
		(start 170.004994 -278.197056)
		(end 170.129454 -278.072596)
		(width 0.18288)
		(layer "In4.Cu")
		(net "M_F_CPU1_SA_DQS_DN<8>")
	)
	(segment
		(start 159.384746 -271.207738)
		(end 159.317436 -271.04467)
		(width 0.18288)
		(layer "In4.Cu")
		(net "M_F_CPU1_SA_DQS_DN<8>")
	)
	(segment
		(start 133.178296 -260.106414)
		(end 133.046724 -260.18236)
		(width 0.088646)
		(layer "In4.Cu")
		(net "M_F_CPU1_SA_DQS_DN<8>")
	)
	(segment
		(start 161.287206 -272.289016)
		(end 160.556448 -271.558258)
		(width 0.18288)
		(layer "In4.Cu")
		(net "M_F_CPU1_SA_DQS_DN<8>")
	)
	(segment
		(start 132.437886 -260.28142)
		(end 132.425948 -260.430772)
		(width 0.088646)
		(layer "In4.Cu")
		(net "M_F_CPU1_SA_DQS_DN<8>")
	)
	(segment
		(start 170.129454 -279.477724)
		(end 170.129454 -278.867616)
		(width 0.18288)
		(layer "In4.Cu")
		(net "M_F_CPU1_SA_DQS_DN<8>")
	)
	(segment
		(start 162.482022 -272.413476)
		(end 162.357562 -272.289016)
		(width 0.18288)
		(layer "In4.Cu")
		(net "M_F_CPU1_SA_DQS_DN<8>")
	)
	(segment
		(start 175.354234 -283.899356)
		(end 175.229774 -284.023816)
		(width 0.18288)
		(layer "In4.Cu")
		(net "M_F_CPU1_SA_DQS_DN<8>")
	)
	(segment
		(start 172.313854 -283.329126)
		(end 171.75353 -283.329126)
		(width 0.18288)
		(layer "In4.Cu")
		(net "M_F_CPU1_SA_DQS_DN<8>")
	)
	(segment
		(start 170.939968 -282.775152)
		(end 170.129454 -280.818844)
		(width 0.18288)
		(layer "In4.Cu")
		(net "M_F_CPU1_SA_DQS_DN<8>")
	)
	(segment
		(start 133.046724 -260.18236)
		(end 132.891784 -260.223762)
		(width 0.088646)
		(layer "In4.Cu")
		(net "M_F_CPU1_SA_DQS_DN<8>")
	)
	(segment
		(start 170.129454 -277.736046)
		(end 169.758614 -275.87448)
		(width 0.18288)
		(layer "In4.Cu")
		(net "M_F_CPU1_SA_DQS_DN<8>")
	)
	(segment
		(start 158.569152 -270.73479)
		(end 158.410148 -270.575786)
		(width 0.18288)
		(layer "In4.Cu")
		(net "M_F_CPU1_SA_DQS_DN<8>")
	)
	(segment
		(start 160.556448 -271.558258)
		(end 160.052004 -271.349216)
		(width 0.18288)
		(layer "In4.Cu")
		(net "M_F_CPU1_SA_DQS_DN<8>")
	)
	(segment
		(start 171.75353 -283.329126)
		(end 171.309538 -283.144976)
		(width 0.18288)
		(layer "In4.Cu")
		(net "M_F_CPU1_SA_DQS_DN<8>")
	)
	(segment
		(start 138.784838 -260.182106)
		(end 138.533886 -260.182106)
		(width 0.088646)
		(layer "In4.Cu")
		(net "M_F_CPU1_SA_DQS_DN<8>")
	)
	(segment
		(start 138.86815 -260.24205)
		(end 138.844782 -260.24205)
		(width 0.088646)
		(layer "In4.Cu")
		(net "M_F_CPU1_SA_DQS_DN<8>")
	)
	(segment
		(start 136.371838 -260.106414)
		(end 136.363456 -260.101588)
		(width 0.088646)
		(layer "In4.Cu")
		(net "M_F_CPU1_SA_DQS_DN<8>")
	)
	(segment
		(start 173.44517 -283.331412)
		(end 173.253146 -283.331412)
		(width 0.18288)
		(layer "In4.Cu")
		(net "M_F_CPU1_SA_DQS_DN<8>")
	)
	(segment
		(start 157.903926 -270.857472)
		(end 157.551628 -270.857472)
		(width 0.18288)
		(layer "In4.Cu")
		(net "M_F_CPU1_SA_DQS_DN<8>")
	)
	(segment
		(start 168.665398 -274.845272)
		(end 167.35298 -274.583906)
		(width 0.18288)
		(layer "In4.Cu")
		(net "M_F_CPU1_SA_DQS_DN<8>")
	)
	(segment
		(start 160.052004 -271.349216)
		(end 159.889444 -271.41678)
		(width 0.18288)
		(layer "In4.Cu")
		(net "M_F_CPU1_SA_DQS_DN<8>")
	)
	(segment
		(start 176.626012 -283.746702)
		(end 176.43602 -283.746702)
		(width 0.18288)
		(layer "In4.Cu")
		(net "M_F_CPU1_SA_DQS_DN<8>")
	)
	(segment
		(start 159.889444 -271.41678)
		(end 159.384746 -271.207738)
		(width 0.18288)
		(layer "In4.Cu")
		(net "M_F_CPU1_SA_DQS_DN<8>")
	)
	(segment
		(start 137.32637 -260.11505)
		(end 137.311638 -260.106414)
		(width 0.088646)
		(layer "In4.Cu")
		(net "M_F_CPU1_SA_DQS_DN<8>")
	)
	(segment
		(start 141.654784 -260.24205)
		(end 138.86815 -260.24205)
		(width 0.18288)
		(layer "In4.Cu")
		(net "M_F_CPU1_SA_DQS_DN<8>")
	)
	(segment
		(start 170.129454 -280.272744)
		(end 170.004994 -280.148284)
		(width 0.18288)
		(layer "In4.Cu")
		(net "M_F_CPU1_SA_DQS_DN<8>")
	)
	(arc
		(start 138.251438 -260.106414)
		(mid 138.06424 -260.056271)
		(end 137.877042 -260.106414)
		(width 0.088646)
		(layer "In4.Cu")
		(net "M_F_CPU1_SA_DQS_DN<8>")
	)
	(arc
		(start 137.311638 -260.106414)
		(mid 137.12444 -260.056271)
		(end 136.937242 -260.106414)
		(width 0.088646)
		(layer "In4.Cu")
		(net "M_F_CPU1_SA_DQS_DN<8>")
	)
	(arc
		(start 134.11835 -260.106414)
		(mid 133.841537 -260.182284)
		(end 133.563106 -260.11251)
		(width 0.088646)
		(layer "In4.Cu")
		(net "M_F_CPU1_SA_DQS_DN<8>")
	)
	(arc
		(start 135.057896 -260.106414)
		(mid 134.781337 -260.182157)
		(end 134.50316 -260.11251)
		(width 0.088646)
		(layer "In4.Cu")
		(net "M_F_CPU1_SA_DQS_DN<8>")
	)
	(arc
		(start 133.552692 -260.106414)
		(mid 133.365494 -260.056271)
		(end 133.178296 -260.106414)
		(width 0.088646)
		(layer "In4.Cu")
		(net "M_F_CPU1_SA_DQS_DN<8>")
	)
	(arc
		(start 136.363456 -260.101588)
		(mid 136.179948 -260.05631)
		(end 135.997696 -260.106414)
		(width 0.088646)
		(layer "In4.Cu")
		(net "M_F_CPU1_SA_DQS_DN<8>")
	)
	(arc
		(start 134.492746 -260.106414)
		(mid 134.305548 -260.056271)
		(end 134.11835 -260.106414)
		(width 0.088646)
		(layer "In4.Cu")
		(net "M_F_CPU1_SA_DQS_DN<8>")
	)
	(arc
		(start 137.877042 -260.106414)
		(mid 137.602843 -260.182249)
		(end 137.32637 -260.11505)
		(width 0.088646)
		(layer "In4.Cu")
		(net "M_F_CPU1_SA_DQS_DN<8>")
	)
	(arc
		(start 135.997696 -260.106414)
		(mid 135.723497 -260.182249)
		(end 135.447024 -260.11505)
		(width 0.088646)
		(layer "In4.Cu")
		(net "M_F_CPU1_SA_DQS_DN<8>")
	)
	(arc
		(start 138.533886 -260.182106)
		(mid 138.387678 -260.162857)
		(end 138.251438 -260.106414)
		(width 0.088646)
		(layer "In4.Cu")
		(net "M_F_CPU1_SA_DQS_DN<8>")
	)
	(arc
		(start 135.432292 -260.106414)
		(mid 135.245094 -260.056271)
		(end 135.057896 -260.106414)
		(width 0.088646)
		(layer "In4.Cu")
		(net "M_F_CPU1_SA_DQS_DN<8>")
	)
	(arc
		(start 136.937242 -260.106414)
		(mid 136.663043 -260.182249)
		(end 136.38657 -260.11505)
		(width 0.088646)
		(layer "In4.Cu")
		(net "M_F_CPU1_SA_DQS_DN<8>")
	)
	(arc
		(start 132.50037 -260.223762)
		(mid 132.457843 -260.240375)
		(end 132.437886 -260.28142)
		(width 0.088646)
		(layer "In4.Cu")
		(net "M_F_CPU1_SA_DQS_DN<8>")
	)
	(segment
		(start 179.833524 -292.670484)
		(end 180.110892 -292.947852)
		(width 0.20066)
		(layer "F.Cu")
		(net "M_F_CPU1_SA_DQS_DN<7>")
	)
	(segment
		(start 179.286154 -293.095426)
		(end 179.711096 -292.670484)
		(width 0.20066)
		(layer "F.Cu")
		(net "M_F_CPU1_SA_DQS_DN<7>")
	)
	(segment
		(start 185.041032 -293.366698)
		(end 185.544714 -293.366698)
		(width 0.20066)
		(layer "F.Cu")
		(net "M_F_CPU1_SA_DQS_DN<7>")
	)
	(segment
		(start 182.444136 -292.941756)
		(end 182.455058 -292.952678)
		(width 0.1016)
		(layer "F.Cu")
		(net "M_F_CPU1_SA_DQS_DN<7>")
	)
	(segment
		(start 179.711096 -292.670484)
		(end 179.833524 -292.670484)
		(width 0.20066)
		(layer "F.Cu")
		(net "M_F_CPU1_SA_DQS_DN<7>")
	)
	(segment
		(start 178.802792 -293.095426)
		(end 179.286154 -293.095426)
		(width 0.20066)
		(layer "F.Cu")
		(net "M_F_CPU1_SA_DQS_DN<7>")
	)
	(segment
		(start 183.549544 -292.666928)
		(end 183.99506 -293.112444)
		(width 0.20066)
		(layer "F.Cu")
		(net "M_F_CPU1_SA_DQS_DN<7>")
	)
	(segment
		(start 135.714994 -267.219938)
		(end 135.714994 -267.755878)
		(width 0.20066)
		(layer "F.Cu")
		(net "M_F_CPU1_SA_DQS_DN<7>")
	)
	(segment
		(start 176.896014 -293.366698)
		(end 178.000914 -293.366698)
		(width 0.20066)
		(layer "F.Cu")
		(net "M_F_CPU1_SA_DQS_DN<7>")
	)
	(segment
		(start 180.110892 -292.947852)
		(end 180.423058 -292.947852)
		(width 0.20066)
		(layer "F.Cu")
		(net "M_F_CPU1_SA_DQS_DN<7>")
	)
	(segment
		(start 178.53152 -293.366698)
		(end 178.802792 -293.095426)
		(width 0.20066)
		(layer "F.Cu")
		(net "M_F_CPU1_SA_DQS_DN<7>")
	)
	(segment
		(start 183.059578 -292.666928)
		(end 183.549544 -292.666928)
		(width 0.20066)
		(layer "F.Cu")
		(net "M_F_CPU1_SA_DQS_DN<7>")
	)
	(segment
		(start 183.99506 -293.112444)
		(end 184.786778 -293.112444)
		(width 0.20066)
		(layer "F.Cu")
		(net "M_F_CPU1_SA_DQS_DN<7>")
	)
	(segment
		(start 178.000914 -293.366698)
		(end 178.53152 -293.366698)
		(width 0.20066)
		(layer "F.Cu")
		(net "M_F_CPU1_SA_DQS_DN<7>")
	)
	(segment
		(start 184.786778 -293.112444)
		(end 185.041032 -293.366698)
		(width 0.20066)
		(layer "F.Cu")
		(net "M_F_CPU1_SA_DQS_DN<7>")
	)
	(segment
		(start 182.455058 -292.952678)
		(end 182.773828 -292.952678)
		(width 0.20066)
		(layer "F.Cu")
		(net "M_F_CPU1_SA_DQS_DN<7>")
	)
	(segment
		(start 180.43398 -292.941756)
		(end 182.444136 -292.941756)
		(width 0.1016)
		(layer "F.Cu")
		(net "M_F_CPU1_SA_DQS_DN<7>")
	)
	(segment
		(start 180.427884 -292.947852)
		(end 180.43398 -292.941756)
		(width 0.1016)
		(layer "F.Cu")
		(net "M_F_CPU1_SA_DQS_DN<7>")
	)
	(segment
		(start 182.773828 -292.952678)
		(end 183.059578 -292.666928)
		(width 0.20066)
		(layer "F.Cu")
		(net "M_F_CPU1_SA_DQS_DN<7>")
	)
	(segment
		(start 180.423058 -292.947852)
		(end 180.427884 -292.947852)
		(width 0.101854)
		(layer "F.Cu")
		(net "M_F_CPU1_SA_DQS_DN<7>")
	)
	(segment
		(start 171.765468 -292.665404)
		(end 171.126404 -292.026594)
		(width 0.18288)
		(layer "In2.Cu")
		(net "M_F_CPU1_SA_DQS_DN<7>")
	)
	(segment
		(start 172.259752 -292.665404)
		(end 171.765468 -292.665404)
		(width 0.18288)
		(layer "In2.Cu")
		(net "M_F_CPU1_SA_DQS_DN<7>")
	)
	(segment
		(start 150.301198 -273.737324)
		(end 150.125176 -273.737324)
		(width 0.18288)
		(layer "In2.Cu")
		(net "M_F_CPU1_SA_DQS_DN<7>")
	)
	(segment
		(start 165.10254 -286.712152)
		(end 164.490146 -286.712152)
		(width 0.18288)
		(layer "In2.Cu")
		(net "M_F_CPU1_SA_DQS_DN<7>")
	)
	(segment
		(start 152.183084 -277.033228)
		(end 151.701754 -276.551644)
		(width 0.18288)
		(layer "In2.Cu")
		(net "M_F_CPU1_SA_DQS_DN<7>")
	)
	(segment
		(start 152.183084 -277.208996)
		(end 152.183084 -277.033228)
		(width 0.18288)
		(layer "In2.Cu")
		(net "M_F_CPU1_SA_DQS_DN<7>")
	)
	(segment
		(start 156.402278 -282.870148)
		(end 156.402278 -281.833066)
		(width 0.18288)
		(layer "In2.Cu")
		(net "M_F_CPU1_SA_DQS_DN<7>")
	)
	(segment
		(start 159.749744 -283.797248)
		(end 159.72155 -283.769054)
		(width 0.16002)
		(layer "In2.Cu")
		(net "M_F_CPU1_SA_DQS_DN<7>")
	)
	(segment
		(start 150.718012 -274.166838)
		(end 150.689056 -274.125182)
		(width 0.18288)
		(layer "In2.Cu")
		(net "M_F_CPU1_SA_DQS_DN<7>")
	)
	(segment
		(start 167.30091 -286.392874)
		(end 167.30091 -286.377126)
		(width 0.16002)
		(layer "In2.Cu")
		(net "M_F_CPU1_SA_DQS_DN<7>")
	)
	(segment
		(start 165.61943 -286.195262)
		(end 165.591236 -286.223456)
		(width 0.16002)
		(layer "In2.Cu")
		(net "M_F_CPU1_SA_DQS_DN<7>")
	)
	(segment
		(start 173.284134 -292.67658)
		(end 173.020482 -292.940232)
		(width 0.18288)
		(layer "In2.Cu")
		(net "M_F_CPU1_SA_DQS_DN<7>")
	)
	(segment
		(start 154.651202 -279.501854)
		(end 154.47518 -279.501854)
		(width 0.18288)
		(layer "In2.Cu")
		(net "M_F_CPU1_SA_DQS_DN<7>")
	)
	(segment
		(start 168.960546 -291.016944)
		(end 168.532302 -289.98291)
		(width 0.18288)
		(layer "In2.Cu")
		(net "M_F_CPU1_SA_DQS_DN<7>")
	)
	(segment
		(start 148.260562 -271.696688)
		(end 146.85264 -271.696688)
		(width 0.18288)
		(layer "In2.Cu")
		(net "M_F_CPU1_SA_DQS_DN<7>")
	)
	(segment
		(start 154.087068 -279.113488)
		(end 154.087068 -278.937466)
		(width 0.18288)
		(layer "In2.Cu")
		(net "M_F_CPU1_SA_DQS_DN<7>")
	)
	(segment
		(start 157.32633 -283.593286)
		(end 157.0482 -283.315156)
		(width 0.18288)
		(layer "In2.Cu")
		(net "M_F_CPU1_SA_DQS_DN<7>")
	)
	(segment
		(start 135.758936 -267.525754)
		(end 135.73125 -267.551408)
		(width 0.088646)
		(layer "In2.Cu")
		(net "M_F_CPU1_SA_DQS_DN<7>")
	)
	(segment
		(start 165.591236 -286.223456)
		(end 165.575488 -286.223456)
		(width 0.16002)
		(layer "In2.Cu")
		(net "M_F_CPU1_SA_DQS_DN<7>")
	)
	(segment
		(start 149.349206 -272.785332)
		(end 149.173184 -272.785332)
		(width 0.18288)
		(layer "In2.Cu")
		(net "M_F_CPU1_SA_DQS_DN<7>")
	)
	(segment
		(start 163.821618 -287.004252)
		(end 163.437062 -286.619696)
		(width 0.18288)
		(layer "In2.Cu")
		(net "M_F_CPU1_SA_DQS_DN<7>")
	)
	(segment
		(start 151.12111 -275.46935)
		(end 151.188674 -275.30679)
		(width 0.18288)
		(layer "In2.Cu")
		(net "M_F_CPU1_SA_DQS_DN<7>")
	)
	(segment
		(start 136.467596 -267.43152)
		(end 136.466834 -267.431266)
		(width 0.088646)
		(layer "In2.Cu")
		(net "M_F_CPU1_SA_DQS_DN<7>")
	)
	(segment
		(start 157.72638 -283.593286)
		(end 157.32633 -283.593286)
		(width 0.18288)
		(layer "In2.Cu")
		(net "M_F_CPU1_SA_DQS_DN<7>")
	)
	(segment
		(start 161.883598 -286.307784)
		(end 160.16097 -284.208474)
		(width 0.18288)
		(layer "In2.Cu")
		(net "M_F_CPU1_SA_DQS_DN<7>")
	)
	(segment
		(start 174.075598 -292.67658)
		(end 173.284134 -292.67658)
		(width 0.18288)
		(layer "In2.Cu")
		(net "M_F_CPU1_SA_DQS_DN<7>")
	)
	(segment
		(start 148.785072 -272.221198)
		(end 148.260562 -271.696688)
		(width 0.18288)
		(layer "In2.Cu")
		(net "M_F_CPU1_SA_DQS_DN<7>")
	)
	(segment
		(start 159.72155 -283.753306)
		(end 159.536892 -283.568648)
		(width 0.16002)
		(layer "In2.Cu")
		(net "M_F_CPU1_SA_DQS_DN<7>")
	)
	(segment
		(start 165.39083 -286.408114)
		(end 165.39083 -286.423862)
		(width 0.16002)
		(layer "In2.Cu")
		(net "M_F_CPU1_SA_DQS_DN<7>")
	)
	(segment
		(start 175.165766 -293.292022)
		(end 174.857918 -293.164514)
		(width 0.18288)
		(layer "In2.Cu")
		(net "M_F_CPU1_SA_DQS_DN<7>")
	)
	(segment
		(start 168.762934 -289.426396)
		(end 168.762934 -288.885884)
		(width 0.18288)
		(layer "In2.Cu")
		(net "M_F_CPU1_SA_DQS_DN<7>")
	)
	(segment
		(start 150.125176 -273.737324)
		(end 149.737064 -273.349212)
		(width 0.18288)
		(layer "In2.Cu")
		(net "M_F_CPU1_SA_DQS_DN<7>")
	)
	(segment
		(start 140.84046 -267.678916)
		(end 140.267436 -267.678916)
		(width 0.088646)
		(layer "In2.Cu")
		(net "M_F_CPU1_SA_DQS_DN<7>")
	)
	(segment
		(start 166.989506 -286.08147)
		(end 165.733222 -286.08147)
		(width 0.18288)
		(layer "In2.Cu")
		(net "M_F_CPU1_SA_DQS_DN<7>")
	)
	(segment
		(start 154.087068 -278.937466)
		(end 153.69921 -278.549608)
		(width 0.18288)
		(layer "In2.Cu")
		(net "M_F_CPU1_SA_DQS_DN<7>")
	)
	(segment
		(start 146.85264 -271.696688)
		(end 143.087598 -267.931646)
		(width 0.18288)
		(layer "In2.Cu")
		(net "M_F_CPU1_SA_DQS_DN<7>")
	)
	(segment
		(start 167.116252 -286.192468)
		(end 167.100504 -286.192468)
		(width 0.16002)
		(layer "In2.Cu")
		(net "M_F_CPU1_SA_DQS_DN<7>")
	)
	(segment
		(start 175.666908 -293.292022)
		(end 175.165766 -293.292022)
		(width 0.18288)
		(layer "In2.Cu")
		(net "M_F_CPU1_SA_DQS_DN<7>")
	)
	(segment
		(start 176.69764 -293.01694)
		(end 176.331372 -293.01694)
		(width 0.18288)
		(layer "In2.Cu")
		(net "M_F_CPU1_SA_DQS_DN<7>")
	)
	(segment
		(start 139.67587 -267.439902)
		(end 139.661392 -267.43152)
		(width 0.088646)
		(layer "In2.Cu")
		(net "M_F_CPU1_SA_DQS_DN<7>")
	)
	(segment
		(start 173.020482 -292.940232)
		(end 173.020482 -292.94201)
		(width 0.18288)
		(layer "In2.Cu")
		(net "M_F_CPU1_SA_DQS_DN<7>")
	)
	(segment
		(start 163.437062 -286.619696)
		(end 162.6362 -286.619696)
		(width 0.18288)
		(layer "In2.Cu")
		(net "M_F_CPU1_SA_DQS_DN<7>")
	)
	(segment
		(start 169.735754 -291.653722)
		(end 168.960546 -291.016944)
		(width 0.18288)
		(layer "In2.Cu")
		(net "M_F_CPU1_SA_DQS_DN<7>")
	)
	(segment
		(start 150.689056 -274.125182)
		(end 150.301198 -273.737324)
		(width 0.18288)
		(layer "In2.Cu")
		(net "M_F_CPU1_SA_DQS_DN<7>")
	)
	(segment
		(start 161.883598 -286.308038)
		(end 161.883598 -286.307784)
		(width 0.18288)
		(layer "In2.Cu")
		(net "M_F_CPU1_SA_DQS_DN<7>")
	)
	(segment
		(start 167.329104 -286.421068)
		(end 167.30091 -286.392874)
		(width 0.16002)
		(layer "In2.Cu")
		(net "M_F_CPU1_SA_DQS_DN<7>")
	)
	(segment
		(start 165.39083 -286.423862)
		(end 165.362636 -286.452056)
		(width 0.16002)
		(layer "In2.Cu")
		(net "M_F_CPU1_SA_DQS_DN<7>")
	)
	(segment
		(start 165.575488 -286.223456)
		(end 165.39083 -286.408114)
		(width 0.16002)
		(layer "In2.Cu")
		(net "M_F_CPU1_SA_DQS_DN<7>")
	)
	(segment
		(start 142.62227 -267.73886)
		(end 140.900404 -267.73886)
		(width 0.18288)
		(layer "In2.Cu")
		(net "M_F_CPU1_SA_DQS_DN<7>")
	)
	(segment
		(start 149.737064 -273.17319)
		(end 149.349206 -272.785332)
		(width 0.18288)
		(layer "In2.Cu")
		(net "M_F_CPU1_SA_DQS_DN<7>")
	)
	(segment
		(start 162.6362 -286.619696)
		(end 161.883598 -286.308038)
		(width 0.18288)
		(layer "In2.Cu")
		(net "M_F_CPU1_SA_DQS_DN<7>")
	)
	(segment
		(start 164.490146 -286.712152)
		(end 164.198046 -287.004252)
		(width 0.18288)
		(layer "In2.Cu")
		(net "M_F_CPU1_SA_DQS_DN<7>")
	)
	(segment
		(start 140.267436 -267.678916)
		(end 140.115544 -267.527024)
		(width 0.088646)
		(layer "In2.Cu")
		(net "M_F_CPU1_SA_DQS_DN<7>")
	)
	(segment
		(start 164.198046 -287.004252)
		(end 163.821618 -287.004252)
		(width 0.18288)
		(layer "In2.Cu")
		(net "M_F_CPU1_SA_DQS_DN<7>")
	)
	(segment
		(start 159.49295 -283.540454)
		(end 159.278828 -283.326332)
		(width 0.18288)
		(layer "In2.Cu")
		(net "M_F_CPU1_SA_DQS_DN<7>")
	)
	(segment
		(start 173.020482 -292.94201)
		(end 172.536358 -292.94201)
		(width 0.18288)
		(layer "In2.Cu")
		(net "M_F_CPU1_SA_DQS_DN<7>")
	)
	(segment
		(start 170.579288 -291.799772)
		(end 169.735754 -291.653722)
		(width 0.18288)
		(layer "In2.Cu")
		(net "M_F_CPU1_SA_DQS_DN<7>")
	)
	(segment
		(start 159.536892 -283.568648)
		(end 159.521144 -283.568648)
		(width 0.16002)
		(layer "In2.Cu")
		(net "M_F_CPU1_SA_DQS_DN<7>")
	)
	(segment
		(start 165.733222 -286.08147)
		(end 165.61943 -286.195262)
		(width 0.18288)
		(layer "In2.Cu")
		(net "M_F_CPU1_SA_DQS_DN<7>")
	)
	(segment
		(start 155.03906 -280.06548)
		(end 155.03906 -279.889712)
		(width 0.18288)
		(layer "In2.Cu")
		(net "M_F_CPU1_SA_DQS_DN<7>")
	)
	(segment
		(start 152.747218 -277.597362)
		(end 152.571196 -277.597362)
		(width 0.18288)
		(layer "In2.Cu")
		(net "M_F_CPU1_SA_DQS_DN<7>")
	)
	(segment
		(start 167.30091 -286.377126)
		(end 167.116252 -286.192468)
		(width 0.16002)
		(layer "In2.Cu")
		(net "M_F_CPU1_SA_DQS_DN<7>")
	)
	(segment
		(start 165.362636 -286.452056)
		(end 165.10254 -286.712152)
		(width 0.18288)
		(layer "In2.Cu")
		(net "M_F_CPU1_SA_DQS_DN<7>")
	)
	(segment
		(start 171.126404 -292.026594)
		(end 170.579288 -291.799772)
		(width 0.18288)
		(layer "In2.Cu")
		(net "M_F_CPU1_SA_DQS_DN<7>")
	)
	(segment
		(start 174.857918 -293.164514)
		(end 174.57801 -292.884606)
		(width 0.18288)
		(layer "In2.Cu")
		(net "M_F_CPU1_SA_DQS_DN<7>")
	)
	(segment
		(start 153.523188 -278.549608)
		(end 153.135076 -278.161242)
		(width 0.18288)
		(layer "In2.Cu")
		(net "M_F_CPU1_SA_DQS_DN<7>")
	)
	(segment
		(start 151.330152 -275.976842)
		(end 151.12111 -275.46935)
		(width 0.18288)
		(layer "In2.Cu")
		(net "M_F_CPU1_SA_DQS_DN<7>")
	)
	(segment
		(start 151.492966 -276.044406)
		(end 151.330152 -275.976842)
		(width 0.18288)
		(layer "In2.Cu")
		(net "M_F_CPU1_SA_DQS_DN<7>")
	)
	(segment
		(start 140.115544 -267.527024)
		(end 139.981178 -267.527024)
		(width 0.088646)
		(layer "In2.Cu")
		(net "M_F_CPU1_SA_DQS_DN<7>")
	)
	(segment
		(start 168.762934 -288.885884)
		(end 168.033954 -287.125918)
		(width 0.18288)
		(layer "In2.Cu")
		(net "M_F_CPU1_SA_DQS_DN<7>")
	)
	(segment
		(start 149.173184 -272.785332)
		(end 148.785072 -272.39722)
		(width 0.18288)
		(layer "In2.Cu")
		(net "M_F_CPU1_SA_DQS_DN<7>")
	)
	(segment
		(start 172.536358 -292.94201)
		(end 172.259752 -292.665404)
		(width 0.18288)
		(layer "In2.Cu")
		(net "M_F_CPU1_SA_DQS_DN<7>")
	)
	(segment
		(start 159.72155 -283.769054)
		(end 159.72155 -283.753306)
		(width 0.16002)
		(layer "In2.Cu")
		(net "M_F_CPU1_SA_DQS_DN<7>")
	)
	(segment
		(start 155.603194 -280.453846)
		(end 155.427172 -280.453846)
		(width 0.18288)
		(layer "In2.Cu")
		(net "M_F_CPU1_SA_DQS_DN<7>")
	)
	(segment
		(start 151.701754 -276.551644)
		(end 151.492966 -276.044406)
		(width 0.18288)
		(layer "In2.Cu")
		(net "M_F_CPU1_SA_DQS_DN<7>")
	)
	(segment
		(start 135.73125 -267.551408)
		(end 135.714994 -267.755878)
		(width 0.088646)
		(layer "In2.Cu")
		(net "M_F_CPU1_SA_DQS_DN<7>")
	)
	(segment
		(start 149.737064 -273.349212)
		(end 149.737064 -273.17319)
		(width 0.18288)
		(layer "In2.Cu")
		(net "M_F_CPU1_SA_DQS_DN<7>")
	)
	(segment
		(start 176.331372 -293.01694)
		(end 175.666908 -293.292022)
		(width 0.18288)
		(layer "In2.Cu")
		(net "M_F_CPU1_SA_DQS_DN<7>")
	)
	(segment
		(start 151.188674 -275.30679)
		(end 150.720298 -274.169886)
		(width 0.18288)
		(layer "In2.Cu")
		(net "M_F_CPU1_SA_DQS_DN<7>")
	)
	(segment
		(start 156.847286 -283.315156)
		(end 156.402278 -282.870148)
		(width 0.18288)
		(layer "In2.Cu")
		(net "M_F_CPU1_SA_DQS_DN<7>")
	)
	(segment
		(start 155.03906 -279.889712)
		(end 154.651202 -279.501854)
		(width 0.18288)
		(layer "In2.Cu")
		(net "M_F_CPU1_SA_DQS_DN<7>")
	)
	(segment
		(start 140.900404 -267.73886)
		(end 140.84046 -267.678916)
		(width 0.088646)
		(layer "In2.Cu")
		(net "M_F_CPU1_SA_DQS_DN<7>")
	)
	(segment
		(start 157.993334 -283.326332)
		(end 157.72638 -283.593286)
		(width 0.18288)
		(layer "In2.Cu")
		(net "M_F_CPU1_SA_DQS_DN<7>")
	)
	(segment
		(start 168.033954 -287.125918)
		(end 167.329104 -286.421068)
		(width 0.18288)
		(layer "In2.Cu")
		(net "M_F_CPU1_SA_DQS_DN<7>")
	)
	(segment
		(start 157.0482 -283.315156)
		(end 156.847286 -283.315156)
		(width 0.18288)
		(layer "In2.Cu")
		(net "M_F_CPU1_SA_DQS_DN<7>")
	)
	(segment
		(start 153.69921 -278.549608)
		(end 153.523188 -278.549608)
		(width 0.18288)
		(layer "In2.Cu")
		(net "M_F_CPU1_SA_DQS_DN<7>")
	)
	(segment
		(start 159.521144 -283.568648)
		(end 159.49295 -283.540454)
		(width 0.16002)
		(layer "In2.Cu")
		(net "M_F_CPU1_SA_DQS_DN<7>")
	)
	(segment
		(start 153.135076 -278.161242)
		(end 153.135076 -277.98522)
		(width 0.18288)
		(layer "In2.Cu")
		(net "M_F_CPU1_SA_DQS_DN<7>")
	)
	(segment
		(start 156.402278 -281.833066)
		(end 155.991052 -280.841704)
		(width 0.18288)
		(layer "In2.Cu")
		(net "M_F_CPU1_SA_DQS_DN<7>")
	)
	(segment
		(start 154.47518 -279.501854)
		(end 154.087068 -279.113488)
		(width 0.18288)
		(layer "In2.Cu")
		(net "M_F_CPU1_SA_DQS_DN<7>")
	)
	(segment
		(start 136.11352 -267.525754)
		(end 135.758936 -267.525754)
		(width 0.088646)
		(layer "In2.Cu")
		(net "M_F_CPU1_SA_DQS_DN<7>")
	)
	(segment
		(start 176.896014 -293.366698)
		(end 176.775618 -293.094918)
		(width 0.18288)
		(layer "In2.Cu")
		(net "M_F_CPU1_SA_DQS_DN<7>")
	)
	(segment
		(start 174.57801 -292.884606)
		(end 174.075598 -292.67658)
		(width 0.18288)
		(layer "In2.Cu")
		(net "M_F_CPU1_SA_DQS_DN<7>")
	)
	(segment
		(start 153.135076 -277.98522)
		(end 152.747218 -277.597362)
		(width 0.18288)
		(layer "In2.Cu")
		(net "M_F_CPU1_SA_DQS_DN<7>")
	)
	(segment
		(start 155.427172 -280.453846)
		(end 155.03906 -280.06548)
		(width 0.18288)
		(layer "In2.Cu")
		(net "M_F_CPU1_SA_DQS_DN<7>")
	)
	(segment
		(start 148.785072 -272.39722)
		(end 148.785072 -272.221198)
		(width 0.18288)
		(layer "In2.Cu")
		(net "M_F_CPU1_SA_DQS_DN<7>")
	)
	(segment
		(start 155.991052 -280.841704)
		(end 155.603194 -280.453846)
		(width 0.18288)
		(layer "In2.Cu")
		(net "M_F_CPU1_SA_DQS_DN<7>")
	)
	(segment
		(start 143.087598 -267.931646)
		(end 142.62227 -267.73886)
		(width 0.18288)
		(layer "In2.Cu")
		(net "M_F_CPU1_SA_DQS_DN<7>")
	)
	(segment
		(start 159.278828 -283.326332)
		(end 157.993334 -283.326332)
		(width 0.18288)
		(layer "In2.Cu")
		(net "M_F_CPU1_SA_DQS_DN<7>")
	)
	(segment
		(start 150.720298 -274.169886)
		(end 150.718012 -274.166838)
		(width 0.18288)
		(layer "In2.Cu")
		(net "M_F_CPU1_SA_DQS_DN<7>")
	)
	(segment
		(start 167.100504 -286.192468)
		(end 167.07231 -286.164274)
		(width 0.16002)
		(layer "In2.Cu")
		(net "M_F_CPU1_SA_DQS_DN<7>")
	)
	(segment
		(start 168.532302 -289.98291)
		(end 168.762934 -289.426396)
		(width 0.18288)
		(layer "In2.Cu")
		(net "M_F_CPU1_SA_DQS_DN<7>")
	)
	(segment
		(start 176.775618 -293.094918)
		(end 176.69764 -293.01694)
		(width 0.18288)
		(layer "In2.Cu")
		(net "M_F_CPU1_SA_DQS_DN<7>")
	)
	(segment
		(start 160.16097 -284.208474)
		(end 159.749744 -283.797248)
		(width 0.18288)
		(layer "In2.Cu")
		(net "M_F_CPU1_SA_DQS_DN<7>")
	)
	(segment
		(start 152.571196 -277.597362)
		(end 152.183084 -277.208996)
		(width 0.18288)
		(layer "In2.Cu")
		(net "M_F_CPU1_SA_DQS_DN<7>")
	)
	(segment
		(start 167.07231 -286.164274)
		(end 166.989506 -286.08147)
		(width 0.18288)
		(layer "In2.Cu")
		(net "M_F_CPU1_SA_DQS_DN<7>")
	)
	(arc
		(start 136.466834 -267.431266)
		(mid 136.296379 -267.50169)
		(end 136.11352 -267.525754)
		(width 0.088646)
		(layer "In2.Cu")
		(net "M_F_CPU1_SA_DQS_DN<7>")
	)
	(arc
		(start 139.661392 -267.43152)
		(mid 139.474194 -267.381377)
		(end 139.286996 -267.43152)
		(width 0.088646)
		(layer "In2.Cu")
		(net "M_F_CPU1_SA_DQS_DN<7>")
	)
	(arc
		(start 138.721592 -267.43152)
		(mid 138.534394 -267.381377)
		(end 138.347196 -267.43152)
		(width 0.088646)
		(layer "In2.Cu")
		(net "M_F_CPU1_SA_DQS_DN<7>")
	)
	(arc
		(start 137.781792 -267.43152)
		(mid 137.594594 -267.381377)
		(end 137.407396 -267.43152)
		(width 0.088646)
		(layer "In2.Cu")
		(net "M_F_CPU1_SA_DQS_DN<7>")
	)
	(arc
		(start 136.841992 -267.43152)
		(mid 136.654794 -267.381377)
		(end 136.467596 -267.43152)
		(width 0.088646)
		(layer "In2.Cu")
		(net "M_F_CPU1_SA_DQS_DN<7>")
	)
	(arc
		(start 137.407396 -267.43152)
		(mid 137.124694 -267.507262)
		(end 136.841992 -267.43152)
		(width 0.088646)
		(layer "In2.Cu")
		(net "M_F_CPU1_SA_DQS_DN<7>")
	)
	(arc
		(start 139.981178 -267.527024)
		(mid 139.912294 -267.522803)
		(end 139.844526 -267.509752)
		(width 0.088646)
		(layer "In2.Cu")
		(net "M_F_CPU1_SA_DQS_DN<7>")
	)
	(arc
		(start 139.286996 -267.43152)
		(mid 139.004294 -267.507262)
		(end 138.721592 -267.43152)
		(width 0.088646)
		(layer "In2.Cu")
		(net "M_F_CPU1_SA_DQS_DN<7>")
	)
	(arc
		(start 139.844526 -267.509752)
		(mid 139.757856 -267.480482)
		(end 139.67587 -267.439902)
		(width 0.088646)
		(layer "In2.Cu")
		(net "M_F_CPU1_SA_DQS_DN<7>")
	)
	(arc
		(start 138.347196 -267.43152)
		(mid 138.064494 -267.507262)
		(end 137.781792 -267.43152)
		(width 0.088646)
		(layer "In2.Cu")
		(net "M_F_CPU1_SA_DQS_DN<7>")
	)
	(segment
		(start 180.427884 -302.297846)
		(end 180.43398 -302.29175)
		(width 0.1016)
		(layer "F.Cu")
		(net "M_F_CPU1_SA_DQS_DN<6>")
	)
	(segment
		(start 178.000914 -302.716692)
		(end 178.53152 -302.716692)
		(width 0.20066)
		(layer "F.Cu")
		(net "M_F_CPU1_SA_DQS_DN<6>")
	)
	(segment
		(start 179.286154 -302.44542)
		(end 179.711096 -302.020478)
		(width 0.20066)
		(layer "F.Cu")
		(net "M_F_CPU1_SA_DQS_DN<6>")
	)
	(segment
		(start 184.786778 -302.462438)
		(end 185.041032 -302.716692)
		(width 0.20066)
		(layer "F.Cu")
		(net "M_F_CPU1_SA_DQS_DN<6>")
	)
	(segment
		(start 179.711096 -302.020478)
		(end 179.833524 -302.020478)
		(width 0.20066)
		(layer "F.Cu")
		(net "M_F_CPU1_SA_DQS_DN<6>")
	)
	(segment
		(start 183.549544 -302.016922)
		(end 183.99506 -302.462438)
		(width 0.20066)
		(layer "F.Cu")
		(net "M_F_CPU1_SA_DQS_DN<6>")
	)
	(segment
		(start 178.802792 -302.44542)
		(end 179.286154 -302.44542)
		(width 0.20066)
		(layer "F.Cu")
		(net "M_F_CPU1_SA_DQS_DN<6>")
	)
	(segment
		(start 180.423058 -302.297846)
		(end 180.427884 -302.297846)
		(width 0.101854)
		(layer "F.Cu")
		(net "M_F_CPU1_SA_DQS_DN<6>")
	)
	(segment
		(start 132.425694 -269.66164)
		(end 132.425948 -270.167862)
		(width 0.20066)
		(layer "F.Cu")
		(net "M_F_CPU1_SA_DQS_DN<6>")
	)
	(segment
		(start 180.43398 -302.29175)
		(end 182.444136 -302.29175)
		(width 0.1016)
		(layer "F.Cu")
		(net "M_F_CPU1_SA_DQS_DN<6>")
	)
	(segment
		(start 185.041032 -302.716692)
		(end 185.544714 -302.716692)
		(width 0.20066)
		(layer "F.Cu")
		(net "M_F_CPU1_SA_DQS_DN<6>")
	)
	(segment
		(start 179.833524 -302.020478)
		(end 180.110892 -302.297846)
		(width 0.20066)
		(layer "F.Cu")
		(net "M_F_CPU1_SA_DQS_DN<6>")
	)
	(segment
		(start 176.896014 -302.716692)
		(end 178.000914 -302.716692)
		(width 0.20066)
		(layer "F.Cu")
		(net "M_F_CPU1_SA_DQS_DN<6>")
	)
	(segment
		(start 182.773828 -302.302672)
		(end 183.059578 -302.016922)
		(width 0.20066)
		(layer "F.Cu")
		(net "M_F_CPU1_SA_DQS_DN<6>")
	)
	(segment
		(start 178.53152 -302.716692)
		(end 178.802792 -302.44542)
		(width 0.20066)
		(layer "F.Cu")
		(net "M_F_CPU1_SA_DQS_DN<6>")
	)
	(segment
		(start 183.059578 -302.016922)
		(end 183.549544 -302.016922)
		(width 0.20066)
		(layer "F.Cu")
		(net "M_F_CPU1_SA_DQS_DN<6>")
	)
	(segment
		(start 182.444136 -302.29175)
		(end 182.455058 -302.302672)
		(width 0.1016)
		(layer "F.Cu")
		(net "M_F_CPU1_SA_DQS_DN<6>")
	)
	(segment
		(start 180.110892 -302.297846)
		(end 180.423058 -302.297846)
		(width 0.20066)
		(layer "F.Cu")
		(net "M_F_CPU1_SA_DQS_DN<6>")
	)
	(segment
		(start 182.455058 -302.302672)
		(end 182.773828 -302.302672)
		(width 0.20066)
		(layer "F.Cu")
		(net "M_F_CPU1_SA_DQS_DN<6>")
	)
	(segment
		(start 132.425948 -270.167862)
		(end 132.425948 -270.19758)
		(width 0.20066)
		(layer "F.Cu")
		(net "M_F_CPU1_SA_DQS_DN<6>")
	)
	(segment
		(start 183.99506 -302.462438)
		(end 184.786778 -302.462438)
		(width 0.20066)
		(layer "F.Cu")
		(net "M_F_CPU1_SA_DQS_DN<6>")
	)
	(segment
		(start 155.843224 -293.606728)
		(end 155.45689 -293.220394)
		(width 0.18288)
		(layer "In4.Cu")
		(net "M_F_CPU1_SA_DQS_DN<6>")
	)
	(segment
		(start 157.268926 -294.535098)
		(end 156.774388 -294.302942)
		(width 0.18288)
		(layer "In4.Cu")
		(net "M_F_CPU1_SA_DQS_DN<6>")
	)
	(segment
		(start 142.248128 -273.733514)
		(end 140.286232 -271.771618)
		(width 0.18288)
		(layer "In4.Cu")
		(net "M_F_CPU1_SA_DQS_DN<6>")
	)
	(segment
		(start 143.044418 -273.733514)
		(end 142.248128 -273.733514)
		(width 0.18288)
		(layer "In4.Cu")
		(net "M_F_CPU1_SA_DQS_DN<6>")
	)
	(segment
		(start 139.6365 -271.03705)
		(end 139.429998 -271.03705)
		(width 0.088646)
		(layer "In4.Cu")
		(net "M_F_CPU1_SA_DQS_DN<6>")
	)
	(segment
		(start 156.019246 -293.606728)
		(end 155.843224 -293.606728)
		(width 0.18288)
		(layer "In4.Cu")
		(net "M_F_CPU1_SA_DQS_DN<6>")
	)
	(segment
		(start 135.060436 -269.871444)
		(end 135.05053 -269.877286)
		(width 0.088646)
		(layer "In4.Cu")
		(net "M_F_CPU1_SA_DQS_DN<6>")
	)
	(segment
		(start 134.122668 -269.870428)
		(end 134.11835 -269.873222)
		(width 0.088646)
		(layer "In4.Cu")
		(net "M_F_CPU1_SA_DQS_DN<6>")
	)
	(segment
		(start 143.23695 -273.926046)
		(end 143.044418 -273.733514)
		(width 0.18288)
		(layer "In4.Cu")
		(net "M_F_CPU1_SA_DQS_DN<6>")
	)
	(segment
		(start 160.649412 -296.344594)
		(end 160.14827 -296.081196)
		(width 0.18288)
		(layer "In4.Cu")
		(net "M_F_CPU1_SA_DQS_DN<6>")
	)
	(segment
		(start 165.973252 -300.297088)
		(end 165.973252 -300.121066)
		(width 0.18288)
		(layer "In4.Cu")
		(net "M_F_CPU1_SA_DQS_DN<6>")
	)
	(segment
		(start 159.157924 -295.49471)
		(end 158.985458 -295.53027)
		(width 0.18288)
		(layer "In4.Cu")
		(net "M_F_CPU1_SA_DQS_DN<6>")
	)
	(segment
		(start 155.45689 -293.220394)
		(end 155.45689 -293.044372)
		(width 0.18288)
		(layer "In4.Cu")
		(net "M_F_CPU1_SA_DQS_DN<6>")
	)
	(segment
		(start 138.776456 -270.724884)
		(end 138.776456 -270.725138)
		(width 0.088646)
		(layer "In4.Cu")
		(net "M_F_CPU1_SA_DQS_DN<6>")
	)
	(segment
		(start 168.515284 -302.295306)
		(end 167.656002 -301.436278)
		(width 0.18288)
		(layer "In4.Cu")
		(net "M_F_CPU1_SA_DQS_DN<6>")
	)
	(segment
		(start 173.46041 -302.02632)
		(end 173.27372 -302.02632)
		(width 0.18288)
		(layer "In4.Cu")
		(net "M_F_CPU1_SA_DQS_DN<6>")
	)
	(segment
		(start 162.879278 -298.17314)
		(end 162.492944 -297.786806)
		(width 0.18288)
		(layer "In4.Cu")
		(net "M_F_CPU1_SA_DQS_DN<6>")
	)
	(segment
		(start 156.405326 -293.992808)
		(end 156.019246 -293.606728)
		(width 0.18288)
		(layer "In4.Cu")
		(net "M_F_CPU1_SA_DQS_DN<6>")
	)
	(segment
		(start 161.353246 -296.714926)
		(end 161.185098 -296.766996)
		(width 0.18288)
		(layer "In4.Cu")
		(net "M_F_CPU1_SA_DQS_DN<6>")
	)
	(segment
		(start 173.27372 -302.02632)
		(end 173.009052 -302.290988)
		(width 0.18288)
		(layer "In4.Cu")
		(net "M_F_CPU1_SA_DQS_DN<6>")
	)
	(segment
		(start 166.535608 -300.683422)
		(end 166.359586 -300.683422)
		(width 0.18288)
		(layer "In4.Cu")
		(net "M_F_CPU1_SA_DQS_DN<6>")
	)
	(segment
		(start 154.508454 -292.271958)
		(end 154.508454 -292.095936)
		(width 0.18288)
		(layer "In4.Cu")
		(net "M_F_CPU1_SA_DQS_DN<6>")
	)
	(segment
		(start 153.373582 -290.961064)
		(end 148.49983 -279.18918)
		(width 0.18288)
		(layer "In4.Cu")
		(net "M_F_CPU1_SA_DQS_DN<6>")
	)
	(segment
		(start 161.867088 -296.984928)
		(end 161.353246 -296.714926)
		(width 0.18288)
		(layer "In4.Cu")
		(net "M_F_CPU1_SA_DQS_DN<6>")
	)
	(segment
		(start 156.774388 -294.302942)
		(end 156.714444 -294.137588)
		(width 0.18288)
		(layer "In4.Cu")
		(net "M_F_CPU1_SA_DQS_DN<6>")
	)
	(segment
		(start 133.178296 -269.873222)
		(end 133.106668 -269.914624)
		(width 0.088646)
		(layer "In4.Cu")
		(net "M_F_CPU1_SA_DQS_DN<6>")
	)
	(segment
		(start 176.896014 -302.716692)
		(end 176.600866 -302.421544)
		(width 0.18288)
		(layer "In4.Cu")
		(net "M_F_CPU1_SA_DQS_DN<6>")
	)
	(segment
		(start 135.432546 -269.873222)
		(end 135.432546 -269.872968)
		(width 0.088646)
		(layer "In4.Cu")
		(net "M_F_CPU1_SA_DQS_DN<6>")
	)
	(segment
		(start 154.508454 -292.095936)
		(end 153.373582 -290.961064)
		(width 0.18288)
		(layer "In4.Cu")
		(net "M_F_CPU1_SA_DQS_DN<6>")
	)
	(segment
		(start 162.492944 -297.786806)
		(end 162.492944 -297.610784)
		(width 0.18288)
		(layer "In4.Cu")
		(net "M_F_CPU1_SA_DQS_DN<6>")
	)
	(segment
		(start 166.359586 -300.683422)
		(end 165.973252 -300.297088)
		(width 0.18288)
		(layer "In4.Cu")
		(net "M_F_CPU1_SA_DQS_DN<6>")
	)
	(segment
		(start 136.387078 -269.881858)
		(end 136.372346 -269.873222)
		(width 0.088646)
		(layer "In4.Cu")
		(net "M_F_CPU1_SA_DQS_DN<6>")
	)
	(segment
		(start 156.714444 -294.137588)
		(end 156.405326 -293.992808)
		(width 0.18288)
		(layer "In4.Cu")
		(net "M_F_CPU1_SA_DQS_DN<6>")
	)
	(segment
		(start 132.822442 -269.99057)
		(end 132.50037 -269.99057)
		(width 0.088646)
		(layer "In4.Cu")
		(net "M_F_CPU1_SA_DQS_DN<6>")
	)
	(segment
		(start 174.854616 -302.603916)
		(end 173.46041 -302.02632)
		(width 0.18288)
		(layer "In4.Cu")
		(net "M_F_CPU1_SA_DQS_DN<6>")
	)
	(segment
		(start 172.61586 -302.290988)
		(end 172.321728 -301.996856)
		(width 0.18288)
		(layer "In4.Cu")
		(net "M_F_CPU1_SA_DQS_DN<6>")
	)
	(segment
		(start 158.52902 -295.230042)
		(end 158.49346 -295.057576)
		(width 0.18288)
		(layer "In4.Cu")
		(net "M_F_CPU1_SA_DQS_DN<6>")
	)
	(segment
		(start 171.906692 -302.295306)
		(end 168.515284 -302.295306)
		(width 0.18288)
		(layer "In4.Cu")
		(net "M_F_CPU1_SA_DQS_DN<6>")
	)
	(segment
		(start 158.037276 -294.757602)
		(end 157.434534 -294.475154)
		(width 0.18288)
		(layer "In4.Cu")
		(net "M_F_CPU1_SA_DQS_DN<6>")
	)
	(segment
		(start 165.973252 -300.121066)
		(end 165.168326 -299.31614)
		(width 0.18288)
		(layer "In4.Cu")
		(net "M_F_CPU1_SA_DQS_DN<6>")
	)
	(segment
		(start 138.439398 -270.213074)
		(end 138.439398 -270.19758)
		(width 0.088646)
		(layer "In4.Cu")
		(net "M_F_CPU1_SA_DQS_DN<6>")
	)
	(segment
		(start 140.286232 -271.771618)
		(end 140.269722 -271.755108)
		(width 0.088646)
		(layer "In4.Cu")
		(net "M_F_CPU1_SA_DQS_DN<6>")
	)
	(segment
		(start 154.894788 -292.658292)
		(end 154.508454 -292.271958)
		(width 0.18288)
		(layer "In4.Cu")
		(net "M_F_CPU1_SA_DQS_DN<6>")
	)
	(segment
		(start 172.205142 -301.996856)
		(end 171.906692 -302.295306)
		(width 0.18288)
		(layer "In4.Cu")
		(net "M_F_CPU1_SA_DQS_DN<6>")
	)
	(segment
		(start 133.563106 -269.879318)
		(end 133.552692 -269.873222)
		(width 0.088646)
		(layer "In4.Cu")
		(net "M_F_CPU1_SA_DQS_DN<6>")
	)
	(segment
		(start 138.881866 -270.828516)
		(end 138.79957 -270.745966)
		(width 0.088646)
		(layer "In4.Cu")
		(net "M_F_CPU1_SA_DQS_DN<6>")
	)
	(segment
		(start 140.269722 -271.670272)
		(end 139.6365 -271.03705)
		(width 0.088646)
		(layer "In4.Cu")
		(net "M_F_CPU1_SA_DQS_DN<6>")
	)
	(segment
		(start 163.511992 -298.629832)
		(end 163.0553 -298.17314)
		(width 0.18288)
		(layer "In4.Cu")
		(net "M_F_CPU1_SA_DQS_DN<6>")
	)
	(segment
		(start 135.06323 -269.869666)
		(end 135.060436 -269.871444)
		(width 0.088646)
		(layer "In4.Cu")
		(net "M_F_CPU1_SA_DQS_DN<6>")
	)
	(segment
		(start 162.492944 -297.610784)
		(end 161.867088 -296.984928)
		(width 0.18288)
		(layer "In4.Cu")
		(net "M_F_CPU1_SA_DQS_DN<6>")
	)
	(segment
		(start 163.0553 -298.17314)
		(end 162.879278 -298.17314)
		(width 0.18288)
		(layer "In4.Cu")
		(net "M_F_CPU1_SA_DQS_DN<6>")
	)
	(segment
		(start 176.2252 -302.421544)
		(end 175.784002 -302.603916)
		(width 0.18288)
		(layer "In4.Cu")
		(net "M_F_CPU1_SA_DQS_DN<6>")
	)
	(segment
		(start 165.168326 -299.31614)
		(end 163.511992 -298.629832)
		(width 0.18288)
		(layer "In4.Cu")
		(net "M_F_CPU1_SA_DQS_DN<6>")
	)
	(segment
		(start 140.269722 -271.755108)
		(end 140.269722 -271.670272)
		(width 0.088646)
		(layer "In4.Cu")
		(net "M_F_CPU1_SA_DQS_DN<6>")
	)
	(segment
		(start 137.326878 -269.881858)
		(end 137.312146 -269.873222)
		(width 0.088646)
		(layer "In4.Cu")
		(net "M_F_CPU1_SA_DQS_DN<6>")
	)
	(segment
		(start 155.07081 -292.658292)
		(end 154.894788 -292.658292)
		(width 0.18288)
		(layer "In4.Cu")
		(net "M_F_CPU1_SA_DQS_DN<6>")
	)
	(segment
		(start 167.656002 -301.436278)
		(end 167.028114 -301.175928)
		(width 0.18288)
		(layer "In4.Cu")
		(net "M_F_CPU1_SA_DQS_DN<6>")
	)
	(segment
		(start 172.321728 -301.996856)
		(end 172.205142 -301.996856)
		(width 0.18288)
		(layer "In4.Cu")
		(net "M_F_CPU1_SA_DQS_DN<6>")
	)
	(segment
		(start 157.434534 -294.475154)
		(end 157.268926 -294.535098)
		(width 0.18288)
		(layer "In4.Cu")
		(net "M_F_CPU1_SA_DQS_DN<6>")
	)
	(segment
		(start 167.028114 -301.175928)
		(end 166.535608 -300.683422)
		(width 0.18288)
		(layer "In4.Cu")
		(net "M_F_CPU1_SA_DQS_DN<6>")
	)
	(segment
		(start 161.185098 -296.766996)
		(end 160.701482 -296.512742)
		(width 0.18288)
		(layer "In4.Cu")
		(net "M_F_CPU1_SA_DQS_DN<6>")
	)
	(segment
		(start 160.701482 -296.512742)
		(end 160.649412 -296.344594)
		(width 0.18288)
		(layer "In4.Cu")
		(net "M_F_CPU1_SA_DQS_DN<6>")
	)
	(segment
		(start 160.14827 -296.081196)
		(end 159.157924 -295.49471)
		(width 0.18288)
		(layer "In4.Cu")
		(net "M_F_CPU1_SA_DQS_DN<6>")
	)
	(segment
		(start 158.985458 -295.53027)
		(end 158.52902 -295.230042)
		(width 0.18288)
		(layer "In4.Cu")
		(net "M_F_CPU1_SA_DQS_DN<6>")
	)
	(segment
		(start 173.009052 -302.290988)
		(end 172.61586 -302.290988)
		(width 0.18288)
		(layer "In4.Cu")
		(net "M_F_CPU1_SA_DQS_DN<6>")
	)
	(segment
		(start 148.49983 -279.18918)
		(end 143.23695 -273.926046)
		(width 0.18288)
		(layer "In4.Cu")
		(net "M_F_CPU1_SA_DQS_DN<6>")
	)
	(segment
		(start 135.447278 -269.881858)
		(end 135.432546 -269.873222)
		(width 0.088646)
		(layer "In4.Cu")
		(net "M_F_CPU1_SA_DQS_DN<6>")
	)
	(segment
		(start 139.319508 -271.00022)
		(end 138.881866 -270.828516)
		(width 0.088646)
		(layer "In4.Cu")
		(net "M_F_CPU1_SA_DQS_DN<6>")
	)
	(segment
		(start 132.437886 -270.048228)
		(end 132.425948 -270.19758)
		(width 0.088646)
		(layer "In4.Cu")
		(net "M_F_CPU1_SA_DQS_DN<6>")
	)
	(segment
		(start 176.600866 -302.421544)
		(end 176.2252 -302.421544)
		(width 0.18288)
		(layer "In4.Cu")
		(net "M_F_CPU1_SA_DQS_DN<6>")
	)
	(segment
		(start 155.45689 -293.044372)
		(end 155.07081 -292.658292)
		(width 0.18288)
		(layer "In4.Cu")
		(net "M_F_CPU1_SA_DQS_DN<6>")
	)
	(segment
		(start 175.784002 -302.603916)
		(end 174.854616 -302.603916)
		(width 0.18288)
		(layer "In4.Cu")
		(net "M_F_CPU1_SA_DQS_DN<6>")
	)
	(segment
		(start 139.429998 -271.03705)
		(end 139.319508 -271.00022)
		(width 0.088646)
		(layer "In4.Cu")
		(net "M_F_CPU1_SA_DQS_DN<6>")
	)
	(segment
		(start 158.49346 -295.057576)
		(end 158.037276 -294.757602)
		(width 0.18288)
		(layer "In4.Cu")
		(net "M_F_CPU1_SA_DQS_DN<6>")
	)
	(arc
		(start 135.99795 -269.873222)
		(mid 135.723721 -269.949147)
		(end 135.447278 -269.881858)
		(width 0.088646)
		(layer "In4.Cu")
		(net "M_F_CPU1_SA_DQS_DN<6>")
	)
	(arc
		(start 136.93775 -269.873222)
		(mid 136.663521 -269.949147)
		(end 136.387078 -269.881858)
		(width 0.088646)
		(layer "In4.Cu")
		(net "M_F_CPU1_SA_DQS_DN<6>")
	)
	(arc
		(start 137.87755 -269.873222)
		(mid 137.603321 -269.949147)
		(end 137.326878 -269.881858)
		(width 0.088646)
		(layer "In4.Cu")
		(net "M_F_CPU1_SA_DQS_DN<6>")
	)
	(arc
		(start 133.106668 -269.914624)
		(mid 132.969548 -269.97128)
		(end 132.822442 -269.99057)
		(width 0.088646)
		(layer "In4.Cu")
		(net "M_F_CPU1_SA_DQS_DN<6>")
	)
	(arc
		(start 134.492746 -269.872968)
		(mid 134.308052 -269.822867)
		(end 134.122668 -269.870428)
		(width 0.088646)
		(layer "In4.Cu")
		(net "M_F_CPU1_SA_DQS_DN<6>")
	)
	(arc
		(start 133.552692 -269.873222)
		(mid 133.365494 -269.823079)
		(end 133.178296 -269.873222)
		(width 0.088646)
		(layer "In4.Cu")
		(net "M_F_CPU1_SA_DQS_DN<6>")
	)
	(arc
		(start 132.50037 -269.99057)
		(mid 132.457843 -270.007183)
		(end 132.437886 -270.048228)
		(width 0.088646)
		(layer "In4.Cu")
		(net "M_F_CPU1_SA_DQS_DN<6>")
	)
	(arc
		(start 138.439398 -270.19758)
		(mid 138.252099 -269.873139)
		(end 137.87755 -269.873222)
		(width 0.088646)
		(layer "In4.Cu")
		(net "M_F_CPU1_SA_DQS_DN<6>")
	)
	(arc
		(start 134.11835 -269.873222)
		(mid 133.841537 -269.949058)
		(end 133.563106 -269.879318)
		(width 0.088646)
		(layer "In4.Cu")
		(net "M_F_CPU1_SA_DQS_DN<6>")
	)
	(arc
		(start 138.776456 -270.725138)
		(mid 138.749873 -270.704866)
		(end 138.721592 -270.687038)
		(width 0.088646)
		(layer "In4.Cu")
		(net "M_F_CPU1_SA_DQS_DN<6>")
	)
	(arc
		(start 135.05053 -269.877286)
		(mid 134.771069 -269.948723)
		(end 134.492746 -269.872968)
		(width 0.088646)
		(layer "In4.Cu")
		(net "M_F_CPU1_SA_DQS_DN<6>")
	)
	(arc
		(start 138.79957 -270.745966)
		(mid 138.788232 -270.735185)
		(end 138.776456 -270.724884)
		(width 0.088646)
		(layer "In4.Cu")
		(net "M_F_CPU1_SA_DQS_DN<6>")
	)
	(arc
		(start 138.721592 -270.687038)
		(mid 138.518769 -270.486807)
		(end 138.439398 -270.213074)
		(width 0.088646)
		(layer "In4.Cu")
		(net "M_F_CPU1_SA_DQS_DN<6>")
	)
	(arc
		(start 137.312146 -269.873222)
		(mid 137.124948 -269.823079)
		(end 136.93775 -269.873222)
		(width 0.088646)
		(layer "In4.Cu")
		(net "M_F_CPU1_SA_DQS_DN<6>")
	)
	(arc
		(start 135.432546 -269.872968)
		(mid 135.248338 -269.822746)
		(end 135.06323 -269.869666)
		(width 0.088646)
		(layer "In4.Cu")
		(net "M_F_CPU1_SA_DQS_DN<6>")
	)
	(arc
		(start 136.372346 -269.873222)
		(mid 136.185148 -269.823079)
		(end 135.99795 -269.873222)
		(width 0.088646)
		(layer "In4.Cu")
		(net "M_F_CPU1_SA_DQS_DN<6>")
	)
	(segment
		(start 179.286154 -311.795414)
		(end 179.711096 -311.370472)
		(width 0.20066)
		(layer "F.Cu")
		(net "M_F_CPU1_SA_DQS_DN<5>")
	)
	(segment
		(start 178.802792 -311.795414)
		(end 179.286154 -311.795414)
		(width 0.20066)
		(layer "F.Cu")
		(net "M_F_CPU1_SA_DQS_DN<5>")
	)
	(segment
		(start 179.711096 -311.370472)
		(end 179.833524 -311.370472)
		(width 0.20066)
		(layer "F.Cu")
		(net "M_F_CPU1_SA_DQS_DN<5>")
	)
	(segment
		(start 180.423058 -311.64784)
		(end 180.427884 -311.64784)
		(width 0.101854)
		(layer "F.Cu")
		(net "M_F_CPU1_SA_DQS_DN<5>")
	)
	(segment
		(start 184.786778 -311.812432)
		(end 185.041032 -312.066686)
		(width 0.20066)
		(layer "F.Cu")
		(net "M_F_CPU1_SA_DQS_DN<5>")
	)
	(segment
		(start 179.833524 -311.370472)
		(end 180.110892 -311.64784)
		(width 0.20066)
		(layer "F.Cu")
		(net "M_F_CPU1_SA_DQS_DN<5>")
	)
	(segment
		(start 182.773828 -311.652666)
		(end 183.059578 -311.366916)
		(width 0.20066)
		(layer "F.Cu")
		(net "M_F_CPU1_SA_DQS_DN<5>")
	)
	(segment
		(start 176.896014 -312.066686)
		(end 178.000914 -312.066686)
		(width 0.20066)
		(layer "F.Cu")
		(net "M_F_CPU1_SA_DQS_DN<5>")
	)
	(segment
		(start 178.53152 -312.066686)
		(end 178.802792 -311.795414)
		(width 0.20066)
		(layer "F.Cu")
		(net "M_F_CPU1_SA_DQS_DN<5>")
	)
	(segment
		(start 185.041032 -312.066686)
		(end 185.544714 -312.066686)
		(width 0.20066)
		(layer "F.Cu")
		(net "M_F_CPU1_SA_DQS_DN<5>")
	)
	(segment
		(start 183.99506 -311.812432)
		(end 184.786778 -311.812432)
		(width 0.20066)
		(layer "F.Cu")
		(net "M_F_CPU1_SA_DQS_DN<5>")
	)
	(segment
		(start 180.43398 -311.641744)
		(end 182.444136 -311.641744)
		(width 0.1016)
		(layer "F.Cu")
		(net "M_F_CPU1_SA_DQS_DN<5>")
	)
	(segment
		(start 135.714994 -277.522178)
		(end 135.71474 -277.522432)
		(width 0.20066)
		(layer "F.Cu")
		(net "M_F_CPU1_SA_DQS_DN<5>")
	)
	(segment
		(start 183.059578 -311.366916)
		(end 183.549544 -311.366916)
		(width 0.20066)
		(layer "F.Cu")
		(net "M_F_CPU1_SA_DQS_DN<5>")
	)
	(segment
		(start 180.110892 -311.64784)
		(end 180.423058 -311.64784)
		(width 0.20066)
		(layer "F.Cu")
		(net "M_F_CPU1_SA_DQS_DN<5>")
	)
	(segment
		(start 183.549544 -311.366916)
		(end 183.99506 -311.812432)
		(width 0.20066)
		(layer "F.Cu")
		(net "M_F_CPU1_SA_DQS_DN<5>")
	)
	(segment
		(start 182.455058 -311.652666)
		(end 182.773828 -311.652666)
		(width 0.20066)
		(layer "F.Cu")
		(net "M_F_CPU1_SA_DQS_DN<5>")
	)
	(segment
		(start 135.714994 -276.986492)
		(end 135.714994 -277.522178)
		(width 0.20066)
		(layer "F.Cu")
		(net "M_F_CPU1_SA_DQS_DN<5>")
	)
	(segment
		(start 180.427884 -311.64784)
		(end 180.43398 -311.641744)
		(width 0.1016)
		(layer "F.Cu")
		(net "M_F_CPU1_SA_DQS_DN<5>")
	)
	(segment
		(start 182.444136 -311.641744)
		(end 182.455058 -311.652666)
		(width 0.1016)
		(layer "F.Cu")
		(net "M_F_CPU1_SA_DQS_DN<5>")
	)
	(segment
		(start 178.000914 -312.066686)
		(end 178.53152 -312.066686)
		(width 0.20066)
		(layer "F.Cu")
		(net "M_F_CPU1_SA_DQS_DN<5>")
	)
	(segment
		(start 168.117266 -311.379362)
		(end 167.841422 -311.655206)
		(width 0.18288)
		(layer "In2.Cu")
		(net "M_F_CPU1_SA_DQS_DN<5>")
	)
	(segment
		(start 156.279088 -311.333896)
		(end 155.89123 -310.946038)
		(width 0.18288)
		(layer "In2.Cu")
		(net "M_F_CPU1_SA_DQS_DN<5>")
	)
	(segment
		(start 157.204664 -311.333896)
		(end 156.279088 -311.333896)
		(width 0.18288)
		(layer "In2.Cu")
		(net "M_F_CPU1_SA_DQS_DN<5>")
	)
	(segment
		(start 165.573202 -311.343548)
		(end 165.261544 -311.655206)
		(width 0.18288)
		(layer "In2.Cu")
		(net "M_F_CPU1_SA_DQS_DN<5>")
	)
	(segment
		(start 163.650168 -310.813704)
		(end 163.621974 -310.78551)
		(width 0.16002)
		(layer "In2.Cu")
		(net "M_F_CPU1_SA_DQS_DN<5>")
	)
	(segment
		(start 144.588484 -291.790882)
		(end 143.726154 -289.70859)
		(width 0.18288)
		(layer "In2.Cu")
		(net "M_F_CPU1_SA_DQS_DN<5>")
	)
	(segment
		(start 174.84598 -311.881266)
		(end 174.646336 -311.681622)
		(width 0.16002)
		(layer "In2.Cu")
		(net "M_F_CPU1_SA_DQS_DN<5>")
	)
	(segment
		(start 148.645626 -301.256954)
		(end 148.770086 -301.132494)
		(width 0.18288)
		(layer "In2.Cu")
		(net "M_F_CPU1_SA_DQS_DN<5>")
	)
	(segment
		(start 154.375104 -309.429912)
		(end 153.987246 -309.042054)
		(width 0.18288)
		(layer "In2.Cu")
		(net "M_F_CPU1_SA_DQS_DN<5>")
	)
	(segment
		(start 148.645626 -300.459394)
		(end 148.645626 -299.910754)
		(width 0.18288)
		(layer "In2.Cu")
		(net "M_F_CPU1_SA_DQS_DN<5>")
	)
	(segment
		(start 148.770086 -298.226734)
		(end 147.353782 -294.55618)
		(width 0.18288)
		(layer "In2.Cu")
		(net "M_F_CPU1_SA_DQS_DN<5>")
	)
	(segment
		(start 148.770086 -303.276254)
		(end 148.645626 -303.151794)
		(width 0.18288)
		(layer "In2.Cu")
		(net "M_F_CPU1_SA_DQS_DN<5>")
	)
	(segment
		(start 174.874174 -311.925716)
		(end 174.84598 -311.897522)
		(width 0.16002)
		(layer "In2.Cu")
		(net "M_F_CPU1_SA_DQS_DN<5>")
	)
	(segment
		(start 163.850574 -310.998362)
		(end 163.665916 -310.813704)
		(width 0.16002)
		(layer "In2.Cu")
		(net "M_F_CPU1_SA_DQS_DN<5>")
	)
	(segment
		(start 175.067468 -312.11901)
		(end 174.874174 -311.925716)
		(width 0.18288)
		(layer "In2.Cu")
		(net "M_F_CPU1_SA_DQS_DN<5>")
	)
	(segment
		(start 164.907214 -311.655206)
		(end 164.610034 -311.358026)
		(width 0.18288)
		(layer "In2.Cu")
		(net "M_F_CPU1_SA_DQS_DN<5>")
	)
	(segment
		(start 136.25449 -277.927308)
		(end 135.950198 -277.546308)
		(width 0.088646)
		(layer "In2.Cu")
		(net "M_F_CPU1_SA_DQS_DN<5>")
	)
	(segment
		(start 169.467022 -311.02808)
		(end 168.618916 -311.379362)
		(width 0.18288)
		(layer "In2.Cu")
		(net "M_F_CPU1_SA_DQS_DN<5>")
	)
	(segment
		(start 172.677074 -311.641998)
		(end 172.536358 -311.641998)
		(width 0.18288)
		(layer "In2.Cu")
		(net "M_F_CPU1_SA_DQS_DN<5>")
	)
	(segment
		(start 152.083262 -307.13807)
		(end 151.90724 -307.13807)
		(width 0.18288)
		(layer "In2.Cu")
		(net "M_F_CPU1_SA_DQS_DN<5>")
	)
	(segment
		(start 148.770086 -299.786294)
		(end 148.770086 -298.226734)
		(width 0.18288)
		(layer "In2.Cu")
		(net "M_F_CPU1_SA_DQS_DN<5>")
	)
	(segment
		(start 151.90724 -307.13807)
		(end 151.519128 -306.749958)
		(width 0.18288)
		(layer "In2.Cu")
		(net "M_F_CPU1_SA_DQS_DN<5>")
	)
	(segment
		(start 135.950198 -277.546308)
		(end 135.926322 -277.522432)
		(width 0.088646)
		(layer "In2.Cu")
		(net "M_F_CPU1_SA_DQS_DN<5>")
	)
	(segment
		(start 163.621974 -310.78551)
		(end 163.555934 -310.71947)
		(width 0.18288)
		(layer "In2.Cu")
		(net "M_F_CPU1_SA_DQS_DN<5>")
	)
	(segment
		(start 164.19449 -311.358026)
		(end 163.878768 -311.042304)
		(width 0.18288)
		(layer "In2.Cu")
		(net "M_F_CPU1_SA_DQS_DN<5>")
	)
	(segment
		(start 175.659288 -312.11901)
		(end 175.067468 -312.11901)
		(width 0.18288)
		(layer "In2.Cu")
		(net "M_F_CPU1_SA_DQS_DN<5>")
	)
	(segment
		(start 162.25139 -310.71947)
		(end 161.880804 -311.090056)
		(width 0.18288)
		(layer "In2.Cu")
		(net "M_F_CPU1_SA_DQS_DN<5>")
	)
	(segment
		(start 149.615144 -304.845974)
		(end 149.615144 -304.669952)
		(width 0.18288)
		(layer "In2.Cu")
		(net "M_F_CPU1_SA_DQS_DN<5>")
	)
	(segment
		(start 152.47112 -307.525928)
		(end 152.083262 -307.13807)
		(width 0.18288)
		(layer "In2.Cu")
		(net "M_F_CPU1_SA_DQS_DN<5>")
	)
	(segment
		(start 155.327096 -310.381904)
		(end 154.939238 -309.994046)
		(width 0.18288)
		(layer "In2.Cu")
		(net "M_F_CPU1_SA_DQS_DN<5>")
	)
	(segment
		(start 155.715208 -310.946038)
		(end 155.327096 -310.557926)
		(width 0.18288)
		(layer "In2.Cu")
		(net "M_F_CPU1_SA_DQS_DN<5>")
	)
	(segment
		(start 153.987246 -309.042054)
		(end 153.811224 -309.042054)
		(width 0.18288)
		(layer "In2.Cu")
		(net "M_F_CPU1_SA_DQS_DN<5>")
	)
	(segment
		(start 167.841422 -311.655206)
		(end 167.487092 -311.655206)
		(width 0.18288)
		(layer "In2.Cu")
		(net "M_F_CPU1_SA_DQS_DN<5>")
	)
	(segment
		(start 151.13127 -306.186078)
		(end 150.955248 -306.186078)
		(width 0.18288)
		(layer "In2.Cu")
		(net "M_F_CPU1_SA_DQS_DN<5>")
	)
	(segment
		(start 173.020482 -311.64022)
		(end 173.020482 -311.641998)
		(width 0.18288)
		(layer "In2.Cu")
		(net "M_F_CPU1_SA_DQS_DN<5>")
	)
	(segment
		(start 150.567136 -305.797966)
		(end 150.567136 -305.621944)
		(width 0.18288)
		(layer "In2.Cu")
		(net "M_F_CPU1_SA_DQS_DN<5>")
	)
	(segment
		(start 155.89123 -310.946038)
		(end 155.715208 -310.946038)
		(width 0.18288)
		(layer "In2.Cu")
		(net "M_F_CPU1_SA_DQS_DN<5>")
	)
	(segment
		(start 172.895768 -311.641998)
		(end 172.677074 -311.641998)
		(width 0.16002)
		(layer "In2.Cu")
		(net "M_F_CPU1_SA_DQS_DN<5>")
	)
	(segment
		(start 165.261544 -311.655206)
		(end 164.907214 -311.655206)
		(width 0.18288)
		(layer "In2.Cu")
		(net "M_F_CPU1_SA_DQS_DN<5>")
	)
	(segment
		(start 172.536358 -311.641998)
		(end 172.271944 -311.377584)
		(width 0.18288)
		(layer "In2.Cu")
		(net "M_F_CPU1_SA_DQS_DN<5>")
	)
	(segment
		(start 153.035254 -308.090062)
		(end 152.859232 -308.090062)
		(width 0.18288)
		(layer "In2.Cu")
		(net "M_F_CPU1_SA_DQS_DN<5>")
	)
	(segment
		(start 171.183046 -310.791098)
		(end 169.704004 -310.791098)
		(width 0.18288)
		(layer "In2.Cu")
		(net "M_F_CPU1_SA_DQS_DN<5>")
	)
	(segment
		(start 160.484312 -311.349644)
		(end 160.166558 -311.667398)
		(width 0.18288)
		(layer "In2.Cu")
		(net "M_F_CPU1_SA_DQS_DN<5>")
	)
	(segment
		(start 151.519128 -306.573936)
		(end 151.13127 -306.186078)
		(width 0.18288)
		(layer "In2.Cu")
		(net "M_F_CPU1_SA_DQS_DN<5>")
	)
	(segment
		(start 174.84598 -311.897522)
		(end 174.84598 -311.881266)
		(width 0.16002)
		(layer "In2.Cu")
		(net "M_F_CPU1_SA_DQS_DN<5>")
	)
	(segment
		(start 151.519128 -306.749958)
		(end 151.519128 -306.573936)
		(width 0.18288)
		(layer "In2.Cu")
		(net "M_F_CPU1_SA_DQS_DN<5>")
	)
	(segment
		(start 171.769532 -311.377584)
		(end 171.183046 -310.791098)
		(width 0.18288)
		(layer "In2.Cu")
		(net "M_F_CPU1_SA_DQS_DN<5>")
	)
	(segment
		(start 148.770086 -301.132494)
		(end 148.770086 -300.583854)
		(width 0.18288)
		(layer "In2.Cu")
		(net "M_F_CPU1_SA_DQS_DN<5>")
	)
	(segment
		(start 161.253932 -311.349644)
		(end 160.484312 -311.349644)
		(width 0.18288)
		(layer "In2.Cu")
		(net "M_F_CPU1_SA_DQS_DN<5>")
	)
	(segment
		(start 159.734504 -311.667398)
		(end 159.431228 -311.364122)
		(width 0.18288)
		(layer "In2.Cu")
		(net "M_F_CPU1_SA_DQS_DN<5>")
	)
	(segment
		(start 148.770086 -301.930054)
		(end 148.645626 -301.805594)
		(width 0.18288)
		(layer "In2.Cu")
		(net "M_F_CPU1_SA_DQS_DN<5>")
	)
	(segment
		(start 143.726154 -283.896562)
		(end 142.325598 -282.49626)
		(width 0.18288)
		(layer "In2.Cu")
		(net "M_F_CPU1_SA_DQS_DN<5>")
	)
	(segment
		(start 167.175434 -311.343548)
		(end 165.573202 -311.343548)
		(width 0.18288)
		(layer "In2.Cu")
		(net "M_F_CPU1_SA_DQS_DN<5>")
	)
	(segment
		(start 153.423112 -308.653942)
		(end 153.423112 -308.47792)
		(width 0.18288)
		(layer "In2.Cu")
		(net "M_F_CPU1_SA_DQS_DN<5>")
	)
	(segment
		(start 155.327096 -310.557926)
		(end 155.327096 -310.381904)
		(width 0.18288)
		(layer "In2.Cu")
		(net "M_F_CPU1_SA_DQS_DN<5>")
	)
	(segment
		(start 148.645626 -303.151794)
		(end 148.645626 -302.603154)
		(width 0.18288)
		(layer "In2.Cu")
		(net "M_F_CPU1_SA_DQS_DN<5>")
	)
	(segment
		(start 143.726154 -289.70859)
		(end 143.726154 -283.896562)
		(width 0.18288)
		(layer "In2.Cu")
		(net "M_F_CPU1_SA_DQS_DN<5>")
	)
	(segment
		(start 174.601886 -311.653428)
		(end 174.330868 -311.38241)
		(width 0.18288)
		(layer "In2.Cu")
		(net "M_F_CPU1_SA_DQS_DN<5>")
	)
	(segment
		(start 176.896014 -312.066686)
		(end 176.646078 -311.81675)
		(width 0.18288)
		(layer "In2.Cu")
		(net "M_F_CPU1_SA_DQS_DN<5>")
	)
	(segment
		(start 139.958318 -278.320754)
		(end 139.598908 -277.961344)
		(width 0.088646)
		(layer "In2.Cu")
		(net "M_F_CPU1_SA_DQS_DN<5>")
	)
	(segment
		(start 150.179278 -305.234086)
		(end 150.003256 -305.234086)
		(width 0.18288)
		(layer "In2.Cu")
		(net "M_F_CPU1_SA_DQS_DN<5>")
	)
	(segment
		(start 154.763216 -309.994046)
		(end 154.375104 -309.605934)
		(width 0.18288)
		(layer "In2.Cu")
		(net "M_F_CPU1_SA_DQS_DN<5>")
	)
	(segment
		(start 158.17977 -311.364122)
		(end 157.899354 -311.644538)
		(width 0.18288)
		(layer "In2.Cu")
		(net "M_F_CPU1_SA_DQS_DN<5>")
	)
	(segment
		(start 148.645626 -301.805594)
		(end 148.645626 -301.256954)
		(width 0.18288)
		(layer "In2.Cu")
		(net "M_F_CPU1_SA_DQS_DN<5>")
	)
	(segment
		(start 149.615144 -304.669952)
		(end 148.770086 -303.824894)
		(width 0.18288)
		(layer "In2.Cu")
		(net "M_F_CPU1_SA_DQS_DN<5>")
	)
	(segment
		(start 163.555934 -310.71947)
		(end 162.25139 -310.71947)
		(width 0.18288)
		(layer "In2.Cu")
		(net "M_F_CPU1_SA_DQS_DN<5>")
	)
	(segment
		(start 157.899354 -311.644538)
		(end 157.515306 -311.644538)
		(width 0.18288)
		(layer "In2.Cu")
		(net "M_F_CPU1_SA_DQS_DN<5>")
	)
	(segment
		(start 136.372092 -278.012144)
		(end 136.279636 -277.958804)
		(width 0.088646)
		(layer "In2.Cu")
		(net "M_F_CPU1_SA_DQS_DN<5>")
	)
	(segment
		(start 139.958318 -278.40559)
		(end 139.958318 -278.320754)
		(width 0.088646)
		(layer "In2.Cu")
		(net "M_F_CPU1_SA_DQS_DN<5>")
	)
	(segment
		(start 173.278292 -311.38241)
		(end 173.020482 -311.64022)
		(width 0.18288)
		(layer "In2.Cu")
		(net "M_F_CPU1_SA_DQS_DN<5>")
	)
	(segment
		(start 174.646336 -311.681622)
		(end 174.63008 -311.681622)
		(width 0.16002)
		(layer "In2.Cu")
		(net "M_F_CPU1_SA_DQS_DN<5>")
	)
	(segment
		(start 173.020482 -311.641998)
		(end 172.895768 -311.641998)
		(width 0.18288)
		(layer "In2.Cu")
		(net "M_F_CPU1_SA_DQS_DN<5>")
	)
	(segment
		(start 150.003256 -305.234086)
		(end 149.615144 -304.845974)
		(width 0.18288)
		(layer "In2.Cu")
		(net "M_F_CPU1_SA_DQS_DN<5>")
	)
	(segment
		(start 169.704004 -310.791098)
		(end 169.467022 -311.02808)
		(width 0.18288)
		(layer "In2.Cu")
		(net "M_F_CPU1_SA_DQS_DN<5>")
	)
	(segment
		(start 150.955248 -306.186078)
		(end 150.567136 -305.797966)
		(width 0.18288)
		(layer "In2.Cu")
		(net "M_F_CPU1_SA_DQS_DN<5>")
	)
	(segment
		(start 141.106144 -279.55367)
		(end 139.958318 -278.40559)
		(width 0.18288)
		(layer "In2.Cu")
		(net "M_F_CPU1_SA_DQS_DN<5>")
	)
	(segment
		(start 148.770086 -300.583854)
		(end 148.645626 -300.459394)
		(width 0.18288)
		(layer "In2.Cu")
		(net "M_F_CPU1_SA_DQS_DN<5>")
	)
	(segment
		(start 167.487092 -311.655206)
		(end 167.175434 -311.343548)
		(width 0.18288)
		(layer "In2.Cu")
		(net "M_F_CPU1_SA_DQS_DN<5>")
	)
	(segment
		(start 163.878768 -311.042304)
		(end 163.850574 -311.01411)
		(width 0.16002)
		(layer "In2.Cu")
		(net "M_F_CPU1_SA_DQS_DN<5>")
	)
	(segment
		(start 160.166558 -311.667398)
		(end 159.734504 -311.667398)
		(width 0.18288)
		(layer "In2.Cu")
		(net "M_F_CPU1_SA_DQS_DN<5>")
	)
	(segment
		(start 136.279636 -277.958804)
		(end 136.25449 -277.927308)
		(width 0.088646)
		(layer "In2.Cu")
		(net "M_F_CPU1_SA_DQS_DN<5>")
	)
	(segment
		(start 139.598908 -277.961344)
		(end 139.004294 -277.961344)
		(width 0.088646)
		(layer "In2.Cu")
		(net "M_F_CPU1_SA_DQS_DN<5>")
	)
	(segment
		(start 163.665916 -310.813704)
		(end 163.650168 -310.813704)
		(width 0.16002)
		(layer "In2.Cu")
		(net "M_F_CPU1_SA_DQS_DN<5>")
	)
	(segment
		(start 152.859232 -308.090062)
		(end 152.47112 -307.70195)
		(width 0.18288)
		(layer "In2.Cu")
		(net "M_F_CPU1_SA_DQS_DN<5>")
	)
	(segment
		(start 152.47112 -307.70195)
		(end 152.47112 -307.525928)
		(width 0.18288)
		(layer "In2.Cu")
		(net "M_F_CPU1_SA_DQS_DN<5>")
	)
	(segment
		(start 142.325598 -282.49626)
		(end 141.106144 -279.55367)
		(width 0.18288)
		(layer "In2.Cu")
		(net "M_F_CPU1_SA_DQS_DN<5>")
	)
	(segment
		(start 135.926322 -277.522432)
		(end 135.71474 -277.522432)
		(width 0.088646)
		(layer "In2.Cu")
		(net "M_F_CPU1_SA_DQS_DN<5>")
	)
	(segment
		(start 174.330868 -311.38241)
		(end 173.278292 -311.38241)
		(width 0.18288)
		(layer "In2.Cu")
		(net "M_F_CPU1_SA_DQS_DN<5>")
	)
	(segment
		(start 164.610034 -311.358026)
		(end 164.19449 -311.358026)
		(width 0.18288)
		(layer "In2.Cu")
		(net "M_F_CPU1_SA_DQS_DN<5>")
	)
	(segment
		(start 163.850574 -311.01411)
		(end 163.850574 -310.998362)
		(width 0.16002)
		(layer "In2.Cu")
		(net "M_F_CPU1_SA_DQS_DN<5>")
	)
	(segment
		(start 153.811224 -309.042054)
		(end 153.423112 -308.653942)
		(width 0.18288)
		(layer "In2.Cu")
		(net "M_F_CPU1_SA_DQS_DN<5>")
	)
	(segment
		(start 154.375104 -309.605934)
		(end 154.375104 -309.429912)
		(width 0.18288)
		(layer "In2.Cu")
		(net "M_F_CPU1_SA_DQS_DN<5>")
	)
	(segment
		(start 148.770086 -303.824894)
		(end 148.770086 -303.276254)
		(width 0.18288)
		(layer "In2.Cu")
		(net "M_F_CPU1_SA_DQS_DN<5>")
	)
	(segment
		(start 148.645626 -302.603154)
		(end 148.770086 -302.478694)
		(width 0.18288)
		(layer "In2.Cu")
		(net "M_F_CPU1_SA_DQS_DN<5>")
	)
	(segment
		(start 176.646078 -311.81675)
		(end 176.388776 -311.81675)
		(width 0.18288)
		(layer "In2.Cu")
		(net "M_F_CPU1_SA_DQS_DN<5>")
	)
	(segment
		(start 176.388776 -311.81675)
		(end 175.659288 -312.11901)
		(width 0.18288)
		(layer "In2.Cu")
		(net "M_F_CPU1_SA_DQS_DN<5>")
	)
	(segment
		(start 161.880804 -311.090056)
		(end 161.253932 -311.349644)
		(width 0.18288)
		(layer "In2.Cu")
		(net "M_F_CPU1_SA_DQS_DN<5>")
	)
	(segment
		(start 172.271944 -311.377584)
		(end 171.769532 -311.377584)
		(width 0.18288)
		(layer "In2.Cu")
		(net "M_F_CPU1_SA_DQS_DN<5>")
	)
	(segment
		(start 157.515306 -311.644538)
		(end 157.204664 -311.333896)
		(width 0.18288)
		(layer "In2.Cu")
		(net "M_F_CPU1_SA_DQS_DN<5>")
	)
	(segment
		(start 174.63008 -311.681622)
		(end 174.601886 -311.653428)
		(width 0.16002)
		(layer "In2.Cu")
		(net "M_F_CPU1_SA_DQS_DN<5>")
	)
	(segment
		(start 148.645626 -299.910754)
		(end 148.770086 -299.786294)
		(width 0.18288)
		(layer "In2.Cu")
		(net "M_F_CPU1_SA_DQS_DN<5>")
	)
	(segment
		(start 148.770086 -302.478694)
		(end 148.770086 -301.930054)
		(width 0.18288)
		(layer "In2.Cu")
		(net "M_F_CPU1_SA_DQS_DN<5>")
	)
	(segment
		(start 153.423112 -308.47792)
		(end 153.035254 -308.090062)
		(width 0.18288)
		(layer "In2.Cu")
		(net "M_F_CPU1_SA_DQS_DN<5>")
	)
	(segment
		(start 147.353782 -294.55618)
		(end 144.588484 -291.790882)
		(width 0.18288)
		(layer "In2.Cu")
		(net "M_F_CPU1_SA_DQS_DN<5>")
	)
	(segment
		(start 150.567136 -305.621944)
		(end 150.179278 -305.234086)
		(width 0.18288)
		(layer "In2.Cu")
		(net "M_F_CPU1_SA_DQS_DN<5>")
	)
	(segment
		(start 168.618916 -311.379362)
		(end 168.117266 -311.379362)
		(width 0.18288)
		(layer "In2.Cu")
		(net "M_F_CPU1_SA_DQS_DN<5>")
	)
	(segment
		(start 154.939238 -309.994046)
		(end 154.763216 -309.994046)
		(width 0.18288)
		(layer "In2.Cu")
		(net "M_F_CPU1_SA_DQS_DN<5>")
	)
	(segment
		(start 159.431228 -311.364122)
		(end 158.17977 -311.364122)
		(width 0.18288)
		(layer "In2.Cu")
		(net "M_F_CPU1_SA_DQS_DN<5>")
	)
	(arc
		(start 138.817096 -278.012144)
		(mid 138.534394 -278.087886)
		(end 138.251692 -278.012144)
		(width 0.088646)
		(layer "In2.Cu")
		(net "M_F_CPU1_SA_DQS_DN<5>")
	)
	(arc
		(start 139.004294 -277.961344)
		(mid 138.907355 -277.974434)
		(end 138.817096 -278.012144)
		(width 0.088646)
		(layer "In2.Cu")
		(net "M_F_CPU1_SA_DQS_DN<5>")
	)
	(arc
		(start 137.877296 -278.012144)
		(mid 137.594594 -278.087886)
		(end 137.311892 -278.012144)
		(width 0.088646)
		(layer "In2.Cu")
		(net "M_F_CPU1_SA_DQS_DN<5>")
	)
	(arc
		(start 138.251692 -278.012144)
		(mid 138.064494 -277.962001)
		(end 137.877296 -278.012144)
		(width 0.088646)
		(layer "In2.Cu")
		(net "M_F_CPU1_SA_DQS_DN<5>")
	)
	(arc
		(start 137.311892 -278.012144)
		(mid 137.124694 -277.962001)
		(end 136.937496 -278.012144)
		(width 0.088646)
		(layer "In2.Cu")
		(net "M_F_CPU1_SA_DQS_DN<5>")
	)
	(arc
		(start 136.937496 -278.012144)
		(mid 136.654794 -278.087886)
		(end 136.372092 -278.012144)
		(width 0.088646)
		(layer "In2.Cu")
		(net "M_F_CPU1_SA_DQS_DN<5>")
	)
	(segment
		(start 180.614828 -274.907248)
		(end 180.855366 -274.66671)
		(width 0.20066)
		(layer "F.Cu")
		(net "M_F_CPU1_SA_DQS_DN<4>")
	)
	(segment
		(start 176.826418 -275.091652)
		(end 179.005992 -275.091652)
		(width 0.1016)
		(layer "F.Cu")
		(net "M_F_CPU1_SA_DQS_DN<4>")
	)
	(segment
		(start 179.011326 -275.086318)
		(end 179.33543 -275.086318)
		(width 0.20066)
		(layer "F.Cu")
		(net "M_F_CPU1_SA_DQS_DN<4>")
	)
	(segment
		(start 175.46701 -274.948396)
		(end 175.881538 -275.362924)
		(width 0.20066)
		(layer "F.Cu")
		(net "M_F_CPU1_SA_DQS_DN<4>")
	)
	(segment
		(start 172.795946 -274.66671)
		(end 173.900846 -274.66671)
		(width 0.20066)
		(layer "F.Cu")
		(net "M_F_CPU1_SA_DQS_DN<4>")
	)
	(segment
		(start 174.449486 -274.66671)
		(end 174.731172 -274.948396)
		(width 0.20066)
		(layer "F.Cu")
		(net "M_F_CPU1_SA_DQS_DN<4>")
	)
	(segment
		(start 174.731172 -274.948396)
		(end 175.46701 -274.948396)
		(width 0.20066)
		(layer "F.Cu")
		(net "M_F_CPU1_SA_DQS_DN<4>")
	)
	(segment
		(start 175.881538 -275.362924)
		(end 176.403254 -275.362924)
		(width 0.20066)
		(layer "F.Cu")
		(net "M_F_CPU1_SA_DQS_DN<4>")
	)
	(segment
		(start 176.403254 -275.362924)
		(end 176.674526 -275.091652)
		(width 0.20066)
		(layer "F.Cu")
		(net "M_F_CPU1_SA_DQS_DN<4>")
	)
	(segment
		(start 179.871878 -275.317712)
		(end 180.282342 -274.907248)
		(width 0.20066)
		(layer "F.Cu")
		(net "M_F_CPU1_SA_DQS_DN<4>")
	)
	(segment
		(start 176.8221 -275.091652)
		(end 176.826418 -275.091652)
		(width 0.101854)
		(layer "F.Cu")
		(net "M_F_CPU1_SA_DQS_DN<4>")
	)
	(segment
		(start 176.674526 -275.091652)
		(end 176.8221 -275.091652)
		(width 0.20066)
		(layer "F.Cu")
		(net "M_F_CPU1_SA_DQS_DN<4>")
	)
	(segment
		(start 133.835648 -262.87222)
		(end 133.835394 -262.872474)
		(width 0.20066)
		(layer "F.Cu")
		(net "M_F_CPU1_SA_DQS_DN<4>")
	)
	(segment
		(start 179.33543 -275.086318)
		(end 179.566824 -275.317712)
		(width 0.20066)
		(layer "F.Cu")
		(net "M_F_CPU1_SA_DQS_DN<4>")
	)
	(segment
		(start 133.835648 -262.336534)
		(end 133.835648 -262.87222)
		(width 0.20066)
		(layer "F.Cu")
		(net "M_F_CPU1_SA_DQS_DN<4>")
	)
	(segment
		(start 180.282342 -274.907248)
		(end 180.614828 -274.907248)
		(width 0.20066)
		(layer "F.Cu")
		(net "M_F_CPU1_SA_DQS_DN<4>")
	)
	(segment
		(start 173.900846 -274.66671)
		(end 174.449486 -274.66671)
		(width 0.20066)
		(layer "F.Cu")
		(net "M_F_CPU1_SA_DQS_DN<4>")
	)
	(segment
		(start 180.855366 -274.66671)
		(end 181.444646 -274.66671)
		(width 0.20066)
		(layer "F.Cu")
		(net "M_F_CPU1_SA_DQS_DN<4>")
	)
	(segment
		(start 179.005992 -275.091652)
		(end 179.011326 -275.086318)
		(width 0.1016)
		(layer "F.Cu")
		(net "M_F_CPU1_SA_DQS_DN<4>")
	)
	(segment
		(start 179.566824 -275.317712)
		(end 179.871878 -275.317712)
		(width 0.20066)
		(layer "F.Cu")
		(net "M_F_CPU1_SA_DQS_DN<4>")
	)
	(segment
		(start 159.473138 -273.644614)
		(end 158.153608 -273.644614)
		(width 0.18288)
		(layer "In2.Cu")
		(net "M_F_CPU1_SA_DQS_DN<4>")
	)
	(segment
		(start 163.834572 -275.07819)
		(end 163.540186 -275.372576)
		(width 0.18288)
		(layer "In2.Cu")
		(net "M_F_CPU1_SA_DQS_DN<4>")
	)
	(segment
		(start 169.829734 -275.14677)
		(end 169.72153 -275.038566)
		(width 0.18288)
		(layer "In2.Cu")
		(net "M_F_CPU1_SA_DQS_DN<4>")
	)
	(segment
		(start 156.365194 -273.222974)
		(end 155.50261 -271.14246)
		(width 0.18288)
		(layer "In2.Cu")
		(net "M_F_CPU1_SA_DQS_DN<4>")
	)
	(segment
		(start 167.094662 -275.887942)
		(end 166.98595 -275.996654)
		(width 0.18288)
		(layer "In2.Cu")
		(net "M_F_CPU1_SA_DQS_DN<4>")
	)
	(segment
		(start 155.50261 -271.14246)
		(end 155.502356 -271.141952)
		(width 0.18288)
		(layer "In2.Cu")
		(net "M_F_CPU1_SA_DQS_DN<4>")
	)
	(segment
		(start 172.795946 -274.66671)
		(end 172.795946 -274.795742)
		(width 0.18288)
		(layer "In2.Cu")
		(net "M_F_CPU1_SA_DQS_DN<4>")
	)
	(segment
		(start 160.396936 -273.678142)
		(end 160.098232 -273.379438)
		(width 0.18288)
		(layer "In2.Cu")
		(net "M_F_CPU1_SA_DQS_DN<4>")
	)
	(segment
		(start 150.241 -265.88085)
		(end 149.506432 -265.88085)
		(width 0.18288)
		(layer "In2.Cu")
		(net "M_F_CPU1_SA_DQS_DN<4>")
	)
	(segment
		(start 165.729666 -275.996654)
		(end 165.621462 -275.88845)
		(width 0.18288)
		(layer "In2.Cu")
		(net "M_F_CPU1_SA_DQS_DN<4>")
	)
	(segment
		(start 169.464736 -274.781772)
		(end 169.251376 -274.568412)
		(width 0.18288)
		(layer "In2.Cu")
		(net "M_F_CPU1_SA_DQS_DN<4>")
	)
	(segment
		(start 164.292026 -275.07819)
		(end 163.834572 -275.07819)
		(width 0.18288)
		(layer "In2.Cu")
		(net "M_F_CPU1_SA_DQS_DN<4>")
	)
	(segment
		(start 171.19473 -275.038058)
		(end 171.086018 -275.14677)
		(width 0.18288)
		(layer "In2.Cu")
		(net "M_F_CPU1_SA_DQS_DN<4>")
	)
	(segment
		(start 167.305736 -275.676868)
		(end 167.277542 -275.705062)
		(width 0.16002)
		(layer "In2.Cu")
		(net "M_F_CPU1_SA_DQS_DN<4>")
	)
	(segment
		(start 165.364668 -275.631656)
		(end 165.072568 -275.339556)
		(width 0.18288)
		(layer "In2.Cu")
		(net "M_F_CPU1_SA_DQS_DN<4>")
	)
	(segment
		(start 162.149536 -275.010372)
		(end 162.133788 -275.010372)
		(width 0.16002)
		(layer "In2.Cu")
		(net "M_F_CPU1_SA_DQS_DN<4>")
	)
	(segment
		(start 161.94913 -274.825714)
		(end 161.94913 -274.809966)
		(width 0.16002)
		(layer "In2.Cu")
		(net "M_F_CPU1_SA_DQS_DN<4>")
	)
	(segment
		(start 169.693336 -275.010372)
		(end 169.677588 -275.010372)
		(width 0.16002)
		(layer "In2.Cu")
		(net "M_F_CPU1_SA_DQS_DN<4>")
	)
	(segment
		(start 165.072568 -275.339556)
		(end 164.553392 -275.339556)
		(width 0.18288)
		(layer "In2.Cu")
		(net "M_F_CPU1_SA_DQS_DN<4>")
	)
	(segment
		(start 133.52272 -262.872474)
		(end 133.835394 -262.872474)
		(width 0.088646)
		(layer "In2.Cu")
		(net "M_F_CPU1_SA_DQS_DN<4>")
	)
	(segment
		(start 163.540186 -275.372576)
		(end 162.51174 -275.372576)
		(width 0.18288)
		(layer "In2.Cu")
		(net "M_F_CPU1_SA_DQS_DN<4>")
	)
	(segment
		(start 157.528514 -273.379438)
		(end 157.301692 -273.60626)
		(width 0.18288)
		(layer "In2.Cu")
		(net "M_F_CPU1_SA_DQS_DN<4>")
	)
	(segment
		(start 167.277542 -275.72081)
		(end 167.138604 -275.859748)
		(width 0.16002)
		(layer "In2.Cu")
		(net "M_F_CPU1_SA_DQS_DN<4>")
	)
	(segment
		(start 172.398436 -275.005038)
		(end 172.027088 -274.63369)
		(width 0.18288)
		(layer "In2.Cu")
		(net "M_F_CPU1_SA_DQS_DN<4>")
	)
	(segment
		(start 148.708872 -265.88085)
		(end 147.231354 -265.88085)
		(width 0.18288)
		(layer "In2.Cu")
		(net "M_F_CPU1_SA_DQS_DN<4>")
	)
	(segment
		(start 162.17773 -275.038566)
		(end 162.149536 -275.010372)
		(width 0.16002)
		(layer "In2.Cu")
		(net "M_F_CPU1_SA_DQS_DN<4>")
	)
	(segment
		(start 160.817306 -273.678142)
		(end 160.396936 -273.678142)
		(width 0.18288)
		(layer "In2.Cu")
		(net "M_F_CPU1_SA_DQS_DN<4>")
	)
	(segment
		(start 148.833332 -265.75639)
		(end 148.708872 -265.88085)
		(width 0.18288)
		(layer "In2.Cu")
		(net "M_F_CPU1_SA_DQS_DN<4>")
	)
	(segment
		(start 144.783556 -263.433052)
		(end 143.921988 -263.075674)
		(width 0.18288)
		(layer "In2.Cu")
		(net "M_F_CPU1_SA_DQS_DN<4>")
	)
	(segment
		(start 162.133788 -275.010372)
		(end 161.94913 -274.825714)
		(width 0.16002)
		(layer "In2.Cu")
		(net "M_F_CPU1_SA_DQS_DN<4>")
	)
	(segment
		(start 169.251376 -274.568412)
		(end 168.414192 -274.568412)
		(width 0.18288)
		(layer "In2.Cu")
		(net "M_F_CPU1_SA_DQS_DN<4>")
	)
	(segment
		(start 168.414192 -274.568412)
		(end 167.305736 -275.676868)
		(width 0.18288)
		(layer "In2.Cu")
		(net "M_F_CPU1_SA_DQS_DN<4>")
	)
	(segment
		(start 138.721338 -263.197594)
		(end 138.7094 -263.204452)
		(width 0.088646)
		(layer "In2.Cu")
		(net "M_F_CPU1_SA_DQS_DN<4>")
	)
	(segment
		(start 169.677588 -275.010372)
		(end 169.49293 -274.825714)
		(width 0.16002)
		(layer "In2.Cu")
		(net "M_F_CPU1_SA_DQS_DN<4>")
	)
	(segment
		(start 160.098232 -273.379438)
		(end 159.738314 -273.379438)
		(width 0.18288)
		(layer "In2.Cu")
		(net "M_F_CPU1_SA_DQS_DN<4>")
	)
	(segment
		(start 165.57752 -275.860256)
		(end 165.392862 -275.675598)
		(width 0.16002)
		(layer "In2.Cu")
		(net "M_F_CPU1_SA_DQS_DN<4>")
	)
	(segment
		(start 171.222924 -275.009864)
		(end 171.19473 -275.038058)
		(width 0.16002)
		(layer "In2.Cu")
		(net "M_F_CPU1_SA_DQS_DN<4>")
	)
	(segment
		(start 169.72153 -275.038566)
		(end 169.693336 -275.010372)
		(width 0.16002)
		(layer "In2.Cu")
		(net "M_F_CPU1_SA_DQS_DN<4>")
	)
	(segment
		(start 166.98595 -275.996654)
		(end 165.729666 -275.996654)
		(width 0.18288)
		(layer "In2.Cu")
		(net "M_F_CPU1_SA_DQS_DN<4>")
	)
	(segment
		(start 164.553392 -275.339556)
		(end 164.292026 -275.07819)
		(width 0.18288)
		(layer "In2.Cu")
		(net "M_F_CPU1_SA_DQS_DN<4>")
	)
	(segment
		(start 172.027088 -274.63369)
		(end 171.599098 -274.63369)
		(width 0.18288)
		(layer "In2.Cu")
		(net "M_F_CPU1_SA_DQS_DN<4>")
	)
	(segment
		(start 159.738314 -273.379438)
		(end 159.473138 -273.644614)
		(width 0.18288)
		(layer "In2.Cu")
		(net "M_F_CPU1_SA_DQS_DN<4>")
	)
	(segment
		(start 167.122856 -275.859748)
		(end 167.094662 -275.887942)
		(width 0.16002)
		(layer "In2.Cu")
		(net "M_F_CPU1_SA_DQS_DN<4>")
	)
	(segment
		(start 155.502356 -271.141952)
		(end 151.192992 -266.832842)
		(width 0.18288)
		(layer "In2.Cu")
		(net "M_F_CPU1_SA_DQS_DN<4>")
	)
	(segment
		(start 171.405804 -274.826984)
		(end 171.37761 -274.855178)
		(width 0.16002)
		(layer "In2.Cu")
		(net "M_F_CPU1_SA_DQS_DN<4>")
	)
	(segment
		(start 156.74848 -273.60626)
		(end 156.365194 -273.222974)
		(width 0.18288)
		(layer "In2.Cu")
		(net "M_F_CPU1_SA_DQS_DN<4>")
	)
	(segment
		(start 169.49293 -274.825714)
		(end 169.49293 -274.809966)
		(width 0.16002)
		(layer "In2.Cu")
		(net "M_F_CPU1_SA_DQS_DN<4>")
	)
	(segment
		(start 171.599098 -274.63369)
		(end 171.405804 -274.826984)
		(width 0.18288)
		(layer "In2.Cu")
		(net "M_F_CPU1_SA_DQS_DN<4>")
	)
	(segment
		(start 171.37761 -274.870926)
		(end 171.238672 -275.009864)
		(width 0.16002)
		(layer "In2.Cu")
		(net "M_F_CPU1_SA_DQS_DN<4>")
	)
	(segment
		(start 161.94913 -274.809966)
		(end 161.920936 -274.781772)
		(width 0.16002)
		(layer "In2.Cu")
		(net "M_F_CPU1_SA_DQS_DN<4>")
	)
	(segment
		(start 161.920936 -274.781772)
		(end 160.817306 -273.678142)
		(width 0.18288)
		(layer "In2.Cu")
		(net "M_F_CPU1_SA_DQS_DN<4>")
	)
	(segment
		(start 171.086018 -275.14677)
		(end 169.829734 -275.14677)
		(width 0.18288)
		(layer "In2.Cu")
		(net "M_F_CPU1_SA_DQS_DN<4>")
	)
	(segment
		(start 150.628858 -266.268708)
		(end 150.241 -265.88085)
		(width 0.18288)
		(layer "In2.Cu")
		(net "M_F_CPU1_SA_DQS_DN<4>")
	)
	(segment
		(start 165.593268 -275.860256)
		(end 165.57752 -275.860256)
		(width 0.16002)
		(layer "In2.Cu")
		(net "M_F_CPU1_SA_DQS_DN<4>")
	)
	(segment
		(start 157.301692 -273.60626)
		(end 156.74848 -273.60626)
		(width 0.18288)
		(layer "In2.Cu")
		(net "M_F_CPU1_SA_DQS_DN<4>")
	)
	(segment
		(start 151.192992 -266.65682)
		(end 150.80488 -266.268708)
		(width 0.18288)
		(layer "In2.Cu")
		(net "M_F_CPU1_SA_DQS_DN<4>")
	)
	(segment
		(start 172.795946 -274.795742)
		(end 172.58665 -275.005038)
		(width 0.18288)
		(layer "In2.Cu")
		(net "M_F_CPU1_SA_DQS_DN<4>")
	)
	(segment
		(start 151.192992 -266.832842)
		(end 151.192992 -266.65682)
		(width 0.18288)
		(layer "In2.Cu")
		(net "M_F_CPU1_SA_DQS_DN<4>")
	)
	(segment
		(start 158.153608 -273.644614)
		(end 157.888432 -273.379438)
		(width 0.18288)
		(layer "In2.Cu")
		(net "M_F_CPU1_SA_DQS_DN<4>")
	)
	(segment
		(start 150.80488 -266.268708)
		(end 150.628858 -266.268708)
		(width 0.18288)
		(layer "In2.Cu")
		(net "M_F_CPU1_SA_DQS_DN<4>")
	)
	(segment
		(start 133.465062 -262.930132)
		(end 133.52272 -262.872474)
		(width 0.088646)
		(layer "In2.Cu")
		(net "M_F_CPU1_SA_DQS_DN<4>")
	)
	(segment
		(start 147.231354 -265.88085)
		(end 144.783556 -263.433052)
		(width 0.18288)
		(layer "In2.Cu")
		(net "M_F_CPU1_SA_DQS_DN<4>")
	)
	(segment
		(start 165.392862 -275.65985)
		(end 165.364668 -275.631656)
		(width 0.16002)
		(layer "In2.Cu")
		(net "M_F_CPU1_SA_DQS_DN<4>")
	)
	(segment
		(start 149.381972 -265.75639)
		(end 148.833332 -265.75639)
		(width 0.18288)
		(layer "In2.Cu")
		(net "M_F_CPU1_SA_DQS_DN<4>")
	)
	(segment
		(start 162.51174 -275.372576)
		(end 162.17773 -275.038566)
		(width 0.18288)
		(layer "In2.Cu")
		(net "M_F_CPU1_SA_DQS_DN<4>")
	)
	(segment
		(start 134.596886 -263.20242)
		(end 134.588504 -263.197594)
		(width 0.088646)
		(layer "In2.Cu")
		(net "M_F_CPU1_SA_DQS_DN<4>")
	)
	(segment
		(start 140.84046 -263.135618)
		(end 139.919456 -263.135618)
		(width 0.088646)
		(layer "In2.Cu")
		(net "M_F_CPU1_SA_DQS_DN<4>")
	)
	(segment
		(start 169.49293 -274.809966)
		(end 169.464736 -274.781772)
		(width 0.16002)
		(layer "In2.Cu")
		(net "M_F_CPU1_SA_DQS_DN<4>")
	)
	(segment
		(start 143.921988 -263.075674)
		(end 140.900404 -263.075674)
		(width 0.18288)
		(layer "In2.Cu")
		(net "M_F_CPU1_SA_DQS_DN<4>")
	)
	(segment
		(start 171.37761 -274.855178)
		(end 171.37761 -274.870926)
		(width 0.16002)
		(layer "In2.Cu")
		(net "M_F_CPU1_SA_DQS_DN<4>")
	)
	(segment
		(start 140.900404 -263.075674)
		(end 140.84046 -263.135618)
		(width 0.088646)
		(layer "In2.Cu")
		(net "M_F_CPU1_SA_DQS_DN<4>")
	)
	(segment
		(start 167.138604 -275.859748)
		(end 167.122856 -275.859748)
		(width 0.16002)
		(layer "In2.Cu")
		(net "M_F_CPU1_SA_DQS_DN<4>")
	)
	(segment
		(start 171.238672 -275.009864)
		(end 171.222924 -275.009864)
		(width 0.16002)
		(layer "In2.Cu")
		(net "M_F_CPU1_SA_DQS_DN<4>")
	)
	(segment
		(start 133.464808 -262.930132)
		(end 133.465062 -262.930132)
		(width 0.088646)
		(layer "In2.Cu")
		(net "M_F_CPU1_SA_DQS_DN<4>")
	)
	(segment
		(start 157.888432 -273.379438)
		(end 157.528514 -273.379438)
		(width 0.18288)
		(layer "In2.Cu")
		(net "M_F_CPU1_SA_DQS_DN<4>")
	)
	(segment
		(start 149.506432 -265.88085)
		(end 149.381972 -265.75639)
		(width 0.18288)
		(layer "In2.Cu")
		(net "M_F_CPU1_SA_DQS_DN<4>")
	)
	(segment
		(start 167.277542 -275.705062)
		(end 167.277542 -275.72081)
		(width 0.16002)
		(layer "In2.Cu")
		(net "M_F_CPU1_SA_DQS_DN<4>")
	)
	(segment
		(start 165.392862 -275.675598)
		(end 165.392862 -275.65985)
		(width 0.16002)
		(layer "In2.Cu")
		(net "M_F_CPU1_SA_DQS_DN<4>")
	)
	(segment
		(start 172.58665 -275.005038)
		(end 172.398436 -275.005038)
		(width 0.18288)
		(layer "In2.Cu")
		(net "M_F_CPU1_SA_DQS_DN<4>")
	)
	(segment
		(start 165.621462 -275.88845)
		(end 165.593268 -275.860256)
		(width 0.16002)
		(layer "In2.Cu")
		(net "M_F_CPU1_SA_DQS_DN<4>")
	)
	(arc
		(start 134.588504 -263.197594)
		(mid 134.305831 -263.121623)
		(end 134.0231 -263.19734)
		(width 0.088646)
		(layer "In2.Cu")
		(net "M_F_CPU1_SA_DQS_DN<4>")
	)
	(arc
		(start 139.919456 -263.135618)
		(mid 139.780022 -263.153129)
		(end 139.6492 -263.204452)
		(width 0.088646)
		(layer "In2.Cu")
		(net "M_F_CPU1_SA_DQS_DN<4>")
	)
	(arc
		(start 139.6492 -263.204452)
		(mid 139.467059 -263.247565)
		(end 139.286742 -263.19734)
		(width 0.088646)
		(layer "In2.Cu")
		(net "M_F_CPU1_SA_DQS_DN<4>")
	)
	(arc
		(start 136.8425 -263.19734)
		(mid 136.654794 -263.247669)
		(end 136.467088 -263.19734)
		(width 0.088646)
		(layer "In2.Cu")
		(net "M_F_CPU1_SA_DQS_DN<4>")
	)
	(arc
		(start 138.346942 -263.19734)
		(mid 138.064638 -263.121784)
		(end 137.7823 -263.19734)
		(width 0.088646)
		(layer "In2.Cu")
		(net "M_F_CPU1_SA_DQS_DN<4>")
	)
	(arc
		(start 134.9629 -263.19734)
		(mid 134.780567 -263.247507)
		(end 134.596886 -263.20242)
		(width 0.088646)
		(layer "In2.Cu")
		(net "M_F_CPU1_SA_DQS_DN<4>")
	)
	(arc
		(start 135.527288 -263.19734)
		(mid 135.245094 -263.121784)
		(end 134.9629 -263.19734)
		(width 0.088646)
		(layer "In2.Cu")
		(net "M_F_CPU1_SA_DQS_DN<4>")
	)
	(arc
		(start 138.7094 -263.204452)
		(mid 138.527259 -263.247565)
		(end 138.346942 -263.19734)
		(width 0.088646)
		(layer "In2.Cu")
		(net "M_F_CPU1_SA_DQS_DN<4>")
	)
	(arc
		(start 136.467088 -263.19734)
		(mid 136.184894 -263.121784)
		(end 135.9027 -263.19734)
		(width 0.088646)
		(layer "In2.Cu")
		(net "M_F_CPU1_SA_DQS_DN<4>")
	)
	(arc
		(start 134.0231 -263.19734)
		(mid 133.673462 -263.210926)
		(end 133.464808 -262.930132)
		(width 0.088646)
		(layer "In2.Cu")
		(net "M_F_CPU1_SA_DQS_DN<4>")
	)
	(arc
		(start 137.7823 -263.19734)
		(mid 137.594594 -263.247669)
		(end 137.406888 -263.19734)
		(width 0.088646)
		(layer "In2.Cu")
		(net "M_F_CPU1_SA_DQS_DN<4>")
	)
	(arc
		(start 139.286742 -263.19734)
		(mid 139.004011 -263.121657)
		(end 138.721338 -263.197594)
		(width 0.088646)
		(layer "In2.Cu")
		(net "M_F_CPU1_SA_DQS_DN<4>")
	)
	(arc
		(start 135.9027 -263.19734)
		(mid 135.714994 -263.247669)
		(end 135.527288 -263.19734)
		(width 0.088646)
		(layer "In2.Cu")
		(net "M_F_CPU1_SA_DQS_DN<4>")
	)
	(arc
		(start 137.406888 -263.19734)
		(mid 137.124694 -263.121784)
		(end 136.8425 -263.19734)
		(width 0.088646)
		(layer "In2.Cu")
		(net "M_F_CPU1_SA_DQS_DN<4>")
	)
	(segment
		(start 172.795946 -284.016704)
		(end 173.900846 -284.016704)
		(width 0.20066)
		(layer "F.Cu")
		(net "M_F_CPU1_SA_DQS_DN<3>")
	)
	(segment
		(start 175.881538 -284.712918)
		(end 176.403254 -284.712918)
		(width 0.20066)
		(layer "F.Cu")
		(net "M_F_CPU1_SA_DQS_DN<3>")
	)
	(segment
		(start 176.403254 -284.712918)
		(end 176.674526 -284.441646)
		(width 0.20066)
		(layer "F.Cu")
		(net "M_F_CPU1_SA_DQS_DN<3>")
	)
	(segment
		(start 179.871878 -284.667706)
		(end 180.282342 -284.257242)
		(width 0.20066)
		(layer "F.Cu")
		(net "M_F_CPU1_SA_DQS_DN<3>")
	)
	(segment
		(start 180.282342 -284.257242)
		(end 180.614828 -284.257242)
		(width 0.20066)
		(layer "F.Cu")
		(net "M_F_CPU1_SA_DQS_DN<3>")
	)
	(segment
		(start 179.566824 -284.667706)
		(end 179.871878 -284.667706)
		(width 0.20066)
		(layer "F.Cu")
		(net "M_F_CPU1_SA_DQS_DN<3>")
	)
	(segment
		(start 130.546094 -260.430518)
		(end 130.546348 -260.430772)
		(width 0.20066)
		(layer "F.Cu")
		(net "M_F_CPU1_SA_DQS_DN<3>")
	)
	(segment
		(start 176.8221 -284.441646)
		(end 176.826418 -284.441646)
		(width 0.101854)
		(layer "F.Cu")
		(net "M_F_CPU1_SA_DQS_DN<3>")
	)
	(segment
		(start 180.855366 -284.016704)
		(end 181.444646 -284.016704)
		(width 0.20066)
		(layer "F.Cu")
		(net "M_F_CPU1_SA_DQS_DN<3>")
	)
	(segment
		(start 179.011326 -284.436312)
		(end 179.33543 -284.436312)
		(width 0.20066)
		(layer "F.Cu")
		(net "M_F_CPU1_SA_DQS_DN<3>")
	)
	(segment
		(start 174.731172 -284.29839)
		(end 175.46701 -284.29839)
		(width 0.20066)
		(layer "F.Cu")
		(net "M_F_CPU1_SA_DQS_DN<3>")
	)
	(segment
		(start 130.546094 -259.894832)
		(end 130.546094 -260.430518)
		(width 0.20066)
		(layer "F.Cu")
		(net "M_F_CPU1_SA_DQS_DN<3>")
	)
	(segment
		(start 180.614828 -284.257242)
		(end 180.855366 -284.016704)
		(width 0.20066)
		(layer "F.Cu")
		(net "M_F_CPU1_SA_DQS_DN<3>")
	)
	(segment
		(start 176.674526 -284.441646)
		(end 176.8221 -284.441646)
		(width 0.20066)
		(layer "F.Cu")
		(net "M_F_CPU1_SA_DQS_DN<3>")
	)
	(segment
		(start 179.33543 -284.436312)
		(end 179.566824 -284.667706)
		(width 0.20066)
		(layer "F.Cu")
		(net "M_F_CPU1_SA_DQS_DN<3>")
	)
	(segment
		(start 173.900846 -284.016704)
		(end 174.449486 -284.016704)
		(width 0.20066)
		(layer "F.Cu")
		(net "M_F_CPU1_SA_DQS_DN<3>")
	)
	(segment
		(start 175.46701 -284.29839)
		(end 175.881538 -284.712918)
		(width 0.20066)
		(layer "F.Cu")
		(net "M_F_CPU1_SA_DQS_DN<3>")
	)
	(segment
		(start 179.005992 -284.441646)
		(end 179.011326 -284.436312)
		(width 0.1016)
		(layer "F.Cu")
		(net "M_F_CPU1_SA_DQS_DN<3>")
	)
	(segment
		(start 176.826418 -284.441646)
		(end 179.005992 -284.441646)
		(width 0.1016)
		(layer "F.Cu")
		(net "M_F_CPU1_SA_DQS_DN<3>")
	)
	(segment
		(start 174.449486 -284.016704)
		(end 174.731172 -284.29839)
		(width 0.20066)
		(layer "F.Cu")
		(net "M_F_CPU1_SA_DQS_DN<3>")
	)
	(segment
		(start 148.67382 -262.683752)
		(end 145.741898 -262.683752)
		(width 0.18288)
		(layer "In4.Cu")
		(net "M_F_CPU1_SA_DQS_DN<3>")
	)
	(segment
		(start 130.35915 -260.75513)
		(end 130.35026 -260.75005)
		(width 0.088646)
		(layer "In4.Cu")
		(net "M_F_CPU1_SA_DQS_DN<3>")
	)
	(segment
		(start 138.844782 -260.638036)
		(end 138.785092 -260.697726)
		(width 0.088646)
		(layer "In4.Cu")
		(net "M_F_CPU1_SA_DQS_DN<3>")
	)
	(segment
		(start 130.17627 -260.488176)
		(end 130.233674 -260.430772)
		(width 0.088646)
		(layer "In4.Cu")
		(net "M_F_CPU1_SA_DQS_DN<3>")
	)
	(segment
		(start 165.880542 -275.35505)
		(end 163.940998 -273.415506)
		(width 0.18288)
		(layer "In4.Cu")
		(net "M_F_CPU1_SA_DQS_DN<3>")
	)
	(segment
		(start 168.745154 -276.218904)
		(end 167.8813 -275.35505)
		(width 0.18288)
		(layer "In4.Cu")
		(net "M_F_CPU1_SA_DQS_DN<3>")
	)
	(segment
		(start 171.395898 -283.965142)
		(end 170.46448 -283.033724)
		(width 0.18288)
		(layer "In4.Cu")
		(net "M_F_CPU1_SA_DQS_DN<3>")
	)
	(segment
		(start 163.940998 -273.415506)
		(end 160.818068 -273.415506)
		(width 0.18288)
		(layer "In4.Cu")
		(net "M_F_CPU1_SA_DQS_DN<3>")
	)
	(segment
		(start 138.86815 -260.638036)
		(end 138.844782 -260.638036)
		(width 0.088646)
		(layer "In4.Cu")
		(net "M_F_CPU1_SA_DQS_DN<3>")
	)
	(segment
		(start 130.748278 -260.746494)
		(end 130.733546 -260.75513)
		(width 0.088646)
		(layer "In4.Cu")
		(net "M_F_CPU1_SA_DQS_DN<3>")
	)
	(segment
		(start 130.233674 -260.430772)
		(end 130.546348 -260.430772)
		(width 0.088646)
		(layer "In4.Cu")
		(net "M_F_CPU1_SA_DQS_DN<3>")
	)
	(segment
		(start 144.11452 -261.706106)
		(end 141.535404 -260.638036)
		(width 0.18288)
		(layer "In4.Cu")
		(net "M_F_CPU1_SA_DQS_DN<3>")
	)
	(segment
		(start 168.869614 -279.442926)
		(end 168.745154 -279.318466)
		(width 0.18288)
		(layer "In4.Cu")
		(net "M_F_CPU1_SA_DQS_DN<3>")
	)
	(segment
		(start 170.042332 -281.956764)
		(end 168.745154 -280.659586)
		(width 0.18288)
		(layer "In4.Cu")
		(net "M_F_CPU1_SA_DQS_DN<3>")
	)
	(segment
		(start 168.745154 -279.318466)
		(end 168.745154 -278.590248)
		(width 0.18288)
		(layer "In4.Cu")
		(net "M_F_CPU1_SA_DQS_DN<3>")
	)
	(segment
		(start 144.632426 -262.224012)
		(end 144.11452 -261.706106)
		(width 0.18288)
		(layer "In4.Cu")
		(net "M_F_CPU1_SA_DQS_DN<3>")
	)
	(segment
		(start 172.315124 -284.276546)
		(end 172.00372 -283.965142)
		(width 0.18288)
		(layer "In4.Cu")
		(net "M_F_CPU1_SA_DQS_DN<3>")
	)
	(segment
		(start 134.50316 -260.749034)
		(end 134.492746 -260.75513)
		(width 0.088646)
		(layer "In4.Cu")
		(net "M_F_CPU1_SA_DQS_DN<3>")
	)
	(segment
		(start 168.869614 -277.919688)
		(end 168.745154 -277.795228)
		(width 0.18288)
		(layer "In4.Cu")
		(net "M_F_CPU1_SA_DQS_DN<3>")
	)
	(segment
		(start 170.46448 -283.033724)
		(end 170.042332 -281.956764)
		(width 0.18288)
		(layer "In4.Cu")
		(net "M_F_CPU1_SA_DQS_DN<3>")
	)
	(segment
		(start 172.00372 -283.965142)
		(end 171.395898 -283.965142)
		(width 0.18288)
		(layer "In4.Cu")
		(net "M_F_CPU1_SA_DQS_DN<3>")
	)
	(segment
		(start 145.741898 -262.683752)
		(end 144.632426 -262.224012)
		(width 0.18288)
		(layer "In4.Cu")
		(net "M_F_CPU1_SA_DQS_DN<3>")
	)
	(segment
		(start 168.869614 -279.989026)
		(end 168.869614 -279.442926)
		(width 0.18288)
		(layer "In4.Cu")
		(net "M_F_CPU1_SA_DQS_DN<3>")
	)
	(segment
		(start 138.299698 -260.697726)
		(end 138.231372 -260.766052)
		(width 0.088646)
		(layer "In4.Cu")
		(net "M_F_CPU1_SA_DQS_DN<3>")
	)
	(segment
		(start 168.745154 -277.795228)
		(end 168.745154 -276.218904)
		(width 0.18288)
		(layer "In4.Cu")
		(net "M_F_CPU1_SA_DQS_DN<3>")
	)
	(segment
		(start 138.785092 -260.697726)
		(end 138.299698 -260.697726)
		(width 0.088646)
		(layer "In4.Cu")
		(net "M_F_CPU1_SA_DQS_DN<3>")
	)
	(segment
		(start 157.354016 -271.363948)
		(end 148.67382 -262.683752)
		(width 0.18288)
		(layer "In4.Cu")
		(net "M_F_CPU1_SA_DQS_DN<3>")
	)
	(segment
		(start 160.818068 -273.415506)
		(end 158.76651 -271.363948)
		(width 0.18288)
		(layer "In4.Cu")
		(net "M_F_CPU1_SA_DQS_DN<3>")
	)
	(segment
		(start 172.536104 -284.276546)
		(end 172.315124 -284.276546)
		(width 0.18288)
		(layer "In4.Cu")
		(net "M_F_CPU1_SA_DQS_DN<3>")
	)
	(segment
		(start 132.62356 -260.749034)
		(end 132.613146 -260.75513)
		(width 0.088646)
		(layer "In4.Cu")
		(net "M_F_CPU1_SA_DQS_DN<3>")
	)
	(segment
		(start 167.8813 -275.35505)
		(end 165.880542 -275.35505)
		(width 0.18288)
		(layer "In4.Cu")
		(net "M_F_CPU1_SA_DQS_DN<3>")
	)
	(segment
		(start 141.535404 -260.638036)
		(end 138.86815 -260.638036)
		(width 0.18288)
		(layer "In4.Cu")
		(net "M_F_CPU1_SA_DQS_DN<3>")
	)
	(segment
		(start 136.382506 -260.749034)
		(end 136.372092 -260.75513)
		(width 0.088646)
		(layer "In4.Cu")
		(net "M_F_CPU1_SA_DQS_DN<3>")
	)
	(segment
		(start 131.688078 -260.746494)
		(end 131.673346 -260.75513)
		(width 0.088646)
		(layer "In4.Cu")
		(net "M_F_CPU1_SA_DQS_DN<3>")
	)
	(segment
		(start 168.745154 -280.113486)
		(end 168.869614 -279.989026)
		(width 0.18288)
		(layer "In4.Cu")
		(net "M_F_CPU1_SA_DQS_DN<3>")
	)
	(segment
		(start 168.869614 -278.465788)
		(end 168.869614 -277.919688)
		(width 0.18288)
		(layer "In4.Cu")
		(net "M_F_CPU1_SA_DQS_DN<3>")
	)
	(segment
		(start 158.76651 -271.363948)
		(end 157.354016 -271.363948)
		(width 0.18288)
		(layer "In4.Cu")
		(net "M_F_CPU1_SA_DQS_DN<3>")
	)
	(segment
		(start 133.563106 -260.749034)
		(end 133.552692 -260.75513)
		(width 0.088646)
		(layer "In4.Cu")
		(net "M_F_CPU1_SA_DQS_DN<3>")
	)
	(segment
		(start 168.745154 -280.659586)
		(end 168.745154 -280.113486)
		(width 0.18288)
		(layer "In4.Cu")
		(net "M_F_CPU1_SA_DQS_DN<3>")
	)
	(segment
		(start 168.745154 -278.590248)
		(end 168.869614 -278.465788)
		(width 0.18288)
		(layer "In4.Cu")
		(net "M_F_CPU1_SA_DQS_DN<3>")
	)
	(segment
		(start 172.795946 -284.016704)
		(end 172.536104 -284.276546)
		(width 0.18288)
		(layer "In4.Cu")
		(net "M_F_CPU1_SA_DQS_DN<3>")
	)
	(arc
		(start 134.11835 -260.75513)
		(mid 133.841537 -260.679294)
		(end 133.563106 -260.749034)
		(width 0.088646)
		(layer "In4.Cu")
		(net "M_F_CPU1_SA_DQS_DN<3>")
	)
	(arc
		(start 135.057896 -260.75513)
		(mid 134.781337 -260.679421)
		(end 134.50316 -260.749034)
		(width 0.088646)
		(layer "In4.Cu")
		(net "M_F_CPU1_SA_DQS_DN<3>")
	)
	(arc
		(start 137.311638 -260.75513)
		(mid 137.12444 -260.805273)
		(end 136.937242 -260.75513)
		(width 0.088646)
		(layer "In4.Cu")
		(net "M_F_CPU1_SA_DQS_DN<3>")
	)
	(arc
		(start 135.997696 -260.75513)
		(mid 135.714994 -260.679388)
		(end 135.432292 -260.75513)
		(width 0.088646)
		(layer "In4.Cu")
		(net "M_F_CPU1_SA_DQS_DN<3>")
	)
	(arc
		(start 137.877042 -260.75513)
		(mid 137.59434 -260.679388)
		(end 137.311638 -260.75513)
		(width 0.088646)
		(layer "In4.Cu")
		(net "M_F_CPU1_SA_DQS_DN<3>")
	)
	(arc
		(start 132.613146 -260.75513)
		(mid 132.425948 -260.805273)
		(end 132.23875 -260.75513)
		(width 0.088646)
		(layer "In4.Cu")
		(net "M_F_CPU1_SA_DQS_DN<3>")
	)
	(arc
		(start 135.432292 -260.75513)
		(mid 135.245094 -260.805273)
		(end 135.057896 -260.75513)
		(width 0.088646)
		(layer "In4.Cu")
		(net "M_F_CPU1_SA_DQS_DN<3>")
	)
	(arc
		(start 130.733546 -260.75513)
		(mid 130.546348 -260.805273)
		(end 130.35915 -260.75513)
		(width 0.088646)
		(layer "In4.Cu")
		(net "M_F_CPU1_SA_DQS_DN<3>")
	)
	(arc
		(start 130.35026 -260.75005)
		(mid 130.234521 -260.638226)
		(end 130.17627 -260.488176)
		(width 0.088646)
		(layer "In4.Cu")
		(net "M_F_CPU1_SA_DQS_DN<3>")
	)
	(arc
		(start 134.492746 -260.75513)
		(mid 134.305548 -260.805273)
		(end 134.11835 -260.75513)
		(width 0.088646)
		(layer "In4.Cu")
		(net "M_F_CPU1_SA_DQS_DN<3>")
	)
	(arc
		(start 133.552692 -260.75513)
		(mid 133.365494 -260.805273)
		(end 133.178296 -260.75513)
		(width 0.088646)
		(layer "In4.Cu")
		(net "M_F_CPU1_SA_DQS_DN<3>")
	)
	(arc
		(start 133.178296 -260.75513)
		(mid 132.901737 -260.679421)
		(end 132.62356 -260.749034)
		(width 0.088646)
		(layer "In4.Cu")
		(net "M_F_CPU1_SA_DQS_DN<3>")
	)
	(arc
		(start 136.372092 -260.75513)
		(mid 136.184894 -260.805273)
		(end 135.997696 -260.75513)
		(width 0.088646)
		(layer "In4.Cu")
		(net "M_F_CPU1_SA_DQS_DN<3>")
	)
	(arc
		(start 138.231372 -260.766052)
		(mid 138.052849 -260.805105)
		(end 137.877042 -260.75513)
		(width 0.088646)
		(layer "In4.Cu")
		(net "M_F_CPU1_SA_DQS_DN<3>")
	)
	(arc
		(start 132.23875 -260.75513)
		(mid 131.964521 -260.679205)
		(end 131.688078 -260.746494)
		(width 0.088646)
		(layer "In4.Cu")
		(net "M_F_CPU1_SA_DQS_DN<3>")
	)
	(arc
		(start 131.673346 -260.75513)
		(mid 131.486148 -260.805273)
		(end 131.29895 -260.75513)
		(width 0.088646)
		(layer "In4.Cu")
		(net "M_F_CPU1_SA_DQS_DN<3>")
	)
	(arc
		(start 136.937242 -260.75513)
		(mid 136.660683 -260.679421)
		(end 136.382506 -260.749034)
		(width 0.088646)
		(layer "In4.Cu")
		(net "M_F_CPU1_SA_DQS_DN<3>")
	)
	(arc
		(start 131.29895 -260.75513)
		(mid 131.024721 -260.679205)
		(end 130.748278 -260.746494)
		(width 0.088646)
		(layer "In4.Cu")
		(net "M_F_CPU1_SA_DQS_DN<3>")
	)
	(segment
		(start 176.403254 -294.062912)
		(end 176.674526 -293.79164)
		(width 0.20066)
		(layer "F.Cu")
		(net "M_F_CPU1_SA_DQS_DN<2>")
	)
	(segment
		(start 175.46701 -293.648384)
		(end 175.881538 -294.062912)
		(width 0.20066)
		(layer "F.Cu")
		(net "M_F_CPU1_SA_DQS_DN<2>")
	)
	(segment
		(start 179.005992 -293.79164)
		(end 179.011326 -293.786306)
		(width 0.1016)
		(layer "F.Cu")
		(net "M_F_CPU1_SA_DQS_DN<2>")
	)
	(segment
		(start 180.282342 -293.607236)
		(end 180.614828 -293.607236)
		(width 0.20066)
		(layer "F.Cu")
		(net "M_F_CPU1_SA_DQS_DN<2>")
	)
	(segment
		(start 176.826418 -293.79164)
		(end 179.005992 -293.79164)
		(width 0.1016)
		(layer "F.Cu")
		(net "M_F_CPU1_SA_DQS_DN<2>")
	)
	(segment
		(start 172.795946 -293.366698)
		(end 173.900846 -293.366698)
		(width 0.20066)
		(layer "F.Cu")
		(net "M_F_CPU1_SA_DQS_DN<2>")
	)
	(segment
		(start 180.855366 -293.366698)
		(end 181.444646 -293.366698)
		(width 0.20066)
		(layer "F.Cu")
		(net "M_F_CPU1_SA_DQS_DN<2>")
	)
	(segment
		(start 174.731172 -293.648384)
		(end 175.46701 -293.648384)
		(width 0.20066)
		(layer "F.Cu")
		(net "M_F_CPU1_SA_DQS_DN<2>")
	)
	(segment
		(start 173.900846 -293.366698)
		(end 174.449486 -293.366698)
		(width 0.20066)
		(layer "F.Cu")
		(net "M_F_CPU1_SA_DQS_DN<2>")
	)
	(segment
		(start 179.871878 -294.0177)
		(end 180.282342 -293.607236)
		(width 0.20066)
		(layer "F.Cu")
		(net "M_F_CPU1_SA_DQS_DN<2>")
	)
	(segment
		(start 179.011326 -293.786306)
		(end 179.33543 -293.786306)
		(width 0.20066)
		(layer "F.Cu")
		(net "M_F_CPU1_SA_DQS_DN<2>")
	)
	(segment
		(start 174.449486 -293.366698)
		(end 174.731172 -293.648384)
		(width 0.20066)
		(layer "F.Cu")
		(net "M_F_CPU1_SA_DQS_DN<2>")
	)
	(segment
		(start 175.881538 -294.062912)
		(end 176.403254 -294.062912)
		(width 0.20066)
		(layer "F.Cu")
		(net "M_F_CPU1_SA_DQS_DN<2>")
	)
	(segment
		(start 179.33543 -293.786306)
		(end 179.566824 -294.0177)
		(width 0.20066)
		(layer "F.Cu")
		(net "M_F_CPU1_SA_DQS_DN<2>")
	)
	(segment
		(start 179.566824 -294.0177)
		(end 179.871878 -294.0177)
		(width 0.20066)
		(layer "F.Cu")
		(net "M_F_CPU1_SA_DQS_DN<2>")
	)
	(segment
		(start 132.895848 -267.219938)
		(end 132.895848 -267.755624)
		(width 0.20066)
		(layer "F.Cu")
		(net "M_F_CPU1_SA_DQS_DN<2>")
	)
	(segment
		(start 180.614828 -293.607236)
		(end 180.855366 -293.366698)
		(width 0.20066)
		(layer "F.Cu")
		(net "M_F_CPU1_SA_DQS_DN<2>")
	)
	(segment
		(start 132.895848 -267.755624)
		(end 132.895594 -267.755878)
		(width 0.20066)
		(layer "F.Cu")
		(net "M_F_CPU1_SA_DQS_DN<2>")
	)
	(segment
		(start 176.8221 -293.79164)
		(end 176.826418 -293.79164)
		(width 0.101854)
		(layer "F.Cu")
		(net "M_F_CPU1_SA_DQS_DN<2>")
	)
	(segment
		(start 176.674526 -293.79164)
		(end 176.8221 -293.79164)
		(width 0.20066)
		(layer "F.Cu")
		(net "M_F_CPU1_SA_DQS_DN<2>")
	)
	(segment
		(start 169.552112 -293.589964)
		(end 169.523918 -293.56177)
		(width 0.16002)
		(layer "In2.Cu")
		(net "M_F_CPU1_SA_DQS_DN<2>")
	)
	(segment
		(start 134.962646 -268.079982)
		(end 134.9629 -268.08049)
		(width 0.088646)
		(layer "In2.Cu")
		(net "M_F_CPU1_SA_DQS_DN<2>")
	)
	(segment
		(start 158.173928 -285.340044)
		(end 158.15818 -285.340044)
		(width 0.16002)
		(layer "In2.Cu")
		(net "M_F_CPU1_SA_DQS_DN<2>")
	)
	(segment
		(start 163.960048 -287.546034)
		(end 163.701222 -287.80486)
		(width 0.18288)
		(layer "In2.Cu")
		(net "M_F_CPU1_SA_DQS_DN<2>")
	)
	(segment
		(start 169.780712 -293.818564)
		(end 169.752518 -293.79037)
		(width 0.16002)
		(layer "In2.Cu")
		(net "M_F_CPU1_SA_DQS_DN<2>")
	)
	(segment
		(start 150.158958 -274.526248)
		(end 147.977606 -272.344642)
		(width 0.18288)
		(layer "In2.Cu")
		(net "M_F_CPU1_SA_DQS_DN<2>")
	)
	(segment
		(start 142.521178 -268.160246)
		(end 140.900404 -268.160246)
		(width 0.18288)
		(layer "In2.Cu")
		(net "M_F_CPU1_SA_DQS_DN<2>")
	)
	(segment
		(start 169.73677 -293.79037)
		(end 169.552112 -293.605712)
		(width 0.16002)
		(layer "In2.Cu")
		(net "M_F_CPU1_SA_DQS_DN<2>")
	)
	(segment
		(start 133.408166 -267.755878)
		(end 132.895594 -267.755878)
		(width 0.088646)
		(layer "In2.Cu")
		(net "M_F_CPU1_SA_DQS_DN<2>")
	)
	(segment
		(start 134.196836 -267.632434)
		(end 134.15899 -267.566902)
		(width 0.088646)
		(layer "In2.Cu")
		(net "M_F_CPU1_SA_DQS_DN<2>")
	)
	(segment
		(start 171.339002 -293.613078)
		(end 171.339002 -293.628826)
		(width 0.16002)
		(layer "In2.Cu")
		(net "M_F_CPU1_SA_DQS_DN<2>")
	)
	(segment
		(start 158.202122 -285.368238)
		(end 158.173928 -285.340044)
		(width 0.16002)
		(layer "In2.Cu")
		(net "M_F_CPU1_SA_DQS_DN<2>")
	)
	(segment
		(start 167.872664 -288.126424)
		(end 167.417496 -287.671256)
		(width 0.18288)
		(layer "In2.Cu")
		(net "M_F_CPU1_SA_DQS_DN<2>")
	)
	(segment
		(start 159.704786 -285.851092)
		(end 159.676592 -285.822898)
		(width 0.16002)
		(layer "In2.Cu")
		(net "M_F_CPU1_SA_DQS_DN<2>")
	)
	(segment
		(start 169.752518 -293.79037)
		(end 169.73677 -293.79037)
		(width 0.16002)
		(layer "In2.Cu")
		(net "M_F_CPU1_SA_DQS_DN<2>")
	)
	(segment
		(start 172.230034 -293.57955)
		(end 172.058838 -293.408354)
		(width 0.18288)
		(layer "In2.Cu")
		(net "M_F_CPU1_SA_DQS_DN<2>")
	)
	(segment
		(start 171.138596 -293.813484)
		(end 171.110402 -293.841678)
		(width 0.16002)
		(layer "In2.Cu")
		(net "M_F_CPU1_SA_DQS_DN<2>")
	)
	(segment
		(start 167.962326 -289.966908)
		(end 168.215056 -289.356546)
		(width 0.18288)
		(layer "In2.Cu")
		(net "M_F_CPU1_SA_DQS_DN<2>")
	)
	(segment
		(start 159.375602 -285.521908)
		(end 158.355792 -285.521908)
		(width 0.18288)
		(layer "In2.Cu")
		(net "M_F_CPU1_SA_DQS_DN<2>")
	)
	(segment
		(start 157.5816 -284.747716)
		(end 157.442154 -284.747716)
		(width 0.18288)
		(layer "In2.Cu")
		(net "M_F_CPU1_SA_DQS_DN<2>")
	)
	(segment
		(start 172.795946 -293.366698)
		(end 172.583094 -293.57955)
		(width 0.18288)
		(layer "In2.Cu")
		(net "M_F_CPU1_SA_DQS_DN<2>")
	)
	(segment
		(start 134.523734 -268.041882)
		(end 134.196836 -267.632434)
		(width 0.088646)
		(layer "In2.Cu")
		(net "M_F_CPU1_SA_DQS_DN<2>")
	)
	(segment
		(start 169.523918 -293.56177)
		(end 169.093896 -293.131748)
		(width 0.18288)
		(layer "In2.Cu")
		(net "M_F_CPU1_SA_DQS_DN<2>")
	)
	(segment
		(start 162.105594 -287.80486)
		(end 160.438084 -286.13735)
		(width 0.18288)
		(layer "In2.Cu")
		(net "M_F_CPU1_SA_DQS_DN<2>")
	)
	(segment
		(start 171.543726 -293.408354)
		(end 171.367196 -293.584884)
		(width 0.18288)
		(layer "In2.Cu")
		(net "M_F_CPU1_SA_DQS_DN<2>")
	)
	(segment
		(start 134.599934 -268.087602)
		(end 134.523734 -268.041882)
		(width 0.088646)
		(layer "In2.Cu")
		(net "M_F_CPU1_SA_DQS_DN<2>")
	)
	(segment
		(start 135.527796 -268.080236)
		(end 135.513064 -268.0716)
		(width 0.088646)
		(layer "In2.Cu")
		(net "M_F_CPU1_SA_DQS_DN<2>")
	)
	(segment
		(start 171.154344 -293.813484)
		(end 171.138596 -293.813484)
		(width 0.16002)
		(layer "In2.Cu")
		(net "M_F_CPU1_SA_DQS_DN<2>")
	)
	(segment
		(start 171.110402 -293.841678)
		(end 171.07789 -293.87419)
		(width 0.18288)
		(layer "In2.Cu")
		(net "M_F_CPU1_SA_DQS_DN<2>")
	)
	(segment
		(start 165.35146 -287.651444)
		(end 164.705538 -287.651444)
		(width 0.18288)
		(layer "In2.Cu")
		(net "M_F_CPU1_SA_DQS_DN<2>")
	)
	(segment
		(start 159.704786 -285.867348)
		(end 159.704786 -285.851092)
		(width 0.16002)
		(layer "In2.Cu")
		(net "M_F_CPU1_SA_DQS_DN<2>")
	)
	(segment
		(start 168.215056 -289.356546)
		(end 168.215056 -288.953194)
		(width 0.18288)
		(layer "In2.Cu")
		(net "M_F_CPU1_SA_DQS_DN<2>")
	)
	(segment
		(start 140.840714 -268.219936)
		(end 140.544804 -268.219936)
		(width 0.088646)
		(layer "In2.Cu")
		(net "M_F_CPU1_SA_DQS_DN<2>")
	)
	(segment
		(start 169.093896 -293.131748)
		(end 167.962326 -289.966908)
		(width 0.18288)
		(layer "In2.Cu")
		(net "M_F_CPU1_SA_DQS_DN<2>")
	)
	(segment
		(start 168.215056 -288.953194)
		(end 167.872664 -288.126424)
		(width 0.18288)
		(layer "In2.Cu")
		(net "M_F_CPU1_SA_DQS_DN<2>")
	)
	(segment
		(start 157.973522 -285.155386)
		(end 157.973522 -285.139638)
		(width 0.16002)
		(layer "In2.Cu")
		(net "M_F_CPU1_SA_DQS_DN<2>")
	)
	(segment
		(start 159.905192 -286.051498)
		(end 159.888936 -286.051498)
		(width 0.16002)
		(layer "In2.Cu")
		(net "M_F_CPU1_SA_DQS_DN<2>")
	)
	(segment
		(start 167.417496 -287.671256)
		(end 167.008302 -287.501584)
		(width 0.18288)
		(layer "In2.Cu")
		(net "M_F_CPU1_SA_DQS_DN<2>")
	)
	(segment
		(start 139.661646 -268.08049)
		(end 139.661392 -268.080236)
		(width 0.088646)
		(layer "In2.Cu")
		(net "M_F_CPU1_SA_DQS_DN<2>")
	)
	(segment
		(start 158.15818 -285.340044)
		(end 157.973522 -285.155386)
		(width 0.16002)
		(layer "In2.Cu")
		(net "M_F_CPU1_SA_DQS_DN<2>")
	)
	(segment
		(start 159.888936 -286.051498)
		(end 159.704786 -285.867348)
		(width 0.16002)
		(layer "In2.Cu")
		(net "M_F_CPU1_SA_DQS_DN<2>")
	)
	(segment
		(start 159.933386 -286.079692)
		(end 159.905192 -286.051498)
		(width 0.16002)
		(layer "In2.Cu")
		(net "M_F_CPU1_SA_DQS_DN<2>")
	)
	(segment
		(start 164.705538 -287.651444)
		(end 164.600128 -287.546034)
		(width 0.18288)
		(layer "In2.Cu")
		(net "M_F_CPU1_SA_DQS_DN<2>")
	)
	(segment
		(start 169.836338 -293.87419)
		(end 169.780712 -293.818564)
		(width 0.18288)
		(layer "In2.Cu")
		(net "M_F_CPU1_SA_DQS_DN<2>")
	)
	(segment
		(start 160.438084 -286.13735)
		(end 159.991044 -286.13735)
		(width 0.18288)
		(layer "In2.Cu")
		(net "M_F_CPU1_SA_DQS_DN<2>")
	)
	(segment
		(start 157.442154 -284.747716)
		(end 155.876498 -283.18206)
		(width 0.18288)
		(layer "In2.Cu")
		(net "M_F_CPU1_SA_DQS_DN<2>")
	)
	(segment
		(start 169.552112 -293.605712)
		(end 169.552112 -293.589964)
		(width 0.16002)
		(layer "In2.Cu")
		(net "M_F_CPU1_SA_DQS_DN<2>")
	)
	(segment
		(start 159.991044 -286.13735)
		(end 159.933386 -286.079692)
		(width 0.18288)
		(layer "In2.Cu")
		(net "M_F_CPU1_SA_DQS_DN<2>")
	)
	(segment
		(start 140.900404 -268.160246)
		(end 140.840714 -268.219936)
		(width 0.088646)
		(layer "In2.Cu")
		(net "M_F_CPU1_SA_DQS_DN<2>")
	)
	(segment
		(start 133.465316 -267.698728)
		(end 133.408166 -267.755878)
		(width 0.088646)
		(layer "In2.Cu")
		(net "M_F_CPU1_SA_DQS_DN<2>")
	)
	(segment
		(start 147.977606 -272.344642)
		(end 147.672044 -272.218404)
		(width 0.18288)
		(layer "In2.Cu")
		(net "M_F_CPU1_SA_DQS_DN<2>")
	)
	(segment
		(start 165.71341 -287.501584)
		(end 165.35146 -287.651444)
		(width 0.18288)
		(layer "In2.Cu")
		(net "M_F_CPU1_SA_DQS_DN<2>")
	)
	(segment
		(start 142.806166 -268.278102)
		(end 142.521178 -268.160246)
		(width 0.18288)
		(layer "In2.Cu")
		(net "M_F_CPU1_SA_DQS_DN<2>")
	)
	(segment
		(start 172.058838 -293.408354)
		(end 171.543726 -293.408354)
		(width 0.18288)
		(layer "In2.Cu")
		(net "M_F_CPU1_SA_DQS_DN<2>")
	)
	(segment
		(start 159.676592 -285.822898)
		(end 159.375602 -285.521908)
		(width 0.18288)
		(layer "In2.Cu")
		(net "M_F_CPU1_SA_DQS_DN<2>")
	)
	(segment
		(start 172.583094 -293.57955)
		(end 172.230034 -293.57955)
		(width 0.18288)
		(layer "In2.Cu")
		(net "M_F_CPU1_SA_DQS_DN<2>")
	)
	(segment
		(start 157.945328 -285.111444)
		(end 157.5816 -284.747716)
		(width 0.18288)
		(layer "In2.Cu")
		(net "M_F_CPU1_SA_DQS_DN<2>")
	)
	(segment
		(start 164.600128 -287.546034)
		(end 163.960048 -287.546034)
		(width 0.18288)
		(layer "In2.Cu")
		(net "M_F_CPU1_SA_DQS_DN<2>")
	)
	(segment
		(start 158.355792 -285.521908)
		(end 158.202122 -285.368238)
		(width 0.18288)
		(layer "In2.Cu")
		(net "M_F_CPU1_SA_DQS_DN<2>")
	)
	(segment
		(start 171.367196 -293.584884)
		(end 171.339002 -293.613078)
		(width 0.16002)
		(layer "In2.Cu")
		(net "M_F_CPU1_SA_DQS_DN<2>")
	)
	(segment
		(start 171.07789 -293.87419)
		(end 169.836338 -293.87419)
		(width 0.18288)
		(layer "In2.Cu")
		(net "M_F_CPU1_SA_DQS_DN<2>")
	)
	(segment
		(start 151.153368 -276.927818)
		(end 150.158958 -274.526248)
		(width 0.18288)
		(layer "In2.Cu")
		(net "M_F_CPU1_SA_DQS_DN<2>")
	)
	(segment
		(start 140.544804 -268.219936)
		(end 140.329412 -268.004544)
		(width 0.088646)
		(layer "In2.Cu")
		(net "M_F_CPU1_SA_DQS_DN<2>")
	)
	(segment
		(start 163.701222 -287.80486)
		(end 162.105594 -287.80486)
		(width 0.18288)
		(layer "In2.Cu")
		(net "M_F_CPU1_SA_DQS_DN<2>")
	)
	(segment
		(start 155.876498 -283.18206)
		(end 155.876498 -281.98445)
		(width 0.18288)
		(layer "In2.Cu")
		(net "M_F_CPU1_SA_DQS_DN<2>")
	)
	(segment
		(start 167.008302 -287.501584)
		(end 165.71341 -287.501584)
		(width 0.18288)
		(layer "In2.Cu")
		(net "M_F_CPU1_SA_DQS_DN<2>")
	)
	(segment
		(start 147.672044 -272.218404)
		(end 146.74596 -272.218404)
		(width 0.18288)
		(layer "In2.Cu")
		(net "M_F_CPU1_SA_DQS_DN<2>")
	)
	(segment
		(start 155.876498 -281.98445)
		(end 155.640024 -281.414982)
		(width 0.18288)
		(layer "In2.Cu")
		(net "M_F_CPU1_SA_DQS_DN<2>")
	)
	(segment
		(start 146.74596 -272.218404)
		(end 142.806166 -268.278102)
		(width 0.18288)
		(layer "In2.Cu")
		(net "M_F_CPU1_SA_DQS_DN<2>")
	)
	(segment
		(start 171.339002 -293.628826)
		(end 171.154344 -293.813484)
		(width 0.16002)
		(layer "In2.Cu")
		(net "M_F_CPU1_SA_DQS_DN<2>")
	)
	(segment
		(start 140.329412 -268.004544)
		(end 139.94384 -268.004544)
		(width 0.088646)
		(layer "In2.Cu")
		(net "M_F_CPU1_SA_DQS_DN<2>")
	)
	(segment
		(start 157.973522 -285.139638)
		(end 157.945328 -285.111444)
		(width 0.16002)
		(layer "In2.Cu")
		(net "M_F_CPU1_SA_DQS_DN<2>")
	)
	(segment
		(start 155.640024 -281.414982)
		(end 151.153368 -276.927818)
		(width 0.18288)
		(layer "In2.Cu")
		(net "M_F_CPU1_SA_DQS_DN<2>")
	)
	(arc
		(start 139.661392 -268.080236)
		(mid 139.474194 -268.130379)
		(end 139.286996 -268.080236)
		(width 0.088646)
		(layer "In2.Cu")
		(net "M_F_CPU1_SA_DQS_DN<2>")
	)
	(arc
		(start 138.721592 -268.080236)
		(mid 138.534394 -268.130379)
		(end 138.347196 -268.080236)
		(width 0.088646)
		(layer "In2.Cu")
		(net "M_F_CPU1_SA_DQS_DN<2>")
	)
	(arc
		(start 136.841992 -268.080236)
		(mid 136.654794 -268.130379)
		(end 136.467596 -268.080236)
		(width 0.088646)
		(layer "In2.Cu")
		(net "M_F_CPU1_SA_DQS_DN<2>")
	)
	(arc
		(start 136.467596 -268.080236)
		(mid 136.184894 -268.00446)
		(end 135.902192 -268.080236)
		(width 0.088646)
		(layer "In2.Cu")
		(net "M_F_CPU1_SA_DQS_DN<2>")
	)
	(arc
		(start 137.407396 -268.080236)
		(mid 137.124694 -268.00446)
		(end 136.841992 -268.080236)
		(width 0.088646)
		(layer "In2.Cu")
		(net "M_F_CPU1_SA_DQS_DN<2>")
	)
	(arc
		(start 134.9629 -268.08049)
		(mid 134.782329 -268.130908)
		(end 134.599934 -268.087602)
		(width 0.088646)
		(layer "In2.Cu")
		(net "M_F_CPU1_SA_DQS_DN<2>")
	)
	(arc
		(start 138.347196 -268.080236)
		(mid 138.064494 -268.00446)
		(end 137.781792 -268.080236)
		(width 0.088646)
		(layer "In2.Cu")
		(net "M_F_CPU1_SA_DQS_DN<2>")
	)
	(arc
		(start 134.15899 -267.566902)
		(mid 134.093395 -267.483866)
		(end 134.007098 -267.42263)
		(width 0.088646)
		(layer "In2.Cu")
		(net "M_F_CPU1_SA_DQS_DN<2>")
	)
	(arc
		(start 139.286996 -268.080236)
		(mid 139.004294 -268.00446)
		(end 138.721592 -268.080236)
		(width 0.088646)
		(layer "In2.Cu")
		(net "M_F_CPU1_SA_DQS_DN<2>")
	)
	(arc
		(start 139.94384 -268.004544)
		(mid 139.797747 -268.023957)
		(end 139.661646 -268.08049)
		(width 0.088646)
		(layer "In2.Cu")
		(net "M_F_CPU1_SA_DQS_DN<2>")
	)
	(arc
		(start 135.513064 -268.0716)
		(mid 135.236762 -268.004278)
		(end 134.962646 -268.079982)
		(width 0.088646)
		(layer "In2.Cu")
		(net "M_F_CPU1_SA_DQS_DN<2>")
	)
	(arc
		(start 134.007098 -267.42263)
		(mid 133.665544 -267.421941)
		(end 133.465316 -267.698728)
		(width 0.088646)
		(layer "In2.Cu")
		(net "M_F_CPU1_SA_DQS_DN<2>")
	)
	(arc
		(start 135.902192 -268.080236)
		(mid 135.714994 -268.130379)
		(end 135.527796 -268.080236)
		(width 0.088646)
		(layer "In2.Cu")
		(net "M_F_CPU1_SA_DQS_DN<2>")
	)
	(arc
		(start 137.781792 -268.080236)
		(mid 137.594594 -268.130379)
		(end 137.407396 -268.080236)
		(width 0.088646)
		(layer "In2.Cu")
		(net "M_F_CPU1_SA_DQS_DN<2>")
	)
	(segment
		(start 180.614828 -302.95723)
		(end 180.855366 -302.716692)
		(width 0.20066)
		(layer "F.Cu")
		(net "M_F_CPU1_SA_DQS_DN<1>")
	)
	(segment
		(start 173.900846 -302.716692)
		(end 174.449486 -302.716692)
		(width 0.20066)
		(layer "F.Cu")
		(net "M_F_CPU1_SA_DQS_DN<1>")
	)
	(segment
		(start 176.826418 -303.141634)
		(end 179.005992 -303.141634)
		(width 0.1016)
		(layer "F.Cu")
		(net "M_F_CPU1_SA_DQS_DN<1>")
	)
	(segment
		(start 179.566824 -303.367694)
		(end 179.871878 -303.367694)
		(width 0.20066)
		(layer "F.Cu")
		(net "M_F_CPU1_SA_DQS_DN<1>")
	)
	(segment
		(start 172.795946 -302.716692)
		(end 173.900846 -302.716692)
		(width 0.20066)
		(layer "F.Cu")
		(net "M_F_CPU1_SA_DQS_DN<1>")
	)
	(segment
		(start 129.606294 -269.66164)
		(end 129.606548 -270.167862)
		(width 0.20066)
		(layer "F.Cu")
		(net "M_F_CPU1_SA_DQS_DN<1>")
	)
	(segment
		(start 176.674526 -303.141634)
		(end 176.8221 -303.141634)
		(width 0.20066)
		(layer "F.Cu")
		(net "M_F_CPU1_SA_DQS_DN<1>")
	)
	(segment
		(start 180.855366 -302.716692)
		(end 181.444646 -302.716692)
		(width 0.20066)
		(layer "F.Cu")
		(net "M_F_CPU1_SA_DQS_DN<1>")
	)
	(segment
		(start 179.011326 -303.1363)
		(end 179.33543 -303.1363)
		(width 0.20066)
		(layer "F.Cu")
		(net "M_F_CPU1_SA_DQS_DN<1>")
	)
	(segment
		(start 174.449486 -302.716692)
		(end 174.731172 -302.998378)
		(width 0.20066)
		(layer "F.Cu")
		(net "M_F_CPU1_SA_DQS_DN<1>")
	)
	(segment
		(start 175.46701 -302.998378)
		(end 175.881538 -303.412906)
		(width 0.20066)
		(layer "F.Cu")
		(net "M_F_CPU1_SA_DQS_DN<1>")
	)
	(segment
		(start 175.881538 -303.412906)
		(end 176.403254 -303.412906)
		(width 0.20066)
		(layer "F.Cu")
		(net "M_F_CPU1_SA_DQS_DN<1>")
	)
	(segment
		(start 179.33543 -303.1363)
		(end 179.566824 -303.367694)
		(width 0.20066)
		(layer "F.Cu")
		(net "M_F_CPU1_SA_DQS_DN<1>")
	)
	(segment
		(start 174.731172 -302.998378)
		(end 175.46701 -302.998378)
		(width 0.20066)
		(layer "F.Cu")
		(net "M_F_CPU1_SA_DQS_DN<1>")
	)
	(segment
		(start 179.871878 -303.367694)
		(end 180.282342 -302.95723)
		(width 0.20066)
		(layer "F.Cu")
		(net "M_F_CPU1_SA_DQS_DN<1>")
	)
	(segment
		(start 176.403254 -303.412906)
		(end 176.674526 -303.141634)
		(width 0.20066)
		(layer "F.Cu")
		(net "M_F_CPU1_SA_DQS_DN<1>")
	)
	(segment
		(start 176.8221 -303.141634)
		(end 176.826418 -303.141634)
		(width 0.101854)
		(layer "F.Cu")
		(net "M_F_CPU1_SA_DQS_DN<1>")
	)
	(segment
		(start 129.606548 -270.167862)
		(end 129.606548 -270.19758)
		(width 0.20066)
		(layer "F.Cu")
		(net "M_F_CPU1_SA_DQS_DN<1>")
	)
	(segment
		(start 180.282342 -302.95723)
		(end 180.614828 -302.95723)
		(width 0.20066)
		(layer "F.Cu")
		(net "M_F_CPU1_SA_DQS_DN<1>")
	)
	(segment
		(start 179.005992 -303.141634)
		(end 179.011326 -303.1363)
		(width 0.1016)
		(layer "F.Cu")
		(net "M_F_CPU1_SA_DQS_DN<1>")
	)
	(segment
		(start 136.387078 -270.513302)
		(end 136.372346 -270.521938)
		(width 0.088646)
		(layer "In4.Cu")
		(net "M_F_CPU1_SA_DQS_DN<1>")
	)
	(segment
		(start 172.795946 -302.716692)
		(end 172.535342 -302.977296)
		(width 0.18288)
		(layer "In4.Cu")
		(net "M_F_CPU1_SA_DQS_DN<1>")
	)
	(segment
		(start 167.377364 -302.79848)
		(end 165.974776 -301.395892)
		(width 0.18288)
		(layer "In4.Cu")
		(net "M_F_CPU1_SA_DQS_DN<1>")
	)
	(segment
		(start 138.345672 -271.334992)
		(end 138.338306 -271.330674)
		(width 0.088646)
		(layer "In4.Cu")
		(net "M_F_CPU1_SA_DQS_DN<1>")
	)
	(segment
		(start 139.38631 -271.26057)
		(end 139.003278 -271.26057)
		(width 0.088646)
		(layer "In4.Cu")
		(net "M_F_CPU1_SA_DQS_DN<1>")
	)
	(segment
		(start 134.491984 -270.522192)
		(end 134.4803 -270.529304)
		(width 0.088646)
		(layer "In4.Cu")
		(net "M_F_CPU1_SA_DQS_DN<1>")
	)
	(segment
		(start 161.635694 -298.892468)
		(end 161.357056 -299.171106)
		(width 0.18288)
		(layer "In4.Cu")
		(net "M_F_CPU1_SA_DQS_DN<1>")
	)
	(segment
		(start 139.948158 -271.992344)
		(end 139.71397 -271.758156)
		(width 0.088646)
		(layer "In4.Cu")
		(net "M_F_CPU1_SA_DQS_DN<1>")
	)
	(segment
		(start 137.326878 -270.513302)
		(end 137.312146 -270.521938)
		(width 0.088646)
		(layer "In4.Cu")
		(net "M_F_CPU1_SA_DQS_DN<1>")
	)
	(segment
		(start 131.614926 -270.549624)
		(end 131.614672 -270.549878)
		(width 0.088646)
		(layer "In4.Cu")
		(net "M_F_CPU1_SA_DQS_DN<1>")
	)
	(segment
		(start 135.447278 -270.513302)
		(end 135.432546 -270.521938)
		(width 0.088646)
		(layer "In4.Cu")
		(net "M_F_CPU1_SA_DQS_DN<1>")
	)
	(segment
		(start 142.679674 -274.077938)
		(end 142.11808 -274.077938)
		(width 0.18288)
		(layer "In4.Cu")
		(net "M_F_CPU1_SA_DQS_DN<1>")
	)
	(segment
		(start 130.934968 -270.109188)
		(end 130.935222 -270.108934)
		(width 0.088646)
		(layer "In4.Cu")
		(net "M_F_CPU1_SA_DQS_DN<1>")
	)
	(segment
		(start 162.64001 -299.168312)
		(end 162.277806 -299.168312)
		(width 0.18288)
		(layer "In4.Cu")
		(net "M_F_CPU1_SA_DQS_DN<1>")
	)
	(segment
		(start 135.432546 -270.521938)
		(end 135.4201 -270.529304)
		(width 0.088646)
		(layer "In4.Cu")
		(net "M_F_CPU1_SA_DQS_DN<1>")
	)
	(segment
		(start 131.298442 -270.522192)
		(end 131.298188 -270.522192)
		(width 0.088646)
		(layer "In4.Cu")
		(net "M_F_CPU1_SA_DQS_DN<1>")
	)
	(segment
		(start 161.357056 -299.171106)
		(end 161.01441 -299.171106)
		(width 0.18288)
		(layer "In4.Cu")
		(net "M_F_CPU1_SA_DQS_DN<1>")
	)
	(segment
		(start 139.71397 -271.58823)
		(end 139.38631 -271.26057)
		(width 0.088646)
		(layer "In4.Cu")
		(net "M_F_CPU1_SA_DQS_DN<1>")
	)
	(segment
		(start 162.277806 -299.168312)
		(end 162.001962 -298.892468)
		(width 0.18288)
		(layer "In4.Cu")
		(net "M_F_CPU1_SA_DQS_DN<1>")
	)
	(segment
		(start 160.830006 -298.337732)
		(end 158.990792 -296.498264)
		(width 0.18288)
		(layer "In4.Cu")
		(net "M_F_CPU1_SA_DQS_DN<1>")
	)
	(segment
		(start 130.889502 -270.04137)
		(end 130.872484 -270.011652)
		(width 0.088646)
		(layer "In4.Cu")
		(net "M_F_CPU1_SA_DQS_DN<1>")
	)
	(segment
		(start 172.535342 -302.977296)
		(end 172.208698 -302.977296)
		(width 0.18288)
		(layer "In4.Cu")
		(net "M_F_CPU1_SA_DQS_DN<1>")
	)
	(segment
		(start 131.261104 -270.500602)
		(end 131.224274 -270.471646)
		(width 0.088646)
		(layer "In4.Cu")
		(net "M_F_CPU1_SA_DQS_DN<1>")
	)
	(segment
		(start 139.71397 -271.758156)
		(end 139.71397 -271.58823)
		(width 0.088646)
		(layer "In4.Cu")
		(net "M_F_CPU1_SA_DQS_DN<1>")
	)
	(segment
		(start 130.17627 -270.14043)
		(end 130.11912 -270.19758)
		(width 0.088646)
		(layer "In4.Cu")
		(net "M_F_CPU1_SA_DQS_DN<1>")
	)
	(segment
		(start 140.048996 -272.008854)
		(end 139.948158 -271.992344)
		(width 0.088646)
		(layer "In4.Cu")
		(net "M_F_CPU1_SA_DQS_DN<1>")
	)
	(segment
		(start 158.990792 -296.498264)
		(end 157.33395 -295.81221)
		(width 0.18288)
		(layer "In4.Cu")
		(net "M_F_CPU1_SA_DQS_DN<1>")
	)
	(segment
		(start 161.01441 -299.171106)
		(end 160.830006 -298.986702)
		(width 0.18288)
		(layer "In4.Cu")
		(net "M_F_CPU1_SA_DQS_DN<1>")
	)
	(segment
		(start 138.722354 -271.336008)
		(end 138.721592 -271.335754)
		(width 0.088646)
		(layer "In4.Cu")
		(net "M_F_CPU1_SA_DQS_DN<1>")
	)
	(segment
		(start 172.208698 -302.977296)
		(end 172.029882 -302.79848)
		(width 0.18288)
		(layer "In4.Cu")
		(net "M_F_CPU1_SA_DQS_DN<1>")
	)
	(segment
		(start 138.347196 -271.335754)
		(end 138.345672 -271.334992)
		(width 0.088646)
		(layer "In4.Cu")
		(net "M_F_CPU1_SA_DQS_DN<1>")
	)
	(segment
		(start 131.636262 -270.542004)
		(end 131.615942 -270.54937)
		(width 0.088646)
		(layer "In4.Cu")
		(net "M_F_CPU1_SA_DQS_DN<1>")
	)
	(segment
		(start 132.24256 -270.524224)
		(end 132.23875 -270.521938)
		(width 0.088646)
		(layer "In4.Cu")
		(net "M_F_CPU1_SA_DQS_DN<1>")
	)
	(segment
		(start 148.048726 -279.44699)
		(end 142.679674 -274.077938)
		(width 0.18288)
		(layer "In4.Cu")
		(net "M_F_CPU1_SA_DQS_DN<1>")
	)
	(segment
		(start 131.298188 -270.522192)
		(end 131.261104 -270.500602)
		(width 0.088646)
		(layer "In4.Cu")
		(net "M_F_CPU1_SA_DQS_DN<1>")
	)
	(segment
		(start 142.11808 -274.077938)
		(end 140.048996 -272.008854)
		(width 0.18288)
		(layer "In4.Cu")
		(net "M_F_CPU1_SA_DQS_DN<1>")
	)
	(segment
		(start 131.688078 -270.513302)
		(end 131.673346 -270.521938)
		(width 0.088646)
		(layer "In4.Cu")
		(net "M_F_CPU1_SA_DQS_DN<1>")
	)
	(segment
		(start 162.001962 -298.892468)
		(end 161.635694 -298.892468)
		(width 0.18288)
		(layer "In4.Cu")
		(net "M_F_CPU1_SA_DQS_DN<1>")
	)
	(segment
		(start 131.615942 -270.54937)
		(end 131.614926 -270.549624)
		(width 0.088646)
		(layer "In4.Cu")
		(net "M_F_CPU1_SA_DQS_DN<1>")
	)
	(segment
		(start 133.18236 -270.524224)
		(end 133.170422 -270.517366)
		(width 0.088646)
		(layer "In4.Cu")
		(net "M_F_CPU1_SA_DQS_DN<1>")
	)
	(segment
		(start 160.830006 -298.986702)
		(end 160.830006 -298.337732)
		(width 0.18288)
		(layer "In4.Cu")
		(net "M_F_CPU1_SA_DQS_DN<1>")
	)
	(segment
		(start 130.718814 -269.86484)
		(end 130.718052 -269.864332)
		(width 0.088646)
		(layer "In4.Cu")
		(net "M_F_CPU1_SA_DQS_DN<1>")
	)
	(segment
		(start 130.11912 -270.19758)
		(end 129.606548 -270.19758)
		(width 0.088646)
		(layer "In4.Cu")
		(net "M_F_CPU1_SA_DQS_DN<1>")
	)
	(segment
		(start 172.029882 -302.79848)
		(end 167.377364 -302.79848)
		(width 0.18288)
		(layer "In4.Cu")
		(net "M_F_CPU1_SA_DQS_DN<1>")
	)
	(segment
		(start 138.159744 -271.011396)
		(end 138.159744 -270.995902)
		(width 0.088646)
		(layer "In4.Cu")
		(net "M_F_CPU1_SA_DQS_DN<1>")
	)
	(segment
		(start 131.672584 -270.5227)
		(end 131.642612 -270.53921)
		(width 0.088646)
		(layer "In4.Cu")
		(net "M_F_CPU1_SA_DQS_DN<1>")
	)
	(segment
		(start 131.224274 -270.471646)
		(end 130.934968 -270.109188)
		(width 0.088646)
		(layer "In4.Cu")
		(net "M_F_CPU1_SA_DQS_DN<1>")
	)
	(segment
		(start 157.33395 -295.81221)
		(end 153.056082 -291.534596)
		(width 0.18288)
		(layer "In4.Cu")
		(net "M_F_CPU1_SA_DQS_DN<1>")
	)
	(segment
		(start 153.056082 -291.534596)
		(end 148.048726 -279.44699)
		(width 0.18288)
		(layer "In4.Cu")
		(net "M_F_CPU1_SA_DQS_DN<1>")
	)
	(segment
		(start 131.673346 -270.521938)
		(end 131.672584 -270.5227)
		(width 0.088646)
		(layer "In4.Cu")
		(net "M_F_CPU1_SA_DQS_DN<1>")
	)
	(segment
		(start 165.974776 -301.395892)
		(end 162.64001 -299.168312)
		(width 0.18288)
		(layer "In4.Cu")
		(net "M_F_CPU1_SA_DQS_DN<1>")
	)
	(arc
		(start 137.87755 -270.521938)
		(mid 137.603351 -270.446103)
		(end 137.326878 -270.513302)
		(width 0.088646)
		(layer "In4.Cu")
		(net "M_F_CPU1_SA_DQS_DN<1>")
	)
	(arc
		(start 130.935222 -270.108934)
		(mid 130.91102 -270.076059)
		(end 130.889502 -270.04137)
		(width 0.088646)
		(layer "In4.Cu")
		(net "M_F_CPU1_SA_DQS_DN<1>")
	)
	(arc
		(start 135.4201 -270.529304)
		(mid 135.23804 -270.572324)
		(end 135.057896 -270.521938)
		(width 0.088646)
		(layer "In4.Cu")
		(net "M_F_CPU1_SA_DQS_DN<1>")
	)
	(arc
		(start 134.4803 -270.529304)
		(mid 134.29824 -270.572324)
		(end 134.118096 -270.521938)
		(width 0.088646)
		(layer "In4.Cu")
		(net "M_F_CPU1_SA_DQS_DN<1>")
	)
	(arc
		(start 136.372346 -270.521938)
		(mid 136.185148 -270.572081)
		(end 135.99795 -270.521938)
		(width 0.088646)
		(layer "In4.Cu")
		(net "M_F_CPU1_SA_DQS_DN<1>")
	)
	(arc
		(start 132.613146 -270.521938)
		(mid 132.428169 -270.572075)
		(end 132.24256 -270.524224)
		(width 0.088646)
		(layer "In4.Cu")
		(net "M_F_CPU1_SA_DQS_DN<1>")
	)
	(arc
		(start 136.93775 -270.521938)
		(mid 136.663551 -270.446103)
		(end 136.387078 -270.513302)
		(width 0.088646)
		(layer "In4.Cu")
		(net "M_F_CPU1_SA_DQS_DN<1>")
	)
	(arc
		(start 132.23875 -270.521938)
		(mid 131.964551 -270.446103)
		(end 131.688078 -270.513302)
		(width 0.088646)
		(layer "In4.Cu")
		(net "M_F_CPU1_SA_DQS_DN<1>")
	)
	(arc
		(start 138.159744 -270.995902)
		(mid 138.080374 -270.722168)
		(end 137.87755 -270.521938)
		(width 0.088646)
		(layer "In4.Cu")
		(net "M_F_CPU1_SA_DQS_DN<1>")
	)
	(arc
		(start 137.312146 -270.521938)
		(mid 137.124948 -270.572081)
		(end 136.93775 -270.521938)
		(width 0.088646)
		(layer "In4.Cu")
		(net "M_F_CPU1_SA_DQS_DN<1>")
	)
	(arc
		(start 135.99795 -270.521938)
		(mid 135.723751 -270.446103)
		(end 135.447278 -270.513302)
		(width 0.088646)
		(layer "In4.Cu")
		(net "M_F_CPU1_SA_DQS_DN<1>")
	)
	(arc
		(start 138.721592 -271.335754)
		(mid 138.534394 -271.385897)
		(end 138.347196 -271.335754)
		(width 0.088646)
		(layer "In4.Cu")
		(net "M_F_CPU1_SA_DQS_DN<1>")
	)
	(arc
		(start 133.170422 -270.517366)
		(mid 132.891185 -270.44621)
		(end 132.613146 -270.521938)
		(width 0.088646)
		(layer "In4.Cu")
		(net "M_F_CPU1_SA_DQS_DN<1>")
	)
	(arc
		(start 134.118096 -270.521938)
		(mid 133.835538 -270.446289)
		(end 133.552946 -270.521938)
		(width 0.088646)
		(layer "In4.Cu")
		(net "M_F_CPU1_SA_DQS_DN<1>")
	)
	(arc
		(start 139.003278 -271.26057)
		(mid 138.857873 -271.279884)
		(end 138.722354 -271.336008)
		(width 0.088646)
		(layer "In4.Cu")
		(net "M_F_CPU1_SA_DQS_DN<1>")
	)
	(arc
		(start 138.338306 -271.330674)
		(mid 138.207392 -271.194314)
		(end 138.159744 -271.011396)
		(width 0.088646)
		(layer "In4.Cu")
		(net "M_F_CPU1_SA_DQS_DN<1>")
	)
	(arc
		(start 130.872484 -270.011652)
		(mid 130.806305 -269.927092)
		(end 130.718814 -269.86484)
		(width 0.088646)
		(layer "In4.Cu")
		(net "M_F_CPU1_SA_DQS_DN<1>")
	)
	(arc
		(start 131.614672 -270.549878)
		(mid 131.453478 -270.571164)
		(end 131.298442 -270.522192)
		(width 0.088646)
		(layer "In4.Cu")
		(net "M_F_CPU1_SA_DQS_DN<1>")
	)
	(arc
		(start 131.642612 -270.53921)
		(mid 131.639483 -270.540712)
		(end 131.636262 -270.542004)
		(width 0.088646)
		(layer "In4.Cu")
		(net "M_F_CPU1_SA_DQS_DN<1>")
	)
	(arc
		(start 130.718052 -269.864332)
		(mid 130.376498 -269.863643)
		(end 130.17627 -270.14043)
		(width 0.088646)
		(layer "In4.Cu")
		(net "M_F_CPU1_SA_DQS_DN<1>")
	)
	(arc
		(start 135.057896 -270.521938)
		(mid 134.774911 -270.446162)
		(end 134.491984 -270.522192)
		(width 0.088646)
		(layer "In4.Cu")
		(net "M_F_CPU1_SA_DQS_DN<1>")
	)
	(arc
		(start 133.552946 -270.521938)
		(mid 133.367969 -270.572075)
		(end 133.18236 -270.524224)
		(width 0.088646)
		(layer "In4.Cu")
		(net "M_F_CPU1_SA_DQS_DN<1>")
	)
	(segment
		(start 133.835648 -276.986492)
		(end 133.835648 -277.522178)
		(width 0.20066)
		(layer "F.Cu")
		(net "M_F_CPU1_SA_DQS_DN<0>")
	)
	(segment
		(start 174.449486 -312.066686)
		(end 174.731172 -312.348372)
		(width 0.20066)
		(layer "F.Cu")
		(net "M_F_CPU1_SA_DQS_DN<0>")
	)
	(segment
		(start 173.900846 -312.066686)
		(end 174.449486 -312.066686)
		(width 0.20066)
		(layer "F.Cu")
		(net "M_F_CPU1_SA_DQS_DN<0>")
	)
	(segment
		(start 176.8221 -312.491628)
		(end 176.826418 -312.491628)
		(width 0.101854)
		(layer "F.Cu")
		(net "M_F_CPU1_SA_DQS_DN<0>")
	)
	(segment
		(start 180.855366 -312.066686)
		(end 181.444646 -312.066686)
		(width 0.20066)
		(layer "F.Cu")
		(net "M_F_CPU1_SA_DQS_DN<0>")
	)
	(segment
		(start 180.282342 -312.307224)
		(end 180.614828 -312.307224)
		(width 0.20066)
		(layer "F.Cu")
		(net "M_F_CPU1_SA_DQS_DN<0>")
	)
	(segment
		(start 179.33543 -312.486294)
		(end 179.566824 -312.717688)
		(width 0.20066)
		(layer "F.Cu")
		(net "M_F_CPU1_SA_DQS_DN<0>")
	)
	(segment
		(start 180.614828 -312.307224)
		(end 180.855366 -312.066686)
		(width 0.20066)
		(layer "F.Cu")
		(net "M_F_CPU1_SA_DQS_DN<0>")
	)
	(segment
		(start 179.871878 -312.717688)
		(end 180.282342 -312.307224)
		(width 0.20066)
		(layer "F.Cu")
		(net "M_F_CPU1_SA_DQS_DN<0>")
	)
	(segment
		(start 179.566824 -312.717688)
		(end 179.871878 -312.717688)
		(width 0.20066)
		(layer "F.Cu")
		(net "M_F_CPU1_SA_DQS_DN<0>")
	)
	(segment
		(start 179.005992 -312.491628)
		(end 179.011326 -312.486294)
		(width 0.1016)
		(layer "F.Cu")
		(net "M_F_CPU1_SA_DQS_DN<0>")
	)
	(segment
		(start 175.46701 -312.348372)
		(end 175.881538 -312.7629)
		(width 0.20066)
		(layer "F.Cu")
		(net "M_F_CPU1_SA_DQS_DN<0>")
	)
	(segment
		(start 174.731172 -312.348372)
		(end 175.46701 -312.348372)
		(width 0.20066)
		(layer "F.Cu")
		(net "M_F_CPU1_SA_DQS_DN<0>")
	)
	(segment
		(start 176.826418 -312.491628)
		(end 179.005992 -312.491628)
		(width 0.1016)
		(layer "F.Cu")
		(net "M_F_CPU1_SA_DQS_DN<0>")
	)
	(segment
		(start 179.011326 -312.486294)
		(end 179.33543 -312.486294)
		(width 0.20066)
		(layer "F.Cu")
		(net "M_F_CPU1_SA_DQS_DN<0>")
	)
	(segment
		(start 176.403254 -312.7629)
		(end 176.674526 -312.491628)
		(width 0.20066)
		(layer "F.Cu")
		(net "M_F_CPU1_SA_DQS_DN<0>")
	)
	(segment
		(start 175.881538 -312.7629)
		(end 176.403254 -312.7629)
		(width 0.20066)
		(layer "F.Cu")
		(net "M_F_CPU1_SA_DQS_DN<0>")
	)
	(segment
		(start 133.835648 -277.522178)
		(end 133.835394 -277.522432)
		(width 0.20066)
		(layer "F.Cu")
		(net "M_F_CPU1_SA_DQS_DN<0>")
	)
	(segment
		(start 172.795946 -312.066686)
		(end 173.900846 -312.066686)
		(width 0.20066)
		(layer "F.Cu")
		(net "M_F_CPU1_SA_DQS_DN<0>")
	)
	(segment
		(start 176.674526 -312.491628)
		(end 176.8221 -312.491628)
		(width 0.20066)
		(layer "F.Cu")
		(net "M_F_CPU1_SA_DQS_DN<0>")
	)
	(segment
		(start 143.207994 -289.812222)
		(end 143.207994 -283.897578)
		(width 0.18288)
		(layer "In2.Cu")
		(net "M_F_CPU1_SA_DQS_DN<0>")
	)
	(segment
		(start 162.44697 -312.75401)
		(end 162.13709 -312.44413)
		(width 0.18288)
		(layer "In2.Cu")
		(net "M_F_CPU1_SA_DQS_DN<0>")
	)
	(segment
		(start 171.521882 -312.163968)
		(end 171.121832 -312.564018)
		(width 0.18288)
		(layer "In2.Cu")
		(net "M_F_CPU1_SA_DQS_DN<0>")
	)
	(segment
		(start 163.76142 -312.75401)
		(end 162.44697 -312.75401)
		(width 0.18288)
		(layer "In2.Cu")
		(net "M_F_CPU1_SA_DQS_DN<0>")
	)
	(segment
		(start 168.076118 -312.792364)
		(end 167.630602 -312.792364)
		(width 0.18288)
		(layer "In2.Cu")
		(net "M_F_CPU1_SA_DQS_DN<0>")
	)
	(segment
		(start 148.119338 -301.968408)
		(end 148.119338 -301.419768)
		(width 0.18288)
		(layer "In2.Cu")
		(net "M_F_CPU1_SA_DQS_DN<0>")
	)
	(segment
		(start 158.05531 -313.289696)
		(end 158.039562 -313.289696)
		(width 0.16002)
		(layer "In2.Cu")
		(net "M_F_CPU1_SA_DQS_DN<0>")
	)
	(segment
		(start 167.008556 -313.41441)
		(end 165.714934 -313.41441)
		(width 0.18288)
		(layer "In2.Cu")
		(net "M_F_CPU1_SA_DQS_DN<0>")
	)
	(segment
		(start 147.994878 -302.092868)
		(end 148.119338 -301.968408)
		(width 0.18288)
		(layer "In2.Cu")
		(net "M_F_CPU1_SA_DQS_DN<0>")
	)
	(segment
		(start 167.333676 -313.105038)
		(end 167.149018 -313.289696)
		(width 0.16002)
		(layer "In2.Cu")
		(net "M_F_CPU1_SA_DQS_DN<0>")
	)
	(segment
		(start 147.994878 -301.295308)
		(end 147.994878 -300.746668)
		(width 0.18288)
		(layer "In2.Cu")
		(net "M_F_CPU1_SA_DQS_DN<0>")
	)
	(segment
		(start 167.36187 -313.061096)
		(end 167.333676 -313.08929)
		(width 0.16002)
		(layer "In2.Cu")
		(net "M_F_CPU1_SA_DQS_DN<0>")
	)
	(segment
		(start 169.606468 -312.35396)
		(end 169.606468 -312.337704)
		(width 0.16002)
		(layer "In2.Cu")
		(net "M_F_CPU1_SA_DQS_DN<0>")
	)
	(segment
		(start 172.356526 -312.321702)
		(end 172.198792 -312.163968)
		(width 0.18288)
		(layer "In2.Cu")
		(net "M_F_CPU1_SA_DQS_DN<0>")
	)
	(segment
		(start 164.391594 -312.478166)
		(end 164.037264 -312.478166)
		(width 0.18288)
		(layer "In2.Cu")
		(net "M_F_CPU1_SA_DQS_DN<0>")
	)
	(segment
		(start 148.119338 -301.419768)
		(end 147.994878 -301.295308)
		(width 0.18288)
		(layer "In2.Cu")
		(net "M_F_CPU1_SA_DQS_DN<0>")
	)
	(segment
		(start 143.207994 -283.897578)
		(end 142.032736 -282.72232)
		(width 0.18288)
		(layer "In2.Cu")
		(net "M_F_CPU1_SA_DQS_DN<0>")
	)
	(segment
		(start 147.994878 -302.641508)
		(end 147.994878 -302.092868)
		(width 0.18288)
		(layer "In2.Cu")
		(net "M_F_CPU1_SA_DQS_DN<0>")
	)
	(segment
		(start 140.317982 -279.360122)
		(end 140.233654 -279.360122)
		(width 0.088646)
		(layer "In2.Cu")
		(net "M_F_CPU1_SA_DQS_DN<0>")
	)
	(segment
		(start 136.937496 -278.66086)
		(end 136.922764 -278.652224)
		(width 0.088646)
		(layer "In2.Cu")
		(net "M_F_CPU1_SA_DQS_DN<0>")
	)
	(segment
		(start 135.810244 -278.336502)
		(end 135.810244 -278.322278)
		(width 0.088646)
		(layer "In2.Cu")
		(net "M_F_CPU1_SA_DQS_DN<0>")
	)
	(segment
		(start 147.994878 -298.602908)
		(end 147.994878 -297.890184)
		(width 0.18288)
		(layer "In2.Cu")
		(net "M_F_CPU1_SA_DQS_DN<0>")
	)
	(segment
		(start 139.595352 -278.72182)
		(end 139.043918 -278.72182)
		(width 0.088646)
		(layer "In2.Cu")
		(net "M_F_CPU1_SA_DQS_DN<0>")
	)
	(segment
		(start 162.13709 -312.44413)
		(end 162.108896 -312.415936)
		(width 0.16002)
		(layer "In2.Cu")
		(net "M_F_CPU1_SA_DQS_DN<0>")
	)
	(segment
		(start 164.037264 -312.478166)
		(end 163.76142 -312.75401)
		(width 0.18288)
		(layer "In2.Cu")
		(net "M_F_CPU1_SA_DQS_DN<0>")
	)
	(segment
		(start 169.765218 -312.496454)
		(end 169.748962 -312.496454)
		(width 0.16002)
		(layer "In2.Cu")
		(net "M_F_CPU1_SA_DQS_DN<0>")
	)
	(segment
		(start 165.040056 -312.739532)
		(end 164.65296 -312.739532)
		(width 0.18288)
		(layer "In2.Cu")
		(net "M_F_CPU1_SA_DQS_DN<0>")
	)
	(segment
		(start 157.265624 -312.50001)
		(end 156.50718 -312.50001)
		(width 0.18288)
		(layer "In2.Cu")
		(net "M_F_CPU1_SA_DQS_DN<0>")
	)
	(segment
		(start 157.82671 -313.061096)
		(end 157.265624 -312.50001)
		(width 0.18288)
		(layer "In2.Cu")
		(net "M_F_CPU1_SA_DQS_DN<0>")
	)
	(segment
		(start 167.105076 -313.31789)
		(end 167.008556 -313.41441)
		(width 0.18288)
		(layer "In2.Cu")
		(net "M_F_CPU1_SA_DQS_DN<0>")
	)
	(segment
		(start 133.465316 -277.579582)
		(end 133.522466 -277.522432)
		(width 0.088646)
		(layer "In2.Cu")
		(net "M_F_CPU1_SA_DQS_DN<0>")
	)
	(segment
		(start 148.119338 -298.727368)
		(end 147.994878 -298.602908)
		(width 0.18288)
		(layer "In2.Cu")
		(net "M_F_CPU1_SA_DQS_DN<0>")
	)
	(segment
		(start 148.119338 -299.276008)
		(end 148.119338 -298.727368)
		(width 0.18288)
		(layer "In2.Cu")
		(net "M_F_CPU1_SA_DQS_DN<0>")
	)
	(segment
		(start 140.867384 -279.909778)
		(end 140.317982 -279.360122)
		(width 0.18288)
		(layer "In2.Cu")
		(net "M_F_CPU1_SA_DQS_DN<0>")
	)
	(segment
		(start 167.630602 -312.792364)
		(end 167.36187 -313.061096)
		(width 0.18288)
		(layer "In2.Cu")
		(net "M_F_CPU1_SA_DQS_DN<0>")
	)
	(segment
		(start 161.67989 -311.98693)
		(end 160.948624 -311.98693)
		(width 0.18288)
		(layer "In2.Cu")
		(net "M_F_CPU1_SA_DQS_DN<0>")
	)
	(segment
		(start 162.108896 -312.415936)
		(end 162.093148 -312.415936)
		(width 0.16002)
		(layer "In2.Cu")
		(net "M_F_CPU1_SA_DQS_DN<0>")
	)
	(segment
		(start 147.994878 -299.949108)
		(end 147.994878 -299.400468)
		(width 0.18288)
		(layer "In2.Cu")
		(net "M_F_CPU1_SA_DQS_DN<0>")
	)
	(segment
		(start 133.648196 -277.84679)
		(end 133.639306 -277.84171)
		(width 0.088646)
		(layer "In2.Cu")
		(net "M_F_CPU1_SA_DQS_DN<0>")
	)
	(segment
		(start 169.793412 -312.524648)
		(end 169.765218 -312.496454)
		(width 0.16002)
		(layer "In2.Cu")
		(net "M_F_CPU1_SA_DQS_DN<0>")
	)
	(segment
		(start 156.50718 -312.50001)
		(end 147.994878 -303.987708)
		(width 0.18288)
		(layer "In2.Cu")
		(net "M_F_CPU1_SA_DQS_DN<0>")
	)
	(segment
		(start 165.59022 -313.289696)
		(end 165.574472 -313.289696)
		(width 0.16002)
		(layer "In2.Cu")
		(net "M_F_CPU1_SA_DQS_DN<0>")
	)
	(segment
		(start 167.149018 -313.289696)
		(end 167.13327 -313.289696)
		(width 0.16002)
		(layer "In2.Cu")
		(net "M_F_CPU1_SA_DQS_DN<0>")
	)
	(segment
		(start 147.994878 -297.890184)
		(end 146.61134 -294.549068)
		(width 0.18288)
		(layer "In2.Cu")
		(net "M_F_CPU1_SA_DQS_DN<0>")
	)
	(segment
		(start 137.877296 -278.66086)
		(end 137.862564 -278.652224)
		(width 0.088646)
		(layer "In2.Cu")
		(net "M_F_CPU1_SA_DQS_DN<0>")
	)
	(segment
		(start 144.151096 -292.089078)
		(end 143.207994 -289.812222)
		(width 0.18288)
		(layer "In2.Cu")
		(net "M_F_CPU1_SA_DQS_DN<0>")
	)
	(segment
		(start 158.039562 -313.289696)
		(end 157.854904 -313.105038)
		(width 0.16002)
		(layer "In2.Cu")
		(net "M_F_CPU1_SA_DQS_DN<0>")
	)
	(segment
		(start 138.814556 -278.659336)
		(end 138.804904 -278.654002)
		(width 0.088646)
		(layer "In2.Cu")
		(net "M_F_CPU1_SA_DQS_DN<0>")
	)
	(segment
		(start 140.233654 -279.360122)
		(end 139.595352 -278.72182)
		(width 0.088646)
		(layer "In2.Cu")
		(net "M_F_CPU1_SA_DQS_DN<0>")
	)
	(segment
		(start 138.816588 -278.660606)
		(end 138.814556 -278.659336)
		(width 0.088646)
		(layer "In2.Cu")
		(net "M_F_CPU1_SA_DQS_DN<0>")
	)
	(segment
		(start 148.119338 -300.073568)
		(end 147.994878 -299.949108)
		(width 0.18288)
		(layer "In2.Cu")
		(net "M_F_CPU1_SA_DQS_DN<0>")
	)
	(segment
		(start 135.527542 -277.84679)
		(end 135.517128 -277.840694)
		(width 0.088646)
		(layer "In2.Cu")
		(net "M_F_CPU1_SA_DQS_DN<0>")
	)
	(segment
		(start 165.389814 -313.08929)
		(end 165.36162 -313.061096)
		(width 0.16002)
		(layer "In2.Cu")
		(net "M_F_CPU1_SA_DQS_DN<0>")
	)
	(segment
		(start 161.90849 -312.21553)
		(end 161.880296 -312.187336)
		(width 0.16002)
		(layer "In2.Cu")
		(net "M_F_CPU1_SA_DQS_DN<0>")
	)
	(segment
		(start 165.714934 -313.41441)
		(end 165.618414 -313.31789)
		(width 0.18288)
		(layer "In2.Cu")
		(net "M_F_CPU1_SA_DQS_DN<0>")
	)
	(segment
		(start 157.854904 -313.105038)
		(end 157.854904 -313.08929)
		(width 0.16002)
		(layer "In2.Cu")
		(net "M_F_CPU1_SA_DQS_DN<0>")
	)
	(segment
		(start 159.549084 -313.38647)
		(end 158.152084 -313.38647)
		(width 0.18288)
		(layer "In2.Cu")
		(net "M_F_CPU1_SA_DQS_DN<0>")
	)
	(segment
		(start 165.574472 -313.289696)
		(end 165.389814 -313.105038)
		(width 0.16002)
		(layer "In2.Cu")
		(net "M_F_CPU1_SA_DQS_DN<0>")
	)
	(segment
		(start 146.61134 -294.549068)
		(end 144.151096 -292.089078)
		(width 0.18288)
		(layer "In2.Cu")
		(net "M_F_CPU1_SA_DQS_DN<0>")
	)
	(segment
		(start 158.083504 -313.31789)
		(end 158.05531 -313.289696)
		(width 0.16002)
		(layer "In2.Cu")
		(net "M_F_CPU1_SA_DQS_DN<0>")
	)
	(segment
		(start 165.36162 -313.061096)
		(end 165.040056 -312.739532)
		(width 0.18288)
		(layer "In2.Cu")
		(net "M_F_CPU1_SA_DQS_DN<0>")
	)
	(segment
		(start 138.804904 -278.654002)
		(end 138.802364 -278.652478)
		(width 0.088646)
		(layer "In2.Cu")
		(net "M_F_CPU1_SA_DQS_DN<0>")
	)
	(segment
		(start 161.880296 -312.187336)
		(end 161.67989 -311.98693)
		(width 0.18288)
		(layer "In2.Cu")
		(net "M_F_CPU1_SA_DQS_DN<0>")
	)
	(segment
		(start 160.948624 -311.98693)
		(end 159.549084 -313.38647)
		(width 0.18288)
		(layer "In2.Cu")
		(net "M_F_CPU1_SA_DQS_DN<0>")
	)
	(segment
		(start 164.65296 -312.739532)
		(end 164.391594 -312.478166)
		(width 0.18288)
		(layer "In2.Cu")
		(net "M_F_CPU1_SA_DQS_DN<0>")
	)
	(segment
		(start 147.994878 -299.400468)
		(end 148.119338 -299.276008)
		(width 0.18288)
		(layer "In2.Cu")
		(net "M_F_CPU1_SA_DQS_DN<0>")
	)
	(segment
		(start 167.333676 -313.08929)
		(end 167.333676 -313.105038)
		(width 0.16002)
		(layer "In2.Cu")
		(net "M_F_CPU1_SA_DQS_DN<0>")
	)
	(segment
		(start 148.119338 -302.765968)
		(end 147.994878 -302.641508)
		(width 0.18288)
		(layer "In2.Cu")
		(net "M_F_CPU1_SA_DQS_DN<0>")
	)
	(segment
		(start 169.748962 -312.496454)
		(end 169.606468 -312.35396)
		(width 0.16002)
		(layer "In2.Cu")
		(net "M_F_CPU1_SA_DQS_DN<0>")
	)
	(segment
		(start 169.351706 -312.082942)
		(end 168.78554 -312.082942)
		(width 0.18288)
		(layer "In2.Cu")
		(net "M_F_CPU1_SA_DQS_DN<0>")
	)
	(segment
		(start 165.618414 -313.31789)
		(end 165.59022 -313.289696)
		(width 0.16002)
		(layer "In2.Cu")
		(net "M_F_CPU1_SA_DQS_DN<0>")
	)
	(segment
		(start 165.389814 -313.105038)
		(end 165.389814 -313.08929)
		(width 0.16002)
		(layer "In2.Cu")
		(net "M_F_CPU1_SA_DQS_DN<0>")
	)
	(segment
		(start 169.832782 -312.564018)
		(end 169.793412 -312.524648)
		(width 0.18288)
		(layer "In2.Cu")
		(net "M_F_CPU1_SA_DQS_DN<0>")
	)
	(segment
		(start 169.578274 -312.30951)
		(end 169.351706 -312.082942)
		(width 0.18288)
		(layer "In2.Cu")
		(net "M_F_CPU1_SA_DQS_DN<0>")
	)
	(segment
		(start 147.994878 -300.746668)
		(end 148.119338 -300.622208)
		(width 0.18288)
		(layer "In2.Cu")
		(net "M_F_CPU1_SA_DQS_DN<0>")
	)
	(segment
		(start 169.606468 -312.337704)
		(end 169.578274 -312.30951)
		(width 0.16002)
		(layer "In2.Cu")
		(net "M_F_CPU1_SA_DQS_DN<0>")
	)
	(segment
		(start 148.119338 -300.622208)
		(end 148.119338 -300.073568)
		(width 0.18288)
		(layer "In2.Cu")
		(net "M_F_CPU1_SA_DQS_DN<0>")
	)
	(segment
		(start 168.78554 -312.082942)
		(end 168.076118 -312.792364)
		(width 0.18288)
		(layer "In2.Cu")
		(net "M_F_CPU1_SA_DQS_DN<0>")
	)
	(segment
		(start 157.854904 -313.08929)
		(end 157.82671 -313.061096)
		(width 0.16002)
		(layer "In2.Cu")
		(net "M_F_CPU1_SA_DQS_DN<0>")
	)
	(segment
		(start 167.13327 -313.289696)
		(end 167.105076 -313.31789)
		(width 0.16002)
		(layer "In2.Cu")
		(net "M_F_CPU1_SA_DQS_DN<0>")
	)
	(segment
		(start 147.994878 -303.439068)
		(end 148.119338 -303.314608)
		(width 0.18288)
		(layer "In2.Cu")
		(net "M_F_CPU1_SA_DQS_DN<0>")
	)
	(segment
		(start 158.152084 -313.38647)
		(end 158.083504 -313.31789)
		(width 0.18288)
		(layer "In2.Cu")
		(net "M_F_CPU1_SA_DQS_DN<0>")
	)
	(segment
		(start 147.994878 -303.987708)
		(end 147.994878 -303.439068)
		(width 0.18288)
		(layer "In2.Cu")
		(net "M_F_CPU1_SA_DQS_DN<0>")
	)
	(segment
		(start 162.093148 -312.415936)
		(end 161.90849 -312.231278)
		(width 0.16002)
		(layer "In2.Cu")
		(net "M_F_CPU1_SA_DQS_DN<0>")
	)
	(segment
		(start 133.522466 -277.522432)
		(end 133.835394 -277.522432)
		(width 0.088646)
		(layer "In2.Cu")
		(net "M_F_CPU1_SA_DQS_DN<0>")
	)
	(segment
		(start 135.997696 -278.66086)
		(end 135.988806 -278.65578)
		(width 0.088646)
		(layer "In2.Cu")
		(net "M_F_CPU1_SA_DQS_DN<0>")
	)
	(segment
		(start 172.54093 -312.321702)
		(end 172.356526 -312.321702)
		(width 0.18288)
		(layer "In2.Cu")
		(net "M_F_CPU1_SA_DQS_DN<0>")
	)
	(segment
		(start 138.251946 -278.66086)
		(end 138.251692 -278.66086)
		(width 0.088646)
		(layer "In2.Cu")
		(net "M_F_CPU1_SA_DQS_DN<0>")
	)
	(segment
		(start 171.121832 -312.564018)
		(end 169.832782 -312.564018)
		(width 0.18288)
		(layer "In2.Cu")
		(net "M_F_CPU1_SA_DQS_DN<0>")
	)
	(segment
		(start 142.032736 -282.72232)
		(end 140.867384 -279.909778)
		(width 0.18288)
		(layer "In2.Cu")
		(net "M_F_CPU1_SA_DQS_DN<0>")
	)
	(segment
		(start 172.198792 -312.163968)
		(end 171.521882 -312.163968)
		(width 0.18288)
		(layer "In2.Cu")
		(net "M_F_CPU1_SA_DQS_DN<0>")
	)
	(segment
		(start 161.90849 -312.231278)
		(end 161.90849 -312.21553)
		(width 0.16002)
		(layer "In2.Cu")
		(net "M_F_CPU1_SA_DQS_DN<0>")
	)
	(segment
		(start 172.795946 -312.066686)
		(end 172.54093 -312.321702)
		(width 0.18288)
		(layer "In2.Cu")
		(net "M_F_CPU1_SA_DQS_DN<0>")
	)
	(segment
		(start 148.119338 -303.314608)
		(end 148.119338 -302.765968)
		(width 0.18288)
		(layer "In2.Cu")
		(net "M_F_CPU1_SA_DQS_DN<0>")
	)
	(arc
		(start 135.810244 -278.322278)
		(mid 135.731025 -278.047593)
		(end 135.527542 -277.84679)
		(width 0.088646)
		(layer "In2.Cu")
		(net "M_F_CPU1_SA_DQS_DN<0>")
	)
	(arc
		(start 133.639306 -277.84171)
		(mid 133.523497 -277.729781)
		(end 133.465316 -277.579582)
		(width 0.088646)
		(layer "In2.Cu")
		(net "M_F_CPU1_SA_DQS_DN<0>")
	)
	(arc
		(start 134.022592 -277.84679)
		(mid 133.835394 -277.896933)
		(end 133.648196 -277.84679)
		(width 0.088646)
		(layer "In2.Cu")
		(net "M_F_CPU1_SA_DQS_DN<0>")
	)
	(arc
		(start 138.802364 -278.652478)
		(mid 138.526062 -278.585125)
		(end 138.251946 -278.66086)
		(width 0.088646)
		(layer "In2.Cu")
		(net "M_F_CPU1_SA_DQS_DN<0>")
	)
	(arc
		(start 136.922764 -278.652224)
		(mid 136.646289 -278.584904)
		(end 136.372092 -278.66086)
		(width 0.088646)
		(layer "In2.Cu")
		(net "M_F_CPU1_SA_DQS_DN<0>")
	)
	(arc
		(start 134.962392 -277.84679)
		(mid 134.775194 -277.896933)
		(end 134.587996 -277.84679)
		(width 0.088646)
		(layer "In2.Cu")
		(net "M_F_CPU1_SA_DQS_DN<0>")
	)
	(arc
		(start 139.043918 -278.72182)
		(mid 138.926225 -278.706178)
		(end 138.816588 -278.660606)
		(width 0.088646)
		(layer "In2.Cu")
		(net "M_F_CPU1_SA_DQS_DN<0>")
	)
	(arc
		(start 136.372092 -278.66086)
		(mid 136.184894 -278.711003)
		(end 135.997696 -278.66086)
		(width 0.088646)
		(layer "In2.Cu")
		(net "M_F_CPU1_SA_DQS_DN<0>")
	)
	(arc
		(start 137.862564 -278.652224)
		(mid 137.586089 -278.584904)
		(end 137.311892 -278.66086)
		(width 0.088646)
		(layer "In2.Cu")
		(net "M_F_CPU1_SA_DQS_DN<0>")
	)
	(arc
		(start 134.587996 -277.84679)
		(mid 134.305294 -277.771048)
		(end 134.022592 -277.84679)
		(width 0.088646)
		(layer "In2.Cu")
		(net "M_F_CPU1_SA_DQS_DN<0>")
	)
	(arc
		(start 137.311892 -278.66086)
		(mid 137.124694 -278.711003)
		(end 136.937496 -278.66086)
		(width 0.088646)
		(layer "In2.Cu")
		(net "M_F_CPU1_SA_DQS_DN<0>")
	)
	(arc
		(start 135.517128 -277.840694)
		(mid 135.23895 -277.771002)
		(end 134.962392 -277.84679)
		(width 0.088646)
		(layer "In2.Cu")
		(net "M_F_CPU1_SA_DQS_DN<0>")
	)
	(arc
		(start 135.988806 -278.65578)
		(mid 135.857892 -278.51942)
		(end 135.810244 -278.336502)
		(width 0.088646)
		(layer "In2.Cu")
		(net "M_F_CPU1_SA_DQS_DN<0>")
	)
	(arc
		(start 138.251692 -278.66086)
		(mid 138.064494 -278.711003)
		(end 137.877296 -278.66086)
		(width 0.088646)
		(layer "In2.Cu")
		(net "M_F_CPU1_SA_DQS_DN<0>")
	)
	(segment
		(start 175.67021 -305.515264)
		(end 175.421544 -305.266598)
		(width 0.20066)
		(layer "F.Cu")
		(net "M_F_CPU1_SA_DQ<9>")
	)
	(segment
		(start 181.444392 -305.266852)
		(end 179.852828 -305.266852)
		(width 0.20066)
		(layer "F.Cu")
		(net "M_F_CPU1_SA_DQ<9>")
	)
	(segment
		(start 130.076448 -271.011142)
		(end 130.076194 -271.011396)
		(width 0.20066)
		(layer "F.Cu")
		(net "M_F_CPU1_SA_DQ<9>")
	)
	(segment
		(start 179.004976 -304.841656)
		(end 176.816258 -304.841656)
		(width 0.1016)
		(layer "F.Cu")
		(net "M_F_CPU1_SA_DQ<9>")
	)
	(segment
		(start 176.145444 -305.515264)
		(end 175.67021 -305.515264)
		(width 0.20066)
		(layer "F.Cu")
		(net "M_F_CPU1_SA_DQ<9>")
	)
	(segment
		(start 179.421282 -304.835306)
		(end 179.011326 -304.835306)
		(width 0.20066)
		(layer "F.Cu")
		(net "M_F_CPU1_SA_DQ<9>")
	)
	(segment
		(start 181.444646 -305.266598)
		(end 181.444392 -305.266852)
		(width 0.20066)
		(layer "F.Cu")
		(net "M_F_CPU1_SA_DQ<9>")
	)
	(segment
		(start 175.421544 -305.266598)
		(end 173.900846 -305.266598)
		(width 0.20066)
		(layer "F.Cu")
		(net "M_F_CPU1_SA_DQ<9>")
	)
	(segment
		(start 176.451514 -304.841656)
		(end 176.333404 -304.959766)
		(width 0.20066)
		(layer "F.Cu")
		(net "M_F_CPU1_SA_DQ<9>")
	)
	(segment
		(start 176.333404 -305.327304)
		(end 176.145444 -305.515264)
		(width 0.20066)
		(layer "F.Cu")
		(net "M_F_CPU1_SA_DQ<9>")
	)
	(segment
		(start 176.796192 -304.841656)
		(end 176.451514 -304.841656)
		(width 0.20066)
		(layer "F.Cu")
		(net "M_F_CPU1_SA_DQ<9>")
	)
	(segment
		(start 176.816258 -304.841656)
		(end 176.796192 -304.841656)
		(width 0.101854)
		(layer "F.Cu")
		(net "M_F_CPU1_SA_DQ<9>")
	)
	(segment
		(start 130.076448 -270.475456)
		(end 130.076448 -271.011142)
		(width 0.20066)
		(layer "F.Cu")
		(net "M_F_CPU1_SA_DQ<9>")
	)
	(segment
		(start 173.900846 -305.266598)
		(end 172.795946 -305.266598)
		(width 0.20066)
		(layer "F.Cu")
		(net "M_F_CPU1_SA_DQ<9>")
	)
	(segment
		(start 179.852828 -305.266852)
		(end 179.421282 -304.835306)
		(width 0.20066)
		(layer "F.Cu")
		(net "M_F_CPU1_SA_DQ<9>")
	)
	(segment
		(start 176.333404 -304.959766)
		(end 176.333404 -305.327304)
		(width 0.20066)
		(layer "F.Cu")
		(net "M_F_CPU1_SA_DQ<9>")
	)
	(segment
		(start 179.011326 -304.835306)
		(end 179.004976 -304.841656)
		(width 0.1016)
		(layer "F.Cu")
		(net "M_F_CPU1_SA_DQ<9>")
	)
	(segment
		(start 167.194484 -304.939446)
		(end 165.203124 -302.948086)
		(width 0.18288)
		(layer "In4.Cu")
		(net "M_F_CPU1_SA_DQ<9>")
	)
	(segment
		(start 163.889436 -302.533812)
		(end 163.487862 -302.935386)
		(width 0.18288)
		(layer "In4.Cu")
		(net "M_F_CPU1_SA_DQ<9>")
	)
	(segment
		(start 130.733546 -271.500854)
		(end 130.65506 -271.455642)
		(width 0.088646)
		(layer "In4.Cu")
		(net "M_F_CPU1_SA_DQ<9>")
	)
	(segment
		(start 139.191746 -273.005296)
		(end 138.909044 -272.722594)
		(width 0.088646)
		(layer "In4.Cu")
		(net "M_F_CPU1_SA_DQ<9>")
	)
	(segment
		(start 139.452604 -273.005296)
		(end 139.191746 -273.005296)
		(width 0.088646)
		(layer "In4.Cu")
		(net "M_F_CPU1_SA_DQ<9>")
	)
	(segment
		(start 139.563094 -273.005296)
		(end 139.452604 -273.005296)
		(width 0.18288)
		(layer "In4.Cu")
		(net "M_F_CPU1_SA_DQ<9>")
	)
	(segment
		(start 159.40278 -299.439076)
		(end 157.933898 -297.970194)
		(width 0.18288)
		(layer "In4.Cu")
		(net "M_F_CPU1_SA_DQ<9>")
	)
	(segment
		(start 163.398962 -301.784766)
		(end 163.05657 -301.442374)
		(width 0.18288)
		(layer "In4.Cu")
		(net "M_F_CPU1_SA_DQ<9>")
	)
	(segment
		(start 131.304538 -271.497552)
		(end 131.298696 -271.500854)
		(width 0.088646)
		(layer "In4.Cu")
		(net "M_F_CPU1_SA_DQ<9>")
	)
	(segment
		(start 138.730482 -272.320004)
		(end 138.721592 -272.314924)
		(width 0.088646)
		(layer "In4.Cu")
		(net "M_F_CPU1_SA_DQ<9>")
	)
	(segment
		(start 159.761174 -300.705266)
		(end 159.40278 -300.346872)
		(width 0.18288)
		(layer "In4.Cu")
		(net "M_F_CPU1_SA_DQ<9>")
	)
	(segment
		(start 165.203124 -302.948086)
		(end 164.562282 -302.948086)
		(width 0.18288)
		(layer "In4.Cu")
		(net "M_F_CPU1_SA_DQ<9>")
	)
	(segment
		(start 151.995632 -292.557962)
		(end 146.843496 -280.119074)
		(width 0.18288)
		(layer "In4.Cu")
		(net "M_F_CPU1_SA_DQ<9>")
	)
	(segment
		(start 135.447278 -271.50949)
		(end 135.432546 -271.500854)
		(width 0.088646)
		(layer "In4.Cu")
		(net "M_F_CPU1_SA_DQ<9>")
	)
	(segment
		(start 172.795946 -305.266598)
		(end 172.349414 -305.71313)
		(width 0.18288)
		(layer "In4.Cu")
		(net "M_F_CPU1_SA_DQ<9>")
	)
	(segment
		(start 163.398962 -302.043338)
		(end 163.398962 -301.784766)
		(width 0.18288)
		(layer "In4.Cu")
		(net "M_F_CPU1_SA_DQ<9>")
	)
	(segment
		(start 135.057896 -271.500854)
		(end 135.052054 -271.50441)
		(width 0.088646)
		(layer "In4.Cu")
		(net "M_F_CPU1_SA_DQ<9>")
	)
	(segment
		(start 133.184138 -271.497552)
		(end 133.178296 -271.500854)
		(width 0.088646)
		(layer "In4.Cu")
		(net "M_F_CPU1_SA_DQ<9>")
	)
	(segment
		(start 134.118096 -271.500854)
		(end 134.112254 -271.50441)
		(width 0.088646)
		(layer "In4.Cu")
		(net "M_F_CPU1_SA_DQ<9>")
	)
	(segment
		(start 132.238496 -271.500854)
		(end 132.232654 -271.50441)
		(width 0.088646)
		(layer "In4.Cu")
		(net "M_F_CPU1_SA_DQ<9>")
	)
	(segment
		(start 162.997388 -302.444912)
		(end 163.398962 -302.043338)
		(width 0.18288)
		(layer "In4.Cu")
		(net "M_F_CPU1_SA_DQ<9>")
	)
	(segment
		(start 133.178296 -271.500854)
		(end 133.172454 -271.50441)
		(width 0.088646)
		(layer "In4.Cu")
		(net "M_F_CPU1_SA_DQ<9>")
	)
	(segment
		(start 168.127426 -304.939446)
		(end 167.194484 -304.939446)
		(width 0.18288)
		(layer "In4.Cu")
		(net "M_F_CPU1_SA_DQ<9>")
	)
	(segment
		(start 137.321036 -271.505934)
		(end 137.312146 -271.500854)
		(width 0.088646)
		(layer "In4.Cu")
		(net "M_F_CPU1_SA_DQ<9>")
	)
	(segment
		(start 157.933898 -297.970194)
		(end 157.407864 -297.970194)
		(width 0.18288)
		(layer "In4.Cu")
		(net "M_F_CPU1_SA_DQ<9>")
	)
	(segment
		(start 132.244338 -271.497552)
		(end 132.238496 -271.500854)
		(width 0.088646)
		(layer "In4.Cu")
		(net "M_F_CPU1_SA_DQ<9>")
	)
	(segment
		(start 163.487862 -302.935386)
		(end 163.22929 -302.935386)
		(width 0.18288)
		(layer "In4.Cu")
		(net "M_F_CPU1_SA_DQ<9>")
	)
	(segment
		(start 163.22929 -302.935386)
		(end 162.997388 -302.703484)
		(width 0.18288)
		(layer "In4.Cu")
		(net "M_F_CPU1_SA_DQ<9>")
	)
	(segment
		(start 160.581086 -300.705266)
		(end 159.761174 -300.705266)
		(width 0.18288)
		(layer "In4.Cu")
		(net "M_F_CPU1_SA_DQ<9>")
	)
	(segment
		(start 146.843496 -280.119074)
		(end 141.800326 -275.075904)
		(width 0.18288)
		(layer "In4.Cu")
		(net "M_F_CPU1_SA_DQ<9>")
	)
	(segment
		(start 164.562282 -302.948086)
		(end 164.148008 -302.533812)
		(width 0.18288)
		(layer "In4.Cu")
		(net "M_F_CPU1_SA_DQ<9>")
	)
	(segment
		(start 138.347196 -272.314924)
		(end 138.332464 -272.32356)
		(width 0.088646)
		(layer "In4.Cu")
		(net "M_F_CPU1_SA_DQ<9>")
	)
	(segment
		(start 163.05657 -301.442374)
		(end 161.318194 -301.442374)
		(width 0.18288)
		(layer "In4.Cu")
		(net "M_F_CPU1_SA_DQ<9>")
	)
	(segment
		(start 172.349414 -305.71313)
		(end 171.29887 -305.71313)
		(width 0.18288)
		(layer "In4.Cu")
		(net "M_F_CPU1_SA_DQ<9>")
	)
	(segment
		(start 136.387078 -271.50949)
		(end 136.372346 -271.500854)
		(width 0.088646)
		(layer "In4.Cu")
		(net "M_F_CPU1_SA_DQ<9>")
	)
	(segment
		(start 171.29887 -305.71313)
		(end 170.338496 -304.752756)
		(width 0.18288)
		(layer "In4.Cu")
		(net "M_F_CPU1_SA_DQ<9>")
	)
	(segment
		(start 141.633702 -275.075904)
		(end 139.563094 -273.005296)
		(width 0.18288)
		(layer "In4.Cu")
		(net "M_F_CPU1_SA_DQ<9>")
	)
	(segment
		(start 138.909044 -272.722594)
		(end 138.909044 -272.639282)
		(width 0.088646)
		(layer "In4.Cu")
		(net "M_F_CPU1_SA_DQ<9>")
	)
	(segment
		(start 135.061706 -271.498822)
		(end 135.057896 -271.500854)
		(width 0.088646)
		(layer "In4.Cu")
		(net "M_F_CPU1_SA_DQ<9>")
	)
	(segment
		(start 137.499598 -271.84731)
		(end 137.499598 -271.825212)
		(width 0.088646)
		(layer "In4.Cu")
		(net "M_F_CPU1_SA_DQ<9>")
	)
	(segment
		(start 134.123938 -271.497552)
		(end 134.118096 -271.500854)
		(width 0.088646)
		(layer "In4.Cu")
		(net "M_F_CPU1_SA_DQ<9>")
	)
	(segment
		(start 141.800326 -275.075904)
		(end 141.633702 -275.075904)
		(width 0.18288)
		(layer "In4.Cu")
		(net "M_F_CPU1_SA_DQ<9>")
	)
	(segment
		(start 159.40278 -300.346872)
		(end 159.40278 -299.439076)
		(width 0.18288)
		(layer "In4.Cu")
		(net "M_F_CPU1_SA_DQ<9>")
	)
	(segment
		(start 164.148008 -302.533812)
		(end 163.889436 -302.533812)
		(width 0.18288)
		(layer "In4.Cu")
		(net "M_F_CPU1_SA_DQ<9>")
	)
	(segment
		(start 170.338496 -304.752756)
		(end 168.314116 -304.752756)
		(width 0.18288)
		(layer "In4.Cu")
		(net "M_F_CPU1_SA_DQ<9>")
	)
	(segment
		(start 168.314116 -304.752756)
		(end 168.127426 -304.939446)
		(width 0.18288)
		(layer "In4.Cu")
		(net "M_F_CPU1_SA_DQ<9>")
	)
	(segment
		(start 157.407864 -297.970194)
		(end 151.995632 -292.557962)
		(width 0.18288)
		(layer "In4.Cu")
		(net "M_F_CPU1_SA_DQ<9>")
	)
	(segment
		(start 162.997388 -302.703484)
		(end 162.997388 -302.444912)
		(width 0.18288)
		(layer "In4.Cu")
		(net "M_F_CPU1_SA_DQ<9>")
	)
	(segment
		(start 161.318194 -301.442374)
		(end 160.581086 -300.705266)
		(width 0.18288)
		(layer "In4.Cu")
		(net "M_F_CPU1_SA_DQ<9>")
	)
	(segment
		(start 131.298696 -271.500854)
		(end 131.292854 -271.50441)
		(width 0.088646)
		(layer "In4.Cu")
		(net "M_F_CPU1_SA_DQ<9>")
	)
	(arc
		(start 137.499598 -271.825212)
		(mid 137.451919 -271.642312)
		(end 137.321036 -271.505934)
		(width 0.088646)
		(layer "In4.Cu")
		(net "M_F_CPU1_SA_DQ<9>")
	)
	(arc
		(start 132.613146 -271.500854)
		(mid 132.429192 -271.450725)
		(end 132.244338 -271.497552)
		(width 0.088646)
		(layer "In4.Cu")
		(net "M_F_CPU1_SA_DQ<9>")
	)
	(arc
		(start 133.172454 -271.50441)
		(mid 132.892319 -271.576693)
		(end 132.613146 -271.500854)
		(width 0.088646)
		(layer "In4.Cu")
		(net "M_F_CPU1_SA_DQ<9>")
	)
	(arc
		(start 138.332464 -272.32356)
		(mid 138.056023 -272.390726)
		(end 137.781792 -272.314924)
		(width 0.088646)
		(layer "In4.Cu")
		(net "M_F_CPU1_SA_DQ<9>")
	)
	(arc
		(start 134.492746 -271.500854)
		(mid 134.308792 -271.450725)
		(end 134.123938 -271.497552)
		(width 0.088646)
		(layer "In4.Cu")
		(net "M_F_CPU1_SA_DQ<9>")
	)
	(arc
		(start 136.93775 -271.500854)
		(mid 136.663551 -271.576689)
		(end 136.387078 -271.50949)
		(width 0.088646)
		(layer "In4.Cu")
		(net "M_F_CPU1_SA_DQ<9>")
	)
	(arc
		(start 130.65506 -271.455642)
		(mid 130.350962 -271.252629)
		(end 130.076194 -271.011396)
		(width 0.088646)
		(layer "In4.Cu")
		(net "M_F_CPU1_SA_DQ<9>")
	)
	(arc
		(start 137.312146 -271.500854)
		(mid 137.124948 -271.450711)
		(end 136.93775 -271.500854)
		(width 0.088646)
		(layer "In4.Cu")
		(net "M_F_CPU1_SA_DQ<9>")
	)
	(arc
		(start 131.292854 -271.50441)
		(mid 131.012719 -271.576693)
		(end 130.733546 -271.500854)
		(width 0.088646)
		(layer "In4.Cu")
		(net "M_F_CPU1_SA_DQ<9>")
	)
	(arc
		(start 135.432546 -271.500854)
		(mid 135.247396 -271.450716)
		(end 135.061706 -271.498822)
		(width 0.088646)
		(layer "In4.Cu")
		(net "M_F_CPU1_SA_DQ<9>")
	)
	(arc
		(start 133.552946 -271.500854)
		(mid 133.368992 -271.450725)
		(end 133.184138 -271.497552)
		(width 0.088646)
		(layer "In4.Cu")
		(net "M_F_CPU1_SA_DQ<9>")
	)
	(arc
		(start 135.99795 -271.500854)
		(mid 135.723751 -271.576689)
		(end 135.447278 -271.50949)
		(width 0.088646)
		(layer "In4.Cu")
		(net "M_F_CPU1_SA_DQ<9>")
	)
	(arc
		(start 138.909044 -272.639282)
		(mid 138.861365 -272.456382)
		(end 138.730482 -272.320004)
		(width 0.088646)
		(layer "In4.Cu")
		(net "M_F_CPU1_SA_DQ<9>")
	)
	(arc
		(start 134.112254 -271.50441)
		(mid 133.832119 -271.576693)
		(end 133.552946 -271.500854)
		(width 0.088646)
		(layer "In4.Cu")
		(net "M_F_CPU1_SA_DQ<9>")
	)
	(arc
		(start 137.781792 -272.314924)
		(mid 137.58051 -272.117437)
		(end 137.499598 -271.84731)
		(width 0.088646)
		(layer "In4.Cu")
		(net "M_F_CPU1_SA_DQ<9>")
	)
	(arc
		(start 136.372346 -271.500854)
		(mid 136.185148 -271.450711)
		(end 135.99795 -271.500854)
		(width 0.088646)
		(layer "In4.Cu")
		(net "M_F_CPU1_SA_DQ<9>")
	)
	(arc
		(start 131.673346 -271.500854)
		(mid 131.489392 -271.450725)
		(end 131.304538 -271.497552)
		(width 0.088646)
		(layer "In4.Cu")
		(net "M_F_CPU1_SA_DQ<9>")
	)
	(arc
		(start 138.721592 -272.314924)
		(mid 138.534394 -272.264781)
		(end 138.347196 -272.314924)
		(width 0.088646)
		(layer "In4.Cu")
		(net "M_F_CPU1_SA_DQ<9>")
	)
	(arc
		(start 132.232654 -271.50441)
		(mid 131.952519 -271.576693)
		(end 131.673346 -271.500854)
		(width 0.088646)
		(layer "In4.Cu")
		(net "M_F_CPU1_SA_DQ<9>")
	)
	(arc
		(start 135.052054 -271.50441)
		(mid 134.771919 -271.576693)
		(end 134.492746 -271.500854)
		(width 0.088646)
		(layer "In4.Cu")
		(net "M_F_CPU1_SA_DQ<9>")
	)
	(segment
		(start 176.843182 -306.541678)
		(end 176.796192 -306.541678)
		(width 0.101854)
		(layer "F.Cu")
		(net "M_F_CPU1_SA_DQ<8>")
	)
	(segment
		(start 179.004976 -306.541678)
		(end 176.843182 -306.541678)
		(width 0.1016)
		(layer "F.Cu")
		(net "M_F_CPU1_SA_DQ<8>")
	)
	(segment
		(start 176.451514 -306.541678)
		(end 176.333404 -306.659788)
		(width 0.20066)
		(layer "F.Cu")
		(net "M_F_CPU1_SA_DQ<8>")
	)
	(segment
		(start 179.852828 -306.966874)
		(end 179.421282 -306.535328)
		(width 0.20066)
		(layer "F.Cu")
		(net "M_F_CPU1_SA_DQ<8>")
	)
	(segment
		(start 176.796192 -306.541678)
		(end 176.451514 -306.541678)
		(width 0.20066)
		(layer "F.Cu")
		(net "M_F_CPU1_SA_DQ<8>")
	)
	(segment
		(start 176.145444 -307.215286)
		(end 175.67021 -307.215286)
		(width 0.20066)
		(layer "F.Cu")
		(net "M_F_CPU1_SA_DQ<8>")
	)
	(segment
		(start 176.333404 -307.027326)
		(end 176.145444 -307.215286)
		(width 0.20066)
		(layer "F.Cu")
		(net "M_F_CPU1_SA_DQ<8>")
	)
	(segment
		(start 179.421282 -306.535328)
		(end 179.011326 -306.535328)
		(width 0.20066)
		(layer "F.Cu")
		(net "M_F_CPU1_SA_DQ<8>")
	)
	(segment
		(start 181.444646 -306.96662)
		(end 181.444392 -306.966874)
		(width 0.20066)
		(layer "F.Cu")
		(net "M_F_CPU1_SA_DQ<8>")
	)
	(segment
		(start 173.900846 -306.96662)
		(end 172.795946 -306.96662)
		(width 0.20066)
		(layer "F.Cu")
		(net "M_F_CPU1_SA_DQ<8>")
	)
	(segment
		(start 176.333404 -306.659788)
		(end 176.333404 -307.027326)
		(width 0.20066)
		(layer "F.Cu")
		(net "M_F_CPU1_SA_DQ<8>")
	)
	(segment
		(start 179.011326 -306.535328)
		(end 179.004976 -306.541678)
		(width 0.1016)
		(layer "F.Cu")
		(net "M_F_CPU1_SA_DQ<8>")
	)
	(segment
		(start 130.546094 -271.289272)
		(end 130.546348 -271.825212)
		(width 0.20066)
		(layer "F.Cu")
		(net "M_F_CPU1_SA_DQ<8>")
	)
	(segment
		(start 175.421544 -306.96662)
		(end 173.900846 -306.96662)
		(width 0.20066)
		(layer "F.Cu")
		(net "M_F_CPU1_SA_DQ<8>")
	)
	(segment
		(start 175.67021 -307.215286)
		(end 175.421544 -306.96662)
		(width 0.20066)
		(layer "F.Cu")
		(net "M_F_CPU1_SA_DQ<8>")
	)
	(segment
		(start 181.444392 -306.966874)
		(end 179.852828 -306.966874)
		(width 0.20066)
		(layer "F.Cu")
		(net "M_F_CPU1_SA_DQ<8>")
	)
	(segment
		(start 140.793724 -275.417534)
		(end 139.376404 -274.000214)
		(width 0.18288)
		(layer "In4.Cu")
		(net "M_F_CPU1_SA_DQ<8>")
	)
	(segment
		(start 164.593016 -304.828956)
		(end 163.523676 -304.828956)
		(width 0.18288)
		(layer "In4.Cu")
		(net "M_F_CPU1_SA_DQ<8>")
	)
	(segment
		(start 169.935906 -308.152292)
		(end 169.935906 -307.654706)
		(width 0.18288)
		(layer "In4.Cu")
		(net "M_F_CPU1_SA_DQ<8>")
	)
	(segment
		(start 170.118786 -308.335172)
		(end 169.935906 -308.152292)
		(width 0.18288)
		(layer "In4.Cu")
		(net "M_F_CPU1_SA_DQ<8>")
	)
	(segment
		(start 137.029444 -272.649188)
		(end 137.029444 -272.639282)
		(width 0.088646)
		(layer "In4.Cu")
		(net "M_F_CPU1_SA_DQ<8>")
	)
	(segment
		(start 133.090412 -272.318988)
		(end 133.083046 -272.31467)
		(width 0.088646)
		(layer "In4.Cu")
		(net "M_F_CPU1_SA_DQ<8>")
	)
	(segment
		(start 138.926062 -273.80311)
		(end 138.251692 -273.12874)
		(width 0.088646)
		(layer "In4.Cu")
		(net "M_F_CPU1_SA_DQ<8>")
	)
	(segment
		(start 170.629326 -307.654706)
		(end 170.629326 -308.152292)
		(width 0.18288)
		(layer "In4.Cu")
		(net "M_F_CPU1_SA_DQ<8>")
	)
	(segment
		(start 139.376404 -274.000214)
		(end 139.1793 -273.80311)
		(width 0.088646)
		(layer "In4.Cu")
		(net "M_F_CPU1_SA_DQ<8>")
	)
	(segment
		(start 170.446446 -308.335172)
		(end 170.118786 -308.335172)
		(width 0.18288)
		(layer "In4.Cu")
		(net "M_F_CPU1_SA_DQ<8>")
	)
	(segment
		(start 140.793724 -275.496274)
		(end 140.793724 -275.417534)
		(width 0.18288)
		(layer "In4.Cu")
		(net "M_F_CPU1_SA_DQ<8>")
	)
	(segment
		(start 136.850882 -272.320004)
		(end 136.841992 -272.314924)
		(width 0.088646)
		(layer "In4.Cu")
		(net "M_F_CPU1_SA_DQ<8>")
	)
	(segment
		(start 169.753026 -307.471826)
		(end 169.16019 -307.471826)
		(width 0.18288)
		(layer "In4.Cu")
		(net "M_F_CPU1_SA_DQ<8>")
	)
	(segment
		(start 134.962646 -272.31467)
		(end 134.958074 -272.31213)
		(width 0.088646)
		(layer "In4.Cu")
		(net "M_F_CPU1_SA_DQ<8>")
	)
	(segment
		(start 134.967218 -272.317464)
		(end 134.962646 -272.31467)
		(width 0.088646)
		(layer "In4.Cu")
		(net "M_F_CPU1_SA_DQ<8>")
	)
	(segment
		(start 168.42232 -306.733956)
		(end 167.353996 -306.733956)
		(width 0.18288)
		(layer "In4.Cu")
		(net "M_F_CPU1_SA_DQ<8>")
	)
	(segment
		(start 170.629326 -308.152292)
		(end 170.446446 -308.335172)
		(width 0.18288)
		(layer "In4.Cu")
		(net "M_F_CPU1_SA_DQ<8>")
	)
	(segment
		(start 163.523676 -304.828956)
		(end 162.687 -303.99228)
		(width 0.18288)
		(layer "In4.Cu")
		(net "M_F_CPU1_SA_DQ<8>")
	)
	(segment
		(start 161.473642 -303.99228)
		(end 158.071566 -300.590204)
		(width 0.18288)
		(layer "In4.Cu")
		(net "M_F_CPU1_SA_DQ<8>")
	)
	(segment
		(start 132.150612 -272.318988)
		(end 132.143246 -272.31467)
		(width 0.088646)
		(layer "In4.Cu")
		(net "M_F_CPU1_SA_DQ<8>")
	)
	(segment
		(start 139.1793 -273.80311)
		(end 138.926062 -273.80311)
		(width 0.088646)
		(layer "In4.Cu")
		(net "M_F_CPU1_SA_DQ<8>")
	)
	(segment
		(start 169.16019 -307.471826)
		(end 168.42232 -306.733956)
		(width 0.18288)
		(layer "In4.Cu")
		(net "M_F_CPU1_SA_DQ<8>")
	)
	(segment
		(start 133.083046 -272.31467)
		(end 133.078474 -272.31213)
		(width 0.088646)
		(layer "In4.Cu")
		(net "M_F_CPU1_SA_DQ<8>")
	)
	(segment
		(start 172.795946 -306.96662)
		(end 172.522896 -307.23967)
		(width 0.18288)
		(layer "In4.Cu")
		(net "M_F_CPU1_SA_DQ<8>")
	)
	(segment
		(start 169.935906 -307.654706)
		(end 169.753026 -307.471826)
		(width 0.18288)
		(layer "In4.Cu")
		(net "M_F_CPU1_SA_DQ<8>")
	)
	(segment
		(start 157.520894 -300.590204)
		(end 151.67102 -294.74033)
		(width 0.18288)
		(layer "In4.Cu")
		(net "M_F_CPU1_SA_DQ<8>")
	)
	(segment
		(start 151.67102 -294.74033)
		(end 145.756376 -280.458926)
		(width 0.18288)
		(layer "In4.Cu")
		(net "M_F_CPU1_SA_DQ<8>")
	)
	(segment
		(start 167.353996 -306.733956)
		(end 166.191692 -305.571652)
		(width 0.18288)
		(layer "In4.Cu")
		(net "M_F_CPU1_SA_DQ<8>")
	)
	(segment
		(start 170.812206 -307.471826)
		(end 170.629326 -307.654706)
		(width 0.18288)
		(layer "In4.Cu")
		(net "M_F_CPU1_SA_DQ<8>")
	)
	(segment
		(start 132.143246 -272.31467)
		(end 132.138674 -272.31213)
		(width 0.088646)
		(layer "In4.Cu")
		(net "M_F_CPU1_SA_DQ<8>")
	)
	(segment
		(start 165.335712 -305.571652)
		(end 164.593016 -304.828956)
		(width 0.18288)
		(layer "In4.Cu")
		(net "M_F_CPU1_SA_DQ<8>")
	)
	(segment
		(start 162.687 -303.99228)
		(end 161.473642 -303.99228)
		(width 0.18288)
		(layer "In4.Cu")
		(net "M_F_CPU1_SA_DQ<8>")
	)
	(segment
		(start 171.962572 -307.471826)
		(end 170.812206 -307.471826)
		(width 0.18288)
		(layer "In4.Cu")
		(net "M_F_CPU1_SA_DQ<8>")
	)
	(segment
		(start 134.022846 -272.31467)
		(end 134.018274 -272.31213)
		(width 0.088646)
		(layer "In4.Cu")
		(net "M_F_CPU1_SA_DQ<8>")
	)
	(segment
		(start 134.030212 -272.318988)
		(end 134.022846 -272.31467)
		(width 0.088646)
		(layer "In4.Cu")
		(net "M_F_CPU1_SA_DQ<8>")
	)
	(segment
		(start 166.191692 -305.571652)
		(end 165.335712 -305.571652)
		(width 0.18288)
		(layer "In4.Cu")
		(net "M_F_CPU1_SA_DQ<8>")
	)
	(segment
		(start 172.522896 -307.23967)
		(end 171.962572 -307.471826)
		(width 0.18288)
		(layer "In4.Cu")
		(net "M_F_CPU1_SA_DQ<8>")
	)
	(segment
		(start 135.902192 -272.314924)
		(end 135.902446 -272.31467)
		(width 0.088646)
		(layer "In4.Cu")
		(net "M_F_CPU1_SA_DQ<8>")
	)
	(segment
		(start 145.756376 -280.458926)
		(end 140.793724 -275.496274)
		(width 0.18288)
		(layer "In4.Cu")
		(net "M_F_CPU1_SA_DQ<8>")
	)
	(segment
		(start 136.467596 -272.314924)
		(end 136.452864 -272.32356)
		(width 0.088646)
		(layer "In4.Cu")
		(net "M_F_CPU1_SA_DQ<8>")
	)
	(segment
		(start 158.071566 -300.590204)
		(end 157.520894 -300.590204)
		(width 0.18288)
		(layer "In4.Cu")
		(net "M_F_CPU1_SA_DQ<8>")
	)
	(arc
		(start 137.311892 -273.12874)
		(mid 137.107557 -272.926135)
		(end 137.029444 -272.649188)
		(width 0.088646)
		(layer "In4.Cu")
		(net "M_F_CPU1_SA_DQ<8>")
	)
	(arc
		(start 134.587996 -272.31467)
		(mid 134.309673 -272.390429)
		(end 134.030212 -272.318988)
		(width 0.088646)
		(layer "In4.Cu")
		(net "M_F_CPU1_SA_DQ<8>")
	)
	(arc
		(start 131.768596 -272.31467)
		(mid 131.38352 -272.368782)
		(end 131.068826 -272.140426)
		(width 0.088646)
		(layer "In4.Cu")
		(net "M_F_CPU1_SA_DQ<8>")
	)
	(arc
		(start 136.452864 -272.32356)
		(mid 136.176423 -272.390726)
		(end 135.902192 -272.314924)
		(width 0.088646)
		(layer "In4.Cu")
		(net "M_F_CPU1_SA_DQ<8>")
	)
	(arc
		(start 135.527796 -272.31467)
		(mid 135.247882 -272.390439)
		(end 134.967218 -272.317464)
		(width 0.088646)
		(layer "In4.Cu")
		(net "M_F_CPU1_SA_DQ<8>")
	)
	(arc
		(start 134.958074 -272.31213)
		(mid 134.772689 -272.264492)
		(end 134.587996 -272.31467)
		(width 0.088646)
		(layer "In4.Cu")
		(net "M_F_CPU1_SA_DQ<8>")
	)
	(arc
		(start 135.902446 -272.31467)
		(mid 135.715138 -272.264561)
		(end 135.527796 -272.31467)
		(width 0.088646)
		(layer "In4.Cu")
		(net "M_F_CPU1_SA_DQ<8>")
	)
	(arc
		(start 137.029444 -272.639282)
		(mid 136.981765 -272.456382)
		(end 136.850882 -272.320004)
		(width 0.088646)
		(layer "In4.Cu")
		(net "M_F_CPU1_SA_DQ<8>")
	)
	(arc
		(start 132.708396 -272.31467)
		(mid 132.430073 -272.390429)
		(end 132.150612 -272.318988)
		(width 0.088646)
		(layer "In4.Cu")
		(net "M_F_CPU1_SA_DQ<8>")
	)
	(arc
		(start 134.018274 -272.31213)
		(mid 133.832889 -272.264492)
		(end 133.648196 -272.31467)
		(width 0.088646)
		(layer "In4.Cu")
		(net "M_F_CPU1_SA_DQ<8>")
	)
	(arc
		(start 136.841992 -272.314924)
		(mid 136.654794 -272.264781)
		(end 136.467596 -272.314924)
		(width 0.088646)
		(layer "In4.Cu")
		(net "M_F_CPU1_SA_DQ<8>")
	)
	(arc
		(start 137.877296 -273.12874)
		(mid 137.594594 -273.204516)
		(end 137.311892 -273.12874)
		(width 0.088646)
		(layer "In4.Cu")
		(net "M_F_CPU1_SA_DQ<8>")
	)
	(arc
		(start 132.138674 -272.31213)
		(mid 131.953289 -272.264492)
		(end 131.768596 -272.31467)
		(width 0.088646)
		(layer "In4.Cu")
		(net "M_F_CPU1_SA_DQ<8>")
	)
	(arc
		(start 133.648196 -272.31467)
		(mid 133.369873 -272.390429)
		(end 133.090412 -272.318988)
		(width 0.088646)
		(layer "In4.Cu")
		(net "M_F_CPU1_SA_DQ<8>")
	)
	(arc
		(start 131.068826 -272.140426)
		(mid 130.845162 -271.920534)
		(end 130.546348 -271.825212)
		(width 0.088646)
		(layer "In4.Cu")
		(net "M_F_CPU1_SA_DQ<8>")
	)
	(arc
		(start 133.078474 -272.31213)
		(mid 132.893089 -272.264492)
		(end 132.708396 -272.31467)
		(width 0.088646)
		(layer "In4.Cu")
		(net "M_F_CPU1_SA_DQ<8>")
	)
	(arc
		(start 138.251692 -273.12874)
		(mid 138.064494 -273.078597)
		(end 137.877296 -273.12874)
		(width 0.088646)
		(layer "In4.Cu")
		(net "M_F_CPU1_SA_DQ<8>")
	)
	(segment
		(start 182.442866 -308.2417)
		(end 182.455058 -308.253892)
		(width 0.1016)
		(layer "F.Cu")
		(net "M_F_CPU1_SA_DQ<7>")
	)
	(segment
		(start 180.434996 -308.2417)
		(end 182.442866 -308.2417)
		(width 0.1016)
		(layer "F.Cu")
		(net "M_F_CPU1_SA_DQ<7>")
	)
	(segment
		(start 178.000914 -307.816758)
		(end 179.699158 -307.816758)
		(width 0.20066)
		(layer "F.Cu")
		(net "M_F_CPU1_SA_DQ<7>")
	)
	(segment
		(start 179.699158 -307.816758)
		(end 180.131212 -308.248812)
		(width 0.20066)
		(layer "F.Cu")
		(net "M_F_CPU1_SA_DQ<7>")
	)
	(segment
		(start 183.340248 -308.04993)
		(end 183.340248 -307.798978)
		(width 0.20066)
		(layer "F.Cu")
		(net "M_F_CPU1_SA_DQ<7>")
	)
	(segment
		(start 183.136286 -308.253892)
		(end 183.340248 -308.04993)
		(width 0.20066)
		(layer "F.Cu")
		(net "M_F_CPU1_SA_DQ<7>")
	)
	(segment
		(start 182.455058 -308.253892)
		(end 183.136286 -308.253892)
		(width 0.20066)
		(layer "F.Cu")
		(net "M_F_CPU1_SA_DQ<7>")
	)
	(segment
		(start 180.131212 -308.248812)
		(end 180.423058 -308.248812)
		(width 0.20066)
		(layer "F.Cu")
		(net "M_F_CPU1_SA_DQ<7>")
	)
	(segment
		(start 134.775448 -275.35886)
		(end 134.775448 -275.894546)
		(width 0.20066)
		(layer "F.Cu")
		(net "M_F_CPU1_SA_DQ<7>")
	)
	(segment
		(start 184.210452 -307.816758)
		(end 185.544714 -307.816758)
		(width 0.20066)
		(layer "F.Cu")
		(net "M_F_CPU1_SA_DQ<7>")
	)
	(segment
		(start 183.574436 -307.56479)
		(end 183.958484 -307.56479)
		(width 0.20066)
		(layer "F.Cu")
		(net "M_F_CPU1_SA_DQ<7>")
	)
	(segment
		(start 180.427884 -308.248812)
		(end 180.434996 -308.2417)
		(width 0.1016)
		(layer "F.Cu")
		(net "M_F_CPU1_SA_DQ<7>")
	)
	(segment
		(start 183.340248 -307.798978)
		(end 183.574436 -307.56479)
		(width 0.20066)
		(layer "F.Cu")
		(net "M_F_CPU1_SA_DQ<7>")
	)
	(segment
		(start 180.423058 -308.248812)
		(end 180.427884 -308.248812)
		(width 0.101854)
		(layer "F.Cu")
		(net "M_F_CPU1_SA_DQ<7>")
	)
	(segment
		(start 183.958484 -307.56479)
		(end 184.210452 -307.816758)
		(width 0.20066)
		(layer "F.Cu")
		(net "M_F_CPU1_SA_DQ<7>")
	)
	(segment
		(start 134.775448 -275.894546)
		(end 134.775194 -275.8948)
		(width 0.20066)
		(layer "F.Cu")
		(net "M_F_CPU1_SA_DQ<7>")
	)
	(segment
		(start 176.896014 -307.816758)
		(end 178.000914 -307.816758)
		(width 0.20066)
		(layer "F.Cu")
		(net "M_F_CPU1_SA_DQ<7>")
	)
	(segment
		(start 159.76854 -307.390292)
		(end 156.347668 -307.390292)
		(width 0.18288)
		(layer "In2.Cu")
		(net "M_F_CPU1_SA_DQ<7>")
	)
	(segment
		(start 175.455834 -307.378354)
		(end 175.116744 -307.378354)
		(width 0.18288)
		(layer "In2.Cu")
		(net "M_F_CPU1_SA_DQ<7>")
	)
	(segment
		(start 143.759174 -281.467052)
		(end 142.524988 -278.487124)
		(width 0.18288)
		(layer "In2.Cu")
		(net "M_F_CPU1_SA_DQ<7>")
	)
	(segment
		(start 167.197278 -306.472844)
		(end 165.59911 -306.472844)
		(width 0.18288)
		(layer "In2.Cu")
		(net "M_F_CPU1_SA_DQ<7>")
	)
	(segment
		(start 161.057844 -306.935378)
		(end 160.223454 -306.935378)
		(width 0.18288)
		(layer "In2.Cu")
		(net "M_F_CPU1_SA_DQ<7>")
	)
	(segment
		(start 167.644826 -306.591716)
		(end 167.31615 -306.591716)
		(width 0.18288)
		(layer "In2.Cu")
		(net "M_F_CPU1_SA_DQ<7>")
	)
	(segment
		(start 151.34082 -302.383444)
		(end 151.34082 -296.847768)
		(width 0.18288)
		(layer "In2.Cu")
		(net "M_F_CPU1_SA_DQ<7>")
	)
	(segment
		(start 175.674782 -307.159406)
		(end 175.455834 -307.378354)
		(width 0.18288)
		(layer "In2.Cu")
		(net "M_F_CPU1_SA_DQ<7>")
	)
	(segment
		(start 134.46252 -275.8948)
		(end 134.775194 -275.8948)
		(width 0.088646)
		(layer "In2.Cu")
		(net "M_F_CPU1_SA_DQ<7>")
	)
	(segment
		(start 171.812712 -306.450492)
		(end 171.412662 -306.450492)
		(width 0.18288)
		(layer "In2.Cu")
		(net "M_F_CPU1_SA_DQ<7>")
	)
	(segment
		(start 175.674782 -306.620672)
		(end 175.674782 -307.159406)
		(width 0.18288)
		(layer "In2.Cu")
		(net "M_F_CPU1_SA_DQ<7>")
	)
	(segment
		(start 139.720066 -276.269958)
		(end 139.474448 -276.269958)
		(width 0.088646)
		(layer "In2.Cu")
		(net "M_F_CPU1_SA_DQ<7>")
	)
	(segment
		(start 169.940732 -306.879752)
		(end 169.302176 -306.241196)
		(width 0.18288)
		(layer "In2.Cu")
		(net "M_F_CPU1_SA_DQ<7>")
	)
	(segment
		(start 174.730664 -306.541424)
		(end 171.903644 -306.541424)
		(width 0.18288)
		(layer "In2.Cu")
		(net "M_F_CPU1_SA_DQ<7>")
	)
	(segment
		(start 174.923704 -307.185314)
		(end 174.923704 -306.734464)
		(width 0.18288)
		(layer "In2.Cu")
		(net "M_F_CPU1_SA_DQ<7>")
	)
	(segment
		(start 146.073114 -289.238436)
		(end 146.073114 -283.780992)
		(width 0.18288)
		(layer "In2.Cu")
		(net "M_F_CPU1_SA_DQ<7>")
	)
	(segment
		(start 156.347668 -307.390292)
		(end 151.34082 -302.383444)
		(width 0.18288)
		(layer "In2.Cu")
		(net "M_F_CPU1_SA_DQ<7>")
	)
	(segment
		(start 134.971282 -276.214078)
		(end 134.962392 -276.219158)
		(width 0.088646)
		(layer "In2.Cu")
		(net "M_F_CPU1_SA_DQ<7>")
	)
	(segment
		(start 176.220374 -306.427632)
		(end 175.867822 -306.427632)
		(width 0.18288)
		(layer "In2.Cu")
		(net "M_F_CPU1_SA_DQ<7>")
	)
	(segment
		(start 146.215862 -289.582606)
		(end 146.073114 -289.238436)
		(width 0.18288)
		(layer "In2.Cu")
		(net "M_F_CPU1_SA_DQ<7>")
	)
	(segment
		(start 176.413414 -306.620672)
		(end 176.220374 -306.427632)
		(width 0.18288)
		(layer "In2.Cu")
		(net "M_F_CPU1_SA_DQ<7>")
	)
	(segment
		(start 146.073114 -283.780992)
		(end 143.759174 -281.467052)
		(width 0.18288)
		(layer "In2.Cu")
		(net "M_F_CPU1_SA_DQ<7>")
	)
	(segment
		(start 171.903644 -306.541424)
		(end 171.812712 -306.450492)
		(width 0.18288)
		(layer "In2.Cu")
		(net "M_F_CPU1_SA_DQ<7>")
	)
	(segment
		(start 175.867822 -306.427632)
		(end 175.674782 -306.620672)
		(width 0.18288)
		(layer "In2.Cu")
		(net "M_F_CPU1_SA_DQ<7>")
	)
	(segment
		(start 169.302176 -306.241196)
		(end 167.995346 -306.241196)
		(width 0.18288)
		(layer "In2.Cu")
		(net "M_F_CPU1_SA_DQ<7>")
	)
	(segment
		(start 164.370258 -306.419504)
		(end 163.919916 -306.419504)
		(width 0.18288)
		(layer "In2.Cu")
		(net "M_F_CPU1_SA_DQ<7>")
	)
	(segment
		(start 151.34082 -296.847768)
		(end 149.827488 -293.194232)
		(width 0.18288)
		(layer "In2.Cu")
		(net "M_F_CPU1_SA_DQ<7>")
	)
	(segment
		(start 134.587996 -276.219158)
		(end 134.579106 -276.214078)
		(width 0.088646)
		(layer "In2.Cu")
		(net "M_F_CPU1_SA_DQ<7>")
	)
	(segment
		(start 137.219944 -275.8948)
		(end 137.219944 -275.884894)
		(width 0.088646)
		(layer "In2.Cu")
		(net "M_F_CPU1_SA_DQ<7>")
	)
	(segment
		(start 171.412662 -306.450492)
		(end 170.983402 -306.879752)
		(width 0.18288)
		(layer "In2.Cu")
		(net "M_F_CPU1_SA_DQ<7>")
	)
	(segment
		(start 135.432546 -275.405342)
		(end 135.42645 -275.408898)
		(width 0.088646)
		(layer "In2.Cu")
		(net "M_F_CPU1_SA_DQ<7>")
	)
	(segment
		(start 165.59911 -306.472844)
		(end 165.234874 -306.83708)
		(width 0.18288)
		(layer "In2.Cu")
		(net "M_F_CPU1_SA_DQ<7>")
	)
	(segment
		(start 176.896014 -307.816758)
		(end 176.606708 -307.816758)
		(width 0.18288)
		(layer "In2.Cu")
		(net "M_F_CPU1_SA_DQ<7>")
	)
	(segment
		(start 165.234874 -306.83708)
		(end 164.787834 -306.83708)
		(width 0.18288)
		(layer "In2.Cu")
		(net "M_F_CPU1_SA_DQ<7>")
	)
	(segment
		(start 142.524988 -278.487124)
		(end 141.197584 -277.15972)
		(width 0.18288)
		(layer "In2.Cu")
		(net "M_F_CPU1_SA_DQ<7>")
	)
	(segment
		(start 136.381236 -275.400008)
		(end 136.372346 -275.405342)
		(width 0.088646)
		(layer "In2.Cu")
		(net "M_F_CPU1_SA_DQ<7>")
	)
	(segment
		(start 135.447278 -275.396706)
		(end 135.432546 -275.405342)
		(width 0.088646)
		(layer "In2.Cu")
		(net "M_F_CPU1_SA_DQ<7>")
	)
	(segment
		(start 161.548572 -307.426106)
		(end 161.057844 -306.935378)
		(width 0.18288)
		(layer "In2.Cu")
		(net "M_F_CPU1_SA_DQ<7>")
	)
	(segment
		(start 163.919916 -306.419504)
		(end 162.913314 -307.426106)
		(width 0.18288)
		(layer "In2.Cu")
		(net "M_F_CPU1_SA_DQ<7>")
	)
	(segment
		(start 167.31615 -306.591716)
		(end 167.197278 -306.472844)
		(width 0.18288)
		(layer "In2.Cu")
		(net "M_F_CPU1_SA_DQ<7>")
	)
	(segment
		(start 136.937496 -275.405342)
		(end 136.937496 -275.405088)
		(width 0.088646)
		(layer "In2.Cu")
		(net "M_F_CPU1_SA_DQ<7>")
	)
	(segment
		(start 174.923704 -306.734464)
		(end 174.730664 -306.541424)
		(width 0.18288)
		(layer "In2.Cu")
		(net "M_F_CPU1_SA_DQ<7>")
	)
	(segment
		(start 162.913314 -307.426106)
		(end 161.548572 -307.426106)
		(width 0.18288)
		(layer "In2.Cu")
		(net "M_F_CPU1_SA_DQ<7>")
	)
	(segment
		(start 170.983402 -306.879752)
		(end 169.940732 -306.879752)
		(width 0.18288)
		(layer "In2.Cu")
		(net "M_F_CPU1_SA_DQ<7>")
	)
	(segment
		(start 164.787834 -306.83708)
		(end 164.370258 -306.419504)
		(width 0.18288)
		(layer "In2.Cu")
		(net "M_F_CPU1_SA_DQ<7>")
	)
	(segment
		(start 160.223454 -306.935378)
		(end 159.76854 -307.390292)
		(width 0.18288)
		(layer "In2.Cu")
		(net "M_F_CPU1_SA_DQ<7>")
	)
	(segment
		(start 134.405116 -275.952204)
		(end 134.46252 -275.8948)
		(width 0.088646)
		(layer "In2.Cu")
		(net "M_F_CPU1_SA_DQ<7>")
	)
	(segment
		(start 141.197584 -277.15972)
		(end 140.72362 -276.685756)
		(width 0.088646)
		(layer "In2.Cu")
		(net "M_F_CPU1_SA_DQ<7>")
	)
	(segment
		(start 137.407396 -276.219158)
		(end 137.398506 -276.214078)
		(width 0.088646)
		(layer "In2.Cu")
		(net "M_F_CPU1_SA_DQ<7>")
	)
	(segment
		(start 176.606708 -307.816758)
		(end 176.413414 -307.623464)
		(width 0.18288)
		(layer "In2.Cu")
		(net "M_F_CPU1_SA_DQ<7>")
	)
	(segment
		(start 176.413414 -307.623464)
		(end 176.413414 -306.620672)
		(width 0.18288)
		(layer "In2.Cu")
		(net "M_F_CPU1_SA_DQ<7>")
	)
	(segment
		(start 140.72362 -276.685756)
		(end 139.720066 -276.269958)
		(width 0.088646)
		(layer "In2.Cu")
		(net "M_F_CPU1_SA_DQ<7>")
	)
	(segment
		(start 149.827488 -293.194232)
		(end 146.215862 -289.582606)
		(width 0.18288)
		(layer "In2.Cu")
		(net "M_F_CPU1_SA_DQ<7>")
	)
	(segment
		(start 175.116744 -307.378354)
		(end 174.923704 -307.185314)
		(width 0.18288)
		(layer "In2.Cu")
		(net "M_F_CPU1_SA_DQ<7>")
	)
	(segment
		(start 167.995346 -306.241196)
		(end 167.644826 -306.591716)
		(width 0.18288)
		(layer "In2.Cu")
		(net "M_F_CPU1_SA_DQ<7>")
	)
	(arc
		(start 136.937496 -275.405088)
		(mid 136.660024 -275.32937)
		(end 136.381236 -275.400008)
		(width 0.088646)
		(layer "In2.Cu")
		(net "M_F_CPU1_SA_DQ<7>")
	)
	(arc
		(start 134.962392 -276.219158)
		(mid 134.775194 -276.269301)
		(end 134.587996 -276.219158)
		(width 0.088646)
		(layer "In2.Cu")
		(net "M_F_CPU1_SA_DQ<7>")
	)
	(arc
		(start 139.286996 -276.219158)
		(mid 139.004294 -276.143382)
		(end 138.721592 -276.219158)
		(width 0.088646)
		(layer "In2.Cu")
		(net "M_F_CPU1_SA_DQ<7>")
	)
	(arc
		(start 137.781792 -276.219158)
		(mid 137.594594 -276.269301)
		(end 137.407396 -276.219158)
		(width 0.088646)
		(layer "In2.Cu")
		(net "M_F_CPU1_SA_DQ<7>")
	)
	(arc
		(start 135.42645 -275.408898)
		(mid 135.223863 -275.615249)
		(end 135.149844 -275.8948)
		(width 0.088646)
		(layer "In2.Cu")
		(net "M_F_CPU1_SA_DQ<7>")
	)
	(arc
		(start 138.347196 -276.219158)
		(mid 138.064494 -276.143382)
		(end 137.781792 -276.219158)
		(width 0.088646)
		(layer "In2.Cu")
		(net "M_F_CPU1_SA_DQ<7>")
	)
	(arc
		(start 138.721592 -276.219158)
		(mid 138.534394 -276.269301)
		(end 138.347196 -276.219158)
		(width 0.088646)
		(layer "In2.Cu")
		(net "M_F_CPU1_SA_DQ<7>")
	)
	(arc
		(start 135.99795 -275.405342)
		(mid 135.723751 -275.329507)
		(end 135.447278 -275.396706)
		(width 0.088646)
		(layer "In2.Cu")
		(net "M_F_CPU1_SA_DQ<7>")
	)
	(arc
		(start 137.398506 -276.214078)
		(mid 137.267592 -276.077718)
		(end 137.219944 -275.8948)
		(width 0.088646)
		(layer "In2.Cu")
		(net "M_F_CPU1_SA_DQ<7>")
	)
	(arc
		(start 137.219944 -275.884894)
		(mid 137.141833 -275.607945)
		(end 136.937496 -275.405342)
		(width 0.088646)
		(layer "In2.Cu")
		(net "M_F_CPU1_SA_DQ<7>")
	)
	(arc
		(start 135.149844 -275.8948)
		(mid 135.102165 -276.0777)
		(end 134.971282 -276.214078)
		(width 0.088646)
		(layer "In2.Cu")
		(net "M_F_CPU1_SA_DQ<7>")
	)
	(arc
		(start 134.579106 -276.214078)
		(mid 134.463367 -276.102254)
		(end 134.405116 -275.952204)
		(width 0.088646)
		(layer "In2.Cu")
		(net "M_F_CPU1_SA_DQ<7>")
	)
	(arc
		(start 136.372346 -275.405342)
		(mid 136.185148 -275.455485)
		(end 135.99795 -275.405342)
		(width 0.088646)
		(layer "In2.Cu")
		(net "M_F_CPU1_SA_DQ<7>")
	)
	(arc
		(start 139.474448 -276.269958)
		(mid 139.377378 -276.256901)
		(end 139.286996 -276.219158)
		(width 0.088646)
		(layer "In2.Cu")
		(net "M_F_CPU1_SA_DQ<7>")
	)
	(segment
		(start 183.340248 -309.749952)
		(end 183.340248 -309.499)
		(width 0.20066)
		(layer "F.Cu")
		(net "M_F_CPU1_SA_DQ<6>")
	)
	(segment
		(start 183.574436 -309.264812)
		(end 183.958484 -309.264812)
		(width 0.20066)
		(layer "F.Cu")
		(net "M_F_CPU1_SA_DQ<6>")
	)
	(segment
		(start 183.136286 -309.953914)
		(end 183.340248 -309.749952)
		(width 0.20066)
		(layer "F.Cu")
		(net "M_F_CPU1_SA_DQ<6>")
	)
	(segment
		(start 179.699158 -309.51678)
		(end 180.131212 -309.948834)
		(width 0.20066)
		(layer "F.Cu")
		(net "M_F_CPU1_SA_DQ<6>")
	)
	(segment
		(start 180.427884 -309.948834)
		(end 180.434996 -309.941722)
		(width 0.1016)
		(layer "F.Cu")
		(net "M_F_CPU1_SA_DQ<6>")
	)
	(segment
		(start 182.455058 -309.953914)
		(end 183.136286 -309.953914)
		(width 0.20066)
		(layer "F.Cu")
		(net "M_F_CPU1_SA_DQ<6>")
	)
	(segment
		(start 176.896014 -309.516526)
		(end 178.00066 -309.516526)
		(width 0.20066)
		(layer "F.Cu")
		(net "M_F_CPU1_SA_DQ<6>")
	)
	(segment
		(start 180.131212 -309.948834)
		(end 180.423058 -309.948834)
		(width 0.20066)
		(layer "F.Cu")
		(net "M_F_CPU1_SA_DQ<6>")
	)
	(segment
		(start 178.00066 -309.516526)
		(end 178.000914 -309.51678)
		(width 0.20066)
		(layer "F.Cu")
		(net "M_F_CPU1_SA_DQ<6>")
	)
	(segment
		(start 183.340248 -309.499)
		(end 183.574436 -309.264812)
		(width 0.20066)
		(layer "F.Cu")
		(net "M_F_CPU1_SA_DQ<6>")
	)
	(segment
		(start 183.958484 -309.264812)
		(end 184.210452 -309.51678)
		(width 0.20066)
		(layer "F.Cu")
		(net "M_F_CPU1_SA_DQ<6>")
	)
	(segment
		(start 135.245094 -276.172676)
		(end 135.245094 -276.708362)
		(width 0.20066)
		(layer "F.Cu")
		(net "M_F_CPU1_SA_DQ<6>")
	)
	(segment
		(start 178.000914 -309.51678)
		(end 179.699158 -309.51678)
		(width 0.20066)
		(layer "F.Cu")
		(net "M_F_CPU1_SA_DQ<6>")
	)
	(segment
		(start 180.434996 -309.941722)
		(end 182.442866 -309.941722)
		(width 0.1016)
		(layer "F.Cu")
		(net "M_F_CPU1_SA_DQ<6>")
	)
	(segment
		(start 182.442866 -309.941722)
		(end 182.455058 -309.953914)
		(width 0.1016)
		(layer "F.Cu")
		(net "M_F_CPU1_SA_DQ<6>")
	)
	(segment
		(start 180.423058 -309.948834)
		(end 180.427884 -309.948834)
		(width 0.101854)
		(layer "F.Cu")
		(net "M_F_CPU1_SA_DQ<6>")
	)
	(segment
		(start 184.210452 -309.51678)
		(end 185.544714 -309.51678)
		(width 0.20066)
		(layer "F.Cu")
		(net "M_F_CPU1_SA_DQ<6>")
	)
	(segment
		(start 135.245094 -276.708362)
		(end 135.245348 -276.708616)
		(width 0.20066)
		(layer "F.Cu")
		(net "M_F_CPU1_SA_DQ<6>")
	)
	(segment
		(start 135.997696 -276.384258)
		(end 135.96874 -276.401022)
		(width 0.088646)
		(layer "In2.Cu")
		(net "M_F_CPU1_SA_DQ<6>")
	)
	(segment
		(start 162.351466 -308.765702)
		(end 162.019996 -309.097172)
		(width 0.18288)
		(layer "In2.Cu")
		(net "M_F_CPU1_SA_DQ<6>")
	)
	(segment
		(start 150.135082 -297.53052)
		(end 148.652738 -293.688008)
		(width 0.18288)
		(layer "In2.Cu")
		(net "M_F_CPU1_SA_DQ<6>")
	)
	(segment
		(start 145.057114 -289.442144)
		(end 145.057114 -283.791152)
		(width 0.18288)
		(layer "In2.Cu")
		(net "M_F_CPU1_SA_DQ<6>")
	)
	(segment
		(start 145.516854 -290.552124)
		(end 145.057114 -289.442144)
		(width 0.18288)
		(layer "In2.Cu")
		(net "M_F_CPU1_SA_DQ<6>")
	)
	(segment
		(start 176.428146 -309.516526)
		(end 176.314862 -309.62981)
		(width 0.18288)
		(layer "In2.Cu")
		(net "M_F_CPU1_SA_DQ<6>")
	)
	(segment
		(start 140.67409 -277.683214)
		(end 140.07465 -277.083774)
		(width 0.088646)
		(layer "In2.Cu")
		(net "M_F_CPU1_SA_DQ<6>")
	)
	(segment
		(start 176.314862 -309.62981)
		(end 176.314862 -310.600598)
		(width 0.18288)
		(layer "In2.Cu")
		(net "M_F_CPU1_SA_DQ<6>")
	)
	(segment
		(start 175.77181 -310.802782)
		(end 175.61179 -310.642762)
		(width 0.18288)
		(layer "In2.Cu")
		(net "M_F_CPU1_SA_DQ<6>")
	)
	(segment
		(start 171.96562 -308.910736)
		(end 171.78274 -309.093616)
		(width 0.18288)
		(layer "In2.Cu")
		(net "M_F_CPU1_SA_DQ<6>")
	)
	(segment
		(start 161.570162 -309.097172)
		(end 161.254694 -308.781704)
		(width 0.18288)
		(layer "In2.Cu")
		(net "M_F_CPU1_SA_DQ<6>")
	)
	(segment
		(start 162.019996 -309.097172)
		(end 161.570162 -309.097172)
		(width 0.18288)
		(layer "In2.Cu")
		(net "M_F_CPU1_SA_DQ<6>")
	)
	(segment
		(start 156.692854 -308.489096)
		(end 155.998164 -308.489096)
		(width 0.18288)
		(layer "In2.Cu")
		(net "M_F_CPU1_SA_DQ<6>")
	)
	(segment
		(start 175.61179 -308.842664)
		(end 175.41875 -308.649624)
		(width 0.18288)
		(layer "In2.Cu")
		(net "M_F_CPU1_SA_DQ<6>")
	)
	(segment
		(start 148.652738 -293.688008)
		(end 145.516854 -290.552124)
		(width 0.18288)
		(layer "In2.Cu")
		(net "M_F_CPU1_SA_DQ<6>")
	)
	(segment
		(start 164.747448 -308.906672)
		(end 164.526976 -309.127144)
		(width 0.18288)
		(layer "In2.Cu")
		(net "M_F_CPU1_SA_DQ<6>")
	)
	(segment
		(start 176.112678 -310.802782)
		(end 175.77181 -310.802782)
		(width 0.18288)
		(layer "In2.Cu")
		(net "M_F_CPU1_SA_DQ<6>")
	)
	(segment
		(start 160.023048 -308.781704)
		(end 159.7279 -309.076852)
		(width 0.18288)
		(layer "In2.Cu")
		(net "M_F_CPU1_SA_DQ<6>")
	)
	(segment
		(start 174.703994 -309.091076)
		(end 172.540676 -309.091076)
		(width 0.18288)
		(layer "In2.Cu")
		(net "M_F_CPU1_SA_DQ<6>")
	)
	(segment
		(start 163.476178 -308.765702)
		(end 162.351466 -308.765702)
		(width 0.18288)
		(layer "In2.Cu")
		(net "M_F_CPU1_SA_DQ<6>")
	)
	(segment
		(start 155.06446 -308.132734)
		(end 154.87142 -307.939694)
		(width 0.18288)
		(layer "In2.Cu")
		(net "M_F_CPU1_SA_DQ<6>")
	)
	(segment
		(start 140.07465 -277.083774)
		(end 139.004548 -277.083774)
		(width 0.088646)
		(layer "In2.Cu")
		(net "M_F_CPU1_SA_DQ<6>")
	)
	(segment
		(start 169.131234 -309.093616)
		(end 168.820846 -308.783228)
		(width 0.18288)
		(layer "In2.Cu")
		(net "M_F_CPU1_SA_DQ<6>")
	)
	(segment
		(start 135.96874 -276.401022)
		(end 135.245348 -276.708616)
		(width 0.088646)
		(layer "In2.Cu")
		(net "M_F_CPU1_SA_DQ<6>")
	)
	(segment
		(start 145.057114 -283.791152)
		(end 143.194786 -281.928824)
		(width 0.18288)
		(layer "In2.Cu")
		(net "M_F_CPU1_SA_DQ<6>")
	)
	(segment
		(start 168.820846 -308.783228)
		(end 167.576246 -308.783228)
		(width 0.18288)
		(layer "In2.Cu")
		(net "M_F_CPU1_SA_DQ<6>")
	)
	(segment
		(start 175.145446 -308.649624)
		(end 174.703994 -309.091076)
		(width 0.18288)
		(layer "In2.Cu")
		(net "M_F_CPU1_SA_DQ<6>")
	)
	(segment
		(start 165.382194 -308.906672)
		(end 164.747448 -308.906672)
		(width 0.18288)
		(layer "In2.Cu")
		(net "M_F_CPU1_SA_DQ<6>")
	)
	(segment
		(start 175.61179 -310.642762)
		(end 175.61179 -308.842664)
		(width 0.18288)
		(layer "In2.Cu")
		(net "M_F_CPU1_SA_DQ<6>")
	)
	(segment
		(start 163.83762 -309.127144)
		(end 163.476178 -308.765702)
		(width 0.18288)
		(layer "In2.Cu")
		(net "M_F_CPU1_SA_DQ<6>")
	)
	(segment
		(start 172.540676 -309.091076)
		(end 172.360336 -308.910736)
		(width 0.18288)
		(layer "In2.Cu")
		(net "M_F_CPU1_SA_DQ<6>")
	)
	(segment
		(start 176.314862 -310.600598)
		(end 176.112678 -310.802782)
		(width 0.18288)
		(layer "In2.Cu")
		(net "M_F_CPU1_SA_DQ<6>")
	)
	(segment
		(start 172.360336 -308.910736)
		(end 171.96562 -308.910736)
		(width 0.18288)
		(layer "In2.Cu")
		(net "M_F_CPU1_SA_DQ<6>")
	)
	(segment
		(start 159.7279 -309.076852)
		(end 157.28061 -309.076852)
		(width 0.18288)
		(layer "In2.Cu")
		(net "M_F_CPU1_SA_DQ<6>")
	)
	(segment
		(start 136.372346 -276.384512)
		(end 136.372092 -276.384258)
		(width 0.088646)
		(layer "In2.Cu")
		(net "M_F_CPU1_SA_DQ<6>")
	)
	(segment
		(start 176.896014 -309.516526)
		(end 176.428146 -309.516526)
		(width 0.18288)
		(layer "In2.Cu")
		(net "M_F_CPU1_SA_DQ<6>")
	)
	(segment
		(start 136.937496 -277.032974)
		(end 136.651492 -276.86762)
		(width 0.088646)
		(layer "In2.Cu")
		(net "M_F_CPU1_SA_DQ<6>")
	)
	(segment
		(start 167.576246 -308.783228)
		(end 167.271954 -309.08752)
		(width 0.18288)
		(layer "In2.Cu")
		(net "M_F_CPU1_SA_DQ<6>")
	)
	(segment
		(start 155.641802 -308.132734)
		(end 155.06446 -308.132734)
		(width 0.18288)
		(layer "In2.Cu")
		(net "M_F_CPU1_SA_DQ<6>")
	)
	(segment
		(start 141.974824 -278.983948)
		(end 140.67409 -277.683214)
		(width 0.18288)
		(layer "In2.Cu")
		(net "M_F_CPU1_SA_DQ<6>")
	)
	(segment
		(start 155.998164 -308.489096)
		(end 155.641802 -308.132734)
		(width 0.18288)
		(layer "In2.Cu")
		(net "M_F_CPU1_SA_DQ<6>")
	)
	(segment
		(start 154.87142 -307.939694)
		(end 154.87142 -307.362352)
		(width 0.18288)
		(layer "In2.Cu")
		(net "M_F_CPU1_SA_DQ<6>")
	)
	(segment
		(start 143.194786 -281.928824)
		(end 141.974824 -278.983948)
		(width 0.18288)
		(layer "In2.Cu")
		(net "M_F_CPU1_SA_DQ<6>")
	)
	(segment
		(start 175.41875 -308.649624)
		(end 175.145446 -308.649624)
		(width 0.18288)
		(layer "In2.Cu")
		(net "M_F_CPU1_SA_DQ<6>")
	)
	(segment
		(start 161.254694 -308.781704)
		(end 160.023048 -308.781704)
		(width 0.18288)
		(layer "In2.Cu")
		(net "M_F_CPU1_SA_DQ<6>")
	)
	(segment
		(start 167.271954 -309.08752)
		(end 165.563042 -309.08752)
		(width 0.18288)
		(layer "In2.Cu")
		(net "M_F_CPU1_SA_DQ<6>")
	)
	(segment
		(start 157.28061 -309.076852)
		(end 156.692854 -308.489096)
		(width 0.18288)
		(layer "In2.Cu")
		(net "M_F_CPU1_SA_DQ<6>")
	)
	(segment
		(start 165.563042 -309.08752)
		(end 165.382194 -308.906672)
		(width 0.18288)
		(layer "In2.Cu")
		(net "M_F_CPU1_SA_DQ<6>")
	)
	(segment
		(start 154.87142 -307.362352)
		(end 150.135082 -302.626014)
		(width 0.18288)
		(layer "In2.Cu")
		(net "M_F_CPU1_SA_DQ<6>")
	)
	(segment
		(start 164.526976 -309.127144)
		(end 163.83762 -309.127144)
		(width 0.18288)
		(layer "In2.Cu")
		(net "M_F_CPU1_SA_DQ<6>")
	)
	(segment
		(start 150.135082 -302.626014)
		(end 150.135082 -297.53052)
		(width 0.18288)
		(layer "In2.Cu")
		(net "M_F_CPU1_SA_DQ<6>")
	)
	(segment
		(start 171.78274 -309.093616)
		(end 169.131234 -309.093616)
		(width 0.18288)
		(layer "In2.Cu")
		(net "M_F_CPU1_SA_DQ<6>")
	)
	(arc
		(start 137.877296 -277.032974)
		(mid 137.594594 -276.957198)
		(end 137.311892 -277.032974)
		(width 0.088646)
		(layer "In2.Cu")
		(net "M_F_CPU1_SA_DQ<6>")
	)
	(arc
		(start 136.372092 -276.384258)
		(mid 136.184894 -276.334115)
		(end 135.997696 -276.384258)
		(width 0.088646)
		(layer "In2.Cu")
		(net "M_F_CPU1_SA_DQ<6>")
	)
	(arc
		(start 138.251692 -277.032974)
		(mid 138.064494 -277.083117)
		(end 137.877296 -277.032974)
		(width 0.088646)
		(layer "In2.Cu")
		(net "M_F_CPU1_SA_DQ<6>")
	)
	(arc
		(start 137.311892 -277.032974)
		(mid 137.124694 -277.083117)
		(end 136.937496 -277.032974)
		(width 0.088646)
		(layer "In2.Cu")
		(net "M_F_CPU1_SA_DQ<6>")
	)
	(arc
		(start 136.651492 -276.86762)
		(mid 136.584162 -276.800462)
		(end 136.559544 -276.708616)
		(width 0.088646)
		(layer "In2.Cu")
		(net "M_F_CPU1_SA_DQ<6>")
	)
	(arc
		(start 138.817096 -277.032974)
		(mid 138.534394 -276.957198)
		(end 138.251692 -277.032974)
		(width 0.088646)
		(layer "In2.Cu")
		(net "M_F_CPU1_SA_DQ<6>")
	)
	(arc
		(start 136.559544 -276.708616)
		(mid 136.50938 -276.521478)
		(end 136.372346 -276.384512)
		(width 0.088646)
		(layer "In2.Cu")
		(net "M_F_CPU1_SA_DQ<6>")
	)
	(arc
		(start 139.004548 -277.083774)
		(mid 138.907478 -277.070717)
		(end 138.817096 -277.032974)
		(width 0.088646)
		(layer "In2.Cu")
		(net "M_F_CPU1_SA_DQ<6>")
	)
	(segment
		(start 179.852828 -308.666896)
		(end 179.421282 -308.23535)
		(width 0.20066)
		(layer "F.Cu")
		(net "M_F_CPU1_SA_DQ<5>")
	)
	(segment
		(start 176.796192 -308.2417)
		(end 176.451514 -308.2417)
		(width 0.20066)
		(layer "F.Cu")
		(net "M_F_CPU1_SA_DQ<5>")
	)
	(segment
		(start 179.004976 -308.2417)
		(end 176.816258 -308.2417)
		(width 0.1016)
		(layer "F.Cu")
		(net "M_F_CPU1_SA_DQ<5>")
	)
	(segment
		(start 173.900846 -308.666642)
		(end 172.795946 -308.666642)
		(width 0.20066)
		(layer "F.Cu")
		(net "M_F_CPU1_SA_DQ<5>")
	)
	(segment
		(start 176.451514 -308.2417)
		(end 176.333404 -308.35981)
		(width 0.20066)
		(layer "F.Cu")
		(net "M_F_CPU1_SA_DQ<5>")
	)
	(segment
		(start 176.816258 -308.2417)
		(end 176.796192 -308.2417)
		(width 0.101854)
		(layer "F.Cu")
		(net "M_F_CPU1_SA_DQ<5>")
	)
	(segment
		(start 176.145444 -308.915308)
		(end 175.67021 -308.915308)
		(width 0.20066)
		(layer "F.Cu")
		(net "M_F_CPU1_SA_DQ<5>")
	)
	(segment
		(start 181.444392 -308.666896)
		(end 179.852828 -308.666896)
		(width 0.20066)
		(layer "F.Cu")
		(net "M_F_CPU1_SA_DQ<5>")
	)
	(segment
		(start 179.421282 -308.23535)
		(end 179.011326 -308.23535)
		(width 0.20066)
		(layer "F.Cu")
		(net "M_F_CPU1_SA_DQ<5>")
	)
	(segment
		(start 181.444646 -308.666642)
		(end 181.444392 -308.666896)
		(width 0.20066)
		(layer "F.Cu")
		(net "M_F_CPU1_SA_DQ<5>")
	)
	(segment
		(start 176.333404 -308.35981)
		(end 176.333404 -308.727348)
		(width 0.20066)
		(layer "F.Cu")
		(net "M_F_CPU1_SA_DQ<5>")
	)
	(segment
		(start 133.835648 -275.35886)
		(end 133.835648 -275.894546)
		(width 0.20066)
		(layer "F.Cu")
		(net "M_F_CPU1_SA_DQ<5>")
	)
	(segment
		(start 176.333404 -308.727348)
		(end 176.145444 -308.915308)
		(width 0.20066)
		(layer "F.Cu")
		(net "M_F_CPU1_SA_DQ<5>")
	)
	(segment
		(start 133.835648 -275.894546)
		(end 133.835394 -275.8948)
		(width 0.20066)
		(layer "F.Cu")
		(net "M_F_CPU1_SA_DQ<5>")
	)
	(segment
		(start 175.421544 -308.666642)
		(end 173.900846 -308.666642)
		(width 0.20066)
		(layer "F.Cu")
		(net "M_F_CPU1_SA_DQ<5>")
	)
	(segment
		(start 175.67021 -308.915308)
		(end 175.421544 -308.666642)
		(width 0.20066)
		(layer "F.Cu")
		(net "M_F_CPU1_SA_DQ<5>")
	)
	(segment
		(start 179.011326 -308.23535)
		(end 179.004976 -308.2417)
		(width 0.1016)
		(layer "F.Cu")
		(net "M_F_CPU1_SA_DQ<5>")
	)
	(segment
		(start 142.225268 -278.677878)
		(end 140.95222 -277.40483)
		(width 0.18288)
		(layer "In2.Cu")
		(net "M_F_CPU1_SA_DQ<5>")
	)
	(segment
		(start 167.91686 -308.264052)
		(end 166.905686 -308.264052)
		(width 0.18288)
		(layer "In2.Cu")
		(net "M_F_CPU1_SA_DQ<5>")
	)
	(segment
		(start 135.527796 -275.570442)
		(end 135.518906 -275.575522)
		(width 0.088646)
		(layer "In2.Cu")
		(net "M_F_CPU1_SA_DQ<5>")
	)
	(segment
		(start 160.702752 -307.704236)
		(end 160.153096 -308.253892)
		(width 0.18288)
		(layer "In2.Cu")
		(net "M_F_CPU1_SA_DQ<5>")
	)
	(segment
		(start 168.256712 -306.76469)
		(end 168.07688 -306.944522)
		(width 0.18288)
		(layer "In2.Cu")
		(net "M_F_CPU1_SA_DQ<5>")
	)
	(segment
		(start 136.46785 -275.570442)
		(end 136.457436 -275.576538)
		(width 0.088646)
		(layer "In2.Cu")
		(net "M_F_CPU1_SA_DQ<5>")
	)
	(segment
		(start 135.340344 -275.8948)
		(end 135.340344 -275.910294)
		(width 0.088646)
		(layer "In2.Cu")
		(net "M_F_CPU1_SA_DQ<5>")
	)
	(segment
		(start 172.795946 -308.666642)
		(end 172.327062 -308.197758)
		(width 0.18288)
		(layer "In2.Cu")
		(net "M_F_CPU1_SA_DQ<5>")
	)
	(segment
		(start 164.010848 -307.598318)
		(end 164.010848 -308.010306)
		(width 0.18288)
		(layer "In2.Cu")
		(net "M_F_CPU1_SA_DQ<5>")
	)
	(segment
		(start 143.474948 -281.695906)
		(end 142.225268 -278.677878)
		(width 0.18288)
		(layer "In2.Cu")
		(net "M_F_CPU1_SA_DQ<5>")
	)
	(segment
		(start 140.95222 -277.40483)
		(end 140.272008 -276.724618)
		(width 0.088646)
		(layer "In2.Cu")
		(net "M_F_CPU1_SA_DQ<5>")
	)
	(segment
		(start 164.184584 -307.424582)
		(end 164.010848 -307.598318)
		(width 0.18288)
		(layer "In2.Cu")
		(net "M_F_CPU1_SA_DQ<5>")
	)
	(segment
		(start 134.213854 -275.960586)
		(end 134.148068 -275.8948)
		(width 0.088646)
		(layer "In2.Cu")
		(net "M_F_CPU1_SA_DQ<5>")
	)
	(segment
		(start 163.78174 -308.239414)
		(end 161.623502 -308.239414)
		(width 0.18288)
		(layer "In2.Cu")
		(net "M_F_CPU1_SA_DQ<5>")
	)
	(segment
		(start 165.986968 -307.651912)
		(end 165.986968 -308.104032)
		(width 0.18288)
		(layer "In2.Cu")
		(net "M_F_CPU1_SA_DQ<5>")
	)
	(segment
		(start 134.507478 -276.392894)
		(end 134.492746 -276.384258)
		(width 0.088646)
		(layer "In2.Cu")
		(net "M_F_CPU1_SA_DQ<5>")
	)
	(segment
		(start 165.986968 -308.104032)
		(end 165.826948 -308.264052)
		(width 0.18288)
		(layer "In2.Cu")
		(net "M_F_CPU1_SA_DQ<5>")
	)
	(segment
		(start 161.623502 -308.239414)
		(end 161.088324 -307.704236)
		(width 0.18288)
		(layer "In2.Cu")
		(net "M_F_CPU1_SA_DQ<5>")
	)
	(segment
		(start 156.945076 -307.970174)
		(end 156.203142 -307.970174)
		(width 0.18288)
		(layer "In2.Cu")
		(net "M_F_CPU1_SA_DQ<5>")
	)
	(segment
		(start 171.4881 -308.073044)
		(end 171.321222 -308.239922)
		(width 0.18288)
		(layer "In2.Cu")
		(net "M_F_CPU1_SA_DQ<5>")
	)
	(segment
		(start 156.203142 -307.970174)
		(end 150.81885 -302.585882)
		(width 0.18288)
		(layer "In2.Cu")
		(net "M_F_CPU1_SA_DQ<5>")
	)
	(segment
		(start 165.826948 -308.264052)
		(end 164.885116 -308.264052)
		(width 0.18288)
		(layer "In2.Cu")
		(net "M_F_CPU1_SA_DQ<5>")
	)
	(segment
		(start 137.029444 -275.904706)
		(end 137.029444 -275.8948)
		(width 0.088646)
		(layer "In2.Cu")
		(net "M_F_CPU1_SA_DQ<5>")
	)
	(segment
		(start 168.862502 -308.004718)
		(end 168.862502 -306.95773)
		(width 0.18288)
		(layer "In2.Cu")
		(net "M_F_CPU1_SA_DQ<5>")
	)
	(segment
		(start 168.862502 -306.95773)
		(end 168.669462 -306.76469)
		(width 0.18288)
		(layer "In2.Cu")
		(net "M_F_CPU1_SA_DQ<5>")
	)
	(segment
		(start 164.737796 -307.571648)
		(end 164.59073 -307.424582)
		(width 0.18288)
		(layer "In2.Cu")
		(net "M_F_CPU1_SA_DQ<5>")
	)
	(segment
		(start 171.4881 -307.637942)
		(end 171.4881 -308.073044)
		(width 0.18288)
		(layer "In2.Cu")
		(net "M_F_CPU1_SA_DQ<5>")
	)
	(segment
		(start 134.492746 -276.384258)
		(end 134.48665 -276.380702)
		(width 0.088646)
		(layer "In2.Cu")
		(net "M_F_CPU1_SA_DQ<5>")
	)
	(segment
		(start 145.565114 -283.786072)
		(end 143.474948 -281.695906)
		(width 0.18288)
		(layer "In2.Cu")
		(net "M_F_CPU1_SA_DQ<5>")
	)
	(segment
		(start 169.097706 -308.239922)
		(end 168.862502 -308.004718)
		(width 0.18288)
		(layer "In2.Cu")
		(net "M_F_CPU1_SA_DQ<5>")
	)
	(segment
		(start 168.07688 -306.944522)
		(end 168.07688 -308.104032)
		(width 0.18288)
		(layer "In2.Cu")
		(net "M_F_CPU1_SA_DQ<5>")
	)
	(segment
		(start 166.745666 -307.651912)
		(end 166.552626 -307.458872)
		(width 0.18288)
		(layer "In2.Cu")
		(net "M_F_CPU1_SA_DQ<5>")
	)
	(segment
		(start 139.633452 -276.460204)
		(end 139.474194 -276.460204)
		(width 0.088646)
		(layer "In2.Cu")
		(net "M_F_CPU1_SA_DQ<5>")
	)
	(segment
		(start 171.68114 -307.444902)
		(end 171.4881 -307.637942)
		(width 0.18288)
		(layer "In2.Cu")
		(net "M_F_CPU1_SA_DQ<5>")
	)
	(segment
		(start 164.737796 -308.116732)
		(end 164.737796 -307.571648)
		(width 0.18288)
		(layer "In2.Cu")
		(net "M_F_CPU1_SA_DQ<5>")
	)
	(segment
		(start 160.153096 -308.253892)
		(end 159.702246 -308.253892)
		(width 0.18288)
		(layer "In2.Cu")
		(net "M_F_CPU1_SA_DQ<5>")
	)
	(segment
		(start 166.552626 -307.458872)
		(end 166.180008 -307.458872)
		(width 0.18288)
		(layer "In2.Cu")
		(net "M_F_CPU1_SA_DQ<5>")
	)
	(segment
		(start 145.565114 -289.34029)
		(end 145.565114 -283.786072)
		(width 0.18288)
		(layer "In2.Cu")
		(net "M_F_CPU1_SA_DQ<5>")
	)
	(segment
		(start 159.702246 -308.253892)
		(end 159.521906 -308.073552)
		(width 0.18288)
		(layer "In2.Cu")
		(net "M_F_CPU1_SA_DQ<5>")
	)
	(segment
		(start 159.521906 -308.073552)
		(end 158.102554 -308.073552)
		(width 0.18288)
		(layer "In2.Cu")
		(net "M_F_CPU1_SA_DQ<5>")
	)
	(segment
		(start 171.321222 -308.239922)
		(end 169.097706 -308.239922)
		(width 0.18288)
		(layer "In2.Cu")
		(net "M_F_CPU1_SA_DQ<5>")
	)
	(segment
		(start 164.59073 -307.424582)
		(end 164.184584 -307.424582)
		(width 0.18288)
		(layer "In2.Cu")
		(net "M_F_CPU1_SA_DQ<5>")
	)
	(segment
		(start 172.327062 -308.197758)
		(end 172.327062 -307.638196)
		(width 0.18288)
		(layer "In2.Cu")
		(net "M_F_CPU1_SA_DQ<5>")
	)
	(segment
		(start 158.102554 -308.073552)
		(end 157.778958 -308.397148)
		(width 0.18288)
		(layer "In2.Cu")
		(net "M_F_CPU1_SA_DQ<5>")
	)
	(segment
		(start 157.778958 -308.397148)
		(end 157.37205 -308.397148)
		(width 0.18288)
		(layer "In2.Cu")
		(net "M_F_CPU1_SA_DQ<5>")
	)
	(segment
		(start 164.010848 -308.010306)
		(end 163.78174 -308.239414)
		(width 0.18288)
		(layer "In2.Cu")
		(net "M_F_CPU1_SA_DQ<5>")
	)
	(segment
		(start 145.838164 -289.99942)
		(end 145.565114 -289.34029)
		(width 0.18288)
		(layer "In2.Cu")
		(net "M_F_CPU1_SA_DQ<5>")
	)
	(segment
		(start 172.133768 -307.444902)
		(end 171.68114 -307.444902)
		(width 0.18288)
		(layer "In2.Cu")
		(net "M_F_CPU1_SA_DQ<5>")
	)
	(segment
		(start 172.327062 -307.638196)
		(end 172.133768 -307.444902)
		(width 0.18288)
		(layer "In2.Cu")
		(net "M_F_CPU1_SA_DQ<5>")
	)
	(segment
		(start 140.272008 -276.724618)
		(end 139.633452 -276.460204)
		(width 0.088646)
		(layer "In2.Cu")
		(net "M_F_CPU1_SA_DQ<5>")
	)
	(segment
		(start 134.148068 -275.8948)
		(end 133.835394 -275.8948)
		(width 0.088646)
		(layer "In2.Cu")
		(net "M_F_CPU1_SA_DQ<5>")
	)
	(segment
		(start 149.257004 -293.41826)
		(end 145.838164 -289.99942)
		(width 0.18288)
		(layer "In2.Cu")
		(net "M_F_CPU1_SA_DQ<5>")
	)
	(segment
		(start 150.81885 -302.585882)
		(end 150.81885 -297.189144)
		(width 0.18288)
		(layer "In2.Cu")
		(net "M_F_CPU1_SA_DQ<5>")
	)
	(segment
		(start 166.905686 -308.264052)
		(end 166.745666 -308.104032)
		(width 0.18288)
		(layer "In2.Cu")
		(net "M_F_CPU1_SA_DQ<5>")
	)
	(segment
		(start 168.07688 -308.104032)
		(end 167.91686 -308.264052)
		(width 0.18288)
		(layer "In2.Cu")
		(net "M_F_CPU1_SA_DQ<5>")
	)
	(segment
		(start 166.745666 -308.104032)
		(end 166.745666 -307.651912)
		(width 0.18288)
		(layer "In2.Cu")
		(net "M_F_CPU1_SA_DQ<5>")
	)
	(segment
		(start 168.669462 -306.76469)
		(end 168.256712 -306.76469)
		(width 0.18288)
		(layer "In2.Cu")
		(net "M_F_CPU1_SA_DQ<5>")
	)
	(segment
		(start 164.885116 -308.264052)
		(end 164.737796 -308.116732)
		(width 0.18288)
		(layer "In2.Cu")
		(net "M_F_CPU1_SA_DQ<5>")
	)
	(segment
		(start 136.850882 -275.575522)
		(end 136.841992 -275.570442)
		(width 0.088646)
		(layer "In2.Cu")
		(net "M_F_CPU1_SA_DQ<5>")
	)
	(segment
		(start 136.841992 -275.570442)
		(end 136.842246 -275.570442)
		(width 0.088646)
		(layer "In2.Cu")
		(net "M_F_CPU1_SA_DQ<5>")
	)
	(segment
		(start 157.37205 -308.397148)
		(end 156.945076 -307.970174)
		(width 0.18288)
		(layer "In2.Cu")
		(net "M_F_CPU1_SA_DQ<5>")
	)
	(segment
		(start 166.180008 -307.458872)
		(end 165.986968 -307.651912)
		(width 0.18288)
		(layer "In2.Cu")
		(net "M_F_CPU1_SA_DQ<5>")
	)
	(segment
		(start 150.81885 -297.189144)
		(end 149.257004 -293.41826)
		(width 0.18288)
		(layer "In2.Cu")
		(net "M_F_CPU1_SA_DQ<5>")
	)
	(segment
		(start 161.088324 -307.704236)
		(end 160.702752 -307.704236)
		(width 0.18288)
		(layer "In2.Cu")
		(net "M_F_CPU1_SA_DQ<5>")
	)
	(arc
		(start 134.48665 -276.380702)
		(mid 134.301195 -276.202507)
		(end 134.213854 -275.960586)
		(width 0.088646)
		(layer "In2.Cu")
		(net "M_F_CPU1_SA_DQ<5>")
	)
	(arc
		(start 139.191492 -276.384258)
		(mid 139.004294 -276.334115)
		(end 138.817096 -276.384258)
		(width 0.088646)
		(layer "In2.Cu")
		(net "M_F_CPU1_SA_DQ<5>")
	)
	(arc
		(start 138.251692 -276.384258)
		(mid 138.064494 -276.334115)
		(end 137.877296 -276.384258)
		(width 0.088646)
		(layer "In2.Cu")
		(net "M_F_CPU1_SA_DQ<5>")
	)
	(arc
		(start 137.029444 -275.8948)
		(mid 136.981765 -275.7119)
		(end 136.850882 -275.575522)
		(width 0.088646)
		(layer "In2.Cu")
		(net "M_F_CPU1_SA_DQ<5>")
	)
	(arc
		(start 135.340344 -275.910294)
		(mid 135.260974 -276.184028)
		(end 135.05815 -276.384258)
		(width 0.088646)
		(layer "In2.Cu")
		(net "M_F_CPU1_SA_DQ<5>")
	)
	(arc
		(start 135.902192 -275.570442)
		(mid 135.714994 -275.520299)
		(end 135.527796 -275.570442)
		(width 0.088646)
		(layer "In2.Cu")
		(net "M_F_CPU1_SA_DQ<5>")
	)
	(arc
		(start 139.425172 -276.458172)
		(mid 139.304273 -276.434043)
		(end 139.191492 -276.384258)
		(width 0.088646)
		(layer "In2.Cu")
		(net "M_F_CPU1_SA_DQ<5>")
	)
	(arc
		(start 137.877296 -276.384258)
		(mid 137.594594 -276.460034)
		(end 137.311892 -276.384258)
		(width 0.088646)
		(layer "In2.Cu")
		(net "M_F_CPU1_SA_DQ<5>")
	)
	(arc
		(start 136.842246 -275.570442)
		(mid 136.655048 -275.520299)
		(end 136.46785 -275.570442)
		(width 0.088646)
		(layer "In2.Cu")
		(net "M_F_CPU1_SA_DQ<5>")
	)
	(arc
		(start 139.474194 -276.460204)
		(mid 139.449661 -276.459716)
		(end 139.425172 -276.458172)
		(width 0.088646)
		(layer "In2.Cu")
		(net "M_F_CPU1_SA_DQ<5>")
	)
	(arc
		(start 135.518906 -275.575522)
		(mid 135.387992 -275.711882)
		(end 135.340344 -275.8948)
		(width 0.088646)
		(layer "In2.Cu")
		(net "M_F_CPU1_SA_DQ<5>")
	)
	(arc
		(start 137.311892 -276.384258)
		(mid 137.107557 -276.181653)
		(end 137.029444 -275.904706)
		(width 0.088646)
		(layer "In2.Cu")
		(net "M_F_CPU1_SA_DQ<5>")
	)
	(arc
		(start 136.457436 -275.576538)
		(mid 136.179004 -275.646384)
		(end 135.902192 -275.570442)
		(width 0.088646)
		(layer "In2.Cu")
		(net "M_F_CPU1_SA_DQ<5>")
	)
	(arc
		(start 138.817096 -276.384258)
		(mid 138.534394 -276.460034)
		(end 138.251692 -276.384258)
		(width 0.088646)
		(layer "In2.Cu")
		(net "M_F_CPU1_SA_DQ<5>")
	)
	(arc
		(start 135.05815 -276.384258)
		(mid 134.783951 -276.460093)
		(end 134.507478 -276.392894)
		(width 0.088646)
		(layer "In2.Cu")
		(net "M_F_CPU1_SA_DQ<5>")
	)
	(segment
		(start 176.333404 -310.059832)
		(end 176.333404 -310.42737)
		(width 0.20066)
		(layer "F.Cu")
		(net "M_F_CPU1_SA_DQ<4>")
	)
	(segment
		(start 175.67021 -310.61533)
		(end 175.421544 -310.366664)
		(width 0.20066)
		(layer "F.Cu")
		(net "M_F_CPU1_SA_DQ<4>")
	)
	(segment
		(start 179.004976 -309.941722)
		(end 176.843182 -309.941722)
		(width 0.1016)
		(layer "F.Cu")
		(net "M_F_CPU1_SA_DQ<4>")
	)
	(segment
		(start 176.843182 -309.941722)
		(end 176.796192 -309.941722)
		(width 0.101854)
		(layer "F.Cu")
		(net "M_F_CPU1_SA_DQ<4>")
	)
	(segment
		(start 176.333404 -310.42737)
		(end 176.145444 -310.61533)
		(width 0.20066)
		(layer "F.Cu")
		(net "M_F_CPU1_SA_DQ<4>")
	)
	(segment
		(start 179.421282 -309.935372)
		(end 179.011326 -309.935372)
		(width 0.20066)
		(layer "F.Cu")
		(net "M_F_CPU1_SA_DQ<4>")
	)
	(segment
		(start 181.444392 -310.366918)
		(end 179.852828 -310.366918)
		(width 0.20066)
		(layer "F.Cu")
		(net "M_F_CPU1_SA_DQ<4>")
	)
	(segment
		(start 133.365494 -276.172676)
		(end 133.365748 -276.708616)
		(width 0.20066)
		(layer "F.Cu")
		(net "M_F_CPU1_SA_DQ<4>")
	)
	(segment
		(start 173.900846 -310.366664)
		(end 172.795946 -310.366664)
		(width 0.20066)
		(layer "F.Cu")
		(net "M_F_CPU1_SA_DQ<4>")
	)
	(segment
		(start 179.852828 -310.366918)
		(end 179.421282 -309.935372)
		(width 0.20066)
		(layer "F.Cu")
		(net "M_F_CPU1_SA_DQ<4>")
	)
	(segment
		(start 176.451514 -309.941722)
		(end 176.333404 -310.059832)
		(width 0.20066)
		(layer "F.Cu")
		(net "M_F_CPU1_SA_DQ<4>")
	)
	(segment
		(start 181.444646 -310.366664)
		(end 181.444392 -310.366918)
		(width 0.20066)
		(layer "F.Cu")
		(net "M_F_CPU1_SA_DQ<4>")
	)
	(segment
		(start 176.796192 -309.941722)
		(end 176.451514 -309.941722)
		(width 0.20066)
		(layer "F.Cu")
		(net "M_F_CPU1_SA_DQ<4>")
	)
	(segment
		(start 179.011326 -309.935372)
		(end 179.004976 -309.941722)
		(width 0.1016)
		(layer "F.Cu")
		(net "M_F_CPU1_SA_DQ<4>")
	)
	(segment
		(start 176.145444 -310.61533)
		(end 175.67021 -310.61533)
		(width 0.20066)
		(layer "F.Cu")
		(net "M_F_CPU1_SA_DQ<4>")
	)
	(segment
		(start 175.421544 -310.366664)
		(end 173.900846 -310.366664)
		(width 0.20066)
		(layer "F.Cu")
		(net "M_F_CPU1_SA_DQ<4>")
	)
	(segment
		(start 136.372092 -277.032974)
		(end 136.371838 -277.032974)
		(width 0.088646)
		(layer "In2.Cu")
		(net "M_F_CPU1_SA_DQ<4>")
	)
	(segment
		(start 164.68598 -310.07177)
		(end 164.68598 -309.828692)
		(width 0.18288)
		(layer "In2.Cu")
		(net "M_F_CPU1_SA_DQ<4>")
	)
	(segment
		(start 156.303218 -310.167782)
		(end 156.303218 -309.894732)
		(width 0.18288)
		(layer "In2.Cu")
		(net "M_F_CPU1_SA_DQ<4>")
	)
	(segment
		(start 150.857966 -304.202338)
		(end 150.620476 -303.964848)
		(width 0.18288)
		(layer "In2.Cu")
		(net "M_F_CPU1_SA_DQ<4>")
	)
	(segment
		(start 149.603968 -297.83151)
		(end 148.110956 -293.962074)
		(width 0.18288)
		(layer "In2.Cu")
		(net "M_F_CPU1_SA_DQ<4>")
	)
	(segment
		(start 134.089648 -277.01621)
		(end 133.365748 -276.708616)
		(width 0.088646)
		(layer "In2.Cu")
		(net "M_F_CPU1_SA_DQ<4>")
	)
	(segment
		(start 140.424154 -277.93315)
		(end 139.765024 -277.27402)
		(width 0.088646)
		(layer "In2.Cu")
		(net "M_F_CPU1_SA_DQ<4>")
	)
	(segment
		(start 166.771066 -309.616348)
		(end 165.822376 -309.616348)
		(width 0.18288)
		(layer "In2.Cu")
		(net "M_F_CPU1_SA_DQ<4>")
	)
	(segment
		(start 167.657018 -310.228996)
		(end 167.383714 -310.228996)
		(width 0.18288)
		(layer "In2.Cu")
		(net "M_F_CPU1_SA_DQ<4>")
	)
	(segment
		(start 172.795946 -310.366664)
		(end 172.068998 -309.639716)
		(width 0.18288)
		(layer "In2.Cu")
		(net "M_F_CPU1_SA_DQ<4>")
	)
	(segment
		(start 148.110956 -293.962074)
		(end 145.15465 -291.005768)
		(width 0.18288)
		(layer "In2.Cu")
		(net "M_F_CPU1_SA_DQ<4>")
	)
	(segment
		(start 164.010594 -309.668672)
		(end 163.785296 -309.89397)
		(width 0.18288)
		(layer "In2.Cu")
		(net "M_F_CPU1_SA_DQ<4>")
	)
	(segment
		(start 155.805124 -309.396638)
		(end 155.532074 -309.396638)
		(width 0.18288)
		(layer "In2.Cu")
		(net "M_F_CPU1_SA_DQ<4>")
	)
	(segment
		(start 167.951912 -309.466742)
		(end 167.951912 -309.934102)
		(width 0.18288)
		(layer "In2.Cu")
		(net "M_F_CPU1_SA_DQ<4>")
	)
	(segment
		(start 142.893288 -282.12288)
		(end 141.676374 -279.18537)
		(width 0.18288)
		(layer "In2.Cu")
		(net "M_F_CPU1_SA_DQ<4>")
	)
	(segment
		(start 153.605992 -306.950364)
		(end 153.0858 -306.950364)
		(width 0.18288)
		(layer "In2.Cu")
		(net "M_F_CPU1_SA_DQ<4>")
	)
	(segment
		(start 153.0858 -306.950364)
		(end 152.84831 -306.712874)
		(width 0.18288)
		(layer "In2.Cu")
		(net "M_F_CPU1_SA_DQ<4>")
	)
	(segment
		(start 160.303718 -310.266588)
		(end 160.012634 -310.266588)
		(width 0.18288)
		(layer "In2.Cu")
		(net "M_F_CPU1_SA_DQ<4>")
	)
	(segment
		(start 168.111932 -309.306722)
		(end 167.951912 -309.466742)
		(width 0.18288)
		(layer "In2.Cu")
		(net "M_F_CPU1_SA_DQ<4>")
	)
	(segment
		(start 156.672026 -309.253128)
		(end 156.446728 -309.02783)
		(width 0.18288)
		(layer "In2.Cu")
		(net "M_F_CPU1_SA_DQ<4>")
	)
	(segment
		(start 156.446728 -309.02783)
		(end 156.173932 -309.02783)
		(width 0.18288)
		(layer "In2.Cu")
		(net "M_F_CPU1_SA_DQ<4>")
	)
	(segment
		(start 164.68598 -309.828692)
		(end 164.52596 -309.668672)
		(width 0.18288)
		(layer "In2.Cu")
		(net "M_F_CPU1_SA_DQ<4>")
	)
	(segment
		(start 134.492746 -277.032974)
		(end 134.492492 -277.032974)
		(width 0.088646)
		(layer "In2.Cu")
		(net "M_F_CPU1_SA_DQ<4>")
	)
	(segment
		(start 151.095456 -304.96002)
		(end 150.857966 -304.72253)
		(width 0.18288)
		(layer "In2.Cu")
		(net "M_F_CPU1_SA_DQ<4>")
	)
	(segment
		(start 171.326048 -309.93207)
		(end 169.50055 -309.93207)
		(width 0.18288)
		(layer "In2.Cu")
		(net "M_F_CPU1_SA_DQ<4>")
	)
	(segment
		(start 160.496758 -309.507636)
		(end 160.496758 -310.073548)
		(width 0.18288)
		(layer "In2.Cu")
		(net "M_F_CPU1_SA_DQ<4>")
	)
	(segment
		(start 152.61082 -305.955192)
		(end 152.090628 -305.955192)
		(width 0.18288)
		(layer "In2.Cu")
		(net "M_F_CPU1_SA_DQ<4>")
	)
	(segment
		(start 160.689798 -309.314596)
		(end 160.496758 -309.507636)
		(width 0.18288)
		(layer "In2.Cu")
		(net "M_F_CPU1_SA_DQ<4>")
	)
	(segment
		(start 135.4328 -277.032974)
		(end 135.432546 -277.032974)
		(width 0.088646)
		(layer "In2.Cu")
		(net "M_F_CPU1_SA_DQ<4>")
	)
	(segment
		(start 150.620476 -303.964848)
		(end 150.100284 -303.964848)
		(width 0.18288)
		(layer "In2.Cu")
		(net "M_F_CPU1_SA_DQ<4>")
	)
	(segment
		(start 151.853138 -305.717702)
		(end 151.853138 -305.19751)
		(width 0.18288)
		(layer "In2.Cu")
		(net "M_F_CPU1_SA_DQ<4>")
	)
	(segment
		(start 160.496758 -310.073548)
		(end 160.303718 -310.266588)
		(width 0.18288)
		(layer "In2.Cu")
		(net "M_F_CPU1_SA_DQ<4>")
	)
	(segment
		(start 161.740596 -309.626)
		(end 161.274252 -309.626)
		(width 0.18288)
		(layer "In2.Cu")
		(net "M_F_CPU1_SA_DQ<4>")
	)
	(segment
		(start 167.951912 -309.934102)
		(end 167.657018 -310.228996)
		(width 0.18288)
		(layer "In2.Cu")
		(net "M_F_CPU1_SA_DQ<4>")
	)
	(segment
		(start 156.672026 -309.525924)
		(end 156.672026 -309.253128)
		(width 0.18288)
		(layer "In2.Cu")
		(net "M_F_CPU1_SA_DQ<4>")
	)
	(segment
		(start 136.841992 -277.198074)
		(end 136.555988 -277.032974)
		(width 0.088646)
		(layer "In2.Cu")
		(net "M_F_CPU1_SA_DQ<4>")
	)
	(segment
		(start 139.765024 -277.27402)
		(end 139.004294 -277.27402)
		(width 0.088646)
		(layer "In2.Cu")
		(net "M_F_CPU1_SA_DQ<4>")
	)
	(segment
		(start 163.785296 -309.89397)
		(end 162.008566 -309.89397)
		(width 0.18288)
		(layer "In2.Cu")
		(net "M_F_CPU1_SA_DQ<4>")
	)
	(segment
		(start 150.857966 -304.72253)
		(end 150.857966 -304.202338)
		(width 0.18288)
		(layer "In2.Cu")
		(net "M_F_CPU1_SA_DQ<4>")
	)
	(segment
		(start 153.843482 -307.187854)
		(end 153.605992 -306.950364)
		(width 0.18288)
		(layer "In2.Cu")
		(net "M_F_CPU1_SA_DQ<4>")
	)
	(segment
		(start 156.837634 -310.424068)
		(end 156.559504 -310.424068)
		(width 0.18288)
		(layer "In2.Cu")
		(net "M_F_CPU1_SA_DQ<4>")
	)
	(segment
		(start 157.898592 -309.96509)
		(end 157.296612 -309.96509)
		(width 0.18288)
		(layer "In2.Cu")
		(net "M_F_CPU1_SA_DQ<4>")
	)
	(segment
		(start 134.11835 -277.032974)
		(end 134.089648 -277.01621)
		(width 0.088646)
		(layer "In2.Cu")
		(net "M_F_CPU1_SA_DQ<4>")
	)
	(segment
		(start 172.068998 -309.639716)
		(end 171.618402 -309.639716)
		(width 0.18288)
		(layer "In2.Cu")
		(net "M_F_CPU1_SA_DQ<4>")
	)
	(segment
		(start 144.549114 -289.543744)
		(end 144.549114 -283.778706)
		(width 0.18288)
		(layer "In2.Cu")
		(net "M_F_CPU1_SA_DQ<4>")
	)
	(segment
		(start 145.15465 -291.005768)
		(end 144.549114 -289.543744)
		(width 0.18288)
		(layer "In2.Cu")
		(net "M_F_CPU1_SA_DQ<4>")
	)
	(segment
		(start 159.342836 -309.59679)
		(end 158.266892 -309.59679)
		(width 0.18288)
		(layer "In2.Cu")
		(net "M_F_CPU1_SA_DQ<4>")
	)
	(segment
		(start 164.83838 -310.22417)
		(end 164.68598 -310.07177)
		(width 0.18288)
		(layer "In2.Cu")
		(net "M_F_CPU1_SA_DQ<4>")
	)
	(segment
		(start 151.853138 -305.19751)
		(end 151.615648 -304.96002)
		(width 0.18288)
		(layer "In2.Cu")
		(net "M_F_CPU1_SA_DQ<4>")
	)
	(segment
		(start 150.100284 -303.964848)
		(end 149.603968 -303.468532)
		(width 0.18288)
		(layer "In2.Cu")
		(net "M_F_CPU1_SA_DQ<4>")
	)
	(segment
		(start 157.296612 -309.96509)
		(end 156.837634 -310.424068)
		(width 0.18288)
		(layer "In2.Cu")
		(net "M_F_CPU1_SA_DQ<4>")
	)
	(segment
		(start 164.52596 -309.668672)
		(end 164.010594 -309.668672)
		(width 0.18288)
		(layer "In2.Cu")
		(net "M_F_CPU1_SA_DQ<4>")
	)
	(segment
		(start 149.603968 -303.468532)
		(end 149.603968 -297.83151)
		(width 0.18288)
		(layer "In2.Cu")
		(net "M_F_CPU1_SA_DQ<4>")
	)
	(segment
		(start 169.208196 -309.639716)
		(end 168.821354 -309.639716)
		(width 0.18288)
		(layer "In2.Cu")
		(net "M_F_CPU1_SA_DQ<4>")
	)
	(segment
		(start 168.821354 -309.639716)
		(end 168.48836 -309.306722)
		(width 0.18288)
		(layer "In2.Cu")
		(net "M_F_CPU1_SA_DQ<4>")
	)
	(segment
		(start 155.532074 -309.396638)
		(end 153.843482 -307.708046)
		(width 0.18288)
		(layer "In2.Cu")
		(net "M_F_CPU1_SA_DQ<4>")
	)
	(segment
		(start 153.843482 -307.708046)
		(end 153.843482 -307.187854)
		(width 0.18288)
		(layer "In2.Cu")
		(net "M_F_CPU1_SA_DQ<4>")
	)
	(segment
		(start 165.214554 -310.22417)
		(end 164.83838 -310.22417)
		(width 0.18288)
		(layer "In2.Cu")
		(net "M_F_CPU1_SA_DQ<4>")
	)
	(segment
		(start 160.962848 -309.314596)
		(end 160.689798 -309.314596)
		(width 0.18288)
		(layer "In2.Cu")
		(net "M_F_CPU1_SA_DQ<4>")
	)
	(segment
		(start 165.822376 -309.616348)
		(end 165.214554 -310.22417)
		(width 0.18288)
		(layer "In2.Cu")
		(net "M_F_CPU1_SA_DQ<4>")
	)
	(segment
		(start 151.615648 -304.96002)
		(end 151.095456 -304.96002)
		(width 0.18288)
		(layer "In2.Cu")
		(net "M_F_CPU1_SA_DQ<4>")
	)
	(segment
		(start 158.266892 -309.59679)
		(end 157.898592 -309.96509)
		(width 0.18288)
		(layer "In2.Cu")
		(net "M_F_CPU1_SA_DQ<4>")
	)
	(segment
		(start 141.676374 -279.18537)
		(end 140.424154 -277.93315)
		(width 0.18288)
		(layer "In2.Cu")
		(net "M_F_CPU1_SA_DQ<4>")
	)
	(segment
		(start 161.274252 -309.626)
		(end 160.962848 -309.314596)
		(width 0.18288)
		(layer "In2.Cu")
		(net "M_F_CPU1_SA_DQ<4>")
	)
	(segment
		(start 156.303218 -309.894732)
		(end 156.672026 -309.525924)
		(width 0.18288)
		(layer "In2.Cu")
		(net "M_F_CPU1_SA_DQ<4>")
	)
	(segment
		(start 160.012634 -310.266588)
		(end 159.342836 -309.59679)
		(width 0.18288)
		(layer "In2.Cu")
		(net "M_F_CPU1_SA_DQ<4>")
	)
	(segment
		(start 162.008566 -309.89397)
		(end 161.740596 -309.626)
		(width 0.18288)
		(layer "In2.Cu")
		(net "M_F_CPU1_SA_DQ<4>")
	)
	(segment
		(start 168.48836 -309.306722)
		(end 168.111932 -309.306722)
		(width 0.18288)
		(layer "In2.Cu")
		(net "M_F_CPU1_SA_DQ<4>")
	)
	(segment
		(start 156.173932 -309.02783)
		(end 155.805124 -309.396638)
		(width 0.18288)
		(layer "In2.Cu")
		(net "M_F_CPU1_SA_DQ<4>")
	)
	(segment
		(start 152.090628 -305.955192)
		(end 151.853138 -305.717702)
		(width 0.18288)
		(layer "In2.Cu")
		(net "M_F_CPU1_SA_DQ<4>")
	)
	(segment
		(start 156.559504 -310.424068)
		(end 156.303218 -310.167782)
		(width 0.18288)
		(layer "In2.Cu")
		(net "M_F_CPU1_SA_DQ<4>")
	)
	(segment
		(start 169.50055 -309.93207)
		(end 169.208196 -309.639716)
		(width 0.18288)
		(layer "In2.Cu")
		(net "M_F_CPU1_SA_DQ<4>")
	)
	(segment
		(start 167.383714 -310.228996)
		(end 166.771066 -309.616348)
		(width 0.18288)
		(layer "In2.Cu")
		(net "M_F_CPU1_SA_DQ<4>")
	)
	(segment
		(start 171.618402 -309.639716)
		(end 171.326048 -309.93207)
		(width 0.18288)
		(layer "In2.Cu")
		(net "M_F_CPU1_SA_DQ<4>")
	)
	(segment
		(start 152.84831 -306.192682)
		(end 152.61082 -305.955192)
		(width 0.18288)
		(layer "In2.Cu")
		(net "M_F_CPU1_SA_DQ<4>")
	)
	(segment
		(start 152.84831 -306.712874)
		(end 152.84831 -306.192682)
		(width 0.18288)
		(layer "In2.Cu")
		(net "M_F_CPU1_SA_DQ<4>")
	)
	(segment
		(start 144.549114 -283.778706)
		(end 142.893288 -282.12288)
		(width 0.18288)
		(layer "In2.Cu")
		(net "M_F_CPU1_SA_DQ<4>")
	)
	(arc
		(start 139.004294 -277.27402)
		(mid 138.979761 -277.273532)
		(end 138.955272 -277.271988)
		(width 0.088646)
		(layer "In2.Cu")
		(net "M_F_CPU1_SA_DQ<4>")
	)
	(arc
		(start 135.432546 -277.032974)
		(mid 135.245348 -277.083117)
		(end 135.05815 -277.032974)
		(width 0.088646)
		(layer "In2.Cu")
		(net "M_F_CPU1_SA_DQ<4>")
	)
	(arc
		(start 138.347196 -277.198074)
		(mid 138.064494 -277.27385)
		(end 137.781792 -277.198074)
		(width 0.088646)
		(layer "In2.Cu")
		(net "M_F_CPU1_SA_DQ<4>")
	)
	(arc
		(start 136.371838 -277.032974)
		(mid 136.184784 -277.083058)
		(end 135.997696 -277.032974)
		(width 0.088646)
		(layer "In2.Cu")
		(net "M_F_CPU1_SA_DQ<4>")
	)
	(arc
		(start 136.555988 -277.032974)
		(mid 136.46404 -277.008337)
		(end 136.372092 -277.032974)
		(width 0.088646)
		(layer "In2.Cu")
		(net "M_F_CPU1_SA_DQ<4>")
	)
	(arc
		(start 137.781792 -277.198074)
		(mid 137.594594 -277.147931)
		(end 137.407396 -277.198074)
		(width 0.088646)
		(layer "In2.Cu")
		(net "M_F_CPU1_SA_DQ<4>")
	)
	(arc
		(start 135.997696 -277.032974)
		(mid 135.715248 -276.957291)
		(end 135.4328 -277.032974)
		(width 0.088646)
		(layer "In2.Cu")
		(net "M_F_CPU1_SA_DQ<4>")
	)
	(arc
		(start 138.955272 -277.271988)
		(mid 138.834373 -277.247859)
		(end 138.721592 -277.198074)
		(width 0.088646)
		(layer "In2.Cu")
		(net "M_F_CPU1_SA_DQ<4>")
	)
	(arc
		(start 137.407396 -277.198074)
		(mid 137.124694 -277.27385)
		(end 136.841992 -277.198074)
		(width 0.088646)
		(layer "In2.Cu")
		(net "M_F_CPU1_SA_DQ<4>")
	)
	(arc
		(start 135.05815 -277.032974)
		(mid 134.775448 -276.957232)
		(end 134.492746 -277.032974)
		(width 0.088646)
		(layer "In2.Cu")
		(net "M_F_CPU1_SA_DQ<4>")
	)
	(arc
		(start 138.721592 -277.198074)
		(mid 138.534394 -277.147931)
		(end 138.347196 -277.198074)
		(width 0.088646)
		(layer "In2.Cu")
		(net "M_F_CPU1_SA_DQ<4>")
	)
	(arc
		(start 134.492492 -277.032974)
		(mid 134.305438 -277.083024)
		(end 134.11835 -277.032974)
		(width 0.088646)
		(layer "In2.Cu")
		(net "M_F_CPU1_SA_DQ<4>")
	)
	(segment
		(start 182.442866 -314.19165)
		(end 182.455058 -314.203842)
		(width 0.1016)
		(layer "F.Cu")
		(net "M_F_CPU1_SA_DQ<3>")
	)
	(segment
		(start 134.775448 -279.150064)
		(end 134.775194 -279.150318)
		(width 0.20066)
		(layer "F.Cu")
		(net "M_F_CPU1_SA_DQ<3>")
	)
	(segment
		(start 183.958484 -313.51474)
		(end 184.210452 -313.766708)
		(width 0.20066)
		(layer "F.Cu")
		(net "M_F_CPU1_SA_DQ<3>")
	)
	(segment
		(start 180.131212 -314.198762)
		(end 180.423058 -314.198762)
		(width 0.20066)
		(layer "F.Cu")
		(net "M_F_CPU1_SA_DQ<3>")
	)
	(segment
		(start 134.775448 -278.614378)
		(end 134.775448 -279.150064)
		(width 0.20066)
		(layer "F.Cu")
		(net "M_F_CPU1_SA_DQ<3>")
	)
	(segment
		(start 182.455058 -314.203842)
		(end 183.136286 -314.203842)
		(width 0.20066)
		(layer "F.Cu")
		(net "M_F_CPU1_SA_DQ<3>")
	)
	(segment
		(start 179.699158 -313.766708)
		(end 180.131212 -314.198762)
		(width 0.20066)
		(layer "F.Cu")
		(net "M_F_CPU1_SA_DQ<3>")
	)
	(segment
		(start 183.340248 -313.99988)
		(end 183.340248 -313.748928)
		(width 0.20066)
		(layer "F.Cu")
		(net "M_F_CPU1_SA_DQ<3>")
	)
	(segment
		(start 183.136286 -314.203842)
		(end 183.340248 -313.99988)
		(width 0.20066)
		(layer "F.Cu")
		(net "M_F_CPU1_SA_DQ<3>")
	)
	(segment
		(start 180.427884 -314.198762)
		(end 180.434996 -314.19165)
		(width 0.1016)
		(layer "F.Cu")
		(net "M_F_CPU1_SA_DQ<3>")
	)
	(segment
		(start 176.896014 -313.766708)
		(end 178.000914 -313.766708)
		(width 0.20066)
		(layer "F.Cu")
		(net "M_F_CPU1_SA_DQ<3>")
	)
	(segment
		(start 180.423058 -314.198762)
		(end 180.427884 -314.198762)
		(width 0.101854)
		(layer "F.Cu")
		(net "M_F_CPU1_SA_DQ<3>")
	)
	(segment
		(start 184.210452 -313.766708)
		(end 185.544714 -313.766708)
		(width 0.20066)
		(layer "F.Cu")
		(net "M_F_CPU1_SA_DQ<3>")
	)
	(segment
		(start 183.340248 -313.748928)
		(end 183.574436 -313.51474)
		(width 0.20066)
		(layer "F.Cu")
		(net "M_F_CPU1_SA_DQ<3>")
	)
	(segment
		(start 180.434996 -314.19165)
		(end 182.442866 -314.19165)
		(width 0.1016)
		(layer "F.Cu")
		(net "M_F_CPU1_SA_DQ<3>")
	)
	(segment
		(start 183.574436 -313.51474)
		(end 183.958484 -313.51474)
		(width 0.20066)
		(layer "F.Cu")
		(net "M_F_CPU1_SA_DQ<3>")
	)
	(segment
		(start 178.000914 -313.766708)
		(end 179.699158 -313.766708)
		(width 0.20066)
		(layer "F.Cu")
		(net "M_F_CPU1_SA_DQ<3>")
	)
	(segment
		(start 176.104042 -314.00877)
		(end 176.104042 -314.673742)
		(width 0.18288)
		(layer "In2.Cu")
		(net "M_F_CPU1_SA_DQ<3>")
	)
	(segment
		(start 141.877034 -284.230318)
		(end 141.309852 -283.663136)
		(width 0.18288)
		(layer "In2.Cu")
		(net "M_F_CPU1_SA_DQ<3>")
	)
	(segment
		(start 174.87138 -315.04128)
		(end 172.731938 -315.04128)
		(width 0.18288)
		(layer "In2.Cu")
		(net "M_F_CPU1_SA_DQ<3>")
	)
	(segment
		(start 140.063728 -280.655014)
		(end 139.3063 -279.897586)
		(width 0.18288)
		(layer "In2.Cu")
		(net "M_F_CPU1_SA_DQ<3>")
	)
	(segment
		(start 138.715496 -279.897586)
		(end 138.420602 -279.602692)
		(width 0.088646)
		(layer "In2.Cu")
		(net "M_F_CPU1_SA_DQ<3>")
	)
	(segment
		(start 136.937496 -279.639776)
		(end 136.922764 -279.648412)
		(width 0.088646)
		(layer "In2.Cu")
		(net "M_F_CPU1_SA_DQ<3>")
	)
	(segment
		(start 164.828982 -314.936378)
		(end 164.706046 -315.059314)
		(width 0.18288)
		(layer "In2.Cu")
		(net "M_F_CPU1_SA_DQ<3>")
	)
	(segment
		(start 165.668706 -315.235082)
		(end 165.370002 -314.936378)
		(width 0.18288)
		(layer "In2.Cu")
		(net "M_F_CPU1_SA_DQ<3>")
	)
	(segment
		(start 146.522186 -298.336716)
		(end 145.227294 -295.21023)
		(width 0.18288)
		(layer "In2.Cu")
		(net "M_F_CPU1_SA_DQ<3>")
	)
	(segment
		(start 164.706046 -315.059314)
		(end 160.245806 -315.059314)
		(width 0.18288)
		(layer "In2.Cu")
		(net "M_F_CPU1_SA_DQ<3>")
	)
	(segment
		(start 160.222438 -315.035946)
		(end 157.704028 -315.035946)
		(width 0.18288)
		(layer "In2.Cu")
		(net "M_F_CPU1_SA_DQ<3>")
	)
	(segment
		(start 175.884586 -314.893198)
		(end 175.019462 -314.893198)
		(width 0.18288)
		(layer "In2.Cu")
		(net "M_F_CPU1_SA_DQ<3>")
	)
	(segment
		(start 146.522186 -304.436272)
		(end 146.522186 -298.336716)
		(width 0.18288)
		(layer "In2.Cu")
		(net "M_F_CPU1_SA_DQ<3>")
	)
	(segment
		(start 141.877034 -290.077652)
		(end 141.877034 -284.230318)
		(width 0.18288)
		(layer "In2.Cu")
		(net "M_F_CPU1_SA_DQ<3>")
	)
	(segment
		(start 139.148058 -279.897586)
		(end 138.715496 -279.897586)
		(width 0.088646)
		(layer "In2.Cu")
		(net "M_F_CPU1_SA_DQ<3>")
	)
	(segment
		(start 172.234352 -315.042804)
		(end 172.081952 -315.195204)
		(width 0.18288)
		(layer "In2.Cu")
		(net "M_F_CPU1_SA_DQ<3>")
	)
	(segment
		(start 156.710126 -314.624212)
		(end 146.522186 -304.436272)
		(width 0.18288)
		(layer "In2.Cu")
		(net "M_F_CPU1_SA_DQ<3>")
	)
	(segment
		(start 134.931658 -278.8793)
		(end 134.775194 -279.150318)
		(width 0.088646)
		(layer "In2.Cu")
		(net "M_F_CPU1_SA_DQ<3>")
	)
	(segment
		(start 172.081952 -315.195204)
		(end 171.438824 -315.195204)
		(width 0.18288)
		(layer "In2.Cu")
		(net "M_F_CPU1_SA_DQ<3>")
	)
	(segment
		(start 176.896014 -313.766708)
		(end 176.346104 -313.766708)
		(width 0.18288)
		(layer "In2.Cu")
		(net "M_F_CPU1_SA_DQ<3>")
	)
	(segment
		(start 160.245806 -315.059314)
		(end 160.222438 -315.035946)
		(width 0.18288)
		(layer "In2.Cu")
		(net "M_F_CPU1_SA_DQ<3>")
	)
	(segment
		(start 135.00989 -278.858472)
		(end 134.931658 -278.8793)
		(width 0.088646)
		(layer "In2.Cu")
		(net "M_F_CPU1_SA_DQ<3>")
	)
	(segment
		(start 169.633646 -315.045852)
		(end 169.313606 -315.365892)
		(width 0.18288)
		(layer "In2.Cu")
		(net "M_F_CPU1_SA_DQ<3>")
	)
	(segment
		(start 167.046656 -315.235082)
		(end 165.668706 -315.235082)
		(width 0.18288)
		(layer "In2.Cu")
		(net "M_F_CPU1_SA_DQ<3>")
	)
	(segment
		(start 139.3063 -279.897586)
		(end 139.148058 -279.897586)
		(width 0.18288)
		(layer "In2.Cu")
		(net "M_F_CPU1_SA_DQ<3>")
	)
	(segment
		(start 167.64 -315.00064)
		(end 167.281098 -315.00064)
		(width 0.18288)
		(layer "In2.Cu")
		(net "M_F_CPU1_SA_DQ<3>")
	)
	(segment
		(start 143.137128 -293.120064)
		(end 141.877034 -290.077652)
		(width 0.18288)
		(layer "In2.Cu")
		(net "M_F_CPU1_SA_DQ<3>")
	)
	(segment
		(start 138.420602 -279.602692)
		(end 138.04011 -279.602692)
		(width 0.088646)
		(layer "In2.Cu")
		(net "M_F_CPU1_SA_DQ<3>")
	)
	(segment
		(start 168.005252 -315.365892)
		(end 167.64 -315.00064)
		(width 0.18288)
		(layer "In2.Cu")
		(net "M_F_CPU1_SA_DQ<3>")
	)
	(segment
		(start 172.730414 -315.042804)
		(end 172.234352 -315.042804)
		(width 0.18288)
		(layer "In2.Cu")
		(net "M_F_CPU1_SA_DQ<3>")
	)
	(segment
		(start 171.438824 -315.195204)
		(end 171.289472 -315.045852)
		(width 0.18288)
		(layer "In2.Cu")
		(net "M_F_CPU1_SA_DQ<3>")
	)
	(segment
		(start 169.313606 -315.365892)
		(end 168.005252 -315.365892)
		(width 0.18288)
		(layer "In2.Cu")
		(net "M_F_CPU1_SA_DQ<3>")
	)
	(segment
		(start 157.704028 -315.035946)
		(end 156.710126 -314.624212)
		(width 0.18288)
		(layer "In2.Cu")
		(net "M_F_CPU1_SA_DQ<3>")
	)
	(segment
		(start 141.309852 -283.663136)
		(end 140.063728 -280.655014)
		(width 0.18288)
		(layer "In2.Cu")
		(net "M_F_CPU1_SA_DQ<3>")
	)
	(segment
		(start 172.731938 -315.04128)
		(end 172.730414 -315.042804)
		(width 0.18288)
		(layer "In2.Cu")
		(net "M_F_CPU1_SA_DQ<3>")
	)
	(segment
		(start 176.104042 -314.673742)
		(end 175.884586 -314.893198)
		(width 0.18288)
		(layer "In2.Cu")
		(net "M_F_CPU1_SA_DQ<3>")
	)
	(segment
		(start 167.281098 -315.00064)
		(end 167.046656 -315.235082)
		(width 0.18288)
		(layer "In2.Cu")
		(net "M_F_CPU1_SA_DQ<3>")
	)
	(segment
		(start 175.019462 -314.893198)
		(end 174.87138 -315.04128)
		(width 0.18288)
		(layer "In2.Cu")
		(net "M_F_CPU1_SA_DQ<3>")
	)
	(segment
		(start 135.997696 -279.639776)
		(end 135.987282 -279.645872)
		(width 0.088646)
		(layer "In2.Cu")
		(net "M_F_CPU1_SA_DQ<3>")
	)
	(segment
		(start 171.289472 -315.045852)
		(end 169.633646 -315.045852)
		(width 0.18288)
		(layer "In2.Cu")
		(net "M_F_CPU1_SA_DQ<3>")
	)
	(segment
		(start 145.227294 -295.21023)
		(end 143.137128 -293.120064)
		(width 0.18288)
		(layer "In2.Cu")
		(net "M_F_CPU1_SA_DQ<3>")
	)
	(segment
		(start 176.346104 -313.766708)
		(end 176.104042 -314.00877)
		(width 0.18288)
		(layer "In2.Cu")
		(net "M_F_CPU1_SA_DQ<3>")
	)
	(segment
		(start 135.149844 -279.165812)
		(end 135.149844 -279.150318)
		(width 0.088646)
		(layer "In2.Cu")
		(net "M_F_CPU1_SA_DQ<3>")
	)
	(segment
		(start 165.370002 -314.936378)
		(end 164.828982 -314.936378)
		(width 0.18288)
		(layer "In2.Cu")
		(net "M_F_CPU1_SA_DQ<3>")
	)
	(arc
		(start 136.922764 -279.648412)
		(mid 136.646289 -279.715732)
		(end 136.372092 -279.639776)
		(width 0.088646)
		(layer "In2.Cu")
		(net "M_F_CPU1_SA_DQ<3>")
	)
	(arc
		(start 138.04011 -279.602692)
		(mid 137.948509 -279.614559)
		(end 137.862564 -279.648412)
		(width 0.088646)
		(layer "In2.Cu")
		(net "M_F_CPU1_SA_DQ<3>")
	)
	(arc
		(start 135.432038 -279.639776)
		(mid 135.229215 -279.439545)
		(end 135.149844 -279.165812)
		(width 0.088646)
		(layer "In2.Cu")
		(net "M_F_CPU1_SA_DQ<3>")
	)
	(arc
		(start 135.149844 -279.150318)
		(mid 135.112984 -278.988521)
		(end 135.00989 -278.858472)
		(width 0.088646)
		(layer "In2.Cu")
		(net "M_F_CPU1_SA_DQ<3>")
	)
	(arc
		(start 137.862564 -279.648412)
		(mid 137.586089 -279.715732)
		(end 137.311892 -279.639776)
		(width 0.088646)
		(layer "In2.Cu")
		(net "M_F_CPU1_SA_DQ<3>")
	)
	(arc
		(start 135.987282 -279.645872)
		(mid 135.70885 -279.715718)
		(end 135.432038 -279.639776)
		(width 0.088646)
		(layer "In2.Cu")
		(net "M_F_CPU1_SA_DQ<3>")
	)
	(arc
		(start 136.372092 -279.639776)
		(mid 136.184894 -279.589633)
		(end 135.997696 -279.639776)
		(width 0.088646)
		(layer "In2.Cu")
		(net "M_F_CPU1_SA_DQ<3>")
	)
	(arc
		(start 137.311892 -279.639776)
		(mid 137.124694 -279.589633)
		(end 136.937496 -279.639776)
		(width 0.088646)
		(layer "In2.Cu")
		(net "M_F_CPU1_SA_DQ<3>")
	)
	(segment
		(start 182.455058 -280.20391)
		(end 183.136286 -280.20391)
		(width 0.20066)
		(layer "F.Cu")
		(net "M_F_CPU1_SA_DQ<31>")
	)
	(segment
		(start 179.699158 -279.766776)
		(end 180.131212 -280.19883)
		(width 0.20066)
		(layer "F.Cu")
		(net "M_F_CPU1_SA_DQ<31>")
	)
	(segment
		(start 184.210452 -279.766776)
		(end 185.544714 -279.766776)
		(width 0.20066)
		(layer "F.Cu")
		(net "M_F_CPU1_SA_DQ<31>")
	)
	(segment
		(start 178.000914 -279.766776)
		(end 179.699158 -279.766776)
		(width 0.20066)
		(layer "F.Cu")
		(net "M_F_CPU1_SA_DQ<31>")
	)
	(segment
		(start 180.131212 -280.19883)
		(end 180.423058 -280.19883)
		(width 0.20066)
		(layer "F.Cu")
		(net "M_F_CPU1_SA_DQ<31>")
	)
	(segment
		(start 176.896014 -279.766776)
		(end 178.000914 -279.766776)
		(width 0.20066)
		(layer "F.Cu")
		(net "M_F_CPU1_SA_DQ<31>")
	)
	(segment
		(start 180.434996 -280.191718)
		(end 182.442866 -280.191718)
		(width 0.1016)
		(layer "F.Cu")
		(net "M_F_CPU1_SA_DQ<31>")
	)
	(segment
		(start 183.340248 -279.999948)
		(end 183.340248 -279.748996)
		(width 0.20066)
		(layer "F.Cu")
		(net "M_F_CPU1_SA_DQ<31>")
	)
	(segment
		(start 182.442866 -280.191718)
		(end 182.455058 -280.20391)
		(width 0.1016)
		(layer "F.Cu")
		(net "M_F_CPU1_SA_DQ<31>")
	)
	(segment
		(start 183.136286 -280.20391)
		(end 183.340248 -279.999948)
		(width 0.20066)
		(layer "F.Cu")
		(net "M_F_CPU1_SA_DQ<31>")
	)
	(segment
		(start 180.427884 -280.19883)
		(end 180.434996 -280.191718)
		(width 0.1016)
		(layer "F.Cu")
		(net "M_F_CPU1_SA_DQ<31>")
	)
	(segment
		(start 183.574436 -279.514808)
		(end 183.958484 -279.514808)
		(width 0.20066)
		(layer "F.Cu")
		(net "M_F_CPU1_SA_DQ<31>")
	)
	(segment
		(start 131.485894 -258.2672)
		(end 131.486148 -258.267454)
		(width 0.20066)
		(layer "F.Cu")
		(net "M_F_CPU1_SA_DQ<31>")
	)
	(segment
		(start 183.340248 -279.748996)
		(end 183.574436 -279.514808)
		(width 0.20066)
		(layer "F.Cu")
		(net "M_F_CPU1_SA_DQ<31>")
	)
	(segment
		(start 131.486148 -258.267454)
		(end 131.486148 -258.80314)
		(width 0.20066)
		(layer "F.Cu")
		(net "M_F_CPU1_SA_DQ<31>")
	)
	(segment
		(start 183.958484 -279.514808)
		(end 184.210452 -279.766776)
		(width 0.20066)
		(layer "F.Cu")
		(net "M_F_CPU1_SA_DQ<31>")
	)
	(segment
		(start 180.423058 -280.19883)
		(end 180.427884 -280.19883)
		(width 0.101854)
		(layer "F.Cu")
		(net "M_F_CPU1_SA_DQ<31>")
	)
	(segment
		(start 164.520626 -268.178026)
		(end 164.393626 -268.305026)
		(width 0.18288)
		(layer "In4.Cu")
		(net "M_F_CPU1_SA_DQ<31>")
	)
	(segment
		(start 161.307526 -268.305026)
		(end 160.596326 -267.593826)
		(width 0.18288)
		(layer "In4.Cu")
		(net "M_F_CPU1_SA_DQ<31>")
	)
	(segment
		(start 141.748002 -258.405122)
		(end 139.55395 -258.405122)
		(width 0.18288)
		(layer "In4.Cu")
		(net "M_F_CPU1_SA_DQ<31>")
	)
	(segment
		(start 134.587996 -258.313428)
		(end 134.577582 -258.307332)
		(width 0.088646)
		(layer "In4.Cu")
		(net "M_F_CPU1_SA_DQ<31>")
	)
	(segment
		(start 132.143246 -258.313428)
		(end 132.067046 -258.35737)
		(width 0.088646)
		(layer "In4.Cu")
		(net "M_F_CPU1_SA_DQ<31>")
	)
	(segment
		(start 176.896014 -279.766776)
		(end 176.2887 -279.766776)
		(width 0.18288)
		(layer "In4.Cu")
		(net "M_F_CPU1_SA_DQ<31>")
	)
	(segment
		(start 138.726418 -258.40309)
		(end 138.464544 -258.40309)
		(width 0.088646)
		(layer "In4.Cu")
		(net "M_F_CPU1_SA_DQ<31>")
	)
	(segment
		(start 164.393626 -268.305026)
		(end 161.307526 -268.305026)
		(width 0.18288)
		(layer "In4.Cu")
		(net "M_F_CPU1_SA_DQ<31>")
	)
	(segment
		(start 166.551102 -269.344902)
		(end 165.384226 -268.178026)
		(width 0.18288)
		(layer "In4.Cu")
		(net "M_F_CPU1_SA_DQ<31>")
	)
	(segment
		(start 158.33471 -266.286996)
		(end 157.387544 -266.286996)
		(width 0.18288)
		(layer "In4.Cu")
		(net "M_F_CPU1_SA_DQ<31>")
	)
	(segment
		(start 171.057316 -270.454882)
		(end 170.746928 -270.144494)
		(width 0.18288)
		(layer "In4.Cu")
		(net "M_F_CPU1_SA_DQ<31>")
	)
	(segment
		(start 157.387544 -266.286996)
		(end 150.98522 -259.884672)
		(width 0.18288)
		(layer "In4.Cu")
		(net "M_F_CPU1_SA_DQ<31>")
	)
	(segment
		(start 168.581578 -270.144494)
		(end 167.781986 -269.344902)
		(width 0.18288)
		(layer "In4.Cu")
		(net "M_F_CPU1_SA_DQ<31>")
	)
	(segment
		(start 170.746928 -270.144494)
		(end 168.581578 -270.144494)
		(width 0.18288)
		(layer "In4.Cu")
		(net "M_F_CPU1_SA_DQ<31>")
	)
	(segment
		(start 171.868338 -270.454882)
		(end 171.057316 -270.454882)
		(width 0.18288)
		(layer "In4.Cu")
		(net "M_F_CPU1_SA_DQ<31>")
	)
	(segment
		(start 150.98522 -259.884672)
		(end 146.041364 -259.884672)
		(width 0.18288)
		(layer "In4.Cu")
		(net "M_F_CPU1_SA_DQ<31>")
	)
	(segment
		(start 139.55395 -258.405122)
		(end 138.72845 -258.405122)
		(width 0.088646)
		(layer "In4.Cu")
		(net "M_F_CPU1_SA_DQ<31>")
	)
	(segment
		(start 135.912606 -258.307332)
		(end 135.902192 -258.313428)
		(width 0.088646)
		(layer "In4.Cu")
		(net "M_F_CPU1_SA_DQ<31>")
	)
	(segment
		(start 137.796778 -258.304792)
		(end 137.782046 -258.313428)
		(width 0.088646)
		(layer "In4.Cu")
		(net "M_F_CPU1_SA_DQ<31>")
	)
	(segment
		(start 136.856978 -258.304792)
		(end 136.842246 -258.313428)
		(width 0.088646)
		(layer "In4.Cu")
		(net "M_F_CPU1_SA_DQ<31>")
	)
	(segment
		(start 167.781986 -269.344902)
		(end 166.551102 -269.344902)
		(width 0.18288)
		(layer "In4.Cu")
		(net "M_F_CPU1_SA_DQ<31>")
	)
	(segment
		(start 174.488094 -270.841216)
		(end 172.254672 -270.841216)
		(width 0.18288)
		(layer "In4.Cu")
		(net "M_F_CPU1_SA_DQ<31>")
	)
	(segment
		(start 172.254672 -270.841216)
		(end 171.868338 -270.454882)
		(width 0.18288)
		(layer "In4.Cu")
		(net "M_F_CPU1_SA_DQ<31>")
	)
	(segment
		(start 144.652746 -259.60832)
		(end 141.748002 -258.405122)
		(width 0.18288)
		(layer "In4.Cu")
		(net "M_F_CPU1_SA_DQ<31>")
	)
	(segment
		(start 146.041364 -259.884672)
		(end 144.652746 -259.60832)
		(width 0.18288)
		(layer "In4.Cu")
		(net "M_F_CPU1_SA_DQ<31>")
	)
	(segment
		(start 175.74895 -279.227026)
		(end 175.74895 -272.102072)
		(width 0.18288)
		(layer "In4.Cu")
		(net "M_F_CPU1_SA_DQ<31>")
	)
	(segment
		(start 165.384226 -268.178026)
		(end 164.520626 -268.178026)
		(width 0.18288)
		(layer "In4.Cu")
		(net "M_F_CPU1_SA_DQ<31>")
	)
	(segment
		(start 133.64845 -258.313428)
		(end 133.638036 -258.307332)
		(width 0.088646)
		(layer "In4.Cu")
		(net "M_F_CPU1_SA_DQ<31>")
	)
	(segment
		(start 160.596326 -267.593826)
		(end 159.64154 -267.593826)
		(width 0.18288)
		(layer "In4.Cu")
		(net "M_F_CPU1_SA_DQ<31>")
	)
	(segment
		(start 176.2887 -279.766776)
		(end 175.74895 -279.227026)
		(width 0.18288)
		(layer "In4.Cu")
		(net "M_F_CPU1_SA_DQ<31>")
	)
	(segment
		(start 159.64154 -267.593826)
		(end 158.33471 -266.286996)
		(width 0.18288)
		(layer "In4.Cu")
		(net "M_F_CPU1_SA_DQ<31>")
	)
	(segment
		(start 132.708396 -258.313428)
		(end 132.697982 -258.307332)
		(width 0.088646)
		(layer "In4.Cu")
		(net "M_F_CPU1_SA_DQ<31>")
	)
	(segment
		(start 138.72845 -258.405122)
		(end 138.726418 -258.40309)
		(width 0.088646)
		(layer "In4.Cu")
		(net "M_F_CPU1_SA_DQ<31>")
	)
	(segment
		(start 175.74895 -272.102072)
		(end 174.488094 -270.841216)
		(width 0.18288)
		(layer "In4.Cu")
		(net "M_F_CPU1_SA_DQ<31>")
	)
	(arc
		(start 134.022846 -258.313428)
		(mid 133.835648 -258.363571)
		(end 133.64845 -258.313428)
		(width 0.088646)
		(layer "In4.Cu")
		(net "M_F_CPU1_SA_DQ<31>")
	)
	(arc
		(start 138.34745 -258.313428)
		(mid 138.073221 -258.237503)
		(end 137.796778 -258.304792)
		(width 0.088646)
		(layer "In4.Cu")
		(net "M_F_CPU1_SA_DQ<31>")
	)
	(arc
		(start 137.782046 -258.313428)
		(mid 137.594848 -258.363571)
		(end 137.40765 -258.313428)
		(width 0.088646)
		(layer "In4.Cu")
		(net "M_F_CPU1_SA_DQ<31>")
	)
	(arc
		(start 136.46785 -258.313428)
		(mid 136.191037 -258.237592)
		(end 135.912606 -258.307332)
		(width 0.088646)
		(layer "In4.Cu")
		(net "M_F_CPU1_SA_DQ<31>")
	)
	(arc
		(start 136.842246 -258.313428)
		(mid 136.655048 -258.363571)
		(end 136.46785 -258.313428)
		(width 0.088646)
		(layer "In4.Cu")
		(net "M_F_CPU1_SA_DQ<31>")
	)
	(arc
		(start 135.527796 -258.313428)
		(mid 135.245094 -258.237686)
		(end 134.962392 -258.313428)
		(width 0.088646)
		(layer "In4.Cu")
		(net "M_F_CPU1_SA_DQ<31>")
	)
	(arc
		(start 138.464544 -258.40309)
		(mid 138.408928 -258.354432)
		(end 138.34745 -258.313428)
		(width 0.088646)
		(layer "In4.Cu")
		(net "M_F_CPU1_SA_DQ<31>")
	)
	(arc
		(start 134.962392 -258.313428)
		(mid 134.775194 -258.363571)
		(end 134.587996 -258.313428)
		(width 0.088646)
		(layer "In4.Cu")
		(net "M_F_CPU1_SA_DQ<31>")
	)
	(arc
		(start 132.067046 -258.35737)
		(mid 131.76199 -258.561219)
		(end 131.486148 -258.80314)
		(width 0.088646)
		(layer "In4.Cu")
		(net "M_F_CPU1_SA_DQ<31>")
	)
	(arc
		(start 132.697982 -258.307332)
		(mid 132.419804 -258.23764)
		(end 132.143246 -258.313428)
		(width 0.088646)
		(layer "In4.Cu")
		(net "M_F_CPU1_SA_DQ<31>")
	)
	(arc
		(start 134.577582 -258.307332)
		(mid 134.299404 -258.23764)
		(end 134.022846 -258.313428)
		(width 0.088646)
		(layer "In4.Cu")
		(net "M_F_CPU1_SA_DQ<31>")
	)
	(arc
		(start 137.40765 -258.313428)
		(mid 137.133421 -258.237503)
		(end 136.856978 -258.304792)
		(width 0.088646)
		(layer "In4.Cu")
		(net "M_F_CPU1_SA_DQ<31>")
	)
	(arc
		(start 133.638036 -258.307332)
		(mid 133.359604 -258.237518)
		(end 133.082792 -258.313428)
		(width 0.088646)
		(layer "In4.Cu")
		(net "M_F_CPU1_SA_DQ<31>")
	)
	(arc
		(start 133.082792 -258.313428)
		(mid 132.895594 -258.363571)
		(end 132.708396 -258.313428)
		(width 0.088646)
		(layer "In4.Cu")
		(net "M_F_CPU1_SA_DQ<31>")
	)
	(arc
		(start 135.902192 -258.313428)
		(mid 135.714994 -258.363571)
		(end 135.527796 -258.313428)
		(width 0.088646)
		(layer "In4.Cu")
		(net "M_F_CPU1_SA_DQ<31>")
	)
	(segment
		(start 183.958484 -281.21483)
		(end 184.210452 -281.466798)
		(width 0.20066)
		(layer "F.Cu")
		(net "M_F_CPU1_SA_DQ<30>")
	)
	(segment
		(start 182.455058 -281.903932)
		(end 183.136286 -281.903932)
		(width 0.20066)
		(layer "F.Cu")
		(net "M_F_CPU1_SA_DQ<30>")
	)
	(segment
		(start 179.699158 -281.466798)
		(end 180.131212 -281.898852)
		(width 0.20066)
		(layer "F.Cu")
		(net "M_F_CPU1_SA_DQ<30>")
	)
	(segment
		(start 180.427884 -281.898852)
		(end 180.434996 -281.89174)
		(width 0.1016)
		(layer "F.Cu")
		(net "M_F_CPU1_SA_DQ<30>")
	)
	(segment
		(start 180.434996 -281.89174)
		(end 182.442866 -281.89174)
		(width 0.1016)
		(layer "F.Cu")
		(net "M_F_CPU1_SA_DQ<30>")
	)
	(segment
		(start 182.442866 -281.89174)
		(end 182.455058 -281.903932)
		(width 0.1016)
		(layer "F.Cu")
		(net "M_F_CPU1_SA_DQ<30>")
	)
	(segment
		(start 131.956048 -259.081016)
		(end 131.956048 -259.093462)
		(width 0.20066)
		(layer "F.Cu")
		(net "M_F_CPU1_SA_DQ<30>")
	)
	(segment
		(start 180.423058 -281.898852)
		(end 180.427884 -281.898852)
		(width 0.101854)
		(layer "F.Cu")
		(net "M_F_CPU1_SA_DQ<30>")
	)
	(segment
		(start 178.000914 -281.466798)
		(end 179.699158 -281.466798)
		(width 0.20066)
		(layer "F.Cu")
		(net "M_F_CPU1_SA_DQ<30>")
	)
	(segment
		(start 180.131212 -281.898852)
		(end 180.423058 -281.898852)
		(width 0.20066)
		(layer "F.Cu")
		(net "M_F_CPU1_SA_DQ<30>")
	)
	(segment
		(start 183.136286 -281.903932)
		(end 183.340248 -281.69997)
		(width 0.20066)
		(layer "F.Cu")
		(net "M_F_CPU1_SA_DQ<30>")
	)
	(segment
		(start 176.896014 -281.466544)
		(end 176.896268 -281.466798)
		(width 0.20066)
		(layer "F.Cu")
		(net "M_F_CPU1_SA_DQ<30>")
	)
	(segment
		(start 183.340248 -281.449018)
		(end 183.574436 -281.21483)
		(width 0.20066)
		(layer "F.Cu")
		(net "M_F_CPU1_SA_DQ<30>")
	)
	(segment
		(start 131.956048 -259.093462)
		(end 131.955794 -259.616956)
		(width 0.20066)
		(layer "F.Cu")
		(net "M_F_CPU1_SA_DQ<30>")
	)
	(segment
		(start 184.210452 -281.466798)
		(end 185.544714 -281.466798)
		(width 0.20066)
		(layer "F.Cu")
		(net "M_F_CPU1_SA_DQ<30>")
	)
	(segment
		(start 176.896268 -281.466798)
		(end 178.000914 -281.466798)
		(width 0.20066)
		(layer "F.Cu")
		(net "M_F_CPU1_SA_DQ<30>")
	)
	(segment
		(start 183.574436 -281.21483)
		(end 183.958484 -281.21483)
		(width 0.20066)
		(layer "F.Cu")
		(net "M_F_CPU1_SA_DQ<30>")
	)
	(segment
		(start 183.340248 -281.69997)
		(end 183.340248 -281.449018)
		(width 0.20066)
		(layer "F.Cu")
		(net "M_F_CPU1_SA_DQ<30>")
	)
	(segment
		(start 172.112686 -277.588726)
		(end 172.295566 -277.405846)
		(width 0.18288)
		(layer "In4.Cu")
		(net "M_F_CPU1_SA_DQ<30>")
	)
	(segment
		(start 145.79092 -260.721602)
		(end 145.684494 -260.677406)
		(width 0.18288)
		(layer "In4.Cu")
		(net "M_F_CPU1_SA_DQ<30>")
	)
	(segment
		(start 150.153624 -260.880352)
		(end 146.391376 -260.880352)
		(width 0.18288)
		(layer "In4.Cu")
		(net "M_F_CPU1_SA_DQ<30>")
	)
	(segment
		(start 132.613146 -259.127498)
		(end 132.534914 -259.172456)
		(width 0.088646)
		(layer "In4.Cu")
		(net "M_F_CPU1_SA_DQ<30>")
	)
	(segment
		(start 134.118096 -259.127498)
		(end 134.11073 -259.12318)
		(width 0.088646)
		(layer "In4.Cu")
		(net "M_F_CPU1_SA_DQ<30>")
	)
	(segment
		(start 172.455586 -281.042618)
		(end 172.295566 -280.882598)
		(width 0.18288)
		(layer "In4.Cu")
		(net "M_F_CPU1_SA_DQ<30>")
	)
	(segment
		(start 134.122668 -259.130038)
		(end 134.118096 -259.127498)
		(width 0.088646)
		(layer "In4.Cu")
		(net "M_F_CPU1_SA_DQ<30>")
	)
	(segment
		(start 133.182868 -259.130038)
		(end 133.17093 -259.12318)
		(width 0.088646)
		(layer "In4.Cu")
		(net "M_F_CPU1_SA_DQ<30>")
	)
	(segment
		(start 172.295566 -278.465026)
		(end 172.112686 -278.282146)
		(width 0.18288)
		(layer "In4.Cu")
		(net "M_F_CPU1_SA_DQ<30>")
	)
	(segment
		(start 172.295566 -275.219414)
		(end 169.506138 -272.429986)
		(width 0.18288)
		(layer "In4.Cu")
		(net "M_F_CPU1_SA_DQ<30>")
	)
	(segment
		(start 172.112686 -278.282146)
		(end 171.823634 -278.282146)
		(width 0.18288)
		(layer "In4.Cu")
		(net "M_F_CPU1_SA_DQ<30>")
	)
	(segment
		(start 137.32637 -259.118862)
		(end 137.311638 -259.127498)
		(width 0.088646)
		(layer "In4.Cu")
		(net "M_F_CPU1_SA_DQ<30>")
	)
	(segment
		(start 132.534914 -259.172456)
		(end 131.955794 -259.616956)
		(width 0.088646)
		(layer "In4.Cu")
		(net "M_F_CPU1_SA_DQ<30>")
	)
	(segment
		(start 160.634426 -269.270226)
		(end 159.850582 -269.270226)
		(width 0.18288)
		(layer "In4.Cu")
		(net "M_F_CPU1_SA_DQ<30>")
	)
	(segment
		(start 145.97126 -260.796532)
		(end 145.79092 -260.721602)
		(width 0.18288)
		(layer "In4.Cu")
		(net "M_F_CPU1_SA_DQ<30>")
	)
	(segment
		(start 158.796228 -268.215872)
		(end 157.489144 -268.215872)
		(width 0.18288)
		(layer "In4.Cu")
		(net "M_F_CPU1_SA_DQ<30>")
	)
	(segment
		(start 176.369726 -281.992832)
		(end 174.782226 -281.992832)
		(width 0.18288)
		(layer "In4.Cu")
		(net "M_F_CPU1_SA_DQ<30>")
	)
	(segment
		(start 165.057074 -270.868394)
		(end 164.190934 -270.002254)
		(width 0.18288)
		(layer "In4.Cu")
		(net "M_F_CPU1_SA_DQ<30>")
	)
	(segment
		(start 145.684494 -260.677406)
		(end 145.028412 -260.49351)
		(width 0.18288)
		(layer "In4.Cu")
		(net "M_F_CPU1_SA_DQ<30>")
	)
	(segment
		(start 171.640754 -278.099266)
		(end 171.640754 -277.771606)
		(width 0.18288)
		(layer "In4.Cu")
		(net "M_F_CPU1_SA_DQ<30>")
	)
	(segment
		(start 171.823634 -277.588726)
		(end 172.112686 -277.588726)
		(width 0.18288)
		(layer "In4.Cu")
		(net "M_F_CPU1_SA_DQ<30>")
	)
	(segment
		(start 169.506138 -272.429986)
		(end 169.056812 -272.429986)
		(width 0.18288)
		(layer "In4.Cu")
		(net "M_F_CPU1_SA_DQ<30>")
	)
	(segment
		(start 135.057896 -259.127498)
		(end 135.05053 -259.12318)
		(width 0.088646)
		(layer "In4.Cu")
		(net "M_F_CPU1_SA_DQ<30>")
	)
	(segment
		(start 169.056812 -272.429986)
		(end 167.49522 -270.868394)
		(width 0.18288)
		(layer "In4.Cu")
		(net "M_F_CPU1_SA_DQ<30>")
	)
	(segment
		(start 159.850582 -269.270226)
		(end 158.796228 -268.215872)
		(width 0.18288)
		(layer "In4.Cu")
		(net "M_F_CPU1_SA_DQ<30>")
	)
	(segment
		(start 136.38657 -259.118862)
		(end 136.371838 -259.127498)
		(width 0.088646)
		(layer "In4.Cu")
		(net "M_F_CPU1_SA_DQ<30>")
	)
	(segment
		(start 174.782226 -281.992832)
		(end 173.832012 -281.042618)
		(width 0.18288)
		(layer "In4.Cu")
		(net "M_F_CPU1_SA_DQ<30>")
	)
	(segment
		(start 136.371838 -259.127498)
		(end 136.363456 -259.132324)
		(width 0.088646)
		(layer "In4.Cu")
		(net "M_F_CPU1_SA_DQ<30>")
	)
	(segment
		(start 173.832012 -281.042618)
		(end 172.455586 -281.042618)
		(width 0.18288)
		(layer "In4.Cu")
		(net "M_F_CPU1_SA_DQ<30>")
	)
	(segment
		(start 135.432292 -259.127498)
		(end 135.427974 -259.130038)
		(width 0.088646)
		(layer "In4.Cu")
		(net "M_F_CPU1_SA_DQ<30>")
	)
	(segment
		(start 138.24712 -259.130038)
		(end 138.2395 -259.134356)
		(width 0.088646)
		(layer "In4.Cu")
		(net "M_F_CPU1_SA_DQ<30>")
	)
	(segment
		(start 171.823634 -278.282146)
		(end 171.640754 -278.099266)
		(width 0.18288)
		(layer "In4.Cu")
		(net "M_F_CPU1_SA_DQ<30>")
	)
	(segment
		(start 137.311638 -259.127498)
		(end 137.2997 -259.134356)
		(width 0.088646)
		(layer "In4.Cu")
		(net "M_F_CPU1_SA_DQ<30>")
	)
	(segment
		(start 146.391376 -260.880352)
		(end 145.97126 -260.796532)
		(width 0.18288)
		(layer "In4.Cu")
		(net "M_F_CPU1_SA_DQ<30>")
	)
	(segment
		(start 172.295566 -280.882598)
		(end 172.295566 -278.465026)
		(width 0.18288)
		(layer "In4.Cu")
		(net "M_F_CPU1_SA_DQ<30>")
	)
	(segment
		(start 141.678152 -259.105654)
		(end 139.55395 -259.105654)
		(width 0.18288)
		(layer "In4.Cu")
		(net "M_F_CPU1_SA_DQ<30>")
	)
	(segment
		(start 157.489144 -268.215872)
		(end 150.153624 -260.880352)
		(width 0.18288)
		(layer "In4.Cu")
		(net "M_F_CPU1_SA_DQ<30>")
	)
	(segment
		(start 162.137598 -270.002254)
		(end 162.006026 -270.133826)
		(width 0.18288)
		(layer "In4.Cu")
		(net "M_F_CPU1_SA_DQ<30>")
	)
	(segment
		(start 135.447024 -259.118862)
		(end 135.432292 -259.127498)
		(width 0.088646)
		(layer "In4.Cu")
		(net "M_F_CPU1_SA_DQ<30>")
	)
	(segment
		(start 164.190934 -270.002254)
		(end 162.137598 -270.002254)
		(width 0.18288)
		(layer "In4.Cu")
		(net "M_F_CPU1_SA_DQ<30>")
	)
	(segment
		(start 171.640754 -277.771606)
		(end 171.823634 -277.588726)
		(width 0.18288)
		(layer "In4.Cu")
		(net "M_F_CPU1_SA_DQ<30>")
	)
	(segment
		(start 162.006026 -270.133826)
		(end 161.498026 -270.133826)
		(width 0.18288)
		(layer "In4.Cu")
		(net "M_F_CPU1_SA_DQ<30>")
	)
	(segment
		(start 172.295566 -277.405846)
		(end 172.295566 -275.219414)
		(width 0.18288)
		(layer "In4.Cu")
		(net "M_F_CPU1_SA_DQ<30>")
	)
	(segment
		(start 167.49522 -270.868394)
		(end 165.057074 -270.868394)
		(width 0.18288)
		(layer "In4.Cu")
		(net "M_F_CPU1_SA_DQ<30>")
	)
	(segment
		(start 135.427974 -259.130038)
		(end 135.42518 -259.131562)
		(width 0.088646)
		(layer "In4.Cu")
		(net "M_F_CPU1_SA_DQ<30>")
	)
	(segment
		(start 139.55395 -259.105654)
		(end 138.338306 -259.105654)
		(width 0.088646)
		(layer "In4.Cu")
		(net "M_F_CPU1_SA_DQ<30>")
	)
	(segment
		(start 176.896014 -281.466544)
		(end 176.369726 -281.992832)
		(width 0.18288)
		(layer "In4.Cu")
		(net "M_F_CPU1_SA_DQ<30>")
	)
	(segment
		(start 161.498026 -270.133826)
		(end 160.634426 -269.270226)
		(width 0.18288)
		(layer "In4.Cu")
		(net "M_F_CPU1_SA_DQ<30>")
	)
	(segment
		(start 145.028412 -260.49351)
		(end 141.678152 -259.105654)
		(width 0.18288)
		(layer "In4.Cu")
		(net "M_F_CPU1_SA_DQ<30>")
	)
	(arc
		(start 134.492746 -259.127498)
		(mid 134.308052 -259.177599)
		(end 134.122668 -259.130038)
		(width 0.088646)
		(layer "In4.Cu")
		(net "M_F_CPU1_SA_DQ<30>")
	)
	(arc
		(start 133.552946 -259.127498)
		(mid 133.368252 -259.177599)
		(end 133.182868 -259.130038)
		(width 0.088646)
		(layer "In4.Cu")
		(net "M_F_CPU1_SA_DQ<30>")
	)
	(arc
		(start 135.42518 -259.131562)
		(mid 135.240998 -259.177642)
		(end 135.057896 -259.127498)
		(width 0.088646)
		(layer "In4.Cu")
		(net "M_F_CPU1_SA_DQ<30>")
	)
	(arc
		(start 134.11073 -259.12318)
		(mid 133.831269 -259.051743)
		(end 133.552946 -259.127498)
		(width 0.088646)
		(layer "In4.Cu")
		(net "M_F_CPU1_SA_DQ<30>")
	)
	(arc
		(start 135.997696 -259.127498)
		(mid 135.723497 -259.051663)
		(end 135.447024 -259.118862)
		(width 0.088646)
		(layer "In4.Cu")
		(net "M_F_CPU1_SA_DQ<30>")
	)
	(arc
		(start 137.877042 -259.127498)
		(mid 137.602843 -259.051663)
		(end 137.32637 -259.118862)
		(width 0.088646)
		(layer "In4.Cu")
		(net "M_F_CPU1_SA_DQ<30>")
	)
	(arc
		(start 138.338306 -259.105654)
		(mid 138.291103 -259.111842)
		(end 138.24712 -259.130038)
		(width 0.088646)
		(layer "In4.Cu")
		(net "M_F_CPU1_SA_DQ<30>")
	)
	(arc
		(start 135.05053 -259.12318)
		(mid 134.771069 -259.051743)
		(end 134.492746 -259.127498)
		(width 0.088646)
		(layer "In4.Cu")
		(net "M_F_CPU1_SA_DQ<30>")
	)
	(arc
		(start 137.2997 -259.134356)
		(mid 137.117589 -259.177681)
		(end 136.937242 -259.127498)
		(width 0.088646)
		(layer "In4.Cu")
		(net "M_F_CPU1_SA_DQ<30>")
	)
	(arc
		(start 133.17093 -259.12318)
		(mid 132.891469 -259.051743)
		(end 132.613146 -259.127498)
		(width 0.088646)
		(layer "In4.Cu")
		(net "M_F_CPU1_SA_DQ<30>")
	)
	(arc
		(start 136.363456 -259.132324)
		(mid 136.179948 -259.177602)
		(end 135.997696 -259.127498)
		(width 0.088646)
		(layer "In4.Cu")
		(net "M_F_CPU1_SA_DQ<30>")
	)
	(arc
		(start 138.2395 -259.134356)
		(mid 138.057389 -259.177681)
		(end 137.877042 -259.127498)
		(width 0.088646)
		(layer "In4.Cu")
		(net "M_F_CPU1_SA_DQ<30>")
	)
	(arc
		(start 136.937242 -259.127498)
		(mid 136.663043 -259.051663)
		(end 136.38657 -259.118862)
		(width 0.088646)
		(layer "In4.Cu")
		(net "M_F_CPU1_SA_DQ<30>")
	)
	(segment
		(start 183.340248 -315.699902)
		(end 183.340248 -315.44895)
		(width 0.20066)
		(layer "F.Cu")
		(net "M_F_CPU1_SA_DQ<2>")
	)
	(segment
		(start 179.699158 -315.46673)
		(end 180.131212 -315.898784)
		(width 0.20066)
		(layer "F.Cu")
		(net "M_F_CPU1_SA_DQ<2>")
	)
	(segment
		(start 183.574436 -315.214762)
		(end 183.958484 -315.214762)
		(width 0.20066)
		(layer "F.Cu")
		(net "M_F_CPU1_SA_DQ<2>")
	)
	(segment
		(start 180.131212 -315.898784)
		(end 180.423058 -315.898784)
		(width 0.20066)
		(layer "F.Cu")
		(net "M_F_CPU1_SA_DQ<2>")
	)
	(segment
		(start 180.423058 -315.898784)
		(end 180.427884 -315.898784)
		(width 0.101854)
		(layer "F.Cu")
		(net "M_F_CPU1_SA_DQ<2>")
	)
	(segment
		(start 184.210452 -315.46673)
		(end 185.544714 -315.46673)
		(width 0.20066)
		(layer "F.Cu")
		(net "M_F_CPU1_SA_DQ<2>")
	)
	(segment
		(start 178.000914 -315.46673)
		(end 179.699158 -315.46673)
		(width 0.20066)
		(layer "F.Cu")
		(net "M_F_CPU1_SA_DQ<2>")
	)
	(segment
		(start 183.958484 -315.214762)
		(end 184.210452 -315.46673)
		(width 0.20066)
		(layer "F.Cu")
		(net "M_F_CPU1_SA_DQ<2>")
	)
	(segment
		(start 176.896014 -315.46673)
		(end 178.000914 -315.46673)
		(width 0.20066)
		(layer "F.Cu")
		(net "M_F_CPU1_SA_DQ<2>")
	)
	(segment
		(start 133.365494 -277.800562)
		(end 133.365494 -278.336248)
		(width 0.20066)
		(layer "F.Cu")
		(net "M_F_CPU1_SA_DQ<2>")
	)
	(segment
		(start 183.340248 -315.44895)
		(end 183.574436 -315.214762)
		(width 0.20066)
		(layer "F.Cu")
		(net "M_F_CPU1_SA_DQ<2>")
	)
	(segment
		(start 180.434996 -315.891672)
		(end 182.442866 -315.891672)
		(width 0.1016)
		(layer "F.Cu")
		(net "M_F_CPU1_SA_DQ<2>")
	)
	(segment
		(start 182.442866 -315.891672)
		(end 182.455058 -315.903864)
		(width 0.1016)
		(layer "F.Cu")
		(net "M_F_CPU1_SA_DQ<2>")
	)
	(segment
		(start 180.427884 -315.898784)
		(end 180.434996 -315.891672)
		(width 0.1016)
		(layer "F.Cu")
		(net "M_F_CPU1_SA_DQ<2>")
	)
	(segment
		(start 183.136286 -315.903864)
		(end 183.340248 -315.699902)
		(width 0.20066)
		(layer "F.Cu")
		(net "M_F_CPU1_SA_DQ<2>")
	)
	(segment
		(start 182.455058 -315.903864)
		(end 183.136286 -315.903864)
		(width 0.20066)
		(layer "F.Cu")
		(net "M_F_CPU1_SA_DQ<2>")
	)
	(segment
		(start 133.365494 -278.336248)
		(end 133.365748 -278.336502)
		(width 0.20066)
		(layer "F.Cu")
		(net "M_F_CPU1_SA_DQ<2>")
	)
	(segment
		(start 156.992828 -315.62548)
		(end 146.014186 -304.646838)
		(width 0.18288)
		(layer "In2.Cu")
		(net "M_F_CPU1_SA_DQ<2>")
	)
	(segment
		(start 133.05282 -278.336502)
		(end 133.365748 -278.336502)
		(width 0.088646)
		(layer "In2.Cu")
		(net "M_F_CPU1_SA_DQ<2>")
	)
	(segment
		(start 140.990828 -283.90342)
		(end 139.79271 -281.011376)
		(width 0.18288)
		(layer "In2.Cu")
		(net "M_F_CPU1_SA_DQ<2>")
	)
	(segment
		(start 164.663374 -315.87059)
		(end 160.571688 -315.87059)
		(width 0.18288)
		(layer "In2.Cu")
		(net "M_F_CPU1_SA_DQ<2>")
	)
	(segment
		(start 175.130968 -315.93409)
		(end 173.699678 -315.93409)
		(width 0.18288)
		(layer "In2.Cu")
		(net "M_F_CPU1_SA_DQ<2>")
	)
	(segment
		(start 133.460998 -279.158954)
		(end 133.460998 -279.140412)
		(width 0.088646)
		(layer "In2.Cu")
		(net "M_F_CPU1_SA_DQ<2>")
	)
	(segment
		(start 132.99567 -278.393652)
		(end 133.05282 -278.336502)
		(width 0.088646)
		(layer "In2.Cu")
		(net "M_F_CPU1_SA_DQ<2>")
	)
	(segment
		(start 139.79271 -281.011376)
		(end 139.148058 -280.366724)
		(width 0.18288)
		(layer "In2.Cu")
		(net "M_F_CPU1_SA_DQ<2>")
	)
	(segment
		(start 160.498028 -315.90107)
		(end 157.508194 -315.90107)
		(width 0.18288)
		(layer "In2.Cu")
		(net "M_F_CPU1_SA_DQ<2>")
	)
	(segment
		(start 173.699678 -315.93409)
		(end 173.211998 -315.89091)
		(width 0.18288)
		(layer "In2.Cu")
		(net "M_F_CPU1_SA_DQ<2>")
	)
	(segment
		(start 146.014186 -298.65828)
		(end 144.689068 -295.458896)
		(width 0.18288)
		(layer "In2.Cu")
		(net "M_F_CPU1_SA_DQ<2>")
	)
	(segment
		(start 141.369034 -290.179252)
		(end 141.369034 -284.281626)
		(width 0.18288)
		(layer "In2.Cu")
		(net "M_F_CPU1_SA_DQ<2>")
	)
	(segment
		(start 157.508194 -315.90107)
		(end 156.992828 -315.62548)
		(width 0.18288)
		(layer "In2.Cu")
		(net "M_F_CPU1_SA_DQ<2>")
	)
	(segment
		(start 142.754604 -293.524432)
		(end 141.369034 -290.179252)
		(width 0.18288)
		(layer "In2.Cu")
		(net "M_F_CPU1_SA_DQ<2>")
	)
	(segment
		(start 176.896014 -315.46673)
		(end 176.355502 -315.690504)
		(width 0.18288)
		(layer "In2.Cu")
		(net "M_F_CPU1_SA_DQ<2>")
	)
	(segment
		(start 176.355502 -315.690504)
		(end 175.130968 -315.93409)
		(width 0.18288)
		(layer "In2.Cu")
		(net "M_F_CPU1_SA_DQ<2>")
	)
	(segment
		(start 160.571688 -315.87059)
		(end 160.498028 -315.90107)
		(width 0.18288)
		(layer "In2.Cu")
		(net "M_F_CPU1_SA_DQ<2>")
	)
	(segment
		(start 138.99388 -280.212546)
		(end 138.534648 -280.212546)
		(width 0.088646)
		(layer "In2.Cu")
		(net "M_F_CPU1_SA_DQ<2>")
	)
	(segment
		(start 146.014186 -304.646838)
		(end 146.014186 -298.65828)
		(width 0.18288)
		(layer "In2.Cu")
		(net "M_F_CPU1_SA_DQ<2>")
	)
	(segment
		(start 135.997696 -280.288492)
		(end 135.987282 -280.282396)
		(width 0.088646)
		(layer "In2.Cu")
		(net "M_F_CPU1_SA_DQ<2>")
	)
	(segment
		(start 133.17855 -278.66086)
		(end 133.16966 -278.65578)
		(width 0.088646)
		(layer "In2.Cu")
		(net "M_F_CPU1_SA_DQ<2>")
	)
	(segment
		(start 172.162724 -315.89091)
		(end 172.121576 -315.873892)
		(width 0.18288)
		(layer "In2.Cu")
		(net "M_F_CPU1_SA_DQ<2>")
	)
	(segment
		(start 134.11835 -280.288492)
		(end 134.10946 -280.283412)
		(width 0.088646)
		(layer "In2.Cu")
		(net "M_F_CPU1_SA_DQ<2>")
	)
	(segment
		(start 139.148058 -280.366724)
		(end 138.99388 -280.212546)
		(width 0.088646)
		(layer "In2.Cu")
		(net "M_F_CPU1_SA_DQ<2>")
	)
	(segment
		(start 168.053004 -315.90107)
		(end 164.737034 -315.90107)
		(width 0.18288)
		(layer "In2.Cu")
		(net "M_F_CPU1_SA_DQ<2>")
	)
	(segment
		(start 164.737034 -315.90107)
		(end 164.663374 -315.87059)
		(width 0.18288)
		(layer "In2.Cu")
		(net "M_F_CPU1_SA_DQ<2>")
	)
	(segment
		(start 141.369034 -284.281626)
		(end 140.990828 -283.90342)
		(width 0.18288)
		(layer "In2.Cu")
		(net "M_F_CPU1_SA_DQ<2>")
	)
	(segment
		(start 173.211998 -315.89091)
		(end 172.162724 -315.89091)
		(width 0.18288)
		(layer "In2.Cu")
		(net "M_F_CPU1_SA_DQ<2>")
	)
	(segment
		(start 133.654292 -279.478232)
		(end 133.648196 -279.474676)
		(width 0.088646)
		(layer "In2.Cu")
		(net "M_F_CPU1_SA_DQ<2>")
	)
	(segment
		(start 144.689068 -295.458896)
		(end 142.754604 -293.524432)
		(width 0.18288)
		(layer "In2.Cu")
		(net "M_F_CPU1_SA_DQ<2>")
	)
	(segment
		(start 172.121576 -315.873892)
		(end 168.118536 -315.873892)
		(width 0.18288)
		(layer "In2.Cu")
		(net "M_F_CPU1_SA_DQ<2>")
	)
	(segment
		(start 168.118536 -315.873892)
		(end 168.053004 -315.90107)
		(width 0.18288)
		(layer "In2.Cu")
		(net "M_F_CPU1_SA_DQ<2>")
	)
	(arc
		(start 133.16966 -278.65578)
		(mid 133.053851 -278.543851)
		(end 132.99567 -278.393652)
		(width 0.088646)
		(layer "In2.Cu")
		(net "M_F_CPU1_SA_DQ<2>")
	)
	(arc
		(start 137.311892 -280.288492)
		(mid 137.124694 -280.338635)
		(end 136.937496 -280.288492)
		(width 0.088646)
		(layer "In2.Cu")
		(net "M_F_CPU1_SA_DQ<2>")
	)
	(arc
		(start 133.648196 -279.474676)
		(mid 133.513263 -279.341322)
		(end 133.460998 -279.158954)
		(width 0.088646)
		(layer "In2.Cu")
		(net "M_F_CPU1_SA_DQ<2>")
	)
	(arc
		(start 135.432038 -280.288492)
		(mid 135.24484 -280.338635)
		(end 135.057642 -280.288492)
		(width 0.088646)
		(layer "In2.Cu")
		(net "M_F_CPU1_SA_DQ<2>")
	)
	(arc
		(start 136.372092 -280.288492)
		(mid 136.184894 -280.338635)
		(end 135.997696 -280.288492)
		(width 0.088646)
		(layer "In2.Cu")
		(net "M_F_CPU1_SA_DQ<2>")
	)
	(arc
		(start 137.877296 -280.288492)
		(mid 137.594594 -280.21275)
		(end 137.311892 -280.288492)
		(width 0.088646)
		(layer "In2.Cu")
		(net "M_F_CPU1_SA_DQ<2>")
	)
	(arc
		(start 133.460998 -279.140412)
		(mid 133.382887 -278.863463)
		(end 133.17855 -278.66086)
		(width 0.088646)
		(layer "In2.Cu")
		(net "M_F_CPU1_SA_DQ<2>")
	)
	(arc
		(start 135.987282 -280.282396)
		(mid 135.70885 -280.212582)
		(end 135.432038 -280.288492)
		(width 0.088646)
		(layer "In2.Cu")
		(net "M_F_CPU1_SA_DQ<2>")
	)
	(arc
		(start 134.10946 -280.283412)
		(mid 133.978546 -280.147052)
		(end 133.930898 -279.964134)
		(width 0.088646)
		(layer "In2.Cu")
		(net "M_F_CPU1_SA_DQ<2>")
	)
	(arc
		(start 135.057642 -280.288492)
		(mid 134.775194 -280.212877)
		(end 134.492746 -280.288492)
		(width 0.088646)
		(layer "In2.Cu")
		(net "M_F_CPU1_SA_DQ<2>")
	)
	(arc
		(start 133.930898 -279.964134)
		(mid 133.856907 -279.684568)
		(end 133.654292 -279.478232)
		(width 0.088646)
		(layer "In2.Cu")
		(net "M_F_CPU1_SA_DQ<2>")
	)
	(arc
		(start 136.937496 -280.288492)
		(mid 136.654794 -280.21275)
		(end 136.372092 -280.288492)
		(width 0.088646)
		(layer "In2.Cu")
		(net "M_F_CPU1_SA_DQ<2>")
	)
	(arc
		(start 134.492746 -280.288492)
		(mid 134.305548 -280.338635)
		(end 134.11835 -280.288492)
		(width 0.088646)
		(layer "In2.Cu")
		(net "M_F_CPU1_SA_DQ<2>")
	)
	(arc
		(start 138.534648 -280.212546)
		(mid 138.388178 -280.231906)
		(end 138.251692 -280.288492)
		(width 0.088646)
		(layer "In2.Cu")
		(net "M_F_CPU1_SA_DQ<2>")
	)
	(arc
		(start 138.251692 -280.288492)
		(mid 138.064494 -280.338635)
		(end 137.877296 -280.288492)
		(width 0.088646)
		(layer "In2.Cu")
		(net "M_F_CPU1_SA_DQ<2>")
	)
	(segment
		(start 173.900846 -280.61666)
		(end 172.795946 -280.61666)
		(width 0.20066)
		(layer "F.Cu")
		(net "M_F_CPU1_SA_DQ<29>")
	)
	(segment
		(start 175.67021 -280.865326)
		(end 175.421544 -280.61666)
		(width 0.20066)
		(layer "F.Cu")
		(net "M_F_CPU1_SA_DQ<29>")
	)
	(segment
		(start 176.816258 -280.191718)
		(end 176.796192 -280.191718)
		(width 0.101854)
		(layer "F.Cu")
		(net "M_F_CPU1_SA_DQ<29>")
	)
	(segment
		(start 181.444392 -280.616914)
		(end 179.852828 -280.616914)
		(width 0.20066)
		(layer "F.Cu")
		(net "M_F_CPU1_SA_DQ<29>")
	)
	(segment
		(start 176.145444 -280.865326)
		(end 175.67021 -280.865326)
		(width 0.20066)
		(layer "F.Cu")
		(net "M_F_CPU1_SA_DQ<29>")
	)
	(segment
		(start 176.796192 -280.191718)
		(end 176.451514 -280.191718)
		(width 0.20066)
		(layer "F.Cu")
		(net "M_F_CPU1_SA_DQ<29>")
	)
	(segment
		(start 181.444646 -280.61666)
		(end 181.444392 -280.616914)
		(width 0.20066)
		(layer "F.Cu")
		(net "M_F_CPU1_SA_DQ<29>")
	)
	(segment
		(start 179.852828 -280.616914)
		(end 179.421282 -280.185368)
		(width 0.20066)
		(layer "F.Cu")
		(net "M_F_CPU1_SA_DQ<29>")
	)
	(segment
		(start 130.546348 -258.267454)
		(end 130.546348 -258.80314)
		(width 0.20066)
		(layer "F.Cu")
		(net "M_F_CPU1_SA_DQ<29>")
	)
	(segment
		(start 176.333404 -280.309828)
		(end 176.333404 -280.677366)
		(width 0.20066)
		(layer "F.Cu")
		(net "M_F_CPU1_SA_DQ<29>")
	)
	(segment
		(start 179.004976 -280.191718)
		(end 176.816258 -280.191718)
		(width 0.1016)
		(layer "F.Cu")
		(net "M_F_CPU1_SA_DQ<29>")
	)
	(segment
		(start 175.421544 -280.61666)
		(end 173.900846 -280.61666)
		(width 0.20066)
		(layer "F.Cu")
		(net "M_F_CPU1_SA_DQ<29>")
	)
	(segment
		(start 176.333404 -280.677366)
		(end 176.145444 -280.865326)
		(width 0.20066)
		(layer "F.Cu")
		(net "M_F_CPU1_SA_DQ<29>")
	)
	(segment
		(start 176.451514 -280.191718)
		(end 176.333404 -280.309828)
		(width 0.20066)
		(layer "F.Cu")
		(net "M_F_CPU1_SA_DQ<29>")
	)
	(segment
		(start 179.421282 -280.185368)
		(end 179.011326 -280.185368)
		(width 0.20066)
		(layer "F.Cu")
		(net "M_F_CPU1_SA_DQ<29>")
	)
	(segment
		(start 130.546094 -258.2672)
		(end 130.546348 -258.267454)
		(width 0.20066)
		(layer "F.Cu")
		(net "M_F_CPU1_SA_DQ<29>")
	)
	(segment
		(start 179.011326 -280.185368)
		(end 179.004976 -280.191718)
		(width 0.1016)
		(layer "F.Cu")
		(net "M_F_CPU1_SA_DQ<29>")
	)
	(segment
		(start 132.08381 -258.597654)
		(end 131.98602 -258.695444)
		(width 0.088646)
		(layer "In4.Cu")
		(net "M_F_CPU1_SA_DQ<29>")
	)
	(segment
		(start 161.310574 -269.140178)
		(end 160.297622 -268.127226)
		(width 0.18288)
		(layer "In4.Cu")
		(net "M_F_CPU1_SA_DQ<29>")
	)
	(segment
		(start 132.627878 -258.487418)
		(end 132.613146 -258.478782)
		(width 0.088646)
		(layer "In4.Cu")
		(net "M_F_CPU1_SA_DQ<29>")
	)
	(segment
		(start 173.593506 -273.820636)
		(end 173.753526 -273.660616)
		(width 0.18288)
		(layer "In4.Cu")
		(net "M_F_CPU1_SA_DQ<29>")
	)
	(segment
		(start 173.97222 -273.500596)
		(end 173.97222 -273.152616)
		(width 0.18288)
		(layer "In4.Cu")
		(net "M_F_CPU1_SA_DQ<29>")
	)
	(segment
		(start 139.568936 -258.765802)
		(end 138.557 -258.765802)
		(width 0.088646)
		(layer "In4.Cu")
		(net "M_F_CPU1_SA_DQ<29>")
	)
	(segment
		(start 138.557 -258.765802)
		(end 138.329416 -258.538218)
		(width 0.088646)
		(layer "In4.Cu")
		(net "M_F_CPU1_SA_DQ<29>")
	)
	(segment
		(start 172.188632 -271.6911)
		(end 172.107606 -271.772126)
		(width 0.18288)
		(layer "In4.Cu")
		(net "M_F_CPU1_SA_DQ<29>")
	)
	(segment
		(start 173.593506 -272.183606)
		(end 173.101 -271.6911)
		(width 0.18288)
		(layer "In4.Cu")
		(net "M_F_CPU1_SA_DQ<29>")
	)
	(segment
		(start 169.412412 -270.654018)
		(end 168.382188 -270.654018)
		(width 0.18288)
		(layer "In4.Cu")
		(net "M_F_CPU1_SA_DQ<29>")
	)
	(segment
		(start 173.753526 -274.996656)
		(end 173.8122 -274.996656)
		(width 0.18288)
		(layer "In4.Cu")
		(net "M_F_CPU1_SA_DQ<29>")
	)
	(segment
		(start 160.297622 -268.127226)
		(end 159.44215 -268.127226)
		(width 0.18288)
		(layer "In4.Cu")
		(net "M_F_CPU1_SA_DQ<29>")
	)
	(segment
		(start 131.802632 -259.138674)
		(end 131.754626 -259.186426)
		(width 0.088646)
		(layer "In4.Cu")
		(net "M_F_CPU1_SA_DQ<29>")
	)
	(segment
		(start 150.359872 -260.382512)
		(end 146.450812 -260.382512)
		(width 0.18288)
		(layer "In4.Cu")
		(net "M_F_CPU1_SA_DQ<29>")
	)
	(segment
		(start 157.583632 -267.606272)
		(end 150.359872 -260.382512)
		(width 0.18288)
		(layer "In4.Cu")
		(net "M_F_CPU1_SA_DQ<29>")
	)
	(segment
		(start 173.97222 -273.152616)
		(end 173.8122 -272.992596)
		(width 0.18288)
		(layer "In4.Cu")
		(net "M_F_CPU1_SA_DQ<29>")
	)
	(segment
		(start 159.44215 -268.127226)
		(end 158.921196 -267.606272)
		(width 0.18288)
		(layer "In4.Cu")
		(net "M_F_CPU1_SA_DQ<29>")
	)
	(segment
		(start 173.97222 -274.836636)
		(end 173.97222 -274.488656)
		(width 0.18288)
		(layer "In4.Cu")
		(net "M_F_CPU1_SA_DQ<29>")
	)
	(segment
		(start 168.382188 -270.654018)
		(end 167.654986 -269.926816)
		(width 0.18288)
		(layer "In4.Cu")
		(net "M_F_CPU1_SA_DQ<29>")
	)
	(segment
		(start 173.753526 -274.328636)
		(end 173.593506 -274.168616)
		(width 0.18288)
		(layer "In4.Cu")
		(net "M_F_CPU1_SA_DQ<29>")
	)
	(segment
		(start 172.107606 -271.772126)
		(end 170.53052 -271.772126)
		(width 0.18288)
		(layer "In4.Cu")
		(net "M_F_CPU1_SA_DQ<29>")
	)
	(segment
		(start 173.753526 -272.992596)
		(end 173.593506 -272.832576)
		(width 0.18288)
		(layer "In4.Cu")
		(net "M_F_CPU1_SA_DQ<29>")
	)
	(segment
		(start 173.8122 -274.996656)
		(end 173.97222 -274.836636)
		(width 0.18288)
		(layer "In4.Cu")
		(net "M_F_CPU1_SA_DQ<29>")
	)
	(segment
		(start 163.812474 -269.140178)
		(end 161.310574 -269.140178)
		(width 0.18288)
		(layer "In4.Cu")
		(net "M_F_CPU1_SA_DQ<29>")
	)
	(segment
		(start 173.8122 -272.992596)
		(end 173.753526 -272.992596)
		(width 0.18288)
		(layer "In4.Cu")
		(net "M_F_CPU1_SA_DQ<29>")
	)
	(segment
		(start 146.450812 -260.382512)
		(end 146.18335 -260.329172)
		(width 0.18288)
		(layer "In4.Cu")
		(net "M_F_CPU1_SA_DQ<29>")
	)
	(segment
		(start 164.520626 -269.041626)
		(end 163.911026 -269.041626)
		(width 0.18288)
		(layer "In4.Cu")
		(net "M_F_CPU1_SA_DQ<29>")
	)
	(segment
		(start 173.593506 -279.8191)
		(end 173.593506 -275.156676)
		(width 0.18288)
		(layer "In4.Cu")
		(net "M_F_CPU1_SA_DQ<29>")
	)
	(segment
		(start 173.8122 -274.328636)
		(end 173.753526 -274.328636)
		(width 0.18288)
		(layer "In4.Cu")
		(net "M_F_CPU1_SA_DQ<29>")
	)
	(segment
		(start 163.911026 -269.041626)
		(end 163.812474 -269.140178)
		(width 0.18288)
		(layer "In4.Cu")
		(net "M_F_CPU1_SA_DQ<29>")
	)
	(segment
		(start 167.654986 -269.926816)
		(end 165.405816 -269.926816)
		(width 0.18288)
		(layer "In4.Cu")
		(net "M_F_CPU1_SA_DQ<29>")
	)
	(segment
		(start 173.101 -271.6911)
		(end 172.188632 -271.6911)
		(width 0.18288)
		(layer "In4.Cu")
		(net "M_F_CPU1_SA_DQ<29>")
	)
	(segment
		(start 173.97222 -274.488656)
		(end 173.8122 -274.328636)
		(width 0.18288)
		(layer "In4.Cu")
		(net "M_F_CPU1_SA_DQ<29>")
	)
	(segment
		(start 137.877296 -258.478782)
		(end 137.862564 -258.487418)
		(width 0.088646)
		(layer "In4.Cu")
		(net "M_F_CPU1_SA_DQ<29>")
	)
	(segment
		(start 172.795946 -280.61666)
		(end 173.593506 -279.8191)
		(width 0.18288)
		(layer "In4.Cu")
		(net "M_F_CPU1_SA_DQ<29>")
	)
	(segment
		(start 170.53052 -271.772126)
		(end 169.412412 -270.654018)
		(width 0.18288)
		(layer "In4.Cu")
		(net "M_F_CPU1_SA_DQ<29>")
	)
	(segment
		(start 173.593506 -272.832576)
		(end 173.593506 -272.183606)
		(width 0.18288)
		(layer "In4.Cu")
		(net "M_F_CPU1_SA_DQ<29>")
	)
	(segment
		(start 136.937496 -258.478782)
		(end 136.922764 -258.487418)
		(width 0.088646)
		(layer "In4.Cu")
		(net "M_F_CPU1_SA_DQ<29>")
	)
	(segment
		(start 173.593506 -274.168616)
		(end 173.593506 -273.820636)
		(width 0.18288)
		(layer "In4.Cu")
		(net "M_F_CPU1_SA_DQ<29>")
	)
	(segment
		(start 130.852926 -259.021326)
		(end 130.546348 -258.80314)
		(width 0.088646)
		(layer "In4.Cu")
		(net "M_F_CPU1_SA_DQ<29>")
	)
	(segment
		(start 173.753526 -273.660616)
		(end 173.8122 -273.660616)
		(width 0.18288)
		(layer "In4.Cu")
		(net "M_F_CPU1_SA_DQ<29>")
	)
	(segment
		(start 158.921196 -267.606272)
		(end 157.583632 -267.606272)
		(width 0.18288)
		(layer "In4.Cu")
		(net "M_F_CPU1_SA_DQ<29>")
	)
	(segment
		(start 146.18335 -260.329172)
		(end 144.8943 -260.072886)
		(width 0.18288)
		(layer "In4.Cu")
		(net "M_F_CPU1_SA_DQ<29>")
	)
	(segment
		(start 134.50316 -258.484878)
		(end 134.492746 -258.478782)
		(width 0.088646)
		(layer "In4.Cu")
		(net "M_F_CPU1_SA_DQ<29>")
	)
	(segment
		(start 141.738858 -258.765802)
		(end 139.568936 -258.765802)
		(width 0.18288)
		(layer "In4.Cu")
		(net "M_F_CPU1_SA_DQ<29>")
	)
	(segment
		(start 173.8122 -273.660616)
		(end 173.97222 -273.500596)
		(width 0.18288)
		(layer "In4.Cu")
		(net "M_F_CPU1_SA_DQ<29>")
	)
	(segment
		(start 173.593506 -275.156676)
		(end 173.753526 -274.996656)
		(width 0.18288)
		(layer "In4.Cu")
		(net "M_F_CPU1_SA_DQ<29>")
	)
	(segment
		(start 165.405816 -269.926816)
		(end 164.520626 -269.041626)
		(width 0.18288)
		(layer "In4.Cu")
		(net "M_F_CPU1_SA_DQ<29>")
	)
	(segment
		(start 144.8943 -260.072886)
		(end 141.738858 -258.765802)
		(width 0.18288)
		(layer "In4.Cu")
		(net "M_F_CPU1_SA_DQ<29>")
	)
	(arc
		(start 134.11835 -258.478782)
		(mid 133.835648 -258.554524)
		(end 133.552946 -258.478782)
		(width 0.088646)
		(layer "In4.Cu")
		(net "M_F_CPU1_SA_DQ<29>")
	)
	(arc
		(start 135.432292 -258.478782)
		(mid 135.245094 -258.428639)
		(end 135.057896 -258.478782)
		(width 0.088646)
		(layer "In4.Cu")
		(net "M_F_CPU1_SA_DQ<29>")
	)
	(arc
		(start 136.372092 -258.478782)
		(mid 136.184894 -258.428639)
		(end 135.997696 -258.478782)
		(width 0.088646)
		(layer "In4.Cu")
		(net "M_F_CPU1_SA_DQ<29>")
	)
	(arc
		(start 133.17855 -258.478782)
		(mid 132.904321 -258.554707)
		(end 132.627878 -258.487418)
		(width 0.088646)
		(layer "In4.Cu")
		(net "M_F_CPU1_SA_DQ<29>")
	)
	(arc
		(start 131.754626 -259.186426)
		(mid 131.286429 -259.198638)
		(end 130.852926 -259.021326)
		(width 0.088646)
		(layer "In4.Cu")
		(net "M_F_CPU1_SA_DQ<29>")
	)
	(arc
		(start 138.329416 -258.538218)
		(mid 138.292506 -258.505947)
		(end 138.251692 -258.478782)
		(width 0.088646)
		(layer "In4.Cu")
		(net "M_F_CPU1_SA_DQ<29>")
	)
	(arc
		(start 131.93776 -258.81203)
		(mid 131.902693 -258.988796)
		(end 131.802632 -259.138674)
		(width 0.088646)
		(layer "In4.Cu")
		(net "M_F_CPU1_SA_DQ<29>")
	)
	(arc
		(start 137.862564 -258.487418)
		(mid 137.586123 -258.554584)
		(end 137.311892 -258.478782)
		(width 0.088646)
		(layer "In4.Cu")
		(net "M_F_CPU1_SA_DQ<29>")
	)
	(arc
		(start 135.997696 -258.478782)
		(mid 135.714994 -258.554524)
		(end 135.432292 -258.478782)
		(width 0.088646)
		(layer "In4.Cu")
		(net "M_F_CPU1_SA_DQ<29>")
	)
	(arc
		(start 136.922764 -258.487418)
		(mid 136.646323 -258.554584)
		(end 136.372092 -258.478782)
		(width 0.088646)
		(layer "In4.Cu")
		(net "M_F_CPU1_SA_DQ<29>")
	)
	(arc
		(start 138.251692 -258.478782)
		(mid 138.064494 -258.428639)
		(end 137.877296 -258.478782)
		(width 0.088646)
		(layer "In4.Cu")
		(net "M_F_CPU1_SA_DQ<29>")
	)
	(arc
		(start 132.613146 -258.478782)
		(mid 132.425948 -258.428639)
		(end 132.23875 -258.478782)
		(width 0.088646)
		(layer "In4.Cu")
		(net "M_F_CPU1_SA_DQ<29>")
	)
	(arc
		(start 132.23875 -258.478782)
		(mid 132.15738 -258.533135)
		(end 132.08381 -258.597654)
		(width 0.088646)
		(layer "In4.Cu")
		(net "M_F_CPU1_SA_DQ<29>")
	)
	(arc
		(start 137.311892 -258.478782)
		(mid 137.124694 -258.428639)
		(end 136.937496 -258.478782)
		(width 0.088646)
		(layer "In4.Cu")
		(net "M_F_CPU1_SA_DQ<29>")
	)
	(arc
		(start 135.057896 -258.478782)
		(mid 134.781337 -258.554491)
		(end 134.50316 -258.484878)
		(width 0.088646)
		(layer "In4.Cu")
		(net "M_F_CPU1_SA_DQ<29>")
	)
	(arc
		(start 133.552946 -258.478782)
		(mid 133.365748 -258.428639)
		(end 133.17855 -258.478782)
		(width 0.088646)
		(layer "In4.Cu")
		(net "M_F_CPU1_SA_DQ<29>")
	)
	(arc
		(start 131.98602 -258.695444)
		(mid 131.950279 -258.748934)
		(end 131.93776 -258.81203)
		(width 0.088646)
		(layer "In4.Cu")
		(net "M_F_CPU1_SA_DQ<29>")
	)
	(arc
		(start 134.492746 -258.478782)
		(mid 134.305548 -258.428639)
		(end 134.11835 -258.478782)
		(width 0.088646)
		(layer "In4.Cu")
		(net "M_F_CPU1_SA_DQ<29>")
	)
	(segment
		(start 176.796192 -281.89174)
		(end 176.451514 -281.89174)
		(width 0.20066)
		(layer "F.Cu")
		(net "M_F_CPU1_SA_DQ<28>")
	)
	(segment
		(start 179.421282 -281.88539)
		(end 179.011326 -281.88539)
		(width 0.20066)
		(layer "F.Cu")
		(net "M_F_CPU1_SA_DQ<28>")
	)
	(segment
		(start 175.67021 -282.565348)
		(end 175.421544 -282.316682)
		(width 0.20066)
		(layer "F.Cu")
		(net "M_F_CPU1_SA_DQ<28>")
	)
	(segment
		(start 176.451514 -281.89174)
		(end 176.333404 -282.00985)
		(width 0.20066)
		(layer "F.Cu")
		(net "M_F_CPU1_SA_DQ<28>")
	)
	(segment
		(start 176.843182 -281.89174)
		(end 176.796192 -281.89174)
		(width 0.101854)
		(layer "F.Cu")
		(net "M_F_CPU1_SA_DQ<28>")
	)
	(segment
		(start 181.444392 -282.316936)
		(end 179.852828 -282.316936)
		(width 0.20066)
		(layer "F.Cu")
		(net "M_F_CPU1_SA_DQ<28>")
	)
	(segment
		(start 181.444646 -282.316682)
		(end 181.444392 -282.316936)
		(width 0.20066)
		(layer "F.Cu")
		(net "M_F_CPU1_SA_DQ<28>")
	)
	(segment
		(start 179.011326 -281.88539)
		(end 179.004976 -281.89174)
		(width 0.1016)
		(layer "F.Cu")
		(net "M_F_CPU1_SA_DQ<28>")
	)
	(segment
		(start 179.004976 -281.89174)
		(end 176.843182 -281.89174)
		(width 0.1016)
		(layer "F.Cu")
		(net "M_F_CPU1_SA_DQ<28>")
	)
	(segment
		(start 173.900846 -282.316682)
		(end 172.795946 -282.316682)
		(width 0.20066)
		(layer "F.Cu")
		(net "M_F_CPU1_SA_DQ<28>")
	)
	(segment
		(start 176.333404 -282.377388)
		(end 176.145444 -282.565348)
		(width 0.20066)
		(layer "F.Cu")
		(net "M_F_CPU1_SA_DQ<28>")
	)
	(segment
		(start 175.421544 -282.316682)
		(end 173.900846 -282.316682)
		(width 0.20066)
		(layer "F.Cu")
		(net "M_F_CPU1_SA_DQ<28>")
	)
	(segment
		(start 176.333404 -282.00985)
		(end 176.333404 -282.377388)
		(width 0.20066)
		(layer "F.Cu")
		(net "M_F_CPU1_SA_DQ<28>")
	)
	(segment
		(start 179.852828 -282.316936)
		(end 179.421282 -281.88539)
		(width 0.20066)
		(layer "F.Cu")
		(net "M_F_CPU1_SA_DQ<28>")
	)
	(segment
		(start 130.076448 -259.081016)
		(end 130.076448 -259.093462)
		(width 0.20066)
		(layer "F.Cu")
		(net "M_F_CPU1_SA_DQ<28>")
	)
	(segment
		(start 176.145444 -282.565348)
		(end 175.67021 -282.565348)
		(width 0.20066)
		(layer "F.Cu")
		(net "M_F_CPU1_SA_DQ<28>")
	)
	(segment
		(start 130.076448 -259.093462)
		(end 130.076194 -259.616956)
		(width 0.20066)
		(layer "F.Cu")
		(net "M_F_CPU1_SA_DQ<28>")
	)
	(segment
		(start 159.497014 -269.930626)
		(end 158.707074 -269.140686)
		(width 0.18288)
		(layer "In4.Cu")
		(net "M_F_CPU1_SA_DQ<28>")
	)
	(segment
		(start 171.792138 -279.90927)
		(end 171.792138 -279.58161)
		(width 0.18288)
		(layer "In4.Cu")
		(net "M_F_CPU1_SA_DQ<28>")
	)
	(segment
		(start 133.090412 -259.296662)
		(end 133.078474 -259.289804)
		(width 0.088646)
		(layer "In4.Cu")
		(net "M_F_CPU1_SA_DQ<28>")
	)
	(segment
		(start 162.682936 -271.032224)
		(end 162.444938 -270.794226)
		(width 0.18288)
		(layer "In4.Cu")
		(net "M_F_CPU1_SA_DQ<28>")
	)
	(segment
		(start 141.566392 -259.451856)
		(end 139.55395 -259.451856)
		(width 0.18288)
		(layer "In4.Cu")
		(net "M_F_CPU1_SA_DQ<28>")
	)
	(segment
		(start 172.12437 -281.885898)
		(end 171.038774 -280.800302)
		(width 0.18288)
		(layer "In4.Cu")
		(net "M_F_CPU1_SA_DQ<28>")
	)
	(segment
		(start 149.770592 -261.378192)
		(end 146.06016 -261.378192)
		(width 0.18288)
		(layer "In4.Cu")
		(net "M_F_CPU1_SA_DQ<28>")
	)
	(segment
		(start 163.195 -271.032224)
		(end 162.682936 -271.032224)
		(width 0.18288)
		(layer "In4.Cu")
		(net "M_F_CPU1_SA_DQ<28>")
	)
	(segment
		(start 134.022846 -259.292344)
		(end 134.018274 -259.289804)
		(width 0.088646)
		(layer "In4.Cu")
		(net "M_F_CPU1_SA_DQ<28>")
	)
	(segment
		(start 164.434266 -271.035526)
		(end 164.428678 -271.035526)
		(width 0.18288)
		(layer "In4.Cu")
		(net "M_F_CPU1_SA_DQ<28>")
	)
	(segment
		(start 135.527542 -259.292598)
		(end 135.527288 -259.292598)
		(width 0.088646)
		(layer "In4.Cu")
		(net "M_F_CPU1_SA_DQ<28>")
	)
	(segment
		(start 170.101768 -273.741896)
		(end 169.869866 -273.509994)
		(width 0.18288)
		(layer "In4.Cu")
		(net "M_F_CPU1_SA_DQ<28>")
	)
	(segment
		(start 162.444938 -270.794226)
		(end 161.396426 -270.794226)
		(width 0.18288)
		(layer "In4.Cu")
		(net "M_F_CPU1_SA_DQ<28>")
	)
	(segment
		(start 171.038774 -280.27503)
		(end 171.221654 -280.09215)
		(width 0.18288)
		(layer "In4.Cu")
		(net "M_F_CPU1_SA_DQ<28>")
	)
	(segment
		(start 171.221654 -279.39873)
		(end 171.038774 -279.21585)
		(width 0.18288)
		(layer "In4.Cu")
		(net "M_F_CPU1_SA_DQ<28>")
	)
	(segment
		(start 146.06016 -261.378192)
		(end 145.405602 -261.107174)
		(width 0.18288)
		(layer "In4.Cu")
		(net "M_F_CPU1_SA_DQ<28>")
	)
	(segment
		(start 170.87977 -275.442934)
		(end 170.87977 -275.184362)
		(width 0.18288)
		(layer "In4.Cu")
		(net "M_F_CPU1_SA_DQ<28>")
	)
	(segment
		(start 132.396484 -259.69468)
		(end 132.348732 -259.769356)
		(width 0.088646)
		(layer "In4.Cu")
		(net "M_F_CPU1_SA_DQ<28>")
	)
	(segment
		(start 171.038774 -275.601938)
		(end 170.87977 -275.442934)
		(width 0.18288)
		(layer "In4.Cu")
		(net "M_F_CPU1_SA_DQ<28>")
	)
	(segment
		(start 166.275258 -272.380456)
		(end 165.457632 -271.56283)
		(width 0.18288)
		(layer "In4.Cu")
		(net "M_F_CPU1_SA_DQ<28>")
	)
	(segment
		(start 163.432998 -270.794226)
		(end 163.195 -271.032224)
		(width 0.18288)
		(layer "In4.Cu")
		(net "M_F_CPU1_SA_DQ<28>")
	)
	(segment
		(start 171.082716 -274.722844)
		(end 170.850814 -274.490942)
		(width 0.18288)
		(layer "In4.Cu")
		(net "M_F_CPU1_SA_DQ<28>")
	)
	(segment
		(start 170.101768 -274.000468)
		(end 170.101768 -273.741896)
		(width 0.18288)
		(layer "In4.Cu")
		(net "M_F_CPU1_SA_DQ<28>")
	)
	(segment
		(start 171.792138 -279.58161)
		(end 171.609258 -279.39873)
		(width 0.18288)
		(layer "In4.Cu")
		(net "M_F_CPU1_SA_DQ<28>")
	)
	(segment
		(start 171.038774 -280.800302)
		(end 171.038774 -280.27503)
		(width 0.18288)
		(layer "In4.Cu")
		(net "M_F_CPU1_SA_DQ<28>")
	)
	(segment
		(start 164.428678 -271.035526)
		(end 164.187378 -270.794226)
		(width 0.18288)
		(layer "In4.Cu")
		(net "M_F_CPU1_SA_DQ<28>")
	)
	(segment
		(start 170.130724 -274.693888)
		(end 169.898822 -274.461986)
		(width 0.18288)
		(layer "In4.Cu")
		(net "M_F_CPU1_SA_DQ<28>")
	)
	(segment
		(start 169.898822 -274.203414)
		(end 170.101768 -274.000468)
		(width 0.18288)
		(layer "In4.Cu")
		(net "M_F_CPU1_SA_DQ<28>")
	)
	(segment
		(start 145.131028 -260.928612)
		(end 141.566392 -259.451856)
		(width 0.18288)
		(layer "In4.Cu")
		(net "M_F_CPU1_SA_DQ<28>")
	)
	(segment
		(start 164.187378 -270.794226)
		(end 163.432998 -270.794226)
		(width 0.18288)
		(layer "In4.Cu")
		(net "M_F_CPU1_SA_DQ<28>")
	)
	(segment
		(start 170.850814 -274.490942)
		(end 170.592242 -274.490942)
		(width 0.18288)
		(layer "In4.Cu")
		(net "M_F_CPU1_SA_DQ<28>")
	)
	(segment
		(start 167.058848 -272.380456)
		(end 166.275258 -272.380456)
		(width 0.18288)
		(layer "In4.Cu")
		(net "M_F_CPU1_SA_DQ<28>")
	)
	(segment
		(start 169.898822 -274.461986)
		(end 169.898822 -274.203414)
		(width 0.18288)
		(layer "In4.Cu")
		(net "M_F_CPU1_SA_DQ<28>")
	)
	(segment
		(start 168.071546 -273.393154)
		(end 167.058848 -272.380456)
		(width 0.18288)
		(layer "In4.Cu")
		(net "M_F_CPU1_SA_DQ<28>")
	)
	(segment
		(start 139.147296 -259.306314)
		(end 138.925554 -259.306314)
		(width 0.088646)
		(layer "In4.Cu")
		(net "M_F_CPU1_SA_DQ<28>")
	)
	(segment
		(start 139.292838 -259.451856)
		(end 139.147296 -259.306314)
		(width 0.088646)
		(layer "In4.Cu")
		(net "M_F_CPU1_SA_DQ<28>")
	)
	(segment
		(start 136.47928 -259.28574)
		(end 136.467342 -259.292598)
		(width 0.088646)
		(layer "In4.Cu")
		(net "M_F_CPU1_SA_DQ<28>")
	)
	(segment
		(start 132.467096 -259.545074)
		(end 132.437632 -259.61594)
		(width 0.088646)
		(layer "In4.Cu")
		(net "M_F_CPU1_SA_DQ<28>")
	)
	(segment
		(start 169.611294 -273.509994)
		(end 169.408348 -273.71294)
		(width 0.18288)
		(layer "In4.Cu")
		(net "M_F_CPU1_SA_DQ<28>")
	)
	(segment
		(start 171.609258 -280.09215)
		(end 171.792138 -279.90927)
		(width 0.18288)
		(layer "In4.Cu")
		(net "M_F_CPU1_SA_DQ<28>")
	)
	(segment
		(start 168.82999 -273.393154)
		(end 168.071546 -273.393154)
		(width 0.18288)
		(layer "In4.Cu")
		(net "M_F_CPU1_SA_DQ<28>")
	)
	(segment
		(start 131.209288 -259.938012)
		(end 131.197604 -259.944616)
		(width 0.088646)
		(layer "In4.Cu")
		(net "M_F_CPU1_SA_DQ<28>")
	)
	(segment
		(start 170.389296 -274.693888)
		(end 170.130724 -274.693888)
		(width 0.18288)
		(layer "In4.Cu")
		(net "M_F_CPU1_SA_DQ<28>")
	)
	(segment
		(start 132.148326 -259.93852)
		(end 132.143246 -259.941314)
		(width 0.088646)
		(layer "In4.Cu")
		(net "M_F_CPU1_SA_DQ<28>")
	)
	(segment
		(start 170.592242 -274.490942)
		(end 170.389296 -274.693888)
		(width 0.18288)
		(layer "In4.Cu")
		(net "M_F_CPU1_SA_DQ<28>")
	)
	(segment
		(start 134.962646 -259.292344)
		(end 134.958074 -259.289804)
		(width 0.088646)
		(layer "In4.Cu")
		(net "M_F_CPU1_SA_DQ<28>")
	)
	(segment
		(start 132.143246 -259.941314)
		(end 132.137404 -259.944616)
		(width 0.088646)
		(layer "In4.Cu")
		(net "M_F_CPU1_SA_DQ<28>")
	)
	(segment
		(start 145.385536 -261.098792)
		(end 145.131028 -260.928612)
		(width 0.18288)
		(layer "In4.Cu")
		(net "M_F_CPU1_SA_DQ<28>")
	)
	(segment
		(start 145.405602 -261.107174)
		(end 145.385536 -261.098792)
		(width 0.18288)
		(layer "In4.Cu")
		(net "M_F_CPU1_SA_DQ<28>")
	)
	(segment
		(start 135.527288 -259.292598)
		(end 135.521192 -259.296154)
		(width 0.088646)
		(layer "In4.Cu")
		(net "M_F_CPU1_SA_DQ<28>")
	)
	(segment
		(start 170.87977 -275.184362)
		(end 171.082716 -274.981416)
		(width 0.18288)
		(layer "In4.Cu")
		(net "M_F_CPU1_SA_DQ<28>")
	)
	(segment
		(start 171.221654 -280.09215)
		(end 171.609258 -280.09215)
		(width 0.18288)
		(layer "In4.Cu")
		(net "M_F_CPU1_SA_DQ<28>")
	)
	(segment
		(start 160.532826 -269.930626)
		(end 159.497014 -269.930626)
		(width 0.18288)
		(layer "In4.Cu")
		(net "M_F_CPU1_SA_DQ<28>")
	)
	(segment
		(start 161.396426 -270.794226)
		(end 160.532826 -269.930626)
		(width 0.18288)
		(layer "In4.Cu")
		(net "M_F_CPU1_SA_DQ<28>")
	)
	(segment
		(start 171.609258 -279.39873)
		(end 171.221654 -279.39873)
		(width 0.18288)
		(layer "In4.Cu")
		(net "M_F_CPU1_SA_DQ<28>")
	)
	(segment
		(start 171.038774 -279.21585)
		(end 171.038774 -275.601938)
		(width 0.18288)
		(layer "In4.Cu")
		(net "M_F_CPU1_SA_DQ<28>")
	)
	(segment
		(start 130.828796 -259.941314)
		(end 130.076194 -259.616956)
		(width 0.088646)
		(layer "In4.Cu")
		(net "M_F_CPU1_SA_DQ<28>")
	)
	(segment
		(start 169.869866 -273.509994)
		(end 169.611294 -273.509994)
		(width 0.18288)
		(layer "In4.Cu")
		(net "M_F_CPU1_SA_DQ<28>")
	)
	(segment
		(start 158.707074 -269.140686)
		(end 157.533086 -269.140686)
		(width 0.18288)
		(layer "In4.Cu")
		(net "M_F_CPU1_SA_DQ<28>")
	)
	(segment
		(start 138.842242 -259.299964)
		(end 138.341862 -259.299964)
		(width 0.088646)
		(layer "In4.Cu")
		(net "M_F_CPU1_SA_DQ<28>")
	)
	(segment
		(start 137.41908 -259.28574)
		(end 137.407142 -259.292598)
		(width 0.088646)
		(layer "In4.Cu")
		(net "M_F_CPU1_SA_DQ<28>")
	)
	(segment
		(start 157.533086 -269.140686)
		(end 149.770592 -261.378192)
		(width 0.18288)
		(layer "In4.Cu")
		(net "M_F_CPU1_SA_DQ<28>")
	)
	(segment
		(start 137.407142 -259.292598)
		(end 137.39241 -259.301234)
		(width 0.088646)
		(layer "In4.Cu")
		(net "M_F_CPU1_SA_DQ<28>")
	)
	(segment
		(start 139.55395 -259.451856)
		(end 139.292838 -259.451856)
		(width 0.088646)
		(layer "In4.Cu")
		(net "M_F_CPU1_SA_DQ<28>")
	)
	(segment
		(start 134.030212 -259.296662)
		(end 134.022846 -259.292344)
		(width 0.088646)
		(layer "In4.Cu")
		(net "M_F_CPU1_SA_DQ<28>")
	)
	(segment
		(start 164.96157 -271.56283)
		(end 164.434266 -271.035526)
		(width 0.18288)
		(layer "In4.Cu")
		(net "M_F_CPU1_SA_DQ<28>")
	)
	(segment
		(start 171.082716 -274.981416)
		(end 171.082716 -274.722844)
		(width 0.18288)
		(layer "In4.Cu")
		(net "M_F_CPU1_SA_DQ<28>")
	)
	(segment
		(start 138.925554 -259.306314)
		(end 138.849354 -259.300218)
		(width 0.088646)
		(layer "In4.Cu")
		(net "M_F_CPU1_SA_DQ<28>")
	)
	(segment
		(start 165.457632 -271.56283)
		(end 164.96157 -271.56283)
		(width 0.18288)
		(layer "In4.Cu")
		(net "M_F_CPU1_SA_DQ<28>")
	)
	(segment
		(start 136.467342 -259.292598)
		(end 136.45261 -259.301234)
		(width 0.088646)
		(layer "In4.Cu")
		(net "M_F_CPU1_SA_DQ<28>")
	)
	(segment
		(start 172.365162 -281.885898)
		(end 172.12437 -281.885898)
		(width 0.18288)
		(layer "In4.Cu")
		(net "M_F_CPU1_SA_DQ<28>")
	)
	(segment
		(start 169.408348 -273.71294)
		(end 169.149776 -273.71294)
		(width 0.18288)
		(layer "In4.Cu")
		(net "M_F_CPU1_SA_DQ<28>")
	)
	(segment
		(start 172.795946 -282.316682)
		(end 172.365162 -281.885898)
		(width 0.18288)
		(layer "In4.Cu")
		(net "M_F_CPU1_SA_DQ<28>")
	)
	(segment
		(start 169.149776 -273.71294)
		(end 168.82999 -273.393154)
		(width 0.18288)
		(layer "In4.Cu")
		(net "M_F_CPU1_SA_DQ<28>")
	)
	(arc
		(start 131.768596 -259.941314)
		(mid 131.489393 -259.865674)
		(end 131.209288 -259.938012)
		(width 0.088646)
		(layer "In4.Cu")
		(net "M_F_CPU1_SA_DQ<28>")
	)
	(arc
		(start 138.849354 -259.300218)
		(mid 138.845801 -259.300016)
		(end 138.842242 -259.299964)
		(width 0.088646)
		(layer "In4.Cu")
		(net "M_F_CPU1_SA_DQ<28>")
	)
	(arc
		(start 135.901938 -259.292598)
		(mid 135.71474 -259.242455)
		(end 135.527542 -259.292598)
		(width 0.088646)
		(layer "In4.Cu")
		(net "M_F_CPU1_SA_DQ<28>")
	)
	(arc
		(start 132.437632 -259.61594)
		(mid 132.418811 -259.656226)
		(end 132.396484 -259.69468)
		(width 0.088646)
		(layer "In4.Cu")
		(net "M_F_CPU1_SA_DQ<28>")
	)
	(arc
		(start 132.137404 -259.944616)
		(mid 131.952549 -259.991566)
		(end 131.768596 -259.941314)
		(width 0.088646)
		(layer "In4.Cu")
		(net "M_F_CPU1_SA_DQ<28>")
	)
	(arc
		(start 137.781538 -259.292598)
		(mid 137.601191 -259.242395)
		(end 137.41908 -259.28574)
		(width 0.088646)
		(layer "In4.Cu")
		(net "M_F_CPU1_SA_DQ<28>")
	)
	(arc
		(start 134.958074 -259.289804)
		(mid 134.772689 -259.242166)
		(end 134.587996 -259.292344)
		(width 0.088646)
		(layer "In4.Cu")
		(net "M_F_CPU1_SA_DQ<28>")
	)
	(arc
		(start 137.39241 -259.301234)
		(mid 137.115935 -259.368554)
		(end 136.841738 -259.292598)
		(width 0.088646)
		(layer "In4.Cu")
		(net "M_F_CPU1_SA_DQ<28>")
	)
	(arc
		(start 132.708396 -259.292344)
		(mid 132.630079 -259.344719)
		(end 132.559298 -259.406898)
		(width 0.088646)
		(layer "In4.Cu")
		(net "M_F_CPU1_SA_DQ<28>")
	)
	(arc
		(start 132.559298 -259.406898)
		(mid 132.506404 -259.471452)
		(end 132.467096 -259.545074)
		(width 0.088646)
		(layer "In4.Cu")
		(net "M_F_CPU1_SA_DQ<28>")
	)
	(arc
		(start 131.197604 -259.944616)
		(mid 131.012749 -259.991566)
		(end 130.828796 -259.941314)
		(width 0.088646)
		(layer "In4.Cu")
		(net "M_F_CPU1_SA_DQ<28>")
	)
	(arc
		(start 138.341862 -259.299964)
		(mid 138.321634 -259.307959)
		(end 138.30173 -259.316728)
		(width 0.088646)
		(layer "In4.Cu")
		(net "M_F_CPU1_SA_DQ<28>")
	)
	(arc
		(start 135.521192 -259.296154)
		(mid 135.241426 -259.368062)
		(end 134.962646 -259.292344)
		(width 0.088646)
		(layer "In4.Cu")
		(net "M_F_CPU1_SA_DQ<28>")
	)
	(arc
		(start 133.648196 -259.292344)
		(mid 133.369873 -259.368137)
		(end 133.090412 -259.296662)
		(width 0.088646)
		(layer "In4.Cu")
		(net "M_F_CPU1_SA_DQ<28>")
	)
	(arc
		(start 138.30173 -259.316728)
		(mid 138.038706 -259.368071)
		(end 137.781538 -259.292598)
		(width 0.088646)
		(layer "In4.Cu")
		(net "M_F_CPU1_SA_DQ<28>")
	)
	(arc
		(start 134.587996 -259.292344)
		(mid 134.309673 -259.368137)
		(end 134.030212 -259.296662)
		(width 0.088646)
		(layer "In4.Cu")
		(net "M_F_CPU1_SA_DQ<28>")
	)
	(arc
		(start 134.018274 -259.289804)
		(mid 133.832889 -259.242166)
		(end 133.648196 -259.292344)
		(width 0.088646)
		(layer "In4.Cu")
		(net "M_F_CPU1_SA_DQ<28>")
	)
	(arc
		(start 132.29082 -259.836666)
		(mid 132.222114 -259.891148)
		(end 132.148326 -259.93852)
		(width 0.088646)
		(layer "In4.Cu")
		(net "M_F_CPU1_SA_DQ<28>")
	)
	(arc
		(start 136.45261 -259.301234)
		(mid 136.176135 -259.368554)
		(end 135.901938 -259.292598)
		(width 0.088646)
		(layer "In4.Cu")
		(net "M_F_CPU1_SA_DQ<28>")
	)
	(arc
		(start 136.841738 -259.292598)
		(mid 136.661391 -259.242395)
		(end 136.47928 -259.28574)
		(width 0.088646)
		(layer "In4.Cu")
		(net "M_F_CPU1_SA_DQ<28>")
	)
	(arc
		(start 132.348732 -259.769356)
		(mid 132.322132 -259.805037)
		(end 132.29082 -259.836666)
		(width 0.088646)
		(layer "In4.Cu")
		(net "M_F_CPU1_SA_DQ<28>")
	)
	(arc
		(start 133.078474 -259.289804)
		(mid 132.893089 -259.242166)
		(end 132.708396 -259.292344)
		(width 0.088646)
		(layer "In4.Cu")
		(net "M_F_CPU1_SA_DQ<28>")
	)
	(segment
		(start 183.340248 -285.698946)
		(end 183.574436 -285.464758)
		(width 0.20066)
		(layer "F.Cu")
		(net "M_F_CPU1_SA_DQ<27>")
	)
	(segment
		(start 183.574436 -285.464758)
		(end 183.958484 -285.464758)
		(width 0.20066)
		(layer "F.Cu")
		(net "M_F_CPU1_SA_DQ<27>")
	)
	(segment
		(start 131.955794 -261.244588)
		(end 131.955794 -261.244842)
		(width 0.20066)
		(layer "F.Cu")
		(net "M_F_CPU1_SA_DQ<27>")
	)
	(segment
		(start 180.427884 -286.14878)
		(end 180.434996 -286.141668)
		(width 0.1016)
		(layer "F.Cu")
		(net "M_F_CPU1_SA_DQ<27>")
	)
	(segment
		(start 183.958484 -285.464758)
		(end 184.210452 -285.716726)
		(width 0.20066)
		(layer "F.Cu")
		(net "M_F_CPU1_SA_DQ<27>")
	)
	(segment
		(start 183.340248 -285.949898)
		(end 183.340248 -285.698946)
		(width 0.20066)
		(layer "F.Cu")
		(net "M_F_CPU1_SA_DQ<27>")
	)
	(segment
		(start 176.896014 -285.716726)
		(end 178.000914 -285.716726)
		(width 0.20066)
		(layer "F.Cu")
		(net "M_F_CPU1_SA_DQ<27>")
	)
	(segment
		(start 180.423058 -286.14878)
		(end 180.427884 -286.14878)
		(width 0.101854)
		(layer "F.Cu")
		(net "M_F_CPU1_SA_DQ<27>")
	)
	(segment
		(start 179.699158 -285.716726)
		(end 180.131212 -286.14878)
		(width 0.20066)
		(layer "F.Cu")
		(net "M_F_CPU1_SA_DQ<27>")
	)
	(segment
		(start 182.455058 -286.15386)
		(end 183.136286 -286.15386)
		(width 0.20066)
		(layer "F.Cu")
		(net "M_F_CPU1_SA_DQ<27>")
	)
	(segment
		(start 131.956048 -261.244334)
		(end 131.955794 -261.244588)
		(width 0.20066)
		(layer "F.Cu")
		(net "M_F_CPU1_SA_DQ<27>")
	)
	(segment
		(start 131.956048 -260.708902)
		(end 131.956048 -261.244334)
		(width 0.20066)
		(layer "F.Cu")
		(net "M_F_CPU1_SA_DQ<27>")
	)
	(segment
		(start 178.000914 -285.716726)
		(end 179.699158 -285.716726)
		(width 0.20066)
		(layer "F.Cu")
		(net "M_F_CPU1_SA_DQ<27>")
	)
	(segment
		(start 182.442866 -286.141668)
		(end 182.455058 -286.15386)
		(width 0.1016)
		(layer "F.Cu")
		(net "M_F_CPU1_SA_DQ<27>")
	)
	(segment
		(start 184.210452 -285.716726)
		(end 185.544714 -285.716726)
		(width 0.20066)
		(layer "F.Cu")
		(net "M_F_CPU1_SA_DQ<27>")
	)
	(segment
		(start 180.434996 -286.141668)
		(end 182.442866 -286.141668)
		(width 0.1016)
		(layer "F.Cu")
		(net "M_F_CPU1_SA_DQ<27>")
	)
	(segment
		(start 180.131212 -286.14878)
		(end 180.423058 -286.14878)
		(width 0.20066)
		(layer "F.Cu")
		(net "M_F_CPU1_SA_DQ<27>")
	)
	(segment
		(start 183.136286 -286.15386)
		(end 183.340248 -285.949898)
		(width 0.20066)
		(layer "F.Cu")
		(net "M_F_CPU1_SA_DQ<27>")
	)
	(segment
		(start 173.424596 -285.292292)
		(end 171.351448 -285.292292)
		(width 0.18288)
		(layer "In4.Cu")
		(net "M_F_CPU1_SA_DQ<27>")
	)
	(segment
		(start 132.708396 -261.5692)
		(end 132.310632 -261.339838)
		(width 0.088646)
		(layer "In4.Cu")
		(net "M_F_CPU1_SA_DQ<27>")
	)
	(segment
		(start 159.480504 -273.27987)
		(end 158.875222 -272.674588)
		(width 0.18288)
		(layer "In4.Cu")
		(net "M_F_CPU1_SA_DQ<27>")
	)
	(segment
		(start 158.875222 -272.674588)
		(end 157.643068 -272.674588)
		(width 0.18288)
		(layer "In4.Cu")
		(net "M_F_CPU1_SA_DQ<27>")
	)
	(segment
		(start 176.47158 -285.292292)
		(end 174.483776 -285.292292)
		(width 0.18288)
		(layer "In4.Cu")
		(net "M_F_CPU1_SA_DQ<27>")
	)
	(segment
		(start 165.554406 -276.239986)
		(end 163.580826 -274.266406)
		(width 0.18288)
		(layer "In4.Cu")
		(net "M_F_CPU1_SA_DQ<27>")
	)
	(segment
		(start 163.580826 -274.266406)
		(end 159.751776 -274.266406)
		(width 0.18288)
		(layer "In4.Cu")
		(net "M_F_CPU1_SA_DQ<27>")
	)
	(segment
		(start 174.300896 -285.475172)
		(end 174.300896 -286.094932)
		(width 0.18288)
		(layer "In4.Cu")
		(net "M_F_CPU1_SA_DQ<27>")
	)
	(segment
		(start 134.962646 -261.5692)
		(end 134.958074 -261.57174)
		(width 0.088646)
		(layer "In4.Cu")
		(net "M_F_CPU1_SA_DQ<27>")
	)
	(segment
		(start 137.781792 -261.5692)
		(end 137.781538 -261.5692)
		(width 0.088646)
		(layer "In4.Cu")
		(net "M_F_CPU1_SA_DQ<27>")
	)
	(segment
		(start 173.607476 -285.475172)
		(end 173.424596 -285.292292)
		(width 0.18288)
		(layer "In4.Cu")
		(net "M_F_CPU1_SA_DQ<27>")
	)
	(segment
		(start 167.928036 -277.43404)
		(end 166.733982 -276.239986)
		(width 0.18288)
		(layer "In4.Cu")
		(net "M_F_CPU1_SA_DQ<27>")
	)
	(segment
		(start 138.751564 -261.284466)
		(end 138.46683 -261.5692)
		(width 0.088646)
		(layer "In4.Cu")
		(net "M_F_CPU1_SA_DQ<27>")
	)
	(segment
		(start 159.480504 -273.995134)
		(end 159.480504 -273.27987)
		(width 0.18288)
		(layer "In4.Cu")
		(net "M_F_CPU1_SA_DQ<27>")
	)
	(segment
		(start 174.300896 -286.094932)
		(end 174.118016 -286.277812)
		(width 0.18288)
		(layer "In4.Cu")
		(net "M_F_CPU1_SA_DQ<27>")
	)
	(segment
		(start 134.022846 -261.5692)
		(end 134.018274 -261.57174)
		(width 0.088646)
		(layer "In4.Cu")
		(net "M_F_CPU1_SA_DQ<27>")
	)
	(segment
		(start 173.607476 -286.094932)
		(end 173.607476 -285.475172)
		(width 0.18288)
		(layer "In4.Cu")
		(net "M_F_CPU1_SA_DQ<27>")
	)
	(segment
		(start 166.733982 -276.239986)
		(end 165.554406 -276.239986)
		(width 0.18288)
		(layer "In4.Cu")
		(net "M_F_CPU1_SA_DQ<27>")
	)
	(segment
		(start 141.223238 -261.284466)
		(end 138.868404 -261.284466)
		(width 0.18288)
		(layer "In4.Cu")
		(net "M_F_CPU1_SA_DQ<27>")
	)
	(segment
		(start 157.643068 -272.674588)
		(end 157.29839 -272.53184)
		(width 0.18288)
		(layer "In4.Cu")
		(net "M_F_CPU1_SA_DQ<27>")
	)
	(segment
		(start 134.030212 -261.564882)
		(end 134.022846 -261.5692)
		(width 0.088646)
		(layer "In4.Cu")
		(net "M_F_CPU1_SA_DQ<27>")
	)
	(segment
		(start 138.46683 -261.5692)
		(end 138.347196 -261.5692)
		(width 0.088646)
		(layer "In4.Cu")
		(net "M_F_CPU1_SA_DQ<27>")
	)
	(segment
		(start 176.896014 -285.716726)
		(end 176.47158 -285.292292)
		(width 0.18288)
		(layer "In4.Cu")
		(net "M_F_CPU1_SA_DQ<27>")
	)
	(segment
		(start 138.868404 -261.284466)
		(end 138.751564 -261.284466)
		(width 0.088646)
		(layer "In4.Cu")
		(net "M_F_CPU1_SA_DQ<27>")
	)
	(segment
		(start 144.165828 -262.910574)
		(end 143.47063 -262.215376)
		(width 0.18288)
		(layer "In4.Cu")
		(net "M_F_CPU1_SA_DQ<27>")
	)
	(segment
		(start 143.47063 -262.215376)
		(end 141.223238 -261.284466)
		(width 0.18288)
		(layer "In4.Cu")
		(net "M_F_CPU1_SA_DQ<27>")
	)
	(segment
		(start 133.090412 -261.564882)
		(end 133.083046 -261.5692)
		(width 0.088646)
		(layer "In4.Cu")
		(net "M_F_CPU1_SA_DQ<27>")
	)
	(segment
		(start 133.083046 -261.5692)
		(end 133.078474 -261.57174)
		(width 0.088646)
		(layer "In4.Cu")
		(net "M_F_CPU1_SA_DQ<27>")
	)
	(segment
		(start 135.53948 -261.576312)
		(end 135.527542 -261.5692)
		(width 0.088646)
		(layer "In4.Cu")
		(net "M_F_CPU1_SA_DQ<27>")
	)
	(segment
		(start 145.568162 -263.491472)
		(end 144.165828 -262.910574)
		(width 0.18288)
		(layer "In4.Cu")
		(net "M_F_CPU1_SA_DQ<27>")
	)
	(segment
		(start 167.928036 -281.86888)
		(end 167.928036 -277.43404)
		(width 0.18288)
		(layer "In4.Cu")
		(net "M_F_CPU1_SA_DQ<27>")
	)
	(segment
		(start 135.902192 -261.5692)
		(end 135.902192 -261.569454)
		(width 0.088646)
		(layer "In4.Cu")
		(net "M_F_CPU1_SA_DQ<27>")
	)
	(segment
		(start 171.351448 -285.292292)
		(end 167.928036 -281.86888)
		(width 0.18288)
		(layer "In4.Cu")
		(net "M_F_CPU1_SA_DQ<27>")
	)
	(segment
		(start 173.790356 -286.277812)
		(end 173.607476 -286.094932)
		(width 0.18288)
		(layer "In4.Cu")
		(net "M_F_CPU1_SA_DQ<27>")
	)
	(segment
		(start 148.258022 -263.491472)
		(end 145.568162 -263.491472)
		(width 0.18288)
		(layer "In4.Cu")
		(net "M_F_CPU1_SA_DQ<27>")
	)
	(segment
		(start 157.29839 -272.53184)
		(end 148.258022 -263.491472)
		(width 0.18288)
		(layer "In4.Cu")
		(net "M_F_CPU1_SA_DQ<27>")
	)
	(segment
		(start 174.118016 -286.277812)
		(end 173.790356 -286.277812)
		(width 0.18288)
		(layer "In4.Cu")
		(net "M_F_CPU1_SA_DQ<27>")
	)
	(segment
		(start 174.483776 -285.292292)
		(end 174.300896 -285.475172)
		(width 0.18288)
		(layer "In4.Cu")
		(net "M_F_CPU1_SA_DQ<27>")
	)
	(segment
		(start 135.527542 -261.5692)
		(end 135.513572 -261.561326)
		(width 0.088646)
		(layer "In4.Cu")
		(net "M_F_CPU1_SA_DQ<27>")
	)
	(segment
		(start 159.751776 -274.266406)
		(end 159.480504 -273.995134)
		(width 0.18288)
		(layer "In4.Cu")
		(net "M_F_CPU1_SA_DQ<27>")
	)
	(segment
		(start 136.467342 -261.5692)
		(end 136.456928 -261.563104)
		(width 0.088646)
		(layer "In4.Cu")
		(net "M_F_CPU1_SA_DQ<27>")
	)
	(arc
		(start 133.078474 -261.57174)
		(mid 132.893089 -261.619378)
		(end 132.708396 -261.5692)
		(width 0.088646)
		(layer "In4.Cu")
		(net "M_F_CPU1_SA_DQ<27>")
	)
	(arc
		(start 134.958074 -261.57174)
		(mid 134.772689 -261.619378)
		(end 134.587996 -261.5692)
		(width 0.088646)
		(layer "In4.Cu")
		(net "M_F_CPU1_SA_DQ<27>")
	)
	(arc
		(start 134.587996 -261.5692)
		(mid 134.309673 -261.493441)
		(end 134.030212 -261.564882)
		(width 0.088646)
		(layer "In4.Cu")
		(net "M_F_CPU1_SA_DQ<27>")
	)
	(arc
		(start 133.648196 -261.5692)
		(mid 133.369873 -261.493441)
		(end 133.090412 -261.564882)
		(width 0.088646)
		(layer "In4.Cu")
		(net "M_F_CPU1_SA_DQ<27>")
	)
	(arc
		(start 137.781538 -261.5692)
		(mid 137.59434 -261.619343)
		(end 137.407142 -261.5692)
		(width 0.088646)
		(layer "In4.Cu")
		(net "M_F_CPU1_SA_DQ<27>")
	)
	(arc
		(start 135.902192 -261.569454)
		(mid 135.721733 -261.619659)
		(end 135.53948 -261.576312)
		(width 0.088646)
		(layer "In4.Cu")
		(net "M_F_CPU1_SA_DQ<27>")
	)
	(arc
		(start 136.841738 -261.5692)
		(mid 136.65454 -261.619343)
		(end 136.467342 -261.5692)
		(width 0.088646)
		(layer "In4.Cu")
		(net "M_F_CPU1_SA_DQ<27>")
	)
	(arc
		(start 137.407142 -261.5692)
		(mid 137.12444 -261.493424)
		(end 136.841738 -261.5692)
		(width 0.088646)
		(layer "In4.Cu")
		(net "M_F_CPU1_SA_DQ<27>")
	)
	(arc
		(start 138.347196 -261.5692)
		(mid 138.064494 -261.493424)
		(end 137.781792 -261.5692)
		(width 0.088646)
		(layer "In4.Cu")
		(net "M_F_CPU1_SA_DQ<27>")
	)
	(arc
		(start 135.513572 -261.561326)
		(mid 135.237075 -261.493543)
		(end 134.962646 -261.5692)
		(width 0.088646)
		(layer "In4.Cu")
		(net "M_F_CPU1_SA_DQ<27>")
	)
	(arc
		(start 132.310632 -261.339838)
		(mid 132.139457 -261.269024)
		(end 131.955794 -261.244842)
		(width 0.088646)
		(layer "In4.Cu")
		(net "M_F_CPU1_SA_DQ<27>")
	)
	(arc
		(start 134.018274 -261.57174)
		(mid 133.832889 -261.619378)
		(end 133.648196 -261.5692)
		(width 0.088646)
		(layer "In4.Cu")
		(net "M_F_CPU1_SA_DQ<27>")
	)
	(arc
		(start 136.456928 -261.563104)
		(mid 136.17875 -261.493381)
		(end 135.902192 -261.5692)
		(width 0.088646)
		(layer "In4.Cu")
		(net "M_F_CPU1_SA_DQ<27>")
	)
	(segment
		(start 183.574436 -287.16478)
		(end 183.958484 -287.16478)
		(width 0.20066)
		(layer "F.Cu")
		(net "M_F_CPU1_SA_DQ<26>")
	)
	(segment
		(start 183.340248 -287.64992)
		(end 183.340248 -287.398968)
		(width 0.20066)
		(layer "F.Cu")
		(net "M_F_CPU1_SA_DQ<26>")
	)
	(segment
		(start 178.000914 -287.416748)
		(end 179.699158 -287.416748)
		(width 0.20066)
		(layer "F.Cu")
		(net "M_F_CPU1_SA_DQ<26>")
	)
	(segment
		(start 131.485894 -261.522718)
		(end 131.486148 -261.522972)
		(width 0.20066)
		(layer "F.Cu")
		(net "M_F_CPU1_SA_DQ<26>")
	)
	(segment
		(start 182.455058 -287.853882)
		(end 183.136286 -287.853882)
		(width 0.20066)
		(layer "F.Cu")
		(net "M_F_CPU1_SA_DQ<26>")
	)
	(segment
		(start 182.442866 -287.84169)
		(end 182.455058 -287.853882)
		(width 0.1016)
		(layer "F.Cu")
		(net "M_F_CPU1_SA_DQ<26>")
	)
	(segment
		(start 131.486148 -261.522972)
		(end 131.486148 -262.058658)
		(width 0.20066)
		(layer "F.Cu")
		(net "M_F_CPU1_SA_DQ<26>")
	)
	(segment
		(start 184.210452 -287.416748)
		(end 185.544714 -287.416748)
		(width 0.20066)
		(layer "F.Cu")
		(net "M_F_CPU1_SA_DQ<26>")
	)
	(segment
		(start 180.131212 -287.848802)
		(end 180.423058 -287.848802)
		(width 0.20066)
		(layer "F.Cu")
		(net "M_F_CPU1_SA_DQ<26>")
	)
	(segment
		(start 183.340248 -287.398968)
		(end 183.574436 -287.16478)
		(width 0.20066)
		(layer "F.Cu")
		(net "M_F_CPU1_SA_DQ<26>")
	)
	(segment
		(start 183.136286 -287.853882)
		(end 183.340248 -287.64992)
		(width 0.20066)
		(layer "F.Cu")
		(net "M_F_CPU1_SA_DQ<26>")
	)
	(segment
		(start 179.699158 -287.416748)
		(end 180.131212 -287.848802)
		(width 0.20066)
		(layer "F.Cu")
		(net "M_F_CPU1_SA_DQ<26>")
	)
	(segment
		(start 180.427884 -287.848802)
		(end 180.434996 -287.84169)
		(width 0.1016)
		(layer "F.Cu")
		(net "M_F_CPU1_SA_DQ<26>")
	)
	(segment
		(start 176.896014 -287.416748)
		(end 178.000914 -287.416748)
		(width 0.20066)
		(layer "F.Cu")
		(net "M_F_CPU1_SA_DQ<26>")
	)
	(segment
		(start 180.423058 -287.848802)
		(end 180.427884 -287.848802)
		(width 0.101854)
		(layer "F.Cu")
		(net "M_F_CPU1_SA_DQ<26>")
	)
	(segment
		(start 183.958484 -287.16478)
		(end 184.210452 -287.416748)
		(width 0.20066)
		(layer "F.Cu")
		(net "M_F_CPU1_SA_DQ<26>")
	)
	(segment
		(start 180.434996 -287.84169)
		(end 182.442866 -287.84169)
		(width 0.1016)
		(layer "F.Cu")
		(net "M_F_CPU1_SA_DQ<26>")
	)
	(segment
		(start 132.244338 -262.386318)
		(end 132.232654 -262.379714)
		(width 0.088646)
		(layer "In4.Cu")
		(net "M_F_CPU1_SA_DQ<26>")
	)
	(segment
		(start 168.349168 -284.661356)
		(end 167.019986 -283.332174)
		(width 0.18288)
		(layer "In4.Cu")
		(net "M_F_CPU1_SA_DQ<26>")
	)
	(segment
		(start 162.077146 -276.008846)
		(end 161.365946 -276.008846)
		(width 0.18288)
		(layer "In4.Cu")
		(net "M_F_CPU1_SA_DQ<26>")
	)
	(segment
		(start 166.349426 -278.515826)
		(end 165.464744 -277.631144)
		(width 0.18288)
		(layer "In4.Cu")
		(net "M_F_CPU1_SA_DQ<26>")
	)
	(segment
		(start 166.349426 -282.126944)
		(end 166.349426 -278.515826)
		(width 0.18288)
		(layer "In4.Cu")
		(net "M_F_CPU1_SA_DQ<26>")
	)
	(segment
		(start 176.860708 -287.138618)
		(end 176.71288 -286.99079)
		(width 0.18288)
		(layer "In4.Cu")
		(net "M_F_CPU1_SA_DQ<26>")
	)
	(segment
		(start 176.896014 -287.223708)
		(end 176.860708 -287.138618)
		(width 0.18288)
		(layer "In4.Cu")
		(net "M_F_CPU1_SA_DQ<26>")
	)
	(segment
		(start 133.184138 -262.386318)
		(end 133.172454 -262.379714)
		(width 0.088646)
		(layer "In4.Cu")
		(net "M_F_CPU1_SA_DQ<26>")
	)
	(segment
		(start 135.057896 -262.383016)
		(end 135.052054 -262.379714)
		(width 0.088646)
		(layer "In4.Cu")
		(net "M_F_CPU1_SA_DQ<26>")
	)
	(segment
		(start 160.692846 -275.335746)
		(end 159.3596 -275.335746)
		(width 0.18288)
		(layer "In4.Cu")
		(net "M_F_CPU1_SA_DQ<26>")
	)
	(segment
		(start 159.3596 -275.335746)
		(end 158.401258 -274.377404)
		(width 0.18288)
		(layer "In4.Cu")
		(net "M_F_CPU1_SA_DQ<26>")
	)
	(segment
		(start 140.368528 -262.241538)
		(end 140.177012 -262.433054)
		(width 0.088646)
		(layer "In4.Cu")
		(net "M_F_CPU1_SA_DQ<26>")
	)
	(segment
		(start 161.365946 -276.008846)
		(end 160.692846 -275.335746)
		(width 0.18288)
		(layer "In4.Cu")
		(net "M_F_CPU1_SA_DQ<26>")
	)
	(segment
		(start 167.019986 -283.332174)
		(end 166.349426 -282.126944)
		(width 0.18288)
		(layer "In4.Cu")
		(net "M_F_CPU1_SA_DQ<26>")
	)
	(segment
		(start 138.817096 -262.383016)
		(end 138.802364 -262.37438)
		(width 0.088646)
		(layer "In4.Cu")
		(net "M_F_CPU1_SA_DQ<26>")
	)
	(segment
		(start 170.25874 -285.646876)
		(end 169.902886 -285.291022)
		(width 0.18288)
		(layer "In4.Cu")
		(net "M_F_CPU1_SA_DQ<26>")
	)
	(segment
		(start 141.61643 -262.241538)
		(end 140.494004 -262.241538)
		(width 0.18288)
		(layer "In4.Cu")
		(net "M_F_CPU1_SA_DQ<26>")
	)
	(segment
		(start 147.78228 -264.487152)
		(end 145.309336 -264.487152)
		(width 0.18288)
		(layer "In4.Cu")
		(net "M_F_CPU1_SA_DQ<26>")
	)
	(segment
		(start 163.796726 -277.728426)
		(end 162.077146 -276.008846)
		(width 0.18288)
		(layer "In4.Cu")
		(net "M_F_CPU1_SA_DQ<26>")
	)
	(segment
		(start 157.672532 -274.377404)
		(end 147.78228 -264.487152)
		(width 0.18288)
		(layer "In4.Cu")
		(net "M_F_CPU1_SA_DQ<26>")
	)
	(segment
		(start 165.464744 -277.631144)
		(end 164.848286 -277.631144)
		(width 0.18288)
		(layer "In4.Cu")
		(net "M_F_CPU1_SA_DQ<26>")
	)
	(segment
		(start 168.543224 -284.661356)
		(end 168.349168 -284.661356)
		(width 0.18288)
		(layer "In4.Cu")
		(net "M_F_CPU1_SA_DQ<26>")
	)
	(segment
		(start 134.123938 -262.386318)
		(end 134.112254 -262.379714)
		(width 0.088646)
		(layer "In4.Cu")
		(net "M_F_CPU1_SA_DQ<26>")
	)
	(segment
		(start 135.061706 -262.385302)
		(end 135.057896 -262.383016)
		(width 0.088646)
		(layer "In4.Cu")
		(net "M_F_CPU1_SA_DQ<26>")
	)
	(segment
		(start 140.177012 -262.433054)
		(end 139.94384 -262.433054)
		(width 0.088646)
		(layer "In4.Cu")
		(net "M_F_CPU1_SA_DQ<26>")
	)
	(segment
		(start 164.848286 -277.631144)
		(end 163.963858 -277.728426)
		(width 0.18288)
		(layer "In4.Cu")
		(net "M_F_CPU1_SA_DQ<26>")
	)
	(segment
		(start 176.896014 -287.416748)
		(end 176.896014 -287.223708)
		(width 0.18288)
		(layer "In4.Cu")
		(net "M_F_CPU1_SA_DQ<26>")
	)
	(segment
		(start 140.494004 -262.241538)
		(end 140.368528 -262.241538)
		(width 0.088646)
		(layer "In4.Cu")
		(net "M_F_CPU1_SA_DQ<26>")
	)
	(segment
		(start 158.401258 -274.377404)
		(end 157.672532 -274.377404)
		(width 0.18288)
		(layer "In4.Cu")
		(net "M_F_CPU1_SA_DQ<26>")
	)
	(segment
		(start 163.963858 -277.728426)
		(end 163.796726 -277.728426)
		(width 0.18288)
		(layer "In4.Cu")
		(net "M_F_CPU1_SA_DQ<26>")
	)
	(segment
		(start 142.412974 -262.571484)
		(end 141.61643 -262.241538)
		(width 0.18288)
		(layer "In4.Cu")
		(net "M_F_CPU1_SA_DQ<26>")
	)
	(segment
		(start 171.369228 -286.99079)
		(end 171.092368 -286.71393)
		(width 0.18288)
		(layer "In4.Cu")
		(net "M_F_CPU1_SA_DQ<26>")
	)
	(segment
		(start 143.63573 -263.79424)
		(end 142.412974 -262.571484)
		(width 0.18288)
		(layer "In4.Cu")
		(net "M_F_CPU1_SA_DQ<26>")
	)
	(segment
		(start 169.17289 -285.291022)
		(end 168.543224 -284.661356)
		(width 0.18288)
		(layer "In4.Cu")
		(net "M_F_CPU1_SA_DQ<26>")
	)
	(segment
		(start 176.71288 -286.99079)
		(end 171.369228 -286.99079)
		(width 0.18288)
		(layer "In4.Cu")
		(net "M_F_CPU1_SA_DQ<26>")
	)
	(segment
		(start 139.756896 -262.383016)
		(end 139.742164 -262.37438)
		(width 0.088646)
		(layer "In4.Cu")
		(net "M_F_CPU1_SA_DQ<26>")
	)
	(segment
		(start 171.092368 -286.71393)
		(end 170.25874 -285.646876)
		(width 0.18288)
		(layer "In4.Cu")
		(net "M_F_CPU1_SA_DQ<26>")
	)
	(segment
		(start 145.309336 -264.487152)
		(end 143.63573 -263.79424)
		(width 0.18288)
		(layer "In4.Cu")
		(net "M_F_CPU1_SA_DQ<26>")
	)
	(segment
		(start 169.902886 -285.291022)
		(end 169.17289 -285.291022)
		(width 0.18288)
		(layer "In4.Cu")
		(net "M_F_CPU1_SA_DQ<26>")
	)
	(arc
		(start 134.492746 -262.383016)
		(mid 134.308792 -262.433145)
		(end 134.123938 -262.386318)
		(width 0.088646)
		(layer "In4.Cu")
		(net "M_F_CPU1_SA_DQ<26>")
	)
	(arc
		(start 137.877296 -262.383016)
		(mid 137.594594 -262.30724)
		(end 137.311892 -262.383016)
		(width 0.088646)
		(layer "In4.Cu")
		(net "M_F_CPU1_SA_DQ<26>")
	)
	(arc
		(start 139.94384 -262.433054)
		(mid 139.847075 -262.420333)
		(end 139.756896 -262.383016)
		(width 0.088646)
		(layer "In4.Cu")
		(net "M_F_CPU1_SA_DQ<26>")
	)
	(arc
		(start 133.172454 -262.379714)
		(mid 132.892349 -262.307272)
		(end 132.613146 -262.383016)
		(width 0.088646)
		(layer "In4.Cu")
		(net "M_F_CPU1_SA_DQ<26>")
	)
	(arc
		(start 136.937496 -262.383016)
		(mid 136.654794 -262.30724)
		(end 136.372092 -262.383016)
		(width 0.088646)
		(layer "In4.Cu")
		(net "M_F_CPU1_SA_DQ<26>")
	)
	(arc
		(start 136.372092 -262.383016)
		(mid 136.184894 -262.433159)
		(end 135.997696 -262.383016)
		(width 0.088646)
		(layer "In4.Cu")
		(net "M_F_CPU1_SA_DQ<26>")
	)
	(arc
		(start 135.997696 -262.383016)
		(mid 135.715138 -262.307367)
		(end 135.432546 -262.383016)
		(width 0.088646)
		(layer "In4.Cu")
		(net "M_F_CPU1_SA_DQ<26>")
	)
	(arc
		(start 132.232654 -262.379714)
		(mid 131.868102 -262.198953)
		(end 131.486148 -262.058658)
		(width 0.088646)
		(layer "In4.Cu")
		(net "M_F_CPU1_SA_DQ<26>")
	)
	(arc
		(start 139.742164 -262.37438)
		(mid 139.465689 -262.30706)
		(end 139.191492 -262.383016)
		(width 0.088646)
		(layer "In4.Cu")
		(net "M_F_CPU1_SA_DQ<26>")
	)
	(arc
		(start 139.191492 -262.383016)
		(mid 139.004294 -262.433159)
		(end 138.817096 -262.383016)
		(width 0.088646)
		(layer "In4.Cu")
		(net "M_F_CPU1_SA_DQ<26>")
	)
	(arc
		(start 138.802364 -262.37438)
		(mid 138.525889 -262.30706)
		(end 138.251692 -262.383016)
		(width 0.088646)
		(layer "In4.Cu")
		(net "M_F_CPU1_SA_DQ<26>")
	)
	(arc
		(start 135.432546 -262.383016)
		(mid 135.247425 -262.433279)
		(end 135.061706 -262.385302)
		(width 0.088646)
		(layer "In4.Cu")
		(net "M_F_CPU1_SA_DQ<26>")
	)
	(arc
		(start 137.311892 -262.383016)
		(mid 137.124694 -262.433159)
		(end 136.937496 -262.383016)
		(width 0.088646)
		(layer "In4.Cu")
		(net "M_F_CPU1_SA_DQ<26>")
	)
	(arc
		(start 132.613146 -262.383016)
		(mid 132.429192 -262.433145)
		(end 132.244338 -262.386318)
		(width 0.088646)
		(layer "In4.Cu")
		(net "M_F_CPU1_SA_DQ<26>")
	)
	(arc
		(start 134.112254 -262.379714)
		(mid 133.832149 -262.307272)
		(end 133.552946 -262.383016)
		(width 0.088646)
		(layer "In4.Cu")
		(net "M_F_CPU1_SA_DQ<26>")
	)
	(arc
		(start 138.251692 -262.383016)
		(mid 138.064494 -262.433159)
		(end 137.877296 -262.383016)
		(width 0.088646)
		(layer "In4.Cu")
		(net "M_F_CPU1_SA_DQ<26>")
	)
	(arc
		(start 133.552946 -262.383016)
		(mid 133.368992 -262.433145)
		(end 133.184138 -262.386318)
		(width 0.088646)
		(layer "In4.Cu")
		(net "M_F_CPU1_SA_DQ<26>")
	)
	(arc
		(start 135.052054 -262.379714)
		(mid 134.771949 -262.307272)
		(end 134.492746 -262.383016)
		(width 0.088646)
		(layer "In4.Cu")
		(net "M_F_CPU1_SA_DQ<26>")
	)
	(segment
		(start 130.076448 -260.708902)
		(end 130.076448 -261.244334)
		(width 0.20066)
		(layer "F.Cu")
		(net "M_F_CPU1_SA_DQ<25>")
	)
	(segment
		(start 179.004976 -286.141668)
		(end 176.816258 -286.141668)
		(width 0.1016)
		(layer "F.Cu")
		(net "M_F_CPU1_SA_DQ<25>")
	)
	(segment
		(start 176.816258 -286.141668)
		(end 176.796192 -286.141668)
		(width 0.101854)
		(layer "F.Cu")
		(net "M_F_CPU1_SA_DQ<25>")
	)
	(segment
		(start 176.796192 -286.141668)
		(end 176.451514 -286.141668)
		(width 0.20066)
		(layer "F.Cu")
		(net "M_F_CPU1_SA_DQ<25>")
	)
	(segment
		(start 179.852828 -286.566864)
		(end 179.421282 -286.135318)
		(width 0.20066)
		(layer "F.Cu")
		(net "M_F_CPU1_SA_DQ<25>")
	)
	(segment
		(start 179.011326 -286.135318)
		(end 179.004976 -286.141668)
		(width 0.1016)
		(layer "F.Cu")
		(net "M_F_CPU1_SA_DQ<25>")
	)
	(segment
		(start 176.145444 -286.815276)
		(end 175.67021 -286.815276)
		(width 0.20066)
		(layer "F.Cu")
		(net "M_F_CPU1_SA_DQ<25>")
	)
	(segment
		(start 179.421282 -286.135318)
		(end 179.011326 -286.135318)
		(width 0.20066)
		(layer "F.Cu")
		(net "M_F_CPU1_SA_DQ<25>")
	)
	(segment
		(start 175.67021 -286.815276)
		(end 175.421544 -286.56661)
		(width 0.20066)
		(layer "F.Cu")
		(net "M_F_CPU1_SA_DQ<25>")
	)
	(segment
		(start 130.076448 -261.244334)
		(end 130.076194 -261.244588)
		(width 0.20066)
		(layer "F.Cu")
		(net "M_F_CPU1_SA_DQ<25>")
	)
	(segment
		(start 181.444392 -286.566864)
		(end 179.852828 -286.566864)
		(width 0.20066)
		(layer "F.Cu")
		(net "M_F_CPU1_SA_DQ<25>")
	)
	(segment
		(start 175.421544 -286.56661)
		(end 173.900846 -286.56661)
		(width 0.20066)
		(layer "F.Cu")
		(net "M_F_CPU1_SA_DQ<25>")
	)
	(segment
		(start 176.451514 -286.141668)
		(end 176.333404 -286.259778)
		(width 0.20066)
		(layer "F.Cu")
		(net "M_F_CPU1_SA_DQ<25>")
	)
	(segment
		(start 176.333404 -286.259778)
		(end 176.333404 -286.627316)
		(width 0.20066)
		(layer "F.Cu")
		(net "M_F_CPU1_SA_DQ<25>")
	)
	(segment
		(start 130.076194 -261.244588)
		(end 130.076194 -261.244842)
		(width 0.20066)
		(layer "F.Cu")
		(net "M_F_CPU1_SA_DQ<25>")
	)
	(segment
		(start 181.444646 -286.56661)
		(end 181.444392 -286.566864)
		(width 0.20066)
		(layer "F.Cu")
		(net "M_F_CPU1_SA_DQ<25>")
	)
	(segment
		(start 176.333404 -286.627316)
		(end 176.145444 -286.815276)
		(width 0.20066)
		(layer "F.Cu")
		(net "M_F_CPU1_SA_DQ<25>")
	)
	(segment
		(start 173.900846 -286.56661)
		(end 172.795946 -286.56661)
		(width 0.20066)
		(layer "F.Cu")
		(net "M_F_CPU1_SA_DQ<25>")
	)
	(segment
		(start 157.61335 -273.268694)
		(end 157.131004 -273.068796)
		(width 0.18288)
		(layer "In4.Cu")
		(net "M_F_CPU1_SA_DQ<25>")
	)
	(segment
		(start 168.300908 -283.894276)
		(end 168.069006 -283.662374)
		(width 0.18288)
		(layer "In4.Cu")
		(net "M_F_CPU1_SA_DQ<25>")
	)
	(segment
		(start 172.024548 -285.795212)
		(end 171.1198 -285.795212)
		(width 0.18288)
		(layer "In4.Cu")
		(net "M_F_CPU1_SA_DQ<25>")
	)
	(segment
		(start 136.382506 -261.740396)
		(end 136.372092 -261.7343)
		(width 0.088646)
		(layer "In4.Cu")
		(net "M_F_CPU1_SA_DQ<25>")
	)
	(segment
		(start 167.076374 -280.935938)
		(end 167.076374 -280.267918)
		(width 0.18288)
		(layer "In4.Cu")
		(net "M_F_CPU1_SA_DQ<25>")
	)
	(segment
		(start 166.916354 -281.095958)
		(end 167.076374 -280.935938)
		(width 0.18288)
		(layer "In4.Cu")
		(net "M_F_CPU1_SA_DQ<25>")
	)
	(segment
		(start 168.55948 -283.894276)
		(end 168.300908 -283.894276)
		(width 0.18288)
		(layer "In4.Cu")
		(net "M_F_CPU1_SA_DQ<25>")
	)
	(segment
		(start 163.019232 -274.87372)
		(end 162.652456 -275.240496)
		(width 0.18288)
		(layer "In4.Cu")
		(net "M_F_CPU1_SA_DQ<25>")
	)
	(segment
		(start 132.243068 -261.731506)
		(end 132.238496 -261.7343)
		(width 0.088646)
		(layer "In4.Cu")
		(net "M_F_CPU1_SA_DQ<25>")
	)
	(segment
		(start 166.624254 -277.138638)
		(end 166.284402 -277.47849)
		(width 0.18288)
		(layer "In4.Cu")
		(net "M_F_CPU1_SA_DQ<25>")
	)
	(segment
		(start 167.114728 -277.629112)
		(end 167.114728 -277.37054)
		(width 0.18288)
		(layer "In4.Cu")
		(net "M_F_CPU1_SA_DQ<25>")
	)
	(segment
		(start 132.238496 -261.7343)
		(end 132.23113 -261.738364)
		(width 0.088646)
		(layer "In4.Cu")
		(net "M_F_CPU1_SA_DQ<25>")
	)
	(segment
		(start 133.178296 -261.7343)
		(end 133.17093 -261.738364)
		(width 0.088646)
		(layer "In4.Cu")
		(net "M_F_CPU1_SA_DQ<25>")
	)
	(segment
		(start 164.224208 -276.781006)
		(end 163.626546 -276.781006)
		(width 0.18288)
		(layer "In4.Cu")
		(net "M_F_CPU1_SA_DQ<25>")
	)
	(segment
		(start 159.580834 -274.835366)
		(end 158.92653 -274.181062)
		(width 0.18288)
		(layer "In4.Cu")
		(net "M_F_CPU1_SA_DQ<25>")
	)
	(segment
		(start 131.298696 -261.7343)
		(end 131.29133 -261.738364)
		(width 0.088646)
		(layer "In4.Cu")
		(net "M_F_CPU1_SA_DQ<25>")
	)
	(segment
		(start 141.062456 -261.631176)
		(end 139.355576 -261.631176)
		(width 0.18288)
		(layer "In4.Cu")
		(net "M_F_CPU1_SA_DQ<25>")
	)
	(segment
		(start 134.122668 -261.731506)
		(end 134.118096 -261.7343)
		(width 0.088646)
		(layer "In4.Cu")
		(net "M_F_CPU1_SA_DQ<25>")
	)
	(segment
		(start 163.626546 -276.781006)
		(end 163.466526 -276.620986)
		(width 0.18288)
		(layer "In4.Cu")
		(net "M_F_CPU1_SA_DQ<25>")
	)
	(segment
		(start 168.069006 -283.662374)
		(end 168.069006 -283.403802)
		(width 0.18288)
		(layer "In4.Cu")
		(net "M_F_CPU1_SA_DQ<25>")
	)
	(segment
		(start 162.273996 -275.240496)
		(end 161.868866 -274.835366)
		(width 0.18288)
		(layer "In4.Cu")
		(net "M_F_CPU1_SA_DQ<25>")
	)
	(segment
		(start 133.182868 -261.731506)
		(end 133.178296 -261.7343)
		(width 0.088646)
		(layer "In4.Cu")
		(net "M_F_CPU1_SA_DQ<25>")
	)
	(segment
		(start 139.226036 -261.760716)
		(end 138.868404 -261.760716)
		(width 0.18288)
		(layer "In4.Cu")
		(net "M_F_CPU1_SA_DQ<25>")
	)
	(segment
		(start 158.92653 -273.454876)
		(end 158.740348 -273.268694)
		(width 0.18288)
		(layer "In4.Cu")
		(net "M_F_CPU1_SA_DQ<25>")
	)
	(segment
		(start 158.740348 -273.268694)
		(end 157.61335 -273.268694)
		(width 0.18288)
		(layer "In4.Cu")
		(net "M_F_CPU1_SA_DQ<25>")
	)
	(segment
		(start 166.284402 -277.47849)
		(end 166.02583 -277.47849)
		(width 0.18288)
		(layer "In4.Cu")
		(net "M_F_CPU1_SA_DQ<25>")
	)
	(segment
		(start 166.916354 -281.998674)
		(end 166.916354 -281.095958)
		(width 0.18288)
		(layer "In4.Cu")
		(net "M_F_CPU1_SA_DQ<25>")
	)
	(segment
		(start 169.018458 -283.69387)
		(end 168.759886 -283.69387)
		(width 0.18288)
		(layer "In4.Cu")
		(net "M_F_CPU1_SA_DQ<25>")
	)
	(segment
		(start 163.466526 -275.03374)
		(end 163.306506 -274.87372)
		(width 0.18288)
		(layer "In4.Cu")
		(net "M_F_CPU1_SA_DQ<25>")
	)
	(segment
		(start 138.868404 -261.760716)
		(end 138.278108 -261.760716)
		(width 0.088646)
		(layer "In4.Cu")
		(net "M_F_CPU1_SA_DQ<25>")
	)
	(segment
		(start 131.303268 -261.731506)
		(end 131.298696 -261.7343)
		(width 0.088646)
		(layer "In4.Cu")
		(net "M_F_CPU1_SA_DQ<25>")
	)
	(segment
		(start 167.461946 -282.544266)
		(end 166.916354 -281.998674)
		(width 0.18288)
		(layer "In4.Cu")
		(net "M_F_CPU1_SA_DQ<25>")
	)
	(segment
		(start 165.513766 -276.966426)
		(end 164.409628 -276.966426)
		(width 0.18288)
		(layer "In4.Cu")
		(net "M_F_CPU1_SA_DQ<25>")
	)
	(segment
		(start 135.44677 -261.742682)
		(end 135.432292 -261.7343)
		(width 0.088646)
		(layer "In4.Cu")
		(net "M_F_CPU1_SA_DQ<25>")
	)
	(segment
		(start 138.278108 -261.760716)
		(end 138.251692 -261.7343)
		(width 0.088646)
		(layer "In4.Cu")
		(net "M_F_CPU1_SA_DQ<25>")
	)
	(segment
		(start 163.306506 -274.87372)
		(end 163.019232 -274.87372)
		(width 0.18288)
		(layer "In4.Cu")
		(net "M_F_CPU1_SA_DQ<25>")
	)
	(segment
		(start 163.466526 -276.620986)
		(end 163.466526 -275.03374)
		(width 0.18288)
		(layer "In4.Cu")
		(net "M_F_CPU1_SA_DQ<25>")
	)
	(segment
		(start 157.131004 -273.068796)
		(end 148.05152 -263.989312)
		(width 0.18288)
		(layer "In4.Cu")
		(net "M_F_CPU1_SA_DQ<25>")
	)
	(segment
		(start 166.774876 -278.227536)
		(end 166.774876 -277.968964)
		(width 0.18288)
		(layer "In4.Cu")
		(net "M_F_CPU1_SA_DQ<25>")
	)
	(segment
		(start 161.868866 -274.835366)
		(end 159.580834 -274.835366)
		(width 0.18288)
		(layer "In4.Cu")
		(net "M_F_CPU1_SA_DQ<25>")
	)
	(segment
		(start 164.409628 -276.966426)
		(end 164.224208 -276.781006)
		(width 0.18288)
		(layer "In4.Cu")
		(net "M_F_CPU1_SA_DQ<25>")
	)
	(segment
		(start 167.076374 -280.267918)
		(end 166.916354 -280.107898)
		(width 0.18288)
		(layer "In4.Cu")
		(net "M_F_CPU1_SA_DQ<25>")
	)
	(segment
		(start 166.02583 -277.47849)
		(end 165.513766 -276.966426)
		(width 0.18288)
		(layer "In4.Cu")
		(net "M_F_CPU1_SA_DQ<25>")
	)
	(segment
		(start 135.057896 -261.7343)
		(end 135.05053 -261.738364)
		(width 0.088646)
		(layer "In4.Cu")
		(net "M_F_CPU1_SA_DQ<25>")
	)
	(segment
		(start 172.795946 -286.56661)
		(end 172.024548 -285.795212)
		(width 0.18288)
		(layer "In4.Cu")
		(net "M_F_CPU1_SA_DQ<25>")
	)
	(segment
		(start 168.269412 -283.203396)
		(end 168.269412 -282.944824)
		(width 0.18288)
		(layer "In4.Cu")
		(net "M_F_CPU1_SA_DQ<25>")
	)
	(segment
		(start 134.118096 -261.7343)
		(end 134.11073 -261.738364)
		(width 0.088646)
		(layer "In4.Cu")
		(net "M_F_CPU1_SA_DQ<25>")
	)
	(segment
		(start 168.069006 -283.403802)
		(end 168.269412 -283.203396)
		(width 0.18288)
		(layer "In4.Cu")
		(net "M_F_CPU1_SA_DQ<25>")
	)
	(segment
		(start 137.877296 -261.7343)
		(end 137.877042 -261.7343)
		(width 0.088646)
		(layer "In4.Cu")
		(net "M_F_CPU1_SA_DQ<25>")
	)
	(segment
		(start 135.997696 -261.7343)
		(end 135.997442 -261.7343)
		(width 0.088646)
		(layer "In4.Cu")
		(net "M_F_CPU1_SA_DQ<25>")
	)
	(segment
		(start 158.92653 -274.181062)
		(end 158.92653 -273.454876)
		(width 0.18288)
		(layer "In4.Cu")
		(net "M_F_CPU1_SA_DQ<25>")
	)
	(segment
		(start 148.05152 -263.989312)
		(end 145.439638 -263.989312)
		(width 0.18288)
		(layer "In4.Cu")
		(net "M_F_CPU1_SA_DQ<25>")
	)
	(segment
		(start 166.882826 -277.138638)
		(end 166.624254 -277.138638)
		(width 0.18288)
		(layer "In4.Cu")
		(net "M_F_CPU1_SA_DQ<25>")
	)
	(segment
		(start 143.901668 -263.352026)
		(end 142.97152 -262.421878)
		(width 0.18288)
		(layer "In4.Cu")
		(net "M_F_CPU1_SA_DQ<25>")
	)
	(segment
		(start 171.1198 -285.795212)
		(end 169.018458 -283.69387)
		(width 0.18288)
		(layer "In4.Cu")
		(net "M_F_CPU1_SA_DQ<25>")
	)
	(segment
		(start 166.916354 -280.107898)
		(end 166.916354 -278.369014)
		(width 0.18288)
		(layer "In4.Cu")
		(net "M_F_CPU1_SA_DQ<25>")
	)
	(segment
		(start 166.774876 -277.968964)
		(end 167.114728 -277.629112)
		(width 0.18288)
		(layer "In4.Cu")
		(net "M_F_CPU1_SA_DQ<25>")
	)
	(segment
		(start 130.733546 -261.7343)
		(end 130.653536 -261.688072)
		(width 0.088646)
		(layer "In4.Cu")
		(net "M_F_CPU1_SA_DQ<25>")
	)
	(segment
		(start 139.355576 -261.631176)
		(end 139.226036 -261.760716)
		(width 0.18288)
		(layer "In4.Cu")
		(net "M_F_CPU1_SA_DQ<25>")
	)
	(segment
		(start 145.439638 -263.989312)
		(end 143.901668 -263.352026)
		(width 0.18288)
		(layer "In4.Cu")
		(net "M_F_CPU1_SA_DQ<25>")
	)
	(segment
		(start 162.652456 -275.240496)
		(end 162.273996 -275.240496)
		(width 0.18288)
		(layer "In4.Cu")
		(net "M_F_CPU1_SA_DQ<25>")
	)
	(segment
		(start 168.269412 -282.944824)
		(end 167.868854 -282.544266)
		(width 0.18288)
		(layer "In4.Cu")
		(net "M_F_CPU1_SA_DQ<25>")
	)
	(segment
		(start 142.97152 -262.421878)
		(end 141.062456 -261.631176)
		(width 0.18288)
		(layer "In4.Cu")
		(net "M_F_CPU1_SA_DQ<25>")
	)
	(segment
		(start 135.432292 -261.7343)
		(end 135.421116 -261.72795)
		(width 0.088646)
		(layer "In4.Cu")
		(net "M_F_CPU1_SA_DQ<25>")
	)
	(segment
		(start 167.868854 -282.544266)
		(end 167.461946 -282.544266)
		(width 0.18288)
		(layer "In4.Cu")
		(net "M_F_CPU1_SA_DQ<25>")
	)
	(segment
		(start 168.759886 -283.69387)
		(end 168.55948 -283.894276)
		(width 0.18288)
		(layer "In4.Cu")
		(net "M_F_CPU1_SA_DQ<25>")
	)
	(segment
		(start 167.114728 -277.37054)
		(end 166.882826 -277.138638)
		(width 0.18288)
		(layer "In4.Cu")
		(net "M_F_CPU1_SA_DQ<25>")
	)
	(segment
		(start 166.916354 -278.369014)
		(end 166.774876 -278.227536)
		(width 0.18288)
		(layer "In4.Cu")
		(net "M_F_CPU1_SA_DQ<25>")
	)
	(arc
		(start 135.997442 -261.7343)
		(mid 135.723183 -261.81017)
		(end 135.44677 -261.742682)
		(width 0.088646)
		(layer "In4.Cu")
		(net "M_F_CPU1_SA_DQ<25>")
	)
	(arc
		(start 137.877042 -261.7343)
		(mid 137.59434 -261.810076)
		(end 137.311638 -261.7343)
		(width 0.088646)
		(layer "In4.Cu")
		(net "M_F_CPU1_SA_DQ<25>")
	)
	(arc
		(start 138.251692 -261.7343)
		(mid 138.064494 -261.684157)
		(end 137.877296 -261.7343)
		(width 0.088646)
		(layer "In4.Cu")
		(net "M_F_CPU1_SA_DQ<25>")
	)
	(arc
		(start 132.23113 -261.738364)
		(mid 131.951698 -261.809927)
		(end 131.673346 -261.7343)
		(width 0.088646)
		(layer "In4.Cu")
		(net "M_F_CPU1_SA_DQ<25>")
	)
	(arc
		(start 134.11073 -261.738364)
		(mid 133.831298 -261.809927)
		(end 133.552946 -261.7343)
		(width 0.088646)
		(layer "In4.Cu")
		(net "M_F_CPU1_SA_DQ<25>")
	)
	(arc
		(start 133.17093 -261.738364)
		(mid 132.891498 -261.809927)
		(end 132.613146 -261.7343)
		(width 0.088646)
		(layer "In4.Cu")
		(net "M_F_CPU1_SA_DQ<25>")
	)
	(arc
		(start 132.613146 -261.7343)
		(mid 132.428482 -261.68404)
		(end 132.243068 -261.731506)
		(width 0.088646)
		(layer "In4.Cu")
		(net "M_F_CPU1_SA_DQ<25>")
	)
	(arc
		(start 135.421116 -261.72795)
		(mid 135.2387 -261.684201)
		(end 135.057896 -261.7343)
		(width 0.088646)
		(layer "In4.Cu")
		(net "M_F_CPU1_SA_DQ<25>")
	)
	(arc
		(start 136.937242 -261.7343)
		(mid 136.660683 -261.810043)
		(end 136.382506 -261.740396)
		(width 0.088646)
		(layer "In4.Cu")
		(net "M_F_CPU1_SA_DQ<25>")
	)
	(arc
		(start 134.492746 -261.7343)
		(mid 134.308082 -261.68404)
		(end 134.122668 -261.731506)
		(width 0.088646)
		(layer "In4.Cu")
		(net "M_F_CPU1_SA_DQ<25>")
	)
	(arc
		(start 131.29133 -261.738364)
		(mid 131.011898 -261.809927)
		(end 130.733546 -261.7343)
		(width 0.088646)
		(layer "In4.Cu")
		(net "M_F_CPU1_SA_DQ<25>")
	)
	(arc
		(start 131.673346 -261.7343)
		(mid 131.488682 -261.68404)
		(end 131.303268 -261.731506)
		(width 0.088646)
		(layer "In4.Cu")
		(net "M_F_CPU1_SA_DQ<25>")
	)
	(arc
		(start 137.311638 -261.7343)
		(mid 137.12444 -261.684157)
		(end 136.937242 -261.7343)
		(width 0.088646)
		(layer "In4.Cu")
		(net "M_F_CPU1_SA_DQ<25>")
	)
	(arc
		(start 136.372092 -261.7343)
		(mid 136.184894 -261.684157)
		(end 135.997696 -261.7343)
		(width 0.088646)
		(layer "In4.Cu")
		(net "M_F_CPU1_SA_DQ<25>")
	)
	(arc
		(start 133.552946 -261.7343)
		(mid 133.368282 -261.68404)
		(end 133.182868 -261.731506)
		(width 0.088646)
		(layer "In4.Cu")
		(net "M_F_CPU1_SA_DQ<25>")
	)
	(arc
		(start 130.653536 -261.688072)
		(mid 130.35036 -261.48535)
		(end 130.076194 -261.244842)
		(width 0.088646)
		(layer "In4.Cu")
		(net "M_F_CPU1_SA_DQ<25>")
	)
	(arc
		(start 135.05053 -261.738364)
		(mid 134.771098 -261.809927)
		(end 134.492746 -261.7343)
		(width 0.088646)
		(layer "In4.Cu")
		(net "M_F_CPU1_SA_DQ<25>")
	)
	(segment
		(start 179.852828 -288.266886)
		(end 179.421282 -287.83534)
		(width 0.20066)
		(layer "F.Cu")
		(net "M_F_CPU1_SA_DQ<24>")
	)
	(segment
		(start 176.333404 -287.9598)
		(end 176.333404 -288.327338)
		(width 0.20066)
		(layer "F.Cu")
		(net "M_F_CPU1_SA_DQ<24>")
	)
	(segment
		(start 176.843182 -287.84169)
		(end 176.796192 -287.84169)
		(width 0.101854)
		(layer "F.Cu")
		(net "M_F_CPU1_SA_DQ<24>")
	)
	(segment
		(start 130.546094 -262.058404)
		(end 130.546348 -262.058658)
		(width 0.20066)
		(layer "F.Cu")
		(net "M_F_CPU1_SA_DQ<24>")
	)
	(segment
		(start 176.796192 -287.84169)
		(end 176.451514 -287.84169)
		(width 0.20066)
		(layer "F.Cu")
		(net "M_F_CPU1_SA_DQ<24>")
	)
	(segment
		(start 181.444392 -288.266886)
		(end 179.852828 -288.266886)
		(width 0.20066)
		(layer "F.Cu")
		(net "M_F_CPU1_SA_DQ<24>")
	)
	(segment
		(start 176.145444 -288.515298)
		(end 175.67021 -288.515298)
		(width 0.20066)
		(layer "F.Cu")
		(net "M_F_CPU1_SA_DQ<24>")
	)
	(segment
		(start 176.451514 -287.84169)
		(end 176.333404 -287.9598)
		(width 0.20066)
		(layer "F.Cu")
		(net "M_F_CPU1_SA_DQ<24>")
	)
	(segment
		(start 175.67021 -288.515298)
		(end 175.421544 -288.266632)
		(width 0.20066)
		(layer "F.Cu")
		(net "M_F_CPU1_SA_DQ<24>")
	)
	(segment
		(start 173.900846 -288.266632)
		(end 172.795946 -288.266632)
		(width 0.20066)
		(layer "F.Cu")
		(net "M_F_CPU1_SA_DQ<24>")
	)
	(segment
		(start 176.333404 -288.327338)
		(end 176.145444 -288.515298)
		(width 0.20066)
		(layer "F.Cu")
		(net "M_F_CPU1_SA_DQ<24>")
	)
	(segment
		(start 130.546094 -261.522718)
		(end 130.546094 -262.058404)
		(width 0.20066)
		(layer "F.Cu")
		(net "M_F_CPU1_SA_DQ<24>")
	)
	(segment
		(start 179.004976 -287.84169)
		(end 176.843182 -287.84169)
		(width 0.1016)
		(layer "F.Cu")
		(net "M_F_CPU1_SA_DQ<24>")
	)
	(segment
		(start 175.421544 -288.266632)
		(end 173.900846 -288.266632)
		(width 0.20066)
		(layer "F.Cu")
		(net "M_F_CPU1_SA_DQ<24>")
	)
	(segment
		(start 181.444646 -288.266632)
		(end 181.444392 -288.266886)
		(width 0.20066)
		(layer "F.Cu")
		(net "M_F_CPU1_SA_DQ<24>")
	)
	(segment
		(start 179.421282 -287.83534)
		(end 179.011326 -287.83534)
		(width 0.20066)
		(layer "F.Cu")
		(net "M_F_CPU1_SA_DQ<24>")
	)
	(segment
		(start 179.011326 -287.83534)
		(end 179.004976 -287.84169)
		(width 0.1016)
		(layer "F.Cu")
		(net "M_F_CPU1_SA_DQ<24>")
	)
	(segment
		(start 165.642544 -279.260046)
		(end 165.8493 -279.05329)
		(width 0.18288)
		(layer "In4.Cu")
		(net "M_F_CPU1_SA_DQ<24>")
	)
	(segment
		(start 165.497764 -282.555696)
		(end 165.497764 -282.059888)
		(width 0.18288)
		(layer "In4.Cu")
		(net "M_F_CPU1_SA_DQ<24>")
	)
	(segment
		(start 164.893498 -278.769572)
		(end 164.604954 -278.481028)
		(width 0.18288)
		(layer "In4.Cu")
		(net "M_F_CPU1_SA_DQ<24>")
	)
	(segment
		(start 165.617398 -278.562816)
		(end 165.358826 -278.562816)
		(width 0.18288)
		(layer "In4.Cu")
		(net "M_F_CPU1_SA_DQ<24>")
	)
	(segment
		(start 135.902192 -262.548116)
		(end 135.902446 -262.548116)
		(width 0.088646)
		(layer "In4.Cu")
		(net "M_F_CPU1_SA_DQ<24>")
	)
	(segment
		(start 165.8493 -278.794718)
		(end 165.617398 -278.562816)
		(width 0.18288)
		(layer "In4.Cu")
		(net "M_F_CPU1_SA_DQ<24>")
	)
	(segment
		(start 168.140634 -285.198566)
		(end 165.497764 -282.555696)
		(width 0.18288)
		(layer "In4.Cu")
		(net "M_F_CPU1_SA_DQ<24>")
	)
	(segment
		(start 158.779464 -276.016466)
		(end 158.596584 -275.833586)
		(width 0.18288)
		(layer "In4.Cu")
		(net "M_F_CPU1_SA_DQ<24>")
	)
	(segment
		(start 164.604954 -278.481028)
		(end 163.736528 -278.481028)
		(width 0.18288)
		(layer "In4.Cu")
		(net "M_F_CPU1_SA_DQ<24>")
	)
	(segment
		(start 162.417506 -278.353774)
		(end 162.158934 -278.353774)
		(width 0.18288)
		(layer "In4.Cu")
		(net "M_F_CPU1_SA_DQ<24>")
	)
	(segment
		(start 168.994074 -285.831026)
		(end 168.361614 -285.198566)
		(width 0.18288)
		(layer "In4.Cu")
		(net "M_F_CPU1_SA_DQ<24>")
	)
	(segment
		(start 165.358826 -278.562816)
		(end 165.15207 -278.769572)
		(width 0.18288)
		(layer "In4.Cu")
		(net "M_F_CPU1_SA_DQ<24>")
	)
	(segment
		(start 131.203446 -262.548116)
		(end 131.201414 -262.546846)
		(width 0.088646)
		(layer "In4.Cu")
		(net "M_F_CPU1_SA_DQ<24>")
	)
	(segment
		(start 140.31468 -262.579358)
		(end 140.264896 -262.629142)
		(width 0.088646)
		(layer "In4.Cu")
		(net "M_F_CPU1_SA_DQ<24>")
	)
	(segment
		(start 140.264896 -262.629142)
		(end 139.837922 -262.629142)
		(width 0.088646)
		(layer "In4.Cu")
		(net "M_F_CPU1_SA_DQ<24>")
	)
	(segment
		(start 165.841426 -281.18943)
		(end 165.501066 -280.84907)
		(width 0.18288)
		(layer "In4.Cu")
		(net "M_F_CPU1_SA_DQ<24>")
	)
	(segment
		(start 162.39363 -277.13813)
		(end 161.833306 -276.577806)
		(width 0.18288)
		(layer "In4.Cu")
		(net "M_F_CPU1_SA_DQ<24>")
	)
	(segment
		(start 172.321474 -287.59912)
		(end 171.170346 -287.59912)
		(width 0.18288)
		(layer "In4.Cu")
		(net "M_F_CPU1_SA_DQ<24>")
	)
	(segment
		(start 159.290004 -276.641814)
		(end 158.962344 -276.641814)
		(width 0.18288)
		(layer "In4.Cu")
		(net "M_F_CPU1_SA_DQ<24>")
	)
	(segment
		(start 172.795946 -288.073592)
		(end 172.321474 -287.59912)
		(width 0.18288)
		(layer "In4.Cu")
		(net "M_F_CPU1_SA_DQ<24>")
	)
	(segment
		(start 134.967218 -262.550656)
		(end 134.962646 -262.548116)
		(width 0.088646)
		(layer "In4.Cu")
		(net "M_F_CPU1_SA_DQ<24>")
	)
	(segment
		(start 165.497764 -282.059888)
		(end 165.841426 -281.716226)
		(width 0.18288)
		(layer "In4.Cu")
		(net "M_F_CPU1_SA_DQ<24>")
	)
	(segment
		(start 172.795946 -288.266632)
		(end 172.795946 -288.073592)
		(width 0.18288)
		(layer "In4.Cu")
		(net "M_F_CPU1_SA_DQ<24>")
	)
	(segment
		(start 161.927032 -278.121872)
		(end 161.927032 -277.8633)
		(width 0.18288)
		(layer "In4.Cu")
		(net "M_F_CPU1_SA_DQ<24>")
	)
	(segment
		(start 159.472884 -276.458934)
		(end 159.290004 -276.641814)
		(width 0.18288)
		(layer "In4.Cu")
		(net "M_F_CPU1_SA_DQ<24>")
	)
	(segment
		(start 132.149088 -262.551418)
		(end 132.137404 -262.544814)
		(width 0.088646)
		(layer "In4.Cu")
		(net "M_F_CPU1_SA_DQ<24>")
	)
	(segment
		(start 161.927032 -277.8633)
		(end 162.39363 -277.396702)
		(width 0.18288)
		(layer "In4.Cu")
		(net "M_F_CPU1_SA_DQ<24>")
	)
	(segment
		(start 131.209288 -262.551418)
		(end 131.203446 -262.548116)
		(width 0.088646)
		(layer "In4.Cu")
		(net "M_F_CPU1_SA_DQ<24>")
	)
	(segment
		(start 163.142676 -277.887176)
		(end 162.884104 -277.887176)
		(width 0.18288)
		(layer "In4.Cu")
		(net "M_F_CPU1_SA_DQ<24>")
	)
	(segment
		(start 159.472884 -276.016466)
		(end 159.472884 -276.458934)
		(width 0.18288)
		(layer "In4.Cu")
		(net "M_F_CPU1_SA_DQ<24>")
	)
	(segment
		(start 162.158934 -278.353774)
		(end 161.927032 -278.121872)
		(width 0.18288)
		(layer "In4.Cu")
		(net "M_F_CPU1_SA_DQ<24>")
	)
	(segment
		(start 145.208244 -264.984992)
		(end 143.32585 -264.205466)
		(width 0.18288)
		(layer "In4.Cu")
		(net "M_F_CPU1_SA_DQ<24>")
	)
	(segment
		(start 160.479486 -275.833586)
		(end 159.655764 -275.833586)
		(width 0.18288)
		(layer "In4.Cu")
		(net "M_F_CPU1_SA_DQ<24>")
	)
	(segment
		(start 158.779464 -276.458934)
		(end 158.779464 -276.016466)
		(width 0.18288)
		(layer "In4.Cu")
		(net "M_F_CPU1_SA_DQ<24>")
	)
	(segment
		(start 163.736528 -278.481028)
		(end 163.142676 -277.887176)
		(width 0.18288)
		(layer "In4.Cu")
		(net "M_F_CPU1_SA_DQ<24>")
	)
	(segment
		(start 165.501066 -280.84907)
		(end 165.501066 -280.36901)
		(width 0.18288)
		(layer "In4.Cu")
		(net "M_F_CPU1_SA_DQ<24>")
	)
	(segment
		(start 140.494004 -262.579358)
		(end 140.31468 -262.579358)
		(width 0.088646)
		(layer "In4.Cu")
		(net "M_F_CPU1_SA_DQ<24>")
	)
	(segment
		(start 158.424626 -275.833586)
		(end 147.576032 -264.984992)
		(width 0.18288)
		(layer "In4.Cu")
		(net "M_F_CPU1_SA_DQ<24>")
	)
	(segment
		(start 168.361614 -285.198566)
		(end 168.140634 -285.198566)
		(width 0.18288)
		(layer "In4.Cu")
		(net "M_F_CPU1_SA_DQ<24>")
	)
	(segment
		(start 158.596584 -275.833586)
		(end 158.424626 -275.833586)
		(width 0.18288)
		(layer "In4.Cu")
		(net "M_F_CPU1_SA_DQ<24>")
	)
	(segment
		(start 165.755066 -279.63114)
		(end 165.642544 -279.518618)
		(width 0.18288)
		(layer "In4.Cu")
		(net "M_F_CPU1_SA_DQ<24>")
	)
	(segment
		(start 134.028688 -262.551418)
		(end 134.017004 -262.544814)
		(width 0.088646)
		(layer "In4.Cu")
		(net "M_F_CPU1_SA_DQ<24>")
	)
	(segment
		(start 161.833306 -276.577806)
		(end 161.223706 -276.577806)
		(width 0.18288)
		(layer "In4.Cu")
		(net "M_F_CPU1_SA_DQ<24>")
	)
	(segment
		(start 162.39363 -277.396702)
		(end 162.39363 -277.13813)
		(width 0.18288)
		(layer "In4.Cu")
		(net "M_F_CPU1_SA_DQ<24>")
	)
	(segment
		(start 139.837922 -262.629142)
		(end 139.818872 -262.610092)
		(width 0.088646)
		(layer "In4.Cu")
		(net "M_F_CPU1_SA_DQ<24>")
	)
	(segment
		(start 141.844014 -262.72363)
		(end 141.49578 -262.579358)
		(width 0.18288)
		(layer "In4.Cu")
		(net "M_F_CPU1_SA_DQ<24>")
	)
	(segment
		(start 169.402252 -285.831026)
		(end 168.994074 -285.831026)
		(width 0.18288)
		(layer "In4.Cu")
		(net "M_F_CPU1_SA_DQ<24>")
	)
	(segment
		(start 158.962344 -276.641814)
		(end 158.779464 -276.458934)
		(width 0.18288)
		(layer "In4.Cu")
		(net "M_F_CPU1_SA_DQ<24>")
	)
	(segment
		(start 165.841426 -281.716226)
		(end 165.841426 -281.18943)
		(width 0.18288)
		(layer "In4.Cu")
		(net "M_F_CPU1_SA_DQ<24>")
	)
	(segment
		(start 137.792206 -262.554212)
		(end 137.781792 -262.548116)
		(width 0.088646)
		(layer "In4.Cu")
		(net "M_F_CPU1_SA_DQ<24>")
	)
	(segment
		(start 133.088888 -262.551418)
		(end 133.077204 -262.544814)
		(width 0.088646)
		(layer "In4.Cu")
		(net "M_F_CPU1_SA_DQ<24>")
	)
	(segment
		(start 147.576032 -264.984992)
		(end 145.208244 -264.984992)
		(width 0.18288)
		(layer "In4.Cu")
		(net "M_F_CPU1_SA_DQ<24>")
	)
	(segment
		(start 161.223706 -276.577806)
		(end 160.479486 -275.833586)
		(width 0.18288)
		(layer "In4.Cu")
		(net "M_F_CPU1_SA_DQ<24>")
	)
	(segment
		(start 141.49578 -262.579358)
		(end 140.494004 -262.579358)
		(width 0.18288)
		(layer "In4.Cu")
		(net "M_F_CPU1_SA_DQ<24>")
	)
	(segment
		(start 165.642544 -279.518618)
		(end 165.642544 -279.260046)
		(width 0.18288)
		(layer "In4.Cu")
		(net "M_F_CPU1_SA_DQ<24>")
	)
	(segment
		(start 162.884104 -277.887176)
		(end 162.417506 -278.353774)
		(width 0.18288)
		(layer "In4.Cu")
		(net "M_F_CPU1_SA_DQ<24>")
	)
	(segment
		(start 143.32585 -264.205466)
		(end 141.844014 -262.72363)
		(width 0.18288)
		(layer "In4.Cu")
		(net "M_F_CPU1_SA_DQ<24>")
	)
	(segment
		(start 165.755066 -280.11501)
		(end 165.755066 -279.63114)
		(width 0.18288)
		(layer "In4.Cu")
		(net "M_F_CPU1_SA_DQ<24>")
	)
	(segment
		(start 159.655764 -275.833586)
		(end 159.472884 -276.016466)
		(width 0.18288)
		(layer "In4.Cu")
		(net "M_F_CPU1_SA_DQ<24>")
	)
	(segment
		(start 138.736578 -262.556752)
		(end 138.721846 -262.548116)
		(width 0.088646)
		(layer "In4.Cu")
		(net "M_F_CPU1_SA_DQ<24>")
	)
	(segment
		(start 134.962646 -262.548116)
		(end 134.956804 -262.544814)
		(width 0.088646)
		(layer "In4.Cu")
		(net "M_F_CPU1_SA_DQ<24>")
	)
	(segment
		(start 165.15207 -278.769572)
		(end 164.893498 -278.769572)
		(width 0.18288)
		(layer "In4.Cu")
		(net "M_F_CPU1_SA_DQ<24>")
	)
	(segment
		(start 139.676378 -262.556752)
		(end 139.661646 -262.548116)
		(width 0.088646)
		(layer "In4.Cu")
		(net "M_F_CPU1_SA_DQ<24>")
	)
	(segment
		(start 171.170346 -287.59912)
		(end 169.402252 -285.831026)
		(width 0.18288)
		(layer "In4.Cu")
		(net "M_F_CPU1_SA_DQ<24>")
	)
	(segment
		(start 165.501066 -280.36901)
		(end 165.755066 -280.11501)
		(width 0.18288)
		(layer "In4.Cu")
		(net "M_F_CPU1_SA_DQ<24>")
	)
	(segment
		(start 165.8493 -279.05329)
		(end 165.8493 -278.794718)
		(width 0.18288)
		(layer "In4.Cu")
		(net "M_F_CPU1_SA_DQ<24>")
	)
	(arc
		(start 137.407396 -262.548116)
		(mid 137.124694 -262.623892)
		(end 136.841992 -262.548116)
		(width 0.088646)
		(layer "In4.Cu")
		(net "M_F_CPU1_SA_DQ<24>")
	)
	(arc
		(start 138.34745 -262.548116)
		(mid 138.070637 -262.623986)
		(end 137.792206 -262.554212)
		(width 0.088646)
		(layer "In4.Cu")
		(net "M_F_CPU1_SA_DQ<24>")
	)
	(arc
		(start 131.768596 -262.548116)
		(mid 131.489393 -262.623756)
		(end 131.209288 -262.551418)
		(width 0.088646)
		(layer "In4.Cu")
		(net "M_F_CPU1_SA_DQ<24>")
	)
	(arc
		(start 138.721846 -262.548116)
		(mid 138.534648 -262.497973)
		(end 138.34745 -262.548116)
		(width 0.088646)
		(layer "In4.Cu")
		(net "M_F_CPU1_SA_DQ<24>")
	)
	(arc
		(start 139.28725 -262.548116)
		(mid 139.013051 -262.623951)
		(end 138.736578 -262.556752)
		(width 0.088646)
		(layer "In4.Cu")
		(net "M_F_CPU1_SA_DQ<24>")
	)
	(arc
		(start 136.467596 -262.548116)
		(mid 136.184894 -262.623892)
		(end 135.902192 -262.548116)
		(width 0.088646)
		(layer "In4.Cu")
		(net "M_F_CPU1_SA_DQ<24>")
	)
	(arc
		(start 131.201414 -262.546846)
		(mid 130.863892 -262.316156)
		(end 130.546348 -262.058658)
		(width 0.088646)
		(layer "In4.Cu")
		(net "M_F_CPU1_SA_DQ<24>")
	)
	(arc
		(start 137.781792 -262.548116)
		(mid 137.594594 -262.497973)
		(end 137.407396 -262.548116)
		(width 0.088646)
		(layer "In4.Cu")
		(net "M_F_CPU1_SA_DQ<24>")
	)
	(arc
		(start 135.902446 -262.548116)
		(mid 135.715138 -262.497973)
		(end 135.527796 -262.548116)
		(width 0.088646)
		(layer "In4.Cu")
		(net "M_F_CPU1_SA_DQ<24>")
	)
	(arc
		(start 134.956804 -262.544814)
		(mid 134.771949 -262.497864)
		(end 134.587996 -262.548116)
		(width 0.088646)
		(layer "In4.Cu")
		(net "M_F_CPU1_SA_DQ<24>")
	)
	(arc
		(start 134.587996 -262.548116)
		(mid 134.308793 -262.623756)
		(end 134.028688 -262.551418)
		(width 0.088646)
		(layer "In4.Cu")
		(net "M_F_CPU1_SA_DQ<24>")
	)
	(arc
		(start 139.818872 -262.610092)
		(mid 139.745825 -262.588233)
		(end 139.676378 -262.556752)
		(width 0.088646)
		(layer "In4.Cu")
		(net "M_F_CPU1_SA_DQ<24>")
	)
	(arc
		(start 136.841992 -262.548116)
		(mid 136.654794 -262.497973)
		(end 136.467596 -262.548116)
		(width 0.088646)
		(layer "In4.Cu")
		(net "M_F_CPU1_SA_DQ<24>")
	)
	(arc
		(start 134.017004 -262.544814)
		(mid 133.832149 -262.497864)
		(end 133.648196 -262.548116)
		(width 0.088646)
		(layer "In4.Cu")
		(net "M_F_CPU1_SA_DQ<24>")
	)
	(arc
		(start 133.648196 -262.548116)
		(mid 133.368993 -262.623756)
		(end 133.088888 -262.551418)
		(width 0.088646)
		(layer "In4.Cu")
		(net "M_F_CPU1_SA_DQ<24>")
	)
	(arc
		(start 133.077204 -262.544814)
		(mid 132.892349 -262.497864)
		(end 132.708396 -262.548116)
		(width 0.088646)
		(layer "In4.Cu")
		(net "M_F_CPU1_SA_DQ<24>")
	)
	(arc
		(start 135.527796 -262.548116)
		(mid 135.247852 -262.62376)
		(end 134.967218 -262.550656)
		(width 0.088646)
		(layer "In4.Cu")
		(net "M_F_CPU1_SA_DQ<24>")
	)
	(arc
		(start 132.708396 -262.548116)
		(mid 132.429193 -262.623756)
		(end 132.149088 -262.551418)
		(width 0.088646)
		(layer "In4.Cu")
		(net "M_F_CPU1_SA_DQ<24>")
	)
	(arc
		(start 132.137404 -262.544814)
		(mid 131.952549 -262.497864)
		(end 131.768596 -262.548116)
		(width 0.088646)
		(layer "In4.Cu")
		(net "M_F_CPU1_SA_DQ<24>")
	)
	(arc
		(start 139.661646 -262.548116)
		(mid 139.474448 -262.497973)
		(end 139.28725 -262.548116)
		(width 0.088646)
		(layer "In4.Cu")
		(net "M_F_CPU1_SA_DQ<24>")
	)
	(segment
		(start 182.455058 -289.553904)
		(end 183.136286 -289.553904)
		(width 0.20066)
		(layer "F.Cu")
		(net "M_F_CPU1_SA_DQ<23>")
	)
	(segment
		(start 180.423058 -289.548824)
		(end 180.427884 -289.548824)
		(width 0.101854)
		(layer "F.Cu")
		(net "M_F_CPU1_SA_DQ<23>")
	)
	(segment
		(start 180.131212 -289.548824)
		(end 180.423058 -289.548824)
		(width 0.20066)
		(layer "F.Cu")
		(net "M_F_CPU1_SA_DQ<23>")
	)
	(segment
		(start 183.340248 -289.349942)
		(end 183.340248 -289.09899)
		(width 0.20066)
		(layer "F.Cu")
		(net "M_F_CPU1_SA_DQ<23>")
	)
	(segment
		(start 180.434996 -289.541712)
		(end 182.442866 -289.541712)
		(width 0.1016)
		(layer "F.Cu")
		(net "M_F_CPU1_SA_DQ<23>")
	)
	(segment
		(start 180.427884 -289.548824)
		(end 180.434996 -289.541712)
		(width 0.1016)
		(layer "F.Cu")
		(net "M_F_CPU1_SA_DQ<23>")
	)
	(segment
		(start 134.775448 -266.127992)
		(end 134.775194 -266.128246)
		(width 0.20066)
		(layer "F.Cu")
		(net "M_F_CPU1_SA_DQ<23>")
	)
	(segment
		(start 179.699158 -289.11677)
		(end 180.131212 -289.548824)
		(width 0.20066)
		(layer "F.Cu")
		(net "M_F_CPU1_SA_DQ<23>")
	)
	(segment
		(start 178.000914 -289.11677)
		(end 179.699158 -289.11677)
		(width 0.20066)
		(layer "F.Cu")
		(net "M_F_CPU1_SA_DQ<23>")
	)
	(segment
		(start 176.896014 -289.11677)
		(end 178.000914 -289.11677)
		(width 0.20066)
		(layer "F.Cu")
		(net "M_F_CPU1_SA_DQ<23>")
	)
	(segment
		(start 134.775448 -265.592306)
		(end 134.775448 -266.127992)
		(width 0.20066)
		(layer "F.Cu")
		(net "M_F_CPU1_SA_DQ<23>")
	)
	(segment
		(start 183.574436 -288.864802)
		(end 183.958484 -288.864802)
		(width 0.20066)
		(layer "F.Cu")
		(net "M_F_CPU1_SA_DQ<23>")
	)
	(segment
		(start 184.210452 -289.11677)
		(end 185.544714 -289.11677)
		(width 0.20066)
		(layer "F.Cu")
		(net "M_F_CPU1_SA_DQ<23>")
	)
	(segment
		(start 183.958484 -288.864802)
		(end 184.210452 -289.11677)
		(width 0.20066)
		(layer "F.Cu")
		(net "M_F_CPU1_SA_DQ<23>")
	)
	(segment
		(start 182.442866 -289.541712)
		(end 182.455058 -289.553904)
		(width 0.1016)
		(layer "F.Cu")
		(net "M_F_CPU1_SA_DQ<23>")
	)
	(segment
		(start 183.340248 -289.09899)
		(end 183.574436 -288.864802)
		(width 0.20066)
		(layer "F.Cu")
		(net "M_F_CPU1_SA_DQ<23>")
	)
	(segment
		(start 183.136286 -289.553904)
		(end 183.340248 -289.349942)
		(width 0.20066)
		(layer "F.Cu")
		(net "M_F_CPU1_SA_DQ<23>")
	)
	(segment
		(start 174.959518 -283.74721)
		(end 174.678086 -283.465778)
		(width 0.18288)
		(layer "In2.Cu")
		(net "M_F_CPU1_SA_DQ<23>")
	)
	(segment
		(start 144.020032 -266.431014)
		(end 142.959074 -265.99134)
		(width 0.18288)
		(layer "In2.Cu")
		(net "M_F_CPU1_SA_DQ<23>")
	)
	(segment
		(start 135.447278 -265.629898)
		(end 135.432546 -265.638534)
		(width 0.088646)
		(layer "In2.Cu")
		(net "M_F_CPU1_SA_DQ<23>")
	)
	(segment
		(start 158.049214 -278.454104)
		(end 157.726634 -278.776684)
		(width 0.18288)
		(layer "In2.Cu")
		(net "M_F_CPU1_SA_DQ<23>")
	)
	(segment
		(start 134.462774 -266.127992)
		(end 134.77494 -266.127992)
		(width 0.088646)
		(layer "In2.Cu")
		(net "M_F_CPU1_SA_DQ<23>")
	)
	(segment
		(start 176.115218 -285.84525)
		(end 175.711358 -285.44139)
		(width 0.18288)
		(layer "In2.Cu")
		(net "M_F_CPU1_SA_DQ<23>")
	)
	(segment
		(start 168.136824 -281.86888)
		(end 168.023794 -281.98191)
		(width 0.18288)
		(layer "In2.Cu")
		(net "M_F_CPU1_SA_DQ<23>")
	)
	(segment
		(start 149.209506 -269.32509)
		(end 146.914108 -269.32509)
		(width 0.18288)
		(layer "In2.Cu")
		(net "M_F_CPU1_SA_DQ<23>")
	)
	(segment
		(start 159.924496 -279.335484)
		(end 159.751522 -279.16251)
		(width 0.18288)
		(layer "In2.Cu")
		(net "M_F_CPU1_SA_DQ<23>")
	)
	(segment
		(start 175.922178 -283.74721)
		(end 174.959518 -283.74721)
		(width 0.18288)
		(layer "In2.Cu")
		(net "M_F_CPU1_SA_DQ<23>")
	)
	(segment
		(start 166.398194 -281.154632)
		(end 165.683692 -281.154632)
		(width 0.18288)
		(layer "In2.Cu")
		(net "M_F_CPU1_SA_DQ<23>")
	)
	(segment
		(start 152.7429 -272.858484)
		(end 149.209506 -269.32509)
		(width 0.18288)
		(layer "In2.Cu")
		(net "M_F_CPU1_SA_DQ<23>")
	)
	(segment
		(start 140.55979 -265.93165)
		(end 140.546074 -265.917934)
		(width 0.088646)
		(layer "In2.Cu")
		(net "M_F_CPU1_SA_DQ<23>")
	)
	(segment
		(start 157.25521 -278.776684)
		(end 153.737056 -275.25853)
		(width 0.18288)
		(layer "In2.Cu")
		(net "M_F_CPU1_SA_DQ<23>")
	)
	(segment
		(start 173.43501 -283.465778)
		(end 173.309026 -283.591762)
		(width 0.18288)
		(layer "In2.Cu")
		(net "M_F_CPU1_SA_DQ<23>")
	)
	(segment
		(start 167.225472 -281.98191)
		(end 166.398194 -281.154632)
		(width 0.18288)
		(layer "In2.Cu")
		(net "M_F_CPU1_SA_DQ<23>")
	)
	(segment
		(start 159.585406 -278.454104)
		(end 158.049214 -278.454104)
		(width 0.18288)
		(layer "In2.Cu")
		(net "M_F_CPU1_SA_DQ<23>")
	)
	(segment
		(start 139.206478 -265.629898)
		(end 139.191746 -265.638534)
		(width 0.088646)
		(layer "In2.Cu")
		(net "M_F_CPU1_SA_DQ<23>")
	)
	(segment
		(start 157.726634 -278.776684)
		(end 157.25521 -278.776684)
		(width 0.18288)
		(layer "In2.Cu")
		(net "M_F_CPU1_SA_DQ<23>")
	)
	(segment
		(start 174.678086 -283.465778)
		(end 173.43501 -283.465778)
		(width 0.18288)
		(layer "In2.Cu")
		(net "M_F_CPU1_SA_DQ<23>")
	)
	(segment
		(start 159.751522 -278.62022)
		(end 159.585406 -278.454104)
		(width 0.18288)
		(layer "In2.Cu")
		(net "M_F_CPU1_SA_DQ<23>")
	)
	(segment
		(start 165.683692 -281.154632)
		(end 164.703252 -280.174192)
		(width 0.18288)
		(layer "In2.Cu")
		(net "M_F_CPU1_SA_DQ<23>")
	)
	(segment
		(start 176.115218 -288.92373)
		(end 176.115218 -285.84525)
		(width 0.18288)
		(layer "In2.Cu")
		(net "M_F_CPU1_SA_DQ<23>")
	)
	(segment
		(start 161.170112 -280.174192)
		(end 160.331404 -279.335484)
		(width 0.18288)
		(layer "In2.Cu")
		(net "M_F_CPU1_SA_DQ<23>")
	)
	(segment
		(start 176.115218 -284.43809)
		(end 176.115218 -283.94025)
		(width 0.18288)
		(layer "In2.Cu")
		(net "M_F_CPU1_SA_DQ<23>")
	)
	(segment
		(start 175.711358 -284.84195)
		(end 176.115218 -284.43809)
		(width 0.18288)
		(layer "In2.Cu")
		(net "M_F_CPU1_SA_DQ<23>")
	)
	(segment
		(start 153.737056 -275.25853)
		(end 152.7429 -272.858484)
		(width 0.18288)
		(layer "In2.Cu")
		(net "M_F_CPU1_SA_DQ<23>")
	)
	(segment
		(start 140.900404 -265.99134)
		(end 140.703808 -265.99134)
		(width 0.088646)
		(layer "In2.Cu")
		(net "M_F_CPU1_SA_DQ<23>")
	)
	(segment
		(start 169.533824 -281.86888)
		(end 168.136824 -281.86888)
		(width 0.18288)
		(layer "In2.Cu")
		(net "M_F_CPU1_SA_DQ<23>")
	)
	(segment
		(start 176.115218 -283.94025)
		(end 175.922178 -283.74721)
		(width 0.18288)
		(layer "In2.Cu")
		(net "M_F_CPU1_SA_DQ<23>")
	)
	(segment
		(start 142.959074 -265.99134)
		(end 140.900404 -265.99134)
		(width 0.18288)
		(layer "In2.Cu")
		(net "M_F_CPU1_SA_DQ<23>")
	)
	(segment
		(start 159.751522 -279.16251)
		(end 159.751522 -278.62022)
		(width 0.18288)
		(layer "In2.Cu")
		(net "M_F_CPU1_SA_DQ<23>")
	)
	(segment
		(start 160.331404 -279.335484)
		(end 159.924496 -279.335484)
		(width 0.18288)
		(layer "In2.Cu")
		(net "M_F_CPU1_SA_DQ<23>")
	)
	(segment
		(start 136.387078 -265.629898)
		(end 136.372346 -265.638534)
		(width 0.088646)
		(layer "In2.Cu")
		(net "M_F_CPU1_SA_DQ<23>")
	)
	(segment
		(start 176.308258 -289.11677)
		(end 176.115218 -288.92373)
		(width 0.18288)
		(layer "In2.Cu")
		(net "M_F_CPU1_SA_DQ<23>")
	)
	(segment
		(start 137.326878 -265.629898)
		(end 137.312146 -265.638534)
		(width 0.088646)
		(layer "In2.Cu")
		(net "M_F_CPU1_SA_DQ<23>")
	)
	(segment
		(start 139.77747 -265.650218)
		(end 139.75715 -265.638534)
		(width 0.088646)
		(layer "In2.Cu")
		(net "M_F_CPU1_SA_DQ<23>")
	)
	(segment
		(start 168.023794 -281.98191)
		(end 167.225472 -281.98191)
		(width 0.18288)
		(layer "In2.Cu")
		(net "M_F_CPU1_SA_DQ<23>")
	)
	(segment
		(start 134.77494 -266.127992)
		(end 134.775194 -266.128246)
		(width 0.088646)
		(layer "In2.Cu")
		(net "M_F_CPU1_SA_DQ<23>")
	)
	(segment
		(start 138.266678 -265.629898)
		(end 138.251946 -265.638534)
		(width 0.088646)
		(layer "In2.Cu")
		(net "M_F_CPU1_SA_DQ<23>")
	)
	(segment
		(start 175.711358 -285.44139)
		(end 175.711358 -284.84195)
		(width 0.18288)
		(layer "In2.Cu")
		(net "M_F_CPU1_SA_DQ<23>")
	)
	(segment
		(start 135.149844 -266.114022)
		(end 135.149844 -266.130278)
		(width 0.088646)
		(layer "In2.Cu")
		(net "M_F_CPU1_SA_DQ<23>")
	)
	(segment
		(start 176.896014 -289.11677)
		(end 176.308258 -289.11677)
		(width 0.18288)
		(layer "In2.Cu")
		(net "M_F_CPU1_SA_DQ<23>")
	)
	(segment
		(start 146.914108 -269.32509)
		(end 144.020032 -266.431014)
		(width 0.18288)
		(layer "In2.Cu")
		(net "M_F_CPU1_SA_DQ<23>")
	)
	(segment
		(start 172.154342 -283.591762)
		(end 171.116498 -282.553918)
		(width 0.18288)
		(layer "In2.Cu")
		(net "M_F_CPU1_SA_DQ<23>")
	)
	(segment
		(start 164.703252 -280.174192)
		(end 161.170112 -280.174192)
		(width 0.18288)
		(layer "In2.Cu")
		(net "M_F_CPU1_SA_DQ<23>")
	)
	(segment
		(start 134.405116 -266.18565)
		(end 134.462774 -266.127992)
		(width 0.088646)
		(layer "In2.Cu")
		(net "M_F_CPU1_SA_DQ<23>")
	)
	(segment
		(start 173.309026 -283.591762)
		(end 172.154342 -283.591762)
		(width 0.18288)
		(layer "In2.Cu")
		(net "M_F_CPU1_SA_DQ<23>")
	)
	(segment
		(start 171.116498 -282.553918)
		(end 170.218862 -282.553918)
		(width 0.18288)
		(layer "In2.Cu")
		(net "M_F_CPU1_SA_DQ<23>")
	)
	(segment
		(start 170.218862 -282.553918)
		(end 169.533824 -281.86888)
		(width 0.18288)
		(layer "In2.Cu")
		(net "M_F_CPU1_SA_DQ<23>")
	)
	(arc
		(start 138.251946 -265.638534)
		(mid 138.064748 -265.688677)
		(end 137.87755 -265.638534)
		(width 0.088646)
		(layer "In2.Cu")
		(net "M_F_CPU1_SA_DQ<23>")
	)
	(arc
		(start 136.93775 -265.638534)
		(mid 136.663521 -265.562609)
		(end 136.387078 -265.629898)
		(width 0.088646)
		(layer "In2.Cu")
		(net "M_F_CPU1_SA_DQ<23>")
	)
	(arc
		(start 135.432546 -265.638534)
		(mid 135.229065 -265.839338)
		(end 135.149844 -266.114022)
		(width 0.088646)
		(layer "In2.Cu")
		(net "M_F_CPU1_SA_DQ<23>")
	)
	(arc
		(start 136.372346 -265.638534)
		(mid 136.185148 -265.688677)
		(end 135.99795 -265.638534)
		(width 0.088646)
		(layer "In2.Cu")
		(net "M_F_CPU1_SA_DQ<23>")
	)
	(arc
		(start 138.81735 -265.638534)
		(mid 138.543121 -265.562609)
		(end 138.266678 -265.629898)
		(width 0.088646)
		(layer "In2.Cu")
		(net "M_F_CPU1_SA_DQ<23>")
	)
	(arc
		(start 135.99795 -265.638534)
		(mid 135.723721 -265.562609)
		(end 135.447278 -265.629898)
		(width 0.088646)
		(layer "In2.Cu")
		(net "M_F_CPU1_SA_DQ<23>")
	)
	(arc
		(start 140.12545 -265.74369)
		(mid 139.945284 -265.71993)
		(end 139.77747 -265.650218)
		(width 0.088646)
		(layer "In2.Cu")
		(net "M_F_CPU1_SA_DQ<23>")
	)
	(arc
		(start 139.75715 -265.638534)
		(mid 139.482921 -265.562609)
		(end 139.206478 -265.629898)
		(width 0.088646)
		(layer "In2.Cu")
		(net "M_F_CPU1_SA_DQ<23>")
	)
	(arc
		(start 137.312146 -265.638534)
		(mid 137.124948 -265.688677)
		(end 136.93775 -265.638534)
		(width 0.088646)
		(layer "In2.Cu")
		(net "M_F_CPU1_SA_DQ<23>")
	)
	(arc
		(start 140.546074 -265.917934)
		(mid 140.35309 -265.788986)
		(end 140.12545 -265.74369)
		(width 0.088646)
		(layer "In2.Cu")
		(net "M_F_CPU1_SA_DQ<23>")
	)
	(arc
		(start 139.191746 -265.638534)
		(mid 139.004548 -265.688677)
		(end 138.81735 -265.638534)
		(width 0.088646)
		(layer "In2.Cu")
		(net "M_F_CPU1_SA_DQ<23>")
	)
	(arc
		(start 137.87755 -265.638534)
		(mid 137.603321 -265.562609)
		(end 137.326878 -265.629898)
		(width 0.088646)
		(layer "In2.Cu")
		(net "M_F_CPU1_SA_DQ<23>")
	)
	(arc
		(start 135.149844 -266.130278)
		(mid 134.80298 -266.50187)
		(end 134.405116 -266.18565)
		(width 0.088646)
		(layer "In2.Cu")
		(net "M_F_CPU1_SA_DQ<23>")
	)
	(arc
		(start 140.703808 -265.99134)
		(mid 140.625852 -265.975834)
		(end 140.55979 -265.93165)
		(width 0.088646)
		(layer "In2.Cu")
		(net "M_F_CPU1_SA_DQ<23>")
	)
	(segment
		(start 183.136286 -291.253926)
		(end 183.340248 -291.049964)
		(width 0.20066)
		(layer "F.Cu")
		(net "M_F_CPU1_SA_DQ<22>")
	)
	(segment
		(start 182.455058 -291.253926)
		(end 183.136286 -291.253926)
		(width 0.20066)
		(layer "F.Cu")
		(net "M_F_CPU1_SA_DQ<22>")
	)
	(segment
		(start 180.423058 -291.248846)
		(end 180.427884 -291.248846)
		(width 0.101854)
		(layer "F.Cu")
		(net "M_F_CPU1_SA_DQ<22>")
	)
	(segment
		(start 176.896014 -290.816538)
		(end 176.896268 -290.816792)
		(width 0.20066)
		(layer "F.Cu")
		(net "M_F_CPU1_SA_DQ<22>")
	)
	(segment
		(start 183.340248 -291.049964)
		(end 183.340248 -290.799012)
		(width 0.20066)
		(layer "F.Cu")
		(net "M_F_CPU1_SA_DQ<22>")
	)
	(segment
		(start 180.434996 -291.241734)
		(end 182.442866 -291.241734)
		(width 0.1016)
		(layer "F.Cu")
		(net "M_F_CPU1_SA_DQ<22>")
	)
	(segment
		(start 184.210452 -290.816792)
		(end 185.544714 -290.816792)
		(width 0.20066)
		(layer "F.Cu")
		(net "M_F_CPU1_SA_DQ<22>")
	)
	(segment
		(start 183.574436 -290.564824)
		(end 183.958484 -290.564824)
		(width 0.20066)
		(layer "F.Cu")
		(net "M_F_CPU1_SA_DQ<22>")
	)
	(segment
		(start 183.340248 -290.799012)
		(end 183.574436 -290.564824)
		(width 0.20066)
		(layer "F.Cu")
		(net "M_F_CPU1_SA_DQ<22>")
	)
	(segment
		(start 182.442866 -291.241734)
		(end 182.455058 -291.253926)
		(width 0.1016)
		(layer "F.Cu")
		(net "M_F_CPU1_SA_DQ<22>")
	)
	(segment
		(start 183.958484 -290.564824)
		(end 184.210452 -290.816792)
		(width 0.20066)
		(layer "F.Cu")
		(net "M_F_CPU1_SA_DQ<22>")
	)
	(segment
		(start 135.245094 -266.405868)
		(end 135.245348 -266.942062)
		(width 0.20066)
		(layer "F.Cu")
		(net "M_F_CPU1_SA_DQ<22>")
	)
	(segment
		(start 179.699158 -290.816792)
		(end 180.131212 -291.248846)
		(width 0.20066)
		(layer "F.Cu")
		(net "M_F_CPU1_SA_DQ<22>")
	)
	(segment
		(start 176.896268 -290.816792)
		(end 178.000914 -290.816792)
		(width 0.20066)
		(layer "F.Cu")
		(net "M_F_CPU1_SA_DQ<22>")
	)
	(segment
		(start 180.131212 -291.248846)
		(end 180.423058 -291.248846)
		(width 0.20066)
		(layer "F.Cu")
		(net "M_F_CPU1_SA_DQ<22>")
	)
	(segment
		(start 178.000914 -290.816792)
		(end 179.699158 -290.816792)
		(width 0.20066)
		(layer "F.Cu")
		(net "M_F_CPU1_SA_DQ<22>")
	)
	(segment
		(start 180.427884 -291.248846)
		(end 180.434996 -291.241734)
		(width 0.1016)
		(layer "F.Cu")
		(net "M_F_CPU1_SA_DQ<22>")
	)
	(segment
		(start 174.500794 -291.055298)
		(end 174.307754 -291.248338)
		(width 0.18288)
		(layer "In2.Cu")
		(net "M_F_CPU1_SA_DQ<22>")
	)
	(segment
		(start 163.882832 -282.762452)
		(end 163.461446 -282.762452)
		(width 0.18288)
		(layer "In2.Cu")
		(net "M_F_CPU1_SA_DQ<22>")
	)
	(segment
		(start 167.127682 -284.467046)
		(end 165.587426 -284.467046)
		(width 0.18288)
		(layer "In2.Cu")
		(net "M_F_CPU1_SA_DQ<22>")
	)
	(segment
		(start 158.048706 -281.007566)
		(end 152.875234 -275.834094)
		(width 0.18288)
		(layer "In2.Cu")
		(net "M_F_CPU1_SA_DQ<22>")
	)
	(segment
		(start 151.881078 -273.434048)
		(end 148.79574 -270.34871)
		(width 0.18288)
		(layer "In2.Cu")
		(net "M_F_CPU1_SA_DQ<22>")
	)
	(segment
		(start 174.7901 -290.314126)
		(end 174.500794 -290.603432)
		(width 0.18288)
		(layer "In2.Cu")
		(net "M_F_CPU1_SA_DQ<22>")
	)
	(segment
		(start 163.301426 -282.392628)
		(end 163.141406 -282.232608)
		(width 0.18288)
		(layer "In2.Cu")
		(net "M_F_CPU1_SA_DQ<22>")
	)
	(segment
		(start 143.637 -267.025628)
		(end 142.893542 -266.717526)
		(width 0.18288)
		(layer "In2.Cu")
		(net "M_F_CPU1_SA_DQ<22>")
	)
	(segment
		(start 163.301426 -282.602432)
		(end 163.301426 -282.392628)
		(width 0.18288)
		(layer "In2.Cu")
		(net "M_F_CPU1_SA_DQ<22>")
	)
	(segment
		(start 172.170598 -287.29305)
		(end 171.960032 -287.082484)
		(width 0.18288)
		(layer "In2.Cu")
		(net "M_F_CPU1_SA_DQ<22>")
	)
	(segment
		(start 164.27577 -283.841698)
		(end 164.02939 -283.595318)
		(width 0.18288)
		(layer "In2.Cu")
		(net "M_F_CPU1_SA_DQ<22>")
	)
	(segment
		(start 175.721518 -290.729924)
		(end 175.30572 -290.314126)
		(width 0.18288)
		(layer "In2.Cu")
		(net "M_F_CPU1_SA_DQ<22>")
	)
	(segment
		(start 167.845486 -283.749242)
		(end 167.127682 -284.467046)
		(width 0.18288)
		(layer "In2.Cu")
		(net "M_F_CPU1_SA_DQ<22>")
	)
	(segment
		(start 136.33704 -266.376912)
		(end 136.184894 -266.376912)
		(width 0.088646)
		(layer "In2.Cu")
		(net "M_F_CPU1_SA_DQ<22>")
	)
	(segment
		(start 168.906698 -284.53715)
		(end 168.11879 -283.749242)
		(width 0.18288)
		(layer "In2.Cu")
		(net "M_F_CPU1_SA_DQ<22>")
	)
	(segment
		(start 171.096686 -286.783272)
		(end 170.218608 -286.783272)
		(width 0.18288)
		(layer "In2.Cu")
		(net "M_F_CPU1_SA_DQ<22>")
	)
	(segment
		(start 136.467596 -266.45235)
		(end 136.33704 -266.376912)
		(width 0.088646)
		(layer "In2.Cu")
		(net "M_F_CPU1_SA_DQ<22>")
	)
	(segment
		(start 163.141406 -282.232608)
		(end 162.35045 -282.232608)
		(width 0.18288)
		(layer "In2.Cu")
		(net "M_F_CPU1_SA_DQ<22>")
	)
	(segment
		(start 171.960032 -287.082484)
		(end 171.395898 -287.082484)
		(width 0.18288)
		(layer "In2.Cu")
		(net "M_F_CPU1_SA_DQ<22>")
	)
	(segment
		(start 152.875234 -275.834094)
		(end 151.881078 -273.434048)
		(width 0.18288)
		(layer "In2.Cu")
		(net "M_F_CPU1_SA_DQ<22>")
	)
	(segment
		(start 164.146484 -283.026104)
		(end 163.882832 -282.762452)
		(width 0.18288)
		(layer "In2.Cu")
		(net "M_F_CPU1_SA_DQ<22>")
	)
	(segment
		(start 170.218608 -286.783272)
		(end 168.906698 -285.471362)
		(width 0.18288)
		(layer "In2.Cu")
		(net "M_F_CPU1_SA_DQ<22>")
	)
	(segment
		(start 164.962078 -283.841698)
		(end 164.27577 -283.841698)
		(width 0.18288)
		(layer "In2.Cu")
		(net "M_F_CPU1_SA_DQ<22>")
	)
	(segment
		(start 171.395898 -287.082484)
		(end 171.096686 -286.783272)
		(width 0.18288)
		(layer "In2.Cu")
		(net "M_F_CPU1_SA_DQ<22>")
	)
	(segment
		(start 173.599348 -291.088318)
		(end 173.599348 -290.551362)
		(width 0.18288)
		(layer "In2.Cu")
		(net "M_F_CPU1_SA_DQ<22>")
	)
	(segment
		(start 164.02939 -283.595318)
		(end 164.02939 -283.369258)
		(width 0.18288)
		(layer "In2.Cu")
		(net "M_F_CPU1_SA_DQ<22>")
	)
	(segment
		(start 173.439328 -290.391342)
		(end 172.459904 -290.391342)
		(width 0.18288)
		(layer "In2.Cu")
		(net "M_F_CPU1_SA_DQ<22>")
	)
	(segment
		(start 168.11879 -283.749242)
		(end 167.845486 -283.749242)
		(width 0.18288)
		(layer "In2.Cu")
		(net "M_F_CPU1_SA_DQ<22>")
	)
	(segment
		(start 162.35045 -282.232608)
		(end 161.909252 -281.79141)
		(width 0.18288)
		(layer "In2.Cu")
		(net "M_F_CPU1_SA_DQ<22>")
	)
	(segment
		(start 175.30572 -290.314126)
		(end 174.7901 -290.314126)
		(width 0.18288)
		(layer "In2.Cu")
		(net "M_F_CPU1_SA_DQ<22>")
	)
	(segment
		(start 160.50768 -281.007566)
		(end 158.048706 -281.007566)
		(width 0.18288)
		(layer "In2.Cu")
		(net "M_F_CPU1_SA_DQ<22>")
	)
	(segment
		(start 142.893542 -266.717526)
		(end 140.900404 -266.717526)
		(width 0.18288)
		(layer "In2.Cu")
		(net "M_F_CPU1_SA_DQ<22>")
	)
	(segment
		(start 165.587426 -284.467046)
		(end 164.962078 -283.841698)
		(width 0.18288)
		(layer "In2.Cu")
		(net "M_F_CPU1_SA_DQ<22>")
	)
	(segment
		(start 163.461446 -282.762452)
		(end 163.301426 -282.602432)
		(width 0.18288)
		(layer "In2.Cu")
		(net "M_F_CPU1_SA_DQ<22>")
	)
	(segment
		(start 140.900404 -266.717526)
		(end 140.489432 -266.717526)
		(width 0.088646)
		(layer "In2.Cu")
		(net "M_F_CPU1_SA_DQ<22>")
	)
	(segment
		(start 135.245602 -266.941808)
		(end 135.245348 -266.942062)
		(width 0.088646)
		(layer "In2.Cu")
		(net "M_F_CPU1_SA_DQ<22>")
	)
	(segment
		(start 172.170598 -290.102036)
		(end 172.170598 -287.29305)
		(width 0.18288)
		(layer "In2.Cu")
		(net "M_F_CPU1_SA_DQ<22>")
	)
	(segment
		(start 174.307754 -291.248338)
		(end 173.759368 -291.248338)
		(width 0.18288)
		(layer "In2.Cu")
		(net "M_F_CPU1_SA_DQ<22>")
	)
	(segment
		(start 146.960082 -270.34871)
		(end 143.637 -267.025628)
		(width 0.18288)
		(layer "In2.Cu")
		(net "M_F_CPU1_SA_DQ<22>")
	)
	(segment
		(start 174.500794 -290.603432)
		(end 174.500794 -291.055298)
		(width 0.18288)
		(layer "In2.Cu")
		(net "M_F_CPU1_SA_DQ<22>")
	)
	(segment
		(start 175.721518 -291.03066)
		(end 175.721518 -290.729924)
		(width 0.18288)
		(layer "In2.Cu")
		(net "M_F_CPU1_SA_DQ<22>")
	)
	(segment
		(start 173.599348 -290.551362)
		(end 173.439328 -290.391342)
		(width 0.18288)
		(layer "In2.Cu")
		(net "M_F_CPU1_SA_DQ<22>")
	)
	(segment
		(start 164.02939 -283.369258)
		(end 164.146484 -283.252164)
		(width 0.18288)
		(layer "In2.Cu")
		(net "M_F_CPU1_SA_DQ<22>")
	)
	(segment
		(start 140.489432 -266.717526)
		(end 140.148564 -266.376658)
		(width 0.088646)
		(layer "In2.Cu")
		(net "M_F_CPU1_SA_DQ<22>")
	)
	(segment
		(start 168.906698 -285.471362)
		(end 168.906698 -284.53715)
		(width 0.18288)
		(layer "In2.Cu")
		(net "M_F_CPU1_SA_DQ<22>")
	)
	(segment
		(start 135.902446 -266.452604)
		(end 135.82269 -266.498578)
		(width 0.088646)
		(layer "In2.Cu")
		(net "M_F_CPU1_SA_DQ<22>")
	)
	(segment
		(start 176.488598 -291.223954)
		(end 175.914812 -291.223954)
		(width 0.18288)
		(layer "In2.Cu")
		(net "M_F_CPU1_SA_DQ<22>")
	)
	(segment
		(start 175.914812 -291.223954)
		(end 175.721518 -291.03066)
		(width 0.18288)
		(layer "In2.Cu")
		(net "M_F_CPU1_SA_DQ<22>")
	)
	(segment
		(start 161.291524 -281.79141)
		(end 160.50768 -281.007566)
		(width 0.18288)
		(layer "In2.Cu")
		(net "M_F_CPU1_SA_DQ<22>")
	)
	(segment
		(start 172.459904 -290.391342)
		(end 172.170598 -290.102036)
		(width 0.18288)
		(layer "In2.Cu")
		(net "M_F_CPU1_SA_DQ<22>")
	)
	(segment
		(start 173.759368 -291.248338)
		(end 173.599348 -291.088318)
		(width 0.18288)
		(layer "In2.Cu")
		(net "M_F_CPU1_SA_DQ<22>")
	)
	(segment
		(start 176.896014 -290.816538)
		(end 176.488598 -291.223954)
		(width 0.18288)
		(layer "In2.Cu")
		(net "M_F_CPU1_SA_DQ<22>")
	)
	(segment
		(start 161.909252 -281.79141)
		(end 161.291524 -281.79141)
		(width 0.18288)
		(layer "In2.Cu")
		(net "M_F_CPU1_SA_DQ<22>")
	)
	(segment
		(start 148.79574 -270.34871)
		(end 146.960082 -270.34871)
		(width 0.18288)
		(layer "In2.Cu")
		(net "M_F_CPU1_SA_DQ<22>")
	)
	(segment
		(start 164.146484 -283.252164)
		(end 164.146484 -283.026104)
		(width 0.18288)
		(layer "In2.Cu")
		(net "M_F_CPU1_SA_DQ<22>")
	)
	(segment
		(start 140.148564 -266.376658)
		(end 139.944094 -266.376658)
		(width 0.088646)
		(layer "In2.Cu")
		(net "M_F_CPU1_SA_DQ<22>")
	)
	(arc
		(start 135.82269 -266.498578)
		(mid 135.519419 -266.701018)
		(end 135.245602 -266.941808)
		(width 0.088646)
		(layer "In2.Cu")
		(net "M_F_CPU1_SA_DQ<22>")
	)
	(arc
		(start 138.721592 -266.45235)
		(mid 138.534394 -266.502527)
		(end 138.347196 -266.45235)
		(width 0.088646)
		(layer "In2.Cu")
		(net "M_F_CPU1_SA_DQ<22>")
	)
	(arc
		(start 136.184894 -266.376912)
		(mid 136.038681 -266.396153)
		(end 135.902446 -266.452604)
		(width 0.088646)
		(layer "In2.Cu")
		(net "M_F_CPU1_SA_DQ<22>")
	)
	(arc
		(start 136.841992 -266.45235)
		(mid 136.654794 -266.502527)
		(end 136.467596 -266.45235)
		(width 0.088646)
		(layer "In2.Cu")
		(net "M_F_CPU1_SA_DQ<22>")
	)
	(arc
		(start 139.661392 -266.45235)
		(mid 139.474194 -266.502527)
		(end 139.286996 -266.45235)
		(width 0.088646)
		(layer "In2.Cu")
		(net "M_F_CPU1_SA_DQ<22>")
	)
	(arc
		(start 138.347196 -266.45235)
		(mid 138.064494 -266.376574)
		(end 137.781792 -266.45235)
		(width 0.088646)
		(layer "In2.Cu")
		(net "M_F_CPU1_SA_DQ<22>")
	)
	(arc
		(start 139.286996 -266.45235)
		(mid 139.004294 -266.376574)
		(end 138.721592 -266.45235)
		(width 0.088646)
		(layer "In2.Cu")
		(net "M_F_CPU1_SA_DQ<22>")
	)
	(arc
		(start 137.781792 -266.45235)
		(mid 137.594594 -266.502527)
		(end 137.407396 -266.45235)
		(width 0.088646)
		(layer "In2.Cu")
		(net "M_F_CPU1_SA_DQ<22>")
	)
	(arc
		(start 137.407396 -266.45235)
		(mid 137.124694 -266.376574)
		(end 136.841992 -266.45235)
		(width 0.088646)
		(layer "In2.Cu")
		(net "M_F_CPU1_SA_DQ<22>")
	)
	(arc
		(start 139.944094 -266.376658)
		(mid 139.797771 -266.39592)
		(end 139.661392 -266.45235)
		(width 0.088646)
		(layer "In2.Cu")
		(net "M_F_CPU1_SA_DQ<22>")
	)
	(segment
		(start 176.451514 -289.541712)
		(end 176.333404 -289.659822)
		(width 0.20066)
		(layer "F.Cu")
		(net "M_F_CPU1_SA_DQ<21>")
	)
	(segment
		(start 179.004976 -289.541712)
		(end 176.816258 -289.541712)
		(width 0.1016)
		(layer "F.Cu")
		(net "M_F_CPU1_SA_DQ<21>")
	)
	(segment
		(start 133.835648 -265.592306)
		(end 133.835648 -266.127738)
		(width 0.20066)
		(layer "F.Cu")
		(net "M_F_CPU1_SA_DQ<21>")
	)
	(segment
		(start 179.421282 -289.535362)
		(end 179.011326 -289.535362)
		(width 0.20066)
		(layer "F.Cu")
		(net "M_F_CPU1_SA_DQ<21>")
	)
	(segment
		(start 181.444646 -289.966654)
		(end 181.444392 -289.966908)
		(width 0.20066)
		(layer "F.Cu")
		(net "M_F_CPU1_SA_DQ<21>")
	)
	(segment
		(start 176.333404 -289.659822)
		(end 176.333404 -290.02736)
		(width 0.20066)
		(layer "F.Cu")
		(net "M_F_CPU1_SA_DQ<21>")
	)
	(segment
		(start 176.145444 -290.21532)
		(end 175.67021 -290.21532)
		(width 0.20066)
		(layer "F.Cu")
		(net "M_F_CPU1_SA_DQ<21>")
	)
	(segment
		(start 176.333404 -290.02736)
		(end 176.145444 -290.21532)
		(width 0.20066)
		(layer "F.Cu")
		(net "M_F_CPU1_SA_DQ<21>")
	)
	(segment
		(start 176.816258 -289.541712)
		(end 176.796192 -289.541712)
		(width 0.101854)
		(layer "F.Cu")
		(net "M_F_CPU1_SA_DQ<21>")
	)
	(segment
		(start 133.835394 -266.127992)
		(end 133.835394 -266.128246)
		(width 0.20066)
		(layer "F.Cu")
		(net "M_F_CPU1_SA_DQ<21>")
	)
	(segment
		(start 173.900846 -289.966654)
		(end 172.795946 -289.966654)
		(width 0.20066)
		(layer "F.Cu")
		(net "M_F_CPU1_SA_DQ<21>")
	)
	(segment
		(start 133.835648 -266.127738)
		(end 133.835394 -266.127992)
		(width 0.20066)
		(layer "F.Cu")
		(net "M_F_CPU1_SA_DQ<21>")
	)
	(segment
		(start 175.421544 -289.966654)
		(end 173.900846 -289.966654)
		(width 0.20066)
		(layer "F.Cu")
		(net "M_F_CPU1_SA_DQ<21>")
	)
	(segment
		(start 176.796192 -289.541712)
		(end 176.451514 -289.541712)
		(width 0.20066)
		(layer "F.Cu")
		(net "M_F_CPU1_SA_DQ<21>")
	)
	(segment
		(start 181.444392 -289.966908)
		(end 179.852828 -289.966908)
		(width 0.20066)
		(layer "F.Cu")
		(net "M_F_CPU1_SA_DQ<21>")
	)
	(segment
		(start 179.011326 -289.535362)
		(end 179.004976 -289.541712)
		(width 0.1016)
		(layer "F.Cu")
		(net "M_F_CPU1_SA_DQ<21>")
	)
	(segment
		(start 179.852828 -289.966908)
		(end 179.421282 -289.535362)
		(width 0.20066)
		(layer "F.Cu")
		(net "M_F_CPU1_SA_DQ<21>")
	)
	(segment
		(start 175.67021 -290.21532)
		(end 175.421544 -289.966654)
		(width 0.20066)
		(layer "F.Cu")
		(net "M_F_CPU1_SA_DQ<21>")
	)
	(segment
		(start 172.169328 -286.14243)
		(end 170.830494 -284.803596)
		(width 0.18288)
		(layer "In2.Cu")
		(net "M_F_CPU1_SA_DQ<21>")
	)
	(segment
		(start 164.4396 -281.177238)
		(end 163.947856 -281.177238)
		(width 0.18288)
		(layer "In2.Cu")
		(net "M_F_CPU1_SA_DQ<21>")
	)
	(segment
		(start 172.915326 -289.678618)
		(end 172.961046 -289.568382)
		(width 0.18288)
		(layer "In2.Cu")
		(net "M_F_CPU1_SA_DQ<21>")
	)
	(segment
		(start 173.505114 -285.94431)
		(end 173.306994 -286.14243)
		(width 0.18288)
		(layer "In2.Cu")
		(net "M_F_CPU1_SA_DQ<21>")
	)
	(segment
		(start 173.306994 -286.14243)
		(end 172.169328 -286.14243)
		(width 0.18288)
		(layer "In2.Cu")
		(net "M_F_CPU1_SA_DQ<21>")
	)
	(segment
		(start 158.272734 -279.696672)
		(end 157.870652 -279.29459)
		(width 0.18288)
		(layer "In2.Cu")
		(net "M_F_CPU1_SA_DQ<21>")
	)
	(segment
		(start 134.148322 -266.127992)
		(end 133.835648 -266.127992)
		(width 0.088646)
		(layer "In2.Cu")
		(net "M_F_CPU1_SA_DQ<21>")
	)
	(segment
		(start 143.823944 -266.723876)
		(end 142.932658 -266.35456)
		(width 0.18288)
		(layer "In2.Cu")
		(net "M_F_CPU1_SA_DQ<21>")
	)
	(segment
		(start 162.385248 -280.705052)
		(end 161.913062 -281.177238)
		(width 0.18288)
		(layer "In2.Cu")
		(net "M_F_CPU1_SA_DQ<21>")
	)
	(segment
		(start 161.401506 -281.177238)
		(end 160.42894 -280.204672)
		(width 0.18288)
		(layer "In2.Cu")
		(net "M_F_CPU1_SA_DQ<21>")
	)
	(segment
		(start 164.63264 -281.370278)
		(end 164.4396 -281.177238)
		(width 0.18288)
		(layer "In2.Cu")
		(net "M_F_CPU1_SA_DQ<21>")
	)
	(segment
		(start 165.077394 -282.716986)
		(end 164.63264 -282.272232)
		(width 0.18288)
		(layer "In2.Cu")
		(net "M_F_CPU1_SA_DQ<21>")
	)
	(segment
		(start 159.723328 -280.204672)
		(end 159.215328 -279.696672)
		(width 0.18288)
		(layer "In2.Cu")
		(net "M_F_CPU1_SA_DQ<21>")
	)
	(segment
		(start 135.057896 -266.617704)
		(end 135.052054 -266.621006)
		(width 0.088646)
		(layer "In2.Cu")
		(net "M_F_CPU1_SA_DQ<21>")
	)
	(segment
		(start 164.63264 -282.272232)
		(end 164.63264 -281.370278)
		(width 0.18288)
		(layer "In2.Cu")
		(net "M_F_CPU1_SA_DQ<21>")
	)
	(segment
		(start 170.830494 -284.803596)
		(end 169.915078 -284.803596)
		(width 0.18288)
		(layer "In2.Cu")
		(net "M_F_CPU1_SA_DQ<21>")
	)
	(segment
		(start 135.527796 -265.803888)
		(end 135.518906 -265.808968)
		(width 0.088646)
		(layer "In2.Cu")
		(net "M_F_CPU1_SA_DQ<21>")
	)
	(segment
		(start 142.932658 -266.35456)
		(end 140.900404 -266.35456)
		(width 0.18288)
		(layer "In2.Cu")
		(net "M_F_CPU1_SA_DQ<21>")
	)
	(segment
		(start 133.835648 -266.127992)
		(end 133.835394 -266.128246)
		(width 0.088646)
		(layer "In2.Cu")
		(net "M_F_CPU1_SA_DQ<21>")
	)
	(segment
		(start 163.947856 -281.177238)
		(end 163.47567 -280.705052)
		(width 0.18288)
		(layer "In2.Cu")
		(net "M_F_CPU1_SA_DQ<21>")
	)
	(segment
		(start 139.286996 -265.803888)
		(end 139.272264 -265.812524)
		(width 0.088646)
		(layer "In2.Cu")
		(net "M_F_CPU1_SA_DQ<21>")
	)
	(segment
		(start 160.42894 -280.204672)
		(end 159.723328 -280.204672)
		(width 0.18288)
		(layer "In2.Cu")
		(net "M_F_CPU1_SA_DQ<21>")
	)
	(segment
		(start 153.306272 -275.546566)
		(end 152.312116 -273.14652)
		(width 0.18288)
		(layer "In2.Cu")
		(net "M_F_CPU1_SA_DQ<21>")
	)
	(segment
		(start 173.562518 -288.96691)
		(end 174.494698 -288.96691)
		(width 0.18288)
		(layer "In2.Cu")
		(net "M_F_CPU1_SA_DQ<21>")
	)
	(segment
		(start 134.214108 -266.193778)
		(end 134.148322 -266.127992)
		(width 0.088646)
		(layer "In2.Cu")
		(net "M_F_CPU1_SA_DQ<21>")
	)
	(segment
		(start 163.47567 -280.705052)
		(end 162.385248 -280.705052)
		(width 0.18288)
		(layer "In2.Cu")
		(net "M_F_CPU1_SA_DQ<21>")
	)
	(segment
		(start 175.437038 -288.02457)
		(end 175.437038 -286.81045)
		(width 0.18288)
		(layer "In2.Cu")
		(net "M_F_CPU1_SA_DQ<21>")
	)
	(segment
		(start 137.407396 -265.803888)
		(end 137.392664 -265.812524)
		(width 0.088646)
		(layer "In2.Cu")
		(net "M_F_CPU1_SA_DQ<21>")
	)
	(segment
		(start 138.347196 -265.803888)
		(end 138.332464 -265.812524)
		(width 0.088646)
		(layer "In2.Cu")
		(net "M_F_CPU1_SA_DQ<21>")
	)
	(segment
		(start 152.312116 -273.14652)
		(end 148.998686 -269.83309)
		(width 0.18288)
		(layer "In2.Cu")
		(net "M_F_CPU1_SA_DQ<21>")
	)
	(segment
		(start 140.701268 -266.35456)
		(end 140.621004 -266.274296)
		(width 0.088646)
		(layer "In2.Cu")
		(net "M_F_CPU1_SA_DQ<21>")
	)
	(segment
		(start 135.340344 -266.128246)
		(end 135.340344 -266.135358)
		(width 0.088646)
		(layer "In2.Cu")
		(net "M_F_CPU1_SA_DQ<21>")
	)
	(segment
		(start 136.467596 -265.803888)
		(end 136.452864 -265.812524)
		(width 0.088646)
		(layer "In2.Cu")
		(net "M_F_CPU1_SA_DQ<21>")
	)
	(segment
		(start 172.961046 -289.568382)
		(end 173.562518 -288.96691)
		(width 0.18288)
		(layer "In2.Cu")
		(net "M_F_CPU1_SA_DQ<21>")
	)
	(segment
		(start 169.915078 -284.803596)
		(end 167.828468 -282.716986)
		(width 0.18288)
		(layer "In2.Cu")
		(net "M_F_CPU1_SA_DQ<21>")
	)
	(segment
		(start 140.900404 -266.35456)
		(end 140.701268 -266.35456)
		(width 0.088646)
		(layer "In2.Cu")
		(net "M_F_CPU1_SA_DQ<21>")
	)
	(segment
		(start 148.998686 -269.83309)
		(end 146.933158 -269.83309)
		(width 0.18288)
		(layer "In2.Cu")
		(net "M_F_CPU1_SA_DQ<21>")
	)
	(segment
		(start 161.913062 -281.177238)
		(end 161.401506 -281.177238)
		(width 0.18288)
		(layer "In2.Cu")
		(net "M_F_CPU1_SA_DQ<21>")
	)
	(segment
		(start 146.933158 -269.83309)
		(end 143.823944 -266.723876)
		(width 0.18288)
		(layer "In2.Cu")
		(net "M_F_CPU1_SA_DQ<21>")
	)
	(segment
		(start 157.870652 -279.29459)
		(end 157.054296 -279.29459)
		(width 0.18288)
		(layer "In2.Cu")
		(net "M_F_CPU1_SA_DQ<21>")
	)
	(segment
		(start 157.054296 -279.29459)
		(end 153.306272 -275.546566)
		(width 0.18288)
		(layer "In2.Cu")
		(net "M_F_CPU1_SA_DQ<21>")
	)
	(segment
		(start 175.437038 -286.81045)
		(end 174.570898 -285.94431)
		(width 0.18288)
		(layer "In2.Cu")
		(net "M_F_CPU1_SA_DQ<21>")
	)
	(segment
		(start 159.215328 -279.696672)
		(end 158.272734 -279.696672)
		(width 0.18288)
		(layer "In2.Cu")
		(net "M_F_CPU1_SA_DQ<21>")
	)
	(segment
		(start 174.494698 -288.96691)
		(end 175.437038 -288.02457)
		(width 0.18288)
		(layer "In2.Cu")
		(net "M_F_CPU1_SA_DQ<21>")
	)
	(segment
		(start 139.733528 -265.845544)
		(end 139.661392 -265.803888)
		(width 0.088646)
		(layer "In2.Cu")
		(net "M_F_CPU1_SA_DQ<21>")
	)
	(segment
		(start 167.828468 -282.716986)
		(end 165.077394 -282.716986)
		(width 0.18288)
		(layer "In2.Cu")
		(net "M_F_CPU1_SA_DQ<21>")
	)
	(segment
		(start 140.621004 -266.274296)
		(end 140.43406 -266.087098)
		(width 0.088646)
		(layer "In2.Cu")
		(net "M_F_CPU1_SA_DQ<21>")
	)
	(segment
		(start 172.795946 -289.966654)
		(end 172.915326 -289.678618)
		(width 0.18288)
		(layer "In2.Cu")
		(net "M_F_CPU1_SA_DQ<21>")
	)
	(segment
		(start 174.570898 -285.94431)
		(end 173.505114 -285.94431)
		(width 0.18288)
		(layer "In2.Cu")
		(net "M_F_CPU1_SA_DQ<21>")
	)
	(arc
		(start 135.052054 -266.621006)
		(mid 134.771919 -266.693289)
		(end 134.492746 -266.61745)
		(width 0.088646)
		(layer "In2.Cu")
		(net "M_F_CPU1_SA_DQ<21>")
	)
	(arc
		(start 138.721592 -265.803888)
		(mid 138.534394 -265.753745)
		(end 138.347196 -265.803888)
		(width 0.088646)
		(layer "In2.Cu")
		(net "M_F_CPU1_SA_DQ<21>")
	)
	(arc
		(start 139.272264 -265.812524)
		(mid 138.995823 -265.87969)
		(end 138.721592 -265.803888)
		(width 0.088646)
		(layer "In2.Cu")
		(net "M_F_CPU1_SA_DQ<21>")
	)
	(arc
		(start 135.340344 -266.135358)
		(mid 135.262904 -266.413875)
		(end 135.057896 -266.617704)
		(width 0.088646)
		(layer "In2.Cu")
		(net "M_F_CPU1_SA_DQ<21>")
	)
	(arc
		(start 134.492746 -266.61745)
		(mid 134.303223 -266.438625)
		(end 134.214108 -266.193778)
		(width 0.088646)
		(layer "In2.Cu")
		(net "M_F_CPU1_SA_DQ<21>")
	)
	(arc
		(start 137.392664 -265.812524)
		(mid 137.116223 -265.87969)
		(end 136.841992 -265.803888)
		(width 0.088646)
		(layer "In2.Cu")
		(net "M_F_CPU1_SA_DQ<21>")
	)
	(arc
		(start 135.902192 -265.803888)
		(mid 135.714994 -265.753745)
		(end 135.527796 -265.803888)
		(width 0.088646)
		(layer "In2.Cu")
		(net "M_F_CPU1_SA_DQ<21>")
	)
	(arc
		(start 136.452864 -265.812524)
		(mid 136.176423 -265.87969)
		(end 135.902192 -265.803888)
		(width 0.088646)
		(layer "In2.Cu")
		(net "M_F_CPU1_SA_DQ<21>")
	)
	(arc
		(start 135.518906 -265.808968)
		(mid 135.387992 -265.945328)
		(end 135.340344 -266.128246)
		(width 0.088646)
		(layer "In2.Cu")
		(net "M_F_CPU1_SA_DQ<21>")
	)
	(arc
		(start 138.332464 -265.812524)
		(mid 138.056023 -265.87969)
		(end 137.781792 -265.803888)
		(width 0.088646)
		(layer "In2.Cu")
		(net "M_F_CPU1_SA_DQ<21>")
	)
	(arc
		(start 139.661392 -265.803888)
		(mid 139.474194 -265.753745)
		(end 139.286996 -265.803888)
		(width 0.088646)
		(layer "In2.Cu")
		(net "M_F_CPU1_SA_DQ<21>")
	)
	(arc
		(start 136.841992 -265.803888)
		(mid 136.654794 -265.753745)
		(end 136.467596 -265.803888)
		(width 0.088646)
		(layer "In2.Cu")
		(net "M_F_CPU1_SA_DQ<21>")
	)
	(arc
		(start 140.06449 -265.93419)
		(mid 139.89318 -265.911638)
		(end 139.733528 -265.845544)
		(width 0.088646)
		(layer "In2.Cu")
		(net "M_F_CPU1_SA_DQ<21>")
	)
	(arc
		(start 137.781792 -265.803888)
		(mid 137.594594 -265.753745)
		(end 137.407396 -265.803888)
		(width 0.088646)
		(layer "In2.Cu")
		(net "M_F_CPU1_SA_DQ<21>")
	)
	(arc
		(start 140.43406 -266.087098)
		(mid 140.264485 -265.973885)
		(end 140.06449 -265.93419)
		(width 0.088646)
		(layer "In2.Cu")
		(net "M_F_CPU1_SA_DQ<21>")
	)
	(segment
		(start 181.444646 -291.666676)
		(end 181.444392 -291.66693)
		(width 0.20066)
		(layer "F.Cu")
		(net "M_F_CPU1_SA_DQ<20>")
	)
	(segment
		(start 176.796192 -291.241734)
		(end 176.451514 -291.241734)
		(width 0.20066)
		(layer "F.Cu")
		(net "M_F_CPU1_SA_DQ<20>")
	)
	(segment
		(start 179.421282 -291.235384)
		(end 179.011326 -291.235384)
		(width 0.20066)
		(layer "F.Cu")
		(net "M_F_CPU1_SA_DQ<20>")
	)
	(segment
		(start 179.852828 -291.66693)
		(end 179.421282 -291.235384)
		(width 0.20066)
		(layer "F.Cu")
		(net "M_F_CPU1_SA_DQ<20>")
	)
	(segment
		(start 179.004976 -291.241734)
		(end 176.843182 -291.241734)
		(width 0.1016)
		(layer "F.Cu")
		(net "M_F_CPU1_SA_DQ<20>")
	)
	(segment
		(start 179.011326 -291.235384)
		(end 179.004976 -291.241734)
		(width 0.1016)
		(layer "F.Cu")
		(net "M_F_CPU1_SA_DQ<20>")
	)
	(segment
		(start 173.900846 -291.666676)
		(end 172.795946 -291.666676)
		(width 0.20066)
		(layer "F.Cu")
		(net "M_F_CPU1_SA_DQ<20>")
	)
	(segment
		(start 175.421544 -291.666676)
		(end 173.900846 -291.666676)
		(width 0.20066)
		(layer "F.Cu")
		(net "M_F_CPU1_SA_DQ<20>")
	)
	(segment
		(start 176.843182 -291.241734)
		(end 176.796192 -291.241734)
		(width 0.101854)
		(layer "F.Cu")
		(net "M_F_CPU1_SA_DQ<20>")
	)
	(segment
		(start 176.333404 -291.727382)
		(end 176.145444 -291.915342)
		(width 0.20066)
		(layer "F.Cu")
		(net "M_F_CPU1_SA_DQ<20>")
	)
	(segment
		(start 176.451514 -291.241734)
		(end 176.333404 -291.359844)
		(width 0.20066)
		(layer "F.Cu")
		(net "M_F_CPU1_SA_DQ<20>")
	)
	(segment
		(start 133.365494 -266.405868)
		(end 133.365494 -266.941808)
		(width 0.20066)
		(layer "F.Cu")
		(net "M_F_CPU1_SA_DQ<20>")
	)
	(segment
		(start 176.145444 -291.915342)
		(end 175.67021 -291.915342)
		(width 0.20066)
		(layer "F.Cu")
		(net "M_F_CPU1_SA_DQ<20>")
	)
	(segment
		(start 175.67021 -291.915342)
		(end 175.421544 -291.666676)
		(width 0.20066)
		(layer "F.Cu")
		(net "M_F_CPU1_SA_DQ<20>")
	)
	(segment
		(start 176.333404 -291.359844)
		(end 176.333404 -291.727382)
		(width 0.20066)
		(layer "F.Cu")
		(net "M_F_CPU1_SA_DQ<20>")
	)
	(segment
		(start 181.444392 -291.66693)
		(end 179.852828 -291.66693)
		(width 0.20066)
		(layer "F.Cu")
		(net "M_F_CPU1_SA_DQ<20>")
	)
	(segment
		(start 161.49066 -283.392626)
		(end 161.162238 -283.721048)
		(width 0.18288)
		(layer "In2.Cu")
		(net "M_F_CPU1_SA_DQ<20>")
	)
	(segment
		(start 171.478702 -290.9824)
		(end 171.478702 -290.570412)
		(width 0.18288)
		(layer "In2.Cu")
		(net "M_F_CPU1_SA_DQ<20>")
	)
	(segment
		(start 135.446008 -267.2588)
		(end 135.415528 -267.276072)
		(width 0.088646)
		(layer "In2.Cu")
		(net "M_F_CPU1_SA_DQ<20>")
	)
	(segment
		(start 171.478702 -290.570412)
		(end 171.12361 -290.21532)
		(width 0.18288)
		(layer "In2.Cu")
		(net "M_F_CPU1_SA_DQ<20>")
	)
	(segment
		(start 171.12361 -289.787838)
		(end 171.454318 -289.45713)
		(width 0.18288)
		(layer "In2.Cu")
		(net "M_F_CPU1_SA_DQ<20>")
	)
	(segment
		(start 135.201152 -267.327126)
		(end 134.32282 -267.327126)
		(width 0.088646)
		(layer "In2.Cu")
		(net "M_F_CPU1_SA_DQ<20>")
	)
	(segment
		(start 146.979386 -270.85671)
		(end 143.484092 -267.361416)
		(width 0.18288)
		(layer "In2.Cu")
		(net "M_F_CPU1_SA_DQ<20>")
	)
	(segment
		(start 162.526218 -285.062676)
		(end 162.526218 -284.84195)
		(width 0.18288)
		(layer "In2.Cu")
		(net "M_F_CPU1_SA_DQ<20>")
	)
	(segment
		(start 133.365748 -266.942062)
		(end 133.365494 -266.941808)
		(width 0.088646)
		(layer "In2.Cu")
		(net "M_F_CPU1_SA_DQ<20>")
	)
	(segment
		(start 162.526218 -284.84195)
		(end 161.949638 -284.26537)
		(width 0.18288)
		(layer "In2.Cu")
		(net "M_F_CPU1_SA_DQ<20>")
	)
	(segment
		(start 157.946598 -281.906726)
		(end 157.508448 -281.906726)
		(width 0.18288)
		(layer "In2.Cu")
		(net "M_F_CPU1_SA_DQ<20>")
	)
	(segment
		(start 171.454318 -288.79165)
		(end 170.867578 -288.20491)
		(width 0.18288)
		(layer "In2.Cu")
		(net "M_F_CPU1_SA_DQ<20>")
	)
	(segment
		(start 163.121848 -285.310326)
		(end 162.773868 -285.310326)
		(width 0.18288)
		(layer "In2.Cu")
		(net "M_F_CPU1_SA_DQ<20>")
	)
	(segment
		(start 168.353994 -285.109666)
		(end 168.086278 -284.84195)
		(width 0.18288)
		(layer "In2.Cu")
		(net "M_F_CPU1_SA_DQ<20>")
	)
	(segment
		(start 142.764002 -267.062966)
		(end 140.900404 -267.062966)
		(width 0.18288)
		(layer "In2.Cu")
		(net "M_F_CPU1_SA_DQ<20>")
	)
	(segment
		(start 159.341058 -281.52217)
		(end 158.331154 -281.52217)
		(width 0.18288)
		(layer "In2.Cu")
		(net "M_F_CPU1_SA_DQ<20>")
	)
	(segment
		(start 160.683194 -281.906726)
		(end 159.725614 -281.906726)
		(width 0.18288)
		(layer "In2.Cu")
		(net "M_F_CPU1_SA_DQ<20>")
	)
	(segment
		(start 169.958258 -288.20491)
		(end 169.308018 -287.55467)
		(width 0.18288)
		(layer "In2.Cu")
		(net "M_F_CPU1_SA_DQ<20>")
	)
	(segment
		(start 158.331154 -281.52217)
		(end 157.946598 -281.906726)
		(width 0.18288)
		(layer "In2.Cu")
		(net "M_F_CPU1_SA_DQ<20>")
	)
	(segment
		(start 167.260778 -285.24073)
		(end 165.295326 -285.24073)
		(width 0.18288)
		(layer "In2.Cu")
		(net "M_F_CPU1_SA_DQ<20>")
	)
	(segment
		(start 159.725614 -281.906726)
		(end 159.341058 -281.52217)
		(width 0.18288)
		(layer "In2.Cu")
		(net "M_F_CPU1_SA_DQ<20>")
	)
	(segment
		(start 172.330364 -291.201094)
		(end 171.697396 -291.201094)
		(width 0.18288)
		(layer "In2.Cu")
		(net "M_F_CPU1_SA_DQ<20>")
	)
	(segment
		(start 172.795946 -291.666676)
		(end 172.330364 -291.201094)
		(width 0.18288)
		(layer "In2.Cu")
		(net "M_F_CPU1_SA_DQ<20>")
	)
	(segment
		(start 161.11728 -282.340812)
		(end 160.683194 -281.906726)
		(width 0.18288)
		(layer "In2.Cu")
		(net "M_F_CPU1_SA_DQ<20>")
	)
	(segment
		(start 171.454318 -289.45713)
		(end 171.454318 -288.79165)
		(width 0.18288)
		(layer "In2.Cu")
		(net "M_F_CPU1_SA_DQ<20>")
	)
	(segment
		(start 143.484092 -267.361416)
		(end 142.764002 -267.062966)
		(width 0.18288)
		(layer "In2.Cu")
		(net "M_F_CPU1_SA_DQ<20>")
	)
	(segment
		(start 156.710634 -280.388314)
		(end 152.44445 -276.12213)
		(width 0.18288)
		(layer "In2.Cu")
		(net "M_F_CPU1_SA_DQ<20>")
	)
	(segment
		(start 161.162238 -283.721048)
		(end 160.889442 -283.721048)
		(width 0.18288)
		(layer "In2.Cu")
		(net "M_F_CPU1_SA_DQ<20>")
	)
	(segment
		(start 136.372092 -266.617704)
		(end 136.28497 -266.567412)
		(width 0.088646)
		(layer "In2.Cu")
		(net "M_F_CPU1_SA_DQ<20>")
	)
	(segment
		(start 168.8084 -286.131)
		(end 168.353994 -285.676594)
		(width 0.18288)
		(layer "In2.Cu")
		(net "M_F_CPU1_SA_DQ<20>")
	)
	(segment
		(start 157.508448 -281.906726)
		(end 157.220412 -281.61869)
		(width 0.18288)
		(layer "In2.Cu")
		(net "M_F_CPU1_SA_DQ<20>")
	)
	(segment
		(start 167.659558 -284.84195)
		(end 167.260778 -285.24073)
		(width 0.18288)
		(layer "In2.Cu")
		(net "M_F_CPU1_SA_DQ<20>")
	)
	(segment
		(start 160.889442 -283.721048)
		(end 160.664652 -283.496258)
		(width 0.18288)
		(layer "In2.Cu")
		(net "M_F_CPU1_SA_DQ<20>")
	)
	(segment
		(start 161.738564 -283.392626)
		(end 161.49066 -283.392626)
		(width 0.18288)
		(layer "In2.Cu")
		(net "M_F_CPU1_SA_DQ<20>")
	)
	(segment
		(start 165.295326 -285.24073)
		(end 164.461698 -284.407102)
		(width 0.18288)
		(layer "In2.Cu")
		(net "M_F_CPU1_SA_DQ<20>")
	)
	(segment
		(start 161.949638 -284.26537)
		(end 161.949638 -283.6037)
		(width 0.18288)
		(layer "In2.Cu")
		(net "M_F_CPU1_SA_DQ<20>")
	)
	(segment
		(start 157.220412 -281.61869)
		(end 156.710634 -280.388314)
		(width 0.18288)
		(layer "In2.Cu")
		(net "M_F_CPU1_SA_DQ<20>")
	)
	(segment
		(start 140.565632 -267.062966)
		(end 140.06957 -266.566904)
		(width 0.088646)
		(layer "In2.Cu")
		(net "M_F_CPU1_SA_DQ<20>")
	)
	(segment
		(start 140.06957 -266.566904)
		(end 139.944094 -266.566904)
		(width 0.088646)
		(layer "In2.Cu")
		(net "M_F_CPU1_SA_DQ<20>")
	)
	(segment
		(start 169.308018 -287.214056)
		(end 168.8084 -286.714438)
		(width 0.18288)
		(layer "In2.Cu")
		(net "M_F_CPU1_SA_DQ<20>")
	)
	(segment
		(start 171.12361 -290.21532)
		(end 171.12361 -289.787838)
		(width 0.18288)
		(layer "In2.Cu")
		(net "M_F_CPU1_SA_DQ<20>")
	)
	(segment
		(start 168.8084 -286.714438)
		(end 168.8084 -286.131)
		(width 0.18288)
		(layer "In2.Cu")
		(net "M_F_CPU1_SA_DQ<20>")
	)
	(segment
		(start 160.664652 -283.223716)
		(end 161.11728 -282.771088)
		(width 0.18288)
		(layer "In2.Cu")
		(net "M_F_CPU1_SA_DQ<20>")
	)
	(segment
		(start 134.118096 -267.266166)
		(end 133.736842 -267.042646)
		(width 0.088646)
		(layer "In2.Cu")
		(net "M_F_CPU1_SA_DQ<20>")
	)
	(segment
		(start 168.353994 -285.676594)
		(end 168.353994 -285.109666)
		(width 0.18288)
		(layer "In2.Cu")
		(net "M_F_CPU1_SA_DQ<20>")
	)
	(segment
		(start 160.664652 -283.496258)
		(end 160.664652 -283.223716)
		(width 0.18288)
		(layer "In2.Cu")
		(net "M_F_CPU1_SA_DQ<20>")
	)
	(segment
		(start 170.867578 -288.20491)
		(end 169.958258 -288.20491)
		(width 0.18288)
		(layer "In2.Cu")
		(net "M_F_CPU1_SA_DQ<20>")
	)
	(segment
		(start 135.674862 -267.052044)
		(end 135.554466 -267.17244)
		(width 0.088646)
		(layer "In2.Cu")
		(net "M_F_CPU1_SA_DQ<20>")
	)
	(segment
		(start 169.308018 -287.55467)
		(end 169.308018 -287.214056)
		(width 0.18288)
		(layer "In2.Cu")
		(net "M_F_CPU1_SA_DQ<20>")
	)
	(segment
		(start 136.28497 -266.567412)
		(end 136.184894 -266.567412)
		(width 0.088646)
		(layer "In2.Cu")
		(net "M_F_CPU1_SA_DQ<20>")
	)
	(segment
		(start 168.086278 -284.84195)
		(end 167.659558 -284.84195)
		(width 0.18288)
		(layer "In2.Cu")
		(net "M_F_CPU1_SA_DQ<20>")
	)
	(segment
		(start 163.281868 -284.567122)
		(end 163.281868 -285.150306)
		(width 0.18288)
		(layer "In2.Cu")
		(net "M_F_CPU1_SA_DQ<20>")
	)
	(segment
		(start 161.949638 -283.6037)
		(end 161.738564 -283.392626)
		(width 0.18288)
		(layer "In2.Cu")
		(net "M_F_CPU1_SA_DQ<20>")
	)
	(segment
		(start 148.58492 -270.85671)
		(end 146.979386 -270.85671)
		(width 0.18288)
		(layer "In2.Cu")
		(net "M_F_CPU1_SA_DQ<20>")
	)
	(segment
		(start 162.773868 -285.310326)
		(end 162.526218 -285.062676)
		(width 0.18288)
		(layer "In2.Cu")
		(net "M_F_CPU1_SA_DQ<20>")
	)
	(segment
		(start 164.461698 -284.407102)
		(end 163.441888 -284.407102)
		(width 0.18288)
		(layer "In2.Cu")
		(net "M_F_CPU1_SA_DQ<20>")
	)
	(segment
		(start 163.441888 -284.407102)
		(end 163.281868 -284.567122)
		(width 0.18288)
		(layer "In2.Cu")
		(net "M_F_CPU1_SA_DQ<20>")
	)
	(segment
		(start 152.44445 -276.12213)
		(end 151.45004 -273.72183)
		(width 0.18288)
		(layer "In2.Cu")
		(net "M_F_CPU1_SA_DQ<20>")
	)
	(segment
		(start 151.45004 -273.72183)
		(end 148.58492 -270.85671)
		(width 0.18288)
		(layer "In2.Cu")
		(net "M_F_CPU1_SA_DQ<20>")
	)
	(segment
		(start 163.281868 -285.150306)
		(end 163.121848 -285.310326)
		(width 0.18288)
		(layer "In2.Cu")
		(net "M_F_CPU1_SA_DQ<20>")
	)
	(segment
		(start 161.11728 -282.771088)
		(end 161.11728 -282.340812)
		(width 0.18288)
		(layer "In2.Cu")
		(net "M_F_CPU1_SA_DQ<20>")
	)
	(segment
		(start 171.697396 -291.201094)
		(end 171.478702 -290.9824)
		(width 0.18288)
		(layer "In2.Cu")
		(net "M_F_CPU1_SA_DQ<20>")
	)
	(segment
		(start 140.900404 -267.062966)
		(end 140.565632 -267.062966)
		(width 0.088646)
		(layer "In2.Cu")
		(net "M_F_CPU1_SA_DQ<20>")
	)
	(arc
		(start 138.251692 -266.617704)
		(mid 138.064494 -266.567527)
		(end 137.877296 -266.617704)
		(width 0.088646)
		(layer "In2.Cu")
		(net "M_F_CPU1_SA_DQ<20>")
	)
	(arc
		(start 134.234428 -267.315442)
		(mid 134.174639 -267.294633)
		(end 134.118096 -267.266166)
		(width 0.088646)
		(layer "In2.Cu")
		(net "M_F_CPU1_SA_DQ<20>")
	)
	(arc
		(start 139.944094 -266.566904)
		(mid 139.847155 -266.579994)
		(end 139.756896 -266.617704)
		(width 0.088646)
		(layer "In2.Cu")
		(net "M_F_CPU1_SA_DQ<20>")
	)
	(arc
		(start 135.415528 -267.276072)
		(mid 135.311336 -267.314176)
		(end 135.201152 -267.327126)
		(width 0.088646)
		(layer "In2.Cu")
		(net "M_F_CPU1_SA_DQ<20>")
	)
	(arc
		(start 137.311892 -266.617704)
		(mid 137.124694 -266.567527)
		(end 136.937496 -266.617704)
		(width 0.088646)
		(layer "In2.Cu")
		(net "M_F_CPU1_SA_DQ<20>")
	)
	(arc
		(start 135.554466 -267.17244)
		(mid 135.507754 -267.215673)
		(end 135.456168 -267.252958)
		(width 0.088646)
		(layer "In2.Cu")
		(net "M_F_CPU1_SA_DQ<20>")
	)
	(arc
		(start 133.736842 -267.042646)
		(mid 133.557996 -266.967636)
		(end 133.365748 -266.942062)
		(width 0.088646)
		(layer "In2.Cu")
		(net "M_F_CPU1_SA_DQ<20>")
	)
	(arc
		(start 137.877296 -266.617704)
		(mid 137.594594 -266.69348)
		(end 137.311892 -266.617704)
		(width 0.088646)
		(layer "In2.Cu")
		(net "M_F_CPU1_SA_DQ<20>")
	)
	(arc
		(start 139.756896 -266.617704)
		(mid 139.474194 -266.69348)
		(end 139.191492 -266.617704)
		(width 0.088646)
		(layer "In2.Cu")
		(net "M_F_CPU1_SA_DQ<20>")
	)
	(arc
		(start 135.835898 -266.805664)
		(mid 135.76815 -266.937203)
		(end 135.674862 -267.052044)
		(width 0.088646)
		(layer "In2.Cu")
		(net "M_F_CPU1_SA_DQ<20>")
	)
	(arc
		(start 136.937496 -266.617704)
		(mid 136.654794 -266.69348)
		(end 136.372092 -266.617704)
		(width 0.088646)
		(layer "In2.Cu")
		(net "M_F_CPU1_SA_DQ<20>")
	)
	(arc
		(start 136.184894 -266.567412)
		(mid 135.973626 -266.632662)
		(end 135.835898 -266.805664)
		(width 0.088646)
		(layer "In2.Cu")
		(net "M_F_CPU1_SA_DQ<20>")
	)
	(arc
		(start 138.817096 -266.617704)
		(mid 138.534394 -266.69348)
		(end 138.251692 -266.617704)
		(width 0.088646)
		(layer "In2.Cu")
		(net "M_F_CPU1_SA_DQ<20>")
	)
	(arc
		(start 134.32282 -267.327126)
		(mid 134.278229 -267.324266)
		(end 134.234428 -267.315442)
		(width 0.088646)
		(layer "In2.Cu")
		(net "M_F_CPU1_SA_DQ<20>")
	)
	(arc
		(start 135.456168 -267.252958)
		(mid 135.451078 -267.255862)
		(end 135.446008 -267.2588)
		(width 0.088646)
		(layer "In2.Cu")
		(net "M_F_CPU1_SA_DQ<20>")
	)
	(arc
		(start 139.191492 -266.617704)
		(mid 139.004294 -266.567527)
		(end 138.817096 -266.617704)
		(width 0.088646)
		(layer "In2.Cu")
		(net "M_F_CPU1_SA_DQ<20>")
	)
	(segment
		(start 173.900846 -314.616592)
		(end 172.795946 -314.616592)
		(width 0.20066)
		(layer "F.Cu")
		(net "M_F_CPU1_SA_DQ<1>")
	)
	(segment
		(start 181.444392 -314.616846)
		(end 179.852828 -314.616846)
		(width 0.20066)
		(layer "F.Cu")
		(net "M_F_CPU1_SA_DQ<1>")
	)
	(segment
		(start 135.245094 -277.800562)
		(end 135.245094 -278.336502)
		(width 0.20066)
		(layer "F.Cu")
		(net "M_F_CPU1_SA_DQ<1>")
	)
	(segment
		(start 176.796192 -314.19165)
		(end 176.451514 -314.19165)
		(width 0.20066)
		(layer "F.Cu")
		(net "M_F_CPU1_SA_DQ<1>")
	)
	(segment
		(start 175.421544 -314.616592)
		(end 173.900846 -314.616592)
		(width 0.20066)
		(layer "F.Cu")
		(net "M_F_CPU1_SA_DQ<1>")
	)
	(segment
		(start 176.333404 -314.30976)
		(end 176.333404 -314.677298)
		(width 0.20066)
		(layer "F.Cu")
		(net "M_F_CPU1_SA_DQ<1>")
	)
	(segment
		(start 176.451514 -314.19165)
		(end 176.333404 -314.30976)
		(width 0.20066)
		(layer "F.Cu")
		(net "M_F_CPU1_SA_DQ<1>")
	)
	(segment
		(start 179.852828 -314.616846)
		(end 179.421282 -314.1853)
		(width 0.20066)
		(layer "F.Cu")
		(net "M_F_CPU1_SA_DQ<1>")
	)
	(segment
		(start 179.004976 -314.19165)
		(end 176.816258 -314.19165)
		(width 0.1016)
		(layer "F.Cu")
		(net "M_F_CPU1_SA_DQ<1>")
	)
	(segment
		(start 179.011326 -314.1853)
		(end 179.004976 -314.19165)
		(width 0.1016)
		(layer "F.Cu")
		(net "M_F_CPU1_SA_DQ<1>")
	)
	(segment
		(start 176.816258 -314.19165)
		(end 176.796192 -314.19165)
		(width 0.101854)
		(layer "F.Cu")
		(net "M_F_CPU1_SA_DQ<1>")
	)
	(segment
		(start 175.67021 -314.865258)
		(end 175.421544 -314.616592)
		(width 0.20066)
		(layer "F.Cu")
		(net "M_F_CPU1_SA_DQ<1>")
	)
	(segment
		(start 179.421282 -314.1853)
		(end 179.011326 -314.1853)
		(width 0.20066)
		(layer "F.Cu")
		(net "M_F_CPU1_SA_DQ<1>")
	)
	(segment
		(start 181.444646 -314.616592)
		(end 181.444392 -314.616846)
		(width 0.20066)
		(layer "F.Cu")
		(net "M_F_CPU1_SA_DQ<1>")
	)
	(segment
		(start 176.333404 -314.677298)
		(end 176.145444 -314.865258)
		(width 0.20066)
		(layer "F.Cu")
		(net "M_F_CPU1_SA_DQ<1>")
	)
	(segment
		(start 176.145444 -314.865258)
		(end 175.67021 -314.865258)
		(width 0.20066)
		(layer "F.Cu")
		(net "M_F_CPU1_SA_DQ<1>")
	)
	(segment
		(start 135.11276 -278.696674)
		(end 135.08863 -278.60752)
		(width 0.088646)
		(layer "In2.Cu")
		(net "M_F_CPU1_SA_DQ<1>")
	)
	(segment
		(start 161.843974 -314.00369)
		(end 161.843974 -313.528964)
		(width 0.18288)
		(layer "In2.Cu")
		(net "M_F_CPU1_SA_DQ<1>")
	)
	(segment
		(start 135.08863 -278.60752)
		(end 135.245094 -278.336502)
		(width 0.088646)
		(layer "In2.Cu")
		(net "M_F_CPU1_SA_DQ<1>")
	)
	(segment
		(start 172.795946 -314.616592)
		(end 172.283628 -314.104274)
		(width 0.18288)
		(layer "In2.Cu")
		(net "M_F_CPU1_SA_DQ<1>")
	)
	(segment
		(start 163.48583 -314.182506)
		(end 163.127944 -314.540392)
		(width 0.18288)
		(layer "In2.Cu")
		(net "M_F_CPU1_SA_DQ<1>")
	)
	(segment
		(start 160.071816 -314.527946)
		(end 159.75584 -314.21197)
		(width 0.18288)
		(layer "In2.Cu")
		(net "M_F_CPU1_SA_DQ<1>")
	)
	(segment
		(start 168.812972 -313.362086)
		(end 168.652952 -313.522106)
		(width 0.18288)
		(layer "In2.Cu")
		(net "M_F_CPU1_SA_DQ<1>")
	)
	(segment
		(start 162.779964 -314.540392)
		(end 162.42157 -314.181998)
		(width 0.18288)
		(layer "In2.Cu")
		(net "M_F_CPU1_SA_DQ<1>")
	)
	(segment
		(start 161.088578 -313.33567)
		(end 160.847278 -313.57697)
		(width 0.18288)
		(layer "In2.Cu")
		(net "M_F_CPU1_SA_DQ<1>")
	)
	(segment
		(start 164.711888 -314.403232)
		(end 164.491162 -314.182506)
		(width 0.18288)
		(layer "In2.Cu")
		(net "M_F_CPU1_SA_DQ<1>")
	)
	(segment
		(start 163.127944 -314.540392)
		(end 162.779964 -314.540392)
		(width 0.18288)
		(layer "In2.Cu")
		(net "M_F_CPU1_SA_DQ<1>")
	)
	(segment
		(start 161.068258 -314.03417)
		(end 161.068258 -314.334906)
		(width 0.18288)
		(layer "In2.Cu")
		(net "M_F_CPU1_SA_DQ<1>")
	)
	(segment
		(start 172.283628 -313.572398)
		(end 172.090588 -313.379358)
		(width 0.18288)
		(layer "In2.Cu")
		(net "M_F_CPU1_SA_DQ<1>")
	)
	(segment
		(start 139.428474 -279.412446)
		(end 139.148058 -279.412446)
		(width 0.18288)
		(layer "In2.Cu")
		(net "M_F_CPU1_SA_DQ<1>")
	)
	(segment
		(start 160.847278 -313.57697)
		(end 160.847278 -313.81319)
		(width 0.18288)
		(layer "In2.Cu")
		(net "M_F_CPU1_SA_DQ<1>")
	)
	(segment
		(start 168.652952 -314.573158)
		(end 168.459912 -314.766198)
		(width 0.18288)
		(layer "In2.Cu")
		(net "M_F_CPU1_SA_DQ<1>")
	)
	(segment
		(start 136.856978 -279.46604)
		(end 136.842246 -279.474676)
		(width 0.088646)
		(layer "In2.Cu")
		(net "M_F_CPU1_SA_DQ<1>")
	)
	(segment
		(start 135.912606 -279.46858)
		(end 135.902192 -279.474676)
		(width 0.088646)
		(layer "In2.Cu")
		(net "M_F_CPU1_SA_DQ<1>")
	)
	(segment
		(start 159.75584 -314.21197)
		(end 157.832298 -314.21197)
		(width 0.18288)
		(layer "In2.Cu")
		(net "M_F_CPU1_SA_DQ<1>")
	)
	(segment
		(start 169.863008 -314.50661)
		(end 169.466768 -314.11037)
		(width 0.18288)
		(layer "In2.Cu")
		(net "M_F_CPU1_SA_DQ<1>")
	)
	(segment
		(start 135.527796 -279.474676)
		(end 135.518906 -279.469596)
		(width 0.088646)
		(layer "In2.Cu")
		(net "M_F_CPU1_SA_DQ<1>")
	)
	(segment
		(start 169.466768 -314.11037)
		(end 169.466768 -313.555126)
		(width 0.18288)
		(layer "In2.Cu")
		(net "M_F_CPU1_SA_DQ<1>")
	)
	(segment
		(start 171.619926 -313.379358)
		(end 171.426886 -313.572398)
		(width 0.18288)
		(layer "In2.Cu")
		(net "M_F_CPU1_SA_DQ<1>")
	)
	(segment
		(start 169.466768 -313.555126)
		(end 169.273728 -313.362086)
		(width 0.18288)
		(layer "In2.Cu")
		(net "M_F_CPU1_SA_DQ<1>")
	)
	(segment
		(start 161.65068 -313.33567)
		(end 161.088578 -313.33567)
		(width 0.18288)
		(layer "In2.Cu")
		(net "M_F_CPU1_SA_DQ<1>")
	)
	(segment
		(start 157.832298 -314.21197)
		(end 157.773116 -314.271152)
		(width 0.18288)
		(layer "In2.Cu")
		(net "M_F_CPU1_SA_DQ<1>")
	)
	(segment
		(start 141.520926 -283.229558)
		(end 140.30071 -280.284682)
		(width 0.18288)
		(layer "In2.Cu")
		(net "M_F_CPU1_SA_DQ<1>")
	)
	(segment
		(start 167.443912 -314.41771)
		(end 167.266112 -314.23991)
		(width 0.18288)
		(layer "In2.Cu")
		(net "M_F_CPU1_SA_DQ<1>")
	)
	(segment
		(start 165.37051 -314.23991)
		(end 165.207188 -314.403232)
		(width 0.18288)
		(layer "In2.Cu")
		(net "M_F_CPU1_SA_DQ<1>")
	)
	(segment
		(start 142.385034 -284.093666)
		(end 141.520926 -283.229558)
		(width 0.18288)
		(layer "In2.Cu")
		(net "M_F_CPU1_SA_DQ<1>")
	)
	(segment
		(start 169.273728 -313.362086)
		(end 168.812972 -313.362086)
		(width 0.18288)
		(layer "In2.Cu")
		(net "M_F_CPU1_SA_DQ<1>")
	)
	(segment
		(start 164.491162 -314.182506)
		(end 163.48583 -314.182506)
		(width 0.18288)
		(layer "In2.Cu")
		(net "M_F_CPU1_SA_DQ<1>")
	)
	(segment
		(start 140.30071 -280.284682)
		(end 139.428474 -279.412446)
		(width 0.18288)
		(layer "In2.Cu")
		(net "M_F_CPU1_SA_DQ<1>")
	)
	(segment
		(start 161.068258 -314.334906)
		(end 160.875218 -314.527946)
		(width 0.18288)
		(layer "In2.Cu")
		(net "M_F_CPU1_SA_DQ<1>")
	)
	(segment
		(start 142.385034 -289.97656)
		(end 142.385034 -284.093666)
		(width 0.18288)
		(layer "In2.Cu")
		(net "M_F_CPU1_SA_DQ<1>")
	)
	(segment
		(start 171.030646 -314.50661)
		(end 169.863008 -314.50661)
		(width 0.18288)
		(layer "In2.Cu")
		(net "M_F_CPU1_SA_DQ<1>")
	)
	(segment
		(start 171.426886 -313.572398)
		(end 171.426886 -314.11037)
		(width 0.18288)
		(layer "In2.Cu")
		(net "M_F_CPU1_SA_DQ<1>")
	)
	(segment
		(start 172.090588 -313.379358)
		(end 171.619926 -313.379358)
		(width 0.18288)
		(layer "In2.Cu")
		(net "M_F_CPU1_SA_DQ<1>")
	)
	(segment
		(start 161.843974 -313.528964)
		(end 161.65068 -313.33567)
		(width 0.18288)
		(layer "In2.Cu")
		(net "M_F_CPU1_SA_DQ<1>")
	)
	(segment
		(start 168.652952 -313.522106)
		(end 168.652952 -314.573158)
		(width 0.18288)
		(layer "In2.Cu")
		(net "M_F_CPU1_SA_DQ<1>")
	)
	(segment
		(start 162.022282 -314.181998)
		(end 161.843974 -314.00369)
		(width 0.18288)
		(layer "In2.Cu")
		(net "M_F_CPU1_SA_DQ<1>")
	)
	(segment
		(start 160.875218 -314.527946)
		(end 160.071816 -314.527946)
		(width 0.18288)
		(layer "In2.Cu")
		(net "M_F_CPU1_SA_DQ<1>")
	)
	(segment
		(start 156.957014 -314.126626)
		(end 147.030186 -304.199798)
		(width 0.18288)
		(layer "In2.Cu")
		(net "M_F_CPU1_SA_DQ<1>")
	)
	(segment
		(start 168.18356 -314.766198)
		(end 167.835072 -314.41771)
		(width 0.18288)
		(layer "In2.Cu")
		(net "M_F_CPU1_SA_DQ<1>")
	)
	(segment
		(start 168.459912 -314.766198)
		(end 168.18356 -314.766198)
		(width 0.18288)
		(layer "In2.Cu")
		(net "M_F_CPU1_SA_DQ<1>")
	)
	(segment
		(start 167.835072 -314.41771)
		(end 167.443912 -314.41771)
		(width 0.18288)
		(layer "In2.Cu")
		(net "M_F_CPU1_SA_DQ<1>")
	)
	(segment
		(start 162.42157 -314.181998)
		(end 162.022282 -314.181998)
		(width 0.18288)
		(layer "In2.Cu")
		(net "M_F_CPU1_SA_DQ<1>")
	)
	(segment
		(start 160.847278 -313.81319)
		(end 161.068258 -314.03417)
		(width 0.18288)
		(layer "In2.Cu")
		(net "M_F_CPU1_SA_DQ<1>")
	)
	(segment
		(start 171.426886 -314.11037)
		(end 171.030646 -314.50661)
		(width 0.18288)
		(layer "In2.Cu")
		(net "M_F_CPU1_SA_DQ<1>")
	)
	(segment
		(start 139.148058 -279.412446)
		(end 138.039856 -279.412446)
		(width 0.088646)
		(layer "In2.Cu")
		(net "M_F_CPU1_SA_DQ<1>")
	)
	(segment
		(start 157.30601 -314.271152)
		(end 156.957014 -314.126626)
		(width 0.18288)
		(layer "In2.Cu")
		(net "M_F_CPU1_SA_DQ<1>")
	)
	(segment
		(start 135.340344 -279.150318)
		(end 135.340344 -279.140412)
		(width 0.088646)
		(layer "In2.Cu")
		(net "M_F_CPU1_SA_DQ<1>")
	)
	(segment
		(start 165.207188 -314.403232)
		(end 164.711888 -314.403232)
		(width 0.18288)
		(layer "In2.Cu")
		(net "M_F_CPU1_SA_DQ<1>")
	)
	(segment
		(start 157.773116 -314.271152)
		(end 157.30601 -314.271152)
		(width 0.18288)
		(layer "In2.Cu")
		(net "M_F_CPU1_SA_DQ<1>")
	)
	(segment
		(start 143.468852 -292.593268)
		(end 142.385034 -289.97656)
		(width 0.18288)
		(layer "In2.Cu")
		(net "M_F_CPU1_SA_DQ<1>")
	)
	(segment
		(start 145.631916 -294.756332)
		(end 143.468852 -292.593268)
		(width 0.18288)
		(layer "In2.Cu")
		(net "M_F_CPU1_SA_DQ<1>")
	)
	(segment
		(start 172.283628 -314.104274)
		(end 172.283628 -313.572398)
		(width 0.18288)
		(layer "In2.Cu")
		(net "M_F_CPU1_SA_DQ<1>")
	)
	(segment
		(start 147.030186 -304.199798)
		(end 147.030186 -298.131992)
		(width 0.18288)
		(layer "In2.Cu")
		(net "M_F_CPU1_SA_DQ<1>")
	)
	(segment
		(start 147.030186 -298.131992)
		(end 145.631916 -294.756332)
		(width 0.18288)
		(layer "In2.Cu")
		(net "M_F_CPU1_SA_DQ<1>")
	)
	(segment
		(start 167.266112 -314.23991)
		(end 165.37051 -314.23991)
		(width 0.18288)
		(layer "In2.Cu")
		(net "M_F_CPU1_SA_DQ<1>")
	)
	(arc
		(start 137.782046 -279.474676)
		(mid 137.594848 -279.524819)
		(end 137.40765 -279.474676)
		(width 0.088646)
		(layer "In2.Cu")
		(net "M_F_CPU1_SA_DQ<1>")
	)
	(arc
		(start 136.46785 -279.474676)
		(mid 136.191037 -279.398806)
		(end 135.912606 -279.46858)
		(width 0.088646)
		(layer "In2.Cu")
		(net "M_F_CPU1_SA_DQ<1>")
	)
	(arc
		(start 136.842246 -279.474676)
		(mid 136.655048 -279.524819)
		(end 136.46785 -279.474676)
		(width 0.088646)
		(layer "In2.Cu")
		(net "M_F_CPU1_SA_DQ<1>")
	)
	(arc
		(start 135.340344 -279.140412)
		(mid 135.278125 -278.892095)
		(end 135.11276 -278.696674)
		(width 0.088646)
		(layer "In2.Cu")
		(net "M_F_CPU1_SA_DQ<1>")
	)
	(arc
		(start 135.518906 -279.469596)
		(mid 135.387992 -279.333236)
		(end 135.340344 -279.150318)
		(width 0.088646)
		(layer "In2.Cu")
		(net "M_F_CPU1_SA_DQ<1>")
	)
	(arc
		(start 135.902192 -279.474676)
		(mid 135.714994 -279.524819)
		(end 135.527796 -279.474676)
		(width 0.088646)
		(layer "In2.Cu")
		(net "M_F_CPU1_SA_DQ<1>")
	)
	(arc
		(start 137.40765 -279.474676)
		(mid 137.133451 -279.398841)
		(end 136.856978 -279.46604)
		(width 0.088646)
		(layer "In2.Cu")
		(net "M_F_CPU1_SA_DQ<1>")
	)
	(arc
		(start 138.039856 -279.412446)
		(mid 137.90726 -279.42826)
		(end 137.782046 -279.474676)
		(width 0.088646)
		(layer "In2.Cu")
		(net "M_F_CPU1_SA_DQ<1>")
	)
	(segment
		(start 182.442866 -295.491662)
		(end 182.455058 -295.503854)
		(width 0.1016)
		(layer "F.Cu")
		(net "M_F_CPU1_SA_DQ<19>")
	)
	(segment
		(start 178.000914 -295.06672)
		(end 179.699158 -295.06672)
		(width 0.20066)
		(layer "F.Cu")
		(net "M_F_CPU1_SA_DQ<19>")
	)
	(segment
		(start 135.245094 -268.033754)
		(end 135.245094 -268.56944)
		(width 0.20066)
		(layer "F.Cu")
		(net "M_F_CPU1_SA_DQ<19>")
	)
	(segment
		(start 183.136286 -295.503854)
		(end 183.340248 -295.299892)
		(width 0.20066)
		(layer "F.Cu")
		(net "M_F_CPU1_SA_DQ<19>")
	)
	(segment
		(start 180.131212 -295.498774)
		(end 180.423058 -295.498774)
		(width 0.20066)
		(layer "F.Cu")
		(net "M_F_CPU1_SA_DQ<19>")
	)
	(segment
		(start 182.455058 -295.503854)
		(end 183.136286 -295.503854)
		(width 0.20066)
		(layer "F.Cu")
		(net "M_F_CPU1_SA_DQ<19>")
	)
	(segment
		(start 183.958484 -294.814752)
		(end 184.210452 -295.06672)
		(width 0.20066)
		(layer "F.Cu")
		(net "M_F_CPU1_SA_DQ<19>")
	)
	(segment
		(start 183.574436 -294.814752)
		(end 183.958484 -294.814752)
		(width 0.20066)
		(layer "F.Cu")
		(net "M_F_CPU1_SA_DQ<19>")
	)
	(segment
		(start 180.434996 -295.491662)
		(end 182.442866 -295.491662)
		(width 0.1016)
		(layer "F.Cu")
		(net "M_F_CPU1_SA_DQ<19>")
	)
	(segment
		(start 183.340248 -295.04894)
		(end 183.574436 -294.814752)
		(width 0.20066)
		(layer "F.Cu")
		(net "M_F_CPU1_SA_DQ<19>")
	)
	(segment
		(start 184.210452 -295.06672)
		(end 185.544714 -295.06672)
		(width 0.20066)
		(layer "F.Cu")
		(net "M_F_CPU1_SA_DQ<19>")
	)
	(segment
		(start 176.896014 -295.06672)
		(end 178.000914 -295.06672)
		(width 0.20066)
		(layer "F.Cu")
		(net "M_F_CPU1_SA_DQ<19>")
	)
	(segment
		(start 135.245094 -268.56944)
		(end 135.245348 -268.569694)
		(width 0.20066)
		(layer "F.Cu")
		(net "M_F_CPU1_SA_DQ<19>")
	)
	(segment
		(start 180.423058 -295.498774)
		(end 180.427884 -295.498774)
		(width 0.101854)
		(layer "F.Cu")
		(net "M_F_CPU1_SA_DQ<19>")
	)
	(segment
		(start 183.340248 -295.299892)
		(end 183.340248 -295.04894)
		(width 0.20066)
		(layer "F.Cu")
		(net "M_F_CPU1_SA_DQ<19>")
	)
	(segment
		(start 179.699158 -295.06672)
		(end 180.131212 -295.498774)
		(width 0.20066)
		(layer "F.Cu")
		(net "M_F_CPU1_SA_DQ<19>")
	)
	(segment
		(start 180.427884 -295.498774)
		(end 180.434996 -295.491662)
		(width 0.1016)
		(layer "F.Cu")
		(net "M_F_CPU1_SA_DQ<19>")
	)
	(segment
		(start 168.485058 -294.342566)
		(end 168.485058 -294.213534)
		(width 0.18288)
		(layer "In2.Cu")
		(net "M_F_CPU1_SA_DQ<19>")
	)
	(segment
		(start 174.360078 -295.279064)
		(end 174.146972 -295.49217)
		(width 0.18288)
		(layer "In2.Cu")
		(net "M_F_CPU1_SA_DQ<19>")
	)
	(segment
		(start 176.09566 -295.539922)
		(end 175.777398 -295.539922)
		(width 0.18288)
		(layer "In2.Cu")
		(net "M_F_CPU1_SA_DQ<19>")
	)
	(segment
		(start 165.19779 -291.777928)
		(end 165.19779 -291.405564)
		(width 0.18288)
		(layer "In2.Cu")
		(net "M_F_CPU1_SA_DQ<19>")
	)
	(segment
		(start 176.896014 -295.06672)
		(end 176.568862 -295.06672)
		(width 0.18288)
		(layer "In2.Cu")
		(net "M_F_CPU1_SA_DQ<19>")
	)
	(segment
		(start 159.456882 -287.231328)
		(end 158.475934 -287.231328)
		(width 0.18288)
		(layer "In2.Cu")
		(net "M_F_CPU1_SA_DQ<19>")
	)
	(segment
		(start 161.866326 -289.363404)
		(end 161.866326 -289.276028)
		(width 0.18288)
		(layer "In2.Cu")
		(net "M_F_CPU1_SA_DQ<19>")
	)
	(segment
		(start 150.3553 -277.495762)
		(end 149.347936 -275.06422)
		(width 0.18288)
		(layer "In2.Cu")
		(net "M_F_CPU1_SA_DQ<19>")
	)
	(segment
		(start 149.347936 -275.06422)
		(end 147.348194 -273.064478)
		(width 0.18288)
		(layer "In2.Cu")
		(net "M_F_CPU1_SA_DQ<19>")
	)
	(segment
		(start 168.839642 -294.69715)
		(end 168.485058 -294.342566)
		(width 0.18288)
		(layer "In2.Cu")
		(net "M_F_CPU1_SA_DQ<19>")
	)
	(segment
		(start 163.9316 -290.51758)
		(end 163.449 -290.03498)
		(width 0.18288)
		(layer "In2.Cu")
		(net "M_F_CPU1_SA_DQ<19>")
	)
	(segment
		(start 174.553118 -294.71112)
		(end 174.360078 -294.90416)
		(width 0.18288)
		(layer "In2.Cu")
		(net "M_F_CPU1_SA_DQ<19>")
	)
	(segment
		(start 168.485058 -294.213534)
		(end 166.561516 -292.289992)
		(width 0.18288)
		(layer "In2.Cu")
		(net "M_F_CPU1_SA_DQ<19>")
	)
	(segment
		(start 159.72536 -286.96285)
		(end 159.456882 -287.231328)
		(width 0.18288)
		(layer "In2.Cu")
		(net "M_F_CPU1_SA_DQ<19>")
	)
	(segment
		(start 135.2931 -268.795246)
		(end 135.245348 -268.569694)
		(width 0.088646)
		(layer "In2.Cu")
		(net "M_F_CPU1_SA_DQ<19>")
	)
	(segment
		(start 155.050998 -282.19146)
		(end 150.3553 -277.495762)
		(width 0.18288)
		(layer "In2.Cu")
		(net "M_F_CPU1_SA_DQ<19>")
	)
	(segment
		(start 140.900404 -268.89075)
		(end 140.21816 -268.89075)
		(width 0.088646)
		(layer "In2.Cu")
		(net "M_F_CPU1_SA_DQ<19>")
	)
	(segment
		(start 175.584358 -294.462454)
		(end 175.391318 -294.269414)
		(width 0.18288)
		(layer "In2.Cu")
		(net "M_F_CPU1_SA_DQ<19>")
	)
	(segment
		(start 173.351698 -295.29913)
		(end 173.351698 -294.83177)
		(width 0.18288)
		(layer "In2.Cu")
		(net "M_F_CPU1_SA_DQ<19>")
	)
	(segment
		(start 173.162722 -294.642794)
		(end 172.398944 -294.642794)
		(width 0.18288)
		(layer "In2.Cu")
		(net "M_F_CPU1_SA_DQ<19>")
	)
	(segment
		(start 160.396682 -287.806384)
		(end 160.396682 -287.264094)
		(width 0.18288)
		(layer "In2.Cu")
		(net "M_F_CPU1_SA_DQ<19>")
	)
	(segment
		(start 147.348194 -273.064478)
		(end 146.657822 -273.064478)
		(width 0.18288)
		(layer "In2.Cu")
		(net "M_F_CPU1_SA_DQ<19>")
	)
	(segment
		(start 166.561516 -292.289992)
		(end 165.709854 -292.289992)
		(width 0.18288)
		(layer "In2.Cu")
		(net "M_F_CPU1_SA_DQ<19>")
	)
	(segment
		(start 164.309806 -290.51758)
		(end 163.9316 -290.51758)
		(width 0.18288)
		(layer "In2.Cu")
		(net "M_F_CPU1_SA_DQ<19>")
	)
	(segment
		(start 155.050998 -284.084522)
		(end 155.050998 -282.19146)
		(width 0.18288)
		(layer "In2.Cu")
		(net "M_F_CPU1_SA_DQ<19>")
	)
	(segment
		(start 173.351698 -294.83177)
		(end 173.162722 -294.642794)
		(width 0.18288)
		(layer "In2.Cu")
		(net "M_F_CPU1_SA_DQ<19>")
	)
	(segment
		(start 175.118268 -294.269414)
		(end 174.676562 -294.71112)
		(width 0.18288)
		(layer "In2.Cu")
		(net "M_F_CPU1_SA_DQ<19>")
	)
	(segment
		(start 162.537902 -290.03498)
		(end 161.866326 -289.363404)
		(width 0.18288)
		(layer "In2.Cu")
		(net "M_F_CPU1_SA_DQ<19>")
	)
	(segment
		(start 140.164058 -268.944852)
		(end 139.944348 -268.944852)
		(width 0.088646)
		(layer "In2.Cu")
		(net "M_F_CPU1_SA_DQ<19>")
	)
	(segment
		(start 174.676562 -294.71112)
		(end 174.553118 -294.71112)
		(width 0.18288)
		(layer "In2.Cu")
		(net "M_F_CPU1_SA_DQ<19>")
	)
	(segment
		(start 140.21816 -268.89075)
		(end 140.164058 -268.944852)
		(width 0.088646)
		(layer "In2.Cu")
		(net "M_F_CPU1_SA_DQ<19>")
	)
	(segment
		(start 176.568862 -295.06672)
		(end 176.09566 -295.539922)
		(width 0.18288)
		(layer "In2.Cu")
		(net "M_F_CPU1_SA_DQ<19>")
	)
	(segment
		(start 175.584358 -295.346882)
		(end 175.584358 -294.462454)
		(width 0.18288)
		(layer "In2.Cu")
		(net "M_F_CPU1_SA_DQ<19>")
	)
	(segment
		(start 135.621776 -268.826234)
		(end 135.394446 -268.864334)
		(width 0.088646)
		(layer "In2.Cu")
		(net "M_F_CPU1_SA_DQ<19>")
	)
	(segment
		(start 161.866326 -289.276028)
		(end 160.396682 -287.806384)
		(width 0.18288)
		(layer "In2.Cu")
		(net "M_F_CPU1_SA_DQ<19>")
	)
	(segment
		(start 171.402756 -294.69715)
		(end 168.839642 -294.69715)
		(width 0.18288)
		(layer "In2.Cu")
		(net "M_F_CPU1_SA_DQ<19>")
	)
	(segment
		(start 173.544738 -295.49217)
		(end 173.351698 -295.29913)
		(width 0.18288)
		(layer "In2.Cu")
		(net "M_F_CPU1_SA_DQ<19>")
	)
	(segment
		(start 172.398944 -294.642794)
		(end 172.262292 -294.779446)
		(width 0.18288)
		(layer "In2.Cu")
		(net "M_F_CPU1_SA_DQ<19>")
	)
	(segment
		(start 163.449 -290.03498)
		(end 162.537902 -290.03498)
		(width 0.18288)
		(layer "In2.Cu")
		(net "M_F_CPU1_SA_DQ<19>")
	)
	(segment
		(start 165.19779 -291.405564)
		(end 164.309806 -290.51758)
		(width 0.18288)
		(layer "In2.Cu")
		(net "M_F_CPU1_SA_DQ<19>")
	)
	(segment
		(start 175.777398 -295.539922)
		(end 175.584358 -295.346882)
		(width 0.18288)
		(layer "In2.Cu")
		(net "M_F_CPU1_SA_DQ<19>")
	)
	(segment
		(start 171.485052 -294.779446)
		(end 171.402756 -294.69715)
		(width 0.18288)
		(layer "In2.Cu")
		(net "M_F_CPU1_SA_DQ<19>")
	)
	(segment
		(start 158.475934 -287.231328)
		(end 158.000954 -287.034478)
		(width 0.18288)
		(layer "In2.Cu")
		(net "M_F_CPU1_SA_DQ<19>")
	)
	(segment
		(start 142.484094 -268.89075)
		(end 140.900404 -268.89075)
		(width 0.18288)
		(layer "In2.Cu")
		(net "M_F_CPU1_SA_DQ<19>")
	)
	(segment
		(start 160.095438 -286.96285)
		(end 159.72536 -286.96285)
		(width 0.18288)
		(layer "In2.Cu")
		(net "M_F_CPU1_SA_DQ<19>")
	)
	(segment
		(start 172.262292 -294.779446)
		(end 171.485052 -294.779446)
		(width 0.18288)
		(layer "In2.Cu")
		(net "M_F_CPU1_SA_DQ<19>")
	)
	(segment
		(start 165.709854 -292.289992)
		(end 165.19779 -291.777928)
		(width 0.18288)
		(layer "In2.Cu")
		(net "M_F_CPU1_SA_DQ<19>")
	)
	(segment
		(start 146.657822 -273.064478)
		(end 142.484094 -268.89075)
		(width 0.18288)
		(layer "In2.Cu")
		(net "M_F_CPU1_SA_DQ<19>")
	)
	(segment
		(start 174.146972 -295.49217)
		(end 173.544738 -295.49217)
		(width 0.18288)
		(layer "In2.Cu")
		(net "M_F_CPU1_SA_DQ<19>")
	)
	(segment
		(start 175.391318 -294.269414)
		(end 175.118268 -294.269414)
		(width 0.18288)
		(layer "In2.Cu")
		(net "M_F_CPU1_SA_DQ<19>")
	)
	(segment
		(start 158.000954 -287.034478)
		(end 155.050998 -284.084522)
		(width 0.18288)
		(layer "In2.Cu")
		(net "M_F_CPU1_SA_DQ<19>")
	)
	(segment
		(start 160.396682 -287.264094)
		(end 160.095438 -286.96285)
		(width 0.18288)
		(layer "In2.Cu")
		(net "M_F_CPU1_SA_DQ<19>")
	)
	(segment
		(start 174.360078 -294.90416)
		(end 174.360078 -295.279064)
		(width 0.18288)
		(layer "In2.Cu")
		(net "M_F_CPU1_SA_DQ<19>")
	)
	(arc
		(start 138.251692 -268.894052)
		(mid 138.064494 -268.944195)
		(end 137.877296 -268.894052)
		(width 0.088646)
		(layer "In2.Cu")
		(net "M_F_CPU1_SA_DQ<19>")
	)
	(arc
		(start 139.756896 -268.894052)
		(mid 139.474194 -268.818276)
		(end 139.191492 -268.894052)
		(width 0.088646)
		(layer "In2.Cu")
		(net "M_F_CPU1_SA_DQ<19>")
	)
	(arc
		(start 136.937496 -268.894052)
		(mid 136.654794 -268.818276)
		(end 136.372092 -268.894052)
		(width 0.088646)
		(layer "In2.Cu")
		(net "M_F_CPU1_SA_DQ<19>")
	)
	(arc
		(start 137.877296 -268.894052)
		(mid 137.594594 -268.818276)
		(end 137.311892 -268.894052)
		(width 0.088646)
		(layer "In2.Cu")
		(net "M_F_CPU1_SA_DQ<19>")
	)
	(arc
		(start 139.944348 -268.944852)
		(mid 139.847278 -268.931795)
		(end 139.756896 -268.894052)
		(width 0.088646)
		(layer "In2.Cu")
		(net "M_F_CPU1_SA_DQ<19>")
	)
	(arc
		(start 135.394446 -268.864334)
		(mid 135.32984 -268.850198)
		(end 135.2931 -268.795246)
		(width 0.088646)
		(layer "In2.Cu")
		(net "M_F_CPU1_SA_DQ<19>")
	)
	(arc
		(start 137.311892 -268.894052)
		(mid 137.124694 -268.944195)
		(end 136.937496 -268.894052)
		(width 0.088646)
		(layer "In2.Cu")
		(net "M_F_CPU1_SA_DQ<19>")
	)
	(arc
		(start 136.372092 -268.894052)
		(mid 136.184894 -268.944195)
		(end 135.997696 -268.894052)
		(width 0.088646)
		(layer "In2.Cu")
		(net "M_F_CPU1_SA_DQ<19>")
	)
	(arc
		(start 139.191492 -268.894052)
		(mid 139.004294 -268.944195)
		(end 138.817096 -268.894052)
		(width 0.088646)
		(layer "In2.Cu")
		(net "M_F_CPU1_SA_DQ<19>")
	)
	(arc
		(start 138.817096 -268.894052)
		(mid 138.534394 -268.818276)
		(end 138.251692 -268.894052)
		(width 0.088646)
		(layer "In2.Cu")
		(net "M_F_CPU1_SA_DQ<19>")
	)
	(arc
		(start 135.997696 -268.894052)
		(mid 135.815638 -268.827422)
		(end 135.621776 -268.826234)
		(width 0.088646)
		(layer "In2.Cu")
		(net "M_F_CPU1_SA_DQ<19>")
	)
	(segment
		(start 178.000914 -296.766742)
		(end 179.699158 -296.766742)
		(width 0.20066)
		(layer "F.Cu")
		(net "M_F_CPU1_SA_DQ<18>")
	)
	(segment
		(start 184.210452 -296.766742)
		(end 185.544714 -296.766742)
		(width 0.20066)
		(layer "F.Cu")
		(net "M_F_CPU1_SA_DQ<18>")
	)
	(segment
		(start 182.455058 -297.203876)
		(end 183.136286 -297.203876)
		(width 0.20066)
		(layer "F.Cu")
		(net "M_F_CPU1_SA_DQ<18>")
	)
	(segment
		(start 134.775448 -269.383256)
		(end 134.775194 -269.38351)
		(width 0.20066)
		(layer "F.Cu")
		(net "M_F_CPU1_SA_DQ<18>")
	)
	(segment
		(start 183.958484 -296.514774)
		(end 184.210452 -296.766742)
		(width 0.20066)
		(layer "F.Cu")
		(net "M_F_CPU1_SA_DQ<18>")
	)
	(segment
		(start 176.896014 -296.766742)
		(end 178.000914 -296.766742)
		(width 0.20066)
		(layer "F.Cu")
		(net "M_F_CPU1_SA_DQ<18>")
	)
	(segment
		(start 180.434996 -297.191684)
		(end 182.442866 -297.191684)
		(width 0.1016)
		(layer "F.Cu")
		(net "M_F_CPU1_SA_DQ<18>")
	)
	(segment
		(start 183.136286 -297.203876)
		(end 183.340248 -296.999914)
		(width 0.20066)
		(layer "F.Cu")
		(net "M_F_CPU1_SA_DQ<18>")
	)
	(segment
		(start 183.340248 -296.748962)
		(end 183.574436 -296.514774)
		(width 0.20066)
		(layer "F.Cu")
		(net "M_F_CPU1_SA_DQ<18>")
	)
	(segment
		(start 134.775448 -268.84757)
		(end 134.775448 -269.383256)
		(width 0.20066)
		(layer "F.Cu")
		(net "M_F_CPU1_SA_DQ<18>")
	)
	(segment
		(start 179.699158 -296.766742)
		(end 180.131212 -297.198796)
		(width 0.20066)
		(layer "F.Cu")
		(net "M_F_CPU1_SA_DQ<18>")
	)
	(segment
		(start 182.442866 -297.191684)
		(end 182.455058 -297.203876)
		(width 0.1016)
		(layer "F.Cu")
		(net "M_F_CPU1_SA_DQ<18>")
	)
	(segment
		(start 183.340248 -296.999914)
		(end 183.340248 -296.748962)
		(width 0.20066)
		(layer "F.Cu")
		(net "M_F_CPU1_SA_DQ<18>")
	)
	(segment
		(start 180.131212 -297.198796)
		(end 180.423058 -297.198796)
		(width 0.20066)
		(layer "F.Cu")
		(net "M_F_CPU1_SA_DQ<18>")
	)
	(segment
		(start 180.423058 -297.198796)
		(end 180.427884 -297.198796)
		(width 0.101854)
		(layer "F.Cu")
		(net "M_F_CPU1_SA_DQ<18>")
	)
	(segment
		(start 180.427884 -297.198796)
		(end 180.434996 -297.191684)
		(width 0.1016)
		(layer "F.Cu")
		(net "M_F_CPU1_SA_DQ<18>")
	)
	(segment
		(start 183.574436 -296.514774)
		(end 183.958484 -296.514774)
		(width 0.20066)
		(layer "F.Cu")
		(net "M_F_CPU1_SA_DQ<18>")
	)
	(segment
		(start 135.527796 -269.707868)
		(end 135.513064 -269.699232)
		(width 0.088646)
		(layer "In2.Cu")
		(net "M_F_CPU1_SA_DQ<18>")
	)
	(segment
		(start 158.717742 -289.260534)
		(end 158.344362 -289.105848)
		(width 0.18288)
		(layer "In2.Cu")
		(net "M_F_CPU1_SA_DQ<18>")
	)
	(segment
		(start 163.857686 -292.228778)
		(end 163.6395 -292.010592)
		(width 0.18288)
		(layer "In2.Cu")
		(net "M_F_CPU1_SA_DQ<18>")
	)
	(segment
		(start 146.671284 -274.055332)
		(end 142.247874 -269.631922)
		(width 0.18288)
		(layer "In2.Cu")
		(net "M_F_CPU1_SA_DQ<18>")
	)
	(segment
		(start 148.454618 -275.608542)
		(end 146.901408 -274.055332)
		(width 0.18288)
		(layer "In2.Cu")
		(net "M_F_CPU1_SA_DQ<18>")
	)
	(segment
		(start 140.900404 -269.631922)
		(end 139.944602 -269.631922)
		(width 0.088646)
		(layer "In2.Cu")
		(net "M_F_CPU1_SA_DQ<18>")
	)
	(segment
		(start 139.286996 -269.707868)
		(end 139.272264 -269.699232)
		(width 0.088646)
		(layer "In2.Cu")
		(net "M_F_CPU1_SA_DQ<18>")
	)
	(segment
		(start 164.801296 -294.003476)
		(end 163.857686 -293.059866)
		(width 0.18288)
		(layer "In2.Cu")
		(net "M_F_CPU1_SA_DQ<18>")
	)
	(segment
		(start 176.896014 -296.766742)
		(end 175.320198 -296.259504)
		(width 0.18288)
		(layer "In2.Cu")
		(net "M_F_CPU1_SA_DQ<18>")
	)
	(segment
		(start 174.775622 -296.341292)
		(end 172.328332 -296.341292)
		(width 0.18288)
		(layer "In2.Cu")
		(net "M_F_CPU1_SA_DQ<18>")
	)
	(segment
		(start 167.418258 -295.541192)
		(end 165.402006 -294.544242)
		(width 0.18288)
		(layer "In2.Cu")
		(net "M_F_CPU1_SA_DQ<18>")
	)
	(segment
		(start 134.467854 -269.377922)
		(end 134.473442 -269.38351)
		(width 0.088646)
		(layer "In2.Cu")
		(net "M_F_CPU1_SA_DQ<18>")
	)
	(segment
		(start 157.809692 -288.571178)
		(end 157.117796 -288.571178)
		(width 0.18288)
		(layer "In2.Cu")
		(net "M_F_CPU1_SA_DQ<18>")
	)
	(segment
		(start 168.791128 -296.01414)
		(end 167.418258 -295.541192)
		(width 0.18288)
		(layer "In2.Cu")
		(net "M_F_CPU1_SA_DQ<18>")
	)
	(segment
		(start 142.247874 -269.631922)
		(end 140.900404 -269.631922)
		(width 0.18288)
		(layer "In2.Cu")
		(net "M_F_CPU1_SA_DQ<18>")
	)
	(segment
		(start 146.901408 -274.055332)
		(end 146.671284 -274.055332)
		(width 0.18288)
		(layer "In2.Cu")
		(net "M_F_CPU1_SA_DQ<18>")
	)
	(segment
		(start 154.034998 -282.612592)
		(end 149.46122 -278.038814)
		(width 0.18288)
		(layer "In2.Cu")
		(net "M_F_CPU1_SA_DQ<18>")
	)
	(segment
		(start 134.405116 -269.44066)
		(end 134.467854 -269.377922)
		(width 0.088646)
		(layer "In2.Cu")
		(net "M_F_CPU1_SA_DQ<18>")
	)
	(segment
		(start 137.407396 -269.707868)
		(end 137.392664 -269.699232)
		(width 0.088646)
		(layer "In2.Cu")
		(net "M_F_CPU1_SA_DQ<18>")
	)
	(segment
		(start 163.6395 -292.010592)
		(end 162.112198 -292.010592)
		(width 0.18288)
		(layer "In2.Cu")
		(net "M_F_CPU1_SA_DQ<18>")
	)
	(segment
		(start 161.500566 -292.276276)
		(end 160.351978 -291.127688)
		(width 0.18288)
		(layer "In2.Cu")
		(net "M_F_CPU1_SA_DQ<18>")
	)
	(segment
		(start 160.351978 -291.127688)
		(end 160.351978 -290.28009)
		(width 0.18288)
		(layer "In2.Cu")
		(net "M_F_CPU1_SA_DQ<18>")
	)
	(segment
		(start 154.034998 -285.258256)
		(end 154.034998 -282.612592)
		(width 0.18288)
		(layer "In2.Cu")
		(net "M_F_CPU1_SA_DQ<18>")
	)
	(segment
		(start 161.846514 -292.276276)
		(end 161.500566 -292.276276)
		(width 0.18288)
		(layer "In2.Cu")
		(net "M_F_CPU1_SA_DQ<18>")
	)
	(segment
		(start 175.320198 -296.259504)
		(end 174.85741 -296.259504)
		(width 0.18288)
		(layer "In2.Cu")
		(net "M_F_CPU1_SA_DQ<18>")
	)
	(segment
		(start 159.332422 -289.260534)
		(end 158.717742 -289.260534)
		(width 0.18288)
		(layer "In2.Cu")
		(net "M_F_CPU1_SA_DQ<18>")
	)
	(segment
		(start 169.139362 -296.362374)
		(end 168.791128 -296.01414)
		(width 0.18288)
		(layer "In2.Cu")
		(net "M_F_CPU1_SA_DQ<18>")
	)
	(segment
		(start 172.328332 -296.341292)
		(end 172.30725 -296.362374)
		(width 0.18288)
		(layer "In2.Cu")
		(net "M_F_CPU1_SA_DQ<18>")
	)
	(segment
		(start 138.347196 -269.707868)
		(end 138.332464 -269.699232)
		(width 0.088646)
		(layer "In2.Cu")
		(net "M_F_CPU1_SA_DQ<18>")
	)
	(segment
		(start 157.117796 -288.571178)
		(end 154.197558 -285.65094)
		(width 0.18288)
		(layer "In2.Cu")
		(net "M_F_CPU1_SA_DQ<18>")
	)
	(segment
		(start 165.402006 -294.544242)
		(end 164.801296 -294.003476)
		(width 0.18288)
		(layer "In2.Cu")
		(net "M_F_CPU1_SA_DQ<18>")
	)
	(segment
		(start 172.30725 -296.362374)
		(end 169.139362 -296.362374)
		(width 0.18288)
		(layer "In2.Cu")
		(net "M_F_CPU1_SA_DQ<18>")
	)
	(segment
		(start 158.344362 -289.105848)
		(end 157.809692 -288.571178)
		(width 0.18288)
		(layer "In2.Cu")
		(net "M_F_CPU1_SA_DQ<18>")
	)
	(segment
		(start 134.473442 -269.38351)
		(end 134.775194 -269.38351)
		(width 0.088646)
		(layer "In2.Cu")
		(net "M_F_CPU1_SA_DQ<18>")
	)
	(segment
		(start 163.857686 -293.059866)
		(end 163.857686 -292.228778)
		(width 0.18288)
		(layer "In2.Cu")
		(net "M_F_CPU1_SA_DQ<18>")
	)
	(segment
		(start 136.467596 -269.707868)
		(end 136.452864 -269.699232)
		(width 0.088646)
		(layer "In2.Cu")
		(net "M_F_CPU1_SA_DQ<18>")
	)
	(segment
		(start 134.587996 -269.707868)
		(end 134.579106 -269.702788)
		(width 0.088646)
		(layer "In2.Cu")
		(net "M_F_CPU1_SA_DQ<18>")
	)
	(segment
		(start 154.197558 -285.65094)
		(end 154.034998 -285.258256)
		(width 0.18288)
		(layer "In2.Cu")
		(net "M_F_CPU1_SA_DQ<18>")
	)
	(segment
		(start 160.351978 -290.28009)
		(end 159.332422 -289.260534)
		(width 0.18288)
		(layer "In2.Cu")
		(net "M_F_CPU1_SA_DQ<18>")
	)
	(segment
		(start 174.85741 -296.259504)
		(end 174.775622 -296.341292)
		(width 0.18288)
		(layer "In2.Cu")
		(net "M_F_CPU1_SA_DQ<18>")
	)
	(segment
		(start 149.46122 -278.038814)
		(end 148.454618 -275.608542)
		(width 0.18288)
		(layer "In2.Cu")
		(net "M_F_CPU1_SA_DQ<18>")
	)
	(segment
		(start 162.112198 -292.010592)
		(end 161.846514 -292.276276)
		(width 0.18288)
		(layer "In2.Cu")
		(net "M_F_CPU1_SA_DQ<18>")
	)
	(arc
		(start 139.944602 -269.631922)
		(mid 139.798 -269.65125)
		(end 139.661392 -269.707868)
		(width 0.088646)
		(layer "In2.Cu")
		(net "M_F_CPU1_SA_DQ<18>")
	)
	(arc
		(start 139.661392 -269.707868)
		(mid 139.474194 -269.758011)
		(end 139.286996 -269.707868)
		(width 0.088646)
		(layer "In2.Cu")
		(net "M_F_CPU1_SA_DQ<18>")
	)
	(arc
		(start 137.781792 -269.707868)
		(mid 137.594594 -269.758011)
		(end 137.407396 -269.707868)
		(width 0.088646)
		(layer "In2.Cu")
		(net "M_F_CPU1_SA_DQ<18>")
	)
	(arc
		(start 135.513064 -269.699232)
		(mid 135.236623 -269.632066)
		(end 134.962392 -269.707868)
		(width 0.088646)
		(layer "In2.Cu")
		(net "M_F_CPU1_SA_DQ<18>")
	)
	(arc
		(start 135.902192 -269.707868)
		(mid 135.714994 -269.758011)
		(end 135.527796 -269.707868)
		(width 0.088646)
		(layer "In2.Cu")
		(net "M_F_CPU1_SA_DQ<18>")
	)
	(arc
		(start 134.579106 -269.702788)
		(mid 134.463297 -269.590859)
		(end 134.405116 -269.44066)
		(width 0.088646)
		(layer "In2.Cu")
		(net "M_F_CPU1_SA_DQ<18>")
	)
	(arc
		(start 134.962392 -269.707868)
		(mid 134.775194 -269.758011)
		(end 134.587996 -269.707868)
		(width 0.088646)
		(layer "In2.Cu")
		(net "M_F_CPU1_SA_DQ<18>")
	)
	(arc
		(start 138.721592 -269.707868)
		(mid 138.534394 -269.758011)
		(end 138.347196 -269.707868)
		(width 0.088646)
		(layer "In2.Cu")
		(net "M_F_CPU1_SA_DQ<18>")
	)
	(arc
		(start 136.841992 -269.707868)
		(mid 136.654794 -269.758011)
		(end 136.467596 -269.707868)
		(width 0.088646)
		(layer "In2.Cu")
		(net "M_F_CPU1_SA_DQ<18>")
	)
	(arc
		(start 139.272264 -269.699232)
		(mid 138.995823 -269.632066)
		(end 138.721592 -269.707868)
		(width 0.088646)
		(layer "In2.Cu")
		(net "M_F_CPU1_SA_DQ<18>")
	)
	(arc
		(start 136.452864 -269.699232)
		(mid 136.176423 -269.632066)
		(end 135.902192 -269.707868)
		(width 0.088646)
		(layer "In2.Cu")
		(net "M_F_CPU1_SA_DQ<18>")
	)
	(arc
		(start 138.332464 -269.699232)
		(mid 138.056023 -269.632066)
		(end 137.781792 -269.707868)
		(width 0.088646)
		(layer "In2.Cu")
		(net "M_F_CPU1_SA_DQ<18>")
	)
	(arc
		(start 137.392664 -269.699232)
		(mid 137.116223 -269.632066)
		(end 136.841992 -269.707868)
		(width 0.088646)
		(layer "In2.Cu")
		(net "M_F_CPU1_SA_DQ<18>")
	)
	(segment
		(start 181.444392 -295.916858)
		(end 179.852828 -295.916858)
		(width 0.20066)
		(layer "F.Cu")
		(net "M_F_CPU1_SA_DQ<17>")
	)
	(segment
		(start 179.852828 -295.916858)
		(end 179.421282 -295.485312)
		(width 0.20066)
		(layer "F.Cu")
		(net "M_F_CPU1_SA_DQ<17>")
	)
	(segment
		(start 176.796192 -295.491662)
		(end 176.451514 -295.491662)
		(width 0.20066)
		(layer "F.Cu")
		(net "M_F_CPU1_SA_DQ<17>")
	)
	(segment
		(start 133.365494 -268.033754)
		(end 133.365494 -268.56944)
		(width 0.20066)
		(layer "F.Cu")
		(net "M_F_CPU1_SA_DQ<17>")
	)
	(segment
		(start 133.365494 -268.56944)
		(end 133.365748 -268.569694)
		(width 0.20066)
		(layer "F.Cu")
		(net "M_F_CPU1_SA_DQ<17>")
	)
	(segment
		(start 175.67021 -296.16527)
		(end 175.421544 -295.916604)
		(width 0.20066)
		(layer "F.Cu")
		(net "M_F_CPU1_SA_DQ<17>")
	)
	(segment
		(start 181.444646 -295.916604)
		(end 181.444392 -295.916858)
		(width 0.20066)
		(layer "F.Cu")
		(net "M_F_CPU1_SA_DQ<17>")
	)
	(segment
		(start 176.816258 -295.491662)
		(end 176.796192 -295.491662)
		(width 0.101854)
		(layer "F.Cu")
		(net "M_F_CPU1_SA_DQ<17>")
	)
	(segment
		(start 179.011326 -295.485312)
		(end 179.004976 -295.491662)
		(width 0.1016)
		(layer "F.Cu")
		(net "M_F_CPU1_SA_DQ<17>")
	)
	(segment
		(start 176.145444 -296.16527)
		(end 175.67021 -296.16527)
		(width 0.20066)
		(layer "F.Cu")
		(net "M_F_CPU1_SA_DQ<17>")
	)
	(segment
		(start 176.333404 -295.97731)
		(end 176.145444 -296.16527)
		(width 0.20066)
		(layer "F.Cu")
		(net "M_F_CPU1_SA_DQ<17>")
	)
	(segment
		(start 175.421544 -295.916604)
		(end 173.900846 -295.916604)
		(width 0.20066)
		(layer "F.Cu")
		(net "M_F_CPU1_SA_DQ<17>")
	)
	(segment
		(start 176.451514 -295.491662)
		(end 176.333404 -295.609772)
		(width 0.20066)
		(layer "F.Cu")
		(net "M_F_CPU1_SA_DQ<17>")
	)
	(segment
		(start 179.421282 -295.485312)
		(end 179.011326 -295.485312)
		(width 0.20066)
		(layer "F.Cu")
		(net "M_F_CPU1_SA_DQ<17>")
	)
	(segment
		(start 179.004976 -295.491662)
		(end 176.816258 -295.491662)
		(width 0.1016)
		(layer "F.Cu")
		(net "M_F_CPU1_SA_DQ<17>")
	)
	(segment
		(start 173.900846 -295.916604)
		(end 172.795946 -295.916604)
		(width 0.20066)
		(layer "F.Cu")
		(net "M_F_CPU1_SA_DQ<17>")
	)
	(segment
		(start 176.333404 -295.609772)
		(end 176.333404 -295.97731)
		(width 0.20066)
		(layer "F.Cu")
		(net "M_F_CPU1_SA_DQ<17>")
	)
	(segment
		(start 169.34307 -295.254426)
		(end 168.637458 -295.254426)
		(width 0.18288)
		(layer "In2.Cu")
		(net "M_F_CPU1_SA_DQ<17>")
	)
	(segment
		(start 164.21608 -291.23894)
		(end 163.628832 -291.23894)
		(width 0.18288)
		(layer "In2.Cu")
		(net "M_F_CPU1_SA_DQ<17>")
	)
	(segment
		(start 155.751276 -285.504128)
		(end 155.47848 -285.504128)
		(width 0.18288)
		(layer "In2.Cu")
		(net "M_F_CPU1_SA_DQ<17>")
	)
	(segment
		(start 155.98267 -286.717486)
		(end 155.75788 -286.492696)
		(width 0.18288)
		(layer "In2.Cu")
		(net "M_F_CPU1_SA_DQ<17>")
	)
	(segment
		(start 171.537376 -295.29913)
		(end 171.006008 -295.830498)
		(width 0.18288)
		(layer "In2.Cu")
		(net "M_F_CPU1_SA_DQ<17>")
	)
	(segment
		(start 147.141438 -273.576542)
		(end 146.68119 -273.576542)
		(width 0.18288)
		(layer "In2.Cu")
		(net "M_F_CPU1_SA_DQ<17>")
	)
	(segment
		(start 154.701748 -285.436564)
		(end 154.542998 -285.053278)
		(width 0.18288)
		(layer "In2.Cu")
		(net "M_F_CPU1_SA_DQ<17>")
	)
	(segment
		(start 162.20567 -291.418264)
		(end 162.004756 -291.21735)
		(width 0.18288)
		(layer "In2.Cu")
		(net "M_F_CPU1_SA_DQ<17>")
	)
	(segment
		(start 155.47848 -285.504128)
		(end 155.260294 -285.722314)
		(width 0.18288)
		(layer "In2.Cu")
		(net "M_F_CPU1_SA_DQ<17>")
	)
	(segment
		(start 154.542998 -285.053278)
		(end 154.542998 -282.402026)
		(width 0.18288)
		(layer "In2.Cu")
		(net "M_F_CPU1_SA_DQ<17>")
	)
	(segment
		(start 140.445744 -269.280386)
		(end 140.300456 -269.135098)
		(width 0.088646)
		(layer "In2.Cu")
		(net "M_F_CPU1_SA_DQ<17>")
	)
	(segment
		(start 169.919142 -295.830498)
		(end 169.34307 -295.254426)
		(width 0.18288)
		(layer "In2.Cu")
		(net "M_F_CPU1_SA_DQ<17>")
	)
	(segment
		(start 167.205406 -293.822374)
		(end 165.370002 -293.822374)
		(width 0.18288)
		(layer "In2.Cu")
		(net "M_F_CPU1_SA_DQ<17>")
	)
	(segment
		(start 140.300456 -269.135098)
		(end 139.944094 -269.135098)
		(width 0.088646)
		(layer "In2.Cu")
		(net "M_F_CPU1_SA_DQ<17>")
	)
	(segment
		(start 149.91461 -277.773638)
		(end 148.9075 -275.342604)
		(width 0.18288)
		(layer "In2.Cu")
		(net "M_F_CPU1_SA_DQ<17>")
	)
	(segment
		(start 165.370002 -293.822374)
		(end 164.44341 -292.895782)
		(width 0.18288)
		(layer "In2.Cu")
		(net "M_F_CPU1_SA_DQ<17>")
	)
	(segment
		(start 157.723332 -288.063178)
		(end 157.328362 -288.063178)
		(width 0.18288)
		(layer "In2.Cu")
		(net "M_F_CPU1_SA_DQ<17>")
	)
	(segment
		(start 160.921954 -289.15741)
		(end 159.629856 -287.865312)
		(width 0.18288)
		(layer "In2.Cu")
		(net "M_F_CPU1_SA_DQ<17>")
	)
	(segment
		(start 155.976066 -286.001714)
		(end 155.976066 -285.728918)
		(width 0.18288)
		(layer "In2.Cu")
		(net "M_F_CPU1_SA_DQ<17>")
	)
	(segment
		(start 164.44341 -292.347142)
		(end 164.566092 -292.22446)
		(width 0.18288)
		(layer "In2.Cu")
		(net "M_F_CPU1_SA_DQ<17>")
	)
	(segment
		(start 148.9075 -275.342604)
		(end 147.141438 -273.576542)
		(width 0.18288)
		(layer "In2.Cu")
		(net "M_F_CPU1_SA_DQ<17>")
	)
	(segment
		(start 157.921198 -287.865312)
		(end 157.723332 -288.063178)
		(width 0.18288)
		(layer "In2.Cu")
		(net "M_F_CPU1_SA_DQ<17>")
	)
	(segment
		(start 134.967218 -269.061946)
		(end 134.960614 -269.057882)
		(width 0.088646)
		(layer "In2.Cu")
		(net "M_F_CPU1_SA_DQ<17>")
	)
	(segment
		(start 156.746448 -286.4993)
		(end 156.473652 -286.4993)
		(width 0.18288)
		(layer "In2.Cu")
		(net "M_F_CPU1_SA_DQ<17>")
	)
	(segment
		(start 172.178472 -295.29913)
		(end 171.537376 -295.29913)
		(width 0.18288)
		(layer "In2.Cu")
		(net "M_F_CPU1_SA_DQ<17>")
	)
	(segment
		(start 159.629856 -287.865312)
		(end 157.921198 -287.865312)
		(width 0.18288)
		(layer "In2.Cu")
		(net "M_F_CPU1_SA_DQ<17>")
	)
	(segment
		(start 164.566092 -291.588952)
		(end 164.21608 -291.23894)
		(width 0.18288)
		(layer "In2.Cu")
		(net "M_F_CPU1_SA_DQ<17>")
	)
	(segment
		(start 156.971238 -286.72409)
		(end 156.746448 -286.4993)
		(width 0.18288)
		(layer "In2.Cu")
		(net "M_F_CPU1_SA_DQ<17>")
	)
	(segment
		(start 156.971238 -286.996886)
		(end 156.971238 -286.72409)
		(width 0.18288)
		(layer "In2.Cu")
		(net "M_F_CPU1_SA_DQ<17>")
	)
	(segment
		(start 157.328362 -288.063178)
		(end 156.753052 -287.487868)
		(width 0.18288)
		(layer "In2.Cu")
		(net "M_F_CPU1_SA_DQ<17>")
	)
	(segment
		(start 155.976066 -285.728918)
		(end 155.751276 -285.504128)
		(width 0.18288)
		(layer "In2.Cu")
		(net "M_F_CPU1_SA_DQ<17>")
	)
	(segment
		(start 154.542998 -282.402026)
		(end 149.91461 -277.773638)
		(width 0.18288)
		(layer "In2.Cu")
		(net "M_F_CPU1_SA_DQ<17>")
	)
	(segment
		(start 142.385034 -269.280386)
		(end 140.900404 -269.280386)
		(width 0.18288)
		(layer "In2.Cu")
		(net "M_F_CPU1_SA_DQ<17>")
	)
	(segment
		(start 156.255466 -286.717486)
		(end 155.98267 -286.717486)
		(width 0.18288)
		(layer "In2.Cu")
		(net "M_F_CPU1_SA_DQ<17>")
	)
	(segment
		(start 156.753052 -287.215072)
		(end 156.971238 -286.996886)
		(width 0.18288)
		(layer "In2.Cu")
		(net "M_F_CPU1_SA_DQ<17>")
	)
	(segment
		(start 163.449508 -291.418264)
		(end 162.20567 -291.418264)
		(width 0.18288)
		(layer "In2.Cu")
		(net "M_F_CPU1_SA_DQ<17>")
	)
	(segment
		(start 164.566092 -292.22446)
		(end 164.566092 -291.588952)
		(width 0.18288)
		(layer "In2.Cu")
		(net "M_F_CPU1_SA_DQ<17>")
	)
	(segment
		(start 172.795946 -295.916604)
		(end 172.178472 -295.29913)
		(width 0.18288)
		(layer "In2.Cu")
		(net "M_F_CPU1_SA_DQ<17>")
	)
	(segment
		(start 156.473652 -286.4993)
		(end 156.255466 -286.717486)
		(width 0.18288)
		(layer "In2.Cu")
		(net "M_F_CPU1_SA_DQ<17>")
	)
	(segment
		(start 171.006008 -295.830498)
		(end 169.919142 -295.830498)
		(width 0.18288)
		(layer "In2.Cu")
		(net "M_F_CPU1_SA_DQ<17>")
	)
	(segment
		(start 168.637458 -295.254426)
		(end 167.205406 -293.822374)
		(width 0.18288)
		(layer "In2.Cu")
		(net "M_F_CPU1_SA_DQ<17>")
	)
	(segment
		(start 163.628832 -291.23894)
		(end 163.449508 -291.418264)
		(width 0.18288)
		(layer "In2.Cu")
		(net "M_F_CPU1_SA_DQ<17>")
	)
	(segment
		(start 155.75788 -286.2199)
		(end 155.976066 -286.001714)
		(width 0.18288)
		(layer "In2.Cu")
		(net "M_F_CPU1_SA_DQ<17>")
	)
	(segment
		(start 140.900404 -269.280386)
		(end 140.445744 -269.280386)
		(width 0.088646)
		(layer "In2.Cu")
		(net "M_F_CPU1_SA_DQ<17>")
	)
	(segment
		(start 155.75788 -286.492696)
		(end 155.75788 -286.2199)
		(width 0.18288)
		(layer "In2.Cu")
		(net "M_F_CPU1_SA_DQ<17>")
	)
	(segment
		(start 155.260294 -285.722314)
		(end 154.987498 -285.722314)
		(width 0.18288)
		(layer "In2.Cu")
		(net "M_F_CPU1_SA_DQ<17>")
	)
	(segment
		(start 154.987498 -285.722314)
		(end 154.701748 -285.436564)
		(width 0.18288)
		(layer "In2.Cu")
		(net "M_F_CPU1_SA_DQ<17>")
	)
	(segment
		(start 135.902192 -269.059152)
		(end 135.902446 -269.059152)
		(width 0.088646)
		(layer "In2.Cu")
		(net "M_F_CPU1_SA_DQ<17>")
	)
	(segment
		(start 161.273236 -291.21735)
		(end 160.921954 -290.866068)
		(width 0.18288)
		(layer "In2.Cu")
		(net "M_F_CPU1_SA_DQ<17>")
	)
	(segment
		(start 156.753052 -287.487868)
		(end 156.753052 -287.215072)
		(width 0.18288)
		(layer "In2.Cu")
		(net "M_F_CPU1_SA_DQ<17>")
	)
	(segment
		(start 146.68119 -273.576542)
		(end 142.385034 -269.280386)
		(width 0.18288)
		(layer "In2.Cu")
		(net "M_F_CPU1_SA_DQ<17>")
	)
	(segment
		(start 160.921954 -290.866068)
		(end 160.921954 -289.15741)
		(width 0.18288)
		(layer "In2.Cu")
		(net "M_F_CPU1_SA_DQ<17>")
	)
	(segment
		(start 164.44341 -292.895782)
		(end 164.44341 -292.347142)
		(width 0.18288)
		(layer "In2.Cu")
		(net "M_F_CPU1_SA_DQ<17>")
	)
	(segment
		(start 162.004756 -291.21735)
		(end 161.273236 -291.21735)
		(width 0.18288)
		(layer "In2.Cu")
		(net "M_F_CPU1_SA_DQ<17>")
	)
	(arc
		(start 138.347196 -269.059152)
		(mid 138.064494 -269.134928)
		(end 137.781792 -269.059152)
		(width 0.088646)
		(layer "In2.Cu")
		(net "M_F_CPU1_SA_DQ<17>")
	)
	(arc
		(start 136.841992 -269.059152)
		(mid 136.654794 -269.009009)
		(end 136.467596 -269.059152)
		(width 0.088646)
		(layer "In2.Cu")
		(net "M_F_CPU1_SA_DQ<17>")
	)
	(arc
		(start 135.527796 -269.059152)
		(mid 135.247882 -269.134921)
		(end 134.967218 -269.061946)
		(width 0.088646)
		(layer "In2.Cu")
		(net "M_F_CPU1_SA_DQ<17>")
	)
	(arc
		(start 139.661392 -269.059152)
		(mid 139.474194 -269.009009)
		(end 139.286996 -269.059152)
		(width 0.088646)
		(layer "In2.Cu")
		(net "M_F_CPU1_SA_DQ<17>")
	)
	(arc
		(start 134.32409 -268.995398)
		(mid 134.141086 -269.018563)
		(end 133.964426 -268.965426)
		(width 0.088646)
		(layer "In2.Cu")
		(net "M_F_CPU1_SA_DQ<17>")
	)
	(arc
		(start 139.895072 -269.133066)
		(mid 139.774168 -269.108947)
		(end 139.661392 -269.059152)
		(width 0.088646)
		(layer "In2.Cu")
		(net "M_F_CPU1_SA_DQ<17>")
	)
	(arc
		(start 133.964426 -268.965426)
		(mid 133.656939 -268.779887)
		(end 133.365748 -268.569694)
		(width 0.088646)
		(layer "In2.Cu")
		(net "M_F_CPU1_SA_DQ<17>")
	)
	(arc
		(start 136.467596 -269.059152)
		(mid 136.184894 -269.134928)
		(end 135.902192 -269.059152)
		(width 0.088646)
		(layer "In2.Cu")
		(net "M_F_CPU1_SA_DQ<17>")
	)
	(arc
		(start 137.407396 -269.059152)
		(mid 137.124694 -269.134928)
		(end 136.841992 -269.059152)
		(width 0.088646)
		(layer "In2.Cu")
		(net "M_F_CPU1_SA_DQ<17>")
	)
	(arc
		(start 137.781792 -269.059152)
		(mid 137.594594 -269.009009)
		(end 137.407396 -269.059152)
		(width 0.088646)
		(layer "In2.Cu")
		(net "M_F_CPU1_SA_DQ<17>")
	)
	(arc
		(start 139.944094 -269.135098)
		(mid 139.919561 -269.13461)
		(end 139.895072 -269.133066)
		(width 0.088646)
		(layer "In2.Cu")
		(net "M_F_CPU1_SA_DQ<17>")
	)
	(arc
		(start 138.721592 -269.059152)
		(mid 138.534394 -269.009009)
		(end 138.347196 -269.059152)
		(width 0.088646)
		(layer "In2.Cu")
		(net "M_F_CPU1_SA_DQ<17>")
	)
	(arc
		(start 135.902446 -269.059152)
		(mid 135.715138 -269.009009)
		(end 135.527796 -269.059152)
		(width 0.088646)
		(layer "In2.Cu")
		(net "M_F_CPU1_SA_DQ<17>")
	)
	(arc
		(start 134.960614 -269.057882)
		(mid 134.649225 -268.956627)
		(end 134.32409 -268.995398)
		(width 0.088646)
		(layer "In2.Cu")
		(net "M_F_CPU1_SA_DQ<17>")
	)
	(arc
		(start 139.286996 -269.059152)
		(mid 139.004294 -269.134928)
		(end 138.721592 -269.059152)
		(width 0.088646)
		(layer "In2.Cu")
		(net "M_F_CPU1_SA_DQ<17>")
	)
	(segment
		(start 176.796192 -297.191684)
		(end 176.451514 -297.191684)
		(width 0.20066)
		(layer "F.Cu")
		(net "M_F_CPU1_SA_DQ<16>")
	)
	(segment
		(start 176.333404 -297.677332)
		(end 176.145444 -297.865292)
		(width 0.20066)
		(layer "F.Cu")
		(net "M_F_CPU1_SA_DQ<16>")
	)
	(segment
		(start 176.451514 -297.191684)
		(end 176.333404 -297.309794)
		(width 0.20066)
		(layer "F.Cu")
		(net "M_F_CPU1_SA_DQ<16>")
	)
	(segment
		(start 173.900846 -297.616626)
		(end 172.795946 -297.616626)
		(width 0.20066)
		(layer "F.Cu")
		(net "M_F_CPU1_SA_DQ<16>")
	)
	(segment
		(start 133.835648 -268.84757)
		(end 133.835648 -269.383256)
		(width 0.20066)
		(layer "F.Cu")
		(net "M_F_CPU1_SA_DQ<16>")
	)
	(segment
		(start 181.444646 -297.616626)
		(end 181.444392 -297.61688)
		(width 0.20066)
		(layer "F.Cu")
		(net "M_F_CPU1_SA_DQ<16>")
	)
	(segment
		(start 176.145444 -297.865292)
		(end 175.67021 -297.865292)
		(width 0.20066)
		(layer "F.Cu")
		(net "M_F_CPU1_SA_DQ<16>")
	)
	(segment
		(start 133.835648 -269.383256)
		(end 133.835394 -269.38351)
		(width 0.20066)
		(layer "F.Cu")
		(net "M_F_CPU1_SA_DQ<16>")
	)
	(segment
		(start 176.333404 -297.309794)
		(end 176.333404 -297.677332)
		(width 0.20066)
		(layer "F.Cu")
		(net "M_F_CPU1_SA_DQ<16>")
	)
	(segment
		(start 179.852828 -297.61688)
		(end 179.421282 -297.185334)
		(width 0.20066)
		(layer "F.Cu")
		(net "M_F_CPU1_SA_DQ<16>")
	)
	(segment
		(start 175.421544 -297.616626)
		(end 173.900846 -297.616626)
		(width 0.20066)
		(layer "F.Cu")
		(net "M_F_CPU1_SA_DQ<16>")
	)
	(segment
		(start 181.444392 -297.61688)
		(end 179.852828 -297.61688)
		(width 0.20066)
		(layer "F.Cu")
		(net "M_F_CPU1_SA_DQ<16>")
	)
	(segment
		(start 179.004976 -297.191684)
		(end 176.843182 -297.191684)
		(width 0.1016)
		(layer "F.Cu")
		(net "M_F_CPU1_SA_DQ<16>")
	)
	(segment
		(start 179.421282 -297.185334)
		(end 179.011326 -297.185334)
		(width 0.20066)
		(layer "F.Cu")
		(net "M_F_CPU1_SA_DQ<16>")
	)
	(segment
		(start 179.011326 -297.185334)
		(end 179.004976 -297.191684)
		(width 0.1016)
		(layer "F.Cu")
		(net "M_F_CPU1_SA_DQ<16>")
	)
	(segment
		(start 175.67021 -297.865292)
		(end 175.421544 -297.616626)
		(width 0.20066)
		(layer "F.Cu")
		(net "M_F_CPU1_SA_DQ<16>")
	)
	(segment
		(start 176.843182 -297.191684)
		(end 176.796192 -297.191684)
		(width 0.101854)
		(layer "F.Cu")
		(net "M_F_CPU1_SA_DQ<16>")
	)
	(segment
		(start 169.647108 -297.18762)
		(end 168.9735 -297.18762)
		(width 0.18288)
		(layer "In2.Cu")
		(net "M_F_CPU1_SA_DQ<16>")
	)
	(segment
		(start 163.571936 -295.617646)
		(end 164.055298 -295.134284)
		(width 0.18288)
		(layer "In2.Cu")
		(net "M_F_CPU1_SA_DQ<16>")
	)
	(segment
		(start 164.758624 -295.782238)
		(end 164.189918 -296.350944)
		(width 0.18288)
		(layer "In2.Cu")
		(net "M_F_CPU1_SA_DQ<16>")
	)
	(segment
		(start 140.230098 -269.822168)
		(end 139.944602 -269.822168)
		(width 0.088646)
		(layer "In2.Cu")
		(net "M_F_CPU1_SA_DQ<16>")
	)
	(segment
		(start 153.526998 -285.359602)
		(end 153.526998 -282.823158)
		(width 0.18288)
		(layer "In2.Cu")
		(net "M_F_CPU1_SA_DQ<16>")
	)
	(segment
		(start 135.447278 -269.881858)
		(end 135.432546 -269.873222)
		(width 0.088646)
		(layer "In2.Cu")
		(net "M_F_CPU1_SA_DQ<16>")
	)
	(segment
		(start 168.025318 -296.61485)
		(end 167.731948 -296.32148)
		(width 0.18288)
		(layer "In2.Cu")
		(net "M_F_CPU1_SA_DQ<16>")
	)
	(segment
		(start 136.387078 -269.881858)
		(end 136.372346 -269.873222)
		(width 0.088646)
		(layer "In2.Cu")
		(net "M_F_CPU1_SA_DQ<16>")
	)
	(segment
		(start 166.081456 -296.83202)
		(end 165.031674 -295.782238)
		(width 0.18288)
		(layer "In2.Cu")
		(net "M_F_CPU1_SA_DQ<16>")
	)
	(segment
		(start 171.417488 -297.02887)
		(end 170.589448 -297.85691)
		(width 0.18288)
		(layer "In2.Cu")
		(net "M_F_CPU1_SA_DQ<16>")
	)
	(segment
		(start 138.266678 -269.881858)
		(end 138.251946 -269.873222)
		(width 0.088646)
		(layer "In2.Cu")
		(net "M_F_CPU1_SA_DQ<16>")
	)
	(segment
		(start 167.731948 -296.32148)
		(end 167.27678 -296.32148)
		(width 0.18288)
		(layer "In2.Cu")
		(net "M_F_CPU1_SA_DQ<16>")
	)
	(segment
		(start 157.759146 -289.956748)
		(end 153.784808 -285.98241)
		(width 0.18288)
		(layer "In2.Cu")
		(net "M_F_CPU1_SA_DQ<16>")
	)
	(segment
		(start 157.759146 -290.183824)
		(end 157.759146 -289.956748)
		(width 0.18288)
		(layer "In2.Cu")
		(net "M_F_CPU1_SA_DQ<16>")
	)
	(segment
		(start 170.589448 -297.85691)
		(end 170.316398 -297.85691)
		(width 0.18288)
		(layer "In2.Cu")
		(net "M_F_CPU1_SA_DQ<16>")
	)
	(segment
		(start 153.526998 -282.823158)
		(end 148.912072 -278.208232)
		(width 0.18288)
		(layer "In2.Cu")
		(net "M_F_CPU1_SA_DQ<16>")
	)
	(segment
		(start 140.900404 -270.016986)
		(end 140.424916 -270.016986)
		(width 0.088646)
		(layer "In2.Cu")
		(net "M_F_CPU1_SA_DQ<16>")
	)
	(segment
		(start 158.222188 -290.646866)
		(end 157.759146 -290.183824)
		(width 0.18288)
		(layer "In2.Cu")
		(net "M_F_CPU1_SA_DQ<16>")
	)
	(segment
		(start 164.055298 -294.78732)
		(end 163.491418 -294.410384)
		(width 0.18288)
		(layer "In2.Cu")
		(net "M_F_CPU1_SA_DQ<16>")
	)
	(segment
		(start 172.795946 -297.616626)
		(end 172.20819 -297.02887)
		(width 0.18288)
		(layer "In2.Cu")
		(net "M_F_CPU1_SA_DQ<16>")
	)
	(segment
		(start 166.76624 -296.83202)
		(end 166.081456 -296.83202)
		(width 0.18288)
		(layer "In2.Cu")
		(net "M_F_CPU1_SA_DQ<16>")
	)
	(segment
		(start 134.148322 -269.38351)
		(end 133.835394 -269.38351)
		(width 0.088646)
		(layer "In2.Cu")
		(net "M_F_CPU1_SA_DQ<16>")
	)
	(segment
		(start 142.144242 -270.016986)
		(end 140.900404 -270.016986)
		(width 0.18288)
		(layer "In2.Cu")
		(net "M_F_CPU1_SA_DQ<16>")
	)
	(segment
		(start 163.571936 -296.139362)
		(end 163.571936 -295.617646)
		(width 0.18288)
		(layer "In2.Cu")
		(net "M_F_CPU1_SA_DQ<16>")
	)
	(segment
		(start 148.912072 -278.208232)
		(end 147.90547 -275.778214)
		(width 0.18288)
		(layer "In2.Cu")
		(net "M_F_CPU1_SA_DQ<16>")
	)
	(segment
		(start 163.783518 -296.350944)
		(end 163.571936 -296.139362)
		(width 0.18288)
		(layer "In2.Cu")
		(net "M_F_CPU1_SA_DQ<16>")
	)
	(segment
		(start 164.055298 -295.134284)
		(end 164.055298 -294.78732)
		(width 0.18288)
		(layer "In2.Cu")
		(net "M_F_CPU1_SA_DQ<16>")
	)
	(segment
		(start 134.507478 -269.881858)
		(end 134.492746 -269.873222)
		(width 0.088646)
		(layer "In2.Cu")
		(net "M_F_CPU1_SA_DQ<16>")
	)
	(segment
		(start 164.189918 -296.350944)
		(end 163.783518 -296.350944)
		(width 0.18288)
		(layer "In2.Cu")
		(net "M_F_CPU1_SA_DQ<16>")
	)
	(segment
		(start 170.316398 -297.85691)
		(end 169.647108 -297.18762)
		(width 0.18288)
		(layer "In2.Cu")
		(net "M_F_CPU1_SA_DQ<16>")
	)
	(segment
		(start 168.9735 -297.18762)
		(end 168.794938 -297.366182)
		(width 0.18288)
		(layer "In2.Cu")
		(net "M_F_CPU1_SA_DQ<16>")
	)
	(segment
		(start 159.056578 -290.646866)
		(end 158.222188 -290.646866)
		(width 0.18288)
		(layer "In2.Cu")
		(net "M_F_CPU1_SA_DQ<16>")
	)
	(segment
		(start 140.424916 -270.016986)
		(end 140.230098 -269.822168)
		(width 0.088646)
		(layer "In2.Cu")
		(net "M_F_CPU1_SA_DQ<16>")
	)
	(segment
		(start 160.396936 -291.987224)
		(end 159.056578 -290.646866)
		(width 0.18288)
		(layer "In2.Cu")
		(net "M_F_CPU1_SA_DQ<16>")
	)
	(segment
		(start 172.20819 -297.02887)
		(end 171.417488 -297.02887)
		(width 0.18288)
		(layer "In2.Cu")
		(net "M_F_CPU1_SA_DQ<16>")
	)
	(segment
		(start 168.025318 -297.74007)
		(end 168.025318 -296.61485)
		(width 0.18288)
		(layer "In2.Cu")
		(net "M_F_CPU1_SA_DQ<16>")
	)
	(segment
		(start 168.794938 -297.366182)
		(end 168.794938 -297.79341)
		(width 0.18288)
		(layer "In2.Cu")
		(net "M_F_CPU1_SA_DQ<16>")
	)
	(segment
		(start 134.2136 -269.448788)
		(end 134.148322 -269.38351)
		(width 0.088646)
		(layer "In2.Cu")
		(net "M_F_CPU1_SA_DQ<16>")
	)
	(segment
		(start 168.601898 -297.98645)
		(end 168.271698 -297.98645)
		(width 0.18288)
		(layer "In2.Cu")
		(net "M_F_CPU1_SA_DQ<16>")
	)
	(segment
		(start 168.271698 -297.98645)
		(end 168.025318 -297.74007)
		(width 0.18288)
		(layer "In2.Cu")
		(net "M_F_CPU1_SA_DQ<16>")
	)
	(segment
		(start 162.055302 -293.81577)
		(end 160.396936 -292.157404)
		(width 0.18288)
		(layer "In2.Cu")
		(net "M_F_CPU1_SA_DQ<16>")
	)
	(segment
		(start 167.27678 -296.32148)
		(end 166.76624 -296.83202)
		(width 0.18288)
		(layer "In2.Cu")
		(net "M_F_CPU1_SA_DQ<16>")
	)
	(segment
		(start 163.491418 -294.410384)
		(end 162.055302 -293.81577)
		(width 0.18288)
		(layer "In2.Cu")
		(net "M_F_CPU1_SA_DQ<16>")
	)
	(segment
		(start 147.90547 -275.778214)
		(end 142.144242 -270.016986)
		(width 0.18288)
		(layer "In2.Cu")
		(net "M_F_CPU1_SA_DQ<16>")
	)
	(segment
		(start 153.784808 -285.98241)
		(end 153.526998 -285.359602)
		(width 0.18288)
		(layer "In2.Cu")
		(net "M_F_CPU1_SA_DQ<16>")
	)
	(segment
		(start 139.206478 -269.881858)
		(end 139.191746 -269.873222)
		(width 0.088646)
		(layer "In2.Cu")
		(net "M_F_CPU1_SA_DQ<16>")
	)
	(segment
		(start 160.396936 -292.157404)
		(end 160.396936 -291.987224)
		(width 0.18288)
		(layer "In2.Cu")
		(net "M_F_CPU1_SA_DQ<16>")
	)
	(segment
		(start 165.031674 -295.782238)
		(end 164.758624 -295.782238)
		(width 0.18288)
		(layer "In2.Cu")
		(net "M_F_CPU1_SA_DQ<16>")
	)
	(segment
		(start 137.326878 -269.881858)
		(end 137.312146 -269.873222)
		(width 0.088646)
		(layer "In2.Cu")
		(net "M_F_CPU1_SA_DQ<16>")
	)
	(segment
		(start 168.794938 -297.79341)
		(end 168.601898 -297.98645)
		(width 0.18288)
		(layer "In2.Cu")
		(net "M_F_CPU1_SA_DQ<16>")
	)
	(arc
		(start 139.191746 -269.873222)
		(mid 139.004548 -269.823079)
		(end 138.81735 -269.873222)
		(width 0.088646)
		(layer "In2.Cu")
		(net "M_F_CPU1_SA_DQ<16>")
	)
	(arc
		(start 135.05815 -269.873222)
		(mid 134.783921 -269.949147)
		(end 134.507478 -269.881858)
		(width 0.088646)
		(layer "In2.Cu")
		(net "M_F_CPU1_SA_DQ<16>")
	)
	(arc
		(start 138.81735 -269.873222)
		(mid 138.543121 -269.949147)
		(end 138.266678 -269.881858)
		(width 0.088646)
		(layer "In2.Cu")
		(net "M_F_CPU1_SA_DQ<16>")
	)
	(arc
		(start 136.93775 -269.873222)
		(mid 136.663521 -269.949147)
		(end 136.387078 -269.881858)
		(width 0.088646)
		(layer "In2.Cu")
		(net "M_F_CPU1_SA_DQ<16>")
	)
	(arc
		(start 138.251946 -269.873222)
		(mid 138.064748 -269.823079)
		(end 137.87755 -269.873222)
		(width 0.088646)
		(layer "In2.Cu")
		(net "M_F_CPU1_SA_DQ<16>")
	)
	(arc
		(start 135.432546 -269.873222)
		(mid 135.245348 -269.823079)
		(end 135.05815 -269.873222)
		(width 0.088646)
		(layer "In2.Cu")
		(net "M_F_CPU1_SA_DQ<16>")
	)
	(arc
		(start 139.944602 -269.822168)
		(mid 139.847521 -269.835364)
		(end 139.75715 -269.873222)
		(width 0.088646)
		(layer "In2.Cu")
		(net "M_F_CPU1_SA_DQ<16>")
	)
	(arc
		(start 137.312146 -269.873222)
		(mid 137.124948 -269.823079)
		(end 136.93775 -269.873222)
		(width 0.088646)
		(layer "In2.Cu")
		(net "M_F_CPU1_SA_DQ<16>")
	)
	(arc
		(start 135.99795 -269.873222)
		(mid 135.723721 -269.949147)
		(end 135.447278 -269.881858)
		(width 0.088646)
		(layer "In2.Cu")
		(net "M_F_CPU1_SA_DQ<16>")
	)
	(arc
		(start 137.87755 -269.873222)
		(mid 137.603321 -269.949147)
		(end 137.326878 -269.881858)
		(width 0.088646)
		(layer "In2.Cu")
		(net "M_F_CPU1_SA_DQ<16>")
	)
	(arc
		(start 139.75715 -269.873222)
		(mid 139.482921 -269.949147)
		(end 139.206478 -269.881858)
		(width 0.088646)
		(layer "In2.Cu")
		(net "M_F_CPU1_SA_DQ<16>")
	)
	(arc
		(start 136.372346 -269.873222)
		(mid 136.185148 -269.823079)
		(end 135.99795 -269.873222)
		(width 0.088646)
		(layer "In2.Cu")
		(net "M_F_CPU1_SA_DQ<16>")
	)
	(arc
		(start 134.492746 -269.873222)
		(mid 134.302839 -269.694116)
		(end 134.2136 -269.448788)
		(width 0.088646)
		(layer "In2.Cu")
		(net "M_F_CPU1_SA_DQ<16>")
	)
	(segment
		(start 176.896014 -298.466764)
		(end 178.000914 -298.466764)
		(width 0.20066)
		(layer "F.Cu")
		(net "M_F_CPU1_SA_DQ<15>")
	)
	(segment
		(start 182.442866 -298.891706)
		(end 182.455058 -298.903898)
		(width 0.1016)
		(layer "F.Cu")
		(net "M_F_CPU1_SA_DQ<15>")
	)
	(segment
		(start 178.000914 -298.466764)
		(end 179.699158 -298.466764)
		(width 0.20066)
		(layer "F.Cu")
		(net "M_F_CPU1_SA_DQ<15>")
	)
	(segment
		(start 183.136286 -298.903898)
		(end 183.340248 -298.699936)
		(width 0.20066)
		(layer "F.Cu")
		(net "M_F_CPU1_SA_DQ<15>")
	)
	(segment
		(start 183.958484 -298.214796)
		(end 184.210452 -298.466764)
		(width 0.20066)
		(layer "F.Cu")
		(net "M_F_CPU1_SA_DQ<15>")
	)
	(segment
		(start 183.340248 -298.699936)
		(end 183.340248 -298.448984)
		(width 0.20066)
		(layer "F.Cu")
		(net "M_F_CPU1_SA_DQ<15>")
	)
	(segment
		(start 179.699158 -298.466764)
		(end 180.131212 -298.898818)
		(width 0.20066)
		(layer "F.Cu")
		(net "M_F_CPU1_SA_DQ<15>")
	)
	(segment
		(start 180.131212 -298.898818)
		(end 180.423058 -298.898818)
		(width 0.20066)
		(layer "F.Cu")
		(net "M_F_CPU1_SA_DQ<15>")
	)
	(segment
		(start 180.434996 -298.891706)
		(end 182.442866 -298.891706)
		(width 0.1016)
		(layer "F.Cu")
		(net "M_F_CPU1_SA_DQ<15>")
	)
	(segment
		(start 131.485894 -268.56944)
		(end 131.486148 -268.569694)
		(width 0.20066)
		(layer "F.Cu")
		(net "M_F_CPU1_SA_DQ<15>")
	)
	(segment
		(start 183.574436 -298.214796)
		(end 183.958484 -298.214796)
		(width 0.20066)
		(layer "F.Cu")
		(net "M_F_CPU1_SA_DQ<15>")
	)
	(segment
		(start 183.340248 -298.448984)
		(end 183.574436 -298.214796)
		(width 0.20066)
		(layer "F.Cu")
		(net "M_F_CPU1_SA_DQ<15>")
	)
	(segment
		(start 182.455058 -298.903898)
		(end 183.136286 -298.903898)
		(width 0.20066)
		(layer "F.Cu")
		(net "M_F_CPU1_SA_DQ<15>")
	)
	(segment
		(start 180.427884 -298.898818)
		(end 180.434996 -298.891706)
		(width 0.1016)
		(layer "F.Cu")
		(net "M_F_CPU1_SA_DQ<15>")
	)
	(segment
		(start 131.485894 -268.033754)
		(end 131.485894 -268.56944)
		(width 0.20066)
		(layer "F.Cu")
		(net "M_F_CPU1_SA_DQ<15>")
	)
	(segment
		(start 184.210452 -298.466764)
		(end 185.544714 -298.466764)
		(width 0.20066)
		(layer "F.Cu")
		(net "M_F_CPU1_SA_DQ<15>")
	)
	(segment
		(start 180.423058 -298.898818)
		(end 180.427884 -298.898818)
		(width 0.101854)
		(layer "F.Cu")
		(net "M_F_CPU1_SA_DQ<15>")
	)
	(segment
		(start 135.057896 -268.245336)
		(end 135.052054 -268.248638)
		(width 0.088646)
		(layer "In4.Cu")
		(net "M_F_CPU1_SA_DQ<15>")
	)
	(segment
		(start 141.010132 -270.488918)
		(end 138.888724 -268.36751)
		(width 0.088646)
		(layer "In4.Cu")
		(net "M_F_CPU1_SA_DQ<15>")
	)
	(segment
		(start 173.949614 -299.521626)
		(end 173.728888 -299.742352)
		(width 0.18288)
		(layer "In4.Cu")
		(net "M_F_CPU1_SA_DQ<15>")
	)
	(segment
		(start 156.965142 -291.404802)
		(end 157.135576 -291.234368)
		(width 0.18288)
		(layer "In4.Cu")
		(net "M_F_CPU1_SA_DQ<15>")
	)
	(segment
		(start 166.865046 -297.781726)
		(end 166.242238 -297.158918)
		(width 0.18288)
		(layer "In4.Cu")
		(net "M_F_CPU1_SA_DQ<15>")
	)
	(segment
		(start 165.564312 -296.27449)
		(end 165.005258 -296.27449)
		(width 0.18288)
		(layer "In4.Cu")
		(net "M_F_CPU1_SA_DQ<15>")
	)
	(segment
		(start 154.873452 -288.713672)
		(end 150.785068 -278.844248)
		(width 0.18288)
		(layer "In4.Cu")
		(net "M_F_CPU1_SA_DQ<15>")
	)
	(segment
		(start 133.184138 -268.242034)
		(end 133.17855 -268.245336)
		(width 0.088646)
		(layer "In4.Cu")
		(net "M_F_CPU1_SA_DQ<15>")
	)
	(segment
		(start 158.719266 -292.559486)
		(end 157.887162 -291.727382)
		(width 0.18288)
		(layer "In4.Cu")
		(net "M_F_CPU1_SA_DQ<15>")
	)
	(segment
		(start 157.455616 -291.895276)
		(end 157.197044 -291.895276)
		(width 0.18288)
		(layer "In4.Cu")
		(net "M_F_CPU1_SA_DQ<15>")
	)
	(segment
		(start 169.405046 -300.003718)
		(end 168.873678 -299.47235)
		(width 0.18288)
		(layer "In4.Cu")
		(net "M_F_CPU1_SA_DQ<15>")
	)
	(segment
		(start 135.44296 -268.251432)
		(end 135.432546 -268.245336)
		(width 0.088646)
		(layer "In4.Cu")
		(net "M_F_CPU1_SA_DQ<15>")
	)
	(segment
		(start 163.669218 -295.297606)
		(end 161.895282 -293.52367)
		(width 0.18288)
		(layer "In4.Cu")
		(net "M_F_CPU1_SA_DQ<15>")
	)
	(segment
		(start 172.278294 -300.003718)
		(end 169.405046 -300.003718)
		(width 0.18288)
		(layer "In4.Cu")
		(net "M_F_CPU1_SA_DQ<15>")
	)
	(segment
		(start 144.336516 -272.395696)
		(end 142.91691 -272.395696)
		(width 0.18288)
		(layer "In4.Cu")
		(net "M_F_CPU1_SA_DQ<15>")
	)
	(segment
		(start 150.785068 -278.844248)
		(end 144.336516 -272.395696)
		(width 0.18288)
		(layer "In4.Cu")
		(net "M_F_CPU1_SA_DQ<15>")
	)
	(segment
		(start 157.135576 -290.975796)
		(end 154.873452 -288.713672)
		(width 0.18288)
		(layer "In4.Cu")
		(net "M_F_CPU1_SA_DQ<15>")
	)
	(segment
		(start 161.895282 -293.52367)
		(end 161.047176 -293.52367)
		(width 0.18288)
		(layer "In4.Cu")
		(net "M_F_CPU1_SA_DQ<15>")
	)
	(segment
		(start 132.23875 -268.245336)
		(end 132.223764 -268.253972)
		(width 0.088646)
		(layer "In4.Cu")
		(net "M_F_CPU1_SA_DQ<15>")
	)
	(segment
		(start 157.887162 -291.727382)
		(end 157.62351 -291.727382)
		(width 0.18288)
		(layer "In4.Cu")
		(net "M_F_CPU1_SA_DQ<15>")
	)
	(segment
		(start 134.123938 -268.242034)
		(end 134.112254 -268.248638)
		(width 0.088646)
		(layer "In4.Cu")
		(net "M_F_CPU1_SA_DQ<15>")
	)
	(segment
		(start 168.873678 -299.112178)
		(end 167.543226 -297.781726)
		(width 0.18288)
		(layer "In4.Cu")
		(net "M_F_CPU1_SA_DQ<15>")
	)
	(segment
		(start 168.873678 -299.47235)
		(end 168.873678 -299.112178)
		(width 0.18288)
		(layer "In4.Cu")
		(net "M_F_CPU1_SA_DQ<15>")
	)
	(segment
		(start 138.888724 -268.36751)
		(end 138.708384 -268.36751)
		(width 0.088646)
		(layer "In4.Cu")
		(net "M_F_CPU1_SA_DQ<15>")
	)
	(segment
		(start 135.061706 -268.24305)
		(end 135.057896 -268.245336)
		(width 0.088646)
		(layer "In4.Cu")
		(net "M_F_CPU1_SA_DQ<15>")
	)
	(segment
		(start 175.841152 -299.521626)
		(end 175.39589 -299.521626)
		(width 0.18288)
		(layer "In4.Cu")
		(net "M_F_CPU1_SA_DQ<15>")
	)
	(segment
		(start 157.135576 -291.234368)
		(end 157.135576 -290.975796)
		(width 0.18288)
		(layer "In4.Cu")
		(net "M_F_CPU1_SA_DQ<15>")
	)
	(segment
		(start 174.425864 -299.521626)
		(end 173.949614 -299.521626)
		(width 0.18288)
		(layer "In4.Cu")
		(net "M_F_CPU1_SA_DQ<15>")
	)
	(segment
		(start 156.965142 -291.663374)
		(end 156.965142 -291.404802)
		(width 0.18288)
		(layer "In4.Cu")
		(net "M_F_CPU1_SA_DQ<15>")
	)
	(segment
		(start 165.005258 -296.27449)
		(end 164.028374 -295.297606)
		(width 0.18288)
		(layer "In4.Cu")
		(net "M_F_CPU1_SA_DQ<15>")
	)
	(segment
		(start 175.39589 -299.521626)
		(end 175.093884 -299.21962)
		(width 0.18288)
		(layer "In4.Cu")
		(net "M_F_CPU1_SA_DQ<15>")
	)
	(segment
		(start 173.728888 -299.742352)
		(end 172.53966 -299.742352)
		(width 0.18288)
		(layer "In4.Cu")
		(net "M_F_CPU1_SA_DQ<15>")
	)
	(segment
		(start 161.047176 -293.52367)
		(end 158.719266 -292.559486)
		(width 0.18288)
		(layer "In4.Cu")
		(net "M_F_CPU1_SA_DQ<15>")
	)
	(segment
		(start 157.197044 -291.895276)
		(end 156.965142 -291.663374)
		(width 0.18288)
		(layer "In4.Cu")
		(net "M_F_CPU1_SA_DQ<15>")
	)
	(segment
		(start 142.91691 -272.395696)
		(end 141.010132 -270.488918)
		(width 0.18288)
		(layer "In4.Cu")
		(net "M_F_CPU1_SA_DQ<15>")
	)
	(segment
		(start 157.62351 -291.727382)
		(end 157.455616 -291.895276)
		(width 0.18288)
		(layer "In4.Cu")
		(net "M_F_CPU1_SA_DQ<15>")
	)
	(segment
		(start 164.028374 -295.297606)
		(end 163.669218 -295.297606)
		(width 0.18288)
		(layer "In4.Cu")
		(net "M_F_CPU1_SA_DQ<15>")
	)
	(segment
		(start 172.53966 -299.742352)
		(end 172.278294 -300.003718)
		(width 0.18288)
		(layer "In4.Cu")
		(net "M_F_CPU1_SA_DQ<15>")
	)
	(segment
		(start 166.242238 -297.158918)
		(end 166.242238 -296.952416)
		(width 0.18288)
		(layer "In4.Cu")
		(net "M_F_CPU1_SA_DQ<15>")
	)
	(segment
		(start 132.627878 -268.253972)
		(end 132.613146 -268.245336)
		(width 0.088646)
		(layer "In4.Cu")
		(net "M_F_CPU1_SA_DQ<15>")
	)
	(segment
		(start 176.896014 -298.466764)
		(end 175.841152 -299.521626)
		(width 0.18288)
		(layer "In4.Cu")
		(net "M_F_CPU1_SA_DQ<15>")
	)
	(segment
		(start 174.72787 -299.21962)
		(end 174.425864 -299.521626)
		(width 0.18288)
		(layer "In4.Cu")
		(net "M_F_CPU1_SA_DQ<15>")
	)
	(segment
		(start 175.093884 -299.21962)
		(end 174.72787 -299.21962)
		(width 0.18288)
		(layer "In4.Cu")
		(net "M_F_CPU1_SA_DQ<15>")
	)
	(segment
		(start 167.543226 -297.781726)
		(end 166.865046 -297.781726)
		(width 0.18288)
		(layer "In4.Cu")
		(net "M_F_CPU1_SA_DQ<15>")
	)
	(segment
		(start 166.242238 -296.952416)
		(end 165.564312 -296.27449)
		(width 0.18288)
		(layer "In4.Cu")
		(net "M_F_CPU1_SA_DQ<15>")
	)
	(arc
		(start 133.552946 -268.245336)
		(mid 133.368992 -268.195207)
		(end 133.184138 -268.242034)
		(width 0.088646)
		(layer "In4.Cu")
		(net "M_F_CPU1_SA_DQ<15>")
	)
	(arc
		(start 138.708384 -268.36751)
		(mid 138.472004 -268.336446)
		(end 138.251692 -268.245336)
		(width 0.088646)
		(layer "In4.Cu")
		(net "M_F_CPU1_SA_DQ<15>")
	)
	(arc
		(start 135.432546 -268.245336)
		(mid 135.247425 -268.195073)
		(end 135.061706 -268.24305)
		(width 0.088646)
		(layer "In4.Cu")
		(net "M_F_CPU1_SA_DQ<15>")
	)
	(arc
		(start 136.937496 -268.245336)
		(mid 136.654794 -268.321112)
		(end 136.372092 -268.245336)
		(width 0.088646)
		(layer "In4.Cu")
		(net "M_F_CPU1_SA_DQ<15>")
	)
	(arc
		(start 134.112254 -268.248638)
		(mid 133.832149 -268.32108)
		(end 133.552946 -268.245336)
		(width 0.088646)
		(layer "In4.Cu")
		(net "M_F_CPU1_SA_DQ<15>")
	)
	(arc
		(start 137.311892 -268.245336)
		(mid 137.124694 -268.195193)
		(end 136.937496 -268.245336)
		(width 0.088646)
		(layer "In4.Cu")
		(net "M_F_CPU1_SA_DQ<15>")
	)
	(arc
		(start 133.17855 -268.245336)
		(mid 132.904351 -268.321171)
		(end 132.627878 -268.253972)
		(width 0.088646)
		(layer "In4.Cu")
		(net "M_F_CPU1_SA_DQ<15>")
	)
	(arc
		(start 137.877296 -268.245336)
		(mid 137.594594 -268.321112)
		(end 137.311892 -268.245336)
		(width 0.088646)
		(layer "In4.Cu")
		(net "M_F_CPU1_SA_DQ<15>")
	)
	(arc
		(start 132.613146 -268.245336)
		(mid 132.425948 -268.195193)
		(end 132.23875 -268.245336)
		(width 0.088646)
		(layer "In4.Cu")
		(net "M_F_CPU1_SA_DQ<15>")
	)
	(arc
		(start 138.251692 -268.245336)
		(mid 138.064494 -268.195193)
		(end 137.877296 -268.245336)
		(width 0.088646)
		(layer "In4.Cu")
		(net "M_F_CPU1_SA_DQ<15>")
	)
	(arc
		(start 135.997696 -268.245336)
		(mid 135.721137 -268.321079)
		(end 135.44296 -268.251432)
		(width 0.088646)
		(layer "In4.Cu")
		(net "M_F_CPU1_SA_DQ<15>")
	)
	(arc
		(start 134.492746 -268.245336)
		(mid 134.308792 -268.195207)
		(end 134.123938 -268.242034)
		(width 0.088646)
		(layer "In4.Cu")
		(net "M_F_CPU1_SA_DQ<15>")
	)
	(arc
		(start 136.372092 -268.245336)
		(mid 136.184894 -268.195193)
		(end 135.997696 -268.245336)
		(width 0.088646)
		(layer "In4.Cu")
		(net "M_F_CPU1_SA_DQ<15>")
	)
	(arc
		(start 132.223764 -268.253972)
		(mid 131.864899 -268.435063)
		(end 131.486148 -268.569694)
		(width 0.088646)
		(layer "In4.Cu")
		(net "M_F_CPU1_SA_DQ<15>")
	)
	(arc
		(start 135.052054 -268.248638)
		(mid 134.771949 -268.32108)
		(end 134.492746 -268.245336)
		(width 0.088646)
		(layer "In4.Cu")
		(net "M_F_CPU1_SA_DQ<15>")
	)
	(segment
		(start 183.574436 -299.914818)
		(end 183.958484 -299.914818)
		(width 0.20066)
		(layer "F.Cu")
		(net "M_F_CPU1_SA_DQ<14>")
	)
	(segment
		(start 180.427884 -300.59884)
		(end 180.434996 -300.591728)
		(width 0.1016)
		(layer "F.Cu")
		(net "M_F_CPU1_SA_DQ<14>")
	)
	(segment
		(start 178.00066 -300.166532)
		(end 178.000914 -300.166786)
		(width 0.20066)
		(layer "F.Cu")
		(net "M_F_CPU1_SA_DQ<14>")
	)
	(segment
		(start 182.455058 -300.60392)
		(end 183.136286 -300.60392)
		(width 0.20066)
		(layer "F.Cu")
		(net "M_F_CPU1_SA_DQ<14>")
	)
	(segment
		(start 179.699158 -300.166786)
		(end 180.131212 -300.59884)
		(width 0.20066)
		(layer "F.Cu")
		(net "M_F_CPU1_SA_DQ<14>")
	)
	(segment
		(start 176.896014 -300.166532)
		(end 178.00066 -300.166532)
		(width 0.20066)
		(layer "F.Cu")
		(net "M_F_CPU1_SA_DQ<14>")
	)
	(segment
		(start 178.000914 -300.166786)
		(end 179.699158 -300.166786)
		(width 0.20066)
		(layer "F.Cu")
		(net "M_F_CPU1_SA_DQ<14>")
	)
	(segment
		(start 184.210452 -300.166786)
		(end 185.544714 -300.166786)
		(width 0.20066)
		(layer "F.Cu")
		(net "M_F_CPU1_SA_DQ<14>")
	)
	(segment
		(start 183.958484 -299.914818)
		(end 184.210452 -300.166786)
		(width 0.20066)
		(layer "F.Cu")
		(net "M_F_CPU1_SA_DQ<14>")
	)
	(segment
		(start 183.136286 -300.60392)
		(end 183.340248 -300.399958)
		(width 0.20066)
		(layer "F.Cu")
		(net "M_F_CPU1_SA_DQ<14>")
	)
	(segment
		(start 180.434996 -300.591728)
		(end 182.442866 -300.591728)
		(width 0.1016)
		(layer "F.Cu")
		(net "M_F_CPU1_SA_DQ<14>")
	)
	(segment
		(start 131.956048 -269.383256)
		(end 131.955794 -269.38351)
		(width 0.20066)
		(layer "F.Cu")
		(net "M_F_CPU1_SA_DQ<14>")
	)
	(segment
		(start 131.956048 -268.84757)
		(end 131.956048 -269.383256)
		(width 0.20066)
		(layer "F.Cu")
		(net "M_F_CPU1_SA_DQ<14>")
	)
	(segment
		(start 182.442866 -300.591728)
		(end 182.455058 -300.60392)
		(width 0.1016)
		(layer "F.Cu")
		(net "M_F_CPU1_SA_DQ<14>")
	)
	(segment
		(start 180.131212 -300.59884)
		(end 180.423058 -300.59884)
		(width 0.20066)
		(layer "F.Cu")
		(net "M_F_CPU1_SA_DQ<14>")
	)
	(segment
		(start 183.340248 -300.149006)
		(end 183.574436 -299.914818)
		(width 0.20066)
		(layer "F.Cu")
		(net "M_F_CPU1_SA_DQ<14>")
	)
	(segment
		(start 183.340248 -300.399958)
		(end 183.340248 -300.149006)
		(width 0.20066)
		(layer "F.Cu")
		(net "M_F_CPU1_SA_DQ<14>")
	)
	(segment
		(start 180.423058 -300.59884)
		(end 180.427884 -300.59884)
		(width 0.101854)
		(layer "F.Cu")
		(net "M_F_CPU1_SA_DQ<14>")
	)
	(segment
		(start 143.927322 -272.731484)
		(end 142.764764 -272.731484)
		(width 0.18288)
		(layer "In4.Cu")
		(net "M_F_CPU1_SA_DQ<14>")
	)
	(segment
		(start 175.186086 -301.055786)
		(end 174.72279 -300.59249)
		(width 0.18288)
		(layer "In4.Cu")
		(net "M_F_CPU1_SA_DQ<14>")
	)
	(segment
		(start 155.64231 -290.797996)
		(end 155.383738 -290.797996)
		(width 0.18288)
		(layer "In4.Cu")
		(net "M_F_CPU1_SA_DQ<14>")
	)
	(segment
		(start 140.766038 -270.732758)
		(end 140.241274 -270.207994)
		(width 0.088646)
		(layer "In4.Cu")
		(net "M_F_CPU1_SA_DQ<14>")
	)
	(segment
		(start 134.123938 -268.897608)
		(end 134.118096 -268.894052)
		(width 0.088646)
		(layer "In4.Cu")
		(net "M_F_CPU1_SA_DQ<14>")
	)
	(segment
		(start 176.896014 -300.166532)
		(end 176.00676 -301.055786)
		(width 0.18288)
		(layer "In4.Cu")
		(net "M_F_CPU1_SA_DQ<14>")
	)
	(segment
		(start 163.792154 -296.352214)
		(end 162.338766 -294.898826)
		(width 0.18288)
		(layer "In4.Cu")
		(net "M_F_CPU1_SA_DQ<14>")
	)
	(segment
		(start 139.33551 -269.20825)
		(end 139.132564 -269.20825)
		(width 0.088646)
		(layer "In4.Cu")
		(net "M_F_CPU1_SA_DQ<14>")
	)
	(segment
		(start 165.49497 -297.27271)
		(end 165.040818 -297.27271)
		(width 0.18288)
		(layer "In4.Cu")
		(net "M_F_CPU1_SA_DQ<14>")
	)
	(segment
		(start 155.383738 -290.797996)
		(end 154.894534 -290.308792)
		(width 0.18288)
		(layer "In4.Cu")
		(net "M_F_CPU1_SA_DQ<14>")
	)
	(segment
		(start 140.241274 -270.207994)
		(end 140.241274 -270.114014)
		(width 0.088646)
		(layer "In4.Cu")
		(net "M_F_CPU1_SA_DQ<14>")
	)
	(segment
		(start 156.308806 -290.853876)
		(end 156.076904 -290.621974)
		(width 0.18288)
		(layer "In4.Cu")
		(net "M_F_CPU1_SA_DQ<14>")
	)
	(segment
		(start 168.341802 -299.672502)
		(end 168.341802 -299.4406)
		(width 0.18288)
		(layer "In4.Cu")
		(net "M_F_CPU1_SA_DQ<14>")
	)
	(segment
		(start 167.22979 -299.00753)
		(end 165.49497 -297.27271)
		(width 0.18288)
		(layer "In4.Cu")
		(net "M_F_CPU1_SA_DQ<14>")
	)
	(segment
		(start 150.222204 -279.026366)
		(end 143.927322 -272.731484)
		(width 0.18288)
		(layer "In4.Cu")
		(net "M_F_CPU1_SA_DQ<14>")
	)
	(segment
		(start 165.040818 -297.27271)
		(end 164.120322 -296.352214)
		(width 0.18288)
		(layer "In4.Cu")
		(net "M_F_CPU1_SA_DQ<14>")
	)
	(segment
		(start 176.00676 -301.055786)
		(end 175.186086 -301.055786)
		(width 0.18288)
		(layer "In4.Cu")
		(net "M_F_CPU1_SA_DQ<14>")
	)
	(segment
		(start 156.308806 -291.112448)
		(end 156.308806 -290.853876)
		(width 0.18288)
		(layer "In4.Cu")
		(net "M_F_CPU1_SA_DQ<14>")
	)
	(segment
		(start 133.178296 -268.894052)
		(end 133.172454 -268.89075)
		(width 0.088646)
		(layer "In4.Cu")
		(net "M_F_CPU1_SA_DQ<14>")
	)
	(segment
		(start 154.894534 -290.308792)
		(end 150.222204 -279.026366)
		(width 0.18288)
		(layer "In4.Cu")
		(net "M_F_CPU1_SA_DQ<14>")
	)
	(segment
		(start 174.413926 -300.59249)
		(end 174.017432 -300.988984)
		(width 0.18288)
		(layer "In4.Cu")
		(net "M_F_CPU1_SA_DQ<14>")
	)
	(segment
		(start 160.465516 -293.892732)
		(end 157.900878 -293.114476)
		(width 0.18288)
		(layer "In4.Cu")
		(net "M_F_CPU1_SA_DQ<14>")
	)
	(segment
		(start 155.818332 -290.621974)
		(end 155.64231 -290.797996)
		(width 0.18288)
		(layer "In4.Cu")
		(net "M_F_CPU1_SA_DQ<14>")
	)
	(segment
		(start 168.341802 -299.4406)
		(end 167.908732 -299.00753)
		(width 0.18288)
		(layer "In4.Cu")
		(net "M_F_CPU1_SA_DQ<14>")
	)
	(segment
		(start 156.132784 -291.547042)
		(end 156.132784 -291.28847)
		(width 0.18288)
		(layer "In4.Cu")
		(net "M_F_CPU1_SA_DQ<14>")
	)
	(segment
		(start 157.900878 -293.114476)
		(end 157.558486 -292.972744)
		(width 0.18288)
		(layer "In4.Cu")
		(net "M_F_CPU1_SA_DQ<14>")
	)
	(segment
		(start 133.184138 -268.897608)
		(end 133.178296 -268.894052)
		(width 0.088646)
		(layer "In4.Cu")
		(net "M_F_CPU1_SA_DQ<14>")
	)
	(segment
		(start 160.858454 -294.28567)
		(end 160.465516 -293.892732)
		(width 0.18288)
		(layer "In4.Cu")
		(net "M_F_CPU1_SA_DQ<14>")
	)
	(segment
		(start 164.120322 -296.352214)
		(end 163.792154 -296.352214)
		(width 0.18288)
		(layer "In4.Cu")
		(net "M_F_CPU1_SA_DQ<14>")
	)
	(segment
		(start 142.764764 -272.731484)
		(end 140.766038 -270.732758)
		(width 0.18288)
		(layer "In4.Cu")
		(net "M_F_CPU1_SA_DQ<14>")
	)
	(segment
		(start 132.613146 -268.894052)
		(end 132.53466 -268.939518)
		(width 0.088646)
		(layer "In4.Cu")
		(net "M_F_CPU1_SA_DQ<14>")
	)
	(segment
		(start 167.908732 -299.00753)
		(end 167.22979 -299.00753)
		(width 0.18288)
		(layer "In4.Cu")
		(net "M_F_CPU1_SA_DQ<14>")
	)
	(segment
		(start 162.338766 -294.898826)
		(end 160.858454 -294.28567)
		(width 0.18288)
		(layer "In4.Cu")
		(net "M_F_CPU1_SA_DQ<14>")
	)
	(segment
		(start 139.132564 -269.20825)
		(end 139.022328 -269.098014)
		(width 0.088646)
		(layer "In4.Cu")
		(net "M_F_CPU1_SA_DQ<14>")
	)
	(segment
		(start 173.272958 -300.59249)
		(end 169.26179 -300.59249)
		(width 0.18288)
		(layer "In4.Cu")
		(net "M_F_CPU1_SA_DQ<14>")
	)
	(segment
		(start 135.057896 -268.894052)
		(end 135.052054 -268.89075)
		(width 0.088646)
		(layer "In4.Cu")
		(net "M_F_CPU1_SA_DQ<14>")
	)
	(segment
		(start 157.558486 -292.972744)
		(end 156.132784 -291.547042)
		(width 0.18288)
		(layer "In4.Cu")
		(net "M_F_CPU1_SA_DQ<14>")
	)
	(segment
		(start 156.076904 -290.621974)
		(end 155.818332 -290.621974)
		(width 0.18288)
		(layer "In4.Cu")
		(net "M_F_CPU1_SA_DQ<14>")
	)
	(segment
		(start 173.669452 -300.988984)
		(end 173.272958 -300.59249)
		(width 0.18288)
		(layer "In4.Cu")
		(net "M_F_CPU1_SA_DQ<14>")
	)
	(segment
		(start 135.061706 -268.896338)
		(end 135.057896 -268.894052)
		(width 0.088646)
		(layer "In4.Cu")
		(net "M_F_CPU1_SA_DQ<14>")
	)
	(segment
		(start 169.26179 -300.59249)
		(end 168.341802 -299.672502)
		(width 0.18288)
		(layer "In4.Cu")
		(net "M_F_CPU1_SA_DQ<14>")
	)
	(segment
		(start 156.132784 -291.28847)
		(end 156.308806 -291.112448)
		(width 0.18288)
		(layer "In4.Cu")
		(net "M_F_CPU1_SA_DQ<14>")
	)
	(segment
		(start 134.118096 -268.894052)
		(end 134.112254 -268.89075)
		(width 0.088646)
		(layer "In4.Cu")
		(net "M_F_CPU1_SA_DQ<14>")
	)
	(segment
		(start 174.72279 -300.59249)
		(end 174.413926 -300.59249)
		(width 0.18288)
		(layer "In4.Cu")
		(net "M_F_CPU1_SA_DQ<14>")
	)
	(segment
		(start 174.017432 -300.988984)
		(end 173.669452 -300.988984)
		(width 0.18288)
		(layer "In4.Cu")
		(net "M_F_CPU1_SA_DQ<14>")
	)
	(segment
		(start 140.241274 -270.114014)
		(end 139.33551 -269.20825)
		(width 0.088646)
		(layer "In4.Cu")
		(net "M_F_CPU1_SA_DQ<14>")
	)
	(arc
		(start 137.311892 -268.894052)
		(mid 137.124694 -268.944195)
		(end 136.937496 -268.894052)
		(width 0.088646)
		(layer "In4.Cu")
		(net "M_F_CPU1_SA_DQ<14>")
	)
	(arc
		(start 135.432546 -268.894052)
		(mid 135.247425 -268.944315)
		(end 135.061706 -268.896338)
		(width 0.088646)
		(layer "In4.Cu")
		(net "M_F_CPU1_SA_DQ<14>")
	)
	(arc
		(start 137.877296 -268.894052)
		(mid 137.594594 -268.818276)
		(end 137.311892 -268.894052)
		(width 0.088646)
		(layer "In4.Cu")
		(net "M_F_CPU1_SA_DQ<14>")
	)
	(arc
		(start 136.372092 -268.894052)
		(mid 136.184894 -268.944195)
		(end 135.997696 -268.894052)
		(width 0.088646)
		(layer "In4.Cu")
		(net "M_F_CPU1_SA_DQ<14>")
	)
	(arc
		(start 135.997696 -268.894052)
		(mid 135.715138 -268.818403)
		(end 135.432546 -268.894052)
		(width 0.088646)
		(layer "In4.Cu")
		(net "M_F_CPU1_SA_DQ<14>")
	)
	(arc
		(start 134.492746 -268.894052)
		(mid 134.308822 -268.944306)
		(end 134.123938 -268.897608)
		(width 0.088646)
		(layer "In4.Cu")
		(net "M_F_CPU1_SA_DQ<14>")
	)
	(arc
		(start 135.052054 -268.89075)
		(mid 134.771949 -268.818308)
		(end 134.492746 -268.894052)
		(width 0.088646)
		(layer "In4.Cu")
		(net "M_F_CPU1_SA_DQ<14>")
	)
	(arc
		(start 139.022328 -269.098014)
		(mid 138.93301 -268.982645)
		(end 138.817096 -268.894052)
		(width 0.088646)
		(layer "In4.Cu")
		(net "M_F_CPU1_SA_DQ<14>")
	)
	(arc
		(start 136.937496 -268.894052)
		(mid 136.654794 -268.818276)
		(end 136.372092 -268.894052)
		(width 0.088646)
		(layer "In4.Cu")
		(net "M_F_CPU1_SA_DQ<14>")
	)
	(arc
		(start 134.112254 -268.89075)
		(mid 133.832149 -268.818308)
		(end 133.552946 -268.894052)
		(width 0.088646)
		(layer "In4.Cu")
		(net "M_F_CPU1_SA_DQ<14>")
	)
	(arc
		(start 138.251692 -268.894052)
		(mid 138.064494 -268.944195)
		(end 137.877296 -268.894052)
		(width 0.088646)
		(layer "In4.Cu")
		(net "M_F_CPU1_SA_DQ<14>")
	)
	(arc
		(start 133.552946 -268.894052)
		(mid 133.369022 -268.944306)
		(end 133.184138 -268.897608)
		(width 0.088646)
		(layer "In4.Cu")
		(net "M_F_CPU1_SA_DQ<14>")
	)
	(arc
		(start 138.817096 -268.894052)
		(mid 138.534394 -268.818276)
		(end 138.251692 -268.894052)
		(width 0.088646)
		(layer "In4.Cu")
		(net "M_F_CPU1_SA_DQ<14>")
	)
	(arc
		(start 132.53466 -268.939518)
		(mid 132.230852 -269.142773)
		(end 131.955794 -269.38351)
		(width 0.088646)
		(layer "In4.Cu")
		(net "M_F_CPU1_SA_DQ<14>")
	)
	(arc
		(start 133.172454 -268.89075)
		(mid 132.892349 -268.818308)
		(end 132.613146 -268.894052)
		(width 0.088646)
		(layer "In4.Cu")
		(net "M_F_CPU1_SA_DQ<14>")
	)
	(segment
		(start 175.421544 -299.316648)
		(end 173.900846 -299.316648)
		(width 0.20066)
		(layer "F.Cu")
		(net "M_F_CPU1_SA_DQ<13>")
	)
	(segment
		(start 179.011326 -298.885356)
		(end 179.004976 -298.891706)
		(width 0.1016)
		(layer "F.Cu")
		(net "M_F_CPU1_SA_DQ<13>")
	)
	(segment
		(start 173.900846 -299.316648)
		(end 172.795946 -299.316648)
		(width 0.20066)
		(layer "F.Cu")
		(net "M_F_CPU1_SA_DQ<13>")
	)
	(segment
		(start 181.444646 -299.316648)
		(end 181.444392 -299.316902)
		(width 0.20066)
		(layer "F.Cu")
		(net "M_F_CPU1_SA_DQ<13>")
	)
	(segment
		(start 175.67021 -299.565314)
		(end 175.421544 -299.316648)
		(width 0.20066)
		(layer "F.Cu")
		(net "M_F_CPU1_SA_DQ<13>")
	)
	(segment
		(start 176.145444 -299.565314)
		(end 175.67021 -299.565314)
		(width 0.20066)
		(layer "F.Cu")
		(net "M_F_CPU1_SA_DQ<13>")
	)
	(segment
		(start 130.546094 -268.56944)
		(end 130.546348 -268.569694)
		(width 0.20066)
		(layer "F.Cu")
		(net "M_F_CPU1_SA_DQ<13>")
	)
	(segment
		(start 130.546094 -268.033754)
		(end 130.546094 -268.56944)
		(width 0.20066)
		(layer "F.Cu")
		(net "M_F_CPU1_SA_DQ<13>")
	)
	(segment
		(start 179.421282 -298.885356)
		(end 179.011326 -298.885356)
		(width 0.20066)
		(layer "F.Cu")
		(net "M_F_CPU1_SA_DQ<13>")
	)
	(segment
		(start 179.004976 -298.891706)
		(end 176.816258 -298.891706)
		(width 0.1016)
		(layer "F.Cu")
		(net "M_F_CPU1_SA_DQ<13>")
	)
	(segment
		(start 176.796192 -298.891706)
		(end 176.451514 -298.891706)
		(width 0.20066)
		(layer "F.Cu")
		(net "M_F_CPU1_SA_DQ<13>")
	)
	(segment
		(start 176.333404 -299.009816)
		(end 176.333404 -299.377354)
		(width 0.20066)
		(layer "F.Cu")
		(net "M_F_CPU1_SA_DQ<13>")
	)
	(segment
		(start 176.816258 -298.891706)
		(end 176.796192 -298.891706)
		(width 0.101854)
		(layer "F.Cu")
		(net "M_F_CPU1_SA_DQ<13>")
	)
	(segment
		(start 176.451514 -298.891706)
		(end 176.333404 -299.009816)
		(width 0.20066)
		(layer "F.Cu")
		(net "M_F_CPU1_SA_DQ<13>")
	)
	(segment
		(start 176.333404 -299.377354)
		(end 176.145444 -299.565314)
		(width 0.20066)
		(layer "F.Cu")
		(net "M_F_CPU1_SA_DQ<13>")
	)
	(segment
		(start 179.852828 -299.316902)
		(end 179.421282 -298.885356)
		(width 0.20066)
		(layer "F.Cu")
		(net "M_F_CPU1_SA_DQ<13>")
	)
	(segment
		(start 181.444392 -299.316902)
		(end 179.852828 -299.316902)
		(width 0.20066)
		(layer "F.Cu")
		(net "M_F_CPU1_SA_DQ<13>")
	)
	(segment
		(start 141.247114 -270.251682)
		(end 139.57046 -268.575028)
		(width 0.088646)
		(layer "In4.Cu")
		(net "M_F_CPU1_SA_DQ<13>")
	)
	(segment
		(start 134.967218 -268.077696)
		(end 134.956804 -268.083538)
		(width 0.088646)
		(layer "In4.Cu")
		(net "M_F_CPU1_SA_DQ<13>")
	)
	(segment
		(start 134.028688 -268.076934)
		(end 134.017004 -268.083538)
		(width 0.088646)
		(layer "In4.Cu")
		(net "M_F_CPU1_SA_DQ<13>")
	)
	(segment
		(start 172.795946 -299.316648)
		(end 172.187616 -299.316648)
		(width 0.18288)
		(layer "In4.Cu")
		(net "M_F_CPU1_SA_DQ<13>")
	)
	(segment
		(start 158.505906 -290.079176)
		(end 158.351728 -290.233354)
		(width 0.18288)
		(layer "In4.Cu")
		(net "M_F_CPU1_SA_DQ<13>")
	)
	(segment
		(start 144.759426 -272.055844)
		(end 143.051276 -272.055844)
		(width 0.18288)
		(layer "In4.Cu")
		(net "M_F_CPU1_SA_DQ<13>")
	)
	(segment
		(start 160.20669 -291.931598)
		(end 159.948118 -291.931598)
		(width 0.18288)
		(layer "In4.Cu")
		(net "M_F_CPU1_SA_DQ<13>")
	)
	(segment
		(start 156.80817 -289.576256)
		(end 157.009084 -289.375342)
		(width 0.18288)
		(layer "In4.Cu")
		(net "M_F_CPU1_SA_DQ<13>")
	)
	(segment
		(start 162.846004 -293.566088)
		(end 162.84575 -293.431214)
		(width 0.18288)
		(layer "In4.Cu")
		(net "M_F_CPU1_SA_DQ<13>")
	)
	(segment
		(start 151.204676 -278.501094)
		(end 144.759426 -272.055844)
		(width 0.18288)
		(layer "In4.Cu")
		(net "M_F_CPU1_SA_DQ<13>")
	)
	(segment
		(start 168.081706 -297.248326)
		(end 167.287194 -297.248326)
		(width 0.18288)
		(layer "In4.Cu")
		(net "M_F_CPU1_SA_DQ<13>")
	)
	(segment
		(start 156.028136 -287.824926)
		(end 154.387296 -286.184086)
		(width 0.18288)
		(layer "In4.Cu")
		(net "M_F_CPU1_SA_DQ<13>")
	)
	(segment
		(start 158.435802 -291.130228)
		(end 158.99638 -290.56965)
		(width 0.18288)
		(layer "In4.Cu")
		(net "M_F_CPU1_SA_DQ<13>")
	)
	(segment
		(start 160.697164 -292.680644)
		(end 160.697164 -292.422072)
		(width 0.18288)
		(layer "In4.Cu")
		(net "M_F_CPU1_SA_DQ<13>")
	)
	(segment
		(start 139.372086 -268.575028)
		(end 138.924538 -268.12748)
		(width 0.088646)
		(layer "In4.Cu")
		(net "M_F_CPU1_SA_DQ<13>")
	)
	(segment
		(start 156.74467 -288.884868)
		(end 156.51861 -288.884868)
		(width 0.18288)
		(layer "In4.Cu")
		(net "M_F_CPU1_SA_DQ<13>")
	)
	(segment
		(start 160.486344 -291.651944)
		(end 160.20669 -291.931598)
		(width 0.18288)
		(layer "In4.Cu")
		(net "M_F_CPU1_SA_DQ<13>")
	)
	(segment
		(start 155.76804 -288.88055)
		(end 155.76804 -288.65449)
		(width 0.18288)
		(layer "In4.Cu")
		(net "M_F_CPU1_SA_DQ<13>")
	)
	(segment
		(start 158.764478 -290.079176)
		(end 158.505906 -290.079176)
		(width 0.18288)
		(layer "In4.Cu")
		(net "M_F_CPU1_SA_DQ<13>")
	)
	(segment
		(start 156.032454 -289.144964)
		(end 155.76804 -288.88055)
		(width 0.18288)
		(layer "In4.Cu")
		(net "M_F_CPU1_SA_DQ<13>")
	)
	(segment
		(start 171.324778 -298.864528)
		(end 171.000928 -299.188378)
		(width 0.18288)
		(layer "In4.Cu")
		(net "M_F_CPU1_SA_DQ<13>")
	)
	(segment
		(start 154.387296 -286.184086)
		(end 151.204676 -278.501094)
		(width 0.18288)
		(layer "In4.Cu")
		(net "M_F_CPU1_SA_DQ<13>")
	)
	(segment
		(start 160.855152 -292.838632)
		(end 160.697164 -292.680644)
		(width 0.18288)
		(layer "In4.Cu")
		(net "M_F_CPU1_SA_DQ<13>")
	)
	(segment
		(start 158.759144 -291.71265)
		(end 158.435802 -291.389308)
		(width 0.18288)
		(layer "In4.Cu")
		(net "M_F_CPU1_SA_DQ<13>")
	)
	(segment
		(start 172.187616 -299.316648)
		(end 171.735496 -298.864528)
		(width 0.18288)
		(layer "In4.Cu")
		(net "M_F_CPU1_SA_DQ<13>")
	)
	(segment
		(start 139.57046 -268.575028)
		(end 139.372086 -268.575028)
		(width 0.088646)
		(layer "In4.Cu")
		(net "M_F_CPU1_SA_DQ<13>")
	)
	(segment
		(start 157.009084 -289.149282)
		(end 156.74467 -288.884868)
		(width 0.18288)
		(layer "In4.Cu")
		(net "M_F_CPU1_SA_DQ<13>")
	)
	(segment
		(start 159.72917 -291.71265)
		(end 158.759144 -291.71265)
		(width 0.18288)
		(layer "In4.Cu")
		(net "M_F_CPU1_SA_DQ<13>")
	)
	(segment
		(start 158.99638 -290.56965)
		(end 158.99638 -290.311078)
		(width 0.18288)
		(layer "In4.Cu")
		(net "M_F_CPU1_SA_DQ<13>")
	)
	(segment
		(start 157.298644 -290.06673)
		(end 157.072584 -290.06673)
		(width 0.18288)
		(layer "In4.Cu")
		(net "M_F_CPU1_SA_DQ<13>")
	)
	(segment
		(start 171.735496 -298.864528)
		(end 171.324778 -298.864528)
		(width 0.18288)
		(layer "In4.Cu")
		(net "M_F_CPU1_SA_DQ<13>")
	)
	(segment
		(start 158.093156 -290.233354)
		(end 157.725618 -289.865816)
		(width 0.18288)
		(layer "In4.Cu")
		(net "M_F_CPU1_SA_DQ<13>")
	)
	(segment
		(start 159.948118 -291.931598)
		(end 159.72917 -291.71265)
		(width 0.18288)
		(layer "In4.Cu")
		(net "M_F_CPU1_SA_DQ<13>")
	)
	(segment
		(start 157.725618 -289.865816)
		(end 157.499558 -289.865816)
		(width 0.18288)
		(layer "In4.Cu")
		(net "M_F_CPU1_SA_DQ<13>")
	)
	(segment
		(start 160.744916 -291.651944)
		(end 160.486344 -291.651944)
		(width 0.18288)
		(layer "In4.Cu")
		(net "M_F_CPU1_SA_DQ<13>")
	)
	(segment
		(start 158.351728 -290.233354)
		(end 158.093156 -290.233354)
		(width 0.18288)
		(layer "In4.Cu")
		(net "M_F_CPU1_SA_DQ<13>")
	)
	(segment
		(start 156.028136 -288.394394)
		(end 156.028136 -287.824926)
		(width 0.18288)
		(layer "In4.Cu")
		(net "M_F_CPU1_SA_DQ<13>")
	)
	(segment
		(start 138.924538 -268.12748)
		(end 138.581638 -268.12748)
		(width 0.088646)
		(layer "In4.Cu")
		(net "M_F_CPU1_SA_DQ<13>")
	)
	(segment
		(start 158.99638 -290.311078)
		(end 158.764478 -290.079176)
		(width 0.18288)
		(layer "In4.Cu")
		(net "M_F_CPU1_SA_DQ<13>")
	)
	(segment
		(start 163.837874 -294.701976)
		(end 162.846004 -293.710106)
		(width 0.18288)
		(layer "In4.Cu")
		(net "M_F_CPU1_SA_DQ<13>")
	)
	(segment
		(start 157.009084 -289.375342)
		(end 157.009084 -289.149282)
		(width 0.18288)
		(layer "In4.Cu")
		(net "M_F_CPU1_SA_DQ<13>")
	)
	(segment
		(start 167.287194 -297.248326)
		(end 165.713918 -295.67505)
		(width 0.18288)
		(layer "In4.Cu")
		(net "M_F_CPU1_SA_DQ<13>")
	)
	(segment
		(start 156.258514 -289.144964)
		(end 156.032454 -289.144964)
		(width 0.18288)
		(layer "In4.Cu")
		(net "M_F_CPU1_SA_DQ<13>")
	)
	(segment
		(start 171.000928 -299.188378)
		(end 170.021758 -299.188378)
		(width 0.18288)
		(layer "In4.Cu")
		(net "M_F_CPU1_SA_DQ<13>")
	)
	(segment
		(start 157.499558 -289.865816)
		(end 157.298644 -290.06673)
		(width 0.18288)
		(layer "In4.Cu")
		(net "M_F_CPU1_SA_DQ<13>")
	)
	(segment
		(start 143.051276 -272.055844)
		(end 141.247114 -270.251682)
		(width 0.18288)
		(layer "In4.Cu")
		(net "M_F_CPU1_SA_DQ<13>")
	)
	(segment
		(start 162.846004 -293.710106)
		(end 162.846004 -293.566088)
		(width 0.18288)
		(layer "In4.Cu")
		(net "M_F_CPU1_SA_DQ<13>")
	)
	(segment
		(start 157.072584 -290.06673)
		(end 156.80817 -289.802316)
		(width 0.18288)
		(layer "In4.Cu")
		(net "M_F_CPU1_SA_DQ<13>")
	)
	(segment
		(start 160.697164 -292.422072)
		(end 160.976818 -292.142418)
		(width 0.18288)
		(layer "In4.Cu")
		(net "M_F_CPU1_SA_DQ<13>")
	)
	(segment
		(start 165.713918 -295.67505)
		(end 165.137338 -295.67505)
		(width 0.18288)
		(layer "In4.Cu")
		(net "M_F_CPU1_SA_DQ<13>")
	)
	(segment
		(start 158.435802 -291.389308)
		(end 158.435802 -291.130228)
		(width 0.18288)
		(layer "In4.Cu")
		(net "M_F_CPU1_SA_DQ<13>")
	)
	(segment
		(start 156.80817 -289.802316)
		(end 156.80817 -289.576256)
		(width 0.18288)
		(layer "In4.Cu")
		(net "M_F_CPU1_SA_DQ<13>")
	)
	(segment
		(start 160.976818 -291.883846)
		(end 160.744916 -291.651944)
		(width 0.18288)
		(layer "In4.Cu")
		(net "M_F_CPU1_SA_DQ<13>")
	)
	(segment
		(start 156.51861 -288.884868)
		(end 156.258514 -289.144964)
		(width 0.18288)
		(layer "In4.Cu")
		(net "M_F_CPU1_SA_DQ<13>")
	)
	(segment
		(start 162.84575 -293.431214)
		(end 162.253168 -292.838632)
		(width 0.18288)
		(layer "In4.Cu")
		(net "M_F_CPU1_SA_DQ<13>")
	)
	(segment
		(start 155.76804 -288.65449)
		(end 156.028136 -288.394394)
		(width 0.18288)
		(layer "In4.Cu")
		(net "M_F_CPU1_SA_DQ<13>")
	)
	(segment
		(start 170.021758 -299.188378)
		(end 168.081706 -297.248326)
		(width 0.18288)
		(layer "In4.Cu")
		(net "M_F_CPU1_SA_DQ<13>")
	)
	(segment
		(start 132.708396 -268.080236)
		(end 132.697982 -268.07414)
		(width 0.088646)
		(layer "In4.Cu")
		(net "M_F_CPU1_SA_DQ<13>")
	)
	(segment
		(start 133.088888 -268.076934)
		(end 133.082792 -268.080236)
		(width 0.088646)
		(layer "In4.Cu")
		(net "M_F_CPU1_SA_DQ<13>")
	)
	(segment
		(start 164.164264 -294.701976)
		(end 163.837874 -294.701976)
		(width 0.18288)
		(layer "In4.Cu")
		(net "M_F_CPU1_SA_DQ<13>")
	)
	(segment
		(start 160.976818 -292.142418)
		(end 160.976818 -291.883846)
		(width 0.18288)
		(layer "In4.Cu")
		(net "M_F_CPU1_SA_DQ<13>")
	)
	(segment
		(start 165.137338 -295.67505)
		(end 164.164264 -294.701976)
		(width 0.18288)
		(layer "In4.Cu")
		(net "M_F_CPU1_SA_DQ<13>")
	)
	(segment
		(start 162.253168 -292.838632)
		(end 160.855152 -292.838632)
		(width 0.18288)
		(layer "In4.Cu")
		(net "M_F_CPU1_SA_DQ<13>")
	)
	(arc
		(start 135.902192 -268.080236)
		(mid 135.714994 -268.130379)
		(end 135.527796 -268.080236)
		(width 0.088646)
		(layer "In4.Cu")
		(net "M_F_CPU1_SA_DQ<13>")
	)
	(arc
		(start 137.781792 -268.080236)
		(mid 137.594594 -268.130379)
		(end 137.407396 -268.080236)
		(width 0.088646)
		(layer "In4.Cu")
		(net "M_F_CPU1_SA_DQ<13>")
	)
	(arc
		(start 134.956804 -268.083538)
		(mid 134.771949 -268.130488)
		(end 134.587996 -268.080236)
		(width 0.088646)
		(layer "In4.Cu")
		(net "M_F_CPU1_SA_DQ<13>")
	)
	(arc
		(start 134.017004 -268.083538)
		(mid 133.832149 -268.130488)
		(end 133.648196 -268.080236)
		(width 0.088646)
		(layer "In4.Cu")
		(net "M_F_CPU1_SA_DQ<13>")
	)
	(arc
		(start 135.527796 -268.080236)
		(mid 135.247852 -268.004592)
		(end 134.967218 -268.077696)
		(width 0.088646)
		(layer "In4.Cu")
		(net "M_F_CPU1_SA_DQ<13>")
	)
	(arc
		(start 133.082792 -268.080236)
		(mid 132.895594 -268.130379)
		(end 132.708396 -268.080236)
		(width 0.088646)
		(layer "In4.Cu")
		(net "M_F_CPU1_SA_DQ<13>")
	)
	(arc
		(start 132.697982 -268.07414)
		(mid 132.419804 -268.004417)
		(end 132.143246 -268.080236)
		(width 0.088646)
		(layer "In4.Cu")
		(net "M_F_CPU1_SA_DQ<13>")
	)
	(arc
		(start 133.648196 -268.080236)
		(mid 133.368993 -268.004596)
		(end 133.088888 -268.076934)
		(width 0.088646)
		(layer "In4.Cu")
		(net "M_F_CPU1_SA_DQ<13>")
	)
	(arc
		(start 138.581638 -268.12748)
		(mid 138.460557 -268.123038)
		(end 138.347196 -268.080236)
		(width 0.088646)
		(layer "In4.Cu")
		(net "M_F_CPU1_SA_DQ<13>")
	)
	(arc
		(start 136.467596 -268.080236)
		(mid 136.184894 -268.00446)
		(end 135.902192 -268.080236)
		(width 0.088646)
		(layer "In4.Cu")
		(net "M_F_CPU1_SA_DQ<13>")
	)
	(arc
		(start 134.587996 -268.080236)
		(mid 134.308793 -268.004596)
		(end 134.028688 -268.076934)
		(width 0.088646)
		(layer "In4.Cu")
		(net "M_F_CPU1_SA_DQ<13>")
	)
	(arc
		(start 131.76885 -268.080236)
		(mid 131.439718 -268.033905)
		(end 131.170426 -268.228826)
		(width 0.088646)
		(layer "In4.Cu")
		(net "M_F_CPU1_SA_DQ<13>")
	)
	(arc
		(start 136.841992 -268.080236)
		(mid 136.654794 -268.130379)
		(end 136.467596 -268.080236)
		(width 0.088646)
		(layer "In4.Cu")
		(net "M_F_CPU1_SA_DQ<13>")
	)
	(arc
		(start 131.170426 -268.228826)
		(mid 130.902858 -268.480688)
		(end 130.546348 -268.569694)
		(width 0.088646)
		(layer "In4.Cu")
		(net "M_F_CPU1_SA_DQ<13>")
	)
	(arc
		(start 137.407396 -268.080236)
		(mid 137.124694 -268.00446)
		(end 136.841992 -268.080236)
		(width 0.088646)
		(layer "In4.Cu")
		(net "M_F_CPU1_SA_DQ<13>")
	)
	(arc
		(start 132.143246 -268.080236)
		(mid 131.956048 -268.130379)
		(end 131.76885 -268.080236)
		(width 0.088646)
		(layer "In4.Cu")
		(net "M_F_CPU1_SA_DQ<13>")
	)
	(arc
		(start 138.347196 -268.080236)
		(mid 138.064494 -268.00446)
		(end 137.781792 -268.080236)
		(width 0.088646)
		(layer "In4.Cu")
		(net "M_F_CPU1_SA_DQ<13>")
	)
	(segment
		(start 130.076448 -269.383256)
		(end 130.076194 -269.38351)
		(width 0.20066)
		(layer "F.Cu")
		(net "M_F_CPU1_SA_DQ<12>")
	)
	(segment
		(start 176.333404 -301.077376)
		(end 176.145444 -301.265336)
		(width 0.20066)
		(layer "F.Cu")
		(net "M_F_CPU1_SA_DQ<12>")
	)
	(segment
		(start 175.421544 -301.01667)
		(end 173.900846 -301.01667)
		(width 0.20066)
		(layer "F.Cu")
		(net "M_F_CPU1_SA_DQ<12>")
	)
	(segment
		(start 179.004976 -300.591728)
		(end 176.843182 -300.591728)
		(width 0.1016)
		(layer "F.Cu")
		(net "M_F_CPU1_SA_DQ<12>")
	)
	(segment
		(start 176.451514 -300.591728)
		(end 176.333404 -300.709838)
		(width 0.20066)
		(layer "F.Cu")
		(net "M_F_CPU1_SA_DQ<12>")
	)
	(segment
		(start 130.076448 -268.84757)
		(end 130.076448 -269.383256)
		(width 0.20066)
		(layer "F.Cu")
		(net "M_F_CPU1_SA_DQ<12>")
	)
	(segment
		(start 181.444646 -301.01667)
		(end 181.444392 -301.016924)
		(width 0.20066)
		(layer "F.Cu")
		(net "M_F_CPU1_SA_DQ<12>")
	)
	(segment
		(start 179.011326 -300.585378)
		(end 179.004976 -300.591728)
		(width 0.1016)
		(layer "F.Cu")
		(net "M_F_CPU1_SA_DQ<12>")
	)
	(segment
		(start 175.67021 -301.265336)
		(end 175.421544 -301.01667)
		(width 0.20066)
		(layer "F.Cu")
		(net "M_F_CPU1_SA_DQ<12>")
	)
	(segment
		(start 173.900846 -301.01667)
		(end 172.795946 -301.01667)
		(width 0.20066)
		(layer "F.Cu")
		(net "M_F_CPU1_SA_DQ<12>")
	)
	(segment
		(start 176.145444 -301.265336)
		(end 175.67021 -301.265336)
		(width 0.20066)
		(layer "F.Cu")
		(net "M_F_CPU1_SA_DQ<12>")
	)
	(segment
		(start 179.421282 -300.585378)
		(end 179.011326 -300.585378)
		(width 0.20066)
		(layer "F.Cu")
		(net "M_F_CPU1_SA_DQ<12>")
	)
	(segment
		(start 176.796192 -300.591728)
		(end 176.451514 -300.591728)
		(width 0.20066)
		(layer "F.Cu")
		(net "M_F_CPU1_SA_DQ<12>")
	)
	(segment
		(start 179.852828 -301.016924)
		(end 179.421282 -300.585378)
		(width 0.20066)
		(layer "F.Cu")
		(net "M_F_CPU1_SA_DQ<12>")
	)
	(segment
		(start 176.333404 -300.709838)
		(end 176.333404 -301.077376)
		(width 0.20066)
		(layer "F.Cu")
		(net "M_F_CPU1_SA_DQ<12>")
	)
	(segment
		(start 181.444392 -301.016924)
		(end 179.852828 -301.016924)
		(width 0.20066)
		(layer "F.Cu")
		(net "M_F_CPU1_SA_DQ<12>")
	)
	(segment
		(start 176.843182 -300.591728)
		(end 176.796192 -300.591728)
		(width 0.101854)
		(layer "F.Cu")
		(net "M_F_CPU1_SA_DQ<12>")
	)
	(segment
		(start 165.765226 -298.730162)
		(end 165.765226 -298.259246)
		(width 0.18288)
		(layer "In4.Cu")
		(net "M_F_CPU1_SA_DQ<12>")
	)
	(segment
		(start 131.870958 -269.780766)
		(end 131.100576 -269.780766)
		(width 0.088646)
		(layer "In4.Cu")
		(net "M_F_CPU1_SA_DQ<12>")
	)
	(segment
		(start 167.912288 -300.515528)
		(end 167.912288 -299.944282)
		(width 0.18288)
		(layer "In4.Cu")
		(net "M_F_CPU1_SA_DQ<12>")
	)
	(segment
		(start 164.97046 -297.949112)
		(end 164.135308 -297.11396)
		(width 0.18288)
		(layer "In4.Cu")
		(net "M_F_CPU1_SA_DQ<12>")
	)
	(segment
		(start 139.571222 -270.045688)
		(end 138.923014 -269.39748)
		(width 0.088646)
		(layer "In4.Cu")
		(net "M_F_CPU1_SA_DQ<12>")
	)
	(segment
		(start 163.169854 -296.508678)
		(end 162.964622 -296.303446)
		(width 0.18288)
		(layer "In4.Cu")
		(net "M_F_CPU1_SA_DQ<12>")
	)
	(segment
		(start 167.912288 -299.944282)
		(end 167.584628 -299.616622)
		(width 0.18288)
		(layer "In4.Cu")
		(net "M_F_CPU1_SA_DQ<12>")
	)
	(segment
		(start 163.645596 -297.344592)
		(end 163.392104 -297.344592)
		(width 0.18288)
		(layer "In4.Cu")
		(net "M_F_CPU1_SA_DQ<12>")
	)
	(segment
		(start 170.826938 -301.43958)
		(end 170.500294 -301.112936)
		(width 0.18288)
		(layer "In4.Cu")
		(net "M_F_CPU1_SA_DQ<12>")
	)
	(segment
		(start 169.876724 -301.477426)
		(end 168.874186 -301.477426)
		(width 0.18288)
		(layer "In4.Cu")
		(net "M_F_CPU1_SA_DQ<12>")
	)
	(segment
		(start 132.513324 -269.243556)
		(end 132.473192 -269.340838)
		(width 0.088646)
		(layer "In4.Cu")
		(net "M_F_CPU1_SA_DQ<12>")
	)
	(segment
		(start 142.599156 -273.073622)
		(end 140.512292 -270.986758)
		(width 0.18288)
		(layer "In4.Cu")
		(net "M_F_CPU1_SA_DQ<12>")
	)
	(segment
		(start 134.028688 -269.062708)
		(end 134.022846 -269.059152)
		(width 0.088646)
		(layer "In4.Cu")
		(net "M_F_CPU1_SA_DQ<12>")
	)
	(segment
		(start 163.392104 -297.344592)
		(end 163.169854 -297.122342)
		(width 0.18288)
		(layer "In4.Cu")
		(net "M_F_CPU1_SA_DQ<12>")
	)
	(segment
		(start 165.765226 -298.259246)
		(end 165.455092 -297.949112)
		(width 0.18288)
		(layer "In4.Cu")
		(net "M_F_CPU1_SA_DQ<12>")
	)
	(segment
		(start 135.902192 -269.059152)
		(end 135.902446 -269.059152)
		(width 0.088646)
		(layer "In4.Cu")
		(net "M_F_CPU1_SA_DQ<12>")
	)
	(segment
		(start 134.967218 -269.061946)
		(end 134.962646 -269.059152)
		(width 0.088646)
		(layer "In4.Cu")
		(net "M_F_CPU1_SA_DQ<12>")
	)
	(segment
		(start 133.083046 -269.059152)
		(end 133.077204 -269.05585)
		(width 0.088646)
		(layer "In4.Cu")
		(net "M_F_CPU1_SA_DQ<12>")
	)
	(segment
		(start 160.87979 -294.844724)
		(end 160.580578 -294.720772)
		(width 0.18288)
		(layer "In4.Cu")
		(net "M_F_CPU1_SA_DQ<12>")
	)
	(segment
		(start 172.795946 -301.01667)
		(end 172.172122 -301.01667)
		(width 0.18288)
		(layer "In4.Cu")
		(net "M_F_CPU1_SA_DQ<12>")
	)
	(segment
		(start 134.022846 -269.059152)
		(end 134.017004 -269.05585)
		(width 0.088646)
		(layer "In4.Cu")
		(net "M_F_CPU1_SA_DQ<12>")
	)
	(segment
		(start 159.262318 -294.487092)
		(end 158.966408 -294.397176)
		(width 0.18288)
		(layer "In4.Cu")
		(net "M_F_CPU1_SA_DQ<12>")
	)
	(segment
		(start 140.006832 -270.481298)
		(end 139.90066 -270.225266)
		(width 0.088646)
		(layer "In4.Cu")
		(net "M_F_CPU1_SA_DQ<12>")
	)
	(segment
		(start 132.610098 -269.13459)
		(end 132.537962 -269.206726)
		(width 0.088646)
		(layer "In4.Cu")
		(net "M_F_CPU1_SA_DQ<12>")
	)
	(segment
		(start 154.069034 -290.332922)
		(end 149.309074 -278.842216)
		(width 0.18288)
		(layer "In4.Cu")
		(net "M_F_CPU1_SA_DQ<12>")
	)
	(segment
		(start 167.584628 -299.616622)
		(end 166.651686 -299.616622)
		(width 0.18288)
		(layer "In4.Cu")
		(net "M_F_CPU1_SA_DQ<12>")
	)
	(segment
		(start 162.026092 -295.319704)
		(end 161.858198 -295.249854)
		(width 0.18288)
		(layer "In4.Cu")
		(net "M_F_CPU1_SA_DQ<12>")
	)
	(segment
		(start 163.876228 -297.11396)
		(end 163.645596 -297.344592)
		(width 0.18288)
		(layer "In4.Cu")
		(net "M_F_CPU1_SA_DQ<12>")
	)
	(segment
		(start 134.962646 -269.059152)
		(end 134.956804 -269.05585)
		(width 0.088646)
		(layer "In4.Cu")
		(net "M_F_CPU1_SA_DQ<12>")
	)
	(segment
		(start 130.776726 -269.671546)
		(end 130.634994 -269.552674)
		(width 0.088646)
		(layer "In4.Cu")
		(net "M_F_CPU1_SA_DQ<12>")
	)
	(segment
		(start 158.716218 -293.929562)
		(end 157.20822 -293.472108)
		(width 0.18288)
		(layer "In4.Cu")
		(net "M_F_CPU1_SA_DQ<12>")
	)
	(segment
		(start 159.729932 -294.236648)
		(end 159.262318 -294.487092)
		(width 0.18288)
		(layer "In4.Cu")
		(net "M_F_CPU1_SA_DQ<12>")
	)
	(segment
		(start 132.146802 -269.70609)
		(end 132.138674 -269.710662)
		(width 0.088646)
		(layer "In4.Cu")
		(net "M_F_CPU1_SA_DQ<12>")
	)
	(segment
		(start 138.851894 -269.184628)
		(end 138.849608 -269.180818)
		(width 0.088646)
		(layer "In4.Cu")
		(net "M_F_CPU1_SA_DQ<12>")
	)
	(segment
		(start 165.455092 -297.949112)
		(end 164.97046 -297.949112)
		(width 0.18288)
		(layer "In4.Cu")
		(net "M_F_CPU1_SA_DQ<12>")
	)
	(segment
		(start 162.395662 -296.120566)
		(end 162.395662 -295.689274)
		(width 0.18288)
		(layer "In4.Cu")
		(net "M_F_CPU1_SA_DQ<12>")
	)
	(segment
		(start 161.510472 -295.612566)
		(end 161.271966 -295.711626)
		(width 0.18288)
		(layer "In4.Cu")
		(net "M_F_CPU1_SA_DQ<12>")
	)
	(segment
		(start 157.20822 -293.472108)
		(end 154.069034 -290.332922)
		(width 0.18288)
		(layer "In4.Cu")
		(net "M_F_CPU1_SA_DQ<12>")
	)
	(segment
		(start 168.874186 -301.477426)
		(end 167.912288 -300.515528)
		(width 0.18288)
		(layer "In4.Cu")
		(net "M_F_CPU1_SA_DQ<12>")
	)
	(segment
		(start 162.578542 -296.303446)
		(end 162.395662 -296.120566)
		(width 0.18288)
		(layer "In4.Cu")
		(net "M_F_CPU1_SA_DQ<12>")
	)
	(segment
		(start 170.241214 -301.112936)
		(end 169.876724 -301.477426)
		(width 0.18288)
		(layer "In4.Cu")
		(net "M_F_CPU1_SA_DQ<12>")
	)
	(segment
		(start 140.512292 -270.986758)
		(end 140.006832 -270.481298)
		(width 0.088646)
		(layer "In4.Cu")
		(net "M_F_CPU1_SA_DQ<12>")
	)
	(segment
		(start 160.97885 -295.083484)
		(end 160.87979 -294.844724)
		(width 0.18288)
		(layer "In4.Cu")
		(net "M_F_CPU1_SA_DQ<12>")
	)
	(segment
		(start 139.721082 -270.045688)
		(end 139.571222 -270.045688)
		(width 0.088646)
		(layer "In4.Cu")
		(net "M_F_CPU1_SA_DQ<12>")
	)
	(segment
		(start 161.858198 -295.249854)
		(end 161.619692 -295.348914)
		(width 0.18288)
		(layer "In4.Cu")
		(net "M_F_CPU1_SA_DQ<12>")
	)
	(segment
		(start 160.580578 -294.720772)
		(end 160.25622 -294.396414)
		(width 0.18288)
		(layer "In4.Cu")
		(net "M_F_CPU1_SA_DQ<12>")
	)
	(segment
		(start 149.309074 -278.842216)
		(end 143.54048 -273.073622)
		(width 0.18288)
		(layer "In4.Cu")
		(net "M_F_CPU1_SA_DQ<12>")
	)
	(segment
		(start 170.500294 -301.112936)
		(end 170.241214 -301.112936)
		(width 0.18288)
		(layer "In4.Cu")
		(net "M_F_CPU1_SA_DQ<12>")
	)
	(segment
		(start 158.966408 -294.397176)
		(end 158.716218 -293.929562)
		(width 0.18288)
		(layer "In4.Cu")
		(net "M_F_CPU1_SA_DQ<12>")
	)
	(segment
		(start 172.172122 -301.01667)
		(end 171.749212 -301.43958)
		(width 0.18288)
		(layer "In4.Cu")
		(net "M_F_CPU1_SA_DQ<12>")
	)
	(segment
		(start 162.395662 -295.689274)
		(end 162.026092 -295.319704)
		(width 0.18288)
		(layer "In4.Cu")
		(net "M_F_CPU1_SA_DQ<12>")
	)
	(segment
		(start 133.088888 -269.062708)
		(end 133.083046 -269.059152)
		(width 0.088646)
		(layer "In4.Cu")
		(net "M_F_CPU1_SA_DQ<12>")
	)
	(segment
		(start 139.90066 -270.225266)
		(end 139.721082 -270.045688)
		(width 0.088646)
		(layer "In4.Cu")
		(net "M_F_CPU1_SA_DQ<12>")
	)
	(segment
		(start 171.749212 -301.43958)
		(end 170.826938 -301.43958)
		(width 0.18288)
		(layer "In4.Cu")
		(net "M_F_CPU1_SA_DQ<12>")
	)
	(segment
		(start 143.54048 -273.073622)
		(end 142.599156 -273.073622)
		(width 0.18288)
		(layer "In4.Cu")
		(net "M_F_CPU1_SA_DQ<12>")
	)
	(segment
		(start 130.170174 -269.38351)
		(end 130.076194 -269.38351)
		(width 0.088646)
		(layer "In4.Cu")
		(net "M_F_CPU1_SA_DQ<12>")
	)
	(segment
		(start 161.271966 -295.711626)
		(end 160.96869 -295.585896)
		(width 0.18288)
		(layer "In4.Cu")
		(net "M_F_CPU1_SA_DQ<12>")
	)
	(segment
		(start 163.169854 -297.122342)
		(end 163.169854 -296.508678)
		(width 0.18288)
		(layer "In4.Cu")
		(net "M_F_CPU1_SA_DQ<12>")
	)
	(segment
		(start 166.651686 -299.616622)
		(end 165.765226 -298.730162)
		(width 0.18288)
		(layer "In4.Cu")
		(net "M_F_CPU1_SA_DQ<12>")
	)
	(segment
		(start 160.96869 -295.585896)
		(end 160.86963 -295.347136)
		(width 0.18288)
		(layer "In4.Cu")
		(net "M_F_CPU1_SA_DQ<12>")
	)
	(segment
		(start 138.730482 -269.064232)
		(end 138.721592 -269.059152)
		(width 0.088646)
		(layer "In4.Cu")
		(net "M_F_CPU1_SA_DQ<12>")
	)
	(segment
		(start 160.86963 -295.347136)
		(end 160.97885 -295.083484)
		(width 0.18288)
		(layer "In4.Cu")
		(net "M_F_CPU1_SA_DQ<12>")
	)
	(segment
		(start 164.135308 -297.11396)
		(end 163.876228 -297.11396)
		(width 0.18288)
		(layer "In4.Cu")
		(net "M_F_CPU1_SA_DQ<12>")
	)
	(segment
		(start 162.964622 -296.303446)
		(end 162.578542 -296.303446)
		(width 0.18288)
		(layer "In4.Cu")
		(net "M_F_CPU1_SA_DQ<12>")
	)
	(segment
		(start 161.619692 -295.348914)
		(end 161.510472 -295.612566)
		(width 0.18288)
		(layer "In4.Cu")
		(net "M_F_CPU1_SA_DQ<12>")
	)
	(segment
		(start 160.25622 -294.396414)
		(end 159.729932 -294.236648)
		(width 0.18288)
		(layer "In4.Cu")
		(net "M_F_CPU1_SA_DQ<12>")
	)
	(arc
		(start 133.648196 -269.059152)
		(mid 133.369022 -269.134917)
		(end 133.088888 -269.062708)
		(width 0.088646)
		(layer "In4.Cu")
		(net "M_F_CPU1_SA_DQ<12>")
	)
	(arc
		(start 130.634994 -269.552674)
		(mid 130.417488 -269.427151)
		(end 130.170174 -269.38351)
		(width 0.088646)
		(layer "In4.Cu")
		(net "M_F_CPU1_SA_DQ<12>")
	)
	(arc
		(start 131.100576 -269.780766)
		(mid 131.054001 -269.777846)
		(end 131.008374 -269.768066)
		(width 0.088646)
		(layer "In4.Cu")
		(net "M_F_CPU1_SA_DQ<12>")
	)
	(arc
		(start 138.894058 -269.32763)
		(mid 138.883261 -269.253097)
		(end 138.851894 -269.184628)
		(width 0.088646)
		(layer "In4.Cu")
		(net "M_F_CPU1_SA_DQ<12>")
	)
	(arc
		(start 135.527796 -269.059152)
		(mid 135.247882 -269.134921)
		(end 134.967218 -269.061946)
		(width 0.088646)
		(layer "In4.Cu")
		(net "M_F_CPU1_SA_DQ<12>")
	)
	(arc
		(start 133.077204 -269.05585)
		(mid 132.892349 -269.0089)
		(end 132.708396 -269.059152)
		(width 0.088646)
		(layer "In4.Cu")
		(net "M_F_CPU1_SA_DQ<12>")
	)
	(arc
		(start 138.923014 -269.39748)
		(mid 138.901601 -269.365433)
		(end 138.894058 -269.32763)
		(width 0.088646)
		(layer "In4.Cu")
		(net "M_F_CPU1_SA_DQ<12>")
	)
	(arc
		(start 138.721592 -269.059152)
		(mid 138.534394 -269.009009)
		(end 138.347196 -269.059152)
		(width 0.088646)
		(layer "In4.Cu")
		(net "M_F_CPU1_SA_DQ<12>")
	)
	(arc
		(start 132.473192 -269.340838)
		(mid 132.406158 -269.466179)
		(end 132.315966 -269.576042)
		(width 0.088646)
		(layer "In4.Cu")
		(net "M_F_CPU1_SA_DQ<12>")
	)
	(arc
		(start 132.138674 -269.710662)
		(mid 132.009336 -269.762986)
		(end 131.870958 -269.780766)
		(width 0.088646)
		(layer "In4.Cu")
		(net "M_F_CPU1_SA_DQ<12>")
	)
	(arc
		(start 132.537962 -269.206726)
		(mid 132.523847 -269.223937)
		(end 132.513324 -269.243556)
		(width 0.088646)
		(layer "In4.Cu")
		(net "M_F_CPU1_SA_DQ<12>")
	)
	(arc
		(start 137.407396 -269.059152)
		(mid 137.124694 -269.134928)
		(end 136.841992 -269.059152)
		(width 0.088646)
		(layer "In4.Cu")
		(net "M_F_CPU1_SA_DQ<12>")
	)
	(arc
		(start 135.902446 -269.059152)
		(mid 135.715138 -269.009009)
		(end 135.527796 -269.059152)
		(width 0.088646)
		(layer "In4.Cu")
		(net "M_F_CPU1_SA_DQ<12>")
	)
	(arc
		(start 132.315966 -269.576042)
		(mid 132.23564 -269.646604)
		(end 132.146802 -269.70609)
		(width 0.088646)
		(layer "In4.Cu")
		(net "M_F_CPU1_SA_DQ<12>")
	)
	(arc
		(start 136.841992 -269.059152)
		(mid 136.654794 -269.009009)
		(end 136.467596 -269.059152)
		(width 0.088646)
		(layer "In4.Cu")
		(net "M_F_CPU1_SA_DQ<12>")
	)
	(arc
		(start 138.347196 -269.059152)
		(mid 138.064494 -269.134928)
		(end 137.781792 -269.059152)
		(width 0.088646)
		(layer "In4.Cu")
		(net "M_F_CPU1_SA_DQ<12>")
	)
	(arc
		(start 134.956804 -269.05585)
		(mid 134.771949 -269.0089)
		(end 134.587996 -269.059152)
		(width 0.088646)
		(layer "In4.Cu")
		(net "M_F_CPU1_SA_DQ<12>")
	)
	(arc
		(start 138.849608 -269.180818)
		(mid 138.79661 -269.115817)
		(end 138.730482 -269.064232)
		(width 0.088646)
		(layer "In4.Cu")
		(net "M_F_CPU1_SA_DQ<12>")
	)
	(arc
		(start 137.781792 -269.059152)
		(mid 137.594594 -269.009009)
		(end 137.407396 -269.059152)
		(width 0.088646)
		(layer "In4.Cu")
		(net "M_F_CPU1_SA_DQ<12>")
	)
	(arc
		(start 132.708396 -269.059152)
		(mid 132.65677 -269.093644)
		(end 132.610098 -269.13459)
		(width 0.088646)
		(layer "In4.Cu")
		(net "M_F_CPU1_SA_DQ<12>")
	)
	(arc
		(start 131.008374 -269.768066)
		(mid 130.977173 -269.759524)
		(end 130.945636 -269.752318)
		(width 0.088646)
		(layer "In4.Cu")
		(net "M_F_CPU1_SA_DQ<12>")
	)
	(arc
		(start 130.945636 -269.752318)
		(mid 130.856205 -269.722338)
		(end 130.776726 -269.671546)
		(width 0.088646)
		(layer "In4.Cu")
		(net "M_F_CPU1_SA_DQ<12>")
	)
	(arc
		(start 134.017004 -269.05585)
		(mid 133.832149 -269.0089)
		(end 133.648196 -269.059152)
		(width 0.088646)
		(layer "In4.Cu")
		(net "M_F_CPU1_SA_DQ<12>")
	)
	(arc
		(start 136.467596 -269.059152)
		(mid 136.184894 -269.134928)
		(end 135.902192 -269.059152)
		(width 0.088646)
		(layer "In4.Cu")
		(net "M_F_CPU1_SA_DQ<12>")
	)
	(arc
		(start 134.587996 -269.059152)
		(mid 134.308822 -269.134917)
		(end 134.028688 -269.062708)
		(width 0.088646)
		(layer "In4.Cu")
		(net "M_F_CPU1_SA_DQ<12>")
	)
	(segment
		(start 183.136286 -304.853848)
		(end 183.340248 -304.649886)
		(width 0.20066)
		(layer "F.Cu")
		(net "M_F_CPU1_SA_DQ<11>")
	)
	(segment
		(start 180.427884 -304.848768)
		(end 180.434996 -304.841656)
		(width 0.1016)
		(layer "F.Cu")
		(net "M_F_CPU1_SA_DQ<11>")
	)
	(segment
		(start 183.340248 -304.398934)
		(end 183.574436 -304.164746)
		(width 0.20066)
		(layer "F.Cu")
		(net "M_F_CPU1_SA_DQ<11>")
	)
	(segment
		(start 180.131212 -304.848768)
		(end 180.423058 -304.848768)
		(width 0.20066)
		(layer "F.Cu")
		(net "M_F_CPU1_SA_DQ<11>")
	)
	(segment
		(start 182.455058 -304.853848)
		(end 183.136286 -304.853848)
		(width 0.20066)
		(layer "F.Cu")
		(net "M_F_CPU1_SA_DQ<11>")
	)
	(segment
		(start 131.956048 -271.011142)
		(end 131.955794 -271.011396)
		(width 0.20066)
		(layer "F.Cu")
		(net "M_F_CPU1_SA_DQ<11>")
	)
	(segment
		(start 179.699158 -304.416714)
		(end 180.131212 -304.848768)
		(width 0.20066)
		(layer "F.Cu")
		(net "M_F_CPU1_SA_DQ<11>")
	)
	(segment
		(start 183.574436 -304.164746)
		(end 183.958484 -304.164746)
		(width 0.20066)
		(layer "F.Cu")
		(net "M_F_CPU1_SA_DQ<11>")
	)
	(segment
		(start 183.958484 -304.164746)
		(end 184.210452 -304.416714)
		(width 0.20066)
		(layer "F.Cu")
		(net "M_F_CPU1_SA_DQ<11>")
	)
	(segment
		(start 182.442866 -304.841656)
		(end 182.455058 -304.853848)
		(width 0.1016)
		(layer "F.Cu")
		(net "M_F_CPU1_SA_DQ<11>")
	)
	(segment
		(start 184.210452 -304.416714)
		(end 185.544714 -304.416714)
		(width 0.20066)
		(layer "F.Cu")
		(net "M_F_CPU1_SA_DQ<11>")
	)
	(segment
		(start 131.956048 -270.475456)
		(end 131.956048 -271.011142)
		(width 0.20066)
		(layer "F.Cu")
		(net "M_F_CPU1_SA_DQ<11>")
	)
	(segment
		(start 183.340248 -304.649886)
		(end 183.340248 -304.398934)
		(width 0.20066)
		(layer "F.Cu")
		(net "M_F_CPU1_SA_DQ<11>")
	)
	(segment
		(start 180.434996 -304.841656)
		(end 182.442866 -304.841656)
		(width 0.1016)
		(layer "F.Cu")
		(net "M_F_CPU1_SA_DQ<11>")
	)
	(segment
		(start 178.000914 -304.416714)
		(end 179.699158 -304.416714)
		(width 0.20066)
		(layer "F.Cu")
		(net "M_F_CPU1_SA_DQ<11>")
	)
	(segment
		(start 176.896014 -304.416714)
		(end 178.000914 -304.416714)
		(width 0.20066)
		(layer "F.Cu")
		(net "M_F_CPU1_SA_DQ<11>")
	)
	(segment
		(start 180.423058 -304.848768)
		(end 180.427884 -304.848768)
		(width 0.101854)
		(layer "F.Cu")
		(net "M_F_CPU1_SA_DQ<11>")
	)
	(segment
		(start 139.452604 -272.63852)
		(end 139.19708 -272.63852)
		(width 0.088646)
		(layer "In4.Cu")
		(net "M_F_CPU1_SA_DQ<11>")
	)
	(segment
		(start 134.962646 -271.335754)
		(end 134.956804 -271.33931)
		(width 0.088646)
		(layer "In4.Cu")
		(net "M_F_CPU1_SA_DQ<11>")
	)
	(segment
		(start 134.022846 -271.335754)
		(end 134.017004 -271.33931)
		(width 0.088646)
		(layer "In4.Cu")
		(net "M_F_CPU1_SA_DQ<11>")
	)
	(segment
		(start 166.792656 -303.790096)
		(end 165.432486 -302.429926)
		(width 0.18288)
		(layer "In4.Cu")
		(net "M_F_CPU1_SA_DQ<11>")
	)
	(segment
		(start 142.16126 -274.724876)
		(end 141.837664 -274.724876)
		(width 0.18288)
		(layer "In4.Cu")
		(net "M_F_CPU1_SA_DQ<11>")
	)
	(segment
		(start 137.407396 -271.335754)
		(end 137.392664 -271.327118)
		(width 0.088646)
		(layer "In4.Cu")
		(net "M_F_CPU1_SA_DQ<11>")
	)
	(segment
		(start 142.29969 -274.863306)
		(end 142.16126 -274.724876)
		(width 0.18288)
		(layer "In4.Cu")
		(net "M_F_CPU1_SA_DQ<11>")
	)
	(segment
		(start 168.991026 -304.169826)
		(end 168.611296 -303.790096)
		(width 0.18288)
		(layer "In4.Cu")
		(net "M_F_CPU1_SA_DQ<11>")
	)
	(segment
		(start 137.413492 -271.33931)
		(end 137.407396 -271.335754)
		(width 0.088646)
		(layer "In4.Cu")
		(net "M_F_CPU1_SA_DQ<11>")
	)
	(segment
		(start 139.19708 -272.63852)
		(end 139.133326 -272.574766)
		(width 0.088646)
		(layer "In4.Cu")
		(net "M_F_CPU1_SA_DQ<11>")
	)
	(segment
		(start 134.967218 -271.333214)
		(end 134.962646 -271.335754)
		(width 0.088646)
		(layer "In4.Cu")
		(net "M_F_CPU1_SA_DQ<11>")
	)
	(segment
		(start 161.284666 -300.59249)
		(end 158.222442 -297.530266)
		(width 0.18288)
		(layer "In4.Cu")
		(net "M_F_CPU1_SA_DQ<11>")
	)
	(segment
		(start 165.432486 -302.429926)
		(end 164.772086 -302.429926)
		(width 0.18288)
		(layer "In4.Cu")
		(net "M_F_CPU1_SA_DQ<11>")
	)
	(segment
		(start 168.611296 -303.790096)
		(end 166.792656 -303.790096)
		(width 0.18288)
		(layer "In4.Cu")
		(net "M_F_CPU1_SA_DQ<11>")
	)
	(segment
		(start 141.837664 -274.724876)
		(end 139.751308 -272.63852)
		(width 0.18288)
		(layer "In4.Cu")
		(net "M_F_CPU1_SA_DQ<11>")
	)
	(segment
		(start 134.028688 -271.332452)
		(end 134.022846 -271.335754)
		(width 0.088646)
		(layer "In4.Cu")
		(net "M_F_CPU1_SA_DQ<11>")
	)
	(segment
		(start 139.133326 -272.574766)
		(end 139.041886 -272.389346)
		(width 0.088646)
		(layer "In4.Cu")
		(net "M_F_CPU1_SA_DQ<11>")
	)
	(segment
		(start 158.222442 -297.530266)
		(end 157.342078 -297.165268)
		(width 0.18288)
		(layer "In4.Cu")
		(net "M_F_CPU1_SA_DQ<11>")
	)
	(segment
		(start 162.93465 -300.59249)
		(end 161.284666 -300.59249)
		(width 0.18288)
		(layer "In4.Cu")
		(net "M_F_CPU1_SA_DQ<11>")
	)
	(segment
		(start 136.467596 -271.335754)
		(end 136.452864 -271.327118)
		(width 0.088646)
		(layer "In4.Cu")
		(net "M_F_CPU1_SA_DQ<11>")
	)
	(segment
		(start 176.896014 -304.416714)
		(end 176.224438 -304.416714)
		(width 0.18288)
		(layer "In4.Cu")
		(net "M_F_CPU1_SA_DQ<11>")
	)
	(segment
		(start 157.342078 -297.165268)
		(end 152.402032 -292.226238)
		(width 0.18288)
		(layer "In4.Cu")
		(net "M_F_CPU1_SA_DQ<11>")
	)
	(segment
		(start 138.266678 -272.140934)
		(end 138.251946 -272.14957)
		(width 0.088646)
		(layer "In4.Cu")
		(net "M_F_CPU1_SA_DQ<11>")
	)
	(segment
		(start 133.088888 -271.332452)
		(end 133.083046 -271.335754)
		(width 0.088646)
		(layer "In4.Cu")
		(net "M_F_CPU1_SA_DQ<11>")
	)
	(segment
		(start 137.87755 -272.14957)
		(end 137.86866 -272.14449)
		(width 0.088646)
		(layer "In4.Cu")
		(net "M_F_CPU1_SA_DQ<11>")
	)
	(segment
		(start 152.402032 -292.226238)
		(end 147.268184 -279.831038)
		(width 0.18288)
		(layer "In4.Cu")
		(net "M_F_CPU1_SA_DQ<11>")
	)
	(segment
		(start 147.268184 -279.831038)
		(end 142.29969 -274.863306)
		(width 0.18288)
		(layer "In4.Cu")
		(net "M_F_CPU1_SA_DQ<11>")
	)
	(segment
		(start 172.578522 -304.842418)
		(end 171.90593 -304.169826)
		(width 0.18288)
		(layer "In4.Cu")
		(net "M_F_CPU1_SA_DQ<11>")
	)
	(segment
		(start 175.798734 -304.842418)
		(end 172.578522 -304.842418)
		(width 0.18288)
		(layer "In4.Cu")
		(net "M_F_CPU1_SA_DQ<11>")
	)
	(segment
		(start 133.083046 -271.335754)
		(end 133.077204 -271.33931)
		(width 0.088646)
		(layer "In4.Cu")
		(net "M_F_CPU1_SA_DQ<11>")
	)
	(segment
		(start 139.751308 -272.63852)
		(end 139.452604 -272.63852)
		(width 0.18288)
		(layer "In4.Cu")
		(net "M_F_CPU1_SA_DQ<11>")
	)
	(segment
		(start 171.90593 -304.169826)
		(end 168.991026 -304.169826)
		(width 0.18288)
		(layer "In4.Cu")
		(net "M_F_CPU1_SA_DQ<11>")
	)
	(segment
		(start 176.224438 -304.416714)
		(end 175.798734 -304.842418)
		(width 0.18288)
		(layer "In4.Cu")
		(net "M_F_CPU1_SA_DQ<11>")
	)
	(segment
		(start 164.772086 -302.429926)
		(end 162.93465 -300.59249)
		(width 0.18288)
		(layer "In4.Cu")
		(net "M_F_CPU1_SA_DQ<11>")
	)
	(arc
		(start 135.527796 -271.335754)
		(mid 135.247852 -271.26011)
		(end 134.967218 -271.333214)
		(width 0.088646)
		(layer "In4.Cu")
		(net "M_F_CPU1_SA_DQ<11>")
	)
	(arc
		(start 136.841992 -271.335754)
		(mid 136.654794 -271.385897)
		(end 136.467596 -271.335754)
		(width 0.088646)
		(layer "In4.Cu")
		(net "M_F_CPU1_SA_DQ<11>")
	)
	(arc
		(start 138.251946 -272.14957)
		(mid 138.064748 -272.199713)
		(end 137.87755 -272.14957)
		(width 0.088646)
		(layer "In4.Cu")
		(net "M_F_CPU1_SA_DQ<11>")
	)
	(arc
		(start 133.077204 -271.33931)
		(mid 132.892349 -271.386228)
		(end 132.708396 -271.336008)
		(width 0.088646)
		(layer "In4.Cu")
		(net "M_F_CPU1_SA_DQ<11>")
	)
	(arc
		(start 137.690098 -271.825212)
		(mid 137.616107 -271.545646)
		(end 137.413492 -271.33931)
		(width 0.088646)
		(layer "In4.Cu")
		(net "M_F_CPU1_SA_DQ<11>")
	)
	(arc
		(start 136.452864 -271.327118)
		(mid 136.176389 -271.259798)
		(end 135.902192 -271.335754)
		(width 0.088646)
		(layer "In4.Cu")
		(net "M_F_CPU1_SA_DQ<11>")
	)
	(arc
		(start 133.648196 -271.336008)
		(mid 133.369022 -271.260209)
		(end 133.088888 -271.332452)
		(width 0.088646)
		(layer "In4.Cu")
		(net "M_F_CPU1_SA_DQ<11>")
	)
	(arc
		(start 137.86866 -272.14449)
		(mid 137.737746 -272.00813)
		(end 137.690098 -271.825212)
		(width 0.088646)
		(layer "In4.Cu")
		(net "M_F_CPU1_SA_DQ<11>")
	)
	(arc
		(start 134.017004 -271.33931)
		(mid 133.832149 -271.386228)
		(end 133.648196 -271.336008)
		(width 0.088646)
		(layer "In4.Cu")
		(net "M_F_CPU1_SA_DQ<11>")
	)
	(arc
		(start 132.708396 -271.336008)
		(mid 132.341511 -271.151871)
		(end 131.955794 -271.011396)
		(width 0.088646)
		(layer "In4.Cu")
		(net "M_F_CPU1_SA_DQ<11>")
	)
	(arc
		(start 139.041886 -272.389346)
		(mid 138.94738 -272.252834)
		(end 138.81735 -272.14957)
		(width 0.088646)
		(layer "In4.Cu")
		(net "M_F_CPU1_SA_DQ<11>")
	)
	(arc
		(start 137.392664 -271.327118)
		(mid 137.116189 -271.259798)
		(end 136.841992 -271.335754)
		(width 0.088646)
		(layer "In4.Cu")
		(net "M_F_CPU1_SA_DQ<11>")
	)
	(arc
		(start 135.902192 -271.335754)
		(mid 135.714994 -271.385897)
		(end 135.527796 -271.335754)
		(width 0.088646)
		(layer "In4.Cu")
		(net "M_F_CPU1_SA_DQ<11>")
	)
	(arc
		(start 134.956804 -271.33931)
		(mid 134.771949 -271.386228)
		(end 134.587996 -271.336008)
		(width 0.088646)
		(layer "In4.Cu")
		(net "M_F_CPU1_SA_DQ<11>")
	)
	(arc
		(start 138.81735 -272.14957)
		(mid 138.543121 -272.073645)
		(end 138.266678 -272.140934)
		(width 0.088646)
		(layer "In4.Cu")
		(net "M_F_CPU1_SA_DQ<11>")
	)
	(arc
		(start 134.587996 -271.336008)
		(mid 134.308822 -271.260209)
		(end 134.028688 -271.332452)
		(width 0.088646)
		(layer "In4.Cu")
		(net "M_F_CPU1_SA_DQ<11>")
	)
	(segment
		(start 131.485894 -271.289272)
		(end 131.486148 -271.825212)
		(width 0.20066)
		(layer "F.Cu")
		(net "M_F_CPU1_SA_DQ<10>")
	)
	(segment
		(start 183.958484 -305.864768)
		(end 184.210452 -306.116736)
		(width 0.20066)
		(layer "F.Cu")
		(net "M_F_CPU1_SA_DQ<10>")
	)
	(segment
		(start 176.896014 -306.116736)
		(end 178.000914 -306.116736)
		(width 0.20066)
		(layer "F.Cu")
		(net "M_F_CPU1_SA_DQ<10>")
	)
	(segment
		(start 180.131212 -306.54879)
		(end 180.423058 -306.54879)
		(width 0.20066)
		(layer "F.Cu")
		(net "M_F_CPU1_SA_DQ<10>")
	)
	(segment
		(start 180.427884 -306.54879)
		(end 180.434996 -306.541678)
		(width 0.1016)
		(layer "F.Cu")
		(net "M_F_CPU1_SA_DQ<10>")
	)
	(segment
		(start 182.455058 -306.55387)
		(end 183.136286 -306.55387)
		(width 0.20066)
		(layer "F.Cu")
		(net "M_F_CPU1_SA_DQ<10>")
	)
	(segment
		(start 180.423058 -306.54879)
		(end 180.427884 -306.54879)
		(width 0.101854)
		(layer "F.Cu")
		(net "M_F_CPU1_SA_DQ<10>")
	)
	(segment
		(start 183.574436 -305.864768)
		(end 183.958484 -305.864768)
		(width 0.20066)
		(layer "F.Cu")
		(net "M_F_CPU1_SA_DQ<10>")
	)
	(segment
		(start 178.000914 -306.116736)
		(end 179.699158 -306.116736)
		(width 0.20066)
		(layer "F.Cu")
		(net "M_F_CPU1_SA_DQ<10>")
	)
	(segment
		(start 179.699158 -306.116736)
		(end 180.131212 -306.54879)
		(width 0.20066)
		(layer "F.Cu")
		(net "M_F_CPU1_SA_DQ<10>")
	)
	(segment
		(start 184.210452 -306.116736)
		(end 185.544714 -306.116736)
		(width 0.20066)
		(layer "F.Cu")
		(net "M_F_CPU1_SA_DQ<10>")
	)
	(segment
		(start 183.340248 -306.098956)
		(end 183.574436 -305.864768)
		(width 0.20066)
		(layer "F.Cu")
		(net "M_F_CPU1_SA_DQ<10>")
	)
	(segment
		(start 180.434996 -306.541678)
		(end 182.442866 -306.541678)
		(width 0.1016)
		(layer "F.Cu")
		(net "M_F_CPU1_SA_DQ<10>")
	)
	(segment
		(start 183.340248 -306.349908)
		(end 183.340248 -306.098956)
		(width 0.20066)
		(layer "F.Cu")
		(net "M_F_CPU1_SA_DQ<10>")
	)
	(segment
		(start 182.442866 -306.541678)
		(end 182.455058 -306.55387)
		(width 0.1016)
		(layer "F.Cu")
		(net "M_F_CPU1_SA_DQ<10>")
	)
	(segment
		(start 183.136286 -306.55387)
		(end 183.340248 -306.349908)
		(width 0.20066)
		(layer "F.Cu")
		(net "M_F_CPU1_SA_DQ<10>")
	)
	(segment
		(start 159.58058 -301.312072)
		(end 158.64078 -300.372272)
		(width 0.18288)
		(layer "In4.Cu")
		(net "M_F_CPU1_SA_DQ<10>")
	)
	(segment
		(start 164.815266 -303.903126)
		(end 164.606986 -304.111406)
		(width 0.18288)
		(layer "In4.Cu")
		(net "M_F_CPU1_SA_DQ<10>")
	)
	(segment
		(start 163.945062 -304.111406)
		(end 162.884612 -303.424844)
		(width 0.18288)
		(layer "In4.Cu")
		(net "M_F_CPU1_SA_DQ<10>")
	)
	(segment
		(start 167.456866 -305.643026)
		(end 167.057832 -305.531012)
		(width 0.18288)
		(layer "In4.Cu")
		(net "M_F_CPU1_SA_DQ<10>")
	)
	(segment
		(start 137.219944 -272.639282)
		(end 137.219944 -272.617184)
		(width 0.088646)
		(layer "In4.Cu")
		(net "M_F_CPU1_SA_DQ<10>")
	)
	(segment
		(start 134.122668 -272.152364)
		(end 134.118096 -272.149824)
		(width 0.088646)
		(layer "In4.Cu")
		(net "M_F_CPU1_SA_DQ<10>")
	)
	(segment
		(start 135.057896 -272.149824)
		(end 135.05053 -272.145506)
		(width 0.088646)
		(layer "In4.Cu")
		(net "M_F_CPU1_SA_DQ<10>")
	)
	(segment
		(start 160.720786 -301.639986)
		(end 160.392872 -301.312072)
		(width 0.18288)
		(layer "In4.Cu")
		(net "M_F_CPU1_SA_DQ<10>")
	)
	(segment
		(start 158.64078 -299.670216)
		(end 157.861 -298.890436)
		(width 0.18288)
		(layer "In4.Cu")
		(net "M_F_CPU1_SA_DQ<10>")
	)
	(segment
		(start 172.437806 -306.54244)
		(end 171.885102 -306.443634)
		(width 0.18288)
		(layer "In4.Cu")
		(net "M_F_CPU1_SA_DQ<10>")
	)
	(segment
		(start 161.029396 -302.689006)
		(end 160.720786 -301.639986)
		(width 0.18288)
		(layer "In4.Cu")
		(net "M_F_CPU1_SA_DQ<10>")
	)
	(segment
		(start 138.989054 -273.550888)
		(end 138.476482 -273.038316)
		(width 0.088646)
		(layer "In4.Cu")
		(net "M_F_CPU1_SA_DQ<10>")
	)
	(segment
		(start 151.593042 -292.960298)
		(end 146.373088 -280.357326)
		(width 0.18288)
		(layer "In4.Cu")
		(net "M_F_CPU1_SA_DQ<10>")
	)
	(segment
		(start 176.8856 -306.111656)
		(end 176.577244 -306.216812)
		(width 0.18288)
		(layer "In4.Cu")
		(net "M_F_CPU1_SA_DQ<10>")
	)
	(segment
		(start 139.452604 -273.550888)
		(end 138.989054 -273.550888)
		(width 0.088646)
		(layer "In4.Cu")
		(net "M_F_CPU1_SA_DQ<10>")
	)
	(segment
		(start 141.357096 -275.341334)
		(end 141.346936 -275.31695)
		(width 0.18288)
		(layer "In4.Cu")
		(net "M_F_CPU1_SA_DQ<10>")
	)
	(segment
		(start 146.373088 -280.357326)
		(end 141.357096 -275.341334)
		(width 0.18288)
		(layer "In4.Cu")
		(net "M_F_CPU1_SA_DQ<10>")
	)
	(segment
		(start 141.346936 -275.31695)
		(end 139.580874 -273.550888)
		(width 0.18288)
		(layer "In4.Cu")
		(net "M_F_CPU1_SA_DQ<10>")
	)
	(segment
		(start 176.577244 -306.216812)
		(end 175.621442 -306.54244)
		(width 0.18288)
		(layer "In4.Cu")
		(net "M_F_CPU1_SA_DQ<10>")
	)
	(segment
		(start 137.407396 -272.96364)
		(end 137.398506 -272.95856)
		(width 0.088646)
		(layer "In4.Cu")
		(net "M_F_CPU1_SA_DQ<10>")
	)
	(segment
		(start 139.580874 -273.550888)
		(end 139.452604 -273.550888)
		(width 0.18288)
		(layer "In4.Cu")
		(net "M_F_CPU1_SA_DQ<10>")
	)
	(segment
		(start 157.52318 -298.890436)
		(end 151.593042 -292.960298)
		(width 0.18288)
		(layer "In4.Cu")
		(net "M_F_CPU1_SA_DQ<10>")
	)
	(segment
		(start 132.238496 -272.149824)
		(end 132.208524 -272.132298)
		(width 0.088646)
		(layer "In4.Cu")
		(net "M_F_CPU1_SA_DQ<10>")
	)
	(segment
		(start 135.99795 -272.14957)
		(end 135.997696 -272.149824)
		(width 0.088646)
		(layer "In4.Cu")
		(net "M_F_CPU1_SA_DQ<10>")
	)
	(segment
		(start 167.057832 -305.531012)
		(end 165.429946 -303.903126)
		(width 0.18288)
		(layer "In4.Cu")
		(net "M_F_CPU1_SA_DQ<10>")
	)
	(segment
		(start 165.429946 -303.903126)
		(end 164.815266 -303.903126)
		(width 0.18288)
		(layer "In4.Cu")
		(net "M_F_CPU1_SA_DQ<10>")
	)
	(segment
		(start 132.243068 -272.152364)
		(end 132.238496 -272.149824)
		(width 0.088646)
		(layer "In4.Cu")
		(net "M_F_CPU1_SA_DQ<10>")
	)
	(segment
		(start 157.861 -298.890436)
		(end 157.52318 -298.890436)
		(width 0.18288)
		(layer "In4.Cu")
		(net "M_F_CPU1_SA_DQ<10>")
	)
	(segment
		(start 162.216846 -303.142396)
		(end 161.447226 -303.142396)
		(width 0.18288)
		(layer "In4.Cu")
		(net "M_F_CPU1_SA_DQ<10>")
	)
	(segment
		(start 136.387078 -272.140934)
		(end 136.372346 -272.14957)
		(width 0.088646)
		(layer "In4.Cu")
		(net "M_F_CPU1_SA_DQ<10>")
	)
	(segment
		(start 133.182868 -272.152364)
		(end 133.178296 -272.149824)
		(width 0.088646)
		(layer "In4.Cu")
		(net "M_F_CPU1_SA_DQ<10>")
	)
	(segment
		(start 162.884612 -303.424844)
		(end 162.216846 -303.142396)
		(width 0.18288)
		(layer "In4.Cu")
		(net "M_F_CPU1_SA_DQ<10>")
	)
	(segment
		(start 171.885102 -306.443634)
		(end 170.613578 -306.276502)
		(width 0.18288)
		(layer "In4.Cu")
		(net "M_F_CPU1_SA_DQ<10>")
	)
	(segment
		(start 160.392872 -301.312072)
		(end 159.58058 -301.312072)
		(width 0.18288)
		(layer "In4.Cu")
		(net "M_F_CPU1_SA_DQ<10>")
	)
	(segment
		(start 158.64078 -300.372272)
		(end 158.64078 -299.670216)
		(width 0.18288)
		(layer "In4.Cu")
		(net "M_F_CPU1_SA_DQ<10>")
	)
	(segment
		(start 164.606986 -304.111406)
		(end 163.945062 -304.111406)
		(width 0.18288)
		(layer "In4.Cu")
		(net "M_F_CPU1_SA_DQ<10>")
	)
	(segment
		(start 175.621442 -306.54244)
		(end 172.437806 -306.54244)
		(width 0.18288)
		(layer "In4.Cu")
		(net "M_F_CPU1_SA_DQ<10>")
	)
	(segment
		(start 161.447226 -303.142396)
		(end 161.265616 -303.008792)
		(width 0.18288)
		(layer "In4.Cu")
		(net "M_F_CPU1_SA_DQ<10>")
	)
	(segment
		(start 161.265616 -303.008792)
		(end 161.029396 -302.689006)
		(width 0.18288)
		(layer "In4.Cu")
		(net "M_F_CPU1_SA_DQ<10>")
	)
	(segment
		(start 170.613578 -306.276502)
		(end 167.708326 -305.643026)
		(width 0.18288)
		(layer "In4.Cu")
		(net "M_F_CPU1_SA_DQ<10>")
	)
	(segment
		(start 133.178296 -272.149824)
		(end 133.17093 -272.145506)
		(width 0.088646)
		(layer "In4.Cu")
		(net "M_F_CPU1_SA_DQ<10>")
	)
	(segment
		(start 176.896014 -306.116736)
		(end 176.8856 -306.111656)
		(width 0.18288)
		(layer "In4.Cu")
		(net "M_F_CPU1_SA_DQ<10>")
	)
	(segment
		(start 167.708326 -305.643026)
		(end 167.456866 -305.643026)
		(width 0.18288)
		(layer "In4.Cu")
		(net "M_F_CPU1_SA_DQ<10>")
	)
	(segment
		(start 135.061706 -272.151856)
		(end 135.057896 -272.149824)
		(width 0.088646)
		(layer "In4.Cu")
		(net "M_F_CPU1_SA_DQ<10>")
	)
	(segment
		(start 138.476482 -273.038316)
		(end 138.347196 -272.96364)
		(width 0.088646)
		(layer "In4.Cu")
		(net "M_F_CPU1_SA_DQ<10>")
	)
	(segment
		(start 134.118096 -272.149824)
		(end 134.11073 -272.145506)
		(width 0.088646)
		(layer "In4.Cu")
		(net "M_F_CPU1_SA_DQ<10>")
	)
	(arc
		(start 132.613146 -272.149824)
		(mid 132.428452 -272.199925)
		(end 132.243068 -272.152364)
		(width 0.088646)
		(layer "In4.Cu")
		(net "M_F_CPU1_SA_DQ<10>")
	)
	(arc
		(start 136.93775 -272.14957)
		(mid 136.663521 -272.073645)
		(end 136.387078 -272.140934)
		(width 0.088646)
		(layer "In4.Cu")
		(net "M_F_CPU1_SA_DQ<10>")
	)
	(arc
		(start 137.398506 -272.95856)
		(mid 137.267592 -272.8222)
		(end 137.219944 -272.639282)
		(width 0.088646)
		(layer "In4.Cu")
		(net "M_F_CPU1_SA_DQ<10>")
	)
	(arc
		(start 135.432546 -272.149824)
		(mid 135.247396 -272.199928)
		(end 135.061706 -272.151856)
		(width 0.088646)
		(layer "In4.Cu")
		(net "M_F_CPU1_SA_DQ<10>")
	)
	(arc
		(start 134.11073 -272.145506)
		(mid 133.831269 -272.074069)
		(end 133.552946 -272.149824)
		(width 0.088646)
		(layer "In4.Cu")
		(net "M_F_CPU1_SA_DQ<10>")
	)
	(arc
		(start 138.347196 -272.96364)
		(mid 138.064494 -272.887864)
		(end 137.781792 -272.96364)
		(width 0.088646)
		(layer "In4.Cu")
		(net "M_F_CPU1_SA_DQ<10>")
	)
	(arc
		(start 137.219944 -272.617184)
		(mid 137.139033 -272.347056)
		(end 136.93775 -272.14957)
		(width 0.088646)
		(layer "In4.Cu")
		(net "M_F_CPU1_SA_DQ<10>")
	)
	(arc
		(start 133.17093 -272.145506)
		(mid 132.891469 -272.074069)
		(end 132.613146 -272.149824)
		(width 0.088646)
		(layer "In4.Cu")
		(net "M_F_CPU1_SA_DQ<10>")
	)
	(arc
		(start 136.372346 -272.14957)
		(mid 136.185148 -272.199713)
		(end 135.99795 -272.14957)
		(width 0.088646)
		(layer "In4.Cu")
		(net "M_F_CPU1_SA_DQ<10>")
	)
	(arc
		(start 137.781792 -272.96364)
		(mid 137.594594 -273.013783)
		(end 137.407396 -272.96364)
		(width 0.088646)
		(layer "In4.Cu")
		(net "M_F_CPU1_SA_DQ<10>")
	)
	(arc
		(start 132.208524 -272.132298)
		(mid 131.857114 -271.955753)
		(end 131.486148 -271.825212)
		(width 0.088646)
		(layer "In4.Cu")
		(net "M_F_CPU1_SA_DQ<10>")
	)
	(arc
		(start 135.997696 -272.149824)
		(mid 135.715138 -272.074175)
		(end 135.432546 -272.149824)
		(width 0.088646)
		(layer "In4.Cu")
		(net "M_F_CPU1_SA_DQ<10>")
	)
	(arc
		(start 134.492746 -272.149824)
		(mid 134.308052 -272.199925)
		(end 134.122668 -272.152364)
		(width 0.088646)
		(layer "In4.Cu")
		(net "M_F_CPU1_SA_DQ<10>")
	)
	(arc
		(start 133.552946 -272.149824)
		(mid 133.368252 -272.199925)
		(end 133.182868 -272.152364)
		(width 0.088646)
		(layer "In4.Cu")
		(net "M_F_CPU1_SA_DQ<10>")
	)
	(arc
		(start 135.05053 -272.145506)
		(mid 134.771069 -272.074069)
		(end 134.492746 -272.149824)
		(width 0.088646)
		(layer "In4.Cu")
		(net "M_F_CPU1_SA_DQ<10>")
	)
	(segment
		(start 179.004976 -315.891672)
		(end 176.843182 -315.891672)
		(width 0.1016)
		(layer "F.Cu")
		(net "M_F_CPU1_SA_DQ<0>")
	)
	(segment
		(start 132.425694 -278.336248)
		(end 132.425948 -278.336502)
		(width 0.20066)
		(layer "F.Cu")
		(net "M_F_CPU1_SA_DQ<0>")
	)
	(segment
		(start 181.444646 -316.316614)
		(end 181.444392 -316.316868)
		(width 0.20066)
		(layer "F.Cu")
		(net "M_F_CPU1_SA_DQ<0>")
	)
	(segment
		(start 179.421282 -315.885322)
		(end 179.011326 -315.885322)
		(width 0.20066)
		(layer "F.Cu")
		(net "M_F_CPU1_SA_DQ<0>")
	)
	(segment
		(start 176.451514 -315.891672)
		(end 176.333404 -316.009782)
		(width 0.20066)
		(layer "F.Cu")
		(net "M_F_CPU1_SA_DQ<0>")
	)
	(segment
		(start 176.333404 -316.37732)
		(end 176.145444 -316.56528)
		(width 0.20066)
		(layer "F.Cu")
		(net "M_F_CPU1_SA_DQ<0>")
	)
	(segment
		(start 176.843182 -315.891672)
		(end 176.796192 -315.891672)
		(width 0.101854)
		(layer "F.Cu")
		(net "M_F_CPU1_SA_DQ<0>")
	)
	(segment
		(start 176.333404 -316.009782)
		(end 176.333404 -316.37732)
		(width 0.20066)
		(layer "F.Cu")
		(net "M_F_CPU1_SA_DQ<0>")
	)
	(segment
		(start 179.852828 -316.316868)
		(end 179.421282 -315.885322)
		(width 0.20066)
		(layer "F.Cu")
		(net "M_F_CPU1_SA_DQ<0>")
	)
	(segment
		(start 181.444392 -316.316868)
		(end 179.852828 -316.316868)
		(width 0.20066)
		(layer "F.Cu")
		(net "M_F_CPU1_SA_DQ<0>")
	)
	(segment
		(start 176.145444 -316.56528)
		(end 175.67021 -316.56528)
		(width 0.20066)
		(layer "F.Cu")
		(net "M_F_CPU1_SA_DQ<0>")
	)
	(segment
		(start 175.421544 -316.316614)
		(end 173.900846 -316.316614)
		(width 0.20066)
		(layer "F.Cu")
		(net "M_F_CPU1_SA_DQ<0>")
	)
	(segment
		(start 176.796192 -315.891672)
		(end 176.451514 -315.891672)
		(width 0.20066)
		(layer "F.Cu")
		(net "M_F_CPU1_SA_DQ<0>")
	)
	(segment
		(start 173.900846 -316.316614)
		(end 172.795946 -316.316614)
		(width 0.20066)
		(layer "F.Cu")
		(net "M_F_CPU1_SA_DQ<0>")
	)
	(segment
		(start 132.425694 -277.800562)
		(end 132.425694 -278.336248)
		(width 0.20066)
		(layer "F.Cu")
		(net "M_F_CPU1_SA_DQ<0>")
	)
	(segment
		(start 175.67021 -316.56528)
		(end 175.421544 -316.316614)
		(width 0.20066)
		(layer "F.Cu")
		(net "M_F_CPU1_SA_DQ<0>")
	)
	(segment
		(start 179.011326 -315.885322)
		(end 179.004976 -315.891672)
		(width 0.1016)
		(layer "F.Cu")
		(net "M_F_CPU1_SA_DQ<0>")
	)
	(segment
		(start 166.673276 -317.155068)
		(end 165.892734 -317.155068)
		(width 0.18288)
		(layer "In2.Cu")
		(net "M_F_CPU1_SA_DQ<0>")
	)
	(segment
		(start 159.772858 -316.725046)
		(end 159.500062 -316.725046)
		(width 0.18288)
		(layer "In2.Cu")
		(net "M_F_CPU1_SA_DQ<0>")
	)
	(segment
		(start 133.270244 -279.150318)
		(end 133.270244 -279.141682)
		(width 0.088646)
		(layer "In2.Cu")
		(net "M_F_CPU1_SA_DQ<0>")
	)
	(segment
		(start 158.021274 -316.725046)
		(end 157.373574 -316.725046)
		(width 0.18288)
		(layer "In2.Cu")
		(net "M_F_CPU1_SA_DQ<0>")
	)
	(segment
		(start 137.792206 -280.459942)
		(end 137.781792 -280.453846)
		(width 0.088646)
		(layer "In2.Cu")
		(net "M_F_CPU1_SA_DQ<0>")
	)
	(segment
		(start 170.203876 -316.39129)
		(end 169.85234 -316.742826)
		(width 0.18288)
		(layer "In2.Cu")
		(net "M_F_CPU1_SA_DQ<0>")
	)
	(segment
		(start 169.85234 -316.742826)
		(end 168.897808 -316.742826)
		(width 0.18288)
		(layer "In2.Cu")
		(net "M_F_CPU1_SA_DQ<0>")
	)
	(segment
		(start 163.258754 -316.37859)
		(end 162.573462 -316.37859)
		(width 0.18288)
		(layer "In2.Cu")
		(net "M_F_CPU1_SA_DQ<0>")
	)
	(segment
		(start 161.506662 -316.743334)
		(end 161.172398 -316.40907)
		(width 0.18288)
		(layer "In2.Cu")
		(net "M_F_CPU1_SA_DQ<0>")
	)
	(segment
		(start 172.795946 -316.316614)
		(end 172.357288 -316.755272)
		(width 0.18288)
		(layer "In2.Cu")
		(net "M_F_CPU1_SA_DQ<0>")
	)
	(segment
		(start 144.270476 -295.852342)
		(end 142.351506 -293.933372)
		(width 0.18288)
		(layer "In2.Cu")
		(net "M_F_CPU1_SA_DQ<0>")
	)
	(segment
		(start 138.689842 -280.402792)
		(end 138.534902 -280.402792)
		(width 0.088646)
		(layer "In2.Cu")
		(net "M_F_CPU1_SA_DQ<0>")
	)
	(segment
		(start 145.506186 -304.857658)
		(end 145.506186 -298.835826)
		(width 0.18288)
		(layer "In2.Cu")
		(net "M_F_CPU1_SA_DQ<0>")
	)
	(segment
		(start 140.771626 -284.35427)
		(end 140.006832 -282.507182)
		(width 0.18288)
		(layer "In2.Cu")
		(net "M_F_CPU1_SA_DQ<0>")
	)
	(segment
		(start 133.561836 -279.644856)
		(end 133.54685 -279.63622)
		(width 0.088646)
		(layer "In2.Cu")
		(net "M_F_CPU1_SA_DQ<0>")
	)
	(segment
		(start 133.740398 -279.986232)
		(end 133.740398 -279.964134)
		(width 0.088646)
		(layer "In2.Cu")
		(net "M_F_CPU1_SA_DQ<0>")
	)
	(segment
		(start 164.329364 -316.743334)
		(end 163.623498 -316.743334)
		(width 0.18288)
		(layer "In2.Cu")
		(net "M_F_CPU1_SA_DQ<0>")
	)
	(segment
		(start 171.200318 -316.755272)
		(end 170.836336 -316.39129)
		(width 0.18288)
		(layer "In2.Cu")
		(net "M_F_CPU1_SA_DQ<0>")
	)
	(segment
		(start 163.623498 -316.743334)
		(end 163.258754 -316.37859)
		(width 0.18288)
		(layer "In2.Cu")
		(net "M_F_CPU1_SA_DQ<0>")
	)
	(segment
		(start 168.564052 -316.40907)
		(end 167.419274 -316.40907)
		(width 0.18288)
		(layer "In2.Cu")
		(net "M_F_CPU1_SA_DQ<0>")
	)
	(segment
		(start 167.419274 -316.40907)
		(end 166.673276 -317.155068)
		(width 0.18288)
		(layer "In2.Cu")
		(net "M_F_CPU1_SA_DQ<0>")
	)
	(segment
		(start 157.373574 -316.725046)
		(end 145.506186 -304.857658)
		(width 0.18288)
		(layer "In2.Cu")
		(net "M_F_CPU1_SA_DQ<0>")
	)
	(segment
		(start 134.587996 -280.453846)
		(end 134.573264 -280.462482)
		(width 0.088646)
		(layer "In2.Cu")
		(net "M_F_CPU1_SA_DQ<0>")
	)
	(segment
		(start 162.573462 -316.37859)
		(end 162.208718 -316.743334)
		(width 0.18288)
		(layer "In2.Cu")
		(net "M_F_CPU1_SA_DQ<0>")
	)
	(segment
		(start 139.148058 -280.861008)
		(end 138.689842 -280.402792)
		(width 0.088646)
		(layer "In2.Cu")
		(net "M_F_CPU1_SA_DQ<0>")
	)
	(segment
		(start 165.892734 -317.155068)
		(end 165.304724 -316.567058)
		(width 0.18288)
		(layer "In2.Cu")
		(net "M_F_CPU1_SA_DQ<0>")
	)
	(segment
		(start 165.304724 -316.567058)
		(end 164.50564 -316.567058)
		(width 0.18288)
		(layer "In2.Cu")
		(net "M_F_CPU1_SA_DQ<0>")
	)
	(segment
		(start 132.738876 -278.336502)
		(end 132.425948 -278.336502)
		(width 0.088646)
		(layer "In2.Cu")
		(net "M_F_CPU1_SA_DQ<0>")
	)
	(segment
		(start 170.836336 -316.39129)
		(end 170.203876 -316.39129)
		(width 0.18288)
		(layer "In2.Cu")
		(net "M_F_CPU1_SA_DQ<0>")
	)
	(segment
		(start 164.50564 -316.567058)
		(end 164.329364 -316.743334)
		(width 0.18288)
		(layer "In2.Cu")
		(net "M_F_CPU1_SA_DQ<0>")
	)
	(segment
		(start 159.500062 -316.725046)
		(end 159.234378 -316.99073)
		(width 0.18288)
		(layer "In2.Cu")
		(net "M_F_CPU1_SA_DQ<0>")
	)
	(segment
		(start 162.208718 -316.743334)
		(end 161.506662 -316.743334)
		(width 0.18288)
		(layer "In2.Cu")
		(net "M_F_CPU1_SA_DQ<0>")
	)
	(segment
		(start 132.804154 -278.40178)
		(end 132.738876 -278.336502)
		(width 0.088646)
		(layer "In2.Cu")
		(net "M_F_CPU1_SA_DQ<0>")
	)
	(segment
		(start 161.172398 -316.40907)
		(end 160.088834 -316.40907)
		(width 0.18288)
		(layer "In2.Cu")
		(net "M_F_CPU1_SA_DQ<0>")
	)
	(segment
		(start 139.859004 -282.150566)
		(end 139.450064 -281.163014)
		(width 0.18288)
		(layer "In2.Cu")
		(net "M_F_CPU1_SA_DQ<0>")
	)
	(segment
		(start 142.351506 -293.933372)
		(end 140.861034 -290.334954)
		(width 0.18288)
		(layer "In2.Cu")
		(net "M_F_CPU1_SA_DQ<0>")
	)
	(segment
		(start 168.897808 -316.742826)
		(end 168.564052 -316.40907)
		(width 0.18288)
		(layer "In2.Cu")
		(net "M_F_CPU1_SA_DQ<0>")
	)
	(segment
		(start 140.861034 -284.570424)
		(end 140.771626 -284.35427)
		(width 0.18288)
		(layer "In2.Cu")
		(net "M_F_CPU1_SA_DQ<0>")
	)
	(segment
		(start 172.357288 -316.755272)
		(end 171.200318 -316.755272)
		(width 0.18288)
		(layer "In2.Cu")
		(net "M_F_CPU1_SA_DQ<0>")
	)
	(segment
		(start 159.234378 -316.99073)
		(end 158.286958 -316.99073)
		(width 0.18288)
		(layer "In2.Cu")
		(net "M_F_CPU1_SA_DQ<0>")
	)
	(segment
		(start 140.006832 -282.507182)
		(end 139.859004 -282.150566)
		(width 0.18288)
		(layer "In2.Cu")
		(net "M_F_CPU1_SA_DQ<0>")
	)
	(segment
		(start 140.861034 -290.334954)
		(end 140.861034 -284.570424)
		(width 0.18288)
		(layer "In2.Cu")
		(net "M_F_CPU1_SA_DQ<0>")
	)
	(segment
		(start 158.286958 -316.99073)
		(end 158.021274 -316.725046)
		(width 0.18288)
		(layer "In2.Cu")
		(net "M_F_CPU1_SA_DQ<0>")
	)
	(segment
		(start 139.450064 -281.163014)
		(end 139.148058 -280.861008)
		(width 0.18288)
		(layer "In2.Cu")
		(net "M_F_CPU1_SA_DQ<0>")
	)
	(segment
		(start 145.506186 -298.835826)
		(end 144.270476 -295.852342)
		(width 0.18288)
		(layer "In2.Cu")
		(net "M_F_CPU1_SA_DQ<0>")
	)
	(segment
		(start 134.977124 -280.462482)
		(end 134.962392 -280.453846)
		(width 0.088646)
		(layer "In2.Cu")
		(net "M_F_CPU1_SA_DQ<0>")
	)
	(segment
		(start 160.088834 -316.40907)
		(end 159.772858 -316.725046)
		(width 0.18288)
		(layer "In2.Cu")
		(net "M_F_CPU1_SA_DQ<0>")
	)
	(arc
		(start 133.270244 -279.141682)
		(mid 133.217974 -278.959317)
		(end 133.083046 -278.82596)
		(width 0.088646)
		(layer "In2.Cu")
		(net "M_F_CPU1_SA_DQ<0>")
	)
	(arc
		(start 134.573264 -280.462482)
		(mid 134.296823 -280.529648)
		(end 134.022592 -280.453846)
		(width 0.088646)
		(layer "In2.Cu")
		(net "M_F_CPU1_SA_DQ<0>")
	)
	(arc
		(start 134.022592 -280.453846)
		(mid 133.82131 -280.256359)
		(end 133.740398 -279.986232)
		(width 0.088646)
		(layer "In2.Cu")
		(net "M_F_CPU1_SA_DQ<0>")
	)
	(arc
		(start 134.962392 -280.453846)
		(mid 134.775194 -280.403703)
		(end 134.587996 -280.453846)
		(width 0.088646)
		(layer "In2.Cu")
		(net "M_F_CPU1_SA_DQ<0>")
	)
	(arc
		(start 133.083046 -278.82596)
		(mid 132.893296 -278.646946)
		(end 132.804154 -278.40178)
		(width 0.088646)
		(layer "In2.Cu")
		(net "M_F_CPU1_SA_DQ<0>")
	)
	(arc
		(start 138.34745 -280.453846)
		(mid 138.070637 -280.529682)
		(end 137.792206 -280.459942)
		(width 0.088646)
		(layer "In2.Cu")
		(net "M_F_CPU1_SA_DQ<0>")
	)
	(arc
		(start 138.534902 -280.402792)
		(mid 138.437821 -280.415988)
		(end 138.34745 -280.453846)
		(width 0.088646)
		(layer "In2.Cu")
		(net "M_F_CPU1_SA_DQ<0>")
	)
	(arc
		(start 135.527796 -280.453846)
		(mid 135.253567 -280.529771)
		(end 134.977124 -280.462482)
		(width 0.088646)
		(layer "In2.Cu")
		(net "M_F_CPU1_SA_DQ<0>")
	)
	(arc
		(start 137.781792 -280.453846)
		(mid 137.594594 -280.403703)
		(end 137.407396 -280.453846)
		(width 0.088646)
		(layer "In2.Cu")
		(net "M_F_CPU1_SA_DQ<0>")
	)
	(arc
		(start 136.467596 -280.453846)
		(mid 136.184894 -280.529588)
		(end 135.902192 -280.453846)
		(width 0.088646)
		(layer "In2.Cu")
		(net "M_F_CPU1_SA_DQ<0>")
	)
	(arc
		(start 135.902192 -280.453846)
		(mid 135.714994 -280.403703)
		(end 135.527796 -280.453846)
		(width 0.088646)
		(layer "In2.Cu")
		(net "M_F_CPU1_SA_DQ<0>")
	)
	(arc
		(start 133.54685 -279.63622)
		(mid 133.344263 -279.429869)
		(end 133.270244 -279.150318)
		(width 0.088646)
		(layer "In2.Cu")
		(net "M_F_CPU1_SA_DQ<0>")
	)
	(arc
		(start 136.841992 -280.453846)
		(mid 136.654794 -280.403703)
		(end 136.467596 -280.453846)
		(width 0.088646)
		(layer "In2.Cu")
		(net "M_F_CPU1_SA_DQ<0>")
	)
	(arc
		(start 133.740398 -279.964134)
		(mid 133.692719 -279.781234)
		(end 133.561836 -279.644856)
		(width 0.088646)
		(layer "In2.Cu")
		(net "M_F_CPU1_SA_DQ<0>")
	)
	(arc
		(start 137.407396 -280.453846)
		(mid 137.124694 -280.529588)
		(end 136.841992 -280.453846)
		(width 0.088646)
		(layer "In2.Cu")
		(net "M_F_CPU1_SA_DQ<0>")
	)
	(segment
		(start 133.365494 -258.2672)
		(end 133.365748 -258.267454)
		(width 0.20066)
		(layer "F.Cu")
		(net "M_F_CPU1_SA_CS_N<3>")
	)
	(segment
		(start 176.896014 -267.016738)
		(end 178.000914 -267.016738)
		(width 0.20066)
		(layer "F.Cu")
		(net "M_F_CPU1_SA_CS_N<3>")
	)
	(segment
		(start 133.365748 -258.267454)
		(end 133.365748 -258.80314)
		(width 0.20066)
		(layer "F.Cu")
		(net "M_F_CPU1_SA_CS_N<3>")
	)
	(segment
		(start 169.168826 -266.639802)
		(end 168.855136 -266.326112)
		(width 0.18288)
		(layer "In2.Cu")
		(net "M_F_CPU1_SA_CS_N<3>")
	)
	(segment
		(start 172.685964 -267.440918)
		(end 172.523912 -267.440918)
		(width 0.18288)
		(layer "In2.Cu")
		(net "M_F_CPU1_SA_CS_N<3>")
	)
	(segment
		(start 164.582602 -265.163046)
		(end 164.143436 -265.163046)
		(width 0.18288)
		(layer "In2.Cu")
		(net "M_F_CPU1_SA_CS_N<3>")
	)
	(segment
		(start 155.468828 -262.597138)
		(end 153.21788 -260.34619)
		(width 0.18288)
		(layer "In2.Cu")
		(net "M_F_CPU1_SA_CS_N<3>")
	)
	(segment
		(start 139.819126 -258.86029)
		(end 139.627864 -259.051552)
		(width 0.088646)
		(layer "In2.Cu")
		(net "M_F_CPU1_SA_CS_N<3>")
	)
	(segment
		(start 168.855136 -266.065508)
		(end 167.665654 -264.876026)
		(width 0.18288)
		(layer "In2.Cu")
		(net "M_F_CPU1_SA_CS_N<3>")
	)
	(segment
		(start 135.07212 -259.135626)
		(end 135.057896 -259.127498)
		(width 0.088646)
		(layer "In2.Cu")
		(net "M_F_CPU1_SA_CS_N<3>")
	)
	(segment
		(start 172.686218 -267.441172)
		(end 172.685964 -267.440918)
		(width 0.18288)
		(layer "In2.Cu")
		(net "M_F_CPU1_SA_CS_N<3>")
	)
	(segment
		(start 165.495732 -264.876026)
		(end 165.244526 -264.62482)
		(width 0.18288)
		(layer "In2.Cu")
		(net "M_F_CPU1_SA_CS_N<3>")
	)
	(segment
		(start 138.266424 -259.118862)
		(end 138.251692 -259.127498)
		(width 0.088646)
		(layer "In2.Cu")
		(net "M_F_CPU1_SA_CS_N<3>")
	)
	(segment
		(start 137.326624 -259.118862)
		(end 137.311892 -259.127498)
		(width 0.088646)
		(layer "In2.Cu")
		(net "M_F_CPU1_SA_CS_N<3>")
	)
	(segment
		(start 148.041868 -260.34619)
		(end 146.882358 -259.18668)
		(width 0.18288)
		(layer "In2.Cu")
		(net "M_F_CPU1_SA_CS_N<3>")
	)
	(segment
		(start 140.90015 -258.86029)
		(end 139.819126 -258.86029)
		(width 0.088646)
		(layer "In2.Cu")
		(net "M_F_CPU1_SA_CS_N<3>")
	)
	(segment
		(start 135.08482 -259.141722)
		(end 135.07212 -259.135626)
		(width 0.088646)
		(layer "In2.Cu")
		(net "M_F_CPU1_SA_CS_N<3>")
	)
	(segment
		(start 173.716696 -267.12164)
		(end 173.397164 -267.441172)
		(width 0.18288)
		(layer "In2.Cu")
		(net "M_F_CPU1_SA_CS_N<3>")
	)
	(segment
		(start 135.444484 -259.12064)
		(end 135.432546 -259.127498)
		(width 0.088646)
		(layer "In2.Cu")
		(net "M_F_CPU1_SA_CS_N<3>")
	)
	(segment
		(start 172.523912 -267.440918)
		(end 171.73194 -266.648946)
		(width 0.18288)
		(layer "In2.Cu")
		(net "M_F_CPU1_SA_CS_N<3>")
	)
	(segment
		(start 139.627864 -259.051552)
		(end 139.482576 -259.051552)
		(width 0.088646)
		(layer "In2.Cu")
		(net "M_F_CPU1_SA_CS_N<3>")
	)
	(segment
		(start 146.882358 -259.18668)
		(end 146.094196 -258.86029)
		(width 0.18288)
		(layer "In2.Cu")
		(net "M_F_CPU1_SA_CS_N<3>")
	)
	(segment
		(start 153.21788 -260.34619)
		(end 148.041868 -260.34619)
		(width 0.18288)
		(layer "In2.Cu")
		(net "M_F_CPU1_SA_CS_N<3>")
	)
	(segment
		(start 160.709102 -264.060178)
		(end 157.430978 -264.060178)
		(width 0.18288)
		(layer "In2.Cu")
		(net "M_F_CPU1_SA_CS_N<3>")
	)
	(segment
		(start 167.665654 -264.876026)
		(end 165.495732 -264.876026)
		(width 0.18288)
		(layer "In2.Cu")
		(net "M_F_CPU1_SA_CS_N<3>")
	)
	(segment
		(start 170.205146 -266.280646)
		(end 169.84599 -266.639802)
		(width 0.18288)
		(layer "In2.Cu")
		(net "M_F_CPU1_SA_CS_N<3>")
	)
	(segment
		(start 170.589194 -266.280646)
		(end 170.205146 -266.280646)
		(width 0.18288)
		(layer "In2.Cu")
		(net "M_F_CPU1_SA_CS_N<3>")
	)
	(segment
		(start 146.094196 -258.86029)
		(end 140.90015 -258.86029)
		(width 0.18288)
		(layer "In2.Cu")
		(net "M_F_CPU1_SA_CS_N<3>")
	)
	(segment
		(start 175.58893 -267.256514)
		(end 175.404526 -267.440918)
		(width 0.18288)
		(layer "In2.Cu")
		(net "M_F_CPU1_SA_CS_N<3>")
	)
	(segment
		(start 176.656238 -267.256514)
		(end 175.58893 -267.256514)
		(width 0.18288)
		(layer "In2.Cu")
		(net "M_F_CPU1_SA_CS_N<3>")
	)
	(segment
		(start 133.372098 -258.818126)
		(end 133.365748 -258.80314)
		(width 0.088646)
		(layer "In2.Cu")
		(net "M_F_CPU1_SA_CS_N<3>")
	)
	(segment
		(start 169.84599 -266.639802)
		(end 169.168826 -266.639802)
		(width 0.18288)
		(layer "In2.Cu")
		(net "M_F_CPU1_SA_CS_N<3>")
	)
	(segment
		(start 174.038006 -267.12164)
		(end 173.716696 -267.12164)
		(width 0.18288)
		(layer "In2.Cu")
		(net "M_F_CPU1_SA_CS_N<3>")
	)
	(segment
		(start 163.896802 -264.916412)
		(end 161.565336 -264.916412)
		(width 0.18288)
		(layer "In2.Cu")
		(net "M_F_CPU1_SA_CS_N<3>")
	)
	(segment
		(start 161.565336 -264.916412)
		(end 160.709102 -264.060178)
		(width 0.18288)
		(layer "In2.Cu")
		(net "M_F_CPU1_SA_CS_N<3>")
	)
	(segment
		(start 135.997696 -259.127498)
		(end 135.997442 -259.127498)
		(width 0.088646)
		(layer "In2.Cu")
		(net "M_F_CPU1_SA_CS_N<3>")
	)
	(segment
		(start 174.357284 -267.440918)
		(end 174.038006 -267.12164)
		(width 0.18288)
		(layer "In2.Cu")
		(net "M_F_CPU1_SA_CS_N<3>")
	)
	(segment
		(start 164.143436 -265.163046)
		(end 163.896802 -264.916412)
		(width 0.18288)
		(layer "In2.Cu")
		(net "M_F_CPU1_SA_CS_N<3>")
	)
	(segment
		(start 175.404526 -267.440918)
		(end 174.357284 -267.440918)
		(width 0.18288)
		(layer "In2.Cu")
		(net "M_F_CPU1_SA_CS_N<3>")
	)
	(segment
		(start 173.397164 -267.441172)
		(end 172.686218 -267.441172)
		(width 0.18288)
		(layer "In2.Cu")
		(net "M_F_CPU1_SA_CS_N<3>")
	)
	(segment
		(start 165.244526 -264.62482)
		(end 164.872924 -264.62482)
		(width 0.18288)
		(layer "In2.Cu")
		(net "M_F_CPU1_SA_CS_N<3>")
	)
	(segment
		(start 155.967938 -262.597138)
		(end 155.468828 -262.597138)
		(width 0.18288)
		(layer "In2.Cu")
		(net "M_F_CPU1_SA_CS_N<3>")
	)
	(segment
		(start 134.50316 -259.121402)
		(end 134.492746 -259.127498)
		(width 0.088646)
		(layer "In2.Cu")
		(net "M_F_CPU1_SA_CS_N<3>")
	)
	(segment
		(start 164.679884 -265.065764)
		(end 164.582602 -265.163046)
		(width 0.18288)
		(layer "In2.Cu")
		(net "M_F_CPU1_SA_CS_N<3>")
	)
	(segment
		(start 164.679884 -264.81786)
		(end 164.679884 -265.065764)
		(width 0.18288)
		(layer "In2.Cu")
		(net "M_F_CPU1_SA_CS_N<3>")
	)
	(segment
		(start 136.386824 -259.118862)
		(end 136.372092 -259.127498)
		(width 0.088646)
		(layer "In2.Cu")
		(net "M_F_CPU1_SA_CS_N<3>")
	)
	(segment
		(start 170.957494 -266.648946)
		(end 170.589194 -266.280646)
		(width 0.18288)
		(layer "In2.Cu")
		(net "M_F_CPU1_SA_CS_N<3>")
	)
	(segment
		(start 134.11835 -259.127498)
		(end 133.372098 -258.818126)
		(width 0.088646)
		(layer "In2.Cu")
		(net "M_F_CPU1_SA_CS_N<3>")
	)
	(segment
		(start 171.73194 -266.648946)
		(end 170.957494 -266.648946)
		(width 0.18288)
		(layer "In2.Cu")
		(net "M_F_CPU1_SA_CS_N<3>")
	)
	(segment
		(start 164.872924 -264.62482)
		(end 164.679884 -264.81786)
		(width 0.18288)
		(layer "In2.Cu")
		(net "M_F_CPU1_SA_CS_N<3>")
	)
	(segment
		(start 139.206224 -259.118862)
		(end 139.191492 -259.127498)
		(width 0.088646)
		(layer "In2.Cu")
		(net "M_F_CPU1_SA_CS_N<3>")
	)
	(segment
		(start 157.430978 -264.060178)
		(end 155.967938 -262.597138)
		(width 0.18288)
		(layer "In2.Cu")
		(net "M_F_CPU1_SA_CS_N<3>")
	)
	(segment
		(start 168.855136 -266.326112)
		(end 168.855136 -266.065508)
		(width 0.18288)
		(layer "In2.Cu")
		(net "M_F_CPU1_SA_CS_N<3>")
	)
	(segment
		(start 176.896014 -267.016738)
		(end 176.656238 -267.256514)
		(width 0.18288)
		(layer "In2.Cu")
		(net "M_F_CPU1_SA_CS_N<3>")
	)
	(arc
		(start 134.492746 -259.127498)
		(mid 134.305548 -259.177641)
		(end 134.11835 -259.127498)
		(width 0.088646)
		(layer "In2.Cu")
		(net "M_F_CPU1_SA_CS_N<3>")
	)
	(arc
		(start 135.057896 -259.127498)
		(mid 134.781337 -259.051755)
		(end 134.50316 -259.121402)
		(width 0.088646)
		(layer "In2.Cu")
		(net "M_F_CPU1_SA_CS_N<3>")
	)
	(arc
		(start 135.406638 -259.14096)
		(mid 135.40435 -259.142099)
		(end 135.402066 -259.143246)
		(width 0.088646)
		(layer "In2.Cu")
		(net "M_F_CPU1_SA_CS_N<3>")
	)
	(arc
		(start 139.482576 -259.051552)
		(mid 139.340101 -259.067553)
		(end 139.206224 -259.118862)
		(width 0.088646)
		(layer "In2.Cu")
		(net "M_F_CPU1_SA_CS_N<3>")
	)
	(arc
		(start 135.45058 -259.117338)
		(mid 135.447517 -259.11896)
		(end 135.444484 -259.12064)
		(width 0.088646)
		(layer "In2.Cu")
		(net "M_F_CPU1_SA_CS_N<3>")
	)
	(arc
		(start 135.432546 -259.127498)
		(mid 135.419722 -259.134479)
		(end 135.406638 -259.14096)
		(width 0.088646)
		(layer "In2.Cu")
		(net "M_F_CPU1_SA_CS_N<3>")
	)
	(arc
		(start 137.877296 -259.127498)
		(mid 137.603097 -259.051663)
		(end 137.326624 -259.118862)
		(width 0.088646)
		(layer "In2.Cu")
		(net "M_F_CPU1_SA_CS_N<3>")
	)
	(arc
		(start 135.995156 -259.126482)
		(mid 135.724034 -259.051935)
		(end 135.45058 -259.117338)
		(width 0.088646)
		(layer "In2.Cu")
		(net "M_F_CPU1_SA_CS_N<3>")
	)
	(arc
		(start 138.251692 -259.127498)
		(mid 138.064494 -259.177641)
		(end 137.877296 -259.127498)
		(width 0.088646)
		(layer "In2.Cu")
		(net "M_F_CPU1_SA_CS_N<3>")
	)
	(arc
		(start 138.817096 -259.127498)
		(mid 138.542897 -259.051663)
		(end 138.266424 -259.118862)
		(width 0.088646)
		(layer "In2.Cu")
		(net "M_F_CPU1_SA_CS_N<3>")
	)
	(arc
		(start 136.937496 -259.127498)
		(mid 136.663297 -259.051663)
		(end 136.386824 -259.118862)
		(width 0.088646)
		(layer "In2.Cu")
		(net "M_F_CPU1_SA_CS_N<3>")
	)
	(arc
		(start 136.372092 -259.127498)
		(mid 136.184894 -259.177641)
		(end 135.997696 -259.127498)
		(width 0.088646)
		(layer "In2.Cu")
		(net "M_F_CPU1_SA_CS_N<3>")
	)
	(arc
		(start 137.311892 -259.127498)
		(mid 137.124694 -259.177641)
		(end 136.937496 -259.127498)
		(width 0.088646)
		(layer "In2.Cu")
		(net "M_F_CPU1_SA_CS_N<3>")
	)
	(arc
		(start 135.402066 -259.143246)
		(mid 135.243276 -259.177718)
		(end 135.08482 -259.141722)
		(width 0.088646)
		(layer "In2.Cu")
		(net "M_F_CPU1_SA_CS_N<3>")
	)
	(arc
		(start 135.997442 -259.127498)
		(mid 135.996299 -259.126989)
		(end 135.995156 -259.126482)
		(width 0.088646)
		(layer "In2.Cu")
		(net "M_F_CPU1_SA_CS_N<3>")
	)
	(arc
		(start 139.191492 -259.127498)
		(mid 139.004294 -259.177641)
		(end 138.817096 -259.127498)
		(width 0.088646)
		(layer "In2.Cu")
		(net "M_F_CPU1_SA_CS_N<3>")
	)
	(segment
		(start 133.835648 -259.081016)
		(end 133.835648 -259.616702)
		(width 0.20066)
		(layer "F.Cu")
		(net "M_F_CPU1_SA_CS_N<2>")
	)
	(segment
		(start 133.835648 -259.616702)
		(end 133.835394 -259.616956)
		(width 0.20066)
		(layer "F.Cu")
		(net "M_F_CPU1_SA_CS_N<2>")
	)
	(segment
		(start 173.900846 -267.866622)
		(end 172.719746 -267.866622)
		(width 0.20066)
		(layer "F.Cu")
		(net "M_F_CPU1_SA_CS_N<2>")
	)
	(segment
		(start 156.615638 -264.601706)
		(end 156.615638 -264.142982)
		(width 0.18288)
		(layer "In2.Cu")
		(net "M_F_CPU1_SA_CS_N<2>")
	)
	(segment
		(start 158.73222 -264.995406)
		(end 158.55061 -265.177016)
		(width 0.18288)
		(layer "In2.Cu")
		(net "M_F_CPU1_SA_CS_N<2>")
	)
	(segment
		(start 147.96262 -260.862572)
		(end 146.670522 -259.570474)
		(width 0.18288)
		(layer "In2.Cu")
		(net "M_F_CPU1_SA_CS_N<2>")
	)
	(segment
		(start 156.346906 -263.87425)
		(end 155.888182 -263.87425)
		(width 0.18288)
		(layer "In2.Cu")
		(net "M_F_CPU1_SA_CS_N<2>")
	)
	(segment
		(start 139.713462 -259.24256)
		(end 139.47394 -259.24256)
		(width 0.088646)
		(layer "In2.Cu")
		(net "M_F_CPU1_SA_CS_N<2>")
	)
	(segment
		(start 134.367778 -259.365242)
		(end 134.185914 -259.470144)
		(width 0.088646)
		(layer "In2.Cu")
		(net "M_F_CPU1_SA_CS_N<2>")
	)
	(segment
		(start 161.446718 -265.815572)
		(end 161.068004 -265.815572)
		(width 0.18288)
		(layer "In2.Cu")
		(net "M_F_CPU1_SA_CS_N<2>")
	)
	(segment
		(start 167.708326 -265.80719)
		(end 167.2844 -265.80719)
		(width 0.18288)
		(layer "In2.Cu")
		(net "M_F_CPU1_SA_CS_N<2>")
	)
	(segment
		(start 139.286742 -259.292598)
		(end 139.27201 -259.301234)
		(width 0.088646)
		(layer "In2.Cu")
		(net "M_F_CPU1_SA_CS_N<2>")
	)
	(segment
		(start 136.467342 -259.292598)
		(end 136.45261 -259.301234)
		(width 0.088646)
		(layer "In2.Cu")
		(net "M_F_CPU1_SA_CS_N<2>")
	)
	(segment
		(start 168.3131 -266.770612)
		(end 168.18864 -266.895072)
		(width 0.18288)
		(layer "In2.Cu")
		(net "M_F_CPU1_SA_CS_N<2>")
	)
	(segment
		(start 167.2844 -265.80719)
		(end 166.939722 -265.462512)
		(width 0.18288)
		(layer "In2.Cu")
		(net "M_F_CPU1_SA_CS_N<2>")
	)
	(segment
		(start 168.53916 -266.770612)
		(end 168.3131 -266.770612)
		(width 0.18288)
		(layer "In2.Cu")
		(net "M_F_CPU1_SA_CS_N<2>")
	)
	(segment
		(start 165.43401 -265.746738)
		(end 165.43401 -266.281662)
		(width 0.18288)
		(layer "In2.Cu")
		(net "M_F_CPU1_SA_CS_N<2>")
	)
	(segment
		(start 146.670522 -259.570474)
		(end 145.794222 -259.207508)
		(width 0.18288)
		(layer "In2.Cu")
		(net "M_F_CPU1_SA_CS_N<2>")
	)
	(segment
		(start 145.794222 -259.207508)
		(end 140.90015 -259.207508)
		(width 0.18288)
		(layer "In2.Cu")
		(net "M_F_CPU1_SA_CS_N<2>")
	)
	(segment
		(start 155.888182 -263.87425)
		(end 152.876504 -260.862572)
		(width 0.18288)
		(layer "In2.Cu")
		(net "M_F_CPU1_SA_CS_N<2>")
	)
	(segment
		(start 164.96792 -266.474702)
		(end 164.23259 -265.739372)
		(width 0.18288)
		(layer "In2.Cu")
		(net "M_F_CPU1_SA_CS_N<2>")
	)
	(segment
		(start 163.79825 -265.739372)
		(end 163.488624 -266.048998)
		(width 0.18288)
		(layer "In2.Cu")
		(net "M_F_CPU1_SA_CS_N<2>")
	)
	(segment
		(start 168.96588 -267.197332)
		(end 168.53916 -266.770612)
		(width 0.18288)
		(layer "In2.Cu")
		(net "M_F_CPU1_SA_CS_N<2>")
	)
	(segment
		(start 161.687002 -265.575288)
		(end 161.446718 -265.815572)
		(width 0.18288)
		(layer "In2.Cu")
		(net "M_F_CPU1_SA_CS_N<2>")
	)
	(segment
		(start 156.864304 -264.850372)
		(end 156.615638 -264.601706)
		(width 0.18288)
		(layer "In2.Cu")
		(net "M_F_CPU1_SA_CS_N<2>")
	)
	(segment
		(start 162.435032 -266.048998)
		(end 161.961322 -265.575288)
		(width 0.18288)
		(layer "In2.Cu")
		(net "M_F_CPU1_SA_CS_N<2>")
	)
	(segment
		(start 171.672504 -267.361924)
		(end 171.3992 -267.361924)
		(width 0.18288)
		(layer "In2.Cu")
		(net "M_F_CPU1_SA_CS_N<2>")
	)
	(segment
		(start 169.31894 -267.197332)
		(end 168.96588 -267.197332)
		(width 0.18288)
		(layer "In2.Cu")
		(net "M_F_CPU1_SA_CS_N<2>")
	)
	(segment
		(start 171.02074 -267.740384)
		(end 169.861992 -267.740384)
		(width 0.18288)
		(layer "In2.Cu")
		(net "M_F_CPU1_SA_CS_N<2>")
	)
	(segment
		(start 166.939722 -265.462512)
		(end 165.718236 -265.462512)
		(width 0.18288)
		(layer "In2.Cu")
		(net "M_F_CPU1_SA_CS_N<2>")
	)
	(segment
		(start 140.90015 -259.207508)
		(end 139.748514 -259.207508)
		(width 0.088646)
		(layer "In2.Cu")
		(net "M_F_CPU1_SA_CS_N<2>")
	)
	(segment
		(start 171.3992 -267.361924)
		(end 171.02074 -267.740384)
		(width 0.18288)
		(layer "In2.Cu")
		(net "M_F_CPU1_SA_CS_N<2>")
	)
	(segment
		(start 134.587996 -259.292598)
		(end 134.573264 -259.301234)
		(width 0.088646)
		(layer "In2.Cu")
		(net "M_F_CPU1_SA_CS_N<2>")
	)
	(segment
		(start 137.407142 -259.292598)
		(end 137.39241 -259.301234)
		(width 0.088646)
		(layer "In2.Cu")
		(net "M_F_CPU1_SA_CS_N<2>")
	)
	(segment
		(start 139.748514 -259.207508)
		(end 139.713462 -259.24256)
		(width 0.088646)
		(layer "In2.Cu")
		(net "M_F_CPU1_SA_CS_N<2>")
	)
	(segment
		(start 168.18864 -266.895072)
		(end 167.96258 -266.895072)
		(width 0.18288)
		(layer "In2.Cu")
		(net "M_F_CPU1_SA_CS_N<2>")
	)
	(segment
		(start 167.96258 -266.895072)
		(end 167.698166 -266.630658)
		(width 0.18288)
		(layer "In2.Cu")
		(net "M_F_CPU1_SA_CS_N<2>")
	)
	(segment
		(start 172.719746 -267.866622)
		(end 172.177202 -267.866622)
		(width 0.18288)
		(layer "In2.Cu")
		(net "M_F_CPU1_SA_CS_N<2>")
	)
	(segment
		(start 167.698166 -266.630658)
		(end 167.698166 -266.369038)
		(width 0.18288)
		(layer "In2.Cu")
		(net "M_F_CPU1_SA_CS_N<2>")
	)
	(segment
		(start 135.53948 -259.28574)
		(end 135.527542 -259.292598)
		(width 0.088646)
		(layer "In2.Cu")
		(net "M_F_CPU1_SA_CS_N<2>")
	)
	(segment
		(start 158.212028 -265.177016)
		(end 157.885384 -264.850372)
		(width 0.18288)
		(layer "In2.Cu")
		(net "M_F_CPU1_SA_CS_N<2>")
	)
	(segment
		(start 165.43401 -266.281662)
		(end 165.24097 -266.474702)
		(width 0.18288)
		(layer "In2.Cu")
		(net "M_F_CPU1_SA_CS_N<2>")
	)
	(segment
		(start 161.068004 -265.815572)
		(end 160.76549 -265.513058)
		(width 0.18288)
		(layer "In2.Cu")
		(net "M_F_CPU1_SA_CS_N<2>")
	)
	(segment
		(start 160.483042 -264.598658)
		(end 159.859218 -264.598658)
		(width 0.18288)
		(layer "In2.Cu")
		(net "M_F_CPU1_SA_CS_N<2>")
	)
	(segment
		(start 156.615638 -264.142982)
		(end 156.346906 -263.87425)
		(width 0.18288)
		(layer "In2.Cu")
		(net "M_F_CPU1_SA_CS_N<2>")
	)
	(segment
		(start 167.86987 -265.968734)
		(end 167.708326 -265.80719)
		(width 0.18288)
		(layer "In2.Cu")
		(net "M_F_CPU1_SA_CS_N<2>")
	)
	(segment
		(start 160.76549 -265.513058)
		(end 160.76549 -264.881106)
		(width 0.18288)
		(layer "In2.Cu")
		(net "M_F_CPU1_SA_CS_N<2>")
	)
	(segment
		(start 160.76549 -264.881106)
		(end 160.483042 -264.598658)
		(width 0.18288)
		(layer "In2.Cu")
		(net "M_F_CPU1_SA_CS_N<2>")
	)
	(segment
		(start 163.488624 -266.048998)
		(end 162.435032 -266.048998)
		(width 0.18288)
		(layer "In2.Cu")
		(net "M_F_CPU1_SA_CS_N<2>")
	)
	(segment
		(start 172.177202 -267.866622)
		(end 171.672504 -267.361924)
		(width 0.18288)
		(layer "In2.Cu")
		(net "M_F_CPU1_SA_CS_N<2>")
	)
	(segment
		(start 157.885384 -264.850372)
		(end 156.864304 -264.850372)
		(width 0.18288)
		(layer "In2.Cu")
		(net "M_F_CPU1_SA_CS_N<2>")
	)
	(segment
		(start 167.86987 -266.197334)
		(end 167.86987 -265.968734)
		(width 0.18288)
		(layer "In2.Cu")
		(net "M_F_CPU1_SA_CS_N<2>")
	)
	(segment
		(start 165.24097 -266.474702)
		(end 164.96792 -266.474702)
		(width 0.18288)
		(layer "In2.Cu")
		(net "M_F_CPU1_SA_CS_N<2>")
	)
	(segment
		(start 165.718236 -265.462512)
		(end 165.43401 -265.746738)
		(width 0.18288)
		(layer "In2.Cu")
		(net "M_F_CPU1_SA_CS_N<2>")
	)
	(segment
		(start 152.876504 -260.862572)
		(end 147.96262 -260.862572)
		(width 0.18288)
		(layer "In2.Cu")
		(net "M_F_CPU1_SA_CS_N<2>")
	)
	(segment
		(start 161.961322 -265.575288)
		(end 161.687002 -265.575288)
		(width 0.18288)
		(layer "In2.Cu")
		(net "M_F_CPU1_SA_CS_N<2>")
	)
	(segment
		(start 167.698166 -266.369038)
		(end 167.86987 -266.197334)
		(width 0.18288)
		(layer "In2.Cu")
		(net "M_F_CPU1_SA_CS_N<2>")
	)
	(segment
		(start 134.185914 -259.470144)
		(end 133.835394 -259.616956)
		(width 0.088646)
		(layer "In2.Cu")
		(net "M_F_CPU1_SA_CS_N<2>")
	)
	(segment
		(start 134.962646 -259.292598)
		(end 134.962392 -259.292598)
		(width 0.088646)
		(layer "In2.Cu")
		(net "M_F_CPU1_SA_CS_N<2>")
	)
	(segment
		(start 159.859218 -264.598658)
		(end 159.46247 -264.995406)
		(width 0.18288)
		(layer "In2.Cu")
		(net "M_F_CPU1_SA_CS_N<2>")
	)
	(segment
		(start 138.346942 -259.292598)
		(end 138.33221 -259.301234)
		(width 0.088646)
		(layer "In2.Cu")
		(net "M_F_CPU1_SA_CS_N<2>")
	)
	(segment
		(start 169.861992 -267.740384)
		(end 169.31894 -267.197332)
		(width 0.18288)
		(layer "In2.Cu")
		(net "M_F_CPU1_SA_CS_N<2>")
	)
	(segment
		(start 164.23259 -265.739372)
		(end 163.79825 -265.739372)
		(width 0.18288)
		(layer "In2.Cu")
		(net "M_F_CPU1_SA_CS_N<2>")
	)
	(segment
		(start 159.46247 -264.995406)
		(end 158.73222 -264.995406)
		(width 0.18288)
		(layer "In2.Cu")
		(net "M_F_CPU1_SA_CS_N<2>")
	)
	(segment
		(start 158.55061 -265.177016)
		(end 158.212028 -265.177016)
		(width 0.18288)
		(layer "In2.Cu")
		(net "M_F_CPU1_SA_CS_N<2>")
	)
	(arc
		(start 135.527542 -259.292598)
		(mid 135.245094 -259.368247)
		(end 134.962646 -259.292598)
		(width 0.088646)
		(layer "In2.Cu")
		(net "M_F_CPU1_SA_CS_N<2>")
	)
	(arc
		(start 134.573264 -259.301234)
		(mid 134.473589 -259.343077)
		(end 134.367778 -259.365242)
		(width 0.088646)
		(layer "In2.Cu")
		(net "M_F_CPU1_SA_CS_N<2>")
	)
	(arc
		(start 134.962392 -259.292598)
		(mid 134.775194 -259.242455)
		(end 134.587996 -259.292598)
		(width 0.088646)
		(layer "In2.Cu")
		(net "M_F_CPU1_SA_CS_N<2>")
	)
	(arc
		(start 139.27201 -259.301234)
		(mid 138.995535 -259.368554)
		(end 138.721338 -259.292598)
		(width 0.088646)
		(layer "In2.Cu")
		(net "M_F_CPU1_SA_CS_N<2>")
	)
	(arc
		(start 137.39241 -259.301234)
		(mid 137.115935 -259.368554)
		(end 136.841738 -259.292598)
		(width 0.088646)
		(layer "In2.Cu")
		(net "M_F_CPU1_SA_CS_N<2>")
	)
	(arc
		(start 138.33221 -259.301234)
		(mid 138.055735 -259.368554)
		(end 137.781538 -259.292598)
		(width 0.088646)
		(layer "In2.Cu")
		(net "M_F_CPU1_SA_CS_N<2>")
	)
	(arc
		(start 138.721338 -259.292598)
		(mid 138.53414 -259.242455)
		(end 138.346942 -259.292598)
		(width 0.088646)
		(layer "In2.Cu")
		(net "M_F_CPU1_SA_CS_N<2>")
	)
	(arc
		(start 136.841738 -259.292598)
		(mid 136.65454 -259.242455)
		(end 136.467342 -259.292598)
		(width 0.088646)
		(layer "In2.Cu")
		(net "M_F_CPU1_SA_CS_N<2>")
	)
	(arc
		(start 136.45261 -259.301234)
		(mid 136.176135 -259.368554)
		(end 135.901938 -259.292598)
		(width 0.088646)
		(layer "In2.Cu")
		(net "M_F_CPU1_SA_CS_N<2>")
	)
	(arc
		(start 137.781538 -259.292598)
		(mid 137.59434 -259.242455)
		(end 137.407142 -259.292598)
		(width 0.088646)
		(layer "In2.Cu")
		(net "M_F_CPU1_SA_CS_N<2>")
	)
	(arc
		(start 139.47394 -259.24256)
		(mid 139.377043 -259.255248)
		(end 139.286742 -259.292598)
		(width 0.088646)
		(layer "In2.Cu")
		(net "M_F_CPU1_SA_CS_N<2>")
	)
	(arc
		(start 135.901938 -259.292598)
		(mid 135.721591 -259.242395)
		(end 135.53948 -259.28574)
		(width 0.088646)
		(layer "In2.Cu")
		(net "M_F_CPU1_SA_CS_N<2>")
	)
	(segment
		(start 184.439814 -267.016738)
		(end 185.544714 -267.016738)
		(width 0.20066)
		(layer "F.Cu")
		(net "M_F_CPU1_SA_CS_N<1>")
	)
	(segment
		(start 135.245094 -258.2672)
		(end 135.245094 -258.80314)
		(width 0.20066)
		(layer "F.Cu")
		(net "M_F_CPU1_SA_CS_N<1>")
	)
	(segment
		(start 148.070316 -259.803138)
		(end 147.108926 -258.841748)
		(width 0.18288)
		(layer "In2.Cu")
		(net "M_F_CPU1_SA_CS_N<1>")
	)
	(segment
		(start 184.439814 -267.016738)
		(end 183.91886 -266.495784)
		(width 0.18288)
		(layer "In2.Cu")
		(net "M_F_CPU1_SA_CS_N<1>")
	)
	(segment
		(start 161.441384 -264.034016)
		(end 160.587182 -263.179814)
		(width 0.18288)
		(layer "In2.Cu")
		(net "M_F_CPU1_SA_CS_N<1>")
	)
	(segment
		(start 157.790642 -263.003284)
		(end 157.10535 -263.003284)
		(width 0.18288)
		(layer "In2.Cu")
		(net "M_F_CPU1_SA_CS_N<1>")
	)
	(segment
		(start 140.90015 -258.47548)
		(end 139.782804 -258.47548)
		(width 0.088646)
		(layer "In2.Cu")
		(net "M_F_CPU1_SA_CS_N<1>")
	)
	(segment
		(start 179.88788 -267.109702)
		(end 179.72786 -267.269722)
		(width 0.18288)
		(layer "In2.Cu")
		(net "M_F_CPU1_SA_CS_N<1>")
	)
	(segment
		(start 164.47262 -264.078212)
		(end 164.2745 -263.880092)
		(width 0.18288)
		(layer "In2.Cu")
		(net "M_F_CPU1_SA_CS_N<1>")
	)
	(segment
		(start 172.199554 -266.32916)
		(end 172.199554 -266.15644)
		(width 0.18288)
		(layer "In2.Cu")
		(net "M_F_CPU1_SA_CS_N<1>")
	)
	(segment
		(start 137.877296 -258.478782)
		(end 137.862564 -258.487418)
		(width 0.088646)
		(layer "In2.Cu")
		(net "M_F_CPU1_SA_CS_N<1>")
	)
	(segment
		(start 179.88788 -266.673584)
		(end 179.88788 -267.109702)
		(width 0.18288)
		(layer "In2.Cu")
		(net "M_F_CPU1_SA_CS_N<1>")
	)
	(segment
		(start 162.37458 -264.351262)
		(end 162.057334 -264.034016)
		(width 0.18288)
		(layer "In2.Cu")
		(net "M_F_CPU1_SA_CS_N<1>")
	)
	(segment
		(start 169.435272 -265.522202)
		(end 169.032936 -265.522202)
		(width 0.18288)
		(layer "In2.Cu")
		(net "M_F_CPU1_SA_CS_N<1>")
	)
	(segment
		(start 179.13858 -267.053822)
		(end 179.13858 -266.78382)
		(width 0.18288)
		(layer "In2.Cu")
		(net "M_F_CPU1_SA_CS_N<1>")
	)
	(segment
		(start 172.199554 -266.15644)
		(end 171.759626 -265.716512)
		(width 0.18288)
		(layer "In2.Cu")
		(net "M_F_CPU1_SA_CS_N<1>")
	)
	(segment
		(start 180.812948 -266.764262)
		(end 180.52923 -266.480544)
		(width 0.18288)
		(layer "In2.Cu")
		(net "M_F_CPU1_SA_CS_N<1>")
	)
	(segment
		(start 182.09514 -267.179298)
		(end 181.9021 -267.372338)
		(width 0.18288)
		(layer "In2.Cu")
		(net "M_F_CPU1_SA_CS_N<1>")
	)
	(segment
		(start 156.167074 -262.065008)
		(end 155.681426 -262.065008)
		(width 0.18288)
		(layer "In2.Cu")
		(net "M_F_CPU1_SA_CS_N<1>")
	)
	(segment
		(start 159.653986 -263.179814)
		(end 159.380936 -263.452864)
		(width 0.18288)
		(layer "In2.Cu")
		(net "M_F_CPU1_SA_CS_N<1>")
	)
	(segment
		(start 180.08092 -266.480544)
		(end 179.88788 -266.673584)
		(width 0.18288)
		(layer "In2.Cu")
		(net "M_F_CPU1_SA_CS_N<1>")
	)
	(segment
		(start 157.10535 -263.003284)
		(end 156.167074 -262.065008)
		(width 0.18288)
		(layer "In2.Cu")
		(net "M_F_CPU1_SA_CS_N<1>")
	)
	(segment
		(start 174.873158 -266.48791)
		(end 174.772828 -266.58824)
		(width 0.18288)
		(layer "In2.Cu")
		(net "M_F_CPU1_SA_CS_N<1>")
	)
	(segment
		(start 172.458634 -266.58824)
		(end 172.199554 -266.32916)
		(width 0.18288)
		(layer "In2.Cu")
		(net "M_F_CPU1_SA_CS_N<1>")
	)
	(segment
		(start 159.380936 -263.452864)
		(end 158.240222 -263.452864)
		(width 0.18288)
		(layer "In2.Cu")
		(net "M_F_CPU1_SA_CS_N<1>")
	)
	(segment
		(start 171.759626 -265.716512)
		(end 169.629582 -265.716512)
		(width 0.18288)
		(layer "In2.Cu")
		(net "M_F_CPU1_SA_CS_N<1>")
	)
	(segment
		(start 179.13858 -266.78382)
		(end 178.94554 -266.59078)
		(width 0.18288)
		(layer "In2.Cu")
		(net "M_F_CPU1_SA_CS_N<1>")
	)
	(segment
		(start 163.90366 -263.880092)
		(end 163.43249 -264.351262)
		(width 0.18288)
		(layer "In2.Cu")
		(net "M_F_CPU1_SA_CS_N<1>")
	)
	(segment
		(start 155.681426 -262.065008)
		(end 153.419556 -259.803138)
		(width 0.18288)
		(layer "In2.Cu")
		(net "M_F_CPU1_SA_CS_N<1>")
	)
	(segment
		(start 138.817096 -258.478782)
		(end 138.802364 -258.487418)
		(width 0.088646)
		(layer "In2.Cu")
		(net "M_F_CPU1_SA_CS_N<1>")
	)
	(segment
		(start 175.693578 -266.59078)
		(end 175.590708 -266.48791)
		(width 0.18288)
		(layer "In2.Cu")
		(net "M_F_CPU1_SA_CS_N<1>")
	)
	(segment
		(start 163.43249 -264.351262)
		(end 162.37458 -264.351262)
		(width 0.18288)
		(layer "In2.Cu")
		(net "M_F_CPU1_SA_CS_N<1>")
	)
	(segment
		(start 174.772828 -266.58824)
		(end 172.458634 -266.58824)
		(width 0.18288)
		(layer "In2.Cu")
		(net "M_F_CPU1_SA_CS_N<1>")
	)
	(segment
		(start 147.108926 -258.841748)
		(end 146.224498 -258.47548)
		(width 0.18288)
		(layer "In2.Cu")
		(net "M_F_CPU1_SA_CS_N<1>")
	)
	(segment
		(start 182.09514 -266.806426)
		(end 182.09514 -267.179298)
		(width 0.18288)
		(layer "In2.Cu")
		(net "M_F_CPU1_SA_CS_N<1>")
	)
	(segment
		(start 160.587182 -263.179814)
		(end 159.653986 -263.179814)
		(width 0.18288)
		(layer "In2.Cu")
		(net "M_F_CPU1_SA_CS_N<1>")
	)
	(segment
		(start 180.52923 -266.480544)
		(end 180.08092 -266.480544)
		(width 0.18288)
		(layer "In2.Cu")
		(net "M_F_CPU1_SA_CS_N<1>")
	)
	(segment
		(start 180.812948 -267.179298)
		(end 180.812948 -266.764262)
		(width 0.18288)
		(layer "In2.Cu")
		(net "M_F_CPU1_SA_CS_N<1>")
	)
	(segment
		(start 179.35448 -267.269722)
		(end 179.13858 -267.053822)
		(width 0.18288)
		(layer "In2.Cu")
		(net "M_F_CPU1_SA_CS_N<1>")
	)
	(segment
		(start 136.937496 -258.478782)
		(end 136.922764 -258.487418)
		(width 0.088646)
		(layer "In2.Cu")
		(net "M_F_CPU1_SA_CS_N<1>")
	)
	(segment
		(start 181.005988 -267.372338)
		(end 180.812948 -267.179298)
		(width 0.18288)
		(layer "In2.Cu")
		(net "M_F_CPU1_SA_CS_N<1>")
	)
	(segment
		(start 162.057334 -264.034016)
		(end 161.441384 -264.034016)
		(width 0.18288)
		(layer "In2.Cu")
		(net "M_F_CPU1_SA_CS_N<1>")
	)
	(segment
		(start 183.91886 -266.495784)
		(end 182.405782 -266.495784)
		(width 0.18288)
		(layer "In2.Cu")
		(net "M_F_CPU1_SA_CS_N<1>")
	)
	(segment
		(start 175.590708 -266.48791)
		(end 174.873158 -266.48791)
		(width 0.18288)
		(layer "In2.Cu")
		(net "M_F_CPU1_SA_CS_N<1>")
	)
	(segment
		(start 182.405782 -266.495784)
		(end 182.09514 -266.806426)
		(width 0.18288)
		(layer "In2.Cu")
		(net "M_F_CPU1_SA_CS_N<1>")
	)
	(segment
		(start 179.72786 -267.269722)
		(end 179.35448 -267.269722)
		(width 0.18288)
		(layer "In2.Cu")
		(net "M_F_CPU1_SA_CS_N<1>")
	)
	(segment
		(start 169.032936 -265.522202)
		(end 167.588946 -264.078212)
		(width 0.18288)
		(layer "In2.Cu")
		(net "M_F_CPU1_SA_CS_N<1>")
	)
	(segment
		(start 135.997696 -258.478782)
		(end 135.601202 -258.70789)
		(width 0.088646)
		(layer "In2.Cu")
		(net "M_F_CPU1_SA_CS_N<1>")
	)
	(segment
		(start 169.629582 -265.716512)
		(end 169.435272 -265.522202)
		(width 0.18288)
		(layer "In2.Cu")
		(net "M_F_CPU1_SA_CS_N<1>")
	)
	(segment
		(start 167.588946 -264.078212)
		(end 164.47262 -264.078212)
		(width 0.18288)
		(layer "In2.Cu")
		(net "M_F_CPU1_SA_CS_N<1>")
	)
	(segment
		(start 146.224498 -258.47548)
		(end 140.90015 -258.47548)
		(width 0.18288)
		(layer "In2.Cu")
		(net "M_F_CPU1_SA_CS_N<1>")
	)
	(segment
		(start 164.2745 -263.880092)
		(end 163.90366 -263.880092)
		(width 0.18288)
		(layer "In2.Cu")
		(net "M_F_CPU1_SA_CS_N<1>")
	)
	(segment
		(start 178.94554 -266.59078)
		(end 175.693578 -266.59078)
		(width 0.18288)
		(layer "In2.Cu")
		(net "M_F_CPU1_SA_CS_N<1>")
	)
	(segment
		(start 181.9021 -267.372338)
		(end 181.005988 -267.372338)
		(width 0.18288)
		(layer "In2.Cu")
		(net "M_F_CPU1_SA_CS_N<1>")
	)
	(segment
		(start 153.419556 -259.803138)
		(end 148.070316 -259.803138)
		(width 0.18288)
		(layer "In2.Cu")
		(net "M_F_CPU1_SA_CS_N<1>")
	)
	(segment
		(start 158.240222 -263.452864)
		(end 157.790642 -263.003284)
		(width 0.18288)
		(layer "In2.Cu")
		(net "M_F_CPU1_SA_CS_N<1>")
	)
	(arc
		(start 138.802364 -258.487418)
		(mid 138.525923 -258.554584)
		(end 138.251692 -258.478782)
		(width 0.088646)
		(layer "In2.Cu")
		(net "M_F_CPU1_SA_CS_N<1>")
	)
	(arc
		(start 137.311892 -258.478782)
		(mid 137.124694 -258.428639)
		(end 136.937496 -258.478782)
		(width 0.088646)
		(layer "In2.Cu")
		(net "M_F_CPU1_SA_CS_N<1>")
	)
	(arc
		(start 136.922764 -258.487418)
		(mid 136.646323 -258.554584)
		(end 136.372092 -258.478782)
		(width 0.088646)
		(layer "In2.Cu")
		(net "M_F_CPU1_SA_CS_N<1>")
	)
	(arc
		(start 137.862564 -258.487418)
		(mid 137.586123 -258.554584)
		(end 137.311892 -258.478782)
		(width 0.088646)
		(layer "In2.Cu")
		(net "M_F_CPU1_SA_CS_N<1>")
	)
	(arc
		(start 139.191492 -258.478782)
		(mid 139.004294 -258.428639)
		(end 138.817096 -258.478782)
		(width 0.088646)
		(layer "In2.Cu")
		(net "M_F_CPU1_SA_CS_N<1>")
	)
	(arc
		(start 138.251692 -258.478782)
		(mid 138.064494 -258.428639)
		(end 137.877296 -258.478782)
		(width 0.088646)
		(layer "In2.Cu")
		(net "M_F_CPU1_SA_CS_N<1>")
	)
	(arc
		(start 139.742164 -258.487418)
		(mid 139.465723 -258.554584)
		(end 139.191492 -258.478782)
		(width 0.088646)
		(layer "In2.Cu")
		(net "M_F_CPU1_SA_CS_N<1>")
	)
	(arc
		(start 139.782804 -258.47548)
		(mid 139.761625 -258.478525)
		(end 139.742164 -258.487418)
		(width 0.088646)
		(layer "In2.Cu")
		(net "M_F_CPU1_SA_CS_N<1>")
	)
	(arc
		(start 136.372092 -258.478782)
		(mid 136.184894 -258.428639)
		(end 135.997696 -258.478782)
		(width 0.088646)
		(layer "In2.Cu")
		(net "M_F_CPU1_SA_CS_N<1>")
	)
	(arc
		(start 135.601202 -258.70789)
		(mid 135.429423 -258.778988)
		(end 135.245094 -258.80314)
		(width 0.088646)
		(layer "In2.Cu")
		(net "M_F_CPU1_SA_CS_N<1>")
	)
	(segment
		(start 134.775448 -259.093462)
		(end 134.775194 -259.616956)
		(width 0.20066)
		(layer "F.Cu")
		(net "M_F_CPU1_SA_CS_N<0>")
	)
	(segment
		(start 134.775448 -259.081016)
		(end 134.775448 -259.093462)
		(width 0.20066)
		(layer "F.Cu")
		(net "M_F_CPU1_SA_CS_N<0>")
	)
	(segment
		(start 180.339746 -267.866622)
		(end 181.444646 -267.866622)
		(width 0.20066)
		(layer "F.Cu")
		(net "M_F_CPU1_SA_CS_N<0>")
	)
	(segment
		(start 177.013108 -268.385036)
		(end 177.013108 -268.87805)
		(width 0.18288)
		(layer "In2.Cu")
		(net "M_F_CPU1_SA_CS_N<0>")
	)
	(segment
		(start 176.820068 -269.07109)
		(end 176.452022 -269.07109)
		(width 0.18288)
		(layer "In2.Cu")
		(net "M_F_CPU1_SA_CS_N<0>")
	)
	(segment
		(start 179.14747 -269.07109)
		(end 178.95443 -268.87805)
		(width 0.18288)
		(layer "In2.Cu")
		(net "M_F_CPU1_SA_CS_N<0>")
	)
	(segment
		(start 173.509178 -269.152878)
		(end 173.333918 -268.977618)
		(width 0.18288)
		(layer "In2.Cu")
		(net "M_F_CPU1_SA_CS_N<0>")
	)
	(segment
		(start 179.512468 -269.07109)
		(end 179.14747 -269.07109)
		(width 0.18288)
		(layer "In2.Cu")
		(net "M_F_CPU1_SA_CS_N<0>")
	)
	(segment
		(start 177.285904 -268.11224)
		(end 177.013108 -268.385036)
		(width 0.18288)
		(layer "In2.Cu")
		(net "M_F_CPU1_SA_CS_N<0>")
	)
	(segment
		(start 176.25949 -268.0843)
		(end 176.050956 -267.875766)
		(width 0.18288)
		(layer "In2.Cu")
		(net "M_F_CPU1_SA_CS_N<0>")
	)
	(segment
		(start 164.215572 -266.615672)
		(end 161.063432 -266.615672)
		(width 0.18288)
		(layer "In2.Cu")
		(net "M_F_CPU1_SA_CS_N<0>")
	)
	(segment
		(start 172.322236 -268.545564)
		(end 171.68241 -268.545564)
		(width 0.18288)
		(layer "In2.Cu")
		(net "M_F_CPU1_SA_CS_N<0>")
	)
	(segment
		(start 180.339746 -267.866622)
		(end 179.92471 -267.866622)
		(width 0.18288)
		(layer "In2.Cu")
		(net "M_F_CPU1_SA_CS_N<0>")
	)
	(segment
		(start 176.452022 -269.07109)
		(end 176.25949 -268.878558)
		(width 0.18288)
		(layer "In2.Cu")
		(net "M_F_CPU1_SA_CS_N<0>")
	)
	(segment
		(start 135.49884 -259.92455)
		(end 134.775194 -259.616956)
		(width 0.088646)
		(layer "In2.Cu")
		(net "M_F_CPU1_SA_CS_N<0>")
	)
	(segment
		(start 169.037254 -268.304772)
		(end 168.801796 -268.069314)
		(width 0.18288)
		(layer "In2.Cu")
		(net "M_F_CPU1_SA_CS_N<0>")
	)
	(segment
		(start 175.677576 -267.875766)
		(end 175.517556 -268.035786)
		(width 0.18288)
		(layer "In2.Cu")
		(net "M_F_CPU1_SA_CS_N<0>")
	)
	(segment
		(start 171.441618 -268.304772)
		(end 169.037254 -268.304772)
		(width 0.18288)
		(layer "In2.Cu")
		(net "M_F_CPU1_SA_CS_N<0>")
	)
	(segment
		(start 173.163738 -268.294612)
		(end 172.573188 -268.294612)
		(width 0.18288)
		(layer "In2.Cu")
		(net "M_F_CPU1_SA_CS_N<0>")
	)
	(segment
		(start 167.32631 -267.512038)
		(end 166.939976 -267.125704)
		(width 0.18288)
		(layer "In2.Cu")
		(net "M_F_CPU1_SA_CS_N<0>")
	)
	(segment
		(start 178.688238 -268.11224)
		(end 177.285904 -268.11224)
		(width 0.18288)
		(layer "In2.Cu")
		(net "M_F_CPU1_SA_CS_N<0>")
	)
	(segment
		(start 147.92198 -261.373366)
		(end 146.503898 -259.955284)
		(width 0.18288)
		(layer "In2.Cu")
		(net "M_F_CPU1_SA_CS_N<0>")
	)
	(segment
		(start 166.939976 -267.125704)
		(end 165.776656 -267.125704)
		(width 0.18288)
		(layer "In2.Cu")
		(net "M_F_CPU1_SA_CS_N<0>")
	)
	(segment
		(start 165.424104 -267.478256)
		(end 165.078156 -267.478256)
		(width 0.18288)
		(layer "In2.Cu")
		(net "M_F_CPU1_SA_CS_N<0>")
	)
	(segment
		(start 171.68241 -268.545564)
		(end 171.441618 -268.304772)
		(width 0.18288)
		(layer "In2.Cu")
		(net "M_F_CPU1_SA_CS_N<0>")
	)
	(segment
		(start 176.050956 -267.875766)
		(end 175.677576 -267.875766)
		(width 0.18288)
		(layer "In2.Cu")
		(net "M_F_CPU1_SA_CS_N<0>")
	)
	(segment
		(start 179.777898 -268.013434)
		(end 179.777898 -268.80566)
		(width 0.18288)
		(layer "In2.Cu")
		(net "M_F_CPU1_SA_CS_N<0>")
	)
	(segment
		(start 135.527796 -259.941314)
		(end 135.527542 -259.941314)
		(width 0.088646)
		(layer "In2.Cu")
		(net "M_F_CPU1_SA_CS_N<0>")
	)
	(segment
		(start 161.063432 -266.615672)
		(end 160.197292 -265.749532)
		(width 0.18288)
		(layer "In2.Cu")
		(net "M_F_CPU1_SA_CS_N<0>")
	)
	(segment
		(start 175.179736 -269.152878)
		(end 173.509178 -269.152878)
		(width 0.18288)
		(layer "In2.Cu")
		(net "M_F_CPU1_SA_CS_N<0>")
	)
	(segment
		(start 173.333918 -268.464792)
		(end 173.163738 -268.294612)
		(width 0.18288)
		(layer "In2.Cu")
		(net "M_F_CPU1_SA_CS_N<0>")
	)
	(segment
		(start 165.776656 -267.125704)
		(end 165.424104 -267.478256)
		(width 0.18288)
		(layer "In2.Cu")
		(net "M_F_CPU1_SA_CS_N<0>")
	)
	(segment
		(start 176.25949 -268.878558)
		(end 176.25949 -268.0843)
		(width 0.18288)
		(layer "In2.Cu")
		(net "M_F_CPU1_SA_CS_N<0>")
	)
	(segment
		(start 146.503898 -259.955284)
		(end 145.540222 -259.555996)
		(width 0.18288)
		(layer "In2.Cu")
		(net "M_F_CPU1_SA_CS_N<0>")
	)
	(segment
		(start 175.517556 -268.815058)
		(end 175.179736 -269.152878)
		(width 0.18288)
		(layer "In2.Cu")
		(net "M_F_CPU1_SA_CS_N<0>")
	)
	(segment
		(start 179.777898 -268.80566)
		(end 179.512468 -269.07109)
		(width 0.18288)
		(layer "In2.Cu")
		(net "M_F_CPU1_SA_CS_N<0>")
	)
	(segment
		(start 165.078156 -267.478256)
		(end 164.215572 -266.615672)
		(width 0.18288)
		(layer "In2.Cu")
		(net "M_F_CPU1_SA_CS_N<0>")
	)
	(segment
		(start 136.467342 -259.941314)
		(end 136.45261 -259.932678)
		(width 0.088646)
		(layer "In2.Cu")
		(net "M_F_CPU1_SA_CS_N<0>")
	)
	(segment
		(start 138.346942 -259.941314)
		(end 138.33221 -259.932678)
		(width 0.088646)
		(layer "In2.Cu")
		(net "M_F_CPU1_SA_CS_N<0>")
	)
	(segment
		(start 157.03169 -265.749532)
		(end 152.655524 -261.373366)
		(width 0.18288)
		(layer "In2.Cu")
		(net "M_F_CPU1_SA_CS_N<0>")
	)
	(segment
		(start 145.540222 -259.555996)
		(end 140.90015 -259.555996)
		(width 0.18288)
		(layer "In2.Cu")
		(net "M_F_CPU1_SA_CS_N<0>")
	)
	(segment
		(start 140.90015 -259.555996)
		(end 140.010388 -259.555996)
		(width 0.088646)
		(layer "In2.Cu")
		(net "M_F_CPU1_SA_CS_N<0>")
	)
	(segment
		(start 137.407142 -259.941314)
		(end 137.39241 -259.932678)
		(width 0.088646)
		(layer "In2.Cu")
		(net "M_F_CPU1_SA_CS_N<0>")
	)
	(segment
		(start 135.527542 -259.941314)
		(end 135.49884 -259.92455)
		(width 0.088646)
		(layer "In2.Cu")
		(net "M_F_CPU1_SA_CS_N<0>")
	)
	(segment
		(start 177.013108 -268.87805)
		(end 176.820068 -269.07109)
		(width 0.18288)
		(layer "In2.Cu")
		(net "M_F_CPU1_SA_CS_N<0>")
	)
	(segment
		(start 168.801796 -268.069314)
		(end 168.801796 -267.827506)
		(width 0.18288)
		(layer "In2.Cu")
		(net "M_F_CPU1_SA_CS_N<0>")
	)
	(segment
		(start 175.517556 -268.035786)
		(end 175.517556 -268.815058)
		(width 0.18288)
		(layer "In2.Cu")
		(net "M_F_CPU1_SA_CS_N<0>")
	)
	(segment
		(start 178.95443 -268.378432)
		(end 178.688238 -268.11224)
		(width 0.18288)
		(layer "In2.Cu")
		(net "M_F_CPU1_SA_CS_N<0>")
	)
	(segment
		(start 173.333918 -268.977618)
		(end 173.333918 -268.464792)
		(width 0.18288)
		(layer "In2.Cu")
		(net "M_F_CPU1_SA_CS_N<0>")
	)
	(segment
		(start 172.573188 -268.294612)
		(end 172.322236 -268.545564)
		(width 0.18288)
		(layer "In2.Cu")
		(net "M_F_CPU1_SA_CS_N<0>")
	)
	(segment
		(start 140.010388 -259.555996)
		(end 139.626848 -259.933948)
		(width 0.088646)
		(layer "In2.Cu")
		(net "M_F_CPU1_SA_CS_N<0>")
	)
	(segment
		(start 160.197292 -265.749532)
		(end 157.03169 -265.749532)
		(width 0.18288)
		(layer "In2.Cu")
		(net "M_F_CPU1_SA_CS_N<0>")
	)
	(segment
		(start 178.95443 -268.87805)
		(end 178.95443 -268.378432)
		(width 0.18288)
		(layer "In2.Cu")
		(net "M_F_CPU1_SA_CS_N<0>")
	)
	(segment
		(start 152.655524 -261.373366)
		(end 147.92198 -261.373366)
		(width 0.18288)
		(layer "In2.Cu")
		(net "M_F_CPU1_SA_CS_N<0>")
	)
	(segment
		(start 168.486328 -267.512038)
		(end 167.32631 -267.512038)
		(width 0.18288)
		(layer "In2.Cu")
		(net "M_F_CPU1_SA_CS_N<0>")
	)
	(segment
		(start 168.801796 -267.827506)
		(end 168.486328 -267.512038)
		(width 0.18288)
		(layer "In2.Cu")
		(net "M_F_CPU1_SA_CS_N<0>")
	)
	(segment
		(start 179.92471 -267.866622)
		(end 179.777898 -268.013434)
		(width 0.18288)
		(layer "In2.Cu")
		(net "M_F_CPU1_SA_CS_N<0>")
	)
	(arc
		(start 137.39241 -259.932678)
		(mid 137.115935 -259.865358)
		(end 136.841738 -259.941314)
		(width 0.088646)
		(layer "In2.Cu")
		(net "M_F_CPU1_SA_CS_N<0>")
	)
	(arc
		(start 135.901938 -259.941314)
		(mid 135.714884 -259.991364)
		(end 135.527796 -259.941314)
		(width 0.088646)
		(layer "In2.Cu")
		(net "M_F_CPU1_SA_CS_N<0>")
	)
	(arc
		(start 139.27201 -259.932678)
		(mid 138.995535 -259.865358)
		(end 138.721338 -259.941314)
		(width 0.088646)
		(layer "In2.Cu")
		(net "M_F_CPU1_SA_CS_N<0>")
	)
	(arc
		(start 139.626848 -259.933948)
		(mid 139.449265 -259.981112)
		(end 139.27201 -259.932678)
		(width 0.088646)
		(layer "In2.Cu")
		(net "M_F_CPU1_SA_CS_N<0>")
	)
	(arc
		(start 137.781538 -259.941314)
		(mid 137.59434 -259.991457)
		(end 137.407142 -259.941314)
		(width 0.088646)
		(layer "In2.Cu")
		(net "M_F_CPU1_SA_CS_N<0>")
	)
	(arc
		(start 136.841738 -259.941314)
		(mid 136.65454 -259.991457)
		(end 136.467342 -259.941314)
		(width 0.088646)
		(layer "In2.Cu")
		(net "M_F_CPU1_SA_CS_N<0>")
	)
	(arc
		(start 138.33221 -259.932678)
		(mid 138.055735 -259.865358)
		(end 137.781538 -259.941314)
		(width 0.088646)
		(layer "In2.Cu")
		(net "M_F_CPU1_SA_CS_N<0>")
	)
	(arc
		(start 138.721338 -259.941314)
		(mid 138.53414 -259.991457)
		(end 138.346942 -259.941314)
		(width 0.088646)
		(layer "In2.Cu")
		(net "M_F_CPU1_SA_CS_N<0>")
	)
	(arc
		(start 136.45261 -259.932678)
		(mid 136.176135 -259.865358)
		(end 135.901938 -259.941314)
		(width 0.088646)
		(layer "In2.Cu")
		(net "M_F_CPU1_SA_CS_N<0>")
	)
	(segment
		(start 134.775448 -261.244334)
		(end 134.775194 -261.244588)
		(width 0.20066)
		(layer "F.Cu")
		(net "M_F_CPU1_SA_CB<7>")
	)
	(segment
		(start 134.775448 -260.708902)
		(end 134.775448 -261.244334)
		(width 0.20066)
		(layer "F.Cu")
		(net "M_F_CPU1_SA_CB<7>")
	)
	(segment
		(start 176.896014 -270.416782)
		(end 178.000914 -270.416782)
		(width 0.20066)
		(layer "F.Cu")
		(net "M_F_CPU1_SA_CB<7>")
	)
	(segment
		(start 180.427884 -270.848836)
		(end 180.434996 -270.841724)
		(width 0.1016)
		(layer "F.Cu")
		(net "M_F_CPU1_SA_CB<7>")
	)
	(segment
		(start 180.131212 -270.848836)
		(end 180.423058 -270.848836)
		(width 0.20066)
		(layer "F.Cu")
		(net "M_F_CPU1_SA_CB<7>")
	)
	(segment
		(start 182.455058 -270.853916)
		(end 183.136286 -270.853916)
		(width 0.20066)
		(layer "F.Cu")
		(net "M_F_CPU1_SA_CB<7>")
	)
	(segment
		(start 179.699158 -270.416782)
		(end 180.131212 -270.848836)
		(width 0.20066)
		(layer "F.Cu")
		(net "M_F_CPU1_SA_CB<7>")
	)
	(segment
		(start 183.958484 -270.164814)
		(end 184.210452 -270.416782)
		(width 0.20066)
		(layer "F.Cu")
		(net "M_F_CPU1_SA_CB<7>")
	)
	(segment
		(start 182.442866 -270.841724)
		(end 182.455058 -270.853916)
		(width 0.1016)
		(layer "F.Cu")
		(net "M_F_CPU1_SA_CB<7>")
	)
	(segment
		(start 183.574436 -270.164814)
		(end 183.958484 -270.164814)
		(width 0.20066)
		(layer "F.Cu")
		(net "M_F_CPU1_SA_CB<7>")
	)
	(segment
		(start 184.210452 -270.416782)
		(end 185.544714 -270.416782)
		(width 0.20066)
		(layer "F.Cu")
		(net "M_F_CPU1_SA_CB<7>")
	)
	(segment
		(start 183.136286 -270.853916)
		(end 183.340248 -270.649954)
		(width 0.20066)
		(layer "F.Cu")
		(net "M_F_CPU1_SA_CB<7>")
	)
	(segment
		(start 178.000914 -270.416782)
		(end 179.699158 -270.416782)
		(width 0.20066)
		(layer "F.Cu")
		(net "M_F_CPU1_SA_CB<7>")
	)
	(segment
		(start 183.340248 -270.399002)
		(end 183.574436 -270.164814)
		(width 0.20066)
		(layer "F.Cu")
		(net "M_F_CPU1_SA_CB<7>")
	)
	(segment
		(start 183.340248 -270.649954)
		(end 183.340248 -270.399002)
		(width 0.20066)
		(layer "F.Cu")
		(net "M_F_CPU1_SA_CB<7>")
	)
	(segment
		(start 134.775194 -261.244588)
		(end 134.775194 -261.244842)
		(width 0.20066)
		(layer "F.Cu")
		(net "M_F_CPU1_SA_CB<7>")
	)
	(segment
		(start 180.434996 -270.841724)
		(end 182.442866 -270.841724)
		(width 0.1016)
		(layer "F.Cu")
		(net "M_F_CPU1_SA_CB<7>")
	)
	(segment
		(start 180.423058 -270.848836)
		(end 180.427884 -270.848836)
		(width 0.101854)
		(layer "F.Cu")
		(net "M_F_CPU1_SA_CB<7>")
	)
	(segment
		(start 175.459898 -270.85417)
		(end 175.266858 -271.04721)
		(width 0.18288)
		(layer "In2.Cu")
		(net "M_F_CPU1_SA_CB<7>")
	)
	(segment
		(start 164.15893 -269.0241)
		(end 163.871656 -269.0241)
		(width 0.18288)
		(layer "In2.Cu")
		(net "M_F_CPU1_SA_CB<7>")
	)
	(segment
		(start 162.093402 -269.136114)
		(end 161.456116 -268.498828)
		(width 0.18288)
		(layer "In2.Cu")
		(net "M_F_CPU1_SA_CB<7>")
	)
	(segment
		(start 134.462266 -261.244842)
		(end 134.775194 -261.244842)
		(width 0.088646)
		(layer "In2.Cu")
		(net "M_F_CPU1_SA_CB<7>")
	)
	(segment
		(start 176.317148 -270.43126)
		(end 176.317148 -270.18361)
		(width 0.18288)
		(layer "In2.Cu")
		(net "M_F_CPU1_SA_CB<7>")
	)
	(segment
		(start 176.688496 -270.6243)
		(end 176.510188 -270.6243)
		(width 0.18288)
		(layer "In2.Cu")
		(net "M_F_CPU1_SA_CB<7>")
	)
	(segment
		(start 175.652938 -269.99057)
		(end 175.459898 -270.18361)
		(width 0.18288)
		(layer "In2.Cu")
		(net "M_F_CPU1_SA_CB<7>")
	)
	(segment
		(start 151.99487 -262.859774)
		(end 147.286218 -262.859774)
		(width 0.18288)
		(layer "In2.Cu")
		(net "M_F_CPU1_SA_CB<7>")
	)
	(segment
		(start 140.346938 -260.900926)
		(end 140.252196 -260.806184)
		(width 0.088646)
		(layer "In2.Cu")
		(net "M_F_CPU1_SA_CB<7>")
	)
	(segment
		(start 163.361116 -269.53464)
		(end 162.915346 -269.53464)
		(width 0.18288)
		(layer "In2.Cu")
		(net "M_F_CPU1_SA_CB<7>")
	)
	(segment
		(start 175.266858 -271.04721)
		(end 174.878238 -271.04721)
		(width 0.18288)
		(layer "In2.Cu")
		(net "M_F_CPU1_SA_CB<7>")
	)
	(segment
		(start 176.896014 -270.416782)
		(end 176.688496 -270.6243)
		(width 0.18288)
		(layer "In2.Cu")
		(net "M_F_CPU1_SA_CB<7>")
	)
	(segment
		(start 172.612558 -270.84147)
		(end 171.809918 -270.03883)
		(width 0.18288)
		(layer "In2.Cu")
		(net "M_F_CPU1_SA_CB<7>")
	)
	(segment
		(start 134.587996 -261.5692)
		(end 134.579106 -261.56412)
		(width 0.088646)
		(layer "In2.Cu")
		(net "M_F_CPU1_SA_CB<7>")
	)
	(segment
		(start 167.793162 -269.194026)
		(end 165.498526 -269.194026)
		(width 0.18288)
		(layer "In2.Cu")
		(net "M_F_CPU1_SA_CB<7>")
	)
	(segment
		(start 140.252196 -260.806184)
		(end 139.944348 -260.806184)
		(width 0.088646)
		(layer "In2.Cu")
		(net "M_F_CPU1_SA_CB<7>")
	)
	(segment
		(start 175.459898 -270.18361)
		(end 175.459898 -270.85417)
		(width 0.18288)
		(layer "In2.Cu")
		(net "M_F_CPU1_SA_CB<7>")
	)
	(segment
		(start 162.915346 -269.53464)
		(end 162.51682 -269.136114)
		(width 0.18288)
		(layer "In2.Cu")
		(net "M_F_CPU1_SA_CB<7>")
	)
	(segment
		(start 163.871656 -269.0241)
		(end 163.361116 -269.53464)
		(width 0.18288)
		(layer "In2.Cu")
		(net "M_F_CPU1_SA_CB<7>")
	)
	(segment
		(start 135.149844 -261.2263)
		(end 135.149844 -261.244842)
		(width 0.088646)
		(layer "In2.Cu")
		(net "M_F_CPU1_SA_CB<7>")
	)
	(segment
		(start 161.456116 -268.498828)
		(end 160.807146 -268.498828)
		(width 0.18288)
		(layer "In2.Cu")
		(net "M_F_CPU1_SA_CB<7>")
	)
	(segment
		(start 176.510188 -270.6243)
		(end 176.317148 -270.43126)
		(width 0.18288)
		(layer "In2.Cu")
		(net "M_F_CPU1_SA_CB<7>")
	)
	(segment
		(start 134.971282 -261.56412)
		(end 134.962392 -261.5692)
		(width 0.088646)
		(layer "In2.Cu")
		(net "M_F_CPU1_SA_CB<7>")
	)
	(segment
		(start 144.792954 -260.900926)
		(end 140.90015 -260.900926)
		(width 0.18288)
		(layer "In2.Cu")
		(net "M_F_CPU1_SA_CB<7>")
	)
	(segment
		(start 176.317148 -270.18361)
		(end 176.124108 -269.99057)
		(width 0.18288)
		(layer "In2.Cu")
		(net "M_F_CPU1_SA_CB<7>")
	)
	(segment
		(start 134.405116 -261.301992)
		(end 134.462266 -261.244842)
		(width 0.088646)
		(layer "In2.Cu")
		(net "M_F_CPU1_SA_CB<7>")
	)
	(segment
		(start 164.455856 -269.321026)
		(end 164.15893 -269.0241)
		(width 0.18288)
		(layer "In2.Cu")
		(net "M_F_CPU1_SA_CB<7>")
	)
	(segment
		(start 140.90015 -260.900926)
		(end 140.346938 -260.900926)
		(width 0.088646)
		(layer "In2.Cu")
		(net "M_F_CPU1_SA_CB<7>")
	)
	(segment
		(start 157.418024 -268.282928)
		(end 151.99487 -262.859774)
		(width 0.18288)
		(layer "In2.Cu")
		(net "M_F_CPU1_SA_CB<7>")
	)
	(segment
		(start 147.286218 -262.859774)
		(end 145.705068 -261.278624)
		(width 0.18288)
		(layer "In2.Cu")
		(net "M_F_CPU1_SA_CB<7>")
	)
	(segment
		(start 174.878238 -271.04721)
		(end 174.672498 -270.84147)
		(width 0.18288)
		(layer "In2.Cu")
		(net "M_F_CPU1_SA_CB<7>")
	)
	(segment
		(start 162.51682 -269.136114)
		(end 162.093402 -269.136114)
		(width 0.18288)
		(layer "In2.Cu")
		(net "M_F_CPU1_SA_CB<7>")
	)
	(segment
		(start 168.637966 -270.03883)
		(end 167.793162 -269.194026)
		(width 0.18288)
		(layer "In2.Cu")
		(net "M_F_CPU1_SA_CB<7>")
	)
	(segment
		(start 160.591246 -268.282928)
		(end 157.418024 -268.282928)
		(width 0.18288)
		(layer "In2.Cu")
		(net "M_F_CPU1_SA_CB<7>")
	)
	(segment
		(start 145.705068 -261.278624)
		(end 144.792954 -260.900926)
		(width 0.18288)
		(layer "In2.Cu")
		(net "M_F_CPU1_SA_CB<7>")
	)
	(segment
		(start 165.371526 -269.321026)
		(end 164.455856 -269.321026)
		(width 0.18288)
		(layer "In2.Cu")
		(net "M_F_CPU1_SA_CB<7>")
	)
	(segment
		(start 174.672498 -270.84147)
		(end 172.612558 -270.84147)
		(width 0.18288)
		(layer "In2.Cu")
		(net "M_F_CPU1_SA_CB<7>")
	)
	(segment
		(start 160.807146 -268.498828)
		(end 160.591246 -268.282928)
		(width 0.18288)
		(layer "In2.Cu")
		(net "M_F_CPU1_SA_CB<7>")
	)
	(segment
		(start 165.498526 -269.194026)
		(end 165.371526 -269.321026)
		(width 0.18288)
		(layer "In2.Cu")
		(net "M_F_CPU1_SA_CB<7>")
	)
	(segment
		(start 176.124108 -269.99057)
		(end 175.652938 -269.99057)
		(width 0.18288)
		(layer "In2.Cu")
		(net "M_F_CPU1_SA_CB<7>")
	)
	(segment
		(start 171.809918 -270.03883)
		(end 168.637966 -270.03883)
		(width 0.18288)
		(layer "In2.Cu")
		(net "M_F_CPU1_SA_CB<7>")
	)
	(arc
		(start 139.191492 -260.75513)
		(mid 139.004294 -260.805273)
		(end 138.817096 -260.75513)
		(width 0.088646)
		(layer "In2.Cu")
		(net "M_F_CPU1_SA_CB<7>")
	)
	(arc
		(start 136.937496 -260.75513)
		(mid 136.654794 -260.679388)
		(end 136.372092 -260.75513)
		(width 0.088646)
		(layer "In2.Cu")
		(net "M_F_CPU1_SA_CB<7>")
	)
	(arc
		(start 134.579106 -261.56412)
		(mid 134.463297 -261.452191)
		(end 134.405116 -261.301992)
		(width 0.088646)
		(layer "In2.Cu")
		(net "M_F_CPU1_SA_CB<7>")
	)
	(arc
		(start 135.432292 -260.75513)
		(mid 135.230006 -260.954111)
		(end 135.149844 -261.2263)
		(width 0.088646)
		(layer "In2.Cu")
		(net "M_F_CPU1_SA_CB<7>")
	)
	(arc
		(start 139.944348 -260.806184)
		(mid 139.847267 -260.792988)
		(end 139.756896 -260.75513)
		(width 0.088646)
		(layer "In2.Cu")
		(net "M_F_CPU1_SA_CB<7>")
	)
	(arc
		(start 138.251692 -260.75513)
		(mid 138.064494 -260.805273)
		(end 137.877296 -260.75513)
		(width 0.088646)
		(layer "In2.Cu")
		(net "M_F_CPU1_SA_CB<7>")
	)
	(arc
		(start 135.149844 -261.244842)
		(mid 135.102165 -261.427742)
		(end 134.971282 -261.56412)
		(width 0.088646)
		(layer "In2.Cu")
		(net "M_F_CPU1_SA_CB<7>")
	)
	(arc
		(start 138.817096 -260.75513)
		(mid 138.534394 -260.679388)
		(end 138.251692 -260.75513)
		(width 0.088646)
		(layer "In2.Cu")
		(net "M_F_CPU1_SA_CB<7>")
	)
	(arc
		(start 137.877296 -260.75513)
		(mid 137.594594 -260.679388)
		(end 137.311892 -260.75513)
		(width 0.088646)
		(layer "In2.Cu")
		(net "M_F_CPU1_SA_CB<7>")
	)
	(arc
		(start 135.997696 -260.75513)
		(mid 135.714994 -260.679388)
		(end 135.432292 -260.75513)
		(width 0.088646)
		(layer "In2.Cu")
		(net "M_F_CPU1_SA_CB<7>")
	)
	(arc
		(start 137.311892 -260.75513)
		(mid 137.124694 -260.805273)
		(end 136.937496 -260.75513)
		(width 0.088646)
		(layer "In2.Cu")
		(net "M_F_CPU1_SA_CB<7>")
	)
	(arc
		(start 134.962392 -261.5692)
		(mid 134.775194 -261.619343)
		(end 134.587996 -261.5692)
		(width 0.088646)
		(layer "In2.Cu")
		(net "M_F_CPU1_SA_CB<7>")
	)
	(arc
		(start 139.756896 -260.75513)
		(mid 139.474194 -260.679388)
		(end 139.191492 -260.75513)
		(width 0.088646)
		(layer "In2.Cu")
		(net "M_F_CPU1_SA_CB<7>")
	)
	(arc
		(start 136.372092 -260.75513)
		(mid 136.184894 -260.805273)
		(end 135.997696 -260.75513)
		(width 0.088646)
		(layer "In2.Cu")
		(net "M_F_CPU1_SA_CB<7>")
	)
	(segment
		(start 184.210452 -272.116804)
		(end 185.544714 -272.116804)
		(width 0.20066)
		(layer "F.Cu")
		(net "M_F_CPU1_SA_CB<6>")
	)
	(segment
		(start 183.958484 -271.864836)
		(end 184.210452 -272.116804)
		(width 0.20066)
		(layer "F.Cu")
		(net "M_F_CPU1_SA_CB<6>")
	)
	(segment
		(start 178.000914 -272.116804)
		(end 179.699158 -272.116804)
		(width 0.20066)
		(layer "F.Cu")
		(net "M_F_CPU1_SA_CB<6>")
	)
	(segment
		(start 178.00066 -272.11655)
		(end 178.000914 -272.116804)
		(width 0.20066)
		(layer "F.Cu")
		(net "M_F_CPU1_SA_CB<6>")
	)
	(segment
		(start 180.131212 -272.548858)
		(end 180.423058 -272.548858)
		(width 0.20066)
		(layer "F.Cu")
		(net "M_F_CPU1_SA_CB<6>")
	)
	(segment
		(start 180.427884 -272.548858)
		(end 180.434996 -272.541746)
		(width 0.1016)
		(layer "F.Cu")
		(net "M_F_CPU1_SA_CB<6>")
	)
	(segment
		(start 180.423058 -272.548858)
		(end 180.427884 -272.548858)
		(width 0.101854)
		(layer "F.Cu")
		(net "M_F_CPU1_SA_CB<6>")
	)
	(segment
		(start 179.699158 -272.116804)
		(end 180.131212 -272.548858)
		(width 0.20066)
		(layer "F.Cu")
		(net "M_F_CPU1_SA_CB<6>")
	)
	(segment
		(start 182.442866 -272.541746)
		(end 182.455058 -272.553938)
		(width 0.1016)
		(layer "F.Cu")
		(net "M_F_CPU1_SA_CB<6>")
	)
	(segment
		(start 183.340248 -272.099024)
		(end 183.574436 -271.864836)
		(width 0.20066)
		(layer "F.Cu")
		(net "M_F_CPU1_SA_CB<6>")
	)
	(segment
		(start 176.896014 -272.11655)
		(end 178.00066 -272.11655)
		(width 0.20066)
		(layer "F.Cu")
		(net "M_F_CPU1_SA_CB<6>")
	)
	(segment
		(start 135.245094 -261.522718)
		(end 135.245094 -262.058658)
		(width 0.20066)
		(layer "F.Cu")
		(net "M_F_CPU1_SA_CB<6>")
	)
	(segment
		(start 183.340248 -272.349976)
		(end 183.340248 -272.099024)
		(width 0.20066)
		(layer "F.Cu")
		(net "M_F_CPU1_SA_CB<6>")
	)
	(segment
		(start 182.455058 -272.553938)
		(end 183.136286 -272.553938)
		(width 0.20066)
		(layer "F.Cu")
		(net "M_F_CPU1_SA_CB<6>")
	)
	(segment
		(start 183.136286 -272.553938)
		(end 183.340248 -272.349976)
		(width 0.20066)
		(layer "F.Cu")
		(net "M_F_CPU1_SA_CB<6>")
	)
	(segment
		(start 183.574436 -271.864836)
		(end 183.958484 -271.864836)
		(width 0.20066)
		(layer "F.Cu")
		(net "M_F_CPU1_SA_CB<6>")
	)
	(segment
		(start 180.434996 -272.541746)
		(end 182.442866 -272.541746)
		(width 0.1016)
		(layer "F.Cu")
		(net "M_F_CPU1_SA_CB<6>")
	)
	(segment
		(start 167.4876 -271.394682)
		(end 167.188134 -271.694148)
		(width 0.18288)
		(layer "In2.Cu")
		(net "M_F_CPU1_SA_CB<6>")
	)
	(segment
		(start 157.274768 -269.992094)
		(end 152.267158 -264.984484)
		(width 0.18288)
		(layer "In2.Cu")
		(net "M_F_CPU1_SA_CB<6>")
	)
	(segment
		(start 174.532544 -272.33499)
		(end 174.339504 -272.52803)
		(width 0.18288)
		(layer "In2.Cu")
		(net "M_F_CPU1_SA_CB<6>")
	)
	(segment
		(start 173.711616 -272.52803)
		(end 173.535086 -272.3515)
		(width 0.18288)
		(layer "In2.Cu")
		(net "M_F_CPU1_SA_CB<6>")
	)
	(segment
		(start 161.95929 -270.81099)
		(end 161.045144 -270.81099)
		(width 0.18288)
		(layer "In2.Cu")
		(net "M_F_CPU1_SA_CB<6>")
	)
	(segment
		(start 162.03803 -270.88973)
		(end 161.95929 -270.81099)
		(width 0.18288)
		(layer "In2.Cu")
		(net "M_F_CPU1_SA_CB<6>")
	)
	(segment
		(start 163.708334 -270.88973)
		(end 162.03803 -270.88973)
		(width 0.18288)
		(layer "In2.Cu")
		(net "M_F_CPU1_SA_CB<6>")
	)
	(segment
		(start 175.501046 -272.321528)
		(end 175.501046 -271.716246)
		(width 0.18288)
		(layer "In2.Cu")
		(net "M_F_CPU1_SA_CB<6>")
	)
	(segment
		(start 176.45888 -271.90573)
		(end 176.29886 -272.06575)
		(width 0.18288)
		(layer "In2.Cu")
		(net "M_F_CPU1_SA_CB<6>")
	)
	(segment
		(start 174.339504 -272.52803)
		(end 173.711616 -272.52803)
		(width 0.18288)
		(layer "In2.Cu")
		(net "M_F_CPU1_SA_CB<6>")
	)
	(segment
		(start 145.085054 -261.802626)
		(end 144.64284 -261.619238)
		(width 0.18288)
		(layer "In2.Cu")
		(net "M_F_CPU1_SA_CB<6>")
	)
	(segment
		(start 152.267158 -264.984484)
		(end 152.267158 -264.578084)
		(width 0.18288)
		(layer "In2.Cu")
		(net "M_F_CPU1_SA_CB<6>")
	)
	(segment
		(start 165.53688 -271.694148)
		(end 164.599112 -270.75638)
		(width 0.18288)
		(layer "In2.Cu")
		(net "M_F_CPU1_SA_CB<6>")
	)
	(segment
		(start 167.760904 -271.394682)
		(end 167.4876 -271.394682)
		(width 0.18288)
		(layer "In2.Cu")
		(net "M_F_CPU1_SA_CB<6>")
	)
	(segment
		(start 159.63265 -269.992094)
		(end 157.274768 -269.992094)
		(width 0.18288)
		(layer "In2.Cu")
		(net "M_F_CPU1_SA_CB<6>")
	)
	(segment
		(start 169.143426 -271.734026)
		(end 168.92397 -271.51457)
		(width 0.18288)
		(layer "In2.Cu")
		(net "M_F_CPU1_SA_CB<6>")
	)
	(segment
		(start 135.902192 -261.5692)
		(end 135.873998 -261.585456)
		(width 0.088646)
		(layer "In2.Cu")
		(net "M_F_CPU1_SA_CB<6>")
	)
	(segment
		(start 159.77489 -269.849854)
		(end 159.63265 -269.992094)
		(width 0.18288)
		(layer "In2.Cu")
		(net "M_F_CPU1_SA_CB<6>")
	)
	(segment
		(start 163.841684 -270.75638)
		(end 163.708334 -270.88973)
		(width 0.18288)
		(layer "In2.Cu")
		(net "M_F_CPU1_SA_CB<6>")
	)
	(segment
		(start 175.722026 -272.542508)
		(end 175.501046 -272.321528)
		(width 0.18288)
		(layer "In2.Cu")
		(net "M_F_CPU1_SA_CB<6>")
	)
	(segment
		(start 151.564848 -263.875774)
		(end 147.158202 -263.875774)
		(width 0.18288)
		(layer "In2.Cu")
		(net "M_F_CPU1_SA_CB<6>")
	)
	(segment
		(start 176.685194 -271.90573)
		(end 176.45888 -271.90573)
		(width 0.18288)
		(layer "In2.Cu")
		(net "M_F_CPU1_SA_CB<6>")
	)
	(segment
		(start 147.158202 -263.875774)
		(end 145.085054 -261.802626)
		(width 0.18288)
		(layer "In2.Cu")
		(net "M_F_CPU1_SA_CB<6>")
	)
	(segment
		(start 174.532544 -271.924272)
		(end 174.532544 -272.33499)
		(width 0.18288)
		(layer "In2.Cu")
		(net "M_F_CPU1_SA_CB<6>")
	)
	(segment
		(start 161.045144 -270.81099)
		(end 160.084008 -269.849854)
		(width 0.18288)
		(layer "In2.Cu")
		(net "M_F_CPU1_SA_CB<6>")
	)
	(segment
		(start 173.535086 -271.851374)
		(end 173.375066 -271.691354)
		(width 0.18288)
		(layer "In2.Cu")
		(net "M_F_CPU1_SA_CB<6>")
	)
	(segment
		(start 175.501046 -271.716246)
		(end 175.341026 -271.556226)
		(width 0.18288)
		(layer "In2.Cu")
		(net "M_F_CPU1_SA_CB<6>")
	)
	(segment
		(start 140.417804 -261.493254)
		(end 139.944348 -261.493254)
		(width 0.088646)
		(layer "In2.Cu")
		(net "M_F_CPU1_SA_CB<6>")
	)
	(segment
		(start 168.92397 -271.51457)
		(end 167.880792 -271.51457)
		(width 0.18288)
		(layer "In2.Cu")
		(net "M_F_CPU1_SA_CB<6>")
	)
	(segment
		(start 173.375066 -271.691354)
		(end 172.589698 -271.691354)
		(width 0.18288)
		(layer "In2.Cu")
		(net "M_F_CPU1_SA_CB<6>")
	)
	(segment
		(start 140.90015 -261.619238)
		(end 140.543788 -261.619238)
		(width 0.088646)
		(layer "In2.Cu")
		(net "M_F_CPU1_SA_CB<6>")
	)
	(segment
		(start 135.873998 -261.585456)
		(end 135.245094 -262.058658)
		(width 0.088646)
		(layer "In2.Cu")
		(net "M_F_CPU1_SA_CB<6>")
	)
	(segment
		(start 144.64284 -261.619238)
		(end 140.90015 -261.619238)
		(width 0.18288)
		(layer "In2.Cu")
		(net "M_F_CPU1_SA_CB<6>")
	)
	(segment
		(start 176.29886 -272.34261)
		(end 176.098962 -272.542508)
		(width 0.18288)
		(layer "In2.Cu")
		(net "M_F_CPU1_SA_CB<6>")
	)
	(segment
		(start 172.547026 -271.734026)
		(end 169.143426 -271.734026)
		(width 0.18288)
		(layer "In2.Cu")
		(net "M_F_CPU1_SA_CB<6>")
	)
	(segment
		(start 176.29886 -272.06575)
		(end 176.29886 -272.34261)
		(width 0.18288)
		(layer "In2.Cu")
		(net "M_F_CPU1_SA_CB<6>")
	)
	(segment
		(start 140.543788 -261.619238)
		(end 140.417804 -261.493254)
		(width 0.088646)
		(layer "In2.Cu")
		(net "M_F_CPU1_SA_CB<6>")
	)
	(segment
		(start 167.880792 -271.51457)
		(end 167.760904 -271.394682)
		(width 0.18288)
		(layer "In2.Cu")
		(net "M_F_CPU1_SA_CB<6>")
	)
	(segment
		(start 173.535086 -272.3515)
		(end 173.535086 -271.851374)
		(width 0.18288)
		(layer "In2.Cu")
		(net "M_F_CPU1_SA_CB<6>")
	)
	(segment
		(start 175.341026 -271.556226)
		(end 174.90059 -271.556226)
		(width 0.18288)
		(layer "In2.Cu")
		(net "M_F_CPU1_SA_CB<6>")
	)
	(segment
		(start 174.90059 -271.556226)
		(end 174.532544 -271.924272)
		(width 0.18288)
		(layer "In2.Cu")
		(net "M_F_CPU1_SA_CB<6>")
	)
	(segment
		(start 172.589698 -271.691354)
		(end 172.547026 -271.734026)
		(width 0.18288)
		(layer "In2.Cu")
		(net "M_F_CPU1_SA_CB<6>")
	)
	(segment
		(start 167.188134 -271.694148)
		(end 165.53688 -271.694148)
		(width 0.18288)
		(layer "In2.Cu")
		(net "M_F_CPU1_SA_CB<6>")
	)
	(segment
		(start 176.098962 -272.542508)
		(end 175.722026 -272.542508)
		(width 0.18288)
		(layer "In2.Cu")
		(net "M_F_CPU1_SA_CB<6>")
	)
	(segment
		(start 160.084008 -269.849854)
		(end 159.77489 -269.849854)
		(width 0.18288)
		(layer "In2.Cu")
		(net "M_F_CPU1_SA_CB<6>")
	)
	(segment
		(start 152.267158 -264.578084)
		(end 151.564848 -263.875774)
		(width 0.18288)
		(layer "In2.Cu")
		(net "M_F_CPU1_SA_CB<6>")
	)
	(segment
		(start 164.599112 -270.75638)
		(end 163.841684 -270.75638)
		(width 0.18288)
		(layer "In2.Cu")
		(net "M_F_CPU1_SA_CB<6>")
	)
	(segment
		(start 176.896014 -272.11655)
		(end 176.685194 -271.90573)
		(width 0.18288)
		(layer "In2.Cu")
		(net "M_F_CPU1_SA_CB<6>")
	)
	(arc
		(start 138.721592 -261.5692)
		(mid 138.534394 -261.619343)
		(end 138.347196 -261.5692)
		(width 0.088646)
		(layer "In2.Cu")
		(net "M_F_CPU1_SA_CB<6>")
	)
	(arc
		(start 137.781792 -261.5692)
		(mid 137.594594 -261.619343)
		(end 137.407396 -261.5692)
		(width 0.088646)
		(layer "In2.Cu")
		(net "M_F_CPU1_SA_CB<6>")
	)
	(arc
		(start 137.407396 -261.5692)
		(mid 137.124694 -261.493424)
		(end 136.841992 -261.5692)
		(width 0.088646)
		(layer "In2.Cu")
		(net "M_F_CPU1_SA_CB<6>")
	)
	(arc
		(start 138.347196 -261.5692)
		(mid 138.064494 -261.493424)
		(end 137.781792 -261.5692)
		(width 0.088646)
		(layer "In2.Cu")
		(net "M_F_CPU1_SA_CB<6>")
	)
	(arc
		(start 136.467596 -261.5692)
		(mid 136.184894 -261.493458)
		(end 135.902192 -261.5692)
		(width 0.088646)
		(layer "In2.Cu")
		(net "M_F_CPU1_SA_CB<6>")
	)
	(arc
		(start 136.841992 -261.5692)
		(mid 136.654794 -261.619343)
		(end 136.467596 -261.5692)
		(width 0.088646)
		(layer "In2.Cu")
		(net "M_F_CPU1_SA_CB<6>")
	)
	(arc
		(start 139.944348 -261.493254)
		(mid 139.797861 -261.512569)
		(end 139.661392 -261.5692)
		(width 0.088646)
		(layer "In2.Cu")
		(net "M_F_CPU1_SA_CB<6>")
	)
	(arc
		(start 139.661392 -261.5692)
		(mid 139.474194 -261.619343)
		(end 139.286996 -261.5692)
		(width 0.088646)
		(layer "In2.Cu")
		(net "M_F_CPU1_SA_CB<6>")
	)
	(arc
		(start 139.286996 -261.5692)
		(mid 139.004294 -261.493424)
		(end 138.721592 -261.5692)
		(width 0.088646)
		(layer "In2.Cu")
		(net "M_F_CPU1_SA_CB<6>")
	)
	(segment
		(start 176.333404 -271.327372)
		(end 176.145444 -271.515332)
		(width 0.20066)
		(layer "F.Cu")
		(net "M_F_CPU1_SA_CB<5>")
	)
	(segment
		(start 181.444392 -271.26692)
		(end 179.852828 -271.26692)
		(width 0.20066)
		(layer "F.Cu")
		(net "M_F_CPU1_SA_CB<5>")
	)
	(segment
		(start 179.421282 -270.835374)
		(end 179.011326 -270.835374)
		(width 0.20066)
		(layer "F.Cu")
		(net "M_F_CPU1_SA_CB<5>")
	)
	(segment
		(start 176.816258 -270.841724)
		(end 176.796192 -270.841724)
		(width 0.101854)
		(layer "F.Cu")
		(net "M_F_CPU1_SA_CB<5>")
	)
	(segment
		(start 133.835648 -261.244334)
		(end 133.835394 -261.244588)
		(width 0.20066)
		(layer "F.Cu")
		(net "M_F_CPU1_SA_CB<5>")
	)
	(segment
		(start 179.011326 -270.835374)
		(end 179.004976 -270.841724)
		(width 0.1016)
		(layer "F.Cu")
		(net "M_F_CPU1_SA_CB<5>")
	)
	(segment
		(start 133.835648 -260.708902)
		(end 133.835648 -261.244334)
		(width 0.20066)
		(layer "F.Cu")
		(net "M_F_CPU1_SA_CB<5>")
	)
	(segment
		(start 176.796192 -270.841724)
		(end 176.451514 -270.841724)
		(width 0.20066)
		(layer "F.Cu")
		(net "M_F_CPU1_SA_CB<5>")
	)
	(segment
		(start 176.145444 -271.515332)
		(end 175.67021 -271.515332)
		(width 0.20066)
		(layer "F.Cu")
		(net "M_F_CPU1_SA_CB<5>")
	)
	(segment
		(start 175.67021 -271.515332)
		(end 175.421544 -271.266666)
		(width 0.20066)
		(layer "F.Cu")
		(net "M_F_CPU1_SA_CB<5>")
	)
	(segment
		(start 133.835394 -261.244588)
		(end 133.835394 -261.244842)
		(width 0.20066)
		(layer "F.Cu")
		(net "M_F_CPU1_SA_CB<5>")
	)
	(segment
		(start 175.421544 -271.266666)
		(end 173.900846 -271.266666)
		(width 0.20066)
		(layer "F.Cu")
		(net "M_F_CPU1_SA_CB<5>")
	)
	(segment
		(start 181.444646 -271.266666)
		(end 181.444392 -271.26692)
		(width 0.20066)
		(layer "F.Cu")
		(net "M_F_CPU1_SA_CB<5>")
	)
	(segment
		(start 176.451514 -270.841724)
		(end 176.333404 -270.959834)
		(width 0.20066)
		(layer "F.Cu")
		(net "M_F_CPU1_SA_CB<5>")
	)
	(segment
		(start 173.900846 -271.266666)
		(end 172.795946 -271.266666)
		(width 0.20066)
		(layer "F.Cu")
		(net "M_F_CPU1_SA_CB<5>")
	)
	(segment
		(start 176.333404 -270.959834)
		(end 176.333404 -271.327372)
		(width 0.20066)
		(layer "F.Cu")
		(net "M_F_CPU1_SA_CB<5>")
	)
	(segment
		(start 179.852828 -271.26692)
		(end 179.421282 -270.835374)
		(width 0.20066)
		(layer "F.Cu")
		(net "M_F_CPU1_SA_CB<5>")
	)
	(segment
		(start 179.004976 -270.841724)
		(end 176.816258 -270.841724)
		(width 0.1016)
		(layer "F.Cu")
		(net "M_F_CPU1_SA_CB<5>")
	)
	(segment
		(start 167.91178 -270.03121)
		(end 167.683434 -269.802864)
		(width 0.18288)
		(layer "In2.Cu")
		(net "M_F_CPU1_SA_CB<5>")
	)
	(segment
		(start 153.485088 -265.068558)
		(end 153.072592 -265.068558)
		(width 0.18288)
		(layer "In2.Cu")
		(net "M_F_CPU1_SA_CB<5>")
	)
	(segment
		(start 154.06878 -266.064746)
		(end 153.776934 -265.7729)
		(width 0.18288)
		(layer "In2.Cu")
		(net "M_F_CPU1_SA_CB<5>")
	)
	(segment
		(start 152.780746 -264.776712)
		(end 152.780746 -264.364216)
		(width 0.18288)
		(layer "In2.Cu")
		(net "M_F_CPU1_SA_CB<5>")
	)
	(segment
		(start 155.76931 -267.765276)
		(end 155.76931 -267.35278)
		(width 0.18288)
		(layer "In2.Cu")
		(net "M_F_CPU1_SA_CB<5>")
	)
	(segment
		(start 158.083758 -269.140686)
		(end 157.14472 -269.140686)
		(width 0.18288)
		(layer "In2.Cu")
		(net "M_F_CPU1_SA_CB<5>")
	)
	(segment
		(start 172.253656 -271.266666)
		(end 171.685966 -270.698976)
		(width 0.18288)
		(layer "In2.Cu")
		(net "M_F_CPU1_SA_CB<5>")
	)
	(segment
		(start 140.173202 -260.99643)
		(end 139.944348 -260.99643)
		(width 0.088646)
		(layer "In2.Cu")
		(net "M_F_CPU1_SA_CB<5>")
	)
	(segment
		(start 134.50316 -261.740396)
		(end 134.492746 -261.7343)
		(width 0.088646)
		(layer "In2.Cu")
		(net "M_F_CPU1_SA_CB<5>")
	)
	(segment
		(start 135.340344 -261.244842)
		(end 135.340344 -261.254748)
		(width 0.088646)
		(layer "In2.Cu")
		(net "M_F_CPU1_SA_CB<5>")
	)
	(segment
		(start 155.76931 -267.35278)
		(end 155.477464 -267.060934)
		(width 0.18288)
		(layer "In2.Cu")
		(net "M_F_CPU1_SA_CB<5>")
	)
	(segment
		(start 159.59963 -269.155926)
		(end 159.318706 -268.875002)
		(width 0.18288)
		(layer "In2.Cu")
		(net "M_F_CPU1_SA_CB<5>")
	)
	(segment
		(start 164.698172 -270.24838)
		(end 164.11448 -270.24838)
		(width 0.18288)
		(layer "In2.Cu")
		(net "M_F_CPU1_SA_CB<5>")
	)
	(segment
		(start 158.349442 -268.875002)
		(end 158.083758 -269.140686)
		(width 0.18288)
		(layer "In2.Cu")
		(net "M_F_CPU1_SA_CB<5>")
	)
	(segment
		(start 145.336768 -261.502144)
		(end 144.747234 -261.25805)
		(width 0.18288)
		(layer "In2.Cu")
		(net "M_F_CPU1_SA_CB<5>")
	)
	(segment
		(start 140.434822 -261.25805)
		(end 140.173202 -260.99643)
		(width 0.088646)
		(layer "In2.Cu")
		(net "M_F_CPU1_SA_CB<5>")
	)
	(segment
		(start 154.773122 -266.769088)
		(end 154.773122 -266.356592)
		(width 0.18288)
		(layer "In2.Cu")
		(net "M_F_CPU1_SA_CB<5>")
	)
	(segment
		(start 169.253916 -270.553942)
		(end 168.980612 -270.553942)
		(width 0.18288)
		(layer "In2.Cu")
		(net "M_F_CPU1_SA_CB<5>")
	)
	(segment
		(start 168.980612 -270.553942)
		(end 168.527984 -271.00657)
		(width 0.18288)
		(layer "In2.Cu")
		(net "M_F_CPU1_SA_CB<5>")
	)
	(segment
		(start 169.926 -271.226026)
		(end 169.253916 -270.553942)
		(width 0.18288)
		(layer "In2.Cu")
		(net "M_F_CPU1_SA_CB<5>")
	)
	(segment
		(start 156.473652 -268.057122)
		(end 156.061156 -268.057122)
		(width 0.18288)
		(layer "In2.Cu")
		(net "M_F_CPU1_SA_CB<5>")
	)
	(segment
		(start 161.434272 -270.29029)
		(end 161.141156 -269.997174)
		(width 0.18288)
		(layer "In2.Cu")
		(net "M_F_CPU1_SA_CB<5>")
	)
	(segment
		(start 172.795946 -271.266666)
		(end 172.253656 -271.266666)
		(width 0.18288)
		(layer "In2.Cu")
		(net "M_F_CPU1_SA_CB<5>")
	)
	(segment
		(start 155.064968 -267.060934)
		(end 154.773122 -266.769088)
		(width 0.18288)
		(layer "In2.Cu")
		(net "M_F_CPU1_SA_CB<5>")
	)
	(segment
		(start 157.14472 -269.140686)
		(end 156.765498 -268.761464)
		(width 0.18288)
		(layer "In2.Cu")
		(net "M_F_CPU1_SA_CB<5>")
	)
	(segment
		(start 153.072592 -265.068558)
		(end 152.780746 -264.776712)
		(width 0.18288)
		(layer "In2.Cu")
		(net "M_F_CPU1_SA_CB<5>")
	)
	(segment
		(start 171.685966 -270.698976)
		(end 171.403518 -270.698976)
		(width 0.18288)
		(layer "In2.Cu")
		(net "M_F_CPU1_SA_CB<5>")
	)
	(segment
		(start 134.148322 -261.244842)
		(end 133.835394 -261.244842)
		(width 0.088646)
		(layer "In2.Cu")
		(net "M_F_CPU1_SA_CB<5>")
	)
	(segment
		(start 153.776934 -265.7729)
		(end 153.776934 -265.360404)
		(width 0.18288)
		(layer "In2.Cu")
		(net "M_F_CPU1_SA_CB<5>")
	)
	(segment
		(start 135.527796 -260.920484)
		(end 135.518906 -260.925564)
		(width 0.088646)
		(layer "In2.Cu")
		(net "M_F_CPU1_SA_CB<5>")
	)
	(segment
		(start 167.91178 -270.80845)
		(end 167.91178 -270.03121)
		(width 0.18288)
		(layer "In2.Cu")
		(net "M_F_CPU1_SA_CB<5>")
	)
	(segment
		(start 164.83711 -270.032226)
		(end 164.83711 -270.109442)
		(width 0.18288)
		(layer "In2.Cu")
		(net "M_F_CPU1_SA_CB<5>")
	)
	(segment
		(start 154.773122 -266.356592)
		(end 154.481276 -266.064746)
		(width 0.18288)
		(layer "In2.Cu")
		(net "M_F_CPU1_SA_CB<5>")
	)
	(segment
		(start 165.735254 -270.604996)
		(end 165.735254 -270.135096)
		(width 0.18288)
		(layer "In2.Cu")
		(net "M_F_CPU1_SA_CB<5>")
	)
	(segment
		(start 166.799514 -270.854932)
		(end 165.98519 -270.854932)
		(width 0.18288)
		(layer "In2.Cu")
		(net "M_F_CPU1_SA_CB<5>")
	)
	(segment
		(start 134.213854 -261.310374)
		(end 134.148322 -261.244842)
		(width 0.088646)
		(layer "In2.Cu")
		(net "M_F_CPU1_SA_CB<5>")
	)
	(segment
		(start 161.141156 -269.199868)
		(end 160.948116 -269.006828)
		(width 0.18288)
		(layer "In2.Cu")
		(net "M_F_CPU1_SA_CB<5>")
	)
	(segment
		(start 165.030404 -269.838932)
		(end 164.83711 -270.032226)
		(width 0.18288)
		(layer "In2.Cu")
		(net "M_F_CPU1_SA_CB<5>")
	)
	(segment
		(start 147.202398 -263.367774)
		(end 145.336768 -261.502144)
		(width 0.18288)
		(layer "In2.Cu")
		(net "M_F_CPU1_SA_CB<5>")
	)
	(segment
		(start 167.683434 -269.802864)
		(end 167.315896 -269.802864)
		(width 0.18288)
		(layer "In2.Cu")
		(net "M_F_CPU1_SA_CB<5>")
	)
	(segment
		(start 134.492746 -261.7343)
		(end 134.48665 -261.730744)
		(width 0.088646)
		(layer "In2.Cu")
		(net "M_F_CPU1_SA_CB<5>")
	)
	(segment
		(start 140.90015 -261.25805)
		(end 140.434822 -261.25805)
		(width 0.088646)
		(layer "In2.Cu")
		(net "M_F_CPU1_SA_CB<5>")
	)
	(segment
		(start 144.747234 -261.25805)
		(end 140.90015 -261.25805)
		(width 0.18288)
		(layer "In2.Cu")
		(net "M_F_CPU1_SA_CB<5>")
	)
	(segment
		(start 155.477464 -267.060934)
		(end 155.064968 -267.060934)
		(width 0.18288)
		(layer "In2.Cu")
		(net "M_F_CPU1_SA_CB<5>")
	)
	(segment
		(start 163.90874 -270.04264)
		(end 161.982912 -270.04264)
		(width 0.18288)
		(layer "In2.Cu")
		(net "M_F_CPU1_SA_CB<5>")
	)
	(segment
		(start 167.315896 -269.802864)
		(end 167.032178 -270.086582)
		(width 0.18288)
		(layer "In2.Cu")
		(net "M_F_CPU1_SA_CB<5>")
	)
	(segment
		(start 164.11448 -270.24838)
		(end 163.90874 -270.04264)
		(width 0.18288)
		(layer "In2.Cu")
		(net "M_F_CPU1_SA_CB<5>")
	)
	(segment
		(start 156.765498 -268.348968)
		(end 156.473652 -268.057122)
		(width 0.18288)
		(layer "In2.Cu")
		(net "M_F_CPU1_SA_CB<5>")
	)
	(segment
		(start 167.032178 -270.622268)
		(end 166.799514 -270.854932)
		(width 0.18288)
		(layer "In2.Cu")
		(net "M_F_CPU1_SA_CB<5>")
	)
	(segment
		(start 156.765498 -268.761464)
		(end 156.765498 -268.348968)
		(width 0.18288)
		(layer "In2.Cu")
		(net "M_F_CPU1_SA_CB<5>")
	)
	(segment
		(start 168.527984 -271.00657)
		(end 168.1099 -271.00657)
		(width 0.18288)
		(layer "In2.Cu")
		(net "M_F_CPU1_SA_CB<5>")
	)
	(segment
		(start 159.318706 -268.875002)
		(end 158.349442 -268.875002)
		(width 0.18288)
		(layer "In2.Cu")
		(net "M_F_CPU1_SA_CB<5>")
	)
	(segment
		(start 165.735254 -270.135096)
		(end 165.43909 -269.838932)
		(width 0.18288)
		(layer "In2.Cu")
		(net "M_F_CPU1_SA_CB<5>")
	)
	(segment
		(start 165.43909 -269.838932)
		(end 165.030404 -269.838932)
		(width 0.18288)
		(layer "In2.Cu")
		(net "M_F_CPU1_SA_CB<5>")
	)
	(segment
		(start 170.876468 -271.226026)
		(end 169.926 -271.226026)
		(width 0.18288)
		(layer "In2.Cu")
		(net "M_F_CPU1_SA_CB<5>")
	)
	(segment
		(start 165.98519 -270.854932)
		(end 165.735254 -270.604996)
		(width 0.18288)
		(layer "In2.Cu")
		(net "M_F_CPU1_SA_CB<5>")
	)
	(segment
		(start 167.032178 -270.086582)
		(end 167.032178 -270.622268)
		(width 0.18288)
		(layer "In2.Cu")
		(net "M_F_CPU1_SA_CB<5>")
	)
	(segment
		(start 153.776934 -265.360404)
		(end 153.485088 -265.068558)
		(width 0.18288)
		(layer "In2.Cu")
		(net "M_F_CPU1_SA_CB<5>")
	)
	(segment
		(start 161.735262 -270.29029)
		(end 161.434272 -270.29029)
		(width 0.18288)
		(layer "In2.Cu")
		(net "M_F_CPU1_SA_CB<5>")
	)
	(segment
		(start 151.784304 -263.367774)
		(end 147.202398 -263.367774)
		(width 0.18288)
		(layer "In2.Cu")
		(net "M_F_CPU1_SA_CB<5>")
	)
	(segment
		(start 160.948116 -269.006828)
		(end 160.292796 -269.006828)
		(width 0.18288)
		(layer "In2.Cu")
		(net "M_F_CPU1_SA_CB<5>")
	)
	(segment
		(start 161.982912 -270.04264)
		(end 161.735262 -270.29029)
		(width 0.18288)
		(layer "In2.Cu")
		(net "M_F_CPU1_SA_CB<5>")
	)
	(segment
		(start 161.141156 -269.997174)
		(end 161.141156 -269.199868)
		(width 0.18288)
		(layer "In2.Cu")
		(net "M_F_CPU1_SA_CB<5>")
	)
	(segment
		(start 156.061156 -268.057122)
		(end 155.76931 -267.765276)
		(width 0.18288)
		(layer "In2.Cu")
		(net "M_F_CPU1_SA_CB<5>")
	)
	(segment
		(start 168.1099 -271.00657)
		(end 167.91178 -270.80845)
		(width 0.18288)
		(layer "In2.Cu")
		(net "M_F_CPU1_SA_CB<5>")
	)
	(segment
		(start 160.143698 -269.155926)
		(end 159.59963 -269.155926)
		(width 0.18288)
		(layer "In2.Cu")
		(net "M_F_CPU1_SA_CB<5>")
	)
	(segment
		(start 160.292796 -269.006828)
		(end 160.143698 -269.155926)
		(width 0.18288)
		(layer "In2.Cu")
		(net "M_F_CPU1_SA_CB<5>")
	)
	(segment
		(start 171.403518 -270.698976)
		(end 170.876468 -271.226026)
		(width 0.18288)
		(layer "In2.Cu")
		(net "M_F_CPU1_SA_CB<5>")
	)
	(segment
		(start 152.780746 -264.364216)
		(end 151.784304 -263.367774)
		(width 0.18288)
		(layer "In2.Cu")
		(net "M_F_CPU1_SA_CB<5>")
	)
	(segment
		(start 164.83711 -270.109442)
		(end 164.698172 -270.24838)
		(width 0.18288)
		(layer "In2.Cu")
		(net "M_F_CPU1_SA_CB<5>")
	)
	(segment
		(start 154.481276 -266.064746)
		(end 154.06878 -266.064746)
		(width 0.18288)
		(layer "In2.Cu")
		(net "M_F_CPU1_SA_CB<5>")
	)
	(arc
		(start 135.057896 -261.7343)
		(mid 134.781337 -261.810043)
		(end 134.50316 -261.740396)
		(width 0.088646)
		(layer "In2.Cu")
		(net "M_F_CPU1_SA_CB<5>")
	)
	(arc
		(start 139.286996 -260.920484)
		(mid 139.004294 -260.996226)
		(end 138.721592 -260.920484)
		(width 0.088646)
		(layer "In2.Cu")
		(net "M_F_CPU1_SA_CB<5>")
	)
	(arc
		(start 135.340344 -261.254748)
		(mid 135.262233 -261.531697)
		(end 135.057896 -261.7343)
		(width 0.088646)
		(layer "In2.Cu")
		(net "M_F_CPU1_SA_CB<5>")
	)
	(arc
		(start 136.841992 -260.920484)
		(mid 136.654794 -260.870341)
		(end 136.467596 -260.920484)
		(width 0.088646)
		(layer "In2.Cu")
		(net "M_F_CPU1_SA_CB<5>")
	)
	(arc
		(start 138.347196 -260.920484)
		(mid 138.064494 -260.996226)
		(end 137.781792 -260.920484)
		(width 0.088646)
		(layer "In2.Cu")
		(net "M_F_CPU1_SA_CB<5>")
	)
	(arc
		(start 134.48665 -261.730744)
		(mid 134.301127 -261.552443)
		(end 134.213854 -261.310374)
		(width 0.088646)
		(layer "In2.Cu")
		(net "M_F_CPU1_SA_CB<5>")
	)
	(arc
		(start 139.661392 -260.920484)
		(mid 139.474194 -260.870341)
		(end 139.286996 -260.920484)
		(width 0.088646)
		(layer "In2.Cu")
		(net "M_F_CPU1_SA_CB<5>")
	)
	(arc
		(start 137.407396 -260.920484)
		(mid 137.124694 -260.996226)
		(end 136.841992 -260.920484)
		(width 0.088646)
		(layer "In2.Cu")
		(net "M_F_CPU1_SA_CB<5>")
	)
	(arc
		(start 135.518906 -260.925564)
		(mid 135.387992 -261.061924)
		(end 135.340344 -261.244842)
		(width 0.088646)
		(layer "In2.Cu")
		(net "M_F_CPU1_SA_CB<5>")
	)
	(arc
		(start 139.944348 -260.99643)
		(mid 139.797878 -260.97707)
		(end 139.661392 -260.920484)
		(width 0.088646)
		(layer "In2.Cu")
		(net "M_F_CPU1_SA_CB<5>")
	)
	(arc
		(start 136.467596 -260.920484)
		(mid 136.184894 -260.996226)
		(end 135.902192 -260.920484)
		(width 0.088646)
		(layer "In2.Cu")
		(net "M_F_CPU1_SA_CB<5>")
	)
	(arc
		(start 137.781792 -260.920484)
		(mid 137.594594 -260.870341)
		(end 137.407396 -260.920484)
		(width 0.088646)
		(layer "In2.Cu")
		(net "M_F_CPU1_SA_CB<5>")
	)
	(arc
		(start 135.902192 -260.920484)
		(mid 135.714994 -260.870341)
		(end 135.527796 -260.920484)
		(width 0.088646)
		(layer "In2.Cu")
		(net "M_F_CPU1_SA_CB<5>")
	)
	(arc
		(start 138.721592 -260.920484)
		(mid 138.534394 -260.870341)
		(end 138.347196 -260.920484)
		(width 0.088646)
		(layer "In2.Cu")
		(net "M_F_CPU1_SA_CB<5>")
	)
	(segment
		(start 179.004976 -272.541746)
		(end 176.843182 -272.541746)
		(width 0.1016)
		(layer "F.Cu")
		(net "M_F_CPU1_SA_CB<4>")
	)
	(segment
		(start 179.011326 -272.535396)
		(end 179.004976 -272.541746)
		(width 0.1016)
		(layer "F.Cu")
		(net "M_F_CPU1_SA_CB<4>")
	)
	(segment
		(start 181.444646 -272.966688)
		(end 181.444392 -272.966942)
		(width 0.20066)
		(layer "F.Cu")
		(net "M_F_CPU1_SA_CB<4>")
	)
	(segment
		(start 179.421282 -272.535396)
		(end 179.011326 -272.535396)
		(width 0.20066)
		(layer "F.Cu")
		(net "M_F_CPU1_SA_CB<4>")
	)
	(segment
		(start 176.796192 -272.541746)
		(end 176.451514 -272.541746)
		(width 0.20066)
		(layer "F.Cu")
		(net "M_F_CPU1_SA_CB<4>")
	)
	(segment
		(start 133.365494 -261.522718)
		(end 133.365748 -261.522972)
		(width 0.20066)
		(layer "F.Cu")
		(net "M_F_CPU1_SA_CB<4>")
	)
	(segment
		(start 179.852828 -272.966942)
		(end 179.421282 -272.535396)
		(width 0.20066)
		(layer "F.Cu")
		(net "M_F_CPU1_SA_CB<4>")
	)
	(segment
		(start 173.900846 -272.966688)
		(end 172.795946 -272.966688)
		(width 0.20066)
		(layer "F.Cu")
		(net "M_F_CPU1_SA_CB<4>")
	)
	(segment
		(start 176.333404 -272.659856)
		(end 176.333404 -273.027394)
		(width 0.20066)
		(layer "F.Cu")
		(net "M_F_CPU1_SA_CB<4>")
	)
	(segment
		(start 176.843182 -272.541746)
		(end 176.796192 -272.541746)
		(width 0.101854)
		(layer "F.Cu")
		(net "M_F_CPU1_SA_CB<4>")
	)
	(segment
		(start 175.421544 -272.966688)
		(end 173.900846 -272.966688)
		(width 0.20066)
		(layer "F.Cu")
		(net "M_F_CPU1_SA_CB<4>")
	)
	(segment
		(start 133.365748 -261.522972)
		(end 133.365748 -262.058658)
		(width 0.20066)
		(layer "F.Cu")
		(net "M_F_CPU1_SA_CB<4>")
	)
	(segment
		(start 176.145444 -273.215354)
		(end 175.67021 -273.215354)
		(width 0.20066)
		(layer "F.Cu")
		(net "M_F_CPU1_SA_CB<4>")
	)
	(segment
		(start 176.451514 -272.541746)
		(end 176.333404 -272.659856)
		(width 0.20066)
		(layer "F.Cu")
		(net "M_F_CPU1_SA_CB<4>")
	)
	(segment
		(start 181.444392 -272.966942)
		(end 179.852828 -272.966942)
		(width 0.20066)
		(layer "F.Cu")
		(net "M_F_CPU1_SA_CB<4>")
	)
	(segment
		(start 175.67021 -273.215354)
		(end 175.421544 -272.966688)
		(width 0.20066)
		(layer "F.Cu")
		(net "M_F_CPU1_SA_CB<4>")
	)
	(segment
		(start 176.333404 -273.027394)
		(end 176.145444 -273.215354)
		(width 0.20066)
		(layer "F.Cu")
		(net "M_F_CPU1_SA_CB<4>")
	)
	(segment
		(start 157.577536 -271.17167)
		(end 157.138878 -271.17167)
		(width 0.18288)
		(layer "In2.Cu")
		(net "M_F_CPU1_SA_CB<4>")
	)
	(segment
		(start 134.214108 -262.457692)
		(end 133.607302 -262.457692)
		(width 0.088646)
		(layer "In2.Cu")
		(net "M_F_CPU1_SA_CB<4>")
	)
	(segment
		(start 164.922708 -272.84299)
		(end 164.699696 -272.619978)
		(width 0.18288)
		(layer "In2.Cu")
		(net "M_F_CPU1_SA_CB<4>")
	)
	(segment
		(start 151.701754 -264.74928)
		(end 151.342344 -264.38987)
		(width 0.18288)
		(layer "In2.Cu")
		(net "M_F_CPU1_SA_CB<4>")
	)
	(segment
		(start 135.997696 -261.7343)
		(end 135.997442 -261.734554)
		(width 0.088646)
		(layer "In2.Cu")
		(net "M_F_CPU1_SA_CB<4>")
	)
	(segment
		(start 169.252392 -272.24609)
		(end 168.924732 -272.24609)
		(width 0.18288)
		(layer "In2.Cu")
		(net "M_F_CPU1_SA_CB<4>")
	)
	(segment
		(start 168.108376 -272.225262)
		(end 168.108376 -272.66519)
		(width 0.18288)
		(layer "In2.Cu")
		(net "M_F_CPU1_SA_CB<4>")
	)
	(segment
		(start 159.91967 -271.160748)
		(end 159.79648 -270.862298)
		(width 0.18288)
		(layer "In2.Cu")
		(net "M_F_CPU1_SA_CB<4>")
	)
	(segment
		(start 157.138878 -271.17167)
		(end 156.98978 -271.022572)
		(width 0.18288)
		(layer "In2.Cu")
		(net "M_F_CPU1_SA_CB<4>")
	)
	(segment
		(start 163.767262 -271.693386)
		(end 163.471606 -271.39773)
		(width 0.18288)
		(layer "In2.Cu")
		(net "M_F_CPU1_SA_CB<4>")
	)
	(segment
		(start 166.53002 -272.34896)
		(end 166.256716 -272.34896)
		(width 0.18288)
		(layer "In2.Cu")
		(net "M_F_CPU1_SA_CB<4>")
	)
	(segment
		(start 135.057896 -262.383016)
		(end 135.043164 -262.37438)
		(width 0.088646)
		(layer "In2.Cu")
		(net "M_F_CPU1_SA_CB<4>")
	)
	(segment
		(start 135.718296 -262.217662)
		(end 135.432292 -262.383016)
		(width 0.088646)
		(layer "In2.Cu")
		(net "M_F_CPU1_SA_CB<4>")
	)
	(segment
		(start 156.56814 -270.004794)
		(end 151.701754 -265.138408)
		(width 0.18288)
		(layer "In2.Cu")
		(net "M_F_CPU1_SA_CB<4>")
	)
	(segment
		(start 172.643292 -272.546826)
		(end 172.430694 -272.546826)
		(width 0.18288)
		(layer "In2.Cu")
		(net "M_F_CPU1_SA_CB<4>")
	)
	(segment
		(start 161.501074 -271.95907)
		(end 161.262568 -271.800066)
		(width 0.18288)
		(layer "In2.Cu")
		(net "M_F_CPU1_SA_CB<4>")
	)
	(segment
		(start 160.548574 -271.45488)
		(end 160.479486 -271.62125)
		(width 0.18288)
		(layer "In2.Cu")
		(net "M_F_CPU1_SA_CB<4>")
	)
	(segment
		(start 165.195758 -272.84299)
		(end 164.922708 -272.84299)
		(width 0.18288)
		(layer "In2.Cu")
		(net "M_F_CPU1_SA_CB<4>")
	)
	(segment
		(start 161.133282 -271.487646)
		(end 160.80105 -271.349978)
		(width 0.18288)
		(layer "In2.Cu")
		(net "M_F_CPU1_SA_CB<4>")
	)
	(segment
		(start 168.924732 -272.24609)
		(end 168.701212 -272.02257)
		(width 0.18288)
		(layer "In2.Cu")
		(net "M_F_CPU1_SA_CB<4>")
	)
	(segment
		(start 163.471606 -271.39773)
		(end 162.404298 -271.39773)
		(width 0.18288)
		(layer "In2.Cu")
		(net "M_F_CPU1_SA_CB<4>")
	)
	(segment
		(start 172.795946 -272.69948)
		(end 172.643292 -272.546826)
		(width 0.18288)
		(layer "In2.Cu")
		(net "M_F_CPU1_SA_CB<4>")
	)
	(segment
		(start 159.925512 -271.564862)
		(end 159.838898 -271.356074)
		(width 0.18288)
		(layer "In2.Cu")
		(net "M_F_CPU1_SA_CB<4>")
	)
	(segment
		(start 166.657782 -272.221198)
		(end 166.53002 -272.34896)
		(width 0.18288)
		(layer "In2.Cu")
		(net "M_F_CPU1_SA_CB<4>")
	)
	(segment
		(start 168.108376 -272.66519)
		(end 167.915336 -272.85823)
		(width 0.18288)
		(layer "In2.Cu")
		(net "M_F_CPU1_SA_CB<4>")
	)
	(segment
		(start 166.109904 -272.202148)
		(end 165.8366 -272.202148)
		(width 0.18288)
		(layer "In2.Cu")
		(net "M_F_CPU1_SA_CB<4>")
	)
	(segment
		(start 159.445452 -270.716248)
		(end 159.239458 -270.510254)
		(width 0.18288)
		(layer "In2.Cu")
		(net "M_F_CPU1_SA_CB<4>")
	)
	(segment
		(start 151.701754 -265.138408)
		(end 151.701754 -264.74928)
		(width 0.18288)
		(layer "In2.Cu")
		(net "M_F_CPU1_SA_CB<4>")
	)
	(segment
		(start 140.254736 -261.6835)
		(end 139.944348 -261.6835)
		(width 0.088646)
		(layer "In2.Cu")
		(net "M_F_CPU1_SA_CB<4>")
	)
	(segment
		(start 160.80105 -271.349978)
		(end 160.548574 -271.45488)
		(width 0.18288)
		(layer "In2.Cu")
		(net "M_F_CPU1_SA_CB<4>")
	)
	(segment
		(start 165.8366 -272.202148)
		(end 165.195758 -272.84299)
		(width 0.18288)
		(layer "In2.Cu")
		(net "M_F_CPU1_SA_CB<4>")
	)
	(segment
		(start 133.4643 -262.354568)
		(end 133.365748 -262.058658)
		(width 0.088646)
		(layer "In2.Cu")
		(net "M_F_CPU1_SA_CB<4>")
	)
	(segment
		(start 172.125894 -272.242026)
		(end 171.652946 -272.242026)
		(width 0.18288)
		(layer "In2.Cu")
		(net "M_F_CPU1_SA_CB<4>")
	)
	(segment
		(start 159.79648 -270.862298)
		(end 159.445452 -270.716248)
		(width 0.18288)
		(layer "In2.Cu")
		(net "M_F_CPU1_SA_CB<4>")
	)
	(segment
		(start 160.270952 -271.707864)
		(end 159.925512 -271.564862)
		(width 0.18288)
		(layer "In2.Cu")
		(net "M_F_CPU1_SA_CB<4>")
	)
	(segment
		(start 147.183348 -264.38987)
		(end 144.961864 -262.168386)
		(width 0.18288)
		(layer "In2.Cu")
		(net "M_F_CPU1_SA_CB<4>")
	)
	(segment
		(start 166.256716 -272.34896)
		(end 166.109904 -272.202148)
		(width 0.18288)
		(layer "In2.Cu")
		(net "M_F_CPU1_SA_CB<4>")
	)
	(segment
		(start 162.404298 -271.39773)
		(end 161.842958 -271.95907)
		(width 0.18288)
		(layer "In2.Cu")
		(net "M_F_CPU1_SA_CB<4>")
	)
	(segment
		(start 167.915336 -272.85823)
		(end 167.568118 -272.85823)
		(width 0.18288)
		(layer "In2.Cu")
		(net "M_F_CPU1_SA_CB<4>")
	)
	(segment
		(start 144.477486 -261.967726)
		(end 140.900404 -261.967726)
		(width 0.18288)
		(layer "In2.Cu")
		(net "M_F_CPU1_SA_CB<4>")
	)
	(segment
		(start 164.506402 -271.693386)
		(end 163.767262 -271.693386)
		(width 0.18288)
		(layer "In2.Cu")
		(net "M_F_CPU1_SA_CB<4>")
	)
	(segment
		(start 171.392342 -272.50263)
		(end 169.508932 -272.50263)
		(width 0.18288)
		(layer "In2.Cu")
		(net "M_F_CPU1_SA_CB<4>")
	)
	(segment
		(start 140.900404 -261.967726)
		(end 140.538962 -261.967726)
		(width 0.088646)
		(layer "In2.Cu")
		(net "M_F_CPU1_SA_CB<4>")
	)
	(segment
		(start 158.238952 -270.510254)
		(end 157.577536 -271.17167)
		(width 0.18288)
		(layer "In2.Cu")
		(net "M_F_CPU1_SA_CB<4>")
	)
	(segment
		(start 168.701212 -272.02257)
		(end 168.311068 -272.02257)
		(width 0.18288)
		(layer "In2.Cu")
		(net "M_F_CPU1_SA_CB<4>")
	)
	(segment
		(start 169.508932 -272.50263)
		(end 169.252392 -272.24609)
		(width 0.18288)
		(layer "In2.Cu")
		(net "M_F_CPU1_SA_CB<4>")
	)
	(segment
		(start 156.98978 -271.022572)
		(end 156.56814 -270.004794)
		(width 0.18288)
		(layer "In2.Cu")
		(net "M_F_CPU1_SA_CB<4>")
	)
	(segment
		(start 161.262568 -271.800066)
		(end 161.133282 -271.487646)
		(width 0.18288)
		(layer "In2.Cu")
		(net "M_F_CPU1_SA_CB<4>")
	)
	(segment
		(start 144.961864 -262.168386)
		(end 144.477486 -261.967726)
		(width 0.18288)
		(layer "In2.Cu")
		(net "M_F_CPU1_SA_CB<4>")
	)
	(segment
		(start 166.931086 -272.221198)
		(end 166.657782 -272.221198)
		(width 0.18288)
		(layer "In2.Cu")
		(net "M_F_CPU1_SA_CB<4>")
	)
	(segment
		(start 168.311068 -272.02257)
		(end 168.108376 -272.225262)
		(width 0.18288)
		(layer "In2.Cu")
		(net "M_F_CPU1_SA_CB<4>")
	)
	(segment
		(start 172.430694 -272.546826)
		(end 172.125894 -272.242026)
		(width 0.18288)
		(layer "In2.Cu")
		(net "M_F_CPU1_SA_CB<4>")
	)
	(segment
		(start 171.652946 -272.242026)
		(end 171.392342 -272.50263)
		(width 0.18288)
		(layer "In2.Cu")
		(net "M_F_CPU1_SA_CB<4>")
	)
	(segment
		(start 160.479486 -271.62125)
		(end 160.270952 -271.707864)
		(width 0.18288)
		(layer "In2.Cu")
		(net "M_F_CPU1_SA_CB<4>")
	)
	(segment
		(start 159.838898 -271.356074)
		(end 159.91967 -271.160748)
		(width 0.18288)
		(layer "In2.Cu")
		(net "M_F_CPU1_SA_CB<4>")
	)
	(segment
		(start 164.699696 -272.619978)
		(end 164.699696 -271.88668)
		(width 0.18288)
		(layer "In2.Cu")
		(net "M_F_CPU1_SA_CB<4>")
	)
	(segment
		(start 167.568118 -272.85823)
		(end 166.931086 -272.221198)
		(width 0.18288)
		(layer "In2.Cu")
		(net "M_F_CPU1_SA_CB<4>")
	)
	(segment
		(start 159.239458 -270.510254)
		(end 158.238952 -270.510254)
		(width 0.18288)
		(layer "In2.Cu")
		(net "M_F_CPU1_SA_CB<4>")
	)
	(segment
		(start 151.342344 -264.38987)
		(end 147.183348 -264.38987)
		(width 0.18288)
		(layer "In2.Cu")
		(net "M_F_CPU1_SA_CB<4>")
	)
	(segment
		(start 172.795946 -272.966688)
		(end 172.795946 -272.69948)
		(width 0.18288)
		(layer "In2.Cu")
		(net "M_F_CPU1_SA_CB<4>")
	)
	(segment
		(start 140.538962 -261.967726)
		(end 140.254736 -261.6835)
		(width 0.088646)
		(layer "In2.Cu")
		(net "M_F_CPU1_SA_CB<4>")
	)
	(segment
		(start 164.699696 -271.88668)
		(end 164.506402 -271.693386)
		(width 0.18288)
		(layer "In2.Cu")
		(net "M_F_CPU1_SA_CB<4>")
	)
	(segment
		(start 161.842958 -271.95907)
		(end 161.501074 -271.95907)
		(width 0.18288)
		(layer "In2.Cu")
		(net "M_F_CPU1_SA_CB<4>")
	)
	(arc
		(start 139.944348 -261.6835)
		(mid 139.847278 -261.696557)
		(end 139.756896 -261.7343)
		(width 0.088646)
		(layer "In2.Cu")
		(net "M_F_CPU1_SA_CB<4>")
	)
	(arc
		(start 137.311892 -261.7343)
		(mid 137.124694 -261.684157)
		(end 136.937496 -261.7343)
		(width 0.088646)
		(layer "In2.Cu")
		(net "M_F_CPU1_SA_CB<4>")
	)
	(arc
		(start 139.191492 -261.7343)
		(mid 139.004294 -261.684157)
		(end 138.817096 -261.7343)
		(width 0.088646)
		(layer "In2.Cu")
		(net "M_F_CPU1_SA_CB<4>")
	)
	(arc
		(start 133.607302 -262.457692)
		(mid 133.519167 -262.429214)
		(end 133.4643 -262.354568)
		(width 0.088646)
		(layer "In2.Cu")
		(net "M_F_CPU1_SA_CB<4>")
	)
	(arc
		(start 135.997442 -261.734554)
		(mid 135.860397 -261.871514)
		(end 135.810244 -262.058658)
		(width 0.088646)
		(layer "In2.Cu")
		(net "M_F_CPU1_SA_CB<4>")
	)
	(arc
		(start 137.877296 -261.7343)
		(mid 137.594594 -261.810076)
		(end 137.311892 -261.7343)
		(width 0.088646)
		(layer "In2.Cu")
		(net "M_F_CPU1_SA_CB<4>")
	)
	(arc
		(start 138.817096 -261.7343)
		(mid 138.534394 -261.810076)
		(end 138.251692 -261.7343)
		(width 0.088646)
		(layer "In2.Cu")
		(net "M_F_CPU1_SA_CB<4>")
	)
	(arc
		(start 135.432292 -262.383016)
		(mid 135.245094 -262.433159)
		(end 135.057896 -262.383016)
		(width 0.088646)
		(layer "In2.Cu")
		(net "M_F_CPU1_SA_CB<4>")
	)
	(arc
		(start 135.043164 -262.37438)
		(mid 134.845779 -262.351832)
		(end 134.650226 -262.386826)
		(width 0.088646)
		(layer "In2.Cu")
		(net "M_F_CPU1_SA_CB<4>")
	)
	(arc
		(start 136.937496 -261.7343)
		(mid 136.654794 -261.810076)
		(end 136.372092 -261.7343)
		(width 0.088646)
		(layer "In2.Cu")
		(net "M_F_CPU1_SA_CB<4>")
	)
	(arc
		(start 134.650226 -262.386826)
		(mid 134.435027 -262.439858)
		(end 134.214108 -262.457692)
		(width 0.088646)
		(layer "In2.Cu")
		(net "M_F_CPU1_SA_CB<4>")
	)
	(arc
		(start 135.810244 -262.058658)
		(mid 135.785596 -262.150487)
		(end 135.718296 -262.217662)
		(width 0.088646)
		(layer "In2.Cu")
		(net "M_F_CPU1_SA_CB<4>")
	)
	(arc
		(start 138.251692 -261.7343)
		(mid 138.064494 -261.684157)
		(end 137.877296 -261.7343)
		(width 0.088646)
		(layer "In2.Cu")
		(net "M_F_CPU1_SA_CB<4>")
	)
	(arc
		(start 136.372092 -261.7343)
		(mid 136.184894 -261.684123)
		(end 135.997696 -261.7343)
		(width 0.088646)
		(layer "In2.Cu")
		(net "M_F_CPU1_SA_CB<4>")
	)
	(arc
		(start 139.756896 -261.7343)
		(mid 139.474194 -261.810076)
		(end 139.191492 -261.7343)
		(width 0.088646)
		(layer "In2.Cu")
		(net "M_F_CPU1_SA_CB<4>")
	)
	(segment
		(start 182.455058 -276.803866)
		(end 183.136286 -276.803866)
		(width 0.20066)
		(layer "F.Cu")
		(net "M_F_CPU1_SA_CB<3>")
	)
	(segment
		(start 135.245094 -263.150604)
		(end 135.245094 -263.686544)
		(width 0.20066)
		(layer "F.Cu")
		(net "M_F_CPU1_SA_CB<3>")
	)
	(segment
		(start 180.131212 -276.798786)
		(end 180.423058 -276.798786)
		(width 0.20066)
		(layer "F.Cu")
		(net "M_F_CPU1_SA_CB<3>")
	)
	(segment
		(start 178.000914 -276.366732)
		(end 179.699158 -276.366732)
		(width 0.20066)
		(layer "F.Cu")
		(net "M_F_CPU1_SA_CB<3>")
	)
	(segment
		(start 183.340248 -276.348952)
		(end 183.574436 -276.114764)
		(width 0.20066)
		(layer "F.Cu")
		(net "M_F_CPU1_SA_CB<3>")
	)
	(segment
		(start 182.442866 -276.791674)
		(end 182.455058 -276.803866)
		(width 0.1016)
		(layer "F.Cu")
		(net "M_F_CPU1_SA_CB<3>")
	)
	(segment
		(start 183.340248 -276.599904)
		(end 183.340248 -276.348952)
		(width 0.20066)
		(layer "F.Cu")
		(net "M_F_CPU1_SA_CB<3>")
	)
	(segment
		(start 176.896014 -276.366732)
		(end 178.000914 -276.366732)
		(width 0.20066)
		(layer "F.Cu")
		(net "M_F_CPU1_SA_CB<3>")
	)
	(segment
		(start 180.434996 -276.791674)
		(end 182.442866 -276.791674)
		(width 0.1016)
		(layer "F.Cu")
		(net "M_F_CPU1_SA_CB<3>")
	)
	(segment
		(start 180.423058 -276.798786)
		(end 180.427884 -276.798786)
		(width 0.101854)
		(layer "F.Cu")
		(net "M_F_CPU1_SA_CB<3>")
	)
	(segment
		(start 180.427884 -276.798786)
		(end 180.434996 -276.791674)
		(width 0.1016)
		(layer "F.Cu")
		(net "M_F_CPU1_SA_CB<3>")
	)
	(segment
		(start 183.958484 -276.114764)
		(end 184.210452 -276.366732)
		(width 0.20066)
		(layer "F.Cu")
		(net "M_F_CPU1_SA_CB<3>")
	)
	(segment
		(start 184.210452 -276.366732)
		(end 185.544714 -276.366732)
		(width 0.20066)
		(layer "F.Cu")
		(net "M_F_CPU1_SA_CB<3>")
	)
	(segment
		(start 179.699158 -276.366732)
		(end 180.131212 -276.798786)
		(width 0.20066)
		(layer "F.Cu")
		(net "M_F_CPU1_SA_CB<3>")
	)
	(segment
		(start 183.574436 -276.114764)
		(end 183.958484 -276.114764)
		(width 0.20066)
		(layer "F.Cu")
		(net "M_F_CPU1_SA_CB<3>")
	)
	(segment
		(start 183.136286 -276.803866)
		(end 183.340248 -276.599904)
		(width 0.20066)
		(layer "F.Cu")
		(net "M_F_CPU1_SA_CB<3>")
	)
	(segment
		(start 173.337982 -275.941282)
		(end 172.496734 -275.941282)
		(width 0.18288)
		(layer "In2.Cu")
		(net "M_F_CPU1_SA_CB<3>")
	)
	(segment
		(start 162.08883 -276.771862)
		(end 161.064956 -275.747988)
		(width 0.18288)
		(layer "In2.Cu")
		(net "M_F_CPU1_SA_CB<3>")
	)
	(segment
		(start 168.61155 -276.102826)
		(end 167.893746 -276.82063)
		(width 0.18288)
		(layer "In2.Cu")
		(net "M_F_CPU1_SA_CB<3>")
	)
	(segment
		(start 140.290296 -264.061702)
		(end 139.944348 -264.061702)
		(width 0.088646)
		(layer "In2.Cu")
		(net "M_F_CPU1_SA_CB<3>")
	)
	(segment
		(start 176.382934 -275.853652)
		(end 174.884334 -275.853652)
		(width 0.18288)
		(layer "In2.Cu")
		(net "M_F_CPU1_SA_CB<3>")
	)
	(segment
		(start 169.611802 -275.99005)
		(end 169.499026 -276.102826)
		(width 0.18288)
		(layer "In2.Cu")
		(net "M_F_CPU1_SA_CB<3>")
	)
	(segment
		(start 140.900404 -263.842246)
		(end 140.509752 -263.842246)
		(width 0.088646)
		(layer "In2.Cu")
		(net "M_F_CPU1_SA_CB<3>")
	)
	(segment
		(start 173.708314 -276.534372)
		(end 173.498002 -276.32406)
		(width 0.18288)
		(layer "In2.Cu")
		(net "M_F_CPU1_SA_CB<3>")
	)
	(segment
		(start 154.729688 -271.53489)
		(end 149.988016 -266.793218)
		(width 0.18288)
		(layer "In2.Cu")
		(net "M_F_CPU1_SA_CB<3>")
	)
	(segment
		(start 143.781526 -263.842246)
		(end 140.900404 -263.842246)
		(width 0.18288)
		(layer "In2.Cu")
		(net "M_F_CPU1_SA_CB<3>")
	)
	(segment
		(start 161.064956 -275.747988)
		(end 161.064956 -275.463508)
		(width 0.18288)
		(layer "In2.Cu")
		(net "M_F_CPU1_SA_CB<3>")
	)
	(segment
		(start 172.394626 -275.839174)
		(end 172.121322 -275.839174)
		(width 0.18288)
		(layer "In2.Cu")
		(net "M_F_CPU1_SA_CB<3>")
	)
	(segment
		(start 157.032452 -274.47621)
		(end 156.299916 -274.47621)
		(width 0.18288)
		(layer "In2.Cu")
		(net "M_F_CPU1_SA_CB<3>")
	)
	(segment
		(start 167.893746 -276.82063)
		(end 164.28593 -276.82063)
		(width 0.18288)
		(layer "In2.Cu")
		(net "M_F_CPU1_SA_CB<3>")
	)
	(segment
		(start 174.203614 -276.534372)
		(end 173.708314 -276.534372)
		(width 0.18288)
		(layer "In2.Cu")
		(net "M_F_CPU1_SA_CB<3>")
	)
	(segment
		(start 157.653482 -275.09724)
		(end 157.032452 -274.47621)
		(width 0.18288)
		(layer "In2.Cu")
		(net "M_F_CPU1_SA_CB<3>")
	)
	(segment
		(start 173.498002 -276.32406)
		(end 173.498002 -276.101302)
		(width 0.18288)
		(layer "In2.Cu")
		(net "M_F_CPU1_SA_CB<3>")
	)
	(segment
		(start 135.997696 -264.010902)
		(end 135.605012 -263.783064)
		(width 0.088646)
		(layer "In2.Cu")
		(net "M_F_CPU1_SA_CB<3>")
	)
	(segment
		(start 173.498002 -276.101302)
		(end 173.337982 -275.941282)
		(width 0.18288)
		(layer "In2.Cu")
		(net "M_F_CPU1_SA_CB<3>")
	)
	(segment
		(start 156.299916 -274.47621)
		(end 155.699206 -273.8755)
		(width 0.18288)
		(layer "In2.Cu")
		(net "M_F_CPU1_SA_CB<3>")
	)
	(segment
		(start 172.121322 -275.839174)
		(end 171.970446 -275.99005)
		(width 0.18288)
		(layer "In2.Cu")
		(net "M_F_CPU1_SA_CB<3>")
	)
	(segment
		(start 176.896014 -276.366732)
		(end 176.382934 -275.853652)
		(width 0.18288)
		(layer "In2.Cu")
		(net "M_F_CPU1_SA_CB<3>")
	)
	(segment
		(start 164.237162 -276.771862)
		(end 162.08883 -276.771862)
		(width 0.18288)
		(layer "In2.Cu")
		(net "M_F_CPU1_SA_CB<3>")
	)
	(segment
		(start 161.064956 -275.463508)
		(end 160.698688 -275.09724)
		(width 0.18288)
		(layer "In2.Cu")
		(net "M_F_CPU1_SA_CB<3>")
	)
	(segment
		(start 164.28593 -276.82063)
		(end 164.237162 -276.771862)
		(width 0.18288)
		(layer "In2.Cu")
		(net "M_F_CPU1_SA_CB<3>")
	)
	(segment
		(start 169.499026 -276.102826)
		(end 168.61155 -276.102826)
		(width 0.18288)
		(layer "In2.Cu")
		(net "M_F_CPU1_SA_CB<3>")
	)
	(segment
		(start 147.209256 -266.793218)
		(end 144.59585 -264.179812)
		(width 0.18288)
		(layer "In2.Cu")
		(net "M_F_CPU1_SA_CB<3>")
	)
	(segment
		(start 144.59585 -264.179812)
		(end 143.781526 -263.842246)
		(width 0.18288)
		(layer "In2.Cu")
		(net "M_F_CPU1_SA_CB<3>")
	)
	(segment
		(start 140.509752 -263.842246)
		(end 140.290296 -264.061702)
		(width 0.088646)
		(layer "In2.Cu")
		(net "M_F_CPU1_SA_CB<3>")
	)
	(segment
		(start 160.698688 -275.09724)
		(end 157.653482 -275.09724)
		(width 0.18288)
		(layer "In2.Cu")
		(net "M_F_CPU1_SA_CB<3>")
	)
	(segment
		(start 172.496734 -275.941282)
		(end 172.394626 -275.839174)
		(width 0.18288)
		(layer "In2.Cu")
		(net "M_F_CPU1_SA_CB<3>")
	)
	(segment
		(start 171.970446 -275.99005)
		(end 169.611802 -275.99005)
		(width 0.18288)
		(layer "In2.Cu")
		(net "M_F_CPU1_SA_CB<3>")
	)
	(segment
		(start 149.988016 -266.793218)
		(end 147.209256 -266.793218)
		(width 0.18288)
		(layer "In2.Cu")
		(net "M_F_CPU1_SA_CB<3>")
	)
	(segment
		(start 174.884334 -275.853652)
		(end 174.203614 -276.534372)
		(width 0.18288)
		(layer "In2.Cu")
		(net "M_F_CPU1_SA_CB<3>")
	)
	(segment
		(start 155.699206 -273.8755)
		(end 154.729688 -271.53489)
		(width 0.18288)
		(layer "In2.Cu")
		(net "M_F_CPU1_SA_CB<3>")
	)
	(arc
		(start 136.372092 -264.010902)
		(mid 136.184894 -264.061045)
		(end 135.997696 -264.010902)
		(width 0.088646)
		(layer "In2.Cu")
		(net "M_F_CPU1_SA_CB<3>")
	)
	(arc
		(start 138.251692 -264.010902)
		(mid 138.064494 -264.061045)
		(end 137.877296 -264.010902)
		(width 0.088646)
		(layer "In2.Cu")
		(net "M_F_CPU1_SA_CB<3>")
	)
	(arc
		(start 139.191492 -264.010902)
		(mid 139.004294 -264.061045)
		(end 138.817096 -264.010902)
		(width 0.088646)
		(layer "In2.Cu")
		(net "M_F_CPU1_SA_CB<3>")
	)
	(arc
		(start 136.937496 -264.010902)
		(mid 136.654794 -263.935126)
		(end 136.372092 -264.010902)
		(width 0.088646)
		(layer "In2.Cu")
		(net "M_F_CPU1_SA_CB<3>")
	)
	(arc
		(start 137.877296 -264.010902)
		(mid 137.594594 -263.935126)
		(end 137.311892 -264.010902)
		(width 0.088646)
		(layer "In2.Cu")
		(net "M_F_CPU1_SA_CB<3>")
	)
	(arc
		(start 137.311892 -264.010902)
		(mid 137.124694 -264.061045)
		(end 136.937496 -264.010902)
		(width 0.088646)
		(layer "In2.Cu")
		(net "M_F_CPU1_SA_CB<3>")
	)
	(arc
		(start 138.817096 -264.010902)
		(mid 138.534394 -263.935126)
		(end 138.251692 -264.010902)
		(width 0.088646)
		(layer "In2.Cu")
		(net "M_F_CPU1_SA_CB<3>")
	)
	(arc
		(start 139.756896 -264.010902)
		(mid 139.474194 -263.935126)
		(end 139.191492 -264.010902)
		(width 0.088646)
		(layer "In2.Cu")
		(net "M_F_CPU1_SA_CB<3>")
	)
	(arc
		(start 139.944348 -264.061702)
		(mid 139.847278 -264.048645)
		(end 139.756896 -264.010902)
		(width 0.088646)
		(layer "In2.Cu")
		(net "M_F_CPU1_SA_CB<3>")
	)
	(arc
		(start 135.605012 -263.783064)
		(mid 135.431431 -263.711015)
		(end 135.245094 -263.686544)
		(width 0.088646)
		(layer "In2.Cu")
		(net "M_F_CPU1_SA_CB<3>")
	)
	(segment
		(start 180.423058 -278.498808)
		(end 180.427884 -278.498808)
		(width 0.101854)
		(layer "F.Cu")
		(net "M_F_CPU1_SA_CB<2>")
	)
	(segment
		(start 134.775448 -263.96442)
		(end 134.775448 -264.500106)
		(width 0.20066)
		(layer "F.Cu")
		(net "M_F_CPU1_SA_CB<2>")
	)
	(segment
		(start 180.131212 -278.498808)
		(end 180.423058 -278.498808)
		(width 0.20066)
		(layer "F.Cu")
		(net "M_F_CPU1_SA_CB<2>")
	)
	(segment
		(start 178.000914 -278.066754)
		(end 179.699158 -278.066754)
		(width 0.20066)
		(layer "F.Cu")
		(net "M_F_CPU1_SA_CB<2>")
	)
	(segment
		(start 183.340248 -278.048974)
		(end 183.574436 -277.814786)
		(width 0.20066)
		(layer "F.Cu")
		(net "M_F_CPU1_SA_CB<2>")
	)
	(segment
		(start 183.340248 -278.299926)
		(end 183.340248 -278.048974)
		(width 0.20066)
		(layer "F.Cu")
		(net "M_F_CPU1_SA_CB<2>")
	)
	(segment
		(start 176.896014 -278.066754)
		(end 178.000914 -278.066754)
		(width 0.20066)
		(layer "F.Cu")
		(net "M_F_CPU1_SA_CB<2>")
	)
	(segment
		(start 180.434996 -278.491696)
		(end 182.442866 -278.491696)
		(width 0.1016)
		(layer "F.Cu")
		(net "M_F_CPU1_SA_CB<2>")
	)
	(segment
		(start 184.210452 -278.066754)
		(end 185.544714 -278.066754)
		(width 0.20066)
		(layer "F.Cu")
		(net "M_F_CPU1_SA_CB<2>")
	)
	(segment
		(start 182.455058 -278.503888)
		(end 183.136286 -278.503888)
		(width 0.20066)
		(layer "F.Cu")
		(net "M_F_CPU1_SA_CB<2>")
	)
	(segment
		(start 183.958484 -277.814786)
		(end 184.210452 -278.066754)
		(width 0.20066)
		(layer "F.Cu")
		(net "M_F_CPU1_SA_CB<2>")
	)
	(segment
		(start 179.699158 -278.066754)
		(end 180.131212 -278.498808)
		(width 0.20066)
		(layer "F.Cu")
		(net "M_F_CPU1_SA_CB<2>")
	)
	(segment
		(start 183.136286 -278.503888)
		(end 183.340248 -278.299926)
		(width 0.20066)
		(layer "F.Cu")
		(net "M_F_CPU1_SA_CB<2>")
	)
	(segment
		(start 182.442866 -278.491696)
		(end 182.455058 -278.503888)
		(width 0.1016)
		(layer "F.Cu")
		(net "M_F_CPU1_SA_CB<2>")
	)
	(segment
		(start 183.574436 -277.814786)
		(end 183.958484 -277.814786)
		(width 0.20066)
		(layer "F.Cu")
		(net "M_F_CPU1_SA_CB<2>")
	)
	(segment
		(start 134.775448 -264.500106)
		(end 134.775194 -264.50036)
		(width 0.20066)
		(layer "F.Cu")
		(net "M_F_CPU1_SA_CB<2>")
	)
	(segment
		(start 180.427884 -278.498808)
		(end 180.434996 -278.491696)
		(width 0.1016)
		(layer "F.Cu")
		(net "M_F_CPU1_SA_CB<2>")
	)
	(segment
		(start 174.979838 -277.499826)
		(end 174.83836 -277.641304)
		(width 0.18288)
		(layer "In2.Cu")
		(net "M_F_CPU1_SA_CB<2>")
	)
	(segment
		(start 160.82518 -277.630636)
		(end 160.82518 -277.516844)
		(width 0.18288)
		(layer "In2.Cu")
		(net "M_F_CPU1_SA_CB<2>")
	)
	(segment
		(start 138.347196 -264.824718)
		(end 138.332464 -264.816082)
		(width 0.088646)
		(layer "In2.Cu")
		(net "M_F_CPU1_SA_CB<2>")
	)
	(segment
		(start 140.900404 -264.622026)
		(end 140.290296 -264.622026)
		(width 0.088646)
		(layer "In2.Cu")
		(net "M_F_CPU1_SA_CB<2>")
	)
	(segment
		(start 161.447226 -278.252682)
		(end 160.82518 -277.630636)
		(width 0.18288)
		(layer "In2.Cu")
		(net "M_F_CPU1_SA_CB<2>")
	)
	(segment
		(start 153.86812 -272.110454)
		(end 149.573234 -267.815568)
		(width 0.18288)
		(layer "In2.Cu")
		(net "M_F_CPU1_SA_CB<2>")
	)
	(segment
		(start 139.286996 -264.824718)
		(end 139.272264 -264.816082)
		(width 0.088646)
		(layer "In2.Cu")
		(net "M_F_CPU1_SA_CB<2>")
	)
	(segment
		(start 140.290296 -264.622026)
		(end 140.163804 -264.748518)
		(width 0.088646)
		(layer "In2.Cu")
		(net "M_F_CPU1_SA_CB<2>")
	)
	(segment
		(start 160.114488 -276.806152)
		(end 157.192218 -276.806152)
		(width 0.18288)
		(layer "In2.Cu")
		(net "M_F_CPU1_SA_CB<2>")
	)
	(segment
		(start 157.192218 -276.806152)
		(end 154.838146 -274.45208)
		(width 0.18288)
		(layer "In2.Cu")
		(net "M_F_CPU1_SA_CB<2>")
	)
	(segment
		(start 172.714158 -277.641304)
		(end 172.712634 -277.642828)
		(width 0.18288)
		(layer "In2.Cu")
		(net "M_F_CPU1_SA_CB<2>")
	)
	(segment
		(start 160.82518 -277.516844)
		(end 160.114488 -276.806152)
		(width 0.18288)
		(layer "In2.Cu")
		(net "M_F_CPU1_SA_CB<2>")
	)
	(segment
		(start 144.411954 -264.983468)
		(end 143.538956 -264.622026)
		(width 0.18288)
		(layer "In2.Cu")
		(net "M_F_CPU1_SA_CB<2>")
	)
	(segment
		(start 171.556426 -277.703026)
		(end 169.62247 -277.703026)
		(width 0.18288)
		(layer "In2.Cu")
		(net "M_F_CPU1_SA_CB<2>")
	)
	(segment
		(start 172.712634 -277.642828)
		(end 172.267626 -277.642828)
		(width 0.18288)
		(layer "In2.Cu")
		(net "M_F_CPU1_SA_CB<2>")
	)
	(segment
		(start 137.407396 -264.824718)
		(end 137.392664 -264.816082)
		(width 0.088646)
		(layer "In2.Cu")
		(net "M_F_CPU1_SA_CB<2>")
	)
	(segment
		(start 140.163804 -264.748518)
		(end 139.944856 -264.748518)
		(width 0.088646)
		(layer "In2.Cu")
		(net "M_F_CPU1_SA_CB<2>")
	)
	(segment
		(start 169.62247 -277.703026)
		(end 167.624252 -278.530812)
		(width 0.18288)
		(layer "In2.Cu")
		(net "M_F_CPU1_SA_CB<2>")
	)
	(segment
		(start 162.084004 -278.473154)
		(end 161.447226 -278.252682)
		(width 0.18288)
		(layer "In2.Cu")
		(net "M_F_CPU1_SA_CB<2>")
	)
	(segment
		(start 167.624252 -278.530812)
		(end 167.312848 -278.530812)
		(width 0.18288)
		(layer "In2.Cu")
		(net "M_F_CPU1_SA_CB<2>")
	)
	(segment
		(start 147.244054 -267.815568)
		(end 144.411954 -264.983468)
		(width 0.18288)
		(layer "In2.Cu")
		(net "M_F_CPU1_SA_CB<2>")
	)
	(segment
		(start 164.742368 -278.712168)
		(end 164.503354 -278.473154)
		(width 0.18288)
		(layer "In2.Cu")
		(net "M_F_CPU1_SA_CB<2>")
	)
	(segment
		(start 143.538956 -264.622026)
		(end 140.900404 -264.622026)
		(width 0.18288)
		(layer "In2.Cu")
		(net "M_F_CPU1_SA_CB<2>")
	)
	(segment
		(start 176.329086 -277.499826)
		(end 174.979838 -277.499826)
		(width 0.18288)
		(layer "In2.Cu")
		(net "M_F_CPU1_SA_CB<2>")
	)
	(segment
		(start 167.312848 -278.530812)
		(end 167.195246 -278.41321)
		(width 0.18288)
		(layer "In2.Cu")
		(net "M_F_CPU1_SA_CB<2>")
	)
	(segment
		(start 136.467596 -264.824718)
		(end 136.452864 -264.816082)
		(width 0.088646)
		(layer "In2.Cu")
		(net "M_F_CPU1_SA_CB<2>")
	)
	(segment
		(start 167.195246 -278.41321)
		(end 165.56482 -278.41321)
		(width 0.18288)
		(layer "In2.Cu")
		(net "M_F_CPU1_SA_CB<2>")
	)
	(segment
		(start 165.56482 -278.41321)
		(end 165.265862 -278.712168)
		(width 0.18288)
		(layer "In2.Cu")
		(net "M_F_CPU1_SA_CB<2>")
	)
	(segment
		(start 172.267626 -277.642828)
		(end 171.556426 -277.703026)
		(width 0.18288)
		(layer "In2.Cu")
		(net "M_F_CPU1_SA_CB<2>")
	)
	(segment
		(start 149.573234 -267.815568)
		(end 147.244054 -267.815568)
		(width 0.18288)
		(layer "In2.Cu")
		(net "M_F_CPU1_SA_CB<2>")
	)
	(segment
		(start 176.896014 -278.066754)
		(end 176.329086 -277.499826)
		(width 0.18288)
		(layer "In2.Cu")
		(net "M_F_CPU1_SA_CB<2>")
	)
	(segment
		(start 154.838146 -274.45208)
		(end 153.86812 -272.110454)
		(width 0.18288)
		(layer "In2.Cu")
		(net "M_F_CPU1_SA_CB<2>")
	)
	(segment
		(start 165.265862 -278.712168)
		(end 164.742368 -278.712168)
		(width 0.18288)
		(layer "In2.Cu")
		(net "M_F_CPU1_SA_CB<2>")
	)
	(segment
		(start 174.83836 -277.641304)
		(end 172.714158 -277.641304)
		(width 0.18288)
		(layer "In2.Cu")
		(net "M_F_CPU1_SA_CB<2>")
	)
	(segment
		(start 164.503354 -278.473154)
		(end 162.084004 -278.473154)
		(width 0.18288)
		(layer "In2.Cu")
		(net "M_F_CPU1_SA_CB<2>")
	)
	(arc
		(start 137.392664 -264.816082)
		(mid 137.116189 -264.748762)
		(end 136.841992 -264.824718)
		(width 0.088646)
		(layer "In2.Cu")
		(net "M_F_CPU1_SA_CB<2>")
	)
	(arc
		(start 136.841992 -264.824718)
		(mid 136.654794 -264.874861)
		(end 136.467596 -264.824718)
		(width 0.088646)
		(layer "In2.Cu")
		(net "M_F_CPU1_SA_CB<2>")
	)
	(arc
		(start 135.527796 -264.824718)
		(mid 135.161099 -264.640254)
		(end 134.775194 -264.50036)
		(width 0.088646)
		(layer "In2.Cu")
		(net "M_F_CPU1_SA_CB<2>")
	)
	(arc
		(start 139.272264 -264.816082)
		(mid 138.995789 -264.748762)
		(end 138.721592 -264.824718)
		(width 0.088646)
		(layer "In2.Cu")
		(net "M_F_CPU1_SA_CB<2>")
	)
	(arc
		(start 138.332464 -264.816082)
		(mid 138.055989 -264.748762)
		(end 137.781792 -264.824718)
		(width 0.088646)
		(layer "In2.Cu")
		(net "M_F_CPU1_SA_CB<2>")
	)
	(arc
		(start 138.721592 -264.824718)
		(mid 138.534394 -264.874861)
		(end 138.347196 -264.824718)
		(width 0.088646)
		(layer "In2.Cu")
		(net "M_F_CPU1_SA_CB<2>")
	)
	(arc
		(start 139.661392 -264.824718)
		(mid 139.474194 -264.874861)
		(end 139.286996 -264.824718)
		(width 0.088646)
		(layer "In2.Cu")
		(net "M_F_CPU1_SA_CB<2>")
	)
	(arc
		(start 137.781792 -264.824718)
		(mid 137.594594 -264.874861)
		(end 137.407396 -264.824718)
		(width 0.088646)
		(layer "In2.Cu")
		(net "M_F_CPU1_SA_CB<2>")
	)
	(arc
		(start 136.452864 -264.816082)
		(mid 136.176389 -264.748762)
		(end 135.902192 -264.824718)
		(width 0.088646)
		(layer "In2.Cu")
		(net "M_F_CPU1_SA_CB<2>")
	)
	(arc
		(start 135.902192 -264.824718)
		(mid 135.714994 -264.874861)
		(end 135.527796 -264.824718)
		(width 0.088646)
		(layer "In2.Cu")
		(net "M_F_CPU1_SA_CB<2>")
	)
	(arc
		(start 139.944856 -264.748518)
		(mid 139.798091 -264.767898)
		(end 139.661392 -264.824718)
		(width 0.088646)
		(layer "In2.Cu")
		(net "M_F_CPU1_SA_CB<2>")
	)
	(segment
		(start 176.451514 -276.791674)
		(end 176.333404 -276.909784)
		(width 0.20066)
		(layer "F.Cu")
		(net "M_F_CPU1_SA_CB<1>")
	)
	(segment
		(start 133.365494 -263.150604)
		(end 133.365748 -263.150858)
		(width 0.20066)
		(layer "F.Cu")
		(net "M_F_CPU1_SA_CB<1>")
	)
	(segment
		(start 176.816258 -276.791674)
		(end 176.796192 -276.791674)
		(width 0.101854)
		(layer "F.Cu")
		(net "M_F_CPU1_SA_CB<1>")
	)
	(segment
		(start 179.004976 -276.791674)
		(end 176.816258 -276.791674)
		(width 0.1016)
		(layer "F.Cu")
		(net "M_F_CPU1_SA_CB<1>")
	)
	(segment
		(start 176.333404 -277.277322)
		(end 176.145444 -277.465282)
		(width 0.20066)
		(layer "F.Cu")
		(net "M_F_CPU1_SA_CB<1>")
	)
	(segment
		(start 175.67021 -277.465282)
		(end 175.421544 -277.216616)
		(width 0.20066)
		(layer "F.Cu")
		(net "M_F_CPU1_SA_CB<1>")
	)
	(segment
		(start 181.444646 -277.216616)
		(end 181.444392 -277.21687)
		(width 0.20066)
		(layer "F.Cu")
		(net "M_F_CPU1_SA_CB<1>")
	)
	(segment
		(start 179.421282 -276.785324)
		(end 179.011326 -276.785324)
		(width 0.20066)
		(layer "F.Cu")
		(net "M_F_CPU1_SA_CB<1>")
	)
	(segment
		(start 176.333404 -276.909784)
		(end 176.333404 -277.277322)
		(width 0.20066)
		(layer "F.Cu")
		(net "M_F_CPU1_SA_CB<1>")
	)
	(segment
		(start 179.011326 -276.785324)
		(end 179.004976 -276.791674)
		(width 0.1016)
		(layer "F.Cu")
		(net "M_F_CPU1_SA_CB<1>")
	)
	(segment
		(start 176.145444 -277.465282)
		(end 175.67021 -277.465282)
		(width 0.20066)
		(layer "F.Cu")
		(net "M_F_CPU1_SA_CB<1>")
	)
	(segment
		(start 179.852828 -277.21687)
		(end 179.421282 -276.785324)
		(width 0.20066)
		(layer "F.Cu")
		(net "M_F_CPU1_SA_CB<1>")
	)
	(segment
		(start 173.900846 -277.216616)
		(end 172.795946 -277.216616)
		(width 0.20066)
		(layer "F.Cu")
		(net "M_F_CPU1_SA_CB<1>")
	)
	(segment
		(start 176.796192 -276.791674)
		(end 176.451514 -276.791674)
		(width 0.20066)
		(layer "F.Cu")
		(net "M_F_CPU1_SA_CB<1>")
	)
	(segment
		(start 175.421544 -277.216616)
		(end 173.900846 -277.216616)
		(width 0.20066)
		(layer "F.Cu")
		(net "M_F_CPU1_SA_CB<1>")
	)
	(segment
		(start 133.365748 -263.150858)
		(end 133.365748 -263.686544)
		(width 0.20066)
		(layer "F.Cu")
		(net "M_F_CPU1_SA_CB<1>")
	)
	(segment
		(start 181.444392 -277.21687)
		(end 179.852828 -277.21687)
		(width 0.20066)
		(layer "F.Cu")
		(net "M_F_CPU1_SA_CB<1>")
	)
	(segment
		(start 165.253162 -277.408894)
		(end 164.83965 -277.408894)
		(width 0.18288)
		(layer "In2.Cu")
		(net "M_F_CPU1_SA_CB<1>")
	)
	(segment
		(start 157.237938 -275.940012)
		(end 157.044898 -275.746972)
		(width 0.18288)
		(layer "In2.Cu")
		(net "M_F_CPU1_SA_CB<1>")
	)
	(segment
		(start 165.749478 -277.90521)
		(end 165.253162 -277.408894)
		(width 0.18288)
		(layer "In2.Cu")
		(net "M_F_CPU1_SA_CB<1>")
	)
	(segment
		(start 161.616898 -277.677626)
		(end 161.392362 -277.45309)
		(width 0.18288)
		(layer "In2.Cu")
		(net "M_F_CPU1_SA_CB<1>")
	)
	(segment
		(start 172.47616 -276.89683)
		(end 172.47616 -276.743414)
		(width 0.18288)
		(layer "In2.Cu")
		(net "M_F_CPU1_SA_CB<1>")
	)
	(segment
		(start 167.284654 -277.601426)
		(end 166.98087 -277.90521)
		(width 0.18288)
		(layer "In2.Cu")
		(net "M_F_CPU1_SA_CB<1>")
	)
	(segment
		(start 161.392362 -277.45309)
		(end 160.926526 -276.328378)
		(width 0.18288)
		(layer "In2.Cu")
		(net "M_F_CPU1_SA_CB<1>")
	)
	(segment
		(start 159.913066 -275.762212)
		(end 159.377126 -276.298152)
		(width 0.18288)
		(layer "In2.Cu")
		(net "M_F_CPU1_SA_CB<1>")
	)
	(segment
		(start 163.368228 -277.279862)
		(end 162.601148 -277.279862)
		(width 0.18288)
		(layer "In2.Cu")
		(net "M_F_CPU1_SA_CB<1>")
	)
	(segment
		(start 168.632632 -277.423626)
		(end 168.454832 -277.601426)
		(width 0.18288)
		(layer "In2.Cu")
		(net "M_F_CPU1_SA_CB<1>")
	)
	(segment
		(start 172.306996 -276.57425)
		(end 171.540424 -276.57425)
		(width 0.18288)
		(layer "In2.Cu")
		(net "M_F_CPU1_SA_CB<1>")
	)
	(segment
		(start 172.795946 -277.216616)
		(end 172.47616 -276.89683)
		(width 0.18288)
		(layer "In2.Cu")
		(net "M_F_CPU1_SA_CB<1>")
	)
	(segment
		(start 170.919648 -277.195026)
		(end 169.960544 -277.195026)
		(width 0.18288)
		(layer "In2.Cu")
		(net "M_F_CPU1_SA_CB<1>")
	)
	(segment
		(start 147.234656 -267.307568)
		(end 144.497298 -264.57021)
		(width 0.18288)
		(layer "In2.Cu")
		(net "M_F_CPU1_SA_CB<1>")
	)
	(segment
		(start 135.558022 -264.083292)
		(end 134.323328 -264.083292)
		(width 0.088646)
		(layer "In2.Cu")
		(net "M_F_CPU1_SA_CB<1>")
	)
	(segment
		(start 160.36036 -275.762212)
		(end 159.913066 -275.762212)
		(width 0.18288)
		(layer "In2.Cu")
		(net "M_F_CPU1_SA_CB<1>")
	)
	(segment
		(start 171.540424 -276.57425)
		(end 170.919648 -277.195026)
		(width 0.18288)
		(layer "In2.Cu")
		(net "M_F_CPU1_SA_CB<1>")
	)
	(segment
		(start 156.089096 -274.98421)
		(end 155.268676 -274.16379)
		(width 0.18288)
		(layer "In2.Cu")
		(net "M_F_CPU1_SA_CB<1>")
	)
	(segment
		(start 157.044898 -275.746972)
		(end 157.044898 -275.207476)
		(width 0.18288)
		(layer "In2.Cu")
		(net "M_F_CPU1_SA_CB<1>")
	)
	(segment
		(start 159.377126 -276.298152)
		(end 158.309818 -276.298152)
		(width 0.18288)
		(layer "In2.Cu")
		(net "M_F_CPU1_SA_CB<1>")
	)
	(segment
		(start 172.47616 -276.743414)
		(end 172.306996 -276.57425)
		(width 0.18288)
		(layer "In2.Cu")
		(net "M_F_CPU1_SA_CB<1>")
	)
	(segment
		(start 166.98087 -277.90521)
		(end 165.749478 -277.90521)
		(width 0.18288)
		(layer "In2.Cu")
		(net "M_F_CPU1_SA_CB<1>")
	)
	(segment
		(start 162.203384 -277.677626)
		(end 161.616898 -277.677626)
		(width 0.18288)
		(layer "In2.Cu")
		(net "M_F_CPU1_SA_CB<1>")
	)
	(segment
		(start 168.632632 -276.934676)
		(end 168.632632 -277.423626)
		(width 0.18288)
		(layer "In2.Cu")
		(net "M_F_CPU1_SA_CB<1>")
	)
	(segment
		(start 135.902192 -264.176002)
		(end 135.902446 -264.175748)
		(width 0.088646)
		(layer "In2.Cu")
		(net "M_F_CPU1_SA_CB<1>")
	)
	(segment
		(start 160.926526 -276.328378)
		(end 160.36036 -275.762212)
		(width 0.18288)
		(layer "In2.Cu")
		(net "M_F_CPU1_SA_CB<1>")
	)
	(segment
		(start 168.945306 -276.622002)
		(end 168.632632 -276.934676)
		(width 0.18288)
		(layer "In2.Cu")
		(net "M_F_CPU1_SA_CB<1>")
	)
	(segment
		(start 162.601148 -277.279862)
		(end 162.203384 -277.677626)
		(width 0.18288)
		(layer "In2.Cu")
		(net "M_F_CPU1_SA_CB<1>")
	)
	(segment
		(start 164.83965 -277.408894)
		(end 164.30498 -277.943564)
		(width 0.18288)
		(layer "In2.Cu")
		(net "M_F_CPU1_SA_CB<1>")
	)
	(segment
		(start 157.044898 -275.207476)
		(end 156.821632 -274.98421)
		(width 0.18288)
		(layer "In2.Cu")
		(net "M_F_CPU1_SA_CB<1>")
	)
	(segment
		(start 144.497298 -264.57021)
		(end 143.72971 -264.251948)
		(width 0.18288)
		(layer "In2.Cu")
		(net "M_F_CPU1_SA_CB<1>")
	)
	(segment
		(start 169.38752 -276.622002)
		(end 168.945306 -276.622002)
		(width 0.18288)
		(layer "In2.Cu")
		(net "M_F_CPU1_SA_CB<1>")
	)
	(segment
		(start 169.960544 -277.195026)
		(end 169.38752 -276.622002)
		(width 0.18288)
		(layer "In2.Cu")
		(net "M_F_CPU1_SA_CB<1>")
	)
	(segment
		(start 164.30498 -277.943564)
		(end 164.03193 -277.943564)
		(width 0.18288)
		(layer "In2.Cu")
		(net "M_F_CPU1_SA_CB<1>")
	)
	(segment
		(start 164.03193 -277.943564)
		(end 163.368228 -277.279862)
		(width 0.18288)
		(layer "In2.Cu")
		(net "M_F_CPU1_SA_CB<1>")
	)
	(segment
		(start 155.268676 -274.16379)
		(end 154.298904 -271.822672)
		(width 0.18288)
		(layer "In2.Cu")
		(net "M_F_CPU1_SA_CB<1>")
	)
	(segment
		(start 168.454832 -277.601426)
		(end 167.284654 -277.601426)
		(width 0.18288)
		(layer "In2.Cu")
		(net "M_F_CPU1_SA_CB<1>")
	)
	(segment
		(start 149.7838 -267.307568)
		(end 147.234656 -267.307568)
		(width 0.18288)
		(layer "In2.Cu")
		(net "M_F_CPU1_SA_CB<1>")
	)
	(segment
		(start 154.298904 -271.822672)
		(end 149.7838 -267.307568)
		(width 0.18288)
		(layer "In2.Cu")
		(net "M_F_CPU1_SA_CB<1>")
	)
	(segment
		(start 156.821632 -274.98421)
		(end 156.089096 -274.98421)
		(width 0.18288)
		(layer "In2.Cu")
		(net "M_F_CPU1_SA_CB<1>")
	)
	(segment
		(start 157.951678 -275.940012)
		(end 157.237938 -275.940012)
		(width 0.18288)
		(layer "In2.Cu")
		(net "M_F_CPU1_SA_CB<1>")
	)
	(segment
		(start 143.72971 -264.251948)
		(end 140.900404 -264.251948)
		(width 0.18288)
		(layer "In2.Cu")
		(net "M_F_CPU1_SA_CB<1>")
	)
	(segment
		(start 140.900404 -264.251948)
		(end 139.944094 -264.251948)
		(width 0.088646)
		(layer "In2.Cu")
		(net "M_F_CPU1_SA_CB<1>")
	)
	(segment
		(start 158.309818 -276.298152)
		(end 157.951678 -275.940012)
		(width 0.18288)
		(layer "In2.Cu")
		(net "M_F_CPU1_SA_CB<1>")
	)
	(arc
		(start 137.407396 -264.176002)
		(mid 137.124694 -264.251778)
		(end 136.841992 -264.176002)
		(width 0.088646)
		(layer "In2.Cu")
		(net "M_F_CPU1_SA_CB<1>")
	)
	(arc
		(start 138.347196 -264.176002)
		(mid 138.064494 -264.251778)
		(end 137.781792 -264.176002)
		(width 0.088646)
		(layer "In2.Cu")
		(net "M_F_CPU1_SA_CB<1>")
	)
	(arc
		(start 139.944094 -264.251948)
		(mid 139.919561 -264.25146)
		(end 139.895072 -264.249916)
		(width 0.088646)
		(layer "In2.Cu")
		(net "M_F_CPU1_SA_CB<1>")
	)
	(arc
		(start 136.467596 -264.176002)
		(mid 136.184894 -264.251778)
		(end 135.902192 -264.176002)
		(width 0.088646)
		(layer "In2.Cu")
		(net "M_F_CPU1_SA_CB<1>")
	)
	(arc
		(start 134.323328 -264.083292)
		(mid 133.805063 -263.980185)
		(end 133.365748 -263.686544)
		(width 0.088646)
		(layer "In2.Cu")
		(net "M_F_CPU1_SA_CB<1>")
	)
	(arc
		(start 135.902446 -264.175748)
		(mid 135.736325 -264.10684)
		(end 135.558022 -264.083292)
		(width 0.088646)
		(layer "In2.Cu")
		(net "M_F_CPU1_SA_CB<1>")
	)
	(arc
		(start 138.721592 -264.176002)
		(mid 138.534394 -264.125859)
		(end 138.347196 -264.176002)
		(width 0.088646)
		(layer "In2.Cu")
		(net "M_F_CPU1_SA_CB<1>")
	)
	(arc
		(start 136.841992 -264.176002)
		(mid 136.654794 -264.125859)
		(end 136.467596 -264.176002)
		(width 0.088646)
		(layer "In2.Cu")
		(net "M_F_CPU1_SA_CB<1>")
	)
	(arc
		(start 139.661392 -264.176002)
		(mid 139.474194 -264.125859)
		(end 139.286996 -264.176002)
		(width 0.088646)
		(layer "In2.Cu")
		(net "M_F_CPU1_SA_CB<1>")
	)
	(arc
		(start 137.781792 -264.176002)
		(mid 137.594594 -264.125859)
		(end 137.407396 -264.176002)
		(width 0.088646)
		(layer "In2.Cu")
		(net "M_F_CPU1_SA_CB<1>")
	)
	(arc
		(start 139.286996 -264.176002)
		(mid 139.004294 -264.251778)
		(end 138.721592 -264.176002)
		(width 0.088646)
		(layer "In2.Cu")
		(net "M_F_CPU1_SA_CB<1>")
	)
	(arc
		(start 139.895072 -264.249916)
		(mid 139.774168 -264.225797)
		(end 139.661392 -264.176002)
		(width 0.088646)
		(layer "In2.Cu")
		(net "M_F_CPU1_SA_CB<1>")
	)
	(segment
		(start 133.835648 -263.96442)
		(end 133.835648 -264.500106)
		(width 0.20066)
		(layer "F.Cu")
		(net "M_F_CPU1_SA_CB<0>")
	)
	(segment
		(start 176.451514 -278.491696)
		(end 176.333404 -278.609806)
		(width 0.20066)
		(layer "F.Cu")
		(net "M_F_CPU1_SA_CB<0>")
	)
	(segment
		(start 179.011326 -278.485346)
		(end 179.004976 -278.491696)
		(width 0.1016)
		(layer "F.Cu")
		(net "M_F_CPU1_SA_CB<0>")
	)
	(segment
		(start 179.421282 -278.485346)
		(end 179.011326 -278.485346)
		(width 0.20066)
		(layer "F.Cu")
		(net "M_F_CPU1_SA_CB<0>")
	)
	(segment
		(start 133.835648 -264.500106)
		(end 133.835394 -264.50036)
		(width 0.20066)
		(layer "F.Cu")
		(net "M_F_CPU1_SA_CB<0>")
	)
	(segment
		(start 179.004976 -278.491696)
		(end 176.843182 -278.491696)
		(width 0.1016)
		(layer "F.Cu")
		(net "M_F_CPU1_SA_CB<0>")
	)
	(segment
		(start 181.444646 -278.916638)
		(end 181.444392 -278.916892)
		(width 0.20066)
		(layer "F.Cu")
		(net "M_F_CPU1_SA_CB<0>")
	)
	(segment
		(start 175.421544 -278.916638)
		(end 173.900846 -278.916638)
		(width 0.20066)
		(layer "F.Cu")
		(net "M_F_CPU1_SA_CB<0>")
	)
	(segment
		(start 176.145444 -279.165304)
		(end 175.67021 -279.165304)
		(width 0.20066)
		(layer "F.Cu")
		(net "M_F_CPU1_SA_CB<0>")
	)
	(segment
		(start 176.796192 -278.491696)
		(end 176.451514 -278.491696)
		(width 0.20066)
		(layer "F.Cu")
		(net "M_F_CPU1_SA_CB<0>")
	)
	(segment
		(start 176.333404 -278.609806)
		(end 176.333404 -278.977344)
		(width 0.20066)
		(layer "F.Cu")
		(net "M_F_CPU1_SA_CB<0>")
	)
	(segment
		(start 181.444392 -278.916892)
		(end 179.852828 -278.916892)
		(width 0.20066)
		(layer "F.Cu")
		(net "M_F_CPU1_SA_CB<0>")
	)
	(segment
		(start 175.67021 -279.165304)
		(end 175.421544 -278.916638)
		(width 0.20066)
		(layer "F.Cu")
		(net "M_F_CPU1_SA_CB<0>")
	)
	(segment
		(start 176.333404 -278.977344)
		(end 176.145444 -279.165304)
		(width 0.20066)
		(layer "F.Cu")
		(net "M_F_CPU1_SA_CB<0>")
	)
	(segment
		(start 173.900846 -278.916638)
		(end 172.795946 -278.916638)
		(width 0.20066)
		(layer "F.Cu")
		(net "M_F_CPU1_SA_CB<0>")
	)
	(segment
		(start 176.843182 -278.491696)
		(end 176.796192 -278.491696)
		(width 0.101854)
		(layer "F.Cu")
		(net "M_F_CPU1_SA_CB<0>")
	)
	(segment
		(start 179.852828 -278.916892)
		(end 179.421282 -278.485346)
		(width 0.20066)
		(layer "F.Cu")
		(net "M_F_CPU1_SA_CB<0>")
	)
	(segment
		(start 162.171126 -279.176226)
		(end 161.995104 -279.352248)
		(width 0.18288)
		(layer "In2.Cu")
		(net "M_F_CPU1_SA_CB<0>")
	)
	(segment
		(start 168.317164 -279.506172)
		(end 168.020492 -279.2095)
		(width 0.18288)
		(layer "In2.Cu")
		(net "M_F_CPU1_SA_CB<0>")
	)
	(segment
		(start 166.988998 -279.942544)
		(end 166.795958 -280.135584)
		(width 0.18288)
		(layer "In2.Cu")
		(net "M_F_CPU1_SA_CB<0>")
	)
	(segment
		(start 135.447278 -264.998454)
		(end 135.432546 -264.989818)
		(width 0.088646)
		(layer "In2.Cu")
		(net "M_F_CPU1_SA_CB<0>")
	)
	(segment
		(start 164.761926 -279.221692)
		(end 164.616384 -279.367234)
		(width 0.18288)
		(layer "In2.Cu")
		(net "M_F_CPU1_SA_CB<0>")
	)
	(segment
		(start 163.829238 -279.367234)
		(end 163.63823 -279.176226)
		(width 0.18288)
		(layer "In2.Cu")
		(net "M_F_CPU1_SA_CB<0>")
	)
	(segment
		(start 160.074102 -277.57628)
		(end 157.723586 -277.57628)
		(width 0.18288)
		(layer "In2.Cu")
		(net "M_F_CPU1_SA_CB<0>")
	)
	(segment
		(start 168.881298 -280.256742)
		(end 168.48963 -280.256742)
		(width 0.18288)
		(layer "In2.Cu")
		(net "M_F_CPU1_SA_CB<0>")
	)
	(segment
		(start 165.998398 -280.135584)
		(end 165.785292 -279.922478)
		(width 0.18288)
		(layer "In2.Cu")
		(net "M_F_CPU1_SA_CB<0>")
	)
	(segment
		(start 165.49878 -279.221692)
		(end 164.761926 -279.221692)
		(width 0.18288)
		(layer "In2.Cu")
		(net "M_F_CPU1_SA_CB<0>")
	)
	(segment
		(start 157.723586 -277.57628)
		(end 156.87167 -277.22322)
		(width 0.18288)
		(layer "In2.Cu")
		(net "M_F_CPU1_SA_CB<0>")
	)
	(segment
		(start 166.988998 -279.566116)
		(end 166.988998 -279.942544)
		(width 0.18288)
		(layer "In2.Cu")
		(net "M_F_CPU1_SA_CB<0>")
	)
	(segment
		(start 140.361924 -265.010392)
		(end 140.290296 -264.938764)
		(width 0.088646)
		(layer "In2.Cu")
		(net "M_F_CPU1_SA_CB<0>")
	)
	(segment
		(start 172.795946 -278.916638)
		(end 172.150278 -278.27097)
		(width 0.18288)
		(layer "In2.Cu")
		(net "M_F_CPU1_SA_CB<0>")
	)
	(segment
		(start 169.074338 -279.82164)
		(end 169.074338 -280.063702)
		(width 0.18288)
		(layer "In2.Cu")
		(net "M_F_CPU1_SA_CB<0>")
	)
	(segment
		(start 134.507478 -264.998454)
		(end 134.492746 -264.989818)
		(width 0.088646)
		(layer "In2.Cu")
		(net "M_F_CPU1_SA_CB<0>")
	)
	(segment
		(start 171.555918 -278.27097)
		(end 171.158662 -278.668226)
		(width 0.18288)
		(layer "In2.Cu")
		(net "M_F_CPU1_SA_CB<0>")
	)
	(segment
		(start 161.563304 -279.352248)
		(end 160.589214 -278.378158)
		(width 0.18288)
		(layer "In2.Cu")
		(net "M_F_CPU1_SA_CB<0>")
	)
	(segment
		(start 171.158662 -278.668226)
		(end 170.227752 -278.668226)
		(width 0.18288)
		(layer "In2.Cu")
		(net "M_F_CPU1_SA_CB<0>")
	)
	(segment
		(start 167.345614 -279.2095)
		(end 166.988998 -279.566116)
		(width 0.18288)
		(layer "In2.Cu")
		(net "M_F_CPU1_SA_CB<0>")
	)
	(segment
		(start 161.995104 -279.352248)
		(end 161.563304 -279.352248)
		(width 0.18288)
		(layer "In2.Cu")
		(net "M_F_CPU1_SA_CB<0>")
	)
	(segment
		(start 154.42057 -274.77212)
		(end 153.437082 -272.397982)
		(width 0.18288)
		(layer "In2.Cu")
		(net "M_F_CPU1_SA_CB<0>")
	)
	(segment
		(start 149.37867 -268.33957)
		(end 147.27936 -268.33957)
		(width 0.18288)
		(layer "In2.Cu")
		(net "M_F_CPU1_SA_CB<0>")
	)
	(segment
		(start 168.48963 -280.256742)
		(end 168.317164 -280.084276)
		(width 0.18288)
		(layer "In2.Cu")
		(net "M_F_CPU1_SA_CB<0>")
	)
	(segment
		(start 136.387078 -264.998454)
		(end 136.372346 -264.989818)
		(width 0.088646)
		(layer "In2.Cu")
		(net "M_F_CPU1_SA_CB<0>")
	)
	(segment
		(start 140.290296 -264.938764)
		(end 139.944856 -264.938764)
		(width 0.088646)
		(layer "In2.Cu")
		(net "M_F_CPU1_SA_CB<0>")
	)
	(segment
		(start 165.785292 -279.922478)
		(end 165.785292 -279.508204)
		(width 0.18288)
		(layer "In2.Cu")
		(net "M_F_CPU1_SA_CB<0>")
	)
	(segment
		(start 153.437082 -272.397982)
		(end 149.37867 -268.33957)
		(width 0.18288)
		(layer "In2.Cu")
		(net "M_F_CPU1_SA_CB<0>")
	)
	(segment
		(start 147.27936 -268.33957)
		(end 144.281652 -265.341862)
		(width 0.18288)
		(layer "In2.Cu")
		(net "M_F_CPU1_SA_CB<0>")
	)
	(segment
		(start 139.206478 -264.998454)
		(end 139.191746 -264.989818)
		(width 0.088646)
		(layer "In2.Cu")
		(net "M_F_CPU1_SA_CB<0>")
	)
	(segment
		(start 134.492746 -264.989818)
		(end 134.48665 -264.986262)
		(width 0.088646)
		(layer "In2.Cu")
		(net "M_F_CPU1_SA_CB<0>")
	)
	(segment
		(start 169.074338 -280.063702)
		(end 168.881298 -280.256742)
		(width 0.18288)
		(layer "In2.Cu")
		(net "M_F_CPU1_SA_CB<0>")
	)
	(segment
		(start 166.795958 -280.135584)
		(end 165.998398 -280.135584)
		(width 0.18288)
		(layer "In2.Cu")
		(net "M_F_CPU1_SA_CB<0>")
	)
	(segment
		(start 137.326878 -264.998454)
		(end 137.312146 -264.989818)
		(width 0.088646)
		(layer "In2.Cu")
		(net "M_F_CPU1_SA_CB<0>")
	)
	(segment
		(start 163.63823 -279.176226)
		(end 162.171126 -279.176226)
		(width 0.18288)
		(layer "In2.Cu")
		(net "M_F_CPU1_SA_CB<0>")
	)
	(segment
		(start 140.900404 -265.010392)
		(end 140.361924 -265.010392)
		(width 0.088646)
		(layer "In2.Cu")
		(net "M_F_CPU1_SA_CB<0>")
	)
	(segment
		(start 168.317164 -280.084276)
		(end 168.317164 -279.506172)
		(width 0.18288)
		(layer "In2.Cu")
		(net "M_F_CPU1_SA_CB<0>")
	)
	(segment
		(start 172.150278 -278.27097)
		(end 171.555918 -278.27097)
		(width 0.18288)
		(layer "In2.Cu")
		(net "M_F_CPU1_SA_CB<0>")
	)
	(segment
		(start 138.266678 -264.998454)
		(end 138.251946 -264.989818)
		(width 0.088646)
		(layer "In2.Cu")
		(net "M_F_CPU1_SA_CB<0>")
	)
	(segment
		(start 144.281652 -265.341862)
		(end 143.480282 -265.010392)
		(width 0.18288)
		(layer "In2.Cu")
		(net "M_F_CPU1_SA_CB<0>")
	)
	(segment
		(start 143.480282 -265.010392)
		(end 140.900404 -265.010392)
		(width 0.18288)
		(layer "In2.Cu")
		(net "M_F_CPU1_SA_CB<0>")
	)
	(segment
		(start 165.785292 -279.508204)
		(end 165.49878 -279.221692)
		(width 0.18288)
		(layer "In2.Cu")
		(net "M_F_CPU1_SA_CB<0>")
	)
	(segment
		(start 168.020492 -279.2095)
		(end 167.345614 -279.2095)
		(width 0.18288)
		(layer "In2.Cu")
		(net "M_F_CPU1_SA_CB<0>")
	)
	(segment
		(start 170.227752 -278.668226)
		(end 169.074338 -279.82164)
		(width 0.18288)
		(layer "In2.Cu")
		(net "M_F_CPU1_SA_CB<0>")
	)
	(segment
		(start 164.616384 -279.367234)
		(end 163.829238 -279.367234)
		(width 0.18288)
		(layer "In2.Cu")
		(net "M_F_CPU1_SA_CB<0>")
	)
	(segment
		(start 160.589214 -278.378158)
		(end 160.386268 -277.888446)
		(width 0.18288)
		(layer "In2.Cu")
		(net "M_F_CPU1_SA_CB<0>")
	)
	(segment
		(start 156.87167 -277.22322)
		(end 154.42057 -274.77212)
		(width 0.18288)
		(layer "In2.Cu")
		(net "M_F_CPU1_SA_CB<0>")
	)
	(segment
		(start 160.386268 -277.888446)
		(end 160.074102 -277.57628)
		(width 0.18288)
		(layer "In2.Cu")
		(net "M_F_CPU1_SA_CB<0>")
	)
	(arc
		(start 135.05815 -264.989818)
		(mid 134.783951 -265.065653)
		(end 134.507478 -264.998454)
		(width 0.088646)
		(layer "In2.Cu")
		(net "M_F_CPU1_SA_CB<0>")
	)
	(arc
		(start 137.87755 -264.989818)
		(mid 137.603351 -265.065653)
		(end 137.326878 -264.998454)
		(width 0.088646)
		(layer "In2.Cu")
		(net "M_F_CPU1_SA_CB<0>")
	)
	(arc
		(start 135.99795 -264.989818)
		(mid 135.723751 -265.065653)
		(end 135.447278 -264.998454)
		(width 0.088646)
		(layer "In2.Cu")
		(net "M_F_CPU1_SA_CB<0>")
	)
	(arc
		(start 138.251946 -264.989818)
		(mid 138.064748 -264.939675)
		(end 137.87755 -264.989818)
		(width 0.088646)
		(layer "In2.Cu")
		(net "M_F_CPU1_SA_CB<0>")
	)
	(arc
		(start 136.372346 -264.989818)
		(mid 136.185148 -264.939675)
		(end 135.99795 -264.989818)
		(width 0.088646)
		(layer "In2.Cu")
		(net "M_F_CPU1_SA_CB<0>")
	)
	(arc
		(start 139.75715 -264.989818)
		(mid 139.482951 -265.065653)
		(end 139.206478 -264.998454)
		(width 0.088646)
		(layer "In2.Cu")
		(net "M_F_CPU1_SA_CB<0>")
	)
	(arc
		(start 137.312146 -264.989818)
		(mid 137.124948 -264.939675)
		(end 136.93775 -264.989818)
		(width 0.088646)
		(layer "In2.Cu")
		(net "M_F_CPU1_SA_CB<0>")
	)
	(arc
		(start 139.944856 -264.938764)
		(mid 139.847639 -264.95192)
		(end 139.75715 -264.989818)
		(width 0.088646)
		(layer "In2.Cu")
		(net "M_F_CPU1_SA_CB<0>")
	)
	(arc
		(start 134.48665 -264.986262)
		(mid 134.147286 -264.761721)
		(end 133.835394 -264.50036)
		(width 0.088646)
		(layer "In2.Cu")
		(net "M_F_CPU1_SA_CB<0>")
	)
	(arc
		(start 135.432546 -264.989818)
		(mid 135.245348 -264.939675)
		(end 135.05815 -264.989818)
		(width 0.088646)
		(layer "In2.Cu")
		(net "M_F_CPU1_SA_CB<0>")
	)
	(arc
		(start 136.93775 -264.989818)
		(mid 136.663551 -265.065653)
		(end 136.387078 -264.998454)
		(width 0.088646)
		(layer "In2.Cu")
		(net "M_F_CPU1_SA_CB<0>")
	)
	(arc
		(start 138.81735 -264.989818)
		(mid 138.543151 -265.065653)
		(end 138.266678 -264.998454)
		(width 0.088646)
		(layer "In2.Cu")
		(net "M_F_CPU1_SA_CB<0>")
	)
	(arc
		(start 139.191746 -264.989818)
		(mid 139.004548 -264.939675)
		(end 138.81735 -264.989818)
		(width 0.088646)
		(layer "In2.Cu")
		(net "M_F_CPU1_SA_CB<0>")
	)
	(segment
		(start 131.485894 -257.175)
		(end 131.486148 -257.175254)
		(width 0.20066)
		(layer "F.Cu")
		(net "M_F_CPU1_SA_CA<6>")
	)
	(segment
		(start 131.485894 -256.639314)
		(end 131.485894 -257.175)
		(width 0.20066)
		(layer "F.Cu")
		(net "M_F_CPU1_SA_CA<6>")
	)
	(segment
		(start 179.86502 -261.066534)
		(end 181.444392 -261.066534)
		(width 0.20066)
		(layer "F.Cu")
		(net "M_F_CPU1_SA_CA<6>")
	)
	(segment
		(start 176.812702 -261.49173)
		(end 176.826418 -261.49173)
		(width 0.101854)
		(layer "F.Cu")
		(net "M_F_CPU1_SA_CA<6>")
	)
	(segment
		(start 175.46066 -260.572504)
		(end 175.786034 -260.572504)
		(width 0.20066)
		(layer "F.Cu")
		(net "M_F_CPU1_SA_CA<6>")
	)
	(segment
		(start 176.826418 -261.49173)
		(end 178.99888 -261.49173)
		(width 0.1016)
		(layer "F.Cu")
		(net "M_F_CPU1_SA_CA<6>")
	)
	(segment
		(start 178.99888 -261.49173)
		(end 179.011326 -261.504176)
		(width 0.1016)
		(layer "F.Cu")
		(net "M_F_CPU1_SA_CA<6>")
	)
	(segment
		(start 179.011326 -261.504176)
		(end 179.427378 -261.504176)
		(width 0.20066)
		(layer "F.Cu")
		(net "M_F_CPU1_SA_CA<6>")
	)
	(segment
		(start 176.70526 -261.49173)
		(end 176.812702 -261.49173)
		(width 0.20066)
		(layer "F.Cu")
		(net "M_F_CPU1_SA_CA<6>")
	)
	(segment
		(start 174.966376 -261.066788)
		(end 175.46066 -260.572504)
		(width 0.20066)
		(layer "F.Cu")
		(net "M_F_CPU1_SA_CA<6>")
	)
	(segment
		(start 175.786034 -260.572504)
		(end 176.70526 -261.49173)
		(width 0.20066)
		(layer "F.Cu")
		(net "M_F_CPU1_SA_CA<6>")
	)
	(segment
		(start 181.444392 -261.066534)
		(end 181.444646 -261.066788)
		(width 0.20066)
		(layer "F.Cu")
		(net "M_F_CPU1_SA_CA<6>")
	)
	(segment
		(start 173.900846 -261.066788)
		(end 174.966376 -261.066788)
		(width 0.20066)
		(layer "F.Cu")
		(net "M_F_CPU1_SA_CA<6>")
	)
	(segment
		(start 172.719746 -261.066788)
		(end 173.900846 -261.066788)
		(width 0.20066)
		(layer "F.Cu")
		(net "M_F_CPU1_SA_CA<6>")
	)
	(segment
		(start 179.427378 -261.504176)
		(end 179.86502 -261.066534)
		(width 0.20066)
		(layer "F.Cu")
		(net "M_F_CPU1_SA_CA<6>")
	)
	(segment
		(start 152.080722 -256.066544)
		(end 151.755094 -255.740916)
		(width 0.18288)
		(layer "In2.Cu")
		(net "M_F_CPU1_SA_CA<6>")
	)
	(segment
		(start 138.405616 -255.17221)
		(end 138.064748 -255.17221)
		(width 0.088646)
		(layer "In2.Cu")
		(net "M_F_CPU1_SA_CA<6>")
	)
	(segment
		(start 136.93775 -255.22301)
		(end 136.937496 -255.223264)
		(width 0.088646)
		(layer "In2.Cu")
		(net "M_F_CPU1_SA_CA<6>")
	)
	(segment
		(start 155.028392 -255.740916)
		(end 154.192986 -255.740916)
		(width 0.18288)
		(layer "In2.Cu")
		(net "M_F_CPU1_SA_CA<6>")
	)
	(segment
		(start 140.033502 -255.300226)
		(end 138.53414 -255.300226)
		(width 0.088646)
		(layer "In2.Cu")
		(net "M_F_CPU1_SA_CA<6>")
	)
	(segment
		(start 150.346918 -255.740916)
		(end 149.968458 -255.740916)
		(width 0.18288)
		(layer "In2.Cu")
		(net "M_F_CPU1_SA_CA<6>")
	)
	(segment
		(start 131.731512 -256.88036)
		(end 131.642358 -256.904236)
		(width 0.088646)
		(layer "In2.Cu")
		(net "M_F_CPU1_SA_CA<6>")
	)
	(segment
		(start 172.14088 -259.172456)
		(end 171.94784 -258.979416)
		(width 0.18288)
		(layer "In2.Cu")
		(net "M_F_CPU1_SA_CA<6>")
	)
	(segment
		(start 170.42257 -258.092702)
		(end 169.618914 -257.932936)
		(width 0.18288)
		(layer "In2.Cu")
		(net "M_F_CPU1_SA_CA<6>")
	)
	(segment
		(start 143.989044 -255.979676)
		(end 141.398752 -255.464564)
		(width 0.18288)
		(layer "In2.Cu")
		(net "M_F_CPU1_SA_CA<6>")
	)
	(segment
		(start 131.642358 -256.904236)
		(end 131.486148 -257.175254)
		(width 0.088646)
		(layer "In2.Cu")
		(net "M_F_CPU1_SA_CA<6>")
	)
	(segment
		(start 137.326878 -255.231646)
		(end 137.312146 -255.22301)
		(width 0.088646)
		(layer "In2.Cu")
		(net "M_F_CPU1_SA_CA<6>")
	)
	(segment
		(start 148.292566 -255.740916)
		(end 147.715986 -255.979676)
		(width 0.18288)
		(layer "In2.Cu")
		(net "M_F_CPU1_SA_CA<6>")
	)
	(segment
		(start 172.719746 -260.793484)
		(end 172.14088 -260.214618)
		(width 0.18288)
		(layer "In2.Cu")
		(net "M_F_CPU1_SA_CA<6>")
	)
	(segment
		(start 152.78481 -255.740916)
		(end 152.459182 -256.066544)
		(width 0.18288)
		(layer "In2.Cu")
		(net "M_F_CPU1_SA_CA<6>")
	)
	(segment
		(start 172.14088 -260.214618)
		(end 172.14088 -259.172456)
		(width 0.18288)
		(layer "In2.Cu")
		(net "M_F_CPU1_SA_CA<6>")
	)
	(segment
		(start 132.623306 -256.856992)
		(end 132.612892 -256.850896)
		(width 0.088646)
		(layer "In2.Cu")
		(net "M_F_CPU1_SA_CA<6>")
	)
	(segment
		(start 147.715986 -255.979676)
		(end 143.989044 -255.979676)
		(width 0.18288)
		(layer "In2.Cu")
		(net "M_F_CPU1_SA_CA<6>")
	)
	(segment
		(start 140.51915 -255.464564)
		(end 140.19784 -255.464564)
		(width 0.088646)
		(layer "In2.Cu")
		(net "M_F_CPU1_SA_CA<6>")
	)
	(segment
		(start 151.376634 -255.740916)
		(end 151.051006 -256.066544)
		(width 0.18288)
		(layer "In2.Cu")
		(net "M_F_CPU1_SA_CA<6>")
	)
	(segment
		(start 169.11955 -257.932936)
		(end 168.922954 -258.129532)
		(width 0.18288)
		(layer "In2.Cu")
		(net "M_F_CPU1_SA_CA<6>")
	)
	(segment
		(start 132.238496 -256.850896)
		(end 132.223764 -256.859532)
		(width 0.088646)
		(layer "In2.Cu")
		(net "M_F_CPU1_SA_CA<6>")
	)
	(segment
		(start 133.648196 -256.03708)
		(end 133.639306 -256.04216)
		(width 0.088646)
		(layer "In2.Cu")
		(net "M_F_CPU1_SA_CA<6>")
	)
	(segment
		(start 150.672546 -256.066544)
		(end 150.346918 -255.740916)
		(width 0.18288)
		(layer "In2.Cu")
		(net "M_F_CPU1_SA_CA<6>")
	)
	(segment
		(start 171.309284 -258.979416)
		(end 170.42257 -258.092702)
		(width 0.18288)
		(layer "In2.Cu")
		(net "M_F_CPU1_SA_CA<6>")
	)
	(segment
		(start 171.94784 -258.979416)
		(end 171.309284 -258.979416)
		(width 0.18288)
		(layer "In2.Cu")
		(net "M_F_CPU1_SA_CA<6>")
	)
	(segment
		(start 168.516554 -258.129532)
		(end 168.1607 -257.773678)
		(width 0.18288)
		(layer "In2.Cu")
		(net "M_F_CPU1_SA_CA<6>")
	)
	(segment
		(start 167.68953 -257.578352)
		(end 159.463994 -257.578352)
		(width 0.18288)
		(layer "In2.Cu")
		(net "M_F_CPU1_SA_CA<6>")
	)
	(segment
		(start 138.533632 -255.300226)
		(end 138.405616 -255.17221)
		(width 0.088646)
		(layer "In2.Cu")
		(net "M_F_CPU1_SA_CA<6>")
	)
	(segment
		(start 148.938742 -255.740916)
		(end 148.292566 -255.740916)
		(width 0.18288)
		(layer "In2.Cu")
		(net "M_F_CPU1_SA_CA<6>")
	)
	(segment
		(start 153.16327 -255.740916)
		(end 152.78481 -255.740916)
		(width 0.18288)
		(layer "In2.Cu")
		(net "M_F_CPU1_SA_CA<6>")
	)
	(segment
		(start 169.618914 -257.932936)
		(end 169.11955 -257.932936)
		(width 0.18288)
		(layer "In2.Cu")
		(net "M_F_CPU1_SA_CA<6>")
	)
	(segment
		(start 133.660388 -256.029968)
		(end 133.648196 -256.03708)
		(width 0.088646)
		(layer "In2.Cu")
		(net "M_F_CPU1_SA_CA<6>")
	)
	(segment
		(start 168.922954 -258.129532)
		(end 168.516554 -258.129532)
		(width 0.18288)
		(layer "In2.Cu")
		(net "M_F_CPU1_SA_CA<6>")
	)
	(segment
		(start 168.1607 -257.773678)
		(end 167.68953 -257.578352)
		(width 0.18288)
		(layer "In2.Cu")
		(net "M_F_CPU1_SA_CA<6>")
	)
	(segment
		(start 141.398752 -255.464564)
		(end 140.51915 -255.464564)
		(width 0.18288)
		(layer "In2.Cu")
		(net "M_F_CPU1_SA_CA<6>")
	)
	(segment
		(start 159.463994 -257.578352)
		(end 155.028392 -255.740916)
		(width 0.18288)
		(layer "In2.Cu")
		(net "M_F_CPU1_SA_CA<6>")
	)
	(segment
		(start 149.64283 -256.066544)
		(end 149.26437 -256.066544)
		(width 0.18288)
		(layer "In2.Cu")
		(net "M_F_CPU1_SA_CA<6>")
	)
	(segment
		(start 172.719746 -261.066788)
		(end 172.719746 -260.793484)
		(width 0.18288)
		(layer "In2.Cu")
		(net "M_F_CPU1_SA_CA<6>")
	)
	(segment
		(start 153.867358 -256.066544)
		(end 153.488898 -256.066544)
		(width 0.18288)
		(layer "In2.Cu")
		(net "M_F_CPU1_SA_CA<6>")
	)
	(segment
		(start 151.755094 -255.740916)
		(end 151.376634 -255.740916)
		(width 0.18288)
		(layer "In2.Cu")
		(net "M_F_CPU1_SA_CA<6>")
	)
	(segment
		(start 152.459182 -256.066544)
		(end 152.080722 -256.066544)
		(width 0.18288)
		(layer "In2.Cu")
		(net "M_F_CPU1_SA_CA<6>")
	)
	(segment
		(start 134.11835 -255.223264)
		(end 134.10946 -255.228344)
		(width 0.088646)
		(layer "In2.Cu")
		(net "M_F_CPU1_SA_CA<6>")
	)
	(segment
		(start 149.968458 -255.740916)
		(end 149.64283 -256.066544)
		(width 0.18288)
		(layer "In2.Cu")
		(net "M_F_CPU1_SA_CA<6>")
	)
	(segment
		(start 140.19784 -255.464564)
		(end 140.033502 -255.300226)
		(width 0.088646)
		(layer "In2.Cu")
		(net "M_F_CPU1_SA_CA<6>")
	)
	(segment
		(start 133.460744 -256.361438)
		(end 133.460744 -256.376932)
		(width 0.088646)
		(layer "In2.Cu")
		(net "M_F_CPU1_SA_CA<6>")
	)
	(segment
		(start 134.50316 -255.22936)
		(end 134.492746 -255.223264)
		(width 0.088646)
		(layer "In2.Cu")
		(net "M_F_CPU1_SA_CA<6>")
	)
	(segment
		(start 154.192986 -255.740916)
		(end 153.867358 -256.066544)
		(width 0.18288)
		(layer "In2.Cu")
		(net "M_F_CPU1_SA_CA<6>")
	)
	(segment
		(start 149.26437 -256.066544)
		(end 148.938742 -255.740916)
		(width 0.18288)
		(layer "In2.Cu")
		(net "M_F_CPU1_SA_CA<6>")
	)
	(segment
		(start 153.488898 -256.066544)
		(end 153.16327 -255.740916)
		(width 0.18288)
		(layer "In2.Cu")
		(net "M_F_CPU1_SA_CA<6>")
	)
	(segment
		(start 151.051006 -256.066544)
		(end 150.672546 -256.066544)
		(width 0.18288)
		(layer "In2.Cu")
		(net "M_F_CPU1_SA_CA<6>")
	)
	(arc
		(start 133.17855 -256.850896)
		(mid 132.901737 -256.926766)
		(end 132.623306 -256.856992)
		(width 0.088646)
		(layer "In2.Cu")
		(net "M_F_CPU1_SA_CA<6>")
	)
	(arc
		(start 137.87755 -255.22301)
		(mid 137.603351 -255.298845)
		(end 137.326878 -255.231646)
		(width 0.088646)
		(layer "In2.Cu")
		(net "M_F_CPU1_SA_CA<6>")
	)
	(arc
		(start 136.937496 -255.223264)
		(mid 136.654794 -255.299006)
		(end 136.372092 -255.223264)
		(width 0.088646)
		(layer "In2.Cu")
		(net "M_F_CPU1_SA_CA<6>")
	)
	(arc
		(start 132.612892 -256.850896)
		(mid 132.425694 -256.800753)
		(end 132.238496 -256.850896)
		(width 0.088646)
		(layer "In2.Cu")
		(net "M_F_CPU1_SA_CA<6>")
	)
	(arc
		(start 133.930898 -255.547622)
		(mid 133.858663 -255.824146)
		(end 133.660388 -256.029968)
		(width 0.088646)
		(layer "In2.Cu")
		(net "M_F_CPU1_SA_CA<6>")
	)
	(arc
		(start 137.312146 -255.22301)
		(mid 137.124948 -255.172867)
		(end 136.93775 -255.22301)
		(width 0.088646)
		(layer "In2.Cu")
		(net "M_F_CPU1_SA_CA<6>")
	)
	(arc
		(start 134.492746 -255.223264)
		(mid 134.305548 -255.173121)
		(end 134.11835 -255.223264)
		(width 0.088646)
		(layer "In2.Cu")
		(net "M_F_CPU1_SA_CA<6>")
	)
	(arc
		(start 135.997696 -255.223264)
		(mid 135.714994 -255.299006)
		(end 135.432292 -255.223264)
		(width 0.088646)
		(layer "In2.Cu")
		(net "M_F_CPU1_SA_CA<6>")
	)
	(arc
		(start 135.432292 -255.223264)
		(mid 135.245094 -255.173121)
		(end 135.057896 -255.223264)
		(width 0.088646)
		(layer "In2.Cu")
		(net "M_F_CPU1_SA_CA<6>")
	)
	(arc
		(start 133.639306 -256.04216)
		(mid 133.508392 -256.17852)
		(end 133.460744 -256.361438)
		(width 0.088646)
		(layer "In2.Cu")
		(net "M_F_CPU1_SA_CA<6>")
	)
	(arc
		(start 135.057896 -255.223264)
		(mid 134.781337 -255.298973)
		(end 134.50316 -255.22936)
		(width 0.088646)
		(layer "In2.Cu")
		(net "M_F_CPU1_SA_CA<6>")
	)
	(arc
		(start 136.372092 -255.223264)
		(mid 136.184894 -255.173121)
		(end 135.997696 -255.223264)
		(width 0.088646)
		(layer "In2.Cu")
		(net "M_F_CPU1_SA_CA<6>")
	)
	(arc
		(start 134.10946 -255.228344)
		(mid 133.978546 -255.364704)
		(end 133.930898 -255.547622)
		(width 0.088646)
		(layer "In2.Cu")
		(net "M_F_CPU1_SA_CA<6>")
	)
	(arc
		(start 138.064748 -255.17221)
		(mid 137.967809 -255.1853)
		(end 137.87755 -255.22301)
		(width 0.088646)
		(layer "In2.Cu")
		(net "M_F_CPU1_SA_CA<6>")
	)
	(arc
		(start 138.53414 -255.300226)
		(mid 138.533886 -255.300226)
		(end 138.533632 -255.300226)
		(width 0.088646)
		(layer "In2.Cu")
		(net "M_F_CPU1_SA_CA<6>")
	)
	(arc
		(start 133.460744 -256.376932)
		(mid 133.381374 -256.650666)
		(end 133.17855 -256.850896)
		(width 0.088646)
		(layer "In2.Cu")
		(net "M_F_CPU1_SA_CA<6>")
	)
	(arc
		(start 132.223764 -256.859532)
		(mid 131.98002 -256.926411)
		(end 131.731512 -256.88036)
		(width 0.088646)
		(layer "In2.Cu")
		(net "M_F_CPU1_SA_CA<6>")
	)
	(segment
		(start 183.9976 -261.48411)
		(end 184.430162 -261.916672)
		(width 0.20066)
		(layer "F.Cu")
		(net "M_F_CPU1_SA_CA<5>")
	)
	(segment
		(start 182.455058 -262.34898)
		(end 182.729124 -262.34898)
		(width 0.20066)
		(layer "F.Cu")
		(net "M_F_CPU1_SA_CA<5>")
	)
	(segment
		(start 134.775448 -255.825498)
		(end 134.775448 -256.361184)
		(width 0.20066)
		(layer "F.Cu")
		(net "M_F_CPU1_SA_CA<5>")
	)
	(segment
		(start 176.896014 -261.916672)
		(end 178.000914 -261.916672)
		(width 0.20066)
		(layer "F.Cu")
		(net "M_F_CPU1_SA_CA<5>")
	)
	(segment
		(start 182.729124 -262.34898)
		(end 183.593994 -261.48411)
		(width 0.20066)
		(layer "F.Cu")
		(net "M_F_CPU1_SA_CA<5>")
	)
	(segment
		(start 180.072284 -262.352282)
		(end 180.423058 -262.352282)
		(width 0.20066)
		(layer "F.Cu")
		(net "M_F_CPU1_SA_CA<5>")
	)
	(segment
		(start 134.775448 -256.361184)
		(end 134.775194 -256.361438)
		(width 0.20066)
		(layer "F.Cu")
		(net "M_F_CPU1_SA_CA<5>")
	)
	(segment
		(start 182.447692 -262.341614)
		(end 182.455058 -262.34898)
		(width 0.1016)
		(layer "F.Cu")
		(net "M_F_CPU1_SA_CA<5>")
	)
	(segment
		(start 183.593994 -261.48411)
		(end 183.9976 -261.48411)
		(width 0.20066)
		(layer "F.Cu")
		(net "M_F_CPU1_SA_CA<5>")
	)
	(segment
		(start 180.438552 -262.341614)
		(end 182.447692 -262.341614)
		(width 0.1016)
		(layer "F.Cu")
		(net "M_F_CPU1_SA_CA<5>")
	)
	(segment
		(start 180.423058 -262.352282)
		(end 180.427884 -262.352282)
		(width 0.101854)
		(layer "F.Cu")
		(net "M_F_CPU1_SA_CA<5>")
	)
	(segment
		(start 178.000914 -261.916672)
		(end 179.636674 -261.916672)
		(width 0.20066)
		(layer "F.Cu")
		(net "M_F_CPU1_SA_CA<5>")
	)
	(segment
		(start 180.427884 -262.352282)
		(end 180.438552 -262.341614)
		(width 0.1016)
		(layer "F.Cu")
		(net "M_F_CPU1_SA_CA<5>")
	)
	(segment
		(start 184.430162 -261.916672)
		(end 185.544714 -261.916672)
		(width 0.20066)
		(layer "F.Cu")
		(net "M_F_CPU1_SA_CA<5>")
	)
	(segment
		(start 179.636674 -261.916672)
		(end 180.072284 -262.352282)
		(width 0.20066)
		(layer "F.Cu")
		(net "M_F_CPU1_SA_CA<5>")
	)
	(segment
		(start 178.343306 -260.641084)
		(end 176.0855 -260.641084)
		(width 0.18288)
		(layer "In2.Cu")
		(net "M_F_CPU1_SA_CA<5>")
	)
	(segment
		(start 138.68273 -255.79451)
		(end 138.684254 -255.796034)
		(width 0.088646)
		(layer "In2.Cu")
		(net "M_F_CPU1_SA_CA<5>")
	)
	(segment
		(start 178.503326 -261.2898)
		(end 178.503326 -260.801104)
		(width 0.18288)
		(layer "In2.Cu")
		(net "M_F_CPU1_SA_CA<5>")
	)
	(segment
		(start 178.503326 -260.801104)
		(end 178.343306 -260.641084)
		(width 0.18288)
		(layer "In2.Cu")
		(net "M_F_CPU1_SA_CA<5>")
	)
	(segment
		(start 168.82364 -258.70154)
		(end 168.336976 -258.70154)
		(width 0.18288)
		(layer "In2.Cu")
		(net "M_F_CPU1_SA_CA<5>")
	)
	(segment
		(start 167.561006 -258.088384)
		(end 159.322516 -258.088384)
		(width 0.18288)
		(layer "In2.Cu")
		(net "M_F_CPU1_SA_CA<5>")
	)
	(segment
		(start 172.395642 -261.491222)
		(end 172.077126 -261.172706)
		(width 0.18288)
		(layer "In2.Cu")
		(net "M_F_CPU1_SA_CA<5>")
	)
	(segment
		(start 168.336976 -258.70154)
		(end 167.838628 -258.203192)
		(width 0.18288)
		(layer "In2.Cu")
		(net "M_F_CPU1_SA_CA<5>")
	)
	(segment
		(start 171.808648 -260.619748)
		(end 169.63136 -260.619748)
		(width 0.18288)
		(layer "In2.Cu")
		(net "M_F_CPU1_SA_CA<5>")
	)
	(segment
		(start 143.628872 -256.331212)
		(end 141.704822 -255.948688)
		(width 0.18288)
		(layer "In2.Cu")
		(net "M_F_CPU1_SA_CA<5>")
	)
	(segment
		(start 178.343306 -261.44982)
		(end 178.503326 -261.2898)
		(width 0.18288)
		(layer "In2.Cu")
		(net "M_F_CPU1_SA_CA<5>")
	)
	(segment
		(start 139.520422 -255.79451)
		(end 138.68273 -255.79451)
		(width 0.088646)
		(layer "In2.Cu")
		(net "M_F_CPU1_SA_CA<5>")
	)
	(segment
		(start 172.077126 -261.172706)
		(end 172.077126 -260.888226)
		(width 0.18288)
		(layer "In2.Cu")
		(net "M_F_CPU1_SA_CA<5>")
	)
	(segment
		(start 147.4978 -256.331212)
		(end 143.628872 -256.331212)
		(width 0.18288)
		(layer "In2.Cu")
		(net "M_F_CPU1_SA_CA<5>")
	)
	(segment
		(start 174.940214 -261.250938)
		(end 174.69993 -261.491222)
		(width 0.18288)
		(layer "In2.Cu")
		(net "M_F_CPU1_SA_CA<5>")
	)
	(segment
		(start 138.684254 -255.796034)
		(end 138.534394 -255.796034)
		(width 0.088646)
		(layer "In2.Cu")
		(net "M_F_CPU1_SA_CA<5>")
	)
	(segment
		(start 172.077126 -260.888226)
		(end 171.808648 -260.619748)
		(width 0.18288)
		(layer "In2.Cu")
		(net "M_F_CPU1_SA_CA<5>")
	)
	(segment
		(start 176.896014 -261.916672)
		(end 176.896014 -261.64286)
		(width 0.18288)
		(layer "In2.Cu")
		(net "M_F_CPU1_SA_CA<5>")
	)
	(segment
		(start 141.704822 -255.948688)
		(end 139.96035 -255.948688)
		(width 0.18288)
		(layer "In2.Cu")
		(net "M_F_CPU1_SA_CA<5>")
	)
	(segment
		(start 177.089054 -261.44982)
		(end 178.343306 -261.44982)
		(width 0.18288)
		(layer "In2.Cu")
		(net "M_F_CPU1_SA_CA<5>")
	)
	(segment
		(start 139.96035 -255.948688)
		(end 139.6746 -255.948688)
		(width 0.088646)
		(layer "In2.Cu")
		(net "M_F_CPU1_SA_CA<5>")
	)
	(segment
		(start 176.896014 -261.64286)
		(end 177.089054 -261.44982)
		(width 0.18288)
		(layer "In2.Cu")
		(net "M_F_CPU1_SA_CA<5>")
	)
	(segment
		(start 169.30497 -260.293358)
		(end 169.30497 -259.18287)
		(width 0.18288)
		(layer "In2.Cu")
		(net "M_F_CPU1_SA_CA<5>")
	)
	(segment
		(start 167.838628 -258.203192)
		(end 167.561006 -258.088384)
		(width 0.18288)
		(layer "In2.Cu")
		(net "M_F_CPU1_SA_CA<5>")
	)
	(segment
		(start 169.30497 -259.18287)
		(end 168.82364 -258.70154)
		(width 0.18288)
		(layer "In2.Cu")
		(net "M_F_CPU1_SA_CA<5>")
	)
	(segment
		(start 175.475646 -261.250938)
		(end 174.940214 -261.250938)
		(width 0.18288)
		(layer "In2.Cu")
		(net "M_F_CPU1_SA_CA<5>")
	)
	(segment
		(start 155.692856 -256.585212)
		(end 148.110448 -256.585212)
		(width 0.18288)
		(layer "In2.Cu")
		(net "M_F_CPU1_SA_CA<5>")
	)
	(segment
		(start 159.322516 -258.088384)
		(end 155.692856 -256.585212)
		(width 0.18288)
		(layer "In2.Cu")
		(net "M_F_CPU1_SA_CA<5>")
	)
	(segment
		(start 176.0855 -260.641084)
		(end 175.475646 -261.250938)
		(width 0.18288)
		(layer "In2.Cu")
		(net "M_F_CPU1_SA_CA<5>")
	)
	(segment
		(start 135.404098 -255.888236)
		(end 134.775194 -256.361438)
		(width 0.088646)
		(layer "In2.Cu")
		(net "M_F_CPU1_SA_CA<5>")
	)
	(segment
		(start 136.380982 -255.866646)
		(end 136.372092 -255.87198)
		(width 0.088646)
		(layer "In2.Cu")
		(net "M_F_CPU1_SA_CA<5>")
	)
	(segment
		(start 135.432292 -255.87198)
		(end 135.404098 -255.888236)
		(width 0.088646)
		(layer "In2.Cu")
		(net "M_F_CPU1_SA_CA<5>")
	)
	(segment
		(start 137.326878 -255.86309)
		(end 137.312146 -255.871726)
		(width 0.088646)
		(layer "In2.Cu")
		(net "M_F_CPU1_SA_CA<5>")
	)
	(segment
		(start 139.6746 -255.948688)
		(end 139.520422 -255.79451)
		(width 0.088646)
		(layer "In2.Cu")
		(net "M_F_CPU1_SA_CA<5>")
	)
	(segment
		(start 148.110448 -256.585212)
		(end 147.4978 -256.331212)
		(width 0.18288)
		(layer "In2.Cu")
		(net "M_F_CPU1_SA_CA<5>")
	)
	(segment
		(start 174.69993 -261.491222)
		(end 172.395642 -261.491222)
		(width 0.18288)
		(layer "In2.Cu")
		(net "M_F_CPU1_SA_CA<5>")
	)
	(segment
		(start 169.63136 -260.619748)
		(end 169.30497 -260.293358)
		(width 0.18288)
		(layer "In2.Cu")
		(net "M_F_CPU1_SA_CA<5>")
	)
	(arc
		(start 137.312146 -255.871726)
		(mid 137.124948 -255.921869)
		(end 136.93775 -255.871726)
		(width 0.088646)
		(layer "In2.Cu")
		(net "M_F_CPU1_SA_CA<5>")
	)
	(arc
		(start 137.87755 -255.871726)
		(mid 137.603321 -255.795801)
		(end 137.326878 -255.86309)
		(width 0.088646)
		(layer "In2.Cu")
		(net "M_F_CPU1_SA_CA<5>")
	)
	(arc
		(start 135.997696 -255.87198)
		(mid 135.714994 -255.796238)
		(end 135.432292 -255.87198)
		(width 0.088646)
		(layer "In2.Cu")
		(net "M_F_CPU1_SA_CA<5>")
	)
	(arc
		(start 136.372092 -255.87198)
		(mid 136.184894 -255.922123)
		(end 135.997696 -255.87198)
		(width 0.088646)
		(layer "In2.Cu")
		(net "M_F_CPU1_SA_CA<5>")
	)
	(arc
		(start 138.534394 -255.796034)
		(mid 138.388198 -255.815321)
		(end 138.251946 -255.871726)
		(width 0.088646)
		(layer "In2.Cu")
		(net "M_F_CPU1_SA_CA<5>")
	)
	(arc
		(start 136.93775 -255.871726)
		(mid 136.660024 -255.795881)
		(end 136.380982 -255.866646)
		(width 0.088646)
		(layer "In2.Cu")
		(net "M_F_CPU1_SA_CA<5>")
	)
	(arc
		(start 138.251946 -255.871726)
		(mid 138.064748 -255.921869)
		(end 137.87755 -255.871726)
		(width 0.088646)
		(layer "In2.Cu")
		(net "M_F_CPU1_SA_CA<5>")
	)
	(segment
		(start 179.427378 -263.204198)
		(end 179.011326 -263.204198)
		(width 0.20066)
		(layer "F.Cu")
		(net "M_F_CPU1_SA_CA<4>")
	)
	(segment
		(start 181.444392 -262.766556)
		(end 179.86502 -262.766556)
		(width 0.20066)
		(layer "F.Cu")
		(net "M_F_CPU1_SA_CA<4>")
	)
	(segment
		(start 133.835648 -255.825498)
		(end 133.835394 -255.825752)
		(width 0.20066)
		(layer "F.Cu")
		(net "M_F_CPU1_SA_CA<4>")
	)
	(segment
		(start 174.791116 -262.76681)
		(end 173.900846 -262.76681)
		(width 0.20066)
		(layer "F.Cu")
		(net "M_F_CPU1_SA_CA<4>")
	)
	(segment
		(start 179.86502 -262.766556)
		(end 179.427378 -263.204198)
		(width 0.20066)
		(layer "F.Cu")
		(net "M_F_CPU1_SA_CA<4>")
	)
	(segment
		(start 176.744376 -263.191752)
		(end 176.715166 -263.191752)
		(width 0.101854)
		(layer "F.Cu")
		(net "M_F_CPU1_SA_CA<4>")
	)
	(segment
		(start 181.444646 -262.76681)
		(end 181.444392 -262.766556)
		(width 0.20066)
		(layer "F.Cu")
		(net "M_F_CPU1_SA_CA<4>")
	)
	(segment
		(start 178.99888 -263.191752)
		(end 176.744376 -263.191752)
		(width 0.1016)
		(layer "F.Cu")
		(net "M_F_CPU1_SA_CA<4>")
	)
	(segment
		(start 175.548036 -262.294116)
		(end 175.26381 -262.294116)
		(width 0.20066)
		(layer "F.Cu")
		(net "M_F_CPU1_SA_CA<4>")
	)
	(segment
		(start 173.900592 -262.766556)
		(end 173.900846 -262.76681)
		(width 0.20066)
		(layer "F.Cu")
		(net "M_F_CPU1_SA_CA<4>")
	)
	(segment
		(start 175.26381 -262.294116)
		(end 174.791116 -262.76681)
		(width 0.20066)
		(layer "F.Cu")
		(net "M_F_CPU1_SA_CA<4>")
	)
	(segment
		(start 133.835394 -255.825752)
		(end 133.835394 -256.361438)
		(width 0.20066)
		(layer "F.Cu")
		(net "M_F_CPU1_SA_CA<4>")
	)
	(segment
		(start 176.715166 -263.191752)
		(end 176.445672 -263.191752)
		(width 0.20066)
		(layer "F.Cu")
		(net "M_F_CPU1_SA_CA<4>")
	)
	(segment
		(start 172.719746 -262.766556)
		(end 173.900592 -262.766556)
		(width 0.20066)
		(layer "F.Cu")
		(net "M_F_CPU1_SA_CA<4>")
	)
	(segment
		(start 179.011326 -263.204198)
		(end 178.99888 -263.191752)
		(width 0.1016)
		(layer "F.Cu")
		(net "M_F_CPU1_SA_CA<4>")
	)
	(segment
		(start 176.445672 -263.191752)
		(end 175.548036 -262.294116)
		(width 0.20066)
		(layer "F.Cu")
		(net "M_F_CPU1_SA_CA<4>")
	)
	(segment
		(start 138.347196 -256.03708)
		(end 138.332464 -256.045716)
		(width 0.088646)
		(layer "In2.Cu")
		(net "M_F_CPU1_SA_CA<4>")
	)
	(segment
		(start 139.142216 -255.984756)
		(end 139.14374 -255.98628)
		(width 0.088646)
		(layer "In2.Cu")
		(net "M_F_CPU1_SA_CA<4>")
	)
	(segment
		(start 164.238178 -259.170424)
		(end 164.078158 -259.010404)
		(width 0.18288)
		(layer "In2.Cu")
		(net "M_F_CPU1_SA_CA<4>")
	)
	(segment
		(start 148.303742 -257.098292)
		(end 147.29968 -256.68224)
		(width 0.18288)
		(layer "In2.Cu")
		(net "M_F_CPU1_SA_CA<4>")
	)
	(segment
		(start 171.22648 -261.383526)
		(end 169.664126 -261.383526)
		(width 0.18288)
		(layer "In2.Cu")
		(net "M_F_CPU1_SA_CA<4>")
	)
	(segment
		(start 139.14374 -255.98628)
		(end 138.534648 -255.98628)
		(width 0.088646)
		(layer "In2.Cu")
		(net "M_F_CPU1_SA_CA<4>")
	)
	(segment
		(start 163.611052 -258.858766)
		(end 162.089592 -258.858766)
		(width 0.18288)
		(layer "In2.Cu")
		(net "M_F_CPU1_SA_CA<4>")
	)
	(segment
		(start 164.398198 -259.759958)
		(end 164.238178 -259.599938)
		(width 0.18288)
		(layer "In2.Cu")
		(net "M_F_CPU1_SA_CA<4>")
	)
	(segment
		(start 159.437324 -258.702556)
		(end 155.565602 -257.098292)
		(width 0.18288)
		(layer "In2.Cu")
		(net "M_F_CPU1_SA_CA<4>")
	)
	(segment
		(start 160.84677 -258.99237)
		(end 159.727138 -258.99237)
		(width 0.18288)
		(layer "In2.Cu")
		(net "M_F_CPU1_SA_CA<4>")
	)
	(segment
		(start 141.676374 -256.325116)
		(end 139.96035 -256.325116)
		(width 0.18288)
		(layer "In2.Cu")
		(net "M_F_CPU1_SA_CA<4>")
	)
	(segment
		(start 161.1249 -259.647182)
		(end 161.1249 -259.2705)
		(width 0.18288)
		(layer "In2.Cu")
		(net "M_F_CPU1_SA_CA<4>")
	)
	(segment
		(start 166.996872 -258.670806)
		(end 165.719506 -258.670806)
		(width 0.18288)
		(layer "In2.Cu")
		(net "M_F_CPU1_SA_CA<4>")
	)
	(segment
		(start 167.53586 -259.209794)
		(end 166.996872 -258.670806)
		(width 0.18288)
		(layer "In2.Cu")
		(net "M_F_CPU1_SA_CA<4>")
	)
	(segment
		(start 159.727138 -258.99237)
		(end 159.437324 -258.702556)
		(width 0.18288)
		(layer "In2.Cu")
		(net "M_F_CPU1_SA_CA<4>")
	)
	(segment
		(start 164.954966 -259.23748)
		(end 164.954966 -259.55117)
		(width 0.18288)
		(layer "In2.Cu")
		(net "M_F_CPU1_SA_CA<4>")
	)
	(segment
		(start 165.148006 -259.04444)
		(end 164.954966 -259.23748)
		(width 0.18288)
		(layer "In2.Cu")
		(net "M_F_CPU1_SA_CA<4>")
	)
	(segment
		(start 134.587996 -256.685796)
		(end 134.560056 -256.66954)
		(width 0.088646)
		(layer "In2.Cu")
		(net "M_F_CPU1_SA_CA<4>")
	)
	(segment
		(start 161.1249 -259.2705)
		(end 160.84677 -258.99237)
		(width 0.18288)
		(layer "In2.Cu")
		(net "M_F_CPU1_SA_CA<4>")
	)
	(segment
		(start 143.472662 -256.68224)
		(end 141.676374 -256.325116)
		(width 0.18288)
		(layer "In2.Cu")
		(net "M_F_CPU1_SA_CA<4>")
	)
	(segment
		(start 168.17594 -260.1341)
		(end 168.397428 -259.912612)
		(width 0.18288)
		(layer "In2.Cu")
		(net "M_F_CPU1_SA_CA<4>")
	)
	(segment
		(start 168.619678 -259.912612)
		(end 168.779698 -259.752592)
		(width 0.18288)
		(layer "In2.Cu")
		(net "M_F_CPU1_SA_CA<4>")
	)
	(segment
		(start 171.685712 -261.568184)
		(end 171.411138 -261.568184)
		(width 0.18288)
		(layer "In2.Cu")
		(net "M_F_CPU1_SA_CA<4>")
	)
	(segment
		(start 168.844976 -260.80212)
		(end 168.684956 -260.6421)
		(width 0.18288)
		(layer "In2.Cu")
		(net "M_F_CPU1_SA_CA<4>")
	)
	(segment
		(start 172.719746 -262.766556)
		(end 172.604176 -262.486648)
		(width 0.18288)
		(layer "In2.Cu")
		(net "M_F_CPU1_SA_CA<4>")
	)
	(segment
		(start 168.17594 -260.48208)
		(end 168.17594 -260.1341)
		(width 0.18288)
		(layer "In2.Cu")
		(net "M_F_CPU1_SA_CA<4>")
	)
	(segment
		(start 134.560056 -256.66954)
		(end 133.835394 -256.361438)
		(width 0.088646)
		(layer "In2.Cu")
		(net "M_F_CPU1_SA_CA<4>")
	)
	(segment
		(start 164.238178 -259.599938)
		(end 164.238178 -259.170424)
		(width 0.18288)
		(layer "In2.Cu")
		(net "M_F_CPU1_SA_CA<4>")
	)
	(segment
		(start 168.779698 -259.402834)
		(end 168.586658 -259.209794)
		(width 0.18288)
		(layer "In2.Cu")
		(net "M_F_CPU1_SA_CA<4>")
	)
	(segment
		(start 168.586658 -259.209794)
		(end 167.53586 -259.209794)
		(width 0.18288)
		(layer "In2.Cu")
		(net "M_F_CPU1_SA_CA<4>")
	)
	(segment
		(start 168.684956 -260.6421)
		(end 168.33596 -260.6421)
		(width 0.18288)
		(layer "In2.Cu")
		(net "M_F_CPU1_SA_CA<4>")
	)
	(segment
		(start 161.921952 -259.026406)
		(end 161.921952 -259.680202)
		(width 0.18288)
		(layer "In2.Cu")
		(net "M_F_CPU1_SA_CA<4>")
	)
	(segment
		(start 163.76269 -259.010404)
		(end 163.611052 -258.858766)
		(width 0.18288)
		(layer "In2.Cu")
		(net "M_F_CPU1_SA_CA<4>")
	)
	(segment
		(start 136.841992 -256.03708)
		(end 136.842246 -256.03708)
		(width 0.088646)
		(layer "In2.Cu")
		(net "M_F_CPU1_SA_CA<4>")
	)
	(segment
		(start 168.779698 -259.752592)
		(end 168.779698 -259.402834)
		(width 0.18288)
		(layer "In2.Cu")
		(net "M_F_CPU1_SA_CA<4>")
	)
	(segment
		(start 164.746178 -259.759958)
		(end 164.398198 -259.759958)
		(width 0.18288)
		(layer "In2.Cu")
		(net "M_F_CPU1_SA_CA<4>")
	)
	(segment
		(start 161.31794 -259.840222)
		(end 161.1249 -259.647182)
		(width 0.18288)
		(layer "In2.Cu")
		(net "M_F_CPU1_SA_CA<4>")
	)
	(segment
		(start 135.902446 -256.03708)
		(end 135.902192 -256.03708)
		(width 0.088646)
		(layer "In2.Cu")
		(net "M_F_CPU1_SA_CA<4>")
	)
	(segment
		(start 135.527796 -256.03708)
		(end 135.527542 -256.037334)
		(width 0.088646)
		(layer "In2.Cu")
		(net "M_F_CPU1_SA_CA<4>")
	)
	(segment
		(start 169.664126 -261.383526)
		(end 169.479468 -261.568184)
		(width 0.18288)
		(layer "In2.Cu")
		(net "M_F_CPU1_SA_CA<4>")
	)
	(segment
		(start 168.844976 -261.182104)
		(end 168.844976 -260.80212)
		(width 0.18288)
		(layer "In2.Cu")
		(net "M_F_CPU1_SA_CA<4>")
	)
	(segment
		(start 161.761932 -259.840222)
		(end 161.31794 -259.840222)
		(width 0.18288)
		(layer "In2.Cu")
		(net "M_F_CPU1_SA_CA<4>")
	)
	(segment
		(start 172.604176 -262.486648)
		(end 171.685712 -261.568184)
		(width 0.18288)
		(layer "In2.Cu")
		(net "M_F_CPU1_SA_CA<4>")
	)
	(segment
		(start 168.397428 -259.912612)
		(end 168.619678 -259.912612)
		(width 0.18288)
		(layer "In2.Cu")
		(net "M_F_CPU1_SA_CA<4>")
	)
	(segment
		(start 165.345872 -259.04444)
		(end 165.148006 -259.04444)
		(width 0.18288)
		(layer "In2.Cu")
		(net "M_F_CPU1_SA_CA<4>")
	)
	(segment
		(start 161.921952 -259.680202)
		(end 161.761932 -259.840222)
		(width 0.18288)
		(layer "In2.Cu")
		(net "M_F_CPU1_SA_CA<4>")
	)
	(segment
		(start 164.078158 -259.010404)
		(end 163.76269 -259.010404)
		(width 0.18288)
		(layer "In2.Cu")
		(net "M_F_CPU1_SA_CA<4>")
	)
	(segment
		(start 169.479468 -261.568184)
		(end 169.231056 -261.568184)
		(width 0.18288)
		(layer "In2.Cu")
		(net "M_F_CPU1_SA_CA<4>")
	)
	(segment
		(start 162.089592 -258.858766)
		(end 161.921952 -259.026406)
		(width 0.18288)
		(layer "In2.Cu")
		(net "M_F_CPU1_SA_CA<4>")
	)
	(segment
		(start 147.29968 -256.68224)
		(end 143.472662 -256.68224)
		(width 0.18288)
		(layer "In2.Cu")
		(net "M_F_CPU1_SA_CA<4>")
	)
	(segment
		(start 137.407396 -256.03708)
		(end 137.392664 -256.045716)
		(width 0.088646)
		(layer "In2.Cu")
		(net "M_F_CPU1_SA_CA<4>")
	)
	(segment
		(start 171.411138 -261.568184)
		(end 171.22648 -261.383526)
		(width 0.18288)
		(layer "In2.Cu")
		(net "M_F_CPU1_SA_CA<4>")
	)
	(segment
		(start 139.374626 -255.984756)
		(end 139.142216 -255.984756)
		(width 0.088646)
		(layer "In2.Cu")
		(net "M_F_CPU1_SA_CA<4>")
	)
	(segment
		(start 139.714986 -256.325116)
		(end 139.374626 -255.984756)
		(width 0.088646)
		(layer "In2.Cu")
		(net "M_F_CPU1_SA_CA<4>")
	)
	(segment
		(start 168.33596 -260.6421)
		(end 168.17594 -260.48208)
		(width 0.18288)
		(layer "In2.Cu")
		(net "M_F_CPU1_SA_CA<4>")
	)
	(segment
		(start 155.565602 -257.098292)
		(end 148.303742 -257.098292)
		(width 0.18288)
		(layer "In2.Cu")
		(net "M_F_CPU1_SA_CA<4>")
	)
	(segment
		(start 169.231056 -261.568184)
		(end 168.844976 -261.182104)
		(width 0.18288)
		(layer "In2.Cu")
		(net "M_F_CPU1_SA_CA<4>")
	)
	(segment
		(start 164.954966 -259.55117)
		(end 164.746178 -259.759958)
		(width 0.18288)
		(layer "In2.Cu")
		(net "M_F_CPU1_SA_CA<4>")
	)
	(segment
		(start 135.248396 -256.520442)
		(end 134.962392 -256.685796)
		(width 0.088646)
		(layer "In2.Cu")
		(net "M_F_CPU1_SA_CA<4>")
	)
	(segment
		(start 165.719506 -258.670806)
		(end 165.345872 -259.04444)
		(width 0.18288)
		(layer "In2.Cu")
		(net "M_F_CPU1_SA_CA<4>")
	)
	(segment
		(start 139.96035 -256.325116)
		(end 139.714986 -256.325116)
		(width 0.088646)
		(layer "In2.Cu")
		(net "M_F_CPU1_SA_CA<4>")
	)
	(arc
		(start 136.842246 -256.03708)
		(mid 136.655048 -255.986937)
		(end 136.46785 -256.03708)
		(width 0.088646)
		(layer "In2.Cu")
		(net "M_F_CPU1_SA_CA<4>")
	)
	(arc
		(start 135.340344 -256.361438)
		(mid 135.315696 -256.453267)
		(end 135.248396 -256.520442)
		(width 0.088646)
		(layer "In2.Cu")
		(net "M_F_CPU1_SA_CA<4>")
	)
	(arc
		(start 135.902192 -256.03708)
		(mid 135.714994 -255.986937)
		(end 135.527796 -256.03708)
		(width 0.088646)
		(layer "In2.Cu")
		(net "M_F_CPU1_SA_CA<4>")
	)
	(arc
		(start 138.534648 -255.98628)
		(mid 138.437573 -255.999329)
		(end 138.347196 -256.03708)
		(width 0.088646)
		(layer "In2.Cu")
		(net "M_F_CPU1_SA_CA<4>")
	)
	(arc
		(start 138.332464 -256.045716)
		(mid 138.056023 -256.112882)
		(end 137.781792 -256.03708)
		(width 0.088646)
		(layer "In2.Cu")
		(net "M_F_CPU1_SA_CA<4>")
	)
	(arc
		(start 134.962392 -256.685796)
		(mid 134.775194 -256.735973)
		(end 134.587996 -256.685796)
		(width 0.088646)
		(layer "In2.Cu")
		(net "M_F_CPU1_SA_CA<4>")
	)
	(arc
		(start 137.781792 -256.03708)
		(mid 137.594594 -255.986937)
		(end 137.407396 -256.03708)
		(width 0.088646)
		(layer "In2.Cu")
		(net "M_F_CPU1_SA_CA<4>")
	)
	(arc
		(start 136.46785 -256.03708)
		(mid 136.185148 -256.112856)
		(end 135.902446 -256.03708)
		(width 0.088646)
		(layer "In2.Cu")
		(net "M_F_CPU1_SA_CA<4>")
	)
	(arc
		(start 135.527542 -256.037334)
		(mid 135.390497 -256.174294)
		(end 135.340344 -256.361438)
		(width 0.088646)
		(layer "In2.Cu")
		(net "M_F_CPU1_SA_CA<4>")
	)
	(arc
		(start 137.392664 -256.045716)
		(mid 137.116223 -256.112882)
		(end 136.841992 -256.03708)
		(width 0.088646)
		(layer "In2.Cu")
		(net "M_F_CPU1_SA_CA<4>")
	)
	(segment
		(start 184.430162 -263.616694)
		(end 185.544714 -263.616694)
		(width 0.20066)
		(layer "F.Cu")
		(net "M_F_CPU1_SA_CA<3>")
	)
	(segment
		(start 180.072284 -264.052304)
		(end 180.423058 -264.052304)
		(width 0.20066)
		(layer "F.Cu")
		(net "M_F_CPU1_SA_CA<3>")
	)
	(segment
		(start 179.636674 -263.616694)
		(end 180.072284 -264.052304)
		(width 0.20066)
		(layer "F.Cu")
		(net "M_F_CPU1_SA_CA<3>")
	)
	(segment
		(start 178.000914 -263.616694)
		(end 179.636674 -263.616694)
		(width 0.20066)
		(layer "F.Cu")
		(net "M_F_CPU1_SA_CA<3>")
	)
	(segment
		(start 183.593994 -263.184132)
		(end 183.9976 -263.184132)
		(width 0.20066)
		(layer "F.Cu")
		(net "M_F_CPU1_SA_CA<3>")
	)
	(segment
		(start 176.819814 -263.616694)
		(end 178.000914 -263.616694)
		(width 0.20066)
		(layer "F.Cu")
		(net "M_F_CPU1_SA_CA<3>")
	)
	(segment
		(start 182.729124 -264.049002)
		(end 183.593994 -263.184132)
		(width 0.20066)
		(layer "F.Cu")
		(net "M_F_CPU1_SA_CA<3>")
	)
	(segment
		(start 182.455058 -264.049002)
		(end 182.729124 -264.049002)
		(width 0.20066)
		(layer "F.Cu")
		(net "M_F_CPU1_SA_CA<3>")
	)
	(segment
		(start 182.447692 -264.041636)
		(end 182.455058 -264.049002)
		(width 0.1016)
		(layer "F.Cu")
		(net "M_F_CPU1_SA_CA<3>")
	)
	(segment
		(start 135.245094 -257.175254)
		(end 135.245094 -256.639314)
		(width 0.20066)
		(layer "F.Cu")
		(net "M_F_CPU1_SA_CA<3>")
	)
	(segment
		(start 180.438552 -264.041636)
		(end 182.447692 -264.041636)
		(width 0.1016)
		(layer "F.Cu")
		(net "M_F_CPU1_SA_CA<3>")
	)
	(segment
		(start 180.423058 -264.052304)
		(end 180.427884 -264.052304)
		(width 0.101854)
		(layer "F.Cu")
		(net "M_F_CPU1_SA_CA<3>")
	)
	(segment
		(start 183.9976 -263.184132)
		(end 184.430162 -263.616694)
		(width 0.20066)
		(layer "F.Cu")
		(net "M_F_CPU1_SA_CA<3>")
	)
	(segment
		(start 180.427884 -264.052304)
		(end 180.438552 -264.041636)
		(width 0.1016)
		(layer "F.Cu")
		(net "M_F_CPU1_SA_CA<3>")
	)
	(segment
		(start 135.68045 -257.015742)
		(end 135.308848 -257.116072)
		(width 0.088646)
		(layer "In2.Cu")
		(net "M_F_CPU1_SA_CA<3>")
	)
	(segment
		(start 148.20519 -257.55854)
		(end 146.942556 -257.035554)
		(width 0.18288)
		(layer "In2.Cu")
		(net "M_F_CPU1_SA_CA<3>")
	)
	(segment
		(start 174.038768 -263.904222)
		(end 173.690788 -263.904222)
		(width 0.18288)
		(layer "In2.Cu")
		(net "M_F_CPU1_SA_CA<3>")
	)
	(segment
		(start 165.39972 -260.693916)
		(end 164.96284 -260.693916)
		(width 0.18288)
		(layer "In2.Cu")
		(net "M_F_CPU1_SA_CA<3>")
	)
	(segment
		(start 173.690788 -263.904222)
		(end 173.530768 -263.744202)
		(width 0.18288)
		(layer "In2.Cu")
		(net "M_F_CPU1_SA_CA<3>")
	)
	(segment
		(start 163.921694 -260.506464)
		(end 163.792154 -260.636004)
		(width 0.18288)
		(layer "In2.Cu")
		(net "M_F_CPU1_SA_CA<3>")
	)
	(segment
		(start 164.775388 -260.506464)
		(end 163.921694 -260.506464)
		(width 0.18288)
		(layer "In2.Cu")
		(net "M_F_CPU1_SA_CA<3>")
	)
	(segment
		(start 139.520676 -257.035554)
		(end 139.346178 -256.91211)
		(width 0.088646)
		(layer "In2.Cu")
		(net "M_F_CPU1_SA_CA<3>")
	)
	(segment
		(start 175.804322 -261.781036)
		(end 175.616616 -261.968742)
		(width 0.18288)
		(layer "In2.Cu")
		(net "M_F_CPU1_SA_CA<3>")
	)
	(segment
		(start 161.386774 -260.636004)
		(end 161.064194 -260.313424)
		(width 0.18288)
		(layer "In2.Cu")
		(net "M_F_CPU1_SA_CA<3>")
	)
	(segment
		(start 165.969696 -260.12394)
		(end 165.39972 -260.693916)
		(width 0.18288)
		(layer "In2.Cu")
		(net "M_F_CPU1_SA_CA<3>")
	)
	(segment
		(start 176.819814 -263.616694)
		(end 176.35728 -263.15416)
		(width 0.18288)
		(layer "In2.Cu")
		(net "M_F_CPU1_SA_CA<3>")
	)
	(segment
		(start 172.401738 -263.191244)
		(end 171.995592 -262.785098)
		(width 0.18288)
		(layer "In2.Cu")
		(net "M_F_CPU1_SA_CA<3>")
	)
	(segment
		(start 174.418752 -263.191244)
		(end 174.258732 -263.351264)
		(width 0.18288)
		(layer "In2.Cu")
		(net "M_F_CPU1_SA_CA<3>")
	)
	(segment
		(start 174.785274 -263.191244)
		(end 174.418752 -263.191244)
		(width 0.18288)
		(layer "In2.Cu")
		(net "M_F_CPU1_SA_CA<3>")
	)
	(segment
		(start 140.90015 -257.035554)
		(end 139.520676 -257.035554)
		(width 0.088646)
		(layer "In2.Cu")
		(net "M_F_CPU1_SA_CA<3>")
	)
	(segment
		(start 135.255 -257.157728)
		(end 135.245094 -257.175254)
		(width 0.088646)
		(layer "In2.Cu")
		(net "M_F_CPU1_SA_CA<3>")
	)
	(segment
		(start 146.942556 -257.035554)
		(end 140.90015 -257.035554)
		(width 0.18288)
		(layer "In2.Cu")
		(net "M_F_CPU1_SA_CA<3>")
	)
	(segment
		(start 155.143454 -257.652774)
		(end 148.299424 -257.652774)
		(width 0.18288)
		(layer "In2.Cu")
		(net "M_F_CPU1_SA_CA<3>")
	)
	(segment
		(start 157.903672 -259.74294)
		(end 156.287216 -258.126484)
		(width 0.18288)
		(layer "In2.Cu")
		(net "M_F_CPU1_SA_CA<3>")
	)
	(segment
		(start 173.370748 -263.191244)
		(end 172.401738 -263.191244)
		(width 0.18288)
		(layer "In2.Cu")
		(net "M_F_CPU1_SA_CA<3>")
	)
	(segment
		(start 169.227246 -262.311642)
		(end 167.617394 -260.70179)
		(width 0.18288)
		(layer "In2.Cu")
		(net "M_F_CPU1_SA_CA<3>")
	)
	(segment
		(start 135.997696 -256.850896)
		(end 135.797036 -256.967228)
		(width 0.088646)
		(layer "In2.Cu")
		(net "M_F_CPU1_SA_CA<3>")
	)
	(segment
		(start 174.258732 -263.684258)
		(end 174.038768 -263.904222)
		(width 0.18288)
		(layer "In2.Cu")
		(net "M_F_CPU1_SA_CA<3>")
	)
	(segment
		(start 173.530768 -263.744202)
		(end 173.530768 -263.351264)
		(width 0.18288)
		(layer "In2.Cu")
		(net "M_F_CPU1_SA_CA<3>")
	)
	(segment
		(start 171.995592 -262.785098)
		(end 171.995592 -262.596884)
		(width 0.18288)
		(layer "In2.Cu")
		(net "M_F_CPU1_SA_CA<3>")
	)
	(segment
		(start 175.616616 -262.359902)
		(end 174.785274 -263.191244)
		(width 0.18288)
		(layer "In2.Cu")
		(net "M_F_CPU1_SA_CA<3>")
	)
	(segment
		(start 175.616616 -261.968742)
		(end 175.616616 -262.359902)
		(width 0.18288)
		(layer "In2.Cu")
		(net "M_F_CPU1_SA_CA<3>")
	)
	(segment
		(start 148.299424 -257.652774)
		(end 148.20519 -257.55854)
		(width 0.18288)
		(layer "In2.Cu")
		(net "M_F_CPU1_SA_CA<3>")
	)
	(segment
		(start 156.287216 -258.126484)
		(end 155.143454 -257.652774)
		(width 0.18288)
		(layer "In2.Cu")
		(net "M_F_CPU1_SA_CA<3>")
	)
	(segment
		(start 176.35728 -261.941056)
		(end 176.19726 -261.781036)
		(width 0.18288)
		(layer "In2.Cu")
		(net "M_F_CPU1_SA_CA<3>")
	)
	(segment
		(start 166.688008 -260.12394)
		(end 165.969696 -260.12394)
		(width 0.18288)
		(layer "In2.Cu")
		(net "M_F_CPU1_SA_CA<3>")
	)
	(segment
		(start 161.064194 -260.313424)
		(end 160.692592 -260.313424)
		(width 0.18288)
		(layer "In2.Cu")
		(net "M_F_CPU1_SA_CA<3>")
	)
	(segment
		(start 164.96284 -260.693916)
		(end 164.775388 -260.506464)
		(width 0.18288)
		(layer "In2.Cu")
		(net "M_F_CPU1_SA_CA<3>")
	)
	(segment
		(start 171.995592 -262.596884)
		(end 171.71035 -262.311642)
		(width 0.18288)
		(layer "In2.Cu")
		(net "M_F_CPU1_SA_CA<3>")
	)
	(segment
		(start 167.617394 -260.70179)
		(end 167.265858 -260.70179)
		(width 0.18288)
		(layer "In2.Cu")
		(net "M_F_CPU1_SA_CA<3>")
	)
	(segment
		(start 160.122108 -259.74294)
		(end 157.903672 -259.74294)
		(width 0.18288)
		(layer "In2.Cu")
		(net "M_F_CPU1_SA_CA<3>")
	)
	(segment
		(start 174.258732 -263.351264)
		(end 174.258732 -263.684258)
		(width 0.18288)
		(layer "In2.Cu")
		(net "M_F_CPU1_SA_CA<3>")
	)
	(segment
		(start 171.71035 -262.311642)
		(end 169.227246 -262.311642)
		(width 0.18288)
		(layer "In2.Cu")
		(net "M_F_CPU1_SA_CA<3>")
	)
	(segment
		(start 167.265858 -260.70179)
		(end 166.688008 -260.12394)
		(width 0.18288)
		(layer "In2.Cu")
		(net "M_F_CPU1_SA_CA<3>")
	)
	(segment
		(start 176.19726 -261.781036)
		(end 175.804322 -261.781036)
		(width 0.18288)
		(layer "In2.Cu")
		(net "M_F_CPU1_SA_CA<3>")
	)
	(segment
		(start 163.792154 -260.636004)
		(end 161.386774 -260.636004)
		(width 0.18288)
		(layer "In2.Cu")
		(net "M_F_CPU1_SA_CA<3>")
	)
	(segment
		(start 176.35728 -263.15416)
		(end 176.35728 -261.941056)
		(width 0.18288)
		(layer "In2.Cu")
		(net "M_F_CPU1_SA_CA<3>")
	)
	(segment
		(start 160.692592 -260.313424)
		(end 160.122108 -259.74294)
		(width 0.18288)
		(layer "In2.Cu")
		(net "M_F_CPU1_SA_CA<3>")
	)
	(segment
		(start 173.530768 -263.351264)
		(end 173.370748 -263.191244)
		(width 0.18288)
		(layer "In2.Cu")
		(net "M_F_CPU1_SA_CA<3>")
	)
	(arc
		(start 136.372092 -256.850896)
		(mid 136.184894 -256.800753)
		(end 135.997696 -256.850896)
		(width 0.088646)
		(layer "In2.Cu")
		(net "M_F_CPU1_SA_CA<3>")
	)
	(arc
		(start 135.797036 -256.967228)
		(mid 135.740328 -256.995291)
		(end 135.68045 -257.015742)
		(width 0.088646)
		(layer "In2.Cu")
		(net "M_F_CPU1_SA_CA<3>")
	)
	(arc
		(start 136.937496 -256.850896)
		(mid 136.654794 -256.926672)
		(end 136.372092 -256.850896)
		(width 0.088646)
		(layer "In2.Cu")
		(net "M_F_CPU1_SA_CA<3>")
	)
	(arc
		(start 139.346178 -256.91211)
		(mid 139.26658 -256.887205)
		(end 139.191492 -256.850896)
		(width 0.088646)
		(layer "In2.Cu")
		(net "M_F_CPU1_SA_CA<3>")
	)
	(arc
		(start 135.308848 -257.116072)
		(mid 135.27775 -257.131511)
		(end 135.255 -257.157728)
		(width 0.088646)
		(layer "In2.Cu")
		(net "M_F_CPU1_SA_CA<3>")
	)
	(arc
		(start 139.191492 -256.850896)
		(mid 139.004294 -256.800753)
		(end 138.817096 -256.850896)
		(width 0.088646)
		(layer "In2.Cu")
		(net "M_F_CPU1_SA_CA<3>")
	)
	(arc
		(start 138.817096 -256.850896)
		(mid 138.534394 -256.926672)
		(end 138.251692 -256.850896)
		(width 0.088646)
		(layer "In2.Cu")
		(net "M_F_CPU1_SA_CA<3>")
	)
	(arc
		(start 137.311892 -256.850896)
		(mid 137.124694 -256.800753)
		(end 136.937496 -256.850896)
		(width 0.088646)
		(layer "In2.Cu")
		(net "M_F_CPU1_SA_CA<3>")
	)
	(arc
		(start 138.251692 -256.850896)
		(mid 138.064494 -256.800753)
		(end 137.877296 -256.850896)
		(width 0.088646)
		(layer "In2.Cu")
		(net "M_F_CPU1_SA_CA<3>")
	)
	(arc
		(start 137.877296 -256.850896)
		(mid 137.594594 -256.926672)
		(end 137.311892 -256.850896)
		(width 0.088646)
		(layer "In2.Cu")
		(net "M_F_CPU1_SA_CA<3>")
	)
	(segment
		(start 174.821088 -264.466578)
		(end 175.291242 -263.996424)
		(width 0.20066)
		(layer "F.Cu")
		(net "M_F_CPU1_SA_CA<2>")
	)
	(segment
		(start 181.444392 -264.466324)
		(end 181.444646 -264.466578)
		(width 0.20066)
		(layer "F.Cu")
		(net "M_F_CPU1_SA_CA<2>")
	)
	(segment
		(start 173.900846 -264.466578)
		(end 174.821088 -264.466578)
		(width 0.20066)
		(layer "F.Cu")
		(net "M_F_CPU1_SA_CA<2>")
	)
	(segment
		(start 179.86502 -264.466324)
		(end 181.444392 -264.466324)
		(width 0.20066)
		(layer "F.Cu")
		(net "M_F_CPU1_SA_CA<2>")
	)
	(segment
		(start 172.719746 -264.466578)
		(end 173.900846 -264.466578)
		(width 0.20066)
		(layer "F.Cu")
		(net "M_F_CPU1_SA_CA<2>")
	)
	(segment
		(start 178.99888 -264.89152)
		(end 179.011326 -264.903966)
		(width 0.1016)
		(layer "F.Cu")
		(net "M_F_CPU1_SA_CA<2>")
	)
	(segment
		(start 176.470564 -264.89152)
		(end 176.691036 -264.89152)
		(width 0.20066)
		(layer "F.Cu")
		(net "M_F_CPU1_SA_CA<2>")
	)
	(segment
		(start 176.691036 -264.89152)
		(end 176.733454 -264.89152)
		(width 0.101854)
		(layer "F.Cu")
		(net "M_F_CPU1_SA_CA<2>")
	)
	(segment
		(start 133.365494 -256.639314)
		(end 133.365494 -257.175)
		(width 0.20066)
		(layer "F.Cu")
		(net "M_F_CPU1_SA_CA<2>")
	)
	(segment
		(start 176.733454 -264.89152)
		(end 178.99888 -264.89152)
		(width 0.1016)
		(layer "F.Cu")
		(net "M_F_CPU1_SA_CA<2>")
	)
	(segment
		(start 179.427378 -264.903966)
		(end 179.86502 -264.466324)
		(width 0.20066)
		(layer "F.Cu")
		(net "M_F_CPU1_SA_CA<2>")
	)
	(segment
		(start 133.365494 -257.175)
		(end 133.365748 -257.175254)
		(width 0.20066)
		(layer "F.Cu")
		(net "M_F_CPU1_SA_CA<2>")
	)
	(segment
		(start 175.575468 -263.996424)
		(end 176.470564 -264.89152)
		(width 0.20066)
		(layer "F.Cu")
		(net "M_F_CPU1_SA_CA<2>")
	)
	(segment
		(start 175.291242 -263.996424)
		(end 175.575468 -263.996424)
		(width 0.20066)
		(layer "F.Cu")
		(net "M_F_CPU1_SA_CA<2>")
	)
	(segment
		(start 179.011326 -264.903966)
		(end 179.427378 -264.903966)
		(width 0.20066)
		(layer "F.Cu")
		(net "M_F_CPU1_SA_CA<2>")
	)
	(segment
		(start 160.974024 -261.409434)
		(end 160.974024 -260.950964)
		(width 0.18288)
		(layer "In2.Cu")
		(net "M_F_CPU1_SA_CA<2>")
	)
	(segment
		(start 159.334708 -260.273292)
		(end 158.288228 -260.273292)
		(width 0.18288)
		(layer "In2.Cu")
		(net "M_F_CPU1_SA_CA<2>")
	)
	(segment
		(start 164.549074 -261.325106)
		(end 164.549074 -261.601712)
		(width 0.18288)
		(layer "In2.Cu")
		(net "M_F_CPU1_SA_CA<2>")
	)
	(segment
		(start 136.937496 -257.499612)
		(end 136.922764 -257.490976)
		(width 0.088646)
		(layer "In2.Cu")
		(net "M_F_CPU1_SA_CA<2>")
	)
	(segment
		(start 164.549074 -261.601712)
		(end 164.389054 -261.761732)
		(width 0.18288)
		(layer "In2.Cu")
		(net "M_F_CPU1_SA_CA<2>")
	)
	(segment
		(start 157.080204 -260.391402)
		(end 157.080204 -260.165342)
		(width 0.18288)
		(layer "In2.Cu")
		(net "M_F_CPU1_SA_CA<2>")
	)
	(segment
		(start 161.976308 -261.561072)
		(end 161.125662 -261.561072)
		(width 0.18288)
		(layer "In2.Cu")
		(net "M_F_CPU1_SA_CA<2>")
	)
	(segment
		(start 160.860486 -260.837426)
		(end 159.898842 -260.837426)
		(width 0.18288)
		(layer "In2.Cu")
		(net "M_F_CPU1_SA_CA<2>")
	)
	(segment
		(start 164.650928 -261.223252)
		(end 164.549074 -261.325106)
		(width 0.18288)
		(layer "In2.Cu")
		(net "M_F_CPU1_SA_CA<2>")
	)
	(segment
		(start 156.278834 -259.076698)
		(end 156.278834 -258.850638)
		(width 0.18288)
		(layer "In2.Cu")
		(net "M_F_CPU1_SA_CA<2>")
	)
	(segment
		(start 169.991024 -262.833612)
		(end 169.539412 -263.285224)
		(width 0.18288)
		(layer "In2.Cu")
		(net "M_F_CPU1_SA_CA<2>")
	)
	(segment
		(start 165.80866 -261.832852)
		(end 165.19906 -261.223252)
		(width 0.18288)
		(layer "In2.Cu")
		(net "M_F_CPU1_SA_CA<2>")
	)
	(segment
		(start 166.896542 -261.832852)
		(end 165.80866 -261.832852)
		(width 0.18288)
		(layer "In2.Cu")
		(net "M_F_CPU1_SA_CA<2>")
	)
	(segment
		(start 137.877296 -257.499612)
		(end 137.862564 -257.490976)
		(width 0.088646)
		(layer "In2.Cu")
		(net "M_F_CPU1_SA_CA<2>")
	)
	(segment
		(start 172.398182 -263.878568)
		(end 172.297598 -263.878568)
		(width 0.18288)
		(layer "In2.Cu")
		(net "M_F_CPU1_SA_CA<2>")
	)
	(segment
		(start 140.90015 -257.407918)
		(end 139.391644 -257.407918)
		(width 0.088646)
		(layer "In2.Cu")
		(net "M_F_CPU1_SA_CA<2>")
	)
	(segment
		(start 139.206478 -257.484626)
		(end 139.191492 -257.499612)
		(width 0.088646)
		(layer "In2.Cu")
		(net "M_F_CPU1_SA_CA<2>")
	)
	(segment
		(start 156.381704 -259.692902)
		(end 156.135324 -259.446522)
		(width 0.18288)
		(layer "In2.Cu")
		(net "M_F_CPU1_SA_CA<2>")
	)
	(segment
		(start 133.636004 -257.175254)
		(end 133.365748 -257.175254)
		(width 0.088646)
		(layer "In2.Cu")
		(net "M_F_CPU1_SA_CA<2>")
	)
	(segment
		(start 157.381448 -260.692646)
		(end 157.080204 -260.391402)
		(width 0.18288)
		(layer "In2.Cu")
		(net "M_F_CPU1_SA_CA<2>")
	)
	(segment
		(start 156.278834 -258.850638)
		(end 156.001974 -258.573778)
		(width 0.18288)
		(layer "In2.Cu")
		(net "M_F_CPU1_SA_CA<2>")
	)
	(segment
		(start 156.001974 -258.573778)
		(end 155.02763 -258.170172)
		(width 0.18288)
		(layer "In2.Cu")
		(net "M_F_CPU1_SA_CA<2>")
	)
	(segment
		(start 157.223714 -259.795518)
		(end 156.977334 -259.549138)
		(width 0.18288)
		(layer "In2.Cu")
		(net "M_F_CPU1_SA_CA<2>")
	)
	(segment
		(start 170.970448 -262.833612)
		(end 169.991024 -262.833612)
		(width 0.18288)
		(layer "In2.Cu")
		(net "M_F_CPU1_SA_CA<2>")
	)
	(segment
		(start 167.326056 -261.403338)
		(end 166.896542 -261.832852)
		(width 0.18288)
		(layer "In2.Cu")
		(net "M_F_CPU1_SA_CA<2>")
	)
	(segment
		(start 162.332924 -261.204456)
		(end 161.976308 -261.561072)
		(width 0.18288)
		(layer "In2.Cu")
		(net "M_F_CPU1_SA_CA<2>")
	)
	(segment
		(start 156.751274 -259.549138)
		(end 156.607764 -259.692902)
		(width 0.18288)
		(layer "In2.Cu")
		(net "M_F_CPU1_SA_CA<2>")
	)
	(segment
		(start 164.389054 -261.761732)
		(end 164.037772 -261.761732)
		(width 0.18288)
		(layer "In2.Cu")
		(net "M_F_CPU1_SA_CA<2>")
	)
	(segment
		(start 134.118096 -257.499612)
		(end 133.736842 -257.276092)
		(width 0.088646)
		(layer "In2.Cu")
		(net "M_F_CPU1_SA_CA<2>")
	)
	(segment
		(start 158.288228 -260.273292)
		(end 157.868874 -260.692646)
		(width 0.18288)
		(layer "In2.Cu")
		(net "M_F_CPU1_SA_CA<2>")
	)
	(segment
		(start 167.599106 -261.403338)
		(end 167.326056 -261.403338)
		(width 0.18288)
		(layer "In2.Cu")
		(net "M_F_CPU1_SA_CA<2>")
	)
	(segment
		(start 133.736842 -257.276092)
		(end 133.636004 -257.175254)
		(width 0.088646)
		(layer "In2.Cu")
		(net "M_F_CPU1_SA_CA<2>")
	)
	(segment
		(start 157.223714 -260.021578)
		(end 157.223714 -259.795518)
		(width 0.18288)
		(layer "In2.Cu")
		(net "M_F_CPU1_SA_CA<2>")
	)
	(segment
		(start 163.480496 -261.204456)
		(end 162.332924 -261.204456)
		(width 0.18288)
		(layer "In2.Cu")
		(net "M_F_CPU1_SA_CA<2>")
	)
	(segment
		(start 168.053766 -262.072882)
		(end 168.053766 -261.857998)
		(width 0.18288)
		(layer "In2.Cu")
		(net "M_F_CPU1_SA_CA<2>")
	)
	(segment
		(start 157.080204 -260.165342)
		(end 157.223714 -260.021578)
		(width 0.18288)
		(layer "In2.Cu")
		(net "M_F_CPU1_SA_CA<2>")
	)
	(segment
		(start 146.75739 -257.407918)
		(end 140.90015 -257.407918)
		(width 0.18288)
		(layer "In2.Cu")
		(net "M_F_CPU1_SA_CA<2>")
	)
	(segment
		(start 164.037772 -261.761732)
		(end 163.480496 -261.204456)
		(width 0.18288)
		(layer "In2.Cu")
		(net "M_F_CPU1_SA_CA<2>")
	)
	(segment
		(start 148.14423 -257.982212)
		(end 146.75739 -257.407918)
		(width 0.18288)
		(layer "In2.Cu")
		(net "M_F_CPU1_SA_CA<2>")
	)
	(segment
		(start 139.391644 -257.407918)
		(end 139.206478 -257.484626)
		(width 0.088646)
		(layer "In2.Cu")
		(net "M_F_CPU1_SA_CA<2>")
	)
	(segment
		(start 156.607764 -259.692902)
		(end 156.381704 -259.692902)
		(width 0.18288)
		(layer "In2.Cu")
		(net "M_F_CPU1_SA_CA<2>")
	)
	(segment
		(start 171.923202 -263.504172)
		(end 171.641008 -263.504172)
		(width 0.18288)
		(layer "In2.Cu")
		(net "M_F_CPU1_SA_CA<2>")
	)
	(segment
		(start 156.135324 -259.446522)
		(end 156.135324 -259.220462)
		(width 0.18288)
		(layer "In2.Cu")
		(net "M_F_CPU1_SA_CA<2>")
	)
	(segment
		(start 159.898842 -260.837426)
		(end 159.334708 -260.273292)
		(width 0.18288)
		(layer "In2.Cu")
		(net "M_F_CPU1_SA_CA<2>")
	)
	(segment
		(start 165.19906 -261.223252)
		(end 164.650928 -261.223252)
		(width 0.18288)
		(layer "In2.Cu")
		(net "M_F_CPU1_SA_CA<2>")
	)
	(segment
		(start 161.125662 -261.561072)
		(end 160.974024 -261.409434)
		(width 0.18288)
		(layer "In2.Cu")
		(net "M_F_CPU1_SA_CA<2>")
	)
	(segment
		(start 156.977334 -259.549138)
		(end 156.751274 -259.549138)
		(width 0.18288)
		(layer "In2.Cu")
		(net "M_F_CPU1_SA_CA<2>")
	)
	(segment
		(start 148.33219 -258.170172)
		(end 148.14423 -257.982212)
		(width 0.18288)
		(layer "In2.Cu")
		(net "M_F_CPU1_SA_CA<2>")
	)
	(segment
		(start 172.719746 -264.200132)
		(end 172.398182 -263.878568)
		(width 0.18288)
		(layer "In2.Cu")
		(net "M_F_CPU1_SA_CA<2>")
	)
	(segment
		(start 155.02763 -258.170172)
		(end 148.33219 -258.170172)
		(width 0.18288)
		(layer "In2.Cu")
		(net "M_F_CPU1_SA_CA<2>")
	)
	(segment
		(start 171.641008 -263.504172)
		(end 170.970448 -262.833612)
		(width 0.18288)
		(layer "In2.Cu")
		(net "M_F_CPU1_SA_CA<2>")
	)
	(segment
		(start 169.539412 -263.285224)
		(end 169.266108 -263.285224)
		(width 0.18288)
		(layer "In2.Cu")
		(net "M_F_CPU1_SA_CA<2>")
	)
	(segment
		(start 160.974024 -260.950964)
		(end 160.860486 -260.837426)
		(width 0.18288)
		(layer "In2.Cu")
		(net "M_F_CPU1_SA_CA<2>")
	)
	(segment
		(start 135.057896 -257.499612)
		(end 135.043164 -257.490976)
		(width 0.088646)
		(layer "In2.Cu")
		(net "M_F_CPU1_SA_CA<2>")
	)
	(segment
		(start 168.053766 -261.857998)
		(end 167.599106 -261.403338)
		(width 0.18288)
		(layer "In2.Cu")
		(net "M_F_CPU1_SA_CA<2>")
	)
	(segment
		(start 157.868874 -260.692646)
		(end 157.381448 -260.692646)
		(width 0.18288)
		(layer "In2.Cu")
		(net "M_F_CPU1_SA_CA<2>")
	)
	(segment
		(start 172.719746 -264.466578)
		(end 172.719746 -264.200132)
		(width 0.18288)
		(layer "In2.Cu")
		(net "M_F_CPU1_SA_CA<2>")
	)
	(segment
		(start 156.135324 -259.220462)
		(end 156.278834 -259.076698)
		(width 0.18288)
		(layer "In2.Cu")
		(net "M_F_CPU1_SA_CA<2>")
	)
	(segment
		(start 172.297598 -263.878568)
		(end 171.923202 -263.504172)
		(width 0.18288)
		(layer "In2.Cu")
		(net "M_F_CPU1_SA_CA<2>")
	)
	(segment
		(start 169.266108 -263.285224)
		(end 168.053766 -262.072882)
		(width 0.18288)
		(layer "In2.Cu")
		(net "M_F_CPU1_SA_CA<2>")
	)
	(segment
		(start 138.817096 -257.499612)
		(end 138.802364 -257.490976)
		(width 0.088646)
		(layer "In2.Cu")
		(net "M_F_CPU1_SA_CA<2>")
	)
	(arc
		(start 137.311892 -257.499612)
		(mid 137.124694 -257.549755)
		(end 136.937496 -257.499612)
		(width 0.088646)
		(layer "In2.Cu")
		(net "M_F_CPU1_SA_CA<2>")
	)
	(arc
		(start 136.372092 -257.499612)
		(mid 136.184894 -257.549755)
		(end 135.997696 -257.499612)
		(width 0.088646)
		(layer "In2.Cu")
		(net "M_F_CPU1_SA_CA<2>")
	)
	(arc
		(start 136.922764 -257.490976)
		(mid 136.646289 -257.423656)
		(end 136.372092 -257.499612)
		(width 0.088646)
		(layer "In2.Cu")
		(net "M_F_CPU1_SA_CA<2>")
	)
	(arc
		(start 135.997696 -257.499612)
		(mid 135.714994 -257.423836)
		(end 135.432292 -257.499612)
		(width 0.088646)
		(layer "In2.Cu")
		(net "M_F_CPU1_SA_CA<2>")
	)
	(arc
		(start 138.251692 -257.499612)
		(mid 138.064494 -257.549755)
		(end 137.877296 -257.499612)
		(width 0.088646)
		(layer "In2.Cu")
		(net "M_F_CPU1_SA_CA<2>")
	)
	(arc
		(start 139.191492 -257.499612)
		(mid 139.004294 -257.549755)
		(end 138.817096 -257.499612)
		(width 0.088646)
		(layer "In2.Cu")
		(net "M_F_CPU1_SA_CA<2>")
	)
	(arc
		(start 135.432292 -257.499612)
		(mid 135.245094 -257.549755)
		(end 135.057896 -257.499612)
		(width 0.088646)
		(layer "In2.Cu")
		(net "M_F_CPU1_SA_CA<2>")
	)
	(arc
		(start 137.862564 -257.490976)
		(mid 137.586089 -257.423656)
		(end 137.311892 -257.499612)
		(width 0.088646)
		(layer "In2.Cu")
		(net "M_F_CPU1_SA_CA<2>")
	)
	(arc
		(start 135.043164 -257.490976)
		(mid 134.766689 -257.423656)
		(end 134.492492 -257.499612)
		(width 0.088646)
		(layer "In2.Cu")
		(net "M_F_CPU1_SA_CA<2>")
	)
	(arc
		(start 134.492492 -257.499612)
		(mid 134.305294 -257.549755)
		(end 134.118096 -257.499612)
		(width 0.088646)
		(layer "In2.Cu")
		(net "M_F_CPU1_SA_CA<2>")
	)
	(arc
		(start 138.802364 -257.490976)
		(mid 138.525889 -257.423656)
		(end 138.251692 -257.499612)
		(width 0.088646)
		(layer "In2.Cu")
		(net "M_F_CPU1_SA_CA<2>")
	)
	(segment
		(start 182.455058 -265.749024)
		(end 182.729124 -265.749024)
		(width 0.20066)
		(layer "F.Cu")
		(net "M_F_CPU1_SA_CA<1>")
	)
	(segment
		(start 179.636674 -265.316716)
		(end 180.072284 -265.752326)
		(width 0.20066)
		(layer "F.Cu")
		(net "M_F_CPU1_SA_CA<1>")
	)
	(segment
		(start 184.430162 -265.316716)
		(end 185.544714 -265.316716)
		(width 0.20066)
		(layer "F.Cu")
		(net "M_F_CPU1_SA_CA<1>")
	)
	(segment
		(start 176.819814 -265.316716)
		(end 178.000914 -265.316716)
		(width 0.20066)
		(layer "F.Cu")
		(net "M_F_CPU1_SA_CA<1>")
	)
	(segment
		(start 183.593994 -264.884154)
		(end 183.9976 -264.884154)
		(width 0.20066)
		(layer "F.Cu")
		(net "M_F_CPU1_SA_CA<1>")
	)
	(segment
		(start 135.714994 -257.45313)
		(end 135.714994 -257.98907)
		(width 0.20066)
		(layer "F.Cu")
		(net "M_F_CPU1_SA_CA<1>")
	)
	(segment
		(start 180.438552 -265.741658)
		(end 182.447692 -265.741658)
		(width 0.1016)
		(layer "F.Cu")
		(net "M_F_CPU1_SA_CA<1>")
	)
	(segment
		(start 182.729124 -265.749024)
		(end 183.593994 -264.884154)
		(width 0.20066)
		(layer "F.Cu")
		(net "M_F_CPU1_SA_CA<1>")
	)
	(segment
		(start 183.9976 -264.884154)
		(end 184.430162 -265.316716)
		(width 0.20066)
		(layer "F.Cu")
		(net "M_F_CPU1_SA_CA<1>")
	)
	(segment
		(start 180.072284 -265.752326)
		(end 180.423058 -265.752326)
		(width 0.20066)
		(layer "F.Cu")
		(net "M_F_CPU1_SA_CA<1>")
	)
	(segment
		(start 180.423058 -265.752326)
		(end 180.427884 -265.752326)
		(width 0.101854)
		(layer "F.Cu")
		(net "M_F_CPU1_SA_CA<1>")
	)
	(segment
		(start 180.427884 -265.752326)
		(end 180.438552 -265.741658)
		(width 0.1016)
		(layer "F.Cu")
		(net "M_F_CPU1_SA_CA<1>")
	)
	(segment
		(start 178.000914 -265.316716)
		(end 179.636674 -265.316716)
		(width 0.20066)
		(layer "F.Cu")
		(net "M_F_CPU1_SA_CA<1>")
	)
	(segment
		(start 182.447692 -265.741658)
		(end 182.455058 -265.749024)
		(width 0.1016)
		(layer "F.Cu")
		(net "M_F_CPU1_SA_CA<1>")
	)
	(segment
		(start 148.253704 -258.700778)
		(end 148.163534 -258.700778)
		(width 0.18288)
		(layer "In2.Cu")
		(net "M_F_CPU1_SA_CA<1>")
	)
	(segment
		(start 157.437836 -261.472172)
		(end 154.666188 -258.700524)
		(width 0.18288)
		(layer "In2.Cu")
		(net "M_F_CPU1_SA_CA<1>")
	)
	(segment
		(start 137.796778 -257.673348)
		(end 137.782046 -257.664712)
		(width 0.088646)
		(layer "In2.Cu")
		(net "M_F_CPU1_SA_CA<1>")
	)
	(segment
		(start 154.666188 -258.700524)
		(end 148.253958 -258.700524)
		(width 0.18288)
		(layer "In2.Cu")
		(net "M_F_CPU1_SA_CA<1>")
	)
	(segment
		(start 140.90015 -257.763518)
		(end 140.213842 -257.763518)
		(width 0.088646)
		(layer "In2.Cu")
		(net "M_F_CPU1_SA_CA<1>")
	)
	(segment
		(start 167.310054 -262.438388)
		(end 167.221662 -262.349996)
		(width 0.18288)
		(layer "In2.Cu")
		(net "M_F_CPU1_SA_CA<1>")
	)
	(segment
		(start 172.185076 -264.625328)
		(end 172.185076 -264.485374)
		(width 0.18288)
		(layer "In2.Cu")
		(net "M_F_CPU1_SA_CA<1>")
	)
	(segment
		(start 173.278292 -264.891266)
		(end 172.451014 -264.891266)
		(width 0.18288)
		(layer "In2.Cu")
		(net "M_F_CPU1_SA_CA<1>")
	)
	(segment
		(start 172.451014 -264.891266)
		(end 172.185076 -264.625328)
		(width 0.18288)
		(layer "In2.Cu")
		(net "M_F_CPU1_SA_CA<1>")
	)
	(segment
		(start 171.712128 -264.012426)
		(end 169.265092 -264.012426)
		(width 0.18288)
		(layer "In2.Cu")
		(net "M_F_CPU1_SA_CA<1>")
	)
	(segment
		(start 163.656518 -262.457438)
		(end 162.17265 -262.457438)
		(width 0.18288)
		(layer "In2.Cu")
		(net "M_F_CPU1_SA_CA<1>")
	)
	(segment
		(start 175.201326 -264.541762)
		(end 174.851822 -264.891266)
		(width 0.18288)
		(layer "In2.Cu")
		(net "M_F_CPU1_SA_CA<1>")
	)
	(segment
		(start 159.478726 -261.624826)
		(end 158.160974 -261.624826)
		(width 0.18288)
		(layer "In2.Cu")
		(net "M_F_CPU1_SA_CA<1>")
	)
	(segment
		(start 167.691054 -262.438388)
		(end 167.310054 -262.438388)
		(width 0.18288)
		(layer "In2.Cu")
		(net "M_F_CPU1_SA_CA<1>")
	)
	(segment
		(start 175.201326 -264.063226)
		(end 175.201326 -264.541762)
		(width 0.18288)
		(layer "In2.Cu")
		(net "M_F_CPU1_SA_CA<1>")
	)
	(segment
		(start 160.393126 -261.518146)
		(end 160.233106 -261.358126)
		(width 0.18288)
		(layer "In2.Cu")
		(net "M_F_CPU1_SA_CA<1>")
	)
	(segment
		(start 175.596296 -263.668256)
		(end 175.201326 -264.063226)
		(width 0.18288)
		(layer "In2.Cu")
		(net "M_F_CPU1_SA_CA<1>")
	)
	(segment
		(start 148.253958 -258.700524)
		(end 148.253704 -258.700778)
		(width 0.18288)
		(layer "In2.Cu")
		(net "M_F_CPU1_SA_CA<1>")
	)
	(segment
		(start 138.736578 -257.673348)
		(end 138.721846 -257.664712)
		(width 0.088646)
		(layer "In2.Cu")
		(net "M_F_CPU1_SA_CA<1>")
	)
	(segment
		(start 148.163534 -258.700778)
		(end 147.717002 -258.254246)
		(width 0.18288)
		(layer "In2.Cu")
		(net "M_F_CPU1_SA_CA<1>")
	)
	(segment
		(start 174.851822 -264.891266)
		(end 174.353474 -264.891266)
		(width 0.18288)
		(layer "In2.Cu")
		(net "M_F_CPU1_SA_CA<1>")
	)
	(segment
		(start 158.00832 -261.472172)
		(end 157.437836 -261.472172)
		(width 0.18288)
		(layer "In2.Cu")
		(net "M_F_CPU1_SA_CA<1>")
	)
	(segment
		(start 140.213842 -257.763518)
		(end 140.064236 -257.613912)
		(width 0.088646)
		(layer "In2.Cu")
		(net "M_F_CPU1_SA_CA<1>")
	)
	(segment
		(start 160.393126 -261.947406)
		(end 160.393126 -261.518146)
		(width 0.18288)
		(layer "In2.Cu")
		(net "M_F_CPU1_SA_CA<1>")
	)
	(segment
		(start 173.438312 -265.303762)
		(end 173.438312 -265.051286)
		(width 0.18288)
		(layer "In2.Cu")
		(net "M_F_CPU1_SA_CA<1>")
	)
	(segment
		(start 161.822638 -262.107426)
		(end 160.553146 -262.107426)
		(width 0.18288)
		(layer "In2.Cu")
		(net "M_F_CPU1_SA_CA<1>")
	)
	(segment
		(start 160.553146 -262.107426)
		(end 160.393126 -261.947406)
		(width 0.18288)
		(layer "In2.Cu")
		(net "M_F_CPU1_SA_CA<1>")
	)
	(segment
		(start 169.265092 -264.012426)
		(end 167.691054 -262.438388)
		(width 0.18288)
		(layer "In2.Cu")
		(net "M_F_CPU1_SA_CA<1>")
	)
	(segment
		(start 174.160434 -265.084306)
		(end 174.160434 -265.270742)
		(width 0.18288)
		(layer "In2.Cu")
		(net "M_F_CPU1_SA_CA<1>")
	)
	(segment
		(start 167.221662 -262.349996)
		(end 164.719254 -262.349996)
		(width 0.18288)
		(layer "In2.Cu")
		(net "M_F_CPU1_SA_CA<1>")
	)
	(segment
		(start 176.057306 -263.668256)
		(end 175.596296 -263.668256)
		(width 0.18288)
		(layer "In2.Cu")
		(net "M_F_CPU1_SA_CA<1>")
	)
	(segment
		(start 173.967394 -265.463782)
		(end 173.598332 -265.463782)
		(width 0.18288)
		(layer "In2.Cu")
		(net "M_F_CPU1_SA_CA<1>")
	)
	(segment
		(start 147.717002 -258.254246)
		(end 146.532346 -257.763518)
		(width 0.18288)
		(layer "In2.Cu")
		(net "M_F_CPU1_SA_CA<1>")
	)
	(segment
		(start 162.17265 -262.457438)
		(end 161.822638 -262.107426)
		(width 0.18288)
		(layer "In2.Cu")
		(net "M_F_CPU1_SA_CA<1>")
	)
	(segment
		(start 160.233106 -261.358126)
		(end 159.745426 -261.358126)
		(width 0.18288)
		(layer "In2.Cu")
		(net "M_F_CPU1_SA_CA<1>")
	)
	(segment
		(start 176.217326 -264.435082)
		(end 176.217326 -263.828276)
		(width 0.18288)
		(layer "In2.Cu")
		(net "M_F_CPU1_SA_CA<1>")
	)
	(segment
		(start 174.353474 -264.891266)
		(end 174.160434 -265.084306)
		(width 0.18288)
		(layer "In2.Cu")
		(net "M_F_CPU1_SA_CA<1>")
	)
	(segment
		(start 176.217326 -263.828276)
		(end 176.057306 -263.668256)
		(width 0.18288)
		(layer "In2.Cu")
		(net "M_F_CPU1_SA_CA<1>")
	)
	(segment
		(start 164.668708 -262.29945)
		(end 163.814506 -262.29945)
		(width 0.18288)
		(layer "In2.Cu")
		(net "M_F_CPU1_SA_CA<1>")
	)
	(segment
		(start 174.160434 -265.270742)
		(end 173.967394 -265.463782)
		(width 0.18288)
		(layer "In2.Cu")
		(net "M_F_CPU1_SA_CA<1>")
	)
	(segment
		(start 164.719254 -262.349996)
		(end 164.668708 -262.29945)
		(width 0.18288)
		(layer "In2.Cu")
		(net "M_F_CPU1_SA_CA<1>")
	)
	(segment
		(start 140.064236 -257.613912)
		(end 139.476988 -257.613912)
		(width 0.088646)
		(layer "In2.Cu")
		(net "M_F_CPU1_SA_CA<1>")
	)
	(segment
		(start 159.745426 -261.358126)
		(end 159.478726 -261.624826)
		(width 0.18288)
		(layer "In2.Cu")
		(net "M_F_CPU1_SA_CA<1>")
	)
	(segment
		(start 136.856978 -257.673348)
		(end 136.842246 -257.664712)
		(width 0.088646)
		(layer "In2.Cu")
		(net "M_F_CPU1_SA_CA<1>")
	)
	(segment
		(start 146.532346 -257.763518)
		(end 140.90015 -257.763518)
		(width 0.18288)
		(layer "In2.Cu")
		(net "M_F_CPU1_SA_CA<1>")
	)
	(segment
		(start 158.160974 -261.624826)
		(end 158.00832 -261.472172)
		(width 0.18288)
		(layer "In2.Cu")
		(net "M_F_CPU1_SA_CA<1>")
	)
	(segment
		(start 136.46785 -257.664712)
		(end 136.078722 -257.891026)
		(width 0.088646)
		(layer "In2.Cu")
		(net "M_F_CPU1_SA_CA<1>")
	)
	(segment
		(start 176.819814 -265.03757)
		(end 176.217326 -264.435082)
		(width 0.18288)
		(layer "In2.Cu")
		(net "M_F_CPU1_SA_CA<1>")
	)
	(segment
		(start 173.438312 -265.051286)
		(end 173.278292 -264.891266)
		(width 0.18288)
		(layer "In2.Cu")
		(net "M_F_CPU1_SA_CA<1>")
	)
	(segment
		(start 172.185076 -264.485374)
		(end 171.712128 -264.012426)
		(width 0.18288)
		(layer "In2.Cu")
		(net "M_F_CPU1_SA_CA<1>")
	)
	(segment
		(start 176.819814 -265.316716)
		(end 176.819814 -265.03757)
		(width 0.18288)
		(layer "In2.Cu")
		(net "M_F_CPU1_SA_CA<1>")
	)
	(segment
		(start 163.814506 -262.29945)
		(end 163.656518 -262.457438)
		(width 0.18288)
		(layer "In2.Cu")
		(net "M_F_CPU1_SA_CA<1>")
	)
	(segment
		(start 173.598332 -265.463782)
		(end 173.438312 -265.303762)
		(width 0.18288)
		(layer "In2.Cu")
		(net "M_F_CPU1_SA_CA<1>")
	)
	(arc
		(start 137.40765 -257.664712)
		(mid 137.133451 -257.740547)
		(end 136.856978 -257.673348)
		(width 0.088646)
		(layer "In2.Cu")
		(net "M_F_CPU1_SA_CA<1>")
	)
	(arc
		(start 136.078722 -257.891026)
		(mid 135.903355 -257.964161)
		(end 135.714994 -257.98907)
		(width 0.088646)
		(layer "In2.Cu")
		(net "M_F_CPU1_SA_CA<1>")
	)
	(arc
		(start 139.28725 -257.664712)
		(mid 139.013051 -257.740547)
		(end 138.736578 -257.673348)
		(width 0.088646)
		(layer "In2.Cu")
		(net "M_F_CPU1_SA_CA<1>")
	)
	(arc
		(start 136.842246 -257.664712)
		(mid 136.655048 -257.614569)
		(end 136.46785 -257.664712)
		(width 0.088646)
		(layer "In2.Cu")
		(net "M_F_CPU1_SA_CA<1>")
	)
	(arc
		(start 138.34745 -257.664712)
		(mid 138.073251 -257.740547)
		(end 137.796778 -257.673348)
		(width 0.088646)
		(layer "In2.Cu")
		(net "M_F_CPU1_SA_CA<1>")
	)
	(arc
		(start 138.721846 -257.664712)
		(mid 138.534648 -257.614569)
		(end 138.34745 -257.664712)
		(width 0.088646)
		(layer "In2.Cu")
		(net "M_F_CPU1_SA_CA<1>")
	)
	(arc
		(start 139.476988 -257.613912)
		(mid 139.378782 -257.62684)
		(end 139.28725 -257.664712)
		(width 0.088646)
		(layer "In2.Cu")
		(net "M_F_CPU1_SA_CA<1>")
	)
	(arc
		(start 137.782046 -257.664712)
		(mid 137.594848 -257.614569)
		(end 137.40765 -257.664712)
		(width 0.088646)
		(layer "In2.Cu")
		(net "M_F_CPU1_SA_CA<1>")
	)
	(segment
		(start 175.786034 -265.672316)
		(end 176.70526 -266.591542)
		(width 0.20066)
		(layer "F.Cu")
		(net "M_F_CPU1_SA_CA<0>")
	)
	(segment
		(start 173.900846 -266.1666)
		(end 174.966376 -266.1666)
		(width 0.20066)
		(layer "F.Cu")
		(net "M_F_CPU1_SA_CA<0>")
	)
	(segment
		(start 179.86502 -266.166346)
		(end 181.444392 -266.166346)
		(width 0.20066)
		(layer "F.Cu")
		(net "M_F_CPU1_SA_CA<0>")
	)
	(segment
		(start 179.011326 -266.603988)
		(end 179.427378 -266.603988)
		(width 0.20066)
		(layer "F.Cu")
		(net "M_F_CPU1_SA_CA<0>")
	)
	(segment
		(start 176.826418 -266.591542)
		(end 178.99888 -266.591542)
		(width 0.1016)
		(layer "F.Cu")
		(net "M_F_CPU1_SA_CA<0>")
	)
	(segment
		(start 172.719746 -266.1666)
		(end 173.900846 -266.1666)
		(width 0.20066)
		(layer "F.Cu")
		(net "M_F_CPU1_SA_CA<0>")
	)
	(segment
		(start 175.46066 -265.672316)
		(end 175.786034 -265.672316)
		(width 0.20066)
		(layer "F.Cu")
		(net "M_F_CPU1_SA_CA<0>")
	)
	(segment
		(start 176.70526 -266.591542)
		(end 176.812702 -266.591542)
		(width 0.20066)
		(layer "F.Cu")
		(net "M_F_CPU1_SA_CA<0>")
	)
	(segment
		(start 132.895848 -257.988816)
		(end 132.895594 -257.98907)
		(width 0.20066)
		(layer "F.Cu")
		(net "M_F_CPU1_SA_CA<0>")
	)
	(segment
		(start 181.444392 -266.166346)
		(end 181.444646 -266.1666)
		(width 0.20066)
		(layer "F.Cu")
		(net "M_F_CPU1_SA_CA<0>")
	)
	(segment
		(start 174.966376 -266.1666)
		(end 175.46066 -265.672316)
		(width 0.20066)
		(layer "F.Cu")
		(net "M_F_CPU1_SA_CA<0>")
	)
	(segment
		(start 176.812702 -266.591542)
		(end 176.826418 -266.591542)
		(width 0.101854)
		(layer "F.Cu")
		(net "M_F_CPU1_SA_CA<0>")
	)
	(segment
		(start 178.99888 -266.591542)
		(end 179.011326 -266.603988)
		(width 0.1016)
		(layer "F.Cu")
		(net "M_F_CPU1_SA_CA<0>")
	)
	(segment
		(start 132.895848 -257.45313)
		(end 132.895848 -257.988816)
		(width 0.20066)
		(layer "F.Cu")
		(net "M_F_CPU1_SA_CA<0>")
	)
	(segment
		(start 179.427378 -266.603988)
		(end 179.86502 -266.166346)
		(width 0.20066)
		(layer "F.Cu")
		(net "M_F_CPU1_SA_CA<0>")
	)
	(segment
		(start 154.825954 -259.868924)
		(end 154.825954 -259.596128)
		(width 0.18288)
		(layer "In2.Cu")
		(net "M_F_CPU1_SA_CA<0>")
	)
	(segment
		(start 163.868862 -263.276334)
		(end 163.57854 -262.986012)
		(width 0.18288)
		(layer "In2.Cu")
		(net "M_F_CPU1_SA_CA<0>")
	)
	(segment
		(start 156.849826 -262.013192)
		(end 156.849826 -261.62)
		(width 0.18288)
		(layer "In2.Cu")
		(net "M_F_CPU1_SA_CA<0>")
	)
	(segment
		(start 140.27658 -258.164076)
		(end 140.218414 -258.164076)
		(width 0.088646)
		(layer "In2.Cu")
		(net "M_F_CPU1_SA_CA<0>")
	)
	(segment
		(start 154.876754 -260.541516)
		(end 154.651456 -260.316218)
		(width 0.18288)
		(layer "In2.Cu")
		(net "M_F_CPU1_SA_CA<0>")
	)
	(segment
		(start 170.915076 -264.525252)
		(end 170.218608 -264.525252)
		(width 0.18288)
		(layer "In2.Cu")
		(net "M_F_CPU1_SA_CA<0>")
	)
	(segment
		(start 140.90015 -258.113276)
		(end 140.32738 -258.113276)
		(width 0.088646)
		(layer "In2.Cu")
		(net "M_F_CPU1_SA_CA<0>")
	)
	(segment
		(start 163.57854 -262.986012)
		(end 162.240722 -262.986012)
		(width 0.18288)
		(layer "In2.Cu")
		(net "M_F_CPU1_SA_CA<0>")
	)
	(segment
		(start 154.825954 -259.596128)
		(end 154.460702 -259.230876)
		(width 0.18288)
		(layer "In2.Cu")
		(net "M_F_CPU1_SA_CA<0>")
	)
	(segment
		(start 148.108416 -259.23113)
		(end 147.394168 -258.516882)
		(width 0.18288)
		(layer "In2.Cu")
		(net "M_F_CPU1_SA_CA<0>")
	)
	(segment
		(start 148.253958 -259.230876)
		(end 148.253704 -259.23113)
		(width 0.18288)
		(layer "In2.Cu")
		(net "M_F_CPU1_SA_CA<0>")
	)
	(segment
		(start 155.647644 -261.03961)
		(end 155.822142 -260.865112)
		(width 0.18288)
		(layer "In2.Cu")
		(net "M_F_CPU1_SA_CA<0>")
	)
	(segment
		(start 154.651456 -260.043422)
		(end 154.825954 -259.868924)
		(width 0.18288)
		(layer "In2.Cu")
		(net "M_F_CPU1_SA_CA<0>")
	)
	(segment
		(start 164.539676 -262.87857)
		(end 164.141912 -263.276334)
		(width 0.18288)
		(layer "In2.Cu")
		(net "M_F_CPU1_SA_CA<0>")
	)
	(segment
		(start 136.856978 -258.304792)
		(end 136.842246 -258.313428)
		(width 0.088646)
		(layer "In2.Cu")
		(net "M_F_CPU1_SA_CA<0>")
	)
	(segment
		(start 166.754048 -263.555226)
		(end 165.819836 -263.555226)
		(width 0.18288)
		(layer "In2.Cu")
		(net "M_F_CPU1_SA_CA<0>")
	)
	(segment
		(start 169.134282 -264.90295)
		(end 168.745916 -264.514584)
		(width 0.18288)
		(layer "In2.Cu")
		(net "M_F_CPU1_SA_CA<0>")
	)
	(segment
		(start 165.819836 -263.555226)
		(end 165.14318 -262.87857)
		(width 0.18288)
		(layer "In2.Cu")
		(net "M_F_CPU1_SA_CA<0>")
	)
	(segment
		(start 168.745916 -264.246614)
		(end 167.638476 -263.139174)
		(width 0.18288)
		(layer "In2.Cu")
		(net "M_F_CPU1_SA_CA<0>")
	)
	(segment
		(start 155.822142 -260.592316)
		(end 155.596844 -260.367018)
		(width 0.18288)
		(layer "In2.Cu")
		(net "M_F_CPU1_SA_CA<0>")
	)
	(segment
		(start 135.912606 -258.307332)
		(end 135.902192 -258.313428)
		(width 0.088646)
		(layer "In2.Cu")
		(net "M_F_CPU1_SA_CA<0>")
	)
	(segment
		(start 156.320236 -261.363206)
		(end 156.145738 -261.537704)
		(width 0.18288)
		(layer "In2.Cu")
		(net "M_F_CPU1_SA_CA<0>")
	)
	(segment
		(start 172.719746 -266.1666)
		(end 172.719746 -265.899138)
		(width 0.18288)
		(layer "In2.Cu")
		(net "M_F_CPU1_SA_CA<0>")
	)
	(segment
		(start 159.631126 -262.310626)
		(end 158.013146 -262.310626)
		(width 0.18288)
		(layer "In2.Cu")
		(net "M_F_CPU1_SA_CA<0>")
	)
	(segment
		(start 154.460702 -259.230876)
		(end 148.253958 -259.230876)
		(width 0.18288)
		(layer "In2.Cu")
		(net "M_F_CPU1_SA_CA<0>")
	)
	(segment
		(start 162.240722 -262.986012)
		(end 161.822638 -263.404096)
		(width 0.18288)
		(layer "In2.Cu")
		(net "M_F_CPU1_SA_CA<0>")
	)
	(segment
		(start 155.872942 -261.537704)
		(end 155.647644 -261.312406)
		(width 0.18288)
		(layer "In2.Cu")
		(net "M_F_CPU1_SA_CA<0>")
	)
	(segment
		(start 171.990004 -265.169396)
		(end 171.55922 -265.169396)
		(width 0.18288)
		(layer "In2.Cu")
		(net "M_F_CPU1_SA_CA<0>")
	)
	(segment
		(start 148.253704 -259.23113)
		(end 148.108416 -259.23113)
		(width 0.18288)
		(layer "In2.Cu")
		(net "M_F_CPU1_SA_CA<0>")
	)
	(segment
		(start 172.719746 -265.899138)
		(end 171.990004 -265.169396)
		(width 0.18288)
		(layer "In2.Cu")
		(net "M_F_CPU1_SA_CA<0>")
	)
	(segment
		(start 156.849826 -261.62)
		(end 156.593032 -261.363206)
		(width 0.18288)
		(layer "In2.Cu")
		(net "M_F_CPU1_SA_CA<0>")
	)
	(segment
		(start 170.218608 -264.525252)
		(end 169.84091 -264.90295)
		(width 0.18288)
		(layer "In2.Cu")
		(net "M_F_CPU1_SA_CA<0>")
	)
	(segment
		(start 137.796778 -258.304792)
		(end 137.782046 -258.313428)
		(width 0.088646)
		(layer "In2.Cu")
		(net "M_F_CPU1_SA_CA<0>")
	)
	(segment
		(start 154.651456 -260.316218)
		(end 154.651456 -260.043422)
		(width 0.18288)
		(layer "In2.Cu")
		(net "M_F_CPU1_SA_CA<0>")
	)
	(segment
		(start 161.822638 -263.404096)
		(end 161.549588 -263.404096)
		(width 0.18288)
		(layer "In2.Cu")
		(net "M_F_CPU1_SA_CA<0>")
	)
	(segment
		(start 155.14955 -260.541516)
		(end 154.876754 -260.541516)
		(width 0.18288)
		(layer "In2.Cu")
		(net "M_F_CPU1_SA_CA<0>")
	)
	(segment
		(start 133.600698 -258.395978)
		(end 133.600698 -258.396232)
		(width 0.088646)
		(layer "In2.Cu")
		(net "M_F_CPU1_SA_CA<0>")
	)
	(segment
		(start 157.279848 -262.443214)
		(end 156.849826 -262.013192)
		(width 0.18288)
		(layer "In2.Cu")
		(net "M_F_CPU1_SA_CA<0>")
	)
	(segment
		(start 171.55922 -265.169396)
		(end 170.915076 -264.525252)
		(width 0.18288)
		(layer "In2.Cu")
		(net "M_F_CPU1_SA_CA<0>")
	)
	(segment
		(start 157.880558 -262.443214)
		(end 157.279848 -262.443214)
		(width 0.18288)
		(layer "In2.Cu")
		(net "M_F_CPU1_SA_CA<0>")
	)
	(segment
		(start 156.593032 -261.363206)
		(end 156.320236 -261.363206)
		(width 0.18288)
		(layer "In2.Cu")
		(net "M_F_CPU1_SA_CA<0>")
	)
	(segment
		(start 161.549588 -263.404096)
		(end 160.773364 -262.627872)
		(width 0.18288)
		(layer "In2.Cu")
		(net "M_F_CPU1_SA_CA<0>")
	)
	(segment
		(start 167.1701 -263.139174)
		(end 166.754048 -263.555226)
		(width 0.18288)
		(layer "In2.Cu")
		(net "M_F_CPU1_SA_CA<0>")
	)
	(segment
		(start 155.647644 -261.312406)
		(end 155.647644 -261.03961)
		(width 0.18288)
		(layer "In2.Cu")
		(net "M_F_CPU1_SA_CA<0>")
	)
	(segment
		(start 156.145738 -261.537704)
		(end 155.872942 -261.537704)
		(width 0.18288)
		(layer "In2.Cu")
		(net "M_F_CPU1_SA_CA<0>")
	)
	(segment
		(start 138.736578 -258.304792)
		(end 138.721846 -258.313428)
		(width 0.088646)
		(layer "In2.Cu")
		(net "M_F_CPU1_SA_CA<0>")
	)
	(segment
		(start 165.14318 -262.87857)
		(end 164.539676 -262.87857)
		(width 0.18288)
		(layer "In2.Cu")
		(net "M_F_CPU1_SA_CA<0>")
	)
	(segment
		(start 164.141912 -263.276334)
		(end 163.868862 -263.276334)
		(width 0.18288)
		(layer "In2.Cu")
		(net "M_F_CPU1_SA_CA<0>")
	)
	(segment
		(start 158.013146 -262.310626)
		(end 157.880558 -262.443214)
		(width 0.18288)
		(layer "In2.Cu")
		(net "M_F_CPU1_SA_CA<0>")
	)
	(segment
		(start 155.822142 -260.865112)
		(end 155.822142 -260.592316)
		(width 0.18288)
		(layer "In2.Cu")
		(net "M_F_CPU1_SA_CA<0>")
	)
	(segment
		(start 133.600698 -258.396232)
		(end 132.895594 -257.98907)
		(width 0.088646)
		(layer "In2.Cu")
		(net "M_F_CPU1_SA_CA<0>")
	)
	(segment
		(start 140.32738 -258.113276)
		(end 140.27658 -258.164076)
		(width 0.088646)
		(layer "In2.Cu")
		(net "M_F_CPU1_SA_CA<0>")
	)
	(segment
		(start 159.948372 -262.627872)
		(end 159.631126 -262.310626)
		(width 0.18288)
		(layer "In2.Cu")
		(net "M_F_CPU1_SA_CA<0>")
	)
	(segment
		(start 155.324048 -260.367018)
		(end 155.14955 -260.541516)
		(width 0.18288)
		(layer "In2.Cu")
		(net "M_F_CPU1_SA_CA<0>")
	)
	(segment
		(start 155.596844 -260.367018)
		(end 155.324048 -260.367018)
		(width 0.18288)
		(layer "In2.Cu")
		(net "M_F_CPU1_SA_CA<0>")
	)
	(segment
		(start 147.394168 -258.516882)
		(end 146.419824 -258.113276)
		(width 0.18288)
		(layer "In2.Cu")
		(net "M_F_CPU1_SA_CA<0>")
	)
	(segment
		(start 134.540498 -258.396232)
		(end 134.539736 -258.395978)
		(width 0.088646)
		(layer "In2.Cu")
		(net "M_F_CPU1_SA_CA<0>")
	)
	(segment
		(start 169.84091 -264.90295)
		(end 169.134282 -264.90295)
		(width 0.18288)
		(layer "In2.Cu")
		(net "M_F_CPU1_SA_CA<0>")
	)
	(segment
		(start 167.638476 -263.139174)
		(end 167.1701 -263.139174)
		(width 0.18288)
		(layer "In2.Cu")
		(net "M_F_CPU1_SA_CA<0>")
	)
	(segment
		(start 146.419824 -258.113276)
		(end 140.90015 -258.113276)
		(width 0.18288)
		(layer "In2.Cu")
		(net "M_F_CPU1_SA_CA<0>")
	)
	(segment
		(start 160.773364 -262.627872)
		(end 159.948372 -262.627872)
		(width 0.18288)
		(layer "In2.Cu")
		(net "M_F_CPU1_SA_CA<0>")
	)
	(segment
		(start 168.745916 -264.514584)
		(end 168.745916 -264.246614)
		(width 0.18288)
		(layer "In2.Cu")
		(net "M_F_CPU1_SA_CA<0>")
	)
	(arc
		(start 140.218414 -258.164076)
		(mid 139.930183 -258.202053)
		(end 139.661646 -258.313428)
		(width 0.088646)
		(layer "In2.Cu")
		(net "M_F_CPU1_SA_CA<0>")
	)
	(arc
		(start 137.782046 -258.313428)
		(mid 137.594848 -258.363571)
		(end 137.40765 -258.313428)
		(width 0.088646)
		(layer "In2.Cu")
		(net "M_F_CPU1_SA_CA<0>")
	)
	(arc
		(start 136.46785 -258.313428)
		(mid 136.191037 -258.237592)
		(end 135.912606 -258.307332)
		(width 0.088646)
		(layer "In2.Cu")
		(net "M_F_CPU1_SA_CA<0>")
	)
	(arc
		(start 136.842246 -258.313428)
		(mid 136.655048 -258.363571)
		(end 136.46785 -258.313428)
		(width 0.088646)
		(layer "In2.Cu")
		(net "M_F_CPU1_SA_CA<0>")
	)
	(arc
		(start 135.527796 -258.313428)
		(mid 135.261335 -258.30711)
		(end 135.010144 -258.396232)
		(width 0.088646)
		(layer "In2.Cu")
		(net "M_F_CPU1_SA_CA<0>")
	)
	(arc
		(start 134.070598 -258.395978)
		(mid 133.835648 -258.458938)
		(end 133.600698 -258.395978)
		(width 0.088646)
		(layer "In2.Cu")
		(net "M_F_CPU1_SA_CA<0>")
	)
	(arc
		(start 138.34745 -258.313428)
		(mid 138.073221 -258.237503)
		(end 137.796778 -258.304792)
		(width 0.088646)
		(layer "In2.Cu")
		(net "M_F_CPU1_SA_CA<0>")
	)
	(arc
		(start 139.28725 -258.313428)
		(mid 139.013021 -258.237503)
		(end 138.736578 -258.304792)
		(width 0.088646)
		(layer "In2.Cu")
		(net "M_F_CPU1_SA_CA<0>")
	)
	(arc
		(start 135.010144 -258.396232)
		(mid 134.775338 -258.459065)
		(end 134.540498 -258.396232)
		(width 0.088646)
		(layer "In2.Cu")
		(net "M_F_CPU1_SA_CA<0>")
	)
	(arc
		(start 135.902192 -258.313428)
		(mid 135.714994 -258.363571)
		(end 135.527796 -258.313428)
		(width 0.088646)
		(layer "In2.Cu")
		(net "M_F_CPU1_SA_CA<0>")
	)
	(arc
		(start 139.661646 -258.313428)
		(mid 139.474448 -258.363571)
		(end 139.28725 -258.313428)
		(width 0.088646)
		(layer "In2.Cu")
		(net "M_F_CPU1_SA_CA<0>")
	)
	(arc
		(start 134.539736 -258.395978)
		(mid 134.305184 -258.333204)
		(end 134.070598 -258.395978)
		(width 0.088646)
		(layer "In2.Cu")
		(net "M_F_CPU1_SA_CA<0>")
	)
	(arc
		(start 137.40765 -258.313428)
		(mid 137.133421 -258.237503)
		(end 136.856978 -258.304792)
		(width 0.088646)
		(layer "In2.Cu")
		(net "M_F_CPU1_SA_CA<0>")
	)
	(arc
		(start 138.721846 -258.313428)
		(mid 138.534648 -258.363571)
		(end 138.34745 -258.313428)
		(width 0.088646)
		(layer "In2.Cu")
		(net "M_F_CPU1_SA_CA<0>")
	)
	(segment
		(start 176.896014 -260.21665)
		(end 178.000914 -260.21665)
		(width 0.20066)
		(layer "F.Cu")
		(net "M_F_CPU1_CLK_DP<1>")
	)
	(segment
		(start 129.606294 -255.011682)
		(end 129.606294 -255.547368)
		(width 0.20066)
		(layer "F.Cu")
		(net "M_F_CPU1_CLK_DP<1>")
	)
	(segment
		(start 129.606294 -255.547368)
		(end 129.606548 -255.547622)
		(width 0.20066)
		(layer "F.Cu")
		(net "M_F_CPU1_CLK_DP<1>")
	)
	(segment
		(start 171.970446 -257.310636)
		(end 169.62882 -256.803398)
		(width 0.18288)
		(layer "In2.Cu")
		(net "M_F_CPU1_CLK_DP<1>")
	)
	(segment
		(start 176.010062 -259.613908)
		(end 175.468026 -258.335272)
		(width 0.18288)
		(layer "In2.Cu")
		(net "M_F_CPU1_CLK_DP<1>")
	)
	(segment
		(start 129.919222 -255.547622)
		(end 129.606548 -255.547622)
		(width 0.088646)
		(layer "In2.Cu")
		(net "M_F_CPU1_CLK_DP<1>")
	)
	(segment
		(start 144.348708 -255.143)
		(end 144.348454 -255.142746)
		(width 0.18288)
		(layer "In2.Cu")
		(net "M_F_CPU1_CLK_DP<1>")
	)
	(segment
		(start 145.178272 -255.240282)
		(end 144.348708 -255.142746)
		(width 0.18288)
		(layer "In2.Cu")
		(net "M_F_CPU1_CLK_DP<1>")
	)
	(segment
		(start 133.460998 -254.724916)
		(end 133.460998 -254.747776)
		(width 0.088646)
		(layer "In2.Cu")
		(net "M_F_CPU1_CLK_DP<1>")
	)
	(segment
		(start 148.308314 -254.695706)
		(end 146.993356 -255.240282)
		(width 0.18288)
		(layer "In2.Cu")
		(net "M_F_CPU1_CLK_DP<1>")
	)
	(segment
		(start 144.348454 -255.142746)
		(end 143.521176 -255.04521)
		(width 0.18288)
		(layer "In2.Cu")
		(net "M_F_CPU1_CLK_DP<1>")
	)
	(segment
		(start 133.178296 -255.223264)
		(end 133.169406 -255.228344)
		(width 0.088646)
		(layer "In2.Cu")
		(net "M_F_CPU1_CLK_DP<1>")
	)
	(segment
		(start 140.51915 -254.644906)
		(end 140.454126 -254.579882)
		(width 0.088646)
		(layer "In2.Cu")
		(net "M_F_CPU1_CLK_DP<1>")
	)
	(segment
		(start 169.62882 -256.803398)
		(end 167.922448 -256.554732)
		(width 0.18288)
		(layer "In2.Cu")
		(net "M_F_CPU1_CLK_DP<1>")
	)
	(segment
		(start 146.993356 -255.240282)
		(end 145.178272 -255.240282)
		(width 0.18288)
		(layer "In2.Cu")
		(net "M_F_CPU1_CLK_DP<1>")
	)
	(segment
		(start 138.346688 -254.40894)
		(end 138.346942 -254.409448)
		(width 0.088646)
		(layer "In2.Cu")
		(net "M_F_CPU1_CLK_DP<1>")
	)
	(segment
		(start 143.521176 -255.04521)
		(end 141.69644 -254.644906)
		(width 0.18288)
		(layer "In2.Cu")
		(net "M_F_CPU1_CLK_DP<1>")
	)
	(segment
		(start 174.311818 -257.817112)
		(end 171.970446 -257.310382)
		(width 0.18288)
		(layer "In2.Cu")
		(net "M_F_CPU1_CLK_DP<1>")
	)
	(segment
		(start 175.290734 -258.15798)
		(end 174.311818 -257.817112)
		(width 0.18288)
		(layer "In2.Cu")
		(net "M_F_CPU1_CLK_DP<1>")
	)
	(segment
		(start 176.316386 -259.920232)
		(end 176.010062 -259.613908)
		(width 0.18288)
		(layer "In2.Cu")
		(net "M_F_CPU1_CLK_DP<1>")
	)
	(segment
		(start 129.984754 -255.613154)
		(end 129.919222 -255.547622)
		(width 0.088646)
		(layer "In2.Cu")
		(net "M_F_CPU1_CLK_DP<1>")
	)
	(segment
		(start 171.970446 -257.310382)
		(end 171.970446 -257.310636)
		(width 0.18288)
		(layer "In2.Cu")
		(net "M_F_CPU1_CLK_DP<1>")
	)
	(segment
		(start 140.201904 -254.579882)
		(end 139.81684 -254.739394)
		(width 0.088646)
		(layer "In2.Cu")
		(net "M_F_CPU1_CLK_DP<1>")
	)
	(segment
		(start 167.922448 -256.554732)
		(end 159.789114 -256.554732)
		(width 0.18288)
		(layer "In2.Cu")
		(net "M_F_CPU1_CLK_DP<1>")
	)
	(segment
		(start 139.81684 -254.739394)
		(end 139.351766 -254.739394)
		(width 0.088646)
		(layer "In2.Cu")
		(net "M_F_CPU1_CLK_DP<1>")
	)
	(segment
		(start 131.768596 -256.03708)
		(end 131.753864 -256.045716)
		(width 0.088646)
		(layer "In2.Cu")
		(net "M_F_CPU1_CLK_DP<1>")
	)
	(segment
		(start 144.348708 -255.142746)
		(end 144.348708 -255.143)
		(width 0.18288)
		(layer "In2.Cu")
		(net "M_F_CPU1_CLK_DP<1>")
	)
	(segment
		(start 176.599596 -259.920232)
		(end 176.316386 -259.920232)
		(width 0.18288)
		(layer "In2.Cu")
		(net "M_F_CPU1_CLK_DP<1>")
	)
	(segment
		(start 140.454126 -254.579882)
		(end 140.201904 -254.579882)
		(width 0.088646)
		(layer "In2.Cu")
		(net "M_F_CPU1_CLK_DP<1>")
	)
	(segment
		(start 141.69644 -254.644906)
		(end 140.51915 -254.644906)
		(width 0.18288)
		(layer "In2.Cu")
		(net "M_F_CPU1_CLK_DP<1>")
	)
	(segment
		(start 159.789114 -256.554732)
		(end 155.301188 -254.695706)
		(width 0.18288)
		(layer "In2.Cu")
		(net "M_F_CPU1_CLK_DP<1>")
	)
	(segment
		(start 139.351766 -254.739394)
		(end 139.067794 -254.609854)
		(width 0.088646)
		(layer "In2.Cu")
		(net "M_F_CPU1_CLK_DP<1>")
	)
	(segment
		(start 139.067794 -254.609854)
		(end 138.721846 -254.40894)
		(width 0.088646)
		(layer "In2.Cu")
		(net "M_F_CPU1_CLK_DP<1>")
	)
	(segment
		(start 155.301188 -254.695706)
		(end 148.308314 -254.695706)
		(width 0.18288)
		(layer "In2.Cu")
		(net "M_F_CPU1_CLK_DP<1>")
	)
	(segment
		(start 130.828796 -256.03708)
		(end 130.814064 -256.045716)
		(width 0.088646)
		(layer "In2.Cu")
		(net "M_F_CPU1_CLK_DP<1>")
	)
	(segment
		(start 132.990844 -255.547622)
		(end 132.990844 -255.557528)
		(width 0.088646)
		(layer "In2.Cu")
		(net "M_F_CPU1_CLK_DP<1>")
	)
	(segment
		(start 176.896014 -260.21665)
		(end 176.599596 -259.920232)
		(width 0.18288)
		(layer "In2.Cu")
		(net "M_F_CPU1_CLK_DP<1>")
	)
	(segment
		(start 134.587996 -254.409194)
		(end 134.573264 -254.41783)
		(width 0.088646)
		(layer "In2.Cu")
		(net "M_F_CPU1_CLK_DP<1>")
	)
	(segment
		(start 175.468026 -258.335272)
		(end 175.290734 -258.15798)
		(width 0.18288)
		(layer "In2.Cu")
		(net "M_F_CPU1_CLK_DP<1>")
	)
	(arc
		(start 132.142992 -256.03708)
		(mid 131.955794 -255.986937)
		(end 131.768596 -256.03708)
		(width 0.088646)
		(layer "In2.Cu")
		(net "M_F_CPU1_CLK_DP<1>")
	)
	(arc
		(start 137.407396 -254.409194)
		(mid 137.124694 -254.48497)
		(end 136.841992 -254.409194)
		(width 0.088646)
		(layer "In2.Cu")
		(net "M_F_CPU1_CLK_DP<1>")
	)
	(arc
		(start 134.962392 -254.409194)
		(mid 134.775194 -254.359051)
		(end 134.587996 -254.409194)
		(width 0.088646)
		(layer "In2.Cu")
		(net "M_F_CPU1_CLK_DP<1>")
	)
	(arc
		(start 131.753864 -256.045716)
		(mid 131.477389 -256.113036)
		(end 131.203192 -256.03708)
		(width 0.088646)
		(layer "In2.Cu")
		(net "M_F_CPU1_CLK_DP<1>")
	)
	(arc
		(start 137.781792 -254.409194)
		(mid 137.594594 -254.359051)
		(end 137.407396 -254.409194)
		(width 0.088646)
		(layer "In2.Cu")
		(net "M_F_CPU1_CLK_DP<1>")
	)
	(arc
		(start 136.467596 -254.409194)
		(mid 136.184894 -254.48497)
		(end 135.902192 -254.409194)
		(width 0.088646)
		(layer "In2.Cu")
		(net "M_F_CPU1_CLK_DP<1>")
	)
	(arc
		(start 134.022592 -254.409194)
		(mid 133.651869 -254.407102)
		(end 133.460998 -254.724916)
		(width 0.088646)
		(layer "In2.Cu")
		(net "M_F_CPU1_CLK_DP<1>")
	)
	(arc
		(start 135.902192 -254.409194)
		(mid 135.714994 -254.359051)
		(end 135.527796 -254.409194)
		(width 0.088646)
		(layer "In2.Cu")
		(net "M_F_CPU1_CLK_DP<1>")
	)
	(arc
		(start 136.841992 -254.409194)
		(mid 136.654794 -254.359051)
		(end 136.467596 -254.409194)
		(width 0.088646)
		(layer "In2.Cu")
		(net "M_F_CPU1_CLK_DP<1>")
	)
	(arc
		(start 130.814064 -256.045716)
		(mid 130.294331 -256.05384)
		(end 129.987548 -255.634236)
		(width 0.088646)
		(layer "In2.Cu")
		(net "M_F_CPU1_CLK_DP<1>")
	)
	(arc
		(start 133.169406 -255.228344)
		(mid 133.038492 -255.364704)
		(end 132.990844 -255.547622)
		(width 0.088646)
		(layer "In2.Cu")
		(net "M_F_CPU1_CLK_DP<1>")
	)
	(arc
		(start 132.990844 -255.557528)
		(mid 132.703969 -256.039613)
		(end 132.142992 -256.03708)
		(width 0.088646)
		(layer "In2.Cu")
		(net "M_F_CPU1_CLK_DP<1>")
	)
	(arc
		(start 129.987548 -255.634236)
		(mid 129.986052 -255.623708)
		(end 129.984754 -255.613154)
		(width 0.088646)
		(layer "In2.Cu")
		(net "M_F_CPU1_CLK_DP<1>")
	)
	(arc
		(start 133.460998 -254.747776)
		(mid 133.381779 -255.022461)
		(end 133.178296 -255.223264)
		(width 0.088646)
		(layer "In2.Cu")
		(net "M_F_CPU1_CLK_DP<1>")
	)
	(arc
		(start 138.346942 -254.409448)
		(mid 138.064321 -254.485063)
		(end 137.781792 -254.409194)
		(width 0.088646)
		(layer "In2.Cu")
		(net "M_F_CPU1_CLK_DP<1>")
	)
	(arc
		(start 134.573264 -254.41783)
		(mid 134.296789 -254.48515)
		(end 134.022592 -254.409194)
		(width 0.088646)
		(layer "In2.Cu")
		(net "M_F_CPU1_CLK_DP<1>")
	)
	(arc
		(start 138.721846 -254.40894)
		(mid 138.534284 -254.358704)
		(end 138.346688 -254.40894)
		(width 0.088646)
		(layer "In2.Cu")
		(net "M_F_CPU1_CLK_DP<1>")
	)
	(arc
		(start 131.203192 -256.03708)
		(mid 131.015994 -255.986937)
		(end 130.828796 -256.03708)
		(width 0.088646)
		(layer "In2.Cu")
		(net "M_F_CPU1_CLK_DP<1>")
	)
	(arc
		(start 135.527796 -254.409194)
		(mid 135.245094 -254.48497)
		(end 134.962392 -254.409194)
		(width 0.088646)
		(layer "In2.Cu")
		(net "M_F_CPU1_CLK_DP<1>")
	)
	(segment
		(start 184.439814 -260.21665)
		(end 185.544714 -260.21665)
		(width 0.20066)
		(layer "F.Cu")
		(net "M_F_CPU1_CLK_DP<0>")
	)
	(segment
		(start 132.425694 -255.547368)
		(end 132.425948 -255.547622)
		(width 0.20066)
		(layer "F.Cu")
		(net "M_F_CPU1_CLK_DP<0>")
	)
	(segment
		(start 132.425694 -255.011682)
		(end 132.425694 -255.547368)
		(width 0.20066)
		(layer "F.Cu")
		(net "M_F_CPU1_CLK_DP<0>")
	)
	(segment
		(start 177.582068 -257.44678)
		(end 177.067972 -257.304032)
		(width 0.18288)
		(layer "In2.Cu")
		(net "M_F_CPU1_CLK_DP<0>")
	)
	(segment
		(start 132.23875 -255.223264)
		(end 132.22986 -255.228344)
		(width 0.088646)
		(layer "In2.Cu")
		(net "M_F_CPU1_CLK_DP<0>")
	)
	(segment
		(start 179.040282 -257.725164)
		(end 177.732182 -257.361944)
		(width 0.18288)
		(layer "In2.Cu")
		(net "M_F_CPU1_CLK_DP<0>")
	)
	(segment
		(start 132.11302 -255.547622)
		(end 132.425948 -255.547622)
		(width 0.088646)
		(layer "In2.Cu")
		(net "M_F_CPU1_CLK_DP<0>")
	)
	(segment
		(start 134.38505 -253.39167)
		(end 134.325106 -253.331726)
		(width 0.088646)
		(layer "In2.Cu")
		(net "M_F_CPU1_CLK_DP<0>")
	)
	(segment
		(start 132.714746 -254.405638)
		(end 132.713222 -254.4064)
		(width 0.088646)
		(layer "In2.Cu")
		(net "M_F_CPU1_CLK_DP<0>")
	)
	(segment
		(start 180.187092 -257.847084)
		(end 180.065172 -257.725164)
		(width 0.18288)
		(layer "In2.Cu")
		(net "M_F_CPU1_CLK_DP<0>")
	)
	(segment
		(start 132.721604 -254.401066)
		(end 132.721858 -254.401574)
		(width 0.088646)
		(layer "In2.Cu")
		(net "M_F_CPU1_CLK_DP<0>")
	)
	(segment
		(start 176.983136 -257.153664)
		(end 176.193196 -256.934208)
		(width 0.18288)
		(layer "In2.Cu")
		(net "M_F_CPU1_CLK_DP<0>")
	)
	(segment
		(start 133.205982 -253.331726)
		(end 132.99059 -253.547118)
		(width 0.088646)
		(layer "In2.Cu")
		(net "M_F_CPU1_CLK_DP<0>")
	)
	(segment
		(start 184.439814 -260.21665)
		(end 184.416954 -260.21665)
		(width 0.18288)
		(layer "In2.Cu")
		(net "M_F_CPU1_CLK_DP<0>")
	)
	(segment
		(start 132.99059 -253.547118)
		(end 132.99059 -253.919736)
		(width 0.088646)
		(layer "In2.Cu")
		(net "M_F_CPU1_CLK_DP<0>")
	)
	(segment
		(start 181.375812 -257.725164)
		(end 180.842412 -257.725164)
		(width 0.18288)
		(layer "In2.Cu")
		(net "M_F_CPU1_CLK_DP<0>")
	)
	(segment
		(start 132.713222 -254.4064)
		(end 132.70865 -254.409194)
		(width 0.088646)
		(layer "In2.Cu")
		(net "M_F_CPU1_CLK_DP<0>")
	)
	(segment
		(start 176.193196 -256.934208)
		(end 167.976296 -255.708404)
		(width 0.18288)
		(layer "In2.Cu")
		(net "M_F_CPU1_CLK_DP<0>")
	)
	(segment
		(start 183.803544 -259.958078)
		(end 183.338978 -259.493512)
		(width 0.18288)
		(layer "In2.Cu")
		(net "M_F_CPU1_CLK_DP<0>")
	)
	(segment
		(start 183.338978 -258.37769)
		(end 182.686452 -257.725164)
		(width 0.18288)
		(layer "In2.Cu")
		(net "M_F_CPU1_CLK_DP<0>")
	)
	(segment
		(start 184.158382 -259.958078)
		(end 183.803544 -259.958078)
		(width 0.18288)
		(layer "In2.Cu")
		(net "M_F_CPU1_CLK_DP<0>")
	)
	(segment
		(start 147.00758 -254.393446)
		(end 146.609054 -254.558292)
		(width 0.18288)
		(layer "In2.Cu")
		(net "M_F_CPU1_CLK_DP<0>")
	)
	(segment
		(start 177.067972 -257.304032)
		(end 176.983136 -257.153664)
		(width 0.18288)
		(layer "In2.Cu")
		(net "M_F_CPU1_CLK_DP<0>")
	)
	(segment
		(start 155.226004 -253.733808)
		(end 148.49475 -253.733808)
		(width 0.18288)
		(layer "In2.Cu")
		(net "M_F_CPU1_CLK_DP<0>")
	)
	(segment
		(start 147.647406 -254.109728)
		(end 147.00758 -254.393446)
		(width 0.18288)
		(layer "In2.Cu")
		(net "M_F_CPU1_CLK_DP<0>")
	)
	(segment
		(start 184.416954 -260.21665)
		(end 184.158382 -259.958078)
		(width 0.18288)
		(layer "In2.Cu")
		(net "M_F_CPU1_CLK_DP<0>")
	)
	(segment
		(start 180.842412 -257.725164)
		(end 180.720492 -257.847084)
		(width 0.18288)
		(layer "In2.Cu")
		(net "M_F_CPU1_CLK_DP<0>")
	)
	(segment
		(start 180.720492 -257.847084)
		(end 180.187092 -257.847084)
		(width 0.18288)
		(layer "In2.Cu")
		(net "M_F_CPU1_CLK_DP<0>")
	)
	(segment
		(start 167.976296 -255.708404)
		(end 159.9946 -255.708404)
		(width 0.18288)
		(layer "In2.Cu")
		(net "M_F_CPU1_CLK_DP<0>")
	)
	(segment
		(start 183.338978 -259.493512)
		(end 183.338978 -258.37769)
		(width 0.18288)
		(layer "In2.Cu")
		(net "M_F_CPU1_CLK_DP<0>")
	)
	(segment
		(start 182.153052 -257.725164)
		(end 182.031132 -257.847084)
		(width 0.18288)
		(layer "In2.Cu")
		(net "M_F_CPU1_CLK_DP<0>")
	)
	(segment
		(start 139.96797 -253.39167)
		(end 134.38505 -253.39167)
		(width 0.18288)
		(layer "In2.Cu")
		(net "M_F_CPU1_CLK_DP<0>")
	)
	(segment
		(start 159.9946 -255.708404)
		(end 155.226004 -253.733808)
		(width 0.18288)
		(layer "In2.Cu")
		(net "M_F_CPU1_CLK_DP<0>")
	)
	(segment
		(start 148.49475 -253.733808)
		(end 147.647406 -254.109728)
		(width 0.18288)
		(layer "In2.Cu")
		(net "M_F_CPU1_CLK_DP<0>")
	)
	(segment
		(start 145.501106 -254.558292)
		(end 144.632172 -254.375158)
		(width 0.18288)
		(layer "In2.Cu")
		(net "M_F_CPU1_CLK_DP<0>")
	)
	(segment
		(start 180.065172 -257.725164)
		(end 179.040282 -257.725164)
		(width 0.18288)
		(layer "In2.Cu")
		(net "M_F_CPU1_CLK_DP<0>")
	)
	(segment
		(start 134.325106 -253.331726)
		(end 133.205982 -253.331726)
		(width 0.088646)
		(layer "In2.Cu")
		(net "M_F_CPU1_CLK_DP<0>")
	)
	(segment
		(start 182.031132 -257.847084)
		(end 181.497732 -257.847084)
		(width 0.18288)
		(layer "In2.Cu")
		(net "M_F_CPU1_CLK_DP<0>")
	)
	(segment
		(start 181.497732 -257.847084)
		(end 181.375812 -257.725164)
		(width 0.18288)
		(layer "In2.Cu")
		(net "M_F_CPU1_CLK_DP<0>")
	)
	(segment
		(start 132.05587 -255.490472)
		(end 132.11302 -255.547622)
		(width 0.088646)
		(layer "In2.Cu")
		(net "M_F_CPU1_CLK_DP<0>")
	)
	(segment
		(start 132.521452 -254.724916)
		(end 132.521452 -254.747776)
		(width 0.088646)
		(layer "In2.Cu")
		(net "M_F_CPU1_CLK_DP<0>")
	)
	(segment
		(start 182.686452 -257.725164)
		(end 182.153052 -257.725164)
		(width 0.18288)
		(layer "In2.Cu")
		(net "M_F_CPU1_CLK_DP<0>")
	)
	(segment
		(start 146.609054 -254.558292)
		(end 145.501106 -254.558292)
		(width 0.18288)
		(layer "In2.Cu")
		(net "M_F_CPU1_CLK_DP<0>")
	)
	(segment
		(start 177.732182 -257.361944)
		(end 177.582068 -257.44678)
		(width 0.18288)
		(layer "In2.Cu")
		(net "M_F_CPU1_CLK_DP<0>")
	)
	(segment
		(start 144.632172 -254.375158)
		(end 139.96797 -253.39167)
		(width 0.18288)
		(layer "In2.Cu")
		(net "M_F_CPU1_CLK_DP<0>")
	)
	(arc
		(start 132.99059 -253.919736)
		(mid 132.918782 -254.195432)
		(end 132.721604 -254.401066)
		(width 0.088646)
		(layer "In2.Cu")
		(net "M_F_CPU1_CLK_DP<0>")
	)
	(arc
		(start 132.521452 -254.747776)
		(mid 132.442233 -255.022461)
		(end 132.23875 -255.223264)
		(width 0.088646)
		(layer "In2.Cu")
		(net "M_F_CPU1_CLK_DP<0>")
	)
	(arc
		(start 132.22986 -255.228344)
		(mid 132.114051 -255.340273)
		(end 132.05587 -255.490472)
		(width 0.088646)
		(layer "In2.Cu")
		(net "M_F_CPU1_CLK_DP<0>")
	)
	(arc
		(start 132.721858 -254.401574)
		(mid 132.718309 -254.403618)
		(end 132.714746 -254.405638)
		(width 0.088646)
		(layer "In2.Cu")
		(net "M_F_CPU1_CLK_DP<0>")
	)
	(arc
		(start 132.70865 -254.409194)
		(mid 132.573717 -254.542548)
		(end 132.521452 -254.724916)
		(width 0.088646)
		(layer "In2.Cu")
		(net "M_F_CPU1_CLK_DP<0>")
	)
	(segment
		(start 130.546094 -255.011682)
		(end 130.546094 -255.547368)
		(width 0.20066)
		(layer "F.Cu")
		(net "M_F_CPU1_CLK_DN<1>")
	)
	(segment
		(start 176.896014 -259.366766)
		(end 178.000914 -259.366766)
		(width 0.20066)
		(layer "F.Cu")
		(net "M_F_CPU1_CLK_DN<1>")
	)
	(segment
		(start 130.546094 -255.547368)
		(end 130.546348 -255.547622)
		(width 0.20066)
		(layer "F.Cu")
		(net "M_F_CPU1_CLK_DN<1>")
	)
	(segment
		(start 133.270244 -254.733552)
		(end 133.270244 -254.742188)
		(width 0.088646)
		(layer "In2.Cu")
		(net "M_F_CPU1_CLK_DN<1>")
	)
	(segment
		(start 149.717506 -254.385826)
		(end 149.595586 -254.263906)
		(width 0.18288)
		(layer "In2.Cu")
		(net "M_F_CPU1_CLK_DN<1>")
	)
	(segment
		(start 176.896014 -259.366766)
		(end 176.873408 -259.366766)
		(width 0.18288)
		(layer "In2.Cu")
		(net "M_F_CPU1_CLK_DN<1>")
	)
	(segment
		(start 130.233674 -255.547622)
		(end 130.546348 -255.547622)
		(width 0.088646)
		(layer "In2.Cu")
		(net "M_F_CPU1_CLK_DN<1>")
	)
	(segment
		(start 139.393168 -254.549148)
		(end 139.155424 -254.440436)
		(width 0.088646)
		(layer "In2.Cu")
		(net "M_F_CPU1_CLK_DN<1>")
	)
	(segment
		(start 132.800344 -255.533398)
		(end 132.800344 -255.547622)
		(width 0.088646)
		(layer "In2.Cu")
		(net "M_F_CPU1_CLK_DN<1>")
	)
	(segment
		(start 169.684192 -256.49809)
		(end 167.945054 -256.244852)
		(width 0.18288)
		(layer "In2.Cu")
		(net "M_F_CPU1_CLK_DN<1>")
	)
	(segment
		(start 176.873408 -259.366766)
		(end 176.629822 -259.610352)
		(width 0.18288)
		(layer "In2.Cu")
		(net "M_F_CPU1_CLK_DN<1>")
	)
	(segment
		(start 146.931634 -254.930402)
		(end 145.19656 -254.930402)
		(width 0.18288)
		(layer "In2.Cu")
		(net "M_F_CPU1_CLK_DN<1>")
	)
	(segment
		(start 176.629822 -259.610352)
		(end 176.44491 -259.610352)
		(width 0.18288)
		(layer "In2.Cu")
		(net "M_F_CPU1_CLK_DN<1>")
	)
	(segment
		(start 149.595586 -254.263906)
		(end 149.062186 -254.263906)
		(width 0.18288)
		(layer "In2.Cu")
		(net "M_F_CPU1_CLK_DN<1>")
	)
	(segment
		(start 152.216866 -254.263906)
		(end 151.683466 -254.263906)
		(width 0.18288)
		(layer "In2.Cu")
		(net "M_F_CPU1_CLK_DN<1>")
	)
	(segment
		(start 176.271936 -259.437378)
		(end 175.7299 -258.158742)
		(width 0.18288)
		(layer "In2.Cu")
		(net "M_F_CPU1_CLK_DN<1>")
	)
	(segment
		(start 167.945054 -256.244852)
		(end 159.850836 -256.244852)
		(width 0.18288)
		(layer "In2.Cu")
		(net "M_F_CPU1_CLK_DN<1>")
	)
	(segment
		(start 151.561546 -254.385826)
		(end 151.028146 -254.385826)
		(width 0.18288)
		(layer "In2.Cu")
		(net "M_F_CPU1_CLK_DN<1>")
	)
	(segment
		(start 175.459898 -257.888486)
		(end 174.395892 -257.518154)
		(width 0.18288)
		(layer "In2.Cu")
		(net "M_F_CPU1_CLK_DN<1>")
	)
	(segment
		(start 150.372826 -254.263906)
		(end 150.250906 -254.385826)
		(width 0.18288)
		(layer "In2.Cu")
		(net "M_F_CPU1_CLK_DN<1>")
	)
	(segment
		(start 130.748278 -255.863344)
		(end 130.733546 -255.87198)
		(width 0.088646)
		(layer "In2.Cu")
		(net "M_F_CPU1_CLK_DN<1>")
	)
	(segment
		(start 152.338786 -254.385826)
		(end 152.216866 -254.263906)
		(width 0.18288)
		(layer "In2.Cu")
		(net "M_F_CPU1_CLK_DN<1>")
	)
	(segment
		(start 159.850836 -256.244852)
		(end 155.36291 -254.385826)
		(width 0.18288)
		(layer "In2.Cu")
		(net "M_F_CPU1_CLK_DN<1>")
	)
	(segment
		(start 148.246592 -254.385826)
		(end 146.931634 -254.930402)
		(width 0.18288)
		(layer "In2.Cu")
		(net "M_F_CPU1_CLK_DN<1>")
	)
	(segment
		(start 143.572738 -254.73914)
		(end 141.730222 -254.335026)
		(width 0.18288)
		(layer "In2.Cu")
		(net "M_F_CPU1_CLK_DN<1>")
	)
	(segment
		(start 139.778994 -254.549148)
		(end 139.393168 -254.549148)
		(width 0.088646)
		(layer "In2.Cu")
		(net "M_F_CPU1_CLK_DN<1>")
	)
	(segment
		(start 148.940266 -254.385826)
		(end 148.246592 -254.385826)
		(width 0.18288)
		(layer "In2.Cu")
		(net "M_F_CPU1_CLK_DN<1>")
	)
	(segment
		(start 175.7299 -258.158742)
		(end 175.459898 -257.888486)
		(width 0.18288)
		(layer "In2.Cu")
		(net "M_F_CPU1_CLK_DN<1>")
	)
	(segment
		(start 141.730222 -254.335026)
		(end 140.52931 -254.335026)
		(width 0.18288)
		(layer "In2.Cu")
		(net "M_F_CPU1_CLK_DN<1>")
	)
	(segment
		(start 145.19656 -254.930402)
		(end 143.572738 -254.73914)
		(width 0.18288)
		(layer "In2.Cu")
		(net "M_F_CPU1_CLK_DN<1>")
	)
	(segment
		(start 140.4747 -254.389636)
		(end 140.163804 -254.389636)
		(width 0.088646)
		(layer "In2.Cu")
		(net "M_F_CPU1_CLK_DN<1>")
	)
	(segment
		(start 151.683466 -254.263906)
		(end 151.561546 -254.385826)
		(width 0.18288)
		(layer "In2.Cu")
		(net "M_F_CPU1_CLK_DN<1>")
	)
	(segment
		(start 134.50316 -254.237998)
		(end 134.492746 -254.244094)
		(width 0.088646)
		(layer "In2.Cu")
		(net "M_F_CPU1_CLK_DN<1>")
	)
	(segment
		(start 150.906226 -254.263906)
		(end 150.372826 -254.263906)
		(width 0.18288)
		(layer "In2.Cu")
		(net "M_F_CPU1_CLK_DN<1>")
	)
	(segment
		(start 151.028146 -254.385826)
		(end 150.906226 -254.263906)
		(width 0.18288)
		(layer "In2.Cu")
		(net "M_F_CPU1_CLK_DN<1>")
	)
	(segment
		(start 150.250906 -254.385826)
		(end 149.717506 -254.385826)
		(width 0.18288)
		(layer "In2.Cu")
		(net "M_F_CPU1_CLK_DN<1>")
	)
	(segment
		(start 133.567678 -254.235458)
		(end 133.54685 -254.24765)
		(width 0.088646)
		(layer "In2.Cu")
		(net "M_F_CPU1_CLK_DN<1>")
	)
	(segment
		(start 131.68376 -255.865884)
		(end 131.673346 -255.87198)
		(width 0.088646)
		(layer "In2.Cu")
		(net "M_F_CPU1_CLK_DN<1>")
	)
	(segment
		(start 149.062186 -254.263906)
		(end 148.940266 -254.385826)
		(width 0.18288)
		(layer "In2.Cu")
		(net "M_F_CPU1_CLK_DN<1>")
	)
	(segment
		(start 140.52931 -254.335026)
		(end 140.4747 -254.389636)
		(width 0.088646)
		(layer "In2.Cu")
		(net "M_F_CPU1_CLK_DN<1>")
	)
	(segment
		(start 174.395892 -257.518154)
		(end 169.684192 -256.49809)
		(width 0.18288)
		(layer "In2.Cu")
		(net "M_F_CPU1_CLK_DN<1>")
	)
	(segment
		(start 139.155424 -254.440436)
		(end 138.81735 -254.244348)
		(width 0.088646)
		(layer "In2.Cu")
		(net "M_F_CPU1_CLK_DN<1>")
	)
	(segment
		(start 176.44491 -259.610352)
		(end 176.271936 -259.437378)
		(width 0.18288)
		(layer "In2.Cu")
		(net "M_F_CPU1_CLK_DN<1>")
	)
	(segment
		(start 140.163804 -254.389636)
		(end 139.778994 -254.549148)
		(width 0.088646)
		(layer "In2.Cu")
		(net "M_F_CPU1_CLK_DN<1>")
	)
	(segment
		(start 130.17627 -255.605026)
		(end 130.233674 -255.547622)
		(width 0.088646)
		(layer "In2.Cu")
		(net "M_F_CPU1_CLK_DN<1>")
	)
	(segment
		(start 155.36291 -254.385826)
		(end 152.338786 -254.385826)
		(width 0.18288)
		(layer "In2.Cu")
		(net "M_F_CPU1_CLK_DN<1>")
	)
	(arc
		(start 135.432292 -254.244094)
		(mid 135.245094 -254.294237)
		(end 135.057896 -254.244094)
		(width 0.088646)
		(layer "In2.Cu")
		(net "M_F_CPU1_CLK_DN<1>")
	)
	(arc
		(start 131.673346 -255.87198)
		(mid 131.486148 -255.922123)
		(end 131.29895 -255.87198)
		(width 0.088646)
		(layer "In2.Cu")
		(net "M_F_CPU1_CLK_DN<1>")
	)
	(arc
		(start 133.54685 -254.24765)
		(mid 133.344263 -254.454001)
		(end 133.270244 -254.733552)
		(width 0.088646)
		(layer "In2.Cu")
		(net "M_F_CPU1_CLK_DN<1>")
	)
	(arc
		(start 138.81735 -254.244348)
		(mid 138.534567 -254.168411)
		(end 138.251692 -254.244094)
		(width 0.088646)
		(layer "In2.Cu")
		(net "M_F_CPU1_CLK_DN<1>")
	)
	(arc
		(start 136.372092 -254.244094)
		(mid 136.184894 -254.294237)
		(end 135.997696 -254.244094)
		(width 0.088646)
		(layer "In2.Cu")
		(net "M_F_CPU1_CLK_DN<1>")
	)
	(arc
		(start 138.251692 -254.244094)
		(mid 138.064494 -254.294237)
		(end 137.877296 -254.244094)
		(width 0.088646)
		(layer "In2.Cu")
		(net "M_F_CPU1_CLK_DN<1>")
	)
	(arc
		(start 134.11835 -254.244094)
		(mid 133.844151 -254.168259)
		(end 133.567678 -254.235458)
		(width 0.088646)
		(layer "In2.Cu")
		(net "M_F_CPU1_CLK_DN<1>")
	)
	(arc
		(start 136.937496 -254.244094)
		(mid 136.654794 -254.168318)
		(end 136.372092 -254.244094)
		(width 0.088646)
		(layer "In2.Cu")
		(net "M_F_CPU1_CLK_DN<1>")
	)
	(arc
		(start 130.733546 -255.87198)
		(mid 130.384554 -255.88537)
		(end 130.17627 -255.605026)
		(width 0.088646)
		(layer "In2.Cu")
		(net "M_F_CPU1_CLK_DN<1>")
	)
	(arc
		(start 133.270244 -254.742188)
		(mid 133.217974 -254.924553)
		(end 133.083046 -255.05791)
		(width 0.088646)
		(layer "In2.Cu")
		(net "M_F_CPU1_CLK_DN<1>")
	)
	(arc
		(start 132.800344 -255.547622)
		(mid 132.613045 -255.872063)
		(end 132.238496 -255.87198)
		(width 0.088646)
		(layer "In2.Cu")
		(net "M_F_CPU1_CLK_DN<1>")
	)
	(arc
		(start 133.083046 -255.05791)
		(mid 132.879565 -255.258714)
		(end 132.800344 -255.533398)
		(width 0.088646)
		(layer "In2.Cu")
		(net "M_F_CPU1_CLK_DN<1>")
	)
	(arc
		(start 137.311892 -254.244094)
		(mid 137.124694 -254.294237)
		(end 136.937496 -254.244094)
		(width 0.088646)
		(layer "In2.Cu")
		(net "M_F_CPU1_CLK_DN<1>")
	)
	(arc
		(start 137.877296 -254.244094)
		(mid 137.594594 -254.168318)
		(end 137.311892 -254.244094)
		(width 0.088646)
		(layer "In2.Cu")
		(net "M_F_CPU1_CLK_DN<1>")
	)
	(arc
		(start 134.492746 -254.244094)
		(mid 134.305548 -254.294237)
		(end 134.11835 -254.244094)
		(width 0.088646)
		(layer "In2.Cu")
		(net "M_F_CPU1_CLK_DN<1>")
	)
	(arc
		(start 132.238496 -255.87198)
		(mid 131.961937 -255.796237)
		(end 131.68376 -255.865884)
		(width 0.088646)
		(layer "In2.Cu")
		(net "M_F_CPU1_CLK_DN<1>")
	)
	(arc
		(start 135.997696 -254.244094)
		(mid 135.714994 -254.168318)
		(end 135.432292 -254.244094)
		(width 0.088646)
		(layer "In2.Cu")
		(net "M_F_CPU1_CLK_DN<1>")
	)
	(arc
		(start 135.057896 -254.244094)
		(mid 134.781337 -254.168351)
		(end 134.50316 -254.237998)
		(width 0.088646)
		(layer "In2.Cu")
		(net "M_F_CPU1_CLK_DN<1>")
	)
	(arc
		(start 131.29895 -255.87198)
		(mid 131.024751 -255.796145)
		(end 130.748278 -255.863344)
		(width 0.088646)
		(layer "In2.Cu")
		(net "M_F_CPU1_CLK_DN<1>")
	)
	(segment
		(start 184.439814 -259.366766)
		(end 185.544714 -259.366766)
		(width 0.20066)
		(layer "F.Cu")
		(net "M_F_CPU1_CLK_DN<0>")
	)
	(segment
		(start 131.485894 -255.011682)
		(end 131.485894 -255.547368)
		(width 0.20066)
		(layer "F.Cu")
		(net "M_F_CPU1_CLK_DN<0>")
	)
	(segment
		(start 131.485894 -255.547368)
		(end 131.486148 -255.547622)
		(width 0.20066)
		(layer "F.Cu")
		(net "M_F_CPU1_CLK_DN<0>")
	)
	(segment
		(start 132.143754 -255.058418)
		(end 132.143754 -255.058164)
		(width 0.088646)
		(layer "In2.Cu")
		(net "M_F_CPU1_CLK_DN<0>")
	)
	(segment
		(start 184.158382 -259.648198)
		(end 183.932068 -259.648198)
		(width 0.18288)
		(layer "In2.Cu")
		(net "M_F_CPU1_CLK_DN<0>")
	)
	(segment
		(start 134.38505 -253.08179)
		(end 134.32536 -253.14148)
		(width 0.088646)
		(layer "In2.Cu")
		(net "M_F_CPU1_CLK_DN<0>")
	)
	(segment
		(start 160.056322 -255.398524)
		(end 155.287726 -253.423928)
		(width 0.18288)
		(layer "In2.Cu")
		(net "M_F_CPU1_CLK_DN<0>")
	)
	(segment
		(start 183.932068 -259.648198)
		(end 183.648858 -259.364988)
		(width 0.18288)
		(layer "In2.Cu")
		(net "M_F_CPU1_CLK_DN<0>")
	)
	(segment
		(start 133.126988 -253.14148)
		(end 132.800344 -253.468124)
		(width 0.088646)
		(layer "In2.Cu")
		(net "M_F_CPU1_CLK_DN<0>")
	)
	(segment
		(start 132.330698 -254.718058)
		(end 132.330698 -254.733552)
		(width 0.088646)
		(layer "In2.Cu")
		(net "M_F_CPU1_CLK_DN<0>")
	)
	(segment
		(start 145.533618 -254.248412)
		(end 144.893792 -254.113538)
		(width 0.18288)
		(layer "In2.Cu")
		(net "M_F_CPU1_CLK_DN<0>")
	)
	(segment
		(start 132.800344 -253.468124)
		(end 132.800344 -253.919736)
		(width 0.088646)
		(layer "In2.Cu")
		(net "M_F_CPU1_CLK_DN<0>")
	)
	(segment
		(start 132.613908 -254.243586)
		(end 132.612892 -254.244094)
		(width 0.088646)
		(layer "In2.Cu")
		(net "M_F_CPU1_CLK_DN<0>")
	)
	(segment
		(start 132.330698 -254.733552)
		(end 132.331206 -254.744982)
		(width 0.088646)
		(layer "In2.Cu")
		(net "M_F_CPU1_CLK_DN<0>")
	)
	(segment
		(start 134.32536 -253.14148)
		(end 133.126988 -253.14148)
		(width 0.088646)
		(layer "In2.Cu")
		(net "M_F_CPU1_CLK_DN<0>")
	)
	(segment
		(start 131.864354 -255.482344)
		(end 131.799076 -255.547622)
		(width 0.088646)
		(layer "In2.Cu")
		(net "M_F_CPU1_CLK_DN<0>")
	)
	(segment
		(start 167.99941 -255.398524)
		(end 160.056322 -255.398524)
		(width 0.18288)
		(layer "In2.Cu")
		(net "M_F_CPU1_CLK_DN<0>")
	)
	(segment
		(start 132.143754 -255.058164)
		(end 132.1435 -255.05791)
		(width 0.088646)
		(layer "In2.Cu")
		(net "M_F_CPU1_CLK_DN<0>")
	)
	(segment
		(start 131.799076 -255.547622)
		(end 131.486148 -255.547622)
		(width 0.088646)
		(layer "In2.Cu")
		(net "M_F_CPU1_CLK_DN<0>")
	)
	(segment
		(start 144.893792 -254.113538)
		(end 140.000482 -253.08179)
		(width 0.18288)
		(layer "In2.Cu")
		(net "M_F_CPU1_CLK_DN<0>")
	)
	(segment
		(start 146.885406 -254.108458)
		(end 146.547078 -254.248412)
		(width 0.18288)
		(layer "In2.Cu")
		(net "M_F_CPU1_CLK_DN<0>")
	)
	(segment
		(start 183.648858 -259.364988)
		(end 183.648858 -258.249166)
		(width 0.18288)
		(layer "In2.Cu")
		(net "M_F_CPU1_CLK_DN<0>")
	)
	(segment
		(start 148.428964 -253.423928)
		(end 147.521676 -253.826264)
		(width 0.18288)
		(layer "In2.Cu")
		(net "M_F_CPU1_CLK_DN<0>")
	)
	(segment
		(start 179.0827 -257.415284)
		(end 176.257712 -256.630424)
		(width 0.18288)
		(layer "In2.Cu")
		(net "M_F_CPU1_CLK_DN<0>")
	)
	(segment
		(start 132.621782 -254.239014)
		(end 132.613908 -254.243586)
		(width 0.088646)
		(layer "In2.Cu")
		(net "M_F_CPU1_CLK_DN<0>")
	)
	(segment
		(start 155.287726 -253.423928)
		(end 148.428964 -253.423928)
		(width 0.18288)
		(layer "In2.Cu")
		(net "M_F_CPU1_CLK_DN<0>")
	)
	(segment
		(start 140.000482 -253.08179)
		(end 134.38505 -253.08179)
		(width 0.18288)
		(layer "In2.Cu")
		(net "M_F_CPU1_CLK_DN<0>")
	)
	(segment
		(start 147.521676 -253.826264)
		(end 146.885406 -254.108458)
		(width 0.18288)
		(layer "In2.Cu")
		(net "M_F_CPU1_CLK_DN<0>")
	)
	(segment
		(start 183.648858 -258.249166)
		(end 182.814976 -257.415284)
		(width 0.18288)
		(layer "In2.Cu")
		(net "M_F_CPU1_CLK_DN<0>")
	)
	(segment
		(start 176.257712 -256.630424)
		(end 167.99941 -255.398524)
		(width 0.18288)
		(layer "In2.Cu")
		(net "M_F_CPU1_CLK_DN<0>")
	)
	(segment
		(start 182.814976 -257.415284)
		(end 179.0827 -257.415284)
		(width 0.18288)
		(layer "In2.Cu")
		(net "M_F_CPU1_CLK_DN<0>")
	)
	(segment
		(start 146.547078 -254.248412)
		(end 145.533618 -254.248412)
		(width 0.18288)
		(layer "In2.Cu")
		(net "M_F_CPU1_CLK_DN<0>")
	)
	(segment
		(start 184.439814 -259.366766)
		(end 184.158382 -259.648198)
		(width 0.18288)
		(layer "In2.Cu")
		(net "M_F_CPU1_CLK_DN<0>")
	)
	(arc
		(start 132.331206 -254.744982)
		(mid 132.278209 -254.92606)
		(end 132.143754 -255.058418)
		(width 0.088646)
		(layer "In2.Cu")
		(net "M_F_CPU1_CLK_DN<0>")
	)
	(arc
		(start 132.800344 -253.919736)
		(mid 132.752665 -254.102636)
		(end 132.621782 -254.239014)
		(width 0.088646)
		(layer "In2.Cu")
		(net "M_F_CPU1_CLK_DN<0>")
	)
	(arc
		(start 132.612892 -254.244094)
		(mid 132.410069 -254.444325)
		(end 132.330698 -254.718058)
		(width 0.088646)
		(layer "In2.Cu")
		(net "M_F_CPU1_CLK_DN<0>")
	)
	(arc
		(start 132.1435 -255.05791)
		(mid 131.959518 -255.228188)
		(end 131.867148 -255.461262)
		(width 0.088646)
		(layer "In2.Cu")
		(net "M_F_CPU1_CLK_DN<0>")
	)
	(arc
		(start 131.867148 -255.461262)
		(mid 131.865652 -255.47179)
		(end 131.864354 -255.482344)
		(width 0.088646)
		(layer "In2.Cu")
		(net "M_F_CPU1_CLK_DN<0>")
	)
	(segment
		(start 176.99863 -269.141702)
		(end 179.004976 -269.141702)
		(width 0.1016)
		(layer "F.Cu")
		(net "M_F_CPU1_ALERT_N")
	)
	(segment
		(start 173.900846 -269.566644)
		(end 174.454312 -269.566644)
		(width 0.20066)
		(layer "F.Cu")
		(net "M_F_CPU1_ALERT_N")
	)
	(segment
		(start 121.618248 -254.733298)
		(end 121.617994 -254.733552)
		(width 0.20066)
		(layer "F.Cu")
		(net "M_F_CPU1_ALERT_N")
	)
	(segment
		(start 179.004976 -269.141702)
		(end 179.011326 -269.135352)
		(width 0.1016)
		(layer "F.Cu")
		(net "M_F_CPU1_ALERT_N")
	)
	(segment
		(start 176.465992 -269.127224)
		(end 176.930558 -269.127224)
		(width 0.20066)
		(layer "F.Cu")
		(net "M_F_CPU1_ALERT_N")
	)
	(segment
		(start 172.795946 -269.566644)
		(end 173.900846 -269.566644)
		(width 0.20066)
		(layer "F.Cu")
		(net "M_F_CPU1_ALERT_N")
	)
	(segment
		(start 176.333404 -269.62735)
		(end 176.333404 -269.259812)
		(width 0.20066)
		(layer "F.Cu")
		(net "M_F_CPU1_ALERT_N")
	)
	(segment
		(start 176.333404 -269.259812)
		(end 176.465992 -269.127224)
		(width 0.20066)
		(layer "F.Cu")
		(net "M_F_CPU1_ALERT_N")
	)
	(segment
		(start 179.961032 -269.76959)
		(end 180.737764 -269.76959)
		(width 0.20066)
		(layer "F.Cu")
		(net "M_F_CPU1_ALERT_N")
	)
	(segment
		(start 176.930558 -269.127224)
		(end 176.984152 -269.127224)
		(width 0.101854)
		(layer "F.Cu")
		(net "M_F_CPU1_ALERT_N")
	)
	(segment
		(start 180.737764 -269.76959)
		(end 180.94071 -269.566644)
		(width 0.20066)
		(layer "F.Cu")
		(net "M_F_CPU1_ALERT_N")
	)
	(segment
		(start 179.011326 -269.135352)
		(end 179.326794 -269.135352)
		(width 0.20066)
		(layer "F.Cu")
		(net "M_F_CPU1_ALERT_N")
	)
	(segment
		(start 176.984152 -269.127224)
		(end 176.99863 -269.141702)
		(width 0.1016)
		(layer "F.Cu")
		(net "M_F_CPU1_ALERT_N")
	)
	(segment
		(start 174.454312 -269.566644)
		(end 174.702978 -269.81531)
		(width 0.20066)
		(layer "F.Cu")
		(net "M_F_CPU1_ALERT_N")
	)
	(segment
		(start 180.94071 -269.566644)
		(end 181.444646 -269.566644)
		(width 0.20066)
		(layer "F.Cu")
		(net "M_F_CPU1_ALERT_N")
	)
	(segment
		(start 176.145444 -269.81531)
		(end 176.333404 -269.62735)
		(width 0.20066)
		(layer "F.Cu")
		(net "M_F_CPU1_ALERT_N")
	)
	(segment
		(start 179.326794 -269.135352)
		(end 179.961032 -269.76959)
		(width 0.20066)
		(layer "F.Cu")
		(net "M_F_CPU1_ALERT_N")
	)
	(segment
		(start 121.618248 -254.197612)
		(end 121.618248 -254.733298)
		(width 0.20066)
		(layer "F.Cu")
		(net "M_F_CPU1_ALERT_N")
	)
	(segment
		(start 174.702978 -269.81531)
		(end 176.145444 -269.81531)
		(width 0.20066)
		(layer "F.Cu")
		(net "M_F_CPU1_ALERT_N")
	)
	(via
		(at 121.617994 -254.733552)
		(size 0.4572)
		(drill 0.2032)
		(layers "F.Cu" "B.Cu")
		(net "M_F_CPU1_ALERT_N")
	)
	(via
		(at 172.795946 -269.566644)
		(size 0.4572)
		(drill 0.2032)
		(layers "F.Cu" "B.Cu")
		(net "M_F_CPU1_ALERT_N")
	)
	(via
		(at 127.726948 -255.547622)
		(size 0.4318)
		(drill 0.2032)
		(layers "F.Cu" "B.Cu")
		(net "M_F_CPU1_ALERT_N")
	)
	(segment
		(start 122.31243 -255.134364)
		(end 121.95048 -255.087628)
		(width 0.20066)
		(layer "B.Cu")
		(net "M_F_CPU1_ALERT_N")
	)
	(segment
		(start 126.10846 -255.155446)
		(end 126.072646 -255.134872)
		(width 0.20066)
		(layer "B.Cu")
		(net "M_F_CPU1_ALERT_N")
	)
	(segment
		(start 123.262644 -255.14046)
		(end 123.249182 -255.132586)
		(width 0.20066)
		(layer "B.Cu")
		(net "M_F_CPU1_ALERT_N")
	)
	(segment
		(start 127.726948 -255.547622)
		(end 127.7239 -255.536446)
		(width 0.20066)
		(layer "B.Cu")
		(net "M_F_CPU1_ALERT_N")
	)
	(segment
		(start 124.672344 -255.14046)
		(end 124.662692 -255.146048)
		(width 0.20066)
		(layer "B.Cu")
		(net "M_F_CPU1_ALERT_N")
	)
	(segment
		(start 121.8438 -255.026414)
		(end 121.617994 -254.733552)
		(width 0.20066)
		(layer "B.Cu")
		(net "M_F_CPU1_ALERT_N")
	)
	(segment
		(start 124.202698 -255.14046)
		(end 124.193046 -255.134872)
		(width 0.20066)
		(layer "B.Cu")
		(net "M_F_CPU1_ALERT_N")
	)
	(segment
		(start 122.322844 -255.14046)
		(end 122.31243 -255.134364)
		(width 0.20066)
		(layer "B.Cu")
		(net "M_F_CPU1_ALERT_N")
	)
	(segment
		(start 127.7239 -255.536446)
		(end 127.038354 -255.14046)
		(width 0.20066)
		(layer "B.Cu")
		(net "M_F_CPU1_ALERT_N")
	)
	(segment
		(start 126.551944 -255.14046)
		(end 126.525782 -255.155446)
		(width 0.20066)
		(layer "B.Cu")
		(net "M_F_CPU1_ALERT_N")
	)
	(arc
		(start 125.612144 -255.14046)
		(mid 125.377194 -255.20342)
		(end 125.142244 -255.14046)
		(width 0.20066)
		(layer "B.Cu")
		(net "M_F_CPU1_ALERT_N")
	)
	(arc
		(start 123.732544 -255.14046)
		(mid 123.497594 -255.20342)
		(end 123.262644 -255.14046)
		(width 0.20066)
		(layer "B.Cu")
		(net "M_F_CPU1_ALERT_N")
	)
	(arc
		(start 127.038354 -255.14046)
		(mid 126.795166 -255.075376)
		(end 126.551944 -255.14046)
		(width 0.20066)
		(layer "B.Cu")
		(net "M_F_CPU1_ALERT_N")
	)
	(arc
		(start 125.142244 -255.14046)
		(mid 124.907294 -255.077534)
		(end 124.672344 -255.14046)
		(width 0.20066)
		(layer "B.Cu")
		(net "M_F_CPU1_ALERT_N")
	)
	(arc
		(start 124.662692 -255.146048)
		(mid 124.431961 -255.203409)
		(end 124.202698 -255.14046)
		(width 0.20066)
		(layer "B.Cu")
		(net "M_F_CPU1_ALERT_N")
	)
	(arc
		(start 122.792744 -255.14046)
		(mid 122.557794 -255.20342)
		(end 122.322844 -255.14046)
		(width 0.20066)
		(layer "B.Cu")
		(net "M_F_CPU1_ALERT_N")
	)
	(arc
		(start 123.249182 -255.132586)
		(mid 123.019929 -255.077372)
		(end 122.792744 -255.14046)
		(width 0.20066)
		(layer "B.Cu")
		(net "M_F_CPU1_ALERT_N")
	)
	(arc
		(start 126.072646 -255.134872)
		(mid 125.841661 -255.077421)
		(end 125.612144 -255.14046)
		(width 0.20066)
		(layer "B.Cu")
		(net "M_F_CPU1_ALERT_N")
	)
	(arc
		(start 121.95048 -255.087628)
		(mid 121.891045 -255.067636)
		(end 121.8438 -255.026414)
		(width 0.20066)
		(layer "B.Cu")
		(net "M_F_CPU1_ALERT_N")
	)
	(arc
		(start 124.193046 -255.134872)
		(mid 123.962061 -255.077421)
		(end 123.732544 -255.14046)
		(width 0.20066)
		(layer "B.Cu")
		(net "M_F_CPU1_ALERT_N")
	)
	(arc
		(start 126.525782 -255.155446)
		(mid 126.317138 -255.211425)
		(end 126.10846 -255.155446)
		(width 0.20066)
		(layer "B.Cu")
		(net "M_F_CPU1_ALERT_N")
	)
	(segment
		(start 130.733546 -258.478782)
		(end 130.733292 -258.478782)
		(width 0.088646)
		(layer "In2.Cu")
		(net "M_F_CPU1_ALERT_N")
	)
	(segment
		(start 128.355344 -256.020824)
		(end 127.726948 -255.547622)
		(width 0.088646)
		(layer "In2.Cu")
		(net "M_F_CPU1_ALERT_N")
	)
	(segment
		(start 137.326624 -260.11505)
		(end 137.311892 -260.106414)
		(width 0.088646)
		(layer "In2.Cu")
		(net "M_F_CPU1_ALERT_N")
	)
	(segment
		(start 129.511044 -257.989578)
		(end 129.511044 -257.98907)
		(width 0.088646)
		(layer "In2.Cu")
		(net "M_F_CPU1_ALERT_N")
	)
	(segment
		(start 128.392682 -256.04216)
		(end 128.383792 -256.03708)
		(width 0.088646)
		(layer "In2.Cu")
		(net "M_F_CPU1_ALERT_N")
	)
	(segment
		(start 140.90015 -259.902706)
		(end 139.960604 -259.902706)
		(width 0.088646)
		(layer "In2.Cu")
		(net "M_F_CPU1_ALERT_N")
	)
	(segment
		(start 139.960604 -259.902706)
		(end 139.756896 -260.106414)
		(width 0.088646)
		(layer "In2.Cu")
		(net "M_F_CPU1_ALERT_N")
	)
	(segment
		(start 172.795946 -269.566644)
		(end 172.31233 -269.083028)
		(width 0.18288)
		(layer "In2.Cu")
		(net "M_F_CPU1_ALERT_N")
	)
	(segment
		(start 134.50316 -260.11251)
		(end 134.492746 -260.106414)
		(width 0.088646)
		(layer "In2.Cu")
		(net "M_F_CPU1_ALERT_N")
	)
	(segment
		(start 132.151882 -259.297678)
		(end 132.142992 -259.292598)
		(width 0.088646)
		(layer "In2.Cu")
		(net "M_F_CPU1_ALERT_N")
	)
	(segment
		(start 138.266424 -260.11505)
		(end 138.251692 -260.106414)
		(width 0.088646)
		(layer "In2.Cu")
		(net "M_F_CPU1_ALERT_N")
	)
	(segment
		(start 146.018758 -260.20395)
		(end 145.29181 -259.902706)
		(width 0.18288)
		(layer "In2.Cu")
		(net "M_F_CPU1_ALERT_N")
	)
	(segment
		(start 131.860798 -258.803648)
		(end 131.860798 -258.80314)
		(width 0.088646)
		(layer "In2.Cu")
		(net "M_F_CPU1_ALERT_N")
	)
	(segment
		(start 128.8542 -256.85115)
		(end 128.853946 -256.850896)
		(width 0.088646)
		(layer "In2.Cu")
		(net "M_F_CPU1_ALERT_N")
	)
	(segment
		(start 157.127956 -266.580366)
		(end 152.441402 -261.893812)
		(width 0.18288)
		(layer "In2.Cu")
		(net "M_F_CPU1_ALERT_N")
	)
	(segment
		(start 169.03319 -269.083028)
		(end 168.186354 -268.236192)
		(width 0.18288)
		(layer "In2.Cu")
		(net "M_F_CPU1_ALERT_N")
	)
	(segment
		(start 168.186354 -268.236192)
		(end 165.091364 -268.236192)
		(width 0.18288)
		(layer "In2.Cu")
		(net "M_F_CPU1_ALERT_N")
	)
	(segment
		(start 147.70862 -261.893812)
		(end 146.018758 -260.20395)
		(width 0.18288)
		(layer "In2.Cu")
		(net "M_F_CPU1_ALERT_N")
	)
	(segment
		(start 172.31233 -269.083028)
		(end 169.03319 -269.083028)
		(width 0.18288)
		(layer "In2.Cu")
		(net "M_F_CPU1_ALERT_N")
	)
	(segment
		(start 129.041398 -257.190748)
		(end 129.041398 -257.175254)
		(width 0.088646)
		(layer "In2.Cu")
		(net "M_F_CPU1_ALERT_N")
	)
	(segment
		(start 161.019744 -267.375132)
		(end 160.224978 -266.580366)
		(width 0.18288)
		(layer "In2.Cu")
		(net "M_F_CPU1_ALERT_N")
	)
	(segment
		(start 164.230304 -267.375132)
		(end 161.019744 -267.375132)
		(width 0.18288)
		(layer "In2.Cu")
		(net "M_F_CPU1_ALERT_N")
	)
	(segment
		(start 160.224978 -266.580366)
		(end 157.127956 -266.580366)
		(width 0.18288)
		(layer "In2.Cu")
		(net "M_F_CPU1_ALERT_N")
	)
	(segment
		(start 152.441402 -261.893812)
		(end 147.70862 -261.893812)
		(width 0.18288)
		(layer "In2.Cu")
		(net "M_F_CPU1_ALERT_N")
	)
	(segment
		(start 129.793746 -258.478782)
		(end 129.793492 -258.478782)
		(width 0.088646)
		(layer "In2.Cu")
		(net "M_F_CPU1_ALERT_N")
	)
	(segment
		(start 128.853946 -256.850896)
		(end 128.841754 -256.843784)
		(width 0.088646)
		(layer "In2.Cu")
		(net "M_F_CPU1_ALERT_N")
	)
	(segment
		(start 131.673346 -258.478782)
		(end 131.673092 -258.478782)
		(width 0.088646)
		(layer "In2.Cu")
		(net "M_F_CPU1_ALERT_N")
	)
	(segment
		(start 131.673346 -258.479036)
		(end 131.673346 -258.478782)
		(width 0.088646)
		(layer "In2.Cu")
		(net "M_F_CPU1_ALERT_N")
	)
	(segment
		(start 132.613908 -260.106414)
		(end 132.613146 -260.10616)
		(width 0.088646)
		(layer "In2.Cu")
		(net "M_F_CPU1_ALERT_N")
	)
	(segment
		(start 165.091364 -268.236192)
		(end 164.230304 -267.375132)
		(width 0.18288)
		(layer "In2.Cu")
		(net "M_F_CPU1_ALERT_N")
	)
	(segment
		(start 133.563106 -260.11251)
		(end 133.552692 -260.106414)
		(width 0.088646)
		(layer "In2.Cu")
		(net "M_F_CPU1_ALERT_N")
	)
	(segment
		(start 128.384046 -256.03708)
		(end 128.355344 -256.020824)
		(width 0.088646)
		(layer "In2.Cu")
		(net "M_F_CPU1_ALERT_N")
	)
	(segment
		(start 129.332482 -257.669792)
		(end 129.323592 -257.664712)
		(width 0.088646)
		(layer "In2.Cu")
		(net "M_F_CPU1_ALERT_N")
	)
	(segment
		(start 136.386824 -260.11505)
		(end 136.372092 -260.106414)
		(width 0.088646)
		(layer "In2.Cu")
		(net "M_F_CPU1_ALERT_N")
	)
	(segment
		(start 145.29181 -259.902706)
		(end 140.90015 -259.902706)
		(width 0.18288)
		(layer "In2.Cu")
		(net "M_F_CPU1_ALERT_N")
	)
	(segment
		(start 128.383792 -256.03708)
		(end 128.384046 -256.03708)
		(width 0.088646)
		(layer "In2.Cu")
		(net "M_F_CPU1_ALERT_N")
	)
	(segment
		(start 135.432292 -260.106414)
		(end 135.432038 -260.106414)
		(width 0.088646)
		(layer "In2.Cu")
		(net "M_F_CPU1_ALERT_N")
	)
	(segment
		(start 139.206224 -260.11505)
		(end 139.191492 -260.106414)
		(width 0.088646)
		(layer "In2.Cu")
		(net "M_F_CPU1_ALERT_N")
	)
	(arc
		(start 139.191492 -260.106414)
		(mid 139.004294 -260.056271)
		(end 138.817096 -260.106414)
		(width 0.088646)
		(layer "In2.Cu")
		(net "M_F_CPU1_ALERT_N")
	)
	(arc
		(start 128.571244 -256.361438)
		(mid 128.523565 -256.178538)
		(end 128.392682 -256.04216)
		(width 0.088646)
		(layer "In2.Cu")
		(net "M_F_CPU1_ALERT_N")
	)
	(arc
		(start 130.35915 -258.478782)
		(mid 130.076448 -258.554524)
		(end 129.793746 -258.478782)
		(width 0.088646)
		(layer "In2.Cu")
		(net "M_F_CPU1_ALERT_N")
	)
	(arc
		(start 138.251692 -260.106414)
		(mid 138.064494 -260.056271)
		(end 137.877296 -260.106414)
		(width 0.088646)
		(layer "In2.Cu")
		(net "M_F_CPU1_ALERT_N")
	)
	(arc
		(start 133.178296 -260.106414)
		(mid 132.896102 -260.182004)
		(end 132.613908 -260.106414)
		(width 0.088646)
		(layer "In2.Cu")
		(net "M_F_CPU1_ALERT_N")
	)
	(arc
		(start 139.756896 -260.106414)
		(mid 139.482697 -260.182249)
		(end 139.206224 -260.11505)
		(width 0.088646)
		(layer "In2.Cu")
		(net "M_F_CPU1_ALERT_N")
	)
	(arc
		(start 135.432038 -260.106414)
		(mid 135.244984 -260.056364)
		(end 135.057896 -260.106414)
		(width 0.088646)
		(layer "In2.Cu")
		(net "M_F_CPU1_ALERT_N")
	)
	(arc
		(start 129.323592 -257.664712)
		(mid 129.120769 -257.464481)
		(end 129.041398 -257.190748)
		(width 0.088646)
		(layer "In2.Cu")
		(net "M_F_CPU1_ALERT_N")
	)
	(arc
		(start 133.552692 -260.106414)
		(mid 133.365494 -260.056237)
		(end 133.178296 -260.106414)
		(width 0.088646)
		(layer "In2.Cu")
		(net "M_F_CPU1_ALERT_N")
	)
	(arc
		(start 134.11835 -260.106414)
		(mid 133.841537 -260.182284)
		(end 133.563106 -260.11251)
		(width 0.088646)
		(layer "In2.Cu")
		(net "M_F_CPU1_ALERT_N")
	)
	(arc
		(start 132.613146 -260.10616)
		(mid 132.406202 -259.89945)
		(end 132.330444 -259.616956)
		(width 0.088646)
		(layer "In2.Cu")
		(net "M_F_CPU1_ALERT_N")
	)
	(arc
		(start 134.492746 -260.106414)
		(mid 134.305548 -260.056271)
		(end 134.11835 -260.106414)
		(width 0.088646)
		(layer "In2.Cu")
		(net "M_F_CPU1_ALERT_N")
	)
	(arc
		(start 129.793492 -258.478782)
		(mid 129.586732 -258.272019)
		(end 129.511044 -257.989578)
		(width 0.088646)
		(layer "In2.Cu")
		(net "M_F_CPU1_ALERT_N")
	)
	(arc
		(start 131.29895 -258.478782)
		(mid 131.016248 -258.554524)
		(end 130.733546 -258.478782)
		(width 0.088646)
		(layer "In2.Cu")
		(net "M_F_CPU1_ALERT_N")
	)
	(arc
		(start 131.860798 -258.80314)
		(mid 131.810505 -258.615964)
		(end 131.673346 -258.479036)
		(width 0.088646)
		(layer "In2.Cu")
		(net "M_F_CPU1_ALERT_N")
	)
	(arc
		(start 131.673092 -258.478782)
		(mid 131.486038 -258.428732)
		(end 131.29895 -258.478782)
		(width 0.088646)
		(layer "In2.Cu")
		(net "M_F_CPU1_ALERT_N")
	)
	(arc
		(start 138.817096 -260.106414)
		(mid 138.542897 -260.182249)
		(end 138.266424 -260.11505)
		(width 0.088646)
		(layer "In2.Cu")
		(net "M_F_CPU1_ALERT_N")
	)
	(arc
		(start 136.372092 -260.106414)
		(mid 136.184894 -260.056271)
		(end 135.997696 -260.106414)
		(width 0.088646)
		(layer "In2.Cu")
		(net "M_F_CPU1_ALERT_N")
	)
	(arc
		(start 136.937496 -260.106414)
		(mid 136.663297 -260.182249)
		(end 136.386824 -260.11505)
		(width 0.088646)
		(layer "In2.Cu")
		(net "M_F_CPU1_ALERT_N")
	)
	(arc
		(start 135.997696 -260.106414)
		(mid 135.714994 -260.182156)
		(end 135.432292 -260.106414)
		(width 0.088646)
		(layer "In2.Cu")
		(net "M_F_CPU1_ALERT_N")
	)
	(arc
		(start 130.733292 -258.478782)
		(mid 130.546238 -258.428732)
		(end 130.35915 -258.478782)
		(width 0.088646)
		(layer "In2.Cu")
		(net "M_F_CPU1_ALERT_N")
	)
	(arc
		(start 129.511044 -257.98907)
		(mid 129.463365 -257.80617)
		(end 129.332482 -257.669792)
		(width 0.088646)
		(layer "In2.Cu")
		(net "M_F_CPU1_ALERT_N")
	)
	(arc
		(start 129.041398 -257.175254)
		(mid 128.991234 -256.988116)
		(end 128.8542 -256.85115)
		(width 0.088646)
		(layer "In2.Cu")
		(net "M_F_CPU1_ALERT_N")
	)
	(arc
		(start 132.142992 -259.292598)
		(mid 131.936391 -259.085924)
		(end 131.860798 -258.803648)
		(width 0.088646)
		(layer "In2.Cu")
		(net "M_F_CPU1_ALERT_N")
	)
	(arc
		(start 137.311892 -260.106414)
		(mid 137.124694 -260.056271)
		(end 136.937496 -260.106414)
		(width 0.088646)
		(layer "In2.Cu")
		(net "M_F_CPU1_ALERT_N")
	)
	(arc
		(start 135.057896 -260.106414)
		(mid 134.781337 -260.182157)
		(end 134.50316 -260.11251)
		(width 0.088646)
		(layer "In2.Cu")
		(net "M_F_CPU1_ALERT_N")
	)
	(arc
		(start 128.841754 -256.843784)
		(mid 128.643526 -256.637936)
		(end 128.571244 -256.361438)
		(width 0.088646)
		(layer "In2.Cu")
		(net "M_F_CPU1_ALERT_N")
	)
	(arc
		(start 137.877296 -260.106414)
		(mid 137.603097 -260.182249)
		(end 137.326624 -260.11505)
		(width 0.088646)
		(layer "In2.Cu")
		(net "M_F_CPU1_ALERT_N")
	)
	(arc
		(start 132.330444 -259.616956)
		(mid 132.282765 -259.434056)
		(end 132.151882 -259.297678)
		(width 0.088646)
		(layer "In2.Cu")
		(net "M_F_CPU1_ALERT_N")
	)
	(segment
		(start 374.726962 -253.383796)
		(end 374.726962 -253.919482)
		(width 0.20066)
		(layer "F.Cu")
		(net "M_F_CPU0_SB_RSP<1>")
	)
	(segment
		(start 420.736014 -243.216684)
		(end 421.840914 -243.216684)
		(width 0.20066)
		(layer "F.Cu")
		(net "M_F_CPU0_SB_RSP<1>")
	)
	(segment
		(start 374.726962 -253.919482)
		(end 374.727216 -253.919736)
		(width 0.20066)
		(layer "F.Cu")
		(net "M_F_CPU0_SB_RSP<1>")
	)
	(segment
		(start 418.56533 -243.53901)
		(end 417.563046 -244.541294)
		(width 0.18288)
		(layer "In6.Cu")
		(net "M_F_CPU0_SB_RSP<1>")
	)
	(segment
		(start 420.388288 -243.53901)
		(end 418.56533 -243.53901)
		(width 0.18288)
		(layer "In6.Cu")
		(net "M_F_CPU0_SB_RSP<1>")
	)
	(segment
		(start 420.736014 -243.216684)
		(end 420.710614 -243.216684)
		(width 0.18288)
		(layer "In6.Cu")
		(net "M_F_CPU0_SB_RSP<1>")
	)
	(segment
		(start 414.487614 -244.38864)
		(end 414.319466 -244.38864)
		(width 0.18288)
		(layer "In6.Cu")
		(net "M_F_CPU0_SB_RSP<1>")
	)
	(segment
		(start 417.563046 -244.541294)
		(end 417.096956 -244.541294)
		(width 0.18288)
		(layer "In6.Cu")
		(net "M_F_CPU0_SB_RSP<1>")
	)
	(segment
		(start 411.985206 -246.392954)
		(end 411.346904 -246.392954)
		(width 0.18288)
		(layer "In6.Cu")
		(net "M_F_CPU0_SB_RSP<1>")
	)
	(segment
		(start 411.164024 -246.210074)
		(end 411.164024 -245.814596)
		(width 0.18288)
		(layer "In6.Cu")
		(net "M_F_CPU0_SB_RSP<1>")
	)
	(segment
		(start 386.597906 -250.523756)
		(end 386.265166 -250.523756)
		(width 0.088646)
		(layer "In6.Cu")
		(net "M_F_CPU0_SB_RSP<1>")
	)
	(segment
		(start 404.522432 -247.55094)
		(end 400.823684 -247.55094)
		(width 0.18288)
		(layer "In6.Cu")
		(net "M_F_CPU0_SB_RSP<1>")
	)
	(segment
		(start 412.925006 -245.453154)
		(end 411.985206 -246.392954)
		(width 0.18288)
		(layer "In6.Cu")
		(net "M_F_CPU0_SB_RSP<1>")
	)
	(segment
		(start 408.810206 -246.392954)
		(end 408.155902 -247.047258)
		(width 0.18288)
		(layer "In6.Cu")
		(net "M_F_CPU0_SB_RSP<1>")
	)
	(segment
		(start 410.981144 -245.631716)
		(end 410.653484 -245.631716)
		(width 0.18288)
		(layer "In6.Cu")
		(net "M_F_CPU0_SB_RSP<1>")
	)
	(segment
		(start 388.781798 -250.523756)
		(end 386.597906 -250.523756)
		(width 0.18288)
		(layer "In6.Cu")
		(net "M_F_CPU0_SB_RSP<1>")
	)
	(segment
		(start 420.710614 -243.216684)
		(end 420.388288 -243.53901)
		(width 0.18288)
		(layer "In6.Cu")
		(net "M_F_CPU0_SB_RSP<1>")
	)
	(segment
		(start 408.155902 -247.047258)
		(end 405.738584 -247.047258)
		(width 0.18288)
		(layer "In6.Cu")
		(net "M_F_CPU0_SB_RSP<1>")
	)
	(segment
		(start 415.363914 -242.920266)
		(end 415.181034 -242.737386)
		(width 0.18288)
		(layer "In6.Cu")
		(net "M_F_CPU0_SB_RSP<1>")
	)
	(segment
		(start 410.287724 -246.392954)
		(end 408.810206 -246.392954)
		(width 0.18288)
		(layer "In6.Cu")
		(net "M_F_CPU0_SB_RSP<1>")
	)
	(segment
		(start 414.319466 -244.38864)
		(end 413.254952 -245.453154)
		(width 0.18288)
		(layer "In6.Cu")
		(net "M_F_CPU0_SB_RSP<1>")
	)
	(segment
		(start 414.670494 -242.920266)
		(end 414.670494 -244.20576)
		(width 0.18288)
		(layer "In6.Cu")
		(net "M_F_CPU0_SB_RSP<1>")
	)
	(segment
		(start 399.919698 -247.925336)
		(end 391.380218 -247.925336)
		(width 0.18288)
		(layer "In6.Cu")
		(net "M_F_CPU0_SB_RSP<1>")
	)
	(segment
		(start 386.216652 -250.57227)
		(end 376.516646 -250.57227)
		(width 0.088646)
		(layer "In6.Cu")
		(net "M_F_CPU0_SB_RSP<1>")
	)
	(segment
		(start 376.516646 -250.57227)
		(end 374.727216 -252.3617)
		(width 0.088646)
		(layer "In6.Cu")
		(net "M_F_CPU0_SB_RSP<1>")
	)
	(segment
		(start 414.670494 -244.20576)
		(end 414.487614 -244.38864)
		(width 0.18288)
		(layer "In6.Cu")
		(net "M_F_CPU0_SB_RSP<1>")
	)
	(segment
		(start 414.853374 -242.737386)
		(end 414.670494 -242.920266)
		(width 0.18288)
		(layer "In6.Cu")
		(net "M_F_CPU0_SB_RSP<1>")
	)
	(segment
		(start 415.546794 -244.38864)
		(end 415.363914 -244.20576)
		(width 0.18288)
		(layer "In6.Cu")
		(net "M_F_CPU0_SB_RSP<1>")
	)
	(segment
		(start 411.164024 -245.814596)
		(end 410.981144 -245.631716)
		(width 0.18288)
		(layer "In6.Cu")
		(net "M_F_CPU0_SB_RSP<1>")
	)
	(segment
		(start 413.254952 -245.453154)
		(end 412.925006 -245.453154)
		(width 0.18288)
		(layer "In6.Cu")
		(net "M_F_CPU0_SB_RSP<1>")
	)
	(segment
		(start 386.265166 -250.523756)
		(end 386.216652 -250.57227)
		(width 0.088646)
		(layer "In6.Cu")
		(net "M_F_CPU0_SB_RSP<1>")
	)
	(segment
		(start 417.096956 -244.541294)
		(end 416.944302 -244.38864)
		(width 0.18288)
		(layer "In6.Cu")
		(net "M_F_CPU0_SB_RSP<1>")
	)
	(segment
		(start 410.470604 -246.210074)
		(end 410.287724 -246.392954)
		(width 0.18288)
		(layer "In6.Cu")
		(net "M_F_CPU0_SB_RSP<1>")
	)
	(segment
		(start 400.823684 -247.55094)
		(end 399.919698 -247.925336)
		(width 0.18288)
		(layer "In6.Cu")
		(net "M_F_CPU0_SB_RSP<1>")
	)
	(segment
		(start 410.470604 -245.814596)
		(end 410.470604 -246.210074)
		(width 0.18288)
		(layer "In6.Cu")
		(net "M_F_CPU0_SB_RSP<1>")
	)
	(segment
		(start 374.727216 -252.3617)
		(end 374.727216 -253.919736)
		(width 0.088646)
		(layer "In6.Cu")
		(net "M_F_CPU0_SB_RSP<1>")
	)
	(segment
		(start 391.380218 -247.925336)
		(end 388.781798 -250.523756)
		(width 0.18288)
		(layer "In6.Cu")
		(net "M_F_CPU0_SB_RSP<1>")
	)
	(segment
		(start 415.181034 -242.737386)
		(end 414.853374 -242.737386)
		(width 0.18288)
		(layer "In6.Cu")
		(net "M_F_CPU0_SB_RSP<1>")
	)
	(segment
		(start 415.363914 -244.20576)
		(end 415.363914 -242.920266)
		(width 0.18288)
		(layer "In6.Cu")
		(net "M_F_CPU0_SB_RSP<1>")
	)
	(segment
		(start 411.346904 -246.392954)
		(end 411.164024 -246.210074)
		(width 0.18288)
		(layer "In6.Cu")
		(net "M_F_CPU0_SB_RSP<1>")
	)
	(segment
		(start 405.738584 -247.047258)
		(end 404.522432 -247.55094)
		(width 0.18288)
		(layer "In6.Cu")
		(net "M_F_CPU0_SB_RSP<1>")
	)
	(segment
		(start 416.944302 -244.38864)
		(end 415.546794 -244.38864)
		(width 0.18288)
		(layer "In6.Cu")
		(net "M_F_CPU0_SB_RSP<1>")
	)
	(segment
		(start 410.653484 -245.631716)
		(end 410.470604 -245.814596)
		(width 0.18288)
		(layer "In6.Cu")
		(net "M_F_CPU0_SB_RSP<1>")
	)
	(segment
		(start 428.254414 -243.216684)
		(end 429.384714 -243.216684)
		(width 0.20066)
		(layer "F.Cu")
		(net "M_F_CPU0_SB_RSP<0>")
	)
	(segment
		(start 375.197116 -254.197612)
		(end 375.196862 -254.197866)
		(width 0.20066)
		(layer "F.Cu")
		(net "M_F_CPU0_SB_RSP<0>")
	)
	(segment
		(start 375.196862 -254.197866)
		(end 375.196862 -254.733552)
		(width 0.20066)
		(layer "F.Cu")
		(net "M_F_CPU0_SB_RSP<0>")
	)
	(segment
		(start 425.348908 -244.492272)
		(end 424.674284 -244.492272)
		(width 0.18288)
		(layer "In6.Cu")
		(net "M_F_CPU0_SB_RSP<0>")
	)
	(segment
		(start 378.293884 -251.207524)
		(end 376.981212 -252.520196)
		(width 0.18288)
		(layer "In6.Cu")
		(net "M_F_CPU0_SB_RSP<0>")
	)
	(segment
		(start 427.176438 -243.423186)
		(end 425.8818 -243.95938)
		(width 0.18288)
		(layer "In6.Cu")
		(net "M_F_CPU0_SB_RSP<0>")
	)
	(segment
		(start 423.123614 -244.479826)
		(end 423.110914 -244.492526)
		(width 0.18288)
		(layer "In6.Cu")
		(net "M_F_CPU0_SB_RSP<0>")
	)
	(segment
		(start 396.423134 -248.87809)
		(end 392.235182 -248.87809)
		(width 0.18288)
		(layer "In6.Cu")
		(net "M_F_CPU0_SB_RSP<0>")
	)
	(segment
		(start 407.96464 -248.906792)
		(end 403.533102 -248.906792)
		(width 0.18288)
		(layer "In6.Cu")
		(net "M_F_CPU0_SB_RSP<0>")
	)
	(segment
		(start 423.110914 -244.492526)
		(end 422.670986 -244.492526)
		(width 0.18288)
		(layer "In6.Cu")
		(net "M_F_CPU0_SB_RSP<0>")
	)
	(segment
		(start 421.134794 -245.34241)
		(end 419.250368 -245.34241)
		(width 0.18288)
		(layer "In6.Cu")
		(net "M_F_CPU0_SB_RSP<0>")
	)
	(segment
		(start 376.528076 -254.335026)
		(end 376.159014 -254.335026)
		(width 0.088646)
		(layer "In6.Cu")
		(net "M_F_CPU0_SB_RSP<0>")
	)
	(segment
		(start 392.235182 -248.87809)
		(end 389.905748 -251.207524)
		(width 0.18288)
		(layer "In6.Cu")
		(net "M_F_CPU0_SB_RSP<0>")
	)
	(segment
		(start 428.047912 -243.423186)
		(end 427.176438 -243.423186)
		(width 0.18288)
		(layer "In6.Cu")
		(net "M_F_CPU0_SB_RSP<0>")
	)
	(segment
		(start 397.107918 -249.562874)
		(end 396.423134 -248.87809)
		(width 0.18288)
		(layer "In6.Cu")
		(net "M_F_CPU0_SB_RSP<0>")
	)
	(segment
		(start 376.981212 -252.520196)
		(end 376.981212 -253.2126)
		(width 0.18288)
		(layer "In6.Cu")
		(net "M_F_CPU0_SB_RSP<0>")
	)
	(segment
		(start 424.674284 -244.492272)
		(end 424.661838 -244.479826)
		(width 0.18288)
		(layer "In6.Cu")
		(net "M_F_CPU0_SB_RSP<0>")
	)
	(segment
		(start 418.174932 -245.787672)
		(end 417.402264 -246.304054)
		(width 0.18288)
		(layer "In6.Cu")
		(net "M_F_CPU0_SB_RSP<0>")
	)
	(segment
		(start 408.721306 -248.150126)
		(end 407.96464 -248.906792)
		(width 0.18288)
		(layer "In6.Cu")
		(net "M_F_CPU0_SB_RSP<0>")
	)
	(segment
		(start 417.402264 -246.304054)
		(end 416.389058 -246.304054)
		(width 0.18288)
		(layer "In6.Cu")
		(net "M_F_CPU0_SB_RSP<0>")
	)
	(segment
		(start 389.905748 -251.207524)
		(end 378.293884 -251.207524)
		(width 0.18288)
		(layer "In6.Cu")
		(net "M_F_CPU0_SB_RSP<0>")
	)
	(segment
		(start 402.87702 -249.562874)
		(end 397.107918 -249.562874)
		(width 0.18288)
		(layer "In6.Cu")
		(net "M_F_CPU0_SB_RSP<0>")
	)
	(segment
		(start 425.8818 -243.95938)
		(end 425.348908 -244.492272)
		(width 0.18288)
		(layer "In6.Cu")
		(net "M_F_CPU0_SB_RSP<0>")
	)
	(segment
		(start 419.250368 -245.34241)
		(end 418.174932 -245.787672)
		(width 0.18288)
		(layer "In6.Cu")
		(net "M_F_CPU0_SB_RSP<0>")
	)
	(segment
		(start 412.81477 -247.228614)
		(end 411.893258 -248.150126)
		(width 0.18288)
		(layer "In6.Cu")
		(net "M_F_CPU0_SB_RSP<0>")
	)
	(segment
		(start 376.981212 -253.2126)
		(end 376.981212 -253.928372)
		(width 0.088646)
		(layer "In6.Cu")
		(net "M_F_CPU0_SB_RSP<0>")
	)
	(segment
		(start 421.499284 -244.97792)
		(end 421.134794 -245.34241)
		(width 0.18288)
		(layer "In6.Cu")
		(net "M_F_CPU0_SB_RSP<0>")
	)
	(segment
		(start 415.464498 -247.228614)
		(end 412.81477 -247.228614)
		(width 0.18288)
		(layer "In6.Cu")
		(net "M_F_CPU0_SB_RSP<0>")
	)
	(segment
		(start 424.661838 -244.479826)
		(end 423.123614 -244.479826)
		(width 0.18288)
		(layer "In6.Cu")
		(net "M_F_CPU0_SB_RSP<0>")
	)
	(segment
		(start 416.389058 -246.304054)
		(end 415.464498 -247.228614)
		(width 0.18288)
		(layer "In6.Cu")
		(net "M_F_CPU0_SB_RSP<0>")
	)
	(segment
		(start 428.254414 -243.216684)
		(end 428.047912 -243.423186)
		(width 0.18288)
		(layer "In6.Cu")
		(net "M_F_CPU0_SB_RSP<0>")
	)
	(segment
		(start 403.533102 -248.906792)
		(end 402.87702 -249.562874)
		(width 0.18288)
		(layer "In6.Cu")
		(net "M_F_CPU0_SB_RSP<0>")
	)
	(segment
		(start 422.670986 -244.492526)
		(end 421.499284 -244.97792)
		(width 0.18288)
		(layer "In6.Cu")
		(net "M_F_CPU0_SB_RSP<0>")
	)
	(segment
		(start 411.893258 -248.150126)
		(end 408.721306 -248.150126)
		(width 0.18288)
		(layer "In6.Cu")
		(net "M_F_CPU0_SB_RSP<0>")
	)
	(arc
		(start 376.794014 -254.244094)
		(mid 376.707293 -254.287942)
		(end 376.616214 -254.321818)
		(width 0.088646)
		(layer "In6.Cu")
		(net "M_F_CPU0_SB_RSP<0>")
	)
	(arc
		(start 376.981212 -253.928372)
		(mid 376.928942 -254.110737)
		(end 376.794014 -254.244094)
		(width 0.088646)
		(layer "In6.Cu")
		(net "M_F_CPU0_SB_RSP<0>")
	)
	(arc
		(start 376.159014 -254.335026)
		(mid 375.638319 -254.438616)
		(end 375.196862 -254.733552)
		(width 0.088646)
		(layer "In6.Cu")
		(net "M_F_CPU0_SB_RSP<0>")
	)
	(arc
		(start 376.616214 -254.321818)
		(mid 376.57264 -254.331713)
		(end 376.528076 -254.335026)
		(width 0.088646)
		(layer "In6.Cu")
		(net "M_F_CPU0_SB_RSP<0>")
	)
	(segment
		(start 430.395126 -247.049036)
		(end 430.669192 -247.049036)
		(width 0.20066)
		(layer "F.Cu")
		(net "M_F_CPU0_SB_PAR")
	)
	(segment
		(start 428.012352 -247.052338)
		(end 428.363126 -247.052338)
		(width 0.20066)
		(layer "F.Cu")
		(net "M_F_CPU0_SB_PAR")
	)
	(segment
		(start 430.669192 -247.049036)
		(end 431.534062 -246.184166)
		(width 0.20066)
		(layer "F.Cu")
		(net "M_F_CPU0_SB_PAR")
	)
	(segment
		(start 431.534062 -246.184166)
		(end 431.937668 -246.184166)
		(width 0.20066)
		(layer "F.Cu")
		(net "M_F_CPU0_SB_PAR")
	)
	(segment
		(start 430.38776 -247.04167)
		(end 430.395126 -247.049036)
		(width 0.1016)
		(layer "F.Cu")
		(net "M_F_CPU0_SB_PAR")
	)
	(segment
		(start 428.367952 -247.052338)
		(end 428.37862 -247.04167)
		(width 0.1016)
		(layer "F.Cu")
		(net "M_F_CPU0_SB_PAR")
	)
	(segment
		(start 427.576742 -246.616728)
		(end 428.012352 -247.052338)
		(width 0.20066)
		(layer "F.Cu")
		(net "M_F_CPU0_SB_PAR")
	)
	(segment
		(start 432.37023 -246.616728)
		(end 433.484782 -246.616728)
		(width 0.20066)
		(layer "F.Cu")
		(net "M_F_CPU0_SB_PAR")
	)
	(segment
		(start 428.363126 -247.052338)
		(end 428.367952 -247.052338)
		(width 0.101854)
		(layer "F.Cu")
		(net "M_F_CPU0_SB_PAR")
	)
	(segment
		(start 431.937668 -246.184166)
		(end 432.37023 -246.616728)
		(width 0.20066)
		(layer "F.Cu")
		(net "M_F_CPU0_SB_PAR")
	)
	(segment
		(start 424.836082 -246.616728)
		(end 425.940982 -246.616728)
		(width 0.20066)
		(layer "F.Cu")
		(net "M_F_CPU0_SB_PAR")
	)
	(segment
		(start 383.545334 -245.27256)
		(end 383.545334 -244.73662)
		(width 0.20066)
		(layer "F.Cu")
		(net "M_F_CPU0_SB_PAR")
	)
	(segment
		(start 425.940982 -246.616728)
		(end 427.576742 -246.616728)
		(width 0.20066)
		(layer "F.Cu")
		(net "M_F_CPU0_SB_PAR")
	)
	(segment
		(start 428.37862 -247.04167)
		(end 430.38776 -247.04167)
		(width 0.1016)
		(layer "F.Cu")
		(net "M_F_CPU0_SB_PAR")
	)
	(segment
		(start 422.28262 -247.070626)
		(end 422.087294 -246.8753)
		(width 0.18288)
		(layer "In2.Cu")
		(net "M_F_CPU0_SB_PAR")
	)
	(segment
		(start 421.205152 -247.040908)
		(end 420.287958 -247.040908)
		(width 0.18288)
		(layer "In2.Cu")
		(net "M_F_CPU0_SB_PAR")
	)
	(segment
		(start 408.50312 -247.220994)
		(end 407.784554 -247.220994)
		(width 0.18288)
		(layer "In2.Cu")
		(net "M_F_CPU0_SB_PAR")
	)
	(segment
		(start 383.640584 -245.516654)
		(end 383.545334 -244.73662)
		(width 0.088646)
		(layer "In2.Cu")
		(net "M_F_CPU0_SB_PAR")
	)
	(segment
		(start 419.486334 -246.717058)
		(end 419.177216 -247.026176)
		(width 0.18288)
		(layer "In2.Cu")
		(net "M_F_CPU0_SB_PAR")
	)
	(segment
		(start 423.541444 -246.314214)
		(end 423.381424 -246.474234)
		(width 0.18288)
		(layer "In2.Cu")
		(net "M_F_CPU0_SB_PAR")
	)
	(segment
		(start 383.828036 -245.875048)
		(end 383.819146 -245.869968)
		(width 0.088646)
		(layer "In2.Cu")
		(net "M_F_CPU0_SB_PAR")
	)
	(segment
		(start 404.446486 -248.007124)
		(end 402.318728 -248.007124)
		(width 0.18288)
		(layer "In2.Cu")
		(net "M_F_CPU0_SB_PAR")
	)
	(segment
		(start 422.087294 -246.628412)
		(end 421.927274 -246.468392)
		(width 0.18288)
		(layer "In2.Cu")
		(net "M_F_CPU0_SB_PAR")
	)
	(segment
		(start 398.044416 -246.87149)
		(end 388.897876 -246.87149)
		(width 0.18288)
		(layer "In2.Cu")
		(net "M_F_CPU0_SB_PAR")
	)
	(segment
		(start 424.836082 -246.616728)
		(end 424.836082 -246.868696)
		(width 0.18288)
		(layer "In2.Cu")
		(net "M_F_CPU0_SB_PAR")
	)
	(segment
		(start 412.58998 -247.034812)
		(end 408.689302 -247.034812)
		(width 0.18288)
		(layer "In2.Cu")
		(net "M_F_CPU0_SB_PAR")
	)
	(segment
		(start 402.318728 -248.007124)
		(end 401.713446 -247.401842)
		(width 0.18288)
		(layer "In2.Cu")
		(net "M_F_CPU0_SB_PAR")
	)
	(segment
		(start 408.689302 -247.034812)
		(end 408.50312 -247.220994)
		(width 0.18288)
		(layer "In2.Cu")
		(net "M_F_CPU0_SB_PAR")
	)
	(segment
		(start 405.302974 -247.150636)
		(end 404.446486 -248.007124)
		(width 0.18288)
		(layer "In2.Cu")
		(net "M_F_CPU0_SB_PAR")
	)
	(segment
		(start 423.381424 -246.910606)
		(end 423.221404 -247.070626)
		(width 0.18288)
		(layer "In2.Cu")
		(net "M_F_CPU0_SB_PAR")
	)
	(segment
		(start 416.243008 -246.555768)
		(end 415.624264 -247.174512)
		(width 0.18288)
		(layer "In2.Cu")
		(net "M_F_CPU0_SB_PAR")
	)
	(segment
		(start 398.574768 -247.401842)
		(end 398.044416 -246.87149)
		(width 0.18288)
		(layer "In2.Cu")
		(net "M_F_CPU0_SB_PAR")
	)
	(segment
		(start 401.713446 -247.401842)
		(end 398.574768 -247.401842)
		(width 0.18288)
		(layer "In2.Cu")
		(net "M_F_CPU0_SB_PAR")
	)
	(segment
		(start 421.365172 -246.880888)
		(end 421.205152 -247.040908)
		(width 0.18288)
		(layer "In2.Cu")
		(net "M_F_CPU0_SB_PAR")
	)
	(segment
		(start 421.365172 -246.628412)
		(end 421.365172 -246.880888)
		(width 0.18288)
		(layer "In2.Cu")
		(net "M_F_CPU0_SB_PAR")
	)
	(segment
		(start 383.640584 -245.55069)
		(end 383.640584 -245.516654)
		(width 0.088646)
		(layer "In2.Cu")
		(net "M_F_CPU0_SB_PAR")
	)
	(segment
		(start 421.525192 -246.468392)
		(end 421.365172 -246.628412)
		(width 0.18288)
		(layer "In2.Cu")
		(net "M_F_CPU0_SB_PAR")
	)
	(segment
		(start 407.784554 -247.220994)
		(end 407.559764 -246.996204)
		(width 0.18288)
		(layer "In2.Cu")
		(net "M_F_CPU0_SB_PAR")
	)
	(segment
		(start 415.624264 -247.174512)
		(end 415.35096 -247.174512)
		(width 0.18288)
		(layer "In2.Cu")
		(net "M_F_CPU0_SB_PAR")
	)
	(segment
		(start 412.854394 -247.299226)
		(end 412.58998 -247.034812)
		(width 0.18288)
		(layer "In2.Cu")
		(net "M_F_CPU0_SB_PAR")
	)
	(segment
		(start 423.381424 -246.474234)
		(end 423.381424 -246.910606)
		(width 0.18288)
		(layer "In2.Cu")
		(net "M_F_CPU0_SB_PAR")
	)
	(segment
		(start 423.889424 -246.314214)
		(end 423.541444 -246.314214)
		(width 0.18288)
		(layer "In2.Cu")
		(net "M_F_CPU0_SB_PAR")
	)
	(segment
		(start 421.927274 -246.468392)
		(end 421.525192 -246.468392)
		(width 0.18288)
		(layer "In2.Cu")
		(net "M_F_CPU0_SB_PAR")
	)
	(segment
		(start 385.990084 -246.130064)
		(end 385.82473 -245.96471)
		(width 0.088646)
		(layer "In2.Cu")
		(net "M_F_CPU0_SB_PAR")
	)
	(segment
		(start 424.247564 -247.05437)
		(end 424.087544 -246.89435)
		(width 0.18288)
		(layer "In2.Cu")
		(net "M_F_CPU0_SB_PAR")
	)
	(segment
		(start 416.654488 -246.555768)
		(end 416.243008 -246.555768)
		(width 0.18288)
		(layer "In2.Cu")
		(net "M_F_CPU0_SB_PAR")
	)
	(segment
		(start 423.221404 -247.070626)
		(end 422.28262 -247.070626)
		(width 0.18288)
		(layer "In2.Cu")
		(net "M_F_CPU0_SB_PAR")
	)
	(segment
		(start 424.650408 -247.05437)
		(end 424.247564 -247.05437)
		(width 0.18288)
		(layer "In2.Cu")
		(net "M_F_CPU0_SB_PAR")
	)
	(segment
		(start 424.836082 -246.868696)
		(end 424.650408 -247.05437)
		(width 0.18288)
		(layer "In2.Cu")
		(net "M_F_CPU0_SB_PAR")
	)
	(segment
		(start 387.03631 -247.489472)
		(end 386.310124 -246.763286)
		(width 0.18288)
		(layer "In2.Cu")
		(net "M_F_CPU0_SB_PAR")
	)
	(segment
		(start 386.310124 -246.763286)
		(end 385.990084 -246.443246)
		(width 0.088646)
		(layer "In2.Cu")
		(net "M_F_CPU0_SB_PAR")
	)
	(segment
		(start 417.124896 -247.026176)
		(end 416.654488 -246.555768)
		(width 0.18288)
		(layer "In2.Cu")
		(net "M_F_CPU0_SB_PAR")
	)
	(segment
		(start 419.177216 -247.026176)
		(end 417.124896 -247.026176)
		(width 0.18288)
		(layer "In2.Cu")
		(net "M_F_CPU0_SB_PAR")
	)
	(segment
		(start 388.897876 -246.87149)
		(end 388.279894 -247.489472)
		(width 0.18288)
		(layer "In2.Cu")
		(net "M_F_CPU0_SB_PAR")
	)
	(segment
		(start 415.21126 -247.034812)
		(end 413.441388 -247.034812)
		(width 0.18288)
		(layer "In2.Cu")
		(net "M_F_CPU0_SB_PAR")
	)
	(segment
		(start 413.176974 -247.299226)
		(end 412.854394 -247.299226)
		(width 0.18288)
		(layer "In2.Cu")
		(net "M_F_CPU0_SB_PAR")
	)
	(segment
		(start 405.989282 -246.996204)
		(end 405.83485 -247.150636)
		(width 0.18288)
		(layer "In2.Cu")
		(net "M_F_CPU0_SB_PAR")
	)
	(segment
		(start 424.087544 -246.89435)
		(end 424.087544 -246.512334)
		(width 0.18288)
		(layer "In2.Cu")
		(net "M_F_CPU0_SB_PAR")
	)
	(segment
		(start 420.287958 -247.040908)
		(end 419.964108 -246.717058)
		(width 0.18288)
		(layer "In2.Cu")
		(net "M_F_CPU0_SB_PAR")
	)
	(segment
		(start 415.35096 -247.174512)
		(end 415.21126 -247.034812)
		(width 0.18288)
		(layer "In2.Cu")
		(net "M_F_CPU0_SB_PAR")
	)
	(segment
		(start 413.441388 -247.034812)
		(end 413.176974 -247.299226)
		(width 0.18288)
		(layer "In2.Cu")
		(net "M_F_CPU0_SB_PAR")
	)
	(segment
		(start 385.990084 -246.443246)
		(end 385.990084 -246.130064)
		(width 0.088646)
		(layer "In2.Cu")
		(net "M_F_CPU0_SB_PAR")
	)
	(segment
		(start 419.964108 -246.717058)
		(end 419.486334 -246.717058)
		(width 0.18288)
		(layer "In2.Cu")
		(net "M_F_CPU0_SB_PAR")
	)
	(segment
		(start 407.559764 -246.996204)
		(end 405.989282 -246.996204)
		(width 0.18288)
		(layer "In2.Cu")
		(net "M_F_CPU0_SB_PAR")
	)
	(segment
		(start 424.087544 -246.512334)
		(end 423.889424 -246.314214)
		(width 0.18288)
		(layer "In2.Cu")
		(net "M_F_CPU0_SB_PAR")
	)
	(segment
		(start 388.279894 -247.489472)
		(end 387.03631 -247.489472)
		(width 0.18288)
		(layer "In2.Cu")
		(net "M_F_CPU0_SB_PAR")
	)
	(segment
		(start 405.83485 -247.150636)
		(end 405.302974 -247.150636)
		(width 0.18288)
		(layer "In2.Cu")
		(net "M_F_CPU0_SB_PAR")
	)
	(segment
		(start 422.087294 -246.8753)
		(end 422.087294 -246.628412)
		(width 0.18288)
		(layer "In2.Cu")
		(net "M_F_CPU0_SB_PAR")
	)
	(arc
		(start 385.142232 -245.875048)
		(mid 384.955034 -245.925191)
		(end 384.767836 -245.875048)
		(width 0.088646)
		(layer "In2.Cu")
		(net "M_F_CPU0_SB_PAR")
	)
	(arc
		(start 384.202432 -245.875048)
		(mid 384.015234 -245.925191)
		(end 383.828036 -245.875048)
		(width 0.088646)
		(layer "In2.Cu")
		(net "M_F_CPU0_SB_PAR")
	)
	(arc
		(start 385.82473 -245.96471)
		(mid 385.769125 -245.916036)
		(end 385.707636 -245.875048)
		(width 0.088646)
		(layer "In2.Cu")
		(net "M_F_CPU0_SB_PAR")
	)
	(arc
		(start 383.819146 -245.869968)
		(mid 383.688232 -245.733608)
		(end 383.640584 -245.55069)
		(width 0.088646)
		(layer "In2.Cu")
		(net "M_F_CPU0_SB_PAR")
	)
	(arc
		(start 385.707636 -245.875048)
		(mid 385.424934 -245.799272)
		(end 385.142232 -245.875048)
		(width 0.088646)
		(layer "In2.Cu")
		(net "M_F_CPU0_SB_PAR")
	)
	(arc
		(start 384.767836 -245.875048)
		(mid 384.485134 -245.799272)
		(end 384.202432 -245.875048)
		(width 0.088646)
		(layer "In2.Cu")
		(net "M_F_CPU0_SB_PAR")
	)
	(segment
		(start 423.271188 -237.87608)
		(end 423.685716 -238.290608)
		(width 0.20066)
		(layer "F.Cu")
		(net "M_F_CPU0_SB_DQS_DP<9>")
	)
	(segment
		(start 427.274736 -238.54791)
		(end 427.57725 -238.245396)
		(width 0.20066)
		(layer "F.Cu")
		(net "M_F_CPU0_SB_DQS_DP<9>")
	)
	(segment
		(start 428.554388 -237.834932)
		(end 428.836074 -238.116618)
		(width 0.20066)
		(layer "F.Cu")
		(net "M_F_CPU0_SB_DQS_DP<9>")
	)
	(segment
		(start 427.947836 -238.245396)
		(end 428.3583 -237.834932)
		(width 0.20066)
		(layer "F.Cu")
		(net "M_F_CPU0_SB_DQS_DP<9>")
	)
	(segment
		(start 423.685716 -238.290608)
		(end 424.371516 -238.290608)
		(width 0.20066)
		(layer "F.Cu")
		(net "M_F_CPU0_SB_DQS_DP<9>")
	)
	(segment
		(start 424.788076 -238.541814)
		(end 426.945298 -238.541814)
		(width 0.1016)
		(layer "F.Cu")
		(net "M_F_CPU0_SB_DQS_DP<9>")
	)
	(segment
		(start 428.836074 -238.116618)
		(end 429.384714 -238.116618)
		(width 0.20066)
		(layer "F.Cu")
		(net "M_F_CPU0_SB_DQS_DP<9>")
	)
	(segment
		(start 421.840914 -238.116618)
		(end 422.430194 -238.116618)
		(width 0.20066)
		(layer "F.Cu")
		(net "M_F_CPU0_SB_DQS_DP<9>")
	)
	(segment
		(start 426.945298 -238.541814)
		(end 426.951394 -238.54791)
		(width 0.1016)
		(layer "F.Cu")
		(net "M_F_CPU0_SB_DQS_DP<9>")
	)
	(segment
		(start 380.725934 -240.389156)
		(end 380.725934 -239.85347)
		(width 0.20066)
		(layer "F.Cu")
		(net "M_F_CPU0_SB_DQS_DP<9>")
	)
	(segment
		(start 424.762168 -238.541814)
		(end 424.788076 -238.541814)
		(width 0.101854)
		(layer "F.Cu")
		(net "M_F_CPU0_SB_DQS_DP<9>")
	)
	(segment
		(start 424.371516 -238.290608)
		(end 424.622722 -238.541814)
		(width 0.20066)
		(layer "F.Cu")
		(net "M_F_CPU0_SB_DQS_DP<9>")
	)
	(segment
		(start 426.951394 -238.54791)
		(end 427.274736 -238.54791)
		(width 0.20066)
		(layer "F.Cu")
		(net "M_F_CPU0_SB_DQS_DP<9>")
	)
	(segment
		(start 424.622722 -238.541814)
		(end 424.762168 -238.541814)
		(width 0.20066)
		(layer "F.Cu")
		(net "M_F_CPU0_SB_DQS_DP<9>")
	)
	(segment
		(start 428.3583 -237.834932)
		(end 428.554388 -237.834932)
		(width 0.20066)
		(layer "F.Cu")
		(net "M_F_CPU0_SB_DQS_DP<9>")
	)
	(segment
		(start 422.430194 -238.116618)
		(end 422.670732 -237.87608)
		(width 0.20066)
		(layer "F.Cu")
		(net "M_F_CPU0_SB_DQS_DP<9>")
	)
	(segment
		(start 420.736014 -238.116618)
		(end 421.840914 -238.116618)
		(width 0.20066)
		(layer "F.Cu")
		(net "M_F_CPU0_SB_DQS_DP<9>")
	)
	(segment
		(start 427.57725 -238.245396)
		(end 427.947836 -238.245396)
		(width 0.20066)
		(layer "F.Cu")
		(net "M_F_CPU0_SB_DQS_DP<9>")
	)
	(segment
		(start 380.725934 -239.85347)
		(end 380.72568 -239.853216)
		(width 0.20066)
		(layer "F.Cu")
		(net "M_F_CPU0_SB_DQS_DP<9>")
	)
	(segment
		(start 422.670732 -237.87608)
		(end 423.271188 -237.87608)
		(width 0.20066)
		(layer "F.Cu")
		(net "M_F_CPU0_SB_DQS_DP<9>")
	)
	(segment
		(start 405.591518 -238.509302)
		(end 405.498046 -238.41583)
		(width 0.18288)
		(layer "In2.Cu")
		(net "M_F_CPU0_SB_DQS_DP<9>")
	)
	(segment
		(start 405.978106 -238.89589)
		(end 405.802592 -238.720376)
		(width 0.18288)
		(layer "In2.Cu")
		(net "M_F_CPU0_SB_DQS_DP<9>")
	)
	(segment
		(start 382.323086 -240.342928)
		(end 382.322832 -240.342928)
		(width 0.088646)
		(layer "In2.Cu")
		(net "M_F_CPU0_SB_DQS_DP<9>")
	)
	(segment
		(start 409.87472 -237.835186)
		(end 409.87472 -237.81893)
		(width 0.16002)
		(layer "In2.Cu")
		(net "M_F_CPU0_SB_DQS_DP<9>")
	)
	(segment
		(start 414.951418 -236.79785)
		(end 414.93567 -236.79785)
		(width 0.16002)
		(layer "In2.Cu")
		(net "M_F_CPU0_SB_DQS_DP<9>")
	)
	(segment
		(start 409.64612 -237.606586)
		(end 409.583636 -237.544102)
		(width 0.18288)
		(layer "In2.Cu")
		(net "M_F_CPU0_SB_DQS_DP<9>")
	)
	(segment
		(start 413.812736 -236.62767)
		(end 413.563816 -236.87659)
		(width 0.18288)
		(layer "In2.Cu")
		(net "M_F_CPU0_SB_DQS_DP<9>")
	)
	(segment
		(start 415.136076 -236.998256)
		(end 415.136076 -236.982508)
		(width 0.16002)
		(layer "In2.Cu")
		(net "M_F_CPU0_SB_DQS_DP<9>")
	)
	(segment
		(start 419.354 -237.857284)
		(end 419.15461 -238.056674)
		(width 0.18288)
		(layer "In2.Cu")
		(net "M_F_CPU0_SB_DQS_DP<9>")
	)
	(segment
		(start 419.53688 -237.674404)
		(end 419.520624 -237.674404)
		(width 0.16002)
		(layer "In2.Cu")
		(net "M_F_CPU0_SB_DQS_DP<9>")
	)
	(segment
		(start 388.020814 -241.684302)
		(end 387.63321 -241.84483)
		(width 0.088646)
		(layer "In2.Cu")
		(net "M_F_CPU0_SB_DQS_DP<9>")
	)
	(segment
		(start 417.414202 -237.813342)
		(end 417.230052 -237.629192)
		(width 0.16002)
		(layer "In2.Cu")
		(net "M_F_CPU0_SB_DQS_DP<9>")
	)
	(segment
		(start 409.674314 -237.63478)
		(end 409.64612 -237.606586)
		(width 0.16002)
		(layer "In2.Cu")
		(net "M_F_CPU0_SB_DQS_DP<9>")
	)
	(segment
		(start 385.621022 -241.161824)
		(end 385.612132 -241.156744)
		(width 0.088646)
		(layer "In2.Cu")
		(net "M_F_CPU0_SB_DQS_DP<9>")
	)
	(segment
		(start 405.635968 -238.537496)
		(end 405.619712 -238.537496)
		(width 0.16002)
		(layer "In2.Cu")
		(net "M_F_CPU0_SB_DQS_DP<9>")
	)
	(segment
		(start 409.306268 -237.544102)
		(end 408.898852 -237.951518)
		(width 0.18288)
		(layer "In2.Cu")
		(net "M_F_CPU0_SB_DQS_DP<9>")
	)
	(segment
		(start 411.840172 -237.831376)
		(end 411.840172 -237.847632)
		(width 0.16002)
		(layer "In2.Cu")
		(net "M_F_CPU0_SB_DQS_DP<9>")
	)
	(segment
		(start 419.382194 -237.82909)
		(end 419.354 -237.857284)
		(width 0.16002)
		(layer "In2.Cu")
		(net "M_F_CPU0_SB_DQS_DP<9>")
	)
	(segment
		(start 419.565074 -237.64621)
		(end 419.53688 -237.674404)
		(width 0.16002)
		(layer "In2.Cu")
		(net "M_F_CPU0_SB_DQS_DP<9>")
	)
	(segment
		(start 405.186642 -238.41583)
		(end 401.858226 -241.744246)
		(width 0.18288)
		(layer "In2.Cu")
		(net "M_F_CPU0_SB_DQS_DP<9>")
	)
	(segment
		(start 413.335216 -237.10519)
		(end 413.307022 -237.133384)
		(width 0.16002)
		(layer "In2.Cu")
		(net "M_F_CPU0_SB_DQS_DP<9>")
	)
	(segment
		(start 420.46398 -237.842552)
		(end 420.200074 -237.842552)
		(width 0.18288)
		(layer "In2.Cu")
		(net "M_F_CPU0_SB_DQS_DP<9>")
	)
	(segment
		(start 409.902914 -237.86338)
		(end 409.87472 -237.835186)
		(width 0.16002)
		(layer "In2.Cu")
		(net "M_F_CPU0_SB_DQS_DP<9>")
	)
	(segment
		(start 415.136076 -236.982508)
		(end 414.951418 -236.79785)
		(width 0.16002)
		(layer "In2.Cu")
		(net "M_F_CPU0_SB_DQS_DP<9>")
	)
	(segment
		(start 388.39902 -241.684302)
		(end 388.020814 -241.684302)
		(width 0.088646)
		(layer "In2.Cu")
		(net "M_F_CPU0_SB_DQS_DP<9>")
	)
	(segment
		(start 405.498046 -238.41583)
		(end 405.186642 -238.41583)
		(width 0.18288)
		(layer "In2.Cu")
		(net "M_F_CPU0_SB_DQS_DP<9>")
	)
	(segment
		(start 419.15461 -238.056674)
		(end 417.641278 -238.056674)
		(width 0.18288)
		(layer "In2.Cu")
		(net "M_F_CPU0_SB_DQS_DP<9>")
	)
	(segment
		(start 417.213796 -237.629192)
		(end 417.185602 -237.600998)
		(width 0.16002)
		(layer "In2.Cu")
		(net "M_F_CPU0_SB_DQS_DP<9>")
	)
	(segment
		(start 420.736014 -238.114586)
		(end 420.46398 -237.842552)
		(width 0.18288)
		(layer "In2.Cu")
		(net "M_F_CPU0_SB_DQS_DP<9>")
	)
	(segment
		(start 384.211322 -240.348008)
		(end 384.202432 -240.342928)
		(width 0.088646)
		(layer "In2.Cu")
		(net "M_F_CPU0_SB_DQS_DP<9>")
	)
	(segment
		(start 407.867358 -238.641128)
		(end 407.612596 -238.89589)
		(width 0.18288)
		(layer "In2.Cu")
		(net "M_F_CPU0_SB_DQS_DP<9>")
	)
	(segment
		(start 414.76549 -236.62767)
		(end 413.812736 -236.62767)
		(width 0.18288)
		(layer "In2.Cu")
		(net "M_F_CPU0_SB_DQS_DP<9>")
	)
	(segment
		(start 381.038608 -239.853216)
		(end 380.72568 -239.853216)
		(width 0.088646)
		(layer "In2.Cu")
		(net "M_F_CPU0_SB_DQS_DP<9>")
	)
	(segment
		(start 386.02793 -241.84483)
		(end 385.799584 -241.616484)
		(width 0.088646)
		(layer "In2.Cu")
		(net "M_F_CPU0_SB_DQS_DP<9>")
	)
	(segment
		(start 387.63321 -241.84483)
		(end 386.02793 -241.84483)
		(width 0.088646)
		(layer "In2.Cu")
		(net "M_F_CPU0_SB_DQS_DP<9>")
	)
	(segment
		(start 411.811978 -237.875826)
		(end 411.622494 -238.06531)
		(width 0.18288)
		(layer "In2.Cu")
		(net "M_F_CPU0_SB_DQS_DP<9>")
	)
	(segment
		(start 414.907476 -236.769656)
		(end 414.76549 -236.62767)
		(width 0.18288)
		(layer "In2.Cu")
		(net "M_F_CPU0_SB_DQS_DP<9>")
	)
	(segment
		(start 411.840172 -237.847632)
		(end 411.811978 -237.875826)
		(width 0.16002)
		(layer "In2.Cu")
		(net "M_F_CPU0_SB_DQS_DP<9>")
	)
	(segment
		(start 419.520624 -237.674404)
		(end 419.382194 -237.812834)
		(width 0.16002)
		(layer "In2.Cu")
		(net "M_F_CPU0_SB_DQS_DP<9>")
	)
	(segment
		(start 405.774398 -238.675926)
		(end 405.635968 -238.537496)
		(width 0.16002)
		(layer "In2.Cu")
		(net "M_F_CPU0_SB_DQS_DP<9>")
	)
	(segment
		(start 419.382194 -237.812834)
		(end 419.382194 -237.82909)
		(width 0.16002)
		(layer "In2.Cu")
		(net "M_F_CPU0_SB_DQS_DP<9>")
	)
	(segment
		(start 410.104844 -238.06531)
		(end 409.902914 -237.86338)
		(width 0.18288)
		(layer "In2.Cu")
		(net "M_F_CPU0_SB_DQS_DP<9>")
	)
	(segment
		(start 417.442396 -237.857792)
		(end 417.414202 -237.829598)
		(width 0.16002)
		(layer "In2.Cu")
		(net "M_F_CPU0_SB_DQS_DP<9>")
	)
	(segment
		(start 385.799584 -241.616484)
		(end 385.799584 -241.481102)
		(width 0.088646)
		(layer "In2.Cu")
		(net "M_F_CPU0_SB_DQS_DP<9>")
	)
	(segment
		(start 405.802592 -238.720376)
		(end 405.774398 -238.692182)
		(width 0.16002)
		(layer "In2.Cu")
		(net "M_F_CPU0_SB_DQS_DP<9>")
	)
	(segment
		(start 417.641278 -238.056674)
		(end 417.442396 -237.857792)
		(width 0.18288)
		(layer "In2.Cu")
		(net "M_F_CPU0_SB_DQS_DP<9>")
	)
	(segment
		(start 415.16427 -237.02645)
		(end 415.136076 -236.998256)
		(width 0.16002)
		(layer "In2.Cu")
		(net "M_F_CPU0_SB_DQS_DP<9>")
	)
	(segment
		(start 412.040578 -237.647226)
		(end 412.024322 -237.647226)
		(width 0.16002)
		(layer "In2.Cu")
		(net "M_F_CPU0_SB_DQS_DP<9>")
	)
	(segment
		(start 420.736014 -238.116618)
		(end 420.736014 -238.114586)
		(width 0.18288)
		(layer "In2.Cu")
		(net "M_F_CPU0_SB_DQS_DP<9>")
	)
	(segment
		(start 407.612596 -238.89589)
		(end 405.978106 -238.89589)
		(width 0.18288)
		(layer "In2.Cu")
		(net "M_F_CPU0_SB_DQS_DP<9>")
	)
	(segment
		(start 414.93567 -236.79785)
		(end 414.907476 -236.769656)
		(width 0.16002)
		(layer "In2.Cu")
		(net "M_F_CPU0_SB_DQS_DP<9>")
	)
	(segment
		(start 419.645846 -237.565438)
		(end 419.565074 -237.64621)
		(width 0.18288)
		(layer "In2.Cu")
		(net "M_F_CPU0_SB_DQS_DP<9>")
	)
	(segment
		(start 412.239714 -237.44809)
		(end 412.068772 -237.619032)
		(width 0.18288)
		(layer "In2.Cu")
		(net "M_F_CPU0_SB_DQS_DP<9>")
	)
	(segment
		(start 412.024322 -237.647226)
		(end 411.840172 -237.831376)
		(width 0.16002)
		(layer "In2.Cu")
		(net "M_F_CPU0_SB_DQS_DP<9>")
	)
	(segment
		(start 388.458964 -241.744246)
		(end 388.39902 -241.684302)
		(width 0.088646)
		(layer "In2.Cu")
		(net "M_F_CPU0_SB_DQS_DP<9>")
	)
	(segment
		(start 405.619712 -238.537496)
		(end 405.591518 -238.509302)
		(width 0.16002)
		(layer "In2.Cu")
		(net "M_F_CPU0_SB_DQS_DP<9>")
	)
	(segment
		(start 415.582862 -237.445042)
		(end 415.16427 -237.02645)
		(width 0.18288)
		(layer "In2.Cu")
		(net "M_F_CPU0_SB_DQS_DP<9>")
	)
	(segment
		(start 413.307022 -237.133384)
		(end 412.992316 -237.44809)
		(width 0.18288)
		(layer "In2.Cu")
		(net "M_F_CPU0_SB_DQS_DP<9>")
	)
	(segment
		(start 417.230052 -237.629192)
		(end 417.213796 -237.629192)
		(width 0.16002)
		(layer "In2.Cu")
		(net "M_F_CPU0_SB_DQS_DP<9>")
	)
	(segment
		(start 409.87472 -237.81893)
		(end 409.69057 -237.63478)
		(width 0.16002)
		(layer "In2.Cu")
		(net "M_F_CPU0_SB_DQS_DP<9>")
	)
	(segment
		(start 405.774398 -238.692182)
		(end 405.774398 -238.675926)
		(width 0.16002)
		(layer "In2.Cu")
		(net "M_F_CPU0_SB_DQS_DP<9>")
	)
	(segment
		(start 408.898852 -237.951518)
		(end 407.867358 -238.641128)
		(width 0.18288)
		(layer "In2.Cu")
		(net "M_F_CPU0_SB_DQS_DP<9>")
	)
	(segment
		(start 417.185602 -237.600998)
		(end 417.029646 -237.445042)
		(width 0.18288)
		(layer "In2.Cu")
		(net "M_F_CPU0_SB_DQS_DP<9>")
	)
	(segment
		(start 419.92296 -237.565438)
		(end 419.645846 -237.565438)
		(width 0.18288)
		(layer "In2.Cu")
		(net "M_F_CPU0_SB_DQS_DP<9>")
	)
	(segment
		(start 413.519874 -236.904784)
		(end 413.335216 -237.089442)
		(width 0.16002)
		(layer "In2.Cu")
		(net "M_F_CPU0_SB_DQS_DP<9>")
	)
	(segment
		(start 401.858226 -241.744246)
		(end 388.458964 -241.744246)
		(width 0.18288)
		(layer "In2.Cu")
		(net "M_F_CPU0_SB_DQS_DP<9>")
	)
	(segment
		(start 413.563816 -236.87659)
		(end 413.535622 -236.904784)
		(width 0.16002)
		(layer "In2.Cu")
		(net "M_F_CPU0_SB_DQS_DP<9>")
	)
	(segment
		(start 411.622494 -238.06531)
		(end 410.104844 -238.06531)
		(width 0.18288)
		(layer "In2.Cu")
		(net "M_F_CPU0_SB_DQS_DP<9>")
	)
	(segment
		(start 384.389884 -240.677192)
		(end 384.389884 -240.667286)
		(width 0.088646)
		(layer "In2.Cu")
		(net "M_F_CPU0_SB_DQS_DP<9>")
	)
	(segment
		(start 413.335216 -237.089442)
		(end 413.335216 -237.10519)
		(width 0.16002)
		(layer "In2.Cu")
		(net "M_F_CPU0_SB_DQS_DP<9>")
	)
	(segment
		(start 413.535622 -236.904784)
		(end 413.519874 -236.904784)
		(width 0.16002)
		(layer "In2.Cu")
		(net "M_F_CPU0_SB_DQS_DP<9>")
	)
	(segment
		(start 417.414202 -237.829598)
		(end 417.414202 -237.813342)
		(width 0.16002)
		(layer "In2.Cu")
		(net "M_F_CPU0_SB_DQS_DP<9>")
	)
	(segment
		(start 412.068772 -237.619032)
		(end 412.040578 -237.647226)
		(width 0.16002)
		(layer "In2.Cu")
		(net "M_F_CPU0_SB_DQS_DP<9>")
	)
	(segment
		(start 417.029646 -237.445042)
		(end 415.582862 -237.445042)
		(width 0.18288)
		(layer "In2.Cu")
		(net "M_F_CPU0_SB_DQS_DP<9>")
	)
	(segment
		(start 420.200074 -237.842552)
		(end 419.92296 -237.565438)
		(width 0.18288)
		(layer "In2.Cu")
		(net "M_F_CPU0_SB_DQS_DP<9>")
	)
	(segment
		(start 409.69057 -237.63478)
		(end 409.674314 -237.63478)
		(width 0.16002)
		(layer "In2.Cu")
		(net "M_F_CPU0_SB_DQS_DP<9>")
	)
	(segment
		(start 381.103886 -239.918494)
		(end 381.038608 -239.853216)
		(width 0.088646)
		(layer "In2.Cu")
		(net "M_F_CPU0_SB_DQS_DP<9>")
	)
	(segment
		(start 412.992316 -237.44809)
		(end 412.239714 -237.44809)
		(width 0.18288)
		(layer "In2.Cu")
		(net "M_F_CPU0_SB_DQS_DP<9>")
	)
	(segment
		(start 409.583636 -237.544102)
		(end 409.306268 -237.544102)
		(width 0.18288)
		(layer "In2.Cu")
		(net "M_F_CPU0_SB_DQS_DP<9>")
	)
	(arc
		(start 382.322832 -240.342928)
		(mid 382.135634 -240.292785)
		(end 381.948436 -240.342928)
		(width 0.088646)
		(layer "In2.Cu")
		(net "M_F_CPU0_SB_DQS_DP<9>")
	)
	(arc
		(start 384.672332 -241.156744)
		(mid 384.467997 -240.954139)
		(end 384.389884 -240.677192)
		(width 0.088646)
		(layer "In2.Cu")
		(net "M_F_CPU0_SB_DQS_DP<9>")
	)
	(arc
		(start 384.389884 -240.667286)
		(mid 384.342205 -240.484386)
		(end 384.211322 -240.348008)
		(width 0.088646)
		(layer "In2.Cu")
		(net "M_F_CPU0_SB_DQS_DP<9>")
	)
	(arc
		(start 383.828036 -240.342928)
		(mid 383.545334 -240.41867)
		(end 383.262632 -240.342928)
		(width 0.088646)
		(layer "In2.Cu")
		(net "M_F_CPU0_SB_DQS_DP<9>")
	)
	(arc
		(start 381.10668 -239.939576)
		(mid 381.105184 -239.929048)
		(end 381.103886 -239.918494)
		(width 0.088646)
		(layer "In2.Cu")
		(net "M_F_CPU0_SB_DQS_DP<9>")
	)
	(arc
		(start 382.888236 -240.342928)
		(mid 382.605678 -240.418577)
		(end 382.323086 -240.342928)
		(width 0.088646)
		(layer "In2.Cu")
		(net "M_F_CPU0_SB_DQS_DP<9>")
	)
	(arc
		(start 384.202432 -240.342928)
		(mid 384.015234 -240.292785)
		(end 383.828036 -240.342928)
		(width 0.088646)
		(layer "In2.Cu")
		(net "M_F_CPU0_SB_DQS_DP<9>")
	)
	(arc
		(start 381.383032 -240.342928)
		(mid 381.198976 -240.172676)
		(end 381.10668 -239.939576)
		(width 0.088646)
		(layer "In2.Cu")
		(net "M_F_CPU0_SB_DQS_DP<9>")
	)
	(arc
		(start 385.612132 -241.156744)
		(mid 385.424934 -241.106601)
		(end 385.237736 -241.156744)
		(width 0.088646)
		(layer "In2.Cu")
		(net "M_F_CPU0_SB_DQS_DP<9>")
	)
	(arc
		(start 385.799584 -241.481102)
		(mid 385.751905 -241.298202)
		(end 385.621022 -241.161824)
		(width 0.088646)
		(layer "In2.Cu")
		(net "M_F_CPU0_SB_DQS_DP<9>")
	)
	(arc
		(start 385.237736 -241.156744)
		(mid 384.955034 -241.23252)
		(end 384.672332 -241.156744)
		(width 0.088646)
		(layer "In2.Cu")
		(net "M_F_CPU0_SB_DQS_DP<9>")
	)
	(arc
		(start 381.948436 -240.342928)
		(mid 381.665734 -240.41867)
		(end 381.383032 -240.342928)
		(width 0.088646)
		(layer "In2.Cu")
		(net "M_F_CPU0_SB_DQS_DP<9>")
	)
	(arc
		(start 383.262632 -240.342928)
		(mid 383.075434 -240.292785)
		(end 382.888236 -240.342928)
		(width 0.088646)
		(layer "In2.Cu")
		(net "M_F_CPU0_SB_DQS_DP<9>")
	)
	(segment
		(start 380.256034 -228.180646)
		(end 380.256034 -227.64496)
		(width 0.20066)
		(layer "F.Cu")
		(net "M_F_CPU0_SB_DQS_DP<8>")
	)
	(segment
		(start 432.648614 -199.284844)
		(end 432.916838 -199.01662)
		(width 0.20066)
		(layer "F.Cu")
		(net "M_F_CPU0_SB_DQS_DP<8>")
	)
	(segment
		(start 432.916838 -199.01662)
		(end 433.484782 -199.01662)
		(width 0.20066)
		(layer "F.Cu")
		(net "M_F_CPU0_SB_DQS_DP<8>")
	)
	(segment
		(start 427.793658 -198.842884)
		(end 428.051976 -198.584566)
		(width 0.20066)
		(layer "F.Cu")
		(net "M_F_CPU0_SB_DQS_DP<8>")
	)
	(segment
		(start 431.625502 -198.839328)
		(end 432.071018 -199.284844)
		(width 0.20066)
		(layer "F.Cu")
		(net "M_F_CPU0_SB_DQS_DP<8>")
	)
	(segment
		(start 430.38776 -198.591678)
		(end 430.395126 -198.584312)
		(width 0.1016)
		(layer "F.Cu")
		(net "M_F_CPU0_SB_DQS_DP<8>")
	)
	(segment
		(start 428.375064 -198.591678)
		(end 430.38776 -198.591678)
		(width 0.1016)
		(layer "F.Cu")
		(net "M_F_CPU0_SB_DQS_DP<8>")
	)
	(segment
		(start 428.051976 -198.584566)
		(end 428.363126 -198.584566)
		(width 0.20066)
		(layer "F.Cu")
		(net "M_F_CPU0_SB_DQS_DP<8>")
	)
	(segment
		(start 425.940982 -199.01662)
		(end 426.534326 -199.01662)
		(width 0.20066)
		(layer "F.Cu")
		(net "M_F_CPU0_SB_DQS_DP<8>")
	)
	(segment
		(start 428.363126 -198.584566)
		(end 428.367952 -198.584566)
		(width 0.101854)
		(layer "F.Cu")
		(net "M_F_CPU0_SB_DQS_DP<8>")
	)
	(segment
		(start 427.090332 -199.267826)
		(end 427.515274 -198.842884)
		(width 0.20066)
		(layer "F.Cu")
		(net "M_F_CPU0_SB_DQS_DP<8>")
	)
	(segment
		(start 427.515274 -198.842884)
		(end 427.793658 -198.842884)
		(width 0.20066)
		(layer "F.Cu")
		(net "M_F_CPU0_SB_DQS_DP<8>")
	)
	(segment
		(start 430.716944 -198.584312)
		(end 430.97196 -198.839328)
		(width 0.20066)
		(layer "F.Cu")
		(net "M_F_CPU0_SB_DQS_DP<8>")
	)
	(segment
		(start 430.395126 -198.584312)
		(end 430.716944 -198.584312)
		(width 0.20066)
		(layer "F.Cu")
		(net "M_F_CPU0_SB_DQS_DP<8>")
	)
	(segment
		(start 426.534326 -199.01662)
		(end 426.785532 -199.267826)
		(width 0.20066)
		(layer "F.Cu")
		(net "M_F_CPU0_SB_DQS_DP<8>")
	)
	(segment
		(start 430.97196 -198.839328)
		(end 431.625502 -198.839328)
		(width 0.20066)
		(layer "F.Cu")
		(net "M_F_CPU0_SB_DQS_DP<8>")
	)
	(segment
		(start 424.836082 -199.01662)
		(end 425.940982 -199.01662)
		(width 0.20066)
		(layer "F.Cu")
		(net "M_F_CPU0_SB_DQS_DP<8>")
	)
	(segment
		(start 426.785532 -199.267826)
		(end 427.090332 -199.267826)
		(width 0.20066)
		(layer "F.Cu")
		(net "M_F_CPU0_SB_DQS_DP<8>")
	)
	(segment
		(start 380.25578 -228.1809)
		(end 380.256034 -228.180646)
		(width 0.20066)
		(layer "F.Cu")
		(net "M_F_CPU0_SB_DQS_DP<8>")
	)
	(segment
		(start 428.367952 -198.584566)
		(end 428.375064 -198.591678)
		(width 0.1016)
		(layer "F.Cu")
		(net "M_F_CPU0_SB_DQS_DP<8>")
	)
	(segment
		(start 432.071018 -199.284844)
		(end 432.648614 -199.284844)
		(width 0.20066)
		(layer "F.Cu")
		(net "M_F_CPU0_SB_DQS_DP<8>")
	)
	(segment
		(start 401.381468 -205.564232)
		(end 401.415758 -205.736952)
		(width 0.18288)
		(layer "In4.Cu")
		(net "M_F_CPU0_SB_DQS_DP<8>")
	)
	(segment
		(start 402.90623 -203.506578)
		(end 402.602954 -203.960476)
		(width 0.18288)
		(layer "In4.Cu")
		(net "M_F_CPU0_SB_DQS_DP<8>")
	)
	(segment
		(start 383.91973 -223.56699)
		(end 383.91973 -223.584262)
		(width 0.088646)
		(layer "In4.Cu")
		(net "M_F_CPU0_SB_DQS_DP<8>")
	)
	(segment
		(start 400.621754 -206.701136)
		(end 400.656044 -206.873602)
		(width 0.18288)
		(layer "In4.Cu")
		(net "M_F_CPU0_SB_DQS_DP<8>")
	)
	(segment
		(start 383.271268 -224.70872)
		(end 383.263394 -224.713292)
		(width 0.088646)
		(layer "In4.Cu")
		(net "M_F_CPU0_SB_DQS_DP<8>")
	)
	(segment
		(start 411.475936 -200.58253)
		(end 410.234892 -200.58253)
		(width 0.18288)
		(layer "In4.Cu")
		(net "M_F_CPU0_SB_DQS_DP<8>")
	)
	(segment
		(start 418.996876 -201.392536)
		(end 418.699442 -201.095102)
		(width 0.18288)
		(layer "In4.Cu")
		(net "M_F_CPU0_SB_DQS_DP<8>")
	)
	(segment
		(start 408.747722 -200.552812)
		(end 408.623262 -200.428352)
		(width 0.18288)
		(layer "In4.Cu")
		(net "M_F_CPU0_SB_DQS_DP<8>")
	)
	(segment
		(start 382.320038 -226.34321)
		(end 382.316736 -226.345242)
		(width 0.088646)
		(layer "In4.Cu")
		(net "M_F_CPU0_SB_DQS_DP<8>")
	)
	(segment
		(start 387.039612 -221.508828)
		(end 386.83438 -221.508828)
		(width 0.088646)
		(layer "In4.Cu")
		(net "M_F_CPU0_SB_DQS_DP<8>")
	)
	(segment
		(start 407.406602 -200.552812)
		(end 407.282142 -200.428352)
		(width 0.18288)
		(layer "In4.Cu")
		(net "M_F_CPU0_SB_DQS_DP<8>")
	)
	(segment
		(start 382.510284 -225.998786)
		(end 382.510284 -226.017328)
		(width 0.088646)
		(layer "In4.Cu")
		(net "M_F_CPU0_SB_DQS_DP<8>")
	)
	(segment
		(start 401.684998 -205.109826)
		(end 401.381468 -205.564232)
		(width 0.18288)
		(layer "In4.Cu")
		(net "M_F_CPU0_SB_DQS_DP<8>")
	)
	(segment
		(start 382.322832 -226.341686)
		(end 382.320038 -226.34321)
		(width 0.088646)
		(layer "In4.Cu")
		(net "M_F_CPU0_SB_DQS_DP<8>")
	)
	(segment
		(start 400.925538 -206.24673)
		(end 400.621754 -206.701136)
		(width 0.18288)
		(layer "In4.Cu")
		(net "M_F_CPU0_SB_DQS_DP<8>")
	)
	(segment
		(start 402.430234 -203.994766)
		(end 402.126704 -204.449172)
		(width 0.18288)
		(layer "In4.Cu")
		(net "M_F_CPU0_SB_DQS_DP<8>")
	)
	(segment
		(start 414.66516 -200.551542)
		(end 414.5407 -200.427082)
		(width 0.18288)
		(layer "In4.Cu")
		(net "M_F_CPU0_SB_DQS_DP<8>")
	)
	(segment
		(start 413.9946 -200.427082)
		(end 413.87014 -200.551542)
		(width 0.18288)
		(layer "In4.Cu")
		(net "M_F_CPU0_SB_DQS_DP<8>")
	)
	(segment
		(start 403.17547 -202.879452)
		(end 402.87194 -203.333858)
		(width 0.18288)
		(layer "In4.Cu")
		(net "M_F_CPU0_SB_DQS_DP<8>")
	)
	(segment
		(start 385.142232 -221.458282)
		(end 385.140962 -221.459044)
		(width 0.088646)
		(layer "In4.Cu")
		(net "M_F_CPU0_SB_DQS_DP<8>")
	)
	(segment
		(start 411.78226 -200.276206)
		(end 411.475936 -200.58253)
		(width 0.18288)
		(layer "In4.Cu")
		(net "M_F_CPU0_SB_DQS_DP<8>")
	)
	(segment
		(start 404.541482 -201.325226)
		(end 404.541482 -201.501248)
		(width 0.18288)
		(layer "In4.Cu")
		(net "M_F_CPU0_SB_DQS_DP<8>")
	)
	(segment
		(start 381.391922 -227.964238)
		(end 381.383032 -227.969318)
		(width 0.088646)
		(layer "In4.Cu")
		(net "M_F_CPU0_SB_DQS_DP<8>")
	)
	(segment
		(start 405.103838 -200.938892)
		(end 404.927816 -200.938892)
		(width 0.18288)
		(layer "In4.Cu")
		(net "M_F_CPU0_SB_DQS_DP<8>")
	)
	(segment
		(start 415.960814 -200.551542)
		(end 414.66516 -200.551542)
		(width 0.18288)
		(layer "In4.Cu")
		(net "M_F_CPU0_SB_DQS_DP<8>")
	)
	(segment
		(start 424.565572 -199.30999)
		(end 423.965624 -199.30999)
		(width 0.18288)
		(layer "In4.Cu")
		(net "M_F_CPU0_SB_DQS_DP<8>")
	)
	(segment
		(start 413.87014 -200.551542)
		(end 412.411672 -200.551542)
		(width 0.18288)
		(layer "In4.Cu")
		(net "M_F_CPU0_SB_DQS_DP<8>")
	)
	(segment
		(start 404.541482 -201.501248)
		(end 403.651466 -202.391264)
		(width 0.18288)
		(layer "In4.Cu")
		(net "M_F_CPU0_SB_DQS_DP<8>")
	)
	(segment
		(start 408.623262 -200.428352)
		(end 408.077162 -200.428352)
		(width 0.18288)
		(layer "In4.Cu")
		(net "M_F_CPU0_SB_DQS_DP<8>")
	)
	(segment
		(start 401.098004 -206.21244)
		(end 400.925538 -206.24673)
		(width 0.18288)
		(layer "In4.Cu")
		(net "M_F_CPU0_SB_DQS_DP<8>")
	)
	(segment
		(start 387.69671 -221.309692)
		(end 387.673342 -221.309692)
		(width 0.088646)
		(layer "In4.Cu")
		(net "M_F_CPU0_SB_DQS_DP<8>")
	)
	(segment
		(start 410.234892 -200.58253)
		(end 409.930854 -200.278492)
		(width 0.18288)
		(layer "In4.Cu")
		(net "M_F_CPU0_SB_DQS_DP<8>")
	)
	(segment
		(start 388.51205 -221.309692)
		(end 387.69671 -221.309692)
		(width 0.18288)
		(layer "In4.Cu")
		(net "M_F_CPU0_SB_DQS_DP<8>")
	)
	(segment
		(start 386.082286 -221.458536)
		(end 386.082032 -221.458282)
		(width 0.088646)
		(layer "In4.Cu")
		(net "M_F_CPU0_SB_DQS_DP<8>")
	)
	(segment
		(start 381.008636 -227.969318)
		(end 380.87681 -227.893626)
		(width 0.088646)
		(layer "In4.Cu")
		(net "M_F_CPU0_SB_DQS_DP<8>")
	)
	(segment
		(start 423.403522 -199.69607)
		(end 423.017188 -200.082404)
		(width 0.18288)
		(layer "In4.Cu")
		(net "M_F_CPU0_SB_DQS_DP<8>")
	)
	(segment
		(start 380.87681 -227.893626)
		(end 380.72187 -227.852224)
		(width 0.088646)
		(layer "In4.Cu")
		(net "M_F_CPU0_SB_DQS_DP<8>")
	)
	(segment
		(start 417.46043 -201.368406)
		(end 416.777678 -201.368406)
		(width 0.18288)
		(layer "In4.Cu")
		(net "M_F_CPU0_SB_DQS_DP<8>")
	)
	(segment
		(start 384.674618 -222.270574)
		(end 384.67284 -222.27159)
		(width 0.088646)
		(layer "In4.Cu")
		(net "M_F_CPU0_SB_DQS_DP<8>")
	)
	(segment
		(start 383.450084 -222.75165)
		(end 383.450084 -222.780098)
		(width 0.088646)
		(layer "In4.Cu")
		(net "M_F_CPU0_SB_DQS_DP<8>")
	)
	(segment
		(start 406.736042 -200.428352)
		(end 406.611582 -200.552812)
		(width 0.18288)
		(layer "In4.Cu")
		(net "M_F_CPU0_SB_DQS_DP<8>")
	)
	(segment
		(start 402.87194 -203.333858)
		(end 402.90623 -203.506578)
		(width 0.18288)
		(layer "In4.Cu")
		(net "M_F_CPU0_SB_DQS_DP<8>")
	)
	(segment
		(start 404.927816 -200.938892)
		(end 404.541482 -201.325226)
		(width 0.18288)
		(layer "In4.Cu")
		(net "M_F_CPU0_SB_DQS_DP<8>")
	)
	(segment
		(start 423.965624 -199.30999)
		(end 423.579544 -199.69607)
		(width 0.18288)
		(layer "In4.Cu")
		(net "M_F_CPU0_SB_DQS_DP<8>")
	)
	(segment
		(start 387.673342 -221.309692)
		(end 387.613652 -221.369382)
		(width 0.088646)
		(layer "In4.Cu")
		(net "M_F_CPU0_SB_DQS_DP<8>")
	)
	(segment
		(start 421.85717 -201.418444)
		(end 421.20566 -201.418444)
		(width 0.18288)
		(layer "In4.Cu")
		(net "M_F_CPU0_SB_DQS_DP<8>")
	)
	(segment
		(start 382.331722 -226.336606)
		(end 382.324356 -226.340924)
		(width 0.088646)
		(layer "In4.Cu")
		(net "M_F_CPU0_SB_DQS_DP<8>")
	)
	(segment
		(start 418.699442 -201.095102)
		(end 417.733734 -201.095102)
		(width 0.18288)
		(layer "In4.Cu")
		(net "M_F_CPU0_SB_DQS_DP<8>")
	)
	(segment
		(start 383.732532 -223.899984)
		(end 383.72034 -223.907096)
		(width 0.088646)
		(layer "In4.Cu")
		(net "M_F_CPU0_SB_DQS_DP<8>")
	)
	(segment
		(start 423.017188 -200.258426)
		(end 421.85717 -201.418444)
		(width 0.18288)
		(layer "In4.Cu")
		(net "M_F_CPU0_SB_DQS_DP<8>")
	)
	(segment
		(start 400.014694 -207.833468)
		(end 398.618964 -211.202524)
		(width 0.18288)
		(layer "In4.Cu")
		(net "M_F_CPU0_SB_DQS_DP<8>")
	)
	(segment
		(start 423.579544 -199.69607)
		(end 423.403522 -199.69607)
		(width 0.18288)
		(layer "In4.Cu")
		(net "M_F_CPU0_SB_DQS_DP<8>")
	)
	(segment
		(start 381.570484 -227.635054)
		(end 381.570484 -227.64496)
		(width 0.088646)
		(layer "In4.Cu")
		(net "M_F_CPU0_SB_DQS_DP<8>")
	)
	(segment
		(start 423.017188 -200.082404)
		(end 423.017188 -200.258426)
		(width 0.18288)
		(layer "In4.Cu")
		(net "M_F_CPU0_SB_DQS_DP<8>")
	)
	(segment
		(start 402.126704 -204.449172)
		(end 402.160994 -204.621638)
		(width 0.18288)
		(layer "In4.Cu")
		(net "M_F_CPU0_SB_DQS_DP<8>")
	)
	(segment
		(start 380.72187 -227.852224)
		(end 380.330456 -227.852224)
		(width 0.088646)
		(layer "In4.Cu")
		(net "M_F_CPU0_SB_DQS_DP<8>")
	)
	(segment
		(start 414.5407 -200.427082)
		(end 413.9946 -200.427082)
		(width 0.18288)
		(layer "In4.Cu")
		(net "M_F_CPU0_SB_DQS_DP<8>")
	)
	(segment
		(start 416.777678 -201.368406)
		(end 415.960814 -200.551542)
		(width 0.18288)
		(layer "In4.Cu")
		(net "M_F_CPU0_SB_DQS_DP<8>")
	)
	(segment
		(start 402.602954 -203.960476)
		(end 402.430234 -203.994766)
		(width 0.18288)
		(layer "In4.Cu")
		(net "M_F_CPU0_SB_DQS_DP<8>")
	)
	(segment
		(start 400.656044 -206.873602)
		(end 400.014694 -207.833468)
		(width 0.18288)
		(layer "In4.Cu")
		(net "M_F_CPU0_SB_DQS_DP<8>")
	)
	(segment
		(start 405.489918 -200.552812)
		(end 405.103838 -200.938892)
		(width 0.18288)
		(layer "In4.Cu")
		(net "M_F_CPU0_SB_DQS_DP<8>")
	)
	(segment
		(start 403.34819 -202.845162)
		(end 403.17547 -202.879452)
		(width 0.18288)
		(layer "In4.Cu")
		(net "M_F_CPU0_SB_DQS_DP<8>")
	)
	(segment
		(start 383.263394 -224.713292)
		(end 383.262378 -224.7138)
		(width 0.088646)
		(layer "In4.Cu")
		(net "M_F_CPU0_SB_DQS_DP<8>")
	)
	(segment
		(start 402.160994 -204.621638)
		(end 401.857718 -205.075536)
		(width 0.18288)
		(layer "In4.Cu")
		(net "M_F_CPU0_SB_DQS_DP<8>")
	)
	(segment
		(start 384.680206 -222.267526)
		(end 384.67538 -222.270066)
		(width 0.088646)
		(layer "In4.Cu")
		(net "M_F_CPU0_SB_DQS_DP<8>")
	)
	(segment
		(start 420.929816 -201.1426)
		(end 420.52494 -201.1426)
		(width 0.18288)
		(layer "In4.Cu")
		(net "M_F_CPU0_SB_DQS_DP<8>")
	)
	(segment
		(start 408.077162 -200.428352)
		(end 407.952702 -200.552812)
		(width 0.18288)
		(layer "In4.Cu")
		(net "M_F_CPU0_SB_DQS_DP<8>")
	)
	(segment
		(start 380.256034 -227.777802)
		(end 380.256034 -227.64496)
		(width 0.088646)
		(layer "In4.Cu")
		(net "M_F_CPU0_SB_DQS_DP<8>")
	)
	(segment
		(start 387.613652 -221.369382)
		(end 387.179058 -221.369382)
		(width 0.088646)
		(layer "In4.Cu")
		(net "M_F_CPU0_SB_DQS_DP<8>")
	)
	(segment
		(start 398.618964 -211.202524)
		(end 388.51205 -221.309692)
		(width 0.18288)
		(layer "In4.Cu")
		(net "M_F_CPU0_SB_DQS_DP<8>")
	)
	(segment
		(start 409.293822 -200.552812)
		(end 408.747722 -200.552812)
		(width 0.18288)
		(layer "In4.Cu")
		(net "M_F_CPU0_SB_DQS_DP<8>")
	)
	(segment
		(start 406.611582 -200.552812)
		(end 405.489918 -200.552812)
		(width 0.18288)
		(layer "In4.Cu")
		(net "M_F_CPU0_SB_DQS_DP<8>")
	)
	(segment
		(start 417.733734 -201.095102)
		(end 417.46043 -201.368406)
		(width 0.18288)
		(layer "In4.Cu")
		(net "M_F_CPU0_SB_DQS_DP<8>")
	)
	(segment
		(start 412.136336 -200.276206)
		(end 411.78226 -200.276206)
		(width 0.18288)
		(layer "In4.Cu")
		(net "M_F_CPU0_SB_DQS_DP<8>")
	)
	(segment
		(start 384.67538 -222.270066)
		(end 384.674618 -222.270574)
		(width 0.088646)
		(layer "In4.Cu")
		(net "M_F_CPU0_SB_DQS_DP<8>")
	)
	(segment
		(start 382.801622 -225.522536)
		(end 382.792732 -225.527616)
		(width 0.088646)
		(layer "In4.Cu")
		(net "M_F_CPU0_SB_DQS_DP<8>")
	)
	(segment
		(start 409.930854 -200.278492)
		(end 409.568142 -200.278492)
		(width 0.18288)
		(layer "In4.Cu")
		(net "M_F_CPU0_SB_DQS_DP<8>")
	)
	(segment
		(start 382.04013 -226.831144)
		(end 382.04013 -226.83978)
		(width 0.088646)
		(layer "In4.Cu")
		(net "M_F_CPU0_SB_DQS_DP<8>")
	)
	(segment
		(start 384.297682 -222.272098)
		(end 384.287268 -222.266002)
		(width 0.088646)
		(layer "In4.Cu")
		(net "M_F_CPU0_SB_DQS_DP<8>")
	)
	(segment
		(start 401.857718 -205.075536)
		(end 401.684998 -205.109826)
		(width 0.18288)
		(layer "In4.Cu")
		(net "M_F_CPU0_SB_DQS_DP<8>")
	)
	(segment
		(start 382.980184 -225.187764)
		(end 382.980184 -225.203258)
		(width 0.088646)
		(layer "In4.Cu")
		(net "M_F_CPU0_SB_DQS_DP<8>")
	)
	(segment
		(start 401.415758 -205.736952)
		(end 401.098004 -206.21244)
		(width 0.18288)
		(layer "In4.Cu")
		(net "M_F_CPU0_SB_DQS_DP<8>")
	)
	(segment
		(start 384.67284 -222.27159)
		(end 384.672078 -222.272098)
		(width 0.088646)
		(layer "In4.Cu")
		(net "M_F_CPU0_SB_DQS_DP<8>")
	)
	(segment
		(start 424.836082 -199.03948)
		(end 424.565572 -199.30999)
		(width 0.18288)
		(layer "In4.Cu")
		(net "M_F_CPU0_SB_DQS_DP<8>")
	)
	(segment
		(start 387.179058 -221.369382)
		(end 387.039612 -221.508828)
		(width 0.088646)
		(layer "In4.Cu")
		(net "M_F_CPU0_SB_DQS_DP<8>")
	)
	(segment
		(start 420.52494 -201.1426)
		(end 420.275004 -201.392536)
		(width 0.18288)
		(layer "In4.Cu")
		(net "M_F_CPU0_SB_DQS_DP<8>")
	)
	(segment
		(start 385.140962 -221.459044)
		(end 385.13004 -221.465394)
		(width 0.088646)
		(layer "In4.Cu")
		(net "M_F_CPU0_SB_DQS_DP<8>")
	)
	(segment
		(start 421.20566 -201.418444)
		(end 420.929816 -201.1426)
		(width 0.18288)
		(layer "In4.Cu")
		(net "M_F_CPU0_SB_DQS_DP<8>")
	)
	(segment
		(start 420.275004 -201.392536)
		(end 418.996876 -201.392536)
		(width 0.18288)
		(layer "In4.Cu")
		(net "M_F_CPU0_SB_DQS_DP<8>")
	)
	(segment
		(start 382.324356 -226.340924)
		(end 382.322832 -226.341686)
		(width 0.088646)
		(layer "In4.Cu")
		(net "M_F_CPU0_SB_DQS_DP<8>")
	)
	(segment
		(start 409.568142 -200.278492)
		(end 409.293822 -200.552812)
		(width 0.18288)
		(layer "In4.Cu")
		(net "M_F_CPU0_SB_DQS_DP<8>")
	)
	(segment
		(start 407.952702 -200.552812)
		(end 407.406602 -200.552812)
		(width 0.18288)
		(layer "In4.Cu")
		(net "M_F_CPU0_SB_DQS_DP<8>")
	)
	(segment
		(start 424.836082 -199.01662)
		(end 424.836082 -199.03948)
		(width 0.18288)
		(layer "In4.Cu")
		(net "M_F_CPU0_SB_DQS_DP<8>")
	)
	(segment
		(start 384.680968 -222.267018)
		(end 384.680206 -222.267526)
		(width 0.088646)
		(layer "In4.Cu")
		(net "M_F_CPU0_SB_DQS_DP<8>")
	)
	(segment
		(start 403.651466 -202.391264)
		(end 403.34819 -202.845162)
		(width 0.18288)
		(layer "In4.Cu")
		(net "M_F_CPU0_SB_DQS_DP<8>")
	)
	(segment
		(start 412.411672 -200.551542)
		(end 412.136336 -200.276206)
		(width 0.18288)
		(layer "In4.Cu")
		(net "M_F_CPU0_SB_DQS_DP<8>")
	)
	(segment
		(start 407.282142 -200.428352)
		(end 406.736042 -200.428352)
		(width 0.18288)
		(layer "In4.Cu")
		(net "M_F_CPU0_SB_DQS_DP<8>")
	)
	(arc
		(start 383.732532 -223.251268)
		(mid 383.867465 -223.384622)
		(end 383.91973 -223.56699)
		(width 0.088646)
		(layer "In4.Cu")
		(net "M_F_CPU0_SB_DQS_DP<8>")
	)
	(arc
		(start 385.707636 -221.458282)
		(mid 385.424934 -221.382506)
		(end 385.142232 -221.458282)
		(width 0.088646)
		(layer "In4.Cu")
		(net "M_F_CPU0_SB_DQS_DP<8>")
	)
	(arc
		(start 382.04013 -226.83978)
		(mid 381.98786 -227.022145)
		(end 381.852932 -227.155502)
		(width 0.088646)
		(layer "In4.Cu")
		(net "M_F_CPU0_SB_DQS_DP<8>")
	)
	(arc
		(start 381.852932 -227.155502)
		(mid 381.648597 -227.358107)
		(end 381.570484 -227.635054)
		(width 0.088646)
		(layer "In4.Cu")
		(net "M_F_CPU0_SB_DQS_DP<8>")
	)
	(arc
		(start 386.082032 -221.458282)
		(mid 385.894834 -221.508425)
		(end 385.707636 -221.458282)
		(width 0.088646)
		(layer "In4.Cu")
		(net "M_F_CPU0_SB_DQS_DP<8>")
	)
	(arc
		(start 383.44983 -224.389442)
		(mid 383.402151 -224.572342)
		(end 383.271268 -224.70872)
		(width 0.088646)
		(layer "In4.Cu")
		(net "M_F_CPU0_SB_DQS_DP<8>")
	)
	(arc
		(start 381.383032 -227.969318)
		(mid 381.195834 -228.019461)
		(end 381.008636 -227.969318)
		(width 0.088646)
		(layer "In4.Cu")
		(net "M_F_CPU0_SB_DQS_DP<8>")
	)
	(arc
		(start 384.672078 -222.272098)
		(mid 384.48488 -222.322241)
		(end 384.297682 -222.272098)
		(width 0.088646)
		(layer "In4.Cu")
		(net "M_F_CPU0_SB_DQS_DP<8>")
	)
	(arc
		(start 385.13004 -221.465394)
		(mid 384.931812 -221.671242)
		(end 384.85953 -221.94774)
		(width 0.088646)
		(layer "In4.Cu")
		(net "M_F_CPU0_SB_DQS_DP<8>")
	)
	(arc
		(start 384.287268 -222.266002)
		(mid 384.00909 -222.196279)
		(end 383.732532 -222.272098)
		(width 0.088646)
		(layer "In4.Cu")
		(net "M_F_CPU0_SB_DQS_DP<8>")
	)
	(arc
		(start 382.792732 -225.527616)
		(mid 382.590446 -225.726597)
		(end 382.510284 -225.998786)
		(width 0.088646)
		(layer "In4.Cu")
		(net "M_F_CPU0_SB_DQS_DP<8>")
	)
	(arc
		(start 382.316736 -226.345242)
		(mid 382.114149 -226.551593)
		(end 382.04013 -226.831144)
		(width 0.088646)
		(layer "In4.Cu")
		(net "M_F_CPU0_SB_DQS_DP<8>")
	)
	(arc
		(start 383.732532 -222.272098)
		(mid 383.528197 -222.474703)
		(end 383.450084 -222.75165)
		(width 0.088646)
		(layer "In4.Cu")
		(net "M_F_CPU0_SB_DQS_DP<8>")
	)
	(arc
		(start 382.510284 -226.017328)
		(mid 382.462605 -226.200228)
		(end 382.331722 -226.336606)
		(width 0.088646)
		(layer "In4.Cu")
		(net "M_F_CPU0_SB_DQS_DP<8>")
	)
	(arc
		(start 383.262378 -224.7138)
		(mid 383.059555 -224.914031)
		(end 382.980184 -225.187764)
		(width 0.088646)
		(layer "In4.Cu")
		(net "M_F_CPU0_SB_DQS_DP<8>")
	)
	(arc
		(start 383.72034 -223.907096)
		(mid 383.522112 -224.112944)
		(end 383.44983 -224.389442)
		(width 0.088646)
		(layer "In4.Cu")
		(net "M_F_CPU0_SB_DQS_DP<8>")
	)
	(arc
		(start 383.91973 -223.584262)
		(mid 383.86746 -223.766627)
		(end 383.732532 -223.899984)
		(width 0.088646)
		(layer "In4.Cu")
		(net "M_F_CPU0_SB_DQS_DP<8>")
	)
	(arc
		(start 382.980184 -225.203258)
		(mid 382.932505 -225.386158)
		(end 382.801622 -225.522536)
		(width 0.088646)
		(layer "In4.Cu")
		(net "M_F_CPU0_SB_DQS_DP<8>")
	)
	(arc
		(start 383.450084 -222.780098)
		(mid 383.530246 -223.052287)
		(end 383.732532 -223.251268)
		(width 0.088646)
		(layer "In4.Cu")
		(net "M_F_CPU0_SB_DQS_DP<8>")
	)
	(arc
		(start 386.83438 -221.508828)
		(mid 386.737332 -221.496049)
		(end 386.646928 -221.458536)
		(width 0.088646)
		(layer "In4.Cu")
		(net "M_F_CPU0_SB_DQS_DP<8>")
	)
	(arc
		(start 384.85953 -221.94774)
		(mid 384.811851 -222.13064)
		(end 384.680968 -222.267018)
		(width 0.088646)
		(layer "In4.Cu")
		(net "M_F_CPU0_SB_DQS_DP<8>")
	)
	(arc
		(start 381.570484 -227.64496)
		(mid 381.522805 -227.82786)
		(end 381.391922 -227.964238)
		(width 0.088646)
		(layer "In4.Cu")
		(net "M_F_CPU0_SB_DQS_DP<8>")
	)
	(arc
		(start 380.330456 -227.852224)
		(mid 380.277832 -227.830426)
		(end 380.256034 -227.777802)
		(width 0.088646)
		(layer "In4.Cu")
		(net "M_F_CPU0_SB_DQS_DP<8>")
	)
	(arc
		(start 386.646928 -221.458536)
		(mid 386.364624 -221.38298)
		(end 386.082286 -221.458536)
		(width 0.088646)
		(layer "In4.Cu")
		(net "M_F_CPU0_SB_DQS_DP<8>")
	)
	(segment
		(start 428.375064 -207.941672)
		(end 430.38776 -207.941672)
		(width 0.1016)
		(layer "F.Cu")
		(net "M_F_CPU0_SB_DQS_DP<7>")
	)
	(segment
		(start 432.916838 -208.366614)
		(end 433.484782 -208.366614)
		(width 0.20066)
		(layer "F.Cu")
		(net "M_F_CPU0_SB_DQS_DP<7>")
	)
	(segment
		(start 428.051976 -207.93456)
		(end 428.363126 -207.93456)
		(width 0.20066)
		(layer "F.Cu")
		(net "M_F_CPU0_SB_DQS_DP<7>")
	)
	(segment
		(start 428.367952 -207.93456)
		(end 428.375064 -207.941672)
		(width 0.1016)
		(layer "F.Cu")
		(net "M_F_CPU0_SB_DQS_DP<7>")
	)
	(segment
		(start 427.515274 -208.192878)
		(end 427.793658 -208.192878)
		(width 0.20066)
		(layer "F.Cu")
		(net "M_F_CPU0_SB_DQS_DP<7>")
	)
	(segment
		(start 424.836082 -208.366614)
		(end 425.940982 -208.366614)
		(width 0.20066)
		(layer "F.Cu")
		(net "M_F_CPU0_SB_DQS_DP<7>")
	)
	(segment
		(start 432.648614 -208.634838)
		(end 432.916838 -208.366614)
		(width 0.20066)
		(layer "F.Cu")
		(net "M_F_CPU0_SB_DQS_DP<7>")
	)
	(segment
		(start 385.894834 -223.297496)
		(end 385.894834 -222.761556)
		(width 0.20066)
		(layer "F.Cu")
		(net "M_F_CPU0_SB_DQS_DP<7>")
	)
	(segment
		(start 425.940982 -208.366614)
		(end 426.534326 -208.366614)
		(width 0.20066)
		(layer "F.Cu")
		(net "M_F_CPU0_SB_DQS_DP<7>")
	)
	(segment
		(start 430.395126 -207.934306)
		(end 430.716944 -207.934306)
		(width 0.20066)
		(layer "F.Cu")
		(net "M_F_CPU0_SB_DQS_DP<7>")
	)
	(segment
		(start 427.090332 -208.61782)
		(end 427.515274 -208.192878)
		(width 0.20066)
		(layer "F.Cu")
		(net "M_F_CPU0_SB_DQS_DP<7>")
	)
	(segment
		(start 430.97196 -208.189322)
		(end 431.625502 -208.189322)
		(width 0.20066)
		(layer "F.Cu")
		(net "M_F_CPU0_SB_DQS_DP<7>")
	)
	(segment
		(start 431.625502 -208.189322)
		(end 432.071018 -208.634838)
		(width 0.20066)
		(layer "F.Cu")
		(net "M_F_CPU0_SB_DQS_DP<7>")
	)
	(segment
		(start 432.071018 -208.634838)
		(end 432.648614 -208.634838)
		(width 0.20066)
		(layer "F.Cu")
		(net "M_F_CPU0_SB_DQS_DP<7>")
	)
	(segment
		(start 426.534326 -208.366614)
		(end 426.785532 -208.61782)
		(width 0.20066)
		(layer "F.Cu")
		(net "M_F_CPU0_SB_DQS_DP<7>")
	)
	(segment
		(start 430.716944 -207.934306)
		(end 430.97196 -208.189322)
		(width 0.20066)
		(layer "F.Cu")
		(net "M_F_CPU0_SB_DQS_DP<7>")
	)
	(segment
		(start 427.793658 -208.192878)
		(end 428.051976 -207.93456)
		(width 0.20066)
		(layer "F.Cu")
		(net "M_F_CPU0_SB_DQS_DP<7>")
	)
	(segment
		(start 428.363126 -207.93456)
		(end 428.367952 -207.93456)
		(width 0.101854)
		(layer "F.Cu")
		(net "M_F_CPU0_SB_DQS_DP<7>")
	)
	(segment
		(start 426.785532 -208.61782)
		(end 427.090332 -208.61782)
		(width 0.20066)
		(layer "F.Cu")
		(net "M_F_CPU0_SB_DQS_DP<7>")
	)
	(segment
		(start 430.38776 -207.941672)
		(end 430.395126 -207.934306)
		(width 0.1016)
		(layer "F.Cu")
		(net "M_F_CPU0_SB_DQS_DP<7>")
	)
	(segment
		(start 414.909508 -206.513176)
		(end 413.71647 -206.513176)
		(width 0.18288)
		(layer "In2.Cu")
		(net "M_F_CPU0_SB_DQS_DP<7>")
	)
	(segment
		(start 417.178998 -208.02727)
		(end 416.423602 -208.02727)
		(width 0.18288)
		(layer "In2.Cu")
		(net "M_F_CPU0_SB_DQS_DP<7>")
	)
	(segment
		(start 422.724072 -208.539334)
		(end 422.408096 -208.223358)
		(width 0.18288)
		(layer "In2.Cu")
		(net "M_F_CPU0_SB_DQS_DP<7>")
	)
	(segment
		(start 422.935146 -208.750408)
		(end 422.906952 -208.722214)
		(width 0.16002)
		(layer "In2.Cu")
		(net "M_F_CPU0_SB_DQS_DP<7>")
	)
	(segment
		(start 424.32986 -208.620106)
		(end 423.651172 -208.90103)
		(width 0.18288)
		(layer "In2.Cu")
		(net "M_F_CPU0_SB_DQS_DP<7>")
	)
	(segment
		(start 419.388036 -207.80756)
		(end 419.388036 -207.791304)
		(width 0.16002)
		(layer "In2.Cu")
		(net "M_F_CPU0_SB_DQS_DP<7>")
	)
	(segment
		(start 387.500622 -222.267018)
		(end 387.493256 -222.271336)
		(width 0.088646)
		(layer "In2.Cu")
		(net "M_F_CPU0_SB_DQS_DP<7>")
	)
	(segment
		(start 423.651172 -208.90103)
		(end 423.085768 -208.90103)
		(width 0.18288)
		(layer "In2.Cu")
		(net "M_F_CPU0_SB_DQS_DP<7>")
	)
	(segment
		(start 387.491478 -222.272352)
		(end 387.471412 -222.283782)
		(width 0.088646)
		(layer "In2.Cu")
		(net "M_F_CPU0_SB_DQS_DP<7>")
	)
	(segment
		(start 417.27374 -207.948784)
		(end 417.257484 -207.948784)
		(width 0.16002)
		(layer "In2.Cu")
		(net "M_F_CPU0_SB_DQS_DP<7>")
	)
	(segment
		(start 386.647182 -222.437198)
		(end 386.617464 -222.45447)
		(width 0.088646)
		(layer "In2.Cu")
		(net "M_F_CPU0_SB_DQS_DP<7>")
	)
	(segment
		(start 409.780486 -205.37932)
		(end 409.316682 -205.37932)
		(width 0.18288)
		(layer "In2.Cu")
		(net "M_F_CPU0_SB_DQS_DP<7>")
	)
	(segment
		(start 422.752266 -208.583784)
		(end 422.752266 -208.567528)
		(width 0.16002)
		(layer "In2.Cu")
		(net "M_F_CPU0_SB_DQS_DP<7>")
	)
	(segment
		(start 410.064458 -205.663292)
		(end 409.780486 -205.37932)
		(width 0.18288)
		(layer "In2.Cu")
		(net "M_F_CPU0_SB_DQS_DP<7>")
	)
	(segment
		(start 387.110478 -222.437198)
		(end 387.021578 -222.437198)
		(width 0.088646)
		(layer "In2.Cu")
		(net "M_F_CPU0_SB_DQS_DP<7>")
	)
	(segment
		(start 387.491732 -222.272098)
		(end 387.491478 -222.272352)
		(width 0.088646)
		(layer "In2.Cu")
		(net "M_F_CPU0_SB_DQS_DP<7>")
	)
	(segment
		(start 422.408096 -208.223358)
		(end 421.314626 -208.223358)
		(width 0.18288)
		(layer "In2.Cu")
		(net "M_F_CPU0_SB_DQS_DP<7>")
	)
	(segment
		(start 413.432498 -206.229204)
		(end 412.968694 -206.229204)
		(width 0.18288)
		(layer "In2.Cu")
		(net "M_F_CPU0_SB_DQS_DP<7>")
	)
	(segment
		(start 421.031416 -207.940148)
		(end 420.432738 -207.940148)
		(width 0.18288)
		(layer "In2.Cu")
		(net "M_F_CPU0_SB_DQS_DP<7>")
	)
	(segment
		(start 390.020302 -220.743526)
		(end 389.634984 -220.743526)
		(width 0.088646)
		(layer "In2.Cu")
		(net "M_F_CPU0_SB_DQS_DP<7>")
	)
	(segment
		(start 422.890696 -208.722214)
		(end 422.752266 -208.583784)
		(width 0.16002)
		(layer "In2.Cu")
		(net "M_F_CPU0_SB_DQS_DP<7>")
	)
	(segment
		(start 416.423602 -208.02727)
		(end 414.909508 -206.513176)
		(width 0.18288)
		(layer "In2.Cu")
		(net "M_F_CPU0_SB_DQS_DP<7>")
	)
	(segment
		(start 417.41217 -207.794098)
		(end 417.41217 -207.810354)
		(width 0.16002)
		(layer "In2.Cu")
		(net "M_F_CPU0_SB_DQS_DP<7>")
	)
	(segment
		(start 420.432738 -207.940148)
		(end 420.198042 -208.174844)
		(width 0.18288)
		(layer "In2.Cu")
		(net "M_F_CPU0_SB_DQS_DP<7>")
	)
	(segment
		(start 419.526466 -207.94599)
		(end 419.388036 -207.80756)
		(width 0.16002)
		(layer "In2.Cu")
		(net "M_F_CPU0_SB_DQS_DP<7>")
	)
	(segment
		(start 420.198042 -208.174844)
		(end 419.771576 -208.174844)
		(width 0.18288)
		(layer "In2.Cu")
		(net "M_F_CPU0_SB_DQS_DP<7>")
	)
	(segment
		(start 408.231594 -205.66761)
		(end 407.637742 -205.073758)
		(width 0.18288)
		(layer "In2.Cu")
		(net "M_F_CPU0_SB_DQS_DP<7>")
	)
	(segment
		(start 405.952706 -205.073758)
		(end 404.901908 -205.775814)
		(width 0.18288)
		(layer "In2.Cu")
		(net "M_F_CPU0_SB_DQS_DP<7>")
	)
	(segment
		(start 412.968694 -206.229204)
		(end 412.666688 -206.53121)
		(width 0.18288)
		(layer "In2.Cu")
		(net "M_F_CPU0_SB_DQS_DP<7>")
	)
	(segment
		(start 419.388036 -207.791304)
		(end 419.359842 -207.76311)
		(width 0.16002)
		(layer "In2.Cu")
		(net "M_F_CPU0_SB_DQS_DP<7>")
	)
	(segment
		(start 422.752266 -208.567528)
		(end 422.724072 -208.539334)
		(width 0.16002)
		(layer "In2.Cu")
		(net "M_F_CPU0_SB_DQS_DP<7>")
	)
	(segment
		(start 387.493256 -222.271336)
		(end 387.491732 -222.272098)
		(width 0.088646)
		(layer "In2.Cu")
		(net "M_F_CPU0_SB_DQS_DP<7>")
	)
	(segment
		(start 387.679184 -221.937834)
		(end 387.679184 -221.94774)
		(width 0.088646)
		(layer "In2.Cu")
		(net "M_F_CPU0_SB_DQS_DP<7>")
	)
	(segment
		(start 417.628578 -207.57769)
		(end 417.440364 -207.765904)
		(width 0.18288)
		(layer "In2.Cu")
		(net "M_F_CPU0_SB_DQS_DP<7>")
	)
	(segment
		(start 412.338774 -206.53121)
		(end 411.470856 -205.663292)
		(width 0.18288)
		(layer "In2.Cu")
		(net "M_F_CPU0_SB_DQS_DP<7>")
	)
	(segment
		(start 409.316682 -205.37932)
		(end 409.028392 -205.66761)
		(width 0.18288)
		(layer "In2.Cu")
		(net "M_F_CPU0_SB_DQS_DP<7>")
	)
	(segment
		(start 419.771576 -208.174844)
		(end 419.570916 -207.974184)
		(width 0.18288)
		(layer "In2.Cu")
		(net "M_F_CPU0_SB_DQS_DP<7>")
	)
	(segment
		(start 412.666688 -206.53121)
		(end 412.338774 -206.53121)
		(width 0.18288)
		(layer "In2.Cu")
		(net "M_F_CPU0_SB_DQS_DP<7>")
	)
	(segment
		(start 424.836082 -208.366614)
		(end 424.58259 -208.620106)
		(width 0.18288)
		(layer "In2.Cu")
		(net "M_F_CPU0_SB_DQS_DP<7>")
	)
	(segment
		(start 387.110986 -222.43669)
		(end 387.110478 -222.437198)
		(width 0.088646)
		(layer "In2.Cu")
		(net "M_F_CPU0_SB_DQS_DP<7>")
	)
	(segment
		(start 395.924532 -214.753444)
		(end 395.921738 -214.753444)
		(width 0.18288)
		(layer "In2.Cu")
		(net "M_F_CPU0_SB_DQS_DP<7>")
	)
	(segment
		(start 404.901908 -205.775814)
		(end 396.31239 -214.365586)
		(width 0.18288)
		(layer "In2.Cu")
		(net "M_F_CPU0_SB_DQS_DP<7>")
	)
	(segment
		(start 419.174422 -207.57769)
		(end 417.628578 -207.57769)
		(width 0.18288)
		(layer "In2.Cu")
		(net "M_F_CPU0_SB_DQS_DP<7>")
	)
	(segment
		(start 395.921738 -214.753444)
		(end 390.600184 -220.074998)
		(width 0.18288)
		(layer "In2.Cu")
		(net "M_F_CPU0_SB_DQS_DP<7>")
	)
	(segment
		(start 419.570916 -207.974184)
		(end 419.542722 -207.94599)
		(width 0.16002)
		(layer "In2.Cu")
		(net "M_F_CPU0_SB_DQS_DP<7>")
	)
	(segment
		(start 389.634984 -220.743526)
		(end 388.97941 -221.3991)
		(width 0.088646)
		(layer "In2.Cu")
		(net "M_F_CPU0_SB_DQS_DP<7>")
	)
	(segment
		(start 421.314626 -208.223358)
		(end 421.031416 -207.940148)
		(width 0.18288)
		(layer "In2.Cu")
		(net "M_F_CPU0_SB_DQS_DP<7>")
	)
	(segment
		(start 417.41217 -207.810354)
		(end 417.27374 -207.948784)
		(width 0.16002)
		(layer "In2.Cu")
		(net "M_F_CPU0_SB_DQS_DP<7>")
	)
	(segment
		(start 409.028392 -205.66761)
		(end 408.231594 -205.66761)
		(width 0.18288)
		(layer "In2.Cu")
		(net "M_F_CPU0_SB_DQS_DP<7>")
	)
	(segment
		(start 419.542722 -207.94599)
		(end 419.526466 -207.94599)
		(width 0.16002)
		(layer "In2.Cu")
		(net "M_F_CPU0_SB_DQS_DP<7>")
	)
	(segment
		(start 387.471412 -222.283782)
		(end 387.110986 -222.43669)
		(width 0.088646)
		(layer "In2.Cu")
		(net "M_F_CPU0_SB_DQS_DP<7>")
	)
	(segment
		(start 417.257484 -207.948784)
		(end 417.22929 -207.976978)
		(width 0.16002)
		(layer "In2.Cu")
		(net "M_F_CPU0_SB_DQS_DP<7>")
	)
	(segment
		(start 417.22929 -207.976978)
		(end 417.178998 -208.02727)
		(width 0.18288)
		(layer "In2.Cu")
		(net "M_F_CPU0_SB_DQS_DP<7>")
	)
	(segment
		(start 419.359842 -207.76311)
		(end 419.174422 -207.57769)
		(width 0.18288)
		(layer "In2.Cu")
		(net "M_F_CPU0_SB_DQS_DP<7>")
	)
	(segment
		(start 422.906952 -208.722214)
		(end 422.890696 -208.722214)
		(width 0.16002)
		(layer "In2.Cu")
		(net "M_F_CPU0_SB_DQS_DP<7>")
	)
	(segment
		(start 411.470856 -205.663292)
		(end 410.064458 -205.663292)
		(width 0.18288)
		(layer "In2.Cu")
		(net "M_F_CPU0_SB_DQS_DP<7>")
	)
	(segment
		(start 386.617464 -222.45447)
		(end 385.894834 -222.761556)
		(width 0.088646)
		(layer "In2.Cu")
		(net "M_F_CPU0_SB_DQS_DP<7>")
	)
	(segment
		(start 413.71647 -206.513176)
		(end 413.432498 -206.229204)
		(width 0.18288)
		(layer "In2.Cu")
		(net "M_F_CPU0_SB_DQS_DP<7>")
	)
	(segment
		(start 407.637742 -205.073758)
		(end 405.952706 -205.073758)
		(width 0.18288)
		(layer "In2.Cu")
		(net "M_F_CPU0_SB_DQS_DP<7>")
	)
	(segment
		(start 424.58259 -208.620106)
		(end 424.32986 -208.620106)
		(width 0.18288)
		(layer "In2.Cu")
		(net "M_F_CPU0_SB_DQS_DP<7>")
	)
	(segment
		(start 423.085768 -208.90103)
		(end 422.935146 -208.750408)
		(width 0.18288)
		(layer "In2.Cu")
		(net "M_F_CPU0_SB_DQS_DP<7>")
	)
	(segment
		(start 390.600184 -220.074998)
		(end 390.600184 -220.163644)
		(width 0.088646)
		(layer "In2.Cu")
		(net "M_F_CPU0_SB_DQS_DP<7>")
	)
	(segment
		(start 417.440364 -207.765904)
		(end 417.41217 -207.794098)
		(width 0.16002)
		(layer "In2.Cu")
		(net "M_F_CPU0_SB_DQS_DP<7>")
	)
	(segment
		(start 390.600184 -220.163644)
		(end 390.020302 -220.743526)
		(width 0.088646)
		(layer "In2.Cu")
		(net "M_F_CPU0_SB_DQS_DP<7>")
	)
	(segment
		(start 396.31239 -214.365586)
		(end 395.924532 -214.753444)
		(width 0.18288)
		(layer "In2.Cu")
		(net "M_F_CPU0_SB_DQS_DP<7>")
	)
	(segment
		(start 388.97941 -221.3991)
		(end 388.97941 -221.398846)
		(width 0.088646)
		(layer "In2.Cu")
		(net "M_F_CPU0_SB_DQS_DP<7>")
	)
	(arc
		(start 388.527036 -221.458282)
		(mid 387.96606 -221.455751)
		(end 387.679184 -221.937834)
		(width 0.088646)
		(layer "In2.Cu")
		(net "M_F_CPU0_SB_DQS_DP<7>")
	)
	(arc
		(start 387.021578 -222.437198)
		(mid 386.83438 -222.387055)
		(end 386.647182 -222.437198)
		(width 0.088646)
		(layer "In2.Cu")
		(net "M_F_CPU0_SB_DQS_DP<7>")
	)
	(arc
		(start 388.97941 -221.398846)
		(mid 388.962487 -221.414751)
		(end 388.944612 -221.42958)
		(width 0.088646)
		(layer "In2.Cu")
		(net "M_F_CPU0_SB_DQS_DP<7>")
	)
	(arc
		(start 387.679184 -221.94774)
		(mid 387.631505 -222.13064)
		(end 387.500622 -222.267018)
		(width 0.088646)
		(layer "In2.Cu")
		(net "M_F_CPU0_SB_DQS_DP<7>")
	)
	(arc
		(start 388.944612 -221.42958)
		(mid 388.923522 -221.444684)
		(end 388.901432 -221.458282)
		(width 0.088646)
		(layer "In2.Cu")
		(net "M_F_CPU0_SB_DQS_DP<7>")
	)
	(arc
		(start 388.901432 -221.458282)
		(mid 388.714234 -221.508425)
		(end 388.527036 -221.458282)
		(width 0.088646)
		(layer "In2.Cu")
		(net "M_F_CPU0_SB_DQS_DP<7>")
	)
	(segment
		(start 431.625502 -217.539316)
		(end 432.071018 -217.984832)
		(width 0.20066)
		(layer "F.Cu")
		(net "M_F_CPU0_SB_DQS_DP<6>")
	)
	(segment
		(start 424.836082 -217.716608)
		(end 425.940982 -217.716608)
		(width 0.20066)
		(layer "F.Cu")
		(net "M_F_CPU0_SB_DQS_DP<6>")
	)
	(segment
		(start 432.916838 -217.716608)
		(end 433.484782 -217.716608)
		(width 0.20066)
		(layer "F.Cu")
		(net "M_F_CPU0_SB_DQS_DP<6>")
	)
	(segment
		(start 427.090332 -217.967814)
		(end 427.515274 -217.542872)
		(width 0.20066)
		(layer "F.Cu")
		(net "M_F_CPU0_SB_DQS_DP<6>")
	)
	(segment
		(start 428.051976 -217.284554)
		(end 428.363126 -217.284554)
		(width 0.20066)
		(layer "F.Cu")
		(net "M_F_CPU0_SB_DQS_DP<6>")
	)
	(segment
		(start 430.97196 -217.539316)
		(end 431.625502 -217.539316)
		(width 0.20066)
		(layer "F.Cu")
		(net "M_F_CPU0_SB_DQS_DP<6>")
	)
	(segment
		(start 382.605534 -230.086662)
		(end 382.605534 -230.622602)
		(width 0.20066)
		(layer "F.Cu")
		(net "M_F_CPU0_SB_DQS_DP<6>")
	)
	(segment
		(start 430.716944 -217.2843)
		(end 430.97196 -217.539316)
		(width 0.20066)
		(layer "F.Cu")
		(net "M_F_CPU0_SB_DQS_DP<6>")
	)
	(segment
		(start 425.940982 -217.716608)
		(end 426.534326 -217.716608)
		(width 0.20066)
		(layer "F.Cu")
		(net "M_F_CPU0_SB_DQS_DP<6>")
	)
	(segment
		(start 426.534326 -217.716608)
		(end 426.785532 -217.967814)
		(width 0.20066)
		(layer "F.Cu")
		(net "M_F_CPU0_SB_DQS_DP<6>")
	)
	(segment
		(start 432.071018 -217.984832)
		(end 432.648614 -217.984832)
		(width 0.20066)
		(layer "F.Cu")
		(net "M_F_CPU0_SB_DQS_DP<6>")
	)
	(segment
		(start 427.793658 -217.542872)
		(end 428.051976 -217.284554)
		(width 0.20066)
		(layer "F.Cu")
		(net "M_F_CPU0_SB_DQS_DP<6>")
	)
	(segment
		(start 427.515274 -217.542872)
		(end 427.793658 -217.542872)
		(width 0.20066)
		(layer "F.Cu")
		(net "M_F_CPU0_SB_DQS_DP<6>")
	)
	(segment
		(start 430.395126 -217.2843)
		(end 430.716944 -217.2843)
		(width 0.20066)
		(layer "F.Cu")
		(net "M_F_CPU0_SB_DQS_DP<6>")
	)
	(segment
		(start 428.367952 -217.284554)
		(end 428.375064 -217.291666)
		(width 0.1016)
		(layer "F.Cu")
		(net "M_F_CPU0_SB_DQS_DP<6>")
	)
	(segment
		(start 428.363126 -217.284554)
		(end 428.367952 -217.284554)
		(width 0.101854)
		(layer "F.Cu")
		(net "M_F_CPU0_SB_DQS_DP<6>")
	)
	(segment
		(start 432.648614 -217.984832)
		(end 432.916838 -217.716608)
		(width 0.20066)
		(layer "F.Cu")
		(net "M_F_CPU0_SB_DQS_DP<6>")
	)
	(segment
		(start 426.785532 -217.967814)
		(end 427.090332 -217.967814)
		(width 0.20066)
		(layer "F.Cu")
		(net "M_F_CPU0_SB_DQS_DP<6>")
	)
	(segment
		(start 428.375064 -217.291666)
		(end 430.38776 -217.291666)
		(width 0.1016)
		(layer "F.Cu")
		(net "M_F_CPU0_SB_DQS_DP<6>")
	)
	(segment
		(start 430.38776 -217.291666)
		(end 430.395126 -217.2843)
		(width 0.1016)
		(layer "F.Cu")
		(net "M_F_CPU0_SB_DQS_DP<6>")
	)
	(segment
		(start 415.6075 -217.276426)
		(end 415.20491 -217.276426)
		(width 0.18288)
		(layer "In2.Cu")
		(net "M_F_CPU0_SB_DQS_DP<6>")
	)
	(segment
		(start 384.091942 -229.649274)
		(end 383.963672 -229.649274)
		(width 0.088646)
		(layer "In2.Cu")
		(net "M_F_CPU0_SB_DQS_DP<6>")
	)
	(segment
		(start 409.370276 -216.438988)
		(end 409.052776 -216.756488)
		(width 0.18288)
		(layer "In2.Cu")
		(net "M_F_CPU0_SB_DQS_DP<6>")
	)
	(segment
		(start 411.492192 -216.7509)
		(end 410.088842 -216.7509)
		(width 0.18288)
		(layer "In2.Cu")
		(net "M_F_CPU0_SB_DQS_DP<6>")
	)
	(segment
		(start 417.426902 -217.128598)
		(end 417.398708 -217.156792)
		(width 0.16002)
		(layer "In2.Cu")
		(net "M_F_CPU0_SB_DQS_DP<6>")
	)
	(segment
		(start 383.517648 -229.66553)
		(end 383.426716 -229.73157)
		(width 0.088646)
		(layer "In2.Cu")
		(net "M_F_CPU0_SB_DQS_DP<6>")
	)
	(segment
		(start 412.309818 -217.568526)
		(end 411.492192 -216.7509)
		(width 0.18288)
		(layer "In2.Cu")
		(net "M_F_CPU0_SB_DQS_DP<6>")
	)
	(segment
		(start 412.994094 -217.251026)
		(end 412.676594 -217.568526)
		(width 0.18288)
		(layer "In2.Cu")
		(net "M_F_CPU0_SB_DQS_DP<6>")
	)
	(segment
		(start 421.162226 -217.524076)
		(end 420.930324 -217.292174)
		(width 0.18288)
		(layer "In2.Cu")
		(net "M_F_CPU0_SB_DQS_DP<6>")
	)
	(segment
		(start 420.27856 -217.5383)
		(end 419.765734 -217.5383)
		(width 0.18288)
		(layer "In2.Cu")
		(net "M_F_CPU0_SB_DQS_DP<6>")
	)
	(segment
		(start 417.65855 -216.89695)
		(end 417.426902 -217.128598)
		(width 0.18288)
		(layer "In2.Cu")
		(net "M_F_CPU0_SB_DQS_DP<6>")
	)
	(segment
		(start 415.20491 -217.276426)
		(end 414.918398 -217.562938)
		(width 0.18288)
		(layer "In2.Cu")
		(net "M_F_CPU0_SB_DQS_DP<6>")
	)
	(segment
		(start 423.076624 -218.239848)
		(end 422.937178 -218.100402)
		(width 0.18288)
		(layer "In2.Cu")
		(net "M_F_CPU0_SB_DQS_DP<6>")
	)
	(segment
		(start 424.836082 -217.716608)
		(end 424.58259 -217.9701)
		(width 0.18288)
		(layer "In2.Cu")
		(net "M_F_CPU0_SB_DQS_DP<6>")
	)
	(segment
		(start 420.930324 -217.292174)
		(end 420.524686 -217.292174)
		(width 0.18288)
		(layer "In2.Cu")
		(net "M_F_CPU0_SB_DQS_DP<6>")
	)
	(segment
		(start 388.13486 -228.16947)
		(end 387.656832 -228.647498)
		(width 0.088646)
		(layer "In2.Cu")
		(net "M_F_CPU0_SB_DQS_DP<6>")
	)
	(segment
		(start 422.908984 -218.072208)
		(end 422.892728 -218.072208)
		(width 0.16002)
		(layer "In2.Cu")
		(net "M_F_CPU0_SB_DQS_DP<6>")
	)
	(segment
		(start 384.211322 -229.592124)
		(end 384.202432 -229.597204)
		(width 0.088646)
		(layer "In2.Cu")
		(net "M_F_CPU0_SB_DQS_DP<6>")
	)
	(segment
		(start 407.600404 -216.08161)
		(end 405.963882 -216.08161)
		(width 0.18288)
		(layer "In2.Cu")
		(net "M_F_CPU0_SB_DQS_DP<6>")
	)
	(segment
		(start 387.534912 -228.75494)
		(end 387.534912 -228.754686)
		(width 0.088646)
		(layer "In2.Cu")
		(net "M_F_CPU0_SB_DQS_DP<6>")
	)
	(segment
		(start 419.348158 -217.120724)
		(end 419.124384 -216.89695)
		(width 0.18288)
		(layer "In2.Cu")
		(net "M_F_CPU0_SB_DQS_DP<6>")
	)
	(segment
		(start 422.892728 -218.072208)
		(end 422.754298 -217.933778)
		(width 0.16002)
		(layer "In2.Cu")
		(net "M_F_CPU0_SB_DQS_DP<6>")
	)
	(segment
		(start 417.244022 -217.311478)
		(end 417.215828 -217.339672)
		(width 0.16002)
		(layer "In2.Cu")
		(net "M_F_CPU0_SB_DQS_DP<6>")
	)
	(segment
		(start 399.788888 -221.50959)
		(end 399.309336 -221.50959)
		(width 0.18288)
		(layer "In2.Cu")
		(net "M_F_CPU0_SB_DQS_DP<6>")
	)
	(segment
		(start 404.533608 -216.76487)
		(end 399.788888 -221.50959)
		(width 0.18288)
		(layer "In2.Cu")
		(net "M_F_CPU0_SB_DQS_DP<6>")
	)
	(segment
		(start 419.531038 -217.303604)
		(end 419.514782 -217.303604)
		(width 0.16002)
		(layer "In2.Cu")
		(net "M_F_CPU0_SB_DQS_DP<6>")
	)
	(segment
		(start 422.754298 -217.933778)
		(end 422.754298 -217.917522)
		(width 0.16002)
		(layer "In2.Cu")
		(net "M_F_CPU0_SB_DQS_DP<6>")
	)
	(segment
		(start 423.337228 -218.239848)
		(end 423.076624 -218.239848)
		(width 0.18288)
		(layer "In2.Cu")
		(net "M_F_CPU0_SB_DQS_DP<6>")
	)
	(segment
		(start 413.71266 -217.562938)
		(end 413.400748 -217.251026)
		(width 0.18288)
		(layer "In2.Cu")
		(net "M_F_CPU0_SB_DQS_DP<6>")
	)
	(segment
		(start 412.676594 -217.568526)
		(end 412.309818 -217.568526)
		(width 0.18288)
		(layer "In2.Cu")
		(net "M_F_CPU0_SB_DQS_DP<6>")
	)
	(segment
		(start 383.812542 -229.605586)
		(end 383.662682 -229.605586)
		(width 0.088646)
		(layer "In2.Cu")
		(net "M_F_CPU0_SB_DQS_DP<6>")
	)
	(segment
		(start 419.376352 -217.165174)
		(end 419.376352 -217.148918)
		(width 0.16002)
		(layer "In2.Cu")
		(net "M_F_CPU0_SB_DQS_DP<6>")
	)
	(segment
		(start 405.592026 -216.453466)
		(end 405.563832 -216.48166)
		(width 0.16002)
		(layer "In2.Cu")
		(net "M_F_CPU0_SB_DQS_DP<6>")
	)
	(segment
		(start 417.260278 -217.311478)
		(end 417.244022 -217.311478)
		(width 0.16002)
		(layer "In2.Cu")
		(net "M_F_CPU0_SB_DQS_DP<6>")
	)
	(segment
		(start 419.559232 -217.331798)
		(end 419.531038 -217.303604)
		(width 0.16002)
		(layer "In2.Cu")
		(net "M_F_CPU0_SB_DQS_DP<6>")
	)
	(segment
		(start 405.563832 -216.48166)
		(end 405.280622 -216.76487)
		(width 0.18288)
		(layer "In2.Cu")
		(net "M_F_CPU0_SB_DQS_DP<6>")
	)
	(segment
		(start 399.309336 -221.50959)
		(end 393.549378 -227.269548)
		(width 0.18288)
		(layer "In2.Cu")
		(net "M_F_CPU0_SB_DQS_DP<6>")
	)
	(segment
		(start 423.988738 -217.9701)
		(end 423.337228 -218.239848)
		(width 0.18288)
		(layer "In2.Cu")
		(net "M_F_CPU0_SB_DQS_DP<6>")
	)
	(segment
		(start 422.937178 -218.100402)
		(end 422.908984 -218.072208)
		(width 0.16002)
		(layer "In2.Cu")
		(net "M_F_CPU0_SB_DQS_DP<6>")
	)
	(segment
		(start 419.514782 -217.303604)
		(end 419.376352 -217.165174)
		(width 0.16002)
		(layer "In2.Cu")
		(net "M_F_CPU0_SB_DQS_DP<6>")
	)
	(segment
		(start 405.280622 -216.76487)
		(end 404.533608 -216.76487)
		(width 0.18288)
		(layer "In2.Cu")
		(net "M_F_CPU0_SB_DQS_DP<6>")
	)
	(segment
		(start 415.869374 -217.5383)
		(end 415.6075 -217.276426)
		(width 0.18288)
		(layer "In2.Cu")
		(net "M_F_CPU0_SB_DQS_DP<6>")
	)
	(segment
		(start 405.963882 -216.08161)
		(end 405.774906 -216.270586)
		(width 0.18288)
		(layer "In2.Cu")
		(net "M_F_CPU0_SB_DQS_DP<6>")
	)
	(segment
		(start 393.549378 -227.269548)
		(end 388.950454 -227.269548)
		(width 0.18288)
		(layer "In2.Cu")
		(net "M_F_CPU0_SB_DQS_DP<6>")
	)
	(segment
		(start 384.12801 -229.639876)
		(end 384.091942 -229.649274)
		(width 0.088646)
		(layer "In2.Cu")
		(net "M_F_CPU0_SB_DQS_DP<6>")
	)
	(segment
		(start 419.376352 -217.148918)
		(end 419.348158 -217.120724)
		(width 0.16002)
		(layer "In2.Cu")
		(net "M_F_CPU0_SB_DQS_DP<6>")
	)
	(segment
		(start 417.398708 -217.173048)
		(end 417.260278 -217.311478)
		(width 0.16002)
		(layer "In2.Cu")
		(net "M_F_CPU0_SB_DQS_DP<6>")
	)
	(segment
		(start 422.754298 -217.917522)
		(end 422.726104 -217.889328)
		(width 0.16002)
		(layer "In2.Cu")
		(net "M_F_CPU0_SB_DQS_DP<6>")
	)
	(segment
		(start 419.765734 -217.5383)
		(end 419.559232 -217.331798)
		(width 0.18288)
		(layer "In2.Cu")
		(net "M_F_CPU0_SB_DQS_DP<6>")
	)
	(segment
		(start 405.746712 -216.29878)
		(end 405.746712 -216.315036)
		(width 0.16002)
		(layer "In2.Cu")
		(net "M_F_CPU0_SB_DQS_DP<6>")
	)
	(segment
		(start 383.118106 -230.086662)
		(end 382.605534 -230.086662)
		(width 0.088646)
		(layer "In2.Cu")
		(net "M_F_CPU0_SB_DQS_DP<6>")
	)
	(segment
		(start 424.58259 -217.9701)
		(end 423.988738 -217.9701)
		(width 0.18288)
		(layer "In2.Cu")
		(net "M_F_CPU0_SB_DQS_DP<6>")
	)
	(segment
		(start 383.175256 -230.029512)
		(end 383.118106 -230.086662)
		(width 0.088646)
		(layer "In2.Cu")
		(net "M_F_CPU0_SB_DQS_DP<6>")
	)
	(segment
		(start 405.774906 -216.270586)
		(end 405.746712 -216.29878)
		(width 0.16002)
		(layer "In2.Cu")
		(net "M_F_CPU0_SB_DQS_DP<6>")
	)
	(segment
		(start 414.918398 -217.562938)
		(end 413.71266 -217.562938)
		(width 0.18288)
		(layer "In2.Cu")
		(net "M_F_CPU0_SB_DQS_DP<6>")
	)
	(segment
		(start 405.746712 -216.315036)
		(end 405.608282 -216.453466)
		(width 0.16002)
		(layer "In2.Cu")
		(net "M_F_CPU0_SB_DQS_DP<6>")
	)
	(segment
		(start 422.360852 -217.524076)
		(end 421.162226 -217.524076)
		(width 0.18288)
		(layer "In2.Cu")
		(net "M_F_CPU0_SB_DQS_DP<6>")
	)
	(segment
		(start 410.088842 -216.7509)
		(end 409.77693 -216.438988)
		(width 0.18288)
		(layer "In2.Cu")
		(net "M_F_CPU0_SB_DQS_DP<6>")
	)
	(segment
		(start 388.13486 -228.085142)
		(end 388.13486 -228.16947)
		(width 0.088646)
		(layer "In2.Cu")
		(net "M_F_CPU0_SB_DQS_DP<6>")
	)
	(segment
		(start 419.124384 -216.89695)
		(end 417.65855 -216.89695)
		(width 0.18288)
		(layer "In2.Cu")
		(net "M_F_CPU0_SB_DQS_DP<6>")
	)
	(segment
		(start 420.524686 -217.292174)
		(end 420.27856 -217.5383)
		(width 0.18288)
		(layer "In2.Cu")
		(net "M_F_CPU0_SB_DQS_DP<6>")
	)
	(segment
		(start 383.963672 -229.649274)
		(end 383.812542 -229.605586)
		(width 0.088646)
		(layer "In2.Cu")
		(net "M_F_CPU0_SB_DQS_DP<6>")
	)
	(segment
		(start 388.950454 -227.269548)
		(end 388.13486 -228.085142)
		(width 0.18288)
		(layer "In2.Cu")
		(net "M_F_CPU0_SB_DQS_DP<6>")
	)
	(segment
		(start 384.202432 -229.597204)
		(end 384.12801 -229.639876)
		(width 0.088646)
		(layer "In2.Cu")
		(net "M_F_CPU0_SB_DQS_DP<6>")
	)
	(segment
		(start 405.608282 -216.453466)
		(end 405.592026 -216.453466)
		(width 0.16002)
		(layer "In2.Cu")
		(net "M_F_CPU0_SB_DQS_DP<6>")
	)
	(segment
		(start 409.052776 -216.756488)
		(end 408.275282 -216.756488)
		(width 0.18288)
		(layer "In2.Cu")
		(net "M_F_CPU0_SB_DQS_DP<6>")
	)
	(segment
		(start 413.400748 -217.251026)
		(end 412.994094 -217.251026)
		(width 0.18288)
		(layer "In2.Cu")
		(net "M_F_CPU0_SB_DQS_DP<6>")
	)
	(segment
		(start 422.726104 -217.889328)
		(end 422.360852 -217.524076)
		(width 0.18288)
		(layer "In2.Cu")
		(net "M_F_CPU0_SB_DQS_DP<6>")
	)
	(segment
		(start 383.662682 -229.605586)
		(end 383.517648 -229.66553)
		(width 0.088646)
		(layer "In2.Cu")
		(net "M_F_CPU0_SB_DQS_DP<6>")
	)
	(segment
		(start 417.215828 -217.339672)
		(end 417.0172 -217.5383)
		(width 0.18288)
		(layer "In2.Cu")
		(net "M_F_CPU0_SB_DQS_DP<6>")
	)
	(segment
		(start 409.77693 -216.438988)
		(end 409.370276 -216.438988)
		(width 0.18288)
		(layer "In2.Cu")
		(net "M_F_CPU0_SB_DQS_DP<6>")
	)
	(segment
		(start 408.275282 -216.756488)
		(end 407.600404 -216.08161)
		(width 0.18288)
		(layer "In2.Cu")
		(net "M_F_CPU0_SB_DQS_DP<6>")
	)
	(segment
		(start 383.358136 -229.762304)
		(end 383.349246 -229.767384)
		(width 0.088646)
		(layer "In2.Cu")
		(net "M_F_CPU0_SB_DQS_DP<6>")
	)
	(segment
		(start 417.0172 -217.5383)
		(end 415.869374 -217.5383)
		(width 0.18288)
		(layer "In2.Cu")
		(net "M_F_CPU0_SB_DQS_DP<6>")
	)
	(segment
		(start 417.398708 -217.156792)
		(end 417.398708 -217.173048)
		(width 0.16002)
		(layer "In2.Cu")
		(net "M_F_CPU0_SB_DQS_DP<6>")
	)
	(segment
		(start 384.389884 -229.26294)
		(end 384.389884 -229.272846)
		(width 0.088646)
		(layer "In2.Cu")
		(net "M_F_CPU0_SB_DQS_DP<6>")
	)
	(arc
		(start 386.177536 -228.783388)
		(mid 385.894834 -228.707612)
		(end 385.612132 -228.783388)
		(width 0.088646)
		(layer "In2.Cu")
		(net "M_F_CPU0_SB_DQS_DP<6>")
	)
	(arc
		(start 387.656832 -228.647498)
		(mid 387.597615 -228.703197)
		(end 387.534912 -228.75494)
		(width 0.088646)
		(layer "In2.Cu")
		(net "M_F_CPU0_SB_DQS_DP<6>")
	)
	(arc
		(start 385.612132 -228.783388)
		(mid 385.424934 -228.833531)
		(end 385.237736 -228.783388)
		(width 0.088646)
		(layer "In2.Cu")
		(net "M_F_CPU0_SB_DQS_DP<6>")
	)
	(arc
		(start 386.551932 -228.783388)
		(mid 386.364734 -228.833531)
		(end 386.177536 -228.783388)
		(width 0.088646)
		(layer "In2.Cu")
		(net "M_F_CPU0_SB_DQS_DP<6>")
	)
	(arc
		(start 383.426716 -229.73157)
		(mid 383.391655 -229.745215)
		(end 383.358136 -229.762304)
		(width 0.088646)
		(layer "In2.Cu")
		(net "M_F_CPU0_SB_DQS_DP<6>")
	)
	(arc
		(start 387.117336 -228.783388)
		(mid 386.834634 -228.707612)
		(end 386.551932 -228.783388)
		(width 0.088646)
		(layer "In2.Cu")
		(net "M_F_CPU0_SB_DQS_DP<6>")
	)
	(arc
		(start 384.389884 -229.272846)
		(mid 384.342205 -229.455746)
		(end 384.211322 -229.592124)
		(width 0.088646)
		(layer "In2.Cu")
		(net "M_F_CPU0_SB_DQS_DP<6>")
	)
	(arc
		(start 384.672332 -228.783388)
		(mid 384.467997 -228.985993)
		(end 384.389884 -229.26294)
		(width 0.088646)
		(layer "In2.Cu")
		(net "M_F_CPU0_SB_DQS_DP<6>")
	)
	(arc
		(start 387.534912 -228.754686)
		(mid 387.513822 -228.76979)
		(end 387.491732 -228.783388)
		(width 0.088646)
		(layer "In2.Cu")
		(net "M_F_CPU0_SB_DQS_DP<6>")
	)
	(arc
		(start 387.491732 -228.783388)
		(mid 387.304534 -228.833531)
		(end 387.117336 -228.783388)
		(width 0.088646)
		(layer "In2.Cu")
		(net "M_F_CPU0_SB_DQS_DP<6>")
	)
	(arc
		(start 385.237736 -228.783388)
		(mid 384.955034 -228.707612)
		(end 384.672332 -228.783388)
		(width 0.088646)
		(layer "In2.Cu")
		(net "M_F_CPU0_SB_DQS_DP<6>")
	)
	(arc
		(start 383.349246 -229.767384)
		(mid 383.233437 -229.879313)
		(end 383.175256 -230.029512)
		(width 0.088646)
		(layer "In2.Cu")
		(net "M_F_CPU0_SB_DQS_DP<6>")
	)
	(segment
		(start 428.367952 -226.634548)
		(end 428.375064 -226.64166)
		(width 0.1016)
		(layer "F.Cu")
		(net "M_F_CPU0_SB_DQS_DP<5>")
	)
	(segment
		(start 427.090332 -227.317808)
		(end 427.515274 -226.892866)
		(width 0.20066)
		(layer "F.Cu")
		(net "M_F_CPU0_SB_DQS_DP<5>")
	)
	(segment
		(start 424.836082 -227.066602)
		(end 425.940982 -227.066602)
		(width 0.20066)
		(layer "F.Cu")
		(net "M_F_CPU0_SB_DQS_DP<5>")
	)
	(segment
		(start 427.793658 -226.892866)
		(end 428.051976 -226.634548)
		(width 0.20066)
		(layer "F.Cu")
		(net "M_F_CPU0_SB_DQS_DP<5>")
	)
	(segment
		(start 428.375064 -226.64166)
		(end 430.38776 -226.64166)
		(width 0.1016)
		(layer "F.Cu")
		(net "M_F_CPU0_SB_DQS_DP<5>")
	)
	(segment
		(start 427.515274 -226.892866)
		(end 427.793658 -226.892866)
		(width 0.20066)
		(layer "F.Cu")
		(net "M_F_CPU0_SB_DQS_DP<5>")
	)
	(segment
		(start 379.31598 -237.947454)
		(end 379.316234 -237.947454)
		(width 0.20066)
		(layer "F.Cu")
		(net "M_F_CPU0_SB_DQS_DP<5>")
	)
	(segment
		(start 426.534326 -227.066602)
		(end 426.785532 -227.317808)
		(width 0.20066)
		(layer "F.Cu")
		(net "M_F_CPU0_SB_DQS_DP<5>")
	)
	(segment
		(start 428.363126 -226.634548)
		(end 428.367952 -226.634548)
		(width 0.101854)
		(layer "F.Cu")
		(net "M_F_CPU0_SB_DQS_DP<5>")
	)
	(segment
		(start 426.785532 -227.317808)
		(end 427.090332 -227.317808)
		(width 0.20066)
		(layer "F.Cu")
		(net "M_F_CPU0_SB_DQS_DP<5>")
	)
	(segment
		(start 425.940982 -227.066602)
		(end 426.534326 -227.066602)
		(width 0.20066)
		(layer "F.Cu")
		(net "M_F_CPU0_SB_DQS_DP<5>")
	)
	(segment
		(start 432.071018 -227.334826)
		(end 432.648614 -227.334826)
		(width 0.20066)
		(layer "F.Cu")
		(net "M_F_CPU0_SB_DQS_DP<5>")
	)
	(segment
		(start 432.648614 -227.334826)
		(end 432.916838 -227.066602)
		(width 0.20066)
		(layer "F.Cu")
		(net "M_F_CPU0_SB_DQS_DP<5>")
	)
	(segment
		(start 430.38776 -226.64166)
		(end 430.395126 -226.634294)
		(width 0.1016)
		(layer "F.Cu")
		(net "M_F_CPU0_SB_DQS_DP<5>")
	)
	(segment
		(start 430.395126 -226.634294)
		(end 430.716944 -226.634294)
		(width 0.20066)
		(layer "F.Cu")
		(net "M_F_CPU0_SB_DQS_DP<5>")
	)
	(segment
		(start 379.316234 -237.947454)
		(end 379.316234 -237.411514)
		(width 0.20066)
		(layer "F.Cu")
		(net "M_F_CPU0_SB_DQS_DP<5>")
	)
	(segment
		(start 430.716944 -226.634294)
		(end 430.97196 -226.88931)
		(width 0.20066)
		(layer "F.Cu")
		(net "M_F_CPU0_SB_DQS_DP<5>")
	)
	(segment
		(start 428.051976 -226.634548)
		(end 428.363126 -226.634548)
		(width 0.20066)
		(layer "F.Cu")
		(net "M_F_CPU0_SB_DQS_DP<5>")
	)
	(segment
		(start 430.97196 -226.88931)
		(end 431.625502 -226.88931)
		(width 0.20066)
		(layer "F.Cu")
		(net "M_F_CPU0_SB_DQS_DP<5>")
	)
	(segment
		(start 431.625502 -226.88931)
		(end 432.071018 -227.334826)
		(width 0.20066)
		(layer "F.Cu")
		(net "M_F_CPU0_SB_DQS_DP<5>")
	)
	(segment
		(start 432.916838 -227.066602)
		(end 433.484782 -227.066602)
		(width 0.20066)
		(layer "F.Cu")
		(net "M_F_CPU0_SB_DQS_DP<5>")
	)
	(segment
		(start 420.252144 -226.915218)
		(end 419.416992 -226.915218)
		(width 0.18288)
		(layer "In4.Cu")
		(net "M_F_CPU0_SB_DQS_DP<5>")
	)
	(segment
		(start 410.430726 -224.351088)
		(end 410.200856 -224.351088)
		(width 0.18288)
		(layer "In4.Cu")
		(net "M_F_CPU0_SB_DQS_DP<5>")
	)
	(segment
		(start 409.537408 -224.092516)
		(end 409.287472 -224.342452)
		(width 0.18288)
		(layer "In4.Cu")
		(net "M_F_CPU0_SB_DQS_DP<5>")
	)
	(segment
		(start 388.858506 -235.1405)
		(end 388.455916 -235.1405)
		(width 0.088646)
		(layer "In4.Cu")
		(net "M_F_CPU0_SB_DQS_DP<5>")
	)
	(segment
		(start 406.29205 -225.217482)
		(end 406.117298 -225.217482)
		(width 0.18288)
		(layer "In4.Cu")
		(net "M_F_CPU0_SB_DQS_DP<5>")
	)
	(segment
		(start 424.836082 -227.066602)
		(end 424.556428 -227.346256)
		(width 0.18288)
		(layer "In4.Cu")
		(net "M_F_CPU0_SB_DQS_DP<5>")
	)
	(segment
		(start 424.181778 -227.212398)
		(end 423.964354 -226.68992)
		(width 0.18288)
		(layer "In4.Cu")
		(net "M_F_CPU0_SB_DQS_DP<5>")
	)
	(segment
		(start 388.941564 -235.08081)
		(end 388.918196 -235.08081)
		(width 0.088646)
		(layer "In4.Cu")
		(net "M_F_CPU0_SB_DQS_DP<5>")
	)
	(segment
		(start 413.907224 -224.862898)
		(end 413.277812 -224.603056)
		(width 0.18288)
		(layer "In4.Cu")
		(net "M_F_CPU0_SB_DQS_DP<5>")
	)
	(segment
		(start 379.828806 -237.411514)
		(end 379.316234 -237.411514)
		(width 0.088646)
		(layer "In4.Cu")
		(net "M_F_CPU0_SB_DQS_DP<5>")
	)
	(segment
		(start 423.964354 -226.68992)
		(end 423.76725 -226.493578)
		(width 0.18288)
		(layer "In4.Cu")
		(net "M_F_CPU0_SB_DQS_DP<5>")
	)
	(segment
		(start 411.94609 -224.978722)
		(end 410.430726 -224.351088)
		(width 0.18288)
		(layer "In4.Cu")
		(net "M_F_CPU0_SB_DQS_DP<5>")
	)
	(segment
		(start 417.096702 -225.457766)
		(end 416.201606 -225.828606)
		(width 0.18288)
		(layer "In4.Cu")
		(net "M_F_CPU0_SB_DQS_DP<5>")
	)
	(segment
		(start 421.20693 -226.919536)
		(end 420.929816 -226.642422)
		(width 0.18288)
		(layer "In4.Cu")
		(net "M_F_CPU0_SB_DQS_DP<5>")
	)
	(segment
		(start 389.372602 -235.08081)
		(end 388.941564 -235.08081)
		(width 0.18288)
		(layer "In4.Cu")
		(net "M_F_CPU0_SB_DQS_DP<5>")
	)
	(segment
		(start 387.475222 -236.972856)
		(end 387.30428 -236.972856)
		(width 0.088646)
		(layer "In4.Cu")
		(net "M_F_CPU0_SB_DQS_DP<5>")
	)
	(segment
		(start 380.923292 -236.91596)
		(end 380.912878 -236.922056)
		(width 0.088646)
		(layer "In4.Cu")
		(net "M_F_CPU0_SB_DQS_DP<5>")
	)
	(segment
		(start 384.297682 -236.922056)
		(end 384.28295 -236.91342)
		(width 0.088646)
		(layer "In4.Cu")
		(net "M_F_CPU0_SB_DQS_DP<5>")
	)
	(segment
		(start 380.696724 -237.014258)
		(end 380.26213 -237.014258)
		(width 0.088646)
		(layer "In4.Cu")
		(net "M_F_CPU0_SB_DQS_DP<5>")
	)
	(segment
		(start 387.8961 -235.700316)
		(end 387.8961 -236.420914)
		(width 0.088646)
		(layer "In4.Cu")
		(net "M_F_CPU0_SB_DQS_DP<5>")
	)
	(segment
		(start 388.455916 -235.1405)
		(end 387.8961 -235.700316)
		(width 0.088646)
		(layer "In4.Cu")
		(net "M_F_CPU0_SB_DQS_DP<5>")
	)
	(segment
		(start 387.8961 -236.420914)
		(end 387.631686 -236.816392)
		(width 0.088646)
		(layer "In4.Cu")
		(net "M_F_CPU0_SB_DQS_DP<5>")
	)
	(segment
		(start 409.287472 -224.342452)
		(end 408.40533 -224.342452)
		(width 0.18288)
		(layer "In4.Cu")
		(net "M_F_CPU0_SB_DQS_DP<5>")
	)
	(segment
		(start 423.31005 -226.30384)
		(end 422.490646 -226.30384)
		(width 0.18288)
		(layer "In4.Cu")
		(net "M_F_CPU0_SB_DQS_DP<5>")
	)
	(segment
		(start 419.416992 -226.915218)
		(end 418.25545 -225.753676)
		(width 0.18288)
		(layer "In4.Cu")
		(net "M_F_CPU0_SB_DQS_DP<5>")
	)
	(segment
		(start 383.357882 -236.922056)
		(end 383.347468 -236.91596)
		(width 0.088646)
		(layer "In4.Cu")
		(net "M_F_CPU0_SB_DQS_DP<5>")
	)
	(segment
		(start 385.237736 -236.922056)
		(end 385.227322 -236.91596)
		(width 0.088646)
		(layer "In4.Cu")
		(net "M_F_CPU0_SB_DQS_DP<5>")
	)
	(segment
		(start 402.679154 -225.170746)
		(end 395.120876 -232.729024)
		(width 0.18288)
		(layer "In4.Cu")
		(net "M_F_CPU0_SB_DQS_DP<5>")
	)
	(segment
		(start 387.117082 -236.922056)
		(end 387.10235 -236.91342)
		(width 0.088646)
		(layer "In4.Cu")
		(net "M_F_CPU0_SB_DQS_DP<5>")
	)
	(segment
		(start 424.315636 -227.346256)
		(end 424.181778 -227.212398)
		(width 0.18288)
		(layer "In4.Cu")
		(net "M_F_CPU0_SB_DQS_DP<5>")
	)
	(segment
		(start 406.117298 -225.217482)
		(end 405.842216 -224.9424)
		(width 0.18288)
		(layer "In4.Cu")
		(net "M_F_CPU0_SB_DQS_DP<5>")
	)
	(segment
		(start 385.611878 -236.922056)
		(end 385.612132 -236.922056)
		(width 0.088646)
		(layer "In4.Cu")
		(net "M_F_CPU0_SB_DQS_DP<5>")
	)
	(segment
		(start 380.912878 -236.922056)
		(end 380.868936 -236.94771)
		(width 0.088646)
		(layer "In4.Cu")
		(net "M_F_CPU0_SB_DQS_DP<5>")
	)
	(segment
		(start 395.120876 -232.729024)
		(end 391.724388 -232.729024)
		(width 0.18288)
		(layer "In4.Cu")
		(net "M_F_CPU0_SB_DQS_DP<5>")
	)
	(segment
		(start 380.803404 -236.985556)
		(end 380.696724 -237.014258)
		(width 0.088646)
		(layer "In4.Cu")
		(net "M_F_CPU0_SB_DQS_DP<5>")
	)
	(segment
		(start 410.200856 -224.351088)
		(end 409.942284 -224.092516)
		(width 0.18288)
		(layer "In4.Cu")
		(net "M_F_CPU0_SB_DQS_DP<5>")
	)
	(segment
		(start 412.019496 -224.978722)
		(end 411.94609 -224.978722)
		(width 0.18288)
		(layer "In4.Cu")
		(net "M_F_CPU0_SB_DQS_DP<5>")
	)
	(segment
		(start 422.490646 -226.30384)
		(end 421.87495 -226.919536)
		(width 0.18288)
		(layer "In4.Cu")
		(net "M_F_CPU0_SB_DQS_DP<5>")
	)
	(segment
		(start 409.942284 -224.092516)
		(end 409.537408 -224.092516)
		(width 0.18288)
		(layer "In4.Cu")
		(net "M_F_CPU0_SB_DQS_DP<5>")
	)
	(segment
		(start 416.201606 -225.828606)
		(end 414.872932 -225.828606)
		(width 0.18288)
		(layer "In4.Cu")
		(net "M_F_CPU0_SB_DQS_DP<5>")
	)
	(segment
		(start 386.177282 -236.922056)
		(end 386.16255 -236.91342)
		(width 0.088646)
		(layer "In4.Cu")
		(net "M_F_CPU0_SB_DQS_DP<5>")
	)
	(segment
		(start 417.540694 -225.457766)
		(end 417.096702 -225.457766)
		(width 0.18288)
		(layer "In4.Cu")
		(net "M_F_CPU0_SB_DQS_DP<5>")
	)
	(segment
		(start 418.25545 -225.753676)
		(end 417.540694 -225.457766)
		(width 0.18288)
		(layer "In4.Cu")
		(net "M_F_CPU0_SB_DQS_DP<5>")
	)
	(segment
		(start 405.208994 -225.170746)
		(end 402.679154 -225.170746)
		(width 0.18288)
		(layer "In4.Cu")
		(net "M_F_CPU0_SB_DQS_DP<5>")
	)
	(segment
		(start 405.43734 -224.9424)
		(end 405.208994 -225.170746)
		(width 0.18288)
		(layer "In4.Cu")
		(net "M_F_CPU0_SB_DQS_DP<5>")
	)
	(segment
		(start 391.724388 -232.729024)
		(end 389.372602 -235.08081)
		(width 0.18288)
		(layer "In4.Cu")
		(net "M_F_CPU0_SB_DQS_DP<5>")
	)
	(segment
		(start 412.926276 -224.603056)
		(end 412.019496 -224.978722)
		(width 0.18288)
		(layer "In4.Cu")
		(net "M_F_CPU0_SB_DQS_DP<5>")
	)
	(segment
		(start 420.52494 -226.642422)
		(end 420.252144 -226.915218)
		(width 0.18288)
		(layer "In4.Cu")
		(net "M_F_CPU0_SB_DQS_DP<5>")
	)
	(segment
		(start 413.277812 -224.603056)
		(end 412.926276 -224.603056)
		(width 0.18288)
		(layer "In4.Cu")
		(net "M_F_CPU0_SB_DQS_DP<5>")
	)
	(segment
		(start 414.872932 -225.828606)
		(end 413.907224 -224.862898)
		(width 0.18288)
		(layer "In4.Cu")
		(net "M_F_CPU0_SB_DQS_DP<5>")
	)
	(segment
		(start 380.868936 -236.94771)
		(end 380.803404 -236.985556)
		(width 0.088646)
		(layer "In4.Cu")
		(net "M_F_CPU0_SB_DQS_DP<5>")
	)
	(segment
		(start 388.918196 -235.08081)
		(end 388.858506 -235.1405)
		(width 0.088646)
		(layer "In4.Cu")
		(net "M_F_CPU0_SB_DQS_DP<5>")
	)
	(segment
		(start 380.068836 -237.087156)
		(end 380.059946 -237.092236)
		(width 0.088646)
		(layer "In4.Cu")
		(net "M_F_CPU0_SB_DQS_DP<5>")
	)
	(segment
		(start 421.87495 -226.919536)
		(end 421.20693 -226.919536)
		(width 0.18288)
		(layer "In4.Cu")
		(net "M_F_CPU0_SB_DQS_DP<5>")
	)
	(segment
		(start 379.885956 -237.354364)
		(end 379.828806 -237.411514)
		(width 0.088646)
		(layer "In4.Cu")
		(net "M_F_CPU0_SB_DQS_DP<5>")
	)
	(segment
		(start 423.76725 -226.493578)
		(end 423.31005 -226.30384)
		(width 0.18288)
		(layer "In4.Cu")
		(net "M_F_CPU0_SB_DQS_DP<5>")
	)
	(segment
		(start 420.929816 -226.642422)
		(end 420.52494 -226.642422)
		(width 0.18288)
		(layer "In4.Cu")
		(net "M_F_CPU0_SB_DQS_DP<5>")
	)
	(segment
		(start 408.40533 -224.342452)
		(end 406.29205 -225.217482)
		(width 0.18288)
		(layer "In4.Cu")
		(net "M_F_CPU0_SB_DQS_DP<5>")
	)
	(segment
		(start 405.842216 -224.9424)
		(end 405.43734 -224.9424)
		(width 0.18288)
		(layer "In4.Cu")
		(net "M_F_CPU0_SB_DQS_DP<5>")
	)
	(segment
		(start 387.631686 -236.816392)
		(end 387.475222 -236.972856)
		(width 0.088646)
		(layer "In4.Cu")
		(net "M_F_CPU0_SB_DQS_DP<5>")
	)
	(segment
		(start 424.556428 -227.346256)
		(end 424.315636 -227.346256)
		(width 0.18288)
		(layer "In4.Cu")
		(net "M_F_CPU0_SB_DQS_DP<5>")
	)
	(arc
		(start 387.10235 -236.91342)
		(mid 386.825875 -236.8461)
		(end 386.551678 -236.922056)
		(width 0.088646)
		(layer "In4.Cu")
		(net "M_F_CPU0_SB_DQS_DP<5>")
	)
	(arc
		(start 380.169166 -237.03915)
		(mid 380.144461 -237.052017)
		(end 380.118874 -237.063026)
		(width 0.088646)
		(layer "In4.Cu")
		(net "M_F_CPU0_SB_DQS_DP<5>")
	)
	(arc
		(start 383.347468 -236.91596)
		(mid 383.06929 -236.846237)
		(end 382.792732 -236.922056)
		(width 0.088646)
		(layer "In4.Cu")
		(net "M_F_CPU0_SB_DQS_DP<5>")
	)
	(arc
		(start 381.478536 -236.922056)
		(mid 381.201723 -236.846186)
		(end 380.923292 -236.91596)
		(width 0.088646)
		(layer "In4.Cu")
		(net "M_F_CPU0_SB_DQS_DP<5>")
	)
	(arc
		(start 386.551678 -236.922056)
		(mid 386.36448 -236.972233)
		(end 386.177282 -236.922056)
		(width 0.088646)
		(layer "In4.Cu")
		(net "M_F_CPU0_SB_DQS_DP<5>")
	)
	(arc
		(start 382.792732 -236.922056)
		(mid 382.605534 -236.972233)
		(end 382.418336 -236.922056)
		(width 0.088646)
		(layer "In4.Cu")
		(net "M_F_CPU0_SB_DQS_DP<5>")
	)
	(arc
		(start 380.26213 -237.014258)
		(mid 380.214016 -237.020614)
		(end 380.169166 -237.03915)
		(width 0.088646)
		(layer "In4.Cu")
		(net "M_F_CPU0_SB_DQS_DP<5>")
	)
	(arc
		(start 383.732278 -236.922056)
		(mid 383.54508 -236.972233)
		(end 383.357882 -236.922056)
		(width 0.088646)
		(layer "In4.Cu")
		(net "M_F_CPU0_SB_DQS_DP<5>")
	)
	(arc
		(start 384.672078 -236.922056)
		(mid 384.48488 -236.972233)
		(end 384.297682 -236.922056)
		(width 0.088646)
		(layer "In4.Cu")
		(net "M_F_CPU0_SB_DQS_DP<5>")
	)
	(arc
		(start 381.852932 -236.922056)
		(mid 381.665734 -236.972233)
		(end 381.478536 -236.922056)
		(width 0.088646)
		(layer "In4.Cu")
		(net "M_F_CPU0_SB_DQS_DP<5>")
	)
	(arc
		(start 384.28295 -236.91342)
		(mid 384.006475 -236.8461)
		(end 383.732278 -236.922056)
		(width 0.088646)
		(layer "In4.Cu")
		(net "M_F_CPU0_SB_DQS_DP<5>")
	)
	(arc
		(start 382.418336 -236.922056)
		(mid 382.135634 -236.84628)
		(end 381.852932 -236.922056)
		(width 0.088646)
		(layer "In4.Cu")
		(net "M_F_CPU0_SB_DQS_DP<5>")
	)
	(arc
		(start 385.227322 -236.91596)
		(mid 384.94889 -236.846114)
		(end 384.672078 -236.922056)
		(width 0.088646)
		(layer "In4.Cu")
		(net "M_F_CPU0_SB_DQS_DP<5>")
	)
	(arc
		(start 380.118874 -237.063026)
		(mid 380.093405 -237.074159)
		(end 380.068836 -237.087156)
		(width 0.088646)
		(layer "In4.Cu")
		(net "M_F_CPU0_SB_DQS_DP<5>")
	)
	(arc
		(start 380.059946 -237.092236)
		(mid 379.944137 -237.204165)
		(end 379.885956 -237.354364)
		(width 0.088646)
		(layer "In4.Cu")
		(net "M_F_CPU0_SB_DQS_DP<5>")
	)
	(arc
		(start 386.16255 -236.91342)
		(mid 385.886075 -236.8461)
		(end 385.611878 -236.922056)
		(width 0.088646)
		(layer "In4.Cu")
		(net "M_F_CPU0_SB_DQS_DP<5>")
	)
	(arc
		(start 385.612132 -236.922056)
		(mid 385.424934 -236.972233)
		(end 385.237736 -236.922056)
		(width 0.088646)
		(layer "In4.Cu")
		(net "M_F_CPU0_SB_DQS_DP<5>")
	)
	(arc
		(start 387.30428 -236.972856)
		(mid 387.207346 -236.959758)
		(end 387.117082 -236.922056)
		(width 0.088646)
		(layer "In4.Cu")
		(net "M_F_CPU0_SB_DQS_DP<5>")
	)
	(segment
		(start 424.836082 -236.416596)
		(end 425.940982 -236.416596)
		(width 0.20066)
		(layer "F.Cu")
		(net "M_F_CPU0_SB_DQS_DP<4>")
	)
	(segment
		(start 428.375064 -235.991654)
		(end 430.38776 -235.991654)
		(width 0.1016)
		(layer "F.Cu")
		(net "M_F_CPU0_SB_DQS_DP<4>")
	)
	(segment
		(start 427.090332 -236.667802)
		(end 427.515274 -236.24286)
		(width 0.20066)
		(layer "F.Cu")
		(net "M_F_CPU0_SB_DQS_DP<4>")
	)
	(segment
		(start 426.534326 -236.416596)
		(end 426.785532 -236.667802)
		(width 0.20066)
		(layer "F.Cu")
		(net "M_F_CPU0_SB_DQS_DP<4>")
	)
	(segment
		(start 430.38776 -235.991654)
		(end 430.395126 -235.984288)
		(width 0.1016)
		(layer "F.Cu")
		(net "M_F_CPU0_SB_DQS_DP<4>")
	)
	(segment
		(start 432.648614 -236.68482)
		(end 432.916838 -236.416596)
		(width 0.20066)
		(layer "F.Cu")
		(net "M_F_CPU0_SB_DQS_DP<4>")
	)
	(segment
		(start 432.071018 -236.68482)
		(end 432.648614 -236.68482)
		(width 0.20066)
		(layer "F.Cu")
		(net "M_F_CPU0_SB_DQS_DP<4>")
	)
	(segment
		(start 427.515274 -236.24286)
		(end 427.793658 -236.24286)
		(width 0.20066)
		(layer "F.Cu")
		(net "M_F_CPU0_SB_DQS_DP<4>")
	)
	(segment
		(start 428.367952 -235.984542)
		(end 428.375064 -235.991654)
		(width 0.1016)
		(layer "F.Cu")
		(net "M_F_CPU0_SB_DQS_DP<4>")
	)
	(segment
		(start 428.363126 -235.984542)
		(end 428.367952 -235.984542)
		(width 0.101854)
		(layer "F.Cu")
		(net "M_F_CPU0_SB_DQS_DP<4>")
	)
	(segment
		(start 428.051976 -235.984542)
		(end 428.363126 -235.984542)
		(width 0.20066)
		(layer "F.Cu")
		(net "M_F_CPU0_SB_DQS_DP<4>")
	)
	(segment
		(start 430.97196 -236.239304)
		(end 431.625502 -236.239304)
		(width 0.20066)
		(layer "F.Cu")
		(net "M_F_CPU0_SB_DQS_DP<4>")
	)
	(segment
		(start 430.395126 -235.984288)
		(end 430.716944 -235.984288)
		(width 0.20066)
		(layer "F.Cu")
		(net "M_F_CPU0_SB_DQS_DP<4>")
	)
	(segment
		(start 425.940982 -236.416596)
		(end 426.534326 -236.416596)
		(width 0.20066)
		(layer "F.Cu")
		(net "M_F_CPU0_SB_DQS_DP<4>")
	)
	(segment
		(start 432.916838 -236.416596)
		(end 433.484782 -236.416596)
		(width 0.20066)
		(layer "F.Cu")
		(net "M_F_CPU0_SB_DQS_DP<4>")
	)
	(segment
		(start 431.625502 -236.239304)
		(end 432.071018 -236.68482)
		(width 0.20066)
		(layer "F.Cu")
		(net "M_F_CPU0_SB_DQS_DP<4>")
	)
	(segment
		(start 430.716944 -235.984288)
		(end 430.97196 -236.239304)
		(width 0.20066)
		(layer "F.Cu")
		(net "M_F_CPU0_SB_DQS_DP<4>")
	)
	(segment
		(start 427.793658 -236.24286)
		(end 428.051976 -235.984542)
		(width 0.20066)
		(layer "F.Cu")
		(net "M_F_CPU0_SB_DQS_DP<4>")
	)
	(segment
		(start 426.785532 -236.667802)
		(end 427.090332 -236.667802)
		(width 0.20066)
		(layer "F.Cu")
		(net "M_F_CPU0_SB_DQS_DP<4>")
	)
	(segment
		(start 382.605534 -240.389156)
		(end 382.605534 -239.85347)
		(width 0.20066)
		(layer "F.Cu")
		(net "M_F_CPU0_SB_DQS_DP<4>")
	)
	(segment
		(start 382.605534 -239.85347)
		(end 382.60528 -239.853216)
		(width 0.20066)
		(layer "F.Cu")
		(net "M_F_CPU0_SB_DQS_DP<4>")
	)
	(segment
		(start 407.73604 -236.684312)
		(end 407.707846 -236.656118)
		(width 0.16002)
		(layer "In2.Cu")
		(net "M_F_CPU0_SB_DQS_DP<4>")
	)
	(segment
		(start 411.859984 -234.832398)
		(end 411.711394 -234.980988)
		(width 0.18288)
		(layer "In2.Cu")
		(net "M_F_CPU0_SB_DQS_DP<4>")
	)
	(segment
		(start 420.289228 -236.242606)
		(end 420.017956 -236.242606)
		(width 0.18288)
		(layer "In2.Cu")
		(net "M_F_CPU0_SB_DQS_DP<4>")
	)
	(segment
		(start 417.284662 -235.991146)
		(end 417.268406 -235.991146)
		(width 0.16002)
		(layer "In2.Cu")
		(net "M_F_CPU0_SB_DQS_DP<4>")
	)
	(segment
		(start 415.141664 -234.77982)
		(end 414.560766 -234.539536)
		(width 0.18288)
		(layer "In2.Cu")
		(net "M_F_CPU0_SB_DQS_DP<4>")
	)
	(segment
		(start 407.91892 -236.867192)
		(end 407.890726 -236.838998)
		(width 0.16002)
		(layer "In2.Cu")
		(net "M_F_CPU0_SB_DQS_DP<4>")
	)
	(segment
		(start 387.499606 -240.527332)
		(end 387.23062 -240.258346)
		(width 0.088646)
		(layer "In2.Cu")
		(net "M_F_CPU0_SB_DQS_DP<4>")
	)
	(segment
		(start 387.23062 -240.258346)
		(end 387.22173 -240.248948)
		(width 0.088646)
		(layer "In2.Cu")
		(net "M_F_CPU0_SB_DQS_DP<4>")
	)
	(segment
		(start 417.645342 -235.61421)
		(end 417.451286 -235.808266)
		(width 0.18288)
		(layer "In2.Cu")
		(net "M_F_CPU0_SB_DQS_DP<4>")
	)
	(segment
		(start 387.125464 -240.182654)
		(end 387.124448 -240.182146)
		(width 0.088646)
		(layer "In2.Cu")
		(net "M_F_CPU0_SB_DQS_DP<4>")
	)
	(segment
		(start 417.423092 -235.83646)
		(end 417.423092 -235.852716)
		(width 0.16002)
		(layer "In2.Cu")
		(net "M_F_CPU0_SB_DQS_DP<4>")
	)
	(segment
		(start 417.423092 -235.852716)
		(end 417.284662 -235.991146)
		(width 0.16002)
		(layer "In2.Cu")
		(net "M_F_CPU0_SB_DQS_DP<4>")
	)
	(segment
		(start 411.50032 -235.192062)
		(end 411.186376 -235.506006)
		(width 0.18288)
		(layer "In2.Cu")
		(net "M_F_CPU0_SB_DQS_DP<4>")
	)
	(segment
		(start 423.189654 -236.873796)
		(end 422.960292 -236.778546)
		(width 0.18288)
		(layer "In2.Cu")
		(net "M_F_CPU0_SB_DQS_DP<4>")
	)
	(segment
		(start 410.165296 -235.506006)
		(end 409.722828 -235.94822)
		(width 0.18288)
		(layer "In2.Cu")
		(net "M_F_CPU0_SB_DQS_DP<4>")
	)
	(segment
		(start 408.967432 -236.261148)
		(end 408.278838 -236.949996)
		(width 0.18288)
		(layer "In2.Cu")
		(net "M_F_CPU0_SB_DQS_DP<4>")
	)
	(segment
		(start 411.711394 -234.980988)
		(end 411.6832 -235.009182)
		(width 0.16002)
		(layer "In2.Cu")
		(net "M_F_CPU0_SB_DQS_DP<4>")
	)
	(segment
		(start 407.73604 -236.700568)
		(end 407.73604 -236.684312)
		(width 0.16002)
		(layer "In2.Cu")
		(net "M_F_CPU0_SB_DQS_DP<4>")
	)
	(segment
		(start 383.751836 -239.363758)
		(end 383.426716 -239.498124)
		(width 0.088646)
		(layer "In2.Cu")
		(net "M_F_CPU0_SB_DQS_DP<4>")
	)
	(segment
		(start 419.1889 -235.61421)
		(end 417.645342 -235.61421)
		(width 0.18288)
		(layer "In2.Cu")
		(net "M_F_CPU0_SB_DQS_DP<4>")
	)
	(segment
		(start 383.175256 -239.796066)
		(end 383.118106 -239.853216)
		(width 0.088646)
		(layer "In2.Cu")
		(net "M_F_CPU0_SB_DQS_DP<4>")
	)
	(segment
		(start 383.118106 -239.853216)
		(end 382.60528 -239.853216)
		(width 0.088646)
		(layer "In2.Cu")
		(net "M_F_CPU0_SB_DQS_DP<4>")
	)
	(segment
		(start 417.268406 -235.991146)
		(end 417.240212 -236.01934)
		(width 0.16002)
		(layer "In2.Cu")
		(net "M_F_CPU0_SB_DQS_DP<4>")
	)
	(segment
		(start 411.6832 -235.009182)
		(end 411.6832 -235.02493)
		(width 0.16002)
		(layer "In2.Cu")
		(net "M_F_CPU0_SB_DQS_DP<4>")
	)
	(segment
		(start 417.142422 -236.11713)
		(end 416.47872 -236.11713)
		(width 0.18288)
		(layer "In2.Cu")
		(net "M_F_CPU0_SB_DQS_DP<4>")
	)
	(segment
		(start 404.597108 -237.216188)
		(end 401.345654 -240.467642)
		(width 0.18288)
		(layer "In2.Cu")
		(net "M_F_CPU0_SB_DQS_DP<4>")
	)
	(segment
		(start 411.6832 -235.02493)
		(end 411.544262 -235.163868)
		(width 0.16002)
		(layer "In2.Cu")
		(net "M_F_CPU0_SB_DQS_DP<4>")
	)
	(segment
		(start 407.87447 -236.838998)
		(end 407.73604 -236.700568)
		(width 0.16002)
		(layer "In2.Cu")
		(net "M_F_CPU0_SB_DQS_DP<4>")
	)
	(segment
		(start 388.399274 -240.527332)
		(end 387.499606 -240.527332)
		(width 0.088646)
		(layer "In2.Cu")
		(net "M_F_CPU0_SB_DQS_DP<4>")
	)
	(segment
		(start 407.521918 -236.47019)
		(end 405.958802 -236.47019)
		(width 0.18288)
		(layer "In2.Cu")
		(net "M_F_CPU0_SB_DQS_DP<4>")
	)
	(segment
		(start 424.606974 -236.64291)
		(end 424.173396 -236.64291)
		(width 0.18288)
		(layer "In2.Cu")
		(net "M_F_CPU0_SB_DQS_DP<4>")
	)
	(segment
		(start 412.495492 -234.832398)
		(end 411.859984 -234.832398)
		(width 0.18288)
		(layer "In2.Cu")
		(net "M_F_CPU0_SB_DQS_DP<4>")
	)
	(segment
		(start 420.017956 -236.242606)
		(end 419.675056 -236.100366)
		(width 0.18288)
		(layer "In2.Cu")
		(net "M_F_CPU0_SB_DQS_DP<4>")
	)
	(segment
		(start 416.47872 -236.11713)
		(end 415.141664 -234.77982)
		(width 0.18288)
		(layer "In2.Cu")
		(net "M_F_CPU0_SB_DQS_DP<4>")
	)
	(segment
		(start 411.186376 -235.506006)
		(end 410.165296 -235.506006)
		(width 0.18288)
		(layer "In2.Cu")
		(net "M_F_CPU0_SB_DQS_DP<4>")
	)
	(segment
		(start 405.648922 -236.78007)
		(end 404.597108 -237.216188)
		(width 0.18288)
		(layer "In2.Cu")
		(net "M_F_CPU0_SB_DQS_DP<4>")
	)
	(segment
		(start 387.175502 -240.21288)
		(end 387.130798 -240.18621)
		(width 0.088646)
		(layer "In2.Cu")
		(net "M_F_CPU0_SB_DQS_DP<4>")
	)
	(segment
		(start 411.528514 -235.163868)
		(end 411.50032 -235.192062)
		(width 0.16002)
		(layer "In2.Cu")
		(net "M_F_CPU0_SB_DQS_DP<4>")
	)
	(segment
		(start 417.451286 -235.808266)
		(end 417.423092 -235.83646)
		(width 0.16002)
		(layer "In2.Cu")
		(net "M_F_CPU0_SB_DQS_DP<4>")
	)
	(segment
		(start 384.217164 -239.355122)
		(end 384.202432 -239.363758)
		(width 0.088646)
		(layer "In2.Cu")
		(net "M_F_CPU0_SB_DQS_DP<4>")
	)
	(segment
		(start 385.237482 -240.177574)
		(end 385.228592 -240.172494)
		(width 0.088646)
		(layer "In2.Cu")
		(net "M_F_CPU0_SB_DQS_DP<4>")
	)
	(segment
		(start 383.828036 -239.363758)
		(end 383.751836 -239.363758)
		(width 0.088646)
		(layer "In2.Cu")
		(net "M_F_CPU0_SB_DQS_DP<4>")
	)
	(segment
		(start 385.05003 -239.853216)
		(end 385.05003 -239.837722)
		(width 0.088646)
		(layer "In2.Cu")
		(net "M_F_CPU0_SB_DQS_DP<4>")
	)
	(segment
		(start 387.124448 -240.182146)
		(end 387.123178 -240.181384)
		(width 0.088646)
		(layer "In2.Cu")
		(net "M_F_CPU0_SB_DQS_DP<4>")
	)
	(segment
		(start 387.11251 -240.17478)
		(end 387.10235 -240.168938)
		(width 0.088646)
		(layer "In2.Cu")
		(net "M_F_CPU0_SB_DQS_DP<4>")
	)
	(segment
		(start 387.129274 -240.185194)
		(end 387.126734 -240.18367)
		(width 0.088646)
		(layer "In2.Cu")
		(net "M_F_CPU0_SB_DQS_DP<4>")
	)
	(segment
		(start 420.939468 -235.990892)
		(end 420.540942 -235.990892)
		(width 0.18288)
		(layer "In2.Cu")
		(net "M_F_CPU0_SB_DQS_DP<4>")
	)
	(segment
		(start 414.560766 -234.539536)
		(end 413.628586 -234.539536)
		(width 0.18288)
		(layer "In2.Cu")
		(net "M_F_CPU0_SB_DQS_DP<4>")
	)
	(segment
		(start 387.122416 -240.180876)
		(end 387.11251 -240.17478)
		(width 0.088646)
		(layer "In2.Cu")
		(net "M_F_CPU0_SB_DQS_DP<4>")
	)
	(segment
		(start 387.123178 -240.181384)
		(end 387.122416 -240.180876)
		(width 0.088646)
		(layer "In2.Cu")
		(net "M_F_CPU0_SB_DQS_DP<4>")
	)
	(segment
		(start 387.126734 -240.18367)
		(end 387.125464 -240.182654)
		(width 0.088646)
		(layer "In2.Cu")
		(net "M_F_CPU0_SB_DQS_DP<4>")
	)
	(segment
		(start 388.458964 -240.467642)
		(end 388.399274 -240.527332)
		(width 0.088646)
		(layer "In2.Cu")
		(net "M_F_CPU0_SB_DQS_DP<4>")
	)
	(segment
		(start 419.675056 -236.100366)
		(end 419.1889 -235.61421)
		(width 0.18288)
		(layer "In2.Cu")
		(net "M_F_CPU0_SB_DQS_DP<4>")
	)
	(segment
		(start 408.001724 -236.949996)
		(end 407.91892 -236.867192)
		(width 0.18288)
		(layer "In2.Cu")
		(net "M_F_CPU0_SB_DQS_DP<4>")
	)
	(segment
		(start 422.668192 -236.486446)
		(end 422.210484 -236.296962)
		(width 0.18288)
		(layer "In2.Cu")
		(net "M_F_CPU0_SB_DQS_DP<4>")
	)
	(segment
		(start 422.960292 -236.778546)
		(end 422.668192 -236.486446)
		(width 0.18288)
		(layer "In2.Cu")
		(net "M_F_CPU0_SB_DQS_DP<4>")
	)
	(segment
		(start 424.173396 -236.64291)
		(end 423.615612 -236.873796)
		(width 0.18288)
		(layer "In2.Cu")
		(net "M_F_CPU0_SB_DQS_DP<4>")
	)
	(segment
		(start 421.245538 -236.296962)
		(end 420.939468 -235.990892)
		(width 0.18288)
		(layer "In2.Cu")
		(net "M_F_CPU0_SB_DQS_DP<4>")
	)
	(segment
		(start 386.177282 -240.177574)
		(end 386.16255 -240.168938)
		(width 0.088646)
		(layer "In2.Cu")
		(net "M_F_CPU0_SB_DQS_DP<4>")
	)
	(segment
		(start 387.130798 -240.18621)
		(end 387.129274 -240.185194)
		(width 0.088646)
		(layer "In2.Cu")
		(net "M_F_CPU0_SB_DQS_DP<4>")
	)
	(segment
		(start 405.958802 -236.47019)
		(end 405.648922 -236.78007)
		(width 0.18288)
		(layer "In2.Cu")
		(net "M_F_CPU0_SB_DQS_DP<4>")
	)
	(segment
		(start 424.836082 -236.416596)
		(end 424.606974 -236.64291)
		(width 0.18288)
		(layer "In2.Cu")
		(net "M_F_CPU0_SB_DQS_DP<4>")
	)
	(segment
		(start 411.544262 -235.163868)
		(end 411.528514 -235.163868)
		(width 0.16002)
		(layer "In2.Cu")
		(net "M_F_CPU0_SB_DQS_DP<4>")
	)
	(segment
		(start 408.278838 -236.949996)
		(end 408.001724 -236.949996)
		(width 0.18288)
		(layer "In2.Cu")
		(net "M_F_CPU0_SB_DQS_DP<4>")
	)
	(segment
		(start 412.88716 -234.28071)
		(end 412.693866 -234.474004)
		(width 0.18288)
		(layer "In2.Cu")
		(net "M_F_CPU0_SB_DQS_DP<4>")
	)
	(segment
		(start 412.693866 -234.474004)
		(end 412.693866 -234.634024)
		(width 0.18288)
		(layer "In2.Cu")
		(net "M_F_CPU0_SB_DQS_DP<4>")
	)
	(segment
		(start 417.240212 -236.01934)
		(end 417.142422 -236.11713)
		(width 0.18288)
		(layer "In2.Cu")
		(net "M_F_CPU0_SB_DQS_DP<4>")
	)
	(segment
		(start 401.345654 -240.467642)
		(end 388.458964 -240.467642)
		(width 0.18288)
		(layer "In2.Cu")
		(net "M_F_CPU0_SB_DQS_DP<4>")
	)
	(segment
		(start 412.693866 -234.634024)
		(end 412.495492 -234.832398)
		(width 0.18288)
		(layer "In2.Cu")
		(net "M_F_CPU0_SB_DQS_DP<4>")
	)
	(segment
		(start 422.210484 -236.296962)
		(end 421.245538 -236.296962)
		(width 0.18288)
		(layer "In2.Cu")
		(net "M_F_CPU0_SB_DQS_DP<4>")
	)
	(segment
		(start 409.722828 -235.94822)
		(end 408.967432 -236.261148)
		(width 0.18288)
		(layer "In2.Cu")
		(net "M_F_CPU0_SB_DQS_DP<4>")
	)
	(segment
		(start 413.36976 -234.28071)
		(end 412.88716 -234.28071)
		(width 0.18288)
		(layer "In2.Cu")
		(net "M_F_CPU0_SB_DQS_DP<4>")
	)
	(segment
		(start 423.615612 -236.873796)
		(end 423.189654 -236.873796)
		(width 0.18288)
		(layer "In2.Cu")
		(net "M_F_CPU0_SB_DQS_DP<4>")
	)
	(segment
		(start 413.628586 -234.539536)
		(end 413.36976 -234.28071)
		(width 0.18288)
		(layer "In2.Cu")
		(net "M_F_CPU0_SB_DQS_DP<4>")
	)
	(segment
		(start 420.540942 -235.990892)
		(end 420.289228 -236.242606)
		(width 0.18288)
		(layer "In2.Cu")
		(net "M_F_CPU0_SB_DQS_DP<4>")
	)
	(segment
		(start 383.358136 -239.528858)
		(end 383.349246 -239.533938)
		(width 0.088646)
		(layer "In2.Cu")
		(net "M_F_CPU0_SB_DQS_DP<4>")
	)
	(segment
		(start 407.707846 -236.656118)
		(end 407.521918 -236.47019)
		(width 0.18288)
		(layer "In2.Cu")
		(net "M_F_CPU0_SB_DQS_DP<4>")
	)
	(segment
		(start 407.890726 -236.838998)
		(end 407.87447 -236.838998)
		(width 0.16002)
		(layer "In2.Cu")
		(net "M_F_CPU0_SB_DQS_DP<4>")
	)
	(arc
		(start 385.05003 -239.837722)
		(mid 384.97066 -239.563988)
		(end 384.767836 -239.363758)
		(width 0.088646)
		(layer "In2.Cu")
		(net "M_F_CPU0_SB_DQS_DP<4>")
	)
	(arc
		(start 386.16255 -240.168938)
		(mid 385.886109 -240.101772)
		(end 385.611878 -240.177574)
		(width 0.088646)
		(layer "In2.Cu")
		(net "M_F_CPU0_SB_DQS_DP<4>")
	)
	(arc
		(start 383.863088 -239.381538)
		(mid 383.845328 -239.373108)
		(end 383.828036 -239.363758)
		(width 0.088646)
		(layer "In2.Cu")
		(net "M_F_CPU0_SB_DQS_DP<4>")
	)
	(arc
		(start 387.22173 -240.248948)
		(mid 387.19972 -240.229498)
		(end 387.175502 -240.21288)
		(width 0.088646)
		(layer "In2.Cu")
		(net "M_F_CPU0_SB_DQS_DP<4>")
	)
	(arc
		(start 387.10235 -240.168938)
		(mid 386.825909 -240.101772)
		(end 386.551678 -240.177574)
		(width 0.088646)
		(layer "In2.Cu")
		(net "M_F_CPU0_SB_DQS_DP<4>")
	)
	(arc
		(start 384.038094 -239.413288)
		(mid 383.948675 -239.407964)
		(end 383.863088 -239.381538)
		(width 0.088646)
		(layer "In2.Cu")
		(net "M_F_CPU0_SB_DQS_DP<4>")
	)
	(arc
		(start 384.202432 -239.363758)
		(mid 384.12314 -239.398075)
		(end 384.038094 -239.413288)
		(width 0.088646)
		(layer "In2.Cu")
		(net "M_F_CPU0_SB_DQS_DP<4>")
	)
	(arc
		(start 385.611878 -240.177574)
		(mid 385.42468 -240.227717)
		(end 385.237482 -240.177574)
		(width 0.088646)
		(layer "In2.Cu")
		(net "M_F_CPU0_SB_DQS_DP<4>")
	)
	(arc
		(start 385.228592 -240.172494)
		(mid 385.097678 -240.036134)
		(end 385.05003 -239.853216)
		(width 0.088646)
		(layer "In2.Cu")
		(net "M_F_CPU0_SB_DQS_DP<4>")
	)
	(arc
		(start 383.349246 -239.533938)
		(mid 383.233437 -239.645867)
		(end 383.175256 -239.796066)
		(width 0.088646)
		(layer "In2.Cu")
		(net "M_F_CPU0_SB_DQS_DP<4>")
	)
	(arc
		(start 386.551678 -240.177574)
		(mid 386.36448 -240.227717)
		(end 386.177282 -240.177574)
		(width 0.088646)
		(layer "In2.Cu")
		(net "M_F_CPU0_SB_DQS_DP<4>")
	)
	(arc
		(start 384.767836 -239.363758)
		(mid 384.493637 -239.287923)
		(end 384.217164 -239.355122)
		(width 0.088646)
		(layer "In2.Cu")
		(net "M_F_CPU0_SB_DQS_DP<4>")
	)
	(arc
		(start 383.426716 -239.498124)
		(mid 383.391655 -239.511769)
		(end 383.358136 -239.528858)
		(width 0.088646)
		(layer "In2.Cu")
		(net "M_F_CPU0_SB_DQS_DP<4>")
	)
	(segment
		(start 422.430194 -200.716642)
		(end 422.670732 -200.476104)
		(width 0.20066)
		(layer "F.Cu")
		(net "M_F_CPU0_SB_DQS_DP<3>")
	)
	(segment
		(start 424.788076 -201.141838)
		(end 426.945298 -201.141838)
		(width 0.1016)
		(layer "F.Cu")
		(net "M_F_CPU0_SB_DQS_DP<3>")
	)
	(segment
		(start 421.840914 -200.716642)
		(end 422.430194 -200.716642)
		(width 0.20066)
		(layer "F.Cu")
		(net "M_F_CPU0_SB_DQS_DP<3>")
	)
	(segment
		(start 424.622722 -201.141838)
		(end 424.762168 -201.141838)
		(width 0.20066)
		(layer "F.Cu")
		(net "M_F_CPU0_SB_DQS_DP<3>")
	)
	(segment
		(start 428.836074 -200.716642)
		(end 429.384714 -200.716642)
		(width 0.20066)
		(layer "F.Cu")
		(net "M_F_CPU0_SB_DQS_DP<3>")
	)
	(segment
		(start 426.951394 -201.147934)
		(end 427.274736 -201.147934)
		(width 0.20066)
		(layer "F.Cu")
		(net "M_F_CPU0_SB_DQS_DP<3>")
	)
	(segment
		(start 428.3583 -200.434956)
		(end 428.554388 -200.434956)
		(width 0.20066)
		(layer "F.Cu")
		(net "M_F_CPU0_SB_DQS_DP<3>")
	)
	(segment
		(start 427.57725 -200.84542)
		(end 427.947836 -200.84542)
		(width 0.20066)
		(layer "F.Cu")
		(net "M_F_CPU0_SB_DQS_DP<3>")
	)
	(segment
		(start 427.274736 -201.147934)
		(end 427.57725 -200.84542)
		(width 0.20066)
		(layer "F.Cu")
		(net "M_F_CPU0_SB_DQS_DP<3>")
	)
	(segment
		(start 420.736014 -200.716642)
		(end 421.840914 -200.716642)
		(width 0.20066)
		(layer "F.Cu")
		(net "M_F_CPU0_SB_DQS_DP<3>")
	)
	(segment
		(start 427.947836 -200.84542)
		(end 428.3583 -200.434956)
		(width 0.20066)
		(layer "F.Cu")
		(net "M_F_CPU0_SB_DQS_DP<3>")
	)
	(segment
		(start 424.371516 -200.890632)
		(end 424.622722 -201.141838)
		(width 0.20066)
		(layer "F.Cu")
		(net "M_F_CPU0_SB_DQS_DP<3>")
	)
	(segment
		(start 428.554388 -200.434956)
		(end 428.836074 -200.716642)
		(width 0.20066)
		(layer "F.Cu")
		(net "M_F_CPU0_SB_DQS_DP<3>")
	)
	(segment
		(start 378.37618 -228.1809)
		(end 378.376434 -228.180646)
		(width 0.20066)
		(layer "F.Cu")
		(net "M_F_CPU0_SB_DQS_DP<3>")
	)
	(segment
		(start 423.271188 -200.476104)
		(end 423.685716 -200.890632)
		(width 0.20066)
		(layer "F.Cu")
		(net "M_F_CPU0_SB_DQS_DP<3>")
	)
	(segment
		(start 423.685716 -200.890632)
		(end 424.371516 -200.890632)
		(width 0.20066)
		(layer "F.Cu")
		(net "M_F_CPU0_SB_DQS_DP<3>")
	)
	(segment
		(start 426.945298 -201.141838)
		(end 426.951394 -201.147934)
		(width 0.1016)
		(layer "F.Cu")
		(net "M_F_CPU0_SB_DQS_DP<3>")
	)
	(segment
		(start 424.762168 -201.141838)
		(end 424.788076 -201.141838)
		(width 0.101854)
		(layer "F.Cu")
		(net "M_F_CPU0_SB_DQS_DP<3>")
	)
	(segment
		(start 422.670732 -200.476104)
		(end 423.271188 -200.476104)
		(width 0.20066)
		(layer "F.Cu")
		(net "M_F_CPU0_SB_DQS_DP<3>")
	)
	(segment
		(start 378.376434 -228.180646)
		(end 378.376434 -227.64496)
		(width 0.20066)
		(layer "F.Cu")
		(net "M_F_CPU0_SB_DQS_DP<3>")
	)
	(segment
		(start 381.014732 -227.317046)
		(end 381.008636 -227.320602)
		(width 0.088646)
		(layer "In4.Cu")
		(net "M_F_CPU0_SB_DQS_DP<3>")
	)
	(segment
		(start 382.700784 -222.761556)
		(end 382.700784 -222.780098)
		(width 0.088646)
		(layer "In4.Cu")
		(net "M_F_CPU0_SB_DQS_DP<3>")
	)
	(segment
		(start 381.948436 -225.69297)
		(end 381.947674 -225.693478)
		(width 0.088646)
		(layer "In4.Cu")
		(net "M_F_CPU0_SB_DQS_DP<3>")
	)
	(segment
		(start 382.230884 -225.193352)
		(end 382.230884 -225.2218)
		(width 0.088646)
		(layer "In4.Cu")
		(net "M_F_CPU0_SB_DQS_DP<3>")
	)
	(segment
		(start 418.522404 -200.096374)
		(end 417.976304 -200.096374)
		(width 0.18288)
		(layer "In4.Cu")
		(net "M_F_CPU0_SB_DQS_DP<3>")
	)
	(segment
		(start 400.233134 -205.988666)
		(end 398.18564 -210.931506)
		(width 0.18288)
		(layer "In4.Cu")
		(net "M_F_CPU0_SB_DQS_DP<3>")
	)
	(segment
		(start 383.358136 -221.623382)
		(end 383.349246 -221.628462)
		(width 0.088646)
		(layer "In4.Cu")
		(net "M_F_CPU0_SB_DQS_DP<3>")
	)
	(segment
		(start 384.767836 -220.809566)
		(end 384.758946 -220.814646)
		(width 0.088646)
		(layer "In4.Cu")
		(net "M_F_CPU0_SB_DQS_DP<3>")
	)
	(segment
		(start 381.947674 -224.065592)
		(end 381.939546 -224.070164)
		(width 0.088646)
		(layer "In4.Cu")
		(net "M_F_CPU0_SB_DQS_DP<3>")
	)
	(segment
		(start 405.154384 -199.812402)
		(end 402.760434 -202.206352)
		(width 0.18288)
		(layer "In4.Cu")
		(net "M_F_CPU0_SB_DQS_DP<3>")
	)
	(segment
		(start 381.948436 -224.065084)
		(end 381.947674 -224.065592)
		(width 0.088646)
		(layer "In4.Cu")
		(net "M_F_CPU0_SB_DQS_DP<3>")
	)
	(segment
		(start 412.697168 -199.961246)
		(end 412.149798 -199.413876)
		(width 0.18288)
		(layer "In4.Cu")
		(net "M_F_CPU0_SB_DQS_DP<3>")
	)
	(segment
		(start 387.69671 -220.744034)
		(end 387.673342 -220.744034)
		(width 0.088646)
		(layer "In4.Cu")
		(net "M_F_CPU0_SB_DQS_DP<3>")
	)
	(segment
		(start 378.189236 -227.320602)
		(end 378.180346 -227.325682)
		(width 0.088646)
		(layer "In4.Cu")
		(net "M_F_CPU0_SB_DQS_DP<3>")
	)
	(segment
		(start 379.518164 -227.329238)
		(end 379.503432 -227.320602)
		(width 0.088646)
		(layer "In4.Cu")
		(net "M_F_CPU0_SB_DQS_DP<3>")
	)
	(segment
		(start 387.613652 -220.684344)
		(end 387.031738 -220.684344)
		(width 0.088646)
		(layer "In4.Cu")
		(net "M_F_CPU0_SB_DQS_DP<3>")
	)
	(segment
		(start 380.457964 -227.329238)
		(end 380.443232 -227.320602)
		(width 0.088646)
		(layer "In4.Cu")
		(net "M_F_CPU0_SB_DQS_DP<3>")
	)
	(segment
		(start 420.736014 -200.716642)
		(end 420.44493 -200.425558)
		(width 0.18288)
		(layer "In4.Cu")
		(net "M_F_CPU0_SB_DQS_DP<3>")
	)
	(segment
		(start 398.18564 -210.931506)
		(end 388.372858 -220.744034)
		(width 0.18288)
		(layer "In4.Cu")
		(net "M_F_CPU0_SB_DQS_DP<3>")
	)
	(segment
		(start 378.06376 -227.64496)
		(end 378.376434 -227.64496)
		(width 0.088646)
		(layer "In4.Cu")
		(net "M_F_CPU0_SB_DQS_DP<3>")
	)
	(segment
		(start 420.44493 -200.425558)
		(end 419.922706 -200.425558)
		(width 0.18288)
		(layer "In4.Cu")
		(net "M_F_CPU0_SB_DQS_DP<3>")
	)
	(segment
		(start 384.298444 -221.622874)
		(end 384.297682 -221.623382)
		(width 0.088646)
		(layer "In4.Cu")
		(net "M_F_CPU0_SB_DQS_DP<3>")
	)
	(segment
		(start 381.939546 -224.70872)
		(end 381.948436 -224.7138)
		(width 0.088646)
		(layer "In4.Cu")
		(net "M_F_CPU0_SB_DQS_DP<3>")
	)
	(segment
		(start 387.673342 -220.744034)
		(end 387.613652 -220.684344)
		(width 0.088646)
		(layer "In4.Cu")
		(net "M_F_CPU0_SB_DQS_DP<3>")
	)
	(segment
		(start 384.297682 -221.623382)
		(end 384.287268 -221.629478)
		(width 0.088646)
		(layer "In4.Cu")
		(net "M_F_CPU0_SB_DQS_DP<3>")
	)
	(segment
		(start 382.894332 -222.433642)
		(end 382.888236 -222.437198)
		(width 0.088646)
		(layer "In4.Cu")
		(net "M_F_CPU0_SB_DQS_DP<3>")
	)
	(segment
		(start 414.125156 -199.4027)
		(end 413.56661 -199.961246)
		(width 0.18288)
		(layer "In4.Cu")
		(net "M_F_CPU0_SB_DQS_DP<3>")
	)
	(segment
		(start 417.851844 -199.971914)
		(end 415.08934 -199.971914)
		(width 0.18288)
		(layer "In4.Cu")
		(net "M_F_CPU0_SB_DQS_DP<3>")
	)
	(segment
		(start 417.976304 -200.096374)
		(end 417.851844 -199.971914)
		(width 0.18288)
		(layer "In4.Cu")
		(net "M_F_CPU0_SB_DQS_DP<3>")
	)
	(segment
		(start 414.520126 -199.4027)
		(end 414.125156 -199.4027)
		(width 0.18288)
		(layer "In4.Cu")
		(net "M_F_CPU0_SB_DQS_DP<3>")
	)
	(segment
		(start 381.477774 -226.507294)
		(end 381.469646 -226.511866)
		(width 0.088646)
		(layer "In4.Cu")
		(net "M_F_CPU0_SB_DQS_DP<3>")
	)
	(segment
		(start 402.760434 -202.206352)
		(end 400.233134 -205.988666)
		(width 0.18288)
		(layer "In4.Cu")
		(net "M_F_CPU0_SB_DQS_DP<3>")
	)
	(segment
		(start 412.149798 -199.413876)
		(end 409.16479 -199.413876)
		(width 0.18288)
		(layer "In4.Cu")
		(net "M_F_CPU0_SB_DQS_DP<3>")
	)
	(segment
		(start 413.56661 -199.961246)
		(end 412.697168 -199.961246)
		(width 0.18288)
		(layer "In4.Cu")
		(net "M_F_CPU0_SB_DQS_DP<3>")
	)
	(segment
		(start 387.031738 -220.684344)
		(end 386.957316 -220.758766)
		(width 0.088646)
		(layer "In4.Cu")
		(net "M_F_CPU0_SB_DQS_DP<3>")
	)
	(segment
		(start 381.478536 -226.506786)
		(end 381.477774 -226.507294)
		(width 0.088646)
		(layer "In4.Cu")
		(net "M_F_CPU0_SB_DQS_DP<3>")
	)
	(segment
		(start 386.957316 -220.758766)
		(end 386.834634 -220.758766)
		(width 0.088646)
		(layer "In4.Cu")
		(net "M_F_CPU0_SB_DQS_DP<3>")
	)
	(segment
		(start 384.303778 -221.619826)
		(end 384.298444 -221.622874)
		(width 0.088646)
		(layer "In4.Cu")
		(net "M_F_CPU0_SB_DQS_DP<3>")
	)
	(segment
		(start 409.16479 -199.413876)
		(end 408.766264 -199.812402)
		(width 0.18288)
		(layer "In4.Cu")
		(net "M_F_CPU0_SB_DQS_DP<3>")
	)
	(segment
		(start 419.469062 -199.971914)
		(end 418.646864 -199.971914)
		(width 0.18288)
		(layer "In4.Cu")
		(net "M_F_CPU0_SB_DQS_DP<3>")
	)
	(segment
		(start 418.646864 -199.971914)
		(end 418.522404 -200.096374)
		(width 0.18288)
		(layer "In4.Cu")
		(net "M_F_CPU0_SB_DQS_DP<3>")
	)
	(segment
		(start 408.766264 -199.812402)
		(end 405.154384 -199.812402)
		(width 0.18288)
		(layer "In4.Cu")
		(net "M_F_CPU0_SB_DQS_DP<3>")
	)
	(segment
		(start 381.760984 -226.017328)
		(end 381.760984 -226.027234)
		(width 0.088646)
		(layer "In4.Cu")
		(net "M_F_CPU0_SB_DQS_DP<3>")
	)
	(segment
		(start 382.418336 -223.251268)
		(end 382.409446 -223.256348)
		(width 0.088646)
		(layer "In4.Cu")
		(net "M_F_CPU0_SB_DQS_DP<3>")
	)
	(segment
		(start 419.922706 -200.425558)
		(end 419.469062 -199.971914)
		(width 0.18288)
		(layer "In4.Cu")
		(net "M_F_CPU0_SB_DQS_DP<3>")
	)
	(segment
		(start 381.947674 -225.693478)
		(end 381.939546 -225.69805)
		(width 0.088646)
		(layer "In4.Cu")
		(net "M_F_CPU0_SB_DQS_DP<3>")
	)
	(segment
		(start 388.372858 -220.744034)
		(end 387.69671 -220.744034)
		(width 0.18288)
		(layer "In4.Cu")
		(net "M_F_CPU0_SB_DQS_DP<3>")
	)
	(segment
		(start 415.08934 -199.971914)
		(end 414.520126 -199.4027)
		(width 0.18288)
		(layer "In4.Cu")
		(net "M_F_CPU0_SB_DQS_DP<3>")
	)
	(segment
		(start 382.230884 -223.575626)
		(end 382.230884 -223.585532)
		(width 0.088646)
		(layer "In4.Cu")
		(net "M_F_CPU0_SB_DQS_DP<3>")
	)
	(segment
		(start 378.006356 -227.587556)
		(end 378.06376 -227.64496)
		(width 0.088646)
		(layer "In4.Cu")
		(net "M_F_CPU0_SB_DQS_DP<3>")
	)
	(segment
		(start 382.888236 -222.437198)
		(end 382.879346 -222.442278)
		(width 0.088646)
		(layer "In4.Cu")
		(net "M_F_CPU0_SB_DQS_DP<3>")
	)
	(arc
		(start 383.349246 -221.628462)
		(mid 383.218332 -221.764822)
		(end 383.170684 -221.94774)
		(width 0.088646)
		(layer "In4.Cu")
		(net "M_F_CPU0_SB_DQS_DP<3>")
	)
	(arc
		(start 385.707636 -220.809566)
		(mid 385.424934 -220.885308)
		(end 385.142232 -220.809566)
		(width 0.088646)
		(layer "In4.Cu")
		(net "M_F_CPU0_SB_DQS_DP<3>")
	)
	(arc
		(start 381.939546 -224.070164)
		(mid 381.760949 -224.389442)
		(end 381.939546 -224.70872)
		(width 0.088646)
		(layer "In4.Cu")
		(net "M_F_CPU0_SB_DQS_DP<3>")
	)
	(arc
		(start 384.758946 -220.814646)
		(mid 384.628032 -220.951006)
		(end 384.580384 -221.133924)
		(width 0.088646)
		(layer "In4.Cu")
		(net "M_F_CPU0_SB_DQS_DP<3>")
	)
	(arc
		(start 381.008636 -227.320602)
		(mid 380.734437 -227.396437)
		(end 380.457964 -227.329238)
		(width 0.088646)
		(layer "In4.Cu")
		(net "M_F_CPU0_SB_DQS_DP<3>")
	)
	(arc
		(start 383.170684 -221.94774)
		(mid 383.096768 -222.227242)
		(end 382.894332 -222.433642)
		(width 0.088646)
		(layer "In4.Cu")
		(net "M_F_CPU0_SB_DQS_DP<3>")
	)
	(arc
		(start 381.939546 -225.69805)
		(mid 381.808632 -225.83441)
		(end 381.760984 -226.017328)
		(width 0.088646)
		(layer "In4.Cu")
		(net "M_F_CPU0_SB_DQS_DP<3>")
	)
	(arc
		(start 384.580384 -221.133924)
		(mid 384.506393 -221.41349)
		(end 384.303778 -221.619826)
		(width 0.088646)
		(layer "In4.Cu")
		(net "M_F_CPU0_SB_DQS_DP<3>")
	)
	(arc
		(start 384.287268 -221.629478)
		(mid 384.00909 -221.699201)
		(end 383.732532 -221.623382)
		(width 0.088646)
		(layer "In4.Cu")
		(net "M_F_CPU0_SB_DQS_DP<3>")
	)
	(arc
		(start 382.409446 -223.256348)
		(mid 382.278532 -223.392708)
		(end 382.230884 -223.575626)
		(width 0.088646)
		(layer "In4.Cu")
		(net "M_F_CPU0_SB_DQS_DP<3>")
	)
	(arc
		(start 381.291084 -226.831144)
		(mid 381.217168 -227.110646)
		(end 381.014732 -227.317046)
		(width 0.088646)
		(layer "In4.Cu")
		(net "M_F_CPU0_SB_DQS_DP<3>")
	)
	(arc
		(start 386.082032 -220.809566)
		(mid 385.894834 -220.759423)
		(end 385.707636 -220.809566)
		(width 0.088646)
		(layer "In4.Cu")
		(net "M_F_CPU0_SB_DQS_DP<3>")
	)
	(arc
		(start 385.142232 -220.809566)
		(mid 384.955034 -220.759423)
		(end 384.767836 -220.809566)
		(width 0.088646)
		(layer "In4.Cu")
		(net "M_F_CPU0_SB_DQS_DP<3>")
	)
	(arc
		(start 379.129036 -227.320602)
		(mid 378.846334 -227.396378)
		(end 378.563632 -227.320602)
		(width 0.088646)
		(layer "In4.Cu")
		(net "M_F_CPU0_SB_DQS_DP<3>")
	)
	(arc
		(start 382.230884 -223.585532)
		(mid 382.152773 -223.862481)
		(end 381.948436 -224.065084)
		(width 0.088646)
		(layer "In4.Cu")
		(net "M_F_CPU0_SB_DQS_DP<3>")
	)
	(arc
		(start 386.647436 -220.809566)
		(mid 386.364734 -220.885308)
		(end 386.082032 -220.809566)
		(width 0.088646)
		(layer "In4.Cu")
		(net "M_F_CPU0_SB_DQS_DP<3>")
	)
	(arc
		(start 380.443232 -227.320602)
		(mid 380.256034 -227.270459)
		(end 380.068836 -227.320602)
		(width 0.088646)
		(layer "In4.Cu")
		(net "M_F_CPU0_SB_DQS_DP<3>")
	)
	(arc
		(start 382.879346 -222.442278)
		(mid 382.748432 -222.578638)
		(end 382.700784 -222.761556)
		(width 0.088646)
		(layer "In4.Cu")
		(net "M_F_CPU0_SB_DQS_DP<3>")
	)
	(arc
		(start 380.068836 -227.320602)
		(mid 379.794637 -227.396437)
		(end 379.518164 -227.329238)
		(width 0.088646)
		(layer "In4.Cu")
		(net "M_F_CPU0_SB_DQS_DP<3>")
	)
	(arc
		(start 381.948436 -224.7138)
		(mid 382.152771 -224.916405)
		(end 382.230884 -225.193352)
		(width 0.088646)
		(layer "In4.Cu")
		(net "M_F_CPU0_SB_DQS_DP<3>")
	)
	(arc
		(start 381.469646 -226.511866)
		(mid 381.338732 -226.648226)
		(end 381.291084 -226.831144)
		(width 0.088646)
		(layer "In4.Cu")
		(net "M_F_CPU0_SB_DQS_DP<3>")
	)
	(arc
		(start 383.732532 -221.623382)
		(mid 383.545334 -221.573239)
		(end 383.358136 -221.623382)
		(width 0.088646)
		(layer "In4.Cu")
		(net "M_F_CPU0_SB_DQS_DP<3>")
	)
	(arc
		(start 378.180346 -227.325682)
		(mid 378.088847 -227.404981)
		(end 378.027438 -227.509324)
		(width 0.088646)
		(layer "In4.Cu")
		(net "M_F_CPU0_SB_DQS_DP<3>")
	)
	(arc
		(start 382.700784 -222.780098)
		(mid 382.620622 -223.052287)
		(end 382.418336 -223.251268)
		(width 0.088646)
		(layer "In4.Cu")
		(net "M_F_CPU0_SB_DQS_DP<3>")
	)
	(arc
		(start 379.503432 -227.320602)
		(mid 379.316234 -227.270459)
		(end 379.129036 -227.320602)
		(width 0.088646)
		(layer "In4.Cu")
		(net "M_F_CPU0_SB_DQS_DP<3>")
	)
	(arc
		(start 382.230884 -225.2218)
		(mid 382.150722 -225.493989)
		(end 381.948436 -225.69297)
		(width 0.088646)
		(layer "In4.Cu")
		(net "M_F_CPU0_SB_DQS_DP<3>")
	)
	(arc
		(start 378.563632 -227.320602)
		(mid 378.376434 -227.270459)
		(end 378.189236 -227.320602)
		(width 0.088646)
		(layer "In4.Cu")
		(net "M_F_CPU0_SB_DQS_DP<3>")
	)
	(arc
		(start 378.027438 -227.509324)
		(mid 378.01477 -227.547867)
		(end 378.006356 -227.587556)
		(width 0.088646)
		(layer "In4.Cu")
		(net "M_F_CPU0_SB_DQS_DP<3>")
	)
	(arc
		(start 381.760984 -226.027234)
		(mid 381.682873 -226.304183)
		(end 381.478536 -226.506786)
		(width 0.088646)
		(layer "In4.Cu")
		(net "M_F_CPU0_SB_DQS_DP<3>")
	)
	(arc
		(start 386.834634 -220.758766)
		(mid 386.737695 -220.771856)
		(end 386.647436 -220.809566)
		(width 0.088646)
		(layer "In4.Cu")
		(net "M_F_CPU0_SB_DQS_DP<3>")
	)
	(segment
		(start 421.840914 -210.066636)
		(end 422.430194 -210.066636)
		(width 0.20066)
		(layer "F.Cu")
		(net "M_F_CPU0_SB_DQS_DP<2>")
	)
	(segment
		(start 428.3583 -209.78495)
		(end 428.554388 -209.78495)
		(width 0.20066)
		(layer "F.Cu")
		(net "M_F_CPU0_SB_DQS_DP<2>")
	)
	(segment
		(start 427.274736 -210.497928)
		(end 427.57725 -210.195414)
		(width 0.20066)
		(layer "F.Cu")
		(net "M_F_CPU0_SB_DQS_DP<2>")
	)
	(segment
		(start 427.57725 -210.195414)
		(end 427.947836 -210.195414)
		(width 0.20066)
		(layer "F.Cu")
		(net "M_F_CPU0_SB_DQS_DP<2>")
	)
	(segment
		(start 424.371516 -210.240626)
		(end 424.622722 -210.491832)
		(width 0.20066)
		(layer "F.Cu")
		(net "M_F_CPU0_SB_DQS_DP<2>")
	)
	(segment
		(start 422.670732 -209.826098)
		(end 423.271188 -209.826098)
		(width 0.20066)
		(layer "F.Cu")
		(net "M_F_CPU0_SB_DQS_DP<2>")
	)
	(segment
		(start 428.554388 -209.78495)
		(end 428.836074 -210.066636)
		(width 0.20066)
		(layer "F.Cu")
		(net "M_F_CPU0_SB_DQS_DP<2>")
	)
	(segment
		(start 424.622722 -210.491832)
		(end 424.762168 -210.491832)
		(width 0.20066)
		(layer "F.Cu")
		(net "M_F_CPU0_SB_DQS_DP<2>")
	)
	(segment
		(start 424.788076 -210.491832)
		(end 426.945298 -210.491832)
		(width 0.1016)
		(layer "F.Cu")
		(net "M_F_CPU0_SB_DQS_DP<2>")
	)
	(segment
		(start 427.947836 -210.195414)
		(end 428.3583 -209.78495)
		(width 0.20066)
		(layer "F.Cu")
		(net "M_F_CPU0_SB_DQS_DP<2>")
	)
	(segment
		(start 426.951394 -210.497928)
		(end 427.274736 -210.497928)
		(width 0.20066)
		(layer "F.Cu")
		(net "M_F_CPU0_SB_DQS_DP<2>")
	)
	(segment
		(start 384.015234 -223.297496)
		(end 384.015234 -222.761556)
		(width 0.20066)
		(layer "F.Cu")
		(net "M_F_CPU0_SB_DQS_DP<2>")
	)
	(segment
		(start 422.430194 -210.066636)
		(end 422.670732 -209.826098)
		(width 0.20066)
		(layer "F.Cu")
		(net "M_F_CPU0_SB_DQS_DP<2>")
	)
	(segment
		(start 423.271188 -209.826098)
		(end 423.685716 -210.240626)
		(width 0.20066)
		(layer "F.Cu")
		(net "M_F_CPU0_SB_DQS_DP<2>")
	)
	(segment
		(start 420.736014 -210.066636)
		(end 421.840914 -210.066636)
		(width 0.20066)
		(layer "F.Cu")
		(net "M_F_CPU0_SB_DQS_DP<2>")
	)
	(segment
		(start 426.945298 -210.491832)
		(end 426.951394 -210.497928)
		(width 0.1016)
		(layer "F.Cu")
		(net "M_F_CPU0_SB_DQS_DP<2>")
	)
	(segment
		(start 424.762168 -210.491832)
		(end 424.788076 -210.491832)
		(width 0.101854)
		(layer "F.Cu")
		(net "M_F_CPU0_SB_DQS_DP<2>")
	)
	(segment
		(start 428.836074 -210.066636)
		(end 429.384714 -210.066636)
		(width 0.20066)
		(layer "F.Cu")
		(net "M_F_CPU0_SB_DQS_DP<2>")
	)
	(segment
		(start 423.685716 -210.240626)
		(end 424.371516 -210.240626)
		(width 0.20066)
		(layer "F.Cu")
		(net "M_F_CPU0_SB_DQS_DP<2>")
	)
	(segment
		(start 417.25596 -209.629756)
		(end 417.227766 -209.601562)
		(width 0.16002)
		(layer "In2.Cu")
		(net "M_F_CPU0_SB_DQS_DP<2>")
	)
	(segment
		(start 384.327908 -222.761556)
		(end 384.015234 -222.761556)
		(width 0.088646)
		(layer "In2.Cu")
		(net "M_F_CPU0_SB_DQS_DP<2>")
	)
	(segment
		(start 388.547864 -222.424752)
		(end 388.546848 -222.42526)
		(width 0.088646)
		(layer "In2.Cu")
		(net "M_F_CPU0_SB_DQS_DP<2>")
	)
	(segment
		(start 416.837114 -209.21091)
		(end 415.413698 -209.21091)
		(width 0.18288)
		(layer "In2.Cu")
		(net "M_F_CPU0_SB_DQS_DP<2>")
	)
	(segment
		(start 415.164778 -208.96199)
		(end 415.136584 -208.933796)
		(width 0.16002)
		(layer "In2.Cu")
		(net "M_F_CPU0_SB_DQS_DP<2>")
	)
	(segment
		(start 405.859488 -207.264)
		(end 405.859488 -207.279748)
		(width 0.16002)
		(layer "In2.Cu")
		(net "M_F_CPU0_SB_DQS_DP<2>")
	)
	(segment
		(start 417.410646 -209.784442)
		(end 417.410646 -209.768186)
		(width 0.16002)
		(layer "In2.Cu")
		(net "M_F_CPU0_SB_DQS_DP<2>")
	)
	(segment
		(start 419.26383 -209.99069)
		(end 417.616894 -209.99069)
		(width 0.18288)
		(layer "In2.Cu")
		(net "M_F_CPU0_SB_DQS_DP<2>")
	)
	(segment
		(start 406.014174 -207.125062)
		(end 405.998426 -207.125062)
		(width 0.16002)
		(layer "In2.Cu")
		(net "M_F_CPU0_SB_DQS_DP<2>")
	)
	(segment
		(start 388.339076 -222.761556)
		(end 388.33933 -222.761556)
		(width 0.088646)
		(layer "In2.Cu")
		(net "M_F_CPU0_SB_DQS_DP<2>")
	)
	(segment
		(start 388.561834 -222.41637)
		(end 388.547864 -222.424752)
		(width 0.088646)
		(layer "In2.Cu")
		(net "M_F_CPU0_SB_DQS_DP<2>")
	)
	(segment
		(start 406.042368 -207.096868)
		(end 406.014174 -207.125062)
		(width 0.16002)
		(layer "In2.Cu")
		(net "M_F_CPU0_SB_DQS_DP<2>")
	)
	(segment
		(start 417.227766 -209.601562)
		(end 416.837114 -209.21091)
		(width 0.18288)
		(layer "In2.Cu")
		(net "M_F_CPU0_SB_DQS_DP<2>")
	)
	(segment
		(start 420.016686 -209.615786)
		(end 419.638734 -209.615786)
		(width 0.18288)
		(layer "In2.Cu")
		(net "M_F_CPU0_SB_DQS_DP<2>")
	)
	(segment
		(start 403.395688 -209.877152)
		(end 402.589238 -209.877152)
		(width 0.18288)
		(layer "In2.Cu")
		(net "M_F_CPU0_SB_DQS_DP<2>")
	)
	(segment
		(start 412.172912 -208.53019)
		(end 411.315916 -207.673194)
		(width 0.18288)
		(layer "In2.Cu")
		(net "M_F_CPU0_SB_DQS_DP<2>")
	)
	(segment
		(start 417.410646 -209.768186)
		(end 417.272216 -209.629756)
		(width 0.16002)
		(layer "In2.Cu")
		(net "M_F_CPU0_SB_DQS_DP<2>")
	)
	(segment
		(start 420.213282 -209.812382)
		(end 420.016686 -209.615786)
		(width 0.18288)
		(layer "In2.Cu")
		(net "M_F_CPU0_SB_DQS_DP<2>")
	)
	(segment
		(start 405.703786 -207.43545)
		(end 405.703786 -207.569054)
		(width 0.18288)
		(layer "In2.Cu")
		(net "M_F_CPU0_SB_DQS_DP<2>")
	)
	(segment
		(start 388.668006 -222.343218)
		(end 388.561834 -222.41637)
		(width 0.088646)
		(layer "In2.Cu")
		(net "M_F_CPU0_SB_DQS_DP<2>")
	)
	(segment
		(start 410.22651 -207.673194)
		(end 409.931362 -207.968342)
		(width 0.18288)
		(layer "In2.Cu")
		(net "M_F_CPU0_SB_DQS_DP<2>")
	)
	(segment
		(start 414.981898 -208.77911)
		(end 414.953704 -208.750916)
		(width 0.16002)
		(layer "In2.Cu")
		(net "M_F_CPU0_SB_DQS_DP<2>")
	)
	(segment
		(start 389.077708 -222.261938)
		(end 388.668006 -222.343218)
		(width 0.088646)
		(layer "In2.Cu")
		(net "M_F_CPU0_SB_DQS_DP<2>")
	)
	(segment
		(start 405.831294 -207.307942)
		(end 405.703786 -207.43545)
		(width 0.18288)
		(layer "In2.Cu")
		(net "M_F_CPU0_SB_DQS_DP<2>")
	)
	(segment
		(start 384.682492 -223.257364)
		(end 384.672078 -223.251268)
		(width 0.088646)
		(layer "In2.Cu")
		(net "M_F_CPU0_SB_DQS_DP<2>")
	)
	(segment
		(start 420.48176 -209.812382)
		(end 420.213282 -209.812382)
		(width 0.18288)
		(layer "In2.Cu")
		(net "M_F_CPU0_SB_DQS_DP<2>")
	)
	(segment
		(start 419.638734 -209.615786)
		(end 419.26383 -209.99069)
		(width 0.18288)
		(layer "In2.Cu")
		(net "M_F_CPU0_SB_DQS_DP<2>")
	)
	(segment
		(start 407.236676 -206.84363)
		(end 406.295606 -206.84363)
		(width 0.18288)
		(layer "In2.Cu")
		(net "M_F_CPU0_SB_DQS_DP<2>")
	)
	(segment
		(start 405.998426 -207.125062)
		(end 405.859488 -207.264)
		(width 0.16002)
		(layer "In2.Cu")
		(net "M_F_CPU0_SB_DQS_DP<2>")
	)
	(segment
		(start 405.859488 -207.279748)
		(end 405.831294 -207.307942)
		(width 0.16002)
		(layer "In2.Cu")
		(net "M_F_CPU0_SB_DQS_DP<2>")
	)
	(segment
		(start 387.506464 -223.259904)
		(end 387.491732 -223.251268)
		(width 0.088646)
		(layer "In2.Cu")
		(net "M_F_CPU0_SB_DQS_DP<2>")
	)
	(segment
		(start 415.413698 -209.21091)
		(end 415.164778 -208.96199)
		(width 0.18288)
		(layer "In2.Cu")
		(net "M_F_CPU0_SB_DQS_DP<2>")
	)
	(segment
		(start 402.589238 -209.877152)
		(end 390.144762 -222.321628)
		(width 0.18288)
		(layer "In2.Cu")
		(net "M_F_CPU0_SB_DQS_DP<2>")
	)
	(segment
		(start 412.655004 -208.53019)
		(end 412.172912 -208.53019)
		(width 0.18288)
		(layer "In2.Cu")
		(net "M_F_CPU0_SB_DQS_DP<2>")
	)
	(segment
		(start 405.703786 -207.569054)
		(end 403.395688 -209.877152)
		(width 0.18288)
		(layer "In2.Cu")
		(net "M_F_CPU0_SB_DQS_DP<2>")
	)
	(segment
		(start 414.997646 -208.77911)
		(end 414.981898 -208.77911)
		(width 0.16002)
		(layer "In2.Cu")
		(net "M_F_CPU0_SB_DQS_DP<2>")
	)
	(segment
		(start 414.953704 -208.750916)
		(end 414.725866 -208.523078)
		(width 0.18288)
		(layer "In2.Cu")
		(net "M_F_CPU0_SB_DQS_DP<2>")
	)
	(segment
		(start 409.240736 -207.70977)
		(end 408.102816 -207.70977)
		(width 0.18288)
		(layer "In2.Cu")
		(net "M_F_CPU0_SB_DQS_DP<2>")
	)
	(segment
		(start 414.725866 -208.523078)
		(end 413.670242 -208.523078)
		(width 0.18288)
		(layer "In2.Cu")
		(net "M_F_CPU0_SB_DQS_DP<2>")
	)
	(segment
		(start 415.136584 -208.933796)
		(end 415.136584 -208.918048)
		(width 0.16002)
		(layer "In2.Cu")
		(net "M_F_CPU0_SB_DQS_DP<2>")
	)
	(segment
		(start 415.136584 -208.918048)
		(end 414.997646 -208.77911)
		(width 0.16002)
		(layer "In2.Cu")
		(net "M_F_CPU0_SB_DQS_DP<2>")
	)
	(segment
		(start 417.272216 -209.629756)
		(end 417.25596 -209.629756)
		(width 0.16002)
		(layer "In2.Cu")
		(net "M_F_CPU0_SB_DQS_DP<2>")
	)
	(segment
		(start 388.33933 -222.761556)
		(end 388.33933 -222.783654)
		(width 0.088646)
		(layer "In2.Cu")
		(net "M_F_CPU0_SB_DQS_DP<2>")
	)
	(segment
		(start 384.392932 -222.82658)
		(end 384.327908 -222.761556)
		(width 0.088646)
		(layer "In2.Cu")
		(net "M_F_CPU0_SB_DQS_DP<2>")
	)
	(segment
		(start 420.736014 -210.066636)
		(end 420.48176 -209.812382)
		(width 0.18288)
		(layer "In2.Cu")
		(net "M_F_CPU0_SB_DQS_DP<2>")
	)
	(segment
		(start 409.931362 -207.968342)
		(end 409.499308 -207.968342)
		(width 0.18288)
		(layer "In2.Cu")
		(net "M_F_CPU0_SB_DQS_DP<2>")
	)
	(segment
		(start 412.94304 -208.818226)
		(end 412.655004 -208.53019)
		(width 0.18288)
		(layer "In2.Cu")
		(net "M_F_CPU0_SB_DQS_DP<2>")
	)
	(segment
		(start 390.144762 -222.321628)
		(end 389.756142 -222.321628)
		(width 0.18288)
		(layer "In2.Cu")
		(net "M_F_CPU0_SB_DQS_DP<2>")
	)
	(segment
		(start 389.756142 -222.321628)
		(end 389.696452 -222.261938)
		(width 0.088646)
		(layer "In2.Cu")
		(net "M_F_CPU0_SB_DQS_DP<2>")
	)
	(segment
		(start 388.544562 -222.426276)
		(end 388.52348 -222.438722)
		(width 0.088646)
		(layer "In2.Cu")
		(net "M_F_CPU0_SB_DQS_DP<2>")
	)
	(segment
		(start 411.315916 -207.673194)
		(end 410.22651 -207.673194)
		(width 0.18288)
		(layer "In2.Cu")
		(net "M_F_CPU0_SB_DQS_DP<2>")
	)
	(segment
		(start 409.499308 -207.968342)
		(end 409.240736 -207.70977)
		(width 0.18288)
		(layer "In2.Cu")
		(net "M_F_CPU0_SB_DQS_DP<2>")
	)
	(segment
		(start 413.670242 -208.523078)
		(end 413.375094 -208.818226)
		(width 0.18288)
		(layer "In2.Cu")
		(net "M_F_CPU0_SB_DQS_DP<2>")
	)
	(segment
		(start 417.43884 -209.812636)
		(end 417.410646 -209.784442)
		(width 0.16002)
		(layer "In2.Cu")
		(net "M_F_CPU0_SB_DQS_DP<2>")
	)
	(segment
		(start 408.102816 -207.70977)
		(end 407.236676 -206.84363)
		(width 0.18288)
		(layer "In2.Cu")
		(net "M_F_CPU0_SB_DQS_DP<2>")
	)
	(segment
		(start 389.696452 -222.261938)
		(end 389.077708 -222.261938)
		(width 0.088646)
		(layer "In2.Cu")
		(net "M_F_CPU0_SB_DQS_DP<2>")
	)
	(segment
		(start 413.375094 -208.818226)
		(end 412.94304 -208.818226)
		(width 0.18288)
		(layer "In2.Cu")
		(net "M_F_CPU0_SB_DQS_DP<2>")
	)
	(segment
		(start 417.616894 -209.99069)
		(end 417.43884 -209.812636)
		(width 0.18288)
		(layer "In2.Cu")
		(net "M_F_CPU0_SB_DQS_DP<2>")
	)
	(segment
		(start 388.52348 -222.438722)
		(end 388.513828 -222.444818)
		(width 0.088646)
		(layer "In2.Cu")
		(net "M_F_CPU0_SB_DQS_DP<2>")
	)
	(segment
		(start 388.546848 -222.42526)
		(end 388.544562 -222.426276)
		(width 0.088646)
		(layer "In2.Cu")
		(net "M_F_CPU0_SB_DQS_DP<2>")
	)
	(segment
		(start 406.295606 -206.84363)
		(end 406.042368 -207.096868)
		(width 0.18288)
		(layer "In2.Cu")
		(net "M_F_CPU0_SB_DQS_DP<2>")
	)
	(segment
		(start 386.566664 -223.259904)
		(end 386.551932 -223.251268)
		(width 0.088646)
		(layer "In2.Cu")
		(net "M_F_CPU0_SB_DQS_DP<2>")
	)
	(arc
		(start 384.672078 -223.251268)
		(mid 384.488022 -223.081016)
		(end 384.395726 -222.847916)
		(width 0.088646)
		(layer "In2.Cu")
		(net "M_F_CPU0_SB_DQS_DP<2>")
	)
	(arc
		(start 388.513828 -222.444818)
		(mid 388.385644 -222.580688)
		(end 388.339076 -222.761556)
		(width 0.088646)
		(layer "In2.Cu")
		(net "M_F_CPU0_SB_DQS_DP<2>")
	)
	(arc
		(start 388.33933 -222.783654)
		(mid 388.054899 -223.252555)
		(end 387.506464 -223.259904)
		(width 0.088646)
		(layer "In2.Cu")
		(net "M_F_CPU0_SB_DQS_DP<2>")
	)
	(arc
		(start 387.117336 -223.251268)
		(mid 386.843107 -223.327193)
		(end 386.566664 -223.259904)
		(width 0.088646)
		(layer "In2.Cu")
		(net "M_F_CPU0_SB_DQS_DP<2>")
	)
	(arc
		(start 384.395726 -222.847916)
		(mid 384.394228 -222.837261)
		(end 384.392932 -222.82658)
		(width 0.088646)
		(layer "In2.Cu")
		(net "M_F_CPU0_SB_DQS_DP<2>")
	)
	(arc
		(start 386.551932 -223.251268)
		(mid 386.364734 -223.201125)
		(end 386.177536 -223.251268)
		(width 0.088646)
		(layer "In2.Cu")
		(net "M_F_CPU0_SB_DQS_DP<2>")
	)
	(arc
		(start 385.612132 -223.251268)
		(mid 385.424934 -223.201125)
		(end 385.237736 -223.251268)
		(width 0.088646)
		(layer "In2.Cu")
		(net "M_F_CPU0_SB_DQS_DP<2>")
	)
	(arc
		(start 385.237736 -223.251268)
		(mid 384.960923 -223.327104)
		(end 384.682492 -223.257364)
		(width 0.088646)
		(layer "In2.Cu")
		(net "M_F_CPU0_SB_DQS_DP<2>")
	)
	(arc
		(start 387.491732 -223.251268)
		(mid 387.304534 -223.201125)
		(end 387.117336 -223.251268)
		(width 0.088646)
		(layer "In2.Cu")
		(net "M_F_CPU0_SB_DQS_DP<2>")
	)
	(arc
		(start 386.177536 -223.251268)
		(mid 385.894834 -223.32701)
		(end 385.612132 -223.251268)
		(width 0.088646)
		(layer "In2.Cu")
		(net "M_F_CPU0_SB_DQS_DP<2>")
	)
	(segment
		(start 380.725934 -230.622602)
		(end 380.72568 -230.622348)
		(width 0.20066)
		(layer "F.Cu")
		(net "M_F_CPU0_SB_DQS_DP<1>")
	)
	(segment
		(start 427.57725 -219.545408)
		(end 427.947836 -219.545408)
		(width 0.20066)
		(layer "F.Cu")
		(net "M_F_CPU0_SB_DQS_DP<1>")
	)
	(segment
		(start 428.3583 -219.134944)
		(end 428.554388 -219.134944)
		(width 0.20066)
		(layer "F.Cu")
		(net "M_F_CPU0_SB_DQS_DP<1>")
	)
	(segment
		(start 423.271188 -219.176092)
		(end 423.685716 -219.59062)
		(width 0.20066)
		(layer "F.Cu")
		(net "M_F_CPU0_SB_DQS_DP<1>")
	)
	(segment
		(start 424.371516 -219.59062)
		(end 424.622722 -219.841826)
		(width 0.20066)
		(layer "F.Cu")
		(net "M_F_CPU0_SB_DQS_DP<1>")
	)
	(segment
		(start 380.72568 -230.622348)
		(end 380.72568 -230.086662)
		(width 0.20066)
		(layer "F.Cu")
		(net "M_F_CPU0_SB_DQS_DP<1>")
	)
	(segment
		(start 424.762168 -219.841826)
		(end 424.788076 -219.841826)
		(width 0.101854)
		(layer "F.Cu")
		(net "M_F_CPU0_SB_DQS_DP<1>")
	)
	(segment
		(start 424.788076 -219.841826)
		(end 426.945298 -219.841826)
		(width 0.1016)
		(layer "F.Cu")
		(net "M_F_CPU0_SB_DQS_DP<1>")
	)
	(segment
		(start 426.951394 -219.847922)
		(end 427.274736 -219.847922)
		(width 0.20066)
		(layer "F.Cu")
		(net "M_F_CPU0_SB_DQS_DP<1>")
	)
	(segment
		(start 422.670732 -219.176092)
		(end 423.271188 -219.176092)
		(width 0.20066)
		(layer "F.Cu")
		(net "M_F_CPU0_SB_DQS_DP<1>")
	)
	(segment
		(start 421.840914 -219.41663)
		(end 422.430194 -219.41663)
		(width 0.20066)
		(layer "F.Cu")
		(net "M_F_CPU0_SB_DQS_DP<1>")
	)
	(segment
		(start 427.274736 -219.847922)
		(end 427.57725 -219.545408)
		(width 0.20066)
		(layer "F.Cu")
		(net "M_F_CPU0_SB_DQS_DP<1>")
	)
	(segment
		(start 427.947836 -219.545408)
		(end 428.3583 -219.134944)
		(width 0.20066)
		(layer "F.Cu")
		(net "M_F_CPU0_SB_DQS_DP<1>")
	)
	(segment
		(start 428.554388 -219.134944)
		(end 428.836074 -219.41663)
		(width 0.20066)
		(layer "F.Cu")
		(net "M_F_CPU0_SB_DQS_DP<1>")
	)
	(segment
		(start 420.736014 -219.41663)
		(end 421.840914 -219.41663)
		(width 0.20066)
		(layer "F.Cu")
		(net "M_F_CPU0_SB_DQS_DP<1>")
	)
	(segment
		(start 423.685716 -219.59062)
		(end 424.371516 -219.59062)
		(width 0.20066)
		(layer "F.Cu")
		(net "M_F_CPU0_SB_DQS_DP<1>")
	)
	(segment
		(start 424.622722 -219.841826)
		(end 424.762168 -219.841826)
		(width 0.20066)
		(layer "F.Cu")
		(net "M_F_CPU0_SB_DQS_DP<1>")
	)
	(segment
		(start 426.945298 -219.841826)
		(end 426.951394 -219.847922)
		(width 0.1016)
		(layer "F.Cu")
		(net "M_F_CPU0_SB_DQS_DP<1>")
	)
	(segment
		(start 428.836074 -219.41663)
		(end 429.384714 -219.41663)
		(width 0.20066)
		(layer "F.Cu")
		(net "M_F_CPU0_SB_DQS_DP<1>")
	)
	(segment
		(start 422.430194 -219.41663)
		(end 422.670732 -219.176092)
		(width 0.20066)
		(layer "F.Cu")
		(net "M_F_CPU0_SB_DQS_DP<1>")
	)
	(segment
		(start 417.25342 -218.97975)
		(end 417.225226 -218.951556)
		(width 0.16002)
		(layer "In2.Cu")
		(net "M_F_CPU0_SB_DQS_DP<1>")
	)
	(segment
		(start 407.509472 -218.18981)
		(end 407.232612 -217.91295)
		(width 0.18288)
		(layer "In2.Cu")
		(net "M_F_CPU0_SB_DQS_DP<1>")
	)
	(segment
		(start 381.383032 -230.57612)
		(end 381.37084 -230.569008)
		(width 0.088646)
		(layer "In2.Cu")
		(net "M_F_CPU0_SB_DQS_DP<1>")
	)
	(segment
		(start 405.07539 -218.69781)
		(end 402.758148 -221.015052)
		(width 0.18288)
		(layer "In2.Cu")
		(net "M_F_CPU0_SB_DQS_DP<1>")
	)
	(segment
		(start 417.408106 -219.134436)
		(end 417.408106 -219.11818)
		(width 0.16002)
		(layer "In2.Cu")
		(net "M_F_CPU0_SB_DQS_DP<1>")
	)
	(segment
		(start 394.241782 -228.67239)
		(end 389.228076 -228.67239)
		(width 0.18288)
		(layer "In2.Cu")
		(net "M_F_CPU0_SB_DQS_DP<1>")
	)
	(segment
		(start 405.82469 -218.37269)
		(end 405.796496 -218.400884)
		(width 0.16002)
		(layer "In2.Cu")
		(net "M_F_CPU0_SB_DQS_DP<1>")
	)
	(segment
		(start 407.692352 -218.356942)
		(end 407.553414 -218.218004)
		(width 0.16002)
		(layer "In2.Cu")
		(net "M_F_CPU0_SB_DQS_DP<1>")
	)
	(segment
		(start 417.225226 -218.951556)
		(end 417.08578 -218.81211)
		(width 0.18288)
		(layer "In2.Cu")
		(net "M_F_CPU0_SB_DQS_DP<1>")
	)
	(segment
		(start 409.694126 -218.951556)
		(end 409.30576 -218.56319)
		(width 0.18288)
		(layer "In2.Cu")
		(net "M_F_CPU0_SB_DQS_DP<1>")
	)
	(segment
		(start 417.4363 -219.16263)
		(end 417.408106 -219.134436)
		(width 0.16002)
		(layer "In2.Cu")
		(net "M_F_CPU0_SB_DQS_DP<1>")
	)
	(segment
		(start 420.226744 -219.104464)
		(end 420.059612 -218.937332)
		(width 0.18288)
		(layer "In2.Cu")
		(net "M_F_CPU0_SB_DQS_DP<1>")
	)
	(segment
		(start 388.890256 -228.925374)
		(end 388.144258 -229.671372)
		(width 0.088646)
		(layer "In2.Cu")
		(net "M_F_CPU0_SB_DQS_DP<1>")
	)
	(segment
		(start 388.144258 -229.671372)
		(end 387.455156 -229.671372)
		(width 0.088646)
		(layer "In2.Cu")
		(net "M_F_CPU0_SB_DQS_DP<1>")
	)
	(segment
		(start 388.975092 -228.925374)
		(end 388.890256 -228.925374)
		(width 0.088646)
		(layer "In2.Cu")
		(net "M_F_CPU0_SB_DQS_DP<1>")
	)
	(segment
		(start 381.038608 -230.086662)
		(end 380.72568 -230.086662)
		(width 0.088646)
		(layer "In2.Cu")
		(net "M_F_CPU0_SB_DQS_DP<1>")
	)
	(segment
		(start 405.963628 -218.218004)
		(end 405.82469 -218.356942)
		(width 0.16002)
		(layer "In2.Cu")
		(net "M_F_CPU0_SB_DQS_DP<1>")
	)
	(segment
		(start 401.89912 -221.015052)
		(end 394.241782 -228.67239)
		(width 0.18288)
		(layer "In2.Cu")
		(net "M_F_CPU0_SB_DQS_DP<1>")
	)
	(segment
		(start 407.692352 -218.37269)
		(end 407.692352 -218.356942)
		(width 0.16002)
		(layer "In2.Cu")
		(net "M_F_CPU0_SB_DQS_DP<1>")
	)
	(segment
		(start 385.237736 -229.762304)
		(end 385.228846 -229.767384)
		(width 0.088646)
		(layer "In2.Cu")
		(net "M_F_CPU0_SB_DQS_DP<1>")
	)
	(segment
		(start 412.171134 -219.867226)
		(end 411.828488 -219.867226)
		(width 0.18288)
		(layer "In2.Cu")
		(net "M_F_CPU0_SB_DQS_DP<1>")
	)
	(segment
		(start 405.796496 -218.400884)
		(end 405.49957 -218.69781)
		(width 0.18288)
		(layer "In2.Cu")
		(net "M_F_CPU0_SB_DQS_DP<1>")
	)
	(segment
		(start 417.269676 -218.97975)
		(end 417.25342 -218.97975)
		(width 0.16002)
		(layer "In2.Cu")
		(net "M_F_CPU0_SB_DQS_DP<1>")
	)
	(segment
		(start 420.736014 -219.41663)
		(end 420.423848 -219.104464)
		(width 0.18288)
		(layer "In2.Cu")
		(net "M_F_CPU0_SB_DQS_DP<1>")
	)
	(segment
		(start 406.28443 -217.91295)
		(end 406.00757 -218.18981)
		(width 0.18288)
		(layer "In2.Cu")
		(net "M_F_CPU0_SB_DQS_DP<1>")
	)
	(segment
		(start 407.882852 -218.56319)
		(end 407.720546 -218.400884)
		(width 0.18288)
		(layer "In2.Cu")
		(net "M_F_CPU0_SB_DQS_DP<1>")
	)
	(segment
		(start 405.979376 -218.218004)
		(end 405.963628 -218.218004)
		(width 0.16002)
		(layer "In2.Cu")
		(net "M_F_CPU0_SB_DQS_DP<1>")
	)
	(segment
		(start 411.510734 -219.549472)
		(end 410.292042 -219.549472)
		(width 0.18288)
		(layer "In2.Cu")
		(net "M_F_CPU0_SB_DQS_DP<1>")
	)
	(segment
		(start 411.828488 -219.867226)
		(end 411.510734 -219.549472)
		(width 0.18288)
		(layer "In2.Cu")
		(net "M_F_CPU0_SB_DQS_DP<1>")
	)
	(segment
		(start 417.408106 -219.11818)
		(end 417.269676 -218.97975)
		(width 0.16002)
		(layer "In2.Cu")
		(net "M_F_CPU0_SB_DQS_DP<1>")
	)
	(segment
		(start 385.050284 -230.086662)
		(end 385.050284 -230.096568)
		(width 0.088646)
		(layer "In2.Cu")
		(net "M_F_CPU0_SB_DQS_DP<1>")
	)
	(segment
		(start 402.758148 -221.015052)
		(end 401.89912 -221.015052)
		(width 0.18288)
		(layer "In2.Cu")
		(net "M_F_CPU0_SB_DQS_DP<1>")
	)
	(segment
		(start 389.228076 -228.67239)
		(end 388.975092 -228.925374)
		(width 0.18288)
		(layer "In2.Cu")
		(net "M_F_CPU0_SB_DQS_DP<1>")
	)
	(segment
		(start 420.423848 -219.104464)
		(end 420.226744 -219.104464)
		(width 0.18288)
		(layer "In2.Cu")
		(net "M_F_CPU0_SB_DQS_DP<1>")
	)
	(segment
		(start 409.30576 -218.56319)
		(end 407.882852 -218.56319)
		(width 0.18288)
		(layer "In2.Cu")
		(net "M_F_CPU0_SB_DQS_DP<1>")
	)
	(segment
		(start 420.059612 -218.937332)
		(end 419.64864 -218.937332)
		(width 0.18288)
		(layer "In2.Cu")
		(net "M_F_CPU0_SB_DQS_DP<1>")
	)
	(segment
		(start 419.64864 -218.937332)
		(end 419.237922 -219.34805)
		(width 0.18288)
		(layer "In2.Cu")
		(net "M_F_CPU0_SB_DQS_DP<1>")
	)
	(segment
		(start 410.292042 -219.549472)
		(end 409.9052 -219.16263)
		(width 0.18288)
		(layer "In2.Cu")
		(net "M_F_CPU0_SB_DQS_DP<1>")
	)
	(segment
		(start 407.537666 -218.218004)
		(end 407.509472 -218.18981)
		(width 0.16002)
		(layer "In2.Cu")
		(net "M_F_CPU0_SB_DQS_DP<1>")
	)
	(segment
		(start 417.62172 -219.34805)
		(end 417.4363 -219.16263)
		(width 0.18288)
		(layer "In2.Cu")
		(net "M_F_CPU0_SB_DQS_DP<1>")
	)
	(segment
		(start 409.9052 -219.16263)
		(end 409.877006 -219.134436)
		(width 0.16002)
		(layer "In2.Cu")
		(net "M_F_CPU0_SB_DQS_DP<1>")
	)
	(segment
		(start 407.553414 -218.218004)
		(end 407.537666 -218.218004)
		(width 0.16002)
		(layer "In2.Cu")
		(net "M_F_CPU0_SB_DQS_DP<1>")
	)
	(segment
		(start 409.72232 -218.97975)
		(end 409.694126 -218.951556)
		(width 0.16002)
		(layer "In2.Cu")
		(net "M_F_CPU0_SB_DQS_DP<1>")
	)
	(segment
		(start 412.827978 -219.549472)
		(end 412.488888 -219.549472)
		(width 0.18288)
		(layer "In2.Cu")
		(net "M_F_CPU0_SB_DQS_DP<1>")
	)
	(segment
		(start 406.00757 -218.18981)
		(end 405.979376 -218.218004)
		(width 0.16002)
		(layer "In2.Cu")
		(net "M_F_CPU0_SB_DQS_DP<1>")
	)
	(segment
		(start 405.49957 -218.69781)
		(end 405.07539 -218.69781)
		(width 0.18288)
		(layer "In2.Cu")
		(net "M_F_CPU0_SB_DQS_DP<1>")
	)
	(segment
		(start 409.738576 -218.97975)
		(end 409.72232 -218.97975)
		(width 0.16002)
		(layer "In2.Cu")
		(net "M_F_CPU0_SB_DQS_DP<1>")
	)
	(segment
		(start 415.206688 -220.10497)
		(end 413.383476 -220.10497)
		(width 0.18288)
		(layer "In2.Cu")
		(net "M_F_CPU0_SB_DQS_DP<1>")
	)
	(segment
		(start 409.877006 -219.134436)
		(end 409.877006 -219.11818)
		(width 0.16002)
		(layer "In2.Cu")
		(net "M_F_CPU0_SB_DQS_DP<1>")
	)
	(segment
		(start 412.488888 -219.549472)
		(end 412.171134 -219.867226)
		(width 0.18288)
		(layer "In2.Cu")
		(net "M_F_CPU0_SB_DQS_DP<1>")
	)
	(segment
		(start 407.232612 -217.91295)
		(end 406.28443 -217.91295)
		(width 0.18288)
		(layer "In2.Cu")
		(net "M_F_CPU0_SB_DQS_DP<1>")
	)
	(segment
		(start 387.116828 -229.76205)
		(end 387.117082 -229.762558)
		(width 0.088646)
		(layer "In2.Cu")
		(net "M_F_CPU0_SB_DQS_DP<1>")
	)
	(segment
		(start 419.237922 -219.34805)
		(end 417.62172 -219.34805)
		(width 0.18288)
		(layer "In2.Cu")
		(net "M_F_CPU0_SB_DQS_DP<1>")
	)
	(segment
		(start 409.877006 -219.11818)
		(end 409.738576 -218.97975)
		(width 0.16002)
		(layer "In2.Cu")
		(net "M_F_CPU0_SB_DQS_DP<1>")
	)
	(segment
		(start 407.720546 -218.400884)
		(end 407.692352 -218.37269)
		(width 0.16002)
		(layer "In2.Cu")
		(net "M_F_CPU0_SB_DQS_DP<1>")
	)
	(segment
		(start 381.10414 -230.152194)
		(end 381.038608 -230.086662)
		(width 0.088646)
		(layer "In2.Cu")
		(net "M_F_CPU0_SB_DQS_DP<1>")
	)
	(segment
		(start 405.82469 -218.356942)
		(end 405.82469 -218.37269)
		(width 0.16002)
		(layer "In2.Cu")
		(net "M_F_CPU0_SB_DQS_DP<1>")
	)
	(segment
		(start 417.08578 -218.81211)
		(end 416.499548 -218.81211)
		(width 0.18288)
		(layer "In2.Cu")
		(net "M_F_CPU0_SB_DQS_DP<1>")
	)
	(segment
		(start 416.499548 -218.81211)
		(end 415.206688 -220.10497)
		(width 0.18288)
		(layer "In2.Cu")
		(net "M_F_CPU0_SB_DQS_DP<1>")
	)
	(segment
		(start 413.383476 -220.10497)
		(end 412.827978 -219.549472)
		(width 0.18288)
		(layer "In2.Cu")
		(net "M_F_CPU0_SB_DQS_DP<1>")
	)
	(arc
		(start 385.050284 -230.096568)
		(mid 384.972173 -230.373517)
		(end 384.767836 -230.57612)
		(width 0.088646)
		(layer "In2.Cu")
		(net "M_F_CPU0_SB_DQS_DP<1>")
	)
	(arc
		(start 386.177536 -229.762304)
		(mid 385.894834 -229.83808)
		(end 385.612132 -229.762304)
		(width 0.088646)
		(layer "In2.Cu")
		(net "M_F_CPU0_SB_DQS_DP<1>")
	)
	(arc
		(start 384.202432 -230.57612)
		(mid 384.015234 -230.525977)
		(end 383.828036 -230.57612)
		(width 0.088646)
		(layer "In2.Cu")
		(net "M_F_CPU0_SB_DQS_DP<1>")
	)
	(arc
		(start 385.228846 -229.767384)
		(mid 385.097932 -229.903744)
		(end 385.050284 -230.086662)
		(width 0.088646)
		(layer "In2.Cu")
		(net "M_F_CPU0_SB_DQS_DP<1>")
	)
	(arc
		(start 383.828036 -230.57612)
		(mid 383.545334 -230.651896)
		(end 383.262632 -230.57612)
		(width 0.088646)
		(layer "In2.Cu")
		(net "M_F_CPU0_SB_DQS_DP<1>")
	)
	(arc
		(start 386.551932 -229.762304)
		(mid 386.364734 -229.712161)
		(end 386.177536 -229.762304)
		(width 0.088646)
		(layer "In2.Cu")
		(net "M_F_CPU0_SB_DQS_DP<1>")
	)
	(arc
		(start 382.888236 -230.57612)
		(mid 382.605534 -230.651896)
		(end 382.322832 -230.57612)
		(width 0.088646)
		(layer "In2.Cu")
		(net "M_F_CPU0_SB_DQS_DP<1>")
	)
	(arc
		(start 382.322832 -230.57612)
		(mid 382.135634 -230.525977)
		(end 381.948436 -230.57612)
		(width 0.088646)
		(layer "In2.Cu")
		(net "M_F_CPU0_SB_DQS_DP<1>")
	)
	(arc
		(start 387.455156 -229.671372)
		(mid 387.280023 -229.694438)
		(end 387.116828 -229.76205)
		(width 0.088646)
		(layer "In2.Cu")
		(net "M_F_CPU0_SB_DQS_DP<1>")
	)
	(arc
		(start 387.117082 -229.762558)
		(mid 386.834461 -229.838173)
		(end 386.551932 -229.762304)
		(width 0.088646)
		(layer "In2.Cu")
		(net "M_F_CPU0_SB_DQS_DP<1>")
	)
	(arc
		(start 381.106934 -230.173022)
		(mid 381.10544 -230.162621)
		(end 381.10414 -230.152194)
		(width 0.088646)
		(layer "In2.Cu")
		(net "M_F_CPU0_SB_DQS_DP<1>")
	)
	(arc
		(start 381.37084 -230.569008)
		(mid 381.195238 -230.400116)
		(end 381.106934 -230.173022)
		(width 0.088646)
		(layer "In2.Cu")
		(net "M_F_CPU0_SB_DQS_DP<1>")
	)
	(arc
		(start 384.767836 -230.57612)
		(mid 384.485134 -230.651896)
		(end 384.202432 -230.57612)
		(width 0.088646)
		(layer "In2.Cu")
		(net "M_F_CPU0_SB_DQS_DP<1>")
	)
	(arc
		(start 385.612132 -229.762304)
		(mid 385.424934 -229.712161)
		(end 385.237736 -229.762304)
		(width 0.088646)
		(layer "In2.Cu")
		(net "M_F_CPU0_SB_DQS_DP<1>")
	)
	(arc
		(start 383.262632 -230.57612)
		(mid 383.075434 -230.525977)
		(end 382.888236 -230.57612)
		(width 0.088646)
		(layer "In2.Cu")
		(net "M_F_CPU0_SB_DQS_DP<1>")
	)
	(arc
		(start 381.948436 -230.57612)
		(mid 381.665734 -230.651896)
		(end 381.383032 -230.57612)
		(width 0.088646)
		(layer "In2.Cu")
		(net "M_F_CPU0_SB_DQS_DP<1>")
	)
	(segment
		(start 427.57725 -228.895402)
		(end 427.947836 -228.895402)
		(width 0.20066)
		(layer "F.Cu")
		(net "M_F_CPU0_SB_DQS_DP<0>")
	)
	(segment
		(start 426.945298 -229.19182)
		(end 426.951394 -229.197916)
		(width 0.1016)
		(layer "F.Cu")
		(net "M_F_CPU0_SB_DQS_DP<0>")
	)
	(segment
		(start 426.951394 -229.197916)
		(end 427.274736 -229.197916)
		(width 0.20066)
		(layer "F.Cu")
		(net "M_F_CPU0_SB_DQS_DP<0>")
	)
	(segment
		(start 423.271188 -228.526086)
		(end 423.685716 -228.940614)
		(width 0.20066)
		(layer "F.Cu")
		(net "M_F_CPU0_SB_DQS_DP<0>")
	)
	(segment
		(start 377.436634 -237.947454)
		(end 377.436634 -237.411514)
		(width 0.20066)
		(layer "F.Cu")
		(net "M_F_CPU0_SB_DQS_DP<0>")
	)
	(segment
		(start 423.685716 -228.940614)
		(end 424.371516 -228.940614)
		(width 0.20066)
		(layer "F.Cu")
		(net "M_F_CPU0_SB_DQS_DP<0>")
	)
	(segment
		(start 427.947836 -228.895402)
		(end 428.3583 -228.484938)
		(width 0.20066)
		(layer "F.Cu")
		(net "M_F_CPU0_SB_DQS_DP<0>")
	)
	(segment
		(start 428.3583 -228.484938)
		(end 428.554388 -228.484938)
		(width 0.20066)
		(layer "F.Cu")
		(net "M_F_CPU0_SB_DQS_DP<0>")
	)
	(segment
		(start 422.430194 -228.766624)
		(end 422.670732 -228.526086)
		(width 0.20066)
		(layer "F.Cu")
		(net "M_F_CPU0_SB_DQS_DP<0>")
	)
	(segment
		(start 421.840914 -228.766624)
		(end 422.430194 -228.766624)
		(width 0.20066)
		(layer "F.Cu")
		(net "M_F_CPU0_SB_DQS_DP<0>")
	)
	(segment
		(start 424.762168 -229.19182)
		(end 424.788076 -229.19182)
		(width 0.101854)
		(layer "F.Cu")
		(net "M_F_CPU0_SB_DQS_DP<0>")
	)
	(segment
		(start 424.788076 -229.19182)
		(end 426.945298 -229.19182)
		(width 0.1016)
		(layer "F.Cu")
		(net "M_F_CPU0_SB_DQS_DP<0>")
	)
	(segment
		(start 420.736014 -228.766624)
		(end 421.840914 -228.766624)
		(width 0.20066)
		(layer "F.Cu")
		(net "M_F_CPU0_SB_DQS_DP<0>")
	)
	(segment
		(start 427.274736 -229.197916)
		(end 427.57725 -228.895402)
		(width 0.20066)
		(layer "F.Cu")
		(net "M_F_CPU0_SB_DQS_DP<0>")
	)
	(segment
		(start 377.43638 -237.947454)
		(end 377.436634 -237.947454)
		(width 0.20066)
		(layer "F.Cu")
		(net "M_F_CPU0_SB_DQS_DP<0>")
	)
	(segment
		(start 428.554388 -228.484938)
		(end 428.836074 -228.766624)
		(width 0.20066)
		(layer "F.Cu")
		(net "M_F_CPU0_SB_DQS_DP<0>")
	)
	(segment
		(start 424.371516 -228.940614)
		(end 424.622722 -229.19182)
		(width 0.20066)
		(layer "F.Cu")
		(net "M_F_CPU0_SB_DQS_DP<0>")
	)
	(segment
		(start 422.670732 -228.526086)
		(end 423.271188 -228.526086)
		(width 0.20066)
		(layer "F.Cu")
		(net "M_F_CPU0_SB_DQS_DP<0>")
	)
	(segment
		(start 428.836074 -228.766624)
		(end 429.384714 -228.766624)
		(width 0.20066)
		(layer "F.Cu")
		(net "M_F_CPU0_SB_DQS_DP<0>")
	)
	(segment
		(start 424.622722 -229.19182)
		(end 424.762168 -229.19182)
		(width 0.20066)
		(layer "F.Cu")
		(net "M_F_CPU0_SB_DQS_DP<0>")
	)
	(segment
		(start 409.556712 -226.643946)
		(end 409.28798 -226.375214)
		(width 0.18288)
		(layer "In4.Cu")
		(net "M_F_CPU0_SB_DQS_DP<0>")
	)
	(segment
		(start 407.491946 -226.375214)
		(end 406.838658 -227.028502)
		(width 0.18288)
		(layer "In4.Cu")
		(net "M_F_CPU0_SB_DQS_DP<0>")
	)
	(segment
		(start 413.580072 -226.539552)
		(end 413.160464 -226.539552)
		(width 0.18288)
		(layer "In4.Cu")
		(net "M_F_CPU0_SB_DQS_DP<0>")
	)
	(segment
		(start 392.232642 -233.846624)
		(end 389.860536 -236.21873)
		(width 0.18288)
		(layer "In4.Cu")
		(net "M_F_CPU0_SB_DQS_DP<0>")
	)
	(segment
		(start 396.31874 -233.846624)
		(end 392.232642 -233.846624)
		(width 0.18288)
		(layer "In4.Cu")
		(net "M_F_CPU0_SB_DQS_DP<0>")
	)
	(segment
		(start 410.393642 -226.38385)
		(end 410.200856 -226.38385)
		(width 0.18288)
		(layer "In4.Cu")
		(net "M_F_CPU0_SB_DQS_DP<0>")
	)
	(segment
		(start 388.660132 -236.158786)
		(end 388.571486 -236.247432)
		(width 0.088646)
		(layer "In4.Cu")
		(net "M_F_CPU0_SB_DQS_DP<0>")
	)
	(segment
		(start 378.658882 -237.901226)
		(end 378.64415 -237.909862)
		(width 0.088646)
		(layer "In4.Cu")
		(net "M_F_CPU0_SB_DQS_DP<0>")
	)
	(segment
		(start 420.736014 -228.766624)
		(end 420.457122 -228.487732)
		(width 0.18288)
		(layer "In4.Cu")
		(net "M_F_CPU0_SB_DQS_DP<0>")
	)
	(segment
		(start 380.538736 -237.901226)
		(end 380.528322 -237.907322)
		(width 0.088646)
		(layer "In4.Cu")
		(net "M_F_CPU0_SB_DQS_DP<0>")
	)
	(segment
		(start 380.927864 -237.909862)
		(end 380.913132 -237.901226)
		(width 0.088646)
		(layer "In4.Cu")
		(net "M_F_CPU0_SB_DQS_DP<0>")
	)
	(segment
		(start 411.799532 -226.966526)
		(end 410.393642 -226.38385)
		(width 0.18288)
		(layer "In4.Cu")
		(net "M_F_CPU0_SB_DQS_DP<0>")
	)
	(segment
		(start 389.860536 -236.21873)
		(end 388.941564 -236.21873)
		(width 0.18288)
		(layer "In4.Cu")
		(net "M_F_CPU0_SB_DQS_DP<0>")
	)
	(segment
		(start 414.90138 -227.86086)
		(end 413.580072 -226.539552)
		(width 0.18288)
		(layer "In4.Cu")
		(net "M_F_CPU0_SB_DQS_DP<0>")
	)
	(segment
		(start 405.17826 -227.215446)
		(end 402.949918 -227.215446)
		(width 0.18288)
		(layer "In4.Cu")
		(net "M_F_CPU0_SB_DQS_DP<0>")
	)
	(segment
		(start 406.123648 -227.210874)
		(end 405.840692 -227.49383)
		(width 0.18288)
		(layer "In4.Cu")
		(net "M_F_CPU0_SB_DQS_DP<0>")
	)
	(segment
		(start 406.838658 -227.028502)
		(end 406.399746 -227.210874)
		(width 0.18288)
		(layer "In4.Cu")
		(net "M_F_CPU0_SB_DQS_DP<0>")
	)
	(segment
		(start 388.858252 -236.158786)
		(end 388.660132 -236.158786)
		(width 0.088646)
		(layer "In4.Cu")
		(net "M_F_CPU0_SB_DQS_DP<0>")
	)
	(segment
		(start 388.366508 -236.974634)
		(end 387.490208 -237.850172)
		(width 0.088646)
		(layer "In4.Cu")
		(net "M_F_CPU0_SB_DQS_DP<0>")
	)
	(segment
		(start 379.598682 -237.901226)
		(end 379.58395 -237.909862)
		(width 0.088646)
		(layer "In4.Cu")
		(net "M_F_CPU0_SB_DQS_DP<0>")
	)
	(segment
		(start 388.941564 -236.21873)
		(end 388.918196 -236.21873)
		(width 0.088646)
		(layer "In4.Cu")
		(net "M_F_CPU0_SB_DQS_DP<0>")
	)
	(segment
		(start 417.696396 -227.86086)
		(end 414.90138 -227.86086)
		(width 0.18288)
		(layer "In4.Cu")
		(net "M_F_CPU0_SB_DQS_DP<0>")
	)
	(segment
		(start 387.490208 -237.850172)
		(end 387.304788 -237.850172)
		(width 0.088646)
		(layer "In4.Cu")
		(net "M_F_CPU0_SB_DQS_DP<0>")
	)
	(segment
		(start 413.160464 -226.539552)
		(end 412.131002 -226.966526)
		(width 0.18288)
		(layer "In4.Cu")
		(net "M_F_CPU0_SB_DQS_DP<0>")
	)
	(segment
		(start 388.571486 -236.247432)
		(end 388.571486 -236.479588)
		(width 0.088646)
		(layer "In4.Cu")
		(net "M_F_CPU0_SB_DQS_DP<0>")
	)
	(segment
		(start 388.571486 -236.479588)
		(end 388.366508 -236.974634)
		(width 0.088646)
		(layer "In4.Cu")
		(net "M_F_CPU0_SB_DQS_DP<0>")
	)
	(segment
		(start 419.850062 -228.487732)
		(end 419.602158 -228.239828)
		(width 0.18288)
		(layer "In4.Cu")
		(net "M_F_CPU0_SB_DQS_DP<0>")
	)
	(segment
		(start 377.749054 -237.411514)
		(end 377.436634 -237.411514)
		(width 0.088646)
		(layer "In4.Cu")
		(net "M_F_CPU0_SB_DQS_DP<0>")
	)
	(segment
		(start 405.456644 -227.49383)
		(end 405.17826 -227.215446)
		(width 0.18288)
		(layer "In4.Cu")
		(net "M_F_CPU0_SB_DQS_DP<0>")
	)
	(segment
		(start 420.457122 -228.487732)
		(end 419.850062 -228.487732)
		(width 0.18288)
		(layer "In4.Cu")
		(net "M_F_CPU0_SB_DQS_DP<0>")
	)
	(segment
		(start 410.200856 -226.38385)
		(end 409.94076 -226.643946)
		(width 0.18288)
		(layer "In4.Cu")
		(net "M_F_CPU0_SB_DQS_DP<0>")
	)
	(segment
		(start 419.602158 -228.239828)
		(end 417.696396 -227.86086)
		(width 0.18288)
		(layer "In4.Cu")
		(net "M_F_CPU0_SB_DQS_DP<0>")
	)
	(segment
		(start 405.840692 -227.49383)
		(end 405.456644 -227.49383)
		(width 0.18288)
		(layer "In4.Cu")
		(net "M_F_CPU0_SB_DQS_DP<0>")
	)
	(segment
		(start 377.81484 -237.4773)
		(end 377.749054 -237.411514)
		(width 0.088646)
		(layer "In4.Cu")
		(net "M_F_CPU0_SB_DQS_DP<0>")
	)
	(segment
		(start 402.949918 -227.215446)
		(end 396.31874 -233.846624)
		(width 0.18288)
		(layer "In4.Cu")
		(net "M_F_CPU0_SB_DQS_DP<0>")
	)
	(segment
		(start 388.918196 -236.21873)
		(end 388.858252 -236.158786)
		(width 0.088646)
		(layer "In4.Cu")
		(net "M_F_CPU0_SB_DQS_DP<0>")
	)
	(segment
		(start 409.28798 -226.375214)
		(end 407.491946 -226.375214)
		(width 0.18288)
		(layer "In4.Cu")
		(net "M_F_CPU0_SB_DQS_DP<0>")
	)
	(segment
		(start 412.131002 -226.966526)
		(end 411.799532 -226.966526)
		(width 0.18288)
		(layer "In4.Cu")
		(net "M_F_CPU0_SB_DQS_DP<0>")
	)
	(segment
		(start 409.94076 -226.643946)
		(end 409.556712 -226.643946)
		(width 0.18288)
		(layer "In4.Cu")
		(net "M_F_CPU0_SB_DQS_DP<0>")
	)
	(segment
		(start 406.399746 -227.210874)
		(end 406.123648 -227.210874)
		(width 0.18288)
		(layer "In4.Cu")
		(net "M_F_CPU0_SB_DQS_DP<0>")
	)
	(arc
		(start 380.528322 -237.907322)
		(mid 380.24989 -237.977168)
		(end 379.973078 -237.901226)
		(width 0.088646)
		(layer "In4.Cu")
		(net "M_F_CPU0_SB_DQS_DP<0>")
	)
	(arc
		(start 379.033278 -237.901226)
		(mid 378.84608 -237.851083)
		(end 378.658882 -237.901226)
		(width 0.088646)
		(layer "In4.Cu")
		(net "M_F_CPU0_SB_DQS_DP<0>")
	)
	(arc
		(start 379.58395 -237.909862)
		(mid 379.307475 -237.977182)
		(end 379.033278 -237.901226)
		(width 0.088646)
		(layer "In4.Cu")
		(net "M_F_CPU0_SB_DQS_DP<0>")
	)
	(arc
		(start 380.913132 -237.901226)
		(mid 380.725934 -237.851083)
		(end 380.538736 -237.901226)
		(width 0.088646)
		(layer "In4.Cu")
		(net "M_F_CPU0_SB_DQS_DP<0>")
	)
	(arc
		(start 384.672332 -237.901226)
		(mid 384.485134 -237.851083)
		(end 384.297936 -237.901226)
		(width 0.088646)
		(layer "In4.Cu")
		(net "M_F_CPU0_SB_DQS_DP<0>")
	)
	(arc
		(start 378.093478 -237.901226)
		(mid 377.909887 -237.731091)
		(end 377.817634 -237.498382)
		(width 0.088646)
		(layer "In4.Cu")
		(net "M_F_CPU0_SB_DQS_DP<0>")
	)
	(arc
		(start 382.418336 -237.901226)
		(mid 382.135634 -237.977002)
		(end 381.852932 -237.901226)
		(width 0.088646)
		(layer "In4.Cu")
		(net "M_F_CPU0_SB_DQS_DP<0>")
	)
	(arc
		(start 387.304788 -237.850172)
		(mid 387.207707 -237.863368)
		(end 387.117336 -237.901226)
		(width 0.088646)
		(layer "In4.Cu")
		(net "M_F_CPU0_SB_DQS_DP<0>")
	)
	(arc
		(start 384.297936 -237.901226)
		(mid 384.015234 -237.976968)
		(end 383.732532 -237.901226)
		(width 0.088646)
		(layer "In4.Cu")
		(net "M_F_CPU0_SB_DQS_DP<0>")
	)
	(arc
		(start 382.792732 -237.901226)
		(mid 382.605534 -237.851083)
		(end 382.418336 -237.901226)
		(width 0.088646)
		(layer "In4.Cu")
		(net "M_F_CPU0_SB_DQS_DP<0>")
	)
	(arc
		(start 383.358136 -237.901226)
		(mid 383.075434 -237.977002)
		(end 382.792732 -237.901226)
		(width 0.088646)
		(layer "In4.Cu")
		(net "M_F_CPU0_SB_DQS_DP<0>")
	)
	(arc
		(start 378.64415 -237.909862)
		(mid 378.367675 -237.977182)
		(end 378.093478 -237.901226)
		(width 0.088646)
		(layer "In4.Cu")
		(net "M_F_CPU0_SB_DQS_DP<0>")
	)
	(arc
		(start 385.612132 -237.901226)
		(mid 385.424934 -237.851083)
		(end 385.237736 -237.901226)
		(width 0.088646)
		(layer "In4.Cu")
		(net "M_F_CPU0_SB_DQS_DP<0>")
	)
	(arc
		(start 381.852932 -237.901226)
		(mid 381.665734 -237.851083)
		(end 381.478536 -237.901226)
		(width 0.088646)
		(layer "In4.Cu")
		(net "M_F_CPU0_SB_DQS_DP<0>")
	)
	(arc
		(start 383.732532 -237.901226)
		(mid 383.545334 -237.851083)
		(end 383.358136 -237.901226)
		(width 0.088646)
		(layer "In4.Cu")
		(net "M_F_CPU0_SB_DQS_DP<0>")
	)
	(arc
		(start 381.478536 -237.901226)
		(mid 381.204337 -237.977061)
		(end 380.927864 -237.909862)
		(width 0.088646)
		(layer "In4.Cu")
		(net "M_F_CPU0_SB_DQS_DP<0>")
	)
	(arc
		(start 386.551932 -237.901226)
		(mid 386.364734 -237.851083)
		(end 386.177536 -237.901226)
		(width 0.088646)
		(layer "In4.Cu")
		(net "M_F_CPU0_SB_DQS_DP<0>")
	)
	(arc
		(start 387.117336 -237.901226)
		(mid 386.834634 -237.976968)
		(end 386.551932 -237.901226)
		(width 0.088646)
		(layer "In4.Cu")
		(net "M_F_CPU0_SB_DQS_DP<0>")
	)
	(arc
		(start 379.973078 -237.901226)
		(mid 379.78588 -237.851083)
		(end 379.598682 -237.901226)
		(width 0.088646)
		(layer "In4.Cu")
		(net "M_F_CPU0_SB_DQS_DP<0>")
	)
	(arc
		(start 386.177536 -237.901226)
		(mid 385.894834 -237.976968)
		(end 385.612132 -237.901226)
		(width 0.088646)
		(layer "In4.Cu")
		(net "M_F_CPU0_SB_DQS_DP<0>")
	)
	(arc
		(start 377.817634 -237.498382)
		(mid 377.816138 -237.487854)
		(end 377.81484 -237.4773)
		(width 0.088646)
		(layer "In4.Cu")
		(net "M_F_CPU0_SB_DQS_DP<0>")
	)
	(arc
		(start 385.237736 -237.901226)
		(mid 384.955034 -237.976968)
		(end 384.672332 -237.901226)
		(width 0.088646)
		(layer "In4.Cu")
		(net "M_F_CPU0_SB_DQS_DP<0>")
	)
	(segment
		(start 428.795434 -237.266734)
		(end 429.384714 -237.266734)
		(width 0.20066)
		(layer "F.Cu")
		(net "M_F_CPU0_SB_DQS_DN<9>")
	)
	(segment
		(start 381.665734 -240.389156)
		(end 381.665734 -239.853216)
		(width 0.20066)
		(layer "F.Cu")
		(net "M_F_CPU0_SB_DQS_DN<9>")
	)
	(segment
		(start 421.840914 -237.266734)
		(end 422.389554 -237.266734)
		(width 0.20066)
		(layer "F.Cu")
		(net "M_F_CPU0_SB_DQS_DN<9>")
	)
	(segment
		(start 424.762168 -237.691676)
		(end 424.766486 -237.691676)
		(width 0.101854)
		(layer "F.Cu")
		(net "M_F_CPU0_SB_DQS_DN<9>")
	)
	(segment
		(start 427.506892 -237.917736)
		(end 427.811946 -237.917736)
		(width 0.20066)
		(layer "F.Cu")
		(net "M_F_CPU0_SB_DQS_DN<9>")
	)
	(segment
		(start 424.343322 -237.962948)
		(end 424.614594 -237.691676)
		(width 0.20066)
		(layer "F.Cu")
		(net "M_F_CPU0_SB_DQS_DN<9>")
	)
	(segment
		(start 422.389554 -237.266734)
		(end 422.67124 -237.54842)
		(width 0.20066)
		(layer "F.Cu")
		(net "M_F_CPU0_SB_DQS_DN<9>")
	)
	(segment
		(start 424.766486 -237.691676)
		(end 426.94606 -237.691676)
		(width 0.1016)
		(layer "F.Cu")
		(net "M_F_CPU0_SB_DQS_DN<9>")
	)
	(segment
		(start 423.821606 -237.962948)
		(end 424.343322 -237.962948)
		(width 0.20066)
		(layer "F.Cu")
		(net "M_F_CPU0_SB_DQS_DN<9>")
	)
	(segment
		(start 428.554896 -237.507272)
		(end 428.795434 -237.266734)
		(width 0.20066)
		(layer "F.Cu")
		(net "M_F_CPU0_SB_DQS_DN<9>")
	)
	(segment
		(start 427.275498 -237.686342)
		(end 427.506892 -237.917736)
		(width 0.20066)
		(layer "F.Cu")
		(net "M_F_CPU0_SB_DQS_DN<9>")
	)
	(segment
		(start 422.67124 -237.54842)
		(end 423.407078 -237.54842)
		(width 0.20066)
		(layer "F.Cu")
		(net "M_F_CPU0_SB_DQS_DN<9>")
	)
	(segment
		(start 428.22241 -237.507272)
		(end 428.554896 -237.507272)
		(width 0.20066)
		(layer "F.Cu")
		(net "M_F_CPU0_SB_DQS_DN<9>")
	)
	(segment
		(start 423.407078 -237.54842)
		(end 423.821606 -237.962948)
		(width 0.20066)
		(layer "F.Cu")
		(net "M_F_CPU0_SB_DQS_DN<9>")
	)
	(segment
		(start 424.614594 -237.691676)
		(end 424.762168 -237.691676)
		(width 0.20066)
		(layer "F.Cu")
		(net "M_F_CPU0_SB_DQS_DN<9>")
	)
	(segment
		(start 426.94606 -237.691676)
		(end 426.951394 -237.686342)
		(width 0.1016)
		(layer "F.Cu")
		(net "M_F_CPU0_SB_DQS_DN<9>")
	)
	(segment
		(start 420.736014 -237.266734)
		(end 421.840914 -237.266734)
		(width 0.20066)
		(layer "F.Cu")
		(net "M_F_CPU0_SB_DQS_DN<9>")
	)
	(segment
		(start 426.951394 -237.686342)
		(end 427.275498 -237.686342)
		(width 0.20066)
		(layer "F.Cu")
		(net "M_F_CPU0_SB_DQS_DN<9>")
	)
	(segment
		(start 427.811946 -237.917736)
		(end 428.22241 -237.507272)
		(width 0.20066)
		(layer "F.Cu")
		(net "M_F_CPU0_SB_DQS_DN<9>")
	)
	(segment
		(start 382.418082 -240.177574)
		(end 382.407668 -240.171478)
		(width 0.088646)
		(layer "In2.Cu")
		(net "M_F_CPU0_SB_DQS_DN<9>")
	)
	(segment
		(start 417.769802 -237.746794)
		(end 417.661598 -237.63859)
		(width 0.18288)
		(layer "In2.Cu")
		(net "M_F_CPU0_SB_DQS_DN<9>")
	)
	(segment
		(start 409.893516 -237.431326)
		(end 409.893516 -237.415578)
		(width 0.16002)
		(layer "In2.Cu")
		(net "M_F_CPU0_SB_DQS_DN<9>")
	)
	(segment
		(start 405.838914 -238.334042)
		(end 405.838914 -238.318294)
		(width 0.16002)
		(layer "In2.Cu")
		(net "M_F_CPU0_SB_DQS_DN<9>")
	)
	(segment
		(start 412.11119 -237.13821)
		(end 411.84957 -237.39983)
		(width 0.18288)
		(layer "In2.Cu")
		(net "M_F_CPU0_SB_DQS_DN<9>")
	)
	(segment
		(start 419.317678 -237.455202)
		(end 419.317678 -237.47095)
		(width 0.16002)
		(layer "In2.Cu")
		(net "M_F_CPU0_SB_DQS_DN<9>")
	)
	(segment
		(start 420.328598 -237.532672)
		(end 420.051484 -237.255558)
		(width 0.18288)
		(layer "In2.Cu")
		(net "M_F_CPU0_SB_DQS_DN<9>")
	)
	(segment
		(start 417.661598 -237.63859)
		(end 417.633404 -237.610396)
		(width 0.16002)
		(layer "In2.Cu")
		(net "M_F_CPU0_SB_DQS_DN<9>")
	)
	(segment
		(start 417.432998 -237.40999)
		(end 417.404804 -237.381796)
		(width 0.16002)
		(layer "In2.Cu")
		(net "M_F_CPU0_SB_DQS_DN<9>")
	)
	(segment
		(start 417.617656 -237.610396)
		(end 417.432998 -237.425738)
		(width 0.16002)
		(layer "In2.Cu")
		(net "M_F_CPU0_SB_DQS_DN<9>")
	)
	(segment
		(start 415.154872 -236.578648)
		(end 415.126678 -236.550454)
		(width 0.16002)
		(layer "In2.Cu")
		(net "M_F_CPU0_SB_DQS_DN<9>")
	)
	(segment
		(start 387.982968 -241.494056)
		(end 387.595364 -241.654584)
		(width 0.088646)
		(layer "In2.Cu")
		(net "M_F_CPU0_SB_DQS_DN<9>")
	)
	(segment
		(start 415.126678 -236.550454)
		(end 414.894014 -236.31779)
		(width 0.18288)
		(layer "In2.Cu")
		(net "M_F_CPU0_SB_DQS_DN<9>")
	)
	(segment
		(start 415.355278 -236.779054)
		(end 415.339022 -236.779054)
		(width 0.16002)
		(layer "In2.Cu")
		(net "M_F_CPU0_SB_DQS_DN<9>")
	)
	(segment
		(start 384.297682 -240.177574)
		(end 384.287268 -240.171478)
		(width 0.088646)
		(layer "In2.Cu")
		(net "M_F_CPU0_SB_DQS_DN<9>")
	)
	(segment
		(start 383.357628 -240.178082)
		(end 383.358136 -240.177574)
		(width 0.088646)
		(layer "In2.Cu")
		(net "M_F_CPU0_SB_DQS_DN<9>")
	)
	(segment
		(start 420.051484 -237.255558)
		(end 419.517322 -237.255558)
		(width 0.18288)
		(layer "In2.Cu")
		(net "M_F_CPU0_SB_DQS_DN<9>")
	)
	(segment
		(start 409.71216 -237.234222)
		(end 409.177744 -237.234222)
		(width 0.18288)
		(layer "In2.Cu")
		(net "M_F_CPU0_SB_DQS_DN<9>")
	)
	(segment
		(start 399.834862 -241.434366)
		(end 399.710402 -241.309906)
		(width 0.18288)
		(layer "In2.Cu")
		(net "M_F_CPU0_SB_DQS_DN<9>")
	)
	(segment
		(start 415.339022 -236.779054)
		(end 415.154872 -236.594904)
		(width 0.16002)
		(layer "In2.Cu")
		(net "M_F_CPU0_SB_DQS_DN<9>")
	)
	(segment
		(start 399.037302 -241.434366)
		(end 388.458964 -241.434366)
		(width 0.18288)
		(layer "In2.Cu")
		(net "M_F_CPU0_SB_DQS_DN<9>")
	)
	(segment
		(start 383.732532 -240.177574)
		(end 383.73304 -240.178082)
		(width 0.088646)
		(layer "In2.Cu")
		(net "M_F_CPU0_SB_DQS_DN<9>")
	)
	(segment
		(start 417.15817 -237.135162)
		(end 415.711386 -237.135162)
		(width 0.18288)
		(layer "In2.Cu")
		(net "M_F_CPU0_SB_DQS_DN<9>")
	)
	(segment
		(start 410.122116 -237.644178)
		(end 410.093922 -237.615984)
		(width 0.16002)
		(layer "In2.Cu")
		(net "M_F_CPU0_SB_DQS_DN<9>")
	)
	(segment
		(start 415.154872 -236.594904)
		(end 415.154872 -236.578648)
		(width 0.16002)
		(layer "In2.Cu")
		(net "M_F_CPU0_SB_DQS_DN<9>")
	)
	(segment
		(start 386.106924 -241.654584)
		(end 385.98983 -241.53749)
		(width 0.088646)
		(layer "In2.Cu")
		(net "M_F_CPU0_SB_DQS_DN<9>")
	)
	(segment
		(start 405.62657 -238.10595)
		(end 405.058118 -238.10595)
		(width 0.18288)
		(layer "In2.Cu")
		(net "M_F_CPU0_SB_DQS_DN<9>")
	)
	(segment
		(start 406.021794 -238.501174)
		(end 405.9936 -238.47298)
		(width 0.16002)
		(layer "In2.Cu")
		(net "M_F_CPU0_SB_DQS_DN<9>")
	)
	(segment
		(start 413.13227 -236.885988)
		(end 413.116014 -236.885988)
		(width 0.16002)
		(layer "In2.Cu")
		(net "M_F_CPU0_SB_DQS_DN<9>")
	)
	(segment
		(start 413.684212 -236.31779)
		(end 413.344614 -236.657388)
		(width 0.18288)
		(layer "In2.Cu")
		(net "M_F_CPU0_SB_DQS_DN<9>")
	)
	(segment
		(start 419.162992 -237.609888)
		(end 419.134798 -237.638082)
		(width 0.16002)
		(layer "In2.Cu")
		(net "M_F_CPU0_SB_DQS_DN<9>")
	)
	(segment
		(start 381.478536 -240.177574)
		(end 381.469646 -240.172494)
		(width 0.088646)
		(layer "In2.Cu")
		(net "M_F_CPU0_SB_DQS_DN<9>")
	)
	(segment
		(start 410.233368 -237.75543)
		(end 410.122116 -237.644178)
		(width 0.18288)
		(layer "In2.Cu")
		(net "M_F_CPU0_SB_DQS_DN<9>")
	)
	(segment
		(start 385.98983 -241.53749)
		(end 385.98983 -241.481102)
		(width 0.088646)
		(layer "In2.Cu")
		(net "M_F_CPU0_SB_DQS_DN<9>")
	)
	(segment
		(start 419.317678 -237.47095)
		(end 419.17874 -237.609888)
		(width 0.16002)
		(layer "In2.Cu")
		(net "M_F_CPU0_SB_DQS_DN<9>")
	)
	(segment
		(start 413.116014 -236.885988)
		(end 413.08782 -236.914182)
		(width 0.16002)
		(layer "In2.Cu")
		(net "M_F_CPU0_SB_DQS_DN<9>")
	)
	(segment
		(start 419.345872 -237.427008)
		(end 419.317678 -237.455202)
		(width 0.16002)
		(layer "In2.Cu")
		(net "M_F_CPU0_SB_DQS_DN<9>")
	)
	(segment
		(start 381.352806 -239.853216)
		(end 381.665734 -239.853216)
		(width 0.088646)
		(layer "In2.Cu")
		(net "M_F_CPU0_SB_DQS_DN<9>")
	)
	(segment
		(start 413.344614 -236.657388)
		(end 413.31642 -236.685582)
		(width 0.16002)
		(layer "In2.Cu")
		(net "M_F_CPU0_SB_DQS_DN<9>")
	)
	(segment
		(start 401.056602 -241.309906)
		(end 400.507962 -241.309906)
		(width 0.18288)
		(layer "In2.Cu")
		(net "M_F_CPU0_SB_DQS_DN<9>")
	)
	(segment
		(start 411.821376 -237.443772)
		(end 411.636718 -237.62843)
		(width 0.16002)
		(layer "In2.Cu")
		(net "M_F_CPU0_SB_DQS_DN<9>")
	)
	(segment
		(start 388.399274 -241.494056)
		(end 387.982968 -241.494056)
		(width 0.088646)
		(layer "In2.Cu")
		(net "M_F_CPU0_SB_DQS_DN<9>")
	)
	(segment
		(start 409.177744 -237.234222)
		(end 408.702002 -237.709964)
		(width 0.18288)
		(layer "In2.Cu")
		(net "M_F_CPU0_SB_DQS_DN<9>")
	)
	(segment
		(start 413.31642 -236.701838)
		(end 413.13227 -236.885988)
		(width 0.16002)
		(layer "In2.Cu")
		(net "M_F_CPU0_SB_DQS_DN<9>")
	)
	(segment
		(start 409.865322 -237.387384)
		(end 409.71216 -237.234222)
		(width 0.18288)
		(layer "In2.Cu")
		(net "M_F_CPU0_SB_DQS_DN<9>")
	)
	(segment
		(start 420.53764 -237.532672)
		(end 420.328598 -237.532672)
		(width 0.18288)
		(layer "In2.Cu")
		(net "M_F_CPU0_SB_DQS_DN<9>")
	)
	(segment
		(start 405.9936 -238.47298)
		(end 405.977852 -238.47298)
		(width 0.16002)
		(layer "In2.Cu")
		(net "M_F_CPU0_SB_DQS_DN<9>")
	)
	(segment
		(start 405.838914 -238.318294)
		(end 405.81072 -238.2901)
		(width 0.16002)
		(layer "In2.Cu")
		(net "M_F_CPU0_SB_DQS_DN<9>")
	)
	(segment
		(start 405.058118 -238.10595)
		(end 401.729702 -241.434366)
		(width 0.18288)
		(layer "In2.Cu")
		(net "M_F_CPU0_SB_DQS_DN<9>")
	)
	(segment
		(start 415.711386 -237.135162)
		(end 415.383472 -236.807248)
		(width 0.18288)
		(layer "In2.Cu")
		(net "M_F_CPU0_SB_DQS_DN<9>")
	)
	(segment
		(start 400.507962 -241.309906)
		(end 400.383502 -241.434366)
		(width 0.18288)
		(layer "In2.Cu")
		(net "M_F_CPU0_SB_DQS_DN<9>")
	)
	(segment
		(start 419.134798 -237.638082)
		(end 419.026086 -237.746794)
		(width 0.18288)
		(layer "In2.Cu")
		(net "M_F_CPU0_SB_DQS_DN<9>")
	)
	(segment
		(start 385.717796 -240.997994)
		(end 385.71805 -240.99774)
		(width 0.088646)
		(layer "In2.Cu")
		(net "M_F_CPU0_SB_DQS_DN<9>")
	)
	(segment
		(start 399.161762 -241.309906)
		(end 399.037302 -241.434366)
		(width 0.18288)
		(layer "In2.Cu")
		(net "M_F_CPU0_SB_DQS_DN<9>")
	)
	(segment
		(start 409.893516 -237.415578)
		(end 409.865322 -237.387384)
		(width 0.16002)
		(layer "In2.Cu")
		(net "M_F_CPU0_SB_DQS_DN<9>")
	)
	(segment
		(start 411.592776 -237.656624)
		(end 411.49397 -237.75543)
		(width 0.18288)
		(layer "In2.Cu")
		(net "M_F_CPU0_SB_DQS_DN<9>")
	)
	(segment
		(start 412.863792 -237.13821)
		(end 412.11119 -237.13821)
		(width 0.18288)
		(layer "In2.Cu")
		(net "M_F_CPU0_SB_DQS_DN<9>")
	)
	(segment
		(start 417.633404 -237.610396)
		(end 417.617656 -237.610396)
		(width 0.16002)
		(layer "In2.Cu")
		(net "M_F_CPU0_SB_DQS_DN<9>")
	)
	(segment
		(start 411.821376 -237.428024)
		(end 411.821376 -237.443772)
		(width 0.16002)
		(layer "In2.Cu")
		(net "M_F_CPU0_SB_DQS_DN<9>")
	)
	(segment
		(start 381.295656 -239.910366)
		(end 381.352806 -239.853216)
		(width 0.088646)
		(layer "In2.Cu")
		(net "M_F_CPU0_SB_DQS_DN<9>")
	)
	(segment
		(start 415.383472 -236.807248)
		(end 415.355278 -236.779054)
		(width 0.16002)
		(layer "In2.Cu")
		(net "M_F_CPU0_SB_DQS_DN<9>")
	)
	(segment
		(start 419.17874 -237.609888)
		(end 419.162992 -237.609888)
		(width 0.16002)
		(layer "In2.Cu")
		(net "M_F_CPU0_SB_DQS_DN<9>")
	)
	(segment
		(start 401.729702 -241.434366)
		(end 401.181062 -241.434366)
		(width 0.18288)
		(layer "In2.Cu")
		(net "M_F_CPU0_SB_DQS_DN<9>")
	)
	(segment
		(start 419.026086 -237.746794)
		(end 417.769802 -237.746794)
		(width 0.18288)
		(layer "In2.Cu")
		(net "M_F_CPU0_SB_DQS_DN<9>")
	)
	(segment
		(start 413.08782 -236.914182)
		(end 412.863792 -237.13821)
		(width 0.18288)
		(layer "In2.Cu")
		(net "M_F_CPU0_SB_DQS_DN<9>")
	)
	(segment
		(start 384.580384 -240.667286)
		(end 384.580384 -240.653062)
		(width 0.088646)
		(layer "In2.Cu")
		(net "M_F_CPU0_SB_DQS_DN<9>")
	)
	(segment
		(start 420.736014 -237.266734)
		(end 420.736014 -237.334298)
		(width 0.18288)
		(layer "In2.Cu")
		(net "M_F_CPU0_SB_DQS_DN<9>")
	)
	(segment
		(start 411.636718 -237.62843)
		(end 411.62097 -237.62843)
		(width 0.16002)
		(layer "In2.Cu")
		(net "M_F_CPU0_SB_DQS_DN<9>")
	)
	(segment
		(start 417.404804 -237.381796)
		(end 417.15817 -237.135162)
		(width 0.18288)
		(layer "In2.Cu")
		(net "M_F_CPU0_SB_DQS_DN<9>")
	)
	(segment
		(start 405.81072 -238.2901)
		(end 405.62657 -238.10595)
		(width 0.18288)
		(layer "In2.Cu")
		(net "M_F_CPU0_SB_DQS_DN<9>")
	)
	(segment
		(start 411.62097 -237.62843)
		(end 411.592776 -237.656624)
		(width 0.16002)
		(layer "In2.Cu")
		(net "M_F_CPU0_SB_DQS_DN<9>")
	)
	(segment
		(start 408.702002 -237.709964)
		(end 407.670508 -238.399574)
		(width 0.18288)
		(layer "In2.Cu")
		(net "M_F_CPU0_SB_DQS_DN<9>")
	)
	(segment
		(start 406.10663 -238.58601)
		(end 406.021794 -238.501174)
		(width 0.18288)
		(layer "In2.Cu")
		(net "M_F_CPU0_SB_DQS_DN<9>")
	)
	(segment
		(start 410.078174 -237.615984)
		(end 409.893516 -237.431326)
		(width 0.16002)
		(layer "In2.Cu")
		(net "M_F_CPU0_SB_DQS_DN<9>")
	)
	(segment
		(start 405.977852 -238.47298)
		(end 405.838914 -238.334042)
		(width 0.16002)
		(layer "In2.Cu")
		(net "M_F_CPU0_SB_DQS_DN<9>")
	)
	(segment
		(start 414.894014 -236.31779)
		(end 413.684212 -236.31779)
		(width 0.18288)
		(layer "In2.Cu")
		(net "M_F_CPU0_SB_DQS_DN<9>")
	)
	(segment
		(start 383.358136 -240.177574)
		(end 383.347722 -240.171478)
		(width 0.088646)
		(layer "In2.Cu")
		(net "M_F_CPU0_SB_DQS_DN<9>")
	)
	(segment
		(start 384.767836 -240.991644)
		(end 384.758946 -240.986564)
		(width 0.088646)
		(layer "In2.Cu")
		(net "M_F_CPU0_SB_DQS_DN<9>")
	)
	(segment
		(start 413.31642 -236.685582)
		(end 413.31642 -236.701838)
		(width 0.16002)
		(layer "In2.Cu")
		(net "M_F_CPU0_SB_DQS_DN<9>")
	)
	(segment
		(start 388.458964 -241.434366)
		(end 388.399274 -241.494056)
		(width 0.088646)
		(layer "In2.Cu")
		(net "M_F_CPU0_SB_DQS_DN<9>")
	)
	(segment
		(start 401.181062 -241.434366)
		(end 401.056602 -241.309906)
		(width 0.18288)
		(layer "In2.Cu")
		(net "M_F_CPU0_SB_DQS_DN<9>")
	)
	(segment
		(start 417.432998 -237.425738)
		(end 417.432998 -237.40999)
		(width 0.16002)
		(layer "In2.Cu")
		(net "M_F_CPU0_SB_DQS_DN<9>")
	)
	(segment
		(start 407.670508 -238.399574)
		(end 407.484072 -238.58601)
		(width 0.18288)
		(layer "In2.Cu")
		(net "M_F_CPU0_SB_DQS_DN<9>")
	)
	(segment
		(start 411.84957 -237.39983)
		(end 411.821376 -237.428024)
		(width 0.16002)
		(layer "In2.Cu")
		(net "M_F_CPU0_SB_DQS_DN<9>")
	)
	(segment
		(start 411.49397 -237.75543)
		(end 410.233368 -237.75543)
		(width 0.18288)
		(layer "In2.Cu")
		(net "M_F_CPU0_SB_DQS_DN<9>")
	)
	(segment
		(start 400.383502 -241.434366)
		(end 399.834862 -241.434366)
		(width 0.18288)
		(layer "In2.Cu")
		(net "M_F_CPU0_SB_DQS_DN<9>")
	)
	(segment
		(start 387.595364 -241.654584)
		(end 386.106924 -241.654584)
		(width 0.088646)
		(layer "In2.Cu")
		(net "M_F_CPU0_SB_DQS_DN<9>")
	)
	(segment
		(start 420.736014 -237.334298)
		(end 420.53764 -237.532672)
		(width 0.18288)
		(layer "In2.Cu")
		(net "M_F_CPU0_SB_DQS_DN<9>")
	)
	(segment
		(start 419.517322 -237.255558)
		(end 419.345872 -237.427008)
		(width 0.18288)
		(layer "In2.Cu")
		(net "M_F_CPU0_SB_DQS_DN<9>")
	)
	(segment
		(start 399.710402 -241.309906)
		(end 399.161762 -241.309906)
		(width 0.18288)
		(layer "In2.Cu")
		(net "M_F_CPU0_SB_DQS_DN<9>")
	)
	(segment
		(start 407.484072 -238.58601)
		(end 406.10663 -238.58601)
		(width 0.18288)
		(layer "In2.Cu")
		(net "M_F_CPU0_SB_DQS_DN<9>")
	)
	(segment
		(start 410.093922 -237.615984)
		(end 410.078174 -237.615984)
		(width 0.16002)
		(layer "In2.Cu")
		(net "M_F_CPU0_SB_DQS_DN<9>")
	)
	(arc
		(start 381.852932 -240.177574)
		(mid 381.665734 -240.227717)
		(end 381.478536 -240.177574)
		(width 0.088646)
		(layer "In2.Cu")
		(net "M_F_CPU0_SB_DQS_DN<9>")
	)
	(arc
		(start 385.71805 -240.99774)
		(mid 385.71286 -240.994663)
		(end 385.707636 -240.991644)
		(width 0.088646)
		(layer "In2.Cu")
		(net "M_F_CPU0_SB_DQS_DN<9>")
	)
	(arc
		(start 382.407668 -240.171478)
		(mid 382.12949 -240.101786)
		(end 381.852932 -240.177574)
		(width 0.088646)
		(layer "In2.Cu")
		(net "M_F_CPU0_SB_DQS_DN<9>")
	)
	(arc
		(start 382.792478 -240.177574)
		(mid 382.60528 -240.227717)
		(end 382.418082 -240.177574)
		(width 0.088646)
		(layer "In2.Cu")
		(net "M_F_CPU0_SB_DQS_DN<9>")
	)
	(arc
		(start 381.469646 -240.172494)
		(mid 381.353837 -240.060565)
		(end 381.295656 -239.910366)
		(width 0.088646)
		(layer "In2.Cu")
		(net "M_F_CPU0_SB_DQS_DN<9>")
	)
	(arc
		(start 384.580384 -240.653062)
		(mid 384.501165 -240.378377)
		(end 384.297682 -240.177574)
		(width 0.088646)
		(layer "In2.Cu")
		(net "M_F_CPU0_SB_DQS_DN<9>")
	)
	(arc
		(start 385.98983 -241.481102)
		(mid 385.917138 -241.203897)
		(end 385.717796 -240.997994)
		(width 0.088646)
		(layer "In2.Cu")
		(net "M_F_CPU0_SB_DQS_DN<9>")
	)
	(arc
		(start 383.347722 -240.171478)
		(mid 383.06929 -240.101664)
		(end 382.792478 -240.177574)
		(width 0.088646)
		(layer "In2.Cu")
		(net "M_F_CPU0_SB_DQS_DN<9>")
	)
	(arc
		(start 384.758946 -240.986564)
		(mid 384.628032 -240.850204)
		(end 384.580384 -240.667286)
		(width 0.088646)
		(layer "In2.Cu")
		(net "M_F_CPU0_SB_DQS_DN<9>")
	)
	(arc
		(start 385.707636 -240.991644)
		(mid 385.424934 -240.915868)
		(end 385.142232 -240.991644)
		(width 0.088646)
		(layer "In2.Cu")
		(net "M_F_CPU0_SB_DQS_DN<9>")
	)
	(arc
		(start 385.142232 -240.991644)
		(mid 384.955034 -241.041787)
		(end 384.767836 -240.991644)
		(width 0.088646)
		(layer "In2.Cu")
		(net "M_F_CPU0_SB_DQS_DN<9>")
	)
	(arc
		(start 384.287268 -240.171478)
		(mid 384.00909 -240.101786)
		(end 383.732532 -240.177574)
		(width 0.088646)
		(layer "In2.Cu")
		(net "M_F_CPU0_SB_DQS_DN<9>")
	)
	(arc
		(start 383.73304 -240.178082)
		(mid 383.545334 -240.228411)
		(end 383.357628 -240.178082)
		(width 0.088646)
		(layer "In2.Cu")
		(net "M_F_CPU0_SB_DQS_DN<9>")
	)
	(segment
		(start 425.940982 -199.866758)
		(end 426.471588 -199.866758)
		(width 0.20066)
		(layer "F.Cu")
		(net "M_F_CPU0_SB_DQS_DN<8>")
	)
	(segment
		(start 426.74286 -199.595486)
		(end 427.226222 -199.595486)
		(width 0.20066)
		(layer "F.Cu")
		(net "M_F_CPU0_SB_DQS_DN<8>")
	)
	(segment
		(start 428.05096 -199.447912)
		(end 428.363126 -199.447912)
		(width 0.20066)
		(layer "F.Cu")
		(net "M_F_CPU0_SB_DQS_DN<8>")
	)
	(segment
		(start 428.374048 -199.441816)
		(end 430.384204 -199.441816)
		(width 0.1016)
		(layer "F.Cu")
		(net "M_F_CPU0_SB_DQS_DN<8>")
	)
	(segment
		(start 379.316234 -228.180646)
		(end 379.316234 -227.64496)
		(width 0.20066)
		(layer "F.Cu")
		(net "M_F_CPU0_SB_DQS_DN<8>")
	)
	(segment
		(start 424.836082 -199.866758)
		(end 425.940982 -199.866758)
		(width 0.20066)
		(layer "F.Cu")
		(net "M_F_CPU0_SB_DQS_DN<8>")
	)
	(segment
		(start 432.9811 -199.866758)
		(end 433.484782 -199.866758)
		(width 0.20066)
		(layer "F.Cu")
		(net "M_F_CPU0_SB_DQS_DN<8>")
	)
	(segment
		(start 427.651164 -199.170544)
		(end 427.773592 -199.170544)
		(width 0.20066)
		(layer "F.Cu")
		(net "M_F_CPU0_SB_DQS_DN<8>")
	)
	(segment
		(start 427.773592 -199.170544)
		(end 428.05096 -199.447912)
		(width 0.20066)
		(layer "F.Cu")
		(net "M_F_CPU0_SB_DQS_DN<8>")
	)
	(segment
		(start 426.471588 -199.866758)
		(end 426.74286 -199.595486)
		(width 0.20066)
		(layer "F.Cu")
		(net "M_F_CPU0_SB_DQS_DN<8>")
	)
	(segment
		(start 379.31598 -228.1809)
		(end 379.316234 -228.180646)
		(width 0.20066)
		(layer "F.Cu")
		(net "M_F_CPU0_SB_DQS_DN<8>")
	)
	(segment
		(start 430.395126 -199.452738)
		(end 430.713896 -199.452738)
		(width 0.20066)
		(layer "F.Cu")
		(net "M_F_CPU0_SB_DQS_DN<8>")
	)
	(segment
		(start 428.363126 -199.447912)
		(end 428.367952 -199.447912)
		(width 0.101854)
		(layer "F.Cu")
		(net "M_F_CPU0_SB_DQS_DN<8>")
	)
	(segment
		(start 432.726846 -199.612504)
		(end 432.9811 -199.866758)
		(width 0.20066)
		(layer "F.Cu")
		(net "M_F_CPU0_SB_DQS_DN<8>")
	)
	(segment
		(start 430.999646 -199.166988)
		(end 431.489612 -199.166988)
		(width 0.20066)
		(layer "F.Cu")
		(net "M_F_CPU0_SB_DQS_DN<8>")
	)
	(segment
		(start 431.935128 -199.612504)
		(end 432.726846 -199.612504)
		(width 0.20066)
		(layer "F.Cu")
		(net "M_F_CPU0_SB_DQS_DN<8>")
	)
	(segment
		(start 428.367952 -199.447912)
		(end 428.374048 -199.441816)
		(width 0.1016)
		(layer "F.Cu")
		(net "M_F_CPU0_SB_DQS_DN<8>")
	)
	(segment
		(start 427.226222 -199.595486)
		(end 427.651164 -199.170544)
		(width 0.20066)
		(layer "F.Cu")
		(net "M_F_CPU0_SB_DQS_DN<8>")
	)
	(segment
		(start 430.384204 -199.441816)
		(end 430.395126 -199.452738)
		(width 0.1016)
		(layer "F.Cu")
		(net "M_F_CPU0_SB_DQS_DN<8>")
	)
	(segment
		(start 431.489612 -199.166988)
		(end 431.935128 -199.612504)
		(width 0.20066)
		(layer "F.Cu")
		(net "M_F_CPU0_SB_DQS_DN<8>")
	)
	(segment
		(start 430.713896 -199.452738)
		(end 430.999646 -199.166988)
		(width 0.20066)
		(layer "F.Cu")
		(net "M_F_CPU0_SB_DQS_DN<8>")
	)
	(segment
		(start 424.836082 -199.866758)
		(end 424.589194 -199.61987)
		(width 0.18288)
		(layer "In4.Cu")
		(net "M_F_CPU0_SB_DQS_DN<8>")
	)
	(segment
		(start 398.881854 -211.378292)
		(end 388.640574 -221.619572)
		(width 0.18288)
		(layer "In4.Cu")
		(net "M_F_CPU0_SB_DQS_DN<8>")
	)
	(segment
		(start 412.141162 -201.154792)
		(end 411.775402 -201.154792)
		(width 0.18288)
		(layer "In4.Cu")
		(net "M_F_CPU0_SB_DQS_DN<8>")
	)
	(segment
		(start 410.193744 -200.89241)
		(end 409.933902 -201.152252)
		(width 0.18288)
		(layer "In4.Cu")
		(net "M_F_CPU0_SB_DQS_DN<8>")
	)
	(segment
		(start 387.258052 -221.559628)
		(end 387.118606 -221.699074)
		(width 0.088646)
		(layer "In4.Cu")
		(net "M_F_CPU0_SB_DQS_DN<8>")
	)
	(segment
		(start 382.888236 -225.69297)
		(end 382.887474 -225.693478)
		(width 0.088646)
		(layer "In4.Cu")
		(net "M_F_CPU0_SB_DQS_DN<8>")
	)
	(segment
		(start 387.673342 -221.619572)
		(end 387.613398 -221.559628)
		(width 0.088646)
		(layer "In4.Cu")
		(net "M_F_CPU0_SB_DQS_DN<8>")
	)
	(segment
		(start 381.760984 -227.64496)
		(end 381.760984 -227.663502)
		(width 0.088646)
		(layer "In4.Cu")
		(net "M_F_CPU0_SB_DQS_DN<8>")
	)
	(segment
		(start 405.618442 -200.862692)
		(end 403.892258 -202.588876)
		(width 0.18288)
		(layer "In4.Cu")
		(net "M_F_CPU0_SB_DQS_DN<8>")
	)
	(segment
		(start 403.892258 -202.588876)
		(end 400.289522 -207.98028)
		(width 0.18288)
		(layer "In4.Cu")
		(net "M_F_CPU0_SB_DQS_DN<8>")
	)
	(segment
		(start 424.094148 -199.61987)
		(end 421.985694 -201.728324)
		(width 0.18288)
		(layer "In4.Cu")
		(net "M_F_CPU0_SB_DQS_DN<8>")
	)
	(segment
		(start 421.193976 -201.728324)
		(end 420.928292 -201.994008)
		(width 0.18288)
		(layer "In4.Cu")
		(net "M_F_CPU0_SB_DQS_DN<8>")
	)
	(segment
		(start 400.289522 -207.98028)
		(end 398.881854 -211.378292)
		(width 0.18288)
		(layer "In4.Cu")
		(net "M_F_CPU0_SB_DQS_DN<8>")
	)
	(segment
		(start 417.862258 -201.404982)
		(end 417.588954 -201.678286)
		(width 0.18288)
		(layer "In4.Cu")
		(net "M_F_CPU0_SB_DQS_DN<8>")
	)
	(segment
		(start 387.69671 -221.619572)
		(end 387.673342 -221.619572)
		(width 0.088646)
		(layer "In4.Cu")
		(net "M_F_CPU0_SB_DQS_DN<8>")
	)
	(segment
		(start 383.828036 -224.065084)
		(end 383.819146 -224.070164)
		(width 0.088646)
		(layer "In4.Cu")
		(net "M_F_CPU0_SB_DQS_DN<8>")
	)
	(segment
		(start 388.640574 -221.619572)
		(end 387.69671 -221.619572)
		(width 0.18288)
		(layer "In4.Cu")
		(net "M_F_CPU0_SB_DQS_DN<8>")
	)
	(segment
		(start 383.170684 -225.203258)
		(end 383.170684 -225.2218)
		(width 0.088646)
		(layer "In4.Cu")
		(net "M_F_CPU0_SB_DQS_DN<8>")
	)
	(segment
		(start 383.819146 -223.080834)
		(end 383.828036 -223.085914)
		(width 0.088646)
		(layer "In4.Cu")
		(net "M_F_CPU0_SB_DQS_DN<8>")
	)
	(segment
		(start 379.823218 -227.639626)
		(end 379.321568 -227.639626)
		(width 0.088646)
		(layer "In4.Cu")
		(net "M_F_CPU0_SB_DQS_DN<8>")
	)
	(segment
		(start 421.985694 -201.728324)
		(end 421.193976 -201.728324)
		(width 0.18288)
		(layer "In4.Cu")
		(net "M_F_CPU0_SB_DQS_DN<8>")
	)
	(segment
		(start 384.212846 -222.443294)
		(end 384.202432 -222.437198)
		(width 0.088646)
		(layer "In4.Cu")
		(net "M_F_CPU0_SB_DQS_DN<8>")
	)
	(segment
		(start 420.544244 -201.994008)
		(end 420.252652 -201.702416)
		(width 0.18288)
		(layer "In4.Cu")
		(net "M_F_CPU0_SB_DQS_DN<8>")
	)
	(segment
		(start 384.110484 -223.557084)
		(end 384.110484 -223.585532)
		(width 0.088646)
		(layer "In4.Cu")
		(net "M_F_CPU0_SB_DQS_DN<8>")
	)
	(segment
		(start 380.696724 -228.04247)
		(end 380.26213 -228.04247)
		(width 0.088646)
		(layer "In4.Cu")
		(net "M_F_CPU0_SB_DQS_DN<8>")
	)
	(segment
		(start 383.364232 -224.875344)
		(end 383.358136 -224.8789)
		(width 0.088646)
		(layer "In4.Cu")
		(net "M_F_CPU0_SB_DQS_DN<8>")
	)
	(segment
		(start 384.779774 -222.430086)
		(end 384.767582 -222.437198)
		(width 0.088646)
		(layer "In4.Cu")
		(net "M_F_CPU0_SB_DQS_DN<8>")
	)
	(segment
		(start 381.948436 -227.320602)
		(end 381.939546 -227.325682)
		(width 0.088646)
		(layer "In4.Cu")
		(net "M_F_CPU0_SB_DQS_DN<8>")
	)
	(segment
		(start 412.434532 -200.861422)
		(end 412.141162 -201.154792)
		(width 0.18288)
		(layer "In4.Cu")
		(net "M_F_CPU0_SB_DQS_DN<8>")
	)
	(segment
		(start 387.613398 -221.559628)
		(end 387.258052 -221.559628)
		(width 0.088646)
		(layer "In4.Cu")
		(net "M_F_CPU0_SB_DQS_DN<8>")
	)
	(segment
		(start 385.237736 -221.623382)
		(end 385.228846 -221.628462)
		(width 0.088646)
		(layer "In4.Cu")
		(net "M_F_CPU0_SB_DQS_DN<8>")
	)
	(segment
		(start 420.252652 -201.702416)
		(end 418.868352 -201.702416)
		(width 0.18288)
		(layer "In4.Cu")
		(net "M_F_CPU0_SB_DQS_DN<8>")
	)
	(segment
		(start 420.928292 -201.994008)
		(end 420.544244 -201.994008)
		(width 0.18288)
		(layer "In4.Cu")
		(net "M_F_CPU0_SB_DQS_DN<8>")
	)
	(segment
		(start 382.424178 -226.50323)
		(end 382.418844 -226.506278)
		(width 0.088646)
		(layer "In4.Cu")
		(net "M_F_CPU0_SB_DQS_DN<8>")
	)
	(segment
		(start 383.828036 -222.437198)
		(end 383.819146 -222.442278)
		(width 0.088646)
		(layer "In4.Cu")
		(net "M_F_CPU0_SB_DQS_DN<8>")
	)
	(segment
		(start 409.265374 -200.862692)
		(end 405.618442 -200.862692)
		(width 0.18288)
		(layer "In4.Cu")
		(net "M_F_CPU0_SB_DQS_DN<8>")
	)
	(segment
		(start 380.913132 -228.134672)
		(end 380.803404 -228.071172)
		(width 0.088646)
		(layer "In4.Cu")
		(net "M_F_CPU0_SB_DQS_DN<8>")
	)
	(segment
		(start 424.589194 -199.61987)
		(end 424.094148 -199.61987)
		(width 0.18288)
		(layer "In4.Cu")
		(net "M_F_CPU0_SB_DQS_DN<8>")
	)
	(segment
		(start 383.358136 -224.8789)
		(end 383.349246 -224.88398)
		(width 0.088646)
		(layer "In4.Cu")
		(net "M_F_CPU0_SB_DQS_DN<8>")
	)
	(segment
		(start 418.570918 -201.404982)
		(end 417.862258 -201.404982)
		(width 0.18288)
		(layer "In4.Cu")
		(net "M_F_CPU0_SB_DQS_DN<8>")
	)
	(segment
		(start 411.51302 -200.89241)
		(end 410.193744 -200.89241)
		(width 0.18288)
		(layer "In4.Cu")
		(net "M_F_CPU0_SB_DQS_DN<8>")
	)
	(segment
		(start 417.588954 -201.678286)
		(end 416.649154 -201.678286)
		(width 0.18288)
		(layer "In4.Cu")
		(net "M_F_CPU0_SB_DQS_DN<8>")
	)
	(segment
		(start 379.885956 -227.702364)
		(end 379.823218 -227.639626)
		(width 0.088646)
		(layer "In4.Cu")
		(net "M_F_CPU0_SB_DQS_DN<8>")
	)
	(segment
		(start 411.775402 -201.154792)
		(end 411.51302 -200.89241)
		(width 0.18288)
		(layer "In4.Cu")
		(net "M_F_CPU0_SB_DQS_DN<8>")
	)
	(segment
		(start 415.83229 -200.861422)
		(end 412.434532 -200.861422)
		(width 0.18288)
		(layer "In4.Cu")
		(net "M_F_CPU0_SB_DQS_DN<8>")
	)
	(segment
		(start 382.887474 -225.693478)
		(end 382.879346 -225.69805)
		(width 0.088646)
		(layer "In4.Cu")
		(net "M_F_CPU0_SB_DQS_DN<8>")
	)
	(segment
		(start 409.933902 -201.152252)
		(end 409.554934 -201.152252)
		(width 0.18288)
		(layer "In4.Cu")
		(net "M_F_CPU0_SB_DQS_DN<8>")
	)
	(segment
		(start 418.868352 -201.702416)
		(end 418.570918 -201.404982)
		(width 0.18288)
		(layer "In4.Cu")
		(net "M_F_CPU0_SB_DQS_DN<8>")
	)
	(segment
		(start 409.554934 -201.152252)
		(end 409.265374 -200.862692)
		(width 0.18288)
		(layer "In4.Cu")
		(net "M_F_CPU0_SB_DQS_DN<8>")
	)
	(segment
		(start 380.803404 -228.071172)
		(end 380.696724 -228.04247)
		(width 0.088646)
		(layer "In4.Cu")
		(net "M_F_CPU0_SB_DQS_DN<8>")
	)
	(segment
		(start 416.649154 -201.678286)
		(end 415.83229 -200.861422)
		(width 0.18288)
		(layer "In4.Cu")
		(net "M_F_CPU0_SB_DQS_DN<8>")
	)
	(segment
		(start 379.321568 -227.639626)
		(end 379.316234 -227.64496)
		(width 0.088646)
		(layer "In4.Cu")
		(net "M_F_CPU0_SB_DQS_DN<8>")
	)
	(segment
		(start 382.230884 -226.822508)
		(end 382.230884 -226.84105)
		(width 0.088646)
		(layer "In4.Cu")
		(net "M_F_CPU0_SB_DQS_DN<8>")
	)
	(segment
		(start 382.418844 -226.506278)
		(end 382.418082 -226.506786)
		(width 0.088646)
		(layer "In4.Cu")
		(net "M_F_CPU0_SB_DQS_DN<8>")
	)
	(segment
		(start 387.118606 -221.699074)
		(end 386.834634 -221.699074)
		(width 0.088646)
		(layer "In4.Cu")
		(net "M_F_CPU0_SB_DQS_DN<8>")
	)
	(arc
		(start 383.640584 -224.389442)
		(mid 383.566668 -224.668944)
		(end 383.364232 -224.875344)
		(width 0.088646)
		(layer "In4.Cu")
		(net "M_F_CPU0_SB_DQS_DN<8>")
	)
	(arc
		(start 386.834634 -221.699074)
		(mid 386.68829 -221.679866)
		(end 386.551932 -221.623382)
		(width 0.088646)
		(layer "In4.Cu")
		(net "M_F_CPU0_SB_DQS_DN<8>")
	)
	(arc
		(start 385.612132 -221.623382)
		(mid 385.424934 -221.573239)
		(end 385.237736 -221.623382)
		(width 0.088646)
		(layer "In4.Cu")
		(net "M_F_CPU0_SB_DQS_DN<8>")
	)
	(arc
		(start 380.26213 -228.04247)
		(mid 380.214016 -228.036114)
		(end 380.169166 -228.017578)
		(width 0.088646)
		(layer "In4.Cu")
		(net "M_F_CPU0_SB_DQS_DN<8>")
	)
	(arc
		(start 383.349246 -224.88398)
		(mid 383.218332 -225.02034)
		(end 383.170684 -225.203258)
		(width 0.088646)
		(layer "In4.Cu")
		(net "M_F_CPU0_SB_DQS_DN<8>")
	)
	(arc
		(start 384.767582 -222.437198)
		(mid 384.491023 -222.512941)
		(end 384.212846 -222.443294)
		(width 0.088646)
		(layer "In4.Cu")
		(net "M_F_CPU0_SB_DQS_DN<8>")
	)
	(arc
		(start 381.760984 -227.663502)
		(mid 381.680822 -227.935691)
		(end 381.478536 -228.134672)
		(width 0.088646)
		(layer "In4.Cu")
		(net "M_F_CPU0_SB_DQS_DN<8>")
	)
	(arc
		(start 385.050284 -221.94774)
		(mid 384.978049 -222.224264)
		(end 384.779774 -222.430086)
		(width 0.088646)
		(layer "In4.Cu")
		(net "M_F_CPU0_SB_DQS_DN<8>")
	)
	(arc
		(start 383.819146 -224.070164)
		(mid 383.688232 -224.206524)
		(end 383.640584 -224.389442)
		(width 0.088646)
		(layer "In4.Cu")
		(net "M_F_CPU0_SB_DQS_DN<8>")
	)
	(arc
		(start 381.478536 -228.134672)
		(mid 381.195834 -228.210414)
		(end 380.913132 -228.134672)
		(width 0.088646)
		(layer "In4.Cu")
		(net "M_F_CPU0_SB_DQS_DN<8>")
	)
	(arc
		(start 382.879346 -225.69805)
		(mid 382.748432 -225.83441)
		(end 382.700784 -226.017328)
		(width 0.088646)
		(layer "In4.Cu")
		(net "M_F_CPU0_SB_DQS_DN<8>")
	)
	(arc
		(start 383.640584 -222.754952)
		(mid 383.640594 -222.764352)
		(end 383.640838 -222.773748)
		(width 0.088646)
		(layer "In4.Cu")
		(net "M_F_CPU0_SB_DQS_DN<8>")
	)
	(arc
		(start 386.177536 -221.623382)
		(mid 385.894834 -221.699158)
		(end 385.612132 -221.623382)
		(width 0.088646)
		(layer "In4.Cu")
		(net "M_F_CPU0_SB_DQS_DN<8>")
	)
	(arc
		(start 382.700784 -226.017328)
		(mid 382.626793 -226.296894)
		(end 382.424178 -226.50323)
		(width 0.088646)
		(layer "In4.Cu")
		(net "M_F_CPU0_SB_DQS_DN<8>")
	)
	(arc
		(start 384.202432 -222.437198)
		(mid 384.015234 -222.387055)
		(end 383.828036 -222.437198)
		(width 0.088646)
		(layer "In4.Cu")
		(net "M_F_CPU0_SB_DQS_DN<8>")
	)
	(arc
		(start 382.230884 -226.84105)
		(mid 382.152773 -227.117999)
		(end 381.948436 -227.320602)
		(width 0.088646)
		(layer "In4.Cu")
		(net "M_F_CPU0_SB_DQS_DN<8>")
	)
	(arc
		(start 384.110484 -223.585532)
		(mid 384.032373 -223.862481)
		(end 383.828036 -224.065084)
		(width 0.088646)
		(layer "In4.Cu")
		(net "M_F_CPU0_SB_DQS_DN<8>")
	)
	(arc
		(start 383.828036 -223.085914)
		(mid 384.030322 -223.284895)
		(end 384.110484 -223.557084)
		(width 0.088646)
		(layer "In4.Cu")
		(net "M_F_CPU0_SB_DQS_DN<8>")
	)
	(arc
		(start 381.939546 -227.325682)
		(mid 381.808632 -227.462042)
		(end 381.760984 -227.64496)
		(width 0.088646)
		(layer "In4.Cu")
		(net "M_F_CPU0_SB_DQS_DN<8>")
	)
	(arc
		(start 383.170684 -225.2218)
		(mid 383.090522 -225.493989)
		(end 382.888236 -225.69297)
		(width 0.088646)
		(layer "In4.Cu")
		(net "M_F_CPU0_SB_DQS_DN<8>")
	)
	(arc
		(start 383.640838 -222.773748)
		(mid 383.691331 -222.949726)
		(end 383.819146 -223.080834)
		(width 0.088646)
		(layer "In4.Cu")
		(net "M_F_CPU0_SB_DQS_DN<8>")
	)
	(arc
		(start 380.118874 -227.993702)
		(mid 379.963541 -227.879104)
		(end 379.885956 -227.702364)
		(width 0.088646)
		(layer "In4.Cu")
		(net "M_F_CPU0_SB_DQS_DN<8>")
	)
	(arc
		(start 383.819146 -222.442278)
		(mid 383.689857 -222.575764)
		(end 383.640584 -222.754952)
		(width 0.088646)
		(layer "In4.Cu")
		(net "M_F_CPU0_SB_DQS_DN<8>")
	)
	(arc
		(start 386.551932 -221.623382)
		(mid 386.364734 -221.573239)
		(end 386.177536 -221.623382)
		(width 0.088646)
		(layer "In4.Cu")
		(net "M_F_CPU0_SB_DQS_DN<8>")
	)
	(arc
		(start 385.228846 -221.628462)
		(mid 385.097932 -221.764822)
		(end 385.050284 -221.94774)
		(width 0.088646)
		(layer "In4.Cu")
		(net "M_F_CPU0_SB_DQS_DN<8>")
	)
	(arc
		(start 380.169166 -228.017578)
		(mid 380.144461 -228.004711)
		(end 380.118874 -227.993702)
		(width 0.088646)
		(layer "In4.Cu")
		(net "M_F_CPU0_SB_DQS_DN<8>")
	)
	(arc
		(start 382.418082 -226.506786)
		(mid 382.283149 -226.64014)
		(end 382.230884 -226.822508)
		(width 0.088646)
		(layer "In4.Cu")
		(net "M_F_CPU0_SB_DQS_DN<8>")
	)
	(segment
		(start 431.489612 -208.516982)
		(end 431.935128 -208.962498)
		(width 0.20066)
		(layer "F.Cu")
		(net "M_F_CPU0_SB_DQS_DN<7>")
	)
	(segment
		(start 425.940982 -209.216752)
		(end 426.471588 -209.216752)
		(width 0.20066)
		(layer "F.Cu")
		(net "M_F_CPU0_SB_DQS_DN<7>")
	)
	(segment
		(start 430.395126 -208.802732)
		(end 430.713896 -208.802732)
		(width 0.20066)
		(layer "F.Cu")
		(net "M_F_CPU0_SB_DQS_DN<7>")
	)
	(segment
		(start 426.74286 -208.94548)
		(end 427.226222 -208.94548)
		(width 0.20066)
		(layer "F.Cu")
		(net "M_F_CPU0_SB_DQS_DN<7>")
	)
	(segment
		(start 424.836082 -209.216752)
		(end 425.940982 -209.216752)
		(width 0.20066)
		(layer "F.Cu")
		(net "M_F_CPU0_SB_DQS_DN<7>")
	)
	(segment
		(start 430.384204 -208.79181)
		(end 430.395126 -208.802732)
		(width 0.1016)
		(layer "F.Cu")
		(net "M_F_CPU0_SB_DQS_DN<7>")
	)
	(segment
		(start 428.363126 -208.797906)
		(end 428.367952 -208.797906)
		(width 0.101854)
		(layer "F.Cu")
		(net "M_F_CPU0_SB_DQS_DN<7>")
	)
	(segment
		(start 427.773592 -208.520538)
		(end 428.05096 -208.797906)
		(width 0.20066)
		(layer "F.Cu")
		(net "M_F_CPU0_SB_DQS_DN<7>")
	)
	(segment
		(start 427.651164 -208.520538)
		(end 427.773592 -208.520538)
		(width 0.20066)
		(layer "F.Cu")
		(net "M_F_CPU0_SB_DQS_DN<7>")
	)
	(segment
		(start 428.05096 -208.797906)
		(end 428.363126 -208.797906)
		(width 0.20066)
		(layer "F.Cu")
		(net "M_F_CPU0_SB_DQS_DN<7>")
	)
	(segment
		(start 432.9811 -209.216752)
		(end 433.484782 -209.216752)
		(width 0.20066)
		(layer "F.Cu")
		(net "M_F_CPU0_SB_DQS_DN<7>")
	)
	(segment
		(start 386.83438 -223.297496)
		(end 386.83438 -222.761556)
		(width 0.20066)
		(layer "F.Cu")
		(net "M_F_CPU0_SB_DQS_DN<7>")
	)
	(segment
		(start 426.471588 -209.216752)
		(end 426.74286 -208.94548)
		(width 0.20066)
		(layer "F.Cu")
		(net "M_F_CPU0_SB_DQS_DN<7>")
	)
	(segment
		(start 432.726846 -208.962498)
		(end 432.9811 -209.216752)
		(width 0.20066)
		(layer "F.Cu")
		(net "M_F_CPU0_SB_DQS_DN<7>")
	)
	(segment
		(start 430.999646 -208.516982)
		(end 431.489612 -208.516982)
		(width 0.20066)
		(layer "F.Cu")
		(net "M_F_CPU0_SB_DQS_DN<7>")
	)
	(segment
		(start 427.226222 -208.94548)
		(end 427.651164 -208.520538)
		(width 0.20066)
		(layer "F.Cu")
		(net "M_F_CPU0_SB_DQS_DN<7>")
	)
	(segment
		(start 428.367952 -208.797906)
		(end 428.374048 -208.79181)
		(width 0.1016)
		(layer "F.Cu")
		(net "M_F_CPU0_SB_DQS_DN<7>")
	)
	(segment
		(start 430.713896 -208.802732)
		(end 430.999646 -208.516982)
		(width 0.20066)
		(layer "F.Cu")
		(net "M_F_CPU0_SB_DQS_DN<7>")
	)
	(segment
		(start 431.935128 -208.962498)
		(end 432.726846 -208.962498)
		(width 0.20066)
		(layer "F.Cu")
		(net "M_F_CPU0_SB_DQS_DN<7>")
	)
	(segment
		(start 428.374048 -208.79181)
		(end 430.384204 -208.79181)
		(width 0.1016)
		(layer "F.Cu")
		(net "M_F_CPU0_SB_DQS_DN<7>")
	)
	(segment
		(start 397.095726 -214.196676)
		(end 396.707614 -214.584788)
		(width 0.18288)
		(layer "In2.Cu")
		(net "M_F_CPU0_SB_DQS_DN<7>")
	)
	(segment
		(start 396.143734 -214.972646)
		(end 396.143734 -215.148668)
		(width 0.18288)
		(layer "In2.Cu")
		(net "M_F_CPU0_SB_DQS_DN<7>")
	)
	(segment
		(start 409.000198 -205.97749)
		(end 408.10307 -205.97749)
		(width 0.18288)
		(layer "In2.Cu")
		(net "M_F_CPU0_SB_DQS_DN<7>")
	)
	(segment
		(start 419.045898 -207.88757)
		(end 417.757102 -207.88757)
		(width 0.18288)
		(layer "In2.Cu")
		(net "M_F_CPU0_SB_DQS_DN<7>")
	)
	(segment
		(start 400.33956 -210.77682)
		(end 399.951702 -211.164678)
		(width 0.18288)
		(layer "In2.Cu")
		(net "M_F_CPU0_SB_DQS_DN<7>")
	)
	(segment
		(start 417.476686 -208.152238)
		(end 417.476686 -208.167986)
		(width 0.16002)
		(layer "In2.Cu")
		(net "M_F_CPU0_SB_DQS_DN<7>")
	)
	(segment
		(start 422.68775 -208.941416)
		(end 422.68775 -208.925668)
		(width 0.16002)
		(layer "In2.Cu")
		(net "M_F_CPU0_SB_DQS_DN<7>")
	)
	(segment
		(start 419.184582 -208.010506)
		(end 419.168834 -208.010506)
		(width 0.16002)
		(layer "In2.Cu")
		(net "M_F_CPU0_SB_DQS_DN<7>")
	)
	(segment
		(start 398.047718 -213.244684)
		(end 397.659606 -213.632796)
		(width 0.18288)
		(layer "In2.Cu")
		(net "M_F_CPU0_SB_DQS_DN<7>")
	)
	(segment
		(start 412.21025 -206.84109)
		(end 411.342332 -205.973172)
		(width 0.18288)
		(layer "In2.Cu")
		(net "M_F_CPU0_SB_DQS_DN<7>")
	)
	(segment
		(start 421.29329 -208.533238)
		(end 421.03294 -208.793588)
		(width 0.18288)
		(layer "In2.Cu")
		(net "M_F_CPU0_SB_DQS_DN<7>")
	)
	(segment
		(start 400.903694 -210.388708)
		(end 400.515582 -210.77682)
		(width 0.18288)
		(layer "In2.Cu")
		(net "M_F_CPU0_SB_DQS_DN<7>")
	)
	(segment
		(start 387.586982 -222.437198)
		(end 387.556756 -222.454724)
		(width 0.088646)
		(layer "In2.Cu")
		(net "M_F_CPU0_SB_DQS_DN<7>")
	)
	(segment
		(start 422.279572 -208.533238)
		(end 421.29329 -208.533238)
		(width 0.18288)
		(layer "In2.Cu")
		(net "M_F_CPU0_SB_DQS_DN<7>")
	)
	(segment
		(start 416.295078 -208.33715)
		(end 414.780984 -206.823056)
		(width 0.18288)
		(layer "In2.Cu")
		(net "M_F_CPU0_SB_DQS_DN<7>")
	)
	(segment
		(start 399.951702 -211.3407)
		(end 399.56359 -211.728812)
		(width 0.18288)
		(layer "In2.Cu")
		(net "M_F_CPU0_SB_DQS_DN<7>")
	)
	(segment
		(start 396.531592 -214.584788)
		(end 396.143734 -214.972646)
		(width 0.18288)
		(layer "In2.Cu")
		(net "M_F_CPU0_SB_DQS_DN<7>")
	)
	(segment
		(start 417.476686 -208.167986)
		(end 417.448492 -208.19618)
		(width 0.16002)
		(layer "In2.Cu")
		(net "M_F_CPU0_SB_DQS_DN<7>")
	)
	(segment
		(start 389.713978 -220.933772)
		(end 389.113776 -221.533974)
		(width 0.088646)
		(layer "In2.Cu")
		(net "M_F_CPU0_SB_DQS_DN<7>")
	)
	(segment
		(start 387.593078 -222.433642)
		(end 387.587744 -222.43669)
		(width 0.088646)
		(layer "In2.Cu")
		(net "M_F_CPU0_SB_DQS_DN<7>")
	)
	(segment
		(start 403.371558 -207.920844)
		(end 403.195536 -207.920844)
		(width 0.18288)
		(layer "In2.Cu")
		(net "M_F_CPU0_SB_DQS_DN<7>")
	)
	(segment
		(start 397.483584 -213.632796)
		(end 397.095726 -214.020654)
		(width 0.18288)
		(layer "In2.Cu")
		(net "M_F_CPU0_SB_DQS_DN<7>")
	)
	(segment
		(start 422.715944 -208.96961)
		(end 422.68775 -208.941416)
		(width 0.16002)
		(layer "In2.Cu")
		(net "M_F_CPU0_SB_DQS_DN<7>")
	)
	(segment
		(start 398.047718 -213.068662)
		(end 398.047718 -213.244684)
		(width 0.18288)
		(layer "In2.Cu")
		(net "M_F_CPU0_SB_DQS_DN<7>")
	)
	(segment
		(start 404.32355 -206.968852)
		(end 404.147528 -206.968852)
		(width 0.18288)
		(layer "In2.Cu")
		(net "M_F_CPU0_SB_DQS_DN<7>")
	)
	(segment
		(start 397.095726 -214.020654)
		(end 397.095726 -214.196676)
		(width 0.18288)
		(layer "In2.Cu")
		(net "M_F_CPU0_SB_DQS_DN<7>")
	)
	(segment
		(start 424.549316 -208.929986)
		(end 424.392598 -208.929986)
		(width 0.18288)
		(layer "In2.Cu")
		(net "M_F_CPU0_SB_DQS_DN<7>")
	)
	(segment
		(start 389.060944 -221.580202)
		(end 389.060944 -221.580456)
		(width 0.088646)
		(layer "In2.Cu")
		(net "M_F_CPU0_SB_DQS_DN<7>")
	)
	(segment
		(start 387.587744 -222.43669)
		(end 387.586982 -222.437198)
		(width 0.088646)
		(layer "In2.Cu")
		(net "M_F_CPU0_SB_DQS_DN<7>")
	)
	(segment
		(start 422.533064 -208.78673)
		(end 422.50487 -208.758536)
		(width 0.16002)
		(layer "In2.Cu")
		(net "M_F_CPU0_SB_DQS_DN<7>")
	)
	(segment
		(start 399.387568 -211.728812)
		(end 398.99971 -212.11667)
		(width 0.18288)
		(layer "In2.Cu")
		(net "M_F_CPU0_SB_DQS_DN<7>")
	)
	(segment
		(start 402.807678 -208.308702)
		(end 402.807678 -208.484724)
		(width 0.18288)
		(layer "In2.Cu")
		(net "M_F_CPU0_SB_DQS_DN<7>")
	)
	(segment
		(start 424.392598 -208.929986)
		(end 423.71391 -209.21091)
		(width 0.18288)
		(layer "In2.Cu")
		(net "M_F_CPU0_SB_DQS_DN<7>")
	)
	(segment
		(start 422.68775 -208.925668)
		(end 422.548812 -208.78673)
		(width 0.16002)
		(layer "In2.Cu")
		(net "M_F_CPU0_SB_DQS_DN<7>")
	)
	(segment
		(start 395.755622 -215.53678)
		(end 395.577822 -215.53678)
		(width 0.18288)
		(layer "In2.Cu")
		(net "M_F_CPU0_SB_DQS_DN<7>")
	)
	(segment
		(start 395.577822 -215.53678)
		(end 390.819386 -220.2942)
		(width 0.18288)
		(layer "In2.Cu")
		(net "M_F_CPU0_SB_DQS_DN<7>")
	)
	(segment
		(start 400.903694 -210.212686)
		(end 400.903694 -210.388708)
		(width 0.18288)
		(layer "In2.Cu")
		(net "M_F_CPU0_SB_DQS_DN<7>")
	)
	(segment
		(start 412.94304 -207.118204)
		(end 412.665926 -206.84109)
		(width 0.18288)
		(layer "In2.Cu")
		(net "M_F_CPU0_SB_DQS_DN<7>")
	)
	(segment
		(start 403.75967 -207.35671)
		(end 403.75967 -207.532732)
		(width 0.18288)
		(layer "In2.Cu")
		(net "M_F_CPU0_SB_DQS_DN<7>")
	)
	(segment
		(start 411.342332 -205.973172)
		(end 410.01823 -205.973172)
		(width 0.18288)
		(layer "In2.Cu")
		(net "M_F_CPU0_SB_DQS_DN<7>")
	)
	(segment
		(start 398.99971 -212.11667)
		(end 398.99971 -212.292692)
		(width 0.18288)
		(layer "In2.Cu")
		(net "M_F_CPU0_SB_DQS_DN<7>")
	)
	(segment
		(start 402.419566 -208.872836)
		(end 402.243544 -208.872836)
		(width 0.18288)
		(layer "In2.Cu")
		(net "M_F_CPU0_SB_DQS_DN<7>")
	)
	(segment
		(start 401.467574 -209.824828)
		(end 401.291552 -209.824828)
		(width 0.18288)
		(layer "In2.Cu")
		(net "M_F_CPU0_SB_DQS_DN<7>")
	)
	(segment
		(start 401.855686 -209.436716)
		(end 401.467574 -209.824828)
		(width 0.18288)
		(layer "In2.Cu")
		(net "M_F_CPU0_SB_DQS_DN<7>")
	)
	(segment
		(start 419.643052 -208.484724)
		(end 419.351714 -208.193386)
		(width 0.18288)
		(layer "In2.Cu")
		(net "M_F_CPU0_SB_DQS_DN<7>")
	)
	(segment
		(start 396.143734 -215.148668)
		(end 395.755622 -215.53678)
		(width 0.18288)
		(layer "In2.Cu")
		(net "M_F_CPU0_SB_DQS_DN<7>")
	)
	(segment
		(start 422.548812 -208.78673)
		(end 422.533064 -208.78673)
		(width 0.16002)
		(layer "In2.Cu")
		(net "M_F_CPU0_SB_DQS_DN<7>")
	)
	(segment
		(start 417.631372 -208.0133)
		(end 417.615624 -208.0133)
		(width 0.16002)
		(layer "In2.Cu")
		(net "M_F_CPU0_SB_DQS_DN<7>")
	)
	(segment
		(start 413.670242 -206.823056)
		(end 413.375094 -207.118204)
		(width 0.18288)
		(layer "In2.Cu")
		(net "M_F_CPU0_SB_DQS_DN<7>")
	)
	(segment
		(start 420.431722 -208.793588)
		(end 420.122858 -208.484724)
		(width 0.18288)
		(layer "In2.Cu")
		(net "M_F_CPU0_SB_DQS_DN<7>")
	)
	(segment
		(start 419.14064 -207.982312)
		(end 419.045898 -207.88757)
		(width 0.18288)
		(layer "In2.Cu")
		(net "M_F_CPU0_SB_DQS_DN<7>")
	)
	(segment
		(start 400.515582 -210.77682)
		(end 400.33956 -210.77682)
		(width 0.18288)
		(layer "In2.Cu")
		(net "M_F_CPU0_SB_DQS_DN<7>")
	)
	(segment
		(start 390.819386 -220.2942)
		(end 390.738868 -220.2942)
		(width 0.088646)
		(layer "In2.Cu")
		(net "M_F_CPU0_SB_DQS_DN<7>")
	)
	(segment
		(start 401.291552 -209.824828)
		(end 400.903694 -210.212686)
		(width 0.18288)
		(layer "In2.Cu")
		(net "M_F_CPU0_SB_DQS_DN<7>")
	)
	(segment
		(start 422.957244 -209.21091)
		(end 422.715944 -208.96961)
		(width 0.18288)
		(layer "In2.Cu")
		(net "M_F_CPU0_SB_DQS_DN<7>")
	)
	(segment
		(start 414.780984 -206.823056)
		(end 413.670242 -206.823056)
		(width 0.18288)
		(layer "In2.Cu")
		(net "M_F_CPU0_SB_DQS_DN<7>")
	)
	(segment
		(start 424.836082 -209.216752)
		(end 424.549316 -208.929986)
		(width 0.18288)
		(layer "In2.Cu")
		(net "M_F_CPU0_SB_DQS_DN<7>")
	)
	(segment
		(start 417.448492 -208.19618)
		(end 417.307522 -208.33715)
		(width 0.18288)
		(layer "In2.Cu")
		(net "M_F_CPU0_SB_DQS_DN<7>")
	)
	(segment
		(start 410.01823 -205.973172)
		(end 409.723082 -206.26832)
		(width 0.18288)
		(layer "In2.Cu")
		(net "M_F_CPU0_SB_DQS_DN<7>")
	)
	(segment
		(start 398.435576 -212.680804)
		(end 398.047718 -213.068662)
		(width 0.18288)
		(layer "In2.Cu")
		(net "M_F_CPU0_SB_DQS_DN<7>")
	)
	(segment
		(start 406.047448 -205.383638)
		(end 405.09952 -206.01686)
		(width 0.18288)
		(layer "In2.Cu")
		(net "M_F_CPU0_SB_DQS_DN<7>")
	)
	(segment
		(start 408.10307 -205.97749)
		(end 407.509218 -205.383638)
		(width 0.18288)
		(layer "In2.Cu")
		(net "M_F_CPU0_SB_DQS_DN<7>")
	)
	(segment
		(start 404.711662 -206.58074)
		(end 404.32355 -206.968852)
		(width 0.18288)
		(layer "In2.Cu")
		(net "M_F_CPU0_SB_DQS_DN<7>")
	)
	(segment
		(start 409.723082 -206.26832)
		(end 409.291028 -206.26832)
		(width 0.18288)
		(layer "In2.Cu")
		(net "M_F_CPU0_SB_DQS_DN<7>")
	)
	(segment
		(start 403.195536 -207.920844)
		(end 402.807678 -208.308702)
		(width 0.18288)
		(layer "In2.Cu")
		(net "M_F_CPU0_SB_DQS_DN<7>")
	)
	(segment
		(start 413.375094 -207.118204)
		(end 412.94304 -207.118204)
		(width 0.18288)
		(layer "In2.Cu")
		(net "M_F_CPU0_SB_DQS_DN<7>")
	)
	(segment
		(start 421.03294 -208.793588)
		(end 420.431722 -208.793588)
		(width 0.18288)
		(layer "In2.Cu")
		(net "M_F_CPU0_SB_DQS_DN<7>")
	)
	(segment
		(start 417.659566 -207.985106)
		(end 417.631372 -208.0133)
		(width 0.16002)
		(layer "In2.Cu")
		(net "M_F_CPU0_SB_DQS_DN<7>")
	)
	(segment
		(start 387.556756 -222.454724)
		(end 386.83438 -222.761556)
		(width 0.088646)
		(layer "In2.Cu")
		(net "M_F_CPU0_SB_DQS_DN<7>")
	)
	(segment
		(start 419.351714 -208.193386)
		(end 419.32352 -208.165192)
		(width 0.16002)
		(layer "In2.Cu")
		(net "M_F_CPU0_SB_DQS_DN<7>")
	)
	(segment
		(start 401.855686 -209.260694)
		(end 401.855686 -209.436716)
		(width 0.18288)
		(layer "In2.Cu")
		(net "M_F_CPU0_SB_DQS_DN<7>")
	)
	(segment
		(start 419.168834 -208.010506)
		(end 419.14064 -207.982312)
		(width 0.16002)
		(layer "In2.Cu")
		(net "M_F_CPU0_SB_DQS_DN<7>")
	)
	(segment
		(start 402.243544 -208.872836)
		(end 401.855686 -209.260694)
		(width 0.18288)
		(layer "In2.Cu")
		(net "M_F_CPU0_SB_DQS_DN<7>")
	)
	(segment
		(start 404.711662 -206.404718)
		(end 404.711662 -206.58074)
		(width 0.18288)
		(layer "In2.Cu")
		(net "M_F_CPU0_SB_DQS_DN<7>")
	)
	(segment
		(start 419.32352 -208.165192)
		(end 419.32352 -208.149444)
		(width 0.16002)
		(layer "In2.Cu")
		(net "M_F_CPU0_SB_DQS_DN<7>")
	)
	(segment
		(start 417.615624 -208.0133)
		(end 417.476686 -208.152238)
		(width 0.16002)
		(layer "In2.Cu")
		(net "M_F_CPU0_SB_DQS_DN<7>")
	)
	(segment
		(start 405.09952 -206.01686)
		(end 404.711662 -206.404718)
		(width 0.18288)
		(layer "In2.Cu")
		(net "M_F_CPU0_SB_DQS_DN<7>")
	)
	(segment
		(start 390.738868 -220.2942)
		(end 390.099296 -220.933772)
		(width 0.088646)
		(layer "In2.Cu")
		(net "M_F_CPU0_SB_DQS_DN<7>")
	)
	(segment
		(start 398.99971 -212.292692)
		(end 398.611598 -212.680804)
		(width 0.18288)
		(layer "In2.Cu")
		(net "M_F_CPU0_SB_DQS_DN<7>")
	)
	(segment
		(start 419.32352 -208.149444)
		(end 419.184582 -208.010506)
		(width 0.16002)
		(layer "In2.Cu")
		(net "M_F_CPU0_SB_DQS_DN<7>")
	)
	(segment
		(start 404.147528 -206.968852)
		(end 403.75967 -207.35671)
		(width 0.18288)
		(layer "In2.Cu")
		(net "M_F_CPU0_SB_DQS_DN<7>")
	)
	(segment
		(start 417.757102 -207.88757)
		(end 417.659566 -207.985106)
		(width 0.18288)
		(layer "In2.Cu")
		(net "M_F_CPU0_SB_DQS_DN<7>")
	)
	(segment
		(start 396.707614 -214.584788)
		(end 396.531592 -214.584788)
		(width 0.18288)
		(layer "In2.Cu")
		(net "M_F_CPU0_SB_DQS_DN<7>")
	)
	(segment
		(start 420.122858 -208.484724)
		(end 419.643052 -208.484724)
		(width 0.18288)
		(layer "In2.Cu")
		(net "M_F_CPU0_SB_DQS_DN<7>")
	)
	(segment
		(start 407.509218 -205.383638)
		(end 406.047448 -205.383638)
		(width 0.18288)
		(layer "In2.Cu")
		(net "M_F_CPU0_SB_DQS_DN<7>")
	)
	(segment
		(start 402.807678 -208.484724)
		(end 402.419566 -208.872836)
		(width 0.18288)
		(layer "In2.Cu")
		(net "M_F_CPU0_SB_DQS_DN<7>")
	)
	(segment
		(start 399.56359 -211.728812)
		(end 399.387568 -211.728812)
		(width 0.18288)
		(layer "In2.Cu")
		(net "M_F_CPU0_SB_DQS_DN<7>")
	)
	(segment
		(start 390.099296 -220.933772)
		(end 389.713978 -220.933772)
		(width 0.088646)
		(layer "In2.Cu")
		(net "M_F_CPU0_SB_DQS_DN<7>")
	)
	(segment
		(start 417.307522 -208.33715)
		(end 416.295078 -208.33715)
		(width 0.18288)
		(layer "In2.Cu")
		(net "M_F_CPU0_SB_DQS_DN<7>")
	)
	(segment
		(start 399.951702 -211.164678)
		(end 399.951702 -211.3407)
		(width 0.18288)
		(layer "In2.Cu")
		(net "M_F_CPU0_SB_DQS_DN<7>")
	)
	(segment
		(start 398.611598 -212.680804)
		(end 398.435576 -212.680804)
		(width 0.18288)
		(layer "In2.Cu")
		(net "M_F_CPU0_SB_DQS_DN<7>")
	)
	(segment
		(start 409.291028 -206.26832)
		(end 409.000198 -205.97749)
		(width 0.18288)
		(layer "In2.Cu")
		(net "M_F_CPU0_SB_DQS_DN<7>")
	)
	(segment
		(start 422.50487 -208.758536)
		(end 422.279572 -208.533238)
		(width 0.18288)
		(layer "In2.Cu")
		(net "M_F_CPU0_SB_DQS_DN<7>")
	)
	(segment
		(start 423.71391 -209.21091)
		(end 422.957244 -209.21091)
		(width 0.18288)
		(layer "In2.Cu")
		(net "M_F_CPU0_SB_DQS_DN<7>")
	)
	(segment
		(start 412.665926 -206.84109)
		(end 412.21025 -206.84109)
		(width 0.18288)
		(layer "In2.Cu")
		(net "M_F_CPU0_SB_DQS_DN<7>")
	)
	(segment
		(start 403.75967 -207.532732)
		(end 403.371558 -207.920844)
		(width 0.18288)
		(layer "In2.Cu")
		(net "M_F_CPU0_SB_DQS_DN<7>")
	)
	(segment
		(start 397.659606 -213.632796)
		(end 397.483584 -213.632796)
		(width 0.18288)
		(layer "In2.Cu")
		(net "M_F_CPU0_SB_DQS_DN<7>")
	)
	(arc
		(start 388.996936 -221.623382)
		(mid 388.714234 -221.699158)
		(end 388.431532 -221.623382)
		(width 0.088646)
		(layer "In2.Cu")
		(net "M_F_CPU0_SB_DQS_DN<7>")
	)
	(arc
		(start 389.113776 -221.533974)
		(mid 389.088078 -221.557908)
		(end 389.060944 -221.580202)
		(width 0.088646)
		(layer "In2.Cu")
		(net "M_F_CPU0_SB_DQS_DN<7>")
	)
	(arc
		(start 388.431532 -221.623382)
		(mid 388.057057 -221.623428)
		(end 387.869684 -221.94774)
		(width 0.088646)
		(layer "In2.Cu")
		(net "M_F_CPU0_SB_DQS_DN<7>")
	)
	(arc
		(start 387.869684 -221.94774)
		(mid 387.795693 -222.227306)
		(end 387.593078 -222.433642)
		(width 0.088646)
		(layer "In2.Cu")
		(net "M_F_CPU0_SB_DQS_DN<7>")
	)
	(arc
		(start 389.060944 -221.580456)
		(mid 389.029672 -221.603011)
		(end 388.996936 -221.623382)
		(width 0.088646)
		(layer "In2.Cu")
		(net "M_F_CPU0_SB_DQS_DN<7>")
	)
	(segment
		(start 426.74286 -218.295474)
		(end 427.226222 -218.295474)
		(width 0.20066)
		(layer "F.Cu")
		(net "M_F_CPU0_SB_DQS_DN<6>")
	)
	(segment
		(start 424.836082 -218.566746)
		(end 425.940982 -218.566746)
		(width 0.20066)
		(layer "F.Cu")
		(net "M_F_CPU0_SB_DQS_DN<6>")
	)
	(segment
		(start 383.545334 -230.622602)
		(end 383.545334 -230.086662)
		(width 0.20066)
		(layer "F.Cu")
		(net "M_F_CPU0_SB_DQS_DN<6>")
	)
	(segment
		(start 430.999646 -217.866976)
		(end 431.489612 -217.866976)
		(width 0.20066)
		(layer "F.Cu")
		(net "M_F_CPU0_SB_DQS_DN<6>")
	)
	(segment
		(start 430.384204 -218.141804)
		(end 430.395126 -218.152726)
		(width 0.1016)
		(layer "F.Cu")
		(net "M_F_CPU0_SB_DQS_DN<6>")
	)
	(segment
		(start 431.489612 -217.866976)
		(end 431.935128 -218.312492)
		(width 0.20066)
		(layer "F.Cu")
		(net "M_F_CPU0_SB_DQS_DN<6>")
	)
	(segment
		(start 426.471588 -218.566746)
		(end 426.74286 -218.295474)
		(width 0.20066)
		(layer "F.Cu")
		(net "M_F_CPU0_SB_DQS_DN<6>")
	)
	(segment
		(start 432.9811 -218.566746)
		(end 433.484782 -218.566746)
		(width 0.20066)
		(layer "F.Cu")
		(net "M_F_CPU0_SB_DQS_DN<6>")
	)
	(segment
		(start 430.713896 -218.152726)
		(end 430.999646 -217.866976)
		(width 0.20066)
		(layer "F.Cu")
		(net "M_F_CPU0_SB_DQS_DN<6>")
	)
	(segment
		(start 430.395126 -218.152726)
		(end 430.713896 -218.152726)
		(width 0.20066)
		(layer "F.Cu")
		(net "M_F_CPU0_SB_DQS_DN<6>")
	)
	(segment
		(start 427.773592 -217.870532)
		(end 428.05096 -218.1479)
		(width 0.20066)
		(layer "F.Cu")
		(net "M_F_CPU0_SB_DQS_DN<6>")
	)
	(segment
		(start 431.935128 -218.312492)
		(end 432.726846 -218.312492)
		(width 0.20066)
		(layer "F.Cu")
		(net "M_F_CPU0_SB_DQS_DN<6>")
	)
	(segment
		(start 428.367952 -218.1479)
		(end 428.374048 -218.141804)
		(width 0.1016)
		(layer "F.Cu")
		(net "M_F_CPU0_SB_DQS_DN<6>")
	)
	(segment
		(start 428.05096 -218.1479)
		(end 428.363126 -218.1479)
		(width 0.20066)
		(layer "F.Cu")
		(net "M_F_CPU0_SB_DQS_DN<6>")
	)
	(segment
		(start 428.363126 -218.1479)
		(end 428.367952 -218.1479)
		(width 0.101854)
		(layer "F.Cu")
		(net "M_F_CPU0_SB_DQS_DN<6>")
	)
	(segment
		(start 432.726846 -218.312492)
		(end 432.9811 -218.566746)
		(width 0.20066)
		(layer "F.Cu")
		(net "M_F_CPU0_SB_DQS_DN<6>")
	)
	(segment
		(start 428.374048 -218.141804)
		(end 430.384204 -218.141804)
		(width 0.1016)
		(layer "F.Cu")
		(net "M_F_CPU0_SB_DQS_DN<6>")
	)
	(segment
		(start 425.940982 -218.566746)
		(end 426.471588 -218.566746)
		(width 0.20066)
		(layer "F.Cu")
		(net "M_F_CPU0_SB_DQS_DN<6>")
	)
	(segment
		(start 427.226222 -218.295474)
		(end 427.651164 -217.870532)
		(width 0.20066)
		(layer "F.Cu")
		(net "M_F_CPU0_SB_DQS_DN<6>")
	)
	(segment
		(start 427.651164 -217.870532)
		(end 427.773592 -217.870532)
		(width 0.20066)
		(layer "F.Cu")
		(net "M_F_CPU0_SB_DQS_DN<6>")
	)
	(segment
		(start 417.463224 -217.514932)
		(end 417.463224 -217.53068)
		(width 0.16002)
		(layer "In2.Cu")
		(net "M_F_CPU0_SB_DQS_DN<6>")
	)
	(segment
		(start 421.237664 -217.833956)
		(end 420.929562 -218.142058)
		(width 0.18288)
		(layer "In2.Cu")
		(net "M_F_CPU0_SB_DQS_DN<6>")
	)
	(segment
		(start 417.43503 -217.558874)
		(end 417.145724 -217.84818)
		(width 0.18288)
		(layer "In2.Cu")
		(net "M_F_CPU0_SB_DQS_DN<6>")
	)
	(segment
		(start 402.758148 -218.978734)
		(end 402.37029 -219.366592)
		(width 0.18288)
		(layer "In2.Cu")
		(net "M_F_CPU0_SB_DQS_DN<6>")
	)
	(segment
		(start 417.602162 -217.375994)
		(end 417.463224 -217.514932)
		(width 0.16002)
		(layer "In2.Cu")
		(net "M_F_CPU0_SB_DQS_DN<6>")
	)
	(segment
		(start 399.050002 -222.38335)
		(end 398.66189 -222.771462)
		(width 0.18288)
		(layer "In2.Cu")
		(net "M_F_CPU0_SB_DQS_DN<6>")
	)
	(segment
		(start 389.078978 -227.579428)
		(end 388.354062 -228.304344)
		(width 0.18288)
		(layer "In2.Cu")
		(net "M_F_CPU0_SB_DQS_DN<6>")
	)
	(segment
		(start 401.982178 -219.930726)
		(end 401.806156 -219.930726)
		(width 0.18288)
		(layer "In2.Cu")
		(net "M_F_CPU0_SB_DQS_DN<6>")
	)
	(segment
		(start 383.611374 -229.832916)
		(end 383.56286 -229.868222)
		(width 0.088646)
		(layer "In2.Cu")
		(net "M_F_CPU0_SB_DQS_DN<6>")
	)
	(segment
		(start 402.37029 -219.366592)
		(end 402.37029 -219.542614)
		(width 0.18288)
		(layer "In2.Cu")
		(net "M_F_CPU0_SB_DQS_DN<6>")
	)
	(segment
		(start 402.37029 -219.542614)
		(end 401.982178 -219.930726)
		(width 0.18288)
		(layer "In2.Cu")
		(net "M_F_CPU0_SB_DQS_DN<6>")
	)
	(segment
		(start 410.04363 -217.06078)
		(end 409.751022 -217.353388)
		(width 0.18288)
		(layer "In2.Cu")
		(net "M_F_CPU0_SB_DQS_DN<6>")
	)
	(segment
		(start 389.627618 -227.579428)
		(end 389.078978 -227.579428)
		(width 0.18288)
		(layer "In2.Cu")
		(net "M_F_CPU0_SB_DQS_DN<6>")
	)
	(segment
		(start 391.771378 -227.579428)
		(end 391.646918 -227.703888)
		(width 0.18288)
		(layer "In2.Cu")
		(net "M_F_CPU0_SB_DQS_DN<6>")
	)
	(segment
		(start 415.195766 -218.165426)
		(end 414.903158 -217.872818)
		(width 0.18288)
		(layer "In2.Cu")
		(net "M_F_CPU0_SB_DQS_DN<6>")
	)
	(segment
		(start 413.019494 -218.165426)
		(end 412.732474 -217.878406)
		(width 0.18288)
		(layer "In2.Cu")
		(net "M_F_CPU0_SB_DQS_DN<6>")
	)
	(segment
		(start 405.994108 -216.489788)
		(end 405.965914 -216.517982)
		(width 0.16002)
		(layer "In2.Cu")
		(net "M_F_CPU0_SB_DQS_DN<6>")
	)
	(segment
		(start 422.535096 -218.136724)
		(end 422.506902 -218.10853)
		(width 0.16002)
		(layer "In2.Cu")
		(net "M_F_CPU0_SB_DQS_DN<6>")
	)
	(segment
		(start 397.533876 -223.723454)
		(end 397.146018 -224.111312)
		(width 0.18288)
		(layer "In2.Cu")
		(net "M_F_CPU0_SB_DQS_DN<6>")
	)
	(segment
		(start 395.242034 -226.015296)
		(end 395.242034 -226.191318)
		(width 0.18288)
		(layer "In2.Cu")
		(net "M_F_CPU0_SB_DQS_DN<6>")
	)
	(segment
		(start 391.646918 -227.703888)
		(end 391.098278 -227.703888)
		(width 0.18288)
		(layer "In2.Cu")
		(net "M_F_CPU0_SB_DQS_DN<6>")
	)
	(segment
		(start 422.506902 -218.10853)
		(end 422.232328 -217.833956)
		(width 0.18288)
		(layer "In2.Cu")
		(net "M_F_CPU0_SB_DQS_DN<6>")
	)
	(segment
		(start 417.463224 -217.53068)
		(end 417.43503 -217.558874)
		(width 0.16002)
		(layer "In2.Cu")
		(net "M_F_CPU0_SB_DQS_DN<6>")
	)
	(segment
		(start 422.550844 -218.136724)
		(end 422.535096 -218.136724)
		(width 0.16002)
		(layer "In2.Cu")
		(net "M_F_CPU0_SB_DQS_DN<6>")
	)
	(segment
		(start 417.646104 -217.3478)
		(end 417.61791 -217.375994)
		(width 0.16002)
		(layer "In2.Cu")
		(net "M_F_CPU0_SB_DQS_DN<6>")
	)
	(segment
		(start 405.950166 -216.517982)
		(end 405.811228 -216.65692)
		(width 0.16002)
		(layer "In2.Cu")
		(net "M_F_CPU0_SB_DQS_DN<6>")
	)
	(segment
		(start 408.146758 -217.066368)
		(end 407.47188 -216.39149)
		(width 0.18288)
		(layer "In2.Cu")
		(net "M_F_CPU0_SB_DQS_DN<6>")
	)
	(segment
		(start 403.322282 -218.4146)
		(end 403.322282 -218.590622)
		(width 0.18288)
		(layer "In2.Cu")
		(net "M_F_CPU0_SB_DQS_DN<6>")
	)
	(segment
		(start 412.732474 -217.878406)
		(end 412.181294 -217.878406)
		(width 0.18288)
		(layer "In2.Cu")
		(net "M_F_CPU0_SB_DQS_DN<6>")
	)
	(segment
		(start 409.395676 -217.353388)
		(end 409.108656 -217.066368)
		(width 0.18288)
		(layer "In2.Cu")
		(net "M_F_CPU0_SB_DQS_DN<6>")
	)
	(segment
		(start 409.108656 -217.066368)
		(end 408.146758 -217.066368)
		(width 0.18288)
		(layer "In2.Cu")
		(net "M_F_CPU0_SB_DQS_DN<6>")
	)
	(segment
		(start 403.886162 -218.026742)
		(end 403.71014 -218.026742)
		(width 0.18288)
		(layer "In2.Cu")
		(net "M_F_CPU0_SB_DQS_DN<6>")
	)
	(segment
		(start 389.752078 -227.703888)
		(end 389.627618 -227.579428)
		(width 0.18288)
		(layer "In2.Cu")
		(net "M_F_CPU0_SB_DQS_DN<6>")
	)
	(segment
		(start 391.098278 -227.703888)
		(end 390.973818 -227.579428)
		(width 0.18288)
		(layer "In2.Cu")
		(net "M_F_CPU0_SB_DQS_DN<6>")
	)
	(segment
		(start 418.99586 -217.20683)
		(end 417.787074 -217.20683)
		(width 0.18288)
		(layer "In2.Cu")
		(net "M_F_CPU0_SB_DQS_DN<6>")
	)
	(segment
		(start 419.128956 -217.339926)
		(end 418.99586 -217.20683)
		(width 0.18288)
		(layer "In2.Cu")
		(net "M_F_CPU0_SB_DQS_DN<6>")
	)
	(segment
		(start 420.244016 -217.84818)
		(end 419.63721 -217.84818)
		(width 0.18288)
		(layer "In2.Cu")
		(net "M_F_CPU0_SB_DQS_DN<6>")
	)
	(segment
		(start 394.853922 -226.57943)
		(end 394.6779 -226.57943)
		(width 0.18288)
		(layer "In2.Cu")
		(net "M_F_CPU0_SB_DQS_DN<6>")
	)
	(segment
		(start 397.709898 -223.723454)
		(end 397.533876 -223.723454)
		(width 0.18288)
		(layer "In2.Cu")
		(net "M_F_CPU0_SB_DQS_DN<6>")
	)
	(segment
		(start 395.242034 -226.191318)
		(end 394.853922 -226.57943)
		(width 0.18288)
		(layer "In2.Cu")
		(net "M_F_CPU0_SB_DQS_DN<6>")
	)
	(segment
		(start 384.297936 -229.762304)
		(end 384.20421 -229.816406)
		(width 0.088646)
		(layer "In2.Cu")
		(net "M_F_CPU0_SB_DQS_DN<6>")
	)
	(segment
		(start 417.787074 -217.20683)
		(end 417.646104 -217.3478)
		(width 0.18288)
		(layer "In2.Cu")
		(net "M_F_CPU0_SB_DQS_DN<6>")
	)
	(segment
		(start 397.146018 -224.111312)
		(end 397.146018 -224.287334)
		(width 0.18288)
		(layer "In2.Cu")
		(net "M_F_CPU0_SB_DQS_DN<6>")
	)
	(segment
		(start 388.354062 -228.304344)
		(end 388.26948 -228.304344)
		(width 0.088646)
		(layer "In2.Cu")
		(net "M_F_CPU0_SB_DQS_DN<6>")
	)
	(segment
		(start 398.485868 -222.771462)
		(end 398.09801 -223.15932)
		(width 0.18288)
		(layer "In2.Cu")
		(net "M_F_CPU0_SB_DQS_DN<6>")
	)
	(segment
		(start 419.172898 -217.36812)
		(end 419.15715 -217.36812)
		(width 0.16002)
		(layer "In2.Cu")
		(net "M_F_CPU0_SB_DQS_DN<6>")
	)
	(segment
		(start 409.751022 -217.353388)
		(end 409.395676 -217.353388)
		(width 0.18288)
		(layer "In2.Cu")
		(net "M_F_CPU0_SB_DQS_DN<6>")
	)
	(segment
		(start 419.311836 -217.522806)
		(end 419.311836 -217.507058)
		(width 0.16002)
		(layer "In2.Cu")
		(net "M_F_CPU0_SB_DQS_DN<6>")
	)
	(segment
		(start 412.181294 -217.878406)
		(end 411.363668 -217.06078)
		(width 0.18288)
		(layer "In2.Cu")
		(net "M_F_CPU0_SB_DQS_DN<6>")
	)
	(segment
		(start 393.677902 -227.579428)
		(end 391.771378 -227.579428)
		(width 0.18288)
		(layer "In2.Cu")
		(net "M_F_CPU0_SB_DQS_DN<6>")
	)
	(segment
		(start 420.929562 -218.142058)
		(end 420.537894 -218.142058)
		(width 0.18288)
		(layer "In2.Cu")
		(net "M_F_CPU0_SB_DQS_DN<6>")
	)
	(segment
		(start 383.700528 -229.795832)
		(end 383.611374 -229.832916)
		(width 0.088646)
		(layer "In2.Cu")
		(net "M_F_CPU0_SB_DQS_DN<6>")
	)
	(segment
		(start 405.811228 -216.672668)
		(end 405.783034 -216.700862)
		(width 0.16002)
		(layer "In2.Cu")
		(net "M_F_CPU0_SB_DQS_DN<6>")
	)
	(segment
		(start 384.767836 -228.948488)
		(end 384.758946 -228.953568)
		(width 0.088646)
		(layer "In2.Cu")
		(net "M_F_CPU0_SB_DQS_DN<6>")
	)
	(segment
		(start 404.274274 -217.63863)
		(end 403.886162 -218.026742)
		(width 0.18288)
		(layer "In2.Cu")
		(net "M_F_CPU0_SB_DQS_DN<6>")
	)
	(segment
		(start 405.783034 -216.700862)
		(end 405.409146 -217.07475)
		(width 0.18288)
		(layer "In2.Cu")
		(net "M_F_CPU0_SB_DQS_DN<6>")
	)
	(segment
		(start 405.811228 -216.65692)
		(end 405.811228 -216.672668)
		(width 0.16002)
		(layer "In2.Cu")
		(net "M_F_CPU0_SB_DQS_DN<6>")
	)
	(segment
		(start 422.689782 -218.275662)
		(end 422.550844 -218.136724)
		(width 0.16002)
		(layer "In2.Cu")
		(net "M_F_CPU0_SB_DQS_DN<6>")
	)
	(segment
		(start 419.34003 -217.551)
		(end 419.311836 -217.522806)
		(width 0.16002)
		(layer "In2.Cu")
		(net "M_F_CPU0_SB_DQS_DN<6>")
	)
	(segment
		(start 403.71014 -218.026742)
		(end 403.322282 -218.4146)
		(width 0.18288)
		(layer "In2.Cu")
		(net "M_F_CPU0_SB_DQS_DN<6>")
	)
	(segment
		(start 396.757906 -224.675446)
		(end 396.581884 -224.675446)
		(width 0.18288)
		(layer "In2.Cu")
		(net "M_F_CPU0_SB_DQS_DN<6>")
	)
	(segment
		(start 419.63721 -217.84818)
		(end 419.34003 -217.551)
		(width 0.18288)
		(layer "In2.Cu")
		(net "M_F_CPU0_SB_DQS_DN<6>")
	)
	(segment
		(start 384.176016 -229.824026)
		(end 384.116834 -229.83952)
		(width 0.088646)
		(layer "In2.Cu")
		(net "M_F_CPU0_SB_DQS_DN<6>")
	)
	(segment
		(start 422.9481 -218.549728)
		(end 422.717976 -218.319604)
		(width 0.18288)
		(layer "In2.Cu")
		(net "M_F_CPU0_SB_DQS_DN<6>")
	)
	(segment
		(start 395.805914 -225.627438)
		(end 395.629892 -225.627438)
		(width 0.18288)
		(layer "In2.Cu")
		(net "M_F_CPU0_SB_DQS_DN<6>")
	)
	(segment
		(start 396.581884 -224.675446)
		(end 396.194026 -225.063304)
		(width 0.18288)
		(layer "In2.Cu")
		(net "M_F_CPU0_SB_DQS_DN<6>")
	)
	(segment
		(start 423.399966 -218.549728)
		(end 422.9481 -218.549728)
		(width 0.18288)
		(layer "In2.Cu")
		(net "M_F_CPU0_SB_DQS_DN<6>")
	)
	(segment
		(start 398.66189 -222.771462)
		(end 398.485868 -222.771462)
		(width 0.18288)
		(layer "In2.Cu")
		(net "M_F_CPU0_SB_DQS_DN<6>")
	)
	(segment
		(start 394.6779 -226.57943)
		(end 393.677902 -227.579428)
		(width 0.18288)
		(layer "In2.Cu")
		(net "M_F_CPU0_SB_DQS_DN<6>")
	)
	(segment
		(start 390.973818 -227.579428)
		(end 390.425178 -227.579428)
		(width 0.18288)
		(layer "In2.Cu")
		(net "M_F_CPU0_SB_DQS_DN<6>")
	)
	(segment
		(start 390.425178 -227.579428)
		(end 390.300718 -227.703888)
		(width 0.18288)
		(layer "In2.Cu")
		(net "M_F_CPU0_SB_DQS_DN<6>")
	)
	(segment
		(start 417.61791 -217.375994)
		(end 417.602162 -217.375994)
		(width 0.16002)
		(layer "In2.Cu")
		(net "M_F_CPU0_SB_DQS_DN<6>")
	)
	(segment
		(start 405.965914 -216.517982)
		(end 405.950166 -216.517982)
		(width 0.16002)
		(layer "In2.Cu")
		(net "M_F_CPU0_SB_DQS_DN<6>")
	)
	(segment
		(start 397.146018 -224.287334)
		(end 396.757906 -224.675446)
		(width 0.18288)
		(layer "In2.Cu")
		(net "M_F_CPU0_SB_DQS_DN<6>")
	)
	(segment
		(start 424.051476 -218.27998)
		(end 423.399966 -218.549728)
		(width 0.18288)
		(layer "In2.Cu")
		(net "M_F_CPU0_SB_DQS_DN<6>")
	)
	(segment
		(start 399.917412 -221.81947)
		(end 399.43786 -221.81947)
		(width 0.18288)
		(layer "In2.Cu")
		(net "M_F_CPU0_SB_DQS_DN<6>")
	)
	(segment
		(start 413.667448 -217.872818)
		(end 413.37484 -218.165426)
		(width 0.18288)
		(layer "In2.Cu")
		(net "M_F_CPU0_SB_DQS_DN<6>")
	)
	(segment
		(start 419.311836 -217.507058)
		(end 419.172898 -217.36812)
		(width 0.16002)
		(layer "In2.Cu")
		(net "M_F_CPU0_SB_DQS_DN<6>")
	)
	(segment
		(start 396.194026 -225.239326)
		(end 395.805914 -225.627438)
		(width 0.18288)
		(layer "In2.Cu")
		(net "M_F_CPU0_SB_DQS_DN<6>")
	)
	(segment
		(start 404.274274 -217.462608)
		(end 404.274274 -217.63863)
		(width 0.18288)
		(layer "In2.Cu")
		(net "M_F_CPU0_SB_DQS_DN<6>")
	)
	(segment
		(start 399.050002 -222.207328)
		(end 399.050002 -222.38335)
		(width 0.18288)
		(layer "In2.Cu")
		(net "M_F_CPU0_SB_DQS_DN<6>")
	)
	(segment
		(start 419.15715 -217.36812)
		(end 419.128956 -217.339926)
		(width 0.16002)
		(layer "In2.Cu")
		(net "M_F_CPU0_SB_DQS_DN<6>")
	)
	(segment
		(start 424.549316 -218.27998)
		(end 424.051476 -218.27998)
		(width 0.18288)
		(layer "In2.Cu")
		(net "M_F_CPU0_SB_DQS_DN<6>")
	)
	(segment
		(start 407.47188 -216.39149)
		(end 406.092406 -216.39149)
		(width 0.18288)
		(layer "In2.Cu")
		(net "M_F_CPU0_SB_DQS_DN<6>")
	)
	(segment
		(start 415.596832 -218.165426)
		(end 415.195766 -218.165426)
		(width 0.18288)
		(layer "In2.Cu")
		(net "M_F_CPU0_SB_DQS_DN<6>")
	)
	(segment
		(start 384.580384 -229.272846)
		(end 384.580384 -229.282752)
		(width 0.088646)
		(layer "In2.Cu")
		(net "M_F_CPU0_SB_DQS_DN<6>")
	)
	(segment
		(start 417.145724 -217.84818)
		(end 415.914078 -217.84818)
		(width 0.18288)
		(layer "In2.Cu")
		(net "M_F_CPU0_SB_DQS_DN<6>")
	)
	(segment
		(start 402.93417 -218.978734)
		(end 402.758148 -218.978734)
		(width 0.18288)
		(layer "In2.Cu")
		(net "M_F_CPU0_SB_DQS_DN<6>")
	)
	(segment
		(start 422.232328 -217.833956)
		(end 421.237664 -217.833956)
		(width 0.18288)
		(layer "In2.Cu")
		(net "M_F_CPU0_SB_DQS_DN<6>")
	)
	(segment
		(start 406.092406 -216.39149)
		(end 405.994108 -216.489788)
		(width 0.18288)
		(layer "In2.Cu")
		(net "M_F_CPU0_SB_DQS_DN<6>")
	)
	(segment
		(start 414.903158 -217.872818)
		(end 413.667448 -217.872818)
		(width 0.18288)
		(layer "In2.Cu")
		(net "M_F_CPU0_SB_DQS_DN<6>")
	)
	(segment
		(start 399.43786 -221.81947)
		(end 399.050002 -222.207328)
		(width 0.18288)
		(layer "In2.Cu")
		(net "M_F_CPU0_SB_DQS_DN<6>")
	)
	(segment
		(start 424.836082 -218.566746)
		(end 424.549316 -218.27998)
		(width 0.18288)
		(layer "In2.Cu")
		(net "M_F_CPU0_SB_DQS_DN<6>")
	)
	(segment
		(start 404.662132 -217.07475)
		(end 404.274274 -217.462608)
		(width 0.18288)
		(layer "In2.Cu")
		(net "M_F_CPU0_SB_DQS_DN<6>")
	)
	(segment
		(start 395.629892 -225.627438)
		(end 395.242034 -226.015296)
		(width 0.18288)
		(layer "In2.Cu")
		(net "M_F_CPU0_SB_DQS_DN<6>")
	)
	(segment
		(start 388.26948 -228.304344)
		(end 387.791706 -228.782118)
		(width 0.088646)
		(layer "In2.Cu")
		(net "M_F_CPU0_SB_DQS_DN<6>")
	)
	(segment
		(start 420.537894 -218.142058)
		(end 420.244016 -217.84818)
		(width 0.18288)
		(layer "In2.Cu")
		(net "M_F_CPU0_SB_DQS_DN<6>")
	)
	(segment
		(start 383.935732 -229.83952)
		(end 383.785364 -229.795832)
		(width 0.088646)
		(layer "In2.Cu")
		(net "M_F_CPU0_SB_DQS_DN<6>")
	)
	(segment
		(start 401.806156 -219.930726)
		(end 399.917412 -221.81947)
		(width 0.18288)
		(layer "In2.Cu")
		(net "M_F_CPU0_SB_DQS_DN<6>")
	)
	(segment
		(start 411.363668 -217.06078)
		(end 410.04363 -217.06078)
		(width 0.18288)
		(layer "In2.Cu")
		(net "M_F_CPU0_SB_DQS_DN<6>")
	)
	(segment
		(start 405.409146 -217.07475)
		(end 404.662132 -217.07475)
		(width 0.18288)
		(layer "In2.Cu")
		(net "M_F_CPU0_SB_DQS_DN<6>")
	)
	(segment
		(start 413.37484 -218.165426)
		(end 413.019494 -218.165426)
		(width 0.18288)
		(layer "In2.Cu")
		(net "M_F_CPU0_SB_DQS_DN<6>")
	)
	(segment
		(start 398.09801 -223.335342)
		(end 397.709898 -223.723454)
		(width 0.18288)
		(layer "In2.Cu")
		(net "M_F_CPU0_SB_DQS_DN<6>")
	)
	(segment
		(start 398.09801 -223.15932)
		(end 398.09801 -223.335342)
		(width 0.18288)
		(layer "In2.Cu")
		(net "M_F_CPU0_SB_DQS_DN<6>")
	)
	(segment
		(start 396.194026 -225.063304)
		(end 396.194026 -225.239326)
		(width 0.18288)
		(layer "In2.Cu")
		(net "M_F_CPU0_SB_DQS_DN<6>")
	)
	(segment
		(start 415.914078 -217.84818)
		(end 415.596832 -218.165426)
		(width 0.18288)
		(layer "In2.Cu")
		(net "M_F_CPU0_SB_DQS_DN<6>")
	)
	(segment
		(start 383.785364 -229.795832)
		(end 383.700528 -229.795832)
		(width 0.088646)
		(layer "In2.Cu")
		(net "M_F_CPU0_SB_DQS_DN<6>")
	)
	(segment
		(start 383.56286 -229.868222)
		(end 383.545334 -230.086662)
		(width 0.088646)
		(layer "In2.Cu")
		(net "M_F_CPU0_SB_DQS_DN<6>")
	)
	(segment
		(start 390.300718 -227.703888)
		(end 389.752078 -227.703888)
		(width 0.18288)
		(layer "In2.Cu")
		(net "M_F_CPU0_SB_DQS_DN<6>")
	)
	(segment
		(start 384.116834 -229.83952)
		(end 383.935732 -229.83952)
		(width 0.088646)
		(layer "In2.Cu")
		(net "M_F_CPU0_SB_DQS_DN<6>")
	)
	(segment
		(start 403.322282 -218.590622)
		(end 402.93417 -218.978734)
		(width 0.18288)
		(layer "In2.Cu")
		(net "M_F_CPU0_SB_DQS_DN<6>")
	)
	(segment
		(start 422.717976 -218.319604)
		(end 422.689782 -218.29141)
		(width 0.16002)
		(layer "In2.Cu")
		(net "M_F_CPU0_SB_DQS_DN<6>")
	)
	(segment
		(start 384.20421 -229.816406)
		(end 384.176016 -229.824026)
		(width 0.088646)
		(layer "In2.Cu")
		(net "M_F_CPU0_SB_DQS_DN<6>")
	)
	(segment
		(start 422.689782 -218.29141)
		(end 422.689782 -218.275662)
		(width 0.16002)
		(layer "In2.Cu")
		(net "M_F_CPU0_SB_DQS_DN<6>")
	)
	(arc
		(start 386.647436 -228.948488)
		(mid 386.364734 -229.024264)
		(end 386.082032 -228.948488)
		(width 0.088646)
		(layer "In2.Cu")
		(net "M_F_CPU0_SB_DQS_DN<6>")
	)
	(arc
		(start 384.758946 -228.953568)
		(mid 384.628032 -229.089928)
		(end 384.580384 -229.272846)
		(width 0.088646)
		(layer "In2.Cu")
		(net "M_F_CPU0_SB_DQS_DN<6>")
	)
	(arc
		(start 387.791706 -228.782118)
		(mid 387.723472 -228.846112)
		(end 387.651244 -228.905562)
		(width 0.088646)
		(layer "In2.Cu")
		(net "M_F_CPU0_SB_DQS_DN<6>")
	)
	(arc
		(start 387.651244 -228.905562)
		(mid 387.619972 -228.928117)
		(end 387.587236 -228.948488)
		(width 0.088646)
		(layer "In2.Cu")
		(net "M_F_CPU0_SB_DQS_DN<6>")
	)
	(arc
		(start 387.587236 -228.948488)
		(mid 387.304534 -229.024264)
		(end 387.021832 -228.948488)
		(width 0.088646)
		(layer "In2.Cu")
		(net "M_F_CPU0_SB_DQS_DN<6>")
	)
	(arc
		(start 385.707636 -228.948488)
		(mid 385.424934 -229.024264)
		(end 385.142232 -228.948488)
		(width 0.088646)
		(layer "In2.Cu")
		(net "M_F_CPU0_SB_DQS_DN<6>")
	)
	(arc
		(start 384.580384 -229.282752)
		(mid 384.502273 -229.559701)
		(end 384.297936 -229.762304)
		(width 0.088646)
		(layer "In2.Cu")
		(net "M_F_CPU0_SB_DQS_DN<6>")
	)
	(arc
		(start 385.142232 -228.948488)
		(mid 384.955034 -228.898345)
		(end 384.767836 -228.948488)
		(width 0.088646)
		(layer "In2.Cu")
		(net "M_F_CPU0_SB_DQS_DN<6>")
	)
	(arc
		(start 387.021832 -228.948488)
		(mid 386.834634 -228.898345)
		(end 386.647436 -228.948488)
		(width 0.088646)
		(layer "In2.Cu")
		(net "M_F_CPU0_SB_DQS_DN<6>")
	)
	(arc
		(start 386.082032 -228.948488)
		(mid 385.894834 -228.898345)
		(end 385.707636 -228.948488)
		(width 0.088646)
		(layer "In2.Cu")
		(net "M_F_CPU0_SB_DQS_DN<6>")
	)
	(segment
		(start 431.935128 -227.662486)
		(end 432.726846 -227.662486)
		(width 0.20066)
		(layer "F.Cu")
		(net "M_F_CPU0_SB_DQS_DN<5>")
	)
	(segment
		(start 380.25578 -237.947454)
		(end 380.256034 -237.411514)
		(width 0.20066)
		(layer "F.Cu")
		(net "M_F_CPU0_SB_DQS_DN<5>")
	)
	(segment
		(start 428.363126 -227.497894)
		(end 428.367952 -227.497894)
		(width 0.101854)
		(layer "F.Cu")
		(net "M_F_CPU0_SB_DQS_DN<5>")
	)
	(segment
		(start 428.367952 -227.497894)
		(end 428.374048 -227.491798)
		(width 0.1016)
		(layer "F.Cu")
		(net "M_F_CPU0_SB_DQS_DN<5>")
	)
	(segment
		(start 430.384204 -227.491798)
		(end 430.395126 -227.50272)
		(width 0.1016)
		(layer "F.Cu")
		(net "M_F_CPU0_SB_DQS_DN<5>")
	)
	(segment
		(start 427.651164 -227.220526)
		(end 427.773592 -227.220526)
		(width 0.20066)
		(layer "F.Cu")
		(net "M_F_CPU0_SB_DQS_DN<5>")
	)
	(segment
		(start 427.773592 -227.220526)
		(end 428.05096 -227.497894)
		(width 0.20066)
		(layer "F.Cu")
		(net "M_F_CPU0_SB_DQS_DN<5>")
	)
	(segment
		(start 426.74286 -227.645468)
		(end 427.226222 -227.645468)
		(width 0.20066)
		(layer "F.Cu")
		(net "M_F_CPU0_SB_DQS_DN<5>")
	)
	(segment
		(start 431.489612 -227.21697)
		(end 431.935128 -227.662486)
		(width 0.20066)
		(layer "F.Cu")
		(net "M_F_CPU0_SB_DQS_DN<5>")
	)
	(segment
		(start 425.940982 -227.91674)
		(end 426.471588 -227.91674)
		(width 0.20066)
		(layer "F.Cu")
		(net "M_F_CPU0_SB_DQS_DN<5>")
	)
	(segment
		(start 428.05096 -227.497894)
		(end 428.363126 -227.497894)
		(width 0.20066)
		(layer "F.Cu")
		(net "M_F_CPU0_SB_DQS_DN<5>")
	)
	(segment
		(start 430.395126 -227.50272)
		(end 430.713896 -227.50272)
		(width 0.20066)
		(layer "F.Cu")
		(net "M_F_CPU0_SB_DQS_DN<5>")
	)
	(segment
		(start 424.836082 -227.91674)
		(end 425.940982 -227.91674)
		(width 0.20066)
		(layer "F.Cu")
		(net "M_F_CPU0_SB_DQS_DN<5>")
	)
	(segment
		(start 426.471588 -227.91674)
		(end 426.74286 -227.645468)
		(width 0.20066)
		(layer "F.Cu")
		(net "M_F_CPU0_SB_DQS_DN<5>")
	)
	(segment
		(start 432.9811 -227.91674)
		(end 433.484782 -227.91674)
		(width 0.20066)
		(layer "F.Cu")
		(net "M_F_CPU0_SB_DQS_DN<5>")
	)
	(segment
		(start 430.999646 -227.21697)
		(end 431.489612 -227.21697)
		(width 0.20066)
		(layer "F.Cu")
		(net "M_F_CPU0_SB_DQS_DN<5>")
	)
	(segment
		(start 427.226222 -227.645468)
		(end 427.651164 -227.220526)
		(width 0.20066)
		(layer "F.Cu")
		(net "M_F_CPU0_SB_DQS_DN<5>")
	)
	(segment
		(start 432.726846 -227.662486)
		(end 432.9811 -227.91674)
		(width 0.20066)
		(layer "F.Cu")
		(net "M_F_CPU0_SB_DQS_DN<5>")
	)
	(segment
		(start 428.374048 -227.491798)
		(end 430.384204 -227.491798)
		(width 0.1016)
		(layer "F.Cu")
		(net "M_F_CPU0_SB_DQS_DN<5>")
	)
	(segment
		(start 430.713896 -227.50272)
		(end 430.999646 -227.21697)
		(width 0.20066)
		(layer "F.Cu")
		(net "M_F_CPU0_SB_DQS_DN<5>")
	)
	(segment
		(start 413.21609 -224.912936)
		(end 412.987998 -224.912936)
		(width 0.18288)
		(layer "In4.Cu")
		(net "M_F_CPU0_SB_DQS_DN<5>")
	)
	(segment
		(start 424.575478 -227.656136)
		(end 424.187112 -227.656136)
		(width 0.18288)
		(layer "In4.Cu")
		(net "M_F_CPU0_SB_DQS_DN<5>")
	)
	(segment
		(start 395.63548 -232.652824)
		(end 395.2494 -233.038904)
		(width 0.18288)
		(layer "In4.Cu")
		(net "M_F_CPU0_SB_DQS_DN<5>")
	)
	(segment
		(start 385.707636 -237.08741)
		(end 385.707382 -237.087664)
		(width 0.088646)
		(layer "In4.Cu")
		(net "M_F_CPU0_SB_DQS_DN<5>")
	)
	(segment
		(start 420.544244 -227.49383)
		(end 420.275512 -227.225098)
		(width 0.18288)
		(layer "In4.Cu")
		(net "M_F_CPU0_SB_DQS_DN<5>")
	)
	(segment
		(start 398.094708 -230.369618)
		(end 397.708374 -230.755952)
		(width 0.18288)
		(layer "In4.Cu")
		(net "M_F_CPU0_SB_DQS_DN<5>")
	)
	(segment
		(start 388.858252 -235.330746)
		(end 388.53491 -235.330746)
		(width 0.088646)
		(layer "In4.Cu")
		(net "M_F_CPU0_SB_DQS_DN<5>")
	)
	(segment
		(start 399.043144 -229.24516)
		(end 399.043144 -229.421182)
		(width 0.18288)
		(layer "In4.Cu")
		(net "M_F_CPU0_SB_DQS_DN<5>")
	)
	(segment
		(start 418.079682 -226.016566)
		(end 417.478972 -225.767646)
		(width 0.18288)
		(layer "In4.Cu")
		(net "M_F_CPU0_SB_DQS_DN<5>")
	)
	(segment
		(start 422.61917 -226.61372)
		(end 422.003474 -227.229416)
		(width 0.18288)
		(layer "In4.Cu")
		(net "M_F_CPU0_SB_DQS_DN<5>")
	)
	(segment
		(start 410.369004 -224.660968)
		(end 410.223716 -224.660968)
		(width 0.18288)
		(layer "In4.Cu")
		(net "M_F_CPU0_SB_DQS_DN<5>")
	)
	(segment
		(start 388.086346 -235.77931)
		(end 388.086346 -236.478826)
		(width 0.088646)
		(layer "In4.Cu")
		(net "M_F_CPU0_SB_DQS_DN<5>")
	)
	(segment
		(start 413.73171 -225.126042)
		(end 413.21609 -224.912936)
		(width 0.18288)
		(layer "In4.Cu")
		(net "M_F_CPU0_SB_DQS_DN<5>")
	)
	(segment
		(start 388.53491 -235.330746)
		(end 388.086346 -235.77931)
		(width 0.088646)
		(layer "In4.Cu")
		(net "M_F_CPU0_SB_DQS_DN<5>")
	)
	(segment
		(start 397.146272 -231.318054)
		(end 396.759938 -231.704388)
		(width 0.18288)
		(layer "In4.Cu")
		(net "M_F_CPU0_SB_DQS_DN<5>")
	)
	(segment
		(start 388.941564 -235.39069)
		(end 388.918196 -235.39069)
		(width 0.088646)
		(layer "In4.Cu")
		(net "M_F_CPU0_SB_DQS_DN<5>")
	)
	(segment
		(start 403.478238 -225.605086)
		(end 403.353778 -225.480626)
		(width 0.18288)
		(layer "In4.Cu")
		(net "M_F_CPU0_SB_DQS_DN<5>")
	)
	(segment
		(start 424.187112 -227.656136)
		(end 423.919142 -227.388166)
		(width 0.18288)
		(layer "In4.Cu")
		(net "M_F_CPU0_SB_DQS_DN<5>")
	)
	(segment
		(start 399.99158 -228.296724)
		(end 399.99158 -228.472746)
		(width 0.18288)
		(layer "In4.Cu")
		(net "M_F_CPU0_SB_DQS_DN<5>")
	)
	(segment
		(start 381.008382 -237.08741)
		(end 381.002286 -237.090712)
		(width 0.088646)
		(layer "In4.Cu")
		(net "M_F_CPU0_SB_DQS_DN<5>")
	)
	(segment
		(start 423.248074 -226.61372)
		(end 422.61917 -226.61372)
		(width 0.18288)
		(layer "In4.Cu")
		(net "M_F_CPU0_SB_DQS_DN<5>")
	)
	(segment
		(start 389.501126 -235.39069)
		(end 388.941564 -235.39069)
		(width 0.18288)
		(layer "In4.Cu")
		(net "M_F_CPU0_SB_DQS_DN<5>")
	)
	(segment
		(start 401.326096 -226.962208)
		(end 400.940016 -227.348288)
		(width 0.18288)
		(layer "In4.Cu")
		(net "M_F_CPU0_SB_DQS_DN<5>")
	)
	(segment
		(start 401.502118 -226.962208)
		(end 401.326096 -226.962208)
		(width 0.18288)
		(layer "In4.Cu")
		(net "M_F_CPU0_SB_DQS_DN<5>")
	)
	(segment
		(start 424.836082 -227.91674)
		(end 424.575478 -227.656136)
		(width 0.18288)
		(layer "In4.Cu")
		(net "M_F_CPU0_SB_DQS_DN<5>")
	)
	(segment
		(start 391.852912 -233.038904)
		(end 389.501126 -235.39069)
		(width 0.18288)
		(layer "In4.Cu")
		(net "M_F_CPU0_SB_DQS_DN<5>")
	)
	(segment
		(start 399.605246 -228.85908)
		(end 399.429224 -228.85908)
		(width 0.18288)
		(layer "In4.Cu")
		(net "M_F_CPU0_SB_DQS_DN<5>")
	)
	(segment
		(start 380.87681 -237.163102)
		(end 380.72187 -237.204504)
		(width 0.088646)
		(layer "In4.Cu")
		(net "M_F_CPU0_SB_DQS_DN<5>")
	)
	(segment
		(start 405.143462 -225.480626)
		(end 404.148798 -225.480626)
		(width 0.18288)
		(layer "In4.Cu")
		(net "M_F_CPU0_SB_DQS_DN<5>")
	)
	(segment
		(start 412.987998 -224.912936)
		(end 412.081218 -225.288602)
		(width 0.18288)
		(layer "In4.Cu")
		(net "M_F_CPU0_SB_DQS_DN<5>")
	)
	(segment
		(start 423.701718 -226.866196)
		(end 423.591736 -226.756468)
		(width 0.18288)
		(layer "In4.Cu")
		(net "M_F_CPU0_SB_DQS_DN<5>")
	)
	(segment
		(start 409.94076 -224.943924)
		(end 409.556712 -224.943924)
		(width 0.18288)
		(layer "In4.Cu")
		(net "M_F_CPU0_SB_DQS_DN<5>")
	)
	(segment
		(start 400.940016 -227.348288)
		(end 400.940016 -227.52431)
		(width 0.18288)
		(layer "In4.Cu")
		(net "M_F_CPU0_SB_DQS_DN<5>")
	)
	(segment
		(start 420.275512 -227.225098)
		(end 419.288468 -227.225098)
		(width 0.18288)
		(layer "In4.Cu")
		(net "M_F_CPU0_SB_DQS_DN<5>")
	)
	(segment
		(start 417.158424 -225.767646)
		(end 416.263328 -226.138486)
		(width 0.18288)
		(layer "In4.Cu")
		(net "M_F_CPU0_SB_DQS_DN<5>")
	)
	(segment
		(start 409.26512 -224.652332)
		(end 408.467052 -224.652332)
		(width 0.18288)
		(layer "In4.Cu")
		(net "M_F_CPU0_SB_DQS_DN<5>")
	)
	(segment
		(start 380.72187 -237.204504)
		(end 380.330456 -237.204504)
		(width 0.088646)
		(layer "In4.Cu")
		(net "M_F_CPU0_SB_DQS_DN<5>")
	)
	(segment
		(start 400.553682 -227.910644)
		(end 400.37766 -227.910644)
		(width 0.18288)
		(layer "In4.Cu")
		(net "M_F_CPU0_SB_DQS_DN<5>")
	)
	(segment
		(start 386.096764 -237.096046)
		(end 386.082032 -237.08741)
		(width 0.088646)
		(layer "In4.Cu")
		(net "M_F_CPU0_SB_DQS_DN<5>")
	)
	(segment
		(start 401.888452 -226.399852)
		(end 401.888452 -226.575874)
		(width 0.18288)
		(layer "In4.Cu")
		(net "M_F_CPU0_SB_DQS_DN<5>")
	)
	(segment
		(start 397.146272 -231.142032)
		(end 397.146272 -231.318054)
		(width 0.18288)
		(layer "In4.Cu")
		(net "M_F_CPU0_SB_DQS_DN<5>")
	)
	(segment
		(start 416.263328 -226.138486)
		(end 414.744408 -226.138486)
		(width 0.18288)
		(layer "In4.Cu")
		(net "M_F_CPU0_SB_DQS_DN<5>")
	)
	(segment
		(start 414.744408 -226.138486)
		(end 413.73171 -225.126042)
		(width 0.18288)
		(layer "In4.Cu")
		(net "M_F_CPU0_SB_DQS_DN<5>")
	)
	(segment
		(start 388.086346 -236.478826)
		(end 387.779514 -236.937804)
		(width 0.088646)
		(layer "In4.Cu")
		(net "M_F_CPU0_SB_DQS_DN<5>")
	)
	(segment
		(start 397.532352 -230.755952)
		(end 397.146272 -231.142032)
		(width 0.18288)
		(layer "In4.Cu")
		(net "M_F_CPU0_SB_DQS_DN<5>")
	)
	(segment
		(start 405.456644 -225.793808)
		(end 405.143462 -225.480626)
		(width 0.18288)
		(layer "In4.Cu")
		(net "M_F_CPU0_SB_DQS_DN<5>")
	)
	(segment
		(start 399.043144 -229.421182)
		(end 398.65681 -229.807516)
		(width 0.18288)
		(layer "In4.Cu")
		(net "M_F_CPU0_SB_DQS_DN<5>")
	)
	(segment
		(start 398.65681 -229.807516)
		(end 398.480788 -229.807516)
		(width 0.18288)
		(layer "In4.Cu")
		(net "M_F_CPU0_SB_DQS_DN<5>")
	)
	(segment
		(start 421.192706 -227.229416)
		(end 420.928292 -227.49383)
		(width 0.18288)
		(layer "In4.Cu")
		(net "M_F_CPU0_SB_DQS_DN<5>")
	)
	(segment
		(start 400.37766 -227.910644)
		(end 399.99158 -228.296724)
		(width 0.18288)
		(layer "In4.Cu")
		(net "M_F_CPU0_SB_DQS_DN<5>")
	)
	(segment
		(start 395.2494 -233.038904)
		(end 391.852912 -233.038904)
		(width 0.18288)
		(layer "In4.Cu")
		(net "M_F_CPU0_SB_DQS_DN<5>")
	)
	(segment
		(start 397.708374 -230.755952)
		(end 397.532352 -230.755952)
		(width 0.18288)
		(layer "In4.Cu")
		(net "M_F_CPU0_SB_DQS_DN<5>")
	)
	(segment
		(start 411.884368 -225.288602)
		(end 410.369004 -224.660968)
		(width 0.18288)
		(layer "In4.Cu")
		(net "M_F_CPU0_SB_DQS_DN<5>")
	)
	(segment
		(start 388.918196 -235.39069)
		(end 388.858252 -235.330746)
		(width 0.088646)
		(layer "In4.Cu")
		(net "M_F_CPU0_SB_DQS_DN<5>")
	)
	(segment
		(start 396.197836 -232.090468)
		(end 396.197836 -232.26649)
		(width 0.18288)
		(layer "In4.Cu")
		(net "M_F_CPU0_SB_DQS_DN<5>")
	)
	(segment
		(start 396.197836 -232.26649)
		(end 395.811502 -232.652824)
		(width 0.18288)
		(layer "In4.Cu")
		(net "M_F_CPU0_SB_DQS_DN<5>")
	)
	(segment
		(start 383.277364 -237.096046)
		(end 383.262632 -237.08741)
		(width 0.088646)
		(layer "In4.Cu")
		(net "M_F_CPU0_SB_DQS_DN<5>")
	)
	(segment
		(start 410.223716 -224.660968)
		(end 409.94076 -224.943924)
		(width 0.18288)
		(layer "In4.Cu")
		(net "M_F_CPU0_SB_DQS_DN<5>")
	)
	(segment
		(start 420.928292 -227.49383)
		(end 420.544244 -227.49383)
		(width 0.18288)
		(layer "In4.Cu")
		(net "M_F_CPU0_SB_DQS_DN<5>")
	)
	(segment
		(start 395.811502 -232.652824)
		(end 395.63548 -232.652824)
		(width 0.18288)
		(layer "In4.Cu")
		(net "M_F_CPU0_SB_DQS_DN<5>")
	)
	(segment
		(start 387.779514 -236.937804)
		(end 387.554216 -237.163102)
		(width 0.088646)
		(layer "In4.Cu")
		(net "M_F_CPU0_SB_DQS_DN<5>")
	)
	(segment
		(start 422.003474 -227.229416)
		(end 421.192706 -227.229416)
		(width 0.18288)
		(layer "In4.Cu")
		(net "M_F_CPU0_SB_DQS_DN<5>")
	)
	(segment
		(start 406.107138 -225.527362)
		(end 405.840692 -225.793808)
		(width 0.18288)
		(layer "In4.Cu")
		(net "M_F_CPU0_SB_DQS_DN<5>")
	)
	(segment
		(start 398.094708 -230.193596)
		(end 398.094708 -230.369618)
		(width 0.18288)
		(layer "In4.Cu")
		(net "M_F_CPU0_SB_DQS_DN<5>")
	)
	(segment
		(start 419.288468 -227.225098)
		(end 418.079682 -226.016566)
		(width 0.18288)
		(layer "In4.Cu")
		(net "M_F_CPU0_SB_DQS_DN<5>")
	)
	(segment
		(start 381.002286 -237.090712)
		(end 380.87681 -237.163102)
		(width 0.088646)
		(layer "In4.Cu")
		(net "M_F_CPU0_SB_DQS_DN<5>")
	)
	(segment
		(start 405.840692 -225.793808)
		(end 405.456644 -225.793808)
		(width 0.18288)
		(layer "In4.Cu")
		(net "M_F_CPU0_SB_DQS_DN<5>")
	)
	(segment
		(start 403.353778 -225.480626)
		(end 402.807678 -225.480626)
		(width 0.18288)
		(layer "In4.Cu")
		(net "M_F_CPU0_SB_DQS_DN<5>")
	)
	(segment
		(start 423.591736 -226.756468)
		(end 423.248074 -226.61372)
		(width 0.18288)
		(layer "In4.Cu")
		(net "M_F_CPU0_SB_DQS_DN<5>")
	)
	(segment
		(start 404.024338 -225.605086)
		(end 403.478238 -225.605086)
		(width 0.18288)
		(layer "In4.Cu")
		(net "M_F_CPU0_SB_DQS_DN<5>")
	)
	(segment
		(start 387.554216 -237.163102)
		(end 387.30428 -237.163102)
		(width 0.088646)
		(layer "In4.Cu")
		(net "M_F_CPU0_SB_DQS_DN<5>")
	)
	(segment
		(start 396.583916 -231.704388)
		(end 396.197836 -232.090468)
		(width 0.18288)
		(layer "In4.Cu")
		(net "M_F_CPU0_SB_DQS_DN<5>")
	)
	(segment
		(start 408.467052 -224.652332)
		(end 406.353772 -225.527362)
		(width 0.18288)
		(layer "In4.Cu")
		(net "M_F_CPU0_SB_DQS_DN<5>")
	)
	(segment
		(start 406.353772 -225.527362)
		(end 406.107138 -225.527362)
		(width 0.18288)
		(layer "In4.Cu")
		(net "M_F_CPU0_SB_DQS_DN<5>")
	)
	(segment
		(start 401.888452 -226.575874)
		(end 401.502118 -226.962208)
		(width 0.18288)
		(layer "In4.Cu")
		(net "M_F_CPU0_SB_DQS_DN<5>")
	)
	(segment
		(start 396.759938 -231.704388)
		(end 396.583916 -231.704388)
		(width 0.18288)
		(layer "In4.Cu")
		(net "M_F_CPU0_SB_DQS_DN<5>")
	)
	(segment
		(start 398.480788 -229.807516)
		(end 398.094708 -230.193596)
		(width 0.18288)
		(layer "In4.Cu")
		(net "M_F_CPU0_SB_DQS_DN<5>")
	)
	(segment
		(start 400.940016 -227.52431)
		(end 400.553682 -227.910644)
		(width 0.18288)
		(layer "In4.Cu")
		(net "M_F_CPU0_SB_DQS_DN<5>")
	)
	(segment
		(start 417.478972 -225.767646)
		(end 417.158424 -225.767646)
		(width 0.18288)
		(layer "In4.Cu")
		(net "M_F_CPU0_SB_DQS_DN<5>")
	)
	(segment
		(start 402.807678 -225.480626)
		(end 401.888452 -226.399852)
		(width 0.18288)
		(layer "In4.Cu")
		(net "M_F_CPU0_SB_DQS_DN<5>")
	)
	(segment
		(start 409.556712 -224.943924)
		(end 409.26512 -224.652332)
		(width 0.18288)
		(layer "In4.Cu")
		(net "M_F_CPU0_SB_DQS_DN<5>")
	)
	(segment
		(start 384.217164 -237.096046)
		(end 384.202432 -237.08741)
		(width 0.088646)
		(layer "In4.Cu")
		(net "M_F_CPU0_SB_DQS_DN<5>")
	)
	(segment
		(start 399.429224 -228.85908)
		(end 399.043144 -229.24516)
		(width 0.18288)
		(layer "In4.Cu")
		(net "M_F_CPU0_SB_DQS_DN<5>")
	)
	(segment
		(start 380.267972 -237.262162)
		(end 380.256034 -237.411514)
		(width 0.088646)
		(layer "In4.Cu")
		(net "M_F_CPU0_SB_DQS_DN<5>")
	)
	(segment
		(start 404.148798 -225.480626)
		(end 404.024338 -225.605086)
		(width 0.18288)
		(layer "In4.Cu")
		(net "M_F_CPU0_SB_DQS_DN<5>")
	)
	(segment
		(start 423.919142 -227.388166)
		(end 423.701718 -226.866196)
		(width 0.18288)
		(layer "In4.Cu")
		(net "M_F_CPU0_SB_DQS_DN<5>")
	)
	(segment
		(start 381.948436 -237.08741)
		(end 381.938022 -237.093506)
		(width 0.088646)
		(layer "In4.Cu")
		(net "M_F_CPU0_SB_DQS_DN<5>")
	)
	(segment
		(start 412.081218 -225.288602)
		(end 411.884368 -225.288602)
		(width 0.18288)
		(layer "In4.Cu")
		(net "M_F_CPU0_SB_DQS_DN<5>")
	)
	(segment
		(start 399.99158 -228.472746)
		(end 399.605246 -228.85908)
		(width 0.18288)
		(layer "In4.Cu")
		(net "M_F_CPU0_SB_DQS_DN<5>")
	)
	(arc
		(start 383.828036 -237.08741)
		(mid 383.553837 -237.163245)
		(end 383.277364 -237.096046)
		(width 0.088646)
		(layer "In4.Cu")
		(net "M_F_CPU0_SB_DQS_DN<5>")
	)
	(arc
		(start 382.888236 -237.08741)
		(mid 382.605534 -237.163186)
		(end 382.322832 -237.08741)
		(width 0.088646)
		(layer "In4.Cu")
		(net "M_F_CPU0_SB_DQS_DN<5>")
	)
	(arc
		(start 384.202432 -237.08741)
		(mid 384.015234 -237.037233)
		(end 383.828036 -237.08741)
		(width 0.088646)
		(layer "In4.Cu")
		(net "M_F_CPU0_SB_DQS_DN<5>")
	)
	(arc
		(start 385.707382 -237.087664)
		(mid 385.424761 -237.163279)
		(end 385.142232 -237.08741)
		(width 0.088646)
		(layer "In4.Cu")
		(net "M_F_CPU0_SB_DQS_DN<5>")
	)
	(arc
		(start 386.647436 -237.08741)
		(mid 386.373237 -237.163245)
		(end 386.096764 -237.096046)
		(width 0.088646)
		(layer "In4.Cu")
		(net "M_F_CPU0_SB_DQS_DN<5>")
	)
	(arc
		(start 384.767836 -237.08741)
		(mid 384.493637 -237.163245)
		(end 384.217164 -237.096046)
		(width 0.088646)
		(layer "In4.Cu")
		(net "M_F_CPU0_SB_DQS_DN<5>")
	)
	(arc
		(start 387.021832 -237.08741)
		(mid 386.834634 -237.037233)
		(end 386.647436 -237.08741)
		(width 0.088646)
		(layer "In4.Cu")
		(net "M_F_CPU0_SB_DQS_DN<5>")
	)
	(arc
		(start 380.330456 -237.204504)
		(mid 380.287929 -237.221117)
		(end 380.267972 -237.262162)
		(width 0.088646)
		(layer "In4.Cu")
		(net "M_F_CPU0_SB_DQS_DN<5>")
	)
	(arc
		(start 386.082032 -237.08741)
		(mid 385.894834 -237.037233)
		(end 385.707636 -237.08741)
		(width 0.088646)
		(layer "In4.Cu")
		(net "M_F_CPU0_SB_DQS_DN<5>")
	)
	(arc
		(start 381.938022 -237.093506)
		(mid 381.65959 -237.163352)
		(end 381.382778 -237.08741)
		(width 0.088646)
		(layer "In4.Cu")
		(net "M_F_CPU0_SB_DQS_DN<5>")
	)
	(arc
		(start 381.382778 -237.08741)
		(mid 381.19558 -237.037233)
		(end 381.008382 -237.08741)
		(width 0.088646)
		(layer "In4.Cu")
		(net "M_F_CPU0_SB_DQS_DN<5>")
	)
	(arc
		(start 387.30428 -237.163102)
		(mid 387.158072 -237.143853)
		(end 387.021832 -237.08741)
		(width 0.088646)
		(layer "In4.Cu")
		(net "M_F_CPU0_SB_DQS_DN<5>")
	)
	(arc
		(start 385.142232 -237.08741)
		(mid 384.955034 -237.037233)
		(end 384.767836 -237.08741)
		(width 0.088646)
		(layer "In4.Cu")
		(net "M_F_CPU0_SB_DQS_DN<5>")
	)
	(arc
		(start 382.322832 -237.08741)
		(mid 382.135634 -237.037233)
		(end 381.948436 -237.08741)
		(width 0.088646)
		(layer "In4.Cu")
		(net "M_F_CPU0_SB_DQS_DN<5>")
	)
	(arc
		(start 383.262632 -237.08741)
		(mid 383.075434 -237.037233)
		(end 382.888236 -237.08741)
		(width 0.088646)
		(layer "In4.Cu")
		(net "M_F_CPU0_SB_DQS_DN<5>")
	)
	(segment
		(start 428.367952 -236.847888)
		(end 428.374048 -236.841792)
		(width 0.1016)
		(layer "F.Cu")
		(net "M_F_CPU0_SB_DQS_DN<4>")
	)
	(segment
		(start 426.74286 -236.995462)
		(end 427.226222 -236.995462)
		(width 0.20066)
		(layer "F.Cu")
		(net "M_F_CPU0_SB_DQS_DN<4>")
	)
	(segment
		(start 427.651164 -236.57052)
		(end 427.773592 -236.57052)
		(width 0.20066)
		(layer "F.Cu")
		(net "M_F_CPU0_SB_DQS_DN<4>")
	)
	(segment
		(start 425.940982 -237.266734)
		(end 426.471588 -237.266734)
		(width 0.20066)
		(layer "F.Cu")
		(net "M_F_CPU0_SB_DQS_DN<4>")
	)
	(segment
		(start 428.363126 -236.847888)
		(end 428.367952 -236.847888)
		(width 0.101854)
		(layer "F.Cu")
		(net "M_F_CPU0_SB_DQS_DN<4>")
	)
	(segment
		(start 427.773592 -236.57052)
		(end 428.05096 -236.847888)
		(width 0.20066)
		(layer "F.Cu")
		(net "M_F_CPU0_SB_DQS_DN<4>")
	)
	(segment
		(start 431.935128 -237.01248)
		(end 432.726846 -237.01248)
		(width 0.20066)
		(layer "F.Cu")
		(net "M_F_CPU0_SB_DQS_DN<4>")
	)
	(segment
		(start 428.374048 -236.841792)
		(end 430.384204 -236.841792)
		(width 0.1016)
		(layer "F.Cu")
		(net "M_F_CPU0_SB_DQS_DN<4>")
	)
	(segment
		(start 432.726846 -237.01248)
		(end 432.9811 -237.266734)
		(width 0.20066)
		(layer "F.Cu")
		(net "M_F_CPU0_SB_DQS_DN<4>")
	)
	(segment
		(start 431.489612 -236.566964)
		(end 431.935128 -237.01248)
		(width 0.20066)
		(layer "F.Cu")
		(net "M_F_CPU0_SB_DQS_DN<4>")
	)
	(segment
		(start 426.471588 -237.266734)
		(end 426.74286 -236.995462)
		(width 0.20066)
		(layer "F.Cu")
		(net "M_F_CPU0_SB_DQS_DN<4>")
	)
	(segment
		(start 428.05096 -236.847888)
		(end 428.363126 -236.847888)
		(width 0.20066)
		(layer "F.Cu")
		(net "M_F_CPU0_SB_DQS_DN<4>")
	)
	(segment
		(start 432.9811 -237.266734)
		(end 433.484782 -237.266734)
		(width 0.20066)
		(layer "F.Cu")
		(net "M_F_CPU0_SB_DQS_DN<4>")
	)
	(segment
		(start 430.999646 -236.566964)
		(end 431.489612 -236.566964)
		(width 0.20066)
		(layer "F.Cu")
		(net "M_F_CPU0_SB_DQS_DN<4>")
	)
	(segment
		(start 430.713896 -236.852714)
		(end 430.999646 -236.566964)
		(width 0.20066)
		(layer "F.Cu")
		(net "M_F_CPU0_SB_DQS_DN<4>")
	)
	(segment
		(start 383.545334 -240.389156)
		(end 383.545334 -239.853216)
		(width 0.20066)
		(layer "F.Cu")
		(net "M_F_CPU0_SB_DQS_DN<4>")
	)
	(segment
		(start 430.384204 -236.841792)
		(end 430.395126 -236.852714)
		(width 0.1016)
		(layer "F.Cu")
		(net "M_F_CPU0_SB_DQS_DN<4>")
	)
	(segment
		(start 430.395126 -236.852714)
		(end 430.713896 -236.852714)
		(width 0.20066)
		(layer "F.Cu")
		(net "M_F_CPU0_SB_DQS_DN<4>")
	)
	(segment
		(start 427.226222 -236.995462)
		(end 427.651164 -236.57052)
		(width 0.20066)
		(layer "F.Cu")
		(net "M_F_CPU0_SB_DQS_DN<4>")
	)
	(segment
		(start 424.836082 -237.266734)
		(end 425.940982 -237.266734)
		(width 0.20066)
		(layer "F.Cu")
		(net "M_F_CPU0_SB_DQS_DN<4>")
	)
	(segment
		(start 415.918396 -235.99521)
		(end 415.742374 -235.99521)
		(width 0.18288)
		(layer "In2.Cu")
		(net "M_F_CPU0_SB_DQS_DN<4>")
	)
	(segment
		(start 383.785872 -239.555782)
		(end 383.561844 -239.648492)
		(width 0.088646)
		(layer "In2.Cu")
		(net "M_F_CPU0_SB_DQS_DN<4>")
	)
	(segment
		(start 384.680968 -239.533938)
		(end 384.672078 -239.528858)
		(width 0.088646)
		(layer "In2.Cu")
		(net "M_F_CPU0_SB_DQS_DN<4>")
	)
	(segment
		(start 411.747716 -235.38307)
		(end 411.719522 -235.411264)
		(width 0.16002)
		(layer "In2.Cu")
		(net "M_F_CPU0_SB_DQS_DN<4>")
	)
	(segment
		(start 383.545334 -239.665002)
		(end 383.545334 -239.853216)
		(width 0.088646)
		(layer "In2.Cu")
		(net "M_F_CPU0_SB_DQS_DN<4>")
	)
	(segment
		(start 407.516838 -236.903514)
		(end 407.488644 -236.87532)
		(width 0.16002)
		(layer "In2.Cu")
		(net "M_F_CPU0_SB_DQS_DN<4>")
	)
	(segment
		(start 387.026912 -240.345976)
		(end 387.02488 -240.34496)
		(width 0.088646)
		(layer "In2.Cu")
		(net "M_F_CPU0_SB_DQS_DN<4>")
	)
	(segment
		(start 404.772368 -237.479332)
		(end 404.772368 -237.479586)
		(width 0.18288)
		(layer "In2.Cu")
		(net "M_F_CPU0_SB_DQS_DN<4>")
	)
	(segment
		(start 395.426946 -240.777522)
		(end 394.878306 -240.777522)
		(width 0.18288)
		(layer "In2.Cu")
		(net "M_F_CPU0_SB_DQS_DN<4>")
	)
	(segment
		(start 387.420612 -240.717578)
		(end 387.091174 -240.38814)
		(width 0.088646)
		(layer "In2.Cu")
		(net "M_F_CPU0_SB_DQS_DN<4>")
	)
	(segment
		(start 394.878306 -240.777522)
		(end 394.753846 -240.901982)
		(width 0.18288)
		(layer "In2.Cu")
		(net "M_F_CPU0_SB_DQS_DN<4>")
	)
	(segment
		(start 411.902402 -235.228384)
		(end 411.886146 -235.228384)
		(width 0.16002)
		(layer "In2.Cu")
		(net "M_F_CPU0_SB_DQS_DN<4>")
	)
	(segment
		(start 384.292602 -239.531906)
		(end 384.292348 -239.531906)
		(width 0.088646)
		(layer "In2.Cu")
		(net "M_F_CPU0_SB_DQS_DN<4>")
	)
	(segment
		(start 396.897606 -240.901982)
		(end 396.773146 -240.777522)
		(width 0.18288)
		(layer "In2.Cu")
		(net "M_F_CPU0_SB_DQS_DN<4>")
	)
	(segment
		(start 417.626546 -236.055662)
		(end 417.487608 -236.1946)
		(width 0.16002)
		(layer "In2.Cu")
		(net "M_F_CPU0_SB_DQS_DN<4>")
	)
	(segment
		(start 397.570706 -240.777522)
		(end 397.446246 -240.901982)
		(width 0.18288)
		(layer "In2.Cu")
		(net "M_F_CPU0_SB_DQS_DN<4>")
	)
	(segment
		(start 417.270946 -236.42701)
		(end 416.350196 -236.42701)
		(width 0.18288)
		(layer "In2.Cu")
		(net "M_F_CPU0_SB_DQS_DN<4>")
	)
	(segment
		(start 415.354262 -235.607098)
		(end 415.354262 -235.431076)
		(width 0.18288)
		(layer "In2.Cu")
		(net "M_F_CPU0_SB_DQS_DN<4>")
	)
	(segment
		(start 409.142692 -236.524546)
		(end 408.407362 -237.259876)
		(width 0.18288)
		(layer "In2.Cu")
		(net "M_F_CPU0_SB_DQS_DN<4>")
	)
	(segment
		(start 387.031992 -240.349278)
		(end 387.03123 -240.34877)
		(width 0.088646)
		(layer "In2.Cu")
		(net "M_F_CPU0_SB_DQS_DN<4>")
	)
	(segment
		(start 387.02488 -240.34496)
		(end 387.023356 -240.343944)
		(width 0.088646)
		(layer "In2.Cu")
		(net "M_F_CPU0_SB_DQS_DN<4>")
	)
	(segment
		(start 417.487608 -236.210348)
		(end 417.459414 -236.238542)
		(width 0.16002)
		(layer "In2.Cu")
		(net "M_F_CPU0_SB_DQS_DN<4>")
	)
	(segment
		(start 421.197278 -236.606842)
		(end 420.963344 -236.840776)
		(width 0.18288)
		(layer "In2.Cu")
		(net "M_F_CPU0_SB_DQS_DN<4>")
	)
	(segment
		(start 407.699718 -237.086394)
		(end 407.671524 -237.0582)
		(width 0.16002)
		(layer "In2.Cu")
		(net "M_F_CPU0_SB_DQS_DN<4>")
	)
	(segment
		(start 394.753846 -240.901982)
		(end 394.205206 -240.901982)
		(width 0.18288)
		(layer "In2.Cu")
		(net "M_F_CPU0_SB_DQS_DN<4>")
	)
	(segment
		(start 391.388346 -240.777522)
		(end 390.839706 -240.777522)
		(width 0.18288)
		(layer "In2.Cu")
		(net "M_F_CPU0_SB_DQS_DN<4>")
	)
	(segment
		(start 403.76602 -238.48568)
		(end 403.378162 -238.873538)
		(width 0.18288)
		(layer "In2.Cu")
		(net "M_F_CPU0_SB_DQS_DN<4>")
	)
	(segment
		(start 398.119346 -240.777522)
		(end 397.570706 -240.777522)
		(width 0.18288)
		(layer "In2.Cu")
		(net "M_F_CPU0_SB_DQS_DN<4>")
	)
	(segment
		(start 397.446246 -240.901982)
		(end 396.897606 -240.901982)
		(width 0.18288)
		(layer "In2.Cu")
		(net "M_F_CPU0_SB_DQS_DN<4>")
	)
	(segment
		(start 396.224506 -240.777522)
		(end 396.100046 -240.901982)
		(width 0.18288)
		(layer "In2.Cu")
		(net "M_F_CPU0_SB_DQS_DN<4>")
	)
	(segment
		(start 407.393394 -236.78007)
		(end 406.087326 -236.78007)
		(width 0.18288)
		(layer "In2.Cu")
		(net "M_F_CPU0_SB_DQS_DN<4>")
	)
	(segment
		(start 392.061446 -240.901982)
		(end 391.512806 -240.901982)
		(width 0.18288)
		(layer "In2.Cu")
		(net "M_F_CPU0_SB_DQS_DN<4>")
	)
	(segment
		(start 394.080746 -240.777522)
		(end 393.532106 -240.777522)
		(width 0.18288)
		(layer "In2.Cu")
		(net "M_F_CPU0_SB_DQS_DN<4>")
	)
	(segment
		(start 404.772368 -237.479586)
		(end 404.330408 -237.921546)
		(width 0.18288)
		(layer "In2.Cu")
		(net "M_F_CPU0_SB_DQS_DN<4>")
	)
	(segment
		(start 417.642294 -236.055662)
		(end 417.626546 -236.055662)
		(width 0.16002)
		(layer "In2.Cu")
		(net "M_F_CPU0_SB_DQS_DN<4>")
	)
	(segment
		(start 393.532106 -240.777522)
		(end 393.407646 -240.901982)
		(width 0.18288)
		(layer "In2.Cu")
		(net "M_F_CPU0_SB_DQS_DN<4>")
	)
	(segment
		(start 390.166606 -240.901982)
		(end 390.042146 -240.777522)
		(width 0.18288)
		(layer "In2.Cu")
		(net "M_F_CPU0_SB_DQS_DN<4>")
	)
	(segment
		(start 416.350196 -236.42701)
		(end 415.918396 -235.99521)
		(width 0.18288)
		(layer "In2.Cu")
		(net "M_F_CPU0_SB_DQS_DN<4>")
	)
	(segment
		(start 407.671524 -237.042452)
		(end 407.532586 -236.903514)
		(width 0.16002)
		(layer "In2.Cu")
		(net "M_F_CPU0_SB_DQS_DN<4>")
	)
	(segment
		(start 411.747716 -235.366814)
		(end 411.747716 -235.38307)
		(width 0.16002)
		(layer "In2.Cu")
		(net "M_F_CPU0_SB_DQS_DN<4>")
	)
	(segment
		(start 394.205206 -240.901982)
		(end 394.080746 -240.777522)
		(width 0.18288)
		(layer "In2.Cu")
		(net "M_F_CPU0_SB_DQS_DN<4>")
	)
	(segment
		(start 387.033008 -240.349786)
		(end 387.031992 -240.349278)
		(width 0.088646)
		(layer "In2.Cu")
		(net "M_F_CPU0_SB_DQS_DN<4>")
	)
	(segment
		(start 396.100046 -240.901982)
		(end 395.551406 -240.901982)
		(width 0.18288)
		(layer "In2.Cu")
		(net "M_F_CPU0_SB_DQS_DN<4>")
	)
	(segment
		(start 414.966404 -235.043218)
		(end 414.498282 -234.849416)
		(width 0.18288)
		(layer "In2.Cu")
		(net "M_F_CPU0_SB_DQS_DN<4>")
	)
	(segment
		(start 411.719522 -235.411264)
		(end 411.3149 -235.815886)
		(width 0.18288)
		(layer "In2.Cu")
		(net "M_F_CPU0_SB_DQS_DN<4>")
	)
	(segment
		(start 405.824182 -237.043214)
		(end 404.772368 -237.479332)
		(width 0.18288)
		(layer "In2.Cu")
		(net "M_F_CPU0_SB_DQS_DN<4>")
	)
	(segment
		(start 387.077966 -240.376456)
		(end 387.033008 -240.349786)
		(width 0.088646)
		(layer "In2.Cu")
		(net "M_F_CPU0_SB_DQS_DN<4>")
	)
	(segment
		(start 424.522138 -236.95279)
		(end 424.236134 -236.95279)
		(width 0.18288)
		(layer "In2.Cu")
		(net "M_F_CPU0_SB_DQS_DN<4>")
	)
	(segment
		(start 417.670488 -236.027468)
		(end 417.642294 -236.055662)
		(width 0.16002)
		(layer "In2.Cu")
		(net "M_F_CPU0_SB_DQS_DN<4>")
	)
	(segment
		(start 403.378162 -238.873538)
		(end 403.378162 -239.04956)
		(width 0.18288)
		(layer "In2.Cu")
		(net "M_F_CPU0_SB_DQS_DN<4>")
	)
	(segment
		(start 415.742374 -235.99521)
		(end 415.354262 -235.607098)
		(width 0.18288)
		(layer "In2.Cu")
		(net "M_F_CPU0_SB_DQS_DN<4>")
	)
	(segment
		(start 408.407362 -237.259876)
		(end 407.8732 -237.259876)
		(width 0.18288)
		(layer "In2.Cu")
		(net "M_F_CPU0_SB_DQS_DN<4>")
	)
	(segment
		(start 407.671524 -237.0582)
		(end 407.671524 -237.042452)
		(width 0.16002)
		(layer "In2.Cu")
		(net "M_F_CPU0_SB_DQS_DN<4>")
	)
	(segment
		(start 413.705294 -234.849416)
		(end 413.412432 -235.142278)
		(width 0.18288)
		(layer "In2.Cu")
		(net "M_F_CPU0_SB_DQS_DN<4>")
	)
	(segment
		(start 409.898088 -236.211618)
		(end 409.142692 -236.524546)
		(width 0.18288)
		(layer "In2.Cu")
		(net "M_F_CPU0_SB_DQS_DN<4>")
	)
	(segment
		(start 383.561844 -239.648492)
		(end 383.545334 -239.665002)
		(width 0.088646)
		(layer "In2.Cu")
		(net "M_F_CPU0_SB_DQS_DN<4>")
	)
	(segment
		(start 384.85953 -239.86744)
		(end 384.85953 -239.853216)
		(width 0.088646)
		(layer "In2.Cu")
		(net "M_F_CPU0_SB_DQS_DN<4>")
	)
	(segment
		(start 419.954964 -236.552486)
		(end 419.499796 -236.36351)
		(width 0.18288)
		(layer "In2.Cu")
		(net "M_F_CPU0_SB_DQS_DN<4>")
	)
	(segment
		(start 388.39902 -240.717578)
		(end 387.420612 -240.717578)
		(width 0.088646)
		(layer "In2.Cu")
		(net "M_F_CPU0_SB_DQS_DN<4>")
	)
	(segment
		(start 386.096764 -240.351564)
		(end 386.082032 -240.342928)
		(width 0.088646)
		(layer "In2.Cu")
		(net "M_F_CPU0_SB_DQS_DN<4>")
	)
	(segment
		(start 402.038058 -240.389664)
		(end 401.862036 -240.389664)
		(width 0.18288)
		(layer "In2.Cu")
		(net "M_F_CPU0_SB_DQS_DN<4>")
	)
	(segment
		(start 396.773146 -240.777522)
		(end 396.224506 -240.777522)
		(width 0.18288)
		(layer "In2.Cu")
		(net "M_F_CPU0_SB_DQS_DN<4>")
	)
	(segment
		(start 398.792446 -240.901982)
		(end 398.243806 -240.901982)
		(width 0.18288)
		(layer "In2.Cu")
		(net "M_F_CPU0_SB_DQS_DN<4>")
	)
	(segment
		(start 384.297682 -239.528858)
		(end 384.292602 -239.531906)
		(width 0.088646)
		(layer "In2.Cu")
		(net "M_F_CPU0_SB_DQS_DN<4>")
	)
	(segment
		(start 420.233856 -236.552486)
		(end 419.954964 -236.552486)
		(width 0.18288)
		(layer "In2.Cu")
		(net "M_F_CPU0_SB_DQS_DN<4>")
	)
	(segment
		(start 402.42617 -240.001552)
		(end 402.038058 -240.389664)
		(width 0.18288)
		(layer "In2.Cu")
		(net "M_F_CPU0_SB_DQS_DN<4>")
	)
	(segment
		(start 404.330154 -238.097568)
		(end 403.942042 -238.48568)
		(width 0.18288)
		(layer "In2.Cu")
		(net "M_F_CPU0_SB_DQS_DN<4>")
	)
	(segment
		(start 419.499796 -236.36351)
		(end 419.060376 -235.92409)
		(width 0.18288)
		(layer "In2.Cu")
		(net "M_F_CPU0_SB_DQS_DN<4>")
	)
	(segment
		(start 411.3149 -235.815886)
		(end 410.29382 -235.815886)
		(width 0.18288)
		(layer "In2.Cu")
		(net "M_F_CPU0_SB_DQS_DN<4>")
	)
	(segment
		(start 385.156964 -240.351564)
		(end 385.142232 -240.342928)
		(width 0.088646)
		(layer "In2.Cu")
		(net "M_F_CPU0_SB_DQS_DN<4>")
	)
	(segment
		(start 390.839706 -240.777522)
		(end 390.715246 -240.901982)
		(width 0.18288)
		(layer "In2.Cu")
		(net "M_F_CPU0_SB_DQS_DN<4>")
	)
	(segment
		(start 417.459414 -236.238542)
		(end 417.270946 -236.42701)
		(width 0.18288)
		(layer "In2.Cu")
		(net "M_F_CPU0_SB_DQS_DN<4>")
	)
	(segment
		(start 403.378162 -239.04956)
		(end 402.99005 -239.437672)
		(width 0.18288)
		(layer "In2.Cu")
		(net "M_F_CPU0_SB_DQS_DN<4>")
	)
	(segment
		(start 411.930596 -235.20019)
		(end 411.902402 -235.228384)
		(width 0.16002)
		(layer "In2.Cu")
		(net "M_F_CPU0_SB_DQS_DN<4>")
	)
	(segment
		(start 403.942042 -238.48568)
		(end 403.76602 -238.48568)
		(width 0.18288)
		(layer "In2.Cu")
		(net "M_F_CPU0_SB_DQS_DN<4>")
	)
	(segment
		(start 424.236134 -236.95279)
		(end 423.67835 -237.183676)
		(width 0.18288)
		(layer "In2.Cu")
		(net "M_F_CPU0_SB_DQS_DN<4>")
	)
	(segment
		(start 407.8732 -237.259876)
		(end 407.699718 -237.086394)
		(width 0.18288)
		(layer "In2.Cu")
		(net "M_F_CPU0_SB_DQS_DN<4>")
	)
	(segment
		(start 423.67835 -237.183676)
		(end 423.126916 -237.183676)
		(width 0.18288)
		(layer "In2.Cu")
		(net "M_F_CPU0_SB_DQS_DN<4>")
	)
	(segment
		(start 419.060376 -235.92409)
		(end 417.773866 -235.92409)
		(width 0.18288)
		(layer "In2.Cu")
		(net "M_F_CPU0_SB_DQS_DN<4>")
	)
	(segment
		(start 420.963344 -236.840776)
		(end 420.522146 -236.840776)
		(width 0.18288)
		(layer "In2.Cu")
		(net "M_F_CPU0_SB_DQS_DN<4>")
	)
	(segment
		(start 406.087326 -236.78007)
		(end 405.824182 -237.043214)
		(width 0.18288)
		(layer "In2.Cu")
		(net "M_F_CPU0_SB_DQS_DN<4>")
	)
	(segment
		(start 404.330408 -237.921546)
		(end 404.330154 -238.097568)
		(width 0.18288)
		(layer "In2.Cu")
		(net "M_F_CPU0_SB_DQS_DN<4>")
	)
	(segment
		(start 392.859006 -240.901982)
		(end 392.734546 -240.777522)
		(width 0.18288)
		(layer "In2.Cu")
		(net "M_F_CPU0_SB_DQS_DN<4>")
	)
	(segment
		(start 392.185906 -240.777522)
		(end 392.061446 -240.901982)
		(width 0.18288)
		(layer "In2.Cu")
		(net "M_F_CPU0_SB_DQS_DN<4>")
	)
	(segment
		(start 387.03123 -240.34877)
		(end 387.026912 -240.345976)
		(width 0.088646)
		(layer "In2.Cu")
		(net "M_F_CPU0_SB_DQS_DN<4>")
	)
	(segment
		(start 390.715246 -240.901982)
		(end 390.166606 -240.901982)
		(width 0.18288)
		(layer "In2.Cu")
		(net "M_F_CPU0_SB_DQS_DN<4>")
	)
	(segment
		(start 398.243806 -240.901982)
		(end 398.119346 -240.777522)
		(width 0.18288)
		(layer "In2.Cu")
		(net "M_F_CPU0_SB_DQS_DN<4>")
	)
	(segment
		(start 422.785032 -237.041944)
		(end 422.492932 -236.749844)
		(width 0.18288)
		(layer "In2.Cu")
		(net "M_F_CPU0_SB_DQS_DN<4>")
	)
	(segment
		(start 407.532586 -236.903514)
		(end 407.516838 -236.903514)
		(width 0.16002)
		(layer "In2.Cu")
		(net "M_F_CPU0_SB_DQS_DN<4>")
	)
	(segment
		(start 411.988508 -235.142278)
		(end 411.930596 -235.20019)
		(width 0.18288)
		(layer "In2.Cu")
		(net "M_F_CPU0_SB_DQS_DN<4>")
	)
	(segment
		(start 407.488644 -236.87532)
		(end 407.393394 -236.78007)
		(width 0.18288)
		(layer "In2.Cu")
		(net "M_F_CPU0_SB_DQS_DN<4>")
	)
	(segment
		(start 387.023356 -240.343944)
		(end 387.021324 -240.342674)
		(width 0.088646)
		(layer "In2.Cu")
		(net "M_F_CPU0_SB_DQS_DN<4>")
	)
	(segment
		(start 420.522146 -236.840776)
		(end 420.233856 -236.552486)
		(width 0.18288)
		(layer "In2.Cu")
		(net "M_F_CPU0_SB_DQS_DN<4>")
	)
	(segment
		(start 422.492932 -236.749844)
		(end 422.147746 -236.606842)
		(width 0.18288)
		(layer "In2.Cu")
		(net "M_F_CPU0_SB_DQS_DN<4>")
	)
	(segment
		(start 411.886146 -235.228384)
		(end 411.747716 -235.366814)
		(width 0.16002)
		(layer "In2.Cu")
		(net "M_F_CPU0_SB_DQS_DN<4>")
	)
	(segment
		(start 424.836082 -237.266734)
		(end 424.522138 -236.95279)
		(width 0.18288)
		(layer "In2.Cu")
		(net "M_F_CPU0_SB_DQS_DN<4>")
	)
	(segment
		(start 413.412432 -235.142278)
		(end 411.988508 -235.142278)
		(width 0.18288)
		(layer "In2.Cu")
		(net "M_F_CPU0_SB_DQS_DN<4>")
	)
	(segment
		(start 402.99005 -239.437672)
		(end 402.814028 -239.437672)
		(width 0.18288)
		(layer "In2.Cu")
		(net "M_F_CPU0_SB_DQS_DN<4>")
	)
	(segment
		(start 417.487608 -236.1946)
		(end 417.487608 -236.210348)
		(width 0.16002)
		(layer "In2.Cu")
		(net "M_F_CPU0_SB_DQS_DN<4>")
	)
	(segment
		(start 414.498282 -234.849416)
		(end 413.705294 -234.849416)
		(width 0.18288)
		(layer "In2.Cu")
		(net "M_F_CPU0_SB_DQS_DN<4>")
	)
	(segment
		(start 402.42617 -239.82553)
		(end 402.42617 -240.001552)
		(width 0.18288)
		(layer "In2.Cu")
		(net "M_F_CPU0_SB_DQS_DN<4>")
	)
	(segment
		(start 401.862036 -240.389664)
		(end 401.474178 -240.777522)
		(width 0.18288)
		(layer "In2.Cu")
		(net "M_F_CPU0_SB_DQS_DN<4>")
	)
	(segment
		(start 417.773866 -235.92409)
		(end 417.670488 -236.027468)
		(width 0.18288)
		(layer "In2.Cu")
		(net "M_F_CPU0_SB_DQS_DN<4>")
	)
	(segment
		(start 423.126916 -237.183676)
		(end 422.785032 -237.041944)
		(width 0.18288)
		(layer "In2.Cu")
		(net "M_F_CPU0_SB_DQS_DN<4>")
	)
	(segment
		(start 388.458964 -240.777522)
		(end 388.39902 -240.717578)
		(width 0.088646)
		(layer "In2.Cu")
		(net "M_F_CPU0_SB_DQS_DN<4>")
	)
	(segment
		(start 410.29382 -235.815886)
		(end 409.898088 -236.211618)
		(width 0.18288)
		(layer "In2.Cu")
		(net "M_F_CPU0_SB_DQS_DN<4>")
	)
	(segment
		(start 398.916906 -240.777522)
		(end 398.792446 -240.901982)
		(width 0.18288)
		(layer "In2.Cu")
		(net "M_F_CPU0_SB_DQS_DN<4>")
	)
	(segment
		(start 401.474178 -240.777522)
		(end 398.916906 -240.777522)
		(width 0.18288)
		(layer "In2.Cu")
		(net "M_F_CPU0_SB_DQS_DN<4>")
	)
	(segment
		(start 402.814028 -239.437672)
		(end 402.42617 -239.82553)
		(width 0.18288)
		(layer "In2.Cu")
		(net "M_F_CPU0_SB_DQS_DN<4>")
	)
	(segment
		(start 391.512806 -240.901982)
		(end 391.388346 -240.777522)
		(width 0.18288)
		(layer "In2.Cu")
		(net "M_F_CPU0_SB_DQS_DN<4>")
	)
	(segment
		(start 422.147746 -236.606842)
		(end 421.197278 -236.606842)
		(width 0.18288)
		(layer "In2.Cu")
		(net "M_F_CPU0_SB_DQS_DN<4>")
	)
	(segment
		(start 390.042146 -240.777522)
		(end 388.458964 -240.777522)
		(width 0.18288)
		(layer "In2.Cu")
		(net "M_F_CPU0_SB_DQS_DN<4>")
	)
	(segment
		(start 393.407646 -240.901982)
		(end 392.859006 -240.901982)
		(width 0.18288)
		(layer "In2.Cu")
		(net "M_F_CPU0_SB_DQS_DN<4>")
	)
	(segment
		(start 392.734546 -240.777522)
		(end 392.185906 -240.777522)
		(width 0.18288)
		(layer "In2.Cu")
		(net "M_F_CPU0_SB_DQS_DN<4>")
	)
	(segment
		(start 415.354262 -235.431076)
		(end 414.966404 -235.043218)
		(width 0.18288)
		(layer "In2.Cu")
		(net "M_F_CPU0_SB_DQS_DN<4>")
	)
	(segment
		(start 395.551406 -240.901982)
		(end 395.426946 -240.777522)
		(width 0.18288)
		(layer "In2.Cu")
		(net "M_F_CPU0_SB_DQS_DN<4>")
	)
	(arc
		(start 386.082032 -240.342928)
		(mid 385.894834 -240.292785)
		(end 385.707636 -240.342928)
		(width 0.088646)
		(layer "In2.Cu")
		(net "M_F_CPU0_SB_DQS_DN<4>")
	)
	(arc
		(start 384.049778 -239.60328)
		(mid 383.914962 -239.595429)
		(end 383.785872 -239.555782)
		(width 0.088646)
		(layer "In2.Cu")
		(net "M_F_CPU0_SB_DQS_DN<4>")
	)
	(arc
		(start 387.091174 -240.38814)
		(mid 387.085081 -240.38172)
		(end 387.077966 -240.376456)
		(width 0.088646)
		(layer "In2.Cu")
		(net "M_F_CPU0_SB_DQS_DN<4>")
	)
	(arc
		(start 385.142232 -240.342928)
		(mid 384.938751 -240.142124)
		(end 384.85953 -239.86744)
		(width 0.088646)
		(layer "In2.Cu")
		(net "M_F_CPU0_SB_DQS_DN<4>")
	)
	(arc
		(start 384.85953 -239.853216)
		(mid 384.811851 -239.670316)
		(end 384.680968 -239.533938)
		(width 0.088646)
		(layer "In2.Cu")
		(net "M_F_CPU0_SB_DQS_DN<4>")
	)
	(arc
		(start 385.707636 -240.342928)
		(mid 385.433407 -240.418853)
		(end 385.156964 -240.351564)
		(width 0.088646)
		(layer "In2.Cu")
		(net "M_F_CPU0_SB_DQS_DN<4>")
	)
	(arc
		(start 387.011926 -240.33734)
		(mid 386.828947 -240.292767)
		(end 386.647436 -240.342928)
		(width 0.088646)
		(layer "In2.Cu")
		(net "M_F_CPU0_SB_DQS_DN<4>")
	)
	(arc
		(start 387.021324 -240.342674)
		(mid 387.016644 -240.339974)
		(end 387.011926 -240.33734)
		(width 0.088646)
		(layer "In2.Cu")
		(net "M_F_CPU0_SB_DQS_DN<4>")
	)
	(arc
		(start 386.647436 -240.342928)
		(mid 386.373207 -240.418853)
		(end 386.096764 -240.351564)
		(width 0.088646)
		(layer "In2.Cu")
		(net "M_F_CPU0_SB_DQS_DN<4>")
	)
	(arc
		(start 384.292348 -239.531906)
		(mid 384.175104 -239.581319)
		(end 384.049778 -239.60328)
		(width 0.088646)
		(layer "In2.Cu")
		(net "M_F_CPU0_SB_DQS_DN<4>")
	)
	(arc
		(start 384.672078 -239.528858)
		(mid 384.48488 -239.478715)
		(end 384.297682 -239.528858)
		(width 0.088646)
		(layer "In2.Cu")
		(net "M_F_CPU0_SB_DQS_DN<4>")
	)
	(segment
		(start 426.94606 -200.2917)
		(end 426.951394 -200.286366)
		(width 0.1016)
		(layer "F.Cu")
		(net "M_F_CPU0_SB_DQS_DN<3>")
	)
	(segment
		(start 428.554896 -200.107296)
		(end 428.795434 -199.866758)
		(width 0.20066)
		(layer "F.Cu")
		(net "M_F_CPU0_SB_DQS_DN<3>")
	)
	(segment
		(start 427.506892 -200.51776)
		(end 427.811946 -200.51776)
		(width 0.20066)
		(layer "F.Cu")
		(net "M_F_CPU0_SB_DQS_DN<3>")
	)
	(segment
		(start 420.736014 -199.866758)
		(end 421.840914 -199.866758)
		(width 0.20066)
		(layer "F.Cu")
		(net "M_F_CPU0_SB_DQS_DN<3>")
	)
	(segment
		(start 428.795434 -199.866758)
		(end 429.384714 -199.866758)
		(width 0.20066)
		(layer "F.Cu")
		(net "M_F_CPU0_SB_DQS_DN<3>")
	)
	(segment
		(start 424.614594 -200.2917)
		(end 424.762168 -200.2917)
		(width 0.20066)
		(layer "F.Cu")
		(net "M_F_CPU0_SB_DQS_DN<3>")
	)
	(segment
		(start 377.43638 -228.1809)
		(end 377.436634 -228.180646)
		(width 0.20066)
		(layer "F.Cu")
		(net "M_F_CPU0_SB_DQS_DN<3>")
	)
	(segment
		(start 423.407078 -200.148444)
		(end 423.821606 -200.562972)
		(width 0.20066)
		(layer "F.Cu")
		(net "M_F_CPU0_SB_DQS_DN<3>")
	)
	(segment
		(start 422.67124 -200.148444)
		(end 423.407078 -200.148444)
		(width 0.20066)
		(layer "F.Cu")
		(net "M_F_CPU0_SB_DQS_DN<3>")
	)
	(segment
		(start 421.840914 -199.866758)
		(end 422.389554 -199.866758)
		(width 0.20066)
		(layer "F.Cu")
		(net "M_F_CPU0_SB_DQS_DN<3>")
	)
	(segment
		(start 422.389554 -199.866758)
		(end 422.67124 -200.148444)
		(width 0.20066)
		(layer "F.Cu")
		(net "M_F_CPU0_SB_DQS_DN<3>")
	)
	(segment
		(start 427.275498 -200.286366)
		(end 427.506892 -200.51776)
		(width 0.20066)
		(layer "F.Cu")
		(net "M_F_CPU0_SB_DQS_DN<3>")
	)
	(segment
		(start 428.22241 -200.107296)
		(end 428.554896 -200.107296)
		(width 0.20066)
		(layer "F.Cu")
		(net "M_F_CPU0_SB_DQS_DN<3>")
	)
	(segment
		(start 377.436634 -228.180646)
		(end 377.436634 -227.64496)
		(width 0.20066)
		(layer "F.Cu")
		(net "M_F_CPU0_SB_DQS_DN<3>")
	)
	(segment
		(start 424.762168 -200.2917)
		(end 424.766486 -200.2917)
		(width 0.101854)
		(layer "F.Cu")
		(net "M_F_CPU0_SB_DQS_DN<3>")
	)
	(segment
		(start 427.811946 -200.51776)
		(end 428.22241 -200.107296)
		(width 0.20066)
		(layer "F.Cu")
		(net "M_F_CPU0_SB_DQS_DN<3>")
	)
	(segment
		(start 424.343322 -200.562972)
		(end 424.614594 -200.2917)
		(width 0.20066)
		(layer "F.Cu")
		(net "M_F_CPU0_SB_DQS_DN<3>")
	)
	(segment
		(start 426.951394 -200.286366)
		(end 427.275498 -200.286366)
		(width 0.20066)
		(layer "F.Cu")
		(net "M_F_CPU0_SB_DQS_DN<3>")
	)
	(segment
		(start 424.766486 -200.2917)
		(end 426.94606 -200.2917)
		(width 0.1016)
		(layer "F.Cu")
		(net "M_F_CPU0_SB_DQS_DN<3>")
	)
	(segment
		(start 423.821606 -200.562972)
		(end 424.343322 -200.562972)
		(width 0.20066)
		(layer "F.Cu")
		(net "M_F_CPU0_SB_DQS_DN<3>")
	)
	(segment
		(start 378.094494 -227.155502)
		(end 378.083572 -227.161852)
		(width 0.088646)
		(layer "In4.Cu")
		(net "M_F_CPU0_SB_DQS_DN<3>")
	)
	(segment
		(start 382.510284 -222.746062)
		(end 382.510284 -222.761556)
		(width 0.088646)
		(layer "In4.Cu")
		(net "M_F_CPU0_SB_DQS_DN<3>")
	)
	(segment
		(start 380.550928 -227.163122)
		(end 380.53899 -227.15601)
		(width 0.088646)
		(layer "In4.Cu")
		(net "M_F_CPU0_SB_DQS_DN<3>")
	)
	(segment
		(start 382.040384 -223.557084)
		(end 382.040384 -223.575626)
		(width 0.088646)
		(layer "In4.Cu")
		(net "M_F_CPU0_SB_DQS_DN<3>")
	)
	(segment
		(start 414.64865 -199.09282)
		(end 413.996632 -199.09282)
		(width 0.18288)
		(layer "In4.Cu")
		(net "M_F_CPU0_SB_DQS_DN<3>")
	)
	(segment
		(start 409.036266 -199.103996)
		(end 408.63774 -199.502522)
		(width 0.18288)
		(layer "In4.Cu")
		(net "M_F_CPU0_SB_DQS_DN<3>")
	)
	(segment
		(start 381.861822 -223.894904)
		(end 381.852932 -223.899984)
		(width 0.088646)
		(layer "In4.Cu")
		(net "M_F_CPU0_SB_DQS_DN<3>")
	)
	(segment
		(start 420.05123 -200.115678)
		(end 419.597586 -199.662034)
		(width 0.18288)
		(layer "In4.Cu")
		(net "M_F_CPU0_SB_DQS_DN<3>")
	)
	(segment
		(start 384.203956 -221.45752)
		(end 384.202432 -221.458282)
		(width 0.088646)
		(layer "In4.Cu")
		(net "M_F_CPU0_SB_DQS_DN<3>")
	)
	(segment
		(start 399.958306 -205.841854)
		(end 397.92275 -210.755738)
		(width 0.18288)
		(layer "In4.Cu")
		(net "M_F_CPU0_SB_DQS_DN<3>")
	)
	(segment
		(start 386.878322 -220.56852)
		(end 386.834126 -220.56852)
		(width 0.088646)
		(layer "In4.Cu")
		(net "M_F_CPU0_SB_DQS_DN<3>")
	)
	(segment
		(start 405.02586 -199.502522)
		(end 402.519642 -202.00874)
		(width 0.18288)
		(layer "In4.Cu")
		(net "M_F_CPU0_SB_DQS_DN<3>")
	)
	(segment
		(start 387.613398 -220.494098)
		(end 386.952744 -220.494098)
		(width 0.088646)
		(layer "In4.Cu")
		(net "M_F_CPU0_SB_DQS_DN<3>")
	)
	(segment
		(start 383.262632 -221.458282)
		(end 383.252472 -221.464124)
		(width 0.088646)
		(layer "In4.Cu")
		(net "M_F_CPU0_SB_DQS_DN<3>")
	)
	(segment
		(start 419.597586 -199.662034)
		(end 415.217864 -199.662034)
		(width 0.18288)
		(layer "In4.Cu")
		(net "M_F_CPU0_SB_DQS_DN<3>")
	)
	(segment
		(start 412.825692 -199.651366)
		(end 412.278322 -199.103996)
		(width 0.18288)
		(layer "In4.Cu")
		(net "M_F_CPU0_SB_DQS_DN<3>")
	)
	(segment
		(start 381.853694 -224.879408)
		(end 381.861822 -224.88398)
		(width 0.088646)
		(layer "In4.Cu")
		(net "M_F_CPU0_SB_DQS_DN<3>")
	)
	(segment
		(start 382.801368 -222.267018)
		(end 382.793494 -222.27159)
		(width 0.088646)
		(layer "In4.Cu")
		(net "M_F_CPU0_SB_DQS_DN<3>")
	)
	(segment
		(start 381.391922 -226.336606)
		(end 381.383032 -226.341686)
		(width 0.088646)
		(layer "In4.Cu")
		(net "M_F_CPU0_SB_DQS_DN<3>")
	)
	(segment
		(start 387.69671 -220.434154)
		(end 387.673342 -220.434154)
		(width 0.088646)
		(layer "In4.Cu")
		(net "M_F_CPU0_SB_DQS_DN<3>")
	)
	(segment
		(start 377.849892 -227.440236)
		(end 377.849384 -227.439982)
		(width 0.088646)
		(layer "In4.Cu")
		(net "M_F_CPU0_SB_DQS_DN<3>")
	)
	(segment
		(start 380.912878 -227.155502)
		(end 380.913386 -227.155756)
		(width 0.088646)
		(layer "In4.Cu")
		(net "M_F_CPU0_SB_DQS_DN<3>")
	)
	(segment
		(start 382.793494 -222.27159)
		(end 382.792478 -222.272098)
		(width 0.088646)
		(layer "In4.Cu")
		(net "M_F_CPU0_SB_DQS_DN<3>")
	)
	(segment
		(start 379.611128 -227.163122)
		(end 379.59919 -227.15601)
		(width 0.088646)
		(layer "In4.Cu")
		(net "M_F_CPU0_SB_DQS_DN<3>")
	)
	(segment
		(start 381.570484 -224.379536)
		(end 381.570484 -224.399348)
		(width 0.088646)
		(layer "In4.Cu")
		(net "M_F_CPU0_SB_DQS_DN<3>")
	)
	(segment
		(start 420.736014 -199.866758)
		(end 420.487094 -200.115678)
		(width 0.18288)
		(layer "In4.Cu")
		(net "M_F_CPU0_SB_DQS_DN<3>")
	)
	(segment
		(start 387.673342 -220.434154)
		(end 387.613398 -220.494098)
		(width 0.088646)
		(layer "In4.Cu")
		(net "M_F_CPU0_SB_DQS_DN<3>")
	)
	(segment
		(start 381.383032 -226.341686)
		(end 381.37084 -226.348798)
		(width 0.088646)
		(layer "In4.Cu")
		(net "M_F_CPU0_SB_DQS_DN<3>")
	)
	(segment
		(start 384.211322 -221.453202)
		(end 384.203956 -221.45752)
		(width 0.088646)
		(layer "In4.Cu")
		(net "M_F_CPU0_SB_DQS_DN<3>")
	)
	(segment
		(start 402.519642 -202.00874)
		(end 399.958306 -205.841854)
		(width 0.18288)
		(layer "In4.Cu")
		(net "M_F_CPU0_SB_DQS_DN<3>")
	)
	(segment
		(start 380.913894 -227.154994)
		(end 380.912878 -227.155502)
		(width 0.088646)
		(layer "In4.Cu")
		(net "M_F_CPU0_SB_DQS_DN<3>")
	)
	(segment
		(start 381.852932 -224.8789)
		(end 381.853694 -224.879408)
		(width 0.088646)
		(layer "In4.Cu")
		(net "M_F_CPU0_SB_DQS_DN<3>")
	)
	(segment
		(start 383.252472 -221.464124)
		(end 383.25044 -221.465394)
		(width 0.088646)
		(layer "In4.Cu")
		(net "M_F_CPU0_SB_DQS_DN<3>")
	)
	(segment
		(start 381.570484 -225.998786)
		(end 381.570484 -226.017328)
		(width 0.088646)
		(layer "In4.Cu")
		(net "M_F_CPU0_SB_DQS_DN<3>")
	)
	(segment
		(start 397.92275 -210.755738)
		(end 388.244334 -220.434154)
		(width 0.18288)
		(layer "In4.Cu")
		(net "M_F_CPU0_SB_DQS_DN<3>")
	)
	(segment
		(start 413.996632 -199.09282)
		(end 413.438086 -199.651366)
		(width 0.18288)
		(layer "In4.Cu")
		(net "M_F_CPU0_SB_DQS_DN<3>")
	)
	(segment
		(start 388.244334 -220.434154)
		(end 387.69671 -220.434154)
		(width 0.18288)
		(layer "In4.Cu")
		(net "M_F_CPU0_SB_DQS_DN<3>")
	)
	(segment
		(start 381.861822 -225.522536)
		(end 381.852932 -225.527616)
		(width 0.088646)
		(layer "In4.Cu")
		(net "M_F_CPU0_SB_DQS_DN<3>")
	)
	(segment
		(start 415.217864 -199.662034)
		(end 414.64865 -199.09282)
		(width 0.18288)
		(layer "In4.Cu")
		(net "M_F_CPU0_SB_DQS_DN<3>")
	)
	(segment
		(start 386.952744 -220.494098)
		(end 386.878322 -220.56852)
		(width 0.088646)
		(layer "In4.Cu")
		(net "M_F_CPU0_SB_DQS_DN<3>")
	)
	(segment
		(start 384.389884 -221.115382)
		(end 384.389884 -221.133924)
		(width 0.088646)
		(layer "In4.Cu")
		(net "M_F_CPU0_SB_DQS_DN<3>")
	)
	(segment
		(start 412.278322 -199.103996)
		(end 409.036266 -199.103996)
		(width 0.18288)
		(layer "In4.Cu")
		(net "M_F_CPU0_SB_DQS_DN<3>")
	)
	(segment
		(start 380.921768 -227.150422)
		(end 380.913894 -227.154994)
		(width 0.088646)
		(layer "In4.Cu")
		(net "M_F_CPU0_SB_DQS_DN<3>")
	)
	(segment
		(start 408.63774 -199.502522)
		(end 405.02586 -199.502522)
		(width 0.18288)
		(layer "In4.Cu")
		(net "M_F_CPU0_SB_DQS_DN<3>")
	)
	(segment
		(start 382.331722 -223.080834)
		(end 382.322832 -223.085914)
		(width 0.088646)
		(layer "In4.Cu")
		(net "M_F_CPU0_SB_DQS_DN<3>")
	)
	(segment
		(start 420.487094 -200.115678)
		(end 420.05123 -200.115678)
		(width 0.18288)
		(layer "In4.Cu")
		(net "M_F_CPU0_SB_DQS_DN<3>")
	)
	(segment
		(start 413.438086 -199.651366)
		(end 412.825692 -199.651366)
		(width 0.18288)
		(layer "In4.Cu")
		(net "M_F_CPU0_SB_DQS_DN<3>")
	)
	(arc
		(start 379.973586 -227.155756)
		(mid 379.793299 -227.206168)
		(end 379.611128 -227.163122)
		(width 0.088646)
		(layer "In4.Cu")
		(net "M_F_CPU0_SB_DQS_DN<3>")
	)
	(arc
		(start 381.570484 -226.017328)
		(mid 381.522805 -226.200228)
		(end 381.391922 -226.336606)
		(width 0.088646)
		(layer "In4.Cu")
		(net "M_F_CPU0_SB_DQS_DN<3>")
	)
	(arc
		(start 386.177536 -220.644212)
		(mid 385.894834 -220.56847)
		(end 385.612132 -220.644212)
		(width 0.088646)
		(layer "In4.Cu")
		(net "M_F_CPU0_SB_DQS_DN<3>")
	)
	(arc
		(start 378.658882 -227.155756)
		(mid 378.376717 -227.080073)
		(end 378.094494 -227.155502)
		(width 0.088646)
		(layer "In4.Cu")
		(net "M_F_CPU0_SB_DQS_DN<3>")
	)
	(arc
		(start 382.04013 -225.21545)
		(mid 381.989637 -225.391428)
		(end 381.861822 -225.522536)
		(width 0.088646)
		(layer "In4.Cu")
		(net "M_F_CPU0_SB_DQS_DN<3>")
	)
	(arc
		(start 378.083572 -227.161852)
		(mid 377.943738 -227.281745)
		(end 377.849892 -227.440236)
		(width 0.088646)
		(layer "In4.Cu")
		(net "M_F_CPU0_SB_DQS_DN<3>")
	)
	(arc
		(start 383.25044 -221.465394)
		(mid 383.052212 -221.671242)
		(end 382.97993 -221.94774)
		(width 0.088646)
		(layer "In4.Cu")
		(net "M_F_CPU0_SB_DQS_DN<3>")
	)
	(arc
		(start 384.202432 -221.458282)
		(mid 384.015234 -221.508425)
		(end 383.828036 -221.458282)
		(width 0.088646)
		(layer "In4.Cu")
		(net "M_F_CPU0_SB_DQS_DN<3>")
	)
	(arc
		(start 382.040384 -225.196654)
		(mid 382.040374 -225.206054)
		(end 382.04013 -225.21545)
		(width 0.088646)
		(layer "In4.Cu")
		(net "M_F_CPU0_SB_DQS_DN<3>")
	)
	(arc
		(start 384.389884 -221.133924)
		(mid 384.342205 -221.316824)
		(end 384.211322 -221.453202)
		(width 0.088646)
		(layer "In4.Cu")
		(net "M_F_CPU0_SB_DQS_DN<3>")
	)
	(arc
		(start 381.570484 -224.399348)
		(mid 381.648595 -224.676297)
		(end 381.852932 -224.8789)
		(width 0.088646)
		(layer "In4.Cu")
		(net "M_F_CPU0_SB_DQS_DN<3>")
	)
	(arc
		(start 383.828036 -221.458282)
		(mid 383.545334 -221.382506)
		(end 383.262632 -221.458282)
		(width 0.088646)
		(layer "In4.Cu")
		(net "M_F_CPU0_SB_DQS_DN<3>")
	)
	(arc
		(start 379.59919 -227.15601)
		(mid 379.316517 -227.080039)
		(end 379.033786 -227.155756)
		(width 0.088646)
		(layer "In4.Cu")
		(net "M_F_CPU0_SB_DQS_DN<3>")
	)
	(arc
		(start 381.10033 -226.831144)
		(mid 381.052651 -227.014044)
		(end 380.921768 -227.150422)
		(width 0.088646)
		(layer "In4.Cu")
		(net "M_F_CPU0_SB_DQS_DN<3>")
	)
	(arc
		(start 382.510284 -222.761556)
		(mid 382.462605 -222.944456)
		(end 382.331722 -223.080834)
		(width 0.088646)
		(layer "In4.Cu")
		(net "M_F_CPU0_SB_DQS_DN<3>")
	)
	(arc
		(start 381.861822 -224.88398)
		(mid 381.991111 -225.017466)
		(end 382.040384 -225.196654)
		(width 0.088646)
		(layer "In4.Cu")
		(net "M_F_CPU0_SB_DQS_DN<3>")
	)
	(arc
		(start 381.37084 -226.348798)
		(mid 381.172612 -226.554646)
		(end 381.10033 -226.831144)
		(width 0.088646)
		(layer "In4.Cu")
		(net "M_F_CPU0_SB_DQS_DN<3>")
	)
	(arc
		(start 382.97993 -221.94774)
		(mid 382.932251 -222.13064)
		(end 382.801368 -222.267018)
		(width 0.088646)
		(layer "In4.Cu")
		(net "M_F_CPU0_SB_DQS_DN<3>")
	)
	(arc
		(start 377.849384 -227.439982)
		(mid 377.667047 -227.590864)
		(end 377.436634 -227.64496)
		(width 0.088646)
		(layer "In4.Cu")
		(net "M_F_CPU0_SB_DQS_DN<3>")
	)
	(arc
		(start 379.033786 -227.155756)
		(mid 378.846334 -227.205992)
		(end 378.658882 -227.155756)
		(width 0.088646)
		(layer "In4.Cu")
		(net "M_F_CPU0_SB_DQS_DN<3>")
	)
	(arc
		(start 386.834126 -220.56852)
		(mid 386.688065 -220.587848)
		(end 386.551932 -220.644212)
		(width 0.088646)
		(layer "In4.Cu")
		(net "M_F_CPU0_SB_DQS_DN<3>")
	)
	(arc
		(start 386.551932 -220.644212)
		(mid 386.364734 -220.694355)
		(end 386.177536 -220.644212)
		(width 0.088646)
		(layer "In4.Cu")
		(net "M_F_CPU0_SB_DQS_DN<3>")
	)
	(arc
		(start 382.322832 -223.085914)
		(mid 382.120546 -223.284895)
		(end 382.040384 -223.557084)
		(width 0.088646)
		(layer "In4.Cu")
		(net "M_F_CPU0_SB_DQS_DN<3>")
	)
	(arc
		(start 385.612132 -220.644212)
		(mid 385.424934 -220.694355)
		(end 385.237736 -220.644212)
		(width 0.088646)
		(layer "In4.Cu")
		(net "M_F_CPU0_SB_DQS_DN<3>")
	)
	(arc
		(start 380.53899 -227.15601)
		(mid 380.256317 -227.080039)
		(end 379.973586 -227.155756)
		(width 0.088646)
		(layer "In4.Cu")
		(net "M_F_CPU0_SB_DQS_DN<3>")
	)
	(arc
		(start 382.040384 -223.575626)
		(mid 381.992705 -223.758526)
		(end 381.861822 -223.894904)
		(width 0.088646)
		(layer "In4.Cu")
		(net "M_F_CPU0_SB_DQS_DN<3>")
	)
	(arc
		(start 380.913386 -227.155756)
		(mid 380.733099 -227.206168)
		(end 380.550928 -227.163122)
		(width 0.088646)
		(layer "In4.Cu")
		(net "M_F_CPU0_SB_DQS_DN<3>")
	)
	(arc
		(start 384.672332 -220.644212)
		(mid 384.470046 -220.843193)
		(end 384.389884 -221.115382)
		(width 0.088646)
		(layer "In4.Cu")
		(net "M_F_CPU0_SB_DQS_DN<3>")
	)
	(arc
		(start 381.852932 -223.899984)
		(mid 381.648597 -224.102589)
		(end 381.570484 -224.379536)
		(width 0.088646)
		(layer "In4.Cu")
		(net "M_F_CPU0_SB_DQS_DN<3>")
	)
	(arc
		(start 382.792478 -222.272098)
		(mid 382.589655 -222.472329)
		(end 382.510284 -222.746062)
		(width 0.088646)
		(layer "In4.Cu")
		(net "M_F_CPU0_SB_DQS_DN<3>")
	)
	(arc
		(start 385.237736 -220.644212)
		(mid 384.955034 -220.56847)
		(end 384.672332 -220.644212)
		(width 0.088646)
		(layer "In4.Cu")
		(net "M_F_CPU0_SB_DQS_DN<3>")
	)
	(arc
		(start 381.852932 -225.527616)
		(mid 381.650646 -225.726597)
		(end 381.570484 -225.998786)
		(width 0.088646)
		(layer "In4.Cu")
		(net "M_F_CPU0_SB_DQS_DN<3>")
	)
	(segment
		(start 384.95478 -223.297496)
		(end 384.95478 -222.761556)
		(width 0.20066)
		(layer "F.Cu")
		(net "M_F_CPU0_SB_DQS_DN<2>")
	)
	(segment
		(start 427.275498 -209.63636)
		(end 427.506892 -209.867754)
		(width 0.20066)
		(layer "F.Cu")
		(net "M_F_CPU0_SB_DQS_DN<2>")
	)
	(segment
		(start 423.407078 -209.498438)
		(end 423.821606 -209.912966)
		(width 0.20066)
		(layer "F.Cu")
		(net "M_F_CPU0_SB_DQS_DN<2>")
	)
	(segment
		(start 427.506892 -209.867754)
		(end 427.811946 -209.867754)
		(width 0.20066)
		(layer "F.Cu")
		(net "M_F_CPU0_SB_DQS_DN<2>")
	)
	(segment
		(start 428.795434 -209.216752)
		(end 429.384714 -209.216752)
		(width 0.20066)
		(layer "F.Cu")
		(net "M_F_CPU0_SB_DQS_DN<2>")
	)
	(segment
		(start 422.67124 -209.498438)
		(end 423.407078 -209.498438)
		(width 0.20066)
		(layer "F.Cu")
		(net "M_F_CPU0_SB_DQS_DN<2>")
	)
	(segment
		(start 428.22241 -209.45729)
		(end 428.554896 -209.45729)
		(width 0.20066)
		(layer "F.Cu")
		(net "M_F_CPU0_SB_DQS_DN<2>")
	)
	(segment
		(start 426.94606 -209.641694)
		(end 426.951394 -209.63636)
		(width 0.1016)
		(layer "F.Cu")
		(net "M_F_CPU0_SB_DQS_DN<2>")
	)
	(segment
		(start 427.811946 -209.867754)
		(end 428.22241 -209.45729)
		(width 0.20066)
		(layer "F.Cu")
		(net "M_F_CPU0_SB_DQS_DN<2>")
	)
	(segment
		(start 420.736014 -209.216752)
		(end 421.840914 -209.216752)
		(width 0.20066)
		(layer "F.Cu")
		(net "M_F_CPU0_SB_DQS_DN<2>")
	)
	(segment
		(start 424.614594 -209.641694)
		(end 424.762168 -209.641694)
		(width 0.20066)
		(layer "F.Cu")
		(net "M_F_CPU0_SB_DQS_DN<2>")
	)
	(segment
		(start 423.821606 -209.912966)
		(end 424.343322 -209.912966)
		(width 0.20066)
		(layer "F.Cu")
		(net "M_F_CPU0_SB_DQS_DN<2>")
	)
	(segment
		(start 424.762168 -209.641694)
		(end 424.766486 -209.641694)
		(width 0.101854)
		(layer "F.Cu")
		(net "M_F_CPU0_SB_DQS_DN<2>")
	)
	(segment
		(start 424.766486 -209.641694)
		(end 426.94606 -209.641694)
		(width 0.1016)
		(layer "F.Cu")
		(net "M_F_CPU0_SB_DQS_DN<2>")
	)
	(segment
		(start 421.840914 -209.216752)
		(end 422.389554 -209.216752)
		(width 0.20066)
		(layer "F.Cu")
		(net "M_F_CPU0_SB_DQS_DN<2>")
	)
	(segment
		(start 424.343322 -209.912966)
		(end 424.614594 -209.641694)
		(width 0.20066)
		(layer "F.Cu")
		(net "M_F_CPU0_SB_DQS_DN<2>")
	)
	(segment
		(start 428.554896 -209.45729)
		(end 428.795434 -209.216752)
		(width 0.20066)
		(layer "F.Cu")
		(net "M_F_CPU0_SB_DQS_DN<2>")
	)
	(segment
		(start 422.389554 -209.216752)
		(end 422.67124 -209.498438)
		(width 0.20066)
		(layer "F.Cu")
		(net "M_F_CPU0_SB_DQS_DN<2>")
	)
	(segment
		(start 426.951394 -209.63636)
		(end 427.275498 -209.63636)
		(width 0.20066)
		(layer "F.Cu")
		(net "M_F_CPU0_SB_DQS_DN<2>")
	)
	(segment
		(start 394.353796 -217.498168)
		(end 393.965684 -217.88628)
		(width 0.18288)
		(layer "In2.Cu")
		(net "M_F_CPU0_SB_DQS_DN<2>")
	)
	(segment
		(start 412.301436 -208.22031)
		(end 411.44444 -207.363314)
		(width 0.18288)
		(layer "In2.Cu")
		(net "M_F_CPU0_SB_DQS_DN<2>")
	)
	(segment
		(start 388.44982 -222.261176)
		(end 388.425436 -222.275654)
		(width 0.088646)
		(layer "In2.Cu")
		(net "M_F_CPU0_SB_DQS_DN<2>")
	)
	(segment
		(start 417.446968 -209.38236)
		(end 416.965638 -208.90103)
		(width 0.18288)
		(layer "In2.Cu")
		(net "M_F_CPU0_SB_DQS_DN<2>")
	)
	(segment
		(start 420.736014 -209.216752)
		(end 420.450264 -209.502502)
		(width 0.18288)
		(layer "In2.Cu")
		(net "M_F_CPU0_SB_DQS_DN<2>")
	)
	(segment
		(start 415.172906 -208.531714)
		(end 414.85439 -208.213198)
		(width 0.18288)
		(layer "In2.Cu")
		(net "M_F_CPU0_SB_DQS_DN<2>")
	)
	(segment
		(start 402.460714 -209.567272)
		(end 395.48181 -216.546176)
		(width 0.18288)
		(layer "In2.Cu")
		(net "M_F_CPU0_SB_DQS_DN<2>")
	)
	(segment
		(start 405.656542 -207.060546)
		(end 405.640286 -207.060546)
		(width 0.16002)
		(layer "In2.Cu")
		(net "M_F_CPU0_SB_DQS_DN<2>")
	)
	(segment
		(start 388.592314 -222.164148)
		(end 388.460488 -222.25508)
		(width 0.088646)
		(layer "In2.Cu")
		(net "M_F_CPU0_SB_DQS_DN<2>")
	)
	(segment
		(start 409.988766 -207.079342)
		(end 409.524962 -207.079342)
		(width 0.18288)
		(layer "In2.Cu")
		(net "M_F_CPU0_SB_DQS_DN<2>")
	)
	(segment
		(start 419.135306 -209.68081)
		(end 417.745418 -209.68081)
		(width 0.18288)
		(layer "In2.Cu")
		(net "M_F_CPU0_SB_DQS_DN<2>")
	)
	(segment
		(start 417.475162 -209.426302)
		(end 417.475162 -209.410554)
		(width 0.16002)
		(layer "In2.Cu")
		(net "M_F_CPU0_SB_DQS_DN<2>")
	)
	(segment
		(start 415.2011 -208.559908)
		(end 415.172906 -208.531714)
		(width 0.16002)
		(layer "In2.Cu")
		(net "M_F_CPU0_SB_DQS_DN<2>")
	)
	(segment
		(start 416.965638 -208.90103)
		(end 415.542222 -208.90103)
		(width 0.18288)
		(layer "In2.Cu")
		(net "M_F_CPU0_SB_DQS_DN<2>")
	)
	(segment
		(start 405.794972 -206.922116)
		(end 405.656542 -207.060546)
		(width 0.16002)
		(layer "In2.Cu")
		(net "M_F_CPU0_SB_DQS_DN<2>")
	)
	(segment
		(start 395.305788 -216.546176)
		(end 394.917676 -216.934288)
		(width 0.18288)
		(layer "In2.Cu")
		(net "M_F_CPU0_SB_DQS_DN<2>")
	)
	(segment
		(start 388.14883 -222.769938)
		(end 388.148576 -222.776288)
		(width 0.088646)
		(layer "In2.Cu")
		(net "M_F_CPU0_SB_DQS_DN<2>")
	)
	(segment
		(start 405.393906 -207.44053)
		(end 403.267164 -209.567272)
		(width 0.18288)
		(layer "In2.Cu")
		(net "M_F_CPU0_SB_DQS_DN<2>")
	)
	(segment
		(start 413.71647 -208.213198)
		(end 413.432498 -207.929226)
		(width 0.18288)
		(layer "In2.Cu")
		(net "M_F_CPU0_SB_DQS_DN<2>")
	)
	(segment
		(start 406.167082 -206.53375)
		(end 405.823166 -206.877666)
		(width 0.18288)
		(layer "In2.Cu")
		(net "M_F_CPU0_SB_DQS_DN<2>")
	)
	(segment
		(start 384.584956 -222.818706)
		(end 384.642106 -222.761556)
		(width 0.088646)
		(layer "In2.Cu")
		(net "M_F_CPU0_SB_DQS_DN<2>")
	)
	(segment
		(start 417.475162 -209.410554)
		(end 417.446968 -209.38236)
		(width 0.16002)
		(layer "In2.Cu")
		(net "M_F_CPU0_SB_DQS_DN<2>")
	)
	(segment
		(start 412.67761 -208.22031)
		(end 412.301436 -208.22031)
		(width 0.18288)
		(layer "In2.Cu")
		(net "M_F_CPU0_SB_DQS_DN<2>")
	)
	(segment
		(start 393.965684 -218.062302)
		(end 390.016238 -222.011748)
		(width 0.18288)
		(layer "In2.Cu")
		(net "M_F_CPU0_SB_DQS_DN<2>")
	)
	(segment
		(start 409.524962 -207.079342)
		(end 409.204414 -207.39989)
		(width 0.18288)
		(layer "In2.Cu")
		(net "M_F_CPU0_SB_DQS_DN<2>")
	)
	(segment
		(start 389.708136 -222.071692)
		(end 389.058912 -222.071692)
		(width 0.088646)
		(layer "In2.Cu")
		(net "M_F_CPU0_SB_DQS_DN<2>")
	)
	(segment
		(start 386.647182 -223.085914)
		(end 386.647436 -223.085914)
		(width 0.088646)
		(layer "In2.Cu")
		(net "M_F_CPU0_SB_DQS_DN<2>")
	)
	(segment
		(start 415.38398 -208.742788)
		(end 415.355786 -208.714594)
		(width 0.16002)
		(layer "In2.Cu")
		(net "M_F_CPU0_SB_DQS_DN<2>")
	)
	(segment
		(start 420.14521 -209.305906)
		(end 419.51021 -209.305906)
		(width 0.18288)
		(layer "In2.Cu")
		(net "M_F_CPU0_SB_DQS_DN<2>")
	)
	(segment
		(start 390.016238 -222.011748)
		(end 389.76808 -222.011748)
		(width 0.18288)
		(layer "In2.Cu")
		(net "M_F_CPU0_SB_DQS_DN<2>")
	)
	(segment
		(start 388.460488 -222.25508)
		(end 388.450582 -222.260668)
		(width 0.088646)
		(layer "In2.Cu")
		(net "M_F_CPU0_SB_DQS_DN<2>")
	)
	(segment
		(start 405.640286 -207.060546)
		(end 405.612092 -207.08874)
		(width 0.16002)
		(layer "In2.Cu")
		(net "M_F_CPU0_SB_DQS_DN<2>")
	)
	(segment
		(start 388.450582 -222.260668)
		(end 388.44982 -222.261176)
		(width 0.088646)
		(layer "In2.Cu")
		(net "M_F_CPU0_SB_DQS_DN<2>")
	)
	(segment
		(start 407.3652 -206.53375)
		(end 406.167082 -206.53375)
		(width 0.18288)
		(layer "In2.Cu")
		(net "M_F_CPU0_SB_DQS_DN<2>")
	)
	(segment
		(start 405.393906 -207.306926)
		(end 405.393906 -207.44053)
		(width 0.18288)
		(layer "In2.Cu")
		(net "M_F_CPU0_SB_DQS_DN<2>")
	)
	(segment
		(start 394.529818 -217.498168)
		(end 394.353796 -217.498168)
		(width 0.18288)
		(layer "In2.Cu")
		(net "M_F_CPU0_SB_DQS_DN<2>")
	)
	(segment
		(start 393.965684 -217.88628)
		(end 393.965684 -218.062302)
		(width 0.18288)
		(layer "In2.Cu")
		(net "M_F_CPU0_SB_DQS_DN<2>")
	)
	(segment
		(start 385.142232 -223.085914)
		(end 385.141978 -223.085914)
		(width 0.088646)
		(layer "In2.Cu")
		(net "M_F_CPU0_SB_DQS_DN<2>")
	)
	(segment
		(start 409.204414 -207.39989)
		(end 408.23134 -207.39989)
		(width 0.18288)
		(layer "In2.Cu")
		(net "M_F_CPU0_SB_DQS_DN<2>")
	)
	(segment
		(start 412.968694 -207.929226)
		(end 412.67761 -208.22031)
		(width 0.18288)
		(layer "In2.Cu")
		(net "M_F_CPU0_SB_DQS_DN<2>")
	)
	(segment
		(start 417.6141 -209.56524)
		(end 417.475162 -209.426302)
		(width 0.16002)
		(layer "In2.Cu")
		(net "M_F_CPU0_SB_DQS_DN<2>")
	)
	(segment
		(start 411.44444 -207.363314)
		(end 410.272738 -207.363314)
		(width 0.18288)
		(layer "In2.Cu")
		(net "M_F_CPU0_SB_DQS_DN<2>")
	)
	(segment
		(start 413.432498 -207.929226)
		(end 412.968694 -207.929226)
		(width 0.18288)
		(layer "In2.Cu")
		(net "M_F_CPU0_SB_DQS_DN<2>")
	)
	(segment
		(start 410.272738 -207.363314)
		(end 409.988766 -207.079342)
		(width 0.18288)
		(layer "In2.Cu")
		(net "M_F_CPU0_SB_DQS_DN<2>")
	)
	(segment
		(start 394.917676 -216.934288)
		(end 394.917676 -217.11031)
		(width 0.18288)
		(layer "In2.Cu")
		(net "M_F_CPU0_SB_DQS_DN<2>")
	)
	(segment
		(start 394.917676 -217.11031)
		(end 394.529818 -217.498168)
		(width 0.18288)
		(layer "In2.Cu")
		(net "M_F_CPU0_SB_DQS_DN<2>")
	)
	(segment
		(start 388.14883 -222.761556)
		(end 388.14883 -222.769938)
		(width 0.088646)
		(layer "In2.Cu")
		(net "M_F_CPU0_SB_DQS_DN<2>")
	)
	(segment
		(start 405.612092 -207.08874)
		(end 405.393906 -207.306926)
		(width 0.18288)
		(layer "In2.Cu")
		(net "M_F_CPU0_SB_DQS_DN<2>")
	)
	(segment
		(start 403.267164 -209.567272)
		(end 402.460714 -209.567272)
		(width 0.18288)
		(layer "In2.Cu")
		(net "M_F_CPU0_SB_DQS_DN<2>")
	)
	(segment
		(start 384.642106 -222.761556)
		(end 384.95478 -222.761556)
		(width 0.088646)
		(layer "In2.Cu")
		(net "M_F_CPU0_SB_DQS_DN<2>")
	)
	(segment
		(start 395.48181 -216.546176)
		(end 395.305788 -216.546176)
		(width 0.18288)
		(layer "In2.Cu")
		(net "M_F_CPU0_SB_DQS_DN<2>")
	)
	(segment
		(start 420.450264 -209.502502)
		(end 420.341806 -209.502502)
		(width 0.18288)
		(layer "In2.Cu")
		(net "M_F_CPU0_SB_DQS_DN<2>")
	)
	(segment
		(start 387.586982 -223.085914)
		(end 387.57225 -223.077278)
		(width 0.088646)
		(layer "In2.Cu")
		(net "M_F_CPU0_SB_DQS_DN<2>")
	)
	(segment
		(start 417.658042 -209.593434)
		(end 417.629848 -209.56524)
		(width 0.16002)
		(layer "In2.Cu")
		(net "M_F_CPU0_SB_DQS_DN<2>")
	)
	(segment
		(start 405.823166 -206.877666)
		(end 405.794972 -206.90586)
		(width 0.16002)
		(layer "In2.Cu")
		(net "M_F_CPU0_SB_DQS_DN<2>")
	)
	(segment
		(start 417.629848 -209.56524)
		(end 417.6141 -209.56524)
		(width 0.16002)
		(layer "In2.Cu")
		(net "M_F_CPU0_SB_DQS_DN<2>")
	)
	(segment
		(start 389.76808 -222.011748)
		(end 389.708136 -222.071692)
		(width 0.088646)
		(layer "In2.Cu")
		(net "M_F_CPU0_SB_DQS_DN<2>")
	)
	(segment
		(start 417.745418 -209.68081)
		(end 417.658042 -209.593434)
		(width 0.18288)
		(layer "In2.Cu")
		(net "M_F_CPU0_SB_DQS_DN<2>")
	)
	(segment
		(start 415.355786 -208.714594)
		(end 415.33953 -208.714594)
		(width 0.16002)
		(layer "In2.Cu")
		(net "M_F_CPU0_SB_DQS_DN<2>")
	)
	(segment
		(start 415.33953 -208.714594)
		(end 415.2011 -208.576164)
		(width 0.16002)
		(layer "In2.Cu")
		(net "M_F_CPU0_SB_DQS_DN<2>")
	)
	(segment
		(start 405.794972 -206.90586)
		(end 405.794972 -206.922116)
		(width 0.16002)
		(layer "In2.Cu")
		(net "M_F_CPU0_SB_DQS_DN<2>")
	)
	(segment
		(start 389.058912 -222.071692)
		(end 388.592314 -222.164148)
		(width 0.088646)
		(layer "In2.Cu")
		(net "M_F_CPU0_SB_DQS_DN<2>")
	)
	(segment
		(start 408.23134 -207.39989)
		(end 407.3652 -206.53375)
		(width 0.18288)
		(layer "In2.Cu")
		(net "M_F_CPU0_SB_DQS_DN<2>")
	)
	(segment
		(start 414.85439 -208.213198)
		(end 413.71647 -208.213198)
		(width 0.18288)
		(layer "In2.Cu")
		(net "M_F_CPU0_SB_DQS_DN<2>")
	)
	(segment
		(start 419.51021 -209.305906)
		(end 419.135306 -209.68081)
		(width 0.18288)
		(layer "In2.Cu")
		(net "M_F_CPU0_SB_DQS_DN<2>")
	)
	(segment
		(start 420.341806 -209.502502)
		(end 420.14521 -209.305906)
		(width 0.18288)
		(layer "In2.Cu")
		(net "M_F_CPU0_SB_DQS_DN<2>")
	)
	(segment
		(start 415.2011 -208.576164)
		(end 415.2011 -208.559908)
		(width 0.16002)
		(layer "In2.Cu")
		(net "M_F_CPU0_SB_DQS_DN<2>")
	)
	(segment
		(start 415.542222 -208.90103)
		(end 415.38398 -208.742788)
		(width 0.18288)
		(layer "In2.Cu")
		(net "M_F_CPU0_SB_DQS_DN<2>")
	)
	(arc
		(start 387.57225 -223.077278)
		(mid 387.295809 -223.010112)
		(end 387.021578 -223.085914)
		(width 0.088646)
		(layer "In2.Cu")
		(net "M_F_CPU0_SB_DQS_DN<2>")
	)
	(arc
		(start 386.082032 -223.085914)
		(mid 385.894834 -223.136057)
		(end 385.707636 -223.085914)
		(width 0.088646)
		(layer "In2.Cu")
		(net "M_F_CPU0_SB_DQS_DN<2>")
	)
	(arc
		(start 384.767582 -223.085914)
		(mid 384.645914 -222.973059)
		(end 384.584956 -222.818706)
		(width 0.088646)
		(layer "In2.Cu")
		(net "M_F_CPU0_SB_DQS_DN<2>")
	)
	(arc
		(start 385.141978 -223.085914)
		(mid 384.95478 -223.136057)
		(end 384.767582 -223.085914)
		(width 0.088646)
		(layer "In2.Cu")
		(net "M_F_CPU0_SB_DQS_DN<2>")
	)
	(arc
		(start 387.021578 -223.085914)
		(mid 386.83438 -223.136057)
		(end 386.647182 -223.085914)
		(width 0.088646)
		(layer "In2.Cu")
		(net "M_F_CPU0_SB_DQS_DN<2>")
	)
	(arc
		(start 388.425436 -222.275654)
		(mid 388.222849 -222.482005)
		(end 388.14883 -222.761556)
		(width 0.088646)
		(layer "In2.Cu")
		(net "M_F_CPU0_SB_DQS_DN<2>")
	)
	(arc
		(start 388.148576 -222.776288)
		(mid 387.955133 -223.08965)
		(end 387.586982 -223.085914)
		(width 0.088646)
		(layer "In2.Cu")
		(net "M_F_CPU0_SB_DQS_DN<2>")
	)
	(arc
		(start 385.707636 -223.085914)
		(mid 385.424934 -223.010172)
		(end 385.142232 -223.085914)
		(width 0.088646)
		(layer "In2.Cu")
		(net "M_F_CPU0_SB_DQS_DN<2>")
	)
	(arc
		(start 386.647436 -223.085914)
		(mid 386.364734 -223.010172)
		(end 386.082032 -223.085914)
		(width 0.088646)
		(layer "In2.Cu")
		(net "M_F_CPU0_SB_DQS_DN<2>")
	)
	(segment
		(start 424.762168 -218.991688)
		(end 424.766486 -218.991688)
		(width 0.101854)
		(layer "F.Cu")
		(net "M_F_CPU0_SB_DQS_DN<1>")
	)
	(segment
		(start 424.614594 -218.991688)
		(end 424.762168 -218.991688)
		(width 0.20066)
		(layer "F.Cu")
		(net "M_F_CPU0_SB_DQS_DN<1>")
	)
	(segment
		(start 428.554896 -218.807284)
		(end 428.795434 -218.566746)
		(width 0.20066)
		(layer "F.Cu")
		(net "M_F_CPU0_SB_DQS_DN<1>")
	)
	(segment
		(start 427.811946 -219.217748)
		(end 428.22241 -218.807284)
		(width 0.20066)
		(layer "F.Cu")
		(net "M_F_CPU0_SB_DQS_DN<1>")
	)
	(segment
		(start 426.94606 -218.991688)
		(end 426.951394 -218.986354)
		(width 0.1016)
		(layer "F.Cu")
		(net "M_F_CPU0_SB_DQS_DN<1>")
	)
	(segment
		(start 421.840914 -218.566746)
		(end 422.389554 -218.566746)
		(width 0.20066)
		(layer "F.Cu")
		(net "M_F_CPU0_SB_DQS_DN<1>")
	)
	(segment
		(start 422.67124 -218.848432)
		(end 423.407078 -218.848432)
		(width 0.20066)
		(layer "F.Cu")
		(net "M_F_CPU0_SB_DQS_DN<1>")
	)
	(segment
		(start 422.389554 -218.566746)
		(end 422.67124 -218.848432)
		(width 0.20066)
		(layer "F.Cu")
		(net "M_F_CPU0_SB_DQS_DN<1>")
	)
	(segment
		(start 424.766486 -218.991688)
		(end 426.94606 -218.991688)
		(width 0.1016)
		(layer "F.Cu")
		(net "M_F_CPU0_SB_DQS_DN<1>")
	)
	(segment
		(start 428.795434 -218.566746)
		(end 429.384714 -218.566746)
		(width 0.20066)
		(layer "F.Cu")
		(net "M_F_CPU0_SB_DQS_DN<1>")
	)
	(segment
		(start 423.821606 -219.26296)
		(end 424.343322 -219.26296)
		(width 0.20066)
		(layer "F.Cu")
		(net "M_F_CPU0_SB_DQS_DN<1>")
	)
	(segment
		(start 423.407078 -218.848432)
		(end 423.821606 -219.26296)
		(width 0.20066)
		(layer "F.Cu")
		(net "M_F_CPU0_SB_DQS_DN<1>")
	)
	(segment
		(start 424.343322 -219.26296)
		(end 424.614594 -218.991688)
		(width 0.20066)
		(layer "F.Cu")
		(net "M_F_CPU0_SB_DQS_DN<1>")
	)
	(segment
		(start 420.736014 -218.566746)
		(end 421.840914 -218.566746)
		(width 0.20066)
		(layer "F.Cu")
		(net "M_F_CPU0_SB_DQS_DN<1>")
	)
	(segment
		(start 427.275498 -218.986354)
		(end 427.506892 -219.217748)
		(width 0.20066)
		(layer "F.Cu")
		(net "M_F_CPU0_SB_DQS_DN<1>")
	)
	(segment
		(start 426.951394 -218.986354)
		(end 427.275498 -218.986354)
		(width 0.20066)
		(layer "F.Cu")
		(net "M_F_CPU0_SB_DQS_DN<1>")
	)
	(segment
		(start 428.22241 -218.807284)
		(end 428.554896 -218.807284)
		(width 0.20066)
		(layer "F.Cu")
		(net "M_F_CPU0_SB_DQS_DN<1>")
	)
	(segment
		(start 381.665734 -230.622602)
		(end 381.665734 -230.086662)
		(width 0.20066)
		(layer "F.Cu")
		(net "M_F_CPU0_SB_DQS_DN<1>")
	)
	(segment
		(start 427.506892 -219.217748)
		(end 427.811946 -219.217748)
		(width 0.20066)
		(layer "F.Cu")
		(net "M_F_CPU0_SB_DQS_DN<1>")
	)
	(segment
		(start 405.621744 -218.153488)
		(end 405.605488 -218.153488)
		(width 0.16002)
		(layer "In2.Cu")
		(net "M_F_CPU0_SB_DQS_DN<1>")
	)
	(segment
		(start 384.681222 -230.40594)
		(end 384.672332 -230.41102)
		(width 0.088646)
		(layer "In2.Cu")
		(net "M_F_CPU0_SB_DQS_DN<1>")
	)
	(segment
		(start 412.956502 -219.239592)
		(end 412.450788 -219.239592)
		(width 0.18288)
		(layer "In2.Cu")
		(net "M_F_CPU0_SB_DQS_DN<1>")
	)
	(segment
		(start 410.420566 -219.239592)
		(end 410.124402 -218.943428)
		(width 0.18288)
		(layer "In2.Cu")
		(net "M_F_CPU0_SB_DQS_DN<1>")
	)
	(segment
		(start 410.124402 -218.943428)
		(end 410.096208 -218.915234)
		(width 0.16002)
		(layer "In2.Cu")
		(net "M_F_CPU0_SB_DQS_DN<1>")
	)
	(segment
		(start 403.858984 -219.29979)
		(end 403.858984 -219.475812)
		(width 0.18288)
		(layer "In2.Cu")
		(net "M_F_CPU0_SB_DQS_DN<1>")
	)
	(segment
		(start 389.099552 -228.36251)
		(end 388.75589 -228.706172)
		(width 0.18288)
		(layer "In2.Cu")
		(net "M_F_CPU0_SB_DQS_DN<1>")
	)
	(segment
		(start 401.770596 -220.705172)
		(end 394.113258 -228.36251)
		(width 0.18288)
		(layer "In2.Cu")
		(net "M_F_CPU0_SB_DQS_DN<1>")
	)
	(segment
		(start 410.096208 -218.915234)
		(end 410.08046 -218.915234)
		(width 0.16002)
		(layer "In2.Cu")
		(net "M_F_CPU0_SB_DQS_DN<1>")
	)
	(segment
		(start 381.352806 -230.086662)
		(end 381.665734 -230.086662)
		(width 0.088646)
		(layer "In2.Cu")
		(net "M_F_CPU0_SB_DQS_DN<1>")
	)
	(segment
		(start 419.520116 -218.627452)
		(end 419.109398 -219.03817)
		(width 0.18288)
		(layer "In2.Cu")
		(net "M_F_CPU0_SB_DQS_DN<1>")
	)
	(segment
		(start 407.361136 -217.60307)
		(end 406.155906 -217.60307)
		(width 0.18288)
		(layer "In2.Cu")
		(net "M_F_CPU0_SB_DQS_DN<1>")
	)
	(segment
		(start 407.756868 -218.015058)
		(end 407.756868 -217.998802)
		(width 0.16002)
		(layer "In2.Cu")
		(net "M_F_CPU0_SB_DQS_DN<1>")
	)
	(segment
		(start 405.371046 -218.38793)
		(end 404.946866 -218.38793)
		(width 0.18288)
		(layer "In2.Cu")
		(net "M_F_CPU0_SB_DQS_DN<1>")
	)
	(segment
		(start 417.214304 -218.50223)
		(end 416.371024 -218.50223)
		(width 0.18288)
		(layer "In2.Cu")
		(net "M_F_CPU0_SB_DQS_DN<1>")
	)
	(segment
		(start 420.508176 -218.794584)
		(end 420.355268 -218.794584)
		(width 0.18288)
		(layer "In2.Cu")
		(net "M_F_CPU0_SB_DQS_DN<1>")
	)
	(segment
		(start 405.577294 -218.181682)
		(end 405.371046 -218.38793)
		(width 0.18288)
		(layer "In2.Cu")
		(net "M_F_CPU0_SB_DQS_DN<1>")
	)
	(segment
		(start 402.629624 -220.705172)
		(end 401.770596 -220.705172)
		(width 0.18288)
		(layer "In2.Cu")
		(net "M_F_CPU0_SB_DQS_DN<1>")
	)
	(segment
		(start 406.155906 -217.60307)
		(end 405.788368 -217.970608)
		(width 0.18288)
		(layer "In2.Cu")
		(net "M_F_CPU0_SB_DQS_DN<1>")
	)
	(segment
		(start 393.564618 -228.36251)
		(end 393.440158 -228.23805)
		(width 0.18288)
		(layer "In2.Cu")
		(net "M_F_CPU0_SB_DQS_DN<1>")
	)
	(segment
		(start 417.627308 -218.915234)
		(end 417.61156 -218.915234)
		(width 0.16002)
		(layer "In2.Cu")
		(net "M_F_CPU0_SB_DQS_DN<1>")
	)
	(segment
		(start 420.355268 -218.794584)
		(end 420.188136 -218.627452)
		(width 0.18288)
		(layer "In2.Cu")
		(net "M_F_CPU0_SB_DQS_DN<1>")
	)
	(segment
		(start 409.434284 -218.25331)
		(end 408.011376 -218.25331)
		(width 0.18288)
		(layer "In2.Cu")
		(net "M_F_CPU0_SB_DQS_DN<1>")
	)
	(segment
		(start 405.760174 -218.015058)
		(end 405.621744 -218.153488)
		(width 0.16002)
		(layer "In2.Cu")
		(net "M_F_CPU0_SB_DQS_DN<1>")
	)
	(segment
		(start 403.858984 -219.475812)
		(end 402.629624 -220.705172)
		(width 0.18288)
		(layer "In2.Cu")
		(net "M_F_CPU0_SB_DQS_DN<1>")
	)
	(segment
		(start 420.736014 -218.566746)
		(end 420.508176 -218.794584)
		(width 0.18288)
		(layer "In2.Cu")
		(net "M_F_CPU0_SB_DQS_DN<1>")
	)
	(segment
		(start 417.61156 -218.915234)
		(end 417.472622 -218.776296)
		(width 0.16002)
		(layer "In2.Cu")
		(net "M_F_CPU0_SB_DQS_DN<1>")
	)
	(segment
		(start 388.75589 -228.706172)
		(end 388.75589 -228.7905)
		(width 0.088646)
		(layer "In2.Cu")
		(net "M_F_CPU0_SB_DQS_DN<1>")
	)
	(segment
		(start 407.728674 -217.970608)
		(end 407.361136 -217.60307)
		(width 0.18288)
		(layer "In2.Cu")
		(net "M_F_CPU0_SB_DQS_DN<1>")
	)
	(segment
		(start 420.188136 -218.627452)
		(end 419.520116 -218.627452)
		(width 0.18288)
		(layer "In2.Cu")
		(net "M_F_CPU0_SB_DQS_DN<1>")
	)
	(segment
		(start 392.891518 -228.23805)
		(end 392.767058 -228.36251)
		(width 0.18288)
		(layer "In2.Cu")
		(net "M_F_CPU0_SB_DQS_DN<1>")
	)
	(segment
		(start 393.440158 -228.23805)
		(end 392.891518 -228.23805)
		(width 0.18288)
		(layer "In2.Cu")
		(net "M_F_CPU0_SB_DQS_DN<1>")
	)
	(segment
		(start 415.078164 -219.79509)
		(end 413.512 -219.79509)
		(width 0.18288)
		(layer "In2.Cu")
		(net "M_F_CPU0_SB_DQS_DN<1>")
	)
	(segment
		(start 407.895298 -218.153488)
		(end 407.756868 -218.015058)
		(width 0.16002)
		(layer "In2.Cu")
		(net "M_F_CPU0_SB_DQS_DN<1>")
	)
	(segment
		(start 416.371024 -218.50223)
		(end 415.078164 -219.79509)
		(width 0.18288)
		(layer "In2.Cu")
		(net "M_F_CPU0_SB_DQS_DN<1>")
	)
	(segment
		(start 409.941522 -218.760548)
		(end 409.913328 -218.732354)
		(width 0.16002)
		(layer "In2.Cu")
		(net "M_F_CPU0_SB_DQS_DN<1>")
	)
	(segment
		(start 381.295656 -230.143812)
		(end 381.352806 -230.086662)
		(width 0.088646)
		(layer "In2.Cu")
		(net "M_F_CPU0_SB_DQS_DN<1>")
	)
	(segment
		(start 384.859784 -230.076756)
		(end 384.859784 -230.086662)
		(width 0.088646)
		(layer "In2.Cu")
		(net "M_F_CPU0_SB_DQS_DN<1>")
	)
	(segment
		(start 411.82036 -218.978226)
		(end 411.558994 -219.239592)
		(width 0.18288)
		(layer "In2.Cu")
		(net "M_F_CPU0_SB_DQS_DN<1>")
	)
	(segment
		(start 388.75589 -228.7905)
		(end 388.065264 -229.481126)
		(width 0.088646)
		(layer "In2.Cu")
		(net "M_F_CPU0_SB_DQS_DN<1>")
	)
	(segment
		(start 407.756868 -217.998802)
		(end 407.728674 -217.970608)
		(width 0.16002)
		(layer "In2.Cu")
		(net "M_F_CPU0_SB_DQS_DN<1>")
	)
	(segment
		(start 413.512 -219.79509)
		(end 412.956502 -219.239592)
		(width 0.18288)
		(layer "In2.Cu")
		(net "M_F_CPU0_SB_DQS_DN<1>")
	)
	(segment
		(start 381.478536 -230.41102)
		(end 381.469646 -230.40594)
		(width 0.088646)
		(layer "In2.Cu")
		(net "M_F_CPU0_SB_DQS_DN<1>")
	)
	(segment
		(start 409.913328 -218.732354)
		(end 409.434284 -218.25331)
		(width 0.18288)
		(layer "In2.Cu")
		(net "M_F_CPU0_SB_DQS_DN<1>")
	)
	(segment
		(start 405.605488 -218.153488)
		(end 405.577294 -218.181682)
		(width 0.16002)
		(layer "In2.Cu")
		(net "M_F_CPU0_SB_DQS_DN<1>")
	)
	(segment
		(start 407.911554 -218.153488)
		(end 407.895298 -218.153488)
		(width 0.16002)
		(layer "In2.Cu")
		(net "M_F_CPU0_SB_DQS_DN<1>")
	)
	(segment
		(start 417.444428 -218.732354)
		(end 417.214304 -218.50223)
		(width 0.18288)
		(layer "In2.Cu")
		(net "M_F_CPU0_SB_DQS_DN<1>")
	)
	(segment
		(start 404.24735 -218.911424)
		(end 403.858984 -219.29979)
		(width 0.18288)
		(layer "In2.Cu")
		(net "M_F_CPU0_SB_DQS_DN<1>")
	)
	(segment
		(start 419.109398 -219.03817)
		(end 417.750244 -219.03817)
		(width 0.18288)
		(layer "In2.Cu")
		(net "M_F_CPU0_SB_DQS_DN<1>")
	)
	(segment
		(start 417.472622 -218.760548)
		(end 417.444428 -218.732354)
		(width 0.16002)
		(layer "In2.Cu")
		(net "M_F_CPU0_SB_DQS_DN<1>")
	)
	(segment
		(start 417.750244 -219.03817)
		(end 417.655502 -218.943428)
		(width 0.18288)
		(layer "In2.Cu")
		(net "M_F_CPU0_SB_DQS_DN<1>")
	)
	(segment
		(start 409.941522 -218.776296)
		(end 409.941522 -218.760548)
		(width 0.16002)
		(layer "In2.Cu")
		(net "M_F_CPU0_SB_DQS_DN<1>")
	)
	(segment
		(start 388.065264 -229.481126)
		(end 387.45541 -229.481126)
		(width 0.088646)
		(layer "In2.Cu")
		(net "M_F_CPU0_SB_DQS_DN<1>")
	)
	(segment
		(start 417.472622 -218.776296)
		(end 417.472622 -218.760548)
		(width 0.16002)
		(layer "In2.Cu")
		(net "M_F_CPU0_SB_DQS_DN<1>")
	)
	(segment
		(start 407.939748 -218.181682)
		(end 407.911554 -218.153488)
		(width 0.16002)
		(layer "In2.Cu")
		(net "M_F_CPU0_SB_DQS_DN<1>")
	)
	(segment
		(start 417.655502 -218.943428)
		(end 417.627308 -218.915234)
		(width 0.16002)
		(layer "In2.Cu")
		(net "M_F_CPU0_SB_DQS_DN<1>")
	)
	(segment
		(start 410.08046 -218.915234)
		(end 409.941522 -218.776296)
		(width 0.16002)
		(layer "In2.Cu")
		(net "M_F_CPU0_SB_DQS_DN<1>")
	)
	(segment
		(start 412.450788 -219.239592)
		(end 412.189422 -218.978226)
		(width 0.18288)
		(layer "In2.Cu")
		(net "M_F_CPU0_SB_DQS_DN<1>")
	)
	(segment
		(start 412.189422 -218.978226)
		(end 411.82036 -218.978226)
		(width 0.18288)
		(layer "In2.Cu")
		(net "M_F_CPU0_SB_DQS_DN<1>")
	)
	(segment
		(start 408.011376 -218.25331)
		(end 407.939748 -218.181682)
		(width 0.18288)
		(layer "In2.Cu")
		(net "M_F_CPU0_SB_DQS_DN<1>")
	)
	(segment
		(start 404.423372 -218.911424)
		(end 404.24735 -218.911424)
		(width 0.18288)
		(layer "In2.Cu")
		(net "M_F_CPU0_SB_DQS_DN<1>")
	)
	(segment
		(start 392.767058 -228.36251)
		(end 389.099552 -228.36251)
		(width 0.18288)
		(layer "In2.Cu")
		(net "M_F_CPU0_SB_DQS_DN<1>")
	)
	(segment
		(start 405.760174 -217.998802)
		(end 405.760174 -218.015058)
		(width 0.16002)
		(layer "In2.Cu")
		(net "M_F_CPU0_SB_DQS_DN<1>")
	)
	(segment
		(start 404.946866 -218.38793)
		(end 404.423372 -218.911424)
		(width 0.18288)
		(layer "In2.Cu")
		(net "M_F_CPU0_SB_DQS_DN<1>")
	)
	(segment
		(start 405.788368 -217.970608)
		(end 405.760174 -217.998802)
		(width 0.16002)
		(layer "In2.Cu")
		(net "M_F_CPU0_SB_DQS_DN<1>")
	)
	(segment
		(start 411.558994 -219.239592)
		(end 410.420566 -219.239592)
		(width 0.18288)
		(layer "In2.Cu")
		(net "M_F_CPU0_SB_DQS_DN<1>")
	)
	(segment
		(start 394.113258 -228.36251)
		(end 393.564618 -228.36251)
		(width 0.18288)
		(layer "In2.Cu")
		(net "M_F_CPU0_SB_DQS_DN<1>")
	)
	(arc
		(start 385.142232 -229.597204)
		(mid 384.937897 -229.799809)
		(end 384.859784 -230.076756)
		(width 0.088646)
		(layer "In2.Cu")
		(net "M_F_CPU0_SB_DQS_DN<1>")
	)
	(arc
		(start 383.358136 -230.41102)
		(mid 383.075434 -230.335244)
		(end 382.792732 -230.41102)
		(width 0.088646)
		(layer "In2.Cu")
		(net "M_F_CPU0_SB_DQS_DN<1>")
	)
	(arc
		(start 382.418336 -230.41102)
		(mid 382.135634 -230.335244)
		(end 381.852932 -230.41102)
		(width 0.088646)
		(layer "In2.Cu")
		(net "M_F_CPU0_SB_DQS_DN<1>")
	)
	(arc
		(start 381.852932 -230.41102)
		(mid 381.665734 -230.461163)
		(end 381.478536 -230.41102)
		(width 0.088646)
		(layer "In2.Cu")
		(net "M_F_CPU0_SB_DQS_DN<1>")
	)
	(arc
		(start 384.297936 -230.41102)
		(mid 384.015234 -230.335244)
		(end 383.732532 -230.41102)
		(width 0.088646)
		(layer "In2.Cu")
		(net "M_F_CPU0_SB_DQS_DN<1>")
	)
	(arc
		(start 381.469646 -230.40594)
		(mid 381.353837 -230.294011)
		(end 381.295656 -230.143812)
		(width 0.088646)
		(layer "In2.Cu")
		(net "M_F_CPU0_SB_DQS_DN<1>")
	)
	(arc
		(start 386.647436 -229.597204)
		(mid 386.364734 -229.521428)
		(end 386.082032 -229.597204)
		(width 0.088646)
		(layer "In2.Cu")
		(net "M_F_CPU0_SB_DQS_DN<1>")
	)
	(arc
		(start 386.082032 -229.597204)
		(mid 385.894834 -229.647347)
		(end 385.707636 -229.597204)
		(width 0.088646)
		(layer "In2.Cu")
		(net "M_F_CPU0_SB_DQS_DN<1>")
	)
	(arc
		(start 384.672332 -230.41102)
		(mid 384.485134 -230.461163)
		(end 384.297936 -230.41102)
		(width 0.088646)
		(layer "In2.Cu")
		(net "M_F_CPU0_SB_DQS_DN<1>")
	)
	(arc
		(start 382.792732 -230.41102)
		(mid 382.605534 -230.461163)
		(end 382.418336 -230.41102)
		(width 0.088646)
		(layer "In2.Cu")
		(net "M_F_CPU0_SB_DQS_DN<1>")
	)
	(arc
		(start 384.859784 -230.086662)
		(mid 384.812105 -230.269562)
		(end 384.681222 -230.40594)
		(width 0.088646)
		(layer "In2.Cu")
		(net "M_F_CPU0_SB_DQS_DN<1>")
	)
	(arc
		(start 387.021832 -229.597204)
		(mid 386.834634 -229.647347)
		(end 386.647436 -229.597204)
		(width 0.088646)
		(layer "In2.Cu")
		(net "M_F_CPU0_SB_DQS_DN<1>")
	)
	(arc
		(start 385.707636 -229.597204)
		(mid 385.424934 -229.521428)
		(end 385.142232 -229.597204)
		(width 0.088646)
		(layer "In2.Cu")
		(net "M_F_CPU0_SB_DQS_DN<1>")
	)
	(arc
		(start 383.732532 -230.41102)
		(mid 383.545334 -230.461163)
		(end 383.358136 -230.41102)
		(width 0.088646)
		(layer "In2.Cu")
		(net "M_F_CPU0_SB_DQS_DN<1>")
	)
	(arc
		(start 387.45541 -229.481126)
		(mid 387.230981 -229.510621)
		(end 387.021832 -229.597204)
		(width 0.088646)
		(layer "In2.Cu")
		(net "M_F_CPU0_SB_DQS_DN<1>")
	)
	(segment
		(start 420.736014 -227.91674)
		(end 421.840914 -227.91674)
		(width 0.20066)
		(layer "F.Cu")
		(net "M_F_CPU0_SB_DQS_DN<0>")
	)
	(segment
		(start 426.94606 -228.341682)
		(end 426.951394 -228.336348)
		(width 0.1016)
		(layer "F.Cu")
		(net "M_F_CPU0_SB_DQS_DN<0>")
	)
	(segment
		(start 427.811946 -228.567742)
		(end 428.22241 -228.157278)
		(width 0.20066)
		(layer "F.Cu")
		(net "M_F_CPU0_SB_DQS_DN<0>")
	)
	(segment
		(start 428.554896 -228.157278)
		(end 428.795434 -227.91674)
		(width 0.20066)
		(layer "F.Cu")
		(net "M_F_CPU0_SB_DQS_DN<0>")
	)
	(segment
		(start 423.407078 -228.198426)
		(end 423.821606 -228.612954)
		(width 0.20066)
		(layer "F.Cu")
		(net "M_F_CPU0_SB_DQS_DN<0>")
	)
	(segment
		(start 378.376434 -237.947454)
		(end 378.376434 -237.411514)
		(width 0.20066)
		(layer "F.Cu")
		(net "M_F_CPU0_SB_DQS_DN<0>")
	)
	(segment
		(start 424.766486 -228.341682)
		(end 426.94606 -228.341682)
		(width 0.1016)
		(layer "F.Cu")
		(net "M_F_CPU0_SB_DQS_DN<0>")
	)
	(segment
		(start 428.22241 -228.157278)
		(end 428.554896 -228.157278)
		(width 0.20066)
		(layer "F.Cu")
		(net "M_F_CPU0_SB_DQS_DN<0>")
	)
	(segment
		(start 378.37618 -237.947454)
		(end 378.376434 -237.947454)
		(width 0.20066)
		(layer "F.Cu")
		(net "M_F_CPU0_SB_DQS_DN<0>")
	)
	(segment
		(start 427.506892 -228.567742)
		(end 427.811946 -228.567742)
		(width 0.20066)
		(layer "F.Cu")
		(net "M_F_CPU0_SB_DQS_DN<0>")
	)
	(segment
		(start 426.951394 -228.336348)
		(end 427.275498 -228.336348)
		(width 0.20066)
		(layer "F.Cu")
		(net "M_F_CPU0_SB_DQS_DN<0>")
	)
	(segment
		(start 428.795434 -227.91674)
		(end 429.384714 -227.91674)
		(width 0.20066)
		(layer "F.Cu")
		(net "M_F_CPU0_SB_DQS_DN<0>")
	)
	(segment
		(start 422.67124 -228.198426)
		(end 423.407078 -228.198426)
		(width 0.20066)
		(layer "F.Cu")
		(net "M_F_CPU0_SB_DQS_DN<0>")
	)
	(segment
		(start 421.840914 -227.91674)
		(end 422.389554 -227.91674)
		(width 0.20066)
		(layer "F.Cu")
		(net "M_F_CPU0_SB_DQS_DN<0>")
	)
	(segment
		(start 422.389554 -227.91674)
		(end 422.67124 -228.198426)
		(width 0.20066)
		(layer "F.Cu")
		(net "M_F_CPU0_SB_DQS_DN<0>")
	)
	(segment
		(start 424.614594 -228.341682)
		(end 424.762168 -228.341682)
		(width 0.20066)
		(layer "F.Cu")
		(net "M_F_CPU0_SB_DQS_DN<0>")
	)
	(segment
		(start 427.275498 -228.336348)
		(end 427.506892 -228.567742)
		(width 0.20066)
		(layer "F.Cu")
		(net "M_F_CPU0_SB_DQS_DN<0>")
	)
	(segment
		(start 424.762168 -228.341682)
		(end 424.766486 -228.341682)
		(width 0.101854)
		(layer "F.Cu")
		(net "M_F_CPU0_SB_DQS_DN<0>")
	)
	(segment
		(start 423.821606 -228.612954)
		(end 424.343322 -228.612954)
		(width 0.20066)
		(layer "F.Cu")
		(net "M_F_CPU0_SB_DQS_DN<0>")
	)
	(segment
		(start 424.343322 -228.612954)
		(end 424.614594 -228.341682)
		(width 0.20066)
		(layer "F.Cu")
		(net "M_F_CPU0_SB_DQS_DN<0>")
	)
	(segment
		(start 417.72713 -227.55098)
		(end 415.029904 -227.55098)
		(width 0.18288)
		(layer "In4.Cu")
		(net "M_F_CPU0_SB_DQS_DN<0>")
	)
	(segment
		(start 381.008382 -237.736126)
		(end 380.997968 -237.73003)
		(width 0.088646)
		(layer "In4.Cu")
		(net "M_F_CPU0_SB_DQS_DN<0>")
	)
	(segment
		(start 412.06928 -226.656646)
		(end 411.861254 -226.656646)
		(width 0.18288)
		(layer "In4.Cu")
		(net "M_F_CPU0_SB_DQS_DN<0>")
	)
	(segment
		(start 419.754812 -227.954078)
		(end 417.72713 -227.55098)
		(width 0.18288)
		(layer "In4.Cu")
		(net "M_F_CPU0_SB_DQS_DN<0>")
	)
	(segment
		(start 409.264612 -226.065334)
		(end 407.363422 -226.065334)
		(width 0.18288)
		(layer "In4.Cu")
		(net "M_F_CPU0_SB_DQS_DN<0>")
	)
	(segment
		(start 407.363422 -226.065334)
		(end 406.66289 -226.765866)
		(width 0.18288)
		(layer "In4.Cu")
		(net "M_F_CPU0_SB_DQS_DN<0>")
	)
	(segment
		(start 388.941564 -235.90885)
		(end 388.918196 -235.90885)
		(width 0.088646)
		(layer "In4.Cu")
		(net "M_F_CPU0_SB_DQS_DN<0>")
	)
	(segment
		(start 400.367246 -229.183692)
		(end 399.980658 -229.57028)
		(width 0.18288)
		(layer "In4.Cu")
		(net "M_F_CPU0_SB_DQS_DN<0>")
	)
	(segment
		(start 378.578364 -237.72749)
		(end 378.563632 -237.736126)
		(width 0.088646)
		(layer "In4.Cu")
		(net "M_F_CPU0_SB_DQS_DN<0>")
	)
	(segment
		(start 388.918196 -235.90885)
		(end 388.858506 -235.96854)
		(width 0.088646)
		(layer "In4.Cu")
		(net "M_F_CPU0_SB_DQS_DN<0>")
	)
	(segment
		(start 389.732012 -235.90885)
		(end 388.941564 -235.90885)
		(width 0.18288)
		(layer "In4.Cu")
		(net "M_F_CPU0_SB_DQS_DN<0>")
	)
	(segment
		(start 398.251934 -231.475026)
		(end 396.190216 -233.536744)
		(width 0.18288)
		(layer "In4.Cu")
		(net "M_F_CPU0_SB_DQS_DN<0>")
	)
	(segment
		(start 388.204964 -236.866684)
		(end 387.411214 -237.659926)
		(width 0.088646)
		(layer "In4.Cu")
		(net "M_F_CPU0_SB_DQS_DN<0>")
	)
	(segment
		(start 398.638268 -230.91267)
		(end 398.251934 -231.299004)
		(width 0.18288)
		(layer "In4.Cu")
		(net "M_F_CPU0_SB_DQS_DN<0>")
	)
	(segment
		(start 398.251934 -231.299004)
		(end 398.251934 -231.475026)
		(width 0.18288)
		(layer "In4.Cu")
		(net "M_F_CPU0_SB_DQS_DN<0>")
	)
	(segment
		(start 415.029904 -227.55098)
		(end 413.708596 -226.229672)
		(width 0.18288)
		(layer "In4.Cu")
		(net "M_F_CPU0_SB_DQS_DN<0>")
	)
	(segment
		(start 405.43734 -226.642422)
		(end 405.174196 -226.905566)
		(width 0.18288)
		(layer "In4.Cu")
		(net "M_F_CPU0_SB_DQS_DN<0>")
	)
	(segment
		(start 381.948436 -237.736126)
		(end 381.938022 -237.73003)
		(width 0.088646)
		(layer "In4.Cu")
		(net "M_F_CPU0_SB_DQS_DN<0>")
	)
	(segment
		(start 409.537408 -225.792538)
		(end 409.264612 -226.065334)
		(width 0.18288)
		(layer "In4.Cu")
		(net "M_F_CPU0_SB_DQS_DN<0>")
	)
	(segment
		(start 388.858506 -235.96854)
		(end 388.581138 -235.96854)
		(width 0.088646)
		(layer "In4.Cu")
		(net "M_F_CPU0_SB_DQS_DN<0>")
	)
	(segment
		(start 392.104118 -233.536744)
		(end 389.732012 -235.90885)
		(width 0.18288)
		(layer "In4.Cu")
		(net "M_F_CPU0_SB_DQS_DN<0>")
	)
	(segment
		(start 383.262632 -237.735872)
		(end 383.262632 -237.736126)
		(width 0.088646)
		(layer "In4.Cu")
		(net "M_F_CPU0_SB_DQS_DN<0>")
	)
	(segment
		(start 405.842216 -226.642422)
		(end 405.43734 -226.642422)
		(width 0.18288)
		(layer "In4.Cu")
		(net "M_F_CPU0_SB_DQS_DN<0>")
	)
	(segment
		(start 413.098742 -226.229672)
		(end 412.06928 -226.656646)
		(width 0.18288)
		(layer "In4.Cu")
		(net "M_F_CPU0_SB_DQS_DN<0>")
	)
	(segment
		(start 388.581138 -235.96854)
		(end 388.380986 -236.168692)
		(width 0.088646)
		(layer "In4.Cu")
		(net "M_F_CPU0_SB_DQS_DN<0>")
	)
	(segment
		(start 399.980658 -229.57028)
		(end 399.980658 -229.746302)
		(width 0.18288)
		(layer "In4.Cu")
		(net "M_F_CPU0_SB_DQS_DN<0>")
	)
	(segment
		(start 388.380986 -236.168692)
		(end 388.380986 -236.44225)
		(width 0.088646)
		(layer "In4.Cu")
		(net "M_F_CPU0_SB_DQS_DN<0>")
	)
	(segment
		(start 410.223716 -226.07397)
		(end 409.942284 -225.792538)
		(width 0.18288)
		(layer "In4.Cu")
		(net "M_F_CPU0_SB_DQS_DN<0>")
	)
	(segment
		(start 405.174196 -226.905566)
		(end 402.821394 -226.905566)
		(width 0.18288)
		(layer "In4.Cu")
		(net "M_F_CPU0_SB_DQS_DN<0>")
	)
	(segment
		(start 398.81429 -230.91267)
		(end 398.638268 -230.91267)
		(width 0.18288)
		(layer "In4.Cu")
		(net "M_F_CPU0_SB_DQS_DN<0>")
	)
	(segment
		(start 410.455364 -226.07397)
		(end 410.223716 -226.07397)
		(width 0.18288)
		(layer "In4.Cu")
		(net "M_F_CPU0_SB_DQS_DN<0>")
	)
	(segment
		(start 406.66289 -226.765866)
		(end 406.33777 -226.900994)
		(width 0.18288)
		(layer "In4.Cu")
		(net "M_F_CPU0_SB_DQS_DN<0>")
	)
	(segment
		(start 399.980658 -229.746302)
		(end 398.81429 -230.91267)
		(width 0.18288)
		(layer "In4.Cu")
		(net "M_F_CPU0_SB_DQS_DN<0>")
	)
	(segment
		(start 409.942284 -225.792538)
		(end 409.537408 -225.792538)
		(width 0.18288)
		(layer "In4.Cu")
		(net "M_F_CPU0_SB_DQS_DN<0>")
	)
	(segment
		(start 396.190216 -233.536744)
		(end 392.104118 -233.536744)
		(width 0.18288)
		(layer "In4.Cu")
		(net "M_F_CPU0_SB_DQS_DN<0>")
	)
	(segment
		(start 406.33777 -226.900994)
		(end 406.100788 -226.900994)
		(width 0.18288)
		(layer "In4.Cu")
		(net "M_F_CPU0_SB_DQS_DN<0>")
	)
	(segment
		(start 413.708596 -226.229672)
		(end 413.098742 -226.229672)
		(width 0.18288)
		(layer "In4.Cu")
		(net "M_F_CPU0_SB_DQS_DN<0>")
	)
	(segment
		(start 419.978586 -228.177852)
		(end 419.754812 -227.954078)
		(width 0.18288)
		(layer "In4.Cu")
		(net "M_F_CPU0_SB_DQS_DN<0>")
	)
	(segment
		(start 406.100788 -226.900994)
		(end 405.842216 -226.642422)
		(width 0.18288)
		(layer "In4.Cu")
		(net "M_F_CPU0_SB_DQS_DN<0>")
	)
	(segment
		(start 411.861254 -226.656646)
		(end 410.455364 -226.07397)
		(width 0.18288)
		(layer "In4.Cu")
		(net "M_F_CPU0_SB_DQS_DN<0>")
	)
	(segment
		(start 420.736014 -227.91674)
		(end 420.474902 -228.177852)
		(width 0.18288)
		(layer "In4.Cu")
		(net "M_F_CPU0_SB_DQS_DN<0>")
	)
	(segment
		(start 378.189236 -237.736126)
		(end 378.180346 -237.731046)
		(width 0.088646)
		(layer "In4.Cu")
		(net "M_F_CPU0_SB_DQS_DN<0>")
	)
	(segment
		(start 379.518164 -237.72749)
		(end 379.503432 -237.736126)
		(width 0.088646)
		(layer "In4.Cu")
		(net "M_F_CPU0_SB_DQS_DN<0>")
	)
	(segment
		(start 378.006356 -237.469172)
		(end 378.064014 -237.411514)
		(width 0.088646)
		(layer "In4.Cu")
		(net "M_F_CPU0_SB_DQS_DN<0>")
	)
	(segment
		(start 387.411214 -237.659926)
		(end 387.304026 -237.659926)
		(width 0.088646)
		(layer "In4.Cu")
		(net "M_F_CPU0_SB_DQS_DN<0>")
	)
	(segment
		(start 388.380986 -236.44225)
		(end 388.204964 -236.866684)
		(width 0.088646)
		(layer "In4.Cu")
		(net "M_F_CPU0_SB_DQS_DN<0>")
	)
	(segment
		(start 420.474902 -228.177852)
		(end 419.978586 -228.177852)
		(width 0.18288)
		(layer "In4.Cu")
		(net "M_F_CPU0_SB_DQS_DN<0>")
	)
	(segment
		(start 400.543268 -229.183692)
		(end 400.367246 -229.183692)
		(width 0.18288)
		(layer "In4.Cu")
		(net "M_F_CPU0_SB_DQS_DN<0>")
	)
	(segment
		(start 378.064014 -237.411514)
		(end 378.376434 -237.411514)
		(width 0.088646)
		(layer "In4.Cu")
		(net "M_F_CPU0_SB_DQS_DN<0>")
	)
	(segment
		(start 402.821394 -226.905566)
		(end 400.543268 -229.183692)
		(width 0.18288)
		(layer "In4.Cu")
		(net "M_F_CPU0_SB_DQS_DN<0>")
	)
	(arc
		(start 382.322832 -237.736126)
		(mid 382.135634 -237.786269)
		(end 381.948436 -237.736126)
		(width 0.088646)
		(layer "In4.Cu")
		(net "M_F_CPU0_SB_DQS_DN<0>")
	)
	(arc
		(start 385.707636 -237.735872)
		(mid 385.424934 -237.66013)
		(end 385.142232 -237.735872)
		(width 0.088646)
		(layer "In4.Cu")
		(net "M_F_CPU0_SB_DQS_DN<0>")
	)
	(arc
		(start 383.828036 -237.735872)
		(mid 383.545334 -237.66013)
		(end 383.262632 -237.735872)
		(width 0.088646)
		(layer "In4.Cu")
		(net "M_F_CPU0_SB_DQS_DN<0>")
	)
	(arc
		(start 386.082032 -237.735872)
		(mid 385.894834 -237.786015)
		(end 385.707636 -237.735872)
		(width 0.088646)
		(layer "In4.Cu")
		(net "M_F_CPU0_SB_DQS_DN<0>")
	)
	(arc
		(start 379.129036 -237.736126)
		(mid 378.854837 -237.660291)
		(end 378.578364 -237.72749)
		(width 0.088646)
		(layer "In4.Cu")
		(net "M_F_CPU0_SB_DQS_DN<0>")
	)
	(arc
		(start 387.021832 -237.735872)
		(mid 386.834634 -237.786015)
		(end 386.647436 -237.735872)
		(width 0.088646)
		(layer "In4.Cu")
		(net "M_F_CPU0_SB_DQS_DN<0>")
	)
	(arc
		(start 385.142232 -237.735872)
		(mid 384.955034 -237.786015)
		(end 384.767836 -237.735872)
		(width 0.088646)
		(layer "In4.Cu")
		(net "M_F_CPU0_SB_DQS_DN<0>")
	)
	(arc
		(start 380.068836 -237.736126)
		(mid 379.794637 -237.660291)
		(end 379.518164 -237.72749)
		(width 0.088646)
		(layer "In4.Cu")
		(net "M_F_CPU0_SB_DQS_DN<0>")
	)
	(arc
		(start 383.262632 -237.736126)
		(mid 383.075434 -237.786269)
		(end 382.888236 -237.736126)
		(width 0.088646)
		(layer "In4.Cu")
		(net "M_F_CPU0_SB_DQS_DN<0>")
	)
	(arc
		(start 381.938022 -237.73003)
		(mid 381.65959 -237.660184)
		(end 381.382778 -237.736126)
		(width 0.088646)
		(layer "In4.Cu")
		(net "M_F_CPU0_SB_DQS_DN<0>")
	)
	(arc
		(start 378.563632 -237.736126)
		(mid 378.376434 -237.786269)
		(end 378.189236 -237.736126)
		(width 0.088646)
		(layer "In4.Cu")
		(net "M_F_CPU0_SB_DQS_DN<0>")
	)
	(arc
		(start 380.443232 -237.736126)
		(mid 380.256034 -237.786269)
		(end 380.068836 -237.736126)
		(width 0.088646)
		(layer "In4.Cu")
		(net "M_F_CPU0_SB_DQS_DN<0>")
	)
	(arc
		(start 384.202432 -237.735872)
		(mid 384.015234 -237.786015)
		(end 383.828036 -237.735872)
		(width 0.088646)
		(layer "In4.Cu")
		(net "M_F_CPU0_SB_DQS_DN<0>")
	)
	(arc
		(start 384.767836 -237.735872)
		(mid 384.485134 -237.66013)
		(end 384.202432 -237.735872)
		(width 0.088646)
		(layer "In4.Cu")
		(net "M_F_CPU0_SB_DQS_DN<0>")
	)
	(arc
		(start 387.304026 -237.659926)
		(mid 387.15795 -237.679385)
		(end 387.021832 -237.735872)
		(width 0.088646)
		(layer "In4.Cu")
		(net "M_F_CPU0_SB_DQS_DN<0>")
	)
	(arc
		(start 382.888236 -237.736126)
		(mid 382.605534 -237.66035)
		(end 382.322832 -237.736126)
		(width 0.088646)
		(layer "In4.Cu")
		(net "M_F_CPU0_SB_DQS_DN<0>")
	)
	(arc
		(start 386.647436 -237.735872)
		(mid 386.364734 -237.66013)
		(end 386.082032 -237.735872)
		(width 0.088646)
		(layer "In4.Cu")
		(net "M_F_CPU0_SB_DQS_DN<0>")
	)
	(arc
		(start 380.997968 -237.73003)
		(mid 380.71979 -237.660307)
		(end 380.443232 -237.736126)
		(width 0.088646)
		(layer "In4.Cu")
		(net "M_F_CPU0_SB_DQS_DN<0>")
	)
	(arc
		(start 378.180346 -237.731046)
		(mid 378.064607 -237.619222)
		(end 378.006356 -237.469172)
		(width 0.088646)
		(layer "In4.Cu")
		(net "M_F_CPU0_SB_DQS_DN<0>")
	)
	(arc
		(start 381.382778 -237.736126)
		(mid 381.19558 -237.786269)
		(end 381.008382 -237.736126)
		(width 0.088646)
		(layer "In4.Cu")
		(net "M_F_CPU0_SB_DQS_DN<0>")
	)
	(arc
		(start 379.503432 -237.736126)
		(mid 379.316234 -237.786269)
		(end 379.129036 -237.736126)
		(width 0.088646)
		(layer "In4.Cu")
		(net "M_F_CPU0_SB_DQS_DN<0>")
	)
	(segment
		(start 426.951394 -220.68536)
		(end 426.945044 -220.69171)
		(width 0.1016)
		(layer "F.Cu")
		(net "M_F_CPU0_SB_DQ<9>")
	)
	(segment
		(start 381.19558 -231.436418)
		(end 381.19558 -230.900732)
		(width 0.20066)
		(layer "F.Cu")
		(net "M_F_CPU0_SB_DQ<9>")
	)
	(segment
		(start 424.273472 -221.177358)
		(end 424.085512 -221.365318)
		(width 0.20066)
		(layer "F.Cu")
		(net "M_F_CPU0_SB_DQ<9>")
	)
	(segment
		(start 424.085512 -221.365318)
		(end 423.610278 -221.365318)
		(width 0.20066)
		(layer "F.Cu")
		(net "M_F_CPU0_SB_DQ<9>")
	)
	(segment
		(start 424.756326 -220.69171)
		(end 424.73626 -220.69171)
		(width 0.101854)
		(layer "F.Cu")
		(net "M_F_CPU0_SB_DQ<9>")
	)
	(segment
		(start 424.391582 -220.69171)
		(end 424.273472 -220.80982)
		(width 0.20066)
		(layer "F.Cu")
		(net "M_F_CPU0_SB_DQ<9>")
	)
	(segment
		(start 427.792896 -221.116906)
		(end 427.36135 -220.68536)
		(width 0.20066)
		(layer "F.Cu")
		(net "M_F_CPU0_SB_DQ<9>")
	)
	(segment
		(start 423.361612 -221.116652)
		(end 421.840914 -221.116652)
		(width 0.20066)
		(layer "F.Cu")
		(net "M_F_CPU0_SB_DQ<9>")
	)
	(segment
		(start 426.945044 -220.69171)
		(end 424.756326 -220.69171)
		(width 0.1016)
		(layer "F.Cu")
		(net "M_F_CPU0_SB_DQ<9>")
	)
	(segment
		(start 424.273472 -220.80982)
		(end 424.273472 -221.177358)
		(width 0.20066)
		(layer "F.Cu")
		(net "M_F_CPU0_SB_DQ<9>")
	)
	(segment
		(start 429.384714 -221.116652)
		(end 429.38446 -221.116906)
		(width 0.20066)
		(layer "F.Cu")
		(net "M_F_CPU0_SB_DQ<9>")
	)
	(segment
		(start 381.19558 -230.900732)
		(end 381.195834 -230.900478)
		(width 0.20066)
		(layer "F.Cu")
		(net "M_F_CPU0_SB_DQ<9>")
	)
	(segment
		(start 421.840914 -221.116652)
		(end 420.736014 -221.116652)
		(width 0.20066)
		(layer "F.Cu")
		(net "M_F_CPU0_SB_DQ<9>")
	)
	(segment
		(start 427.36135 -220.68536)
		(end 426.951394 -220.68536)
		(width 0.20066)
		(layer "F.Cu")
		(net "M_F_CPU0_SB_DQ<9>")
	)
	(segment
		(start 423.610278 -221.365318)
		(end 423.361612 -221.116652)
		(width 0.20066)
		(layer "F.Cu")
		(net "M_F_CPU0_SB_DQ<9>")
	)
	(segment
		(start 424.73626 -220.69171)
		(end 424.391582 -220.69171)
		(width 0.20066)
		(layer "F.Cu")
		(net "M_F_CPU0_SB_DQ<9>")
	)
	(segment
		(start 429.38446 -221.116906)
		(end 427.792896 -221.116906)
		(width 0.20066)
		(layer "F.Cu")
		(net "M_F_CPU0_SB_DQ<9>")
	)
	(segment
		(start 407.10231 -220.697552)
		(end 406.86609 -220.461332)
		(width 0.18288)
		(layer "In2.Cu")
		(net "M_F_CPU0_SB_DQ<9>")
	)
	(segment
		(start 420.134034 -221.61627)
		(end 419.940994 -221.42323)
		(width 0.18288)
		(layer "In2.Cu")
		(net "M_F_CPU0_SB_DQ<9>")
	)
	(segment
		(start 406.467818 -220.461332)
		(end 406.215342 -220.713808)
		(width 0.18288)
		(layer "In2.Cu")
		(net "M_F_CPU0_SB_DQ<9>")
	)
	(segment
		(start 408.313382 -220.534738)
		(end 408.150568 -220.697552)
		(width 0.18288)
		(layer "In2.Cu")
		(net "M_F_CPU0_SB_DQ<9>")
	)
	(segment
		(start 411.62478 -221.454472)
		(end 411.62478 -221.436184)
		(width 0.18288)
		(layer "In2.Cu")
		(net "M_F_CPU0_SB_DQ<9>")
	)
	(segment
		(start 408.851608 -220.534738)
		(end 408.313382 -220.534738)
		(width 0.18288)
		(layer "In2.Cu")
		(net "M_F_CPU0_SB_DQ<9>")
	)
	(segment
		(start 419.940994 -221.42323)
		(end 419.940994 -220.888814)
		(width 0.18288)
		(layer "In2.Cu")
		(net "M_F_CPU0_SB_DQ<9>")
	)
	(segment
		(start 406.215342 -220.713808)
		(end 405.405336 -220.713808)
		(width 0.18288)
		(layer "In2.Cu")
		(net "M_F_CPU0_SB_DQ<9>")
	)
	(segment
		(start 409.38958 -221.545912)
		(end 409.044648 -221.20098)
		(width 0.18288)
		(layer "In2.Cu")
		(net "M_F_CPU0_SB_DQ<9>")
	)
	(segment
		(start 394.54963 -229.81412)
		(end 389.61949 -229.81412)
		(width 0.18288)
		(layer "In2.Cu")
		(net "M_F_CPU0_SB_DQ<9>")
	)
	(segment
		(start 420.736014 -221.455996)
		(end 420.652702 -221.539308)
		(width 0.18288)
		(layer "In2.Cu")
		(net "M_F_CPU0_SB_DQ<9>")
	)
	(segment
		(start 420.652702 -221.539308)
		(end 420.466774 -221.61627)
		(width 0.18288)
		(layer "In2.Cu")
		(net "M_F_CPU0_SB_DQ<9>")
	)
	(segment
		(start 381.775716 -231.34574)
		(end 381.260604 -230.950262)
		(width 0.088646)
		(layer "In2.Cu")
		(net "M_F_CPU0_SB_DQ<9>")
	)
	(segment
		(start 408.150568 -220.697552)
		(end 407.10231 -220.697552)
		(width 0.18288)
		(layer "In2.Cu")
		(net "M_F_CPU0_SB_DQ<9>")
	)
	(segment
		(start 381.852932 -231.39019)
		(end 381.775716 -231.34574)
		(width 0.088646)
		(layer "In2.Cu")
		(net "M_F_CPU0_SB_DQ<9>")
	)
	(segment
		(start 413.796734 -221.896432)
		(end 413.183832 -221.28353)
		(width 0.18288)
		(layer "In2.Cu")
		(net "M_F_CPU0_SB_DQ<9>")
	)
	(segment
		(start 412.87319 -221.28353)
		(end 412.542228 -221.614492)
		(width 0.18288)
		(layer "In2.Cu")
		(net "M_F_CPU0_SB_DQ<9>")
	)
	(segment
		(start 418.851842 -221.429072)
		(end 418.688012 -221.592902)
		(width 0.18288)
		(layer "In2.Cu")
		(net "M_F_CPU0_SB_DQ<9>")
	)
	(segment
		(start 415.889694 -221.280228)
		(end 415.365692 -221.280228)
		(width 0.18288)
		(layer "In2.Cu")
		(net "M_F_CPU0_SB_DQ<9>")
	)
	(segment
		(start 381.260604 -230.950262)
		(end 381.195834 -230.900478)
		(width 0.088646)
		(layer "In2.Cu")
		(net "M_F_CPU0_SB_DQ<9>")
	)
	(segment
		(start 402.327618 -222.036132)
		(end 394.54963 -229.81412)
		(width 0.18288)
		(layer "In2.Cu")
		(net "M_F_CPU0_SB_DQ<9>")
	)
	(segment
		(start 417.788344 -221.399862)
		(end 417.788344 -220.934026)
		(width 0.18288)
		(layer "In2.Cu")
		(net "M_F_CPU0_SB_DQ<9>")
	)
	(segment
		(start 415.991294 -221.381828)
		(end 415.889694 -221.280228)
		(width 0.18288)
		(layer "In2.Cu")
		(net "M_F_CPU0_SB_DQ<9>")
	)
	(segment
		(start 420.736014 -221.116652)
		(end 420.736014 -221.455996)
		(width 0.18288)
		(layer "In2.Cu")
		(net "M_F_CPU0_SB_DQ<9>")
	)
	(segment
		(start 412.542228 -221.614492)
		(end 411.7848 -221.614492)
		(width 0.18288)
		(layer "In2.Cu")
		(net "M_F_CPU0_SB_DQ<9>")
	)
	(segment
		(start 417.282122 -220.427804)
		(end 416.997134 -220.427804)
		(width 0.18288)
		(layer "In2.Cu")
		(net "M_F_CPU0_SB_DQ<9>")
	)
	(segment
		(start 417.981384 -221.592902)
		(end 417.788344 -221.399862)
		(width 0.18288)
		(layer "In2.Cu")
		(net "M_F_CPU0_SB_DQ<9>")
	)
	(segment
		(start 411.62478 -221.436184)
		(end 411.358588 -221.169992)
		(width 0.18288)
		(layer "In2.Cu")
		(net "M_F_CPU0_SB_DQ<9>")
	)
	(segment
		(start 418.851842 -220.840046)
		(end 418.851842 -221.429072)
		(width 0.18288)
		(layer "In2.Cu")
		(net "M_F_CPU0_SB_DQ<9>")
	)
	(segment
		(start 389.61949 -229.81412)
		(end 389.18642 -229.81412)
		(width 0.088646)
		(layer "In2.Cu")
		(net "M_F_CPU0_SB_DQ<9>")
	)
	(segment
		(start 385.520184 -230.900478)
		(end 385.520184 -230.91902)
		(width 0.088646)
		(layer "In2.Cu")
		(net "M_F_CPU0_SB_DQ<9>")
	)
	(segment
		(start 382.807464 -231.398826)
		(end 382.792732 -231.39019)
		(width 0.088646)
		(layer "In2.Cu")
		(net "M_F_CPU0_SB_DQ<9>")
	)
	(segment
		(start 410.905452 -221.169992)
		(end 410.529532 -221.545912)
		(width 0.18288)
		(layer "In2.Cu")
		(net "M_F_CPU0_SB_DQ<9>")
	)
	(segment
		(start 411.7848 -221.614492)
		(end 411.62478 -221.454472)
		(width 0.18288)
		(layer "In2.Cu")
		(net "M_F_CPU0_SB_DQ<9>")
	)
	(segment
		(start 413.183832 -221.28353)
		(end 412.87319 -221.28353)
		(width 0.18288)
		(layer "In2.Cu")
		(net "M_F_CPU0_SB_DQ<9>")
	)
	(segment
		(start 411.358588 -221.169992)
		(end 410.905452 -221.169992)
		(width 0.18288)
		(layer "In2.Cu")
		(net "M_F_CPU0_SB_DQ<9>")
	)
	(segment
		(start 388.474966 -230.525574)
		(end 387.774434 -230.525574)
		(width 0.088646)
		(layer "In2.Cu")
		(net "M_F_CPU0_SB_DQ<9>")
	)
	(segment
		(start 404.083012 -222.036132)
		(end 402.327618 -222.036132)
		(width 0.18288)
		(layer "In2.Cu")
		(net "M_F_CPU0_SB_DQ<9>")
	)
	(segment
		(start 415.991294 -222.005906)
		(end 415.991294 -221.381828)
		(width 0.18288)
		(layer "In2.Cu")
		(net "M_F_CPU0_SB_DQ<9>")
	)
	(segment
		(start 414.749488 -221.896432)
		(end 413.796734 -221.896432)
		(width 0.18288)
		(layer "In2.Cu")
		(net "M_F_CPU0_SB_DQ<9>")
	)
	(segment
		(start 416.536378 -222.198946)
		(end 416.184334 -222.198946)
		(width 0.18288)
		(layer "In2.Cu")
		(net "M_F_CPU0_SB_DQ<9>")
	)
	(segment
		(start 416.804094 -220.620844)
		(end 416.804094 -221.93123)
		(width 0.18288)
		(layer "In2.Cu")
		(net "M_F_CPU0_SB_DQ<9>")
	)
	(segment
		(start 409.044648 -220.727778)
		(end 408.851608 -220.534738)
		(width 0.18288)
		(layer "In2.Cu")
		(net "M_F_CPU0_SB_DQ<9>")
	)
	(segment
		(start 418.688012 -221.592902)
		(end 417.981384 -221.592902)
		(width 0.18288)
		(layer "In2.Cu")
		(net "M_F_CPU0_SB_DQ<9>")
	)
	(segment
		(start 410.529532 -221.545912)
		(end 409.38958 -221.545912)
		(width 0.18288)
		(layer "In2.Cu")
		(net "M_F_CPU0_SB_DQ<9>")
	)
	(segment
		(start 416.804094 -221.93123)
		(end 416.536378 -222.198946)
		(width 0.18288)
		(layer "In2.Cu")
		(net "M_F_CPU0_SB_DQ<9>")
	)
	(segment
		(start 405.405336 -220.713808)
		(end 404.083012 -222.036132)
		(width 0.18288)
		(layer "In2.Cu")
		(net "M_F_CPU0_SB_DQ<9>")
	)
	(segment
		(start 417.788344 -220.934026)
		(end 417.282122 -220.427804)
		(width 0.18288)
		(layer "In2.Cu")
		(net "M_F_CPU0_SB_DQ<9>")
	)
	(segment
		(start 419.940994 -220.888814)
		(end 419.732206 -220.680026)
		(width 0.18288)
		(layer "In2.Cu")
		(net "M_F_CPU0_SB_DQ<9>")
	)
	(segment
		(start 406.86609 -220.461332)
		(end 406.467818 -220.461332)
		(width 0.18288)
		(layer "In2.Cu")
		(net "M_F_CPU0_SB_DQ<9>")
	)
	(segment
		(start 416.184334 -222.198946)
		(end 415.991294 -222.005906)
		(width 0.18288)
		(layer "In2.Cu")
		(net "M_F_CPU0_SB_DQ<9>")
	)
	(segment
		(start 419.011862 -220.680026)
		(end 418.851842 -220.840046)
		(width 0.18288)
		(layer "In2.Cu")
		(net "M_F_CPU0_SB_DQ<9>")
	)
	(segment
		(start 385.707636 -230.57612)
		(end 385.698746 -230.5812)
		(width 0.088646)
		(layer "In2.Cu")
		(net "M_F_CPU0_SB_DQ<9>")
	)
	(segment
		(start 420.466774 -221.61627)
		(end 420.134034 -221.61627)
		(width 0.18288)
		(layer "In2.Cu")
		(net "M_F_CPU0_SB_DQ<9>")
	)
	(segment
		(start 419.732206 -220.680026)
		(end 419.011862 -220.680026)
		(width 0.18288)
		(layer "In2.Cu")
		(net "M_F_CPU0_SB_DQ<9>")
	)
	(segment
		(start 415.365692 -221.280228)
		(end 414.749488 -221.896432)
		(width 0.18288)
		(layer "In2.Cu")
		(net "M_F_CPU0_SB_DQ<9>")
	)
	(segment
		(start 389.18642 -229.81412)
		(end 388.474966 -230.525574)
		(width 0.088646)
		(layer "In2.Cu")
		(net "M_F_CPU0_SB_DQ<9>")
	)
	(segment
		(start 416.997134 -220.427804)
		(end 416.804094 -220.620844)
		(width 0.18288)
		(layer "In2.Cu")
		(net "M_F_CPU0_SB_DQ<9>")
	)
	(segment
		(start 409.044648 -221.20098)
		(end 409.044648 -220.727778)
		(width 0.18288)
		(layer "In2.Cu")
		(net "M_F_CPU0_SB_DQ<9>")
	)
	(arc
		(start 387.021832 -230.57612)
		(mid 386.834634 -230.525977)
		(end 386.647436 -230.57612)
		(width 0.088646)
		(layer "In2.Cu")
		(net "M_F_CPU0_SB_DQ<9>")
	)
	(arc
		(start 382.792732 -231.39019)
		(mid 382.605534 -231.340047)
		(end 382.418336 -231.39019)
		(width 0.088646)
		(layer "In2.Cu")
		(net "M_F_CPU0_SB_DQ<9>")
	)
	(arc
		(start 386.082032 -230.57612)
		(mid 385.894834 -230.525977)
		(end 385.707636 -230.57612)
		(width 0.088646)
		(layer "In2.Cu")
		(net "M_F_CPU0_SB_DQ<9>")
	)
	(arc
		(start 387.774434 -230.525574)
		(mid 387.677506 -230.538525)
		(end 387.587236 -230.57612)
		(width 0.088646)
		(layer "In2.Cu")
		(net "M_F_CPU0_SB_DQ<9>")
	)
	(arc
		(start 385.698746 -230.5812)
		(mid 385.567832 -230.71756)
		(end 385.520184 -230.900478)
		(width 0.088646)
		(layer "In2.Cu")
		(net "M_F_CPU0_SB_DQ<9>")
	)
	(arc
		(start 383.732532 -231.39019)
		(mid 383.545334 -231.340047)
		(end 383.358136 -231.39019)
		(width 0.088646)
		(layer "In2.Cu")
		(net "M_F_CPU0_SB_DQ<9>")
	)
	(arc
		(start 385.520184 -230.91902)
		(mid 385.440022 -231.191209)
		(end 385.237736 -231.39019)
		(width 0.088646)
		(layer "In2.Cu")
		(net "M_F_CPU0_SB_DQ<9>")
	)
	(arc
		(start 383.358136 -231.39019)
		(mid 383.083907 -231.466115)
		(end 382.807464 -231.398826)
		(width 0.088646)
		(layer "In2.Cu")
		(net "M_F_CPU0_SB_DQ<9>")
	)
	(arc
		(start 382.418336 -231.39019)
		(mid 382.135634 -231.465932)
		(end 381.852932 -231.39019)
		(width 0.088646)
		(layer "In2.Cu")
		(net "M_F_CPU0_SB_DQ<9>")
	)
	(arc
		(start 384.297936 -231.39019)
		(mid 384.015234 -231.465932)
		(end 383.732532 -231.39019)
		(width 0.088646)
		(layer "In2.Cu")
		(net "M_F_CPU0_SB_DQ<9>")
	)
	(arc
		(start 386.647436 -230.57612)
		(mid 386.364734 -230.651896)
		(end 386.082032 -230.57612)
		(width 0.088646)
		(layer "In2.Cu")
		(net "M_F_CPU0_SB_DQ<9>")
	)
	(arc
		(start 385.237736 -231.39019)
		(mid 384.955034 -231.465932)
		(end 384.672332 -231.39019)
		(width 0.088646)
		(layer "In2.Cu")
		(net "M_F_CPU0_SB_DQ<9>")
	)
	(arc
		(start 384.672332 -231.39019)
		(mid 384.485134 -231.340047)
		(end 384.297936 -231.39019)
		(width 0.088646)
		(layer "In2.Cu")
		(net "M_F_CPU0_SB_DQ<9>")
	)
	(arc
		(start 387.587236 -230.57612)
		(mid 387.304534 -230.651896)
		(end 387.021832 -230.57612)
		(width 0.088646)
		(layer "In2.Cu")
		(net "M_F_CPU0_SB_DQ<9>")
	)
	(segment
		(start 427.36135 -222.385382)
		(end 426.951394 -222.385382)
		(width 0.20066)
		(layer "F.Cu")
		(net "M_F_CPU0_SB_DQ<8>")
	)
	(segment
		(start 424.73626 -222.391732)
		(end 424.391582 -222.391732)
		(width 0.20066)
		(layer "F.Cu")
		(net "M_F_CPU0_SB_DQ<8>")
	)
	(segment
		(start 426.951394 -222.385382)
		(end 426.945044 -222.391732)
		(width 0.1016)
		(layer "F.Cu")
		(net "M_F_CPU0_SB_DQ<8>")
	)
	(segment
		(start 427.792896 -222.816928)
		(end 427.36135 -222.385382)
		(width 0.20066)
		(layer "F.Cu")
		(net "M_F_CPU0_SB_DQ<8>")
	)
	(segment
		(start 424.085512 -223.06534)
		(end 423.610278 -223.06534)
		(width 0.20066)
		(layer "F.Cu")
		(net "M_F_CPU0_SB_DQ<8>")
	)
	(segment
		(start 421.840914 -222.816674)
		(end 420.736014 -222.816674)
		(width 0.20066)
		(layer "F.Cu")
		(net "M_F_CPU0_SB_DQ<8>")
	)
	(segment
		(start 423.610278 -223.06534)
		(end 423.361612 -222.816674)
		(width 0.20066)
		(layer "F.Cu")
		(net "M_F_CPU0_SB_DQ<8>")
	)
	(segment
		(start 424.78325 -222.391732)
		(end 424.73626 -222.391732)
		(width 0.101854)
		(layer "F.Cu")
		(net "M_F_CPU0_SB_DQ<8>")
	)
	(segment
		(start 429.38446 -222.816928)
		(end 427.792896 -222.816928)
		(width 0.20066)
		(layer "F.Cu")
		(net "M_F_CPU0_SB_DQ<8>")
	)
	(segment
		(start 426.945044 -222.391732)
		(end 424.78325 -222.391732)
		(width 0.1016)
		(layer "F.Cu")
		(net "M_F_CPU0_SB_DQ<8>")
	)
	(segment
		(start 423.361612 -222.816674)
		(end 421.840914 -222.816674)
		(width 0.20066)
		(layer "F.Cu")
		(net "M_F_CPU0_SB_DQ<8>")
	)
	(segment
		(start 424.273472 -222.87738)
		(end 424.085512 -223.06534)
		(width 0.20066)
		(layer "F.Cu")
		(net "M_F_CPU0_SB_DQ<8>")
	)
	(segment
		(start 381.665734 -232.250488)
		(end 381.665734 -231.714548)
		(width 0.20066)
		(layer "F.Cu")
		(net "M_F_CPU0_SB_DQ<8>")
	)
	(segment
		(start 424.273472 -222.509842)
		(end 424.273472 -222.87738)
		(width 0.20066)
		(layer "F.Cu")
		(net "M_F_CPU0_SB_DQ<8>")
	)
	(segment
		(start 424.391582 -222.391732)
		(end 424.273472 -222.509842)
		(width 0.20066)
		(layer "F.Cu")
		(net "M_F_CPU0_SB_DQ<8>")
	)
	(segment
		(start 429.384714 -222.816674)
		(end 429.38446 -222.816928)
		(width 0.20066)
		(layer "F.Cu")
		(net "M_F_CPU0_SB_DQ<8>")
	)
	(segment
		(start 414.687512 -224.110296)
		(end 414.106868 -224.110296)
		(width 0.18288)
		(layer "In2.Cu")
		(net "M_F_CPU0_SB_DQ<8>")
	)
	(segment
		(start 388.86384 -230.841296)
		(end 388.70001 -231.005126)
		(width 0.088646)
		(layer "In2.Cu")
		(net "M_F_CPU0_SB_DQ<8>")
	)
	(segment
		(start 382.230122 -232.137204)
		(end 381.665734 -231.714548)
		(width 0.088646)
		(layer "In2.Cu")
		(net "M_F_CPU0_SB_DQ<8>")
	)
	(segment
		(start 417.413694 -223.898206)
		(end 417.413694 -223.492314)
		(width 0.18288)
		(layer "In2.Cu")
		(net "M_F_CPU0_SB_DQ<8>")
	)
	(segment
		(start 418.831014 -224.787714)
		(end 418.670994 -224.947734)
		(width 0.18288)
		(layer "In2.Cu")
		(net "M_F_CPU0_SB_DQ<8>")
	)
	(segment
		(start 416.655758 -223.433386)
		(end 416.655758 -224.854262)
		(width 0.18288)
		(layer "In2.Cu")
		(net "M_F_CPU0_SB_DQ<8>")
	)
	(segment
		(start 405.814276 -222.445072)
		(end 405.207216 -223.052132)
		(width 0.18288)
		(layer "In2.Cu")
		(net "M_F_CPU0_SB_DQ<8>")
	)
	(segment
		(start 417.573714 -224.058226)
		(end 417.413694 -223.898206)
		(width 0.18288)
		(layer "In2.Cu")
		(net "M_F_CPU0_SB_DQ<8>")
	)
	(segment
		(start 387.590538 -231.33939)
		(end 387.304534 -231.33939)
		(width 0.088646)
		(layer "In2.Cu")
		(net "M_F_CPU0_SB_DQ<8>")
	)
	(segment
		(start 405.207216 -223.052132)
		(end 402.815044 -223.052132)
		(width 0.18288)
		(layer "In2.Cu")
		(net "M_F_CPU0_SB_DQ<8>")
	)
	(segment
		(start 387.924802 -231.005126)
		(end 387.590538 -231.33939)
		(width 0.088646)
		(layer "In2.Cu")
		(net "M_F_CPU0_SB_DQ<8>")
	)
	(segment
		(start 412.62935 -222.912432)
		(end 412.276544 -223.265238)
		(width 0.18288)
		(layer "In2.Cu")
		(net "M_F_CPU0_SB_DQ<8>")
	)
	(segment
		(start 416.762946 -223.326198)
		(end 416.655758 -223.433386)
		(width 0.18288)
		(layer "In2.Cu")
		(net "M_F_CPU0_SB_DQ<8>")
	)
	(segment
		(start 420.065708 -224.065592)
		(end 418.991034 -224.065592)
		(width 0.18288)
		(layer "In2.Cu")
		(net "M_F_CPU0_SB_DQ<8>")
	)
	(segment
		(start 408.64028 -222.445072)
		(end 405.814276 -222.445072)
		(width 0.18288)
		(layer "In2.Cu")
		(net "M_F_CPU0_SB_DQ<8>")
	)
	(segment
		(start 416.655758 -224.854262)
		(end 416.48634 -225.02368)
		(width 0.18288)
		(layer "In2.Cu")
		(net "M_F_CPU0_SB_DQ<8>")
	)
	(segment
		(start 415.717736 -223.23171)
		(end 415.130996 -223.23171)
		(width 0.18288)
		(layer "In2.Cu")
		(net "M_F_CPU0_SB_DQ<8>")
	)
	(segment
		(start 412.276544 -223.265238)
		(end 410.562806 -223.265238)
		(width 0.18288)
		(layer "In2.Cu")
		(net "M_F_CPU0_SB_DQ<8>")
	)
	(segment
		(start 418.831014 -224.225612)
		(end 418.831014 -224.787714)
		(width 0.18288)
		(layer "In2.Cu")
		(net "M_F_CPU0_SB_DQ<8>")
	)
	(segment
		(start 410.53766 -223.240092)
		(end 409.804108 -223.240092)
		(width 0.18288)
		(layer "In2.Cu")
		(net "M_F_CPU0_SB_DQ<8>")
	)
	(segment
		(start 417.413694 -223.492314)
		(end 417.247578 -223.326198)
		(width 0.18288)
		(layer "In2.Cu")
		(net "M_F_CPU0_SB_DQ<8>")
	)
	(segment
		(start 418.108892 -224.218246)
		(end 417.948872 -224.058226)
		(width 0.18288)
		(layer "In2.Cu")
		(net "M_F_CPU0_SB_DQ<8>")
	)
	(segment
		(start 414.106868 -224.110296)
		(end 413.89808 -223.901508)
		(width 0.18288)
		(layer "In2.Cu")
		(net "M_F_CPU0_SB_DQ<8>")
	)
	(segment
		(start 418.991034 -224.065592)
		(end 418.831014 -224.225612)
		(width 0.18288)
		(layer "In2.Cu")
		(net "M_F_CPU0_SB_DQ<8>")
	)
	(segment
		(start 385.990084 -231.714548)
		(end 385.990084 -231.724454)
		(width 0.088646)
		(layer "In2.Cu")
		(net "M_F_CPU0_SB_DQ<8>")
	)
	(segment
		(start 413.89808 -223.68891)
		(end 413.121602 -222.912432)
		(width 0.18288)
		(layer "In2.Cu")
		(net "M_F_CPU0_SB_DQ<8>")
	)
	(segment
		(start 414.880806 -223.917002)
		(end 414.687512 -224.110296)
		(width 0.18288)
		(layer "In2.Cu")
		(net "M_F_CPU0_SB_DQ<8>")
	)
	(segment
		(start 415.912046 -223.42602)
		(end 415.717736 -223.23171)
		(width 0.18288)
		(layer "In2.Cu")
		(net "M_F_CPU0_SB_DQ<8>")
	)
	(segment
		(start 417.247578 -223.326198)
		(end 416.762946 -223.326198)
		(width 0.18288)
		(layer "In2.Cu")
		(net "M_F_CPU0_SB_DQ<8>")
	)
	(segment
		(start 413.121602 -222.912432)
		(end 412.62935 -222.912432)
		(width 0.18288)
		(layer "In2.Cu")
		(net "M_F_CPU0_SB_DQ<8>")
	)
	(segment
		(start 395.02588 -230.841296)
		(end 389.61949 -230.841296)
		(width 0.18288)
		(layer "In2.Cu")
		(net "M_F_CPU0_SB_DQ<8>")
	)
	(segment
		(start 409.803346 -223.240854)
		(end 409.436062 -223.240854)
		(width 0.18288)
		(layer "In2.Cu")
		(net "M_F_CPU0_SB_DQ<8>")
	)
	(segment
		(start 415.130996 -223.23171)
		(end 414.880806 -223.4819)
		(width 0.18288)
		(layer "In2.Cu")
		(net "M_F_CPU0_SB_DQ<8>")
	)
	(segment
		(start 409.436062 -223.240854)
		(end 408.64028 -222.445072)
		(width 0.18288)
		(layer "In2.Cu")
		(net "M_F_CPU0_SB_DQ<8>")
	)
	(segment
		(start 420.736014 -222.816674)
		(end 420.734744 -222.816674)
		(width 0.18288)
		(layer "In2.Cu")
		(net "M_F_CPU0_SB_DQ<8>")
	)
	(segment
		(start 388.70001 -231.005126)
		(end 387.924802 -231.005126)
		(width 0.088646)
		(layer "In2.Cu")
		(net "M_F_CPU0_SB_DQ<8>")
	)
	(segment
		(start 410.562806 -223.265238)
		(end 410.53766 -223.240092)
		(width 0.18288)
		(layer "In2.Cu")
		(net "M_F_CPU0_SB_DQ<8>")
	)
	(segment
		(start 402.815044 -223.052132)
		(end 395.02588 -230.841296)
		(width 0.18288)
		(layer "In2.Cu")
		(net "M_F_CPU0_SB_DQ<8>")
	)
	(segment
		(start 418.670994 -224.947734)
		(end 418.268912 -224.947734)
		(width 0.18288)
		(layer "In2.Cu")
		(net "M_F_CPU0_SB_DQ<8>")
	)
	(segment
		(start 420.233094 -223.898206)
		(end 420.065708 -224.065592)
		(width 0.18288)
		(layer "In2.Cu")
		(net "M_F_CPU0_SB_DQ<8>")
	)
	(segment
		(start 414.880806 -223.4819)
		(end 414.880806 -223.917002)
		(width 0.18288)
		(layer "In2.Cu")
		(net "M_F_CPU0_SB_DQ<8>")
	)
	(segment
		(start 416.172396 -225.02368)
		(end 415.912046 -224.76333)
		(width 0.18288)
		(layer "In2.Cu")
		(net "M_F_CPU0_SB_DQ<8>")
	)
	(segment
		(start 418.108892 -224.787714)
		(end 418.108892 -224.218246)
		(width 0.18288)
		(layer "In2.Cu")
		(net "M_F_CPU0_SB_DQ<8>")
	)
	(segment
		(start 389.61949 -230.841296)
		(end 388.86384 -230.841296)
		(width 0.088646)
		(layer "In2.Cu")
		(net "M_F_CPU0_SB_DQ<8>")
	)
	(segment
		(start 409.804108 -223.240092)
		(end 409.803346 -223.240854)
		(width 0.18288)
		(layer "In2.Cu")
		(net "M_F_CPU0_SB_DQ<8>")
	)
	(segment
		(start 420.233094 -223.318324)
		(end 420.233094 -223.898206)
		(width 0.18288)
		(layer "In2.Cu")
		(net "M_F_CPU0_SB_DQ<8>")
	)
	(segment
		(start 417.948872 -224.058226)
		(end 417.573714 -224.058226)
		(width 0.18288)
		(layer "In2.Cu")
		(net "M_F_CPU0_SB_DQ<8>")
	)
	(segment
		(start 418.268912 -224.947734)
		(end 418.108892 -224.787714)
		(width 0.18288)
		(layer "In2.Cu")
		(net "M_F_CPU0_SB_DQ<8>")
	)
	(segment
		(start 416.48634 -225.02368)
		(end 416.172396 -225.02368)
		(width 0.18288)
		(layer "In2.Cu")
		(net "M_F_CPU0_SB_DQ<8>")
	)
	(segment
		(start 420.734744 -222.816674)
		(end 420.233094 -223.318324)
		(width 0.18288)
		(layer "In2.Cu")
		(net "M_F_CPU0_SB_DQ<8>")
	)
	(segment
		(start 386.177536 -231.39019)
		(end 386.168646 -231.39527)
		(width 0.088646)
		(layer "In2.Cu")
		(net "M_F_CPU0_SB_DQ<8>")
	)
	(segment
		(start 415.912046 -224.76333)
		(end 415.912046 -223.42602)
		(width 0.18288)
		(layer "In2.Cu")
		(net "M_F_CPU0_SB_DQ<8>")
	)
	(segment
		(start 413.89808 -223.901508)
		(end 413.89808 -223.68891)
		(width 0.18288)
		(layer "In2.Cu")
		(net "M_F_CPU0_SB_DQ<8>")
	)
	(arc
		(start 385.990084 -231.724454)
		(mid 385.911973 -232.001403)
		(end 385.707636 -232.204006)
		(width 0.088646)
		(layer "In2.Cu")
		(net "M_F_CPU0_SB_DQ<8>")
	)
	(arc
		(start 387.117336 -231.39019)
		(mid 386.834634 -231.465932)
		(end 386.551932 -231.39019)
		(width 0.088646)
		(layer "In2.Cu")
		(net "M_F_CPU0_SB_DQ<8>")
	)
	(arc
		(start 385.142232 -232.204006)
		(mid 384.955034 -232.153863)
		(end 384.767836 -232.204006)
		(width 0.088646)
		(layer "In2.Cu")
		(net "M_F_CPU0_SB_DQ<8>")
	)
	(arc
		(start 385.707636 -232.204006)
		(mid 385.424934 -232.279782)
		(end 385.142232 -232.204006)
		(width 0.088646)
		(layer "In2.Cu")
		(net "M_F_CPU0_SB_DQ<8>")
	)
	(arc
		(start 386.551932 -231.39019)
		(mid 386.364734 -231.340047)
		(end 386.177536 -231.39019)
		(width 0.088646)
		(layer "In2.Cu")
		(net "M_F_CPU0_SB_DQ<8>")
	)
	(arc
		(start 387.304534 -231.33939)
		(mid 387.207595 -231.35248)
		(end 387.117336 -231.39019)
		(width 0.088646)
		(layer "In2.Cu")
		(net "M_F_CPU0_SB_DQ<8>")
	)
	(arc
		(start 386.168646 -231.39527)
		(mid 386.037732 -231.53163)
		(end 385.990084 -231.714548)
		(width 0.088646)
		(layer "In2.Cu")
		(net "M_F_CPU0_SB_DQ<8>")
	)
	(arc
		(start 384.202432 -232.204006)
		(mid 384.015234 -232.153863)
		(end 383.828036 -232.204006)
		(width 0.088646)
		(layer "In2.Cu")
		(net "M_F_CPU0_SB_DQ<8>")
	)
	(arc
		(start 383.828036 -232.204006)
		(mid 383.545334 -232.279782)
		(end 383.262632 -232.204006)
		(width 0.088646)
		(layer "In2.Cu")
		(net "M_F_CPU0_SB_DQ<8>")
	)
	(arc
		(start 383.262632 -232.204006)
		(mid 383.075434 -232.153863)
		(end 382.888236 -232.204006)
		(width 0.088646)
		(layer "In2.Cu")
		(net "M_F_CPU0_SB_DQ<8>")
	)
	(arc
		(start 384.767836 -232.204006)
		(mid 384.485134 -232.279782)
		(end 384.202432 -232.204006)
		(width 0.088646)
		(layer "In2.Cu")
		(net "M_F_CPU0_SB_DQ<8>")
	)
	(arc
		(start 382.888236 -232.204006)
		(mid 382.605534 -232.279782)
		(end 382.322832 -232.204006)
		(width 0.088646)
		(layer "In2.Cu")
		(net "M_F_CPU0_SB_DQ<8>")
	)
	(arc
		(start 382.322832 -232.204006)
		(mid 382.274785 -232.172953)
		(end 382.230122 -232.137204)
		(width 0.088646)
		(layer "In2.Cu")
		(net "M_F_CPU0_SB_DQ<8>")
	)
	(segment
		(start 427.639226 -223.666558)
		(end 428.07128 -224.098612)
		(width 0.20066)
		(layer "F.Cu")
		(net "M_F_CPU0_SB_DQ<7>")
	)
	(segment
		(start 431.280316 -223.648778)
		(end 431.514504 -223.41459)
		(width 0.20066)
		(layer "F.Cu")
		(net "M_F_CPU0_SB_DQ<7>")
	)
	(segment
		(start 425.940982 -223.666558)
		(end 427.639226 -223.666558)
		(width 0.20066)
		(layer "F.Cu")
		(net "M_F_CPU0_SB_DQ<7>")
	)
	(segment
		(start 379.31598 -236.319822)
		(end 379.316234 -236.319568)
		(width 0.20066)
		(layer "F.Cu")
		(net "M_F_CPU0_SB_DQ<7>")
	)
	(segment
		(start 430.382934 -224.0915)
		(end 430.395126 -224.103692)
		(width 0.1016)
		(layer "F.Cu")
		(net "M_F_CPU0_SB_DQ<7>")
	)
	(segment
		(start 430.395126 -224.103692)
		(end 431.076354 -224.103692)
		(width 0.20066)
		(layer "F.Cu")
		(net "M_F_CPU0_SB_DQ<7>")
	)
	(segment
		(start 432.15052 -223.666558)
		(end 433.484782 -223.666558)
		(width 0.20066)
		(layer "F.Cu")
		(net "M_F_CPU0_SB_DQ<7>")
	)
	(segment
		(start 428.07128 -224.098612)
		(end 428.363126 -224.098612)
		(width 0.20066)
		(layer "F.Cu")
		(net "M_F_CPU0_SB_DQ<7>")
	)
	(segment
		(start 424.836082 -223.666558)
		(end 425.940982 -223.666558)
		(width 0.20066)
		(layer "F.Cu")
		(net "M_F_CPU0_SB_DQ<7>")
	)
	(segment
		(start 379.316234 -236.319568)
		(end 379.316234 -235.783882)
		(width 0.20066)
		(layer "F.Cu")
		(net "M_F_CPU0_SB_DQ<7>")
	)
	(segment
		(start 431.280316 -223.89973)
		(end 431.280316 -223.648778)
		(width 0.20066)
		(layer "F.Cu")
		(net "M_F_CPU0_SB_DQ<7>")
	)
	(segment
		(start 431.898552 -223.41459)
		(end 432.15052 -223.666558)
		(width 0.20066)
		(layer "F.Cu")
		(net "M_F_CPU0_SB_DQ<7>")
	)
	(segment
		(start 431.514504 -223.41459)
		(end 431.898552 -223.41459)
		(width 0.20066)
		(layer "F.Cu")
		(net "M_F_CPU0_SB_DQ<7>")
	)
	(segment
		(start 428.363126 -224.098612)
		(end 428.367952 -224.098612)
		(width 0.101854)
		(layer "F.Cu")
		(net "M_F_CPU0_SB_DQ<7>")
	)
	(segment
		(start 428.367952 -224.098612)
		(end 428.375064 -224.0915)
		(width 0.1016)
		(layer "F.Cu")
		(net "M_F_CPU0_SB_DQ<7>")
	)
	(segment
		(start 431.076354 -224.103692)
		(end 431.280316 -223.89973)
		(width 0.20066)
		(layer "F.Cu")
		(net "M_F_CPU0_SB_DQ<7>")
	)
	(segment
		(start 428.375064 -224.0915)
		(end 430.382934 -224.0915)
		(width 0.1016)
		(layer "F.Cu")
		(net "M_F_CPU0_SB_DQ<7>")
	)
	(segment
		(start 422.272714 -223.058736)
		(end 422.272714 -222.745554)
		(width 0.18288)
		(layer "In4.Cu")
		(net "M_F_CPU0_SB_DQ<7>")
	)
	(segment
		(start 420.055294 -222.719138)
		(end 418.028628 -220.692472)
		(width 0.18288)
		(layer "In4.Cu")
		(net "M_F_CPU0_SB_DQ<7>")
	)
	(segment
		(start 404.212298 -220.692472)
		(end 394.167106 -230.737664)
		(width 0.18288)
		(layer "In4.Cu")
		(net "M_F_CPU0_SB_DQ<7>")
	)
	(segment
		(start 424.836082 -223.666558)
		(end 423.591228 -223.241616)
		(width 0.18288)
		(layer "In4.Cu")
		(net "M_F_CPU0_SB_DQ<7>")
	)
	(segment
		(start 421.579294 -223.058736)
		(end 421.396414 -223.241616)
		(width 0.18288)
		(layer "In4.Cu")
		(net "M_F_CPU0_SB_DQ<7>")
	)
	(segment
		(start 387.679184 -233.332274)
		(end 387.679184 -233.34218)
		(width 0.088646)
		(layer "In4.Cu")
		(net "M_F_CPU0_SB_DQ<7>")
	)
	(segment
		(start 420.475918 -223.241616)
		(end 420.055294 -222.820992)
		(width 0.18288)
		(layer "In4.Cu")
		(net "M_F_CPU0_SB_DQ<7>")
	)
	(segment
		(start 423.591228 -223.241616)
		(end 422.455594 -223.241616)
		(width 0.18288)
		(layer "In4.Cu")
		(net "M_F_CPU0_SB_DQ<7>")
	)
	(segment
		(start 388.975092 -232.658158)
		(end 388.433564 -232.658158)
		(width 0.18288)
		(layer "In4.Cu")
		(net "M_F_CPU0_SB_DQ<7>")
	)
	(segment
		(start 387.030722 -234.475528)
		(end 387.021832 -234.480608)
		(width 0.088646)
		(layer "In4.Cu")
		(net "M_F_CPU0_SB_DQ<7>")
	)
	(segment
		(start 388.108444 -232.724198)
		(end 388.039356 -232.793286)
		(width 0.088646)
		(layer "In4.Cu")
		(net "M_F_CPU0_SB_DQ<7>")
	)
	(segment
		(start 420.055294 -222.820992)
		(end 420.055294 -222.719138)
		(width 0.18288)
		(layer "In4.Cu")
		(net "M_F_CPU0_SB_DQ<7>")
	)
	(segment
		(start 418.028628 -220.692472)
		(end 404.212298 -220.692472)
		(width 0.18288)
		(layer "In4.Cu")
		(net "M_F_CPU0_SB_DQ<7>")
	)
	(segment
		(start 382.792732 -235.294424)
		(end 382.788922 -235.29671)
		(width 0.088646)
		(layer "In4.Cu")
		(net "M_F_CPU0_SB_DQ<7>")
	)
	(segment
		(start 388.17423 -232.658158)
		(end 388.108444 -232.724198)
		(width 0.088646)
		(layer "In4.Cu")
		(net "M_F_CPU0_SB_DQ<7>")
	)
	(segment
		(start 422.455594 -223.241616)
		(end 422.272714 -223.058736)
		(width 0.18288)
		(layer "In4.Cu")
		(net "M_F_CPU0_SB_DQ<7>")
	)
	(segment
		(start 421.762174 -222.562674)
		(end 421.579294 -222.745554)
		(width 0.18288)
		(layer "In4.Cu")
		(net "M_F_CPU0_SB_DQ<7>")
	)
	(segment
		(start 422.089834 -222.562674)
		(end 421.762174 -222.562674)
		(width 0.18288)
		(layer "In4.Cu")
		(net "M_F_CPU0_SB_DQ<7>")
	)
	(segment
		(start 388.433564 -232.658158)
		(end 388.17423 -232.658158)
		(width 0.088646)
		(layer "In4.Cu")
		(net "M_F_CPU0_SB_DQ<7>")
	)
	(segment
		(start 379.979174 -235.291122)
		(end 379.973332 -235.294424)
		(width 0.088646)
		(layer "In4.Cu")
		(net "M_F_CPU0_SB_DQ<7>")
	)
	(segment
		(start 386.177282 -235.294424)
		(end 386.16255 -235.285788)
		(width 0.088646)
		(layer "In4.Cu")
		(net "M_F_CPU0_SB_DQ<7>")
	)
	(segment
		(start 421.396414 -223.241616)
		(end 420.475918 -223.241616)
		(width 0.18288)
		(layer "In4.Cu")
		(net "M_F_CPU0_SB_DQ<7>")
	)
	(segment
		(start 380.918974 -235.291122)
		(end 380.90729 -235.297726)
		(width 0.088646)
		(layer "In4.Cu")
		(net "M_F_CPU0_SB_DQ<7>")
	)
	(segment
		(start 381.852932 -235.294424)
		(end 381.848614 -235.296964)
		(width 0.088646)
		(layer "In4.Cu")
		(net "M_F_CPU0_SB_DQ<7>")
	)
	(segment
		(start 421.579294 -222.745554)
		(end 421.579294 -223.058736)
		(width 0.18288)
		(layer "In4.Cu")
		(net "M_F_CPU0_SB_DQ<7>")
	)
	(segment
		(start 379.316234 -235.783628)
		(end 379.316234 -235.783882)
		(width 0.088646)
		(layer "In4.Cu")
		(net "M_F_CPU0_SB_DQ<7>")
	)
	(segment
		(start 387.209284 -234.137708)
		(end 387.209284 -234.15625)
		(width 0.088646)
		(layer "In4.Cu")
		(net "M_F_CPU0_SB_DQ<7>")
	)
	(segment
		(start 382.798574 -235.291122)
		(end 382.792732 -235.294424)
		(width 0.088646)
		(layer "In4.Cu")
		(net "M_F_CPU0_SB_DQ<7>")
	)
	(segment
		(start 422.272714 -222.745554)
		(end 422.089834 -222.562674)
		(width 0.18288)
		(layer "In4.Cu")
		(net "M_F_CPU0_SB_DQ<7>")
	)
	(segment
		(start 379.973332 -235.294424)
		(end 379.868938 -235.355892)
		(width 0.088646)
		(layer "In4.Cu")
		(net "M_F_CPU0_SB_DQ<7>")
	)
	(segment
		(start 387.021832 -234.480608)
		(end 387.015736 -234.484164)
		(width 0.088646)
		(layer "In4.Cu")
		(net "M_F_CPU0_SB_DQ<7>")
	)
	(segment
		(start 387.500622 -233.661458)
		(end 387.491732 -233.666538)
		(width 0.088646)
		(layer "In4.Cu")
		(net "M_F_CPU0_SB_DQ<7>")
	)
	(segment
		(start 383.732532 -235.294424)
		(end 383.728214 -235.296964)
		(width 0.088646)
		(layer "In4.Cu")
		(net "M_F_CPU0_SB_DQ<7>")
	)
	(segment
		(start 394.167106 -230.737664)
		(end 390.895586 -230.737664)
		(width 0.18288)
		(layer "In4.Cu")
		(net "M_F_CPU0_SB_DQ<7>")
	)
	(segment
		(start 390.895586 -230.737664)
		(end 388.975092 -232.658158)
		(width 0.18288)
		(layer "In4.Cu")
		(net "M_F_CPU0_SB_DQ<7>")
	)
	(segment
		(start 386.560568 -235.289344)
		(end 386.551678 -235.294424)
		(width 0.088646)
		(layer "In4.Cu")
		(net "M_F_CPU0_SB_DQ<7>")
	)
	(segment
		(start 385.237482 -235.294424)
		(end 385.22275 -235.285788)
		(width 0.088646)
		(layer "In4.Cu")
		(net "M_F_CPU0_SB_DQ<7>")
	)
	(arc
		(start 387.491732 -233.666538)
		(mid 387.289446 -233.865519)
		(end 387.209284 -234.137708)
		(width 0.088646)
		(layer "In4.Cu")
		(net "M_F_CPU0_SB_DQ<7>")
	)
	(arc
		(start 388.039356 -232.793286)
		(mid 388.002446 -232.825557)
		(end 387.961632 -232.852722)
		(width 0.088646)
		(layer "In4.Cu")
		(net "M_F_CPU0_SB_DQ<7>")
	)
	(arc
		(start 385.611878 -235.294424)
		(mid 385.42468 -235.344567)
		(end 385.237482 -235.294424)
		(width 0.088646)
		(layer "In4.Cu")
		(net "M_F_CPU0_SB_DQ<7>")
	)
	(arc
		(start 386.16255 -235.285788)
		(mid 385.886075 -235.218468)
		(end 385.611878 -235.294424)
		(width 0.088646)
		(layer "In4.Cu")
		(net "M_F_CPU0_SB_DQ<7>")
	)
	(arc
		(start 382.788922 -235.29671)
		(mid 382.603203 -235.344662)
		(end 382.418082 -235.294424)
		(width 0.088646)
		(layer "In4.Cu")
		(net "M_F_CPU0_SB_DQ<7>")
	)
	(arc
		(start 383.728214 -235.296964)
		(mid 383.542719 -235.344633)
		(end 383.357882 -235.294424)
		(width 0.088646)
		(layer "In4.Cu")
		(net "M_F_CPU0_SB_DQ<7>")
	)
	(arc
		(start 382.418082 -235.294424)
		(mid 382.135524 -235.218775)
		(end 381.852932 -235.294424)
		(width 0.088646)
		(layer "In4.Cu")
		(net "M_F_CPU0_SB_DQ<7>")
	)
	(arc
		(start 386.73913 -234.970066)
		(mid 386.691451 -235.152966)
		(end 386.560568 -235.289344)
		(width 0.088646)
		(layer "In4.Cu")
		(net "M_F_CPU0_SB_DQ<7>")
	)
	(arc
		(start 383.357882 -235.294424)
		(mid 383.078679 -235.218784)
		(end 382.798574 -235.291122)
		(width 0.088646)
		(layer "In4.Cu")
		(net "M_F_CPU0_SB_DQ<7>")
	)
	(arc
		(start 387.209284 -234.15625)
		(mid 387.161605 -234.33915)
		(end 387.030722 -234.475528)
		(width 0.088646)
		(layer "In4.Cu")
		(net "M_F_CPU0_SB_DQ<7>")
	)
	(arc
		(start 387.679184 -233.34218)
		(mid 387.631505 -233.52508)
		(end 387.500622 -233.661458)
		(width 0.088646)
		(layer "In4.Cu")
		(net "M_F_CPU0_SB_DQ<7>")
	)
	(arc
		(start 386.551678 -235.294424)
		(mid 386.36448 -235.344567)
		(end 386.177282 -235.294424)
		(width 0.088646)
		(layer "In4.Cu")
		(net "M_F_CPU0_SB_DQ<7>")
	)
	(arc
		(start 380.538482 -235.294424)
		(mid 380.259279 -235.218784)
		(end 379.979174 -235.291122)
		(width 0.088646)
		(layer "In4.Cu")
		(net "M_F_CPU0_SB_DQ<7>")
	)
	(arc
		(start 381.478282 -235.294424)
		(mid 381.199079 -235.218784)
		(end 380.918974 -235.291122)
		(width 0.088646)
		(layer "In4.Cu")
		(net "M_F_CPU0_SB_DQ<7>")
	)
	(arc
		(start 387.015736 -234.484164)
		(mid 386.813149 -234.690515)
		(end 386.73913 -234.970066)
		(width 0.088646)
		(layer "In4.Cu")
		(net "M_F_CPU0_SB_DQ<7>")
	)
	(arc
		(start 381.848614 -235.296964)
		(mid 381.663119 -235.344633)
		(end 381.478282 -235.294424)
		(width 0.088646)
		(layer "In4.Cu")
		(net "M_F_CPU0_SB_DQ<7>")
	)
	(arc
		(start 385.22275 -235.285788)
		(mid 384.946275 -235.218468)
		(end 384.672078 -235.294424)
		(width 0.088646)
		(layer "In4.Cu")
		(net "M_F_CPU0_SB_DQ<7>")
	)
	(arc
		(start 380.90729 -235.297726)
		(mid 380.722435 -235.344676)
		(end 380.538482 -235.294424)
		(width 0.088646)
		(layer "In4.Cu")
		(net "M_F_CPU0_SB_DQ<7>")
	)
	(arc
		(start 387.961632 -232.852722)
		(mid 387.757297 -233.055327)
		(end 387.679184 -233.332274)
		(width 0.088646)
		(layer "In4.Cu")
		(net "M_F_CPU0_SB_DQ<7>")
	)
	(arc
		(start 384.672078 -235.294424)
		(mid 384.48488 -235.344567)
		(end 384.297682 -235.294424)
		(width 0.088646)
		(layer "In4.Cu")
		(net "M_F_CPU0_SB_DQ<7>")
	)
	(arc
		(start 384.297682 -235.294424)
		(mid 384.015124 -235.218775)
		(end 383.732532 -235.294424)
		(width 0.088646)
		(layer "In4.Cu")
		(net "M_F_CPU0_SB_DQ<7>")
	)
	(arc
		(start 379.868938 -235.355892)
		(mid 379.579055 -235.552276)
		(end 379.316234 -235.783628)
		(width 0.088646)
		(layer "In4.Cu")
		(net "M_F_CPU0_SB_DQ<7>")
	)
	(segment
		(start 431.076354 -225.803714)
		(end 431.280316 -225.599752)
		(width 0.20066)
		(layer "F.Cu")
		(net "M_F_CPU0_SB_DQ<6>")
	)
	(segment
		(start 428.363126 -225.798634)
		(end 428.367952 -225.798634)
		(width 0.101854)
		(layer "F.Cu")
		(net "M_F_CPU0_SB_DQ<6>")
	)
	(segment
		(start 432.15052 -225.36658)
		(end 433.484782 -225.36658)
		(width 0.20066)
		(layer "F.Cu")
		(net "M_F_CPU0_SB_DQ<6>")
	)
	(segment
		(start 379.786134 -237.133892)
		(end 379.78588 -237.133638)
		(width 0.20066)
		(layer "F.Cu")
		(net "M_F_CPU0_SB_DQ<6>")
	)
	(segment
		(start 428.07128 -225.798634)
		(end 428.363126 -225.798634)
		(width 0.20066)
		(layer "F.Cu")
		(net "M_F_CPU0_SB_DQ<6>")
	)
	(segment
		(start 428.375064 -225.791522)
		(end 430.382934 -225.791522)
		(width 0.1016)
		(layer "F.Cu")
		(net "M_F_CPU0_SB_DQ<6>")
	)
	(segment
		(start 430.395126 -225.803714)
		(end 431.076354 -225.803714)
		(width 0.20066)
		(layer "F.Cu")
		(net "M_F_CPU0_SB_DQ<6>")
	)
	(segment
		(start 431.280316 -225.599752)
		(end 431.280316 -225.3488)
		(width 0.20066)
		(layer "F.Cu")
		(net "M_F_CPU0_SB_DQ<6>")
	)
	(segment
		(start 427.639226 -225.36658)
		(end 428.07128 -225.798634)
		(width 0.20066)
		(layer "F.Cu")
		(net "M_F_CPU0_SB_DQ<6>")
	)
	(segment
		(start 425.940982 -225.36658)
		(end 427.639226 -225.36658)
		(width 0.20066)
		(layer "F.Cu")
		(net "M_F_CPU0_SB_DQ<6>")
	)
	(segment
		(start 428.367952 -225.798634)
		(end 428.375064 -225.791522)
		(width 0.1016)
		(layer "F.Cu")
		(net "M_F_CPU0_SB_DQ<6>")
	)
	(segment
		(start 431.898552 -225.114612)
		(end 432.15052 -225.36658)
		(width 0.20066)
		(layer "F.Cu")
		(net "M_F_CPU0_SB_DQ<6>")
	)
	(segment
		(start 431.280316 -225.3488)
		(end 431.514504 -225.114612)
		(width 0.20066)
		(layer "F.Cu")
		(net "M_F_CPU0_SB_DQ<6>")
	)
	(segment
		(start 431.514504 -225.114612)
		(end 431.898552 -225.114612)
		(width 0.20066)
		(layer "F.Cu")
		(net "M_F_CPU0_SB_DQ<6>")
	)
	(segment
		(start 379.78588 -237.133638)
		(end 379.78588 -236.597952)
		(width 0.20066)
		(layer "F.Cu")
		(net "M_F_CPU0_SB_DQ<6>")
	)
	(segment
		(start 430.382934 -225.791522)
		(end 430.395126 -225.803714)
		(width 0.1016)
		(layer "F.Cu")
		(net "M_F_CPU0_SB_DQ<6>")
	)
	(segment
		(start 424.836082 -225.36658)
		(end 425.940982 -225.36658)
		(width 0.20066)
		(layer "F.Cu")
		(net "M_F_CPU0_SB_DQ<6>")
	)
	(segment
		(start 423.372026 -225.210878)
		(end 423.444162 -225.037142)
		(width 0.18288)
		(layer "In4.Cu")
		(net "M_F_CPU0_SB_DQ<6>")
	)
	(segment
		(start 418.621464 -224.443544)
		(end 418.293804 -224.443544)
		(width 0.18288)
		(layer "In4.Cu")
		(net "M_F_CPU0_SB_DQ<6>")
	)
	(segment
		(start 385.156964 -236.099604)
		(end 385.142232 -236.10824)
		(width 0.088646)
		(layer "In4.Cu")
		(net "M_F_CPU0_SB_DQ<6>")
	)
	(segment
		(start 384.217164 -236.099604)
		(end 384.202432 -236.10824)
		(width 0.088646)
		(layer "In4.Cu")
		(net "M_F_CPU0_SB_DQ<6>")
	)
	(segment
		(start 409.172156 -222.5294)
		(end 403.882606 -222.5294)
		(width 0.18288)
		(layer "In4.Cu")
		(net "M_F_CPU0_SB_DQ<6>")
	)
	(segment
		(start 418.110924 -223.954086)
		(end 417.928044 -223.771206)
		(width 0.18288)
		(layer "In4.Cu")
		(net "M_F_CPU0_SB_DQ<6>")
	)
	(segment
		(start 414.388554 -223.194626)
		(end 413.851344 -222.657416)
		(width 0.18288)
		(layer "In4.Cu")
		(net "M_F_CPU0_SB_DQ<6>")
	)
	(segment
		(start 417.928044 -223.771206)
		(end 416.44062 -223.771206)
		(width 0.18288)
		(layer "In4.Cu")
		(net "M_F_CPU0_SB_DQ<6>")
	)
	(segment
		(start 388.433564 -233.891836)
		(end 388.32917 -233.891836)
		(width 0.088646)
		(layer "In4.Cu")
		(net "M_F_CPU0_SB_DQ<6>")
	)
	(segment
		(start 420.079424 -224.437956)
		(end 419.412674 -223.771206)
		(width 0.18288)
		(layer "In4.Cu")
		(net "M_F_CPU0_SB_DQ<6>")
	)
	(segment
		(start 424.836082 -225.36658)
		(end 424.319954 -225.152966)
		(width 0.18288)
		(layer "In4.Cu")
		(net "M_F_CPU0_SB_DQ<6>")
	)
	(segment
		(start 409.323032 -222.378524)
		(end 409.172156 -222.5294)
		(width 0.18288)
		(layer "In4.Cu")
		(net "M_F_CPU0_SB_DQ<6>")
	)
	(segment
		(start 424.319954 -225.152966)
		(end 424.111166 -225.239326)
		(width 0.18288)
		(layer "In4.Cu")
		(net "M_F_CPU0_SB_DQ<6>")
	)
	(segment
		(start 403.882606 -222.5294)
		(end 394.678662 -231.733344)
		(width 0.18288)
		(layer "In4.Cu")
		(net "M_F_CPU0_SB_DQ<6>")
	)
	(segment
		(start 380.329694 -236.18063)
		(end 379.78588 -236.597952)
		(width 0.088646)
		(layer "In4.Cu")
		(net "M_F_CPU0_SB_DQ<6>")
	)
	(segment
		(start 418.804344 -223.954086)
		(end 418.804344 -224.260664)
		(width 0.18288)
		(layer "In4.Cu")
		(net "M_F_CPU0_SB_DQ<6>")
	)
	(segment
		(start 381.012954 -236.111034)
		(end 381.001016 -236.104176)
		(width 0.088646)
		(layer "In4.Cu")
		(net "M_F_CPU0_SB_DQ<6>")
	)
	(segment
		(start 389.14959 -233.891836)
		(end 388.433564 -233.891836)
		(width 0.18288)
		(layer "In4.Cu")
		(net "M_F_CPU0_SB_DQ<6>")
	)
	(segment
		(start 422.6814 -224.58172)
		(end 422.32072 -224.9424)
		(width 0.18288)
		(layer "In4.Cu")
		(net "M_F_CPU0_SB_DQ<6>")
	)
	(segment
		(start 388.32917 -233.891836)
		(end 387.679184 -234.541822)
		(width 0.088646)
		(layer "In4.Cu")
		(net "M_F_CPU0_SB_DQ<6>")
	)
	(segment
		(start 387.030722 -236.10316)
		(end 387.021832 -236.10824)
		(width 0.088646)
		(layer "In4.Cu")
		(net "M_F_CPU0_SB_DQ<6>")
	)
	(segment
		(start 386.096764 -236.099604)
		(end 386.082032 -236.10824)
		(width 0.088646)
		(layer "In4.Cu")
		(net "M_F_CPU0_SB_DQ<6>")
	)
	(segment
		(start 420.079424 -224.69221)
		(end 420.079424 -224.437956)
		(width 0.18288)
		(layer "In4.Cu")
		(net "M_F_CPU0_SB_DQ<6>")
	)
	(segment
		(start 423.320464 -224.738946)
		(end 422.941242 -224.58172)
		(width 0.18288)
		(layer "In4.Cu")
		(net "M_F_CPU0_SB_DQ<6>")
	)
	(segment
		(start 418.804344 -224.260664)
		(end 418.621464 -224.443544)
		(width 0.18288)
		(layer "In4.Cu")
		(net "M_F_CPU0_SB_DQ<6>")
	)
	(segment
		(start 412.91383 -222.657416)
		(end 412.634938 -222.378524)
		(width 0.18288)
		(layer "In4.Cu")
		(net "M_F_CPU0_SB_DQ<6>")
	)
	(segment
		(start 413.851344 -222.657416)
		(end 412.91383 -222.657416)
		(width 0.18288)
		(layer "In4.Cu")
		(net "M_F_CPU0_SB_DQ<6>")
	)
	(segment
		(start 419.412674 -223.771206)
		(end 418.987224 -223.771206)
		(width 0.18288)
		(layer "In4.Cu")
		(net "M_F_CPU0_SB_DQ<6>")
	)
	(segment
		(start 391.308082 -231.733344)
		(end 389.14959 -233.891836)
		(width 0.18288)
		(layer "In4.Cu")
		(net "M_F_CPU0_SB_DQ<6>")
	)
	(segment
		(start 422.941242 -224.58172)
		(end 422.6814 -224.58172)
		(width 0.18288)
		(layer "In4.Cu")
		(net "M_F_CPU0_SB_DQ<6>")
	)
	(segment
		(start 415.86404 -223.194626)
		(end 414.388554 -223.194626)
		(width 0.18288)
		(layer "In4.Cu")
		(net "M_F_CPU0_SB_DQ<6>")
	)
	(segment
		(start 394.678662 -231.733344)
		(end 391.308082 -231.733344)
		(width 0.18288)
		(layer "In4.Cu")
		(net "M_F_CPU0_SB_DQ<6>")
	)
	(segment
		(start 424.111166 -225.239326)
		(end 424.012868 -225.476308)
		(width 0.18288)
		(layer "In4.Cu")
		(net "M_F_CPU0_SB_DQ<6>")
	)
	(segment
		(start 423.444162 -225.037142)
		(end 423.320464 -224.738946)
		(width 0.18288)
		(layer "In4.Cu")
		(net "M_F_CPU0_SB_DQ<6>")
	)
	(segment
		(start 424.012868 -225.476308)
		(end 423.804334 -225.562922)
		(width 0.18288)
		(layer "In4.Cu")
		(net "M_F_CPU0_SB_DQ<6>")
	)
	(segment
		(start 382.892554 -236.111034)
		(end 382.88341 -236.1057)
		(width 0.088646)
		(layer "In4.Cu")
		(net "M_F_CPU0_SB_DQ<6>")
	)
	(segment
		(start 422.32072 -224.9424)
		(end 420.329614 -224.9424)
		(width 0.18288)
		(layer "In4.Cu")
		(net "M_F_CPU0_SB_DQ<6>")
	)
	(segment
		(start 412.634938 -222.378524)
		(end 409.323032 -222.378524)
		(width 0.18288)
		(layer "In4.Cu")
		(net "M_F_CPU0_SB_DQ<6>")
	)
	(segment
		(start 418.110924 -224.260664)
		(end 418.110924 -223.954086)
		(width 0.18288)
		(layer "In4.Cu")
		(net "M_F_CPU0_SB_DQ<6>")
	)
	(segment
		(start 416.44062 -223.771206)
		(end 415.86404 -223.194626)
		(width 0.18288)
		(layer "In4.Cu")
		(net "M_F_CPU0_SB_DQ<6>")
	)
	(segment
		(start 423.458894 -225.41992)
		(end 423.372026 -225.210878)
		(width 0.18288)
		(layer "In4.Cu")
		(net "M_F_CPU0_SB_DQ<6>")
	)
	(segment
		(start 387.506464 -235.285788)
		(end 387.491478 -235.294424)
		(width 0.088646)
		(layer "In4.Cu")
		(net "M_F_CPU0_SB_DQ<6>")
	)
	(segment
		(start 418.293804 -224.443544)
		(end 418.110924 -224.260664)
		(width 0.18288)
		(layer "In4.Cu")
		(net "M_F_CPU0_SB_DQ<6>")
	)
	(segment
		(start 423.804334 -225.562922)
		(end 423.458894 -225.41992)
		(width 0.18288)
		(layer "In4.Cu")
		(net "M_F_CPU0_SB_DQ<6>")
	)
	(segment
		(start 387.209284 -235.768388)
		(end 387.209284 -235.783882)
		(width 0.088646)
		(layer "In4.Cu")
		(net "M_F_CPU0_SB_DQ<6>")
	)
	(segment
		(start 380.443232 -236.108494)
		(end 380.403608 -236.131354)
		(width 0.088646)
		(layer "In4.Cu")
		(net "M_F_CPU0_SB_DQ<6>")
	)
	(segment
		(start 381.948182 -236.108494)
		(end 381.942594 -236.105192)
		(width 0.088646)
		(layer "In4.Cu")
		(net "M_F_CPU0_SB_DQ<6>")
	)
	(segment
		(start 383.828036 -236.10824)
		(end 383.822194 -236.105192)
		(width 0.088646)
		(layer "In4.Cu")
		(net "M_F_CPU0_SB_DQ<6>")
	)
	(segment
		(start 418.987224 -223.771206)
		(end 418.804344 -223.954086)
		(width 0.18288)
		(layer "In4.Cu")
		(net "M_F_CPU0_SB_DQ<6>")
	)
	(segment
		(start 420.329614 -224.9424)
		(end 420.079424 -224.69221)
		(width 0.18288)
		(layer "In4.Cu")
		(net "M_F_CPU0_SB_DQ<6>")
	)
	(segment
		(start 387.679184 -234.541822)
		(end 387.679184 -234.970066)
		(width 0.088646)
		(layer "In4.Cu")
		(net "M_F_CPU0_SB_DQ<6>")
	)
	(arc
		(start 381.942594 -236.105192)
		(mid 381.662379 -236.032751)
		(end 381.383032 -236.108494)
		(width 0.088646)
		(layer "In4.Cu")
		(net "M_F_CPU0_SB_DQ<6>")
	)
	(arc
		(start 385.142232 -236.10824)
		(mid 384.955034 -236.158383)
		(end 384.767836 -236.10824)
		(width 0.088646)
		(layer "In4.Cu")
		(net "M_F_CPU0_SB_DQ<6>")
	)
	(arc
		(start 387.679184 -234.970066)
		(mid 387.63318 -235.150003)
		(end 387.506464 -235.285788)
		(width 0.088646)
		(layer "In4.Cu")
		(net "M_F_CPU0_SB_DQ<6>")
	)
	(arc
		(start 382.88341 -236.1057)
		(mid 382.602746 -236.032692)
		(end 382.322832 -236.108494)
		(width 0.088646)
		(layer "In4.Cu")
		(net "M_F_CPU0_SB_DQ<6>")
	)
	(arc
		(start 387.021832 -236.10824)
		(mid 386.834634 -236.158383)
		(end 386.647436 -236.10824)
		(width 0.088646)
		(layer "In4.Cu")
		(net "M_F_CPU0_SB_DQ<6>")
	)
	(arc
		(start 386.082032 -236.10824)
		(mid 385.894834 -236.158383)
		(end 385.707636 -236.10824)
		(width 0.088646)
		(layer "In4.Cu")
		(net "M_F_CPU0_SB_DQ<6>")
	)
	(arc
		(start 387.209284 -235.783882)
		(mid 387.161605 -235.966782)
		(end 387.030722 -236.10316)
		(width 0.088646)
		(layer "In4.Cu")
		(net "M_F_CPU0_SB_DQ<6>")
	)
	(arc
		(start 384.202432 -236.10824)
		(mid 384.015234 -236.158383)
		(end 383.828036 -236.10824)
		(width 0.088646)
		(layer "In4.Cu")
		(net "M_F_CPU0_SB_DQ<6>")
	)
	(arc
		(start 384.767836 -236.10824)
		(mid 384.493607 -236.032315)
		(end 384.217164 -236.099604)
		(width 0.088646)
		(layer "In4.Cu")
		(net "M_F_CPU0_SB_DQ<6>")
	)
	(arc
		(start 381.383032 -236.108494)
		(mid 381.198338 -236.158595)
		(end 381.012954 -236.111034)
		(width 0.088646)
		(layer "In4.Cu")
		(net "M_F_CPU0_SB_DQ<6>")
	)
	(arc
		(start 386.647436 -236.10824)
		(mid 386.373207 -236.032315)
		(end 386.096764 -236.099604)
		(width 0.088646)
		(layer "In4.Cu")
		(net "M_F_CPU0_SB_DQ<6>")
	)
	(arc
		(start 382.322832 -236.108494)
		(mid 382.135524 -236.158603)
		(end 381.948182 -236.108494)
		(width 0.088646)
		(layer "In4.Cu")
		(net "M_F_CPU0_SB_DQ<6>")
	)
	(arc
		(start 380.403608 -236.131354)
		(mid 380.365827 -236.154756)
		(end 380.329694 -236.18063)
		(width 0.088646)
		(layer "In4.Cu")
		(net "M_F_CPU0_SB_DQ<6>")
	)
	(arc
		(start 383.262632 -236.108494)
		(mid 383.077938 -236.158595)
		(end 382.892554 -236.111034)
		(width 0.088646)
		(layer "In4.Cu")
		(net "M_F_CPU0_SB_DQ<6>")
	)
	(arc
		(start 381.001016 -236.104176)
		(mid 380.721555 -236.032739)
		(end 380.443232 -236.108494)
		(width 0.088646)
		(layer "In4.Cu")
		(net "M_F_CPU0_SB_DQ<6>")
	)
	(arc
		(start 383.822194 -236.105192)
		(mid 383.541979 -236.032751)
		(end 383.262632 -236.108494)
		(width 0.088646)
		(layer "In4.Cu")
		(net "M_F_CPU0_SB_DQ<6>")
	)
	(arc
		(start 385.707636 -236.10824)
		(mid 385.433407 -236.032315)
		(end 385.156964 -236.099604)
		(width 0.088646)
		(layer "In4.Cu")
		(net "M_F_CPU0_SB_DQ<6>")
	)
	(arc
		(start 387.491478 -235.294424)
		(mid 387.288655 -235.494655)
		(end 387.209284 -235.768388)
		(width 0.088646)
		(layer "In4.Cu")
		(net "M_F_CPU0_SB_DQ<6>")
	)
	(segment
		(start 423.361612 -224.516696)
		(end 421.840914 -224.516696)
		(width 0.20066)
		(layer "F.Cu")
		(net "M_F_CPU0_SB_DQ<5>")
	)
	(segment
		(start 424.273472 -224.209864)
		(end 424.273472 -224.577402)
		(width 0.20066)
		(layer "F.Cu")
		(net "M_F_CPU0_SB_DQ<5>")
	)
	(segment
		(start 427.792896 -224.51695)
		(end 427.36135 -224.085404)
		(width 0.20066)
		(layer "F.Cu")
		(net "M_F_CPU0_SB_DQ<5>")
	)
	(segment
		(start 429.38446 -224.51695)
		(end 427.792896 -224.51695)
		(width 0.20066)
		(layer "F.Cu")
		(net "M_F_CPU0_SB_DQ<5>")
	)
	(segment
		(start 424.273472 -224.577402)
		(end 424.085512 -224.765362)
		(width 0.20066)
		(layer "F.Cu")
		(net "M_F_CPU0_SB_DQ<5>")
	)
	(segment
		(start 421.840914 -224.516696)
		(end 420.736014 -224.516696)
		(width 0.20066)
		(layer "F.Cu")
		(net "M_F_CPU0_SB_DQ<5>")
	)
	(segment
		(start 424.73626 -224.091754)
		(end 424.391582 -224.091754)
		(width 0.20066)
		(layer "F.Cu")
		(net "M_F_CPU0_SB_DQ<5>")
	)
	(segment
		(start 424.391582 -224.091754)
		(end 424.273472 -224.209864)
		(width 0.20066)
		(layer "F.Cu")
		(net "M_F_CPU0_SB_DQ<5>")
	)
	(segment
		(start 378.376434 -236.319568)
		(end 378.376434 -235.783882)
		(width 0.20066)
		(layer "F.Cu")
		(net "M_F_CPU0_SB_DQ<5>")
	)
	(segment
		(start 429.384714 -224.516696)
		(end 429.38446 -224.51695)
		(width 0.20066)
		(layer "F.Cu")
		(net "M_F_CPU0_SB_DQ<5>")
	)
	(segment
		(start 424.085512 -224.765362)
		(end 423.610278 -224.765362)
		(width 0.20066)
		(layer "F.Cu")
		(net "M_F_CPU0_SB_DQ<5>")
	)
	(segment
		(start 378.37618 -236.319822)
		(end 378.376434 -236.319568)
		(width 0.20066)
		(layer "F.Cu")
		(net "M_F_CPU0_SB_DQ<5>")
	)
	(segment
		(start 426.945044 -224.091754)
		(end 424.756326 -224.091754)
		(width 0.1016)
		(layer "F.Cu")
		(net "M_F_CPU0_SB_DQ<5>")
	)
	(segment
		(start 426.951394 -224.085404)
		(end 426.945044 -224.091754)
		(width 0.1016)
		(layer "F.Cu")
		(net "M_F_CPU0_SB_DQ<5>")
	)
	(segment
		(start 424.756326 -224.091754)
		(end 424.73626 -224.091754)
		(width 0.101854)
		(layer "F.Cu")
		(net "M_F_CPU0_SB_DQ<5>")
	)
	(segment
		(start 423.610278 -224.765362)
		(end 423.361612 -224.516696)
		(width 0.20066)
		(layer "F.Cu")
		(net "M_F_CPU0_SB_DQ<5>")
	)
	(segment
		(start 427.36135 -224.085404)
		(end 426.951394 -224.085404)
		(width 0.20066)
		(layer "F.Cu")
		(net "M_F_CPU0_SB_DQ<5>")
	)
	(segment
		(start 417.962842 -222.648272)
		(end 417.962842 -223.110806)
		(width 0.18288)
		(layer "In4.Cu")
		(net "M_F_CPU0_SB_DQ<5>")
	)
	(segment
		(start 419.623494 -223.270826)
		(end 418.816282 -223.270826)
		(width 0.18288)
		(layer "In4.Cu")
		(net "M_F_CPU0_SB_DQ<5>")
	)
	(segment
		(start 387.117082 -234.645708)
		(end 387.108192 -234.650788)
		(width 0.088646)
		(layer "In4.Cu")
		(net "M_F_CPU0_SB_DQ<5>")
	)
	(segment
		(start 415.945828 -221.449392)
		(end 415.785808 -221.289372)
		(width 0.18288)
		(layer "In4.Cu")
		(net "M_F_CPU0_SB_DQ<5>")
	)
	(segment
		(start 409.166314 -221.518226)
		(end 404.169372 -221.518226)
		(width 0.18288)
		(layer "In4.Cu")
		(net "M_F_CPU0_SB_DQ<5>")
	)
	(segment
		(start 418.656262 -222.648272)
		(end 418.496242 -222.488252)
		(width 0.18288)
		(layer "In4.Cu")
		(net "M_F_CPU0_SB_DQ<5>")
	)
	(segment
		(start 418.816282 -223.270826)
		(end 418.656262 -223.110806)
		(width 0.18288)
		(layer "In4.Cu")
		(net "M_F_CPU0_SB_DQ<5>")
	)
	(segment
		(start 416.509708 -222.427292)
		(end 416.105848 -222.427292)
		(width 0.18288)
		(layer "In4.Cu")
		(net "M_F_CPU0_SB_DQ<5>")
	)
	(segment
		(start 383.827782 -235.459524)
		(end 383.824226 -235.461556)
		(width 0.088646)
		(layer "In4.Cu")
		(net "M_F_CPU0_SB_DQ<5>")
	)
	(segment
		(start 410.753306 -221.283022)
		(end 410.536136 -221.500192)
		(width 0.18288)
		(layer "In4.Cu")
		(net "M_F_CPU0_SB_DQ<5>")
	)
	(segment
		(start 415.945828 -222.267272)
		(end 415.945828 -221.449392)
		(width 0.18288)
		(layer "In4.Cu")
		(net "M_F_CPU0_SB_DQ<5>")
	)
	(segment
		(start 394.452094 -231.235504)
		(end 391.101834 -231.235504)
		(width 0.18288)
		(layer "In4.Cu")
		(net "M_F_CPU0_SB_DQ<5>")
	)
	(segment
		(start 389.16737 -233.169968)
		(end 388.433564 -233.169968)
		(width 0.18288)
		(layer "In4.Cu")
		(net "M_F_CPU0_SB_DQ<5>")
	)
	(segment
		(start 416.669728 -222.587312)
		(end 416.509708 -222.427292)
		(width 0.18288)
		(layer "In4.Cu")
		(net "M_F_CPU0_SB_DQ<5>")
	)
	(segment
		(start 381.014224 -235.456222)
		(end 381.00254 -235.462826)
		(width 0.088646)
		(layer "In4.Cu")
		(net "M_F_CPU0_SB_DQ<5>")
	)
	(segment
		(start 387.123178 -234.642152)
		(end 387.117082 -234.645708)
		(width 0.088646)
		(layer "In4.Cu")
		(net "M_F_CPU0_SB_DQ<5>")
	)
	(segment
		(start 386.096764 -235.46816)
		(end 386.082032 -235.459524)
		(width 0.088646)
		(layer "In4.Cu")
		(net "M_F_CPU0_SB_DQ<5>")
	)
	(segment
		(start 411.229556 -221.500192)
		(end 411.012386 -221.283022)
		(width 0.18288)
		(layer "In4.Cu")
		(net "M_F_CPU0_SB_DQ<5>")
	)
	(segment
		(start 420.543228 -224.32391)
		(end 420.543228 -224.19056)
		(width 0.18288)
		(layer "In4.Cu")
		(net "M_F_CPU0_SB_DQ<5>")
	)
	(segment
		(start 382.893824 -235.456222)
		(end 382.88341 -235.462064)
		(width 0.088646)
		(layer "In4.Cu")
		(net "M_F_CPU0_SB_DQ<5>")
	)
	(segment
		(start 420.543228 -224.19056)
		(end 419.623494 -223.270826)
		(width 0.18288)
		(layer "In4.Cu")
		(net "M_F_CPU0_SB_DQ<5>")
	)
	(segment
		(start 388.433564 -233.169968)
		(end 388.145528 -233.169968)
		(width 0.088646)
		(layer "In4.Cu")
		(net "M_F_CPU0_SB_DQ<5>")
	)
	(segment
		(start 413.425894 -221.416626)
		(end 412.765494 -221.416626)
		(width 0.18288)
		(layer "In4.Cu")
		(net "M_F_CPU0_SB_DQ<5>")
	)
	(segment
		(start 417.802822 -223.270826)
		(end 416.829748 -223.270826)
		(width 0.18288)
		(layer "In4.Cu")
		(net "M_F_CPU0_SB_DQ<5>")
	)
	(segment
		(start 416.105848 -222.427292)
		(end 415.945828 -222.267272)
		(width 0.18288)
		(layer "In4.Cu")
		(net "M_F_CPU0_SB_DQ<5>")
	)
	(segment
		(start 413.62884 -221.619572)
		(end 413.425894 -221.416626)
		(width 0.18288)
		(layer "In4.Cu")
		(net "M_F_CPU0_SB_DQ<5>")
	)
	(segment
		(start 416.669728 -223.110806)
		(end 416.669728 -222.587312)
		(width 0.18288)
		(layer "In4.Cu")
		(net "M_F_CPU0_SB_DQ<5>")
	)
	(segment
		(start 416.829748 -223.270826)
		(end 416.669728 -223.110806)
		(width 0.18288)
		(layer "In4.Cu")
		(net "M_F_CPU0_SB_DQ<5>")
	)
	(segment
		(start 420.736014 -224.516696)
		(end 420.543228 -224.32391)
		(width 0.18288)
		(layer "In4.Cu")
		(net "M_F_CPU0_SB_DQ<5>")
	)
	(segment
		(start 414.915604 -221.8817)
		(end 414.755584 -222.04172)
		(width 0.18288)
		(layer "In4.Cu")
		(net "M_F_CPU0_SB_DQ<5>")
	)
	(segment
		(start 387.587236 -233.831892)
		(end 387.578346 -233.836972)
		(width 0.088646)
		(layer "In4.Cu")
		(net "M_F_CPU0_SB_DQ<5>")
	)
	(segment
		(start 379.040898 -236.277658)
		(end 378.935488 -236.215936)
		(width 0.088646)
		(layer "In4.Cu")
		(net "M_F_CPU0_SB_DQ<5>")
	)
	(segment
		(start 413.81172 -222.04172)
		(end 413.62884 -221.85884)
		(width 0.18288)
		(layer "In4.Cu")
		(net "M_F_CPU0_SB_DQ<5>")
	)
	(segment
		(start 380.074424 -235.456222)
		(end 380.063502 -235.462318)
		(width 0.088646)
		(layer "In4.Cu")
		(net "M_F_CPU0_SB_DQ<5>")
	)
	(segment
		(start 391.101834 -231.235504)
		(end 389.16737 -233.169968)
		(width 0.18288)
		(layer "In4.Cu")
		(net "M_F_CPU0_SB_DQ<5>")
	)
	(segment
		(start 404.169372 -221.518226)
		(end 394.452094 -231.235504)
		(width 0.18288)
		(layer "In4.Cu")
		(net "M_F_CPU0_SB_DQ<5>")
	)
	(segment
		(start 418.656262 -223.110806)
		(end 418.656262 -222.648272)
		(width 0.18288)
		(layer "In4.Cu")
		(net "M_F_CPU0_SB_DQ<5>")
	)
	(segment
		(start 411.229556 -221.6658)
		(end 411.229556 -221.500192)
		(width 0.18288)
		(layer "In4.Cu")
		(net "M_F_CPU0_SB_DQ<5>")
	)
	(segment
		(start 415.075624 -221.289372)
		(end 414.915604 -221.449392)
		(width 0.18288)
		(layer "In4.Cu")
		(net "M_F_CPU0_SB_DQ<5>")
	)
	(segment
		(start 418.122862 -222.488252)
		(end 417.962842 -222.648272)
		(width 0.18288)
		(layer "In4.Cu")
		(net "M_F_CPU0_SB_DQ<5>")
	)
	(segment
		(start 412.3563 -221.82582)
		(end 411.389576 -221.82582)
		(width 0.18288)
		(layer "In4.Cu")
		(net "M_F_CPU0_SB_DQ<5>")
	)
	(segment
		(start 414.915604 -221.449392)
		(end 414.915604 -221.8817)
		(width 0.18288)
		(layer "In4.Cu")
		(net "M_F_CPU0_SB_DQ<5>")
	)
	(segment
		(start 414.755584 -222.04172)
		(end 413.81172 -222.04172)
		(width 0.18288)
		(layer "In4.Cu")
		(net "M_F_CPU0_SB_DQ<5>")
	)
	(segment
		(start 410.536136 -221.66326)
		(end 410.373576 -221.82582)
		(width 0.18288)
		(layer "In4.Cu")
		(net "M_F_CPU0_SB_DQ<5>")
	)
	(segment
		(start 411.012386 -221.283022)
		(end 410.753306 -221.283022)
		(width 0.18288)
		(layer "In4.Cu")
		(net "M_F_CPU0_SB_DQ<5>")
	)
	(segment
		(start 410.536136 -221.500192)
		(end 410.536136 -221.66326)
		(width 0.18288)
		(layer "In4.Cu")
		(net "M_F_CPU0_SB_DQ<5>")
	)
	(segment
		(start 409.473908 -221.82582)
		(end 409.166314 -221.518226)
		(width 0.18288)
		(layer "In4.Cu")
		(net "M_F_CPU0_SB_DQ<5>")
	)
	(segment
		(start 381.948182 -235.459524)
		(end 381.944626 -235.461556)
		(width 0.088646)
		(layer "In4.Cu")
		(net "M_F_CPU0_SB_DQ<5>")
	)
	(segment
		(start 412.765494 -221.416626)
		(end 412.3563 -221.82582)
		(width 0.18288)
		(layer "In4.Cu")
		(net "M_F_CPU0_SB_DQ<5>")
	)
	(segment
		(start 379.88113 -235.783882)
		(end 379.88113 -235.79201)
		(width 0.088646)
		(layer "In4.Cu")
		(net "M_F_CPU0_SB_DQ<5>")
	)
	(segment
		(start 418.496242 -222.488252)
		(end 418.122862 -222.488252)
		(width 0.18288)
		(layer "In4.Cu")
		(net "M_F_CPU0_SB_DQ<5>")
	)
	(segment
		(start 413.62884 -221.85884)
		(end 413.62884 -221.619572)
		(width 0.18288)
		(layer "In4.Cu")
		(net "M_F_CPU0_SB_DQ<5>")
	)
	(segment
		(start 385.156964 -235.46816)
		(end 385.142232 -235.459524)
		(width 0.088646)
		(layer "In4.Cu")
		(net "M_F_CPU0_SB_DQ<5>")
	)
	(segment
		(start 386.92963 -234.970066)
		(end 386.92963 -234.98556)
		(width 0.088646)
		(layer "In4.Cu")
		(net "M_F_CPU0_SB_DQ<5>")
	)
	(segment
		(start 378.376688 -235.784136)
		(end 378.376434 -235.783882)
		(width 0.088646)
		(layer "In4.Cu")
		(net "M_F_CPU0_SB_DQ<5>")
	)
	(segment
		(start 410.373576 -221.82582)
		(end 409.473908 -221.82582)
		(width 0.18288)
		(layer "In4.Cu")
		(net "M_F_CPU0_SB_DQ<5>")
	)
	(segment
		(start 417.962842 -223.110806)
		(end 417.802822 -223.270826)
		(width 0.18288)
		(layer "In4.Cu")
		(net "M_F_CPU0_SB_DQ<5>")
	)
	(segment
		(start 384.217164 -235.46816)
		(end 384.202432 -235.459524)
		(width 0.088646)
		(layer "In4.Cu")
		(net "M_F_CPU0_SB_DQ<5>")
	)
	(segment
		(start 415.785808 -221.289372)
		(end 415.075624 -221.289372)
		(width 0.18288)
		(layer "In4.Cu")
		(net "M_F_CPU0_SB_DQ<5>")
	)
	(segment
		(start 411.389576 -221.82582)
		(end 411.229556 -221.6658)
		(width 0.18288)
		(layer "In4.Cu")
		(net "M_F_CPU0_SB_DQ<5>")
	)
	(arc
		(start 386.92963 -234.98556)
		(mid 386.85026 -235.259294)
		(end 386.647436 -235.459524)
		(width 0.088646)
		(layer "In4.Cu")
		(net "M_F_CPU0_SB_DQ<5>")
	)
	(arc
		(start 385.142232 -235.459524)
		(mid 384.955034 -235.409381)
		(end 384.767836 -235.459524)
		(width 0.088646)
		(layer "In4.Cu")
		(net "M_F_CPU0_SB_DQ<5>")
	)
	(arc
		(start 387.578346 -233.836972)
		(mid 387.447432 -233.973332)
		(end 387.399784 -234.15625)
		(width 0.088646)
		(layer "In4.Cu")
		(net "M_F_CPU0_SB_DQ<5>")
	)
	(arc
		(start 386.647436 -235.459524)
		(mid 386.373237 -235.535359)
		(end 386.096764 -235.46816)
		(width 0.088646)
		(layer "In4.Cu")
		(net "M_F_CPU0_SB_DQ<5>")
	)
	(arc
		(start 382.88341 -235.462064)
		(mid 382.602775 -235.535232)
		(end 382.322832 -235.459524)
		(width 0.088646)
		(layer "In4.Cu")
		(net "M_F_CPU0_SB_DQ<5>")
	)
	(arc
		(start 388.145528 -233.169968)
		(mid 387.959015 -233.240224)
		(end 387.865366 -233.416094)
		(width 0.088646)
		(layer "In4.Cu")
		(net "M_F_CPU0_SB_DQ<5>")
	)
	(arc
		(start 387.865366 -233.416094)
		(mid 387.774748 -233.656388)
		(end 387.587236 -233.831892)
		(width 0.088646)
		(layer "In4.Cu")
		(net "M_F_CPU0_SB_DQ<5>")
	)
	(arc
		(start 384.767836 -235.459524)
		(mid 384.493637 -235.535359)
		(end 384.217164 -235.46816)
		(width 0.088646)
		(layer "In4.Cu")
		(net "M_F_CPU0_SB_DQ<5>")
	)
	(arc
		(start 381.944626 -235.461556)
		(mid 381.663542 -235.535293)
		(end 381.383032 -235.459524)
		(width 0.088646)
		(layer "In4.Cu")
		(net "M_F_CPU0_SB_DQ<5>")
	)
	(arc
		(start 383.262632 -235.459524)
		(mid 383.078678 -235.409395)
		(end 382.893824 -235.456222)
		(width 0.088646)
		(layer "In4.Cu")
		(net "M_F_CPU0_SB_DQ<5>")
	)
	(arc
		(start 378.935488 -236.215936)
		(mid 378.642284 -236.017899)
		(end 378.376688 -235.784136)
		(width 0.088646)
		(layer "In4.Cu")
		(net "M_F_CPU0_SB_DQ<5>")
	)
	(arc
		(start 384.202432 -235.459524)
		(mid 384.015124 -235.409381)
		(end 383.827782 -235.459524)
		(width 0.088646)
		(layer "In4.Cu")
		(net "M_F_CPU0_SB_DQ<5>")
	)
	(arc
		(start 386.082032 -235.459524)
		(mid 385.894834 -235.409381)
		(end 385.707636 -235.459524)
		(width 0.088646)
		(layer "In4.Cu")
		(net "M_F_CPU0_SB_DQ<5>")
	)
	(arc
		(start 385.707636 -235.459524)
		(mid 385.433437 -235.535359)
		(end 385.156964 -235.46816)
		(width 0.088646)
		(layer "In4.Cu")
		(net "M_F_CPU0_SB_DQ<5>")
	)
	(arc
		(start 383.824226 -235.461556)
		(mid 383.543142 -235.535293)
		(end 383.262632 -235.459524)
		(width 0.088646)
		(layer "In4.Cu")
		(net "M_F_CPU0_SB_DQ<5>")
	)
	(arc
		(start 387.399784 -234.15625)
		(mid 387.325793 -234.435816)
		(end 387.123178 -234.642152)
		(width 0.088646)
		(layer "In4.Cu")
		(net "M_F_CPU0_SB_DQ<5>")
	)
	(arc
		(start 380.443232 -235.459524)
		(mid 380.259278 -235.409395)
		(end 380.074424 -235.456222)
		(width 0.088646)
		(layer "In4.Cu")
		(net "M_F_CPU0_SB_DQ<5>")
	)
	(arc
		(start 382.322832 -235.459524)
		(mid 382.135524 -235.409381)
		(end 381.948182 -235.459524)
		(width 0.088646)
		(layer "In4.Cu")
		(net "M_F_CPU0_SB_DQ<5>")
	)
	(arc
		(start 381.00254 -235.462826)
		(mid 380.722435 -235.535268)
		(end 380.443232 -235.459524)
		(width 0.088646)
		(layer "In4.Cu")
		(net "M_F_CPU0_SB_DQ<5>")
	)
	(arc
		(start 380.063502 -235.462318)
		(mid 379.929886 -235.599038)
		(end 379.88113 -235.783882)
		(width 0.088646)
		(layer "In4.Cu")
		(net "M_F_CPU0_SB_DQ<5>")
	)
	(arc
		(start 381.383032 -235.459524)
		(mid 381.199078 -235.409395)
		(end 381.014224 -235.456222)
		(width 0.088646)
		(layer "In4.Cu")
		(net "M_F_CPU0_SB_DQ<5>")
	)
	(arc
		(start 379.88113 -235.79201)
		(mid 379.598814 -236.273234)
		(end 379.040898 -236.277658)
		(width 0.088646)
		(layer "In4.Cu")
		(net "M_F_CPU0_SB_DQ<5>")
	)
	(arc
		(start 387.108192 -234.650788)
		(mid 386.977278 -234.787148)
		(end 386.92963 -234.970066)
		(width 0.088646)
		(layer "In4.Cu")
		(net "M_F_CPU0_SB_DQ<5>")
	)
	(segment
		(start 429.38446 -226.216972)
		(end 427.792896 -226.216972)
		(width 0.20066)
		(layer "F.Cu")
		(net "M_F_CPU0_SB_DQ<4>")
	)
	(segment
		(start 423.610278 -226.465384)
		(end 423.361612 -226.216718)
		(width 0.20066)
		(layer "F.Cu")
		(net "M_F_CPU0_SB_DQ<4>")
	)
	(segment
		(start 424.273472 -225.909886)
		(end 424.273472 -226.277424)
		(width 0.20066)
		(layer "F.Cu")
		(net "M_F_CPU0_SB_DQ<4>")
	)
	(segment
		(start 424.391582 -225.791776)
		(end 424.273472 -225.909886)
		(width 0.20066)
		(layer "F.Cu")
		(net "M_F_CPU0_SB_DQ<4>")
	)
	(segment
		(start 424.085512 -226.465384)
		(end 423.610278 -226.465384)
		(width 0.20066)
		(layer "F.Cu")
		(net "M_F_CPU0_SB_DQ<4>")
	)
	(segment
		(start 427.36135 -225.785426)
		(end 426.951394 -225.785426)
		(width 0.20066)
		(layer "F.Cu")
		(net "M_F_CPU0_SB_DQ<4>")
	)
	(segment
		(start 424.78325 -225.791776)
		(end 424.73626 -225.791776)
		(width 0.101854)
		(layer "F.Cu")
		(net "M_F_CPU0_SB_DQ<4>")
	)
	(segment
		(start 427.792896 -226.216972)
		(end 427.36135 -225.785426)
		(width 0.20066)
		(layer "F.Cu")
		(net "M_F_CPU0_SB_DQ<4>")
	)
	(segment
		(start 429.384714 -226.216718)
		(end 429.38446 -226.216972)
		(width 0.20066)
		(layer "F.Cu")
		(net "M_F_CPU0_SB_DQ<4>")
	)
	(segment
		(start 426.945044 -225.791776)
		(end 424.78325 -225.791776)
		(width 0.1016)
		(layer "F.Cu")
		(net "M_F_CPU0_SB_DQ<4>")
	)
	(segment
		(start 423.361612 -226.216718)
		(end 421.840914 -226.216718)
		(width 0.20066)
		(layer "F.Cu")
		(net "M_F_CPU0_SB_DQ<4>")
	)
	(segment
		(start 377.90628 -237.133638)
		(end 377.90628 -236.597952)
		(width 0.20066)
		(layer "F.Cu")
		(net "M_F_CPU0_SB_DQ<4>")
	)
	(segment
		(start 377.906534 -237.133892)
		(end 377.90628 -237.133638)
		(width 0.20066)
		(layer "F.Cu")
		(net "M_F_CPU0_SB_DQ<4>")
	)
	(segment
		(start 424.273472 -226.277424)
		(end 424.085512 -226.465384)
		(width 0.20066)
		(layer "F.Cu")
		(net "M_F_CPU0_SB_DQ<4>")
	)
	(segment
		(start 424.73626 -225.791776)
		(end 424.391582 -225.791776)
		(width 0.20066)
		(layer "F.Cu")
		(net "M_F_CPU0_SB_DQ<4>")
	)
	(segment
		(start 421.840914 -226.216718)
		(end 420.736014 -226.216718)
		(width 0.20066)
		(layer "F.Cu")
		(net "M_F_CPU0_SB_DQ<4>")
	)
	(segment
		(start 426.951394 -225.785426)
		(end 426.945044 -225.791776)
		(width 0.1016)
		(layer "F.Cu")
		(net "M_F_CPU0_SB_DQ<4>")
	)
	(segment
		(start 404.766018 -224.565972)
		(end 404.438358 -224.565972)
		(width 0.18288)
		(layer "In4.Cu")
		(net "M_F_CPU0_SB_DQ<4>")
	)
	(segment
		(start 384.297682 -236.273594)
		(end 384.28295 -236.28223)
		(width 0.088646)
		(layer "In4.Cu")
		(net "M_F_CPU0_SB_DQ<4>")
	)
	(segment
		(start 386.177282 -236.273594)
		(end 386.16255 -236.28223)
		(width 0.088646)
		(layer "In4.Cu")
		(net "M_F_CPU0_SB_DQ<4>")
	)
	(segment
		(start 404.255478 -224.383092)
		(end 404.255478 -223.425258)
		(width 0.18288)
		(layer "In4.Cu")
		(net "M_F_CPU0_SB_DQ<4>")
	)
	(segment
		(start 381.852932 -236.27334)
		(end 381.850392 -236.271816)
		(width 0.088646)
		(layer "In4.Cu")
		(net "M_F_CPU0_SB_DQ<4>")
	)
	(segment
		(start 419.19652 -224.952052)
		(end 416.513264 -224.952052)
		(width 0.18288)
		(layer "In4.Cu")
		(net "M_F_CPU0_SB_DQ<4>")
	)
	(segment
		(start 404.948898 -224.383092)
		(end 404.766018 -224.565972)
		(width 0.18288)
		(layer "In4.Cu")
		(net "M_F_CPU0_SB_DQ<4>")
	)
	(segment
		(start 407.205434 -224.171256)
		(end 407.022554 -224.354136)
		(width 0.18288)
		(layer "In4.Cu")
		(net "M_F_CPU0_SB_DQ<4>")
	)
	(segment
		(start 389.349488 -234.396026)
		(end 388.433564 -234.396026)
		(width 0.18288)
		(layer "In4.Cu")
		(net "M_F_CPU0_SB_DQ<4>")
	)
	(segment
		(start 406.512014 -224.171256)
		(end 406.512014 -223.425258)
		(width 0.18288)
		(layer "In4.Cu")
		(net "M_F_CPU0_SB_DQ<4>")
	)
	(segment
		(start 420.736014 -226.216718)
		(end 419.76167 -225.242374)
		(width 0.18288)
		(layer "In4.Cu")
		(net "M_F_CPU0_SB_DQ<4>")
	)
	(segment
		(start 407.205434 -223.425258)
		(end 407.205434 -224.171256)
		(width 0.18288)
		(layer "In4.Cu")
		(net "M_F_CPU0_SB_DQ<4>")
	)
	(segment
		(start 380.39802 -236.416596)
		(end 380.311406 -236.573314)
		(width 0.088646)
		(layer "In4.Cu")
		(net "M_F_CPU0_SB_DQ<4>")
	)
	(segment
		(start 388.17677 -234.396026)
		(end 387.869684 -234.703112)
		(width 0.088646)
		(layer "In4.Cu")
		(net "M_F_CPU0_SB_DQ<4>")
	)
	(segment
		(start 387.399784 -235.783882)
		(end 387.399784 -235.798106)
		(width 0.088646)
		(layer "In4.Cu")
		(net "M_F_CPU0_SB_DQ<4>")
	)
	(segment
		(start 415.670238 -224.109026)
		(end 414.385506 -224.109026)
		(width 0.18288)
		(layer "In4.Cu")
		(net "M_F_CPU0_SB_DQ<4>")
	)
	(segment
		(start 407.388314 -223.242378)
		(end 407.205434 -223.425258)
		(width 0.18288)
		(layer "In4.Cu")
		(net "M_F_CPU0_SB_DQ<4>")
	)
	(segment
		(start 379.039374 -236.918754)
		(end 379.02769 -236.925612)
		(width 0.088646)
		(layer "In4.Cu")
		(net "M_F_CPU0_SB_DQ<4>")
	)
	(segment
		(start 419.76167 -225.242374)
		(end 419.486842 -225.242374)
		(width 0.18288)
		(layer "In4.Cu")
		(net "M_F_CPU0_SB_DQ<4>")
	)
	(segment
		(start 416.513264 -224.952052)
		(end 415.670238 -224.109026)
		(width 0.18288)
		(layer "In4.Cu")
		(net "M_F_CPU0_SB_DQ<4>")
	)
	(segment
		(start 404.438358 -224.565972)
		(end 404.255478 -224.383092)
		(width 0.18288)
		(layer "In4.Cu")
		(net "M_F_CPU0_SB_DQ<4>")
	)
	(segment
		(start 378.600716 -236.897164)
		(end 377.90628 -236.597952)
		(width 0.088646)
		(layer "In4.Cu")
		(net "M_F_CPU0_SB_DQ<4>")
	)
	(segment
		(start 414.385506 -224.109026)
		(end 413.458406 -223.181926)
		(width 0.18288)
		(layer "In4.Cu")
		(net "M_F_CPU0_SB_DQ<4>")
	)
	(segment
		(start 407.022554 -224.354136)
		(end 406.694894 -224.354136)
		(width 0.18288)
		(layer "In4.Cu")
		(net "M_F_CPU0_SB_DQ<4>")
	)
	(segment
		(start 412.685738 -223.181926)
		(end 412.333694 -223.53397)
		(width 0.18288)
		(layer "In4.Cu")
		(net "M_F_CPU0_SB_DQ<4>")
	)
	(segment
		(start 394.904214 -232.231184)
		(end 391.51433 -232.231184)
		(width 0.18288)
		(layer "In4.Cu")
		(net "M_F_CPU0_SB_DQ<4>")
	)
	(segment
		(start 387.117082 -236.273594)
		(end 387.10235 -236.28223)
		(width 0.088646)
		(layer "In4.Cu")
		(net "M_F_CPU0_SB_DQ<4>")
	)
	(segment
		(start 388.433564 -234.396026)
		(end 388.17677 -234.396026)
		(width 0.088646)
		(layer "In4.Cu")
		(net "M_F_CPU0_SB_DQ<4>")
	)
	(segment
		(start 413.458406 -223.181926)
		(end 412.685738 -223.181926)
		(width 0.18288)
		(layer "In4.Cu")
		(net "M_F_CPU0_SB_DQ<4>")
	)
	(segment
		(start 405.131778 -223.242378)
		(end 404.948898 -223.425258)
		(width 0.18288)
		(layer "In4.Cu")
		(net "M_F_CPU0_SB_DQ<4>")
	)
	(segment
		(start 385.237482 -236.273594)
		(end 385.22275 -236.28223)
		(width 0.088646)
		(layer "In4.Cu")
		(net "M_F_CPU0_SB_DQ<4>")
	)
	(segment
		(start 387.587236 -235.459524)
		(end 387.578346 -235.464604)
		(width 0.088646)
		(layer "In4.Cu")
		(net "M_F_CPU0_SB_DQ<4>")
	)
	(segment
		(start 406.329134 -223.242378)
		(end 405.131778 -223.242378)
		(width 0.18288)
		(layer "In4.Cu")
		(net "M_F_CPU0_SB_DQ<4>")
	)
	(segment
		(start 380.920498 -236.277658)
		(end 380.90856 -236.2708)
		(width 0.088646)
		(layer "In4.Cu")
		(net "M_F_CPU0_SB_DQ<4>")
	)
	(segment
		(start 387.869684 -234.703112)
		(end 387.869684 -234.970066)
		(width 0.088646)
		(layer "In4.Cu")
		(net "M_F_CPU0_SB_DQ<4>")
	)
	(segment
		(start 404.255478 -223.425258)
		(end 404.072598 -223.242378)
		(width 0.18288)
		(layer "In4.Cu")
		(net "M_F_CPU0_SB_DQ<4>")
	)
	(segment
		(start 391.51433 -232.231184)
		(end 389.349488 -234.396026)
		(width 0.18288)
		(layer "In4.Cu")
		(net "M_F_CPU0_SB_DQ<4>")
	)
	(segment
		(start 379.980444 -236.918246)
		(end 379.96749 -236.925612)
		(width 0.088646)
		(layer "In4.Cu")
		(net "M_F_CPU0_SB_DQ<4>")
	)
	(segment
		(start 411.82417 -223.53397)
		(end 411.532578 -223.242378)
		(width 0.18288)
		(layer "In4.Cu")
		(net "M_F_CPU0_SB_DQ<4>")
	)
	(segment
		(start 387.593332 -235.455968)
		(end 387.587236 -235.459524)
		(width 0.088646)
		(layer "In4.Cu")
		(net "M_F_CPU0_SB_DQ<4>")
	)
	(segment
		(start 412.333694 -223.53397)
		(end 411.82417 -223.53397)
		(width 0.18288)
		(layer "In4.Cu")
		(net "M_F_CPU0_SB_DQ<4>")
	)
	(segment
		(start 404.072598 -223.242378)
		(end 403.89302 -223.242378)
		(width 0.18288)
		(layer "In4.Cu")
		(net "M_F_CPU0_SB_DQ<4>")
	)
	(segment
		(start 411.532578 -223.242378)
		(end 407.388314 -223.242378)
		(width 0.18288)
		(layer "In4.Cu")
		(net "M_F_CPU0_SB_DQ<4>")
	)
	(segment
		(start 406.512014 -223.425258)
		(end 406.329134 -223.242378)
		(width 0.18288)
		(layer "In4.Cu")
		(net "M_F_CPU0_SB_DQ<4>")
	)
	(segment
		(start 406.694894 -224.354136)
		(end 406.512014 -224.171256)
		(width 0.18288)
		(layer "In4.Cu")
		(net "M_F_CPU0_SB_DQ<4>")
	)
	(segment
		(start 404.948898 -223.425258)
		(end 404.948898 -224.383092)
		(width 0.18288)
		(layer "In4.Cu")
		(net "M_F_CPU0_SB_DQ<4>")
	)
	(segment
		(start 419.486842 -225.242374)
		(end 419.19652 -224.952052)
		(width 0.18288)
		(layer "In4.Cu")
		(net "M_F_CPU0_SB_DQ<4>")
	)
	(segment
		(start 403.89302 -223.242378)
		(end 394.904214 -232.231184)
		(width 0.18288)
		(layer "In4.Cu")
		(net "M_F_CPU0_SB_DQ<4>")
	)
	(segment
		(start 382.800098 -236.277658)
		(end 382.788922 -236.271308)
		(width 0.088646)
		(layer "In4.Cu")
		(net "M_F_CPU0_SB_DQ<4>")
	)
	(segment
		(start 383.732278 -236.273594)
		(end 383.729992 -236.271816)
		(width 0.088646)
		(layer "In4.Cu")
		(net "M_F_CPU0_SB_DQ<4>")
	)
	(arc
		(start 382.788922 -236.271308)
		(mid 382.603232 -236.22323)
		(end 382.418082 -236.27334)
		(width 0.088646)
		(layer "In4.Cu")
		(net "M_F_CPU0_SB_DQ<4>")
	)
	(arc
		(start 383.357882 -236.27334)
		(mid 383.079559 -236.349099)
		(end 382.800098 -236.277658)
		(width 0.088646)
		(layer "In4.Cu")
		(net "M_F_CPU0_SB_DQ<4>")
	)
	(arc
		(start 380.311406 -236.573314)
		(mid 380.229756 -236.699264)
		(end 380.13132 -236.812582)
		(width 0.088646)
		(layer "In4.Cu")
		(net "M_F_CPU0_SB_DQ<4>")
	)
	(arc
		(start 382.418082 -236.27334)
		(mid 382.135524 -236.348989)
		(end 381.852932 -236.27334)
		(width 0.088646)
		(layer "In4.Cu")
		(net "M_F_CPU0_SB_DQ<4>")
	)
	(arc
		(start 381.478282 -236.27334)
		(mid 381.199959 -236.349099)
		(end 380.920498 -236.277658)
		(width 0.088646)
		(layer "In4.Cu")
		(net "M_F_CPU0_SB_DQ<4>")
	)
	(arc
		(start 379.02769 -236.925612)
		(mid 378.85568 -236.972453)
		(end 378.681488 -236.934502)
		(width 0.088646)
		(layer "In4.Cu")
		(net "M_F_CPU0_SB_DQ<4>")
	)
	(arc
		(start 379.96749 -236.925612)
		(mid 379.782635 -236.972562)
		(end 379.598682 -236.92231)
		(width 0.088646)
		(layer "In4.Cu")
		(net "M_F_CPU0_SB_DQ<4>")
	)
	(arc
		(start 387.399784 -235.798106)
		(mid 387.320565 -236.072791)
		(end 387.117082 -236.273594)
		(width 0.088646)
		(layer "In4.Cu")
		(net "M_F_CPU0_SB_DQ<4>")
	)
	(arc
		(start 387.10235 -236.28223)
		(mid 386.825909 -236.349396)
		(end 386.551678 -236.273594)
		(width 0.088646)
		(layer "In4.Cu")
		(net "M_F_CPU0_SB_DQ<4>")
	)
	(arc
		(start 387.578346 -235.464604)
		(mid 387.447432 -235.600964)
		(end 387.399784 -235.783882)
		(width 0.088646)
		(layer "In4.Cu")
		(net "M_F_CPU0_SB_DQ<4>")
	)
	(arc
		(start 386.16255 -236.28223)
		(mid 385.886109 -236.349396)
		(end 385.611878 -236.273594)
		(width 0.088646)
		(layer "In4.Cu")
		(net "M_F_CPU0_SB_DQ<4>")
	)
	(arc
		(start 386.551678 -236.273594)
		(mid 386.36448 -236.223451)
		(end 386.177282 -236.273594)
		(width 0.088646)
		(layer "In4.Cu")
		(net "M_F_CPU0_SB_DQ<4>")
	)
	(arc
		(start 385.22275 -236.28223)
		(mid 384.946309 -236.349396)
		(end 384.672078 -236.273594)
		(width 0.088646)
		(layer "In4.Cu")
		(net "M_F_CPU0_SB_DQ<4>")
	)
	(arc
		(start 378.681488 -236.934502)
		(mid 378.641326 -236.915348)
		(end 378.600716 -236.897164)
		(width 0.088646)
		(layer "In4.Cu")
		(net "M_F_CPU0_SB_DQ<4>")
	)
	(arc
		(start 379.598682 -236.92231)
		(mid 379.319447 -236.855786)
		(end 379.039374 -236.918754)
		(width 0.088646)
		(layer "In4.Cu")
		(net "M_F_CPU0_SB_DQ<4>")
	)
	(arc
		(start 384.672078 -236.273594)
		(mid 384.48488 -236.223451)
		(end 384.297682 -236.273594)
		(width 0.088646)
		(layer "In4.Cu")
		(net "M_F_CPU0_SB_DQ<4>")
	)
	(arc
		(start 385.611878 -236.273594)
		(mid 385.42468 -236.223451)
		(end 385.237482 -236.273594)
		(width 0.088646)
		(layer "In4.Cu")
		(net "M_F_CPU0_SB_DQ<4>")
	)
	(arc
		(start 380.13132 -236.812582)
		(mid 380.058161 -236.868667)
		(end 379.980444 -236.918246)
		(width 0.088646)
		(layer "In4.Cu")
		(net "M_F_CPU0_SB_DQ<4>")
	)
	(arc
		(start 384.28295 -236.28223)
		(mid 384.006509 -236.349396)
		(end 383.732278 -236.273594)
		(width 0.088646)
		(layer "In4.Cu")
		(net "M_F_CPU0_SB_DQ<4>")
	)
	(arc
		(start 387.869684 -234.970066)
		(mid 387.795768 -235.249568)
		(end 387.593332 -235.455968)
		(width 0.088646)
		(layer "In4.Cu")
		(net "M_F_CPU0_SB_DQ<4>")
	)
	(arc
		(start 380.90856 -236.2708)
		(mid 380.623027 -236.237687)
		(end 380.39802 -236.416596)
		(width 0.088646)
		(layer "In4.Cu")
		(net "M_F_CPU0_SB_DQ<4>")
	)
	(arc
		(start 381.850392 -236.271816)
		(mid 381.664143 -236.223171)
		(end 381.478282 -236.27334)
		(width 0.088646)
		(layer "In4.Cu")
		(net "M_F_CPU0_SB_DQ<4>")
	)
	(arc
		(start 383.729992 -236.271816)
		(mid 383.543743 -236.223171)
		(end 383.357882 -236.27334)
		(width 0.088646)
		(layer "In4.Cu")
		(net "M_F_CPU0_SB_DQ<4>")
	)
	(segment
		(start 379.78588 -238.76127)
		(end 379.78588 -238.225584)
		(width 0.20066)
		(layer "F.Cu")
		(net "M_F_CPU0_SB_DQ<3>")
	)
	(segment
		(start 428.375064 -230.041704)
		(end 430.382934 -230.041704)
		(width 0.1016)
		(layer "F.Cu")
		(net "M_F_CPU0_SB_DQ<3>")
	)
	(segment
		(start 427.639226 -229.616762)
		(end 428.07128 -230.048816)
		(width 0.20066)
		(layer "F.Cu")
		(net "M_F_CPU0_SB_DQ<3>")
	)
	(segment
		(start 379.786134 -238.761524)
		(end 379.78588 -238.76127)
		(width 0.20066)
		(layer "F.Cu")
		(net "M_F_CPU0_SB_DQ<3>")
	)
	(segment
		(start 425.940982 -229.616762)
		(end 427.639226 -229.616762)
		(width 0.20066)
		(layer "F.Cu")
		(net "M_F_CPU0_SB_DQ<3>")
	)
	(segment
		(start 432.15052 -229.616762)
		(end 433.484782 -229.616762)
		(width 0.20066)
		(layer "F.Cu")
		(net "M_F_CPU0_SB_DQ<3>")
	)
	(segment
		(start 428.363126 -230.048816)
		(end 428.367952 -230.048816)
		(width 0.101854)
		(layer "F.Cu")
		(net "M_F_CPU0_SB_DQ<3>")
	)
	(segment
		(start 431.280316 -229.849934)
		(end 431.280316 -229.598982)
		(width 0.20066)
		(layer "F.Cu")
		(net "M_F_CPU0_SB_DQ<3>")
	)
	(segment
		(start 431.898552 -229.364794)
		(end 432.15052 -229.616762)
		(width 0.20066)
		(layer "F.Cu")
		(net "M_F_CPU0_SB_DQ<3>")
	)
	(segment
		(start 428.367952 -230.048816)
		(end 428.375064 -230.041704)
		(width 0.1016)
		(layer "F.Cu")
		(net "M_F_CPU0_SB_DQ<3>")
	)
	(segment
		(start 430.382934 -230.041704)
		(end 430.395126 -230.053896)
		(width 0.1016)
		(layer "F.Cu")
		(net "M_F_CPU0_SB_DQ<3>")
	)
	(segment
		(start 431.514504 -229.364794)
		(end 431.898552 -229.364794)
		(width 0.20066)
		(layer "F.Cu")
		(net "M_F_CPU0_SB_DQ<3>")
	)
	(segment
		(start 431.280316 -229.598982)
		(end 431.514504 -229.364794)
		(width 0.20066)
		(layer "F.Cu")
		(net "M_F_CPU0_SB_DQ<3>")
	)
	(segment
		(start 431.076354 -230.053896)
		(end 431.280316 -229.849934)
		(width 0.20066)
		(layer "F.Cu")
		(net "M_F_CPU0_SB_DQ<3>")
	)
	(segment
		(start 430.395126 -230.053896)
		(end 431.076354 -230.053896)
		(width 0.20066)
		(layer "F.Cu")
		(net "M_F_CPU0_SB_DQ<3>")
	)
	(segment
		(start 424.836082 -229.616762)
		(end 425.940982 -229.616762)
		(width 0.20066)
		(layer "F.Cu")
		(net "M_F_CPU0_SB_DQ<3>")
	)
	(segment
		(start 428.07128 -230.048816)
		(end 428.363126 -230.048816)
		(width 0.20066)
		(layer "F.Cu")
		(net "M_F_CPU0_SB_DQ<3>")
	)
	(segment
		(start 388.83082 -236.782102)
		(end 387.223 -238.389922)
		(width 0.088646)
		(layer "In4.Cu")
		(net "M_F_CPU0_SB_DQ<3>")
	)
	(segment
		(start 405.825198 -229.194106)
		(end 404.319232 -229.194106)
		(width 0.18288)
		(layer "In4.Cu")
		(net "M_F_CPU0_SB_DQ<3>")
	)
	(segment
		(start 390.001252 -236.782102)
		(end 388.941564 -236.782102)
		(width 0.18288)
		(layer "In4.Cu")
		(net "M_F_CPU0_SB_DQ<3>")
	)
	(segment
		(start 421.484044 -229.538022)
		(end 421.484044 -229.374954)
		(width 0.18288)
		(layer "In4.Cu")
		(net "M_F_CPU0_SB_DQ<3>")
	)
	(segment
		(start 423.879772 -229.616762)
		(end 423.455084 -229.192074)
		(width 0.18288)
		(layer "In4.Cu")
		(net "M_F_CPU0_SB_DQ<3>")
	)
	(segment
		(start 411.465014 -227.476812)
		(end 411.304994 -227.636832)
		(width 0.18288)
		(layer "In4.Cu")
		(net "M_F_CPU0_SB_DQ<3>")
	)
	(segment
		(start 421.666924 -229.720902)
		(end 421.484044 -229.538022)
		(width 0.18288)
		(layer "In4.Cu")
		(net "M_F_CPU0_SB_DQ<3>")
	)
	(segment
		(start 380.920498 -238.545624)
		(end 380.913132 -238.549942)
		(width 0.088646)
		(layer "In4.Cu")
		(net "M_F_CPU0_SB_DQ<3>")
	)
	(segment
		(start 396.905226 -234.344464)
		(end 392.43889 -234.344464)
		(width 0.18288)
		(layer "In4.Cu")
		(net "M_F_CPU0_SB_DQ<3>")
	)
	(segment
		(start 382.800098 -238.545624)
		(end 382.792732 -238.549942)
		(width 0.088646)
		(layer "In4.Cu")
		(net "M_F_CPU0_SB_DQ<3>")
	)
	(segment
		(start 381.852932 -238.549942)
		(end 381.850392 -238.551466)
		(width 0.088646)
		(layer "In4.Cu")
		(net "M_F_CPU0_SB_DQ<3>")
	)
	(segment
		(start 403.625812 -228.304598)
		(end 403.442932 -228.487478)
		(width 0.18288)
		(layer "In4.Cu")
		(net "M_F_CPU0_SB_DQ<3>")
	)
	(segment
		(start 387.223 -238.389922)
		(end 386.947664 -238.48568)
		(width 0.088646)
		(layer "In4.Cu")
		(net "M_F_CPU0_SB_DQ<3>")
	)
	(segment
		(start 404.136352 -228.487478)
		(end 403.953472 -228.304598)
		(width 0.18288)
		(layer "In4.Cu")
		(net "M_F_CPU0_SB_DQ<3>")
	)
	(segment
		(start 403.442932 -229.011226)
		(end 403.260052 -229.194106)
		(width 0.18288)
		(layer "In4.Cu")
		(net "M_F_CPU0_SB_DQ<3>")
	)
	(segment
		(start 413.705294 -227.697792)
		(end 413.545274 -227.537772)
		(width 0.18288)
		(layer "In4.Cu")
		(net "M_F_CPU0_SB_DQ<3>")
	)
	(segment
		(start 403.260052 -229.194106)
		(end 402.055584 -229.194106)
		(width 0.18288)
		(layer "In4.Cu")
		(net "M_F_CPU0_SB_DQ<3>")
	)
	(segment
		(start 415.566352 -228.624384)
		(end 414.164272 -228.624384)
		(width 0.18288)
		(layer "In4.Cu")
		(net "M_F_CPU0_SB_DQ<3>")
	)
	(segment
		(start 380.538482 -238.549942)
		(end 380.14148 -238.320834)
		(width 0.088646)
		(layer "In4.Cu")
		(net "M_F_CPU0_SB_DQ<3>")
	)
	(segment
		(start 422.360344 -229.192074)
		(end 422.177464 -229.374954)
		(width 0.18288)
		(layer "In4.Cu")
		(net "M_F_CPU0_SB_DQ<3>")
	)
	(segment
		(start 413.171894 -227.537772)
		(end 413.011874 -227.697792)
		(width 0.18288)
		(layer "In4.Cu")
		(net "M_F_CPU0_SB_DQ<3>")
	)
	(segment
		(start 411.304994 -227.636832)
		(end 411.304994 -228.165406)
		(width 0.18288)
		(layer "In4.Cu")
		(net "M_F_CPU0_SB_DQ<3>")
	)
	(segment
		(start 411.838394 -227.476812)
		(end 411.465014 -227.476812)
		(width 0.18288)
		(layer "In4.Cu")
		(net "M_F_CPU0_SB_DQ<3>")
	)
	(segment
		(start 383.732532 -238.549942)
		(end 383.729992 -238.551466)
		(width 0.088646)
		(layer "In4.Cu")
		(net "M_F_CPU0_SB_DQ<3>")
	)
	(segment
		(start 404.136352 -229.011226)
		(end 404.136352 -228.487478)
		(width 0.18288)
		(layer "In4.Cu")
		(net "M_F_CPU0_SB_DQ<3>")
	)
	(segment
		(start 413.011874 -228.165406)
		(end 412.851854 -228.325426)
		(width 0.18288)
		(layer "In4.Cu")
		(net "M_F_CPU0_SB_DQ<3>")
	)
	(segment
		(start 403.953472 -228.304598)
		(end 403.625812 -228.304598)
		(width 0.18288)
		(layer "In4.Cu")
		(net "M_F_CPU0_SB_DQ<3>")
	)
	(segment
		(start 411.128464 -228.341936)
		(end 409.50515 -228.341936)
		(width 0.18288)
		(layer "In4.Cu")
		(net "M_F_CPU0_SB_DQ<3>")
	)
	(segment
		(start 411.998414 -228.165406)
		(end 411.998414 -227.636832)
		(width 0.18288)
		(layer "In4.Cu")
		(net "M_F_CPU0_SB_DQ<3>")
	)
	(segment
		(start 408.75204 -227.588826)
		(end 407.430478 -227.588826)
		(width 0.18288)
		(layer "In4.Cu")
		(net "M_F_CPU0_SB_DQ<3>")
	)
	(segment
		(start 416.134042 -229.192074)
		(end 415.566352 -228.624384)
		(width 0.18288)
		(layer "In4.Cu")
		(net "M_F_CPU0_SB_DQ<3>")
	)
	(segment
		(start 422.177464 -229.374954)
		(end 422.177464 -229.538022)
		(width 0.18288)
		(layer "In4.Cu")
		(net "M_F_CPU0_SB_DQ<3>")
	)
	(segment
		(start 413.011874 -227.697792)
		(end 413.011874 -228.165406)
		(width 0.18288)
		(layer "In4.Cu")
		(net "M_F_CPU0_SB_DQ<3>")
	)
	(segment
		(start 412.851854 -228.325426)
		(end 412.158434 -228.325426)
		(width 0.18288)
		(layer "In4.Cu")
		(net "M_F_CPU0_SB_DQ<3>")
	)
	(segment
		(start 402.055584 -229.194106)
		(end 396.905226 -234.344464)
		(width 0.18288)
		(layer "In4.Cu")
		(net "M_F_CPU0_SB_DQ<3>")
	)
	(segment
		(start 412.158434 -228.325426)
		(end 411.998414 -228.165406)
		(width 0.18288)
		(layer "In4.Cu")
		(net "M_F_CPU0_SB_DQ<3>")
	)
	(segment
		(start 421.484044 -229.374954)
		(end 421.301164 -229.192074)
		(width 0.18288)
		(layer "In4.Cu")
		(net "M_F_CPU0_SB_DQ<3>")
	)
	(segment
		(start 421.994584 -229.720902)
		(end 421.666924 -229.720902)
		(width 0.18288)
		(layer "In4.Cu")
		(net "M_F_CPU0_SB_DQ<3>")
	)
	(segment
		(start 392.43889 -234.344464)
		(end 390.001252 -236.782102)
		(width 0.18288)
		(layer "In4.Cu")
		(net "M_F_CPU0_SB_DQ<3>")
	)
	(segment
		(start 424.836082 -229.616762)
		(end 423.879772 -229.616762)
		(width 0.18288)
		(layer "In4.Cu")
		(net "M_F_CPU0_SB_DQ<3>")
	)
	(segment
		(start 388.941564 -236.782102)
		(end 388.83082 -236.782102)
		(width 0.088646)
		(layer "In4.Cu")
		(net "M_F_CPU0_SB_DQ<3>")
	)
	(segment
		(start 414.164272 -228.624384)
		(end 413.705294 -228.165406)
		(width 0.18288)
		(layer "In4.Cu")
		(net "M_F_CPU0_SB_DQ<3>")
	)
	(segment
		(start 411.998414 -227.636832)
		(end 411.838394 -227.476812)
		(width 0.18288)
		(layer "In4.Cu")
		(net "M_F_CPU0_SB_DQ<3>")
	)
	(segment
		(start 413.545274 -227.537772)
		(end 413.171894 -227.537772)
		(width 0.18288)
		(layer "In4.Cu")
		(net "M_F_CPU0_SB_DQ<3>")
	)
	(segment
		(start 411.304994 -228.165406)
		(end 411.128464 -228.341936)
		(width 0.18288)
		(layer "In4.Cu")
		(net "M_F_CPU0_SB_DQ<3>")
	)
	(segment
		(start 404.319232 -229.194106)
		(end 404.136352 -229.011226)
		(width 0.18288)
		(layer "In4.Cu")
		(net "M_F_CPU0_SB_DQ<3>")
	)
	(segment
		(start 422.177464 -229.538022)
		(end 421.994584 -229.720902)
		(width 0.18288)
		(layer "In4.Cu")
		(net "M_F_CPU0_SB_DQ<3>")
	)
	(segment
		(start 421.301164 -229.192074)
		(end 416.134042 -229.192074)
		(width 0.18288)
		(layer "In4.Cu")
		(net "M_F_CPU0_SB_DQ<3>")
	)
	(segment
		(start 407.430478 -227.588826)
		(end 405.825198 -229.194106)
		(width 0.18288)
		(layer "In4.Cu")
		(net "M_F_CPU0_SB_DQ<3>")
	)
	(segment
		(start 413.705294 -228.165406)
		(end 413.705294 -227.697792)
		(width 0.18288)
		(layer "In4.Cu")
		(net "M_F_CPU0_SB_DQ<3>")
	)
	(segment
		(start 409.50515 -228.341936)
		(end 408.75204 -227.588826)
		(width 0.18288)
		(layer "In4.Cu")
		(net "M_F_CPU0_SB_DQ<3>")
	)
	(segment
		(start 403.442932 -228.487478)
		(end 403.442932 -229.011226)
		(width 0.18288)
		(layer "In4.Cu")
		(net "M_F_CPU0_SB_DQ<3>")
	)
	(segment
		(start 423.455084 -229.192074)
		(end 422.360344 -229.192074)
		(width 0.18288)
		(layer "In4.Cu")
		(net "M_F_CPU0_SB_DQ<3>")
	)
	(segment
		(start 380.913132 -238.549942)
		(end 380.90856 -238.552736)
		(width 0.088646)
		(layer "In4.Cu")
		(net "M_F_CPU0_SB_DQ<3>")
	)
	(segment
		(start 382.792732 -238.549942)
		(end 382.788922 -238.552228)
		(width 0.088646)
		(layer "In4.Cu")
		(net "M_F_CPU0_SB_DQ<3>")
	)
	(arc
		(start 381.478282 -238.549942)
		(mid 381.199959 -238.474183)
		(end 380.920498 -238.545624)
		(width 0.088646)
		(layer "In4.Cu")
		(net "M_F_CPU0_SB_DQ<3>")
	)
	(arc
		(start 385.237736 -238.549942)
		(mid 384.955034 -238.474166)
		(end 384.672332 -238.549942)
		(width 0.088646)
		(layer "In4.Cu")
		(net "M_F_CPU0_SB_DQ<3>")
	)
	(arc
		(start 386.551932 -238.549942)
		(mid 386.364734 -238.600085)
		(end 386.177536 -238.549942)
		(width 0.088646)
		(layer "In4.Cu")
		(net "M_F_CPU0_SB_DQ<3>")
	)
	(arc
		(start 382.418082 -238.549942)
		(mid 382.135524 -238.474293)
		(end 381.852932 -238.549942)
		(width 0.088646)
		(layer "In4.Cu")
		(net "M_F_CPU0_SB_DQ<3>")
	)
	(arc
		(start 380.90856 -238.552736)
		(mid 380.723146 -238.600248)
		(end 380.538482 -238.549942)
		(width 0.088646)
		(layer "In4.Cu")
		(net "M_F_CPU0_SB_DQ<3>")
	)
	(arc
		(start 386.177536 -238.549942)
		(mid 385.894834 -238.474166)
		(end 385.612132 -238.549942)
		(width 0.088646)
		(layer "In4.Cu")
		(net "M_F_CPU0_SB_DQ<3>")
	)
	(arc
		(start 382.788922 -238.552228)
		(mid 382.603203 -238.60018)
		(end 382.418082 -238.549942)
		(width 0.088646)
		(layer "In4.Cu")
		(net "M_F_CPU0_SB_DQ<3>")
	)
	(arc
		(start 383.357882 -238.549942)
		(mid 383.079559 -238.474183)
		(end 382.800098 -238.545624)
		(width 0.088646)
		(layer "In4.Cu")
		(net "M_F_CPU0_SB_DQ<3>")
	)
	(arc
		(start 385.612132 -238.549942)
		(mid 385.424934 -238.600085)
		(end 385.237736 -238.549942)
		(width 0.088646)
		(layer "In4.Cu")
		(net "M_F_CPU0_SB_DQ<3>")
	)
	(arc
		(start 381.850392 -238.551466)
		(mid 381.664143 -238.600144)
		(end 381.478282 -238.549942)
		(width 0.088646)
		(layer "In4.Cu")
		(net "M_F_CPU0_SB_DQ<3>")
	)
	(arc
		(start 384.297936 -238.549942)
		(mid 384.015234 -238.474166)
		(end 383.732532 -238.549942)
		(width 0.088646)
		(layer "In4.Cu")
		(net "M_F_CPU0_SB_DQ<3>")
	)
	(arc
		(start 380.14148 -238.320834)
		(mid 379.969943 -238.249838)
		(end 379.78588 -238.225584)
		(width 0.088646)
		(layer "In4.Cu")
		(net "M_F_CPU0_SB_DQ<3>")
	)
	(arc
		(start 383.729992 -238.551466)
		(mid 383.543743 -238.600144)
		(end 383.357882 -238.549942)
		(width 0.088646)
		(layer "In4.Cu")
		(net "M_F_CPU0_SB_DQ<3>")
	)
	(arc
		(start 386.947664 -238.48568)
		(mid 386.743894 -238.481501)
		(end 386.551932 -238.549942)
		(width 0.088646)
		(layer "In4.Cu")
		(net "M_F_CPU0_SB_DQ<3>")
	)
	(arc
		(start 384.672332 -238.549942)
		(mid 384.485134 -238.600085)
		(end 384.297936 -238.549942)
		(width 0.088646)
		(layer "In4.Cu")
		(net "M_F_CPU0_SB_DQ<3>")
	)
	(segment
		(start 431.898552 -195.364608)
		(end 432.15052 -195.616576)
		(width 0.20066)
		(layer "F.Cu")
		(net "M_F_CPU0_SB_DQ<31>")
	)
	(segment
		(start 428.367952 -196.04863)
		(end 428.375064 -196.041518)
		(width 0.1016)
		(layer "F.Cu")
		(net "M_F_CPU0_SB_DQ<31>")
	)
	(segment
		(start 428.363126 -196.04863)
		(end 428.367952 -196.04863)
		(width 0.101854)
		(layer "F.Cu")
		(net "M_F_CPU0_SB_DQ<31>")
	)
	(segment
		(start 427.639226 -195.616576)
		(end 428.07128 -196.04863)
		(width 0.20066)
		(layer "F.Cu")
		(net "M_F_CPU0_SB_DQ<31>")
	)
	(segment
		(start 430.382934 -196.041518)
		(end 430.395126 -196.05371)
		(width 0.1016)
		(layer "F.Cu")
		(net "M_F_CPU0_SB_DQ<31>")
	)
	(segment
		(start 432.15052 -195.616576)
		(end 433.484782 -195.616576)
		(width 0.20066)
		(layer "F.Cu")
		(net "M_F_CPU0_SB_DQ<31>")
	)
	(segment
		(start 431.280316 -195.598796)
		(end 431.514504 -195.364608)
		(width 0.20066)
		(layer "F.Cu")
		(net "M_F_CPU0_SB_DQ<31>")
	)
	(segment
		(start 431.076354 -196.05371)
		(end 431.280316 -195.849748)
		(width 0.20066)
		(layer "F.Cu")
		(net "M_F_CPU0_SB_DQ<31>")
	)
	(segment
		(start 430.395126 -196.05371)
		(end 431.076354 -196.05371)
		(width 0.20066)
		(layer "F.Cu")
		(net "M_F_CPU0_SB_DQ<31>")
	)
	(segment
		(start 425.940982 -195.616576)
		(end 427.639226 -195.616576)
		(width 0.20066)
		(layer "F.Cu")
		(net "M_F_CPU0_SB_DQ<31>")
	)
	(segment
		(start 428.07128 -196.04863)
		(end 428.363126 -196.04863)
		(width 0.20066)
		(layer "F.Cu")
		(net "M_F_CPU0_SB_DQ<31>")
	)
	(segment
		(start 431.514504 -195.364608)
		(end 431.898552 -195.364608)
		(width 0.20066)
		(layer "F.Cu")
		(net "M_F_CPU0_SB_DQ<31>")
	)
	(segment
		(start 431.280316 -195.849748)
		(end 431.280316 -195.598796)
		(width 0.20066)
		(layer "F.Cu")
		(net "M_F_CPU0_SB_DQ<31>")
	)
	(segment
		(start 376.96648 -227.36683)
		(end 376.96648 -226.831144)
		(width 0.20066)
		(layer "F.Cu")
		(net "M_F_CPU0_SB_DQ<31>")
	)
	(segment
		(start 428.375064 -196.041518)
		(end 430.382934 -196.041518)
		(width 0.1016)
		(layer "F.Cu")
		(net "M_F_CPU0_SB_DQ<31>")
	)
	(segment
		(start 424.836082 -195.616576)
		(end 425.940982 -195.616576)
		(width 0.20066)
		(layer "F.Cu")
		(net "M_F_CPU0_SB_DQ<31>")
	)
	(segment
		(start 376.966734 -227.367084)
		(end 376.96648 -227.36683)
		(width 0.20066)
		(layer "F.Cu")
		(net "M_F_CPU0_SB_DQ<31>")
	)
	(segment
		(start 379.981968 -222.267018)
		(end 379.973078 -222.272098)
		(width 0.088646)
		(layer "In4.Cu")
		(net "M_F_CPU0_SB_DQ<31>")
	)
	(segment
		(start 378.751084 -222.746062)
		(end 378.751084 -222.761556)
		(width 0.088646)
		(layer "In4.Cu")
		(net "M_F_CPU0_SB_DQ<31>")
	)
	(segment
		(start 382.510284 -219.496132)
		(end 382.510284 -219.506038)
		(width 0.088646)
		(layer "In4.Cu")
		(net "M_F_CPU0_SB_DQ<31>")
	)
	(segment
		(start 378.093478 -224.8789)
		(end 378.102368 -224.88398)
		(width 0.088646)
		(layer "In4.Cu")
		(net "M_F_CPU0_SB_DQ<31>")
	)
	(segment
		(start 424.836082 -195.616576)
		(end 423.627804 -195.273676)
		(width 0.18288)
		(layer "In4.Cu")
		(net "M_F_CPU0_SB_DQ<31>")
	)
	(segment
		(start 380.440438 -221.459806)
		(end 380.437136 -221.461838)
		(width 0.088646)
		(layer "In4.Cu")
		(net "M_F_CPU0_SB_DQ<31>")
	)
	(segment
		(start 387.493256 -218.093544)
		(end 387.362192 -218.093544)
		(width 0.088646)
		(layer "In4.Cu")
		(net "M_F_CPU0_SB_DQ<31>")
	)
	(segment
		(start 381.100584 -220.309948)
		(end 381.100584 -220.319854)
		(width 0.088646)
		(layer "In4.Cu")
		(net "M_F_CPU0_SB_DQ<31>")
	)
	(segment
		(start 395.613636 -210.211162)
		(end 395.613636 -210.212178)
		(width 0.18288)
		(layer "In4.Cu")
		(net "M_F_CPU0_SB_DQ<31>")
	)
	(segment
		(start 387.73227 -218.093544)
		(end 387.493256 -218.093544)
		(width 0.18288)
		(layer "In4.Cu")
		(net "M_F_CPU0_SB_DQ<31>")
	)
	(segment
		(start 380.630684 -221.115382)
		(end 380.630684 -221.133924)
		(width 0.088646)
		(layer "In4.Cu")
		(net "M_F_CPU0_SB_DQ<31>")
	)
	(segment
		(start 418.11575 -194.531488)
		(end 417.38169 -194.347592)
		(width 0.18288)
		(layer "In4.Cu")
		(net "M_F_CPU0_SB_DQ<31>")
	)
	(segment
		(start 423.627804 -195.273676)
		(end 423.03192 -195.190872)
		(width 0.18288)
		(layer "In4.Cu")
		(net "M_F_CPU0_SB_DQ<31>")
	)
	(segment
		(start 384.687064 -219.007944)
		(end 384.672332 -219.01658)
		(width 0.088646)
		(layer "In4.Cu")
		(net "M_F_CPU0_SB_DQ<31>")
	)
	(segment
		(start 382.331722 -219.825316)
		(end 382.322832 -219.830396)
		(width 0.088646)
		(layer "In4.Cu")
		(net "M_F_CPU0_SB_DQ<31>")
	)
	(segment
		(start 387.109208 -218.346528)
		(end 386.845048 -218.741752)
		(width 0.088646)
		(layer "In4.Cu")
		(net "M_F_CPU0_SB_DQ<31>")
	)
	(segment
		(start 408.013662 -196.026786)
		(end 406.572974 -196.204586)
		(width 0.18288)
		(layer "In4.Cu")
		(net "M_F_CPU0_SB_DQ<31>")
	)
	(segment
		(start 412.226252 -194.26047)
		(end 411.729174 -194.38493)
		(width 0.18288)
		(layer "In4.Cu")
		(net "M_F_CPU0_SB_DQ<31>")
	)
	(segment
		(start 386.845048 -218.741752)
		(end 386.629656 -218.957144)
		(width 0.088646)
		(layer "In4.Cu")
		(net "M_F_CPU0_SB_DQ<31>")
	)
	(segment
		(start 378.102368 -223.894904)
		(end 378.093478 -223.899984)
		(width 0.088646)
		(layer "In4.Cu")
		(net "M_F_CPU0_SB_DQ<31>")
	)
	(segment
		(start 379.598682 -222.272098)
		(end 379.58395 -222.263462)
		(width 0.088646)
		(layer "In4.Cu")
		(net "M_F_CPU0_SB_DQ<31>")
	)
	(segment
		(start 378.572522 -223.080834)
		(end 378.563632 -223.085914)
		(width 0.088646)
		(layer "In4.Cu")
		(net "M_F_CPU0_SB_DQ<31>")
	)
	(segment
		(start 377.811284 -224.373948)
		(end 377.811284 -224.404936)
		(width 0.088646)
		(layer "In4.Cu")
		(net "M_F_CPU0_SB_DQ<31>")
	)
	(segment
		(start 395.613636 -210.212178)
		(end 387.73227 -218.093544)
		(width 0.18288)
		(layer "In4.Cu")
		(net "M_F_CPU0_SB_DQ<31>")
	)
	(segment
		(start 377.623832 -226.341686)
		(end 377.617736 -226.345242)
		(width 0.088646)
		(layer "In4.Cu")
		(net "M_F_CPU0_SB_DQ<31>")
	)
	(segment
		(start 404.951946 -196.524118)
		(end 401.054824 -200.442322)
		(width 0.18288)
		(layer "In4.Cu")
		(net "M_F_CPU0_SB_DQ<31>")
	)
	(segment
		(start 401.054824 -200.442322)
		(end 397.385032 -205.935326)
		(width 0.18288)
		(layer "In4.Cu")
		(net "M_F_CPU0_SB_DQ<31>")
	)
	(segment
		(start 423.03192 -195.190872)
		(end 419.349936 -195.190872)
		(width 0.18288)
		(layer "In4.Cu")
		(net "M_F_CPU0_SB_DQ<31>")
	)
	(segment
		(start 380.922022 -220.639132)
		(end 380.913132 -220.644212)
		(width 0.088646)
		(layer "In4.Cu")
		(net "M_F_CPU0_SB_DQ<31>")
	)
	(segment
		(start 377.279408 -226.831144)
		(end 376.96648 -226.831144)
		(width 0.088646)
		(layer "In4.Cu")
		(net "M_F_CPU0_SB_DQ<31>")
	)
	(segment
		(start 380.452122 -221.453202)
		(end 380.443232 -221.458282)
		(width 0.088646)
		(layer "In4.Cu")
		(net "M_F_CPU0_SB_DQ<31>")
	)
	(segment
		(start 387.362192 -218.093544)
		(end 387.109208 -218.346528)
		(width 0.088646)
		(layer "In4.Cu")
		(net "M_F_CPU0_SB_DQ<31>")
	)
	(segment
		(start 419.349936 -195.190872)
		(end 418.11575 -194.531488)
		(width 0.18288)
		(layer "In4.Cu")
		(net "M_F_CPU0_SB_DQ<31>")
	)
	(segment
		(start 377.632722 -226.336606)
		(end 377.623832 -226.341686)
		(width 0.088646)
		(layer "In4.Cu")
		(net "M_F_CPU0_SB_DQ<31>")
	)
	(segment
		(start 377.34494 -226.765612)
		(end 377.279408 -226.831144)
		(width 0.088646)
		(layer "In4.Cu")
		(net "M_F_CPU0_SB_DQ<31>")
	)
	(segment
		(start 411.729174 -194.38493)
		(end 410.324046 -195.135754)
		(width 0.18288)
		(layer "In4.Cu")
		(net "M_F_CPU0_SB_DQ<31>")
	)
	(segment
		(start 378.28093 -223.568006)
		(end 378.28093 -223.575626)
		(width 0.088646)
		(layer "In4.Cu")
		(net "M_F_CPU0_SB_DQ<31>")
	)
	(segment
		(start 406.572974 -196.204586)
		(end 405.572722 -196.266054)
		(width 0.18288)
		(layer "In4.Cu")
		(net "M_F_CPU0_SB_DQ<31>")
	)
	(segment
		(start 377.811284 -225.99523)
		(end 377.811284 -226.017328)
		(width 0.088646)
		(layer "In4.Cu")
		(net "M_F_CPU0_SB_DQ<31>")
	)
	(segment
		(start 405.572722 -196.266054)
		(end 404.951946 -196.524118)
		(width 0.18288)
		(layer "In4.Cu")
		(net "M_F_CPU0_SB_DQ<31>")
	)
	(segment
		(start 378.102368 -225.522536)
		(end 378.093478 -225.527616)
		(width 0.088646)
		(layer "In4.Cu")
		(net "M_F_CPU0_SB_DQ<31>")
	)
	(segment
		(start 385.626864 -219.007944)
		(end 385.612132 -219.01658)
		(width 0.088646)
		(layer "In4.Cu")
		(net "M_F_CPU0_SB_DQ<31>")
	)
	(segment
		(start 380.443232 -221.458282)
		(end 380.440438 -221.459806)
		(width 0.088646)
		(layer "In4.Cu")
		(net "M_F_CPU0_SB_DQ<31>")
	)
	(segment
		(start 397.385032 -205.935326)
		(end 395.613636 -210.211162)
		(width 0.18288)
		(layer "In4.Cu")
		(net "M_F_CPU0_SB_DQ<31>")
	)
	(segment
		(start 417.38169 -194.347592)
		(end 416.6743 -194.26047)
		(width 0.18288)
		(layer "In4.Cu")
		(net "M_F_CPU0_SB_DQ<31>")
	)
	(segment
		(start 410.324046 -195.135754)
		(end 408.013662 -196.026786)
		(width 0.18288)
		(layer "In4.Cu")
		(net "M_F_CPU0_SB_DQ<31>")
	)
	(segment
		(start 416.6743 -194.26047)
		(end 412.226252 -194.26047)
		(width 0.18288)
		(layer "In4.Cu")
		(net "M_F_CPU0_SB_DQ<31>")
	)
	(arc
		(start 383.732532 -219.01658)
		(mid 383.545334 -219.066723)
		(end 383.358136 -219.01658)
		(width 0.088646)
		(layer "In4.Cu")
		(net "M_F_CPU0_SB_DQ<31>")
	)
	(arc
		(start 378.093478 -225.527616)
		(mid 377.892196 -225.725103)
		(end 377.811284 -225.99523)
		(width 0.088646)
		(layer "In4.Cu")
		(net "M_F_CPU0_SB_DQ<31>")
	)
	(arc
		(start 381.948436 -219.830396)
		(mid 381.665734 -219.75462)
		(end 381.383032 -219.830396)
		(width 0.088646)
		(layer "In4.Cu")
		(net "M_F_CPU0_SB_DQ<31>")
	)
	(arc
		(start 385.612132 -219.01658)
		(mid 385.424934 -219.066723)
		(end 385.237736 -219.01658)
		(width 0.088646)
		(layer "In4.Cu")
		(net "M_F_CPU0_SB_DQ<31>")
	)
	(arc
		(start 386.551932 -219.01658)
		(mid 386.364734 -219.066723)
		(end 386.177536 -219.01658)
		(width 0.088646)
		(layer "In4.Cu")
		(net "M_F_CPU0_SB_DQ<31>")
	)
	(arc
		(start 381.100584 -220.319854)
		(mid 381.052905 -220.502754)
		(end 380.922022 -220.639132)
		(width 0.088646)
		(layer "In4.Cu")
		(net "M_F_CPU0_SB_DQ<31>")
	)
	(arc
		(start 379.033278 -222.272098)
		(mid 378.830455 -222.472329)
		(end 378.751084 -222.746062)
		(width 0.088646)
		(layer "In4.Cu")
		(net "M_F_CPU0_SB_DQ<31>")
	)
	(arc
		(start 378.093478 -223.899984)
		(mid 377.890655 -224.100215)
		(end 377.811284 -224.373948)
		(width 0.088646)
		(layer "In4.Cu")
		(net "M_F_CPU0_SB_DQ<31>")
	)
	(arc
		(start 377.811284 -224.404936)
		(mid 377.890654 -224.67867)
		(end 378.093478 -224.8789)
		(width 0.088646)
		(layer "In4.Cu")
		(net "M_F_CPU0_SB_DQ<31>")
	)
	(arc
		(start 382.322832 -219.830396)
		(mid 382.135634 -219.880539)
		(end 381.948436 -219.830396)
		(width 0.088646)
		(layer "In4.Cu")
		(net "M_F_CPU0_SB_DQ<31>")
	)
	(arc
		(start 379.973078 -222.272098)
		(mid 379.78588 -222.322241)
		(end 379.598682 -222.272098)
		(width 0.088646)
		(layer "In4.Cu")
		(net "M_F_CPU0_SB_DQ<31>")
	)
	(arc
		(start 378.28093 -223.575626)
		(mid 378.233251 -223.758526)
		(end 378.102368 -223.894904)
		(width 0.088646)
		(layer "In4.Cu")
		(net "M_F_CPU0_SB_DQ<31>")
	)
	(arc
		(start 378.563632 -223.085914)
		(mid 378.35856 -223.289593)
		(end 378.28093 -223.568006)
		(width 0.088646)
		(layer "In4.Cu")
		(net "M_F_CPU0_SB_DQ<31>")
	)
	(arc
		(start 382.792732 -219.01658)
		(mid 382.588397 -219.219185)
		(end 382.510284 -219.496132)
		(width 0.088646)
		(layer "In4.Cu")
		(net "M_F_CPU0_SB_DQ<31>")
	)
	(arc
		(start 383.358136 -219.01658)
		(mid 383.075434 -218.940804)
		(end 382.792732 -219.01658)
		(width 0.088646)
		(layer "In4.Cu")
		(net "M_F_CPU0_SB_DQ<31>")
	)
	(arc
		(start 378.751084 -222.761556)
		(mid 378.703405 -222.944456)
		(end 378.572522 -223.080834)
		(width 0.088646)
		(layer "In4.Cu")
		(net "M_F_CPU0_SB_DQ<31>")
	)
	(arc
		(start 380.437136 -221.461838)
		(mid 380.234549 -221.668189)
		(end 380.16053 -221.94774)
		(width 0.088646)
		(layer "In4.Cu")
		(net "M_F_CPU0_SB_DQ<31>")
	)
	(arc
		(start 378.102368 -224.88398)
		(mid 378.280965 -225.203258)
		(end 378.102368 -225.522536)
		(width 0.088646)
		(layer "In4.Cu")
		(net "M_F_CPU0_SB_DQ<31>")
	)
	(arc
		(start 380.630684 -221.133924)
		(mid 380.583005 -221.316824)
		(end 380.452122 -221.453202)
		(width 0.088646)
		(layer "In4.Cu")
		(net "M_F_CPU0_SB_DQ<31>")
	)
	(arc
		(start 379.58395 -222.263462)
		(mid 379.307475 -222.196142)
		(end 379.033278 -222.272098)
		(width 0.088646)
		(layer "In4.Cu")
		(net "M_F_CPU0_SB_DQ<31>")
	)
	(arc
		(start 380.913132 -220.644212)
		(mid 380.710846 -220.843193)
		(end 380.630684 -221.115382)
		(width 0.088646)
		(layer "In4.Cu")
		(net "M_F_CPU0_SB_DQ<31>")
	)
	(arc
		(start 382.510284 -219.506038)
		(mid 382.462605 -219.688938)
		(end 382.331722 -219.825316)
		(width 0.088646)
		(layer "In4.Cu")
		(net "M_F_CPU0_SB_DQ<31>")
	)
	(arc
		(start 381.383032 -219.830396)
		(mid 381.178697 -220.033001)
		(end 381.100584 -220.309948)
		(width 0.088646)
		(layer "In4.Cu")
		(net "M_F_CPU0_SB_DQ<31>")
	)
	(arc
		(start 377.811284 -226.017328)
		(mid 377.763605 -226.200228)
		(end 377.632722 -226.336606)
		(width 0.088646)
		(layer "In4.Cu")
		(net "M_F_CPU0_SB_DQ<31>")
	)
	(arc
		(start 377.617736 -226.345242)
		(mid 377.432213 -226.523543)
		(end 377.34494 -226.765612)
		(width 0.088646)
		(layer "In4.Cu")
		(net "M_F_CPU0_SB_DQ<31>")
	)
	(arc
		(start 386.177536 -219.01658)
		(mid 385.903337 -218.940745)
		(end 385.626864 -219.007944)
		(width 0.088646)
		(layer "In4.Cu")
		(net "M_F_CPU0_SB_DQ<31>")
	)
	(arc
		(start 380.16053 -221.94774)
		(mid 380.112851 -222.13064)
		(end 379.981968 -222.267018)
		(width 0.088646)
		(layer "In4.Cu")
		(net "M_F_CPU0_SB_DQ<31>")
	)
	(arc
		(start 384.297936 -219.01658)
		(mid 384.015234 -218.940804)
		(end 383.732532 -219.01658)
		(width 0.088646)
		(layer "In4.Cu")
		(net "M_F_CPU0_SB_DQ<31>")
	)
	(arc
		(start 385.237736 -219.01658)
		(mid 384.963537 -218.940745)
		(end 384.687064 -219.007944)
		(width 0.088646)
		(layer "In4.Cu")
		(net "M_F_CPU0_SB_DQ<31>")
	)
	(arc
		(start 386.629656 -218.957144)
		(mid 386.592746 -218.989415)
		(end 386.551932 -219.01658)
		(width 0.088646)
		(layer "In4.Cu")
		(net "M_F_CPU0_SB_DQ<31>")
	)
	(arc
		(start 384.672332 -219.01658)
		(mid 384.485134 -219.066723)
		(end 384.297936 -219.01658)
		(width 0.088646)
		(layer "In4.Cu")
		(net "M_F_CPU0_SB_DQ<31>")
	)
	(segment
		(start 380.725934 -227.367084)
		(end 380.72568 -227.36683)
		(width 0.20066)
		(layer "F.Cu")
		(net "M_F_CPU0_SB_DQ<30>")
	)
	(segment
		(start 431.280316 -197.298818)
		(end 431.514504 -197.06463)
		(width 0.20066)
		(layer "F.Cu")
		(net "M_F_CPU0_SB_DQ<30>")
	)
	(segment
		(start 430.382934 -197.74154)
		(end 430.395126 -197.753732)
		(width 0.1016)
		(layer "F.Cu")
		(net "M_F_CPU0_SB_DQ<30>")
	)
	(segment
		(start 428.367952 -197.748652)
		(end 428.375064 -197.74154)
		(width 0.1016)
		(layer "F.Cu")
		(net "M_F_CPU0_SB_DQ<30>")
	)
	(segment
		(start 427.639226 -197.316598)
		(end 428.07128 -197.748652)
		(width 0.20066)
		(layer "F.Cu")
		(net "M_F_CPU0_SB_DQ<30>")
	)
	(segment
		(start 380.72568 -227.36683)
		(end 380.72568 -226.831144)
		(width 0.20066)
		(layer "F.Cu")
		(net "M_F_CPU0_SB_DQ<30>")
	)
	(segment
		(start 431.898552 -197.06463)
		(end 432.15052 -197.316598)
		(width 0.20066)
		(layer "F.Cu")
		(net "M_F_CPU0_SB_DQ<30>")
	)
	(segment
		(start 425.940982 -197.316598)
		(end 427.639226 -197.316598)
		(width 0.20066)
		(layer "F.Cu")
		(net "M_F_CPU0_SB_DQ<30>")
	)
	(segment
		(start 424.836082 -197.316598)
		(end 425.940982 -197.316598)
		(width 0.20066)
		(layer "F.Cu")
		(net "M_F_CPU0_SB_DQ<30>")
	)
	(segment
		(start 428.07128 -197.748652)
		(end 428.363126 -197.748652)
		(width 0.20066)
		(layer "F.Cu")
		(net "M_F_CPU0_SB_DQ<30>")
	)
	(segment
		(start 432.15052 -197.316598)
		(end 433.484782 -197.316598)
		(width 0.20066)
		(layer "F.Cu")
		(net "M_F_CPU0_SB_DQ<30>")
	)
	(segment
		(start 428.363126 -197.748652)
		(end 428.367952 -197.748652)
		(width 0.101854)
		(layer "F.Cu")
		(net "M_F_CPU0_SB_DQ<30>")
	)
	(segment
		(start 430.395126 -197.753732)
		(end 431.076354 -197.753732)
		(width 0.20066)
		(layer "F.Cu")
		(net "M_F_CPU0_SB_DQ<30>")
	)
	(segment
		(start 428.375064 -197.74154)
		(end 430.382934 -197.74154)
		(width 0.1016)
		(layer "F.Cu")
		(net "M_F_CPU0_SB_DQ<30>")
	)
	(segment
		(start 431.280316 -197.54977)
		(end 431.280316 -197.298818)
		(width 0.20066)
		(layer "F.Cu")
		(net "M_F_CPU0_SB_DQ<30>")
	)
	(segment
		(start 431.076354 -197.753732)
		(end 431.280316 -197.54977)
		(width 0.20066)
		(layer "F.Cu")
		(net "M_F_CPU0_SB_DQ<30>")
	)
	(segment
		(start 431.514504 -197.06463)
		(end 431.898552 -197.06463)
		(width 0.20066)
		(layer "F.Cu")
		(net "M_F_CPU0_SB_DQ<30>")
	)
	(segment
		(start 380.059946 -224.70872)
		(end 380.068836 -224.7138)
		(width 0.088646)
		(layer "In4.Cu")
		(net "M_F_CPU0_SB_DQ<30>")
	)
	(segment
		(start 383.358136 -219.995496)
		(end 383.349246 -220.000576)
		(width 0.088646)
		(layer "In4.Cu")
		(net "M_F_CPU0_SB_DQ<30>")
	)
	(segment
		(start 399.30578 -205.909164)
		(end 397.354806 -210.619594)
		(width 0.18288)
		(layer "In4.Cu")
		(net "M_F_CPU0_SB_DQ<30>")
	)
	(segment
		(start 388.182358 -219.791788)
		(end 387.69671 -219.791788)
		(width 0.18288)
		(layer "In4.Cu")
		(net "M_F_CPU0_SB_DQ<30>")
	)
	(segment
		(start 382.424178 -221.619826)
		(end 382.418082 -221.623382)
		(width 0.088646)
		(layer "In4.Cu")
		(net "M_F_CPU0_SB_DQ<30>")
	)
	(segment
		(start 405.192738 -198.592186)
		(end 402.185886 -201.599038)
		(width 0.18288)
		(layer "In4.Cu")
		(net "M_F_CPU0_SB_DQ<30>")
	)
	(segment
		(start 422.350438 -198.592186)
		(end 422.16451 -198.406258)
		(width 0.18288)
		(layer "In4.Cu")
		(net "M_F_CPU0_SB_DQ<30>")
	)
	(segment
		(start 423.458894 -197.317614)
		(end 423.458894 -198.227442)
		(width 0.18288)
		(layer "In4.Cu")
		(net "M_F_CPU0_SB_DQ<30>")
	)
	(segment
		(start 424.42511 -196.905626)
		(end 423.870882 -196.905626)
		(width 0.18288)
		(layer "In4.Cu")
		(net "M_F_CPU0_SB_DQ<30>")
	)
	(segment
		(start 384.687064 -220.004132)
		(end 384.672332 -219.995496)
		(width 0.088646)
		(layer "In4.Cu")
		(net "M_F_CPU0_SB_DQ<30>")
	)
	(segment
		(start 380.059946 -226.336606)
		(end 380.068836 -226.341686)
		(width 0.088646)
		(layer "In4.Cu")
		(net "M_F_CPU0_SB_DQ<30>")
	)
	(segment
		(start 421.98163 -197.994778)
		(end 421.542718 -197.994778)
		(width 0.18288)
		(layer "In4.Cu")
		(net "M_F_CPU0_SB_DQ<30>")
	)
	(segment
		(start 421.359838 -198.432166)
		(end 421.199818 -198.592186)
		(width 0.18288)
		(layer "In4.Cu")
		(net "M_F_CPU0_SB_DQ<30>")
	)
	(segment
		(start 385.626864 -220.004132)
		(end 385.612132 -219.995496)
		(width 0.088646)
		(layer "In4.Cu")
		(net "M_F_CPU0_SB_DQ<30>")
	)
	(segment
		(start 380.068836 -224.065084)
		(end 380.059946 -224.070164)
		(width 0.088646)
		(layer "In4.Cu")
		(net "M_F_CPU0_SB_DQ<30>")
	)
	(segment
		(start 382.230884 -221.939104)
		(end 382.230884 -221.957646)
		(width 0.088646)
		(layer "In4.Cu")
		(net "M_F_CPU0_SB_DQ<30>")
	)
	(segment
		(start 387.273038 -219.995496)
		(end 387.117336 -219.995496)
		(width 0.088646)
		(layer "In4.Cu")
		(net "M_F_CPU0_SB_DQ<30>")
	)
	(segment
		(start 380.821184 -222.761556)
		(end 380.821184 -222.780098)
		(width 0.088646)
		(layer "In4.Cu")
		(net "M_F_CPU0_SB_DQ<30>")
	)
	(segment
		(start 421.199818 -198.592186)
		(end 405.192738 -198.592186)
		(width 0.18288)
		(layer "In4.Cu")
		(net "M_F_CPU0_SB_DQ<30>")
	)
	(segment
		(start 421.359838 -198.177658)
		(end 421.359838 -198.432166)
		(width 0.18288)
		(layer "In4.Cu")
		(net "M_F_CPU0_SB_DQ<30>")
	)
	(segment
		(start 380.538736 -223.251268)
		(end 380.529846 -223.256348)
		(width 0.088646)
		(layer "In4.Cu")
		(net "M_F_CPU0_SB_DQ<30>")
	)
	(segment
		(start 423.458894 -198.227442)
		(end 423.09415 -198.592186)
		(width 0.18288)
		(layer "In4.Cu")
		(net "M_F_CPU0_SB_DQ<30>")
	)
	(segment
		(start 380.074932 -224.061528)
		(end 380.068836 -224.065084)
		(width 0.088646)
		(layer "In4.Cu")
		(net "M_F_CPU0_SB_DQ<30>")
	)
	(segment
		(start 424.836082 -197.316598)
		(end 424.42511 -196.905626)
		(width 0.18288)
		(layer "In4.Cu")
		(net "M_F_CPU0_SB_DQ<30>")
	)
	(segment
		(start 422.16451 -198.406258)
		(end 422.16451 -198.177658)
		(width 0.18288)
		(layer "In4.Cu")
		(net "M_F_CPU0_SB_DQ<30>")
	)
	(segment
		(start 380.068836 -225.69297)
		(end 380.059946 -225.69805)
		(width 0.088646)
		(layer "In4.Cu")
		(net "M_F_CPU0_SB_DQ<30>")
	)
	(segment
		(start 397.354806 -210.619594)
		(end 397.276574 -210.697826)
		(width 0.18288)
		(layer "In4.Cu")
		(net "M_F_CPU0_SB_DQ<30>")
	)
	(segment
		(start 387.476746 -219.791788)
		(end 387.273038 -219.995496)
		(width 0.088646)
		(layer "In4.Cu")
		(net "M_F_CPU0_SB_DQ<30>")
	)
	(segment
		(start 423.09415 -198.592186)
		(end 422.350438 -198.592186)
		(width 0.18288)
		(layer "In4.Cu")
		(net "M_F_CPU0_SB_DQ<30>")
	)
	(segment
		(start 421.542718 -197.994778)
		(end 421.359838 -198.177658)
		(width 0.18288)
		(layer "In4.Cu")
		(net "M_F_CPU0_SB_DQ<30>")
	)
	(segment
		(start 380.347474 -226.765866)
		(end 380.412752 -226.831144)
		(width 0.088646)
		(layer "In4.Cu")
		(net "M_F_CPU0_SB_DQ<30>")
	)
	(segment
		(start 422.16451 -198.177658)
		(end 421.98163 -197.994778)
		(width 0.18288)
		(layer "In4.Cu")
		(net "M_F_CPU0_SB_DQ<30>")
	)
	(segment
		(start 387.69671 -219.791788)
		(end 387.476746 -219.791788)
		(width 0.088646)
		(layer "In4.Cu")
		(net "M_F_CPU0_SB_DQ<30>")
	)
	(segment
		(start 381.008636 -222.437198)
		(end 380.999746 -222.442278)
		(width 0.088646)
		(layer "In4.Cu")
		(net "M_F_CPU0_SB_DQ<30>")
	)
	(segment
		(start 382.888236 -220.809566)
		(end 382.879346 -220.814646)
		(width 0.088646)
		(layer "In4.Cu")
		(net "M_F_CPU0_SB_DQ<30>")
	)
	(segment
		(start 402.185886 -201.599038)
		(end 399.30578 -205.909164)
		(width 0.18288)
		(layer "In4.Cu")
		(net "M_F_CPU0_SB_DQ<30>")
	)
	(segment
		(start 380.35103 -225.187764)
		(end 380.35103 -225.225356)
		(width 0.088646)
		(layer "In4.Cu")
		(net "M_F_CPU0_SB_DQ<30>")
	)
	(segment
		(start 397.276574 -210.697572)
		(end 388.182358 -219.791788)
		(width 0.18288)
		(layer "In4.Cu")
		(net "M_F_CPU0_SB_DQ<30>")
	)
	(segment
		(start 380.412752 -226.831144)
		(end 380.72568 -226.831144)
		(width 0.088646)
		(layer "In4.Cu")
		(net "M_F_CPU0_SB_DQ<30>")
	)
	(segment
		(start 383.170684 -220.319854)
		(end 383.170684 -220.334078)
		(width 0.088646)
		(layer "In4.Cu")
		(net "M_F_CPU0_SB_DQ<30>")
	)
	(segment
		(start 397.276574 -210.697826)
		(end 397.276574 -210.697572)
		(width 0.18288)
		(layer "In4.Cu")
		(net "M_F_CPU0_SB_DQ<30>")
	)
	(segment
		(start 423.870882 -196.905626)
		(end 423.458894 -197.317614)
		(width 0.18288)
		(layer "In4.Cu")
		(net "M_F_CPU0_SB_DQ<30>")
	)
	(segment
		(start 386.566664 -220.004132)
		(end 386.551932 -219.995496)
		(width 0.088646)
		(layer "In4.Cu")
		(net "M_F_CPU0_SB_DQ<30>")
	)
	(arc
		(start 383.349246 -220.000576)
		(mid 383.218332 -220.136936)
		(end 383.170684 -220.319854)
		(width 0.088646)
		(layer "In4.Cu")
		(net "M_F_CPU0_SB_DQ<30>")
	)
	(arc
		(start 380.529846 -223.256348)
		(mid 380.398932 -223.392708)
		(end 380.351284 -223.575626)
		(width 0.088646)
		(layer "In4.Cu")
		(net "M_F_CPU0_SB_DQ<30>")
	)
	(arc
		(start 380.351284 -223.575626)
		(mid 380.277368 -223.855128)
		(end 380.074932 -224.061528)
		(width 0.088646)
		(layer "In4.Cu")
		(net "M_F_CPU0_SB_DQ<30>")
	)
	(arc
		(start 384.672332 -219.995496)
		(mid 384.485134 -219.945353)
		(end 384.297936 -219.995496)
		(width 0.088646)
		(layer "In4.Cu")
		(net "M_F_CPU0_SB_DQ<30>")
	)
	(arc
		(start 382.700784 -221.133924)
		(mid 382.626793 -221.41349)
		(end 382.424178 -221.619826)
		(width 0.088646)
		(layer "In4.Cu")
		(net "M_F_CPU0_SB_DQ<30>")
	)
	(arc
		(start 383.732532 -219.995496)
		(mid 383.545334 -219.945353)
		(end 383.358136 -219.995496)
		(width 0.088646)
		(layer "In4.Cu")
		(net "M_F_CPU0_SB_DQ<30>")
	)
	(arc
		(start 382.879346 -220.814646)
		(mid 382.748432 -220.951006)
		(end 382.700784 -221.133924)
		(width 0.088646)
		(layer "In4.Cu")
		(net "M_F_CPU0_SB_DQ<30>")
	)
	(arc
		(start 380.068836 -224.7138)
		(mid 380.271659 -224.914031)
		(end 380.35103 -225.187764)
		(width 0.088646)
		(layer "In4.Cu")
		(net "M_F_CPU0_SB_DQ<30>")
	)
	(arc
		(start 386.551932 -219.995496)
		(mid 386.364734 -219.945353)
		(end 386.177536 -219.995496)
		(width 0.088646)
		(layer "In4.Cu")
		(net "M_F_CPU0_SB_DQ<30>")
	)
	(arc
		(start 380.821184 -222.780098)
		(mid 380.741022 -223.052287)
		(end 380.538736 -223.251268)
		(width 0.088646)
		(layer "In4.Cu")
		(net "M_F_CPU0_SB_DQ<30>")
	)
	(arc
		(start 386.177536 -219.995496)
		(mid 385.903337 -220.071331)
		(end 385.626864 -220.004132)
		(width 0.088646)
		(layer "In4.Cu")
		(net "M_F_CPU0_SB_DQ<30>")
	)
	(arc
		(start 384.297936 -219.995496)
		(mid 384.015234 -220.071272)
		(end 383.732532 -219.995496)
		(width 0.088646)
		(layer "In4.Cu")
		(net "M_F_CPU0_SB_DQ<30>")
	)
	(arc
		(start 382.230884 -221.957646)
		(mid 382.152773 -222.234595)
		(end 381.948436 -222.437198)
		(width 0.088646)
		(layer "In4.Cu")
		(net "M_F_CPU0_SB_DQ<30>")
	)
	(arc
		(start 385.612132 -219.995496)
		(mid 385.424934 -219.945353)
		(end 385.237736 -219.995496)
		(width 0.088646)
		(layer "In4.Cu")
		(net "M_F_CPU0_SB_DQ<30>")
	)
	(arc
		(start 381.948436 -222.437198)
		(mid 381.665734 -222.512974)
		(end 381.383032 -222.437198)
		(width 0.088646)
		(layer "In4.Cu")
		(net "M_F_CPU0_SB_DQ<30>")
	)
	(arc
		(start 387.117336 -219.995496)
		(mid 386.843137 -220.071331)
		(end 386.566664 -220.004132)
		(width 0.088646)
		(layer "In4.Cu")
		(net "M_F_CPU0_SB_DQ<30>")
	)
	(arc
		(start 381.383032 -222.437198)
		(mid 381.195834 -222.387055)
		(end 381.008636 -222.437198)
		(width 0.088646)
		(layer "In4.Cu")
		(net "M_F_CPU0_SB_DQ<30>")
	)
	(arc
		(start 380.068836 -226.341686)
		(mid 380.258419 -226.520756)
		(end 380.347474 -226.765866)
		(width 0.088646)
		(layer "In4.Cu")
		(net "M_F_CPU0_SB_DQ<30>")
	)
	(arc
		(start 380.35103 -225.225356)
		(mid 380.270119 -225.495484)
		(end 380.068836 -225.69297)
		(width 0.088646)
		(layer "In4.Cu")
		(net "M_F_CPU0_SB_DQ<30>")
	)
	(arc
		(start 383.170684 -220.334078)
		(mid 383.091543 -220.608701)
		(end 382.888236 -220.809566)
		(width 0.088646)
		(layer "In4.Cu")
		(net "M_F_CPU0_SB_DQ<30>")
	)
	(arc
		(start 380.059946 -225.69805)
		(mid 379.881349 -226.017328)
		(end 380.059946 -226.336606)
		(width 0.088646)
		(layer "In4.Cu")
		(net "M_F_CPU0_SB_DQ<30>")
	)
	(arc
		(start 385.237736 -219.995496)
		(mid 384.963537 -220.071331)
		(end 384.687064 -220.004132)
		(width 0.088646)
		(layer "In4.Cu")
		(net "M_F_CPU0_SB_DQ<30>")
	)
	(arc
		(start 380.059946 -224.070164)
		(mid 379.881349 -224.389442)
		(end 380.059946 -224.70872)
		(width 0.088646)
		(layer "In4.Cu")
		(net "M_F_CPU0_SB_DQ<30>")
	)
	(arc
		(start 380.999746 -222.442278)
		(mid 380.868832 -222.578638)
		(end 380.821184 -222.761556)
		(width 0.088646)
		(layer "In4.Cu")
		(net "M_F_CPU0_SB_DQ<30>")
	)
	(arc
		(start 382.418082 -221.623382)
		(mid 382.283149 -221.756736)
		(end 382.230884 -221.939104)
		(width 0.088646)
		(layer "In4.Cu")
		(net "M_F_CPU0_SB_DQ<30>")
	)
	(segment
		(start 430.395126 -231.753918)
		(end 431.076354 -231.753918)
		(width 0.20066)
		(layer "F.Cu")
		(net "M_F_CPU0_SB_DQ<2>")
	)
	(segment
		(start 428.07128 -231.748838)
		(end 428.363126 -231.748838)
		(width 0.20066)
		(layer "F.Cu")
		(net "M_F_CPU0_SB_DQ<2>")
	)
	(segment
		(start 431.898552 -231.064816)
		(end 432.15052 -231.316784)
		(width 0.20066)
		(layer "F.Cu")
		(net "M_F_CPU0_SB_DQ<2>")
	)
	(segment
		(start 379.316234 -239.575086)
		(end 379.316234 -239.0394)
		(width 0.20066)
		(layer "F.Cu")
		(net "M_F_CPU0_SB_DQ<2>")
	)
	(segment
		(start 428.367952 -231.748838)
		(end 428.375064 -231.741726)
		(width 0.1016)
		(layer "F.Cu")
		(net "M_F_CPU0_SB_DQ<2>")
	)
	(segment
		(start 432.15052 -231.316784)
		(end 433.484782 -231.316784)
		(width 0.20066)
		(layer "F.Cu")
		(net "M_F_CPU0_SB_DQ<2>")
	)
	(segment
		(start 431.280316 -231.299004)
		(end 431.514504 -231.064816)
		(width 0.20066)
		(layer "F.Cu")
		(net "M_F_CPU0_SB_DQ<2>")
	)
	(segment
		(start 428.375064 -231.741726)
		(end 430.382934 -231.741726)
		(width 0.1016)
		(layer "F.Cu")
		(net "M_F_CPU0_SB_DQ<2>")
	)
	(segment
		(start 428.363126 -231.748838)
		(end 428.367952 -231.748838)
		(width 0.101854)
		(layer "F.Cu")
		(net "M_F_CPU0_SB_DQ<2>")
	)
	(segment
		(start 430.382934 -231.741726)
		(end 430.395126 -231.753918)
		(width 0.1016)
		(layer "F.Cu")
		(net "M_F_CPU0_SB_DQ<2>")
	)
	(segment
		(start 431.076354 -231.753918)
		(end 431.280316 -231.549956)
		(width 0.20066)
		(layer "F.Cu")
		(net "M_F_CPU0_SB_DQ<2>")
	)
	(segment
		(start 427.639226 -231.316784)
		(end 428.07128 -231.748838)
		(width 0.20066)
		(layer "F.Cu")
		(net "M_F_CPU0_SB_DQ<2>")
	)
	(segment
		(start 431.514504 -231.064816)
		(end 431.898552 -231.064816)
		(width 0.20066)
		(layer "F.Cu")
		(net "M_F_CPU0_SB_DQ<2>")
	)
	(segment
		(start 431.280316 -231.549956)
		(end 431.280316 -231.299004)
		(width 0.20066)
		(layer "F.Cu")
		(net "M_F_CPU0_SB_DQ<2>")
	)
	(segment
		(start 379.31598 -239.57534)
		(end 379.316234 -239.575086)
		(width 0.20066)
		(layer "F.Cu")
		(net "M_F_CPU0_SB_DQ<2>")
	)
	(segment
		(start 424.836082 -231.316784)
		(end 425.940982 -231.316784)
		(width 0.20066)
		(layer "F.Cu")
		(net "M_F_CPU0_SB_DQ<2>")
	)
	(segment
		(start 425.940982 -231.316784)
		(end 427.639226 -231.316784)
		(width 0.20066)
		(layer "F.Cu")
		(net "M_F_CPU0_SB_DQ<2>")
	)
	(segment
		(start 423.548302 -230.5685)
		(end 423.548302 -230.232966)
		(width 0.18288)
		(layer "In4.Cu")
		(net "M_F_CPU0_SB_DQ<2>")
	)
	(segment
		(start 383.827782 -239.364012)
		(end 383.824226 -239.361726)
		(width 0.088646)
		(layer "In4.Cu")
		(net "M_F_CPU0_SB_DQ<2>")
	)
	(segment
		(start 413.784542 -231.779064)
		(end 413.784542 -230.997506)
		(width 0.18288)
		(layer "In4.Cu")
		(net "M_F_CPU0_SB_DQ<2>")
	)
	(segment
		(start 423.365422 -230.050086)
		(end 423.037762 -230.050086)
		(width 0.18288)
		(layer "In4.Cu")
		(net "M_F_CPU0_SB_DQ<2>")
	)
	(segment
		(start 388.78637 -237.789212)
		(end 387.495288 -239.080294)
		(width 0.088646)
		(layer "In4.Cu")
		(net "M_F_CPU0_SB_DQ<2>")
	)
	(segment
		(start 413.784542 -230.997506)
		(end 413.601662 -230.814626)
		(width 0.18288)
		(layer "In4.Cu")
		(net "M_F_CPU0_SB_DQ<2>")
	)
	(segment
		(start 381.014224 -239.367314)
		(end 381.008382 -239.364012)
		(width 0.088646)
		(layer "In4.Cu")
		(net "M_F_CPU0_SB_DQ<2>")
	)
	(segment
		(start 407.586434 -230.89235)
		(end 401.765516 -230.89235)
		(width 0.18288)
		(layer "In4.Cu")
		(net "M_F_CPU0_SB_DQ<2>")
	)
	(segment
		(start 413.601662 -230.814626)
		(end 412.994094 -230.814626)
		(width 0.18288)
		(layer "In4.Cu")
		(net "M_F_CPU0_SB_DQ<2>")
	)
	(segment
		(start 414.477962 -230.997506)
		(end 414.477962 -231.779064)
		(width 0.18288)
		(layer "In4.Cu")
		(net "M_F_CPU0_SB_DQ<2>")
	)
	(segment
		(start 384.217164 -239.355122)
		(end 384.202432 -239.363758)
		(width 0.088646)
		(layer "In4.Cu")
		(net "M_F_CPU0_SB_DQ<2>")
	)
	(segment
		(start 415.55924 -230.814626)
		(end 414.660842 -230.814626)
		(width 0.18288)
		(layer "In4.Cu")
		(net "M_F_CPU0_SB_DQ<2>")
	)
	(segment
		(start 415.739834 -230.99522)
		(end 415.55924 -230.814626)
		(width 0.18288)
		(layer "In4.Cu")
		(net "M_F_CPU0_SB_DQ<2>")
	)
	(segment
		(start 380.074424 -239.367314)
		(end 380.068582 -239.364012)
		(width 0.088646)
		(layer "In4.Cu")
		(net "M_F_CPU0_SB_DQ<2>")
	)
	(segment
		(start 424.270678 -230.75138)
		(end 423.731182 -230.75138)
		(width 0.18288)
		(layer "In4.Cu")
		(net "M_F_CPU0_SB_DQ<2>")
	)
	(segment
		(start 386.096764 -239.355122)
		(end 386.082032 -239.363758)
		(width 0.088646)
		(layer "In4.Cu")
		(net "M_F_CPU0_SB_DQ<2>")
	)
	(segment
		(start 385.156964 -239.355122)
		(end 385.142232 -239.363758)
		(width 0.088646)
		(layer "In4.Cu")
		(net "M_F_CPU0_SB_DQ<2>")
	)
	(segment
		(start 422.672002 -230.75138)
		(end 421.7289 -230.75138)
		(width 0.18288)
		(layer "In4.Cu")
		(net "M_F_CPU0_SB_DQ<2>")
	)
	(segment
		(start 414.477962 -231.779064)
		(end 414.295082 -231.961944)
		(width 0.18288)
		(layer "In4.Cu")
		(net "M_F_CPU0_SB_DQ<2>")
	)
	(segment
		(start 379.134624 -239.367314)
		(end 379.128782 -239.364012)
		(width 0.088646)
		(layer "In4.Cu")
		(net "M_F_CPU0_SB_DQ<2>")
	)
	(segment
		(start 407.766774 -230.256842)
		(end 407.766774 -230.71201)
		(width 0.18288)
		(layer "In4.Cu")
		(net "M_F_CPU0_SB_DQ<2>")
	)
	(segment
		(start 408.627326 -230.57104)
		(end 408.153108 -230.096822)
		(width 0.18288)
		(layer "In4.Cu")
		(net "M_F_CPU0_SB_DQ<2>")
	)
	(segment
		(start 387.495288 -239.080294)
		(end 387.021832 -239.363758)
		(width 0.088646)
		(layer "In4.Cu")
		(net "M_F_CPU0_SB_DQ<2>")
	)
	(segment
		(start 383.828036 -239.363758)
		(end 383.827782 -239.364012)
		(width 0.088646)
		(layer "In4.Cu")
		(net "M_F_CPU0_SB_DQ<2>")
	)
	(segment
		(start 397.317722 -235.340144)
		(end 392.851386 -235.340144)
		(width 0.18288)
		(layer "In4.Cu")
		(net "M_F_CPU0_SB_DQ<2>")
	)
	(segment
		(start 409.013914 -230.41102)
		(end 408.853894 -230.57104)
		(width 0.18288)
		(layer "In4.Cu")
		(net "M_F_CPU0_SB_DQ<2>")
	)
	(segment
		(start 421.7289 -230.75138)
		(end 421.587676 -230.892604)
		(width 0.18288)
		(layer "In4.Cu")
		(net "M_F_CPU0_SB_DQ<2>")
	)
	(segment
		(start 407.766774 -230.71201)
		(end 407.586434 -230.89235)
		(width 0.18288)
		(layer "In4.Cu")
		(net "M_F_CPU0_SB_DQ<2>")
	)
	(segment
		(start 381.008382 -239.364012)
		(end 381.00254 -239.360456)
		(width 0.088646)
		(layer "In4.Cu")
		(net "M_F_CPU0_SB_DQ<2>")
	)
	(segment
		(start 420.446962 -230.892604)
		(end 420.344346 -230.99522)
		(width 0.18288)
		(layer "In4.Cu")
		(net "M_F_CPU0_SB_DQ<2>")
	)
	(segment
		(start 407.926794 -230.096822)
		(end 407.766774 -230.256842)
		(width 0.18288)
		(layer "In4.Cu")
		(net "M_F_CPU0_SB_DQ<2>")
	)
	(segment
		(start 424.836082 -231.316784)
		(end 424.270678 -230.75138)
		(width 0.18288)
		(layer "In4.Cu")
		(net "M_F_CPU0_SB_DQ<2>")
	)
	(segment
		(start 379.003306 -239.0394)
		(end 379.316234 -239.0394)
		(width 0.088646)
		(layer "In4.Cu")
		(net "M_F_CPU0_SB_DQ<2>")
	)
	(segment
		(start 422.854882 -230.232966)
		(end 422.854882 -230.5685)
		(width 0.18288)
		(layer "In4.Cu")
		(net "M_F_CPU0_SB_DQ<2>")
	)
	(segment
		(start 379.128782 -239.364012)
		(end 379.123702 -239.360964)
		(width 0.088646)
		(layer "In4.Cu")
		(net "M_F_CPU0_SB_DQ<2>")
	)
	(segment
		(start 414.660842 -230.814626)
		(end 414.477962 -230.997506)
		(width 0.18288)
		(layer "In4.Cu")
		(net "M_F_CPU0_SB_DQ<2>")
	)
	(segment
		(start 423.037762 -230.050086)
		(end 422.854882 -230.232966)
		(width 0.18288)
		(layer "In4.Cu")
		(net "M_F_CPU0_SB_DQ<2>")
	)
	(segment
		(start 390.402318 -237.789212)
		(end 388.941564 -237.789212)
		(width 0.18288)
		(layer "In4.Cu")
		(net "M_F_CPU0_SB_DQ<2>")
	)
	(segment
		(start 382.893824 -239.367314)
		(end 382.887982 -239.364012)
		(width 0.088646)
		(layer "In4.Cu")
		(net "M_F_CPU0_SB_DQ<2>")
	)
	(segment
		(start 378.945902 -239.096804)
		(end 379.003306 -239.0394)
		(width 0.088646)
		(layer "In4.Cu")
		(net "M_F_CPU0_SB_DQ<2>")
	)
	(segment
		(start 412.22168 -230.042212)
		(end 409.173934 -230.042212)
		(width 0.18288)
		(layer "In4.Cu")
		(net "M_F_CPU0_SB_DQ<2>")
	)
	(segment
		(start 412.994094 -230.814626)
		(end 412.22168 -230.042212)
		(width 0.18288)
		(layer "In4.Cu")
		(net "M_F_CPU0_SB_DQ<2>")
	)
	(segment
		(start 380.068582 -239.364012)
		(end 380.06274 -239.360456)
		(width 0.088646)
		(layer "In4.Cu")
		(net "M_F_CPU0_SB_DQ<2>")
	)
	(segment
		(start 381.948182 -239.364012)
		(end 381.944626 -239.361726)
		(width 0.088646)
		(layer "In4.Cu")
		(net "M_F_CPU0_SB_DQ<2>")
	)
	(segment
		(start 413.967422 -231.961944)
		(end 413.784542 -231.779064)
		(width 0.18288)
		(layer "In4.Cu")
		(net "M_F_CPU0_SB_DQ<2>")
	)
	(segment
		(start 401.765516 -230.89235)
		(end 397.317722 -235.340144)
		(width 0.18288)
		(layer "In4.Cu")
		(net "M_F_CPU0_SB_DQ<2>")
	)
	(segment
		(start 388.941564 -237.789212)
		(end 388.78637 -237.789212)
		(width 0.088646)
		(layer "In4.Cu")
		(net "M_F_CPU0_SB_DQ<2>")
	)
	(segment
		(start 421.587676 -230.892604)
		(end 420.446962 -230.892604)
		(width 0.18288)
		(layer "In4.Cu")
		(net "M_F_CPU0_SB_DQ<2>")
	)
	(segment
		(start 423.731182 -230.75138)
		(end 423.548302 -230.5685)
		(width 0.18288)
		(layer "In4.Cu")
		(net "M_F_CPU0_SB_DQ<2>")
	)
	(segment
		(start 382.887982 -239.364012)
		(end 382.88341 -239.361218)
		(width 0.088646)
		(layer "In4.Cu")
		(net "M_F_CPU0_SB_DQ<2>")
	)
	(segment
		(start 423.548302 -230.232966)
		(end 423.365422 -230.050086)
		(width 0.18288)
		(layer "In4.Cu")
		(net "M_F_CPU0_SB_DQ<2>")
	)
	(segment
		(start 392.851386 -235.340144)
		(end 390.402318 -237.789212)
		(width 0.18288)
		(layer "In4.Cu")
		(net "M_F_CPU0_SB_DQ<2>")
	)
	(segment
		(start 420.344346 -230.99522)
		(end 415.739834 -230.99522)
		(width 0.18288)
		(layer "In4.Cu")
		(net "M_F_CPU0_SB_DQ<2>")
	)
	(segment
		(start 409.013914 -230.202232)
		(end 409.013914 -230.41102)
		(width 0.18288)
		(layer "In4.Cu")
		(net "M_F_CPU0_SB_DQ<2>")
	)
	(segment
		(start 409.173934 -230.042212)
		(end 409.013914 -230.202232)
		(width 0.18288)
		(layer "In4.Cu")
		(net "M_F_CPU0_SB_DQ<2>")
	)
	(segment
		(start 408.153108 -230.096822)
		(end 407.926794 -230.096822)
		(width 0.18288)
		(layer "In4.Cu")
		(net "M_F_CPU0_SB_DQ<2>")
	)
	(segment
		(start 414.295082 -231.961944)
		(end 413.967422 -231.961944)
		(width 0.18288)
		(layer "In4.Cu")
		(net "M_F_CPU0_SB_DQ<2>")
	)
	(segment
		(start 408.853894 -230.57104)
		(end 408.627326 -230.57104)
		(width 0.18288)
		(layer "In4.Cu")
		(net "M_F_CPU0_SB_DQ<2>")
	)
	(segment
		(start 422.854882 -230.5685)
		(end 422.672002 -230.75138)
		(width 0.18288)
		(layer "In4.Cu")
		(net "M_F_CPU0_SB_DQ<2>")
	)
	(arc
		(start 383.262632 -239.364012)
		(mid 383.078678 -239.414107)
		(end 382.893824 -239.367314)
		(width 0.088646)
		(layer "In4.Cu")
		(net "M_F_CPU0_SB_DQ<2>")
	)
	(arc
		(start 380.443232 -239.364012)
		(mid 380.259278 -239.414107)
		(end 380.074424 -239.367314)
		(width 0.088646)
		(layer "In4.Cu")
		(net "M_F_CPU0_SB_DQ<2>")
	)
	(arc
		(start 379.503432 -239.364012)
		(mid 379.319478 -239.414107)
		(end 379.134624 -239.367314)
		(width 0.088646)
		(layer "In4.Cu")
		(net "M_F_CPU0_SB_DQ<2>")
	)
	(arc
		(start 386.082032 -239.363758)
		(mid 385.894834 -239.413901)
		(end 385.707636 -239.363758)
		(width 0.088646)
		(layer "In4.Cu")
		(net "M_F_CPU0_SB_DQ<2>")
	)
	(arc
		(start 383.824226 -239.361726)
		(mid 383.543113 -239.288149)
		(end 383.262632 -239.364012)
		(width 0.088646)
		(layer "In4.Cu")
		(net "M_F_CPU0_SB_DQ<2>")
	)
	(arc
		(start 384.202432 -239.363758)
		(mid 384.015234 -239.413901)
		(end 383.828036 -239.363758)
		(width 0.088646)
		(layer "In4.Cu")
		(net "M_F_CPU0_SB_DQ<2>")
	)
	(arc
		(start 382.88341 -239.361218)
		(mid 382.602746 -239.288177)
		(end 382.322832 -239.364012)
		(width 0.088646)
		(layer "In4.Cu")
		(net "M_F_CPU0_SB_DQ<2>")
	)
	(arc
		(start 387.021832 -239.363758)
		(mid 386.834634 -239.413901)
		(end 386.647436 -239.363758)
		(width 0.088646)
		(layer "In4.Cu")
		(net "M_F_CPU0_SB_DQ<2>")
	)
	(arc
		(start 384.767836 -239.363758)
		(mid 384.493637 -239.287923)
		(end 384.217164 -239.355122)
		(width 0.088646)
		(layer "In4.Cu")
		(net "M_F_CPU0_SB_DQ<2>")
	)
	(arc
		(start 385.707636 -239.363758)
		(mid 385.433437 -239.287923)
		(end 385.156964 -239.355122)
		(width 0.088646)
		(layer "In4.Cu")
		(net "M_F_CPU0_SB_DQ<2>")
	)
	(arc
		(start 381.944626 -239.361726)
		(mid 381.663513 -239.288149)
		(end 381.383032 -239.364012)
		(width 0.088646)
		(layer "In4.Cu")
		(net "M_F_CPU0_SB_DQ<2>")
	)
	(arc
		(start 379.123702 -239.360964)
		(mid 379.005407 -239.248688)
		(end 378.945902 -239.096804)
		(width 0.088646)
		(layer "In4.Cu")
		(net "M_F_CPU0_SB_DQ<2>")
	)
	(arc
		(start 382.322832 -239.364012)
		(mid 382.135524 -239.414121)
		(end 381.948182 -239.364012)
		(width 0.088646)
		(layer "In4.Cu")
		(net "M_F_CPU0_SB_DQ<2>")
	)
	(arc
		(start 381.00254 -239.360456)
		(mid 380.722405 -239.28814)
		(end 380.443232 -239.364012)
		(width 0.088646)
		(layer "In4.Cu")
		(net "M_F_CPU0_SB_DQ<2>")
	)
	(arc
		(start 385.142232 -239.363758)
		(mid 384.955034 -239.413901)
		(end 384.767836 -239.363758)
		(width 0.088646)
		(layer "In4.Cu")
		(net "M_F_CPU0_SB_DQ<2>")
	)
	(arc
		(start 386.647436 -239.363758)
		(mid 386.373237 -239.287923)
		(end 386.096764 -239.355122)
		(width 0.088646)
		(layer "In4.Cu")
		(net "M_F_CPU0_SB_DQ<2>")
	)
	(arc
		(start 381.383032 -239.364012)
		(mid 381.199078 -239.414107)
		(end 381.014224 -239.367314)
		(width 0.088646)
		(layer "In4.Cu")
		(net "M_F_CPU0_SB_DQ<2>")
	)
	(arc
		(start 380.06274 -239.360456)
		(mid 379.782605 -239.28814)
		(end 379.503432 -239.364012)
		(width 0.088646)
		(layer "In4.Cu")
		(net "M_F_CPU0_SB_DQ<2>")
	)
	(segment
		(start 424.085512 -196.71538)
		(end 423.610278 -196.71538)
		(width 0.20066)
		(layer "F.Cu")
		(net "M_F_CPU0_SB_DQ<29>")
	)
	(segment
		(start 424.756326 -196.041772)
		(end 424.73626 -196.041772)
		(width 0.101854)
		(layer "F.Cu")
		(net "M_F_CPU0_SB_DQ<29>")
	)
	(segment
		(start 427.36135 -196.035422)
		(end 426.951394 -196.035422)
		(width 0.20066)
		(layer "F.Cu")
		(net "M_F_CPU0_SB_DQ<29>")
	)
	(segment
		(start 423.610278 -196.71538)
		(end 423.361612 -196.466714)
		(width 0.20066)
		(layer "F.Cu")
		(net "M_F_CPU0_SB_DQ<29>")
	)
	(segment
		(start 421.840914 -196.466714)
		(end 420.736014 -196.466714)
		(width 0.20066)
		(layer "F.Cu")
		(net "M_F_CPU0_SB_DQ<29>")
	)
	(segment
		(start 377.906534 -227.367084)
		(end 377.90628 -227.36683)
		(width 0.20066)
		(layer "F.Cu")
		(net "M_F_CPU0_SB_DQ<29>")
	)
	(segment
		(start 423.361612 -196.466714)
		(end 421.840914 -196.466714)
		(width 0.20066)
		(layer "F.Cu")
		(net "M_F_CPU0_SB_DQ<29>")
	)
	(segment
		(start 424.273472 -196.159882)
		(end 424.273472 -196.52742)
		(width 0.20066)
		(layer "F.Cu")
		(net "M_F_CPU0_SB_DQ<29>")
	)
	(segment
		(start 427.792896 -196.466968)
		(end 427.36135 -196.035422)
		(width 0.20066)
		(layer "F.Cu")
		(net "M_F_CPU0_SB_DQ<29>")
	)
	(segment
		(start 429.38446 -196.466968)
		(end 427.792896 -196.466968)
		(width 0.20066)
		(layer "F.Cu")
		(net "M_F_CPU0_SB_DQ<29>")
	)
	(segment
		(start 426.951394 -196.035422)
		(end 426.945044 -196.041772)
		(width 0.1016)
		(layer "F.Cu")
		(net "M_F_CPU0_SB_DQ<29>")
	)
	(segment
		(start 424.273472 -196.52742)
		(end 424.085512 -196.71538)
		(width 0.20066)
		(layer "F.Cu")
		(net "M_F_CPU0_SB_DQ<29>")
	)
	(segment
		(start 424.73626 -196.041772)
		(end 424.391582 -196.041772)
		(width 0.20066)
		(layer "F.Cu")
		(net "M_F_CPU0_SB_DQ<29>")
	)
	(segment
		(start 377.90628 -227.36683)
		(end 377.90628 -226.831144)
		(width 0.20066)
		(layer "F.Cu")
		(net "M_F_CPU0_SB_DQ<29>")
	)
	(segment
		(start 424.391582 -196.041772)
		(end 424.273472 -196.159882)
		(width 0.20066)
		(layer "F.Cu")
		(net "M_F_CPU0_SB_DQ<29>")
	)
	(segment
		(start 426.945044 -196.041772)
		(end 424.756326 -196.041772)
		(width 0.1016)
		(layer "F.Cu")
		(net "M_F_CPU0_SB_DQ<29>")
	)
	(segment
		(start 429.384714 -196.466714)
		(end 429.38446 -196.466968)
		(width 0.20066)
		(layer "F.Cu")
		(net "M_F_CPU0_SB_DQ<29>")
	)
	(segment
		(start 391.707116 -214.858854)
		(end 391.707116 -214.8586)
		(width 0.18288)
		(layer "In4.Cu")
		(net "M_F_CPU0_SB_DQ<29>")
	)
	(segment
		(start 418.1094 -195.915026)
		(end 417.92652 -195.732146)
		(width 0.18288)
		(layer "In4.Cu")
		(net "M_F_CPU0_SB_DQ<29>")
	)
	(segment
		(start 417.05022 -195.915026)
		(end 416.372294 -195.915026)
		(width 0.18288)
		(layer "In4.Cu")
		(net "M_F_CPU0_SB_DQ<29>")
	)
	(segment
		(start 414.69183 -196.080126)
		(end 414.69183 -195.342002)
		(width 0.18288)
		(layer "In4.Cu")
		(net "M_F_CPU0_SB_DQ<29>")
	)
	(segment
		(start 382.424178 -219.99194)
		(end 382.418082 -219.995496)
		(width 0.088646)
		(layer "In4.Cu")
		(net "M_F_CPU0_SB_DQ<29>")
	)
	(segment
		(start 416.372294 -195.915026)
		(end 416.042094 -196.245226)
		(width 0.18288)
		(layer "In4.Cu")
		(net "M_F_CPU0_SB_DQ<29>")
	)
	(segment
		(start 377.593352 -226.831144)
		(end 377.90628 -226.831144)
		(width 0.088646)
		(layer "In4.Cu")
		(net "M_F_CPU0_SB_DQ<29>")
	)
	(segment
		(start 414.494218 -195.14439)
		(end 414.085278 -195.14439)
		(width 0.18288)
		(layer "In4.Cu")
		(net "M_F_CPU0_SB_DQ<29>")
	)
	(segment
		(start 377.719082 -226.506786)
		(end 377.710192 -226.511866)
		(width 0.088646)
		(layer "In4.Cu")
		(net "M_F_CPU0_SB_DQ<29>")
	)
	(segment
		(start 384.767582 -219.18168)
		(end 384.757168 -219.187776)
		(width 0.088646)
		(layer "In4.Cu")
		(net "M_F_CPU0_SB_DQ<29>")
	)
	(segment
		(start 378.659136 -223.251268)
		(end 378.650246 -223.256348)
		(width 0.088646)
		(layer "In4.Cu")
		(net "M_F_CPU0_SB_DQ<29>")
	)
	(segment
		(start 414.085278 -195.14439)
		(end 413.902398 -195.32727)
		(width 0.18288)
		(layer "In4.Cu")
		(net "M_F_CPU0_SB_DQ<29>")
	)
	(segment
		(start 401.418806 -200.815702)
		(end 398.260824 -205.540356)
		(width 0.18288)
		(layer "In4.Cu")
		(net "M_F_CPU0_SB_DQ<29>")
	)
	(segment
		(start 408.492706 -196.772022)
		(end 405.658066 -196.772022)
		(width 0.18288)
		(layer "In4.Cu")
		(net "M_F_CPU0_SB_DQ<29>")
	)
	(segment
		(start 378.189236 -225.69297)
		(end 378.180346 -225.69805)
		(width 0.088646)
		(layer "In4.Cu")
		(net "M_F_CPU0_SB_DQ<29>")
	)
	(segment
		(start 412.460694 -195.813426)
		(end 411.508956 -195.813426)
		(width 0.18288)
		(layer "In4.Cu")
		(net "M_F_CPU0_SB_DQ<29>")
	)
	(segment
		(start 378.47143 -225.187764)
		(end 378.47143 -225.225356)
		(width 0.088646)
		(layer "In4.Cu")
		(net "M_F_CPU0_SB_DQ<29>")
	)
	(segment
		(start 405.658066 -196.772022)
		(end 405.309578 -196.916548)
		(width 0.18288)
		(layer "In4.Cu")
		(net "M_F_CPU0_SB_DQ<29>")
	)
	(segment
		(start 386.647182 -219.18168)
		(end 386.63245 -219.190316)
		(width 0.088646)
		(layer "In4.Cu")
		(net "M_F_CPU0_SB_DQ<29>")
	)
	(segment
		(start 378.941584 -222.761556)
		(end 378.941584 -222.780098)
		(width 0.088646)
		(layer "In4.Cu")
		(net "M_F_CPU0_SB_DQ<29>")
	)
	(segment
		(start 385.707382 -219.18168)
		(end 385.69265 -219.190316)
		(width 0.088646)
		(layer "In4.Cu")
		(net "M_F_CPU0_SB_DQ<29>")
	)
	(segment
		(start 413.742378 -196.245226)
		(end 412.892494 -196.245226)
		(width 0.18288)
		(layer "In4.Cu")
		(net "M_F_CPU0_SB_DQ<29>")
	)
	(segment
		(start 387.49351 -218.721686)
		(end 387.134608 -218.721686)
		(width 0.088646)
		(layer "In4.Cu")
		(net "M_F_CPU0_SB_DQ<29>")
	)
	(segment
		(start 391.707116 -214.8586)
		(end 387.84403 -218.721686)
		(width 0.18288)
		(layer "In4.Cu")
		(net "M_F_CPU0_SB_DQ<29>")
	)
	(segment
		(start 417.92652 -195.380356)
		(end 417.74364 -195.197476)
		(width 0.18288)
		(layer "In4.Cu")
		(net "M_F_CPU0_SB_DQ<29>")
	)
	(segment
		(start 381.478536 -219.995496)
		(end 381.469646 -220.000576)
		(width 0.088646)
		(layer "In4.Cu")
		(net "M_F_CPU0_SB_DQ<29>")
	)
	(segment
		(start 382.888236 -219.18168)
		(end 382.879346 -219.18676)
		(width 0.088646)
		(layer "In4.Cu")
		(net "M_F_CPU0_SB_DQ<29>")
	)
	(segment
		(start 416.042094 -196.245226)
		(end 414.85693 -196.245226)
		(width 0.18288)
		(layer "In4.Cu")
		(net "M_F_CPU0_SB_DQ<29>")
	)
	(segment
		(start 420.184326 -195.915026)
		(end 418.1094 -195.915026)
		(width 0.18288)
		(layer "In4.Cu")
		(net "M_F_CPU0_SB_DQ<29>")
	)
	(segment
		(start 412.892494 -196.245226)
		(end 412.460694 -195.813426)
		(width 0.18288)
		(layer "In4.Cu")
		(net "M_F_CPU0_SB_DQ<29>")
	)
	(segment
		(start 381.291084 -220.319854)
		(end 381.291084 -220.338396)
		(width 0.088646)
		(layer "In4.Cu")
		(net "M_F_CPU0_SB_DQ<29>")
	)
	(segment
		(start 396.306294 -210.259676)
		(end 391.707116 -214.858854)
		(width 0.18288)
		(layer "In4.Cu")
		(net "M_F_CPU0_SB_DQ<29>")
	)
	(segment
		(start 380.544578 -221.619826)
		(end 380.538482 -221.623382)
		(width 0.088646)
		(layer "In4.Cu")
		(net "M_F_CPU0_SB_DQ<29>")
	)
	(segment
		(start 378.180346 -224.70872)
		(end 378.189236 -224.7138)
		(width 0.088646)
		(layer "In4.Cu")
		(net "M_F_CPU0_SB_DQ<29>")
	)
	(segment
		(start 377.725178 -226.50323)
		(end 377.719082 -226.506786)
		(width 0.088646)
		(layer "In4.Cu")
		(net "M_F_CPU0_SB_DQ<29>")
	)
	(segment
		(start 411.508956 -195.813426)
		(end 410.391102 -196.93128)
		(width 0.18288)
		(layer "In4.Cu")
		(net "M_F_CPU0_SB_DQ<29>")
	)
	(segment
		(start 382.418082 -219.995496)
		(end 382.407668 -220.001592)
		(width 0.088646)
		(layer "In4.Cu")
		(net "M_F_CPU0_SB_DQ<29>")
	)
	(segment
		(start 405.309578 -196.916548)
		(end 401.418806 -200.815702)
		(width 0.18288)
		(layer "In4.Cu")
		(net "M_F_CPU0_SB_DQ<29>")
	)
	(segment
		(start 413.902398 -196.085206)
		(end 413.742378 -196.245226)
		(width 0.18288)
		(layer "In4.Cu")
		(net "M_F_CPU0_SB_DQ<29>")
	)
	(segment
		(start 417.2331 -195.732146)
		(end 417.05022 -195.915026)
		(width 0.18288)
		(layer "In4.Cu")
		(net "M_F_CPU0_SB_DQ<29>")
	)
	(segment
		(start 378.195332 -224.061528)
		(end 378.189236 -224.065084)
		(width 0.088646)
		(layer "In4.Cu")
		(net "M_F_CPU0_SB_DQ<29>")
	)
	(segment
		(start 379.518164 -222.445834)
		(end 379.503432 -222.437198)
		(width 0.088646)
		(layer "In4.Cu")
		(net "M_F_CPU0_SB_DQ<29>")
	)
	(segment
		(start 398.260824 -205.540356)
		(end 396.306294 -210.259676)
		(width 0.18288)
		(layer "In4.Cu")
		(net "M_F_CPU0_SB_DQ<29>")
	)
	(segment
		(start 414.69183 -195.342002)
		(end 414.494218 -195.14439)
		(width 0.18288)
		(layer "In4.Cu")
		(net "M_F_CPU0_SB_DQ<29>")
	)
	(segment
		(start 417.74364 -195.197476)
		(end 417.41598 -195.197476)
		(width 0.18288)
		(layer "In4.Cu")
		(net "M_F_CPU0_SB_DQ<29>")
	)
	(segment
		(start 417.2331 -195.380356)
		(end 417.2331 -195.732146)
		(width 0.18288)
		(layer "In4.Cu")
		(net "M_F_CPU0_SB_DQ<29>")
	)
	(segment
		(start 410.391102 -196.93128)
		(end 408.651964 -196.93128)
		(width 0.18288)
		(layer "In4.Cu")
		(net "M_F_CPU0_SB_DQ<29>")
	)
	(segment
		(start 380.35103 -221.94774)
		(end 380.35103 -221.963234)
		(width 0.088646)
		(layer "In4.Cu")
		(net "M_F_CPU0_SB_DQ<29>")
	)
	(segment
		(start 414.85693 -196.245226)
		(end 414.69183 -196.080126)
		(width 0.18288)
		(layer "In4.Cu")
		(net "M_F_CPU0_SB_DQ<29>")
	)
	(segment
		(start 387.134608 -218.721686)
		(end 386.764276 -219.092018)
		(width 0.088646)
		(layer "In4.Cu")
		(net "M_F_CPU0_SB_DQ<29>")
	)
	(segment
		(start 420.736014 -196.466714)
		(end 420.184326 -195.915026)
		(width 0.18288)
		(layer "In4.Cu")
		(net "M_F_CPU0_SB_DQ<29>")
	)
	(segment
		(start 417.41598 -195.197476)
		(end 417.2331 -195.380356)
		(width 0.18288)
		(layer "In4.Cu")
		(net "M_F_CPU0_SB_DQ<29>")
	)
	(segment
		(start 378.189236 -224.065084)
		(end 378.180346 -224.070164)
		(width 0.088646)
		(layer "In4.Cu")
		(net "M_F_CPU0_SB_DQ<29>")
	)
	(segment
		(start 380.538482 -221.623382)
		(end 380.529592 -221.628462)
		(width 0.088646)
		(layer "In4.Cu")
		(net "M_F_CPU0_SB_DQ<29>")
	)
	(segment
		(start 377.536202 -226.773994)
		(end 377.593352 -226.831144)
		(width 0.088646)
		(layer "In4.Cu")
		(net "M_F_CPU0_SB_DQ<29>")
	)
	(segment
		(start 417.92652 -195.732146)
		(end 417.92652 -195.380356)
		(width 0.18288)
		(layer "In4.Cu")
		(net "M_F_CPU0_SB_DQ<29>")
	)
	(segment
		(start 413.902398 -195.32727)
		(end 413.902398 -196.085206)
		(width 0.18288)
		(layer "In4.Cu")
		(net "M_F_CPU0_SB_DQ<29>")
	)
	(segment
		(start 379.129036 -222.437198)
		(end 379.120146 -222.442278)
		(width 0.088646)
		(layer "In4.Cu")
		(net "M_F_CPU0_SB_DQ<29>")
	)
	(segment
		(start 387.84403 -218.721686)
		(end 387.49351 -218.721686)
		(width 0.18288)
		(layer "In4.Cu")
		(net "M_F_CPU0_SB_DQ<29>")
	)
	(segment
		(start 408.651964 -196.93128)
		(end 408.492706 -196.772022)
		(width 0.18288)
		(layer "In4.Cu")
		(net "M_F_CPU0_SB_DQ<29>")
	)
	(segment
		(start 381.008636 -220.809566)
		(end 380.999746 -220.814646)
		(width 0.088646)
		(layer "In4.Cu")
		(net "M_F_CPU0_SB_DQ<29>")
	)
	(arc
		(start 384.202432 -219.18168)
		(mid 384.015234 -219.131537)
		(end 383.828036 -219.18168)
		(width 0.088646)
		(layer "In4.Cu")
		(net "M_F_CPU0_SB_DQ<29>")
	)
	(arc
		(start 379.503432 -222.437198)
		(mid 379.316234 -222.387055)
		(end 379.129036 -222.437198)
		(width 0.088646)
		(layer "In4.Cu")
		(net "M_F_CPU0_SB_DQ<29>")
	)
	(arc
		(start 378.47143 -225.225356)
		(mid 378.390519 -225.495484)
		(end 378.189236 -225.69297)
		(width 0.088646)
		(layer "In4.Cu")
		(net "M_F_CPU0_SB_DQ<29>")
	)
	(arc
		(start 378.180346 -224.070164)
		(mid 378.001749 -224.389442)
		(end 378.180346 -224.70872)
		(width 0.088646)
		(layer "In4.Cu")
		(net "M_F_CPU0_SB_DQ<29>")
	)
	(arc
		(start 379.120146 -222.442278)
		(mid 378.989232 -222.578638)
		(end 378.941584 -222.761556)
		(width 0.088646)
		(layer "In4.Cu")
		(net "M_F_CPU0_SB_DQ<29>")
	)
	(arc
		(start 381.469646 -220.000576)
		(mid 381.338732 -220.136936)
		(end 381.291084 -220.319854)
		(width 0.088646)
		(layer "In4.Cu")
		(net "M_F_CPU0_SB_DQ<29>")
	)
	(arc
		(start 386.63245 -219.190316)
		(mid 386.355975 -219.257636)
		(end 386.081778 -219.18168)
		(width 0.088646)
		(layer "In4.Cu")
		(net "M_F_CPU0_SB_DQ<29>")
	)
	(arc
		(start 380.821184 -221.133924)
		(mid 380.747193 -221.41349)
		(end 380.544578 -221.619826)
		(width 0.088646)
		(layer "In4.Cu")
		(net "M_F_CPU0_SB_DQ<29>")
	)
	(arc
		(start 378.180346 -225.69805)
		(mid 378.049432 -225.83441)
		(end 378.001784 -226.017328)
		(width 0.088646)
		(layer "In4.Cu")
		(net "M_F_CPU0_SB_DQ<29>")
	)
	(arc
		(start 386.738368 -219.116402)
		(mid 386.694393 -219.151301)
		(end 386.647182 -219.18168)
		(width 0.088646)
		(layer "In4.Cu")
		(net "M_F_CPU0_SB_DQ<29>")
	)
	(arc
		(start 383.828036 -219.18168)
		(mid 383.545334 -219.257456)
		(end 383.262632 -219.18168)
		(width 0.088646)
		(layer "In4.Cu")
		(net "M_F_CPU0_SB_DQ<29>")
	)
	(arc
		(start 378.471684 -223.575626)
		(mid 378.397768 -223.855128)
		(end 378.195332 -224.061528)
		(width 0.088646)
		(layer "In4.Cu")
		(net "M_F_CPU0_SB_DQ<29>")
	)
	(arc
		(start 380.999746 -220.814646)
		(mid 380.868832 -220.951006)
		(end 380.821184 -221.133924)
		(width 0.088646)
		(layer "In4.Cu")
		(net "M_F_CPU0_SB_DQ<29>")
	)
	(arc
		(start 380.35103 -221.963234)
		(mid 380.27166 -222.236968)
		(end 380.068836 -222.437198)
		(width 0.088646)
		(layer "In4.Cu")
		(net "M_F_CPU0_SB_DQ<29>")
	)
	(arc
		(start 382.879346 -219.18676)
		(mid 382.748432 -219.32312)
		(end 382.700784 -219.506038)
		(width 0.088646)
		(layer "In4.Cu")
		(net "M_F_CPU0_SB_DQ<29>")
	)
	(arc
		(start 378.189236 -224.7138)
		(mid 378.392059 -224.914031)
		(end 378.47143 -225.187764)
		(width 0.088646)
		(layer "In4.Cu")
		(net "M_F_CPU0_SB_DQ<29>")
	)
	(arc
		(start 384.757168 -219.187776)
		(mid 384.47899 -219.257499)
		(end 384.202432 -219.18168)
		(width 0.088646)
		(layer "In4.Cu")
		(net "M_F_CPU0_SB_DQ<29>")
	)
	(arc
		(start 385.69265 -219.190316)
		(mid 385.416175 -219.257636)
		(end 385.141978 -219.18168)
		(width 0.088646)
		(layer "In4.Cu")
		(net "M_F_CPU0_SB_DQ<29>")
	)
	(arc
		(start 378.941584 -222.780098)
		(mid 378.861422 -223.052287)
		(end 378.659136 -223.251268)
		(width 0.088646)
		(layer "In4.Cu")
		(net "M_F_CPU0_SB_DQ<29>")
	)
	(arc
		(start 385.141978 -219.18168)
		(mid 384.95478 -219.131537)
		(end 384.767582 -219.18168)
		(width 0.088646)
		(layer "In4.Cu")
		(net "M_F_CPU0_SB_DQ<29>")
	)
	(arc
		(start 381.291084 -220.338396)
		(mid 381.210922 -220.610585)
		(end 381.008636 -220.809566)
		(width 0.088646)
		(layer "In4.Cu")
		(net "M_F_CPU0_SB_DQ<29>")
	)
	(arc
		(start 380.529592 -221.628462)
		(mid 380.398678 -221.764822)
		(end 380.35103 -221.94774)
		(width 0.088646)
		(layer "In4.Cu")
		(net "M_F_CPU0_SB_DQ<29>")
	)
	(arc
		(start 382.700784 -219.506038)
		(mid 382.626793 -219.785604)
		(end 382.424178 -219.99194)
		(width 0.088646)
		(layer "In4.Cu")
		(net "M_F_CPU0_SB_DQ<29>")
	)
	(arc
		(start 378.001784 -226.017328)
		(mid 377.927793 -226.296894)
		(end 377.725178 -226.50323)
		(width 0.088646)
		(layer "In4.Cu")
		(net "M_F_CPU0_SB_DQ<29>")
	)
	(arc
		(start 377.710192 -226.511866)
		(mid 377.594383 -226.623795)
		(end 377.536202 -226.773994)
		(width 0.088646)
		(layer "In4.Cu")
		(net "M_F_CPU0_SB_DQ<29>")
	)
	(arc
		(start 383.262632 -219.18168)
		(mid 383.075434 -219.131537)
		(end 382.888236 -219.18168)
		(width 0.088646)
		(layer "In4.Cu")
		(net "M_F_CPU0_SB_DQ<29>")
	)
	(arc
		(start 386.081778 -219.18168)
		(mid 385.89458 -219.131537)
		(end 385.707382 -219.18168)
		(width 0.088646)
		(layer "In4.Cu")
		(net "M_F_CPU0_SB_DQ<29>")
	)
	(arc
		(start 382.407668 -220.001592)
		(mid 382.12949 -220.071315)
		(end 381.852932 -219.995496)
		(width 0.088646)
		(layer "In4.Cu")
		(net "M_F_CPU0_SB_DQ<29>")
	)
	(arc
		(start 386.764276 -219.092018)
		(mid 386.751515 -219.104415)
		(end 386.738368 -219.116402)
		(width 0.088646)
		(layer "In4.Cu")
		(net "M_F_CPU0_SB_DQ<29>")
	)
	(arc
		(start 380.068836 -222.437198)
		(mid 379.794637 -222.513033)
		(end 379.518164 -222.445834)
		(width 0.088646)
		(layer "In4.Cu")
		(net "M_F_CPU0_SB_DQ<29>")
	)
	(arc
		(start 378.650246 -223.256348)
		(mid 378.519332 -223.392708)
		(end 378.471684 -223.575626)
		(width 0.088646)
		(layer "In4.Cu")
		(net "M_F_CPU0_SB_DQ<29>")
	)
	(arc
		(start 381.852932 -219.995496)
		(mid 381.665734 -219.945353)
		(end 381.478536 -219.995496)
		(width 0.088646)
		(layer "In4.Cu")
		(net "M_F_CPU0_SB_DQ<29>")
	)
	(segment
		(start 424.273472 -197.859904)
		(end 424.273472 -198.227442)
		(width 0.20066)
		(layer "F.Cu")
		(net "M_F_CPU0_SB_DQ<28>")
	)
	(segment
		(start 426.945044 -197.741794)
		(end 424.78325 -197.741794)
		(width 0.1016)
		(layer "F.Cu")
		(net "M_F_CPU0_SB_DQ<28>")
	)
	(segment
		(start 379.786134 -227.367084)
		(end 379.78588 -227.36683)
		(width 0.20066)
		(layer "F.Cu")
		(net "M_F_CPU0_SB_DQ<28>")
	)
	(segment
		(start 423.610278 -198.415402)
		(end 423.361612 -198.166736)
		(width 0.20066)
		(layer "F.Cu")
		(net "M_F_CPU0_SB_DQ<28>")
	)
	(segment
		(start 379.78588 -227.36683)
		(end 379.78588 -226.831144)
		(width 0.20066)
		(layer "F.Cu")
		(net "M_F_CPU0_SB_DQ<28>")
	)
	(segment
		(start 424.085512 -198.415402)
		(end 423.610278 -198.415402)
		(width 0.20066)
		(layer "F.Cu")
		(net "M_F_CPU0_SB_DQ<28>")
	)
	(segment
		(start 423.361612 -198.166736)
		(end 421.840914 -198.166736)
		(width 0.20066)
		(layer "F.Cu")
		(net "M_F_CPU0_SB_DQ<28>")
	)
	(segment
		(start 427.792896 -198.16699)
		(end 427.36135 -197.735444)
		(width 0.20066)
		(layer "F.Cu")
		(net "M_F_CPU0_SB_DQ<28>")
	)
	(segment
		(start 424.78325 -197.741794)
		(end 424.73626 -197.741794)
		(width 0.101854)
		(layer "F.Cu")
		(net "M_F_CPU0_SB_DQ<28>")
	)
	(segment
		(start 426.951394 -197.735444)
		(end 426.945044 -197.741794)
		(width 0.1016)
		(layer "F.Cu")
		(net "M_F_CPU0_SB_DQ<28>")
	)
	(segment
		(start 429.38446 -198.16699)
		(end 427.792896 -198.16699)
		(width 0.20066)
		(layer "F.Cu")
		(net "M_F_CPU0_SB_DQ<28>")
	)
	(segment
		(start 429.384714 -198.166736)
		(end 429.38446 -198.16699)
		(width 0.20066)
		(layer "F.Cu")
		(net "M_F_CPU0_SB_DQ<28>")
	)
	(segment
		(start 424.73626 -197.741794)
		(end 424.391582 -197.741794)
		(width 0.20066)
		(layer "F.Cu")
		(net "M_F_CPU0_SB_DQ<28>")
	)
	(segment
		(start 427.36135 -197.735444)
		(end 426.951394 -197.735444)
		(width 0.20066)
		(layer "F.Cu")
		(net "M_F_CPU0_SB_DQ<28>")
	)
	(segment
		(start 421.840914 -198.166736)
		(end 420.736014 -198.166736)
		(width 0.20066)
		(layer "F.Cu")
		(net "M_F_CPU0_SB_DQ<28>")
	)
	(segment
		(start 424.391582 -197.741794)
		(end 424.273472 -197.859904)
		(width 0.20066)
		(layer "F.Cu")
		(net "M_F_CPU0_SB_DQ<28>")
	)
	(segment
		(start 424.273472 -198.227442)
		(end 424.085512 -198.415402)
		(width 0.20066)
		(layer "F.Cu")
		(net "M_F_CPU0_SB_DQ<28>")
	)
	(segment
		(start 383.262632 -219.830396)
		(end 383.25044 -219.837508)
		(width 0.088646)
		(layer "In4.Cu")
		(net "M_F_CPU0_SB_DQ<28>")
	)
	(segment
		(start 419.109652 -197.887844)
		(end 418.926772 -198.070724)
		(width 0.18288)
		(layer "In4.Cu")
		(net "M_F_CPU0_SB_DQ<28>")
	)
	(segment
		(start 414.41116 -197.819264)
		(end 414.0454 -197.819264)
		(width 0.18288)
		(layer "In4.Cu")
		(net "M_F_CPU0_SB_DQ<28>")
	)
	(segment
		(start 417.539932 -197.742048)
		(end 417.212272 -197.742048)
		(width 0.18288)
		(layer "In4.Cu")
		(net "M_F_CPU0_SB_DQ<28>")
	)
	(segment
		(start 420.736014 -198.166736)
		(end 420.233094 -197.663816)
		(width 0.18288)
		(layer "In4.Cu")
		(net "M_F_CPU0_SB_DQ<28>")
	)
	(segment
		(start 384.767582 -219.830396)
		(end 384.757168 -219.8243)
		(width 0.088646)
		(layer "In4.Cu")
		(net "M_F_CPU0_SB_DQ<28>")
	)
	(segment
		(start 379.973078 -226.506786)
		(end 379.981968 -226.511866)
		(width 0.088646)
		(layer "In4.Cu")
		(net "M_F_CPU0_SB_DQ<28>")
	)
	(segment
		(start 387.35762 -219.22105)
		(end 387.213348 -219.365322)
		(width 0.088646)
		(layer "In4.Cu")
		(net "M_F_CPU0_SB_DQ<28>")
	)
	(segment
		(start 382.801368 -220.639132)
		(end 382.792478 -220.644212)
		(width 0.088646)
		(layer "In4.Cu")
		(net "M_F_CPU0_SB_DQ<28>")
	)
	(segment
		(start 418.926772 -198.070724)
		(end 418.599112 -198.070724)
		(width 0.18288)
		(layer "In4.Cu")
		(net "M_F_CPU0_SB_DQ<28>")
	)
	(segment
		(start 380.630684 -222.746062)
		(end 380.630684 -222.761556)
		(width 0.088646)
		(layer "In4.Cu")
		(net "M_F_CPU0_SB_DQ<28>")
	)
	(segment
		(start 401.862544 -201.17181)
		(end 398.869408 -205.650846)
		(width 0.18288)
		(layer "In4.Cu")
		(net "M_F_CPU0_SB_DQ<28>")
	)
	(segment
		(start 382.331722 -221.453202)
		(end 382.322832 -221.458282)
		(width 0.088646)
		(layer "In4.Cu")
		(net "M_F_CPU0_SB_DQ<28>")
	)
	(segment
		(start 381.478536 -222.272098)
		(end 381.468122 -222.266002)
		(width 0.088646)
		(layer "In4.Cu")
		(net "M_F_CPU0_SB_DQ<28>")
	)
	(segment
		(start 408.370024 -197.875906)
		(end 405.158448 -197.875906)
		(width 0.18288)
		(layer "In4.Cu")
		(net "M_F_CPU0_SB_DQ<28>")
	)
	(segment
		(start 412.254192 -196.887592)
		(end 411.670754 -197.47103)
		(width 0.18288)
		(layer "In4.Cu")
		(net "M_F_CPU0_SB_DQ<28>")
	)
	(segment
		(start 387.213348 -219.365322)
		(end 387.213348 -219.665042)
		(width 0.088646)
		(layer "In4.Cu")
		(net "M_F_CPU0_SB_DQ<28>")
	)
	(segment
		(start 417.029392 -197.559168)
		(end 417.029392 -197.19798)
		(width 0.18288)
		(layer "In4.Cu")
		(net "M_F_CPU0_SB_DQ<28>")
	)
	(segment
		(start 382.322832 -221.458282)
		(end 382.320038 -221.459806)
		(width 0.088646)
		(layer "In4.Cu")
		(net "M_F_CPU0_SB_DQ<28>")
	)
	(segment
		(start 408.7749 -197.47103)
		(end 408.370024 -197.875906)
		(width 0.18288)
		(layer "In4.Cu")
		(net "M_F_CPU0_SB_DQ<28>")
	)
	(segment
		(start 380.16053 -223.568006)
		(end 380.16053 -223.575626)
		(width 0.088646)
		(layer "In4.Cu")
		(net "M_F_CPU0_SB_DQ<28>")
	)
	(segment
		(start 418.233352 -197.0151)
		(end 417.905692 -197.0151)
		(width 0.18288)
		(layer "In4.Cu")
		(net "M_F_CPU0_SB_DQ<28>")
	)
	(segment
		(start 379.690884 -224.373948)
		(end 379.690884 -224.404936)
		(width 0.088646)
		(layer "In4.Cu")
		(net "M_F_CPU0_SB_DQ<28>")
	)
	(segment
		(start 379.690884 -225.99523)
		(end 379.690884 -226.032822)
		(width 0.088646)
		(layer "In4.Cu")
		(net "M_F_CPU0_SB_DQ<28>")
	)
	(segment
		(start 398.869408 -205.650846)
		(end 396.92453 -210.345528)
		(width 0.18288)
		(layer "In4.Cu")
		(net "M_F_CPU0_SB_DQ<28>")
	)
	(segment
		(start 417.722812 -197.559168)
		(end 417.539932 -197.742048)
		(width 0.18288)
		(layer "In4.Cu")
		(net "M_F_CPU0_SB_DQ<28>")
	)
	(segment
		(start 417.905692 -197.0151)
		(end 417.722812 -197.19798)
		(width 0.18288)
		(layer "In4.Cu")
		(net "M_F_CPU0_SB_DQ<28>")
	)
	(segment
		(start 414.0454 -197.819264)
		(end 413.862266 -197.63613)
		(width 0.18288)
		(layer "In4.Cu")
		(net "M_F_CPU0_SB_DQ<28>")
	)
	(segment
		(start 382.04013 -221.94774)
		(end 382.04013 -221.956376)
		(width 0.088646)
		(layer "In4.Cu")
		(net "M_F_CPU0_SB_DQ<28>")
	)
	(segment
		(start 420.233094 -197.1929)
		(end 420.055294 -197.0151)
		(width 0.18288)
		(layer "In4.Cu")
		(net "M_F_CPU0_SB_DQ<28>")
	)
	(segment
		(start 387.213348 -219.665042)
		(end 387.084062 -219.794328)
		(width 0.088646)
		(layer "In4.Cu")
		(net "M_F_CPU0_SB_DQ<28>")
	)
	(segment
		(start 405.158448 -197.875906)
		(end 401.862544 -201.17181)
		(width 0.18288)
		(layer "In4.Cu")
		(net "M_F_CPU0_SB_DQ<28>")
	)
	(segment
		(start 396.92453 -210.345528)
		(end 388.049008 -219.22105)
		(width 0.18288)
		(layer "In4.Cu")
		(net "M_F_CPU0_SB_DQ<28>")
	)
	(segment
		(start 379.973078 -224.8789)
		(end 379.981968 -224.88398)
		(width 0.088646)
		(layer "In4.Cu")
		(net "M_F_CPU0_SB_DQ<28>")
	)
	(segment
		(start 413.862266 -197.047612)
		(end 413.702246 -196.887592)
		(width 0.18288)
		(layer "In4.Cu")
		(net "M_F_CPU0_SB_DQ<28>")
	)
	(segment
		(start 413.862266 -197.63613)
		(end 413.862266 -197.047612)
		(width 0.18288)
		(layer "In4.Cu")
		(net "M_F_CPU0_SB_DQ<28>")
	)
	(segment
		(start 417.029392 -197.19798)
		(end 416.846512 -197.0151)
		(width 0.18288)
		(layer "In4.Cu")
		(net "M_F_CPU0_SB_DQ<28>")
	)
	(segment
		(start 413.702246 -196.887592)
		(end 412.254192 -196.887592)
		(width 0.18288)
		(layer "In4.Cu")
		(net "M_F_CPU0_SB_DQ<28>")
	)
	(segment
		(start 385.707382 -219.830396)
		(end 385.69265 -219.82176)
		(width 0.088646)
		(layer "In4.Cu")
		(net "M_F_CPU0_SB_DQ<28>")
	)
	(segment
		(start 418.599112 -198.070724)
		(end 418.416232 -197.887844)
		(width 0.18288)
		(layer "In4.Cu")
		(net "M_F_CPU0_SB_DQ<28>")
	)
	(segment
		(start 386.647182 -219.830396)
		(end 386.63245 -219.82176)
		(width 0.088646)
		(layer "In4.Cu")
		(net "M_F_CPU0_SB_DQ<28>")
	)
	(segment
		(start 419.292532 -197.0151)
		(end 419.109652 -197.19798)
		(width 0.18288)
		(layer "In4.Cu")
		(net "M_F_CPU0_SB_DQ<28>")
	)
	(segment
		(start 379.981968 -225.522536)
		(end 379.973078 -225.527616)
		(width 0.088646)
		(layer "In4.Cu")
		(net "M_F_CPU0_SB_DQ<28>")
	)
	(segment
		(start 387.084062 -219.794328)
		(end 387.021578 -219.830396)
		(width 0.088646)
		(layer "In4.Cu")
		(net "M_F_CPU0_SB_DQ<28>")
	)
	(segment
		(start 418.416232 -197.887844)
		(end 418.416232 -197.19798)
		(width 0.18288)
		(layer "In4.Cu")
		(net "M_F_CPU0_SB_DQ<28>")
	)
	(segment
		(start 418.416232 -197.19798)
		(end 418.233352 -197.0151)
		(width 0.18288)
		(layer "In4.Cu")
		(net "M_F_CPU0_SB_DQ<28>")
	)
	(segment
		(start 419.109652 -197.19798)
		(end 419.109652 -197.887844)
		(width 0.18288)
		(layer "In4.Cu")
		(net "M_F_CPU0_SB_DQ<28>")
	)
	(segment
		(start 380.155958 -226.773994)
		(end 380.098808 -226.831144)
		(width 0.088646)
		(layer "In4.Cu")
		(net "M_F_CPU0_SB_DQ<28>")
	)
	(segment
		(start 382.320038 -221.459806)
		(end 382.316736 -221.461838)
		(width 0.088646)
		(layer "In4.Cu")
		(net "M_F_CPU0_SB_DQ<28>")
	)
	(segment
		(start 417.212272 -197.742048)
		(end 417.029392 -197.559168)
		(width 0.18288)
		(layer "In4.Cu")
		(net "M_F_CPU0_SB_DQ<28>")
	)
	(segment
		(start 380.452122 -223.080834)
		(end 380.443232 -223.085914)
		(width 0.088646)
		(layer "In4.Cu")
		(net "M_F_CPU0_SB_DQ<28>")
	)
	(segment
		(start 387.49351 -219.22105)
		(end 387.35762 -219.22105)
		(width 0.088646)
		(layer "In4.Cu")
		(net "M_F_CPU0_SB_DQ<28>")
	)
	(segment
		(start 420.055294 -197.0151)
		(end 419.292532 -197.0151)
		(width 0.18288)
		(layer "In4.Cu")
		(net "M_F_CPU0_SB_DQ<28>")
	)
	(segment
		(start 388.049008 -219.22105)
		(end 387.49351 -219.22105)
		(width 0.18288)
		(layer "In4.Cu")
		(net "M_F_CPU0_SB_DQ<28>")
	)
	(segment
		(start 382.510284 -221.111826)
		(end 382.510284 -221.133924)
		(width 0.088646)
		(layer "In4.Cu")
		(net "M_F_CPU0_SB_DQ<28>")
	)
	(segment
		(start 420.233094 -197.663816)
		(end 420.233094 -197.1929)
		(width 0.18288)
		(layer "In4.Cu")
		(net "M_F_CPU0_SB_DQ<28>")
	)
	(segment
		(start 414.60166 -197.628764)
		(end 414.41116 -197.819264)
		(width 0.18288)
		(layer "In4.Cu")
		(net "M_F_CPU0_SB_DQ<28>")
	)
	(segment
		(start 417.722812 -197.19798)
		(end 417.722812 -197.559168)
		(width 0.18288)
		(layer "In4.Cu")
		(net "M_F_CPU0_SB_DQ<28>")
	)
	(segment
		(start 416.846512 -197.0151)
		(end 415.945828 -197.0151)
		(width 0.18288)
		(layer "In4.Cu")
		(net "M_F_CPU0_SB_DQ<28>")
	)
	(segment
		(start 415.945828 -197.0151)
		(end 415.621978 -196.880988)
		(width 0.18288)
		(layer "In4.Cu")
		(net "M_F_CPU0_SB_DQ<28>")
	)
	(segment
		(start 411.670754 -197.47103)
		(end 408.7749 -197.47103)
		(width 0.18288)
		(layer "In4.Cu")
		(net "M_F_CPU0_SB_DQ<28>")
	)
	(segment
		(start 379.981968 -223.894904)
		(end 379.973078 -223.899984)
		(width 0.088646)
		(layer "In4.Cu")
		(net "M_F_CPU0_SB_DQ<28>")
	)
	(segment
		(start 380.098808 -226.831144)
		(end 379.78588 -226.831144)
		(width 0.088646)
		(layer "In4.Cu")
		(net "M_F_CPU0_SB_DQ<28>")
	)
	(segment
		(start 415.621978 -196.880988)
		(end 414.76168 -196.880988)
		(width 0.18288)
		(layer "In4.Cu")
		(net "M_F_CPU0_SB_DQ<28>")
	)
	(segment
		(start 414.76168 -196.880988)
		(end 414.60166 -197.041008)
		(width 0.18288)
		(layer "In4.Cu")
		(net "M_F_CPU0_SB_DQ<28>")
	)
	(segment
		(start 414.60166 -197.041008)
		(end 414.60166 -197.628764)
		(width 0.18288)
		(layer "In4.Cu")
		(net "M_F_CPU0_SB_DQ<28>")
	)
	(arc
		(start 386.081778 -219.830396)
		(mid 385.89458 -219.880539)
		(end 385.707382 -219.830396)
		(width 0.088646)
		(layer "In4.Cu")
		(net "M_F_CPU0_SB_DQ<28>")
	)
	(arc
		(start 379.973078 -225.527616)
		(mid 379.771796 -225.725103)
		(end 379.690884 -225.99523)
		(width 0.088646)
		(layer "In4.Cu")
		(net "M_F_CPU0_SB_DQ<28>")
	)
	(arc
		(start 380.630684 -222.761556)
		(mid 380.583005 -222.944456)
		(end 380.452122 -223.080834)
		(width 0.088646)
		(layer "In4.Cu")
		(net "M_F_CPU0_SB_DQ<28>")
	)
	(arc
		(start 379.973078 -223.899984)
		(mid 379.770255 -224.100215)
		(end 379.690884 -224.373948)
		(width 0.088646)
		(layer "In4.Cu")
		(net "M_F_CPU0_SB_DQ<28>")
	)
	(arc
		(start 382.97993 -220.319854)
		(mid 382.932251 -220.502754)
		(end 382.801368 -220.639132)
		(width 0.088646)
		(layer "In4.Cu")
		(net "M_F_CPU0_SB_DQ<28>")
	)
	(arc
		(start 380.912878 -222.272098)
		(mid 380.710055 -222.472329)
		(end 380.630684 -222.746062)
		(width 0.088646)
		(layer "In4.Cu")
		(net "M_F_CPU0_SB_DQ<28>")
	)
	(arc
		(start 380.16053 -223.575626)
		(mid 380.112851 -223.758526)
		(end 379.981968 -223.894904)
		(width 0.088646)
		(layer "In4.Cu")
		(net "M_F_CPU0_SB_DQ<28>")
	)
	(arc
		(start 387.021578 -219.830396)
		(mid 386.83438 -219.880539)
		(end 386.647182 -219.830396)
		(width 0.088646)
		(layer "In4.Cu")
		(net "M_F_CPU0_SB_DQ<28>")
	)
	(arc
		(start 384.202432 -219.830396)
		(mid 384.015234 -219.880539)
		(end 383.828036 -219.830396)
		(width 0.088646)
		(layer "In4.Cu")
		(net "M_F_CPU0_SB_DQ<28>")
	)
	(arc
		(start 379.690884 -226.032822)
		(mid 379.770254 -226.306556)
		(end 379.973078 -226.506786)
		(width 0.088646)
		(layer "In4.Cu")
		(net "M_F_CPU0_SB_DQ<28>")
	)
	(arc
		(start 383.25044 -219.837508)
		(mid 383.052212 -220.043356)
		(end 382.97993 -220.319854)
		(width 0.088646)
		(layer "In4.Cu")
		(net "M_F_CPU0_SB_DQ<28>")
	)
	(arc
		(start 379.981968 -226.511866)
		(mid 380.097777 -226.623795)
		(end 380.155958 -226.773994)
		(width 0.088646)
		(layer "In4.Cu")
		(net "M_F_CPU0_SB_DQ<28>")
	)
	(arc
		(start 379.981968 -224.88398)
		(mid 380.160565 -225.203258)
		(end 379.981968 -225.522536)
		(width 0.088646)
		(layer "In4.Cu")
		(net "M_F_CPU0_SB_DQ<28>")
	)
	(arc
		(start 385.141978 -219.830396)
		(mid 384.95478 -219.880539)
		(end 384.767582 -219.830396)
		(width 0.088646)
		(layer "In4.Cu")
		(net "M_F_CPU0_SB_DQ<28>")
	)
	(arc
		(start 382.510284 -221.133924)
		(mid 382.462605 -221.316824)
		(end 382.331722 -221.453202)
		(width 0.088646)
		(layer "In4.Cu")
		(net "M_F_CPU0_SB_DQ<28>")
	)
	(arc
		(start 382.792478 -220.644212)
		(mid 382.591196 -220.841699)
		(end 382.510284 -221.111826)
		(width 0.088646)
		(layer "In4.Cu")
		(net "M_F_CPU0_SB_DQ<28>")
	)
	(arc
		(start 383.828036 -219.830396)
		(mid 383.545334 -219.75462)
		(end 383.262632 -219.830396)
		(width 0.088646)
		(layer "In4.Cu")
		(net "M_F_CPU0_SB_DQ<28>")
	)
	(arc
		(start 385.69265 -219.82176)
		(mid 385.416175 -219.75444)
		(end 385.141978 -219.830396)
		(width 0.088646)
		(layer "In4.Cu")
		(net "M_F_CPU0_SB_DQ<28>")
	)
	(arc
		(start 386.63245 -219.82176)
		(mid 386.355975 -219.75444)
		(end 386.081778 -219.830396)
		(width 0.088646)
		(layer "In4.Cu")
		(net "M_F_CPU0_SB_DQ<28>")
	)
	(arc
		(start 384.757168 -219.8243)
		(mid 384.47899 -219.754577)
		(end 384.202432 -219.830396)
		(width 0.088646)
		(layer "In4.Cu")
		(net "M_F_CPU0_SB_DQ<28>")
	)
	(arc
		(start 381.852932 -222.272098)
		(mid 381.665734 -222.322241)
		(end 381.478536 -222.272098)
		(width 0.088646)
		(layer "In4.Cu")
		(net "M_F_CPU0_SB_DQ<28>")
	)
	(arc
		(start 382.04013 -221.956376)
		(mid 381.98786 -222.138741)
		(end 381.852932 -222.272098)
		(width 0.088646)
		(layer "In4.Cu")
		(net "M_F_CPU0_SB_DQ<28>")
	)
	(arc
		(start 382.316736 -221.461838)
		(mid 382.114149 -221.668189)
		(end 382.04013 -221.94774)
		(width 0.088646)
		(layer "In4.Cu")
		(net "M_F_CPU0_SB_DQ<28>")
	)
	(arc
		(start 379.690884 -224.404936)
		(mid 379.770254 -224.67867)
		(end 379.973078 -224.8789)
		(width 0.088646)
		(layer "In4.Cu")
		(net "M_F_CPU0_SB_DQ<28>")
	)
	(arc
		(start 380.443232 -223.085914)
		(mid 380.23816 -223.289593)
		(end 380.16053 -223.568006)
		(width 0.088646)
		(layer "In4.Cu")
		(net "M_F_CPU0_SB_DQ<28>")
	)
	(arc
		(start 381.468122 -222.266002)
		(mid 381.18969 -222.196156)
		(end 380.912878 -222.272098)
		(width 0.088646)
		(layer "In4.Cu")
		(net "M_F_CPU0_SB_DQ<28>")
	)
	(segment
		(start 427.639226 -201.56678)
		(end 428.07128 -201.998834)
		(width 0.20066)
		(layer "F.Cu")
		(net "M_F_CPU0_SB_DQ<27>")
	)
	(segment
		(start 432.15052 -201.56678)
		(end 433.484782 -201.56678)
		(width 0.20066)
		(layer "F.Cu")
		(net "M_F_CPU0_SB_DQ<27>")
	)
	(segment
		(start 428.363126 -201.998834)
		(end 428.367952 -201.998834)
		(width 0.101854)
		(layer "F.Cu")
		(net "M_F_CPU0_SB_DQ<27>")
	)
	(segment
		(start 431.514504 -201.314812)
		(end 431.898552 -201.314812)
		(width 0.20066)
		(layer "F.Cu")
		(net "M_F_CPU0_SB_DQ<27>")
	)
	(segment
		(start 431.280316 -201.549)
		(end 431.514504 -201.314812)
		(width 0.20066)
		(layer "F.Cu")
		(net "M_F_CPU0_SB_DQ<27>")
	)
	(segment
		(start 379.78588 -228.994716)
		(end 379.78588 -228.45903)
		(width 0.20066)
		(layer "F.Cu")
		(net "M_F_CPU0_SB_DQ<27>")
	)
	(segment
		(start 428.375064 -201.991722)
		(end 430.382934 -201.991722)
		(width 0.1016)
		(layer "F.Cu")
		(net "M_F_CPU0_SB_DQ<27>")
	)
	(segment
		(start 431.898552 -201.314812)
		(end 432.15052 -201.56678)
		(width 0.20066)
		(layer "F.Cu")
		(net "M_F_CPU0_SB_DQ<27>")
	)
	(segment
		(start 428.367952 -201.998834)
		(end 428.375064 -201.991722)
		(width 0.1016)
		(layer "F.Cu")
		(net "M_F_CPU0_SB_DQ<27>")
	)
	(segment
		(start 428.07128 -201.998834)
		(end 428.363126 -201.998834)
		(width 0.20066)
		(layer "F.Cu")
		(net "M_F_CPU0_SB_DQ<27>")
	)
	(segment
		(start 424.836082 -201.56678)
		(end 425.940982 -201.56678)
		(width 0.20066)
		(layer "F.Cu")
		(net "M_F_CPU0_SB_DQ<27>")
	)
	(segment
		(start 431.076354 -202.003914)
		(end 431.280316 -201.799952)
		(width 0.20066)
		(layer "F.Cu")
		(net "M_F_CPU0_SB_DQ<27>")
	)
	(segment
		(start 379.786134 -228.99497)
		(end 379.78588 -228.994716)
		(width 0.20066)
		(layer "F.Cu")
		(net "M_F_CPU0_SB_DQ<27>")
	)
	(segment
		(start 430.395126 -202.003914)
		(end 431.076354 -202.003914)
		(width 0.20066)
		(layer "F.Cu")
		(net "M_F_CPU0_SB_DQ<27>")
	)
	(segment
		(start 430.382934 -201.991722)
		(end 430.395126 -202.003914)
		(width 0.1016)
		(layer "F.Cu")
		(net "M_F_CPU0_SB_DQ<27>")
	)
	(segment
		(start 425.940982 -201.56678)
		(end 427.639226 -201.56678)
		(width 0.20066)
		(layer "F.Cu")
		(net "M_F_CPU0_SB_DQ<27>")
	)
	(segment
		(start 431.280316 -201.799952)
		(end 431.280316 -201.549)
		(width 0.20066)
		(layer "F.Cu")
		(net "M_F_CPU0_SB_DQ<27>")
	)
	(segment
		(start 420.036244 -203.571602)
		(end 419.204902 -203.571602)
		(width 0.18288)
		(layer "In4.Cu")
		(net "M_F_CPU0_SB_DQ<27>")
	)
	(segment
		(start 423.248074 -202.27163)
		(end 422.76649 -202.27163)
		(width 0.18288)
		(layer "In4.Cu")
		(net "M_F_CPU0_SB_DQ<27>")
	)
	(segment
		(start 422.76649 -202.27163)
		(end 422.48201 -202.55611)
		(width 0.18288)
		(layer "In4.Cu")
		(net "M_F_CPU0_SB_DQ<27>")
	)
	(segment
		(start 382.888236 -227.320602)
		(end 382.879346 -227.325682)
		(width 0.088646)
		(layer "In4.Cu")
		(net "M_F_CPU0_SB_DQ<27>")
	)
	(segment
		(start 384.297936 -224.8789)
		(end 384.289046 -224.88398)
		(width 0.088646)
		(layer "In4.Cu")
		(net "M_F_CPU0_SB_DQ<27>")
	)
	(segment
		(start 387.387084 -222.631)
		(end 387.142736 -222.386652)
		(width 0.088646)
		(layer "In4.Cu")
		(net "M_F_CPU0_SB_DQ<27>")
	)
	(segment
		(start 380.32944 -228.875844)
		(end 379.981206 -228.60889)
		(width 0.088646)
		(layer "In4.Cu")
		(net "M_F_CPU0_SB_DQ<27>")
	)
	(segment
		(start 385.237736 -223.251268)
		(end 385.228846 -223.256348)
		(width 0.088646)
		(layer "In4.Cu")
		(net "M_F_CPU0_SB_DQ<27>")
	)
	(segment
		(start 423.568114 -203.230226)
		(end 423.408094 -203.070206)
		(width 0.18288)
		(layer "In4.Cu")
		(net "M_F_CPU0_SB_DQ<27>")
	)
	(segment
		(start 424.836082 -201.56678)
		(end 424.442128 -201.172826)
		(width 0.18288)
		(layer "In4.Cu")
		(net "M_F_CPU0_SB_DQ<27>")
	)
	(segment
		(start 382.230884 -228.450394)
		(end 382.230884 -228.468936)
		(width 0.088646)
		(layer "In4.Cu")
		(net "M_F_CPU0_SB_DQ<27>")
	)
	(segment
		(start 423.408094 -203.070206)
		(end 423.408094 -202.43165)
		(width 0.18288)
		(layer "In4.Cu")
		(net "M_F_CPU0_SB_DQ<27>")
	)
	(segment
		(start 412.614872 -202.844146)
		(end 412.480506 -202.978512)
		(width 0.18288)
		(layer "In4.Cu")
		(net "M_F_CPU0_SB_DQ<27>")
	)
	(segment
		(start 409.357576 -202.978512)
		(end 409.210256 -202.831192)
		(width 0.18288)
		(layer "In4.Cu")
		(net "M_F_CPU0_SB_DQ<27>")
	)
	(segment
		(start 387.142736 -222.386652)
		(end 386.83438 -222.386652)
		(width 0.088646)
		(layer "In4.Cu")
		(net "M_F_CPU0_SB_DQ<27>")
	)
	(segment
		(start 379.981206 -228.60889)
		(end 379.78588 -228.45903)
		(width 0.088646)
		(layer "In4.Cu")
		(net "M_F_CPU0_SB_DQ<27>")
	)
	(segment
		(start 419.204902 -203.571602)
		(end 418.84981 -203.926694)
		(width 0.18288)
		(layer "In4.Cu")
		(net "M_F_CPU0_SB_DQ<27>")
	)
	(segment
		(start 424.373294 -202.885294)
		(end 424.028362 -203.230226)
		(width 0.18288)
		(layer "In4.Cu")
		(net "M_F_CPU0_SB_DQ<27>")
	)
	(segment
		(start 383.828036 -225.69297)
		(end 383.819146 -225.69805)
		(width 0.088646)
		(layer "In4.Cu")
		(net "M_F_CPU0_SB_DQ<27>")
	)
	(segment
		(start 418.84981 -203.926694)
		(end 418.006022 -203.926694)
		(width 0.18288)
		(layer "In4.Cu")
		(net "M_F_CPU0_SB_DQ<27>")
	)
	(segment
		(start 416.442144 -203.528676)
		(end 415.74466 -202.831192)
		(width 0.18288)
		(layer "In4.Cu")
		(net "M_F_CPU0_SB_DQ<27>")
	)
	(segment
		(start 405.364442 -202.831192)
		(end 405.17699 -203.018644)
		(width 0.18288)
		(layer "In4.Cu")
		(net "M_F_CPU0_SB_DQ<27>")
	)
	(segment
		(start 382.894332 -227.317046)
		(end 382.888236 -227.320602)
		(width 0.088646)
		(layer "In4.Cu")
		(net "M_F_CPU0_SB_DQ<27>")
	)
	(segment
		(start 383.358136 -226.506786)
		(end 383.349246 -226.511866)
		(width 0.088646)
		(layer "In4.Cu")
		(net "M_F_CPU0_SB_DQ<27>")
	)
	(segment
		(start 399.909538 -211.759038)
		(end 389.037576 -222.631)
		(width 0.18288)
		(layer "In4.Cu")
		(net "M_F_CPU0_SB_DQ<27>")
	)
	(segment
		(start 381.008382 -228.948234)
		(end 381.001016 -228.952552)
		(width 0.088646)
		(layer "In4.Cu")
		(net "M_F_CPU0_SB_DQ<27>")
	)
	(segment
		(start 389.037576 -222.631)
		(end 387.69671 -222.631)
		(width 0.18288)
		(layer "In4.Cu")
		(net "M_F_CPU0_SB_DQ<27>")
	)
	(segment
		(start 420.156894 -203.692252)
		(end 420.036244 -203.571602)
		(width 0.18288)
		(layer "In4.Cu")
		(net "M_F_CPU0_SB_DQ<27>")
	)
	(segment
		(start 405.17699 -203.018644)
		(end 405.17699 -204.413866)
		(width 0.18288)
		(layer "In4.Cu")
		(net "M_F_CPU0_SB_DQ<27>")
	)
	(segment
		(start 381.012954 -228.945694)
		(end 381.008382 -228.948234)
		(width 0.088646)
		(layer "In4.Cu")
		(net "M_F_CPU0_SB_DQ<27>")
	)
	(segment
		(start 382.700784 -227.64496)
		(end 382.700784 -227.659184)
		(width 0.088646)
		(layer "In4.Cu")
		(net "M_F_CPU0_SB_DQ<27>")
	)
	(segment
		(start 399.909792 -211.75853)
		(end 399.909538 -211.759038)
		(width 0.18288)
		(layer "In4.Cu")
		(net "M_F_CPU0_SB_DQ<27>")
	)
	(segment
		(start 409.210256 -202.831192)
		(end 405.364442 -202.831192)
		(width 0.18288)
		(layer "In4.Cu")
		(net "M_F_CPU0_SB_DQ<27>")
	)
	(segment
		(start 384.767836 -224.065084)
		(end 384.758946 -224.070164)
		(width 0.088646)
		(layer "In4.Cu")
		(net "M_F_CPU0_SB_DQ<27>")
	)
	(segment
		(start 383.640584 -226.017328)
		(end 383.640584 -226.027234)
		(width 0.088646)
		(layer "In4.Cu")
		(net "M_F_CPU0_SB_DQ<27>")
	)
	(segment
		(start 418.006022 -203.926694)
		(end 417.608004 -203.528676)
		(width 0.18288)
		(layer "In4.Cu")
		(net "M_F_CPU0_SB_DQ<27>")
	)
	(segment
		(start 380.443232 -228.948234)
		(end 380.403354 -228.92512)
		(width 0.088646)
		(layer "In4.Cu")
		(net "M_F_CPU0_SB_DQ<27>")
	)
	(segment
		(start 384.773932 -224.061528)
		(end 384.767836 -224.065084)
		(width 0.088646)
		(layer "In4.Cu")
		(net "M_F_CPU0_SB_DQ<27>")
	)
	(segment
		(start 424.442128 -201.172826)
		(end 424.170094 -201.172826)
		(width 0.18288)
		(layer "In4.Cu")
		(net "M_F_CPU0_SB_DQ<27>")
	)
	(segment
		(start 417.608004 -203.528676)
		(end 416.442144 -203.528676)
		(width 0.18288)
		(layer "In4.Cu")
		(net "M_F_CPU0_SB_DQ<27>")
	)
	(segment
		(start 424.373294 -202.138026)
		(end 424.373294 -202.885294)
		(width 0.18288)
		(layer "In4.Cu")
		(net "M_F_CPU0_SB_DQ<27>")
	)
	(segment
		(start 387.69671 -222.631)
		(end 387.387084 -222.631)
		(width 0.088646)
		(layer "In4.Cu")
		(net "M_F_CPU0_SB_DQ<27>")
	)
	(segment
		(start 424.017694 -201.325226)
		(end 424.017694 -201.782426)
		(width 0.18288)
		(layer "In4.Cu")
		(net "M_F_CPU0_SB_DQ<27>")
	)
	(segment
		(start 422.48201 -203.532232)
		(end 422.32199 -203.692252)
		(width 0.18288)
		(layer "In4.Cu")
		(net "M_F_CPU0_SB_DQ<27>")
	)
	(segment
		(start 412.480506 -202.978512)
		(end 409.357576 -202.978512)
		(width 0.18288)
		(layer "In4.Cu")
		(net "M_F_CPU0_SB_DQ<27>")
	)
	(segment
		(start 424.017694 -201.782426)
		(end 424.373294 -202.138026)
		(width 0.18288)
		(layer "In4.Cu")
		(net "M_F_CPU0_SB_DQ<27>")
	)
	(segment
		(start 401.378928 -208.211928)
		(end 399.909792 -211.75853)
		(width 0.18288)
		(layer "In4.Cu")
		(net "M_F_CPU0_SB_DQ<27>")
	)
	(segment
		(start 422.48201 -202.55611)
		(end 422.48201 -203.532232)
		(width 0.18288)
		(layer "In4.Cu")
		(net "M_F_CPU0_SB_DQ<27>")
	)
	(segment
		(start 412.614872 -202.831192)
		(end 412.614872 -202.844146)
		(width 0.18288)
		(layer "In4.Cu")
		(net "M_F_CPU0_SB_DQ<27>")
	)
	(segment
		(start 422.32199 -203.692252)
		(end 420.156894 -203.692252)
		(width 0.18288)
		(layer "In4.Cu")
		(net "M_F_CPU0_SB_DQ<27>")
	)
	(segment
		(start 415.74466 -202.831192)
		(end 412.614872 -202.831192)
		(width 0.18288)
		(layer "In4.Cu")
		(net "M_F_CPU0_SB_DQ<27>")
	)
	(segment
		(start 381.383032 -228.948488)
		(end 381.383032 -228.948234)
		(width 0.088646)
		(layer "In4.Cu")
		(net "M_F_CPU0_SB_DQ<27>")
	)
	(segment
		(start 385.520184 -222.761556)
		(end 385.520184 -222.77578)
		(width 0.088646)
		(layer "In4.Cu")
		(net "M_F_CPU0_SB_DQ<27>")
	)
	(segment
		(start 384.110484 -225.203258)
		(end 384.110484 -225.2218)
		(width 0.088646)
		(layer "In4.Cu")
		(net "M_F_CPU0_SB_DQ<27>")
	)
	(segment
		(start 405.17699 -204.413866)
		(end 401.378928 -208.211928)
		(width 0.18288)
		(layer "In4.Cu")
		(net "M_F_CPU0_SB_DQ<27>")
	)
	(segment
		(start 384.580384 -224.389442)
		(end 384.580384 -224.399348)
		(width 0.088646)
		(layer "In4.Cu")
		(net "M_F_CPU0_SB_DQ<27>")
	)
	(segment
		(start 385.707636 -222.437198)
		(end 385.698746 -222.442278)
		(width 0.088646)
		(layer "In4.Cu")
		(net "M_F_CPU0_SB_DQ<27>")
	)
	(segment
		(start 423.408094 -202.43165)
		(end 423.248074 -202.27163)
		(width 0.18288)
		(layer "In4.Cu")
		(net "M_F_CPU0_SB_DQ<27>")
	)
	(segment
		(start 424.170094 -201.172826)
		(end 424.017694 -201.325226)
		(width 0.18288)
		(layer "In4.Cu")
		(net "M_F_CPU0_SB_DQ<27>")
	)
	(segment
		(start 424.028362 -203.230226)
		(end 423.568114 -203.230226)
		(width 0.18288)
		(layer "In4.Cu")
		(net "M_F_CPU0_SB_DQ<27>")
	)
	(arc
		(start 386.83438 -222.386652)
		(mid 386.731618 -222.401166)
		(end 386.636768 -222.443294)
		(width 0.088646)
		(layer "In4.Cu")
		(net "M_F_CPU0_SB_DQ<27>")
	)
	(arc
		(start 386.636768 -222.443294)
		(mid 386.35859 -222.513017)
		(end 386.082032 -222.437198)
		(width 0.088646)
		(layer "In4.Cu")
		(net "M_F_CPU0_SB_DQ<27>")
	)
	(arc
		(start 382.700784 -227.659184)
		(mid 382.621565 -227.933869)
		(end 382.418082 -228.134672)
		(width 0.088646)
		(layer "In4.Cu")
		(net "M_F_CPU0_SB_DQ<27>")
	)
	(arc
		(start 383.349246 -226.511866)
		(mid 383.218332 -226.648226)
		(end 383.170684 -226.831144)
		(width 0.088646)
		(layer "In4.Cu")
		(net "M_F_CPU0_SB_DQ<27>")
	)
	(arc
		(start 384.580384 -224.399348)
		(mid 384.502273 -224.676297)
		(end 384.297936 -224.8789)
		(width 0.088646)
		(layer "In4.Cu")
		(net "M_F_CPU0_SB_DQ<27>")
	)
	(arc
		(start 383.819146 -225.69805)
		(mid 383.688232 -225.83441)
		(end 383.640584 -226.017328)
		(width 0.088646)
		(layer "In4.Cu")
		(net "M_F_CPU0_SB_DQ<27>")
	)
	(arc
		(start 385.228846 -223.256348)
		(mid 385.097932 -223.392708)
		(end 385.050284 -223.575626)
		(width 0.088646)
		(layer "In4.Cu")
		(net "M_F_CPU0_SB_DQ<27>")
	)
	(arc
		(start 383.640584 -226.027234)
		(mid 383.562473 -226.304183)
		(end 383.358136 -226.506786)
		(width 0.088646)
		(layer "In4.Cu")
		(net "M_F_CPU0_SB_DQ<27>")
	)
	(arc
		(start 385.520184 -222.77578)
		(mid 385.441043 -223.050403)
		(end 385.237736 -223.251268)
		(width 0.088646)
		(layer "In4.Cu")
		(net "M_F_CPU0_SB_DQ<27>")
	)
	(arc
		(start 382.418082 -228.134672)
		(mid 382.283149 -228.268026)
		(end 382.230884 -228.450394)
		(width 0.088646)
		(layer "In4.Cu")
		(net "M_F_CPU0_SB_DQ<27>")
	)
	(arc
		(start 385.698746 -222.442278)
		(mid 385.567832 -222.578638)
		(end 385.520184 -222.761556)
		(width 0.088646)
		(layer "In4.Cu")
		(net "M_F_CPU0_SB_DQ<27>")
	)
	(arc
		(start 381.383032 -228.948234)
		(mid 381.198338 -228.898133)
		(end 381.012954 -228.945694)
		(width 0.088646)
		(layer "In4.Cu")
		(net "M_F_CPU0_SB_DQ<27>")
	)
	(arc
		(start 383.170684 -226.831144)
		(mid 383.096768 -227.110646)
		(end 382.894332 -227.317046)
		(width 0.088646)
		(layer "In4.Cu")
		(net "M_F_CPU0_SB_DQ<27>")
	)
	(arc
		(start 382.230884 -228.468936)
		(mid 382.152773 -228.745885)
		(end 381.948436 -228.948488)
		(width 0.088646)
		(layer "In4.Cu")
		(net "M_F_CPU0_SB_DQ<27>")
	)
	(arc
		(start 384.289046 -224.88398)
		(mid 384.158132 -225.02034)
		(end 384.110484 -225.203258)
		(width 0.088646)
		(layer "In4.Cu")
		(net "M_F_CPU0_SB_DQ<27>")
	)
	(arc
		(start 385.050284 -223.575626)
		(mid 384.976368 -223.855128)
		(end 384.773932 -224.061528)
		(width 0.088646)
		(layer "In4.Cu")
		(net "M_F_CPU0_SB_DQ<27>")
	)
	(arc
		(start 381.948436 -228.948488)
		(mid 381.665734 -229.024264)
		(end 381.383032 -228.948488)
		(width 0.088646)
		(layer "In4.Cu")
		(net "M_F_CPU0_SB_DQ<27>")
	)
	(arc
		(start 382.879346 -227.325682)
		(mid 382.748432 -227.462042)
		(end 382.700784 -227.64496)
		(width 0.088646)
		(layer "In4.Cu")
		(net "M_F_CPU0_SB_DQ<27>")
	)
	(arc
		(start 384.758946 -224.070164)
		(mid 384.628032 -224.206524)
		(end 384.580384 -224.389442)
		(width 0.088646)
		(layer "In4.Cu")
		(net "M_F_CPU0_SB_DQ<27>")
	)
	(arc
		(start 386.082032 -222.437198)
		(mid 385.894834 -222.387055)
		(end 385.707636 -222.437198)
		(width 0.088646)
		(layer "In4.Cu")
		(net "M_F_CPU0_SB_DQ<27>")
	)
	(arc
		(start 384.110484 -225.2218)
		(mid 384.030322 -225.493989)
		(end 383.828036 -225.69297)
		(width 0.088646)
		(layer "In4.Cu")
		(net "M_F_CPU0_SB_DQ<27>")
	)
	(arc
		(start 381.001016 -228.952552)
		(mid 380.721555 -229.024021)
		(end 380.443232 -228.948234)
		(width 0.088646)
		(layer "In4.Cu")
		(net "M_F_CPU0_SB_DQ<27>")
	)
	(arc
		(start 380.403354 -228.92512)
		(mid 380.365587 -228.901697)
		(end 380.32944 -228.875844)
		(width 0.088646)
		(layer "In4.Cu")
		(net "M_F_CPU0_SB_DQ<27>")
	)
	(segment
		(start 428.363126 -203.698856)
		(end 428.367952 -203.698856)
		(width 0.101854)
		(layer "F.Cu")
		(net "M_F_CPU0_SB_DQ<26>")
	)
	(segment
		(start 428.375064 -203.691744)
		(end 430.382934 -203.691744)
		(width 0.1016)
		(layer "F.Cu")
		(net "M_F_CPU0_SB_DQ<26>")
	)
	(segment
		(start 430.395126 -203.703936)
		(end 431.076354 -203.703936)
		(width 0.20066)
		(layer "F.Cu")
		(net "M_F_CPU0_SB_DQ<26>")
	)
	(segment
		(start 425.940982 -203.266802)
		(end 427.639226 -203.266802)
		(width 0.20066)
		(layer "F.Cu")
		(net "M_F_CPU0_SB_DQ<26>")
	)
	(segment
		(start 431.280316 -203.499974)
		(end 431.280316 -203.249022)
		(width 0.20066)
		(layer "F.Cu")
		(net "M_F_CPU0_SB_DQ<26>")
	)
	(segment
		(start 431.898552 -203.014834)
		(end 432.15052 -203.266802)
		(width 0.20066)
		(layer "F.Cu")
		(net "M_F_CPU0_SB_DQ<26>")
	)
	(segment
		(start 428.07128 -203.698856)
		(end 428.363126 -203.698856)
		(width 0.20066)
		(layer "F.Cu")
		(net "M_F_CPU0_SB_DQ<26>")
	)
	(segment
		(start 431.076354 -203.703936)
		(end 431.280316 -203.499974)
		(width 0.20066)
		(layer "F.Cu")
		(net "M_F_CPU0_SB_DQ<26>")
	)
	(segment
		(start 379.316234 -229.808532)
		(end 379.316234 -229.272846)
		(width 0.20066)
		(layer "F.Cu")
		(net "M_F_CPU0_SB_DQ<26>")
	)
	(segment
		(start 424.836082 -203.266802)
		(end 425.940982 -203.266802)
		(width 0.20066)
		(layer "F.Cu")
		(net "M_F_CPU0_SB_DQ<26>")
	)
	(segment
		(start 427.639226 -203.266802)
		(end 428.07128 -203.698856)
		(width 0.20066)
		(layer "F.Cu")
		(net "M_F_CPU0_SB_DQ<26>")
	)
	(segment
		(start 428.367952 -203.698856)
		(end 428.375064 -203.691744)
		(width 0.1016)
		(layer "F.Cu")
		(net "M_F_CPU0_SB_DQ<26>")
	)
	(segment
		(start 432.15052 -203.266802)
		(end 433.484782 -203.266802)
		(width 0.20066)
		(layer "F.Cu")
		(net "M_F_CPU0_SB_DQ<26>")
	)
	(segment
		(start 379.31598 -229.808786)
		(end 379.316234 -229.808532)
		(width 0.20066)
		(layer "F.Cu")
		(net "M_F_CPU0_SB_DQ<26>")
	)
	(segment
		(start 431.514504 -203.014834)
		(end 431.898552 -203.014834)
		(width 0.20066)
		(layer "F.Cu")
		(net "M_F_CPU0_SB_DQ<26>")
	)
	(segment
		(start 430.382934 -203.691744)
		(end 430.395126 -203.703936)
		(width 0.1016)
		(layer "F.Cu")
		(net "M_F_CPU0_SB_DQ<26>")
	)
	(segment
		(start 431.280316 -203.249022)
		(end 431.514504 -203.014834)
		(width 0.20066)
		(layer "F.Cu")
		(net "M_F_CPU0_SB_DQ<26>")
	)
	(segment
		(start 420.9288 -205.39202)
		(end 420.549832 -205.39202)
		(width 0.18288)
		(layer "In4.Cu")
		(net "M_F_CPU0_SB_DQ<26>")
	)
	(segment
		(start 406.307798 -206.218028)
		(end 404.857458 -206.218028)
		(width 0.18288)
		(layer "In4.Cu")
		(net "M_F_CPU0_SB_DQ<26>")
	)
	(segment
		(start 385.237736 -224.8789)
		(end 385.228846 -224.88398)
		(width 0.088646)
		(layer "In4.Cu")
		(net "M_F_CPU0_SB_DQ<26>")
	)
	(segment
		(start 423.484294 -204.482446)
		(end 423.204894 -204.203046)
		(width 0.18288)
		(layer "In4.Cu")
		(net "M_F_CPU0_SB_DQ<26>")
	)
	(segment
		(start 387.69671 -223.642936)
		(end 387.020054 -223.642936)
		(width 0.088646)
		(layer "In4.Cu")
		(net "M_F_CPU0_SB_DQ<26>")
	)
	(segment
		(start 383.828036 -227.320602)
		(end 383.819146 -227.325682)
		(width 0.088646)
		(layer "In4.Cu")
		(net "M_F_CPU0_SB_DQ<26>")
	)
	(segment
		(start 424.330368 -203.772516)
		(end 424.330368 -205.19517)
		(width 0.18288)
		(layer "In4.Cu")
		(net "M_F_CPU0_SB_DQ<26>")
	)
	(segment
		(start 379.973332 -229.762304)
		(end 379.91034 -229.72522)
		(width 0.088646)
		(layer "In4.Cu")
		(net "M_F_CPU0_SB_DQ<26>")
	)
	(segment
		(start 424.330368 -205.19517)
		(end 424.16476 -205.360778)
		(width 0.18288)
		(layer "In4.Cu")
		(net "M_F_CPU0_SB_DQ<26>")
	)
	(segment
		(start 382.894332 -228.944932)
		(end 382.888236 -228.948488)
		(width 0.088646)
		(layer "In4.Cu")
		(net "M_F_CPU0_SB_DQ<26>")
	)
	(segment
		(start 382.418336 -229.762304)
		(end 382.418082 -229.762304)
		(width 0.088646)
		(layer "In4.Cu")
		(net "M_F_CPU0_SB_DQ<26>")
	)
	(segment
		(start 382.888236 -228.948488)
		(end 382.879346 -228.953568)
		(width 0.088646)
		(layer "In4.Cu")
		(net "M_F_CPU0_SB_DQ<26>")
	)
	(segment
		(start 385.050284 -225.203258)
		(end 385.050284 -225.217482)
		(width 0.088646)
		(layer "In4.Cu")
		(net "M_F_CPU0_SB_DQ<26>")
	)
	(segment
		(start 408.904694 -205.668626)
		(end 406.8572 -205.668626)
		(width 0.18288)
		(layer "In4.Cu")
		(net "M_F_CPU0_SB_DQ<26>")
	)
	(segment
		(start 423.204894 -204.203046)
		(end 422.117774 -204.203046)
		(width 0.18288)
		(layer "In4.Cu")
		(net "M_F_CPU0_SB_DQ<26>")
	)
	(segment
		(start 380.918974 -229.765606)
		(end 380.913132 -229.762304)
		(width 0.088646)
		(layer "In4.Cu")
		(net "M_F_CPU0_SB_DQ<26>")
	)
	(segment
		(start 385.707636 -224.065084)
		(end 385.698746 -224.070164)
		(width 0.088646)
		(layer "In4.Cu")
		(net "M_F_CPU0_SB_DQ<26>")
	)
	(segment
		(start 401.188936 -211.887816)
		(end 389.433816 -223.642936)
		(width 0.18288)
		(layer "In4.Cu")
		(net "M_F_CPU0_SB_DQ<26>")
	)
	(segment
		(start 385.990084 -223.575626)
		(end 385.990084 -223.585532)
		(width 0.088646)
		(layer "In4.Cu")
		(net "M_F_CPU0_SB_DQ<26>")
	)
	(segment
		(start 414.556702 -204.369162)
		(end 414.182306 -204.369162)
		(width 0.18288)
		(layer "In4.Cu")
		(net "M_F_CPU0_SB_DQ<26>")
	)
	(segment
		(start 414.739582 -204.552042)
		(end 414.556702 -204.369162)
		(width 0.18288)
		(layer "In4.Cu")
		(net "M_F_CPU0_SB_DQ<26>")
	)
	(segment
		(start 413.999426 -204.552042)
		(end 413.999426 -205.250542)
		(width 0.18288)
		(layer "In4.Cu")
		(net "M_F_CPU0_SB_DQ<26>")
	)
	(segment
		(start 384.110484 -226.831144)
		(end 384.110484 -226.84105)
		(width 0.088646)
		(layer "In4.Cu")
		(net "M_F_CPU0_SB_DQ<26>")
	)
	(segment
		(start 423.484294 -205.188566)
		(end 423.484294 -204.482446)
		(width 0.18288)
		(layer "In4.Cu")
		(net "M_F_CPU0_SB_DQ<26>")
	)
	(segment
		(start 384.297936 -226.506786)
		(end 384.289046 -226.511866)
		(width 0.088646)
		(layer "In4.Cu")
		(net "M_F_CPU0_SB_DQ<26>")
	)
	(segment
		(start 383.640584 -227.64496)
		(end 383.640584 -227.663502)
		(width 0.088646)
		(layer "In4.Cu")
		(net "M_F_CPU0_SB_DQ<26>")
	)
	(segment
		(start 406.8572 -205.668626)
		(end 406.307798 -206.218028)
		(width 0.18288)
		(layer "In4.Cu")
		(net "M_F_CPU0_SB_DQ<26>")
	)
	(segment
		(start 424.836082 -203.266802)
		(end 424.330368 -203.772516)
		(width 0.18288)
		(layer "In4.Cu")
		(net "M_F_CPU0_SB_DQ<26>")
	)
	(segment
		(start 381.852932 -229.762304)
		(end 381.848614 -229.759764)
		(width 0.088646)
		(layer "In4.Cu")
		(net "M_F_CPU0_SB_DQ<26>")
	)
	(segment
		(start 414.182306 -204.369162)
		(end 413.999426 -204.552042)
		(width 0.18288)
		(layer "In4.Cu")
		(net "M_F_CPU0_SB_DQ<26>")
	)
	(segment
		(start 402.604478 -208.471008)
		(end 401.188936 -211.887816)
		(width 0.18288)
		(layer "In4.Cu")
		(net "M_F_CPU0_SB_DQ<26>")
	)
	(segment
		(start 414.739582 -205.178406)
		(end 414.739582 -204.552042)
		(width 0.18288)
		(layer "In4.Cu")
		(net "M_F_CPU0_SB_DQ<26>")
	)
	(segment
		(start 415.128202 -205.567026)
		(end 414.739582 -205.178406)
		(width 0.18288)
		(layer "In4.Cu")
		(net "M_F_CPU0_SB_DQ<26>")
	)
	(segment
		(start 420.470838 -205.313026)
		(end 416.270694 -205.313026)
		(width 0.18288)
		(layer "In4.Cu")
		(net "M_F_CPU0_SB_DQ<26>")
	)
	(segment
		(start 409.260294 -205.313026)
		(end 408.904694 -205.668626)
		(width 0.18288)
		(layer "In4.Cu")
		(net "M_F_CPU0_SB_DQ<26>")
	)
	(segment
		(start 412.86049 -205.592426)
		(end 412.58109 -205.313026)
		(width 0.18288)
		(layer "In4.Cu")
		(net "M_F_CPU0_SB_DQ<26>")
	)
	(segment
		(start 416.270694 -205.313026)
		(end 416.016694 -205.567026)
		(width 0.18288)
		(layer "In4.Cu")
		(net "M_F_CPU0_SB_DQ<26>")
	)
	(segment
		(start 424.16476 -205.360778)
		(end 423.656506 -205.360778)
		(width 0.18288)
		(layer "In4.Cu")
		(net "M_F_CPU0_SB_DQ<26>")
	)
	(segment
		(start 382.700784 -229.272846)
		(end 382.700784 -229.282752)
		(width 0.088646)
		(layer "In4.Cu")
		(net "M_F_CPU0_SB_DQ<26>")
	)
	(segment
		(start 383.358136 -228.134672)
		(end 383.349246 -228.139752)
		(width 0.088646)
		(layer "In4.Cu")
		(net "M_F_CPU0_SB_DQ<26>")
	)
	(segment
		(start 413.999426 -205.250542)
		(end 413.657542 -205.592426)
		(width 0.18288)
		(layer "In4.Cu")
		(net "M_F_CPU0_SB_DQ<26>")
	)
	(segment
		(start 416.016694 -205.567026)
		(end 415.128202 -205.567026)
		(width 0.18288)
		(layer "In4.Cu")
		(net "M_F_CPU0_SB_DQ<26>")
	)
	(segment
		(start 385.520184 -224.389442)
		(end 385.520184 -224.399348)
		(width 0.088646)
		(layer "In4.Cu")
		(net "M_F_CPU0_SB_DQ<26>")
	)
	(segment
		(start 412.58109 -205.313026)
		(end 411.44952 -205.313026)
		(width 0.18288)
		(layer "In4.Cu")
		(net "M_F_CPU0_SB_DQ<26>")
	)
	(segment
		(start 389.433816 -223.642936)
		(end 387.69671 -223.642936)
		(width 0.18288)
		(layer "In4.Cu")
		(net "M_F_CPU0_SB_DQ<26>")
	)
	(segment
		(start 380.913132 -229.762304)
		(end 380.90729 -229.758748)
		(width 0.088646)
		(layer "In4.Cu")
		(net "M_F_CPU0_SB_DQ<26>")
	)
	(segment
		(start 413.657542 -205.592426)
		(end 412.86049 -205.592426)
		(width 0.18288)
		(layer "In4.Cu")
		(net "M_F_CPU0_SB_DQ<26>")
	)
	(segment
		(start 404.857458 -206.218028)
		(end 402.604478 -208.471008)
		(width 0.18288)
		(layer "In4.Cu")
		(net "M_F_CPU0_SB_DQ<26>")
	)
	(segment
		(start 379.83668 -229.675436)
		(end 379.316234 -229.272846)
		(width 0.088646)
		(layer "In4.Cu")
		(net "M_F_CPU0_SB_DQ<26>")
	)
	(segment
		(start 423.656506 -205.360778)
		(end 423.484294 -205.188566)
		(width 0.18288)
		(layer "In4.Cu")
		(net "M_F_CPU0_SB_DQ<26>")
	)
	(segment
		(start 422.117774 -204.203046)
		(end 420.9288 -205.39202)
		(width 0.18288)
		(layer "In4.Cu")
		(net "M_F_CPU0_SB_DQ<26>")
	)
	(segment
		(start 387.020054 -223.642936)
		(end 386.736336 -223.359218)
		(width 0.088646)
		(layer "In4.Cu")
		(net "M_F_CPU0_SB_DQ<26>")
	)
	(segment
		(start 384.580384 -226.008692)
		(end 384.580384 -226.027234)
		(width 0.088646)
		(layer "In4.Cu")
		(net "M_F_CPU0_SB_DQ<26>")
	)
	(segment
		(start 386.177536 -223.251268)
		(end 386.168646 -223.256348)
		(width 0.088646)
		(layer "In4.Cu")
		(net "M_F_CPU0_SB_DQ<26>")
	)
	(segment
		(start 410.7561 -205.662276)
		(end 410.40685 -205.313026)
		(width 0.18288)
		(layer "In4.Cu")
		(net "M_F_CPU0_SB_DQ<26>")
	)
	(segment
		(start 420.549832 -205.39202)
		(end 420.470838 -205.313026)
		(width 0.18288)
		(layer "In4.Cu")
		(net "M_F_CPU0_SB_DQ<26>")
	)
	(segment
		(start 411.44952 -205.313026)
		(end 411.10027 -205.662276)
		(width 0.18288)
		(layer "In4.Cu")
		(net "M_F_CPU0_SB_DQ<26>")
	)
	(segment
		(start 386.736336 -223.359218)
		(end 386.551932 -223.251268)
		(width 0.088646)
		(layer "In4.Cu")
		(net "M_F_CPU0_SB_DQ<26>")
	)
	(segment
		(start 410.40685 -205.313026)
		(end 409.260294 -205.313026)
		(width 0.18288)
		(layer "In4.Cu")
		(net "M_F_CPU0_SB_DQ<26>")
	)
	(segment
		(start 411.10027 -205.662276)
		(end 410.7561 -205.662276)
		(width 0.18288)
		(layer "In4.Cu")
		(net "M_F_CPU0_SB_DQ<26>")
	)
	(segment
		(start 379.979174 -229.765606)
		(end 379.973332 -229.762304)
		(width 0.088646)
		(layer "In4.Cu")
		(net "M_F_CPU0_SB_DQ<26>")
	)
	(arc
		(start 384.767582 -225.69297)
		(mid 384.632649 -225.826324)
		(end 384.580384 -226.008692)
		(width 0.088646)
		(layer "In4.Cu")
		(net "M_F_CPU0_SB_DQ<26>")
	)
	(arc
		(start 385.990084 -223.585532)
		(mid 385.911973 -223.862481)
		(end 385.707636 -224.065084)
		(width 0.088646)
		(layer "In4.Cu")
		(net "M_F_CPU0_SB_DQ<26>")
	)
	(arc
		(start 384.110484 -226.84105)
		(mid 384.032373 -227.117999)
		(end 383.828036 -227.320602)
		(width 0.088646)
		(layer "In4.Cu")
		(net "M_F_CPU0_SB_DQ<26>")
	)
	(arc
		(start 383.640584 -227.663502)
		(mid 383.560422 -227.935691)
		(end 383.358136 -228.134672)
		(width 0.088646)
		(layer "In4.Cu")
		(net "M_F_CPU0_SB_DQ<26>")
	)
	(arc
		(start 384.580384 -226.027234)
		(mid 384.502273 -226.304183)
		(end 384.297936 -226.506786)
		(width 0.088646)
		(layer "In4.Cu")
		(net "M_F_CPU0_SB_DQ<26>")
	)
	(arc
		(start 383.349246 -228.139752)
		(mid 383.218332 -228.276112)
		(end 383.170684 -228.45903)
		(width 0.088646)
		(layer "In4.Cu")
		(net "M_F_CPU0_SB_DQ<26>")
	)
	(arc
		(start 381.848614 -229.759764)
		(mid 381.663119 -229.712095)
		(end 381.478282 -229.762304)
		(width 0.088646)
		(layer "In4.Cu")
		(net "M_F_CPU0_SB_DQ<26>")
	)
	(arc
		(start 382.418082 -229.762304)
		(mid 382.135524 -229.837953)
		(end 381.852932 -229.762304)
		(width 0.088646)
		(layer "In4.Cu")
		(net "M_F_CPU0_SB_DQ<26>")
	)
	(arc
		(start 379.91034 -229.72522)
		(mid 379.872729 -229.701483)
		(end 379.83668 -229.675436)
		(width 0.088646)
		(layer "In4.Cu")
		(net "M_F_CPU0_SB_DQ<26>")
	)
	(arc
		(start 385.520184 -224.399348)
		(mid 385.442073 -224.676297)
		(end 385.237736 -224.8789)
		(width 0.088646)
		(layer "In4.Cu")
		(net "M_F_CPU0_SB_DQ<26>")
	)
	(arc
		(start 380.90729 -229.758748)
		(mid 380.722405 -229.711955)
		(end 380.538482 -229.762304)
		(width 0.088646)
		(layer "In4.Cu")
		(net "M_F_CPU0_SB_DQ<26>")
	)
	(arc
		(start 385.698746 -224.070164)
		(mid 385.567832 -224.206524)
		(end 385.520184 -224.389442)
		(width 0.088646)
		(layer "In4.Cu")
		(net "M_F_CPU0_SB_DQ<26>")
	)
	(arc
		(start 382.879346 -228.953568)
		(mid 382.748432 -229.089928)
		(end 382.700784 -229.272846)
		(width 0.088646)
		(layer "In4.Cu")
		(net "M_F_CPU0_SB_DQ<26>")
	)
	(arc
		(start 383.819146 -227.325682)
		(mid 383.688232 -227.462042)
		(end 383.640584 -227.64496)
		(width 0.088646)
		(layer "In4.Cu")
		(net "M_F_CPU0_SB_DQ<26>")
	)
	(arc
		(start 385.050284 -225.217482)
		(mid 384.971065 -225.492167)
		(end 384.767582 -225.69297)
		(width 0.088646)
		(layer "In4.Cu")
		(net "M_F_CPU0_SB_DQ<26>")
	)
	(arc
		(start 384.289046 -226.511866)
		(mid 384.158132 -226.648226)
		(end 384.110484 -226.831144)
		(width 0.088646)
		(layer "In4.Cu")
		(net "M_F_CPU0_SB_DQ<26>")
	)
	(arc
		(start 380.538482 -229.762304)
		(mid 380.259279 -229.837944)
		(end 379.979174 -229.765606)
		(width 0.088646)
		(layer "In4.Cu")
		(net "M_F_CPU0_SB_DQ<26>")
	)
	(arc
		(start 386.551932 -223.251268)
		(mid 386.364734 -223.201125)
		(end 386.177536 -223.251268)
		(width 0.088646)
		(layer "In4.Cu")
		(net "M_F_CPU0_SB_DQ<26>")
	)
	(arc
		(start 386.168646 -223.256348)
		(mid 386.037732 -223.392708)
		(end 385.990084 -223.575626)
		(width 0.088646)
		(layer "In4.Cu")
		(net "M_F_CPU0_SB_DQ<26>")
	)
	(arc
		(start 383.170684 -228.45903)
		(mid 383.096768 -228.738532)
		(end 382.894332 -228.944932)
		(width 0.088646)
		(layer "In4.Cu")
		(net "M_F_CPU0_SB_DQ<26>")
	)
	(arc
		(start 381.478282 -229.762304)
		(mid 381.199079 -229.837944)
		(end 380.918974 -229.765606)
		(width 0.088646)
		(layer "In4.Cu")
		(net "M_F_CPU0_SB_DQ<26>")
	)
	(arc
		(start 385.228846 -224.88398)
		(mid 385.097932 -225.02034)
		(end 385.050284 -225.203258)
		(width 0.088646)
		(layer "In4.Cu")
		(net "M_F_CPU0_SB_DQ<26>")
	)
	(arc
		(start 382.700784 -229.282752)
		(mid 382.622673 -229.559701)
		(end 382.418336 -229.762304)
		(width 0.088646)
		(layer "In4.Cu")
		(net "M_F_CPU0_SB_DQ<26>")
	)
	(segment
		(start 377.906534 -228.99497)
		(end 377.90628 -228.994716)
		(width 0.20066)
		(layer "F.Cu")
		(net "M_F_CPU0_SB_DQ<25>")
	)
	(segment
		(start 426.951394 -201.985372)
		(end 426.945044 -201.991722)
		(width 0.1016)
		(layer "F.Cu")
		(net "M_F_CPU0_SB_DQ<25>")
	)
	(segment
		(start 423.361612 -202.416664)
		(end 421.840914 -202.416664)
		(width 0.20066)
		(layer "F.Cu")
		(net "M_F_CPU0_SB_DQ<25>")
	)
	(segment
		(start 429.384714 -202.416664)
		(end 429.38446 -202.416918)
		(width 0.20066)
		(layer "F.Cu")
		(net "M_F_CPU0_SB_DQ<25>")
	)
	(segment
		(start 421.840914 -202.416664)
		(end 420.736014 -202.416664)
		(width 0.20066)
		(layer "F.Cu")
		(net "M_F_CPU0_SB_DQ<25>")
	)
	(segment
		(start 424.391582 -201.991722)
		(end 424.273472 -202.109832)
		(width 0.20066)
		(layer "F.Cu")
		(net "M_F_CPU0_SB_DQ<25>")
	)
	(segment
		(start 377.90628 -228.994716)
		(end 377.90628 -228.45903)
		(width 0.20066)
		(layer "F.Cu")
		(net "M_F_CPU0_SB_DQ<25>")
	)
	(segment
		(start 427.792896 -202.416918)
		(end 427.36135 -201.985372)
		(width 0.20066)
		(layer "F.Cu")
		(net "M_F_CPU0_SB_DQ<25>")
	)
	(segment
		(start 427.36135 -201.985372)
		(end 426.951394 -201.985372)
		(width 0.20066)
		(layer "F.Cu")
		(net "M_F_CPU0_SB_DQ<25>")
	)
	(segment
		(start 424.73626 -201.991722)
		(end 424.391582 -201.991722)
		(width 0.20066)
		(layer "F.Cu")
		(net "M_F_CPU0_SB_DQ<25>")
	)
	(segment
		(start 424.756326 -201.991722)
		(end 424.73626 -201.991722)
		(width 0.101854)
		(layer "F.Cu")
		(net "M_F_CPU0_SB_DQ<25>")
	)
	(segment
		(start 424.273472 -202.109832)
		(end 424.273472 -202.47737)
		(width 0.20066)
		(layer "F.Cu")
		(net "M_F_CPU0_SB_DQ<25>")
	)
	(segment
		(start 424.085512 -202.66533)
		(end 423.610278 -202.66533)
		(width 0.20066)
		(layer "F.Cu")
		(net "M_F_CPU0_SB_DQ<25>")
	)
	(segment
		(start 426.945044 -201.991722)
		(end 424.756326 -201.991722)
		(width 0.1016)
		(layer "F.Cu")
		(net "M_F_CPU0_SB_DQ<25>")
	)
	(segment
		(start 423.610278 -202.66533)
		(end 423.361612 -202.416664)
		(width 0.20066)
		(layer "F.Cu")
		(net "M_F_CPU0_SB_DQ<25>")
	)
	(segment
		(start 429.38446 -202.416918)
		(end 427.792896 -202.416918)
		(width 0.20066)
		(layer "F.Cu")
		(net "M_F_CPU0_SB_DQ<25>")
	)
	(segment
		(start 424.273472 -202.47737)
		(end 424.085512 -202.66533)
		(width 0.20066)
		(layer "F.Cu")
		(net "M_F_CPU0_SB_DQ<25>")
	)
	(segment
		(start 417.971732 -202.275186)
		(end 417.971732 -202.831446)
		(width 0.18288)
		(layer "In4.Cu")
		(net "M_F_CPU0_SB_DQ<25>")
	)
	(segment
		(start 414.43656 -201.36231)
		(end 414.1089 -201.36231)
		(width 0.18288)
		(layer "In4.Cu")
		(net "M_F_CPU0_SB_DQ<25>")
	)
	(segment
		(start 387.69671 -222.11919)
		(end 387.460744 -222.11919)
		(width 0.088646)
		(layer "In4.Cu")
		(net "M_F_CPU0_SB_DQ<25>")
	)
	(segment
		(start 404.166578 -203.093574)
		(end 403.823932 -203.606654)
		(width 0.18288)
		(layer "In4.Cu")
		(net "M_F_CPU0_SB_DQ<25>")
	)
	(segment
		(start 383.450084 -225.998786)
		(end 383.450084 -226.017328)
		(width 0.088646)
		(layer "In4.Cu")
		(net "M_F_CPU0_SB_DQ<25>")
	)
	(segment
		(start 384.211322 -224.70872)
		(end 384.202432 -224.7138)
		(width 0.088646)
		(layer "In4.Cu")
		(net "M_F_CPU0_SB_DQ<25>")
	)
	(segment
		(start 411.26791 -202.290426)
		(end 411.08503 -202.473306)
		(width 0.18288)
		(layer "In4.Cu")
		(net "M_F_CPU0_SB_DQ<25>")
	)
	(segment
		(start 412.611316 -202.136248)
		(end 412.133542 -201.658474)
		(width 0.18288)
		(layer "In4.Cu")
		(net "M_F_CPU0_SB_DQ<25>")
	)
	(segment
		(start 380.538482 -228.783388)
		(end 380.536958 -228.782372)
		(width 0.088646)
		(layer "In4.Cu")
		(net "M_F_CPU0_SB_DQ<25>")
	)
	(segment
		(start 382.331722 -227.964238)
		(end 382.322832 -227.969318)
		(width 0.088646)
		(layer "In4.Cu")
		(net "M_F_CPU0_SB_DQ<25>")
	)
	(segment
		(start 404.358602 -204.403198)
		(end 404.17623 -204.675994)
		(width 0.18288)
		(layer "In4.Cu")
		(net "M_F_CPU0_SB_DQ<25>")
	)
	(segment
		(start 388.845298 -222.11919)
		(end 387.69671 -222.11919)
		(width 0.18288)
		(layer "In4.Cu")
		(net "M_F_CPU0_SB_DQ<25>")
	)
	(segment
		(start 399.447766 -211.516468)
		(end 399.447512 -211.516976)
		(width 0.18288)
		(layer "In4.Cu")
		(net "M_F_CPU0_SB_DQ<25>")
	)
	(segment
		(start 417.971732 -202.831446)
		(end 417.811712 -202.991466)
		(width 0.18288)
		(layer "In4.Cu")
		(net "M_F_CPU0_SB_DQ<25>")
	)
	(segment
		(start 403.823932 -203.606654)
		(end 403.874478 -203.8604)
		(width 0.18288)
		(layer "In4.Cu")
		(net "M_F_CPU0_SB_DQ<25>")
	)
	(segment
		(start 380.920244 -228.779324)
		(end 380.914148 -228.78288)
		(width 0.088646)
		(layer "In4.Cu")
		(net "M_F_CPU0_SB_DQ<25>")
	)
	(segment
		(start 379.973332 -228.134418)
		(end 379.96749 -228.131116)
		(width 0.088646)
		(layer "In4.Cu")
		(net "M_F_CPU0_SB_DQ<25>")
	)
	(segment
		(start 380.914148 -228.78288)
		(end 380.906782 -228.787198)
		(width 0.088646)
		(layer "In4.Cu")
		(net "M_F_CPU0_SB_DQ<25>")
	)
	(segment
		(start 410.57449 -201.841354)
		(end 410.39161 -201.658474)
		(width 0.18288)
		(layer "In4.Cu")
		(net "M_F_CPU0_SB_DQ<25>")
	)
	(segment
		(start 415.837116 -202.136248)
		(end 414.80232 -202.136248)
		(width 0.18288)
		(layer "In4.Cu")
		(net "M_F_CPU0_SB_DQ<25>")
	)
	(segment
		(start 418.55771 -202.102212)
		(end 418.144706 -202.102212)
		(width 0.18288)
		(layer "In4.Cu")
		(net "M_F_CPU0_SB_DQ<25>")
	)
	(segment
		(start 379.979174 -228.137974)
		(end 379.973332 -228.134418)
		(width 0.088646)
		(layer "In4.Cu")
		(net "M_F_CPU0_SB_DQ<25>")
	)
	(segment
		(start 385.601972 -222.27794)
		(end 385.59994 -222.27921)
		(width 0.088646)
		(layer "In4.Cu")
		(net "M_F_CPU0_SB_DQ<25>")
	)
	(segment
		(start 411.26791 -201.841354)
		(end 411.26791 -202.290426)
		(width 0.18288)
		(layer "In4.Cu")
		(net "M_F_CPU0_SB_DQ<25>")
	)
	(segment
		(start 418.87775 -203.038456)
		(end 418.71773 -202.878436)
		(width 0.18288)
		(layer "In4.Cu")
		(net "M_F_CPU0_SB_DQ<25>")
	)
	(segment
		(start 403.310344 -205.151482)
		(end 403.36089 -205.40472)
		(width 0.18288)
		(layer "In4.Cu")
		(net "M_F_CPU0_SB_DQ<25>")
	)
	(segment
		(start 403.178518 -205.677516)
		(end 402.925026 -205.727808)
		(width 0.18288)
		(layer "In4.Cu")
		(net "M_F_CPU0_SB_DQ<25>")
	)
	(segment
		(start 403.103842 -205.01356)
		(end 403.310344 -205.151482)
		(width 0.18288)
		(layer "In4.Cu")
		(net "M_F_CPU0_SB_DQ<25>")
	)
	(segment
		(start 405.105362 -202.15479)
		(end 404.166578 -203.093574)
		(width 0.18288)
		(layer "In4.Cu")
		(net "M_F_CPU0_SB_DQ<25>")
	)
	(segment
		(start 414.1089 -201.36231)
		(end 413.92602 -201.54519)
		(width 0.18288)
		(layer "In4.Cu")
		(net "M_F_CPU0_SB_DQ<25>")
	)
	(segment
		(start 418.144706 -202.102212)
		(end 417.971732 -202.275186)
		(width 0.18288)
		(layer "In4.Cu")
		(net "M_F_CPU0_SB_DQ<25>")
	)
	(segment
		(start 379.033532 -228.134418)
		(end 379.02769 -228.131116)
		(width 0.088646)
		(layer "In4.Cu")
		(net "M_F_CPU0_SB_DQ<25>")
	)
	(segment
		(start 382.04013 -228.444806)
		(end 382.04013 -228.467666)
		(width 0.088646)
		(layer "In4.Cu")
		(net "M_F_CPU0_SB_DQ<25>")
	)
	(segment
		(start 413.92602 -201.953368)
		(end 413.74314 -202.136248)
		(width 0.18288)
		(layer "In4.Cu")
		(net "M_F_CPU0_SB_DQ<25>")
	)
	(segment
		(start 378.600716 -228.159564)
		(end 377.90628 -228.45903)
		(width 0.088646)
		(layer "In4.Cu")
		(net "M_F_CPU0_SB_DQ<25>")
	)
	(segment
		(start 409.637738 -201.658474)
		(end 409.141422 -202.15479)
		(width 0.18288)
		(layer "In4.Cu")
		(net "M_F_CPU0_SB_DQ<25>")
	)
	(segment
		(start 403.922738 -204.726286)
		(end 403.48916 -204.436726)
		(width 0.18288)
		(layer "In4.Cu")
		(net "M_F_CPU0_SB_DQ<25>")
	)
	(segment
		(start 414.80232 -202.136248)
		(end 414.61944 -201.953368)
		(width 0.18288)
		(layer "In4.Cu")
		(net "M_F_CPU0_SB_DQ<25>")
	)
	(segment
		(start 414.61944 -201.953368)
		(end 414.61944 -201.54519)
		(width 0.18288)
		(layer "In4.Cu")
		(net "M_F_CPU0_SB_DQ<25>")
	)
	(segment
		(start 420.736014 -202.416664)
		(end 420.114222 -203.038456)
		(width 0.18288)
		(layer "In4.Cu")
		(net "M_F_CPU0_SB_DQ<25>")
	)
	(segment
		(start 403.05355 -204.760068)
		(end 403.103842 -205.01356)
		(width 0.18288)
		(layer "In4.Cu")
		(net "M_F_CPU0_SB_DQ<25>")
	)
	(segment
		(start 384.389884 -224.373948)
		(end 384.389884 -224.389442)
		(width 0.088646)
		(layer "In4.Cu")
		(net "M_F_CPU0_SB_DQ<25>")
	)
	(segment
		(start 404.308056 -204.14996)
		(end 404.358602 -204.403198)
		(width 0.18288)
		(layer "In4.Cu")
		(net "M_F_CPU0_SB_DQ<25>")
	)
	(segment
		(start 403.48916 -204.436726)
		(end 403.235922 -204.487272)
		(width 0.18288)
		(layer "In4.Cu")
		(net "M_F_CPU0_SB_DQ<25>")
	)
	(segment
		(start 418.71773 -202.262232)
		(end 418.55771 -202.102212)
		(width 0.18288)
		(layer "In4.Cu")
		(net "M_F_CPU0_SB_DQ<25>")
	)
	(segment
		(start 416.692334 -202.991466)
		(end 415.837116 -202.136248)
		(width 0.18288)
		(layer "In4.Cu")
		(net "M_F_CPU0_SB_DQ<25>")
	)
	(segment
		(start 384.85953 -223.561402)
		(end 384.85953 -223.575626)
		(width 0.088646)
		(layer "In4.Cu")
		(net "M_F_CPU0_SB_DQ<25>")
	)
	(segment
		(start 411.45079 -201.658474)
		(end 411.26791 -201.841354)
		(width 0.18288)
		(layer "In4.Cu")
		(net "M_F_CPU0_SB_DQ<25>")
	)
	(segment
		(start 403.36089 -205.40472)
		(end 403.178518 -205.677516)
		(width 0.18288)
		(layer "In4.Cu")
		(net "M_F_CPU0_SB_DQ<25>")
	)
	(segment
		(start 402.465032 -205.640432)
		(end 400.931126 -207.935576)
		(width 0.18288)
		(layer "In4.Cu")
		(net "M_F_CPU0_SB_DQ<25>")
	)
	(segment
		(start 410.57449 -202.290426)
		(end 410.57449 -201.841354)
		(width 0.18288)
		(layer "In4.Cu")
		(net "M_F_CPU0_SB_DQ<25>")
	)
	(segment
		(start 412.133542 -201.658474)
		(end 411.45079 -201.658474)
		(width 0.18288)
		(layer "In4.Cu")
		(net "M_F_CPU0_SB_DQ<25>")
	)
	(segment
		(start 413.74314 -202.136248)
		(end 412.611316 -202.136248)
		(width 0.18288)
		(layer "In4.Cu")
		(net "M_F_CPU0_SB_DQ<25>")
	)
	(segment
		(start 382.510284 -227.629466)
		(end 382.510284 -227.64496)
		(width 0.088646)
		(layer "In4.Cu")
		(net "M_F_CPU0_SB_DQ<25>")
	)
	(segment
		(start 380.305818 -228.518212)
		(end 380.277878 -228.450648)
		(width 0.088646)
		(layer "In4.Cu")
		(net "M_F_CPU0_SB_DQ<25>")
	)
	(segment
		(start 381.478536 -228.783388)
		(end 381.47752 -228.78288)
		(width 0.088646)
		(layer "In4.Cu")
		(net "M_F_CPU0_SB_DQ<25>")
	)
	(segment
		(start 409.141422 -202.15479)
		(end 405.105362 -202.15479)
		(width 0.18288)
		(layer "In4.Cu")
		(net "M_F_CPU0_SB_DQ<25>")
	)
	(segment
		(start 399.447512 -211.516976)
		(end 388.845298 -222.11919)
		(width 0.18288)
		(layer "In4.Cu")
		(net "M_F_CPU0_SB_DQ<25>")
	)
	(segment
		(start 403.874478 -203.8604)
		(end 404.308056 -204.14996)
		(width 0.18288)
		(layer "In4.Cu")
		(net "M_F_CPU0_SB_DQ<25>")
	)
	(segment
		(start 402.925026 -205.727808)
		(end 402.718524 -205.589886)
		(width 0.18288)
		(layer "In4.Cu")
		(net "M_F_CPU0_SB_DQ<25>")
	)
	(segment
		(start 400.931126 -207.935576)
		(end 399.447766 -211.516468)
		(width 0.18288)
		(layer "In4.Cu")
		(net "M_F_CPU0_SB_DQ<25>")
	)
	(segment
		(start 379.039374 -228.137974)
		(end 379.033532 -228.134418)
		(width 0.088646)
		(layer "In4.Cu")
		(net "M_F_CPU0_SB_DQ<25>")
	)
	(segment
		(start 414.61944 -201.54519)
		(end 414.43656 -201.36231)
		(width 0.18288)
		(layer "In4.Cu")
		(net "M_F_CPU0_SB_DQ<25>")
	)
	(segment
		(start 402.718524 -205.589886)
		(end 402.465032 -205.640432)
		(width 0.18288)
		(layer "In4.Cu")
		(net "M_F_CPU0_SB_DQ<25>")
	)
	(segment
		(start 385.612132 -222.272098)
		(end 385.601972 -222.27794)
		(width 0.088646)
		(layer "In4.Cu")
		(net "M_F_CPU0_SB_DQ<25>")
	)
	(segment
		(start 382.801368 -227.150422)
		(end 382.792478 -227.155502)
		(width 0.088646)
		(layer "In4.Cu")
		(net "M_F_CPU0_SB_DQ<25>")
	)
	(segment
		(start 410.75737 -202.473306)
		(end 410.57449 -202.290426)
		(width 0.18288)
		(layer "In4.Cu")
		(net "M_F_CPU0_SB_DQ<25>")
	)
	(segment
		(start 383.919984 -225.193352)
		(end 383.919984 -225.203258)
		(width 0.088646)
		(layer "In4.Cu")
		(net "M_F_CPU0_SB_DQ<25>")
	)
	(segment
		(start 413.92602 -201.54519)
		(end 413.92602 -201.953368)
		(width 0.18288)
		(layer "In4.Cu")
		(net "M_F_CPU0_SB_DQ<25>")
	)
	(segment
		(start 385.150868 -223.080834)
		(end 385.141978 -223.085914)
		(width 0.088646)
		(layer "In4.Cu")
		(net "M_F_CPU0_SB_DQ<25>")
	)
	(segment
		(start 383.262632 -226.341686)
		(end 383.25044 -226.348798)
		(width 0.088646)
		(layer "In4.Cu")
		(net "M_F_CPU0_SB_DQ<25>")
	)
	(segment
		(start 387.460744 -222.11919)
		(end 387.383528 -222.196406)
		(width 0.088646)
		(layer "In4.Cu")
		(net "M_F_CPU0_SB_DQ<25>")
	)
	(segment
		(start 411.08503 -202.473306)
		(end 410.75737 -202.473306)
		(width 0.18288)
		(layer "In4.Cu")
		(net "M_F_CPU0_SB_DQ<25>")
	)
	(segment
		(start 383.741422 -225.522536)
		(end 383.732532 -225.527616)
		(width 0.088646)
		(layer "In4.Cu")
		(net "M_F_CPU0_SB_DQ<25>")
	)
	(segment
		(start 384.680968 -223.894904)
		(end 384.672078 -223.899984)
		(width 0.088646)
		(layer "In4.Cu")
		(net "M_F_CPU0_SB_DQ<25>")
	)
	(segment
		(start 410.39161 -201.658474)
		(end 409.637738 -201.658474)
		(width 0.18288)
		(layer "In4.Cu")
		(net "M_F_CPU0_SB_DQ<25>")
	)
	(segment
		(start 417.811712 -202.991466)
		(end 416.692334 -202.991466)
		(width 0.18288)
		(layer "In4.Cu")
		(net "M_F_CPU0_SB_DQ<25>")
	)
	(segment
		(start 387.383528 -222.196406)
		(end 386.83438 -222.196406)
		(width 0.088646)
		(layer "In4.Cu")
		(net "M_F_CPU0_SB_DQ<25>")
	)
	(segment
		(start 420.114222 -203.038456)
		(end 418.87775 -203.038456)
		(width 0.18288)
		(layer "In4.Cu")
		(net "M_F_CPU0_SB_DQ<25>")
	)
	(segment
		(start 404.17623 -204.675994)
		(end 403.922738 -204.726286)
		(width 0.18288)
		(layer "In4.Cu")
		(net "M_F_CPU0_SB_DQ<25>")
	)
	(segment
		(start 403.235922 -204.487272)
		(end 403.05355 -204.760068)
		(width 0.18288)
		(layer "In4.Cu")
		(net "M_F_CPU0_SB_DQ<25>")
	)
	(segment
		(start 383.271522 -226.336606)
		(end 383.262632 -226.341686)
		(width 0.088646)
		(layer "In4.Cu")
		(net "M_F_CPU0_SB_DQ<25>")
	)
	(segment
		(start 418.71773 -202.878436)
		(end 418.71773 -202.262232)
		(width 0.18288)
		(layer "In4.Cu")
		(net "M_F_CPU0_SB_DQ<25>")
	)
	(arc
		(start 386.177536 -222.272098)
		(mid 385.894834 -222.196322)
		(end 385.612132 -222.272098)
		(width 0.088646)
		(layer "In4.Cu")
		(net "M_F_CPU0_SB_DQ<25>")
	)
	(arc
		(start 379.02769 -228.131116)
		(mid 378.85568 -228.084275)
		(end 378.681488 -228.122226)
		(width 0.088646)
		(layer "In4.Cu")
		(net "M_F_CPU0_SB_DQ<25>")
	)
	(arc
		(start 384.85953 -223.575626)
		(mid 384.811851 -223.758526)
		(end 384.680968 -223.894904)
		(width 0.088646)
		(layer "In4.Cu")
		(net "M_F_CPU0_SB_DQ<25>")
	)
	(arc
		(start 380.536958 -228.782372)
		(mid 380.399729 -228.669247)
		(end 380.305818 -228.518212)
		(width 0.088646)
		(layer "In4.Cu")
		(net "M_F_CPU0_SB_DQ<25>")
	)
	(arc
		(start 379.598682 -228.134418)
		(mid 379.319508 -228.210183)
		(end 379.039374 -228.137974)
		(width 0.088646)
		(layer "In4.Cu")
		(net "M_F_CPU0_SB_DQ<25>")
	)
	(arc
		(start 383.919984 -225.203258)
		(mid 383.872305 -225.386158)
		(end 383.741422 -225.522536)
		(width 0.088646)
		(layer "In4.Cu")
		(net "M_F_CPU0_SB_DQ<25>")
	)
	(arc
		(start 380.277878 -228.450648)
		(mid 380.228917 -228.359151)
		(end 380.16307 -228.278944)
		(width 0.088646)
		(layer "In4.Cu")
		(net "M_F_CPU0_SB_DQ<25>")
	)
	(arc
		(start 381.47752 -228.78288)
		(mid 381.199362 -228.707656)
		(end 380.920244 -228.779324)
		(width 0.088646)
		(layer "In4.Cu")
		(net "M_F_CPU0_SB_DQ<25>")
	)
	(arc
		(start 383.450084 -226.017328)
		(mid 383.402405 -226.200228)
		(end 383.271522 -226.336606)
		(width 0.088646)
		(layer "In4.Cu")
		(net "M_F_CPU0_SB_DQ<25>")
	)
	(arc
		(start 384.202432 -224.7138)
		(mid 383.998097 -224.916405)
		(end 383.919984 -225.193352)
		(width 0.088646)
		(layer "In4.Cu")
		(net "M_F_CPU0_SB_DQ<25>")
	)
	(arc
		(start 382.792478 -227.155502)
		(mid 382.589655 -227.355733)
		(end 382.510284 -227.629466)
		(width 0.088646)
		(layer "In4.Cu")
		(net "M_F_CPU0_SB_DQ<25>")
	)
	(arc
		(start 386.83438 -222.196406)
		(mid 386.688172 -222.215655)
		(end 386.551932 -222.272098)
		(width 0.088646)
		(layer "In4.Cu")
		(net "M_F_CPU0_SB_DQ<25>")
	)
	(arc
		(start 378.681488 -228.122226)
		(mid 378.641323 -228.141374)
		(end 378.600716 -228.159564)
		(width 0.088646)
		(layer "In4.Cu")
		(net "M_F_CPU0_SB_DQ<25>")
	)
	(arc
		(start 379.96749 -228.131116)
		(mid 379.782635 -228.084198)
		(end 379.598682 -228.134418)
		(width 0.088646)
		(layer "In4.Cu")
		(net "M_F_CPU0_SB_DQ<25>")
	)
	(arc
		(start 382.04013 -228.467666)
		(mid 381.98786 -228.650031)
		(end 381.852932 -228.783388)
		(width 0.088646)
		(layer "In4.Cu")
		(net "M_F_CPU0_SB_DQ<25>")
	)
	(arc
		(start 384.672078 -223.899984)
		(mid 384.469255 -224.100215)
		(end 384.389884 -224.373948)
		(width 0.088646)
		(layer "In4.Cu")
		(net "M_F_CPU0_SB_DQ<25>")
	)
	(arc
		(start 380.16307 -228.278944)
		(mid 380.075752 -228.202418)
		(end 379.979174 -228.137974)
		(width 0.088646)
		(layer "In4.Cu")
		(net "M_F_CPU0_SB_DQ<25>")
	)
	(arc
		(start 383.25044 -226.348798)
		(mid 383.052212 -226.554646)
		(end 382.97993 -226.831144)
		(width 0.088646)
		(layer "In4.Cu")
		(net "M_F_CPU0_SB_DQ<25>")
	)
	(arc
		(start 380.906782 -228.787198)
		(mid 380.722122 -228.833711)
		(end 380.538482 -228.783388)
		(width 0.088646)
		(layer "In4.Cu")
		(net "M_F_CPU0_SB_DQ<25>")
	)
	(arc
		(start 385.59994 -222.27921)
		(mid 385.401712 -222.485058)
		(end 385.32943 -222.761556)
		(width 0.088646)
		(layer "In4.Cu")
		(net "M_F_CPU0_SB_DQ<25>")
	)
	(arc
		(start 381.852932 -228.783388)
		(mid 381.665734 -228.833531)
		(end 381.478536 -228.783388)
		(width 0.088646)
		(layer "In4.Cu")
		(net "M_F_CPU0_SB_DQ<25>")
	)
	(arc
		(start 384.389884 -224.389442)
		(mid 384.342205 -224.572342)
		(end 384.211322 -224.70872)
		(width 0.088646)
		(layer "In4.Cu")
		(net "M_F_CPU0_SB_DQ<25>")
	)
	(arc
		(start 382.510284 -227.64496)
		(mid 382.462605 -227.82786)
		(end 382.331722 -227.964238)
		(width 0.088646)
		(layer "In4.Cu")
		(net "M_F_CPU0_SB_DQ<25>")
	)
	(arc
		(start 386.551932 -222.272098)
		(mid 386.364734 -222.322241)
		(end 386.177536 -222.272098)
		(width 0.088646)
		(layer "In4.Cu")
		(net "M_F_CPU0_SB_DQ<25>")
	)
	(arc
		(start 385.141978 -223.085914)
		(mid 384.938673 -223.28678)
		(end 384.85953 -223.561402)
		(width 0.088646)
		(layer "In4.Cu")
		(net "M_F_CPU0_SB_DQ<25>")
	)
	(arc
		(start 383.732532 -225.527616)
		(mid 383.530246 -225.726597)
		(end 383.450084 -225.998786)
		(width 0.088646)
		(layer "In4.Cu")
		(net "M_F_CPU0_SB_DQ<25>")
	)
	(arc
		(start 385.32943 -222.761556)
		(mid 385.281751 -222.944456)
		(end 385.150868 -223.080834)
		(width 0.088646)
		(layer "In4.Cu")
		(net "M_F_CPU0_SB_DQ<25>")
	)
	(arc
		(start 382.322832 -227.969318)
		(mid 382.119351 -228.170122)
		(end 382.04013 -228.444806)
		(width 0.088646)
		(layer "In4.Cu")
		(net "M_F_CPU0_SB_DQ<25>")
	)
	(arc
		(start 382.97993 -226.831144)
		(mid 382.932251 -227.014044)
		(end 382.801368 -227.150422)
		(width 0.088646)
		(layer "In4.Cu")
		(net "M_F_CPU0_SB_DQ<25>")
	)
	(segment
		(start 424.273472 -204.177392)
		(end 424.085512 -204.365352)
		(width 0.20066)
		(layer "F.Cu")
		(net "M_F_CPU0_SB_DQ<24>")
	)
	(segment
		(start 424.78325 -203.691744)
		(end 424.73626 -203.691744)
		(width 0.101854)
		(layer "F.Cu")
		(net "M_F_CPU0_SB_DQ<24>")
	)
	(segment
		(start 424.273472 -203.809854)
		(end 424.273472 -204.177392)
		(width 0.20066)
		(layer "F.Cu")
		(net "M_F_CPU0_SB_DQ<24>")
	)
	(segment
		(start 429.384714 -204.116686)
		(end 429.38446 -204.11694)
		(width 0.20066)
		(layer "F.Cu")
		(net "M_F_CPU0_SB_DQ<24>")
	)
	(segment
		(start 423.361612 -204.116686)
		(end 421.840914 -204.116686)
		(width 0.20066)
		(layer "F.Cu")
		(net "M_F_CPU0_SB_DQ<24>")
	)
	(segment
		(start 424.085512 -204.365352)
		(end 423.610278 -204.365352)
		(width 0.20066)
		(layer "F.Cu")
		(net "M_F_CPU0_SB_DQ<24>")
	)
	(segment
		(start 421.840914 -204.116686)
		(end 420.736014 -204.116686)
		(width 0.20066)
		(layer "F.Cu")
		(net "M_F_CPU0_SB_DQ<24>")
	)
	(segment
		(start 427.792896 -204.11694)
		(end 427.36135 -203.685394)
		(width 0.20066)
		(layer "F.Cu")
		(net "M_F_CPU0_SB_DQ<24>")
	)
	(segment
		(start 378.37618 -229.808786)
		(end 378.376434 -229.808532)
		(width 0.20066)
		(layer "F.Cu")
		(net "M_F_CPU0_SB_DQ<24>")
	)
	(segment
		(start 423.610278 -204.365352)
		(end 423.361612 -204.116686)
		(width 0.20066)
		(layer "F.Cu")
		(net "M_F_CPU0_SB_DQ<24>")
	)
	(segment
		(start 427.36135 -203.685394)
		(end 426.951394 -203.685394)
		(width 0.20066)
		(layer "F.Cu")
		(net "M_F_CPU0_SB_DQ<24>")
	)
	(segment
		(start 378.376434 -229.808532)
		(end 378.376434 -229.272846)
		(width 0.20066)
		(layer "F.Cu")
		(net "M_F_CPU0_SB_DQ<24>")
	)
	(segment
		(start 426.951394 -203.685394)
		(end 426.945044 -203.691744)
		(width 0.1016)
		(layer "F.Cu")
		(net "M_F_CPU0_SB_DQ<24>")
	)
	(segment
		(start 424.391582 -203.691744)
		(end 424.273472 -203.809854)
		(width 0.20066)
		(layer "F.Cu")
		(net "M_F_CPU0_SB_DQ<24>")
	)
	(segment
		(start 424.73626 -203.691744)
		(end 424.391582 -203.691744)
		(width 0.20066)
		(layer "F.Cu")
		(net "M_F_CPU0_SB_DQ<24>")
	)
	(segment
		(start 426.945044 -203.691744)
		(end 424.78325 -203.691744)
		(width 0.1016)
		(layer "F.Cu")
		(net "M_F_CPU0_SB_DQ<24>")
	)
	(segment
		(start 429.38446 -204.11694)
		(end 427.792896 -204.11694)
		(width 0.20066)
		(layer "F.Cu")
		(net "M_F_CPU0_SB_DQ<24>")
	)
	(segment
		(start 381.008382 -229.597204)
		(end 381.00254 -229.593648)
		(width 0.088646)
		(layer "In4.Cu")
		(net "M_F_CPU0_SB_DQ<24>")
	)
	(segment
		(start 382.331722 -229.592124)
		(end 382.322832 -229.597204)
		(width 0.088646)
		(layer "In4.Cu")
		(net "M_F_CPU0_SB_DQ<24>")
	)
	(segment
		(start 382.97993 -228.45141)
		(end 382.97993 -228.45903)
		(width 0.088646)
		(layer "In4.Cu")
		(net "M_F_CPU0_SB_DQ<24>")
	)
	(segment
		(start 378.917454 -228.857048)
		(end 378.376434 -229.272846)
		(width 0.088646)
		(layer "In4.Cu")
		(net "M_F_CPU0_SB_DQ<24>")
	)
	(segment
		(start 416.278314 -204.704696)
		(end 416.118294 -204.544676)
		(width 0.18288)
		(layer "In4.Cu")
		(net "M_F_CPU0_SB_DQ<24>")
	)
	(segment
		(start 382.510284 -229.257352)
		(end 382.510284 -229.272846)
		(width 0.088646)
		(layer "In4.Cu")
		(net "M_F_CPU0_SB_DQ<24>")
	)
	(segment
		(start 406.58796 -203.979526)
		(end 406.42794 -203.819506)
		(width 0.18288)
		(layer "In4.Cu")
		(net "M_F_CPU0_SB_DQ<24>")
	)
	(segment
		(start 379.88113 -229.272846)
		(end 379.88113 -229.268528)
		(width 0.088646)
		(layer "In4.Cu")
		(net "M_F_CPU0_SB_DQ<24>")
	)
	(segment
		(start 412.638494 -204.365606)
		(end 412.638494 -203.688696)
		(width 0.18288)
		(layer "In4.Cu")
		(net "M_F_CPU0_SB_DQ<24>")
	)
	(segment
		(start 385.329684 -224.379536)
		(end 385.329684 -224.389442)
		(width 0.088646)
		(layer "In4.Cu")
		(net "M_F_CPU0_SB_DQ<24>")
	)
	(segment
		(start 408.787092 -203.949046)
		(end 408.787092 -204.338936)
		(width 0.18288)
		(layer "In4.Cu")
		(net "M_F_CPU0_SB_DQ<24>")
	)
	(segment
		(start 412.638494 -203.688696)
		(end 412.478474 -203.528676)
		(width 0.18288)
		(layer "In4.Cu")
		(net "M_F_CPU0_SB_DQ<24>")
	)
	(segment
		(start 420.736014 -204.116686)
		(end 420.710614 -204.116686)
		(width 0.18288)
		(layer "In4.Cu")
		(net "M_F_CPU0_SB_DQ<24>")
	)
	(segment
		(start 385.799584 -223.557084)
		(end 385.799584 -223.575626)
		(width 0.088646)
		(layer "In4.Cu")
		(net "M_F_CPU0_SB_DQ<24>")
	)
	(segment
		(start 384.859784 -225.193352)
		(end 384.859784 -225.203258)
		(width 0.088646)
		(layer "In4.Cu")
		(net "M_F_CPU0_SB_DQ<24>")
	)
	(segment
		(start 406.053798 -203.819506)
		(end 405.794718 -204.078586)
		(width 0.18288)
		(layer "In4.Cu")
		(net "M_F_CPU0_SB_DQ<24>")
	)
	(segment
		(start 389.231886 -223.140778)
		(end 387.69671 -223.140778)
		(width 0.18288)
		(layer "In4.Cu")
		(net "M_F_CPU0_SB_DQ<24>")
	)
	(segment
		(start 417.510468 -204.703426)
		(end 417.509198 -204.704696)
		(width 0.18288)
		(layer "In4.Cu")
		(net "M_F_CPU0_SB_DQ<24>")
	)
	(segment
		(start 412.798514 -204.525626)
		(end 412.638494 -204.365606)
		(width 0.18288)
		(layer "In4.Cu")
		(net "M_F_CPU0_SB_DQ<24>")
	)
	(segment
		(start 407.312114 -204.92212)
		(end 407.129234 -205.105)
		(width 0.18288)
		(layer "In4.Cu")
		(net "M_F_CPU0_SB_DQ<24>")
	)
	(segment
		(start 414.899094 -203.382626)
		(end 413.786574 -203.382626)
		(width 0.18288)
		(layer "In4.Cu")
		(net "M_F_CPU0_SB_DQ<24>")
	)
	(segment
		(start 408.253692 -204.498956)
		(end 408.093672 -204.338936)
		(width 0.18288)
		(layer "In4.Cu")
		(net "M_F_CPU0_SB_DQ<24>")
	)
	(segment
		(start 413.265874 -204.525626)
		(end 412.798514 -204.525626)
		(width 0.18288)
		(layer "In4.Cu")
		(net "M_F_CPU0_SB_DQ<24>")
	)
	(segment
		(start 420.149274 -204.678026)
		(end 419.318694 -204.678026)
		(width 0.18288)
		(layer "In4.Cu")
		(net "M_F_CPU0_SB_DQ<24>")
	)
	(segment
		(start 407.933652 -203.789026)
		(end 407.472134 -203.789026)
		(width 0.18288)
		(layer "In4.Cu")
		(net "M_F_CPU0_SB_DQ<24>")
	)
	(segment
		(start 419.140894 -204.500226)
		(end 417.743894 -204.500226)
		(width 0.18288)
		(layer "In4.Cu")
		(net "M_F_CPU0_SB_DQ<24>")
	)
	(segment
		(start 379.040898 -228.77907)
		(end 378.991368 -228.807518)
		(width 0.088646)
		(layer "In4.Cu")
		(net "M_F_CPU0_SB_DQ<24>")
	)
	(segment
		(start 407.312114 -203.949046)
		(end 407.312114 -204.92212)
		(width 0.18288)
		(layer "In4.Cu")
		(net "M_F_CPU0_SB_DQ<24>")
	)
	(segment
		(start 402.129752 -208.184496)
		(end 400.674332 -211.698078)
		(width 0.18288)
		(layer "In4.Cu")
		(net "M_F_CPU0_SB_DQ<24>")
	)
	(segment
		(start 415.915094 -203.738226)
		(end 415.254694 -203.738226)
		(width 0.18288)
		(layer "In4.Cu")
		(net "M_F_CPU0_SB_DQ<24>")
	)
	(segment
		(start 405.794718 -204.078586)
		(end 405.794718 -205.311756)
		(width 0.18288)
		(layer "In4.Cu")
		(net "M_F_CPU0_SB_DQ<24>")
	)
	(segment
		(start 381.014224 -229.600506)
		(end 381.008382 -229.597204)
		(width 0.088646)
		(layer "In4.Cu")
		(net "M_F_CPU0_SB_DQ<24>")
	)
	(segment
		(start 387.69671 -223.140778)
		(end 386.85216 -223.140778)
		(width 0.088646)
		(layer "In4.Cu")
		(net "M_F_CPU0_SB_DQ<24>")
	)
	(segment
		(start 385.621022 -223.894904)
		(end 385.612132 -223.899984)
		(width 0.088646)
		(layer "In4.Cu")
		(net "M_F_CPU0_SB_DQ<24>")
	)
	(segment
		(start 382.801368 -228.778308)
		(end 382.792478 -228.783388)
		(width 0.088646)
		(layer "In4.Cu")
		(net "M_F_CPU0_SB_DQ<24>")
	)
	(segment
		(start 383.919984 -226.821238)
		(end 383.919984 -226.831144)
		(width 0.088646)
		(layer "In4.Cu")
		(net "M_F_CPU0_SB_DQ<24>")
	)
	(segment
		(start 406.77084 -205.105)
		(end 406.58796 -204.92212)
		(width 0.18288)
		(layer "In4.Cu")
		(net "M_F_CPU0_SB_DQ<24>")
	)
	(segment
		(start 411.073346 -203.528676)
		(end 410.913326 -203.688696)
		(width 0.18288)
		(layer "In4.Cu")
		(net "M_F_CPU0_SB_DQ<24>")
	)
	(segment
		(start 408.787092 -204.338936)
		(end 408.627072 -204.498956)
		(width 0.18288)
		(layer "In4.Cu")
		(net "M_F_CPU0_SB_DQ<24>")
	)
	(segment
		(start 404.674324 -205.639924)
		(end 402.129752 -208.184496)
		(width 0.18288)
		(layer "In4.Cu")
		(net "M_F_CPU0_SB_DQ<24>")
	)
	(segment
		(start 410.219906 -203.688696)
		(end 410.059886 -203.528676)
		(width 0.18288)
		(layer "In4.Cu")
		(net "M_F_CPU0_SB_DQ<24>")
	)
	(segment
		(start 383.450084 -227.635054)
		(end 383.450084 -227.64496)
		(width 0.088646)
		(layer "In4.Cu")
		(net "M_F_CPU0_SB_DQ<24>")
	)
	(segment
		(start 400.674078 -211.698586)
		(end 389.231886 -223.140778)
		(width 0.18288)
		(layer "In4.Cu")
		(net "M_F_CPU0_SB_DQ<24>")
	)
	(segment
		(start 385.151122 -224.70872)
		(end 385.142232 -224.7138)
		(width 0.088646)
		(layer "In4.Cu")
		(net "M_F_CPU0_SB_DQ<24>")
	)
	(segment
		(start 384.38963 -226.003104)
		(end 384.38963 -226.025964)
		(width 0.088646)
		(layer "In4.Cu")
		(net "M_F_CPU0_SB_DQ<24>")
	)
	(segment
		(start 416.118294 -204.544676)
		(end 416.118294 -203.941426)
		(width 0.18288)
		(layer "In4.Cu")
		(net "M_F_CPU0_SB_DQ<24>")
	)
	(segment
		(start 410.379926 -204.352652)
		(end 410.219906 -204.192632)
		(width 0.18288)
		(layer "In4.Cu")
		(net "M_F_CPU0_SB_DQ<24>")
	)
	(segment
		(start 408.093672 -204.338936)
		(end 408.093672 -203.949046)
		(width 0.18288)
		(layer "In4.Cu")
		(net "M_F_CPU0_SB_DQ<24>")
	)
	(segment
		(start 417.743894 -204.500226)
		(end 417.540694 -204.703426)
		(width 0.18288)
		(layer "In4.Cu")
		(net "M_F_CPU0_SB_DQ<24>")
	)
	(segment
		(start 410.913326 -203.688696)
		(end 410.913326 -204.192632)
		(width 0.18288)
		(layer "In4.Cu")
		(net "M_F_CPU0_SB_DQ<24>")
	)
	(segment
		(start 408.627072 -204.498956)
		(end 408.253692 -204.498956)
		(width 0.18288)
		(layer "In4.Cu")
		(net "M_F_CPU0_SB_DQ<24>")
	)
	(segment
		(start 410.913326 -204.192632)
		(end 410.753306 -204.352652)
		(width 0.18288)
		(layer "In4.Cu")
		(net "M_F_CPU0_SB_DQ<24>")
	)
	(segment
		(start 410.753306 -204.352652)
		(end 410.379926 -204.352652)
		(width 0.18288)
		(layer "In4.Cu")
		(net "M_F_CPU0_SB_DQ<24>")
	)
	(segment
		(start 400.674332 -211.698078)
		(end 400.674078 -211.698586)
		(width 0.18288)
		(layer "In4.Cu")
		(net "M_F_CPU0_SB_DQ<24>")
	)
	(segment
		(start 384.681222 -225.522536)
		(end 384.672332 -225.527616)
		(width 0.088646)
		(layer "In4.Cu")
		(net "M_F_CPU0_SB_DQ<24>")
	)
	(segment
		(start 406.42794 -203.819506)
		(end 406.053798 -203.819506)
		(width 0.18288)
		(layer "In4.Cu")
		(net "M_F_CPU0_SB_DQ<24>")
	)
	(segment
		(start 419.318694 -204.678026)
		(end 419.140894 -204.500226)
		(width 0.18288)
		(layer "In4.Cu")
		(net "M_F_CPU0_SB_DQ<24>")
	)
	(segment
		(start 383.741422 -227.150422)
		(end 383.732532 -227.155502)
		(width 0.088646)
		(layer "In4.Cu")
		(net "M_F_CPU0_SB_DQ<24>")
	)
	(segment
		(start 381.948182 -229.597204)
		(end 381.944626 -229.595172)
		(width 0.088646)
		(layer "In4.Cu")
		(net "M_F_CPU0_SB_DQ<24>")
	)
	(segment
		(start 405.46655 -205.639924)
		(end 404.674324 -205.639924)
		(width 0.18288)
		(layer "In4.Cu")
		(net "M_F_CPU0_SB_DQ<24>")
	)
	(segment
		(start 413.786574 -203.382626)
		(end 413.425894 -203.743306)
		(width 0.18288)
		(layer "In4.Cu")
		(net "M_F_CPU0_SB_DQ<24>")
	)
	(segment
		(start 407.472134 -203.789026)
		(end 407.312114 -203.949046)
		(width 0.18288)
		(layer "In4.Cu")
		(net "M_F_CPU0_SB_DQ<24>")
	)
	(segment
		(start 408.093672 -203.949046)
		(end 407.933652 -203.789026)
		(width 0.18288)
		(layer "In4.Cu")
		(net "M_F_CPU0_SB_DQ<24>")
	)
	(segment
		(start 410.059886 -203.528676)
		(end 409.207462 -203.528676)
		(width 0.18288)
		(layer "In4.Cu")
		(net "M_F_CPU0_SB_DQ<24>")
	)
	(segment
		(start 406.58796 -204.92212)
		(end 406.58796 -203.979526)
		(width 0.18288)
		(layer "In4.Cu")
		(net "M_F_CPU0_SB_DQ<24>")
	)
	(segment
		(start 415.254694 -203.738226)
		(end 414.899094 -203.382626)
		(width 0.18288)
		(layer "In4.Cu")
		(net "M_F_CPU0_SB_DQ<24>")
	)
	(segment
		(start 417.540694 -204.703426)
		(end 417.510468 -204.703426)
		(width 0.18288)
		(layer "In4.Cu")
		(net "M_F_CPU0_SB_DQ<24>")
	)
	(segment
		(start 420.710614 -204.116686)
		(end 420.149274 -204.678026)
		(width 0.18288)
		(layer "In4.Cu")
		(net "M_F_CPU0_SB_DQ<24>")
	)
	(segment
		(start 409.207462 -203.528676)
		(end 408.787092 -203.949046)
		(width 0.18288)
		(layer "In4.Cu")
		(net "M_F_CPU0_SB_DQ<24>")
	)
	(segment
		(start 413.425894 -203.743306)
		(end 413.425894 -204.365606)
		(width 0.18288)
		(layer "In4.Cu")
		(net "M_F_CPU0_SB_DQ<24>")
	)
	(segment
		(start 410.219906 -204.192632)
		(end 410.219906 -203.688696)
		(width 0.18288)
		(layer "In4.Cu")
		(net "M_F_CPU0_SB_DQ<24>")
	)
	(segment
		(start 407.129234 -205.105)
		(end 406.77084 -205.105)
		(width 0.18288)
		(layer "In4.Cu")
		(net "M_F_CPU0_SB_DQ<24>")
	)
	(segment
		(start 412.478474 -203.528676)
		(end 411.073346 -203.528676)
		(width 0.18288)
		(layer "In4.Cu")
		(net "M_F_CPU0_SB_DQ<24>")
	)
	(segment
		(start 386.647182 -223.085914)
		(end 386.636768 -223.079818)
		(width 0.088646)
		(layer "In4.Cu")
		(net "M_F_CPU0_SB_DQ<24>")
	)
	(segment
		(start 417.509198 -204.704696)
		(end 416.278314 -204.704696)
		(width 0.18288)
		(layer "In4.Cu")
		(net "M_F_CPU0_SB_DQ<24>")
	)
	(segment
		(start 405.794718 -205.311756)
		(end 405.46655 -205.639924)
		(width 0.18288)
		(layer "In4.Cu")
		(net "M_F_CPU0_SB_DQ<24>")
	)
	(segment
		(start 383.271522 -227.964238)
		(end 383.262632 -227.969318)
		(width 0.088646)
		(layer "In4.Cu")
		(net "M_F_CPU0_SB_DQ<24>")
	)
	(segment
		(start 413.425894 -204.365606)
		(end 413.265874 -204.525626)
		(width 0.18288)
		(layer "In4.Cu")
		(net "M_F_CPU0_SB_DQ<24>")
	)
	(segment
		(start 416.118294 -203.941426)
		(end 415.915094 -203.738226)
		(width 0.18288)
		(layer "In4.Cu")
		(net "M_F_CPU0_SB_DQ<24>")
	)
	(arc
		(start 386.636768 -223.079818)
		(mid 386.35859 -223.010126)
		(end 386.082032 -223.085914)
		(width 0.088646)
		(layer "In4.Cu")
		(net "M_F_CPU0_SB_DQ<24>")
	)
	(arc
		(start 385.612132 -223.899984)
		(mid 385.407797 -224.102589)
		(end 385.329684 -224.379536)
		(width 0.088646)
		(layer "In4.Cu")
		(net "M_F_CPU0_SB_DQ<24>")
	)
	(arc
		(start 382.510284 -229.272846)
		(mid 382.462605 -229.455746)
		(end 382.331722 -229.592124)
		(width 0.088646)
		(layer "In4.Cu")
		(net "M_F_CPU0_SB_DQ<24>")
	)
	(arc
		(start 382.97993 -228.45903)
		(mid 382.932251 -228.64193)
		(end 382.801368 -228.778308)
		(width 0.088646)
		(layer "In4.Cu")
		(net "M_F_CPU0_SB_DQ<24>")
	)
	(arc
		(start 384.859784 -225.203258)
		(mid 384.812105 -225.386158)
		(end 384.681222 -225.522536)
		(width 0.088646)
		(layer "In4.Cu")
		(net "M_F_CPU0_SB_DQ<24>")
	)
	(arc
		(start 385.142232 -224.7138)
		(mid 384.937897 -224.916405)
		(end 384.859784 -225.193352)
		(width 0.088646)
		(layer "In4.Cu")
		(net "M_F_CPU0_SB_DQ<24>")
	)
	(arc
		(start 380.443232 -229.597204)
		(mid 380.068535 -229.597323)
		(end 379.88113 -229.272846)
		(width 0.088646)
		(layer "In4.Cu")
		(net "M_F_CPU0_SB_DQ<24>")
	)
	(arc
		(start 386.082032 -223.085914)
		(mid 385.879746 -223.284895)
		(end 385.799584 -223.557084)
		(width 0.088646)
		(layer "In4.Cu")
		(net "M_F_CPU0_SB_DQ<24>")
	)
	(arc
		(start 384.672332 -225.527616)
		(mid 384.468851 -225.72842)
		(end 384.38963 -226.003104)
		(width 0.088646)
		(layer "In4.Cu")
		(net "M_F_CPU0_SB_DQ<24>")
	)
	(arc
		(start 383.919984 -226.831144)
		(mid 383.872305 -227.014044)
		(end 383.741422 -227.150422)
		(width 0.088646)
		(layer "In4.Cu")
		(net "M_F_CPU0_SB_DQ<24>")
	)
	(arc
		(start 378.991368 -228.807518)
		(mid 378.953586 -228.831053)
		(end 378.917454 -228.857048)
		(width 0.088646)
		(layer "In4.Cu")
		(net "M_F_CPU0_SB_DQ<24>")
	)
	(arc
		(start 383.450084 -227.64496)
		(mid 383.402405 -227.82786)
		(end 383.271522 -227.964238)
		(width 0.088646)
		(layer "In4.Cu")
		(net "M_F_CPU0_SB_DQ<24>")
	)
	(arc
		(start 381.944626 -229.595172)
		(mid 381.663542 -229.521435)
		(end 381.383032 -229.597204)
		(width 0.088646)
		(layer "In4.Cu")
		(net "M_F_CPU0_SB_DQ<24>")
	)
	(arc
		(start 382.792478 -228.783388)
		(mid 382.589655 -228.983619)
		(end 382.510284 -229.257352)
		(width 0.088646)
		(layer "In4.Cu")
		(net "M_F_CPU0_SB_DQ<24>")
	)
	(arc
		(start 386.85216 -223.140778)
		(mid 386.746061 -223.126828)
		(end 386.647182 -223.085914)
		(width 0.088646)
		(layer "In4.Cu")
		(net "M_F_CPU0_SB_DQ<24>")
	)
	(arc
		(start 383.262632 -227.969318)
		(mid 383.05756 -228.172997)
		(end 382.97993 -228.45141)
		(width 0.088646)
		(layer "In4.Cu")
		(net "M_F_CPU0_SB_DQ<24>")
	)
	(arc
		(start 385.329684 -224.389442)
		(mid 385.282005 -224.572342)
		(end 385.151122 -224.70872)
		(width 0.088646)
		(layer "In4.Cu")
		(net "M_F_CPU0_SB_DQ<24>")
	)
	(arc
		(start 382.322832 -229.597204)
		(mid 382.135524 -229.647347)
		(end 381.948182 -229.597204)
		(width 0.088646)
		(layer "In4.Cu")
		(net "M_F_CPU0_SB_DQ<24>")
	)
	(arc
		(start 385.799584 -223.575626)
		(mid 385.751905 -223.758526)
		(end 385.621022 -223.894904)
		(width 0.088646)
		(layer "In4.Cu")
		(net "M_F_CPU0_SB_DQ<24>")
	)
	(arc
		(start 384.202432 -226.341686)
		(mid 383.998097 -226.544291)
		(end 383.919984 -226.821238)
		(width 0.088646)
		(layer "In4.Cu")
		(net "M_F_CPU0_SB_DQ<24>")
	)
	(arc
		(start 379.88113 -229.268528)
		(mid 379.600496 -228.784267)
		(end 379.040898 -228.77907)
		(width 0.088646)
		(layer "In4.Cu")
		(net "M_F_CPU0_SB_DQ<24>")
	)
	(arc
		(start 383.732532 -227.155502)
		(mid 383.528197 -227.358107)
		(end 383.450084 -227.635054)
		(width 0.088646)
		(layer "In4.Cu")
		(net "M_F_CPU0_SB_DQ<24>")
	)
	(arc
		(start 381.00254 -229.593648)
		(mid 380.722405 -229.521365)
		(end 380.443232 -229.597204)
		(width 0.088646)
		(layer "In4.Cu")
		(net "M_F_CPU0_SB_DQ<24>")
	)
	(arc
		(start 381.383032 -229.597204)
		(mid 381.199078 -229.647333)
		(end 381.014224 -229.600506)
		(width 0.088646)
		(layer "In4.Cu")
		(net "M_F_CPU0_SB_DQ<24>")
	)
	(arc
		(start 384.38963 -226.025964)
		(mid 384.33736 -226.208329)
		(end 384.202432 -226.341686)
		(width 0.088646)
		(layer "In4.Cu")
		(net "M_F_CPU0_SB_DQ<24>")
	)
	(segment
		(start 431.280316 -204.94879)
		(end 431.514504 -204.714602)
		(width 0.20066)
		(layer "F.Cu")
		(net "M_F_CPU0_SB_DQ<23>")
	)
	(segment
		(start 425.940982 -204.96657)
		(end 427.639226 -204.96657)
		(width 0.20066)
		(layer "F.Cu")
		(net "M_F_CPU0_SB_DQ<23>")
	)
	(segment
		(start 431.898552 -204.714602)
		(end 432.15052 -204.96657)
		(width 0.20066)
		(layer "F.Cu")
		(net "M_F_CPU0_SB_DQ<23>")
	)
	(segment
		(start 385.894834 -221.133924)
		(end 385.894834 -221.669864)
		(width 0.20066)
		(layer "F.Cu")
		(net "M_F_CPU0_SB_DQ<23>")
	)
	(segment
		(start 430.382934 -205.391512)
		(end 430.395126 -205.403704)
		(width 0.1016)
		(layer "F.Cu")
		(net "M_F_CPU0_SB_DQ<23>")
	)
	(segment
		(start 427.639226 -204.96657)
		(end 428.07128 -205.398624)
		(width 0.20066)
		(layer "F.Cu")
		(net "M_F_CPU0_SB_DQ<23>")
	)
	(segment
		(start 431.076354 -205.403704)
		(end 431.280316 -205.199742)
		(width 0.20066)
		(layer "F.Cu")
		(net "M_F_CPU0_SB_DQ<23>")
	)
	(segment
		(start 428.363126 -205.398624)
		(end 428.367952 -205.398624)
		(width 0.101854)
		(layer "F.Cu")
		(net "M_F_CPU0_SB_DQ<23>")
	)
	(segment
		(start 431.514504 -204.714602)
		(end 431.898552 -204.714602)
		(width 0.20066)
		(layer "F.Cu")
		(net "M_F_CPU0_SB_DQ<23>")
	)
	(segment
		(start 430.395126 -205.403704)
		(end 431.076354 -205.403704)
		(width 0.20066)
		(layer "F.Cu")
		(net "M_F_CPU0_SB_DQ<23>")
	)
	(segment
		(start 428.375064 -205.391512)
		(end 430.382934 -205.391512)
		(width 0.1016)
		(layer "F.Cu")
		(net "M_F_CPU0_SB_DQ<23>")
	)
	(segment
		(start 428.07128 -205.398624)
		(end 428.363126 -205.398624)
		(width 0.20066)
		(layer "F.Cu")
		(net "M_F_CPU0_SB_DQ<23>")
	)
	(segment
		(start 428.367952 -205.398624)
		(end 428.375064 -205.391512)
		(width 0.1016)
		(layer "F.Cu")
		(net "M_F_CPU0_SB_DQ<23>")
	)
	(segment
		(start 431.280316 -205.199742)
		(end 431.280316 -204.94879)
		(width 0.20066)
		(layer "F.Cu")
		(net "M_F_CPU0_SB_DQ<23>")
	)
	(segment
		(start 432.15052 -204.96657)
		(end 433.484782 -204.96657)
		(width 0.20066)
		(layer "F.Cu")
		(net "M_F_CPU0_SB_DQ<23>")
	)
	(segment
		(start 424.836082 -204.96657)
		(end 425.940982 -204.96657)
		(width 0.20066)
		(layer "F.Cu")
		(net "M_F_CPU0_SB_DQ<23>")
	)
	(segment
		(start 412.47695 -202.700128)
		(end 412.32709 -202.849988)
		(width 0.18288)
		(layer "In2.Cu")
		(net "M_F_CPU0_SB_DQ<23>")
	)
	(segment
		(start 388.716266 -219.26042)
		(end 388.251446 -219.26042)
		(width 0.088646)
		(layer "In2.Cu")
		(net "M_F_CPU0_SB_DQ<23>")
	)
	(segment
		(start 385.707636 -220.809566)
		(end 385.698746 -220.814646)
		(width 0.088646)
		(layer "In2.Cu")
		(net "M_F_CPU0_SB_DQ<23>")
	)
	(segment
		(start 409.413202 -202.849988)
		(end 409.32989 -202.766676)
		(width 0.18288)
		(layer "In2.Cu")
		(net "M_F_CPU0_SB_DQ<23>")
	)
	(segment
		(start 407.94813 -202.828652)
		(end 404.973536 -202.828652)
		(width 0.18288)
		(layer "In2.Cu")
		(net "M_F_CPU0_SB_DQ<23>")
	)
	(segment
		(start 408.010106 -202.766676)
		(end 407.94813 -202.828652)
		(width 0.18288)
		(layer "In2.Cu")
		(net "M_F_CPU0_SB_DQ<23>")
	)
	(segment
		(start 404.973536 -202.828652)
		(end 403.379686 -204.422502)
		(width 0.18288)
		(layer "In2.Cu")
		(net "M_F_CPU0_SB_DQ<23>")
	)
	(segment
		(start 387.586982 -219.18168)
		(end 387.57225 -219.190316)
		(width 0.088646)
		(layer "In2.Cu")
		(net "M_F_CPU0_SB_DQ<23>")
	)
	(segment
		(start 412.32709 -202.849988)
		(end 409.413202 -202.849988)
		(width 0.18288)
		(layer "In2.Cu")
		(net "M_F_CPU0_SB_DQ<23>")
	)
	(segment
		(start 420.091108 -205.876144)
		(end 419.20922 -204.557376)
		(width 0.18288)
		(layer "In2.Cu")
		(net "M_F_CPU0_SB_DQ<23>")
	)
	(segment
		(start 403.379686 -204.597)
		(end 389.245602 -218.731084)
		(width 0.18288)
		(layer "In2.Cu")
		(net "M_F_CPU0_SB_DQ<23>")
	)
	(segment
		(start 416.292538 -203.699872)
		(end 415.28365 -203.699872)
		(width 0.18288)
		(layer "In2.Cu")
		(net "M_F_CPU0_SB_DQ<23>")
	)
	(segment
		(start 423.686732 -205.549754)
		(end 423.63263 -205.715616)
		(width 0.18288)
		(layer "In2.Cu")
		(net "M_F_CPU0_SB_DQ<23>")
	)
	(segment
		(start 385.990084 -220.319854)
		(end 385.990084 -220.338396)
		(width 0.088646)
		(layer "In2.Cu")
		(net "M_F_CPU0_SB_DQ<23>")
	)
	(segment
		(start 403.379686 -204.422502)
		(end 403.379686 -204.597)
		(width 0.18288)
		(layer "In2.Cu")
		(net "M_F_CPU0_SB_DQ<23>")
	)
	(segment
		(start 423.63263 -205.715616)
		(end 422.59377 -206.242412)
		(width 0.18288)
		(layer "In2.Cu")
		(net "M_F_CPU0_SB_DQ<23>")
	)
	(segment
		(start 416.337496 -203.654914)
		(end 416.292538 -203.699872)
		(width 0.18288)
		(layer "In2.Cu")
		(net "M_F_CPU0_SB_DQ<23>")
	)
	(segment
		(start 386.177536 -219.995496)
		(end 386.168646 -220.000576)
		(width 0.088646)
		(layer "In2.Cu")
		(net "M_F_CPU0_SB_DQ<23>")
	)
	(segment
		(start 386.647182 -219.18168)
		(end 386.638292 -219.18676)
		(width 0.088646)
		(layer "In2.Cu")
		(net "M_F_CPU0_SB_DQ<23>")
	)
	(segment
		(start 389.245602 -218.731084)
		(end 388.716266 -219.26042)
		(width 0.088646)
		(layer "In2.Cu")
		(net "M_F_CPU0_SB_DQ<23>")
	)
	(segment
		(start 386.45973 -219.506038)
		(end 386.45973 -219.521532)
		(width 0.088646)
		(layer "In2.Cu")
		(net "M_F_CPU0_SB_DQ<23>")
	)
	(segment
		(start 420.457376 -206.242412)
		(end 420.091108 -205.876144)
		(width 0.18288)
		(layer "In2.Cu")
		(net "M_F_CPU0_SB_DQ<23>")
	)
	(segment
		(start 385.581906 -221.133924)
		(end 385.894834 -221.133924)
		(width 0.088646)
		(layer "In2.Cu")
		(net "M_F_CPU0_SB_DQ<23>")
	)
	(segment
		(start 424.836082 -204.96657)
		(end 423.686732 -205.549754)
		(width 0.18288)
		(layer "In2.Cu")
		(net "M_F_CPU0_SB_DQ<23>")
	)
	(segment
		(start 385.524756 -221.076774)
		(end 385.581906 -221.133924)
		(width 0.088646)
		(layer "In2.Cu")
		(net "M_F_CPU0_SB_DQ<23>")
	)
	(segment
		(start 418.306758 -203.654914)
		(end 416.337496 -203.654914)
		(width 0.18288)
		(layer "In2.Cu")
		(net "M_F_CPU0_SB_DQ<23>")
	)
	(segment
		(start 409.32989 -202.766676)
		(end 408.010106 -202.766676)
		(width 0.18288)
		(layer "In2.Cu")
		(net "M_F_CPU0_SB_DQ<23>")
	)
	(segment
		(start 422.59377 -206.242412)
		(end 420.457376 -206.242412)
		(width 0.18288)
		(layer "In2.Cu")
		(net "M_F_CPU0_SB_DQ<23>")
	)
	(segment
		(start 415.28365 -203.699872)
		(end 414.495996 -203.373736)
		(width 0.18288)
		(layer "In2.Cu")
		(net "M_F_CPU0_SB_DQ<23>")
	)
	(segment
		(start 388.251446 -219.26042)
		(end 388.251446 -219.257626)
		(width 0.088646)
		(layer "In2.Cu")
		(net "M_F_CPU0_SB_DQ<23>")
	)
	(segment
		(start 419.20922 -204.557376)
		(end 418.306758 -203.654914)
		(width 0.18288)
		(layer "In2.Cu")
		(net "M_F_CPU0_SB_DQ<23>")
	)
	(segment
		(start 413.235902 -202.700128)
		(end 412.47695 -202.700128)
		(width 0.18288)
		(layer "In2.Cu")
		(net "M_F_CPU0_SB_DQ<23>")
	)
	(segment
		(start 414.495996 -203.373736)
		(end 413.235902 -202.700128)
		(width 0.18288)
		(layer "In2.Cu")
		(net "M_F_CPU0_SB_DQ<23>")
	)
	(arc
		(start 387.961378 -219.18168)
		(mid 387.77418 -219.131537)
		(end 387.586982 -219.18168)
		(width 0.088646)
		(layer "In2.Cu")
		(net "M_F_CPU0_SB_DQ<23>")
	)
	(arc
		(start 386.168646 -220.000576)
		(mid 386.037732 -220.136936)
		(end 385.990084 -220.319854)
		(width 0.088646)
		(layer "In2.Cu")
		(net "M_F_CPU0_SB_DQ<23>")
	)
	(arc
		(start 385.990084 -220.338396)
		(mid 385.909922 -220.610585)
		(end 385.707636 -220.809566)
		(width 0.088646)
		(layer "In2.Cu")
		(net "M_F_CPU0_SB_DQ<23>")
	)
	(arc
		(start 385.698746 -220.814646)
		(mid 385.582937 -220.926575)
		(end 385.524756 -221.076774)
		(width 0.088646)
		(layer "In2.Cu")
		(net "M_F_CPU0_SB_DQ<23>")
	)
	(arc
		(start 388.251446 -219.257626)
		(mid 388.101295 -219.23921)
		(end 387.961378 -219.18168)
		(width 0.088646)
		(layer "In2.Cu")
		(net "M_F_CPU0_SB_DQ<23>")
	)
	(arc
		(start 387.57225 -219.190316)
		(mid 387.295775 -219.257636)
		(end 387.021578 -219.18168)
		(width 0.088646)
		(layer "In2.Cu")
		(net "M_F_CPU0_SB_DQ<23>")
	)
	(arc
		(start 386.45973 -219.521532)
		(mid 386.38036 -219.795266)
		(end 386.177536 -219.995496)
		(width 0.088646)
		(layer "In2.Cu")
		(net "M_F_CPU0_SB_DQ<23>")
	)
	(arc
		(start 386.638292 -219.18676)
		(mid 386.507378 -219.32312)
		(end 386.45973 -219.506038)
		(width 0.088646)
		(layer "In2.Cu")
		(net "M_F_CPU0_SB_DQ<23>")
	)
	(arc
		(start 387.021578 -219.18168)
		(mid 386.83438 -219.131537)
		(end 386.647182 -219.18168)
		(width 0.088646)
		(layer "In2.Cu")
		(net "M_F_CPU0_SB_DQ<23>")
	)
	(segment
		(start 431.076354 -207.103726)
		(end 431.280316 -206.899764)
		(width 0.20066)
		(layer "F.Cu")
		(net "M_F_CPU0_SB_DQ<22>")
	)
	(segment
		(start 428.367952 -207.098646)
		(end 428.375064 -207.091534)
		(width 0.1016)
		(layer "F.Cu")
		(net "M_F_CPU0_SB_DQ<22>")
	)
	(segment
		(start 431.514504 -206.414624)
		(end 431.898552 -206.414624)
		(width 0.20066)
		(layer "F.Cu")
		(net "M_F_CPU0_SB_DQ<22>")
	)
	(segment
		(start 431.898552 -206.414624)
		(end 432.15052 -206.666592)
		(width 0.20066)
		(layer "F.Cu")
		(net "M_F_CPU0_SB_DQ<22>")
	)
	(segment
		(start 430.395126 -207.103726)
		(end 431.076354 -207.103726)
		(width 0.20066)
		(layer "F.Cu")
		(net "M_F_CPU0_SB_DQ<22>")
	)
	(segment
		(start 425.940982 -206.666592)
		(end 427.639226 -206.666592)
		(width 0.20066)
		(layer "F.Cu")
		(net "M_F_CPU0_SB_DQ<22>")
	)
	(segment
		(start 431.280316 -206.648812)
		(end 431.514504 -206.414624)
		(width 0.20066)
		(layer "F.Cu")
		(net "M_F_CPU0_SB_DQ<22>")
	)
	(segment
		(start 431.280316 -206.899764)
		(end 431.280316 -206.648812)
		(width 0.20066)
		(layer "F.Cu")
		(net "M_F_CPU0_SB_DQ<22>")
	)
	(segment
		(start 430.382934 -207.091534)
		(end 430.395126 -207.103726)
		(width 0.1016)
		(layer "F.Cu")
		(net "M_F_CPU0_SB_DQ<22>")
	)
	(segment
		(start 428.363126 -207.098646)
		(end 428.367952 -207.098646)
		(width 0.101854)
		(layer "F.Cu")
		(net "M_F_CPU0_SB_DQ<22>")
	)
	(segment
		(start 428.07128 -207.098646)
		(end 428.363126 -207.098646)
		(width 0.20066)
		(layer "F.Cu")
		(net "M_F_CPU0_SB_DQ<22>")
	)
	(segment
		(start 424.836082 -206.666592)
		(end 425.940982 -206.666592)
		(width 0.20066)
		(layer "F.Cu")
		(net "M_F_CPU0_SB_DQ<22>")
	)
	(segment
		(start 427.639226 -206.666592)
		(end 428.07128 -207.098646)
		(width 0.20066)
		(layer "F.Cu")
		(net "M_F_CPU0_SB_DQ<22>")
	)
	(segment
		(start 428.375064 -207.091534)
		(end 430.382934 -207.091534)
		(width 0.1016)
		(layer "F.Cu")
		(net "M_F_CPU0_SB_DQ<22>")
	)
	(segment
		(start 432.15052 -206.666592)
		(end 433.484782 -206.666592)
		(width 0.20066)
		(layer "F.Cu")
		(net "M_F_CPU0_SB_DQ<22>")
	)
	(segment
		(start 386.364734 -222.48368)
		(end 386.364734 -221.94774)
		(width 0.20066)
		(layer "F.Cu")
		(net "M_F_CPU0_SB_DQ<22>")
	)
	(segment
		(start 409.758896 -203.50226)
		(end 408.310842 -203.50226)
		(width 0.18288)
		(layer "In2.Cu")
		(net "M_F_CPU0_SB_DQ<22>")
	)
	(segment
		(start 388.440422 -220.639132)
		(end 388.431532 -220.644212)
		(width 0.088646)
		(layer "In2.Cu")
		(net "M_F_CPU0_SB_DQ<22>")
	)
	(segment
		(start 408.078432 -203.73467)
		(end 407.722324 -203.73467)
		(width 0.18288)
		(layer "In2.Cu")
		(net "M_F_CPU0_SB_DQ<22>")
	)
	(segment
		(start 423.450766 -207.794098)
		(end 422.747694 -207.091026)
		(width 0.18288)
		(layer "In2.Cu")
		(net "M_F_CPU0_SB_DQ<22>")
	)
	(segment
		(start 415.560764 -204.283056)
		(end 415.306002 -204.537818)
		(width 0.18288)
		(layer "In2.Cu")
		(net "M_F_CPU0_SB_DQ<22>")
	)
	(segment
		(start 424.363388 -207.601058)
		(end 424.170348 -207.794098)
		(width 0.18288)
		(layer "In2.Cu")
		(net "M_F_CPU0_SB_DQ<22>")
	)
	(segment
		(start 403.975062 -204.591412)
		(end 403.975062 -204.852016)
		(width 0.18288)
		(layer "In2.Cu")
		(net "M_F_CPU0_SB_DQ<22>")
	)
	(segment
		(start 406.168606 -203.336652)
		(end 405.802846 -203.702412)
		(width 0.18288)
		(layer "In2.Cu")
		(net "M_F_CPU0_SB_DQ<22>")
	)
	(segment
		(start 424.363388 -207.139286)
		(end 424.363388 -207.601058)
		(width 0.18288)
		(layer "In2.Cu")
		(net "M_F_CPU0_SB_DQ<22>")
	)
	(segment
		(start 405.802846 -203.702412)
		(end 404.864062 -203.702412)
		(width 0.18288)
		(layer "In2.Cu")
		(net "M_F_CPU0_SB_DQ<22>")
	)
	(segment
		(start 404.864062 -203.702412)
		(end 403.975062 -204.591412)
		(width 0.18288)
		(layer "In2.Cu")
		(net "M_F_CPU0_SB_DQ<22>")
	)
	(segment
		(start 413.383984 -204.537818)
		(end 412.107126 -203.689966)
		(width 0.18288)
		(layer "In2.Cu")
		(net "M_F_CPU0_SB_DQ<22>")
	)
	(segment
		(start 418.451538 -206.252826)
		(end 417.420806 -205.222094)
		(width 0.18288)
		(layer "In2.Cu")
		(net "M_F_CPU0_SB_DQ<22>")
	)
	(segment
		(start 387.030722 -221.453202)
		(end 387.021832 -221.458282)
		(width 0.088646)
		(layer "In2.Cu")
		(net "M_F_CPU0_SB_DQ<22>")
	)
	(segment
		(start 417.420806 -205.222094)
		(end 417.420806 -204.967586)
		(width 0.18288)
		(layer "In2.Cu")
		(net "M_F_CPU0_SB_DQ<22>")
	)
	(segment
		(start 420.555928 -207.090772)
		(end 419.717982 -206.252826)
		(width 0.18288)
		(layer "In2.Cu")
		(net "M_F_CPU0_SB_DQ<22>")
	)
	(segment
		(start 412.107126 -203.689966)
		(end 409.946602 -203.689966)
		(width 0.18288)
		(layer "In2.Cu")
		(net "M_F_CPU0_SB_DQ<22>")
	)
	(segment
		(start 407.722324 -203.73467)
		(end 407.324306 -203.336652)
		(width 0.18288)
		(layer "In2.Cu")
		(net "M_F_CPU0_SB_DQ<22>")
	)
	(segment
		(start 409.946602 -203.689966)
		(end 409.758896 -203.50226)
		(width 0.18288)
		(layer "In2.Cu")
		(net "M_F_CPU0_SB_DQ<22>")
	)
	(segment
		(start 407.324306 -203.336652)
		(end 406.168606 -203.336652)
		(width 0.18288)
		(layer "In2.Cu")
		(net "M_F_CPU0_SB_DQ<22>")
	)
	(segment
		(start 388.618984 -220.208094)
		(end 388.618984 -220.319854)
		(width 0.088646)
		(layer "In2.Cu")
		(net "M_F_CPU0_SB_DQ<22>")
	)
	(segment
		(start 403.975062 -204.852016)
		(end 389.670798 -219.15628)
		(width 0.18288)
		(layer "In2.Cu")
		(net "M_F_CPU0_SB_DQ<22>")
	)
	(segment
		(start 416.736276 -204.283056)
		(end 415.560764 -204.283056)
		(width 0.18288)
		(layer "In2.Cu")
		(net "M_F_CPU0_SB_DQ<22>")
	)
	(segment
		(start 387.209284 -221.115382)
		(end 387.209284 -221.133924)
		(width 0.088646)
		(layer "In2.Cu")
		(net "M_F_CPU0_SB_DQ<22>")
	)
	(segment
		(start 415.306002 -204.537818)
		(end 413.383984 -204.537818)
		(width 0.18288)
		(layer "In2.Cu")
		(net "M_F_CPU0_SB_DQ<22>")
	)
	(segment
		(start 386.99313 -221.474792)
		(end 386.364734 -221.94774)
		(width 0.088646)
		(layer "In2.Cu")
		(net "M_F_CPU0_SB_DQ<22>")
	)
	(segment
		(start 424.170348 -207.794098)
		(end 423.450766 -207.794098)
		(width 0.18288)
		(layer "In2.Cu")
		(net "M_F_CPU0_SB_DQ<22>")
	)
	(segment
		(start 387.021832 -221.458282)
		(end 386.99313 -221.474792)
		(width 0.088646)
		(layer "In2.Cu")
		(net "M_F_CPU0_SB_DQ<22>")
	)
	(segment
		(start 424.836082 -206.666592)
		(end 424.363388 -207.139286)
		(width 0.18288)
		(layer "In2.Cu")
		(net "M_F_CPU0_SB_DQ<22>")
	)
	(segment
		(start 389.670798 -219.15628)
		(end 388.618984 -220.208094)
		(width 0.088646)
		(layer "In2.Cu")
		(net "M_F_CPU0_SB_DQ<22>")
	)
	(segment
		(start 422.747694 -207.091026)
		(end 420.689786 -207.091026)
		(width 0.18288)
		(layer "In2.Cu")
		(net "M_F_CPU0_SB_DQ<22>")
	)
	(segment
		(start 420.689786 -207.091026)
		(end 420.555928 -207.090772)
		(width 0.18288)
		(layer "In2.Cu")
		(net "M_F_CPU0_SB_DQ<22>")
	)
	(segment
		(start 408.310842 -203.50226)
		(end 408.078432 -203.73467)
		(width 0.18288)
		(layer "In2.Cu")
		(net "M_F_CPU0_SB_DQ<22>")
	)
	(segment
		(start 419.717982 -206.252826)
		(end 418.451538 -206.252826)
		(width 0.18288)
		(layer "In2.Cu")
		(net "M_F_CPU0_SB_DQ<22>")
	)
	(segment
		(start 417.420806 -204.967586)
		(end 416.736276 -204.283056)
		(width 0.18288)
		(layer "In2.Cu")
		(net "M_F_CPU0_SB_DQ<22>")
	)
	(arc
		(start 387.209284 -221.133924)
		(mid 387.161605 -221.316824)
		(end 387.030722 -221.453202)
		(width 0.088646)
		(layer "In2.Cu")
		(net "M_F_CPU0_SB_DQ<22>")
	)
	(arc
		(start 387.491732 -220.644212)
		(mid 387.289446 -220.843193)
		(end 387.209284 -221.115382)
		(width 0.088646)
		(layer "In2.Cu")
		(net "M_F_CPU0_SB_DQ<22>")
	)
	(arc
		(start 388.057136 -220.644212)
		(mid 387.774434 -220.56847)
		(end 387.491732 -220.644212)
		(width 0.088646)
		(layer "In2.Cu")
		(net "M_F_CPU0_SB_DQ<22>")
	)
	(arc
		(start 388.431532 -220.644212)
		(mid 388.244334 -220.694355)
		(end 388.057136 -220.644212)
		(width 0.088646)
		(layer "In2.Cu")
		(net "M_F_CPU0_SB_DQ<22>")
	)
	(arc
		(start 388.618984 -220.319854)
		(mid 388.571305 -220.502754)
		(end 388.440422 -220.639132)
		(width 0.088646)
		(layer "In2.Cu")
		(net "M_F_CPU0_SB_DQ<22>")
	)
	(segment
		(start 384.95478 -221.134178)
		(end 384.955034 -221.133924)
		(width 0.20066)
		(layer "F.Cu")
		(net "M_F_CPU0_SB_DQ<21>")
	)
	(segment
		(start 423.610278 -206.065374)
		(end 423.361612 -205.816708)
		(width 0.20066)
		(layer "F.Cu")
		(net "M_F_CPU0_SB_DQ<21>")
	)
	(segment
		(start 424.391582 -205.391766)
		(end 424.273472 -205.509876)
		(width 0.20066)
		(layer "F.Cu")
		(net "M_F_CPU0_SB_DQ<21>")
	)
	(segment
		(start 427.36135 -205.385416)
		(end 426.951394 -205.385416)
		(width 0.20066)
		(layer "F.Cu")
		(net "M_F_CPU0_SB_DQ<21>")
	)
	(segment
		(start 426.951394 -205.385416)
		(end 426.945044 -205.391766)
		(width 0.1016)
		(layer "F.Cu")
		(net "M_F_CPU0_SB_DQ<21>")
	)
	(segment
		(start 384.95478 -221.669864)
		(end 384.95478 -221.134178)
		(width 0.20066)
		(layer "F.Cu")
		(net "M_F_CPU0_SB_DQ<21>")
	)
	(segment
		(start 424.273472 -205.509876)
		(end 424.273472 -205.877414)
		(width 0.20066)
		(layer "F.Cu")
		(net "M_F_CPU0_SB_DQ<21>")
	)
	(segment
		(start 427.792896 -205.816962)
		(end 427.36135 -205.385416)
		(width 0.20066)
		(layer "F.Cu")
		(net "M_F_CPU0_SB_DQ<21>")
	)
	(segment
		(start 429.384714 -205.816708)
		(end 429.38446 -205.816962)
		(width 0.20066)
		(layer "F.Cu")
		(net "M_F_CPU0_SB_DQ<21>")
	)
	(segment
		(start 423.361612 -205.816708)
		(end 421.840914 -205.816708)
		(width 0.20066)
		(layer "F.Cu")
		(net "M_F_CPU0_SB_DQ<21>")
	)
	(segment
		(start 424.756326 -205.391766)
		(end 424.73626 -205.391766)
		(width 0.101854)
		(layer "F.Cu")
		(net "M_F_CPU0_SB_DQ<21>")
	)
	(segment
		(start 424.085512 -206.065374)
		(end 423.610278 -206.065374)
		(width 0.20066)
		(layer "F.Cu")
		(net "M_F_CPU0_SB_DQ<21>")
	)
	(segment
		(start 424.73626 -205.391766)
		(end 424.391582 -205.391766)
		(width 0.20066)
		(layer "F.Cu")
		(net "M_F_CPU0_SB_DQ<21>")
	)
	(segment
		(start 426.945044 -205.391766)
		(end 424.756326 -205.391766)
		(width 0.1016)
		(layer "F.Cu")
		(net "M_F_CPU0_SB_DQ<21>")
	)
	(segment
		(start 424.273472 -205.877414)
		(end 424.085512 -206.065374)
		(width 0.20066)
		(layer "F.Cu")
		(net "M_F_CPU0_SB_DQ<21>")
	)
	(segment
		(start 429.38446 -205.816962)
		(end 427.792896 -205.816962)
		(width 0.20066)
		(layer "F.Cu")
		(net "M_F_CPU0_SB_DQ<21>")
	)
	(segment
		(start 421.840914 -205.816708)
		(end 420.736014 -205.816708)
		(width 0.20066)
		(layer "F.Cu")
		(net "M_F_CPU0_SB_DQ<21>")
	)
	(segment
		(start 388.635494 -218.771724)
		(end 388.3406 -219.066618)
		(width 0.088646)
		(layer "In2.Cu")
		(net "M_F_CPU0_SB_DQ<21>")
	)
	(segment
		(start 406.377394 -201.449178)
		(end 405.800052 -202.02652)
		(width 0.18288)
		(layer "In2.Cu")
		(net "M_F_CPU0_SB_DQ<21>")
	)
	(segment
		(start 412.711392 -201.889106)
		(end 411.801564 -201.889106)
		(width 0.18288)
		(layer "In2.Cu")
		(net "M_F_CPU0_SB_DQ<21>")
	)
	(segment
		(start 419.31336 -202.843892)
		(end 418.776912 -202.843892)
		(width 0.18288)
		(layer "In2.Cu")
		(net "M_F_CPU0_SB_DQ<21>")
	)
	(segment
		(start 417.686744 -202.843892)
		(end 415.682684 -202.843892)
		(width 0.18288)
		(layer "In2.Cu")
		(net "M_F_CPU0_SB_DQ<21>")
	)
	(segment
		(start 402.857716 -203.863194)
		(end 402.857716 -204.272642)
		(width 0.18288)
		(layer "In2.Cu")
		(net "M_F_CPU0_SB_DQ<21>")
	)
	(segment
		(start 418.583872 -202.650852)
		(end 418.583872 -202.347576)
		(width 0.18288)
		(layer "In2.Cu")
		(net "M_F_CPU0_SB_DQ<21>")
	)
	(segment
		(start 411.535626 -202.155044)
		(end 410.179012 -202.155044)
		(width 0.18288)
		(layer "In2.Cu")
		(net "M_F_CPU0_SB_DQ<21>")
	)
	(segment
		(start 405.800052 -202.02652)
		(end 404.69439 -202.02652)
		(width 0.18288)
		(layer "In2.Cu")
		(net "M_F_CPU0_SB_DQ<21>")
	)
	(segment
		(start 386.551932 -219.01658)
		(end 386.545836 -219.020136)
		(width 0.088646)
		(layer "In2.Cu")
		(net "M_F_CPU0_SB_DQ<21>")
	)
	(segment
		(start 415.489644 -202.311762)
		(end 415.17316 -201.995278)
		(width 0.18288)
		(layer "In2.Cu")
		(net "M_F_CPU0_SB_DQ<21>")
	)
	(segment
		(start 386.090668 -219.825316)
		(end 386.081778 -219.830396)
		(width 0.088646)
		(layer "In2.Cu")
		(net "M_F_CPU0_SB_DQ<21>")
	)
	(segment
		(start 409.44292 -201.418952)
		(end 408.828748 -201.418952)
		(width 0.18288)
		(layer "In2.Cu")
		(net "M_F_CPU0_SB_DQ<21>")
	)
	(segment
		(start 420.1541 -204.838046)
		(end 420.1541 -203.684632)
		(width 0.18288)
		(layer "In2.Cu")
		(net "M_F_CPU0_SB_DQ<21>")
	)
	(segment
		(start 420.568374 -205.41234)
		(end 420.267384 -205.11135)
		(width 0.18288)
		(layer "In2.Cu")
		(net "M_F_CPU0_SB_DQ<21>")
	)
	(segment
		(start 407.676858 -202.039982)
		(end 407.086054 -201.449178)
		(width 0.18288)
		(layer "In2.Cu")
		(net "M_F_CPU0_SB_DQ<21>")
	)
	(segment
		(start 387.506464 -219.007944)
		(end 387.491732 -219.01658)
		(width 0.088646)
		(layer "In2.Cu")
		(net "M_F_CPU0_SB_DQ<21>")
	)
	(segment
		(start 388.3406 -219.066618)
		(end 388.251446 -219.066618)
		(width 0.088646)
		(layer "In2.Cu")
		(net "M_F_CPU0_SB_DQ<21>")
	)
	(segment
		(start 410.179012 -202.155044)
		(end 409.44292 -201.418952)
		(width 0.18288)
		(layer "In2.Cu")
		(net "M_F_CPU0_SB_DQ<21>")
	)
	(segment
		(start 417.879784 -202.650852)
		(end 417.686744 -202.843892)
		(width 0.18288)
		(layer "In2.Cu")
		(net "M_F_CPU0_SB_DQ<21>")
	)
	(segment
		(start 418.583872 -202.347576)
		(end 418.400992 -202.164696)
		(width 0.18288)
		(layer "In2.Cu")
		(net "M_F_CPU0_SB_DQ<21>")
	)
	(segment
		(start 418.776912 -202.843892)
		(end 418.583872 -202.650852)
		(width 0.18288)
		(layer "In2.Cu")
		(net "M_F_CPU0_SB_DQ<21>")
	)
	(segment
		(start 385.621022 -220.639132)
		(end 385.612132 -220.644212)
		(width 0.088646)
		(layer "In2.Cu")
		(net "M_F_CPU0_SB_DQ<21>")
	)
	(segment
		(start 420.1541 -203.684632)
		(end 419.31336 -202.843892)
		(width 0.18288)
		(layer "In2.Cu")
		(net "M_F_CPU0_SB_DQ<21>")
	)
	(segment
		(start 385.267962 -221.133924)
		(end 384.955034 -221.133924)
		(width 0.088646)
		(layer "In2.Cu")
		(net "M_F_CPU0_SB_DQ<21>")
	)
	(segment
		(start 408.207718 -202.039982)
		(end 407.676858 -202.039982)
		(width 0.18288)
		(layer "In2.Cu")
		(net "M_F_CPU0_SB_DQ<21>")
	)
	(segment
		(start 385.332986 -221.0689)
		(end 385.267962 -221.133924)
		(width 0.088646)
		(layer "In2.Cu")
		(net "M_F_CPU0_SB_DQ<21>")
	)
	(segment
		(start 418.062664 -202.164696)
		(end 417.879784 -202.347576)
		(width 0.18288)
		(layer "In2.Cu")
		(net "M_F_CPU0_SB_DQ<21>")
	)
	(segment
		(start 388.635494 -218.494864)
		(end 388.635494 -218.771724)
		(width 0.088646)
		(layer "In2.Cu")
		(net "M_F_CPU0_SB_DQ<21>")
	)
	(segment
		(start 418.400992 -202.164696)
		(end 418.062664 -202.164696)
		(width 0.18288)
		(layer "In2.Cu")
		(net "M_F_CPU0_SB_DQ<21>")
	)
	(segment
		(start 386.566664 -219.007944)
		(end 386.551932 -219.01658)
		(width 0.088646)
		(layer "In2.Cu")
		(net "M_F_CPU0_SB_DQ<21>")
	)
	(segment
		(start 415.682684 -202.843892)
		(end 415.489644 -202.650852)
		(width 0.18288)
		(layer "In2.Cu")
		(net "M_F_CPU0_SB_DQ<21>")
	)
	(segment
		(start 385.799584 -220.30436)
		(end 385.799584 -220.319854)
		(width 0.088646)
		(layer "In2.Cu")
		(net "M_F_CPU0_SB_DQ<21>")
	)
	(segment
		(start 420.736014 -205.816708)
		(end 420.623746 -205.546198)
		(width 0.18288)
		(layer "In2.Cu")
		(net "M_F_CPU0_SB_DQ<21>")
	)
	(segment
		(start 402.857716 -204.272642)
		(end 388.822438 -218.30792)
		(width 0.18288)
		(layer "In2.Cu")
		(net "M_F_CPU0_SB_DQ<21>")
	)
	(segment
		(start 415.17316 -201.995278)
		(end 412.817564 -201.995278)
		(width 0.18288)
		(layer "In2.Cu")
		(net "M_F_CPU0_SB_DQ<21>")
	)
	(segment
		(start 411.801564 -201.889106)
		(end 411.535626 -202.155044)
		(width 0.18288)
		(layer "In2.Cu")
		(net "M_F_CPU0_SB_DQ<21>")
	)
	(segment
		(start 388.822438 -218.30792)
		(end 388.635494 -218.494864)
		(width 0.088646)
		(layer "In2.Cu")
		(net "M_F_CPU0_SB_DQ<21>")
	)
	(segment
		(start 412.817564 -201.995278)
		(end 412.711392 -201.889106)
		(width 0.18288)
		(layer "In2.Cu")
		(net "M_F_CPU0_SB_DQ<21>")
	)
	(segment
		(start 407.086054 -201.449178)
		(end 406.377394 -201.449178)
		(width 0.18288)
		(layer "In2.Cu")
		(net "M_F_CPU0_SB_DQ<21>")
	)
	(segment
		(start 417.879784 -202.347576)
		(end 417.879784 -202.650852)
		(width 0.18288)
		(layer "In2.Cu")
		(net "M_F_CPU0_SB_DQ<21>")
	)
	(segment
		(start 420.267384 -205.11135)
		(end 420.1541 -204.838046)
		(width 0.18288)
		(layer "In2.Cu")
		(net "M_F_CPU0_SB_DQ<21>")
	)
	(segment
		(start 404.69439 -202.02652)
		(end 402.857716 -203.863194)
		(width 0.18288)
		(layer "In2.Cu")
		(net "M_F_CPU0_SB_DQ<21>")
	)
	(segment
		(start 408.828748 -201.418952)
		(end 408.207718 -202.039982)
		(width 0.18288)
		(layer "In2.Cu")
		(net "M_F_CPU0_SB_DQ<21>")
	)
	(segment
		(start 420.623746 -205.546198)
		(end 420.568374 -205.41234)
		(width 0.18288)
		(layer "In2.Cu")
		(net "M_F_CPU0_SB_DQ<21>")
	)
	(segment
		(start 415.489644 -202.650852)
		(end 415.489644 -202.311762)
		(width 0.18288)
		(layer "In2.Cu")
		(net "M_F_CPU0_SB_DQ<21>")
	)
	(arc
		(start 385.799584 -220.319854)
		(mid 385.751905 -220.502754)
		(end 385.621022 -220.639132)
		(width 0.088646)
		(layer "In2.Cu")
		(net "M_F_CPU0_SB_DQ<21>")
	)
	(arc
		(start 386.26923 -219.506038)
		(mid 386.221551 -219.688938)
		(end 386.090668 -219.825316)
		(width 0.088646)
		(layer "In2.Cu")
		(net "M_F_CPU0_SB_DQ<21>")
	)
	(arc
		(start 387.491732 -219.01658)
		(mid 387.304534 -219.066723)
		(end 387.117336 -219.01658)
		(width 0.088646)
		(layer "In2.Cu")
		(net "M_F_CPU0_SB_DQ<21>")
	)
	(arc
		(start 385.612132 -220.644212)
		(mid 385.422156 -220.823424)
		(end 385.332986 -221.0689)
		(width 0.088646)
		(layer "In2.Cu")
		(net "M_F_CPU0_SB_DQ<21>")
	)
	(arc
		(start 387.117336 -219.01658)
		(mid 386.843137 -218.940745)
		(end 386.566664 -219.007944)
		(width 0.088646)
		(layer "In2.Cu")
		(net "M_F_CPU0_SB_DQ<21>")
	)
	(arc
		(start 388.057136 -219.01658)
		(mid 387.782937 -218.940745)
		(end 387.506464 -219.007944)
		(width 0.088646)
		(layer "In2.Cu")
		(net "M_F_CPU0_SB_DQ<21>")
	)
	(arc
		(start 386.545836 -219.020136)
		(mid 386.343249 -219.226487)
		(end 386.26923 -219.506038)
		(width 0.088646)
		(layer "In2.Cu")
		(net "M_F_CPU0_SB_DQ<21>")
	)
	(arc
		(start 388.251446 -219.066618)
		(mid 388.150884 -219.054838)
		(end 388.057136 -219.01658)
		(width 0.088646)
		(layer "In2.Cu")
		(net "M_F_CPU0_SB_DQ<21>")
	)
	(arc
		(start 386.081778 -219.830396)
		(mid 385.878955 -220.030627)
		(end 385.799584 -220.30436)
		(width 0.088646)
		(layer "In2.Cu")
		(net "M_F_CPU0_SB_DQ<21>")
	)
	(segment
		(start 421.840914 -207.51673)
		(end 420.736014 -207.51673)
		(width 0.20066)
		(layer "F.Cu")
		(net "M_F_CPU0_SB_DQ<20>")
	)
	(segment
		(start 427.792896 -207.516984)
		(end 427.36135 -207.085438)
		(width 0.20066)
		(layer "F.Cu")
		(net "M_F_CPU0_SB_DQ<20>")
	)
	(segment
		(start 424.085512 -207.765396)
		(end 423.610278 -207.765396)
		(width 0.20066)
		(layer "F.Cu")
		(net "M_F_CPU0_SB_DQ<20>")
	)
	(segment
		(start 424.73626 -207.091788)
		(end 424.391582 -207.091788)
		(width 0.20066)
		(layer "F.Cu")
		(net "M_F_CPU0_SB_DQ<20>")
	)
	(segment
		(start 423.361612 -207.51673)
		(end 421.840914 -207.51673)
		(width 0.20066)
		(layer "F.Cu")
		(net "M_F_CPU0_SB_DQ<20>")
	)
	(segment
		(start 424.273472 -207.209898)
		(end 424.273472 -207.577436)
		(width 0.20066)
		(layer "F.Cu")
		(net "M_F_CPU0_SB_DQ<20>")
	)
	(segment
		(start 384.485134 -221.947994)
		(end 384.48488 -221.94774)
		(width 0.20066)
		(layer "F.Cu")
		(net "M_F_CPU0_SB_DQ<20>")
	)
	(segment
		(start 426.951394 -207.085438)
		(end 426.945044 -207.091788)
		(width 0.1016)
		(layer "F.Cu")
		(net "M_F_CPU0_SB_DQ<20>")
	)
	(segment
		(start 424.273472 -207.577436)
		(end 424.085512 -207.765396)
		(width 0.20066)
		(layer "F.Cu")
		(net "M_F_CPU0_SB_DQ<20>")
	)
	(segment
		(start 423.610278 -207.765396)
		(end 423.361612 -207.51673)
		(width 0.20066)
		(layer "F.Cu")
		(net "M_F_CPU0_SB_DQ<20>")
	)
	(segment
		(start 429.38446 -207.516984)
		(end 427.792896 -207.516984)
		(width 0.20066)
		(layer "F.Cu")
		(net "M_F_CPU0_SB_DQ<20>")
	)
	(segment
		(start 427.36135 -207.085438)
		(end 426.951394 -207.085438)
		(width 0.20066)
		(layer "F.Cu")
		(net "M_F_CPU0_SB_DQ<20>")
	)
	(segment
		(start 384.485134 -222.48368)
		(end 384.485134 -221.947994)
		(width 0.20066)
		(layer "F.Cu")
		(net "M_F_CPU0_SB_DQ<20>")
	)
	(segment
		(start 426.945044 -207.091788)
		(end 424.78325 -207.091788)
		(width 0.1016)
		(layer "F.Cu")
		(net "M_F_CPU0_SB_DQ<20>")
	)
	(segment
		(start 424.78325 -207.091788)
		(end 424.73626 -207.091788)
		(width 0.101854)
		(layer "F.Cu")
		(net "M_F_CPU0_SB_DQ<20>")
	)
	(segment
		(start 429.384714 -207.51673)
		(end 429.38446 -207.516984)
		(width 0.20066)
		(layer "F.Cu")
		(net "M_F_CPU0_SB_DQ<20>")
	)
	(segment
		(start 424.391582 -207.091788)
		(end 424.273472 -207.209898)
		(width 0.20066)
		(layer "F.Cu")
		(net "M_F_CPU0_SB_DQ<20>")
	)
	(segment
		(start 419.922198 -207.05572)
		(end 417.553394 -207.05572)
		(width 0.18288)
		(layer "In2.Cu")
		(net "M_F_CPU0_SB_DQ<20>")
	)
	(segment
		(start 420.383208 -207.51673)
		(end 419.922198 -207.05572)
		(width 0.18288)
		(layer "In2.Cu")
		(net "M_F_CPU0_SB_DQ<20>")
	)
	(segment
		(start 416.157156 -206.723742)
		(end 416.157156 -206.1845)
		(width 0.18288)
		(layer "In2.Cu")
		(net "M_F_CPU0_SB_DQ<20>")
	)
	(segment
		(start 390.040114 -219.52585)
		(end 389.569198 -219.996766)
		(width 0.088646)
		(layer "In2.Cu")
		(net "M_F_CPU0_SB_DQ<20>")
	)
	(segment
		(start 415.617914 -205.628494)
		(end 415.344864 -205.628494)
		(width 0.18288)
		(layer "In2.Cu")
		(net "M_F_CPU0_SB_DQ<20>")
	)
	(segment
		(start 416.89274 -205.166214)
		(end 416.654488 -204.927962)
		(width 0.18288)
		(layer "In2.Cu")
		(net "M_F_CPU0_SB_DQ<20>")
	)
	(segment
		(start 416.709352 -207.002634)
		(end 416.436048 -207.002634)
		(width 0.18288)
		(layer "In2.Cu")
		(net "M_F_CPU0_SB_DQ<20>")
	)
	(segment
		(start 420.736014 -207.51673)
		(end 420.383208 -207.51673)
		(width 0.18288)
		(layer "In2.Cu")
		(net "M_F_CPU0_SB_DQ<20>")
	)
	(segment
		(start 385.237482 -222.272098)
		(end 385.209034 -222.255588)
		(width 0.088646)
		(layer "In2.Cu")
		(net "M_F_CPU0_SB_DQ<20>")
	)
	(segment
		(start 416.968178 -206.743808)
		(end 416.709352 -207.002634)
		(width 0.18288)
		(layer "In2.Cu")
		(net "M_F_CPU0_SB_DQ<20>")
	)
	(segment
		(start 414.843722 -205.127352)
		(end 413.696658 -205.127352)
		(width 0.18288)
		(layer "In2.Cu")
		(net "M_F_CPU0_SB_DQ<20>")
	)
	(segment
		(start 416.318446 -204.927962)
		(end 415.617914 -205.628494)
		(width 0.18288)
		(layer "In2.Cu")
		(net "M_F_CPU0_SB_DQ<20>")
	)
	(segment
		(start 416.157156 -206.1845)
		(end 416.89274 -205.448916)
		(width 0.18288)
		(layer "In2.Cu")
		(net "M_F_CPU0_SB_DQ<20>")
	)
	(segment
		(start 413.696658 -205.127352)
		(end 413.40405 -205.41996)
		(width 0.18288)
		(layer "In2.Cu")
		(net "M_F_CPU0_SB_DQ<20>")
	)
	(segment
		(start 415.344864 -205.628494)
		(end 414.843722 -205.127352)
		(width 0.18288)
		(layer "In2.Cu")
		(net "M_F_CPU0_SB_DQ<20>")
	)
	(segment
		(start 386.837936 -222.106744)
		(end 386.551678 -222.272098)
		(width 0.088646)
		(layer "In2.Cu")
		(net "M_F_CPU0_SB_DQ<20>")
	)
	(segment
		(start 388.809484 -220.291406)
		(end 388.809484 -220.338396)
		(width 0.088646)
		(layer "In2.Cu")
		(net "M_F_CPU0_SB_DQ<20>")
	)
	(segment
		(start 416.436048 -207.002634)
		(end 416.157156 -206.723742)
		(width 0.18288)
		(layer "In2.Cu")
		(net "M_F_CPU0_SB_DQ<20>")
	)
	(segment
		(start 409.223972 -204.291692)
		(end 408.991308 -204.059028)
		(width 0.18288)
		(layer "In2.Cu")
		(net "M_F_CPU0_SB_DQ<20>")
	)
	(segment
		(start 412.028894 -204.906626)
		(end 411.46984 -204.347572)
		(width 0.18288)
		(layer "In2.Cu")
		(net "M_F_CPU0_SB_DQ<20>")
	)
	(segment
		(start 385.612132 -222.272098)
		(end 385.611878 -222.272098)
		(width 0.088646)
		(layer "In2.Cu")
		(net "M_F_CPU0_SB_DQ<20>")
	)
	(segment
		(start 417.553394 -207.05572)
		(end 417.241482 -206.743808)
		(width 0.18288)
		(layer "In2.Cu")
		(net "M_F_CPU0_SB_DQ<20>")
	)
	(segment
		(start 412.511494 -204.906626)
		(end 412.028894 -204.906626)
		(width 0.18288)
		(layer "In2.Cu")
		(net "M_F_CPU0_SB_DQ<20>")
	)
	(segment
		(start 409.223972 -204.654404)
		(end 409.223972 -204.291692)
		(width 0.18288)
		(layer "In2.Cu")
		(net "M_F_CPU0_SB_DQ<20>")
	)
	(segment
		(start 385.209034 -222.255588)
		(end 384.48488 -221.94774)
		(width 0.088646)
		(layer "In2.Cu")
		(net "M_F_CPU0_SB_DQ<20>")
	)
	(segment
		(start 387.399784 -221.133924)
		(end 387.399784 -221.14383)
		(width 0.088646)
		(layer "In2.Cu")
		(net "M_F_CPU0_SB_DQ<20>")
	)
	(segment
		(start 409.337002 -204.767434)
		(end 409.223972 -204.654404)
		(width 0.18288)
		(layer "In2.Cu")
		(net "M_F_CPU0_SB_DQ<20>")
	)
	(segment
		(start 416.89274 -205.448916)
		(end 416.89274 -205.166214)
		(width 0.18288)
		(layer "In2.Cu")
		(net "M_F_CPU0_SB_DQ<20>")
	)
	(segment
		(start 410.197808 -204.347572)
		(end 409.777946 -204.767434)
		(width 0.18288)
		(layer "In2.Cu")
		(net "M_F_CPU0_SB_DQ<20>")
	)
	(segment
		(start 413.40405 -205.41996)
		(end 413.024828 -205.41996)
		(width 0.18288)
		(layer "In2.Cu")
		(net "M_F_CPU0_SB_DQ<20>")
	)
	(segment
		(start 413.024828 -205.41996)
		(end 412.511494 -204.906626)
		(width 0.18288)
		(layer "In2.Cu")
		(net "M_F_CPU0_SB_DQ<20>")
	)
	(segment
		(start 404.529798 -204.939392)
		(end 404.529798 -205.036166)
		(width 0.18288)
		(layer "In2.Cu")
		(net "M_F_CPU0_SB_DQ<20>")
	)
	(segment
		(start 408.112468 -204.50556)
		(end 404.96363 -204.50556)
		(width 0.18288)
		(layer "In2.Cu")
		(net "M_F_CPU0_SB_DQ<20>")
	)
	(segment
		(start 409.777946 -204.767434)
		(end 409.337002 -204.767434)
		(width 0.18288)
		(layer "In2.Cu")
		(net "M_F_CPU0_SB_DQ<20>")
	)
	(segment
		(start 408.559 -204.059028)
		(end 408.112468 -204.50556)
		(width 0.18288)
		(layer "In2.Cu")
		(net "M_F_CPU0_SB_DQ<20>")
	)
	(segment
		(start 416.654488 -204.927962)
		(end 416.318446 -204.927962)
		(width 0.18288)
		(layer "In2.Cu")
		(net "M_F_CPU0_SB_DQ<20>")
	)
	(segment
		(start 387.587236 -220.809566)
		(end 387.578346 -220.814646)
		(width 0.088646)
		(layer "In2.Cu")
		(net "M_F_CPU0_SB_DQ<20>")
	)
	(segment
		(start 411.46984 -204.347572)
		(end 410.197808 -204.347572)
		(width 0.18288)
		(layer "In2.Cu")
		(net "M_F_CPU0_SB_DQ<20>")
	)
	(segment
		(start 389.104124 -219.996766)
		(end 388.809484 -220.291406)
		(width 0.088646)
		(layer "In2.Cu")
		(net "M_F_CPU0_SB_DQ<20>")
	)
	(segment
		(start 417.241482 -206.743808)
		(end 416.968178 -206.743808)
		(width 0.18288)
		(layer "In2.Cu")
		(net "M_F_CPU0_SB_DQ<20>")
	)
	(segment
		(start 404.529798 -205.036166)
		(end 390.040114 -219.52585)
		(width 0.18288)
		(layer "In2.Cu")
		(net "M_F_CPU0_SB_DQ<20>")
	)
	(segment
		(start 387.117336 -221.623382)
		(end 387.117082 -221.623636)
		(width 0.088646)
		(layer "In2.Cu")
		(net "M_F_CPU0_SB_DQ<20>")
	)
	(segment
		(start 389.569198 -219.996766)
		(end 389.104124 -219.996766)
		(width 0.088646)
		(layer "In2.Cu")
		(net "M_F_CPU0_SB_DQ<20>")
	)
	(segment
		(start 408.991308 -204.059028)
		(end 408.559 -204.059028)
		(width 0.18288)
		(layer "In2.Cu")
		(net "M_F_CPU0_SB_DQ<20>")
	)
	(segment
		(start 404.96363 -204.50556)
		(end 404.529798 -204.939392)
		(width 0.18288)
		(layer "In2.Cu")
		(net "M_F_CPU0_SB_DQ<20>")
	)
	(arc
		(start 387.578346 -220.814646)
		(mid 387.447432 -220.951006)
		(end 387.399784 -221.133924)
		(width 0.088646)
		(layer "In2.Cu")
		(net "M_F_CPU0_SB_DQ<20>")
	)
	(arc
		(start 388.527036 -220.809566)
		(mid 388.244334 -220.885308)
		(end 387.961632 -220.809566)
		(width 0.088646)
		(layer "In2.Cu")
		(net "M_F_CPU0_SB_DQ<20>")
	)
	(arc
		(start 386.929884 -221.94774)
		(mid 386.905236 -222.039569)
		(end 386.837936 -222.106744)
		(width 0.088646)
		(layer "In2.Cu")
		(net "M_F_CPU0_SB_DQ<20>")
	)
	(arc
		(start 387.399784 -221.14383)
		(mid 387.321673 -221.420779)
		(end 387.117336 -221.623382)
		(width 0.088646)
		(layer "In2.Cu")
		(net "M_F_CPU0_SB_DQ<20>")
	)
	(arc
		(start 387.117082 -221.623636)
		(mid 386.980037 -221.760596)
		(end 386.929884 -221.94774)
		(width 0.088646)
		(layer "In2.Cu")
		(net "M_F_CPU0_SB_DQ<20>")
	)
	(arc
		(start 388.809484 -220.338396)
		(mid 388.729322 -220.610585)
		(end 388.527036 -220.809566)
		(width 0.088646)
		(layer "In2.Cu")
		(net "M_F_CPU0_SB_DQ<20>")
	)
	(arc
		(start 387.961632 -220.809566)
		(mid 387.774434 -220.759423)
		(end 387.587236 -220.809566)
		(width 0.088646)
		(layer "In2.Cu")
		(net "M_F_CPU0_SB_DQ<20>")
	)
	(arc
		(start 386.551678 -222.272098)
		(mid 386.364624 -222.322148)
		(end 386.177536 -222.272098)
		(width 0.088646)
		(layer "In2.Cu")
		(net "M_F_CPU0_SB_DQ<20>")
	)
	(arc
		(start 385.611878 -222.272098)
		(mid 385.42468 -222.322275)
		(end 385.237482 -222.272098)
		(width 0.088646)
		(layer "In2.Cu")
		(net "M_F_CPU0_SB_DQ<20>")
	)
	(arc
		(start 386.177536 -222.272098)
		(mid 385.894834 -222.196322)
		(end 385.612132 -222.272098)
		(width 0.088646)
		(layer "In2.Cu")
		(net "M_F_CPU0_SB_DQ<20>")
	)
	(segment
		(start 424.756326 -230.041704)
		(end 424.73626 -230.041704)
		(width 0.101854)
		(layer "F.Cu")
		(net "M_F_CPU0_SB_DQ<1>")
	)
	(segment
		(start 429.38446 -230.4669)
		(end 427.792896 -230.4669)
		(width 0.20066)
		(layer "F.Cu")
		(net "M_F_CPU0_SB_DQ<1>")
	)
	(segment
		(start 424.273472 -230.527352)
		(end 424.085512 -230.715312)
		(width 0.20066)
		(layer "F.Cu")
		(net "M_F_CPU0_SB_DQ<1>")
	)
	(segment
		(start 423.361612 -230.466646)
		(end 421.840914 -230.466646)
		(width 0.20066)
		(layer "F.Cu")
		(net "M_F_CPU0_SB_DQ<1>")
	)
	(segment
		(start 421.840914 -230.466646)
		(end 420.736014 -230.466646)
		(width 0.20066)
		(layer "F.Cu")
		(net "M_F_CPU0_SB_DQ<1>")
	)
	(segment
		(start 377.90628 -238.76127)
		(end 377.90628 -238.225584)
		(width 0.20066)
		(layer "F.Cu")
		(net "M_F_CPU0_SB_DQ<1>")
	)
	(segment
		(start 423.610278 -230.715312)
		(end 423.361612 -230.466646)
		(width 0.20066)
		(layer "F.Cu")
		(net "M_F_CPU0_SB_DQ<1>")
	)
	(segment
		(start 426.945044 -230.041704)
		(end 424.756326 -230.041704)
		(width 0.1016)
		(layer "F.Cu")
		(net "M_F_CPU0_SB_DQ<1>")
	)
	(segment
		(start 427.792896 -230.4669)
		(end 427.36135 -230.035354)
		(width 0.20066)
		(layer "F.Cu")
		(net "M_F_CPU0_SB_DQ<1>")
	)
	(segment
		(start 424.391582 -230.041704)
		(end 424.273472 -230.159814)
		(width 0.20066)
		(layer "F.Cu")
		(net "M_F_CPU0_SB_DQ<1>")
	)
	(segment
		(start 377.906534 -238.761524)
		(end 377.90628 -238.76127)
		(width 0.20066)
		(layer "F.Cu")
		(net "M_F_CPU0_SB_DQ<1>")
	)
	(segment
		(start 424.73626 -230.041704)
		(end 424.391582 -230.041704)
		(width 0.20066)
		(layer "F.Cu")
		(net "M_F_CPU0_SB_DQ<1>")
	)
	(segment
		(start 426.951394 -230.035354)
		(end 426.945044 -230.041704)
		(width 0.1016)
		(layer "F.Cu")
		(net "M_F_CPU0_SB_DQ<1>")
	)
	(segment
		(start 429.384714 -230.466646)
		(end 429.38446 -230.4669)
		(width 0.20066)
		(layer "F.Cu")
		(net "M_F_CPU0_SB_DQ<1>")
	)
	(segment
		(start 424.273472 -230.159814)
		(end 424.273472 -230.527352)
		(width 0.20066)
		(layer "F.Cu")
		(net "M_F_CPU0_SB_DQ<1>")
	)
	(segment
		(start 424.085512 -230.715312)
		(end 423.610278 -230.715312)
		(width 0.20066)
		(layer "F.Cu")
		(net "M_F_CPU0_SB_DQ<1>")
	)
	(segment
		(start 427.36135 -230.035354)
		(end 426.951394 -230.035354)
		(width 0.20066)
		(layer "F.Cu")
		(net "M_F_CPU0_SB_DQ<1>")
	)
	(segment
		(start 408.199844 -228.340158)
		(end 408.016964 -228.157278)
		(width 0.18288)
		(layer "In4.Cu")
		(net "M_F_CPU0_SB_DQ<1>")
	)
	(segment
		(start 418.32403 -230.493062)
		(end 418.14115 -230.310182)
		(width 0.18288)
		(layer "In4.Cu")
		(net "M_F_CPU0_SB_DQ<1>")
	)
	(segment
		(start 414.723326 -229.895146)
		(end 414.723326 -229.315264)
		(width 0.18288)
		(layer "In4.Cu")
		(net "M_F_CPU0_SB_DQ<1>")
	)
	(segment
		(start 388.941564 -237.282482)
		(end 388.81558 -237.282482)
		(width 0.088646)
		(layer "In4.Cu")
		(net "M_F_CPU0_SB_DQ<1>")
	)
	(segment
		(start 406.977342 -229.192074)
		(end 406.817322 -229.352094)
		(width 0.18288)
		(layer "In4.Cu")
		(net "M_F_CPU0_SB_DQ<1>")
	)
	(segment
		(start 414.906206 -230.078026)
		(end 414.723326 -229.895146)
		(width 0.18288)
		(layer "In4.Cu")
		(net "M_F_CPU0_SB_DQ<1>")
	)
	(segment
		(start 419.964616 -229.695248)
		(end 419.01745 -229.695248)
		(width 0.18288)
		(layer "In4.Cu")
		(net "M_F_CPU0_SB_DQ<1>")
	)
	(segment
		(start 415.582862 -230.078026)
		(end 414.906206 -230.078026)
		(width 0.18288)
		(layer "In4.Cu")
		(net "M_F_CPU0_SB_DQ<1>")
	)
	(segment
		(start 407.323544 -229.192074)
		(end 406.977342 -229.192074)
		(width 0.18288)
		(layer "In4.Cu")
		(net "M_F_CPU0_SB_DQ<1>")
	)
	(segment
		(start 418.14115 -229.878128)
		(end 417.95827 -229.695248)
		(width 0.18288)
		(layer "In4.Cu")
		(net "M_F_CPU0_SB_DQ<1>")
	)
	(segment
		(start 404.51786 -230.327708)
		(end 404.1902 -230.327708)
		(width 0.18288)
		(layer "In4.Cu")
		(net "M_F_CPU0_SB_DQ<1>")
	)
	(segment
		(start 417.95827 -229.695248)
		(end 417.060634 -229.695248)
		(width 0.18288)
		(layer "In4.Cu")
		(net "M_F_CPU0_SB_DQ<1>")
	)
	(segment
		(start 414.029906 -229.895146)
		(end 413.847026 -230.078026)
		(width 0.18288)
		(layer "In4.Cu")
		(net "M_F_CPU0_SB_DQ<1>")
	)
	(segment
		(start 414.212786 -229.132384)
		(end 414.029906 -229.315264)
		(width 0.18288)
		(layer "In4.Cu")
		(net "M_F_CPU0_SB_DQ<1>")
	)
	(segment
		(start 382.887982 -238.715042)
		(end 382.88341 -238.717582)
		(width 0.088646)
		(layer "In4.Cu")
		(net "M_F_CPU0_SB_DQ<1>")
	)
	(segment
		(start 420.736014 -230.466646)
		(end 419.964616 -229.695248)
		(width 0.18288)
		(layer "In4.Cu")
		(net "M_F_CPU0_SB_DQ<1>")
	)
	(segment
		(start 404.70074 -230.144828)
		(end 404.51786 -230.327708)
		(width 0.18288)
		(layer "In4.Cu")
		(net "M_F_CPU0_SB_DQ<1>")
	)
	(segment
		(start 379.126496 -238.716312)
		(end 379.121416 -238.71936)
		(width 0.088646)
		(layer "In4.Cu")
		(net "M_F_CPU0_SB_DQ<1>")
	)
	(segment
		(start 380.073154 -238.712248)
		(end 380.068582 -238.715042)
		(width 0.088646)
		(layer "In4.Cu")
		(net "M_F_CPU0_SB_DQ<1>")
	)
	(segment
		(start 406.817322 -229.352094)
		(end 406.817322 -229.879652)
		(width 0.18288)
		(layer "In4.Cu")
		(net "M_F_CPU0_SB_DQ<1>")
	)
	(segment
		(start 381.008382 -238.715042)
		(end 381.001016 -238.71936)
		(width 0.088646)
		(layer "In4.Cu")
		(net "M_F_CPU0_SB_DQ<1>")
	)
	(segment
		(start 408.382724 -229.192074)
		(end 408.199844 -229.009194)
		(width 0.18288)
		(layer "In4.Cu")
		(net "M_F_CPU0_SB_DQ<1>")
	)
	(segment
		(start 419.01745 -229.695248)
		(end 418.83457 -229.878128)
		(width 0.18288)
		(layer "In4.Cu")
		(net "M_F_CPU0_SB_DQ<1>")
	)
	(segment
		(start 411.872938 -229.192074)
		(end 408.382724 -229.192074)
		(width 0.18288)
		(layer "In4.Cu")
		(net "M_F_CPU0_SB_DQ<1>")
	)
	(segment
		(start 411.874208 -229.190804)
		(end 411.872938 -229.192074)
		(width 0.18288)
		(layer "In4.Cu")
		(net "M_F_CPU0_SB_DQ<1>")
	)
	(segment
		(start 378.563632 -238.715042)
		(end 378.483622 -238.668814)
		(width 0.088646)
		(layer "In4.Cu")
		(net "M_F_CPU0_SB_DQ<1>")
	)
	(segment
		(start 402.80336 -230.327708)
		(end 402.62048 -230.144828)
		(width 0.18288)
		(layer "In4.Cu")
		(net "M_F_CPU0_SB_DQ<1>")
	)
	(segment
		(start 403.3139 -229.8827)
		(end 403.3139 -230.144828)
		(width 0.18288)
		(layer "In4.Cu")
		(net "M_F_CPU0_SB_DQ<1>")
	)
	(segment
		(start 414.029906 -229.315264)
		(end 414.029906 -229.895146)
		(width 0.18288)
		(layer "In4.Cu")
		(net "M_F_CPU0_SB_DQ<1>")
	)
	(segment
		(start 416.787584 -229.968298)
		(end 416.787584 -230.19258)
		(width 0.18288)
		(layer "In4.Cu")
		(net "M_F_CPU0_SB_DQ<1>")
	)
	(segment
		(start 405.111966 -229.69982)
		(end 404.88362 -229.69982)
		(width 0.18288)
		(layer "In4.Cu")
		(net "M_F_CPU0_SB_DQ<1>")
	)
	(segment
		(start 407.506424 -228.340158)
		(end 407.506424 -229.009194)
		(width 0.18288)
		(layer "In4.Cu")
		(net "M_F_CPU0_SB_DQ<1>")
	)
	(segment
		(start 403.82444 -229.69982)
		(end 403.49678 -229.69982)
		(width 0.18288)
		(layer "In4.Cu")
		(net "M_F_CPU0_SB_DQ<1>")
	)
	(segment
		(start 406.817322 -229.879652)
		(end 406.657302 -230.039672)
		(width 0.18288)
		(layer "In4.Cu")
		(net "M_F_CPU0_SB_DQ<1>")
	)
	(segment
		(start 402.62048 -230.144828)
		(end 402.62048 -229.8827)
		(width 0.18288)
		(layer "In4.Cu")
		(net "M_F_CPU0_SB_DQ<1>")
	)
	(segment
		(start 408.199844 -229.009194)
		(end 408.199844 -228.340158)
		(width 0.18288)
		(layer "In4.Cu")
		(net "M_F_CPU0_SB_DQ<1>")
	)
	(segment
		(start 402.4376 -229.69982)
		(end 402.253958 -229.69982)
		(width 0.18288)
		(layer "In4.Cu")
		(net "M_F_CPU0_SB_DQ<1>")
	)
	(segment
		(start 406.657302 -230.039672)
		(end 405.451818 -230.039672)
		(width 0.18288)
		(layer "In4.Cu")
		(net "M_F_CPU0_SB_DQ<1>")
	)
	(segment
		(start 380.068582 -238.715042)
		(end 380.061216 -238.71936)
		(width 0.088646)
		(layer "In4.Cu")
		(net "M_F_CPU0_SB_DQ<1>")
	)
	(segment
		(start 416.787584 -230.19258)
		(end 416.604704 -230.37546)
		(width 0.18288)
		(layer "In4.Cu")
		(net "M_F_CPU0_SB_DQ<1>")
	)
	(segment
		(start 414.723326 -229.315264)
		(end 414.540446 -229.132384)
		(width 0.18288)
		(layer "In4.Cu")
		(net "M_F_CPU0_SB_DQ<1>")
	)
	(segment
		(start 382.892554 -238.712248)
		(end 382.887982 -238.715042)
		(width 0.088646)
		(layer "In4.Cu")
		(net "M_F_CPU0_SB_DQ<1>")
	)
	(segment
		(start 415.880296 -230.37546)
		(end 415.582862 -230.078026)
		(width 0.18288)
		(layer "In4.Cu")
		(net "M_F_CPU0_SB_DQ<1>")
	)
	(segment
		(start 402.62048 -229.8827)
		(end 402.4376 -229.69982)
		(width 0.18288)
		(layer "In4.Cu")
		(net "M_F_CPU0_SB_DQ<1>")
	)
	(segment
		(start 397.111474 -234.842304)
		(end 392.645138 -234.842304)
		(width 0.18288)
		(layer "In4.Cu")
		(net "M_F_CPU0_SB_DQ<1>")
	)
	(segment
		(start 383.828036 -238.715042)
		(end 383.827782 -238.715042)
		(width 0.088646)
		(layer "In4.Cu")
		(net "M_F_CPU0_SB_DQ<1>")
	)
	(segment
		(start 407.689304 -228.157278)
		(end 407.506424 -228.340158)
		(width 0.18288)
		(layer "In4.Cu")
		(net "M_F_CPU0_SB_DQ<1>")
	)
	(segment
		(start 418.14115 -230.310182)
		(end 418.14115 -229.878128)
		(width 0.18288)
		(layer "In4.Cu")
		(net "M_F_CPU0_SB_DQ<1>")
	)
	(segment
		(start 418.83457 -229.878128)
		(end 418.83457 -230.310182)
		(width 0.18288)
		(layer "In4.Cu")
		(net "M_F_CPU0_SB_DQ<1>")
	)
	(segment
		(start 387.571234 -238.526828)
		(end 386.950712 -238.683292)
		(width 0.088646)
		(layer "In4.Cu")
		(net "M_F_CPU0_SB_DQ<1>")
	)
	(segment
		(start 417.060634 -229.695248)
		(end 416.787584 -229.968298)
		(width 0.18288)
		(layer "In4.Cu")
		(net "M_F_CPU0_SB_DQ<1>")
	)
	(segment
		(start 405.451818 -230.039672)
		(end 405.111966 -229.69982)
		(width 0.18288)
		(layer "In4.Cu")
		(net "M_F_CPU0_SB_DQ<1>")
	)
	(segment
		(start 412.968694 -230.078026)
		(end 412.081472 -229.190804)
		(width 0.18288)
		(layer "In4.Cu")
		(net "M_F_CPU0_SB_DQ<1>")
	)
	(segment
		(start 403.13102 -230.327708)
		(end 402.80336 -230.327708)
		(width 0.18288)
		(layer "In4.Cu")
		(net "M_F_CPU0_SB_DQ<1>")
	)
	(segment
		(start 404.1902 -230.327708)
		(end 404.00732 -230.144828)
		(width 0.18288)
		(layer "In4.Cu")
		(net "M_F_CPU0_SB_DQ<1>")
	)
	(segment
		(start 414.540446 -229.132384)
		(end 414.212786 -229.132384)
		(width 0.18288)
		(layer "In4.Cu")
		(net "M_F_CPU0_SB_DQ<1>")
	)
	(segment
		(start 407.506424 -229.009194)
		(end 407.323544 -229.192074)
		(width 0.18288)
		(layer "In4.Cu")
		(net "M_F_CPU0_SB_DQ<1>")
	)
	(segment
		(start 402.253958 -229.69982)
		(end 397.111474 -234.842304)
		(width 0.18288)
		(layer "In4.Cu")
		(net "M_F_CPU0_SB_DQ<1>")
	)
	(segment
		(start 392.645138 -234.842304)
		(end 390.20496 -237.282482)
		(width 0.18288)
		(layer "In4.Cu")
		(net "M_F_CPU0_SB_DQ<1>")
	)
	(segment
		(start 403.3139 -230.144828)
		(end 403.13102 -230.327708)
		(width 0.18288)
		(layer "In4.Cu")
		(net "M_F_CPU0_SB_DQ<1>")
	)
	(segment
		(start 388.81558 -237.282482)
		(end 387.571234 -238.526828)
		(width 0.088646)
		(layer "In4.Cu")
		(net "M_F_CPU0_SB_DQ<1>")
	)
	(segment
		(start 390.20496 -237.282482)
		(end 388.941564 -237.282482)
		(width 0.18288)
		(layer "In4.Cu")
		(net "M_F_CPU0_SB_DQ<1>")
	)
	(segment
		(start 418.83457 -230.310182)
		(end 418.65169 -230.493062)
		(width 0.18288)
		(layer "In4.Cu")
		(net "M_F_CPU0_SB_DQ<1>")
	)
	(segment
		(start 404.00732 -230.144828)
		(end 404.00732 -229.8827)
		(width 0.18288)
		(layer "In4.Cu")
		(net "M_F_CPU0_SB_DQ<1>")
	)
	(segment
		(start 404.70074 -229.8827)
		(end 404.70074 -230.144828)
		(width 0.18288)
		(layer "In4.Cu")
		(net "M_F_CPU0_SB_DQ<1>")
	)
	(segment
		(start 412.081472 -229.190804)
		(end 411.874208 -229.190804)
		(width 0.18288)
		(layer "In4.Cu")
		(net "M_F_CPU0_SB_DQ<1>")
	)
	(segment
		(start 381.012954 -238.712248)
		(end 381.008382 -238.715042)
		(width 0.088646)
		(layer "In4.Cu")
		(net "M_F_CPU0_SB_DQ<1>")
	)
	(segment
		(start 408.016964 -228.157278)
		(end 407.689304 -228.157278)
		(width 0.18288)
		(layer "In4.Cu")
		(net "M_F_CPU0_SB_DQ<1>")
	)
	(segment
		(start 381.948182 -238.715042)
		(end 381.942594 -238.718344)
		(width 0.088646)
		(layer "In4.Cu")
		(net "M_F_CPU0_SB_DQ<1>")
	)
	(segment
		(start 404.88362 -229.69982)
		(end 404.70074 -229.8827)
		(width 0.18288)
		(layer "In4.Cu")
		(net "M_F_CPU0_SB_DQ<1>")
	)
	(segment
		(start 418.65169 -230.493062)
		(end 418.32403 -230.493062)
		(width 0.18288)
		(layer "In4.Cu")
		(net "M_F_CPU0_SB_DQ<1>")
	)
	(segment
		(start 403.49678 -229.69982)
		(end 403.3139 -229.8827)
		(width 0.18288)
		(layer "In4.Cu")
		(net "M_F_CPU0_SB_DQ<1>")
	)
	(segment
		(start 383.827782 -238.715042)
		(end 383.822194 -238.718344)
		(width 0.088646)
		(layer "In4.Cu")
		(net "M_F_CPU0_SB_DQ<1>")
	)
	(segment
		(start 404.00732 -229.8827)
		(end 403.82444 -229.69982)
		(width 0.18288)
		(layer "In4.Cu")
		(net "M_F_CPU0_SB_DQ<1>")
	)
	(segment
		(start 416.604704 -230.37546)
		(end 415.880296 -230.37546)
		(width 0.18288)
		(layer "In4.Cu")
		(net "M_F_CPU0_SB_DQ<1>")
	)
	(segment
		(start 413.847026 -230.078026)
		(end 412.968694 -230.078026)
		(width 0.18288)
		(layer "In4.Cu")
		(net "M_F_CPU0_SB_DQ<1>")
	)
	(arc
		(start 380.443232 -238.715042)
		(mid 380.258568 -238.664782)
		(end 380.073154 -238.712248)
		(width 0.088646)
		(layer "In4.Cu")
		(net "M_F_CPU0_SB_DQ<1>")
	)
	(arc
		(start 386.647436 -238.715042)
		(mid 386.364734 -238.790818)
		(end 386.082032 -238.715042)
		(width 0.088646)
		(layer "In4.Cu")
		(net "M_F_CPU0_SB_DQ<1>")
	)
	(arc
		(start 384.767836 -238.715042)
		(mid 384.485134 -238.790818)
		(end 384.202432 -238.715042)
		(width 0.088646)
		(layer "In4.Cu")
		(net "M_F_CPU0_SB_DQ<1>")
	)
	(arc
		(start 386.082032 -238.715042)
		(mid 385.894834 -238.664899)
		(end 385.707636 -238.715042)
		(width 0.088646)
		(layer "In4.Cu")
		(net "M_F_CPU0_SB_DQ<1>")
	)
	(arc
		(start 381.001016 -238.71936)
		(mid 380.721555 -238.790797)
		(end 380.443232 -238.715042)
		(width 0.088646)
		(layer "In4.Cu")
		(net "M_F_CPU0_SB_DQ<1>")
	)
	(arc
		(start 383.262632 -238.715042)
		(mid 383.077968 -238.664782)
		(end 382.892554 -238.712248)
		(width 0.088646)
		(layer "In4.Cu")
		(net "M_F_CPU0_SB_DQ<1>")
	)
	(arc
		(start 379.503432 -238.715042)
		(mid 379.314782 -238.664774)
		(end 379.126496 -238.716312)
		(width 0.088646)
		(layer "In4.Cu")
		(net "M_F_CPU0_SB_DQ<1>")
	)
	(arc
		(start 386.950712 -238.683292)
		(mid 386.795689 -238.666881)
		(end 386.647436 -238.715042)
		(width 0.088646)
		(layer "In4.Cu")
		(net "M_F_CPU0_SB_DQ<1>")
	)
	(arc
		(start 382.322832 -238.715042)
		(mid 382.135524 -238.664899)
		(end 381.948182 -238.715042)
		(width 0.088646)
		(layer "In4.Cu")
		(net "M_F_CPU0_SB_DQ<1>")
	)
	(arc
		(start 384.202432 -238.715042)
		(mid 384.015234 -238.664899)
		(end 383.828036 -238.715042)
		(width 0.088646)
		(layer "In4.Cu")
		(net "M_F_CPU0_SB_DQ<1>")
	)
	(arc
		(start 379.121416 -238.71936)
		(mid 378.841955 -238.790797)
		(end 378.563632 -238.715042)
		(width 0.088646)
		(layer "In4.Cu")
		(net "M_F_CPU0_SB_DQ<1>")
	)
	(arc
		(start 378.483622 -238.668814)
		(mid 378.180452 -238.466085)
		(end 377.90628 -238.225584)
		(width 0.088646)
		(layer "In4.Cu")
		(net "M_F_CPU0_SB_DQ<1>")
	)
	(arc
		(start 383.822194 -238.718344)
		(mid 383.541979 -238.790785)
		(end 383.262632 -238.715042)
		(width 0.088646)
		(layer "In4.Cu")
		(net "M_F_CPU0_SB_DQ<1>")
	)
	(arc
		(start 380.061216 -238.71936)
		(mid 379.781755 -238.790797)
		(end 379.503432 -238.715042)
		(width 0.088646)
		(layer "In4.Cu")
		(net "M_F_CPU0_SB_DQ<1>")
	)
	(arc
		(start 381.942594 -238.718344)
		(mid 381.662379 -238.790785)
		(end 381.383032 -238.715042)
		(width 0.088646)
		(layer "In4.Cu")
		(net "M_F_CPU0_SB_DQ<1>")
	)
	(arc
		(start 385.142232 -238.715042)
		(mid 384.955034 -238.664899)
		(end 384.767836 -238.715042)
		(width 0.088646)
		(layer "In4.Cu")
		(net "M_F_CPU0_SB_DQ<1>")
	)
	(arc
		(start 382.88341 -238.717582)
		(mid 382.602775 -238.79075)
		(end 382.322832 -238.715042)
		(width 0.088646)
		(layer "In4.Cu")
		(net "M_F_CPU0_SB_DQ<1>")
	)
	(arc
		(start 381.383032 -238.715042)
		(mid 381.198368 -238.664782)
		(end 381.012954 -238.712248)
		(width 0.088646)
		(layer "In4.Cu")
		(net "M_F_CPU0_SB_DQ<1>")
	)
	(arc
		(start 385.707636 -238.715042)
		(mid 385.424934 -238.790818)
		(end 385.142232 -238.715042)
		(width 0.088646)
		(layer "In4.Cu")
		(net "M_F_CPU0_SB_DQ<1>")
	)
	(segment
		(start 424.836082 -210.916774)
		(end 425.940982 -210.916774)
		(width 0.20066)
		(layer "F.Cu")
		(net "M_F_CPU0_SB_DQ<19>")
	)
	(segment
		(start 431.898552 -210.664806)
		(end 432.15052 -210.916774)
		(width 0.20066)
		(layer "F.Cu")
		(net "M_F_CPU0_SB_DQ<19>")
	)
	(segment
		(start 386.364734 -224.111566)
		(end 386.364734 -223.575626)
		(width 0.20066)
		(layer "F.Cu")
		(net "M_F_CPU0_SB_DQ<19>")
	)
	(segment
		(start 428.367952 -211.348828)
		(end 428.375064 -211.341716)
		(width 0.1016)
		(layer "F.Cu")
		(net "M_F_CPU0_SB_DQ<19>")
	)
	(segment
		(start 428.363126 -211.348828)
		(end 428.367952 -211.348828)
		(width 0.101854)
		(layer "F.Cu")
		(net "M_F_CPU0_SB_DQ<19>")
	)
	(segment
		(start 427.639226 -210.916774)
		(end 428.07128 -211.348828)
		(width 0.20066)
		(layer "F.Cu")
		(net "M_F_CPU0_SB_DQ<19>")
	)
	(segment
		(start 425.940982 -210.916774)
		(end 427.639226 -210.916774)
		(width 0.20066)
		(layer "F.Cu")
		(net "M_F_CPU0_SB_DQ<19>")
	)
	(segment
		(start 430.395126 -211.353908)
		(end 431.076354 -211.353908)
		(width 0.20066)
		(layer "F.Cu")
		(net "M_F_CPU0_SB_DQ<19>")
	)
	(segment
		(start 428.375064 -211.341716)
		(end 430.382934 -211.341716)
		(width 0.1016)
		(layer "F.Cu")
		(net "M_F_CPU0_SB_DQ<19>")
	)
	(segment
		(start 431.280316 -210.898994)
		(end 431.514504 -210.664806)
		(width 0.20066)
		(layer "F.Cu")
		(net "M_F_CPU0_SB_DQ<19>")
	)
	(segment
		(start 431.280316 -211.149946)
		(end 431.280316 -210.898994)
		(width 0.20066)
		(layer "F.Cu")
		(net "M_F_CPU0_SB_DQ<19>")
	)
	(segment
		(start 430.382934 -211.341716)
		(end 430.395126 -211.353908)
		(width 0.1016)
		(layer "F.Cu")
		(net "M_F_CPU0_SB_DQ<19>")
	)
	(segment
		(start 431.076354 -211.353908)
		(end 431.280316 -211.149946)
		(width 0.20066)
		(layer "F.Cu")
		(net "M_F_CPU0_SB_DQ<19>")
	)
	(segment
		(start 432.15052 -210.916774)
		(end 433.484782 -210.916774)
		(width 0.20066)
		(layer "F.Cu")
		(net "M_F_CPU0_SB_DQ<19>")
	)
	(segment
		(start 431.514504 -210.664806)
		(end 431.898552 -210.664806)
		(width 0.20066)
		(layer "F.Cu")
		(net "M_F_CPU0_SB_DQ<19>")
	)
	(segment
		(start 428.07128 -211.348828)
		(end 428.363126 -211.348828)
		(width 0.20066)
		(layer "F.Cu")
		(net "M_F_CPU0_SB_DQ<19>")
	)
	(segment
		(start 422.8973 -210.188556)
		(end 422.464484 -210.621372)
		(width 0.18288)
		(layer "In2.Cu")
		(net "M_F_CPU0_SB_DQ<19>")
	)
	(segment
		(start 413.570166 -209.662522)
		(end 413.25927 -209.351626)
		(width 0.18288)
		(layer "In2.Cu")
		(net "M_F_CPU0_SB_DQ<19>")
	)
	(segment
		(start 410.018992 -208.811622)
		(end 409.82646 -209.004154)
		(width 0.18288)
		(layer "In2.Cu")
		(net "M_F_CPU0_SB_DQ<19>")
	)
	(segment
		(start 422.464484 -211.158582)
		(end 422.338754 -211.284312)
		(width 0.18288)
		(layer "In2.Cu")
		(net "M_F_CPU0_SB_DQ<19>")
	)
	(segment
		(start 409.82646 -209.004154)
		(end 409.82646 -209.41665)
		(width 0.18288)
		(layer "In2.Cu")
		(net "M_F_CPU0_SB_DQ<19>")
	)
	(segment
		(start 402.797518 -210.420966)
		(end 390.433814 -222.78467)
		(width 0.18288)
		(layer "In2.Cu")
		(net "M_F_CPU0_SB_DQ<19>")
	)
	(segment
		(start 409.63342 -209.60969)
		(end 409.300426 -209.60969)
		(width 0.18288)
		(layer "In2.Cu")
		(net "M_F_CPU0_SB_DQ<19>")
	)
	(segment
		(start 421.420798 -210.49107)
		(end 420.26205 -210.49107)
		(width 0.18288)
		(layer "In2.Cu")
		(net "M_F_CPU0_SB_DQ<19>")
	)
	(segment
		(start 422.464484 -210.621372)
		(end 422.464484 -211.158582)
		(width 0.18288)
		(layer "In2.Cu")
		(net "M_F_CPU0_SB_DQ<19>")
	)
	(segment
		(start 406.376886 -208.253076)
		(end 405.811736 -208.818226)
		(width 0.18288)
		(layer "In2.Cu")
		(net "M_F_CPU0_SB_DQ<19>")
	)
	(segment
		(start 421.738298 -211.284312)
		(end 421.556688 -211.102702)
		(width 0.18288)
		(layer "In2.Cu")
		(net "M_F_CPU0_SB_DQ<19>")
	)
	(segment
		(start 424.516296 -211.23656)
		(end 423.981372 -211.23656)
		(width 0.18288)
		(layer "In2.Cu")
		(net "M_F_CPU0_SB_DQ<19>")
	)
	(segment
		(start 389.75411 -222.78467)
		(end 389.076946 -222.78467)
		(width 0.088646)
		(layer "In2.Cu")
		(net "M_F_CPU0_SB_DQ<19>")
	)
	(segment
		(start 420.23919 -210.51393)
		(end 416.772598 -210.51393)
		(width 0.18288)
		(layer "In2.Cu")
		(net "M_F_CPU0_SB_DQ<19>")
	)
	(segment
		(start 416.772598 -210.51393)
		(end 416.015678 -209.75701)
		(width 0.18288)
		(layer "In2.Cu")
		(net "M_F_CPU0_SB_DQ<19>")
	)
	(segment
		(start 420.26205 -210.49107)
		(end 420.23919 -210.51393)
		(width 0.18288)
		(layer "In2.Cu")
		(net "M_F_CPU0_SB_DQ<19>")
	)
	(segment
		(start 407.07945 -208.253076)
		(end 406.376886 -208.253076)
		(width 0.18288)
		(layer "In2.Cu")
		(net "M_F_CPU0_SB_DQ<19>")
	)
	(segment
		(start 409.300426 -209.60969)
		(end 408.6352 -208.944464)
		(width 0.18288)
		(layer "In2.Cu")
		(net "M_F_CPU0_SB_DQ<19>")
	)
	(segment
		(start 422.338754 -211.284312)
		(end 421.738298 -211.284312)
		(width 0.18288)
		(layer "In2.Cu")
		(net "M_F_CPU0_SB_DQ<19>")
	)
	(segment
		(start 387.117336 -223.899984)
		(end 387.089396 -223.883728)
		(width 0.088646)
		(layer "In2.Cu")
		(net "M_F_CPU0_SB_DQ<19>")
	)
	(segment
		(start 409.82646 -209.41665)
		(end 409.63342 -209.60969)
		(width 0.18288)
		(layer "In2.Cu")
		(net "M_F_CPU0_SB_DQ<19>")
	)
	(segment
		(start 389.076946 -222.78467)
		(end 388.860538 -223.001078)
		(width 0.088646)
		(layer "In2.Cu")
		(net "M_F_CPU0_SB_DQ<19>")
	)
	(segment
		(start 421.556688 -210.62696)
		(end 421.420798 -210.49107)
		(width 0.18288)
		(layer "In2.Cu")
		(net "M_F_CPU0_SB_DQ<19>")
	)
	(segment
		(start 423.744898 -211.000086)
		(end 423.744898 -210.328256)
		(width 0.18288)
		(layer "In2.Cu")
		(net "M_F_CPU0_SB_DQ<19>")
	)
	(segment
		(start 424.836082 -210.916774)
		(end 424.516296 -211.23656)
		(width 0.18288)
		(layer "In2.Cu")
		(net "M_F_CPU0_SB_DQ<19>")
	)
	(segment
		(start 403.60854 -210.420966)
		(end 402.797518 -210.420966)
		(width 0.18288)
		(layer "In2.Cu")
		(net "M_F_CPU0_SB_DQ<19>")
	)
	(segment
		(start 415.122106 -209.662522)
		(end 413.570166 -209.662522)
		(width 0.18288)
		(layer "In2.Cu")
		(net "M_F_CPU0_SB_DQ<19>")
	)
	(segment
		(start 415.216594 -209.75701)
		(end 415.122106 -209.662522)
		(width 0.18288)
		(layer "In2.Cu")
		(net "M_F_CPU0_SB_DQ<19>")
	)
	(segment
		(start 405.21128 -208.818226)
		(end 403.60854 -210.420966)
		(width 0.18288)
		(layer "In2.Cu")
		(net "M_F_CPU0_SB_DQ<19>")
	)
	(segment
		(start 411.639258 -208.811622)
		(end 410.018992 -208.811622)
		(width 0.18288)
		(layer "In2.Cu")
		(net "M_F_CPU0_SB_DQ<19>")
	)
	(segment
		(start 387.089396 -223.883728)
		(end 386.364734 -223.575626)
		(width 0.088646)
		(layer "In2.Cu")
		(net "M_F_CPU0_SB_DQ<19>")
	)
	(segment
		(start 412.179262 -209.351626)
		(end 411.639258 -208.811622)
		(width 0.18288)
		(layer "In2.Cu")
		(net "M_F_CPU0_SB_DQ<19>")
	)
	(segment
		(start 388.618984 -223.553528)
		(end 388.618984 -223.575626)
		(width 0.088646)
		(layer "In2.Cu")
		(net "M_F_CPU0_SB_DQ<19>")
	)
	(segment
		(start 405.811736 -208.818226)
		(end 405.21128 -208.818226)
		(width 0.18288)
		(layer "In2.Cu")
		(net "M_F_CPU0_SB_DQ<19>")
	)
	(segment
		(start 388.440422 -223.894904)
		(end 388.431532 -223.899984)
		(width 0.088646)
		(layer "In2.Cu")
		(net "M_F_CPU0_SB_DQ<19>")
	)
	(segment
		(start 423.981372 -211.23656)
		(end 423.744898 -211.000086)
		(width 0.18288)
		(layer "In2.Cu")
		(net "M_F_CPU0_SB_DQ<19>")
	)
	(segment
		(start 408.6352 -208.944464)
		(end 407.770838 -208.944464)
		(width 0.18288)
		(layer "In2.Cu")
		(net "M_F_CPU0_SB_DQ<19>")
	)
	(segment
		(start 421.556688 -211.102702)
		(end 421.556688 -210.62696)
		(width 0.18288)
		(layer "In2.Cu")
		(net "M_F_CPU0_SB_DQ<19>")
	)
	(segment
		(start 413.25927 -209.351626)
		(end 412.179262 -209.351626)
		(width 0.18288)
		(layer "In2.Cu")
		(net "M_F_CPU0_SB_DQ<19>")
	)
	(segment
		(start 407.770838 -208.944464)
		(end 407.07945 -208.253076)
		(width 0.18288)
		(layer "In2.Cu")
		(net "M_F_CPU0_SB_DQ<19>")
	)
	(segment
		(start 423.744898 -210.328256)
		(end 423.605198 -210.188556)
		(width 0.18288)
		(layer "In2.Cu")
		(net "M_F_CPU0_SB_DQ<19>")
	)
	(segment
		(start 390.433814 -222.78467)
		(end 389.75411 -222.78467)
		(width 0.18288)
		(layer "In2.Cu")
		(net "M_F_CPU0_SB_DQ<19>")
	)
	(segment
		(start 423.605198 -210.188556)
		(end 422.8973 -210.188556)
		(width 0.18288)
		(layer "In2.Cu")
		(net "M_F_CPU0_SB_DQ<19>")
	)
	(segment
		(start 416.015678 -209.75701)
		(end 415.216594 -209.75701)
		(width 0.18288)
		(layer "In2.Cu")
		(net "M_F_CPU0_SB_DQ<19>")
	)
	(arc
		(start 387.491732 -223.899984)
		(mid 387.304534 -223.950161)
		(end 387.117336 -223.899984)
		(width 0.088646)
		(layer "In2.Cu")
		(net "M_F_CPU0_SB_DQ<19>")
	)
	(arc
		(start 388.431532 -223.899984)
		(mid 388.244334 -223.950127)
		(end 388.057136 -223.899984)
		(width 0.088646)
		(layer "In2.Cu")
		(net "M_F_CPU0_SB_DQ<19>")
	)
	(arc
		(start 388.618984 -223.575626)
		(mid 388.571305 -223.758526)
		(end 388.440422 -223.894904)
		(width 0.088646)
		(layer "In2.Cu")
		(net "M_F_CPU0_SB_DQ<19>")
	)
	(arc
		(start 388.057136 -223.899984)
		(mid 387.774434 -223.824208)
		(end 387.491732 -223.899984)
		(width 0.088646)
		(layer "In2.Cu")
		(net "M_F_CPU0_SB_DQ<19>")
	)
	(arc
		(start 388.860538 -223.001078)
		(mid 388.687659 -223.254515)
		(end 388.618984 -223.553528)
		(width 0.088646)
		(layer "In2.Cu")
		(net "M_F_CPU0_SB_DQ<19>")
	)
	(segment
		(start 430.395126 -213.05393)
		(end 431.076354 -213.05393)
		(width 0.20066)
		(layer "F.Cu")
		(net "M_F_CPU0_SB_DQ<18>")
	)
	(segment
		(start 432.15052 -212.616796)
		(end 433.484782 -212.616796)
		(width 0.20066)
		(layer "F.Cu")
		(net "M_F_CPU0_SB_DQ<18>")
	)
	(segment
		(start 425.940982 -212.616796)
		(end 427.639226 -212.616796)
		(width 0.20066)
		(layer "F.Cu")
		(net "M_F_CPU0_SB_DQ<18>")
	)
	(segment
		(start 431.076354 -213.05393)
		(end 431.280316 -212.849968)
		(width 0.20066)
		(layer "F.Cu")
		(net "M_F_CPU0_SB_DQ<18>")
	)
	(segment
		(start 385.894834 -224.925382)
		(end 385.894834 -224.389442)
		(width 0.20066)
		(layer "F.Cu")
		(net "M_F_CPU0_SB_DQ<18>")
	)
	(segment
		(start 427.639226 -212.616796)
		(end 428.07128 -213.04885)
		(width 0.20066)
		(layer "F.Cu")
		(net "M_F_CPU0_SB_DQ<18>")
	)
	(segment
		(start 431.280316 -212.849968)
		(end 431.280316 -212.599016)
		(width 0.20066)
		(layer "F.Cu")
		(net "M_F_CPU0_SB_DQ<18>")
	)
	(segment
		(start 428.363126 -213.04885)
		(end 428.367952 -213.04885)
		(width 0.101854)
		(layer "F.Cu")
		(net "M_F_CPU0_SB_DQ<18>")
	)
	(segment
		(start 431.280316 -212.599016)
		(end 431.514504 -212.364828)
		(width 0.20066)
		(layer "F.Cu")
		(net "M_F_CPU0_SB_DQ<18>")
	)
	(segment
		(start 431.898552 -212.364828)
		(end 432.15052 -212.616796)
		(width 0.20066)
		(layer "F.Cu")
		(net "M_F_CPU0_SB_DQ<18>")
	)
	(segment
		(start 428.07128 -213.04885)
		(end 428.363126 -213.04885)
		(width 0.20066)
		(layer "F.Cu")
		(net "M_F_CPU0_SB_DQ<18>")
	)
	(segment
		(start 428.367952 -213.04885)
		(end 428.375064 -213.041738)
		(width 0.1016)
		(layer "F.Cu")
		(net "M_F_CPU0_SB_DQ<18>")
	)
	(segment
		(start 431.514504 -212.364828)
		(end 431.898552 -212.364828)
		(width 0.20066)
		(layer "F.Cu")
		(net "M_F_CPU0_SB_DQ<18>")
	)
	(segment
		(start 430.382934 -213.041738)
		(end 430.395126 -213.05393)
		(width 0.1016)
		(layer "F.Cu")
		(net "M_F_CPU0_SB_DQ<18>")
	)
	(segment
		(start 424.836082 -212.616796)
		(end 425.940982 -212.616796)
		(width 0.20066)
		(layer "F.Cu")
		(net "M_F_CPU0_SB_DQ<18>")
	)
	(segment
		(start 428.375064 -213.041738)
		(end 430.382934 -213.041738)
		(width 0.1016)
		(layer "F.Cu")
		(net "M_F_CPU0_SB_DQ<18>")
	)
	(segment
		(start 405.345138 -211.365084)
		(end 404.180548 -211.365084)
		(width 0.18288)
		(layer "In2.Cu")
		(net "M_F_CPU0_SB_DQ<18>")
	)
	(segment
		(start 409.879546 -211.225384)
		(end 408.329892 -211.225384)
		(width 0.18288)
		(layer "In2.Cu")
		(net "M_F_CPU0_SB_DQ<18>")
	)
	(segment
		(start 412.65983 -211.412328)
		(end 412.388812 -211.14131)
		(width 0.18288)
		(layer "In2.Cu")
		(net "M_F_CPU0_SB_DQ<18>")
	)
	(segment
		(start 388.674864 -224.629726)
		(end 388.275322 -224.629726)
		(width 0.088646)
		(layer "In2.Cu")
		(net "M_F_CPU0_SB_DQ<18>")
	)
	(segment
		(start 407.797508 -211.484464)
		(end 407.059638 -210.746594)
		(width 0.18288)
		(layer "In2.Cu")
		(net "M_F_CPU0_SB_DQ<18>")
	)
	(segment
		(start 424.088306 -212.356446)
		(end 424.088306 -213.377272)
		(width 0.18288)
		(layer "In2.Cu")
		(net "M_F_CPU0_SB_DQ<18>")
	)
	(segment
		(start 424.432984 -212.213698)
		(end 424.231054 -212.213698)
		(width 0.18288)
		(layer "In2.Cu")
		(net "M_F_CPU0_SB_DQ<18>")
	)
	(segment
		(start 421.19423 -212.194648)
		(end 419.291516 -212.194648)
		(width 0.18288)
		(layer "In2.Cu")
		(net "M_F_CPU0_SB_DQ<18>")
	)
	(segment
		(start 389.75411 -223.802448)
		(end 389.502142 -223.802448)
		(width 0.088646)
		(layer "In2.Cu")
		(net "M_F_CPU0_SB_DQ<18>")
	)
	(segment
		(start 424.836082 -212.616796)
		(end 424.432984 -212.213698)
		(width 0.18288)
		(layer "In2.Cu")
		(net "M_F_CPU0_SB_DQ<18>")
	)
	(segment
		(start 424.231054 -212.213698)
		(end 424.088306 -212.356446)
		(width 0.18288)
		(layer "In2.Cu")
		(net "M_F_CPU0_SB_DQ<18>")
	)
	(segment
		(start 419.291516 -212.194648)
		(end 419.027356 -211.930488)
		(width 0.18288)
		(layer "In2.Cu")
		(net "M_F_CPU0_SB_DQ<18>")
	)
	(segment
		(start 411.703266 -211.332064)
		(end 409.986226 -211.332064)
		(width 0.18288)
		(layer "In2.Cu")
		(net "M_F_CPU0_SB_DQ<18>")
	)
	(segment
		(start 417.012374 -212.247226)
		(end 416.177476 -211.412328)
		(width 0.18288)
		(layer "In2.Cu")
		(net "M_F_CPU0_SB_DQ<18>")
	)
	(segment
		(start 417.442904 -212.247226)
		(end 417.012374 -212.247226)
		(width 0.18288)
		(layer "In2.Cu")
		(net "M_F_CPU0_SB_DQ<18>")
	)
	(segment
		(start 408.070812 -211.484464)
		(end 407.797508 -211.484464)
		(width 0.18288)
		(layer "In2.Cu")
		(net "M_F_CPU0_SB_DQ<18>")
	)
	(segment
		(start 423.5323 -213.585298)
		(end 423.381424 -213.434422)
		(width 0.18288)
		(layer "In2.Cu")
		(net "M_F_CPU0_SB_DQ<18>")
	)
	(segment
		(start 399.475706 -215.205564)
		(end 390.878822 -223.802448)
		(width 0.18288)
		(layer "In2.Cu")
		(net "M_F_CPU0_SB_DQ<18>")
	)
	(segment
		(start 422.83126 -212.0392)
		(end 422.679368 -212.191092)
		(width 0.18288)
		(layer "In2.Cu")
		(net "M_F_CPU0_SB_DQ<18>")
	)
	(segment
		(start 421.35425 -212.69452)
		(end 421.35425 -212.354668)
		(width 0.18288)
		(layer "In2.Cu")
		(net "M_F_CPU0_SB_DQ<18>")
	)
	(segment
		(start 389.502142 -223.802448)
		(end 388.674864 -224.629726)
		(width 0.088646)
		(layer "In2.Cu")
		(net "M_F_CPU0_SB_DQ<18>")
	)
	(segment
		(start 405.717756 -211.510372)
		(end 405.490426 -211.510372)
		(width 0.18288)
		(layer "In2.Cu")
		(net "M_F_CPU0_SB_DQ<18>")
	)
	(segment
		(start 406.481534 -210.746594)
		(end 405.717756 -211.510372)
		(width 0.18288)
		(layer "In2.Cu")
		(net "M_F_CPU0_SB_DQ<18>")
	)
	(segment
		(start 423.381424 -212.230462)
		(end 423.190162 -212.0392)
		(width 0.18288)
		(layer "In2.Cu")
		(net "M_F_CPU0_SB_DQ<18>")
	)
	(segment
		(start 412.388812 -211.14131)
		(end 411.89402 -211.14131)
		(width 0.18288)
		(layer "In2.Cu")
		(net "M_F_CPU0_SB_DQ<18>")
	)
	(segment
		(start 424.088306 -213.377272)
		(end 423.88028 -213.585298)
		(width 0.18288)
		(layer "In2.Cu")
		(net "M_F_CPU0_SB_DQ<18>")
	)
	(segment
		(start 386.647436 -224.7138)
		(end 386.619496 -224.697544)
		(width 0.088646)
		(layer "In2.Cu")
		(net "M_F_CPU0_SB_DQ<18>")
	)
	(segment
		(start 423.88028 -213.585298)
		(end 423.5323 -213.585298)
		(width 0.18288)
		(layer "In2.Cu")
		(net "M_F_CPU0_SB_DQ<18>")
	)
	(segment
		(start 409.986226 -211.332064)
		(end 409.879546 -211.225384)
		(width 0.18288)
		(layer "In2.Cu")
		(net "M_F_CPU0_SB_DQ<18>")
	)
	(segment
		(start 422.072816 -212.69452)
		(end 421.912796 -212.85454)
		(width 0.18288)
		(layer "In2.Cu")
		(net "M_F_CPU0_SB_DQ<18>")
	)
	(segment
		(start 422.232836 -212.191092)
		(end 422.072816 -212.351112)
		(width 0.18288)
		(layer "In2.Cu")
		(net "M_F_CPU0_SB_DQ<18>")
	)
	(segment
		(start 421.51427 -212.85454)
		(end 421.35425 -212.69452)
		(width 0.18288)
		(layer "In2.Cu")
		(net "M_F_CPU0_SB_DQ<18>")
	)
	(segment
		(start 422.072816 -212.351112)
		(end 422.072816 -212.69452)
		(width 0.18288)
		(layer "In2.Cu")
		(net "M_F_CPU0_SB_DQ<18>")
	)
	(segment
		(start 416.177476 -211.412328)
		(end 412.65983 -211.412328)
		(width 0.18288)
		(layer "In2.Cu")
		(net "M_F_CPU0_SB_DQ<18>")
	)
	(segment
		(start 405.490426 -211.510372)
		(end 405.345138 -211.365084)
		(width 0.18288)
		(layer "In2.Cu")
		(net "M_F_CPU0_SB_DQ<18>")
	)
	(segment
		(start 386.619496 -224.697544)
		(end 385.894834 -224.389442)
		(width 0.088646)
		(layer "In2.Cu")
		(net "M_F_CPU0_SB_DQ<18>")
	)
	(segment
		(start 423.190162 -212.0392)
		(end 422.83126 -212.0392)
		(width 0.18288)
		(layer "In2.Cu")
		(net "M_F_CPU0_SB_DQ<18>")
	)
	(segment
		(start 421.35425 -212.354668)
		(end 421.19423 -212.194648)
		(width 0.18288)
		(layer "In2.Cu")
		(net "M_F_CPU0_SB_DQ<18>")
	)
	(segment
		(start 422.679368 -212.191092)
		(end 422.232836 -212.191092)
		(width 0.18288)
		(layer "In2.Cu")
		(net "M_F_CPU0_SB_DQ<18>")
	)
	(segment
		(start 423.381424 -213.434422)
		(end 423.381424 -212.230462)
		(width 0.18288)
		(layer "In2.Cu")
		(net "M_F_CPU0_SB_DQ<18>")
	)
	(segment
		(start 400.340068 -215.205564)
		(end 399.475706 -215.205564)
		(width 0.18288)
		(layer "In2.Cu")
		(net "M_F_CPU0_SB_DQ<18>")
	)
	(segment
		(start 421.912796 -212.85454)
		(end 421.51427 -212.85454)
		(width 0.18288)
		(layer "In2.Cu")
		(net "M_F_CPU0_SB_DQ<18>")
	)
	(segment
		(start 417.759642 -211.930488)
		(end 417.442904 -212.247226)
		(width 0.18288)
		(layer "In2.Cu")
		(net "M_F_CPU0_SB_DQ<18>")
	)
	(segment
		(start 390.878822 -223.802448)
		(end 389.75411 -223.802448)
		(width 0.18288)
		(layer "In2.Cu")
		(net "M_F_CPU0_SB_DQ<18>")
	)
	(segment
		(start 408.329892 -211.225384)
		(end 408.070812 -211.484464)
		(width 0.18288)
		(layer "In2.Cu")
		(net "M_F_CPU0_SB_DQ<18>")
	)
	(segment
		(start 419.027356 -211.930488)
		(end 417.759642 -211.930488)
		(width 0.18288)
		(layer "In2.Cu")
		(net "M_F_CPU0_SB_DQ<18>")
	)
	(segment
		(start 404.180548 -211.365084)
		(end 400.340068 -215.205564)
		(width 0.18288)
		(layer "In2.Cu")
		(net "M_F_CPU0_SB_DQ<18>")
	)
	(segment
		(start 407.059638 -210.746594)
		(end 406.481534 -210.746594)
		(width 0.18288)
		(layer "In2.Cu")
		(net "M_F_CPU0_SB_DQ<18>")
	)
	(segment
		(start 411.89402 -211.14131)
		(end 411.703266 -211.332064)
		(width 0.18288)
		(layer "In2.Cu")
		(net "M_F_CPU0_SB_DQ<18>")
	)
	(arc
		(start 388.275322 -224.629726)
		(mid 388.112943 -224.651113)
		(end 387.961632 -224.7138)
		(width 0.088646)
		(layer "In2.Cu")
		(net "M_F_CPU0_SB_DQ<18>")
	)
	(arc
		(start 387.021832 -224.7138)
		(mid 386.834634 -224.763977)
		(end 386.647436 -224.7138)
		(width 0.088646)
		(layer "In2.Cu")
		(net "M_F_CPU0_SB_DQ<18>")
	)
	(arc
		(start 387.587236 -224.7138)
		(mid 387.304534 -224.638024)
		(end 387.021832 -224.7138)
		(width 0.088646)
		(layer "In2.Cu")
		(net "M_F_CPU0_SB_DQ<18>")
	)
	(arc
		(start 387.961632 -224.7138)
		(mid 387.774434 -224.763943)
		(end 387.587236 -224.7138)
		(width 0.088646)
		(layer "In2.Cu")
		(net "M_F_CPU0_SB_DQ<18>")
	)
	(segment
		(start 429.38446 -211.766912)
		(end 427.792896 -211.766912)
		(width 0.20066)
		(layer "F.Cu")
		(net "M_F_CPU0_SB_DQ<17>")
	)
	(segment
		(start 424.756326 -211.341716)
		(end 424.73626 -211.341716)
		(width 0.101854)
		(layer "F.Cu")
		(net "M_F_CPU0_SB_DQ<17>")
	)
	(segment
		(start 426.945044 -211.341716)
		(end 424.756326 -211.341716)
		(width 0.1016)
		(layer "F.Cu")
		(net "M_F_CPU0_SB_DQ<17>")
	)
	(segment
		(start 427.792896 -211.766912)
		(end 427.36135 -211.335366)
		(width 0.20066)
		(layer "F.Cu")
		(net "M_F_CPU0_SB_DQ<17>")
	)
	(segment
		(start 429.384714 -211.766658)
		(end 429.38446 -211.766912)
		(width 0.20066)
		(layer "F.Cu")
		(net "M_F_CPU0_SB_DQ<17>")
	)
	(segment
		(start 424.273472 -211.827364)
		(end 424.085512 -212.015324)
		(width 0.20066)
		(layer "F.Cu")
		(net "M_F_CPU0_SB_DQ<17>")
	)
	(segment
		(start 384.485134 -223.57588)
		(end 384.48488 -223.575626)
		(width 0.20066)
		(layer "F.Cu")
		(net "M_F_CPU0_SB_DQ<17>")
	)
	(segment
		(start 423.361612 -211.766658)
		(end 421.840914 -211.766658)
		(width 0.20066)
		(layer "F.Cu")
		(net "M_F_CPU0_SB_DQ<17>")
	)
	(segment
		(start 421.840914 -211.766658)
		(end 420.736014 -211.766658)
		(width 0.20066)
		(layer "F.Cu")
		(net "M_F_CPU0_SB_DQ<17>")
	)
	(segment
		(start 426.951394 -211.335366)
		(end 426.945044 -211.341716)
		(width 0.1016)
		(layer "F.Cu")
		(net "M_F_CPU0_SB_DQ<17>")
	)
	(segment
		(start 384.485134 -224.111566)
		(end 384.485134 -223.57588)
		(width 0.20066)
		(layer "F.Cu")
		(net "M_F_CPU0_SB_DQ<17>")
	)
	(segment
		(start 427.36135 -211.335366)
		(end 426.951394 -211.335366)
		(width 0.20066)
		(layer "F.Cu")
		(net "M_F_CPU0_SB_DQ<17>")
	)
	(segment
		(start 424.085512 -212.015324)
		(end 423.610278 -212.015324)
		(width 0.20066)
		(layer "F.Cu")
		(net "M_F_CPU0_SB_DQ<17>")
	)
	(segment
		(start 424.73626 -211.341716)
		(end 424.391582 -211.341716)
		(width 0.20066)
		(layer "F.Cu")
		(net "M_F_CPU0_SB_DQ<17>")
	)
	(segment
		(start 424.391582 -211.341716)
		(end 424.273472 -211.459826)
		(width 0.20066)
		(layer "F.Cu")
		(net "M_F_CPU0_SB_DQ<17>")
	)
	(segment
		(start 423.610278 -212.015324)
		(end 423.361612 -211.766658)
		(width 0.20066)
		(layer "F.Cu")
		(net "M_F_CPU0_SB_DQ<17>")
	)
	(segment
		(start 424.273472 -211.459826)
		(end 424.273472 -211.827364)
		(width 0.20066)
		(layer "F.Cu")
		(net "M_F_CPU0_SB_DQ<17>")
	)
	(segment
		(start 400.681698 -213.261702)
		(end 400.681698 -213.534498)
		(width 0.18288)
		(layer "In2.Cu")
		(net "M_F_CPU0_SB_DQ<17>")
	)
	(segment
		(start 400.33956 -214.188548)
		(end 400.183604 -214.032592)
		(width 0.18288)
		(layer "In2.Cu")
		(net "M_F_CPU0_SB_DQ<17>")
	)
	(segment
		(start 389.091678 -223.294448)
		(end 388.809484 -223.585532)
		(width 0.088646)
		(layer "In2.Cu")
		(net "M_F_CPU0_SB_DQ<17>")
	)
	(segment
		(start 400.681698 -213.534498)
		(end 400.837654 -213.690454)
		(width 0.18288)
		(layer "In2.Cu")
		(net "M_F_CPU0_SB_DQ<17>")
	)
	(segment
		(start 404.54326 -210.490562)
		(end 404.270464 -210.490562)
		(width 0.18288)
		(layer "In2.Cu")
		(net "M_F_CPU0_SB_DQ<17>")
	)
	(segment
		(start 401.677886 -212.53831)
		(end 401.833842 -212.694266)
		(width 0.18288)
		(layer "In2.Cu")
		(net "M_F_CPU0_SB_DQ<17>")
	)
	(segment
		(start 384.797554 -223.575626)
		(end 384.48488 -223.575626)
		(width 0.088646)
		(layer "In2.Cu")
		(net "M_F_CPU0_SB_DQ<17>")
	)
	(segment
		(start 402.331936 -212.196172)
		(end 402.17598 -212.040216)
		(width 0.18288)
		(layer "In2.Cu")
		(net "M_F_CPU0_SB_DQ<17>")
	)
	(segment
		(start 413.068008 -209.885026)
		(end 412.646114 -209.885026)
		(width 0.18288)
		(layer "In2.Cu")
		(net "M_F_CPU0_SB_DQ<17>")
	)
	(segment
		(start 405.041354 -209.719672)
		(end 405.041354 -209.992468)
		(width 0.18288)
		(layer "In2.Cu")
		(net "M_F_CPU0_SB_DQ<17>")
	)
	(segment
		(start 410.39161 -210.062318)
		(end 409.919932 -210.533996)
		(width 0.18288)
		(layer "In2.Cu")
		(net "M_F_CPU0_SB_DQ<17>")
	)
	(segment
		(start 408.432254 -209.662522)
		(end 406.02916 -209.662522)
		(width 0.18288)
		(layer "In2.Cu")
		(net "M_F_CPU0_SB_DQ<17>")
	)
	(segment
		(start 411.76829 -210.547204)
		(end 411.283404 -210.062318)
		(width 0.18288)
		(layer "In2.Cu")
		(net "M_F_CPU0_SB_DQ<17>")
	)
	(segment
		(start 412.486094 -210.354164)
		(end 412.293054 -210.547204)
		(width 0.18288)
		(layer "In2.Cu")
		(net "M_F_CPU0_SB_DQ<17>")
	)
	(segment
		(start 405.041354 -209.992468)
		(end 405.33701 -210.288124)
		(width 0.18288)
		(layer "In2.Cu")
		(net "M_F_CPU0_SB_DQ<17>")
	)
	(segment
		(start 401.179792 -213.036404)
		(end 400.906996 -213.036404)
		(width 0.18288)
		(layer "In2.Cu")
		(net "M_F_CPU0_SB_DQ<17>")
	)
	(segment
		(start 402.674074 -211.269326)
		(end 402.674074 -211.542122)
		(width 0.18288)
		(layer "In2.Cu")
		(net "M_F_CPU0_SB_DQ<17>")
	)
	(segment
		(start 402.674074 -211.542122)
		(end 402.83003 -211.698078)
		(width 0.18288)
		(layer "In2.Cu")
		(net "M_F_CPU0_SB_DQ<17>")
	)
	(segment
		(start 414.748726 -210.864958)
		(end 413.774382 -210.864958)
		(width 0.18288)
		(layer "In2.Cu")
		(net "M_F_CPU0_SB_DQ<17>")
	)
	(segment
		(start 399.910808 -214.032592)
		(end 390.648952 -223.294448)
		(width 0.18288)
		(layer "In2.Cu")
		(net "M_F_CPU0_SB_DQ<17>")
	)
	(segment
		(start 405.42718 -209.333846)
		(end 405.041354 -209.719672)
		(width 0.18288)
		(layer "In2.Cu")
		(net "M_F_CPU0_SB_DQ<17>")
	)
	(segment
		(start 411.283404 -210.062318)
		(end 410.39161 -210.062318)
		(width 0.18288)
		(layer "In2.Cu")
		(net "M_F_CPU0_SB_DQ<17>")
	)
	(segment
		(start 409.919932 -210.533996)
		(end 408.759914 -210.533996)
		(width 0.18288)
		(layer "In2.Cu")
		(net "M_F_CPU0_SB_DQ<17>")
	)
	(segment
		(start 389.75411 -223.294448)
		(end 389.091678 -223.294448)
		(width 0.088646)
		(layer "In2.Cu")
		(net "M_F_CPU0_SB_DQ<17>")
	)
	(segment
		(start 412.293054 -210.547204)
		(end 411.76829 -210.547204)
		(width 0.18288)
		(layer "In2.Cu")
		(net "M_F_CPU0_SB_DQ<17>")
	)
	(segment
		(start 404.270464 -210.490562)
		(end 403.821392 -210.939634)
		(width 0.18288)
		(layer "In2.Cu")
		(net "M_F_CPU0_SB_DQ<17>")
	)
	(segment
		(start 413.261048 -210.351624)
		(end 413.261048 -210.078066)
		(width 0.18288)
		(layer "In2.Cu")
		(net "M_F_CPU0_SB_DQ<17>")
	)
	(segment
		(start 415.817304 -210.292696)
		(end 415.320988 -210.292696)
		(width 0.18288)
		(layer "In2.Cu")
		(net "M_F_CPU0_SB_DQ<17>")
	)
	(segment
		(start 406.02916 -209.662522)
		(end 405.700484 -209.333846)
		(width 0.18288)
		(layer "In2.Cu")
		(net "M_F_CPU0_SB_DQ<17>")
	)
	(segment
		(start 400.906996 -213.036404)
		(end 400.681698 -213.261702)
		(width 0.18288)
		(layer "In2.Cu")
		(net "M_F_CPU0_SB_DQ<17>")
	)
	(segment
		(start 390.648952 -223.294448)
		(end 389.75411 -223.294448)
		(width 0.18288)
		(layer "In2.Cu")
		(net "M_F_CPU0_SB_DQ<17>")
	)
	(segment
		(start 400.612356 -214.188548)
		(end 400.33956 -214.188548)
		(width 0.18288)
		(layer "In2.Cu")
		(net "M_F_CPU0_SB_DQ<17>")
	)
	(segment
		(start 405.111712 -210.786218)
		(end 404.838916 -210.786218)
		(width 0.18288)
		(layer "In2.Cu")
		(net "M_F_CPU0_SB_DQ<17>")
	)
	(segment
		(start 401.335748 -213.19236)
		(end 401.179792 -213.036404)
		(width 0.18288)
		(layer "In2.Cu")
		(net "M_F_CPU0_SB_DQ<17>")
	)
	(segment
		(start 400.837654 -213.690454)
		(end 400.837654 -213.96325)
		(width 0.18288)
		(layer "In2.Cu")
		(net "M_F_CPU0_SB_DQ<17>")
	)
	(segment
		(start 405.33701 -210.56092)
		(end 405.111712 -210.786218)
		(width 0.18288)
		(layer "In2.Cu")
		(net "M_F_CPU0_SB_DQ<17>")
	)
	(segment
		(start 401.833842 -212.967062)
		(end 401.608544 -213.19236)
		(width 0.18288)
		(layer "In2.Cu")
		(net "M_F_CPU0_SB_DQ<17>")
	)
	(segment
		(start 401.677886 -212.265514)
		(end 401.677886 -212.53831)
		(width 0.18288)
		(layer "In2.Cu")
		(net "M_F_CPU0_SB_DQ<17>")
	)
	(segment
		(start 408.566874 -209.797142)
		(end 408.432254 -209.662522)
		(width 0.18288)
		(layer "In2.Cu")
		(net "M_F_CPU0_SB_DQ<17>")
	)
	(segment
		(start 420.736014 -211.766658)
		(end 420.30142 -211.332064)
		(width 0.18288)
		(layer "In2.Cu")
		(net "M_F_CPU0_SB_DQ<17>")
	)
	(segment
		(start 405.700484 -209.333846)
		(end 405.42718 -209.333846)
		(width 0.18288)
		(layer "In2.Cu")
		(net "M_F_CPU0_SB_DQ<17>")
	)
	(segment
		(start 405.33701 -210.288124)
		(end 405.33701 -210.56092)
		(width 0.18288)
		(layer "In2.Cu")
		(net "M_F_CPU0_SB_DQ<17>")
	)
	(segment
		(start 420.30142 -211.332064)
		(end 416.856672 -211.332064)
		(width 0.18288)
		(layer "In2.Cu")
		(net "M_F_CPU0_SB_DQ<17>")
	)
	(segment
		(start 400.837654 -213.96325)
		(end 400.612356 -214.188548)
		(width 0.18288)
		(layer "In2.Cu")
		(net "M_F_CPU0_SB_DQ<17>")
	)
	(segment
		(start 413.774382 -210.864958)
		(end 413.261048 -210.351624)
		(width 0.18288)
		(layer "In2.Cu")
		(net "M_F_CPU0_SB_DQ<17>")
	)
	(segment
		(start 408.759914 -210.533996)
		(end 408.566874 -210.340956)
		(width 0.18288)
		(layer "In2.Cu")
		(net "M_F_CPU0_SB_DQ<17>")
	)
	(segment
		(start 402.83003 -211.698078)
		(end 402.83003 -211.970874)
		(width 0.18288)
		(layer "In2.Cu")
		(net "M_F_CPU0_SB_DQ<17>")
	)
	(segment
		(start 400.183604 -214.032592)
		(end 399.910808 -214.032592)
		(width 0.18288)
		(layer "In2.Cu")
		(net "M_F_CPU0_SB_DQ<17>")
	)
	(segment
		(start 404.838916 -210.786218)
		(end 404.54326 -210.490562)
		(width 0.18288)
		(layer "In2.Cu")
		(net "M_F_CPU0_SB_DQ<17>")
	)
	(segment
		(start 403.003766 -210.939634)
		(end 402.674074 -211.269326)
		(width 0.18288)
		(layer "In2.Cu")
		(net "M_F_CPU0_SB_DQ<17>")
	)
	(segment
		(start 402.17598 -212.040216)
		(end 401.903184 -212.040216)
		(width 0.18288)
		(layer "In2.Cu")
		(net "M_F_CPU0_SB_DQ<17>")
	)
	(segment
		(start 402.604732 -212.196172)
		(end 402.331936 -212.196172)
		(width 0.18288)
		(layer "In2.Cu")
		(net "M_F_CPU0_SB_DQ<17>")
	)
	(segment
		(start 384.86334 -223.641412)
		(end 384.797554 -223.575626)
		(width 0.088646)
		(layer "In2.Cu")
		(net "M_F_CPU0_SB_DQ<17>")
	)
	(segment
		(start 401.903184 -212.040216)
		(end 401.677886 -212.265514)
		(width 0.18288)
		(layer "In2.Cu")
		(net "M_F_CPU0_SB_DQ<17>")
	)
	(segment
		(start 413.261048 -210.078066)
		(end 413.068008 -209.885026)
		(width 0.18288)
		(layer "In2.Cu")
		(net "M_F_CPU0_SB_DQ<17>")
	)
	(segment
		(start 401.608544 -213.19236)
		(end 401.335748 -213.19236)
		(width 0.18288)
		(layer "In2.Cu")
		(net "M_F_CPU0_SB_DQ<17>")
	)
	(segment
		(start 415.320988 -210.292696)
		(end 414.748726 -210.864958)
		(width 0.18288)
		(layer "In2.Cu")
		(net "M_F_CPU0_SB_DQ<17>")
	)
	(segment
		(start 416.856672 -211.332064)
		(end 415.817304 -210.292696)
		(width 0.18288)
		(layer "In2.Cu")
		(net "M_F_CPU0_SB_DQ<17>")
	)
	(segment
		(start 412.486094 -210.045046)
		(end 412.486094 -210.354164)
		(width 0.18288)
		(layer "In2.Cu")
		(net "M_F_CPU0_SB_DQ<17>")
	)
	(segment
		(start 402.83003 -211.970874)
		(end 402.604732 -212.196172)
		(width 0.18288)
		(layer "In2.Cu")
		(net "M_F_CPU0_SB_DQ<17>")
	)
	(segment
		(start 408.566874 -210.340956)
		(end 408.566874 -209.797142)
		(width 0.18288)
		(layer "In2.Cu")
		(net "M_F_CPU0_SB_DQ<17>")
	)
	(segment
		(start 401.833842 -212.694266)
		(end 401.833842 -212.967062)
		(width 0.18288)
		(layer "In2.Cu")
		(net "M_F_CPU0_SB_DQ<17>")
	)
	(segment
		(start 403.821392 -210.939634)
		(end 403.003766 -210.939634)
		(width 0.18288)
		(layer "In2.Cu")
		(net "M_F_CPU0_SB_DQ<17>")
	)
	(segment
		(start 412.646114 -209.885026)
		(end 412.486094 -210.045046)
		(width 0.18288)
		(layer "In2.Cu")
		(net "M_F_CPU0_SB_DQ<17>")
	)
	(arc
		(start 387.021832 -224.065084)
		(mid 386.834634 -224.014907)
		(end 386.647436 -224.065084)
		(width 0.088646)
		(layer "In2.Cu")
		(net "M_F_CPU0_SB_DQ<17>")
	)
	(arc
		(start 386.647436 -224.065084)
		(mid 386.364734 -224.14086)
		(end 386.082032 -224.065084)
		(width 0.088646)
		(layer "In2.Cu")
		(net "M_F_CPU0_SB_DQ<17>")
	)
	(arc
		(start 386.082032 -224.065084)
		(mid 385.894834 -224.014941)
		(end 385.707636 -224.065084)
		(width 0.088646)
		(layer "In2.Cu")
		(net "M_F_CPU0_SB_DQ<17>")
	)
	(arc
		(start 387.587236 -224.065084)
		(mid 387.304534 -224.140826)
		(end 387.021832 -224.065084)
		(width 0.088646)
		(layer "In2.Cu")
		(net "M_F_CPU0_SB_DQ<17>")
	)
	(arc
		(start 388.809484 -223.585532)
		(mid 388.522609 -224.067617)
		(end 387.961632 -224.065084)
		(width 0.088646)
		(layer "In2.Cu")
		(net "M_F_CPU0_SB_DQ<17>")
	)
	(arc
		(start 385.707636 -224.065084)
		(mid 385.171166 -224.080961)
		(end 384.86334 -223.641412)
		(width 0.088646)
		(layer "In2.Cu")
		(net "M_F_CPU0_SB_DQ<17>")
	)
	(arc
		(start 387.961632 -224.065084)
		(mid 387.774434 -224.014941)
		(end 387.587236 -224.065084)
		(width 0.088646)
		(layer "In2.Cu")
		(net "M_F_CPU0_SB_DQ<17>")
	)
	(segment
		(start 427.36135 -213.035388)
		(end 426.951394 -213.035388)
		(width 0.20066)
		(layer "F.Cu")
		(net "M_F_CPU0_SB_DQ<16>")
	)
	(segment
		(start 384.95478 -224.389696)
		(end 384.955034 -224.389442)
		(width 0.20066)
		(layer "F.Cu")
		(net "M_F_CPU0_SB_DQ<16>")
	)
	(segment
		(start 427.792896 -213.466934)
		(end 427.36135 -213.035388)
		(width 0.20066)
		(layer "F.Cu")
		(net "M_F_CPU0_SB_DQ<16>")
	)
	(segment
		(start 423.610278 -213.715346)
		(end 423.361612 -213.46668)
		(width 0.20066)
		(layer "F.Cu")
		(net "M_F_CPU0_SB_DQ<16>")
	)
	(segment
		(start 424.273472 -213.527386)
		(end 424.085512 -213.715346)
		(width 0.20066)
		(layer "F.Cu")
		(net "M_F_CPU0_SB_DQ<16>")
	)
	(segment
		(start 423.361612 -213.46668)
		(end 421.840914 -213.46668)
		(width 0.20066)
		(layer "F.Cu")
		(net "M_F_CPU0_SB_DQ<16>")
	)
	(segment
		(start 424.085512 -213.715346)
		(end 423.610278 -213.715346)
		(width 0.20066)
		(layer "F.Cu")
		(net "M_F_CPU0_SB_DQ<16>")
	)
	(segment
		(start 429.384714 -213.46668)
		(end 429.38446 -213.466934)
		(width 0.20066)
		(layer "F.Cu")
		(net "M_F_CPU0_SB_DQ<16>")
	)
	(segment
		(start 421.840914 -213.46668)
		(end 420.736014 -213.46668)
		(width 0.20066)
		(layer "F.Cu")
		(net "M_F_CPU0_SB_DQ<16>")
	)
	(segment
		(start 429.38446 -213.466934)
		(end 427.792896 -213.466934)
		(width 0.20066)
		(layer "F.Cu")
		(net "M_F_CPU0_SB_DQ<16>")
	)
	(segment
		(start 426.951394 -213.035388)
		(end 426.945044 -213.041738)
		(width 0.1016)
		(layer "F.Cu")
		(net "M_F_CPU0_SB_DQ<16>")
	)
	(segment
		(start 424.78325 -213.041738)
		(end 424.73626 -213.041738)
		(width 0.101854)
		(layer "F.Cu")
		(net "M_F_CPU0_SB_DQ<16>")
	)
	(segment
		(start 384.95478 -224.925382)
		(end 384.95478 -224.389696)
		(width 0.20066)
		(layer "F.Cu")
		(net "M_F_CPU0_SB_DQ<16>")
	)
	(segment
		(start 424.273472 -213.159848)
		(end 424.273472 -213.527386)
		(width 0.20066)
		(layer "F.Cu")
		(net "M_F_CPU0_SB_DQ<16>")
	)
	(segment
		(start 424.391582 -213.041738)
		(end 424.273472 -213.159848)
		(width 0.20066)
		(layer "F.Cu")
		(net "M_F_CPU0_SB_DQ<16>")
	)
	(segment
		(start 426.945044 -213.041738)
		(end 424.78325 -213.041738)
		(width 0.1016)
		(layer "F.Cu")
		(net "M_F_CPU0_SB_DQ<16>")
	)
	(segment
		(start 424.73626 -213.041738)
		(end 424.391582 -213.041738)
		(width 0.20066)
		(layer "F.Cu")
		(net "M_F_CPU0_SB_DQ<16>")
	)
	(segment
		(start 396.617952 -219.061792)
		(end 396.345156 -219.061792)
		(width 0.18288)
		(layer "In2.Cu")
		(net "M_F_CPU0_SB_DQ<16>")
	)
	(segment
		(start 385.612132 -224.8789)
		(end 385.583938 -224.862644)
		(width 0.088646)
		(layer "In2.Cu")
		(net "M_F_CPU0_SB_DQ<16>")
	)
	(segment
		(start 393.629388 -222.050356)
		(end 393.356592 -222.050356)
		(width 0.18288)
		(layer "In2.Cu")
		(net "M_F_CPU0_SB_DQ<16>")
	)
	(segment
		(start 395.809978 -220.246448)
		(end 395.621764 -220.05798)
		(width 0.18288)
		(layer "In2.Cu")
		(net "M_F_CPU0_SB_DQ<16>")
	)
	(segment
		(start 415.332164 -211.926932)
		(end 415.073084 -212.186012)
		(width 0.18288)
		(layer "In2.Cu")
		(net "M_F_CPU0_SB_DQ<16>")
	)
	(segment
		(start 407.626566 -212.221572)
		(end 405.934926 -212.221572)
		(width 0.18288)
		(layer "In2.Cu")
		(net "M_F_CPU0_SB_DQ<16>")
	)
	(segment
		(start 389.297164 -224.312226)
		(end 388.776464 -224.832926)
		(width 0.088646)
		(layer "In2.Cu")
		(net "M_F_CPU0_SB_DQ<16>")
	)
	(segment
		(start 397.078962 -219.25026)
		(end 396.806166 -219.25026)
		(width 0.18288)
		(layer "In2.Cu")
		(net "M_F_CPU0_SB_DQ<16>")
	)
	(segment
		(start 408.53614 -211.757514)
		(end 408.278076 -212.015578)
		(width 0.18288)
		(layer "In2.Cu")
		(net "M_F_CPU0_SB_DQ<16>")
	)
	(segment
		(start 407.83256 -212.015578)
		(end 407.626566 -212.221572)
		(width 0.18288)
		(layer "In2.Cu")
		(net "M_F_CPU0_SB_DQ<16>")
	)
	(segment
		(start 405.876506 -212.163152)
		(end 404.16607 -212.163152)
		(width 0.18288)
		(layer "In2.Cu")
		(net "M_F_CPU0_SB_DQ<16>")
	)
	(segment
		(start 399.071338 -217.257884)
		(end 398.798542 -217.257884)
		(width 0.18288)
		(layer "In2.Cu")
		(net "M_F_CPU0_SB_DQ<16>")
	)
	(segment
		(start 398.112234 -217.56751)
		(end 398.300448 -217.755978)
		(width 0.18288)
		(layer "In2.Cu")
		(net "M_F_CPU0_SB_DQ<16>")
	)
	(segment
		(start 398.610328 -217.069416)
		(end 398.337532 -217.069416)
		(width 0.18288)
		(layer "In2.Cu")
		(net "M_F_CPU0_SB_DQ<16>")
	)
	(segment
		(start 415.073084 -212.186012)
		(end 413.413448 -212.186012)
		(width 0.18288)
		(layer "In2.Cu")
		(net "M_F_CPU0_SB_DQ<16>")
	)
	(segment
		(start 415.82594 -211.926932)
		(end 415.332164 -211.926932)
		(width 0.18288)
		(layer "In2.Cu")
		(net "M_F_CPU0_SB_DQ<16>")
	)
	(segment
		(start 395.621764 -220.05798)
		(end 395.348968 -220.05798)
		(width 0.18288)
		(layer "In2.Cu")
		(net "M_F_CPU0_SB_DQ<16>")
	)
	(segment
		(start 394.35278 -221.054168)
		(end 394.127482 -221.279466)
		(width 0.18288)
		(layer "In2.Cu")
		(net "M_F_CPU0_SB_DQ<16>")
	)
	(segment
		(start 393.09421 -223.235012)
		(end 392.821414 -223.235012)
		(width 0.18288)
		(layer "In2.Cu")
		(net "M_F_CPU0_SB_DQ<16>")
	)
	(segment
		(start 420.736014 -213.46668)
		(end 420.150544 -212.88121)
		(width 0.18288)
		(layer "In2.Cu")
		(net "M_F_CPU0_SB_DQ<16>")
	)
	(segment
		(start 399.296636 -217.032586)
		(end 399.071338 -217.257884)
		(width 0.18288)
		(layer "In2.Cu")
		(net "M_F_CPU0_SB_DQ<16>")
	)
	(segment
		(start 396.119858 -219.559886)
		(end 396.308072 -219.748354)
		(width 0.18288)
		(layer "In2.Cu")
		(net "M_F_CPU0_SB_DQ<16>")
	)
	(segment
		(start 398.337532 -217.069416)
		(end 398.112234 -217.294714)
		(width 0.18288)
		(layer "In2.Cu")
		(net "M_F_CPU0_SB_DQ<16>")
	)
	(segment
		(start 409.008326 -211.757514)
		(end 408.53614 -211.757514)
		(width 0.18288)
		(layer "In2.Cu")
		(net "M_F_CPU0_SB_DQ<16>")
	)
	(segment
		(start 416.244532 -212.78596)
		(end 416.024822 -212.56625)
		(width 0.18288)
		(layer "In2.Cu")
		(net "M_F_CPU0_SB_DQ<16>")
	)
	(segment
		(start 416.631628 -212.78596)
		(end 416.244532 -212.78596)
		(width 0.18288)
		(layer "In2.Cu")
		(net "M_F_CPU0_SB_DQ<16>")
	)
	(segment
		(start 395.311884 -220.744542)
		(end 395.311884 -221.017338)
		(width 0.18288)
		(layer "In2.Cu")
		(net "M_F_CPU0_SB_DQ<16>")
	)
	(segment
		(start 412.541974 -211.937092)
		(end 412.253684 -212.225382)
		(width 0.18288)
		(layer "In2.Cu")
		(net "M_F_CPU0_SB_DQ<16>")
	)
	(segment
		(start 396.345156 -219.061792)
		(end 396.119858 -219.28709)
		(width 0.18288)
		(layer "In2.Cu")
		(net "M_F_CPU0_SB_DQ<16>")
	)
	(segment
		(start 397.116046 -218.290902)
		(end 397.116046 -218.563698)
		(width 0.18288)
		(layer "In2.Cu")
		(net "M_F_CPU0_SB_DQ<16>")
	)
	(segment
		(start 389.75411 -224.312226)
		(end 389.297164 -224.312226)
		(width 0.088646)
		(layer "In2.Cu")
		(net "M_F_CPU0_SB_DQ<16>")
	)
	(segment
		(start 399.606516 -216.073228)
		(end 399.33372 -216.073228)
		(width 0.18288)
		(layer "In2.Cu")
		(net "M_F_CPU0_SB_DQ<16>")
	)
	(segment
		(start 411.382972 -211.86394)
		(end 410.285184 -211.86394)
		(width 0.18288)
		(layer "In2.Cu")
		(net "M_F_CPU0_SB_DQ<16>")
	)
	(segment
		(start 399.108422 -216.298526)
		(end 399.108422 -216.571322)
		(width 0.18288)
		(layer "In2.Cu")
		(net "M_F_CPU0_SB_DQ<16>")
	)
	(segment
		(start 404.16607 -212.163152)
		(end 400.067526 -216.261696)
		(width 0.18288)
		(layer "In2.Cu")
		(net "M_F_CPU0_SB_DQ<16>")
	)
	(segment
		(start 395.12367 -220.556074)
		(end 395.311884 -220.744542)
		(width 0.18288)
		(layer "In2.Cu")
		(net "M_F_CPU0_SB_DQ<16>")
	)
	(segment
		(start 396.806166 -219.25026)
		(end 396.617952 -219.061792)
		(width 0.18288)
		(layer "In2.Cu")
		(net "M_F_CPU0_SB_DQ<16>")
	)
	(segment
		(start 393.356592 -222.050356)
		(end 393.131294 -222.275654)
		(width 0.18288)
		(layer "In2.Cu")
		(net "M_F_CPU0_SB_DQ<16>")
	)
	(segment
		(start 392.135106 -223.544638)
		(end 392.32332 -223.733106)
		(width 0.18288)
		(layer "In2.Cu")
		(net "M_F_CPU0_SB_DQ<16>")
	)
	(segment
		(start 399.79473 -216.261696)
		(end 399.606516 -216.073228)
		(width 0.18288)
		(layer "In2.Cu")
		(net "M_F_CPU0_SB_DQ<16>")
	)
	(segment
		(start 396.082774 -220.246448)
		(end 395.809978 -220.246448)
		(width 0.18288)
		(layer "In2.Cu")
		(net "M_F_CPU0_SB_DQ<16>")
	)
	(segment
		(start 392.32332 -224.005902)
		(end 392.016996 -224.312226)
		(width 0.18288)
		(layer "In2.Cu")
		(net "M_F_CPU0_SB_DQ<16>")
	)
	(segment
		(start 388.776464 -224.832926)
		(end 388.22884 -224.832926)
		(width 0.088646)
		(layer "In2.Cu")
		(net "M_F_CPU0_SB_DQ<16>")
	)
	(segment
		(start 394.090398 -222.238824)
		(end 393.817602 -222.238824)
		(width 0.18288)
		(layer "In2.Cu")
		(net "M_F_CPU0_SB_DQ<16>")
	)
	(segment
		(start 417.45789 -212.958426)
		(end 416.804094 -212.958426)
		(width 0.18288)
		(layer "In2.Cu")
		(net "M_F_CPU0_SB_DQ<16>")
	)
	(segment
		(start 411.744414 -212.225382)
		(end 411.382972 -211.86394)
		(width 0.18288)
		(layer "In2.Cu")
		(net "M_F_CPU0_SB_DQ<16>")
	)
	(segment
		(start 393.817602 -222.238824)
		(end 393.629388 -222.050356)
		(width 0.18288)
		(layer "In2.Cu")
		(net "M_F_CPU0_SB_DQ<16>")
	)
	(segment
		(start 405.934926 -212.221572)
		(end 405.876506 -212.163152)
		(width 0.18288)
		(layer "In2.Cu")
		(net "M_F_CPU0_SB_DQ<16>")
	)
	(segment
		(start 394.315696 -221.74073)
		(end 394.315696 -222.013526)
		(width 0.18288)
		(layer "In2.Cu")
		(net "M_F_CPU0_SB_DQ<16>")
	)
	(segment
		(start 394.315696 -222.013526)
		(end 394.090398 -222.238824)
		(width 0.18288)
		(layer "In2.Cu")
		(net "M_F_CPU0_SB_DQ<16>")
	)
	(segment
		(start 394.127482 -221.552262)
		(end 394.315696 -221.74073)
		(width 0.18288)
		(layer "In2.Cu")
		(net "M_F_CPU0_SB_DQ<16>")
	)
	(segment
		(start 416.024822 -212.56625)
		(end 416.024822 -212.125814)
		(width 0.18288)
		(layer "In2.Cu")
		(net "M_F_CPU0_SB_DQ<16>")
	)
	(segment
		(start 396.308072 -219.748354)
		(end 396.308072 -220.02115)
		(width 0.18288)
		(layer "In2.Cu")
		(net "M_F_CPU0_SB_DQ<16>")
	)
	(segment
		(start 408.278076 -212.015578)
		(end 407.83256 -212.015578)
		(width 0.18288)
		(layer "In2.Cu")
		(net "M_F_CPU0_SB_DQ<16>")
	)
	(segment
		(start 396.308072 -220.02115)
		(end 396.082774 -220.246448)
		(width 0.18288)
		(layer "In2.Cu")
		(net "M_F_CPU0_SB_DQ<16>")
	)
	(segment
		(start 410.285184 -211.86394)
		(end 409.923742 -212.225382)
		(width 0.18288)
		(layer "In2.Cu")
		(net "M_F_CPU0_SB_DQ<16>")
	)
	(segment
		(start 393.131294 -222.275654)
		(end 393.131294 -222.54845)
		(width 0.18288)
		(layer "In2.Cu")
		(net "M_F_CPU0_SB_DQ<16>")
	)
	(segment
		(start 393.319508 -222.736918)
		(end 393.319508 -223.009714)
		(width 0.18288)
		(layer "In2.Cu")
		(net "M_F_CPU0_SB_DQ<16>")
	)
	(segment
		(start 392.821414 -223.235012)
		(end 392.6332 -223.046544)
		(width 0.18288)
		(layer "In2.Cu")
		(net "M_F_CPU0_SB_DQ<16>")
	)
	(segment
		(start 398.112234 -217.294714)
		(end 398.112234 -217.56751)
		(width 0.18288)
		(layer "In2.Cu")
		(net "M_F_CPU0_SB_DQ<16>")
	)
	(segment
		(start 400.067526 -216.261696)
		(end 399.79473 -216.261696)
		(width 0.18288)
		(layer "In2.Cu")
		(net "M_F_CPU0_SB_DQ<16>")
	)
	(segment
		(start 399.108422 -216.571322)
		(end 399.296636 -216.75979)
		(width 0.18288)
		(layer "In2.Cu")
		(net "M_F_CPU0_SB_DQ<16>")
	)
	(segment
		(start 397.341344 -218.065604)
		(end 397.116046 -218.290902)
		(width 0.18288)
		(layer "In2.Cu")
		(net "M_F_CPU0_SB_DQ<16>")
	)
	(segment
		(start 397.30426 -219.024962)
		(end 397.078962 -219.25026)
		(width 0.18288)
		(layer "In2.Cu")
		(net "M_F_CPU0_SB_DQ<16>")
	)
	(segment
		(start 412.253684 -212.225382)
		(end 411.744414 -212.225382)
		(width 0.18288)
		(layer "In2.Cu")
		(net "M_F_CPU0_SB_DQ<16>")
	)
	(segment
		(start 413.164528 -211.937092)
		(end 412.541974 -211.937092)
		(width 0.18288)
		(layer "In2.Cu")
		(net "M_F_CPU0_SB_DQ<16>")
	)
	(segment
		(start 397.802354 -218.254072)
		(end 397.61414 -218.065604)
		(width 0.18288)
		(layer "In2.Cu")
		(net "M_F_CPU0_SB_DQ<16>")
	)
	(segment
		(start 392.016996 -224.312226)
		(end 389.75411 -224.312226)
		(width 0.18288)
		(layer "In2.Cu")
		(net "M_F_CPU0_SB_DQ<16>")
	)
	(segment
		(start 392.360404 -223.046544)
		(end 392.135106 -223.271842)
		(width 0.18288)
		(layer "In2.Cu")
		(net "M_F_CPU0_SB_DQ<16>")
	)
	(segment
		(start 397.116046 -218.563698)
		(end 397.30426 -218.752166)
		(width 0.18288)
		(layer "In2.Cu")
		(net "M_F_CPU0_SB_DQ<16>")
	)
	(segment
		(start 393.131294 -222.54845)
		(end 393.319508 -222.736918)
		(width 0.18288)
		(layer "In2.Cu")
		(net "M_F_CPU0_SB_DQ<16>")
	)
	(segment
		(start 392.6332 -223.046544)
		(end 392.360404 -223.046544)
		(width 0.18288)
		(layer "In2.Cu")
		(net "M_F_CPU0_SB_DQ<16>")
	)
	(segment
		(start 393.319508 -223.009714)
		(end 393.09421 -223.235012)
		(width 0.18288)
		(layer "In2.Cu")
		(net "M_F_CPU0_SB_DQ<16>")
	)
	(segment
		(start 409.923742 -212.225382)
		(end 409.476194 -212.225382)
		(width 0.18288)
		(layer "In2.Cu")
		(net "M_F_CPU0_SB_DQ<16>")
	)
	(segment
		(start 394.625576 -221.054168)
		(end 394.35278 -221.054168)
		(width 0.18288)
		(layer "In2.Cu")
		(net "M_F_CPU0_SB_DQ<16>")
	)
	(segment
		(start 399.33372 -216.073228)
		(end 399.108422 -216.298526)
		(width 0.18288)
		(layer "In2.Cu")
		(net "M_F_CPU0_SB_DQ<16>")
	)
	(segment
		(start 398.300448 -218.028774)
		(end 398.07515 -218.254072)
		(width 0.18288)
		(layer "In2.Cu")
		(net "M_F_CPU0_SB_DQ<16>")
	)
	(segment
		(start 394.81379 -221.242636)
		(end 394.625576 -221.054168)
		(width 0.18288)
		(layer "In2.Cu")
		(net "M_F_CPU0_SB_DQ<16>")
	)
	(segment
		(start 395.12367 -220.283278)
		(end 395.12367 -220.556074)
		(width 0.18288)
		(layer "In2.Cu")
		(net "M_F_CPU0_SB_DQ<16>")
	)
	(segment
		(start 398.300448 -217.755978)
		(end 398.300448 -218.028774)
		(width 0.18288)
		(layer "In2.Cu")
		(net "M_F_CPU0_SB_DQ<16>")
	)
	(segment
		(start 396.119858 -219.28709)
		(end 396.119858 -219.559886)
		(width 0.18288)
		(layer "In2.Cu")
		(net "M_F_CPU0_SB_DQ<16>")
	)
	(segment
		(start 385.583938 -224.862644)
		(end 384.955034 -224.389442)
		(width 0.088646)
		(layer "In2.Cu")
		(net "M_F_CPU0_SB_DQ<16>")
	)
	(segment
		(start 399.296636 -216.75979)
		(end 399.296636 -217.032586)
		(width 0.18288)
		(layer "In2.Cu")
		(net "M_F_CPU0_SB_DQ<16>")
	)
	(segment
		(start 398.07515 -218.254072)
		(end 397.802354 -218.254072)
		(width 0.18288)
		(layer "In2.Cu")
		(net "M_F_CPU0_SB_DQ<16>")
	)
	(segment
		(start 395.311884 -221.017338)
		(end 395.086586 -221.242636)
		(width 0.18288)
		(layer "In2.Cu")
		(net "M_F_CPU0_SB_DQ<16>")
	)
	(segment
		(start 397.61414 -218.065604)
		(end 397.341344 -218.065604)
		(width 0.18288)
		(layer "In2.Cu")
		(net "M_F_CPU0_SB_DQ<16>")
	)
	(segment
		(start 409.476194 -212.225382)
		(end 409.008326 -211.757514)
		(width 0.18288)
		(layer "In2.Cu")
		(net "M_F_CPU0_SB_DQ<16>")
	)
	(segment
		(start 395.348968 -220.05798)
		(end 395.12367 -220.283278)
		(width 0.18288)
		(layer "In2.Cu")
		(net "M_F_CPU0_SB_DQ<16>")
	)
	(segment
		(start 398.798542 -217.257884)
		(end 398.610328 -217.069416)
		(width 0.18288)
		(layer "In2.Cu")
		(net "M_F_CPU0_SB_DQ<16>")
	)
	(segment
		(start 420.150544 -212.88121)
		(end 419.405816 -212.88121)
		(width 0.18288)
		(layer "In2.Cu")
		(net "M_F_CPU0_SB_DQ<16>")
	)
	(segment
		(start 392.135106 -223.271842)
		(end 392.135106 -223.544638)
		(width 0.18288)
		(layer "In2.Cu")
		(net "M_F_CPU0_SB_DQ<16>")
	)
	(segment
		(start 419.405816 -212.88121)
		(end 419.266116 -213.02091)
		(width 0.18288)
		(layer "In2.Cu")
		(net "M_F_CPU0_SB_DQ<16>")
	)
	(segment
		(start 417.520374 -213.02091)
		(end 417.45789 -212.958426)
		(width 0.18288)
		(layer "In2.Cu")
		(net "M_F_CPU0_SB_DQ<16>")
	)
	(segment
		(start 395.086586 -221.242636)
		(end 394.81379 -221.242636)
		(width 0.18288)
		(layer "In2.Cu")
		(net "M_F_CPU0_SB_DQ<16>")
	)
	(segment
		(start 413.413448 -212.186012)
		(end 413.164528 -211.937092)
		(width 0.18288)
		(layer "In2.Cu")
		(net "M_F_CPU0_SB_DQ<16>")
	)
	(segment
		(start 416.804094 -212.958426)
		(end 416.631628 -212.78596)
		(width 0.18288)
		(layer "In2.Cu")
		(net "M_F_CPU0_SB_DQ<16>")
	)
	(segment
		(start 394.127482 -221.279466)
		(end 394.127482 -221.552262)
		(width 0.18288)
		(layer "In2.Cu")
		(net "M_F_CPU0_SB_DQ<16>")
	)
	(segment
		(start 397.30426 -218.752166)
		(end 397.30426 -219.024962)
		(width 0.18288)
		(layer "In2.Cu")
		(net "M_F_CPU0_SB_DQ<16>")
	)
	(segment
		(start 419.266116 -213.02091)
		(end 417.520374 -213.02091)
		(width 0.18288)
		(layer "In2.Cu")
		(net "M_F_CPU0_SB_DQ<16>")
	)
	(segment
		(start 392.32332 -223.733106)
		(end 392.32332 -224.005902)
		(width 0.18288)
		(layer "In2.Cu")
		(net "M_F_CPU0_SB_DQ<16>")
	)
	(segment
		(start 416.024822 -212.125814)
		(end 415.82594 -211.926932)
		(width 0.18288)
		(layer "In2.Cu")
		(net "M_F_CPU0_SB_DQ<16>")
	)
	(arc
		(start 387.117336 -224.8789)
		(mid 386.834634 -224.954676)
		(end 386.551932 -224.8789)
		(width 0.088646)
		(layer "In2.Cu")
		(net "M_F_CPU0_SB_DQ<16>")
	)
	(arc
		(start 386.177536 -224.8789)
		(mid 385.894834 -224.954642)
		(end 385.612132 -224.8789)
		(width 0.088646)
		(layer "In2.Cu")
		(net "M_F_CPU0_SB_DQ<16>")
	)
	(arc
		(start 388.057136 -224.8789)
		(mid 387.774434 -224.954676)
		(end 387.491732 -224.8789)
		(width 0.088646)
		(layer "In2.Cu")
		(net "M_F_CPU0_SB_DQ<16>")
	)
	(arc
		(start 388.22884 -224.832926)
		(mid 388.139968 -224.844625)
		(end 388.057136 -224.8789)
		(width 0.088646)
		(layer "In2.Cu")
		(net "M_F_CPU0_SB_DQ<16>")
	)
	(arc
		(start 386.551932 -224.8789)
		(mid 386.364734 -224.828757)
		(end 386.177536 -224.8789)
		(width 0.088646)
		(layer "In2.Cu")
		(net "M_F_CPU0_SB_DQ<16>")
	)
	(arc
		(start 387.491732 -224.8789)
		(mid 387.304534 -224.828723)
		(end 387.117336 -224.8789)
		(width 0.088646)
		(layer "In2.Cu")
		(net "M_F_CPU0_SB_DQ<16>")
	)
	(segment
		(start 428.363126 -214.748618)
		(end 428.367952 -214.748618)
		(width 0.101854)
		(layer "F.Cu")
		(net "M_F_CPU0_SB_DQ<15>")
	)
	(segment
		(start 431.898552 -214.064596)
		(end 432.15052 -214.316564)
		(width 0.20066)
		(layer "F.Cu")
		(net "M_F_CPU0_SB_DQ<15>")
	)
	(segment
		(start 431.280316 -214.298784)
		(end 431.514504 -214.064596)
		(width 0.20066)
		(layer "F.Cu")
		(net "M_F_CPU0_SB_DQ<15>")
	)
	(segment
		(start 431.514504 -214.064596)
		(end 431.898552 -214.064596)
		(width 0.20066)
		(layer "F.Cu")
		(net "M_F_CPU0_SB_DQ<15>")
	)
	(segment
		(start 428.07128 -214.748618)
		(end 428.363126 -214.748618)
		(width 0.20066)
		(layer "F.Cu")
		(net "M_F_CPU0_SB_DQ<15>")
	)
	(segment
		(start 424.836082 -214.316564)
		(end 425.940982 -214.316564)
		(width 0.20066)
		(layer "F.Cu")
		(net "M_F_CPU0_SB_DQ<15>")
	)
	(segment
		(start 428.367952 -214.748618)
		(end 428.375064 -214.741506)
		(width 0.1016)
		(layer "F.Cu")
		(net "M_F_CPU0_SB_DQ<15>")
	)
	(segment
		(start 425.940982 -214.316564)
		(end 427.639226 -214.316564)
		(width 0.20066)
		(layer "F.Cu")
		(net "M_F_CPU0_SB_DQ<15>")
	)
	(segment
		(start 428.375064 -214.741506)
		(end 430.382934 -214.741506)
		(width 0.1016)
		(layer "F.Cu")
		(net "M_F_CPU0_SB_DQ<15>")
	)
	(segment
		(start 430.382934 -214.741506)
		(end 430.395126 -214.753698)
		(width 0.1016)
		(layer "F.Cu")
		(net "M_F_CPU0_SB_DQ<15>")
	)
	(segment
		(start 432.15052 -214.316564)
		(end 433.484782 -214.316564)
		(width 0.20066)
		(layer "F.Cu")
		(net "M_F_CPU0_SB_DQ<15>")
	)
	(segment
		(start 427.639226 -214.316564)
		(end 428.07128 -214.748618)
		(width 0.20066)
		(layer "F.Cu")
		(net "M_F_CPU0_SB_DQ<15>")
	)
	(segment
		(start 431.076354 -214.753698)
		(end 431.280316 -214.549736)
		(width 0.20066)
		(layer "F.Cu")
		(net "M_F_CPU0_SB_DQ<15>")
	)
	(segment
		(start 382.60528 -228.994716)
		(end 382.60528 -228.45903)
		(width 0.20066)
		(layer "F.Cu")
		(net "M_F_CPU0_SB_DQ<15>")
	)
	(segment
		(start 382.605534 -228.99497)
		(end 382.60528 -228.994716)
		(width 0.20066)
		(layer "F.Cu")
		(net "M_F_CPU0_SB_DQ<15>")
	)
	(segment
		(start 431.280316 -214.549736)
		(end 431.280316 -214.298784)
		(width 0.20066)
		(layer "F.Cu")
		(net "M_F_CPU0_SB_DQ<15>")
	)
	(segment
		(start 430.395126 -214.753698)
		(end 431.076354 -214.753698)
		(width 0.20066)
		(layer "F.Cu")
		(net "M_F_CPU0_SB_DQ<15>")
	)
	(segment
		(start 383.450084 -227.635054)
		(end 383.450084 -227.64496)
		(width 0.088646)
		(layer "In2.Cu")
		(net "M_F_CPU0_SB_DQ<15>")
	)
	(segment
		(start 424.836082 -214.316564)
		(end 423.520616 -214.753444)
		(width 0.18288)
		(layer "In2.Cu")
		(net "M_F_CPU0_SB_DQ<15>")
	)
	(segment
		(start 387.209284 -225.998786)
		(end 387.209284 -226.017328)
		(width 0.088646)
		(layer "In2.Cu")
		(net "M_F_CPU0_SB_DQ<15>")
	)
	(segment
		(start 421.838374 -213.999826)
		(end 421.480742 -213.999826)
		(width 0.18288)
		(layer "In2.Cu")
		(net "M_F_CPU0_SB_DQ<15>")
	)
	(segment
		(start 387.030722 -226.336606)
		(end 387.021832 -226.341686)
		(width 0.088646)
		(layer "In2.Cu")
		(net "M_F_CPU0_SB_DQ<15>")
	)
	(segment
		(start 383.271522 -227.964238)
		(end 383.262632 -227.969318)
		(width 0.088646)
		(layer "In2.Cu")
		(net "M_F_CPU0_SB_DQ<15>")
	)
	(segment
		(start 413.375602 -213.148926)
		(end 412.802832 -213.148926)
		(width 0.18288)
		(layer "In2.Cu")
		(net "M_F_CPU0_SB_DQ<15>")
	)
	(segment
		(start 389.06196 -225.45167)
		(end 388.714488 -225.45167)
		(width 0.088646)
		(layer "In2.Cu")
		(net "M_F_CPU0_SB_DQ<15>")
	)
	(segment
		(start 420.491158 -214.740744)
		(end 420.169848 -214.419434)
		(width 0.18288)
		(layer "In2.Cu")
		(net "M_F_CPU0_SB_DQ<15>")
	)
	(segment
		(start 412.802832 -213.148926)
		(end 412.688786 -213.03488)
		(width 0.18288)
		(layer "In2.Cu")
		(net "M_F_CPU0_SB_DQ<15>")
	)
	(segment
		(start 404.47849 -213.087458)
		(end 392.43635 -225.129598)
		(width 0.18288)
		(layer "In2.Cu")
		(net "M_F_CPU0_SB_DQ<15>")
	)
	(segment
		(start 386.560822 -227.150422)
		(end 386.551932 -227.155502)
		(width 0.088646)
		(layer "In2.Cu")
		(net "M_F_CPU0_SB_DQ<15>")
	)
	(segment
		(start 415.064448 -213.073996)
		(end 413.450532 -213.073996)
		(width 0.18288)
		(layer "In2.Cu")
		(net "M_F_CPU0_SB_DQ<15>")
	)
	(segment
		(start 389.75411 -225.129598)
		(end 389.384032 -225.129598)
		(width 0.088646)
		(layer "In2.Cu")
		(net "M_F_CPU0_SB_DQ<15>")
	)
	(segment
		(start 423.520616 -214.753444)
		(end 422.280588 -214.753444)
		(width 0.18288)
		(layer "In2.Cu")
		(net "M_F_CPU0_SB_DQ<15>")
	)
	(segment
		(start 412.688786 -213.03488)
		(end 409.369006 -213.03488)
		(width 0.18288)
		(layer "In2.Cu")
		(net "M_F_CPU0_SB_DQ<15>")
	)
	(segment
		(start 420.169848 -214.15248)
		(end 419.940994 -213.923626)
		(width 0.18288)
		(layer "In2.Cu")
		(net "M_F_CPU0_SB_DQ<15>")
	)
	(segment
		(start 421.160702 -214.740744)
		(end 420.491158 -214.740744)
		(width 0.18288)
		(layer "In2.Cu")
		(net "M_F_CPU0_SB_DQ<15>")
	)
	(segment
		(start 422.03751 -214.510366)
		(end 422.03751 -214.198962)
		(width 0.18288)
		(layer "In2.Cu")
		(net "M_F_CPU0_SB_DQ<15>")
	)
	(segment
		(start 420.169848 -214.419434)
		(end 420.169848 -214.15248)
		(width 0.18288)
		(layer "In2.Cu")
		(net "M_F_CPU0_SB_DQ<15>")
	)
	(segment
		(start 421.480742 -213.999826)
		(end 421.320722 -214.159846)
		(width 0.18288)
		(layer "In2.Cu")
		(net "M_F_CPU0_SB_DQ<15>")
	)
	(segment
		(start 416.646614 -213.923626)
		(end 415.294318 -213.303866)
		(width 0.18288)
		(layer "In2.Cu")
		(net "M_F_CPU0_SB_DQ<15>")
	)
	(segment
		(start 392.43635 -225.129598)
		(end 389.75411 -225.129598)
		(width 0.18288)
		(layer "In2.Cu")
		(net "M_F_CPU0_SB_DQ<15>")
	)
	(segment
		(start 422.280588 -214.753444)
		(end 422.03751 -214.510366)
		(width 0.18288)
		(layer "In2.Cu")
		(net "M_F_CPU0_SB_DQ<15>")
	)
	(segment
		(start 382.873504 -228.45903)
		(end 382.60528 -228.45903)
		(width 0.088646)
		(layer "In2.Cu")
		(net "M_F_CPU0_SB_DQ<15>")
	)
	(segment
		(start 421.320722 -214.159846)
		(end 421.320722 -214.580724)
		(width 0.18288)
		(layer "In2.Cu")
		(net "M_F_CPU0_SB_DQ<15>")
	)
	(segment
		(start 415.294318 -213.303866)
		(end 415.064448 -213.073996)
		(width 0.18288)
		(layer "In2.Cu")
		(net "M_F_CPU0_SB_DQ<15>")
	)
	(segment
		(start 389.384032 -225.129598)
		(end 389.06196 -225.45167)
		(width 0.088646)
		(layer "In2.Cu")
		(net "M_F_CPU0_SB_DQ<15>")
	)
	(segment
		(start 413.450532 -213.073996)
		(end 413.375602 -213.148926)
		(width 0.18288)
		(layer "In2.Cu")
		(net "M_F_CPU0_SB_DQ<15>")
	)
	(segment
		(start 409.316428 -213.087458)
		(end 404.47849 -213.087458)
		(width 0.18288)
		(layer "In2.Cu")
		(net "M_F_CPU0_SB_DQ<15>")
	)
	(segment
		(start 419.940994 -213.923626)
		(end 416.646614 -213.923626)
		(width 0.18288)
		(layer "In2.Cu")
		(net "M_F_CPU0_SB_DQ<15>")
	)
	(segment
		(start 409.369006 -213.03488)
		(end 409.316428 -213.087458)
		(width 0.18288)
		(layer "In2.Cu")
		(net "M_F_CPU0_SB_DQ<15>")
	)
	(segment
		(start 386.739384 -226.821238)
		(end 386.739384 -226.831144)
		(width 0.088646)
		(layer "In2.Cu")
		(net "M_F_CPU0_SB_DQ<15>")
	)
	(segment
		(start 421.320722 -214.580724)
		(end 421.160702 -214.740744)
		(width 0.18288)
		(layer "In2.Cu")
		(net "M_F_CPU0_SB_DQ<15>")
	)
	(segment
		(start 422.03751 -214.198962)
		(end 421.838374 -213.999826)
		(width 0.18288)
		(layer "In2.Cu")
		(net "M_F_CPU0_SB_DQ<15>")
	)
	(arc
		(start 385.612132 -227.155502)
		(mid 385.424934 -227.205645)
		(end 385.237736 -227.155502)
		(width 0.088646)
		(layer "In2.Cu")
		(net "M_F_CPU0_SB_DQ<15>")
	)
	(arc
		(start 384.672332 -227.155502)
		(mid 384.485134 -227.205645)
		(end 384.297936 -227.155502)
		(width 0.088646)
		(layer "In2.Cu")
		(net "M_F_CPU0_SB_DQ<15>")
	)
	(arc
		(start 384.297936 -227.155502)
		(mid 384.015234 -227.079726)
		(end 383.732532 -227.155502)
		(width 0.088646)
		(layer "In2.Cu")
		(net "M_F_CPU0_SB_DQ<15>")
	)
	(arc
		(start 386.177536 -227.155502)
		(mid 385.894834 -227.079726)
		(end 385.612132 -227.155502)
		(width 0.088646)
		(layer "In2.Cu")
		(net "M_F_CPU0_SB_DQ<15>")
	)
	(arc
		(start 387.491732 -225.527616)
		(mid 387.289446 -225.726597)
		(end 387.209284 -225.998786)
		(width 0.088646)
		(layer "In2.Cu")
		(net "M_F_CPU0_SB_DQ<15>")
	)
	(arc
		(start 387.209284 -226.017328)
		(mid 387.161605 -226.200228)
		(end 387.030722 -226.336606)
		(width 0.088646)
		(layer "In2.Cu")
		(net "M_F_CPU0_SB_DQ<15>")
	)
	(arc
		(start 386.739384 -226.831144)
		(mid 386.691705 -227.014044)
		(end 386.560822 -227.150422)
		(width 0.088646)
		(layer "In2.Cu")
		(net "M_F_CPU0_SB_DQ<15>")
	)
	(arc
		(start 388.431532 -225.527616)
		(mid 388.244334 -225.577759)
		(end 388.057136 -225.527616)
		(width 0.088646)
		(layer "In2.Cu")
		(net "M_F_CPU0_SB_DQ<15>")
	)
	(arc
		(start 382.988058 -228.36251)
		(mid 382.948377 -228.431632)
		(end 382.873504 -228.45903)
		(width 0.088646)
		(layer "In2.Cu")
		(net "M_F_CPU0_SB_DQ<15>")
	)
	(arc
		(start 387.021832 -226.341686)
		(mid 386.817497 -226.544291)
		(end 386.739384 -226.821238)
		(width 0.088646)
		(layer "In2.Cu")
		(net "M_F_CPU0_SB_DQ<15>")
	)
	(arc
		(start 388.057136 -225.527616)
		(mid 387.774434 -225.451874)
		(end 387.491732 -225.527616)
		(width 0.088646)
		(layer "In2.Cu")
		(net "M_F_CPU0_SB_DQ<15>")
	)
	(arc
		(start 383.262632 -227.969318)
		(mid 383.081658 -228.13539)
		(end 382.988058 -228.36251)
		(width 0.088646)
		(layer "In2.Cu")
		(net "M_F_CPU0_SB_DQ<15>")
	)
	(arc
		(start 388.714488 -225.45167)
		(mid 388.568018 -225.47103)
		(end 388.431532 -225.527616)
		(width 0.088646)
		(layer "In2.Cu")
		(net "M_F_CPU0_SB_DQ<15>")
	)
	(arc
		(start 385.237736 -227.155502)
		(mid 384.955034 -227.079726)
		(end 384.672332 -227.155502)
		(width 0.088646)
		(layer "In2.Cu")
		(net "M_F_CPU0_SB_DQ<15>")
	)
	(arc
		(start 383.732532 -227.155502)
		(mid 383.528197 -227.358107)
		(end 383.450084 -227.635054)
		(width 0.088646)
		(layer "In2.Cu")
		(net "M_F_CPU0_SB_DQ<15>")
	)
	(arc
		(start 386.551932 -227.155502)
		(mid 386.364734 -227.205645)
		(end 386.177536 -227.155502)
		(width 0.088646)
		(layer "In2.Cu")
		(net "M_F_CPU0_SB_DQ<15>")
	)
	(arc
		(start 383.450084 -227.64496)
		(mid 383.402405 -227.82786)
		(end 383.271522 -227.964238)
		(width 0.088646)
		(layer "In2.Cu")
		(net "M_F_CPU0_SB_DQ<15>")
	)
	(segment
		(start 431.514504 -215.764618)
		(end 431.898552 -215.764618)
		(width 0.20066)
		(layer "F.Cu")
		(net "M_F_CPU0_SB_DQ<14>")
	)
	(segment
		(start 425.940982 -216.016586)
		(end 427.639226 -216.016586)
		(width 0.20066)
		(layer "F.Cu")
		(net "M_F_CPU0_SB_DQ<14>")
	)
	(segment
		(start 431.280316 -216.249758)
		(end 431.280316 -215.998806)
		(width 0.20066)
		(layer "F.Cu")
		(net "M_F_CPU0_SB_DQ<14>")
	)
	(segment
		(start 432.15052 -216.016586)
		(end 433.484782 -216.016586)
		(width 0.20066)
		(layer "F.Cu")
		(net "M_F_CPU0_SB_DQ<14>")
	)
	(segment
		(start 428.375064 -216.441528)
		(end 430.382934 -216.441528)
		(width 0.1016)
		(layer "F.Cu")
		(net "M_F_CPU0_SB_DQ<14>")
	)
	(segment
		(start 424.836082 -216.016586)
		(end 425.940982 -216.016586)
		(width 0.20066)
		(layer "F.Cu")
		(net "M_F_CPU0_SB_DQ<14>")
	)
	(segment
		(start 428.07128 -216.44864)
		(end 428.363126 -216.44864)
		(width 0.20066)
		(layer "F.Cu")
		(net "M_F_CPU0_SB_DQ<14>")
	)
	(segment
		(start 430.395126 -216.45372)
		(end 431.076354 -216.45372)
		(width 0.20066)
		(layer "F.Cu")
		(net "M_F_CPU0_SB_DQ<14>")
	)
	(segment
		(start 427.639226 -216.016586)
		(end 428.07128 -216.44864)
		(width 0.20066)
		(layer "F.Cu")
		(net "M_F_CPU0_SB_DQ<14>")
	)
	(segment
		(start 431.280316 -215.998806)
		(end 431.514504 -215.764618)
		(width 0.20066)
		(layer "F.Cu")
		(net "M_F_CPU0_SB_DQ<14>")
	)
	(segment
		(start 428.363126 -216.44864)
		(end 428.367952 -216.44864)
		(width 0.101854)
		(layer "F.Cu")
		(net "M_F_CPU0_SB_DQ<14>")
	)
	(segment
		(start 430.382934 -216.441528)
		(end 430.395126 -216.45372)
		(width 0.1016)
		(layer "F.Cu")
		(net "M_F_CPU0_SB_DQ<14>")
	)
	(segment
		(start 431.076354 -216.45372)
		(end 431.280316 -216.249758)
		(width 0.20066)
		(layer "F.Cu")
		(net "M_F_CPU0_SB_DQ<14>")
	)
	(segment
		(start 431.898552 -215.764618)
		(end 432.15052 -216.016586)
		(width 0.20066)
		(layer "F.Cu")
		(net "M_F_CPU0_SB_DQ<14>")
	)
	(segment
		(start 383.075434 -229.808532)
		(end 383.075434 -229.272846)
		(width 0.20066)
		(layer "F.Cu")
		(net "M_F_CPU0_SB_DQ<14>")
	)
	(segment
		(start 383.07518 -229.808786)
		(end 383.075434 -229.808532)
		(width 0.20066)
		(layer "F.Cu")
		(net "M_F_CPU0_SB_DQ<14>")
	)
	(segment
		(start 428.367952 -216.44864)
		(end 428.375064 -216.441528)
		(width 0.1016)
		(layer "F.Cu")
		(net "M_F_CPU0_SB_DQ<14>")
	)
	(segment
		(start 413.52216 -215.594692)
		(end 412.589218 -214.66175)
		(width 0.18288)
		(layer "In2.Cu")
		(net "M_F_CPU0_SB_DQ<14>")
	)
	(segment
		(start 417.40455 -215.697054)
		(end 417.1315 -215.697054)
		(width 0.18288)
		(layer "In2.Cu")
		(net "M_F_CPU0_SB_DQ<14>")
	)
	(segment
		(start 407.888948 -214.973662)
		(end 407.33726 -214.421974)
		(width 0.18288)
		(layer "In2.Cu")
		(net "M_F_CPU0_SB_DQ<14>")
	)
	(segment
		(start 387.196584 -227.8126)
		(end 387.092698 -227.916486)
		(width 0.088646)
		(layer "In2.Cu")
		(net "M_F_CPU0_SB_DQ<14>")
	)
	(segment
		(start 399.2245 -219.77858)
		(end 399.2245 -220.1164)
		(width 0.18288)
		(layer "In2.Cu")
		(net "M_F_CPU0_SB_DQ<14>")
	)
	(segment
		(start 421.444928 -216.124282)
		(end 421.444928 -215.791796)
		(width 0.18288)
		(layer "In2.Cu")
		(net "M_F_CPU0_SB_DQ<14>")
	)
	(segment
		(start 410.02585 -214.789766)
		(end 409.899866 -214.663782)
		(width 0.18288)
		(layer "In2.Cu")
		(net "M_F_CPU0_SB_DQ<14>")
	)
	(segment
		(start 409.899866 -214.663782)
		(end 409.626562 -214.663782)
		(width 0.18288)
		(layer "In2.Cu")
		(net "M_F_CPU0_SB_DQ<14>")
	)
	(segment
		(start 422.343326 -215.574626)
		(end 422.16705 -215.750902)
		(width 0.18288)
		(layer "In2.Cu")
		(net "M_F_CPU0_SB_DQ<14>")
	)
	(segment
		(start 421.244014 -215.590882)
		(end 420.483538 -215.590882)
		(width 0.18288)
		(layer "In2.Cu")
		(net "M_F_CPU0_SB_DQ<14>")
	)
	(segment
		(start 409.626562 -214.663782)
		(end 409.110942 -215.179402)
		(width 0.18288)
		(layer "In2.Cu")
		(net "M_F_CPU0_SB_DQ<14>")
	)
	(segment
		(start 424.511978 -216.34069)
		(end 424.073066 -216.34069)
		(width 0.18288)
		(layer "In2.Cu")
		(net "M_F_CPU0_SB_DQ<14>")
	)
	(segment
		(start 419.229286 -215.57107)
		(end 417.530534 -215.57107)
		(width 0.18288)
		(layer "In2.Cu")
		(net "M_F_CPU0_SB_DQ<14>")
	)
	(segment
		(start 404.493984 -215.291924)
		(end 403.711156 -215.291924)
		(width 0.18288)
		(layer "In2.Cu")
		(net "M_F_CPU0_SB_DQ<14>")
	)
	(segment
		(start 415.305494 -215.380316)
		(end 415.091118 -215.594692)
		(width 0.18288)
		(layer "In2.Cu")
		(net "M_F_CPU0_SB_DQ<14>")
	)
	(segment
		(start 406.410668 -214.75065)
		(end 405.035258 -214.75065)
		(width 0.18288)
		(layer "In2.Cu")
		(net "M_F_CPU0_SB_DQ<14>")
	)
	(segment
		(start 393.14628 -226.19462)
		(end 388.412482 -226.19462)
		(width 0.18288)
		(layer "In2.Cu")
		(net "M_F_CPU0_SB_DQ<14>")
	)
	(segment
		(start 383.919984 -228.440488)
		(end 383.919984 -228.45903)
		(width 0.088646)
		(layer "In2.Cu")
		(net "M_F_CPU0_SB_DQ<14>")
	)
	(segment
		(start 383.741422 -228.778308)
		(end 383.732532 -228.783388)
		(width 0.088646)
		(layer "In2.Cu")
		(net "M_F_CPU0_SB_DQ<14>")
	)
	(segment
		(start 387.197346 -227.8126)
		(end 387.196584 -227.8126)
		(width 0.088646)
		(layer "In2.Cu")
		(net "M_F_CPU0_SB_DQ<14>")
	)
	(segment
		(start 422.16705 -216.178384)
		(end 422.00703 -216.338404)
		(width 0.18288)
		(layer "In2.Cu")
		(net "M_F_CPU0_SB_DQ<14>")
	)
	(segment
		(start 420.398194 -215.676226)
		(end 419.334442 -215.676226)
		(width 0.18288)
		(layer "In2.Cu")
		(net "M_F_CPU0_SB_DQ<14>")
	)
	(segment
		(start 421.444928 -215.791796)
		(end 421.244014 -215.590882)
		(width 0.18288)
		(layer "In2.Cu")
		(net "M_F_CPU0_SB_DQ<14>")
	)
	(segment
		(start 406.739344 -214.421974)
		(end 406.410668 -214.75065)
		(width 0.18288)
		(layer "In2.Cu")
		(net "M_F_CPU0_SB_DQ<14>")
	)
	(segment
		(start 387.73481 -226.872292)
		(end 387.266434 -227.340668)
		(width 0.088646)
		(layer "In2.Cu")
		(net "M_F_CPU0_SB_DQ<14>")
	)
	(segment
		(start 399.2245 -220.1164)
		(end 393.14628 -226.19462)
		(width 0.18288)
		(layer "In2.Cu")
		(net "M_F_CPU0_SB_DQ<14>")
	)
	(segment
		(start 387.266434 -227.340668)
		(end 387.266434 -227.743512)
		(width 0.088646)
		(layer "In2.Cu")
		(net "M_F_CPU0_SB_DQ<14>")
	)
	(segment
		(start 417.1315 -215.697054)
		(end 416.814762 -215.380316)
		(width 0.18288)
		(layer "In2.Cu")
		(net "M_F_CPU0_SB_DQ<14>")
	)
	(segment
		(start 412.589218 -214.66175)
		(end 411.843474 -214.66175)
		(width 0.18288)
		(layer "In2.Cu")
		(net "M_F_CPU0_SB_DQ<14>")
	)
	(segment
		(start 421.65905 -216.338404)
		(end 421.444928 -216.124282)
		(width 0.18288)
		(layer "In2.Cu")
		(net "M_F_CPU0_SB_DQ<14>")
	)
	(segment
		(start 424.836082 -216.016586)
		(end 424.511978 -216.34069)
		(width 0.18288)
		(layer "In2.Cu")
		(net "M_F_CPU0_SB_DQ<14>")
	)
	(segment
		(start 387.266434 -227.743512)
		(end 387.197346 -227.8126)
		(width 0.088646)
		(layer "In2.Cu")
		(net "M_F_CPU0_SB_DQ<14>")
	)
	(segment
		(start 420.483538 -215.590882)
		(end 420.398194 -215.676226)
		(width 0.18288)
		(layer "In2.Cu")
		(net "M_F_CPU0_SB_DQ<14>")
	)
	(segment
		(start 405.035258 -214.75065)
		(end 404.493984 -215.291924)
		(width 0.18288)
		(layer "In2.Cu")
		(net "M_F_CPU0_SB_DQ<14>")
	)
	(segment
		(start 403.711156 -215.291924)
		(end 399.2245 -219.77858)
		(width 0.18288)
		(layer "In2.Cu")
		(net "M_F_CPU0_SB_DQ<14>")
	)
	(segment
		(start 383.61493 -228.827076)
		(end 383.075434 -229.272846)
		(width 0.088646)
		(layer "In2.Cu")
		(net "M_F_CPU0_SB_DQ<14>")
	)
	(segment
		(start 415.091118 -215.594692)
		(end 413.52216 -215.594692)
		(width 0.18288)
		(layer "In2.Cu")
		(net "M_F_CPU0_SB_DQ<14>")
	)
	(segment
		(start 423.307002 -215.574626)
		(end 422.343326 -215.574626)
		(width 0.18288)
		(layer "In2.Cu")
		(net "M_F_CPU0_SB_DQ<14>")
	)
	(segment
		(start 422.16705 -215.750902)
		(end 422.16705 -216.178384)
		(width 0.18288)
		(layer "In2.Cu")
		(net "M_F_CPU0_SB_DQ<14>")
	)
	(segment
		(start 407.33726 -214.421974)
		(end 406.739344 -214.421974)
		(width 0.18288)
		(layer "In2.Cu")
		(net "M_F_CPU0_SB_DQ<14>")
	)
	(segment
		(start 388.412482 -226.19462)
		(end 387.73481 -226.872292)
		(width 0.18288)
		(layer "In2.Cu")
		(net "M_F_CPU0_SB_DQ<14>")
	)
	(segment
		(start 408.631898 -214.973662)
		(end 407.888948 -214.973662)
		(width 0.18288)
		(layer "In2.Cu")
		(net "M_F_CPU0_SB_DQ<14>")
	)
	(segment
		(start 408.837638 -215.179402)
		(end 408.631898 -214.973662)
		(width 0.18288)
		(layer "In2.Cu")
		(net "M_F_CPU0_SB_DQ<14>")
	)
	(segment
		(start 411.843474 -214.66175)
		(end 411.715458 -214.789766)
		(width 0.18288)
		(layer "In2.Cu")
		(net "M_F_CPU0_SB_DQ<14>")
	)
	(segment
		(start 424.073066 -216.34069)
		(end 423.307002 -215.574626)
		(width 0.18288)
		(layer "In2.Cu")
		(net "M_F_CPU0_SB_DQ<14>")
	)
	(segment
		(start 416.814762 -215.380316)
		(end 415.305494 -215.380316)
		(width 0.18288)
		(layer "In2.Cu")
		(net "M_F_CPU0_SB_DQ<14>")
	)
	(segment
		(start 411.715458 -214.789766)
		(end 410.02585 -214.789766)
		(width 0.18288)
		(layer "In2.Cu")
		(net "M_F_CPU0_SB_DQ<14>")
	)
	(segment
		(start 409.110942 -215.179402)
		(end 408.837638 -215.179402)
		(width 0.18288)
		(layer "In2.Cu")
		(net "M_F_CPU0_SB_DQ<14>")
	)
	(segment
		(start 419.334442 -215.676226)
		(end 419.229286 -215.57107)
		(width 0.18288)
		(layer "In2.Cu")
		(net "M_F_CPU0_SB_DQ<14>")
	)
	(segment
		(start 417.530534 -215.57107)
		(end 417.40455 -215.697054)
		(width 0.18288)
		(layer "In2.Cu")
		(net "M_F_CPU0_SB_DQ<14>")
	)
	(segment
		(start 422.00703 -216.338404)
		(end 421.65905 -216.338404)
		(width 0.18288)
		(layer "In2.Cu")
		(net "M_F_CPU0_SB_DQ<14>")
	)
	(arc
		(start 386.082032 -227.969318)
		(mid 385.894834 -228.019461)
		(end 385.707636 -227.969318)
		(width 0.088646)
		(layer "In2.Cu")
		(net "M_F_CPU0_SB_DQ<14>")
	)
	(arc
		(start 387.021832 -227.969318)
		(mid 386.834634 -228.019461)
		(end 386.647436 -227.969318)
		(width 0.088646)
		(layer "In2.Cu")
		(net "M_F_CPU0_SB_DQ<14>")
	)
	(arc
		(start 385.707636 -227.969318)
		(mid 385.424934 -227.893576)
		(end 385.142232 -227.969318)
		(width 0.088646)
		(layer "In2.Cu")
		(net "M_F_CPU0_SB_DQ<14>")
	)
	(arc
		(start 384.202432 -227.969318)
		(mid 384.000146 -228.168299)
		(end 383.919984 -228.440488)
		(width 0.088646)
		(layer "In2.Cu")
		(net "M_F_CPU0_SB_DQ<14>")
	)
	(arc
		(start 383.732532 -228.783388)
		(mid 383.675575 -228.810196)
		(end 383.61493 -228.827076)
		(width 0.088646)
		(layer "In2.Cu")
		(net "M_F_CPU0_SB_DQ<14>")
	)
	(arc
		(start 384.767836 -227.969318)
		(mid 384.485134 -227.893576)
		(end 384.202432 -227.969318)
		(width 0.088646)
		(layer "In2.Cu")
		(net "M_F_CPU0_SB_DQ<14>")
	)
	(arc
		(start 386.647436 -227.969318)
		(mid 386.364734 -227.893576)
		(end 386.082032 -227.969318)
		(width 0.088646)
		(layer "In2.Cu")
		(net "M_F_CPU0_SB_DQ<14>")
	)
	(arc
		(start 383.919984 -228.45903)
		(mid 383.872305 -228.64193)
		(end 383.741422 -228.778308)
		(width 0.088646)
		(layer "In2.Cu")
		(net "M_F_CPU0_SB_DQ<14>")
	)
	(arc
		(start 385.142232 -227.969318)
		(mid 384.955034 -228.019461)
		(end 384.767836 -227.969318)
		(width 0.088646)
		(layer "In2.Cu")
		(net "M_F_CPU0_SB_DQ<14>")
	)
	(arc
		(start 387.092698 -227.916486)
		(mid 387.058832 -227.945005)
		(end 387.021832 -227.969318)
		(width 0.088646)
		(layer "In2.Cu")
		(net "M_F_CPU0_SB_DQ<14>")
	)
	(segment
		(start 424.273472 -215.227408)
		(end 424.085512 -215.415368)
		(width 0.20066)
		(layer "F.Cu")
		(net "M_F_CPU0_SB_DQ<13>")
	)
	(segment
		(start 429.384714 -215.166702)
		(end 429.38446 -215.166956)
		(width 0.20066)
		(layer "F.Cu")
		(net "M_F_CPU0_SB_DQ<13>")
	)
	(segment
		(start 424.273472 -214.85987)
		(end 424.273472 -215.227408)
		(width 0.20066)
		(layer "F.Cu")
		(net "M_F_CPU0_SB_DQ<13>")
	)
	(segment
		(start 424.391582 -214.74176)
		(end 424.273472 -214.85987)
		(width 0.20066)
		(layer "F.Cu")
		(net "M_F_CPU0_SB_DQ<13>")
	)
	(segment
		(start 424.73626 -214.74176)
		(end 424.391582 -214.74176)
		(width 0.20066)
		(layer "F.Cu")
		(net "M_F_CPU0_SB_DQ<13>")
	)
	(segment
		(start 423.610278 -215.415368)
		(end 423.361612 -215.166702)
		(width 0.20066)
		(layer "F.Cu")
		(net "M_F_CPU0_SB_DQ<13>")
	)
	(segment
		(start 426.951394 -214.73541)
		(end 426.945044 -214.74176)
		(width 0.1016)
		(layer "F.Cu")
		(net "M_F_CPU0_SB_DQ<13>")
	)
	(segment
		(start 429.38446 -215.166956)
		(end 427.792896 -215.166956)
		(width 0.20066)
		(layer "F.Cu")
		(net "M_F_CPU0_SB_DQ<13>")
	)
	(segment
		(start 381.665734 -228.45903)
		(end 381.665734 -228.99497)
		(width 0.20066)
		(layer "F.Cu")
		(net "M_F_CPU0_SB_DQ<13>")
	)
	(segment
		(start 427.36135 -214.73541)
		(end 426.951394 -214.73541)
		(width 0.20066)
		(layer "F.Cu")
		(net "M_F_CPU0_SB_DQ<13>")
	)
	(segment
		(start 424.085512 -215.415368)
		(end 423.610278 -215.415368)
		(width 0.20066)
		(layer "F.Cu")
		(net "M_F_CPU0_SB_DQ<13>")
	)
	(segment
		(start 421.840914 -215.166702)
		(end 420.736014 -215.166702)
		(width 0.20066)
		(layer "F.Cu")
		(net "M_F_CPU0_SB_DQ<13>")
	)
	(segment
		(start 423.361612 -215.166702)
		(end 421.840914 -215.166702)
		(width 0.20066)
		(layer "F.Cu")
		(net "M_F_CPU0_SB_DQ<13>")
	)
	(segment
		(start 426.945044 -214.74176)
		(end 424.756326 -214.74176)
		(width 0.1016)
		(layer "F.Cu")
		(net "M_F_CPU0_SB_DQ<13>")
	)
	(segment
		(start 424.756326 -214.74176)
		(end 424.73626 -214.74176)
		(width 0.101854)
		(layer "F.Cu")
		(net "M_F_CPU0_SB_DQ<13>")
	)
	(segment
		(start 427.792896 -215.166956)
		(end 427.36135 -214.73541)
		(width 0.20066)
		(layer "F.Cu")
		(net "M_F_CPU0_SB_DQ<13>")
	)
	(segment
		(start 412.378906 -214.15375)
		(end 411.996636 -214.15375)
		(width 0.18288)
		(layer "In2.Cu")
		(net "M_F_CPU0_SB_DQ<13>")
	)
	(segment
		(start 404.548086 -214.25535)
		(end 404.548086 -214.51697)
		(width 0.18288)
		(layer "In2.Cu")
		(net "M_F_CPU0_SB_DQ<13>")
	)
	(segment
		(start 382.337564 -228.957124)
		(end 382.322832 -228.948488)
		(width 0.088646)
		(layer "In2.Cu")
		(net "M_F_CPU0_SB_DQ<13>")
	)
	(segment
		(start 397.786098 -220.835728)
		(end 397.457168 -221.164658)
		(width 0.18288)
		(layer "In2.Cu")
		(net "M_F_CPU0_SB_DQ<13>")
	)
	(segment
		(start 396.124684 -222.15983)
		(end 395.795754 -222.48876)
		(width 0.18288)
		(layer "In2.Cu")
		(net "M_F_CPU0_SB_DQ<13>")
	)
	(segment
		(start 383.358136 -228.134672)
		(end 383.349246 -228.139752)
		(width 0.088646)
		(layer "In2.Cu")
		(net "M_F_CPU0_SB_DQ<13>")
	)
	(segment
		(start 409.977082 -213.920832)
		(end 409.650946 -213.920832)
		(width 0.18288)
		(layer "In2.Cu")
		(net "M_F_CPU0_SB_DQ<13>")
	)
	(segment
		(start 405.774906 -213.870032)
		(end 405.500332 -213.595458)
		(width 0.18288)
		(layer "In2.Cu")
		(net "M_F_CPU0_SB_DQ<13>")
	)
	(segment
		(start 396.790926 -221.8309)
		(end 396.461996 -222.15983)
		(width 0.18288)
		(layer "In2.Cu")
		(net "M_F_CPU0_SB_DQ<13>")
	)
	(segment
		(start 393.139168 -225.145346)
		(end 392.642598 -225.641916)
		(width 0.18288)
		(layer "In2.Cu")
		(net "M_F_CPU0_SB_DQ<13>")
	)
	(segment
		(start 395.129512 -223.155002)
		(end 394.800582 -223.483932)
		(width 0.18288)
		(layer "In2.Cu")
		(net "M_F_CPU0_SB_DQ<13>")
	)
	(segment
		(start 392.642598 -225.641916)
		(end 389.75411 -225.641916)
		(width 0.18288)
		(layer "In2.Cu")
		(net "M_F_CPU0_SB_DQ<13>")
	)
	(segment
		(start 393.47648 -225.145346)
		(end 393.139168 -225.145346)
		(width 0.18288)
		(layer "In2.Cu")
		(net "M_F_CPU0_SB_DQ<13>")
	)
	(segment
		(start 414.921446 -214.119714)
		(end 414.728406 -213.926674)
		(width 0.18288)
		(layer "In2.Cu")
		(net "M_F_CPU0_SB_DQ<13>")
	)
	(segment
		(start 404.387812 -214.095076)
		(end 404.548086 -214.25535)
		(width 0.18288)
		(layer "In2.Cu")
		(net "M_F_CPU0_SB_DQ<13>")
	)
	(segment
		(start 383.828036 -227.320602)
		(end 383.819146 -227.325682)
		(width 0.088646)
		(layer "In2.Cu")
		(net "M_F_CPU0_SB_DQ<13>")
	)
	(segment
		(start 387.117336 -226.506786)
		(end 387.108446 -226.511866)
		(width 0.088646)
		(layer "In2.Cu")
		(net "M_F_CPU0_SB_DQ<13>")
	)
	(segment
		(start 382.04394 -228.524562)
		(end 381.978408 -228.45903)
		(width 0.088646)
		(layer "In2.Cu")
		(net "M_F_CPU0_SB_DQ<13>")
	)
	(segment
		(start 418.916612 -215.06307)
		(end 417.867592 -215.06307)
		(width 0.18288)
		(layer "In2.Cu")
		(net "M_F_CPU0_SB_DQ<13>")
	)
	(segment
		(start 408.760422 -214.482172)
		(end 408.539696 -214.261446)
		(width 0.18288)
		(layer "In2.Cu")
		(net "M_F_CPU0_SB_DQ<13>")
	)
	(segment
		(start 396.461996 -222.15983)
		(end 396.124684 -222.15983)
		(width 0.18288)
		(layer "In2.Cu")
		(net "M_F_CPU0_SB_DQ<13>")
	)
	(segment
		(start 387.587236 -225.69297)
		(end 387.578346 -225.69805)
		(width 0.088646)
		(layer "In2.Cu")
		(net "M_F_CPU0_SB_DQ<13>")
	)
	(segment
		(start 394.13434 -224.150174)
		(end 393.80541 -224.479104)
		(width 0.18288)
		(layer "In2.Cu")
		(net "M_F_CPU0_SB_DQ<13>")
	)
	(segment
		(start 414.075626 -214.30615)
		(end 413.785304 -214.30615)
		(width 0.18288)
		(layer "In2.Cu")
		(net "M_F_CPU0_SB_DQ<13>")
	)
	(segment
		(start 407.808938 -213.595458)
		(end 407.534364 -213.870032)
		(width 0.18288)
		(layer "In2.Cu")
		(net "M_F_CPU0_SB_DQ<13>")
	)
	(segment
		(start 411.996636 -214.15375)
		(end 411.388814 -213.545928)
		(width 0.18288)
		(layer "In2.Cu")
		(net "M_F_CPU0_SB_DQ<13>")
	)
	(segment
		(start 396.790926 -221.493588)
		(end 396.790926 -221.8309)
		(width 0.18288)
		(layer "In2.Cu")
		(net "M_F_CPU0_SB_DQ<13>")
	)
	(segment
		(start 411.388814 -213.545928)
		(end 410.351986 -213.545928)
		(width 0.18288)
		(layer "In2.Cu")
		(net "M_F_CPU0_SB_DQ<13>")
	)
	(segment
		(start 408.539696 -214.261446)
		(end 408.539696 -213.788498)
		(width 0.18288)
		(layer "In2.Cu")
		(net "M_F_CPU0_SB_DQ<13>")
	)
	(segment
		(start 382.322832 -228.948488)
		(end 382.316736 -228.944932)
		(width 0.088646)
		(layer "In2.Cu")
		(net "M_F_CPU0_SB_DQ<13>")
	)
	(segment
		(start 415.56559 -214.756746)
		(end 415.114486 -214.756746)
		(width 0.18288)
		(layer "In2.Cu")
		(net "M_F_CPU0_SB_DQ<13>")
	)
	(segment
		(start 409.650946 -213.920832)
		(end 409.089606 -214.482172)
		(width 0.18288)
		(layer "In2.Cu")
		(net "M_F_CPU0_SB_DQ<13>")
	)
	(segment
		(start 419.6334 -214.619332)
		(end 419.36035 -214.619332)
		(width 0.18288)
		(layer "In2.Cu")
		(net "M_F_CPU0_SB_DQ<13>")
	)
	(segment
		(start 412.86938 -213.663276)
		(end 412.378906 -214.15375)
		(width 0.18288)
		(layer "In2.Cu")
		(net "M_F_CPU0_SB_DQ<13>")
	)
	(segment
		(start 405.500332 -213.595458)
		(end 404.689056 -213.595458)
		(width 0.18288)
		(layer "In2.Cu")
		(net "M_F_CPU0_SB_DQ<13>")
	)
	(segment
		(start 394.800582 -223.821244)
		(end 394.471652 -224.150174)
		(width 0.18288)
		(layer "In2.Cu")
		(net "M_F_CPU0_SB_DQ<13>")
	)
	(segment
		(start 404.689056 -213.595458)
		(end 404.387812 -213.896702)
		(width 0.18288)
		(layer "In2.Cu")
		(net "M_F_CPU0_SB_DQ<13>")
	)
	(segment
		(start 397.119856 -221.164658)
		(end 396.790926 -221.493588)
		(width 0.18288)
		(layer "In2.Cu")
		(net "M_F_CPU0_SB_DQ<13>")
	)
	(segment
		(start 414.455102 -213.926674)
		(end 414.075626 -214.30615)
		(width 0.18288)
		(layer "In2.Cu")
		(net "M_F_CPU0_SB_DQ<13>")
	)
	(segment
		(start 420.18077 -215.166702)
		(end 419.6334 -214.619332)
		(width 0.18288)
		(layer "In2.Cu")
		(net "M_F_CPU0_SB_DQ<13>")
	)
	(segment
		(start 417.867592 -215.06307)
		(end 417.236148 -214.431626)
		(width 0.18288)
		(layer "In2.Cu")
		(net "M_F_CPU0_SB_DQ<13>")
	)
	(segment
		(start 386.929884 -226.831144)
		(end 386.929884 -226.84105)
		(width 0.088646)
		(layer "In2.Cu")
		(net "M_F_CPU0_SB_DQ<13>")
	)
	(segment
		(start 408.539696 -213.788498)
		(end 408.346656 -213.595458)
		(width 0.18288)
		(layer "In2.Cu")
		(net "M_F_CPU0_SB_DQ<13>")
	)
	(segment
		(start 394.471652 -224.150174)
		(end 394.13434 -224.150174)
		(width 0.18288)
		(layer "In2.Cu")
		(net "M_F_CPU0_SB_DQ<13>")
	)
	(segment
		(start 389.75411 -225.641916)
		(end 388.714742 -225.641916)
		(width 0.088646)
		(layer "In2.Cu")
		(net "M_F_CPU0_SB_DQ<13>")
	)
	(segment
		(start 414.921446 -214.563706)
		(end 414.921446 -214.119714)
		(width 0.18288)
		(layer "In2.Cu")
		(net "M_F_CPU0_SB_DQ<13>")
	)
	(segment
		(start 415.114486 -214.756746)
		(end 414.921446 -214.563706)
		(width 0.18288)
		(layer "In2.Cu")
		(net "M_F_CPU0_SB_DQ<13>")
	)
	(segment
		(start 382.894332 -228.944932)
		(end 382.888236 -228.948488)
		(width 0.088646)
		(layer "In2.Cu")
		(net "M_F_CPU0_SB_DQ<13>")
	)
	(segment
		(start 408.346656 -213.595458)
		(end 407.808938 -213.595458)
		(width 0.18288)
		(layer "In2.Cu")
		(net "M_F_CPU0_SB_DQ<13>")
	)
	(segment
		(start 419.36035 -214.619332)
		(end 418.916612 -215.06307)
		(width 0.18288)
		(layer "In2.Cu")
		(net "M_F_CPU0_SB_DQ<13>")
	)
	(segment
		(start 387.399784 -226.017328)
		(end 387.399784 -226.027234)
		(width 0.088646)
		(layer "In2.Cu")
		(net "M_F_CPU0_SB_DQ<13>")
	)
	(segment
		(start 393.80541 -224.479104)
		(end 393.80541 -224.816416)
		(width 0.18288)
		(layer "In2.Cu")
		(net "M_F_CPU0_SB_DQ<13>")
	)
	(segment
		(start 407.534364 -213.870032)
		(end 405.774906 -213.870032)
		(width 0.18288)
		(layer "In2.Cu")
		(net "M_F_CPU0_SB_DQ<13>")
	)
	(segment
		(start 404.387812 -213.896702)
		(end 404.387812 -214.095076)
		(width 0.18288)
		(layer "In2.Cu")
		(net "M_F_CPU0_SB_DQ<13>")
	)
	(segment
		(start 395.466824 -223.155002)
		(end 395.129512 -223.155002)
		(width 0.18288)
		(layer "In2.Cu")
		(net "M_F_CPU0_SB_DQ<13>")
	)
	(segment
		(start 394.800582 -223.483932)
		(end 394.800582 -223.821244)
		(width 0.18288)
		(layer "In2.Cu")
		(net "M_F_CPU0_SB_DQ<13>")
	)
	(segment
		(start 413.14243 -213.663276)
		(end 412.86938 -213.663276)
		(width 0.18288)
		(layer "In2.Cu")
		(net "M_F_CPU0_SB_DQ<13>")
	)
	(segment
		(start 383.640584 -227.64496)
		(end 383.640584 -227.663502)
		(width 0.088646)
		(layer "In2.Cu")
		(net "M_F_CPU0_SB_DQ<13>")
	)
	(segment
		(start 395.795754 -222.48876)
		(end 395.795754 -222.826072)
		(width 0.18288)
		(layer "In2.Cu")
		(net "M_F_CPU0_SB_DQ<13>")
	)
	(segment
		(start 415.89071 -214.431626)
		(end 415.56559 -214.756746)
		(width 0.18288)
		(layer "In2.Cu")
		(net "M_F_CPU0_SB_DQ<13>")
	)
	(segment
		(start 397.457168 -221.164658)
		(end 397.119856 -221.164658)
		(width 0.18288)
		(layer "In2.Cu")
		(net "M_F_CPU0_SB_DQ<13>")
	)
	(segment
		(start 404.281132 -214.783924)
		(end 403.50059 -214.783924)
		(width 0.18288)
		(layer "In2.Cu")
		(net "M_F_CPU0_SB_DQ<13>")
	)
	(segment
		(start 420.736014 -215.166702)
		(end 420.18077 -215.166702)
		(width 0.18288)
		(layer "In2.Cu")
		(net "M_F_CPU0_SB_DQ<13>")
	)
	(segment
		(start 417.236148 -214.431626)
		(end 415.89071 -214.431626)
		(width 0.18288)
		(layer "In2.Cu")
		(net "M_F_CPU0_SB_DQ<13>")
	)
	(segment
		(start 409.089606 -214.482172)
		(end 408.760422 -214.482172)
		(width 0.18288)
		(layer "In2.Cu")
		(net "M_F_CPU0_SB_DQ<13>")
	)
	(segment
		(start 381.978408 -228.45903)
		(end 381.665734 -228.45903)
		(width 0.088646)
		(layer "In2.Cu")
		(net "M_F_CPU0_SB_DQ<13>")
	)
	(segment
		(start 410.351986 -213.545928)
		(end 409.977082 -213.920832)
		(width 0.18288)
		(layer "In2.Cu")
		(net "M_F_CPU0_SB_DQ<13>")
	)
	(segment
		(start 404.548086 -214.51697)
		(end 404.281132 -214.783924)
		(width 0.18288)
		(layer "In2.Cu")
		(net "M_F_CPU0_SB_DQ<13>")
	)
	(segment
		(start 403.50059 -214.783924)
		(end 397.786098 -220.498416)
		(width 0.18288)
		(layer "In2.Cu")
		(net "M_F_CPU0_SB_DQ<13>")
	)
	(segment
		(start 395.795754 -222.826072)
		(end 395.466824 -223.155002)
		(width 0.18288)
		(layer "In2.Cu")
		(net "M_F_CPU0_SB_DQ<13>")
	)
	(segment
		(start 393.80541 -224.816416)
		(end 393.47648 -225.145346)
		(width 0.18288)
		(layer "In2.Cu")
		(net "M_F_CPU0_SB_DQ<13>")
	)
	(segment
		(start 397.786098 -220.498416)
		(end 397.786098 -220.835728)
		(width 0.18288)
		(layer "In2.Cu")
		(net "M_F_CPU0_SB_DQ<13>")
	)
	(segment
		(start 414.728406 -213.926674)
		(end 414.455102 -213.926674)
		(width 0.18288)
		(layer "In2.Cu")
		(net "M_F_CPU0_SB_DQ<13>")
	)
	(segment
		(start 413.785304 -214.30615)
		(end 413.14243 -213.663276)
		(width 0.18288)
		(layer "In2.Cu")
		(net "M_F_CPU0_SB_DQ<13>")
	)
	(arc
		(start 386.082032 -227.320602)
		(mid 385.894834 -227.270459)
		(end 385.707636 -227.320602)
		(width 0.088646)
		(layer "In2.Cu")
		(net "M_F_CPU0_SB_DQ<13>")
	)
	(arc
		(start 382.888236 -228.948488)
		(mid 382.614037 -229.024323)
		(end 382.337564 -228.957124)
		(width 0.088646)
		(layer "In2.Cu")
		(net "M_F_CPU0_SB_DQ<13>")
	)
	(arc
		(start 383.640584 -227.663502)
		(mid 383.560422 -227.935691)
		(end 383.358136 -228.134672)
		(width 0.088646)
		(layer "In2.Cu")
		(net "M_F_CPU0_SB_DQ<13>")
	)
	(arc
		(start 387.578346 -225.69805)
		(mid 387.447432 -225.83441)
		(end 387.399784 -226.017328)
		(width 0.088646)
		(layer "In2.Cu")
		(net "M_F_CPU0_SB_DQ<13>")
	)
	(arc
		(start 385.142232 -227.320602)
		(mid 384.955034 -227.270459)
		(end 384.767836 -227.320602)
		(width 0.088646)
		(layer "In2.Cu")
		(net "M_F_CPU0_SB_DQ<13>")
	)
	(arc
		(start 383.819146 -227.325682)
		(mid 383.688232 -227.462042)
		(end 383.640584 -227.64496)
		(width 0.088646)
		(layer "In2.Cu")
		(net "M_F_CPU0_SB_DQ<13>")
	)
	(arc
		(start 388.714742 -225.641916)
		(mid 388.61753 -225.65508)
		(end 388.527036 -225.69297)
		(width 0.088646)
		(layer "In2.Cu")
		(net "M_F_CPU0_SB_DQ<13>")
	)
	(arc
		(start 387.399784 -226.027234)
		(mid 387.321673 -226.304183)
		(end 387.117336 -226.506786)
		(width 0.088646)
		(layer "In2.Cu")
		(net "M_F_CPU0_SB_DQ<13>")
	)
	(arc
		(start 382.316736 -228.944932)
		(mid 382.131213 -228.766631)
		(end 382.04394 -228.524562)
		(width 0.088646)
		(layer "In2.Cu")
		(net "M_F_CPU0_SB_DQ<13>")
	)
	(arc
		(start 388.527036 -225.69297)
		(mid 388.244334 -225.768712)
		(end 387.961632 -225.69297)
		(width 0.088646)
		(layer "In2.Cu")
		(net "M_F_CPU0_SB_DQ<13>")
	)
	(arc
		(start 383.170684 -228.45903)
		(mid 383.096768 -228.738532)
		(end 382.894332 -228.944932)
		(width 0.088646)
		(layer "In2.Cu")
		(net "M_F_CPU0_SB_DQ<13>")
	)
	(arc
		(start 386.647436 -227.320602)
		(mid 386.364734 -227.396378)
		(end 386.082032 -227.320602)
		(width 0.088646)
		(layer "In2.Cu")
		(net "M_F_CPU0_SB_DQ<13>")
	)
	(arc
		(start 383.349246 -228.139752)
		(mid 383.218332 -228.276112)
		(end 383.170684 -228.45903)
		(width 0.088646)
		(layer "In2.Cu")
		(net "M_F_CPU0_SB_DQ<13>")
	)
	(arc
		(start 384.202432 -227.320602)
		(mid 384.015234 -227.270459)
		(end 383.828036 -227.320602)
		(width 0.088646)
		(layer "In2.Cu")
		(net "M_F_CPU0_SB_DQ<13>")
	)
	(arc
		(start 387.108446 -226.511866)
		(mid 386.977532 -226.648226)
		(end 386.929884 -226.831144)
		(width 0.088646)
		(layer "In2.Cu")
		(net "M_F_CPU0_SB_DQ<13>")
	)
	(arc
		(start 386.929884 -226.84105)
		(mid 386.851773 -227.117999)
		(end 386.647436 -227.320602)
		(width 0.088646)
		(layer "In2.Cu")
		(net "M_F_CPU0_SB_DQ<13>")
	)
	(arc
		(start 387.961632 -225.69297)
		(mid 387.774434 -225.642827)
		(end 387.587236 -225.69297)
		(width 0.088646)
		(layer "In2.Cu")
		(net "M_F_CPU0_SB_DQ<13>")
	)
	(arc
		(start 384.767836 -227.320602)
		(mid 384.485134 -227.396378)
		(end 384.202432 -227.320602)
		(width 0.088646)
		(layer "In2.Cu")
		(net "M_F_CPU0_SB_DQ<13>")
	)
	(arc
		(start 385.707636 -227.320602)
		(mid 385.424934 -227.396378)
		(end 385.142232 -227.320602)
		(width 0.088646)
		(layer "In2.Cu")
		(net "M_F_CPU0_SB_DQ<13>")
	)
	(segment
		(start 426.945044 -216.441782)
		(end 424.78325 -216.441782)
		(width 0.1016)
		(layer "F.Cu")
		(net "M_F_CPU0_SB_DQ<12>")
	)
	(segment
		(start 424.085512 -217.11539)
		(end 423.610278 -217.11539)
		(width 0.20066)
		(layer "F.Cu")
		(net "M_F_CPU0_SB_DQ<12>")
	)
	(segment
		(start 381.19558 -229.808786)
		(end 381.195834 -229.808532)
		(width 0.20066)
		(layer "F.Cu")
		(net "M_F_CPU0_SB_DQ<12>")
	)
	(segment
		(start 429.38446 -216.866978)
		(end 427.792896 -216.866978)
		(width 0.20066)
		(layer "F.Cu")
		(net "M_F_CPU0_SB_DQ<12>")
	)
	(segment
		(start 429.384714 -216.866724)
		(end 429.38446 -216.866978)
		(width 0.20066)
		(layer "F.Cu")
		(net "M_F_CPU0_SB_DQ<12>")
	)
	(segment
		(start 424.391582 -216.441782)
		(end 424.273472 -216.559892)
		(width 0.20066)
		(layer "F.Cu")
		(net "M_F_CPU0_SB_DQ<12>")
	)
	(segment
		(start 424.73626 -216.441782)
		(end 424.391582 -216.441782)
		(width 0.20066)
		(layer "F.Cu")
		(net "M_F_CPU0_SB_DQ<12>")
	)
	(segment
		(start 424.78325 -216.441782)
		(end 424.73626 -216.441782)
		(width 0.101854)
		(layer "F.Cu")
		(net "M_F_CPU0_SB_DQ<12>")
	)
	(segment
		(start 426.951394 -216.435432)
		(end 426.945044 -216.441782)
		(width 0.1016)
		(layer "F.Cu")
		(net "M_F_CPU0_SB_DQ<12>")
	)
	(segment
		(start 381.195834 -229.808532)
		(end 381.195834 -229.272846)
		(width 0.20066)
		(layer "F.Cu")
		(net "M_F_CPU0_SB_DQ<12>")
	)
	(segment
		(start 427.792896 -216.866978)
		(end 427.36135 -216.435432)
		(width 0.20066)
		(layer "F.Cu")
		(net "M_F_CPU0_SB_DQ<12>")
	)
	(segment
		(start 424.273472 -216.92743)
		(end 424.085512 -217.11539)
		(width 0.20066)
		(layer "F.Cu")
		(net "M_F_CPU0_SB_DQ<12>")
	)
	(segment
		(start 421.840914 -216.866724)
		(end 420.736014 -216.866724)
		(width 0.20066)
		(layer "F.Cu")
		(net "M_F_CPU0_SB_DQ<12>")
	)
	(segment
		(start 424.273472 -216.559892)
		(end 424.273472 -216.92743)
		(width 0.20066)
		(layer "F.Cu")
		(net "M_F_CPU0_SB_DQ<12>")
	)
	(segment
		(start 423.610278 -217.11539)
		(end 423.361612 -216.866724)
		(width 0.20066)
		(layer "F.Cu")
		(net "M_F_CPU0_SB_DQ<12>")
	)
	(segment
		(start 427.36135 -216.435432)
		(end 426.951394 -216.435432)
		(width 0.20066)
		(layer "F.Cu")
		(net "M_F_CPU0_SB_DQ<12>")
	)
	(segment
		(start 423.361612 -216.866724)
		(end 421.840914 -216.866724)
		(width 0.20066)
		(layer "F.Cu")
		(net "M_F_CPU0_SB_DQ<12>")
	)
	(segment
		(start 403.698964 -216.022936)
		(end 403.698964 -216.295732)
		(width 0.18288)
		(layer "In2.Cu")
		(net "M_F_CPU0_SB_DQ<12>")
	)
	(segment
		(start 400.842734 -219.389198)
		(end 400.842734 -219.66174)
		(width 0.18288)
		(layer "In2.Cu")
		(net "M_F_CPU0_SB_DQ<12>")
	)
	(segment
		(start 416.005264 -216.10447)
		(end 416.005264 -216.459562)
		(width 0.18288)
		(layer "In2.Cu")
		(net "M_F_CPU0_SB_DQ<12>")
	)
	(segment
		(start 393.352782 -226.706684)
		(end 388.662418 -226.706684)
		(width 0.18288)
		(layer "In2.Cu")
		(net "M_F_CPU0_SB_DQ<12>")
	)
	(segment
		(start 404.31339 -215.918288)
		(end 404.194772 -215.799924)
		(width 0.18288)
		(layer "In2.Cu")
		(net "M_F_CPU0_SB_DQ<12>")
	)
	(segment
		(start 403.817582 -216.686892)
		(end 403.59457 -216.909904)
		(width 0.18288)
		(layer "In2.Cu")
		(net "M_F_CPU0_SB_DQ<12>")
	)
	(segment
		(start 402.825966 -217.405966)
		(end 402.825966 -217.678508)
		(width 0.18288)
		(layer "In2.Cu")
		(net "M_F_CPU0_SB_DQ<12>")
	)
	(segment
		(start 405.678386 -215.26119)
		(end 405.243284 -215.26119)
		(width 0.18288)
		(layer "In2.Cu")
		(net "M_F_CPU0_SB_DQ<12>")
	)
	(segment
		(start 412.938722 -216.489026)
		(end 412.24073 -215.791034)
		(width 0.18288)
		(layer "In2.Cu")
		(net "M_F_CPU0_SB_DQ<12>")
	)
	(segment
		(start 402.21154 -217.783156)
		(end 401.938744 -217.783156)
		(width 0.18288)
		(layer "In2.Cu")
		(net "M_F_CPU0_SB_DQ<12>")
	)
	(segment
		(start 401.338542 -218.893136)
		(end 401.219924 -218.774772)
		(width 0.18288)
		(layer "In2.Cu")
		(net "M_F_CPU0_SB_DQ<12>")
	)
	(segment
		(start 402.707348 -217.287348)
		(end 402.825966 -217.405966)
		(width 0.18288)
		(layer "In2.Cu")
		(net "M_F_CPU0_SB_DQ<12>")
	)
	(segment
		(start 399.088356 -220.97111)
		(end 393.352782 -226.706684)
		(width 0.18288)
		(layer "In2.Cu")
		(net "M_F_CPU0_SB_DQ<12>")
	)
	(segment
		(start 416.165284 -215.94445)
		(end 416.005264 -216.10447)
		(width 0.18288)
		(layer "In2.Cu")
		(net "M_F_CPU0_SB_DQ<12>")
	)
	(segment
		(start 411.944566 -215.791034)
		(end 411.46222 -215.308688)
		(width 0.18288)
		(layer "In2.Cu")
		(net "M_F_CPU0_SB_DQ<12>")
	)
	(segment
		(start 383.486152 -229.403148)
		(end 383.385822 -229.503478)
		(width 0.088646)
		(layer "In2.Cu")
		(net "M_F_CPU0_SB_DQ<12>")
	)
	(segment
		(start 404.586186 -215.918288)
		(end 404.31339 -215.918288)
		(width 0.18288)
		(layer "In2.Cu")
		(net "M_F_CPU0_SB_DQ<12>")
	)
	(segment
		(start 401.938744 -217.783156)
		(end 401.715732 -218.006168)
		(width 0.18288)
		(layer "In2.Cu")
		(net "M_F_CPU0_SB_DQ<12>")
	)
	(segment
		(start 403.817582 -216.41435)
		(end 403.817582 -216.686892)
		(width 0.18288)
		(layer "In2.Cu")
		(net "M_F_CPU0_SB_DQ<12>")
	)
	(segment
		(start 381.695452 -229.460044)
		(end 381.195834 -229.272846)
		(width 0.088646)
		(layer "In2.Cu")
		(net "M_F_CPU0_SB_DQ<12>")
	)
	(segment
		(start 403.203156 -216.79154)
		(end 402.93036 -216.79154)
		(width 0.18288)
		(layer "In2.Cu")
		(net "M_F_CPU0_SB_DQ<12>")
	)
	(segment
		(start 388.662418 -226.706684)
		(end 388.11581 -227.253292)
		(width 0.18288)
		(layer "In2.Cu")
		(net "M_F_CPU0_SB_DQ<12>")
	)
	(segment
		(start 401.83435 -218.670124)
		(end 401.611338 -218.893136)
		(width 0.18288)
		(layer "In2.Cu")
		(net "M_F_CPU0_SB_DQ<12>")
	)
	(segment
		(start 382.893824 -229.600506)
		(end 382.887982 -229.597204)
		(width 0.088646)
		(layer "In2.Cu")
		(net "M_F_CPU0_SB_DQ<12>")
	)
	(segment
		(start 416.005264 -216.459562)
		(end 415.812224 -216.652602)
		(width 0.18288)
		(layer "In2.Cu")
		(net "M_F_CPU0_SB_DQ<12>")
	)
	(segment
		(start 401.611338 -218.893136)
		(end 401.338542 -218.893136)
		(width 0.18288)
		(layer "In2.Cu")
		(net "M_F_CPU0_SB_DQ<12>")
	)
	(segment
		(start 420.078916 -216.209626)
		(end 419.547294 -216.209626)
		(width 0.18288)
		(layer "In2.Cu")
		(net "M_F_CPU0_SB_DQ<12>")
	)
	(segment
		(start 388.11581 -227.253292)
		(end 387.618986 -227.750116)
		(width 0.088646)
		(layer "In2.Cu")
		(net "M_F_CPU0_SB_DQ<12>")
	)
	(segment
		(start 404.194772 -215.799924)
		(end 403.921976 -215.799924)
		(width 0.18288)
		(layer "In2.Cu")
		(net "M_F_CPU0_SB_DQ<12>")
	)
	(segment
		(start 399.7325 -220.262196)
		(end 399.851118 -220.380814)
		(width 0.18288)
		(layer "In2.Cu")
		(net "M_F_CPU0_SB_DQ<12>")
	)
	(segment
		(start 416.490404 -215.94445)
		(end 416.165284 -215.94445)
		(width 0.18288)
		(layer "In2.Cu")
		(net "M_F_CPU0_SB_DQ<12>")
	)
	(segment
		(start 407.75763 -215.54821)
		(end 405.965406 -215.54821)
		(width 0.18288)
		(layer "In2.Cu")
		(net "M_F_CPU0_SB_DQ<12>")
	)
	(segment
		(start 382.887982 -229.597204)
		(end 382.88341 -229.59441)
		(width 0.088646)
		(layer "In2.Cu")
		(net "M_F_CPU0_SB_DQ<12>")
	)
	(segment
		(start 401.715732 -218.006168)
		(end 401.715732 -218.278964)
		(width 0.18288)
		(layer "In2.Cu")
		(net "M_F_CPU0_SB_DQ<12>")
	)
	(segment
		(start 403.59457 -216.909904)
		(end 403.321774 -216.909904)
		(width 0.18288)
		(layer "In2.Cu")
		(net "M_F_CPU0_SB_DQ<12>")
	)
	(segment
		(start 412.24073 -215.791034)
		(end 411.944566 -215.791034)
		(width 0.18288)
		(layer "In2.Cu")
		(net "M_F_CPU0_SB_DQ<12>")
	)
	(segment
		(start 384.297936 -228.134672)
		(end 384.289046 -228.139752)
		(width 0.088646)
		(layer "In2.Cu")
		(net "M_F_CPU0_SB_DQ<12>")
	)
	(segment
		(start 402.93036 -216.79154)
		(end 402.707348 -217.014552)
		(width 0.18288)
		(layer "In2.Cu")
		(net "M_F_CPU0_SB_DQ<12>")
	)
	(segment
		(start 401.715732 -218.278964)
		(end 401.83435 -218.397582)
		(width 0.18288)
		(layer "In2.Cu")
		(net "M_F_CPU0_SB_DQ<12>")
	)
	(segment
		(start 407.824178 -215.481662)
		(end 407.75763 -215.54821)
		(width 0.18288)
		(layer "In2.Cu")
		(net "M_F_CPU0_SB_DQ<12>")
	)
	(segment
		(start 405.965406 -215.54821)
		(end 405.678386 -215.26119)
		(width 0.18288)
		(layer "In2.Cu")
		(net "M_F_CPU0_SB_DQ<12>")
	)
	(segment
		(start 408.761184 -215.930988)
		(end 408.311858 -215.481662)
		(width 0.18288)
		(layer "In2.Cu")
		(net "M_F_CPU0_SB_DQ<12>")
	)
	(segment
		(start 411.46222 -215.308688)
		(end 410.264864 -215.308688)
		(width 0.18288)
		(layer "In2.Cu")
		(net "M_F_CPU0_SB_DQ<12>")
	)
	(segment
		(start 399.955512 -219.766388)
		(end 399.7325 -219.9894)
		(width 0.18288)
		(layer "In2.Cu")
		(net "M_F_CPU0_SB_DQ<12>")
	)
	(segment
		(start 415.408364 -216.652602)
		(end 414.957006 -216.201244)
		(width 0.18288)
		(layer "In2.Cu")
		(net "M_F_CPU0_SB_DQ<12>")
	)
	(segment
		(start 384.110484 -228.45903)
		(end 384.110484 -228.468936)
		(width 0.088646)
		(layer "In2.Cu")
		(net "M_F_CPU0_SB_DQ<12>")
	)
	(segment
		(start 399.533364 -220.97111)
		(end 399.088356 -220.97111)
		(width 0.18288)
		(layer "In2.Cu")
		(net "M_F_CPU0_SB_DQ<12>")
	)
	(segment
		(start 413.671766 -216.201244)
		(end 413.383984 -216.489026)
		(width 0.18288)
		(layer "In2.Cu")
		(net "M_F_CPU0_SB_DQ<12>")
	)
	(segment
		(start 415.812224 -216.652602)
		(end 415.408364 -216.652602)
		(width 0.18288)
		(layer "In2.Cu")
		(net "M_F_CPU0_SB_DQ<12>")
	)
	(segment
		(start 405.243284 -215.26119)
		(end 404.586186 -215.918288)
		(width 0.18288)
		(layer "In2.Cu")
		(net "M_F_CPU0_SB_DQ<12>")
	)
	(segment
		(start 419.547294 -216.209626)
		(end 419.37305 -216.38387)
		(width 0.18288)
		(layer "In2.Cu")
		(net "M_F_CPU0_SB_DQ<12>")
	)
	(segment
		(start 381.948182 -229.597204)
		(end 381.775716 -229.49789)
		(width 0.088646)
		(layer "In2.Cu")
		(net "M_F_CPU0_SB_DQ<12>")
	)
	(segment
		(start 400.947128 -218.774772)
		(end 400.724116 -218.997784)
		(width 0.18288)
		(layer "In2.Cu")
		(net "M_F_CPU0_SB_DQ<12>")
	)
	(segment
		(start 414.957006 -216.201244)
		(end 413.671766 -216.201244)
		(width 0.18288)
		(layer "In2.Cu")
		(net "M_F_CPU0_SB_DQ<12>")
	)
	(segment
		(start 403.698964 -216.295732)
		(end 403.817582 -216.41435)
		(width 0.18288)
		(layer "In2.Cu")
		(net "M_F_CPU0_SB_DQ<12>")
	)
	(segment
		(start 419.37305 -216.38387)
		(end 416.929824 -216.38387)
		(width 0.18288)
		(layer "In2.Cu")
		(net "M_F_CPU0_SB_DQ<12>")
	)
	(segment
		(start 400.346926 -219.884752)
		(end 400.228308 -219.766388)
		(width 0.18288)
		(layer "In2.Cu")
		(net "M_F_CPU0_SB_DQ<12>")
	)
	(segment
		(start 403.321774 -216.909904)
		(end 403.203156 -216.79154)
		(width 0.18288)
		(layer "In2.Cu")
		(net "M_F_CPU0_SB_DQ<12>")
	)
	(segment
		(start 383.26695 -229.594664)
		(end 383.262632 -229.597204)
		(width 0.088646)
		(layer "In2.Cu")
		(net "M_F_CPU0_SB_DQ<12>")
	)
	(segment
		(start 402.707348 -217.014552)
		(end 402.707348 -217.287348)
		(width 0.18288)
		(layer "In2.Cu")
		(net "M_F_CPU0_SB_DQ<12>")
	)
	(segment
		(start 400.724116 -218.997784)
		(end 400.724116 -219.27058)
		(width 0.18288)
		(layer "In2.Cu")
		(net "M_F_CPU0_SB_DQ<12>")
	)
	(segment
		(start 420.736014 -216.866724)
		(end 420.078916 -216.209626)
		(width 0.18288)
		(layer "In2.Cu")
		(net "M_F_CPU0_SB_DQ<12>")
	)
	(segment
		(start 383.828036 -228.948488)
		(end 383.827782 -228.948742)
		(width 0.088646)
		(layer "In2.Cu")
		(net "M_F_CPU0_SB_DQ<12>")
	)
	(segment
		(start 408.311858 -215.481662)
		(end 407.824178 -215.481662)
		(width 0.18288)
		(layer "In2.Cu")
		(net "M_F_CPU0_SB_DQ<12>")
	)
	(segment
		(start 401.83435 -218.397582)
		(end 401.83435 -218.670124)
		(width 0.18288)
		(layer "In2.Cu")
		(net "M_F_CPU0_SB_DQ<12>")
	)
	(segment
		(start 399.851118 -220.380814)
		(end 399.851118 -220.653356)
		(width 0.18288)
		(layer "In2.Cu")
		(net "M_F_CPU0_SB_DQ<12>")
	)
	(segment
		(start 402.825966 -217.678508)
		(end 402.602954 -217.90152)
		(width 0.18288)
		(layer "In2.Cu")
		(net "M_F_CPU0_SB_DQ<12>")
	)
	(segment
		(start 399.7325 -219.9894)
		(end 399.7325 -220.262196)
		(width 0.18288)
		(layer "In2.Cu")
		(net "M_F_CPU0_SB_DQ<12>")
	)
	(segment
		(start 409.642564 -215.930988)
		(end 408.761184 -215.930988)
		(width 0.18288)
		(layer "In2.Cu")
		(net "M_F_CPU0_SB_DQ<12>")
	)
	(segment
		(start 403.921976 -215.799924)
		(end 403.698964 -216.022936)
		(width 0.18288)
		(layer "In2.Cu")
		(net "M_F_CPU0_SB_DQ<12>")
	)
	(segment
		(start 401.219924 -218.774772)
		(end 400.947128 -218.774772)
		(width 0.18288)
		(layer "In2.Cu")
		(net "M_F_CPU0_SB_DQ<12>")
	)
	(segment
		(start 400.228308 -219.766388)
		(end 399.955512 -219.766388)
		(width 0.18288)
		(layer "In2.Cu")
		(net "M_F_CPU0_SB_DQ<12>")
	)
	(segment
		(start 410.264864 -215.308688)
		(end 409.642564 -215.930988)
		(width 0.18288)
		(layer "In2.Cu")
		(net "M_F_CPU0_SB_DQ<12>")
	)
	(segment
		(start 413.383984 -216.489026)
		(end 412.938722 -216.489026)
		(width 0.18288)
		(layer "In2.Cu")
		(net "M_F_CPU0_SB_DQ<12>")
	)
	(segment
		(start 399.851118 -220.653356)
		(end 399.533364 -220.97111)
		(width 0.18288)
		(layer "In2.Cu")
		(net "M_F_CPU0_SB_DQ<12>")
	)
	(segment
		(start 400.619722 -219.884752)
		(end 400.346926 -219.884752)
		(width 0.18288)
		(layer "In2.Cu")
		(net "M_F_CPU0_SB_DQ<12>")
	)
	(segment
		(start 416.929824 -216.38387)
		(end 416.490404 -215.94445)
		(width 0.18288)
		(layer "In2.Cu")
		(net "M_F_CPU0_SB_DQ<12>")
	)
	(segment
		(start 400.842734 -219.66174)
		(end 400.619722 -219.884752)
		(width 0.18288)
		(layer "In2.Cu")
		(net "M_F_CPU0_SB_DQ<12>")
	)
	(segment
		(start 400.724116 -219.27058)
		(end 400.842734 -219.389198)
		(width 0.18288)
		(layer "In2.Cu")
		(net "M_F_CPU0_SB_DQ<12>")
	)
	(segment
		(start 383.660396 -229.152958)
		(end 383.486152 -229.403148)
		(width 0.088646)
		(layer "In2.Cu")
		(net "M_F_CPU0_SB_DQ<12>")
	)
	(segment
		(start 402.330158 -217.90152)
		(end 402.21154 -217.783156)
		(width 0.18288)
		(layer "In2.Cu")
		(net "M_F_CPU0_SB_DQ<12>")
	)
	(segment
		(start 402.602954 -217.90152)
		(end 402.330158 -217.90152)
		(width 0.18288)
		(layer "In2.Cu")
		(net "M_F_CPU0_SB_DQ<12>")
	)
	(arc
		(start 384.672332 -228.134672)
		(mid 384.485134 -228.084529)
		(end 384.297936 -228.134672)
		(width 0.088646)
		(layer "In2.Cu")
		(net "M_F_CPU0_SB_DQ<12>")
	)
	(arc
		(start 386.177536 -228.134672)
		(mid 385.894834 -228.210414)
		(end 385.612132 -228.134672)
		(width 0.088646)
		(layer "In2.Cu")
		(net "M_F_CPU0_SB_DQ<12>")
	)
	(arc
		(start 382.88341 -229.59441)
		(mid 382.602746 -229.521402)
		(end 382.322832 -229.597204)
		(width 0.088646)
		(layer "In2.Cu")
		(net "M_F_CPU0_SB_DQ<12>")
	)
	(arc
		(start 383.827782 -228.948742)
		(mid 383.725432 -229.035569)
		(end 383.660396 -229.152958)
		(width 0.088646)
		(layer "In2.Cu")
		(net "M_F_CPU0_SB_DQ<12>")
	)
	(arc
		(start 381.775716 -229.49789)
		(mid 381.736355 -229.477333)
		(end 381.695452 -229.460044)
		(width 0.088646)
		(layer "In2.Cu")
		(net "M_F_CPU0_SB_DQ<12>")
	)
	(arc
		(start 386.551932 -228.134672)
		(mid 386.364734 -228.084529)
		(end 386.177536 -228.134672)
		(width 0.088646)
		(layer "In2.Cu")
		(net "M_F_CPU0_SB_DQ<12>")
	)
	(arc
		(start 384.110484 -228.468936)
		(mid 384.032373 -228.745885)
		(end 383.828036 -228.948488)
		(width 0.088646)
		(layer "In2.Cu")
		(net "M_F_CPU0_SB_DQ<12>")
	)
	(arc
		(start 382.322832 -229.597204)
		(mid 382.135524 -229.647347)
		(end 381.948182 -229.597204)
		(width 0.088646)
		(layer "In2.Cu")
		(net "M_F_CPU0_SB_DQ<12>")
	)
	(arc
		(start 387.618986 -227.750116)
		(mid 387.380818 -227.958907)
		(end 387.117336 -228.134672)
		(width 0.088646)
		(layer "In2.Cu")
		(net "M_F_CPU0_SB_DQ<12>")
	)
	(arc
		(start 385.237736 -228.134672)
		(mid 384.955034 -228.210414)
		(end 384.672332 -228.134672)
		(width 0.088646)
		(layer "In2.Cu")
		(net "M_F_CPU0_SB_DQ<12>")
	)
	(arc
		(start 385.612132 -228.134672)
		(mid 385.424934 -228.084529)
		(end 385.237736 -228.134672)
		(width 0.088646)
		(layer "In2.Cu")
		(net "M_F_CPU0_SB_DQ<12>")
	)
	(arc
		(start 384.289046 -228.139752)
		(mid 384.158132 -228.276112)
		(end 384.110484 -228.45903)
		(width 0.088646)
		(layer "In2.Cu")
		(net "M_F_CPU0_SB_DQ<12>")
	)
	(arc
		(start 383.385822 -229.503478)
		(mid 383.329389 -229.552987)
		(end 383.26695 -229.594664)
		(width 0.088646)
		(layer "In2.Cu")
		(net "M_F_CPU0_SB_DQ<12>")
	)
	(arc
		(start 383.262632 -229.597204)
		(mid 383.078678 -229.647333)
		(end 382.893824 -229.600506)
		(width 0.088646)
		(layer "In2.Cu")
		(net "M_F_CPU0_SB_DQ<12>")
	)
	(arc
		(start 387.117336 -228.134672)
		(mid 386.834634 -228.210414)
		(end 386.551932 -228.134672)
		(width 0.088646)
		(layer "In2.Cu")
		(net "M_F_CPU0_SB_DQ<12>")
	)
	(segment
		(start 427.639226 -220.266768)
		(end 428.07128 -220.698822)
		(width 0.20066)
		(layer "F.Cu")
		(net "M_F_CPU0_SB_DQ<11>")
	)
	(segment
		(start 383.07518 -231.436418)
		(end 383.07518 -230.900732)
		(width 0.20066)
		(layer "F.Cu")
		(net "M_F_CPU0_SB_DQ<11>")
	)
	(segment
		(start 428.07128 -220.698822)
		(end 428.363126 -220.698822)
		(width 0.20066)
		(layer "F.Cu")
		(net "M_F_CPU0_SB_DQ<11>")
	)
	(segment
		(start 424.836082 -220.266768)
		(end 425.940982 -220.266768)
		(width 0.20066)
		(layer "F.Cu")
		(net "M_F_CPU0_SB_DQ<11>")
	)
	(segment
		(start 431.280316 -220.49994)
		(end 431.280316 -220.248988)
		(width 0.20066)
		(layer "F.Cu")
		(net "M_F_CPU0_SB_DQ<11>")
	)
	(segment
		(start 428.367952 -220.698822)
		(end 428.375064 -220.69171)
		(width 0.1016)
		(layer "F.Cu")
		(net "M_F_CPU0_SB_DQ<11>")
	)
	(segment
		(start 425.940982 -220.266768)
		(end 427.639226 -220.266768)
		(width 0.20066)
		(layer "F.Cu")
		(net "M_F_CPU0_SB_DQ<11>")
	)
	(segment
		(start 430.395126 -220.703902)
		(end 431.076354 -220.703902)
		(width 0.20066)
		(layer "F.Cu")
		(net "M_F_CPU0_SB_DQ<11>")
	)
	(segment
		(start 431.076354 -220.703902)
		(end 431.280316 -220.49994)
		(width 0.20066)
		(layer "F.Cu")
		(net "M_F_CPU0_SB_DQ<11>")
	)
	(segment
		(start 431.280316 -220.248988)
		(end 431.514504 -220.0148)
		(width 0.20066)
		(layer "F.Cu")
		(net "M_F_CPU0_SB_DQ<11>")
	)
	(segment
		(start 431.514504 -220.0148)
		(end 431.898552 -220.0148)
		(width 0.20066)
		(layer "F.Cu")
		(net "M_F_CPU0_SB_DQ<11>")
	)
	(segment
		(start 383.07518 -230.900732)
		(end 383.075434 -230.900478)
		(width 0.20066)
		(layer "F.Cu")
		(net "M_F_CPU0_SB_DQ<11>")
	)
	(segment
		(start 428.375064 -220.69171)
		(end 430.382934 -220.69171)
		(width 0.1016)
		(layer "F.Cu")
		(net "M_F_CPU0_SB_DQ<11>")
	)
	(segment
		(start 430.382934 -220.69171)
		(end 430.395126 -220.703902)
		(width 0.1016)
		(layer "F.Cu")
		(net "M_F_CPU0_SB_DQ<11>")
	)
	(segment
		(start 428.363126 -220.698822)
		(end 428.367952 -220.698822)
		(width 0.101854)
		(layer "F.Cu")
		(net "M_F_CPU0_SB_DQ<11>")
	)
	(segment
		(start 431.898552 -220.0148)
		(end 432.15052 -220.266768)
		(width 0.20066)
		(layer "F.Cu")
		(net "M_F_CPU0_SB_DQ<11>")
	)
	(segment
		(start 432.15052 -220.266768)
		(end 433.484782 -220.266768)
		(width 0.20066)
		(layer "F.Cu")
		(net "M_F_CPU0_SB_DQ<11>")
	)
	(segment
		(start 408.790648 -220.01988)
		(end 408.625294 -219.854526)
		(width 0.18288)
		(layer "In2.Cu")
		(net "M_F_CPU0_SB_DQ<11>")
	)
	(segment
		(start 405.197564 -219.42552)
		(end 404.23084 -220.392244)
		(width 0.18288)
		(layer "In2.Cu")
		(net "M_F_CPU0_SB_DQ<11>")
	)
	(segment
		(start 403.74316 -221.528132)
		(end 402.117052 -221.528132)
		(width 0.18288)
		(layer "In2.Cu")
		(net "M_F_CPU0_SB_DQ<11>")
	)
	(segment
		(start 383.665222 -231.133142)
		(end 383.506726 -231.09047)
		(width 0.088646)
		(layer "In2.Cu")
		(net "M_F_CPU0_SB_DQ<11>")
	)
	(segment
		(start 385.151122 -231.219756)
		(end 385.142232 -231.224836)
		(width 0.088646)
		(layer "In2.Cu")
		(net "M_F_CPU0_SB_DQ<11>")
	)
	(segment
		(start 424.078146 -221.226888)
		(end 423.884852 -221.420182)
		(width 0.18288)
		(layer "In2.Cu")
		(net "M_F_CPU0_SB_DQ<11>")
	)
	(segment
		(start 422.757346 -220.689932)
		(end 422.2242 -220.689932)
		(width 0.18288)
		(layer "In2.Cu")
		(net "M_F_CPU0_SB_DQ<11>")
	)
	(segment
		(start 419.877494 -220.070426)
		(end 419.445694 -220.070426)
		(width 0.18288)
		(layer "In2.Cu")
		(net "M_F_CPU0_SB_DQ<11>")
	)
	(segment
		(start 412.56966 -220.661992)
		(end 409.873196 -220.661992)
		(width 0.18288)
		(layer "In2.Cu")
		(net "M_F_CPU0_SB_DQ<11>")
	)
	(segment
		(start 388.179564 -230.335328)
		(end 387.774434 -230.335328)
		(width 0.088646)
		(layer "In2.Cu")
		(net "M_F_CPU0_SB_DQ<11>")
	)
	(segment
		(start 415.35604 -220.768672)
		(end 415.259266 -220.671898)
		(width 0.18288)
		(layer "In2.Cu")
		(net "M_F_CPU0_SB_DQ<11>")
	)
	(segment
		(start 394.35786 -229.287324)
		(end 389.61949 -229.287324)
		(width 0.18288)
		(layer "In2.Cu")
		(net "M_F_CPU0_SB_DQ<11>")
	)
	(segment
		(start 407.888694 -219.241878)
		(end 407.888694 -219.511626)
		(width 0.18288)
		(layer "In2.Cu")
		(net "M_F_CPU0_SB_DQ<11>")
	)
	(segment
		(start 404.23084 -221.040452)
		(end 403.74316 -221.528132)
		(width 0.18288)
		(layer "In2.Cu")
		(net "M_F_CPU0_SB_DQ<11>")
	)
	(segment
		(start 385.329684 -230.890572)
		(end 385.329684 -230.900478)
		(width 0.088646)
		(layer "In2.Cu")
		(net "M_F_CPU0_SB_DQ<11>")
	)
	(segment
		(start 409.231084 -220.01988)
		(end 408.790648 -220.01988)
		(width 0.18288)
		(layer "In2.Cu")
		(net "M_F_CPU0_SB_DQ<11>")
	)
	(segment
		(start 407.530808 -219.869512)
		(end 405.91486 -219.869512)
		(width 0.18288)
		(layer "In2.Cu")
		(net "M_F_CPU0_SB_DQ<11>")
	)
	(segment
		(start 423.487596 -221.420182)
		(end 422.757346 -220.689932)
		(width 0.18288)
		(layer "In2.Cu")
		(net "M_F_CPU0_SB_DQ<11>")
	)
	(segment
		(start 424.214798 -220.266768)
		(end 424.078146 -220.40342)
		(width 0.18288)
		(layer "In2.Cu")
		(net "M_F_CPU0_SB_DQ<11>")
	)
	(segment
		(start 424.836082 -220.266768)
		(end 424.214798 -220.266768)
		(width 0.18288)
		(layer "In2.Cu")
		(net "M_F_CPU0_SB_DQ<11>")
	)
	(segment
		(start 405.470868 -219.42552)
		(end 405.197564 -219.42552)
		(width 0.18288)
		(layer "In2.Cu")
		(net "M_F_CPU0_SB_DQ<11>")
	)
	(segment
		(start 407.888694 -219.511626)
		(end 407.530808 -219.869512)
		(width 0.18288)
		(layer "In2.Cu")
		(net "M_F_CPU0_SB_DQ<11>")
	)
	(segment
		(start 408.625294 -219.241878)
		(end 408.465274 -219.081858)
		(width 0.18288)
		(layer "In2.Cu")
		(net "M_F_CPU0_SB_DQ<11>")
	)
	(segment
		(start 424.078146 -220.40342)
		(end 424.078146 -221.226888)
		(width 0.18288)
		(layer "In2.Cu")
		(net "M_F_CPU0_SB_DQ<11>")
	)
	(segment
		(start 389.227568 -229.287324)
		(end 388.179564 -230.335328)
		(width 0.088646)
		(layer "In2.Cu")
		(net "M_F_CPU0_SB_DQ<11>")
	)
	(segment
		(start 405.91486 -219.869512)
		(end 405.470868 -219.42552)
		(width 0.18288)
		(layer "In2.Cu")
		(net "M_F_CPU0_SB_DQ<11>")
	)
	(segment
		(start 417.390326 -219.900754)
		(end 416.694366 -219.900754)
		(width 0.18288)
		(layer "In2.Cu")
		(net "M_F_CPU0_SB_DQ<11>")
	)
	(segment
		(start 415.826448 -220.768672)
		(end 415.35604 -220.768672)
		(width 0.18288)
		(layer "In2.Cu")
		(net "M_F_CPU0_SB_DQ<11>")
	)
	(segment
		(start 408.465274 -219.081858)
		(end 408.048714 -219.081858)
		(width 0.18288)
		(layer "In2.Cu")
		(net "M_F_CPU0_SB_DQ<11>")
	)
	(segment
		(start 422.2242 -220.689932)
		(end 421.936926 -220.402658)
		(width 0.18288)
		(layer "In2.Cu")
		(net "M_F_CPU0_SB_DQ<11>")
	)
	(segment
		(start 413.23768 -220.768672)
		(end 412.67634 -220.768672)
		(width 0.18288)
		(layer "In2.Cu")
		(net "M_F_CPU0_SB_DQ<11>")
	)
	(segment
		(start 421.165782 -220.689932)
		(end 420.497 -220.689932)
		(width 0.18288)
		(layer "In2.Cu")
		(net "M_F_CPU0_SB_DQ<11>")
	)
	(segment
		(start 420.497 -220.689932)
		(end 419.877494 -220.070426)
		(width 0.18288)
		(layer "In2.Cu")
		(net "M_F_CPU0_SB_DQ<11>")
	)
	(segment
		(start 408.048714 -219.081858)
		(end 407.888694 -219.241878)
		(width 0.18288)
		(layer "In2.Cu")
		(net "M_F_CPU0_SB_DQ<11>")
	)
	(segment
		(start 383.506726 -231.09047)
		(end 383.265426 -231.09047)
		(width 0.088646)
		(layer "In2.Cu")
		(net "M_F_CPU0_SB_DQ<11>")
	)
	(segment
		(start 409.873196 -220.661992)
		(end 409.231084 -220.01988)
		(width 0.18288)
		(layer "In2.Cu")
		(net "M_F_CPU0_SB_DQ<11>")
	)
	(segment
		(start 421.936926 -220.402658)
		(end 421.453056 -220.402658)
		(width 0.18288)
		(layer "In2.Cu")
		(net "M_F_CPU0_SB_DQ<11>")
	)
	(segment
		(start 419.445694 -220.070426)
		(end 419.256718 -219.88145)
		(width 0.18288)
		(layer "In2.Cu")
		(net "M_F_CPU0_SB_DQ<11>")
	)
	(segment
		(start 389.61949 -229.287324)
		(end 389.227568 -229.287324)
		(width 0.088646)
		(layer "In2.Cu")
		(net "M_F_CPU0_SB_DQ<11>")
	)
	(segment
		(start 402.117052 -221.528132)
		(end 394.35786 -229.287324)
		(width 0.18288)
		(layer "In2.Cu")
		(net "M_F_CPU0_SB_DQ<11>")
	)
	(segment
		(start 423.884852 -221.420182)
		(end 423.487596 -221.420182)
		(width 0.18288)
		(layer "In2.Cu")
		(net "M_F_CPU0_SB_DQ<11>")
	)
	(segment
		(start 419.256718 -219.88145)
		(end 417.40963 -219.88145)
		(width 0.18288)
		(layer "In2.Cu")
		(net "M_F_CPU0_SB_DQ<11>")
	)
	(segment
		(start 383.265426 -231.09047)
		(end 383.075434 -230.900478)
		(width 0.088646)
		(layer "In2.Cu")
		(net "M_F_CPU0_SB_DQ<11>")
	)
	(segment
		(start 413.334454 -220.671898)
		(end 413.23768 -220.768672)
		(width 0.18288)
		(layer "In2.Cu")
		(net "M_F_CPU0_SB_DQ<11>")
	)
	(segment
		(start 412.67634 -220.768672)
		(end 412.56966 -220.661992)
		(width 0.18288)
		(layer "In2.Cu")
		(net "M_F_CPU0_SB_DQ<11>")
	)
	(segment
		(start 421.453056 -220.402658)
		(end 421.165782 -220.689932)
		(width 0.18288)
		(layer "In2.Cu")
		(net "M_F_CPU0_SB_DQ<11>")
	)
	(segment
		(start 404.23084 -220.392244)
		(end 404.23084 -221.040452)
		(width 0.18288)
		(layer "In2.Cu")
		(net "M_F_CPU0_SB_DQ<11>")
	)
	(segment
		(start 383.828036 -231.224836)
		(end 383.687828 -231.142794)
		(width 0.088646)
		(layer "In2.Cu")
		(net "M_F_CPU0_SB_DQ<11>")
	)
	(segment
		(start 416.694366 -219.900754)
		(end 415.826448 -220.768672)
		(width 0.18288)
		(layer "In2.Cu")
		(net "M_F_CPU0_SB_DQ<11>")
	)
	(segment
		(start 408.625294 -219.854526)
		(end 408.625294 -219.241878)
		(width 0.18288)
		(layer "In2.Cu")
		(net "M_F_CPU0_SB_DQ<11>")
	)
	(segment
		(start 417.40963 -219.88145)
		(end 417.390326 -219.900754)
		(width 0.18288)
		(layer "In2.Cu")
		(net "M_F_CPU0_SB_DQ<11>")
	)
	(segment
		(start 415.259266 -220.671898)
		(end 413.334454 -220.671898)
		(width 0.18288)
		(layer "In2.Cu")
		(net "M_F_CPU0_SB_DQ<11>")
	)
	(arc
		(start 384.202432 -231.224836)
		(mid 384.015234 -231.274979)
		(end 383.828036 -231.224836)
		(width 0.088646)
		(layer "In2.Cu")
		(net "M_F_CPU0_SB_DQ<11>")
	)
	(arc
		(start 385.612132 -230.41102)
		(mid 385.407797 -230.613625)
		(end 385.329684 -230.890572)
		(width 0.088646)
		(layer "In2.Cu")
		(net "M_F_CPU0_SB_DQ<11>")
	)
	(arc
		(start 387.117336 -230.41102)
		(mid 386.834634 -230.335244)
		(end 386.551932 -230.41102)
		(width 0.088646)
		(layer "In2.Cu")
		(net "M_F_CPU0_SB_DQ<11>")
	)
	(arc
		(start 387.491732 -230.41102)
		(mid 387.304534 -230.461163)
		(end 387.117336 -230.41102)
		(width 0.088646)
		(layer "In2.Cu")
		(net "M_F_CPU0_SB_DQ<11>")
	)
	(arc
		(start 386.551932 -230.41102)
		(mid 386.364734 -230.461163)
		(end 386.177536 -230.41102)
		(width 0.088646)
		(layer "In2.Cu")
		(net "M_F_CPU0_SB_DQ<11>")
	)
	(arc
		(start 385.142232 -231.224836)
		(mid 384.955034 -231.274979)
		(end 384.767836 -231.224836)
		(width 0.088646)
		(layer "In2.Cu")
		(net "M_F_CPU0_SB_DQ<11>")
	)
	(arc
		(start 387.774434 -230.335328)
		(mid 387.628111 -230.35459)
		(end 387.491732 -230.41102)
		(width 0.088646)
		(layer "In2.Cu")
		(net "M_F_CPU0_SB_DQ<11>")
	)
	(arc
		(start 386.177536 -230.41102)
		(mid 385.894834 -230.335244)
		(end 385.612132 -230.41102)
		(width 0.088646)
		(layer "In2.Cu")
		(net "M_F_CPU0_SB_DQ<11>")
	)
	(arc
		(start 384.767836 -231.224836)
		(mid 384.485134 -231.149094)
		(end 384.202432 -231.224836)
		(width 0.088646)
		(layer "In2.Cu")
		(net "M_F_CPU0_SB_DQ<11>")
	)
	(arc
		(start 383.687828 -231.142794)
		(mid 383.676844 -231.137221)
		(end 383.665222 -231.133142)
		(width 0.088646)
		(layer "In2.Cu")
		(net "M_F_CPU0_SB_DQ<11>")
	)
	(arc
		(start 385.329684 -230.900478)
		(mid 385.282005 -231.083378)
		(end 385.151122 -231.219756)
		(width 0.088646)
		(layer "In2.Cu")
		(net "M_F_CPU0_SB_DQ<11>")
	)
	(segment
		(start 430.395126 -222.403924)
		(end 431.076354 -222.403924)
		(width 0.20066)
		(layer "F.Cu")
		(net "M_F_CPU0_SB_DQ<10>")
	)
	(segment
		(start 431.514504 -221.714822)
		(end 431.898552 -221.714822)
		(width 0.20066)
		(layer "F.Cu")
		(net "M_F_CPU0_SB_DQ<10>")
	)
	(segment
		(start 427.639226 -221.96679)
		(end 428.07128 -222.398844)
		(width 0.20066)
		(layer "F.Cu")
		(net "M_F_CPU0_SB_DQ<10>")
	)
	(segment
		(start 431.076354 -222.403924)
		(end 431.280316 -222.199962)
		(width 0.20066)
		(layer "F.Cu")
		(net "M_F_CPU0_SB_DQ<10>")
	)
	(segment
		(start 428.363126 -222.398844)
		(end 428.367952 -222.398844)
		(width 0.101854)
		(layer "F.Cu")
		(net "M_F_CPU0_SB_DQ<10>")
	)
	(segment
		(start 424.836082 -221.96679)
		(end 425.940982 -221.96679)
		(width 0.20066)
		(layer "F.Cu")
		(net "M_F_CPU0_SB_DQ<10>")
	)
	(segment
		(start 428.375064 -222.391732)
		(end 430.382934 -222.391732)
		(width 0.1016)
		(layer "F.Cu")
		(net "M_F_CPU0_SB_DQ<10>")
	)
	(segment
		(start 425.940982 -221.96679)
		(end 427.639226 -221.96679)
		(width 0.20066)
		(layer "F.Cu")
		(net "M_F_CPU0_SB_DQ<10>")
	)
	(segment
		(start 431.280316 -221.94901)
		(end 431.514504 -221.714822)
		(width 0.20066)
		(layer "F.Cu")
		(net "M_F_CPU0_SB_DQ<10>")
	)
	(segment
		(start 432.15052 -221.96679)
		(end 433.484782 -221.96679)
		(width 0.20066)
		(layer "F.Cu")
		(net "M_F_CPU0_SB_DQ<10>")
	)
	(segment
		(start 431.898552 -221.714822)
		(end 432.15052 -221.96679)
		(width 0.20066)
		(layer "F.Cu")
		(net "M_F_CPU0_SB_DQ<10>")
	)
	(segment
		(start 382.605534 -232.250488)
		(end 382.605534 -231.714548)
		(width 0.20066)
		(layer "F.Cu")
		(net "M_F_CPU0_SB_DQ<10>")
	)
	(segment
		(start 431.280316 -222.199962)
		(end 431.280316 -221.94901)
		(width 0.20066)
		(layer "F.Cu")
		(net "M_F_CPU0_SB_DQ<10>")
	)
	(segment
		(start 428.367952 -222.398844)
		(end 428.375064 -222.391732)
		(width 0.1016)
		(layer "F.Cu")
		(net "M_F_CPU0_SB_DQ<10>")
	)
	(segment
		(start 430.382934 -222.391732)
		(end 430.395126 -222.403924)
		(width 0.1016)
		(layer "F.Cu")
		(net "M_F_CPU0_SB_DQ<10>")
	)
	(segment
		(start 428.07128 -222.398844)
		(end 428.363126 -222.398844)
		(width 0.20066)
		(layer "F.Cu")
		(net "M_F_CPU0_SB_DQ<10>")
	)
	(segment
		(start 402.551138 -222.544132)
		(end 394.772134 -230.323136)
		(width 0.18288)
		(layer "In2.Cu")
		(net "M_F_CPU0_SB_DQ<10>")
	)
	(segment
		(start 418.949124 -223.093788)
		(end 418.756084 -223.286828)
		(width 0.18288)
		(layer "In2.Cu")
		(net "M_F_CPU0_SB_DQ<10>")
	)
	(segment
		(start 417.797996 -222.561404)
		(end 417.569142 -222.33255)
		(width 0.18288)
		(layer "In2.Cu")
		(net "M_F_CPU0_SB_DQ<10>")
	)
	(segment
		(start 410.280866 -222.658432)
		(end 409.890214 -222.26778)
		(width 0.18288)
		(layer "In2.Cu")
		(net "M_F_CPU0_SB_DQ<10>")
	)
	(segment
		(start 409.273248 -222.26778)
		(end 408.53614 -221.530672)
		(width 0.18288)
		(layer "In2.Cu")
		(net "M_F_CPU0_SB_DQ<10>")
	)
	(segment
		(start 420.257732 -222.389954)
		(end 420.095934 -222.228156)
		(width 0.18288)
		(layer "In2.Cu")
		(net "M_F_CPU0_SB_DQ<10>")
	)
	(segment
		(start 406.260554 -221.496128)
		(end 405.421338 -221.496128)
		(width 0.18288)
		(layer "In2.Cu")
		(net "M_F_CPU0_SB_DQ<10>")
	)
	(segment
		(start 394.772134 -230.323136)
		(end 389.61949 -230.323136)
		(width 0.18288)
		(layer "In2.Cu")
		(net "M_F_CPU0_SB_DQ<10>")
	)
	(segment
		(start 407.123138 -221.711012)
		(end 406.475438 -221.711012)
		(width 0.18288)
		(layer "In2.Cu")
		(net "M_F_CPU0_SB_DQ<10>")
	)
	(segment
		(start 422.890696 -222.389954)
		(end 420.257732 -222.389954)
		(width 0.18288)
		(layer "In2.Cu")
		(net "M_F_CPU0_SB_DQ<10>")
	)
	(segment
		(start 418.949124 -222.62719)
		(end 418.949124 -223.093788)
		(width 0.18288)
		(layer "In2.Cu")
		(net "M_F_CPU0_SB_DQ<10>")
	)
	(segment
		(start 417.991036 -223.286828)
		(end 417.797996 -223.093788)
		(width 0.18288)
		(layer "In2.Cu")
		(net "M_F_CPU0_SB_DQ<10>")
	)
	(segment
		(start 408.53614 -221.530672)
		(end 407.303478 -221.530672)
		(width 0.18288)
		(layer "In2.Cu")
		(net "M_F_CPU0_SB_DQ<10>")
	)
	(segment
		(start 424.466766 -221.96679)
		(end 424.273726 -222.15983)
		(width 0.18288)
		(layer "In2.Cu")
		(net "M_F_CPU0_SB_DQ<10>")
	)
	(segment
		(start 411.471618 -222.658432)
		(end 410.280866 -222.658432)
		(width 0.18288)
		(layer "In2.Cu")
		(net "M_F_CPU0_SB_DQ<10>")
	)
	(segment
		(start 409.890214 -222.26778)
		(end 409.273248 -222.26778)
		(width 0.18288)
		(layer "In2.Cu")
		(net "M_F_CPU0_SB_DQ<10>")
	)
	(segment
		(start 383.24282 -231.988614)
		(end 382.941322 -231.895396)
		(width 0.088646)
		(layer "In2.Cu")
		(net "M_F_CPU0_SB_DQ<10>")
	)
	(segment
		(start 387.810248 -230.81488)
		(end 387.475984 -231.149144)
		(width 0.088646)
		(layer "In2.Cu")
		(net "M_F_CPU0_SB_DQ<10>")
	)
	(segment
		(start 423.22369 -222.722948)
		(end 422.890696 -222.389954)
		(width 0.18288)
		(layer "In2.Cu")
		(net "M_F_CPU0_SB_DQ<10>")
	)
	(segment
		(start 406.475438 -221.711012)
		(end 406.260554 -221.496128)
		(width 0.18288)
		(layer "In2.Cu")
		(net "M_F_CPU0_SB_DQ<10>")
	)
	(segment
		(start 416.73018 -222.72371)
		(end 415.477706 -222.72371)
		(width 0.18288)
		(layer "In2.Cu")
		(net "M_F_CPU0_SB_DQ<10>")
	)
	(segment
		(start 424.836082 -221.96679)
		(end 424.466766 -221.96679)
		(width 0.18288)
		(layer "In2.Cu")
		(net "M_F_CPU0_SB_DQ<10>")
	)
	(segment
		(start 412.450026 -222.141542)
		(end 411.988508 -222.141542)
		(width 0.18288)
		(layer "In2.Cu")
		(net "M_F_CPU0_SB_DQ<10>")
	)
	(segment
		(start 423.465752 -223.459294)
		(end 423.22369 -223.217232)
		(width 0.18288)
		(layer "In2.Cu")
		(net "M_F_CPU0_SB_DQ<10>")
	)
	(segment
		(start 388.598664 -230.81488)
		(end 387.810248 -230.81488)
		(width 0.088646)
		(layer "In2.Cu")
		(net "M_F_CPU0_SB_DQ<10>")
	)
	(segment
		(start 423.972736 -223.459294)
		(end 423.465752 -223.459294)
		(width 0.18288)
		(layer "In2.Cu")
		(net "M_F_CPU0_SB_DQ<10>")
	)
	(segment
		(start 417.569142 -222.33255)
		(end 417.12134 -222.33255)
		(width 0.18288)
		(layer "In2.Cu")
		(net "M_F_CPU0_SB_DQ<10>")
	)
	(segment
		(start 424.273726 -223.158304)
		(end 423.972736 -223.459294)
		(width 0.18288)
		(layer "In2.Cu")
		(net "M_F_CPU0_SB_DQ<10>")
	)
	(segment
		(start 419.348158 -222.228156)
		(end 418.949124 -222.62719)
		(width 0.18288)
		(layer "In2.Cu")
		(net "M_F_CPU0_SB_DQ<10>")
	)
	(segment
		(start 420.095934 -222.228156)
		(end 419.348158 -222.228156)
		(width 0.18288)
		(layer "In2.Cu")
		(net "M_F_CPU0_SB_DQ<10>")
	)
	(segment
		(start 417.12134 -222.33255)
		(end 416.73018 -222.72371)
		(width 0.18288)
		(layer "In2.Cu")
		(net "M_F_CPU0_SB_DQ<10>")
	)
	(segment
		(start 423.22369 -223.217232)
		(end 423.22369 -222.722948)
		(width 0.18288)
		(layer "In2.Cu")
		(net "M_F_CPU0_SB_DQ<10>")
	)
	(segment
		(start 407.303478 -221.530672)
		(end 407.123138 -221.711012)
		(width 0.18288)
		(layer "In2.Cu")
		(net "M_F_CPU0_SB_DQ<10>")
	)
	(segment
		(start 424.273726 -222.15983)
		(end 424.273726 -223.158304)
		(width 0.18288)
		(layer "In2.Cu")
		(net "M_F_CPU0_SB_DQ<10>")
	)
	(segment
		(start 412.712916 -222.404432)
		(end 412.450026 -222.141542)
		(width 0.18288)
		(layer "In2.Cu")
		(net "M_F_CPU0_SB_DQ<10>")
	)
	(segment
		(start 385.799584 -231.696006)
		(end 385.799584 -231.714548)
		(width 0.088646)
		(layer "In2.Cu")
		(net "M_F_CPU0_SB_DQ<10>")
	)
	(segment
		(start 389.61949 -230.323136)
		(end 389.090408 -230.323136)
		(width 0.088646)
		(layer "In2.Cu")
		(net "M_F_CPU0_SB_DQ<10>")
	)
	(segment
		(start 411.988508 -222.141542)
		(end 411.471618 -222.658432)
		(width 0.18288)
		(layer "In2.Cu")
		(net "M_F_CPU0_SB_DQ<10>")
	)
	(segment
		(start 415.477706 -222.72371)
		(end 415.158428 -222.404432)
		(width 0.18288)
		(layer "In2.Cu")
		(net "M_F_CPU0_SB_DQ<10>")
	)
	(segment
		(start 405.421338 -221.496128)
		(end 404.373334 -222.544132)
		(width 0.18288)
		(layer "In2.Cu")
		(net "M_F_CPU0_SB_DQ<10>")
	)
	(segment
		(start 387.475984 -231.149144)
		(end 387.304534 -231.149144)
		(width 0.088646)
		(layer "In2.Cu")
		(net "M_F_CPU0_SB_DQ<10>")
	)
	(segment
		(start 417.797996 -223.093788)
		(end 417.797996 -222.561404)
		(width 0.18288)
		(layer "In2.Cu")
		(net "M_F_CPU0_SB_DQ<10>")
	)
	(segment
		(start 389.090408 -230.323136)
		(end 388.598664 -230.81488)
		(width 0.088646)
		(layer "In2.Cu")
		(net "M_F_CPU0_SB_DQ<10>")
	)
	(segment
		(start 418.756084 -223.286828)
		(end 417.991036 -223.286828)
		(width 0.18288)
		(layer "In2.Cu")
		(net "M_F_CPU0_SB_DQ<10>")
	)
	(segment
		(start 382.941322 -231.895396)
		(end 382.605534 -231.714548)
		(width 0.088646)
		(layer "In2.Cu")
		(net "M_F_CPU0_SB_DQ<10>")
	)
	(segment
		(start 415.158428 -222.404432)
		(end 412.712916 -222.404432)
		(width 0.18288)
		(layer "In2.Cu")
		(net "M_F_CPU0_SB_DQ<10>")
	)
	(segment
		(start 404.373334 -222.544132)
		(end 402.551138 -222.544132)
		(width 0.18288)
		(layer "In2.Cu")
		(net "M_F_CPU0_SB_DQ<10>")
	)
	(arc
		(start 386.647436 -231.224836)
		(mid 386.090062 -231.220287)
		(end 385.799584 -231.696006)
		(width 0.088646)
		(layer "In2.Cu")
		(net "M_F_CPU0_SB_DQ<10>")
	)
	(arc
		(start 384.297936 -232.038906)
		(mid 384.015234 -231.96313)
		(end 383.732532 -232.038906)
		(width 0.088646)
		(layer "In2.Cu")
		(net "M_F_CPU0_SB_DQ<10>")
	)
	(arc
		(start 387.021832 -231.224836)
		(mid 386.834634 -231.274979)
		(end 386.647436 -231.224836)
		(width 0.088646)
		(layer "In2.Cu")
		(net "M_F_CPU0_SB_DQ<10>")
	)
	(arc
		(start 383.732532 -232.038906)
		(mid 383.545334 -232.089049)
		(end 383.358136 -232.038906)
		(width 0.088646)
		(layer "In2.Cu")
		(net "M_F_CPU0_SB_DQ<10>")
	)
	(arc
		(start 387.304534 -231.149144)
		(mid 387.158211 -231.168406)
		(end 387.021832 -231.224836)
		(width 0.088646)
		(layer "In2.Cu")
		(net "M_F_CPU0_SB_DQ<10>")
	)
	(arc
		(start 385.799584 -231.714548)
		(mid 385.612285 -232.038989)
		(end 385.237736 -232.038906)
		(width 0.088646)
		(layer "In2.Cu")
		(net "M_F_CPU0_SB_DQ<10>")
	)
	(arc
		(start 383.358136 -232.038906)
		(mid 383.301881 -232.010542)
		(end 383.24282 -231.988614)
		(width 0.088646)
		(layer "In2.Cu")
		(net "M_F_CPU0_SB_DQ<10>")
	)
	(arc
		(start 384.672332 -232.038906)
		(mid 384.485134 -232.089049)
		(end 384.297936 -232.038906)
		(width 0.088646)
		(layer "In2.Cu")
		(net "M_F_CPU0_SB_DQ<10>")
	)
	(arc
		(start 385.237736 -232.038906)
		(mid 384.955034 -231.96313)
		(end 384.672332 -232.038906)
		(width 0.088646)
		(layer "In2.Cu")
		(net "M_F_CPU0_SB_DQ<10>")
	)
	(segment
		(start 427.36135 -231.735376)
		(end 426.951394 -231.735376)
		(width 0.20066)
		(layer "F.Cu")
		(net "M_F_CPU0_SB_DQ<0>")
	)
	(segment
		(start 424.273472 -231.859836)
		(end 424.273472 -232.227374)
		(width 0.20066)
		(layer "F.Cu")
		(net "M_F_CPU0_SB_DQ<0>")
	)
	(segment
		(start 378.376434 -239.575086)
		(end 378.376434 -239.0394)
		(width 0.20066)
		(layer "F.Cu")
		(net "M_F_CPU0_SB_DQ<0>")
	)
	(segment
		(start 427.792896 -232.166922)
		(end 427.36135 -231.735376)
		(width 0.20066)
		(layer "F.Cu")
		(net "M_F_CPU0_SB_DQ<0>")
	)
	(segment
		(start 424.391582 -231.741726)
		(end 424.273472 -231.859836)
		(width 0.20066)
		(layer "F.Cu")
		(net "M_F_CPU0_SB_DQ<0>")
	)
	(segment
		(start 429.384714 -232.166668)
		(end 429.38446 -232.166922)
		(width 0.20066)
		(layer "F.Cu")
		(net "M_F_CPU0_SB_DQ<0>")
	)
	(segment
		(start 421.840914 -232.166668)
		(end 420.736014 -232.166668)
		(width 0.20066)
		(layer "F.Cu")
		(net "M_F_CPU0_SB_DQ<0>")
	)
	(segment
		(start 429.38446 -232.166922)
		(end 427.792896 -232.166922)
		(width 0.20066)
		(layer "F.Cu")
		(net "M_F_CPU0_SB_DQ<0>")
	)
	(segment
		(start 424.085512 -232.415334)
		(end 423.610278 -232.415334)
		(width 0.20066)
		(layer "F.Cu")
		(net "M_F_CPU0_SB_DQ<0>")
	)
	(segment
		(start 426.945044 -231.741726)
		(end 424.78325 -231.741726)
		(width 0.1016)
		(layer "F.Cu")
		(net "M_F_CPU0_SB_DQ<0>")
	)
	(segment
		(start 424.73626 -231.741726)
		(end 424.391582 -231.741726)
		(width 0.20066)
		(layer "F.Cu")
		(net "M_F_CPU0_SB_DQ<0>")
	)
	(segment
		(start 378.37618 -239.57534)
		(end 378.376434 -239.575086)
		(width 0.20066)
		(layer "F.Cu")
		(net "M_F_CPU0_SB_DQ<0>")
	)
	(segment
		(start 423.361612 -232.166668)
		(end 421.840914 -232.166668)
		(width 0.20066)
		(layer "F.Cu")
		(net "M_F_CPU0_SB_DQ<0>")
	)
	(segment
		(start 424.78325 -231.741726)
		(end 424.73626 -231.741726)
		(width 0.101854)
		(layer "F.Cu")
		(net "M_F_CPU0_SB_DQ<0>")
	)
	(segment
		(start 424.273472 -232.227374)
		(end 424.085512 -232.415334)
		(width 0.20066)
		(layer "F.Cu")
		(net "M_F_CPU0_SB_DQ<0>")
	)
	(segment
		(start 426.951394 -231.735376)
		(end 426.945044 -231.741726)
		(width 0.1016)
		(layer "F.Cu")
		(net "M_F_CPU0_SB_DQ<0>")
	)
	(segment
		(start 423.610278 -232.415334)
		(end 423.361612 -232.166668)
		(width 0.20066)
		(layer "F.Cu")
		(net "M_F_CPU0_SB_DQ<0>")
	)
	(segment
		(start 404.09241 -232.543604)
		(end 404.09241 -231.926384)
		(width 0.18288)
		(layer "In4.Cu")
		(net "M_F_CPU0_SB_DQ<0>")
	)
	(segment
		(start 387.856476 -239.095534)
		(end 387.10235 -239.537494)
		(width 0.088646)
		(layer "In4.Cu")
		(net "M_F_CPU0_SB_DQ<0>")
	)
	(segment
		(start 403.90953 -231.743504)
		(end 403.58187 -231.743504)
		(width 0.18288)
		(layer "In4.Cu")
		(net "M_F_CPU0_SB_DQ<0>")
	)
	(segment
		(start 402.70557 -231.926384)
		(end 402.52269 -231.743504)
		(width 0.18288)
		(layer "In4.Cu")
		(net "M_F_CPU0_SB_DQ<0>")
	)
	(segment
		(start 407.159968 -232.549446)
		(end 406.977088 -232.732326)
		(width 0.18288)
		(layer "In4.Cu")
		(net "M_F_CPU0_SB_DQ<0>")
	)
	(segment
		(start 409.522676 -230.892096)
		(end 408.671268 -231.743504)
		(width 0.18288)
		(layer "In4.Cu")
		(net "M_F_CPU0_SB_DQ<0>")
	)
	(segment
		(start 411.206696 -231.76484)
		(end 410.879036 -231.76484)
		(width 0.18288)
		(layer "In4.Cu")
		(net "M_F_CPU0_SB_DQ<0>")
	)
	(segment
		(start 402.88845 -232.726484)
		(end 402.70557 -232.543604)
		(width 0.18288)
		(layer "In4.Cu")
		(net "M_F_CPU0_SB_DQ<0>")
	)
	(segment
		(start 417.697158 -231.50322)
		(end 416.50158 -231.50322)
		(width 0.18288)
		(layer "In4.Cu")
		(net "M_F_CPU0_SB_DQ<0>")
	)
	(segment
		(start 393.057634 -235.837984)
		(end 390.58215 -238.313468)
		(width 0.18288)
		(layer "In4.Cu")
		(net "M_F_CPU0_SB_DQ<0>")
	)
	(segment
		(start 388.839202 -238.313468)
		(end 388.266432 -238.886238)
		(width 0.088646)
		(layer "In4.Cu")
		(net "M_F_CPU0_SB_DQ<0>")
	)
	(segment
		(start 385.237482 -239.528858)
		(end 385.22275 -239.537494)
		(width 0.088646)
		(layer "In4.Cu")
		(net "M_F_CPU0_SB_DQ<0>")
	)
	(segment
		(start 418.125402 -231.931718)
		(end 417.91128 -231.717596)
		(width 0.18288)
		(layer "In4.Cu")
		(net "M_F_CPU0_SB_DQ<0>")
	)
	(segment
		(start 382.798574 -239.532414)
		(end 382.792732 -239.528858)
		(width 0.088646)
		(layer "In4.Cu")
		(net "M_F_CPU0_SB_DQ<0>")
	)
	(segment
		(start 403.39899 -231.926384)
		(end 403.39899 -232.543604)
		(width 0.18288)
		(layer "In4.Cu")
		(net "M_F_CPU0_SB_DQ<0>")
	)
	(segment
		(start 419.032944 -231.717342)
		(end 419.032944 -231.717596)
		(width 0.18288)
		(layer "In4.Cu")
		(net "M_F_CPU0_SB_DQ<0>")
	)
	(segment
		(start 420.736014 -231.915208)
		(end 420.324026 -231.50322)
		(width 0.18288)
		(layer "In4.Cu")
		(net "M_F_CPU0_SB_DQ<0>")
	)
	(segment
		(start 413.126174 -232.503472)
		(end 412.966154 -232.343452)
		(width 0.18288)
		(layer "In4.Cu")
		(net "M_F_CPU0_SB_DQ<0>")
	)
	(segment
		(start 418.818822 -231.931718)
		(end 418.125402 -231.931718)
		(width 0.18288)
		(layer "In4.Cu")
		(net "M_F_CPU0_SB_DQ<0>")
	)
	(segment
		(start 404.60295 -232.726484)
		(end 404.27529 -232.726484)
		(width 0.18288)
		(layer "In4.Cu")
		(net "M_F_CPU0_SB_DQ<0>")
	)
	(segment
		(start 404.78583 -232.543604)
		(end 404.60295 -232.726484)
		(width 0.18288)
		(layer "In4.Cu")
		(net "M_F_CPU0_SB_DQ<0>")
	)
	(segment
		(start 417.91128 -231.717596)
		(end 417.91128 -231.717342)
		(width 0.18288)
		(layer "In4.Cu")
		(net "M_F_CPU0_SB_DQ<0>")
	)
	(segment
		(start 380.913132 -239.528858)
		(end 380.90729 -239.525556)
		(width 0.088646)
		(layer "In4.Cu")
		(net "M_F_CPU0_SB_DQ<0>")
	)
	(segment
		(start 406.466548 -232.549446)
		(end 406.466548 -231.926384)
		(width 0.18288)
		(layer "In4.Cu")
		(net "M_F_CPU0_SB_DQ<0>")
	)
	(segment
		(start 404.78583 -231.926384)
		(end 404.78583 -232.543604)
		(width 0.18288)
		(layer "In4.Cu")
		(net "M_F_CPU0_SB_DQ<0>")
	)
	(segment
		(start 380.918974 -239.532414)
		(end 380.913132 -239.528858)
		(width 0.088646)
		(layer "In4.Cu")
		(net "M_F_CPU0_SB_DQ<0>")
	)
	(segment
		(start 403.58187 -231.743504)
		(end 403.39899 -231.926384)
		(width 0.18288)
		(layer "In4.Cu")
		(net "M_F_CPU0_SB_DQ<0>")
	)
	(segment
		(start 411.572456 -230.892096)
		(end 411.389576 -231.074976)
		(width 0.18288)
		(layer "In4.Cu")
		(net "M_F_CPU0_SB_DQ<0>")
	)
	(segment
		(start 412.966154 -232.016046)
		(end 411.842204 -230.892096)
		(width 0.18288)
		(layer "In4.Cu")
		(net "M_F_CPU0_SB_DQ<0>")
	)
	(segment
		(start 411.842204 -230.892096)
		(end 411.572456 -230.892096)
		(width 0.18288)
		(layer "In4.Cu")
		(net "M_F_CPU0_SB_DQ<0>")
	)
	(segment
		(start 416.50158 -231.50322)
		(end 416.179254 -231.825546)
		(width 0.18288)
		(layer "In4.Cu")
		(net "M_F_CPU0_SB_DQ<0>")
	)
	(segment
		(start 404.27529 -232.726484)
		(end 404.09241 -232.543604)
		(width 0.18288)
		(layer "In4.Cu")
		(net "M_F_CPU0_SB_DQ<0>")
	)
	(segment
		(start 404.09241 -231.926384)
		(end 403.90953 -231.743504)
		(width 0.18288)
		(layer "In4.Cu")
		(net "M_F_CPU0_SB_DQ<0>")
	)
	(segment
		(start 416.179254 -231.825546)
		(end 416.179254 -232.19791)
		(width 0.18288)
		(layer "In4.Cu")
		(net "M_F_CPU0_SB_DQ<0>")
	)
	(segment
		(start 415.873692 -232.503472)
		(end 413.126174 -232.503472)
		(width 0.18288)
		(layer "In4.Cu")
		(net "M_F_CPU0_SB_DQ<0>")
	)
	(segment
		(start 397.52397 -235.837984)
		(end 393.057634 -235.837984)
		(width 0.18288)
		(layer "In4.Cu")
		(net "M_F_CPU0_SB_DQ<0>")
	)
	(segment
		(start 406.466548 -231.926384)
		(end 406.283668 -231.743504)
		(width 0.18288)
		(layer "In4.Cu")
		(net "M_F_CPU0_SB_DQ<0>")
	)
	(segment
		(start 411.389576 -231.58196)
		(end 411.206696 -231.76484)
		(width 0.18288)
		(layer "In4.Cu")
		(net "M_F_CPU0_SB_DQ<0>")
	)
	(segment
		(start 384.297682 -239.528858)
		(end 384.287268 -239.534954)
		(width 0.088646)
		(layer "In4.Cu")
		(net "M_F_CPU0_SB_DQ<0>")
	)
	(segment
		(start 403.39899 -232.543604)
		(end 403.21611 -232.726484)
		(width 0.18288)
		(layer "In4.Cu")
		(net "M_F_CPU0_SB_DQ<0>")
	)
	(segment
		(start 386.177282 -239.528858)
		(end 386.16255 -239.537494)
		(width 0.088646)
		(layer "In4.Cu")
		(net "M_F_CPU0_SB_DQ<0>")
	)
	(segment
		(start 420.324026 -231.50322)
		(end 419.247066 -231.50322)
		(width 0.18288)
		(layer "In4.Cu")
		(net "M_F_CPU0_SB_DQ<0>")
	)
	(segment
		(start 382.792732 -239.528858)
		(end 382.788922 -239.526826)
		(width 0.088646)
		(layer "In4.Cu")
		(net "M_F_CPU0_SB_DQ<0>")
	)
	(segment
		(start 407.159968 -231.926384)
		(end 407.159968 -232.549446)
		(width 0.18288)
		(layer "In4.Cu")
		(net "M_F_CPU0_SB_DQ<0>")
	)
	(segment
		(start 406.283668 -231.743504)
		(end 404.96871 -231.743504)
		(width 0.18288)
		(layer "In4.Cu")
		(net "M_F_CPU0_SB_DQ<0>")
	)
	(segment
		(start 406.977088 -232.732326)
		(end 406.649428 -232.732326)
		(width 0.18288)
		(layer "In4.Cu")
		(net "M_F_CPU0_SB_DQ<0>")
	)
	(segment
		(start 403.21611 -232.726484)
		(end 402.88845 -232.726484)
		(width 0.18288)
		(layer "In4.Cu")
		(net "M_F_CPU0_SB_DQ<0>")
	)
	(segment
		(start 378.64161 -239.304576)
		(end 378.376434 -239.0394)
		(width 0.088646)
		(layer "In4.Cu")
		(net "M_F_CPU0_SB_DQ<0>")
	)
	(segment
		(start 407.342848 -231.743504)
		(end 407.159968 -231.926384)
		(width 0.18288)
		(layer "In4.Cu")
		(net "M_F_CPU0_SB_DQ<0>")
	)
	(segment
		(start 388.941564 -238.313468)
		(end 388.839202 -238.313468)
		(width 0.088646)
		(layer "In4.Cu")
		(net "M_F_CPU0_SB_DQ<0>")
	)
	(segment
		(start 378.81687 -239.304576)
		(end 378.64161 -239.304576)
		(width 0.088646)
		(layer "In4.Cu")
		(net "M_F_CPU0_SB_DQ<0>")
	)
	(segment
		(start 402.70557 -232.543604)
		(end 402.70557 -231.926384)
		(width 0.18288)
		(layer "In4.Cu")
		(net "M_F_CPU0_SB_DQ<0>")
	)
	(segment
		(start 420.736014 -232.166668)
		(end 420.736014 -231.915208)
		(width 0.18288)
		(layer "In4.Cu")
		(net "M_F_CPU0_SB_DQ<0>")
	)
	(segment
		(start 419.032944 -231.717596)
		(end 418.818822 -231.931718)
		(width 0.18288)
		(layer "In4.Cu")
		(net "M_F_CPU0_SB_DQ<0>")
	)
	(segment
		(start 410.879036 -231.76484)
		(end 410.696156 -231.58196)
		(width 0.18288)
		(layer "In4.Cu")
		(net "M_F_CPU0_SB_DQ<0>")
	)
	(segment
		(start 410.696156 -231.58196)
		(end 410.696156 -231.074976)
		(width 0.18288)
		(layer "In4.Cu")
		(net "M_F_CPU0_SB_DQ<0>")
	)
	(segment
		(start 404.96871 -231.743504)
		(end 404.78583 -231.926384)
		(width 0.18288)
		(layer "In4.Cu")
		(net "M_F_CPU0_SB_DQ<0>")
	)
	(segment
		(start 402.52269 -231.743504)
		(end 401.61845 -231.743504)
		(width 0.18288)
		(layer "In4.Cu")
		(net "M_F_CPU0_SB_DQ<0>")
	)
	(segment
		(start 379.973332 -239.528858)
		(end 379.96749 -239.525556)
		(width 0.088646)
		(layer "In4.Cu")
		(net "M_F_CPU0_SB_DQ<0>")
	)
	(segment
		(start 408.671268 -231.743504)
		(end 407.342848 -231.743504)
		(width 0.18288)
		(layer "In4.Cu")
		(net "M_F_CPU0_SB_DQ<0>")
	)
	(segment
		(start 390.58215 -238.313468)
		(end 388.941564 -238.313468)
		(width 0.18288)
		(layer "In4.Cu")
		(net "M_F_CPU0_SB_DQ<0>")
	)
	(segment
		(start 412.966154 -232.343452)
		(end 412.966154 -232.016046)
		(width 0.18288)
		(layer "In4.Cu")
		(net "M_F_CPU0_SB_DQ<0>")
	)
	(segment
		(start 417.91128 -231.717342)
		(end 417.697158 -231.50322)
		(width 0.18288)
		(layer "In4.Cu")
		(net "M_F_CPU0_SB_DQ<0>")
	)
	(segment
		(start 411.389576 -231.074976)
		(end 411.389576 -231.58196)
		(width 0.18288)
		(layer "In4.Cu")
		(net "M_F_CPU0_SB_DQ<0>")
	)
	(segment
		(start 381.852932 -239.528858)
		(end 381.848614 -239.526318)
		(width 0.088646)
		(layer "In4.Cu")
		(net "M_F_CPU0_SB_DQ<0>")
	)
	(segment
		(start 388.266432 -238.886238)
		(end 387.856476 -239.095534)
		(width 0.088646)
		(layer "In4.Cu")
		(net "M_F_CPU0_SB_DQ<0>")
	)
	(segment
		(start 383.732532 -239.528858)
		(end 383.728214 -239.526318)
		(width 0.088646)
		(layer "In4.Cu")
		(net "M_F_CPU0_SB_DQ<0>")
	)
	(segment
		(start 419.247066 -231.50322)
		(end 419.032944 -231.717342)
		(width 0.18288)
		(layer "In4.Cu")
		(net "M_F_CPU0_SB_DQ<0>")
	)
	(segment
		(start 401.61845 -231.743504)
		(end 397.52397 -235.837984)
		(width 0.18288)
		(layer "In4.Cu")
		(net "M_F_CPU0_SB_DQ<0>")
	)
	(segment
		(start 406.649428 -232.732326)
		(end 406.466548 -232.549446)
		(width 0.18288)
		(layer "In4.Cu")
		(net "M_F_CPU0_SB_DQ<0>")
	)
	(segment
		(start 410.513276 -230.892096)
		(end 409.522676 -230.892096)
		(width 0.18288)
		(layer "In4.Cu")
		(net "M_F_CPU0_SB_DQ<0>")
	)
	(segment
		(start 379.979174 -239.532414)
		(end 379.973332 -239.528858)
		(width 0.088646)
		(layer "In4.Cu")
		(net "M_F_CPU0_SB_DQ<0>")
	)
	(segment
		(start 410.696156 -231.074976)
		(end 410.513276 -230.892096)
		(width 0.18288)
		(layer "In4.Cu")
		(net "M_F_CPU0_SB_DQ<0>")
	)
	(segment
		(start 416.179254 -232.19791)
		(end 415.873692 -232.503472)
		(width 0.18288)
		(layer "In4.Cu")
		(net "M_F_CPU0_SB_DQ<0>")
	)
	(arc
		(start 381.478282 -239.528858)
		(mid 381.199108 -239.604623)
		(end 380.918974 -239.532414)
		(width 0.088646)
		(layer "In4.Cu")
		(net "M_F_CPU0_SB_DQ<0>")
	)
	(arc
		(start 383.728214 -239.526318)
		(mid 383.542719 -239.478649)
		(end 383.357882 -239.528858)
		(width 0.088646)
		(layer "In4.Cu")
		(net "M_F_CPU0_SB_DQ<0>")
	)
	(arc
		(start 384.672078 -239.528858)
		(mid 384.48488 -239.478715)
		(end 384.297682 -239.528858)
		(width 0.088646)
		(layer "In4.Cu")
		(net "M_F_CPU0_SB_DQ<0>")
	)
	(arc
		(start 382.788922 -239.526826)
		(mid 382.603232 -239.478748)
		(end 382.418082 -239.528858)
		(width 0.088646)
		(layer "In4.Cu")
		(net "M_F_CPU0_SB_DQ<0>")
	)
	(arc
		(start 380.538482 -239.528858)
		(mid 380.259308 -239.604623)
		(end 379.979174 -239.532414)
		(width 0.088646)
		(layer "In4.Cu")
		(net "M_F_CPU0_SB_DQ<0>")
	)
	(arc
		(start 379.598682 -239.528858)
		(mid 379.16014 -239.582726)
		(end 378.81687 -239.304576)
		(width 0.088646)
		(layer "In4.Cu")
		(net "M_F_CPU0_SB_DQ<0>")
	)
	(arc
		(start 384.287268 -239.534954)
		(mid 384.00909 -239.604677)
		(end 383.732532 -239.528858)
		(width 0.088646)
		(layer "In4.Cu")
		(net "M_F_CPU0_SB_DQ<0>")
	)
	(arc
		(start 386.551678 -239.528858)
		(mid 386.36448 -239.478715)
		(end 386.177282 -239.528858)
		(width 0.088646)
		(layer "In4.Cu")
		(net "M_F_CPU0_SB_DQ<0>")
	)
	(arc
		(start 386.16255 -239.537494)
		(mid 385.886075 -239.604814)
		(end 385.611878 -239.528858)
		(width 0.088646)
		(layer "In4.Cu")
		(net "M_F_CPU0_SB_DQ<0>")
	)
	(arc
		(start 381.848614 -239.526318)
		(mid 381.663119 -239.478649)
		(end 381.478282 -239.528858)
		(width 0.088646)
		(layer "In4.Cu")
		(net "M_F_CPU0_SB_DQ<0>")
	)
	(arc
		(start 385.611878 -239.528858)
		(mid 385.42468 -239.478715)
		(end 385.237482 -239.528858)
		(width 0.088646)
		(layer "In4.Cu")
		(net "M_F_CPU0_SB_DQ<0>")
	)
	(arc
		(start 379.96749 -239.525556)
		(mid 379.782635 -239.478606)
		(end 379.598682 -239.528858)
		(width 0.088646)
		(layer "In4.Cu")
		(net "M_F_CPU0_SB_DQ<0>")
	)
	(arc
		(start 383.357882 -239.528858)
		(mid 383.078708 -239.604623)
		(end 382.798574 -239.532414)
		(width 0.088646)
		(layer "In4.Cu")
		(net "M_F_CPU0_SB_DQ<0>")
	)
	(arc
		(start 385.22275 -239.537494)
		(mid 384.946275 -239.604814)
		(end 384.672078 -239.528858)
		(width 0.088646)
		(layer "In4.Cu")
		(net "M_F_CPU0_SB_DQ<0>")
	)
	(arc
		(start 380.90729 -239.525556)
		(mid 380.722435 -239.478606)
		(end 380.538482 -239.528858)
		(width 0.088646)
		(layer "In4.Cu")
		(net "M_F_CPU0_SB_DQ<0>")
	)
	(arc
		(start 387.10235 -239.537494)
		(mid 386.825875 -239.604814)
		(end 386.551678 -239.528858)
		(width 0.088646)
		(layer "In4.Cu")
		(net "M_F_CPU0_SB_DQ<0>")
	)
	(arc
		(start 382.418082 -239.528858)
		(mid 382.135524 -239.604507)
		(end 381.852932 -239.528858)
		(width 0.088646)
		(layer "In4.Cu")
		(net "M_F_CPU0_SB_DQ<0>")
	)
	(segment
		(start 381.665734 -243.644928)
		(end 381.665734 -243.108988)
		(width 0.20066)
		(layer "F.Cu")
		(net "M_F_CPU0_SB_CS_N<3>")
	)
	(segment
		(start 424.836082 -244.916706)
		(end 425.940982 -244.916706)
		(width 0.20066)
		(layer "F.Cu")
		(net "M_F_CPU0_SB_CS_N<3>")
	)
	(segment
		(start 422.15308 -244.807994)
		(end 421.61714 -244.807994)
		(width 0.18288)
		(layer "In2.Cu")
		(net "M_F_CPU0_SB_CS_N<3>")
	)
	(segment
		(start 423.381424 -245.026942)
		(end 423.381424 -244.650768)
		(width 0.18288)
		(layer "In2.Cu")
		(net "M_F_CPU0_SB_CS_N<3>")
	)
	(segment
		(start 415.294572 -243.642642)
		(end 412.632652 -243.642642)
		(width 0.18288)
		(layer "In2.Cu")
		(net "M_F_CPU0_SB_CS_N<3>")
	)
	(segment
		(start 410.298392 -243.318538)
		(end 409.974288 -243.642642)
		(width 0.18288)
		(layer "In2.Cu")
		(net "M_F_CPU0_SB_CS_N<3>")
	)
	(segment
		(start 419.646354 -243.423186)
		(end 418.454586 -243.423186)
		(width 0.18288)
		(layer "In2.Cu")
		(net "M_F_CPU0_SB_CS_N<3>")
	)
	(segment
		(start 424.605704 -244.490748)
		(end 424.26001 -244.490748)
		(width 0.18288)
		(layer "In2.Cu")
		(net "M_F_CPU0_SB_CS_N<3>")
	)
	(segment
		(start 408.371802 -243.642642)
		(end 407.523442 -244.491002)
		(width 0.18288)
		(layer "In2.Cu")
		(net "M_F_CPU0_SB_CS_N<3>")
	)
	(segment
		(start 423.889424 -245.186962)
		(end 423.541444 -245.186962)
		(width 0.18288)
		(layer "In2.Cu")
		(net "M_F_CPU0_SB_CS_N<3>")
	)
	(segment
		(start 386.875782 -245.737126)
		(end 386.686298 -245.547642)
		(width 0.088646)
		(layer "In2.Cu")
		(net "M_F_CPU0_SB_CS_N<3>")
	)
	(segment
		(start 420.169848 -243.94668)
		(end 419.646354 -243.423186)
		(width 0.18288)
		(layer "In2.Cu")
		(net "M_F_CPU0_SB_CS_N<3>")
	)
	(segment
		(start 381.978408 -243.108988)
		(end 381.665734 -243.108988)
		(width 0.088646)
		(layer "In2.Cu")
		(net "M_F_CPU0_SB_CS_N<3>")
	)
	(segment
		(start 423.381424 -244.650768)
		(end 423.210736 -244.48008)
		(width 0.18288)
		(layer "In2.Cu")
		(net "M_F_CPU0_SB_CS_N<3>")
	)
	(segment
		(start 424.26001 -244.490748)
		(end 424.09999 -244.650768)
		(width 0.18288)
		(layer "In2.Cu")
		(net "M_F_CPU0_SB_CS_N<3>")
	)
	(segment
		(start 403.387814 -245.826788)
		(end 399.207228 -245.826788)
		(width 0.18288)
		(layer "In2.Cu")
		(net "M_F_CPU0_SB_CS_N<3>")
	)
	(segment
		(start 384.389884 -243.93271)
		(end 384.389884 -243.922804)
		(width 0.088646)
		(layer "In2.Cu")
		(net "M_F_CPU0_SB_CS_N<3>")
	)
	(segment
		(start 382.322832 -243.598446)
		(end 382.316736 -243.59489)
		(width 0.088646)
		(layer "In2.Cu")
		(net "M_F_CPU0_SB_CS_N<3>")
	)
	(segment
		(start 412.632652 -243.642642)
		(end 412.308548 -243.318538)
		(width 0.18288)
		(layer "In2.Cu")
		(net "M_F_CPU0_SB_CS_N<3>")
	)
	(segment
		(start 424.836082 -244.916706)
		(end 424.697652 -244.582696)
		(width 0.18288)
		(layer "In2.Cu")
		(net "M_F_CPU0_SB_CS_N<3>")
	)
	(segment
		(start 399.207228 -245.826788)
		(end 398.732756 -245.352316)
		(width 0.18288)
		(layer "In2.Cu")
		(net "M_F_CPU0_SB_CS_N<3>")
	)
	(segment
		(start 420.459662 -244.490748)
		(end 420.169848 -244.200934)
		(width 0.18288)
		(layer "In2.Cu")
		(net "M_F_CPU0_SB_CS_N<3>")
	)
	(segment
		(start 417.020756 -243.640864)
		(end 416.689794 -243.971826)
		(width 0.18288)
		(layer "In2.Cu")
		(net "M_F_CPU0_SB_CS_N<3>")
	)
	(segment
		(start 424.09999 -244.650768)
		(end 424.09999 -244.976396)
		(width 0.18288)
		(layer "In2.Cu")
		(net "M_F_CPU0_SB_CS_N<3>")
	)
	(segment
		(start 407.523442 -244.491002)
		(end 404.7236 -244.491002)
		(width 0.18288)
		(layer "In2.Cu")
		(net "M_F_CPU0_SB_CS_N<3>")
	)
	(segment
		(start 423.541444 -245.186962)
		(end 423.381424 -245.026942)
		(width 0.18288)
		(layer "In2.Cu")
		(net "M_F_CPU0_SB_CS_N<3>")
	)
	(segment
		(start 382.04394 -243.17452)
		(end 381.978408 -243.108988)
		(width 0.088646)
		(layer "In2.Cu")
		(net "M_F_CPU0_SB_CS_N<3>")
	)
	(segment
		(start 415.623756 -243.971826)
		(end 415.294572 -243.642642)
		(width 0.18288)
		(layer "In2.Cu")
		(net "M_F_CPU0_SB_CS_N<3>")
	)
	(segment
		(start 416.689794 -243.971826)
		(end 415.623756 -243.971826)
		(width 0.18288)
		(layer "In2.Cu")
		(net "M_F_CPU0_SB_CS_N<3>")
	)
	(segment
		(start 387.061964 -245.737126)
		(end 386.875782 -245.737126)
		(width 0.088646)
		(layer "In2.Cu")
		(net "M_F_CPU0_SB_CS_N<3>")
	)
	(segment
		(start 418.454586 -243.423186)
		(end 418.236908 -243.640864)
		(width 0.18288)
		(layer "In2.Cu")
		(net "M_F_CPU0_SB_CS_N<3>")
	)
	(segment
		(start 388.084314 -245.352316)
		(end 387.699504 -245.737126)
		(width 0.18288)
		(layer "In2.Cu")
		(net "M_F_CPU0_SB_CS_N<3>")
	)
	(segment
		(start 421.299894 -244.490748)
		(end 420.459662 -244.490748)
		(width 0.18288)
		(layer "In2.Cu")
		(net "M_F_CPU0_SB_CS_N<3>")
	)
	(segment
		(start 386.686298 -244.52834)
		(end 386.629656 -244.471698)
		(width 0.088646)
		(layer "In2.Cu")
		(net "M_F_CPU0_SB_CS_N<3>")
	)
	(segment
		(start 423.210736 -244.48008)
		(end 422.480994 -244.48008)
		(width 0.18288)
		(layer "In2.Cu")
		(net "M_F_CPU0_SB_CS_N<3>")
	)
	(segment
		(start 398.732756 -245.352316)
		(end 388.084314 -245.352316)
		(width 0.18288)
		(layer "In2.Cu")
		(net "M_F_CPU0_SB_CS_N<3>")
	)
	(segment
		(start 386.686298 -245.547642)
		(end 386.686298 -244.52834)
		(width 0.088646)
		(layer "In2.Cu")
		(net "M_F_CPU0_SB_CS_N<3>")
	)
	(segment
		(start 421.61714 -244.807994)
		(end 421.299894 -244.490748)
		(width 0.18288)
		(layer "In2.Cu")
		(net "M_F_CPU0_SB_CS_N<3>")
	)
	(segment
		(start 422.480994 -244.48008)
		(end 422.15308 -244.807994)
		(width 0.18288)
		(layer "In2.Cu")
		(net "M_F_CPU0_SB_CS_N<3>")
	)
	(segment
		(start 418.236908 -243.640864)
		(end 417.020756 -243.640864)
		(width 0.18288)
		(layer "In2.Cu")
		(net "M_F_CPU0_SB_CS_N<3>")
	)
	(segment
		(start 409.974288 -243.642642)
		(end 408.371802 -243.642642)
		(width 0.18288)
		(layer "In2.Cu")
		(net "M_F_CPU0_SB_CS_N<3>")
	)
	(segment
		(start 424.697652 -244.582696)
		(end 424.605704 -244.490748)
		(width 0.18288)
		(layer "In2.Cu")
		(net "M_F_CPU0_SB_CS_N<3>")
	)
	(segment
		(start 412.308548 -243.318538)
		(end 410.298392 -243.318538)
		(width 0.18288)
		(layer "In2.Cu")
		(net "M_F_CPU0_SB_CS_N<3>")
	)
	(segment
		(start 382.337564 -243.607082)
		(end 382.322832 -243.598446)
		(width 0.088646)
		(layer "In2.Cu")
		(net "M_F_CPU0_SB_CS_N<3>")
	)
	(segment
		(start 420.169848 -244.200934)
		(end 420.169848 -243.94668)
		(width 0.18288)
		(layer "In2.Cu")
		(net "M_F_CPU0_SB_CS_N<3>")
	)
	(segment
		(start 404.7236 -244.491002)
		(end 403.387814 -245.826788)
		(width 0.18288)
		(layer "In2.Cu")
		(net "M_F_CPU0_SB_CS_N<3>")
	)
	(segment
		(start 387.699504 -245.737126)
		(end 387.061964 -245.737126)
		(width 0.18288)
		(layer "In2.Cu")
		(net "M_F_CPU0_SB_CS_N<3>")
	)
	(segment
		(start 384.211322 -243.603526)
		(end 384.202432 -243.598446)
		(width 0.088646)
		(layer "In2.Cu")
		(net "M_F_CPU0_SB_CS_N<3>")
	)
	(segment
		(start 424.09999 -244.976396)
		(end 423.889424 -245.186962)
		(width 0.18288)
		(layer "In2.Cu")
		(net "M_F_CPU0_SB_CS_N<3>")
	)
	(arc
		(start 383.262632 -243.598446)
		(mid 383.075434 -243.548303)
		(end 382.888236 -243.598446)
		(width 0.088646)
		(layer "In2.Cu")
		(net "M_F_CPU0_SB_CS_N<3>")
	)
	(arc
		(start 385.612132 -244.412262)
		(mid 385.424934 -244.362119)
		(end 385.237736 -244.412262)
		(width 0.088646)
		(layer "In2.Cu")
		(net "M_F_CPU0_SB_CS_N<3>")
	)
	(arc
		(start 386.177536 -244.412262)
		(mid 385.894834 -244.488038)
		(end 385.612132 -244.412262)
		(width 0.088646)
		(layer "In2.Cu")
		(net "M_F_CPU0_SB_CS_N<3>")
	)
	(arc
		(start 385.237736 -244.412262)
		(mid 384.955034 -244.488038)
		(end 384.672332 -244.412262)
		(width 0.088646)
		(layer "In2.Cu")
		(net "M_F_CPU0_SB_CS_N<3>")
	)
	(arc
		(start 383.828036 -243.598446)
		(mid 383.545334 -243.674222)
		(end 383.262632 -243.598446)
		(width 0.088646)
		(layer "In2.Cu")
		(net "M_F_CPU0_SB_CS_N<3>")
	)
	(arc
		(start 386.551932 -244.412262)
		(mid 386.364734 -244.362119)
		(end 386.177536 -244.412262)
		(width 0.088646)
		(layer "In2.Cu")
		(net "M_F_CPU0_SB_CS_N<3>")
	)
	(arc
		(start 384.672332 -244.412262)
		(mid 384.467997 -244.209657)
		(end 384.389884 -243.93271)
		(width 0.088646)
		(layer "In2.Cu")
		(net "M_F_CPU0_SB_CS_N<3>")
	)
	(arc
		(start 384.202432 -243.598446)
		(mid 384.015234 -243.548303)
		(end 383.828036 -243.598446)
		(width 0.088646)
		(layer "In2.Cu")
		(net "M_F_CPU0_SB_CS_N<3>")
	)
	(arc
		(start 386.629656 -244.471698)
		(mid 386.592746 -244.439427)
		(end 386.551932 -244.412262)
		(width 0.088646)
		(layer "In2.Cu")
		(net "M_F_CPU0_SB_CS_N<3>")
	)
	(arc
		(start 382.316736 -243.59489)
		(mid 382.131213 -243.416589)
		(end 382.04394 -243.17452)
		(width 0.088646)
		(layer "In2.Cu")
		(net "M_F_CPU0_SB_CS_N<3>")
	)
	(arc
		(start 384.389884 -243.922804)
		(mid 384.342205 -243.739904)
		(end 384.211322 -243.603526)
		(width 0.088646)
		(layer "In2.Cu")
		(net "M_F_CPU0_SB_CS_N<3>")
	)
	(arc
		(start 382.888236 -243.598446)
		(mid 382.614037 -243.674281)
		(end 382.337564 -243.607082)
		(width 0.088646)
		(layer "In2.Cu")
		(net "M_F_CPU0_SB_CS_N<3>")
	)
	(segment
		(start 421.840914 -245.76659)
		(end 420.736014 -245.76659)
		(width 0.20066)
		(layer "F.Cu")
		(net "M_F_CPU0_SB_CS_N<2>")
	)
	(segment
		(start 381.19558 -244.458744)
		(end 381.195834 -244.45849)
		(width 0.20066)
		(layer "F.Cu")
		(net "M_F_CPU0_SB_CS_N<2>")
	)
	(segment
		(start 381.195834 -244.45849)
		(end 381.195834 -243.922804)
		(width 0.20066)
		(layer "F.Cu")
		(net "M_F_CPU0_SB_CS_N<2>")
	)
	(segment
		(start 386.296154 -245.421658)
		(end 386.16001 -245.285514)
		(width 0.088646)
		(layer "In2.Cu")
		(net "M_F_CPU0_SB_CS_N<2>")
	)
	(segment
		(start 386.296154 -246.15267)
		(end 386.296154 -245.421658)
		(width 0.088646)
		(layer "In2.Cu")
		(net "M_F_CPU0_SB_CS_N<2>")
	)
	(segment
		(start 403.62759 -246.869712)
		(end 403.309582 -246.869712)
		(width 0.18288)
		(layer "In2.Cu")
		(net "M_F_CPU0_SB_CS_N<2>")
	)
	(segment
		(start 410.184092 -245.584726)
		(end 410.184092 -246.006874)
		(width 0.18288)
		(layer "In2.Cu")
		(net "M_F_CPU0_SB_CS_N<2>")
	)
	(segment
		(start 419.169342 -246.207534)
		(end 418.428932 -245.467124)
		(width 0.18288)
		(layer "In2.Cu")
		(net "M_F_CPU0_SB_CS_N<2>")
	)
	(segment
		(start 413.514794 -246.232426)
		(end 413.362394 -246.080026)
		(width 0.18288)
		(layer "In2.Cu")
		(net "M_F_CPU0_SB_CS_N<2>")
	)
	(segment
		(start 388.178548 -246.61241)
		(end 386.755894 -246.61241)
		(width 0.18288)
		(layer "In2.Cu")
		(net "M_F_CPU0_SB_CS_N<2>")
	)
	(segment
		(start 408.90952 -246.172228)
		(end 408.716226 -245.978934)
		(width 0.18288)
		(layer "In2.Cu")
		(net "M_F_CPU0_SB_CS_N<2>")
	)
	(segment
		(start 409.043886 -246.523256)
		(end 408.90952 -246.38889)
		(width 0.18288)
		(layer "In2.Cu")
		(net "M_F_CPU0_SB_CS_N<2>")
	)
	(segment
		(start 386.755894 -246.61241)
		(end 386.430774 -246.28729)
		(width 0.18288)
		(layer "In2.Cu")
		(net "M_F_CPU0_SB_CS_N<2>")
	)
	(segment
		(start 415.48685 -245.851426)
		(end 415.10585 -246.232426)
		(width 0.18288)
		(layer "In2.Cu")
		(net "M_F_CPU0_SB_CS_N<2>")
	)
	(segment
		(start 403.82063 -247.255284)
		(end 403.82063 -247.062752)
		(width 0.18288)
		(layer "In2.Cu")
		(net "M_F_CPU0_SB_CS_N<2>")
	)
	(segment
		(start 410.476192 -245.292626)
		(end 410.184092 -245.584726)
		(width 0.18288)
		(layer "In2.Cu")
		(net "M_F_CPU0_SB_CS_N<2>")
	)
	(segment
		(start 418.428932 -245.467124)
		(end 418.019484 -245.467124)
		(width 0.18288)
		(layer "In2.Cu")
		(net "M_F_CPU0_SB_CS_N<2>")
	)
	(segment
		(start 398.790922 -246.886984)
		(end 398.338548 -246.43461)
		(width 0.18288)
		(layer "In2.Cu")
		(net "M_F_CPU0_SB_CS_N<2>")
	)
	(segment
		(start 408.90952 -246.38889)
		(end 408.90952 -246.172228)
		(width 0.18288)
		(layer "In2.Cu")
		(net "M_F_CPU0_SB_CS_N<2>")
	)
	(segment
		(start 403.116542 -247.255284)
		(end 402.923502 -247.448324)
		(width 0.18288)
		(layer "In2.Cu")
		(net "M_F_CPU0_SB_CS_N<2>")
	)
	(segment
		(start 410.184092 -246.006874)
		(end 409.66771 -246.523256)
		(width 0.18288)
		(layer "In2.Cu")
		(net "M_F_CPU0_SB_CS_N<2>")
	)
	(segment
		(start 403.309582 -246.869712)
		(end 403.116542 -247.062752)
		(width 0.18288)
		(layer "In2.Cu")
		(net "M_F_CPU0_SB_CS_N<2>")
	)
	(segment
		(start 381.852932 -244.412262)
		(end 381.824738 -244.396006)
		(width 0.088646)
		(layer "In2.Cu")
		(net "M_F_CPU0_SB_CS_N<2>")
	)
	(segment
		(start 403.116542 -247.062752)
		(end 403.116542 -247.255284)
		(width 0.18288)
		(layer "In2.Cu")
		(net "M_F_CPU0_SB_CS_N<2>")
	)
	(segment
		(start 404.233888 -247.448324)
		(end 404.01367 -247.448324)
		(width 0.18288)
		(layer "In2.Cu")
		(net "M_F_CPU0_SB_CS_N<2>")
	)
	(segment
		(start 404.01367 -247.448324)
		(end 403.82063 -247.255284)
		(width 0.18288)
		(layer "In2.Cu")
		(net "M_F_CPU0_SB_CS_N<2>")
	)
	(segment
		(start 418.019484 -245.467124)
		(end 417.826444 -245.660164)
		(width 0.18288)
		(layer "In2.Cu")
		(net "M_F_CPU0_SB_CS_N<2>")
	)
	(segment
		(start 413.362394 -246.080026)
		(end 412.538926 -246.080026)
		(width 0.18288)
		(layer "In2.Cu")
		(net "M_F_CPU0_SB_CS_N<2>")
	)
	(segment
		(start 409.66771 -246.523256)
		(end 409.043886 -246.523256)
		(width 0.18288)
		(layer "In2.Cu")
		(net "M_F_CPU0_SB_CS_N<2>")
	)
	(segment
		(start 401.943316 -246.886984)
		(end 398.790922 -246.886984)
		(width 0.18288)
		(layer "In2.Cu")
		(net "M_F_CPU0_SB_CS_N<2>")
	)
	(segment
		(start 383.358136 -244.412262)
		(end 383.347722 -244.418358)
		(width 0.088646)
		(layer "In2.Cu")
		(net "M_F_CPU0_SB_CS_N<2>")
	)
	(segment
		(start 383.732786 -244.412516)
		(end 383.732532 -244.412262)
		(width 0.088646)
		(layer "In2.Cu")
		(net "M_F_CPU0_SB_CS_N<2>")
	)
	(segment
		(start 405.038814 -245.905528)
		(end 404.845774 -246.098568)
		(width 0.18288)
		(layer "In2.Cu")
		(net "M_F_CPU0_SB_CS_N<2>")
	)
	(segment
		(start 404.845774 -246.836438)
		(end 404.233888 -247.448324)
		(width 0.18288)
		(layer "In2.Cu")
		(net "M_F_CPU0_SB_CS_N<2>")
	)
	(segment
		(start 420.736014 -245.76659)
		(end 420.29507 -246.207534)
		(width 0.18288)
		(layer "In2.Cu")
		(net "M_F_CPU0_SB_CS_N<2>")
	)
	(segment
		(start 403.82063 -247.062752)
		(end 403.62759 -246.869712)
		(width 0.18288)
		(layer "In2.Cu")
		(net "M_F_CPU0_SB_CS_N<2>")
	)
	(segment
		(start 412.425642 -245.53037)
		(end 412.42869 -245.527322)
		(width 0.18288)
		(layer "In2.Cu")
		(net "M_F_CPU0_SB_CS_N<2>")
	)
	(segment
		(start 383.919984 -244.737128)
		(end 383.919984 -244.73662)
		(width 0.088646)
		(layer "In2.Cu")
		(net "M_F_CPU0_SB_CS_N<2>")
	)
	(segment
		(start 388.356348 -246.43461)
		(end 388.178548 -246.61241)
		(width 0.18288)
		(layer "In2.Cu")
		(net "M_F_CPU0_SB_CS_N<2>")
	)
	(segment
		(start 406.127204 -246.482362)
		(end 405.55037 -245.905528)
		(width 0.18288)
		(layer "In2.Cu")
		(net "M_F_CPU0_SB_CS_N<2>")
	)
	(segment
		(start 417.826444 -246.004842)
		(end 417.471352 -246.359934)
		(width 0.18288)
		(layer "In2.Cu")
		(net "M_F_CPU0_SB_CS_N<2>")
	)
	(segment
		(start 381.824738 -244.396006)
		(end 381.195834 -243.922804)
		(width 0.088646)
		(layer "In2.Cu")
		(net "M_F_CPU0_SB_CS_N<2>")
	)
	(segment
		(start 382.418082 -244.412262)
		(end 382.417828 -244.412262)
		(width 0.088646)
		(layer "In2.Cu")
		(net "M_F_CPU0_SB_CS_N<2>")
	)
	(segment
		(start 407.354532 -246.482362)
		(end 406.127204 -246.482362)
		(width 0.18288)
		(layer "In2.Cu")
		(net "M_F_CPU0_SB_CS_N<2>")
	)
	(segment
		(start 412.42869 -245.527322)
		(end 412.193994 -245.292626)
		(width 0.18288)
		(layer "In2.Cu")
		(net "M_F_CPU0_SB_CS_N<2>")
	)
	(segment
		(start 407.85796 -245.978934)
		(end 407.354532 -246.482362)
		(width 0.18288)
		(layer "In2.Cu")
		(net "M_F_CPU0_SB_CS_N<2>")
	)
	(segment
		(start 420.29507 -246.207534)
		(end 419.169342 -246.207534)
		(width 0.18288)
		(layer "In2.Cu")
		(net "M_F_CPU0_SB_CS_N<2>")
	)
	(segment
		(start 416.689794 -245.851426)
		(end 415.48685 -245.851426)
		(width 0.18288)
		(layer "In2.Cu")
		(net "M_F_CPU0_SB_CS_N<2>")
	)
	(segment
		(start 398.338548 -246.43461)
		(end 388.356348 -246.43461)
		(width 0.18288)
		(layer "In2.Cu")
		(net "M_F_CPU0_SB_CS_N<2>")
	)
	(segment
		(start 412.193994 -245.292626)
		(end 410.476192 -245.292626)
		(width 0.18288)
		(layer "In2.Cu")
		(net "M_F_CPU0_SB_CS_N<2>")
	)
	(segment
		(start 402.923502 -247.448324)
		(end 402.504656 -247.448324)
		(width 0.18288)
		(layer "In2.Cu")
		(net "M_F_CPU0_SB_CS_N<2>")
	)
	(segment
		(start 386.430774 -246.28729)
		(end 386.296154 -246.15267)
		(width 0.088646)
		(layer "In2.Cu")
		(net "M_F_CPU0_SB_CS_N<2>")
	)
	(segment
		(start 404.845774 -246.098568)
		(end 404.845774 -246.836438)
		(width 0.18288)
		(layer "In2.Cu")
		(net "M_F_CPU0_SB_CS_N<2>")
	)
	(segment
		(start 402.504656 -247.448324)
		(end 401.943316 -246.886984)
		(width 0.18288)
		(layer "In2.Cu")
		(net "M_F_CPU0_SB_CS_N<2>")
	)
	(segment
		(start 415.10585 -246.232426)
		(end 413.514794 -246.232426)
		(width 0.18288)
		(layer "In2.Cu")
		(net "M_F_CPU0_SB_CS_N<2>")
	)
	(segment
		(start 417.198302 -246.359934)
		(end 416.689794 -245.851426)
		(width 0.18288)
		(layer "In2.Cu")
		(net "M_F_CPU0_SB_CS_N<2>")
	)
	(segment
		(start 405.55037 -245.905528)
		(end 405.038814 -245.905528)
		(width 0.18288)
		(layer "In2.Cu")
		(net "M_F_CPU0_SB_CS_N<2>")
	)
	(segment
		(start 408.716226 -245.978934)
		(end 407.85796 -245.978934)
		(width 0.18288)
		(layer "In2.Cu")
		(net "M_F_CPU0_SB_CS_N<2>")
	)
	(segment
		(start 417.826444 -245.660164)
		(end 417.826444 -246.004842)
		(width 0.18288)
		(layer "In2.Cu")
		(net "M_F_CPU0_SB_CS_N<2>")
	)
	(segment
		(start 417.471352 -246.359934)
		(end 417.198302 -246.359934)
		(width 0.18288)
		(layer "In2.Cu")
		(net "M_F_CPU0_SB_CS_N<2>")
	)
	(segment
		(start 412.538926 -246.080026)
		(end 412.425642 -245.966742)
		(width 0.18288)
		(layer "In2.Cu")
		(net "M_F_CPU0_SB_CS_N<2>")
	)
	(segment
		(start 412.425642 -245.966742)
		(end 412.425642 -245.53037)
		(width 0.18288)
		(layer "In2.Cu")
		(net "M_F_CPU0_SB_CS_N<2>")
	)
	(arc
		(start 386.082032 -245.226332)
		(mid 385.894834 -245.176189)
		(end 385.707636 -245.226332)
		(width 0.088646)
		(layer "In2.Cu")
		(net "M_F_CPU0_SB_CS_N<2>")
	)
	(arc
		(start 382.417828 -244.412262)
		(mid 382.13538 -244.487945)
		(end 381.852932 -244.412262)
		(width 0.088646)
		(layer "In2.Cu")
		(net "M_F_CPU0_SB_CS_N<2>")
	)
	(arc
		(start 382.792478 -244.412262)
		(mid 382.60528 -244.362119)
		(end 382.418082 -244.412262)
		(width 0.088646)
		(layer "In2.Cu")
		(net "M_F_CPU0_SB_CS_N<2>")
	)
	(arc
		(start 385.707636 -245.226332)
		(mid 385.424934 -245.302074)
		(end 385.142232 -245.226332)
		(width 0.088646)
		(layer "In2.Cu")
		(net "M_F_CPU0_SB_CS_N<2>")
	)
	(arc
		(start 384.202432 -245.226332)
		(mid 383.995672 -245.019569)
		(end 383.919984 -244.737128)
		(width 0.088646)
		(layer "In2.Cu")
		(net "M_F_CPU0_SB_CS_N<2>")
	)
	(arc
		(start 383.919984 -244.73662)
		(mid 383.86982 -244.549482)
		(end 383.732786 -244.412516)
		(width 0.088646)
		(layer "In2.Cu")
		(net "M_F_CPU0_SB_CS_N<2>")
	)
	(arc
		(start 383.347722 -244.418358)
		(mid 383.06929 -244.488204)
		(end 382.792478 -244.412262)
		(width 0.088646)
		(layer "In2.Cu")
		(net "M_F_CPU0_SB_CS_N<2>")
	)
	(arc
		(start 386.16001 -245.285514)
		(mid 386.12296 -245.253368)
		(end 386.082032 -245.226332)
		(width 0.088646)
		(layer "In2.Cu")
		(net "M_F_CPU0_SB_CS_N<2>")
	)
	(arc
		(start 384.767836 -245.226332)
		(mid 384.485134 -245.302074)
		(end 384.202432 -245.226332)
		(width 0.088646)
		(layer "In2.Cu")
		(net "M_F_CPU0_SB_CS_N<2>")
	)
	(arc
		(start 385.142232 -245.226332)
		(mid 384.955034 -245.176189)
		(end 384.767836 -245.226332)
		(width 0.088646)
		(layer "In2.Cu")
		(net "M_F_CPU0_SB_CS_N<2>")
	)
	(arc
		(start 383.732532 -244.412262)
		(mid 383.545334 -244.362119)
		(end 383.358136 -244.412262)
		(width 0.088646)
		(layer "In2.Cu")
		(net "M_F_CPU0_SB_CS_N<2>")
	)
	(segment
		(start 382.605534 -243.644928)
		(end 382.60528 -243.644674)
		(width 0.20066)
		(layer "F.Cu")
		(net "M_F_CPU0_SB_CS_N<1>")
	)
	(segment
		(start 433.484782 -244.916706)
		(end 432.379882 -244.916706)
		(width 0.20066)
		(layer "F.Cu")
		(net "M_F_CPU0_SB_CS_N<1>")
	)
	(segment
		(start 382.60528 -243.644674)
		(end 382.60528 -243.108988)
		(width 0.20066)
		(layer "F.Cu")
		(net "M_F_CPU0_SB_CS_N<1>")
	)
	(segment
		(start 422.739312 -242.79225)
		(end 420.2557 -242.79225)
		(width 0.18288)
		(layer "In2.Cu")
		(net "M_F_CPU0_SB_CS_N<1>")
	)
	(segment
		(start 420.08171 -242.61826)
		(end 420.08171 -242.213384)
		(width 0.18288)
		(layer "In2.Cu")
		(net "M_F_CPU0_SB_CS_N<1>")
	)
	(segment
		(start 423.571416 -242.907058)
		(end 422.85412 -242.907058)
		(width 0.18288)
		(layer "In2.Cu")
		(net "M_F_CPU0_SB_CS_N<1>")
	)
	(segment
		(start 427.822868 -242.79479)
		(end 427.650148 -242.62207)
		(width 0.18288)
		(layer "In2.Cu")
		(net "M_F_CPU0_SB_CS_N<1>")
	)
	(segment
		(start 420.08171 -242.213384)
		(end 419.92169 -242.053364)
		(width 0.18288)
		(layer "In2.Cu")
		(net "M_F_CPU0_SB_CS_N<1>")
	)
	(segment
		(start 423.683684 -242.79479)
		(end 423.571416 -242.907058)
		(width 0.18288)
		(layer "In2.Cu")
		(net "M_F_CPU0_SB_CS_N<1>")
	)
	(segment
		(start 426.855636 -242.62207)
		(end 426.682916 -242.79479)
		(width 0.18288)
		(layer "In2.Cu")
		(net "M_F_CPU0_SB_CS_N<1>")
	)
	(segment
		(start 399.396458 -245.290848)
		(end 398.867376 -244.761766)
		(width 0.18288)
		(layer "In2.Cu")
		(net "M_F_CPU0_SB_CS_N<1>")
	)
	(segment
		(start 382.235456 -243.166138)
		(end 382.292606 -243.108988)
		(width 0.088646)
		(layer "In2.Cu")
		(net "M_F_CPU0_SB_CS_N<1>")
	)
	(segment
		(start 387.937756 -244.761766)
		(end 387.786626 -244.912896)
		(width 0.18288)
		(layer "In2.Cu")
		(net "M_F_CPU0_SB_CS_N<1>")
	)
	(segment
		(start 415.360612 -243.054124)
		(end 415.097468 -242.79098)
		(width 0.18288)
		(layer "In2.Cu")
		(net "M_F_CPU0_SB_CS_N<1>")
	)
	(segment
		(start 387.340602 -244.912896)
		(end 386.76453 -244.336824)
		(width 0.088646)
		(layer "In2.Cu")
		(net "M_F_CPU0_SB_CS_N<1>")
	)
	(segment
		(start 432.379882 -244.916706)
		(end 430.257966 -242.79479)
		(width 0.18288)
		(layer "In2.Cu")
		(net "M_F_CPU0_SB_CS_N<1>")
	)
	(segment
		(start 404.838662 -243.642388)
		(end 403.190202 -245.290848)
		(width 0.18288)
		(layer "In2.Cu")
		(net "M_F_CPU0_SB_CS_N<1>")
	)
	(segment
		(start 384.767836 -244.247162)
		(end 384.758946 -244.242082)
		(width 0.088646)
		(layer "In2.Cu")
		(net "M_F_CPU0_SB_CS_N<1>")
	)
	(segment
		(start 427.650148 -242.62207)
		(end 427.650148 -242.167156)
		(width 0.18288)
		(layer "In2.Cu")
		(net "M_F_CPU0_SB_CS_N<1>")
	)
	(segment
		(start 419.638988 -242.053364)
		(end 419.3413 -242.351052)
		(width 0.18288)
		(layer "In2.Cu")
		(net "M_F_CPU0_SB_CS_N<1>")
	)
	(segment
		(start 416.479736 -242.79098)
		(end 416.216592 -243.054124)
		(width 0.18288)
		(layer "In2.Cu")
		(net "M_F_CPU0_SB_CS_N<1>")
	)
	(segment
		(start 419.18128 -242.79098)
		(end 416.479736 -242.79098)
		(width 0.18288)
		(layer "In2.Cu")
		(net "M_F_CPU0_SB_CS_N<1>")
	)
	(segment
		(start 419.92169 -242.053364)
		(end 419.638988 -242.053364)
		(width 0.18288)
		(layer "In2.Cu")
		(net "M_F_CPU0_SB_CS_N<1>")
	)
	(segment
		(start 403.190202 -245.290848)
		(end 399.396458 -245.290848)
		(width 0.18288)
		(layer "In2.Cu")
		(net "M_F_CPU0_SB_CS_N<1>")
	)
	(segment
		(start 407.515568 -243.640864)
		(end 405.543766 -243.640864)
		(width 0.18288)
		(layer "In2.Cu")
		(net "M_F_CPU0_SB_CS_N<1>")
	)
	(segment
		(start 427.650148 -242.167156)
		(end 427.490128 -242.007136)
		(width 0.18288)
		(layer "In2.Cu")
		(net "M_F_CPU0_SB_CS_N<1>")
	)
	(segment
		(start 384.580384 -243.922804)
		(end 384.580384 -243.912898)
		(width 0.088646)
		(layer "In2.Cu")
		(net "M_F_CPU0_SB_CS_N<1>")
	)
	(segment
		(start 427.015656 -242.007136)
		(end 426.855636 -242.167156)
		(width 0.18288)
		(layer "In2.Cu")
		(net "M_F_CPU0_SB_CS_N<1>")
	)
	(segment
		(start 426.855636 -242.167156)
		(end 426.855636 -242.62207)
		(width 0.18288)
		(layer "In2.Cu")
		(net "M_F_CPU0_SB_CS_N<1>")
	)
	(segment
		(start 383.358136 -243.433346)
		(end 383.347722 -243.42725)
		(width 0.088646)
		(layer "In2.Cu")
		(net "M_F_CPU0_SB_CS_N<1>")
	)
	(segment
		(start 408.365452 -242.79098)
		(end 407.515568 -243.640864)
		(width 0.18288)
		(layer "In2.Cu")
		(net "M_F_CPU0_SB_CS_N<1>")
	)
	(segment
		(start 382.292606 -243.108988)
		(end 382.60528 -243.108988)
		(width 0.088646)
		(layer "In2.Cu")
		(net "M_F_CPU0_SB_CS_N<1>")
	)
	(segment
		(start 426.682916 -242.79479)
		(end 423.683684 -242.79479)
		(width 0.18288)
		(layer "In2.Cu")
		(net "M_F_CPU0_SB_CS_N<1>")
	)
	(segment
		(start 398.867376 -244.761766)
		(end 387.937756 -244.761766)
		(width 0.18288)
		(layer "In2.Cu")
		(net "M_F_CPU0_SB_CS_N<1>")
	)
	(segment
		(start 405.542242 -243.642388)
		(end 404.838662 -243.642388)
		(width 0.18288)
		(layer "In2.Cu")
		(net "M_F_CPU0_SB_CS_N<1>")
	)
	(segment
		(start 416.216592 -243.054124)
		(end 415.360612 -243.054124)
		(width 0.18288)
		(layer "In2.Cu")
		(net "M_F_CPU0_SB_CS_N<1>")
	)
	(segment
		(start 419.3413 -242.351052)
		(end 419.3413 -242.63096)
		(width 0.18288)
		(layer "In2.Cu")
		(net "M_F_CPU0_SB_CS_N<1>")
	)
	(segment
		(start 419.3413 -242.63096)
		(end 419.18128 -242.79098)
		(width 0.18288)
		(layer "In2.Cu")
		(net "M_F_CPU0_SB_CS_N<1>")
	)
	(segment
		(start 387.519164 -244.912896)
		(end 387.340602 -244.912896)
		(width 0.088646)
		(layer "In2.Cu")
		(net "M_F_CPU0_SB_CS_N<1>")
	)
	(segment
		(start 427.490128 -242.007136)
		(end 427.015656 -242.007136)
		(width 0.18288)
		(layer "In2.Cu")
		(net "M_F_CPU0_SB_CS_N<1>")
	)
	(segment
		(start 420.2557 -242.79225)
		(end 420.08171 -242.61826)
		(width 0.18288)
		(layer "In2.Cu")
		(net "M_F_CPU0_SB_CS_N<1>")
	)
	(segment
		(start 387.786626 -244.912896)
		(end 387.519164 -244.912896)
		(width 0.18288)
		(layer "In2.Cu")
		(net "M_F_CPU0_SB_CS_N<1>")
	)
	(segment
		(start 405.543766 -243.640864)
		(end 405.542242 -243.642388)
		(width 0.18288)
		(layer "In2.Cu")
		(net "M_F_CPU0_SB_CS_N<1>")
	)
	(segment
		(start 415.097468 -242.79098)
		(end 408.365452 -242.79098)
		(width 0.18288)
		(layer "In2.Cu")
		(net "M_F_CPU0_SB_CS_N<1>")
	)
	(segment
		(start 430.257966 -242.79479)
		(end 427.822868 -242.79479)
		(width 0.18288)
		(layer "In2.Cu")
		(net "M_F_CPU0_SB_CS_N<1>")
	)
	(segment
		(start 422.85412 -242.907058)
		(end 422.739312 -242.79225)
		(width 0.18288)
		(layer "In2.Cu")
		(net "M_F_CPU0_SB_CS_N<1>")
	)
	(arc
		(start 382.418082 -243.433346)
		(mid 382.296414 -243.320491)
		(end 382.235456 -243.166138)
		(width 0.088646)
		(layer "In2.Cu")
		(net "M_F_CPU0_SB_CS_N<1>")
	)
	(arc
		(start 386.647436 -244.247162)
		(mid 386.364734 -244.171386)
		(end 386.082032 -244.247162)
		(width 0.088646)
		(layer "In2.Cu")
		(net "M_F_CPU0_SB_CS_N<1>")
	)
	(arc
		(start 386.76453 -244.336824)
		(mid 386.708925 -244.28815)
		(end 386.647436 -244.247162)
		(width 0.088646)
		(layer "In2.Cu")
		(net "M_F_CPU0_SB_CS_N<1>")
	)
	(arc
		(start 386.082032 -244.247162)
		(mid 385.894834 -244.297305)
		(end 385.707636 -244.247162)
		(width 0.088646)
		(layer "In2.Cu")
		(net "M_F_CPU0_SB_CS_N<1>")
	)
	(arc
		(start 383.347722 -243.42725)
		(mid 383.06929 -243.357404)
		(end 382.792478 -243.433346)
		(width 0.088646)
		(layer "In2.Cu")
		(net "M_F_CPU0_SB_CS_N<1>")
	)
	(arc
		(start 383.732532 -243.433346)
		(mid 383.545334 -243.483489)
		(end 383.358136 -243.433346)
		(width 0.088646)
		(layer "In2.Cu")
		(net "M_F_CPU0_SB_CS_N<1>")
	)
	(arc
		(start 384.758946 -244.242082)
		(mid 384.628032 -244.105722)
		(end 384.580384 -243.922804)
		(width 0.088646)
		(layer "In2.Cu")
		(net "M_F_CPU0_SB_CS_N<1>")
	)
	(arc
		(start 384.580384 -243.912898)
		(mid 384.502273 -243.635949)
		(end 384.297936 -243.433346)
		(width 0.088646)
		(layer "In2.Cu")
		(net "M_F_CPU0_SB_CS_N<1>")
	)
	(arc
		(start 385.707636 -244.247162)
		(mid 385.424934 -244.171386)
		(end 385.142232 -244.247162)
		(width 0.088646)
		(layer "In2.Cu")
		(net "M_F_CPU0_SB_CS_N<1>")
	)
	(arc
		(start 385.142232 -244.247162)
		(mid 384.955034 -244.297305)
		(end 384.767836 -244.247162)
		(width 0.088646)
		(layer "In2.Cu")
		(net "M_F_CPU0_SB_CS_N<1>")
	)
	(arc
		(start 384.297936 -243.433346)
		(mid 384.015234 -243.35757)
		(end 383.732532 -243.433346)
		(width 0.088646)
		(layer "In2.Cu")
		(net "M_F_CPU0_SB_CS_N<1>")
	)
	(arc
		(start 382.792478 -243.433346)
		(mid 382.60528 -243.483489)
		(end 382.418082 -243.433346)
		(width 0.088646)
		(layer "In2.Cu")
		(net "M_F_CPU0_SB_CS_N<1>")
	)
	(segment
		(start 429.384714 -245.76659)
		(end 428.279814 -245.76659)
		(width 0.20066)
		(layer "F.Cu")
		(net "M_F_CPU0_SB_CS_N<0>")
	)
	(segment
		(start 383.07518 -244.458744)
		(end 383.07518 -243.923058)
		(width 0.20066)
		(layer "F.Cu")
		(net "M_F_CPU0_SB_CS_N<0>")
	)
	(segment
		(start 383.07518 -243.923058)
		(end 383.075434 -243.922804)
		(width 0.20066)
		(layer "F.Cu")
		(net "M_F_CPU0_SB_CS_N<0>")
	)
	(segment
		(start 419.676834 -244.556026)
		(end 419.30574 -244.556026)
		(width 0.18288)
		(layer "In2.Cu")
		(net "M_F_CPU0_SB_CS_N<0>")
	)
	(segment
		(start 386.4864 -245.821708)
		(end 386.4864 -245.342664)
		(width 0.088646)
		(layer "In2.Cu")
		(net "M_F_CPU0_SB_CS_N<0>")
	)
	(segment
		(start 423.152062 -245.766844)
		(end 422.729914 -245.344696)
		(width 0.18288)
		(layer "In2.Cu")
		(net "M_F_CPU0_SB_CS_N<0>")
	)
	(segment
		(start 409.2067 -244.84584)
		(end 409.2067 -244.346984)
		(width 0.18288)
		(layer "In2.Cu")
		(net "M_F_CPU0_SB_CS_N<0>")
	)
	(segment
		(start 409.01366 -244.153944)
		(end 408.596846 -244.153944)
		(width 0.18288)
		(layer "In2.Cu")
		(net "M_F_CPU0_SB_CS_N<0>")
	)
	(segment
		(start 407.632154 -245.404386)
		(end 407.227024 -244.999256)
		(width 0.18288)
		(layer "In2.Cu")
		(net "M_F_CPU0_SB_CS_N<0>")
	)
	(segment
		(start 420.465504 -245.344696)
		(end 419.676834 -244.556026)
		(width 0.18288)
		(layer "In2.Cu")
		(net "M_F_CPU0_SB_CS_N<0>")
	)
	(segment
		(start 412.701994 -244.74297)
		(end 412.541974 -244.58295)
		(width 0.18288)
		(layer "In2.Cu")
		(net "M_F_CPU0_SB_CS_N<0>")
	)
	(segment
		(start 413.69361 -245.08841)
		(end 413.387794 -245.394226)
		(width 0.18288)
		(layer "In2.Cu")
		(net "M_F_CPU0_SB_CS_N<0>")
	)
	(segment
		(start 417.85159 -244.161056)
		(end 417.45662 -244.556026)
		(width 0.18288)
		(layer "In2.Cu")
		(net "M_F_CPU0_SB_CS_N<0>")
	)
	(segment
		(start 410.521404 -244.312186)
		(end 410.328364 -244.505226)
		(width 0.18288)
		(layer "In2.Cu")
		(net "M_F_CPU0_SB_CS_N<0>")
	)
	(segment
		(start 426.230288 -246.203216)
		(end 425.863766 -246.203216)
		(width 0.18288)
		(layer "In2.Cu")
		(net "M_F_CPU0_SB_CS_N<0>")
	)
	(segment
		(start 424.455336 -245.343172)
		(end 424.031664 -245.766844)
		(width 0.18288)
		(layer "In2.Cu")
		(net "M_F_CPU0_SB_CS_N<0>")
	)
	(segment
		(start 411.225492 -244.02034)
		(end 411.032452 -243.8273)
		(width 0.18288)
		(layer "In2.Cu")
		(net "M_F_CPU0_SB_CS_N<0>")
	)
	(segment
		(start 418.91077 -244.161056)
		(end 417.85159 -244.161056)
		(width 0.18288)
		(layer "In2.Cu")
		(net "M_F_CPU0_SB_CS_N<0>")
	)
	(segment
		(start 427.819312 -245.306088)
		(end 426.578776 -245.306088)
		(width 0.18288)
		(layer "In2.Cu")
		(net "M_F_CPU0_SB_CS_N<0>")
	)
	(segment
		(start 425.863766 -246.203216)
		(end 425.689268 -246.028718)
		(width 0.18288)
		(layer "In2.Cu")
		(net "M_F_CPU0_SB_CS_N<0>")
	)
	(segment
		(start 388.24408 -245.92661)
		(end 387.94436 -246.22633)
		(width 0.18288)
		(layer "In2.Cu")
		(net "M_F_CPU0_SB_CS_N<0>")
	)
	(segment
		(start 412.701994 -245.076726)
		(end 412.701994 -244.74297)
		(width 0.18288)
		(layer "In2.Cu")
		(net "M_F_CPU0_SB_CS_N<0>")
	)
	(segment
		(start 417.053014 -244.556026)
		(end 416.867594 -244.741446)
		(width 0.18288)
		(layer "In2.Cu")
		(net "M_F_CPU0_SB_CS_N<0>")
	)
	(segment
		(start 416.003994 -245.15318)
		(end 416.003994 -244.639846)
		(width 0.18288)
		(layer "In2.Cu")
		(net "M_F_CPU0_SB_CS_N<0>")
	)
	(segment
		(start 403.601936 -246.35079)
		(end 398.999964 -246.35079)
		(width 0.18288)
		(layer "In2.Cu")
		(net "M_F_CPU0_SB_CS_N<0>")
	)
	(segment
		(start 408.417522 -244.333268)
		(end 408.417522 -245.056406)
		(width 0.18288)
		(layer "In2.Cu")
		(net "M_F_CPU0_SB_CS_N<0>")
	)
	(segment
		(start 428.279814 -245.76659)
		(end 427.819312 -245.306088)
		(width 0.18288)
		(layer "In2.Cu")
		(net "M_F_CPU0_SB_CS_N<0>")
	)
	(segment
		(start 404.57247 -245.380256)
		(end 403.601936 -246.35079)
		(width 0.18288)
		(layer "In2.Cu")
		(net "M_F_CPU0_SB_CS_N<0>")
	)
	(segment
		(start 406.26411 -244.999256)
		(end 405.88311 -245.380256)
		(width 0.18288)
		(layer "In2.Cu")
		(net "M_F_CPU0_SB_CS_N<0>")
	)
	(segment
		(start 408.596846 -244.153944)
		(end 408.417522 -244.333268)
		(width 0.18288)
		(layer "In2.Cu")
		(net "M_F_CPU0_SB_CS_N<0>")
	)
	(segment
		(start 384.297936 -245.060978)
		(end 384.297936 -245.060724)
		(width 0.088646)
		(layer "In2.Cu")
		(net "M_F_CPU0_SB_CS_N<0>")
	)
	(segment
		(start 411.225492 -244.312186)
		(end 411.225492 -244.02034)
		(width 0.18288)
		(layer "In2.Cu")
		(net "M_F_CPU0_SB_CS_N<0>")
	)
	(segment
		(start 409.333954 -244.973094)
		(end 409.2067 -244.84584)
		(width 0.18288)
		(layer "In2.Cu")
		(net "M_F_CPU0_SB_CS_N<0>")
	)
	(segment
		(start 405.88311 -245.380256)
		(end 404.57247 -245.380256)
		(width 0.18288)
		(layer "In2.Cu")
		(net "M_F_CPU0_SB_CS_N<0>")
	)
	(segment
		(start 407.227024 -244.999256)
		(end 406.26411 -244.999256)
		(width 0.18288)
		(layer "In2.Cu")
		(net "M_F_CPU0_SB_CS_N<0>")
	)
	(segment
		(start 386.4864 -245.342664)
		(end 386.29463 -245.150894)
		(width 0.088646)
		(layer "In2.Cu")
		(net "M_F_CPU0_SB_CS_N<0>")
	)
	(segment
		(start 415.843974 -244.479826)
		(end 413.837628 -244.479826)
		(width 0.18288)
		(layer "In2.Cu")
		(net "M_F_CPU0_SB_CS_N<0>")
	)
	(segment
		(start 426.578776 -245.306088)
		(end 426.418756 -245.466108)
		(width 0.18288)
		(layer "In2.Cu")
		(net "M_F_CPU0_SB_CS_N<0>")
	)
	(segment
		(start 412.541974 -244.58295)
		(end 411.848046 -244.58295)
		(width 0.18288)
		(layer "In2.Cu")
		(net "M_F_CPU0_SB_CS_N<0>")
	)
	(segment
		(start 409.2067 -244.346984)
		(end 409.01366 -244.153944)
		(width 0.18288)
		(layer "In2.Cu")
		(net "M_F_CPU0_SB_CS_N<0>")
	)
	(segment
		(start 408.069542 -245.404386)
		(end 407.632154 -245.404386)
		(width 0.18288)
		(layer "In2.Cu")
		(net "M_F_CPU0_SB_CS_N<0>")
	)
	(segment
		(start 411.032452 -243.8273)
		(end 410.721048 -243.8273)
		(width 0.18288)
		(layer "In2.Cu")
		(net "M_F_CPU0_SB_CS_N<0>")
	)
	(segment
		(start 416.867594 -244.741446)
		(end 416.867594 -245.15318)
		(width 0.18288)
		(layer "In2.Cu")
		(net "M_F_CPU0_SB_CS_N<0>")
	)
	(segment
		(start 410.11221 -244.505226)
		(end 409.644342 -244.973094)
		(width 0.18288)
		(layer "In2.Cu")
		(net "M_F_CPU0_SB_CS_N<0>")
	)
	(segment
		(start 416.164014 -245.3132)
		(end 416.003994 -245.15318)
		(width 0.18288)
		(layer "In2.Cu")
		(net "M_F_CPU0_SB_CS_N<0>")
	)
	(segment
		(start 413.019494 -245.394226)
		(end 412.701994 -245.076726)
		(width 0.18288)
		(layer "In2.Cu")
		(net "M_F_CPU0_SB_CS_N<0>")
	)
	(segment
		(start 413.69361 -244.623844)
		(end 413.69361 -245.08841)
		(width 0.18288)
		(layer "In2.Cu")
		(net "M_F_CPU0_SB_CS_N<0>")
	)
	(segment
		(start 383.800096 -244.230906)
		(end 383.075434 -243.922804)
		(width 0.088646)
		(layer "In2.Cu")
		(net "M_F_CPU0_SB_CS_N<0>")
	)
	(segment
		(start 410.328364 -244.505226)
		(end 410.11221 -244.505226)
		(width 0.18288)
		(layer "In2.Cu")
		(net "M_F_CPU0_SB_CS_N<0>")
	)
	(segment
		(start 426.418756 -246.014748)
		(end 426.230288 -246.203216)
		(width 0.18288)
		(layer "In2.Cu")
		(net "M_F_CPU0_SB_CS_N<0>")
	)
	(segment
		(start 425.529248 -245.343172)
		(end 424.455336 -245.343172)
		(width 0.18288)
		(layer "In2.Cu")
		(net "M_F_CPU0_SB_CS_N<0>")
	)
	(segment
		(start 419.30574 -244.556026)
		(end 418.91077 -244.161056)
		(width 0.18288)
		(layer "In2.Cu")
		(net "M_F_CPU0_SB_CS_N<0>")
	)
	(segment
		(start 386.891022 -246.22633)
		(end 386.691378 -246.026686)
		(width 0.18288)
		(layer "In2.Cu")
		(net "M_F_CPU0_SB_CS_N<0>")
	)
	(segment
		(start 425.689268 -246.028718)
		(end 425.689268 -245.503192)
		(width 0.18288)
		(layer "In2.Cu")
		(net "M_F_CPU0_SB_CS_N<0>")
	)
	(segment
		(start 398.575784 -245.92661)
		(end 388.24408 -245.92661)
		(width 0.18288)
		(layer "In2.Cu")
		(net "M_F_CPU0_SB_CS_N<0>")
	)
	(segment
		(start 410.521404 -244.026944)
		(end 410.521404 -244.312186)
		(width 0.18288)
		(layer "In2.Cu")
		(net "M_F_CPU0_SB_CS_N<0>")
	)
	(segment
		(start 410.721048 -243.8273)
		(end 410.521404 -244.026944)
		(width 0.18288)
		(layer "In2.Cu")
		(net "M_F_CPU0_SB_CS_N<0>")
	)
	(segment
		(start 387.94436 -246.22633)
		(end 386.891022 -246.22633)
		(width 0.18288)
		(layer "In2.Cu")
		(net "M_F_CPU0_SB_CS_N<0>")
	)
	(segment
		(start 411.418532 -244.505226)
		(end 411.225492 -244.312186)
		(width 0.18288)
		(layer "In2.Cu")
		(net "M_F_CPU0_SB_CS_N<0>")
	)
	(segment
		(start 422.729914 -245.344696)
		(end 420.465504 -245.344696)
		(width 0.18288)
		(layer "In2.Cu")
		(net "M_F_CPU0_SB_CS_N<0>")
	)
	(segment
		(start 416.707574 -245.3132)
		(end 416.164014 -245.3132)
		(width 0.18288)
		(layer "In2.Cu")
		(net "M_F_CPU0_SB_CS_N<0>")
	)
	(segment
		(start 426.418756 -245.466108)
		(end 426.418756 -246.014748)
		(width 0.18288)
		(layer "In2.Cu")
		(net "M_F_CPU0_SB_CS_N<0>")
	)
	(segment
		(start 409.644342 -244.973094)
		(end 409.333954 -244.973094)
		(width 0.18288)
		(layer "In2.Cu")
		(net "M_F_CPU0_SB_CS_N<0>")
	)
	(segment
		(start 424.031664 -245.766844)
		(end 423.152062 -245.766844)
		(width 0.18288)
		(layer "In2.Cu")
		(net "M_F_CPU0_SB_CS_N<0>")
	)
	(segment
		(start 413.387794 -245.394226)
		(end 413.019494 -245.394226)
		(width 0.18288)
		(layer "In2.Cu")
		(net "M_F_CPU0_SB_CS_N<0>")
	)
	(segment
		(start 398.999964 -246.35079)
		(end 398.575784 -245.92661)
		(width 0.18288)
		(layer "In2.Cu")
		(net "M_F_CPU0_SB_CS_N<0>")
	)
	(segment
		(start 425.689268 -245.503192)
		(end 425.529248 -245.343172)
		(width 0.18288)
		(layer "In2.Cu")
		(net "M_F_CPU0_SB_CS_N<0>")
	)
	(segment
		(start 413.837628 -244.479826)
		(end 413.69361 -244.623844)
		(width 0.18288)
		(layer "In2.Cu")
		(net "M_F_CPU0_SB_CS_N<0>")
	)
	(segment
		(start 417.45662 -244.556026)
		(end 417.053014 -244.556026)
		(width 0.18288)
		(layer "In2.Cu")
		(net "M_F_CPU0_SB_CS_N<0>")
	)
	(segment
		(start 416.867594 -245.15318)
		(end 416.707574 -245.3132)
		(width 0.18288)
		(layer "In2.Cu")
		(net "M_F_CPU0_SB_CS_N<0>")
	)
	(segment
		(start 408.417522 -245.056406)
		(end 408.069542 -245.404386)
		(width 0.18288)
		(layer "In2.Cu")
		(net "M_F_CPU0_SB_CS_N<0>")
	)
	(segment
		(start 386.691378 -246.026686)
		(end 386.4864 -245.821708)
		(width 0.088646)
		(layer "In2.Cu")
		(net "M_F_CPU0_SB_CS_N<0>")
	)
	(segment
		(start 383.828036 -244.247162)
		(end 383.800096 -244.230906)
		(width 0.088646)
		(layer "In2.Cu")
		(net "M_F_CPU0_SB_CS_N<0>")
	)
	(segment
		(start 416.003994 -244.639846)
		(end 415.843974 -244.479826)
		(width 0.18288)
		(layer "In2.Cu")
		(net "M_F_CPU0_SB_CS_N<0>")
	)
	(segment
		(start 384.110484 -244.73662)
		(end 384.110484 -244.736366)
		(width 0.088646)
		(layer "In2.Cu")
		(net "M_F_CPU0_SB_CS_N<0>")
	)
	(segment
		(start 411.848046 -244.58295)
		(end 411.770322 -244.505226)
		(width 0.18288)
		(layer "In2.Cu")
		(net "M_F_CPU0_SB_CS_N<0>")
	)
	(segment
		(start 411.770322 -244.505226)
		(end 411.418532 -244.505226)
		(width 0.18288)
		(layer "In2.Cu")
		(net "M_F_CPU0_SB_CS_N<0>")
	)
	(arc
		(start 386.29463 -245.150894)
		(mid 386.239028 -245.102101)
		(end 386.177536 -245.060978)
		(width 0.088646)
		(layer "In2.Cu")
		(net "M_F_CPU0_SB_CS_N<0>")
	)
	(arc
		(start 384.110484 -244.736366)
		(mid 384.034804 -244.45392)
		(end 383.828036 -244.247162)
		(width 0.088646)
		(layer "In2.Cu")
		(net "M_F_CPU0_SB_CS_N<0>")
	)
	(arc
		(start 386.177536 -245.060978)
		(mid 385.894834 -244.985236)
		(end 385.612132 -245.060978)
		(width 0.088646)
		(layer "In2.Cu")
		(net "M_F_CPU0_SB_CS_N<0>")
	)
	(arc
		(start 385.612132 -245.060978)
		(mid 385.424934 -245.111121)
		(end 385.237736 -245.060978)
		(width 0.088646)
		(layer "In2.Cu")
		(net "M_F_CPU0_SB_CS_N<0>")
	)
	(arc
		(start 385.237736 -245.060978)
		(mid 384.955034 -244.985236)
		(end 384.672332 -245.060978)
		(width 0.088646)
		(layer "In2.Cu")
		(net "M_F_CPU0_SB_CS_N<0>")
	)
	(arc
		(start 384.297936 -245.060724)
		(mid 384.160713 -244.923827)
		(end 384.110484 -244.73662)
		(width 0.088646)
		(layer "In2.Cu")
		(net "M_F_CPU0_SB_CS_N<0>")
	)
	(arc
		(start 384.672332 -245.060978)
		(mid 384.485134 -245.111121)
		(end 384.297936 -245.060978)
		(width 0.088646)
		(layer "In2.Cu")
		(net "M_F_CPU0_SB_CS_N<0>")
	)
	(segment
		(start 428.363126 -239.39881)
		(end 428.367952 -239.39881)
		(width 0.101854)
		(layer "F.Cu")
		(net "M_F_CPU0_SB_CB<7>")
	)
	(segment
		(start 424.836082 -238.966756)
		(end 425.940982 -238.966756)
		(width 0.20066)
		(layer "F.Cu")
		(net "M_F_CPU0_SB_CB<7>")
	)
	(segment
		(start 430.382934 -239.391698)
		(end 430.395126 -239.40389)
		(width 0.1016)
		(layer "F.Cu")
		(net "M_F_CPU0_SB_CB<7>")
	)
	(segment
		(start 427.639226 -238.966756)
		(end 428.07128 -239.39881)
		(width 0.20066)
		(layer "F.Cu")
		(net "M_F_CPU0_SB_CB<7>")
	)
	(segment
		(start 431.514504 -238.714788)
		(end 431.898552 -238.714788)
		(width 0.20066)
		(layer "F.Cu")
		(net "M_F_CPU0_SB_CB<7>")
	)
	(segment
		(start 383.07518 -240.66754)
		(end 383.075434 -240.667286)
		(width 0.20066)
		(layer "F.Cu")
		(net "M_F_CPU0_SB_CB<7>")
	)
	(segment
		(start 431.280316 -239.199928)
		(end 431.280316 -238.948976)
		(width 0.20066)
		(layer "F.Cu")
		(net "M_F_CPU0_SB_CB<7>")
	)
	(segment
		(start 431.076354 -239.40389)
		(end 431.280316 -239.199928)
		(width 0.20066)
		(layer "F.Cu")
		(net "M_F_CPU0_SB_CB<7>")
	)
	(segment
		(start 431.898552 -238.714788)
		(end 432.15052 -238.966756)
		(width 0.20066)
		(layer "F.Cu")
		(net "M_F_CPU0_SB_CB<7>")
	)
	(segment
		(start 428.07128 -239.39881)
		(end 428.363126 -239.39881)
		(width 0.20066)
		(layer "F.Cu")
		(net "M_F_CPU0_SB_CB<7>")
	)
	(segment
		(start 428.375064 -239.391698)
		(end 430.382934 -239.391698)
		(width 0.1016)
		(layer "F.Cu")
		(net "M_F_CPU0_SB_CB<7>")
	)
	(segment
		(start 425.940982 -238.966756)
		(end 427.639226 -238.966756)
		(width 0.20066)
		(layer "F.Cu")
		(net "M_F_CPU0_SB_CB<7>")
	)
	(segment
		(start 430.395126 -239.40389)
		(end 431.076354 -239.40389)
		(width 0.20066)
		(layer "F.Cu")
		(net "M_F_CPU0_SB_CB<7>")
	)
	(segment
		(start 383.07518 -241.203226)
		(end 383.07518 -240.66754)
		(width 0.20066)
		(layer "F.Cu")
		(net "M_F_CPU0_SB_CB<7>")
	)
	(segment
		(start 431.280316 -238.948976)
		(end 431.514504 -238.714788)
		(width 0.20066)
		(layer "F.Cu")
		(net "M_F_CPU0_SB_CB<7>")
	)
	(segment
		(start 432.15052 -238.966756)
		(end 433.484782 -238.966756)
		(width 0.20066)
		(layer "F.Cu")
		(net "M_F_CPU0_SB_CB<7>")
	)
	(segment
		(start 428.367952 -239.39881)
		(end 428.375064 -239.391698)
		(width 0.1016)
		(layer "F.Cu")
		(net "M_F_CPU0_SB_CB<7>")
	)
	(segment
		(start 422.055036 -239.189006)
		(end 421.861996 -239.382046)
		(width 0.18288)
		(layer "In2.Cu")
		(net "M_F_CPU0_SB_CB<7>")
	)
	(segment
		(start 383.741676 -240.943638)
		(end 383.247138 -240.706402)
		(width 0.088646)
		(layer "In2.Cu")
		(net "M_F_CPU0_SB_CB<7>")
	)
	(segment
		(start 415.94405 -238.587026)
		(end 415.056574 -237.69955)
		(width 0.18288)
		(layer "In2.Cu")
		(net "M_F_CPU0_SB_CB<7>")
	)
	(segment
		(start 422.906444 -238.351568)
		(end 422.730168 -238.527844)
		(width 0.18288)
		(layer "In2.Cu")
		(net "M_F_CPU0_SB_CB<7>")
	)
	(segment
		(start 407.924508 -239.66043)
		(end 407.699464 -239.435386)
		(width 0.18288)
		(layer "In2.Cu")
		(net "M_F_CPU0_SB_CB<7>")
	)
	(segment
		(start 421.861996 -239.382046)
		(end 421.486584 -239.382046)
		(width 0.18288)
		(layer "In2.Cu")
		(net "M_F_CPU0_SB_CB<7>")
	)
	(segment
		(start 420.156894 -238.714026)
		(end 419.572694 -238.714026)
		(width 0.18288)
		(layer "In2.Cu")
		(net "M_F_CPU0_SB_CB<7>")
	)
	(segment
		(start 424.836082 -238.966756)
		(end 423.908474 -238.966756)
		(width 0.18288)
		(layer "In2.Cu")
		(net "M_F_CPU0_SB_CB<7>")
	)
	(segment
		(start 386.596636 -242.257834)
		(end 386.308092 -242.546378)
		(width 0.088646)
		(layer "In2.Cu")
		(net "M_F_CPU0_SB_CB<7>")
	)
	(segment
		(start 420.28364 -238.58728)
		(end 420.156894 -238.714026)
		(width 0.18288)
		(layer "In2.Cu")
		(net "M_F_CPU0_SB_CB<7>")
	)
	(segment
		(start 421.486584 -239.382046)
		(end 421.293544 -239.189006)
		(width 0.18288)
		(layer "In2.Cu")
		(net "M_F_CPU0_SB_CB<7>")
	)
	(segment
		(start 423.715434 -238.773716)
		(end 423.715434 -238.128556)
		(width 0.18288)
		(layer "In2.Cu")
		(net "M_F_CPU0_SB_CB<7>")
	)
	(segment
		(start 421.293544 -238.669068)
		(end 421.167052 -238.542576)
		(width 0.18288)
		(layer "In2.Cu")
		(net "M_F_CPU0_SB_CB<7>")
	)
	(segment
		(start 422.055036 -238.667798)
		(end 422.055036 -239.189006)
		(width 0.18288)
		(layer "In2.Cu")
		(net "M_F_CPU0_SB_CB<7>")
	)
	(segment
		(start 387.265164 -242.257834)
		(end 386.596636 -242.257834)
		(width 0.088646)
		(layer "In2.Cu")
		(net "M_F_CPU0_SB_CB<7>")
	)
	(segment
		(start 422.19499 -238.527844)
		(end 422.055036 -238.667798)
		(width 0.18288)
		(layer "In2.Cu")
		(net "M_F_CPU0_SB_CB<7>")
	)
	(segment
		(start 423.517314 -237.930436)
		(end 423.066464 -237.930436)
		(width 0.18288)
		(layer "In2.Cu")
		(net "M_F_CPU0_SB_CB<7>")
	)
	(segment
		(start 408.210766 -239.66043)
		(end 407.924508 -239.66043)
		(width 0.18288)
		(layer "In2.Cu")
		(net "M_F_CPU0_SB_CB<7>")
	)
	(segment
		(start 407.699464 -239.435386)
		(end 404.90521 -239.435386)
		(width 0.18288)
		(layer "In2.Cu")
		(net "M_F_CPU0_SB_CB<7>")
	)
	(segment
		(start 412.62173 -238.587026)
		(end 409.28417 -238.587026)
		(width 0.18288)
		(layer "In2.Cu")
		(net "M_F_CPU0_SB_CB<7>")
	)
	(segment
		(start 422.730168 -238.527844)
		(end 422.19499 -238.527844)
		(width 0.18288)
		(layer "In2.Cu")
		(net "M_F_CPU0_SB_CB<7>")
	)
	(segment
		(start 422.906444 -238.090456)
		(end 422.906444 -238.351568)
		(width 0.18288)
		(layer "In2.Cu")
		(net "M_F_CPU0_SB_CB<7>")
	)
	(segment
		(start 420.28364 -238.587026)
		(end 420.28364 -238.58728)
		(width 0.18288)
		(layer "In2.Cu")
		(net "M_F_CPU0_SB_CB<7>")
	)
	(segment
		(start 413.509206 -237.69955)
		(end 412.62173 -238.587026)
		(width 0.18288)
		(layer "In2.Cu")
		(net "M_F_CPU0_SB_CB<7>")
	)
	(segment
		(start 384.110484 -241.481102)
		(end 384.110484 -241.471196)
		(width 0.088646)
		(layer "In2.Cu")
		(net "M_F_CPU0_SB_CB<7>")
	)
	(segment
		(start 423.066464 -237.930436)
		(end 422.906444 -238.090456)
		(width 0.18288)
		(layer "In2.Cu")
		(net "M_F_CPU0_SB_CB<7>")
	)
	(segment
		(start 423.715434 -238.128556)
		(end 423.517314 -237.930436)
		(width 0.18288)
		(layer "In2.Cu")
		(net "M_F_CPU0_SB_CB<7>")
	)
	(segment
		(start 385.520184 -242.294918)
		(end 385.520184 -242.294664)
		(width 0.088646)
		(layer "In2.Cu")
		(net "M_F_CPU0_SB_CB<7>")
	)
	(segment
		(start 402.082762 -242.257834)
		(end 387.265164 -242.257834)
		(width 0.18288)
		(layer "In2.Cu")
		(net "M_F_CPU0_SB_CB<7>")
	)
	(segment
		(start 384.29819 -241.80546)
		(end 384.297682 -241.805206)
		(width 0.088646)
		(layer "In2.Cu")
		(net "M_F_CPU0_SB_CB<7>")
	)
	(segment
		(start 419.445694 -238.587026)
		(end 415.94405 -238.587026)
		(width 0.18288)
		(layer "In2.Cu")
		(net "M_F_CPU0_SB_CB<7>")
	)
	(segment
		(start 421.293544 -239.189006)
		(end 421.293544 -238.669068)
		(width 0.18288)
		(layer "In2.Cu")
		(net "M_F_CPU0_SB_CB<7>")
	)
	(segment
		(start 409.28417 -238.587026)
		(end 408.210766 -239.66043)
		(width 0.18288)
		(layer "In2.Cu")
		(net "M_F_CPU0_SB_CB<7>")
	)
	(segment
		(start 419.572694 -238.714026)
		(end 419.445694 -238.587026)
		(width 0.18288)
		(layer "In2.Cu")
		(net "M_F_CPU0_SB_CB<7>")
	)
	(segment
		(start 421.167052 -238.542576)
		(end 420.32809 -238.542576)
		(width 0.18288)
		(layer "In2.Cu")
		(net "M_F_CPU0_SB_CB<7>")
	)
	(segment
		(start 383.828036 -240.991644)
		(end 383.781046 -240.964466)
		(width 0.088646)
		(layer "In2.Cu")
		(net "M_F_CPU0_SB_CB<7>")
	)
	(segment
		(start 385.707636 -242.619276)
		(end 385.698746 -242.614196)
		(width 0.088646)
		(layer "In2.Cu")
		(net "M_F_CPU0_SB_CB<7>")
	)
	(segment
		(start 404.90521 -239.435386)
		(end 402.082762 -242.257834)
		(width 0.18288)
		(layer "In2.Cu")
		(net "M_F_CPU0_SB_CB<7>")
	)
	(segment
		(start 415.056574 -237.69955)
		(end 413.509206 -237.69955)
		(width 0.18288)
		(layer "In2.Cu")
		(net "M_F_CPU0_SB_CB<7>")
	)
	(segment
		(start 423.908474 -238.966756)
		(end 423.715434 -238.773716)
		(width 0.18288)
		(layer "In2.Cu")
		(net "M_F_CPU0_SB_CB<7>")
	)
	(segment
		(start 420.32809 -238.542576)
		(end 420.28364 -238.587026)
		(width 0.18288)
		(layer "In2.Cu")
		(net "M_F_CPU0_SB_CB<7>")
	)
	(arc
		(start 386.082032 -242.619276)
		(mid 385.894834 -242.669419)
		(end 385.707636 -242.619276)
		(width 0.088646)
		(layer "In2.Cu")
		(net "M_F_CPU0_SB_CB<7>")
	)
	(arc
		(start 385.698746 -242.614196)
		(mid 385.567832 -242.477836)
		(end 385.520184 -242.294918)
		(width 0.088646)
		(layer "In2.Cu")
		(net "M_F_CPU0_SB_CB<7>")
	)
	(arc
		(start 383.162556 -240.67897)
		(mid 383.119111 -240.672265)
		(end 383.075434 -240.667286)
		(width 0.088646)
		(layer "In2.Cu")
		(net "M_F_CPU0_SB_CB<7>")
	)
	(arc
		(start 385.237736 -241.80546)
		(mid 384.955034 -241.729718)
		(end 384.672332 -241.80546)
		(width 0.088646)
		(layer "In2.Cu")
		(net "M_F_CPU0_SB_CB<7>")
	)
	(arc
		(start 384.297682 -241.805206)
		(mid 384.160637 -241.668246)
		(end 384.110484 -241.481102)
		(width 0.088646)
		(layer "In2.Cu")
		(net "M_F_CPU0_SB_CB<7>")
	)
	(arc
		(start 383.781046 -240.964466)
		(mid 383.761563 -240.95367)
		(end 383.741676 -240.943638)
		(width 0.088646)
		(layer "In2.Cu")
		(net "M_F_CPU0_SB_CB<7>")
	)
	(arc
		(start 384.672332 -241.80546)
		(mid 384.485278 -241.85551)
		(end 384.29819 -241.80546)
		(width 0.088646)
		(layer "In2.Cu")
		(net "M_F_CPU0_SB_CB<7>")
	)
	(arc
		(start 385.520184 -242.294664)
		(mid 385.444504 -242.012218)
		(end 385.237736 -241.80546)
		(width 0.088646)
		(layer "In2.Cu")
		(net "M_F_CPU0_SB_CB<7>")
	)
	(arc
		(start 384.110484 -241.471196)
		(mid 384.032373 -241.194247)
		(end 383.828036 -240.991644)
		(width 0.088646)
		(layer "In2.Cu")
		(net "M_F_CPU0_SB_CB<7>")
	)
	(arc
		(start 383.247138 -240.706402)
		(mid 383.205789 -240.689782)
		(end 383.162556 -240.67897)
		(width 0.088646)
		(layer "In2.Cu")
		(net "M_F_CPU0_SB_CB<7>")
	)
	(arc
		(start 386.308092 -242.546378)
		(mid 386.191191 -242.570823)
		(end 386.082032 -242.619276)
		(width 0.088646)
		(layer "In2.Cu")
		(net "M_F_CPU0_SB_CB<7>")
	)
	(segment
		(start 427.639226 -240.666778)
		(end 428.07128 -241.098832)
		(width 0.20066)
		(layer "F.Cu")
		(net "M_F_CPU0_SB_CB<6>")
	)
	(segment
		(start 425.940982 -240.666778)
		(end 427.639226 -240.666778)
		(width 0.20066)
		(layer "F.Cu")
		(net "M_F_CPU0_SB_CB<6>")
	)
	(segment
		(start 431.514504 -240.41481)
		(end 431.898552 -240.41481)
		(width 0.20066)
		(layer "F.Cu")
		(net "M_F_CPU0_SB_CB<6>")
	)
	(segment
		(start 431.898552 -240.41481)
		(end 432.15052 -240.666778)
		(width 0.20066)
		(layer "F.Cu")
		(net "M_F_CPU0_SB_CB<6>")
	)
	(segment
		(start 431.280316 -240.89995)
		(end 431.280316 -240.648998)
		(width 0.20066)
		(layer "F.Cu")
		(net "M_F_CPU0_SB_CB<6>")
	)
	(segment
		(start 424.836082 -240.666778)
		(end 425.940982 -240.666778)
		(width 0.20066)
		(layer "F.Cu")
		(net "M_F_CPU0_SB_CB<6>")
	)
	(segment
		(start 432.15052 -240.666778)
		(end 433.484782 -240.666778)
		(width 0.20066)
		(layer "F.Cu")
		(net "M_F_CPU0_SB_CB<6>")
	)
	(segment
		(start 431.076354 -241.103912)
		(end 431.280316 -240.89995)
		(width 0.20066)
		(layer "F.Cu")
		(net "M_F_CPU0_SB_CB<6>")
	)
	(segment
		(start 382.60528 -242.016788)
		(end 382.60528 -241.481102)
		(width 0.20066)
		(layer "F.Cu")
		(net "M_F_CPU0_SB_CB<6>")
	)
	(segment
		(start 382.605534 -242.017042)
		(end 382.60528 -242.016788)
		(width 0.20066)
		(layer "F.Cu")
		(net "M_F_CPU0_SB_CB<6>")
	)
	(segment
		(start 431.280316 -240.648998)
		(end 431.514504 -240.41481)
		(width 0.20066)
		(layer "F.Cu")
		(net "M_F_CPU0_SB_CB<6>")
	)
	(segment
		(start 430.382934 -241.09172)
		(end 430.395126 -241.103912)
		(width 0.1016)
		(layer "F.Cu")
		(net "M_F_CPU0_SB_CB<6>")
	)
	(segment
		(start 428.367952 -241.098832)
		(end 428.375064 -241.09172)
		(width 0.1016)
		(layer "F.Cu")
		(net "M_F_CPU0_SB_CB<6>")
	)
	(segment
		(start 428.375064 -241.09172)
		(end 430.382934 -241.09172)
		(width 0.1016)
		(layer "F.Cu")
		(net "M_F_CPU0_SB_CB<6>")
	)
	(segment
		(start 428.07128 -241.098832)
		(end 428.363126 -241.098832)
		(width 0.20066)
		(layer "F.Cu")
		(net "M_F_CPU0_SB_CB<6>")
	)
	(segment
		(start 430.395126 -241.103912)
		(end 431.076354 -241.103912)
		(width 0.20066)
		(layer "F.Cu")
		(net "M_F_CPU0_SB_CB<6>")
	)
	(segment
		(start 428.363126 -241.098832)
		(end 428.367952 -241.098832)
		(width 0.101854)
		(layer "F.Cu")
		(net "M_F_CPU0_SB_CB<6>")
	)
	(segment
		(start 411.74797 -240.26622)
		(end 409.2956 -240.26622)
		(width 0.18288)
		(layer "In2.Cu")
		(net "M_F_CPU0_SB_CB<6>")
	)
	(segment
		(start 407.685494 -241.254026)
		(end 407.55824 -241.126772)
		(width 0.18288)
		(layer "In2.Cu")
		(net "M_F_CPU0_SB_CB<6>")
	)
	(segment
		(start 423.685462 -240.888266)
		(end 423.685462 -240.140236)
		(width 0.18288)
		(layer "In2.Cu")
		(net "M_F_CPU0_SB_CB<6>")
	)
	(segment
		(start 382.235456 -241.538252)
		(end 382.292606 -241.481102)
		(width 0.088646)
		(layer "In2.Cu")
		(net "M_F_CPU0_SB_CB<6>")
	)
	(segment
		(start 417.17722 -240.272824)
		(end 416.997642 -240.452402)
		(width 0.18288)
		(layer "In2.Cu")
		(net "M_F_CPU0_SB_CB<6>")
	)
	(segment
		(start 412.418784 -240.46688)
		(end 411.94863 -240.46688)
		(width 0.18288)
		(layer "In2.Cu")
		(net "M_F_CPU0_SB_CB<6>")
	)
	(segment
		(start 404.856696 -241.505232)
		(end 402.697442 -243.664486)
		(width 0.18288)
		(layer "In2.Cu")
		(net "M_F_CPU0_SB_CB<6>")
	)
	(segment
		(start 386.702046 -243.283232)
		(end 386.551932 -243.433346)
		(width 0.088646)
		(layer "In2.Cu")
		(net "M_F_CPU0_SB_CB<6>")
	)
	(segment
		(start 399.616168 -243.283232)
		(end 387.265164 -243.283232)
		(width 0.18288)
		(layer "In2.Cu")
		(net "M_F_CPU0_SB_CB<6>")
	)
	(segment
		(start 385.237736 -243.433346)
		(end 385.228846 -243.428266)
		(width 0.088646)
		(layer "In2.Cu")
		(net "M_F_CPU0_SB_CB<6>")
	)
	(segment
		(start 382.888236 -242.619276)
		(end 382.879346 -242.614196)
		(width 0.088646)
		(layer "In2.Cu")
		(net "M_F_CPU0_SB_CB<6>")
	)
	(segment
		(start 422.122854 -240.764568)
		(end 421.661082 -240.764568)
		(width 0.18288)
		(layer "In2.Cu")
		(net "M_F_CPU0_SB_CB<6>")
	)
	(segment
		(start 408.307794 -241.254026)
		(end 407.685494 -241.254026)
		(width 0.18288)
		(layer "In2.Cu")
		(net "M_F_CPU0_SB_CB<6>")
	)
	(segment
		(start 421.139112 -240.242598)
		(end 420.453058 -240.242598)
		(width 0.18288)
		(layer "In2.Cu")
		(net "M_F_CPU0_SB_CB<6>")
	)
	(segment
		(start 420.25443 -240.441226)
		(end 419.521894 -240.441226)
		(width 0.18288)
		(layer "In2.Cu")
		(net "M_F_CPU0_SB_CB<6>")
	)
	(segment
		(start 415.603944 -240.23828)
		(end 412.647384 -240.23828)
		(width 0.18288)
		(layer "In2.Cu")
		(net "M_F_CPU0_SB_CB<6>")
	)
	(segment
		(start 399.997422 -243.664486)
		(end 399.616168 -243.283232)
		(width 0.18288)
		(layer "In2.Cu")
		(net "M_F_CPU0_SB_CB<6>")
	)
	(segment
		(start 382.424178 -241.809016)
		(end 382.418082 -241.80546)
		(width 0.088646)
		(layer "In2.Cu")
		(net "M_F_CPU0_SB_CB<6>")
	)
	(segment
		(start 424.440858 -241.062002)
		(end 423.859198 -241.062002)
		(width 0.18288)
		(layer "In2.Cu")
		(net "M_F_CPU0_SB_CB<6>")
	)
	(segment
		(start 420.453058 -240.242598)
		(end 420.25443 -240.441226)
		(width 0.18288)
		(layer "In2.Cu")
		(net "M_F_CPU0_SB_CB<6>")
	)
	(segment
		(start 423.685462 -240.140236)
		(end 423.492422 -239.947196)
		(width 0.18288)
		(layer "In2.Cu")
		(net "M_F_CPU0_SB_CB<6>")
	)
	(segment
		(start 387.265164 -243.283232)
		(end 386.702046 -243.283232)
		(width 0.088646)
		(layer "In2.Cu")
		(net "M_F_CPU0_SB_CB<6>")
	)
	(segment
		(start 411.94863 -240.46688)
		(end 411.74797 -240.26622)
		(width 0.18288)
		(layer "In2.Cu")
		(net "M_F_CPU0_SB_CB<6>")
	)
	(segment
		(start 419.353492 -240.272824)
		(end 417.17722 -240.272824)
		(width 0.18288)
		(layer "In2.Cu")
		(net "M_F_CPU0_SB_CB<6>")
	)
	(segment
		(start 385.050284 -243.108988)
		(end 385.050284 -243.090446)
		(width 0.088646)
		(layer "In2.Cu")
		(net "M_F_CPU0_SB_CB<6>")
	)
	(segment
		(start 419.521894 -240.441226)
		(end 419.353492 -240.272824)
		(width 0.18288)
		(layer "In2.Cu")
		(net "M_F_CPU0_SB_CB<6>")
	)
	(segment
		(start 405.613108 -241.324638)
		(end 404.856696 -241.505232)
		(width 0.18288)
		(layer "In2.Cu")
		(net "M_F_CPU0_SB_CB<6>")
	)
	(segment
		(start 415.818574 -240.452402)
		(end 415.817812 -240.452148)
		(width 0.18288)
		(layer "In2.Cu")
		(net "M_F_CPU0_SB_CB<6>")
	)
	(segment
		(start 412.647384 -240.23828)
		(end 412.418784 -240.46688)
		(width 0.18288)
		(layer "In2.Cu")
		(net "M_F_CPU0_SB_CB<6>")
	)
	(segment
		(start 424.836082 -240.666778)
		(end 424.440858 -241.062002)
		(width 0.18288)
		(layer "In2.Cu")
		(net "M_F_CPU0_SB_CB<6>")
	)
	(segment
		(start 405.810974 -241.126772)
		(end 405.613108 -241.324638)
		(width 0.18288)
		(layer "In2.Cu")
		(net "M_F_CPU0_SB_CB<6>")
	)
	(segment
		(start 421.661082 -240.764568)
		(end 421.139112 -240.242598)
		(width 0.18288)
		(layer "In2.Cu")
		(net "M_F_CPU0_SB_CB<6>")
	)
	(segment
		(start 422.940226 -239.947196)
		(end 422.122854 -240.764568)
		(width 0.18288)
		(layer "In2.Cu")
		(net "M_F_CPU0_SB_CB<6>")
	)
	(segment
		(start 402.697442 -243.664486)
		(end 399.997422 -243.664486)
		(width 0.18288)
		(layer "In2.Cu")
		(net "M_F_CPU0_SB_CB<6>")
	)
	(segment
		(start 415.817812 -240.452148)
		(end 415.603944 -240.23828)
		(width 0.18288)
		(layer "In2.Cu")
		(net "M_F_CPU0_SB_CB<6>")
	)
	(segment
		(start 407.55824 -241.126772)
		(end 405.810974 -241.126772)
		(width 0.18288)
		(layer "In2.Cu")
		(net "M_F_CPU0_SB_CB<6>")
	)
	(segment
		(start 409.2956 -240.26622)
		(end 408.307794 -241.254026)
		(width 0.18288)
		(layer "In2.Cu")
		(net "M_F_CPU0_SB_CB<6>")
	)
	(segment
		(start 423.492422 -239.947196)
		(end 422.940226 -239.947196)
		(width 0.18288)
		(layer "In2.Cu")
		(net "M_F_CPU0_SB_CB<6>")
	)
	(segment
		(start 423.859198 -241.062002)
		(end 423.685462 -240.888266)
		(width 0.18288)
		(layer "In2.Cu")
		(net "M_F_CPU0_SB_CB<6>")
	)
	(segment
		(start 382.292606 -241.481102)
		(end 382.60528 -241.481102)
		(width 0.088646)
		(layer "In2.Cu")
		(net "M_F_CPU0_SB_CB<6>")
	)
	(segment
		(start 416.997642 -240.452402)
		(end 415.818574 -240.452402)
		(width 0.18288)
		(layer "In2.Cu")
		(net "M_F_CPU0_SB_CB<6>")
	)
	(arc
		(start 385.228846 -243.428266)
		(mid 385.097932 -243.291906)
		(end 385.050284 -243.108988)
		(width 0.088646)
		(layer "In2.Cu")
		(net "M_F_CPU0_SB_CB<6>")
	)
	(arc
		(start 384.767836 -242.619276)
		(mid 384.485134 -242.543534)
		(end 384.202432 -242.619276)
		(width 0.088646)
		(layer "In2.Cu")
		(net "M_F_CPU0_SB_CB<6>")
	)
	(arc
		(start 385.050284 -243.090446)
		(mid 384.970122 -242.818257)
		(end 384.767836 -242.619276)
		(width 0.088646)
		(layer "In2.Cu")
		(net "M_F_CPU0_SB_CB<6>")
	)
	(arc
		(start 385.612132 -243.433346)
		(mid 385.424934 -243.483489)
		(end 385.237736 -243.433346)
		(width 0.088646)
		(layer "In2.Cu")
		(net "M_F_CPU0_SB_CB<6>")
	)
	(arc
		(start 383.262632 -242.619276)
		(mid 383.075434 -242.669419)
		(end 382.888236 -242.619276)
		(width 0.088646)
		(layer "In2.Cu")
		(net "M_F_CPU0_SB_CB<6>")
	)
	(arc
		(start 383.828036 -242.619276)
		(mid 383.545334 -242.543534)
		(end 383.262632 -242.619276)
		(width 0.088646)
		(layer "In2.Cu")
		(net "M_F_CPU0_SB_CB<6>")
	)
	(arc
		(start 382.418082 -241.80546)
		(mid 382.296414 -241.692605)
		(end 382.235456 -241.538252)
		(width 0.088646)
		(layer "In2.Cu")
		(net "M_F_CPU0_SB_CB<6>")
	)
	(arc
		(start 386.177536 -243.433346)
		(mid 385.894834 -243.35757)
		(end 385.612132 -243.433346)
		(width 0.088646)
		(layer "In2.Cu")
		(net "M_F_CPU0_SB_CB<6>")
	)
	(arc
		(start 382.879346 -242.614196)
		(mid 382.748432 -242.477836)
		(end 382.700784 -242.294918)
		(width 0.088646)
		(layer "In2.Cu")
		(net "M_F_CPU0_SB_CB<6>")
	)
	(arc
		(start 384.202432 -242.619276)
		(mid 384.015234 -242.669419)
		(end 383.828036 -242.619276)
		(width 0.088646)
		(layer "In2.Cu")
		(net "M_F_CPU0_SB_CB<6>")
	)
	(arc
		(start 382.700784 -242.294918)
		(mid 382.626793 -242.015352)
		(end 382.424178 -241.809016)
		(width 0.088646)
		(layer "In2.Cu")
		(net "M_F_CPU0_SB_CB<6>")
	)
	(arc
		(start 386.551932 -243.433346)
		(mid 386.364734 -243.483489)
		(end 386.177536 -243.433346)
		(width 0.088646)
		(layer "In2.Cu")
		(net "M_F_CPU0_SB_CB<6>")
	)
	(segment
		(start 426.945044 -239.391698)
		(end 424.756326 -239.391698)
		(width 0.1016)
		(layer "F.Cu")
		(net "M_F_CPU0_SB_CB<5>")
	)
	(segment
		(start 427.36135 -239.385348)
		(end 426.951394 -239.385348)
		(width 0.20066)
		(layer "F.Cu")
		(net "M_F_CPU0_SB_CB<5>")
	)
	(segment
		(start 424.085512 -240.065306)
		(end 423.610278 -240.065306)
		(width 0.20066)
		(layer "F.Cu")
		(net "M_F_CPU0_SB_CB<5>")
	)
	(segment
		(start 424.73626 -239.391698)
		(end 424.391582 -239.391698)
		(width 0.20066)
		(layer "F.Cu")
		(net "M_F_CPU0_SB_CB<5>")
	)
	(segment
		(start 426.951394 -239.385348)
		(end 426.945044 -239.391698)
		(width 0.1016)
		(layer "F.Cu")
		(net "M_F_CPU0_SB_CB<5>")
	)
	(segment
		(start 429.384714 -239.81664)
		(end 429.38446 -239.816894)
		(width 0.20066)
		(layer "F.Cu")
		(net "M_F_CPU0_SB_CB<5>")
	)
	(segment
		(start 427.792896 -239.816894)
		(end 427.36135 -239.385348)
		(width 0.20066)
		(layer "F.Cu")
		(net "M_F_CPU0_SB_CB<5>")
	)
	(segment
		(start 424.273472 -239.509808)
		(end 424.273472 -239.877346)
		(width 0.20066)
		(layer "F.Cu")
		(net "M_F_CPU0_SB_CB<5>")
	)
	(segment
		(start 423.610278 -240.065306)
		(end 423.361612 -239.81664)
		(width 0.20066)
		(layer "F.Cu")
		(net "M_F_CPU0_SB_CB<5>")
	)
	(segment
		(start 424.756326 -239.391698)
		(end 424.73626 -239.391698)
		(width 0.101854)
		(layer "F.Cu")
		(net "M_F_CPU0_SB_CB<5>")
	)
	(segment
		(start 421.840914 -239.81664)
		(end 420.736014 -239.81664)
		(width 0.20066)
		(layer "F.Cu")
		(net "M_F_CPU0_SB_CB<5>")
	)
	(segment
		(start 424.273472 -239.877346)
		(end 424.085512 -240.065306)
		(width 0.20066)
		(layer "F.Cu")
		(net "M_F_CPU0_SB_CB<5>")
	)
	(segment
		(start 424.391582 -239.391698)
		(end 424.273472 -239.509808)
		(width 0.20066)
		(layer "F.Cu")
		(net "M_F_CPU0_SB_CB<5>")
	)
	(segment
		(start 429.38446 -239.816894)
		(end 427.792896 -239.816894)
		(width 0.20066)
		(layer "F.Cu")
		(net "M_F_CPU0_SB_CB<5>")
	)
	(segment
		(start 423.361612 -239.81664)
		(end 421.840914 -239.81664)
		(width 0.20066)
		(layer "F.Cu")
		(net "M_F_CPU0_SB_CB<5>")
	)
	(segment
		(start 381.19558 -241.203226)
		(end 381.19558 -240.66754)
		(width 0.20066)
		(layer "F.Cu")
		(net "M_F_CPU0_SB_CB<5>")
	)
	(segment
		(start 381.19558 -240.66754)
		(end 381.195834 -240.667286)
		(width 0.20066)
		(layer "F.Cu")
		(net "M_F_CPU0_SB_CB<5>")
	)
	(segment
		(start 414.467548 -239.215422)
		(end 414.467548 -238.736632)
		(width 0.18288)
		(layer "In2.Cu")
		(net "M_F_CPU0_SB_CB<5>")
	)
	(segment
		(start 410.36875 -239.75822)
		(end 409.753562 -239.143032)
		(width 0.18288)
		(layer "In2.Cu")
		(net "M_F_CPU0_SB_CB<5>")
	)
	(segment
		(start 414.467548 -238.736632)
		(end 414.266888 -238.535972)
		(width 0.18288)
		(layer "In2.Cu")
		(net "M_F_CPU0_SB_CB<5>")
	)
	(segment
		(start 404.639272 -241.031268)
		(end 404.147528 -241.031268)
		(width 0.18288)
		(layer "In2.Cu")
		(net "M_F_CPU0_SB_CB<5>")
	)
	(segment
		(start 401.51304 -243.152422)
		(end 401.153884 -242.793266)
		(width 0.18288)
		(layer "In2.Cu")
		(net "M_F_CPU0_SB_CB<5>")
	)
	(segment
		(start 400.449796 -243.152422)
		(end 400.22399 -243.152422)
		(width 0.18288)
		(layer "In2.Cu")
		(net "M_F_CPU0_SB_CB<5>")
	)
	(segment
		(start 413.173164 -239.719358)
		(end 412.900114 -239.719358)
		(width 0.18288)
		(layer "In2.Cu")
		(net "M_F_CPU0_SB_CB<5>")
	)
	(segment
		(start 413.76346 -238.729012)
		(end 413.76346 -239.129062)
		(width 0.18288)
		(layer "In2.Cu")
		(net "M_F_CPU0_SB_CB<5>")
	)
	(segment
		(start 413.76346 -239.129062)
		(end 413.173164 -239.719358)
		(width 0.18288)
		(layer "In2.Cu")
		(net "M_F_CPU0_SB_CB<5>")
	)
	(segment
		(start 408.421586 -240.188242)
		(end 407.723086 -240.188242)
		(width 0.18288)
		(layer "In2.Cu")
		(net "M_F_CPU0_SB_CB<5>")
	)
	(segment
		(start 399.84172 -242.770152)
		(end 387.265164 -242.770152)
		(width 0.18288)
		(layer "In2.Cu")
		(net "M_F_CPU0_SB_CB<5>")
	)
	(segment
		(start 404.147528 -241.031268)
		(end 403.285198 -241.893598)
		(width 0.18288)
		(layer "In2.Cu")
		(net "M_F_CPU0_SB_CB<5>")
	)
	(segment
		(start 407.292556 -240.618772)
		(end 406.329388 -240.618772)
		(width 0.18288)
		(layer "In2.Cu")
		(net "M_F_CPU0_SB_CB<5>")
	)
	(segment
		(start 416.815524 -239.263682)
		(end 416.815524 -239.740694)
		(width 0.18288)
		(layer "In2.Cu")
		(net "M_F_CPU0_SB_CB<5>")
	)
	(segment
		(start 407.723086 -240.188242)
		(end 407.292556 -240.618772)
		(width 0.18288)
		(layer "In2.Cu")
		(net "M_F_CPU0_SB_CB<5>")
	)
	(segment
		(start 420.1414 -239.222026)
		(end 419.367462 -239.222026)
		(width 0.18288)
		(layer "In2.Cu")
		(net "M_F_CPU0_SB_CB<5>")
	)
	(segment
		(start 403.285198 -241.893598)
		(end 403.285198 -242.331494)
		(width 0.18288)
		(layer "In2.Cu")
		(net "M_F_CPU0_SB_CB<5>")
	)
	(segment
		(start 411.935168 -239.095026)
		(end 411.271974 -239.75822)
		(width 0.18288)
		(layer "In2.Cu")
		(net "M_F_CPU0_SB_CB<5>")
	)
	(segment
		(start 386.89407 -242.770152)
		(end 386.860542 -242.736624)
		(width 0.088646)
		(layer "In2.Cu")
		(net "M_F_CPU0_SB_CB<5>")
	)
	(segment
		(start 382.792732 -241.156744)
		(end 382.788922 -241.154458)
		(width 0.088646)
		(layer "In2.Cu")
		(net "M_F_CPU0_SB_CB<5>")
	)
	(segment
		(start 405.654002 -239.943386)
		(end 405.16175 -239.943386)
		(width 0.18288)
		(layer "In2.Cu")
		(net "M_F_CPU0_SB_CB<5>")
	)
	(segment
		(start 414.660588 -239.408462)
		(end 414.467548 -239.215422)
		(width 0.18288)
		(layer "In2.Cu")
		(net "M_F_CPU0_SB_CB<5>")
	)
	(segment
		(start 419.367462 -239.222026)
		(end 418.828728 -239.76076)
		(width 0.18288)
		(layer "In2.Cu")
		(net "M_F_CPU0_SB_CB<5>")
	)
	(segment
		(start 409.466796 -239.143032)
		(end 408.421586 -240.188242)
		(width 0.18288)
		(layer "In2.Cu")
		(net "M_F_CPU0_SB_CB<5>")
	)
	(segment
		(start 381.508508 -240.667286)
		(end 381.195834 -240.667286)
		(width 0.088646)
		(layer "In2.Cu")
		(net "M_F_CPU0_SB_CB<5>")
	)
	(segment
		(start 382.798574 -241.160046)
		(end 382.792732 -241.156744)
		(width 0.088646)
		(layer "In2.Cu")
		(net "M_F_CPU0_SB_CB<5>")
	)
	(segment
		(start 416.622484 -239.933734)
		(end 416.124136 -239.933734)
		(width 0.18288)
		(layer "In2.Cu")
		(net "M_F_CPU0_SB_CB<5>")
	)
	(segment
		(start 383.732532 -241.156744)
		(end 383.728214 -241.154204)
		(width 0.088646)
		(layer "In2.Cu")
		(net "M_F_CPU0_SB_CB<5>")
	)
	(segment
		(start 385.329684 -242.31346)
		(end 385.329684 -242.294918)
		(width 0.088646)
		(layer "In2.Cu")
		(net "M_F_CPU0_SB_CB<5>")
	)
	(segment
		(start 417.269422 -239.117378)
		(end 416.961828 -239.117378)
		(width 0.18288)
		(layer "In2.Cu")
		(net "M_F_CPU0_SB_CB<5>")
	)
	(segment
		(start 403.006052 -242.61064)
		(end 402.568156 -242.61064)
		(width 0.18288)
		(layer "In2.Cu")
		(net "M_F_CPU0_SB_CB<5>")
	)
	(segment
		(start 412.275782 -239.095026)
		(end 411.935168 -239.095026)
		(width 0.18288)
		(layer "In2.Cu")
		(net "M_F_CPU0_SB_CB<5>")
	)
	(segment
		(start 400.22399 -243.152422)
		(end 399.84172 -242.770152)
		(width 0.18288)
		(layer "In2.Cu")
		(net "M_F_CPU0_SB_CB<5>")
	)
	(segment
		(start 416.124136 -239.933734)
		(end 415.598864 -239.408462)
		(width 0.18288)
		(layer "In2.Cu")
		(net "M_F_CPU0_SB_CB<5>")
	)
	(segment
		(start 416.961828 -239.117378)
		(end 416.815524 -239.263682)
		(width 0.18288)
		(layer "In2.Cu")
		(net "M_F_CPU0_SB_CB<5>")
	)
	(segment
		(start 416.815524 -239.740694)
		(end 416.622484 -239.933734)
		(width 0.18288)
		(layer "In2.Cu")
		(net "M_F_CPU0_SB_CB<5>")
	)
	(segment
		(start 386.860542 -242.736624)
		(end 386.404104 -242.736624)
		(width 0.088646)
		(layer "In2.Cu")
		(net "M_F_CPU0_SB_CB<5>")
	)
	(segment
		(start 402.568156 -242.61064)
		(end 402.026374 -243.152422)
		(width 0.18288)
		(layer "In2.Cu")
		(net "M_F_CPU0_SB_CB<5>")
	)
	(segment
		(start 383.919984 -241.491008)
		(end 383.919984 -241.481102)
		(width 0.088646)
		(layer "In2.Cu")
		(net "M_F_CPU0_SB_CB<5>")
	)
	(segment
		(start 405.16175 -239.943386)
		(end 404.96871 -240.136426)
		(width 0.18288)
		(layer "In2.Cu")
		(net "M_F_CPU0_SB_CB<5>")
	)
	(segment
		(start 406.329388 -240.618772)
		(end 405.654002 -239.943386)
		(width 0.18288)
		(layer "In2.Cu")
		(net "M_F_CPU0_SB_CB<5>")
	)
	(segment
		(start 412.900114 -239.719358)
		(end 412.275782 -239.095026)
		(width 0.18288)
		(layer "In2.Cu")
		(net "M_F_CPU0_SB_CB<5>")
	)
	(segment
		(start 404.96871 -240.70183)
		(end 404.639272 -241.031268)
		(width 0.18288)
		(layer "In2.Cu")
		(net "M_F_CPU0_SB_CB<5>")
	)
	(segment
		(start 404.96871 -240.136426)
		(end 404.96871 -240.70183)
		(width 0.18288)
		(layer "In2.Cu")
		(net "M_F_CPU0_SB_CB<5>")
	)
	(segment
		(start 420.736014 -239.81664)
		(end 420.1414 -239.222026)
		(width 0.18288)
		(layer "In2.Cu")
		(net "M_F_CPU0_SB_CB<5>")
	)
	(segment
		(start 383.741422 -241.161824)
		(end 383.732532 -241.156744)
		(width 0.088646)
		(layer "In2.Cu")
		(net "M_F_CPU0_SB_CB<5>")
	)
	(segment
		(start 411.271974 -239.75822)
		(end 410.36875 -239.75822)
		(width 0.18288)
		(layer "In2.Cu")
		(net "M_F_CPU0_SB_CB<5>")
	)
	(segment
		(start 415.598864 -239.408462)
		(end 414.660588 -239.408462)
		(width 0.18288)
		(layer "In2.Cu")
		(net "M_F_CPU0_SB_CB<5>")
	)
	(segment
		(start 403.285198 -242.331494)
		(end 403.006052 -242.61064)
		(width 0.18288)
		(layer "In2.Cu")
		(net "M_F_CPU0_SB_CB<5>")
	)
	(segment
		(start 418.828728 -239.76076)
		(end 417.912804 -239.76076)
		(width 0.18288)
		(layer "In2.Cu")
		(net "M_F_CPU0_SB_CB<5>")
	)
	(segment
		(start 401.153884 -242.793266)
		(end 400.808952 -242.793266)
		(width 0.18288)
		(layer "In2.Cu")
		(net "M_F_CPU0_SB_CB<5>")
	)
	(segment
		(start 413.9565 -238.535972)
		(end 413.76346 -238.729012)
		(width 0.18288)
		(layer "In2.Cu")
		(net "M_F_CPU0_SB_CB<5>")
	)
	(segment
		(start 409.753562 -239.143032)
		(end 409.466796 -239.143032)
		(width 0.18288)
		(layer "In2.Cu")
		(net "M_F_CPU0_SB_CB<5>")
	)
	(segment
		(start 385.142486 -241.970814)
		(end 385.142232 -241.97056)
		(width 0.088646)
		(layer "In2.Cu")
		(net "M_F_CPU0_SB_CB<5>")
	)
	(segment
		(start 417.912804 -239.76076)
		(end 417.269422 -239.117378)
		(width 0.18288)
		(layer "In2.Cu")
		(net "M_F_CPU0_SB_CB<5>")
	)
	(segment
		(start 387.265164 -242.770152)
		(end 386.89407 -242.770152)
		(width 0.088646)
		(layer "In2.Cu")
		(net "M_F_CPU0_SB_CB<5>")
	)
	(segment
		(start 402.026374 -243.152422)
		(end 401.51304 -243.152422)
		(width 0.18288)
		(layer "In2.Cu")
		(net "M_F_CPU0_SB_CB<5>")
	)
	(segment
		(start 381.574294 -240.733072)
		(end 381.508508 -240.667286)
		(width 0.088646)
		(layer "In2.Cu")
		(net "M_F_CPU0_SB_CB<5>")
	)
	(segment
		(start 414.266888 -238.535972)
		(end 413.9565 -238.535972)
		(width 0.18288)
		(layer "In2.Cu")
		(net "M_F_CPU0_SB_CB<5>")
	)
	(segment
		(start 400.808952 -242.793266)
		(end 400.449796 -243.152422)
		(width 0.18288)
		(layer "In2.Cu")
		(net "M_F_CPU0_SB_CB<5>")
	)
	(arc
		(start 383.357882 -241.156744)
		(mid 383.078679 -241.232384)
		(end 382.798574 -241.160046)
		(width 0.088646)
		(layer "In2.Cu")
		(net "M_F_CPU0_SB_CB<5>")
	)
	(arc
		(start 382.418082 -241.156744)
		(mid 381.882038 -241.172296)
		(end 381.574294 -240.733072)
		(width 0.088646)
		(layer "In2.Cu")
		(net "M_F_CPU0_SB_CB<5>")
	)
	(arc
		(start 384.202432 -241.97056)
		(mid 383.998097 -241.767955)
		(end 383.919984 -241.491008)
		(width 0.088646)
		(layer "In2.Cu")
		(net "M_F_CPU0_SB_CB<5>")
	)
	(arc
		(start 382.788922 -241.154458)
		(mid 382.603203 -241.106506)
		(end 382.418082 -241.156744)
		(width 0.088646)
		(layer "In2.Cu")
		(net "M_F_CPU0_SB_CB<5>")
	)
	(arc
		(start 384.767836 -241.97056)
		(mid 384.485134 -242.046302)
		(end 384.202432 -241.97056)
		(width 0.088646)
		(layer "In2.Cu")
		(net "M_F_CPU0_SB_CB<5>")
	)
	(arc
		(start 386.177536 -242.78463)
		(mid 385.894834 -242.860372)
		(end 385.612132 -242.78463)
		(width 0.088646)
		(layer "In2.Cu")
		(net "M_F_CPU0_SB_CB<5>")
	)
	(arc
		(start 385.329684 -242.294918)
		(mid 385.27952 -242.10778)
		(end 385.142486 -241.970814)
		(width 0.088646)
		(layer "In2.Cu")
		(net "M_F_CPU0_SB_CB<5>")
	)
	(arc
		(start 386.404104 -242.736624)
		(mid 386.287027 -242.742701)
		(end 386.177536 -242.78463)
		(width 0.088646)
		(layer "In2.Cu")
		(net "M_F_CPU0_SB_CB<5>")
	)
	(arc
		(start 383.728214 -241.154204)
		(mid 383.542719 -241.106535)
		(end 383.357882 -241.156744)
		(width 0.088646)
		(layer "In2.Cu")
		(net "M_F_CPU0_SB_CB<5>")
	)
	(arc
		(start 385.612132 -242.78463)
		(mid 385.409846 -242.585649)
		(end 385.329684 -242.31346)
		(width 0.088646)
		(layer "In2.Cu")
		(net "M_F_CPU0_SB_CB<5>")
	)
	(arc
		(start 383.919984 -241.481102)
		(mid 383.872305 -241.298202)
		(end 383.741422 -241.161824)
		(width 0.088646)
		(layer "In2.Cu")
		(net "M_F_CPU0_SB_CB<5>")
	)
	(arc
		(start 385.142232 -241.97056)
		(mid 384.955034 -241.920417)
		(end 384.767836 -241.97056)
		(width 0.088646)
		(layer "In2.Cu")
		(net "M_F_CPU0_SB_CB<5>")
	)
	(segment
		(start 427.792896 -241.516916)
		(end 427.36135 -241.08537)
		(width 0.20066)
		(layer "F.Cu")
		(net "M_F_CPU0_SB_CB<4>")
	)
	(segment
		(start 429.38446 -241.516916)
		(end 427.792896 -241.516916)
		(width 0.20066)
		(layer "F.Cu")
		(net "M_F_CPU0_SB_CB<4>")
	)
	(segment
		(start 381.665734 -242.017042)
		(end 381.665734 -241.481102)
		(width 0.20066)
		(layer "F.Cu")
		(net "M_F_CPU0_SB_CB<4>")
	)
	(segment
		(start 424.391582 -241.09172)
		(end 424.273472 -241.20983)
		(width 0.20066)
		(layer "F.Cu")
		(net "M_F_CPU0_SB_CB<4>")
	)
	(segment
		(start 423.361612 -241.516662)
		(end 421.840914 -241.516662)
		(width 0.20066)
		(layer "F.Cu")
		(net "M_F_CPU0_SB_CB<4>")
	)
	(segment
		(start 429.384714 -241.516662)
		(end 429.38446 -241.516916)
		(width 0.20066)
		(layer "F.Cu")
		(net "M_F_CPU0_SB_CB<4>")
	)
	(segment
		(start 427.36135 -241.08537)
		(end 426.951394 -241.08537)
		(width 0.20066)
		(layer "F.Cu")
		(net "M_F_CPU0_SB_CB<4>")
	)
	(segment
		(start 426.945044 -241.09172)
		(end 424.78325 -241.09172)
		(width 0.1016)
		(layer "F.Cu")
		(net "M_F_CPU0_SB_CB<4>")
	)
	(segment
		(start 424.73626 -241.09172)
		(end 424.391582 -241.09172)
		(width 0.20066)
		(layer "F.Cu")
		(net "M_F_CPU0_SB_CB<4>")
	)
	(segment
		(start 424.085512 -241.765328)
		(end 423.610278 -241.765328)
		(width 0.20066)
		(layer "F.Cu")
		(net "M_F_CPU0_SB_CB<4>")
	)
	(segment
		(start 424.273472 -241.577368)
		(end 424.085512 -241.765328)
		(width 0.20066)
		(layer "F.Cu")
		(net "M_F_CPU0_SB_CB<4>")
	)
	(segment
		(start 423.610278 -241.765328)
		(end 423.361612 -241.516662)
		(width 0.20066)
		(layer "F.Cu")
		(net "M_F_CPU0_SB_CB<4>")
	)
	(segment
		(start 424.273472 -241.20983)
		(end 424.273472 -241.577368)
		(width 0.20066)
		(layer "F.Cu")
		(net "M_F_CPU0_SB_CB<4>")
	)
	(segment
		(start 424.78325 -241.09172)
		(end 424.73626 -241.09172)
		(width 0.101854)
		(layer "F.Cu")
		(net "M_F_CPU0_SB_CB<4>")
	)
	(segment
		(start 426.951394 -241.08537)
		(end 426.945044 -241.09172)
		(width 0.1016)
		(layer "F.Cu")
		(net "M_F_CPU0_SB_CB<4>")
	)
	(segment
		(start 421.840914 -241.516662)
		(end 420.736014 -241.516662)
		(width 0.20066)
		(layer "F.Cu")
		(net "M_F_CPU0_SB_CB<4>")
	)
	(segment
		(start 416.441382 -241.153442)
		(end 416.441382 -241.690144)
		(width 0.18288)
		(layer "In2.Cu")
		(net "M_F_CPU0_SB_CB<4>")
	)
	(segment
		(start 407.152602 -241.982752)
		(end 406.992582 -242.142772)
		(width 0.18288)
		(layer "In2.Cu")
		(net "M_F_CPU0_SB_CB<4>")
	)
	(segment
		(start 412.411926 -241.691668)
		(end 412.411926 -241.243866)
		(width 0.18288)
		(layer "In2.Cu")
		(net "M_F_CPU0_SB_CB<4>")
	)
	(segment
		(start 417.323016 -240.960402)
		(end 416.634422 -240.960402)
		(width 0.18288)
		(layer "In2.Cu")
		(net "M_F_CPU0_SB_CB<4>")
	)
	(segment
		(start 416.634422 -240.960402)
		(end 416.441382 -241.153442)
		(width 0.18288)
		(layer "In2.Cu")
		(net "M_F_CPU0_SB_CB<4>")
	)
	(segment
		(start 418.83838 -241.200686)
		(end 418.64534 -241.393726)
		(width 0.18288)
		(layer "In2.Cu")
		(net "M_F_CPU0_SB_CB<4>")
	)
	(segment
		(start 406.259538 -242.474496)
		(end 406.259538 -242.13185)
		(width 0.18288)
		(layer "In2.Cu")
		(net "M_F_CPU0_SB_CB<4>")
	)
	(segment
		(start 405.549862 -241.869214)
		(end 405.00046 -242.096798)
		(width 0.18288)
		(layer "In2.Cu")
		(net "M_F_CPU0_SB_CB<4>")
	)
	(segment
		(start 410.726382 -241.787426)
		(end 410.566362 -241.627406)
		(width 0.18288)
		(layer "In2.Cu")
		(net "M_F_CPU0_SB_CB<4>")
	)
	(segment
		(start 419.339014 -241.013742)
		(end 419.15207 -241.200686)
		(width 0.18288)
		(layer "In2.Cu")
		(net "M_F_CPU0_SB_CB<4>")
	)
	(segment
		(start 405.996902 -241.869214)
		(end 405.549862 -241.869214)
		(width 0.18288)
		(layer "In2.Cu")
		(net "M_F_CPU0_SB_CB<4>")
	)
	(segment
		(start 399.402554 -243.800884)
		(end 387.519164 -243.800884)
		(width 0.18288)
		(layer "In2.Cu")
		(net "M_F_CPU0_SB_CB<4>")
	)
	(segment
		(start 415.497264 -241.28857)
		(end 415.28619 -241.077496)
		(width 0.18288)
		(layer "In2.Cu")
		(net "M_F_CPU0_SB_CB<4>")
	)
	(segment
		(start 382.320038 -241.969036)
		(end 382.316736 -241.967004)
		(width 0.088646)
		(layer "In2.Cu")
		(net "M_F_CPU0_SB_CB<4>")
	)
	(segment
		(start 409.072588 -241.657632)
		(end 408.943048 -241.787172)
		(width 0.18288)
		(layer "In2.Cu")
		(net "M_F_CPU0_SB_CB<4>")
	)
	(segment
		(start 418.063426 -241.814858)
		(end 417.870132 -241.621564)
		(width 0.18288)
		(layer "In2.Cu")
		(net "M_F_CPU0_SB_CB<4>")
	)
	(segment
		(start 414.794446 -241.077496)
		(end 414.46323 -240.74628)
		(width 0.18288)
		(layer "In2.Cu")
		(net "M_F_CPU0_SB_CB<4>")
	)
	(segment
		(start 406.992582 -242.142772)
		(end 406.992582 -242.474496)
		(width 0.18288)
		(layer "In2.Cu")
		(net "M_F_CPU0_SB_CB<4>")
	)
	(segment
		(start 406.832562 -242.634516)
		(end 406.419558 -242.634516)
		(width 0.18288)
		(layer "In2.Cu")
		(net "M_F_CPU0_SB_CB<4>")
	)
	(segment
		(start 407.685748 -241.787172)
		(end 407.490168 -241.982752)
		(width 0.18288)
		(layer "In2.Cu")
		(net "M_F_CPU0_SB_CB<4>")
	)
	(segment
		(start 408.943048 -241.787172)
		(end 407.685748 -241.787172)
		(width 0.18288)
		(layer "In2.Cu")
		(net "M_F_CPU0_SB_CB<4>")
	)
	(segment
		(start 384.681222 -242.78971)
		(end 384.672332 -242.78463)
		(width 0.088646)
		(layer "In2.Cu")
		(net "M_F_CPU0_SB_CB<4>")
	)
	(segment
		(start 409.072588 -241.225832)
		(end 409.072588 -241.657632)
		(width 0.18288)
		(layer "In2.Cu")
		(net "M_F_CPU0_SB_CB<4>")
	)
	(segment
		(start 381.978408 -241.481102)
		(end 381.665734 -241.481102)
		(width 0.088646)
		(layer "In2.Cu")
		(net "M_F_CPU0_SB_CB<4>")
	)
	(segment
		(start 410.566362 -241.255042)
		(end 410.373068 -241.061748)
		(width 0.18288)
		(layer "In2.Cu")
		(net "M_F_CPU0_SB_CB<4>")
	)
	(segment
		(start 384.859784 -243.118894)
		(end 384.859784 -243.108988)
		(width 0.088646)
		(layer "In2.Cu")
		(net "M_F_CPU0_SB_CB<4>")
	)
	(segment
		(start 411.32633 -241.622326)
		(end 411.16123 -241.787426)
		(width 0.18288)
		(layer "In2.Cu")
		(net "M_F_CPU0_SB_CB<4>")
	)
	(segment
		(start 405.00046 -242.096798)
		(end 402.92401 -244.173248)
		(width 0.18288)
		(layer "In2.Cu")
		(net "M_F_CPU0_SB_CB<4>")
	)
	(segment
		(start 409.236672 -241.061748)
		(end 409.072588 -241.225832)
		(width 0.18288)
		(layer "In2.Cu")
		(net "M_F_CPU0_SB_CB<4>")
	)
	(segment
		(start 412.218886 -241.050826)
		(end 411.599634 -241.050826)
		(width 0.18288)
		(layer "In2.Cu")
		(net "M_F_CPU0_SB_CB<4>")
	)
	(segment
		(start 382.322832 -241.97056)
		(end 382.320038 -241.969036)
		(width 0.088646)
		(layer "In2.Cu")
		(net "M_F_CPU0_SB_CB<4>")
	)
	(segment
		(start 413.140398 -241.825018)
		(end 412.545276 -241.825018)
		(width 0.18288)
		(layer "In2.Cu")
		(net "M_F_CPU0_SB_CB<4>")
	)
	(segment
		(start 418.64534 -241.393726)
		(end 418.64534 -241.652298)
		(width 0.18288)
		(layer "In2.Cu")
		(net "M_F_CPU0_SB_CB<4>")
	)
	(segment
		(start 417.870132 -241.246152)
		(end 417.710112 -241.086132)
		(width 0.18288)
		(layer "In2.Cu")
		(net "M_F_CPU0_SB_CB<4>")
	)
	(segment
		(start 406.992582 -242.474496)
		(end 406.832562 -242.634516)
		(width 0.18288)
		(layer "In2.Cu")
		(net "M_F_CPU0_SB_CB<4>")
	)
	(segment
		(start 420.233094 -241.013742)
		(end 419.339014 -241.013742)
		(width 0.18288)
		(layer "In2.Cu")
		(net "M_F_CPU0_SB_CB<4>")
	)
	(segment
		(start 418.64534 -241.652298)
		(end 418.48278 -241.814858)
		(width 0.18288)
		(layer "In2.Cu")
		(net "M_F_CPU0_SB_CB<4>")
	)
	(segment
		(start 416.27298 -241.858546)
		(end 415.690304 -241.858546)
		(width 0.18288)
		(layer "In2.Cu")
		(net "M_F_CPU0_SB_CB<4>")
	)
	(segment
		(start 402.92401 -244.173248)
		(end 399.774918 -244.173248)
		(width 0.18288)
		(layer "In2.Cu")
		(net "M_F_CPU0_SB_CB<4>")
	)
	(segment
		(start 382.510284 -242.317016)
		(end 382.510284 -242.294918)
		(width 0.088646)
		(layer "In2.Cu")
		(net "M_F_CPU0_SB_CB<4>")
	)
	(segment
		(start 420.736014 -241.516662)
		(end 420.233094 -241.013742)
		(width 0.18288)
		(layer "In2.Cu")
		(net "M_F_CPU0_SB_CB<4>")
	)
	(segment
		(start 382.04394 -241.546634)
		(end 381.978408 -241.481102)
		(width 0.088646)
		(layer "In2.Cu")
		(net "M_F_CPU0_SB_CB<4>")
	)
	(segment
		(start 411.599634 -241.050826)
		(end 411.32633 -241.32413)
		(width 0.18288)
		(layer "In2.Cu")
		(net "M_F_CPU0_SB_CB<4>")
	)
	(segment
		(start 415.497264 -241.665506)
		(end 415.497264 -241.28857)
		(width 0.18288)
		(layer "In2.Cu")
		(net "M_F_CPU0_SB_CB<4>")
	)
	(segment
		(start 415.28619 -241.077496)
		(end 414.794446 -241.077496)
		(width 0.18288)
		(layer "In2.Cu")
		(net "M_F_CPU0_SB_CB<4>")
	)
	(segment
		(start 419.15207 -241.200686)
		(end 418.83838 -241.200686)
		(width 0.18288)
		(layer "In2.Cu")
		(net "M_F_CPU0_SB_CB<4>")
	)
	(segment
		(start 411.32633 -241.32413)
		(end 411.32633 -241.622326)
		(width 0.18288)
		(layer "In2.Cu")
		(net "M_F_CPU0_SB_CB<4>")
	)
	(segment
		(start 411.16123 -241.787426)
		(end 410.726382 -241.787426)
		(width 0.18288)
		(layer "In2.Cu")
		(net "M_F_CPU0_SB_CB<4>")
	)
	(segment
		(start 399.774918 -244.173248)
		(end 399.402554 -243.800884)
		(width 0.18288)
		(layer "In2.Cu")
		(net "M_F_CPU0_SB_CB<4>")
	)
	(segment
		(start 386.917438 -243.5479)
		(end 386.83438 -243.5479)
		(width 0.088646)
		(layer "In2.Cu")
		(net "M_F_CPU0_SB_CB<4>")
	)
	(segment
		(start 413.333438 -241.194082)
		(end 413.333438 -241.631978)
		(width 0.18288)
		(layer "In2.Cu")
		(net "M_F_CPU0_SB_CB<4>")
	)
	(segment
		(start 406.259538 -242.13185)
		(end 405.996902 -241.869214)
		(width 0.18288)
		(layer "In2.Cu")
		(net "M_F_CPU0_SB_CB<4>")
	)
	(segment
		(start 387.170422 -243.800884)
		(end 386.917438 -243.5479)
		(width 0.088646)
		(layer "In2.Cu")
		(net "M_F_CPU0_SB_CB<4>")
	)
	(segment
		(start 387.519164 -243.800884)
		(end 387.170422 -243.800884)
		(width 0.088646)
		(layer "In2.Cu")
		(net "M_F_CPU0_SB_CB<4>")
	)
	(segment
		(start 418.48278 -241.814858)
		(end 418.063426 -241.814858)
		(width 0.18288)
		(layer "In2.Cu")
		(net "M_F_CPU0_SB_CB<4>")
	)
	(segment
		(start 413.78124 -240.74628)
		(end 413.333438 -241.194082)
		(width 0.18288)
		(layer "In2.Cu")
		(net "M_F_CPU0_SB_CB<4>")
	)
	(segment
		(start 413.333438 -241.631978)
		(end 413.140398 -241.825018)
		(width 0.18288)
		(layer "In2.Cu")
		(net "M_F_CPU0_SB_CB<4>")
	)
	(segment
		(start 412.411926 -241.243866)
		(end 412.218886 -241.050826)
		(width 0.18288)
		(layer "In2.Cu")
		(net "M_F_CPU0_SB_CB<4>")
	)
	(segment
		(start 416.441382 -241.690144)
		(end 416.27298 -241.858546)
		(width 0.18288)
		(layer "In2.Cu")
		(net "M_F_CPU0_SB_CB<4>")
	)
	(segment
		(start 407.490168 -241.982752)
		(end 407.152602 -241.982752)
		(width 0.18288)
		(layer "In2.Cu")
		(net "M_F_CPU0_SB_CB<4>")
	)
	(segment
		(start 414.46323 -240.74628)
		(end 413.78124 -240.74628)
		(width 0.18288)
		(layer "In2.Cu")
		(net "M_F_CPU0_SB_CB<4>")
	)
	(segment
		(start 417.870132 -241.621564)
		(end 417.870132 -241.246152)
		(width 0.18288)
		(layer "In2.Cu")
		(net "M_F_CPU0_SB_CB<4>")
	)
	(segment
		(start 417.448746 -241.086132)
		(end 417.323016 -240.960402)
		(width 0.18288)
		(layer "In2.Cu")
		(net "M_F_CPU0_SB_CB<4>")
	)
	(segment
		(start 410.566362 -241.627406)
		(end 410.566362 -241.255042)
		(width 0.18288)
		(layer "In2.Cu")
		(net "M_F_CPU0_SB_CB<4>")
	)
	(segment
		(start 415.690304 -241.858546)
		(end 415.497264 -241.665506)
		(width 0.18288)
		(layer "In2.Cu")
		(net "M_F_CPU0_SB_CB<4>")
	)
	(segment
		(start 383.358136 -242.78463)
		(end 383.347722 -242.790726)
		(width 0.088646)
		(layer "In2.Cu")
		(net "M_F_CPU0_SB_CB<4>")
	)
	(segment
		(start 412.545276 -241.825018)
		(end 412.411926 -241.691668)
		(width 0.18288)
		(layer "In2.Cu")
		(net "M_F_CPU0_SB_CB<4>")
	)
	(segment
		(start 417.710112 -241.086132)
		(end 417.448746 -241.086132)
		(width 0.18288)
		(layer "In2.Cu")
		(net "M_F_CPU0_SB_CB<4>")
	)
	(segment
		(start 382.331722 -241.97564)
		(end 382.322832 -241.97056)
		(width 0.088646)
		(layer "In2.Cu")
		(net "M_F_CPU0_SB_CB<4>")
	)
	(segment
		(start 406.419558 -242.634516)
		(end 406.259538 -242.474496)
		(width 0.18288)
		(layer "In2.Cu")
		(net "M_F_CPU0_SB_CB<4>")
	)
	(segment
		(start 410.373068 -241.061748)
		(end 409.236672 -241.061748)
		(width 0.18288)
		(layer "In2.Cu")
		(net "M_F_CPU0_SB_CB<4>")
	)
	(arc
		(start 385.707636 -243.598446)
		(mid 385.424934 -243.674222)
		(end 385.142232 -243.598446)
		(width 0.088646)
		(layer "In2.Cu")
		(net "M_F_CPU0_SB_CB<4>")
	)
	(arc
		(start 383.732532 -242.78463)
		(mid 383.545334 -242.734487)
		(end 383.358136 -242.78463)
		(width 0.088646)
		(layer "In2.Cu")
		(net "M_F_CPU0_SB_CB<4>")
	)
	(arc
		(start 384.859784 -243.108988)
		(mid 384.812105 -242.926088)
		(end 384.681222 -242.78971)
		(width 0.088646)
		(layer "In2.Cu")
		(net "M_F_CPU0_SB_CB<4>")
	)
	(arc
		(start 386.647436 -243.598446)
		(mid 386.364734 -243.674222)
		(end 386.082032 -243.598446)
		(width 0.088646)
		(layer "In2.Cu")
		(net "M_F_CPU0_SB_CB<4>")
	)
	(arc
		(start 384.672332 -242.78463)
		(mid 384.485134 -242.734487)
		(end 384.297936 -242.78463)
		(width 0.088646)
		(layer "In2.Cu")
		(net "M_F_CPU0_SB_CB<4>")
	)
	(arc
		(start 382.510284 -242.294918)
		(mid 382.462605 -242.112018)
		(end 382.331722 -241.97564)
		(width 0.088646)
		(layer "In2.Cu")
		(net "M_F_CPU0_SB_CB<4>")
	)
	(arc
		(start 382.316736 -241.967004)
		(mid 382.131213 -241.788703)
		(end 382.04394 -241.546634)
		(width 0.088646)
		(layer "In2.Cu")
		(net "M_F_CPU0_SB_CB<4>")
	)
	(arc
		(start 386.082032 -243.598446)
		(mid 385.894834 -243.548303)
		(end 385.707636 -243.598446)
		(width 0.088646)
		(layer "In2.Cu")
		(net "M_F_CPU0_SB_CB<4>")
	)
	(arc
		(start 386.83438 -243.5479)
		(mid 386.737588 -243.560891)
		(end 386.647436 -243.598446)
		(width 0.088646)
		(layer "In2.Cu")
		(net "M_F_CPU0_SB_CB<4>")
	)
	(arc
		(start 384.297936 -242.78463)
		(mid 384.015234 -242.860372)
		(end 383.732532 -242.78463)
		(width 0.088646)
		(layer "In2.Cu")
		(net "M_F_CPU0_SB_CB<4>")
	)
	(arc
		(start 383.347722 -242.790726)
		(mid 383.06929 -242.86054)
		(end 382.792478 -242.78463)
		(width 0.088646)
		(layer "In2.Cu")
		(net "M_F_CPU0_SB_CB<4>")
	)
	(arc
		(start 385.142232 -243.598446)
		(mid 384.937897 -243.395841)
		(end 384.859784 -243.118894)
		(width 0.088646)
		(layer "In2.Cu")
		(net "M_F_CPU0_SB_CB<4>")
	)
	(arc
		(start 382.792478 -242.78463)
		(mid 382.591196 -242.587143)
		(end 382.510284 -242.317016)
		(width 0.088646)
		(layer "In2.Cu")
		(net "M_F_CPU0_SB_CB<4>")
	)
	(segment
		(start 430.395126 -233.45394)
		(end 431.076354 -233.45394)
		(width 0.20066)
		(layer "F.Cu")
		(net "M_F_CPU0_SB_CB<3>")
	)
	(segment
		(start 427.639226 -233.016806)
		(end 428.07128 -233.44886)
		(width 0.20066)
		(layer "F.Cu")
		(net "M_F_CPU0_SB_CB<3>")
	)
	(segment
		(start 431.076354 -233.45394)
		(end 431.280316 -233.249978)
		(width 0.20066)
		(layer "F.Cu")
		(net "M_F_CPU0_SB_CB<3>")
	)
	(segment
		(start 431.280316 -232.999026)
		(end 431.514504 -232.764838)
		(width 0.20066)
		(layer "F.Cu")
		(net "M_F_CPU0_SB_CB<3>")
	)
	(segment
		(start 382.605534 -238.761524)
		(end 382.605534 -238.225584)
		(width 0.20066)
		(layer "F.Cu")
		(net "M_F_CPU0_SB_CB<3>")
	)
	(segment
		(start 432.15052 -233.016806)
		(end 433.484782 -233.016806)
		(width 0.20066)
		(layer "F.Cu")
		(net "M_F_CPU0_SB_CB<3>")
	)
	(segment
		(start 424.836082 -233.016806)
		(end 425.940982 -233.016806)
		(width 0.20066)
		(layer "F.Cu")
		(net "M_F_CPU0_SB_CB<3>")
	)
	(segment
		(start 428.363126 -233.44886)
		(end 428.367952 -233.44886)
		(width 0.101854)
		(layer "F.Cu")
		(net "M_F_CPU0_SB_CB<3>")
	)
	(segment
		(start 430.382934 -233.441748)
		(end 430.395126 -233.45394)
		(width 0.1016)
		(layer "F.Cu")
		(net "M_F_CPU0_SB_CB<3>")
	)
	(segment
		(start 431.898552 -232.764838)
		(end 432.15052 -233.016806)
		(width 0.20066)
		(layer "F.Cu")
		(net "M_F_CPU0_SB_CB<3>")
	)
	(segment
		(start 428.375064 -233.441748)
		(end 430.382934 -233.441748)
		(width 0.1016)
		(layer "F.Cu")
		(net "M_F_CPU0_SB_CB<3>")
	)
	(segment
		(start 428.07128 -233.44886)
		(end 428.363126 -233.44886)
		(width 0.20066)
		(layer "F.Cu")
		(net "M_F_CPU0_SB_CB<3>")
	)
	(segment
		(start 431.280316 -233.249978)
		(end 431.280316 -232.999026)
		(width 0.20066)
		(layer "F.Cu")
		(net "M_F_CPU0_SB_CB<3>")
	)
	(segment
		(start 431.514504 -232.764838)
		(end 431.898552 -232.764838)
		(width 0.20066)
		(layer "F.Cu")
		(net "M_F_CPU0_SB_CB<3>")
	)
	(segment
		(start 425.940982 -233.016806)
		(end 427.639226 -233.016806)
		(width 0.20066)
		(layer "F.Cu")
		(net "M_F_CPU0_SB_CB<3>")
	)
	(segment
		(start 428.367952 -233.44886)
		(end 428.375064 -233.441748)
		(width 0.1016)
		(layer "F.Cu")
		(net "M_F_CPU0_SB_CB<3>")
	)
	(segment
		(start 419.361366 -231.67467)
		(end 419.222174 -231.813862)
		(width 0.18288)
		(layer "In2.Cu")
		(net "M_F_CPU0_SB_CB<3>")
	)
	(segment
		(start 424.836082 -233.016806)
		(end 424.320208 -233.53268)
		(width 0.18288)
		(layer "In2.Cu")
		(net "M_F_CPU0_SB_CB<3>")
	)
	(segment
		(start 416.711638 -230.852726)
		(end 412.881826 -230.852726)
		(width 0.18288)
		(layer "In2.Cu")
		(net "M_F_CPU0_SB_CB<3>")
	)
	(segment
		(start 419.222174 -231.813862)
		(end 417.672774 -231.813862)
		(width 0.18288)
		(layer "In2.Cu")
		(net "M_F_CPU0_SB_CB<3>")
	)
	(segment
		(start 412.243778 -231.490774)
		(end 411.79242 -231.70007)
		(width 0.18288)
		(layer "In2.Cu")
		(net "M_F_CPU0_SB_CB<3>")
	)
	(segment
		(start 388.133082 -238.366046)
		(end 387.89864 -238.600488)
		(width 0.088646)
		(layer "In2.Cu")
		(net "M_F_CPU0_SB_CB<3>")
	)
	(segment
		(start 408.90698 -231.865678)
		(end 405.961088 -233.49585)
		(width 0.18288)
		(layer "In2.Cu")
		(net "M_F_CPU0_SB_CB<3>")
	)
	(segment
		(start 412.881826 -230.852726)
		(end 412.243778 -231.490774)
		(width 0.18288)
		(layer "In2.Cu")
		(net "M_F_CPU0_SB_CB<3>")
	)
	(segment
		(start 419.917626 -231.67467)
		(end 419.361366 -231.67467)
		(width 0.18288)
		(layer "In2.Cu")
		(net "M_F_CPU0_SB_CB<3>")
	)
	(segment
		(start 424.320208 -233.53268)
		(end 422.666922 -233.53268)
		(width 0.18288)
		(layer "In2.Cu")
		(net "M_F_CPU0_SB_CB<3>")
	)
	(segment
		(start 409.174188 -231.742488)
		(end 408.90698 -231.865678)
		(width 0.18288)
		(layer "In2.Cu")
		(net "M_F_CPU0_SB_CB<3>")
	)
	(segment
		(start 405.19858 -233.668824)
		(end 400.501358 -238.366046)
		(width 0.18288)
		(layer "In2.Cu")
		(net "M_F_CPU0_SB_CB<3>")
	)
	(segment
		(start 400.501358 -238.366046)
		(end 388.458964 -238.366046)
		(width 0.18288)
		(layer "In2.Cu")
		(net "M_F_CPU0_SB_CB<3>")
	)
	(segment
		(start 382.235456 -238.282734)
		(end 382.292606 -238.225584)
		(width 0.088646)
		(layer "In2.Cu")
		(net "M_F_CPU0_SB_CB<3>")
	)
	(segment
		(start 417.672774 -231.813862)
		(end 416.711638 -230.852726)
		(width 0.18288)
		(layer "In2.Cu")
		(net "M_F_CPU0_SB_CB<3>")
	)
	(segment
		(start 385.990084 -238.225584)
		(end 385.990084 -238.207042)
		(width 0.088646)
		(layer "In2.Cu")
		(net "M_F_CPU0_SB_CB<3>")
	)
	(segment
		(start 382.980184 -238.207042)
		(end 382.980184 -238.225584)
		(width 0.088646)
		(layer "In2.Cu")
		(net "M_F_CPU0_SB_CB<3>")
	)
	(segment
		(start 420.110666 -232.16235)
		(end 420.110666 -231.86771)
		(width 0.18288)
		(layer "In2.Cu")
		(net "M_F_CPU0_SB_CB<3>")
	)
	(segment
		(start 420.540942 -232.592626)
		(end 420.110666 -232.16235)
		(width 0.18288)
		(layer "In2.Cu")
		(net "M_F_CPU0_SB_CB<3>")
	)
	(segment
		(start 382.292606 -238.225584)
		(end 382.605534 -238.225584)
		(width 0.088646)
		(layer "In2.Cu")
		(net "M_F_CPU0_SB_CB<3>")
	)
	(segment
		(start 411.275784 -231.742488)
		(end 409.174188 -231.742488)
		(width 0.18288)
		(layer "In2.Cu")
		(net "M_F_CPU0_SB_CB<3>")
	)
	(segment
		(start 420.110666 -231.86771)
		(end 419.917626 -231.67467)
		(width 0.18288)
		(layer "In2.Cu")
		(net "M_F_CPU0_SB_CB<3>")
	)
	(segment
		(start 387.89864 -238.600488)
		(end 387.304534 -238.600488)
		(width 0.088646)
		(layer "In2.Cu")
		(net "M_F_CPU0_SB_CB<3>")
	)
	(segment
		(start 388.458964 -238.366046)
		(end 388.133082 -238.366046)
		(width 0.088646)
		(layer "In2.Cu")
		(net "M_F_CPU0_SB_CB<3>")
	)
	(segment
		(start 411.79242 -231.70007)
		(end 411.275784 -231.742488)
		(width 0.18288)
		(layer "In2.Cu")
		(net "M_F_CPU0_SB_CB<3>")
	)
	(segment
		(start 421.726868 -232.592626)
		(end 420.540942 -232.592626)
		(width 0.18288)
		(layer "In2.Cu")
		(net "M_F_CPU0_SB_CB<3>")
	)
	(segment
		(start 405.788114 -233.668824)
		(end 405.19858 -233.668824)
		(width 0.18288)
		(layer "In2.Cu")
		(net "M_F_CPU0_SB_CB<3>")
	)
	(segment
		(start 422.666922 -233.53268)
		(end 421.726868 -232.592626)
		(width 0.18288)
		(layer "In2.Cu")
		(net "M_F_CPU0_SB_CB<3>")
	)
	(segment
		(start 405.961088 -233.49585)
		(end 405.788114 -233.668824)
		(width 0.18288)
		(layer "In2.Cu")
		(net "M_F_CPU0_SB_CB<3>")
	)
	(arc
		(start 384.202432 -237.735872)
		(mid 384.015234 -237.786015)
		(end 383.828036 -237.735872)
		(width 0.088646)
		(layer "In2.Cu")
		(net "M_F_CPU0_SB_CB<3>")
	)
	(arc
		(start 387.304534 -238.600488)
		(mid 387.207606 -238.587537)
		(end 387.117336 -238.549942)
		(width 0.088646)
		(layer "In2.Cu")
		(net "M_F_CPU0_SB_CB<3>")
	)
	(arc
		(start 382.980184 -238.225584)
		(mid 382.634209 -238.599389)
		(end 382.235456 -238.282734)
		(width 0.088646)
		(layer "In2.Cu")
		(net "M_F_CPU0_SB_CB<3>")
	)
	(arc
		(start 386.551932 -238.549942)
		(mid 386.177457 -238.549896)
		(end 385.990084 -238.225584)
		(width 0.088646)
		(layer "In2.Cu")
		(net "M_F_CPU0_SB_CB<3>")
	)
	(arc
		(start 385.142232 -237.735872)
		(mid 384.955034 -237.786015)
		(end 384.767836 -237.735872)
		(width 0.088646)
		(layer "In2.Cu")
		(net "M_F_CPU0_SB_CB<3>")
	)
	(arc
		(start 383.828036 -237.735872)
		(mid 383.270662 -237.731323)
		(end 382.980184 -238.207042)
		(width 0.088646)
		(layer "In2.Cu")
		(net "M_F_CPU0_SB_CB<3>")
	)
	(arc
		(start 387.117336 -238.549942)
		(mid 386.834634 -238.474166)
		(end 386.551932 -238.549942)
		(width 0.088646)
		(layer "In2.Cu")
		(net "M_F_CPU0_SB_CB<3>")
	)
	(arc
		(start 384.767836 -237.735872)
		(mid 384.485134 -237.66013)
		(end 384.202432 -237.735872)
		(width 0.088646)
		(layer "In2.Cu")
		(net "M_F_CPU0_SB_CB<3>")
	)
	(arc
		(start 385.990084 -238.207042)
		(mid 385.699606 -237.731323)
		(end 385.142232 -237.735872)
		(width 0.088646)
		(layer "In2.Cu")
		(net "M_F_CPU0_SB_CB<3>")
	)
	(segment
		(start 431.280316 -234.698794)
		(end 431.514504 -234.464606)
		(width 0.20066)
		(layer "F.Cu")
		(net "M_F_CPU0_SB_CB<2>")
	)
	(segment
		(start 432.15052 -234.716574)
		(end 433.484782 -234.716574)
		(width 0.20066)
		(layer "F.Cu")
		(net "M_F_CPU0_SB_CB<2>")
	)
	(segment
		(start 431.280316 -234.949746)
		(end 431.280316 -234.698794)
		(width 0.20066)
		(layer "F.Cu")
		(net "M_F_CPU0_SB_CB<2>")
	)
	(segment
		(start 428.363126 -235.148628)
		(end 428.367952 -235.148628)
		(width 0.101854)
		(layer "F.Cu")
		(net "M_F_CPU0_SB_CB<2>")
	)
	(segment
		(start 430.382934 -235.141516)
		(end 430.395126 -235.153708)
		(width 0.1016)
		(layer "F.Cu")
		(net "M_F_CPU0_SB_CB<2>")
	)
	(segment
		(start 383.07518 -239.57534)
		(end 383.07518 -239.039654)
		(width 0.20066)
		(layer "F.Cu")
		(net "M_F_CPU0_SB_CB<2>")
	)
	(segment
		(start 430.395126 -235.153708)
		(end 431.076354 -235.153708)
		(width 0.20066)
		(layer "F.Cu")
		(net "M_F_CPU0_SB_CB<2>")
	)
	(segment
		(start 431.898552 -234.464606)
		(end 432.15052 -234.716574)
		(width 0.20066)
		(layer "F.Cu")
		(net "M_F_CPU0_SB_CB<2>")
	)
	(segment
		(start 427.639226 -234.716574)
		(end 428.07128 -235.148628)
		(width 0.20066)
		(layer "F.Cu")
		(net "M_F_CPU0_SB_CB<2>")
	)
	(segment
		(start 428.07128 -235.148628)
		(end 428.363126 -235.148628)
		(width 0.20066)
		(layer "F.Cu")
		(net "M_F_CPU0_SB_CB<2>")
	)
	(segment
		(start 383.07518 -239.039654)
		(end 383.075434 -239.0394)
		(width 0.20066)
		(layer "F.Cu")
		(net "M_F_CPU0_SB_CB<2>")
	)
	(segment
		(start 424.836082 -234.716574)
		(end 425.940982 -234.716574)
		(width 0.20066)
		(layer "F.Cu")
		(net "M_F_CPU0_SB_CB<2>")
	)
	(segment
		(start 428.367952 -235.148628)
		(end 428.375064 -235.141516)
		(width 0.1016)
		(layer "F.Cu")
		(net "M_F_CPU0_SB_CB<2>")
	)
	(segment
		(start 431.076354 -235.153708)
		(end 431.280316 -234.949746)
		(width 0.20066)
		(layer "F.Cu")
		(net "M_F_CPU0_SB_CB<2>")
	)
	(segment
		(start 425.940982 -234.716574)
		(end 427.639226 -234.716574)
		(width 0.20066)
		(layer "F.Cu")
		(net "M_F_CPU0_SB_CB<2>")
	)
	(segment
		(start 428.375064 -235.141516)
		(end 430.382934 -235.141516)
		(width 0.1016)
		(layer "F.Cu")
		(net "M_F_CPU0_SB_CB<2>")
	)
	(segment
		(start 431.514504 -234.464606)
		(end 431.898552 -234.464606)
		(width 0.20066)
		(layer "F.Cu")
		(net "M_F_CPU0_SB_CB<2>")
	)
	(segment
		(start 408.091894 -235.20527)
		(end 407.656284 -235.20527)
		(width 0.18288)
		(layer "In2.Cu")
		(net "M_F_CPU0_SB_CB<2>")
	)
	(segment
		(start 424.836082 -234.716574)
		(end 424.579542 -234.716574)
		(width 0.18288)
		(layer "In2.Cu")
		(net "M_F_CPU0_SB_CB<2>")
	)
	(segment
		(start 423.534586 -234.93603)
		(end 423.534586 -234.38739)
		(width 0.18288)
		(layer "In2.Cu")
		(net "M_F_CPU0_SB_CB<2>")
	)
	(segment
		(start 424.197526 -235.09859)
		(end 423.697146 -235.09859)
		(width 0.18288)
		(layer "In2.Cu")
		(net "M_F_CPU0_SB_CB<2>")
	)
	(segment
		(start 411.59811 -233.538014)
		(end 410.062934 -233.538014)
		(width 0.18288)
		(layer "In2.Cu")
		(net "M_F_CPU0_SB_CB<2>")
	)
	(segment
		(start 388.458964 -239.40389)
		(end 387.737858 -239.40389)
		(width 0.088646)
		(layer "In2.Cu")
		(net "M_F_CPU0_SB_CB<2>")
	)
	(segment
		(start 420.375588 -234.292394)
		(end 420.242746 -234.159552)
		(width 0.18288)
		(layer "In2.Cu")
		(net "M_F_CPU0_SB_CB<2>")
	)
	(segment
		(start 412.930594 -232.643426)
		(end 412.361888 -233.212132)
		(width 0.18288)
		(layer "In2.Cu")
		(net "M_F_CPU0_SB_CB<2>")
	)
	(segment
		(start 400.913092 -239.40389)
		(end 388.458964 -239.40389)
		(width 0.18288)
		(layer "In2.Cu")
		(net "M_F_CPU0_SB_CB<2>")
	)
	(segment
		(start 387.737858 -239.40389)
		(end 387.622034 -239.288066)
		(width 0.088646)
		(layer "In2.Cu")
		(net "M_F_CPU0_SB_CB<2>")
	)
	(segment
		(start 383.683764 -238.578136)
		(end 383.322322 -238.89589)
		(width 0.088646)
		(layer "In2.Cu")
		(net "M_F_CPU0_SB_CB<2>")
	)
	(segment
		(start 423.697146 -235.09859)
		(end 423.534586 -234.93603)
		(width 0.18288)
		(layer "In2.Cu")
		(net "M_F_CPU0_SB_CB<2>")
	)
	(segment
		(start 419.835838 -234.159552)
		(end 419.694106 -234.301284)
		(width 0.18288)
		(layer "In2.Cu")
		(net "M_F_CPU0_SB_CB<2>")
	)
	(segment
		(start 420.81958 -234.292648)
		(end 420.819326 -234.292394)
		(width 0.18288)
		(layer "In2.Cu")
		(net "M_F_CPU0_SB_CB<2>")
	)
	(segment
		(start 422.216072 -234.81919)
		(end 421.903652 -234.81919)
		(width 0.18288)
		(layer "In2.Cu")
		(net "M_F_CPU0_SB_CB<2>")
	)
	(segment
		(start 386.096764 -239.355122)
		(end 386.082032 -239.363758)
		(width 0.088646)
		(layer "In2.Cu")
		(net "M_F_CPU0_SB_CB<2>")
	)
	(segment
		(start 424.579542 -234.716574)
		(end 424.197526 -235.09859)
		(width 0.18288)
		(layer "In2.Cu")
		(net "M_F_CPU0_SB_CB<2>")
	)
	(segment
		(start 416.416744 -233.534204)
		(end 415.991294 -232.935526)
		(width 0.18288)
		(layer "In2.Cu")
		(net "M_F_CPU0_SB_CB<2>")
	)
	(segment
		(start 405.00681 -235.310172)
		(end 400.913092 -239.40389)
		(width 0.18288)
		(layer "In2.Cu")
		(net "M_F_CPU0_SB_CB<2>")
	)
	(segment
		(start 421.37711 -234.292648)
		(end 420.81958 -234.292648)
		(width 0.18288)
		(layer "In2.Cu")
		(net "M_F_CPU0_SB_CB<2>")
	)
	(segment
		(start 421.903652 -234.81919)
		(end 421.37711 -234.292648)
		(width 0.18288)
		(layer "In2.Cu")
		(net "M_F_CPU0_SB_CB<2>")
	)
	(segment
		(start 417.203636 -234.301284)
		(end 416.975544 -234.195366)
		(width 0.18288)
		(layer "In2.Cu")
		(net "M_F_CPU0_SB_CB<2>")
	)
	(segment
		(start 385.520184 -239.0394)
		(end 385.520184 -239.029494)
		(width 0.088646)
		(layer "In2.Cu")
		(net "M_F_CPU0_SB_CB<2>")
	)
	(segment
		(start 423.534586 -234.38739)
		(end 423.315384 -234.168188)
		(width 0.18288)
		(layer "In2.Cu")
		(net "M_F_CPU0_SB_CB<2>")
	)
	(segment
		(start 411.923992 -233.212132)
		(end 411.59811 -233.538014)
		(width 0.18288)
		(layer "In2.Cu")
		(net "M_F_CPU0_SB_CB<2>")
	)
	(segment
		(start 410.062934 -233.538014)
		(end 409.879546 -233.354626)
		(width 0.18288)
		(layer "In2.Cu")
		(net "M_F_CPU0_SB_CB<2>")
	)
	(segment
		(start 407.656284 -235.20527)
		(end 407.566114 -235.1151)
		(width 0.18288)
		(layer "In2.Cu")
		(net "M_F_CPU0_SB_CB<2>")
	)
	(segment
		(start 412.361888 -233.212132)
		(end 411.923992 -233.212132)
		(width 0.18288)
		(layer "In2.Cu")
		(net "M_F_CPU0_SB_CB<2>")
	)
	(segment
		(start 415.614866 -232.559098)
		(end 413.162496 -232.559098)
		(width 0.18288)
		(layer "In2.Cu")
		(net "M_F_CPU0_SB_CB<2>")
	)
	(segment
		(start 415.991294 -232.935526)
		(end 415.614866 -232.559098)
		(width 0.18288)
		(layer "In2.Cu")
		(net "M_F_CPU0_SB_CB<2>")
	)
	(segment
		(start 383.322322 -238.89589)
		(end 383.075434 -239.0394)
		(width 0.088646)
		(layer "In2.Cu")
		(net "M_F_CPU0_SB_CB<2>")
	)
	(segment
		(start 413.162496 -232.559098)
		(end 412.930594 -232.643426)
		(width 0.18288)
		(layer "In2.Cu")
		(net "M_F_CPU0_SB_CB<2>")
	)
	(segment
		(start 405.736298 -235.310172)
		(end 405.00681 -235.310172)
		(width 0.18288)
		(layer "In2.Cu")
		(net "M_F_CPU0_SB_CB<2>")
	)
	(segment
		(start 387.622034 -239.288066)
		(end 387.30428 -239.288066)
		(width 0.088646)
		(layer "In2.Cu")
		(net "M_F_CPU0_SB_CB<2>")
	)
	(segment
		(start 420.242746 -234.159552)
		(end 419.835838 -234.159552)
		(width 0.18288)
		(layer "In2.Cu")
		(net "M_F_CPU0_SB_CB<2>")
	)
	(segment
		(start 408.284934 -233.983022)
		(end 408.284934 -235.01223)
		(width 0.18288)
		(layer "In2.Cu")
		(net "M_F_CPU0_SB_CB<2>")
	)
	(segment
		(start 422.867074 -234.168188)
		(end 422.216072 -234.81919)
		(width 0.18288)
		(layer "In2.Cu")
		(net "M_F_CPU0_SB_CB<2>")
	)
	(segment
		(start 408.284934 -235.01223)
		(end 408.091894 -235.20527)
		(width 0.18288)
		(layer "In2.Cu")
		(net "M_F_CPU0_SB_CB<2>")
	)
	(segment
		(start 420.819326 -234.292394)
		(end 420.375588 -234.292394)
		(width 0.18288)
		(layer "In2.Cu")
		(net "M_F_CPU0_SB_CB<2>")
	)
	(segment
		(start 423.315384 -234.168188)
		(end 422.867074 -234.168188)
		(width 0.18288)
		(layer "In2.Cu")
		(net "M_F_CPU0_SB_CB<2>")
	)
	(segment
		(start 408.91333 -233.354626)
		(end 408.284934 -233.983022)
		(width 0.18288)
		(layer "In2.Cu")
		(net "M_F_CPU0_SB_CB<2>")
	)
	(segment
		(start 405.93137 -235.1151)
		(end 405.736298 -235.310172)
		(width 0.18288)
		(layer "In2.Cu")
		(net "M_F_CPU0_SB_CB<2>")
	)
	(segment
		(start 383.732532 -238.549942)
		(end 383.683764 -238.578136)
		(width 0.088646)
		(layer "In2.Cu")
		(net "M_F_CPU0_SB_CB<2>")
	)
	(segment
		(start 419.694106 -234.301284)
		(end 417.203636 -234.301284)
		(width 0.18288)
		(layer "In2.Cu")
		(net "M_F_CPU0_SB_CB<2>")
	)
	(segment
		(start 409.879546 -233.354626)
		(end 408.91333 -233.354626)
		(width 0.18288)
		(layer "In2.Cu")
		(net "M_F_CPU0_SB_CB<2>")
	)
	(segment
		(start 416.975544 -234.195366)
		(end 416.416744 -233.534204)
		(width 0.18288)
		(layer "In2.Cu")
		(net "M_F_CPU0_SB_CB<2>")
	)
	(segment
		(start 407.566114 -235.1151)
		(end 405.93137 -235.1151)
		(width 0.18288)
		(layer "In2.Cu")
		(net "M_F_CPU0_SB_CB<2>")
	)
	(arc
		(start 386.082032 -239.363758)
		(mid 385.707557 -239.363712)
		(end 385.520184 -239.0394)
		(width 0.088646)
		(layer "In2.Cu")
		(net "M_F_CPU0_SB_CB<2>")
	)
	(arc
		(start 385.520184 -239.029494)
		(mid 385.233309 -238.547409)
		(end 384.672332 -238.549942)
		(width 0.088646)
		(layer "In2.Cu")
		(net "M_F_CPU0_SB_CB<2>")
	)
	(arc
		(start 387.021832 -239.363758)
		(mid 386.834634 -239.413901)
		(end 386.647436 -239.363758)
		(width 0.088646)
		(layer "In2.Cu")
		(net "M_F_CPU0_SB_CB<2>")
	)
	(arc
		(start 387.30428 -239.288066)
		(mid 387.158072 -239.307315)
		(end 387.021832 -239.363758)
		(width 0.088646)
		(layer "In2.Cu")
		(net "M_F_CPU0_SB_CB<2>")
	)
	(arc
		(start 384.672332 -238.549942)
		(mid 384.485134 -238.600085)
		(end 384.297936 -238.549942)
		(width 0.088646)
		(layer "In2.Cu")
		(net "M_F_CPU0_SB_CB<2>")
	)
	(arc
		(start 386.647436 -239.363758)
		(mid 386.373237 -239.287923)
		(end 386.096764 -239.355122)
		(width 0.088646)
		(layer "In2.Cu")
		(net "M_F_CPU0_SB_CB<2>")
	)
	(arc
		(start 384.297936 -238.549942)
		(mid 384.015234 -238.474166)
		(end 383.732532 -238.549942)
		(width 0.088646)
		(layer "In2.Cu")
		(net "M_F_CPU0_SB_CB<2>")
	)
	(segment
		(start 429.38446 -233.866944)
		(end 427.792896 -233.866944)
		(width 0.20066)
		(layer "F.Cu")
		(net "M_F_CPU0_SB_CB<1>")
	)
	(segment
		(start 426.951394 -233.435398)
		(end 426.945044 -233.441748)
		(width 0.1016)
		(layer "F.Cu")
		(net "M_F_CPU0_SB_CB<1>")
	)
	(segment
		(start 424.756326 -233.441748)
		(end 424.73626 -233.441748)
		(width 0.101854)
		(layer "F.Cu")
		(net "M_F_CPU0_SB_CB<1>")
	)
	(segment
		(start 426.945044 -233.441748)
		(end 424.756326 -233.441748)
		(width 0.1016)
		(layer "F.Cu")
		(net "M_F_CPU0_SB_CB<1>")
	)
	(segment
		(start 427.792896 -233.866944)
		(end 427.36135 -233.435398)
		(width 0.20066)
		(layer "F.Cu")
		(net "M_F_CPU0_SB_CB<1>")
	)
	(segment
		(start 427.36135 -233.435398)
		(end 426.951394 -233.435398)
		(width 0.20066)
		(layer "F.Cu")
		(net "M_F_CPU0_SB_CB<1>")
	)
	(segment
		(start 424.273472 -233.927396)
		(end 424.085512 -234.115356)
		(width 0.20066)
		(layer "F.Cu")
		(net "M_F_CPU0_SB_CB<1>")
	)
	(segment
		(start 424.391582 -233.441748)
		(end 424.273472 -233.559858)
		(width 0.20066)
		(layer "F.Cu")
		(net "M_F_CPU0_SB_CB<1>")
	)
	(segment
		(start 423.610278 -234.115356)
		(end 423.361612 -233.86669)
		(width 0.20066)
		(layer "F.Cu")
		(net "M_F_CPU0_SB_CB<1>")
	)
	(segment
		(start 424.273472 -233.559858)
		(end 424.273472 -233.927396)
		(width 0.20066)
		(layer "F.Cu")
		(net "M_F_CPU0_SB_CB<1>")
	)
	(segment
		(start 423.361612 -233.86669)
		(end 421.840914 -233.86669)
		(width 0.20066)
		(layer "F.Cu")
		(net "M_F_CPU0_SB_CB<1>")
	)
	(segment
		(start 424.085512 -234.115356)
		(end 423.610278 -234.115356)
		(width 0.20066)
		(layer "F.Cu")
		(net "M_F_CPU0_SB_CB<1>")
	)
	(segment
		(start 421.840914 -233.86669)
		(end 420.736014 -233.86669)
		(width 0.20066)
		(layer "F.Cu")
		(net "M_F_CPU0_SB_CB<1>")
	)
	(segment
		(start 429.384714 -233.86669)
		(end 429.38446 -233.866944)
		(width 0.20066)
		(layer "F.Cu")
		(net "M_F_CPU0_SB_CB<1>")
	)
	(segment
		(start 381.665734 -238.761524)
		(end 381.665734 -238.225584)
		(width 0.20066)
		(layer "F.Cu")
		(net "M_F_CPU0_SB_CB<1>")
	)
	(segment
		(start 424.73626 -233.441748)
		(end 424.391582 -233.441748)
		(width 0.20066)
		(layer "F.Cu")
		(net "M_F_CPU0_SB_CB<1>")
	)
	(segment
		(start 416.82416 -232.990644)
		(end 416.545014 -232.711498)
		(width 0.18288)
		(layer "In2.Cu")
		(net "M_F_CPU0_SB_CB<1>")
	)
	(segment
		(start 406.11425 -234.273598)
		(end 405.318214 -234.273598)
		(width 0.18288)
		(layer "In2.Cu")
		(net "M_F_CPU0_SB_CB<1>")
	)
	(segment
		(start 420.110666 -232.896156)
		(end 419.876986 -232.662476)
		(width 0.18288)
		(layer "In2.Cu")
		(net "M_F_CPU0_SB_CB<1>")
	)
	(segment
		(start 419.876986 -232.662476)
		(end 419.521386 -232.662476)
		(width 0.18288)
		(layer "In2.Cu")
		(net "M_F_CPU0_SB_CB<1>")
	)
	(segment
		(start 419.328346 -232.855516)
		(end 419.328346 -233.38663)
		(width 0.18288)
		(layer "In2.Cu")
		(net "M_F_CPU0_SB_CB<1>")
	)
	(segment
		(start 383.170684 -238.225584)
		(end 383.170684 -238.23549)
		(width 0.088646)
		(layer "In2.Cu")
		(net "M_F_CPU0_SB_CB<1>")
	)
	(segment
		(start 419.038786 -233.67619)
		(end 417.770056 -233.67619)
		(width 0.18288)
		(layer "In2.Cu")
		(net "M_F_CPU0_SB_CB<1>")
	)
	(segment
		(start 381.978662 -238.225584)
		(end 381.665734 -238.225584)
		(width 0.088646)
		(layer "In2.Cu")
		(net "M_F_CPU0_SB_CB<1>")
	)
	(segment
		(start 405.318214 -234.273598)
		(end 400.71548 -238.876332)
		(width 0.18288)
		(layer "In2.Cu")
		(net "M_F_CPU0_SB_CB<1>")
	)
	(segment
		(start 411.7975 -232.62971)
		(end 411.528768 -232.360978)
		(width 0.18288)
		(layer "In2.Cu")
		(net "M_F_CPU0_SB_CB<1>")
	)
	(segment
		(start 407.743406 -234.109514)
		(end 407.329386 -234.523534)
		(width 0.18288)
		(layer "In2.Cu")
		(net "M_F_CPU0_SB_CB<1>")
	)
	(segment
		(start 407.329386 -234.523534)
		(end 406.364186 -234.523534)
		(width 0.18288)
		(layer "In2.Cu")
		(net "M_F_CPU0_SB_CB<1>")
	)
	(segment
		(start 419.328346 -233.38663)
		(end 419.038786 -233.67619)
		(width 0.18288)
		(layer "In2.Cu")
		(net "M_F_CPU0_SB_CB<1>")
	)
	(segment
		(start 407.743406 -233.783886)
		(end 407.743406 -234.109514)
		(width 0.18288)
		(layer "In2.Cu")
		(net "M_F_CPU0_SB_CB<1>")
	)
	(segment
		(start 410.22524 -232.360978)
		(end 409.956508 -232.62971)
		(width 0.18288)
		(layer "In2.Cu")
		(net "M_F_CPU0_SB_CB<1>")
	)
	(segment
		(start 420.736014 -233.86669)
		(end 420.110666 -233.241342)
		(width 0.18288)
		(layer "In2.Cu")
		(net "M_F_CPU0_SB_CB<1>")
	)
	(segment
		(start 387.9469 -238.876332)
		(end 387.861302 -238.790734)
		(width 0.088646)
		(layer "In2.Cu")
		(net "M_F_CPU0_SB_CB<1>")
	)
	(segment
		(start 382.04394 -238.290862)
		(end 381.978662 -238.225584)
		(width 0.088646)
		(layer "In2.Cu")
		(net "M_F_CPU0_SB_CB<1>")
	)
	(segment
		(start 413.81045 -231.754426)
		(end 413.044894 -231.754426)
		(width 0.18288)
		(layer "In2.Cu")
		(net "M_F_CPU0_SB_CB<1>")
	)
	(segment
		(start 417.770056 -233.67619)
		(end 417.08451 -232.990644)
		(width 0.18288)
		(layer "In2.Cu")
		(net "M_F_CPU0_SB_CB<1>")
	)
	(segment
		(start 409.956508 -232.62971)
		(end 408.687778 -232.62971)
		(width 0.18288)
		(layer "In2.Cu")
		(net "M_F_CPU0_SB_CB<1>")
	)
	(segment
		(start 408.687778 -232.62971)
		(end 408.414982 -232.902506)
		(width 0.18288)
		(layer "In2.Cu")
		(net "M_F_CPU0_SB_CB<1>")
	)
	(segment
		(start 406.364186 -234.523534)
		(end 406.11425 -234.273598)
		(width 0.18288)
		(layer "In2.Cu")
		(net "M_F_CPU0_SB_CB<1>")
	)
	(segment
		(start 408.414982 -233.11231)
		(end 407.743406 -233.783886)
		(width 0.18288)
		(layer "In2.Cu")
		(net "M_F_CPU0_SB_CB<1>")
	)
	(segment
		(start 408.414982 -232.902506)
		(end 408.414982 -233.11231)
		(width 0.18288)
		(layer "In2.Cu")
		(net "M_F_CPU0_SB_CB<1>")
	)
	(segment
		(start 385.799584 -238.23549)
		(end 385.799584 -238.225584)
		(width 0.088646)
		(layer "In2.Cu")
		(net "M_F_CPU0_SB_CB<1>")
	)
	(segment
		(start 414.075372 -231.489504)
		(end 413.81045 -231.754426)
		(width 0.18288)
		(layer "In2.Cu")
		(net "M_F_CPU0_SB_CB<1>")
	)
	(segment
		(start 414.533588 -231.489504)
		(end 414.075372 -231.489504)
		(width 0.18288)
		(layer "In2.Cu")
		(net "M_F_CPU0_SB_CB<1>")
	)
	(segment
		(start 388.458964 -238.876332)
		(end 387.9469 -238.876332)
		(width 0.088646)
		(layer "In2.Cu")
		(net "M_F_CPU0_SB_CB<1>")
	)
	(segment
		(start 416.545014 -232.485438)
		(end 416.83559 -232.194862)
		(width 0.18288)
		(layer "In2.Cu")
		(net "M_F_CPU0_SB_CB<1>")
	)
	(segment
		(start 416.83559 -231.780842)
		(end 416.44316 -231.388412)
		(width 0.18288)
		(layer "In2.Cu")
		(net "M_F_CPU0_SB_CB<1>")
	)
	(segment
		(start 413.044894 -231.754426)
		(end 412.16961 -232.62971)
		(width 0.18288)
		(layer "In2.Cu")
		(net "M_F_CPU0_SB_CB<1>")
	)
	(segment
		(start 387.861302 -238.790734)
		(end 387.304534 -238.790734)
		(width 0.088646)
		(layer "In2.Cu")
		(net "M_F_CPU0_SB_CB<1>")
	)
	(segment
		(start 416.0774 -231.388412)
		(end 415.711386 -231.754426)
		(width 0.18288)
		(layer "In2.Cu")
		(net "M_F_CPU0_SB_CB<1>")
	)
	(segment
		(start 420.110666 -233.241342)
		(end 420.110666 -232.896156)
		(width 0.18288)
		(layer "In2.Cu")
		(net "M_F_CPU0_SB_CB<1>")
	)
	(segment
		(start 414.79851 -231.754426)
		(end 414.533588 -231.489504)
		(width 0.18288)
		(layer "In2.Cu")
		(net "M_F_CPU0_SB_CB<1>")
	)
	(segment
		(start 416.545014 -232.711498)
		(end 416.545014 -232.485438)
		(width 0.18288)
		(layer "In2.Cu")
		(net "M_F_CPU0_SB_CB<1>")
	)
	(segment
		(start 419.521386 -232.662476)
		(end 419.328346 -232.855516)
		(width 0.18288)
		(layer "In2.Cu")
		(net "M_F_CPU0_SB_CB<1>")
	)
	(segment
		(start 400.71548 -238.876332)
		(end 388.458964 -238.876332)
		(width 0.18288)
		(layer "In2.Cu")
		(net "M_F_CPU0_SB_CB<1>")
	)
	(segment
		(start 416.83559 -232.194862)
		(end 416.83559 -231.780842)
		(width 0.18288)
		(layer "In2.Cu")
		(net "M_F_CPU0_SB_CB<1>")
	)
	(segment
		(start 412.16961 -232.62971)
		(end 411.7975 -232.62971)
		(width 0.18288)
		(layer "In2.Cu")
		(net "M_F_CPU0_SB_CB<1>")
	)
	(segment
		(start 416.44316 -231.388412)
		(end 416.0774 -231.388412)
		(width 0.18288)
		(layer "In2.Cu")
		(net "M_F_CPU0_SB_CB<1>")
	)
	(segment
		(start 417.08451 -232.990644)
		(end 416.82416 -232.990644)
		(width 0.18288)
		(layer "In2.Cu")
		(net "M_F_CPU0_SB_CB<1>")
	)
	(segment
		(start 415.711386 -231.754426)
		(end 414.79851 -231.754426)
		(width 0.18288)
		(layer "In2.Cu")
		(net "M_F_CPU0_SB_CB<1>")
	)
	(segment
		(start 411.528768 -232.360978)
		(end 410.22524 -232.360978)
		(width 0.18288)
		(layer "In2.Cu")
		(net "M_F_CPU0_SB_CB<1>")
	)
	(arc
		(start 387.304534 -238.790734)
		(mid 387.158211 -238.771472)
		(end 387.021832 -238.715042)
		(width 0.088646)
		(layer "In2.Cu")
		(net "M_F_CPU0_SB_CB<1>")
	)
	(arc
		(start 383.170684 -238.23549)
		(mid 382.633274 -238.79014)
		(end 382.04394 -238.290862)
		(width 0.088646)
		(layer "In2.Cu")
		(net "M_F_CPU0_SB_CB<1>")
	)
	(arc
		(start 386.647436 -238.715042)
		(mid 386.08646 -238.717573)
		(end 385.799584 -238.23549)
		(width 0.088646)
		(layer "In2.Cu")
		(net "M_F_CPU0_SB_CB<1>")
	)
	(arc
		(start 387.021832 -238.715042)
		(mid 386.834634 -238.664899)
		(end 386.647436 -238.715042)
		(width 0.088646)
		(layer "In2.Cu")
		(net "M_F_CPU0_SB_CB<1>")
	)
	(arc
		(start 385.237736 -237.901226)
		(mid 384.955034 -237.976968)
		(end 384.672332 -237.901226)
		(width 0.088646)
		(layer "In2.Cu")
		(net "M_F_CPU0_SB_CB<1>")
	)
	(arc
		(start 384.297936 -237.901226)
		(mid 384.015234 -237.976968)
		(end 383.732532 -237.901226)
		(width 0.088646)
		(layer "In2.Cu")
		(net "M_F_CPU0_SB_CB<1>")
	)
	(arc
		(start 385.799584 -238.225584)
		(mid 385.612285 -237.901143)
		(end 385.237736 -237.901226)
		(width 0.088646)
		(layer "In2.Cu")
		(net "M_F_CPU0_SB_CB<1>")
	)
	(arc
		(start 384.672332 -237.901226)
		(mid 384.485134 -237.851083)
		(end 384.297936 -237.901226)
		(width 0.088646)
		(layer "In2.Cu")
		(net "M_F_CPU0_SB_CB<1>")
	)
	(arc
		(start 383.732532 -237.901226)
		(mid 383.358057 -237.901272)
		(end 383.170684 -238.225584)
		(width 0.088646)
		(layer "In2.Cu")
		(net "M_F_CPU0_SB_CB<1>")
	)
	(segment
		(start 427.792896 -235.566966)
		(end 427.36135 -235.13542)
		(width 0.20066)
		(layer "F.Cu")
		(net "M_F_CPU0_SB_CB<0>")
	)
	(segment
		(start 424.391582 -235.14177)
		(end 424.273472 -235.25988)
		(width 0.20066)
		(layer "F.Cu")
		(net "M_F_CPU0_SB_CB<0>")
	)
	(segment
		(start 429.38446 -235.566966)
		(end 427.792896 -235.566966)
		(width 0.20066)
		(layer "F.Cu")
		(net "M_F_CPU0_SB_CB<0>")
	)
	(segment
		(start 424.78325 -235.14177)
		(end 424.73626 -235.14177)
		(width 0.101854)
		(layer "F.Cu")
		(net "M_F_CPU0_SB_CB<0>")
	)
	(segment
		(start 426.945044 -235.14177)
		(end 424.78325 -235.14177)
		(width 0.1016)
		(layer "F.Cu")
		(net "M_F_CPU0_SB_CB<0>")
	)
	(segment
		(start 429.384714 -235.566712)
		(end 429.38446 -235.566966)
		(width 0.20066)
		(layer "F.Cu")
		(net "M_F_CPU0_SB_CB<0>")
	)
	(segment
		(start 423.361612 -235.566712)
		(end 421.840914 -235.566712)
		(width 0.20066)
		(layer "F.Cu")
		(net "M_F_CPU0_SB_CB<0>")
	)
	(segment
		(start 424.273472 -235.627418)
		(end 424.085512 -235.815378)
		(width 0.20066)
		(layer "F.Cu")
		(net "M_F_CPU0_SB_CB<0>")
	)
	(segment
		(start 381.19558 -239.57534)
		(end 381.195834 -239.575086)
		(width 0.20066)
		(layer "F.Cu")
		(net "M_F_CPU0_SB_CB<0>")
	)
	(segment
		(start 424.273472 -235.25988)
		(end 424.273472 -235.627418)
		(width 0.20066)
		(layer "F.Cu")
		(net "M_F_CPU0_SB_CB<0>")
	)
	(segment
		(start 421.840914 -235.566712)
		(end 420.736014 -235.566712)
		(width 0.20066)
		(layer "F.Cu")
		(net "M_F_CPU0_SB_CB<0>")
	)
	(segment
		(start 426.951394 -235.13542)
		(end 426.945044 -235.14177)
		(width 0.1016)
		(layer "F.Cu")
		(net "M_F_CPU0_SB_CB<0>")
	)
	(segment
		(start 424.085512 -235.815378)
		(end 423.610278 -235.815378)
		(width 0.20066)
		(layer "F.Cu")
		(net "M_F_CPU0_SB_CB<0>")
	)
	(segment
		(start 427.36135 -235.13542)
		(end 426.951394 -235.13542)
		(width 0.20066)
		(layer "F.Cu")
		(net "M_F_CPU0_SB_CB<0>")
	)
	(segment
		(start 424.73626 -235.14177)
		(end 424.391582 -235.14177)
		(width 0.20066)
		(layer "F.Cu")
		(net "M_F_CPU0_SB_CB<0>")
	)
	(segment
		(start 423.610278 -235.815378)
		(end 423.361612 -235.566712)
		(width 0.20066)
		(layer "F.Cu")
		(net "M_F_CPU0_SB_CB<0>")
	)
	(segment
		(start 381.195834 -239.575086)
		(end 381.195834 -239.0394)
		(width 0.20066)
		(layer "F.Cu")
		(net "M_F_CPU0_SB_CB<0>")
	)
	(segment
		(start 407.83256 -235.71835)
		(end 407.59888 -235.95203)
		(width 0.18288)
		(layer "In2.Cu")
		(net "M_F_CPU0_SB_CB<0>")
	)
	(segment
		(start 383.827782 -238.715042)
		(end 383.822702 -238.71809)
		(width 0.088646)
		(layer "In2.Cu")
		(net "M_F_CPU0_SB_CB<0>")
	)
	(segment
		(start 408.267408 -235.858812)
		(end 408.126946 -235.71835)
		(width 0.18288)
		(layer "In2.Cu")
		(net "M_F_CPU0_SB_CB<0>")
	)
	(segment
		(start 416.134804 -235.029248)
		(end 416.134804 -234.668568)
		(width 0.18288)
		(layer "In2.Cu")
		(net "M_F_CPU0_SB_CB<0>")
	)
	(segment
		(start 411.155134 -234.046014)
		(end 411.008068 -234.19308)
		(width 0.18288)
		(layer "In2.Cu")
		(net "M_F_CPU0_SB_CB<0>")
	)
	(segment
		(start 409.157932 -235.241338)
		(end 408.540458 -235.858812)
		(width 0.18288)
		(layer "In2.Cu")
		(net "M_F_CPU0_SB_CB<0>")
	)
	(segment
		(start 411.51683 -234.046014)
		(end 411.155134 -234.046014)
		(width 0.18288)
		(layer "In2.Cu")
		(net "M_F_CPU0_SB_CB<0>")
	)
	(segment
		(start 387.977634 -239.917478)
		(end 387.538468 -239.478312)
		(width 0.088646)
		(layer "In2.Cu")
		(net "M_F_CPU0_SB_CB<0>")
	)
	(segment
		(start 417.084764 -234.870752)
		(end 416.6997 -235.255816)
		(width 0.18288)
		(layer "In2.Cu")
		(net "M_F_CPU0_SB_CB<0>")
	)
	(segment
		(start 409.513786 -234.29341)
		(end 409.25877 -234.038394)
		(width 0.18288)
		(layer "In2.Cu")
		(net "M_F_CPU0_SB_CB<0>")
	)
	(segment
		(start 407.59888 -235.95203)
		(end 405.790146 -235.95203)
		(width 0.18288)
		(layer "In2.Cu")
		(net "M_F_CPU0_SB_CB<0>")
	)
	(segment
		(start 386.177282 -239.528858)
		(end 386.16255 -239.537494)
		(width 0.088646)
		(layer "In2.Cu")
		(net "M_F_CPU0_SB_CB<0>")
	)
	(segment
		(start 420.736014 -235.266738)
		(end 420.603934 -235.134912)
		(width 0.18288)
		(layer "In2.Cu")
		(net "M_F_CPU0_SB_CB<0>")
	)
	(segment
		(start 383.549652 -239.101122)
		(end 383.363216 -239.287558)
		(width 0.088646)
		(layer "In2.Cu")
		(net "M_F_CPU0_SB_CB<0>")
	)
	(segment
		(start 381.948182 -239.364012)
		(end 381.547116 -239.13338)
		(width 0.088646)
		(layer "In2.Cu")
		(net "M_F_CPU0_SB_CB<0>")
	)
	(segment
		(start 401.131024 -239.917478)
		(end 388.458964 -239.917478)
		(width 0.18288)
		(layer "In2.Cu")
		(net "M_F_CPU0_SB_CB<0>")
	)
	(segment
		(start 420.603934 -235.134912)
		(end 420.431722 -235.134912)
		(width 0.18288)
		(layer "In2.Cu")
		(net "M_F_CPU0_SB_CB<0>")
	)
	(segment
		(start 382.887982 -239.364012)
		(end 382.88341 -239.361218)
		(width 0.088646)
		(layer "In2.Cu")
		(net "M_F_CPU0_SB_CB<0>")
	)
	(segment
		(start 415.734754 -233.636058)
		(end 415.392362 -233.636058)
		(width 0.18288)
		(layer "In2.Cu")
		(net "M_F_CPU0_SB_CB<0>")
	)
	(segment
		(start 416.134804 -234.668568)
		(end 416.314382 -234.48899)
		(width 0.18288)
		(layer "In2.Cu")
		(net "M_F_CPU0_SB_CB<0>")
	)
	(segment
		(start 383.828036 -238.715042)
		(end 383.827782 -238.715042)
		(width 0.088646)
		(layer "In2.Cu")
		(net "M_F_CPU0_SB_CB<0>")
	)
	(segment
		(start 409.25877 -234.038394)
		(end 408.985974 -234.038394)
		(width 0.18288)
		(layer "In2.Cu")
		(net "M_F_CPU0_SB_CB<0>")
	)
	(segment
		(start 419.352984 -235.09859)
		(end 417.585652 -235.09859)
		(width 0.18288)
		(layer "In2.Cu")
		(net "M_F_CPU0_SB_CB<0>")
	)
	(segment
		(start 414.823402 -233.067098)
		(end 413.853122 -233.067098)
		(width 0.18288)
		(layer "In2.Cu")
		(net "M_F_CPU0_SB_CB<0>")
	)
	(segment
		(start 388.458964 -239.917478)
		(end 387.977634 -239.917478)
		(width 0.088646)
		(layer "In2.Cu")
		(net "M_F_CPU0_SB_CB<0>")
	)
	(segment
		(start 420.106094 -234.809284)
		(end 419.64229 -234.809284)
		(width 0.18288)
		(layer "In2.Cu")
		(net "M_F_CPU0_SB_CB<0>")
	)
	(segment
		(start 387.538468 -239.478312)
		(end 387.30428 -239.478312)
		(width 0.088646)
		(layer "In2.Cu")
		(net "M_F_CPU0_SB_CB<0>")
	)
	(segment
		(start 411.774386 -234.30357)
		(end 411.51683 -234.046014)
		(width 0.18288)
		(layer "In2.Cu")
		(net "M_F_CPU0_SB_CB<0>")
	)
	(segment
		(start 420.736014 -235.566712)
		(end 420.736014 -235.266738)
		(width 0.18288)
		(layer "In2.Cu")
		(net "M_F_CPU0_SB_CB<0>")
	)
	(segment
		(start 405.790146 -235.95203)
		(end 405.663146 -235.82503)
		(width 0.18288)
		(layer "In2.Cu")
		(net "M_F_CPU0_SB_CB<0>")
	)
	(segment
		(start 416.6997 -235.255816)
		(end 416.361372 -235.255816)
		(width 0.18288)
		(layer "In2.Cu")
		(net "M_F_CPU0_SB_CB<0>")
	)
	(segment
		(start 410.010102 -234.29341)
		(end 409.513786 -234.29341)
		(width 0.18288)
		(layer "In2.Cu")
		(net "M_F_CPU0_SB_CB<0>")
	)
	(segment
		(start 416.314382 -234.215686)
		(end 415.734754 -233.636058)
		(width 0.18288)
		(layer "In2.Cu")
		(net "M_F_CPU0_SB_CB<0>")
	)
	(segment
		(start 408.792934 -234.60329)
		(end 409.157932 -234.968288)
		(width 0.18288)
		(layer "In2.Cu")
		(net "M_F_CPU0_SB_CB<0>")
	)
	(segment
		(start 385.329684 -239.054894)
		(end 385.329684 -239.0394)
		(width 0.088646)
		(layer "In2.Cu")
		(net "M_F_CPU0_SB_CB<0>")
	)
	(segment
		(start 412.145226 -234.30357)
		(end 411.774386 -234.30357)
		(width 0.18288)
		(layer "In2.Cu")
		(net "M_F_CPU0_SB_CB<0>")
	)
	(segment
		(start 413.853122 -233.067098)
		(end 413.286194 -233.634026)
		(width 0.18288)
		(layer "In2.Cu")
		(net "M_F_CPU0_SB_CB<0>")
	)
	(segment
		(start 382.893824 -239.367314)
		(end 382.887982 -239.364012)
		(width 0.088646)
		(layer "In2.Cu")
		(net "M_F_CPU0_SB_CB<0>")
	)
	(segment
		(start 408.792934 -234.231434)
		(end 408.792934 -234.60329)
		(width 0.18288)
		(layer "In2.Cu")
		(net "M_F_CPU0_SB_CB<0>")
	)
	(segment
		(start 416.314382 -234.48899)
		(end 416.314382 -234.215686)
		(width 0.18288)
		(layer "In2.Cu")
		(net "M_F_CPU0_SB_CB<0>")
	)
	(segment
		(start 385.151122 -238.720122)
		(end 385.142232 -238.715042)
		(width 0.088646)
		(layer "In2.Cu")
		(net "M_F_CPU0_SB_CB<0>")
	)
	(segment
		(start 410.734764 -234.19308)
		(end 410.587698 -234.046014)
		(width 0.18288)
		(layer "In2.Cu")
		(net "M_F_CPU0_SB_CB<0>")
	)
	(segment
		(start 410.587698 -234.046014)
		(end 410.257498 -234.046014)
		(width 0.18288)
		(layer "In2.Cu")
		(net "M_F_CPU0_SB_CB<0>")
	)
	(segment
		(start 410.257498 -234.046014)
		(end 410.010102 -234.29341)
		(width 0.18288)
		(layer "In2.Cu")
		(net "M_F_CPU0_SB_CB<0>")
	)
	(segment
		(start 415.392362 -233.636058)
		(end 414.823402 -233.067098)
		(width 0.18288)
		(layer "In2.Cu")
		(net "M_F_CPU0_SB_CB<0>")
	)
	(segment
		(start 420.431722 -235.134912)
		(end 420.106094 -234.809284)
		(width 0.18288)
		(layer "In2.Cu")
		(net "M_F_CPU0_SB_CB<0>")
	)
	(segment
		(start 412.81477 -233.634026)
		(end 412.145226 -234.30357)
		(width 0.18288)
		(layer "In2.Cu")
		(net "M_F_CPU0_SB_CB<0>")
	)
	(segment
		(start 411.008068 -234.19308)
		(end 410.734764 -234.19308)
		(width 0.18288)
		(layer "In2.Cu")
		(net "M_F_CPU0_SB_CB<0>")
	)
	(segment
		(start 405.223472 -235.82503)
		(end 401.131024 -239.917478)
		(width 0.18288)
		(layer "In2.Cu")
		(net "M_F_CPU0_SB_CB<0>")
	)
	(segment
		(start 413.286194 -233.634026)
		(end 412.81477 -233.634026)
		(width 0.18288)
		(layer "In2.Cu")
		(net "M_F_CPU0_SB_CB<0>")
	)
	(segment
		(start 417.585652 -235.09859)
		(end 417.357814 -234.870752)
		(width 0.18288)
		(layer "In2.Cu")
		(net "M_F_CPU0_SB_CB<0>")
	)
	(segment
		(start 408.126946 -235.71835)
		(end 407.83256 -235.71835)
		(width 0.18288)
		(layer "In2.Cu")
		(net "M_F_CPU0_SB_CB<0>")
	)
	(segment
		(start 408.985974 -234.038394)
		(end 408.792934 -234.231434)
		(width 0.18288)
		(layer "In2.Cu")
		(net "M_F_CPU0_SB_CB<0>")
	)
	(segment
		(start 408.540458 -235.858812)
		(end 408.267408 -235.858812)
		(width 0.18288)
		(layer "In2.Cu")
		(net "M_F_CPU0_SB_CB<0>")
	)
	(segment
		(start 419.64229 -234.809284)
		(end 419.352984 -235.09859)
		(width 0.18288)
		(layer "In2.Cu")
		(net "M_F_CPU0_SB_CB<0>")
	)
	(segment
		(start 416.361372 -235.255816)
		(end 416.134804 -235.029248)
		(width 0.18288)
		(layer "In2.Cu")
		(net "M_F_CPU0_SB_CB<0>")
	)
	(segment
		(start 417.357814 -234.870752)
		(end 417.084764 -234.870752)
		(width 0.18288)
		(layer "In2.Cu")
		(net "M_F_CPU0_SB_CB<0>")
	)
	(segment
		(start 383.26695 -239.361472)
		(end 383.262632 -239.364012)
		(width 0.088646)
		(layer "In2.Cu")
		(net "M_F_CPU0_SB_CB<0>")
	)
	(segment
		(start 409.157932 -234.968288)
		(end 409.157932 -235.241338)
		(width 0.18288)
		(layer "In2.Cu")
		(net "M_F_CPU0_SB_CB<0>")
	)
	(segment
		(start 405.663146 -235.82503)
		(end 405.223472 -235.82503)
		(width 0.18288)
		(layer "In2.Cu")
		(net "M_F_CPU0_SB_CB<0>")
	)
	(arc
		(start 383.822702 -238.71809)
		(mid 383.722275 -238.805778)
		(end 383.658872 -238.923068)
		(width 0.088646)
		(layer "In2.Cu")
		(net "M_F_CPU0_SB_CB<0>")
	)
	(arc
		(start 384.767836 -238.715042)
		(mid 384.485134 -238.790818)
		(end 384.202432 -238.715042)
		(width 0.088646)
		(layer "In2.Cu")
		(net "M_F_CPU0_SB_CB<0>")
	)
	(arc
		(start 387.30428 -239.478312)
		(mid 387.199079 -239.493449)
		(end 387.10235 -239.537494)
		(width 0.088646)
		(layer "In2.Cu")
		(net "M_F_CPU0_SB_CB<0>")
	)
	(arc
		(start 387.10235 -239.537494)
		(mid 386.825875 -239.604814)
		(end 386.551678 -239.528858)
		(width 0.088646)
		(layer "In2.Cu")
		(net "M_F_CPU0_SB_CB<0>")
	)
	(arc
		(start 386.16255 -239.537494)
		(mid 385.886075 -239.604814)
		(end 385.611878 -239.528858)
		(width 0.088646)
		(layer "In2.Cu")
		(net "M_F_CPU0_SB_CB<0>")
	)
	(arc
		(start 384.202432 -238.715042)
		(mid 384.015234 -238.664899)
		(end 383.828036 -238.715042)
		(width 0.088646)
		(layer "In2.Cu")
		(net "M_F_CPU0_SB_CB<0>")
	)
	(arc
		(start 386.551678 -239.528858)
		(mid 386.36448 -239.478715)
		(end 386.177282 -239.528858)
		(width 0.088646)
		(layer "In2.Cu")
		(net "M_F_CPU0_SB_CB<0>")
	)
	(arc
		(start 381.547116 -239.13338)
		(mid 381.37764 -239.063336)
		(end 381.195834 -239.0394)
		(width 0.088646)
		(layer "In2.Cu")
		(net "M_F_CPU0_SB_CB<0>")
	)
	(arc
		(start 382.322832 -239.364012)
		(mid 382.135524 -239.414121)
		(end 381.948182 -239.364012)
		(width 0.088646)
		(layer "In2.Cu")
		(net "M_F_CPU0_SB_CB<0>")
	)
	(arc
		(start 383.658872 -238.923068)
		(mid 383.614793 -239.018559)
		(end 383.549652 -239.101122)
		(width 0.088646)
		(layer "In2.Cu")
		(net "M_F_CPU0_SB_CB<0>")
	)
	(arc
		(start 382.88341 -239.361218)
		(mid 382.602746 -239.28821)
		(end 382.322832 -239.364012)
		(width 0.088646)
		(layer "In2.Cu")
		(net "M_F_CPU0_SB_CB<0>")
	)
	(arc
		(start 383.363216 -239.287558)
		(mid 383.317505 -239.327669)
		(end 383.26695 -239.361472)
		(width 0.088646)
		(layer "In2.Cu")
		(net "M_F_CPU0_SB_CB<0>")
	)
	(arc
		(start 385.329684 -239.0394)
		(mid 385.282005 -238.8565)
		(end 385.151122 -238.720122)
		(width 0.088646)
		(layer "In2.Cu")
		(net "M_F_CPU0_SB_CB<0>")
	)
	(arc
		(start 385.142232 -238.715042)
		(mid 384.955034 -238.664899)
		(end 384.767836 -238.715042)
		(width 0.088646)
		(layer "In2.Cu")
		(net "M_F_CPU0_SB_CB<0>")
	)
	(arc
		(start 385.611878 -239.528858)
		(mid 385.409055 -239.328627)
		(end 385.329684 -239.054894)
		(width 0.088646)
		(layer "In2.Cu")
		(net "M_F_CPU0_SB_CB<0>")
	)
	(arc
		(start 383.262632 -239.364012)
		(mid 383.078678 -239.414107)
		(end 382.893824 -239.367314)
		(width 0.088646)
		(layer "In2.Cu")
		(net "M_F_CPU0_SB_CB<0>")
	)
	(segment
		(start 422.906444 -247.466612)
		(end 423.400728 -246.972328)
		(width 0.20066)
		(layer "F.Cu")
		(net "M_F_CPU0_SB_CA<6>")
	)
	(segment
		(start 424.75277 -247.891554)
		(end 424.766486 -247.891554)
		(width 0.101854)
		(layer "F.Cu")
		(net "M_F_CPU0_SB_CA<6>")
	)
	(segment
		(start 421.840914 -247.466612)
		(end 422.906444 -247.466612)
		(width 0.20066)
		(layer "F.Cu")
		(net "M_F_CPU0_SB_CA<6>")
	)
	(segment
		(start 427.805088 -247.466358)
		(end 429.38446 -247.466358)
		(width 0.20066)
		(layer "F.Cu")
		(net "M_F_CPU0_SB_CA<6>")
	)
	(segment
		(start 429.38446 -247.466358)
		(end 429.384714 -247.466612)
		(width 0.20066)
		(layer "F.Cu")
		(net "M_F_CPU0_SB_CA<6>")
	)
	(segment
		(start 420.736014 -247.466612)
		(end 421.840914 -247.466612)
		(width 0.20066)
		(layer "F.Cu")
		(net "M_F_CPU0_SB_CA<6>")
	)
	(segment
		(start 380.72568 -245.272306)
		(end 380.72568 -244.73662)
		(width 0.20066)
		(layer "F.Cu")
		(net "M_F_CPU0_SB_CA<6>")
	)
	(segment
		(start 424.645328 -247.891554)
		(end 424.75277 -247.891554)
		(width 0.20066)
		(layer "F.Cu")
		(net "M_F_CPU0_SB_CA<6>")
	)
	(segment
		(start 426.938948 -247.891554)
		(end 426.951394 -247.904)
		(width 0.1016)
		(layer "F.Cu")
		(net "M_F_CPU0_SB_CA<6>")
	)
	(segment
		(start 427.367446 -247.904)
		(end 427.805088 -247.466358)
		(width 0.20066)
		(layer "F.Cu")
		(net "M_F_CPU0_SB_CA<6>")
	)
	(segment
		(start 424.766486 -247.891554)
		(end 426.938948 -247.891554)
		(width 0.1016)
		(layer "F.Cu")
		(net "M_F_CPU0_SB_CA<6>")
	)
	(segment
		(start 423.400728 -246.972328)
		(end 423.726102 -246.972328)
		(width 0.20066)
		(layer "F.Cu")
		(net "M_F_CPU0_SB_CA<6>")
	)
	(segment
		(start 426.951394 -247.904)
		(end 427.367446 -247.904)
		(width 0.20066)
		(layer "F.Cu")
		(net "M_F_CPU0_SB_CA<6>")
	)
	(segment
		(start 423.726102 -246.972328)
		(end 424.645328 -247.891554)
		(width 0.20066)
		(layer "F.Cu")
		(net "M_F_CPU0_SB_CA<6>")
	)
	(segment
		(start 380.725934 -245.27256)
		(end 380.72568 -245.272306)
		(width 0.20066)
		(layer "F.Cu")
		(net "M_F_CPU0_SB_CA<6>")
	)
	(segment
		(start 385.799584 -246.364506)
		(end 385.799838 -246.364252)
		(width 0.088646)
		(layer "In2.Cu")
		(net "M_F_CPU0_SB_CA<6>")
	)
	(segment
		(start 416.090354 -247.45315)
		(end 416.090354 -247.696482)
		(width 0.18288)
		(layer "In2.Cu")
		(net "M_F_CPU0_SB_CA<6>")
	)
	(segment
		(start 408.59329 -248.167906)
		(end 408.274012 -247.848628)
		(width 0.18288)
		(layer "In2.Cu")
		(net "M_F_CPU0_SB_CA<6>")
	)
	(segment
		(start 399.359374 -248.532396)
		(end 398.92732 -248.532396)
		(width 0.18288)
		(layer "In2.Cu")
		(net "M_F_CPU0_SB_CA<6>")
	)
	(segment
		(start 385.799838 -246.209058)
		(end 385.69011 -246.099584)
		(width 0.088646)
		(layer "In2.Cu")
		(net "M_F_CPU0_SB_CA<6>")
	)
	(segment
		(start 401.15363 -247.92051)
		(end 400.96059 -248.11355)
		(width 0.18288)
		(layer "In2.Cu")
		(net "M_F_CPU0_SB_CA<6>")
	)
	(segment
		(start 411.391354 -247.583452)
		(end 410.310076 -247.583452)
		(width 0.18288)
		(layer "In2.Cu")
		(net "M_F_CPU0_SB_CA<6>")
	)
	(segment
		(start 414.794192 -248.213118)
		(end 413.703516 -248.213118)
		(width 0.18288)
		(layer "In2.Cu")
		(net "M_F_CPU0_SB_CA<6>")
	)
	(segment
		(start 412.836614 -247.885712)
		(end 412.528766 -248.19356)
		(width 0.18288)
		(layer "In2.Cu")
		(net "M_F_CPU0_SB_CA<6>")
	)
	(segment
		(start 382.337564 -245.234968)
		(end 382.322832 -245.226332)
		(width 0.088646)
		(layer "In2.Cu")
		(net "M_F_CPU0_SB_CA<6>")
	)
	(segment
		(start 386.02666 -247.047004)
		(end 385.799584 -246.819928)
		(width 0.088646)
		(layer "In2.Cu")
		(net "M_F_CPU0_SB_CA<6>")
	)
	(segment
		(start 408.274012 -247.848628)
		(end 407.71699 -247.848628)
		(width 0.18288)
		(layer "In2.Cu")
		(net "M_F_CPU0_SB_CA<6>")
	)
	(segment
		(start 399.552414 -248.339356)
		(end 399.359374 -248.532396)
		(width 0.18288)
		(layer "In2.Cu")
		(net "M_F_CPU0_SB_CA<6>")
	)
	(segment
		(start 415.150808 -247.856502)
		(end 414.794192 -248.213118)
		(width 0.18288)
		(layer "In2.Cu")
		(net "M_F_CPU0_SB_CA<6>")
	)
	(segment
		(start 398.92732 -248.532396)
		(end 397.61922 -247.224296)
		(width 0.18288)
		(layer "In2.Cu")
		(net "M_F_CPU0_SB_CA<6>")
	)
	(segment
		(start 405.898858 -247.847612)
		(end 405.397208 -247.847612)
		(width 0.18288)
		(layer "In2.Cu")
		(net "M_F_CPU0_SB_CA<6>")
	)
	(segment
		(start 416.984434 -248.160286)
		(end 416.791394 -247.967246)
		(width 0.18288)
		(layer "In2.Cu")
		(net "M_F_CPU0_SB_CA<6>")
	)
	(segment
		(start 381.383032 -245.226078)
		(end 381.353822 -245.209568)
		(width 0.088646)
		(layer "In2.Cu")
		(net "M_F_CPU0_SB_CA<6>")
	)
	(segment
		(start 416.791394 -247.967246)
		(end 416.791394 -247.42775)
		(width 0.18288)
		(layer "In2.Cu")
		(net "M_F_CPU0_SB_CA<6>")
	)
	(segment
		(start 416.275774 -247.26773)
		(end 416.090354 -247.45315)
		(width 0.18288)
		(layer "In2.Cu")
		(net "M_F_CPU0_SB_CA<6>")
	)
	(segment
		(start 412.528766 -248.19356)
		(end 412.001462 -248.19356)
		(width 0.18288)
		(layer "In2.Cu")
		(net "M_F_CPU0_SB_CA<6>")
	)
	(segment
		(start 416.090354 -247.696482)
		(end 415.930334 -247.856502)
		(width 0.18288)
		(layer "In2.Cu")
		(net "M_F_CPU0_SB_CA<6>")
	)
	(segment
		(start 406.244298 -248.193052)
		(end 405.898858 -247.847612)
		(width 0.18288)
		(layer "In2.Cu")
		(net "M_F_CPU0_SB_CA<6>")
	)
	(segment
		(start 400.96059 -248.339356)
		(end 400.76755 -248.532396)
		(width 0.18288)
		(layer "In2.Cu")
		(net "M_F_CPU0_SB_CA<6>")
	)
	(segment
		(start 416.791394 -247.42775)
		(end 416.631374 -247.26773)
		(width 0.18288)
		(layer "In2.Cu")
		(net "M_F_CPU0_SB_CA<6>")
	)
	(segment
		(start 399.745454 -247.92051)
		(end 399.552414 -248.11355)
		(width 0.18288)
		(layer "In2.Cu")
		(net "M_F_CPU0_SB_CA<6>")
	)
	(segment
		(start 381.38354 -245.226078)
		(end 381.383032 -245.226078)
		(width 0.088646)
		(layer "In2.Cu")
		(net "M_F_CPU0_SB_CA<6>")
	)
	(segment
		(start 386.82549 -247.845834)
		(end 386.02666 -247.047004)
		(width 0.18288)
		(layer "In2.Cu")
		(net "M_F_CPU0_SB_CA<6>")
	)
	(segment
		(start 416.631374 -247.26773)
		(end 416.275774 -247.26773)
		(width 0.18288)
		(layer "In2.Cu")
		(net "M_F_CPU0_SB_CA<6>")
	)
	(segment
		(start 419.491922 -248.169684)
		(end 418.953442 -247.631204)
		(width 0.18288)
		(layer "In2.Cu")
		(net "M_F_CPU0_SB_CA<6>")
	)
	(segment
		(start 385.799584 -246.819928)
		(end 385.799584 -246.364506)
		(width 0.088646)
		(layer "In2.Cu")
		(net "M_F_CPU0_SB_CA<6>")
	)
	(segment
		(start 417.313872 -248.160286)
		(end 416.984434 -248.160286)
		(width 0.18288)
		(layer "In2.Cu")
		(net "M_F_CPU0_SB_CA<6>")
	)
	(segment
		(start 401.664678 -248.11355)
		(end 401.471638 -247.92051)
		(width 0.18288)
		(layer "In2.Cu")
		(net "M_F_CPU0_SB_CA<6>")
	)
	(segment
		(start 381.353822 -245.209568)
		(end 380.72568 -244.73662)
		(width 0.088646)
		(layer "In2.Cu")
		(net "M_F_CPU0_SB_CA<6>")
	)
	(segment
		(start 401.857718 -248.532396)
		(end 401.664678 -248.339356)
		(width 0.18288)
		(layer "In2.Cu")
		(net "M_F_CPU0_SB_CA<6>")
	)
	(segment
		(start 400.449542 -248.532396)
		(end 400.256502 -248.339356)
		(width 0.18288)
		(layer "In2.Cu")
		(net "M_F_CPU0_SB_CA<6>")
	)
	(segment
		(start 400.256502 -248.11355)
		(end 400.063462 -247.92051)
		(width 0.18288)
		(layer "In2.Cu")
		(net "M_F_CPU0_SB_CA<6>")
	)
	(segment
		(start 388.672578 -247.845834)
		(end 386.82549 -247.845834)
		(width 0.18288)
		(layer "In2.Cu")
		(net "M_F_CPU0_SB_CA<6>")
	)
	(segment
		(start 420.032942 -248.169684)
		(end 419.491922 -248.169684)
		(width 0.18288)
		(layer "In2.Cu")
		(net "M_F_CPU0_SB_CA<6>")
	)
	(segment
		(start 415.930334 -247.856502)
		(end 415.150808 -247.856502)
		(width 0.18288)
		(layer "In2.Cu")
		(net "M_F_CPU0_SB_CA<6>")
	)
	(segment
		(start 400.96059 -248.11355)
		(end 400.96059 -248.339356)
		(width 0.18288)
		(layer "In2.Cu")
		(net "M_F_CPU0_SB_CA<6>")
	)
	(segment
		(start 405.397208 -247.847612)
		(end 404.712424 -248.532396)
		(width 0.18288)
		(layer "In2.Cu")
		(net "M_F_CPU0_SB_CA<6>")
	)
	(segment
		(start 407.372566 -248.193052)
		(end 406.244298 -248.193052)
		(width 0.18288)
		(layer "In2.Cu")
		(net "M_F_CPU0_SB_CA<6>")
	)
	(segment
		(start 404.712424 -248.532396)
		(end 401.857718 -248.532396)
		(width 0.18288)
		(layer "In2.Cu")
		(net "M_F_CPU0_SB_CA<6>")
	)
	(segment
		(start 407.71699 -247.848628)
		(end 407.372566 -248.193052)
		(width 0.18288)
		(layer "In2.Cu")
		(net "M_F_CPU0_SB_CA<6>")
	)
	(segment
		(start 410.310076 -247.583452)
		(end 409.725622 -248.167906)
		(width 0.18288)
		(layer "In2.Cu")
		(net "M_F_CPU0_SB_CA<6>")
	)
	(segment
		(start 400.256502 -248.339356)
		(end 400.256502 -248.11355)
		(width 0.18288)
		(layer "In2.Cu")
		(net "M_F_CPU0_SB_CA<6>")
	)
	(segment
		(start 400.063462 -247.92051)
		(end 399.745454 -247.92051)
		(width 0.18288)
		(layer "In2.Cu")
		(net "M_F_CPU0_SB_CA<6>")
	)
	(segment
		(start 385.69011 -246.099584)
		(end 385.69011 -246.09933)
		(width 0.088646)
		(layer "In2.Cu")
		(net "M_F_CPU0_SB_CA<6>")
	)
	(segment
		(start 399.552414 -248.11355)
		(end 399.552414 -248.339356)
		(width 0.18288)
		(layer "In2.Cu")
		(net "M_F_CPU0_SB_CA<6>")
	)
	(segment
		(start 397.61922 -247.224296)
		(end 389.294116 -247.224296)
		(width 0.18288)
		(layer "In2.Cu")
		(net "M_F_CPU0_SB_CA<6>")
	)
	(segment
		(start 383.262632 -245.226586)
		(end 383.262632 -245.226332)
		(width 0.088646)
		(layer "In2.Cu")
		(net "M_F_CPU0_SB_CA<6>")
	)
	(segment
		(start 401.471638 -247.92051)
		(end 401.15363 -247.92051)
		(width 0.18288)
		(layer "In2.Cu")
		(net "M_F_CPU0_SB_CA<6>")
	)
	(segment
		(start 413.37611 -247.885712)
		(end 412.836614 -247.885712)
		(width 0.18288)
		(layer "In2.Cu")
		(net "M_F_CPU0_SB_CA<6>")
	)
	(segment
		(start 420.736014 -247.466612)
		(end 420.032942 -248.169684)
		(width 0.18288)
		(layer "In2.Cu")
		(net "M_F_CPU0_SB_CA<6>")
	)
	(segment
		(start 418.953442 -247.631204)
		(end 417.842954 -247.631204)
		(width 0.18288)
		(layer "In2.Cu")
		(net "M_F_CPU0_SB_CA<6>")
	)
	(segment
		(start 389.294116 -247.224296)
		(end 388.672578 -247.845834)
		(width 0.18288)
		(layer "In2.Cu")
		(net "M_F_CPU0_SB_CA<6>")
	)
	(segment
		(start 412.001462 -248.19356)
		(end 411.391354 -247.583452)
		(width 0.18288)
		(layer "In2.Cu")
		(net "M_F_CPU0_SB_CA<6>")
	)
	(segment
		(start 383.450084 -245.560596)
		(end 383.450084 -245.55069)
		(width 0.088646)
		(layer "In2.Cu")
		(net "M_F_CPU0_SB_CA<6>")
	)
	(segment
		(start 409.725622 -248.167906)
		(end 408.59329 -248.167906)
		(width 0.18288)
		(layer "In2.Cu")
		(net "M_F_CPU0_SB_CA<6>")
	)
	(segment
		(start 385.799838 -246.364252)
		(end 385.799838 -246.209058)
		(width 0.088646)
		(layer "In2.Cu")
		(net "M_F_CPU0_SB_CA<6>")
	)
	(segment
		(start 401.664678 -248.339356)
		(end 401.664678 -248.11355)
		(width 0.18288)
		(layer "In2.Cu")
		(net "M_F_CPU0_SB_CA<6>")
	)
	(segment
		(start 400.76755 -248.532396)
		(end 400.449542 -248.532396)
		(width 0.18288)
		(layer "In2.Cu")
		(net "M_F_CPU0_SB_CA<6>")
	)
	(segment
		(start 413.703516 -248.213118)
		(end 413.37611 -247.885712)
		(width 0.18288)
		(layer "In2.Cu")
		(net "M_F_CPU0_SB_CA<6>")
	)
	(segment
		(start 417.842954 -247.631204)
		(end 417.313872 -248.160286)
		(width 0.18288)
		(layer "In2.Cu")
		(net "M_F_CPU0_SB_CA<6>")
	)
	(arc
		(start 382.888236 -245.226332)
		(mid 382.614007 -245.302257)
		(end 382.337564 -245.234968)
		(width 0.088646)
		(layer "In2.Cu")
		(net "M_F_CPU0_SB_CA<6>")
	)
	(arc
		(start 385.612132 -246.040148)
		(mid 385.424934 -245.990005)
		(end 385.237736 -246.040148)
		(width 0.088646)
		(layer "In2.Cu")
		(net "M_F_CPU0_SB_CA<6>")
	)
	(arc
		(start 384.672332 -246.040148)
		(mid 384.485134 -245.990005)
		(end 384.297936 -246.040148)
		(width 0.088646)
		(layer "In2.Cu")
		(net "M_F_CPU0_SB_CA<6>")
	)
	(arc
		(start 384.297936 -246.040148)
		(mid 384.015234 -246.115924)
		(end 383.732532 -246.040148)
		(width 0.088646)
		(layer "In2.Cu")
		(net "M_F_CPU0_SB_CA<6>")
	)
	(arc
		(start 383.732532 -246.040148)
		(mid 383.528197 -245.837543)
		(end 383.450084 -245.560596)
		(width 0.088646)
		(layer "In2.Cu")
		(net "M_F_CPU0_SB_CA<6>")
	)
	(arc
		(start 381.948436 -245.226332)
		(mid 381.665959 -245.301854)
		(end 381.38354 -245.226078)
		(width 0.088646)
		(layer "In2.Cu")
		(net "M_F_CPU0_SB_CA<6>")
	)
	(arc
		(start 383.262632 -245.226332)
		(mid 383.075434 -245.176189)
		(end 382.888236 -245.226332)
		(width 0.088646)
		(layer "In2.Cu")
		(net "M_F_CPU0_SB_CA<6>")
	)
	(arc
		(start 382.322832 -245.226332)
		(mid 382.135634 -245.176189)
		(end 381.948436 -245.226332)
		(width 0.088646)
		(layer "In2.Cu")
		(net "M_F_CPU0_SB_CA<6>")
	)
	(arc
		(start 385.237736 -246.040148)
		(mid 384.955034 -246.115924)
		(end 384.672332 -246.040148)
		(width 0.088646)
		(layer "In2.Cu")
		(net "M_F_CPU0_SB_CA<6>")
	)
	(arc
		(start 383.450084 -245.55069)
		(mid 383.399844 -245.363489)
		(end 383.262632 -245.226586)
		(width 0.088646)
		(layer "In2.Cu")
		(net "M_F_CPU0_SB_CA<6>")
	)
	(arc
		(start 385.69011 -246.09933)
		(mid 385.65306 -246.067184)
		(end 385.612132 -246.040148)
		(width 0.088646)
		(layer "In2.Cu")
		(net "M_F_CPU0_SB_CA<6>")
	)
	(segment
		(start 427.576742 -248.31675)
		(end 428.012352 -248.75236)
		(width 0.20066)
		(layer "F.Cu")
		(net "M_F_CPU0_SB_CA<5>")
	)
	(segment
		(start 383.075434 -246.086376)
		(end 383.075434 -245.55069)
		(width 0.20066)
		(layer "F.Cu")
		(net "M_F_CPU0_SB_CA<5>")
	)
	(segment
		(start 424.836082 -248.31675)
		(end 425.940982 -248.31675)
		(width 0.20066)
		(layer "F.Cu")
		(net "M_F_CPU0_SB_CA<5>")
	)
	(segment
		(start 428.367952 -248.75236)
		(end 428.37862 -248.741692)
		(width 0.1016)
		(layer "F.Cu")
		(net "M_F_CPU0_SB_CA<5>")
	)
	(segment
		(start 431.937668 -247.884188)
		(end 432.37023 -248.31675)
		(width 0.20066)
		(layer "F.Cu")
		(net "M_F_CPU0_SB_CA<5>")
	)
	(segment
		(start 432.37023 -248.31675)
		(end 433.484782 -248.31675)
		(width 0.20066)
		(layer "F.Cu")
		(net "M_F_CPU0_SB_CA<5>")
	)
	(segment
		(start 431.534062 -247.884188)
		(end 431.937668 -247.884188)
		(width 0.20066)
		(layer "F.Cu")
		(net "M_F_CPU0_SB_CA<5>")
	)
	(segment
		(start 430.38776 -248.741692)
		(end 430.395126 -248.749058)
		(width 0.1016)
		(layer "F.Cu")
		(net "M_F_CPU0_SB_CA<5>")
	)
	(segment
		(start 383.07518 -246.08663)
		(end 383.075434 -246.086376)
		(width 0.20066)
		(layer "F.Cu")
		(net "M_F_CPU0_SB_CA<5>")
	)
	(segment
		(start 428.012352 -248.75236)
		(end 428.363126 -248.75236)
		(width 0.20066)
		(layer "F.Cu")
		(net "M_F_CPU0_SB_CA<5>")
	)
	(segment
		(start 428.363126 -248.75236)
		(end 428.367952 -248.75236)
		(width 0.101854)
		(layer "F.Cu")
		(net "M_F_CPU0_SB_CA<5>")
	)
	(segment
		(start 430.395126 -248.749058)
		(end 430.669192 -248.749058)
		(width 0.20066)
		(layer "F.Cu")
		(net "M_F_CPU0_SB_CA<5>")
	)
	(segment
		(start 428.37862 -248.741692)
		(end 430.38776 -248.741692)
		(width 0.1016)
		(layer "F.Cu")
		(net "M_F_CPU0_SB_CA<5>")
	)
	(segment
		(start 425.940982 -248.31675)
		(end 427.576742 -248.31675)
		(width 0.20066)
		(layer "F.Cu")
		(net "M_F_CPU0_SB_CA<5>")
	)
	(segment
		(start 430.669192 -248.749058)
		(end 431.534062 -247.884188)
		(width 0.20066)
		(layer "F.Cu")
		(net "M_F_CPU0_SB_CA<5>")
	)
	(segment
		(start 424.208194 -248.47677)
		(end 424.208194 -249.37085)
		(width 0.18288)
		(layer "In2.Cu")
		(net "M_F_CPU0_SB_CA<5>")
	)
	(segment
		(start 386.470398 -248.225056)
		(end 385.85013 -247.604788)
		(width 0.18288)
		(layer "In2.Cu")
		(net "M_F_CPU0_SB_CA<5>")
	)
	(segment
		(start 408.731466 -248.851928)
		(end 407.671778 -248.851928)
		(width 0.18288)
		(layer "In2.Cu")
		(net "M_F_CPU0_SB_CA<5>")
	)
	(segment
		(start 407.551636 -248.731786)
		(end 405.843486 -248.731786)
		(width 0.18288)
		(layer "In2.Cu")
		(net "M_F_CPU0_SB_CA<5>")
	)
	(segment
		(start 422.506394 -248.015506)
		(end 422.506394 -248.417334)
		(width 0.18288)
		(layer "In2.Cu")
		(net "M_F_CPU0_SB_CA<5>")
	)
	(segment
		(start 385.85013 -247.604788)
		(end 385.520184 -247.274842)
		(width 0.088646)
		(layer "In2.Cu")
		(net "M_F_CPU0_SB_CA<5>")
	)
	(segment
		(start 422.82872 -247.69318)
		(end 422.506394 -248.015506)
		(width 0.18288)
		(layer "In2.Cu")
		(net "M_F_CPU0_SB_CA<5>")
	)
	(segment
		(start 424.208194 -249.37085)
		(end 424.015154 -249.56389)
		(width 0.18288)
		(layer "In2.Cu")
		(net "M_F_CPU0_SB_CA<5>")
	)
	(segment
		(start 416.192208 -248.70537)
		(end 416.028378 -248.8692)
		(width 0.18288)
		(layer "In2.Cu")
		(net "M_F_CPU0_SB_CA<5>")
	)
	(segment
		(start 422.180512 -248.743216)
		(end 419.817042 -248.743216)
		(width 0.18288)
		(layer "In2.Cu")
		(net "M_F_CPU0_SB_CA<5>")
	)
	(segment
		(start 424.015154 -249.56389)
		(end 423.61612 -249.56389)
		(width 0.18288)
		(layer "In2.Cu")
		(net "M_F_CPU0_SB_CA<5>")
	)
	(segment
		(start 412.518098 -248.85269)
		(end 412.401004 -248.735596)
		(width 0.18288)
		(layer "In2.Cu")
		(net "M_F_CPU0_SB_CA<5>")
	)
	(segment
		(start 383.170684 -246.330978)
		(end 383.075434 -245.55069)
		(width 0.088646)
		(layer "In2.Cu")
		(net "M_F_CPU0_SB_CA<5>")
	)
	(segment
		(start 398.688052 -249.051064)
		(end 397.206724 -247.569736)
		(width 0.18288)
		(layer "In2.Cu")
		(net "M_F_CPU0_SB_CA<5>")
	)
	(segment
		(start 419.817042 -248.743216)
		(end 419.334442 -248.70537)
		(width 0.18288)
		(layer "In2.Cu")
		(net "M_F_CPU0_SB_CA<5>")
	)
	(segment
		(start 405.843486 -248.731786)
		(end 405.524208 -249.051064)
		(width 0.18288)
		(layer "In2.Cu")
		(net "M_F_CPU0_SB_CA<5>")
	)
	(segment
		(start 424.836082 -248.31675)
		(end 424.368214 -248.31675)
		(width 0.18288)
		(layer "In2.Cu")
		(net "M_F_CPU0_SB_CA<5>")
	)
	(segment
		(start 415.23031 -248.8692)
		(end 415.096706 -248.735596)
		(width 0.18288)
		(layer "In2.Cu")
		(net "M_F_CPU0_SB_CA<5>")
	)
	(segment
		(start 389.888476 -247.569736)
		(end 389.233156 -248.225056)
		(width 0.18288)
		(layer "In2.Cu")
		(net "M_F_CPU0_SB_CA<5>")
	)
	(segment
		(start 423.29608 -247.69318)
		(end 422.82872 -247.69318)
		(width 0.18288)
		(layer "In2.Cu")
		(net "M_F_CPU0_SB_CA<5>")
	)
	(segment
		(start 424.368214 -248.31675)
		(end 424.208194 -248.47677)
		(width 0.18288)
		(layer "In2.Cu")
		(net "M_F_CPU0_SB_CA<5>")
	)
	(segment
		(start 423.4561 -249.40387)
		(end 423.4561 -247.8532)
		(width 0.18288)
		(layer "In2.Cu")
		(net "M_F_CPU0_SB_CA<5>")
	)
	(segment
		(start 385.520184 -246.94388)
		(end 385.35483 -246.778526)
		(width 0.088646)
		(layer "In2.Cu")
		(net "M_F_CPU0_SB_CA<5>")
	)
	(segment
		(start 407.671778 -248.851928)
		(end 407.551636 -248.731786)
		(width 0.18288)
		(layer "In2.Cu")
		(net "M_F_CPU0_SB_CA<5>")
	)
	(segment
		(start 397.206724 -247.569736)
		(end 389.888476 -247.569736)
		(width 0.18288)
		(layer "In2.Cu")
		(net "M_F_CPU0_SB_CA<5>")
	)
	(segment
		(start 389.233156 -248.225056)
		(end 386.470398 -248.225056)
		(width 0.18288)
		(layer "In2.Cu")
		(net "M_F_CPU0_SB_CA<5>")
	)
	(segment
		(start 405.524208 -249.051064)
		(end 398.688052 -249.051064)
		(width 0.18288)
		(layer "In2.Cu")
		(net "M_F_CPU0_SB_CA<5>")
	)
	(segment
		(start 415.096706 -248.735596)
		(end 413.42056 -248.735596)
		(width 0.18288)
		(layer "In2.Cu")
		(net "M_F_CPU0_SB_CA<5>")
	)
	(segment
		(start 383.358136 -246.688864)
		(end 383.357882 -246.68861)
		(width 0.088646)
		(layer "In2.Cu")
		(net "M_F_CPU0_SB_CA<5>")
	)
	(segment
		(start 423.4561 -247.8532)
		(end 423.29608 -247.69318)
		(width 0.18288)
		(layer "In2.Cu")
		(net "M_F_CPU0_SB_CA<5>")
	)
	(segment
		(start 416.028378 -248.8692)
		(end 415.23031 -248.8692)
		(width 0.18288)
		(layer "In2.Cu")
		(net "M_F_CPU0_SB_CA<5>")
	)
	(segment
		(start 419.334442 -248.70537)
		(end 416.192208 -248.70537)
		(width 0.18288)
		(layer "In2.Cu")
		(net "M_F_CPU0_SB_CA<5>")
	)
	(segment
		(start 413.303466 -248.85269)
		(end 412.518098 -248.85269)
		(width 0.18288)
		(layer "In2.Cu")
		(net "M_F_CPU0_SB_CA<5>")
	)
	(segment
		(start 422.506394 -248.417334)
		(end 422.180512 -248.743216)
		(width 0.18288)
		(layer "In2.Cu")
		(net "M_F_CPU0_SB_CA<5>")
	)
	(segment
		(start 383.170684 -246.364506)
		(end 383.170684 -246.330978)
		(width 0.088646)
		(layer "In2.Cu")
		(net "M_F_CPU0_SB_CA<5>")
	)
	(segment
		(start 423.61612 -249.56389)
		(end 423.4561 -249.40387)
		(width 0.18288)
		(layer "In2.Cu")
		(net "M_F_CPU0_SB_CA<5>")
	)
	(segment
		(start 412.401004 -248.735596)
		(end 408.847798 -248.735596)
		(width 0.18288)
		(layer "In2.Cu")
		(net "M_F_CPU0_SB_CA<5>")
	)
	(segment
		(start 385.520184 -247.274842)
		(end 385.520184 -246.94388)
		(width 0.088646)
		(layer "In2.Cu")
		(net "M_F_CPU0_SB_CA<5>")
	)
	(segment
		(start 408.847798 -248.735596)
		(end 408.731466 -248.851928)
		(width 0.18288)
		(layer "In2.Cu")
		(net "M_F_CPU0_SB_CA<5>")
	)
	(segment
		(start 413.42056 -248.735596)
		(end 413.303466 -248.85269)
		(width 0.18288)
		(layer "In2.Cu")
		(net "M_F_CPU0_SB_CA<5>")
	)
	(arc
		(start 383.357882 -246.68861)
		(mid 383.220837 -246.55165)
		(end 383.170684 -246.364506)
		(width 0.088646)
		(layer "In2.Cu")
		(net "M_F_CPU0_SB_CA<5>")
	)
	(arc
		(start 384.672332 -246.688864)
		(mid 384.485134 -246.739007)
		(end 384.297936 -246.688864)
		(width 0.088646)
		(layer "In2.Cu")
		(net "M_F_CPU0_SB_CA<5>")
	)
	(arc
		(start 384.297936 -246.688864)
		(mid 384.015234 -246.613088)
		(end 383.732532 -246.688864)
		(width 0.088646)
		(layer "In2.Cu")
		(net "M_F_CPU0_SB_CA<5>")
	)
	(arc
		(start 383.732532 -246.688864)
		(mid 383.545334 -246.739007)
		(end 383.358136 -246.688864)
		(width 0.088646)
		(layer "In2.Cu")
		(net "M_F_CPU0_SB_CA<5>")
	)
	(arc
		(start 385.237736 -246.688864)
		(mid 384.955034 -246.613088)
		(end 384.672332 -246.688864)
		(width 0.088646)
		(layer "In2.Cu")
		(net "M_F_CPU0_SB_CA<5>")
	)
	(arc
		(start 385.35483 -246.778526)
		(mid 385.299225 -246.729852)
		(end 385.237736 -246.688864)
		(width 0.088646)
		(layer "In2.Cu")
		(net "M_F_CPU0_SB_CA<5>")
	)
	(segment
		(start 424.75277 -249.591576)
		(end 424.766486 -249.591576)
		(width 0.101854)
		(layer "F.Cu")
		(net "M_F_CPU0_SB_CA<4>")
	)
	(segment
		(start 426.938948 -249.591576)
		(end 426.951394 -249.604022)
		(width 0.1016)
		(layer "F.Cu")
		(net "M_F_CPU0_SB_CA<4>")
	)
	(segment
		(start 427.805088 -249.16638)
		(end 429.38446 -249.16638)
		(width 0.20066)
		(layer "F.Cu")
		(net "M_F_CPU0_SB_CA<4>")
	)
	(segment
		(start 421.840914 -249.166634)
		(end 422.906444 -249.166634)
		(width 0.20066)
		(layer "F.Cu")
		(net "M_F_CPU0_SB_CA<4>")
	)
	(segment
		(start 422.906444 -249.166634)
		(end 423.400728 -248.67235)
		(width 0.20066)
		(layer "F.Cu")
		(net "M_F_CPU0_SB_CA<4>")
	)
	(segment
		(start 424.645328 -249.591576)
		(end 424.75277 -249.591576)
		(width 0.20066)
		(layer "F.Cu")
		(net "M_F_CPU0_SB_CA<4>")
	)
	(segment
		(start 423.400728 -248.67235)
		(end 423.726102 -248.67235)
		(width 0.20066)
		(layer "F.Cu")
		(net "M_F_CPU0_SB_CA<4>")
	)
	(segment
		(start 424.766486 -249.591576)
		(end 426.938948 -249.591576)
		(width 0.1016)
		(layer "F.Cu")
		(net "M_F_CPU0_SB_CA<4>")
	)
	(segment
		(start 423.726102 -248.67235)
		(end 424.645328 -249.591576)
		(width 0.20066)
		(layer "F.Cu")
		(net "M_F_CPU0_SB_CA<4>")
	)
	(segment
		(start 426.951394 -249.604022)
		(end 427.367446 -249.604022)
		(width 0.20066)
		(layer "F.Cu")
		(net "M_F_CPU0_SB_CA<4>")
	)
	(segment
		(start 427.367446 -249.604022)
		(end 427.805088 -249.16638)
		(width 0.20066)
		(layer "F.Cu")
		(net "M_F_CPU0_SB_CA<4>")
	)
	(segment
		(start 429.38446 -249.16638)
		(end 429.384714 -249.166634)
		(width 0.20066)
		(layer "F.Cu")
		(net "M_F_CPU0_SB_CA<4>")
	)
	(segment
		(start 420.736014 -249.166634)
		(end 421.840914 -249.166634)
		(width 0.20066)
		(layer "F.Cu")
		(net "M_F_CPU0_SB_CA<4>")
	)
	(segment
		(start 381.19558 -246.08663)
		(end 381.195834 -246.086376)
		(width 0.20066)
		(layer "F.Cu")
		(net "M_F_CPU0_SB_CA<4>")
	)
	(segment
		(start 381.195834 -246.086376)
		(end 381.195834 -245.55069)
		(width 0.20066)
		(layer "F.Cu")
		(net "M_F_CPU0_SB_CA<4>")
	)
	(segment
		(start 408.612594 -249.864626)
		(end 408.612594 -249.531632)
		(width 0.18288)
		(layer "In2.Cu")
		(net "M_F_CPU0_SB_CA<4>")
	)
	(segment
		(start 385.329684 -247.178322)
		(end 385.329938 -247.178068)
		(width 0.088646)
		(layer "In2.Cu")
		(net "M_F_CPU0_SB_CA<4>")
	)
	(segment
		(start 403.215856 -249.567192)
		(end 403.022816 -249.760232)
		(width 0.18288)
		(layer "In2.Cu")
		(net "M_F_CPU0_SB_CA<4>")
	)
	(segment
		(start 385.329684 -247.58269)
		(end 385.329684 -247.178322)
		(width 0.088646)
		(layer "In2.Cu")
		(net "M_F_CPU0_SB_CA<4>")
	)
	(segment
		(start 415.90468 -249.565414)
		(end 415.724594 -249.385328)
		(width 0.18288)
		(layer "In2.Cu")
		(net "M_F_CPU0_SB_CA<4>")
	)
	(segment
		(start 382.792986 -246.040402)
		(end 382.792732 -246.040148)
		(width 0.088646)
		(layer "In2.Cu")
		(net "M_F_CPU0_SB_CA<4>")
	)
	(segment
		(start 389.283956 -248.822464)
		(end 388.354824 -249.207274)
		(width 0.18288)
		(layer "In2.Cu")
		(net "M_F_CPU0_SB_CA<4>")
	)
	(segment
		(start 414.817306 -249.607832)
		(end 414.510474 -249.914664)
		(width 0.18288)
		(layer "In2.Cu")
		(net "M_F_CPU0_SB_CA<4>")
	)
	(segment
		(start 411.254194 -249.251216)
		(end 410.377386 -249.251216)
		(width 0.18288)
		(layer "In2.Cu")
		(net "M_F_CPU0_SB_CA<4>")
	)
	(segment
		(start 412.453836 -249.873262)
		(end 411.87624 -249.873262)
		(width 0.18288)
		(layer "In2.Cu")
		(net "M_F_CPU0_SB_CA<4>")
	)
	(segment
		(start 404.430992 -249.760232)
		(end 404.430992 -250.168156)
		(width 0.18288)
		(layer "In2.Cu")
		(net "M_F_CPU0_SB_CA<4>")
	)
	(segment
		(start 403.726904 -250.168156)
		(end 403.726904 -249.760232)
		(width 0.18288)
		(layer "In2.Cu")
		(net "M_F_CPU0_SB_CA<4>")
	)
	(segment
		(start 385.329938 -247.022874)
		(end 385.22021 -246.9134)
		(width 0.088646)
		(layer "In2.Cu")
		(net "M_F_CPU0_SB_CA<4>")
	)
	(segment
		(start 407.838402 -249.371612)
		(end 407.238962 -249.971052)
		(width 0.18288)
		(layer "In2.Cu")
		(net "M_F_CPU0_SB_CA<4>")
	)
	(segment
		(start 405.92756 -249.567192)
		(end 404.624032 -249.567192)
		(width 0.18288)
		(layer "In2.Cu")
		(net "M_F_CPU0_SB_CA<4>")
	)
	(segment
		(start 403.726904 -249.760232)
		(end 403.533864 -249.567192)
		(width 0.18288)
		(layer "In2.Cu")
		(net "M_F_CPU0_SB_CA<4>")
	)
	(segment
		(start 398.568164 -249.682762)
		(end 396.801086 -247.915684)
		(width 0.18288)
		(layer "In2.Cu")
		(net "M_F_CPU0_SB_CA<4>")
	)
	(segment
		(start 406.33142 -249.971052)
		(end 405.92756 -249.567192)
		(width 0.18288)
		(layer "In2.Cu")
		(net "M_F_CPU0_SB_CA<4>")
	)
	(segment
		(start 402.318728 -250.168156)
		(end 402.318728 -249.91568)
		(width 0.18288)
		(layer "In2.Cu")
		(net "M_F_CPU0_SB_CA<4>")
	)
	(segment
		(start 385.329938 -247.178068)
		(end 385.329938 -247.022874)
		(width 0.088646)
		(layer "In2.Cu")
		(net "M_F_CPU0_SB_CA<4>")
	)
	(segment
		(start 416.0647 -249.991626)
		(end 415.90468 -249.831606)
		(width 0.18288)
		(layer "In2.Cu")
		(net "M_F_CPU0_SB_CA<4>")
	)
	(segment
		(start 404.237952 -250.361196)
		(end 403.919944 -250.361196)
		(width 0.18288)
		(layer "In2.Cu")
		(net "M_F_CPU0_SB_CA<4>")
	)
	(segment
		(start 410.377386 -249.251216)
		(end 409.824682 -249.80392)
		(width 0.18288)
		(layer "In2.Cu")
		(net "M_F_CPU0_SB_CA<4>")
	)
	(segment
		(start 416.547554 -249.991626)
		(end 416.0647 -249.991626)
		(width 0.18288)
		(layer "In2.Cu")
		(net "M_F_CPU0_SB_CA<4>")
	)
	(segment
		(start 417.885118 -249.244866)
		(end 417.264342 -249.865642)
		(width 0.18288)
		(layer "In2.Cu")
		(net "M_F_CPU0_SB_CA<4>")
	)
	(segment
		(start 385.600702 -247.853708)
		(end 385.329684 -247.58269)
		(width 0.088646)
		(layer "In2.Cu")
		(net "M_F_CPU0_SB_CA<4>")
	)
	(segment
		(start 403.533864 -249.567192)
		(end 403.215856 -249.567192)
		(width 0.18288)
		(layer "In2.Cu")
		(net "M_F_CPU0_SB_CA<4>")
	)
	(segment
		(start 416.673538 -249.865642)
		(end 416.547554 -249.991626)
		(width 0.18288)
		(layer "In2.Cu")
		(net "M_F_CPU0_SB_CA<4>")
	)
	(segment
		(start 402.08581 -249.682762)
		(end 398.568164 -249.682762)
		(width 0.18288)
		(layer "In2.Cu")
		(net "M_F_CPU0_SB_CA<4>")
	)
	(segment
		(start 402.318728 -249.91568)
		(end 402.08581 -249.682762)
		(width 0.18288)
		(layer "In2.Cu")
		(net "M_F_CPU0_SB_CA<4>")
	)
	(segment
		(start 418.914834 -249.244866)
		(end 417.885118 -249.244866)
		(width 0.18288)
		(layer "In2.Cu")
		(net "M_F_CPU0_SB_CA<4>")
	)
	(segment
		(start 411.87624 -249.873262)
		(end 411.254194 -249.251216)
		(width 0.18288)
		(layer "In2.Cu")
		(net "M_F_CPU0_SB_CA<4>")
	)
	(segment
		(start 407.238962 -249.971052)
		(end 406.33142 -249.971052)
		(width 0.18288)
		(layer "In2.Cu")
		(net "M_F_CPU0_SB_CA<4>")
	)
	(segment
		(start 385.22021 -246.9134)
		(end 385.22021 -246.913146)
		(width 0.088646)
		(layer "In2.Cu")
		(net "M_F_CPU0_SB_CA<4>")
	)
	(segment
		(start 415.125408 -249.607832)
		(end 414.817306 -249.607832)
		(width 0.18288)
		(layer "In2.Cu")
		(net "M_F_CPU0_SB_CA<4>")
	)
	(segment
		(start 415.724594 -249.385328)
		(end 415.347912 -249.385328)
		(width 0.18288)
		(layer "In2.Cu")
		(net "M_F_CPU0_SB_CA<4>")
	)
	(segment
		(start 388.354824 -249.207274)
		(end 386.954268 -249.207274)
		(width 0.18288)
		(layer "In2.Cu")
		(net "M_F_CPU0_SB_CA<4>")
	)
	(segment
		(start 404.624032 -249.567192)
		(end 404.430992 -249.760232)
		(width 0.18288)
		(layer "In2.Cu")
		(net "M_F_CPU0_SB_CA<4>")
	)
	(segment
		(start 404.430992 -250.168156)
		(end 404.237952 -250.361196)
		(width 0.18288)
		(layer "In2.Cu")
		(net "M_F_CPU0_SB_CA<4>")
	)
	(segment
		(start 396.801086 -247.915684)
		(end 390.190736 -247.915684)
		(width 0.18288)
		(layer "In2.Cu")
		(net "M_F_CPU0_SB_CA<4>")
	)
	(segment
		(start 415.90468 -249.831606)
		(end 415.90468 -249.565414)
		(width 0.18288)
		(layer "In2.Cu")
		(net "M_F_CPU0_SB_CA<4>")
	)
	(segment
		(start 382.980184 -246.374412)
		(end 382.980184 -246.364506)
		(width 0.088646)
		(layer "In2.Cu")
		(net "M_F_CPU0_SB_CA<4>")
	)
	(segment
		(start 408.764994 -250.017026)
		(end 408.612594 -249.864626)
		(width 0.18288)
		(layer "In2.Cu")
		(net "M_F_CPU0_SB_CA<4>")
	)
	(segment
		(start 420.736014 -249.166634)
		(end 420.14902 -249.753628)
		(width 0.18288)
		(layer "In2.Cu")
		(net "M_F_CPU0_SB_CA<4>")
	)
	(segment
		(start 417.264342 -249.865642)
		(end 416.673538 -249.865642)
		(width 0.18288)
		(layer "In2.Cu")
		(net "M_F_CPU0_SB_CA<4>")
	)
	(segment
		(start 390.190736 -247.915684)
		(end 389.283956 -248.822464)
		(width 0.18288)
		(layer "In2.Cu")
		(net "M_F_CPU0_SB_CA<4>")
	)
	(segment
		(start 408.452574 -249.371612)
		(end 407.838402 -249.371612)
		(width 0.18288)
		(layer "In2.Cu")
		(net "M_F_CPU0_SB_CA<4>")
	)
	(segment
		(start 403.022816 -249.760232)
		(end 403.022816 -250.168156)
		(width 0.18288)
		(layer "In2.Cu")
		(net "M_F_CPU0_SB_CA<4>")
	)
	(segment
		(start 381.852932 -246.040148)
		(end 381.824738 -246.023892)
		(width 0.088646)
		(layer "In2.Cu")
		(net "M_F_CPU0_SB_CA<4>")
	)
	(segment
		(start 415.347912 -249.385328)
		(end 415.125408 -249.607832)
		(width 0.18288)
		(layer "In2.Cu")
		(net "M_F_CPU0_SB_CA<4>")
	)
	(segment
		(start 409.368752 -249.80392)
		(end 409.155646 -250.017026)
		(width 0.18288)
		(layer "In2.Cu")
		(net "M_F_CPU0_SB_CA<4>")
	)
	(segment
		(start 386.954268 -249.207274)
		(end 385.600702 -247.853708)
		(width 0.18288)
		(layer "In2.Cu")
		(net "M_F_CPU0_SB_CA<4>")
	)
	(segment
		(start 403.919944 -250.361196)
		(end 403.726904 -250.168156)
		(width 0.18288)
		(layer "In2.Cu")
		(net "M_F_CPU0_SB_CA<4>")
	)
	(segment
		(start 408.612594 -249.531632)
		(end 408.452574 -249.371612)
		(width 0.18288)
		(layer "In2.Cu")
		(net "M_F_CPU0_SB_CA<4>")
	)
	(segment
		(start 420.14902 -249.753628)
		(end 419.423596 -249.753628)
		(width 0.18288)
		(layer "In2.Cu")
		(net "M_F_CPU0_SB_CA<4>")
	)
	(segment
		(start 413.286448 -249.371866)
		(end 412.955232 -249.371866)
		(width 0.18288)
		(layer "In2.Cu")
		(net "M_F_CPU0_SB_CA<4>")
	)
	(segment
		(start 412.955232 -249.371866)
		(end 412.453836 -249.873262)
		(width 0.18288)
		(layer "In2.Cu")
		(net "M_F_CPU0_SB_CA<4>")
	)
	(segment
		(start 403.022816 -250.168156)
		(end 402.829776 -250.361196)
		(width 0.18288)
		(layer "In2.Cu")
		(net "M_F_CPU0_SB_CA<4>")
	)
	(segment
		(start 414.510474 -249.914664)
		(end 413.829246 -249.914664)
		(width 0.18288)
		(layer "In2.Cu")
		(net "M_F_CPU0_SB_CA<4>")
	)
	(segment
		(start 402.511768 -250.361196)
		(end 402.318728 -250.168156)
		(width 0.18288)
		(layer "In2.Cu")
		(net "M_F_CPU0_SB_CA<4>")
	)
	(segment
		(start 409.824682 -249.80392)
		(end 409.368752 -249.80392)
		(width 0.18288)
		(layer "In2.Cu")
		(net "M_F_CPU0_SB_CA<4>")
	)
	(segment
		(start 419.423596 -249.753628)
		(end 418.914834 -249.244866)
		(width 0.18288)
		(layer "In2.Cu")
		(net "M_F_CPU0_SB_CA<4>")
	)
	(segment
		(start 413.829246 -249.914664)
		(end 413.286448 -249.371866)
		(width 0.18288)
		(layer "In2.Cu")
		(net "M_F_CPU0_SB_CA<4>")
	)
	(segment
		(start 381.824738 -246.023892)
		(end 381.195834 -245.55069)
		(width 0.088646)
		(layer "In2.Cu")
		(net "M_F_CPU0_SB_CA<4>")
	)
	(segment
		(start 409.155646 -250.017026)
		(end 408.764994 -250.017026)
		(width 0.18288)
		(layer "In2.Cu")
		(net "M_F_CPU0_SB_CA<4>")
	)
	(segment
		(start 402.829776 -250.361196)
		(end 402.511768 -250.361196)
		(width 0.18288)
		(layer "In2.Cu")
		(net "M_F_CPU0_SB_CA<4>")
	)
	(arc
		(start 382.792732 -246.040148)
		(mid 382.605534 -245.990005)
		(end 382.418336 -246.040148)
		(width 0.088646)
		(layer "In2.Cu")
		(net "M_F_CPU0_SB_CA<4>")
	)
	(arc
		(start 382.980184 -246.364506)
		(mid 382.93002 -246.177368)
		(end 382.792986 -246.040402)
		(width 0.088646)
		(layer "In2.Cu")
		(net "M_F_CPU0_SB_CA<4>")
	)
	(arc
		(start 385.142232 -246.853964)
		(mid 384.955034 -246.803821)
		(end 384.767836 -246.853964)
		(width 0.088646)
		(layer "In2.Cu")
		(net "M_F_CPU0_SB_CA<4>")
	)
	(arc
		(start 383.828036 -246.853964)
		(mid 383.545334 -246.92974)
		(end 383.262632 -246.853964)
		(width 0.088646)
		(layer "In2.Cu")
		(net "M_F_CPU0_SB_CA<4>")
	)
	(arc
		(start 383.262632 -246.853964)
		(mid 383.058297 -246.651359)
		(end 382.980184 -246.374412)
		(width 0.088646)
		(layer "In2.Cu")
		(net "M_F_CPU0_SB_CA<4>")
	)
	(arc
		(start 384.202432 -246.853964)
		(mid 384.015234 -246.803821)
		(end 383.828036 -246.853964)
		(width 0.088646)
		(layer "In2.Cu")
		(net "M_F_CPU0_SB_CA<4>")
	)
	(arc
		(start 385.22021 -246.913146)
		(mid 385.18316 -246.881)
		(end 385.142232 -246.853964)
		(width 0.088646)
		(layer "In2.Cu")
		(net "M_F_CPU0_SB_CA<4>")
	)
	(arc
		(start 384.767836 -246.853964)
		(mid 384.485134 -246.92974)
		(end 384.202432 -246.853964)
		(width 0.088646)
		(layer "In2.Cu")
		(net "M_F_CPU0_SB_CA<4>")
	)
	(arc
		(start 382.418336 -246.040148)
		(mid 382.135634 -246.11589)
		(end 381.852932 -246.040148)
		(width 0.088646)
		(layer "In2.Cu")
		(net "M_F_CPU0_SB_CA<4>")
	)
	(segment
		(start 424.836082 -250.016772)
		(end 425.940982 -250.016772)
		(width 0.20066)
		(layer "F.Cu")
		(net "M_F_CPU0_SB_CA<3>")
	)
	(segment
		(start 430.38776 -250.441714)
		(end 430.395126 -250.44908)
		(width 0.1016)
		(layer "F.Cu")
		(net "M_F_CPU0_SB_CA<3>")
	)
	(segment
		(start 427.576742 -250.016772)
		(end 428.012352 -250.452382)
		(width 0.20066)
		(layer "F.Cu")
		(net "M_F_CPU0_SB_CA<3>")
	)
	(segment
		(start 428.367952 -250.452382)
		(end 428.37862 -250.441714)
		(width 0.1016)
		(layer "F.Cu")
		(net "M_F_CPU0_SB_CA<3>")
	)
	(segment
		(start 428.012352 -250.452382)
		(end 428.363126 -250.452382)
		(width 0.20066)
		(layer "F.Cu")
		(net "M_F_CPU0_SB_CA<3>")
	)
	(segment
		(start 431.534062 -249.58421)
		(end 431.937668 -249.58421)
		(width 0.20066)
		(layer "F.Cu")
		(net "M_F_CPU0_SB_CA<3>")
	)
	(segment
		(start 430.395126 -250.44908)
		(end 430.669192 -250.44908)
		(width 0.20066)
		(layer "F.Cu")
		(net "M_F_CPU0_SB_CA<3>")
	)
	(segment
		(start 432.37023 -250.016772)
		(end 433.484782 -250.016772)
		(width 0.20066)
		(layer "F.Cu")
		(net "M_F_CPU0_SB_CA<3>")
	)
	(segment
		(start 425.940982 -250.016772)
		(end 427.576742 -250.016772)
		(width 0.20066)
		(layer "F.Cu")
		(net "M_F_CPU0_SB_CA<3>")
	)
	(segment
		(start 428.37862 -250.441714)
		(end 430.38776 -250.441714)
		(width 0.1016)
		(layer "F.Cu")
		(net "M_F_CPU0_SB_CA<3>")
	)
	(segment
		(start 431.937668 -249.58421)
		(end 432.37023 -250.016772)
		(width 0.20066)
		(layer "F.Cu")
		(net "M_F_CPU0_SB_CA<3>")
	)
	(segment
		(start 430.669192 -250.44908)
		(end 431.534062 -249.58421)
		(width 0.20066)
		(layer "F.Cu")
		(net "M_F_CPU0_SB_CA<3>")
	)
	(segment
		(start 428.363126 -250.452382)
		(end 428.367952 -250.452382)
		(width 0.101854)
		(layer "F.Cu")
		(net "M_F_CPU0_SB_CA<3>")
	)
	(segment
		(start 382.605534 -246.900446)
		(end 382.605534 -246.364506)
		(width 0.20066)
		(layer "F.Cu")
		(net "M_F_CPU0_SB_CA<3>")
	)
	(segment
		(start 382.242314 -246.450358)
		(end 382.328166 -246.364506)
		(width 0.088646)
		(layer "In2.Cu")
		(net "M_F_CPU0_SB_CA<3>")
	)
	(segment
		(start 420.242238 -250.44146)
		(end 420.0652 -250.264422)
		(width 0.18288)
		(layer "In2.Cu")
		(net "M_F_CPU0_SB_CA<3>")
	)
	(segment
		(start 401.458684 -250.226322)
		(end 398.386808 -250.226322)
		(width 0.18288)
		(layer "In2.Cu")
		(net "M_F_CPU0_SB_CA<3>")
	)
	(segment
		(start 382.328166 -246.364506)
		(end 382.605534 -246.364506)
		(width 0.088646)
		(layer "In2.Cu")
		(net "M_F_CPU0_SB_CA<3>")
	)
	(segment
		(start 382.700784 -247.178322)
		(end 382.700784 -247.168416)
		(width 0.088646)
		(layer "In2.Cu")
		(net "M_F_CPU0_SB_CA<3>")
	)
	(segment
		(start 418.892736 -250.754388)
		(end 417.909756 -250.754388)
		(width 0.18288)
		(layer "In2.Cu")
		(net "M_F_CPU0_SB_CA<3>")
	)
	(segment
		(start 424.836082 -250.016772)
		(end 424.396662 -250.456192)
		(width 0.18288)
		(layer "In2.Cu")
		(net "M_F_CPU0_SB_CA<3>")
	)
	(segment
		(start 398.386808 -250.226322)
		(end 396.426436 -248.26595)
		(width 0.18288)
		(layer "In2.Cu")
		(net "M_F_CPU0_SB_CA<3>")
	)
	(segment
		(start 409.501086 -250.418092)
		(end 409.260548 -250.65863)
		(width 0.18288)
		(layer "In2.Cu")
		(net "M_F_CPU0_SB_CA<3>")
	)
	(segment
		(start 386.94995 -249.701558)
		(end 385.351528 -248.103136)
		(width 0.18288)
		(layer "In2.Cu")
		(net "M_F_CPU0_SB_CA<3>")
	)
	(segment
		(start 416.592004 -250.928124)
		(end 416.095688 -250.928124)
		(width 0.18288)
		(layer "In2.Cu")
		(net "M_F_CPU0_SB_CA<3>")
	)
	(segment
		(start 382.418336 -246.688864)
		(end 382.418082 -246.68861)
		(width 0.088646)
		(layer "In2.Cu")
		(net "M_F_CPU0_SB_CA<3>")
	)
	(segment
		(start 382.888236 -247.50268)
		(end 382.879346 -247.4976)
		(width 0.088646)
		(layer "In2.Cu")
		(net "M_F_CPU0_SB_CA<3>")
	)
	(segment
		(start 422.18102 -249.73407)
		(end 421.802306 -249.73407)
		(width 0.18288)
		(layer "In2.Cu")
		(net "M_F_CPU0_SB_CA<3>")
	)
	(segment
		(start 416.095688 -250.928124)
		(end 415.616136 -250.448572)
		(width 0.18288)
		(layer "In2.Cu")
		(net "M_F_CPU0_SB_CA<3>")
	)
	(segment
		(start 384.31851 -247.553226)
		(end 384.015234 -247.553226)
		(width 0.088646)
		(layer "In2.Cu")
		(net "M_F_CPU0_SB_CA<3>")
	)
	(segment
		(start 417.124134 -250.395994)
		(end 416.592004 -250.928124)
		(width 0.18288)
		(layer "In2.Cu")
		(net "M_F_CPU0_SB_CA<3>")
	)
	(segment
		(start 421.802306 -249.73407)
		(end 421.094916 -250.44146)
		(width 0.18288)
		(layer "In2.Cu")
		(net "M_F_CPU0_SB_CA<3>")
	)
	(segment
		(start 396.426436 -248.26595)
		(end 390.66089 -248.26595)
		(width 0.18288)
		(layer "In2.Cu")
		(net "M_F_CPU0_SB_CA<3>")
	)
	(segment
		(start 422.513506 -250.456192)
		(end 422.34104 -250.283726)
		(width 0.18288)
		(layer "In2.Cu")
		(net "M_F_CPU0_SB_CA<3>")
	)
	(segment
		(start 415.616136 -250.448572)
		(end 412.19247 -250.448572)
		(width 0.18288)
		(layer "In2.Cu")
		(net "M_F_CPU0_SB_CA<3>")
	)
	(segment
		(start 389.8011 -249.12574)
		(end 388.41045 -249.701558)
		(width 0.18288)
		(layer "In2.Cu")
		(net "M_F_CPU0_SB_CA<3>")
	)
	(segment
		(start 388.41045 -249.701558)
		(end 386.94995 -249.701558)
		(width 0.18288)
		(layer "In2.Cu")
		(net "M_F_CPU0_SB_CA<3>")
	)
	(segment
		(start 412.16199 -250.418092)
		(end 409.501086 -250.418092)
		(width 0.18288)
		(layer "In2.Cu")
		(net "M_F_CPU0_SB_CA<3>")
	)
	(segment
		(start 382.249172 -246.480076)
		(end 382.242314 -246.450358)
		(width 0.088646)
		(layer "In2.Cu")
		(net "M_F_CPU0_SB_CA<3>")
	)
	(segment
		(start 417.909756 -250.754388)
		(end 417.551362 -250.395994)
		(width 0.18288)
		(layer "In2.Cu")
		(net "M_F_CPU0_SB_CA<3>")
	)
	(segment
		(start 407.857198 -250.65863)
		(end 407.678636 -250.480068)
		(width 0.18288)
		(layer "In2.Cu")
		(net "M_F_CPU0_SB_CA<3>")
	)
	(segment
		(start 421.094916 -250.44146)
		(end 420.242238 -250.44146)
		(width 0.18288)
		(layer "In2.Cu")
		(net "M_F_CPU0_SB_CA<3>")
	)
	(segment
		(start 390.66089 -248.26595)
		(end 389.8011 -249.12574)
		(width 0.18288)
		(layer "In2.Cu")
		(net "M_F_CPU0_SB_CA<3>")
	)
	(segment
		(start 419.382702 -250.264422)
		(end 418.892736 -250.754388)
		(width 0.18288)
		(layer "In2.Cu")
		(net "M_F_CPU0_SB_CA<3>")
	)
	(segment
		(start 385.169918 -247.921526)
		(end 384.68681 -247.921526)
		(width 0.088646)
		(layer "In2.Cu")
		(net "M_F_CPU0_SB_CA<3>")
	)
	(segment
		(start 405.44496 -250.480068)
		(end 405.045164 -250.879864)
		(width 0.18288)
		(layer "In2.Cu")
		(net "M_F_CPU0_SB_CA<3>")
	)
	(segment
		(start 422.34104 -250.283726)
		(end 422.34104 -249.89409)
		(width 0.18288)
		(layer "In2.Cu")
		(net "M_F_CPU0_SB_CA<3>")
	)
	(segment
		(start 420.0652 -250.264422)
		(end 419.382702 -250.264422)
		(width 0.18288)
		(layer "In2.Cu")
		(net "M_F_CPU0_SB_CA<3>")
	)
	(segment
		(start 409.260548 -250.65863)
		(end 407.857198 -250.65863)
		(width 0.18288)
		(layer "In2.Cu")
		(net "M_F_CPU0_SB_CA<3>")
	)
	(segment
		(start 424.396662 -250.456192)
		(end 422.513506 -250.456192)
		(width 0.18288)
		(layer "In2.Cu")
		(net "M_F_CPU0_SB_CA<3>")
	)
	(segment
		(start 412.19247 -250.448572)
		(end 412.16199 -250.418092)
		(width 0.18288)
		(layer "In2.Cu")
		(net "M_F_CPU0_SB_CA<3>")
	)
	(segment
		(start 405.045164 -250.879864)
		(end 402.112226 -250.879864)
		(width 0.18288)
		(layer "In2.Cu")
		(net "M_F_CPU0_SB_CA<3>")
	)
	(segment
		(start 407.678636 -250.480068)
		(end 405.44496 -250.480068)
		(width 0.18288)
		(layer "In2.Cu")
		(net "M_F_CPU0_SB_CA<3>")
	)
	(segment
		(start 422.34104 -249.89409)
		(end 422.18102 -249.73407)
		(width 0.18288)
		(layer "In2.Cu")
		(net "M_F_CPU0_SB_CA<3>")
	)
	(segment
		(start 385.351528 -248.103136)
		(end 385.169918 -247.921526)
		(width 0.088646)
		(layer "In2.Cu")
		(net "M_F_CPU0_SB_CA<3>")
	)
	(segment
		(start 384.68681 -247.921526)
		(end 384.31851 -247.553226)
		(width 0.088646)
		(layer "In2.Cu")
		(net "M_F_CPU0_SB_CA<3>")
	)
	(segment
		(start 417.551362 -250.395994)
		(end 417.124134 -250.395994)
		(width 0.18288)
		(layer "In2.Cu")
		(net "M_F_CPU0_SB_CA<3>")
	)
	(segment
		(start 402.112226 -250.879864)
		(end 401.458684 -250.226322)
		(width 0.18288)
		(layer "In2.Cu")
		(net "M_F_CPU0_SB_CA<3>")
	)
	(arc
		(start 384.015234 -247.553226)
		(mid 383.918311 -247.540268)
		(end 383.828036 -247.50268)
		(width 0.088646)
		(layer "In2.Cu")
		(net "M_F_CPU0_SB_CA<3>")
	)
	(arc
		(start 382.879346 -247.4976)
		(mid 382.748432 -247.36124)
		(end 382.700784 -247.178322)
		(width 0.088646)
		(layer "In2.Cu")
		(net "M_F_CPU0_SB_CA<3>")
	)
	(arc
		(start 382.418082 -246.68861)
		(mid 382.314286 -246.600009)
		(end 382.249172 -246.480076)
		(width 0.088646)
		(layer "In2.Cu")
		(net "M_F_CPU0_SB_CA<3>")
	)
	(arc
		(start 382.700784 -247.168416)
		(mid 382.622673 -246.891467)
		(end 382.418336 -246.688864)
		(width 0.088646)
		(layer "In2.Cu")
		(net "M_F_CPU0_SB_CA<3>")
	)
	(arc
		(start 383.828036 -247.50268)
		(mid 383.545334 -247.426904)
		(end 383.262632 -247.50268)
		(width 0.088646)
		(layer "In2.Cu")
		(net "M_F_CPU0_SB_CA<3>")
	)
	(arc
		(start 383.262632 -247.50268)
		(mid 383.075434 -247.552823)
		(end 382.888236 -247.50268)
		(width 0.088646)
		(layer "In2.Cu")
		(net "M_F_CPU0_SB_CA<3>")
	)
	(segment
		(start 423.726102 -250.372372)
		(end 424.645328 -251.291598)
		(width 0.20066)
		(layer "F.Cu")
		(net "M_F_CPU0_SB_CA<2>")
	)
	(segment
		(start 421.840914 -250.866656)
		(end 422.906444 -250.866656)
		(width 0.20066)
		(layer "F.Cu")
		(net "M_F_CPU0_SB_CA<2>")
	)
	(segment
		(start 426.951394 -251.304044)
		(end 427.367446 -251.304044)
		(width 0.20066)
		(layer "F.Cu")
		(net "M_F_CPU0_SB_CA<2>")
	)
	(segment
		(start 424.645328 -251.291598)
		(end 424.75277 -251.291598)
		(width 0.20066)
		(layer "F.Cu")
		(net "M_F_CPU0_SB_CA<2>")
	)
	(segment
		(start 423.400728 -250.372372)
		(end 423.726102 -250.372372)
		(width 0.20066)
		(layer "F.Cu")
		(net "M_F_CPU0_SB_CA<2>")
	)
	(segment
		(start 422.906444 -250.866656)
		(end 423.400728 -250.372372)
		(width 0.20066)
		(layer "F.Cu")
		(net "M_F_CPU0_SB_CA<2>")
	)
	(segment
		(start 427.367446 -251.304044)
		(end 427.805088 -250.866402)
		(width 0.20066)
		(layer "F.Cu")
		(net "M_F_CPU0_SB_CA<2>")
	)
	(segment
		(start 381.665734 -246.900446)
		(end 381.665734 -246.364506)
		(width 0.20066)
		(layer "F.Cu")
		(net "M_F_CPU0_SB_CA<2>")
	)
	(segment
		(start 420.736014 -250.866656)
		(end 421.840914 -250.866656)
		(width 0.20066)
		(layer "F.Cu")
		(net "M_F_CPU0_SB_CA<2>")
	)
	(segment
		(start 429.38446 -250.866402)
		(end 429.384714 -250.866656)
		(width 0.20066)
		(layer "F.Cu")
		(net "M_F_CPU0_SB_CA<2>")
	)
	(segment
		(start 427.805088 -250.866402)
		(end 429.38446 -250.866402)
		(width 0.20066)
		(layer "F.Cu")
		(net "M_F_CPU0_SB_CA<2>")
	)
	(segment
		(start 424.766486 -251.291598)
		(end 426.938948 -251.291598)
		(width 0.1016)
		(layer "F.Cu")
		(net "M_F_CPU0_SB_CA<2>")
	)
	(segment
		(start 426.938948 -251.291598)
		(end 426.951394 -251.304044)
		(width 0.1016)
		(layer "F.Cu")
		(net "M_F_CPU0_SB_CA<2>")
	)
	(segment
		(start 424.75277 -251.291598)
		(end 424.766486 -251.291598)
		(width 0.101854)
		(layer "F.Cu")
		(net "M_F_CPU0_SB_CA<2>")
	)
	(segment
		(start 400.249898 -251.41174)
		(end 400.056858 -251.2187)
		(width 0.18288)
		(layer "In2.Cu")
		(net "M_F_CPU0_SB_CA<2>")
	)
	(segment
		(start 384.884422 -248.124726)
		(end 384.585718 -248.124726)
		(width 0.088646)
		(layer "In2.Cu")
		(net "M_F_CPU0_SB_CA<2>")
	)
	(segment
		(start 406.176734 -251.6124)
		(end 405.75357 -251.189236)
		(width 0.18288)
		(layer "In2.Cu")
		(net "M_F_CPU0_SB_CA<2>")
	)
	(segment
		(start 416.07994 -251.743718)
		(end 415.511488 -251.175266)
		(width 0.18288)
		(layer "In2.Cu")
		(net "M_F_CPU0_SB_CA<2>")
	)
	(segment
		(start 388.695692 -250.095004)
		(end 386.982716 -250.095004)
		(width 0.18288)
		(layer "In2.Cu")
		(net "M_F_CPU0_SB_CA<2>")
	)
	(segment
		(start 420.241222 -251.602748)
		(end 420.078408 -251.765562)
		(width 0.18288)
		(layer "In2.Cu")
		(net "M_F_CPU0_SB_CA<2>")
	)
	(segment
		(start 417.524184 -251.265436)
		(end 417.045902 -251.743718)
		(width 0.18288)
		(layer "In2.Cu")
		(net "M_F_CPU0_SB_CA<2>")
	)
	(segment
		(start 400.056858 -251.2187)
		(end 400.056858 -250.953016)
		(width 0.18288)
		(layer "In2.Cu")
		(net "M_F_CPU0_SB_CA<2>")
	)
	(segment
		(start 415.511488 -251.175266)
		(end 415.238184 -251.175266)
		(width 0.18288)
		(layer "In2.Cu")
		(net "M_F_CPU0_SB_CA<2>")
	)
	(segment
		(start 400.056858 -250.953016)
		(end 399.863818 -250.759976)
		(width 0.18288)
		(layer "In2.Cu")
		(net "M_F_CPU0_SB_CA<2>")
	)
	(segment
		(start 382.054354 -246.489474)
		(end 382.04394 -246.429784)
		(width 0.088646)
		(layer "In2.Cu")
		(net "M_F_CPU0_SB_CA<2>")
	)
	(segment
		(start 386.764276 -250.00458)
		(end 385.10718 -248.347484)
		(width 0.18288)
		(layer "In2.Cu")
		(net "M_F_CPU0_SB_CA<2>")
	)
	(segment
		(start 412.914846 -251.005594)
		(end 412.696406 -251.224034)
		(width 0.18288)
		(layer "In2.Cu")
		(net "M_F_CPU0_SB_CA<2>")
	)
	(segment
		(start 405.48052 -251.189236)
		(end 405.258016 -251.41174)
		(width 0.18288)
		(layer "In2.Cu")
		(net "M_F_CPU0_SB_CA<2>")
	)
	(segment
		(start 407.649172 -251.201682)
		(end 407.238454 -251.6124)
		(width 0.18288)
		(layer "In2.Cu")
		(net "M_F_CPU0_SB_CA<2>")
	)
	(segment
		(start 409.53182 -251.545852)
		(end 409.216098 -251.23013)
		(width 0.18288)
		(layer "In2.Cu")
		(net "M_F_CPU0_SB_CA<2>")
	)
	(segment
		(start 409.216098 -251.23013)
		(end 408.873452 -251.23013)
		(width 0.18288)
		(layer "In2.Cu")
		(net "M_F_CPU0_SB_CA<2>")
	)
	(segment
		(start 407.238454 -251.6124)
		(end 406.176734 -251.6124)
		(width 0.18288)
		(layer "In2.Cu")
		(net "M_F_CPU0_SB_CA<2>")
	)
	(segment
		(start 408.615896 -251.487686)
		(end 408.254454 -251.487686)
		(width 0.18288)
		(layer "In2.Cu")
		(net "M_F_CPU0_SB_CA<2>")
	)
	(segment
		(start 400.953986 -250.759976)
		(end 400.760946 -250.953016)
		(width 0.18288)
		(layer "In2.Cu")
		(net "M_F_CPU0_SB_CA<2>")
	)
	(segment
		(start 405.258016 -251.41174)
		(end 401.658074 -251.41174)
		(width 0.18288)
		(layer "In2.Cu")
		(net "M_F_CPU0_SB_CA<2>")
	)
	(segment
		(start 382.510284 -247.188228)
		(end 382.510284 -247.178322)
		(width 0.088646)
		(layer "In2.Cu")
		(net "M_F_CPU0_SB_CA<2>")
	)
	(segment
		(start 399.35277 -251.2187)
		(end 399.15973 -251.41174)
		(width 0.18288)
		(layer "In2.Cu")
		(net "M_F_CPU0_SB_CA<2>")
	)
	(segment
		(start 401.658074 -251.41174)
		(end 401.465034 -251.2187)
		(width 0.18288)
		(layer "In2.Cu")
		(net "M_F_CPU0_SB_CA<2>")
	)
	(segment
		(start 385.10718 -248.347484)
		(end 384.884422 -248.124726)
		(width 0.088646)
		(layer "In2.Cu")
		(net "M_F_CPU0_SB_CA<2>")
	)
	(segment
		(start 401.271994 -250.759976)
		(end 400.953986 -250.759976)
		(width 0.18288)
		(layer "In2.Cu")
		(net "M_F_CPU0_SB_CA<2>")
	)
	(segment
		(start 399.863818 -250.759976)
		(end 399.54581 -250.759976)
		(width 0.18288)
		(layer "In2.Cu")
		(net "M_F_CPU0_SB_CA<2>")
	)
	(segment
		(start 411.963362 -251.712984)
		(end 411.963362 -251.59716)
		(width 0.18288)
		(layer "In2.Cu")
		(net "M_F_CPU0_SB_CA<2>")
	)
	(segment
		(start 408.873452 -251.23013)
		(end 408.615896 -251.487686)
		(width 0.18288)
		(layer "In2.Cu")
		(net "M_F_CPU0_SB_CA<2>")
	)
	(segment
		(start 384.204464 -247.743472)
		(end 384.01498 -247.743472)
		(width 0.088646)
		(layer "In2.Cu")
		(net "M_F_CPU0_SB_CA<2>")
	)
	(segment
		(start 412.536386 -251.906024)
		(end 412.156402 -251.906024)
		(width 0.18288)
		(layer "In2.Cu")
		(net "M_F_CPU0_SB_CA<2>")
	)
	(segment
		(start 400.567906 -251.41174)
		(end 400.249898 -251.41174)
		(width 0.18288)
		(layer "In2.Cu")
		(net "M_F_CPU0_SB_CA<2>")
	)
	(segment
		(start 401.465034 -250.953016)
		(end 401.271994 -250.759976)
		(width 0.18288)
		(layer "In2.Cu")
		(net "M_F_CPU0_SB_CA<2>")
	)
	(segment
		(start 412.696406 -251.224034)
		(end 412.696406 -251.746004)
		(width 0.18288)
		(layer "In2.Cu")
		(net "M_F_CPU0_SB_CA<2>")
	)
	(segment
		(start 417.045902 -251.743718)
		(end 416.07994 -251.743718)
		(width 0.18288)
		(layer "In2.Cu")
		(net "M_F_CPU0_SB_CA<2>")
	)
	(segment
		(start 401.465034 -251.2187)
		(end 401.465034 -250.953016)
		(width 0.18288)
		(layer "In2.Cu")
		(net "M_F_CPU0_SB_CA<2>")
	)
	(segment
		(start 405.75357 -251.189236)
		(end 405.48052 -251.189236)
		(width 0.18288)
		(layer "In2.Cu")
		(net "M_F_CPU0_SB_CA<2>")
	)
	(segment
		(start 420.078408 -251.765562)
		(end 419.616382 -251.765562)
		(width 0.18288)
		(layer "In2.Cu")
		(net "M_F_CPU0_SB_CA<2>")
	)
	(segment
		(start 415.238184 -251.175266)
		(end 414.815528 -251.597922)
		(width 0.18288)
		(layer "In2.Cu")
		(net "M_F_CPU0_SB_CA<2>")
	)
	(segment
		(start 398.641062 -251.41174)
		(end 395.840712 -248.61139)
		(width 0.18288)
		(layer "In2.Cu")
		(net "M_F_CPU0_SB_CA<2>")
	)
	(segment
		(start 419.116256 -251.265436)
		(end 417.524184 -251.265436)
		(width 0.18288)
		(layer "In2.Cu")
		(net "M_F_CPU0_SB_CA<2>")
	)
	(segment
		(start 412.156402 -251.906024)
		(end 411.963362 -251.712984)
		(width 0.18288)
		(layer "In2.Cu")
		(net "M_F_CPU0_SB_CA<2>")
	)
	(segment
		(start 395.840712 -248.61139)
		(end 391.127234 -248.61139)
		(width 0.18288)
		(layer "In2.Cu")
		(net "M_F_CPU0_SB_CA<2>")
	)
	(segment
		(start 420.736014 -250.866656)
		(end 420.241222 -251.361448)
		(width 0.18288)
		(layer "In2.Cu")
		(net "M_F_CPU0_SB_CA<2>")
	)
	(segment
		(start 399.54581 -250.759976)
		(end 399.35277 -250.953016)
		(width 0.18288)
		(layer "In2.Cu")
		(net "M_F_CPU0_SB_CA<2>")
	)
	(segment
		(start 411.963362 -251.59716)
		(end 411.716728 -251.350526)
		(width 0.18288)
		(layer "In2.Cu")
		(net "M_F_CPU0_SB_CA<2>")
	)
	(segment
		(start 420.241222 -251.361448)
		(end 420.241222 -251.602748)
		(width 0.18288)
		(layer "In2.Cu")
		(net "M_F_CPU0_SB_CA<2>")
	)
	(segment
		(start 390.313926 -249.424698)
		(end 388.695692 -250.095004)
		(width 0.18288)
		(layer "In2.Cu")
		(net "M_F_CPU0_SB_CA<2>")
	)
	(segment
		(start 411.438852 -251.350526)
		(end 411.027372 -250.939046)
		(width 0.18288)
		(layer "In2.Cu")
		(net "M_F_CPU0_SB_CA<2>")
	)
	(segment
		(start 382.331722 -246.859044)
		(end 382.322832 -246.853964)
		(width 0.088646)
		(layer "In2.Cu")
		(net "M_F_CPU0_SB_CA<2>")
	)
	(segment
		(start 411.027372 -250.939046)
		(end 410.479748 -250.939046)
		(width 0.18288)
		(layer "In2.Cu")
		(net "M_F_CPU0_SB_CA<2>")
	)
	(segment
		(start 414.815528 -251.597922)
		(end 413.8295 -251.597922)
		(width 0.18288)
		(layer "In2.Cu")
		(net "M_F_CPU0_SB_CA<2>")
	)
	(segment
		(start 409.872942 -251.545852)
		(end 409.53182 -251.545852)
		(width 0.18288)
		(layer "In2.Cu")
		(net "M_F_CPU0_SB_CA<2>")
	)
	(segment
		(start 408.254454 -251.487686)
		(end 407.96845 -251.201682)
		(width 0.18288)
		(layer "In2.Cu")
		(net "M_F_CPU0_SB_CA<2>")
	)
	(segment
		(start 400.760946 -250.953016)
		(end 400.760946 -251.2187)
		(width 0.18288)
		(layer "In2.Cu")
		(net "M_F_CPU0_SB_CA<2>")
	)
	(segment
		(start 382.04394 -246.429784)
		(end 381.978662 -246.364506)
		(width 0.088646)
		(layer "In2.Cu")
		(net "M_F_CPU0_SB_CA<2>")
	)
	(segment
		(start 407.96845 -251.201682)
		(end 407.649172 -251.201682)
		(width 0.18288)
		(layer "In2.Cu")
		(net "M_F_CPU0_SB_CA<2>")
	)
	(segment
		(start 413.237172 -251.005594)
		(end 412.914846 -251.005594)
		(width 0.18288)
		(layer "In2.Cu")
		(net "M_F_CPU0_SB_CA<2>")
	)
	(segment
		(start 400.760946 -251.2187)
		(end 400.567906 -251.41174)
		(width 0.18288)
		(layer "In2.Cu")
		(net "M_F_CPU0_SB_CA<2>")
	)
	(segment
		(start 413.8295 -251.597922)
		(end 413.237172 -251.005594)
		(width 0.18288)
		(layer "In2.Cu")
		(net "M_F_CPU0_SB_CA<2>")
	)
	(segment
		(start 381.978662 -246.364506)
		(end 381.665734 -246.364506)
		(width 0.088646)
		(layer "In2.Cu")
		(net "M_F_CPU0_SB_CA<2>")
	)
	(segment
		(start 412.696406 -251.746004)
		(end 412.536386 -251.906024)
		(width 0.18288)
		(layer "In2.Cu")
		(net "M_F_CPU0_SB_CA<2>")
	)
	(segment
		(start 410.479748 -250.939046)
		(end 409.872942 -251.545852)
		(width 0.18288)
		(layer "In2.Cu")
		(net "M_F_CPU0_SB_CA<2>")
	)
	(segment
		(start 384.585718 -248.124726)
		(end 384.204464 -247.743472)
		(width 0.088646)
		(layer "In2.Cu")
		(net "M_F_CPU0_SB_CA<2>")
	)
	(segment
		(start 399.15973 -251.41174)
		(end 398.641062 -251.41174)
		(width 0.18288)
		(layer "In2.Cu")
		(net "M_F_CPU0_SB_CA<2>")
	)
	(segment
		(start 391.127234 -248.61139)
		(end 390.313926 -249.424698)
		(width 0.18288)
		(layer "In2.Cu")
		(net "M_F_CPU0_SB_CA<2>")
	)
	(segment
		(start 419.616382 -251.765562)
		(end 419.116256 -251.265436)
		(width 0.18288)
		(layer "In2.Cu")
		(net "M_F_CPU0_SB_CA<2>")
	)
	(segment
		(start 411.716728 -251.350526)
		(end 411.438852 -251.350526)
		(width 0.18288)
		(layer "In2.Cu")
		(net "M_F_CPU0_SB_CA<2>")
	)
	(segment
		(start 399.35277 -250.953016)
		(end 399.35277 -251.2187)
		(width 0.18288)
		(layer "In2.Cu")
		(net "M_F_CPU0_SB_CA<2>")
	)
	(arc
		(start 383.358136 -247.66778)
		(mid 383.075434 -247.743556)
		(end 382.792732 -247.66778)
		(width 0.088646)
		(layer "In2.Cu")
		(net "M_F_CPU0_SB_CA<2>")
	)
	(arc
		(start 386.982716 -250.095004)
		(mid 386.864505 -250.071508)
		(end 386.764276 -250.00458)
		(width 0.18288)
		(layer "In2.Cu")
		(net "M_F_CPU0_SB_CA<2>")
	)
	(arc
		(start 382.510284 -247.178322)
		(mid 382.462605 -246.995422)
		(end 382.331722 -246.859044)
		(width 0.088646)
		(layer "In2.Cu")
		(net "M_F_CPU0_SB_CA<2>")
	)
	(arc
		(start 382.792732 -247.66778)
		(mid 382.588397 -247.465175)
		(end 382.510284 -247.188228)
		(width 0.088646)
		(layer "In2.Cu")
		(net "M_F_CPU0_SB_CA<2>")
	)
	(arc
		(start 382.322832 -246.853964)
		(mid 382.150477 -246.699786)
		(end 382.054354 -246.489474)
		(width 0.088646)
		(layer "In2.Cu")
		(net "M_F_CPU0_SB_CA<2>")
	)
	(arc
		(start 383.732532 -247.66778)
		(mid 383.545334 -247.617637)
		(end 383.358136 -247.66778)
		(width 0.088646)
		(layer "In2.Cu")
		(net "M_F_CPU0_SB_CA<2>")
	)
	(arc
		(start 384.01498 -247.743472)
		(mid 383.868767 -247.724231)
		(end 383.732532 -247.66778)
		(width 0.088646)
		(layer "In2.Cu")
		(net "M_F_CPU0_SB_CA<2>")
	)
	(segment
		(start 431.937668 -251.284232)
		(end 432.37023 -251.716794)
		(width 0.20066)
		(layer "F.Cu")
		(net "M_F_CPU0_SB_CA<1>")
	)
	(segment
		(start 430.669192 -252.149102)
		(end 431.534062 -251.284232)
		(width 0.20066)
		(layer "F.Cu")
		(net "M_F_CPU0_SB_CA<1>")
	)
	(segment
		(start 428.363126 -252.152404)
		(end 428.367952 -252.152404)
		(width 0.101854)
		(layer "F.Cu")
		(net "M_F_CPU0_SB_CA<1>")
	)
	(segment
		(start 425.940982 -251.716794)
		(end 427.576742 -251.716794)
		(width 0.20066)
		(layer "F.Cu")
		(net "M_F_CPU0_SB_CA<1>")
	)
	(segment
		(start 427.576742 -251.716794)
		(end 428.012352 -252.152404)
		(width 0.20066)
		(layer "F.Cu")
		(net "M_F_CPU0_SB_CA<1>")
	)
	(segment
		(start 430.395126 -252.149102)
		(end 430.669192 -252.149102)
		(width 0.20066)
		(layer "F.Cu")
		(net "M_F_CPU0_SB_CA<1>")
	)
	(segment
		(start 378.016262 -255.825752)
		(end 378.016262 -256.361438)
		(width 0.20066)
		(layer "F.Cu")
		(net "M_F_CPU0_SB_CA<1>")
	)
	(segment
		(start 430.38776 -252.141736)
		(end 430.395126 -252.149102)
		(width 0.1016)
		(layer "F.Cu")
		(net "M_F_CPU0_SB_CA<1>")
	)
	(segment
		(start 428.012352 -252.152404)
		(end 428.363126 -252.152404)
		(width 0.20066)
		(layer "F.Cu")
		(net "M_F_CPU0_SB_CA<1>")
	)
	(segment
		(start 378.016516 -255.825498)
		(end 378.016262 -255.825752)
		(width 0.20066)
		(layer "F.Cu")
		(net "M_F_CPU0_SB_CA<1>")
	)
	(segment
		(start 428.367952 -252.152404)
		(end 428.37862 -252.141736)
		(width 0.1016)
		(layer "F.Cu")
		(net "M_F_CPU0_SB_CA<1>")
	)
	(segment
		(start 432.37023 -251.716794)
		(end 433.484782 -251.716794)
		(width 0.20066)
		(layer "F.Cu")
		(net "M_F_CPU0_SB_CA<1>")
	)
	(segment
		(start 431.534062 -251.284232)
		(end 431.937668 -251.284232)
		(width 0.20066)
		(layer "F.Cu")
		(net "M_F_CPU0_SB_CA<1>")
	)
	(segment
		(start 424.836082 -251.716794)
		(end 425.940982 -251.716794)
		(width 0.20066)
		(layer "F.Cu")
		(net "M_F_CPU0_SB_CA<1>")
	)
	(segment
		(start 428.37862 -252.141736)
		(end 430.38776 -252.141736)
		(width 0.1016)
		(layer "F.Cu")
		(net "M_F_CPU0_SB_CA<1>")
	)
	(segment
		(start 377.350528 -255.8669)
		(end 377.359418 -255.87198)
		(width 0.088646)
		(layer "In2.Cu")
		(net "M_F_CPU0_SB_CA<1>")
	)
	(segment
		(start 386.748274 -251.766324)
		(end 383.10566 -252.124718)
		(width 0.18288)
		(layer "In2.Cu")
		(net "M_F_CPU0_SB_CA<1>")
	)
	(segment
		(start 378.151644 -256.710434)
		(end 378.172726 -256.632456)
		(width 0.088646)
		(layer "In2.Cu")
		(net "M_F_CPU0_SB_CA<1>")
	)
	(segment
		(start 417.611814 -253.052072)
		(end 417.567872 -253.00813)
		(width 0.18288)
		(layer "In2.Cu")
		(net "M_F_CPU0_SB_CA<1>")
	)
	(segment
		(start 377.641866 -256.351532)
		(end 377.641866 -256.370074)
		(width 0.088646)
		(layer "In2.Cu")
		(net "M_F_CPU0_SB_CA<1>")
	)
	(segment
		(start 377.641612 -254.733552)
		(end 377.641612 -254.734314)
		(width 0.088646)
		(layer "In2.Cu")
		(net "M_F_CPU0_SB_CA<1>")
	)
	(segment
		(start 389.363712 -251.027946)
		(end 388.792212 -251.298202)
		(width 0.18288)
		(layer "In2.Cu")
		(net "M_F_CPU0_SB_CA<1>")
	)
	(segment
		(start 378.622814 -253.52121)
		(end 378.417582 -253.52121)
		(width 0.088646)
		(layer "In2.Cu")
		(net "M_F_CPU0_SB_CA<1>")
	)
	(segment
		(start 424.836082 -251.716794)
		(end 422.823132 -253.052072)
		(width 0.18288)
		(layer "In2.Cu")
		(net "M_F_CPU0_SB_CA<1>")
	)
	(segment
		(start 422.823132 -253.052072)
		(end 417.611814 -253.052072)
		(width 0.18288)
		(layer "In2.Cu")
		(net "M_F_CPU0_SB_CA<1>")
	)
	(segment
		(start 388.792212 -251.298202)
		(end 388.791958 -251.298202)
		(width 0.18288)
		(layer "In2.Cu")
		(net "M_F_CPU0_SB_CA<1>")
	)
	(segment
		(start 417.567872 -253.00813)
		(end 406.02281 -253.00813)
		(width 0.18288)
		(layer "In2.Cu")
		(net "M_F_CPU0_SB_CA<1>")
	)
	(segment
		(start 392.251946 -249.30227)
		(end 391.56894 -249.985276)
		(width 0.18288)
		(layer "In2.Cu")
		(net "M_F_CPU0_SB_CA<1>")
	)
	(segment
		(start 391.56894 -249.985276)
		(end 389.363712 -251.027946)
		(width 0.18288)
		(layer "In2.Cu")
		(net "M_F_CPU0_SB_CA<1>")
	)
	(segment
		(start 383.10566 -252.124718)
		(end 379.34138 -253.068074)
		(width 0.18288)
		(layer "In2.Cu")
		(net "M_F_CPU0_SB_CA<1>")
	)
	(segment
		(start 388.791958 -251.298202)
		(end 387.827012 -251.56541)
		(width 0.18288)
		(layer "In2.Cu")
		(net "M_F_CPU0_SB_CA<1>")
	)
	(segment
		(start 379.34138 -253.068074)
		(end 378.88799 -253.256034)
		(width 0.18288)
		(layer "In2.Cu")
		(net "M_F_CPU0_SB_CA<1>")
	)
	(segment
		(start 378.774198 -253.369826)
		(end 378.622814 -253.52121)
		(width 0.088646)
		(layer "In2.Cu")
		(net "M_F_CPU0_SB_CA<1>")
	)
	(segment
		(start 378.257562 -253.587504)
		(end 378.111766 -253.7333)
		(width 0.088646)
		(layer "In2.Cu")
		(net "M_F_CPU0_SB_CA<1>")
	)
	(segment
		(start 378.08027 -256.472182)
		(end 378.016262 -256.361438)
		(width 0.088646)
		(layer "In2.Cu")
		(net "M_F_CPU0_SB_CA<1>")
	)
	(segment
		(start 378.88799 -253.256034)
		(end 378.774198 -253.369826)
		(width 0.18288)
		(layer "In2.Cu")
		(net "M_F_CPU0_SB_CA<1>")
	)
	(segment
		(start 378.417582 -253.52121)
		(end 378.257562 -253.587504)
		(width 0.088646)
		(layer "In2.Cu")
		(net "M_F_CPU0_SB_CA<1>")
	)
	(segment
		(start 403.51456 -252.509274)
		(end 398.259046 -252.509274)
		(width 0.18288)
		(layer "In2.Cu")
		(net "M_F_CPU0_SB_CA<1>")
	)
	(segment
		(start 377.841256 -254.402082)
		(end 377.820174 -254.414274)
		(width 0.088646)
		(layer "In2.Cu")
		(net "M_F_CPU0_SB_CA<1>")
	)
	(segment
		(start 377.359418 -255.223264)
		(end 377.350528 -255.228344)
		(width 0.088646)
		(layer "In2.Cu")
		(net "M_F_CPU0_SB_CA<1>")
	)
	(segment
		(start 378.111766 -253.7333)
		(end 378.111766 -253.919736)
		(width 0.088646)
		(layer "In2.Cu")
		(net "M_F_CPU0_SB_CA<1>")
	)
	(segment
		(start 387.827012 -251.56541)
		(end 386.748274 -251.766324)
		(width 0.18288)
		(layer "In2.Cu")
		(net "M_F_CPU0_SB_CA<1>")
	)
	(segment
		(start 395.052042 -249.30227)
		(end 392.251946 -249.30227)
		(width 0.18288)
		(layer "In2.Cu")
		(net "M_F_CPU0_SB_CA<1>")
	)
	(segment
		(start 378.172726 -256.632456)
		(end 378.08027 -256.472182)
		(width 0.088646)
		(layer "In2.Cu")
		(net "M_F_CPU0_SB_CA<1>")
	)
	(segment
		(start 406.02281 -253.00813)
		(end 403.51456 -252.509274)
		(width 0.18288)
		(layer "In2.Cu")
		(net "M_F_CPU0_SB_CA<1>")
	)
	(segment
		(start 398.259046 -252.509274)
		(end 395.052042 -249.30227)
		(width 0.18288)
		(layer "In2.Cu")
		(net "M_F_CPU0_SB_CA<1>")
	)
	(arc
		(start 377.820174 -254.414274)
		(mid 377.68926 -254.550634)
		(end 377.641612 -254.733552)
		(width 0.088646)
		(layer "In2.Cu")
		(net "M_F_CPU0_SB_CA<1>")
	)
	(arc
		(start 377.829064 -256.685796)
		(mid 377.987552 -256.734729)
		(end 378.151644 -256.710434)
		(width 0.088646)
		(layer "In2.Cu")
		(net "M_F_CPU0_SB_CA<1>")
	)
	(arc
		(start 378.111766 -253.919736)
		(mid 378.039531 -254.19626)
		(end 377.841256 -254.402082)
		(width 0.088646)
		(layer "In2.Cu")
		(net "M_F_CPU0_SB_CA<1>")
	)
	(arc
		(start 377.641866 -256.370074)
		(mid 377.694136 -256.552439)
		(end 377.829064 -256.685796)
		(width 0.088646)
		(layer "In2.Cu")
		(net "M_F_CPU0_SB_CA<1>")
	)
	(arc
		(start 377.641612 -254.734314)
		(mid 377.565997 -255.016578)
		(end 377.359418 -255.223264)
		(width 0.088646)
		(layer "In2.Cu")
		(net "M_F_CPU0_SB_CA<1>")
	)
	(arc
		(start 377.350528 -255.228344)
		(mid 377.171931 -255.547622)
		(end 377.350528 -255.8669)
		(width 0.088646)
		(layer "In2.Cu")
		(net "M_F_CPU0_SB_CA<1>")
	)
	(arc
		(start 377.359418 -255.87198)
		(mid 377.563753 -256.074585)
		(end 377.641866 -256.351532)
		(width 0.088646)
		(layer "In2.Cu")
		(net "M_F_CPU0_SB_CA<1>")
	)
	(segment
		(start 420.736014 -252.566678)
		(end 421.840914 -252.566678)
		(width 0.20066)
		(layer "F.Cu")
		(net "M_F_CPU0_SB_CA<0>")
	)
	(segment
		(start 424.004994 -252.566678)
		(end 424.623484 -253.185168)
		(width 0.20066)
		(layer "F.Cu")
		(net "M_F_CPU0_SB_CA<0>")
	)
	(segment
		(start 426.545248 -253.737872)
		(end 427.23943 -253.737872)
		(width 0.20066)
		(layer "F.Cu")
		(net "M_F_CPU0_SB_CA<0>")
	)
	(segment
		(start 378.486162 -257.175)
		(end 378.486416 -257.175254)
		(width 0.20066)
		(layer "F.Cu")
		(net "M_F_CPU0_SB_CA<0>")
	)
	(segment
		(start 421.840914 -252.566678)
		(end 424.004994 -252.566678)
		(width 0.20066)
		(layer "F.Cu")
		(net "M_F_CPU0_SB_CA<0>")
	)
	(segment
		(start 427.23943 -253.737872)
		(end 428.410624 -252.566678)
		(width 0.20066)
		(layer "F.Cu")
		(net "M_F_CPU0_SB_CA<0>")
	)
	(segment
		(start 425.992544 -253.185168)
		(end 426.545248 -253.737872)
		(width 0.20066)
		(layer "F.Cu")
		(net "M_F_CPU0_SB_CA<0>")
	)
	(segment
		(start 378.486162 -256.639314)
		(end 378.486162 -257.175)
		(width 0.20066)
		(layer "F.Cu")
		(net "M_F_CPU0_SB_CA<0>")
	)
	(segment
		(start 424.623484 -253.185168)
		(end 425.992544 -253.185168)
		(width 0.20066)
		(layer "F.Cu")
		(net "M_F_CPU0_SB_CA<0>")
	)
	(segment
		(start 428.410624 -252.566678)
		(end 429.384714 -252.566678)
		(width 0.20066)
		(layer "F.Cu")
		(net "M_F_CPU0_SB_CA<0>")
	)
	(segment
		(start 377.921012 -253.416308)
		(end 377.921012 -253.919736)
		(width 0.088646)
		(layer "In2.Cu")
		(net "M_F_CPU0_SB_CA<0>")
	)
	(segment
		(start 395.444726 -248.95683)
		(end 391.626598 -248.95683)
		(width 0.18288)
		(layer "In2.Cu")
		(net "M_F_CPU0_SB_CA<0>")
	)
	(segment
		(start 382.62433 -251.414026)
		(end 381.720598 -251.414026)
		(width 0.18288)
		(layer "In2.Cu")
		(net "M_F_CPU0_SB_CA<0>")
	)
	(segment
		(start 378.329952 -256.904236)
		(end 378.486416 -257.175254)
		(width 0.088646)
		(layer "In2.Cu")
		(net "M_F_CPU0_SB_CA<0>")
	)
	(segment
		(start 377.27255 -255.05283)
		(end 377.26366 -255.05791)
		(width 0.088646)
		(layer "In2.Cu")
		(net "M_F_CPU0_SB_CA<0>")
	)
	(segment
		(start 411.88513 -252.47981)
		(end 411.5816 -252.17628)
		(width 0.18288)
		(layer "In2.Cu")
		(net "M_F_CPU0_SB_CA<0>")
	)
	(segment
		(start 378.652532 -252.684788)
		(end 378.370846 -252.966474)
		(width 0.18288)
		(layer "In2.Cu")
		(net "M_F_CPU0_SB_CA<0>")
	)
	(segment
		(start 378.370846 -252.966474)
		(end 377.921012 -253.416308)
		(width 0.088646)
		(layer "In2.Cu")
		(net "M_F_CPU0_SB_CA<0>")
	)
	(segment
		(start 377.733814 -256.850896)
		(end 377.748546 -256.859532)
		(width 0.088646)
		(layer "In2.Cu")
		(net "M_F_CPU0_SB_CA<0>")
	)
	(segment
		(start 388.532624 -250.724924)
		(end 387.465062 -250.937268)
		(width 0.18288)
		(layer "In2.Cu")
		(net "M_F_CPU0_SB_CA<0>")
	)
	(segment
		(start 377.451112 -254.723646)
		(end 377.451112 -254.733552)
		(width 0.088646)
		(layer "In2.Cu")
		(net "M_F_CPU0_SB_CA<0>")
	)
	(segment
		(start 405.07031 -252.17628)
		(end 404.820628 -251.926598)
		(width 0.18288)
		(layer "In2.Cu")
		(net "M_F_CPU0_SB_CA<0>")
	)
	(segment
		(start 378.240798 -256.88036)
		(end 378.329952 -256.904236)
		(width 0.088646)
		(layer "In2.Cu")
		(net "M_F_CPU0_SB_CA<0>")
	)
	(segment
		(start 377.451112 -256.352802)
		(end 377.451112 -256.361438)
		(width 0.088646)
		(layer "In2.Cu")
		(net "M_F_CPU0_SB_CA<0>")
	)
	(segment
		(start 413.070548 -252.47981)
		(end 411.88513 -252.47981)
		(width 0.18288)
		(layer "In2.Cu")
		(net "M_F_CPU0_SB_CA<0>")
	)
	(segment
		(start 398.414494 -251.926598)
		(end 395.444726 -248.95683)
		(width 0.18288)
		(layer "In2.Cu")
		(net "M_F_CPU0_SB_CA<0>")
	)
	(segment
		(start 387.465062 -250.937268)
		(end 384.125978 -251.266198)
		(width 0.18288)
		(layer "In2.Cu")
		(net "M_F_CPU0_SB_CA<0>")
	)
	(segment
		(start 384.125978 -251.266198)
		(end 382.62433 -251.414026)
		(width 0.18288)
		(layer "In2.Cu")
		(net "M_F_CPU0_SB_CA<0>")
	)
	(segment
		(start 377.74245 -254.239014)
		(end 377.73356 -254.244094)
		(width 0.088646)
		(layer "In2.Cu")
		(net "M_F_CPU0_SB_CA<0>")
	)
	(segment
		(start 413.407098 -252.14326)
		(end 413.070548 -252.47981)
		(width 0.18288)
		(layer "In2.Cu")
		(net "M_F_CPU0_SB_CA<0>")
	)
	(segment
		(start 420.469314 -252.299978)
		(end 415.505392 -252.299978)
		(width 0.18288)
		(layer "In2.Cu")
		(net "M_F_CPU0_SB_CA<0>")
	)
	(segment
		(start 411.5816 -252.17628)
		(end 405.07031 -252.17628)
		(width 0.18288)
		(layer "In2.Cu")
		(net "M_F_CPU0_SB_CA<0>")
	)
	(segment
		(start 381.720598 -251.414026)
		(end 378.652532 -252.684788)
		(width 0.18288)
		(layer "In2.Cu")
		(net "M_F_CPU0_SB_CA<0>")
	)
	(segment
		(start 415.348674 -252.14326)
		(end 413.407098 -252.14326)
		(width 0.18288)
		(layer "In2.Cu")
		(net "M_F_CPU0_SB_CA<0>")
	)
	(segment
		(start 404.820628 -251.926598)
		(end 398.414494 -251.926598)
		(width 0.18288)
		(layer "In2.Cu")
		(net "M_F_CPU0_SB_CA<0>")
	)
	(segment
		(start 415.505392 -252.299978)
		(end 415.348674 -252.14326)
		(width 0.18288)
		(layer "In2.Cu")
		(net "M_F_CPU0_SB_CA<0>")
	)
	(segment
		(start 390.796526 -249.786902)
		(end 390.46912 -249.922538)
		(width 0.18288)
		(layer "In2.Cu")
		(net "M_F_CPU0_SB_CA<0>")
	)
	(segment
		(start 377.727718 -256.84734)
		(end 377.733814 -256.850896)
		(width 0.088646)
		(layer "In2.Cu")
		(net "M_F_CPU0_SB_CA<0>")
	)
	(segment
		(start 390.46912 -249.922538)
		(end 388.532624 -250.724924)
		(width 0.18288)
		(layer "In2.Cu")
		(net "M_F_CPU0_SB_CA<0>")
	)
	(segment
		(start 376.981466 -255.525524)
		(end 376.981466 -255.557528)
		(width 0.088646)
		(layer "In2.Cu")
		(net "M_F_CPU0_SB_CA<0>")
	)
	(segment
		(start 391.626598 -248.95683)
		(end 390.796526 -249.786902)
		(width 0.18288)
		(layer "In2.Cu")
		(net "M_F_CPU0_SB_CA<0>")
	)
	(segment
		(start 420.736014 -252.566678)
		(end 420.469314 -252.299978)
		(width 0.18288)
		(layer "In2.Cu")
		(net "M_F_CPU0_SB_CA<0>")
	)
	(arc
		(start 377.263914 -256.03708)
		(mid 377.398847 -256.170434)
		(end 377.451112 -256.352802)
		(width 0.088646)
		(layer "In2.Cu")
		(net "M_F_CPU0_SB_CA<0>")
	)
	(arc
		(start 377.748546 -256.859532)
		(mid 377.99229 -256.926411)
		(end 378.240798 -256.88036)
		(width 0.088646)
		(layer "In2.Cu")
		(net "M_F_CPU0_SB_CA<0>")
	)
	(arc
		(start 376.981466 -255.557528)
		(mid 377.059577 -255.834477)
		(end 377.263914 -256.03708)
		(width 0.088646)
		(layer "In2.Cu")
		(net "M_F_CPU0_SB_CA<0>")
	)
	(arc
		(start 377.451112 -256.361438)
		(mid 377.525103 -256.641004)
		(end 377.727718 -256.84734)
		(width 0.088646)
		(layer "In2.Cu")
		(net "M_F_CPU0_SB_CA<0>")
	)
	(arc
		(start 377.921012 -253.919736)
		(mid 377.873333 -254.102636)
		(end 377.74245 -254.239014)
		(width 0.088646)
		(layer "In2.Cu")
		(net "M_F_CPU0_SB_CA<0>")
	)
	(arc
		(start 377.26366 -255.05791)
		(mid 377.062378 -255.255397)
		(end 376.981466 -255.525524)
		(width 0.088646)
		(layer "In2.Cu")
		(net "M_F_CPU0_SB_CA<0>")
	)
	(arc
		(start 377.451112 -254.733552)
		(mid 377.403433 -254.916452)
		(end 377.27255 -255.05283)
		(width 0.088646)
		(layer "In2.Cu")
		(net "M_F_CPU0_SB_CA<0>")
	)
	(arc
		(start 377.73356 -254.244094)
		(mid 377.529225 -254.446699)
		(end 377.451112 -254.723646)
		(width 0.088646)
		(layer "In2.Cu")
		(net "M_F_CPU0_SB_CA<0>")
	)
	(segment
		(start 421.840914 -244.066568)
		(end 420.736014 -244.066568)
		(width 0.20066)
		(layer "F.Cu")
		(net "M_F_CPU0_SA_RSP<1>")
	)
	(segment
		(start 376.606562 -253.383796)
		(end 376.606562 -253.919736)
		(width 0.20066)
		(layer "F.Cu")
		(net "M_F_CPU0_SA_RSP<1>")
	)
	(segment
		(start 401.54733 -248.880122)
		(end 401.54733 -248.610882)
		(width 0.18288)
		(layer "In6.Cu")
		(net "M_F_CPU0_SA_RSP<1>")
	)
	(segment
		(start 408.934666 -246.976646)
		(end 408.250898 -247.660414)
		(width 0.18288)
		(layer "In6.Cu")
		(net "M_F_CPU0_SA_RSP<1>")
	)
	(segment
		(start 378.006864 -250.872244)
		(end 376.541792 -252.337316)
		(width 0.18288)
		(layer "In6.Cu")
		(net "M_F_CPU0_SA_RSP<1>")
	)
	(segment
		(start 406.987756 -248.405396)
		(end 406.660096 -248.405396)
		(width 0.18288)
		(layer "In6.Cu")
		(net "M_F_CPU0_SA_RSP<1>")
	)
	(segment
		(start 405.211534 -248.11101)
		(end 403.401276 -248.11101)
		(width 0.18288)
		(layer "In6.Cu")
		(net "M_F_CPU0_SA_RSP<1>")
	)
	(segment
		(start 417.889182 -245.040658)
		(end 416.710876 -245.040658)
		(width 0.18288)
		(layer "In6.Cu")
		(net "M_F_CPU0_SA_RSP<1>")
	)
	(segment
		(start 400.85391 -248.880122)
		(end 400.67103 -249.063002)
		(width 0.18288)
		(layer "In6.Cu")
		(net "M_F_CPU0_SA_RSP<1>")
	)
	(segment
		(start 400.16049 -248.880122)
		(end 400.16049 -248.610882)
		(width 0.18288)
		(layer "In6.Cu")
		(net "M_F_CPU0_SA_RSP<1>")
	)
	(segment
		(start 401.73021 -249.063002)
		(end 401.54733 -248.880122)
		(width 0.18288)
		(layer "In6.Cu")
		(net "M_F_CPU0_SA_RSP<1>")
	)
	(segment
		(start 406.477216 -247.843294)
		(end 406.294336 -247.660414)
		(width 0.18288)
		(layer "In6.Cu")
		(net "M_F_CPU0_SA_RSP<1>")
	)
	(segment
		(start 398.08023 -248.880122)
		(end 397.89735 -249.063002)
		(width 0.18288)
		(layer "In6.Cu")
		(net "M_F_CPU0_SA_RSP<1>")
	)
	(segment
		(start 403.080474 -248.431812)
		(end 402.73351 -248.431812)
		(width 0.18288)
		(layer "In6.Cu")
		(net "M_F_CPU0_SA_RSP<1>")
	)
	(segment
		(start 407.353516 -247.660414)
		(end 407.170636 -247.843294)
		(width 0.18288)
		(layer "In6.Cu")
		(net "M_F_CPU0_SA_RSP<1>")
	)
	(segment
		(start 414.30956 -245.387114)
		(end 414.080198 -245.387114)
		(width 0.18288)
		(layer "In6.Cu")
		(net "M_F_CPU0_SA_RSP<1>")
	)
	(segment
		(start 418.350954 -244.578886)
		(end 417.889182 -245.040658)
		(width 0.18288)
		(layer "In6.Cu")
		(net "M_F_CPU0_SA_RSP<1>")
	)
	(segment
		(start 406.477216 -248.222516)
		(end 406.477216 -247.843294)
		(width 0.18288)
		(layer "In6.Cu")
		(net "M_F_CPU0_SA_RSP<1>")
	)
	(segment
		(start 410.510228 -247.159526)
		(end 410.327348 -246.976646)
		(width 0.18288)
		(layer "In6.Cu")
		(net "M_F_CPU0_SA_RSP<1>")
	)
	(segment
		(start 405.66213 -247.660414)
		(end 405.211534 -248.11101)
		(width 0.18288)
		(layer "In6.Cu")
		(net "M_F_CPU0_SA_RSP<1>")
	)
	(segment
		(start 414.67532 -246.384572)
		(end 414.49244 -246.201692)
		(width 0.18288)
		(layer "In6.Cu")
		(net "M_F_CPU0_SA_RSP<1>")
	)
	(segment
		(start 415.00298 -246.384572)
		(end 414.67532 -246.384572)
		(width 0.18288)
		(layer "In6.Cu")
		(net "M_F_CPU0_SA_RSP<1>")
	)
	(segment
		(start 415.36874 -245.387114)
		(end 415.18586 -245.569994)
		(width 0.18288)
		(layer "In6.Cu")
		(net "M_F_CPU0_SA_RSP<1>")
	)
	(segment
		(start 402.24075 -248.610882)
		(end 402.24075 -248.880122)
		(width 0.18288)
		(layer "In6.Cu")
		(net "M_F_CPU0_SA_RSP<1>")
	)
	(segment
		(start 411.386528 -246.976646)
		(end 411.203648 -247.159526)
		(width 0.18288)
		(layer "In6.Cu")
		(net "M_F_CPU0_SA_RSP<1>")
	)
	(segment
		(start 411.020768 -247.651524)
		(end 410.693108 -247.651524)
		(width 0.18288)
		(layer "In6.Cu")
		(net "M_F_CPU0_SA_RSP<1>")
	)
	(segment
		(start 397.89735 -249.063002)
		(end 397.56969 -249.063002)
		(width 0.18288)
		(layer "In6.Cu")
		(net "M_F_CPU0_SA_RSP<1>")
	)
	(segment
		(start 397.38681 -248.610882)
		(end 397.20393 -248.428002)
		(width 0.18288)
		(layer "In6.Cu")
		(net "M_F_CPU0_SA_RSP<1>")
	)
	(segment
		(start 389.471154 -250.872244)
		(end 378.006864 -250.872244)
		(width 0.18288)
		(layer "In6.Cu")
		(net "M_F_CPU0_SA_RSP<1>")
	)
	(segment
		(start 400.67103 -249.063002)
		(end 400.34337 -249.063002)
		(width 0.18288)
		(layer "In6.Cu")
		(net "M_F_CPU0_SA_RSP<1>")
	)
	(segment
		(start 397.20393 -248.428002)
		(end 391.915396 -248.428002)
		(width 0.18288)
		(layer "In6.Cu")
		(net "M_F_CPU0_SA_RSP<1>")
	)
	(segment
		(start 401.36445 -248.428002)
		(end 401.03679 -248.428002)
		(width 0.18288)
		(layer "In6.Cu")
		(net "M_F_CPU0_SA_RSP<1>")
	)
	(segment
		(start 414.49244 -246.201692)
		(end 414.49244 -245.569994)
		(width 0.18288)
		(layer "In6.Cu")
		(net "M_F_CPU0_SA_RSP<1>")
	)
	(segment
		(start 399.97761 -248.428002)
		(end 399.64995 -248.428002)
		(width 0.18288)
		(layer "In6.Cu")
		(net "M_F_CPU0_SA_RSP<1>")
	)
	(segment
		(start 398.26311 -248.428002)
		(end 398.08023 -248.610882)
		(width 0.18288)
		(layer "In6.Cu")
		(net "M_F_CPU0_SA_RSP<1>")
	)
	(segment
		(start 403.401276 -248.11101)
		(end 403.080474 -248.431812)
		(width 0.18288)
		(layer "In6.Cu")
		(net "M_F_CPU0_SA_RSP<1>")
	)
	(segment
		(start 398.77365 -248.610882)
		(end 398.59077 -248.428002)
		(width 0.18288)
		(layer "In6.Cu")
		(net "M_F_CPU0_SA_RSP<1>")
	)
	(segment
		(start 416.36442 -245.387114)
		(end 415.36874 -245.387114)
		(width 0.18288)
		(layer "In6.Cu")
		(net "M_F_CPU0_SA_RSP<1>")
	)
	(segment
		(start 420.736014 -244.066568)
		(end 420.191692 -244.066568)
		(width 0.18288)
		(layer "In6.Cu")
		(net "M_F_CPU0_SA_RSP<1>")
	)
	(segment
		(start 410.510228 -247.468644)
		(end 410.510228 -247.159526)
		(width 0.18288)
		(layer "In6.Cu")
		(net "M_F_CPU0_SA_RSP<1>")
	)
	(segment
		(start 402.05787 -249.063002)
		(end 401.73021 -249.063002)
		(width 0.18288)
		(layer "In6.Cu")
		(net "M_F_CPU0_SA_RSP<1>")
	)
	(segment
		(start 398.77365 -248.880122)
		(end 398.77365 -248.610882)
		(width 0.18288)
		(layer "In6.Cu")
		(net "M_F_CPU0_SA_RSP<1>")
	)
	(segment
		(start 398.59077 -248.428002)
		(end 398.26311 -248.428002)
		(width 0.18288)
		(layer "In6.Cu")
		(net "M_F_CPU0_SA_RSP<1>")
	)
	(segment
		(start 376.541792 -253.854966)
		(end 376.606562 -253.919736)
		(width 0.18288)
		(layer "In6.Cu")
		(net "M_F_CPU0_SA_RSP<1>")
	)
	(segment
		(start 399.46707 -248.610882)
		(end 399.46707 -248.880122)
		(width 0.18288)
		(layer "In6.Cu")
		(net "M_F_CPU0_SA_RSP<1>")
	)
	(segment
		(start 402.42363 -248.428002)
		(end 402.24075 -248.610882)
		(width 0.18288)
		(layer "In6.Cu")
		(net "M_F_CPU0_SA_RSP<1>")
	)
	(segment
		(start 400.16049 -248.610882)
		(end 399.97761 -248.428002)
		(width 0.18288)
		(layer "In6.Cu")
		(net "M_F_CPU0_SA_RSP<1>")
	)
	(segment
		(start 402.24075 -248.880122)
		(end 402.05787 -249.063002)
		(width 0.18288)
		(layer "In6.Cu")
		(net "M_F_CPU0_SA_RSP<1>")
	)
	(segment
		(start 406.294336 -247.660414)
		(end 405.66213 -247.660414)
		(width 0.18288)
		(layer "In6.Cu")
		(net "M_F_CPU0_SA_RSP<1>")
	)
	(segment
		(start 398.95653 -249.063002)
		(end 398.77365 -248.880122)
		(width 0.18288)
		(layer "In6.Cu")
		(net "M_F_CPU0_SA_RSP<1>")
	)
	(segment
		(start 420.191692 -244.066568)
		(end 419.679374 -244.578886)
		(width 0.18288)
		(layer "In6.Cu")
		(net "M_F_CPU0_SA_RSP<1>")
	)
	(segment
		(start 414.080198 -245.387114)
		(end 413.430466 -246.036846)
		(width 0.18288)
		(layer "In6.Cu")
		(net "M_F_CPU0_SA_RSP<1>")
	)
	(segment
		(start 411.203648 -247.468644)
		(end 411.020768 -247.651524)
		(width 0.18288)
		(layer "In6.Cu")
		(net "M_F_CPU0_SA_RSP<1>")
	)
	(segment
		(start 416.710876 -245.040658)
		(end 416.36442 -245.387114)
		(width 0.18288)
		(layer "In6.Cu")
		(net "M_F_CPU0_SA_RSP<1>")
	)
	(segment
		(start 419.679374 -244.578886)
		(end 418.350954 -244.578886)
		(width 0.18288)
		(layer "In6.Cu")
		(net "M_F_CPU0_SA_RSP<1>")
	)
	(segment
		(start 407.170636 -248.222516)
		(end 406.987756 -248.405396)
		(width 0.18288)
		(layer "In6.Cu")
		(net "M_F_CPU0_SA_RSP<1>")
	)
	(segment
		(start 399.28419 -249.063002)
		(end 398.95653 -249.063002)
		(width 0.18288)
		(layer "In6.Cu")
		(net "M_F_CPU0_SA_RSP<1>")
	)
	(segment
		(start 410.327348 -246.976646)
		(end 408.934666 -246.976646)
		(width 0.18288)
		(layer "In6.Cu")
		(net "M_F_CPU0_SA_RSP<1>")
	)
	(segment
		(start 399.46707 -248.880122)
		(end 399.28419 -249.063002)
		(width 0.18288)
		(layer "In6.Cu")
		(net "M_F_CPU0_SA_RSP<1>")
	)
	(segment
		(start 397.38681 -248.880122)
		(end 397.38681 -248.610882)
		(width 0.18288)
		(layer "In6.Cu")
		(net "M_F_CPU0_SA_RSP<1>")
	)
	(segment
		(start 401.54733 -248.610882)
		(end 401.36445 -248.428002)
		(width 0.18288)
		(layer "In6.Cu")
		(net "M_F_CPU0_SA_RSP<1>")
	)
	(segment
		(start 400.34337 -249.063002)
		(end 400.16049 -248.880122)
		(width 0.18288)
		(layer "In6.Cu")
		(net "M_F_CPU0_SA_RSP<1>")
	)
	(segment
		(start 412.138114 -246.976646)
		(end 411.386528 -246.976646)
		(width 0.18288)
		(layer "In6.Cu")
		(net "M_F_CPU0_SA_RSP<1>")
	)
	(segment
		(start 406.660096 -248.405396)
		(end 406.477216 -248.222516)
		(width 0.18288)
		(layer "In6.Cu")
		(net "M_F_CPU0_SA_RSP<1>")
	)
	(segment
		(start 414.49244 -245.569994)
		(end 414.30956 -245.387114)
		(width 0.18288)
		(layer "In6.Cu")
		(net "M_F_CPU0_SA_RSP<1>")
	)
	(segment
		(start 413.430466 -246.036846)
		(end 413.077914 -246.036846)
		(width 0.18288)
		(layer "In6.Cu")
		(net "M_F_CPU0_SA_RSP<1>")
	)
	(segment
		(start 413.077914 -246.036846)
		(end 412.138114 -246.976646)
		(width 0.18288)
		(layer "In6.Cu")
		(net "M_F_CPU0_SA_RSP<1>")
	)
	(segment
		(start 399.64995 -248.428002)
		(end 399.46707 -248.610882)
		(width 0.18288)
		(layer "In6.Cu")
		(net "M_F_CPU0_SA_RSP<1>")
	)
	(segment
		(start 415.18586 -246.201692)
		(end 415.00298 -246.384572)
		(width 0.18288)
		(layer "In6.Cu")
		(net "M_F_CPU0_SA_RSP<1>")
	)
	(segment
		(start 408.250898 -247.660414)
		(end 407.353516 -247.660414)
		(width 0.18288)
		(layer "In6.Cu")
		(net "M_F_CPU0_SA_RSP<1>")
	)
	(segment
		(start 407.170636 -247.843294)
		(end 407.170636 -248.222516)
		(width 0.18288)
		(layer "In6.Cu")
		(net "M_F_CPU0_SA_RSP<1>")
	)
	(segment
		(start 376.541792 -252.337316)
		(end 376.541792 -253.854966)
		(width 0.18288)
		(layer "In6.Cu")
		(net "M_F_CPU0_SA_RSP<1>")
	)
	(segment
		(start 415.18586 -245.569994)
		(end 415.18586 -246.201692)
		(width 0.18288)
		(layer "In6.Cu")
		(net "M_F_CPU0_SA_RSP<1>")
	)
	(segment
		(start 391.915396 -248.428002)
		(end 389.471154 -250.872244)
		(width 0.18288)
		(layer "In6.Cu")
		(net "M_F_CPU0_SA_RSP<1>")
	)
	(segment
		(start 402.73351 -248.431812)
		(end 402.7297 -248.428002)
		(width 0.18288)
		(layer "In6.Cu")
		(net "M_F_CPU0_SA_RSP<1>")
	)
	(segment
		(start 398.08023 -248.610882)
		(end 398.08023 -248.880122)
		(width 0.18288)
		(layer "In6.Cu")
		(net "M_F_CPU0_SA_RSP<1>")
	)
	(segment
		(start 410.693108 -247.651524)
		(end 410.510228 -247.468644)
		(width 0.18288)
		(layer "In6.Cu")
		(net "M_F_CPU0_SA_RSP<1>")
	)
	(segment
		(start 397.56969 -249.063002)
		(end 397.38681 -248.880122)
		(width 0.18288)
		(layer "In6.Cu")
		(net "M_F_CPU0_SA_RSP<1>")
	)
	(segment
		(start 402.7297 -248.428002)
		(end 402.42363 -248.428002)
		(width 0.18288)
		(layer "In6.Cu")
		(net "M_F_CPU0_SA_RSP<1>")
	)
	(segment
		(start 411.203648 -247.159526)
		(end 411.203648 -247.468644)
		(width 0.18288)
		(layer "In6.Cu")
		(net "M_F_CPU0_SA_RSP<1>")
	)
	(segment
		(start 401.03679 -248.428002)
		(end 400.85391 -248.610882)
		(width 0.18288)
		(layer "In6.Cu")
		(net "M_F_CPU0_SA_RSP<1>")
	)
	(segment
		(start 400.85391 -248.610882)
		(end 400.85391 -248.880122)
		(width 0.18288)
		(layer "In6.Cu")
		(net "M_F_CPU0_SA_RSP<1>")
	)
	(segment
		(start 428.254414 -244.066568)
		(end 429.384714 -244.066568)
		(width 0.20066)
		(layer "F.Cu")
		(net "M_F_CPU0_SA_RSP<0>")
	)
	(segment
		(start 376.136916 -254.733298)
		(end 376.136662 -254.733552)
		(width 0.20066)
		(layer "F.Cu")
		(net "M_F_CPU0_SA_RSP<0>")
	)
	(segment
		(start 376.136916 -254.197612)
		(end 376.136916 -254.733298)
		(width 0.20066)
		(layer "F.Cu")
		(net "M_F_CPU0_SA_RSP<0>")
	)
	(segment
		(start 422.41851 -245.34241)
		(end 421.568626 -246.192294)
		(width 0.18288)
		(layer "In6.Cu")
		(net "M_F_CPU0_SA_RSP<0>")
	)
	(segment
		(start 416.578034 -246.893334)
		(end 415.681414 -247.789954)
		(width 0.18288)
		(layer "In6.Cu")
		(net "M_F_CPU0_SA_RSP<0>")
	)
	(segment
		(start 377.506992 -252.477016)
		(end 377.506992 -253.2126)
		(width 0.18288)
		(layer "In6.Cu")
		(net "M_F_CPU0_SA_RSP<0>")
	)
	(segment
		(start 378.441204 -251.542804)
		(end 377.506992 -252.477016)
		(width 0.18288)
		(layer "In6.Cu")
		(net "M_F_CPU0_SA_RSP<0>")
	)
	(segment
		(start 408.261312 -249.449844)
		(end 403.993096 -249.449844)
		(width 0.18288)
		(layer "In6.Cu")
		(net "M_F_CPU0_SA_RSP<0>")
	)
	(segment
		(start 425.96181 -245.34241)
		(end 422.41851 -245.34241)
		(width 0.18288)
		(layer "In6.Cu")
		(net "M_F_CPU0_SA_RSP<0>")
	)
	(segment
		(start 411.637988 -248.66981)
		(end 411.487366 -248.820432)
		(width 0.18288)
		(layer "In6.Cu")
		(net "M_F_CPU0_SA_RSP<0>")
	)
	(segment
		(start 426.677074 -244.627146)
		(end 425.96181 -245.34241)
		(width 0.18288)
		(layer "In6.Cu")
		(net "M_F_CPU0_SA_RSP<0>")
	)
	(segment
		(start 411.487366 -248.820432)
		(end 410.35732 -248.820432)
		(width 0.18288)
		(layer "In6.Cu")
		(net "M_F_CPU0_SA_RSP<0>")
	)
	(segment
		(start 377.506992 -253.411736)
		(end 377.171966 -253.746762)
		(width 0.088646)
		(layer "In6.Cu")
		(net "M_F_CPU0_SA_RSP<0>")
	)
	(segment
		(start 403.370034 -250.072906)
		(end 396.66291 -250.072906)
		(width 0.18288)
		(layer "In6.Cu")
		(net "M_F_CPU0_SA_RSP<0>")
	)
	(segment
		(start 377.171966 -253.746762)
		(end 377.171966 -253.919736)
		(width 0.088646)
		(layer "In6.Cu")
		(net "M_F_CPU0_SA_RSP<0>")
	)
	(segment
		(start 376.89536 -254.405638)
		(end 376.50293 -254.634492)
		(width 0.088646)
		(layer "In6.Cu")
		(net "M_F_CPU0_SA_RSP<0>")
	)
	(segment
		(start 421.568626 -246.192294)
		(end 420.024306 -246.192294)
		(width 0.18288)
		(layer "In6.Cu")
		(net "M_F_CPU0_SA_RSP<0>")
	)
	(segment
		(start 410.184854 -248.647966)
		(end 409.06319 -248.647966)
		(width 0.18288)
		(layer "In6.Cu")
		(net "M_F_CPU0_SA_RSP<0>")
	)
	(segment
		(start 392.818112 -249.26925)
		(end 390.544558 -251.542804)
		(width 0.18288)
		(layer "In6.Cu")
		(net "M_F_CPU0_SA_RSP<0>")
	)
	(segment
		(start 417.888166 -246.893334)
		(end 416.578034 -246.893334)
		(width 0.18288)
		(layer "In6.Cu")
		(net "M_F_CPU0_SA_RSP<0>")
	)
	(segment
		(start 413.018986 -247.789954)
		(end 412.13913 -248.66981)
		(width 0.18288)
		(layer "In6.Cu")
		(net "M_F_CPU0_SA_RSP<0>")
	)
	(segment
		(start 427.693836 -244.627146)
		(end 426.677074 -244.627146)
		(width 0.18288)
		(layer "In6.Cu")
		(net "M_F_CPU0_SA_RSP<0>")
	)
	(segment
		(start 420.024306 -246.192294)
		(end 419.824154 -246.392446)
		(width 0.18288)
		(layer "In6.Cu")
		(net "M_F_CPU0_SA_RSP<0>")
	)
	(segment
		(start 412.13913 -248.66981)
		(end 411.637988 -248.66981)
		(width 0.18288)
		(layer "In6.Cu")
		(net "M_F_CPU0_SA_RSP<0>")
	)
	(segment
		(start 410.35732 -248.820432)
		(end 410.184854 -248.647966)
		(width 0.18288)
		(layer "In6.Cu")
		(net "M_F_CPU0_SA_RSP<0>")
	)
	(segment
		(start 418.389054 -246.392446)
		(end 417.888166 -246.893334)
		(width 0.18288)
		(layer "In6.Cu")
		(net "M_F_CPU0_SA_RSP<0>")
	)
	(segment
		(start 403.993096 -249.449844)
		(end 403.370034 -250.072906)
		(width 0.18288)
		(layer "In6.Cu")
		(net "M_F_CPU0_SA_RSP<0>")
	)
	(segment
		(start 415.681414 -247.789954)
		(end 413.018986 -247.789954)
		(width 0.18288)
		(layer "In6.Cu")
		(net "M_F_CPU0_SA_RSP<0>")
	)
	(segment
		(start 390.544558 -251.542804)
		(end 378.441204 -251.542804)
		(width 0.18288)
		(layer "In6.Cu")
		(net "M_F_CPU0_SA_RSP<0>")
	)
	(segment
		(start 409.06319 -248.647966)
		(end 408.261312 -249.449844)
		(width 0.18288)
		(layer "In6.Cu")
		(net "M_F_CPU0_SA_RSP<0>")
	)
	(segment
		(start 395.859254 -249.26925)
		(end 392.818112 -249.26925)
		(width 0.18288)
		(layer "In6.Cu")
		(net "M_F_CPU0_SA_RSP<0>")
	)
	(segment
		(start 428.254414 -244.066568)
		(end 427.693836 -244.627146)
		(width 0.18288)
		(layer "In6.Cu")
		(net "M_F_CPU0_SA_RSP<0>")
	)
	(segment
		(start 419.824154 -246.392446)
		(end 418.389054 -246.392446)
		(width 0.18288)
		(layer "In6.Cu")
		(net "M_F_CPU0_SA_RSP<0>")
	)
	(segment
		(start 396.66291 -250.072906)
		(end 395.859254 -249.26925)
		(width 0.18288)
		(layer "In6.Cu")
		(net "M_F_CPU0_SA_RSP<0>")
	)
	(segment
		(start 377.506992 -253.2126)
		(end 377.506992 -253.411736)
		(width 0.088646)
		(layer "In6.Cu")
		(net "M_F_CPU0_SA_RSP<0>")
	)
	(arc
		(start 377.171966 -253.919736)
		(mid 377.097975 -254.199302)
		(end 376.89536 -254.405638)
		(width 0.088646)
		(layer "In6.Cu")
		(net "M_F_CPU0_SA_RSP<0>")
	)
	(arc
		(start 376.50293 -254.634492)
		(mid 376.32637 -254.708321)
		(end 376.136662 -254.733552)
		(width 0.088646)
		(layer "In6.Cu")
		(net "M_F_CPU0_SA_RSP<0>")
	)
	(segment
		(start 426.951394 -258.95427)
		(end 427.505876 -258.95427)
		(width 0.20066)
		(layer "F.Cu")
		(net "M_F_CPU0_SA_PAR")
	)
	(segment
		(start 379.896116 -256.361184)
		(end 379.895862 -256.361438)
		(width 0.20066)
		(layer "F.Cu")
		(net "M_F_CPU0_SA_PAR")
	)
	(segment
		(start 427.918372 -259.366766)
		(end 429.384714 -259.366766)
		(width 0.20066)
		(layer "F.Cu")
		(net "M_F_CPU0_SA_PAR")
	)
	(segment
		(start 426.938948 -258.941824)
		(end 426.951394 -258.95427)
		(width 0.1016)
		(layer "F.Cu")
		(net "M_F_CPU0_SA_PAR")
	)
	(segment
		(start 424.763946 -258.941824)
		(end 426.938948 -258.941824)
		(width 0.1016)
		(layer "F.Cu")
		(net "M_F_CPU0_SA_PAR")
	)
	(segment
		(start 421.840914 -259.366766)
		(end 422.728644 -259.366766)
		(width 0.20066)
		(layer "F.Cu")
		(net "M_F_CPU0_SA_PAR")
	)
	(segment
		(start 423.620946 -258.474464)
		(end 423.997374 -258.474464)
		(width 0.20066)
		(layer "F.Cu")
		(net "M_F_CPU0_SA_PAR")
	)
	(segment
		(start 422.728644 -259.366766)
		(end 423.620946 -258.474464)
		(width 0.20066)
		(layer "F.Cu")
		(net "M_F_CPU0_SA_PAR")
	)
	(segment
		(start 424.743626 -258.941824)
		(end 424.763946 -258.941824)
		(width 0.101854)
		(layer "F.Cu")
		(net "M_F_CPU0_SA_PAR")
	)
	(segment
		(start 427.505876 -258.95427)
		(end 427.918372 -259.366766)
		(width 0.20066)
		(layer "F.Cu")
		(net "M_F_CPU0_SA_PAR")
	)
	(segment
		(start 424.464734 -258.941824)
		(end 424.743626 -258.941824)
		(width 0.20066)
		(layer "F.Cu")
		(net "M_F_CPU0_SA_PAR")
	)
	(segment
		(start 423.997374 -258.474464)
		(end 424.464734 -258.941824)
		(width 0.20066)
		(layer "F.Cu")
		(net "M_F_CPU0_SA_PAR")
	)
	(segment
		(start 379.896116 -255.825498)
		(end 379.896116 -256.361184)
		(width 0.20066)
		(layer "F.Cu")
		(net "M_F_CPU0_SA_PAR")
	)
	(segment
		(start 420.736014 -259.366766)
		(end 421.840914 -259.366766)
		(width 0.20066)
		(layer "F.Cu")
		(net "M_F_CPU0_SA_PAR")
	)
	(segment
		(start 422.541192 -259.950204)
		(end 422.900348 -259.591048)
		(width 0.18288)
		(layer "In2.Cu")
		(net "M_F_CPU0_SA_PAR")
	)
	(segment
		(start 381.210312 -256.351532)
		(end 381.210312 -256.361438)
		(width 0.088646)
		(layer "In2.Cu")
		(net "M_F_CPU0_SA_PAR")
	)
	(segment
		(start 387.994652 -255.084326)
		(end 387.968998 -255.10998)
		(width 0.088646)
		(layer "In2.Cu")
		(net "M_F_CPU0_SA_PAR")
	)
	(segment
		(start 381.50165 -255.8669)
		(end 381.49276 -255.87198)
		(width 0.088646)
		(layer "In2.Cu")
		(net "M_F_CPU0_SA_PAR")
	)
	(segment
		(start 420.736014 -259.366766)
		(end 420.879778 -259.71373)
		(width 0.18288)
		(layer "In2.Cu")
		(net "M_F_CPU0_SA_PAR")
	)
	(segment
		(start 422.900348 -259.132324)
		(end 422.441116 -258.673092)
		(width 0.18288)
		(layer "In2.Cu")
		(net "M_F_CPU0_SA_PAR")
	)
	(segment
		(start 388.459218 -255.084326)
		(end 387.994652 -255.084326)
		(width 0.088646)
		(layer "In2.Cu")
		(net "M_F_CPU0_SA_PAR")
	)
	(segment
		(start 422.441116 -258.673092)
		(end 420.500556 -257.960114)
		(width 0.18288)
		(layer "In2.Cu")
		(net "M_F_CPU0_SA_PAR")
	)
	(segment
		(start 396.280386 -255.222248)
		(end 395.402816 -255.585722)
		(width 0.18288)
		(layer "In2.Cu")
		(net "M_F_CPU0_SA_PAR")
	)
	(segment
		(start 385.347464 -255.05791)
		(end 385.332732 -255.049274)
		(width 0.088646)
		(layer "In2.Cu")
		(net "M_F_CPU0_SA_PAR")
	)
	(segment
		(start 420.500556 -257.960114)
		(end 415.862262 -257.070352)
		(width 0.18288)
		(layer "In2.Cu")
		(net "M_F_CPU0_SA_PAR")
	)
	(segment
		(start 379.739652 -256.632456)
		(end 379.832108 -256.472182)
		(width 0.088646)
		(layer "In2.Cu")
		(net "M_F_CPU0_SA_PAR")
	)
	(segment
		(start 421.116252 -259.950204)
		(end 422.541192 -259.950204)
		(width 0.18288)
		(layer "In2.Cu")
		(net "M_F_CPU0_SA_PAR")
	)
	(segment
		(start 407.587196 -257.070352)
		(end 403.125178 -255.222248)
		(width 0.18288)
		(layer "In2.Cu")
		(net "M_F_CPU0_SA_PAR")
	)
	(segment
		(start 415.862262 -257.070352)
		(end 407.587196 -257.070352)
		(width 0.18288)
		(layer "In2.Cu")
		(net "M_F_CPU0_SA_PAR")
	)
	(segment
		(start 395.402816 -255.585722)
		(end 391.882122 -255.585722)
		(width 0.18288)
		(layer "In2.Cu")
		(net "M_F_CPU0_SA_PAR")
	)
	(segment
		(start 379.832108 -256.472182)
		(end 379.895862 -256.361438)
		(width 0.088646)
		(layer "In2.Cu")
		(net "M_F_CPU0_SA_PAR")
	)
	(segment
		(start 379.760734 -256.710434)
		(end 379.739652 -256.632456)
		(width 0.088646)
		(layer "In2.Cu")
		(net "M_F_CPU0_SA_PAR")
	)
	(segment
		(start 420.879778 -259.71373)
		(end 421.116252 -259.950204)
		(width 0.18288)
		(layer "In2.Cu")
		(net "M_F_CPU0_SA_PAR")
	)
	(segment
		(start 381.03175 -256.680716)
		(end 381.02286 -256.685796)
		(width 0.088646)
		(layer "In2.Cu")
		(net "M_F_CPU0_SA_PAR")
	)
	(segment
		(start 386.489702 -254.981964)
		(end 386.004816 -254.981964)
		(width 0.088646)
		(layer "In2.Cu")
		(net "M_F_CPU0_SA_PAR")
	)
	(segment
		(start 391.882122 -255.585722)
		(end 389.360664 -255.084326)
		(width 0.18288)
		(layer "In2.Cu")
		(net "M_F_CPU0_SA_PAR")
	)
	(segment
		(start 382.528064 -255.05791)
		(end 382.513332 -255.049274)
		(width 0.088646)
		(layer "In2.Cu")
		(net "M_F_CPU0_SA_PAR")
	)
	(segment
		(start 386.617718 -255.10998)
		(end 386.489702 -254.981964)
		(width 0.088646)
		(layer "In2.Cu")
		(net "M_F_CPU0_SA_PAR")
	)
	(segment
		(start 380.08306 -256.685796)
		(end 380.08306 -256.68605)
		(width 0.088646)
		(layer "In2.Cu")
		(net "M_F_CPU0_SA_PAR")
	)
	(segment
		(start 389.360664 -255.084326)
		(end 388.459218 -255.084326)
		(width 0.18288)
		(layer "In2.Cu")
		(net "M_F_CPU0_SA_PAR")
	)
	(segment
		(start 422.900348 -259.591048)
		(end 422.900348 -259.132324)
		(width 0.18288)
		(layer "In2.Cu")
		(net "M_F_CPU0_SA_PAR")
	)
	(segment
		(start 403.125178 -255.222248)
		(end 396.280386 -255.222248)
		(width 0.18288)
		(layer "In2.Cu")
		(net "M_F_CPU0_SA_PAR")
	)
	(segment
		(start 387.968998 -255.10998)
		(end 386.617718 -255.10998)
		(width 0.088646)
		(layer "In2.Cu")
		(net "M_F_CPU0_SA_PAR")
	)
	(segment
		(start 381.680212 -255.533398)
		(end 381.680212 -255.547622)
		(width 0.088646)
		(layer "In2.Cu")
		(net "M_F_CPU0_SA_PAR")
	)
	(arc
		(start 384.407664 -255.05791)
		(mid 384.124962 -254.982168)
		(end 383.84226 -255.05791)
		(width 0.088646)
		(layer "In2.Cu")
		(net "M_F_CPU0_SA_PAR")
	)
	(arc
		(start 382.90246 -255.05791)
		(mid 382.715262 -255.108053)
		(end 382.528064 -255.05791)
		(width 0.088646)
		(layer "In2.Cu")
		(net "M_F_CPU0_SA_PAR")
	)
	(arc
		(start 382.513332 -255.049274)
		(mid 382.236891 -254.982108)
		(end 381.96266 -255.05791)
		(width 0.088646)
		(layer "In2.Cu")
		(net "M_F_CPU0_SA_PAR")
	)
	(arc
		(start 381.96266 -255.05791)
		(mid 381.759355 -255.258776)
		(end 381.680212 -255.533398)
		(width 0.088646)
		(layer "In2.Cu")
		(net "M_F_CPU0_SA_PAR")
	)
	(arc
		(start 383.467864 -255.05791)
		(mid 383.185162 -254.982168)
		(end 382.90246 -255.05791)
		(width 0.088646)
		(layer "In2.Cu")
		(net "M_F_CPU0_SA_PAR")
	)
	(arc
		(start 385.332732 -255.049274)
		(mid 385.056257 -254.981954)
		(end 384.78206 -255.05791)
		(width 0.088646)
		(layer "In2.Cu")
		(net "M_F_CPU0_SA_PAR")
	)
	(arc
		(start 381.49276 -255.87198)
		(mid 381.288425 -256.074585)
		(end 381.210312 -256.351532)
		(width 0.088646)
		(layer "In2.Cu")
		(net "M_F_CPU0_SA_PAR")
	)
	(arc
		(start 385.72186 -255.05791)
		(mid 385.534662 -255.108053)
		(end 385.347464 -255.05791)
		(width 0.088646)
		(layer "In2.Cu")
		(net "M_F_CPU0_SA_PAR")
	)
	(arc
		(start 381.210312 -256.361438)
		(mid 381.162633 -256.544338)
		(end 381.03175 -256.680716)
		(width 0.088646)
		(layer "In2.Cu")
		(net "M_F_CPU0_SA_PAR")
	)
	(arc
		(start 386.004816 -254.981964)
		(mid 385.858329 -255.001279)
		(end 385.72186 -255.05791)
		(width 0.088646)
		(layer "In2.Cu")
		(net "M_F_CPU0_SA_PAR")
	)
	(arc
		(start 383.84226 -255.05791)
		(mid 383.655062 -255.108053)
		(end 383.467864 -255.05791)
		(width 0.088646)
		(layer "In2.Cu")
		(net "M_F_CPU0_SA_PAR")
	)
	(arc
		(start 381.02286 -256.685796)
		(mid 380.835662 -256.735939)
		(end 380.648464 -256.685796)
		(width 0.088646)
		(layer "In2.Cu")
		(net "M_F_CPU0_SA_PAR")
	)
	(arc
		(start 380.648464 -256.685796)
		(mid 380.365762 -256.61002)
		(end 380.08306 -256.685796)
		(width 0.088646)
		(layer "In2.Cu")
		(net "M_F_CPU0_SA_PAR")
	)
	(arc
		(start 381.680212 -255.547622)
		(mid 381.632533 -255.730522)
		(end 381.50165 -255.8669)
		(width 0.088646)
		(layer "In2.Cu")
		(net "M_F_CPU0_SA_PAR")
	)
	(arc
		(start 380.08306 -256.68605)
		(mid 379.924661 -256.734836)
		(end 379.760734 -256.710434)
		(width 0.088646)
		(layer "In2.Cu")
		(net "M_F_CPU0_SA_PAR")
	)
	(arc
		(start 384.78206 -255.05791)
		(mid 384.594862 -255.108053)
		(end 384.407664 -255.05791)
		(width 0.088646)
		(layer "In2.Cu")
		(net "M_F_CPU0_SA_PAR")
	)
	(segment
		(start 428.367952 -273.384518)
		(end 428.375064 -273.39163)
		(width 0.1016)
		(layer "F.Cu")
		(net "M_F_CPU0_SA_DQS_DP<9>")
	)
	(segment
		(start 426.534326 -273.816572)
		(end 426.785532 -274.067778)
		(width 0.20066)
		(layer "F.Cu")
		(net "M_F_CPU0_SA_DQS_DP<9>")
	)
	(segment
		(start 428.363126 -273.384518)
		(end 428.367952 -273.384518)
		(width 0.101854)
		(layer "F.Cu")
		(net "M_F_CPU0_SA_DQS_DP<9>")
	)
	(segment
		(start 432.916838 -273.816572)
		(end 433.484782 -273.816572)
		(width 0.20066)
		(layer "F.Cu")
		(net "M_F_CPU0_SA_DQS_DP<9>")
	)
	(segment
		(start 430.716944 -273.384264)
		(end 430.97196 -273.63928)
		(width 0.20066)
		(layer "F.Cu")
		(net "M_F_CPU0_SA_DQS_DP<9>")
	)
	(segment
		(start 430.38776 -273.39163)
		(end 430.395126 -273.384264)
		(width 0.1016)
		(layer "F.Cu")
		(net "M_F_CPU0_SA_DQS_DP<9>")
	)
	(segment
		(start 427.515274 -273.642836)
		(end 427.793658 -273.642836)
		(width 0.20066)
		(layer "F.Cu")
		(net "M_F_CPU0_SA_DQS_DP<9>")
	)
	(segment
		(start 382.715516 -262.336534)
		(end 382.715516 -262.87222)
		(width 0.20066)
		(layer "F.Cu")
		(net "M_F_CPU0_SA_DQS_DP<9>")
	)
	(segment
		(start 382.715516 -262.87222)
		(end 382.715262 -262.872474)
		(width 0.20066)
		(layer "F.Cu")
		(net "M_F_CPU0_SA_DQS_DP<9>")
	)
	(segment
		(start 427.793658 -273.642836)
		(end 428.051976 -273.384518)
		(width 0.20066)
		(layer "F.Cu")
		(net "M_F_CPU0_SA_DQS_DP<9>")
	)
	(segment
		(start 425.940982 -273.816572)
		(end 426.534326 -273.816572)
		(width 0.20066)
		(layer "F.Cu")
		(net "M_F_CPU0_SA_DQS_DP<9>")
	)
	(segment
		(start 424.836082 -273.816572)
		(end 425.940982 -273.816572)
		(width 0.20066)
		(layer "F.Cu")
		(net "M_F_CPU0_SA_DQS_DP<9>")
	)
	(segment
		(start 426.785532 -274.067778)
		(end 427.090332 -274.067778)
		(width 0.20066)
		(layer "F.Cu")
		(net "M_F_CPU0_SA_DQS_DP<9>")
	)
	(segment
		(start 427.090332 -274.067778)
		(end 427.515274 -273.642836)
		(width 0.20066)
		(layer "F.Cu")
		(net "M_F_CPU0_SA_DQS_DP<9>")
	)
	(segment
		(start 431.625502 -273.63928)
		(end 432.071018 -274.084796)
		(width 0.20066)
		(layer "F.Cu")
		(net "M_F_CPU0_SA_DQS_DP<9>")
	)
	(segment
		(start 430.97196 -273.63928)
		(end 431.625502 -273.63928)
		(width 0.20066)
		(layer "F.Cu")
		(net "M_F_CPU0_SA_DQS_DP<9>")
	)
	(segment
		(start 428.375064 -273.39163)
		(end 430.38776 -273.39163)
		(width 0.1016)
		(layer "F.Cu")
		(net "M_F_CPU0_SA_DQS_DP<9>")
	)
	(segment
		(start 430.395126 -273.384264)
		(end 430.716944 -273.384264)
		(width 0.20066)
		(layer "F.Cu")
		(net "M_F_CPU0_SA_DQS_DP<9>")
	)
	(segment
		(start 432.071018 -274.084796)
		(end 432.648614 -274.084796)
		(width 0.20066)
		(layer "F.Cu")
		(net "M_F_CPU0_SA_DQS_DP<9>")
	)
	(segment
		(start 432.648614 -274.084796)
		(end 432.916838 -273.816572)
		(width 0.20066)
		(layer "F.Cu")
		(net "M_F_CPU0_SA_DQS_DP<9>")
	)
	(segment
		(start 428.051976 -273.384518)
		(end 428.363126 -273.384518)
		(width 0.20066)
		(layer "F.Cu")
		(net "M_F_CPU0_SA_DQS_DP<9>")
	)
	(segment
		(start 407.81732 -272.47469)
		(end 407.801064 -272.47469)
		(width 0.16002)
		(layer "In2.Cu")
		(net "M_F_CPU0_SA_DQS_DP<9>")
	)
	(segment
		(start 421.184324 -273.608038)
		(end 421.042338 -273.469862)
		(width 0.18288)
		(layer "In2.Cu")
		(net "M_F_CPU0_SA_DQS_DP<9>")
	)
	(segment
		(start 404.620476 -271.820894)
		(end 403.927564 -270.149828)
		(width 0.18288)
		(layer "In2.Cu")
		(net "M_F_CPU0_SA_DQS_DP<9>")
	)
	(segment
		(start 393.058904 -262.825484)
		(end 391.96772 -262.373618)
		(width 0.18288)
		(layer "In2.Cu")
		(net "M_F_CPU0_SA_DQS_DP<9>")
	)
	(segment
		(start 411.716982 -273.124168)
		(end 411.688788 -273.095974)
		(width 0.16002)
		(layer "In2.Cu")
		(net "M_F_CPU0_SA_DQS_DP<9>")
	)
	(segment
		(start 419.158166 -273.021552)
		(end 417.644834 -273.021552)
		(width 0.18288)
		(layer "In2.Cu")
		(net "M_F_CPU0_SA_DQS_DP<9>")
	)
	(segment
		(start 409.074874 -272.79473)
		(end 408.648662 -272.79473)
		(width 0.18288)
		(layer "In2.Cu")
		(net "M_F_CPU0_SA_DQS_DP<9>")
	)
	(segment
		(start 407.58872 -272.24609)
		(end 407.287476 -271.944846)
		(width 0.18288)
		(layer "In2.Cu")
		(net "M_F_CPU0_SA_DQS_DP<9>")
	)
	(segment
		(start 384.060192 -262.552434)
		(end 383.868168 -262.552434)
		(width 0.088646)
		(layer "In2.Cu")
		(net "M_F_CPU0_SA_DQS_DP<9>")
	)
	(segment
		(start 424.615356 -274.037298)
		(end 422.773348 -274.037298)
		(width 0.18288)
		(layer "In2.Cu")
		(net "M_F_CPU0_SA_DQS_DP<9>")
	)
	(segment
		(start 411.421072 -272.828258)
		(end 409.998672 -272.828258)
		(width 0.18288)
		(layer "In2.Cu")
		(net "M_F_CPU0_SA_DQS_DP<9>")
	)
	(segment
		(start 407.287476 -271.944846)
		(end 405.900636 -271.944846)
		(width 0.18288)
		(layer "In2.Cu")
		(net "M_F_CPU0_SA_DQS_DP<9>")
	)
	(segment
		(start 415.421572 -273.378168)
		(end 415.127186 -273.672554)
		(width 0.18288)
		(layer "In2.Cu")
		(net "M_F_CPU0_SA_DQS_DP<9>")
	)
	(segment
		(start 424.836082 -273.816572)
		(end 424.615356 -274.037298)
		(width 0.18288)
		(layer "In2.Cu")
		(net "M_F_CPU0_SA_DQS_DP<9>")
	)
	(segment
		(start 384.14706 -262.47852)
		(end 384.060192 -262.552434)
		(width 0.088646)
		(layer "In2.Cu")
		(net "M_F_CPU0_SA_DQS_DP<9>")
	)
	(segment
		(start 421.042338 -273.469862)
		(end 420.961312 -273.391122)
		(width 0.18288)
		(layer "In2.Cu")
		(net "M_F_CPU0_SA_DQS_DP<9>")
	)
	(segment
		(start 383.86385 -262.548116)
		(end 383.84226 -262.548116)
		(width 0.088646)
		(layer "In2.Cu")
		(net "M_F_CPU0_SA_DQS_DP<9>")
	)
	(segment
		(start 383.868168 -262.552434)
		(end 383.86385 -262.548116)
		(width 0.088646)
		(layer "In2.Cu")
		(net "M_F_CPU0_SA_DQS_DP<9>")
	)
	(segment
		(start 411.945582 -273.352768)
		(end 411.917388 -273.324574)
		(width 0.16002)
		(layer "In2.Cu")
		(net "M_F_CPU0_SA_DQS_DP<9>")
	)
	(segment
		(start 407.801064 -272.47469)
		(end 407.616914 -272.29054)
		(width 0.16002)
		(layer "In2.Cu")
		(net "M_F_CPU0_SA_DQS_DP<9>")
	)
	(segment
		(start 417.026852 -273.639534)
		(end 416.140392 -273.639534)
		(width 0.18288)
		(layer "In2.Cu")
		(net "M_F_CPU0_SA_DQS_DP<9>")
	)
	(segment
		(start 411.917388 -273.324574)
		(end 411.901132 -273.324574)
		(width 0.16002)
		(layer "In2.Cu")
		(net "M_F_CPU0_SA_DQS_DP<9>")
	)
	(segment
		(start 420.96055 -273.392138)
		(end 420.492936 -273.392138)
		(width 0.18288)
		(layer "In2.Cu")
		(net "M_F_CPU0_SA_DQS_DP<9>")
	)
	(segment
		(start 422.773348 -274.037298)
		(end 421.737282 -273.608038)
		(width 0.18288)
		(layer "In2.Cu")
		(net "M_F_CPU0_SA_DQS_DP<9>")
	)
	(segment
		(start 420.261034 -273.62404)
		(end 419.760654 -273.62404)
		(width 0.18288)
		(layer "In2.Cu")
		(net "M_F_CPU0_SA_DQS_DP<9>")
	)
	(segment
		(start 411.688788 -273.095974)
		(end 411.421072 -272.828258)
		(width 0.18288)
		(layer "In2.Cu")
		(net "M_F_CPU0_SA_DQS_DP<9>")
	)
	(segment
		(start 419.560248 -273.423634)
		(end 419.543992 -273.423634)
		(width 0.16002)
		(layer "In2.Cu")
		(net "M_F_CPU0_SA_DQS_DP<9>")
	)
	(segment
		(start 407.616914 -272.29054)
		(end 407.616914 -272.274284)
		(width 0.16002)
		(layer "In2.Cu")
		(net "M_F_CPU0_SA_DQS_DP<9>")
	)
	(segment
		(start 408.407362 -272.55343)
		(end 407.89606 -272.55343)
		(width 0.18288)
		(layer "In2.Cu")
		(net "M_F_CPU0_SA_DQS_DP<9>")
	)
	(segment
		(start 407.616914 -272.274284)
		(end 407.58872 -272.24609)
		(width 0.16002)
		(layer "In2.Cu")
		(net "M_F_CPU0_SA_DQS_DP<9>")
	)
	(segment
		(start 413.557212 -273.672554)
		(end 413.262826 -273.378168)
		(width 0.18288)
		(layer "In2.Cu")
		(net "M_F_CPU0_SA_DQS_DP<9>")
	)
	(segment
		(start 419.359842 -273.223228)
		(end 419.331648 -273.195034)
		(width 0.16002)
		(layer "In2.Cu")
		(net "M_F_CPU0_SA_DQS_DP<9>")
	)
	(segment
		(start 420.492936 -273.392138)
		(end 420.261034 -273.62404)
		(width 0.18288)
		(layer "In2.Cu")
		(net "M_F_CPU0_SA_DQS_DP<9>")
	)
	(segment
		(start 386.757164 -262.383016)
		(end 386.742432 -262.37438)
		(width 0.088646)
		(layer "In2.Cu")
		(net "M_F_CPU0_SA_DQS_DP<9>")
	)
	(segment
		(start 405.239982 -271.67967)
		(end 405.01316 -271.906492)
		(width 0.18288)
		(layer "In2.Cu")
		(net "M_F_CPU0_SA_DQS_DP<9>")
	)
	(segment
		(start 419.760654 -273.62404)
		(end 419.588442 -273.451828)
		(width 0.18288)
		(layer "In2.Cu")
		(net "M_F_CPU0_SA_DQS_DP<9>")
	)
	(segment
		(start 417.22802 -273.454622)
		(end 417.211764 -273.454622)
		(width 0.16002)
		(layer "In2.Cu")
		(net "M_F_CPU0_SA_DQS_DP<9>")
	)
	(segment
		(start 383.467864 -262.548116)
		(end 383.439924 -262.564372)
		(width 0.088646)
		(layer "In2.Cu")
		(net "M_F_CPU0_SA_DQS_DP<9>")
	)
	(segment
		(start 388.780528 -262.433562)
		(end 387.884162 -262.433562)
		(width 0.088646)
		(layer "In2.Cu")
		(net "M_F_CPU0_SA_DQS_DP<9>")
	)
	(segment
		(start 419.359842 -273.239484)
		(end 419.359842 -273.223228)
		(width 0.16002)
		(layer "In2.Cu")
		(net "M_F_CPU0_SA_DQS_DP<9>")
	)
	(segment
		(start 419.588442 -273.451828)
		(end 419.560248 -273.423634)
		(width 0.16002)
		(layer "In2.Cu")
		(net "M_F_CPU0_SA_DQS_DP<9>")
	)
	(segment
		(start 408.648662 -272.79473)
		(end 408.407362 -272.55343)
		(width 0.18288)
		(layer "In2.Cu")
		(net "M_F_CPU0_SA_DQS_DP<9>")
	)
	(segment
		(start 395.142212 -264.909046)
		(end 393.058904 -262.825484)
		(width 0.18288)
		(layer "In2.Cu")
		(net "M_F_CPU0_SA_DQS_DP<9>")
	)
	(segment
		(start 404.70582 -271.906492)
		(end 404.620476 -271.820894)
		(width 0.18288)
		(layer "In2.Cu")
		(net "M_F_CPU0_SA_DQS_DP<9>")
	)
	(segment
		(start 398.686782 -264.909046)
		(end 395.142212 -264.909046)
		(width 0.18288)
		(layer "In2.Cu")
		(net "M_F_CPU0_SA_DQS_DP<9>")
	)
	(segment
		(start 405.01316 -271.906492)
		(end 404.70582 -271.906492)
		(width 0.18288)
		(layer "In2.Cu")
		(net "M_F_CPU0_SA_DQS_DP<9>")
	)
	(segment
		(start 411.901132 -273.324574)
		(end 411.716982 -273.140424)
		(width 0.16002)
		(layer "In2.Cu")
		(net "M_F_CPU0_SA_DQS_DP<9>")
	)
	(segment
		(start 388.840472 -262.373618)
		(end 388.780528 -262.433562)
		(width 0.088646)
		(layer "In2.Cu")
		(net "M_F_CPU0_SA_DQS_DP<9>")
	)
	(segment
		(start 407.89606 -272.55343)
		(end 407.845514 -272.502884)
		(width 0.18288)
		(layer "In2.Cu")
		(net "M_F_CPU0_SA_DQS_DP<9>")
	)
	(segment
		(start 412.246318 -273.653504)
		(end 411.945582 -273.352768)
		(width 0.18288)
		(layer "In2.Cu")
		(net "M_F_CPU0_SA_DQS_DP<9>")
	)
	(segment
		(start 419.331648 -273.195034)
		(end 419.158166 -273.021552)
		(width 0.18288)
		(layer "In2.Cu")
		(net "M_F_CPU0_SA_DQS_DP<9>")
	)
	(segment
		(start 409.34005 -272.529554)
		(end 409.074874 -272.79473)
		(width 0.18288)
		(layer "In2.Cu")
		(net "M_F_CPU0_SA_DQS_DP<9>")
	)
	(segment
		(start 405.63546 -271.67967)
		(end 405.239982 -271.67967)
		(width 0.18288)
		(layer "In2.Cu")
		(net "M_F_CPU0_SA_DQS_DP<9>")
	)
	(segment
		(start 391.96772 -262.373618)
		(end 388.840472 -262.373618)
		(width 0.18288)
		(layer "In2.Cu")
		(net "M_F_CPU0_SA_DQS_DP<9>")
	)
	(segment
		(start 419.543992 -273.423634)
		(end 419.359842 -273.239484)
		(width 0.16002)
		(layer "In2.Cu")
		(net "M_F_CPU0_SA_DQS_DP<9>")
	)
	(segment
		(start 416.140392 -273.639534)
		(end 415.879026 -273.378168)
		(width 0.18288)
		(layer "In2.Cu")
		(net "M_F_CPU0_SA_DQS_DP<9>")
	)
	(segment
		(start 405.900636 -271.944846)
		(end 405.63546 -271.67967)
		(width 0.18288)
		(layer "In2.Cu")
		(net "M_F_CPU0_SA_DQS_DP<9>")
	)
	(segment
		(start 412.530036 -273.653504)
		(end 412.246318 -273.653504)
		(width 0.18288)
		(layer "In2.Cu")
		(net "M_F_CPU0_SA_DQS_DP<9>")
	)
	(segment
		(start 421.737282 -273.608038)
		(end 421.184324 -273.608038)
		(width 0.18288)
		(layer "In2.Cu")
		(net "M_F_CPU0_SA_DQS_DP<9>")
	)
	(segment
		(start 417.41217 -273.254216)
		(end 417.41217 -273.270472)
		(width 0.16002)
		(layer "In2.Cu")
		(net "M_F_CPU0_SA_DQS_DP<9>")
	)
	(segment
		(start 417.41217 -273.270472)
		(end 417.22802 -273.454622)
		(width 0.16002)
		(layer "In2.Cu")
		(net "M_F_CPU0_SA_DQS_DP<9>")
	)
	(segment
		(start 417.211764 -273.454622)
		(end 417.18357 -273.482816)
		(width 0.16002)
		(layer "In2.Cu")
		(net "M_F_CPU0_SA_DQS_DP<9>")
	)
	(segment
		(start 383.439924 -262.564372)
		(end 382.715262 -262.872474)
		(width 0.088646)
		(layer "In2.Cu")
		(net "M_F_CPU0_SA_DQS_DP<9>")
	)
	(segment
		(start 412.805372 -273.378168)
		(end 412.530036 -273.653504)
		(width 0.18288)
		(layer "In2.Cu")
		(net "M_F_CPU0_SA_DQS_DP<9>")
	)
	(segment
		(start 417.440364 -273.226022)
		(end 417.41217 -273.254216)
		(width 0.16002)
		(layer "In2.Cu")
		(net "M_F_CPU0_SA_DQS_DP<9>")
	)
	(segment
		(start 413.262826 -273.378168)
		(end 412.805372 -273.378168)
		(width 0.18288)
		(layer "In2.Cu")
		(net "M_F_CPU0_SA_DQS_DP<9>")
	)
	(segment
		(start 415.127186 -273.672554)
		(end 413.557212 -273.672554)
		(width 0.18288)
		(layer "In2.Cu")
		(net "M_F_CPU0_SA_DQS_DP<9>")
	)
	(segment
		(start 417.644834 -273.021552)
		(end 417.440364 -273.226022)
		(width 0.18288)
		(layer "In2.Cu")
		(net "M_F_CPU0_SA_DQS_DP<9>")
	)
	(segment
		(start 411.716982 -273.140424)
		(end 411.716982 -273.124168)
		(width 0.16002)
		(layer "In2.Cu")
		(net "M_F_CPU0_SA_DQS_DP<9>")
	)
	(segment
		(start 403.927564 -270.149828)
		(end 398.686782 -264.909046)
		(width 0.18288)
		(layer "In2.Cu")
		(net "M_F_CPU0_SA_DQS_DP<9>")
	)
	(segment
		(start 409.699968 -272.529554)
		(end 409.34005 -272.529554)
		(width 0.18288)
		(layer "In2.Cu")
		(net "M_F_CPU0_SA_DQS_DP<9>")
	)
	(segment
		(start 384.31216 -262.383016)
		(end 384.14706 -262.47852)
		(width 0.088646)
		(layer "In2.Cu")
		(net "M_F_CPU0_SA_DQS_DP<9>")
	)
	(segment
		(start 417.18357 -273.482816)
		(end 417.026852 -273.639534)
		(width 0.18288)
		(layer "In2.Cu")
		(net "M_F_CPU0_SA_DQS_DP<9>")
	)
	(segment
		(start 407.845514 -272.502884)
		(end 407.81732 -272.47469)
		(width 0.16002)
		(layer "In2.Cu")
		(net "M_F_CPU0_SA_DQS_DP<9>")
	)
	(segment
		(start 415.879026 -273.378168)
		(end 415.421572 -273.378168)
		(width 0.18288)
		(layer "In2.Cu")
		(net "M_F_CPU0_SA_DQS_DP<9>")
	)
	(segment
		(start 420.961312 -273.391122)
		(end 420.96055 -273.392138)
		(width 0.18288)
		(layer "In2.Cu")
		(net "M_F_CPU0_SA_DQS_DP<9>")
	)
	(segment
		(start 409.998672 -272.828258)
		(end 409.699968 -272.529554)
		(width 0.18288)
		(layer "In2.Cu")
		(net "M_F_CPU0_SA_DQS_DP<9>")
	)
	(arc
		(start 385.25196 -262.383016)
		(mid 385.064762 -262.433159)
		(end 384.877564 -262.383016)
		(width 0.088646)
		(layer "In2.Cu")
		(net "M_F_CPU0_SA_DQS_DP<9>")
	)
	(arc
		(start 386.742432 -262.37438)
		(mid 386.465957 -262.30706)
		(end 386.19176 -262.383016)
		(width 0.088646)
		(layer "In2.Cu")
		(net "M_F_CPU0_SA_DQS_DP<9>")
	)
	(arc
		(start 383.84226 -262.548116)
		(mid 383.655062 -262.497973)
		(end 383.467864 -262.548116)
		(width 0.088646)
		(layer "In2.Cu")
		(net "M_F_CPU0_SA_DQS_DP<9>")
	)
	(arc
		(start 387.13156 -262.383016)
		(mid 386.944362 -262.433159)
		(end 386.757164 -262.383016)
		(width 0.088646)
		(layer "In2.Cu")
		(net "M_F_CPU0_SA_DQS_DP<9>")
	)
	(arc
		(start 384.877564 -262.383016)
		(mid 384.594862 -262.30724)
		(end 384.31216 -262.383016)
		(width 0.088646)
		(layer "In2.Cu")
		(net "M_F_CPU0_SA_DQS_DP<9>")
	)
	(arc
		(start 385.817364 -262.383016)
		(mid 385.534662 -262.30724)
		(end 385.25196 -262.383016)
		(width 0.088646)
		(layer "In2.Cu")
		(net "M_F_CPU0_SA_DQS_DP<9>")
	)
	(arc
		(start 386.19176 -262.383016)
		(mid 386.004562 -262.433159)
		(end 385.817364 -262.383016)
		(width 0.088646)
		(layer "In2.Cu")
		(net "M_F_CPU0_SA_DQS_DP<9>")
	)
	(arc
		(start 387.682232 -262.37438)
		(mid 387.405757 -262.30706)
		(end 387.13156 -262.383016)
		(width 0.088646)
		(layer "In2.Cu")
		(net "M_F_CPU0_SA_DQS_DP<9>")
	)
	(arc
		(start 387.884162 -262.433562)
		(mid 387.778961 -262.418425)
		(end 387.682232 -262.37438)
		(width 0.088646)
		(layer "In2.Cu")
		(net "M_F_CPU0_SA_DQS_DP<9>")
	)
	(segment
		(start 426.534326 -283.166566)
		(end 426.785532 -283.417772)
		(width 0.20066)
		(layer "F.Cu")
		(net "M_F_CPU0_SA_DQS_DP<8>")
	)
	(segment
		(start 432.071018 -283.43479)
		(end 432.648614 -283.43479)
		(width 0.20066)
		(layer "F.Cu")
		(net "M_F_CPU0_SA_DQS_DP<8>")
	)
	(segment
		(start 430.395126 -282.734258)
		(end 430.716944 -282.734258)
		(width 0.20066)
		(layer "F.Cu")
		(net "M_F_CPU0_SA_DQS_DP<8>")
	)
	(segment
		(start 428.051976 -282.734512)
		(end 428.363126 -282.734512)
		(width 0.20066)
		(layer "F.Cu")
		(net "M_F_CPU0_SA_DQS_DP<8>")
	)
	(segment
		(start 430.716944 -282.734258)
		(end 430.97196 -282.989274)
		(width 0.20066)
		(layer "F.Cu")
		(net "M_F_CPU0_SA_DQS_DP<8>")
	)
	(segment
		(start 427.515274 -282.99283)
		(end 427.793658 -282.99283)
		(width 0.20066)
		(layer "F.Cu")
		(net "M_F_CPU0_SA_DQS_DP<8>")
	)
	(segment
		(start 430.38776 -282.741624)
		(end 430.395126 -282.734258)
		(width 0.1016)
		(layer "F.Cu")
		(net "M_F_CPU0_SA_DQS_DP<8>")
	)
	(segment
		(start 424.836082 -283.166566)
		(end 425.940982 -283.166566)
		(width 0.20066)
		(layer "F.Cu")
		(net "M_F_CPU0_SA_DQS_DP<8>")
	)
	(segment
		(start 427.793658 -282.99283)
		(end 428.051976 -282.734512)
		(width 0.20066)
		(layer "F.Cu")
		(net "M_F_CPU0_SA_DQS_DP<8>")
	)
	(segment
		(start 427.090332 -283.417772)
		(end 427.515274 -282.99283)
		(width 0.20066)
		(layer "F.Cu")
		(net "M_F_CPU0_SA_DQS_DP<8>")
	)
	(segment
		(start 379.426216 -259.895086)
		(end 379.426216 -260.430772)
		(width 0.20066)
		(layer "F.Cu")
		(net "M_F_CPU0_SA_DQS_DP<8>")
	)
	(segment
		(start 431.625502 -282.989274)
		(end 432.071018 -283.43479)
		(width 0.20066)
		(layer "F.Cu")
		(net "M_F_CPU0_SA_DQS_DP<8>")
	)
	(segment
		(start 432.916838 -283.166566)
		(end 433.484782 -283.166566)
		(width 0.20066)
		(layer "F.Cu")
		(net "M_F_CPU0_SA_DQS_DP<8>")
	)
	(segment
		(start 379.425962 -259.894832)
		(end 379.426216 -259.895086)
		(width 0.20066)
		(layer "F.Cu")
		(net "M_F_CPU0_SA_DQS_DP<8>")
	)
	(segment
		(start 430.97196 -282.989274)
		(end 431.625502 -282.989274)
		(width 0.20066)
		(layer "F.Cu")
		(net "M_F_CPU0_SA_DQS_DP<8>")
	)
	(segment
		(start 428.367952 -282.734512)
		(end 428.375064 -282.741624)
		(width 0.1016)
		(layer "F.Cu")
		(net "M_F_CPU0_SA_DQS_DP<8>")
	)
	(segment
		(start 432.648614 -283.43479)
		(end 432.916838 -283.166566)
		(width 0.20066)
		(layer "F.Cu")
		(net "M_F_CPU0_SA_DQS_DP<8>")
	)
	(segment
		(start 426.785532 -283.417772)
		(end 427.090332 -283.417772)
		(width 0.20066)
		(layer "F.Cu")
		(net "M_F_CPU0_SA_DQS_DP<8>")
	)
	(segment
		(start 428.363126 -282.734512)
		(end 428.367952 -282.734512)
		(width 0.101854)
		(layer "F.Cu")
		(net "M_F_CPU0_SA_DQS_DP<8>")
	)
	(segment
		(start 428.375064 -282.741624)
		(end 430.38776 -282.741624)
		(width 0.1016)
		(layer "F.Cu")
		(net "M_F_CPU0_SA_DQS_DP<8>")
	)
	(segment
		(start 425.940982 -283.166566)
		(end 426.534326 -283.166566)
		(width 0.20066)
		(layer "F.Cu")
		(net "M_F_CPU0_SA_DQS_DP<8>")
	)
	(segment
		(start 389.656828 -259.93217)
		(end 386.808218 -259.93217)
		(width 0.18288)
		(layer "In4.Cu")
		(net "M_F_CPU0_SA_DQS_DP<8>")
	)
	(segment
		(start 386.78485 -259.93217)
		(end 386.72516 -259.99186)
		(width 0.088646)
		(layer "In4.Cu")
		(net "M_F_CPU0_SA_DQS_DP<8>")
	)
	(segment
		(start 386.808218 -259.93217)
		(end 386.78485 -259.93217)
		(width 0.088646)
		(layer "In4.Cu")
		(net "M_F_CPU0_SA_DQS_DP<8>")
	)
	(segment
		(start 382.536954 -259.946648)
		(end 382.528572 -259.941822)
		(width 0.088646)
		(layer "In4.Cu")
		(net "M_F_CPU0_SA_DQS_DP<8>")
	)
	(segment
		(start 386.72516 -259.99186)
		(end 386.473954 -259.99186)
		(width 0.088646)
		(layer "In4.Cu")
		(net "M_F_CPU0_SA_DQS_DP<8>")
	)
	(segment
		(start 420.842694 -282.74264)
		(end 420.842694 -282.742386)
		(width 0.18288)
		(layer "In4.Cu")
		(net "M_F_CPU0_SA_DQS_DP<8>")
	)
	(segment
		(start 420.842694 -282.742386)
		(end 420.614094 -282.742386)
		(width 0.18288)
		(layer "In4.Cu")
		(net "M_F_CPU0_SA_DQS_DP<8>")
	)
	(segment
		(start 420.614094 -282.74264)
		(end 420.525194 -282.74264)
		(width 0.18288)
		(layer "In4.Cu")
		(net "M_F_CPU0_SA_DQS_DP<8>")
	)
	(segment
		(start 379.938788 -260.430772)
		(end 379.426216 -260.430772)
		(width 0.088646)
		(layer "In4.Cu")
		(net "M_F_CPU0_SA_DQS_DP<8>")
	)
	(segment
		(start 420.248588 -283.019246)
		(end 419.75532 -283.019246)
		(width 0.18288)
		(layer "In4.Cu")
		(net "M_F_CPU0_SA_DQS_DP<8>")
	)
	(segment
		(start 420.614094 -282.742386)
		(end 420.614094 -282.74264)
		(width 0.18288)
		(layer "In4.Cu")
		(net "M_F_CPU0_SA_DQS_DP<8>")
	)
	(segment
		(start 411.700726 -271.979136)
		(end 409.355798 -271.979136)
		(width 0.18288)
		(layer "In4.Cu")
		(net "M_F_CPU0_SA_DQS_DP<8>")
	)
	(segment
		(start 416.69589 -274.547076)
		(end 415.445956 -274.298156)
		(width 0.18288)
		(layer "In4.Cu")
		(net "M_F_CPU0_SA_DQS_DP<8>")
	)
	(segment
		(start 409.355798 -271.979136)
		(end 408.672284 -271.295368)
		(width 0.18288)
		(layer "In4.Cu")
		(net "M_F_CPU0_SA_DQS_DP<8>")
	)
	(segment
		(start 406.116028 -270.265906)
		(end 405.843232 -269.99311)
		(width 0.18288)
		(layer "In4.Cu")
		(net "M_F_CPU0_SA_DQS_DP<8>")
	)
	(segment
		(start 420.525194 -282.74264)
		(end 420.248588 -283.019246)
		(width 0.18288)
		(layer "In4.Cu")
		(net "M_F_CPU0_SA_DQS_DP<8>")
	)
	(segment
		(start 413.576516 -272.757392)
		(end 413.576516 -272.757138)
		(width 0.18288)
		(layer "In4.Cu")
		(net "M_F_CPU0_SA_DQS_DP<8>")
	)
	(segment
		(start 419.75532 -283.019246)
		(end 419.425374 -282.882086)
		(width 0.18288)
		(layer "In4.Cu")
		(net "M_F_CPU0_SA_DQS_DP<8>")
	)
	(segment
		(start 381.587756 -259.941314)
		(end 381.587756 -259.941568)
		(width 0.088646)
		(layer "In4.Cu")
		(net "M_F_CPU0_SA_DQS_DP<8>")
	)
	(segment
		(start 384.419602 -259.948934)
		(end 384.40741 -259.941822)
		(width 0.088646)
		(layer "In4.Cu")
		(net "M_F_CPU0_SA_DQS_DP<8>")
	)
	(segment
		(start 385.722114 -259.941568)
		(end 385.72186 -259.941568)
		(width 0.088646)
		(layer "In4.Cu")
		(net "M_F_CPU0_SA_DQS_DP<8>")
	)
	(segment
		(start 393.866878 -261.876032)
		(end 393.018264 -261.522972)
		(width 0.18288)
		(layer "In4.Cu")
		(net "M_F_CPU0_SA_DQS_DP<8>")
	)
	(segment
		(start 384.40741 -259.941822)
		(end 384.396742 -259.935472)
		(width 0.088646)
		(layer "In4.Cu")
		(net "M_F_CPU0_SA_DQS_DP<8>")
	)
	(segment
		(start 405.175974 -269.99311)
		(end 397.058896 -261.876032)
		(width 0.18288)
		(layer "In4.Cu")
		(net "M_F_CPU0_SA_DQS_DP<8>")
	)
	(segment
		(start 423.945812 -283.589476)
		(end 422.081706 -283.589476)
		(width 0.18288)
		(layer "In4.Cu")
		(net "M_F_CPU0_SA_DQS_DP<8>")
	)
	(segment
		(start 413.576516 -272.757138)
		(end 411.700726 -271.979136)
		(width 0.18288)
		(layer "In4.Cu")
		(net "M_F_CPU0_SA_DQS_DP<8>")
	)
	(segment
		(start 421.513762 -283.021532)
		(end 421.210994 -283.021532)
		(width 0.18288)
		(layer "In4.Cu")
		(net "M_F_CPU0_SA_DQS_DP<8>")
	)
	(segment
		(start 380.178818 -260.106414)
		(end 380.169928 -260.111494)
		(width 0.088646)
		(layer "In4.Cu")
		(net "M_F_CPU0_SA_DQS_DP<8>")
	)
	(segment
		(start 415.445956 -274.298156)
		(end 414.137602 -272.989802)
		(width 0.18288)
		(layer "In4.Cu")
		(net "M_F_CPU0_SA_DQS_DP<8>")
	)
	(segment
		(start 414.137602 -272.989802)
		(end 413.576516 -272.757392)
		(width 0.18288)
		(layer "In4.Cu")
		(net "M_F_CPU0_SA_DQS_DP<8>")
	)
	(segment
		(start 417.696904 -275.060918)
		(end 417.527994 -274.892008)
		(width 0.18288)
		(layer "In4.Cu")
		(net "M_F_CPU0_SA_DQS_DP<8>")
	)
	(segment
		(start 405.843232 -269.99311)
		(end 405.175974 -269.99311)
		(width 0.18288)
		(layer "In4.Cu")
		(net "M_F_CPU0_SA_DQS_DP<8>")
	)
	(segment
		(start 420.932102 -282.74264)
		(end 420.842694 -282.74264)
		(width 0.18288)
		(layer "In4.Cu")
		(net "M_F_CPU0_SA_DQS_DP<8>")
	)
	(segment
		(start 406.47874 -270.265906)
		(end 406.116028 -270.265906)
		(width 0.18288)
		(layer "In4.Cu")
		(net "M_F_CPU0_SA_DQS_DP<8>")
	)
	(segment
		(start 418.379402 -277.705312)
		(end 417.996878 -275.783802)
		(width 0.18288)
		(layer "In4.Cu")
		(net "M_F_CPU0_SA_DQS_DP<8>")
	)
	(segment
		(start 392.685524 -261.190232)
		(end 389.656828 -259.93217)
		(width 0.18288)
		(layer "In4.Cu")
		(net "M_F_CPU0_SA_DQS_DP<8>")
	)
	(segment
		(start 380.913386 -260.004814)
		(end 380.806706 -260.033516)
		(width 0.088646)
		(layer "In4.Cu")
		(net "M_F_CPU0_SA_DQS_DP<8>")
	)
	(segment
		(start 419.425374 -282.882086)
		(end 419.142926 -282.599638)
		(width 0.18288)
		(layer "In4.Cu")
		(net "M_F_CPU0_SA_DQS_DP<8>")
	)
	(segment
		(start 424.565826 -283.436822)
		(end 424.314366 -283.436822)
		(width 0.18288)
		(layer "In4.Cu")
		(net "M_F_CPU0_SA_DQS_DP<8>")
	)
	(segment
		(start 424.836082 -283.166566)
		(end 424.565826 -283.436822)
		(width 0.18288)
		(layer "In4.Cu")
		(net "M_F_CPU0_SA_DQS_DP<8>")
	)
	(segment
		(start 408.672284 -271.295368)
		(end 406.684988 -270.4719)
		(width 0.18288)
		(layer "In4.Cu")
		(net "M_F_CPU0_SA_DQS_DP<8>")
	)
	(segment
		(start 380.806706 -260.033516)
		(end 380.372112 -260.033516)
		(width 0.088646)
		(layer "In4.Cu")
		(net "M_F_CPU0_SA_DQS_DP<8>")
	)
	(segment
		(start 417.996878 -275.783802)
		(end 417.696904 -275.060918)
		(width 0.18288)
		(layer "In4.Cu")
		(net "M_F_CPU0_SA_DQS_DP<8>")
	)
	(segment
		(start 397.058896 -261.876032)
		(end 393.866878 -261.876032)
		(width 0.18288)
		(layer "In4.Cu")
		(net "M_F_CPU0_SA_DQS_DP<8>")
	)
	(segment
		(start 379.995938 -260.373622)
		(end 379.938788 -260.430772)
		(width 0.088646)
		(layer "In4.Cu")
		(net "M_F_CPU0_SA_DQS_DP<8>")
	)
	(segment
		(start 418.379402 -280.757122)
		(end 418.379402 -277.705312)
		(width 0.18288)
		(layer "In4.Cu")
		(net "M_F_CPU0_SA_DQS_DP<8>")
	)
	(segment
		(start 419.142926 -282.599638)
		(end 418.379402 -280.757122)
		(width 0.18288)
		(layer "In4.Cu")
		(net "M_F_CPU0_SA_DQS_DP<8>")
	)
	(segment
		(start 417.527994 -274.892008)
		(end 416.69589 -274.547076)
		(width 0.18288)
		(layer "In4.Cu")
		(net "M_F_CPU0_SA_DQS_DP<8>")
	)
	(segment
		(start 421.210994 -283.021532)
		(end 420.932102 -282.74264)
		(width 0.18288)
		(layer "In4.Cu")
		(net "M_F_CPU0_SA_DQS_DP<8>")
	)
	(segment
		(start 422.081706 -283.589476)
		(end 421.513762 -283.021532)
		(width 0.18288)
		(layer "In4.Cu")
		(net "M_F_CPU0_SA_DQS_DP<8>")
	)
	(segment
		(start 406.684988 -270.4719)
		(end 406.47874 -270.265906)
		(width 0.18288)
		(layer "In4.Cu")
		(net "M_F_CPU0_SA_DQS_DP<8>")
	)
	(segment
		(start 393.018264 -261.522972)
		(end 392.685524 -261.190232)
		(width 0.18288)
		(layer "In4.Cu")
		(net "M_F_CPU0_SA_DQS_DP<8>")
	)
	(segment
		(start 383.480056 -259.948934)
		(end 383.468118 -259.941822)
		(width 0.088646)
		(layer "In4.Cu")
		(net "M_F_CPU0_SA_DQS_DP<8>")
	)
	(segment
		(start 424.314366 -283.436822)
		(end 423.945812 -283.589476)
		(width 0.18288)
		(layer "In4.Cu")
		(net "M_F_CPU0_SA_DQS_DP<8>")
	)
	(segment
		(start 385.359402 -259.948934)
		(end 385.347464 -259.941822)
		(width 0.088646)
		(layer "In4.Cu")
		(net "M_F_CPU0_SA_DQS_DP<8>")
	)
	(segment
		(start 381.5969 -259.946648)
		(end 381.588518 -259.941822)
		(width 0.088646)
		(layer "In4.Cu")
		(net "M_F_CPU0_SA_DQS_DP<8>")
	)
	(segment
		(start 381.023368 -259.941568)
		(end 380.913386 -260.004814)
		(width 0.088646)
		(layer "In4.Cu")
		(net "M_F_CPU0_SA_DQS_DP<8>")
	)
	(arc
		(start 382.902714 -259.941568)
		(mid 382.720492 -259.991768)
		(end 382.536954 -259.946648)
		(width 0.088646)
		(layer "In4.Cu")
		(net "M_F_CPU0_SA_DQS_DP<8>")
	)
	(arc
		(start 383.842514 -259.941568)
		(mid 383.662227 -259.99198)
		(end 383.480056 -259.948934)
		(width 0.088646)
		(layer "In4.Cu")
		(net "M_F_CPU0_SA_DQS_DP<8>")
	)
	(arc
		(start 386.286502 -259.941568)
		(mid 386.004308 -259.866012)
		(end 385.722114 -259.941568)
		(width 0.088646)
		(layer "In4.Cu")
		(net "M_F_CPU0_SA_DQS_DP<8>")
	)
	(arc
		(start 383.468118 -259.941822)
		(mid 383.185445 -259.865851)
		(end 382.902714 -259.941568)
		(width 0.088646)
		(layer "In4.Cu")
		(net "M_F_CPU0_SA_DQS_DP<8>")
	)
	(arc
		(start 381.588518 -259.941822)
		(mid 381.588137 -259.941568)
		(end 381.587756 -259.941314)
		(width 0.088646)
		(layer "In4.Cu")
		(net "M_F_CPU0_SA_DQS_DP<8>")
	)
	(arc
		(start 380.372112 -260.033516)
		(mid 380.323998 -260.039872)
		(end 380.279148 -260.058408)
		(width 0.088646)
		(layer "In4.Cu")
		(net "M_F_CPU0_SA_DQS_DP<8>")
	)
	(arc
		(start 380.228856 -260.082284)
		(mid 380.203387 -260.093417)
		(end 380.178818 -260.106414)
		(width 0.088646)
		(layer "In4.Cu")
		(net "M_F_CPU0_SA_DQS_DP<8>")
	)
	(arc
		(start 380.169928 -260.111494)
		(mid 380.054119 -260.223423)
		(end 379.995938 -260.373622)
		(width 0.088646)
		(layer "In4.Cu")
		(net "M_F_CPU0_SA_DQS_DP<8>")
	)
	(arc
		(start 381.956818 -259.945124)
		(mid 381.777053 -259.991898)
		(end 381.5969 -259.946648)
		(width 0.088646)
		(layer "In4.Cu")
		(net "M_F_CPU0_SA_DQS_DP<8>")
	)
	(arc
		(start 386.473954 -259.99186)
		(mid 386.376915 -259.979066)
		(end 386.286502 -259.941568)
		(width 0.088646)
		(layer "In4.Cu")
		(net "M_F_CPU0_SA_DQS_DP<8>")
	)
	(arc
		(start 381.963168 -259.941568)
		(mid 381.960002 -259.943362)
		(end 381.956818 -259.945124)
		(width 0.088646)
		(layer "In4.Cu")
		(net "M_F_CPU0_SA_DQS_DP<8>")
	)
	(arc
		(start 385.347464 -259.941822)
		(mid 385.064791 -259.865851)
		(end 384.78206 -259.941568)
		(width 0.088646)
		(layer "In4.Cu")
		(net "M_F_CPU0_SA_DQS_DP<8>")
	)
	(arc
		(start 384.78206 -259.941568)
		(mid 384.601773 -259.99198)
		(end 384.419602 -259.948934)
		(width 0.088646)
		(layer "In4.Cu")
		(net "M_F_CPU0_SA_DQS_DP<8>")
	)
	(arc
		(start 381.587756 -259.941568)
		(mid 381.305562 -259.866012)
		(end 381.023368 -259.941568)
		(width 0.088646)
		(layer "In4.Cu")
		(net "M_F_CPU0_SA_DQS_DP<8>")
	)
	(arc
		(start 380.279148 -260.058408)
		(mid 380.254443 -260.071275)
		(end 380.228856 -260.082284)
		(width 0.088646)
		(layer "In4.Cu")
		(net "M_F_CPU0_SA_DQS_DP<8>")
	)
	(arc
		(start 384.396742 -259.935472)
		(mid 384.118818 -259.86584)
		(end 383.842514 -259.941568)
		(width 0.088646)
		(layer "In4.Cu")
		(net "M_F_CPU0_SA_DQS_DP<8>")
	)
	(arc
		(start 385.72186 -259.941568)
		(mid 385.541573 -259.99198)
		(end 385.359402 -259.948934)
		(width 0.088646)
		(layer "In4.Cu")
		(net "M_F_CPU0_SA_DQS_DP<8>")
	)
	(arc
		(start 382.528572 -259.941822)
		(mid 382.245899 -259.865851)
		(end 381.963168 -259.941568)
		(width 0.088646)
		(layer "In4.Cu")
		(net "M_F_CPU0_SA_DQS_DP<8>")
	)
	(segment
		(start 432.648614 -292.784784)
		(end 432.071018 -292.784784)
		(width 0.20066)
		(layer "F.Cu")
		(net "M_F_CPU0_SA_DQS_DP<7>")
	)
	(segment
		(start 430.38776 -292.091872)
		(end 428.375064 -292.091872)
		(width 0.1016)
		(layer "F.Cu")
		(net "M_F_CPU0_SA_DQS_DP<7>")
	)
	(segment
		(start 430.97196 -292.339268)
		(end 430.717198 -292.084506)
		(width 0.20066)
		(layer "F.Cu")
		(net "M_F_CPU0_SA_DQS_DP<7>")
	)
	(segment
		(start 382.715516 -267.219938)
		(end 382.715516 -267.755624)
		(width 0.20066)
		(layer "F.Cu")
		(net "M_F_CPU0_SA_DQS_DP<7>")
	)
	(segment
		(start 427.793658 -292.342824)
		(end 427.515274 -292.342824)
		(width 0.20066)
		(layer "F.Cu")
		(net "M_F_CPU0_SA_DQS_DP<7>")
	)
	(segment
		(start 428.367952 -292.08476)
		(end 428.363126 -292.08476)
		(width 0.101854)
		(layer "F.Cu")
		(net "M_F_CPU0_SA_DQS_DP<7>")
	)
	(segment
		(start 433.484782 -292.516814)
		(end 432.916584 -292.516814)
		(width 0.20066)
		(layer "F.Cu")
		(net "M_F_CPU0_SA_DQS_DP<7>")
	)
	(segment
		(start 428.051722 -292.08476)
		(end 427.793658 -292.342824)
		(width 0.20066)
		(layer "F.Cu")
		(net "M_F_CPU0_SA_DQS_DP<7>")
	)
	(segment
		(start 431.625502 -292.339268)
		(end 430.97196 -292.339268)
		(width 0.20066)
		(layer "F.Cu")
		(net "M_F_CPU0_SA_DQS_DP<7>")
	)
	(segment
		(start 430.717198 -292.084506)
		(end 430.395126 -292.084506)
		(width 0.20066)
		(layer "F.Cu")
		(net "M_F_CPU0_SA_DQS_DP<7>")
	)
	(segment
		(start 428.363126 -292.08476)
		(end 428.051722 -292.08476)
		(width 0.20066)
		(layer "F.Cu")
		(net "M_F_CPU0_SA_DQS_DP<7>")
	)
	(segment
		(start 428.375064 -292.091872)
		(end 428.367952 -292.08476)
		(width 0.1016)
		(layer "F.Cu")
		(net "M_F_CPU0_SA_DQS_DP<7>")
	)
	(segment
		(start 426.53458 -292.516814)
		(end 425.940982 -292.516814)
		(width 0.20066)
		(layer "F.Cu")
		(net "M_F_CPU0_SA_DQS_DP<7>")
	)
	(segment
		(start 426.785532 -292.767766)
		(end 426.53458 -292.516814)
		(width 0.20066)
		(layer "F.Cu")
		(net "M_F_CPU0_SA_DQS_DP<7>")
	)
	(segment
		(start 430.395126 -292.084506)
		(end 430.38776 -292.091872)
		(width 0.1016)
		(layer "F.Cu")
		(net "M_F_CPU0_SA_DQS_DP<7>")
	)
	(segment
		(start 424.836082 -292.51656)
		(end 425.940728 -292.51656)
		(width 0.20066)
		(layer "F.Cu")
		(net "M_F_CPU0_SA_DQS_DP<7>")
	)
	(segment
		(start 425.940728 -292.51656)
		(end 425.940982 -292.516814)
		(width 0.20066)
		(layer "F.Cu")
		(net "M_F_CPU0_SA_DQS_DP<7>")
	)
	(segment
		(start 432.071018 -292.784784)
		(end 431.625502 -292.339268)
		(width 0.20066)
		(layer "F.Cu")
		(net "M_F_CPU0_SA_DQS_DP<7>")
	)
	(segment
		(start 427.090332 -292.767766)
		(end 426.785532 -292.767766)
		(width 0.20066)
		(layer "F.Cu")
		(net "M_F_CPU0_SA_DQS_DP<7>")
	)
	(segment
		(start 382.715516 -267.755624)
		(end 382.715262 -267.755878)
		(width 0.20066)
		(layer "F.Cu")
		(net "M_F_CPU0_SA_DQS_DP<7>")
	)
	(segment
		(start 432.916584 -292.516814)
		(end 432.648614 -292.784784)
		(width 0.20066)
		(layer "F.Cu")
		(net "M_F_CPU0_SA_DQS_DP<7>")
	)
	(segment
		(start 427.515274 -292.342824)
		(end 427.090332 -292.767766)
		(width 0.20066)
		(layer "F.Cu")
		(net "M_F_CPU0_SA_DQS_DP<7>")
	)
	(segment
		(start 424.645582 -292.70706)
		(end 424.208702 -292.70706)
		(width 0.18288)
		(layer "In2.Cu")
		(net "M_F_CPU0_SA_DQS_DP<7>")
	)
	(segment
		(start 405.267922 -282.739846)
		(end 405.002492 -283.005276)
		(width 0.18288)
		(layer "In2.Cu")
		(net "M_F_CPU0_SA_DQS_DP<7>")
	)
	(segment
		(start 416.23742 -286.950658)
		(end 415.488374 -286.201866)
		(width 0.18288)
		(layer "In2.Cu")
		(net "M_F_CPU0_SA_DQS_DP<7>")
	)
	(segment
		(start 422.07815 -292.3667)
		(end 421.24757 -292.3667)
		(width 0.18288)
		(layer "In2.Cu")
		(net "M_F_CPU0_SA_DQS_DP<7>")
	)
	(segment
		(start 422.693338 -292.621208)
		(end 422.07815 -292.3667)
		(width 0.18288)
		(layer "In2.Cu")
		(net "M_F_CPU0_SA_DQS_DP<7>")
	)
	(segment
		(start 411.673294 -286.120332)
		(end 411.48381 -286.309816)
		(width 0.18288)
		(layer "In2.Cu")
		(net "M_F_CPU0_SA_DQS_DP<7>")
	)
	(segment
		(start 416.808666 -289.98291)
		(end 417.012882 -289.489134)
		(width 0.18288)
		(layer "In2.Cu")
		(net "M_F_CPU0_SA_DQS_DP<7>")
	)
	(segment
		(start 390.625076 -267.42898)
		(end 388.840472 -267.42898)
		(width 0.18288)
		(layer "In2.Cu")
		(net "M_F_CPU0_SA_DQS_DP<7>")
	)
	(segment
		(start 410.639006 -286.309816)
		(end 410.014166 -286.05099)
		(width 0.18288)
		(layer "In2.Cu")
		(net "M_F_CPU0_SA_DQS_DP<7>")
	)
	(segment
		(start 417.012882 -289.489134)
		(end 417.012882 -288.823146)
		(width 0.18288)
		(layer "In2.Cu")
		(net "M_F_CPU0_SA_DQS_DP<7>")
	)
	(segment
		(start 413.312102 -286.004254)
		(end 413.312102 -286.02051)
		(width 0.16002)
		(layer "In2.Cu")
		(net "M_F_CPU0_SA_DQS_DP<7>")
	)
	(segment
		(start 417.157662 -290.826444)
		(end 416.808666 -289.98291)
		(width 0.18288)
		(layer "In2.Cu")
		(net "M_F_CPU0_SA_DQS_DP<7>")
	)
	(segment
		(start 412.140908 -286.120332)
		(end 411.673294 -286.120332)
		(width 0.18288)
		(layer "In2.Cu")
		(net "M_F_CPU0_SA_DQS_DP<7>")
	)
	(segment
		(start 388.780782 -267.48867)
		(end 388.286498 -267.48867)
		(width 0.088646)
		(layer "In2.Cu")
		(net "M_F_CPU0_SA_DQS_DP<7>")
	)
	(segment
		(start 415.443924 -286.173672)
		(end 415.259774 -285.989522)
		(width 0.16002)
		(layer "In2.Cu")
		(net "M_F_CPU0_SA_DQS_DP<7>")
	)
	(segment
		(start 420.487602 -292.092126)
		(end 420.224204 -292.355524)
		(width 0.18288)
		(layer "In2.Cu")
		(net "M_F_CPU0_SA_DQS_DP<7>")
	)
	(segment
		(start 420.972996 -292.092126)
		(end 420.487602 -292.092126)
		(width 0.18288)
		(layer "In2.Cu")
		(net "M_F_CPU0_SA_DQS_DP<7>")
	)
	(segment
		(start 424.836082 -292.51656)
		(end 424.645582 -292.70706)
		(width 0.18288)
		(layer "In2.Cu")
		(net "M_F_CPU0_SA_DQS_DP<7>")
	)
	(segment
		(start 417.012882 -288.823146)
		(end 416.23742 -286.950658)
		(width 0.18288)
		(layer "In2.Cu")
		(net "M_F_CPU0_SA_DQS_DP<7>")
	)
	(segment
		(start 413.111696 -286.20466)
		(end 413.083502 -286.232854)
		(width 0.16002)
		(layer "In2.Cu")
		(net "M_F_CPU0_SA_DQS_DP<7>")
	)
	(segment
		(start 413.544766 -285.77159)
		(end 413.340296 -285.97606)
		(width 0.18288)
		(layer "In2.Cu")
		(net "M_F_CPU0_SA_DQS_DP<7>")
	)
	(segment
		(start 398.888458 -273.946112)
		(end 396.329154 -271.386808)
		(width 0.18288)
		(layer "In2.Cu")
		(net "M_F_CPU0_SA_DQS_DP<7>")
	)
	(segment
		(start 396.329154 -271.386808)
		(end 394.921232 -271.386808)
		(width 0.18288)
		(layer "In2.Cu")
		(net "M_F_CPU0_SA_DQS_DP<7>")
	)
	(segment
		(start 407.34742 -283.016452)
		(end 405.95677 -283.016452)
		(width 0.18288)
		(layer "In2.Cu")
		(net "M_F_CPU0_SA_DQS_DP<7>")
	)
	(segment
		(start 405.95677 -283.016452)
		(end 405.680164 -282.739846)
		(width 0.18288)
		(layer "In2.Cu")
		(net "M_F_CPU0_SA_DQS_DP<7>")
	)
	(segment
		(start 420.224204 -292.355524)
		(end 419.83406 -292.355524)
		(width 0.18288)
		(layer "In2.Cu")
		(net "M_F_CPU0_SA_DQS_DP<7>")
	)
	(segment
		(start 405.002492 -283.005276)
		(end 404.915878 -283.005276)
		(width 0.18288)
		(layer "In2.Cu")
		(net "M_F_CPU0_SA_DQS_DP<7>")
	)
	(segment
		(start 422.973246 -292.901116)
		(end 422.693338 -292.621208)
		(width 0.18288)
		(layer "In2.Cu")
		(net "M_F_CPU0_SA_DQS_DP<7>")
	)
	(segment
		(start 399.904966 -276.37613)
		(end 398.933924 -274.02028)
		(width 0.18288)
		(layer "In2.Cu")
		(net "M_F_CPU0_SA_DQS_DP<7>")
	)
	(segment
		(start 415.259774 -285.989522)
		(end 415.259774 -285.973266)
		(width 0.16002)
		(layer "In2.Cu")
		(net "M_F_CPU0_SA_DQS_DP<7>")
	)
	(segment
		(start 387.711442 -267.27531)
		(end 387.711442 -267.275056)
		(width 0.088646)
		(layer "In2.Cu")
		(net "M_F_CPU0_SA_DQS_DP<7>")
	)
	(segment
		(start 386.756656 -267.266674)
		(end 386.75691 -267.265912)
		(width 0.088646)
		(layer "In2.Cu")
		(net "M_F_CPU0_SA_DQS_DP<7>")
	)
	(segment
		(start 398.933924 -274.02028)
		(end 398.938496 -274.017232)
		(width 0.18288)
		(layer "In2.Cu")
		(net "M_F_CPU0_SA_DQS_DP<7>")
	)
	(segment
		(start 407.909014 -283.578046)
		(end 407.88082 -283.549852)
		(width 0.16002)
		(layer "In2.Cu")
		(net "M_F_CPU0_SA_DQS_DP<7>")
	)
	(segment
		(start 419.83406 -292.355524)
		(end 419.241732 -291.76345)
		(width 0.18288)
		(layer "In2.Cu")
		(net "M_F_CPU0_SA_DQS_DP<7>")
	)
	(segment
		(start 412.914084 -286.402272)
		(end 412.422848 -286.402272)
		(width 0.18288)
		(layer "In2.Cu")
		(net "M_F_CPU0_SA_DQS_DP<7>")
	)
	(segment
		(start 413.312102 -286.02051)
		(end 413.127952 -286.20466)
		(width 0.16002)
		(layer "In2.Cu")
		(net "M_F_CPU0_SA_DQS_DP<7>")
	)
	(segment
		(start 413.340296 -285.97606)
		(end 413.312102 -286.004254)
		(width 0.16002)
		(layer "In2.Cu")
		(net "M_F_CPU0_SA_DQS_DP<7>")
	)
	(segment
		(start 415.058098 -285.77159)
		(end 413.544766 -285.77159)
		(width 0.18288)
		(layer "In2.Cu")
		(net "M_F_CPU0_SA_DQS_DP<7>")
	)
	(segment
		(start 413.083502 -286.232854)
		(end 412.914084 -286.402272)
		(width 0.18288)
		(layer "In2.Cu")
		(net "M_F_CPU0_SA_DQS_DP<7>")
	)
	(segment
		(start 410.014166 -286.05099)
		(end 408.3304 -283.999432)
		(width 0.18288)
		(layer "In2.Cu")
		(net "M_F_CPU0_SA_DQS_DP<7>")
	)
	(segment
		(start 408.3304 -283.999432)
		(end 407.909014 -283.578046)
		(width 0.18288)
		(layer "In2.Cu")
		(net "M_F_CPU0_SA_DQS_DP<7>")
	)
	(segment
		(start 417.80968 -291.361876)
		(end 417.157662 -290.826444)
		(width 0.18288)
		(layer "In2.Cu")
		(net "M_F_CPU0_SA_DQS_DP<7>")
	)
	(segment
		(start 424.208702 -292.70706)
		(end 423.544238 -292.982142)
		(width 0.18288)
		(layer "In2.Cu")
		(net "M_F_CPU0_SA_DQS_DP<7>")
	)
	(segment
		(start 407.65222 -283.321252)
		(end 407.34742 -283.016452)
		(width 0.18288)
		(layer "In2.Cu")
		(net "M_F_CPU0_SA_DQS_DP<7>")
	)
	(segment
		(start 387.711442 -267.275056)
		(end 387.710172 -267.274294)
		(width 0.088646)
		(layer "In2.Cu")
		(net "M_F_CPU0_SA_DQS_DP<7>")
	)
	(segment
		(start 384.053334 -267.335508)
		(end 383.65176 -267.335508)
		(width 0.088646)
		(layer "In2.Cu")
		(net "M_F_CPU0_SA_DQS_DP<7>")
	)
	(segment
		(start 412.422848 -286.402272)
		(end 412.140908 -286.120332)
		(width 0.18288)
		(layer "In2.Cu")
		(net "M_F_CPU0_SA_DQS_DP<7>")
	)
	(segment
		(start 407.88082 -283.549852)
		(end 407.864564 -283.549852)
		(width 0.16002)
		(layer "In2.Cu")
		(net "M_F_CPU0_SA_DQS_DP<7>")
	)
	(segment
		(start 383.284984 -267.698728)
		(end 383.227834 -267.755878)
		(width 0.088646)
		(layer "In2.Cu")
		(net "M_F_CPU0_SA_DQS_DP<7>")
	)
	(segment
		(start 415.46018 -286.173672)
		(end 415.443924 -286.173672)
		(width 0.16002)
		(layer "In2.Cu")
		(net "M_F_CPU0_SA_DQS_DP<7>")
	)
	(segment
		(start 405.680164 -282.739846)
		(end 405.267922 -282.739846)
		(width 0.18288)
		(layer "In2.Cu")
		(net "M_F_CPU0_SA_DQS_DP<7>")
	)
	(segment
		(start 404.19401 -280.665936)
		(end 399.923 -276.394164)
		(width 0.18288)
		(layer "In2.Cu")
		(net "M_F_CPU0_SA_DQS_DP<7>")
	)
	(segment
		(start 383.227834 -267.755878)
		(end 382.715262 -267.755878)
		(width 0.088646)
		(layer "In2.Cu")
		(net "M_F_CPU0_SA_DQS_DP<7>")
	)
	(segment
		(start 404.652226 -282.741624)
		(end 404.652226 -281.771344)
		(width 0.18288)
		(layer "In2.Cu")
		(net "M_F_CPU0_SA_DQS_DP<7>")
	)
	(segment
		(start 419.241732 -291.76345)
		(end 418.606478 -291.499544)
		(width 0.18288)
		(layer "In2.Cu")
		(net "M_F_CPU0_SA_DQS_DP<7>")
	)
	(segment
		(start 407.680414 -283.349446)
		(end 407.65222 -283.321252)
		(width 0.16002)
		(layer "In2.Cu")
		(net "M_F_CPU0_SA_DQS_DP<7>")
	)
	(segment
		(start 394.921232 -271.386808)
		(end 391.202926 -267.668248)
		(width 0.18288)
		(layer "In2.Cu")
		(net "M_F_CPU0_SA_DQS_DP<7>")
	)
	(segment
		(start 407.864564 -283.549852)
		(end 407.680414 -283.365702)
		(width 0.16002)
		(layer "In2.Cu")
		(net "M_F_CPU0_SA_DQS_DP<7>")
	)
	(segment
		(start 388.840472 -267.42898)
		(end 388.780782 -267.48867)
		(width 0.088646)
		(layer "In2.Cu")
		(net "M_F_CPU0_SA_DQS_DP<7>")
	)
	(segment
		(start 404.652226 -281.771344)
		(end 404.19401 -280.665936)
		(width 0.18288)
		(layer "In2.Cu")
		(net "M_F_CPU0_SA_DQS_DP<7>")
	)
	(segment
		(start 399.923 -276.394164)
		(end 399.904966 -276.37613)
		(width 0.18288)
		(layer "In2.Cu")
		(net "M_F_CPU0_SA_DQS_DP<7>")
	)
	(segment
		(start 413.127952 -286.20466)
		(end 413.111696 -286.20466)
		(width 0.16002)
		(layer "In2.Cu")
		(net "M_F_CPU0_SA_DQS_DP<7>")
	)
	(segment
		(start 415.259774 -285.973266)
		(end 415.23158 -285.945072)
		(width 0.16002)
		(layer "In2.Cu")
		(net "M_F_CPU0_SA_DQS_DP<7>")
	)
	(segment
		(start 415.488374 -286.201866)
		(end 415.46018 -286.173672)
		(width 0.16002)
		(layer "In2.Cu")
		(net "M_F_CPU0_SA_DQS_DP<7>")
	)
	(segment
		(start 404.915878 -283.005276)
		(end 404.652226 -282.741624)
		(width 0.18288)
		(layer "In2.Cu")
		(net "M_F_CPU0_SA_DQS_DP<7>")
	)
	(segment
		(start 383.628646 -267.342874)
		(end 383.596642 -267.365226)
		(width 0.088646)
		(layer "In2.Cu")
		(net "M_F_CPU0_SA_DQS_DP<7>")
	)
	(segment
		(start 423.544238 -292.982142)
		(end 423.168572 -292.982142)
		(width 0.18288)
		(layer "In2.Cu")
		(net "M_F_CPU0_SA_DQS_DP<7>")
	)
	(segment
		(start 387.710172 -267.274294)
		(end 387.69671 -267.266674)
		(width 0.088646)
		(layer "In2.Cu")
		(net "M_F_CPU0_SA_DQS_DP<7>")
	)
	(segment
		(start 407.680414 -283.365702)
		(end 407.680414 -283.349446)
		(width 0.16002)
		(layer "In2.Cu")
		(net "M_F_CPU0_SA_DQS_DP<7>")
	)
	(segment
		(start 415.23158 -285.945072)
		(end 415.058098 -285.77159)
		(width 0.18288)
		(layer "In2.Cu")
		(net "M_F_CPU0_SA_DQS_DP<7>")
	)
	(segment
		(start 398.938496 -274.017232)
		(end 398.888458 -273.946112)
		(width 0.18288)
		(layer "In2.Cu")
		(net "M_F_CPU0_SA_DQS_DP<7>")
	)
	(segment
		(start 388.286498 -267.48867)
		(end 388.134606 -267.336778)
		(width 0.088646)
		(layer "In2.Cu")
		(net "M_F_CPU0_SA_DQS_DP<7>")
	)
	(segment
		(start 411.48381 -286.309816)
		(end 410.639006 -286.309816)
		(width 0.18288)
		(layer "In2.Cu")
		(net "M_F_CPU0_SA_DQS_DP<7>")
	)
	(segment
		(start 423.168572 -292.982142)
		(end 422.973246 -292.901116)
		(width 0.18288)
		(layer "In2.Cu")
		(net "M_F_CPU0_SA_DQS_DP<7>")
	)
	(segment
		(start 383.467864 -267.43152)
		(end 383.458974 -267.4366)
		(width 0.088646)
		(layer "In2.Cu")
		(net "M_F_CPU0_SA_DQS_DP<7>")
	)
	(segment
		(start 388.134606 -267.336778)
		(end 387.920738 -267.336778)
		(width 0.088646)
		(layer "In2.Cu")
		(net "M_F_CPU0_SA_DQS_DP<7>")
	)
	(segment
		(start 421.24757 -292.3667)
		(end 420.972996 -292.092126)
		(width 0.18288)
		(layer "In2.Cu")
		(net "M_F_CPU0_SA_DQS_DP<7>")
	)
	(segment
		(start 418.606478 -291.499544)
		(end 417.80968 -291.361876)
		(width 0.18288)
		(layer "In2.Cu")
		(net "M_F_CPU0_SA_DQS_DP<7>")
	)
	(segment
		(start 391.202926 -267.668248)
		(end 390.625076 -267.42898)
		(width 0.18288)
		(layer "In2.Cu")
		(net "M_F_CPU0_SA_DQS_DP<7>")
	)
	(arc
		(start 385.817364 -267.266166)
		(mid 385.534662 -267.190424)
		(end 385.25196 -267.266166)
		(width 0.088646)
		(layer "In2.Cu")
		(net "M_F_CPU0_SA_DQS_DP<7>")
	)
	(arc
		(start 387.69671 -267.266674)
		(mid 387.414406 -267.191118)
		(end 387.132068 -267.266674)
		(width 0.088646)
		(layer "In2.Cu")
		(net "M_F_CPU0_SA_DQS_DP<7>")
	)
	(arc
		(start 383.596642 -267.365226)
		(mid 383.558536 -267.38867)
		(end 383.517902 -267.40739)
		(width 0.088646)
		(layer "In2.Cu")
		(net "M_F_CPU0_SA_DQS_DP<7>")
	)
	(arc
		(start 386.75691 -267.265912)
		(mid 386.474289 -267.190331)
		(end 386.19176 -267.266166)
		(width 0.088646)
		(layer "In2.Cu")
		(net "M_F_CPU0_SA_DQS_DP<7>")
	)
	(arc
		(start 383.517902 -267.40739)
		(mid 383.492433 -267.418523)
		(end 383.467864 -267.43152)
		(width 0.088646)
		(layer "In2.Cu")
		(net "M_F_CPU0_SA_DQS_DP<7>")
	)
	(arc
		(start 384.877564 -267.266166)
		(mid 384.594862 -267.190424)
		(end 384.31216 -267.266166)
		(width 0.088646)
		(layer "In2.Cu")
		(net "M_F_CPU0_SA_DQS_DP<7>")
	)
	(arc
		(start 387.132068 -267.266674)
		(mid 386.944362 -267.317003)
		(end 386.756656 -267.266674)
		(width 0.088646)
		(layer "In2.Cu")
		(net "M_F_CPU0_SA_DQS_DP<7>")
	)
	(arc
		(start 387.8326 -267.325602)
		(mid 387.770335 -267.304516)
		(end 387.711442 -267.27531)
		(width 0.088646)
		(layer "In2.Cu")
		(net "M_F_CPU0_SA_DQS_DP<7>")
	)
	(arc
		(start 384.31216 -267.266166)
		(mid 384.187308 -267.317854)
		(end 384.053334 -267.335508)
		(width 0.088646)
		(layer "In2.Cu")
		(net "M_F_CPU0_SA_DQS_DP<7>")
	)
	(arc
		(start 387.920738 -267.336778)
		(mid 387.876308 -267.334037)
		(end 387.8326 -267.325602)
		(width 0.088646)
		(layer "In2.Cu")
		(net "M_F_CPU0_SA_DQS_DP<7>")
	)
	(arc
		(start 386.19176 -267.266166)
		(mid 386.004562 -267.316309)
		(end 385.817364 -267.266166)
		(width 0.088646)
		(layer "In2.Cu")
		(net "M_F_CPU0_SA_DQS_DP<7>")
	)
	(arc
		(start 383.65176 -267.335508)
		(mid 383.639645 -267.337435)
		(end 383.628646 -267.342874)
		(width 0.088646)
		(layer "In2.Cu")
		(net "M_F_CPU0_SA_DQS_DP<7>")
	)
	(arc
		(start 385.25196 -267.266166)
		(mid 385.064762 -267.316309)
		(end 384.877564 -267.266166)
		(width 0.088646)
		(layer "In2.Cu")
		(net "M_F_CPU0_SA_DQS_DP<7>")
	)
	(arc
		(start 383.458974 -267.4366)
		(mid 383.343165 -267.548529)
		(end 383.284984 -267.698728)
		(width 0.088646)
		(layer "In2.Cu")
		(net "M_F_CPU0_SA_DQS_DP<7>")
	)
	(segment
		(start 424.836082 -301.866554)
		(end 425.940728 -301.866554)
		(width 0.20066)
		(layer "F.Cu")
		(net "M_F_CPU0_SA_DQS_DP<6>")
	)
	(segment
		(start 426.785532 -302.11776)
		(end 426.53458 -301.866808)
		(width 0.20066)
		(layer "F.Cu")
		(net "M_F_CPU0_SA_DQS_DP<6>")
	)
	(segment
		(start 430.97196 -301.689262)
		(end 430.717198 -301.4345)
		(width 0.20066)
		(layer "F.Cu")
		(net "M_F_CPU0_SA_DQS_DP<6>")
	)
	(segment
		(start 427.793658 -301.692818)
		(end 427.515274 -301.692818)
		(width 0.20066)
		(layer "F.Cu")
		(net "M_F_CPU0_SA_DQS_DP<6>")
	)
	(segment
		(start 428.051722 -301.434754)
		(end 427.793658 -301.692818)
		(width 0.20066)
		(layer "F.Cu")
		(net "M_F_CPU0_SA_DQS_DP<6>")
	)
	(segment
		(start 428.375064 -301.441866)
		(end 428.367952 -301.434754)
		(width 0.1016)
		(layer "F.Cu")
		(net "M_F_CPU0_SA_DQS_DP<6>")
	)
	(segment
		(start 432.071018 -302.134778)
		(end 431.625502 -301.689262)
		(width 0.20066)
		(layer "F.Cu")
		(net "M_F_CPU0_SA_DQS_DP<6>")
	)
	(segment
		(start 431.625502 -301.689262)
		(end 430.97196 -301.689262)
		(width 0.20066)
		(layer "F.Cu")
		(net "M_F_CPU0_SA_DQS_DP<6>")
	)
	(segment
		(start 379.426216 -270.167862)
		(end 379.426216 -270.19758)
		(width 0.20066)
		(layer "F.Cu")
		(net "M_F_CPU0_SA_DQS_DP<6>")
	)
	(segment
		(start 433.484782 -301.866808)
		(end 432.916584 -301.866808)
		(width 0.20066)
		(layer "F.Cu")
		(net "M_F_CPU0_SA_DQS_DP<6>")
	)
	(segment
		(start 427.515274 -301.692818)
		(end 427.090332 -302.11776)
		(width 0.20066)
		(layer "F.Cu")
		(net "M_F_CPU0_SA_DQS_DP<6>")
	)
	(segment
		(start 425.940728 -301.866554)
		(end 425.940982 -301.866808)
		(width 0.20066)
		(layer "F.Cu")
		(net "M_F_CPU0_SA_DQS_DP<6>")
	)
	(segment
		(start 432.648614 -302.134778)
		(end 432.071018 -302.134778)
		(width 0.20066)
		(layer "F.Cu")
		(net "M_F_CPU0_SA_DQS_DP<6>")
	)
	(segment
		(start 428.363126 -301.434754)
		(end 428.051722 -301.434754)
		(width 0.20066)
		(layer "F.Cu")
		(net "M_F_CPU0_SA_DQS_DP<6>")
	)
	(segment
		(start 426.53458 -301.866808)
		(end 425.940982 -301.866808)
		(width 0.20066)
		(layer "F.Cu")
		(net "M_F_CPU0_SA_DQS_DP<6>")
	)
	(segment
		(start 430.717198 -301.4345)
		(end 430.395126 -301.4345)
		(width 0.20066)
		(layer "F.Cu")
		(net "M_F_CPU0_SA_DQS_DP<6>")
	)
	(segment
		(start 428.367952 -301.434754)
		(end 428.363126 -301.434754)
		(width 0.101854)
		(layer "F.Cu")
		(net "M_F_CPU0_SA_DQS_DP<6>")
	)
	(segment
		(start 430.38776 -301.441866)
		(end 428.375064 -301.441866)
		(width 0.1016)
		(layer "F.Cu")
		(net "M_F_CPU0_SA_DQS_DP<6>")
	)
	(segment
		(start 432.916584 -301.866808)
		(end 432.648614 -302.134778)
		(width 0.20066)
		(layer "F.Cu")
		(net "M_F_CPU0_SA_DQS_DP<6>")
	)
	(segment
		(start 427.090332 -302.11776)
		(end 426.785532 -302.11776)
		(width 0.20066)
		(layer "F.Cu")
		(net "M_F_CPU0_SA_DQS_DP<6>")
	)
	(segment
		(start 430.395126 -301.4345)
		(end 430.38776 -301.441866)
		(width 0.1016)
		(layer "F.Cu")
		(net "M_F_CPU0_SA_DQS_DP<6>")
	)
	(segment
		(start 379.425962 -269.66164)
		(end 379.426216 -270.167862)
		(width 0.20066)
		(layer "F.Cu")
		(net "M_F_CPU0_SA_DQS_DP<6>")
	)
	(segment
		(start 387.655562 -270.846804)
		(end 387.401054 -270.846804)
		(width 0.088646)
		(layer "In4.Cu")
		(net "M_F_CPU0_SA_DQS_DP<6>")
	)
	(segment
		(start 388.428992 -271.535906)
		(end 388.344664 -271.535906)
		(width 0.088646)
		(layer "In4.Cu")
		(net "M_F_CPU0_SA_DQS_DP<6>")
	)
	(segment
		(start 390.31672 -273.423634)
		(end 388.445502 -271.552416)
		(width 0.18288)
		(layer "In4.Cu")
		(net "M_F_CPU0_SA_DQS_DP<6>")
	)
	(segment
		(start 391.11301 -273.423634)
		(end 390.31672 -273.423634)
		(width 0.18288)
		(layer "In4.Cu")
		(net "M_F_CPU0_SA_DQS_DP<6>")
	)
	(segment
		(start 386.928868 -270.665956)
		(end 386.874258 -270.611092)
		(width 0.088646)
		(layer "In4.Cu")
		(net "M_F_CPU0_SA_DQS_DP<6>")
	)
	(segment
		(start 410.459174 -297.198542)
		(end 409.993084 -296.732452)
		(width 0.18288)
		(layer "In4.Cu")
		(net "M_F_CPU0_SA_DQS_DP<6>")
	)
	(segment
		(start 379.995938 -270.14043)
		(end 379.938788 -270.19758)
		(width 0.088646)
		(layer "In4.Cu")
		(net "M_F_CPU0_SA_DQS_DP<6>")
	)
	(segment
		(start 411.21457 -297.953938)
		(end 411.21457 -297.953684)
		(width 0.18288)
		(layer "In4.Cu")
		(net "M_F_CPU0_SA_DQS_DP<6>")
	)
	(segment
		(start 404.525988 -293.734744)
		(end 401.57654 -290.785296)
		(width 0.18288)
		(layer "In4.Cu")
		(net "M_F_CPU0_SA_DQS_DP<6>")
	)
	(segment
		(start 388.344664 -271.535906)
		(end 387.655562 -270.846804)
		(width 0.088646)
		(layer "In4.Cu")
		(net "M_F_CPU0_SA_DQS_DP<6>")
	)
	(segment
		(start 424.590972 -302.111664)
		(end 424.103546 -302.111664)
		(width 0.18288)
		(layer "In4.Cu")
		(net "M_F_CPU0_SA_DQS_DP<6>")
	)
	(segment
		(start 387.401054 -270.846804)
		(end 387.324346 -270.82115)
		(width 0.088646)
		(layer "In4.Cu")
		(net "M_F_CPU0_SA_DQS_DP<6>")
	)
	(segment
		(start 386.569966 -270.19758)
		(end 386.569966 -270.183356)
		(width 0.088646)
		(layer "In4.Cu")
		(net "M_F_CPU0_SA_DQS_DP<6>")
	)
	(segment
		(start 424.836082 -301.866554)
		(end 424.590972 -302.111664)
		(width 0.18288)
		(layer "In4.Cu")
		(net "M_F_CPU0_SA_DQS_DP<6>")
	)
	(segment
		(start 411.21457 -297.953684)
		(end 410.459174 -297.198542)
		(width 0.18288)
		(layer "In4.Cu")
		(net "M_F_CPU0_SA_DQS_DP<6>")
	)
	(segment
		(start 422.856406 -302.294036)
		(end 421.4622 -301.71644)
		(width 0.18288)
		(layer "In4.Cu")
		(net "M_F_CPU0_SA_DQS_DP<6>")
	)
	(segment
		(start 419.718236 -301.985426)
		(end 416.583876 -301.985426)
		(width 0.18288)
		(layer "In4.Cu")
		(net "M_F_CPU0_SA_DQS_DP<6>")
	)
	(segment
		(start 385.347464 -269.707868)
		(end 385.332732 -269.699232)
		(width 0.088646)
		(layer "In4.Cu")
		(net "M_F_CPU0_SA_DQS_DP<6>")
	)
	(segment
		(start 381.023114 -269.708376)
		(end 380.95174 -269.749778)
		(width 0.088646)
		(layer "In4.Cu")
		(net "M_F_CPU0_SA_DQS_DP<6>")
	)
	(segment
		(start 413.284162 -299.05325)
		(end 411.627828 -298.366942)
		(width 0.18288)
		(layer "In4.Cu")
		(net "M_F_CPU0_SA_DQS_DP<6>")
	)
	(segment
		(start 409.993084 -296.732452)
		(end 408.239468 -295.810432)
		(width 0.18288)
		(layer "In4.Cu")
		(net "M_F_CPU0_SA_DQS_DP<6>")
	)
	(segment
		(start 381.588264 -269.707868)
		(end 381.58801 -269.708122)
		(width 0.088646)
		(layer "In4.Cu")
		(net "M_F_CPU0_SA_DQS_DP<6>")
	)
	(segment
		(start 382.907286 -269.705328)
		(end 382.902714 -269.708122)
		(width 0.088646)
		(layer "In4.Cu")
		(net "M_F_CPU0_SA_DQS_DP<6>")
	)
	(segment
		(start 406.129236 -294.48633)
		(end 404.525988 -293.734744)
		(width 0.18288)
		(layer "In4.Cu")
		(net "M_F_CPU0_SA_DQS_DP<6>")
	)
	(segment
		(start 379.938788 -270.19758)
		(end 379.426216 -270.19758)
		(width 0.088646)
		(layer "In4.Cu")
		(net "M_F_CPU0_SA_DQS_DP<6>")
	)
	(segment
		(start 384.407664 -269.707868)
		(end 384.392932 -269.699232)
		(width 0.088646)
		(layer "In4.Cu")
		(net "M_F_CPU0_SA_DQS_DP<6>")
	)
	(segment
		(start 388.445502 -271.552416)
		(end 388.428992 -271.535906)
		(width 0.088646)
		(layer "In4.Cu")
		(net "M_F_CPU0_SA_DQS_DP<6>")
	)
	(segment
		(start 380.76251 -269.800324)
		(end 380.372112 -269.800324)
		(width 0.088646)
		(layer "In4.Cu")
		(net "M_F_CPU0_SA_DQS_DP<6>")
	)
	(segment
		(start 421.228012 -301.71644)
		(end 420.953946 -301.442374)
		(width 0.18288)
		(layer "In4.Cu")
		(net "M_F_CPU0_SA_DQS_DP<6>")
	)
	(segment
		(start 386.757418 -270.521938)
		(end 386.748528 -270.516858)
		(width 0.088646)
		(layer "In4.Cu")
		(net "M_F_CPU0_SA_DQS_DP<6>")
	)
	(segment
		(start 420.502334 -301.442374)
		(end 420.257732 -301.686976)
		(width 0.18288)
		(layer "In4.Cu")
		(net "M_F_CPU0_SA_DQS_DP<6>")
	)
	(segment
		(start 396.702788 -279.013412)
		(end 391.11301 -273.423634)
		(width 0.18288)
		(layer "In4.Cu")
		(net "M_F_CPU0_SA_DQS_DP<6>")
	)
	(segment
		(start 424.103546 -302.111664)
		(end 423.662348 -302.294036)
		(width 0.18288)
		(layer "In4.Cu")
		(net "M_F_CPU0_SA_DQS_DP<6>")
	)
	(segment
		(start 416.583876 -301.985426)
		(end 415.771838 -301.173388)
		(width 0.18288)
		(layer "In4.Cu")
		(net "M_F_CPU0_SA_DQS_DP<6>")
	)
	(segment
		(start 408.239468 -295.810432)
		(end 407.258774 -295.229534)
		(width 0.18288)
		(layer "In4.Cu")
		(net "M_F_CPU0_SA_DQS_DP<6>")
	)
	(segment
		(start 382.902714 -269.708122)
		(end 382.898142 -269.710662)
		(width 0.088646)
		(layer "In4.Cu")
		(net "M_F_CPU0_SA_DQS_DP<6>")
	)
	(segment
		(start 423.662348 -302.294036)
		(end 422.856406 -302.294036)
		(width 0.18288)
		(layer "In4.Cu")
		(net "M_F_CPU0_SA_DQS_DP<6>")
	)
	(segment
		(start 387.324346 -270.82115)
		(end 386.928868 -270.665956)
		(width 0.088646)
		(layer "In4.Cu")
		(net "M_F_CPU0_SA_DQS_DP<6>")
	)
	(segment
		(start 411.627828 -298.366942)
		(end 411.21457 -297.953938)
		(width 0.18288)
		(layer "In4.Cu")
		(net "M_F_CPU0_SA_DQS_DP<6>")
	)
	(segment
		(start 415.771838 -301.173388)
		(end 415.14395 -300.913038)
		(width 0.18288)
		(layer "In4.Cu")
		(net "M_F_CPU0_SA_DQS_DP<6>")
	)
	(segment
		(start 381.97028 -269.703804)
		(end 381.96266 -269.707868)
		(width 0.088646)
		(layer "In4.Cu")
		(net "M_F_CPU0_SA_DQS_DP<6>")
	)
	(segment
		(start 420.953946 -301.442374)
		(end 420.502334 -301.442374)
		(width 0.18288)
		(layer "In4.Cu")
		(net "M_F_CPU0_SA_DQS_DP<6>")
	)
	(segment
		(start 407.258774 -295.229534)
		(end 406.129236 -294.48633)
		(width 0.18288)
		(layer "In4.Cu")
		(net "M_F_CPU0_SA_DQS_DP<6>")
	)
	(segment
		(start 383.467864 -269.707868)
		(end 383.467864 -269.708122)
		(width 0.088646)
		(layer "In4.Cu")
		(net "M_F_CPU0_SA_DQS_DP<6>")
	)
	(segment
		(start 401.57654 -290.785296)
		(end 396.702788 -279.013412)
		(width 0.18288)
		(layer "In4.Cu")
		(net "M_F_CPU0_SA_DQS_DP<6>")
	)
	(segment
		(start 420.257732 -301.686976)
		(end 420.016686 -301.686976)
		(width 0.18288)
		(layer "In4.Cu")
		(net "M_F_CPU0_SA_DQS_DP<6>")
	)
	(segment
		(start 420.016686 -301.686976)
		(end 419.718236 -301.985426)
		(width 0.18288)
		(layer "In4.Cu")
		(net "M_F_CPU0_SA_DQS_DP<6>")
	)
	(segment
		(start 415.14395 -300.913038)
		(end 413.284162 -299.05325)
		(width 0.18288)
		(layer "In4.Cu")
		(net "M_F_CPU0_SA_DQS_DP<6>")
	)
	(segment
		(start 421.4622 -301.71644)
		(end 421.228012 -301.71644)
		(width 0.18288)
		(layer "In4.Cu")
		(net "M_F_CPU0_SA_DQS_DP<6>")
	)
	(arc
		(start 384.78206 -269.707868)
		(mid 384.594862 -269.758011)
		(end 384.407664 -269.707868)
		(width 0.088646)
		(layer "In4.Cu")
		(net "M_F_CPU0_SA_DQS_DP<6>")
	)
	(arc
		(start 381.58801 -269.708122)
		(mid 381.305533 -269.6326)
		(end 381.023114 -269.708376)
		(width 0.088646)
		(layer "In4.Cu")
		(net "M_F_CPU0_SA_DQS_DP<6>")
	)
	(arc
		(start 386.874258 -270.611092)
		(mid 386.85694 -270.59472)
		(end 386.838952 -270.579088)
		(width 0.088646)
		(layer "In4.Cu")
		(net "M_F_CPU0_SA_DQS_DP<6>")
	)
	(arc
		(start 383.84226 -269.707868)
		(mid 383.655062 -269.758011)
		(end 383.467864 -269.707868)
		(width 0.088646)
		(layer "In4.Cu")
		(net "M_F_CPU0_SA_DQS_DP<6>")
	)
	(arc
		(start 383.467864 -269.708122)
		(mid 383.18795 -269.632353)
		(end 382.907286 -269.705328)
		(width 0.088646)
		(layer "In4.Cu")
		(net "M_F_CPU0_SA_DQS_DP<6>")
	)
	(arc
		(start 386.569966 -270.183356)
		(mid 386.281184 -269.70426)
		(end 385.72186 -269.707868)
		(width 0.088646)
		(layer "In4.Cu")
		(net "M_F_CPU0_SA_DQS_DP<6>")
	)
	(arc
		(start 380.372112 -269.800324)
		(mid 380.323998 -269.80668)
		(end 380.279148 -269.825216)
		(width 0.088646)
		(layer "In4.Cu")
		(net "M_F_CPU0_SA_DQS_DP<6>")
	)
	(arc
		(start 380.228856 -269.849092)
		(mid 380.073523 -269.96369)
		(end 379.995938 -270.14043)
		(width 0.088646)
		(layer "In4.Cu")
		(net "M_F_CPU0_SA_DQS_DP<6>")
	)
	(arc
		(start 386.748528 -270.516858)
		(mid 386.617614 -270.380498)
		(end 386.569966 -270.19758)
		(width 0.088646)
		(layer "In4.Cu")
		(net "M_F_CPU0_SA_DQS_DP<6>")
	)
	(arc
		(start 382.528064 -269.708122)
		(mid 382.249741 -269.632363)
		(end 381.97028 -269.703804)
		(width 0.088646)
		(layer "In4.Cu")
		(net "M_F_CPU0_SA_DQS_DP<6>")
	)
	(arc
		(start 381.96266 -269.707868)
		(mid 381.775462 -269.758011)
		(end 381.588264 -269.707868)
		(width 0.088646)
		(layer "In4.Cu")
		(net "M_F_CPU0_SA_DQS_DP<6>")
	)
	(arc
		(start 385.332732 -269.699232)
		(mid 385.056291 -269.632066)
		(end 384.78206 -269.707868)
		(width 0.088646)
		(layer "In4.Cu")
		(net "M_F_CPU0_SA_DQS_DP<6>")
	)
	(arc
		(start 385.72186 -269.707868)
		(mid 385.534662 -269.758011)
		(end 385.347464 -269.707868)
		(width 0.088646)
		(layer "In4.Cu")
		(net "M_F_CPU0_SA_DQS_DP<6>")
	)
	(arc
		(start 384.392932 -269.699232)
		(mid 384.116491 -269.632066)
		(end 383.84226 -269.707868)
		(width 0.088646)
		(layer "In4.Cu")
		(net "M_F_CPU0_SA_DQS_DP<6>")
	)
	(arc
		(start 386.838952 -270.579088)
		(mid 386.799445 -270.548715)
		(end 386.757418 -270.521938)
		(width 0.088646)
		(layer "In4.Cu")
		(net "M_F_CPU0_SA_DQS_DP<6>")
	)
	(arc
		(start 382.898142 -269.710662)
		(mid 382.712757 -269.7583)
		(end 382.528064 -269.708122)
		(width 0.088646)
		(layer "In4.Cu")
		(net "M_F_CPU0_SA_DQS_DP<6>")
	)
	(arc
		(start 380.95174 -269.749778)
		(mid 380.860448 -269.787484)
		(end 380.76251 -269.800324)
		(width 0.088646)
		(layer "In4.Cu")
		(net "M_F_CPU0_SA_DQS_DP<6>")
	)
	(arc
		(start 380.279148 -269.825216)
		(mid 380.254443 -269.838083)
		(end 380.228856 -269.849092)
		(width 0.088646)
		(layer "In4.Cu")
		(net "M_F_CPU0_SA_DQS_DP<6>")
	)
	(segment
		(start 428.363126 -310.784748)
		(end 428.051722 -310.784748)
		(width 0.20066)
		(layer "F.Cu")
		(net "M_F_CPU0_SA_DQS_DP<5>")
	)
	(segment
		(start 432.071018 -311.484772)
		(end 431.625502 -311.039256)
		(width 0.20066)
		(layer "F.Cu")
		(net "M_F_CPU0_SA_DQS_DP<5>")
	)
	(segment
		(start 430.717198 -310.784494)
		(end 430.395126 -310.784494)
		(width 0.20066)
		(layer "F.Cu")
		(net "M_F_CPU0_SA_DQS_DP<5>")
	)
	(segment
		(start 428.375064 -310.79186)
		(end 428.367952 -310.784748)
		(width 0.1016)
		(layer "F.Cu")
		(net "M_F_CPU0_SA_DQS_DP<5>")
	)
	(segment
		(start 427.793658 -311.042812)
		(end 427.515274 -311.042812)
		(width 0.20066)
		(layer "F.Cu")
		(net "M_F_CPU0_SA_DQS_DP<5>")
	)
	(segment
		(start 382.715516 -276.986492)
		(end 382.715516 -277.522178)
		(width 0.20066)
		(layer "F.Cu")
		(net "M_F_CPU0_SA_DQS_DP<5>")
	)
	(segment
		(start 426.785532 -311.467754)
		(end 426.53458 -311.216802)
		(width 0.20066)
		(layer "F.Cu")
		(net "M_F_CPU0_SA_DQS_DP<5>")
	)
	(segment
		(start 428.367952 -310.784748)
		(end 428.363126 -310.784748)
		(width 0.101854)
		(layer "F.Cu")
		(net "M_F_CPU0_SA_DQS_DP<5>")
	)
	(segment
		(start 433.484782 -311.216802)
		(end 432.916584 -311.216802)
		(width 0.20066)
		(layer "F.Cu")
		(net "M_F_CPU0_SA_DQS_DP<5>")
	)
	(segment
		(start 424.836082 -311.216548)
		(end 424.836336 -311.216802)
		(width 0.20066)
		(layer "F.Cu")
		(net "M_F_CPU0_SA_DQS_DP<5>")
	)
	(segment
		(start 430.395126 -310.784494)
		(end 430.38776 -310.79186)
		(width 0.1016)
		(layer "F.Cu")
		(net "M_F_CPU0_SA_DQS_DP<5>")
	)
	(segment
		(start 432.648614 -311.484772)
		(end 432.071018 -311.484772)
		(width 0.20066)
		(layer "F.Cu")
		(net "M_F_CPU0_SA_DQS_DP<5>")
	)
	(segment
		(start 427.090332 -311.467754)
		(end 426.785532 -311.467754)
		(width 0.20066)
		(layer "F.Cu")
		(net "M_F_CPU0_SA_DQS_DP<5>")
	)
	(segment
		(start 382.715516 -277.522178)
		(end 382.715262 -277.522432)
		(width 0.20066)
		(layer "F.Cu")
		(net "M_F_CPU0_SA_DQS_DP<5>")
	)
	(segment
		(start 424.836336 -311.216802)
		(end 425.940982 -311.216802)
		(width 0.20066)
		(layer "F.Cu")
		(net "M_F_CPU0_SA_DQS_DP<5>")
	)
	(segment
		(start 426.53458 -311.216802)
		(end 425.940982 -311.216802)
		(width 0.20066)
		(layer "F.Cu")
		(net "M_F_CPU0_SA_DQS_DP<5>")
	)
	(segment
		(start 427.515274 -311.042812)
		(end 427.090332 -311.467754)
		(width 0.20066)
		(layer "F.Cu")
		(net "M_F_CPU0_SA_DQS_DP<5>")
	)
	(segment
		(start 430.97196 -311.039256)
		(end 430.717198 -310.784494)
		(width 0.20066)
		(layer "F.Cu")
		(net "M_F_CPU0_SA_DQS_DP<5>")
	)
	(segment
		(start 431.625502 -311.039256)
		(end 430.97196 -311.039256)
		(width 0.20066)
		(layer "F.Cu")
		(net "M_F_CPU0_SA_DQS_DP<5>")
	)
	(segment
		(start 430.38776 -310.79186)
		(end 428.375064 -310.79186)
		(width 0.1016)
		(layer "F.Cu")
		(net "M_F_CPU0_SA_DQS_DP<5>")
	)
	(segment
		(start 432.916584 -311.216802)
		(end 432.648614 -311.484772)
		(width 0.20066)
		(layer "F.Cu")
		(net "M_F_CPU0_SA_DQS_DP<5>")
	)
	(segment
		(start 428.051722 -310.784748)
		(end 427.793658 -311.042812)
		(width 0.20066)
		(layer "F.Cu")
		(net "M_F_CPU0_SA_DQS_DP<5>")
	)
	(segment
		(start 395.559534 -294.383206)
		(end 392.791442 -291.615114)
		(width 0.18288)
		(layer "In2.Cu")
		(net "M_F_CPU0_SA_DQS_DP<5>")
	)
	(segment
		(start 417.23183 -310.764682)
		(end 416.496246 -311.069482)
		(width 0.18288)
		(layer "In2.Cu")
		(net "M_F_CPU0_SA_DQS_DP<5>")
	)
	(segment
		(start 409.131262 -311.039764)
		(end 408.393392 -311.039764)
		(width 0.18288)
		(layer "In2.Cu")
		(net "M_F_CPU0_SA_DQS_DP<5>")
	)
	(segment
		(start 389.32358 -279.412954)
		(end 388.105904 -278.195278)
		(width 0.18288)
		(layer "In2.Cu")
		(net "M_F_CPU0_SA_DQS_DP<5>")
	)
	(segment
		(start 423.033444 -311.706514)
		(end 423.00525 -311.67832)
		(width 0.16002)
		(layer "In2.Cu")
		(net "M_F_CPU0_SA_DQS_DP<5>")
	)
	(segment
		(start 415.16935 -311.033668)
		(end 413.504888 -311.033668)
		(width 0.18288)
		(layer "In2.Cu")
		(net "M_F_CPU0_SA_DQS_DP<5>")
	)
	(segment
		(start 411.993588 -310.794908)
		(end 411.809438 -310.610758)
		(width 0.16002)
		(layer "In2.Cu")
		(net "M_F_CPU0_SA_DQS_DP<5>")
	)
	(segment
		(start 405.827484 -310.766714)
		(end 405.464772 -310.766714)
		(width 0.18288)
		(layer "In2.Cu")
		(net "M_F_CPU0_SA_DQS_DP<5>")
	)
	(segment
		(start 390.528556 -282.320492)
		(end 389.32358 -279.412954)
		(width 0.18288)
		(layer "In2.Cu")
		(net "M_F_CPU0_SA_DQS_DP<5>")
	)
	(segment
		(start 412.843218 -310.744108)
		(end 412.53918 -311.048146)
		(width 0.18288)
		(layer "In2.Cu")
		(net "M_F_CPU0_SA_DQS_DP<5>")
	)
	(segment
		(start 387.597396 -277.771098)
		(end 386.943854 -277.771098)
		(width 0.088646)
		(layer "In2.Cu")
		(net "M_F_CPU0_SA_DQS_DP<5>")
	)
	(segment
		(start 415.795206 -310.779922)
		(end 415.423096 -310.779922)
		(width 0.18288)
		(layer "In2.Cu")
		(net "M_F_CPU0_SA_DQS_DP<5>")
	)
	(segment
		(start 388.021576 -278.195278)
		(end 387.597396 -277.771098)
		(width 0.088646)
		(layer "In2.Cu")
		(net "M_F_CPU0_SA_DQS_DP<5>")
	)
	(segment
		(start 384.34518 -277.810722)
		(end 384.343148 -277.808436)
		(width 0.088646)
		(layer "In2.Cu")
		(net "M_F_CPU0_SA_DQS_DP<5>")
	)
	(segment
		(start 383.390394 -277.257256)
		(end 383.125218 -277.522432)
		(width 0.088646)
		(layer "In2.Cu")
		(net "M_F_CPU0_SA_DQS_DP<5>")
	)
	(segment
		(start 410.062934 -310.40959)
		(end 409.645612 -310.826658)
		(width 0.18288)
		(layer "In2.Cu")
		(net "M_F_CPU0_SA_DQS_DP<5>")
	)
	(segment
		(start 424.54576 -311.50687)
		(end 424.266106 -311.50687)
		(width 0.18288)
		(layer "In2.Cu")
		(net "M_F_CPU0_SA_DQS_DP<5>")
	)
	(segment
		(start 422.78935 -311.478168)
		(end 422.78935 -311.46242)
		(width 0.16002)
		(layer "In2.Cu")
		(net "M_F_CPU0_SA_DQS_DP<5>")
	)
	(segment
		(start 411.781244 -310.566308)
		(end 411.624526 -310.40959)
		(width 0.18288)
		(layer "In2.Cu")
		(net "M_F_CPU0_SA_DQS_DP<5>")
	)
	(segment
		(start 408.132026 -310.778398)
		(end 407.674572 -310.778398)
		(width 0.18288)
		(layer "In2.Cu")
		(net "M_F_CPU0_SA_DQS_DP<5>")
	)
	(segment
		(start 423.13606 -311.80913)
		(end 423.033444 -311.706514)
		(width 0.18288)
		(layer "In2.Cu")
		(net "M_F_CPU0_SA_DQS_DP<5>")
	)
	(segment
		(start 420.838884 -310.792114)
		(end 420.608252 -310.792114)
		(width 0.16002)
		(layer "In2.Cu")
		(net "M_F_CPU0_SA_DQS_DP<5>")
	)
	(segment
		(start 412.263082 -311.048146)
		(end 412.038038 -310.823102)
		(width 0.18288)
		(layer "In2.Cu")
		(net "M_F_CPU0_SA_DQS_DP<5>")
	)
	(segment
		(start 424.836082 -311.216548)
		(end 424.54576 -311.50687)
		(width 0.18288)
		(layer "In2.Cu")
		(net "M_F_CPU0_SA_DQS_DP<5>")
	)
	(segment
		(start 412.038038 -310.823102)
		(end 412.009844 -310.794908)
		(width 0.16002)
		(layer "In2.Cu")
		(net "M_F_CPU0_SA_DQS_DP<5>")
	)
	(segment
		(start 384.407664 -277.84679)
		(end 384.34518 -277.810722)
		(width 0.088646)
		(layer "In2.Cu")
		(net "M_F_CPU0_SA_DQS_DP<5>")
	)
	(segment
		(start 384.343148 -277.808436)
		(end 384.016504 -277.398988)
		(width 0.088646)
		(layer "In2.Cu")
		(net "M_F_CPU0_SA_DQS_DP<5>")
	)
	(segment
		(start 416.084766 -311.069482)
		(end 415.795206 -310.779922)
		(width 0.18288)
		(layer "In2.Cu")
		(net "M_F_CPU0_SA_DQS_DP<5>")
	)
	(segment
		(start 415.423096 -310.779922)
		(end 415.16935 -311.033668)
		(width 0.18288)
		(layer "In2.Cu")
		(net "M_F_CPU0_SA_DQS_DP<5>")
	)
	(segment
		(start 404.34768 -311.024016)
		(end 397.020034 -303.69637)
		(width 0.18288)
		(layer "In2.Cu")
		(net "M_F_CPU0_SA_DQS_DP<5>")
	)
	(segment
		(start 416.496246 -311.069482)
		(end 416.084766 -311.069482)
		(width 0.18288)
		(layer "In2.Cu")
		(net "M_F_CPU0_SA_DQS_DP<5>")
	)
	(segment
		(start 421.253412 -311.07253)
		(end 420.972996 -310.792114)
		(width 0.18288)
		(layer "In2.Cu")
		(net "M_F_CPU0_SA_DQS_DP<5>")
	)
	(segment
		(start 409.645612 -310.826658)
		(end 409.131262 -311.039764)
		(width 0.18288)
		(layer "In2.Cu")
		(net "M_F_CPU0_SA_DQS_DP<5>")
	)
	(segment
		(start 419.838124 -311.067704)
		(end 419.251638 -310.481218)
		(width 0.18288)
		(layer "In2.Cu")
		(net "M_F_CPU0_SA_DQS_DP<5>")
	)
	(segment
		(start 392.791442 -291.615114)
		(end 391.976102 -289.646868)
		(width 0.18288)
		(layer "In2.Cu")
		(net "M_F_CPU0_SA_DQS_DP<5>")
	)
	(segment
		(start 383.125218 -277.522432)
		(end 382.715262 -277.522432)
		(width 0.088646)
		(layer "In2.Cu")
		(net "M_F_CPU0_SA_DQS_DP<5>")
	)
	(segment
		(start 407.674572 -310.778398)
		(end 407.398728 -311.054242)
		(width 0.18288)
		(layer "In2.Cu")
		(net "M_F_CPU0_SA_DQS_DP<5>")
	)
	(segment
		(start 405.20747 -311.024016)
		(end 404.34768 -311.024016)
		(width 0.18288)
		(layer "In2.Cu")
		(net "M_F_CPU0_SA_DQS_DP<5>")
	)
	(segment
		(start 422.39946 -311.07253)
		(end 421.253412 -311.07253)
		(width 0.18288)
		(layer "In2.Cu")
		(net "M_F_CPU0_SA_DQS_DP<5>")
	)
	(segment
		(start 412.009844 -310.794908)
		(end 411.993588 -310.794908)
		(width 0.16002)
		(layer "In2.Cu")
		(net "M_F_CPU0_SA_DQS_DP<5>")
	)
	(segment
		(start 423.536618 -311.80913)
		(end 423.13606 -311.80913)
		(width 0.18288)
		(layer "In2.Cu")
		(net "M_F_CPU0_SA_DQS_DP<5>")
	)
	(segment
		(start 423.00525 -311.67832)
		(end 422.989502 -311.67832)
		(width 0.16002)
		(layer "In2.Cu")
		(net "M_F_CPU0_SA_DQS_DP<5>")
	)
	(segment
		(start 406.115012 -311.054242)
		(end 405.827484 -310.766714)
		(width 0.18288)
		(layer "In2.Cu")
		(net "M_F_CPU0_SA_DQS_DP<5>")
	)
	(segment
		(start 408.393392 -311.039764)
		(end 408.132026 -310.778398)
		(width 0.18288)
		(layer "In2.Cu")
		(net "M_F_CPU0_SA_DQS_DP<5>")
	)
	(segment
		(start 411.809438 -310.610758)
		(end 411.809438 -310.594502)
		(width 0.16002)
		(layer "In2.Cu")
		(net "M_F_CPU0_SA_DQS_DP<5>")
	)
	(segment
		(start 413.215328 -310.744108)
		(end 412.843218 -310.744108)
		(width 0.18288)
		(layer "In2.Cu")
		(net "M_F_CPU0_SA_DQS_DP<5>")
	)
	(segment
		(start 407.398728 -311.054242)
		(end 406.115012 -311.054242)
		(width 0.18288)
		(layer "In2.Cu")
		(net "M_F_CPU0_SA_DQS_DP<5>")
	)
	(segment
		(start 391.976102 -283.768038)
		(end 390.528556 -282.320492)
		(width 0.18288)
		(layer "In2.Cu")
		(net "M_F_CPU0_SA_DQS_DP<5>")
	)
	(segment
		(start 422.989502 -311.67832)
		(end 422.78935 -311.478168)
		(width 0.16002)
		(layer "In2.Cu")
		(net "M_F_CPU0_SA_DQS_DP<5>")
	)
	(segment
		(start 384.016504 -277.398988)
		(end 383.978658 -277.333456)
		(width 0.088646)
		(layer "In2.Cu")
		(net "M_F_CPU0_SA_DQS_DP<5>")
	)
	(segment
		(start 417.515548 -310.481218)
		(end 417.23183 -310.764682)
		(width 0.18288)
		(layer "In2.Cu")
		(net "M_F_CPU0_SA_DQS_DP<5>")
	)
	(segment
		(start 391.976102 -289.646868)
		(end 391.976102 -283.768038)
		(width 0.18288)
		(layer "In2.Cu")
		(net "M_F_CPU0_SA_DQS_DP<5>")
	)
	(segment
		(start 419.251638 -310.481218)
		(end 417.515548 -310.481218)
		(width 0.18288)
		(layer "In2.Cu")
		(net "M_F_CPU0_SA_DQS_DP<5>")
	)
	(segment
		(start 411.809438 -310.594502)
		(end 411.781244 -310.566308)
		(width 0.16002)
		(layer "In2.Cu")
		(net "M_F_CPU0_SA_DQS_DP<5>")
	)
	(segment
		(start 413.504888 -311.033668)
		(end 413.215328 -310.744108)
		(width 0.18288)
		(layer "In2.Cu")
		(net "M_F_CPU0_SA_DQS_DP<5>")
	)
	(segment
		(start 420.608252 -310.792114)
		(end 420.487602 -310.792114)
		(width 0.18288)
		(layer "In2.Cu")
		(net "M_F_CPU0_SA_DQS_DP<5>")
	)
	(segment
		(start 397.020034 -298.168822)
		(end 395.559534 -294.383206)
		(width 0.18288)
		(layer "In2.Cu")
		(net "M_F_CPU0_SA_DQS_DP<5>")
	)
	(segment
		(start 405.464772 -310.766714)
		(end 405.20747 -311.024016)
		(width 0.18288)
		(layer "In2.Cu")
		(net "M_F_CPU0_SA_DQS_DP<5>")
	)
	(segment
		(start 388.105904 -278.195278)
		(end 388.021576 -278.195278)
		(width 0.088646)
		(layer "In2.Cu")
		(net "M_F_CPU0_SA_DQS_DP<5>")
	)
	(segment
		(start 412.53918 -311.048146)
		(end 412.263082 -311.048146)
		(width 0.18288)
		(layer "In2.Cu")
		(net "M_F_CPU0_SA_DQS_DP<5>")
	)
	(segment
		(start 420.972996 -310.792114)
		(end 420.838884 -310.792114)
		(width 0.18288)
		(layer "In2.Cu")
		(net "M_F_CPU0_SA_DQS_DP<5>")
	)
	(segment
		(start 424.266106 -311.50687)
		(end 423.536618 -311.80913)
		(width 0.18288)
		(layer "In2.Cu")
		(net "M_F_CPU0_SA_DQS_DP<5>")
	)
	(segment
		(start 422.78935 -311.46242)
		(end 422.761156 -311.434226)
		(width 0.16002)
		(layer "In2.Cu")
		(net "M_F_CPU0_SA_DQS_DP<5>")
	)
	(segment
		(start 397.020034 -303.69637)
		(end 397.020034 -298.168822)
		(width 0.18288)
		(layer "In2.Cu")
		(net "M_F_CPU0_SA_DQS_DP<5>")
	)
	(segment
		(start 411.624526 -310.40959)
		(end 410.062934 -310.40959)
		(width 0.18288)
		(layer "In2.Cu")
		(net "M_F_CPU0_SA_DQS_DP<5>")
	)
	(segment
		(start 420.487602 -310.792114)
		(end 420.212012 -311.067704)
		(width 0.18288)
		(layer "In2.Cu")
		(net "M_F_CPU0_SA_DQS_DP<5>")
	)
	(segment
		(start 422.761156 -311.434226)
		(end 422.39946 -311.07253)
		(width 0.18288)
		(layer "In2.Cu")
		(net "M_F_CPU0_SA_DQS_DP<5>")
	)
	(segment
		(start 420.212012 -311.067704)
		(end 419.838124 -311.067704)
		(width 0.18288)
		(layer "In2.Cu")
		(net "M_F_CPU0_SA_DQS_DP<5>")
	)
	(arc
		(start 384.78206 -277.84679)
		(mid 384.594862 -277.896933)
		(end 384.407664 -277.84679)
		(width 0.088646)
		(layer "In2.Cu")
		(net "M_F_CPU0_SA_DQS_DP<5>")
	)
	(arc
		(start 386.66166 -277.84679)
		(mid 386.474462 -277.896933)
		(end 386.287264 -277.84679)
		(width 0.088646)
		(layer "In2.Cu")
		(net "M_F_CPU0_SA_DQS_DP<5>")
	)
	(arc
		(start 386.943854 -277.771098)
		(mid 386.797793 -277.790426)
		(end 386.66166 -277.84679)
		(width 0.088646)
		(layer "In2.Cu")
		(net "M_F_CPU0_SA_DQS_DP<5>")
	)
	(arc
		(start 383.826766 -277.189184)
		(mid 383.597509 -277.152126)
		(end 383.390394 -277.257256)
		(width 0.088646)
		(layer "In2.Cu")
		(net "M_F_CPU0_SA_DQS_DP<5>")
	)
	(arc
		(start 385.72186 -277.84679)
		(mid 385.534662 -277.896933)
		(end 385.347464 -277.84679)
		(width 0.088646)
		(layer "In2.Cu")
		(net "M_F_CPU0_SA_DQS_DP<5>")
	)
	(arc
		(start 386.287264 -277.84679)
		(mid 386.004562 -277.771048)
		(end 385.72186 -277.84679)
		(width 0.088646)
		(layer "In2.Cu")
		(net "M_F_CPU0_SA_DQS_DP<5>")
	)
	(arc
		(start 385.347464 -277.84679)
		(mid 385.064762 -277.771048)
		(end 384.78206 -277.84679)
		(width 0.088646)
		(layer "In2.Cu")
		(net "M_F_CPU0_SA_DQS_DP<5>")
	)
	(arc
		(start 383.978658 -277.333456)
		(mid 383.913063 -277.25042)
		(end 383.826766 -277.189184)
		(width 0.088646)
		(layer "In2.Cu")
		(net "M_F_CPU0_SA_DQS_DP<5>")
	)
	(segment
		(start 428.3583 -275.234908)
		(end 428.554388 -275.234908)
		(width 0.20066)
		(layer "F.Cu")
		(net "M_F_CPU0_SA_DQS_DP<4>")
	)
	(segment
		(start 427.57725 -275.645372)
		(end 427.947836 -275.645372)
		(width 0.20066)
		(layer "F.Cu")
		(net "M_F_CPU0_SA_DQS_DP<4>")
	)
	(segment
		(start 426.951394 -275.947886)
		(end 427.274736 -275.947886)
		(width 0.20066)
		(layer "F.Cu")
		(net "M_F_CPU0_SA_DQS_DP<4>")
	)
	(segment
		(start 428.554388 -275.234908)
		(end 428.836074 -275.516594)
		(width 0.20066)
		(layer "F.Cu")
		(net "M_F_CPU0_SA_DQS_DP<4>")
	)
	(segment
		(start 427.947836 -275.645372)
		(end 428.3583 -275.234908)
		(width 0.20066)
		(layer "F.Cu")
		(net "M_F_CPU0_SA_DQS_DP<4>")
	)
	(segment
		(start 422.670732 -275.276056)
		(end 423.271188 -275.276056)
		(width 0.20066)
		(layer "F.Cu")
		(net "M_F_CPU0_SA_DQS_DP<4>")
	)
	(segment
		(start 424.762168 -275.94179)
		(end 424.788076 -275.94179)
		(width 0.101854)
		(layer "F.Cu")
		(net "M_F_CPU0_SA_DQS_DP<4>")
	)
	(segment
		(start 423.685716 -275.690584)
		(end 424.371516 -275.690584)
		(width 0.20066)
		(layer "F.Cu")
		(net "M_F_CPU0_SA_DQS_DP<4>")
	)
	(segment
		(start 424.622722 -275.94179)
		(end 424.762168 -275.94179)
		(width 0.20066)
		(layer "F.Cu")
		(net "M_F_CPU0_SA_DQS_DP<4>")
	)
	(segment
		(start 420.736014 -275.516594)
		(end 421.840914 -275.516594)
		(width 0.20066)
		(layer "F.Cu")
		(net "M_F_CPU0_SA_DQS_DP<4>")
	)
	(segment
		(start 427.274736 -275.947886)
		(end 427.57725 -275.645372)
		(width 0.20066)
		(layer "F.Cu")
		(net "M_F_CPU0_SA_DQS_DP<4>")
	)
	(segment
		(start 423.271188 -275.276056)
		(end 423.685716 -275.690584)
		(width 0.20066)
		(layer "F.Cu")
		(net "M_F_CPU0_SA_DQS_DP<4>")
	)
	(segment
		(start 426.945298 -275.94179)
		(end 426.951394 -275.947886)
		(width 0.1016)
		(layer "F.Cu")
		(net "M_F_CPU0_SA_DQS_DP<4>")
	)
	(segment
		(start 422.430194 -275.516594)
		(end 422.670732 -275.276056)
		(width 0.20066)
		(layer "F.Cu")
		(net "M_F_CPU0_SA_DQS_DP<4>")
	)
	(segment
		(start 428.836074 -275.516594)
		(end 429.384714 -275.516594)
		(width 0.20066)
		(layer "F.Cu")
		(net "M_F_CPU0_SA_DQS_DP<4>")
	)
	(segment
		(start 424.788076 -275.94179)
		(end 426.945298 -275.94179)
		(width 0.1016)
		(layer "F.Cu")
		(net "M_F_CPU0_SA_DQS_DP<4>")
	)
	(segment
		(start 421.840914 -275.516594)
		(end 422.430194 -275.516594)
		(width 0.20066)
		(layer "F.Cu")
		(net "M_F_CPU0_SA_DQS_DP<4>")
	)
	(segment
		(start 424.371516 -275.690584)
		(end 424.622722 -275.94179)
		(width 0.20066)
		(layer "F.Cu")
		(net "M_F_CPU0_SA_DQS_DP<4>")
	)
	(segment
		(start 380.835916 -262.87222)
		(end 380.835662 -262.872474)
		(width 0.20066)
		(layer "F.Cu")
		(net "M_F_CPU0_SA_DQS_DP<4>")
	)
	(segment
		(start 380.835916 -262.336534)
		(end 380.835916 -262.87222)
		(width 0.20066)
		(layer "F.Cu")
		(net "M_F_CPU0_SA_DQS_DP<4>")
	)
	(segment
		(start 409.870402 -275.229574)
		(end 409.870402 -275.213318)
		(width 0.16002)
		(layer "In2.Cu")
		(net "M_F_CPU0_SA_DQS_DP<4>")
	)
	(segment
		(start 406.129236 -273.954494)
		(end 405.816562 -274.267168)
		(width 0.18288)
		(layer "In2.Cu")
		(net "M_F_CPU0_SA_DQS_DP<4>")
	)
	(segment
		(start 419.565074 -275.046186)
		(end 419.53688 -275.07438)
		(width 0.16002)
		(layer "In2.Cu")
		(net "M_F_CPU0_SA_DQS_DP<4>")
	)
	(segment
		(start 391.799318 -263.385554)
		(end 388.840472 -263.385554)
		(width 0.18288)
		(layer "In2.Cu")
		(net "M_F_CPU0_SA_DQS_DP<4>")
	)
	(segment
		(start 415.436812 -275.924264)
		(end 415.420556 -275.924264)
		(width 0.16002)
		(layer "In2.Cu")
		(net "M_F_CPU0_SA_DQS_DP<4>")
	)
	(segment
		(start 410.323284 -275.682456)
		(end 409.898596 -275.257768)
		(width 0.18288)
		(layer "In2.Cu")
		(net "M_F_CPU0_SA_DQS_DP<4>")
	)
	(segment
		(start 408.026362 -274.267168)
		(end 407.691844 -274.267168)
		(width 0.18288)
		(layer "In2.Cu")
		(net "M_F_CPU0_SA_DQS_DP<4>")
	)
	(segment
		(start 420.534338 -275.314918)
		(end 420.20998 -275.314918)
		(width 0.18288)
		(layer "In2.Cu")
		(net "M_F_CPU0_SA_DQS_DP<4>")
	)
	(segment
		(start 381.148336 -262.872474)
		(end 380.835662 -262.872474)
		(width 0.088646)
		(layer "In2.Cu")
		(net "M_F_CPU0_SA_DQS_DP<4>")
	)
	(segment
		(start 420.20998 -275.314918)
		(end 419.838632 -274.94357)
		(width 0.18288)
		(layer "In2.Cu")
		(net "M_F_CPU0_SA_DQS_DP<4>")
	)
	(segment
		(start 417.442396 -275.257768)
		(end 417.414202 -275.229574)
		(width 0.16002)
		(layer "In2.Cu")
		(net "M_F_CPU0_SA_DQS_DP<4>")
	)
	(segment
		(start 413.085534 -275.850858)
		(end 412.884112 -275.649436)
		(width 0.18288)
		(layer "In2.Cu")
		(net "M_F_CPU0_SA_DQS_DP<4>")
	)
	(segment
		(start 382.443228 -263.368282)
		(end 382.432814 -263.362186)
		(width 0.088646)
		(layer "In2.Cu")
		(net "M_F_CPU0_SA_DQS_DP<4>")
	)
	(segment
		(start 405.131016 -273.91614)
		(end 404.560024 -273.91614)
		(width 0.18288)
		(layer "In2.Cu")
		(net "M_F_CPU0_SA_DQS_DP<4>")
	)
	(segment
		(start 408.305508 -273.988022)
		(end 408.026362 -274.267168)
		(width 0.18288)
		(layer "In2.Cu")
		(net "M_F_CPU0_SA_DQS_DP<4>")
	)
	(segment
		(start 417.641278 -275.45665)
		(end 417.442396 -275.257768)
		(width 0.18288)
		(layer "In2.Cu")
		(net "M_F_CPU0_SA_DQS_DP<4>")
	)
	(segment
		(start 381.213868 -262.938006)
		(end 381.148336 -262.872474)
		(width 0.088646)
		(layer "In2.Cu")
		(net "M_F_CPU0_SA_DQS_DP<4>")
	)
	(segment
		(start 388.780782 -263.325864)
		(end 387.859778 -263.325864)
		(width 0.088646)
		(layer "In2.Cu")
		(net "M_F_CPU0_SA_DQS_DP<4>")
	)
	(segment
		(start 413.129984 -275.879052)
		(end 413.113728 -275.879052)
		(width 0.16002)
		(layer "In2.Cu")
		(net "M_F_CPU0_SA_DQS_DP<4>")
	)
	(segment
		(start 405.482044 -274.267168)
		(end 405.131016 -273.91614)
		(width 0.18288)
		(layer "In2.Cu")
		(net "M_F_CPU0_SA_DQS_DP<4>")
	)
	(segment
		(start 403.179534 -271.31772)
		(end 398.052544 -266.19073)
		(width 0.18288)
		(layer "In2.Cu")
		(net "M_F_CPU0_SA_DQS_DP<4>")
	)
	(segment
		(start 419.53688 -275.07438)
		(end 419.520624 -275.07438)
		(width 0.16002)
		(layer "In2.Cu")
		(net "M_F_CPU0_SA_DQS_DP<4>")
	)
	(segment
		(start 415.420556 -275.924264)
		(end 415.282126 -276.062694)
		(width 0.16002)
		(layer "In2.Cu")
		(net "M_F_CPU0_SA_DQS_DP<4>")
	)
	(segment
		(start 417.185602 -275.000974)
		(end 417.06292 -274.878292)
		(width 0.18288)
		(layer "In2.Cu")
		(net "M_F_CPU0_SA_DQS_DP<4>")
	)
	(segment
		(start 419.382194 -275.229066)
		(end 419.354 -275.25726)
		(width 0.16002)
		(layer "In2.Cu")
		(net "M_F_CPU0_SA_DQS_DP<4>")
	)
	(segment
		(start 398.052544 -266.19073)
		(end 395.042898 -266.19073)
		(width 0.18288)
		(layer "In2.Cu")
		(net "M_F_CPU0_SA_DQS_DP<4>")
	)
	(segment
		(start 388.840472 -263.385554)
		(end 388.780782 -263.325864)
		(width 0.088646)
		(layer "In2.Cu")
		(net "M_F_CPU0_SA_DQS_DP<4>")
	)
	(segment
		(start 409.898596 -275.257768)
		(end 409.870402 -275.229574)
		(width 0.16002)
		(layer "In2.Cu")
		(net "M_F_CPU0_SA_DQS_DP<4>")
	)
	(segment
		(start 392.548364 -263.696196)
		(end 391.799318 -263.385554)
		(width 0.18288)
		(layer "In2.Cu")
		(net "M_F_CPU0_SA_DQS_DP<4>")
	)
	(segment
		(start 411.77464 -275.96719)
		(end 411.489906 -275.682456)
		(width 0.18288)
		(layer "In2.Cu")
		(net "M_F_CPU0_SA_DQS_DP<4>")
	)
	(segment
		(start 409.686252 -275.029168)
		(end 409.669996 -275.029168)
		(width 0.16002)
		(layer "In2.Cu")
		(net "M_F_CPU0_SA_DQS_DP<4>")
	)
	(segment
		(start 412.524448 -275.649436)
		(end 412.206694 -275.96719)
		(width 0.18288)
		(layer "In2.Cu")
		(net "M_F_CPU0_SA_DQS_DP<4>")
	)
	(segment
		(start 416.482784 -274.878292)
		(end 415.465006 -275.89607)
		(width 0.18288)
		(layer "In2.Cu")
		(net "M_F_CPU0_SA_DQS_DP<4>")
	)
	(segment
		(start 408.62885 -273.988022)
		(end 408.305508 -273.988022)
		(width 0.18288)
		(layer "In2.Cu")
		(net "M_F_CPU0_SA_DQS_DP<4>")
	)
	(segment
		(start 415.054542 -276.306534)
		(end 413.54121 -276.306534)
		(width 0.18288)
		(layer "In2.Cu")
		(net "M_F_CPU0_SA_DQS_DP<4>")
	)
	(segment
		(start 404.042118 -273.398234)
		(end 403.179534 -271.31772)
		(width 0.18288)
		(layer "In2.Cu")
		(net "M_F_CPU0_SA_DQS_DP<4>")
	)
	(segment
		(start 415.282126 -276.07895)
		(end 415.253932 -276.107144)
		(width 0.16002)
		(layer "In2.Cu")
		(net "M_F_CPU0_SA_DQS_DP<4>")
	)
	(segment
		(start 412.206694 -275.96719)
		(end 411.77464 -275.96719)
		(width 0.18288)
		(layer "In2.Cu")
		(net "M_F_CPU0_SA_DQS_DP<4>")
	)
	(segment
		(start 412.884112 -275.649436)
		(end 412.524448 -275.649436)
		(width 0.18288)
		(layer "In2.Cu")
		(net "M_F_CPU0_SA_DQS_DP<4>")
	)
	(segment
		(start 405.816562 -274.267168)
		(end 405.482044 -274.267168)
		(width 0.18288)
		(layer "In2.Cu")
		(net "M_F_CPU0_SA_DQS_DP<4>")
	)
	(segment
		(start 413.314134 -276.063202)
		(end 413.129984 -275.879052)
		(width 0.16002)
		(layer "In2.Cu")
		(net "M_F_CPU0_SA_DQS_DP<4>")
	)
	(segment
		(start 411.489906 -275.682456)
		(end 410.323284 -275.682456)
		(width 0.18288)
		(layer "In2.Cu")
		(net "M_F_CPU0_SA_DQS_DP<4>")
	)
	(segment
		(start 417.230052 -275.029168)
		(end 417.213796 -275.029168)
		(width 0.16002)
		(layer "In2.Cu")
		(net "M_F_CPU0_SA_DQS_DP<4>")
	)
	(segment
		(start 419.838632 -274.94357)
		(end 419.66769 -274.94357)
		(width 0.18288)
		(layer "In2.Cu")
		(net "M_F_CPU0_SA_DQS_DP<4>")
	)
	(segment
		(start 417.06292 -274.878292)
		(end 416.482784 -274.878292)
		(width 0.18288)
		(layer "In2.Cu")
		(net "M_F_CPU0_SA_DQS_DP<4>")
	)
	(segment
		(start 413.113728 -275.879052)
		(end 413.085534 -275.850858)
		(width 0.16002)
		(layer "In2.Cu")
		(net "M_F_CPU0_SA_DQS_DP<4>")
	)
	(segment
		(start 404.560024 -273.91614)
		(end 404.042118 -273.398234)
		(width 0.18288)
		(layer "In2.Cu")
		(net "M_F_CPU0_SA_DQS_DP<4>")
	)
	(segment
		(start 419.382194 -275.21281)
		(end 419.382194 -275.229066)
		(width 0.16002)
		(layer "In2.Cu")
		(net "M_F_CPU0_SA_DQS_DP<4>")
	)
	(segment
		(start 419.520624 -275.07438)
		(end 419.382194 -275.21281)
		(width 0.16002)
		(layer "In2.Cu")
		(net "M_F_CPU0_SA_DQS_DP<4>")
	)
	(segment
		(start 409.870402 -275.213318)
		(end 409.686252 -275.029168)
		(width 0.16002)
		(layer "In2.Cu")
		(net "M_F_CPU0_SA_DQS_DP<4>")
	)
	(segment
		(start 409.641802 -275.000974)
		(end 408.62885 -273.988022)
		(width 0.18288)
		(layer "In2.Cu")
		(net "M_F_CPU0_SA_DQS_DP<4>")
	)
	(segment
		(start 413.342328 -276.107652)
		(end 413.314134 -276.079458)
		(width 0.16002)
		(layer "In2.Cu")
		(net "M_F_CPU0_SA_DQS_DP<4>")
	)
	(segment
		(start 409.669996 -275.029168)
		(end 409.641802 -275.000974)
		(width 0.16002)
		(layer "In2.Cu")
		(net "M_F_CPU0_SA_DQS_DP<4>")
	)
	(segment
		(start 417.213796 -275.029168)
		(end 417.185602 -275.000974)
		(width 0.16002)
		(layer "In2.Cu")
		(net "M_F_CPU0_SA_DQS_DP<4>")
	)
	(segment
		(start 413.54121 -276.306534)
		(end 413.342328 -276.107652)
		(width 0.18288)
		(layer "In2.Cu")
		(net "M_F_CPU0_SA_DQS_DP<4>")
	)
	(segment
		(start 386.757164 -263.362186)
		(end 386.742432 -263.370822)
		(width 0.088646)
		(layer "In2.Cu")
		(net "M_F_CPU0_SA_DQS_DP<4>")
	)
	(segment
		(start 417.414202 -275.213318)
		(end 417.230052 -275.029168)
		(width 0.16002)
		(layer "In2.Cu")
		(net "M_F_CPU0_SA_DQS_DP<4>")
	)
	(segment
		(start 420.736014 -275.516594)
		(end 420.534338 -275.314918)
		(width 0.18288)
		(layer "In2.Cu")
		(net "M_F_CPU0_SA_DQS_DP<4>")
	)
	(segment
		(start 413.314134 -276.079458)
		(end 413.314134 -276.063202)
		(width 0.16002)
		(layer "In2.Cu")
		(net "M_F_CPU0_SA_DQS_DP<4>")
	)
	(segment
		(start 395.042898 -266.19073)
		(end 392.548364 -263.696196)
		(width 0.18288)
		(layer "In2.Cu")
		(net "M_F_CPU0_SA_DQS_DP<4>")
	)
	(segment
		(start 415.282126 -276.062694)
		(end 415.282126 -276.07895)
		(width 0.16002)
		(layer "In2.Cu")
		(net "M_F_CPU0_SA_DQS_DP<4>")
	)
	(segment
		(start 419.354 -275.25726)
		(end 419.15461 -275.45665)
		(width 0.18288)
		(layer "In2.Cu")
		(net "M_F_CPU0_SA_DQS_DP<4>")
	)
	(segment
		(start 407.691844 -274.267168)
		(end 407.37917 -273.954494)
		(width 0.18288)
		(layer "In2.Cu")
		(net "M_F_CPU0_SA_DQS_DP<4>")
	)
	(segment
		(start 415.253932 -276.107144)
		(end 415.054542 -276.306534)
		(width 0.18288)
		(layer "In2.Cu")
		(net "M_F_CPU0_SA_DQS_DP<4>")
	)
	(segment
		(start 415.465006 -275.89607)
		(end 415.436812 -275.924264)
		(width 0.16002)
		(layer "In2.Cu")
		(net "M_F_CPU0_SA_DQS_DP<4>")
	)
	(segment
		(start 417.414202 -275.229574)
		(end 417.414202 -275.213318)
		(width 0.16002)
		(layer "In2.Cu")
		(net "M_F_CPU0_SA_DQS_DP<4>")
	)
	(segment
		(start 419.15461 -275.45665)
		(end 417.641278 -275.45665)
		(width 0.18288)
		(layer "In2.Cu")
		(net "M_F_CPU0_SA_DQS_DP<4>")
	)
	(segment
		(start 419.66769 -274.94357)
		(end 419.565074 -275.046186)
		(width 0.18288)
		(layer "In2.Cu")
		(net "M_F_CPU0_SA_DQS_DP<4>")
	)
	(segment
		(start 407.37917 -273.954494)
		(end 406.129236 -273.954494)
		(width 0.18288)
		(layer "In2.Cu")
		(net "M_F_CPU0_SA_DQS_DP<4>")
	)
	(arc
		(start 386.19176 -263.362186)
		(mid 386.004562 -263.312043)
		(end 385.817364 -263.362186)
		(width 0.088646)
		(layer "In2.Cu")
		(net "M_F_CPU0_SA_DQS_DP<4>")
	)
	(arc
		(start 385.25196 -263.362186)
		(mid 385.064762 -263.312043)
		(end 384.877564 -263.362186)
		(width 0.088646)
		(layer "In2.Cu")
		(net "M_F_CPU0_SA_DQS_DP<4>")
	)
	(arc
		(start 382.432814 -263.362186)
		(mid 382.245616 -263.312043)
		(end 382.058418 -263.362186)
		(width 0.088646)
		(layer "In2.Cu")
		(net "M_F_CPU0_SA_DQS_DP<4>")
	)
	(arc
		(start 387.13156 -263.362186)
		(mid 386.944362 -263.312043)
		(end 386.757164 -263.362186)
		(width 0.088646)
		(layer "In2.Cu")
		(net "M_F_CPU0_SA_DQS_DP<4>")
	)
	(arc
		(start 386.742432 -263.370822)
		(mid 386.465991 -263.437988)
		(end 386.19176 -263.362186)
		(width 0.088646)
		(layer "In2.Cu")
		(net "M_F_CPU0_SA_DQS_DP<4>")
	)
	(arc
		(start 383.937764 -263.362186)
		(mid 383.655062 -263.437928)
		(end 383.37236 -263.362186)
		(width 0.088646)
		(layer "In2.Cu")
		(net "M_F_CPU0_SA_DQS_DP<4>")
	)
	(arc
		(start 382.058418 -263.362186)
		(mid 381.531216 -263.382598)
		(end 381.216662 -262.959088)
		(width 0.088646)
		(layer "In2.Cu")
		(net "M_F_CPU0_SA_DQS_DP<4>")
	)
	(arc
		(start 387.859778 -263.325864)
		(mid 387.768217 -263.337337)
		(end 387.682232 -263.370822)
		(width 0.088646)
		(layer "In2.Cu")
		(net "M_F_CPU0_SA_DQS_DP<4>")
	)
	(arc
		(start 383.37236 -263.362186)
		(mid 383.185162 -263.312043)
		(end 382.997964 -263.362186)
		(width 0.088646)
		(layer "In2.Cu")
		(net "M_F_CPU0_SA_DQS_DP<4>")
	)
	(arc
		(start 387.682232 -263.370822)
		(mid 387.405791 -263.437988)
		(end 387.13156 -263.362186)
		(width 0.088646)
		(layer "In2.Cu")
		(net "M_F_CPU0_SA_DQS_DP<4>")
	)
	(arc
		(start 381.216662 -262.959088)
		(mid 381.215166 -262.94856)
		(end 381.213868 -262.938006)
		(width 0.088646)
		(layer "In2.Cu")
		(net "M_F_CPU0_SA_DQS_DP<4>")
	)
	(arc
		(start 385.817364 -263.362186)
		(mid 385.534662 -263.437928)
		(end 385.25196 -263.362186)
		(width 0.088646)
		(layer "In2.Cu")
		(net "M_F_CPU0_SA_DQS_DP<4>")
	)
	(arc
		(start 382.997964 -263.362186)
		(mid 382.721405 -263.437895)
		(end 382.443228 -263.368282)
		(width 0.088646)
		(layer "In2.Cu")
		(net "M_F_CPU0_SA_DQS_DP<4>")
	)
	(arc
		(start 384.877564 -263.362186)
		(mid 384.594862 -263.437928)
		(end 384.31216 -263.362186)
		(width 0.088646)
		(layer "In2.Cu")
		(net "M_F_CPU0_SA_DQS_DP<4>")
	)
	(arc
		(start 384.31216 -263.362186)
		(mid 384.124962 -263.312043)
		(end 383.937764 -263.362186)
		(width 0.088646)
		(layer "In2.Cu")
		(net "M_F_CPU0_SA_DQS_DP<4>")
	)
	(segment
		(start 427.274736 -285.29788)
		(end 427.57725 -284.995366)
		(width 0.20066)
		(layer "F.Cu")
		(net "M_F_CPU0_SA_DQS_DP<3>")
	)
	(segment
		(start 424.762168 -285.291784)
		(end 424.788076 -285.291784)
		(width 0.101854)
		(layer "F.Cu")
		(net "M_F_CPU0_SA_DQS_DP<3>")
	)
	(segment
		(start 421.840914 -284.866588)
		(end 422.430194 -284.866588)
		(width 0.20066)
		(layer "F.Cu")
		(net "M_F_CPU0_SA_DQS_DP<3>")
	)
	(segment
		(start 426.945298 -285.291784)
		(end 426.951394 -285.29788)
		(width 0.1016)
		(layer "F.Cu")
		(net "M_F_CPU0_SA_DQS_DP<3>")
	)
	(segment
		(start 428.836074 -284.866588)
		(end 429.384714 -284.866588)
		(width 0.20066)
		(layer "F.Cu")
		(net "M_F_CPU0_SA_DQS_DP<3>")
	)
	(segment
		(start 422.430194 -284.866588)
		(end 422.670732 -284.62605)
		(width 0.20066)
		(layer "F.Cu")
		(net "M_F_CPU0_SA_DQS_DP<3>")
	)
	(segment
		(start 426.951394 -285.29788)
		(end 427.274736 -285.29788)
		(width 0.20066)
		(layer "F.Cu")
		(net "M_F_CPU0_SA_DQS_DP<3>")
	)
	(segment
		(start 423.685716 -285.040578)
		(end 424.371516 -285.040578)
		(width 0.20066)
		(layer "F.Cu")
		(net "M_F_CPU0_SA_DQS_DP<3>")
	)
	(segment
		(start 428.3583 -284.584902)
		(end 428.554388 -284.584902)
		(width 0.20066)
		(layer "F.Cu")
		(net "M_F_CPU0_SA_DQS_DP<3>")
	)
	(segment
		(start 424.622722 -285.291784)
		(end 424.762168 -285.291784)
		(width 0.20066)
		(layer "F.Cu")
		(net "M_F_CPU0_SA_DQS_DP<3>")
	)
	(segment
		(start 428.554388 -284.584902)
		(end 428.836074 -284.866588)
		(width 0.20066)
		(layer "F.Cu")
		(net "M_F_CPU0_SA_DQS_DP<3>")
	)
	(segment
		(start 424.371516 -285.040578)
		(end 424.622722 -285.291784)
		(width 0.20066)
		(layer "F.Cu")
		(net "M_F_CPU0_SA_DQS_DP<3>")
	)
	(segment
		(start 377.546362 -260.430518)
		(end 377.546616 -260.430772)
		(width 0.20066)
		(layer "F.Cu")
		(net "M_F_CPU0_SA_DQS_DP<3>")
	)
	(segment
		(start 427.57725 -284.995366)
		(end 427.947836 -284.995366)
		(width 0.20066)
		(layer "F.Cu")
		(net "M_F_CPU0_SA_DQS_DP<3>")
	)
	(segment
		(start 422.670732 -284.62605)
		(end 423.271188 -284.62605)
		(width 0.20066)
		(layer "F.Cu")
		(net "M_F_CPU0_SA_DQS_DP<3>")
	)
	(segment
		(start 377.546362 -259.894832)
		(end 377.546362 -260.430518)
		(width 0.20066)
		(layer "F.Cu")
		(net "M_F_CPU0_SA_DQS_DP<3>")
	)
	(segment
		(start 420.736014 -284.866588)
		(end 421.840914 -284.866588)
		(width 0.20066)
		(layer "F.Cu")
		(net "M_F_CPU0_SA_DQS_DP<3>")
	)
	(segment
		(start 423.271188 -284.62605)
		(end 423.685716 -285.040578)
		(width 0.20066)
		(layer "F.Cu")
		(net "M_F_CPU0_SA_DQS_DP<3>")
	)
	(segment
		(start 424.788076 -285.291784)
		(end 426.945298 -285.291784)
		(width 0.1016)
		(layer "F.Cu")
		(net "M_F_CPU0_SA_DQS_DP<3>")
	)
	(segment
		(start 427.947836 -284.995366)
		(end 428.3583 -284.584902)
		(width 0.20066)
		(layer "F.Cu")
		(net "M_F_CPU0_SA_DQS_DP<3>")
	)
	(segment
		(start 396.485364 -262.993632)
		(end 393.620244 -262.993632)
		(width 0.18288)
		(layer "In4.Cu")
		(net "M_F_CPU0_SA_DQS_DP<3>")
	)
	(segment
		(start 379.708664 -260.920484)
		(end 379.693932 -260.92912)
		(width 0.088646)
		(layer "In4.Cu")
		(net "M_F_CPU0_SA_DQS_DP<3>")
	)
	(segment
		(start 391.87882 -261.968996)
		(end 389.41375 -260.947916)
		(width 0.18288)
		(layer "In4.Cu")
		(net "M_F_CPU0_SA_DQS_DP<3>")
	)
	(segment
		(start 419.207442 -284.275022)
		(end 418.139372 -283.207206)
		(width 0.18288)
		(layer "In4.Cu")
		(net "M_F_CPU0_SA_DQS_DP<3>")
	)
	(segment
		(start 386.31876 -260.887972)
		(end 386.286756 -260.919976)
		(width 0.088646)
		(layer "In4.Cu")
		(net "M_F_CPU0_SA_DQS_DP<3>")
	)
	(segment
		(start 419.815264 -284.275022)
		(end 419.207442 -284.275022)
		(width 0.18288)
		(layer "In4.Cu")
		(net "M_F_CPU0_SA_DQS_DP<3>")
	)
	(segment
		(start 405.16556 -271.673828)
		(end 396.485364 -262.993632)
		(width 0.18288)
		(layer "In4.Cu")
		(net "M_F_CPU0_SA_DQS_DP<3>")
	)
	(segment
		(start 416.375342 -276.347428)
		(end 415.692844 -275.66493)
		(width 0.18288)
		(layer "In4.Cu")
		(net "M_F_CPU0_SA_DQS_DP<3>")
	)
	(segment
		(start 408.629612 -273.725386)
		(end 406.578054 -271.673828)
		(width 0.18288)
		(layer "In4.Cu")
		(net "M_F_CPU0_SA_DQS_DP<3>")
	)
	(segment
		(start 378.768864 -260.920484)
		(end 378.754132 -260.92912)
		(width 0.088646)
		(layer "In4.Cu")
		(net "M_F_CPU0_SA_DQS_DP<3>")
	)
	(segment
		(start 385.722114 -260.919976)
		(end 385.721606 -260.920484)
		(width 0.088646)
		(layer "In4.Cu")
		(net "M_F_CPU0_SA_DQS_DP<3>")
	)
	(segment
		(start 417.717224 -282.130246)
		(end 416.375342 -280.78811)
		(width 0.18288)
		(layer "In4.Cu")
		(net "M_F_CPU0_SA_DQS_DP<3>")
	)
	(segment
		(start 418.139372 -283.207206)
		(end 417.717224 -282.130246)
		(width 0.18288)
		(layer "In4.Cu")
		(net "M_F_CPU0_SA_DQS_DP<3>")
	)
	(segment
		(start 420.736014 -284.866588)
		(end 420.455852 -284.586426)
		(width 0.18288)
		(layer "In4.Cu")
		(net "M_F_CPU0_SA_DQS_DP<3>")
	)
	(segment
		(start 382.528064 -260.920484)
		(end 382.513332 -260.92912)
		(width 0.088646)
		(layer "In4.Cu")
		(net "M_F_CPU0_SA_DQS_DP<3>")
	)
	(segment
		(start 393.620244 -262.993632)
		(end 392.396472 -262.486648)
		(width 0.18288)
		(layer "In4.Cu")
		(net "M_F_CPU0_SA_DQS_DP<3>")
	)
	(segment
		(start 389.41375 -260.947916)
		(end 386.808218 -260.947916)
		(width 0.18288)
		(layer "In4.Cu")
		(net "M_F_CPU0_SA_DQS_DP<3>")
	)
	(segment
		(start 415.692844 -275.66493)
		(end 413.692086 -275.66493)
		(width 0.18288)
		(layer "In4.Cu")
		(net "M_F_CPU0_SA_DQS_DP<3>")
	)
	(segment
		(start 380.648464 -260.920484)
		(end 380.633732 -260.92912)
		(width 0.088646)
		(layer "In4.Cu")
		(net "M_F_CPU0_SA_DQS_DP<3>")
	)
	(segment
		(start 416.375342 -280.78811)
		(end 416.375342 -276.347428)
		(width 0.18288)
		(layer "In4.Cu")
		(net "M_F_CPU0_SA_DQS_DP<3>")
	)
	(segment
		(start 386.78485 -260.947916)
		(end 386.724906 -260.887972)
		(width 0.088646)
		(layer "In4.Cu")
		(net "M_F_CPU0_SA_DQS_DP<3>")
	)
	(segment
		(start 413.692086 -275.66493)
		(end 411.752542 -273.725386)
		(width 0.18288)
		(layer "In4.Cu")
		(net "M_F_CPU0_SA_DQS_DP<3>")
	)
	(segment
		(start 384.40741 -260.920484)
		(end 384.396996 -260.92658)
		(width 0.088646)
		(layer "In4.Cu")
		(net "M_F_CPU0_SA_DQS_DP<3>")
	)
	(segment
		(start 386.808218 -260.947916)
		(end 386.78485 -260.947916)
		(width 0.088646)
		(layer "In4.Cu")
		(net "M_F_CPU0_SA_DQS_DP<3>")
	)
	(segment
		(start 411.752542 -273.725386)
		(end 408.629612 -273.725386)
		(width 0.18288)
		(layer "In4.Cu")
		(net "M_F_CPU0_SA_DQS_DP<3>")
	)
	(segment
		(start 420.455852 -284.586426)
		(end 420.126668 -284.586426)
		(width 0.18288)
		(layer "In4.Cu")
		(net "M_F_CPU0_SA_DQS_DP<3>")
	)
	(segment
		(start 392.396472 -262.486648)
		(end 391.87882 -261.968996)
		(width 0.18288)
		(layer "In4.Cu")
		(net "M_F_CPU0_SA_DQS_DP<3>")
	)
	(segment
		(start 386.724906 -260.887972)
		(end 386.31876 -260.887972)
		(width 0.088646)
		(layer "In4.Cu")
		(net "M_F_CPU0_SA_DQS_DP<3>")
	)
	(segment
		(start 377.924568 -260.49605)
		(end 377.85929 -260.430772)
		(width 0.088646)
		(layer "In4.Cu")
		(net "M_F_CPU0_SA_DQS_DP<3>")
	)
	(segment
		(start 406.578054 -271.673828)
		(end 405.16556 -271.673828)
		(width 0.18288)
		(layer "In4.Cu")
		(net "M_F_CPU0_SA_DQS_DP<3>")
	)
	(segment
		(start 377.85929 -260.430772)
		(end 377.546616 -260.430772)
		(width 0.088646)
		(layer "In4.Cu")
		(net "M_F_CPU0_SA_DQS_DP<3>")
	)
	(segment
		(start 420.126668 -284.586426)
		(end 419.815264 -284.275022)
		(width 0.18288)
		(layer "In4.Cu")
		(net "M_F_CPU0_SA_DQS_DP<3>")
	)
	(arc
		(start 385.34721 -260.920484)
		(mid 385.064508 -260.996226)
		(end 384.781806 -260.920484)
		(width 0.088646)
		(layer "In4.Cu")
		(net "M_F_CPU0_SA_DQS_DP<3>")
	)
	(arc
		(start 382.90246 -260.920484)
		(mid 382.715262 -260.870341)
		(end 382.528064 -260.920484)
		(width 0.088646)
		(layer "In4.Cu")
		(net "M_F_CPU0_SA_DQS_DP<3>")
	)
	(arc
		(start 381.96266 -260.920484)
		(mid 381.775462 -260.870341)
		(end 381.588264 -260.920484)
		(width 0.088646)
		(layer "In4.Cu")
		(net "M_F_CPU0_SA_DQS_DP<3>")
	)
	(arc
		(start 379.14326 -260.920484)
		(mid 378.956062 -260.870341)
		(end 378.768864 -260.920484)
		(width 0.088646)
		(layer "In4.Cu")
		(net "M_F_CPU0_SA_DQS_DP<3>")
	)
	(arc
		(start 384.781806 -260.920484)
		(mid 384.594608 -260.870341)
		(end 384.40741 -260.920484)
		(width 0.088646)
		(layer "In4.Cu")
		(net "M_F_CPU0_SA_DQS_DP<3>")
	)
	(arc
		(start 383.84226 -260.920484)
		(mid 383.655062 -260.870341)
		(end 383.467864 -260.920484)
		(width 0.088646)
		(layer "In4.Cu")
		(net "M_F_CPU0_SA_DQS_DP<3>")
	)
	(arc
		(start 379.693932 -260.92912)
		(mid 379.417491 -260.996286)
		(end 379.14326 -260.920484)
		(width 0.088646)
		(layer "In4.Cu")
		(net "M_F_CPU0_SA_DQS_DP<3>")
	)
	(arc
		(start 386.286756 -260.919976)
		(mid 386.004452 -260.995532)
		(end 385.722114 -260.919976)
		(width 0.088646)
		(layer "In4.Cu")
		(net "M_F_CPU0_SA_DQS_DP<3>")
	)
	(arc
		(start 381.588264 -260.920484)
		(mid 381.305562 -260.996226)
		(end 381.02286 -260.920484)
		(width 0.088646)
		(layer "In4.Cu")
		(net "M_F_CPU0_SA_DQS_DP<3>")
	)
	(arc
		(start 385.721606 -260.920484)
		(mid 385.534408 -260.870341)
		(end 385.34721 -260.920484)
		(width 0.088646)
		(layer "In4.Cu")
		(net "M_F_CPU0_SA_DQS_DP<3>")
	)
	(arc
		(start 380.08306 -260.920484)
		(mid 379.895862 -260.870341)
		(end 379.708664 -260.920484)
		(width 0.088646)
		(layer "In4.Cu")
		(net "M_F_CPU0_SA_DQS_DP<3>")
	)
	(arc
		(start 383.467864 -260.920484)
		(mid 383.185162 -260.996226)
		(end 382.90246 -260.920484)
		(width 0.088646)
		(layer "In4.Cu")
		(net "M_F_CPU0_SA_DQS_DP<3>")
	)
	(arc
		(start 378.754132 -260.92912)
		(mid 378.234228 -260.937155)
		(end 377.927362 -260.517386)
		(width 0.088646)
		(layer "In4.Cu")
		(net "M_F_CPU0_SA_DQS_DP<3>")
	)
	(arc
		(start 377.927362 -260.517386)
		(mid 377.925864 -260.506731)
		(end 377.924568 -260.49605)
		(width 0.088646)
		(layer "In4.Cu")
		(net "M_F_CPU0_SA_DQS_DP<3>")
	)
	(arc
		(start 384.396996 -260.92658)
		(mid 384.118818 -260.996272)
		(end 383.84226 -260.920484)
		(width 0.088646)
		(layer "In4.Cu")
		(net "M_F_CPU0_SA_DQS_DP<3>")
	)
	(arc
		(start 380.633732 -260.92912)
		(mid 380.357291 -260.996286)
		(end 380.08306 -260.920484)
		(width 0.088646)
		(layer "In4.Cu")
		(net "M_F_CPU0_SA_DQS_DP<3>")
	)
	(arc
		(start 381.02286 -260.920484)
		(mid 380.835662 -260.870341)
		(end 380.648464 -260.920484)
		(width 0.088646)
		(layer "In4.Cu")
		(net "M_F_CPU0_SA_DQS_DP<3>")
	)
	(arc
		(start 382.513332 -260.92912)
		(mid 382.236891 -260.996286)
		(end 381.96266 -260.920484)
		(width 0.088646)
		(layer "In4.Cu")
		(net "M_F_CPU0_SA_DQS_DP<3>")
	)
	(segment
		(start 427.57725 -294.34536)
		(end 427.947836 -294.34536)
		(width 0.20066)
		(layer "F.Cu")
		(net "M_F_CPU0_SA_DQS_DP<2>")
	)
	(segment
		(start 421.840914 -294.216582)
		(end 422.430194 -294.216582)
		(width 0.20066)
		(layer "F.Cu")
		(net "M_F_CPU0_SA_DQS_DP<2>")
	)
	(segment
		(start 424.788076 -294.641778)
		(end 426.945298 -294.641778)
		(width 0.1016)
		(layer "F.Cu")
		(net "M_F_CPU0_SA_DQS_DP<2>")
	)
	(segment
		(start 426.951394 -294.647874)
		(end 427.274736 -294.647874)
		(width 0.20066)
		(layer "F.Cu")
		(net "M_F_CPU0_SA_DQS_DP<2>")
	)
	(segment
		(start 424.622722 -294.641778)
		(end 424.762168 -294.641778)
		(width 0.20066)
		(layer "F.Cu")
		(net "M_F_CPU0_SA_DQS_DP<2>")
	)
	(segment
		(start 428.3583 -293.934896)
		(end 428.554388 -293.934896)
		(width 0.20066)
		(layer "F.Cu")
		(net "M_F_CPU0_SA_DQS_DP<2>")
	)
	(segment
		(start 424.371516 -294.390572)
		(end 424.622722 -294.641778)
		(width 0.20066)
		(layer "F.Cu")
		(net "M_F_CPU0_SA_DQS_DP<2>")
	)
	(segment
		(start 381.775716 -267.755624)
		(end 381.775462 -267.755878)
		(width 0.20066)
		(layer "F.Cu")
		(net "M_F_CPU0_SA_DQS_DP<2>")
	)
	(segment
		(start 428.554388 -293.934896)
		(end 428.836074 -294.216582)
		(width 0.20066)
		(layer "F.Cu")
		(net "M_F_CPU0_SA_DQS_DP<2>")
	)
	(segment
		(start 420.736014 -294.216582)
		(end 421.840914 -294.216582)
		(width 0.20066)
		(layer "F.Cu")
		(net "M_F_CPU0_SA_DQS_DP<2>")
	)
	(segment
		(start 424.762168 -294.641778)
		(end 424.788076 -294.641778)
		(width 0.101854)
		(layer "F.Cu")
		(net "M_F_CPU0_SA_DQS_DP<2>")
	)
	(segment
		(start 381.775716 -267.219938)
		(end 381.775716 -267.755624)
		(width 0.20066)
		(layer "F.Cu")
		(net "M_F_CPU0_SA_DQS_DP<2>")
	)
	(segment
		(start 427.947836 -294.34536)
		(end 428.3583 -293.934896)
		(width 0.20066)
		(layer "F.Cu")
		(net "M_F_CPU0_SA_DQS_DP<2>")
	)
	(segment
		(start 423.271188 -293.976044)
		(end 423.685716 -294.390572)
		(width 0.20066)
		(layer "F.Cu")
		(net "M_F_CPU0_SA_DQS_DP<2>")
	)
	(segment
		(start 423.685716 -294.390572)
		(end 424.371516 -294.390572)
		(width 0.20066)
		(layer "F.Cu")
		(net "M_F_CPU0_SA_DQS_DP<2>")
	)
	(segment
		(start 427.274736 -294.647874)
		(end 427.57725 -294.34536)
		(width 0.20066)
		(layer "F.Cu")
		(net "M_F_CPU0_SA_DQS_DP<2>")
	)
	(segment
		(start 422.430194 -294.216582)
		(end 422.670732 -293.976044)
		(width 0.20066)
		(layer "F.Cu")
		(net "M_F_CPU0_SA_DQS_DP<2>")
	)
	(segment
		(start 426.945298 -294.641778)
		(end 426.951394 -294.647874)
		(width 0.1016)
		(layer "F.Cu")
		(net "M_F_CPU0_SA_DQS_DP<2>")
	)
	(segment
		(start 428.836074 -294.216582)
		(end 429.384714 -294.216582)
		(width 0.20066)
		(layer "F.Cu")
		(net "M_F_CPU0_SA_DQS_DP<2>")
	)
	(segment
		(start 422.670732 -293.976044)
		(end 423.271188 -293.976044)
		(width 0.20066)
		(layer "F.Cu")
		(net "M_F_CPU0_SA_DQS_DP<2>")
	)
	(segment
		(start 388.190486 -268.19479)
		(end 387.884162 -268.19479)
		(width 0.088646)
		(layer "In2.Cu")
		(net "M_F_CPU0_SA_DQS_DP<2>")
	)
	(segment
		(start 417.473384 -293.993316)
		(end 417.289234 -293.809166)
		(width 0.16002)
		(layer "In2.Cu")
		(net "M_F_CPU0_SA_DQS_DP<2>")
	)
	(segment
		(start 415.182304 -287.9344)
		(end 414.885632 -287.811464)
		(width 0.18288)
		(layer "In2.Cu")
		(net "M_F_CPU0_SA_DQS_DP<2>")
	)
	(segment
		(start 388.405878 -268.410182)
		(end 388.190486 -268.19479)
		(width 0.088646)
		(layer "In2.Cu")
		(net "M_F_CPU0_SA_DQS_DP<2>")
	)
	(segment
		(start 402.364702 -280.814272)
		(end 402.364702 -280.63825)
		(width 0.18288)
		(layer "In2.Cu")
		(net "M_F_CPU0_SA_DQS_DP<2>")
	)
	(segment
		(start 416.42157 -292.709854)
		(end 416.236658 -292.192964)
		(width 0.18288)
		(layer "In2.Cu")
		(net "M_F_CPU0_SA_DQS_DP<2>")
	)
	(segment
		(start 388.840472 -268.470126)
		(end 388.780528 -268.410182)
		(width 0.088646)
		(layer "In2.Cu")
		(net "M_F_CPU0_SA_DQS_DP<2>")
	)
	(segment
		(start 403.506686 -282.047442)
		(end 403.316948 -281.590242)
		(width 0.18288)
		(layer "In2.Cu")
		(net "M_F_CPU0_SA_DQS_DP<2>")
	)
	(segment
		(start 415.549334 -288.301684)
		(end 415.182304 -287.9344)
		(width 0.18288)
		(layer "In2.Cu")
		(net "M_F_CPU0_SA_DQS_DP<2>")
	)
	(segment
		(start 398.830546 -277.103586)
		(end 398.48028 -276.25802)
		(width 0.18288)
		(layer "In2.Cu")
		(net "M_F_CPU0_SA_DQS_DP<2>")
	)
	(segment
		(start 398.874488 -277.147528)
		(end 398.830546 -277.103586)
		(width 0.18288)
		(layer "In2.Cu")
		(net "M_F_CPU0_SA_DQS_DP<2>")
	)
	(segment
		(start 420.408862 -293.88943)
		(end 420.041578 -293.88943)
		(width 0.18288)
		(layer "In2.Cu")
		(net "M_F_CPU0_SA_DQS_DP<2>")
	)
	(segment
		(start 396.769844 -273.811492)
		(end 396.769844 -273.63547)
		(width 0.18288)
		(layer "In2.Cu")
		(net "M_F_CPU0_SA_DQS_DP<2>")
	)
	(segment
		(start 399.508726 -277.957788)
		(end 399.508726 -277.78202)
		(width 0.18288)
		(layer "In2.Cu")
		(net "M_F_CPU0_SA_DQS_DP<2>")
	)
	(segment
		(start 420.041578 -293.88943)
		(end 419.870382 -293.718234)
		(width 0.18288)
		(layer "In2.Cu")
		(net "M_F_CPU0_SA_DQS_DP<2>")
	)
	(segment
		(start 407.4414 -286.070294)
		(end 407.425652 -286.070294)
		(width 0.16002)
		(layer "In2.Cu")
		(net "M_F_CPU0_SA_DQS_DP<2>")
	)
	(segment
		(start 383.383028 -268.251432)
		(end 383.372614 -268.245336)
		(width 0.088646)
		(layer "In2.Cu")
		(net "M_F_CPU0_SA_DQS_DP<2>")
	)
	(segment
		(start 403.316948 -281.590242)
		(end 403.316694 -281.590242)
		(width 0.18288)
		(layer "In2.Cu")
		(net "M_F_CPU0_SA_DQS_DP<2>")
	)
	(segment
		(start 410.590238 -288.2392)
		(end 410.465778 -288.11474)
		(width 0.18288)
		(layer "In2.Cu")
		(net "M_F_CPU0_SA_DQS_DP<2>")
	)
	(segment
		(start 416.236658 -292.192964)
		(end 416.312096 -292.03396)
		(width 0.18288)
		(layer "In2.Cu")
		(net "M_F_CPU0_SA_DQS_DP<2>")
	)
	(segment
		(start 405.253698 -285.057596)
		(end 404.763986 -284.567884)
		(width 0.18288)
		(layer "In2.Cu")
		(net "M_F_CPU0_SA_DQS_DP<2>")
	)
	(segment
		(start 406.167336 -285.831788)
		(end 405.922988 -285.58744)
		(width 0.18288)
		(layer "In2.Cu")
		(net "M_F_CPU0_SA_DQS_DP<2>")
	)
	(segment
		(start 419.146482 -294.18407)
		(end 417.647882 -294.18407)
		(width 0.18288)
		(layer "In2.Cu")
		(net "M_F_CPU0_SA_DQS_DP<2>")
	)
	(segment
		(start 407.397458 -286.0421)
		(end 407.187146 -285.831788)
		(width 0.18288)
		(layer "In2.Cu")
		(net "M_F_CPU0_SA_DQS_DP<2>")
	)
	(segment
		(start 401.41271 -279.86228)
		(end 401.41271 -279.686258)
		(width 0.18288)
		(layer "In2.Cu")
		(net "M_F_CPU0_SA_DQS_DP<2>")
	)
	(segment
		(start 398.174972 -275.520912)
		(end 397.835628 -274.701254)
		(width 0.18288)
		(layer "In2.Cu")
		(net "M_F_CPU0_SA_DQS_DP<2>")
	)
	(segment
		(start 419.870382 -293.718234)
		(end 419.612318 -293.718234)
		(width 0.18288)
		(layer "In2.Cu")
		(net "M_F_CPU0_SA_DQS_DP<2>")
	)
	(segment
		(start 407.802588 -286.44723)
		(end 407.654252 -286.298894)
		(width 0.18288)
		(layer "In2.Cu")
		(net "M_F_CPU0_SA_DQS_DP<2>")
	)
	(segment
		(start 416.765486 -293.301674)
		(end 416.580828 -292.785292)
		(width 0.18288)
		(layer "In2.Cu")
		(net "M_F_CPU0_SA_DQS_DP<2>")
	)
	(segment
		(start 416.580828 -292.785292)
		(end 416.42157 -292.709854)
		(width 0.18288)
		(layer "In2.Cu")
		(net "M_F_CPU0_SA_DQS_DP<2>")
	)
	(segment
		(start 407.626058 -286.254952)
		(end 407.4414 -286.070294)
		(width 0.16002)
		(layer "In2.Cu")
		(net "M_F_CPU0_SA_DQS_DP<2>")
	)
	(segment
		(start 400.07286 -278.346154)
		(end 399.896838 -278.346154)
		(width 0.18288)
		(layer "In2.Cu")
		(net "M_F_CPU0_SA_DQS_DP<2>")
	)
	(segment
		(start 417.272978 -293.809166)
		(end 417.244784 -293.780972)
		(width 0.16002)
		(layer "In2.Cu")
		(net "M_F_CPU0_SA_DQS_DP<2>")
	)
	(segment
		(start 405.710644 -285.35884)
		(end 405.694388 -285.35884)
		(width 0.16002)
		(layer "In2.Cu")
		(net "M_F_CPU0_SA_DQS_DP<2>")
	)
	(segment
		(start 411.974792 -287.855914)
		(end 411.715966 -288.11474)
		(width 0.18288)
		(layer "In2.Cu")
		(net "M_F_CPU0_SA_DQS_DP<2>")
	)
	(segment
		(start 417.244784 -293.780972)
		(end 416.765486 -293.301674)
		(width 0.18288)
		(layer "In2.Cu")
		(net "M_F_CPU0_SA_DQS_DP<2>")
	)
	(segment
		(start 417.473384 -294.009572)
		(end 417.473384 -293.993316)
		(width 0.16002)
		(layer "In2.Cu")
		(net "M_F_CPU0_SA_DQS_DP<2>")
	)
	(segment
		(start 412.517082 -287.961324)
		(end 412.411672 -287.855914)
		(width 0.18288)
		(layer "In2.Cu")
		(net "M_F_CPU0_SA_DQS_DP<2>")
	)
	(segment
		(start 407.187146 -285.831788)
		(end 406.167336 -285.831788)
		(width 0.18288)
		(layer "In2.Cu")
		(net "M_F_CPU0_SA_DQS_DP<2>")
	)
	(segment
		(start 411.138878 -288.2392)
		(end 410.590238 -288.2392)
		(width 0.18288)
		(layer "In2.Cu")
		(net "M_F_CPU0_SA_DQS_DP<2>")
	)
	(segment
		(start 415.569908 -289.958526)
		(end 415.845244 -289.293808)
		(width 0.18288)
		(layer "In2.Cu")
		(net "M_F_CPU0_SA_DQS_DP<2>")
	)
	(segment
		(start 398.48028 -276.25802)
		(end 398.317466 -276.19071)
		(width 0.18288)
		(layer "In2.Cu")
		(net "M_F_CPU0_SA_DQS_DP<2>")
	)
	(segment
		(start 401.800822 -280.250392)
		(end 401.41271 -279.86228)
		(width 0.18288)
		(layer "In2.Cu")
		(net "M_F_CPU0_SA_DQS_DP<2>")
	)
	(segment
		(start 402.364702 -280.63825)
		(end 401.976844 -280.250392)
		(width 0.18288)
		(layer "In2.Cu")
		(net "M_F_CPU0_SA_DQS_DP<2>")
	)
	(segment
		(start 419.297866 -294.032686)
		(end 419.269672 -294.06088)
		(width 0.16002)
		(layer "In2.Cu")
		(net "M_F_CPU0_SA_DQS_DP<2>")
	)
	(segment
		(start 400.460718 -278.910034)
		(end 400.460718 -278.734012)
		(width 0.18288)
		(layer "In2.Cu")
		(net "M_F_CPU0_SA_DQS_DP<2>")
	)
	(segment
		(start 397.333978 -274.199858)
		(end 397.157956 -274.199858)
		(width 0.18288)
		(layer "In2.Cu")
		(net "M_F_CPU0_SA_DQS_DP<2>")
	)
	(segment
		(start 399.896838 -278.346154)
		(end 399.508726 -277.957788)
		(width 0.18288)
		(layer "In2.Cu")
		(net "M_F_CPU0_SA_DQS_DP<2>")
	)
	(segment
		(start 409.917138 -288.11474)
		(end 409.471114 -287.668716)
		(width 0.18288)
		(layer "In2.Cu")
		(net "M_F_CPU0_SA_DQS_DP<2>")
	)
	(segment
		(start 400.84883 -279.2984)
		(end 400.460718 -278.910034)
		(width 0.18288)
		(layer "In2.Cu")
		(net "M_F_CPU0_SA_DQS_DP<2>")
	)
	(segment
		(start 412.411672 -287.855914)
		(end 411.974792 -287.855914)
		(width 0.18288)
		(layer "In2.Cu")
		(net "M_F_CPU0_SA_DQS_DP<2>")
	)
	(segment
		(start 408.906726 -287.28035)
		(end 408.906726 -287.104328)
		(width 0.18288)
		(layer "In2.Cu")
		(net "M_F_CPU0_SA_DQS_DP<2>")
	)
	(segment
		(start 399.508726 -277.78202)
		(end 398.874488 -277.147528)
		(width 0.18288)
		(layer "In2.Cu")
		(net "M_F_CPU0_SA_DQS_DP<2>")
	)
	(segment
		(start 403.506686 -283.310584)
		(end 403.506686 -282.047442)
		(width 0.18288)
		(layer "In2.Cu")
		(net "M_F_CPU0_SA_DQS_DP<2>")
	)
	(segment
		(start 411.715966 -288.11474)
		(end 411.263338 -288.11474)
		(width 0.18288)
		(layer "In2.Cu")
		(net "M_F_CPU0_SA_DQS_DP<2>")
	)
	(segment
		(start 414.885632 -287.811464)
		(end 413.716216 -287.811464)
		(width 0.18288)
		(layer "In2.Cu")
		(net "M_F_CPU0_SA_DQS_DP<2>")
	)
	(segment
		(start 402.752814 -281.202384)
		(end 402.364702 -280.814272)
		(width 0.18288)
		(layer "In2.Cu")
		(net "M_F_CPU0_SA_DQS_DP<2>")
	)
	(segment
		(start 403.316694 -281.590242)
		(end 402.928836 -281.202384)
		(width 0.18288)
		(layer "In2.Cu")
		(net "M_F_CPU0_SA_DQS_DP<2>")
	)
	(segment
		(start 397.835628 -274.701254)
		(end 397.835374 -274.701254)
		(width 0.18288)
		(layer "In2.Cu")
		(net "M_F_CPU0_SA_DQS_DP<2>")
	)
	(segment
		(start 405.393144 -285.057596)
		(end 405.253698 -285.057596)
		(width 0.18288)
		(layer "In2.Cu")
		(net "M_F_CPU0_SA_DQS_DP<2>")
	)
	(segment
		(start 405.894794 -285.54299)
		(end 405.710644 -285.35884)
		(width 0.16002)
		(layer "In2.Cu")
		(net "M_F_CPU0_SA_DQS_DP<2>")
	)
	(segment
		(start 413.354266 -287.961324)
		(end 412.517082 -287.961324)
		(width 0.18288)
		(layer "In2.Cu")
		(net "M_F_CPU0_SA_DQS_DP<2>")
	)
	(segment
		(start 419.494716 -293.835836)
		(end 419.47846 -293.835836)
		(width 0.16002)
		(layer "In2.Cu")
		(net "M_F_CPU0_SA_DQS_DP<2>")
	)
	(segment
		(start 400.460718 -278.734012)
		(end 400.07286 -278.346154)
		(width 0.18288)
		(layer "In2.Cu")
		(net "M_F_CPU0_SA_DQS_DP<2>")
	)
	(segment
		(start 405.894794 -285.559246)
		(end 405.894794 -285.54299)
		(width 0.16002)
		(layer "In2.Cu")
		(net "M_F_CPU0_SA_DQS_DP<2>")
	)
	(segment
		(start 415.845244 -289.293808)
		(end 415.845244 -289.015932)
		(width 0.18288)
		(layer "In2.Cu")
		(net "M_F_CPU0_SA_DQS_DP<2>")
	)
	(segment
		(start 390.34212 -268.470126)
		(end 388.840472 -268.470126)
		(width 0.18288)
		(layer "In2.Cu")
		(net "M_F_CPU0_SA_DQS_DP<2>")
	)
	(segment
		(start 407.626058 -286.2707)
		(end 407.626058 -286.254952)
		(width 0.16002)
		(layer "In2.Cu")
		(net "M_F_CPU0_SA_DQS_DP<2>")
	)
	(segment
		(start 407.425652 -286.070294)
		(end 407.397458 -286.0421)
		(width 0.16002)
		(layer "In2.Cu")
		(net "M_F_CPU0_SA_DQS_DP<2>")
	)
	(segment
		(start 419.269672 -294.06088)
		(end 419.146482 -294.18407)
		(width 0.18288)
		(layer "In2.Cu")
		(net "M_F_CPU0_SA_DQS_DP<2>")
	)
	(segment
		(start 394.557758 -272.528284)
		(end 390.610852 -268.581632)
		(width 0.18288)
		(layer "In2.Cu")
		(net "M_F_CPU0_SA_DQS_DP<2>")
	)
	(segment
		(start 411.263338 -288.11474)
		(end 411.138878 -288.2392)
		(width 0.18288)
		(layer "In2.Cu")
		(net "M_F_CPU0_SA_DQS_DP<2>")
	)
	(segment
		(start 410.465778 -288.11474)
		(end 409.917138 -288.11474)
		(width 0.18288)
		(layer "In2.Cu")
		(net "M_F_CPU0_SA_DQS_DP<2>")
	)
	(segment
		(start 415.845244 -289.015932)
		(end 415.549334 -288.301684)
		(width 0.18288)
		(layer "In2.Cu")
		(net "M_F_CPU0_SA_DQS_DP<2>")
	)
	(segment
		(start 404.763986 -284.567884)
		(end 404.587964 -284.567884)
		(width 0.18288)
		(layer "In2.Cu")
		(net "M_F_CPU0_SA_DQS_DP<2>")
	)
	(segment
		(start 402.928836 -281.202384)
		(end 402.752814 -281.202384)
		(width 0.18288)
		(layer "In2.Cu")
		(net "M_F_CPU0_SA_DQS_DP<2>")
	)
	(segment
		(start 404.199852 -284.00375)
		(end 403.506686 -283.310584)
		(width 0.18288)
		(layer "In2.Cu")
		(net "M_F_CPU0_SA_DQS_DP<2>")
	)
	(segment
		(start 409.295092 -287.668716)
		(end 408.906726 -287.28035)
		(width 0.18288)
		(layer "In2.Cu")
		(net "M_F_CPU0_SA_DQS_DP<2>")
	)
	(segment
		(start 404.199852 -284.179772)
		(end 404.199852 -284.00375)
		(width 0.18288)
		(layer "In2.Cu")
		(net "M_F_CPU0_SA_DQS_DP<2>")
	)
	(segment
		(start 382.447546 -268.253972)
		(end 382.339342 -268.191234)
		(width 0.088646)
		(layer "In2.Cu")
		(net "M_F_CPU0_SA_DQS_DP<2>")
	)
	(segment
		(start 401.41271 -279.686258)
		(end 401.024852 -279.2984)
		(width 0.18288)
		(layer "In2.Cu")
		(net "M_F_CPU0_SA_DQS_DP<2>")
	)
	(segment
		(start 382.010666 -267.779754)
		(end 381.98679 -267.755878)
		(width 0.088646)
		(layer "In2.Cu")
		(net "M_F_CPU0_SA_DQS_DP<2>")
	)
	(segment
		(start 408.906726 -287.104328)
		(end 408.249628 -286.44723)
		(width 0.18288)
		(layer "In2.Cu")
		(net "M_F_CPU0_SA_DQS_DP<2>")
	)
	(segment
		(start 405.666194 -285.330646)
		(end 405.393144 -285.057596)
		(width 0.18288)
		(layer "In2.Cu")
		(net "M_F_CPU0_SA_DQS_DP<2>")
	)
	(segment
		(start 409.471114 -287.668716)
		(end 409.295092 -287.668716)
		(width 0.18288)
		(layer "In2.Cu")
		(net "M_F_CPU0_SA_DQS_DP<2>")
	)
	(segment
		(start 405.922988 -285.58744)
		(end 405.894794 -285.559246)
		(width 0.16002)
		(layer "In2.Cu")
		(net "M_F_CPU0_SA_DQS_DP<2>")
	)
	(segment
		(start 382.339342 -268.191234)
		(end 382.010666 -267.779754)
		(width 0.088646)
		(layer "In2.Cu")
		(net "M_F_CPU0_SA_DQS_DP<2>")
	)
	(segment
		(start 388.780528 -268.410182)
		(end 388.405878 -268.410182)
		(width 0.088646)
		(layer "In2.Cu")
		(net "M_F_CPU0_SA_DQS_DP<2>")
	)
	(segment
		(start 407.654252 -286.298894)
		(end 407.626058 -286.2707)
		(width 0.16002)
		(layer "In2.Cu")
		(net "M_F_CPU0_SA_DQS_DP<2>")
	)
	(segment
		(start 395.742414 -272.60804)
		(end 395.646148 -272.568162)
		(width 0.18288)
		(layer "In2.Cu")
		(net "M_F_CPU0_SA_DQS_DP<2>")
	)
	(segment
		(start 405.694388 -285.35884)
		(end 405.666194 -285.330646)
		(width 0.16002)
		(layer "In2.Cu")
		(net "M_F_CPU0_SA_DQS_DP<2>")
	)
	(segment
		(start 396.769844 -273.63547)
		(end 395.742414 -272.60804)
		(width 0.18288)
		(layer "In2.Cu")
		(net "M_F_CPU0_SA_DQS_DP<2>")
	)
	(segment
		(start 404.587964 -284.567884)
		(end 404.199852 -284.179772)
		(width 0.18288)
		(layer "In2.Cu")
		(net "M_F_CPU0_SA_DQS_DP<2>")
	)
	(segment
		(start 417.501578 -294.037766)
		(end 417.473384 -294.009572)
		(width 0.16002)
		(layer "In2.Cu")
		(net "M_F_CPU0_SA_DQS_DP<2>")
	)
	(segment
		(start 419.297866 -294.01643)
		(end 419.297866 -294.032686)
		(width 0.16002)
		(layer "In2.Cu")
		(net "M_F_CPU0_SA_DQS_DP<2>")
	)
	(segment
		(start 381.98679 -267.755878)
		(end 381.775462 -267.755878)
		(width 0.088646)
		(layer "In2.Cu")
		(net "M_F_CPU0_SA_DQS_DP<2>")
	)
	(segment
		(start 398.317466 -276.19071)
		(end 398.107662 -275.683472)
		(width 0.18288)
		(layer "In2.Cu")
		(net "M_F_CPU0_SA_DQS_DP<2>")
	)
	(segment
		(start 401.976844 -280.250392)
		(end 401.800822 -280.250392)
		(width 0.18288)
		(layer "In2.Cu")
		(net "M_F_CPU0_SA_DQS_DP<2>")
	)
	(segment
		(start 416.312096 -292.03396)
		(end 415.569908 -289.958526)
		(width 0.18288)
		(layer "In2.Cu")
		(net "M_F_CPU0_SA_DQS_DP<2>")
	)
	(segment
		(start 417.289234 -293.809166)
		(end 417.272978 -293.809166)
		(width 0.16002)
		(layer "In2.Cu")
		(net "M_F_CPU0_SA_DQS_DP<2>")
	)
	(segment
		(start 408.249628 -286.44723)
		(end 407.802588 -286.44723)
		(width 0.18288)
		(layer "In2.Cu")
		(net "M_F_CPU0_SA_DQS_DP<2>")
	)
	(segment
		(start 420.736014 -294.216582)
		(end 420.408862 -293.88943)
		(width 0.18288)
		(layer "In2.Cu")
		(net "M_F_CPU0_SA_DQS_DP<2>")
	)
	(segment
		(start 419.612318 -293.718234)
		(end 419.494716 -293.835836)
		(width 0.18288)
		(layer "In2.Cu")
		(net "M_F_CPU0_SA_DQS_DP<2>")
	)
	(segment
		(start 390.610852 -268.581632)
		(end 390.34212 -268.470126)
		(width 0.18288)
		(layer "In2.Cu")
		(net "M_F_CPU0_SA_DQS_DP<2>")
	)
	(segment
		(start 395.646148 -272.568162)
		(end 395.549374 -272.528284)
		(width 0.18288)
		(layer "In2.Cu")
		(net "M_F_CPU0_SA_DQS_DP<2>")
	)
	(segment
		(start 395.549374 -272.528284)
		(end 394.557758 -272.528284)
		(width 0.18288)
		(layer "In2.Cu")
		(net "M_F_CPU0_SA_DQS_DP<2>")
	)
	(segment
		(start 401.024852 -279.2984)
		(end 400.84883 -279.2984)
		(width 0.18288)
		(layer "In2.Cu")
		(net "M_F_CPU0_SA_DQS_DP<2>")
	)
	(segment
		(start 417.647882 -294.18407)
		(end 417.501578 -294.037766)
		(width 0.18288)
		(layer "In2.Cu")
		(net "M_F_CPU0_SA_DQS_DP<2>")
	)
	(segment
		(start 419.47846 -293.835836)
		(end 419.297866 -294.01643)
		(width 0.16002)
		(layer "In2.Cu")
		(net "M_F_CPU0_SA_DQS_DP<2>")
	)
	(segment
		(start 397.835374 -274.701254)
		(end 397.333978 -274.199858)
		(width 0.18288)
		(layer "In2.Cu")
		(net "M_F_CPU0_SA_DQS_DP<2>")
	)
	(segment
		(start 413.716216 -287.811464)
		(end 413.354266 -287.961324)
		(width 0.18288)
		(layer "In2.Cu")
		(net "M_F_CPU0_SA_DQS_DP<2>")
	)
	(segment
		(start 398.107662 -275.683472)
		(end 398.174972 -275.520912)
		(width 0.18288)
		(layer "In2.Cu")
		(net "M_F_CPU0_SA_DQS_DP<2>")
	)
	(segment
		(start 397.157956 -274.199858)
		(end 396.769844 -273.811492)
		(width 0.18288)
		(layer "In2.Cu")
		(net "M_F_CPU0_SA_DQS_DP<2>")
	)
	(arc
		(start 387.696964 -268.245336)
		(mid 387.414262 -268.321112)
		(end 387.13156 -268.245336)
		(width 0.088646)
		(layer "In2.Cu")
		(net "M_F_CPU0_SA_DQS_DP<2>")
	)
	(arc
		(start 387.13156 -268.245336)
		(mid 386.944362 -268.195193)
		(end 386.757164 -268.245336)
		(width 0.088646)
		(layer "In2.Cu")
		(net "M_F_CPU0_SA_DQS_DP<2>")
	)
	(arc
		(start 382.998218 -268.245336)
		(mid 382.724019 -268.321171)
		(end 382.447546 -268.253972)
		(width 0.088646)
		(layer "In2.Cu")
		(net "M_F_CPU0_SA_DQS_DP<2>")
	)
	(arc
		(start 384.31216 -268.245336)
		(mid 384.124962 -268.195193)
		(end 383.937764 -268.245336)
		(width 0.088646)
		(layer "In2.Cu")
		(net "M_F_CPU0_SA_DQS_DP<2>")
	)
	(arc
		(start 384.877564 -268.245336)
		(mid 384.594862 -268.321112)
		(end 384.31216 -268.245336)
		(width 0.088646)
		(layer "In2.Cu")
		(net "M_F_CPU0_SA_DQS_DP<2>")
	)
	(arc
		(start 386.757164 -268.245336)
		(mid 386.474462 -268.321112)
		(end 386.19176 -268.245336)
		(width 0.088646)
		(layer "In2.Cu")
		(net "M_F_CPU0_SA_DQS_DP<2>")
	)
	(arc
		(start 385.817364 -268.245336)
		(mid 385.534662 -268.321112)
		(end 385.25196 -268.245336)
		(width 0.088646)
		(layer "In2.Cu")
		(net "M_F_CPU0_SA_DQS_DP<2>")
	)
	(arc
		(start 383.372614 -268.245336)
		(mid 383.185416 -268.195193)
		(end 382.998218 -268.245336)
		(width 0.088646)
		(layer "In2.Cu")
		(net "M_F_CPU0_SA_DQS_DP<2>")
	)
	(arc
		(start 386.19176 -268.245336)
		(mid 386.004562 -268.195193)
		(end 385.817364 -268.245336)
		(width 0.088646)
		(layer "In2.Cu")
		(net "M_F_CPU0_SA_DQS_DP<2>")
	)
	(arc
		(start 387.884162 -268.19479)
		(mid 387.787234 -268.207741)
		(end 387.696964 -268.245336)
		(width 0.088646)
		(layer "In2.Cu")
		(net "M_F_CPU0_SA_DQS_DP<2>")
	)
	(arc
		(start 383.937764 -268.245336)
		(mid 383.661205 -268.321079)
		(end 383.383028 -268.251432)
		(width 0.088646)
		(layer "In2.Cu")
		(net "M_F_CPU0_SA_DQS_DP<2>")
	)
	(arc
		(start 385.25196 -268.245336)
		(mid 385.064762 -268.195193)
		(end 384.877564 -268.245336)
		(width 0.088646)
		(layer "In2.Cu")
		(net "M_F_CPU0_SA_DQS_DP<2>")
	)
	(segment
		(start 423.271188 -303.326038)
		(end 423.685716 -303.740566)
		(width 0.20066)
		(layer "F.Cu")
		(net "M_F_CPU0_SA_DQS_DP<1>")
	)
	(segment
		(start 428.554388 -303.28489)
		(end 428.836074 -303.566576)
		(width 0.20066)
		(layer "F.Cu")
		(net "M_F_CPU0_SA_DQS_DP<1>")
	)
	(segment
		(start 424.762168 -303.991772)
		(end 424.788076 -303.991772)
		(width 0.101854)
		(layer "F.Cu")
		(net "M_F_CPU0_SA_DQS_DP<1>")
	)
	(segment
		(start 424.371516 -303.740566)
		(end 424.622722 -303.991772)
		(width 0.20066)
		(layer "F.Cu")
		(net "M_F_CPU0_SA_DQS_DP<1>")
	)
	(segment
		(start 427.947836 -303.695354)
		(end 428.3583 -303.28489)
		(width 0.20066)
		(layer "F.Cu")
		(net "M_F_CPU0_SA_DQS_DP<1>")
	)
	(segment
		(start 427.274736 -303.997868)
		(end 427.57725 -303.695354)
		(width 0.20066)
		(layer "F.Cu")
		(net "M_F_CPU0_SA_DQS_DP<1>")
	)
	(segment
		(start 426.951394 -303.997868)
		(end 427.274736 -303.997868)
		(width 0.20066)
		(layer "F.Cu")
		(net "M_F_CPU0_SA_DQS_DP<1>")
	)
	(segment
		(start 423.685716 -303.740566)
		(end 424.371516 -303.740566)
		(width 0.20066)
		(layer "F.Cu")
		(net "M_F_CPU0_SA_DQS_DP<1>")
	)
	(segment
		(start 422.430194 -303.566576)
		(end 422.670732 -303.326038)
		(width 0.20066)
		(layer "F.Cu")
		(net "M_F_CPU0_SA_DQS_DP<1>")
	)
	(segment
		(start 428.3583 -303.28489)
		(end 428.554388 -303.28489)
		(width 0.20066)
		(layer "F.Cu")
		(net "M_F_CPU0_SA_DQS_DP<1>")
	)
	(segment
		(start 378.486162 -269.66164)
		(end 378.486416 -270.167862)
		(width 0.20066)
		(layer "F.Cu")
		(net "M_F_CPU0_SA_DQS_DP<1>")
	)
	(segment
		(start 427.57725 -303.695354)
		(end 427.947836 -303.695354)
		(width 0.20066)
		(layer "F.Cu")
		(net "M_F_CPU0_SA_DQS_DP<1>")
	)
	(segment
		(start 428.836074 -303.566576)
		(end 429.384714 -303.566576)
		(width 0.20066)
		(layer "F.Cu")
		(net "M_F_CPU0_SA_DQS_DP<1>")
	)
	(segment
		(start 424.622722 -303.991772)
		(end 424.762168 -303.991772)
		(width 0.20066)
		(layer "F.Cu")
		(net "M_F_CPU0_SA_DQS_DP<1>")
	)
	(segment
		(start 424.788076 -303.991772)
		(end 426.945298 -303.991772)
		(width 0.1016)
		(layer "F.Cu")
		(net "M_F_CPU0_SA_DQS_DP<1>")
	)
	(segment
		(start 378.486416 -270.167862)
		(end 378.486416 -270.19758)
		(width 0.20066)
		(layer "F.Cu")
		(net "M_F_CPU0_SA_DQS_DP<1>")
	)
	(segment
		(start 420.736014 -303.566576)
		(end 421.840914 -303.566576)
		(width 0.20066)
		(layer "F.Cu")
		(net "M_F_CPU0_SA_DQS_DP<1>")
	)
	(segment
		(start 422.670732 -303.326038)
		(end 423.271188 -303.326038)
		(width 0.20066)
		(layer "F.Cu")
		(net "M_F_CPU0_SA_DQS_DP<1>")
	)
	(segment
		(start 426.945298 -303.991772)
		(end 426.951394 -303.997868)
		(width 0.1016)
		(layer "F.Cu")
		(net "M_F_CPU0_SA_DQS_DP<1>")
	)
	(segment
		(start 421.840914 -303.566576)
		(end 422.430194 -303.566576)
		(width 0.20066)
		(layer "F.Cu")
		(net "M_F_CPU0_SA_DQS_DP<1>")
	)
	(segment
		(start 414.240472 -302.159924)
		(end 413.717232 -301.636684)
		(width 0.18288)
		(layer "In4.Cu")
		(net "M_F_CPU0_SA_DQS_DP<1>")
	)
	(segment
		(start 419.841426 -303.10836)
		(end 419.295326 -303.10836)
		(width 0.18288)
		(layer "In4.Cu")
		(net "M_F_CPU0_SA_DQS_DP<1>")
	)
	(segment
		(start 410.208222 -299.478192)
		(end 409.945332 -299.741082)
		(width 0.18288)
		(layer "In4.Cu")
		(net "M_F_CPU0_SA_DQS_DP<1>")
	)
	(segment
		(start 380.096014 -270.69415)
		(end 380.085092 -270.688308)
		(width 0.088646)
		(layer "In4.Cu")
		(net "M_F_CPU0_SA_DQS_DP<1>")
	)
	(segment
		(start 418.624766 -303.23282)
		(end 418.500306 -303.10836)
		(width 0.18288)
		(layer "In4.Cu")
		(net "M_F_CPU0_SA_DQS_DP<1>")
	)
	(segment
		(start 379.093984 -270.65859)
		(end 379.029214 -270.607536)
		(width 0.088646)
		(layer "In4.Cu")
		(net "M_F_CPU0_SA_DQS_DP<1>")
	)
	(segment
		(start 402.639276 -293.792148)
		(end 402.252942 -293.405814)
		(width 0.18288)
		(layer "In4.Cu")
		(net "M_F_CPU0_SA_DQS_DP<1>")
	)
	(segment
		(start 404.149814 -295.302686)
		(end 404.149814 -295.126664)
		(width 0.18288)
		(layer "In4.Cu")
		(net "M_F_CPU0_SA_DQS_DP<1>")
	)
	(segment
		(start 386.187696 -271.498314)
		(end 386.185918 -271.497298)
		(width 0.088646)
		(layer "In4.Cu")
		(net "M_F_CPU0_SA_DQS_DP<1>")
	)
	(segment
		(start 416.816286 -303.10836)
		(end 416.691826 -303.23282)
		(width 0.18288)
		(layer "In4.Cu")
		(net "M_F_CPU0_SA_DQS_DP<1>")
	)
	(segment
		(start 403.587712 -294.740584)
		(end 403.201378 -294.35425)
		(width 0.18288)
		(layer "In4.Cu")
		(net "M_F_CPU0_SA_DQS_DP<1>")
	)
	(segment
		(start 419.170866 -303.23282)
		(end 418.624766 -303.23282)
		(width 0.18288)
		(layer "In4.Cu")
		(net "M_F_CPU0_SA_DQS_DP<1>")
	)
	(segment
		(start 413.263334 -301.333408)
		(end 413.090614 -301.367698)
		(width 0.18288)
		(layer "In4.Cu")
		(net "M_F_CPU0_SA_DQS_DP<1>")
	)
	(segment
		(start 404.71217 -295.68902)
		(end 404.536148 -295.68902)
		(width 0.18288)
		(layer "In4.Cu")
		(net "M_F_CPU0_SA_DQS_DP<1>")
	)
	(segment
		(start 416.021266 -303.10836)
		(end 415.188908 -303.10836)
		(width 0.18288)
		(layer "In4.Cu")
		(net "M_F_CPU0_SA_DQS_DP<1>")
	)
	(segment
		(start 409.945332 -299.741082)
		(end 409.57627 -299.741082)
		(width 0.18288)
		(layer "In4.Cu")
		(net "M_F_CPU0_SA_DQS_DP<1>")
	)
	(segment
		(start 405.09825 -296.0751)
		(end 404.71217 -295.68902)
		(width 0.18288)
		(layer "In4.Cu")
		(net "M_F_CPU0_SA_DQS_DP<1>")
	)
	(segment
		(start 378.700284 -270.195548)
		(end 378.697744 -270.19758)
		(width 0.088646)
		(layer "In4.Cu")
		(net "M_F_CPU0_SA_DQS_DP<1>")
	)
	(segment
		(start 386.189728 -271.499584)
		(end 386.187696 -271.498314)
		(width 0.088646)
		(layer "In4.Cu")
		(net "M_F_CPU0_SA_DQS_DP<1>")
	)
	(segment
		(start 414.802828 -302.72228)
		(end 414.626806 -302.72228)
		(width 0.18288)
		(layer "In4.Cu")
		(net "M_F_CPU0_SA_DQS_DP<1>")
	)
	(segment
		(start 411.153356 -299.923962)
		(end 410.486098 -299.478192)
		(width 0.18288)
		(layer "In4.Cu")
		(net "M_F_CPU0_SA_DQS_DP<1>")
	)
	(segment
		(start 410.486098 -299.478192)
		(end 410.208222 -299.478192)
		(width 0.18288)
		(layer "In4.Cu")
		(net "M_F_CPU0_SA_DQS_DP<1>")
	)
	(segment
		(start 420.020242 -303.287176)
		(end 419.841426 -303.10836)
		(width 0.18288)
		(layer "In4.Cu")
		(net "M_F_CPU0_SA_DQS_DP<1>")
	)
	(segment
		(start 415.188908 -303.10836)
		(end 414.802828 -302.72228)
		(width 0.18288)
		(layer "In4.Cu")
		(net "M_F_CPU0_SA_DQS_DP<1>")
	)
	(segment
		(start 387.463792 -271.667224)
		(end 387.247384 -271.450816)
		(width 0.088646)
		(layer "In4.Cu")
		(net "M_F_CPU0_SA_DQS_DP<1>")
	)
	(segment
		(start 395.725904 -279.622758)
		(end 390.603232 -274.499832)
		(width 0.18288)
		(layer "In4.Cu")
		(net "M_F_CPU0_SA_DQS_DP<1>")
	)
	(segment
		(start 379.70714 -270.688054)
		(end 379.697234 -270.693642)
		(width 0.088646)
		(layer "In4.Cu")
		(net "M_F_CPU0_SA_DQS_DP<1>")
	)
	(segment
		(start 402.252942 -293.229792)
		(end 401.866862 -292.843712)
		(width 0.18288)
		(layer "In4.Cu")
		(net "M_F_CPU0_SA_DQS_DP<1>")
	)
	(segment
		(start 387.753352 -272.12671)
		(end 387.463792 -271.83715)
		(width 0.088646)
		(layer "In4.Cu")
		(net "M_F_CPU0_SA_DQS_DP<1>")
	)
	(segment
		(start 407.191972 -297.198034)
		(end 406.755092 -296.761154)
		(width 0.18288)
		(layer "In4.Cu")
		(net "M_F_CPU0_SA_DQS_DP<1>")
	)
	(segment
		(start 419.295326 -303.10836)
		(end 419.170866 -303.23282)
		(width 0.18288)
		(layer "In4.Cu")
		(net "M_F_CPU0_SA_DQS_DP<1>")
	)
	(segment
		(start 402.252942 -293.405814)
		(end 402.252942 -293.229792)
		(width 0.18288)
		(layer "In4.Cu")
		(net "M_F_CPU0_SA_DQS_DP<1>")
	)
	(segment
		(start 402.815298 -293.792148)
		(end 402.639276 -293.792148)
		(width 0.18288)
		(layer "In4.Cu")
		(net "M_F_CPU0_SA_DQS_DP<1>")
	)
	(segment
		(start 387.769862 -272.228056)
		(end 387.753352 -272.12671)
		(width 0.088646)
		(layer "In4.Cu")
		(net "M_F_CPU0_SA_DQS_DP<1>")
	)
	(segment
		(start 385.347464 -270.687038)
		(end 385.332732 -270.695674)
		(width 0.088646)
		(layer "In4.Cu")
		(net "M_F_CPU0_SA_DQS_DP<1>")
	)
	(segment
		(start 382.528064 -270.687038)
		(end 382.513332 -270.695674)
		(width 0.088646)
		(layer "In4.Cu")
		(net "M_F_CPU0_SA_DQS_DP<1>")
	)
	(segment
		(start 379.640846 -270.721074)
		(end 379.620018 -270.728694)
		(width 0.088646)
		(layer "In4.Cu")
		(net "M_F_CPU0_SA_DQS_DP<1>")
	)
	(segment
		(start 407.578306 -297.76039)
		(end 407.191972 -297.374056)
		(width 0.18288)
		(layer "In4.Cu")
		(net "M_F_CPU0_SA_DQS_DP<1>")
	)
	(segment
		(start 389.929624 -274.387818)
		(end 387.769862 -272.228056)
		(width 0.18288)
		(layer "In4.Cu")
		(net "M_F_CPU0_SA_DQS_DP<1>")
	)
	(segment
		(start 404.149814 -295.126664)
		(end 403.763734 -294.740584)
		(width 0.18288)
		(layer "In4.Cu")
		(net "M_F_CPU0_SA_DQS_DP<1>")
	)
	(segment
		(start 413.717232 -301.636684)
		(end 413.263334 -301.333408)
		(width 0.18288)
		(layer "In4.Cu")
		(net "M_F_CPU0_SA_DQS_DP<1>")
	)
	(segment
		(start 418.500306 -303.10836)
		(end 416.816286 -303.10836)
		(width 0.18288)
		(layer "In4.Cu")
		(net "M_F_CPU0_SA_DQS_DP<1>")
	)
	(segment
		(start 403.201378 -294.178228)
		(end 402.815298 -293.792148)
		(width 0.18288)
		(layer "In4.Cu")
		(net "M_F_CPU0_SA_DQS_DP<1>")
	)
	(segment
		(start 401.69084 -292.843712)
		(end 401.304506 -292.457378)
		(width 0.18288)
		(layer "In4.Cu")
		(net "M_F_CPU0_SA_DQS_DP<1>")
	)
	(segment
		(start 411.814772 -300.365922)
		(end 411.642052 -300.400212)
		(width 0.18288)
		(layer "In4.Cu")
		(net "M_F_CPU0_SA_DQS_DP<1>")
	)
	(segment
		(start 414.626806 -302.72228)
		(end 414.240472 -302.335946)
		(width 0.18288)
		(layer "In4.Cu")
		(net "M_F_CPU0_SA_DQS_DP<1>")
	)
	(segment
		(start 379.029214 -270.607536)
		(end 378.700284 -270.195548)
		(width 0.088646)
		(layer "In4.Cu")
		(net "M_F_CPU0_SA_DQS_DP<1>")
	)
	(segment
		(start 383.467864 -270.687038)
		(end 383.453132 -270.695674)
		(width 0.088646)
		(layer "In4.Cu")
		(net "M_F_CPU0_SA_DQS_DP<1>")
	)
	(segment
		(start 420.456614 -303.287176)
		(end 420.020242 -303.287176)
		(width 0.18288)
		(layer "In4.Cu")
		(net "M_F_CPU0_SA_DQS_DP<1>")
	)
	(segment
		(start 416.691826 -303.23282)
		(end 416.145726 -303.23282)
		(width 0.18288)
		(layer "In4.Cu")
		(net "M_F_CPU0_SA_DQS_DP<1>")
	)
	(segment
		(start 379.697234 -270.693642)
		(end 379.673358 -270.706596)
		(width 0.088646)
		(layer "In4.Cu")
		(net "M_F_CPU0_SA_DQS_DP<1>")
	)
	(segment
		(start 406.755092 -296.761154)
		(end 405.09825 -296.0751)
		(width 0.18288)
		(layer "In4.Cu")
		(net "M_F_CPU0_SA_DQS_DP<1>")
	)
	(segment
		(start 387.247384 -271.450816)
		(end 386.9436 -271.450816)
		(width 0.088646)
		(layer "In4.Cu")
		(net "M_F_CPU0_SA_DQS_DP<1>")
	)
	(segment
		(start 390.491218 -274.387818)
		(end 389.929624 -274.387818)
		(width 0.18288)
		(layer "In4.Cu")
		(net "M_F_CPU0_SA_DQS_DP<1>")
	)
	(segment
		(start 381.028956 -270.69034)
		(end 381.017272 -270.683736)
		(width 0.088646)
		(layer "In4.Cu")
		(net "M_F_CPU0_SA_DQS_DP<1>")
	)
	(segment
		(start 407.754328 -297.76039)
		(end 407.578306 -297.76039)
		(width 0.18288)
		(layer "In4.Cu")
		(net "M_F_CPU0_SA_DQS_DP<1>")
	)
	(segment
		(start 412.601918 -300.891702)
		(end 411.814772 -300.365922)
		(width 0.18288)
		(layer "In4.Cu")
		(net "M_F_CPU0_SA_DQS_DP<1>")
	)
	(segment
		(start 380.085092 -270.688308)
		(end 380.08306 -270.687038)
		(width 0.088646)
		(layer "In4.Cu")
		(net "M_F_CPU0_SA_DQS_DP<1>")
	)
	(segment
		(start 379.641862 -270.72082)
		(end 379.640846 -270.721074)
		(width 0.088646)
		(layer "In4.Cu")
		(net "M_F_CPU0_SA_DQS_DP<1>")
	)
	(segment
		(start 409.57627 -299.741082)
		(end 409.316174 -299.480986)
		(width 0.18288)
		(layer "In4.Cu")
		(net "M_F_CPU0_SA_DQS_DP<1>")
	)
	(segment
		(start 409.316174 -299.480986)
		(end 408.825954 -299.480986)
		(width 0.18288)
		(layer "In4.Cu")
		(net "M_F_CPU0_SA_DQS_DP<1>")
	)
	(segment
		(start 385.73075 -270.692118)
		(end 385.72186 -270.687038)
		(width 0.088646)
		(layer "In4.Cu")
		(net "M_F_CPU0_SA_DQS_DP<1>")
	)
	(segment
		(start 407.191972 -297.374056)
		(end 407.191972 -297.198034)
		(width 0.18288)
		(layer "In4.Cu")
		(net "M_F_CPU0_SA_DQS_DP<1>")
	)
	(segment
		(start 404.536148 -295.68902)
		(end 404.149814 -295.302686)
		(width 0.18288)
		(layer "In4.Cu")
		(net "M_F_CPU0_SA_DQS_DP<1>")
	)
	(segment
		(start 411.187646 -300.096682)
		(end 411.153356 -299.923962)
		(width 0.18288)
		(layer "In4.Cu")
		(net "M_F_CPU0_SA_DQS_DP<1>")
	)
	(segment
		(start 386.206746 -271.50949)
		(end 386.192014 -271.500854)
		(width 0.088646)
		(layer "In4.Cu")
		(net "M_F_CPU0_SA_DQS_DP<1>")
	)
	(segment
		(start 403.763734 -294.740584)
		(end 403.587712 -294.740584)
		(width 0.18288)
		(layer "In4.Cu")
		(net "M_F_CPU0_SA_DQS_DP<1>")
	)
	(segment
		(start 387.463792 -271.83715)
		(end 387.463792 -271.667224)
		(width 0.088646)
		(layer "In4.Cu")
		(net "M_F_CPU0_SA_DQS_DP<1>")
	)
	(segment
		(start 378.697744 -270.19758)
		(end 378.486416 -270.19758)
		(width 0.088646)
		(layer "In4.Cu")
		(net "M_F_CPU0_SA_DQS_DP<1>")
	)
	(segment
		(start 400.73326 -291.710364)
		(end 395.725904 -279.622758)
		(width 0.18288)
		(layer "In4.Cu")
		(net "M_F_CPU0_SA_DQS_DP<1>")
	)
	(segment
		(start 413.090614 -301.367698)
		(end 412.636208 -301.064168)
		(width 0.18288)
		(layer "In4.Cu")
		(net "M_F_CPU0_SA_DQS_DP<1>")
	)
	(segment
		(start 401.304506 -292.281356)
		(end 400.73326 -291.710364)
		(width 0.18288)
		(layer "In4.Cu")
		(net "M_F_CPU0_SA_DQS_DP<1>")
	)
	(segment
		(start 401.866862 -292.843712)
		(end 401.69084 -292.843712)
		(width 0.18288)
		(layer "In4.Cu")
		(net "M_F_CPU0_SA_DQS_DP<1>")
	)
	(segment
		(start 386.192014 -271.500854)
		(end 386.189728 -271.499584)
		(width 0.088646)
		(layer "In4.Cu")
		(net "M_F_CPU0_SA_DQS_DP<1>")
	)
	(segment
		(start 412.636208 -301.064168)
		(end 412.601918 -300.891702)
		(width 0.18288)
		(layer "In4.Cu")
		(net "M_F_CPU0_SA_DQS_DP<1>")
	)
	(segment
		(start 384.407664 -270.687038)
		(end 384.392932 -270.695674)
		(width 0.088646)
		(layer "In4.Cu")
		(net "M_F_CPU0_SA_DQS_DP<1>")
	)
	(segment
		(start 390.603232 -274.499832)
		(end 390.491218 -274.387818)
		(width 0.18288)
		(layer "In4.Cu")
		(net "M_F_CPU0_SA_DQS_DP<1>")
	)
	(segment
		(start 411.642052 -300.400212)
		(end 411.187646 -300.096682)
		(width 0.18288)
		(layer "In4.Cu")
		(net "M_F_CPU0_SA_DQS_DP<1>")
	)
	(segment
		(start 414.240472 -302.335946)
		(end 414.240472 -302.159924)
		(width 0.18288)
		(layer "In4.Cu")
		(net "M_F_CPU0_SA_DQS_DP<1>")
	)
	(segment
		(start 408.460194 -299.115226)
		(end 408.460194 -298.466256)
		(width 0.18288)
		(layer "In4.Cu")
		(net "M_F_CPU0_SA_DQS_DP<1>")
	)
	(segment
		(start 401.304506 -292.457378)
		(end 401.304506 -292.281356)
		(width 0.18288)
		(layer "In4.Cu")
		(net "M_F_CPU0_SA_DQS_DP<1>")
	)
	(segment
		(start 403.201378 -294.35425)
		(end 403.201378 -294.178228)
		(width 0.18288)
		(layer "In4.Cu")
		(net "M_F_CPU0_SA_DQS_DP<1>")
	)
	(segment
		(start 408.825954 -299.480986)
		(end 408.460194 -299.115226)
		(width 0.18288)
		(layer "In4.Cu")
		(net "M_F_CPU0_SA_DQS_DP<1>")
	)
	(segment
		(start 416.145726 -303.23282)
		(end 416.021266 -303.10836)
		(width 0.18288)
		(layer "In4.Cu")
		(net "M_F_CPU0_SA_DQS_DP<1>")
	)
	(segment
		(start 420.736014 -303.566576)
		(end 420.456614 -303.287176)
		(width 0.18288)
		(layer "In4.Cu")
		(net "M_F_CPU0_SA_DQS_DP<1>")
	)
	(segment
		(start 379.14326 -270.687038)
		(end 379.093984 -270.65859)
		(width 0.088646)
		(layer "In4.Cu")
		(net "M_F_CPU0_SA_DQS_DP<1>")
	)
	(segment
		(start 379.708664 -270.687038)
		(end 379.70714 -270.688054)
		(width 0.088646)
		(layer "In4.Cu")
		(net "M_F_CPU0_SA_DQS_DP<1>")
	)
	(segment
		(start 408.460194 -298.466256)
		(end 407.754328 -297.76039)
		(width 0.18288)
		(layer "In4.Cu")
		(net "M_F_CPU0_SA_DQS_DP<1>")
	)
	(arc
		(start 385.72186 -270.687038)
		(mid 385.534662 -270.636895)
		(end 385.347464 -270.687038)
		(width 0.088646)
		(layer "In4.Cu")
		(net "M_F_CPU0_SA_DQS_DP<1>")
	)
	(arc
		(start 382.513332 -270.695674)
		(mid 382.236857 -270.762994)
		(end 381.96266 -270.687038)
		(width 0.088646)
		(layer "In4.Cu")
		(net "M_F_CPU0_SA_DQS_DP<1>")
	)
	(arc
		(start 379.673358 -270.706596)
		(mid 379.657864 -270.714269)
		(end 379.641862 -270.72082)
		(width 0.088646)
		(layer "In4.Cu")
		(net "M_F_CPU0_SA_DQS_DP<1>")
	)
	(arc
		(start 386.757418 -271.500854)
		(mid 386.483219 -271.576689)
		(end 386.206746 -271.50949)
		(width 0.088646)
		(layer "In4.Cu")
		(net "M_F_CPU0_SA_DQS_DP<1>")
	)
	(arc
		(start 385.909312 -271.011396)
		(mid 385.861633 -270.828496)
		(end 385.73075 -270.692118)
		(width 0.088646)
		(layer "In4.Cu")
		(net "M_F_CPU0_SA_DQS_DP<1>")
	)
	(arc
		(start 381.017272 -270.683736)
		(mid 380.832417 -270.636786)
		(end 380.648464 -270.687038)
		(width 0.088646)
		(layer "In4.Cu")
		(net "M_F_CPU0_SA_DQS_DP<1>")
	)
	(arc
		(start 382.90246 -270.687038)
		(mid 382.715262 -270.636895)
		(end 382.528064 -270.687038)
		(width 0.088646)
		(layer "In4.Cu")
		(net "M_F_CPU0_SA_DQS_DP<1>")
	)
	(arc
		(start 381.96266 -270.687038)
		(mid 381.775462 -270.636895)
		(end 381.588264 -270.687038)
		(width 0.088646)
		(layer "In4.Cu")
		(net "M_F_CPU0_SA_DQS_DP<1>")
	)
	(arc
		(start 380.648464 -270.687038)
		(mid 380.373182 -270.762642)
		(end 380.096014 -270.69415)
		(width 0.088646)
		(layer "In4.Cu")
		(net "M_F_CPU0_SA_DQS_DP<1>")
	)
	(arc
		(start 383.84226 -270.687038)
		(mid 383.655062 -270.636895)
		(end 383.467864 -270.687038)
		(width 0.088646)
		(layer "In4.Cu")
		(net "M_F_CPU0_SA_DQS_DP<1>")
	)
	(arc
		(start 386.185918 -271.497298)
		(mid 385.983331 -271.290947)
		(end 385.909312 -271.011396)
		(width 0.088646)
		(layer "In4.Cu")
		(net "M_F_CPU0_SA_DQS_DP<1>")
	)
	(arc
		(start 383.453132 -270.695674)
		(mid 383.176657 -270.762994)
		(end 382.90246 -270.687038)
		(width 0.088646)
		(layer "In4.Cu")
		(net "M_F_CPU0_SA_DQS_DP<1>")
	)
	(arc
		(start 384.78206 -270.687038)
		(mid 384.594862 -270.636895)
		(end 384.407664 -270.687038)
		(width 0.088646)
		(layer "In4.Cu")
		(net "M_F_CPU0_SA_DQS_DP<1>")
	)
	(arc
		(start 386.9436 -271.450816)
		(mid 386.847229 -271.463635)
		(end 386.757418 -271.500854)
		(width 0.088646)
		(layer "In4.Cu")
		(net "M_F_CPU0_SA_DQS_DP<1>")
	)
	(arc
		(start 384.392932 -270.695674)
		(mid 384.116457 -270.762994)
		(end 383.84226 -270.687038)
		(width 0.088646)
		(layer "In4.Cu")
		(net "M_F_CPU0_SA_DQS_DP<1>")
	)
	(arc
		(start 385.332732 -270.695674)
		(mid 385.056257 -270.762994)
		(end 384.78206 -270.687038)
		(width 0.088646)
		(layer "In4.Cu")
		(net "M_F_CPU0_SA_DQS_DP<1>")
	)
	(arc
		(start 379.620018 -270.728694)
		(mid 379.377013 -270.760803)
		(end 379.14326 -270.687038)
		(width 0.088646)
		(layer "In4.Cu")
		(net "M_F_CPU0_SA_DQS_DP<1>")
	)
	(arc
		(start 381.588264 -270.687038)
		(mid 381.309061 -270.762678)
		(end 381.028956 -270.69034)
		(width 0.088646)
		(layer "In4.Cu")
		(net "M_F_CPU0_SA_DQS_DP<1>")
	)
	(arc
		(start 380.08306 -270.687038)
		(mid 379.895862 -270.636895)
		(end 379.708664 -270.687038)
		(width 0.088646)
		(layer "In4.Cu")
		(net "M_F_CPU0_SA_DQS_DP<1>")
	)
	(segment
		(start 420.736014 -312.91657)
		(end 421.840914 -312.91657)
		(width 0.20066)
		(layer "F.Cu")
		(net "M_F_CPU0_SA_DQS_DP<0>")
	)
	(segment
		(start 421.840914 -312.91657)
		(end 422.430194 -312.91657)
		(width 0.20066)
		(layer "F.Cu")
		(net "M_F_CPU0_SA_DQS_DP<0>")
	)
	(segment
		(start 424.622722 -313.341766)
		(end 424.762168 -313.341766)
		(width 0.20066)
		(layer "F.Cu")
		(net "M_F_CPU0_SA_DQS_DP<0>")
	)
	(segment
		(start 422.430194 -312.91657)
		(end 422.670732 -312.676032)
		(width 0.20066)
		(layer "F.Cu")
		(net "M_F_CPU0_SA_DQS_DP<0>")
	)
	(segment
		(start 380.835916 -276.986492)
		(end 380.835916 -277.522178)
		(width 0.20066)
		(layer "F.Cu")
		(net "M_F_CPU0_SA_DQS_DP<0>")
	)
	(segment
		(start 424.371516 -313.09056)
		(end 424.622722 -313.341766)
		(width 0.20066)
		(layer "F.Cu")
		(net "M_F_CPU0_SA_DQS_DP<0>")
	)
	(segment
		(start 424.788076 -313.341766)
		(end 426.945298 -313.341766)
		(width 0.1016)
		(layer "F.Cu")
		(net "M_F_CPU0_SA_DQS_DP<0>")
	)
	(segment
		(start 427.57725 -313.045348)
		(end 427.947836 -313.045348)
		(width 0.20066)
		(layer "F.Cu")
		(net "M_F_CPU0_SA_DQS_DP<0>")
	)
	(segment
		(start 428.836074 -312.91657)
		(end 429.384714 -312.91657)
		(width 0.20066)
		(layer "F.Cu")
		(net "M_F_CPU0_SA_DQS_DP<0>")
	)
	(segment
		(start 426.951394 -313.347862)
		(end 427.274736 -313.347862)
		(width 0.20066)
		(layer "F.Cu")
		(net "M_F_CPU0_SA_DQS_DP<0>")
	)
	(segment
		(start 380.835916 -277.522178)
		(end 380.835662 -277.522432)
		(width 0.20066)
		(layer "F.Cu")
		(net "M_F_CPU0_SA_DQS_DP<0>")
	)
	(segment
		(start 426.945298 -313.341766)
		(end 426.951394 -313.347862)
		(width 0.1016)
		(layer "F.Cu")
		(net "M_F_CPU0_SA_DQS_DP<0>")
	)
	(segment
		(start 423.271188 -312.676032)
		(end 423.685716 -313.09056)
		(width 0.20066)
		(layer "F.Cu")
		(net "M_F_CPU0_SA_DQS_DP<0>")
	)
	(segment
		(start 427.274736 -313.347862)
		(end 427.57725 -313.045348)
		(width 0.20066)
		(layer "F.Cu")
		(net "M_F_CPU0_SA_DQS_DP<0>")
	)
	(segment
		(start 424.762168 -313.341766)
		(end 424.788076 -313.341766)
		(width 0.101854)
		(layer "F.Cu")
		(net "M_F_CPU0_SA_DQS_DP<0>")
	)
	(segment
		(start 422.670732 -312.676032)
		(end 423.271188 -312.676032)
		(width 0.20066)
		(layer "F.Cu")
		(net "M_F_CPU0_SA_DQS_DP<0>")
	)
	(segment
		(start 428.3583 -312.634884)
		(end 428.554388 -312.634884)
		(width 0.20066)
		(layer "F.Cu")
		(net "M_F_CPU0_SA_DQS_DP<0>")
	)
	(segment
		(start 428.554388 -312.634884)
		(end 428.836074 -312.91657)
		(width 0.20066)
		(layer "F.Cu")
		(net "M_F_CPU0_SA_DQS_DP<0>")
	)
	(segment
		(start 427.947836 -313.045348)
		(end 428.3583 -312.634884)
		(width 0.20066)
		(layer "F.Cu")
		(net "M_F_CPU0_SA_DQS_DP<0>")
	)
	(segment
		(start 423.685716 -313.09056)
		(end 424.371516 -313.09056)
		(width 0.20066)
		(layer "F.Cu")
		(net "M_F_CPU0_SA_DQS_DP<0>")
	)
	(segment
		(start 381.213868 -277.58771)
		(end 381.14859 -277.522432)
		(width 0.088646)
		(layer "In2.Cu")
		(net "M_F_CPU0_SA_DQS_DP<0>")
	)
	(segment
		(start 387.456426 -278.912066)
		(end 386.983732 -278.912066)
		(width 0.088646)
		(layer "In2.Cu")
		(net "M_F_CPU0_SA_DQS_DP<0>")
	)
	(segment
		(start 411.963616 -313.35345)
		(end 411.674056 -313.06389)
		(width 0.18288)
		(layer "In2.Cu")
		(net "M_F_CPU0_SA_DQS_DP<0>")
	)
	(segment
		(start 394.288518 -294.724836)
		(end 391.828274 -292.264846)
		(width 0.18288)
		(layer "In2.Cu")
		(net "M_F_CPU0_SA_DQS_DP<0>")
	)
	(segment
		(start 417.343082 -312.556906)
		(end 417.327334 -312.556906)
		(width 0.16002)
		(layer "In2.Cu")
		(net "M_F_CPU0_SA_DQS_DP<0>")
	)
	(segment
		(start 404.318724 -312.80989)
		(end 395.625066 -304.116232)
		(width 0.18288)
		(layer "In2.Cu")
		(net "M_F_CPU0_SA_DQS_DP<0>")
	)
	(segment
		(start 385.721606 -278.825452)
		(end 385.709668 -278.81834)
		(width 0.088646)
		(layer "In2.Cu")
		(net "M_F_CPU0_SA_DQS_DP<0>")
	)
	(segment
		(start 405.963628 -313.69635)
		(end 405.80437 -313.537092)
		(width 0.18288)
		(layer "In2.Cu")
		(net "M_F_CPU0_SA_DQS_DP<0>")
	)
	(segment
		(start 388.544054 -280.085038)
		(end 388.038848 -279.579324)
		(width 0.18288)
		(layer "In2.Cu")
		(net "M_F_CPU0_SA_DQS_DP<0>")
	)
	(segment
		(start 409.645612 -312.434732)
		(end 409.629356 -312.434732)
		(width 0.16002)
		(layer "In2.Cu")
		(net "M_F_CPU0_SA_DQS_DP<0>")
	)
	(segment
		(start 391.828274 -292.264846)
		(end 390.838182 -289.873944)
		(width 0.18288)
		(layer "In2.Cu")
		(net "M_F_CPU0_SA_DQS_DP<0>")
	)
	(segment
		(start 409.491434 -312.29681)
		(end 409.017216 -312.29681)
		(width 0.18288)
		(layer "In2.Cu")
		(net "M_F_CPU0_SA_DQS_DP<0>")
	)
	(segment
		(start 409.017216 -312.29681)
		(end 407.617676 -313.69635)
		(width 0.18288)
		(layer "In2.Cu")
		(net "M_F_CPU0_SA_DQS_DP<0>")
	)
	(segment
		(start 413.311086 -313.492642)
		(end 413.126936 -313.308492)
		(width 0.16002)
		(layer "In2.Cu")
		(net "M_F_CPU0_SA_DQS_DP<0>")
	)
	(segment
		(start 420.451026 -312.631582)
		(end 420.16807 -312.631582)
		(width 0.18288)
		(layer "In2.Cu")
		(net "M_F_CPU0_SA_DQS_DP<0>")
	)
	(segment
		(start 383.843022 -278.82596)
		(end 383.8321 -278.81961)
		(width 0.088646)
		(layer "In2.Cu")
		(net "M_F_CPU0_SA_DQS_DP<0>")
	)
	(segment
		(start 417.644326 -312.873898)
		(end 417.514278 -312.74385)
		(width 0.18288)
		(layer "In2.Cu")
		(net "M_F_CPU0_SA_DQS_DP<0>")
	)
	(segment
		(start 410.258514 -313.06389)
		(end 409.857956 -312.663332)
		(width 0.18288)
		(layer "In2.Cu")
		(net "M_F_CPU0_SA_DQS_DP<0>")
	)
	(segment
		(start 417.327334 -312.556906)
		(end 417.29914 -312.528712)
		(width 0.16002)
		(layer "In2.Cu")
		(net "M_F_CPU0_SA_DQS_DP<0>")
	)
	(segment
		(start 381.14859 -277.522432)
		(end 380.835662 -277.522432)
		(width 0.088646)
		(layer "In2.Cu")
		(net "M_F_CPU0_SA_DQS_DP<0>")
	)
	(segment
		(start 416.14471 -313.102244)
		(end 415.699194 -313.102244)
		(width 0.18288)
		(layer "In2.Cu")
		(net "M_F_CPU0_SA_DQS_DP<0>")
	)
	(segment
		(start 420.010336 -312.473848)
		(end 419.590474 -312.473848)
		(width 0.18288)
		(layer "In2.Cu")
		(net "M_F_CPU0_SA_DQS_DP<0>")
	)
	(segment
		(start 419.590474 -312.473848)
		(end 419.190424 -312.873898)
		(width 0.18288)
		(layer "In2.Cu")
		(net "M_F_CPU0_SA_DQS_DP<0>")
	)
	(segment
		(start 417.16325 -312.392822)
		(end 416.854132 -312.392822)
		(width 0.18288)
		(layer "In2.Cu")
		(net "M_F_CPU0_SA_DQS_DP<0>")
	)
	(segment
		(start 386.651246 -278.81961)
		(end 386.65023 -278.819102)
		(width 0.088646)
		(layer "In2.Cu")
		(net "M_F_CPU0_SA_DQS_DP<0>")
	)
	(segment
		(start 386.65023 -278.819102)
		(end 386.649976 -278.818848)
		(width 0.088646)
		(layer "In2.Cu")
		(net "M_F_CPU0_SA_DQS_DP<0>")
	)
	(segment
		(start 395.625066 -304.116232)
		(end 395.625066 -297.951906)
		(width 0.18288)
		(layer "In2.Cu")
		(net "M_F_CPU0_SA_DQS_DP<0>")
	)
	(segment
		(start 417.486084 -312.715656)
		(end 417.486084 -312.699908)
		(width 0.16002)
		(layer "In2.Cu")
		(net "M_F_CPU0_SA_DQS_DP<0>")
	)
	(segment
		(start 416.854132 -312.392822)
		(end 416.14471 -313.102244)
		(width 0.18288)
		(layer "In2.Cu")
		(net "M_F_CPU0_SA_DQS_DP<0>")
	)
	(segment
		(start 409.629356 -312.434732)
		(end 409.601162 -312.406538)
		(width 0.16002)
		(layer "In2.Cu")
		(net "M_F_CPU0_SA_DQS_DP<0>")
	)
	(segment
		(start 419.190424 -312.873898)
		(end 417.644326 -312.873898)
		(width 0.18288)
		(layer "In2.Cu")
		(net "M_F_CPU0_SA_DQS_DP<0>")
	)
	(segment
		(start 415.264346 -313.537092)
		(end 415.077148 -313.72429)
		(width 0.18288)
		(layer "In2.Cu")
		(net "M_F_CPU0_SA_DQS_DP<0>")
	)
	(segment
		(start 411.674056 -313.06389)
		(end 410.258514 -313.06389)
		(width 0.18288)
		(layer "In2.Cu")
		(net "M_F_CPU0_SA_DQS_DP<0>")
	)
	(segment
		(start 409.829762 -312.635138)
		(end 409.829762 -312.618882)
		(width 0.16002)
		(layer "In2.Cu")
		(net "M_F_CPU0_SA_DQS_DP<0>")
	)
	(segment
		(start 395.625066 -297.951906)
		(end 394.288518 -294.724836)
		(width 0.18288)
		(layer "In2.Cu")
		(net "M_F_CPU0_SA_DQS_DP<0>")
	)
	(segment
		(start 417.29914 -312.528712)
		(end 417.16325 -312.392822)
		(width 0.18288)
		(layer "In2.Cu")
		(net "M_F_CPU0_SA_DQS_DP<0>")
	)
	(segment
		(start 417.514278 -312.74385)
		(end 417.486084 -312.715656)
		(width 0.16002)
		(layer "In2.Cu")
		(net "M_F_CPU0_SA_DQS_DP<0>")
	)
	(segment
		(start 412.335726 -313.35345)
		(end 411.963616 -313.35345)
		(width 0.18288)
		(layer "In2.Cu")
		(net "M_F_CPU0_SA_DQS_DP<0>")
	)
	(segment
		(start 413.33928 -313.537092)
		(end 413.311086 -313.508898)
		(width 0.16002)
		(layer "In2.Cu")
		(net "M_F_CPU0_SA_DQS_DP<0>")
	)
	(segment
		(start 415.492946 -313.308492)
		(end 415.47669 -313.308492)
		(width 0.16002)
		(layer "In2.Cu")
		(net "M_F_CPU0_SA_DQS_DP<0>")
	)
	(segment
		(start 405.80437 -313.537092)
		(end 405.776176 -313.508898)
		(width 0.16002)
		(layer "In2.Cu")
		(net "M_F_CPU0_SA_DQS_DP<0>")
	)
	(segment
		(start 415.077148 -313.72429)
		(end 413.526478 -313.72429)
		(width 0.18288)
		(layer "In2.Cu")
		(net "M_F_CPU0_SA_DQS_DP<0>")
	)
	(segment
		(start 409.829762 -312.618882)
		(end 409.645612 -312.434732)
		(width 0.16002)
		(layer "In2.Cu")
		(net "M_F_CPU0_SA_DQS_DP<0>")
	)
	(segment
		(start 405.077168 -312.80989)
		(end 404.318724 -312.80989)
		(width 0.18288)
		(layer "In2.Cu")
		(net "M_F_CPU0_SA_DQS_DP<0>")
	)
	(segment
		(start 405.547576 -313.280298)
		(end 405.077168 -312.80989)
		(width 0.18288)
		(layer "In2.Cu")
		(net "M_F_CPU0_SA_DQS_DP<0>")
	)
	(segment
		(start 390.838182 -289.873944)
		(end 390.838182 -284.026102)
		(width 0.18288)
		(layer "In2.Cu")
		(net "M_F_CPU0_SA_DQS_DP<0>")
	)
	(segment
		(start 420.16807 -312.631582)
		(end 420.010336 -312.473848)
		(width 0.18288)
		(layer "In2.Cu")
		(net "M_F_CPU0_SA_DQS_DP<0>")
	)
	(segment
		(start 405.776176 -313.508898)
		(end 405.776176 -313.492642)
		(width 0.16002)
		(layer "In2.Cu")
		(net "M_F_CPU0_SA_DQS_DP<0>")
	)
	(segment
		(start 413.082486 -313.280298)
		(end 412.8516 -313.049412)
		(width 0.18288)
		(layer "In2.Cu")
		(net "M_F_CPU0_SA_DQS_DP<0>")
	)
	(segment
		(start 415.52114 -313.280298)
		(end 415.492946 -313.308492)
		(width 0.16002)
		(layer "In2.Cu")
		(net "M_F_CPU0_SA_DQS_DP<0>")
	)
	(segment
		(start 412.8516 -313.049412)
		(end 412.639764 -313.049412)
		(width 0.18288)
		(layer "In2.Cu")
		(net "M_F_CPU0_SA_DQS_DP<0>")
	)
	(segment
		(start 409.857956 -312.663332)
		(end 409.829762 -312.635138)
		(width 0.16002)
		(layer "In2.Cu")
		(net "M_F_CPU0_SA_DQS_DP<0>")
	)
	(segment
		(start 383.560066 -278.336502)
		(end 383.560066 -278.325072)
		(width 0.088646)
		(layer "In2.Cu")
		(net "M_F_CPU0_SA_DQS_DP<0>")
	)
	(segment
		(start 386.662168 -278.82596)
		(end 386.651246 -278.81961)
		(width 0.088646)
		(layer "In2.Cu")
		(net "M_F_CPU0_SA_DQS_DP<0>")
	)
	(segment
		(start 407.617676 -313.69635)
		(end 405.963628 -313.69635)
		(width 0.18288)
		(layer "In2.Cu")
		(net "M_F_CPU0_SA_DQS_DP<0>")
	)
	(segment
		(start 420.736014 -312.91657)
		(end 420.451026 -312.631582)
		(width 0.18288)
		(layer "In2.Cu")
		(net "M_F_CPU0_SA_DQS_DP<0>")
	)
	(segment
		(start 381.503428 -278.01824)
		(end 381.493014 -278.012144)
		(width 0.088646)
		(layer "In2.Cu")
		(net "M_F_CPU0_SA_DQS_DP<0>")
	)
	(segment
		(start 413.11068 -313.308492)
		(end 413.082486 -313.280298)
		(width 0.16002)
		(layer "In2.Cu")
		(net "M_F_CPU0_SA_DQS_DP<0>")
	)
	(segment
		(start 413.126936 -313.308492)
		(end 413.11068 -313.308492)
		(width 0.16002)
		(layer "In2.Cu")
		(net "M_F_CPU0_SA_DQS_DP<0>")
	)
	(segment
		(start 415.29254 -313.508898)
		(end 415.264346 -313.537092)
		(width 0.16002)
		(layer "In2.Cu")
		(net "M_F_CPU0_SA_DQS_DP<0>")
	)
	(segment
		(start 389.709406 -282.89758)
		(end 388.544054 -280.085038)
		(width 0.18288)
		(layer "In2.Cu")
		(net "M_F_CPU0_SA_DQS_DP<0>")
	)
	(segment
		(start 405.57577 -313.308492)
		(end 405.547576 -313.280298)
		(width 0.16002)
		(layer "In2.Cu")
		(net "M_F_CPU0_SA_DQS_DP<0>")
	)
	(segment
		(start 413.311086 -313.508898)
		(end 413.311086 -313.492642)
		(width 0.16002)
		(layer "In2.Cu")
		(net "M_F_CPU0_SA_DQS_DP<0>")
	)
	(segment
		(start 390.838182 -284.026102)
		(end 389.709406 -282.89758)
		(width 0.18288)
		(layer "In2.Cu")
		(net "M_F_CPU0_SA_DQS_DP<0>")
	)
	(segment
		(start 384.781806 -278.825452)
		(end 384.769868 -278.81834)
		(width 0.088646)
		(layer "In2.Cu")
		(net "M_F_CPU0_SA_DQS_DP<0>")
	)
	(segment
		(start 415.699194 -313.102244)
		(end 415.52114 -313.280298)
		(width 0.18288)
		(layer "In2.Cu")
		(net "M_F_CPU0_SA_DQS_DP<0>")
	)
	(segment
		(start 417.486084 -312.699908)
		(end 417.343082 -312.556906)
		(width 0.16002)
		(layer "In2.Cu")
		(net "M_F_CPU0_SA_DQS_DP<0>")
	)
	(segment
		(start 405.592026 -313.308492)
		(end 405.57577 -313.308492)
		(width 0.16002)
		(layer "In2.Cu")
		(net "M_F_CPU0_SA_DQS_DP<0>")
	)
	(segment
		(start 388.038848 -279.494488)
		(end 387.456426 -278.912066)
		(width 0.088646)
		(layer "In2.Cu")
		(net "M_F_CPU0_SA_DQS_DP<0>")
	)
	(segment
		(start 405.776176 -313.492642)
		(end 405.592026 -313.308492)
		(width 0.16002)
		(layer "In2.Cu")
		(net "M_F_CPU0_SA_DQS_DP<0>")
	)
	(segment
		(start 415.29254 -313.492642)
		(end 415.29254 -313.508898)
		(width 0.16002)
		(layer "In2.Cu")
		(net "M_F_CPU0_SA_DQS_DP<0>")
	)
	(segment
		(start 409.601162 -312.406538)
		(end 409.491434 -312.29681)
		(width 0.18288)
		(layer "In2.Cu")
		(net "M_F_CPU0_SA_DQS_DP<0>")
	)
	(segment
		(start 413.526478 -313.72429)
		(end 413.33928 -313.537092)
		(width 0.18288)
		(layer "In2.Cu")
		(net "M_F_CPU0_SA_DQS_DP<0>")
	)
	(segment
		(start 415.47669 -313.308492)
		(end 415.29254 -313.492642)
		(width 0.16002)
		(layer "In2.Cu")
		(net "M_F_CPU0_SA_DQS_DP<0>")
	)
	(segment
		(start 388.038848 -279.579324)
		(end 388.038848 -279.494488)
		(width 0.088646)
		(layer "In2.Cu")
		(net "M_F_CPU0_SA_DQS_DP<0>")
	)
	(segment
		(start 412.639764 -313.049412)
		(end 412.335726 -313.35345)
		(width 0.18288)
		(layer "In2.Cu")
		(net "M_F_CPU0_SA_DQS_DP<0>")
	)
	(segment
		(start 383.37236 -278.01189)
		(end 383.37236 -278.012144)
		(width 0.088646)
		(layer "In2.Cu")
		(net "M_F_CPU0_SA_DQS_DP<0>")
	)
	(arc
		(start 386.983732 -278.912066)
		(mid 386.817291 -278.890141)
		(end 386.662168 -278.82596)
		(width 0.088646)
		(layer "In2.Cu")
		(net "M_F_CPU0_SA_DQS_DP<0>")
	)
	(arc
		(start 385.34721 -278.825706)
		(mid 385.064479 -278.901389)
		(end 384.781806 -278.825452)
		(width 0.088646)
		(layer "In2.Cu")
		(net "M_F_CPU0_SA_DQS_DP<0>")
	)
	(arc
		(start 382.997964 -278.012144)
		(mid 382.715262 -278.087886)
		(end 382.43256 -278.012144)
		(width 0.088646)
		(layer "In2.Cu")
		(net "M_F_CPU0_SA_DQS_DP<0>")
	)
	(arc
		(start 382.058164 -278.012144)
		(mid 381.781605 -278.087853)
		(end 381.503428 -278.01824)
		(width 0.088646)
		(layer "In2.Cu")
		(net "M_F_CPU0_SA_DQS_DP<0>")
	)
	(arc
		(start 384.40741 -278.825706)
		(mid 384.125245 -278.901389)
		(end 383.843022 -278.82596)
		(width 0.088646)
		(layer "In2.Cu")
		(net "M_F_CPU0_SA_DQS_DP<0>")
	)
	(arc
		(start 386.28701 -278.825706)
		(mid 386.004279 -278.901389)
		(end 385.721606 -278.825452)
		(width 0.088646)
		(layer "In2.Cu")
		(net "M_F_CPU0_SA_DQS_DP<0>")
	)
	(arc
		(start 385.709668 -278.81834)
		(mid 385.527498 -278.775351)
		(end 385.34721 -278.825706)
		(width 0.088646)
		(layer "In2.Cu")
		(net "M_F_CPU0_SA_DQS_DP<0>")
	)
	(arc
		(start 381.216662 -277.608792)
		(mid 381.215166 -277.598264)
		(end 381.213868 -277.58771)
		(width 0.088646)
		(layer "In2.Cu")
		(net "M_F_CPU0_SA_DQS_DP<0>")
	)
	(arc
		(start 383.37236 -278.012144)
		(mid 383.185162 -277.962001)
		(end 382.997964 -278.012144)
		(width 0.088646)
		(layer "In2.Cu")
		(net "M_F_CPU0_SA_DQS_DP<0>")
	)
	(arc
		(start 384.769868 -278.81834)
		(mid 384.587698 -278.775351)
		(end 384.40741 -278.825706)
		(width 0.088646)
		(layer "In2.Cu")
		(net "M_F_CPU0_SA_DQS_DP<0>")
	)
	(arc
		(start 381.493014 -278.012144)
		(mid 381.309032 -277.841866)
		(end 381.216662 -277.608792)
		(width 0.088646)
		(layer "In2.Cu")
		(net "M_F_CPU0_SA_DQS_DP<0>")
	)
	(arc
		(start 383.560066 -278.325072)
		(mid 383.506932 -278.144073)
		(end 383.37236 -278.01189)
		(width 0.088646)
		(layer "In2.Cu")
		(net "M_F_CPU0_SA_DQS_DP<0>")
	)
	(arc
		(start 382.43256 -278.012144)
		(mid 382.245362 -277.962001)
		(end 382.058164 -278.012144)
		(width 0.088646)
		(layer "In2.Cu")
		(net "M_F_CPU0_SA_DQS_DP<0>")
	)
	(arc
		(start 386.649976 -278.818848)
		(mid 386.467611 -278.775434)
		(end 386.28701 -278.825706)
		(width 0.088646)
		(layer "In2.Cu")
		(net "M_F_CPU0_SA_DQS_DP<0>")
	)
	(arc
		(start 383.8321 -278.81961)
		(mid 383.632716 -278.61373)
		(end 383.560066 -278.336502)
		(width 0.088646)
		(layer "In2.Cu")
		(net "M_F_CPU0_SA_DQS_DP<0>")
	)
	(segment
		(start 383.655062 -262.336534)
		(end 383.655062 -262.872474)
		(width 0.20066)
		(layer "F.Cu")
		(net "M_F_CPU0_SA_DQS_DN<9>")
	)
	(segment
		(start 428.05096 -274.247864)
		(end 428.363126 -274.247864)
		(width 0.20066)
		(layer "F.Cu")
		(net "M_F_CPU0_SA_DQS_DN<9>")
	)
	(segment
		(start 426.74286 -274.395438)
		(end 427.226222 -274.395438)
		(width 0.20066)
		(layer "F.Cu")
		(net "M_F_CPU0_SA_DQS_DN<9>")
	)
	(segment
		(start 430.395126 -274.25269)
		(end 430.713896 -274.25269)
		(width 0.20066)
		(layer "F.Cu")
		(net "M_F_CPU0_SA_DQS_DN<9>")
	)
	(segment
		(start 425.940982 -274.66671)
		(end 426.471588 -274.66671)
		(width 0.20066)
		(layer "F.Cu")
		(net "M_F_CPU0_SA_DQS_DN<9>")
	)
	(segment
		(start 432.726846 -274.412456)
		(end 432.9811 -274.66671)
		(width 0.20066)
		(layer "F.Cu")
		(net "M_F_CPU0_SA_DQS_DN<9>")
	)
	(segment
		(start 430.384204 -274.241768)
		(end 430.395126 -274.25269)
		(width 0.1016)
		(layer "F.Cu")
		(net "M_F_CPU0_SA_DQS_DN<9>")
	)
	(segment
		(start 432.9811 -274.66671)
		(end 433.484782 -274.66671)
		(width 0.20066)
		(layer "F.Cu")
		(net "M_F_CPU0_SA_DQS_DN<9>")
	)
	(segment
		(start 430.999646 -273.96694)
		(end 431.489612 -273.96694)
		(width 0.20066)
		(layer "F.Cu")
		(net "M_F_CPU0_SA_DQS_DN<9>")
	)
	(segment
		(start 427.651164 -273.970496)
		(end 427.773592 -273.970496)
		(width 0.20066)
		(layer "F.Cu")
		(net "M_F_CPU0_SA_DQS_DN<9>")
	)
	(segment
		(start 424.836082 -274.66671)
		(end 425.940982 -274.66671)
		(width 0.20066)
		(layer "F.Cu")
		(net "M_F_CPU0_SA_DQS_DN<9>")
	)
	(segment
		(start 427.226222 -274.395438)
		(end 427.651164 -273.970496)
		(width 0.20066)
		(layer "F.Cu")
		(net "M_F_CPU0_SA_DQS_DN<9>")
	)
	(segment
		(start 426.471588 -274.66671)
		(end 426.74286 -274.395438)
		(width 0.20066)
		(layer "F.Cu")
		(net "M_F_CPU0_SA_DQS_DN<9>")
	)
	(segment
		(start 427.773592 -273.970496)
		(end 428.05096 -274.247864)
		(width 0.20066)
		(layer "F.Cu")
		(net "M_F_CPU0_SA_DQS_DN<9>")
	)
	(segment
		(start 428.374048 -274.241768)
		(end 430.384204 -274.241768)
		(width 0.1016)
		(layer "F.Cu")
		(net "M_F_CPU0_SA_DQS_DN<9>")
	)
	(segment
		(start 431.935128 -274.412456)
		(end 432.726846 -274.412456)
		(width 0.20066)
		(layer "F.Cu")
		(net "M_F_CPU0_SA_DQS_DN<9>")
	)
	(segment
		(start 428.363126 -274.247864)
		(end 428.367952 -274.247864)
		(width 0.101854)
		(layer "F.Cu")
		(net "M_F_CPU0_SA_DQS_DN<9>")
	)
	(segment
		(start 431.489612 -273.96694)
		(end 431.935128 -274.412456)
		(width 0.20066)
		(layer "F.Cu")
		(net "M_F_CPU0_SA_DQS_DN<9>")
	)
	(segment
		(start 430.713896 -274.25269)
		(end 430.999646 -273.96694)
		(width 0.20066)
		(layer "F.Cu")
		(net "M_F_CPU0_SA_DQS_DN<9>")
	)
	(segment
		(start 428.367952 -274.247864)
		(end 428.374048 -274.241768)
		(width 0.1016)
		(layer "F.Cu")
		(net "M_F_CPU0_SA_DQS_DN<9>")
	)
	(segment
		(start 388.780782 -262.623808)
		(end 387.884162 -262.623808)
		(width 0.088646)
		(layer "In2.Cu")
		(net "M_F_CPU0_SA_DQS_DN<9>")
	)
	(segment
		(start 407.626312 -272.722086)
		(end 407.598118 -272.693892)
		(width 0.16002)
		(layer "In2.Cu")
		(net "M_F_CPU0_SA_DQS_DN<9>")
	)
	(segment
		(start 411.49778 -273.34337)
		(end 411.469586 -273.315176)
		(width 0.16002)
		(layer "In2.Cu")
		(net "M_F_CPU0_SA_DQS_DN<9>")
	)
	(segment
		(start 401.372324 -268.033246)
		(end 401.196302 -268.033246)
		(width 0.18288)
		(layer "In2.Cu")
		(net "M_F_CPU0_SA_DQS_DN<9>")
	)
	(segment
		(start 405.587962 -272.5674)
		(end 405.253444 -272.5674)
		(width 0.18288)
		(layer "In2.Cu")
		(net "M_F_CPU0_SA_DQS_DN<9>")
	)
	(segment
		(start 395.686788 -265.343386)
		(end 395.562328 -265.218926)
		(width 0.18288)
		(layer "In2.Cu")
		(net "M_F_CPU0_SA_DQS_DN<9>")
	)
	(segment
		(start 408.278838 -272.86331)
		(end 407.767536 -272.86331)
		(width 0.18288)
		(layer "In2.Cu")
		(net "M_F_CPU0_SA_DQS_DN<9>")
	)
	(segment
		(start 413.52216 -273.982434)
		(end 413.237426 -274.267168)
		(width 0.18288)
		(layer "In2.Cu")
		(net "M_F_CPU0_SA_DQS_DN<9>")
	)
	(segment
		(start 401.196302 -268.033246)
		(end 400.80819 -267.645134)
		(width 0.18288)
		(layer "In2.Cu")
		(net "M_F_CPU0_SA_DQS_DN<9>")
	)
	(segment
		(start 412.805372 -274.267168)
		(end 412.501588 -273.963384)
		(width 0.18288)
		(layer "In2.Cu")
		(net "M_F_CPU0_SA_DQS_DN<9>")
	)
	(segment
		(start 420.210234 -273.93392)
		(end 419.63213 -273.93392)
		(width 0.18288)
		(layer "In2.Cu")
		(net "M_F_CPU0_SA_DQS_DN<9>")
	)
	(segment
		(start 405.900636 -272.254726)
		(end 405.587962 -272.5674)
		(width 0.18288)
		(layer "In2.Cu")
		(net "M_F_CPU0_SA_DQS_DN<9>")
	)
	(segment
		(start 423.876724 -274.347178)
		(end 423.752264 -274.471638)
		(width 0.18288)
		(layer "In2.Cu")
		(net "M_F_CPU0_SA_DQS_DN<9>")
	)
	(segment
		(start 407.767536 -272.86331)
		(end 407.626312 -272.722086)
		(width 0.18288)
		(layer "In2.Cu")
		(net "M_F_CPU0_SA_DQS_DN<9>")
	)
	(segment
		(start 412.117794 -273.963384)
		(end 411.72638 -273.57197)
		(width 0.18288)
		(layer "In2.Cu")
		(net "M_F_CPU0_SA_DQS_DN<9>")
	)
	(segment
		(start 411.698186 -273.528028)
		(end 411.513528 -273.34337)
		(width 0.16002)
		(layer "In2.Cu")
		(net "M_F_CPU0_SA_DQS_DN<9>")
	)
	(segment
		(start 402.324316 -268.985238)
		(end 402.148294 -268.985238)
		(width 0.18288)
		(layer "In2.Cu")
		(net "M_F_CPU0_SA_DQS_DN<9>")
	)
	(segment
		(start 419.112446 -273.414236)
		(end 419.029642 -273.331432)
		(width 0.18288)
		(layer "In2.Cu")
		(net "M_F_CPU0_SA_DQS_DN<9>")
	)
	(segment
		(start 411.513528 -273.34337)
		(end 411.49778 -273.34337)
		(width 0.16002)
		(layer "In2.Cu")
		(net "M_F_CPU0_SA_DQS_DN<9>")
	)
	(segment
		(start 396.235428 -265.343386)
		(end 395.686788 -265.343386)
		(width 0.18288)
		(layer "In2.Cu")
		(net "M_F_CPU0_SA_DQS_DN<9>")
	)
	(segment
		(start 415.421572 -274.267168)
		(end 415.136838 -273.982434)
		(width 0.18288)
		(layer "In2.Cu")
		(net "M_F_CPU0_SA_DQS_DN<9>")
	)
	(segment
		(start 384.407664 -262.548116)
		(end 384.256788 -262.635238)
		(width 0.088646)
		(layer "In2.Cu")
		(net "M_F_CPU0_SA_DQS_DN<9>")
	)
	(segment
		(start 407.598118 -272.693892)
		(end 407.598118 -272.678144)
		(width 0.16002)
		(layer "In2.Cu")
		(net "M_F_CPU0_SA_DQS_DN<9>")
	)
	(segment
		(start 419.36924 -273.67103)
		(end 419.341046 -273.642836)
		(width 0.16002)
		(layer "In2.Cu")
		(net "M_F_CPU0_SA_DQS_DN<9>")
	)
	(segment
		(start 407.158952 -272.254726)
		(end 405.900636 -272.254726)
		(width 0.18288)
		(layer "In2.Cu")
		(net "M_F_CPU0_SA_DQS_DN<9>")
	)
	(segment
		(start 419.341046 -273.627088)
		(end 419.156388 -273.44243)
		(width 0.16002)
		(layer "In2.Cu")
		(net "M_F_CPU0_SA_DQS_DN<9>")
	)
	(segment
		(start 419.14064 -273.44243)
		(end 419.112446 -273.414236)
		(width 0.16002)
		(layer "In2.Cu")
		(net "M_F_CPU0_SA_DQS_DN<9>")
	)
	(segment
		(start 384.130296 -262.74268)
		(end 383.784856 -262.74268)
		(width 0.088646)
		(layer "In2.Cu")
		(net "M_F_CPU0_SA_DQS_DN<9>")
	)
	(segment
		(start 395.013688 -265.218926)
		(end 392.883644 -263.088882)
		(width 0.18288)
		(layer "In2.Cu")
		(net "M_F_CPU0_SA_DQS_DN<9>")
	)
	(segment
		(start 403.100286 -269.93723)
		(end 402.712174 -269.549118)
		(width 0.18288)
		(layer "In2.Cu")
		(net "M_F_CPU0_SA_DQS_DN<9>")
	)
	(segment
		(start 407.41346 -272.493486)
		(end 407.397712 -272.493486)
		(width 0.16002)
		(layer "In2.Cu")
		(net "M_F_CPU0_SA_DQS_DN<9>")
	)
	(segment
		(start 424.51655 -274.347178)
		(end 423.876724 -274.347178)
		(width 0.18288)
		(layer "In2.Cu")
		(net "M_F_CPU0_SA_DQS_DN<9>")
	)
	(segment
		(start 417.773358 -273.331432)
		(end 417.659566 -273.445224)
		(width 0.18288)
		(layer "In2.Cu")
		(net "M_F_CPU0_SA_DQS_DN<9>")
	)
	(segment
		(start 409.68803 -273.417284)
		(end 409.353512 -273.417284)
		(width 0.18288)
		(layer "In2.Cu")
		(net "M_F_CPU0_SA_DQS_DN<9>")
	)
	(segment
		(start 419.156388 -273.44243)
		(end 419.14064 -273.44243)
		(width 0.16002)
		(layer "In2.Cu")
		(net "M_F_CPU0_SA_DQS_DN<9>")
	)
	(segment
		(start 421.67556 -273.917918)
		(end 421.256968 -273.917918)
		(width 0.18288)
		(layer "In2.Cu")
		(net "M_F_CPU0_SA_DQS_DN<9>")
	)
	(segment
		(start 404.357078 -271.995646)
		(end 403.66442 -270.325088)
		(width 0.18288)
		(layer "In2.Cu")
		(net "M_F_CPU0_SA_DQS_DN<9>")
	)
	(segment
		(start 417.430966 -273.673824)
		(end 417.402772 -273.702018)
		(width 0.16002)
		(layer "In2.Cu")
		(net "M_F_CPU0_SA_DQS_DN<9>")
	)
	(segment
		(start 415.136838 -273.982434)
		(end 413.52216 -273.982434)
		(width 0.18288)
		(layer "In2.Cu")
		(net "M_F_CPU0_SA_DQS_DN<9>")
	)
	(segment
		(start 404.576534 -272.216372)
		(end 404.357078 -271.995646)
		(width 0.18288)
		(layer "In2.Cu")
		(net "M_F_CPU0_SA_DQS_DN<9>")
	)
	(segment
		(start 417.631372 -273.473418)
		(end 417.615624 -273.473418)
		(width 0.16002)
		(layer "In2.Cu")
		(net "M_F_CPU0_SA_DQS_DN<9>")
	)
	(segment
		(start 407.598118 -272.678144)
		(end 407.41346 -272.493486)
		(width 0.16002)
		(layer "In2.Cu")
		(net "M_F_CPU0_SA_DQS_DN<9>")
	)
	(segment
		(start 420.51732 -274.241006)
		(end 420.210234 -273.93392)
		(width 0.18288)
		(layer "In2.Cu")
		(net "M_F_CPU0_SA_DQS_DN<9>")
	)
	(segment
		(start 398.558258 -265.218926)
		(end 396.359888 -265.218926)
		(width 0.18288)
		(layer "In2.Cu")
		(net "M_F_CPU0_SA_DQS_DN<9>")
	)
	(segment
		(start 411.469586 -273.315176)
		(end 411.292548 -273.138138)
		(width 0.18288)
		(layer "In2.Cu")
		(net "M_F_CPU0_SA_DQS_DN<9>")
	)
	(segment
		(start 409.353512 -273.417284)
		(end 409.040838 -273.10461)
		(width 0.18288)
		(layer "In2.Cu")
		(net "M_F_CPU0_SA_DQS_DN<9>")
	)
	(segment
		(start 401.760182 -268.597126)
		(end 401.760182 -268.421104)
		(width 0.18288)
		(layer "In2.Cu")
		(net "M_F_CPU0_SA_DQS_DN<9>")
	)
	(segment
		(start 383.784856 -262.74268)
		(end 383.655062 -262.872474)
		(width 0.088646)
		(layer "In2.Cu")
		(net "M_F_CPU0_SA_DQS_DN<9>")
	)
	(segment
		(start 417.615624 -273.473418)
		(end 417.430966 -273.658076)
		(width 0.16002)
		(layer "In2.Cu")
		(net "M_F_CPU0_SA_DQS_DN<9>")
	)
	(segment
		(start 402.148294 -268.985238)
		(end 401.760182 -268.597126)
		(width 0.18288)
		(layer "In2.Cu")
		(net "M_F_CPU0_SA_DQS_DN<9>")
	)
	(segment
		(start 413.237426 -274.267168)
		(end 412.805372 -274.267168)
		(width 0.18288)
		(layer "In2.Cu")
		(net "M_F_CPU0_SA_DQS_DN<9>")
	)
	(segment
		(start 423.079164 -274.347178)
		(end 422.711626 -274.347178)
		(width 0.18288)
		(layer "In2.Cu")
		(net "M_F_CPU0_SA_DQS_DN<9>")
	)
	(segment
		(start 417.430966 -273.658076)
		(end 417.430966 -273.673824)
		(width 0.16002)
		(layer "In2.Cu")
		(net "M_F_CPU0_SA_DQS_DN<9>")
	)
	(segment
		(start 417.402772 -273.702018)
		(end 417.155376 -273.949414)
		(width 0.18288)
		(layer "In2.Cu")
		(net "M_F_CPU0_SA_DQS_DN<9>")
	)
	(segment
		(start 404.902416 -272.216372)
		(end 404.576534 -272.216372)
		(width 0.18288)
		(layer "In2.Cu")
		(net "M_F_CPU0_SA_DQS_DN<9>")
	)
	(segment
		(start 407.369518 -272.465292)
		(end 407.158952 -272.254726)
		(width 0.18288)
		(layer "In2.Cu")
		(net "M_F_CPU0_SA_DQS_DN<9>")
	)
	(segment
		(start 419.63213 -273.93392)
		(end 419.36924 -273.67103)
		(width 0.18288)
		(layer "In2.Cu")
		(net "M_F_CPU0_SA_DQS_DN<9>")
	)
	(segment
		(start 403.66442 -270.325088)
		(end 403.664166 -270.325088)
		(width 0.18288)
		(layer "In2.Cu")
		(net "M_F_CPU0_SA_DQS_DN<9>")
	)
	(segment
		(start 400.24431 -267.081254)
		(end 399.856198 -266.693142)
		(width 0.18288)
		(layer "In2.Cu")
		(net "M_F_CPU0_SA_DQS_DN<9>")
	)
	(segment
		(start 401.760182 -268.421104)
		(end 401.372324 -268.033246)
		(width 0.18288)
		(layer "In2.Cu")
		(net "M_F_CPU0_SA_DQS_DN<9>")
	)
	(segment
		(start 412.501588 -273.963384)
		(end 412.117794 -273.963384)
		(width 0.18288)
		(layer "In2.Cu")
		(net "M_F_CPU0_SA_DQS_DN<9>")
	)
	(segment
		(start 384.256788 -262.635238)
		(end 384.130296 -262.74268)
		(width 0.088646)
		(layer "In2.Cu")
		(net "M_F_CPU0_SA_DQS_DN<9>")
	)
	(segment
		(start 396.359888 -265.218926)
		(end 396.235428 -265.343386)
		(width 0.18288)
		(layer "In2.Cu")
		(net "M_F_CPU0_SA_DQS_DN<9>")
	)
	(segment
		(start 407.397712 -272.493486)
		(end 407.369518 -272.465292)
		(width 0.16002)
		(layer "In2.Cu")
		(net "M_F_CPU0_SA_DQS_DN<9>")
	)
	(segment
		(start 388.840472 -262.683498)
		(end 388.780782 -262.623808)
		(width 0.088646)
		(layer "In2.Cu")
		(net "M_F_CPU0_SA_DQS_DN<9>")
	)
	(segment
		(start 411.292548 -273.138138)
		(end 409.967176 -273.138138)
		(width 0.18288)
		(layer "In2.Cu")
		(net "M_F_CPU0_SA_DQS_DN<9>")
	)
	(segment
		(start 403.276308 -269.93723)
		(end 403.100286 -269.93723)
		(width 0.18288)
		(layer "In2.Cu")
		(net "M_F_CPU0_SA_DQS_DN<9>")
	)
	(segment
		(start 391.904982 -262.683498)
		(end 388.840472 -262.683498)
		(width 0.18288)
		(layer "In2.Cu")
		(net "M_F_CPU0_SA_DQS_DN<9>")
	)
	(segment
		(start 400.80819 -267.645134)
		(end 400.80819 -267.469112)
		(width 0.18288)
		(layer "In2.Cu")
		(net "M_F_CPU0_SA_DQS_DN<9>")
	)
	(segment
		(start 400.420332 -267.081254)
		(end 400.24431 -267.081254)
		(width 0.18288)
		(layer "In2.Cu")
		(net "M_F_CPU0_SA_DQS_DN<9>")
	)
	(segment
		(start 409.967176 -273.138138)
		(end 409.68803 -273.417284)
		(width 0.18288)
		(layer "In2.Cu")
		(net "M_F_CPU0_SA_DQS_DN<9>")
	)
	(segment
		(start 399.856198 -266.51712)
		(end 398.558258 -265.218926)
		(width 0.18288)
		(layer "In2.Cu")
		(net "M_F_CPU0_SA_DQS_DN<9>")
	)
	(segment
		(start 386.676646 -262.556752)
		(end 386.661914 -262.548116)
		(width 0.088646)
		(layer "In2.Cu")
		(net "M_F_CPU0_SA_DQS_DN<9>")
	)
	(segment
		(start 419.029642 -273.331432)
		(end 417.773358 -273.331432)
		(width 0.18288)
		(layer "In2.Cu")
		(net "M_F_CPU0_SA_DQS_DN<9>")
	)
	(segment
		(start 411.72638 -273.57197)
		(end 411.698186 -273.543776)
		(width 0.16002)
		(layer "In2.Cu")
		(net "M_F_CPU0_SA_DQS_DN<9>")
	)
	(segment
		(start 395.562328 -265.218926)
		(end 395.013688 -265.218926)
		(width 0.18288)
		(layer "In2.Cu")
		(net "M_F_CPU0_SA_DQS_DN<9>")
	)
	(segment
		(start 420.93388 -274.241006)
		(end 420.51732 -274.241006)
		(width 0.18288)
		(layer "In2.Cu")
		(net "M_F_CPU0_SA_DQS_DN<9>")
	)
	(segment
		(start 385.732274 -262.554212)
		(end 385.72186 -262.548116)
		(width 0.088646)
		(layer "In2.Cu")
		(net "M_F_CPU0_SA_DQS_DN<9>")
	)
	(segment
		(start 399.856198 -266.693142)
		(end 399.856198 -266.51712)
		(width 0.18288)
		(layer "In2.Cu")
		(net "M_F_CPU0_SA_DQS_DN<9>")
	)
	(segment
		(start 419.341046 -273.642836)
		(end 419.341046 -273.627088)
		(width 0.16002)
		(layer "In2.Cu")
		(net "M_F_CPU0_SA_DQS_DN<9>")
	)
	(segment
		(start 416.17138 -273.949414)
		(end 415.853626 -274.267168)
		(width 0.18288)
		(layer "In2.Cu")
		(net "M_F_CPU0_SA_DQS_DN<9>")
	)
	(segment
		(start 417.659566 -273.445224)
		(end 417.631372 -273.473418)
		(width 0.16002)
		(layer "In2.Cu")
		(net "M_F_CPU0_SA_DQS_DN<9>")
	)
	(segment
		(start 400.80819 -267.469112)
		(end 400.420332 -267.081254)
		(width 0.18288)
		(layer "In2.Cu")
		(net "M_F_CPU0_SA_DQS_DN<9>")
	)
	(segment
		(start 417.155376 -273.949414)
		(end 416.17138 -273.949414)
		(width 0.18288)
		(layer "In2.Cu")
		(net "M_F_CPU0_SA_DQS_DN<9>")
	)
	(segment
		(start 423.752264 -274.471638)
		(end 423.203624 -274.471638)
		(width 0.18288)
		(layer "In2.Cu")
		(net "M_F_CPU0_SA_DQS_DN<9>")
	)
	(segment
		(start 423.203624 -274.471638)
		(end 423.079164 -274.347178)
		(width 0.18288)
		(layer "In2.Cu")
		(net "M_F_CPU0_SA_DQS_DN<9>")
	)
	(segment
		(start 402.712174 -269.373096)
		(end 402.324316 -268.985238)
		(width 0.18288)
		(layer "In2.Cu")
		(net "M_F_CPU0_SA_DQS_DN<9>")
	)
	(segment
		(start 411.698186 -273.543776)
		(end 411.698186 -273.528028)
		(width 0.16002)
		(layer "In2.Cu")
		(net "M_F_CPU0_SA_DQS_DN<9>")
	)
	(segment
		(start 415.853626 -274.267168)
		(end 415.421572 -274.267168)
		(width 0.18288)
		(layer "In2.Cu")
		(net "M_F_CPU0_SA_DQS_DN<9>")
	)
	(segment
		(start 422.711626 -274.347178)
		(end 421.67556 -273.917918)
		(width 0.18288)
		(layer "In2.Cu")
		(net "M_F_CPU0_SA_DQS_DN<9>")
	)
	(segment
		(start 409.040838 -273.10461)
		(end 408.520138 -273.10461)
		(width 0.18288)
		(layer "In2.Cu")
		(net "M_F_CPU0_SA_DQS_DN<9>")
	)
	(segment
		(start 408.520138 -273.10461)
		(end 408.278838 -272.86331)
		(width 0.18288)
		(layer "In2.Cu")
		(net "M_F_CPU0_SA_DQS_DN<9>")
	)
	(segment
		(start 405.253444 -272.5674)
		(end 404.902416 -272.216372)
		(width 0.18288)
		(layer "In2.Cu")
		(net "M_F_CPU0_SA_DQS_DN<9>")
	)
	(segment
		(start 402.712174 -269.549118)
		(end 402.712174 -269.373096)
		(width 0.18288)
		(layer "In2.Cu")
		(net "M_F_CPU0_SA_DQS_DN<9>")
	)
	(segment
		(start 424.836082 -274.66671)
		(end 424.51655 -274.347178)
		(width 0.18288)
		(layer "In2.Cu")
		(net "M_F_CPU0_SA_DQS_DN<9>")
	)
	(segment
		(start 392.883644 -263.088882)
		(end 391.904982 -262.683498)
		(width 0.18288)
		(layer "In2.Cu")
		(net "M_F_CPU0_SA_DQS_DN<9>")
	)
	(segment
		(start 421.256968 -273.917918)
		(end 420.93388 -274.241006)
		(width 0.18288)
		(layer "In2.Cu")
		(net "M_F_CPU0_SA_DQS_DN<9>")
	)
	(segment
		(start 403.664166 -270.325088)
		(end 403.276308 -269.93723)
		(width 0.18288)
		(layer "In2.Cu")
		(net "M_F_CPU0_SA_DQS_DN<9>")
	)
	(arc
		(start 385.72186 -262.548116)
		(mid 385.534662 -262.497973)
		(end 385.347464 -262.548116)
		(width 0.088646)
		(layer "In2.Cu")
		(net "M_F_CPU0_SA_DQS_DN<9>")
	)
	(arc
		(start 385.347464 -262.548116)
		(mid 385.064762 -262.623892)
		(end 384.78206 -262.548116)
		(width 0.088646)
		(layer "In2.Cu")
		(net "M_F_CPU0_SA_DQS_DN<9>")
	)
	(arc
		(start 386.661914 -262.548116)
		(mid 386.474716 -262.497973)
		(end 386.287518 -262.548116)
		(width 0.088646)
		(layer "In2.Cu")
		(net "M_F_CPU0_SA_DQS_DN<9>")
	)
	(arc
		(start 387.601714 -262.548116)
		(mid 387.414516 -262.497973)
		(end 387.227318 -262.548116)
		(width 0.088646)
		(layer "In2.Cu")
		(net "M_F_CPU0_SA_DQS_DN<9>")
	)
	(arc
		(start 387.884162 -262.623808)
		(mid 387.737954 -262.604559)
		(end 387.601714 -262.548116)
		(width 0.088646)
		(layer "In2.Cu")
		(net "M_F_CPU0_SA_DQS_DN<9>")
	)
	(arc
		(start 387.227318 -262.548116)
		(mid 386.953119 -262.623951)
		(end 386.676646 -262.556752)
		(width 0.088646)
		(layer "In2.Cu")
		(net "M_F_CPU0_SA_DQS_DN<9>")
	)
	(arc
		(start 384.78206 -262.548116)
		(mid 384.594862 -262.497973)
		(end 384.407664 -262.548116)
		(width 0.088646)
		(layer "In2.Cu")
		(net "M_F_CPU0_SA_DQS_DN<9>")
	)
	(arc
		(start 386.287518 -262.548116)
		(mid 386.010705 -262.623986)
		(end 385.732274 -262.554212)
		(width 0.088646)
		(layer "In2.Cu")
		(net "M_F_CPU0_SA_DQS_DN<9>")
	)
	(segment
		(start 428.374048 -283.591762)
		(end 430.384204 -283.591762)
		(width 0.1016)
		(layer "F.Cu")
		(net "M_F_CPU0_SA_DQS_DN<8>")
	)
	(segment
		(start 430.999646 -283.316934)
		(end 431.489612 -283.316934)
		(width 0.20066)
		(layer "F.Cu")
		(net "M_F_CPU0_SA_DQS_DN<8>")
	)
	(segment
		(start 427.651164 -283.32049)
		(end 427.773592 -283.32049)
		(width 0.20066)
		(layer "F.Cu")
		(net "M_F_CPU0_SA_DQS_DN<8>")
	)
	(segment
		(start 430.384204 -283.591762)
		(end 430.395126 -283.602684)
		(width 0.1016)
		(layer "F.Cu")
		(net "M_F_CPU0_SA_DQS_DN<8>")
	)
	(segment
		(start 426.471588 -284.016704)
		(end 426.74286 -283.745432)
		(width 0.20066)
		(layer "F.Cu")
		(net "M_F_CPU0_SA_DQS_DN<8>")
	)
	(segment
		(start 380.366016 -259.895086)
		(end 380.366016 -260.430772)
		(width 0.20066)
		(layer "F.Cu")
		(net "M_F_CPU0_SA_DQS_DN<8>")
	)
	(segment
		(start 425.940982 -284.016704)
		(end 426.471588 -284.016704)
		(width 0.20066)
		(layer "F.Cu")
		(net "M_F_CPU0_SA_DQS_DN<8>")
	)
	(segment
		(start 424.836082 -284.016704)
		(end 425.940982 -284.016704)
		(width 0.20066)
		(layer "F.Cu")
		(net "M_F_CPU0_SA_DQS_DN<8>")
	)
	(segment
		(start 431.935128 -283.76245)
		(end 432.726846 -283.76245)
		(width 0.20066)
		(layer "F.Cu")
		(net "M_F_CPU0_SA_DQS_DN<8>")
	)
	(segment
		(start 432.726846 -283.76245)
		(end 432.9811 -284.016704)
		(width 0.20066)
		(layer "F.Cu")
		(net "M_F_CPU0_SA_DQS_DN<8>")
	)
	(segment
		(start 426.74286 -283.745432)
		(end 427.226222 -283.745432)
		(width 0.20066)
		(layer "F.Cu")
		(net "M_F_CPU0_SA_DQS_DN<8>")
	)
	(segment
		(start 428.367952 -283.597858)
		(end 428.374048 -283.591762)
		(width 0.1016)
		(layer "F.Cu")
		(net "M_F_CPU0_SA_DQS_DN<8>")
	)
	(segment
		(start 380.365762 -259.894832)
		(end 380.366016 -259.895086)
		(width 0.20066)
		(layer "F.Cu")
		(net "M_F_CPU0_SA_DQS_DN<8>")
	)
	(segment
		(start 430.713896 -283.602684)
		(end 430.999646 -283.316934)
		(width 0.20066)
		(layer "F.Cu")
		(net "M_F_CPU0_SA_DQS_DN<8>")
	)
	(segment
		(start 427.226222 -283.745432)
		(end 427.651164 -283.32049)
		(width 0.20066)
		(layer "F.Cu")
		(net "M_F_CPU0_SA_DQS_DN<8>")
	)
	(segment
		(start 427.773592 -283.32049)
		(end 428.05096 -283.597858)
		(width 0.20066)
		(layer "F.Cu")
		(net "M_F_CPU0_SA_DQS_DN<8>")
	)
	(segment
		(start 430.395126 -283.602684)
		(end 430.713896 -283.602684)
		(width 0.20066)
		(layer "F.Cu")
		(net "M_F_CPU0_SA_DQS_DN<8>")
	)
	(segment
		(start 431.489612 -283.316934)
		(end 431.935128 -283.76245)
		(width 0.20066)
		(layer "F.Cu")
		(net "M_F_CPU0_SA_DQS_DN<8>")
	)
	(segment
		(start 428.05096 -283.597858)
		(end 428.363126 -283.597858)
		(width 0.20066)
		(layer "F.Cu")
		(net "M_F_CPU0_SA_DQS_DN<8>")
	)
	(segment
		(start 428.363126 -283.597858)
		(end 428.367952 -283.597858)
		(width 0.101854)
		(layer "F.Cu")
		(net "M_F_CPU0_SA_DQS_DN<8>")
	)
	(segment
		(start 432.9811 -284.016704)
		(end 433.484782 -284.016704)
		(width 0.20066)
		(layer "F.Cu")
		(net "M_F_CPU0_SA_DQS_DN<8>")
	)
	(segment
		(start 412.722822 -272.738596)
		(end 411.63875 -272.289016)
		(width 0.18288)
		(layer "In4.Cu")
		(net "M_F_CPU0_SA_DQS_DN<8>")
	)
	(segment
		(start 423.169842 -284.023816)
		(end 422.623742 -284.023816)
		(width 0.18288)
		(layer "In4.Cu")
		(net "M_F_CPU0_SA_DQS_DN<8>")
	)
	(segment
		(start 416.605466 -274.845272)
		(end 415.293048 -274.583906)
		(width 0.18288)
		(layer "In4.Cu")
		(net "M_F_CPU0_SA_DQS_DN<8>")
	)
	(segment
		(start 417.945062 -280.148284)
		(end 417.945062 -279.602184)
		(width 0.18288)
		(layer "In4.Cu")
		(net "M_F_CPU0_SA_DQS_DN<8>")
	)
	(segment
		(start 392.509756 -261.452868)
		(end 389.594852 -260.24205)
		(width 0.18288)
		(layer "In4.Cu")
		(net "M_F_CPU0_SA_DQS_DN<8>")
	)
	(segment
		(start 423.294302 -283.899356)
		(end 423.169842 -284.023816)
		(width 0.18288)
		(layer "In4.Cu")
		(net "M_F_CPU0_SA_DQS_DN<8>")
	)
	(segment
		(start 386.724906 -260.182106)
		(end 386.473954 -260.182106)
		(width 0.088646)
		(layer "In4.Cu")
		(net "M_F_CPU0_SA_DQS_DN<8>")
	)
	(segment
		(start 418.069522 -278.072596)
		(end 418.069522 -277.736046)
		(width 0.18288)
		(layer "In4.Cu")
		(net "M_F_CPU0_SA_DQS_DN<8>")
	)
	(segment
		(start 406.12568 -270.575786)
		(end 405.843994 -270.857472)
		(width 0.18288)
		(layer "In4.Cu")
		(net "M_F_CPU0_SA_DQS_DN<8>")
	)
	(segment
		(start 422.499282 -283.899356)
		(end 421.953182 -283.899356)
		(width 0.18288)
		(layer "In4.Cu")
		(net "M_F_CPU0_SA_DQS_DN<8>")
	)
	(segment
		(start 410.29763 -272.289016)
		(end 409.227274 -272.289016)
		(width 0.18288)
		(layer "In4.Cu")
		(net "M_F_CPU0_SA_DQS_DN<8>")
	)
	(segment
		(start 413.29483 -273.11096)
		(end 412.790132 -272.901664)
		(width 0.18288)
		(layer "In4.Cu")
		(net "M_F_CPU0_SA_DQS_DN<8>")
	)
	(segment
		(start 405.491696 -270.857472)
		(end 405.127206 -270.492982)
		(width 0.18288)
		(layer "In4.Cu")
		(net "M_F_CPU0_SA_DQS_DN<8>")
	)
	(segment
		(start 407.992072 -271.349216)
		(end 407.829512 -271.41678)
		(width 0.18288)
		(layer "In4.Cu")
		(net "M_F_CPU0_SA_DQS_DN<8>")
	)
	(segment
		(start 407.829512 -271.41678)
		(end 407.324814 -271.207738)
		(width 0.18288)
		(layer "In4.Cu")
		(net "M_F_CPU0_SA_DQS_DN<8>")
	)
	(segment
		(start 386.808218 -260.24205)
		(end 386.78485 -260.24205)
		(width 0.088646)
		(layer "In4.Cu")
		(net "M_F_CPU0_SA_DQS_DN<8>")
	)
	(segment
		(start 420.932102 -283.592524)
		(end 420.51732 -283.592524)
		(width 0.18288)
		(layer "In4.Cu")
		(net "M_F_CPU0_SA_DQS_DN<8>")
	)
	(segment
		(start 420.51732 -283.592524)
		(end 420.253922 -283.329126)
		(width 0.18288)
		(layer "In4.Cu")
		(net "M_F_CPU0_SA_DQS_DN<8>")
	)
	(segment
		(start 424.007534 -283.899356)
		(end 423.294302 -283.899356)
		(width 0.18288)
		(layer "In4.Cu")
		(net "M_F_CPU0_SA_DQS_DN<8>")
	)
	(segment
		(start 417.945062 -278.743156)
		(end 417.945062 -278.197056)
		(width 0.18288)
		(layer "In4.Cu")
		(net "M_F_CPU0_SA_DQS_DN<8>")
	)
	(segment
		(start 381.503174 -260.11251)
		(end 381.49276 -260.106414)
		(width 0.088646)
		(layer "In4.Cu")
		(net "M_F_CPU0_SA_DQS_DN<8>")
	)
	(segment
		(start 417.698682 -275.87448)
		(end 417.434014 -275.236686)
		(width 0.18288)
		(layer "In4.Cu")
		(net "M_F_CPU0_SA_DQS_DN<8>")
	)
	(segment
		(start 420.253922 -283.329126)
		(end 419.693598 -283.329126)
		(width 0.18288)
		(layer "In4.Cu")
		(net "M_F_CPU0_SA_DQS_DN<8>")
	)
	(segment
		(start 422.623742 -284.023816)
		(end 422.499282 -283.899356)
		(width 0.18288)
		(layer "In4.Cu")
		(net "M_F_CPU0_SA_DQS_DN<8>")
	)
	(segment
		(start 384.311906 -260.106414)
		(end 384.303524 -260.101588)
		(width 0.088646)
		(layer "In4.Cu")
		(net "M_F_CPU0_SA_DQS_DN<8>")
	)
	(segment
		(start 384.326638 -260.11505)
		(end 384.311906 -260.106414)
		(width 0.088646)
		(layer "In4.Cu")
		(net "M_F_CPU0_SA_DQS_DN<8>")
	)
	(segment
		(start 406.50922 -270.73479)
		(end 406.350216 -270.575786)
		(width 0.18288)
		(layer "In4.Cu")
		(net "M_F_CPU0_SA_DQS_DN<8>")
	)
	(segment
		(start 418.069522 -280.272744)
		(end 417.945062 -280.148284)
		(width 0.18288)
		(layer "In4.Cu")
		(net "M_F_CPU0_SA_DQS_DN<8>")
	)
	(segment
		(start 413.961834 -273.252692)
		(end 413.457644 -273.04365)
		(width 0.18288)
		(layer "In4.Cu")
		(net "M_F_CPU0_SA_DQS_DN<8>")
	)
	(segment
		(start 421.193214 -283.331412)
		(end 420.932102 -283.592524)
		(width 0.18288)
		(layer "In4.Cu")
		(net "M_F_CPU0_SA_DQS_DN<8>")
	)
	(segment
		(start 405.127206 -270.492982)
		(end 405.127206 -270.382746)
		(width 0.18288)
		(layer "In4.Cu")
		(net "M_F_CPU0_SA_DQS_DN<8>")
	)
	(segment
		(start 382.443228 -260.11251)
		(end 382.432814 -260.106414)
		(width 0.088646)
		(layer "In4.Cu")
		(net "M_F_CPU0_SA_DQS_DN<8>")
	)
	(segment
		(start 417.434014 -275.236686)
		(end 417.352226 -275.154898)
		(width 0.18288)
		(layer "In4.Cu")
		(net "M_F_CPU0_SA_DQS_DN<8>")
	)
	(segment
		(start 424.376088 -283.746702)
		(end 424.007534 -283.899356)
		(width 0.18288)
		(layer "In4.Cu")
		(net "M_F_CPU0_SA_DQS_DN<8>")
	)
	(segment
		(start 385.266438 -260.11505)
		(end 385.251706 -260.106414)
		(width 0.088646)
		(layer "In4.Cu")
		(net "M_F_CPU0_SA_DQS_DN<8>")
	)
	(segment
		(start 419.693598 -283.329126)
		(end 419.249606 -283.144976)
		(width 0.18288)
		(layer "In4.Cu")
		(net "M_F_CPU0_SA_DQS_DN<8>")
	)
	(segment
		(start 411.09265 -272.289016)
		(end 410.96819 -272.413476)
		(width 0.18288)
		(layer "In4.Cu")
		(net "M_F_CPU0_SA_DQS_DN<8>")
	)
	(segment
		(start 405.127206 -270.382746)
		(end 396.930372 -262.185912)
		(width 0.18288)
		(layer "In4.Cu")
		(net "M_F_CPU0_SA_DQS_DN<8>")
	)
	(segment
		(start 405.843994 -270.857472)
		(end 405.491696 -270.857472)
		(width 0.18288)
		(layer "In4.Cu")
		(net "M_F_CPU0_SA_DQS_DN<8>")
	)
	(segment
		(start 419.249606 -283.144976)
		(end 418.880036 -282.775152)
		(width 0.18288)
		(layer "In4.Cu")
		(net "M_F_CPU0_SA_DQS_DN<8>")
	)
	(segment
		(start 393.804902 -262.185912)
		(end 392.842496 -261.785608)
		(width 0.18288)
		(layer "In4.Cu")
		(net "M_F_CPU0_SA_DQS_DN<8>")
	)
	(segment
		(start 411.63875 -272.289016)
		(end 411.09265 -272.289016)
		(width 0.18288)
		(layer "In4.Cu")
		(net "M_F_CPU0_SA_DQS_DN<8>")
	)
	(segment
		(start 418.880036 -282.775152)
		(end 418.069522 -280.818844)
		(width 0.18288)
		(layer "In4.Cu")
		(net "M_F_CPU0_SA_DQS_DN<8>")
	)
	(segment
		(start 415.293048 -274.583906)
		(end 413.961834 -273.252692)
		(width 0.18288)
		(layer "In4.Cu")
		(net "M_F_CPU0_SA_DQS_DN<8>")
	)
	(segment
		(start 421.953182 -283.899356)
		(end 421.385238 -283.331412)
		(width 0.18288)
		(layer "In4.Cu")
		(net "M_F_CPU0_SA_DQS_DN<8>")
	)
	(segment
		(start 406.350216 -270.575786)
		(end 406.12568 -270.575786)
		(width 0.18288)
		(layer "In4.Cu")
		(net "M_F_CPU0_SA_DQS_DN<8>")
	)
	(segment
		(start 421.385238 -283.331412)
		(end 421.193214 -283.331412)
		(width 0.18288)
		(layer "In4.Cu")
		(net "M_F_CPU0_SA_DQS_DN<8>")
	)
	(segment
		(start 407.324814 -271.207738)
		(end 407.257504 -271.04467)
		(width 0.18288)
		(layer "In4.Cu")
		(net "M_F_CPU0_SA_DQS_DN<8>")
	)
	(segment
		(start 417.945062 -278.197056)
		(end 418.069522 -278.072596)
		(width 0.18288)
		(layer "In4.Cu")
		(net "M_F_CPU0_SA_DQS_DN<8>")
	)
	(segment
		(start 383.387092 -260.11505)
		(end 383.37236 -260.106414)
		(width 0.088646)
		(layer "In4.Cu")
		(net "M_F_CPU0_SA_DQS_DN<8>")
	)
	(segment
		(start 410.96819 -272.413476)
		(end 410.42209 -272.413476)
		(width 0.18288)
		(layer "In4.Cu")
		(net "M_F_CPU0_SA_DQS_DN<8>")
	)
	(segment
		(start 396.930372 -262.185912)
		(end 393.804902 -262.185912)
		(width 0.18288)
		(layer "In4.Cu")
		(net "M_F_CPU0_SA_DQS_DN<8>")
	)
	(segment
		(start 392.842496 -261.785608)
		(end 392.509756 -261.452868)
		(width 0.18288)
		(layer "In4.Cu")
		(net "M_F_CPU0_SA_DQS_DN<8>")
	)
	(segment
		(start 386.78485 -260.24205)
		(end 386.724906 -260.182106)
		(width 0.088646)
		(layer "In4.Cu")
		(net "M_F_CPU0_SA_DQS_DN<8>")
	)
	(segment
		(start 413.457644 -273.04365)
		(end 413.29483 -273.11096)
		(width 0.18288)
		(layer "In4.Cu")
		(net "M_F_CPU0_SA_DQS_DN<8>")
	)
	(segment
		(start 418.069522 -278.867616)
		(end 417.945062 -278.743156)
		(width 0.18288)
		(layer "In4.Cu")
		(net "M_F_CPU0_SA_DQS_DN<8>")
	)
	(segment
		(start 408.496516 -271.558258)
		(end 407.992072 -271.349216)
		(width 0.18288)
		(layer "In4.Cu")
		(net "M_F_CPU0_SA_DQS_DN<8>")
	)
	(segment
		(start 409.227274 -272.289016)
		(end 408.496516 -271.558258)
		(width 0.18288)
		(layer "In4.Cu")
		(net "M_F_CPU0_SA_DQS_DN<8>")
	)
	(segment
		(start 389.594852 -260.24205)
		(end 386.808218 -260.24205)
		(width 0.18288)
		(layer "In4.Cu")
		(net "M_F_CPU0_SA_DQS_DN<8>")
	)
	(segment
		(start 380.986792 -260.18236)
		(end 380.831852 -260.223762)
		(width 0.088646)
		(layer "In4.Cu")
		(net "M_F_CPU0_SA_DQS_DN<8>")
	)
	(segment
		(start 381.118364 -260.106414)
		(end 380.986792 -260.18236)
		(width 0.088646)
		(layer "In4.Cu")
		(net "M_F_CPU0_SA_DQS_DN<8>")
	)
	(segment
		(start 412.790132 -272.901664)
		(end 412.722822 -272.738596)
		(width 0.18288)
		(layer "In4.Cu")
		(net "M_F_CPU0_SA_DQS_DN<8>")
	)
	(segment
		(start 380.831852 -260.223762)
		(end 380.440438 -260.223762)
		(width 0.088646)
		(layer "In4.Cu")
		(net "M_F_CPU0_SA_DQS_DN<8>")
	)
	(segment
		(start 418.069522 -280.818844)
		(end 418.069522 -280.272744)
		(width 0.18288)
		(layer "In4.Cu")
		(net "M_F_CPU0_SA_DQS_DN<8>")
	)
	(segment
		(start 380.377954 -260.28142)
		(end 380.366016 -260.430772)
		(width 0.088646)
		(layer "In4.Cu")
		(net "M_F_CPU0_SA_DQS_DN<8>")
	)
	(segment
		(start 418.069522 -279.477724)
		(end 418.069522 -278.867616)
		(width 0.18288)
		(layer "In4.Cu")
		(net "M_F_CPU0_SA_DQS_DN<8>")
	)
	(segment
		(start 424.56608 -283.746702)
		(end 424.376088 -283.746702)
		(width 0.18288)
		(layer "In4.Cu")
		(net "M_F_CPU0_SA_DQS_DN<8>")
	)
	(segment
		(start 417.352226 -275.154898)
		(end 416.605466 -274.845272)
		(width 0.18288)
		(layer "In4.Cu")
		(net "M_F_CPU0_SA_DQS_DN<8>")
	)
	(segment
		(start 418.069522 -277.736046)
		(end 417.698682 -275.87448)
		(width 0.18288)
		(layer "In4.Cu")
		(net "M_F_CPU0_SA_DQS_DN<8>")
	)
	(segment
		(start 410.42209 -272.413476)
		(end 410.29763 -272.289016)
		(width 0.18288)
		(layer "In4.Cu")
		(net "M_F_CPU0_SA_DQS_DN<8>")
	)
	(segment
		(start 407.257504 -271.04467)
		(end 406.50922 -270.73479)
		(width 0.18288)
		(layer "In4.Cu")
		(net "M_F_CPU0_SA_DQS_DN<8>")
	)
	(segment
		(start 417.945062 -279.602184)
		(end 418.069522 -279.477724)
		(width 0.18288)
		(layer "In4.Cu")
		(net "M_F_CPU0_SA_DQS_DN<8>")
	)
	(segment
		(start 424.836082 -284.016704)
		(end 424.56608 -283.746702)
		(width 0.18288)
		(layer "In4.Cu")
		(net "M_F_CPU0_SA_DQS_DN<8>")
	)
	(arc
		(start 384.87731 -260.106414)
		(mid 384.603111 -260.182249)
		(end 384.326638 -260.11505)
		(width 0.088646)
		(layer "In4.Cu")
		(net "M_F_CPU0_SA_DQS_DN<8>")
	)
	(arc
		(start 382.432814 -260.106414)
		(mid 382.245616 -260.056271)
		(end 382.058418 -260.106414)
		(width 0.088646)
		(layer "In4.Cu")
		(net "M_F_CPU0_SA_DQS_DN<8>")
	)
	(arc
		(start 380.440438 -260.223762)
		(mid 380.397911 -260.240375)
		(end 380.377954 -260.28142)
		(width 0.088646)
		(layer "In4.Cu")
		(net "M_F_CPU0_SA_DQS_DN<8>")
	)
	(arc
		(start 382.997964 -260.106414)
		(mid 382.721405 -260.182157)
		(end 382.443228 -260.11251)
		(width 0.088646)
		(layer "In4.Cu")
		(net "M_F_CPU0_SA_DQS_DN<8>")
	)
	(arc
		(start 385.81711 -260.106414)
		(mid 385.542911 -260.182249)
		(end 385.266438 -260.11505)
		(width 0.088646)
		(layer "In4.Cu")
		(net "M_F_CPU0_SA_DQS_DN<8>")
	)
	(arc
		(start 383.937764 -260.106414)
		(mid 383.663565 -260.182249)
		(end 383.387092 -260.11505)
		(width 0.088646)
		(layer "In4.Cu")
		(net "M_F_CPU0_SA_DQS_DN<8>")
	)
	(arc
		(start 382.058418 -260.106414)
		(mid 381.781605 -260.182284)
		(end 381.503174 -260.11251)
		(width 0.088646)
		(layer "In4.Cu")
		(net "M_F_CPU0_SA_DQS_DN<8>")
	)
	(arc
		(start 381.49276 -260.106414)
		(mid 381.305562 -260.056271)
		(end 381.118364 -260.106414)
		(width 0.088646)
		(layer "In4.Cu")
		(net "M_F_CPU0_SA_DQS_DN<8>")
	)
	(arc
		(start 385.251706 -260.106414)
		(mid 385.064508 -260.056271)
		(end 384.87731 -260.106414)
		(width 0.088646)
		(layer "In4.Cu")
		(net "M_F_CPU0_SA_DQS_DN<8>")
	)
	(arc
		(start 386.191506 -260.106414)
		(mid 386.004308 -260.056271)
		(end 385.81711 -260.106414)
		(width 0.088646)
		(layer "In4.Cu")
		(net "M_F_CPU0_SA_DQS_DN<8>")
	)
	(arc
		(start 384.303524 -260.101588)
		(mid 384.120016 -260.05631)
		(end 383.937764 -260.106414)
		(width 0.088646)
		(layer "In4.Cu")
		(net "M_F_CPU0_SA_DQS_DN<8>")
	)
	(arc
		(start 383.37236 -260.106414)
		(mid 383.185162 -260.056271)
		(end 382.997964 -260.106414)
		(width 0.088646)
		(layer "In4.Cu")
		(net "M_F_CPU0_SA_DQS_DN<8>")
	)
	(arc
		(start 386.473954 -260.182106)
		(mid 386.327746 -260.162857)
		(end 386.191506 -260.106414)
		(width 0.088646)
		(layer "In4.Cu")
		(net "M_F_CPU0_SA_DQS_DN<8>")
	)
	(segment
		(start 428.363126 -292.947852)
		(end 428.367952 -292.947852)
		(width 0.101854)
		(layer "F.Cu")
		(net "M_F_CPU0_SA_DQS_DN<7>")
	)
	(segment
		(start 426.471588 -293.366698)
		(end 426.74286 -293.095426)
		(width 0.20066)
		(layer "F.Cu")
		(net "M_F_CPU0_SA_DQS_DN<7>")
	)
	(segment
		(start 431.489612 -292.666928)
		(end 431.935128 -293.112444)
		(width 0.20066)
		(layer "F.Cu")
		(net "M_F_CPU0_SA_DQS_DN<7>")
	)
	(segment
		(start 432.726846 -293.112444)
		(end 432.9811 -293.366698)
		(width 0.20066)
		(layer "F.Cu")
		(net "M_F_CPU0_SA_DQS_DN<7>")
	)
	(segment
		(start 427.651164 -292.670484)
		(end 427.773592 -292.670484)
		(width 0.20066)
		(layer "F.Cu")
		(net "M_F_CPU0_SA_DQS_DN<7>")
	)
	(segment
		(start 428.367952 -292.947852)
		(end 428.374048 -292.941756)
		(width 0.1016)
		(layer "F.Cu")
		(net "M_F_CPU0_SA_DQS_DN<7>")
	)
	(segment
		(start 430.999646 -292.666928)
		(end 431.489612 -292.666928)
		(width 0.20066)
		(layer "F.Cu")
		(net "M_F_CPU0_SA_DQS_DN<7>")
	)
	(segment
		(start 425.940982 -293.366698)
		(end 426.471588 -293.366698)
		(width 0.20066)
		(layer "F.Cu")
		(net "M_F_CPU0_SA_DQS_DN<7>")
	)
	(segment
		(start 430.713896 -292.952678)
		(end 430.999646 -292.666928)
		(width 0.20066)
		(layer "F.Cu")
		(net "M_F_CPU0_SA_DQS_DN<7>")
	)
	(segment
		(start 383.655062 -267.219938)
		(end 383.655062 -267.755878)
		(width 0.20066)
		(layer "F.Cu")
		(net "M_F_CPU0_SA_DQS_DN<7>")
	)
	(segment
		(start 428.05096 -292.947852)
		(end 428.363126 -292.947852)
		(width 0.20066)
		(layer "F.Cu")
		(net "M_F_CPU0_SA_DQS_DN<7>")
	)
	(segment
		(start 424.836082 -293.366698)
		(end 425.940982 -293.366698)
		(width 0.20066)
		(layer "F.Cu")
		(net "M_F_CPU0_SA_DQS_DN<7>")
	)
	(segment
		(start 430.395126 -292.952678)
		(end 430.713896 -292.952678)
		(width 0.20066)
		(layer "F.Cu")
		(net "M_F_CPU0_SA_DQS_DN<7>")
	)
	(segment
		(start 430.384204 -292.941756)
		(end 430.395126 -292.952678)
		(width 0.1016)
		(layer "F.Cu")
		(net "M_F_CPU0_SA_DQS_DN<7>")
	)
	(segment
		(start 427.773592 -292.670484)
		(end 428.05096 -292.947852)
		(width 0.20066)
		(layer "F.Cu")
		(net "M_F_CPU0_SA_DQS_DN<7>")
	)
	(segment
		(start 426.74286 -293.095426)
		(end 427.226222 -293.095426)
		(width 0.20066)
		(layer "F.Cu")
		(net "M_F_CPU0_SA_DQS_DN<7>")
	)
	(segment
		(start 427.226222 -293.095426)
		(end 427.651164 -292.670484)
		(width 0.20066)
		(layer "F.Cu")
		(net "M_F_CPU0_SA_DQS_DN<7>")
	)
	(segment
		(start 432.9811 -293.366698)
		(end 433.484782 -293.366698)
		(width 0.20066)
		(layer "F.Cu")
		(net "M_F_CPU0_SA_DQS_DN<7>")
	)
	(segment
		(start 431.935128 -293.112444)
		(end 432.726846 -293.112444)
		(width 0.20066)
		(layer "F.Cu")
		(net "M_F_CPU0_SA_DQS_DN<7>")
	)
	(segment
		(start 428.374048 -292.941756)
		(end 430.384204 -292.941756)
		(width 0.1016)
		(layer "F.Cu")
		(net "M_F_CPU0_SA_DQS_DN<7>")
	)
	(segment
		(start 413.302704 -286.452056)
		(end 413.042608 -286.712152)
		(width 0.18288)
		(layer "In2.Cu")
		(net "M_F_CPU0_SA_DQS_DN<7>")
	)
	(segment
		(start 388.840472 -267.73886)
		(end 388.780528 -267.678916)
		(width 0.088646)
		(layer "In2.Cu")
		(net "M_F_CPU0_SA_DQS_DN<7>")
	)
	(segment
		(start 422.797986 -293.164514)
		(end 422.518078 -292.884606)
		(width 0.18288)
		(layer "In2.Cu")
		(net "M_F_CPU0_SA_DQS_DN<7>")
	)
	(segment
		(start 399.061178 -275.46935)
		(end 399.128742 -275.30679)
		(width 0.18288)
		(layer "In2.Cu")
		(net "M_F_CPU0_SA_DQS_DN<7>")
	)
	(segment
		(start 401.075144 -277.98522)
		(end 400.687286 -277.597362)
		(width 0.18288)
		(layer "In2.Cu")
		(net "M_F_CPU0_SA_DQS_DN<7>")
	)
	(segment
		(start 400.123152 -277.033228)
		(end 399.641822 -276.551644)
		(width 0.18288)
		(layer "In2.Cu")
		(net "M_F_CPU0_SA_DQS_DN<7>")
	)
	(segment
		(start 413.515556 -286.223456)
		(end 413.330898 -286.408114)
		(width 0.16002)
		(layer "In2.Cu")
		(net "M_F_CPU0_SA_DQS_DN<7>")
	)
	(segment
		(start 401.463256 -278.549608)
		(end 401.075144 -278.161242)
		(width 0.18288)
		(layer "In2.Cu")
		(net "M_F_CPU0_SA_DQS_DN<7>")
	)
	(segment
		(start 383.671318 -267.551408)
		(end 383.655062 -267.755878)
		(width 0.088646)
		(layer "In2.Cu")
		(net "M_F_CPU0_SA_DQS_DN<7>")
	)
	(segment
		(start 415.040572 -286.192468)
		(end 415.012378 -286.164274)
		(width 0.16002)
		(layer "In2.Cu")
		(net "M_F_CPU0_SA_DQS_DN<7>")
	)
	(segment
		(start 405.933402 -283.326332)
		(end 405.666448 -283.593286)
		(width 0.18288)
		(layer "In2.Cu")
		(net "M_F_CPU0_SA_DQS_DN<7>")
	)
	(segment
		(start 400.123152 -277.208996)
		(end 400.123152 -277.033228)
		(width 0.18288)
		(layer "In2.Cu")
		(net "M_F_CPU0_SA_DQS_DN<7>")
	)
	(segment
		(start 415.974022 -287.125918)
		(end 415.269172 -286.421068)
		(width 0.18288)
		(layer "In2.Cu")
		(net "M_F_CPU0_SA_DQS_DN<7>")
	)
	(segment
		(start 398.065244 -273.737324)
		(end 397.677132 -273.349212)
		(width 0.18288)
		(layer "In2.Cu")
		(net "M_F_CPU0_SA_DQS_DN<7>")
	)
	(segment
		(start 418.519356 -291.799772)
		(end 417.675822 -291.653722)
		(width 0.18288)
		(layer "In2.Cu")
		(net "M_F_CPU0_SA_DQS_DN<7>")
	)
	(segment
		(start 397.113252 -272.785332)
		(end 396.72514 -272.39722)
		(width 0.18288)
		(layer "In2.Cu")
		(net "M_F_CPU0_SA_DQS_DN<7>")
	)
	(segment
		(start 408.101038 -284.208474)
		(end 407.689812 -283.797248)
		(width 0.18288)
		(layer "In2.Cu")
		(net "M_F_CPU0_SA_DQS_DN<7>")
	)
	(segment
		(start 413.67329 -286.08147)
		(end 413.559498 -286.195262)
		(width 0.18288)
		(layer "In2.Cu")
		(net "M_F_CPU0_SA_DQS_DN<7>")
	)
	(segment
		(start 415.240978 -286.392874)
		(end 415.240978 -286.377126)
		(width 0.16002)
		(layer "In2.Cu")
		(net "M_F_CPU0_SA_DQS_DN<7>")
	)
	(segment
		(start 424.836082 -293.366698)
		(end 424.715686 -293.094918)
		(width 0.18288)
		(layer "In2.Cu")
		(net "M_F_CPU0_SA_DQS_DN<7>")
	)
	(segment
		(start 417.675822 -291.653722)
		(end 416.900614 -291.016944)
		(width 0.18288)
		(layer "In2.Cu")
		(net "M_F_CPU0_SA_DQS_DN<7>")
	)
	(segment
		(start 403.543262 -280.453846)
		(end 403.36724 -280.453846)
		(width 0.18288)
		(layer "In2.Cu")
		(net "M_F_CPU0_SA_DQS_DN<7>")
	)
	(segment
		(start 415.05632 -286.192468)
		(end 415.040572 -286.192468)
		(width 0.16002)
		(layer "In2.Cu")
		(net "M_F_CPU0_SA_DQS_DN<7>")
	)
	(segment
		(start 397.289274 -272.785332)
		(end 397.113252 -272.785332)
		(width 0.18288)
		(layer "In2.Cu")
		(net "M_F_CPU0_SA_DQS_DN<7>")
	)
	(segment
		(start 424.637708 -293.01694)
		(end 424.27144 -293.01694)
		(width 0.18288)
		(layer "In2.Cu")
		(net "M_F_CPU0_SA_DQS_DN<7>")
	)
	(segment
		(start 391.027666 -267.931646)
		(end 390.562338 -267.73886)
		(width 0.18288)
		(layer "In2.Cu")
		(net "M_F_CPU0_SA_DQS_DN<7>")
	)
	(segment
		(start 416.47237 -289.98291)
		(end 416.703002 -289.426396)
		(width 0.18288)
		(layer "In2.Cu")
		(net "M_F_CPU0_SA_DQS_DN<7>")
	)
	(segment
		(start 397.677132 -273.17319)
		(end 397.289274 -272.785332)
		(width 0.18288)
		(layer "In2.Cu")
		(net "M_F_CPU0_SA_DQS_DN<7>")
	)
	(segment
		(start 413.330898 -286.408114)
		(end 413.330898 -286.423862)
		(width 0.16002)
		(layer "In2.Cu")
		(net "M_F_CPU0_SA_DQS_DN<7>")
	)
	(segment
		(start 424.27144 -293.01694)
		(end 423.606976 -293.292022)
		(width 0.18288)
		(layer "In2.Cu")
		(net "M_F_CPU0_SA_DQS_DN<7>")
	)
	(segment
		(start 407.47696 -283.568648)
		(end 407.461212 -283.568648)
		(width 0.16002)
		(layer "In2.Cu")
		(net "M_F_CPU0_SA_DQS_DN<7>")
	)
	(segment
		(start 420.19982 -292.665404)
		(end 419.705536 -292.665404)
		(width 0.18288)
		(layer "In2.Cu")
		(net "M_F_CPU0_SA_DQS_DN<7>")
	)
	(segment
		(start 424.715686 -293.094918)
		(end 424.637708 -293.01694)
		(width 0.18288)
		(layer "In2.Cu")
		(net "M_F_CPU0_SA_DQS_DN<7>")
	)
	(segment
		(start 388.780528 -267.678916)
		(end 388.207504 -267.678916)
		(width 0.088646)
		(layer "In2.Cu")
		(net "M_F_CPU0_SA_DQS_DN<7>")
	)
	(segment
		(start 415.240978 -286.377126)
		(end 415.05632 -286.192468)
		(width 0.16002)
		(layer "In2.Cu")
		(net "M_F_CPU0_SA_DQS_DN<7>")
	)
	(segment
		(start 402.027136 -279.113488)
		(end 402.027136 -278.937466)
		(width 0.18288)
		(layer "In2.Cu")
		(net "M_F_CPU0_SA_DQS_DN<7>")
	)
	(segment
		(start 422.518078 -292.884606)
		(end 422.015666 -292.67658)
		(width 0.18288)
		(layer "In2.Cu")
		(net "M_F_CPU0_SA_DQS_DN<7>")
	)
	(segment
		(start 411.37713 -286.619696)
		(end 410.576268 -286.619696)
		(width 0.18288)
		(layer "In2.Cu")
		(net "M_F_CPU0_SA_DQS_DN<7>")
	)
	(segment
		(start 404.988268 -283.315156)
		(end 404.787354 -283.315156)
		(width 0.18288)
		(layer "In2.Cu")
		(net "M_F_CPU0_SA_DQS_DN<7>")
	)
	(segment
		(start 398.241266 -273.737324)
		(end 398.065244 -273.737324)
		(width 0.18288)
		(layer "In2.Cu")
		(net "M_F_CPU0_SA_DQS_DN<7>")
	)
	(segment
		(start 399.433034 -276.044406)
		(end 399.27022 -275.976842)
		(width 0.18288)
		(layer "In2.Cu")
		(net "M_F_CPU0_SA_DQS_DN<7>")
	)
	(segment
		(start 420.476426 -292.94201)
		(end 420.19982 -292.665404)
		(width 0.18288)
		(layer "In2.Cu")
		(net "M_F_CPU0_SA_DQS_DN<7>")
	)
	(segment
		(start 384.407664 -267.43152)
		(end 384.406902 -267.431266)
		(width 0.088646)
		(layer "In2.Cu")
		(net "M_F_CPU0_SA_DQS_DN<7>")
	)
	(segment
		(start 403.36724 -280.453846)
		(end 402.979128 -280.06548)
		(width 0.18288)
		(layer "In2.Cu")
		(net "M_F_CPU0_SA_DQS_DN<7>")
	)
	(segment
		(start 415.269172 -286.421068)
		(end 415.240978 -286.392874)
		(width 0.16002)
		(layer "In2.Cu")
		(net "M_F_CPU0_SA_DQS_DN<7>")
	)
	(segment
		(start 397.677132 -273.349212)
		(end 397.677132 -273.17319)
		(width 0.18288)
		(layer "In2.Cu")
		(net "M_F_CPU0_SA_DQS_DN<7>")
	)
	(segment
		(start 399.128742 -275.30679)
		(end 398.660366 -274.169886)
		(width 0.18288)
		(layer "In2.Cu")
		(net "M_F_CPU0_SA_DQS_DN<7>")
	)
	(segment
		(start 384.053588 -267.525754)
		(end 383.699004 -267.525754)
		(width 0.088646)
		(layer "In2.Cu")
		(net "M_F_CPU0_SA_DQS_DN<7>")
	)
	(segment
		(start 407.461212 -283.568648)
		(end 407.433018 -283.540454)
		(width 0.16002)
		(layer "In2.Cu")
		(net "M_F_CPU0_SA_DQS_DN<7>")
	)
	(segment
		(start 399.27022 -275.976842)
		(end 399.061178 -275.46935)
		(width 0.18288)
		(layer "In2.Cu")
		(net "M_F_CPU0_SA_DQS_DN<7>")
	)
	(segment
		(start 398.660366 -274.169886)
		(end 398.65808 -274.166838)
		(width 0.18288)
		(layer "In2.Cu")
		(net "M_F_CPU0_SA_DQS_DN<7>")
	)
	(segment
		(start 404.787354 -283.315156)
		(end 404.342346 -282.870148)
		(width 0.18288)
		(layer "In2.Cu")
		(net "M_F_CPU0_SA_DQS_DN<7>")
	)
	(segment
		(start 407.689812 -283.797248)
		(end 407.661618 -283.769054)
		(width 0.16002)
		(layer "In2.Cu")
		(net "M_F_CPU0_SA_DQS_DN<7>")
	)
	(segment
		(start 410.576268 -286.619696)
		(end 409.823666 -286.308038)
		(width 0.18288)
		(layer "In2.Cu")
		(net "M_F_CPU0_SA_DQS_DN<7>")
	)
	(segment
		(start 421.224202 -292.67658)
		(end 420.96055 -292.940232)
		(width 0.18288)
		(layer "In2.Cu")
		(net "M_F_CPU0_SA_DQS_DN<7>")
	)
	(segment
		(start 396.20063 -271.696688)
		(end 394.792708 -271.696688)
		(width 0.18288)
		(layer "In2.Cu")
		(net "M_F_CPU0_SA_DQS_DN<7>")
	)
	(segment
		(start 415.012378 -286.164274)
		(end 414.929574 -286.08147)
		(width 0.18288)
		(layer "In2.Cu")
		(net "M_F_CPU0_SA_DQS_DN<7>")
	)
	(segment
		(start 420.96055 -292.94201)
		(end 420.476426 -292.94201)
		(width 0.18288)
		(layer "In2.Cu")
		(net "M_F_CPU0_SA_DQS_DN<7>")
	)
	(segment
		(start 423.606976 -293.292022)
		(end 423.105834 -293.292022)
		(width 0.18288)
		(layer "In2.Cu")
		(net "M_F_CPU0_SA_DQS_DN<7>")
	)
	(segment
		(start 412.138114 -287.004252)
		(end 411.761686 -287.004252)
		(width 0.18288)
		(layer "In2.Cu")
		(net "M_F_CPU0_SA_DQS_DN<7>")
	)
	(segment
		(start 402.979128 -280.06548)
		(end 402.979128 -279.889712)
		(width 0.18288)
		(layer "In2.Cu")
		(net "M_F_CPU0_SA_DQS_DN<7>")
	)
	(segment
		(start 414.929574 -286.08147)
		(end 413.67329 -286.08147)
		(width 0.18288)
		(layer "In2.Cu")
		(net "M_F_CPU0_SA_DQS_DN<7>")
	)
	(segment
		(start 387.615938 -267.439902)
		(end 387.60146 -267.43152)
		(width 0.088646)
		(layer "In2.Cu")
		(net "M_F_CPU0_SA_DQS_DN<7>")
	)
	(segment
		(start 419.705536 -292.665404)
		(end 419.066472 -292.026594)
		(width 0.18288)
		(layer "In2.Cu")
		(net "M_F_CPU0_SA_DQS_DN<7>")
	)
	(segment
		(start 400.511264 -277.597362)
		(end 400.123152 -277.208996)
		(width 0.18288)
		(layer "In2.Cu")
		(net "M_F_CPU0_SA_DQS_DN<7>")
	)
	(segment
		(start 422.015666 -292.67658)
		(end 421.224202 -292.67658)
		(width 0.18288)
		(layer "In2.Cu")
		(net "M_F_CPU0_SA_DQS_DN<7>")
	)
	(segment
		(start 396.72514 -272.39722)
		(end 396.72514 -272.221198)
		(width 0.18288)
		(layer "In2.Cu")
		(net "M_F_CPU0_SA_DQS_DN<7>")
	)
	(segment
		(start 396.72514 -272.221198)
		(end 396.20063 -271.696688)
		(width 0.18288)
		(layer "In2.Cu")
		(net "M_F_CPU0_SA_DQS_DN<7>")
	)
	(segment
		(start 423.105834 -293.292022)
		(end 422.797986 -293.164514)
		(width 0.18288)
		(layer "In2.Cu")
		(net "M_F_CPU0_SA_DQS_DN<7>")
	)
	(segment
		(start 399.641822 -276.551644)
		(end 399.433034 -276.044406)
		(width 0.18288)
		(layer "In2.Cu")
		(net "M_F_CPU0_SA_DQS_DN<7>")
	)
	(segment
		(start 398.629124 -274.125182)
		(end 398.241266 -273.737324)
		(width 0.18288)
		(layer "In2.Cu")
		(net "M_F_CPU0_SA_DQS_DN<7>")
	)
	(segment
		(start 404.342346 -281.833066)
		(end 403.93112 -280.841704)
		(width 0.18288)
		(layer "In2.Cu")
		(net "M_F_CPU0_SA_DQS_DN<7>")
	)
	(segment
		(start 413.559498 -286.195262)
		(end 413.531304 -286.223456)
		(width 0.16002)
		(layer "In2.Cu")
		(net "M_F_CPU0_SA_DQS_DN<7>")
	)
	(segment
		(start 413.330898 -286.423862)
		(end 413.302704 -286.452056)
		(width 0.16002)
		(layer "In2.Cu")
		(net "M_F_CPU0_SA_DQS_DN<7>")
	)
	(segment
		(start 402.59127 -279.501854)
		(end 402.415248 -279.501854)
		(width 0.18288)
		(layer "In2.Cu")
		(net "M_F_CPU0_SA_DQS_DN<7>")
	)
	(segment
		(start 412.430214 -286.712152)
		(end 412.138114 -287.004252)
		(width 0.18288)
		(layer "In2.Cu")
		(net "M_F_CPU0_SA_DQS_DN<7>")
	)
	(segment
		(start 409.823666 -286.307784)
		(end 408.101038 -284.208474)
		(width 0.18288)
		(layer "In2.Cu")
		(net "M_F_CPU0_SA_DQS_DN<7>")
	)
	(segment
		(start 419.066472 -292.026594)
		(end 418.519356 -291.799772)
		(width 0.18288)
		(layer "In2.Cu")
		(net "M_F_CPU0_SA_DQS_DN<7>")
	)
	(segment
		(start 416.703002 -288.885884)
		(end 415.974022 -287.125918)
		(width 0.18288)
		(layer "In2.Cu")
		(net "M_F_CPU0_SA_DQS_DN<7>")
	)
	(segment
		(start 403.93112 -280.841704)
		(end 403.543262 -280.453846)
		(width 0.18288)
		(layer "In2.Cu")
		(net "M_F_CPU0_SA_DQS_DN<7>")
	)
	(segment
		(start 402.415248 -279.501854)
		(end 402.027136 -279.113488)
		(width 0.18288)
		(layer "In2.Cu")
		(net "M_F_CPU0_SA_DQS_DN<7>")
	)
	(segment
		(start 400.687286 -277.597362)
		(end 400.511264 -277.597362)
		(width 0.18288)
		(layer "In2.Cu")
		(net "M_F_CPU0_SA_DQS_DN<7>")
	)
	(segment
		(start 388.207504 -267.678916)
		(end 388.055612 -267.527024)
		(width 0.088646)
		(layer "In2.Cu")
		(net "M_F_CPU0_SA_DQS_DN<7>")
	)
	(segment
		(start 411.761686 -287.004252)
		(end 411.37713 -286.619696)
		(width 0.18288)
		(layer "In2.Cu")
		(net "M_F_CPU0_SA_DQS_DN<7>")
	)
	(segment
		(start 416.703002 -289.426396)
		(end 416.703002 -288.885884)
		(width 0.18288)
		(layer "In2.Cu")
		(net "M_F_CPU0_SA_DQS_DN<7>")
	)
	(segment
		(start 404.342346 -282.870148)
		(end 404.342346 -281.833066)
		(width 0.18288)
		(layer "In2.Cu")
		(net "M_F_CPU0_SA_DQS_DN<7>")
	)
	(segment
		(start 402.027136 -278.937466)
		(end 401.639278 -278.549608)
		(width 0.18288)
		(layer "In2.Cu")
		(net "M_F_CPU0_SA_DQS_DN<7>")
	)
	(segment
		(start 402.979128 -279.889712)
		(end 402.59127 -279.501854)
		(width 0.18288)
		(layer "In2.Cu")
		(net "M_F_CPU0_SA_DQS_DN<7>")
	)
	(segment
		(start 394.792708 -271.696688)
		(end 391.027666 -267.931646)
		(width 0.18288)
		(layer "In2.Cu")
		(net "M_F_CPU0_SA_DQS_DN<7>")
	)
	(segment
		(start 407.433018 -283.540454)
		(end 407.218896 -283.326332)
		(width 0.18288)
		(layer "In2.Cu")
		(net "M_F_CPU0_SA_DQS_DN<7>")
	)
	(segment
		(start 383.699004 -267.525754)
		(end 383.671318 -267.551408)
		(width 0.088646)
		(layer "In2.Cu")
		(net "M_F_CPU0_SA_DQS_DN<7>")
	)
	(segment
		(start 405.266398 -283.593286)
		(end 404.988268 -283.315156)
		(width 0.18288)
		(layer "In2.Cu")
		(net "M_F_CPU0_SA_DQS_DN<7>")
	)
	(segment
		(start 407.661618 -283.753306)
		(end 407.47696 -283.568648)
		(width 0.16002)
		(layer "In2.Cu")
		(net "M_F_CPU0_SA_DQS_DN<7>")
	)
	(segment
		(start 413.531304 -286.223456)
		(end 413.515556 -286.223456)
		(width 0.16002)
		(layer "In2.Cu")
		(net "M_F_CPU0_SA_DQS_DN<7>")
	)
	(segment
		(start 413.042608 -286.712152)
		(end 412.430214 -286.712152)
		(width 0.18288)
		(layer "In2.Cu")
		(net "M_F_CPU0_SA_DQS_DN<7>")
	)
	(segment
		(start 390.562338 -267.73886)
		(end 388.840472 -267.73886)
		(width 0.18288)
		(layer "In2.Cu")
		(net "M_F_CPU0_SA_DQS_DN<7>")
	)
	(segment
		(start 407.218896 -283.326332)
		(end 405.933402 -283.326332)
		(width 0.18288)
		(layer "In2.Cu")
		(net "M_F_CPU0_SA_DQS_DN<7>")
	)
	(segment
		(start 405.666448 -283.593286)
		(end 405.266398 -283.593286)
		(width 0.18288)
		(layer "In2.Cu")
		(net "M_F_CPU0_SA_DQS_DN<7>")
	)
	(segment
		(start 420.96055 -292.940232)
		(end 420.96055 -292.94201)
		(width 0.18288)
		(layer "In2.Cu")
		(net "M_F_CPU0_SA_DQS_DN<7>")
	)
	(segment
		(start 398.65808 -274.166838)
		(end 398.629124 -274.125182)
		(width 0.18288)
		(layer "In2.Cu")
		(net "M_F_CPU0_SA_DQS_DN<7>")
	)
	(segment
		(start 407.661618 -283.769054)
		(end 407.661618 -283.753306)
		(width 0.16002)
		(layer "In2.Cu")
		(net "M_F_CPU0_SA_DQS_DN<7>")
	)
	(segment
		(start 401.639278 -278.549608)
		(end 401.463256 -278.549608)
		(width 0.18288)
		(layer "In2.Cu")
		(net "M_F_CPU0_SA_DQS_DN<7>")
	)
	(segment
		(start 401.075144 -278.161242)
		(end 401.075144 -277.98522)
		(width 0.18288)
		(layer "In2.Cu")
		(net "M_F_CPU0_SA_DQS_DN<7>")
	)
	(segment
		(start 409.823666 -286.308038)
		(end 409.823666 -286.307784)
		(width 0.18288)
		(layer "In2.Cu")
		(net "M_F_CPU0_SA_DQS_DN<7>")
	)
	(segment
		(start 416.900614 -291.016944)
		(end 416.47237 -289.98291)
		(width 0.18288)
		(layer "In2.Cu")
		(net "M_F_CPU0_SA_DQS_DN<7>")
	)
	(segment
		(start 388.055612 -267.527024)
		(end 387.921246 -267.527024)
		(width 0.088646)
		(layer "In2.Cu")
		(net "M_F_CPU0_SA_DQS_DN<7>")
	)
	(arc
		(start 386.66166 -267.43152)
		(mid 386.474462 -267.381377)
		(end 386.287264 -267.43152)
		(width 0.088646)
		(layer "In2.Cu")
		(net "M_F_CPU0_SA_DQS_DN<7>")
	)
	(arc
		(start 386.287264 -267.43152)
		(mid 386.004562 -267.507262)
		(end 385.72186 -267.43152)
		(width 0.088646)
		(layer "In2.Cu")
		(net "M_F_CPU0_SA_DQS_DN<7>")
	)
	(arc
		(start 387.921246 -267.527024)
		(mid 387.852362 -267.522803)
		(end 387.784594 -267.509752)
		(width 0.088646)
		(layer "In2.Cu")
		(net "M_F_CPU0_SA_DQS_DN<7>")
	)
	(arc
		(start 384.406902 -267.431266)
		(mid 384.236447 -267.50169)
		(end 384.053588 -267.525754)
		(width 0.088646)
		(layer "In2.Cu")
		(net "M_F_CPU0_SA_DQS_DN<7>")
	)
	(arc
		(start 385.72186 -267.43152)
		(mid 385.534662 -267.381377)
		(end 385.347464 -267.43152)
		(width 0.088646)
		(layer "In2.Cu")
		(net "M_F_CPU0_SA_DQS_DN<7>")
	)
	(arc
		(start 387.60146 -267.43152)
		(mid 387.414262 -267.381377)
		(end 387.227064 -267.43152)
		(width 0.088646)
		(layer "In2.Cu")
		(net "M_F_CPU0_SA_DQS_DN<7>")
	)
	(arc
		(start 384.78206 -267.43152)
		(mid 384.594862 -267.381377)
		(end 384.407664 -267.43152)
		(width 0.088646)
		(layer "In2.Cu")
		(net "M_F_CPU0_SA_DQS_DN<7>")
	)
	(arc
		(start 387.784594 -267.509752)
		(mid 387.697924 -267.480482)
		(end 387.615938 -267.439902)
		(width 0.088646)
		(layer "In2.Cu")
		(net "M_F_CPU0_SA_DQS_DN<7>")
	)
	(arc
		(start 385.347464 -267.43152)
		(mid 385.064762 -267.507262)
		(end 384.78206 -267.43152)
		(width 0.088646)
		(layer "In2.Cu")
		(net "M_F_CPU0_SA_DQS_DN<7>")
	)
	(arc
		(start 387.227064 -267.43152)
		(mid 386.944362 -267.507262)
		(end 386.66166 -267.43152)
		(width 0.088646)
		(layer "In2.Cu")
		(net "M_F_CPU0_SA_DQS_DN<7>")
	)
	(segment
		(start 432.726846 -302.462438)
		(end 432.9811 -302.716692)
		(width 0.20066)
		(layer "F.Cu")
		(net "M_F_CPU0_SA_DQS_DN<6>")
	)
	(segment
		(start 425.940982 -302.716692)
		(end 426.471588 -302.716692)
		(width 0.20066)
		(layer "F.Cu")
		(net "M_F_CPU0_SA_DQS_DN<6>")
	)
	(segment
		(start 430.384204 -302.29175)
		(end 430.395126 -302.302672)
		(width 0.1016)
		(layer "F.Cu")
		(net "M_F_CPU0_SA_DQS_DN<6>")
	)
	(segment
		(start 428.05096 -302.297846)
		(end 428.363126 -302.297846)
		(width 0.20066)
		(layer "F.Cu")
		(net "M_F_CPU0_SA_DQS_DN<6>")
	)
	(segment
		(start 427.773592 -302.020478)
		(end 428.05096 -302.297846)
		(width 0.20066)
		(layer "F.Cu")
		(net "M_F_CPU0_SA_DQS_DN<6>")
	)
	(segment
		(start 430.395126 -302.302672)
		(end 430.713896 -302.302672)
		(width 0.20066)
		(layer "F.Cu")
		(net "M_F_CPU0_SA_DQS_DN<6>")
	)
	(segment
		(start 380.366016 -270.167862)
		(end 380.366016 -270.19758)
		(width 0.20066)
		(layer "F.Cu")
		(net "M_F_CPU0_SA_DQS_DN<6>")
	)
	(segment
		(start 424.836082 -302.716692)
		(end 425.940982 -302.716692)
		(width 0.20066)
		(layer "F.Cu")
		(net "M_F_CPU0_SA_DQS_DN<6>")
	)
	(segment
		(start 430.713896 -302.302672)
		(end 430.999646 -302.016922)
		(width 0.20066)
		(layer "F.Cu")
		(net "M_F_CPU0_SA_DQS_DN<6>")
	)
	(segment
		(start 431.489612 -302.016922)
		(end 431.935128 -302.462438)
		(width 0.20066)
		(layer "F.Cu")
		(net "M_F_CPU0_SA_DQS_DN<6>")
	)
	(segment
		(start 427.651164 -302.020478)
		(end 427.773592 -302.020478)
		(width 0.20066)
		(layer "F.Cu")
		(net "M_F_CPU0_SA_DQS_DN<6>")
	)
	(segment
		(start 428.374048 -302.29175)
		(end 430.384204 -302.29175)
		(width 0.1016)
		(layer "F.Cu")
		(net "M_F_CPU0_SA_DQS_DN<6>")
	)
	(segment
		(start 380.365762 -269.66164)
		(end 380.366016 -270.167862)
		(width 0.20066)
		(layer "F.Cu")
		(net "M_F_CPU0_SA_DQS_DN<6>")
	)
	(segment
		(start 428.363126 -302.297846)
		(end 428.367952 -302.297846)
		(width 0.101854)
		(layer "F.Cu")
		(net "M_F_CPU0_SA_DQS_DN<6>")
	)
	(segment
		(start 427.226222 -302.44542)
		(end 427.651164 -302.020478)
		(width 0.20066)
		(layer "F.Cu")
		(net "M_F_CPU0_SA_DQS_DN<6>")
	)
	(segment
		(start 430.999646 -302.016922)
		(end 431.489612 -302.016922)
		(width 0.20066)
		(layer "F.Cu")
		(net "M_F_CPU0_SA_DQS_DN<6>")
	)
	(segment
		(start 426.471588 -302.716692)
		(end 426.74286 -302.44542)
		(width 0.20066)
		(layer "F.Cu")
		(net "M_F_CPU0_SA_DQS_DN<6>")
	)
	(segment
		(start 428.367952 -302.297846)
		(end 428.374048 -302.29175)
		(width 0.1016)
		(layer "F.Cu")
		(net "M_F_CPU0_SA_DQS_DN<6>")
	)
	(segment
		(start 431.935128 -302.462438)
		(end 432.726846 -302.462438)
		(width 0.20066)
		(layer "F.Cu")
		(net "M_F_CPU0_SA_DQS_DN<6>")
	)
	(segment
		(start 432.9811 -302.716692)
		(end 433.484782 -302.716692)
		(width 0.20066)
		(layer "F.Cu")
		(net "M_F_CPU0_SA_DQS_DN<6>")
	)
	(segment
		(start 426.74286 -302.44542)
		(end 427.226222 -302.44542)
		(width 0.20066)
		(layer "F.Cu")
		(net "M_F_CPU0_SA_DQS_DN<6>")
	)
	(segment
		(start 380.76251 -269.99057)
		(end 380.440438 -269.99057)
		(width 0.088646)
		(layer "In4.Cu")
		(net "M_F_CPU0_SA_DQS_DN<6>")
	)
	(segment
		(start 408.088338 -296.081196)
		(end 407.097992 -295.49471)
		(width 0.18288)
		(layer "In4.Cu")
		(net "M_F_CPU0_SA_DQS_DN<6>")
	)
	(segment
		(start 388.20979 -271.755108)
		(end 388.20979 -271.670272)
		(width 0.088646)
		(layer "In4.Cu")
		(net "M_F_CPU0_SA_DQS_DN<6>")
	)
	(segment
		(start 402.448522 -292.095936)
		(end 401.31365 -290.961064)
		(width 0.18288)
		(layer "In4.Cu")
		(net "M_F_CPU0_SA_DQS_DN<6>")
	)
	(segment
		(start 410.995368 -298.17314)
		(end 410.819346 -298.17314)
		(width 0.18288)
		(layer "In4.Cu")
		(net "M_F_CPU0_SA_DQS_DN<6>")
	)
	(segment
		(start 403.396958 -293.220394)
		(end 403.396958 -293.044372)
		(width 0.18288)
		(layer "In4.Cu")
		(net "M_F_CPU0_SA_DQS_DN<6>")
	)
	(segment
		(start 424.540934 -302.421544)
		(end 424.165268 -302.421544)
		(width 0.18288)
		(layer "In4.Cu")
		(net "M_F_CPU0_SA_DQS_DN<6>")
	)
	(segment
		(start 383.387346 -269.881858)
		(end 383.372614 -269.873222)
		(width 0.088646)
		(layer "In4.Cu")
		(net "M_F_CPU0_SA_DQS_DN<6>")
	)
	(segment
		(start 406.469088 -295.230042)
		(end 406.433528 -295.057576)
		(width 0.18288)
		(layer "In4.Cu")
		(net "M_F_CPU0_SA_DQS_DN<6>")
	)
	(segment
		(start 390.984486 -273.733514)
		(end 390.188196 -273.733514)
		(width 0.18288)
		(layer "In4.Cu")
		(net "M_F_CPU0_SA_DQS_DN<6>")
	)
	(segment
		(start 416.455352 -302.295306)
		(end 415.59607 -301.436278)
		(width 0.18288)
		(layer "In4.Cu")
		(net "M_F_CPU0_SA_DQS_DN<6>")
	)
	(segment
		(start 409.807156 -296.984928)
		(end 409.293314 -296.714926)
		(width 0.18288)
		(layer "In4.Cu")
		(net "M_F_CPU0_SA_DQS_DN<6>")
	)
	(segment
		(start 403.959314 -293.606728)
		(end 403.783292 -293.606728)
		(width 0.18288)
		(layer "In4.Cu")
		(net "M_F_CPU0_SA_DQS_DN<6>")
	)
	(segment
		(start 384.327146 -269.881858)
		(end 384.312414 -269.873222)
		(width 0.088646)
		(layer "In4.Cu")
		(net "M_F_CPU0_SA_DQS_DN<6>")
	)
	(segment
		(start 383.000504 -269.871444)
		(end 382.990598 -269.877286)
		(width 0.088646)
		(layer "In4.Cu")
		(net "M_F_CPU0_SA_DQS_DN<6>")
	)
	(segment
		(start 404.345394 -293.992808)
		(end 403.959314 -293.606728)
		(width 0.18288)
		(layer "In4.Cu")
		(net "M_F_CPU0_SA_DQS_DN<6>")
	)
	(segment
		(start 404.714456 -294.302942)
		(end 404.654512 -294.137588)
		(width 0.18288)
		(layer "In4.Cu")
		(net "M_F_CPU0_SA_DQS_DN<6>")
	)
	(segment
		(start 409.293314 -296.714926)
		(end 409.125166 -296.766996)
		(width 0.18288)
		(layer "In4.Cu")
		(net "M_F_CPU0_SA_DQS_DN<6>")
	)
	(segment
		(start 405.208994 -294.535098)
		(end 404.714456 -294.302942)
		(width 0.18288)
		(layer "In4.Cu")
		(net "M_F_CPU0_SA_DQS_DN<6>")
	)
	(segment
		(start 413.91332 -300.297088)
		(end 413.91332 -300.121066)
		(width 0.18288)
		(layer "In4.Cu")
		(net "M_F_CPU0_SA_DQS_DN<6>")
	)
	(segment
		(start 380.377954 -270.048228)
		(end 380.366016 -270.19758)
		(width 0.088646)
		(layer "In4.Cu")
		(net "M_F_CPU0_SA_DQS_DN<6>")
	)
	(segment
		(start 402.448522 -292.271958)
		(end 402.448522 -292.095936)
		(width 0.18288)
		(layer "In4.Cu")
		(net "M_F_CPU0_SA_DQS_DN<6>")
	)
	(segment
		(start 387.259576 -271.00022)
		(end 386.821934 -270.828516)
		(width 0.088646)
		(layer "In4.Cu")
		(net "M_F_CPU0_SA_DQS_DN<6>")
	)
	(segment
		(start 406.925526 -295.53027)
		(end 406.469088 -295.230042)
		(width 0.18288)
		(layer "In4.Cu")
		(net "M_F_CPU0_SA_DQS_DN<6>")
	)
	(segment
		(start 401.31365 -290.961064)
		(end 396.439898 -279.18918)
		(width 0.18288)
		(layer "In4.Cu")
		(net "M_F_CPU0_SA_DQS_DN<6>")
	)
	(segment
		(start 409.125166 -296.766996)
		(end 408.64155 -296.512742)
		(width 0.18288)
		(layer "In4.Cu")
		(net "M_F_CPU0_SA_DQS_DN<6>")
	)
	(segment
		(start 404.654512 -294.137588)
		(end 404.345394 -293.992808)
		(width 0.18288)
		(layer "In4.Cu")
		(net "M_F_CPU0_SA_DQS_DN<6>")
	)
	(segment
		(start 386.379466 -270.213074)
		(end 386.379466 -270.19758)
		(width 0.088646)
		(layer "In4.Cu")
		(net "M_F_CPU0_SA_DQS_DN<6>")
	)
	(segment
		(start 414.299654 -300.683422)
		(end 413.91332 -300.297088)
		(width 0.18288)
		(layer "In4.Cu")
		(net "M_F_CPU0_SA_DQS_DN<6>")
	)
	(segment
		(start 408.64155 -296.512742)
		(end 408.58948 -296.344594)
		(width 0.18288)
		(layer "In4.Cu")
		(net "M_F_CPU0_SA_DQS_DN<6>")
	)
	(segment
		(start 386.821934 -270.828516)
		(end 386.739638 -270.745966)
		(width 0.088646)
		(layer "In4.Cu")
		(net "M_F_CPU0_SA_DQS_DN<6>")
	)
	(segment
		(start 403.010878 -292.658292)
		(end 402.834856 -292.658292)
		(width 0.18288)
		(layer "In4.Cu")
		(net "M_F_CPU0_SA_DQS_DN<6>")
	)
	(segment
		(start 403.396958 -293.044372)
		(end 403.010878 -292.658292)
		(width 0.18288)
		(layer "In4.Cu")
		(net "M_F_CPU0_SA_DQS_DN<6>")
	)
	(segment
		(start 407.097992 -295.49471)
		(end 406.925526 -295.53027)
		(width 0.18288)
		(layer "In4.Cu")
		(net "M_F_CPU0_SA_DQS_DN<6>")
	)
	(segment
		(start 382.062736 -269.870428)
		(end 382.058418 -269.873222)
		(width 0.088646)
		(layer "In4.Cu")
		(net "M_F_CPU0_SA_DQS_DN<6>")
	)
	(segment
		(start 383.003298 -269.869666)
		(end 383.000504 -269.871444)
		(width 0.088646)
		(layer "In4.Cu")
		(net "M_F_CPU0_SA_DQS_DN<6>")
	)
	(segment
		(start 413.108394 -299.31614)
		(end 411.45206 -298.629832)
		(width 0.18288)
		(layer "In4.Cu")
		(net "M_F_CPU0_SA_DQS_DN<6>")
	)
	(segment
		(start 408.58948 -296.344594)
		(end 408.088338 -296.081196)
		(width 0.18288)
		(layer "In4.Cu")
		(net "M_F_CPU0_SA_DQS_DN<6>")
	)
	(segment
		(start 421.213788 -302.02632)
		(end 420.94912 -302.290988)
		(width 0.18288)
		(layer "In4.Cu")
		(net "M_F_CPU0_SA_DQS_DN<6>")
	)
	(segment
		(start 419.84676 -302.295306)
		(end 416.455352 -302.295306)
		(width 0.18288)
		(layer "In4.Cu")
		(net "M_F_CPU0_SA_DQS_DN<6>")
	)
	(segment
		(start 413.91332 -300.121066)
		(end 413.108394 -299.31614)
		(width 0.18288)
		(layer "In4.Cu")
		(net "M_F_CPU0_SA_DQS_DN<6>")
	)
	(segment
		(start 405.374602 -294.475154)
		(end 405.208994 -294.535098)
		(width 0.18288)
		(layer "In4.Cu")
		(net "M_F_CPU0_SA_DQS_DN<6>")
	)
	(segment
		(start 423.72407 -302.603916)
		(end 422.794684 -302.603916)
		(width 0.18288)
		(layer "In4.Cu")
		(net "M_F_CPU0_SA_DQS_DN<6>")
	)
	(segment
		(start 402.834856 -292.658292)
		(end 402.448522 -292.271958)
		(width 0.18288)
		(layer "In4.Cu")
		(net "M_F_CPU0_SA_DQS_DN<6>")
	)
	(segment
		(start 388.20979 -271.670272)
		(end 387.576568 -271.03705)
		(width 0.088646)
		(layer "In4.Cu")
		(net "M_F_CPU0_SA_DQS_DN<6>")
	)
	(segment
		(start 420.94912 -302.290988)
		(end 420.555928 -302.290988)
		(width 0.18288)
		(layer "In4.Cu")
		(net "M_F_CPU0_SA_DQS_DN<6>")
	)
	(segment
		(start 424.836082 -302.716692)
		(end 424.540934 -302.421544)
		(width 0.18288)
		(layer "In4.Cu")
		(net "M_F_CPU0_SA_DQS_DN<6>")
	)
	(segment
		(start 381.503174 -269.879318)
		(end 381.49276 -269.873222)
		(width 0.088646)
		(layer "In4.Cu")
		(net "M_F_CPU0_SA_DQS_DN<6>")
	)
	(segment
		(start 406.433528 -295.057576)
		(end 405.977344 -294.757602)
		(width 0.18288)
		(layer "In4.Cu")
		(net "M_F_CPU0_SA_DQS_DN<6>")
	)
	(segment
		(start 405.977344 -294.757602)
		(end 405.374602 -294.475154)
		(width 0.18288)
		(layer "In4.Cu")
		(net "M_F_CPU0_SA_DQS_DN<6>")
	)
	(segment
		(start 411.45206 -298.629832)
		(end 410.995368 -298.17314)
		(width 0.18288)
		(layer "In4.Cu")
		(net "M_F_CPU0_SA_DQS_DN<6>")
	)
	(segment
		(start 420.261796 -301.996856)
		(end 420.14521 -301.996856)
		(width 0.18288)
		(layer "In4.Cu")
		(net "M_F_CPU0_SA_DQS_DN<6>")
	)
	(segment
		(start 414.968182 -301.175928)
		(end 414.475676 -300.683422)
		(width 0.18288)
		(layer "In4.Cu")
		(net "M_F_CPU0_SA_DQS_DN<6>")
	)
	(segment
		(start 383.372614 -269.873222)
		(end 383.372614 -269.872968)
		(width 0.088646)
		(layer "In4.Cu")
		(net "M_F_CPU0_SA_DQS_DN<6>")
	)
	(segment
		(start 387.370066 -271.03705)
		(end 387.259576 -271.00022)
		(width 0.088646)
		(layer "In4.Cu")
		(net "M_F_CPU0_SA_DQS_DN<6>")
	)
	(segment
		(start 422.794684 -302.603916)
		(end 421.400478 -302.02632)
		(width 0.18288)
		(layer "In4.Cu")
		(net "M_F_CPU0_SA_DQS_DN<6>")
	)
	(segment
		(start 424.165268 -302.421544)
		(end 423.72407 -302.603916)
		(width 0.18288)
		(layer "In4.Cu")
		(net "M_F_CPU0_SA_DQS_DN<6>")
	)
	(segment
		(start 410.433012 -297.610784)
		(end 409.807156 -296.984928)
		(width 0.18288)
		(layer "In4.Cu")
		(net "M_F_CPU0_SA_DQS_DN<6>")
	)
	(segment
		(start 414.475676 -300.683422)
		(end 414.299654 -300.683422)
		(width 0.18288)
		(layer "In4.Cu")
		(net "M_F_CPU0_SA_DQS_DN<6>")
	)
	(segment
		(start 385.266946 -269.881858)
		(end 385.252214 -269.873222)
		(width 0.088646)
		(layer "In4.Cu")
		(net "M_F_CPU0_SA_DQS_DN<6>")
	)
	(segment
		(start 420.555928 -302.290988)
		(end 420.261796 -301.996856)
		(width 0.18288)
		(layer "In4.Cu")
		(net "M_F_CPU0_SA_DQS_DN<6>")
	)
	(segment
		(start 386.716524 -270.724884)
		(end 386.716524 -270.725138)
		(width 0.088646)
		(layer "In4.Cu")
		(net "M_F_CPU0_SA_DQS_DN<6>")
	)
	(segment
		(start 388.2263 -271.771618)
		(end 388.20979 -271.755108)
		(width 0.088646)
		(layer "In4.Cu")
		(net "M_F_CPU0_SA_DQS_DN<6>")
	)
	(segment
		(start 403.783292 -293.606728)
		(end 403.396958 -293.220394)
		(width 0.18288)
		(layer "In4.Cu")
		(net "M_F_CPU0_SA_DQS_DN<6>")
	)
	(segment
		(start 387.576568 -271.03705)
		(end 387.370066 -271.03705)
		(width 0.088646)
		(layer "In4.Cu")
		(net "M_F_CPU0_SA_DQS_DN<6>")
	)
	(segment
		(start 381.118364 -269.873222)
		(end 381.046736 -269.914624)
		(width 0.088646)
		(layer "In4.Cu")
		(net "M_F_CPU0_SA_DQS_DN<6>")
	)
	(segment
		(start 420.14521 -301.996856)
		(end 419.84676 -302.295306)
		(width 0.18288)
		(layer "In4.Cu")
		(net "M_F_CPU0_SA_DQS_DN<6>")
	)
	(segment
		(start 410.433012 -297.786806)
		(end 410.433012 -297.610784)
		(width 0.18288)
		(layer "In4.Cu")
		(net "M_F_CPU0_SA_DQS_DN<6>")
	)
	(segment
		(start 410.819346 -298.17314)
		(end 410.433012 -297.786806)
		(width 0.18288)
		(layer "In4.Cu")
		(net "M_F_CPU0_SA_DQS_DN<6>")
	)
	(segment
		(start 421.400478 -302.02632)
		(end 421.213788 -302.02632)
		(width 0.18288)
		(layer "In4.Cu")
		(net "M_F_CPU0_SA_DQS_DN<6>")
	)
	(segment
		(start 396.439898 -279.18918)
		(end 391.177018 -273.926046)
		(width 0.18288)
		(layer "In4.Cu")
		(net "M_F_CPU0_SA_DQS_DN<6>")
	)
	(segment
		(start 390.188196 -273.733514)
		(end 388.2263 -271.771618)
		(width 0.18288)
		(layer "In4.Cu")
		(net "M_F_CPU0_SA_DQS_DN<6>")
	)
	(segment
		(start 391.177018 -273.926046)
		(end 390.984486 -273.733514)
		(width 0.18288)
		(layer "In4.Cu")
		(net "M_F_CPU0_SA_DQS_DN<6>")
	)
	(segment
		(start 415.59607 -301.436278)
		(end 414.968182 -301.175928)
		(width 0.18288)
		(layer "In4.Cu")
		(net "M_F_CPU0_SA_DQS_DN<6>")
	)
	(arc
		(start 383.938018 -269.873222)
		(mid 383.663789 -269.949147)
		(end 383.387346 -269.881858)
		(width 0.088646)
		(layer "In4.Cu")
		(net "M_F_CPU0_SA_DQS_DN<6>")
	)
	(arc
		(start 386.66166 -270.687038)
		(mid 386.458837 -270.486807)
		(end 386.379466 -270.213074)
		(width 0.088646)
		(layer "In4.Cu")
		(net "M_F_CPU0_SA_DQS_DN<6>")
	)
	(arc
		(start 386.716524 -270.725138)
		(mid 386.689941 -270.704866)
		(end 386.66166 -270.687038)
		(width 0.088646)
		(layer "In4.Cu")
		(net "M_F_CPU0_SA_DQS_DN<6>")
	)
	(arc
		(start 382.058418 -269.873222)
		(mid 381.781605 -269.949058)
		(end 381.503174 -269.879318)
		(width 0.088646)
		(layer "In4.Cu")
		(net "M_F_CPU0_SA_DQS_DN<6>")
	)
	(arc
		(start 383.372614 -269.872968)
		(mid 383.188406 -269.822746)
		(end 383.003298 -269.869666)
		(width 0.088646)
		(layer "In4.Cu")
		(net "M_F_CPU0_SA_DQS_DN<6>")
	)
	(arc
		(start 385.817618 -269.873222)
		(mid 385.543389 -269.949147)
		(end 385.266946 -269.881858)
		(width 0.088646)
		(layer "In4.Cu")
		(net "M_F_CPU0_SA_DQS_DN<6>")
	)
	(arc
		(start 380.440438 -269.99057)
		(mid 380.397911 -270.007183)
		(end 380.377954 -270.048228)
		(width 0.088646)
		(layer "In4.Cu")
		(net "M_F_CPU0_SA_DQS_DN<6>")
	)
	(arc
		(start 382.990598 -269.877286)
		(mid 382.711137 -269.948723)
		(end 382.432814 -269.872968)
		(width 0.088646)
		(layer "In4.Cu")
		(net "M_F_CPU0_SA_DQS_DN<6>")
	)
	(arc
		(start 381.49276 -269.873222)
		(mid 381.305562 -269.823079)
		(end 381.118364 -269.873222)
		(width 0.088646)
		(layer "In4.Cu")
		(net "M_F_CPU0_SA_DQS_DN<6>")
	)
	(arc
		(start 382.432814 -269.872968)
		(mid 382.24812 -269.822867)
		(end 382.062736 -269.870428)
		(width 0.088646)
		(layer "In4.Cu")
		(net "M_F_CPU0_SA_DQS_DN<6>")
	)
	(arc
		(start 386.739638 -270.745966)
		(mid 386.7283 -270.735185)
		(end 386.716524 -270.724884)
		(width 0.088646)
		(layer "In4.Cu")
		(net "M_F_CPU0_SA_DQS_DN<6>")
	)
	(arc
		(start 384.877818 -269.873222)
		(mid 384.603589 -269.949147)
		(end 384.327146 -269.881858)
		(width 0.088646)
		(layer "In4.Cu")
		(net "M_F_CPU0_SA_DQS_DN<6>")
	)
	(arc
		(start 385.252214 -269.873222)
		(mid 385.065016 -269.823079)
		(end 384.877818 -269.873222)
		(width 0.088646)
		(layer "In4.Cu")
		(net "M_F_CPU0_SA_DQS_DN<6>")
	)
	(arc
		(start 386.379466 -270.19758)
		(mid 386.192167 -269.873139)
		(end 385.817618 -269.873222)
		(width 0.088646)
		(layer "In4.Cu")
		(net "M_F_CPU0_SA_DQS_DN<6>")
	)
	(arc
		(start 384.312414 -269.873222)
		(mid 384.125216 -269.823079)
		(end 383.938018 -269.873222)
		(width 0.088646)
		(layer "In4.Cu")
		(net "M_F_CPU0_SA_DQS_DN<6>")
	)
	(arc
		(start 381.046736 -269.914624)
		(mid 380.909616 -269.97128)
		(end 380.76251 -269.99057)
		(width 0.088646)
		(layer "In4.Cu")
		(net "M_F_CPU0_SA_DQS_DN<6>")
	)
	(segment
		(start 427.226222 -311.795414)
		(end 427.651164 -311.370472)
		(width 0.20066)
		(layer "F.Cu")
		(net "M_F_CPU0_SA_DQS_DN<5>")
	)
	(segment
		(start 431.489612 -311.366916)
		(end 431.935128 -311.812432)
		(width 0.20066)
		(layer "F.Cu")
		(net "M_F_CPU0_SA_DQS_DN<5>")
	)
	(segment
		(start 430.384204 -311.641744)
		(end 430.395126 -311.652666)
		(width 0.1016)
		(layer "F.Cu")
		(net "M_F_CPU0_SA_DQS_DN<5>")
	)
	(segment
		(start 427.651164 -311.370472)
		(end 427.773592 -311.370472)
		(width 0.20066)
		(layer "F.Cu")
		(net "M_F_CPU0_SA_DQS_DN<5>")
	)
	(segment
		(start 425.940982 -312.066686)
		(end 426.471588 -312.066686)
		(width 0.20066)
		(layer "F.Cu")
		(net "M_F_CPU0_SA_DQS_DN<5>")
	)
	(segment
		(start 432.726846 -311.812432)
		(end 432.9811 -312.066686)
		(width 0.20066)
		(layer "F.Cu")
		(net "M_F_CPU0_SA_DQS_DN<5>")
	)
	(segment
		(start 428.05096 -311.64784)
		(end 428.363126 -311.64784)
		(width 0.20066)
		(layer "F.Cu")
		(net "M_F_CPU0_SA_DQS_DN<5>")
	)
	(segment
		(start 426.74286 -311.795414)
		(end 427.226222 -311.795414)
		(width 0.20066)
		(layer "F.Cu")
		(net "M_F_CPU0_SA_DQS_DN<5>")
	)
	(segment
		(start 428.363126 -311.64784)
		(end 428.367952 -311.64784)
		(width 0.101854)
		(layer "F.Cu")
		(net "M_F_CPU0_SA_DQS_DN<5>")
	)
	(segment
		(start 431.935128 -311.812432)
		(end 432.726846 -311.812432)
		(width 0.20066)
		(layer "F.Cu")
		(net "M_F_CPU0_SA_DQS_DN<5>")
	)
	(segment
		(start 428.374048 -311.641744)
		(end 430.384204 -311.641744)
		(width 0.1016)
		(layer "F.Cu")
		(net "M_F_CPU0_SA_DQS_DN<5>")
	)
	(segment
		(start 383.655062 -277.522178)
		(end 383.654808 -277.522432)
		(width 0.20066)
		(layer "F.Cu")
		(net "M_F_CPU0_SA_DQS_DN<5>")
	)
	(segment
		(start 424.836082 -312.066686)
		(end 425.940982 -312.066686)
		(width 0.20066)
		(layer "F.Cu")
		(net "M_F_CPU0_SA_DQS_DN<5>")
	)
	(segment
		(start 427.773592 -311.370472)
		(end 428.05096 -311.64784)
		(width 0.20066)
		(layer "F.Cu")
		(net "M_F_CPU0_SA_DQS_DN<5>")
	)
	(segment
		(start 428.367952 -311.64784)
		(end 428.374048 -311.641744)
		(width 0.1016)
		(layer "F.Cu")
		(net "M_F_CPU0_SA_DQS_DN<5>")
	)
	(segment
		(start 430.713896 -311.652666)
		(end 430.999646 -311.366916)
		(width 0.20066)
		(layer "F.Cu")
		(net "M_F_CPU0_SA_DQS_DN<5>")
	)
	(segment
		(start 432.9811 -312.066686)
		(end 433.484782 -312.066686)
		(width 0.20066)
		(layer "F.Cu")
		(net "M_F_CPU0_SA_DQS_DN<5>")
	)
	(segment
		(start 383.655062 -276.986492)
		(end 383.655062 -277.522178)
		(width 0.20066)
		(layer "F.Cu")
		(net "M_F_CPU0_SA_DQS_DN<5>")
	)
	(segment
		(start 430.999646 -311.366916)
		(end 431.489612 -311.366916)
		(width 0.20066)
		(layer "F.Cu")
		(net "M_F_CPU0_SA_DQS_DN<5>")
	)
	(segment
		(start 430.395126 -311.652666)
		(end 430.713896 -311.652666)
		(width 0.20066)
		(layer "F.Cu")
		(net "M_F_CPU0_SA_DQS_DN<5>")
	)
	(segment
		(start 426.471588 -312.066686)
		(end 426.74286 -311.795414)
		(width 0.20066)
		(layer "F.Cu")
		(net "M_F_CPU0_SA_DQS_DN<5>")
	)
	(segment
		(start 408.106626 -311.667398)
		(end 407.674572 -311.667398)
		(width 0.18288)
		(layer "In2.Cu")
		(net "M_F_CPU0_SA_DQS_DN<5>")
	)
	(segment
		(start 411.562042 -310.78551)
		(end 411.496002 -310.71947)
		(width 0.18288)
		(layer "In2.Cu")
		(net "M_F_CPU0_SA_DQS_DN<5>")
	)
	(segment
		(start 422.786048 -311.897522)
		(end 422.786048 -311.881266)
		(width 0.16002)
		(layer "In2.Cu")
		(net "M_F_CPU0_SA_DQS_DN<5>")
	)
	(segment
		(start 391.666222 -283.896562)
		(end 390.26592 -282.49626)
		(width 0.18288)
		(layer "In2.Cu")
		(net "M_F_CPU0_SA_DQS_DN<5>")
	)
	(segment
		(start 420.96055 -311.641998)
		(end 420.835836 -311.641998)
		(width 0.18288)
		(layer "In2.Cu")
		(net "M_F_CPU0_SA_DQS_DN<5>")
	)
	(segment
		(start 407.674572 -311.667398)
		(end 407.371296 -311.364122)
		(width 0.18288)
		(layer "In2.Cu")
		(net "M_F_CPU0_SA_DQS_DN<5>")
	)
	(segment
		(start 422.270936 -311.38241)
		(end 421.21836 -311.38241)
		(width 0.18288)
		(layer "In2.Cu")
		(net "M_F_CPU0_SA_DQS_DN<5>")
	)
	(segment
		(start 417.644072 -310.791098)
		(end 417.40709 -311.02808)
		(width 0.18288)
		(layer "In2.Cu")
		(net "M_F_CPU0_SA_DQS_DN<5>")
	)
	(segment
		(start 383.890266 -277.546308)
		(end 383.86639 -277.522432)
		(width 0.088646)
		(layer "In2.Cu")
		(net "M_F_CPU0_SA_DQS_DN<5>")
	)
	(segment
		(start 398.507204 -305.797966)
		(end 398.507204 -305.621944)
		(width 0.18288)
		(layer "In2.Cu")
		(net "M_F_CPU0_SA_DQS_DN<5>")
	)
	(segment
		(start 403.655276 -310.946038)
		(end 403.267164 -310.557926)
		(width 0.18288)
		(layer "In2.Cu")
		(net "M_F_CPU0_SA_DQS_DN<5>")
	)
	(segment
		(start 392.528552 -291.790882)
		(end 391.666222 -289.70859)
		(width 0.18288)
		(layer "In2.Cu")
		(net "M_F_CPU0_SA_DQS_DN<5>")
	)
	(segment
		(start 420.617142 -311.641998)
		(end 420.476426 -311.641998)
		(width 0.18288)
		(layer "In2.Cu")
		(net "M_F_CPU0_SA_DQS_DN<5>")
	)
	(segment
		(start 387.518402 -277.961344)
		(end 386.944362 -277.961344)
		(width 0.088646)
		(layer "In2.Cu")
		(net "M_F_CPU0_SA_DQS_DN<5>")
	)
	(segment
		(start 387.886702 -278.329644)
		(end 387.518402 -277.961344)
		(width 0.088646)
		(layer "In2.Cu")
		(net "M_F_CPU0_SA_DQS_DN<5>")
	)
	(segment
		(start 396.585694 -302.603154)
		(end 396.710154 -302.478694)
		(width 0.18288)
		(layer "In2.Cu")
		(net "M_F_CPU0_SA_DQS_DN<5>")
	)
	(segment
		(start 420.476426 -311.641998)
		(end 420.212012 -311.377584)
		(width 0.18288)
		(layer "In2.Cu")
		(net "M_F_CPU0_SA_DQS_DN<5>")
	)
	(segment
		(start 415.78149 -311.655206)
		(end 415.42716 -311.655206)
		(width 0.18288)
		(layer "In2.Cu")
		(net "M_F_CPU0_SA_DQS_DN<5>")
	)
	(segment
		(start 399.847308 -307.13807)
		(end 399.459196 -306.749958)
		(width 0.18288)
		(layer "In2.Cu")
		(net "M_F_CPU0_SA_DQS_DN<5>")
	)
	(segment
		(start 396.585694 -303.151794)
		(end 396.585694 -302.603154)
		(width 0.18288)
		(layer "In2.Cu")
		(net "M_F_CPU0_SA_DQS_DN<5>")
	)
	(segment
		(start 412.134558 -311.358026)
		(end 411.818836 -311.042304)
		(width 0.18288)
		(layer "In2.Cu")
		(net "M_F_CPU0_SA_DQS_DN<5>")
	)
	(segment
		(start 416.558984 -311.379362)
		(end 416.057334 -311.379362)
		(width 0.18288)
		(layer "In2.Cu")
		(net "M_F_CPU0_SA_DQS_DN<5>")
	)
	(segment
		(start 409.820872 -311.090056)
		(end 409.194 -311.349644)
		(width 0.18288)
		(layer "In2.Cu")
		(net "M_F_CPU0_SA_DQS_DN<5>")
	)
	(segment
		(start 423.007536 -312.11901)
		(end 422.814242 -311.925716)
		(width 0.18288)
		(layer "In2.Cu")
		(net "M_F_CPU0_SA_DQS_DN<5>")
	)
	(segment
		(start 411.818836 -311.042304)
		(end 411.790642 -311.01411)
		(width 0.16002)
		(layer "In2.Cu")
		(net "M_F_CPU0_SA_DQS_DN<5>")
	)
	(segment
		(start 411.496002 -310.71947)
		(end 410.191458 -310.71947)
		(width 0.18288)
		(layer "In2.Cu")
		(net "M_F_CPU0_SA_DQS_DN<5>")
	)
	(segment
		(start 390.26592 -282.49626)
		(end 389.06069 -279.588722)
		(width 0.18288)
		(layer "In2.Cu")
		(net "M_F_CPU0_SA_DQS_DN<5>")
	)
	(segment
		(start 420.96055 -311.64022)
		(end 420.96055 -311.641998)
		(width 0.18288)
		(layer "In2.Cu")
		(net "M_F_CPU0_SA_DQS_DN<5>")
	)
	(segment
		(start 387.886702 -278.41448)
		(end 387.886702 -278.329644)
		(width 0.088646)
		(layer "In2.Cu")
		(net "M_F_CPU0_SA_DQS_DN<5>")
	)
	(segment
		(start 391.666222 -289.70859)
		(end 391.666222 -283.896562)
		(width 0.18288)
		(layer "In2.Cu")
		(net "M_F_CPU0_SA_DQS_DN<5>")
	)
	(segment
		(start 396.585694 -300.459394)
		(end 396.585694 -299.910754)
		(width 0.18288)
		(layer "In2.Cu")
		(net "M_F_CPU0_SA_DQS_DN<5>")
	)
	(segment
		(start 420.835836 -311.641998)
		(end 420.617142 -311.641998)
		(width 0.16002)
		(layer "In2.Cu")
		(net "M_F_CPU0_SA_DQS_DN<5>")
	)
	(segment
		(start 422.786048 -311.881266)
		(end 422.586404 -311.681622)
		(width 0.16002)
		(layer "In2.Cu")
		(net "M_F_CPU0_SA_DQS_DN<5>")
	)
	(segment
		(start 384.219704 -277.958804)
		(end 384.194558 -277.927308)
		(width 0.088646)
		(layer "In2.Cu")
		(net "M_F_CPU0_SA_DQS_DN<5>")
	)
	(segment
		(start 401.927314 -309.042054)
		(end 401.751292 -309.042054)
		(width 0.18288)
		(layer "In2.Cu")
		(net "M_F_CPU0_SA_DQS_DN<5>")
	)
	(segment
		(start 396.710154 -301.930054)
		(end 396.585694 -301.805594)
		(width 0.18288)
		(layer "In2.Cu")
		(net "M_F_CPU0_SA_DQS_DN<5>")
	)
	(segment
		(start 403.267164 -310.381904)
		(end 402.879306 -309.994046)
		(width 0.18288)
		(layer "In2.Cu")
		(net "M_F_CPU0_SA_DQS_DN<5>")
	)
	(segment
		(start 417.40709 -311.02808)
		(end 416.558984 -311.379362)
		(width 0.18288)
		(layer "In2.Cu")
		(net "M_F_CPU0_SA_DQS_DN<5>")
	)
	(segment
		(start 404.219156 -311.333896)
		(end 403.831298 -310.946038)
		(width 0.18288)
		(layer "In2.Cu")
		(net "M_F_CPU0_SA_DQS_DN<5>")
	)
	(segment
		(start 422.570148 -311.681622)
		(end 422.541954 -311.653428)
		(width 0.16002)
		(layer "In2.Cu")
		(net "M_F_CPU0_SA_DQS_DN<5>")
	)
	(segment
		(start 399.071338 -306.186078)
		(end 398.895316 -306.186078)
		(width 0.18288)
		(layer "In2.Cu")
		(net "M_F_CPU0_SA_DQS_DN<5>")
	)
	(segment
		(start 400.7993 -308.090062)
		(end 400.411188 -307.70195)
		(width 0.18288)
		(layer "In2.Cu")
		(net "M_F_CPU0_SA_DQS_DN<5>")
	)
	(segment
		(start 411.790642 -311.01411)
		(end 411.790642 -310.998362)
		(width 0.16002)
		(layer "In2.Cu")
		(net "M_F_CPU0_SA_DQS_DN<5>")
	)
	(segment
		(start 401.751292 -309.042054)
		(end 401.36318 -308.653942)
		(width 0.18288)
		(layer "In2.Cu")
		(net "M_F_CPU0_SA_DQS_DN<5>")
	)
	(segment
		(start 384.31216 -278.012144)
		(end 384.219704 -277.958804)
		(width 0.088646)
		(layer "In2.Cu")
		(net "M_F_CPU0_SA_DQS_DN<5>")
	)
	(segment
		(start 398.119346 -305.234086)
		(end 397.943324 -305.234086)
		(width 0.18288)
		(layer "In2.Cu")
		(net "M_F_CPU0_SA_DQS_DN<5>")
	)
	(segment
		(start 384.194558 -277.927308)
		(end 383.890266 -277.546308)
		(width 0.088646)
		(layer "In2.Cu")
		(net "M_F_CPU0_SA_DQS_DN<5>")
	)
	(segment
		(start 422.814242 -311.925716)
		(end 422.786048 -311.897522)
		(width 0.16002)
		(layer "In2.Cu")
		(net "M_F_CPU0_SA_DQS_DN<5>")
	)
	(segment
		(start 399.459196 -306.749958)
		(end 399.459196 -306.573936)
		(width 0.18288)
		(layer "In2.Cu")
		(net "M_F_CPU0_SA_DQS_DN<5>")
	)
	(segment
		(start 419.7096 -311.377584)
		(end 419.123114 -310.791098)
		(width 0.18288)
		(layer "In2.Cu")
		(net "M_F_CPU0_SA_DQS_DN<5>")
	)
	(segment
		(start 396.710154 -300.583854)
		(end 396.585694 -300.459394)
		(width 0.18288)
		(layer "In2.Cu")
		(net "M_F_CPU0_SA_DQS_DN<5>")
	)
	(segment
		(start 415.42716 -311.655206)
		(end 415.115502 -311.343548)
		(width 0.18288)
		(layer "In2.Cu")
		(net "M_F_CPU0_SA_DQS_DN<5>")
	)
	(segment
		(start 397.555212 -304.845974)
		(end 397.555212 -304.669952)
		(width 0.18288)
		(layer "In2.Cu")
		(net "M_F_CPU0_SA_DQS_DN<5>")
	)
	(segment
		(start 402.315172 -309.605934)
		(end 402.315172 -309.429912)
		(width 0.18288)
		(layer "In2.Cu")
		(net "M_F_CPU0_SA_DQS_DN<5>")
	)
	(segment
		(start 422.586404 -311.681622)
		(end 422.570148 -311.681622)
		(width 0.16002)
		(layer "In2.Cu")
		(net "M_F_CPU0_SA_DQS_DN<5>")
	)
	(segment
		(start 396.585694 -301.256954)
		(end 396.710154 -301.132494)
		(width 0.18288)
		(layer "In2.Cu")
		(net "M_F_CPU0_SA_DQS_DN<5>")
	)
	(segment
		(start 411.790642 -310.998362)
		(end 411.605984 -310.813704)
		(width 0.16002)
		(layer "In2.Cu")
		(net "M_F_CPU0_SA_DQS_DN<5>")
	)
	(segment
		(start 402.315172 -309.429912)
		(end 401.927314 -309.042054)
		(width 0.18288)
		(layer "In2.Cu")
		(net "M_F_CPU0_SA_DQS_DN<5>")
	)
	(segment
		(start 401.36318 -308.653942)
		(end 401.36318 -308.47792)
		(width 0.18288)
		(layer "In2.Cu")
		(net "M_F_CPU0_SA_DQS_DN<5>")
	)
	(segment
		(start 400.411188 -307.525928)
		(end 400.02333 -307.13807)
		(width 0.18288)
		(layer "In2.Cu")
		(net "M_F_CPU0_SA_DQS_DN<5>")
	)
	(segment
		(start 405.455374 -311.644538)
		(end 405.144732 -311.333896)
		(width 0.18288)
		(layer "In2.Cu")
		(net "M_F_CPU0_SA_DQS_DN<5>")
	)
	(segment
		(start 403.831298 -310.946038)
		(end 403.655276 -310.946038)
		(width 0.18288)
		(layer "In2.Cu")
		(net "M_F_CPU0_SA_DQS_DN<5>")
	)
	(segment
		(start 400.411188 -307.70195)
		(end 400.411188 -307.525928)
		(width 0.18288)
		(layer "In2.Cu")
		(net "M_F_CPU0_SA_DQS_DN<5>")
	)
	(segment
		(start 413.51327 -311.343548)
		(end 413.201612 -311.655206)
		(width 0.18288)
		(layer "In2.Cu")
		(net "M_F_CPU0_SA_DQS_DN<5>")
	)
	(segment
		(start 419.123114 -310.791098)
		(end 417.644072 -310.791098)
		(width 0.18288)
		(layer "In2.Cu")
		(net "M_F_CPU0_SA_DQS_DN<5>")
	)
	(segment
		(start 407.371296 -311.364122)
		(end 406.119838 -311.364122)
		(width 0.18288)
		(layer "In2.Cu")
		(net "M_F_CPU0_SA_DQS_DN<5>")
	)
	(segment
		(start 397.943324 -305.234086)
		(end 397.555212 -304.845974)
		(width 0.18288)
		(layer "In2.Cu")
		(net "M_F_CPU0_SA_DQS_DN<5>")
	)
	(segment
		(start 408.42438 -311.349644)
		(end 408.106626 -311.667398)
		(width 0.18288)
		(layer "In2.Cu")
		(net "M_F_CPU0_SA_DQS_DN<5>")
	)
	(segment
		(start 400.975322 -308.090062)
		(end 400.7993 -308.090062)
		(width 0.18288)
		(layer "In2.Cu")
		(net "M_F_CPU0_SA_DQS_DN<5>")
	)
	(segment
		(start 403.267164 -310.557926)
		(end 403.267164 -310.381904)
		(width 0.18288)
		(layer "In2.Cu")
		(net "M_F_CPU0_SA_DQS_DN<5>")
	)
	(segment
		(start 424.586146 -311.81675)
		(end 424.328844 -311.81675)
		(width 0.18288)
		(layer "In2.Cu")
		(net "M_F_CPU0_SA_DQS_DN<5>")
	)
	(segment
		(start 397.555212 -304.669952)
		(end 396.710154 -303.824894)
		(width 0.18288)
		(layer "In2.Cu")
		(net "M_F_CPU0_SA_DQS_DN<5>")
	)
	(segment
		(start 396.710154 -302.478694)
		(end 396.710154 -301.930054)
		(width 0.18288)
		(layer "In2.Cu")
		(net "M_F_CPU0_SA_DQS_DN<5>")
	)
	(segment
		(start 412.550102 -311.358026)
		(end 412.134558 -311.358026)
		(width 0.18288)
		(layer "In2.Cu")
		(net "M_F_CPU0_SA_DQS_DN<5>")
	)
	(segment
		(start 415.115502 -311.343548)
		(end 413.51327 -311.343548)
		(width 0.18288)
		(layer "In2.Cu")
		(net "M_F_CPU0_SA_DQS_DN<5>")
	)
	(segment
		(start 422.541954 -311.653428)
		(end 422.270936 -311.38241)
		(width 0.18288)
		(layer "In2.Cu")
		(net "M_F_CPU0_SA_DQS_DN<5>")
	)
	(segment
		(start 405.839422 -311.644538)
		(end 405.455374 -311.644538)
		(width 0.18288)
		(layer "In2.Cu")
		(net "M_F_CPU0_SA_DQS_DN<5>")
	)
	(segment
		(start 400.02333 -307.13807)
		(end 399.847308 -307.13807)
		(width 0.18288)
		(layer "In2.Cu")
		(net "M_F_CPU0_SA_DQS_DN<5>")
	)
	(segment
		(start 396.585694 -299.910754)
		(end 396.710154 -299.786294)
		(width 0.18288)
		(layer "In2.Cu")
		(net "M_F_CPU0_SA_DQS_DN<5>")
	)
	(segment
		(start 420.212012 -311.377584)
		(end 419.7096 -311.377584)
		(width 0.18288)
		(layer "In2.Cu")
		(net "M_F_CPU0_SA_DQS_DN<5>")
	)
	(segment
		(start 402.703284 -309.994046)
		(end 402.315172 -309.605934)
		(width 0.18288)
		(layer "In2.Cu")
		(net "M_F_CPU0_SA_DQS_DN<5>")
	)
	(segment
		(start 424.328844 -311.81675)
		(end 423.599356 -312.11901)
		(width 0.18288)
		(layer "In2.Cu")
		(net "M_F_CPU0_SA_DQS_DN<5>")
	)
	(segment
		(start 424.836082 -312.066686)
		(end 424.586146 -311.81675)
		(width 0.18288)
		(layer "In2.Cu")
		(net "M_F_CPU0_SA_DQS_DN<5>")
	)
	(segment
		(start 396.710154 -298.226734)
		(end 395.29385 -294.55618)
		(width 0.18288)
		(layer "In2.Cu")
		(net "M_F_CPU0_SA_DQS_DN<5>")
	)
	(segment
		(start 395.29385 -294.55618)
		(end 392.528552 -291.790882)
		(width 0.18288)
		(layer "In2.Cu")
		(net "M_F_CPU0_SA_DQS_DN<5>")
	)
	(segment
		(start 396.585694 -301.805594)
		(end 396.585694 -301.256954)
		(width 0.18288)
		(layer "In2.Cu")
		(net "M_F_CPU0_SA_DQS_DN<5>")
	)
	(segment
		(start 401.36318 -308.47792)
		(end 400.975322 -308.090062)
		(width 0.18288)
		(layer "In2.Cu")
		(net "M_F_CPU0_SA_DQS_DN<5>")
	)
	(segment
		(start 409.194 -311.349644)
		(end 408.42438 -311.349644)
		(width 0.18288)
		(layer "In2.Cu")
		(net "M_F_CPU0_SA_DQS_DN<5>")
	)
	(segment
		(start 406.119838 -311.364122)
		(end 405.839422 -311.644538)
		(width 0.18288)
		(layer "In2.Cu")
		(net "M_F_CPU0_SA_DQS_DN<5>")
	)
	(segment
		(start 411.590236 -310.813704)
		(end 411.562042 -310.78551)
		(width 0.16002)
		(layer "In2.Cu")
		(net "M_F_CPU0_SA_DQS_DN<5>")
	)
	(segment
		(start 396.710154 -299.786294)
		(end 396.710154 -298.226734)
		(width 0.18288)
		(layer "In2.Cu")
		(net "M_F_CPU0_SA_DQS_DN<5>")
	)
	(segment
		(start 411.605984 -310.813704)
		(end 411.590236 -310.813704)
		(width 0.16002)
		(layer "In2.Cu")
		(net "M_F_CPU0_SA_DQS_DN<5>")
	)
	(segment
		(start 423.599356 -312.11901)
		(end 423.007536 -312.11901)
		(width 0.18288)
		(layer "In2.Cu")
		(net "M_F_CPU0_SA_DQS_DN<5>")
	)
	(segment
		(start 412.847282 -311.655206)
		(end 412.550102 -311.358026)
		(width 0.18288)
		(layer "In2.Cu")
		(net "M_F_CPU0_SA_DQS_DN<5>")
	)
	(segment
		(start 405.144732 -311.333896)
		(end 404.219156 -311.333896)
		(width 0.18288)
		(layer "In2.Cu")
		(net "M_F_CPU0_SA_DQS_DN<5>")
	)
	(segment
		(start 396.710154 -301.132494)
		(end 396.710154 -300.583854)
		(width 0.18288)
		(layer "In2.Cu")
		(net "M_F_CPU0_SA_DQS_DN<5>")
	)
	(segment
		(start 398.507204 -305.621944)
		(end 398.119346 -305.234086)
		(width 0.18288)
		(layer "In2.Cu")
		(net "M_F_CPU0_SA_DQS_DN<5>")
	)
	(segment
		(start 383.86639 -277.522432)
		(end 383.654808 -277.522432)
		(width 0.088646)
		(layer "In2.Cu")
		(net "M_F_CPU0_SA_DQS_DN<5>")
	)
	(segment
		(start 396.710154 -303.824894)
		(end 396.710154 -303.276254)
		(width 0.18288)
		(layer "In2.Cu")
		(net "M_F_CPU0_SA_DQS_DN<5>")
	)
	(segment
		(start 396.710154 -303.276254)
		(end 396.585694 -303.151794)
		(width 0.18288)
		(layer "In2.Cu")
		(net "M_F_CPU0_SA_DQS_DN<5>")
	)
	(segment
		(start 421.21836 -311.38241)
		(end 420.96055 -311.64022)
		(width 0.18288)
		(layer "In2.Cu")
		(net "M_F_CPU0_SA_DQS_DN<5>")
	)
	(segment
		(start 416.057334 -311.379362)
		(end 415.78149 -311.655206)
		(width 0.18288)
		(layer "In2.Cu")
		(net "M_F_CPU0_SA_DQS_DN<5>")
	)
	(segment
		(start 413.201612 -311.655206)
		(end 412.847282 -311.655206)
		(width 0.18288)
		(layer "In2.Cu")
		(net "M_F_CPU0_SA_DQS_DN<5>")
	)
	(segment
		(start 399.459196 -306.573936)
		(end 399.071338 -306.186078)
		(width 0.18288)
		(layer "In2.Cu")
		(net "M_F_CPU0_SA_DQS_DN<5>")
	)
	(segment
		(start 389.06069 -279.588722)
		(end 387.886702 -278.41448)
		(width 0.18288)
		(layer "In2.Cu")
		(net "M_F_CPU0_SA_DQS_DN<5>")
	)
	(segment
		(start 402.879306 -309.994046)
		(end 402.703284 -309.994046)
		(width 0.18288)
		(layer "In2.Cu")
		(net "M_F_CPU0_SA_DQS_DN<5>")
	)
	(segment
		(start 410.191458 -310.71947)
		(end 409.820872 -311.090056)
		(width 0.18288)
		(layer "In2.Cu")
		(net "M_F_CPU0_SA_DQS_DN<5>")
	)
	(segment
		(start 398.895316 -306.186078)
		(end 398.507204 -305.797966)
		(width 0.18288)
		(layer "In2.Cu")
		(net "M_F_CPU0_SA_DQS_DN<5>")
	)
	(arc
		(start 385.817364 -278.012144)
		(mid 385.534662 -278.087886)
		(end 385.25196 -278.012144)
		(width 0.088646)
		(layer "In2.Cu")
		(net "M_F_CPU0_SA_DQS_DN<5>")
	)
	(arc
		(start 386.757164 -278.012144)
		(mid 386.474462 -278.087886)
		(end 386.19176 -278.012144)
		(width 0.088646)
		(layer "In2.Cu")
		(net "M_F_CPU0_SA_DQS_DN<5>")
	)
	(arc
		(start 384.877564 -278.012144)
		(mid 384.594862 -278.087886)
		(end 384.31216 -278.012144)
		(width 0.088646)
		(layer "In2.Cu")
		(net "M_F_CPU0_SA_DQS_DN<5>")
	)
	(arc
		(start 386.944362 -277.961344)
		(mid 386.847423 -277.974434)
		(end 386.757164 -278.012144)
		(width 0.088646)
		(layer "In2.Cu")
		(net "M_F_CPU0_SA_DQS_DN<5>")
	)
	(arc
		(start 386.19176 -278.012144)
		(mid 386.004562 -277.962001)
		(end 385.817364 -278.012144)
		(width 0.088646)
		(layer "In2.Cu")
		(net "M_F_CPU0_SA_DQS_DN<5>")
	)
	(arc
		(start 385.25196 -278.012144)
		(mid 385.064762 -277.962001)
		(end 384.877564 -278.012144)
		(width 0.088646)
		(layer "In2.Cu")
		(net "M_F_CPU0_SA_DQS_DN<5>")
	)
	(segment
		(start 426.951394 -275.086318)
		(end 427.275498 -275.086318)
		(width 0.20066)
		(layer "F.Cu")
		(net "M_F_CPU0_SA_DQS_DN<4>")
	)
	(segment
		(start 424.762168 -275.091652)
		(end 424.766486 -275.091652)
		(width 0.101854)
		(layer "F.Cu")
		(net "M_F_CPU0_SA_DQS_DN<4>")
	)
	(segment
		(start 427.506892 -275.317712)
		(end 427.811946 -275.317712)
		(width 0.20066)
		(layer "F.Cu")
		(net "M_F_CPU0_SA_DQS_DN<4>")
	)
	(segment
		(start 427.811946 -275.317712)
		(end 428.22241 -274.907248)
		(width 0.20066)
		(layer "F.Cu")
		(net "M_F_CPU0_SA_DQS_DN<4>")
	)
	(segment
		(start 423.407078 -274.948396)
		(end 423.821606 -275.362924)
		(width 0.20066)
		(layer "F.Cu")
		(net "M_F_CPU0_SA_DQS_DN<4>")
	)
	(segment
		(start 381.775716 -262.87222)
		(end 381.775462 -262.872474)
		(width 0.20066)
		(layer "F.Cu")
		(net "M_F_CPU0_SA_DQS_DN<4>")
	)
	(segment
		(start 422.389554 -274.66671)
		(end 422.67124 -274.948396)
		(width 0.20066)
		(layer "F.Cu")
		(net "M_F_CPU0_SA_DQS_DN<4>")
	)
	(segment
		(start 420.736014 -274.66671)
		(end 421.840914 -274.66671)
		(width 0.20066)
		(layer "F.Cu")
		(net "M_F_CPU0_SA_DQS_DN<4>")
	)
	(segment
		(start 424.614594 -275.091652)
		(end 424.762168 -275.091652)
		(width 0.20066)
		(layer "F.Cu")
		(net "M_F_CPU0_SA_DQS_DN<4>")
	)
	(segment
		(start 427.275498 -275.086318)
		(end 427.506892 -275.317712)
		(width 0.20066)
		(layer "F.Cu")
		(net "M_F_CPU0_SA_DQS_DN<4>")
	)
	(segment
		(start 424.343322 -275.362924)
		(end 424.614594 -275.091652)
		(width 0.20066)
		(layer "F.Cu")
		(net "M_F_CPU0_SA_DQS_DN<4>")
	)
	(segment
		(start 428.554896 -274.907248)
		(end 428.795434 -274.66671)
		(width 0.20066)
		(layer "F.Cu")
		(net "M_F_CPU0_SA_DQS_DN<4>")
	)
	(segment
		(start 428.22241 -274.907248)
		(end 428.554896 -274.907248)
		(width 0.20066)
		(layer "F.Cu")
		(net "M_F_CPU0_SA_DQS_DN<4>")
	)
	(segment
		(start 428.795434 -274.66671)
		(end 429.384714 -274.66671)
		(width 0.20066)
		(layer "F.Cu")
		(net "M_F_CPU0_SA_DQS_DN<4>")
	)
	(segment
		(start 426.94606 -275.091652)
		(end 426.951394 -275.086318)
		(width 0.1016)
		(layer "F.Cu")
		(net "M_F_CPU0_SA_DQS_DN<4>")
	)
	(segment
		(start 422.67124 -274.948396)
		(end 423.407078 -274.948396)
		(width 0.20066)
		(layer "F.Cu")
		(net "M_F_CPU0_SA_DQS_DN<4>")
	)
	(segment
		(start 421.840914 -274.66671)
		(end 422.389554 -274.66671)
		(width 0.20066)
		(layer "F.Cu")
		(net "M_F_CPU0_SA_DQS_DN<4>")
	)
	(segment
		(start 381.775716 -262.336534)
		(end 381.775716 -262.87222)
		(width 0.20066)
		(layer "F.Cu")
		(net "M_F_CPU0_SA_DQS_DN<4>")
	)
	(segment
		(start 423.821606 -275.362924)
		(end 424.343322 -275.362924)
		(width 0.20066)
		(layer "F.Cu")
		(net "M_F_CPU0_SA_DQS_DN<4>")
	)
	(segment
		(start 424.766486 -275.091652)
		(end 426.94606 -275.091652)
		(width 0.1016)
		(layer "F.Cu")
		(net "M_F_CPU0_SA_DQS_DN<4>")
	)
	(segment
		(start 399.13306 -266.65682)
		(end 398.744948 -266.268708)
		(width 0.18288)
		(layer "In2.Cu")
		(net "M_F_CPU0_SA_DQS_DN<4>")
	)
	(segment
		(start 408.0383 -273.379438)
		(end 407.678382 -273.379438)
		(width 0.18288)
		(layer "In2.Cu")
		(net "M_F_CPU0_SA_DQS_DN<4>")
	)
	(segment
		(start 410.073856 -275.010372)
		(end 409.889198 -274.825714)
		(width 0.16002)
		(layer "In2.Cu")
		(net "M_F_CPU0_SA_DQS_DN<4>")
	)
	(segment
		(start 409.861004 -274.781772)
		(end 408.757374 -273.678142)
		(width 0.18288)
		(layer "In2.Cu")
		(net "M_F_CPU0_SA_DQS_DN<4>")
	)
	(segment
		(start 413.33293 -275.675598)
		(end 413.33293 -275.65985)
		(width 0.16002)
		(layer "In2.Cu")
		(net "M_F_CPU0_SA_DQS_DN<4>")
	)
	(segment
		(start 381.462788 -262.872474)
		(end 381.775462 -262.872474)
		(width 0.088646)
		(layer "In2.Cu")
		(net "M_F_CPU0_SA_DQS_DN<4>")
	)
	(segment
		(start 398.744948 -266.268708)
		(end 398.568926 -266.268708)
		(width 0.18288)
		(layer "In2.Cu")
		(net "M_F_CPU0_SA_DQS_DN<4>")
	)
	(segment
		(start 415.21761 -275.705062)
		(end 415.21761 -275.72081)
		(width 0.16002)
		(layer "In2.Cu")
		(net "M_F_CPU0_SA_DQS_DN<4>")
	)
	(segment
		(start 420.338504 -275.005038)
		(end 419.967156 -274.63369)
		(width 0.18288)
		(layer "In2.Cu")
		(net "M_F_CPU0_SA_DQS_DN<4>")
	)
	(segment
		(start 413.669734 -275.996654)
		(end 413.56153 -275.88845)
		(width 0.18288)
		(layer "In2.Cu")
		(net "M_F_CPU0_SA_DQS_DN<4>")
	)
	(segment
		(start 419.345872 -274.826984)
		(end 419.317678 -274.855178)
		(width 0.16002)
		(layer "In2.Cu")
		(net "M_F_CPU0_SA_DQS_DN<4>")
	)
	(segment
		(start 396.7734 -265.75639)
		(end 396.64894 -265.88085)
		(width 0.18288)
		(layer "In2.Cu")
		(net "M_F_CPU0_SA_DQS_DN<4>")
	)
	(segment
		(start 417.432998 -274.825714)
		(end 417.432998 -274.809966)
		(width 0.16002)
		(layer "In2.Cu")
		(net "M_F_CPU0_SA_DQS_DN<4>")
	)
	(segment
		(start 405.8285 -273.379438)
		(end 405.468582 -273.379438)
		(width 0.18288)
		(layer "In2.Cu")
		(net "M_F_CPU0_SA_DQS_DN<4>")
	)
	(segment
		(start 417.191444 -274.568412)
		(end 416.35426 -274.568412)
		(width 0.18288)
		(layer "In2.Cu")
		(net "M_F_CPU0_SA_DQS_DN<4>")
	)
	(segment
		(start 416.35426 -274.568412)
		(end 415.245804 -275.676868)
		(width 0.18288)
		(layer "In2.Cu")
		(net "M_F_CPU0_SA_DQS_DN<4>")
	)
	(segment
		(start 411.77464 -275.07819)
		(end 411.480254 -275.372576)
		(width 0.18288)
		(layer "In2.Cu")
		(net "M_F_CPU0_SA_DQS_DN<4>")
	)
	(segment
		(start 417.661598 -275.038566)
		(end 417.633404 -275.010372)
		(width 0.16002)
		(layer "In2.Cu")
		(net "M_F_CPU0_SA_DQS_DN<4>")
	)
	(segment
		(start 381.404876 -262.930132)
		(end 381.40513 -262.930132)
		(width 0.088646)
		(layer "In2.Cu")
		(net "M_F_CPU0_SA_DQS_DN<4>")
	)
	(segment
		(start 413.012636 -275.339556)
		(end 412.49346 -275.339556)
		(width 0.18288)
		(layer "In2.Cu")
		(net "M_F_CPU0_SA_DQS_DN<4>")
	)
	(segment
		(start 415.245804 -275.676868)
		(end 415.21761 -275.705062)
		(width 0.16002)
		(layer "In2.Cu")
		(net "M_F_CPU0_SA_DQS_DN<4>")
	)
	(segment
		(start 391.862056 -263.075674)
		(end 388.840472 -263.075674)
		(width 0.18288)
		(layer "In2.Cu")
		(net "M_F_CPU0_SA_DQS_DN<4>")
	)
	(segment
		(start 417.617656 -275.010372)
		(end 417.432998 -274.825714)
		(width 0.16002)
		(layer "In2.Cu")
		(net "M_F_CPU0_SA_DQS_DN<4>")
	)
	(segment
		(start 413.56153 -275.88845)
		(end 413.533336 -275.860256)
		(width 0.16002)
		(layer "In2.Cu")
		(net "M_F_CPU0_SA_DQS_DN<4>")
	)
	(segment
		(start 409.889198 -274.809966)
		(end 409.861004 -274.781772)
		(width 0.16002)
		(layer "In2.Cu")
		(net "M_F_CPU0_SA_DQS_DN<4>")
	)
	(segment
		(start 420.526718 -275.005038)
		(end 420.338504 -275.005038)
		(width 0.18288)
		(layer "In2.Cu")
		(net "M_F_CPU0_SA_DQS_DN<4>")
	)
	(segment
		(start 399.13306 -266.832842)
		(end 399.13306 -266.65682)
		(width 0.18288)
		(layer "In2.Cu")
		(net "M_F_CPU0_SA_DQS_DN<4>")
	)
	(segment
		(start 388.780528 -263.135618)
		(end 387.859524 -263.135618)
		(width 0.088646)
		(layer "In2.Cu")
		(net "M_F_CPU0_SA_DQS_DN<4>")
	)
	(segment
		(start 382.536954 -263.20242)
		(end 382.528572 -263.197594)
		(width 0.088646)
		(layer "In2.Cu")
		(net "M_F_CPU0_SA_DQS_DN<4>")
	)
	(segment
		(start 415.21761 -275.72081)
		(end 415.078672 -275.859748)
		(width 0.16002)
		(layer "In2.Cu")
		(net "M_F_CPU0_SA_DQS_DN<4>")
	)
	(segment
		(start 412.232094 -275.07819)
		(end 411.77464 -275.07819)
		(width 0.18288)
		(layer "In2.Cu")
		(net "M_F_CPU0_SA_DQS_DN<4>")
	)
	(segment
		(start 415.078672 -275.859748)
		(end 415.062924 -275.859748)
		(width 0.16002)
		(layer "In2.Cu")
		(net "M_F_CPU0_SA_DQS_DN<4>")
	)
	(segment
		(start 404.688548 -273.60626)
		(end 404.305262 -273.222974)
		(width 0.18288)
		(layer "In2.Cu")
		(net "M_F_CPU0_SA_DQS_DN<4>")
	)
	(segment
		(start 410.451808 -275.372576)
		(end 410.117798 -275.038566)
		(width 0.18288)
		(layer "In2.Cu")
		(net "M_F_CPU0_SA_DQS_DN<4>")
	)
	(segment
		(start 404.305262 -273.222974)
		(end 403.442678 -271.14246)
		(width 0.18288)
		(layer "In2.Cu")
		(net "M_F_CPU0_SA_DQS_DN<4>")
	)
	(segment
		(start 397.4465 -265.88085)
		(end 397.32204 -265.75639)
		(width 0.18288)
		(layer "In2.Cu")
		(net "M_F_CPU0_SA_DQS_DN<4>")
	)
	(segment
		(start 419.317678 -274.870926)
		(end 419.17874 -275.009864)
		(width 0.16002)
		(layer "In2.Cu")
		(net "M_F_CPU0_SA_DQS_DN<4>")
	)
	(segment
		(start 415.03473 -275.887942)
		(end 414.926018 -275.996654)
		(width 0.18288)
		(layer "In2.Cu")
		(net "M_F_CPU0_SA_DQS_DN<4>")
	)
	(segment
		(start 398.181068 -265.88085)
		(end 397.4465 -265.88085)
		(width 0.18288)
		(layer "In2.Cu")
		(net "M_F_CPU0_SA_DQS_DN<4>")
	)
	(segment
		(start 392.723624 -263.433052)
		(end 391.862056 -263.075674)
		(width 0.18288)
		(layer "In2.Cu")
		(net "M_F_CPU0_SA_DQS_DN<4>")
	)
	(segment
		(start 398.568926 -266.268708)
		(end 398.181068 -265.88085)
		(width 0.18288)
		(layer "In2.Cu")
		(net "M_F_CPU0_SA_DQS_DN<4>")
	)
	(segment
		(start 386.661406 -263.197594)
		(end 386.649468 -263.204452)
		(width 0.088646)
		(layer "In2.Cu")
		(net "M_F_CPU0_SA_DQS_DN<4>")
	)
	(segment
		(start 420.736014 -274.795742)
		(end 420.526718 -275.005038)
		(width 0.18288)
		(layer "In2.Cu")
		(net "M_F_CPU0_SA_DQS_DN<4>")
	)
	(segment
		(start 405.468582 -273.379438)
		(end 405.24176 -273.60626)
		(width 0.18288)
		(layer "In2.Cu")
		(net "M_F_CPU0_SA_DQS_DN<4>")
	)
	(segment
		(start 388.840472 -263.075674)
		(end 388.780528 -263.135618)
		(width 0.088646)
		(layer "In2.Cu")
		(net "M_F_CPU0_SA_DQS_DN<4>")
	)
	(segment
		(start 413.33293 -275.65985)
		(end 413.304736 -275.631656)
		(width 0.16002)
		(layer "In2.Cu")
		(net "M_F_CPU0_SA_DQS_DN<4>")
	)
	(segment
		(start 419.317678 -274.855178)
		(end 419.317678 -274.870926)
		(width 0.16002)
		(layer "In2.Cu")
		(net "M_F_CPU0_SA_DQS_DN<4>")
	)
	(segment
		(start 419.162992 -275.009864)
		(end 419.134798 -275.038058)
		(width 0.16002)
		(layer "In2.Cu")
		(net "M_F_CPU0_SA_DQS_DN<4>")
	)
	(segment
		(start 410.089604 -275.010372)
		(end 410.073856 -275.010372)
		(width 0.16002)
		(layer "In2.Cu")
		(net "M_F_CPU0_SA_DQS_DN<4>")
	)
	(segment
		(start 408.337004 -273.678142)
		(end 408.0383 -273.379438)
		(width 0.18288)
		(layer "In2.Cu")
		(net "M_F_CPU0_SA_DQS_DN<4>")
	)
	(segment
		(start 409.889198 -274.825714)
		(end 409.889198 -274.809966)
		(width 0.16002)
		(layer "In2.Cu")
		(net "M_F_CPU0_SA_DQS_DN<4>")
	)
	(segment
		(start 397.32204 -265.75639)
		(end 396.7734 -265.75639)
		(width 0.18288)
		(layer "In2.Cu")
		(net "M_F_CPU0_SA_DQS_DN<4>")
	)
	(segment
		(start 415.062924 -275.859748)
		(end 415.03473 -275.887942)
		(width 0.16002)
		(layer "In2.Cu")
		(net "M_F_CPU0_SA_DQS_DN<4>")
	)
	(segment
		(start 413.533336 -275.860256)
		(end 413.517588 -275.860256)
		(width 0.16002)
		(layer "In2.Cu")
		(net "M_F_CPU0_SA_DQS_DN<4>")
	)
	(segment
		(start 417.633404 -275.010372)
		(end 417.617656 -275.010372)
		(width 0.16002)
		(layer "In2.Cu")
		(net "M_F_CPU0_SA_DQS_DN<4>")
	)
	(segment
		(start 419.026086 -275.14677)
		(end 417.769802 -275.14677)
		(width 0.18288)
		(layer "In2.Cu")
		(net "M_F_CPU0_SA_DQS_DN<4>")
	)
	(segment
		(start 395.171422 -265.88085)
		(end 392.723624 -263.433052)
		(width 0.18288)
		(layer "In2.Cu")
		(net "M_F_CPU0_SA_DQS_DN<4>")
	)
	(segment
		(start 419.17874 -275.009864)
		(end 419.162992 -275.009864)
		(width 0.16002)
		(layer "In2.Cu")
		(net "M_F_CPU0_SA_DQS_DN<4>")
	)
	(segment
		(start 417.769802 -275.14677)
		(end 417.661598 -275.038566)
		(width 0.18288)
		(layer "In2.Cu")
		(net "M_F_CPU0_SA_DQS_DN<4>")
	)
	(segment
		(start 403.442424 -271.141952)
		(end 399.13306 -266.832842)
		(width 0.18288)
		(layer "In2.Cu")
		(net "M_F_CPU0_SA_DQS_DN<4>")
	)
	(segment
		(start 381.40513 -262.930132)
		(end 381.462788 -262.872474)
		(width 0.088646)
		(layer "In2.Cu")
		(net "M_F_CPU0_SA_DQS_DN<4>")
	)
	(segment
		(start 396.64894 -265.88085)
		(end 395.171422 -265.88085)
		(width 0.18288)
		(layer "In2.Cu")
		(net "M_F_CPU0_SA_DQS_DN<4>")
	)
	(segment
		(start 419.967156 -274.63369)
		(end 419.539166 -274.63369)
		(width 0.18288)
		(layer "In2.Cu")
		(net "M_F_CPU0_SA_DQS_DN<4>")
	)
	(segment
		(start 420.736014 -274.66671)
		(end 420.736014 -274.795742)
		(width 0.18288)
		(layer "In2.Cu")
		(net "M_F_CPU0_SA_DQS_DN<4>")
	)
	(segment
		(start 411.480254 -275.372576)
		(end 410.451808 -275.372576)
		(width 0.18288)
		(layer "In2.Cu")
		(net "M_F_CPU0_SA_DQS_DN<4>")
	)
	(segment
		(start 419.134798 -275.038058)
		(end 419.026086 -275.14677)
		(width 0.18288)
		(layer "In2.Cu")
		(net "M_F_CPU0_SA_DQS_DN<4>")
	)
	(segment
		(start 408.757374 -273.678142)
		(end 408.337004 -273.678142)
		(width 0.18288)
		(layer "In2.Cu")
		(net "M_F_CPU0_SA_DQS_DN<4>")
	)
	(segment
		(start 410.117798 -275.038566)
		(end 410.089604 -275.010372)
		(width 0.16002)
		(layer "In2.Cu")
		(net "M_F_CPU0_SA_DQS_DN<4>")
	)
	(segment
		(start 419.539166 -274.63369)
		(end 419.345872 -274.826984)
		(width 0.18288)
		(layer "In2.Cu")
		(net "M_F_CPU0_SA_DQS_DN<4>")
	)
	(segment
		(start 403.442678 -271.14246)
		(end 403.442424 -271.141952)
		(width 0.18288)
		(layer "In2.Cu")
		(net "M_F_CPU0_SA_DQS_DN<4>")
	)
	(segment
		(start 417.404804 -274.781772)
		(end 417.191444 -274.568412)
		(width 0.18288)
		(layer "In2.Cu")
		(net "M_F_CPU0_SA_DQS_DN<4>")
	)
	(segment
		(start 413.517588 -275.860256)
		(end 413.33293 -275.675598)
		(width 0.16002)
		(layer "In2.Cu")
		(net "M_F_CPU0_SA_DQS_DN<4>")
	)
	(segment
		(start 413.304736 -275.631656)
		(end 413.012636 -275.339556)
		(width 0.18288)
		(layer "In2.Cu")
		(net "M_F_CPU0_SA_DQS_DN<4>")
	)
	(segment
		(start 405.24176 -273.60626)
		(end 404.688548 -273.60626)
		(width 0.18288)
		(layer "In2.Cu")
		(net "M_F_CPU0_SA_DQS_DN<4>")
	)
	(segment
		(start 406.093676 -273.644614)
		(end 405.8285 -273.379438)
		(width 0.18288)
		(layer "In2.Cu")
		(net "M_F_CPU0_SA_DQS_DN<4>")
	)
	(segment
		(start 414.926018 -275.996654)
		(end 413.669734 -275.996654)
		(width 0.18288)
		(layer "In2.Cu")
		(net "M_F_CPU0_SA_DQS_DN<4>")
	)
	(segment
		(start 417.432998 -274.809966)
		(end 417.404804 -274.781772)
		(width 0.16002)
		(layer "In2.Cu")
		(net "M_F_CPU0_SA_DQS_DN<4>")
	)
	(segment
		(start 407.678382 -273.379438)
		(end 407.413206 -273.644614)
		(width 0.18288)
		(layer "In2.Cu")
		(net "M_F_CPU0_SA_DQS_DN<4>")
	)
	(segment
		(start 407.413206 -273.644614)
		(end 406.093676 -273.644614)
		(width 0.18288)
		(layer "In2.Cu")
		(net "M_F_CPU0_SA_DQS_DN<4>")
	)
	(segment
		(start 412.49346 -275.339556)
		(end 412.232094 -275.07819)
		(width 0.18288)
		(layer "In2.Cu")
		(net "M_F_CPU0_SA_DQS_DN<4>")
	)
	(arc
		(start 385.722368 -263.19734)
		(mid 385.534662 -263.247669)
		(end 385.346956 -263.19734)
		(width 0.088646)
		(layer "In2.Cu")
		(net "M_F_CPU0_SA_DQS_DN<4>")
	)
	(arc
		(start 386.649468 -263.204452)
		(mid 386.467327 -263.247565)
		(end 386.28701 -263.19734)
		(width 0.088646)
		(layer "In2.Cu")
		(net "M_F_CPU0_SA_DQS_DN<4>")
	)
	(arc
		(start 382.902968 -263.19734)
		(mid 382.720635 -263.247507)
		(end 382.536954 -263.20242)
		(width 0.088646)
		(layer "In2.Cu")
		(net "M_F_CPU0_SA_DQS_DN<4>")
	)
	(arc
		(start 387.859524 -263.135618)
		(mid 387.72009 -263.153129)
		(end 387.589268 -263.204452)
		(width 0.088646)
		(layer "In2.Cu")
		(net "M_F_CPU0_SA_DQS_DN<4>")
	)
	(arc
		(start 383.842768 -263.19734)
		(mid 383.655062 -263.247669)
		(end 383.467356 -263.19734)
		(width 0.088646)
		(layer "In2.Cu")
		(net "M_F_CPU0_SA_DQS_DN<4>")
	)
	(arc
		(start 387.22681 -263.19734)
		(mid 386.944079 -263.121657)
		(end 386.661406 -263.197594)
		(width 0.088646)
		(layer "In2.Cu")
		(net "M_F_CPU0_SA_DQS_DN<4>")
	)
	(arc
		(start 384.782568 -263.19734)
		(mid 384.594862 -263.247669)
		(end 384.407156 -263.19734)
		(width 0.088646)
		(layer "In2.Cu")
		(net "M_F_CPU0_SA_DQS_DN<4>")
	)
	(arc
		(start 385.346956 -263.19734)
		(mid 385.064762 -263.121784)
		(end 384.782568 -263.19734)
		(width 0.088646)
		(layer "In2.Cu")
		(net "M_F_CPU0_SA_DQS_DN<4>")
	)
	(arc
		(start 381.963168 -263.19734)
		(mid 381.61353 -263.210926)
		(end 381.404876 -262.930132)
		(width 0.088646)
		(layer "In2.Cu")
		(net "M_F_CPU0_SA_DQS_DN<4>")
	)
	(arc
		(start 383.467356 -263.19734)
		(mid 383.185162 -263.121784)
		(end 382.902968 -263.19734)
		(width 0.088646)
		(layer "In2.Cu")
		(net "M_F_CPU0_SA_DQS_DN<4>")
	)
	(arc
		(start 387.589268 -263.204452)
		(mid 387.407127 -263.247565)
		(end 387.22681 -263.19734)
		(width 0.088646)
		(layer "In2.Cu")
		(net "M_F_CPU0_SA_DQS_DN<4>")
	)
	(arc
		(start 386.28701 -263.19734)
		(mid 386.004706 -263.121784)
		(end 385.722368 -263.19734)
		(width 0.088646)
		(layer "In2.Cu")
		(net "M_F_CPU0_SA_DQS_DN<4>")
	)
	(arc
		(start 382.528572 -263.197594)
		(mid 382.245899 -263.121623)
		(end 381.963168 -263.19734)
		(width 0.088646)
		(layer "In2.Cu")
		(net "M_F_CPU0_SA_DQS_DN<4>")
	)
	(arc
		(start 384.407156 -263.19734)
		(mid 384.124962 -263.121784)
		(end 383.842768 -263.19734)
		(width 0.088646)
		(layer "In2.Cu")
		(net "M_F_CPU0_SA_DQS_DN<4>")
	)
	(segment
		(start 422.389554 -284.016704)
		(end 422.67124 -284.29839)
		(width 0.20066)
		(layer "F.Cu")
		(net "M_F_CPU0_SA_DQS_DN<3>")
	)
	(segment
		(start 428.22241 -284.257242)
		(end 428.554896 -284.257242)
		(width 0.20066)
		(layer "F.Cu")
		(net "M_F_CPU0_SA_DQS_DN<3>")
	)
	(segment
		(start 426.94606 -284.441646)
		(end 426.951394 -284.436312)
		(width 0.1016)
		(layer "F.Cu")
		(net "M_F_CPU0_SA_DQS_DN<3>")
	)
	(segment
		(start 427.275498 -284.436312)
		(end 427.506892 -284.667706)
		(width 0.20066)
		(layer "F.Cu")
		(net "M_F_CPU0_SA_DQS_DN<3>")
	)
	(segment
		(start 421.840914 -284.016704)
		(end 422.389554 -284.016704)
		(width 0.20066)
		(layer "F.Cu")
		(net "M_F_CPU0_SA_DQS_DN<3>")
	)
	(segment
		(start 424.766486 -284.441646)
		(end 426.94606 -284.441646)
		(width 0.1016)
		(layer "F.Cu")
		(net "M_F_CPU0_SA_DQS_DN<3>")
	)
	(segment
		(start 378.486162 -260.430518)
		(end 378.486416 -260.430772)
		(width 0.20066)
		(layer "F.Cu")
		(net "M_F_CPU0_SA_DQS_DN<3>")
	)
	(segment
		(start 426.951394 -284.436312)
		(end 427.275498 -284.436312)
		(width 0.20066)
		(layer "F.Cu")
		(net "M_F_CPU0_SA_DQS_DN<3>")
	)
	(segment
		(start 423.407078 -284.29839)
		(end 423.821606 -284.712918)
		(width 0.20066)
		(layer "F.Cu")
		(net "M_F_CPU0_SA_DQS_DN<3>")
	)
	(segment
		(start 428.795434 -284.016704)
		(end 429.384714 -284.016704)
		(width 0.20066)
		(layer "F.Cu")
		(net "M_F_CPU0_SA_DQS_DN<3>")
	)
	(segment
		(start 424.343322 -284.712918)
		(end 424.614594 -284.441646)
		(width 0.20066)
		(layer "F.Cu")
		(net "M_F_CPU0_SA_DQS_DN<3>")
	)
	(segment
		(start 428.554896 -284.257242)
		(end 428.795434 -284.016704)
		(width 0.20066)
		(layer "F.Cu")
		(net "M_F_CPU0_SA_DQS_DN<3>")
	)
	(segment
		(start 427.811946 -284.667706)
		(end 428.22241 -284.257242)
		(width 0.20066)
		(layer "F.Cu")
		(net "M_F_CPU0_SA_DQS_DN<3>")
	)
	(segment
		(start 422.67124 -284.29839)
		(end 423.407078 -284.29839)
		(width 0.20066)
		(layer "F.Cu")
		(net "M_F_CPU0_SA_DQS_DN<3>")
	)
	(segment
		(start 424.614594 -284.441646)
		(end 424.762168 -284.441646)
		(width 0.20066)
		(layer "F.Cu")
		(net "M_F_CPU0_SA_DQS_DN<3>")
	)
	(segment
		(start 423.821606 -284.712918)
		(end 424.343322 -284.712918)
		(width 0.20066)
		(layer "F.Cu")
		(net "M_F_CPU0_SA_DQS_DN<3>")
	)
	(segment
		(start 378.486162 -259.894832)
		(end 378.486162 -260.430518)
		(width 0.20066)
		(layer "F.Cu")
		(net "M_F_CPU0_SA_DQS_DN<3>")
	)
	(segment
		(start 427.506892 -284.667706)
		(end 427.811946 -284.667706)
		(width 0.20066)
		(layer "F.Cu")
		(net "M_F_CPU0_SA_DQS_DN<3>")
	)
	(segment
		(start 420.736014 -284.016704)
		(end 421.840914 -284.016704)
		(width 0.20066)
		(layer "F.Cu")
		(net "M_F_CPU0_SA_DQS_DN<3>")
	)
	(segment
		(start 424.762168 -284.441646)
		(end 424.766486 -284.441646)
		(width 0.101854)
		(layer "F.Cu")
		(net "M_F_CPU0_SA_DQS_DN<3>")
	)
	(segment
		(start 379.628146 -260.746494)
		(end 379.613414 -260.75513)
		(width 0.088646)
		(layer "In4.Cu")
		(net "M_F_CPU0_SA_DQS_DN<3>")
	)
	(segment
		(start 419.943788 -283.965142)
		(end 419.335966 -283.965142)
		(width 0.18288)
		(layer "In4.Cu")
		(net "M_F_CPU0_SA_DQS_DN<3>")
	)
	(segment
		(start 406.706578 -271.363948)
		(end 405.294084 -271.363948)
		(width 0.18288)
		(layer "In4.Cu")
		(net "M_F_CPU0_SA_DQS_DN<3>")
	)
	(segment
		(start 416.685222 -280.659586)
		(end 416.685222 -280.113486)
		(width 0.18288)
		(layer "In4.Cu")
		(net "M_F_CPU0_SA_DQS_DN<3>")
	)
	(segment
		(start 381.503174 -260.749034)
		(end 381.49276 -260.75513)
		(width 0.088646)
		(layer "In4.Cu")
		(net "M_F_CPU0_SA_DQS_DN<3>")
	)
	(segment
		(start 416.809682 -277.919688)
		(end 416.685222 -277.795228)
		(width 0.18288)
		(layer "In4.Cu")
		(net "M_F_CPU0_SA_DQS_DN<3>")
	)
	(segment
		(start 413.82061 -275.35505)
		(end 411.881066 -273.415506)
		(width 0.18288)
		(layer "In4.Cu")
		(net "M_F_CPU0_SA_DQS_DN<3>")
	)
	(segment
		(start 384.322574 -260.749034)
		(end 384.31216 -260.75513)
		(width 0.088646)
		(layer "In4.Cu")
		(net "M_F_CPU0_SA_DQS_DN<3>")
	)
	(segment
		(start 420.255192 -284.276546)
		(end 419.943788 -283.965142)
		(width 0.18288)
		(layer "In4.Cu")
		(net "M_F_CPU0_SA_DQS_DN<3>")
	)
	(segment
		(start 415.821368 -275.35505)
		(end 413.82061 -275.35505)
		(width 0.18288)
		(layer "In4.Cu")
		(net "M_F_CPU0_SA_DQS_DN<3>")
	)
	(segment
		(start 392.054588 -261.706106)
		(end 389.475472 -260.638036)
		(width 0.18288)
		(layer "In4.Cu")
		(net "M_F_CPU0_SA_DQS_DN<3>")
	)
	(segment
		(start 411.881066 -273.415506)
		(end 408.758136 -273.415506)
		(width 0.18288)
		(layer "In4.Cu")
		(net "M_F_CPU0_SA_DQS_DN<3>")
	)
	(segment
		(start 416.809682 -279.442926)
		(end 416.685222 -279.318466)
		(width 0.18288)
		(layer "In4.Cu")
		(net "M_F_CPU0_SA_DQS_DN<3>")
	)
	(segment
		(start 386.808218 -260.638036)
		(end 386.78485 -260.638036)
		(width 0.088646)
		(layer "In4.Cu")
		(net "M_F_CPU0_SA_DQS_DN<3>")
	)
	(segment
		(start 416.809682 -279.989026)
		(end 416.809682 -279.442926)
		(width 0.18288)
		(layer "In4.Cu")
		(net "M_F_CPU0_SA_DQS_DN<3>")
	)
	(segment
		(start 416.809682 -278.465788)
		(end 416.809682 -277.919688)
		(width 0.18288)
		(layer "In4.Cu")
		(net "M_F_CPU0_SA_DQS_DN<3>")
	)
	(segment
		(start 396.613888 -262.683752)
		(end 393.681966 -262.683752)
		(width 0.18288)
		(layer "In4.Cu")
		(net "M_F_CPU0_SA_DQS_DN<3>")
	)
	(segment
		(start 393.681966 -262.683752)
		(end 392.572494 -262.224012)
		(width 0.18288)
		(layer "In4.Cu")
		(net "M_F_CPU0_SA_DQS_DN<3>")
	)
	(segment
		(start 405.294084 -271.363948)
		(end 396.613888 -262.683752)
		(width 0.18288)
		(layer "In4.Cu")
		(net "M_F_CPU0_SA_DQS_DN<3>")
	)
	(segment
		(start 378.116338 -260.488176)
		(end 378.173742 -260.430772)
		(width 0.088646)
		(layer "In4.Cu")
		(net "M_F_CPU0_SA_DQS_DN<3>")
	)
	(segment
		(start 408.758136 -273.415506)
		(end 406.706578 -271.363948)
		(width 0.18288)
		(layer "In4.Cu")
		(net "M_F_CPU0_SA_DQS_DN<3>")
	)
	(segment
		(start 382.443228 -260.749034)
		(end 382.432814 -260.75513)
		(width 0.088646)
		(layer "In4.Cu")
		(net "M_F_CPU0_SA_DQS_DN<3>")
	)
	(segment
		(start 419.335966 -283.965142)
		(end 418.404548 -283.033724)
		(width 0.18288)
		(layer "In4.Cu")
		(net "M_F_CPU0_SA_DQS_DN<3>")
	)
	(segment
		(start 392.572494 -262.224012)
		(end 392.054588 -261.706106)
		(width 0.18288)
		(layer "In4.Cu")
		(net "M_F_CPU0_SA_DQS_DN<3>")
	)
	(segment
		(start 416.685222 -276.218904)
		(end 415.821368 -275.35505)
		(width 0.18288)
		(layer "In4.Cu")
		(net "M_F_CPU0_SA_DQS_DN<3>")
	)
	(segment
		(start 386.239766 -260.697726)
		(end 386.17144 -260.766052)
		(width 0.088646)
		(layer "In4.Cu")
		(net "M_F_CPU0_SA_DQS_DN<3>")
	)
	(segment
		(start 416.685222 -279.318466)
		(end 416.685222 -278.590248)
		(width 0.18288)
		(layer "In4.Cu")
		(net "M_F_CPU0_SA_DQS_DN<3>")
	)
	(segment
		(start 378.299218 -260.75513)
		(end 378.290328 -260.75005)
		(width 0.088646)
		(layer "In4.Cu")
		(net "M_F_CPU0_SA_DQS_DN<3>")
	)
	(segment
		(start 417.9824 -281.956764)
		(end 416.685222 -280.659586)
		(width 0.18288)
		(layer "In4.Cu")
		(net "M_F_CPU0_SA_DQS_DN<3>")
	)
	(segment
		(start 378.688346 -260.746494)
		(end 378.673614 -260.75513)
		(width 0.088646)
		(layer "In4.Cu")
		(net "M_F_CPU0_SA_DQS_DN<3>")
	)
	(segment
		(start 418.404548 -283.033724)
		(end 417.9824 -281.956764)
		(width 0.18288)
		(layer "In4.Cu")
		(net "M_F_CPU0_SA_DQS_DN<3>")
	)
	(segment
		(start 416.685222 -278.590248)
		(end 416.809682 -278.465788)
		(width 0.18288)
		(layer "In4.Cu")
		(net "M_F_CPU0_SA_DQS_DN<3>")
	)
	(segment
		(start 389.475472 -260.638036)
		(end 386.808218 -260.638036)
		(width 0.18288)
		(layer "In4.Cu")
		(net "M_F_CPU0_SA_DQS_DN<3>")
	)
	(segment
		(start 416.685222 -280.113486)
		(end 416.809682 -279.989026)
		(width 0.18288)
		(layer "In4.Cu")
		(net "M_F_CPU0_SA_DQS_DN<3>")
	)
	(segment
		(start 416.685222 -277.795228)
		(end 416.685222 -276.218904)
		(width 0.18288)
		(layer "In4.Cu")
		(net "M_F_CPU0_SA_DQS_DN<3>")
	)
	(segment
		(start 420.736014 -284.016704)
		(end 420.476172 -284.276546)
		(width 0.18288)
		(layer "In4.Cu")
		(net "M_F_CPU0_SA_DQS_DN<3>")
	)
	(segment
		(start 386.72516 -260.697726)
		(end 386.239766 -260.697726)
		(width 0.088646)
		(layer "In4.Cu")
		(net "M_F_CPU0_SA_DQS_DN<3>")
	)
	(segment
		(start 380.563628 -260.749034)
		(end 380.553214 -260.75513)
		(width 0.088646)
		(layer "In4.Cu")
		(net "M_F_CPU0_SA_DQS_DN<3>")
	)
	(segment
		(start 386.78485 -260.638036)
		(end 386.72516 -260.697726)
		(width 0.088646)
		(layer "In4.Cu")
		(net "M_F_CPU0_SA_DQS_DN<3>")
	)
	(segment
		(start 420.476172 -284.276546)
		(end 420.255192 -284.276546)
		(width 0.18288)
		(layer "In4.Cu")
		(net "M_F_CPU0_SA_DQS_DN<3>")
	)
	(segment
		(start 378.173742 -260.430772)
		(end 378.486416 -260.430772)
		(width 0.088646)
		(layer "In4.Cu")
		(net "M_F_CPU0_SA_DQS_DN<3>")
	)
	(arc
		(start 382.058418 -260.75513)
		(mid 381.781605 -260.679294)
		(end 381.503174 -260.749034)
		(width 0.088646)
		(layer "In4.Cu")
		(net "M_F_CPU0_SA_DQS_DN<3>")
	)
	(arc
		(start 379.613414 -260.75513)
		(mid 379.426216 -260.805273)
		(end 379.239018 -260.75513)
		(width 0.088646)
		(layer "In4.Cu")
		(net "M_F_CPU0_SA_DQS_DN<3>")
	)
	(arc
		(start 380.553214 -260.75513)
		(mid 380.366016 -260.805273)
		(end 380.178818 -260.75513)
		(width 0.088646)
		(layer "In4.Cu")
		(net "M_F_CPU0_SA_DQS_DN<3>")
	)
	(arc
		(start 384.87731 -260.75513)
		(mid 384.600751 -260.679421)
		(end 384.322574 -260.749034)
		(width 0.088646)
		(layer "In4.Cu")
		(net "M_F_CPU0_SA_DQS_DN<3>")
	)
	(arc
		(start 384.31216 -260.75513)
		(mid 384.124962 -260.805273)
		(end 383.937764 -260.75513)
		(width 0.088646)
		(layer "In4.Cu")
		(net "M_F_CPU0_SA_DQS_DN<3>")
	)
	(arc
		(start 378.673614 -260.75513)
		(mid 378.486416 -260.805273)
		(end 378.299218 -260.75513)
		(width 0.088646)
		(layer "In4.Cu")
		(net "M_F_CPU0_SA_DQS_DN<3>")
	)
	(arc
		(start 385.251706 -260.75513)
		(mid 385.064508 -260.805273)
		(end 384.87731 -260.75513)
		(width 0.088646)
		(layer "In4.Cu")
		(net "M_F_CPU0_SA_DQS_DN<3>")
	)
	(arc
		(start 382.997964 -260.75513)
		(mid 382.721405 -260.679421)
		(end 382.443228 -260.749034)
		(width 0.088646)
		(layer "In4.Cu")
		(net "M_F_CPU0_SA_DQS_DN<3>")
	)
	(arc
		(start 379.239018 -260.75513)
		(mid 378.964789 -260.679205)
		(end 378.688346 -260.746494)
		(width 0.088646)
		(layer "In4.Cu")
		(net "M_F_CPU0_SA_DQS_DN<3>")
	)
	(arc
		(start 380.178818 -260.75513)
		(mid 379.904589 -260.679205)
		(end 379.628146 -260.746494)
		(width 0.088646)
		(layer "In4.Cu")
		(net "M_F_CPU0_SA_DQS_DN<3>")
	)
	(arc
		(start 383.37236 -260.75513)
		(mid 383.185162 -260.805273)
		(end 382.997964 -260.75513)
		(width 0.088646)
		(layer "In4.Cu")
		(net "M_F_CPU0_SA_DQS_DN<3>")
	)
	(arc
		(start 386.17144 -260.766052)
		(mid 385.992917 -260.805105)
		(end 385.81711 -260.75513)
		(width 0.088646)
		(layer "In4.Cu")
		(net "M_F_CPU0_SA_DQS_DN<3>")
	)
	(arc
		(start 383.937764 -260.75513)
		(mid 383.655062 -260.679388)
		(end 383.37236 -260.75513)
		(width 0.088646)
		(layer "In4.Cu")
		(net "M_F_CPU0_SA_DQS_DN<3>")
	)
	(arc
		(start 382.432814 -260.75513)
		(mid 382.245616 -260.805273)
		(end 382.058418 -260.75513)
		(width 0.088646)
		(layer "In4.Cu")
		(net "M_F_CPU0_SA_DQS_DN<3>")
	)
	(arc
		(start 381.118364 -260.75513)
		(mid 380.841805 -260.679421)
		(end 380.563628 -260.749034)
		(width 0.088646)
		(layer "In4.Cu")
		(net "M_F_CPU0_SA_DQS_DN<3>")
	)
	(arc
		(start 381.49276 -260.75513)
		(mid 381.305562 -260.805273)
		(end 381.118364 -260.75513)
		(width 0.088646)
		(layer "In4.Cu")
		(net "M_F_CPU0_SA_DQS_DN<3>")
	)
	(arc
		(start 378.290328 -260.75005)
		(mid 378.174589 -260.638226)
		(end 378.116338 -260.488176)
		(width 0.088646)
		(layer "In4.Cu")
		(net "M_F_CPU0_SA_DQS_DN<3>")
	)
	(arc
		(start 385.81711 -260.75513)
		(mid 385.534408 -260.679388)
		(end 385.251706 -260.75513)
		(width 0.088646)
		(layer "In4.Cu")
		(net "M_F_CPU0_SA_DQS_DN<3>")
	)
	(segment
		(start 427.811946 -294.0177)
		(end 428.22241 -293.607236)
		(width 0.20066)
		(layer "F.Cu")
		(net "M_F_CPU0_SA_DQS_DN<2>")
	)
	(segment
		(start 428.795434 -293.366698)
		(end 429.384714 -293.366698)
		(width 0.20066)
		(layer "F.Cu")
		(net "M_F_CPU0_SA_DQS_DN<2>")
	)
	(segment
		(start 424.766486 -293.79164)
		(end 426.94606 -293.79164)
		(width 0.1016)
		(layer "F.Cu")
		(net "M_F_CPU0_SA_DQS_DN<2>")
	)
	(segment
		(start 424.762168 -293.79164)
		(end 424.766486 -293.79164)
		(width 0.101854)
		(layer "F.Cu")
		(net "M_F_CPU0_SA_DQS_DN<2>")
	)
	(segment
		(start 426.94606 -293.79164)
		(end 426.951394 -293.786306)
		(width 0.1016)
		(layer "F.Cu")
		(net "M_F_CPU0_SA_DQS_DN<2>")
	)
	(segment
		(start 422.67124 -293.648384)
		(end 423.407078 -293.648384)
		(width 0.20066)
		(layer "F.Cu")
		(net "M_F_CPU0_SA_DQS_DN<2>")
	)
	(segment
		(start 424.343322 -294.062912)
		(end 424.614594 -293.79164)
		(width 0.20066)
		(layer "F.Cu")
		(net "M_F_CPU0_SA_DQS_DN<2>")
	)
	(segment
		(start 424.614594 -293.79164)
		(end 424.762168 -293.79164)
		(width 0.20066)
		(layer "F.Cu")
		(net "M_F_CPU0_SA_DQS_DN<2>")
	)
	(segment
		(start 380.835916 -267.755624)
		(end 380.835662 -267.755878)
		(width 0.20066)
		(layer "F.Cu")
		(net "M_F_CPU0_SA_DQS_DN<2>")
	)
	(segment
		(start 428.554896 -293.607236)
		(end 428.795434 -293.366698)
		(width 0.20066)
		(layer "F.Cu")
		(net "M_F_CPU0_SA_DQS_DN<2>")
	)
	(segment
		(start 423.821606 -294.062912)
		(end 424.343322 -294.062912)
		(width 0.20066)
		(layer "F.Cu")
		(net "M_F_CPU0_SA_DQS_DN<2>")
	)
	(segment
		(start 420.736014 -293.366698)
		(end 421.840914 -293.366698)
		(width 0.20066)
		(layer "F.Cu")
		(net "M_F_CPU0_SA_DQS_DN<2>")
	)
	(segment
		(start 427.275498 -293.786306)
		(end 427.506892 -294.0177)
		(width 0.20066)
		(layer "F.Cu")
		(net "M_F_CPU0_SA_DQS_DN<2>")
	)
	(segment
		(start 380.835916 -267.219938)
		(end 380.835916 -267.755624)
		(width 0.20066)
		(layer "F.Cu")
		(net "M_F_CPU0_SA_DQS_DN<2>")
	)
	(segment
		(start 428.22241 -293.607236)
		(end 428.554896 -293.607236)
		(width 0.20066)
		(layer "F.Cu")
		(net "M_F_CPU0_SA_DQS_DN<2>")
	)
	(segment
		(start 426.951394 -293.786306)
		(end 427.275498 -293.786306)
		(width 0.20066)
		(layer "F.Cu")
		(net "M_F_CPU0_SA_DQS_DN<2>")
	)
	(segment
		(start 423.407078 -293.648384)
		(end 423.821606 -294.062912)
		(width 0.20066)
		(layer "F.Cu")
		(net "M_F_CPU0_SA_DQS_DN<2>")
	)
	(segment
		(start 427.506892 -294.0177)
		(end 427.811946 -294.0177)
		(width 0.20066)
		(layer "F.Cu")
		(net "M_F_CPU0_SA_DQS_DN<2>")
	)
	(segment
		(start 422.389554 -293.366698)
		(end 422.67124 -293.648384)
		(width 0.20066)
		(layer "F.Cu")
		(net "M_F_CPU0_SA_DQS_DN<2>")
	)
	(segment
		(start 421.840914 -293.366698)
		(end 422.389554 -293.366698)
		(width 0.20066)
		(layer "F.Cu")
		(net "M_F_CPU0_SA_DQS_DN<2>")
	)
	(segment
		(start 415.902394 -289.966908)
		(end 416.155124 -289.356546)
		(width 0.18288)
		(layer "In2.Cu")
		(net "M_F_CPU0_SA_DQS_DN<2>")
	)
	(segment
		(start 408.378152 -286.13735)
		(end 407.931112 -286.13735)
		(width 0.18288)
		(layer "In2.Cu")
		(net "M_F_CPU0_SA_DQS_DN<2>")
	)
	(segment
		(start 420.736014 -293.366698)
		(end 420.523162 -293.57955)
		(width 0.18288)
		(layer "In2.Cu")
		(net "M_F_CPU0_SA_DQS_DN<2>")
	)
	(segment
		(start 407.644854 -285.867348)
		(end 407.644854 -285.851092)
		(width 0.16002)
		(layer "In2.Cu")
		(net "M_F_CPU0_SA_DQS_DN<2>")
	)
	(segment
		(start 416.155124 -288.953194)
		(end 415.812732 -288.126424)
		(width 0.18288)
		(layer "In2.Cu")
		(net "M_F_CPU0_SA_DQS_DN<2>")
	)
	(segment
		(start 415.812732 -288.126424)
		(end 415.357564 -287.671256)
		(width 0.18288)
		(layer "In2.Cu")
		(net "M_F_CPU0_SA_DQS_DN<2>")
	)
	(segment
		(start 417.692586 -293.79037)
		(end 417.676838 -293.79037)
		(width 0.16002)
		(layer "In2.Cu")
		(net "M_F_CPU0_SA_DQS_DN<2>")
	)
	(segment
		(start 383.467864 -268.080236)
		(end 383.453132 -268.0716)
		(width 0.088646)
		(layer "In2.Cu")
		(net "M_F_CPU0_SA_DQS_DN<2>")
	)
	(segment
		(start 388.840472 -268.160246)
		(end 388.780782 -268.219936)
		(width 0.088646)
		(layer "In2.Cu")
		(net "M_F_CPU0_SA_DQS_DN<2>")
	)
	(segment
		(start 412.540196 -287.546034)
		(end 411.846268 -287.546034)
		(width 0.18288)
		(layer "In2.Cu")
		(net "M_F_CPU0_SA_DQS_DN<2>")
	)
	(segment
		(start 403.816566 -281.98445)
		(end 403.580092 -281.414982)
		(width 0.18288)
		(layer "In2.Cu")
		(net "M_F_CPU0_SA_DQS_DN<2>")
	)
	(segment
		(start 414.94837 -287.501584)
		(end 413.653478 -287.501584)
		(width 0.18288)
		(layer "In2.Cu")
		(net "M_F_CPU0_SA_DQS_DN<2>")
	)
	(segment
		(start 388.780782 -268.219936)
		(end 388.484872 -268.219936)
		(width 0.088646)
		(layer "In2.Cu")
		(net "M_F_CPU0_SA_DQS_DN<2>")
	)
	(segment
		(start 390.403842 -268.160246)
		(end 388.840472 -268.160246)
		(width 0.18288)
		(layer "In2.Cu")
		(net "M_F_CPU0_SA_DQS_DN<2>")
	)
	(segment
		(start 403.816566 -283.18206)
		(end 403.816566 -281.98445)
		(width 0.18288)
		(layer "In2.Cu")
		(net "M_F_CPU0_SA_DQS_DN<2>")
	)
	(segment
		(start 419.27907 -293.613078)
		(end 419.27907 -293.628826)
		(width 0.16002)
		(layer "In2.Cu")
		(net "M_F_CPU0_SA_DQS_DN<2>")
	)
	(segment
		(start 403.580092 -281.414982)
		(end 399.093436 -276.927818)
		(width 0.18288)
		(layer "In2.Cu")
		(net "M_F_CPU0_SA_DQS_DN<2>")
	)
	(segment
		(start 382.136904 -267.632434)
		(end 382.099058 -267.566902)
		(width 0.088646)
		(layer "In2.Cu")
		(net "M_F_CPU0_SA_DQS_DN<2>")
	)
	(segment
		(start 413.291528 -287.651444)
		(end 412.645606 -287.651444)
		(width 0.18288)
		(layer "In2.Cu")
		(net "M_F_CPU0_SA_DQS_DN<2>")
	)
	(segment
		(start 417.72078 -293.818564)
		(end 417.692586 -293.79037)
		(width 0.16002)
		(layer "In2.Cu")
		(net "M_F_CPU0_SA_DQS_DN<2>")
	)
	(segment
		(start 395.612112 -272.218404)
		(end 394.686282 -272.218404)
		(width 0.18288)
		(layer "In2.Cu")
		(net "M_F_CPU0_SA_DQS_DN<2>")
	)
	(segment
		(start 419.483794 -293.408354)
		(end 419.307264 -293.584884)
		(width 0.18288)
		(layer "In2.Cu")
		(net "M_F_CPU0_SA_DQS_DN<2>")
	)
	(segment
		(start 406.098248 -285.340044)
		(end 405.91359 -285.155386)
		(width 0.16002)
		(layer "In2.Cu")
		(net "M_F_CPU0_SA_DQS_DN<2>")
	)
	(segment
		(start 406.14219 -285.368238)
		(end 406.113996 -285.340044)
		(width 0.16002)
		(layer "In2.Cu")
		(net "M_F_CPU0_SA_DQS_DN<2>")
	)
	(segment
		(start 387.601714 -268.08049)
		(end 387.60146 -268.080236)
		(width 0.088646)
		(layer "In2.Cu")
		(net "M_F_CPU0_SA_DQS_DN<2>")
	)
	(segment
		(start 407.644854 -285.851092)
		(end 407.61666 -285.822898)
		(width 0.16002)
		(layer "In2.Cu")
		(net "M_F_CPU0_SA_DQS_DN<2>")
	)
	(segment
		(start 417.776406 -293.87419)
		(end 417.72078 -293.818564)
		(width 0.18288)
		(layer "In2.Cu")
		(net "M_F_CPU0_SA_DQS_DN<2>")
	)
	(segment
		(start 390.78662 -268.318742)
		(end 390.403842 -268.160246)
		(width 0.18288)
		(layer "In2.Cu")
		(net "M_F_CPU0_SA_DQS_DN<2>")
	)
	(segment
		(start 417.49218 -293.605712)
		(end 417.49218 -293.589964)
		(width 0.16002)
		(layer "In2.Cu")
		(net "M_F_CPU0_SA_DQS_DN<2>")
	)
	(segment
		(start 417.676838 -293.79037)
		(end 417.49218 -293.605712)
		(width 0.16002)
		(layer "In2.Cu")
		(net "M_F_CPU0_SA_DQS_DN<2>")
	)
	(segment
		(start 406.113996 -285.340044)
		(end 406.098248 -285.340044)
		(width 0.16002)
		(layer "In2.Cu")
		(net "M_F_CPU0_SA_DQS_DN<2>")
	)
	(segment
		(start 398.099026 -274.526248)
		(end 395.917674 -272.344642)
		(width 0.18288)
		(layer "In2.Cu")
		(net "M_F_CPU0_SA_DQS_DN<2>")
	)
	(segment
		(start 407.931112 -286.13735)
		(end 407.873454 -286.079692)
		(width 0.18288)
		(layer "In2.Cu")
		(net "M_F_CPU0_SA_DQS_DN<2>")
	)
	(segment
		(start 416.155124 -289.356546)
		(end 416.155124 -288.953194)
		(width 0.18288)
		(layer "In2.Cu")
		(net "M_F_CPU0_SA_DQS_DN<2>")
	)
	(segment
		(start 399.093436 -276.927818)
		(end 398.099026 -274.526248)
		(width 0.18288)
		(layer "In2.Cu")
		(net "M_F_CPU0_SA_DQS_DN<2>")
	)
	(segment
		(start 388.484872 -268.219936)
		(end 388.26948 -268.004544)
		(width 0.088646)
		(layer "In2.Cu")
		(net "M_F_CPU0_SA_DQS_DN<2>")
	)
	(segment
		(start 381.348234 -267.755878)
		(end 380.835662 -267.755878)
		(width 0.088646)
		(layer "In2.Cu")
		(net "M_F_CPU0_SA_DQS_DN<2>")
	)
	(segment
		(start 407.829004 -286.051498)
		(end 407.644854 -285.867348)
		(width 0.16002)
		(layer "In2.Cu")
		(net "M_F_CPU0_SA_DQS_DN<2>")
	)
	(segment
		(start 419.05047 -293.841678)
		(end 419.017958 -293.87419)
		(width 0.18288)
		(layer "In2.Cu")
		(net "M_F_CPU0_SA_DQS_DN<2>")
	)
	(segment
		(start 405.91359 -285.139638)
		(end 405.885396 -285.111444)
		(width 0.16002)
		(layer "In2.Cu")
		(net "M_F_CPU0_SA_DQS_DN<2>")
	)
	(segment
		(start 419.094412 -293.813484)
		(end 419.078664 -293.813484)
		(width 0.16002)
		(layer "In2.Cu")
		(net "M_F_CPU0_SA_DQS_DN<2>")
	)
	(segment
		(start 417.49218 -293.589964)
		(end 417.463986 -293.56177)
		(width 0.16002)
		(layer "In2.Cu")
		(net "M_F_CPU0_SA_DQS_DN<2>")
	)
	(segment
		(start 411.587442 -287.80486)
		(end 410.045662 -287.80486)
		(width 0.18288)
		(layer "In2.Cu")
		(net "M_F_CPU0_SA_DQS_DN<2>")
	)
	(segment
		(start 388.26948 -268.004544)
		(end 387.883908 -268.004544)
		(width 0.088646)
		(layer "In2.Cu")
		(net "M_F_CPU0_SA_DQS_DN<2>")
	)
	(segment
		(start 407.873454 -286.079692)
		(end 407.84526 -286.051498)
		(width 0.16002)
		(layer "In2.Cu")
		(net "M_F_CPU0_SA_DQS_DN<2>")
	)
	(segment
		(start 381.405384 -267.698728)
		(end 381.348234 -267.755878)
		(width 0.088646)
		(layer "In2.Cu")
		(net "M_F_CPU0_SA_DQS_DN<2>")
	)
	(segment
		(start 382.902714 -268.079982)
		(end 382.902968 -268.08049)
		(width 0.088646)
		(layer "In2.Cu")
		(net "M_F_CPU0_SA_DQS_DN<2>")
	)
	(segment
		(start 412.645606 -287.651444)
		(end 412.540196 -287.546034)
		(width 0.18288)
		(layer "In2.Cu")
		(net "M_F_CPU0_SA_DQS_DN<2>")
	)
	(segment
		(start 405.885396 -285.111444)
		(end 405.521668 -284.747716)
		(width 0.18288)
		(layer "In2.Cu")
		(net "M_F_CPU0_SA_DQS_DN<2>")
	)
	(segment
		(start 419.27907 -293.628826)
		(end 419.094412 -293.813484)
		(width 0.16002)
		(layer "In2.Cu")
		(net "M_F_CPU0_SA_DQS_DN<2>")
	)
	(segment
		(start 405.521668 -284.747716)
		(end 405.382222 -284.747716)
		(width 0.18288)
		(layer "In2.Cu")
		(net "M_F_CPU0_SA_DQS_DN<2>")
	)
	(segment
		(start 419.017958 -293.87419)
		(end 417.776406 -293.87419)
		(width 0.18288)
		(layer "In2.Cu")
		(net "M_F_CPU0_SA_DQS_DN<2>")
	)
	(segment
		(start 411.846268 -287.546034)
		(end 411.587442 -287.80486)
		(width 0.18288)
		(layer "In2.Cu")
		(net "M_F_CPU0_SA_DQS_DN<2>")
	)
	(segment
		(start 382.540002 -268.087602)
		(end 382.463802 -268.041882)
		(width 0.088646)
		(layer "In2.Cu")
		(net "M_F_CPU0_SA_DQS_DN<2>")
	)
	(segment
		(start 406.29586 -285.521908)
		(end 406.14219 -285.368238)
		(width 0.18288)
		(layer "In2.Cu")
		(net "M_F_CPU0_SA_DQS_DN<2>")
	)
	(segment
		(start 419.078664 -293.813484)
		(end 419.05047 -293.841678)
		(width 0.16002)
		(layer "In2.Cu")
		(net "M_F_CPU0_SA_DQS_DN<2>")
	)
	(segment
		(start 410.045662 -287.80486)
		(end 408.378152 -286.13735)
		(width 0.18288)
		(layer "In2.Cu")
		(net "M_F_CPU0_SA_DQS_DN<2>")
	)
	(segment
		(start 407.61666 -285.822898)
		(end 407.31567 -285.521908)
		(width 0.18288)
		(layer "In2.Cu")
		(net "M_F_CPU0_SA_DQS_DN<2>")
	)
	(segment
		(start 420.170102 -293.57955)
		(end 419.998906 -293.408354)
		(width 0.18288)
		(layer "In2.Cu")
		(net "M_F_CPU0_SA_DQS_DN<2>")
	)
	(segment
		(start 413.653478 -287.501584)
		(end 413.291528 -287.651444)
		(width 0.18288)
		(layer "In2.Cu")
		(net "M_F_CPU0_SA_DQS_DN<2>")
	)
	(segment
		(start 415.357564 -287.671256)
		(end 414.94837 -287.501584)
		(width 0.18288)
		(layer "In2.Cu")
		(net "M_F_CPU0_SA_DQS_DN<2>")
	)
	(segment
		(start 420.523162 -293.57955)
		(end 420.170102 -293.57955)
		(width 0.18288)
		(layer "In2.Cu")
		(net "M_F_CPU0_SA_DQS_DN<2>")
	)
	(segment
		(start 395.917674 -272.344642)
		(end 395.612112 -272.218404)
		(width 0.18288)
		(layer "In2.Cu")
		(net "M_F_CPU0_SA_DQS_DN<2>")
	)
	(segment
		(start 417.033964 -293.131748)
		(end 415.902394 -289.966908)
		(width 0.18288)
		(layer "In2.Cu")
		(net "M_F_CPU0_SA_DQS_DN<2>")
	)
	(segment
		(start 405.382222 -284.747716)
		(end 403.816566 -283.18206)
		(width 0.18288)
		(layer "In2.Cu")
		(net "M_F_CPU0_SA_DQS_DN<2>")
	)
	(segment
		(start 419.307264 -293.584884)
		(end 419.27907 -293.613078)
		(width 0.16002)
		(layer "In2.Cu")
		(net "M_F_CPU0_SA_DQS_DN<2>")
	)
	(segment
		(start 394.686282 -272.218404)
		(end 390.78662 -268.318742)
		(width 0.18288)
		(layer "In2.Cu")
		(net "M_F_CPU0_SA_DQS_DN<2>")
	)
	(segment
		(start 407.31567 -285.521908)
		(end 406.29586 -285.521908)
		(width 0.18288)
		(layer "In2.Cu")
		(net "M_F_CPU0_SA_DQS_DN<2>")
	)
	(segment
		(start 407.84526 -286.051498)
		(end 407.829004 -286.051498)
		(width 0.16002)
		(layer "In2.Cu")
		(net "M_F_CPU0_SA_DQS_DN<2>")
	)
	(segment
		(start 382.463802 -268.041882)
		(end 382.136904 -267.632434)
		(width 0.088646)
		(layer "In2.Cu")
		(net "M_F_CPU0_SA_DQS_DN<2>")
	)
	(segment
		(start 405.91359 -285.155386)
		(end 405.91359 -285.139638)
		(width 0.16002)
		(layer "In2.Cu")
		(net "M_F_CPU0_SA_DQS_DN<2>")
	)
	(segment
		(start 417.463986 -293.56177)
		(end 417.033964 -293.131748)
		(width 0.18288)
		(layer "In2.Cu")
		(net "M_F_CPU0_SA_DQS_DN<2>")
	)
	(segment
		(start 419.998906 -293.408354)
		(end 419.483794 -293.408354)
		(width 0.18288)
		(layer "In2.Cu")
		(net "M_F_CPU0_SA_DQS_DN<2>")
	)
	(arc
		(start 387.60146 -268.080236)
		(mid 387.414262 -268.130379)
		(end 387.227064 -268.080236)
		(width 0.088646)
		(layer "In2.Cu")
		(net "M_F_CPU0_SA_DQS_DN<2>")
	)
	(arc
		(start 386.66166 -268.080236)
		(mid 386.474462 -268.130379)
		(end 386.287264 -268.080236)
		(width 0.088646)
		(layer "In2.Cu")
		(net "M_F_CPU0_SA_DQS_DN<2>")
	)
	(arc
		(start 383.453132 -268.0716)
		(mid 383.17683 -268.004278)
		(end 382.902714 -268.079982)
		(width 0.088646)
		(layer "In2.Cu")
		(net "M_F_CPU0_SA_DQS_DN<2>")
	)
	(arc
		(start 385.72186 -268.080236)
		(mid 385.534662 -268.130379)
		(end 385.347464 -268.080236)
		(width 0.088646)
		(layer "In2.Cu")
		(net "M_F_CPU0_SA_DQS_DN<2>")
	)
	(arc
		(start 387.227064 -268.080236)
		(mid 386.944362 -268.00446)
		(end 386.66166 -268.080236)
		(width 0.088646)
		(layer "In2.Cu")
		(net "M_F_CPU0_SA_DQS_DN<2>")
	)
	(arc
		(start 384.407664 -268.080236)
		(mid 384.124962 -268.00446)
		(end 383.84226 -268.080236)
		(width 0.088646)
		(layer "In2.Cu")
		(net "M_F_CPU0_SA_DQS_DN<2>")
	)
	(arc
		(start 386.287264 -268.080236)
		(mid 386.004562 -268.00446)
		(end 385.72186 -268.080236)
		(width 0.088646)
		(layer "In2.Cu")
		(net "M_F_CPU0_SA_DQS_DN<2>")
	)
	(arc
		(start 382.099058 -267.566902)
		(mid 382.033463 -267.483866)
		(end 381.947166 -267.42263)
		(width 0.088646)
		(layer "In2.Cu")
		(net "M_F_CPU0_SA_DQS_DN<2>")
	)
	(arc
		(start 385.347464 -268.080236)
		(mid 385.064762 -268.00446)
		(end 384.78206 -268.080236)
		(width 0.088646)
		(layer "In2.Cu")
		(net "M_F_CPU0_SA_DQS_DN<2>")
	)
	(arc
		(start 382.902968 -268.08049)
		(mid 382.722397 -268.130908)
		(end 382.540002 -268.087602)
		(width 0.088646)
		(layer "In2.Cu")
		(net "M_F_CPU0_SA_DQS_DN<2>")
	)
	(arc
		(start 383.84226 -268.080236)
		(mid 383.655062 -268.130379)
		(end 383.467864 -268.080236)
		(width 0.088646)
		(layer "In2.Cu")
		(net "M_F_CPU0_SA_DQS_DN<2>")
	)
	(arc
		(start 384.78206 -268.080236)
		(mid 384.594862 -268.130379)
		(end 384.407664 -268.080236)
		(width 0.088646)
		(layer "In2.Cu")
		(net "M_F_CPU0_SA_DQS_DN<2>")
	)
	(arc
		(start 381.947166 -267.42263)
		(mid 381.605612 -267.421941)
		(end 381.405384 -267.698728)
		(width 0.088646)
		(layer "In2.Cu")
		(net "M_F_CPU0_SA_DQS_DN<2>")
	)
	(arc
		(start 387.883908 -268.004544)
		(mid 387.737815 -268.023957)
		(end 387.601714 -268.08049)
		(width 0.088646)
		(layer "In2.Cu")
		(net "M_F_CPU0_SA_DQS_DN<2>")
	)
	(segment
		(start 422.67124 -302.998378)
		(end 423.407078 -302.998378)
		(width 0.20066)
		(layer "F.Cu")
		(net "M_F_CPU0_SA_DQS_DN<1>")
	)
	(segment
		(start 423.407078 -302.998378)
		(end 423.821606 -303.412906)
		(width 0.20066)
		(layer "F.Cu")
		(net "M_F_CPU0_SA_DQS_DN<1>")
	)
	(segment
		(start 427.275498 -303.1363)
		(end 427.506892 -303.367694)
		(width 0.20066)
		(layer "F.Cu")
		(net "M_F_CPU0_SA_DQS_DN<1>")
	)
	(segment
		(start 428.795434 -302.716692)
		(end 429.384714 -302.716692)
		(width 0.20066)
		(layer "F.Cu")
		(net "M_F_CPU0_SA_DQS_DN<1>")
	)
	(segment
		(start 427.506892 -303.367694)
		(end 427.811946 -303.367694)
		(width 0.20066)
		(layer "F.Cu")
		(net "M_F_CPU0_SA_DQS_DN<1>")
	)
	(segment
		(start 424.343322 -303.412906)
		(end 424.614594 -303.141634)
		(width 0.20066)
		(layer "F.Cu")
		(net "M_F_CPU0_SA_DQS_DN<1>")
	)
	(segment
		(start 426.951394 -303.1363)
		(end 427.275498 -303.1363)
		(width 0.20066)
		(layer "F.Cu")
		(net "M_F_CPU0_SA_DQS_DN<1>")
	)
	(segment
		(start 377.546362 -269.66164)
		(end 377.546616 -270.167862)
		(width 0.20066)
		(layer "F.Cu")
		(net "M_F_CPU0_SA_DQS_DN<1>")
	)
	(segment
		(start 427.811946 -303.367694)
		(end 428.22241 -302.95723)
		(width 0.20066)
		(layer "F.Cu")
		(net "M_F_CPU0_SA_DQS_DN<1>")
	)
	(segment
		(start 377.546616 -270.167862)
		(end 377.546616 -270.19758)
		(width 0.20066)
		(layer "F.Cu")
		(net "M_F_CPU0_SA_DQS_DN<1>")
	)
	(segment
		(start 424.766486 -303.141634)
		(end 426.94606 -303.141634)
		(width 0.1016)
		(layer "F.Cu")
		(net "M_F_CPU0_SA_DQS_DN<1>")
	)
	(segment
		(start 426.94606 -303.141634)
		(end 426.951394 -303.1363)
		(width 0.1016)
		(layer "F.Cu")
		(net "M_F_CPU0_SA_DQS_DN<1>")
	)
	(segment
		(start 420.736014 -302.716692)
		(end 421.840914 -302.716692)
		(width 0.20066)
		(layer "F.Cu")
		(net "M_F_CPU0_SA_DQS_DN<1>")
	)
	(segment
		(start 423.821606 -303.412906)
		(end 424.343322 -303.412906)
		(width 0.20066)
		(layer "F.Cu")
		(net "M_F_CPU0_SA_DQS_DN<1>")
	)
	(segment
		(start 428.22241 -302.95723)
		(end 428.554896 -302.95723)
		(width 0.20066)
		(layer "F.Cu")
		(net "M_F_CPU0_SA_DQS_DN<1>")
	)
	(segment
		(start 428.554896 -302.95723)
		(end 428.795434 -302.716692)
		(width 0.20066)
		(layer "F.Cu")
		(net "M_F_CPU0_SA_DQS_DN<1>")
	)
	(segment
		(start 424.762168 -303.141634)
		(end 424.766486 -303.141634)
		(width 0.101854)
		(layer "F.Cu")
		(net "M_F_CPU0_SA_DQS_DN<1>")
	)
	(segment
		(start 422.389554 -302.716692)
		(end 422.67124 -302.998378)
		(width 0.20066)
		(layer "F.Cu")
		(net "M_F_CPU0_SA_DQS_DN<1>")
	)
	(segment
		(start 421.840914 -302.716692)
		(end 422.389554 -302.716692)
		(width 0.20066)
		(layer "F.Cu")
		(net "M_F_CPU0_SA_DQS_DN<1>")
	)
	(segment
		(start 424.614594 -303.141634)
		(end 424.762168 -303.141634)
		(width 0.20066)
		(layer "F.Cu")
		(net "M_F_CPU0_SA_DQS_DN<1>")
	)
	(segment
		(start 379.23851 -270.522192)
		(end 379.238256 -270.522192)
		(width 0.088646)
		(layer "In4.Cu")
		(net "M_F_CPU0_SA_DQS_DN<1>")
	)
	(segment
		(start 409.575762 -298.892468)
		(end 409.297124 -299.171106)
		(width 0.18288)
		(layer "In4.Cu")
		(net "M_F_CPU0_SA_DQS_DN<1>")
	)
	(segment
		(start 409.94203 -298.892468)
		(end 409.575762 -298.892468)
		(width 0.18288)
		(layer "In4.Cu")
		(net "M_F_CPU0_SA_DQS_DN<1>")
	)
	(segment
		(start 420.47541 -302.977296)
		(end 420.148766 -302.977296)
		(width 0.18288)
		(layer "In4.Cu")
		(net "M_F_CPU0_SA_DQS_DN<1>")
	)
	(segment
		(start 379.55601 -270.54937)
		(end 379.554994 -270.549624)
		(width 0.088646)
		(layer "In4.Cu")
		(net "M_F_CPU0_SA_DQS_DN<1>")
	)
	(segment
		(start 410.217874 -299.168312)
		(end 409.94203 -298.892468)
		(width 0.18288)
		(layer "In4.Cu")
		(net "M_F_CPU0_SA_DQS_DN<1>")
	)
	(segment
		(start 395.988794 -279.44699)
		(end 390.619742 -274.077938)
		(width 0.18288)
		(layer "In4.Cu")
		(net "M_F_CPU0_SA_DQS_DN<1>")
	)
	(segment
		(start 382.432052 -270.522192)
		(end 382.420368 -270.529304)
		(width 0.088646)
		(layer "In4.Cu")
		(net "M_F_CPU0_SA_DQS_DN<1>")
	)
	(segment
		(start 419.96995 -302.79848)
		(end 415.317432 -302.79848)
		(width 0.18288)
		(layer "In4.Cu")
		(net "M_F_CPU0_SA_DQS_DN<1>")
	)
	(segment
		(start 420.148766 -302.977296)
		(end 419.96995 -302.79848)
		(width 0.18288)
		(layer "In4.Cu")
		(net "M_F_CPU0_SA_DQS_DN<1>")
	)
	(segment
		(start 383.372614 -270.521938)
		(end 383.360168 -270.529304)
		(width 0.088646)
		(layer "In4.Cu")
		(net "M_F_CPU0_SA_DQS_DN<1>")
	)
	(segment
		(start 378.658882 -269.86484)
		(end 378.65812 -269.864332)
		(width 0.088646)
		(layer "In4.Cu")
		(net "M_F_CPU0_SA_DQS_DN<1>")
	)
	(segment
		(start 379.164342 -270.471646)
		(end 378.875036 -270.109188)
		(width 0.088646)
		(layer "In4.Cu")
		(net "M_F_CPU0_SA_DQS_DN<1>")
	)
	(segment
		(start 378.875036 -270.109188)
		(end 378.87529 -270.108934)
		(width 0.088646)
		(layer "In4.Cu")
		(net "M_F_CPU0_SA_DQS_DN<1>")
	)
	(segment
		(start 408.954478 -299.171106)
		(end 408.770074 -298.986702)
		(width 0.18288)
		(layer "In4.Cu")
		(net "M_F_CPU0_SA_DQS_DN<1>")
	)
	(segment
		(start 378.059188 -270.19758)
		(end 377.546616 -270.19758)
		(width 0.088646)
		(layer "In4.Cu")
		(net "M_F_CPU0_SA_DQS_DN<1>")
	)
	(segment
		(start 387.326378 -271.26057)
		(end 386.943346 -271.26057)
		(width 0.088646)
		(layer "In4.Cu")
		(net "M_F_CPU0_SA_DQS_DN<1>")
	)
	(segment
		(start 390.619742 -274.077938)
		(end 390.058148 -274.077938)
		(width 0.18288)
		(layer "In4.Cu")
		(net "M_F_CPU0_SA_DQS_DN<1>")
	)
	(segment
		(start 387.989064 -272.008854)
		(end 387.888226 -271.992344)
		(width 0.088646)
		(layer "In4.Cu")
		(net "M_F_CPU0_SA_DQS_DN<1>")
	)
	(segment
		(start 380.182628 -270.524224)
		(end 380.178818 -270.521938)
		(width 0.088646)
		(layer "In4.Cu")
		(net "M_F_CPU0_SA_DQS_DN<1>")
	)
	(segment
		(start 379.201172 -270.500602)
		(end 379.164342 -270.471646)
		(width 0.088646)
		(layer "In4.Cu")
		(net "M_F_CPU0_SA_DQS_DN<1>")
	)
	(segment
		(start 379.613414 -270.521938)
		(end 379.612652 -270.5227)
		(width 0.088646)
		(layer "In4.Cu")
		(net "M_F_CPU0_SA_DQS_DN<1>")
	)
	(segment
		(start 387.888226 -271.992344)
		(end 387.654038 -271.758156)
		(width 0.088646)
		(layer "In4.Cu")
		(net "M_F_CPU0_SA_DQS_DN<1>")
	)
	(segment
		(start 386.28574 -271.334992)
		(end 386.278374 -271.330674)
		(width 0.088646)
		(layer "In4.Cu")
		(net "M_F_CPU0_SA_DQS_DN<1>")
	)
	(segment
		(start 386.662422 -271.336008)
		(end 386.66166 -271.335754)
		(width 0.088646)
		(layer "In4.Cu")
		(net "M_F_CPU0_SA_DQS_DN<1>")
	)
	(segment
		(start 413.914844 -301.395892)
		(end 410.580078 -299.168312)
		(width 0.18288)
		(layer "In4.Cu")
		(net "M_F_CPU0_SA_DQS_DN<1>")
	)
	(segment
		(start 387.654038 -271.758156)
		(end 387.654038 -271.58823)
		(width 0.088646)
		(layer "In4.Cu")
		(net "M_F_CPU0_SA_DQS_DN<1>")
	)
	(segment
		(start 379.612652 -270.5227)
		(end 379.58268 -270.53921)
		(width 0.088646)
		(layer "In4.Cu")
		(net "M_F_CPU0_SA_DQS_DN<1>")
	)
	(segment
		(start 390.058148 -274.077938)
		(end 387.989064 -272.008854)
		(width 0.18288)
		(layer "In4.Cu")
		(net "M_F_CPU0_SA_DQS_DN<1>")
	)
	(segment
		(start 410.580078 -299.168312)
		(end 410.217874 -299.168312)
		(width 0.18288)
		(layer "In4.Cu")
		(net "M_F_CPU0_SA_DQS_DN<1>")
	)
	(segment
		(start 379.238256 -270.522192)
		(end 379.201172 -270.500602)
		(width 0.088646)
		(layer "In4.Cu")
		(net "M_F_CPU0_SA_DQS_DN<1>")
	)
	(segment
		(start 385.266946 -270.513302)
		(end 385.252214 -270.521938)
		(width 0.088646)
		(layer "In4.Cu")
		(net "M_F_CPU0_SA_DQS_DN<1>")
	)
	(segment
		(start 386.099812 -271.011396)
		(end 386.099812 -270.995902)
		(width 0.088646)
		(layer "In4.Cu")
		(net "M_F_CPU0_SA_DQS_DN<1>")
	)
	(segment
		(start 406.93086 -296.498264)
		(end 405.274018 -295.81221)
		(width 0.18288)
		(layer "In4.Cu")
		(net "M_F_CPU0_SA_DQS_DN<1>")
	)
	(segment
		(start 379.57633 -270.542004)
		(end 379.55601 -270.54937)
		(width 0.088646)
		(layer "In4.Cu")
		(net "M_F_CPU0_SA_DQS_DN<1>")
	)
	(segment
		(start 386.287264 -271.335754)
		(end 386.28574 -271.334992)
		(width 0.088646)
		(layer "In4.Cu")
		(net "M_F_CPU0_SA_DQS_DN<1>")
	)
	(segment
		(start 383.387346 -270.513302)
		(end 383.372614 -270.521938)
		(width 0.088646)
		(layer "In4.Cu")
		(net "M_F_CPU0_SA_DQS_DN<1>")
	)
	(segment
		(start 408.770074 -298.337732)
		(end 406.93086 -296.498264)
		(width 0.18288)
		(layer "In4.Cu")
		(net "M_F_CPU0_SA_DQS_DN<1>")
	)
	(segment
		(start 384.327146 -270.513302)
		(end 384.312414 -270.521938)
		(width 0.088646)
		(layer "In4.Cu")
		(net "M_F_CPU0_SA_DQS_DN<1>")
	)
	(segment
		(start 379.628146 -270.513302)
		(end 379.613414 -270.521938)
		(width 0.088646)
		(layer "In4.Cu")
		(net "M_F_CPU0_SA_DQS_DN<1>")
	)
	(segment
		(start 400.99615 -291.534596)
		(end 395.988794 -279.44699)
		(width 0.18288)
		(layer "In4.Cu")
		(net "M_F_CPU0_SA_DQS_DN<1>")
	)
	(segment
		(start 379.554994 -270.549624)
		(end 379.55474 -270.549878)
		(width 0.088646)
		(layer "In4.Cu")
		(net "M_F_CPU0_SA_DQS_DN<1>")
	)
	(segment
		(start 378.82957 -270.04137)
		(end 378.812552 -270.011652)
		(width 0.088646)
		(layer "In4.Cu")
		(net "M_F_CPU0_SA_DQS_DN<1>")
	)
	(segment
		(start 378.116338 -270.14043)
		(end 378.059188 -270.19758)
		(width 0.088646)
		(layer "In4.Cu")
		(net "M_F_CPU0_SA_DQS_DN<1>")
	)
	(segment
		(start 409.297124 -299.171106)
		(end 408.954478 -299.171106)
		(width 0.18288)
		(layer "In4.Cu")
		(net "M_F_CPU0_SA_DQS_DN<1>")
	)
	(segment
		(start 408.770074 -298.986702)
		(end 408.770074 -298.337732)
		(width 0.18288)
		(layer "In4.Cu")
		(net "M_F_CPU0_SA_DQS_DN<1>")
	)
	(segment
		(start 415.317432 -302.79848)
		(end 413.914844 -301.395892)
		(width 0.18288)
		(layer "In4.Cu")
		(net "M_F_CPU0_SA_DQS_DN<1>")
	)
	(segment
		(start 405.274018 -295.81221)
		(end 400.99615 -291.534596)
		(width 0.18288)
		(layer "In4.Cu")
		(net "M_F_CPU0_SA_DQS_DN<1>")
	)
	(segment
		(start 387.654038 -271.58823)
		(end 387.326378 -271.26057)
		(width 0.088646)
		(layer "In4.Cu")
		(net "M_F_CPU0_SA_DQS_DN<1>")
	)
	(segment
		(start 420.736014 -302.716692)
		(end 420.47541 -302.977296)
		(width 0.18288)
		(layer "In4.Cu")
		(net "M_F_CPU0_SA_DQS_DN<1>")
	)
	(segment
		(start 381.122428 -270.524224)
		(end 381.11049 -270.517366)
		(width 0.088646)
		(layer "In4.Cu")
		(net "M_F_CPU0_SA_DQS_DN<1>")
	)
	(arc
		(start 379.58268 -270.53921)
		(mid 379.579551 -270.540712)
		(end 379.57633 -270.542004)
		(width 0.088646)
		(layer "In4.Cu")
		(net "M_F_CPU0_SA_DQS_DN<1>")
	)
	(arc
		(start 385.817618 -270.521938)
		(mid 385.543419 -270.446103)
		(end 385.266946 -270.513302)
		(width 0.088646)
		(layer "In4.Cu")
		(net "M_F_CPU0_SA_DQS_DN<1>")
	)
	(arc
		(start 378.87529 -270.108934)
		(mid 378.851088 -270.076059)
		(end 378.82957 -270.04137)
		(width 0.088646)
		(layer "In4.Cu")
		(net "M_F_CPU0_SA_DQS_DN<1>")
	)
	(arc
		(start 382.997964 -270.521938)
		(mid 382.714979 -270.446162)
		(end 382.432052 -270.522192)
		(width 0.088646)
		(layer "In4.Cu")
		(net "M_F_CPU0_SA_DQS_DN<1>")
	)
	(arc
		(start 384.877818 -270.521938)
		(mid 384.603619 -270.446103)
		(end 384.327146 -270.513302)
		(width 0.088646)
		(layer "In4.Cu")
		(net "M_F_CPU0_SA_DQS_DN<1>")
	)
	(arc
		(start 384.312414 -270.521938)
		(mid 384.125216 -270.572081)
		(end 383.938018 -270.521938)
		(width 0.088646)
		(layer "In4.Cu")
		(net "M_F_CPU0_SA_DQS_DN<1>")
	)
	(arc
		(start 379.55474 -270.549878)
		(mid 379.393546 -270.571164)
		(end 379.23851 -270.522192)
		(width 0.088646)
		(layer "In4.Cu")
		(net "M_F_CPU0_SA_DQS_DN<1>")
	)
	(arc
		(start 381.11049 -270.517366)
		(mid 380.831253 -270.44621)
		(end 380.553214 -270.521938)
		(width 0.088646)
		(layer "In4.Cu")
		(net "M_F_CPU0_SA_DQS_DN<1>")
	)
	(arc
		(start 386.943346 -271.26057)
		(mid 386.797941 -271.279884)
		(end 386.662422 -271.336008)
		(width 0.088646)
		(layer "In4.Cu")
		(net "M_F_CPU0_SA_DQS_DN<1>")
	)
	(arc
		(start 383.938018 -270.521938)
		(mid 383.663819 -270.446103)
		(end 383.387346 -270.513302)
		(width 0.088646)
		(layer "In4.Cu")
		(net "M_F_CPU0_SA_DQS_DN<1>")
	)
	(arc
		(start 383.360168 -270.529304)
		(mid 383.178108 -270.572324)
		(end 382.997964 -270.521938)
		(width 0.088646)
		(layer "In4.Cu")
		(net "M_F_CPU0_SA_DQS_DN<1>")
	)
	(arc
		(start 382.058164 -270.521938)
		(mid 381.775606 -270.446289)
		(end 381.493014 -270.521938)
		(width 0.088646)
		(layer "In4.Cu")
		(net "M_F_CPU0_SA_DQS_DN<1>")
	)
	(arc
		(start 386.278374 -271.330674)
		(mid 386.14746 -271.194314)
		(end 386.099812 -271.011396)
		(width 0.088646)
		(layer "In4.Cu")
		(net "M_F_CPU0_SA_DQS_DN<1>")
	)
	(arc
		(start 386.66166 -271.335754)
		(mid 386.474462 -271.385897)
		(end 386.287264 -271.335754)
		(width 0.088646)
		(layer "In4.Cu")
		(net "M_F_CPU0_SA_DQS_DN<1>")
	)
	(arc
		(start 382.420368 -270.529304)
		(mid 382.238308 -270.572324)
		(end 382.058164 -270.521938)
		(width 0.088646)
		(layer "In4.Cu")
		(net "M_F_CPU0_SA_DQS_DN<1>")
	)
	(arc
		(start 380.178818 -270.521938)
		(mid 379.904619 -270.446103)
		(end 379.628146 -270.513302)
		(width 0.088646)
		(layer "In4.Cu")
		(net "M_F_CPU0_SA_DQS_DN<1>")
	)
	(arc
		(start 378.65812 -269.864332)
		(mid 378.316566 -269.863643)
		(end 378.116338 -270.14043)
		(width 0.088646)
		(layer "In4.Cu")
		(net "M_F_CPU0_SA_DQS_DN<1>")
	)
	(arc
		(start 385.252214 -270.521938)
		(mid 385.065016 -270.572081)
		(end 384.877818 -270.521938)
		(width 0.088646)
		(layer "In4.Cu")
		(net "M_F_CPU0_SA_DQS_DN<1>")
	)
	(arc
		(start 380.553214 -270.521938)
		(mid 380.368237 -270.572075)
		(end 380.182628 -270.524224)
		(width 0.088646)
		(layer "In4.Cu")
		(net "M_F_CPU0_SA_DQS_DN<1>")
	)
	(arc
		(start 378.812552 -270.011652)
		(mid 378.746373 -269.927092)
		(end 378.658882 -269.86484)
		(width 0.088646)
		(layer "In4.Cu")
		(net "M_F_CPU0_SA_DQS_DN<1>")
	)
	(arc
		(start 386.099812 -270.995902)
		(mid 386.020442 -270.722168)
		(end 385.817618 -270.521938)
		(width 0.088646)
		(layer "In4.Cu")
		(net "M_F_CPU0_SA_DQS_DN<1>")
	)
	(arc
		(start 381.493014 -270.521938)
		(mid 381.308037 -270.572075)
		(end 381.122428 -270.524224)
		(width 0.088646)
		(layer "In4.Cu")
		(net "M_F_CPU0_SA_DQS_DN<1>")
	)
	(segment
		(start 424.766486 -312.491628)
		(end 426.94606 -312.491628)
		(width 0.1016)
		(layer "F.Cu")
		(net "M_F_CPU0_SA_DQS_DN<0>")
	)
	(segment
		(start 421.840914 -312.066686)
		(end 422.389554 -312.066686)
		(width 0.20066)
		(layer "F.Cu")
		(net "M_F_CPU0_SA_DQS_DN<0>")
	)
	(segment
		(start 428.22241 -312.307224)
		(end 428.554896 -312.307224)
		(width 0.20066)
		(layer "F.Cu")
		(net "M_F_CPU0_SA_DQS_DN<0>")
	)
	(segment
		(start 381.775716 -276.986492)
		(end 381.775716 -277.522178)
		(width 0.20066)
		(layer "F.Cu")
		(net "M_F_CPU0_SA_DQS_DN<0>")
	)
	(segment
		(start 428.795434 -312.066686)
		(end 429.384714 -312.066686)
		(width 0.20066)
		(layer "F.Cu")
		(net "M_F_CPU0_SA_DQS_DN<0>")
	)
	(segment
		(start 427.506892 -312.717688)
		(end 427.811946 -312.717688)
		(width 0.20066)
		(layer "F.Cu")
		(net "M_F_CPU0_SA_DQS_DN<0>")
	)
	(segment
		(start 426.951394 -312.486294)
		(end 427.275498 -312.486294)
		(width 0.20066)
		(layer "F.Cu")
		(net "M_F_CPU0_SA_DQS_DN<0>")
	)
	(segment
		(start 424.614594 -312.491628)
		(end 424.762168 -312.491628)
		(width 0.20066)
		(layer "F.Cu")
		(net "M_F_CPU0_SA_DQS_DN<0>")
	)
	(segment
		(start 427.275498 -312.486294)
		(end 427.506892 -312.717688)
		(width 0.20066)
		(layer "F.Cu")
		(net "M_F_CPU0_SA_DQS_DN<0>")
	)
	(segment
		(start 420.736014 -312.066686)
		(end 421.840914 -312.066686)
		(width 0.20066)
		(layer "F.Cu")
		(net "M_F_CPU0_SA_DQS_DN<0>")
	)
	(segment
		(start 424.762168 -312.491628)
		(end 424.766486 -312.491628)
		(width 0.101854)
		(layer "F.Cu")
		(net "M_F_CPU0_SA_DQS_DN<0>")
	)
	(segment
		(start 381.775716 -277.522178)
		(end 381.775462 -277.522432)
		(width 0.20066)
		(layer "F.Cu")
		(net "M_F_CPU0_SA_DQS_DN<0>")
	)
	(segment
		(start 427.811946 -312.717688)
		(end 428.22241 -312.307224)
		(width 0.20066)
		(layer "F.Cu")
		(net "M_F_CPU0_SA_DQS_DN<0>")
	)
	(segment
		(start 424.343322 -312.7629)
		(end 424.614594 -312.491628)
		(width 0.20066)
		(layer "F.Cu")
		(net "M_F_CPU0_SA_DQS_DN<0>")
	)
	(segment
		(start 422.389554 -312.066686)
		(end 422.67124 -312.348372)
		(width 0.20066)
		(layer "F.Cu")
		(net "M_F_CPU0_SA_DQS_DN<0>")
	)
	(segment
		(start 428.554896 -312.307224)
		(end 428.795434 -312.066686)
		(width 0.20066)
		(layer "F.Cu")
		(net "M_F_CPU0_SA_DQS_DN<0>")
	)
	(segment
		(start 423.407078 -312.348372)
		(end 423.821606 -312.7629)
		(width 0.20066)
		(layer "F.Cu")
		(net "M_F_CPU0_SA_DQS_DN<0>")
	)
	(segment
		(start 426.94606 -312.491628)
		(end 426.951394 -312.486294)
		(width 0.1016)
		(layer "F.Cu")
		(net "M_F_CPU0_SA_DQS_DN<0>")
	)
	(segment
		(start 422.67124 -312.348372)
		(end 423.407078 -312.348372)
		(width 0.20066)
		(layer "F.Cu")
		(net "M_F_CPU0_SA_DQS_DN<0>")
	)
	(segment
		(start 423.821606 -312.7629)
		(end 424.343322 -312.7629)
		(width 0.20066)
		(layer "F.Cu")
		(net "M_F_CPU0_SA_DQS_DN<0>")
	)
	(segment
		(start 395.934946 -300.746668)
		(end 396.059406 -300.622208)
		(width 0.18288)
		(layer "In2.Cu")
		(net "M_F_CPU0_SA_DQS_DN<0>")
	)
	(segment
		(start 417.73348 -312.524648)
		(end 417.705286 -312.496454)
		(width 0.16002)
		(layer "In2.Cu")
		(net "M_F_CPU0_SA_DQS_DN<0>")
	)
	(segment
		(start 405.205692 -312.50001)
		(end 404.447248 -312.50001)
		(width 0.18288)
		(layer "In2.Cu")
		(net "M_F_CPU0_SA_DQS_DN<0>")
	)
	(segment
		(start 388.25805 -279.360122)
		(end 388.173722 -279.360122)
		(width 0.088646)
		(layer "In2.Cu")
		(net "M_F_CPU0_SA_DQS_DN<0>")
	)
	(segment
		(start 391.148062 -289.812222)
		(end 391.148062 -283.897578)
		(width 0.18288)
		(layer "In2.Cu")
		(net "M_F_CPU0_SA_DQS_DN<0>")
	)
	(segment
		(start 404.447248 -312.50001)
		(end 395.934946 -303.987708)
		(width 0.18288)
		(layer "In2.Cu")
		(net "M_F_CPU0_SA_DQS_DN<0>")
	)
	(segment
		(start 406.023572 -313.31789)
		(end 405.995378 -313.289696)
		(width 0.16002)
		(layer "In2.Cu")
		(net "M_F_CPU0_SA_DQS_DN<0>")
	)
	(segment
		(start 410.077158 -312.44413)
		(end 410.048964 -312.415936)
		(width 0.16002)
		(layer "In2.Cu")
		(net "M_F_CPU0_SA_DQS_DN<0>")
	)
	(segment
		(start 383.750312 -278.336502)
		(end 383.750312 -278.322278)
		(width 0.088646)
		(layer "In2.Cu")
		(net "M_F_CPU0_SA_DQS_DN<0>")
	)
	(segment
		(start 410.048964 -312.415936)
		(end 410.033216 -312.415936)
		(width 0.16002)
		(layer "In2.Cu")
		(net "M_F_CPU0_SA_DQS_DN<0>")
	)
	(segment
		(start 388.173722 -279.360122)
		(end 387.53542 -278.72182)
		(width 0.088646)
		(layer "In2.Cu")
		(net "M_F_CPU0_SA_DQS_DN<0>")
	)
	(segment
		(start 413.530288 -313.289696)
		(end 413.51454 -313.289696)
		(width 0.16002)
		(layer "In2.Cu")
		(net "M_F_CPU0_SA_DQS_DN<0>")
	)
	(segment
		(start 394.551408 -294.549068)
		(end 392.091164 -292.089078)
		(width 0.18288)
		(layer "In2.Cu")
		(net "M_F_CPU0_SA_DQS_DN<0>")
	)
	(segment
		(start 396.059406 -299.276008)
		(end 396.059406 -298.727368)
		(width 0.18288)
		(layer "In2.Cu")
		(net "M_F_CPU0_SA_DQS_DN<0>")
	)
	(segment
		(start 412.980124 -312.739532)
		(end 412.593028 -312.739532)
		(width 0.18288)
		(layer "In2.Cu")
		(net "M_F_CPU0_SA_DQS_DN<0>")
	)
	(segment
		(start 419.46195 -312.163968)
		(end 419.0619 -312.564018)
		(width 0.18288)
		(layer "In2.Cu")
		(net "M_F_CPU0_SA_DQS_DN<0>")
	)
	(segment
		(start 386.756656 -278.660606)
		(end 386.754624 -278.659336)
		(width 0.088646)
		(layer "In2.Cu")
		(net "M_F_CPU0_SA_DQS_DN<0>")
	)
	(segment
		(start 415.089086 -313.289696)
		(end 415.073338 -313.289696)
		(width 0.16002)
		(layer "In2.Cu")
		(net "M_F_CPU0_SA_DQS_DN<0>")
	)
	(segment
		(start 420.296594 -312.321702)
		(end 420.13886 -312.163968)
		(width 0.18288)
		(layer "In2.Cu")
		(net "M_F_CPU0_SA_DQS_DN<0>")
	)
	(segment
		(start 415.301938 -313.061096)
		(end 415.273744 -313.08929)
		(width 0.16002)
		(layer "In2.Cu")
		(net "M_F_CPU0_SA_DQS_DN<0>")
	)
	(segment
		(start 417.291774 -312.082942)
		(end 416.725608 -312.082942)
		(width 0.18288)
		(layer "In2.Cu")
		(net "M_F_CPU0_SA_DQS_DN<0>")
	)
	(segment
		(start 395.934946 -301.295308)
		(end 395.934946 -300.746668)
		(width 0.18288)
		(layer "In2.Cu")
		(net "M_F_CPU0_SA_DQS_DN<0>")
	)
	(segment
		(start 396.059406 -303.314608)
		(end 396.059406 -302.765968)
		(width 0.18288)
		(layer "In2.Cu")
		(net "M_F_CPU0_SA_DQS_DN<0>")
	)
	(segment
		(start 412.331662 -312.478166)
		(end 411.977332 -312.478166)
		(width 0.18288)
		(layer "In2.Cu")
		(net "M_F_CPU0_SA_DQS_DN<0>")
	)
	(segment
		(start 383.46761 -277.84679)
		(end 383.457196 -277.840694)
		(width 0.088646)
		(layer "In2.Cu")
		(net "M_F_CPU0_SA_DQS_DN<0>")
	)
	(segment
		(start 396.059406 -298.727368)
		(end 395.934946 -298.602908)
		(width 0.18288)
		(layer "In2.Cu")
		(net "M_F_CPU0_SA_DQS_DN<0>")
	)
	(segment
		(start 409.848558 -312.21553)
		(end 409.820364 -312.187336)
		(width 0.16002)
		(layer "In2.Cu")
		(net "M_F_CPU0_SA_DQS_DN<0>")
	)
	(segment
		(start 414.948624 -313.41441)
		(end 413.655002 -313.41441)
		(width 0.18288)
		(layer "In2.Cu")
		(net "M_F_CPU0_SA_DQS_DN<0>")
	)
	(segment
		(start 411.977332 -312.478166)
		(end 411.701488 -312.75401)
		(width 0.18288)
		(layer "In2.Cu")
		(net "M_F_CPU0_SA_DQS_DN<0>")
	)
	(segment
		(start 417.518342 -312.30951)
		(end 417.291774 -312.082942)
		(width 0.18288)
		(layer "In2.Cu")
		(net "M_F_CPU0_SA_DQS_DN<0>")
	)
	(segment
		(start 385.817364 -278.66086)
		(end 385.802632 -278.652224)
		(width 0.088646)
		(layer "In2.Cu")
		(net "M_F_CPU0_SA_DQS_DN<0>")
	)
	(segment
		(start 405.766778 -313.061096)
		(end 405.205692 -312.50001)
		(width 0.18288)
		(layer "In2.Cu")
		(net "M_F_CPU0_SA_DQS_DN<0>")
	)
	(segment
		(start 405.97963 -313.289696)
		(end 405.794972 -313.105038)
		(width 0.16002)
		(layer "In2.Cu")
		(net "M_F_CPU0_SA_DQS_DN<0>")
	)
	(segment
		(start 409.619958 -311.98693)
		(end 408.888692 -311.98693)
		(width 0.18288)
		(layer "In2.Cu")
		(net "M_F_CPU0_SA_DQS_DN<0>")
	)
	(segment
		(start 415.273744 -313.105038)
		(end 415.089086 -313.289696)
		(width 0.16002)
		(layer "In2.Cu")
		(net "M_F_CPU0_SA_DQS_DN<0>")
	)
	(segment
		(start 413.301688 -313.061096)
		(end 412.980124 -312.739532)
		(width 0.18288)
		(layer "In2.Cu")
		(net "M_F_CPU0_SA_DQS_DN<0>")
	)
	(segment
		(start 381.405384 -277.579582)
		(end 381.462534 -277.522432)
		(width 0.088646)
		(layer "In2.Cu")
		(net "M_F_CPU0_SA_DQS_DN<0>")
	)
	(segment
		(start 406.092152 -313.38647)
		(end 406.023572 -313.31789)
		(width 0.18288)
		(layer "In2.Cu")
		(net "M_F_CPU0_SA_DQS_DN<0>")
	)
	(segment
		(start 395.934946 -302.092868)
		(end 396.059406 -301.968408)
		(width 0.18288)
		(layer "In2.Cu")
		(net "M_F_CPU0_SA_DQS_DN<0>")
	)
	(segment
		(start 413.329882 -313.08929)
		(end 413.301688 -313.061096)
		(width 0.16002)
		(layer "In2.Cu")
		(net "M_F_CPU0_SA_DQS_DN<0>")
	)
	(segment
		(start 395.934946 -302.641508)
		(end 395.934946 -302.092868)
		(width 0.18288)
		(layer "In2.Cu")
		(net "M_F_CPU0_SA_DQS_DN<0>")
	)
	(segment
		(start 415.045144 -313.31789)
		(end 414.948624 -313.41441)
		(width 0.18288)
		(layer "In2.Cu")
		(net "M_F_CPU0_SA_DQS_DN<0>")
	)
	(segment
		(start 409.848558 -312.231278)
		(end 409.848558 -312.21553)
		(width 0.16002)
		(layer "In2.Cu")
		(net "M_F_CPU0_SA_DQS_DN<0>")
	)
	(segment
		(start 388.807452 -279.909778)
		(end 388.25805 -279.360122)
		(width 0.18288)
		(layer "In2.Cu")
		(net "M_F_CPU0_SA_DQS_DN<0>")
	)
	(segment
		(start 392.091164 -292.089078)
		(end 391.148062 -289.812222)
		(width 0.18288)
		(layer "In2.Cu")
		(net "M_F_CPU0_SA_DQS_DN<0>")
	)
	(segment
		(start 396.059406 -300.073568)
		(end 395.934946 -299.949108)
		(width 0.18288)
		(layer "In2.Cu")
		(net "M_F_CPU0_SA_DQS_DN<0>")
	)
	(segment
		(start 395.934946 -297.890184)
		(end 394.551408 -294.549068)
		(width 0.18288)
		(layer "In2.Cu")
		(net "M_F_CPU0_SA_DQS_DN<0>")
	)
	(segment
		(start 396.059406 -300.622208)
		(end 396.059406 -300.073568)
		(width 0.18288)
		(layer "In2.Cu")
		(net "M_F_CPU0_SA_DQS_DN<0>")
	)
	(segment
		(start 381.588264 -277.84679)
		(end 381.579374 -277.84171)
		(width 0.088646)
		(layer "In2.Cu")
		(net "M_F_CPU0_SA_DQS_DN<0>")
	)
	(segment
		(start 383.937764 -278.66086)
		(end 383.928874 -278.65578)
		(width 0.088646)
		(layer "In2.Cu")
		(net "M_F_CPU0_SA_DQS_DN<0>")
	)
	(segment
		(start 391.148062 -283.897578)
		(end 389.972804 -282.72232)
		(width 0.18288)
		(layer "In2.Cu")
		(net "M_F_CPU0_SA_DQS_DN<0>")
	)
	(segment
		(start 417.68903 -312.496454)
		(end 417.546536 -312.35396)
		(width 0.16002)
		(layer "In2.Cu")
		(net "M_F_CPU0_SA_DQS_DN<0>")
	)
	(segment
		(start 412.593028 -312.739532)
		(end 412.331662 -312.478166)
		(width 0.18288)
		(layer "In2.Cu")
		(net "M_F_CPU0_SA_DQS_DN<0>")
	)
	(segment
		(start 408.888692 -311.98693)
		(end 407.489152 -313.38647)
		(width 0.18288)
		(layer "In2.Cu")
		(net "M_F_CPU0_SA_DQS_DN<0>")
	)
	(segment
		(start 395.934946 -299.400468)
		(end 396.059406 -299.276008)
		(width 0.18288)
		(layer "In2.Cu")
		(net "M_F_CPU0_SA_DQS_DN<0>")
	)
	(segment
		(start 389.972804 -282.72232)
		(end 388.807452 -279.909778)
		(width 0.18288)
		(layer "In2.Cu")
		(net "M_F_CPU0_SA_DQS_DN<0>")
	)
	(segment
		(start 417.705286 -312.496454)
		(end 417.68903 -312.496454)
		(width 0.16002)
		(layer "In2.Cu")
		(net "M_F_CPU0_SA_DQS_DN<0>")
	)
	(segment
		(start 411.701488 -312.75401)
		(end 410.387038 -312.75401)
		(width 0.18288)
		(layer "In2.Cu")
		(net "M_F_CPU0_SA_DQS_DN<0>")
	)
	(segment
		(start 405.794972 -313.105038)
		(end 405.794972 -313.08929)
		(width 0.16002)
		(layer "In2.Cu")
		(net "M_F_CPU0_SA_DQS_DN<0>")
	)
	(segment
		(start 420.13886 -312.163968)
		(end 419.46195 -312.163968)
		(width 0.18288)
		(layer "In2.Cu")
		(net "M_F_CPU0_SA_DQS_DN<0>")
	)
	(segment
		(start 413.655002 -313.41441)
		(end 413.558482 -313.31789)
		(width 0.18288)
		(layer "In2.Cu")
		(net "M_F_CPU0_SA_DQS_DN<0>")
	)
	(segment
		(start 416.016186 -312.792364)
		(end 415.57067 -312.792364)
		(width 0.18288)
		(layer "In2.Cu")
		(net "M_F_CPU0_SA_DQS_DN<0>")
	)
	(segment
		(start 413.51454 -313.289696)
		(end 413.329882 -313.105038)
		(width 0.16002)
		(layer "In2.Cu")
		(net "M_F_CPU0_SA_DQS_DN<0>")
	)
	(segment
		(start 415.073338 -313.289696)
		(end 415.045144 -313.31789)
		(width 0.16002)
		(layer "In2.Cu")
		(net "M_F_CPU0_SA_DQS_DN<0>")
	)
	(segment
		(start 410.033216 -312.415936)
		(end 409.848558 -312.231278)
		(width 0.16002)
		(layer "In2.Cu")
		(net "M_F_CPU0_SA_DQS_DN<0>")
	)
	(segment
		(start 417.546536 -312.337704)
		(end 417.518342 -312.30951)
		(width 0.16002)
		(layer "In2.Cu")
		(net "M_F_CPU0_SA_DQS_DN<0>")
	)
	(segment
		(start 420.736014 -312.066686)
		(end 420.480998 -312.321702)
		(width 0.18288)
		(layer "In2.Cu")
		(net "M_F_CPU0_SA_DQS_DN<0>")
	)
	(segment
		(start 415.273744 -313.08929)
		(end 415.273744 -313.105038)
		(width 0.16002)
		(layer "In2.Cu")
		(net "M_F_CPU0_SA_DQS_DN<0>")
	)
	(segment
		(start 381.462534 -277.522432)
		(end 381.775462 -277.522432)
		(width 0.088646)
		(layer "In2.Cu")
		(net "M_F_CPU0_SA_DQS_DN<0>")
	)
	(segment
		(start 386.192014 -278.66086)
		(end 386.19176 -278.66086)
		(width 0.088646)
		(layer "In2.Cu")
		(net "M_F_CPU0_SA_DQS_DN<0>")
	)
	(segment
		(start 405.995378 -313.289696)
		(end 405.97963 -313.289696)
		(width 0.16002)
		(layer "In2.Cu")
		(net "M_F_CPU0_SA_DQS_DN<0>")
	)
	(segment
		(start 413.329882 -313.105038)
		(end 413.329882 -313.08929)
		(width 0.16002)
		(layer "In2.Cu")
		(net "M_F_CPU0_SA_DQS_DN<0>")
	)
	(segment
		(start 395.934946 -298.602908)
		(end 395.934946 -297.890184)
		(width 0.18288)
		(layer "In2.Cu")
		(net "M_F_CPU0_SA_DQS_DN<0>")
	)
	(segment
		(start 413.558482 -313.31789)
		(end 413.530288 -313.289696)
		(width 0.16002)
		(layer "In2.Cu")
		(net "M_F_CPU0_SA_DQS_DN<0>")
	)
	(segment
		(start 395.934946 -299.949108)
		(end 395.934946 -299.400468)
		(width 0.18288)
		(layer "In2.Cu")
		(net "M_F_CPU0_SA_DQS_DN<0>")
	)
	(segment
		(start 410.387038 -312.75401)
		(end 410.077158 -312.44413)
		(width 0.18288)
		(layer "In2.Cu")
		(net "M_F_CPU0_SA_DQS_DN<0>")
	)
	(segment
		(start 395.934946 -303.439068)
		(end 396.059406 -303.314608)
		(width 0.18288)
		(layer "In2.Cu")
		(net "M_F_CPU0_SA_DQS_DN<0>")
	)
	(segment
		(start 386.744972 -278.654002)
		(end 386.742432 -278.652478)
		(width 0.088646)
		(layer "In2.Cu")
		(net "M_F_CPU0_SA_DQS_DN<0>")
	)
	(segment
		(start 420.480998 -312.321702)
		(end 420.296594 -312.321702)
		(width 0.18288)
		(layer "In2.Cu")
		(net "M_F_CPU0_SA_DQS_DN<0>")
	)
	(segment
		(start 396.059406 -301.419768)
		(end 395.934946 -301.295308)
		(width 0.18288)
		(layer "In2.Cu")
		(net "M_F_CPU0_SA_DQS_DN<0>")
	)
	(segment
		(start 409.820364 -312.187336)
		(end 409.619958 -311.98693)
		(width 0.18288)
		(layer "In2.Cu")
		(net "M_F_CPU0_SA_DQS_DN<0>")
	)
	(segment
		(start 419.0619 -312.564018)
		(end 417.77285 -312.564018)
		(width 0.18288)
		(layer "In2.Cu")
		(net "M_F_CPU0_SA_DQS_DN<0>")
	)
	(segment
		(start 396.059406 -302.765968)
		(end 395.934946 -302.641508)
		(width 0.18288)
		(layer "In2.Cu")
		(net "M_F_CPU0_SA_DQS_DN<0>")
	)
	(segment
		(start 384.877564 -278.66086)
		(end 384.862832 -278.652224)
		(width 0.088646)
		(layer "In2.Cu")
		(net "M_F_CPU0_SA_DQS_DN<0>")
	)
	(segment
		(start 417.546536 -312.35396)
		(end 417.546536 -312.337704)
		(width 0.16002)
		(layer "In2.Cu")
		(net "M_F_CPU0_SA_DQS_DN<0>")
	)
	(segment
		(start 407.489152 -313.38647)
		(end 406.092152 -313.38647)
		(width 0.18288)
		(layer "In2.Cu")
		(net "M_F_CPU0_SA_DQS_DN<0>")
	)
	(segment
		(start 386.754624 -278.659336)
		(end 386.744972 -278.654002)
		(width 0.088646)
		(layer "In2.Cu")
		(net "M_F_CPU0_SA_DQS_DN<0>")
	)
	(segment
		(start 387.53542 -278.72182)
		(end 386.983986 -278.72182)
		(width 0.088646)
		(layer "In2.Cu")
		(net "M_F_CPU0_SA_DQS_DN<0>")
	)
	(segment
		(start 405.794972 -313.08929)
		(end 405.766778 -313.061096)
		(width 0.16002)
		(layer "In2.Cu")
		(net "M_F_CPU0_SA_DQS_DN<0>")
	)
	(segment
		(start 395.934946 -303.987708)
		(end 395.934946 -303.439068)
		(width 0.18288)
		(layer "In2.Cu")
		(net "M_F_CPU0_SA_DQS_DN<0>")
	)
	(segment
		(start 416.725608 -312.082942)
		(end 416.016186 -312.792364)
		(width 0.18288)
		(layer "In2.Cu")
		(net "M_F_CPU0_SA_DQS_DN<0>")
	)
	(segment
		(start 415.57067 -312.792364)
		(end 415.301938 -313.061096)
		(width 0.18288)
		(layer "In2.Cu")
		(net "M_F_CPU0_SA_DQS_DN<0>")
	)
	(segment
		(start 396.059406 -301.968408)
		(end 396.059406 -301.419768)
		(width 0.18288)
		(layer "In2.Cu")
		(net "M_F_CPU0_SA_DQS_DN<0>")
	)
	(segment
		(start 417.77285 -312.564018)
		(end 417.73348 -312.524648)
		(width 0.18288)
		(layer "In2.Cu")
		(net "M_F_CPU0_SA_DQS_DN<0>")
	)
	(arc
		(start 384.862832 -278.652224)
		(mid 384.586357 -278.584904)
		(end 384.31216 -278.66086)
		(width 0.088646)
		(layer "In2.Cu")
		(net "M_F_CPU0_SA_DQS_DN<0>")
	)
	(arc
		(start 386.983986 -278.72182)
		(mid 386.866293 -278.706178)
		(end 386.756656 -278.660606)
		(width 0.088646)
		(layer "In2.Cu")
		(net "M_F_CPU0_SA_DQS_DN<0>")
	)
	(arc
		(start 384.31216 -278.66086)
		(mid 384.124962 -278.711003)
		(end 383.937764 -278.66086)
		(width 0.088646)
		(layer "In2.Cu")
		(net "M_F_CPU0_SA_DQS_DN<0>")
	)
	(arc
		(start 383.750312 -278.322278)
		(mid 383.671093 -278.047593)
		(end 383.46761 -277.84679)
		(width 0.088646)
		(layer "In2.Cu")
		(net "M_F_CPU0_SA_DQS_DN<0>")
	)
	(arc
		(start 382.90246 -277.84679)
		(mid 382.715262 -277.896933)
		(end 382.528064 -277.84679)
		(width 0.088646)
		(layer "In2.Cu")
		(net "M_F_CPU0_SA_DQS_DN<0>")
	)
	(arc
		(start 385.25196 -278.66086)
		(mid 385.064762 -278.711003)
		(end 384.877564 -278.66086)
		(width 0.088646)
		(layer "In2.Cu")
		(net "M_F_CPU0_SA_DQS_DN<0>")
	)
	(arc
		(start 386.742432 -278.652478)
		(mid 386.46613 -278.585125)
		(end 386.192014 -278.66086)
		(width 0.088646)
		(layer "In2.Cu")
		(net "M_F_CPU0_SA_DQS_DN<0>")
	)
	(arc
		(start 383.928874 -278.65578)
		(mid 383.79796 -278.51942)
		(end 383.750312 -278.336502)
		(width 0.088646)
		(layer "In2.Cu")
		(net "M_F_CPU0_SA_DQS_DN<0>")
	)
	(arc
		(start 383.457196 -277.840694)
		(mid 383.179018 -277.771002)
		(end 382.90246 -277.84679)
		(width 0.088646)
		(layer "In2.Cu")
		(net "M_F_CPU0_SA_DQS_DN<0>")
	)
	(arc
		(start 385.802632 -278.652224)
		(mid 385.526157 -278.584904)
		(end 385.25196 -278.66086)
		(width 0.088646)
		(layer "In2.Cu")
		(net "M_F_CPU0_SA_DQS_DN<0>")
	)
	(arc
		(start 381.579374 -277.84171)
		(mid 381.463565 -277.729781)
		(end 381.405384 -277.579582)
		(width 0.088646)
		(layer "In2.Cu")
		(net "M_F_CPU0_SA_DQS_DN<0>")
	)
	(arc
		(start 382.528064 -277.84679)
		(mid 382.245362 -277.771048)
		(end 381.96266 -277.84679)
		(width 0.088646)
		(layer "In2.Cu")
		(net "M_F_CPU0_SA_DQS_DN<0>")
	)
	(arc
		(start 381.96266 -277.84679)
		(mid 381.775462 -277.896933)
		(end 381.588264 -277.84679)
		(width 0.088646)
		(layer "In2.Cu")
		(net "M_F_CPU0_SA_DQS_DN<0>")
	)
	(arc
		(start 386.19176 -278.66086)
		(mid 386.004562 -278.711003)
		(end 385.817364 -278.66086)
		(width 0.088646)
		(layer "In2.Cu")
		(net "M_F_CPU0_SA_DQS_DN<0>")
	)
	(segment
		(start 424.391582 -304.841656)
		(end 424.273472 -304.959766)
		(width 0.20066)
		(layer "F.Cu")
		(net "M_F_CPU0_SA_DQ<9>")
	)
	(segment
		(start 423.361612 -305.266598)
		(end 421.840914 -305.266598)
		(width 0.20066)
		(layer "F.Cu")
		(net "M_F_CPU0_SA_DQ<9>")
	)
	(segment
		(start 427.792896 -305.266852)
		(end 427.36135 -304.835306)
		(width 0.20066)
		(layer "F.Cu")
		(net "M_F_CPU0_SA_DQ<9>")
	)
	(segment
		(start 424.273472 -305.327304)
		(end 424.085512 -305.515264)
		(width 0.20066)
		(layer "F.Cu")
		(net "M_F_CPU0_SA_DQ<9>")
	)
	(segment
		(start 429.38446 -305.266852)
		(end 427.792896 -305.266852)
		(width 0.20066)
		(layer "F.Cu")
		(net "M_F_CPU0_SA_DQ<9>")
	)
	(segment
		(start 426.945044 -304.841656)
		(end 424.756326 -304.841656)
		(width 0.1016)
		(layer "F.Cu")
		(net "M_F_CPU0_SA_DQ<9>")
	)
	(segment
		(start 424.085512 -305.515264)
		(end 423.610278 -305.515264)
		(width 0.20066)
		(layer "F.Cu")
		(net "M_F_CPU0_SA_DQ<9>")
	)
	(segment
		(start 424.73626 -304.841656)
		(end 424.391582 -304.841656)
		(width 0.20066)
		(layer "F.Cu")
		(net "M_F_CPU0_SA_DQ<9>")
	)
	(segment
		(start 378.016516 -270.475456)
		(end 378.016516 -271.011142)
		(width 0.20066)
		(layer "F.Cu")
		(net "M_F_CPU0_SA_DQ<9>")
	)
	(segment
		(start 427.36135 -304.835306)
		(end 426.951394 -304.835306)
		(width 0.20066)
		(layer "F.Cu")
		(net "M_F_CPU0_SA_DQ<9>")
	)
	(segment
		(start 429.384714 -305.266598)
		(end 429.38446 -305.266852)
		(width 0.20066)
		(layer "F.Cu")
		(net "M_F_CPU0_SA_DQ<9>")
	)
	(segment
		(start 424.273472 -304.959766)
		(end 424.273472 -305.327304)
		(width 0.20066)
		(layer "F.Cu")
		(net "M_F_CPU0_SA_DQ<9>")
	)
	(segment
		(start 426.951394 -304.835306)
		(end 426.945044 -304.841656)
		(width 0.1016)
		(layer "F.Cu")
		(net "M_F_CPU0_SA_DQ<9>")
	)
	(segment
		(start 424.756326 -304.841656)
		(end 424.73626 -304.841656)
		(width 0.101854)
		(layer "F.Cu")
		(net "M_F_CPU0_SA_DQ<9>")
	)
	(segment
		(start 421.840914 -305.266598)
		(end 420.736014 -305.266598)
		(width 0.20066)
		(layer "F.Cu")
		(net "M_F_CPU0_SA_DQ<9>")
	)
	(segment
		(start 423.610278 -305.515264)
		(end 423.361612 -305.266598)
		(width 0.20066)
		(layer "F.Cu")
		(net "M_F_CPU0_SA_DQ<9>")
	)
	(segment
		(start 378.016516 -271.011142)
		(end 378.016262 -271.011396)
		(width 0.20066)
		(layer "F.Cu")
		(net "M_F_CPU0_SA_DQ<9>")
	)
	(segment
		(start 387.503162 -273.005296)
		(end 387.392672 -273.005296)
		(width 0.18288)
		(layer "In4.Cu")
		(net "M_F_CPU0_SA_DQ<9>")
	)
	(segment
		(start 384.327146 -271.50949)
		(end 384.312414 -271.500854)
		(width 0.088646)
		(layer "In4.Cu")
		(net "M_F_CPU0_SA_DQ<9>")
	)
	(segment
		(start 412.088076 -302.533812)
		(end 411.829504 -302.533812)
		(width 0.18288)
		(layer "In4.Cu")
		(net "M_F_CPU0_SA_DQ<9>")
	)
	(segment
		(start 379.244606 -271.497552)
		(end 379.238764 -271.500854)
		(width 0.088646)
		(layer "In4.Cu")
		(net "M_F_CPU0_SA_DQ<9>")
	)
	(segment
		(start 412.50235 -302.948086)
		(end 412.088076 -302.533812)
		(width 0.18288)
		(layer "In4.Cu")
		(net "M_F_CPU0_SA_DQ<9>")
	)
	(segment
		(start 407.701242 -300.705266)
		(end 407.342848 -300.346872)
		(width 0.18288)
		(layer "In4.Cu")
		(net "M_F_CPU0_SA_DQ<9>")
	)
	(segment
		(start 410.937456 -302.703484)
		(end 410.937456 -302.444912)
		(width 0.18288)
		(layer "In4.Cu")
		(net "M_F_CPU0_SA_DQ<9>")
	)
	(segment
		(start 385.261104 -271.505934)
		(end 385.252214 -271.500854)
		(width 0.088646)
		(layer "In4.Cu")
		(net "M_F_CPU0_SA_DQ<9>")
	)
	(segment
		(start 419.238938 -305.71313)
		(end 418.278564 -304.752756)
		(width 0.18288)
		(layer "In4.Cu")
		(net "M_F_CPU0_SA_DQ<9>")
	)
	(segment
		(start 380.184406 -271.497552)
		(end 380.178564 -271.500854)
		(width 0.088646)
		(layer "In4.Cu")
		(net "M_F_CPU0_SA_DQ<9>")
	)
	(segment
		(start 386.287264 -272.314924)
		(end 386.272532 -272.32356)
		(width 0.088646)
		(layer "In4.Cu")
		(net "M_F_CPU0_SA_DQ<9>")
	)
	(segment
		(start 410.937456 -302.444912)
		(end 411.33903 -302.043338)
		(width 0.18288)
		(layer "In4.Cu")
		(net "M_F_CPU0_SA_DQ<9>")
	)
	(segment
		(start 382.064006 -271.497552)
		(end 382.058164 -271.500854)
		(width 0.088646)
		(layer "In4.Cu")
		(net "M_F_CPU0_SA_DQ<9>")
	)
	(segment
		(start 405.873966 -297.970194)
		(end 405.347932 -297.970194)
		(width 0.18288)
		(layer "In4.Cu")
		(net "M_F_CPU0_SA_DQ<9>")
	)
	(segment
		(start 387.131814 -273.005296)
		(end 386.849112 -272.722594)
		(width 0.088646)
		(layer "In4.Cu")
		(net "M_F_CPU0_SA_DQ<9>")
	)
	(segment
		(start 420.289482 -305.71313)
		(end 419.238938 -305.71313)
		(width 0.18288)
		(layer "In4.Cu")
		(net "M_F_CPU0_SA_DQ<9>")
	)
	(segment
		(start 408.521154 -300.705266)
		(end 407.701242 -300.705266)
		(width 0.18288)
		(layer "In4.Cu")
		(net "M_F_CPU0_SA_DQ<9>")
	)
	(segment
		(start 383.001774 -271.498822)
		(end 382.997964 -271.500854)
		(width 0.088646)
		(layer "In4.Cu")
		(net "M_F_CPU0_SA_DQ<9>")
	)
	(segment
		(start 418.278564 -304.752756)
		(end 416.254184 -304.752756)
		(width 0.18288)
		(layer "In4.Cu")
		(net "M_F_CPU0_SA_DQ<9>")
	)
	(segment
		(start 381.118364 -271.500854)
		(end 381.112522 -271.50441)
		(width 0.088646)
		(layer "In4.Cu")
		(net "M_F_CPU0_SA_DQ<9>")
	)
	(segment
		(start 416.254184 -304.752756)
		(end 416.067494 -304.939446)
		(width 0.18288)
		(layer "In4.Cu")
		(net "M_F_CPU0_SA_DQ<9>")
	)
	(segment
		(start 394.783564 -280.119074)
		(end 389.740394 -275.075904)
		(width 0.18288)
		(layer "In4.Cu")
		(net "M_F_CPU0_SA_DQ<9>")
	)
	(segment
		(start 416.067494 -304.939446)
		(end 415.134552 -304.939446)
		(width 0.18288)
		(layer "In4.Cu")
		(net "M_F_CPU0_SA_DQ<9>")
	)
	(segment
		(start 378.673614 -271.500854)
		(end 378.595128 -271.455642)
		(width 0.088646)
		(layer "In4.Cu")
		(net "M_F_CPU0_SA_DQ<9>")
	)
	(segment
		(start 411.33903 -301.784766)
		(end 410.996638 -301.442374)
		(width 0.18288)
		(layer "In4.Cu")
		(net "M_F_CPU0_SA_DQ<9>")
	)
	(segment
		(start 411.42793 -302.935386)
		(end 411.169358 -302.935386)
		(width 0.18288)
		(layer "In4.Cu")
		(net "M_F_CPU0_SA_DQ<9>")
	)
	(segment
		(start 420.736014 -305.266598)
		(end 420.289482 -305.71313)
		(width 0.18288)
		(layer "In4.Cu")
		(net "M_F_CPU0_SA_DQ<9>")
	)
	(segment
		(start 385.439666 -271.84731)
		(end 385.439666 -271.825212)
		(width 0.088646)
		(layer "In4.Cu")
		(net "M_F_CPU0_SA_DQ<9>")
	)
	(segment
		(start 380.178564 -271.500854)
		(end 380.172722 -271.50441)
		(width 0.088646)
		(layer "In4.Cu")
		(net "M_F_CPU0_SA_DQ<9>")
	)
	(segment
		(start 413.143192 -302.948086)
		(end 412.50235 -302.948086)
		(width 0.18288)
		(layer "In4.Cu")
		(net "M_F_CPU0_SA_DQ<9>")
	)
	(segment
		(start 389.740394 -275.075904)
		(end 389.57377 -275.075904)
		(width 0.18288)
		(layer "In4.Cu")
		(net "M_F_CPU0_SA_DQ<9>")
	)
	(segment
		(start 382.997964 -271.500854)
		(end 382.992122 -271.50441)
		(width 0.088646)
		(layer "In4.Cu")
		(net "M_F_CPU0_SA_DQ<9>")
	)
	(segment
		(start 381.124206 -271.497552)
		(end 381.118364 -271.500854)
		(width 0.088646)
		(layer "In4.Cu")
		(net "M_F_CPU0_SA_DQ<9>")
	)
	(segment
		(start 409.258262 -301.442374)
		(end 408.521154 -300.705266)
		(width 0.18288)
		(layer "In4.Cu")
		(net "M_F_CPU0_SA_DQ<9>")
	)
	(segment
		(start 407.342848 -300.346872)
		(end 407.342848 -299.439076)
		(width 0.18288)
		(layer "In4.Cu")
		(net "M_F_CPU0_SA_DQ<9>")
	)
	(segment
		(start 387.392672 -273.005296)
		(end 387.131814 -273.005296)
		(width 0.088646)
		(layer "In4.Cu")
		(net "M_F_CPU0_SA_DQ<9>")
	)
	(segment
		(start 382.058164 -271.500854)
		(end 382.052322 -271.50441)
		(width 0.088646)
		(layer "In4.Cu")
		(net "M_F_CPU0_SA_DQ<9>")
	)
	(segment
		(start 389.57377 -275.075904)
		(end 387.503162 -273.005296)
		(width 0.18288)
		(layer "In4.Cu")
		(net "M_F_CPU0_SA_DQ<9>")
	)
	(segment
		(start 410.996638 -301.442374)
		(end 409.258262 -301.442374)
		(width 0.18288)
		(layer "In4.Cu")
		(net "M_F_CPU0_SA_DQ<9>")
	)
	(segment
		(start 379.238764 -271.500854)
		(end 379.232922 -271.50441)
		(width 0.088646)
		(layer "In4.Cu")
		(net "M_F_CPU0_SA_DQ<9>")
	)
	(segment
		(start 383.387346 -271.50949)
		(end 383.372614 -271.500854)
		(width 0.088646)
		(layer "In4.Cu")
		(net "M_F_CPU0_SA_DQ<9>")
	)
	(segment
		(start 399.9357 -292.557962)
		(end 394.783564 -280.119074)
		(width 0.18288)
		(layer "In4.Cu")
		(net "M_F_CPU0_SA_DQ<9>")
	)
	(segment
		(start 386.67055 -272.320004)
		(end 386.66166 -272.314924)
		(width 0.088646)
		(layer "In4.Cu")
		(net "M_F_CPU0_SA_DQ<9>")
	)
	(segment
		(start 407.342848 -299.439076)
		(end 405.873966 -297.970194)
		(width 0.18288)
		(layer "In4.Cu")
		(net "M_F_CPU0_SA_DQ<9>")
	)
	(segment
		(start 386.849112 -272.722594)
		(end 386.849112 -272.639282)
		(width 0.088646)
		(layer "In4.Cu")
		(net "M_F_CPU0_SA_DQ<9>")
	)
	(segment
		(start 405.347932 -297.970194)
		(end 399.9357 -292.557962)
		(width 0.18288)
		(layer "In4.Cu")
		(net "M_F_CPU0_SA_DQ<9>")
	)
	(segment
		(start 411.829504 -302.533812)
		(end 411.42793 -302.935386)
		(width 0.18288)
		(layer "In4.Cu")
		(net "M_F_CPU0_SA_DQ<9>")
	)
	(segment
		(start 415.134552 -304.939446)
		(end 413.143192 -302.948086)
		(width 0.18288)
		(layer "In4.Cu")
		(net "M_F_CPU0_SA_DQ<9>")
	)
	(segment
		(start 411.169358 -302.935386)
		(end 410.937456 -302.703484)
		(width 0.18288)
		(layer "In4.Cu")
		(net "M_F_CPU0_SA_DQ<9>")
	)
	(segment
		(start 411.33903 -302.043338)
		(end 411.33903 -301.784766)
		(width 0.18288)
		(layer "In4.Cu")
		(net "M_F_CPU0_SA_DQ<9>")
	)
	(arc
		(start 383.938018 -271.500854)
		(mid 383.663819 -271.576689)
		(end 383.387346 -271.50949)
		(width 0.088646)
		(layer "In4.Cu")
		(net "M_F_CPU0_SA_DQ<9>")
	)
	(arc
		(start 380.172722 -271.50441)
		(mid 379.892587 -271.576693)
		(end 379.613414 -271.500854)
		(width 0.088646)
		(layer "In4.Cu")
		(net "M_F_CPU0_SA_DQ<9>")
	)
	(arc
		(start 386.849112 -272.639282)
		(mid 386.801433 -272.456382)
		(end 386.67055 -272.320004)
		(width 0.088646)
		(layer "In4.Cu")
		(net "M_F_CPU0_SA_DQ<9>")
	)
	(arc
		(start 382.992122 -271.50441)
		(mid 382.711987 -271.576693)
		(end 382.432814 -271.500854)
		(width 0.088646)
		(layer "In4.Cu")
		(net "M_F_CPU0_SA_DQ<9>")
	)
	(arc
		(start 383.372614 -271.500854)
		(mid 383.187464 -271.450716)
		(end 383.001774 -271.498822)
		(width 0.088646)
		(layer "In4.Cu")
		(net "M_F_CPU0_SA_DQ<9>")
	)
	(arc
		(start 386.66166 -272.314924)
		(mid 386.474462 -272.264781)
		(end 386.287264 -272.314924)
		(width 0.088646)
		(layer "In4.Cu")
		(net "M_F_CPU0_SA_DQ<9>")
	)
	(arc
		(start 384.312414 -271.500854)
		(mid 384.125216 -271.450711)
		(end 383.938018 -271.500854)
		(width 0.088646)
		(layer "In4.Cu")
		(net "M_F_CPU0_SA_DQ<9>")
	)
	(arc
		(start 384.877818 -271.500854)
		(mid 384.603619 -271.576689)
		(end 384.327146 -271.50949)
		(width 0.088646)
		(layer "In4.Cu")
		(net "M_F_CPU0_SA_DQ<9>")
	)
	(arc
		(start 379.232922 -271.50441)
		(mid 378.952787 -271.576693)
		(end 378.673614 -271.500854)
		(width 0.088646)
		(layer "In4.Cu")
		(net "M_F_CPU0_SA_DQ<9>")
	)
	(arc
		(start 385.72186 -272.314924)
		(mid 385.520578 -272.117437)
		(end 385.439666 -271.84731)
		(width 0.088646)
		(layer "In4.Cu")
		(net "M_F_CPU0_SA_DQ<9>")
	)
	(arc
		(start 382.052322 -271.50441)
		(mid 381.772187 -271.576693)
		(end 381.493014 -271.500854)
		(width 0.088646)
		(layer "In4.Cu")
		(net "M_F_CPU0_SA_DQ<9>")
	)
	(arc
		(start 382.432814 -271.500854)
		(mid 382.24886 -271.450725)
		(end 382.064006 -271.497552)
		(width 0.088646)
		(layer "In4.Cu")
		(net "M_F_CPU0_SA_DQ<9>")
	)
	(arc
		(start 386.272532 -272.32356)
		(mid 385.996091 -272.390726)
		(end 385.72186 -272.314924)
		(width 0.088646)
		(layer "In4.Cu")
		(net "M_F_CPU0_SA_DQ<9>")
	)
	(arc
		(start 381.493014 -271.500854)
		(mid 381.30906 -271.450725)
		(end 381.124206 -271.497552)
		(width 0.088646)
		(layer "In4.Cu")
		(net "M_F_CPU0_SA_DQ<9>")
	)
	(arc
		(start 381.112522 -271.50441)
		(mid 380.832387 -271.576693)
		(end 380.553214 -271.500854)
		(width 0.088646)
		(layer "In4.Cu")
		(net "M_F_CPU0_SA_DQ<9>")
	)
	(arc
		(start 378.595128 -271.455642)
		(mid 378.29103 -271.252629)
		(end 378.016262 -271.011396)
		(width 0.088646)
		(layer "In4.Cu")
		(net "M_F_CPU0_SA_DQ<9>")
	)
	(arc
		(start 385.252214 -271.500854)
		(mid 385.065016 -271.450711)
		(end 384.877818 -271.500854)
		(width 0.088646)
		(layer "In4.Cu")
		(net "M_F_CPU0_SA_DQ<9>")
	)
	(arc
		(start 380.553214 -271.500854)
		(mid 380.36926 -271.450725)
		(end 380.184406 -271.497552)
		(width 0.088646)
		(layer "In4.Cu")
		(net "M_F_CPU0_SA_DQ<9>")
	)
	(arc
		(start 385.439666 -271.825212)
		(mid 385.391987 -271.642312)
		(end 385.261104 -271.505934)
		(width 0.088646)
		(layer "In4.Cu")
		(net "M_F_CPU0_SA_DQ<9>")
	)
	(arc
		(start 379.613414 -271.500854)
		(mid 379.42946 -271.450725)
		(end 379.244606 -271.497552)
		(width 0.088646)
		(layer "In4.Cu")
		(net "M_F_CPU0_SA_DQ<9>")
	)
	(segment
		(start 426.951394 -306.535328)
		(end 426.945044 -306.541678)
		(width 0.1016)
		(layer "F.Cu")
		(net "M_F_CPU0_SA_DQ<8>")
	)
	(segment
		(start 378.486162 -271.289272)
		(end 378.486416 -271.825212)
		(width 0.20066)
		(layer "F.Cu")
		(net "M_F_CPU0_SA_DQ<8>")
	)
	(segment
		(start 424.73626 -306.541678)
		(end 424.391582 -306.541678)
		(width 0.20066)
		(layer "F.Cu")
		(net "M_F_CPU0_SA_DQ<8>")
	)
	(segment
		(start 424.273472 -307.027326)
		(end 424.085512 -307.215286)
		(width 0.20066)
		(layer "F.Cu")
		(net "M_F_CPU0_SA_DQ<8>")
	)
	(segment
		(start 424.391582 -306.541678)
		(end 424.273472 -306.659788)
		(width 0.20066)
		(layer "F.Cu")
		(net "M_F_CPU0_SA_DQ<8>")
	)
	(segment
		(start 429.38446 -306.966874)
		(end 427.792896 -306.966874)
		(width 0.20066)
		(layer "F.Cu")
		(net "M_F_CPU0_SA_DQ<8>")
	)
	(segment
		(start 423.610278 -307.215286)
		(end 423.361612 -306.96662)
		(width 0.20066)
		(layer "F.Cu")
		(net "M_F_CPU0_SA_DQ<8>")
	)
	(segment
		(start 426.945044 -306.541678)
		(end 424.78325 -306.541678)
		(width 0.1016)
		(layer "F.Cu")
		(net "M_F_CPU0_SA_DQ<8>")
	)
	(segment
		(start 429.384714 -306.96662)
		(end 429.38446 -306.966874)
		(width 0.20066)
		(layer "F.Cu")
		(net "M_F_CPU0_SA_DQ<8>")
	)
	(segment
		(start 423.361612 -306.96662)
		(end 421.840914 -306.96662)
		(width 0.20066)
		(layer "F.Cu")
		(net "M_F_CPU0_SA_DQ<8>")
	)
	(segment
		(start 424.085512 -307.215286)
		(end 423.610278 -307.215286)
		(width 0.20066)
		(layer "F.Cu")
		(net "M_F_CPU0_SA_DQ<8>")
	)
	(segment
		(start 424.273472 -306.659788)
		(end 424.273472 -307.027326)
		(width 0.20066)
		(layer "F.Cu")
		(net "M_F_CPU0_SA_DQ<8>")
	)
	(segment
		(start 424.78325 -306.541678)
		(end 424.73626 -306.541678)
		(width 0.101854)
		(layer "F.Cu")
		(net "M_F_CPU0_SA_DQ<8>")
	)
	(segment
		(start 427.792896 -306.966874)
		(end 427.36135 -306.535328)
		(width 0.20066)
		(layer "F.Cu")
		(net "M_F_CPU0_SA_DQ<8>")
	)
	(segment
		(start 421.840914 -306.96662)
		(end 420.736014 -306.96662)
		(width 0.20066)
		(layer "F.Cu")
		(net "M_F_CPU0_SA_DQ<8>")
	)
	(segment
		(start 427.36135 -306.535328)
		(end 426.951394 -306.535328)
		(width 0.20066)
		(layer "F.Cu")
		(net "M_F_CPU0_SA_DQ<8>")
	)
	(segment
		(start 409.41371 -303.99228)
		(end 406.011634 -300.590204)
		(width 0.18288)
		(layer "In4.Cu")
		(net "M_F_CPU0_SA_DQ<8>")
	)
	(segment
		(start 418.058854 -308.335172)
		(end 417.875974 -308.152292)
		(width 0.18288)
		(layer "In4.Cu")
		(net "M_F_CPU0_SA_DQ<8>")
	)
	(segment
		(start 418.569394 -308.152292)
		(end 418.386514 -308.335172)
		(width 0.18288)
		(layer "In4.Cu")
		(net "M_F_CPU0_SA_DQ<8>")
	)
	(segment
		(start 417.693094 -307.471826)
		(end 417.100258 -307.471826)
		(width 0.18288)
		(layer "In4.Cu")
		(net "M_F_CPU0_SA_DQ<8>")
	)
	(segment
		(start 406.011634 -300.590204)
		(end 405.460962 -300.590204)
		(width 0.18288)
		(layer "In4.Cu")
		(net "M_F_CPU0_SA_DQ<8>")
	)
	(segment
		(start 381.023114 -272.31467)
		(end 381.018542 -272.31213)
		(width 0.088646)
		(layer "In4.Cu")
		(net "M_F_CPU0_SA_DQ<8>")
	)
	(segment
		(start 417.875974 -307.654706)
		(end 417.693094 -307.471826)
		(width 0.18288)
		(layer "In4.Cu")
		(net "M_F_CPU0_SA_DQ<8>")
	)
	(segment
		(start 415.294064 -306.733956)
		(end 414.13176 -305.571652)
		(width 0.18288)
		(layer "In4.Cu")
		(net "M_F_CPU0_SA_DQ<8>")
	)
	(segment
		(start 381.962914 -272.31467)
		(end 381.958342 -272.31213)
		(width 0.088646)
		(layer "In4.Cu")
		(net "M_F_CPU0_SA_DQ<8>")
	)
	(segment
		(start 388.733792 -275.496274)
		(end 388.733792 -275.417534)
		(width 0.18288)
		(layer "In4.Cu")
		(net "M_F_CPU0_SA_DQ<8>")
	)
	(segment
		(start 388.733792 -275.417534)
		(end 387.316472 -274.000214)
		(width 0.18288)
		(layer "In4.Cu")
		(net "M_F_CPU0_SA_DQ<8>")
	)
	(segment
		(start 387.119368 -273.80311)
		(end 386.86613 -273.80311)
		(width 0.088646)
		(layer "In4.Cu")
		(net "M_F_CPU0_SA_DQ<8>")
	)
	(segment
		(start 382.902714 -272.31467)
		(end 382.898142 -272.31213)
		(width 0.088646)
		(layer "In4.Cu")
		(net "M_F_CPU0_SA_DQ<8>")
	)
	(segment
		(start 380.083314 -272.31467)
		(end 380.078742 -272.31213)
		(width 0.088646)
		(layer "In4.Cu")
		(net "M_F_CPU0_SA_DQ<8>")
	)
	(segment
		(start 420.736014 -306.96662)
		(end 420.462964 -307.23967)
		(width 0.18288)
		(layer "In4.Cu")
		(net "M_F_CPU0_SA_DQ<8>")
	)
	(segment
		(start 393.696444 -280.458926)
		(end 388.733792 -275.496274)
		(width 0.18288)
		(layer "In4.Cu")
		(net "M_F_CPU0_SA_DQ<8>")
	)
	(segment
		(start 384.407664 -272.314924)
		(end 384.392932 -272.32356)
		(width 0.088646)
		(layer "In4.Cu")
		(net "M_F_CPU0_SA_DQ<8>")
	)
	(segment
		(start 399.611088 -294.74033)
		(end 393.696444 -280.458926)
		(width 0.18288)
		(layer "In4.Cu")
		(net "M_F_CPU0_SA_DQ<8>")
	)
	(segment
		(start 417.875974 -308.152292)
		(end 417.875974 -307.654706)
		(width 0.18288)
		(layer "In4.Cu")
		(net "M_F_CPU0_SA_DQ<8>")
	)
	(segment
		(start 387.316472 -274.000214)
		(end 387.119368 -273.80311)
		(width 0.088646)
		(layer "In4.Cu")
		(net "M_F_CPU0_SA_DQ<8>")
	)
	(segment
		(start 384.79095 -272.320004)
		(end 384.78206 -272.314924)
		(width 0.088646)
		(layer "In4.Cu")
		(net "M_F_CPU0_SA_DQ<8>")
	)
	(segment
		(start 418.386514 -308.335172)
		(end 418.058854 -308.335172)
		(width 0.18288)
		(layer "In4.Cu")
		(net "M_F_CPU0_SA_DQ<8>")
	)
	(segment
		(start 412.533084 -304.828956)
		(end 411.463744 -304.828956)
		(width 0.18288)
		(layer "In4.Cu")
		(net "M_F_CPU0_SA_DQ<8>")
	)
	(segment
		(start 386.86613 -273.80311)
		(end 386.19176 -273.12874)
		(width 0.088646)
		(layer "In4.Cu")
		(net "M_F_CPU0_SA_DQ<8>")
	)
	(segment
		(start 413.27578 -305.571652)
		(end 412.533084 -304.828956)
		(width 0.18288)
		(layer "In4.Cu")
		(net "M_F_CPU0_SA_DQ<8>")
	)
	(segment
		(start 405.460962 -300.590204)
		(end 399.611088 -294.74033)
		(width 0.18288)
		(layer "In4.Cu")
		(net "M_F_CPU0_SA_DQ<8>")
	)
	(segment
		(start 418.569394 -307.654706)
		(end 418.569394 -308.152292)
		(width 0.18288)
		(layer "In4.Cu")
		(net "M_F_CPU0_SA_DQ<8>")
	)
	(segment
		(start 416.362388 -306.733956)
		(end 415.294064 -306.733956)
		(width 0.18288)
		(layer "In4.Cu")
		(net "M_F_CPU0_SA_DQ<8>")
	)
	(segment
		(start 419.90264 -307.471826)
		(end 418.752274 -307.471826)
		(width 0.18288)
		(layer "In4.Cu")
		(net "M_F_CPU0_SA_DQ<8>")
	)
	(segment
		(start 383.84226 -272.314924)
		(end 383.842514 -272.31467)
		(width 0.088646)
		(layer "In4.Cu")
		(net "M_F_CPU0_SA_DQ<8>")
	)
	(segment
		(start 420.462964 -307.23967)
		(end 419.90264 -307.471826)
		(width 0.18288)
		(layer "In4.Cu")
		(net "M_F_CPU0_SA_DQ<8>")
	)
	(segment
		(start 384.969512 -272.649188)
		(end 384.969512 -272.639282)
		(width 0.088646)
		(layer "In4.Cu")
		(net "M_F_CPU0_SA_DQ<8>")
	)
	(segment
		(start 414.13176 -305.571652)
		(end 413.27578 -305.571652)
		(width 0.18288)
		(layer "In4.Cu")
		(net "M_F_CPU0_SA_DQ<8>")
	)
	(segment
		(start 418.752274 -307.471826)
		(end 418.569394 -307.654706)
		(width 0.18288)
		(layer "In4.Cu")
		(net "M_F_CPU0_SA_DQ<8>")
	)
	(segment
		(start 380.09068 -272.318988)
		(end 380.083314 -272.31467)
		(width 0.088646)
		(layer "In4.Cu")
		(net "M_F_CPU0_SA_DQ<8>")
	)
	(segment
		(start 381.97028 -272.318988)
		(end 381.962914 -272.31467)
		(width 0.088646)
		(layer "In4.Cu")
		(net "M_F_CPU0_SA_DQ<8>")
	)
	(segment
		(start 411.463744 -304.828956)
		(end 410.627068 -303.99228)
		(width 0.18288)
		(layer "In4.Cu")
		(net "M_F_CPU0_SA_DQ<8>")
	)
	(segment
		(start 382.907286 -272.317464)
		(end 382.902714 -272.31467)
		(width 0.088646)
		(layer "In4.Cu")
		(net "M_F_CPU0_SA_DQ<8>")
	)
	(segment
		(start 417.100258 -307.471826)
		(end 416.362388 -306.733956)
		(width 0.18288)
		(layer "In4.Cu")
		(net "M_F_CPU0_SA_DQ<8>")
	)
	(segment
		(start 410.627068 -303.99228)
		(end 409.41371 -303.99228)
		(width 0.18288)
		(layer "In4.Cu")
		(net "M_F_CPU0_SA_DQ<8>")
	)
	(segment
		(start 381.03048 -272.318988)
		(end 381.023114 -272.31467)
		(width 0.088646)
		(layer "In4.Cu")
		(net "M_F_CPU0_SA_DQ<8>")
	)
	(arc
		(start 385.817364 -273.12874)
		(mid 385.534662 -273.204516)
		(end 385.25196 -273.12874)
		(width 0.088646)
		(layer "In4.Cu")
		(net "M_F_CPU0_SA_DQ<8>")
	)
	(arc
		(start 381.018542 -272.31213)
		(mid 380.833157 -272.264492)
		(end 380.648464 -272.31467)
		(width 0.088646)
		(layer "In4.Cu")
		(net "M_F_CPU0_SA_DQ<8>")
	)
	(arc
		(start 383.842514 -272.31467)
		(mid 383.655206 -272.264561)
		(end 383.467864 -272.31467)
		(width 0.088646)
		(layer "In4.Cu")
		(net "M_F_CPU0_SA_DQ<8>")
	)
	(arc
		(start 382.528064 -272.31467)
		(mid 382.249741 -272.390429)
		(end 381.97028 -272.318988)
		(width 0.088646)
		(layer "In4.Cu")
		(net "M_F_CPU0_SA_DQ<8>")
	)
	(arc
		(start 380.648464 -272.31467)
		(mid 380.370141 -272.390429)
		(end 380.09068 -272.318988)
		(width 0.088646)
		(layer "In4.Cu")
		(net "M_F_CPU0_SA_DQ<8>")
	)
	(arc
		(start 379.008894 -272.140426)
		(mid 378.78523 -271.920534)
		(end 378.486416 -271.825212)
		(width 0.088646)
		(layer "In4.Cu")
		(net "M_F_CPU0_SA_DQ<8>")
	)
	(arc
		(start 386.19176 -273.12874)
		(mid 386.004562 -273.078597)
		(end 385.817364 -273.12874)
		(width 0.088646)
		(layer "In4.Cu")
		(net "M_F_CPU0_SA_DQ<8>")
	)
	(arc
		(start 384.969512 -272.639282)
		(mid 384.921833 -272.456382)
		(end 384.79095 -272.320004)
		(width 0.088646)
		(layer "In4.Cu")
		(net "M_F_CPU0_SA_DQ<8>")
	)
	(arc
		(start 384.392932 -272.32356)
		(mid 384.116491 -272.390726)
		(end 383.84226 -272.314924)
		(width 0.088646)
		(layer "In4.Cu")
		(net "M_F_CPU0_SA_DQ<8>")
	)
	(arc
		(start 381.958342 -272.31213)
		(mid 381.772957 -272.264492)
		(end 381.588264 -272.31467)
		(width 0.088646)
		(layer "In4.Cu")
		(net "M_F_CPU0_SA_DQ<8>")
	)
	(arc
		(start 382.898142 -272.31213)
		(mid 382.712757 -272.264492)
		(end 382.528064 -272.31467)
		(width 0.088646)
		(layer "In4.Cu")
		(net "M_F_CPU0_SA_DQ<8>")
	)
	(arc
		(start 383.467864 -272.31467)
		(mid 383.18795 -272.390439)
		(end 382.907286 -272.317464)
		(width 0.088646)
		(layer "In4.Cu")
		(net "M_F_CPU0_SA_DQ<8>")
	)
	(arc
		(start 381.588264 -272.31467)
		(mid 381.309941 -272.390429)
		(end 381.03048 -272.318988)
		(width 0.088646)
		(layer "In4.Cu")
		(net "M_F_CPU0_SA_DQ<8>")
	)
	(arc
		(start 379.708664 -272.31467)
		(mid 379.323588 -272.368782)
		(end 379.008894 -272.140426)
		(width 0.088646)
		(layer "In4.Cu")
		(net "M_F_CPU0_SA_DQ<8>")
	)
	(arc
		(start 380.078742 -272.31213)
		(mid 379.893357 -272.264492)
		(end 379.708664 -272.31467)
		(width 0.088646)
		(layer "In4.Cu")
		(net "M_F_CPU0_SA_DQ<8>")
	)
	(arc
		(start 385.25196 -273.12874)
		(mid 385.047625 -272.926135)
		(end 384.969512 -272.649188)
		(width 0.088646)
		(layer "In4.Cu")
		(net "M_F_CPU0_SA_DQ<8>")
	)
	(arc
		(start 384.78206 -272.314924)
		(mid 384.594862 -272.264781)
		(end 384.407664 -272.314924)
		(width 0.088646)
		(layer "In4.Cu")
		(net "M_F_CPU0_SA_DQ<8>")
	)
	(segment
		(start 431.898552 -307.56479)
		(end 432.15052 -307.816758)
		(width 0.20066)
		(layer "F.Cu")
		(net "M_F_CPU0_SA_DQ<7>")
	)
	(segment
		(start 382.715516 -275.35886)
		(end 382.715516 -275.894546)
		(width 0.20066)
		(layer "F.Cu")
		(net "M_F_CPU0_SA_DQ<7>")
	)
	(segment
		(start 428.367952 -308.248812)
		(end 428.375064 -308.2417)
		(width 0.1016)
		(layer "F.Cu")
		(net "M_F_CPU0_SA_DQ<7>")
	)
	(segment
		(start 431.076354 -308.253892)
		(end 431.280316 -308.04993)
		(width 0.20066)
		(layer "F.Cu")
		(net "M_F_CPU0_SA_DQ<7>")
	)
	(segment
		(start 428.07128 -308.248812)
		(end 428.363126 -308.248812)
		(width 0.20066)
		(layer "F.Cu")
		(net "M_F_CPU0_SA_DQ<7>")
	)
	(segment
		(start 425.940982 -307.816758)
		(end 427.639226 -307.816758)
		(width 0.20066)
		(layer "F.Cu")
		(net "M_F_CPU0_SA_DQ<7>")
	)
	(segment
		(start 430.382934 -308.2417)
		(end 430.395126 -308.253892)
		(width 0.1016)
		(layer "F.Cu")
		(net "M_F_CPU0_SA_DQ<7>")
	)
	(segment
		(start 427.639226 -307.816758)
		(end 428.07128 -308.248812)
		(width 0.20066)
		(layer "F.Cu")
		(net "M_F_CPU0_SA_DQ<7>")
	)
	(segment
		(start 432.15052 -307.816758)
		(end 433.484782 -307.816758)
		(width 0.20066)
		(layer "F.Cu")
		(net "M_F_CPU0_SA_DQ<7>")
	)
	(segment
		(start 430.395126 -308.253892)
		(end 431.076354 -308.253892)
		(width 0.20066)
		(layer "F.Cu")
		(net "M_F_CPU0_SA_DQ<7>")
	)
	(segment
		(start 382.715516 -275.894546)
		(end 382.715262 -275.8948)
		(width 0.20066)
		(layer "F.Cu")
		(net "M_F_CPU0_SA_DQ<7>")
	)
	(segment
		(start 424.836082 -307.816758)
		(end 425.940982 -307.816758)
		(width 0.20066)
		(layer "F.Cu")
		(net "M_F_CPU0_SA_DQ<7>")
	)
	(segment
		(start 431.280316 -308.04993)
		(end 431.280316 -307.798978)
		(width 0.20066)
		(layer "F.Cu")
		(net "M_F_CPU0_SA_DQ<7>")
	)
	(segment
		(start 428.363126 -308.248812)
		(end 428.367952 -308.248812)
		(width 0.101854)
		(layer "F.Cu")
		(net "M_F_CPU0_SA_DQ<7>")
	)
	(segment
		(start 428.375064 -308.2417)
		(end 430.382934 -308.2417)
		(width 0.1016)
		(layer "F.Cu")
		(net "M_F_CPU0_SA_DQ<7>")
	)
	(segment
		(start 431.280316 -307.798978)
		(end 431.514504 -307.56479)
		(width 0.20066)
		(layer "F.Cu")
		(net "M_F_CPU0_SA_DQ<7>")
	)
	(segment
		(start 431.514504 -307.56479)
		(end 431.898552 -307.56479)
		(width 0.20066)
		(layer "F.Cu")
		(net "M_F_CPU0_SA_DQ<7>")
	)
	(segment
		(start 423.61485 -306.620672)
		(end 423.61485 -307.159406)
		(width 0.18288)
		(layer "In2.Cu")
		(net "M_F_CPU0_SA_DQ<7>")
	)
	(segment
		(start 408.163522 -306.935378)
		(end 407.708608 -307.390292)
		(width 0.18288)
		(layer "In2.Cu")
		(net "M_F_CPU0_SA_DQ<7>")
	)
	(segment
		(start 424.353482 -307.623464)
		(end 424.353482 -306.620672)
		(width 0.18288)
		(layer "In2.Cu")
		(net "M_F_CPU0_SA_DQ<7>")
	)
	(segment
		(start 415.256218 -306.591716)
		(end 415.137346 -306.472844)
		(width 0.18288)
		(layer "In2.Cu")
		(net "M_F_CPU0_SA_DQ<7>")
	)
	(segment
		(start 423.61485 -307.159406)
		(end 423.395902 -307.378354)
		(width 0.18288)
		(layer "In2.Cu")
		(net "M_F_CPU0_SA_DQ<7>")
	)
	(segment
		(start 424.160442 -306.427632)
		(end 423.80789 -306.427632)
		(width 0.18288)
		(layer "In2.Cu")
		(net "M_F_CPU0_SA_DQ<7>")
	)
	(segment
		(start 423.80789 -306.427632)
		(end 423.61485 -306.620672)
		(width 0.18288)
		(layer "In2.Cu")
		(net "M_F_CPU0_SA_DQ<7>")
	)
	(segment
		(start 423.056812 -307.378354)
		(end 422.863772 -307.185314)
		(width 0.18288)
		(layer "In2.Cu")
		(net "M_F_CPU0_SA_DQ<7>")
	)
	(segment
		(start 424.836082 -307.816758)
		(end 424.546776 -307.816758)
		(width 0.18288)
		(layer "In2.Cu")
		(net "M_F_CPU0_SA_DQ<7>")
	)
	(segment
		(start 408.997912 -306.935378)
		(end 408.163522 -306.935378)
		(width 0.18288)
		(layer "In2.Cu")
		(net "M_F_CPU0_SA_DQ<7>")
	)
	(segment
		(start 422.863772 -306.734464)
		(end 422.670732 -306.541424)
		(width 0.18288)
		(layer "In2.Cu")
		(net "M_F_CPU0_SA_DQ<7>")
	)
	(segment
		(start 415.137346 -306.472844)
		(end 413.539178 -306.472844)
		(width 0.18288)
		(layer "In2.Cu")
		(net "M_F_CPU0_SA_DQ<7>")
	)
	(segment
		(start 399.280888 -296.847768)
		(end 397.767556 -293.194232)
		(width 0.18288)
		(layer "In2.Cu")
		(net "M_F_CPU0_SA_DQ<7>")
	)
	(segment
		(start 423.395902 -307.378354)
		(end 423.056812 -307.378354)
		(width 0.18288)
		(layer "In2.Cu")
		(net "M_F_CPU0_SA_DQ<7>")
	)
	(segment
		(start 409.48864 -307.426106)
		(end 408.997912 -306.935378)
		(width 0.18288)
		(layer "In2.Cu")
		(net "M_F_CPU0_SA_DQ<7>")
	)
	(segment
		(start 413.174942 -306.83708)
		(end 412.727902 -306.83708)
		(width 0.18288)
		(layer "In2.Cu")
		(net "M_F_CPU0_SA_DQ<7>")
	)
	(segment
		(start 422.863772 -307.185314)
		(end 422.863772 -306.734464)
		(width 0.18288)
		(layer "In2.Cu")
		(net "M_F_CPU0_SA_DQ<7>")
	)
	(segment
		(start 382.345184 -275.952204)
		(end 382.402588 -275.8948)
		(width 0.088646)
		(layer "In2.Cu")
		(net "M_F_CPU0_SA_DQ<7>")
	)
	(segment
		(start 394.013182 -283.780992)
		(end 391.699242 -281.467052)
		(width 0.18288)
		(layer "In2.Cu")
		(net "M_F_CPU0_SA_DQ<7>")
	)
	(segment
		(start 424.353482 -306.620672)
		(end 424.160442 -306.427632)
		(width 0.18288)
		(layer "In2.Cu")
		(net "M_F_CPU0_SA_DQ<7>")
	)
	(segment
		(start 384.877564 -275.405342)
		(end 384.877564 -275.405088)
		(width 0.088646)
		(layer "In2.Cu")
		(net "M_F_CPU0_SA_DQ<7>")
	)
	(segment
		(start 415.584894 -306.591716)
		(end 415.256218 -306.591716)
		(width 0.18288)
		(layer "In2.Cu")
		(net "M_F_CPU0_SA_DQ<7>")
	)
	(segment
		(start 384.321304 -275.400008)
		(end 384.312414 -275.405342)
		(width 0.088646)
		(layer "In2.Cu")
		(net "M_F_CPU0_SA_DQ<7>")
	)
	(segment
		(start 412.310326 -306.419504)
		(end 411.859984 -306.419504)
		(width 0.18288)
		(layer "In2.Cu")
		(net "M_F_CPU0_SA_DQ<7>")
	)
	(segment
		(start 424.546776 -307.816758)
		(end 424.353482 -307.623464)
		(width 0.18288)
		(layer "In2.Cu")
		(net "M_F_CPU0_SA_DQ<7>")
	)
	(segment
		(start 382.402588 -275.8948)
		(end 382.715262 -275.8948)
		(width 0.088646)
		(layer "In2.Cu")
		(net "M_F_CPU0_SA_DQ<7>")
	)
	(segment
		(start 419.843712 -306.541424)
		(end 419.75278 -306.450492)
		(width 0.18288)
		(layer "In2.Cu")
		(net "M_F_CPU0_SA_DQ<7>")
	)
	(segment
		(start 422.670732 -306.541424)
		(end 419.843712 -306.541424)
		(width 0.18288)
		(layer "In2.Cu")
		(net "M_F_CPU0_SA_DQ<7>")
	)
	(segment
		(start 383.387346 -275.396706)
		(end 383.372614 -275.405342)
		(width 0.088646)
		(layer "In2.Cu")
		(net "M_F_CPU0_SA_DQ<7>")
	)
	(segment
		(start 419.35273 -306.450492)
		(end 418.92347 -306.879752)
		(width 0.18288)
		(layer "In2.Cu")
		(net "M_F_CPU0_SA_DQ<7>")
	)
	(segment
		(start 382.91135 -276.214078)
		(end 382.90246 -276.219158)
		(width 0.088646)
		(layer "In2.Cu")
		(net "M_F_CPU0_SA_DQ<7>")
	)
	(segment
		(start 415.935414 -306.241196)
		(end 415.584894 -306.591716)
		(width 0.18288)
		(layer "In2.Cu")
		(net "M_F_CPU0_SA_DQ<7>")
	)
	(segment
		(start 417.8808 -306.879752)
		(end 417.242244 -306.241196)
		(width 0.18288)
		(layer "In2.Cu")
		(net "M_F_CPU0_SA_DQ<7>")
	)
	(segment
		(start 394.15593 -289.582606)
		(end 394.013182 -289.238436)
		(width 0.18288)
		(layer "In2.Cu")
		(net "M_F_CPU0_SA_DQ<7>")
	)
	(segment
		(start 419.75278 -306.450492)
		(end 419.35273 -306.450492)
		(width 0.18288)
		(layer "In2.Cu")
		(net "M_F_CPU0_SA_DQ<7>")
	)
	(segment
		(start 411.859984 -306.419504)
		(end 410.853382 -307.426106)
		(width 0.18288)
		(layer "In2.Cu")
		(net "M_F_CPU0_SA_DQ<7>")
	)
	(segment
		(start 391.699242 -281.467052)
		(end 390.465056 -278.487124)
		(width 0.18288)
		(layer "In2.Cu")
		(net "M_F_CPU0_SA_DQ<7>")
	)
	(segment
		(start 388.663688 -276.685756)
		(end 387.660134 -276.269958)
		(width 0.088646)
		(layer "In2.Cu")
		(net "M_F_CPU0_SA_DQ<7>")
	)
	(segment
		(start 385.347464 -276.219158)
		(end 385.338574 -276.214078)
		(width 0.088646)
		(layer "In2.Cu")
		(net "M_F_CPU0_SA_DQ<7>")
	)
	(segment
		(start 382.528064 -276.219158)
		(end 382.519174 -276.214078)
		(width 0.088646)
		(layer "In2.Cu")
		(net "M_F_CPU0_SA_DQ<7>")
	)
	(segment
		(start 399.280888 -302.383444)
		(end 399.280888 -296.847768)
		(width 0.18288)
		(layer "In2.Cu")
		(net "M_F_CPU0_SA_DQ<7>")
	)
	(segment
		(start 387.660134 -276.269958)
		(end 387.414516 -276.269958)
		(width 0.088646)
		(layer "In2.Cu")
		(net "M_F_CPU0_SA_DQ<7>")
	)
	(segment
		(start 383.372614 -275.405342)
		(end 383.366518 -275.408898)
		(width 0.088646)
		(layer "In2.Cu")
		(net "M_F_CPU0_SA_DQ<7>")
	)
	(segment
		(start 412.727902 -306.83708)
		(end 412.310326 -306.419504)
		(width 0.18288)
		(layer "In2.Cu")
		(net "M_F_CPU0_SA_DQ<7>")
	)
	(segment
		(start 417.242244 -306.241196)
		(end 415.935414 -306.241196)
		(width 0.18288)
		(layer "In2.Cu")
		(net "M_F_CPU0_SA_DQ<7>")
	)
	(segment
		(start 407.708608 -307.390292)
		(end 404.287736 -307.390292)
		(width 0.18288)
		(layer "In2.Cu")
		(net "M_F_CPU0_SA_DQ<7>")
	)
	(segment
		(start 385.160012 -275.8948)
		(end 385.160012 -275.884894)
		(width 0.088646)
		(layer "In2.Cu")
		(net "M_F_CPU0_SA_DQ<7>")
	)
	(segment
		(start 390.465056 -278.487124)
		(end 389.137652 -277.15972)
		(width 0.18288)
		(layer "In2.Cu")
		(net "M_F_CPU0_SA_DQ<7>")
	)
	(segment
		(start 389.137652 -277.15972)
		(end 388.663688 -276.685756)
		(width 0.088646)
		(layer "In2.Cu")
		(net "M_F_CPU0_SA_DQ<7>")
	)
	(segment
		(start 394.013182 -289.238436)
		(end 394.013182 -283.780992)
		(width 0.18288)
		(layer "In2.Cu")
		(net "M_F_CPU0_SA_DQ<7>")
	)
	(segment
		(start 410.853382 -307.426106)
		(end 409.48864 -307.426106)
		(width 0.18288)
		(layer "In2.Cu")
		(net "M_F_CPU0_SA_DQ<7>")
	)
	(segment
		(start 397.767556 -293.194232)
		(end 394.15593 -289.582606)
		(width 0.18288)
		(layer "In2.Cu")
		(net "M_F_CPU0_SA_DQ<7>")
	)
	(segment
		(start 413.539178 -306.472844)
		(end 413.174942 -306.83708)
		(width 0.18288)
		(layer "In2.Cu")
		(net "M_F_CPU0_SA_DQ<7>")
	)
	(segment
		(start 418.92347 -306.879752)
		(end 417.8808 -306.879752)
		(width 0.18288)
		(layer "In2.Cu")
		(net "M_F_CPU0_SA_DQ<7>")
	)
	(segment
		(start 404.287736 -307.390292)
		(end 399.280888 -302.383444)
		(width 0.18288)
		(layer "In2.Cu")
		(net "M_F_CPU0_SA_DQ<7>")
	)
	(arc
		(start 382.519174 -276.214078)
		(mid 382.403435 -276.102254)
		(end 382.345184 -275.952204)
		(width 0.088646)
		(layer "In2.Cu")
		(net "M_F_CPU0_SA_DQ<7>")
	)
	(arc
		(start 383.938018 -275.405342)
		(mid 383.663819 -275.329507)
		(end 383.387346 -275.396706)
		(width 0.088646)
		(layer "In2.Cu")
		(net "M_F_CPU0_SA_DQ<7>")
	)
	(arc
		(start 385.160012 -275.884894)
		(mid 385.081901 -275.607945)
		(end 384.877564 -275.405342)
		(width 0.088646)
		(layer "In2.Cu")
		(net "M_F_CPU0_SA_DQ<7>")
	)
	(arc
		(start 386.287264 -276.219158)
		(mid 386.004562 -276.143382)
		(end 385.72186 -276.219158)
		(width 0.088646)
		(layer "In2.Cu")
		(net "M_F_CPU0_SA_DQ<7>")
	)
	(arc
		(start 382.90246 -276.219158)
		(mid 382.715262 -276.269301)
		(end 382.528064 -276.219158)
		(width 0.088646)
		(layer "In2.Cu")
		(net "M_F_CPU0_SA_DQ<7>")
	)
	(arc
		(start 386.66166 -276.219158)
		(mid 386.474462 -276.269301)
		(end 386.287264 -276.219158)
		(width 0.088646)
		(layer "In2.Cu")
		(net "M_F_CPU0_SA_DQ<7>")
	)
	(arc
		(start 387.227064 -276.219158)
		(mid 386.944362 -276.143382)
		(end 386.66166 -276.219158)
		(width 0.088646)
		(layer "In2.Cu")
		(net "M_F_CPU0_SA_DQ<7>")
	)
	(arc
		(start 384.877564 -275.405088)
		(mid 384.600092 -275.32937)
		(end 384.321304 -275.400008)
		(width 0.088646)
		(layer "In2.Cu")
		(net "M_F_CPU0_SA_DQ<7>")
	)
	(arc
		(start 385.72186 -276.219158)
		(mid 385.534662 -276.269301)
		(end 385.347464 -276.219158)
		(width 0.088646)
		(layer "In2.Cu")
		(net "M_F_CPU0_SA_DQ<7>")
	)
	(arc
		(start 383.089912 -275.8948)
		(mid 383.042233 -276.0777)
		(end 382.91135 -276.214078)
		(width 0.088646)
		(layer "In2.Cu")
		(net "M_F_CPU0_SA_DQ<7>")
	)
	(arc
		(start 384.312414 -275.405342)
		(mid 384.125216 -275.455485)
		(end 383.938018 -275.405342)
		(width 0.088646)
		(layer "In2.Cu")
		(net "M_F_CPU0_SA_DQ<7>")
	)
	(arc
		(start 383.366518 -275.408898)
		(mid 383.163931 -275.615249)
		(end 383.089912 -275.8948)
		(width 0.088646)
		(layer "In2.Cu")
		(net "M_F_CPU0_SA_DQ<7>")
	)
	(arc
		(start 387.414516 -276.269958)
		(mid 387.317446 -276.256901)
		(end 387.227064 -276.219158)
		(width 0.088646)
		(layer "In2.Cu")
		(net "M_F_CPU0_SA_DQ<7>")
	)
	(arc
		(start 385.338574 -276.214078)
		(mid 385.20766 -276.077718)
		(end 385.160012 -275.8948)
		(width 0.088646)
		(layer "In2.Cu")
		(net "M_F_CPU0_SA_DQ<7>")
	)
	(segment
		(start 430.382934 -309.941722)
		(end 428.375064 -309.941722)
		(width 0.1016)
		(layer "F.Cu")
		(net "M_F_CPU0_SA_DQ<6>")
	)
	(segment
		(start 428.07128 -309.948834)
		(end 427.639226 -309.51678)
		(width 0.20066)
		(layer "F.Cu")
		(net "M_F_CPU0_SA_DQ<6>")
	)
	(segment
		(start 431.898552 -309.264812)
		(end 431.514504 -309.264812)
		(width 0.20066)
		(layer "F.Cu")
		(net "M_F_CPU0_SA_DQ<6>")
	)
	(segment
		(start 425.940728 -309.516526)
		(end 425.940982 -309.51678)
		(width 0.20066)
		(layer "F.Cu")
		(net "M_F_CPU0_SA_DQ<6>")
	)
	(segment
		(start 428.363126 -309.948834)
		(end 428.07128 -309.948834)
		(width 0.20066)
		(layer "F.Cu")
		(net "M_F_CPU0_SA_DQ<6>")
	)
	(segment
		(start 430.395126 -309.953914)
		(end 430.382934 -309.941722)
		(width 0.1016)
		(layer "F.Cu")
		(net "M_F_CPU0_SA_DQ<6>")
	)
	(segment
		(start 424.836082 -309.516526)
		(end 425.940728 -309.516526)
		(width 0.20066)
		(layer "F.Cu")
		(net "M_F_CPU0_SA_DQ<6>")
	)
	(segment
		(start 431.514504 -309.264812)
		(end 431.280316 -309.499)
		(width 0.20066)
		(layer "F.Cu")
		(net "M_F_CPU0_SA_DQ<6>")
	)
	(segment
		(start 432.15052 -309.51678)
		(end 431.898552 -309.264812)
		(width 0.20066)
		(layer "F.Cu")
		(net "M_F_CPU0_SA_DQ<6>")
	)
	(segment
		(start 383.185162 -276.172676)
		(end 383.185162 -276.708362)
		(width 0.20066)
		(layer "F.Cu")
		(net "M_F_CPU0_SA_DQ<6>")
	)
	(segment
		(start 427.639226 -309.51678)
		(end 425.940982 -309.51678)
		(width 0.20066)
		(layer "F.Cu")
		(net "M_F_CPU0_SA_DQ<6>")
	)
	(segment
		(start 428.375064 -309.941722)
		(end 428.367952 -309.948834)
		(width 0.1016)
		(layer "F.Cu")
		(net "M_F_CPU0_SA_DQ<6>")
	)
	(segment
		(start 433.484782 -309.51678)
		(end 432.15052 -309.51678)
		(width 0.20066)
		(layer "F.Cu")
		(net "M_F_CPU0_SA_DQ<6>")
	)
	(segment
		(start 431.280316 -309.749952)
		(end 431.076354 -309.953914)
		(width 0.20066)
		(layer "F.Cu")
		(net "M_F_CPU0_SA_DQ<6>")
	)
	(segment
		(start 428.367952 -309.948834)
		(end 428.363126 -309.948834)
		(width 0.101854)
		(layer "F.Cu")
		(net "M_F_CPU0_SA_DQ<6>")
	)
	(segment
		(start 383.185162 -276.708362)
		(end 383.185416 -276.708616)
		(width 0.20066)
		(layer "F.Cu")
		(net "M_F_CPU0_SA_DQ<6>")
	)
	(segment
		(start 431.076354 -309.953914)
		(end 430.395126 -309.953914)
		(width 0.20066)
		(layer "F.Cu")
		(net "M_F_CPU0_SA_DQ<6>")
	)
	(segment
		(start 431.280316 -309.499)
		(end 431.280316 -309.749952)
		(width 0.20066)
		(layer "F.Cu")
		(net "M_F_CPU0_SA_DQ<6>")
	)
	(segment
		(start 424.25493 -310.600598)
		(end 424.052746 -310.802782)
		(width 0.18288)
		(layer "In2.Cu")
		(net "M_F_CPU0_SA_DQ<6>")
	)
	(segment
		(start 409.960064 -309.097172)
		(end 409.51023 -309.097172)
		(width 0.18288)
		(layer "In2.Cu")
		(net "M_F_CPU0_SA_DQ<6>")
	)
	(segment
		(start 419.905688 -308.910736)
		(end 419.722808 -309.093616)
		(width 0.18288)
		(layer "In2.Cu")
		(net "M_F_CPU0_SA_DQ<6>")
	)
	(segment
		(start 391.134854 -281.928824)
		(end 389.914892 -278.983948)
		(width 0.18288)
		(layer "In2.Cu")
		(net "M_F_CPU0_SA_DQ<6>")
	)
	(segment
		(start 415.516314 -308.783228)
		(end 415.212022 -309.08752)
		(width 0.18288)
		(layer "In2.Cu")
		(net "M_F_CPU0_SA_DQ<6>")
	)
	(segment
		(start 412.467044 -309.127144)
		(end 411.777688 -309.127144)
		(width 0.18288)
		(layer "In2.Cu")
		(net "M_F_CPU0_SA_DQ<6>")
	)
	(segment
		(start 384.312414 -276.384512)
		(end 384.31216 -276.384258)
		(width 0.088646)
		(layer "In2.Cu")
		(net "M_F_CPU0_SA_DQ<6>")
	)
	(segment
		(start 413.322262 -308.906672)
		(end 412.687516 -308.906672)
		(width 0.18288)
		(layer "In2.Cu")
		(net "M_F_CPU0_SA_DQ<6>")
	)
	(segment
		(start 423.551858 -310.642762)
		(end 423.551858 -308.842664)
		(width 0.18288)
		(layer "In2.Cu")
		(net "M_F_CPU0_SA_DQ<6>")
	)
	(segment
		(start 423.358818 -308.649624)
		(end 423.085514 -308.649624)
		(width 0.18288)
		(layer "In2.Cu")
		(net "M_F_CPU0_SA_DQ<6>")
	)
	(segment
		(start 392.997182 -283.791152)
		(end 391.134854 -281.928824)
		(width 0.18288)
		(layer "In2.Cu")
		(net "M_F_CPU0_SA_DQ<6>")
	)
	(segment
		(start 413.50311 -309.08752)
		(end 413.322262 -308.906672)
		(width 0.18288)
		(layer "In2.Cu")
		(net "M_F_CPU0_SA_DQ<6>")
	)
	(segment
		(start 409.194762 -308.781704)
		(end 407.963116 -308.781704)
		(width 0.18288)
		(layer "In2.Cu")
		(net "M_F_CPU0_SA_DQ<6>")
	)
	(segment
		(start 420.300404 -308.910736)
		(end 419.905688 -308.910736)
		(width 0.18288)
		(layer "In2.Cu")
		(net "M_F_CPU0_SA_DQ<6>")
	)
	(segment
		(start 420.480744 -309.091076)
		(end 420.300404 -308.910736)
		(width 0.18288)
		(layer "In2.Cu")
		(net "M_F_CPU0_SA_DQ<6>")
	)
	(segment
		(start 403.004528 -308.132734)
		(end 402.811488 -307.939694)
		(width 0.18288)
		(layer "In2.Cu")
		(net "M_F_CPU0_SA_DQ<6>")
	)
	(segment
		(start 424.368214 -309.516526)
		(end 424.25493 -309.62981)
		(width 0.18288)
		(layer "In2.Cu")
		(net "M_F_CPU0_SA_DQ<6>")
	)
	(segment
		(start 393.456922 -290.552124)
		(end 392.997182 -289.442144)
		(width 0.18288)
		(layer "In2.Cu")
		(net "M_F_CPU0_SA_DQ<6>")
	)
	(segment
		(start 405.220678 -309.076852)
		(end 404.632922 -308.489096)
		(width 0.18288)
		(layer "In2.Cu")
		(net "M_F_CPU0_SA_DQ<6>")
	)
	(segment
		(start 403.58187 -308.132734)
		(end 403.004528 -308.132734)
		(width 0.18288)
		(layer "In2.Cu")
		(net "M_F_CPU0_SA_DQ<6>")
	)
	(segment
		(start 403.938232 -308.489096)
		(end 403.58187 -308.132734)
		(width 0.18288)
		(layer "In2.Cu")
		(net "M_F_CPU0_SA_DQ<6>")
	)
	(segment
		(start 423.711878 -310.802782)
		(end 423.551858 -310.642762)
		(width 0.18288)
		(layer "In2.Cu")
		(net "M_F_CPU0_SA_DQ<6>")
	)
	(segment
		(start 398.07515 -302.626014)
		(end 398.07515 -297.53052)
		(width 0.18288)
		(layer "In2.Cu")
		(net "M_F_CPU0_SA_DQ<6>")
	)
	(segment
		(start 419.722808 -309.093616)
		(end 417.071302 -309.093616)
		(width 0.18288)
		(layer "In2.Cu")
		(net "M_F_CPU0_SA_DQ<6>")
	)
	(segment
		(start 411.416246 -308.765702)
		(end 410.291534 -308.765702)
		(width 0.18288)
		(layer "In2.Cu")
		(net "M_F_CPU0_SA_DQ<6>")
	)
	(segment
		(start 384.877564 -277.032974)
		(end 384.59156 -276.86762)
		(width 0.088646)
		(layer "In2.Cu")
		(net "M_F_CPU0_SA_DQ<6>")
	)
	(segment
		(start 424.052746 -310.802782)
		(end 423.711878 -310.802782)
		(width 0.18288)
		(layer "In2.Cu")
		(net "M_F_CPU0_SA_DQ<6>")
	)
	(segment
		(start 392.997182 -289.442144)
		(end 392.997182 -283.791152)
		(width 0.18288)
		(layer "In2.Cu")
		(net "M_F_CPU0_SA_DQ<6>")
	)
	(segment
		(start 404.632922 -308.489096)
		(end 403.938232 -308.489096)
		(width 0.18288)
		(layer "In2.Cu")
		(net "M_F_CPU0_SA_DQ<6>")
	)
	(segment
		(start 416.760914 -308.783228)
		(end 415.516314 -308.783228)
		(width 0.18288)
		(layer "In2.Cu")
		(net "M_F_CPU0_SA_DQ<6>")
	)
	(segment
		(start 424.25493 -309.62981)
		(end 424.25493 -310.600598)
		(width 0.18288)
		(layer "In2.Cu")
		(net "M_F_CPU0_SA_DQ<6>")
	)
	(segment
		(start 409.51023 -309.097172)
		(end 409.194762 -308.781704)
		(width 0.18288)
		(layer "In2.Cu")
		(net "M_F_CPU0_SA_DQ<6>")
	)
	(segment
		(start 396.592806 -293.688008)
		(end 393.456922 -290.552124)
		(width 0.18288)
		(layer "In2.Cu")
		(net "M_F_CPU0_SA_DQ<6>")
	)
	(segment
		(start 424.836082 -309.516526)
		(end 424.368214 -309.516526)
		(width 0.18288)
		(layer "In2.Cu")
		(net "M_F_CPU0_SA_DQ<6>")
	)
	(segment
		(start 411.777688 -309.127144)
		(end 411.416246 -308.765702)
		(width 0.18288)
		(layer "In2.Cu")
		(net "M_F_CPU0_SA_DQ<6>")
	)
	(segment
		(start 423.551858 -308.842664)
		(end 423.358818 -308.649624)
		(width 0.18288)
		(layer "In2.Cu")
		(net "M_F_CPU0_SA_DQ<6>")
	)
	(segment
		(start 423.085514 -308.649624)
		(end 422.644062 -309.091076)
		(width 0.18288)
		(layer "In2.Cu")
		(net "M_F_CPU0_SA_DQ<6>")
	)
	(segment
		(start 422.644062 -309.091076)
		(end 420.480744 -309.091076)
		(width 0.18288)
		(layer "In2.Cu")
		(net "M_F_CPU0_SA_DQ<6>")
	)
	(segment
		(start 383.937764 -276.384258)
		(end 383.908808 -276.401022)
		(width 0.088646)
		(layer "In2.Cu")
		(net "M_F_CPU0_SA_DQ<6>")
	)
	(segment
		(start 383.908808 -276.401022)
		(end 383.185416 -276.708616)
		(width 0.088646)
		(layer "In2.Cu")
		(net "M_F_CPU0_SA_DQ<6>")
	)
	(segment
		(start 398.07515 -297.53052)
		(end 396.592806 -293.688008)
		(width 0.18288)
		(layer "In2.Cu")
		(net "M_F_CPU0_SA_DQ<6>")
	)
	(segment
		(start 388.614158 -277.683214)
		(end 388.014718 -277.083774)
		(width 0.088646)
		(layer "In2.Cu")
		(net "M_F_CPU0_SA_DQ<6>")
	)
	(segment
		(start 389.914892 -278.983948)
		(end 388.614158 -277.683214)
		(width 0.18288)
		(layer "In2.Cu")
		(net "M_F_CPU0_SA_DQ<6>")
	)
	(segment
		(start 417.071302 -309.093616)
		(end 416.760914 -308.783228)
		(width 0.18288)
		(layer "In2.Cu")
		(net "M_F_CPU0_SA_DQ<6>")
	)
	(segment
		(start 402.811488 -307.362352)
		(end 398.07515 -302.626014)
		(width 0.18288)
		(layer "In2.Cu")
		(net "M_F_CPU0_SA_DQ<6>")
	)
	(segment
		(start 388.014718 -277.083774)
		(end 386.944616 -277.083774)
		(width 0.088646)
		(layer "In2.Cu")
		(net "M_F_CPU0_SA_DQ<6>")
	)
	(segment
		(start 407.667968 -309.076852)
		(end 405.220678 -309.076852)
		(width 0.18288)
		(layer "In2.Cu")
		(net "M_F_CPU0_SA_DQ<6>")
	)
	(segment
		(start 407.963116 -308.781704)
		(end 407.667968 -309.076852)
		(width 0.18288)
		(layer "In2.Cu")
		(net "M_F_CPU0_SA_DQ<6>")
	)
	(segment
		(start 402.811488 -307.939694)
		(end 402.811488 -307.362352)
		(width 0.18288)
		(layer "In2.Cu")
		(net "M_F_CPU0_SA_DQ<6>")
	)
	(segment
		(start 412.687516 -308.906672)
		(end 412.467044 -309.127144)
		(width 0.18288)
		(layer "In2.Cu")
		(net "M_F_CPU0_SA_DQ<6>")
	)
	(segment
		(start 410.291534 -308.765702)
		(end 409.960064 -309.097172)
		(width 0.18288)
		(layer "In2.Cu")
		(net "M_F_CPU0_SA_DQ<6>")
	)
	(segment
		(start 415.212022 -309.08752)
		(end 413.50311 -309.08752)
		(width 0.18288)
		(layer "In2.Cu")
		(net "M_F_CPU0_SA_DQ<6>")
	)
	(arc
		(start 386.19176 -277.032974)
		(mid 386.004562 -277.083117)
		(end 385.817364 -277.032974)
		(width 0.088646)
		(layer "In2.Cu")
		(net "M_F_CPU0_SA_DQ<6>")
	)
	(arc
		(start 385.25196 -277.032974)
		(mid 385.064762 -277.083117)
		(end 384.877564 -277.032974)
		(width 0.088646)
		(layer "In2.Cu")
		(net "M_F_CPU0_SA_DQ<6>")
	)
	(arc
		(start 384.499612 -276.708616)
		(mid 384.449448 -276.521478)
		(end 384.312414 -276.384512)
		(width 0.088646)
		(layer "In2.Cu")
		(net "M_F_CPU0_SA_DQ<6>")
	)
	(arc
		(start 384.31216 -276.384258)
		(mid 384.124962 -276.334115)
		(end 383.937764 -276.384258)
		(width 0.088646)
		(layer "In2.Cu")
		(net "M_F_CPU0_SA_DQ<6>")
	)
	(arc
		(start 384.59156 -276.86762)
		(mid 384.52423 -276.800462)
		(end 384.499612 -276.708616)
		(width 0.088646)
		(layer "In2.Cu")
		(net "M_F_CPU0_SA_DQ<6>")
	)
	(arc
		(start 386.944616 -277.083774)
		(mid 386.847546 -277.070717)
		(end 386.757164 -277.032974)
		(width 0.088646)
		(layer "In2.Cu")
		(net "M_F_CPU0_SA_DQ<6>")
	)
	(arc
		(start 385.817364 -277.032974)
		(mid 385.534662 -276.957198)
		(end 385.25196 -277.032974)
		(width 0.088646)
		(layer "In2.Cu")
		(net "M_F_CPU0_SA_DQ<6>")
	)
	(arc
		(start 386.757164 -277.032974)
		(mid 386.474462 -276.957198)
		(end 386.19176 -277.032974)
		(width 0.088646)
		(layer "In2.Cu")
		(net "M_F_CPU0_SA_DQ<6>")
	)
	(segment
		(start 424.73626 -308.2417)
		(end 424.391582 -308.2417)
		(width 0.20066)
		(layer "F.Cu")
		(net "M_F_CPU0_SA_DQ<5>")
	)
	(segment
		(start 426.945044 -308.2417)
		(end 424.756326 -308.2417)
		(width 0.1016)
		(layer "F.Cu")
		(net "M_F_CPU0_SA_DQ<5>")
	)
	(segment
		(start 423.610278 -308.915308)
		(end 423.361612 -308.666642)
		(width 0.20066)
		(layer "F.Cu")
		(net "M_F_CPU0_SA_DQ<5>")
	)
	(segment
		(start 424.273472 -308.727348)
		(end 424.085512 -308.915308)
		(width 0.20066)
		(layer "F.Cu")
		(net "M_F_CPU0_SA_DQ<5>")
	)
	(segment
		(start 427.792896 -308.666896)
		(end 427.36135 -308.23535)
		(width 0.20066)
		(layer "F.Cu")
		(net "M_F_CPU0_SA_DQ<5>")
	)
	(segment
		(start 427.36135 -308.23535)
		(end 426.951394 -308.23535)
		(width 0.20066)
		(layer "F.Cu")
		(net "M_F_CPU0_SA_DQ<5>")
	)
	(segment
		(start 423.361612 -308.666642)
		(end 421.840914 -308.666642)
		(width 0.20066)
		(layer "F.Cu")
		(net "M_F_CPU0_SA_DQ<5>")
	)
	(segment
		(start 424.085512 -308.915308)
		(end 423.610278 -308.915308)
		(width 0.20066)
		(layer "F.Cu")
		(net "M_F_CPU0_SA_DQ<5>")
	)
	(segment
		(start 424.273472 -308.35981)
		(end 424.273472 -308.727348)
		(width 0.20066)
		(layer "F.Cu")
		(net "M_F_CPU0_SA_DQ<5>")
	)
	(segment
		(start 424.756326 -308.2417)
		(end 424.73626 -308.2417)
		(width 0.101854)
		(layer "F.Cu")
		(net "M_F_CPU0_SA_DQ<5>")
	)
	(segment
		(start 424.391582 -308.2417)
		(end 424.273472 -308.35981)
		(width 0.20066)
		(layer "F.Cu")
		(net "M_F_CPU0_SA_DQ<5>")
	)
	(segment
		(start 381.775716 -275.894546)
		(end 381.775462 -275.8948)
		(width 0.20066)
		(layer "F.Cu")
		(net "M_F_CPU0_SA_DQ<5>")
	)
	(segment
		(start 421.840914 -308.666642)
		(end 420.736014 -308.666642)
		(width 0.20066)
		(layer "F.Cu")
		(net "M_F_CPU0_SA_DQ<5>")
	)
	(segment
		(start 429.38446 -308.666896)
		(end 427.792896 -308.666896)
		(width 0.20066)
		(layer "F.Cu")
		(net "M_F_CPU0_SA_DQ<5>")
	)
	(segment
		(start 426.951394 -308.23535)
		(end 426.945044 -308.2417)
		(width 0.1016)
		(layer "F.Cu")
		(net "M_F_CPU0_SA_DQ<5>")
	)
	(segment
		(start 429.384714 -308.666642)
		(end 429.38446 -308.666896)
		(width 0.20066)
		(layer "F.Cu")
		(net "M_F_CPU0_SA_DQ<5>")
	)
	(segment
		(start 381.775716 -275.35886)
		(end 381.775716 -275.894546)
		(width 0.20066)
		(layer "F.Cu")
		(net "M_F_CPU0_SA_DQ<5>")
	)
	(segment
		(start 384.969512 -275.904706)
		(end 384.969512 -275.8948)
		(width 0.088646)
		(layer "In2.Cu")
		(net "M_F_CPU0_SA_DQ<5>")
	)
	(segment
		(start 412.530798 -307.424582)
		(end 412.124652 -307.424582)
		(width 0.18288)
		(layer "In2.Cu")
		(net "M_F_CPU0_SA_DQ<5>")
	)
	(segment
		(start 407.461974 -308.073552)
		(end 406.042622 -308.073552)
		(width 0.18288)
		(layer "In2.Cu")
		(net "M_F_CPU0_SA_DQ<5>")
	)
	(segment
		(start 405.312118 -308.397148)
		(end 404.885144 -307.970174)
		(width 0.18288)
		(layer "In2.Cu")
		(net "M_F_CPU0_SA_DQ<5>")
	)
	(segment
		(start 420.26713 -307.638196)
		(end 420.073836 -307.444902)
		(width 0.18288)
		(layer "In2.Cu")
		(net "M_F_CPU0_SA_DQ<5>")
	)
	(segment
		(start 419.26129 -308.239922)
		(end 417.037774 -308.239922)
		(width 0.18288)
		(layer "In2.Cu")
		(net "M_F_CPU0_SA_DQ<5>")
	)
	(segment
		(start 390.165336 -278.677878)
		(end 388.892288 -277.40483)
		(width 0.18288)
		(layer "In2.Cu")
		(net "M_F_CPU0_SA_DQ<5>")
	)
	(segment
		(start 391.415016 -281.695906)
		(end 390.165336 -278.677878)
		(width 0.18288)
		(layer "In2.Cu")
		(net "M_F_CPU0_SA_DQ<5>")
	)
	(segment
		(start 420.26713 -308.197758)
		(end 420.26713 -307.638196)
		(width 0.18288)
		(layer "In2.Cu")
		(net "M_F_CPU0_SA_DQ<5>")
	)
	(segment
		(start 419.428168 -307.637942)
		(end 419.428168 -308.073044)
		(width 0.18288)
		(layer "In2.Cu")
		(net "M_F_CPU0_SA_DQ<5>")
	)
	(segment
		(start 412.825184 -308.264052)
		(end 412.677864 -308.116732)
		(width 0.18288)
		(layer "In2.Cu")
		(net "M_F_CPU0_SA_DQ<5>")
	)
	(segment
		(start 408.093164 -308.253892)
		(end 407.642314 -308.253892)
		(width 0.18288)
		(layer "In2.Cu")
		(net "M_F_CPU0_SA_DQ<5>")
	)
	(segment
		(start 416.60953 -306.76469)
		(end 416.19678 -306.76469)
		(width 0.18288)
		(layer "In2.Cu")
		(net "M_F_CPU0_SA_DQ<5>")
	)
	(segment
		(start 398.758918 -302.585882)
		(end 398.758918 -297.189144)
		(width 0.18288)
		(layer "In2.Cu")
		(net "M_F_CPU0_SA_DQ<5>")
	)
	(segment
		(start 405.719026 -308.397148)
		(end 405.312118 -308.397148)
		(width 0.18288)
		(layer "In2.Cu")
		(net "M_F_CPU0_SA_DQ<5>")
	)
	(segment
		(start 416.016948 -308.104032)
		(end 415.856928 -308.264052)
		(width 0.18288)
		(layer "In2.Cu")
		(net "M_F_CPU0_SA_DQ<5>")
	)
	(segment
		(start 416.80257 -306.95773)
		(end 416.60953 -306.76469)
		(width 0.18288)
		(layer "In2.Cu")
		(net "M_F_CPU0_SA_DQ<5>")
	)
	(segment
		(start 397.197072 -293.41826)
		(end 393.778232 -289.99942)
		(width 0.18288)
		(layer "In2.Cu")
		(net "M_F_CPU0_SA_DQ<5>")
	)
	(segment
		(start 416.19678 -306.76469)
		(end 416.016948 -306.944522)
		(width 0.18288)
		(layer "In2.Cu")
		(net "M_F_CPU0_SA_DQ<5>")
	)
	(segment
		(start 412.677864 -307.571648)
		(end 412.530798 -307.424582)
		(width 0.18288)
		(layer "In2.Cu")
		(net "M_F_CPU0_SA_DQ<5>")
	)
	(segment
		(start 384.78206 -275.570442)
		(end 384.782314 -275.570442)
		(width 0.088646)
		(layer "In2.Cu")
		(net "M_F_CPU0_SA_DQ<5>")
	)
	(segment
		(start 404.14321 -307.970174)
		(end 398.758918 -302.585882)
		(width 0.18288)
		(layer "In2.Cu")
		(net "M_F_CPU0_SA_DQ<5>")
	)
	(segment
		(start 415.856928 -308.264052)
		(end 414.845754 -308.264052)
		(width 0.18288)
		(layer "In2.Cu")
		(net "M_F_CPU0_SA_DQ<5>")
	)
	(segment
		(start 412.677864 -308.116732)
		(end 412.677864 -307.571648)
		(width 0.18288)
		(layer "In2.Cu")
		(net "M_F_CPU0_SA_DQ<5>")
	)
	(segment
		(start 411.950916 -308.010306)
		(end 411.721808 -308.239414)
		(width 0.18288)
		(layer "In2.Cu")
		(net "M_F_CPU0_SA_DQ<5>")
	)
	(segment
		(start 407.642314 -308.253892)
		(end 407.461974 -308.073552)
		(width 0.18288)
		(layer "In2.Cu")
		(net "M_F_CPU0_SA_DQ<5>")
	)
	(segment
		(start 387.57352 -276.460204)
		(end 387.414262 -276.460204)
		(width 0.088646)
		(layer "In2.Cu")
		(net "M_F_CPU0_SA_DQ<5>")
	)
	(segment
		(start 382.153922 -275.960586)
		(end 382.088136 -275.8948)
		(width 0.088646)
		(layer "In2.Cu")
		(net "M_F_CPU0_SA_DQ<5>")
	)
	(segment
		(start 420.073836 -307.444902)
		(end 419.621208 -307.444902)
		(width 0.18288)
		(layer "In2.Cu")
		(net "M_F_CPU0_SA_DQ<5>")
	)
	(segment
		(start 388.892288 -277.40483)
		(end 388.212076 -276.724618)
		(width 0.088646)
		(layer "In2.Cu")
		(net "M_F_CPU0_SA_DQ<5>")
	)
	(segment
		(start 413.767016 -308.264052)
		(end 412.825184 -308.264052)
		(width 0.18288)
		(layer "In2.Cu")
		(net "M_F_CPU0_SA_DQ<5>")
	)
	(segment
		(start 409.56357 -308.239414)
		(end 409.028392 -307.704236)
		(width 0.18288)
		(layer "In2.Cu")
		(net "M_F_CPU0_SA_DQ<5>")
	)
	(segment
		(start 411.950916 -307.598318)
		(end 411.950916 -308.010306)
		(width 0.18288)
		(layer "In2.Cu")
		(net "M_F_CPU0_SA_DQ<5>")
	)
	(segment
		(start 388.212076 -276.724618)
		(end 387.57352 -276.460204)
		(width 0.088646)
		(layer "In2.Cu")
		(net "M_F_CPU0_SA_DQ<5>")
	)
	(segment
		(start 414.685734 -308.104032)
		(end 414.685734 -307.651912)
		(width 0.18288)
		(layer "In2.Cu")
		(net "M_F_CPU0_SA_DQ<5>")
	)
	(segment
		(start 409.028392 -307.704236)
		(end 408.64282 -307.704236)
		(width 0.18288)
		(layer "In2.Cu")
		(net "M_F_CPU0_SA_DQ<5>")
	)
	(segment
		(start 414.120076 -307.458872)
		(end 413.927036 -307.651912)
		(width 0.18288)
		(layer "In2.Cu")
		(net "M_F_CPU0_SA_DQ<5>")
	)
	(segment
		(start 414.845754 -308.264052)
		(end 414.685734 -308.104032)
		(width 0.18288)
		(layer "In2.Cu")
		(net "M_F_CPU0_SA_DQ<5>")
	)
	(segment
		(start 393.505182 -283.786072)
		(end 391.415016 -281.695906)
		(width 0.18288)
		(layer "In2.Cu")
		(net "M_F_CPU0_SA_DQ<5>")
	)
	(segment
		(start 393.505182 -289.34029)
		(end 393.505182 -283.786072)
		(width 0.18288)
		(layer "In2.Cu")
		(net "M_F_CPU0_SA_DQ<5>")
	)
	(segment
		(start 416.80257 -308.004718)
		(end 416.80257 -306.95773)
		(width 0.18288)
		(layer "In2.Cu")
		(net "M_F_CPU0_SA_DQ<5>")
	)
	(segment
		(start 420.736014 -308.666642)
		(end 420.26713 -308.197758)
		(width 0.18288)
		(layer "In2.Cu")
		(net "M_F_CPU0_SA_DQ<5>")
	)
	(segment
		(start 413.927036 -308.104032)
		(end 413.767016 -308.264052)
		(width 0.18288)
		(layer "In2.Cu")
		(net "M_F_CPU0_SA_DQ<5>")
	)
	(segment
		(start 382.088136 -275.8948)
		(end 381.775462 -275.8948)
		(width 0.088646)
		(layer "In2.Cu")
		(net "M_F_CPU0_SA_DQ<5>")
	)
	(segment
		(start 406.042622 -308.073552)
		(end 405.719026 -308.397148)
		(width 0.18288)
		(layer "In2.Cu")
		(net "M_F_CPU0_SA_DQ<5>")
	)
	(segment
		(start 383.280412 -275.8948)
		(end 383.280412 -275.910294)
		(width 0.088646)
		(layer "In2.Cu")
		(net "M_F_CPU0_SA_DQ<5>")
	)
	(segment
		(start 414.492694 -307.458872)
		(end 414.120076 -307.458872)
		(width 0.18288)
		(layer "In2.Cu")
		(net "M_F_CPU0_SA_DQ<5>")
	)
	(segment
		(start 416.016948 -306.944522)
		(end 416.016948 -308.104032)
		(width 0.18288)
		(layer "In2.Cu")
		(net "M_F_CPU0_SA_DQ<5>")
	)
	(segment
		(start 411.721808 -308.239414)
		(end 409.56357 -308.239414)
		(width 0.18288)
		(layer "In2.Cu")
		(net "M_F_CPU0_SA_DQ<5>")
	)
	(segment
		(start 408.64282 -307.704236)
		(end 408.093164 -308.253892)
		(width 0.18288)
		(layer "In2.Cu")
		(net "M_F_CPU0_SA_DQ<5>")
	)
	(segment
		(start 383.467864 -275.570442)
		(end 383.458974 -275.575522)
		(width 0.088646)
		(layer "In2.Cu")
		(net "M_F_CPU0_SA_DQ<5>")
	)
	(segment
		(start 413.927036 -307.651912)
		(end 413.927036 -308.104032)
		(width 0.18288)
		(layer "In2.Cu")
		(net "M_F_CPU0_SA_DQ<5>")
	)
	(segment
		(start 398.758918 -297.189144)
		(end 397.197072 -293.41826)
		(width 0.18288)
		(layer "In2.Cu")
		(net "M_F_CPU0_SA_DQ<5>")
	)
	(segment
		(start 419.428168 -308.073044)
		(end 419.26129 -308.239922)
		(width 0.18288)
		(layer "In2.Cu")
		(net "M_F_CPU0_SA_DQ<5>")
	)
	(segment
		(start 419.621208 -307.444902)
		(end 419.428168 -307.637942)
		(width 0.18288)
		(layer "In2.Cu")
		(net "M_F_CPU0_SA_DQ<5>")
	)
	(segment
		(start 417.037774 -308.239922)
		(end 416.80257 -308.004718)
		(width 0.18288)
		(layer "In2.Cu")
		(net "M_F_CPU0_SA_DQ<5>")
	)
	(segment
		(start 412.124652 -307.424582)
		(end 411.950916 -307.598318)
		(width 0.18288)
		(layer "In2.Cu")
		(net "M_F_CPU0_SA_DQ<5>")
	)
	(segment
		(start 404.885144 -307.970174)
		(end 404.14321 -307.970174)
		(width 0.18288)
		(layer "In2.Cu")
		(net "M_F_CPU0_SA_DQ<5>")
	)
	(segment
		(start 414.685734 -307.651912)
		(end 414.492694 -307.458872)
		(width 0.18288)
		(layer "In2.Cu")
		(net "M_F_CPU0_SA_DQ<5>")
	)
	(segment
		(start 384.407918 -275.570442)
		(end 384.397504 -275.576538)
		(width 0.088646)
		(layer "In2.Cu")
		(net "M_F_CPU0_SA_DQ<5>")
	)
	(segment
		(start 393.778232 -289.99942)
		(end 393.505182 -289.34029)
		(width 0.18288)
		(layer "In2.Cu")
		(net "M_F_CPU0_SA_DQ<5>")
	)
	(segment
		(start 382.432814 -276.384258)
		(end 382.426718 -276.380702)
		(width 0.088646)
		(layer "In2.Cu")
		(net "M_F_CPU0_SA_DQ<5>")
	)
	(segment
		(start 382.447546 -276.392894)
		(end 382.432814 -276.384258)
		(width 0.088646)
		(layer "In2.Cu")
		(net "M_F_CPU0_SA_DQ<5>")
	)
	(segment
		(start 384.79095 -275.575522)
		(end 384.78206 -275.570442)
		(width 0.088646)
		(layer "In2.Cu")
		(net "M_F_CPU0_SA_DQ<5>")
	)
	(arc
		(start 384.969512 -275.8948)
		(mid 384.921833 -275.7119)
		(end 384.79095 -275.575522)
		(width 0.088646)
		(layer "In2.Cu")
		(net "M_F_CPU0_SA_DQ<5>")
	)
	(arc
		(start 383.84226 -275.570442)
		(mid 383.655062 -275.520299)
		(end 383.467864 -275.570442)
		(width 0.088646)
		(layer "In2.Cu")
		(net "M_F_CPU0_SA_DQ<5>")
	)
	(arc
		(start 387.36524 -276.458172)
		(mid 387.244341 -276.434043)
		(end 387.13156 -276.384258)
		(width 0.088646)
		(layer "In2.Cu")
		(net "M_F_CPU0_SA_DQ<5>")
	)
	(arc
		(start 387.13156 -276.384258)
		(mid 386.944362 -276.334115)
		(end 386.757164 -276.384258)
		(width 0.088646)
		(layer "In2.Cu")
		(net "M_F_CPU0_SA_DQ<5>")
	)
	(arc
		(start 382.998218 -276.384258)
		(mid 382.724019 -276.460093)
		(end 382.447546 -276.392894)
		(width 0.088646)
		(layer "In2.Cu")
		(net "M_F_CPU0_SA_DQ<5>")
	)
	(arc
		(start 386.19176 -276.384258)
		(mid 386.004562 -276.334115)
		(end 385.817364 -276.384258)
		(width 0.088646)
		(layer "In2.Cu")
		(net "M_F_CPU0_SA_DQ<5>")
	)
	(arc
		(start 385.25196 -276.384258)
		(mid 385.047625 -276.181653)
		(end 384.969512 -275.904706)
		(width 0.088646)
		(layer "In2.Cu")
		(net "M_F_CPU0_SA_DQ<5>")
	)
	(arc
		(start 385.817364 -276.384258)
		(mid 385.534662 -276.460034)
		(end 385.25196 -276.384258)
		(width 0.088646)
		(layer "In2.Cu")
		(net "M_F_CPU0_SA_DQ<5>")
	)
	(arc
		(start 386.757164 -276.384258)
		(mid 386.474462 -276.460034)
		(end 386.19176 -276.384258)
		(width 0.088646)
		(layer "In2.Cu")
		(net "M_F_CPU0_SA_DQ<5>")
	)
	(arc
		(start 383.458974 -275.575522)
		(mid 383.32806 -275.711882)
		(end 383.280412 -275.8948)
		(width 0.088646)
		(layer "In2.Cu")
		(net "M_F_CPU0_SA_DQ<5>")
	)
	(arc
		(start 384.397504 -275.576538)
		(mid 384.119072 -275.646384)
		(end 383.84226 -275.570442)
		(width 0.088646)
		(layer "In2.Cu")
		(net "M_F_CPU0_SA_DQ<5>")
	)
	(arc
		(start 383.280412 -275.910294)
		(mid 383.201042 -276.184028)
		(end 382.998218 -276.384258)
		(width 0.088646)
		(layer "In2.Cu")
		(net "M_F_CPU0_SA_DQ<5>")
	)
	(arc
		(start 384.782314 -275.570442)
		(mid 384.595116 -275.520299)
		(end 384.407918 -275.570442)
		(width 0.088646)
		(layer "In2.Cu")
		(net "M_F_CPU0_SA_DQ<5>")
	)
	(arc
		(start 382.426718 -276.380702)
		(mid 382.241263 -276.202507)
		(end 382.153922 -275.960586)
		(width 0.088646)
		(layer "In2.Cu")
		(net "M_F_CPU0_SA_DQ<5>")
	)
	(arc
		(start 387.414262 -276.460204)
		(mid 387.389729 -276.459716)
		(end 387.36524 -276.458172)
		(width 0.088646)
		(layer "In2.Cu")
		(net "M_F_CPU0_SA_DQ<5>")
	)
	(segment
		(start 424.391582 -309.941722)
		(end 424.273472 -310.059832)
		(width 0.20066)
		(layer "F.Cu")
		(net "M_F_CPU0_SA_DQ<4>")
	)
	(segment
		(start 423.361612 -310.366664)
		(end 421.840914 -310.366664)
		(width 0.20066)
		(layer "F.Cu")
		(net "M_F_CPU0_SA_DQ<4>")
	)
	(segment
		(start 424.273472 -310.059832)
		(end 424.273472 -310.42737)
		(width 0.20066)
		(layer "F.Cu")
		(net "M_F_CPU0_SA_DQ<4>")
	)
	(segment
		(start 424.73626 -309.941722)
		(end 424.391582 -309.941722)
		(width 0.20066)
		(layer "F.Cu")
		(net "M_F_CPU0_SA_DQ<4>")
	)
	(segment
		(start 427.792896 -310.366918)
		(end 427.36135 -309.935372)
		(width 0.20066)
		(layer "F.Cu")
		(net "M_F_CPU0_SA_DQ<4>")
	)
	(segment
		(start 427.36135 -309.935372)
		(end 426.951394 -309.935372)
		(width 0.20066)
		(layer "F.Cu")
		(net "M_F_CPU0_SA_DQ<4>")
	)
	(segment
		(start 429.38446 -310.366918)
		(end 427.792896 -310.366918)
		(width 0.20066)
		(layer "F.Cu")
		(net "M_F_CPU0_SA_DQ<4>")
	)
	(segment
		(start 426.951394 -309.935372)
		(end 426.945044 -309.941722)
		(width 0.1016)
		(layer "F.Cu")
		(net "M_F_CPU0_SA_DQ<4>")
	)
	(segment
		(start 421.840914 -310.366664)
		(end 420.736014 -310.366664)
		(width 0.20066)
		(layer "F.Cu")
		(net "M_F_CPU0_SA_DQ<4>")
	)
	(segment
		(start 423.610278 -310.61533)
		(end 423.361612 -310.366664)
		(width 0.20066)
		(layer "F.Cu")
		(net "M_F_CPU0_SA_DQ<4>")
	)
	(segment
		(start 424.273472 -310.42737)
		(end 424.085512 -310.61533)
		(width 0.20066)
		(layer "F.Cu")
		(net "M_F_CPU0_SA_DQ<4>")
	)
	(segment
		(start 424.78325 -309.941722)
		(end 424.73626 -309.941722)
		(width 0.101854)
		(layer "F.Cu")
		(net "M_F_CPU0_SA_DQ<4>")
	)
	(segment
		(start 429.384714 -310.366664)
		(end 429.38446 -310.366918)
		(width 0.20066)
		(layer "F.Cu")
		(net "M_F_CPU0_SA_DQ<4>")
	)
	(segment
		(start 381.305562 -276.172676)
		(end 381.305816 -276.708616)
		(width 0.20066)
		(layer "F.Cu")
		(net "M_F_CPU0_SA_DQ<4>")
	)
	(segment
		(start 426.945044 -309.941722)
		(end 424.78325 -309.941722)
		(width 0.1016)
		(layer "F.Cu")
		(net "M_F_CPU0_SA_DQ<4>")
	)
	(segment
		(start 424.085512 -310.61533)
		(end 423.610278 -310.61533)
		(width 0.20066)
		(layer "F.Cu")
		(net "M_F_CPU0_SA_DQ<4>")
	)
	(segment
		(start 404.114 -309.02783)
		(end 403.745192 -309.396638)
		(width 0.18288)
		(layer "In2.Cu")
		(net "M_F_CPU0_SA_DQ<4>")
	)
	(segment
		(start 399.035524 -304.96002)
		(end 398.798034 -304.72253)
		(width 0.18288)
		(layer "In2.Cu")
		(net "M_F_CPU0_SA_DQ<4>")
	)
	(segment
		(start 384.31216 -277.032974)
		(end 384.311906 -277.032974)
		(width 0.088646)
		(layer "In2.Cu")
		(net "M_F_CPU0_SA_DQ<4>")
	)
	(segment
		(start 382.432814 -277.032974)
		(end 382.43256 -277.032974)
		(width 0.088646)
		(layer "In2.Cu")
		(net "M_F_CPU0_SA_DQ<4>")
	)
	(segment
		(start 384.78206 -277.198074)
		(end 384.496056 -277.032974)
		(width 0.088646)
		(layer "In2.Cu")
		(net "M_F_CPU0_SA_DQ<4>")
	)
	(segment
		(start 420.736014 -310.366664)
		(end 420.009066 -309.639716)
		(width 0.18288)
		(layer "In2.Cu")
		(net "M_F_CPU0_SA_DQ<4>")
	)
	(segment
		(start 399.793206 -305.717702)
		(end 399.793206 -305.19751)
		(width 0.18288)
		(layer "In2.Cu")
		(net "M_F_CPU0_SA_DQ<4>")
	)
	(segment
		(start 404.243286 -310.167782)
		(end 404.243286 -309.894732)
		(width 0.18288)
		(layer "In2.Cu")
		(net "M_F_CPU0_SA_DQ<4>")
	)
	(segment
		(start 400.550888 -305.955192)
		(end 400.030696 -305.955192)
		(width 0.18288)
		(layer "In2.Cu")
		(net "M_F_CPU0_SA_DQ<4>")
	)
	(segment
		(start 409.948634 -309.89397)
		(end 409.680664 -309.626)
		(width 0.18288)
		(layer "In2.Cu")
		(net "M_F_CPU0_SA_DQ<4>")
	)
	(segment
		(start 403.745192 -309.396638)
		(end 403.472142 -309.396638)
		(width 0.18288)
		(layer "In2.Cu")
		(net "M_F_CPU0_SA_DQ<4>")
	)
	(segment
		(start 416.052 -309.306722)
		(end 415.89198 -309.466742)
		(width 0.18288)
		(layer "In2.Cu")
		(net "M_F_CPU0_SA_DQ<4>")
	)
	(segment
		(start 400.788378 -306.712874)
		(end 400.788378 -306.192682)
		(width 0.18288)
		(layer "In2.Cu")
		(net "M_F_CPU0_SA_DQ<4>")
	)
	(segment
		(start 404.777702 -310.424068)
		(end 404.499572 -310.424068)
		(width 0.18288)
		(layer "In2.Cu")
		(net "M_F_CPU0_SA_DQ<4>")
	)
	(segment
		(start 400.788378 -306.192682)
		(end 400.550888 -305.955192)
		(width 0.18288)
		(layer "In2.Cu")
		(net "M_F_CPU0_SA_DQ<4>")
	)
	(segment
		(start 404.612094 -309.253128)
		(end 404.386796 -309.02783)
		(width 0.18288)
		(layer "In2.Cu")
		(net "M_F_CPU0_SA_DQ<4>")
	)
	(segment
		(start 420.009066 -309.639716)
		(end 419.55847 -309.639716)
		(width 0.18288)
		(layer "In2.Cu")
		(net "M_F_CPU0_SA_DQ<4>")
	)
	(segment
		(start 382.029716 -277.01621)
		(end 381.305816 -276.708616)
		(width 0.088646)
		(layer "In2.Cu")
		(net "M_F_CPU0_SA_DQ<4>")
	)
	(segment
		(start 405.83866 -309.96509)
		(end 405.23668 -309.96509)
		(width 0.18288)
		(layer "In2.Cu")
		(net "M_F_CPU0_SA_DQ<4>")
	)
	(segment
		(start 397.544036 -297.83151)
		(end 396.051024 -293.962074)
		(width 0.18288)
		(layer "In2.Cu")
		(net "M_F_CPU0_SA_DQ<4>")
	)
	(segment
		(start 411.725364 -309.89397)
		(end 409.948634 -309.89397)
		(width 0.18288)
		(layer "In2.Cu")
		(net "M_F_CPU0_SA_DQ<4>")
	)
	(segment
		(start 389.616442 -279.18537)
		(end 388.364222 -277.93315)
		(width 0.18288)
		(layer "In2.Cu")
		(net "M_F_CPU0_SA_DQ<4>")
	)
	(segment
		(start 403.472142 -309.396638)
		(end 401.78355 -307.708046)
		(width 0.18288)
		(layer "In2.Cu")
		(net "M_F_CPU0_SA_DQ<4>")
	)
	(segment
		(start 390.833356 -282.12288)
		(end 389.616442 -279.18537)
		(width 0.18288)
		(layer "In2.Cu")
		(net "M_F_CPU0_SA_DQ<4>")
	)
	(segment
		(start 388.364222 -277.93315)
		(end 387.705092 -277.27402)
		(width 0.088646)
		(layer "In2.Cu")
		(net "M_F_CPU0_SA_DQ<4>")
	)
	(segment
		(start 408.436826 -309.507636)
		(end 408.436826 -310.073548)
		(width 0.18288)
		(layer "In2.Cu")
		(net "M_F_CPU0_SA_DQ<4>")
	)
	(segment
		(start 412.466028 -309.668672)
		(end 411.950662 -309.668672)
		(width 0.18288)
		(layer "In2.Cu")
		(net "M_F_CPU0_SA_DQ<4>")
	)
	(segment
		(start 401.54606 -306.950364)
		(end 401.025868 -306.950364)
		(width 0.18288)
		(layer "In2.Cu")
		(net "M_F_CPU0_SA_DQ<4>")
	)
	(segment
		(start 416.761422 -309.639716)
		(end 416.428428 -309.306722)
		(width 0.18288)
		(layer "In2.Cu")
		(net "M_F_CPU0_SA_DQ<4>")
	)
	(segment
		(start 408.436826 -310.073548)
		(end 408.243786 -310.266588)
		(width 0.18288)
		(layer "In2.Cu")
		(net "M_F_CPU0_SA_DQ<4>")
	)
	(segment
		(start 419.55847 -309.639716)
		(end 419.266116 -309.93207)
		(width 0.18288)
		(layer "In2.Cu")
		(net "M_F_CPU0_SA_DQ<4>")
	)
	(segment
		(start 413.154622 -310.22417)
		(end 412.778448 -310.22417)
		(width 0.18288)
		(layer "In2.Cu")
		(net "M_F_CPU0_SA_DQ<4>")
	)
	(segment
		(start 393.094718 -291.005768)
		(end 392.489182 -289.543744)
		(width 0.18288)
		(layer "In2.Cu")
		(net "M_F_CPU0_SA_DQ<4>")
	)
	(segment
		(start 408.243786 -310.266588)
		(end 407.952702 -310.266588)
		(width 0.18288)
		(layer "In2.Cu")
		(net "M_F_CPU0_SA_DQ<4>")
	)
	(segment
		(start 392.489182 -283.778706)
		(end 390.833356 -282.12288)
		(width 0.18288)
		(layer "In2.Cu")
		(net "M_F_CPU0_SA_DQ<4>")
	)
	(segment
		(start 413.762444 -309.616348)
		(end 413.154622 -310.22417)
		(width 0.18288)
		(layer "In2.Cu")
		(net "M_F_CPU0_SA_DQ<4>")
	)
	(segment
		(start 411.950662 -309.668672)
		(end 411.725364 -309.89397)
		(width 0.18288)
		(layer "In2.Cu")
		(net "M_F_CPU0_SA_DQ<4>")
	)
	(segment
		(start 419.266116 -309.93207)
		(end 417.440618 -309.93207)
		(width 0.18288)
		(layer "In2.Cu")
		(net "M_F_CPU0_SA_DQ<4>")
	)
	(segment
		(start 417.440618 -309.93207)
		(end 417.148264 -309.639716)
		(width 0.18288)
		(layer "In2.Cu")
		(net "M_F_CPU0_SA_DQ<4>")
	)
	(segment
		(start 417.148264 -309.639716)
		(end 416.761422 -309.639716)
		(width 0.18288)
		(layer "In2.Cu")
		(net "M_F_CPU0_SA_DQ<4>")
	)
	(segment
		(start 416.428428 -309.306722)
		(end 416.052 -309.306722)
		(width 0.18288)
		(layer "In2.Cu")
		(net "M_F_CPU0_SA_DQ<4>")
	)
	(segment
		(start 400.030696 -305.955192)
		(end 399.793206 -305.717702)
		(width 0.18288)
		(layer "In2.Cu")
		(net "M_F_CPU0_SA_DQ<4>")
	)
	(segment
		(start 398.798034 -304.72253)
		(end 398.798034 -304.202338)
		(width 0.18288)
		(layer "In2.Cu")
		(net "M_F_CPU0_SA_DQ<4>")
	)
	(segment
		(start 383.372868 -277.032974)
		(end 383.372614 -277.032974)
		(width 0.088646)
		(layer "In2.Cu")
		(net "M_F_CPU0_SA_DQ<4>")
	)
	(segment
		(start 412.778448 -310.22417)
		(end 412.626048 -310.07177)
		(width 0.18288)
		(layer "In2.Cu")
		(net "M_F_CPU0_SA_DQ<4>")
	)
	(segment
		(start 412.626048 -309.828692)
		(end 412.466028 -309.668672)
		(width 0.18288)
		(layer "In2.Cu")
		(net "M_F_CPU0_SA_DQ<4>")
	)
	(segment
		(start 382.058418 -277.032974)
		(end 382.029716 -277.01621)
		(width 0.088646)
		(layer "In2.Cu")
		(net "M_F_CPU0_SA_DQ<4>")
	)
	(segment
		(start 399.793206 -305.19751)
		(end 399.555716 -304.96002)
		(width 0.18288)
		(layer "In2.Cu")
		(net "M_F_CPU0_SA_DQ<4>")
	)
	(segment
		(start 405.23668 -309.96509)
		(end 404.777702 -310.424068)
		(width 0.18288)
		(layer "In2.Cu")
		(net "M_F_CPU0_SA_DQ<4>")
	)
	(segment
		(start 406.20696 -309.59679)
		(end 405.83866 -309.96509)
		(width 0.18288)
		(layer "In2.Cu")
		(net "M_F_CPU0_SA_DQ<4>")
	)
	(segment
		(start 387.705092 -277.27402)
		(end 386.944362 -277.27402)
		(width 0.088646)
		(layer "In2.Cu")
		(net "M_F_CPU0_SA_DQ<4>")
	)
	(segment
		(start 401.025868 -306.950364)
		(end 400.788378 -306.712874)
		(width 0.18288)
		(layer "In2.Cu")
		(net "M_F_CPU0_SA_DQ<4>")
	)
	(segment
		(start 398.560544 -303.964848)
		(end 398.040352 -303.964848)
		(width 0.18288)
		(layer "In2.Cu")
		(net "M_F_CPU0_SA_DQ<4>")
	)
	(segment
		(start 399.555716 -304.96002)
		(end 399.035524 -304.96002)
		(width 0.18288)
		(layer "In2.Cu")
		(net "M_F_CPU0_SA_DQ<4>")
	)
	(segment
		(start 414.711134 -309.616348)
		(end 413.762444 -309.616348)
		(width 0.18288)
		(layer "In2.Cu")
		(net "M_F_CPU0_SA_DQ<4>")
	)
	(segment
		(start 409.21432 -309.626)
		(end 408.902916 -309.314596)
		(width 0.18288)
		(layer "In2.Cu")
		(net "M_F_CPU0_SA_DQ<4>")
	)
	(segment
		(start 401.78355 -307.187854)
		(end 401.54606 -306.950364)
		(width 0.18288)
		(layer "In2.Cu")
		(net "M_F_CPU0_SA_DQ<4>")
	)
	(segment
		(start 408.902916 -309.314596)
		(end 408.629866 -309.314596)
		(width 0.18288)
		(layer "In2.Cu")
		(net "M_F_CPU0_SA_DQ<4>")
	)
	(segment
		(start 415.89198 -309.466742)
		(end 415.89198 -309.934102)
		(width 0.18288)
		(layer "In2.Cu")
		(net "M_F_CPU0_SA_DQ<4>")
	)
	(segment
		(start 397.544036 -303.468532)
		(end 397.544036 -297.83151)
		(width 0.18288)
		(layer "In2.Cu")
		(net "M_F_CPU0_SA_DQ<4>")
	)
	(segment
		(start 404.499572 -310.424068)
		(end 404.243286 -310.167782)
		(width 0.18288)
		(layer "In2.Cu")
		(net "M_F_CPU0_SA_DQ<4>")
	)
	(segment
		(start 407.952702 -310.266588)
		(end 407.282904 -309.59679)
		(width 0.18288)
		(layer "In2.Cu")
		(net "M_F_CPU0_SA_DQ<4>")
	)
	(segment
		(start 392.489182 -289.543744)
		(end 392.489182 -283.778706)
		(width 0.18288)
		(layer "In2.Cu")
		(net "M_F_CPU0_SA_DQ<4>")
	)
	(segment
		(start 404.243286 -309.894732)
		(end 404.612094 -309.525924)
		(width 0.18288)
		(layer "In2.Cu")
		(net "M_F_CPU0_SA_DQ<4>")
	)
	(segment
		(start 415.323782 -310.228996)
		(end 414.711134 -309.616348)
		(width 0.18288)
		(layer "In2.Cu")
		(net "M_F_CPU0_SA_DQ<4>")
	)
	(segment
		(start 409.680664 -309.626)
		(end 409.21432 -309.626)
		(width 0.18288)
		(layer "In2.Cu")
		(net "M_F_CPU0_SA_DQ<4>")
	)
	(segment
		(start 408.629866 -309.314596)
		(end 408.436826 -309.507636)
		(width 0.18288)
		(layer "In2.Cu")
		(net "M_F_CPU0_SA_DQ<4>")
	)
	(segment
		(start 412.626048 -310.07177)
		(end 412.626048 -309.828692)
		(width 0.18288)
		(layer "In2.Cu")
		(net "M_F_CPU0_SA_DQ<4>")
	)
	(segment
		(start 401.78355 -307.708046)
		(end 401.78355 -307.187854)
		(width 0.18288)
		(layer "In2.Cu")
		(net "M_F_CPU0_SA_DQ<4>")
	)
	(segment
		(start 398.040352 -303.964848)
		(end 397.544036 -303.468532)
		(width 0.18288)
		(layer "In2.Cu")
		(net "M_F_CPU0_SA_DQ<4>")
	)
	(segment
		(start 407.282904 -309.59679)
		(end 406.20696 -309.59679)
		(width 0.18288)
		(layer "In2.Cu")
		(net "M_F_CPU0_SA_DQ<4>")
	)
	(segment
		(start 415.597086 -310.228996)
		(end 415.323782 -310.228996)
		(width 0.18288)
		(layer "In2.Cu")
		(net "M_F_CPU0_SA_DQ<4>")
	)
	(segment
		(start 415.89198 -309.934102)
		(end 415.597086 -310.228996)
		(width 0.18288)
		(layer "In2.Cu")
		(net "M_F_CPU0_SA_DQ<4>")
	)
	(segment
		(start 404.612094 -309.525924)
		(end 404.612094 -309.253128)
		(width 0.18288)
		(layer "In2.Cu")
		(net "M_F_CPU0_SA_DQ<4>")
	)
	(segment
		(start 398.798034 -304.202338)
		(end 398.560544 -303.964848)
		(width 0.18288)
		(layer "In2.Cu")
		(net "M_F_CPU0_SA_DQ<4>")
	)
	(segment
		(start 404.386796 -309.02783)
		(end 404.114 -309.02783)
		(width 0.18288)
		(layer "In2.Cu")
		(net "M_F_CPU0_SA_DQ<4>")
	)
	(segment
		(start 396.051024 -293.962074)
		(end 393.094718 -291.005768)
		(width 0.18288)
		(layer "In2.Cu")
		(net "M_F_CPU0_SA_DQ<4>")
	)
	(arc
		(start 386.66166 -277.198074)
		(mid 386.474462 -277.147931)
		(end 386.287264 -277.198074)
		(width 0.088646)
		(layer "In2.Cu")
		(net "M_F_CPU0_SA_DQ<4>")
	)
	(arc
		(start 384.496056 -277.032974)
		(mid 384.404108 -277.008337)
		(end 384.31216 -277.032974)
		(width 0.088646)
		(layer "In2.Cu")
		(net "M_F_CPU0_SA_DQ<4>")
	)
	(arc
		(start 383.937764 -277.032974)
		(mid 383.655316 -276.957291)
		(end 383.372868 -277.032974)
		(width 0.088646)
		(layer "In2.Cu")
		(net "M_F_CPU0_SA_DQ<4>")
	)
	(arc
		(start 383.372614 -277.032974)
		(mid 383.185416 -277.083117)
		(end 382.998218 -277.032974)
		(width 0.088646)
		(layer "In2.Cu")
		(net "M_F_CPU0_SA_DQ<4>")
	)
	(arc
		(start 384.311906 -277.032974)
		(mid 384.124852 -277.083058)
		(end 383.937764 -277.032974)
		(width 0.088646)
		(layer "In2.Cu")
		(net "M_F_CPU0_SA_DQ<4>")
	)
	(arc
		(start 386.287264 -277.198074)
		(mid 386.004562 -277.27385)
		(end 385.72186 -277.198074)
		(width 0.088646)
		(layer "In2.Cu")
		(net "M_F_CPU0_SA_DQ<4>")
	)
	(arc
		(start 386.944362 -277.27402)
		(mid 386.919829 -277.273532)
		(end 386.89534 -277.271988)
		(width 0.088646)
		(layer "In2.Cu")
		(net "M_F_CPU0_SA_DQ<4>")
	)
	(arc
		(start 385.72186 -277.198074)
		(mid 385.534662 -277.147931)
		(end 385.347464 -277.198074)
		(width 0.088646)
		(layer "In2.Cu")
		(net "M_F_CPU0_SA_DQ<4>")
	)
	(arc
		(start 382.998218 -277.032974)
		(mid 382.715516 -276.957232)
		(end 382.432814 -277.032974)
		(width 0.088646)
		(layer "In2.Cu")
		(net "M_F_CPU0_SA_DQ<4>")
	)
	(arc
		(start 385.347464 -277.198074)
		(mid 385.064762 -277.27385)
		(end 384.78206 -277.198074)
		(width 0.088646)
		(layer "In2.Cu")
		(net "M_F_CPU0_SA_DQ<4>")
	)
	(arc
		(start 386.89534 -277.271988)
		(mid 386.774441 -277.247859)
		(end 386.66166 -277.198074)
		(width 0.088646)
		(layer "In2.Cu")
		(net "M_F_CPU0_SA_DQ<4>")
	)
	(arc
		(start 382.43256 -277.032974)
		(mid 382.245506 -277.083024)
		(end 382.058418 -277.032974)
		(width 0.088646)
		(layer "In2.Cu")
		(net "M_F_CPU0_SA_DQ<4>")
	)
	(segment
		(start 432.15052 -313.766708)
		(end 433.484782 -313.766708)
		(width 0.20066)
		(layer "F.Cu")
		(net "M_F_CPU0_SA_DQ<3>")
	)
	(segment
		(start 430.382934 -314.19165)
		(end 430.395126 -314.203842)
		(width 0.1016)
		(layer "F.Cu")
		(net "M_F_CPU0_SA_DQ<3>")
	)
	(segment
		(start 382.715516 -279.150064)
		(end 382.715262 -279.150318)
		(width 0.20066)
		(layer "F.Cu")
		(net "M_F_CPU0_SA_DQ<3>")
	)
	(segment
		(start 428.363126 -314.198762)
		(end 428.367952 -314.198762)
		(width 0.101854)
		(layer "F.Cu")
		(net "M_F_CPU0_SA_DQ<3>")
	)
	(segment
		(start 431.280316 -313.99988)
		(end 431.280316 -313.748928)
		(width 0.20066)
		(layer "F.Cu")
		(net "M_F_CPU0_SA_DQ<3>")
	)
	(segment
		(start 427.639226 -313.766708)
		(end 428.07128 -314.198762)
		(width 0.20066)
		(layer "F.Cu")
		(net "M_F_CPU0_SA_DQ<3>")
	)
	(segment
		(start 431.076354 -314.203842)
		(end 431.280316 -313.99988)
		(width 0.20066)
		(layer "F.Cu")
		(net "M_F_CPU0_SA_DQ<3>")
	)
	(segment
		(start 431.280316 -313.748928)
		(end 431.514504 -313.51474)
		(width 0.20066)
		(layer "F.Cu")
		(net "M_F_CPU0_SA_DQ<3>")
	)
	(segment
		(start 431.898552 -313.51474)
		(end 432.15052 -313.766708)
		(width 0.20066)
		(layer "F.Cu")
		(net "M_F_CPU0_SA_DQ<3>")
	)
	(segment
		(start 431.514504 -313.51474)
		(end 431.898552 -313.51474)
		(width 0.20066)
		(layer "F.Cu")
		(net "M_F_CPU0_SA_DQ<3>")
	)
	(segment
		(start 428.07128 -314.198762)
		(end 428.363126 -314.198762)
		(width 0.20066)
		(layer "F.Cu")
		(net "M_F_CPU0_SA_DQ<3>")
	)
	(segment
		(start 424.836082 -313.766708)
		(end 425.940982 -313.766708)
		(width 0.20066)
		(layer "F.Cu")
		(net "M_F_CPU0_SA_DQ<3>")
	)
	(segment
		(start 382.715516 -278.614378)
		(end 382.715516 -279.150064)
		(width 0.20066)
		(layer "F.Cu")
		(net "M_F_CPU0_SA_DQ<3>")
	)
	(segment
		(start 428.375064 -314.19165)
		(end 430.382934 -314.19165)
		(width 0.1016)
		(layer "F.Cu")
		(net "M_F_CPU0_SA_DQ<3>")
	)
	(segment
		(start 428.367952 -314.198762)
		(end 428.375064 -314.19165)
		(width 0.1016)
		(layer "F.Cu")
		(net "M_F_CPU0_SA_DQ<3>")
	)
	(segment
		(start 425.940982 -313.766708)
		(end 427.639226 -313.766708)
		(width 0.20066)
		(layer "F.Cu")
		(net "M_F_CPU0_SA_DQ<3>")
	)
	(segment
		(start 430.395126 -314.203842)
		(end 431.076354 -314.203842)
		(width 0.20066)
		(layer "F.Cu")
		(net "M_F_CPU0_SA_DQ<3>")
	)
	(segment
		(start 382.949958 -278.858472)
		(end 382.871726 -278.8793)
		(width 0.088646)
		(layer "In2.Cu")
		(net "M_F_CPU0_SA_DQ<3>")
	)
	(segment
		(start 424.04411 -314.00877)
		(end 424.04411 -314.673742)
		(width 0.18288)
		(layer "In2.Cu")
		(net "M_F_CPU0_SA_DQ<3>")
	)
	(segment
		(start 382.871726 -278.8793)
		(end 382.715262 -279.150318)
		(width 0.088646)
		(layer "In2.Cu")
		(net "M_F_CPU0_SA_DQ<3>")
	)
	(segment
		(start 424.836082 -313.766708)
		(end 424.286172 -313.766708)
		(width 0.18288)
		(layer "In2.Cu")
		(net "M_F_CPU0_SA_DQ<3>")
	)
	(segment
		(start 408.162506 -315.035946)
		(end 405.644096 -315.035946)
		(width 0.18288)
		(layer "In2.Cu")
		(net "M_F_CPU0_SA_DQ<3>")
	)
	(segment
		(start 420.670482 -315.042804)
		(end 420.17442 -315.042804)
		(width 0.18288)
		(layer "In2.Cu")
		(net "M_F_CPU0_SA_DQ<3>")
	)
	(segment
		(start 389.817102 -290.077652)
		(end 389.817102 -284.230318)
		(width 0.18288)
		(layer "In2.Cu")
		(net "M_F_CPU0_SA_DQ<3>")
	)
	(segment
		(start 408.185874 -315.059314)
		(end 408.162506 -315.035946)
		(width 0.18288)
		(layer "In2.Cu")
		(net "M_F_CPU0_SA_DQ<3>")
	)
	(segment
		(start 389.24992 -283.663136)
		(end 388.003796 -280.655014)
		(width 0.18288)
		(layer "In2.Cu")
		(net "M_F_CPU0_SA_DQ<3>")
	)
	(segment
		(start 394.462254 -304.436272)
		(end 394.462254 -298.336716)
		(width 0.18288)
		(layer "In2.Cu")
		(net "M_F_CPU0_SA_DQ<3>")
	)
	(segment
		(start 415.221166 -315.00064)
		(end 414.986724 -315.235082)
		(width 0.18288)
		(layer "In2.Cu")
		(net "M_F_CPU0_SA_DQ<3>")
	)
	(segment
		(start 423.824654 -314.893198)
		(end 422.95953 -314.893198)
		(width 0.18288)
		(layer "In2.Cu")
		(net "M_F_CPU0_SA_DQ<3>")
	)
	(segment
		(start 412.76905 -314.936378)
		(end 412.646114 -315.059314)
		(width 0.18288)
		(layer "In2.Cu")
		(net "M_F_CPU0_SA_DQ<3>")
	)
	(segment
		(start 412.646114 -315.059314)
		(end 408.185874 -315.059314)
		(width 0.18288)
		(layer "In2.Cu")
		(net "M_F_CPU0_SA_DQ<3>")
	)
	(segment
		(start 415.580068 -315.00064)
		(end 415.221166 -315.00064)
		(width 0.18288)
		(layer "In2.Cu")
		(net "M_F_CPU0_SA_DQ<3>")
	)
	(segment
		(start 387.088126 -279.897586)
		(end 386.655564 -279.897586)
		(width 0.088646)
		(layer "In2.Cu")
		(net "M_F_CPU0_SA_DQ<3>")
	)
	(segment
		(start 413.608774 -315.235082)
		(end 413.31007 -314.936378)
		(width 0.18288)
		(layer "In2.Cu")
		(net "M_F_CPU0_SA_DQ<3>")
	)
	(segment
		(start 383.937764 -279.639776)
		(end 383.92735 -279.645872)
		(width 0.088646)
		(layer "In2.Cu")
		(net "M_F_CPU0_SA_DQ<3>")
	)
	(segment
		(start 394.462254 -298.336716)
		(end 393.167362 -295.21023)
		(width 0.18288)
		(layer "In2.Cu")
		(net "M_F_CPU0_SA_DQ<3>")
	)
	(segment
		(start 417.253674 -315.365892)
		(end 415.94532 -315.365892)
		(width 0.18288)
		(layer "In2.Cu")
		(net "M_F_CPU0_SA_DQ<3>")
	)
	(segment
		(start 420.02202 -315.195204)
		(end 419.378892 -315.195204)
		(width 0.18288)
		(layer "In2.Cu")
		(net "M_F_CPU0_SA_DQ<3>")
	)
	(segment
		(start 404.650194 -314.624212)
		(end 394.462254 -304.436272)
		(width 0.18288)
		(layer "In2.Cu")
		(net "M_F_CPU0_SA_DQ<3>")
	)
	(segment
		(start 420.672006 -315.04128)
		(end 420.670482 -315.042804)
		(width 0.18288)
		(layer "In2.Cu")
		(net "M_F_CPU0_SA_DQ<3>")
	)
	(segment
		(start 389.817102 -284.230318)
		(end 389.24992 -283.663136)
		(width 0.18288)
		(layer "In2.Cu")
		(net "M_F_CPU0_SA_DQ<3>")
	)
	(segment
		(start 388.003796 -280.655014)
		(end 387.246368 -279.897586)
		(width 0.18288)
		(layer "In2.Cu")
		(net "M_F_CPU0_SA_DQ<3>")
	)
	(segment
		(start 422.811448 -315.04128)
		(end 420.672006 -315.04128)
		(width 0.18288)
		(layer "In2.Cu")
		(net "M_F_CPU0_SA_DQ<3>")
	)
	(segment
		(start 386.655564 -279.897586)
		(end 386.36067 -279.602692)
		(width 0.088646)
		(layer "In2.Cu")
		(net "M_F_CPU0_SA_DQ<3>")
	)
	(segment
		(start 420.17442 -315.042804)
		(end 420.02202 -315.195204)
		(width 0.18288)
		(layer "In2.Cu")
		(net "M_F_CPU0_SA_DQ<3>")
	)
	(segment
		(start 391.077196 -293.120064)
		(end 389.817102 -290.077652)
		(width 0.18288)
		(layer "In2.Cu")
		(net "M_F_CPU0_SA_DQ<3>")
	)
	(segment
		(start 419.22954 -315.045852)
		(end 417.573714 -315.045852)
		(width 0.18288)
		(layer "In2.Cu")
		(net "M_F_CPU0_SA_DQ<3>")
	)
	(segment
		(start 405.644096 -315.035946)
		(end 404.650194 -314.624212)
		(width 0.18288)
		(layer "In2.Cu")
		(net "M_F_CPU0_SA_DQ<3>")
	)
	(segment
		(start 383.089912 -279.165812)
		(end 383.089912 -279.150318)
		(width 0.088646)
		(layer "In2.Cu")
		(net "M_F_CPU0_SA_DQ<3>")
	)
	(segment
		(start 419.378892 -315.195204)
		(end 419.22954 -315.045852)
		(width 0.18288)
		(layer "In2.Cu")
		(net "M_F_CPU0_SA_DQ<3>")
	)
	(segment
		(start 393.167362 -295.21023)
		(end 391.077196 -293.120064)
		(width 0.18288)
		(layer "In2.Cu")
		(net "M_F_CPU0_SA_DQ<3>")
	)
	(segment
		(start 384.877564 -279.639776)
		(end 384.862832 -279.648412)
		(width 0.088646)
		(layer "In2.Cu")
		(net "M_F_CPU0_SA_DQ<3>")
	)
	(segment
		(start 424.286172 -313.766708)
		(end 424.04411 -314.00877)
		(width 0.18288)
		(layer "In2.Cu")
		(net "M_F_CPU0_SA_DQ<3>")
	)
	(segment
		(start 387.246368 -279.897586)
		(end 387.088126 -279.897586)
		(width 0.18288)
		(layer "In2.Cu")
		(net "M_F_CPU0_SA_DQ<3>")
	)
	(segment
		(start 417.573714 -315.045852)
		(end 417.253674 -315.365892)
		(width 0.18288)
		(layer "In2.Cu")
		(net "M_F_CPU0_SA_DQ<3>")
	)
	(segment
		(start 422.95953 -314.893198)
		(end 422.811448 -315.04128)
		(width 0.18288)
		(layer "In2.Cu")
		(net "M_F_CPU0_SA_DQ<3>")
	)
	(segment
		(start 386.36067 -279.602692)
		(end 385.980178 -279.602692)
		(width 0.088646)
		(layer "In2.Cu")
		(net "M_F_CPU0_SA_DQ<3>")
	)
	(segment
		(start 414.986724 -315.235082)
		(end 413.608774 -315.235082)
		(width 0.18288)
		(layer "In2.Cu")
		(net "M_F_CPU0_SA_DQ<3>")
	)
	(segment
		(start 415.94532 -315.365892)
		(end 415.580068 -315.00064)
		(width 0.18288)
		(layer "In2.Cu")
		(net "M_F_CPU0_SA_DQ<3>")
	)
	(segment
		(start 413.31007 -314.936378)
		(end 412.76905 -314.936378)
		(width 0.18288)
		(layer "In2.Cu")
		(net "M_F_CPU0_SA_DQ<3>")
	)
	(segment
		(start 424.04411 -314.673742)
		(end 423.824654 -314.893198)
		(width 0.18288)
		(layer "In2.Cu")
		(net "M_F_CPU0_SA_DQ<3>")
	)
	(arc
		(start 384.862832 -279.648412)
		(mid 384.586357 -279.715732)
		(end 384.31216 -279.639776)
		(width 0.088646)
		(layer "In2.Cu")
		(net "M_F_CPU0_SA_DQ<3>")
	)
	(arc
		(start 385.25196 -279.639776)
		(mid 385.064762 -279.589633)
		(end 384.877564 -279.639776)
		(width 0.088646)
		(layer "In2.Cu")
		(net "M_F_CPU0_SA_DQ<3>")
	)
	(arc
		(start 384.31216 -279.639776)
		(mid 384.124962 -279.589633)
		(end 383.937764 -279.639776)
		(width 0.088646)
		(layer "In2.Cu")
		(net "M_F_CPU0_SA_DQ<3>")
	)
	(arc
		(start 383.089912 -279.150318)
		(mid 383.053052 -278.988521)
		(end 382.949958 -278.858472)
		(width 0.088646)
		(layer "In2.Cu")
		(net "M_F_CPU0_SA_DQ<3>")
	)
	(arc
		(start 385.802632 -279.648412)
		(mid 385.526157 -279.715732)
		(end 385.25196 -279.639776)
		(width 0.088646)
		(layer "In2.Cu")
		(net "M_F_CPU0_SA_DQ<3>")
	)
	(arc
		(start 383.372106 -279.639776)
		(mid 383.169283 -279.439545)
		(end 383.089912 -279.165812)
		(width 0.088646)
		(layer "In2.Cu")
		(net "M_F_CPU0_SA_DQ<3>")
	)
	(arc
		(start 385.980178 -279.602692)
		(mid 385.888577 -279.614559)
		(end 385.802632 -279.648412)
		(width 0.088646)
		(layer "In2.Cu")
		(net "M_F_CPU0_SA_DQ<3>")
	)
	(arc
		(start 383.92735 -279.645872)
		(mid 383.648918 -279.715718)
		(end 383.372106 -279.639776)
		(width 0.088646)
		(layer "In2.Cu")
		(net "M_F_CPU0_SA_DQ<3>")
	)
	(segment
		(start 427.639226 -279.766776)
		(end 428.07128 -280.19883)
		(width 0.20066)
		(layer "F.Cu")
		(net "M_F_CPU0_SA_DQ<31>")
	)
	(segment
		(start 432.15052 -279.766776)
		(end 433.484782 -279.766776)
		(width 0.20066)
		(layer "F.Cu")
		(net "M_F_CPU0_SA_DQ<31>")
	)
	(segment
		(start 430.395126 -280.20391)
		(end 431.076354 -280.20391)
		(width 0.20066)
		(layer "F.Cu")
		(net "M_F_CPU0_SA_DQ<31>")
	)
	(segment
		(start 424.836082 -279.766776)
		(end 425.940982 -279.766776)
		(width 0.20066)
		(layer "F.Cu")
		(net "M_F_CPU0_SA_DQ<31>")
	)
	(segment
		(start 428.375064 -280.191718)
		(end 430.382934 -280.191718)
		(width 0.1016)
		(layer "F.Cu")
		(net "M_F_CPU0_SA_DQ<31>")
	)
	(segment
		(start 431.514504 -279.514808)
		(end 431.898552 -279.514808)
		(width 0.20066)
		(layer "F.Cu")
		(net "M_F_CPU0_SA_DQ<31>")
	)
	(segment
		(start 428.07128 -280.19883)
		(end 428.363126 -280.19883)
		(width 0.20066)
		(layer "F.Cu")
		(net "M_F_CPU0_SA_DQ<31>")
	)
	(segment
		(start 431.280316 -279.999948)
		(end 431.280316 -279.748996)
		(width 0.20066)
		(layer "F.Cu")
		(net "M_F_CPU0_SA_DQ<31>")
	)
	(segment
		(start 431.280316 -279.748996)
		(end 431.514504 -279.514808)
		(width 0.20066)
		(layer "F.Cu")
		(net "M_F_CPU0_SA_DQ<31>")
	)
	(segment
		(start 379.425962 -258.2672)
		(end 379.426216 -258.267454)
		(width 0.20066)
		(layer "F.Cu")
		(net "M_F_CPU0_SA_DQ<31>")
	)
	(segment
		(start 428.367952 -280.19883)
		(end 428.375064 -280.191718)
		(width 0.1016)
		(layer "F.Cu")
		(net "M_F_CPU0_SA_DQ<31>")
	)
	(segment
		(start 431.898552 -279.514808)
		(end 432.15052 -279.766776)
		(width 0.20066)
		(layer "F.Cu")
		(net "M_F_CPU0_SA_DQ<31>")
	)
	(segment
		(start 430.382934 -280.191718)
		(end 430.395126 -280.20391)
		(width 0.1016)
		(layer "F.Cu")
		(net "M_F_CPU0_SA_DQ<31>")
	)
	(segment
		(start 431.076354 -280.20391)
		(end 431.280316 -279.999948)
		(width 0.20066)
		(layer "F.Cu")
		(net "M_F_CPU0_SA_DQ<31>")
	)
	(segment
		(start 425.940982 -279.766776)
		(end 427.639226 -279.766776)
		(width 0.20066)
		(layer "F.Cu")
		(net "M_F_CPU0_SA_DQ<31>")
	)
	(segment
		(start 379.426216 -258.267454)
		(end 379.426216 -258.80314)
		(width 0.20066)
		(layer "F.Cu")
		(net "M_F_CPU0_SA_DQ<31>")
	)
	(segment
		(start 428.363126 -280.19883)
		(end 428.367952 -280.19883)
		(width 0.101854)
		(layer "F.Cu")
		(net "M_F_CPU0_SA_DQ<31>")
	)
	(segment
		(start 408.536394 -267.593826)
		(end 407.581608 -267.593826)
		(width 0.18288)
		(layer "In4.Cu")
		(net "M_F_CPU0_SA_DQ<31>")
	)
	(segment
		(start 418.686996 -270.144494)
		(end 416.521646 -270.144494)
		(width 0.18288)
		(layer "In4.Cu")
		(net "M_F_CPU0_SA_DQ<31>")
	)
	(segment
		(start 382.528064 -258.313428)
		(end 382.51765 -258.307332)
		(width 0.088646)
		(layer "In4.Cu")
		(net "M_F_CPU0_SA_DQ<31>")
	)
	(segment
		(start 409.247594 -268.305026)
		(end 408.536394 -267.593826)
		(width 0.18288)
		(layer "In4.Cu")
		(net "M_F_CPU0_SA_DQ<31>")
	)
	(segment
		(start 423.689018 -272.102072)
		(end 422.428162 -270.841216)
		(width 0.18288)
		(layer "In4.Cu")
		(net "M_F_CPU0_SA_DQ<31>")
	)
	(segment
		(start 419.808406 -270.454882)
		(end 418.997384 -270.454882)
		(width 0.18288)
		(layer "In4.Cu")
		(net "M_F_CPU0_SA_DQ<31>")
	)
	(segment
		(start 380.648464 -258.313428)
		(end 380.63805 -258.307332)
		(width 0.088646)
		(layer "In4.Cu")
		(net "M_F_CPU0_SA_DQ<31>")
	)
	(segment
		(start 413.324294 -268.178026)
		(end 412.460694 -268.178026)
		(width 0.18288)
		(layer "In4.Cu")
		(net "M_F_CPU0_SA_DQ<31>")
	)
	(segment
		(start 415.722054 -269.344902)
		(end 414.49117 -269.344902)
		(width 0.18288)
		(layer "In4.Cu")
		(net "M_F_CPU0_SA_DQ<31>")
	)
	(segment
		(start 424.228768 -279.766776)
		(end 423.689018 -279.227026)
		(width 0.18288)
		(layer "In4.Cu")
		(net "M_F_CPU0_SA_DQ<31>")
	)
	(segment
		(start 420.19474 -270.841216)
		(end 419.808406 -270.454882)
		(width 0.18288)
		(layer "In4.Cu")
		(net "M_F_CPU0_SA_DQ<31>")
	)
	(segment
		(start 386.668518 -258.405122)
		(end 386.666486 -258.40309)
		(width 0.088646)
		(layer "In4.Cu")
		(net "M_F_CPU0_SA_DQ<31>")
	)
	(segment
		(start 416.521646 -270.144494)
		(end 415.722054 -269.344902)
		(width 0.18288)
		(layer "In4.Cu")
		(net "M_F_CPU0_SA_DQ<31>")
	)
	(segment
		(start 384.797046 -258.304792)
		(end 384.782314 -258.313428)
		(width 0.088646)
		(layer "In4.Cu")
		(net "M_F_CPU0_SA_DQ<31>")
	)
	(segment
		(start 424.836082 -279.766776)
		(end 424.228768 -279.766776)
		(width 0.18288)
		(layer "In4.Cu")
		(net "M_F_CPU0_SA_DQ<31>")
	)
	(segment
		(start 380.083314 -258.313428)
		(end 380.007114 -258.35737)
		(width 0.088646)
		(layer "In4.Cu")
		(net "M_F_CPU0_SA_DQ<31>")
	)
	(segment
		(start 405.327612 -266.286996)
		(end 398.925288 -259.884672)
		(width 0.18288)
		(layer "In4.Cu")
		(net "M_F_CPU0_SA_DQ<31>")
	)
	(segment
		(start 385.736846 -258.304792)
		(end 385.722114 -258.313428)
		(width 0.088646)
		(layer "In4.Cu")
		(net "M_F_CPU0_SA_DQ<31>")
	)
	(segment
		(start 412.460694 -268.178026)
		(end 412.333694 -268.305026)
		(width 0.18288)
		(layer "In4.Cu")
		(net "M_F_CPU0_SA_DQ<31>")
	)
	(segment
		(start 414.49117 -269.344902)
		(end 413.324294 -268.178026)
		(width 0.18288)
		(layer "In4.Cu")
		(net "M_F_CPU0_SA_DQ<31>")
	)
	(segment
		(start 407.581608 -267.593826)
		(end 406.274778 -266.286996)
		(width 0.18288)
		(layer "In4.Cu")
		(net "M_F_CPU0_SA_DQ<31>")
	)
	(segment
		(start 387.494018 -258.405122)
		(end 386.668518 -258.405122)
		(width 0.088646)
		(layer "In4.Cu")
		(net "M_F_CPU0_SA_DQ<31>")
	)
	(segment
		(start 386.666486 -258.40309)
		(end 386.404612 -258.40309)
		(width 0.088646)
		(layer "In4.Cu")
		(net "M_F_CPU0_SA_DQ<31>")
	)
	(segment
		(start 393.981432 -259.884672)
		(end 392.592814 -259.60832)
		(width 0.18288)
		(layer "In4.Cu")
		(net "M_F_CPU0_SA_DQ<31>")
	)
	(segment
		(start 406.274778 -266.286996)
		(end 405.327612 -266.286996)
		(width 0.18288)
		(layer "In4.Cu")
		(net "M_F_CPU0_SA_DQ<31>")
	)
	(segment
		(start 392.592814 -259.60832)
		(end 389.68807 -258.405122)
		(width 0.18288)
		(layer "In4.Cu")
		(net "M_F_CPU0_SA_DQ<31>")
	)
	(segment
		(start 418.997384 -270.454882)
		(end 418.686996 -270.144494)
		(width 0.18288)
		(layer "In4.Cu")
		(net "M_F_CPU0_SA_DQ<31>")
	)
	(segment
		(start 423.689018 -279.227026)
		(end 423.689018 -272.102072)
		(width 0.18288)
		(layer "In4.Cu")
		(net "M_F_CPU0_SA_DQ<31>")
	)
	(segment
		(start 383.852674 -258.307332)
		(end 383.84226 -258.313428)
		(width 0.088646)
		(layer "In4.Cu")
		(net "M_F_CPU0_SA_DQ<31>")
	)
	(segment
		(start 412.333694 -268.305026)
		(end 409.247594 -268.305026)
		(width 0.18288)
		(layer "In4.Cu")
		(net "M_F_CPU0_SA_DQ<31>")
	)
	(segment
		(start 422.428162 -270.841216)
		(end 420.19474 -270.841216)
		(width 0.18288)
		(layer "In4.Cu")
		(net "M_F_CPU0_SA_DQ<31>")
	)
	(segment
		(start 398.925288 -259.884672)
		(end 393.981432 -259.884672)
		(width 0.18288)
		(layer "In4.Cu")
		(net "M_F_CPU0_SA_DQ<31>")
	)
	(segment
		(start 389.68807 -258.405122)
		(end 387.494018 -258.405122)
		(width 0.18288)
		(layer "In4.Cu")
		(net "M_F_CPU0_SA_DQ<31>")
	)
	(segment
		(start 381.588518 -258.313428)
		(end 381.578104 -258.307332)
		(width 0.088646)
		(layer "In4.Cu")
		(net "M_F_CPU0_SA_DQ<31>")
	)
	(arc
		(start 381.02286 -258.313428)
		(mid 380.835662 -258.363571)
		(end 380.648464 -258.313428)
		(width 0.088646)
		(layer "In4.Cu")
		(net "M_F_CPU0_SA_DQ<31>")
	)
	(arc
		(start 384.782314 -258.313428)
		(mid 384.595116 -258.363571)
		(end 384.407918 -258.313428)
		(width 0.088646)
		(layer "In4.Cu")
		(net "M_F_CPU0_SA_DQ<31>")
	)
	(arc
		(start 385.722114 -258.313428)
		(mid 385.534916 -258.363571)
		(end 385.347718 -258.313428)
		(width 0.088646)
		(layer "In4.Cu")
		(net "M_F_CPU0_SA_DQ<31>")
	)
	(arc
		(start 380.63805 -258.307332)
		(mid 380.359872 -258.23764)
		(end 380.083314 -258.313428)
		(width 0.088646)
		(layer "In4.Cu")
		(net "M_F_CPU0_SA_DQ<31>")
	)
	(arc
		(start 382.51765 -258.307332)
		(mid 382.239472 -258.23764)
		(end 381.962914 -258.313428)
		(width 0.088646)
		(layer "In4.Cu")
		(net "M_F_CPU0_SA_DQ<31>")
	)
	(arc
		(start 386.404612 -258.40309)
		(mid 386.348996 -258.354432)
		(end 386.287518 -258.313428)
		(width 0.088646)
		(layer "In4.Cu")
		(net "M_F_CPU0_SA_DQ<31>")
	)
	(arc
		(start 381.962914 -258.313428)
		(mid 381.775716 -258.363571)
		(end 381.588518 -258.313428)
		(width 0.088646)
		(layer "In4.Cu")
		(net "M_F_CPU0_SA_DQ<31>")
	)
	(arc
		(start 381.578104 -258.307332)
		(mid 381.299672 -258.237518)
		(end 381.02286 -258.313428)
		(width 0.088646)
		(layer "In4.Cu")
		(net "M_F_CPU0_SA_DQ<31>")
	)
	(arc
		(start 386.287518 -258.313428)
		(mid 386.013289 -258.237503)
		(end 385.736846 -258.304792)
		(width 0.088646)
		(layer "In4.Cu")
		(net "M_F_CPU0_SA_DQ<31>")
	)
	(arc
		(start 384.407918 -258.313428)
		(mid 384.131105 -258.237592)
		(end 383.852674 -258.307332)
		(width 0.088646)
		(layer "In4.Cu")
		(net "M_F_CPU0_SA_DQ<31>")
	)
	(arc
		(start 383.84226 -258.313428)
		(mid 383.655062 -258.363571)
		(end 383.467864 -258.313428)
		(width 0.088646)
		(layer "In4.Cu")
		(net "M_F_CPU0_SA_DQ<31>")
	)
	(arc
		(start 383.467864 -258.313428)
		(mid 383.185162 -258.237686)
		(end 382.90246 -258.313428)
		(width 0.088646)
		(layer "In4.Cu")
		(net "M_F_CPU0_SA_DQ<31>")
	)
	(arc
		(start 385.347718 -258.313428)
		(mid 385.073489 -258.237503)
		(end 384.797046 -258.304792)
		(width 0.088646)
		(layer "In4.Cu")
		(net "M_F_CPU0_SA_DQ<31>")
	)
	(arc
		(start 380.007114 -258.35737)
		(mid 379.702058 -258.561219)
		(end 379.426216 -258.80314)
		(width 0.088646)
		(layer "In4.Cu")
		(net "M_F_CPU0_SA_DQ<31>")
	)
	(arc
		(start 382.90246 -258.313428)
		(mid 382.715262 -258.363571)
		(end 382.528064 -258.313428)
		(width 0.088646)
		(layer "In4.Cu")
		(net "M_F_CPU0_SA_DQ<31>")
	)
	(segment
		(start 431.280316 -281.449018)
		(end 431.280316 -281.69997)
		(width 0.20066)
		(layer "F.Cu")
		(net "M_F_CPU0_SA_DQ<30>")
	)
	(segment
		(start 427.639226 -281.466798)
		(end 425.940982 -281.466798)
		(width 0.20066)
		(layer "F.Cu")
		(net "M_F_CPU0_SA_DQ<30>")
	)
	(segment
		(start 379.896116 -259.093462)
		(end 379.895862 -259.616956)
		(width 0.20066)
		(layer "F.Cu")
		(net "M_F_CPU0_SA_DQ<30>")
	)
	(segment
		(start 431.280316 -281.69997)
		(end 431.076354 -281.903932)
		(width 0.20066)
		(layer "F.Cu")
		(net "M_F_CPU0_SA_DQ<30>")
	)
	(segment
		(start 428.367952 -281.898852)
		(end 428.363126 -281.898852)
		(width 0.101854)
		(layer "F.Cu")
		(net "M_F_CPU0_SA_DQ<30>")
	)
	(segment
		(start 424.836082 -281.466544)
		(end 424.836336 -281.466798)
		(width 0.20066)
		(layer "F.Cu")
		(net "M_F_CPU0_SA_DQ<30>")
	)
	(segment
		(start 379.896116 -259.081016)
		(end 379.896116 -259.093462)
		(width 0.20066)
		(layer "F.Cu")
		(net "M_F_CPU0_SA_DQ<30>")
	)
	(segment
		(start 428.363126 -281.898852)
		(end 428.07128 -281.898852)
		(width 0.20066)
		(layer "F.Cu")
		(net "M_F_CPU0_SA_DQ<30>")
	)
	(segment
		(start 430.395126 -281.903932)
		(end 430.382934 -281.89174)
		(width 0.1016)
		(layer "F.Cu")
		(net "M_F_CPU0_SA_DQ<30>")
	)
	(segment
		(start 433.484782 -281.466798)
		(end 432.15052 -281.466798)
		(width 0.20066)
		(layer "F.Cu")
		(net "M_F_CPU0_SA_DQ<30>")
	)
	(segment
		(start 428.375064 -281.89174)
		(end 428.367952 -281.898852)
		(width 0.1016)
		(layer "F.Cu")
		(net "M_F_CPU0_SA_DQ<30>")
	)
	(segment
		(start 431.898552 -281.21483)
		(end 431.514504 -281.21483)
		(width 0.20066)
		(layer "F.Cu")
		(net "M_F_CPU0_SA_DQ<30>")
	)
	(segment
		(start 428.07128 -281.898852)
		(end 427.639226 -281.466798)
		(width 0.20066)
		(layer "F.Cu")
		(net "M_F_CPU0_SA_DQ<30>")
	)
	(segment
		(start 432.15052 -281.466798)
		(end 431.898552 -281.21483)
		(width 0.20066)
		(layer "F.Cu")
		(net "M_F_CPU0_SA_DQ<30>")
	)
	(segment
		(start 424.836336 -281.466798)
		(end 425.940982 -281.466798)
		(width 0.20066)
		(layer "F.Cu")
		(net "M_F_CPU0_SA_DQ<30>")
	)
	(segment
		(start 430.382934 -281.89174)
		(end 428.375064 -281.89174)
		(width 0.1016)
		(layer "F.Cu")
		(net "M_F_CPU0_SA_DQ<30>")
	)
	(segment
		(start 431.076354 -281.903932)
		(end 430.395126 -281.903932)
		(width 0.20066)
		(layer "F.Cu")
		(net "M_F_CPU0_SA_DQ<30>")
	)
	(segment
		(start 431.514504 -281.21483)
		(end 431.280316 -281.449018)
		(width 0.20066)
		(layer "F.Cu")
		(net "M_F_CPU0_SA_DQ<30>")
	)
	(segment
		(start 380.553214 -259.127498)
		(end 380.474982 -259.172456)
		(width 0.088646)
		(layer "In4.Cu")
		(net "M_F_CPU0_SA_DQ<30>")
	)
	(segment
		(start 416.99688 -272.429986)
		(end 415.435288 -270.868394)
		(width 0.18288)
		(layer "In4.Cu")
		(net "M_F_CPU0_SA_DQ<30>")
	)
	(segment
		(start 420.052754 -278.282146)
		(end 419.763702 -278.282146)
		(width 0.18288)
		(layer "In4.Cu")
		(net "M_F_CPU0_SA_DQ<30>")
	)
	(segment
		(start 382.062736 -259.130038)
		(end 382.058164 -259.127498)
		(width 0.088646)
		(layer "In4.Cu")
		(net "M_F_CPU0_SA_DQ<30>")
	)
	(segment
		(start 393.730988 -260.721602)
		(end 393.624562 -260.677406)
		(width 0.18288)
		(layer "In4.Cu")
		(net "M_F_CPU0_SA_DQ<30>")
	)
	(segment
		(start 422.722294 -281.992832)
		(end 421.77208 -281.042618)
		(width 0.18288)
		(layer "In4.Cu")
		(net "M_F_CPU0_SA_DQ<30>")
	)
	(segment
		(start 398.093692 -260.880352)
		(end 394.331444 -260.880352)
		(width 0.18288)
		(layer "In4.Cu")
		(net "M_F_CPU0_SA_DQ<30>")
	)
	(segment
		(start 419.580822 -278.099266)
		(end 419.580822 -277.771606)
		(width 0.18288)
		(layer "In4.Cu")
		(net "M_F_CPU0_SA_DQ<30>")
	)
	(segment
		(start 410.077666 -270.002254)
		(end 409.946094 -270.133826)
		(width 0.18288)
		(layer "In4.Cu")
		(net "M_F_CPU0_SA_DQ<30>")
	)
	(segment
		(start 409.438094 -270.133826)
		(end 408.574494 -269.270226)
		(width 0.18288)
		(layer "In4.Cu")
		(net "M_F_CPU0_SA_DQ<30>")
	)
	(segment
		(start 381.122936 -259.130038)
		(end 381.110998 -259.12318)
		(width 0.088646)
		(layer "In4.Cu")
		(net "M_F_CPU0_SA_DQ<30>")
	)
	(segment
		(start 420.235634 -280.882598)
		(end 420.235634 -278.465026)
		(width 0.18288)
		(layer "In4.Cu")
		(net "M_F_CPU0_SA_DQ<30>")
	)
	(segment
		(start 393.911328 -260.796532)
		(end 393.730988 -260.721602)
		(width 0.18288)
		(layer "In4.Cu")
		(net "M_F_CPU0_SA_DQ<30>")
	)
	(segment
		(start 384.326638 -259.118862)
		(end 384.311906 -259.127498)
		(width 0.088646)
		(layer "In4.Cu")
		(net "M_F_CPU0_SA_DQ<30>")
	)
	(segment
		(start 412.131002 -270.002254)
		(end 410.077666 -270.002254)
		(width 0.18288)
		(layer "In4.Cu")
		(net "M_F_CPU0_SA_DQ<30>")
	)
	(segment
		(start 420.395654 -281.042618)
		(end 420.235634 -280.882598)
		(width 0.18288)
		(layer "In4.Cu")
		(net "M_F_CPU0_SA_DQ<30>")
	)
	(segment
		(start 407.79065 -269.270226)
		(end 406.736296 -268.215872)
		(width 0.18288)
		(layer "In4.Cu")
		(net "M_F_CPU0_SA_DQ<30>")
	)
	(segment
		(start 393.624562 -260.677406)
		(end 392.96848 -260.49351)
		(width 0.18288)
		(layer "In4.Cu")
		(net "M_F_CPU0_SA_DQ<30>")
	)
	(segment
		(start 382.997964 -259.127498)
		(end 382.990598 -259.12318)
		(width 0.088646)
		(layer "In4.Cu")
		(net "M_F_CPU0_SA_DQ<30>")
	)
	(segment
		(start 420.235634 -275.219414)
		(end 417.446206 -272.429986)
		(width 0.18288)
		(layer "In4.Cu")
		(net "M_F_CPU0_SA_DQ<30>")
	)
	(segment
		(start 419.580822 -277.771606)
		(end 419.763702 -277.588726)
		(width 0.18288)
		(layer "In4.Cu")
		(net "M_F_CPU0_SA_DQ<30>")
	)
	(segment
		(start 409.946094 -270.133826)
		(end 409.438094 -270.133826)
		(width 0.18288)
		(layer "In4.Cu")
		(net "M_F_CPU0_SA_DQ<30>")
	)
	(segment
		(start 392.96848 -260.49351)
		(end 389.61822 -259.105654)
		(width 0.18288)
		(layer "In4.Cu")
		(net "M_F_CPU0_SA_DQ<30>")
	)
	(segment
		(start 419.763702 -278.282146)
		(end 419.580822 -278.099266)
		(width 0.18288)
		(layer "In4.Cu")
		(net "M_F_CPU0_SA_DQ<30>")
	)
	(segment
		(start 420.052754 -277.588726)
		(end 420.235634 -277.405846)
		(width 0.18288)
		(layer "In4.Cu")
		(net "M_F_CPU0_SA_DQ<30>")
	)
	(segment
		(start 384.311906 -259.127498)
		(end 384.303524 -259.132324)
		(width 0.088646)
		(layer "In4.Cu")
		(net "M_F_CPU0_SA_DQ<30>")
	)
	(segment
		(start 405.429212 -268.215872)
		(end 398.093692 -260.880352)
		(width 0.18288)
		(layer "In4.Cu")
		(net "M_F_CPU0_SA_DQ<30>")
	)
	(segment
		(start 385.266438 -259.118862)
		(end 385.251706 -259.127498)
		(width 0.088646)
		(layer "In4.Cu")
		(net "M_F_CPU0_SA_DQ<30>")
	)
	(segment
		(start 383.368042 -259.130038)
		(end 383.365248 -259.131562)
		(width 0.088646)
		(layer "In4.Cu")
		(net "M_F_CPU0_SA_DQ<30>")
	)
	(segment
		(start 389.61822 -259.105654)
		(end 387.494018 -259.105654)
		(width 0.18288)
		(layer "In4.Cu")
		(net "M_F_CPU0_SA_DQ<30>")
	)
	(segment
		(start 412.997142 -270.868394)
		(end 412.131002 -270.002254)
		(width 0.18288)
		(layer "In4.Cu")
		(net "M_F_CPU0_SA_DQ<30>")
	)
	(segment
		(start 387.494018 -259.105654)
		(end 386.278374 -259.105654)
		(width 0.088646)
		(layer "In4.Cu")
		(net "M_F_CPU0_SA_DQ<30>")
	)
	(segment
		(start 424.836082 -281.466544)
		(end 424.309794 -281.992832)
		(width 0.18288)
		(layer "In4.Cu")
		(net "M_F_CPU0_SA_DQ<30>")
	)
	(segment
		(start 415.435288 -270.868394)
		(end 412.997142 -270.868394)
		(width 0.18288)
		(layer "In4.Cu")
		(net "M_F_CPU0_SA_DQ<30>")
	)
	(segment
		(start 385.251706 -259.127498)
		(end 385.239768 -259.134356)
		(width 0.088646)
		(layer "In4.Cu")
		(net "M_F_CPU0_SA_DQ<30>")
	)
	(segment
		(start 406.736296 -268.215872)
		(end 405.429212 -268.215872)
		(width 0.18288)
		(layer "In4.Cu")
		(net "M_F_CPU0_SA_DQ<30>")
	)
	(segment
		(start 419.763702 -277.588726)
		(end 420.052754 -277.588726)
		(width 0.18288)
		(layer "In4.Cu")
		(net "M_F_CPU0_SA_DQ<30>")
	)
	(segment
		(start 421.77208 -281.042618)
		(end 420.395654 -281.042618)
		(width 0.18288)
		(layer "In4.Cu")
		(net "M_F_CPU0_SA_DQ<30>")
	)
	(segment
		(start 408.574494 -269.270226)
		(end 407.79065 -269.270226)
		(width 0.18288)
		(layer "In4.Cu")
		(net "M_F_CPU0_SA_DQ<30>")
	)
	(segment
		(start 383.387092 -259.118862)
		(end 383.37236 -259.127498)
		(width 0.088646)
		(layer "In4.Cu")
		(net "M_F_CPU0_SA_DQ<30>")
	)
	(segment
		(start 383.37236 -259.127498)
		(end 383.368042 -259.130038)
		(width 0.088646)
		(layer "In4.Cu")
		(net "M_F_CPU0_SA_DQ<30>")
	)
	(segment
		(start 417.446206 -272.429986)
		(end 416.99688 -272.429986)
		(width 0.18288)
		(layer "In4.Cu")
		(net "M_F_CPU0_SA_DQ<30>")
	)
	(segment
		(start 424.309794 -281.992832)
		(end 422.722294 -281.992832)
		(width 0.18288)
		(layer "In4.Cu")
		(net "M_F_CPU0_SA_DQ<30>")
	)
	(segment
		(start 382.058164 -259.127498)
		(end 382.050798 -259.12318)
		(width 0.088646)
		(layer "In4.Cu")
		(net "M_F_CPU0_SA_DQ<30>")
	)
	(segment
		(start 420.235634 -278.465026)
		(end 420.052754 -278.282146)
		(width 0.18288)
		(layer "In4.Cu")
		(net "M_F_CPU0_SA_DQ<30>")
	)
	(segment
		(start 386.187188 -259.130038)
		(end 386.179568 -259.134356)
		(width 0.088646)
		(layer "In4.Cu")
		(net "M_F_CPU0_SA_DQ<30>")
	)
	(segment
		(start 380.474982 -259.172456)
		(end 379.895862 -259.616956)
		(width 0.088646)
		(layer "In4.Cu")
		(net "M_F_CPU0_SA_DQ<30>")
	)
	(segment
		(start 420.235634 -277.405846)
		(end 420.235634 -275.219414)
		(width 0.18288)
		(layer "In4.Cu")
		(net "M_F_CPU0_SA_DQ<30>")
	)
	(segment
		(start 394.331444 -260.880352)
		(end 393.911328 -260.796532)
		(width 0.18288)
		(layer "In4.Cu")
		(net "M_F_CPU0_SA_DQ<30>")
	)
	(arc
		(start 384.303524 -259.132324)
		(mid 384.120016 -259.177602)
		(end 383.937764 -259.127498)
		(width 0.088646)
		(layer "In4.Cu")
		(net "M_F_CPU0_SA_DQ<30>")
	)
	(arc
		(start 385.81711 -259.127498)
		(mid 385.542911 -259.051663)
		(end 385.266438 -259.118862)
		(width 0.088646)
		(layer "In4.Cu")
		(net "M_F_CPU0_SA_DQ<30>")
	)
	(arc
		(start 382.990598 -259.12318)
		(mid 382.711137 -259.051743)
		(end 382.432814 -259.127498)
		(width 0.088646)
		(layer "In4.Cu")
		(net "M_F_CPU0_SA_DQ<30>")
	)
	(arc
		(start 381.110998 -259.12318)
		(mid 380.831537 -259.051743)
		(end 380.553214 -259.127498)
		(width 0.088646)
		(layer "In4.Cu")
		(net "M_F_CPU0_SA_DQ<30>")
	)
	(arc
		(start 385.239768 -259.134356)
		(mid 385.057657 -259.177681)
		(end 384.87731 -259.127498)
		(width 0.088646)
		(layer "In4.Cu")
		(net "M_F_CPU0_SA_DQ<30>")
	)
	(arc
		(start 383.365248 -259.131562)
		(mid 383.181066 -259.177642)
		(end 382.997964 -259.127498)
		(width 0.088646)
		(layer "In4.Cu")
		(net "M_F_CPU0_SA_DQ<30>")
	)
	(arc
		(start 386.278374 -259.105654)
		(mid 386.231171 -259.111842)
		(end 386.187188 -259.130038)
		(width 0.088646)
		(layer "In4.Cu")
		(net "M_F_CPU0_SA_DQ<30>")
	)
	(arc
		(start 382.432814 -259.127498)
		(mid 382.24812 -259.177599)
		(end 382.062736 -259.130038)
		(width 0.088646)
		(layer "In4.Cu")
		(net "M_F_CPU0_SA_DQ<30>")
	)
	(arc
		(start 382.050798 -259.12318)
		(mid 381.771337 -259.051743)
		(end 381.493014 -259.127498)
		(width 0.088646)
		(layer "In4.Cu")
		(net "M_F_CPU0_SA_DQ<30>")
	)
	(arc
		(start 386.179568 -259.134356)
		(mid 385.997457 -259.177681)
		(end 385.81711 -259.127498)
		(width 0.088646)
		(layer "In4.Cu")
		(net "M_F_CPU0_SA_DQ<30>")
	)
	(arc
		(start 383.937764 -259.127498)
		(mid 383.663565 -259.051663)
		(end 383.387092 -259.118862)
		(width 0.088646)
		(layer "In4.Cu")
		(net "M_F_CPU0_SA_DQ<30>")
	)
	(arc
		(start 381.493014 -259.127498)
		(mid 381.30832 -259.177599)
		(end 381.122936 -259.130038)
		(width 0.088646)
		(layer "In4.Cu")
		(net "M_F_CPU0_SA_DQ<30>")
	)
	(arc
		(start 384.87731 -259.127498)
		(mid 384.603111 -259.051663)
		(end 384.326638 -259.118862)
		(width 0.088646)
		(layer "In4.Cu")
		(net "M_F_CPU0_SA_DQ<30>")
	)
	(segment
		(start 425.940982 -315.46673)
		(end 427.639226 -315.46673)
		(width 0.20066)
		(layer "F.Cu")
		(net "M_F_CPU0_SA_DQ<2>")
	)
	(segment
		(start 428.363126 -315.898784)
		(end 428.367952 -315.898784)
		(width 0.101854)
		(layer "F.Cu")
		(net "M_F_CPU0_SA_DQ<2>")
	)
	(segment
		(start 381.305562 -278.336248)
		(end 381.305816 -278.336502)
		(width 0.20066)
		(layer "F.Cu")
		(net "M_F_CPU0_SA_DQ<2>")
	)
	(segment
		(start 432.15052 -315.46673)
		(end 433.484782 -315.46673)
		(width 0.20066)
		(layer "F.Cu")
		(net "M_F_CPU0_SA_DQ<2>")
	)
	(segment
		(start 430.382934 -315.891672)
		(end 430.395126 -315.903864)
		(width 0.1016)
		(layer "F.Cu")
		(net "M_F_CPU0_SA_DQ<2>")
	)
	(segment
		(start 431.280316 -315.44895)
		(end 431.514504 -315.214762)
		(width 0.20066)
		(layer "F.Cu")
		(net "M_F_CPU0_SA_DQ<2>")
	)
	(segment
		(start 427.639226 -315.46673)
		(end 428.07128 -315.898784)
		(width 0.20066)
		(layer "F.Cu")
		(net "M_F_CPU0_SA_DQ<2>")
	)
	(segment
		(start 381.305562 -277.800562)
		(end 381.305562 -278.336248)
		(width 0.20066)
		(layer "F.Cu")
		(net "M_F_CPU0_SA_DQ<2>")
	)
	(segment
		(start 431.280316 -315.699902)
		(end 431.280316 -315.44895)
		(width 0.20066)
		(layer "F.Cu")
		(net "M_F_CPU0_SA_DQ<2>")
	)
	(segment
		(start 431.514504 -315.214762)
		(end 431.898552 -315.214762)
		(width 0.20066)
		(layer "F.Cu")
		(net "M_F_CPU0_SA_DQ<2>")
	)
	(segment
		(start 424.836082 -315.46673)
		(end 425.940982 -315.46673)
		(width 0.20066)
		(layer "F.Cu")
		(net "M_F_CPU0_SA_DQ<2>")
	)
	(segment
		(start 428.367952 -315.898784)
		(end 428.375064 -315.891672)
		(width 0.1016)
		(layer "F.Cu")
		(net "M_F_CPU0_SA_DQ<2>")
	)
	(segment
		(start 428.07128 -315.898784)
		(end 428.363126 -315.898784)
		(width 0.20066)
		(layer "F.Cu")
		(net "M_F_CPU0_SA_DQ<2>")
	)
	(segment
		(start 431.076354 -315.903864)
		(end 431.280316 -315.699902)
		(width 0.20066)
		(layer "F.Cu")
		(net "M_F_CPU0_SA_DQ<2>")
	)
	(segment
		(start 430.395126 -315.903864)
		(end 431.076354 -315.903864)
		(width 0.20066)
		(layer "F.Cu")
		(net "M_F_CPU0_SA_DQ<2>")
	)
	(segment
		(start 431.898552 -315.214762)
		(end 432.15052 -315.46673)
		(width 0.20066)
		(layer "F.Cu")
		(net "M_F_CPU0_SA_DQ<2>")
	)
	(segment
		(start 428.375064 -315.891672)
		(end 430.382934 -315.891672)
		(width 0.1016)
		(layer "F.Cu")
		(net "M_F_CPU0_SA_DQ<2>")
	)
	(segment
		(start 392.629136 -295.458896)
		(end 390.694672 -293.524432)
		(width 0.18288)
		(layer "In2.Cu")
		(net "M_F_CPU0_SA_DQ<2>")
	)
	(segment
		(start 412.603442 -315.87059)
		(end 408.511756 -315.87059)
		(width 0.18288)
		(layer "In2.Cu")
		(net "M_F_CPU0_SA_DQ<2>")
	)
	(segment
		(start 424.29557 -315.690504)
		(end 423.071036 -315.93409)
		(width 0.18288)
		(layer "In2.Cu")
		(net "M_F_CPU0_SA_DQ<2>")
	)
	(segment
		(start 420.102792 -315.89091)
		(end 420.061644 -315.873892)
		(width 0.18288)
		(layer "In2.Cu")
		(net "M_F_CPU0_SA_DQ<2>")
	)
	(segment
		(start 416.058604 -315.873892)
		(end 415.993072 -315.90107)
		(width 0.18288)
		(layer "In2.Cu")
		(net "M_F_CPU0_SA_DQ<2>")
	)
	(segment
		(start 412.677102 -315.90107)
		(end 412.603442 -315.87059)
		(width 0.18288)
		(layer "In2.Cu")
		(net "M_F_CPU0_SA_DQ<2>")
	)
	(segment
		(start 424.836082 -315.46673)
		(end 424.29557 -315.690504)
		(width 0.18288)
		(layer "In2.Cu")
		(net "M_F_CPU0_SA_DQ<2>")
	)
	(segment
		(start 380.992888 -278.336502)
		(end 381.305816 -278.336502)
		(width 0.088646)
		(layer "In2.Cu")
		(net "M_F_CPU0_SA_DQ<2>")
	)
	(segment
		(start 381.118618 -278.66086)
		(end 381.109728 -278.65578)
		(width 0.088646)
		(layer "In2.Cu")
		(net "M_F_CPU0_SA_DQ<2>")
	)
	(segment
		(start 381.59436 -279.478232)
		(end 381.588264 -279.474676)
		(width 0.088646)
		(layer "In2.Cu")
		(net "M_F_CPU0_SA_DQ<2>")
	)
	(segment
		(start 393.954254 -304.646838)
		(end 393.954254 -298.65828)
		(width 0.18288)
		(layer "In2.Cu")
		(net "M_F_CPU0_SA_DQ<2>")
	)
	(segment
		(start 408.438096 -315.90107)
		(end 405.448262 -315.90107)
		(width 0.18288)
		(layer "In2.Cu")
		(net "M_F_CPU0_SA_DQ<2>")
	)
	(segment
		(start 389.309102 -284.281626)
		(end 388.930896 -283.90342)
		(width 0.18288)
		(layer "In2.Cu")
		(net "M_F_CPU0_SA_DQ<2>")
	)
	(segment
		(start 421.639746 -315.93409)
		(end 421.152066 -315.89091)
		(width 0.18288)
		(layer "In2.Cu")
		(net "M_F_CPU0_SA_DQ<2>")
	)
	(segment
		(start 386.933948 -280.212546)
		(end 386.474716 -280.212546)
		(width 0.088646)
		(layer "In2.Cu")
		(net "M_F_CPU0_SA_DQ<2>")
	)
	(segment
		(start 380.935738 -278.393652)
		(end 380.992888 -278.336502)
		(width 0.088646)
		(layer "In2.Cu")
		(net "M_F_CPU0_SA_DQ<2>")
	)
	(segment
		(start 388.930896 -283.90342)
		(end 387.732778 -281.011376)
		(width 0.18288)
		(layer "In2.Cu")
		(net "M_F_CPU0_SA_DQ<2>")
	)
	(segment
		(start 415.993072 -315.90107)
		(end 412.677102 -315.90107)
		(width 0.18288)
		(layer "In2.Cu")
		(net "M_F_CPU0_SA_DQ<2>")
	)
	(segment
		(start 404.932896 -315.62548)
		(end 393.954254 -304.646838)
		(width 0.18288)
		(layer "In2.Cu")
		(net "M_F_CPU0_SA_DQ<2>")
	)
	(segment
		(start 387.088126 -280.366724)
		(end 386.933948 -280.212546)
		(width 0.088646)
		(layer "In2.Cu")
		(net "M_F_CPU0_SA_DQ<2>")
	)
	(segment
		(start 381.401066 -279.158954)
		(end 381.401066 -279.140412)
		(width 0.088646)
		(layer "In2.Cu")
		(net "M_F_CPU0_SA_DQ<2>")
	)
	(segment
		(start 390.694672 -293.524432)
		(end 389.309102 -290.179252)
		(width 0.18288)
		(layer "In2.Cu")
		(net "M_F_CPU0_SA_DQ<2>")
	)
	(segment
		(start 383.937764 -280.288492)
		(end 383.92735 -280.282396)
		(width 0.088646)
		(layer "In2.Cu")
		(net "M_F_CPU0_SA_DQ<2>")
	)
	(segment
		(start 387.732778 -281.011376)
		(end 387.088126 -280.366724)
		(width 0.18288)
		(layer "In2.Cu")
		(net "M_F_CPU0_SA_DQ<2>")
	)
	(segment
		(start 423.071036 -315.93409)
		(end 421.639746 -315.93409)
		(width 0.18288)
		(layer "In2.Cu")
		(net "M_F_CPU0_SA_DQ<2>")
	)
	(segment
		(start 389.309102 -290.179252)
		(end 389.309102 -284.281626)
		(width 0.18288)
		(layer "In2.Cu")
		(net "M_F_CPU0_SA_DQ<2>")
	)
	(segment
		(start 382.058418 -280.288492)
		(end 382.049528 -280.283412)
		(width 0.088646)
		(layer "In2.Cu")
		(net "M_F_CPU0_SA_DQ<2>")
	)
	(segment
		(start 405.448262 -315.90107)
		(end 404.932896 -315.62548)
		(width 0.18288)
		(layer "In2.Cu")
		(net "M_F_CPU0_SA_DQ<2>")
	)
	(segment
		(start 420.061644 -315.873892)
		(end 416.058604 -315.873892)
		(width 0.18288)
		(layer "In2.Cu")
		(net "M_F_CPU0_SA_DQ<2>")
	)
	(segment
		(start 393.954254 -298.65828)
		(end 392.629136 -295.458896)
		(width 0.18288)
		(layer "In2.Cu")
		(net "M_F_CPU0_SA_DQ<2>")
	)
	(segment
		(start 408.511756 -315.87059)
		(end 408.438096 -315.90107)
		(width 0.18288)
		(layer "In2.Cu")
		(net "M_F_CPU0_SA_DQ<2>")
	)
	(segment
		(start 421.152066 -315.89091)
		(end 420.102792 -315.89091)
		(width 0.18288)
		(layer "In2.Cu")
		(net "M_F_CPU0_SA_DQ<2>")
	)
	(arc
		(start 385.817364 -280.288492)
		(mid 385.534662 -280.21275)
		(end 385.25196 -280.288492)
		(width 0.088646)
		(layer "In2.Cu")
		(net "M_F_CPU0_SA_DQ<2>")
	)
	(arc
		(start 386.474716 -280.212546)
		(mid 386.328246 -280.231906)
		(end 386.19176 -280.288492)
		(width 0.088646)
		(layer "In2.Cu")
		(net "M_F_CPU0_SA_DQ<2>")
	)
	(arc
		(start 383.372106 -280.288492)
		(mid 383.184908 -280.338635)
		(end 382.99771 -280.288492)
		(width 0.088646)
		(layer "In2.Cu")
		(net "M_F_CPU0_SA_DQ<2>")
	)
	(arc
		(start 385.25196 -280.288492)
		(mid 385.064762 -280.338635)
		(end 384.877564 -280.288492)
		(width 0.088646)
		(layer "In2.Cu")
		(net "M_F_CPU0_SA_DQ<2>")
	)
	(arc
		(start 384.877564 -280.288492)
		(mid 384.594862 -280.21275)
		(end 384.31216 -280.288492)
		(width 0.088646)
		(layer "In2.Cu")
		(net "M_F_CPU0_SA_DQ<2>")
	)
	(arc
		(start 384.31216 -280.288492)
		(mid 384.124962 -280.338635)
		(end 383.937764 -280.288492)
		(width 0.088646)
		(layer "In2.Cu")
		(net "M_F_CPU0_SA_DQ<2>")
	)
	(arc
		(start 382.99771 -280.288492)
		(mid 382.715262 -280.212877)
		(end 382.432814 -280.288492)
		(width 0.088646)
		(layer "In2.Cu")
		(net "M_F_CPU0_SA_DQ<2>")
	)
	(arc
		(start 386.19176 -280.288492)
		(mid 386.004562 -280.338635)
		(end 385.817364 -280.288492)
		(width 0.088646)
		(layer "In2.Cu")
		(net "M_F_CPU0_SA_DQ<2>")
	)
	(arc
		(start 381.588264 -279.474676)
		(mid 381.453331 -279.341322)
		(end 381.401066 -279.158954)
		(width 0.088646)
		(layer "In2.Cu")
		(net "M_F_CPU0_SA_DQ<2>")
	)
	(arc
		(start 382.432814 -280.288492)
		(mid 382.245616 -280.338635)
		(end 382.058418 -280.288492)
		(width 0.088646)
		(layer "In2.Cu")
		(net "M_F_CPU0_SA_DQ<2>")
	)
	(arc
		(start 383.92735 -280.282396)
		(mid 383.648918 -280.212582)
		(end 383.372106 -280.288492)
		(width 0.088646)
		(layer "In2.Cu")
		(net "M_F_CPU0_SA_DQ<2>")
	)
	(arc
		(start 381.401066 -279.140412)
		(mid 381.322955 -278.863463)
		(end 381.118618 -278.66086)
		(width 0.088646)
		(layer "In2.Cu")
		(net "M_F_CPU0_SA_DQ<2>")
	)
	(arc
		(start 381.109728 -278.65578)
		(mid 380.993919 -278.543851)
		(end 380.935738 -278.393652)
		(width 0.088646)
		(layer "In2.Cu")
		(net "M_F_CPU0_SA_DQ<2>")
	)
	(arc
		(start 382.049528 -280.283412)
		(mid 381.918614 -280.147052)
		(end 381.870966 -279.964134)
		(width 0.088646)
		(layer "In2.Cu")
		(net "M_F_CPU0_SA_DQ<2>")
	)
	(arc
		(start 381.870966 -279.964134)
		(mid 381.796975 -279.684568)
		(end 381.59436 -279.478232)
		(width 0.088646)
		(layer "In2.Cu")
		(net "M_F_CPU0_SA_DQ<2>")
	)
	(segment
		(start 426.945044 -280.191718)
		(end 424.756326 -280.191718)
		(width 0.1016)
		(layer "F.Cu")
		(net "M_F_CPU0_SA_DQ<29>")
	)
	(segment
		(start 427.36135 -280.185368)
		(end 426.951394 -280.185368)
		(width 0.20066)
		(layer "F.Cu")
		(net "M_F_CPU0_SA_DQ<29>")
	)
	(segment
		(start 423.610278 -280.865326)
		(end 423.361612 -280.61666)
		(width 0.20066)
		(layer "F.Cu")
		(net "M_F_CPU0_SA_DQ<29>")
	)
	(segment
		(start 429.38446 -280.616914)
		(end 427.792896 -280.616914)
		(width 0.20066)
		(layer "F.Cu")
		(net "M_F_CPU0_SA_DQ<29>")
	)
	(segment
		(start 424.391582 -280.191718)
		(end 424.273472 -280.309828)
		(width 0.20066)
		(layer "F.Cu")
		(net "M_F_CPU0_SA_DQ<29>")
	)
	(segment
		(start 378.486416 -258.267454)
		(end 378.486416 -258.80314)
		(width 0.20066)
		(layer "F.Cu")
		(net "M_F_CPU0_SA_DQ<29>")
	)
	(segment
		(start 424.756326 -280.191718)
		(end 424.73626 -280.191718)
		(width 0.101854)
		(layer "F.Cu")
		(net "M_F_CPU0_SA_DQ<29>")
	)
	(segment
		(start 421.840914 -280.61666)
		(end 420.736014 -280.61666)
		(width 0.20066)
		(layer "F.Cu")
		(net "M_F_CPU0_SA_DQ<29>")
	)
	(segment
		(start 424.273472 -280.677366)
		(end 424.085512 -280.865326)
		(width 0.20066)
		(layer "F.Cu")
		(net "M_F_CPU0_SA_DQ<29>")
	)
	(segment
		(start 378.486162 -258.2672)
		(end 378.486416 -258.267454)
		(width 0.20066)
		(layer "F.Cu")
		(net "M_F_CPU0_SA_DQ<29>")
	)
	(segment
		(start 424.085512 -280.865326)
		(end 423.610278 -280.865326)
		(width 0.20066)
		(layer "F.Cu")
		(net "M_F_CPU0_SA_DQ<29>")
	)
	(segment
		(start 423.361612 -280.61666)
		(end 421.840914 -280.61666)
		(width 0.20066)
		(layer "F.Cu")
		(net "M_F_CPU0_SA_DQ<29>")
	)
	(segment
		(start 424.73626 -280.191718)
		(end 424.391582 -280.191718)
		(width 0.20066)
		(layer "F.Cu")
		(net "M_F_CPU0_SA_DQ<29>")
	)
	(segment
		(start 427.792896 -280.616914)
		(end 427.36135 -280.185368)
		(width 0.20066)
		(layer "F.Cu")
		(net "M_F_CPU0_SA_DQ<29>")
	)
	(segment
		(start 429.384714 -280.61666)
		(end 429.38446 -280.616914)
		(width 0.20066)
		(layer "F.Cu")
		(net "M_F_CPU0_SA_DQ<29>")
	)
	(segment
		(start 424.273472 -280.309828)
		(end 424.273472 -280.677366)
		(width 0.20066)
		(layer "F.Cu")
		(net "M_F_CPU0_SA_DQ<29>")
	)
	(segment
		(start 426.951394 -280.185368)
		(end 426.945044 -280.191718)
		(width 0.1016)
		(layer "F.Cu")
		(net "M_F_CPU0_SA_DQ<29>")
	)
	(segment
		(start 380.567946 -258.487418)
		(end 380.553214 -258.478782)
		(width 0.088646)
		(layer "In4.Cu")
		(net "M_F_CPU0_SA_DQ<29>")
	)
	(segment
		(start 421.533574 -274.168616)
		(end 421.533574 -273.820636)
		(width 0.18288)
		(layer "In4.Cu")
		(net "M_F_CPU0_SA_DQ<29>")
	)
	(segment
		(start 421.912288 -274.836636)
		(end 421.912288 -274.488656)
		(width 0.18288)
		(layer "In4.Cu")
		(net "M_F_CPU0_SA_DQ<29>")
	)
	(segment
		(start 421.752268 -274.328636)
		(end 421.693594 -274.328636)
		(width 0.18288)
		(layer "In4.Cu")
		(net "M_F_CPU0_SA_DQ<29>")
	)
	(segment
		(start 405.5237 -267.606272)
		(end 398.29994 -260.382512)
		(width 0.18288)
		(layer "In4.Cu")
		(net "M_F_CPU0_SA_DQ<29>")
	)
	(segment
		(start 380.023878 -258.597654)
		(end 379.926088 -258.695444)
		(width 0.088646)
		(layer "In4.Cu")
		(net "M_F_CPU0_SA_DQ<29>")
	)
	(segment
		(start 408.23769 -268.127226)
		(end 407.382218 -268.127226)
		(width 0.18288)
		(layer "In4.Cu")
		(net "M_F_CPU0_SA_DQ<29>")
	)
	(segment
		(start 420.1287 -271.6911)
		(end 420.047674 -271.772126)
		(width 0.18288)
		(layer "In4.Cu")
		(net "M_F_CPU0_SA_DQ<29>")
	)
	(segment
		(start 416.322256 -270.654018)
		(end 415.595054 -269.926816)
		(width 0.18288)
		(layer "In4.Cu")
		(net "M_F_CPU0_SA_DQ<29>")
	)
	(segment
		(start 394.39088 -260.382512)
		(end 394.123418 -260.329172)
		(width 0.18288)
		(layer "In4.Cu")
		(net "M_F_CPU0_SA_DQ<29>")
	)
	(segment
		(start 384.877564 -258.478782)
		(end 384.862832 -258.487418)
		(width 0.088646)
		(layer "In4.Cu")
		(net "M_F_CPU0_SA_DQ<29>")
	)
	(segment
		(start 421.912288 -274.488656)
		(end 421.752268 -274.328636)
		(width 0.18288)
		(layer "In4.Cu")
		(net "M_F_CPU0_SA_DQ<29>")
	)
	(segment
		(start 420.047674 -271.772126)
		(end 418.470588 -271.772126)
		(width 0.18288)
		(layer "In4.Cu")
		(net "M_F_CPU0_SA_DQ<29>")
	)
	(segment
		(start 421.693594 -274.328636)
		(end 421.533574 -274.168616)
		(width 0.18288)
		(layer "In4.Cu")
		(net "M_F_CPU0_SA_DQ<29>")
	)
	(segment
		(start 421.693594 -272.992596)
		(end 421.533574 -272.832576)
		(width 0.18288)
		(layer "In4.Cu")
		(net "M_F_CPU0_SA_DQ<29>")
	)
	(segment
		(start 386.497068 -258.765802)
		(end 386.269484 -258.538218)
		(width 0.088646)
		(layer "In4.Cu")
		(net "M_F_CPU0_SA_DQ<29>")
	)
	(segment
		(start 417.35248 -270.654018)
		(end 416.322256 -270.654018)
		(width 0.18288)
		(layer "In4.Cu")
		(net "M_F_CPU0_SA_DQ<29>")
	)
	(segment
		(start 421.752268 -274.996656)
		(end 421.912288 -274.836636)
		(width 0.18288)
		(layer "In4.Cu")
		(net "M_F_CPU0_SA_DQ<29>")
	)
	(segment
		(start 378.792994 -259.021326)
		(end 378.486416 -258.80314)
		(width 0.088646)
		(layer "In4.Cu")
		(net "M_F_CPU0_SA_DQ<29>")
	)
	(segment
		(start 421.912288 -273.152616)
		(end 421.752268 -272.992596)
		(width 0.18288)
		(layer "In4.Cu")
		(net "M_F_CPU0_SA_DQ<29>")
	)
	(segment
		(start 421.693594 -273.660616)
		(end 421.752268 -273.660616)
		(width 0.18288)
		(layer "In4.Cu")
		(net "M_F_CPU0_SA_DQ<29>")
	)
	(segment
		(start 421.912288 -273.500596)
		(end 421.912288 -273.152616)
		(width 0.18288)
		(layer "In4.Cu")
		(net "M_F_CPU0_SA_DQ<29>")
	)
	(segment
		(start 420.736014 -280.61666)
		(end 421.533574 -279.8191)
		(width 0.18288)
		(layer "In4.Cu")
		(net "M_F_CPU0_SA_DQ<29>")
	)
	(segment
		(start 411.752542 -269.140178)
		(end 409.250642 -269.140178)
		(width 0.18288)
		(layer "In4.Cu")
		(net "M_F_CPU0_SA_DQ<29>")
	)
	(segment
		(start 382.443228 -258.484878)
		(end 382.432814 -258.478782)
		(width 0.088646)
		(layer "In4.Cu")
		(net "M_F_CPU0_SA_DQ<29>")
	)
	(segment
		(start 411.851094 -269.041626)
		(end 411.752542 -269.140178)
		(width 0.18288)
		(layer "In4.Cu")
		(net "M_F_CPU0_SA_DQ<29>")
	)
	(segment
		(start 413.345884 -269.926816)
		(end 412.460694 -269.041626)
		(width 0.18288)
		(layer "In4.Cu")
		(net "M_F_CPU0_SA_DQ<29>")
	)
	(segment
		(start 421.752268 -273.660616)
		(end 421.912288 -273.500596)
		(width 0.18288)
		(layer "In4.Cu")
		(net "M_F_CPU0_SA_DQ<29>")
	)
	(segment
		(start 421.752268 -272.992596)
		(end 421.693594 -272.992596)
		(width 0.18288)
		(layer "In4.Cu")
		(net "M_F_CPU0_SA_DQ<29>")
	)
	(segment
		(start 407.382218 -268.127226)
		(end 406.861264 -267.606272)
		(width 0.18288)
		(layer "In4.Cu")
		(net "M_F_CPU0_SA_DQ<29>")
	)
	(segment
		(start 392.834368 -260.072886)
		(end 389.678926 -258.765802)
		(width 0.18288)
		(layer "In4.Cu")
		(net "M_F_CPU0_SA_DQ<29>")
	)
	(segment
		(start 406.861264 -267.606272)
		(end 405.5237 -267.606272)
		(width 0.18288)
		(layer "In4.Cu")
		(net "M_F_CPU0_SA_DQ<29>")
	)
	(segment
		(start 421.533574 -272.183606)
		(end 421.041068 -271.6911)
		(width 0.18288)
		(layer "In4.Cu")
		(net "M_F_CPU0_SA_DQ<29>")
	)
	(segment
		(start 398.29994 -260.382512)
		(end 394.39088 -260.382512)
		(width 0.18288)
		(layer "In4.Cu")
		(net "M_F_CPU0_SA_DQ<29>")
	)
	(segment
		(start 385.817364 -258.478782)
		(end 385.802632 -258.487418)
		(width 0.088646)
		(layer "In4.Cu")
		(net "M_F_CPU0_SA_DQ<29>")
	)
	(segment
		(start 421.533574 -275.156676)
		(end 421.693594 -274.996656)
		(width 0.18288)
		(layer "In4.Cu")
		(net "M_F_CPU0_SA_DQ<29>")
	)
	(segment
		(start 418.470588 -271.772126)
		(end 417.35248 -270.654018)
		(width 0.18288)
		(layer "In4.Cu")
		(net "M_F_CPU0_SA_DQ<29>")
	)
	(segment
		(start 412.460694 -269.041626)
		(end 411.851094 -269.041626)
		(width 0.18288)
		(layer "In4.Cu")
		(net "M_F_CPU0_SA_DQ<29>")
	)
	(segment
		(start 389.678926 -258.765802)
		(end 387.509004 -258.765802)
		(width 0.18288)
		(layer "In4.Cu")
		(net "M_F_CPU0_SA_DQ<29>")
	)
	(segment
		(start 421.041068 -271.6911)
		(end 420.1287 -271.6911)
		(width 0.18288)
		(layer "In4.Cu")
		(net "M_F_CPU0_SA_DQ<29>")
	)
	(segment
		(start 421.533574 -279.8191)
		(end 421.533574 -275.156676)
		(width 0.18288)
		(layer "In4.Cu")
		(net "M_F_CPU0_SA_DQ<29>")
	)
	(segment
		(start 421.533574 -273.820636)
		(end 421.693594 -273.660616)
		(width 0.18288)
		(layer "In4.Cu")
		(net "M_F_CPU0_SA_DQ<29>")
	)
	(segment
		(start 409.250642 -269.140178)
		(end 408.23769 -268.127226)
		(width 0.18288)
		(layer "In4.Cu")
		(net "M_F_CPU0_SA_DQ<29>")
	)
	(segment
		(start 387.509004 -258.765802)
		(end 386.497068 -258.765802)
		(width 0.088646)
		(layer "In4.Cu")
		(net "M_F_CPU0_SA_DQ<29>")
	)
	(segment
		(start 415.595054 -269.926816)
		(end 413.345884 -269.926816)
		(width 0.18288)
		(layer "In4.Cu")
		(net "M_F_CPU0_SA_DQ<29>")
	)
	(segment
		(start 421.533574 -272.832576)
		(end 421.533574 -272.183606)
		(width 0.18288)
		(layer "In4.Cu")
		(net "M_F_CPU0_SA_DQ<29>")
	)
	(segment
		(start 394.123418 -260.329172)
		(end 392.834368 -260.072886)
		(width 0.18288)
		(layer "In4.Cu")
		(net "M_F_CPU0_SA_DQ<29>")
	)
	(segment
		(start 421.693594 -274.996656)
		(end 421.752268 -274.996656)
		(width 0.18288)
		(layer "In4.Cu")
		(net "M_F_CPU0_SA_DQ<29>")
	)
	(segment
		(start 379.7427 -259.138674)
		(end 379.694694 -259.186426)
		(width 0.088646)
		(layer "In4.Cu")
		(net "M_F_CPU0_SA_DQ<29>")
	)
	(arc
		(start 382.058418 -258.478782)
		(mid 381.775716 -258.554524)
		(end 381.493014 -258.478782)
		(width 0.088646)
		(layer "In4.Cu")
		(net "M_F_CPU0_SA_DQ<29>")
	)
	(arc
		(start 380.553214 -258.478782)
		(mid 380.366016 -258.428639)
		(end 380.178818 -258.478782)
		(width 0.088646)
		(layer "In4.Cu")
		(net "M_F_CPU0_SA_DQ<29>")
	)
	(arc
		(start 384.862832 -258.487418)
		(mid 384.586391 -258.554584)
		(end 384.31216 -258.478782)
		(width 0.088646)
		(layer "In4.Cu")
		(net "M_F_CPU0_SA_DQ<29>")
	)
	(arc
		(start 383.937764 -258.478782)
		(mid 383.655062 -258.554524)
		(end 383.37236 -258.478782)
		(width 0.088646)
		(layer "In4.Cu")
		(net "M_F_CPU0_SA_DQ<29>")
	)
	(arc
		(start 384.31216 -258.478782)
		(mid 384.124962 -258.428639)
		(end 383.937764 -258.478782)
		(width 0.088646)
		(layer "In4.Cu")
		(net "M_F_CPU0_SA_DQ<29>")
	)
	(arc
		(start 381.493014 -258.478782)
		(mid 381.305816 -258.428639)
		(end 381.118618 -258.478782)
		(width 0.088646)
		(layer "In4.Cu")
		(net "M_F_CPU0_SA_DQ<29>")
	)
	(arc
		(start 385.25196 -258.478782)
		(mid 385.064762 -258.428639)
		(end 384.877564 -258.478782)
		(width 0.088646)
		(layer "In4.Cu")
		(net "M_F_CPU0_SA_DQ<29>")
	)
	(arc
		(start 386.269484 -258.538218)
		(mid 386.232574 -258.505947)
		(end 386.19176 -258.478782)
		(width 0.088646)
		(layer "In4.Cu")
		(net "M_F_CPU0_SA_DQ<29>")
	)
	(arc
		(start 380.178818 -258.478782)
		(mid 380.097448 -258.533135)
		(end 380.023878 -258.597654)
		(width 0.088646)
		(layer "In4.Cu")
		(net "M_F_CPU0_SA_DQ<29>")
	)
	(arc
		(start 382.997964 -258.478782)
		(mid 382.721405 -258.554491)
		(end 382.443228 -258.484878)
		(width 0.088646)
		(layer "In4.Cu")
		(net "M_F_CPU0_SA_DQ<29>")
	)
	(arc
		(start 379.877828 -258.81203)
		(mid 379.842761 -258.988796)
		(end 379.7427 -259.138674)
		(width 0.088646)
		(layer "In4.Cu")
		(net "M_F_CPU0_SA_DQ<29>")
	)
	(arc
		(start 381.118618 -258.478782)
		(mid 380.844389 -258.554707)
		(end 380.567946 -258.487418)
		(width 0.088646)
		(layer "In4.Cu")
		(net "M_F_CPU0_SA_DQ<29>")
	)
	(arc
		(start 379.926088 -258.695444)
		(mid 379.890347 -258.748934)
		(end 379.877828 -258.81203)
		(width 0.088646)
		(layer "In4.Cu")
		(net "M_F_CPU0_SA_DQ<29>")
	)
	(arc
		(start 379.694694 -259.186426)
		(mid 379.226497 -259.198638)
		(end 378.792994 -259.021326)
		(width 0.088646)
		(layer "In4.Cu")
		(net "M_F_CPU0_SA_DQ<29>")
	)
	(arc
		(start 382.432814 -258.478782)
		(mid 382.245616 -258.428639)
		(end 382.058418 -258.478782)
		(width 0.088646)
		(layer "In4.Cu")
		(net "M_F_CPU0_SA_DQ<29>")
	)
	(arc
		(start 383.37236 -258.478782)
		(mid 383.185162 -258.428639)
		(end 382.997964 -258.478782)
		(width 0.088646)
		(layer "In4.Cu")
		(net "M_F_CPU0_SA_DQ<29>")
	)
	(arc
		(start 386.19176 -258.478782)
		(mid 386.004562 -258.428639)
		(end 385.817364 -258.478782)
		(width 0.088646)
		(layer "In4.Cu")
		(net "M_F_CPU0_SA_DQ<29>")
	)
	(arc
		(start 385.802632 -258.487418)
		(mid 385.526191 -258.554584)
		(end 385.25196 -258.478782)
		(width 0.088646)
		(layer "In4.Cu")
		(net "M_F_CPU0_SA_DQ<29>")
	)
	(segment
		(start 421.840914 -282.316682)
		(end 420.736014 -282.316682)
		(width 0.20066)
		(layer "F.Cu")
		(net "M_F_CPU0_SA_DQ<28>")
	)
	(segment
		(start 426.945044 -281.89174)
		(end 424.78325 -281.89174)
		(width 0.1016)
		(layer "F.Cu")
		(net "M_F_CPU0_SA_DQ<28>")
	)
	(segment
		(start 424.273472 -282.00985)
		(end 424.273472 -282.377388)
		(width 0.20066)
		(layer "F.Cu")
		(net "M_F_CPU0_SA_DQ<28>")
	)
	(segment
		(start 424.73626 -281.89174)
		(end 424.391582 -281.89174)
		(width 0.20066)
		(layer "F.Cu")
		(net "M_F_CPU0_SA_DQ<28>")
	)
	(segment
		(start 427.792896 -282.316936)
		(end 427.36135 -281.88539)
		(width 0.20066)
		(layer "F.Cu")
		(net "M_F_CPU0_SA_DQ<28>")
	)
	(segment
		(start 423.361612 -282.316682)
		(end 421.840914 -282.316682)
		(width 0.20066)
		(layer "F.Cu")
		(net "M_F_CPU0_SA_DQ<28>")
	)
	(segment
		(start 427.36135 -281.88539)
		(end 426.951394 -281.88539)
		(width 0.20066)
		(layer "F.Cu")
		(net "M_F_CPU0_SA_DQ<28>")
	)
	(segment
		(start 378.016516 -259.093462)
		(end 378.016262 -259.616956)
		(width 0.20066)
		(layer "F.Cu")
		(net "M_F_CPU0_SA_DQ<28>")
	)
	(segment
		(start 426.951394 -281.88539)
		(end 426.945044 -281.89174)
		(width 0.1016)
		(layer "F.Cu")
		(net "M_F_CPU0_SA_DQ<28>")
	)
	(segment
		(start 424.391582 -281.89174)
		(end 424.273472 -282.00985)
		(width 0.20066)
		(layer "F.Cu")
		(net "M_F_CPU0_SA_DQ<28>")
	)
	(segment
		(start 424.273472 -282.377388)
		(end 424.085512 -282.565348)
		(width 0.20066)
		(layer "F.Cu")
		(net "M_F_CPU0_SA_DQ<28>")
	)
	(segment
		(start 424.78325 -281.89174)
		(end 424.73626 -281.89174)
		(width 0.101854)
		(layer "F.Cu")
		(net "M_F_CPU0_SA_DQ<28>")
	)
	(segment
		(start 429.38446 -282.316936)
		(end 427.792896 -282.316936)
		(width 0.20066)
		(layer "F.Cu")
		(net "M_F_CPU0_SA_DQ<28>")
	)
	(segment
		(start 429.384714 -282.316682)
		(end 429.38446 -282.316936)
		(width 0.20066)
		(layer "F.Cu")
		(net "M_F_CPU0_SA_DQ<28>")
	)
	(segment
		(start 378.016516 -259.081016)
		(end 378.016516 -259.093462)
		(width 0.20066)
		(layer "F.Cu")
		(net "M_F_CPU0_SA_DQ<28>")
	)
	(segment
		(start 423.610278 -282.565348)
		(end 423.361612 -282.316682)
		(width 0.20066)
		(layer "F.Cu")
		(net "M_F_CPU0_SA_DQ<28>")
	)
	(segment
		(start 424.085512 -282.565348)
		(end 423.610278 -282.565348)
		(width 0.20066)
		(layer "F.Cu")
		(net "M_F_CPU0_SA_DQ<28>")
	)
	(segment
		(start 417.551362 -273.509994)
		(end 417.348416 -273.71294)
		(width 0.18288)
		(layer "In4.Cu")
		(net "M_F_CPU0_SA_DQ<28>")
	)
	(segment
		(start 385.359148 -259.28574)
		(end 385.34721 -259.292598)
		(width 0.088646)
		(layer "In4.Cu")
		(net "M_F_CPU0_SA_DQ<28>")
	)
	(segment
		(start 381.962914 -259.292344)
		(end 381.958342 -259.289804)
		(width 0.088646)
		(layer "In4.Cu")
		(net "M_F_CPU0_SA_DQ<28>")
	)
	(segment
		(start 417.809934 -273.509994)
		(end 417.551362 -273.509994)
		(width 0.18288)
		(layer "In4.Cu")
		(net "M_F_CPU0_SA_DQ<28>")
	)
	(segment
		(start 418.041836 -273.741896)
		(end 417.809934 -273.509994)
		(width 0.18288)
		(layer "In4.Cu")
		(net "M_F_CPU0_SA_DQ<28>")
	)
	(segment
		(start 417.348416 -273.71294)
		(end 417.089844 -273.71294)
		(width 0.18288)
		(layer "In4.Cu")
		(net "M_F_CPU0_SA_DQ<28>")
	)
	(segment
		(start 418.978842 -280.800302)
		(end 418.978842 -280.27503)
		(width 0.18288)
		(layer "In4.Cu")
		(net "M_F_CPU0_SA_DQ<28>")
	)
	(segment
		(start 411.373066 -270.794226)
		(end 411.135068 -271.032224)
		(width 0.18288)
		(layer "In4.Cu")
		(net "M_F_CPU0_SA_DQ<28>")
	)
	(segment
		(start 412.901638 -271.56283)
		(end 412.374334 -271.035526)
		(width 0.18288)
		(layer "In4.Cu")
		(net "M_F_CPU0_SA_DQ<28>")
	)
	(segment
		(start 387.232906 -259.451856)
		(end 387.087364 -259.306314)
		(width 0.088646)
		(layer "In4.Cu")
		(net "M_F_CPU0_SA_DQ<28>")
	)
	(segment
		(start 407.437082 -269.930626)
		(end 406.647142 -269.140686)
		(width 0.18288)
		(layer "In4.Cu")
		(net "M_F_CPU0_SA_DQ<28>")
	)
	(segment
		(start 397.71066 -261.378192)
		(end 394.000228 -261.378192)
		(width 0.18288)
		(layer "In4.Cu")
		(net "M_F_CPU0_SA_DQ<28>")
	)
	(segment
		(start 419.549326 -279.39873)
		(end 419.161722 -279.39873)
		(width 0.18288)
		(layer "In4.Cu")
		(net "M_F_CPU0_SA_DQ<28>")
	)
	(segment
		(start 386.865622 -259.306314)
		(end 386.789422 -259.300218)
		(width 0.088646)
		(layer "In4.Cu")
		(net "M_F_CPU0_SA_DQ<28>")
	)
	(segment
		(start 418.819838 -275.184362)
		(end 419.022784 -274.981416)
		(width 0.18288)
		(layer "In4.Cu")
		(net "M_F_CPU0_SA_DQ<28>")
	)
	(segment
		(start 418.070792 -274.693888)
		(end 417.83889 -274.461986)
		(width 0.18288)
		(layer "In4.Cu")
		(net "M_F_CPU0_SA_DQ<28>")
	)
	(segment
		(start 412.127446 -270.794226)
		(end 411.373066 -270.794226)
		(width 0.18288)
		(layer "In4.Cu")
		(net "M_F_CPU0_SA_DQ<28>")
	)
	(segment
		(start 411.135068 -271.032224)
		(end 410.623004 -271.032224)
		(width 0.18288)
		(layer "In4.Cu")
		(net "M_F_CPU0_SA_DQ<28>")
	)
	(segment
		(start 383.46761 -259.292598)
		(end 383.467356 -259.292598)
		(width 0.088646)
		(layer "In4.Cu")
		(net "M_F_CPU0_SA_DQ<28>")
	)
	(segment
		(start 419.732206 -279.58161)
		(end 419.549326 -279.39873)
		(width 0.18288)
		(layer "In4.Cu")
		(net "M_F_CPU0_SA_DQ<28>")
	)
	(segment
		(start 420.30523 -281.885898)
		(end 420.064438 -281.885898)
		(width 0.18288)
		(layer "In4.Cu")
		(net "M_F_CPU0_SA_DQ<28>")
	)
	(segment
		(start 412.374334 -271.035526)
		(end 412.368746 -271.035526)
		(width 0.18288)
		(layer "In4.Cu")
		(net "M_F_CPU0_SA_DQ<28>")
	)
	(segment
		(start 408.472894 -269.930626)
		(end 407.437082 -269.930626)
		(width 0.18288)
		(layer "In4.Cu")
		(net "M_F_CPU0_SA_DQ<28>")
	)
	(segment
		(start 387.494018 -259.451856)
		(end 387.232906 -259.451856)
		(width 0.088646)
		(layer "In4.Cu")
		(net "M_F_CPU0_SA_DQ<28>")
	)
	(segment
		(start 414.215326 -272.380456)
		(end 413.3977 -271.56283)
		(width 0.18288)
		(layer "In4.Cu")
		(net "M_F_CPU0_SA_DQ<28>")
	)
	(segment
		(start 380.088394 -259.93852)
		(end 380.083314 -259.941314)
		(width 0.088646)
		(layer "In4.Cu")
		(net "M_F_CPU0_SA_DQ<28>")
	)
	(segment
		(start 419.732206 -279.90927)
		(end 419.732206 -279.58161)
		(width 0.18288)
		(layer "In4.Cu")
		(net "M_F_CPU0_SA_DQ<28>")
	)
	(segment
		(start 418.329364 -274.693888)
		(end 418.070792 -274.693888)
		(width 0.18288)
		(layer "In4.Cu")
		(net "M_F_CPU0_SA_DQ<28>")
	)
	(segment
		(start 416.770058 -273.393154)
		(end 416.011614 -273.393154)
		(width 0.18288)
		(layer "In4.Cu")
		(net "M_F_CPU0_SA_DQ<28>")
	)
	(segment
		(start 410.385006 -270.794226)
		(end 409.336494 -270.794226)
		(width 0.18288)
		(layer "In4.Cu")
		(net "M_F_CPU0_SA_DQ<28>")
	)
	(segment
		(start 420.064438 -281.885898)
		(end 418.978842 -280.800302)
		(width 0.18288)
		(layer "In4.Cu")
		(net "M_F_CPU0_SA_DQ<28>")
	)
	(segment
		(start 387.087364 -259.306314)
		(end 386.865622 -259.306314)
		(width 0.088646)
		(layer "In4.Cu")
		(net "M_F_CPU0_SA_DQ<28>")
	)
	(segment
		(start 418.978842 -275.601938)
		(end 418.819838 -275.442934)
		(width 0.18288)
		(layer "In4.Cu")
		(net "M_F_CPU0_SA_DQ<28>")
	)
	(segment
		(start 418.790882 -274.490942)
		(end 418.53231 -274.490942)
		(width 0.18288)
		(layer "In4.Cu")
		(net "M_F_CPU0_SA_DQ<28>")
	)
	(segment
		(start 381.97028 -259.296662)
		(end 381.962914 -259.292344)
		(width 0.088646)
		(layer "In4.Cu")
		(net "M_F_CPU0_SA_DQ<28>")
	)
	(segment
		(start 380.083314 -259.941314)
		(end 380.077472 -259.944616)
		(width 0.088646)
		(layer "In4.Cu")
		(net "M_F_CPU0_SA_DQ<28>")
	)
	(segment
		(start 418.978842 -279.21585)
		(end 418.978842 -275.601938)
		(width 0.18288)
		(layer "In4.Cu")
		(net "M_F_CPU0_SA_DQ<28>")
	)
	(segment
		(start 383.467356 -259.292598)
		(end 383.46126 -259.296154)
		(width 0.088646)
		(layer "In4.Cu")
		(net "M_F_CPU0_SA_DQ<28>")
	)
	(segment
		(start 418.041836 -274.000468)
		(end 418.041836 -273.741896)
		(width 0.18288)
		(layer "In4.Cu")
		(net "M_F_CPU0_SA_DQ<28>")
	)
	(segment
		(start 416.011614 -273.393154)
		(end 414.998916 -272.380456)
		(width 0.18288)
		(layer "In4.Cu")
		(net "M_F_CPU0_SA_DQ<28>")
	)
	(segment
		(start 393.071096 -260.928612)
		(end 389.50646 -259.451856)
		(width 0.18288)
		(layer "In4.Cu")
		(net "M_F_CPU0_SA_DQ<28>")
	)
	(segment
		(start 386.78231 -259.299964)
		(end 386.28193 -259.299964)
		(width 0.088646)
		(layer "In4.Cu")
		(net "M_F_CPU0_SA_DQ<28>")
	)
	(segment
		(start 417.83889 -274.461986)
		(end 417.83889 -274.203414)
		(width 0.18288)
		(layer "In4.Cu")
		(net "M_F_CPU0_SA_DQ<28>")
	)
	(segment
		(start 393.325604 -261.098792)
		(end 393.071096 -260.928612)
		(width 0.18288)
		(layer "In4.Cu")
		(net "M_F_CPU0_SA_DQ<28>")
	)
	(segment
		(start 414.998916 -272.380456)
		(end 414.215326 -272.380456)
		(width 0.18288)
		(layer "In4.Cu")
		(net "M_F_CPU0_SA_DQ<28>")
	)
	(segment
		(start 419.161722 -279.39873)
		(end 418.978842 -279.21585)
		(width 0.18288)
		(layer "In4.Cu")
		(net "M_F_CPU0_SA_DQ<28>")
	)
	(segment
		(start 418.819838 -275.442934)
		(end 418.819838 -275.184362)
		(width 0.18288)
		(layer "In4.Cu")
		(net "M_F_CPU0_SA_DQ<28>")
	)
	(segment
		(start 381.03048 -259.296662)
		(end 381.018542 -259.289804)
		(width 0.088646)
		(layer "In4.Cu")
		(net "M_F_CPU0_SA_DQ<28>")
	)
	(segment
		(start 413.3977 -271.56283)
		(end 412.901638 -271.56283)
		(width 0.18288)
		(layer "In4.Cu")
		(net "M_F_CPU0_SA_DQ<28>")
	)
	(segment
		(start 380.336552 -259.69468)
		(end 380.2888 -259.769356)
		(width 0.088646)
		(layer "In4.Cu")
		(net "M_F_CPU0_SA_DQ<28>")
	)
	(segment
		(start 412.368746 -271.035526)
		(end 412.127446 -270.794226)
		(width 0.18288)
		(layer "In4.Cu")
		(net "M_F_CPU0_SA_DQ<28>")
	)
	(segment
		(start 405.473154 -269.140686)
		(end 397.71066 -261.378192)
		(width 0.18288)
		(layer "In4.Cu")
		(net "M_F_CPU0_SA_DQ<28>")
	)
	(segment
		(start 419.022784 -274.722844)
		(end 418.790882 -274.490942)
		(width 0.18288)
		(layer "In4.Cu")
		(net "M_F_CPU0_SA_DQ<28>")
	)
	(segment
		(start 419.549326 -280.09215)
		(end 419.732206 -279.90927)
		(width 0.18288)
		(layer "In4.Cu")
		(net "M_F_CPU0_SA_DQ<28>")
	)
	(segment
		(start 406.647142 -269.140686)
		(end 405.473154 -269.140686)
		(width 0.18288)
		(layer "In4.Cu")
		(net "M_F_CPU0_SA_DQ<28>")
	)
	(segment
		(start 410.623004 -271.032224)
		(end 410.385006 -270.794226)
		(width 0.18288)
		(layer "In4.Cu")
		(net "M_F_CPU0_SA_DQ<28>")
	)
	(segment
		(start 418.978842 -280.27503)
		(end 419.161722 -280.09215)
		(width 0.18288)
		(layer "In4.Cu")
		(net "M_F_CPU0_SA_DQ<28>")
	)
	(segment
		(start 409.336494 -270.794226)
		(end 408.472894 -269.930626)
		(width 0.18288)
		(layer "In4.Cu")
		(net "M_F_CPU0_SA_DQ<28>")
	)
	(segment
		(start 378.768864 -259.941314)
		(end 378.016262 -259.616956)
		(width 0.088646)
		(layer "In4.Cu")
		(net "M_F_CPU0_SA_DQ<28>")
	)
	(segment
		(start 384.40741 -259.292598)
		(end 384.392678 -259.301234)
		(width 0.088646)
		(layer "In4.Cu")
		(net "M_F_CPU0_SA_DQ<28>")
	)
	(segment
		(start 418.53231 -274.490942)
		(end 418.329364 -274.693888)
		(width 0.18288)
		(layer "In4.Cu")
		(net "M_F_CPU0_SA_DQ<28>")
	)
	(segment
		(start 385.34721 -259.292598)
		(end 385.332478 -259.301234)
		(width 0.088646)
		(layer "In4.Cu")
		(net "M_F_CPU0_SA_DQ<28>")
	)
	(segment
		(start 384.419348 -259.28574)
		(end 384.40741 -259.292598)
		(width 0.088646)
		(layer "In4.Cu")
		(net "M_F_CPU0_SA_DQ<28>")
	)
	(segment
		(start 419.161722 -280.09215)
		(end 419.549326 -280.09215)
		(width 0.18288)
		(layer "In4.Cu")
		(net "M_F_CPU0_SA_DQ<28>")
	)
	(segment
		(start 379.149356 -259.938012)
		(end 379.137672 -259.944616)
		(width 0.088646)
		(layer "In4.Cu")
		(net "M_F_CPU0_SA_DQ<28>")
	)
	(segment
		(start 382.902714 -259.292344)
		(end 382.898142 -259.289804)
		(width 0.088646)
		(layer "In4.Cu")
		(net "M_F_CPU0_SA_DQ<28>")
	)
	(segment
		(start 417.83889 -274.203414)
		(end 418.041836 -274.000468)
		(width 0.18288)
		(layer "In4.Cu")
		(net "M_F_CPU0_SA_DQ<28>")
	)
	(segment
		(start 417.089844 -273.71294)
		(end 416.770058 -273.393154)
		(width 0.18288)
		(layer "In4.Cu")
		(net "M_F_CPU0_SA_DQ<28>")
	)
	(segment
		(start 389.50646 -259.451856)
		(end 387.494018 -259.451856)
		(width 0.18288)
		(layer "In4.Cu")
		(net "M_F_CPU0_SA_DQ<28>")
	)
	(segment
		(start 394.000228 -261.378192)
		(end 393.34567 -261.107174)
		(width 0.18288)
		(layer "In4.Cu")
		(net "M_F_CPU0_SA_DQ<28>")
	)
	(segment
		(start 420.736014 -282.316682)
		(end 420.30523 -281.885898)
		(width 0.18288)
		(layer "In4.Cu")
		(net "M_F_CPU0_SA_DQ<28>")
	)
	(segment
		(start 393.34567 -261.107174)
		(end 393.325604 -261.098792)
		(width 0.18288)
		(layer "In4.Cu")
		(net "M_F_CPU0_SA_DQ<28>")
	)
	(segment
		(start 419.022784 -274.981416)
		(end 419.022784 -274.722844)
		(width 0.18288)
		(layer "In4.Cu")
		(net "M_F_CPU0_SA_DQ<28>")
	)
	(segment
		(start 380.407164 -259.545074)
		(end 380.3777 -259.61594)
		(width 0.088646)
		(layer "In4.Cu")
		(net "M_F_CPU0_SA_DQ<28>")
	)
	(arc
		(start 379.137672 -259.944616)
		(mid 378.952817 -259.991566)
		(end 378.768864 -259.941314)
		(width 0.088646)
		(layer "In4.Cu")
		(net "M_F_CPU0_SA_DQ<28>")
	)
	(arc
		(start 381.018542 -259.289804)
		(mid 380.833157 -259.242166)
		(end 380.648464 -259.292344)
		(width 0.088646)
		(layer "In4.Cu")
		(net "M_F_CPU0_SA_DQ<28>")
	)
	(arc
		(start 381.958342 -259.289804)
		(mid 381.772957 -259.242166)
		(end 381.588264 -259.292344)
		(width 0.088646)
		(layer "In4.Cu")
		(net "M_F_CPU0_SA_DQ<28>")
	)
	(arc
		(start 385.332478 -259.301234)
		(mid 385.056003 -259.368554)
		(end 384.781806 -259.292598)
		(width 0.088646)
		(layer "In4.Cu")
		(net "M_F_CPU0_SA_DQ<28>")
	)
	(arc
		(start 379.708664 -259.941314)
		(mid 379.429461 -259.865674)
		(end 379.149356 -259.938012)
		(width 0.088646)
		(layer "In4.Cu")
		(net "M_F_CPU0_SA_DQ<28>")
	)
	(arc
		(start 385.721606 -259.292598)
		(mid 385.541259 -259.242395)
		(end 385.359148 -259.28574)
		(width 0.088646)
		(layer "In4.Cu")
		(net "M_F_CPU0_SA_DQ<28>")
	)
	(arc
		(start 382.528064 -259.292344)
		(mid 382.249741 -259.368137)
		(end 381.97028 -259.296662)
		(width 0.088646)
		(layer "In4.Cu")
		(net "M_F_CPU0_SA_DQ<28>")
	)
	(arc
		(start 380.2888 -259.769356)
		(mid 380.2622 -259.805037)
		(end 380.230888 -259.836666)
		(width 0.088646)
		(layer "In4.Cu")
		(net "M_F_CPU0_SA_DQ<28>")
	)
	(arc
		(start 386.789422 -259.300218)
		(mid 386.785869 -259.300016)
		(end 386.78231 -259.299964)
		(width 0.088646)
		(layer "In4.Cu")
		(net "M_F_CPU0_SA_DQ<28>")
	)
	(arc
		(start 386.28193 -259.299964)
		(mid 386.261702 -259.307959)
		(end 386.241798 -259.316728)
		(width 0.088646)
		(layer "In4.Cu")
		(net "M_F_CPU0_SA_DQ<28>")
	)
	(arc
		(start 380.499366 -259.406898)
		(mid 380.446472 -259.471452)
		(end 380.407164 -259.545074)
		(width 0.088646)
		(layer "In4.Cu")
		(net "M_F_CPU0_SA_DQ<28>")
	)
	(arc
		(start 380.3777 -259.61594)
		(mid 380.358879 -259.656226)
		(end 380.336552 -259.69468)
		(width 0.088646)
		(layer "In4.Cu")
		(net "M_F_CPU0_SA_DQ<28>")
	)
	(arc
		(start 383.46126 -259.296154)
		(mid 383.181494 -259.368062)
		(end 382.902714 -259.292344)
		(width 0.088646)
		(layer "In4.Cu")
		(net "M_F_CPU0_SA_DQ<28>")
	)
	(arc
		(start 380.648464 -259.292344)
		(mid 380.570147 -259.344719)
		(end 380.499366 -259.406898)
		(width 0.088646)
		(layer "In4.Cu")
		(net "M_F_CPU0_SA_DQ<28>")
	)
	(arc
		(start 380.230888 -259.836666)
		(mid 380.162182 -259.891148)
		(end 380.088394 -259.93852)
		(width 0.088646)
		(layer "In4.Cu")
		(net "M_F_CPU0_SA_DQ<28>")
	)
	(arc
		(start 381.588264 -259.292344)
		(mid 381.309941 -259.368137)
		(end 381.03048 -259.296662)
		(width 0.088646)
		(layer "In4.Cu")
		(net "M_F_CPU0_SA_DQ<28>")
	)
	(arc
		(start 386.241798 -259.316728)
		(mid 385.978774 -259.368071)
		(end 385.721606 -259.292598)
		(width 0.088646)
		(layer "In4.Cu")
		(net "M_F_CPU0_SA_DQ<28>")
	)
	(arc
		(start 382.898142 -259.289804)
		(mid 382.712757 -259.242166)
		(end 382.528064 -259.292344)
		(width 0.088646)
		(layer "In4.Cu")
		(net "M_F_CPU0_SA_DQ<28>")
	)
	(arc
		(start 384.392678 -259.301234)
		(mid 384.116203 -259.368554)
		(end 383.842006 -259.292598)
		(width 0.088646)
		(layer "In4.Cu")
		(net "M_F_CPU0_SA_DQ<28>")
	)
	(arc
		(start 384.781806 -259.292598)
		(mid 384.601459 -259.242395)
		(end 384.419348 -259.28574)
		(width 0.088646)
		(layer "In4.Cu")
		(net "M_F_CPU0_SA_DQ<28>")
	)
	(arc
		(start 380.077472 -259.944616)
		(mid 379.892617 -259.991566)
		(end 379.708664 -259.941314)
		(width 0.088646)
		(layer "In4.Cu")
		(net "M_F_CPU0_SA_DQ<28>")
	)
	(arc
		(start 383.842006 -259.292598)
		(mid 383.654808 -259.242455)
		(end 383.46761 -259.292598)
		(width 0.088646)
		(layer "In4.Cu")
		(net "M_F_CPU0_SA_DQ<28>")
	)
	(segment
		(start 431.076354 -286.15386)
		(end 431.280316 -285.949898)
		(width 0.20066)
		(layer "F.Cu")
		(net "M_F_CPU0_SA_DQ<27>")
	)
	(segment
		(start 430.395126 -286.15386)
		(end 431.076354 -286.15386)
		(width 0.20066)
		(layer "F.Cu")
		(net "M_F_CPU0_SA_DQ<27>")
	)
	(segment
		(start 425.940982 -285.716726)
		(end 427.639226 -285.716726)
		(width 0.20066)
		(layer "F.Cu")
		(net "M_F_CPU0_SA_DQ<27>")
	)
	(segment
		(start 428.367952 -286.14878)
		(end 428.375064 -286.141668)
		(width 0.1016)
		(layer "F.Cu")
		(net "M_F_CPU0_SA_DQ<27>")
	)
	(segment
		(start 424.836082 -285.716726)
		(end 425.940982 -285.716726)
		(width 0.20066)
		(layer "F.Cu")
		(net "M_F_CPU0_SA_DQ<27>")
	)
	(segment
		(start 428.375064 -286.141668)
		(end 430.382934 -286.141668)
		(width 0.1016)
		(layer "F.Cu")
		(net "M_F_CPU0_SA_DQ<27>")
	)
	(segment
		(start 379.896116 -260.708902)
		(end 379.896116 -261.244334)
		(width 0.20066)
		(layer "F.Cu")
		(net "M_F_CPU0_SA_DQ<27>")
	)
	(segment
		(start 379.895862 -261.244588)
		(end 379.895862 -261.244842)
		(width 0.20066)
		(layer "F.Cu")
		(net "M_F_CPU0_SA_DQ<27>")
	)
	(segment
		(start 432.15052 -285.716726)
		(end 433.484782 -285.716726)
		(width 0.20066)
		(layer "F.Cu")
		(net "M_F_CPU0_SA_DQ<27>")
	)
	(segment
		(start 379.896116 -261.244334)
		(end 379.895862 -261.244588)
		(width 0.20066)
		(layer "F.Cu")
		(net "M_F_CPU0_SA_DQ<27>")
	)
	(segment
		(start 431.898552 -285.464758)
		(end 432.15052 -285.716726)
		(width 0.20066)
		(layer "F.Cu")
		(net "M_F_CPU0_SA_DQ<27>")
	)
	(segment
		(start 427.639226 -285.716726)
		(end 428.07128 -286.14878)
		(width 0.20066)
		(layer "F.Cu")
		(net "M_F_CPU0_SA_DQ<27>")
	)
	(segment
		(start 430.382934 -286.141668)
		(end 430.395126 -286.15386)
		(width 0.1016)
		(layer "F.Cu")
		(net "M_F_CPU0_SA_DQ<27>")
	)
	(segment
		(start 431.280316 -285.949898)
		(end 431.280316 -285.698946)
		(width 0.20066)
		(layer "F.Cu")
		(net "M_F_CPU0_SA_DQ<27>")
	)
	(segment
		(start 428.07128 -286.14878)
		(end 428.363126 -286.14878)
		(width 0.20066)
		(layer "F.Cu")
		(net "M_F_CPU0_SA_DQ<27>")
	)
	(segment
		(start 431.514504 -285.464758)
		(end 431.898552 -285.464758)
		(width 0.20066)
		(layer "F.Cu")
		(net "M_F_CPU0_SA_DQ<27>")
	)
	(segment
		(start 428.363126 -286.14878)
		(end 428.367952 -286.14878)
		(width 0.101854)
		(layer "F.Cu")
		(net "M_F_CPU0_SA_DQ<27>")
	)
	(segment
		(start 431.280316 -285.698946)
		(end 431.514504 -285.464758)
		(width 0.20066)
		(layer "F.Cu")
		(net "M_F_CPU0_SA_DQ<27>")
	)
	(segment
		(start 411.520894 -274.266406)
		(end 407.691844 -274.266406)
		(width 0.18288)
		(layer "In4.Cu")
		(net "M_F_CPU0_SA_DQ<27>")
	)
	(segment
		(start 413.494474 -276.239986)
		(end 411.520894 -274.266406)
		(width 0.18288)
		(layer "In4.Cu")
		(net "M_F_CPU0_SA_DQ<27>")
	)
	(segment
		(start 421.364664 -285.292292)
		(end 419.291516 -285.292292)
		(width 0.18288)
		(layer "In4.Cu")
		(net "M_F_CPU0_SA_DQ<27>")
	)
	(segment
		(start 405.583136 -272.674588)
		(end 405.238458 -272.53184)
		(width 0.18288)
		(layer "In4.Cu")
		(net "M_F_CPU0_SA_DQ<27>")
	)
	(segment
		(start 422.423844 -285.292292)
		(end 422.240964 -285.475172)
		(width 0.18288)
		(layer "In4.Cu")
		(net "M_F_CPU0_SA_DQ<27>")
	)
	(segment
		(start 383.479548 -261.576312)
		(end 383.46761 -261.5692)
		(width 0.088646)
		(layer "In4.Cu")
		(net "M_F_CPU0_SA_DQ<27>")
	)
	(segment
		(start 422.240964 -285.475172)
		(end 422.240964 -286.094932)
		(width 0.18288)
		(layer "In4.Cu")
		(net "M_F_CPU0_SA_DQ<27>")
	)
	(segment
		(start 396.19809 -263.491472)
		(end 393.50823 -263.491472)
		(width 0.18288)
		(layer "In4.Cu")
		(net "M_F_CPU0_SA_DQ<27>")
	)
	(segment
		(start 407.420572 -273.27987)
		(end 406.81529 -272.674588)
		(width 0.18288)
		(layer "In4.Cu")
		(net "M_F_CPU0_SA_DQ<27>")
	)
	(segment
		(start 382.902714 -261.5692)
		(end 382.898142 -261.57174)
		(width 0.088646)
		(layer "In4.Cu")
		(net "M_F_CPU0_SA_DQ<27>")
	)
	(segment
		(start 421.547544 -285.475172)
		(end 421.364664 -285.292292)
		(width 0.18288)
		(layer "In4.Cu")
		(net "M_F_CPU0_SA_DQ<27>")
	)
	(segment
		(start 381.97028 -261.564882)
		(end 381.962914 -261.5692)
		(width 0.088646)
		(layer "In4.Cu")
		(net "M_F_CPU0_SA_DQ<27>")
	)
	(segment
		(start 421.730424 -286.277812)
		(end 421.547544 -286.094932)
		(width 0.18288)
		(layer "In4.Cu")
		(net "M_F_CPU0_SA_DQ<27>")
	)
	(segment
		(start 392.105896 -262.910574)
		(end 391.410698 -262.215376)
		(width 0.18288)
		(layer "In4.Cu")
		(net "M_F_CPU0_SA_DQ<27>")
	)
	(segment
		(start 422.240964 -286.094932)
		(end 422.058084 -286.277812)
		(width 0.18288)
		(layer "In4.Cu")
		(net "M_F_CPU0_SA_DQ<27>")
	)
	(segment
		(start 386.406898 -261.5692)
		(end 386.287264 -261.5692)
		(width 0.088646)
		(layer "In4.Cu")
		(net "M_F_CPU0_SA_DQ<27>")
	)
	(segment
		(start 407.691844 -274.266406)
		(end 407.420572 -273.995134)
		(width 0.18288)
		(layer "In4.Cu")
		(net "M_F_CPU0_SA_DQ<27>")
	)
	(segment
		(start 381.023114 -261.5692)
		(end 381.018542 -261.57174)
		(width 0.088646)
		(layer "In4.Cu")
		(net "M_F_CPU0_SA_DQ<27>")
	)
	(segment
		(start 419.291516 -285.292292)
		(end 415.868104 -281.86888)
		(width 0.18288)
		(layer "In4.Cu")
		(net "M_F_CPU0_SA_DQ<27>")
	)
	(segment
		(start 406.81529 -272.674588)
		(end 405.583136 -272.674588)
		(width 0.18288)
		(layer "In4.Cu")
		(net "M_F_CPU0_SA_DQ<27>")
	)
	(segment
		(start 422.058084 -286.277812)
		(end 421.730424 -286.277812)
		(width 0.18288)
		(layer "In4.Cu")
		(net "M_F_CPU0_SA_DQ<27>")
	)
	(segment
		(start 414.67405 -276.239986)
		(end 413.494474 -276.239986)
		(width 0.18288)
		(layer "In4.Cu")
		(net "M_F_CPU0_SA_DQ<27>")
	)
	(segment
		(start 386.808472 -261.284466)
		(end 386.691632 -261.284466)
		(width 0.088646)
		(layer "In4.Cu")
		(net "M_F_CPU0_SA_DQ<27>")
	)
	(segment
		(start 383.46761 -261.5692)
		(end 383.45364 -261.561326)
		(width 0.088646)
		(layer "In4.Cu")
		(net "M_F_CPU0_SA_DQ<27>")
	)
	(segment
		(start 405.238458 -272.53184)
		(end 396.19809 -263.491472)
		(width 0.18288)
		(layer "In4.Cu")
		(net "M_F_CPU0_SA_DQ<27>")
	)
	(segment
		(start 381.962914 -261.5692)
		(end 381.958342 -261.57174)
		(width 0.088646)
		(layer "In4.Cu")
		(net "M_F_CPU0_SA_DQ<27>")
	)
	(segment
		(start 407.420572 -273.995134)
		(end 407.420572 -273.27987)
		(width 0.18288)
		(layer "In4.Cu")
		(net "M_F_CPU0_SA_DQ<27>")
	)
	(segment
		(start 389.163306 -261.284466)
		(end 386.808472 -261.284466)
		(width 0.18288)
		(layer "In4.Cu")
		(net "M_F_CPU0_SA_DQ<27>")
	)
	(segment
		(start 421.547544 -286.094932)
		(end 421.547544 -285.475172)
		(width 0.18288)
		(layer "In4.Cu")
		(net "M_F_CPU0_SA_DQ<27>")
	)
	(segment
		(start 384.40741 -261.5692)
		(end 384.396996 -261.563104)
		(width 0.088646)
		(layer "In4.Cu")
		(net "M_F_CPU0_SA_DQ<27>")
	)
	(segment
		(start 424.411648 -285.292292)
		(end 422.423844 -285.292292)
		(width 0.18288)
		(layer "In4.Cu")
		(net "M_F_CPU0_SA_DQ<27>")
	)
	(segment
		(start 391.410698 -262.215376)
		(end 389.163306 -261.284466)
		(width 0.18288)
		(layer "In4.Cu")
		(net "M_F_CPU0_SA_DQ<27>")
	)
	(segment
		(start 385.72186 -261.5692)
		(end 385.721606 -261.5692)
		(width 0.088646)
		(layer "In4.Cu")
		(net "M_F_CPU0_SA_DQ<27>")
	)
	(segment
		(start 415.868104 -281.86888)
		(end 415.868104 -277.43404)
		(width 0.18288)
		(layer "In4.Cu")
		(net "M_F_CPU0_SA_DQ<27>")
	)
	(segment
		(start 383.84226 -261.5692)
		(end 383.84226 -261.569454)
		(width 0.088646)
		(layer "In4.Cu")
		(net "M_F_CPU0_SA_DQ<27>")
	)
	(segment
		(start 380.648464 -261.5692)
		(end 380.2507 -261.339838)
		(width 0.088646)
		(layer "In4.Cu")
		(net "M_F_CPU0_SA_DQ<27>")
	)
	(segment
		(start 386.691632 -261.284466)
		(end 386.406898 -261.5692)
		(width 0.088646)
		(layer "In4.Cu")
		(net "M_F_CPU0_SA_DQ<27>")
	)
	(segment
		(start 381.03048 -261.564882)
		(end 381.023114 -261.5692)
		(width 0.088646)
		(layer "In4.Cu")
		(net "M_F_CPU0_SA_DQ<27>")
	)
	(segment
		(start 415.868104 -277.43404)
		(end 414.67405 -276.239986)
		(width 0.18288)
		(layer "In4.Cu")
		(net "M_F_CPU0_SA_DQ<27>")
	)
	(segment
		(start 424.836082 -285.716726)
		(end 424.411648 -285.292292)
		(width 0.18288)
		(layer "In4.Cu")
		(net "M_F_CPU0_SA_DQ<27>")
	)
	(segment
		(start 393.50823 -263.491472)
		(end 392.105896 -262.910574)
		(width 0.18288)
		(layer "In4.Cu")
		(net "M_F_CPU0_SA_DQ<27>")
	)
	(arc
		(start 385.721606 -261.5692)
		(mid 385.534408 -261.619343)
		(end 385.34721 -261.5692)
		(width 0.088646)
		(layer "In4.Cu")
		(net "M_F_CPU0_SA_DQ<27>")
	)
	(arc
		(start 383.45364 -261.561326)
		(mid 383.177143 -261.493543)
		(end 382.902714 -261.5692)
		(width 0.088646)
		(layer "In4.Cu")
		(net "M_F_CPU0_SA_DQ<27>")
	)
	(arc
		(start 382.528064 -261.5692)
		(mid 382.249741 -261.493441)
		(end 381.97028 -261.564882)
		(width 0.088646)
		(layer "In4.Cu")
		(net "M_F_CPU0_SA_DQ<27>")
	)
	(arc
		(start 381.018542 -261.57174)
		(mid 380.833157 -261.619378)
		(end 380.648464 -261.5692)
		(width 0.088646)
		(layer "In4.Cu")
		(net "M_F_CPU0_SA_DQ<27>")
	)
	(arc
		(start 381.588264 -261.5692)
		(mid 381.309941 -261.493441)
		(end 381.03048 -261.564882)
		(width 0.088646)
		(layer "In4.Cu")
		(net "M_F_CPU0_SA_DQ<27>")
	)
	(arc
		(start 380.2507 -261.339838)
		(mid 380.079525 -261.269024)
		(end 379.895862 -261.244842)
		(width 0.088646)
		(layer "In4.Cu")
		(net "M_F_CPU0_SA_DQ<27>")
	)
	(arc
		(start 383.84226 -261.569454)
		(mid 383.661801 -261.619659)
		(end 383.479548 -261.576312)
		(width 0.088646)
		(layer "In4.Cu")
		(net "M_F_CPU0_SA_DQ<27>")
	)
	(arc
		(start 381.958342 -261.57174)
		(mid 381.772957 -261.619378)
		(end 381.588264 -261.5692)
		(width 0.088646)
		(layer "In4.Cu")
		(net "M_F_CPU0_SA_DQ<27>")
	)
	(arc
		(start 382.898142 -261.57174)
		(mid 382.712757 -261.619378)
		(end 382.528064 -261.5692)
		(width 0.088646)
		(layer "In4.Cu")
		(net "M_F_CPU0_SA_DQ<27>")
	)
	(arc
		(start 384.396996 -261.563104)
		(mid 384.118818 -261.493381)
		(end 383.84226 -261.5692)
		(width 0.088646)
		(layer "In4.Cu")
		(net "M_F_CPU0_SA_DQ<27>")
	)
	(arc
		(start 386.287264 -261.5692)
		(mid 386.004562 -261.493424)
		(end 385.72186 -261.5692)
		(width 0.088646)
		(layer "In4.Cu")
		(net "M_F_CPU0_SA_DQ<27>")
	)
	(arc
		(start 384.781806 -261.5692)
		(mid 384.594608 -261.619343)
		(end 384.40741 -261.5692)
		(width 0.088646)
		(layer "In4.Cu")
		(net "M_F_CPU0_SA_DQ<27>")
	)
	(arc
		(start 385.34721 -261.5692)
		(mid 385.064508 -261.493424)
		(end 384.781806 -261.5692)
		(width 0.088646)
		(layer "In4.Cu")
		(net "M_F_CPU0_SA_DQ<27>")
	)
	(segment
		(start 432.15052 -287.416748)
		(end 433.484782 -287.416748)
		(width 0.20066)
		(layer "F.Cu")
		(net "M_F_CPU0_SA_DQ<26>")
	)
	(segment
		(start 431.898552 -287.16478)
		(end 432.15052 -287.416748)
		(width 0.20066)
		(layer "F.Cu")
		(net "M_F_CPU0_SA_DQ<26>")
	)
	(segment
		(start 431.076354 -287.853882)
		(end 431.280316 -287.64992)
		(width 0.20066)
		(layer "F.Cu")
		(net "M_F_CPU0_SA_DQ<26>")
	)
	(segment
		(start 431.280316 -287.398968)
		(end 431.514504 -287.16478)
		(width 0.20066)
		(layer "F.Cu")
		(net "M_F_CPU0_SA_DQ<26>")
	)
	(segment
		(start 431.514504 -287.16478)
		(end 431.898552 -287.16478)
		(width 0.20066)
		(layer "F.Cu")
		(net "M_F_CPU0_SA_DQ<26>")
	)
	(segment
		(start 428.375064 -287.84169)
		(end 430.382934 -287.84169)
		(width 0.1016)
		(layer "F.Cu")
		(net "M_F_CPU0_SA_DQ<26>")
	)
	(segment
		(start 430.382934 -287.84169)
		(end 430.395126 -287.853882)
		(width 0.1016)
		(layer "F.Cu")
		(net "M_F_CPU0_SA_DQ<26>")
	)
	(segment
		(start 379.425962 -261.522718)
		(end 379.426216 -261.522972)
		(width 0.20066)
		(layer "F.Cu")
		(net "M_F_CPU0_SA_DQ<26>")
	)
	(segment
		(start 427.639226 -287.416748)
		(end 428.07128 -287.848802)
		(width 0.20066)
		(layer "F.Cu")
		(net "M_F_CPU0_SA_DQ<26>")
	)
	(segment
		(start 431.280316 -287.64992)
		(end 431.280316 -287.398968)
		(width 0.20066)
		(layer "F.Cu")
		(net "M_F_CPU0_SA_DQ<26>")
	)
	(segment
		(start 379.426216 -261.522972)
		(end 379.426216 -262.058658)
		(width 0.20066)
		(layer "F.Cu")
		(net "M_F_CPU0_SA_DQ<26>")
	)
	(segment
		(start 428.07128 -287.848802)
		(end 428.363126 -287.848802)
		(width 0.20066)
		(layer "F.Cu")
		(net "M_F_CPU0_SA_DQ<26>")
	)
	(segment
		(start 430.395126 -287.853882)
		(end 431.076354 -287.853882)
		(width 0.20066)
		(layer "F.Cu")
		(net "M_F_CPU0_SA_DQ<26>")
	)
	(segment
		(start 424.836082 -287.416748)
		(end 425.940982 -287.416748)
		(width 0.20066)
		(layer "F.Cu")
		(net "M_F_CPU0_SA_DQ<26>")
	)
	(segment
		(start 428.363126 -287.848802)
		(end 428.367952 -287.848802)
		(width 0.101854)
		(layer "F.Cu")
		(net "M_F_CPU0_SA_DQ<26>")
	)
	(segment
		(start 425.940982 -287.416748)
		(end 427.639226 -287.416748)
		(width 0.20066)
		(layer "F.Cu")
		(net "M_F_CPU0_SA_DQ<26>")
	)
	(segment
		(start 428.367952 -287.848802)
		(end 428.375064 -287.84169)
		(width 0.1016)
		(layer "F.Cu")
		(net "M_F_CPU0_SA_DQ<26>")
	)
	(segment
		(start 417.842954 -285.291022)
		(end 417.112958 -285.291022)
		(width 0.18288)
		(layer "In4.Cu")
		(net "M_F_CPU0_SA_DQ<26>")
	)
	(segment
		(start 417.112958 -285.291022)
		(end 416.483292 -284.661356)
		(width 0.18288)
		(layer "In4.Cu")
		(net "M_F_CPU0_SA_DQ<26>")
	)
	(segment
		(start 389.556498 -262.241538)
		(end 388.434072 -262.241538)
		(width 0.18288)
		(layer "In4.Cu")
		(net "M_F_CPU0_SA_DQ<26>")
	)
	(segment
		(start 380.184406 -262.386318)
		(end 380.172722 -262.379714)
		(width 0.088646)
		(layer "In4.Cu")
		(net "M_F_CPU0_SA_DQ<26>")
	)
	(segment
		(start 408.632914 -275.335746)
		(end 407.299668 -275.335746)
		(width 0.18288)
		(layer "In4.Cu")
		(net "M_F_CPU0_SA_DQ<26>")
	)
	(segment
		(start 418.198808 -285.646876)
		(end 417.842954 -285.291022)
		(width 0.18288)
		(layer "In4.Cu")
		(net "M_F_CPU0_SA_DQ<26>")
	)
	(segment
		(start 382.064006 -262.386318)
		(end 382.052322 -262.379714)
		(width 0.088646)
		(layer "In4.Cu")
		(net "M_F_CPU0_SA_DQ<26>")
	)
	(segment
		(start 411.903926 -277.728426)
		(end 411.736794 -277.728426)
		(width 0.18288)
		(layer "In4.Cu")
		(net "M_F_CPU0_SA_DQ<26>")
	)
	(segment
		(start 388.11708 -262.433054)
		(end 387.883908 -262.433054)
		(width 0.088646)
		(layer "In4.Cu")
		(net "M_F_CPU0_SA_DQ<26>")
	)
	(segment
		(start 424.800776 -287.138618)
		(end 424.652948 -286.99079)
		(width 0.18288)
		(layer "In4.Cu")
		(net "M_F_CPU0_SA_DQ<26>")
	)
	(segment
		(start 419.309296 -286.99079)
		(end 419.032436 -286.71393)
		(width 0.18288)
		(layer "In4.Cu")
		(net "M_F_CPU0_SA_DQ<26>")
	)
	(segment
		(start 391.575798 -263.79424)
		(end 390.353042 -262.571484)
		(width 0.18288)
		(layer "In4.Cu")
		(net "M_F_CPU0_SA_DQ<26>")
	)
	(segment
		(start 405.6126 -274.377404)
		(end 395.722348 -264.487152)
		(width 0.18288)
		(layer "In4.Cu")
		(net "M_F_CPU0_SA_DQ<26>")
	)
	(segment
		(start 407.299668 -275.335746)
		(end 406.341326 -274.377404)
		(width 0.18288)
		(layer "In4.Cu")
		(net "M_F_CPU0_SA_DQ<26>")
	)
	(segment
		(start 390.353042 -262.571484)
		(end 389.556498 -262.241538)
		(width 0.18288)
		(layer "In4.Cu")
		(net "M_F_CPU0_SA_DQ<26>")
	)
	(segment
		(start 409.306014 -276.008846)
		(end 408.632914 -275.335746)
		(width 0.18288)
		(layer "In4.Cu")
		(net "M_F_CPU0_SA_DQ<26>")
	)
	(segment
		(start 414.289494 -282.126944)
		(end 414.289494 -278.515826)
		(width 0.18288)
		(layer "In4.Cu")
		(net "M_F_CPU0_SA_DQ<26>")
	)
	(segment
		(start 381.124206 -262.386318)
		(end 381.112522 -262.379714)
		(width 0.088646)
		(layer "In4.Cu")
		(net "M_F_CPU0_SA_DQ<26>")
	)
	(segment
		(start 424.836082 -287.416748)
		(end 424.836082 -287.223708)
		(width 0.18288)
		(layer "In4.Cu")
		(net "M_F_CPU0_SA_DQ<26>")
	)
	(segment
		(start 414.960054 -283.332174)
		(end 414.289494 -282.126944)
		(width 0.18288)
		(layer "In4.Cu")
		(net "M_F_CPU0_SA_DQ<26>")
	)
	(segment
		(start 387.696964 -262.383016)
		(end 387.682232 -262.37438)
		(width 0.088646)
		(layer "In4.Cu")
		(net "M_F_CPU0_SA_DQ<26>")
	)
	(segment
		(start 406.341326 -274.377404)
		(end 405.6126 -274.377404)
		(width 0.18288)
		(layer "In4.Cu")
		(net "M_F_CPU0_SA_DQ<26>")
	)
	(segment
		(start 393.249404 -264.487152)
		(end 391.575798 -263.79424)
		(width 0.18288)
		(layer "In4.Cu")
		(net "M_F_CPU0_SA_DQ<26>")
	)
	(segment
		(start 416.483292 -284.661356)
		(end 416.289236 -284.661356)
		(width 0.18288)
		(layer "In4.Cu")
		(net "M_F_CPU0_SA_DQ<26>")
	)
	(segment
		(start 424.836082 -287.223708)
		(end 424.800776 -287.138618)
		(width 0.18288)
		(layer "In4.Cu")
		(net "M_F_CPU0_SA_DQ<26>")
	)
	(segment
		(start 388.308596 -262.241538)
		(end 388.11708 -262.433054)
		(width 0.088646)
		(layer "In4.Cu")
		(net "M_F_CPU0_SA_DQ<26>")
	)
	(segment
		(start 412.788354 -277.631144)
		(end 411.903926 -277.728426)
		(width 0.18288)
		(layer "In4.Cu")
		(net "M_F_CPU0_SA_DQ<26>")
	)
	(segment
		(start 388.434072 -262.241538)
		(end 388.308596 -262.241538)
		(width 0.088646)
		(layer "In4.Cu")
		(net "M_F_CPU0_SA_DQ<26>")
	)
	(segment
		(start 395.722348 -264.487152)
		(end 393.249404 -264.487152)
		(width 0.18288)
		(layer "In4.Cu")
		(net "M_F_CPU0_SA_DQ<26>")
	)
	(segment
		(start 383.001774 -262.385302)
		(end 382.997964 -262.383016)
		(width 0.088646)
		(layer "In4.Cu")
		(net "M_F_CPU0_SA_DQ<26>")
	)
	(segment
		(start 386.757164 -262.383016)
		(end 386.742432 -262.37438)
		(width 0.088646)
		(layer "In4.Cu")
		(net "M_F_CPU0_SA_DQ<26>")
	)
	(segment
		(start 411.736794 -277.728426)
		(end 410.017214 -276.008846)
		(width 0.18288)
		(layer "In4.Cu")
		(net "M_F_CPU0_SA_DQ<26>")
	)
	(segment
		(start 424.652948 -286.99079)
		(end 419.309296 -286.99079)
		(width 0.18288)
		(layer "In4.Cu")
		(net "M_F_CPU0_SA_DQ<26>")
	)
	(segment
		(start 413.404812 -277.631144)
		(end 412.788354 -277.631144)
		(width 0.18288)
		(layer "In4.Cu")
		(net "M_F_CPU0_SA_DQ<26>")
	)
	(segment
		(start 416.289236 -284.661356)
		(end 414.960054 -283.332174)
		(width 0.18288)
		(layer "In4.Cu")
		(net "M_F_CPU0_SA_DQ<26>")
	)
	(segment
		(start 414.289494 -278.515826)
		(end 413.404812 -277.631144)
		(width 0.18288)
		(layer "In4.Cu")
		(net "M_F_CPU0_SA_DQ<26>")
	)
	(segment
		(start 410.017214 -276.008846)
		(end 409.306014 -276.008846)
		(width 0.18288)
		(layer "In4.Cu")
		(net "M_F_CPU0_SA_DQ<26>")
	)
	(segment
		(start 382.997964 -262.383016)
		(end 382.992122 -262.379714)
		(width 0.088646)
		(layer "In4.Cu")
		(net "M_F_CPU0_SA_DQ<26>")
	)
	(segment
		(start 419.032436 -286.71393)
		(end 418.198808 -285.646876)
		(width 0.18288)
		(layer "In4.Cu")
		(net "M_F_CPU0_SA_DQ<26>")
	)
	(arc
		(start 382.432814 -262.383016)
		(mid 382.24886 -262.433145)
		(end 382.064006 -262.386318)
		(width 0.088646)
		(layer "In4.Cu")
		(net "M_F_CPU0_SA_DQ<26>")
	)
	(arc
		(start 387.13156 -262.383016)
		(mid 386.944362 -262.433159)
		(end 386.757164 -262.383016)
		(width 0.088646)
		(layer "In4.Cu")
		(net "M_F_CPU0_SA_DQ<26>")
	)
	(arc
		(start 386.742432 -262.37438)
		(mid 386.465957 -262.30706)
		(end 386.19176 -262.383016)
		(width 0.088646)
		(layer "In4.Cu")
		(net "M_F_CPU0_SA_DQ<26>")
	)
	(arc
		(start 385.25196 -262.383016)
		(mid 385.064762 -262.433159)
		(end 384.877564 -262.383016)
		(width 0.088646)
		(layer "In4.Cu")
		(net "M_F_CPU0_SA_DQ<26>")
	)
	(arc
		(start 387.883908 -262.433054)
		(mid 387.787143 -262.420333)
		(end 387.696964 -262.383016)
		(width 0.088646)
		(layer "In4.Cu")
		(net "M_F_CPU0_SA_DQ<26>")
	)
	(arc
		(start 387.682232 -262.37438)
		(mid 387.405757 -262.30706)
		(end 387.13156 -262.383016)
		(width 0.088646)
		(layer "In4.Cu")
		(net "M_F_CPU0_SA_DQ<26>")
	)
	(arc
		(start 381.112522 -262.379714)
		(mid 380.832417 -262.307272)
		(end 380.553214 -262.383016)
		(width 0.088646)
		(layer "In4.Cu")
		(net "M_F_CPU0_SA_DQ<26>")
	)
	(arc
		(start 384.31216 -262.383016)
		(mid 384.124962 -262.433159)
		(end 383.937764 -262.383016)
		(width 0.088646)
		(layer "In4.Cu")
		(net "M_F_CPU0_SA_DQ<26>")
	)
	(arc
		(start 382.052322 -262.379714)
		(mid 381.772217 -262.307272)
		(end 381.493014 -262.383016)
		(width 0.088646)
		(layer "In4.Cu")
		(net "M_F_CPU0_SA_DQ<26>")
	)
	(arc
		(start 381.493014 -262.383016)
		(mid 381.30906 -262.433145)
		(end 381.124206 -262.386318)
		(width 0.088646)
		(layer "In4.Cu")
		(net "M_F_CPU0_SA_DQ<26>")
	)
	(arc
		(start 380.172722 -262.379714)
		(mid 379.80817 -262.198953)
		(end 379.426216 -262.058658)
		(width 0.088646)
		(layer "In4.Cu")
		(net "M_F_CPU0_SA_DQ<26>")
	)
	(arc
		(start 383.372614 -262.383016)
		(mid 383.187493 -262.433279)
		(end 383.001774 -262.385302)
		(width 0.088646)
		(layer "In4.Cu")
		(net "M_F_CPU0_SA_DQ<26>")
	)
	(arc
		(start 382.992122 -262.379714)
		(mid 382.712017 -262.307272)
		(end 382.432814 -262.383016)
		(width 0.088646)
		(layer "In4.Cu")
		(net "M_F_CPU0_SA_DQ<26>")
	)
	(arc
		(start 384.877564 -262.383016)
		(mid 384.594862 -262.30724)
		(end 384.31216 -262.383016)
		(width 0.088646)
		(layer "In4.Cu")
		(net "M_F_CPU0_SA_DQ<26>")
	)
	(arc
		(start 386.19176 -262.383016)
		(mid 386.004562 -262.433159)
		(end 385.817364 -262.383016)
		(width 0.088646)
		(layer "In4.Cu")
		(net "M_F_CPU0_SA_DQ<26>")
	)
	(arc
		(start 383.937764 -262.383016)
		(mid 383.655206 -262.307367)
		(end 383.372614 -262.383016)
		(width 0.088646)
		(layer "In4.Cu")
		(net "M_F_CPU0_SA_DQ<26>")
	)
	(arc
		(start 385.817364 -262.383016)
		(mid 385.534662 -262.30724)
		(end 385.25196 -262.383016)
		(width 0.088646)
		(layer "In4.Cu")
		(net "M_F_CPU0_SA_DQ<26>")
	)
	(arc
		(start 380.553214 -262.383016)
		(mid 380.36926 -262.433145)
		(end 380.184406 -262.386318)
		(width 0.088646)
		(layer "In4.Cu")
		(net "M_F_CPU0_SA_DQ<26>")
	)
	(segment
		(start 378.016516 -260.708902)
		(end 378.016516 -261.244334)
		(width 0.20066)
		(layer "F.Cu")
		(net "M_F_CPU0_SA_DQ<25>")
	)
	(segment
		(start 424.391582 -286.141668)
		(end 424.273472 -286.259778)
		(width 0.20066)
		(layer "F.Cu")
		(net "M_F_CPU0_SA_DQ<25>")
	)
	(segment
		(start 423.610278 -286.815276)
		(end 423.361612 -286.56661)
		(width 0.20066)
		(layer "F.Cu")
		(net "M_F_CPU0_SA_DQ<25>")
	)
	(segment
		(start 429.38446 -286.566864)
		(end 427.792896 -286.566864)
		(width 0.20066)
		(layer "F.Cu")
		(net "M_F_CPU0_SA_DQ<25>")
	)
	(segment
		(start 421.840914 -286.56661)
		(end 420.736014 -286.56661)
		(width 0.20066)
		(layer "F.Cu")
		(net "M_F_CPU0_SA_DQ<25>")
	)
	(segment
		(start 426.951394 -286.135318)
		(end 426.945044 -286.141668)
		(width 0.1016)
		(layer "F.Cu")
		(net "M_F_CPU0_SA_DQ<25>")
	)
	(segment
		(start 424.273472 -286.259778)
		(end 424.273472 -286.627316)
		(width 0.20066)
		(layer "F.Cu")
		(net "M_F_CPU0_SA_DQ<25>")
	)
	(segment
		(start 424.273472 -286.627316)
		(end 424.085512 -286.815276)
		(width 0.20066)
		(layer "F.Cu")
		(net "M_F_CPU0_SA_DQ<25>")
	)
	(segment
		(start 424.73626 -286.141668)
		(end 424.391582 -286.141668)
		(width 0.20066)
		(layer "F.Cu")
		(net "M_F_CPU0_SA_DQ<25>")
	)
	(segment
		(start 378.016516 -261.244334)
		(end 378.016262 -261.244588)
		(width 0.20066)
		(layer "F.Cu")
		(net "M_F_CPU0_SA_DQ<25>")
	)
	(segment
		(start 426.945044 -286.141668)
		(end 424.756326 -286.141668)
		(width 0.1016)
		(layer "F.Cu")
		(net "M_F_CPU0_SA_DQ<25>")
	)
	(segment
		(start 427.36135 -286.135318)
		(end 426.951394 -286.135318)
		(width 0.20066)
		(layer "F.Cu")
		(net "M_F_CPU0_SA_DQ<25>")
	)
	(segment
		(start 424.085512 -286.815276)
		(end 423.610278 -286.815276)
		(width 0.20066)
		(layer "F.Cu")
		(net "M_F_CPU0_SA_DQ<25>")
	)
	(segment
		(start 429.384714 -286.56661)
		(end 429.38446 -286.566864)
		(width 0.20066)
		(layer "F.Cu")
		(net "M_F_CPU0_SA_DQ<25>")
	)
	(segment
		(start 423.361612 -286.56661)
		(end 421.840914 -286.56661)
		(width 0.20066)
		(layer "F.Cu")
		(net "M_F_CPU0_SA_DQ<25>")
	)
	(segment
		(start 378.016262 -261.244588)
		(end 378.016262 -261.244842)
		(width 0.20066)
		(layer "F.Cu")
		(net "M_F_CPU0_SA_DQ<25>")
	)
	(segment
		(start 427.792896 -286.566864)
		(end 427.36135 -286.135318)
		(width 0.20066)
		(layer "F.Cu")
		(net "M_F_CPU0_SA_DQ<25>")
	)
	(segment
		(start 424.756326 -286.141668)
		(end 424.73626 -286.141668)
		(width 0.101854)
		(layer "F.Cu")
		(net "M_F_CPU0_SA_DQ<25>")
	)
	(segment
		(start 416.009074 -283.403802)
		(end 416.20948 -283.203396)
		(width 0.18288)
		(layer "In4.Cu")
		(net "M_F_CPU0_SA_DQ<25>")
	)
	(segment
		(start 386.808472 -261.760716)
		(end 386.218176 -261.760716)
		(width 0.088646)
		(layer "In4.Cu")
		(net "M_F_CPU0_SA_DQ<25>")
	)
	(segment
		(start 416.958526 -283.69387)
		(end 416.699954 -283.69387)
		(width 0.18288)
		(layer "In4.Cu")
		(net "M_F_CPU0_SA_DQ<25>")
	)
	(segment
		(start 420.736014 -286.56661)
		(end 419.964616 -285.795212)
		(width 0.18288)
		(layer "In4.Cu")
		(net "M_F_CPU0_SA_DQ<25>")
	)
	(segment
		(start 405.553418 -273.268694)
		(end 405.071072 -273.068796)
		(width 0.18288)
		(layer "In4.Cu")
		(net "M_F_CPU0_SA_DQ<25>")
	)
	(segment
		(start 393.379706 -263.989312)
		(end 391.841736 -263.352026)
		(width 0.18288)
		(layer "In4.Cu")
		(net "M_F_CPU0_SA_DQ<25>")
	)
	(segment
		(start 378.673614 -261.7343)
		(end 378.593604 -261.688072)
		(width 0.088646)
		(layer "In4.Cu")
		(net "M_F_CPU0_SA_DQ<25>")
	)
	(segment
		(start 383.937764 -261.7343)
		(end 383.93751 -261.7343)
		(width 0.088646)
		(layer "In4.Cu")
		(net "M_F_CPU0_SA_DQ<25>")
	)
	(segment
		(start 414.564322 -277.138638)
		(end 414.22447 -277.47849)
		(width 0.18288)
		(layer "In4.Cu")
		(net "M_F_CPU0_SA_DQ<25>")
	)
	(segment
		(start 416.20948 -282.944824)
		(end 415.808922 -282.544266)
		(width 0.18288)
		(layer "In4.Cu")
		(net "M_F_CPU0_SA_DQ<25>")
	)
	(segment
		(start 409.808934 -274.835366)
		(end 407.520902 -274.835366)
		(width 0.18288)
		(layer "In4.Cu")
		(net "M_F_CPU0_SA_DQ<25>")
	)
	(segment
		(start 382.997964 -261.7343)
		(end 382.990598 -261.738364)
		(width 0.088646)
		(layer "In4.Cu")
		(net "M_F_CPU0_SA_DQ<25>")
	)
	(segment
		(start 391.841736 -263.352026)
		(end 390.911588 -262.421878)
		(width 0.18288)
		(layer "In4.Cu")
		(net "M_F_CPU0_SA_DQ<25>")
	)
	(segment
		(start 416.009074 -283.662374)
		(end 416.009074 -283.403802)
		(width 0.18288)
		(layer "In4.Cu")
		(net "M_F_CPU0_SA_DQ<25>")
	)
	(segment
		(start 414.856422 -280.107898)
		(end 414.856422 -278.369014)
		(width 0.18288)
		(layer "In4.Cu")
		(net "M_F_CPU0_SA_DQ<25>")
	)
	(segment
		(start 416.240976 -283.894276)
		(end 416.009074 -283.662374)
		(width 0.18288)
		(layer "In4.Cu")
		(net "M_F_CPU0_SA_DQ<25>")
	)
	(segment
		(start 411.406594 -276.620986)
		(end 411.406594 -275.03374)
		(width 0.18288)
		(layer "In4.Cu")
		(net "M_F_CPU0_SA_DQ<25>")
	)
	(segment
		(start 410.592524 -275.240496)
		(end 410.214064 -275.240496)
		(width 0.18288)
		(layer "In4.Cu")
		(net "M_F_CPU0_SA_DQ<25>")
	)
	(segment
		(start 382.062736 -261.731506)
		(end 382.058164 -261.7343)
		(width 0.088646)
		(layer "In4.Cu")
		(net "M_F_CPU0_SA_DQ<25>")
	)
	(segment
		(start 381.118364 -261.7343)
		(end 381.110998 -261.738364)
		(width 0.088646)
		(layer "In4.Cu")
		(net "M_F_CPU0_SA_DQ<25>")
	)
	(segment
		(start 383.386838 -261.742682)
		(end 383.37236 -261.7343)
		(width 0.088646)
		(layer "In4.Cu")
		(net "M_F_CPU0_SA_DQ<25>")
	)
	(segment
		(start 414.714944 -278.227536)
		(end 414.714944 -277.968964)
		(width 0.18288)
		(layer "In4.Cu")
		(net "M_F_CPU0_SA_DQ<25>")
	)
	(segment
		(start 414.856422 -281.095958)
		(end 415.016442 -280.935938)
		(width 0.18288)
		(layer "In4.Cu")
		(net "M_F_CPU0_SA_DQ<25>")
	)
	(segment
		(start 411.406594 -275.03374)
		(end 411.246574 -274.87372)
		(width 0.18288)
		(layer "In4.Cu")
		(net "M_F_CPU0_SA_DQ<25>")
	)
	(segment
		(start 413.453834 -276.966426)
		(end 412.349696 -276.966426)
		(width 0.18288)
		(layer "In4.Cu")
		(net "M_F_CPU0_SA_DQ<25>")
	)
	(segment
		(start 415.054796 -277.37054)
		(end 414.822894 -277.138638)
		(width 0.18288)
		(layer "In4.Cu")
		(net "M_F_CPU0_SA_DQ<25>")
	)
	(segment
		(start 414.856422 -281.998674)
		(end 414.856422 -281.095958)
		(width 0.18288)
		(layer "In4.Cu")
		(net "M_F_CPU0_SA_DQ<25>")
	)
	(segment
		(start 413.965898 -277.47849)
		(end 413.453834 -276.966426)
		(width 0.18288)
		(layer "In4.Cu")
		(net "M_F_CPU0_SA_DQ<25>")
	)
	(segment
		(start 380.183136 -261.731506)
		(end 380.178564 -261.7343)
		(width 0.088646)
		(layer "In4.Cu")
		(net "M_F_CPU0_SA_DQ<25>")
	)
	(segment
		(start 384.322574 -261.740396)
		(end 384.31216 -261.7343)
		(width 0.088646)
		(layer "In4.Cu")
		(net "M_F_CPU0_SA_DQ<25>")
	)
	(segment
		(start 411.566614 -276.781006)
		(end 411.406594 -276.620986)
		(width 0.18288)
		(layer "In4.Cu")
		(net "M_F_CPU0_SA_DQ<25>")
	)
	(segment
		(start 415.402014 -282.544266)
		(end 414.856422 -281.998674)
		(width 0.18288)
		(layer "In4.Cu")
		(net "M_F_CPU0_SA_DQ<25>")
	)
	(segment
		(start 395.991588 -263.989312)
		(end 393.379706 -263.989312)
		(width 0.18288)
		(layer "In4.Cu")
		(net "M_F_CPU0_SA_DQ<25>")
	)
	(segment
		(start 406.680416 -273.268694)
		(end 405.553418 -273.268694)
		(width 0.18288)
		(layer "In4.Cu")
		(net "M_F_CPU0_SA_DQ<25>")
	)
	(segment
		(start 412.164276 -276.781006)
		(end 411.566614 -276.781006)
		(width 0.18288)
		(layer "In4.Cu")
		(net "M_F_CPU0_SA_DQ<25>")
	)
	(segment
		(start 411.246574 -274.87372)
		(end 410.9593 -274.87372)
		(width 0.18288)
		(layer "In4.Cu")
		(net "M_F_CPU0_SA_DQ<25>")
	)
	(segment
		(start 379.243336 -261.731506)
		(end 379.238764 -261.7343)
		(width 0.088646)
		(layer "In4.Cu")
		(net "M_F_CPU0_SA_DQ<25>")
	)
	(segment
		(start 414.822894 -277.138638)
		(end 414.564322 -277.138638)
		(width 0.18288)
		(layer "In4.Cu")
		(net "M_F_CPU0_SA_DQ<25>")
	)
	(segment
		(start 390.911588 -262.421878)
		(end 389.002524 -261.631176)
		(width 0.18288)
		(layer "In4.Cu")
		(net "M_F_CPU0_SA_DQ<25>")
	)
	(segment
		(start 416.699954 -283.69387)
		(end 416.499548 -283.894276)
		(width 0.18288)
		(layer "In4.Cu")
		(net "M_F_CPU0_SA_DQ<25>")
	)
	(segment
		(start 385.817364 -261.7343)
		(end 385.81711 -261.7343)
		(width 0.088646)
		(layer "In4.Cu")
		(net "M_F_CPU0_SA_DQ<25>")
	)
	(segment
		(start 387.295644 -261.631176)
		(end 387.166104 -261.760716)
		(width 0.18288)
		(layer "In4.Cu")
		(net "M_F_CPU0_SA_DQ<25>")
	)
	(segment
		(start 419.964616 -285.795212)
		(end 419.059868 -285.795212)
		(width 0.18288)
		(layer "In4.Cu")
		(net "M_F_CPU0_SA_DQ<25>")
	)
	(segment
		(start 382.058164 -261.7343)
		(end 382.050798 -261.738364)
		(width 0.088646)
		(layer "In4.Cu")
		(net "M_F_CPU0_SA_DQ<25>")
	)
	(segment
		(start 414.22447 -277.47849)
		(end 413.965898 -277.47849)
		(width 0.18288)
		(layer "In4.Cu")
		(net "M_F_CPU0_SA_DQ<25>")
	)
	(segment
		(start 414.856422 -278.369014)
		(end 414.714944 -278.227536)
		(width 0.18288)
		(layer "In4.Cu")
		(net "M_F_CPU0_SA_DQ<25>")
	)
	(segment
		(start 416.499548 -283.894276)
		(end 416.240976 -283.894276)
		(width 0.18288)
		(layer "In4.Cu")
		(net "M_F_CPU0_SA_DQ<25>")
	)
	(segment
		(start 381.122936 -261.731506)
		(end 381.118364 -261.7343)
		(width 0.088646)
		(layer "In4.Cu")
		(net "M_F_CPU0_SA_DQ<25>")
	)
	(segment
		(start 407.520902 -274.835366)
		(end 406.866598 -274.181062)
		(width 0.18288)
		(layer "In4.Cu")
		(net "M_F_CPU0_SA_DQ<25>")
	)
	(segment
		(start 387.166104 -261.760716)
		(end 386.808472 -261.760716)
		(width 0.18288)
		(layer "In4.Cu")
		(net "M_F_CPU0_SA_DQ<25>")
	)
	(segment
		(start 386.218176 -261.760716)
		(end 386.19176 -261.7343)
		(width 0.088646)
		(layer "In4.Cu")
		(net "M_F_CPU0_SA_DQ<25>")
	)
	(segment
		(start 415.016442 -280.267918)
		(end 414.856422 -280.107898)
		(width 0.18288)
		(layer "In4.Cu")
		(net "M_F_CPU0_SA_DQ<25>")
	)
	(segment
		(start 415.054796 -277.629112)
		(end 415.054796 -277.37054)
		(width 0.18288)
		(layer "In4.Cu")
		(net "M_F_CPU0_SA_DQ<25>")
	)
	(segment
		(start 410.214064 -275.240496)
		(end 409.808934 -274.835366)
		(width 0.18288)
		(layer "In4.Cu")
		(net "M_F_CPU0_SA_DQ<25>")
	)
	(segment
		(start 419.059868 -285.795212)
		(end 416.958526 -283.69387)
		(width 0.18288)
		(layer "In4.Cu")
		(net "M_F_CPU0_SA_DQ<25>")
	)
	(segment
		(start 406.866598 -274.181062)
		(end 406.866598 -273.454876)
		(width 0.18288)
		(layer "In4.Cu")
		(net "M_F_CPU0_SA_DQ<25>")
	)
	(segment
		(start 416.20948 -283.203396)
		(end 416.20948 -282.944824)
		(width 0.18288)
		(layer "In4.Cu")
		(net "M_F_CPU0_SA_DQ<25>")
	)
	(segment
		(start 383.37236 -261.7343)
		(end 383.361184 -261.72795)
		(width 0.088646)
		(layer "In4.Cu")
		(net "M_F_CPU0_SA_DQ<25>")
	)
	(segment
		(start 415.016442 -280.935938)
		(end 415.016442 -280.267918)
		(width 0.18288)
		(layer "In4.Cu")
		(net "M_F_CPU0_SA_DQ<25>")
	)
	(segment
		(start 405.071072 -273.068796)
		(end 395.991588 -263.989312)
		(width 0.18288)
		(layer "In4.Cu")
		(net "M_F_CPU0_SA_DQ<25>")
	)
	(segment
		(start 380.178564 -261.7343)
		(end 380.171198 -261.738364)
		(width 0.088646)
		(layer "In4.Cu")
		(net "M_F_CPU0_SA_DQ<25>")
	)
	(segment
		(start 415.808922 -282.544266)
		(end 415.402014 -282.544266)
		(width 0.18288)
		(layer "In4.Cu")
		(net "M_F_CPU0_SA_DQ<25>")
	)
	(segment
		(start 379.238764 -261.7343)
		(end 379.231398 -261.738364)
		(width 0.088646)
		(layer "In4.Cu")
		(net "M_F_CPU0_SA_DQ<25>")
	)
	(segment
		(start 412.349696 -276.966426)
		(end 412.164276 -276.781006)
		(width 0.18288)
		(layer "In4.Cu")
		(net "M_F_CPU0_SA_DQ<25>")
	)
	(segment
		(start 389.002524 -261.631176)
		(end 387.295644 -261.631176)
		(width 0.18288)
		(layer "In4.Cu")
		(net "M_F_CPU0_SA_DQ<25>")
	)
	(segment
		(start 406.866598 -273.454876)
		(end 406.680416 -273.268694)
		(width 0.18288)
		(layer "In4.Cu")
		(net "M_F_CPU0_SA_DQ<25>")
	)
	(segment
		(start 410.9593 -274.87372)
		(end 410.592524 -275.240496)
		(width 0.18288)
		(layer "In4.Cu")
		(net "M_F_CPU0_SA_DQ<25>")
	)
	(segment
		(start 414.714944 -277.968964)
		(end 415.054796 -277.629112)
		(width 0.18288)
		(layer "In4.Cu")
		(net "M_F_CPU0_SA_DQ<25>")
	)
	(arc
		(start 383.93751 -261.7343)
		(mid 383.663251 -261.81017)
		(end 383.386838 -261.742682)
		(width 0.088646)
		(layer "In4.Cu")
		(net "M_F_CPU0_SA_DQ<25>")
	)
	(arc
		(start 379.231398 -261.738364)
		(mid 378.951966 -261.809927)
		(end 378.673614 -261.7343)
		(width 0.088646)
		(layer "In4.Cu")
		(net "M_F_CPU0_SA_DQ<25>")
	)
	(arc
		(start 381.493014 -261.7343)
		(mid 381.30835 -261.68404)
		(end 381.122936 -261.731506)
		(width 0.088646)
		(layer "In4.Cu")
		(net "M_F_CPU0_SA_DQ<25>")
	)
	(arc
		(start 378.593604 -261.688072)
		(mid 378.290428 -261.48535)
		(end 378.016262 -261.244842)
		(width 0.088646)
		(layer "In4.Cu")
		(net "M_F_CPU0_SA_DQ<25>")
	)
	(arc
		(start 383.361184 -261.72795)
		(mid 383.178768 -261.684201)
		(end 382.997964 -261.7343)
		(width 0.088646)
		(layer "In4.Cu")
		(net "M_F_CPU0_SA_DQ<25>")
	)
	(arc
		(start 384.87731 -261.7343)
		(mid 384.600751 -261.810043)
		(end 384.322574 -261.740396)
		(width 0.088646)
		(layer "In4.Cu")
		(net "M_F_CPU0_SA_DQ<25>")
	)
	(arc
		(start 382.432814 -261.7343)
		(mid 382.24815 -261.68404)
		(end 382.062736 -261.731506)
		(width 0.088646)
		(layer "In4.Cu")
		(net "M_F_CPU0_SA_DQ<25>")
	)
	(arc
		(start 380.553214 -261.7343)
		(mid 380.36855 -261.68404)
		(end 380.183136 -261.731506)
		(width 0.088646)
		(layer "In4.Cu")
		(net "M_F_CPU0_SA_DQ<25>")
	)
	(arc
		(start 380.171198 -261.738364)
		(mid 379.891766 -261.809927)
		(end 379.613414 -261.7343)
		(width 0.088646)
		(layer "In4.Cu")
		(net "M_F_CPU0_SA_DQ<25>")
	)
	(arc
		(start 382.990598 -261.738364)
		(mid 382.711166 -261.809927)
		(end 382.432814 -261.7343)
		(width 0.088646)
		(layer "In4.Cu")
		(net "M_F_CPU0_SA_DQ<25>")
	)
	(arc
		(start 385.251706 -261.7343)
		(mid 385.064508 -261.684157)
		(end 384.87731 -261.7343)
		(width 0.088646)
		(layer "In4.Cu")
		(net "M_F_CPU0_SA_DQ<25>")
	)
	(arc
		(start 385.81711 -261.7343)
		(mid 385.534408 -261.810076)
		(end 385.251706 -261.7343)
		(width 0.088646)
		(layer "In4.Cu")
		(net "M_F_CPU0_SA_DQ<25>")
	)
	(arc
		(start 384.31216 -261.7343)
		(mid 384.124962 -261.684157)
		(end 383.937764 -261.7343)
		(width 0.088646)
		(layer "In4.Cu")
		(net "M_F_CPU0_SA_DQ<25>")
	)
	(arc
		(start 386.19176 -261.7343)
		(mid 386.004562 -261.684157)
		(end 385.817364 -261.7343)
		(width 0.088646)
		(layer "In4.Cu")
		(net "M_F_CPU0_SA_DQ<25>")
	)
	(arc
		(start 379.613414 -261.7343)
		(mid 379.42875 -261.68404)
		(end 379.243336 -261.731506)
		(width 0.088646)
		(layer "In4.Cu")
		(net "M_F_CPU0_SA_DQ<25>")
	)
	(arc
		(start 381.110998 -261.738364)
		(mid 380.831566 -261.809927)
		(end 380.553214 -261.7343)
		(width 0.088646)
		(layer "In4.Cu")
		(net "M_F_CPU0_SA_DQ<25>")
	)
	(arc
		(start 382.050798 -261.738364)
		(mid 381.771366 -261.809927)
		(end 381.493014 -261.7343)
		(width 0.088646)
		(layer "In4.Cu")
		(net "M_F_CPU0_SA_DQ<25>")
	)
	(segment
		(start 424.73626 -287.84169)
		(end 424.391582 -287.84169)
		(width 0.20066)
		(layer "F.Cu")
		(net "M_F_CPU0_SA_DQ<24>")
	)
	(segment
		(start 424.273472 -288.327338)
		(end 424.085512 -288.515298)
		(width 0.20066)
		(layer "F.Cu")
		(net "M_F_CPU0_SA_DQ<24>")
	)
	(segment
		(start 423.361612 -288.266632)
		(end 421.840914 -288.266632)
		(width 0.20066)
		(layer "F.Cu")
		(net "M_F_CPU0_SA_DQ<24>")
	)
	(segment
		(start 429.38446 -288.266886)
		(end 427.792896 -288.266886)
		(width 0.20066)
		(layer "F.Cu")
		(net "M_F_CPU0_SA_DQ<24>")
	)
	(segment
		(start 423.610278 -288.515298)
		(end 423.361612 -288.266632)
		(width 0.20066)
		(layer "F.Cu")
		(net "M_F_CPU0_SA_DQ<24>")
	)
	(segment
		(start 426.951394 -287.83534)
		(end 426.945044 -287.84169)
		(width 0.1016)
		(layer "F.Cu")
		(net "M_F_CPU0_SA_DQ<24>")
	)
	(segment
		(start 424.273472 -287.9598)
		(end 424.273472 -288.327338)
		(width 0.20066)
		(layer "F.Cu")
		(net "M_F_CPU0_SA_DQ<24>")
	)
	(segment
		(start 429.384714 -288.266632)
		(end 429.38446 -288.266886)
		(width 0.20066)
		(layer "F.Cu")
		(net "M_F_CPU0_SA_DQ<24>")
	)
	(segment
		(start 424.391582 -287.84169)
		(end 424.273472 -287.9598)
		(width 0.20066)
		(layer "F.Cu")
		(net "M_F_CPU0_SA_DQ<24>")
	)
	(segment
		(start 378.486162 -261.522718)
		(end 378.486162 -262.058404)
		(width 0.20066)
		(layer "F.Cu")
		(net "M_F_CPU0_SA_DQ<24>")
	)
	(segment
		(start 427.36135 -287.83534)
		(end 426.951394 -287.83534)
		(width 0.20066)
		(layer "F.Cu")
		(net "M_F_CPU0_SA_DQ<24>")
	)
	(segment
		(start 424.78325 -287.84169)
		(end 424.73626 -287.84169)
		(width 0.101854)
		(layer "F.Cu")
		(net "M_F_CPU0_SA_DQ<24>")
	)
	(segment
		(start 421.840914 -288.266632)
		(end 420.736014 -288.266632)
		(width 0.20066)
		(layer "F.Cu")
		(net "M_F_CPU0_SA_DQ<24>")
	)
	(segment
		(start 426.945044 -287.84169)
		(end 424.78325 -287.84169)
		(width 0.1016)
		(layer "F.Cu")
		(net "M_F_CPU0_SA_DQ<24>")
	)
	(segment
		(start 424.085512 -288.515298)
		(end 423.610278 -288.515298)
		(width 0.20066)
		(layer "F.Cu")
		(net "M_F_CPU0_SA_DQ<24>")
	)
	(segment
		(start 427.792896 -288.266886)
		(end 427.36135 -287.83534)
		(width 0.20066)
		(layer "F.Cu")
		(net "M_F_CPU0_SA_DQ<24>")
	)
	(segment
		(start 378.486162 -262.058404)
		(end 378.486416 -262.058658)
		(width 0.20066)
		(layer "F.Cu")
		(net "M_F_CPU0_SA_DQ<24>")
	)
	(segment
		(start 413.092138 -278.769572)
		(end 412.833566 -278.769572)
		(width 0.18288)
		(layer "In4.Cu")
		(net "M_F_CPU0_SA_DQ<24>")
	)
	(segment
		(start 411.676596 -278.481028)
		(end 411.082744 -277.887176)
		(width 0.18288)
		(layer "In4.Cu")
		(net "M_F_CPU0_SA_DQ<24>")
	)
	(segment
		(start 407.230072 -276.641814)
		(end 406.902412 -276.641814)
		(width 0.18288)
		(layer "In4.Cu")
		(net "M_F_CPU0_SA_DQ<24>")
	)
	(segment
		(start 395.5161 -264.984992)
		(end 393.148312 -264.984992)
		(width 0.18288)
		(layer "In4.Cu")
		(net "M_F_CPU0_SA_DQ<24>")
	)
	(segment
		(start 413.441134 -280.84907)
		(end 413.441134 -280.36901)
		(width 0.18288)
		(layer "In4.Cu")
		(net "M_F_CPU0_SA_DQ<24>")
	)
	(segment
		(start 409.8671 -278.121872)
		(end 409.8671 -277.8633)
		(width 0.18288)
		(layer "In4.Cu")
		(net "M_F_CPU0_SA_DQ<24>")
	)
	(segment
		(start 387.77799 -262.629142)
		(end 387.75894 -262.610092)
		(width 0.088646)
		(layer "In4.Cu")
		(net "M_F_CPU0_SA_DQ<24>")
	)
	(segment
		(start 416.080702 -285.198566)
		(end 413.437832 -282.555696)
		(width 0.18288)
		(layer "In4.Cu")
		(net "M_F_CPU0_SA_DQ<24>")
	)
	(segment
		(start 406.719532 -276.016466)
		(end 406.536652 -275.833586)
		(width 0.18288)
		(layer "In4.Cu")
		(net "M_F_CPU0_SA_DQ<24>")
	)
	(segment
		(start 381.028956 -262.551418)
		(end 381.017272 -262.544814)
		(width 0.088646)
		(layer "In4.Cu")
		(net "M_F_CPU0_SA_DQ<24>")
	)
	(segment
		(start 407.412952 -276.458934)
		(end 407.230072 -276.641814)
		(width 0.18288)
		(layer "In4.Cu")
		(net "M_F_CPU0_SA_DQ<24>")
	)
	(segment
		(start 407.412952 -276.016466)
		(end 407.412952 -276.458934)
		(width 0.18288)
		(layer "In4.Cu")
		(net "M_F_CPU0_SA_DQ<24>")
	)
	(segment
		(start 413.582612 -279.260046)
		(end 413.789368 -279.05329)
		(width 0.18288)
		(layer "In4.Cu")
		(net "M_F_CPU0_SA_DQ<24>")
	)
	(segment
		(start 419.110414 -287.59912)
		(end 417.34232 -285.831026)
		(width 0.18288)
		(layer "In4.Cu")
		(net "M_F_CPU0_SA_DQ<24>")
	)
	(segment
		(start 410.099002 -278.353774)
		(end 409.8671 -278.121872)
		(width 0.18288)
		(layer "In4.Cu")
		(net "M_F_CPU0_SA_DQ<24>")
	)
	(segment
		(start 413.781494 -281.716226)
		(end 413.781494 -281.18943)
		(width 0.18288)
		(layer "In4.Cu")
		(net "M_F_CPU0_SA_DQ<24>")
	)
	(segment
		(start 413.789368 -278.794718)
		(end 413.557466 -278.562816)
		(width 0.18288)
		(layer "In4.Cu")
		(net "M_F_CPU0_SA_DQ<24>")
	)
	(segment
		(start 391.265918 -264.205466)
		(end 389.784082 -262.72363)
		(width 0.18288)
		(layer "In4.Cu")
		(net "M_F_CPU0_SA_DQ<24>")
	)
	(segment
		(start 410.333698 -277.13813)
		(end 409.773374 -276.577806)
		(width 0.18288)
		(layer "In4.Cu")
		(net "M_F_CPU0_SA_DQ<24>")
	)
	(segment
		(start 410.333698 -277.396702)
		(end 410.333698 -277.13813)
		(width 0.18288)
		(layer "In4.Cu")
		(net "M_F_CPU0_SA_DQ<24>")
	)
	(segment
		(start 409.773374 -276.577806)
		(end 409.163774 -276.577806)
		(width 0.18288)
		(layer "In4.Cu")
		(net "M_F_CPU0_SA_DQ<24>")
	)
	(segment
		(start 413.582612 -279.518618)
		(end 413.582612 -279.260046)
		(width 0.18288)
		(layer "In4.Cu")
		(net "M_F_CPU0_SA_DQ<24>")
	)
	(segment
		(start 386.676646 -262.556752)
		(end 386.661914 -262.548116)
		(width 0.088646)
		(layer "In4.Cu")
		(net "M_F_CPU0_SA_DQ<24>")
	)
	(segment
		(start 393.148312 -264.984992)
		(end 391.265918 -264.205466)
		(width 0.18288)
		(layer "In4.Cu")
		(net "M_F_CPU0_SA_DQ<24>")
	)
	(segment
		(start 387.616446 -262.556752)
		(end 387.601714 -262.548116)
		(width 0.088646)
		(layer "In4.Cu")
		(net "M_F_CPU0_SA_DQ<24>")
	)
	(segment
		(start 409.8671 -277.8633)
		(end 410.333698 -277.396702)
		(width 0.18288)
		(layer "In4.Cu")
		(net "M_F_CPU0_SA_DQ<24>")
	)
	(segment
		(start 406.902412 -276.641814)
		(end 406.719532 -276.458934)
		(width 0.18288)
		(layer "In4.Cu")
		(net "M_F_CPU0_SA_DQ<24>")
	)
	(segment
		(start 413.437832 -282.059888)
		(end 413.781494 -281.716226)
		(width 0.18288)
		(layer "In4.Cu")
		(net "M_F_CPU0_SA_DQ<24>")
	)
	(segment
		(start 406.719532 -276.458934)
		(end 406.719532 -276.016466)
		(width 0.18288)
		(layer "In4.Cu")
		(net "M_F_CPU0_SA_DQ<24>")
	)
	(segment
		(start 416.934142 -285.831026)
		(end 416.301682 -285.198566)
		(width 0.18288)
		(layer "In4.Cu")
		(net "M_F_CPU0_SA_DQ<24>")
	)
	(segment
		(start 406.364694 -275.833586)
		(end 395.5161 -264.984992)
		(width 0.18288)
		(layer "In4.Cu")
		(net "M_F_CPU0_SA_DQ<24>")
	)
	(segment
		(start 389.435848 -262.579358)
		(end 388.434072 -262.579358)
		(width 0.18288)
		(layer "In4.Cu")
		(net "M_F_CPU0_SA_DQ<24>")
	)
	(segment
		(start 388.204964 -262.629142)
		(end 387.77799 -262.629142)
		(width 0.088646)
		(layer "In4.Cu")
		(net "M_F_CPU0_SA_DQ<24>")
	)
	(segment
		(start 382.907286 -262.550656)
		(end 382.902714 -262.548116)
		(width 0.088646)
		(layer "In4.Cu")
		(net "M_F_CPU0_SA_DQ<24>")
	)
	(segment
		(start 413.789368 -279.05329)
		(end 413.789368 -278.794718)
		(width 0.18288)
		(layer "In4.Cu")
		(net "M_F_CPU0_SA_DQ<24>")
	)
	(segment
		(start 379.143514 -262.548116)
		(end 379.141482 -262.546846)
		(width 0.088646)
		(layer "In4.Cu")
		(net "M_F_CPU0_SA_DQ<24>")
	)
	(segment
		(start 413.298894 -278.562816)
		(end 413.092138 -278.769572)
		(width 0.18288)
		(layer "In4.Cu")
		(net "M_F_CPU0_SA_DQ<24>")
	)
	(segment
		(start 379.149356 -262.551418)
		(end 379.143514 -262.548116)
		(width 0.088646)
		(layer "In4.Cu")
		(net "M_F_CPU0_SA_DQ<24>")
	)
	(segment
		(start 412.833566 -278.769572)
		(end 412.545022 -278.481028)
		(width 0.18288)
		(layer "In4.Cu")
		(net "M_F_CPU0_SA_DQ<24>")
	)
	(segment
		(start 420.261542 -287.59912)
		(end 419.110414 -287.59912)
		(width 0.18288)
		(layer "In4.Cu")
		(net "M_F_CPU0_SA_DQ<24>")
	)
	(segment
		(start 413.441134 -280.36901)
		(end 413.695134 -280.11501)
		(width 0.18288)
		(layer "In4.Cu")
		(net "M_F_CPU0_SA_DQ<24>")
	)
	(segment
		(start 417.34232 -285.831026)
		(end 416.934142 -285.831026)
		(width 0.18288)
		(layer "In4.Cu")
		(net "M_F_CPU0_SA_DQ<24>")
	)
	(segment
		(start 410.824172 -277.887176)
		(end 410.357574 -278.353774)
		(width 0.18288)
		(layer "In4.Cu")
		(net "M_F_CPU0_SA_DQ<24>")
	)
	(segment
		(start 410.357574 -278.353774)
		(end 410.099002 -278.353774)
		(width 0.18288)
		(layer "In4.Cu")
		(net "M_F_CPU0_SA_DQ<24>")
	)
	(segment
		(start 413.437832 -282.555696)
		(end 413.437832 -282.059888)
		(width 0.18288)
		(layer "In4.Cu")
		(net "M_F_CPU0_SA_DQ<24>")
	)
	(segment
		(start 382.902714 -262.548116)
		(end 382.896872 -262.544814)
		(width 0.088646)
		(layer "In4.Cu")
		(net "M_F_CPU0_SA_DQ<24>")
	)
	(segment
		(start 389.784082 -262.72363)
		(end 389.435848 -262.579358)
		(width 0.18288)
		(layer "In4.Cu")
		(net "M_F_CPU0_SA_DQ<24>")
	)
	(segment
		(start 420.736014 -288.266632)
		(end 420.736014 -288.073592)
		(width 0.18288)
		(layer "In4.Cu")
		(net "M_F_CPU0_SA_DQ<24>")
	)
	(segment
		(start 416.301682 -285.198566)
		(end 416.080702 -285.198566)
		(width 0.18288)
		(layer "In4.Cu")
		(net "M_F_CPU0_SA_DQ<24>")
	)
	(segment
		(start 412.545022 -278.481028)
		(end 411.676596 -278.481028)
		(width 0.18288)
		(layer "In4.Cu")
		(net "M_F_CPU0_SA_DQ<24>")
	)
	(segment
		(start 407.595832 -275.833586)
		(end 407.412952 -276.016466)
		(width 0.18288)
		(layer "In4.Cu")
		(net "M_F_CPU0_SA_DQ<24>")
	)
	(segment
		(start 385.732274 -262.554212)
		(end 385.72186 -262.548116)
		(width 0.088646)
		(layer "In4.Cu")
		(net "M_F_CPU0_SA_DQ<24>")
	)
	(segment
		(start 380.089156 -262.551418)
		(end 380.077472 -262.544814)
		(width 0.088646)
		(layer "In4.Cu")
		(net "M_F_CPU0_SA_DQ<24>")
	)
	(segment
		(start 408.419554 -275.833586)
		(end 407.595832 -275.833586)
		(width 0.18288)
		(layer "In4.Cu")
		(net "M_F_CPU0_SA_DQ<24>")
	)
	(segment
		(start 409.163774 -276.577806)
		(end 408.419554 -275.833586)
		(width 0.18288)
		(layer "In4.Cu")
		(net "M_F_CPU0_SA_DQ<24>")
	)
	(segment
		(start 411.082744 -277.887176)
		(end 410.824172 -277.887176)
		(width 0.18288)
		(layer "In4.Cu")
		(net "M_F_CPU0_SA_DQ<24>")
	)
	(segment
		(start 413.695134 -280.11501)
		(end 413.695134 -279.63114)
		(width 0.18288)
		(layer "In4.Cu")
		(net "M_F_CPU0_SA_DQ<24>")
	)
	(segment
		(start 406.536652 -275.833586)
		(end 406.364694 -275.833586)
		(width 0.18288)
		(layer "In4.Cu")
		(net "M_F_CPU0_SA_DQ<24>")
	)
	(segment
		(start 420.736014 -288.073592)
		(end 420.261542 -287.59912)
		(width 0.18288)
		(layer "In4.Cu")
		(net "M_F_CPU0_SA_DQ<24>")
	)
	(segment
		(start 413.781494 -281.18943)
		(end 413.441134 -280.84907)
		(width 0.18288)
		(layer "In4.Cu")
		(net "M_F_CPU0_SA_DQ<24>")
	)
	(segment
		(start 381.968756 -262.551418)
		(end 381.957072 -262.544814)
		(width 0.088646)
		(layer "In4.Cu")
		(net "M_F_CPU0_SA_DQ<24>")
	)
	(segment
		(start 388.254748 -262.579358)
		(end 388.204964 -262.629142)
		(width 0.088646)
		(layer "In4.Cu")
		(net "M_F_CPU0_SA_DQ<24>")
	)
	(segment
		(start 413.557466 -278.562816)
		(end 413.298894 -278.562816)
		(width 0.18288)
		(layer "In4.Cu")
		(net "M_F_CPU0_SA_DQ<24>")
	)
	(segment
		(start 388.434072 -262.579358)
		(end 388.254748 -262.579358)
		(width 0.088646)
		(layer "In4.Cu")
		(net "M_F_CPU0_SA_DQ<24>")
	)
	(segment
		(start 413.695134 -279.63114)
		(end 413.582612 -279.518618)
		(width 0.18288)
		(layer "In4.Cu")
		(net "M_F_CPU0_SA_DQ<24>")
	)
	(segment
		(start 383.84226 -262.548116)
		(end 383.842514 -262.548116)
		(width 0.088646)
		(layer "In4.Cu")
		(net "M_F_CPU0_SA_DQ<24>")
	)
	(arc
		(start 381.957072 -262.544814)
		(mid 381.772217 -262.497864)
		(end 381.588264 -262.548116)
		(width 0.088646)
		(layer "In4.Cu")
		(net "M_F_CPU0_SA_DQ<24>")
	)
	(arc
		(start 386.287518 -262.548116)
		(mid 386.010705 -262.623986)
		(end 385.732274 -262.554212)
		(width 0.088646)
		(layer "In4.Cu")
		(net "M_F_CPU0_SA_DQ<24>")
	)
	(arc
		(start 382.896872 -262.544814)
		(mid 382.712017 -262.497864)
		(end 382.528064 -262.548116)
		(width 0.088646)
		(layer "In4.Cu")
		(net "M_F_CPU0_SA_DQ<24>")
	)
	(arc
		(start 387.601714 -262.548116)
		(mid 387.414516 -262.497973)
		(end 387.227318 -262.548116)
		(width 0.088646)
		(layer "In4.Cu")
		(net "M_F_CPU0_SA_DQ<24>")
	)
	(arc
		(start 387.75894 -262.610092)
		(mid 387.685893 -262.588233)
		(end 387.616446 -262.556752)
		(width 0.088646)
		(layer "In4.Cu")
		(net "M_F_CPU0_SA_DQ<24>")
	)
	(arc
		(start 384.78206 -262.548116)
		(mid 384.594862 -262.497973)
		(end 384.407664 -262.548116)
		(width 0.088646)
		(layer "In4.Cu")
		(net "M_F_CPU0_SA_DQ<24>")
	)
	(arc
		(start 383.842514 -262.548116)
		(mid 383.655206 -262.497973)
		(end 383.467864 -262.548116)
		(width 0.088646)
		(layer "In4.Cu")
		(net "M_F_CPU0_SA_DQ<24>")
	)
	(arc
		(start 384.407664 -262.548116)
		(mid 384.124962 -262.623892)
		(end 383.84226 -262.548116)
		(width 0.088646)
		(layer "In4.Cu")
		(net "M_F_CPU0_SA_DQ<24>")
	)
	(arc
		(start 382.528064 -262.548116)
		(mid 382.248861 -262.623756)
		(end 381.968756 -262.551418)
		(width 0.088646)
		(layer "In4.Cu")
		(net "M_F_CPU0_SA_DQ<24>")
	)
	(arc
		(start 385.72186 -262.548116)
		(mid 385.534662 -262.497973)
		(end 385.347464 -262.548116)
		(width 0.088646)
		(layer "In4.Cu")
		(net "M_F_CPU0_SA_DQ<24>")
	)
	(arc
		(start 380.648464 -262.548116)
		(mid 380.369261 -262.623756)
		(end 380.089156 -262.551418)
		(width 0.088646)
		(layer "In4.Cu")
		(net "M_F_CPU0_SA_DQ<24>")
	)
	(arc
		(start 385.347464 -262.548116)
		(mid 385.064762 -262.623892)
		(end 384.78206 -262.548116)
		(width 0.088646)
		(layer "In4.Cu")
		(net "M_F_CPU0_SA_DQ<24>")
	)
	(arc
		(start 383.467864 -262.548116)
		(mid 383.18792 -262.62376)
		(end 382.907286 -262.550656)
		(width 0.088646)
		(layer "In4.Cu")
		(net "M_F_CPU0_SA_DQ<24>")
	)
	(arc
		(start 381.588264 -262.548116)
		(mid 381.309061 -262.623756)
		(end 381.028956 -262.551418)
		(width 0.088646)
		(layer "In4.Cu")
		(net "M_F_CPU0_SA_DQ<24>")
	)
	(arc
		(start 387.227318 -262.548116)
		(mid 386.953119 -262.623951)
		(end 386.676646 -262.556752)
		(width 0.088646)
		(layer "In4.Cu")
		(net "M_F_CPU0_SA_DQ<24>")
	)
	(arc
		(start 386.661914 -262.548116)
		(mid 386.474716 -262.497973)
		(end 386.287518 -262.548116)
		(width 0.088646)
		(layer "In4.Cu")
		(net "M_F_CPU0_SA_DQ<24>")
	)
	(arc
		(start 380.077472 -262.544814)
		(mid 379.892617 -262.497864)
		(end 379.708664 -262.548116)
		(width 0.088646)
		(layer "In4.Cu")
		(net "M_F_CPU0_SA_DQ<24>")
	)
	(arc
		(start 379.708664 -262.548116)
		(mid 379.429461 -262.623756)
		(end 379.149356 -262.551418)
		(width 0.088646)
		(layer "In4.Cu")
		(net "M_F_CPU0_SA_DQ<24>")
	)
	(arc
		(start 379.141482 -262.546846)
		(mid 378.80396 -262.316156)
		(end 378.486416 -262.058658)
		(width 0.088646)
		(layer "In4.Cu")
		(net "M_F_CPU0_SA_DQ<24>")
	)
	(arc
		(start 381.017272 -262.544814)
		(mid 380.832417 -262.497864)
		(end 380.648464 -262.548116)
		(width 0.088646)
		(layer "In4.Cu")
		(net "M_F_CPU0_SA_DQ<24>")
	)
	(segment
		(start 425.940982 -289.11677)
		(end 427.639226 -289.11677)
		(width 0.20066)
		(layer "F.Cu")
		(net "M_F_CPU0_SA_DQ<23>")
	)
	(segment
		(start 428.367952 -289.548824)
		(end 428.375064 -289.541712)
		(width 0.1016)
		(layer "F.Cu")
		(net "M_F_CPU0_SA_DQ<23>")
	)
	(segment
		(start 424.836082 -289.11677)
		(end 425.940982 -289.11677)
		(width 0.20066)
		(layer "F.Cu")
		(net "M_F_CPU0_SA_DQ<23>")
	)
	(segment
		(start 431.898552 -288.864802)
		(end 432.15052 -289.11677)
		(width 0.20066)
		(layer "F.Cu")
		(net "M_F_CPU0_SA_DQ<23>")
	)
	(segment
		(start 431.076354 -289.553904)
		(end 431.280316 -289.349942)
		(width 0.20066)
		(layer "F.Cu")
		(net "M_F_CPU0_SA_DQ<23>")
	)
	(segment
		(start 427.639226 -289.11677)
		(end 428.07128 -289.548824)
		(width 0.20066)
		(layer "F.Cu")
		(net "M_F_CPU0_SA_DQ<23>")
	)
	(segment
		(start 382.715516 -265.592306)
		(end 382.715516 -266.127992)
		(width 0.20066)
		(layer "F.Cu")
		(net "M_F_CPU0_SA_DQ<23>")
	)
	(segment
		(start 428.07128 -289.548824)
		(end 428.363126 -289.548824)
		(width 0.20066)
		(layer "F.Cu")
		(net "M_F_CPU0_SA_DQ<23>")
	)
	(segment
		(start 430.395126 -289.553904)
		(end 431.076354 -289.553904)
		(width 0.20066)
		(layer "F.Cu")
		(net "M_F_CPU0_SA_DQ<23>")
	)
	(segment
		(start 431.514504 -288.864802)
		(end 431.898552 -288.864802)
		(width 0.20066)
		(layer "F.Cu")
		(net "M_F_CPU0_SA_DQ<23>")
	)
	(segment
		(start 431.280316 -289.09899)
		(end 431.514504 -288.864802)
		(width 0.20066)
		(layer "F.Cu")
		(net "M_F_CPU0_SA_DQ<23>")
	)
	(segment
		(start 431.280316 -289.349942)
		(end 431.280316 -289.09899)
		(width 0.20066)
		(layer "F.Cu")
		(net "M_F_CPU0_SA_DQ<23>")
	)
	(segment
		(start 432.15052 -289.11677)
		(end 433.484782 -289.11677)
		(width 0.20066)
		(layer "F.Cu")
		(net "M_F_CPU0_SA_DQ<23>")
	)
	(segment
		(start 428.375064 -289.541712)
		(end 430.382934 -289.541712)
		(width 0.1016)
		(layer "F.Cu")
		(net "M_F_CPU0_SA_DQ<23>")
	)
	(segment
		(start 430.382934 -289.541712)
		(end 430.395126 -289.553904)
		(width 0.1016)
		(layer "F.Cu")
		(net "M_F_CPU0_SA_DQ<23>")
	)
	(segment
		(start 428.363126 -289.548824)
		(end 428.367952 -289.548824)
		(width 0.101854)
		(layer "F.Cu")
		(net "M_F_CPU0_SA_DQ<23>")
	)
	(segment
		(start 382.715516 -266.127992)
		(end 382.715262 -266.128246)
		(width 0.20066)
		(layer "F.Cu")
		(net "M_F_CPU0_SA_DQ<23>")
	)
	(segment
		(start 382.715008 -266.127992)
		(end 382.715262 -266.128246)
		(width 0.088646)
		(layer "In2.Cu")
		(net "M_F_CPU0_SA_DQ<23>")
	)
	(segment
		(start 424.055286 -284.43809)
		(end 424.055286 -283.94025)
		(width 0.18288)
		(layer "In2.Cu")
		(net "M_F_CPU0_SA_DQ<23>")
	)
	(segment
		(start 387.717538 -265.650218)
		(end 387.697218 -265.638534)
		(width 0.088646)
		(layer "In2.Cu")
		(net "M_F_CPU0_SA_DQ<23>")
	)
	(segment
		(start 424.055286 -285.84525)
		(end 423.651426 -285.44139)
		(width 0.18288)
		(layer "In2.Cu")
		(net "M_F_CPU0_SA_DQ<23>")
	)
	(segment
		(start 390.899142 -265.99134)
		(end 388.840472 -265.99134)
		(width 0.18288)
		(layer "In2.Cu")
		(net "M_F_CPU0_SA_DQ<23>")
	)
	(segment
		(start 420.09441 -283.591762)
		(end 419.056566 -282.553918)
		(width 0.18288)
		(layer "In2.Cu")
		(net "M_F_CPU0_SA_DQ<23>")
	)
	(segment
		(start 405.989282 -278.454104)
		(end 405.666702 -278.776684)
		(width 0.18288)
		(layer "In2.Cu")
		(net "M_F_CPU0_SA_DQ<23>")
	)
	(segment
		(start 418.15893 -282.553918)
		(end 417.473892 -281.86888)
		(width 0.18288)
		(layer "In2.Cu")
		(net "M_F_CPU0_SA_DQ<23>")
	)
	(segment
		(start 383.387346 -265.629898)
		(end 383.372614 -265.638534)
		(width 0.088646)
		(layer "In2.Cu")
		(net "M_F_CPU0_SA_DQ<23>")
	)
	(segment
		(start 421.249094 -283.591762)
		(end 420.09441 -283.591762)
		(width 0.18288)
		(layer "In2.Cu")
		(net "M_F_CPU0_SA_DQ<23>")
	)
	(segment
		(start 382.402842 -266.127992)
		(end 382.715008 -266.127992)
		(width 0.088646)
		(layer "In2.Cu")
		(net "M_F_CPU0_SA_DQ<23>")
	)
	(segment
		(start 423.651426 -285.44139)
		(end 423.651426 -284.84195)
		(width 0.18288)
		(layer "In2.Cu")
		(net "M_F_CPU0_SA_DQ<23>")
	)
	(segment
		(start 417.473892 -281.86888)
		(end 416.076892 -281.86888)
		(width 0.18288)
		(layer "In2.Cu")
		(net "M_F_CPU0_SA_DQ<23>")
	)
	(segment
		(start 405.666702 -278.776684)
		(end 405.195278 -278.776684)
		(width 0.18288)
		(layer "In2.Cu")
		(net "M_F_CPU0_SA_DQ<23>")
	)
	(segment
		(start 422.899586 -283.74721)
		(end 422.618154 -283.465778)
		(width 0.18288)
		(layer "In2.Cu")
		(net "M_F_CPU0_SA_DQ<23>")
	)
	(segment
		(start 422.618154 -283.465778)
		(end 421.375078 -283.465778)
		(width 0.18288)
		(layer "In2.Cu")
		(net "M_F_CPU0_SA_DQ<23>")
	)
	(segment
		(start 412.64332 -280.174192)
		(end 409.11018 -280.174192)
		(width 0.18288)
		(layer "In2.Cu")
		(net "M_F_CPU0_SA_DQ<23>")
	)
	(segment
		(start 388.840472 -265.99134)
		(end 388.643876 -265.99134)
		(width 0.088646)
		(layer "In2.Cu")
		(net "M_F_CPU0_SA_DQ<23>")
	)
	(segment
		(start 413.62376 -281.154632)
		(end 412.64332 -280.174192)
		(width 0.18288)
		(layer "In2.Cu")
		(net "M_F_CPU0_SA_DQ<23>")
	)
	(segment
		(start 384.327146 -265.629898)
		(end 384.312414 -265.638534)
		(width 0.088646)
		(layer "In2.Cu")
		(net "M_F_CPU0_SA_DQ<23>")
	)
	(segment
		(start 416.076892 -281.86888)
		(end 415.963862 -281.98191)
		(width 0.18288)
		(layer "In2.Cu")
		(net "M_F_CPU0_SA_DQ<23>")
	)
	(segment
		(start 407.69159 -278.62022)
		(end 407.525474 -278.454104)
		(width 0.18288)
		(layer "In2.Cu")
		(net "M_F_CPU0_SA_DQ<23>")
	)
	(segment
		(start 424.836082 -289.11677)
		(end 424.248326 -289.11677)
		(width 0.18288)
		(layer "In2.Cu")
		(net "M_F_CPU0_SA_DQ<23>")
	)
	(segment
		(start 423.651426 -284.84195)
		(end 424.055286 -284.43809)
		(width 0.18288)
		(layer "In2.Cu")
		(net "M_F_CPU0_SA_DQ<23>")
	)
	(segment
		(start 421.375078 -283.465778)
		(end 421.249094 -283.591762)
		(width 0.18288)
		(layer "In2.Cu")
		(net "M_F_CPU0_SA_DQ<23>")
	)
	(segment
		(start 401.677124 -275.25853)
		(end 400.682968 -272.858484)
		(width 0.18288)
		(layer "In2.Cu")
		(net "M_F_CPU0_SA_DQ<23>")
	)
	(segment
		(start 397.149574 -269.32509)
		(end 394.854176 -269.32509)
		(width 0.18288)
		(layer "In2.Cu")
		(net "M_F_CPU0_SA_DQ<23>")
	)
	(segment
		(start 387.146546 -265.629898)
		(end 387.131814 -265.638534)
		(width 0.088646)
		(layer "In2.Cu")
		(net "M_F_CPU0_SA_DQ<23>")
	)
	(segment
		(start 383.089912 -266.114022)
		(end 383.089912 -266.130278)
		(width 0.088646)
		(layer "In2.Cu")
		(net "M_F_CPU0_SA_DQ<23>")
	)
	(segment
		(start 415.16554 -281.98191)
		(end 414.338262 -281.154632)
		(width 0.18288)
		(layer "In2.Cu")
		(net "M_F_CPU0_SA_DQ<23>")
	)
	(segment
		(start 424.055286 -288.92373)
		(end 424.055286 -285.84525)
		(width 0.18288)
		(layer "In2.Cu")
		(net "M_F_CPU0_SA_DQ<23>")
	)
	(segment
		(start 419.056566 -282.553918)
		(end 418.15893 -282.553918)
		(width 0.18288)
		(layer "In2.Cu")
		(net "M_F_CPU0_SA_DQ<23>")
	)
	(segment
		(start 407.69159 -279.16251)
		(end 407.69159 -278.62022)
		(width 0.18288)
		(layer "In2.Cu")
		(net "M_F_CPU0_SA_DQ<23>")
	)
	(segment
		(start 424.248326 -289.11677)
		(end 424.055286 -288.92373)
		(width 0.18288)
		(layer "In2.Cu")
		(net "M_F_CPU0_SA_DQ<23>")
	)
	(segment
		(start 386.206746 -265.629898)
		(end 386.192014 -265.638534)
		(width 0.088646)
		(layer "In2.Cu")
		(net "M_F_CPU0_SA_DQ<23>")
	)
	(segment
		(start 408.271472 -279.335484)
		(end 407.864564 -279.335484)
		(width 0.18288)
		(layer "In2.Cu")
		(net "M_F_CPU0_SA_DQ<23>")
	)
	(segment
		(start 409.11018 -280.174192)
		(end 408.271472 -279.335484)
		(width 0.18288)
		(layer "In2.Cu")
		(net "M_F_CPU0_SA_DQ<23>")
	)
	(segment
		(start 405.195278 -278.776684)
		(end 401.677124 -275.25853)
		(width 0.18288)
		(layer "In2.Cu")
		(net "M_F_CPU0_SA_DQ<23>")
	)
	(segment
		(start 388.499858 -265.93165)
		(end 388.486142 -265.917934)
		(width 0.088646)
		(layer "In2.Cu")
		(net "M_F_CPU0_SA_DQ<23>")
	)
	(segment
		(start 414.338262 -281.154632)
		(end 413.62376 -281.154632)
		(width 0.18288)
		(layer "In2.Cu")
		(net "M_F_CPU0_SA_DQ<23>")
	)
	(segment
		(start 391.9601 -266.431014)
		(end 390.899142 -265.99134)
		(width 0.18288)
		(layer "In2.Cu")
		(net "M_F_CPU0_SA_DQ<23>")
	)
	(segment
		(start 400.682968 -272.858484)
		(end 397.149574 -269.32509)
		(width 0.18288)
		(layer "In2.Cu")
		(net "M_F_CPU0_SA_DQ<23>")
	)
	(segment
		(start 424.055286 -283.94025)
		(end 423.862246 -283.74721)
		(width 0.18288)
		(layer "In2.Cu")
		(net "M_F_CPU0_SA_DQ<23>")
	)
	(segment
		(start 394.854176 -269.32509)
		(end 391.9601 -266.431014)
		(width 0.18288)
		(layer "In2.Cu")
		(net "M_F_CPU0_SA_DQ<23>")
	)
	(segment
		(start 423.862246 -283.74721)
		(end 422.899586 -283.74721)
		(width 0.18288)
		(layer "In2.Cu")
		(net "M_F_CPU0_SA_DQ<23>")
	)
	(segment
		(start 385.266946 -265.629898)
		(end 385.252214 -265.638534)
		(width 0.088646)
		(layer "In2.Cu")
		(net "M_F_CPU0_SA_DQ<23>")
	)
	(segment
		(start 415.963862 -281.98191)
		(end 415.16554 -281.98191)
		(width 0.18288)
		(layer "In2.Cu")
		(net "M_F_CPU0_SA_DQ<23>")
	)
	(segment
		(start 407.525474 -278.454104)
		(end 405.989282 -278.454104)
		(width 0.18288)
		(layer "In2.Cu")
		(net "M_F_CPU0_SA_DQ<23>")
	)
	(segment
		(start 382.345184 -266.18565)
		(end 382.402842 -266.127992)
		(width 0.088646)
		(layer "In2.Cu")
		(net "M_F_CPU0_SA_DQ<23>")
	)
	(segment
		(start 407.864564 -279.335484)
		(end 407.69159 -279.16251)
		(width 0.18288)
		(layer "In2.Cu")
		(net "M_F_CPU0_SA_DQ<23>")
	)
	(arc
		(start 384.312414 -265.638534)
		(mid 384.125216 -265.688677)
		(end 383.938018 -265.638534)
		(width 0.088646)
		(layer "In2.Cu")
		(net "M_F_CPU0_SA_DQ<23>")
	)
	(arc
		(start 383.089912 -266.130278)
		(mid 382.743048 -266.50187)
		(end 382.345184 -266.18565)
		(width 0.088646)
		(layer "In2.Cu")
		(net "M_F_CPU0_SA_DQ<23>")
	)
	(arc
		(start 385.817618 -265.638534)
		(mid 385.543389 -265.562609)
		(end 385.266946 -265.629898)
		(width 0.088646)
		(layer "In2.Cu")
		(net "M_F_CPU0_SA_DQ<23>")
	)
	(arc
		(start 383.372614 -265.638534)
		(mid 383.169133 -265.839338)
		(end 383.089912 -266.114022)
		(width 0.088646)
		(layer "In2.Cu")
		(net "M_F_CPU0_SA_DQ<23>")
	)
	(arc
		(start 388.643876 -265.99134)
		(mid 388.56592 -265.975834)
		(end 388.499858 -265.93165)
		(width 0.088646)
		(layer "In2.Cu")
		(net "M_F_CPU0_SA_DQ<23>")
	)
	(arc
		(start 383.938018 -265.638534)
		(mid 383.663789 -265.562609)
		(end 383.387346 -265.629898)
		(width 0.088646)
		(layer "In2.Cu")
		(net "M_F_CPU0_SA_DQ<23>")
	)
	(arc
		(start 386.757418 -265.638534)
		(mid 386.483189 -265.562609)
		(end 386.206746 -265.629898)
		(width 0.088646)
		(layer "In2.Cu")
		(net "M_F_CPU0_SA_DQ<23>")
	)
	(arc
		(start 388.065518 -265.74369)
		(mid 387.885352 -265.71993)
		(end 387.717538 -265.650218)
		(width 0.088646)
		(layer "In2.Cu")
		(net "M_F_CPU0_SA_DQ<23>")
	)
	(arc
		(start 384.877818 -265.638534)
		(mid 384.603589 -265.562609)
		(end 384.327146 -265.629898)
		(width 0.088646)
		(layer "In2.Cu")
		(net "M_F_CPU0_SA_DQ<23>")
	)
	(arc
		(start 385.252214 -265.638534)
		(mid 385.065016 -265.688677)
		(end 384.877818 -265.638534)
		(width 0.088646)
		(layer "In2.Cu")
		(net "M_F_CPU0_SA_DQ<23>")
	)
	(arc
		(start 386.192014 -265.638534)
		(mid 386.004816 -265.688677)
		(end 385.817618 -265.638534)
		(width 0.088646)
		(layer "In2.Cu")
		(net "M_F_CPU0_SA_DQ<23>")
	)
	(arc
		(start 387.131814 -265.638534)
		(mid 386.944616 -265.688677)
		(end 386.757418 -265.638534)
		(width 0.088646)
		(layer "In2.Cu")
		(net "M_F_CPU0_SA_DQ<23>")
	)
	(arc
		(start 388.486142 -265.917934)
		(mid 388.293158 -265.788986)
		(end 388.065518 -265.74369)
		(width 0.088646)
		(layer "In2.Cu")
		(net "M_F_CPU0_SA_DQ<23>")
	)
	(arc
		(start 387.697218 -265.638534)
		(mid 387.422989 -265.562609)
		(end 387.146546 -265.629898)
		(width 0.088646)
		(layer "In2.Cu")
		(net "M_F_CPU0_SA_DQ<23>")
	)
	(segment
		(start 428.367952 -291.248846)
		(end 428.363126 -291.248846)
		(width 0.101854)
		(layer "F.Cu")
		(net "M_F_CPU0_SA_DQ<22>")
	)
	(segment
		(start 431.514504 -290.564824)
		(end 431.280316 -290.799012)
		(width 0.20066)
		(layer "F.Cu")
		(net "M_F_CPU0_SA_DQ<22>")
	)
	(segment
		(start 424.836082 -290.816538)
		(end 424.836336 -290.816792)
		(width 0.20066)
		(layer "F.Cu")
		(net "M_F_CPU0_SA_DQ<22>")
	)
	(segment
		(start 431.076354 -291.253926)
		(end 430.395126 -291.253926)
		(width 0.20066)
		(layer "F.Cu")
		(net "M_F_CPU0_SA_DQ<22>")
	)
	(segment
		(start 431.280316 -290.799012)
		(end 431.280316 -291.049964)
		(width 0.20066)
		(layer "F.Cu")
		(net "M_F_CPU0_SA_DQ<22>")
	)
	(segment
		(start 428.07128 -291.248846)
		(end 427.639226 -290.816792)
		(width 0.20066)
		(layer "F.Cu")
		(net "M_F_CPU0_SA_DQ<22>")
	)
	(segment
		(start 383.185162 -266.405868)
		(end 383.185416 -266.942062)
		(width 0.20066)
		(layer "F.Cu")
		(net "M_F_CPU0_SA_DQ<22>")
	)
	(segment
		(start 427.639226 -290.816792)
		(end 425.940982 -290.816792)
		(width 0.20066)
		(layer "F.Cu")
		(net "M_F_CPU0_SA_DQ<22>")
	)
	(segment
		(start 424.836336 -290.816792)
		(end 425.940982 -290.816792)
		(width 0.20066)
		(layer "F.Cu")
		(net "M_F_CPU0_SA_DQ<22>")
	)
	(segment
		(start 431.898552 -290.564824)
		(end 431.514504 -290.564824)
		(width 0.20066)
		(layer "F.Cu")
		(net "M_F_CPU0_SA_DQ<22>")
	)
	(segment
		(start 430.395126 -291.253926)
		(end 430.382934 -291.241734)
		(width 0.1016)
		(layer "F.Cu")
		(net "M_F_CPU0_SA_DQ<22>")
	)
	(segment
		(start 430.382934 -291.241734)
		(end 428.375064 -291.241734)
		(width 0.1016)
		(layer "F.Cu")
		(net "M_F_CPU0_SA_DQ<22>")
	)
	(segment
		(start 428.375064 -291.241734)
		(end 428.367952 -291.248846)
		(width 0.1016)
		(layer "F.Cu")
		(net "M_F_CPU0_SA_DQ<22>")
	)
	(segment
		(start 428.363126 -291.248846)
		(end 428.07128 -291.248846)
		(width 0.20066)
		(layer "F.Cu")
		(net "M_F_CPU0_SA_DQ<22>")
	)
	(segment
		(start 431.280316 -291.049964)
		(end 431.076354 -291.253926)
		(width 0.20066)
		(layer "F.Cu")
		(net "M_F_CPU0_SA_DQ<22>")
	)
	(segment
		(start 433.484782 -290.816792)
		(end 432.15052 -290.816792)
		(width 0.20066)
		(layer "F.Cu")
		(net "M_F_CPU0_SA_DQ<22>")
	)
	(segment
		(start 432.15052 -290.816792)
		(end 431.898552 -290.564824)
		(width 0.20066)
		(layer "F.Cu")
		(net "M_F_CPU0_SA_DQ<22>")
	)
	(segment
		(start 388.4295 -266.717526)
		(end 388.088632 -266.376658)
		(width 0.088646)
		(layer "In2.Cu")
		(net "M_F_CPU0_SA_DQ<22>")
	)
	(segment
		(start 391.577068 -267.025628)
		(end 390.83361 -266.717526)
		(width 0.18288)
		(layer "In2.Cu")
		(net "M_F_CPU0_SA_DQ<22>")
	)
	(segment
		(start 410.290518 -282.232608)
		(end 409.84932 -281.79141)
		(width 0.18288)
		(layer "In2.Cu")
		(net "M_F_CPU0_SA_DQ<22>")
	)
	(segment
		(start 399.821146 -273.434048)
		(end 396.735808 -270.34871)
		(width 0.18288)
		(layer "In2.Cu")
		(net "M_F_CPU0_SA_DQ<22>")
	)
	(segment
		(start 415.06775 -284.467046)
		(end 413.527494 -284.467046)
		(width 0.18288)
		(layer "In2.Cu")
		(net "M_F_CPU0_SA_DQ<22>")
	)
	(segment
		(start 423.661586 -290.729924)
		(end 423.245788 -290.314126)
		(width 0.18288)
		(layer "In2.Cu")
		(net "M_F_CPU0_SA_DQ<22>")
	)
	(segment
		(start 419.335966 -287.082484)
		(end 419.036754 -286.783272)
		(width 0.18288)
		(layer "In2.Cu")
		(net "M_F_CPU0_SA_DQ<22>")
	)
	(segment
		(start 422.247822 -291.248338)
		(end 421.699436 -291.248338)
		(width 0.18288)
		(layer "In2.Cu")
		(net "M_F_CPU0_SA_DQ<22>")
	)
	(segment
		(start 415.785554 -283.749242)
		(end 415.06775 -284.467046)
		(width 0.18288)
		(layer "In2.Cu")
		(net "M_F_CPU0_SA_DQ<22>")
	)
	(segment
		(start 411.241494 -282.392628)
		(end 411.081474 -282.232608)
		(width 0.18288)
		(layer "In2.Cu")
		(net "M_F_CPU0_SA_DQ<22>")
	)
	(segment
		(start 383.18567 -266.941808)
		(end 383.185416 -266.942062)
		(width 0.088646)
		(layer "In2.Cu")
		(net "M_F_CPU0_SA_DQ<22>")
	)
	(segment
		(start 424.428666 -291.223954)
		(end 423.85488 -291.223954)
		(width 0.18288)
		(layer "In2.Cu")
		(net "M_F_CPU0_SA_DQ<22>")
	)
	(segment
		(start 421.699436 -291.248338)
		(end 421.539416 -291.088318)
		(width 0.18288)
		(layer "In2.Cu")
		(net "M_F_CPU0_SA_DQ<22>")
	)
	(segment
		(start 390.83361 -266.717526)
		(end 388.840472 -266.717526)
		(width 0.18288)
		(layer "In2.Cu")
		(net "M_F_CPU0_SA_DQ<22>")
	)
	(segment
		(start 411.8229 -282.762452)
		(end 411.401514 -282.762452)
		(width 0.18288)
		(layer "In2.Cu")
		(net "M_F_CPU0_SA_DQ<22>")
	)
	(segment
		(start 388.840472 -266.717526)
		(end 388.4295 -266.717526)
		(width 0.088646)
		(layer "In2.Cu")
		(net "M_F_CPU0_SA_DQ<22>")
	)
	(segment
		(start 422.730168 -290.314126)
		(end 422.440862 -290.603432)
		(width 0.18288)
		(layer "In2.Cu")
		(net "M_F_CPU0_SA_DQ<22>")
	)
	(segment
		(start 420.110666 -287.29305)
		(end 419.9001 -287.082484)
		(width 0.18288)
		(layer "In2.Cu")
		(net "M_F_CPU0_SA_DQ<22>")
	)
	(segment
		(start 411.081474 -282.232608)
		(end 410.290518 -282.232608)
		(width 0.18288)
		(layer "In2.Cu")
		(net "M_F_CPU0_SA_DQ<22>")
	)
	(segment
		(start 421.539416 -290.551362)
		(end 421.379396 -290.391342)
		(width 0.18288)
		(layer "In2.Cu")
		(net "M_F_CPU0_SA_DQ<22>")
	)
	(segment
		(start 394.90015 -270.34871)
		(end 391.577068 -267.025628)
		(width 0.18288)
		(layer "In2.Cu")
		(net "M_F_CPU0_SA_DQ<22>")
	)
	(segment
		(start 388.088632 -266.376658)
		(end 387.884162 -266.376658)
		(width 0.088646)
		(layer "In2.Cu")
		(net "M_F_CPU0_SA_DQ<22>")
	)
	(segment
		(start 423.661586 -291.03066)
		(end 423.661586 -290.729924)
		(width 0.18288)
		(layer "In2.Cu")
		(net "M_F_CPU0_SA_DQ<22>")
	)
	(segment
		(start 421.539416 -291.088318)
		(end 421.539416 -290.551362)
		(width 0.18288)
		(layer "In2.Cu")
		(net "M_F_CPU0_SA_DQ<22>")
	)
	(segment
		(start 411.241494 -282.602432)
		(end 411.241494 -282.392628)
		(width 0.18288)
		(layer "In2.Cu")
		(net "M_F_CPU0_SA_DQ<22>")
	)
	(segment
		(start 412.086552 -283.252164)
		(end 412.086552 -283.026104)
		(width 0.18288)
		(layer "In2.Cu")
		(net "M_F_CPU0_SA_DQ<22>")
	)
	(segment
		(start 416.846766 -285.471362)
		(end 416.846766 -284.53715)
		(width 0.18288)
		(layer "In2.Cu")
		(net "M_F_CPU0_SA_DQ<22>")
	)
	(segment
		(start 418.158676 -286.783272)
		(end 416.846766 -285.471362)
		(width 0.18288)
		(layer "In2.Cu")
		(net "M_F_CPU0_SA_DQ<22>")
	)
	(segment
		(start 384.407664 -266.45235)
		(end 384.277108 -266.376912)
		(width 0.088646)
		(layer "In2.Cu")
		(net "M_F_CPU0_SA_DQ<22>")
	)
	(segment
		(start 409.84932 -281.79141)
		(end 409.231592 -281.79141)
		(width 0.18288)
		(layer "In2.Cu")
		(net "M_F_CPU0_SA_DQ<22>")
	)
	(segment
		(start 416.058858 -283.749242)
		(end 415.785554 -283.749242)
		(width 0.18288)
		(layer "In2.Cu")
		(net "M_F_CPU0_SA_DQ<22>")
	)
	(segment
		(start 411.401514 -282.762452)
		(end 411.241494 -282.602432)
		(width 0.18288)
		(layer "In2.Cu")
		(net "M_F_CPU0_SA_DQ<22>")
	)
	(segment
		(start 421.379396 -290.391342)
		(end 420.399972 -290.391342)
		(width 0.18288)
		(layer "In2.Cu")
		(net "M_F_CPU0_SA_DQ<22>")
	)
	(segment
		(start 420.399972 -290.391342)
		(end 420.110666 -290.102036)
		(width 0.18288)
		(layer "In2.Cu")
		(net "M_F_CPU0_SA_DQ<22>")
	)
	(segment
		(start 405.988774 -281.007566)
		(end 400.815302 -275.834094)
		(width 0.18288)
		(layer "In2.Cu")
		(net "M_F_CPU0_SA_DQ<22>")
	)
	(segment
		(start 413.527494 -284.467046)
		(end 412.902146 -283.841698)
		(width 0.18288)
		(layer "In2.Cu")
		(net "M_F_CPU0_SA_DQ<22>")
	)
	(segment
		(start 422.440862 -290.603432)
		(end 422.440862 -291.055298)
		(width 0.18288)
		(layer "In2.Cu")
		(net "M_F_CPU0_SA_DQ<22>")
	)
	(segment
		(start 409.231592 -281.79141)
		(end 408.447748 -281.007566)
		(width 0.18288)
		(layer "In2.Cu")
		(net "M_F_CPU0_SA_DQ<22>")
	)
	(segment
		(start 423.245788 -290.314126)
		(end 422.730168 -290.314126)
		(width 0.18288)
		(layer "In2.Cu")
		(net "M_F_CPU0_SA_DQ<22>")
	)
	(segment
		(start 411.969458 -283.595318)
		(end 411.969458 -283.369258)
		(width 0.18288)
		(layer "In2.Cu")
		(net "M_F_CPU0_SA_DQ<22>")
	)
	(segment
		(start 400.815302 -275.834094)
		(end 399.821146 -273.434048)
		(width 0.18288)
		(layer "In2.Cu")
		(net "M_F_CPU0_SA_DQ<22>")
	)
	(segment
		(start 411.969458 -283.369258)
		(end 412.086552 -283.252164)
		(width 0.18288)
		(layer "In2.Cu")
		(net "M_F_CPU0_SA_DQ<22>")
	)
	(segment
		(start 384.277108 -266.376912)
		(end 384.124962 -266.376912)
		(width 0.088646)
		(layer "In2.Cu")
		(net "M_F_CPU0_SA_DQ<22>")
	)
	(segment
		(start 412.215838 -283.841698)
		(end 411.969458 -283.595318)
		(width 0.18288)
		(layer "In2.Cu")
		(net "M_F_CPU0_SA_DQ<22>")
	)
	(segment
		(start 424.836082 -290.816538)
		(end 424.428666 -291.223954)
		(width 0.18288)
		(layer "In2.Cu")
		(net "M_F_CPU0_SA_DQ<22>")
	)
	(segment
		(start 408.447748 -281.007566)
		(end 405.988774 -281.007566)
		(width 0.18288)
		(layer "In2.Cu")
		(net "M_F_CPU0_SA_DQ<22>")
	)
	(segment
		(start 419.9001 -287.082484)
		(end 419.335966 -287.082484)
		(width 0.18288)
		(layer "In2.Cu")
		(net "M_F_CPU0_SA_DQ<22>")
	)
	(segment
		(start 396.735808 -270.34871)
		(end 394.90015 -270.34871)
		(width 0.18288)
		(layer "In2.Cu")
		(net "M_F_CPU0_SA_DQ<22>")
	)
	(segment
		(start 412.902146 -283.841698)
		(end 412.215838 -283.841698)
		(width 0.18288)
		(layer "In2.Cu")
		(net "M_F_CPU0_SA_DQ<22>")
	)
	(segment
		(start 420.110666 -290.102036)
		(end 420.110666 -287.29305)
		(width 0.18288)
		(layer "In2.Cu")
		(net "M_F_CPU0_SA_DQ<22>")
	)
	(segment
		(start 416.846766 -284.53715)
		(end 416.058858 -283.749242)
		(width 0.18288)
		(layer "In2.Cu")
		(net "M_F_CPU0_SA_DQ<22>")
	)
	(segment
		(start 412.086552 -283.026104)
		(end 411.8229 -282.762452)
		(width 0.18288)
		(layer "In2.Cu")
		(net "M_F_CPU0_SA_DQ<22>")
	)
	(segment
		(start 423.85488 -291.223954)
		(end 423.661586 -291.03066)
		(width 0.18288)
		(layer "In2.Cu")
		(net "M_F_CPU0_SA_DQ<22>")
	)
	(segment
		(start 422.440862 -291.055298)
		(end 422.247822 -291.248338)
		(width 0.18288)
		(layer "In2.Cu")
		(net "M_F_CPU0_SA_DQ<22>")
	)
	(segment
		(start 383.842514 -266.452604)
		(end 383.762758 -266.498578)
		(width 0.088646)
		(layer "In2.Cu")
		(net "M_F_CPU0_SA_DQ<22>")
	)
	(segment
		(start 419.036754 -286.783272)
		(end 418.158676 -286.783272)
		(width 0.18288)
		(layer "In2.Cu")
		(net "M_F_CPU0_SA_DQ<22>")
	)
	(arc
		(start 384.124962 -266.376912)
		(mid 383.978749 -266.396153)
		(end 383.842514 -266.452604)
		(width 0.088646)
		(layer "In2.Cu")
		(net "M_F_CPU0_SA_DQ<22>")
	)
	(arc
		(start 387.884162 -266.376658)
		(mid 387.737839 -266.39592)
		(end 387.60146 -266.45235)
		(width 0.088646)
		(layer "In2.Cu")
		(net "M_F_CPU0_SA_DQ<22>")
	)
	(arc
		(start 385.72186 -266.45235)
		(mid 385.534662 -266.502527)
		(end 385.347464 -266.45235)
		(width 0.088646)
		(layer "In2.Cu")
		(net "M_F_CPU0_SA_DQ<22>")
	)
	(arc
		(start 387.227064 -266.45235)
		(mid 386.944362 -266.376574)
		(end 386.66166 -266.45235)
		(width 0.088646)
		(layer "In2.Cu")
		(net "M_F_CPU0_SA_DQ<22>")
	)
	(arc
		(start 386.66166 -266.45235)
		(mid 386.474462 -266.502527)
		(end 386.287264 -266.45235)
		(width 0.088646)
		(layer "In2.Cu")
		(net "M_F_CPU0_SA_DQ<22>")
	)
	(arc
		(start 384.78206 -266.45235)
		(mid 384.594862 -266.502527)
		(end 384.407664 -266.45235)
		(width 0.088646)
		(layer "In2.Cu")
		(net "M_F_CPU0_SA_DQ<22>")
	)
	(arc
		(start 387.60146 -266.45235)
		(mid 387.414262 -266.502527)
		(end 387.227064 -266.45235)
		(width 0.088646)
		(layer "In2.Cu")
		(net "M_F_CPU0_SA_DQ<22>")
	)
	(arc
		(start 385.347464 -266.45235)
		(mid 385.064762 -266.376574)
		(end 384.78206 -266.45235)
		(width 0.088646)
		(layer "In2.Cu")
		(net "M_F_CPU0_SA_DQ<22>")
	)
	(arc
		(start 383.762758 -266.498578)
		(mid 383.459487 -266.701018)
		(end 383.18567 -266.941808)
		(width 0.088646)
		(layer "In2.Cu")
		(net "M_F_CPU0_SA_DQ<22>")
	)
	(arc
		(start 386.287264 -266.45235)
		(mid 386.004562 -266.376574)
		(end 385.72186 -266.45235)
		(width 0.088646)
		(layer "In2.Cu")
		(net "M_F_CPU0_SA_DQ<22>")
	)
	(segment
		(start 381.775462 -266.127992)
		(end 381.775462 -266.128246)
		(width 0.20066)
		(layer "F.Cu")
		(net "M_F_CPU0_SA_DQ<21>")
	)
	(segment
		(start 424.756326 -289.541712)
		(end 424.73626 -289.541712)
		(width 0.101854)
		(layer "F.Cu")
		(net "M_F_CPU0_SA_DQ<21>")
	)
	(segment
		(start 424.73626 -289.541712)
		(end 424.391582 -289.541712)
		(width 0.20066)
		(layer "F.Cu")
		(net "M_F_CPU0_SA_DQ<21>")
	)
	(segment
		(start 424.273472 -289.659822)
		(end 424.273472 -290.02736)
		(width 0.20066)
		(layer "F.Cu")
		(net "M_F_CPU0_SA_DQ<21>")
	)
	(segment
		(start 427.792896 -289.966908)
		(end 427.36135 -289.535362)
		(width 0.20066)
		(layer "F.Cu")
		(net "M_F_CPU0_SA_DQ<21>")
	)
	(segment
		(start 429.384714 -289.966654)
		(end 429.38446 -289.966908)
		(width 0.20066)
		(layer "F.Cu")
		(net "M_F_CPU0_SA_DQ<21>")
	)
	(segment
		(start 423.361612 -289.966654)
		(end 421.840914 -289.966654)
		(width 0.20066)
		(layer "F.Cu")
		(net "M_F_CPU0_SA_DQ<21>")
	)
	(segment
		(start 424.085512 -290.21532)
		(end 423.610278 -290.21532)
		(width 0.20066)
		(layer "F.Cu")
		(net "M_F_CPU0_SA_DQ<21>")
	)
	(segment
		(start 426.945044 -289.541712)
		(end 424.756326 -289.541712)
		(width 0.1016)
		(layer "F.Cu")
		(net "M_F_CPU0_SA_DQ<21>")
	)
	(segment
		(start 426.951394 -289.535362)
		(end 426.945044 -289.541712)
		(width 0.1016)
		(layer "F.Cu")
		(net "M_F_CPU0_SA_DQ<21>")
	)
	(segment
		(start 424.273472 -290.02736)
		(end 424.085512 -290.21532)
		(width 0.20066)
		(layer "F.Cu")
		(net "M_F_CPU0_SA_DQ<21>")
	)
	(segment
		(start 381.775716 -266.127738)
		(end 381.775462 -266.127992)
		(width 0.20066)
		(layer "F.Cu")
		(net "M_F_CPU0_SA_DQ<21>")
	)
	(segment
		(start 424.391582 -289.541712)
		(end 424.273472 -289.659822)
		(width 0.20066)
		(layer "F.Cu")
		(net "M_F_CPU0_SA_DQ<21>")
	)
	(segment
		(start 381.775716 -265.592306)
		(end 381.775716 -266.127738)
		(width 0.20066)
		(layer "F.Cu")
		(net "M_F_CPU0_SA_DQ<21>")
	)
	(segment
		(start 429.38446 -289.966908)
		(end 427.792896 -289.966908)
		(width 0.20066)
		(layer "F.Cu")
		(net "M_F_CPU0_SA_DQ<21>")
	)
	(segment
		(start 423.610278 -290.21532)
		(end 423.361612 -289.966654)
		(width 0.20066)
		(layer "F.Cu")
		(net "M_F_CPU0_SA_DQ<21>")
	)
	(segment
		(start 421.840914 -289.966654)
		(end 420.736014 -289.966654)
		(width 0.20066)
		(layer "F.Cu")
		(net "M_F_CPU0_SA_DQ<21>")
	)
	(segment
		(start 427.36135 -289.535362)
		(end 426.951394 -289.535362)
		(width 0.20066)
		(layer "F.Cu")
		(net "M_F_CPU0_SA_DQ<21>")
	)
	(segment
		(start 423.377106 -288.02457)
		(end 423.377106 -286.81045)
		(width 0.18288)
		(layer "In2.Cu")
		(net "M_F_CPU0_SA_DQ<21>")
	)
	(segment
		(start 421.247062 -286.14243)
		(end 420.109396 -286.14243)
		(width 0.18288)
		(layer "In2.Cu")
		(net "M_F_CPU0_SA_DQ<21>")
	)
	(segment
		(start 409.85313 -281.177238)
		(end 409.341574 -281.177238)
		(width 0.18288)
		(layer "In2.Cu")
		(net "M_F_CPU0_SA_DQ<21>")
	)
	(segment
		(start 401.24634 -275.546566)
		(end 400.252184 -273.14652)
		(width 0.18288)
		(layer "In2.Cu")
		(net "M_F_CPU0_SA_DQ<21>")
	)
	(segment
		(start 422.510966 -285.94431)
		(end 421.445182 -285.94431)
		(width 0.18288)
		(layer "In2.Cu")
		(net "M_F_CPU0_SA_DQ<21>")
	)
	(segment
		(start 413.017462 -282.716986)
		(end 412.572708 -282.272232)
		(width 0.18288)
		(layer "In2.Cu")
		(net "M_F_CPU0_SA_DQ<21>")
	)
	(segment
		(start 388.561072 -266.274296)
		(end 388.374128 -266.087098)
		(width 0.088646)
		(layer "In2.Cu")
		(net "M_F_CPU0_SA_DQ<21>")
	)
	(segment
		(start 407.155396 -279.696672)
		(end 406.212802 -279.696672)
		(width 0.18288)
		(layer "In2.Cu")
		(net "M_F_CPU0_SA_DQ<21>")
	)
	(segment
		(start 396.938754 -269.83309)
		(end 394.873226 -269.83309)
		(width 0.18288)
		(layer "In2.Cu")
		(net "M_F_CPU0_SA_DQ<21>")
	)
	(segment
		(start 405.81072 -279.29459)
		(end 404.994364 -279.29459)
		(width 0.18288)
		(layer "In2.Cu")
		(net "M_F_CPU0_SA_DQ<21>")
	)
	(segment
		(start 382.997964 -266.617704)
		(end 382.992122 -266.621006)
		(width 0.088646)
		(layer "In2.Cu")
		(net "M_F_CPU0_SA_DQ<21>")
	)
	(segment
		(start 388.840472 -266.35456)
		(end 388.641336 -266.35456)
		(width 0.088646)
		(layer "In2.Cu")
		(net "M_F_CPU0_SA_DQ<21>")
	)
	(segment
		(start 421.502586 -288.96691)
		(end 422.434766 -288.96691)
		(width 0.18288)
		(layer "In2.Cu")
		(net "M_F_CPU0_SA_DQ<21>")
	)
	(segment
		(start 409.341574 -281.177238)
		(end 408.369008 -280.204672)
		(width 0.18288)
		(layer "In2.Cu")
		(net "M_F_CPU0_SA_DQ<21>")
	)
	(segment
		(start 417.855146 -284.803596)
		(end 415.768536 -282.716986)
		(width 0.18288)
		(layer "In2.Cu")
		(net "M_F_CPU0_SA_DQ<21>")
	)
	(segment
		(start 390.872726 -266.35456)
		(end 388.840472 -266.35456)
		(width 0.18288)
		(layer "In2.Cu")
		(net "M_F_CPU0_SA_DQ<21>")
	)
	(segment
		(start 387.673596 -265.845544)
		(end 387.60146 -265.803888)
		(width 0.088646)
		(layer "In2.Cu")
		(net "M_F_CPU0_SA_DQ<21>")
	)
	(segment
		(start 408.369008 -280.204672)
		(end 407.663396 -280.204672)
		(width 0.18288)
		(layer "In2.Cu")
		(net "M_F_CPU0_SA_DQ<21>")
	)
	(segment
		(start 394.873226 -269.83309)
		(end 391.764012 -266.723876)
		(width 0.18288)
		(layer "In2.Cu")
		(net "M_F_CPU0_SA_DQ<21>")
	)
	(segment
		(start 384.407664 -265.803888)
		(end 384.392932 -265.812524)
		(width 0.088646)
		(layer "In2.Cu")
		(net "M_F_CPU0_SA_DQ<21>")
	)
	(segment
		(start 404.994364 -279.29459)
		(end 401.24634 -275.546566)
		(width 0.18288)
		(layer "In2.Cu")
		(net "M_F_CPU0_SA_DQ<21>")
	)
	(segment
		(start 422.434766 -288.96691)
		(end 423.377106 -288.02457)
		(width 0.18288)
		(layer "In2.Cu")
		(net "M_F_CPU0_SA_DQ<21>")
	)
	(segment
		(start 418.770562 -284.803596)
		(end 417.855146 -284.803596)
		(width 0.18288)
		(layer "In2.Cu")
		(net "M_F_CPU0_SA_DQ<21>")
	)
	(segment
		(start 385.347464 -265.803888)
		(end 385.332732 -265.812524)
		(width 0.088646)
		(layer "In2.Cu")
		(net "M_F_CPU0_SA_DQ<21>")
	)
	(segment
		(start 412.379668 -281.177238)
		(end 411.887924 -281.177238)
		(width 0.18288)
		(layer "In2.Cu")
		(net "M_F_CPU0_SA_DQ<21>")
	)
	(segment
		(start 410.325316 -280.705052)
		(end 409.85313 -281.177238)
		(width 0.18288)
		(layer "In2.Cu")
		(net "M_F_CPU0_SA_DQ<21>")
	)
	(segment
		(start 406.212802 -279.696672)
		(end 405.81072 -279.29459)
		(width 0.18288)
		(layer "In2.Cu")
		(net "M_F_CPU0_SA_DQ<21>")
	)
	(segment
		(start 388.641336 -266.35456)
		(end 388.561072 -266.274296)
		(width 0.088646)
		(layer "In2.Cu")
		(net "M_F_CPU0_SA_DQ<21>")
	)
	(segment
		(start 381.775716 -266.127992)
		(end 381.775462 -266.128246)
		(width 0.088646)
		(layer "In2.Cu")
		(net "M_F_CPU0_SA_DQ<21>")
	)
	(segment
		(start 421.445182 -285.94431)
		(end 421.247062 -286.14243)
		(width 0.18288)
		(layer "In2.Cu")
		(net "M_F_CPU0_SA_DQ<21>")
	)
	(segment
		(start 383.467864 -265.803888)
		(end 383.458974 -265.808968)
		(width 0.088646)
		(layer "In2.Cu")
		(net "M_F_CPU0_SA_DQ<21>")
	)
	(segment
		(start 407.663396 -280.204672)
		(end 407.155396 -279.696672)
		(width 0.18288)
		(layer "In2.Cu")
		(net "M_F_CPU0_SA_DQ<21>")
	)
	(segment
		(start 386.287264 -265.803888)
		(end 386.272532 -265.812524)
		(width 0.088646)
		(layer "In2.Cu")
		(net "M_F_CPU0_SA_DQ<21>")
	)
	(segment
		(start 412.572708 -282.272232)
		(end 412.572708 -281.370278)
		(width 0.18288)
		(layer "In2.Cu")
		(net "M_F_CPU0_SA_DQ<21>")
	)
	(segment
		(start 391.764012 -266.723876)
		(end 390.872726 -266.35456)
		(width 0.18288)
		(layer "In2.Cu")
		(net "M_F_CPU0_SA_DQ<21>")
	)
	(segment
		(start 383.280412 -266.128246)
		(end 383.280412 -266.135358)
		(width 0.088646)
		(layer "In2.Cu")
		(net "M_F_CPU0_SA_DQ<21>")
	)
	(segment
		(start 387.227064 -265.803888)
		(end 387.212332 -265.812524)
		(width 0.088646)
		(layer "In2.Cu")
		(net "M_F_CPU0_SA_DQ<21>")
	)
	(segment
		(start 420.901114 -289.568382)
		(end 421.502586 -288.96691)
		(width 0.18288)
		(layer "In2.Cu")
		(net "M_F_CPU0_SA_DQ<21>")
	)
	(segment
		(start 423.377106 -286.81045)
		(end 422.510966 -285.94431)
		(width 0.18288)
		(layer "In2.Cu")
		(net "M_F_CPU0_SA_DQ<21>")
	)
	(segment
		(start 415.768536 -282.716986)
		(end 413.017462 -282.716986)
		(width 0.18288)
		(layer "In2.Cu")
		(net "M_F_CPU0_SA_DQ<21>")
	)
	(segment
		(start 420.855394 -289.678618)
		(end 420.901114 -289.568382)
		(width 0.18288)
		(layer "In2.Cu")
		(net "M_F_CPU0_SA_DQ<21>")
	)
	(segment
		(start 400.252184 -273.14652)
		(end 396.938754 -269.83309)
		(width 0.18288)
		(layer "In2.Cu")
		(net "M_F_CPU0_SA_DQ<21>")
	)
	(segment
		(start 382.08839 -266.127992)
		(end 381.775716 -266.127992)
		(width 0.088646)
		(layer "In2.Cu")
		(net "M_F_CPU0_SA_DQ<21>")
	)
	(segment
		(start 420.736014 -289.966654)
		(end 420.855394 -289.678618)
		(width 0.18288)
		(layer "In2.Cu")
		(net "M_F_CPU0_SA_DQ<21>")
	)
	(segment
		(start 382.154176 -266.193778)
		(end 382.08839 -266.127992)
		(width 0.088646)
		(layer "In2.Cu")
		(net "M_F_CPU0_SA_DQ<21>")
	)
	(segment
		(start 412.572708 -281.370278)
		(end 412.379668 -281.177238)
		(width 0.18288)
		(layer "In2.Cu")
		(net "M_F_CPU0_SA_DQ<21>")
	)
	(segment
		(start 411.415738 -280.705052)
		(end 410.325316 -280.705052)
		(width 0.18288)
		(layer "In2.Cu")
		(net "M_F_CPU0_SA_DQ<21>")
	)
	(segment
		(start 411.887924 -281.177238)
		(end 411.415738 -280.705052)
		(width 0.18288)
		(layer "In2.Cu")
		(net "M_F_CPU0_SA_DQ<21>")
	)
	(segment
		(start 420.109396 -286.14243)
		(end 418.770562 -284.803596)
		(width 0.18288)
		(layer "In2.Cu")
		(net "M_F_CPU0_SA_DQ<21>")
	)
	(arc
		(start 382.992122 -266.621006)
		(mid 382.711987 -266.693289)
		(end 382.432814 -266.61745)
		(width 0.088646)
		(layer "In2.Cu")
		(net "M_F_CPU0_SA_DQ<21>")
	)
	(arc
		(start 386.272532 -265.812524)
		(mid 385.996091 -265.87969)
		(end 385.72186 -265.803888)
		(width 0.088646)
		(layer "In2.Cu")
		(net "M_F_CPU0_SA_DQ<21>")
	)
	(arc
		(start 388.004558 -265.93419)
		(mid 387.833248 -265.911638)
		(end 387.673596 -265.845544)
		(width 0.088646)
		(layer "In2.Cu")
		(net "M_F_CPU0_SA_DQ<21>")
	)
	(arc
		(start 384.392932 -265.812524)
		(mid 384.116491 -265.87969)
		(end 383.84226 -265.803888)
		(width 0.088646)
		(layer "In2.Cu")
		(net "M_F_CPU0_SA_DQ<21>")
	)
	(arc
		(start 385.332732 -265.812524)
		(mid 385.056291 -265.87969)
		(end 384.78206 -265.803888)
		(width 0.088646)
		(layer "In2.Cu")
		(net "M_F_CPU0_SA_DQ<21>")
	)
	(arc
		(start 383.280412 -266.135358)
		(mid 383.202972 -266.413875)
		(end 382.997964 -266.617704)
		(width 0.088646)
		(layer "In2.Cu")
		(net "M_F_CPU0_SA_DQ<21>")
	)
	(arc
		(start 387.212332 -265.812524)
		(mid 386.935891 -265.87969)
		(end 386.66166 -265.803888)
		(width 0.088646)
		(layer "In2.Cu")
		(net "M_F_CPU0_SA_DQ<21>")
	)
	(arc
		(start 387.60146 -265.803888)
		(mid 387.414262 -265.753745)
		(end 387.227064 -265.803888)
		(width 0.088646)
		(layer "In2.Cu")
		(net "M_F_CPU0_SA_DQ<21>")
	)
	(arc
		(start 382.432814 -266.61745)
		(mid 382.243291 -266.438625)
		(end 382.154176 -266.193778)
		(width 0.088646)
		(layer "In2.Cu")
		(net "M_F_CPU0_SA_DQ<21>")
	)
	(arc
		(start 386.66166 -265.803888)
		(mid 386.474462 -265.753745)
		(end 386.287264 -265.803888)
		(width 0.088646)
		(layer "In2.Cu")
		(net "M_F_CPU0_SA_DQ<21>")
	)
	(arc
		(start 384.78206 -265.803888)
		(mid 384.594862 -265.753745)
		(end 384.407664 -265.803888)
		(width 0.088646)
		(layer "In2.Cu")
		(net "M_F_CPU0_SA_DQ<21>")
	)
	(arc
		(start 383.84226 -265.803888)
		(mid 383.655062 -265.753745)
		(end 383.467864 -265.803888)
		(width 0.088646)
		(layer "In2.Cu")
		(net "M_F_CPU0_SA_DQ<21>")
	)
	(arc
		(start 383.458974 -265.808968)
		(mid 383.32806 -265.945328)
		(end 383.280412 -266.128246)
		(width 0.088646)
		(layer "In2.Cu")
		(net "M_F_CPU0_SA_DQ<21>")
	)
	(arc
		(start 385.72186 -265.803888)
		(mid 385.534662 -265.753745)
		(end 385.347464 -265.803888)
		(width 0.088646)
		(layer "In2.Cu")
		(net "M_F_CPU0_SA_DQ<21>")
	)
	(arc
		(start 388.374128 -266.087098)
		(mid 388.204553 -265.973885)
		(end 388.004558 -265.93419)
		(width 0.088646)
		(layer "In2.Cu")
		(net "M_F_CPU0_SA_DQ<21>")
	)
	(segment
		(start 426.951394 -291.235384)
		(end 426.945044 -291.241734)
		(width 0.1016)
		(layer "F.Cu")
		(net "M_F_CPU0_SA_DQ<20>")
	)
	(segment
		(start 424.391582 -291.241734)
		(end 424.273472 -291.359844)
		(width 0.20066)
		(layer "F.Cu")
		(net "M_F_CPU0_SA_DQ<20>")
	)
	(segment
		(start 424.085512 -291.915342)
		(end 423.610278 -291.915342)
		(width 0.20066)
		(layer "F.Cu")
		(net "M_F_CPU0_SA_DQ<20>")
	)
	(segment
		(start 429.38446 -291.66693)
		(end 427.792896 -291.66693)
		(width 0.20066)
		(layer "F.Cu")
		(net "M_F_CPU0_SA_DQ<20>")
	)
	(segment
		(start 424.273472 -291.359844)
		(end 424.273472 -291.727382)
		(width 0.20066)
		(layer "F.Cu")
		(net "M_F_CPU0_SA_DQ<20>")
	)
	(segment
		(start 424.78325 -291.241734)
		(end 424.73626 -291.241734)
		(width 0.101854)
		(layer "F.Cu")
		(net "M_F_CPU0_SA_DQ<20>")
	)
	(segment
		(start 381.305562 -266.405868)
		(end 381.305562 -266.941808)
		(width 0.20066)
		(layer "F.Cu")
		(net "M_F_CPU0_SA_DQ<20>")
	)
	(segment
		(start 424.73626 -291.241734)
		(end 424.391582 -291.241734)
		(width 0.20066)
		(layer "F.Cu")
		(net "M_F_CPU0_SA_DQ<20>")
	)
	(segment
		(start 424.273472 -291.727382)
		(end 424.085512 -291.915342)
		(width 0.20066)
		(layer "F.Cu")
		(net "M_F_CPU0_SA_DQ<20>")
	)
	(segment
		(start 427.36135 -291.235384)
		(end 426.951394 -291.235384)
		(width 0.20066)
		(layer "F.Cu")
		(net "M_F_CPU0_SA_DQ<20>")
	)
	(segment
		(start 421.840914 -291.666676)
		(end 420.736014 -291.666676)
		(width 0.20066)
		(layer "F.Cu")
		(net "M_F_CPU0_SA_DQ<20>")
	)
	(segment
		(start 429.384714 -291.666676)
		(end 429.38446 -291.66693)
		(width 0.20066)
		(layer "F.Cu")
		(net "M_F_CPU0_SA_DQ<20>")
	)
	(segment
		(start 423.361612 -291.666676)
		(end 421.840914 -291.666676)
		(width 0.20066)
		(layer "F.Cu")
		(net "M_F_CPU0_SA_DQ<20>")
	)
	(segment
		(start 426.945044 -291.241734)
		(end 424.78325 -291.241734)
		(width 0.1016)
		(layer "F.Cu")
		(net "M_F_CPU0_SA_DQ<20>")
	)
	(segment
		(start 427.792896 -291.66693)
		(end 427.36135 -291.235384)
		(width 0.20066)
		(layer "F.Cu")
		(net "M_F_CPU0_SA_DQ<20>")
	)
	(segment
		(start 423.610278 -291.915342)
		(end 423.361612 -291.666676)
		(width 0.20066)
		(layer "F.Cu")
		(net "M_F_CPU0_SA_DQ<20>")
	)
	(segment
		(start 404.650702 -280.388314)
		(end 400.384518 -276.12213)
		(width 0.18288)
		(layer "In2.Cu")
		(net "M_F_CPU0_SA_DQ<20>")
	)
	(segment
		(start 417.248086 -287.214056)
		(end 416.748468 -286.714438)
		(width 0.18288)
		(layer "In2.Cu")
		(net "M_F_CPU0_SA_DQ<20>")
	)
	(segment
		(start 406.271222 -281.52217)
		(end 405.886666 -281.906726)
		(width 0.18288)
		(layer "In2.Cu")
		(net "M_F_CPU0_SA_DQ<20>")
	)
	(segment
		(start 400.384518 -276.12213)
		(end 399.390108 -273.72183)
		(width 0.18288)
		(layer "In2.Cu")
		(net "M_F_CPU0_SA_DQ<20>")
	)
	(segment
		(start 411.221936 -284.567122)
		(end 411.221936 -285.150306)
		(width 0.18288)
		(layer "In2.Cu")
		(net "M_F_CPU0_SA_DQ<20>")
	)
	(segment
		(start 419.41877 -290.570412)
		(end 419.063678 -290.21532)
		(width 0.18288)
		(layer "In2.Cu")
		(net "M_F_CPU0_SA_DQ<20>")
	)
	(segment
		(start 409.057348 -282.771088)
		(end 409.057348 -282.340812)
		(width 0.18288)
		(layer "In2.Cu")
		(net "M_F_CPU0_SA_DQ<20>")
	)
	(segment
		(start 382.058164 -267.266166)
		(end 381.67691 -267.042646)
		(width 0.088646)
		(layer "In2.Cu")
		(net "M_F_CPU0_SA_DQ<20>")
	)
	(segment
		(start 409.678632 -283.392626)
		(end 409.430728 -283.392626)
		(width 0.18288)
		(layer "In2.Cu")
		(net "M_F_CPU0_SA_DQ<20>")
	)
	(segment
		(start 416.748468 -286.131)
		(end 416.294062 -285.676594)
		(width 0.18288)
		(layer "In2.Cu")
		(net "M_F_CPU0_SA_DQ<20>")
	)
	(segment
		(start 396.524988 -270.85671)
		(end 394.919454 -270.85671)
		(width 0.18288)
		(layer "In2.Cu")
		(net "M_F_CPU0_SA_DQ<20>")
	)
	(segment
		(start 408.623262 -281.906726)
		(end 407.665682 -281.906726)
		(width 0.18288)
		(layer "In2.Cu")
		(net "M_F_CPU0_SA_DQ<20>")
	)
	(segment
		(start 407.665682 -281.906726)
		(end 407.281126 -281.52217)
		(width 0.18288)
		(layer "In2.Cu")
		(net "M_F_CPU0_SA_DQ<20>")
	)
	(segment
		(start 388.5057 -267.062966)
		(end 388.009638 -266.566904)
		(width 0.088646)
		(layer "In2.Cu")
		(net "M_F_CPU0_SA_DQ<20>")
	)
	(segment
		(start 416.294062 -285.109666)
		(end 416.026346 -284.84195)
		(width 0.18288)
		(layer "In2.Cu")
		(net "M_F_CPU0_SA_DQ<20>")
	)
	(segment
		(start 405.448516 -281.906726)
		(end 405.16048 -281.61869)
		(width 0.18288)
		(layer "In2.Cu")
		(net "M_F_CPU0_SA_DQ<20>")
	)
	(segment
		(start 405.886666 -281.906726)
		(end 405.448516 -281.906726)
		(width 0.18288)
		(layer "In2.Cu")
		(net "M_F_CPU0_SA_DQ<20>")
	)
	(segment
		(start 408.60472 -283.223716)
		(end 409.057348 -282.771088)
		(width 0.18288)
		(layer "In2.Cu")
		(net "M_F_CPU0_SA_DQ<20>")
	)
	(segment
		(start 416.294062 -285.676594)
		(end 416.294062 -285.109666)
		(width 0.18288)
		(layer "In2.Cu")
		(net "M_F_CPU0_SA_DQ<20>")
	)
	(segment
		(start 410.466286 -285.062676)
		(end 410.466286 -284.84195)
		(width 0.18288)
		(layer "In2.Cu")
		(net "M_F_CPU0_SA_DQ<20>")
	)
	(segment
		(start 409.057348 -282.340812)
		(end 408.623262 -281.906726)
		(width 0.18288)
		(layer "In2.Cu")
		(net "M_F_CPU0_SA_DQ<20>")
	)
	(segment
		(start 408.82951 -283.721048)
		(end 408.60472 -283.496258)
		(width 0.18288)
		(layer "In2.Cu")
		(net "M_F_CPU0_SA_DQ<20>")
	)
	(segment
		(start 399.390108 -273.72183)
		(end 396.524988 -270.85671)
		(width 0.18288)
		(layer "In2.Cu")
		(net "M_F_CPU0_SA_DQ<20>")
	)
	(segment
		(start 384.225038 -266.567412)
		(end 384.124962 -266.567412)
		(width 0.088646)
		(layer "In2.Cu")
		(net "M_F_CPU0_SA_DQ<20>")
	)
	(segment
		(start 381.305816 -266.942062)
		(end 381.305562 -266.941808)
		(width 0.088646)
		(layer "In2.Cu")
		(net "M_F_CPU0_SA_DQ<20>")
	)
	(segment
		(start 418.807646 -288.20491)
		(end 417.898326 -288.20491)
		(width 0.18288)
		(layer "In2.Cu")
		(net "M_F_CPU0_SA_DQ<20>")
	)
	(segment
		(start 410.466286 -284.84195)
		(end 409.889706 -284.26537)
		(width 0.18288)
		(layer "In2.Cu")
		(net "M_F_CPU0_SA_DQ<20>")
	)
	(segment
		(start 405.16048 -281.61869)
		(end 404.650702 -280.388314)
		(width 0.18288)
		(layer "In2.Cu")
		(net "M_F_CPU0_SA_DQ<20>")
	)
	(segment
		(start 419.394386 -289.45713)
		(end 419.394386 -288.79165)
		(width 0.18288)
		(layer "In2.Cu")
		(net "M_F_CPU0_SA_DQ<20>")
	)
	(segment
		(start 394.919454 -270.85671)
		(end 391.42416 -267.361416)
		(width 0.18288)
		(layer "In2.Cu")
		(net "M_F_CPU0_SA_DQ<20>")
	)
	(segment
		(start 409.102306 -283.721048)
		(end 408.82951 -283.721048)
		(width 0.18288)
		(layer "In2.Cu")
		(net "M_F_CPU0_SA_DQ<20>")
	)
	(segment
		(start 411.061916 -285.310326)
		(end 410.713936 -285.310326)
		(width 0.18288)
		(layer "In2.Cu")
		(net "M_F_CPU0_SA_DQ<20>")
	)
	(segment
		(start 383.386076 -267.2588)
		(end 383.355596 -267.276072)
		(width 0.088646)
		(layer "In2.Cu")
		(net "M_F_CPU0_SA_DQ<20>")
	)
	(segment
		(start 412.401766 -284.407102)
		(end 411.381956 -284.407102)
		(width 0.18288)
		(layer "In2.Cu")
		(net "M_F_CPU0_SA_DQ<20>")
	)
	(segment
		(start 415.200846 -285.24073)
		(end 413.235394 -285.24073)
		(width 0.18288)
		(layer "In2.Cu")
		(net "M_F_CPU0_SA_DQ<20>")
	)
	(segment
		(start 409.889706 -283.6037)
		(end 409.678632 -283.392626)
		(width 0.18288)
		(layer "In2.Cu")
		(net "M_F_CPU0_SA_DQ<20>")
	)
	(segment
		(start 409.889706 -284.26537)
		(end 409.889706 -283.6037)
		(width 0.18288)
		(layer "In2.Cu")
		(net "M_F_CPU0_SA_DQ<20>")
	)
	(segment
		(start 383.14122 -267.327126)
		(end 382.262888 -267.327126)
		(width 0.088646)
		(layer "In2.Cu")
		(net "M_F_CPU0_SA_DQ<20>")
	)
	(segment
		(start 416.748468 -286.714438)
		(end 416.748468 -286.131)
		(width 0.18288)
		(layer "In2.Cu")
		(net "M_F_CPU0_SA_DQ<20>")
	)
	(segment
		(start 411.221936 -285.150306)
		(end 411.061916 -285.310326)
		(width 0.18288)
		(layer "In2.Cu")
		(net "M_F_CPU0_SA_DQ<20>")
	)
	(segment
		(start 407.281126 -281.52217)
		(end 406.271222 -281.52217)
		(width 0.18288)
		(layer "In2.Cu")
		(net "M_F_CPU0_SA_DQ<20>")
	)
	(segment
		(start 419.637464 -291.201094)
		(end 419.41877 -290.9824)
		(width 0.18288)
		(layer "In2.Cu")
		(net "M_F_CPU0_SA_DQ<20>")
	)
	(segment
		(start 419.063678 -289.787838)
		(end 419.394386 -289.45713)
		(width 0.18288)
		(layer "In2.Cu")
		(net "M_F_CPU0_SA_DQ<20>")
	)
	(segment
		(start 390.70407 -267.062966)
		(end 388.840472 -267.062966)
		(width 0.18288)
		(layer "In2.Cu")
		(net "M_F_CPU0_SA_DQ<20>")
	)
	(segment
		(start 383.61493 -267.052044)
		(end 383.494534 -267.17244)
		(width 0.088646)
		(layer "In2.Cu")
		(net "M_F_CPU0_SA_DQ<20>")
	)
	(segment
		(start 391.42416 -267.361416)
		(end 390.70407 -267.062966)
		(width 0.18288)
		(layer "In2.Cu")
		(net "M_F_CPU0_SA_DQ<20>")
	)
	(segment
		(start 416.026346 -284.84195)
		(end 415.599626 -284.84195)
		(width 0.18288)
		(layer "In2.Cu")
		(net "M_F_CPU0_SA_DQ<20>")
	)
	(segment
		(start 419.394386 -288.79165)
		(end 418.807646 -288.20491)
		(width 0.18288)
		(layer "In2.Cu")
		(net "M_F_CPU0_SA_DQ<20>")
	)
	(segment
		(start 388.009638 -266.566904)
		(end 387.884162 -266.566904)
		(width 0.088646)
		(layer "In2.Cu")
		(net "M_F_CPU0_SA_DQ<20>")
	)
	(segment
		(start 419.41877 -290.9824)
		(end 419.41877 -290.570412)
		(width 0.18288)
		(layer "In2.Cu")
		(net "M_F_CPU0_SA_DQ<20>")
	)
	(segment
		(start 417.898326 -288.20491)
		(end 417.248086 -287.55467)
		(width 0.18288)
		(layer "In2.Cu")
		(net "M_F_CPU0_SA_DQ<20>")
	)
	(segment
		(start 388.840472 -267.062966)
		(end 388.5057 -267.062966)
		(width 0.088646)
		(layer "In2.Cu")
		(net "M_F_CPU0_SA_DQ<20>")
	)
	(segment
		(start 384.31216 -266.617704)
		(end 384.225038 -266.567412)
		(width 0.088646)
		(layer "In2.Cu")
		(net "M_F_CPU0_SA_DQ<20>")
	)
	(segment
		(start 415.599626 -284.84195)
		(end 415.200846 -285.24073)
		(width 0.18288)
		(layer "In2.Cu")
		(net "M_F_CPU0_SA_DQ<20>")
	)
	(segment
		(start 410.713936 -285.310326)
		(end 410.466286 -285.062676)
		(width 0.18288)
		(layer "In2.Cu")
		(net "M_F_CPU0_SA_DQ<20>")
	)
	(segment
		(start 419.063678 -290.21532)
		(end 419.063678 -289.787838)
		(width 0.18288)
		(layer "In2.Cu")
		(net "M_F_CPU0_SA_DQ<20>")
	)
	(segment
		(start 411.381956 -284.407102)
		(end 411.221936 -284.567122)
		(width 0.18288)
		(layer "In2.Cu")
		(net "M_F_CPU0_SA_DQ<20>")
	)
	(segment
		(start 409.430728 -283.392626)
		(end 409.102306 -283.721048)
		(width 0.18288)
		(layer "In2.Cu")
		(net "M_F_CPU0_SA_DQ<20>")
	)
	(segment
		(start 420.270432 -291.201094)
		(end 419.637464 -291.201094)
		(width 0.18288)
		(layer "In2.Cu")
		(net "M_F_CPU0_SA_DQ<20>")
	)
	(segment
		(start 413.235394 -285.24073)
		(end 412.401766 -284.407102)
		(width 0.18288)
		(layer "In2.Cu")
		(net "M_F_CPU0_SA_DQ<20>")
	)
	(segment
		(start 420.736014 -291.666676)
		(end 420.270432 -291.201094)
		(width 0.18288)
		(layer "In2.Cu")
		(net "M_F_CPU0_SA_DQ<20>")
	)
	(segment
		(start 408.60472 -283.496258)
		(end 408.60472 -283.223716)
		(width 0.18288)
		(layer "In2.Cu")
		(net "M_F_CPU0_SA_DQ<20>")
	)
	(segment
		(start 417.248086 -287.55467)
		(end 417.248086 -287.214056)
		(width 0.18288)
		(layer "In2.Cu")
		(net "M_F_CPU0_SA_DQ<20>")
	)
	(arc
		(start 386.19176 -266.617704)
		(mid 386.004562 -266.567527)
		(end 385.817364 -266.617704)
		(width 0.088646)
		(layer "In2.Cu")
		(net "M_F_CPU0_SA_DQ<20>")
	)
	(arc
		(start 382.262888 -267.327126)
		(mid 382.218297 -267.324266)
		(end 382.174496 -267.315442)
		(width 0.088646)
		(layer "In2.Cu")
		(net "M_F_CPU0_SA_DQ<20>")
	)
	(arc
		(start 384.124962 -266.567412)
		(mid 383.913694 -266.632662)
		(end 383.775966 -266.805664)
		(width 0.088646)
		(layer "In2.Cu")
		(net "M_F_CPU0_SA_DQ<20>")
	)
	(arc
		(start 387.884162 -266.566904)
		(mid 387.787223 -266.579994)
		(end 387.696964 -266.617704)
		(width 0.088646)
		(layer "In2.Cu")
		(net "M_F_CPU0_SA_DQ<20>")
	)
	(arc
		(start 386.757164 -266.617704)
		(mid 386.474462 -266.69348)
		(end 386.19176 -266.617704)
		(width 0.088646)
		(layer "In2.Cu")
		(net "M_F_CPU0_SA_DQ<20>")
	)
	(arc
		(start 383.775966 -266.805664)
		(mid 383.708218 -266.937203)
		(end 383.61493 -267.052044)
		(width 0.088646)
		(layer "In2.Cu")
		(net "M_F_CPU0_SA_DQ<20>")
	)
	(arc
		(start 384.877564 -266.617704)
		(mid 384.594862 -266.69348)
		(end 384.31216 -266.617704)
		(width 0.088646)
		(layer "In2.Cu")
		(net "M_F_CPU0_SA_DQ<20>")
	)
	(arc
		(start 385.25196 -266.617704)
		(mid 385.064762 -266.567527)
		(end 384.877564 -266.617704)
		(width 0.088646)
		(layer "In2.Cu")
		(net "M_F_CPU0_SA_DQ<20>")
	)
	(arc
		(start 382.174496 -267.315442)
		(mid 382.114707 -267.294633)
		(end 382.058164 -267.266166)
		(width 0.088646)
		(layer "In2.Cu")
		(net "M_F_CPU0_SA_DQ<20>")
	)
	(arc
		(start 381.67691 -267.042646)
		(mid 381.498064 -266.967636)
		(end 381.305816 -266.942062)
		(width 0.088646)
		(layer "In2.Cu")
		(net "M_F_CPU0_SA_DQ<20>")
	)
	(arc
		(start 385.817364 -266.617704)
		(mid 385.534662 -266.69348)
		(end 385.25196 -266.617704)
		(width 0.088646)
		(layer "In2.Cu")
		(net "M_F_CPU0_SA_DQ<20>")
	)
	(arc
		(start 383.494534 -267.17244)
		(mid 383.447822 -267.215673)
		(end 383.396236 -267.252958)
		(width 0.088646)
		(layer "In2.Cu")
		(net "M_F_CPU0_SA_DQ<20>")
	)
	(arc
		(start 383.396236 -267.252958)
		(mid 383.391146 -267.255862)
		(end 383.386076 -267.2588)
		(width 0.088646)
		(layer "In2.Cu")
		(net "M_F_CPU0_SA_DQ<20>")
	)
	(arc
		(start 387.696964 -266.617704)
		(mid 387.414262 -266.69348)
		(end 387.13156 -266.617704)
		(width 0.088646)
		(layer "In2.Cu")
		(net "M_F_CPU0_SA_DQ<20>")
	)
	(arc
		(start 383.355596 -267.276072)
		(mid 383.251404 -267.314176)
		(end 383.14122 -267.327126)
		(width 0.088646)
		(layer "In2.Cu")
		(net "M_F_CPU0_SA_DQ<20>")
	)
	(arc
		(start 387.13156 -266.617704)
		(mid 386.944362 -266.567527)
		(end 386.757164 -266.617704)
		(width 0.088646)
		(layer "In2.Cu")
		(net "M_F_CPU0_SA_DQ<20>")
	)
	(segment
		(start 424.085512 -314.865258)
		(end 423.610278 -314.865258)
		(width 0.20066)
		(layer "F.Cu")
		(net "M_F_CPU0_SA_DQ<1>")
	)
	(segment
		(start 429.384714 -314.616592)
		(end 429.38446 -314.616846)
		(width 0.20066)
		(layer "F.Cu")
		(net "M_F_CPU0_SA_DQ<1>")
	)
	(segment
		(start 424.756326 -314.19165)
		(end 424.73626 -314.19165)
		(width 0.101854)
		(layer "F.Cu")
		(net "M_F_CPU0_SA_DQ<1>")
	)
	(segment
		(start 424.273472 -314.677298)
		(end 424.085512 -314.865258)
		(width 0.20066)
		(layer "F.Cu")
		(net "M_F_CPU0_SA_DQ<1>")
	)
	(segment
		(start 424.73626 -314.19165)
		(end 424.391582 -314.19165)
		(width 0.20066)
		(layer "F.Cu")
		(net "M_F_CPU0_SA_DQ<1>")
	)
	(segment
		(start 421.840914 -314.616592)
		(end 420.736014 -314.616592)
		(width 0.20066)
		(layer "F.Cu")
		(net "M_F_CPU0_SA_DQ<1>")
	)
	(segment
		(start 427.792896 -314.616846)
		(end 427.36135 -314.1853)
		(width 0.20066)
		(layer "F.Cu")
		(net "M_F_CPU0_SA_DQ<1>")
	)
	(segment
		(start 426.951394 -314.1853)
		(end 426.945044 -314.19165)
		(width 0.1016)
		(layer "F.Cu")
		(net "M_F_CPU0_SA_DQ<1>")
	)
	(segment
		(start 427.36135 -314.1853)
		(end 426.951394 -314.1853)
		(width 0.20066)
		(layer "F.Cu")
		(net "M_F_CPU0_SA_DQ<1>")
	)
	(segment
		(start 429.38446 -314.616846)
		(end 427.792896 -314.616846)
		(width 0.20066)
		(layer "F.Cu")
		(net "M_F_CPU0_SA_DQ<1>")
	)
	(segment
		(start 424.273472 -314.30976)
		(end 424.273472 -314.677298)
		(width 0.20066)
		(layer "F.Cu")
		(net "M_F_CPU0_SA_DQ<1>")
	)
	(segment
		(start 426.945044 -314.19165)
		(end 424.756326 -314.19165)
		(width 0.1016)
		(layer "F.Cu")
		(net "M_F_CPU0_SA_DQ<1>")
	)
	(segment
		(start 424.391582 -314.19165)
		(end 424.273472 -314.30976)
		(width 0.20066)
		(layer "F.Cu")
		(net "M_F_CPU0_SA_DQ<1>")
	)
	(segment
		(start 423.610278 -314.865258)
		(end 423.361612 -314.616592)
		(width 0.20066)
		(layer "F.Cu")
		(net "M_F_CPU0_SA_DQ<1>")
	)
	(segment
		(start 383.185162 -277.800562)
		(end 383.185162 -278.336502)
		(width 0.20066)
		(layer "F.Cu")
		(net "M_F_CPU0_SA_DQ<1>")
	)
	(segment
		(start 423.361612 -314.616592)
		(end 421.840914 -314.616592)
		(width 0.20066)
		(layer "F.Cu")
		(net "M_F_CPU0_SA_DQ<1>")
	)
	(segment
		(start 408.815286 -314.527946)
		(end 408.011884 -314.527946)
		(width 0.18288)
		(layer "In2.Cu")
		(net "M_F_CPU0_SA_DQ<1>")
	)
	(segment
		(start 393.571984 -294.756332)
		(end 391.40892 -292.593268)
		(width 0.18288)
		(layer "In2.Cu")
		(net "M_F_CPU0_SA_DQ<1>")
	)
	(segment
		(start 410.720032 -314.540392)
		(end 410.361638 -314.181998)
		(width 0.18288)
		(layer "In2.Cu")
		(net "M_F_CPU0_SA_DQ<1>")
	)
	(segment
		(start 409.784042 -314.00369)
		(end 409.784042 -313.528964)
		(width 0.18288)
		(layer "In2.Cu")
		(net "M_F_CPU0_SA_DQ<1>")
	)
	(segment
		(start 409.008326 -314.03417)
		(end 409.008326 -314.334906)
		(width 0.18288)
		(layer "In2.Cu")
		(net "M_F_CPU0_SA_DQ<1>")
	)
	(segment
		(start 415.77514 -314.41771)
		(end 415.38398 -314.41771)
		(width 0.18288)
		(layer "In2.Cu")
		(net "M_F_CPU0_SA_DQ<1>")
	)
	(segment
		(start 410.361638 -314.181998)
		(end 409.96235 -314.181998)
		(width 0.18288)
		(layer "In2.Cu")
		(net "M_F_CPU0_SA_DQ<1>")
	)
	(segment
		(start 390.325102 -289.97656)
		(end 390.325102 -284.093666)
		(width 0.18288)
		(layer "In2.Cu")
		(net "M_F_CPU0_SA_DQ<1>")
	)
	(segment
		(start 383.852674 -279.46858)
		(end 383.84226 -279.474676)
		(width 0.088646)
		(layer "In2.Cu")
		(net "M_F_CPU0_SA_DQ<1>")
	)
	(segment
		(start 394.970254 -298.131992)
		(end 393.571984 -294.756332)
		(width 0.18288)
		(layer "In2.Cu")
		(net "M_F_CPU0_SA_DQ<1>")
	)
	(segment
		(start 412.43123 -314.182506)
		(end 411.425898 -314.182506)
		(width 0.18288)
		(layer "In2.Cu")
		(net "M_F_CPU0_SA_DQ<1>")
	)
	(segment
		(start 405.713184 -314.271152)
		(end 405.246078 -314.271152)
		(width 0.18288)
		(layer "In2.Cu")
		(net "M_F_CPU0_SA_DQ<1>")
	)
	(segment
		(start 409.008326 -314.334906)
		(end 408.815286 -314.527946)
		(width 0.18288)
		(layer "In2.Cu")
		(net "M_F_CPU0_SA_DQ<1>")
	)
	(segment
		(start 409.028646 -313.33567)
		(end 408.787346 -313.57697)
		(width 0.18288)
		(layer "In2.Cu")
		(net "M_F_CPU0_SA_DQ<1>")
	)
	(segment
		(start 420.223696 -313.572398)
		(end 420.030656 -313.379358)
		(width 0.18288)
		(layer "In2.Cu")
		(net "M_F_CPU0_SA_DQ<1>")
	)
	(segment
		(start 405.772366 -314.21197)
		(end 405.713184 -314.271152)
		(width 0.18288)
		(layer "In2.Cu")
		(net "M_F_CPU0_SA_DQ<1>")
	)
	(segment
		(start 411.068012 -314.540392)
		(end 410.720032 -314.540392)
		(width 0.18288)
		(layer "In2.Cu")
		(net "M_F_CPU0_SA_DQ<1>")
	)
	(segment
		(start 387.088126 -279.412446)
		(end 385.979924 -279.412446)
		(width 0.088646)
		(layer "In2.Cu")
		(net "M_F_CPU0_SA_DQ<1>")
	)
	(segment
		(start 387.368542 -279.412446)
		(end 387.088126 -279.412446)
		(width 0.18288)
		(layer "In2.Cu")
		(net "M_F_CPU0_SA_DQ<1>")
	)
	(segment
		(start 411.425898 -314.182506)
		(end 411.068012 -314.540392)
		(width 0.18288)
		(layer "In2.Cu")
		(net "M_F_CPU0_SA_DQ<1>")
	)
	(segment
		(start 416.59302 -314.573158)
		(end 416.39998 -314.766198)
		(width 0.18288)
		(layer "In2.Cu")
		(net "M_F_CPU0_SA_DQ<1>")
	)
	(segment
		(start 409.590748 -313.33567)
		(end 409.028646 -313.33567)
		(width 0.18288)
		(layer "In2.Cu")
		(net "M_F_CPU0_SA_DQ<1>")
	)
	(segment
		(start 417.213796 -313.362086)
		(end 416.75304 -313.362086)
		(width 0.18288)
		(layer "In2.Cu")
		(net "M_F_CPU0_SA_DQ<1>")
	)
	(segment
		(start 420.736014 -314.616592)
		(end 420.223696 -314.104274)
		(width 0.18288)
		(layer "In2.Cu")
		(net "M_F_CPU0_SA_DQ<1>")
	)
	(segment
		(start 405.246078 -314.271152)
		(end 404.897082 -314.126626)
		(width 0.18288)
		(layer "In2.Cu")
		(net "M_F_CPU0_SA_DQ<1>")
	)
	(segment
		(start 408.787346 -313.57697)
		(end 408.787346 -313.81319)
		(width 0.18288)
		(layer "In2.Cu")
		(net "M_F_CPU0_SA_DQ<1>")
	)
	(segment
		(start 419.559994 -313.379358)
		(end 419.366954 -313.572398)
		(width 0.18288)
		(layer "In2.Cu")
		(net "M_F_CPU0_SA_DQ<1>")
	)
	(segment
		(start 417.406836 -313.555126)
		(end 417.213796 -313.362086)
		(width 0.18288)
		(layer "In2.Cu")
		(net "M_F_CPU0_SA_DQ<1>")
	)
	(segment
		(start 383.467864 -279.474676)
		(end 383.458974 -279.469596)
		(width 0.088646)
		(layer "In2.Cu")
		(net "M_F_CPU0_SA_DQ<1>")
	)
	(segment
		(start 394.970254 -304.199798)
		(end 394.970254 -298.131992)
		(width 0.18288)
		(layer "In2.Cu")
		(net "M_F_CPU0_SA_DQ<1>")
	)
	(segment
		(start 413.310578 -314.23991)
		(end 413.147256 -314.403232)
		(width 0.18288)
		(layer "In2.Cu")
		(net "M_F_CPU0_SA_DQ<1>")
	)
	(segment
		(start 412.651956 -314.403232)
		(end 412.43123 -314.182506)
		(width 0.18288)
		(layer "In2.Cu")
		(net "M_F_CPU0_SA_DQ<1>")
	)
	(segment
		(start 383.052828 -278.696674)
		(end 383.028698 -278.60752)
		(width 0.088646)
		(layer "In2.Cu")
		(net "M_F_CPU0_SA_DQ<1>")
	)
	(segment
		(start 408.787346 -313.81319)
		(end 409.008326 -314.03417)
		(width 0.18288)
		(layer "In2.Cu")
		(net "M_F_CPU0_SA_DQ<1>")
	)
	(segment
		(start 389.460994 -283.229558)
		(end 388.240778 -280.284682)
		(width 0.18288)
		(layer "In2.Cu")
		(net "M_F_CPU0_SA_DQ<1>")
	)
	(segment
		(start 416.39998 -314.766198)
		(end 416.123628 -314.766198)
		(width 0.18288)
		(layer "In2.Cu")
		(net "M_F_CPU0_SA_DQ<1>")
	)
	(segment
		(start 391.40892 -292.593268)
		(end 390.325102 -289.97656)
		(width 0.18288)
		(layer "In2.Cu")
		(net "M_F_CPU0_SA_DQ<1>")
	)
	(segment
		(start 416.123628 -314.766198)
		(end 415.77514 -314.41771)
		(width 0.18288)
		(layer "In2.Cu")
		(net "M_F_CPU0_SA_DQ<1>")
	)
	(segment
		(start 417.803076 -314.50661)
		(end 417.406836 -314.11037)
		(width 0.18288)
		(layer "In2.Cu")
		(net "M_F_CPU0_SA_DQ<1>")
	)
	(segment
		(start 416.59302 -313.522106)
		(end 416.59302 -314.573158)
		(width 0.18288)
		(layer "In2.Cu")
		(net "M_F_CPU0_SA_DQ<1>")
	)
	(segment
		(start 417.406836 -314.11037)
		(end 417.406836 -313.555126)
		(width 0.18288)
		(layer "In2.Cu")
		(net "M_F_CPU0_SA_DQ<1>")
	)
	(segment
		(start 407.695908 -314.21197)
		(end 405.772366 -314.21197)
		(width 0.18288)
		(layer "In2.Cu")
		(net "M_F_CPU0_SA_DQ<1>")
	)
	(segment
		(start 409.784042 -313.528964)
		(end 409.590748 -313.33567)
		(width 0.18288)
		(layer "In2.Cu")
		(net "M_F_CPU0_SA_DQ<1>")
	)
	(segment
		(start 419.366954 -314.11037)
		(end 418.970714 -314.50661)
		(width 0.18288)
		(layer "In2.Cu")
		(net "M_F_CPU0_SA_DQ<1>")
	)
	(segment
		(start 415.20618 -314.23991)
		(end 413.310578 -314.23991)
		(width 0.18288)
		(layer "In2.Cu")
		(net "M_F_CPU0_SA_DQ<1>")
	)
	(segment
		(start 419.366954 -313.572398)
		(end 419.366954 -314.11037)
		(width 0.18288)
		(layer "In2.Cu")
		(net "M_F_CPU0_SA_DQ<1>")
	)
	(segment
		(start 383.280412 -279.150318)
		(end 383.280412 -279.140412)
		(width 0.088646)
		(layer "In2.Cu")
		(net "M_F_CPU0_SA_DQ<1>")
	)
	(segment
		(start 420.223696 -314.104274)
		(end 420.223696 -313.572398)
		(width 0.18288)
		(layer "In2.Cu")
		(net "M_F_CPU0_SA_DQ<1>")
	)
	(segment
		(start 416.75304 -313.362086)
		(end 416.59302 -313.522106)
		(width 0.18288)
		(layer "In2.Cu")
		(net "M_F_CPU0_SA_DQ<1>")
	)
	(segment
		(start 390.325102 -284.093666)
		(end 389.460994 -283.229558)
		(width 0.18288)
		(layer "In2.Cu")
		(net "M_F_CPU0_SA_DQ<1>")
	)
	(segment
		(start 420.030656 -313.379358)
		(end 419.559994 -313.379358)
		(width 0.18288)
		(layer "In2.Cu")
		(net "M_F_CPU0_SA_DQ<1>")
	)
	(segment
		(start 415.38398 -314.41771)
		(end 415.20618 -314.23991)
		(width 0.18288)
		(layer "In2.Cu")
		(net "M_F_CPU0_SA_DQ<1>")
	)
	(segment
		(start 409.96235 -314.181998)
		(end 409.784042 -314.00369)
		(width 0.18288)
		(layer "In2.Cu")
		(net "M_F_CPU0_SA_DQ<1>")
	)
	(segment
		(start 408.011884 -314.527946)
		(end 407.695908 -314.21197)
		(width 0.18288)
		(layer "In2.Cu")
		(net "M_F_CPU0_SA_DQ<1>")
	)
	(segment
		(start 404.897082 -314.126626)
		(end 394.970254 -304.199798)
		(width 0.18288)
		(layer "In2.Cu")
		(net "M_F_CPU0_SA_DQ<1>")
	)
	(segment
		(start 413.147256 -314.403232)
		(end 412.651956 -314.403232)
		(width 0.18288)
		(layer "In2.Cu")
		(net "M_F_CPU0_SA_DQ<1>")
	)
	(segment
		(start 383.028698 -278.60752)
		(end 383.185162 -278.336502)
		(width 0.088646)
		(layer "In2.Cu")
		(net "M_F_CPU0_SA_DQ<1>")
	)
	(segment
		(start 388.240778 -280.284682)
		(end 387.368542 -279.412446)
		(width 0.18288)
		(layer "In2.Cu")
		(net "M_F_CPU0_SA_DQ<1>")
	)
	(segment
		(start 418.970714 -314.50661)
		(end 417.803076 -314.50661)
		(width 0.18288)
		(layer "In2.Cu")
		(net "M_F_CPU0_SA_DQ<1>")
	)
	(segment
		(start 384.797046 -279.46604)
		(end 384.782314 -279.474676)
		(width 0.088646)
		(layer "In2.Cu")
		(net "M_F_CPU0_SA_DQ<1>")
	)
	(arc
		(start 385.722114 -279.474676)
		(mid 385.534916 -279.524819)
		(end 385.347718 -279.474676)
		(width 0.088646)
		(layer "In2.Cu")
		(net "M_F_CPU0_SA_DQ<1>")
	)
	(arc
		(start 383.458974 -279.469596)
		(mid 383.32806 -279.333236)
		(end 383.280412 -279.150318)
		(width 0.088646)
		(layer "In2.Cu")
		(net "M_F_CPU0_SA_DQ<1>")
	)
	(arc
		(start 385.347718 -279.474676)
		(mid 385.073519 -279.398841)
		(end 384.797046 -279.46604)
		(width 0.088646)
		(layer "In2.Cu")
		(net "M_F_CPU0_SA_DQ<1>")
	)
	(arc
		(start 385.979924 -279.412446)
		(mid 385.847328 -279.42826)
		(end 385.722114 -279.474676)
		(width 0.088646)
		(layer "In2.Cu")
		(net "M_F_CPU0_SA_DQ<1>")
	)
	(arc
		(start 384.407918 -279.474676)
		(mid 384.131105 -279.398806)
		(end 383.852674 -279.46858)
		(width 0.088646)
		(layer "In2.Cu")
		(net "M_F_CPU0_SA_DQ<1>")
	)
	(arc
		(start 383.84226 -279.474676)
		(mid 383.655062 -279.524819)
		(end 383.467864 -279.474676)
		(width 0.088646)
		(layer "In2.Cu")
		(net "M_F_CPU0_SA_DQ<1>")
	)
	(arc
		(start 384.782314 -279.474676)
		(mid 384.595116 -279.524819)
		(end 384.407918 -279.474676)
		(width 0.088646)
		(layer "In2.Cu")
		(net "M_F_CPU0_SA_DQ<1>")
	)
	(arc
		(start 383.280412 -279.140412)
		(mid 383.218193 -278.892095)
		(end 383.052828 -278.696674)
		(width 0.088646)
		(layer "In2.Cu")
		(net "M_F_CPU0_SA_DQ<1>")
	)
	(segment
		(start 431.898552 -294.814752)
		(end 432.15052 -295.06672)
		(width 0.20066)
		(layer "F.Cu")
		(net "M_F_CPU0_SA_DQ<19>")
	)
	(segment
		(start 424.836082 -295.06672)
		(end 425.940982 -295.06672)
		(width 0.20066)
		(layer "F.Cu")
		(net "M_F_CPU0_SA_DQ<19>")
	)
	(segment
		(start 431.514504 -294.814752)
		(end 431.898552 -294.814752)
		(width 0.20066)
		(layer "F.Cu")
		(net "M_F_CPU0_SA_DQ<19>")
	)
	(segment
		(start 383.185162 -268.56944)
		(end 383.185416 -268.569694)
		(width 0.20066)
		(layer "F.Cu")
		(net "M_F_CPU0_SA_DQ<19>")
	)
	(segment
		(start 431.280316 -295.299892)
		(end 431.280316 -295.04894)
		(width 0.20066)
		(layer "F.Cu")
		(net "M_F_CPU0_SA_DQ<19>")
	)
	(segment
		(start 432.15052 -295.06672)
		(end 433.484782 -295.06672)
		(width 0.20066)
		(layer "F.Cu")
		(net "M_F_CPU0_SA_DQ<19>")
	)
	(segment
		(start 428.375064 -295.491662)
		(end 430.382934 -295.491662)
		(width 0.1016)
		(layer "F.Cu")
		(net "M_F_CPU0_SA_DQ<19>")
	)
	(segment
		(start 383.185162 -268.033754)
		(end 383.185162 -268.56944)
		(width 0.20066)
		(layer "F.Cu")
		(net "M_F_CPU0_SA_DQ<19>")
	)
	(segment
		(start 427.639226 -295.06672)
		(end 428.07128 -295.498774)
		(width 0.20066)
		(layer "F.Cu")
		(net "M_F_CPU0_SA_DQ<19>")
	)
	(segment
		(start 431.076354 -295.503854)
		(end 431.280316 -295.299892)
		(width 0.20066)
		(layer "F.Cu")
		(net "M_F_CPU0_SA_DQ<19>")
	)
	(segment
		(start 428.07128 -295.498774)
		(end 428.363126 -295.498774)
		(width 0.20066)
		(layer "F.Cu")
		(net "M_F_CPU0_SA_DQ<19>")
	)
	(segment
		(start 425.940982 -295.06672)
		(end 427.639226 -295.06672)
		(width 0.20066)
		(layer "F.Cu")
		(net "M_F_CPU0_SA_DQ<19>")
	)
	(segment
		(start 431.280316 -295.04894)
		(end 431.514504 -294.814752)
		(width 0.20066)
		(layer "F.Cu")
		(net "M_F_CPU0_SA_DQ<19>")
	)
	(segment
		(start 430.382934 -295.491662)
		(end 430.395126 -295.503854)
		(width 0.1016)
		(layer "F.Cu")
		(net "M_F_CPU0_SA_DQ<19>")
	)
	(segment
		(start 428.363126 -295.498774)
		(end 428.367952 -295.498774)
		(width 0.101854)
		(layer "F.Cu")
		(net "M_F_CPU0_SA_DQ<19>")
	)
	(segment
		(start 428.367952 -295.498774)
		(end 428.375064 -295.491662)
		(width 0.1016)
		(layer "F.Cu")
		(net "M_F_CPU0_SA_DQ<19>")
	)
	(segment
		(start 430.395126 -295.503854)
		(end 431.076354 -295.503854)
		(width 0.20066)
		(layer "F.Cu")
		(net "M_F_CPU0_SA_DQ<19>")
	)
	(segment
		(start 422.300146 -294.90416)
		(end 422.300146 -295.279064)
		(width 0.18288)
		(layer "In2.Cu")
		(net "M_F_CPU0_SA_DQ<19>")
	)
	(segment
		(start 402.991066 -284.084522)
		(end 402.991066 -282.19146)
		(width 0.18288)
		(layer "In2.Cu")
		(net "M_F_CPU0_SA_DQ<19>")
	)
	(segment
		(start 421.291766 -294.83177)
		(end 421.10279 -294.642794)
		(width 0.18288)
		(layer "In2.Cu")
		(net "M_F_CPU0_SA_DQ<19>")
	)
	(segment
		(start 420.20236 -294.779446)
		(end 419.42512 -294.779446)
		(width 0.18288)
		(layer "In2.Cu")
		(net "M_F_CPU0_SA_DQ<19>")
	)
	(segment
		(start 412.249874 -290.51758)
		(end 411.871668 -290.51758)
		(width 0.18288)
		(layer "In2.Cu")
		(net "M_F_CPU0_SA_DQ<19>")
	)
	(segment
		(start 420.339012 -294.642794)
		(end 420.20236 -294.779446)
		(width 0.18288)
		(layer "In2.Cu")
		(net "M_F_CPU0_SA_DQ<19>")
	)
	(segment
		(start 388.840472 -268.89075)
		(end 388.158228 -268.89075)
		(width 0.088646)
		(layer "In2.Cu")
		(net "M_F_CPU0_SA_DQ<19>")
	)
	(segment
		(start 423.331386 -294.269414)
		(end 423.058336 -294.269414)
		(width 0.18288)
		(layer "In2.Cu")
		(net "M_F_CPU0_SA_DQ<19>")
	)
	(segment
		(start 408.33675 -287.264094)
		(end 408.035506 -286.96285)
		(width 0.18288)
		(layer "In2.Cu")
		(net "M_F_CPU0_SA_DQ<19>")
	)
	(segment
		(start 424.836082 -295.06672)
		(end 424.50893 -295.06672)
		(width 0.18288)
		(layer "In2.Cu")
		(net "M_F_CPU0_SA_DQ<19>")
	)
	(segment
		(start 419.342824 -294.69715)
		(end 416.77971 -294.69715)
		(width 0.18288)
		(layer "In2.Cu")
		(net "M_F_CPU0_SA_DQ<19>")
	)
	(segment
		(start 409.806394 -289.363404)
		(end 409.806394 -289.276028)
		(width 0.18288)
		(layer "In2.Cu")
		(net "M_F_CPU0_SA_DQ<19>")
	)
	(segment
		(start 394.59789 -273.064478)
		(end 390.424162 -268.89075)
		(width 0.18288)
		(layer "In2.Cu")
		(net "M_F_CPU0_SA_DQ<19>")
	)
	(segment
		(start 414.501584 -292.289992)
		(end 413.649922 -292.289992)
		(width 0.18288)
		(layer "In2.Cu")
		(net "M_F_CPU0_SA_DQ<19>")
	)
	(segment
		(start 423.524426 -295.346882)
		(end 423.524426 -294.462454)
		(width 0.18288)
		(layer "In2.Cu")
		(net "M_F_CPU0_SA_DQ<19>")
	)
	(segment
		(start 410.47797 -290.03498)
		(end 409.806394 -289.363404)
		(width 0.18288)
		(layer "In2.Cu")
		(net "M_F_CPU0_SA_DQ<19>")
	)
	(segment
		(start 423.524426 -294.462454)
		(end 423.331386 -294.269414)
		(width 0.18288)
		(layer "In2.Cu")
		(net "M_F_CPU0_SA_DQ<19>")
	)
	(segment
		(start 416.425126 -294.213534)
		(end 414.501584 -292.289992)
		(width 0.18288)
		(layer "In2.Cu")
		(net "M_F_CPU0_SA_DQ<19>")
	)
	(segment
		(start 422.61663 -294.71112)
		(end 422.493186 -294.71112)
		(width 0.18288)
		(layer "In2.Cu")
		(net "M_F_CPU0_SA_DQ<19>")
	)
	(segment
		(start 421.484806 -295.49217)
		(end 421.291766 -295.29913)
		(width 0.18288)
		(layer "In2.Cu")
		(net "M_F_CPU0_SA_DQ<19>")
	)
	(segment
		(start 388.158228 -268.89075)
		(end 388.104126 -268.944852)
		(width 0.088646)
		(layer "In2.Cu")
		(net "M_F_CPU0_SA_DQ<19>")
	)
	(segment
		(start 421.291766 -295.29913)
		(end 421.291766 -294.83177)
		(width 0.18288)
		(layer "In2.Cu")
		(net "M_F_CPU0_SA_DQ<19>")
	)
	(segment
		(start 397.288004 -275.06422)
		(end 395.288262 -273.064478)
		(width 0.18288)
		(layer "In2.Cu")
		(net "M_F_CPU0_SA_DQ<19>")
	)
	(segment
		(start 408.035506 -286.96285)
		(end 407.665428 -286.96285)
		(width 0.18288)
		(layer "In2.Cu")
		(net "M_F_CPU0_SA_DQ<19>")
	)
	(segment
		(start 398.295368 -277.495762)
		(end 397.288004 -275.06422)
		(width 0.18288)
		(layer "In2.Cu")
		(net "M_F_CPU0_SA_DQ<19>")
	)
	(segment
		(start 424.035728 -295.539922)
		(end 423.717466 -295.539922)
		(width 0.18288)
		(layer "In2.Cu")
		(net "M_F_CPU0_SA_DQ<19>")
	)
	(segment
		(start 422.08704 -295.49217)
		(end 421.484806 -295.49217)
		(width 0.18288)
		(layer "In2.Cu")
		(net "M_F_CPU0_SA_DQ<19>")
	)
	(segment
		(start 409.806394 -289.276028)
		(end 408.33675 -287.806384)
		(width 0.18288)
		(layer "In2.Cu")
		(net "M_F_CPU0_SA_DQ<19>")
	)
	(segment
		(start 402.991066 -282.19146)
		(end 398.295368 -277.495762)
		(width 0.18288)
		(layer "In2.Cu")
		(net "M_F_CPU0_SA_DQ<19>")
	)
	(segment
		(start 407.665428 -286.96285)
		(end 407.39695 -287.231328)
		(width 0.18288)
		(layer "In2.Cu")
		(net "M_F_CPU0_SA_DQ<19>")
	)
	(segment
		(start 423.058336 -294.269414)
		(end 422.61663 -294.71112)
		(width 0.18288)
		(layer "In2.Cu")
		(net "M_F_CPU0_SA_DQ<19>")
	)
	(segment
		(start 419.42512 -294.779446)
		(end 419.342824 -294.69715)
		(width 0.18288)
		(layer "In2.Cu")
		(net "M_F_CPU0_SA_DQ<19>")
	)
	(segment
		(start 388.104126 -268.944852)
		(end 387.884416 -268.944852)
		(width 0.088646)
		(layer "In2.Cu")
		(net "M_F_CPU0_SA_DQ<19>")
	)
	(segment
		(start 422.300146 -295.279064)
		(end 422.08704 -295.49217)
		(width 0.18288)
		(layer "In2.Cu")
		(net "M_F_CPU0_SA_DQ<19>")
	)
	(segment
		(start 416.425126 -294.342566)
		(end 416.425126 -294.213534)
		(width 0.18288)
		(layer "In2.Cu")
		(net "M_F_CPU0_SA_DQ<19>")
	)
	(segment
		(start 395.288262 -273.064478)
		(end 394.59789 -273.064478)
		(width 0.18288)
		(layer "In2.Cu")
		(net "M_F_CPU0_SA_DQ<19>")
	)
	(segment
		(start 411.389068 -290.03498)
		(end 410.47797 -290.03498)
		(width 0.18288)
		(layer "In2.Cu")
		(net "M_F_CPU0_SA_DQ<19>")
	)
	(segment
		(start 413.649922 -292.289992)
		(end 413.137858 -291.777928)
		(width 0.18288)
		(layer "In2.Cu")
		(net "M_F_CPU0_SA_DQ<19>")
	)
	(segment
		(start 413.137858 -291.405564)
		(end 412.249874 -290.51758)
		(width 0.18288)
		(layer "In2.Cu")
		(net "M_F_CPU0_SA_DQ<19>")
	)
	(segment
		(start 405.941022 -287.034478)
		(end 402.991066 -284.084522)
		(width 0.18288)
		(layer "In2.Cu")
		(net "M_F_CPU0_SA_DQ<19>")
	)
	(segment
		(start 413.137858 -291.777928)
		(end 413.137858 -291.405564)
		(width 0.18288)
		(layer "In2.Cu")
		(net "M_F_CPU0_SA_DQ<19>")
	)
	(segment
		(start 390.424162 -268.89075)
		(end 388.840472 -268.89075)
		(width 0.18288)
		(layer "In2.Cu")
		(net "M_F_CPU0_SA_DQ<19>")
	)
	(segment
		(start 423.717466 -295.539922)
		(end 423.524426 -295.346882)
		(width 0.18288)
		(layer "In2.Cu")
		(net "M_F_CPU0_SA_DQ<19>")
	)
	(segment
		(start 406.416002 -287.231328)
		(end 405.941022 -287.034478)
		(width 0.18288)
		(layer "In2.Cu")
		(net "M_F_CPU0_SA_DQ<19>")
	)
	(segment
		(start 383.233168 -268.795246)
		(end 383.185416 -268.569694)
		(width 0.088646)
		(layer "In2.Cu")
		(net "M_F_CPU0_SA_DQ<19>")
	)
	(segment
		(start 407.39695 -287.231328)
		(end 406.416002 -287.231328)
		(width 0.18288)
		(layer "In2.Cu")
		(net "M_F_CPU0_SA_DQ<19>")
	)
	(segment
		(start 416.77971 -294.69715)
		(end 416.425126 -294.342566)
		(width 0.18288)
		(layer "In2.Cu")
		(net "M_F_CPU0_SA_DQ<19>")
	)
	(segment
		(start 421.10279 -294.642794)
		(end 420.339012 -294.642794)
		(width 0.18288)
		(layer "In2.Cu")
		(net "M_F_CPU0_SA_DQ<19>")
	)
	(segment
		(start 383.561844 -268.826234)
		(end 383.334514 -268.864334)
		(width 0.088646)
		(layer "In2.Cu")
		(net "M_F_CPU0_SA_DQ<19>")
	)
	(segment
		(start 424.50893 -295.06672)
		(end 424.035728 -295.539922)
		(width 0.18288)
		(layer "In2.Cu")
		(net "M_F_CPU0_SA_DQ<19>")
	)
	(segment
		(start 408.33675 -287.806384)
		(end 408.33675 -287.264094)
		(width 0.18288)
		(layer "In2.Cu")
		(net "M_F_CPU0_SA_DQ<19>")
	)
	(segment
		(start 411.871668 -290.51758)
		(end 411.389068 -290.03498)
		(width 0.18288)
		(layer "In2.Cu")
		(net "M_F_CPU0_SA_DQ<19>")
	)
	(segment
		(start 422.493186 -294.71112)
		(end 422.300146 -294.90416)
		(width 0.18288)
		(layer "In2.Cu")
		(net "M_F_CPU0_SA_DQ<19>")
	)
	(arc
		(start 384.31216 -268.894052)
		(mid 384.124962 -268.944195)
		(end 383.937764 -268.894052)
		(width 0.088646)
		(layer "In2.Cu")
		(net "M_F_CPU0_SA_DQ<19>")
	)
	(arc
		(start 383.937764 -268.894052)
		(mid 383.755706 -268.827422)
		(end 383.561844 -268.826234)
		(width 0.088646)
		(layer "In2.Cu")
		(net "M_F_CPU0_SA_DQ<19>")
	)
	(arc
		(start 386.19176 -268.894052)
		(mid 386.004562 -268.944195)
		(end 385.817364 -268.894052)
		(width 0.088646)
		(layer "In2.Cu")
		(net "M_F_CPU0_SA_DQ<19>")
	)
	(arc
		(start 387.13156 -268.894052)
		(mid 386.944362 -268.944195)
		(end 386.757164 -268.894052)
		(width 0.088646)
		(layer "In2.Cu")
		(net "M_F_CPU0_SA_DQ<19>")
	)
	(arc
		(start 383.334514 -268.864334)
		(mid 383.269908 -268.850198)
		(end 383.233168 -268.795246)
		(width 0.088646)
		(layer "In2.Cu")
		(net "M_F_CPU0_SA_DQ<19>")
	)
	(arc
		(start 387.884416 -268.944852)
		(mid 387.787346 -268.931795)
		(end 387.696964 -268.894052)
		(width 0.088646)
		(layer "In2.Cu")
		(net "M_F_CPU0_SA_DQ<19>")
	)
	(arc
		(start 386.757164 -268.894052)
		(mid 386.474462 -268.818276)
		(end 386.19176 -268.894052)
		(width 0.088646)
		(layer "In2.Cu")
		(net "M_F_CPU0_SA_DQ<19>")
	)
	(arc
		(start 385.817364 -268.894052)
		(mid 385.534662 -268.818276)
		(end 385.25196 -268.894052)
		(width 0.088646)
		(layer "In2.Cu")
		(net "M_F_CPU0_SA_DQ<19>")
	)
	(arc
		(start 385.25196 -268.894052)
		(mid 385.064762 -268.944195)
		(end 384.877564 -268.894052)
		(width 0.088646)
		(layer "In2.Cu")
		(net "M_F_CPU0_SA_DQ<19>")
	)
	(arc
		(start 384.877564 -268.894052)
		(mid 384.594862 -268.818276)
		(end 384.31216 -268.894052)
		(width 0.088646)
		(layer "In2.Cu")
		(net "M_F_CPU0_SA_DQ<19>")
	)
	(arc
		(start 387.696964 -268.894052)
		(mid 387.414262 -268.818276)
		(end 387.13156 -268.894052)
		(width 0.088646)
		(layer "In2.Cu")
		(net "M_F_CPU0_SA_DQ<19>")
	)
	(segment
		(start 430.395126 -297.203876)
		(end 431.076354 -297.203876)
		(width 0.20066)
		(layer "F.Cu")
		(net "M_F_CPU0_SA_DQ<18>")
	)
	(segment
		(start 431.514504 -296.514774)
		(end 431.898552 -296.514774)
		(width 0.20066)
		(layer "F.Cu")
		(net "M_F_CPU0_SA_DQ<18>")
	)
	(segment
		(start 432.15052 -296.766742)
		(end 433.484782 -296.766742)
		(width 0.20066)
		(layer "F.Cu")
		(net "M_F_CPU0_SA_DQ<18>")
	)
	(segment
		(start 424.836082 -296.766742)
		(end 425.940982 -296.766742)
		(width 0.20066)
		(layer "F.Cu")
		(net "M_F_CPU0_SA_DQ<18>")
	)
	(segment
		(start 427.639226 -296.766742)
		(end 428.07128 -297.198796)
		(width 0.20066)
		(layer "F.Cu")
		(net "M_F_CPU0_SA_DQ<18>")
	)
	(segment
		(start 431.280316 -296.999914)
		(end 431.280316 -296.748962)
		(width 0.20066)
		(layer "F.Cu")
		(net "M_F_CPU0_SA_DQ<18>")
	)
	(segment
		(start 382.715516 -269.383256)
		(end 382.715262 -269.38351)
		(width 0.20066)
		(layer "F.Cu")
		(net "M_F_CPU0_SA_DQ<18>")
	)
	(segment
		(start 431.280316 -296.748962)
		(end 431.514504 -296.514774)
		(width 0.20066)
		(layer "F.Cu")
		(net "M_F_CPU0_SA_DQ<18>")
	)
	(segment
		(start 430.382934 -297.191684)
		(end 430.395126 -297.203876)
		(width 0.1016)
		(layer "F.Cu")
		(net "M_F_CPU0_SA_DQ<18>")
	)
	(segment
		(start 428.07128 -297.198796)
		(end 428.363126 -297.198796)
		(width 0.20066)
		(layer "F.Cu")
		(net "M_F_CPU0_SA_DQ<18>")
	)
	(segment
		(start 428.375064 -297.191684)
		(end 430.382934 -297.191684)
		(width 0.1016)
		(layer "F.Cu")
		(net "M_F_CPU0_SA_DQ<18>")
	)
	(segment
		(start 425.940982 -296.766742)
		(end 427.639226 -296.766742)
		(width 0.20066)
		(layer "F.Cu")
		(net "M_F_CPU0_SA_DQ<18>")
	)
	(segment
		(start 431.076354 -297.203876)
		(end 431.280316 -296.999914)
		(width 0.20066)
		(layer "F.Cu")
		(net "M_F_CPU0_SA_DQ<18>")
	)
	(segment
		(start 382.715516 -268.84757)
		(end 382.715516 -269.383256)
		(width 0.20066)
		(layer "F.Cu")
		(net "M_F_CPU0_SA_DQ<18>")
	)
	(segment
		(start 428.363126 -297.198796)
		(end 428.367952 -297.198796)
		(width 0.101854)
		(layer "F.Cu")
		(net "M_F_CPU0_SA_DQ<18>")
	)
	(segment
		(start 431.898552 -296.514774)
		(end 432.15052 -296.766742)
		(width 0.20066)
		(layer "F.Cu")
		(net "M_F_CPU0_SA_DQ<18>")
	)
	(segment
		(start 428.367952 -297.198796)
		(end 428.375064 -297.191684)
		(width 0.1016)
		(layer "F.Cu")
		(net "M_F_CPU0_SA_DQ<18>")
	)
	(segment
		(start 408.292046 -290.28009)
		(end 407.27249 -289.260534)
		(width 0.18288)
		(layer "In2.Cu")
		(net "M_F_CPU0_SA_DQ<18>")
	)
	(segment
		(start 409.786582 -292.276276)
		(end 409.440634 -292.276276)
		(width 0.18288)
		(layer "In2.Cu")
		(net "M_F_CPU0_SA_DQ<18>")
	)
	(segment
		(start 406.28443 -289.105848)
		(end 405.74976 -288.571178)
		(width 0.18288)
		(layer "In2.Cu")
		(net "M_F_CPU0_SA_DQ<18>")
	)
	(segment
		(start 394.841476 -274.055332)
		(end 394.611352 -274.055332)
		(width 0.18288)
		(layer "In2.Cu")
		(net "M_F_CPU0_SA_DQ<18>")
	)
	(segment
		(start 416.731196 -296.01414)
		(end 415.358326 -295.541192)
		(width 0.18288)
		(layer "In2.Cu")
		(net "M_F_CPU0_SA_DQ<18>")
	)
	(segment
		(start 383.467864 -269.707868)
		(end 383.453132 -269.699232)
		(width 0.088646)
		(layer "In2.Cu")
		(net "M_F_CPU0_SA_DQ<18>")
	)
	(segment
		(start 411.797754 -292.228778)
		(end 411.579568 -292.010592)
		(width 0.18288)
		(layer "In2.Cu")
		(net "M_F_CPU0_SA_DQ<18>")
	)
	(segment
		(start 382.407922 -269.377922)
		(end 382.41351 -269.38351)
		(width 0.088646)
		(layer "In2.Cu")
		(net "M_F_CPU0_SA_DQ<18>")
	)
	(segment
		(start 405.74976 -288.571178)
		(end 405.057864 -288.571178)
		(width 0.18288)
		(layer "In2.Cu")
		(net "M_F_CPU0_SA_DQ<18>")
	)
	(segment
		(start 410.052266 -292.010592)
		(end 409.786582 -292.276276)
		(width 0.18288)
		(layer "In2.Cu")
		(net "M_F_CPU0_SA_DQ<18>")
	)
	(segment
		(start 406.65781 -289.260534)
		(end 406.28443 -289.105848)
		(width 0.18288)
		(layer "In2.Cu")
		(net "M_F_CPU0_SA_DQ<18>")
	)
	(segment
		(start 420.247318 -296.362374)
		(end 417.07943 -296.362374)
		(width 0.18288)
		(layer "In2.Cu")
		(net "M_F_CPU0_SA_DQ<18>")
	)
	(segment
		(start 388.840472 -269.631922)
		(end 387.88467 -269.631922)
		(width 0.088646)
		(layer "In2.Cu")
		(net "M_F_CPU0_SA_DQ<18>")
	)
	(segment
		(start 411.579568 -292.010592)
		(end 410.052266 -292.010592)
		(width 0.18288)
		(layer "In2.Cu")
		(net "M_F_CPU0_SA_DQ<18>")
	)
	(segment
		(start 402.137626 -285.65094)
		(end 401.975066 -285.258256)
		(width 0.18288)
		(layer "In2.Cu")
		(net "M_F_CPU0_SA_DQ<18>")
	)
	(segment
		(start 422.71569 -296.341292)
		(end 420.2684 -296.341292)
		(width 0.18288)
		(layer "In2.Cu")
		(net "M_F_CPU0_SA_DQ<18>")
	)
	(segment
		(start 390.187942 -269.631922)
		(end 388.840472 -269.631922)
		(width 0.18288)
		(layer "In2.Cu")
		(net "M_F_CPU0_SA_DQ<18>")
	)
	(segment
		(start 413.342074 -294.544242)
		(end 412.741364 -294.003476)
		(width 0.18288)
		(layer "In2.Cu")
		(net "M_F_CPU0_SA_DQ<18>")
	)
	(segment
		(start 422.797478 -296.259504)
		(end 422.71569 -296.341292)
		(width 0.18288)
		(layer "In2.Cu")
		(net "M_F_CPU0_SA_DQ<18>")
	)
	(segment
		(start 405.057864 -288.571178)
		(end 402.137626 -285.65094)
		(width 0.18288)
		(layer "In2.Cu")
		(net "M_F_CPU0_SA_DQ<18>")
	)
	(segment
		(start 401.975066 -282.612592)
		(end 397.401288 -278.038814)
		(width 0.18288)
		(layer "In2.Cu")
		(net "M_F_CPU0_SA_DQ<18>")
	)
	(segment
		(start 397.401288 -278.038814)
		(end 396.394686 -275.608542)
		(width 0.18288)
		(layer "In2.Cu")
		(net "M_F_CPU0_SA_DQ<18>")
	)
	(segment
		(start 394.611352 -274.055332)
		(end 390.187942 -269.631922)
		(width 0.18288)
		(layer "In2.Cu")
		(net "M_F_CPU0_SA_DQ<18>")
	)
	(segment
		(start 412.741364 -294.003476)
		(end 411.797754 -293.059866)
		(width 0.18288)
		(layer "In2.Cu")
		(net "M_F_CPU0_SA_DQ<18>")
	)
	(segment
		(start 409.440634 -292.276276)
		(end 408.292046 -291.127688)
		(width 0.18288)
		(layer "In2.Cu")
		(net "M_F_CPU0_SA_DQ<18>")
	)
	(segment
		(start 385.347464 -269.707868)
		(end 385.332732 -269.699232)
		(width 0.088646)
		(layer "In2.Cu")
		(net "M_F_CPU0_SA_DQ<18>")
	)
	(segment
		(start 384.407664 -269.707868)
		(end 384.392932 -269.699232)
		(width 0.088646)
		(layer "In2.Cu")
		(net "M_F_CPU0_SA_DQ<18>")
	)
	(segment
		(start 423.260266 -296.259504)
		(end 422.797478 -296.259504)
		(width 0.18288)
		(layer "In2.Cu")
		(net "M_F_CPU0_SA_DQ<18>")
	)
	(segment
		(start 396.394686 -275.608542)
		(end 394.841476 -274.055332)
		(width 0.18288)
		(layer "In2.Cu")
		(net "M_F_CPU0_SA_DQ<18>")
	)
	(segment
		(start 408.292046 -291.127688)
		(end 408.292046 -290.28009)
		(width 0.18288)
		(layer "In2.Cu")
		(net "M_F_CPU0_SA_DQ<18>")
	)
	(segment
		(start 411.797754 -293.059866)
		(end 411.797754 -292.228778)
		(width 0.18288)
		(layer "In2.Cu")
		(net "M_F_CPU0_SA_DQ<18>")
	)
	(segment
		(start 382.528064 -269.707868)
		(end 382.519174 -269.702788)
		(width 0.088646)
		(layer "In2.Cu")
		(net "M_F_CPU0_SA_DQ<18>")
	)
	(segment
		(start 387.227064 -269.707868)
		(end 387.212332 -269.699232)
		(width 0.088646)
		(layer "In2.Cu")
		(net "M_F_CPU0_SA_DQ<18>")
	)
	(segment
		(start 386.287264 -269.707868)
		(end 386.272532 -269.699232)
		(width 0.088646)
		(layer "In2.Cu")
		(net "M_F_CPU0_SA_DQ<18>")
	)
	(segment
		(start 401.975066 -285.258256)
		(end 401.975066 -282.612592)
		(width 0.18288)
		(layer "In2.Cu")
		(net "M_F_CPU0_SA_DQ<18>")
	)
	(segment
		(start 382.41351 -269.38351)
		(end 382.715262 -269.38351)
		(width 0.088646)
		(layer "In2.Cu")
		(net "M_F_CPU0_SA_DQ<18>")
	)
	(segment
		(start 415.358326 -295.541192)
		(end 413.342074 -294.544242)
		(width 0.18288)
		(layer "In2.Cu")
		(net "M_F_CPU0_SA_DQ<18>")
	)
	(segment
		(start 417.07943 -296.362374)
		(end 416.731196 -296.01414)
		(width 0.18288)
		(layer "In2.Cu")
		(net "M_F_CPU0_SA_DQ<18>")
	)
	(segment
		(start 407.27249 -289.260534)
		(end 406.65781 -289.260534)
		(width 0.18288)
		(layer "In2.Cu")
		(net "M_F_CPU0_SA_DQ<18>")
	)
	(segment
		(start 420.2684 -296.341292)
		(end 420.247318 -296.362374)
		(width 0.18288)
		(layer "In2.Cu")
		(net "M_F_CPU0_SA_DQ<18>")
	)
	(segment
		(start 382.345184 -269.44066)
		(end 382.407922 -269.377922)
		(width 0.088646)
		(layer "In2.Cu")
		(net "M_F_CPU0_SA_DQ<18>")
	)
	(segment
		(start 424.836082 -296.766742)
		(end 423.260266 -296.259504)
		(width 0.18288)
		(layer "In2.Cu")
		(net "M_F_CPU0_SA_DQ<18>")
	)
	(arc
		(start 387.60146 -269.707868)
		(mid 387.414262 -269.758011)
		(end 387.227064 -269.707868)
		(width 0.088646)
		(layer "In2.Cu")
		(net "M_F_CPU0_SA_DQ<18>")
	)
	(arc
		(start 385.72186 -269.707868)
		(mid 385.534662 -269.758011)
		(end 385.347464 -269.707868)
		(width 0.088646)
		(layer "In2.Cu")
		(net "M_F_CPU0_SA_DQ<18>")
	)
	(arc
		(start 382.90246 -269.707868)
		(mid 382.715262 -269.758011)
		(end 382.528064 -269.707868)
		(width 0.088646)
		(layer "In2.Cu")
		(net "M_F_CPU0_SA_DQ<18>")
	)
	(arc
		(start 384.78206 -269.707868)
		(mid 384.594862 -269.758011)
		(end 384.407664 -269.707868)
		(width 0.088646)
		(layer "In2.Cu")
		(net "M_F_CPU0_SA_DQ<18>")
	)
	(arc
		(start 384.392932 -269.699232)
		(mid 384.116491 -269.632066)
		(end 383.84226 -269.707868)
		(width 0.088646)
		(layer "In2.Cu")
		(net "M_F_CPU0_SA_DQ<18>")
	)
	(arc
		(start 386.66166 -269.707868)
		(mid 386.474462 -269.758011)
		(end 386.287264 -269.707868)
		(width 0.088646)
		(layer "In2.Cu")
		(net "M_F_CPU0_SA_DQ<18>")
	)
	(arc
		(start 382.519174 -269.702788)
		(mid 382.403365 -269.590859)
		(end 382.345184 -269.44066)
		(width 0.088646)
		(layer "In2.Cu")
		(net "M_F_CPU0_SA_DQ<18>")
	)
	(arc
		(start 387.212332 -269.699232)
		(mid 386.935891 -269.632066)
		(end 386.66166 -269.707868)
		(width 0.088646)
		(layer "In2.Cu")
		(net "M_F_CPU0_SA_DQ<18>")
	)
	(arc
		(start 383.453132 -269.699232)
		(mid 383.176691 -269.632066)
		(end 382.90246 -269.707868)
		(width 0.088646)
		(layer "In2.Cu")
		(net "M_F_CPU0_SA_DQ<18>")
	)
	(arc
		(start 387.88467 -269.631922)
		(mid 387.738068 -269.65125)
		(end 387.60146 -269.707868)
		(width 0.088646)
		(layer "In2.Cu")
		(net "M_F_CPU0_SA_DQ<18>")
	)
	(arc
		(start 385.332732 -269.699232)
		(mid 385.056291 -269.632066)
		(end 384.78206 -269.707868)
		(width 0.088646)
		(layer "In2.Cu")
		(net "M_F_CPU0_SA_DQ<18>")
	)
	(arc
		(start 383.84226 -269.707868)
		(mid 383.655062 -269.758011)
		(end 383.467864 -269.707868)
		(width 0.088646)
		(layer "In2.Cu")
		(net "M_F_CPU0_SA_DQ<18>")
	)
	(arc
		(start 386.272532 -269.699232)
		(mid 385.996091 -269.632066)
		(end 385.72186 -269.707868)
		(width 0.088646)
		(layer "In2.Cu")
		(net "M_F_CPU0_SA_DQ<18>")
	)
	(segment
		(start 421.840914 -295.916604)
		(end 420.736014 -295.916604)
		(width 0.20066)
		(layer "F.Cu")
		(net "M_F_CPU0_SA_DQ<17>")
	)
	(segment
		(start 426.951394 -295.485312)
		(end 426.945044 -295.491662)
		(width 0.1016)
		(layer "F.Cu")
		(net "M_F_CPU0_SA_DQ<17>")
	)
	(segment
		(start 423.610278 -296.16527)
		(end 423.361612 -295.916604)
		(width 0.20066)
		(layer "F.Cu")
		(net "M_F_CPU0_SA_DQ<17>")
	)
	(segment
		(start 381.305562 -268.033754)
		(end 381.305562 -268.56944)
		(width 0.20066)
		(layer "F.Cu")
		(net "M_F_CPU0_SA_DQ<17>")
	)
	(segment
		(start 424.273472 -295.609772)
		(end 424.273472 -295.97731)
		(width 0.20066)
		(layer "F.Cu")
		(net "M_F_CPU0_SA_DQ<17>")
	)
	(segment
		(start 424.391582 -295.491662)
		(end 424.273472 -295.609772)
		(width 0.20066)
		(layer "F.Cu")
		(net "M_F_CPU0_SA_DQ<17>")
	)
	(segment
		(start 429.384714 -295.916604)
		(end 429.38446 -295.916858)
		(width 0.20066)
		(layer "F.Cu")
		(net "M_F_CPU0_SA_DQ<17>")
	)
	(segment
		(start 381.305562 -268.56944)
		(end 381.305816 -268.569694)
		(width 0.20066)
		(layer "F.Cu")
		(net "M_F_CPU0_SA_DQ<17>")
	)
	(segment
		(start 423.361612 -295.916604)
		(end 421.840914 -295.916604)
		(width 0.20066)
		(layer "F.Cu")
		(net "M_F_CPU0_SA_DQ<17>")
	)
	(segment
		(start 424.085512 -296.16527)
		(end 423.610278 -296.16527)
		(width 0.20066)
		(layer "F.Cu")
		(net "M_F_CPU0_SA_DQ<17>")
	)
	(segment
		(start 429.38446 -295.916858)
		(end 427.792896 -295.916858)
		(width 0.20066)
		(layer "F.Cu")
		(net "M_F_CPU0_SA_DQ<17>")
	)
	(segment
		(start 424.73626 -295.491662)
		(end 424.391582 -295.491662)
		(width 0.20066)
		(layer "F.Cu")
		(net "M_F_CPU0_SA_DQ<17>")
	)
	(segment
		(start 424.756326 -295.491662)
		(end 424.73626 -295.491662)
		(width 0.101854)
		(layer "F.Cu")
		(net "M_F_CPU0_SA_DQ<17>")
	)
	(segment
		(start 427.36135 -295.485312)
		(end 426.951394 -295.485312)
		(width 0.20066)
		(layer "F.Cu")
		(net "M_F_CPU0_SA_DQ<17>")
	)
	(segment
		(start 427.792896 -295.916858)
		(end 427.36135 -295.485312)
		(width 0.20066)
		(layer "F.Cu")
		(net "M_F_CPU0_SA_DQ<17>")
	)
	(segment
		(start 426.945044 -295.491662)
		(end 424.756326 -295.491662)
		(width 0.1016)
		(layer "F.Cu")
		(net "M_F_CPU0_SA_DQ<17>")
	)
	(segment
		(start 424.273472 -295.97731)
		(end 424.085512 -296.16527)
		(width 0.20066)
		(layer "F.Cu")
		(net "M_F_CPU0_SA_DQ<17>")
	)
	(segment
		(start 412.50616 -292.22446)
		(end 412.50616 -291.588952)
		(width 0.18288)
		(layer "In2.Cu")
		(net "M_F_CPU0_SA_DQ<17>")
	)
	(segment
		(start 418.946076 -295.830498)
		(end 417.85921 -295.830498)
		(width 0.18288)
		(layer "In2.Cu")
		(net "M_F_CPU0_SA_DQ<17>")
	)
	(segment
		(start 402.483066 -282.402026)
		(end 397.854678 -277.773638)
		(width 0.18288)
		(layer "In2.Cu")
		(net "M_F_CPU0_SA_DQ<17>")
	)
	(segment
		(start 407.569924 -287.865312)
		(end 405.861266 -287.865312)
		(width 0.18288)
		(layer "In2.Cu")
		(net "M_F_CPU0_SA_DQ<17>")
	)
	(segment
		(start 405.861266 -287.865312)
		(end 405.6634 -288.063178)
		(width 0.18288)
		(layer "In2.Cu")
		(net "M_F_CPU0_SA_DQ<17>")
	)
	(segment
		(start 419.477444 -295.29913)
		(end 418.946076 -295.830498)
		(width 0.18288)
		(layer "In2.Cu")
		(net "M_F_CPU0_SA_DQ<17>")
	)
	(segment
		(start 402.483066 -285.053278)
		(end 402.483066 -282.402026)
		(width 0.18288)
		(layer "In2.Cu")
		(net "M_F_CPU0_SA_DQ<17>")
	)
	(segment
		(start 388.840472 -269.280386)
		(end 388.385812 -269.280386)
		(width 0.088646)
		(layer "In2.Cu")
		(net "M_F_CPU0_SA_DQ<17>")
	)
	(segment
		(start 404.69312 -287.487868)
		(end 404.69312 -287.215072)
		(width 0.18288)
		(layer "In2.Cu")
		(net "M_F_CPU0_SA_DQ<17>")
	)
	(segment
		(start 412.383478 -292.347142)
		(end 412.50616 -292.22446)
		(width 0.18288)
		(layer "In2.Cu")
		(net "M_F_CPU0_SA_DQ<17>")
	)
	(segment
		(start 403.691344 -285.504128)
		(end 403.418548 -285.504128)
		(width 0.18288)
		(layer "In2.Cu")
		(net "M_F_CPU0_SA_DQ<17>")
	)
	(segment
		(start 413.31007 -293.822374)
		(end 412.383478 -292.895782)
		(width 0.18288)
		(layer "In2.Cu")
		(net "M_F_CPU0_SA_DQ<17>")
	)
	(segment
		(start 409.944824 -291.21735)
		(end 409.213304 -291.21735)
		(width 0.18288)
		(layer "In2.Cu")
		(net "M_F_CPU0_SA_DQ<17>")
	)
	(segment
		(start 403.200362 -285.722314)
		(end 402.927566 -285.722314)
		(width 0.18288)
		(layer "In2.Cu")
		(net "M_F_CPU0_SA_DQ<17>")
	)
	(segment
		(start 412.156148 -291.23894)
		(end 411.5689 -291.23894)
		(width 0.18288)
		(layer "In2.Cu")
		(net "M_F_CPU0_SA_DQ<17>")
	)
	(segment
		(start 420.736014 -295.916604)
		(end 420.11854 -295.29913)
		(width 0.18288)
		(layer "In2.Cu")
		(net "M_F_CPU0_SA_DQ<17>")
	)
	(segment
		(start 404.195534 -286.717486)
		(end 403.922738 -286.717486)
		(width 0.18288)
		(layer "In2.Cu")
		(net "M_F_CPU0_SA_DQ<17>")
	)
	(segment
		(start 396.847568 -275.342604)
		(end 395.081506 -273.576542)
		(width 0.18288)
		(layer "In2.Cu")
		(net "M_F_CPU0_SA_DQ<17>")
	)
	(segment
		(start 404.686516 -286.4993)
		(end 404.41372 -286.4993)
		(width 0.18288)
		(layer "In2.Cu")
		(net "M_F_CPU0_SA_DQ<17>")
	)
	(segment
		(start 416.577526 -295.254426)
		(end 415.145474 -293.822374)
		(width 0.18288)
		(layer "In2.Cu")
		(net "M_F_CPU0_SA_DQ<17>")
	)
	(segment
		(start 402.927566 -285.722314)
		(end 402.641816 -285.436564)
		(width 0.18288)
		(layer "In2.Cu")
		(net "M_F_CPU0_SA_DQ<17>")
	)
	(segment
		(start 395.081506 -273.576542)
		(end 394.621258 -273.576542)
		(width 0.18288)
		(layer "In2.Cu")
		(net "M_F_CPU0_SA_DQ<17>")
	)
	(segment
		(start 415.145474 -293.822374)
		(end 413.31007 -293.822374)
		(width 0.18288)
		(layer "In2.Cu")
		(net "M_F_CPU0_SA_DQ<17>")
	)
	(segment
		(start 382.907286 -269.061946)
		(end 382.900682 -269.057882)
		(width 0.088646)
		(layer "In2.Cu")
		(net "M_F_CPU0_SA_DQ<17>")
	)
	(segment
		(start 403.916134 -286.001714)
		(end 403.916134 -285.728918)
		(width 0.18288)
		(layer "In2.Cu")
		(net "M_F_CPU0_SA_DQ<17>")
	)
	(segment
		(start 405.6634 -288.063178)
		(end 405.26843 -288.063178)
		(width 0.18288)
		(layer "In2.Cu")
		(net "M_F_CPU0_SA_DQ<17>")
	)
	(segment
		(start 403.697948 -286.492696)
		(end 403.697948 -286.2199)
		(width 0.18288)
		(layer "In2.Cu")
		(net "M_F_CPU0_SA_DQ<17>")
	)
	(segment
		(start 417.283138 -295.254426)
		(end 416.577526 -295.254426)
		(width 0.18288)
		(layer "In2.Cu")
		(net "M_F_CPU0_SA_DQ<17>")
	)
	(segment
		(start 390.325102 -269.280386)
		(end 388.840472 -269.280386)
		(width 0.18288)
		(layer "In2.Cu")
		(net "M_F_CPU0_SA_DQ<17>")
	)
	(segment
		(start 411.389576 -291.418264)
		(end 410.145738 -291.418264)
		(width 0.18288)
		(layer "In2.Cu")
		(net "M_F_CPU0_SA_DQ<17>")
	)
	(segment
		(start 402.641816 -285.436564)
		(end 402.483066 -285.053278)
		(width 0.18288)
		(layer "In2.Cu")
		(net "M_F_CPU0_SA_DQ<17>")
	)
	(segment
		(start 403.418548 -285.504128)
		(end 403.200362 -285.722314)
		(width 0.18288)
		(layer "In2.Cu")
		(net "M_F_CPU0_SA_DQ<17>")
	)
	(segment
		(start 397.854678 -277.773638)
		(end 396.847568 -275.342604)
		(width 0.18288)
		(layer "In2.Cu")
		(net "M_F_CPU0_SA_DQ<17>")
	)
	(segment
		(start 404.41372 -286.4993)
		(end 404.195534 -286.717486)
		(width 0.18288)
		(layer "In2.Cu")
		(net "M_F_CPU0_SA_DQ<17>")
	)
	(segment
		(start 420.11854 -295.29913)
		(end 419.477444 -295.29913)
		(width 0.18288)
		(layer "In2.Cu")
		(net "M_F_CPU0_SA_DQ<17>")
	)
	(segment
		(start 412.50616 -291.588952)
		(end 412.156148 -291.23894)
		(width 0.18288)
		(layer "In2.Cu")
		(net "M_F_CPU0_SA_DQ<17>")
	)
	(segment
		(start 411.5689 -291.23894)
		(end 411.389576 -291.418264)
		(width 0.18288)
		(layer "In2.Cu")
		(net "M_F_CPU0_SA_DQ<17>")
	)
	(segment
		(start 394.621258 -273.576542)
		(end 390.325102 -269.280386)
		(width 0.18288)
		(layer "In2.Cu")
		(net "M_F_CPU0_SA_DQ<17>")
	)
	(segment
		(start 404.911306 -286.996886)
		(end 404.911306 -286.72409)
		(width 0.18288)
		(layer "In2.Cu")
		(net "M_F_CPU0_SA_DQ<17>")
	)
	(segment
		(start 408.862022 -290.866068)
		(end 408.862022 -289.15741)
		(width 0.18288)
		(layer "In2.Cu")
		(net "M_F_CPU0_SA_DQ<17>")
	)
	(segment
		(start 412.383478 -292.895782)
		(end 412.383478 -292.347142)
		(width 0.18288)
		(layer "In2.Cu")
		(net "M_F_CPU0_SA_DQ<17>")
	)
	(segment
		(start 403.697948 -286.2199)
		(end 403.916134 -286.001714)
		(width 0.18288)
		(layer "In2.Cu")
		(net "M_F_CPU0_SA_DQ<17>")
	)
	(segment
		(start 404.69312 -287.215072)
		(end 404.911306 -286.996886)
		(width 0.18288)
		(layer "In2.Cu")
		(net "M_F_CPU0_SA_DQ<17>")
	)
	(segment
		(start 408.862022 -289.15741)
		(end 407.569924 -287.865312)
		(width 0.18288)
		(layer "In2.Cu")
		(net "M_F_CPU0_SA_DQ<17>")
	)
	(segment
		(start 403.922738 -286.717486)
		(end 403.697948 -286.492696)
		(width 0.18288)
		(layer "In2.Cu")
		(net "M_F_CPU0_SA_DQ<17>")
	)
	(segment
		(start 409.213304 -291.21735)
		(end 408.862022 -290.866068)
		(width 0.18288)
		(layer "In2.Cu")
		(net "M_F_CPU0_SA_DQ<17>")
	)
	(segment
		(start 403.916134 -285.728918)
		(end 403.691344 -285.504128)
		(width 0.18288)
		(layer "In2.Cu")
		(net "M_F_CPU0_SA_DQ<17>")
	)
	(segment
		(start 404.911306 -286.72409)
		(end 404.686516 -286.4993)
		(width 0.18288)
		(layer "In2.Cu")
		(net "M_F_CPU0_SA_DQ<17>")
	)
	(segment
		(start 417.85921 -295.830498)
		(end 417.283138 -295.254426)
		(width 0.18288)
		(layer "In2.Cu")
		(net "M_F_CPU0_SA_DQ<17>")
	)
	(segment
		(start 405.26843 -288.063178)
		(end 404.69312 -287.487868)
		(width 0.18288)
		(layer "In2.Cu")
		(net "M_F_CPU0_SA_DQ<17>")
	)
	(segment
		(start 388.385812 -269.280386)
		(end 388.240524 -269.135098)
		(width 0.088646)
		(layer "In2.Cu")
		(net "M_F_CPU0_SA_DQ<17>")
	)
	(segment
		(start 410.145738 -291.418264)
		(end 409.944824 -291.21735)
		(width 0.18288)
		(layer "In2.Cu")
		(net "M_F_CPU0_SA_DQ<17>")
	)
	(segment
		(start 383.84226 -269.059152)
		(end 383.842514 -269.059152)
		(width 0.088646)
		(layer "In2.Cu")
		(net "M_F_CPU0_SA_DQ<17>")
	)
	(segment
		(start 388.240524 -269.135098)
		(end 387.884162 -269.135098)
		(width 0.088646)
		(layer "In2.Cu")
		(net "M_F_CPU0_SA_DQ<17>")
	)
	(arc
		(start 384.78206 -269.059152)
		(mid 384.594862 -269.009009)
		(end 384.407664 -269.059152)
		(width 0.088646)
		(layer "In2.Cu")
		(net "M_F_CPU0_SA_DQ<17>")
	)
	(arc
		(start 383.842514 -269.059152)
		(mid 383.655206 -269.009009)
		(end 383.467864 -269.059152)
		(width 0.088646)
		(layer "In2.Cu")
		(net "M_F_CPU0_SA_DQ<17>")
	)
	(arc
		(start 384.407664 -269.059152)
		(mid 384.124962 -269.134928)
		(end 383.84226 -269.059152)
		(width 0.088646)
		(layer "In2.Cu")
		(net "M_F_CPU0_SA_DQ<17>")
	)
	(arc
		(start 387.227064 -269.059152)
		(mid 386.944362 -269.134928)
		(end 386.66166 -269.059152)
		(width 0.088646)
		(layer "In2.Cu")
		(net "M_F_CPU0_SA_DQ<17>")
	)
	(arc
		(start 385.72186 -269.059152)
		(mid 385.534662 -269.009009)
		(end 385.347464 -269.059152)
		(width 0.088646)
		(layer "In2.Cu")
		(net "M_F_CPU0_SA_DQ<17>")
	)
	(arc
		(start 386.66166 -269.059152)
		(mid 386.474462 -269.009009)
		(end 386.287264 -269.059152)
		(width 0.088646)
		(layer "In2.Cu")
		(net "M_F_CPU0_SA_DQ<17>")
	)
	(arc
		(start 387.60146 -269.059152)
		(mid 387.414262 -269.009009)
		(end 387.227064 -269.059152)
		(width 0.088646)
		(layer "In2.Cu")
		(net "M_F_CPU0_SA_DQ<17>")
	)
	(arc
		(start 386.287264 -269.059152)
		(mid 386.004562 -269.134928)
		(end 385.72186 -269.059152)
		(width 0.088646)
		(layer "In2.Cu")
		(net "M_F_CPU0_SA_DQ<17>")
	)
	(arc
		(start 385.347464 -269.059152)
		(mid 385.064762 -269.134928)
		(end 384.78206 -269.059152)
		(width 0.088646)
		(layer "In2.Cu")
		(net "M_F_CPU0_SA_DQ<17>")
	)
	(arc
		(start 387.884162 -269.135098)
		(mid 387.859629 -269.13461)
		(end 387.83514 -269.133066)
		(width 0.088646)
		(layer "In2.Cu")
		(net "M_F_CPU0_SA_DQ<17>")
	)
	(arc
		(start 387.83514 -269.133066)
		(mid 387.714236 -269.108947)
		(end 387.60146 -269.059152)
		(width 0.088646)
		(layer "In2.Cu")
		(net "M_F_CPU0_SA_DQ<17>")
	)
	(arc
		(start 382.264158 -268.995398)
		(mid 382.081154 -269.018563)
		(end 381.904494 -268.965426)
		(width 0.088646)
		(layer "In2.Cu")
		(net "M_F_CPU0_SA_DQ<17>")
	)
	(arc
		(start 382.900682 -269.057882)
		(mid 382.589293 -268.956627)
		(end 382.264158 -268.995398)
		(width 0.088646)
		(layer "In2.Cu")
		(net "M_F_CPU0_SA_DQ<17>")
	)
	(arc
		(start 383.467864 -269.059152)
		(mid 383.18795 -269.134921)
		(end 382.907286 -269.061946)
		(width 0.088646)
		(layer "In2.Cu")
		(net "M_F_CPU0_SA_DQ<17>")
	)
	(arc
		(start 381.904494 -268.965426)
		(mid 381.597007 -268.779887)
		(end 381.305816 -268.569694)
		(width 0.088646)
		(layer "In2.Cu")
		(net "M_F_CPU0_SA_DQ<17>")
	)
	(segment
		(start 429.38446 -297.61688)
		(end 427.792896 -297.61688)
		(width 0.20066)
		(layer "F.Cu")
		(net "M_F_CPU0_SA_DQ<16>")
	)
	(segment
		(start 424.78325 -297.191684)
		(end 424.73626 -297.191684)
		(width 0.101854)
		(layer "F.Cu")
		(net "M_F_CPU0_SA_DQ<16>")
	)
	(segment
		(start 427.792896 -297.61688)
		(end 427.36135 -297.185334)
		(width 0.20066)
		(layer "F.Cu")
		(net "M_F_CPU0_SA_DQ<16>")
	)
	(segment
		(start 424.273472 -297.677332)
		(end 424.085512 -297.865292)
		(width 0.20066)
		(layer "F.Cu")
		(net "M_F_CPU0_SA_DQ<16>")
	)
	(segment
		(start 381.775716 -269.383256)
		(end 381.775462 -269.38351)
		(width 0.20066)
		(layer "F.Cu")
		(net "M_F_CPU0_SA_DQ<16>")
	)
	(segment
		(start 427.36135 -297.185334)
		(end 426.951394 -297.185334)
		(width 0.20066)
		(layer "F.Cu")
		(net "M_F_CPU0_SA_DQ<16>")
	)
	(segment
		(start 421.840914 -297.616626)
		(end 420.736014 -297.616626)
		(width 0.20066)
		(layer "F.Cu")
		(net "M_F_CPU0_SA_DQ<16>")
	)
	(segment
		(start 429.384714 -297.616626)
		(end 429.38446 -297.61688)
		(width 0.20066)
		(layer "F.Cu")
		(net "M_F_CPU0_SA_DQ<16>")
	)
	(segment
		(start 424.085512 -297.865292)
		(end 423.610278 -297.865292)
		(width 0.20066)
		(layer "F.Cu")
		(net "M_F_CPU0_SA_DQ<16>")
	)
	(segment
		(start 426.951394 -297.185334)
		(end 426.945044 -297.191684)
		(width 0.1016)
		(layer "F.Cu")
		(net "M_F_CPU0_SA_DQ<16>")
	)
	(segment
		(start 423.361612 -297.616626)
		(end 421.840914 -297.616626)
		(width 0.20066)
		(layer "F.Cu")
		(net "M_F_CPU0_SA_DQ<16>")
	)
	(segment
		(start 424.391582 -297.191684)
		(end 424.273472 -297.309794)
		(width 0.20066)
		(layer "F.Cu")
		(net "M_F_CPU0_SA_DQ<16>")
	)
	(segment
		(start 424.273472 -297.309794)
		(end 424.273472 -297.677332)
		(width 0.20066)
		(layer "F.Cu")
		(net "M_F_CPU0_SA_DQ<16>")
	)
	(segment
		(start 426.945044 -297.191684)
		(end 424.78325 -297.191684)
		(width 0.1016)
		(layer "F.Cu")
		(net "M_F_CPU0_SA_DQ<16>")
	)
	(segment
		(start 381.775716 -268.84757)
		(end 381.775716 -269.383256)
		(width 0.20066)
		(layer "F.Cu")
		(net "M_F_CPU0_SA_DQ<16>")
	)
	(segment
		(start 424.73626 -297.191684)
		(end 424.391582 -297.191684)
		(width 0.20066)
		(layer "F.Cu")
		(net "M_F_CPU0_SA_DQ<16>")
	)
	(segment
		(start 423.610278 -297.865292)
		(end 423.361612 -297.616626)
		(width 0.20066)
		(layer "F.Cu")
		(net "M_F_CPU0_SA_DQ<16>")
	)
	(segment
		(start 401.467066 -282.823158)
		(end 396.85214 -278.208232)
		(width 0.18288)
		(layer "In2.Cu")
		(net "M_F_CPU0_SA_DQ<16>")
	)
	(segment
		(start 382.447546 -269.881858)
		(end 382.432814 -269.873222)
		(width 0.088646)
		(layer "In2.Cu")
		(net "M_F_CPU0_SA_DQ<16>")
	)
	(segment
		(start 388.840472 -270.016986)
		(end 388.364984 -270.016986)
		(width 0.088646)
		(layer "In2.Cu")
		(net "M_F_CPU0_SA_DQ<16>")
	)
	(segment
		(start 416.735006 -297.366182)
		(end 416.735006 -297.79341)
		(width 0.18288)
		(layer "In2.Cu")
		(net "M_F_CPU0_SA_DQ<16>")
	)
	(segment
		(start 408.337004 -291.987224)
		(end 406.996646 -290.646866)
		(width 0.18288)
		(layer "In2.Cu")
		(net "M_F_CPU0_SA_DQ<16>")
	)
	(segment
		(start 418.529516 -297.85691)
		(end 418.256466 -297.85691)
		(width 0.18288)
		(layer "In2.Cu")
		(net "M_F_CPU0_SA_DQ<16>")
	)
	(segment
		(start 385.266946 -269.881858)
		(end 385.252214 -269.873222)
		(width 0.088646)
		(layer "In2.Cu")
		(net "M_F_CPU0_SA_DQ<16>")
	)
	(segment
		(start 411.723586 -296.350944)
		(end 411.512004 -296.139362)
		(width 0.18288)
		(layer "In2.Cu")
		(net "M_F_CPU0_SA_DQ<16>")
	)
	(segment
		(start 418.256466 -297.85691)
		(end 417.587176 -297.18762)
		(width 0.18288)
		(layer "In2.Cu")
		(net "M_F_CPU0_SA_DQ<16>")
	)
	(segment
		(start 415.965386 -297.74007)
		(end 415.965386 -296.61485)
		(width 0.18288)
		(layer "In2.Cu")
		(net "M_F_CPU0_SA_DQ<16>")
	)
	(segment
		(start 414.706308 -296.83202)
		(end 414.021524 -296.83202)
		(width 0.18288)
		(layer "In2.Cu")
		(net "M_F_CPU0_SA_DQ<16>")
	)
	(segment
		(start 411.995366 -294.78732)
		(end 411.431486 -294.410384)
		(width 0.18288)
		(layer "In2.Cu")
		(net "M_F_CPU0_SA_DQ<16>")
	)
	(segment
		(start 415.672016 -296.32148)
		(end 415.216848 -296.32148)
		(width 0.18288)
		(layer "In2.Cu")
		(net "M_F_CPU0_SA_DQ<16>")
	)
	(segment
		(start 411.431486 -294.410384)
		(end 409.99537 -293.81577)
		(width 0.18288)
		(layer "In2.Cu")
		(net "M_F_CPU0_SA_DQ<16>")
	)
	(segment
		(start 408.337004 -292.157404)
		(end 408.337004 -291.987224)
		(width 0.18288)
		(layer "In2.Cu")
		(net "M_F_CPU0_SA_DQ<16>")
	)
	(segment
		(start 388.364984 -270.016986)
		(end 388.170166 -269.822168)
		(width 0.088646)
		(layer "In2.Cu")
		(net "M_F_CPU0_SA_DQ<16>")
	)
	(segment
		(start 415.216848 -296.32148)
		(end 414.706308 -296.83202)
		(width 0.18288)
		(layer "In2.Cu")
		(net "M_F_CPU0_SA_DQ<16>")
	)
	(segment
		(start 412.971742 -295.782238)
		(end 412.698692 -295.782238)
		(width 0.18288)
		(layer "In2.Cu")
		(net "M_F_CPU0_SA_DQ<16>")
	)
	(segment
		(start 416.211766 -297.98645)
		(end 415.965386 -297.74007)
		(width 0.18288)
		(layer "In2.Cu")
		(net "M_F_CPU0_SA_DQ<16>")
	)
	(segment
		(start 419.357556 -297.02887)
		(end 418.529516 -297.85691)
		(width 0.18288)
		(layer "In2.Cu")
		(net "M_F_CPU0_SA_DQ<16>")
	)
	(segment
		(start 415.965386 -296.61485)
		(end 415.672016 -296.32148)
		(width 0.18288)
		(layer "In2.Cu")
		(net "M_F_CPU0_SA_DQ<16>")
	)
	(segment
		(start 395.845538 -275.778214)
		(end 390.08431 -270.016986)
		(width 0.18288)
		(layer "In2.Cu")
		(net "M_F_CPU0_SA_DQ<16>")
	)
	(segment
		(start 386.206746 -269.881858)
		(end 386.192014 -269.873222)
		(width 0.088646)
		(layer "In2.Cu")
		(net "M_F_CPU0_SA_DQ<16>")
	)
	(segment
		(start 412.129986 -296.350944)
		(end 411.723586 -296.350944)
		(width 0.18288)
		(layer "In2.Cu")
		(net "M_F_CPU0_SA_DQ<16>")
	)
	(segment
		(start 401.467066 -285.359602)
		(end 401.467066 -282.823158)
		(width 0.18288)
		(layer "In2.Cu")
		(net "M_F_CPU0_SA_DQ<16>")
	)
	(segment
		(start 382.153668 -269.448788)
		(end 382.08839 -269.38351)
		(width 0.088646)
		(layer "In2.Cu")
		(net "M_F_CPU0_SA_DQ<16>")
	)
	(segment
		(start 388.170166 -269.822168)
		(end 387.88467 -269.822168)
		(width 0.088646)
		(layer "In2.Cu")
		(net "M_F_CPU0_SA_DQ<16>")
	)
	(segment
		(start 406.162256 -290.646866)
		(end 405.699214 -290.183824)
		(width 0.18288)
		(layer "In2.Cu")
		(net "M_F_CPU0_SA_DQ<16>")
	)
	(segment
		(start 411.512004 -295.617646)
		(end 411.995366 -295.134284)
		(width 0.18288)
		(layer "In2.Cu")
		(net "M_F_CPU0_SA_DQ<16>")
	)
	(segment
		(start 416.735006 -297.79341)
		(end 416.541966 -297.98645)
		(width 0.18288)
		(layer "In2.Cu")
		(net "M_F_CPU0_SA_DQ<16>")
	)
	(segment
		(start 396.85214 -278.208232)
		(end 395.845538 -275.778214)
		(width 0.18288)
		(layer "In2.Cu")
		(net "M_F_CPU0_SA_DQ<16>")
	)
	(segment
		(start 416.913568 -297.18762)
		(end 416.735006 -297.366182)
		(width 0.18288)
		(layer "In2.Cu")
		(net "M_F_CPU0_SA_DQ<16>")
	)
	(segment
		(start 416.541966 -297.98645)
		(end 416.211766 -297.98645)
		(width 0.18288)
		(layer "In2.Cu")
		(net "M_F_CPU0_SA_DQ<16>")
	)
	(segment
		(start 411.995366 -295.134284)
		(end 411.995366 -294.78732)
		(width 0.18288)
		(layer "In2.Cu")
		(net "M_F_CPU0_SA_DQ<16>")
	)
	(segment
		(start 420.736014 -297.616626)
		(end 420.148258 -297.02887)
		(width 0.18288)
		(layer "In2.Cu")
		(net "M_F_CPU0_SA_DQ<16>")
	)
	(segment
		(start 411.512004 -296.139362)
		(end 411.512004 -295.617646)
		(width 0.18288)
		(layer "In2.Cu")
		(net "M_F_CPU0_SA_DQ<16>")
	)
	(segment
		(start 417.587176 -297.18762)
		(end 416.913568 -297.18762)
		(width 0.18288)
		(layer "In2.Cu")
		(net "M_F_CPU0_SA_DQ<16>")
	)
	(segment
		(start 382.08839 -269.38351)
		(end 381.775462 -269.38351)
		(width 0.088646)
		(layer "In2.Cu")
		(net "M_F_CPU0_SA_DQ<16>")
	)
	(segment
		(start 383.387346 -269.881858)
		(end 383.372614 -269.873222)
		(width 0.088646)
		(layer "In2.Cu")
		(net "M_F_CPU0_SA_DQ<16>")
	)
	(segment
		(start 384.327146 -269.881858)
		(end 384.312414 -269.873222)
		(width 0.088646)
		(layer "In2.Cu")
		(net "M_F_CPU0_SA_DQ<16>")
	)
	(segment
		(start 387.146546 -269.881858)
		(end 387.131814 -269.873222)
		(width 0.088646)
		(layer "In2.Cu")
		(net "M_F_CPU0_SA_DQ<16>")
	)
	(segment
		(start 414.021524 -296.83202)
		(end 412.971742 -295.782238)
		(width 0.18288)
		(layer "In2.Cu")
		(net "M_F_CPU0_SA_DQ<16>")
	)
	(segment
		(start 405.699214 -289.956748)
		(end 401.724876 -285.98241)
		(width 0.18288)
		(layer "In2.Cu")
		(net "M_F_CPU0_SA_DQ<16>")
	)
	(segment
		(start 406.996646 -290.646866)
		(end 406.162256 -290.646866)
		(width 0.18288)
		(layer "In2.Cu")
		(net "M_F_CPU0_SA_DQ<16>")
	)
	(segment
		(start 390.08431 -270.016986)
		(end 388.840472 -270.016986)
		(width 0.18288)
		(layer "In2.Cu")
		(net "M_F_CPU0_SA_DQ<16>")
	)
	(segment
		(start 412.698692 -295.782238)
		(end 412.129986 -296.350944)
		(width 0.18288)
		(layer "In2.Cu")
		(net "M_F_CPU0_SA_DQ<16>")
	)
	(segment
		(start 401.724876 -285.98241)
		(end 401.467066 -285.359602)
		(width 0.18288)
		(layer "In2.Cu")
		(net "M_F_CPU0_SA_DQ<16>")
	)
	(segment
		(start 409.99537 -293.81577)
		(end 408.337004 -292.157404)
		(width 0.18288)
		(layer "In2.Cu")
		(net "M_F_CPU0_SA_DQ<16>")
	)
	(segment
		(start 420.148258 -297.02887)
		(end 419.357556 -297.02887)
		(width 0.18288)
		(layer "In2.Cu")
		(net "M_F_CPU0_SA_DQ<16>")
	)
	(segment
		(start 405.699214 -290.183824)
		(end 405.699214 -289.956748)
		(width 0.18288)
		(layer "In2.Cu")
		(net "M_F_CPU0_SA_DQ<16>")
	)
	(arc
		(start 384.312414 -269.873222)
		(mid 384.125216 -269.823079)
		(end 383.938018 -269.873222)
		(width 0.088646)
		(layer "In2.Cu")
		(net "M_F_CPU0_SA_DQ<16>")
	)
	(arc
		(start 382.998218 -269.873222)
		(mid 382.723989 -269.949147)
		(end 382.447546 -269.881858)
		(width 0.088646)
		(layer "In2.Cu")
		(net "M_F_CPU0_SA_DQ<16>")
	)
	(arc
		(start 385.252214 -269.873222)
		(mid 385.065016 -269.823079)
		(end 384.877818 -269.873222)
		(width 0.088646)
		(layer "In2.Cu")
		(net "M_F_CPU0_SA_DQ<16>")
	)
	(arc
		(start 384.877818 -269.873222)
		(mid 384.603589 -269.949147)
		(end 384.327146 -269.881858)
		(width 0.088646)
		(layer "In2.Cu")
		(net "M_F_CPU0_SA_DQ<16>")
	)
	(arc
		(start 383.938018 -269.873222)
		(mid 383.663789 -269.949147)
		(end 383.387346 -269.881858)
		(width 0.088646)
		(layer "In2.Cu")
		(net "M_F_CPU0_SA_DQ<16>")
	)
	(arc
		(start 385.817618 -269.873222)
		(mid 385.543389 -269.949147)
		(end 385.266946 -269.881858)
		(width 0.088646)
		(layer "In2.Cu")
		(net "M_F_CPU0_SA_DQ<16>")
	)
	(arc
		(start 386.192014 -269.873222)
		(mid 386.004816 -269.823079)
		(end 385.817618 -269.873222)
		(width 0.088646)
		(layer "In2.Cu")
		(net "M_F_CPU0_SA_DQ<16>")
	)
	(arc
		(start 383.372614 -269.873222)
		(mid 383.185416 -269.823079)
		(end 382.998218 -269.873222)
		(width 0.088646)
		(layer "In2.Cu")
		(net "M_F_CPU0_SA_DQ<16>")
	)
	(arc
		(start 387.131814 -269.873222)
		(mid 386.944616 -269.823079)
		(end 386.757418 -269.873222)
		(width 0.088646)
		(layer "In2.Cu")
		(net "M_F_CPU0_SA_DQ<16>")
	)
	(arc
		(start 387.88467 -269.822168)
		(mid 387.787589 -269.835364)
		(end 387.697218 -269.873222)
		(width 0.088646)
		(layer "In2.Cu")
		(net "M_F_CPU0_SA_DQ<16>")
	)
	(arc
		(start 387.697218 -269.873222)
		(mid 387.422989 -269.949147)
		(end 387.146546 -269.881858)
		(width 0.088646)
		(layer "In2.Cu")
		(net "M_F_CPU0_SA_DQ<16>")
	)
	(arc
		(start 382.432814 -269.873222)
		(mid 382.242907 -269.694116)
		(end 382.153668 -269.448788)
		(width 0.088646)
		(layer "In2.Cu")
		(net "M_F_CPU0_SA_DQ<16>")
	)
	(arc
		(start 386.757418 -269.873222)
		(mid 386.483189 -269.949147)
		(end 386.206746 -269.881858)
		(width 0.088646)
		(layer "In2.Cu")
		(net "M_F_CPU0_SA_DQ<16>")
	)
	(segment
		(start 379.425962 -268.56944)
		(end 379.426216 -268.569694)
		(width 0.20066)
		(layer "F.Cu")
		(net "M_F_CPU0_SA_DQ<15>")
	)
	(segment
		(start 431.514504 -298.214796)
		(end 431.898552 -298.214796)
		(width 0.20066)
		(layer "F.Cu")
		(net "M_F_CPU0_SA_DQ<15>")
	)
	(segment
		(start 428.363126 -298.898818)
		(end 428.367952 -298.898818)
		(width 0.101854)
		(layer "F.Cu")
		(net "M_F_CPU0_SA_DQ<15>")
	)
	(segment
		(start 431.898552 -298.214796)
		(end 432.15052 -298.466764)
		(width 0.20066)
		(layer "F.Cu")
		(net "M_F_CPU0_SA_DQ<15>")
	)
	(segment
		(start 428.367952 -298.898818)
		(end 428.375064 -298.891706)
		(width 0.1016)
		(layer "F.Cu")
		(net "M_F_CPU0_SA_DQ<15>")
	)
	(segment
		(start 424.836082 -298.466764)
		(end 425.940982 -298.466764)
		(width 0.20066)
		(layer "F.Cu")
		(net "M_F_CPU0_SA_DQ<15>")
	)
	(segment
		(start 430.395126 -298.903898)
		(end 431.076354 -298.903898)
		(width 0.20066)
		(layer "F.Cu")
		(net "M_F_CPU0_SA_DQ<15>")
	)
	(segment
		(start 428.07128 -298.898818)
		(end 428.363126 -298.898818)
		(width 0.20066)
		(layer "F.Cu")
		(net "M_F_CPU0_SA_DQ<15>")
	)
	(segment
		(start 428.375064 -298.891706)
		(end 430.382934 -298.891706)
		(width 0.1016)
		(layer "F.Cu")
		(net "M_F_CPU0_SA_DQ<15>")
	)
	(segment
		(start 379.425962 -268.033754)
		(end 379.425962 -268.56944)
		(width 0.20066)
		(layer "F.Cu")
		(net "M_F_CPU0_SA_DQ<15>")
	)
	(segment
		(start 431.076354 -298.903898)
		(end 431.280316 -298.699936)
		(width 0.20066)
		(layer "F.Cu")
		(net "M_F_CPU0_SA_DQ<15>")
	)
	(segment
		(start 431.280316 -298.448984)
		(end 431.514504 -298.214796)
		(width 0.20066)
		(layer "F.Cu")
		(net "M_F_CPU0_SA_DQ<15>")
	)
	(segment
		(start 425.940982 -298.466764)
		(end 427.639226 -298.466764)
		(width 0.20066)
		(layer "F.Cu")
		(net "M_F_CPU0_SA_DQ<15>")
	)
	(segment
		(start 430.382934 -298.891706)
		(end 430.395126 -298.903898)
		(width 0.1016)
		(layer "F.Cu")
		(net "M_F_CPU0_SA_DQ<15>")
	)
	(segment
		(start 432.15052 -298.466764)
		(end 433.484782 -298.466764)
		(width 0.20066)
		(layer "F.Cu")
		(net "M_F_CPU0_SA_DQ<15>")
	)
	(segment
		(start 431.280316 -298.699936)
		(end 431.280316 -298.448984)
		(width 0.20066)
		(layer "F.Cu")
		(net "M_F_CPU0_SA_DQ<15>")
	)
	(segment
		(start 427.639226 -298.466764)
		(end 428.07128 -298.898818)
		(width 0.20066)
		(layer "F.Cu")
		(net "M_F_CPU0_SA_DQ<15>")
	)
	(segment
		(start 405.82723 -291.727382)
		(end 405.563578 -291.727382)
		(width 0.18288)
		(layer "In4.Cu")
		(net "M_F_CPU0_SA_DQ<15>")
	)
	(segment
		(start 412.945326 -296.27449)
		(end 411.968442 -295.297606)
		(width 0.18288)
		(layer "In4.Cu")
		(net "M_F_CPU0_SA_DQ<15>")
	)
	(segment
		(start 415.483294 -297.781726)
		(end 414.805114 -297.781726)
		(width 0.18288)
		(layer "In4.Cu")
		(net "M_F_CPU0_SA_DQ<15>")
	)
	(segment
		(start 420.479728 -299.742352)
		(end 420.218362 -300.003718)
		(width 0.18288)
		(layer "In4.Cu")
		(net "M_F_CPU0_SA_DQ<15>")
	)
	(segment
		(start 421.889682 -299.521626)
		(end 421.668956 -299.742352)
		(width 0.18288)
		(layer "In4.Cu")
		(net "M_F_CPU0_SA_DQ<15>")
	)
	(segment
		(start 422.365932 -299.521626)
		(end 421.889682 -299.521626)
		(width 0.18288)
		(layer "In4.Cu")
		(net "M_F_CPU0_SA_DQ<15>")
	)
	(segment
		(start 383.383028 -268.251432)
		(end 383.372614 -268.245336)
		(width 0.088646)
		(layer "In4.Cu")
		(net "M_F_CPU0_SA_DQ<15>")
	)
	(segment
		(start 382.064006 -268.242034)
		(end 382.052322 -268.248638)
		(width 0.088646)
		(layer "In4.Cu")
		(net "M_F_CPU0_SA_DQ<15>")
	)
	(segment
		(start 388.9502 -270.488918)
		(end 386.828792 -268.36751)
		(width 0.088646)
		(layer "In4.Cu")
		(net "M_F_CPU0_SA_DQ<15>")
	)
	(segment
		(start 411.968442 -295.297606)
		(end 411.609286 -295.297606)
		(width 0.18288)
		(layer "In4.Cu")
		(net "M_F_CPU0_SA_DQ<15>")
	)
	(segment
		(start 402.81352 -288.713672)
		(end 398.725136 -278.844248)
		(width 0.18288)
		(layer "In4.Cu")
		(net "M_F_CPU0_SA_DQ<15>")
	)
	(segment
		(start 423.335958 -299.521626)
		(end 423.033952 -299.21962)
		(width 0.18288)
		(layer "In4.Cu")
		(net "M_F_CPU0_SA_DQ<15>")
	)
	(segment
		(start 421.668956 -299.742352)
		(end 420.479728 -299.742352)
		(width 0.18288)
		(layer "In4.Cu")
		(net "M_F_CPU0_SA_DQ<15>")
	)
	(segment
		(start 413.50438 -296.27449)
		(end 412.945326 -296.27449)
		(width 0.18288)
		(layer "In4.Cu")
		(net "M_F_CPU0_SA_DQ<15>")
	)
	(segment
		(start 398.725136 -278.844248)
		(end 392.276584 -272.395696)
		(width 0.18288)
		(layer "In4.Cu")
		(net "M_F_CPU0_SA_DQ<15>")
	)
	(segment
		(start 405.395684 -291.895276)
		(end 405.137112 -291.895276)
		(width 0.18288)
		(layer "In4.Cu")
		(net "M_F_CPU0_SA_DQ<15>")
	)
	(segment
		(start 416.813746 -299.47235)
		(end 416.813746 -299.112178)
		(width 0.18288)
		(layer "In4.Cu")
		(net "M_F_CPU0_SA_DQ<15>")
	)
	(segment
		(start 423.78122 -299.521626)
		(end 423.335958 -299.521626)
		(width 0.18288)
		(layer "In4.Cu")
		(net "M_F_CPU0_SA_DQ<15>")
	)
	(segment
		(start 386.828792 -268.36751)
		(end 386.648452 -268.36751)
		(width 0.088646)
		(layer "In4.Cu")
		(net "M_F_CPU0_SA_DQ<15>")
	)
	(segment
		(start 383.001774 -268.24305)
		(end 382.997964 -268.245336)
		(width 0.088646)
		(layer "In4.Cu")
		(net "M_F_CPU0_SA_DQ<15>")
	)
	(segment
		(start 380.178818 -268.245336)
		(end 380.163832 -268.253972)
		(width 0.088646)
		(layer "In4.Cu")
		(net "M_F_CPU0_SA_DQ<15>")
	)
	(segment
		(start 382.997964 -268.245336)
		(end 382.992122 -268.248638)
		(width 0.088646)
		(layer "In4.Cu")
		(net "M_F_CPU0_SA_DQ<15>")
	)
	(segment
		(start 381.124206 -268.242034)
		(end 381.118618 -268.245336)
		(width 0.088646)
		(layer "In4.Cu")
		(net "M_F_CPU0_SA_DQ<15>")
	)
	(segment
		(start 416.813746 -299.112178)
		(end 415.483294 -297.781726)
		(width 0.18288)
		(layer "In4.Cu")
		(net "M_F_CPU0_SA_DQ<15>")
	)
	(segment
		(start 414.805114 -297.781726)
		(end 414.182306 -297.158918)
		(width 0.18288)
		(layer "In4.Cu")
		(net "M_F_CPU0_SA_DQ<15>")
	)
	(segment
		(start 417.345114 -300.003718)
		(end 416.813746 -299.47235)
		(width 0.18288)
		(layer "In4.Cu")
		(net "M_F_CPU0_SA_DQ<15>")
	)
	(segment
		(start 405.563578 -291.727382)
		(end 405.395684 -291.895276)
		(width 0.18288)
		(layer "In4.Cu")
		(net "M_F_CPU0_SA_DQ<15>")
	)
	(segment
		(start 404.90521 -291.404802)
		(end 405.075644 -291.234368)
		(width 0.18288)
		(layer "In4.Cu")
		(net "M_F_CPU0_SA_DQ<15>")
	)
	(segment
		(start 414.182306 -297.158918)
		(end 414.182306 -296.952416)
		(width 0.18288)
		(layer "In4.Cu")
		(net "M_F_CPU0_SA_DQ<15>")
	)
	(segment
		(start 422.667938 -299.21962)
		(end 422.365932 -299.521626)
		(width 0.18288)
		(layer "In4.Cu")
		(net "M_F_CPU0_SA_DQ<15>")
	)
	(segment
		(start 414.182306 -296.952416)
		(end 413.50438 -296.27449)
		(width 0.18288)
		(layer "In4.Cu")
		(net "M_F_CPU0_SA_DQ<15>")
	)
	(segment
		(start 405.075644 -290.975796)
		(end 402.81352 -288.713672)
		(width 0.18288)
		(layer "In4.Cu")
		(net "M_F_CPU0_SA_DQ<15>")
	)
	(segment
		(start 380.567946 -268.253972)
		(end 380.553214 -268.245336)
		(width 0.088646)
		(layer "In4.Cu")
		(net "M_F_CPU0_SA_DQ<15>")
	)
	(segment
		(start 424.836082 -298.466764)
		(end 423.78122 -299.521626)
		(width 0.18288)
		(layer "In4.Cu")
		(net "M_F_CPU0_SA_DQ<15>")
	)
	(segment
		(start 409.83535 -293.52367)
		(end 408.987244 -293.52367)
		(width 0.18288)
		(layer "In4.Cu")
		(net "M_F_CPU0_SA_DQ<15>")
	)
	(segment
		(start 420.218362 -300.003718)
		(end 417.345114 -300.003718)
		(width 0.18288)
		(layer "In4.Cu")
		(net "M_F_CPU0_SA_DQ<15>")
	)
	(segment
		(start 405.137112 -291.895276)
		(end 404.90521 -291.663374)
		(width 0.18288)
		(layer "In4.Cu")
		(net "M_F_CPU0_SA_DQ<15>")
	)
	(segment
		(start 405.075644 -291.234368)
		(end 405.075644 -290.975796)
		(width 0.18288)
		(layer "In4.Cu")
		(net "M_F_CPU0_SA_DQ<15>")
	)
	(segment
		(start 406.659334 -292.559486)
		(end 405.82723 -291.727382)
		(width 0.18288)
		(layer "In4.Cu")
		(net "M_F_CPU0_SA_DQ<15>")
	)
	(segment
		(start 390.856978 -272.395696)
		(end 388.9502 -270.488918)
		(width 0.18288)
		(layer "In4.Cu")
		(net "M_F_CPU0_SA_DQ<15>")
	)
	(segment
		(start 392.276584 -272.395696)
		(end 390.856978 -272.395696)
		(width 0.18288)
		(layer "In4.Cu")
		(net "M_F_CPU0_SA_DQ<15>")
	)
	(segment
		(start 408.987244 -293.52367)
		(end 406.659334 -292.559486)
		(width 0.18288)
		(layer "In4.Cu")
		(net "M_F_CPU0_SA_DQ<15>")
	)
	(segment
		(start 411.609286 -295.297606)
		(end 409.83535 -293.52367)
		(width 0.18288)
		(layer "In4.Cu")
		(net "M_F_CPU0_SA_DQ<15>")
	)
	(segment
		(start 423.033952 -299.21962)
		(end 422.667938 -299.21962)
		(width 0.18288)
		(layer "In4.Cu")
		(net "M_F_CPU0_SA_DQ<15>")
	)
	(segment
		(start 404.90521 -291.663374)
		(end 404.90521 -291.404802)
		(width 0.18288)
		(layer "In4.Cu")
		(net "M_F_CPU0_SA_DQ<15>")
	)
	(arc
		(start 384.877564 -268.245336)
		(mid 384.594862 -268.321112)
		(end 384.31216 -268.245336)
		(width 0.088646)
		(layer "In4.Cu")
		(net "M_F_CPU0_SA_DQ<15>")
	)
	(arc
		(start 382.992122 -268.248638)
		(mid 382.712017 -268.32108)
		(end 382.432814 -268.245336)
		(width 0.088646)
		(layer "In4.Cu")
		(net "M_F_CPU0_SA_DQ<15>")
	)
	(arc
		(start 382.052322 -268.248638)
		(mid 381.772217 -268.32108)
		(end 381.493014 -268.245336)
		(width 0.088646)
		(layer "In4.Cu")
		(net "M_F_CPU0_SA_DQ<15>")
	)
	(arc
		(start 385.817364 -268.245336)
		(mid 385.534662 -268.321112)
		(end 385.25196 -268.245336)
		(width 0.088646)
		(layer "In4.Cu")
		(net "M_F_CPU0_SA_DQ<15>")
	)
	(arc
		(start 380.163832 -268.253972)
		(mid 379.804967 -268.435063)
		(end 379.426216 -268.569694)
		(width 0.088646)
		(layer "In4.Cu")
		(net "M_F_CPU0_SA_DQ<15>")
	)
	(arc
		(start 383.937764 -268.245336)
		(mid 383.661205 -268.321079)
		(end 383.383028 -268.251432)
		(width 0.088646)
		(layer "In4.Cu")
		(net "M_F_CPU0_SA_DQ<15>")
	)
	(arc
		(start 386.19176 -268.245336)
		(mid 386.004562 -268.195193)
		(end 385.817364 -268.245336)
		(width 0.088646)
		(layer "In4.Cu")
		(net "M_F_CPU0_SA_DQ<15>")
	)
	(arc
		(start 384.31216 -268.245336)
		(mid 384.124962 -268.195193)
		(end 383.937764 -268.245336)
		(width 0.088646)
		(layer "In4.Cu")
		(net "M_F_CPU0_SA_DQ<15>")
	)
	(arc
		(start 381.493014 -268.245336)
		(mid 381.30906 -268.195207)
		(end 381.124206 -268.242034)
		(width 0.088646)
		(layer "In4.Cu")
		(net "M_F_CPU0_SA_DQ<15>")
	)
	(arc
		(start 386.648452 -268.36751)
		(mid 386.412072 -268.336446)
		(end 386.19176 -268.245336)
		(width 0.088646)
		(layer "In4.Cu")
		(net "M_F_CPU0_SA_DQ<15>")
	)
	(arc
		(start 380.553214 -268.245336)
		(mid 380.366016 -268.195193)
		(end 380.178818 -268.245336)
		(width 0.088646)
		(layer "In4.Cu")
		(net "M_F_CPU0_SA_DQ<15>")
	)
	(arc
		(start 385.25196 -268.245336)
		(mid 385.064762 -268.195193)
		(end 384.877564 -268.245336)
		(width 0.088646)
		(layer "In4.Cu")
		(net "M_F_CPU0_SA_DQ<15>")
	)
	(arc
		(start 382.432814 -268.245336)
		(mid 382.24886 -268.195207)
		(end 382.064006 -268.242034)
		(width 0.088646)
		(layer "In4.Cu")
		(net "M_F_CPU0_SA_DQ<15>")
	)
	(arc
		(start 381.118618 -268.245336)
		(mid 380.844419 -268.321171)
		(end 380.567946 -268.253972)
		(width 0.088646)
		(layer "In4.Cu")
		(net "M_F_CPU0_SA_DQ<15>")
	)
	(arc
		(start 383.372614 -268.245336)
		(mid 383.187493 -268.195073)
		(end 383.001774 -268.24305)
		(width 0.088646)
		(layer "In4.Cu")
		(net "M_F_CPU0_SA_DQ<15>")
	)
	(segment
		(start 425.940728 -300.166532)
		(end 425.940982 -300.166786)
		(width 0.20066)
		(layer "F.Cu")
		(net "M_F_CPU0_SA_DQ<14>")
	)
	(segment
		(start 428.375064 -300.591728)
		(end 428.367952 -300.59884)
		(width 0.1016)
		(layer "F.Cu")
		(net "M_F_CPU0_SA_DQ<14>")
	)
	(segment
		(start 431.280316 -300.149006)
		(end 431.280316 -300.399958)
		(width 0.20066)
		(layer "F.Cu")
		(net "M_F_CPU0_SA_DQ<14>")
	)
	(segment
		(start 428.363126 -300.59884)
		(end 428.07128 -300.59884)
		(width 0.20066)
		(layer "F.Cu")
		(net "M_F_CPU0_SA_DQ<14>")
	)
	(segment
		(start 431.514504 -299.914818)
		(end 431.280316 -300.149006)
		(width 0.20066)
		(layer "F.Cu")
		(net "M_F_CPU0_SA_DQ<14>")
	)
	(segment
		(start 430.395126 -300.60392)
		(end 430.382934 -300.591728)
		(width 0.1016)
		(layer "F.Cu")
		(net "M_F_CPU0_SA_DQ<14>")
	)
	(segment
		(start 431.898552 -299.914818)
		(end 431.514504 -299.914818)
		(width 0.20066)
		(layer "F.Cu")
		(net "M_F_CPU0_SA_DQ<14>")
	)
	(segment
		(start 431.076354 -300.60392)
		(end 430.395126 -300.60392)
		(width 0.20066)
		(layer "F.Cu")
		(net "M_F_CPU0_SA_DQ<14>")
	)
	(segment
		(start 427.639226 -300.166786)
		(end 425.940982 -300.166786)
		(width 0.20066)
		(layer "F.Cu")
		(net "M_F_CPU0_SA_DQ<14>")
	)
	(segment
		(start 424.836082 -300.166532)
		(end 425.940728 -300.166532)
		(width 0.20066)
		(layer "F.Cu")
		(net "M_F_CPU0_SA_DQ<14>")
	)
	(segment
		(start 428.367952 -300.59884)
		(end 428.363126 -300.59884)
		(width 0.101854)
		(layer "F.Cu")
		(net "M_F_CPU0_SA_DQ<14>")
	)
	(segment
		(start 428.07128 -300.59884)
		(end 427.639226 -300.166786)
		(width 0.20066)
		(layer "F.Cu")
		(net "M_F_CPU0_SA_DQ<14>")
	)
	(segment
		(start 379.896116 -268.84757)
		(end 379.896116 -269.383256)
		(width 0.20066)
		(layer "F.Cu")
		(net "M_F_CPU0_SA_DQ<14>")
	)
	(segment
		(start 430.382934 -300.591728)
		(end 428.375064 -300.591728)
		(width 0.1016)
		(layer "F.Cu")
		(net "M_F_CPU0_SA_DQ<14>")
	)
	(segment
		(start 433.484782 -300.166786)
		(end 432.15052 -300.166786)
		(width 0.20066)
		(layer "F.Cu")
		(net "M_F_CPU0_SA_DQ<14>")
	)
	(segment
		(start 432.15052 -300.166786)
		(end 431.898552 -299.914818)
		(width 0.20066)
		(layer "F.Cu")
		(net "M_F_CPU0_SA_DQ<14>")
	)
	(segment
		(start 379.896116 -269.383256)
		(end 379.895862 -269.38351)
		(width 0.20066)
		(layer "F.Cu")
		(net "M_F_CPU0_SA_DQ<14>")
	)
	(segment
		(start 431.280316 -300.399958)
		(end 431.076354 -300.60392)
		(width 0.20066)
		(layer "F.Cu")
		(net "M_F_CPU0_SA_DQ<14>")
	)
	(segment
		(start 424.836082 -300.166532)
		(end 423.946828 -301.055786)
		(width 0.18288)
		(layer "In4.Cu")
		(net "M_F_CPU0_SA_DQ<14>")
	)
	(segment
		(start 391.86739 -272.731484)
		(end 390.704832 -272.731484)
		(width 0.18288)
		(layer "In4.Cu")
		(net "M_F_CPU0_SA_DQ<14>")
	)
	(segment
		(start 381.118364 -268.894052)
		(end 381.112522 -268.89075)
		(width 0.088646)
		(layer "In4.Cu")
		(net "M_F_CPU0_SA_DQ<14>")
	)
	(segment
		(start 388.181342 -270.114014)
		(end 387.275578 -269.20825)
		(width 0.088646)
		(layer "In4.Cu")
		(net "M_F_CPU0_SA_DQ<14>")
	)
	(segment
		(start 422.662858 -300.59249)
		(end 422.353994 -300.59249)
		(width 0.18288)
		(layer "In4.Cu")
		(net "M_F_CPU0_SA_DQ<14>")
	)
	(segment
		(start 387.275578 -269.20825)
		(end 387.072632 -269.20825)
		(width 0.088646)
		(layer "In4.Cu")
		(net "M_F_CPU0_SA_DQ<14>")
	)
	(segment
		(start 405.840946 -293.114476)
		(end 405.498554 -292.972744)
		(width 0.18288)
		(layer "In4.Cu")
		(net "M_F_CPU0_SA_DQ<14>")
	)
	(segment
		(start 408.405584 -293.892732)
		(end 405.840946 -293.114476)
		(width 0.18288)
		(layer "In4.Cu")
		(net "M_F_CPU0_SA_DQ<14>")
	)
	(segment
		(start 404.016972 -290.621974)
		(end 403.7584 -290.621974)
		(width 0.18288)
		(layer "In4.Cu")
		(net "M_F_CPU0_SA_DQ<14>")
	)
	(segment
		(start 413.435038 -297.27271)
		(end 412.980886 -297.27271)
		(width 0.18288)
		(layer "In4.Cu")
		(net "M_F_CPU0_SA_DQ<14>")
	)
	(segment
		(start 403.323806 -290.797996)
		(end 402.834602 -290.308792)
		(width 0.18288)
		(layer "In4.Cu")
		(net "M_F_CPU0_SA_DQ<14>")
	)
	(segment
		(start 380.553214 -268.894052)
		(end 380.474728 -268.939518)
		(width 0.088646)
		(layer "In4.Cu")
		(net "M_F_CPU0_SA_DQ<14>")
	)
	(segment
		(start 415.169858 -299.00753)
		(end 413.435038 -297.27271)
		(width 0.18288)
		(layer "In4.Cu")
		(net "M_F_CPU0_SA_DQ<14>")
	)
	(segment
		(start 416.28187 -299.672502)
		(end 416.28187 -299.4406)
		(width 0.18288)
		(layer "In4.Cu")
		(net "M_F_CPU0_SA_DQ<14>")
	)
	(segment
		(start 411.732222 -296.352214)
		(end 410.278834 -294.898826)
		(width 0.18288)
		(layer "In4.Cu")
		(net "M_F_CPU0_SA_DQ<14>")
	)
	(segment
		(start 404.248874 -290.853876)
		(end 404.016972 -290.621974)
		(width 0.18288)
		(layer "In4.Cu")
		(net "M_F_CPU0_SA_DQ<14>")
	)
	(segment
		(start 412.980886 -297.27271)
		(end 412.06039 -296.352214)
		(width 0.18288)
		(layer "In4.Cu")
		(net "M_F_CPU0_SA_DQ<14>")
	)
	(segment
		(start 387.072632 -269.20825)
		(end 386.962396 -269.098014)
		(width 0.088646)
		(layer "In4.Cu")
		(net "M_F_CPU0_SA_DQ<14>")
	)
	(segment
		(start 412.06039 -296.352214)
		(end 411.732222 -296.352214)
		(width 0.18288)
		(layer "In4.Cu")
		(net "M_F_CPU0_SA_DQ<14>")
	)
	(segment
		(start 382.058164 -268.894052)
		(end 382.052322 -268.89075)
		(width 0.088646)
		(layer "In4.Cu")
		(net "M_F_CPU0_SA_DQ<14>")
	)
	(segment
		(start 405.498554 -292.972744)
		(end 404.072852 -291.547042)
		(width 0.18288)
		(layer "In4.Cu")
		(net "M_F_CPU0_SA_DQ<14>")
	)
	(segment
		(start 403.7584 -290.621974)
		(end 403.582378 -290.797996)
		(width 0.18288)
		(layer "In4.Cu")
		(net "M_F_CPU0_SA_DQ<14>")
	)
	(segment
		(start 388.706106 -270.732758)
		(end 388.181342 -270.207994)
		(width 0.088646)
		(layer "In4.Cu")
		(net "M_F_CPU0_SA_DQ<14>")
	)
	(segment
		(start 404.072852 -291.28847)
		(end 404.248874 -291.112448)
		(width 0.18288)
		(layer "In4.Cu")
		(net "M_F_CPU0_SA_DQ<14>")
	)
	(segment
		(start 404.248874 -291.112448)
		(end 404.248874 -290.853876)
		(width 0.18288)
		(layer "In4.Cu")
		(net "M_F_CPU0_SA_DQ<14>")
	)
	(segment
		(start 416.28187 -299.4406)
		(end 415.8488 -299.00753)
		(width 0.18288)
		(layer "In4.Cu")
		(net "M_F_CPU0_SA_DQ<14>")
	)
	(segment
		(start 408.798522 -294.28567)
		(end 408.405584 -293.892732)
		(width 0.18288)
		(layer "In4.Cu")
		(net "M_F_CPU0_SA_DQ<14>")
	)
	(segment
		(start 423.126154 -301.055786)
		(end 422.662858 -300.59249)
		(width 0.18288)
		(layer "In4.Cu")
		(net "M_F_CPU0_SA_DQ<14>")
	)
	(segment
		(start 422.353994 -300.59249)
		(end 421.9575 -300.988984)
		(width 0.18288)
		(layer "In4.Cu")
		(net "M_F_CPU0_SA_DQ<14>")
	)
	(segment
		(start 382.997964 -268.894052)
		(end 382.992122 -268.89075)
		(width 0.088646)
		(layer "In4.Cu")
		(net "M_F_CPU0_SA_DQ<14>")
	)
	(segment
		(start 421.60952 -300.988984)
		(end 421.213026 -300.59249)
		(width 0.18288)
		(layer "In4.Cu")
		(net "M_F_CPU0_SA_DQ<14>")
	)
	(segment
		(start 388.181342 -270.207994)
		(end 388.181342 -270.114014)
		(width 0.088646)
		(layer "In4.Cu")
		(net "M_F_CPU0_SA_DQ<14>")
	)
	(segment
		(start 421.213026 -300.59249)
		(end 417.201858 -300.59249)
		(width 0.18288)
		(layer "In4.Cu")
		(net "M_F_CPU0_SA_DQ<14>")
	)
	(segment
		(start 404.072852 -291.547042)
		(end 404.072852 -291.28847)
		(width 0.18288)
		(layer "In4.Cu")
		(net "M_F_CPU0_SA_DQ<14>")
	)
	(segment
		(start 402.834602 -290.308792)
		(end 398.162272 -279.026366)
		(width 0.18288)
		(layer "In4.Cu")
		(net "M_F_CPU0_SA_DQ<14>")
	)
	(segment
		(start 381.124206 -268.897608)
		(end 381.118364 -268.894052)
		(width 0.088646)
		(layer "In4.Cu")
		(net "M_F_CPU0_SA_DQ<14>")
	)
	(segment
		(start 423.946828 -301.055786)
		(end 423.126154 -301.055786)
		(width 0.18288)
		(layer "In4.Cu")
		(net "M_F_CPU0_SA_DQ<14>")
	)
	(segment
		(start 410.278834 -294.898826)
		(end 408.798522 -294.28567)
		(width 0.18288)
		(layer "In4.Cu")
		(net "M_F_CPU0_SA_DQ<14>")
	)
	(segment
		(start 398.162272 -279.026366)
		(end 391.86739 -272.731484)
		(width 0.18288)
		(layer "In4.Cu")
		(net "M_F_CPU0_SA_DQ<14>")
	)
	(segment
		(start 390.704832 -272.731484)
		(end 388.706106 -270.732758)
		(width 0.18288)
		(layer "In4.Cu")
		(net "M_F_CPU0_SA_DQ<14>")
	)
	(segment
		(start 383.001774 -268.896338)
		(end 382.997964 -268.894052)
		(width 0.088646)
		(layer "In4.Cu")
		(net "M_F_CPU0_SA_DQ<14>")
	)
	(segment
		(start 415.8488 -299.00753)
		(end 415.169858 -299.00753)
		(width 0.18288)
		(layer "In4.Cu")
		(net "M_F_CPU0_SA_DQ<14>")
	)
	(segment
		(start 382.064006 -268.897608)
		(end 382.058164 -268.894052)
		(width 0.088646)
		(layer "In4.Cu")
		(net "M_F_CPU0_SA_DQ<14>")
	)
	(segment
		(start 417.201858 -300.59249)
		(end 416.28187 -299.672502)
		(width 0.18288)
		(layer "In4.Cu")
		(net "M_F_CPU0_SA_DQ<14>")
	)
	(segment
		(start 403.582378 -290.797996)
		(end 403.323806 -290.797996)
		(width 0.18288)
		(layer "In4.Cu")
		(net "M_F_CPU0_SA_DQ<14>")
	)
	(segment
		(start 421.9575 -300.988984)
		(end 421.60952 -300.988984)
		(width 0.18288)
		(layer "In4.Cu")
		(net "M_F_CPU0_SA_DQ<14>")
	)
	(arc
		(start 386.962396 -269.098014)
		(mid 386.873078 -268.982645)
		(end 386.757164 -268.894052)
		(width 0.088646)
		(layer "In4.Cu")
		(net "M_F_CPU0_SA_DQ<14>")
	)
	(arc
		(start 383.372614 -268.894052)
		(mid 383.187493 -268.944315)
		(end 383.001774 -268.896338)
		(width 0.088646)
		(layer "In4.Cu")
		(net "M_F_CPU0_SA_DQ<14>")
	)
	(arc
		(start 385.817364 -268.894052)
		(mid 385.534662 -268.818276)
		(end 385.25196 -268.894052)
		(width 0.088646)
		(layer "In4.Cu")
		(net "M_F_CPU0_SA_DQ<14>")
	)
	(arc
		(start 381.112522 -268.89075)
		(mid 380.832417 -268.818308)
		(end 380.553214 -268.894052)
		(width 0.088646)
		(layer "In4.Cu")
		(net "M_F_CPU0_SA_DQ<14>")
	)
	(arc
		(start 382.052322 -268.89075)
		(mid 381.772217 -268.818308)
		(end 381.493014 -268.894052)
		(width 0.088646)
		(layer "In4.Cu")
		(net "M_F_CPU0_SA_DQ<14>")
	)
	(arc
		(start 386.19176 -268.894052)
		(mid 386.004562 -268.944195)
		(end 385.817364 -268.894052)
		(width 0.088646)
		(layer "In4.Cu")
		(net "M_F_CPU0_SA_DQ<14>")
	)
	(arc
		(start 382.992122 -268.89075)
		(mid 382.712017 -268.818308)
		(end 382.432814 -268.894052)
		(width 0.088646)
		(layer "In4.Cu")
		(net "M_F_CPU0_SA_DQ<14>")
	)
	(arc
		(start 381.493014 -268.894052)
		(mid 381.30909 -268.944306)
		(end 381.124206 -268.897608)
		(width 0.088646)
		(layer "In4.Cu")
		(net "M_F_CPU0_SA_DQ<14>")
	)
	(arc
		(start 386.757164 -268.894052)
		(mid 386.474462 -268.818276)
		(end 386.19176 -268.894052)
		(width 0.088646)
		(layer "In4.Cu")
		(net "M_F_CPU0_SA_DQ<14>")
	)
	(arc
		(start 385.25196 -268.894052)
		(mid 385.064762 -268.944195)
		(end 384.877564 -268.894052)
		(width 0.088646)
		(layer "In4.Cu")
		(net "M_F_CPU0_SA_DQ<14>")
	)
	(arc
		(start 384.31216 -268.894052)
		(mid 384.124962 -268.944195)
		(end 383.937764 -268.894052)
		(width 0.088646)
		(layer "In4.Cu")
		(net "M_F_CPU0_SA_DQ<14>")
	)
	(arc
		(start 384.877564 -268.894052)
		(mid 384.594862 -268.818276)
		(end 384.31216 -268.894052)
		(width 0.088646)
		(layer "In4.Cu")
		(net "M_F_CPU0_SA_DQ<14>")
	)
	(arc
		(start 380.474728 -268.939518)
		(mid 380.17092 -269.142773)
		(end 379.895862 -269.38351)
		(width 0.088646)
		(layer "In4.Cu")
		(net "M_F_CPU0_SA_DQ<14>")
	)
	(arc
		(start 382.432814 -268.894052)
		(mid 382.24889 -268.944306)
		(end 382.064006 -268.897608)
		(width 0.088646)
		(layer "In4.Cu")
		(net "M_F_CPU0_SA_DQ<14>")
	)
	(arc
		(start 383.937764 -268.894052)
		(mid 383.655206 -268.818403)
		(end 383.372614 -268.894052)
		(width 0.088646)
		(layer "In4.Cu")
		(net "M_F_CPU0_SA_DQ<14>")
	)
	(segment
		(start 421.840914 -299.316648)
		(end 420.736014 -299.316648)
		(width 0.20066)
		(layer "F.Cu")
		(net "M_F_CPU0_SA_DQ<13>")
	)
	(segment
		(start 424.085512 -299.565314)
		(end 423.610278 -299.565314)
		(width 0.20066)
		(layer "F.Cu")
		(net "M_F_CPU0_SA_DQ<13>")
	)
	(segment
		(start 424.391582 -298.891706)
		(end 424.273472 -299.009816)
		(width 0.20066)
		(layer "F.Cu")
		(net "M_F_CPU0_SA_DQ<13>")
	)
	(segment
		(start 424.273472 -299.377354)
		(end 424.085512 -299.565314)
		(width 0.20066)
		(layer "F.Cu")
		(net "M_F_CPU0_SA_DQ<13>")
	)
	(segment
		(start 423.610278 -299.565314)
		(end 423.361612 -299.316648)
		(width 0.20066)
		(layer "F.Cu")
		(net "M_F_CPU0_SA_DQ<13>")
	)
	(segment
		(start 423.361612 -299.316648)
		(end 421.840914 -299.316648)
		(width 0.20066)
		(layer "F.Cu")
		(net "M_F_CPU0_SA_DQ<13>")
	)
	(segment
		(start 424.273472 -299.009816)
		(end 424.273472 -299.377354)
		(width 0.20066)
		(layer "F.Cu")
		(net "M_F_CPU0_SA_DQ<13>")
	)
	(segment
		(start 378.486162 -268.56944)
		(end 378.486416 -268.569694)
		(width 0.20066)
		(layer "F.Cu")
		(net "M_F_CPU0_SA_DQ<13>")
	)
	(segment
		(start 427.792896 -299.316902)
		(end 427.36135 -298.885356)
		(width 0.20066)
		(layer "F.Cu")
		(net "M_F_CPU0_SA_DQ<13>")
	)
	(segment
		(start 424.73626 -298.891706)
		(end 424.391582 -298.891706)
		(width 0.20066)
		(layer "F.Cu")
		(net "M_F_CPU0_SA_DQ<13>")
	)
	(segment
		(start 429.384714 -299.316648)
		(end 429.38446 -299.316902)
		(width 0.20066)
		(layer "F.Cu")
		(net "M_F_CPU0_SA_DQ<13>")
	)
	(segment
		(start 426.945044 -298.891706)
		(end 424.756326 -298.891706)
		(width 0.1016)
		(layer "F.Cu")
		(net "M_F_CPU0_SA_DQ<13>")
	)
	(segment
		(start 424.756326 -298.891706)
		(end 424.73626 -298.891706)
		(width 0.101854)
		(layer "F.Cu")
		(net "M_F_CPU0_SA_DQ<13>")
	)
	(segment
		(start 427.36135 -298.885356)
		(end 426.951394 -298.885356)
		(width 0.20066)
		(layer "F.Cu")
		(net "M_F_CPU0_SA_DQ<13>")
	)
	(segment
		(start 426.951394 -298.885356)
		(end 426.945044 -298.891706)
		(width 0.1016)
		(layer "F.Cu")
		(net "M_F_CPU0_SA_DQ<13>")
	)
	(segment
		(start 378.486162 -268.033754)
		(end 378.486162 -268.56944)
		(width 0.20066)
		(layer "F.Cu")
		(net "M_F_CPU0_SA_DQ<13>")
	)
	(segment
		(start 429.38446 -299.316902)
		(end 427.792896 -299.316902)
		(width 0.20066)
		(layer "F.Cu")
		(net "M_F_CPU0_SA_DQ<13>")
	)
	(segment
		(start 418.940996 -299.188378)
		(end 417.961826 -299.188378)
		(width 0.18288)
		(layer "In4.Cu")
		(net "M_F_CPU0_SA_DQ<13>")
	)
	(segment
		(start 399.144744 -278.501094)
		(end 392.699494 -272.055844)
		(width 0.18288)
		(layer "In4.Cu")
		(net "M_F_CPU0_SA_DQ<13>")
	)
	(segment
		(start 410.786072 -293.566088)
		(end 410.785818 -293.431214)
		(width 0.18288)
		(layer "In4.Cu")
		(net "M_F_CPU0_SA_DQ<13>")
	)
	(segment
		(start 404.748238 -289.802316)
		(end 404.748238 -289.576256)
		(width 0.18288)
		(layer "In4.Cu")
		(net "M_F_CPU0_SA_DQ<13>")
	)
	(segment
		(start 404.748238 -289.576256)
		(end 404.949152 -289.375342)
		(width 0.18288)
		(layer "In4.Cu")
		(net "M_F_CPU0_SA_DQ<13>")
	)
	(segment
		(start 419.264846 -298.864528)
		(end 418.940996 -299.188378)
		(width 0.18288)
		(layer "In4.Cu")
		(net "M_F_CPU0_SA_DQ<13>")
	)
	(segment
		(start 403.708108 -288.88055)
		(end 403.708108 -288.65449)
		(width 0.18288)
		(layer "In4.Cu")
		(net "M_F_CPU0_SA_DQ<13>")
	)
	(segment
		(start 417.961826 -299.188378)
		(end 416.021774 -297.248326)
		(width 0.18288)
		(layer "In4.Cu")
		(net "M_F_CPU0_SA_DQ<13>")
	)
	(segment
		(start 413.653986 -295.67505)
		(end 413.077406 -295.67505)
		(width 0.18288)
		(layer "In4.Cu")
		(net "M_F_CPU0_SA_DQ<13>")
	)
	(segment
		(start 404.684738 -288.884868)
		(end 404.458678 -288.884868)
		(width 0.18288)
		(layer "In4.Cu")
		(net "M_F_CPU0_SA_DQ<13>")
	)
	(segment
		(start 402.327364 -286.184086)
		(end 399.144744 -278.501094)
		(width 0.18288)
		(layer "In4.Cu")
		(net "M_F_CPU0_SA_DQ<13>")
	)
	(segment
		(start 410.193236 -292.838632)
		(end 408.79522 -292.838632)
		(width 0.18288)
		(layer "In4.Cu")
		(net "M_F_CPU0_SA_DQ<13>")
	)
	(segment
		(start 386.864606 -268.12748)
		(end 386.521706 -268.12748)
		(width 0.088646)
		(layer "In4.Cu")
		(net "M_F_CPU0_SA_DQ<13>")
	)
	(segment
		(start 408.637232 -292.680644)
		(end 408.637232 -292.422072)
		(width 0.18288)
		(layer "In4.Cu")
		(net "M_F_CPU0_SA_DQ<13>")
	)
	(segment
		(start 412.104332 -294.701976)
		(end 411.777942 -294.701976)
		(width 0.18288)
		(layer "In4.Cu")
		(net "M_F_CPU0_SA_DQ<13>")
	)
	(segment
		(start 405.665686 -289.865816)
		(end 405.439626 -289.865816)
		(width 0.18288)
		(layer "In4.Cu")
		(net "M_F_CPU0_SA_DQ<13>")
	)
	(segment
		(start 404.198582 -289.144964)
		(end 403.972522 -289.144964)
		(width 0.18288)
		(layer "In4.Cu")
		(net "M_F_CPU0_SA_DQ<13>")
	)
	(segment
		(start 407.669238 -291.71265)
		(end 406.699212 -291.71265)
		(width 0.18288)
		(layer "In4.Cu")
		(net "M_F_CPU0_SA_DQ<13>")
	)
	(segment
		(start 382.907286 -268.077696)
		(end 382.896872 -268.083538)
		(width 0.088646)
		(layer "In4.Cu")
		(net "M_F_CPU0_SA_DQ<13>")
	)
	(segment
		(start 389.187182 -270.251682)
		(end 387.510528 -268.575028)
		(width 0.088646)
		(layer "In4.Cu")
		(net "M_F_CPU0_SA_DQ<13>")
	)
	(segment
		(start 419.675564 -298.864528)
		(end 419.264846 -298.864528)
		(width 0.18288)
		(layer "In4.Cu")
		(net "M_F_CPU0_SA_DQ<13>")
	)
	(segment
		(start 405.238712 -290.06673)
		(end 405.012652 -290.06673)
		(width 0.18288)
		(layer "In4.Cu")
		(net "M_F_CPU0_SA_DQ<13>")
	)
	(segment
		(start 404.949152 -289.375342)
		(end 404.949152 -289.149282)
		(width 0.18288)
		(layer "In4.Cu")
		(net "M_F_CPU0_SA_DQ<13>")
	)
	(segment
		(start 408.426412 -291.651944)
		(end 408.146758 -291.931598)
		(width 0.18288)
		(layer "In4.Cu")
		(net "M_F_CPU0_SA_DQ<13>")
	)
	(segment
		(start 406.936448 -290.311078)
		(end 406.704546 -290.079176)
		(width 0.18288)
		(layer "In4.Cu")
		(net "M_F_CPU0_SA_DQ<13>")
	)
	(segment
		(start 406.033224 -290.233354)
		(end 405.665686 -289.865816)
		(width 0.18288)
		(layer "In4.Cu")
		(net "M_F_CPU0_SA_DQ<13>")
	)
	(segment
		(start 407.888186 -291.931598)
		(end 407.669238 -291.71265)
		(width 0.18288)
		(layer "In4.Cu")
		(net "M_F_CPU0_SA_DQ<13>")
	)
	(segment
		(start 406.37587 -291.389308)
		(end 406.37587 -291.130228)
		(width 0.18288)
		(layer "In4.Cu")
		(net "M_F_CPU0_SA_DQ<13>")
	)
	(segment
		(start 408.916886 -292.142418)
		(end 408.916886 -291.883846)
		(width 0.18288)
		(layer "In4.Cu")
		(net "M_F_CPU0_SA_DQ<13>")
	)
	(segment
		(start 390.991344 -272.055844)
		(end 389.187182 -270.251682)
		(width 0.18288)
		(layer "In4.Cu")
		(net "M_F_CPU0_SA_DQ<13>")
	)
	(segment
		(start 404.458678 -288.884868)
		(end 404.198582 -289.144964)
		(width 0.18288)
		(layer "In4.Cu")
		(net "M_F_CPU0_SA_DQ<13>")
	)
	(segment
		(start 408.146758 -291.931598)
		(end 407.888186 -291.931598)
		(width 0.18288)
		(layer "In4.Cu")
		(net "M_F_CPU0_SA_DQ<13>")
	)
	(segment
		(start 416.021774 -297.248326)
		(end 415.227262 -297.248326)
		(width 0.18288)
		(layer "In4.Cu")
		(net "M_F_CPU0_SA_DQ<13>")
	)
	(segment
		(start 408.79522 -292.838632)
		(end 408.637232 -292.680644)
		(width 0.18288)
		(layer "In4.Cu")
		(net "M_F_CPU0_SA_DQ<13>")
	)
	(segment
		(start 403.972522 -289.144964)
		(end 403.708108 -288.88055)
		(width 0.18288)
		(layer "In4.Cu")
		(net "M_F_CPU0_SA_DQ<13>")
	)
	(segment
		(start 406.699212 -291.71265)
		(end 406.37587 -291.389308)
		(width 0.18288)
		(layer "In4.Cu")
		(net "M_F_CPU0_SA_DQ<13>")
	)
	(segment
		(start 405.439626 -289.865816)
		(end 405.238712 -290.06673)
		(width 0.18288)
		(layer "In4.Cu")
		(net "M_F_CPU0_SA_DQ<13>")
	)
	(segment
		(start 420.127684 -299.316648)
		(end 419.675564 -298.864528)
		(width 0.18288)
		(layer "In4.Cu")
		(net "M_F_CPU0_SA_DQ<13>")
	)
	(segment
		(start 403.708108 -288.65449)
		(end 403.968204 -288.394394)
		(width 0.18288)
		(layer "In4.Cu")
		(net "M_F_CPU0_SA_DQ<13>")
	)
	(segment
		(start 381.968756 -268.076934)
		(end 381.957072 -268.083538)
		(width 0.088646)
		(layer "In4.Cu")
		(net "M_F_CPU0_SA_DQ<13>")
	)
	(segment
		(start 406.291796 -290.233354)
		(end 406.033224 -290.233354)
		(width 0.18288)
		(layer "In4.Cu")
		(net "M_F_CPU0_SA_DQ<13>")
	)
	(segment
		(start 387.312154 -268.575028)
		(end 386.864606 -268.12748)
		(width 0.088646)
		(layer "In4.Cu")
		(net "M_F_CPU0_SA_DQ<13>")
	)
	(segment
		(start 415.227262 -297.248326)
		(end 413.653986 -295.67505)
		(width 0.18288)
		(layer "In4.Cu")
		(net "M_F_CPU0_SA_DQ<13>")
	)
	(segment
		(start 406.704546 -290.079176)
		(end 406.445974 -290.079176)
		(width 0.18288)
		(layer "In4.Cu")
		(net "M_F_CPU0_SA_DQ<13>")
	)
	(segment
		(start 408.637232 -292.422072)
		(end 408.916886 -292.142418)
		(width 0.18288)
		(layer "In4.Cu")
		(net "M_F_CPU0_SA_DQ<13>")
	)
	(segment
		(start 406.37587 -291.130228)
		(end 406.936448 -290.56965)
		(width 0.18288)
		(layer "In4.Cu")
		(net "M_F_CPU0_SA_DQ<13>")
	)
	(segment
		(start 411.777942 -294.701976)
		(end 410.786072 -293.710106)
		(width 0.18288)
		(layer "In4.Cu")
		(net "M_F_CPU0_SA_DQ<13>")
	)
	(segment
		(start 410.786072 -293.710106)
		(end 410.786072 -293.566088)
		(width 0.18288)
		(layer "In4.Cu")
		(net "M_F_CPU0_SA_DQ<13>")
	)
	(segment
		(start 410.785818 -293.431214)
		(end 410.193236 -292.838632)
		(width 0.18288)
		(layer "In4.Cu")
		(net "M_F_CPU0_SA_DQ<13>")
	)
	(segment
		(start 403.968204 -288.394394)
		(end 403.968204 -287.824926)
		(width 0.18288)
		(layer "In4.Cu")
		(net "M_F_CPU0_SA_DQ<13>")
	)
	(segment
		(start 408.684984 -291.651944)
		(end 408.426412 -291.651944)
		(width 0.18288)
		(layer "In4.Cu")
		(net "M_F_CPU0_SA_DQ<13>")
	)
	(segment
		(start 406.936448 -290.56965)
		(end 406.936448 -290.311078)
		(width 0.18288)
		(layer "In4.Cu")
		(net "M_F_CPU0_SA_DQ<13>")
	)
	(segment
		(start 404.949152 -289.149282)
		(end 404.684738 -288.884868)
		(width 0.18288)
		(layer "In4.Cu")
		(net "M_F_CPU0_SA_DQ<13>")
	)
	(segment
		(start 381.028956 -268.076934)
		(end 381.02286 -268.080236)
		(width 0.088646)
		(layer "In4.Cu")
		(net "M_F_CPU0_SA_DQ<13>")
	)
	(segment
		(start 392.699494 -272.055844)
		(end 390.991344 -272.055844)
		(width 0.18288)
		(layer "In4.Cu")
		(net "M_F_CPU0_SA_DQ<13>")
	)
	(segment
		(start 405.012652 -290.06673)
		(end 404.748238 -289.802316)
		(width 0.18288)
		(layer "In4.Cu")
		(net "M_F_CPU0_SA_DQ<13>")
	)
	(segment
		(start 406.445974 -290.079176)
		(end 406.291796 -290.233354)
		(width 0.18288)
		(layer "In4.Cu")
		(net "M_F_CPU0_SA_DQ<13>")
	)
	(segment
		(start 380.648464 -268.080236)
		(end 380.63805 -268.07414)
		(width 0.088646)
		(layer "In4.Cu")
		(net "M_F_CPU0_SA_DQ<13>")
	)
	(segment
		(start 408.916886 -291.883846)
		(end 408.684984 -291.651944)
		(width 0.18288)
		(layer "In4.Cu")
		(net "M_F_CPU0_SA_DQ<13>")
	)
	(segment
		(start 413.077406 -295.67505)
		(end 412.104332 -294.701976)
		(width 0.18288)
		(layer "In4.Cu")
		(net "M_F_CPU0_SA_DQ<13>")
	)
	(segment
		(start 403.968204 -287.824926)
		(end 402.327364 -286.184086)
		(width 0.18288)
		(layer "In4.Cu")
		(net "M_F_CPU0_SA_DQ<13>")
	)
	(segment
		(start 387.510528 -268.575028)
		(end 387.312154 -268.575028)
		(width 0.088646)
		(layer "In4.Cu")
		(net "M_F_CPU0_SA_DQ<13>")
	)
	(segment
		(start 420.736014 -299.316648)
		(end 420.127684 -299.316648)
		(width 0.18288)
		(layer "In4.Cu")
		(net "M_F_CPU0_SA_DQ<13>")
	)
	(arc
		(start 384.78206 -268.080236)
		(mid 384.594862 -268.130379)
		(end 384.407664 -268.080236)
		(width 0.088646)
		(layer "In4.Cu")
		(net "M_F_CPU0_SA_DQ<13>")
	)
	(arc
		(start 383.467864 -268.080236)
		(mid 383.18792 -268.004592)
		(end 382.907286 -268.077696)
		(width 0.088646)
		(layer "In4.Cu")
		(net "M_F_CPU0_SA_DQ<13>")
	)
	(arc
		(start 381.02286 -268.080236)
		(mid 380.835662 -268.130379)
		(end 380.648464 -268.080236)
		(width 0.088646)
		(layer "In4.Cu")
		(net "M_F_CPU0_SA_DQ<13>")
	)
	(arc
		(start 386.521706 -268.12748)
		(mid 386.400625 -268.123038)
		(end 386.287264 -268.080236)
		(width 0.088646)
		(layer "In4.Cu")
		(net "M_F_CPU0_SA_DQ<13>")
	)
	(arc
		(start 385.347464 -268.080236)
		(mid 385.064762 -268.00446)
		(end 384.78206 -268.080236)
		(width 0.088646)
		(layer "In4.Cu")
		(net "M_F_CPU0_SA_DQ<13>")
	)
	(arc
		(start 386.287264 -268.080236)
		(mid 386.004562 -268.00446)
		(end 385.72186 -268.080236)
		(width 0.088646)
		(layer "In4.Cu")
		(net "M_F_CPU0_SA_DQ<13>")
	)
	(arc
		(start 381.957072 -268.083538)
		(mid 381.772217 -268.130488)
		(end 381.588264 -268.080236)
		(width 0.088646)
		(layer "In4.Cu")
		(net "M_F_CPU0_SA_DQ<13>")
	)
	(arc
		(start 383.84226 -268.080236)
		(mid 383.655062 -268.130379)
		(end 383.467864 -268.080236)
		(width 0.088646)
		(layer "In4.Cu")
		(net "M_F_CPU0_SA_DQ<13>")
	)
	(arc
		(start 385.72186 -268.080236)
		(mid 385.534662 -268.130379)
		(end 385.347464 -268.080236)
		(width 0.088646)
		(layer "In4.Cu")
		(net "M_F_CPU0_SA_DQ<13>")
	)
	(arc
		(start 380.63805 -268.07414)
		(mid 380.359872 -268.004417)
		(end 380.083314 -268.080236)
		(width 0.088646)
		(layer "In4.Cu")
		(net "M_F_CPU0_SA_DQ<13>")
	)
	(arc
		(start 380.083314 -268.080236)
		(mid 379.896116 -268.130379)
		(end 379.708918 -268.080236)
		(width 0.088646)
		(layer "In4.Cu")
		(net "M_F_CPU0_SA_DQ<13>")
	)
	(arc
		(start 382.896872 -268.083538)
		(mid 382.712017 -268.130488)
		(end 382.528064 -268.080236)
		(width 0.088646)
		(layer "In4.Cu")
		(net "M_F_CPU0_SA_DQ<13>")
	)
	(arc
		(start 379.110494 -268.228826)
		(mid 378.842926 -268.480688)
		(end 378.486416 -268.569694)
		(width 0.088646)
		(layer "In4.Cu")
		(net "M_F_CPU0_SA_DQ<13>")
	)
	(arc
		(start 379.708918 -268.080236)
		(mid 379.379786 -268.033905)
		(end 379.110494 -268.228826)
		(width 0.088646)
		(layer "In4.Cu")
		(net "M_F_CPU0_SA_DQ<13>")
	)
	(arc
		(start 382.528064 -268.080236)
		(mid 382.248861 -268.004596)
		(end 381.968756 -268.076934)
		(width 0.088646)
		(layer "In4.Cu")
		(net "M_F_CPU0_SA_DQ<13>")
	)
	(arc
		(start 384.407664 -268.080236)
		(mid 384.124962 -268.00446)
		(end 383.84226 -268.080236)
		(width 0.088646)
		(layer "In4.Cu")
		(net "M_F_CPU0_SA_DQ<13>")
	)
	(arc
		(start 381.588264 -268.080236)
		(mid 381.309061 -268.004596)
		(end 381.028956 -268.076934)
		(width 0.088646)
		(layer "In4.Cu")
		(net "M_F_CPU0_SA_DQ<13>")
	)
	(segment
		(start 424.273472 -301.077376)
		(end 424.085512 -301.265336)
		(width 0.20066)
		(layer "F.Cu")
		(net "M_F_CPU0_SA_DQ<12>")
	)
	(segment
		(start 423.361612 -301.01667)
		(end 421.840914 -301.01667)
		(width 0.20066)
		(layer "F.Cu")
		(net "M_F_CPU0_SA_DQ<12>")
	)
	(segment
		(start 423.610278 -301.265336)
		(end 423.361612 -301.01667)
		(width 0.20066)
		(layer "F.Cu")
		(net "M_F_CPU0_SA_DQ<12>")
	)
	(segment
		(start 427.792896 -301.016924)
		(end 427.36135 -300.585378)
		(width 0.20066)
		(layer "F.Cu")
		(net "M_F_CPU0_SA_DQ<12>")
	)
	(segment
		(start 424.085512 -301.265336)
		(end 423.610278 -301.265336)
		(width 0.20066)
		(layer "F.Cu")
		(net "M_F_CPU0_SA_DQ<12>")
	)
	(segment
		(start 427.36135 -300.585378)
		(end 426.951394 -300.585378)
		(width 0.20066)
		(layer "F.Cu")
		(net "M_F_CPU0_SA_DQ<12>")
	)
	(segment
		(start 424.78325 -300.591728)
		(end 424.73626 -300.591728)
		(width 0.101854)
		(layer "F.Cu")
		(net "M_F_CPU0_SA_DQ<12>")
	)
	(segment
		(start 378.016516 -269.383256)
		(end 378.016262 -269.38351)
		(width 0.20066)
		(layer "F.Cu")
		(net "M_F_CPU0_SA_DQ<12>")
	)
	(segment
		(start 426.945044 -300.591728)
		(end 424.78325 -300.591728)
		(width 0.1016)
		(layer "F.Cu")
		(net "M_F_CPU0_SA_DQ<12>")
	)
	(segment
		(start 424.73626 -300.591728)
		(end 424.391582 -300.591728)
		(width 0.20066)
		(layer "F.Cu")
		(net "M_F_CPU0_SA_DQ<12>")
	)
	(segment
		(start 429.384714 -301.01667)
		(end 429.38446 -301.016924)
		(width 0.20066)
		(layer "F.Cu")
		(net "M_F_CPU0_SA_DQ<12>")
	)
	(segment
		(start 378.016516 -268.84757)
		(end 378.016516 -269.383256)
		(width 0.20066)
		(layer "F.Cu")
		(net "M_F_CPU0_SA_DQ<12>")
	)
	(segment
		(start 424.273472 -300.709838)
		(end 424.273472 -301.077376)
		(width 0.20066)
		(layer "F.Cu")
		(net "M_F_CPU0_SA_DQ<12>")
	)
	(segment
		(start 424.391582 -300.591728)
		(end 424.273472 -300.709838)
		(width 0.20066)
		(layer "F.Cu")
		(net "M_F_CPU0_SA_DQ<12>")
	)
	(segment
		(start 429.38446 -301.016924)
		(end 427.792896 -301.016924)
		(width 0.20066)
		(layer "F.Cu")
		(net "M_F_CPU0_SA_DQ<12>")
	)
	(segment
		(start 426.951394 -300.585378)
		(end 426.945044 -300.591728)
		(width 0.1016)
		(layer "F.Cu")
		(net "M_F_CPU0_SA_DQ<12>")
	)
	(segment
		(start 421.840914 -301.01667)
		(end 420.736014 -301.01667)
		(width 0.20066)
		(layer "F.Cu")
		(net "M_F_CPU0_SA_DQ<12>")
	)
	(segment
		(start 408.819858 -294.844724)
		(end 408.520646 -294.720772)
		(width 0.18288)
		(layer "In4.Cu")
		(net "M_F_CPU0_SA_DQ<12>")
	)
	(segment
		(start 409.55976 -295.348914)
		(end 409.45054 -295.612566)
		(width 0.18288)
		(layer "In4.Cu")
		(net "M_F_CPU0_SA_DQ<12>")
	)
	(segment
		(start 386.791962 -269.184628)
		(end 386.789676 -269.180818)
		(width 0.088646)
		(layer "In4.Cu")
		(net "M_F_CPU0_SA_DQ<12>")
	)
	(segment
		(start 418.181282 -301.112936)
		(end 417.816792 -301.477426)
		(width 0.18288)
		(layer "In4.Cu")
		(net "M_F_CPU0_SA_DQ<12>")
	)
	(segment
		(start 406.656286 -293.929562)
		(end 405.148288 -293.472108)
		(width 0.18288)
		(layer "In4.Cu")
		(net "M_F_CPU0_SA_DQ<12>")
	)
	(segment
		(start 407.202386 -294.487092)
		(end 406.906476 -294.397176)
		(width 0.18288)
		(layer "In4.Cu")
		(net "M_F_CPU0_SA_DQ<12>")
	)
	(segment
		(start 411.109922 -297.122342)
		(end 411.109922 -296.508678)
		(width 0.18288)
		(layer "In4.Cu")
		(net "M_F_CPU0_SA_DQ<12>")
	)
	(segment
		(start 411.332172 -297.344592)
		(end 411.109922 -297.122342)
		(width 0.18288)
		(layer "In4.Cu")
		(net "M_F_CPU0_SA_DQ<12>")
	)
	(segment
		(start 415.524696 -299.616622)
		(end 414.591754 -299.616622)
		(width 0.18288)
		(layer "In4.Cu")
		(net "M_F_CPU0_SA_DQ<12>")
	)
	(segment
		(start 380.453392 -269.243556)
		(end 380.41326 -269.340838)
		(width 0.088646)
		(layer "In4.Cu")
		(net "M_F_CPU0_SA_DQ<12>")
	)
	(segment
		(start 388.45236 -270.986758)
		(end 387.9469 -270.481298)
		(width 0.088646)
		(layer "In4.Cu")
		(net "M_F_CPU0_SA_DQ<12>")
	)
	(segment
		(start 387.66115 -270.045688)
		(end 387.51129 -270.045688)
		(width 0.088646)
		(layer "In4.Cu")
		(net "M_F_CPU0_SA_DQ<12>")
	)
	(segment
		(start 409.45054 -295.612566)
		(end 409.212034 -295.711626)
		(width 0.18288)
		(layer "In4.Cu")
		(net "M_F_CPU0_SA_DQ<12>")
	)
	(segment
		(start 415.852356 -300.515528)
		(end 415.852356 -299.944282)
		(width 0.18288)
		(layer "In4.Cu")
		(net "M_F_CPU0_SA_DQ<12>")
	)
	(segment
		(start 408.520646 -294.720772)
		(end 408.196288 -294.396414)
		(width 0.18288)
		(layer "In4.Cu")
		(net "M_F_CPU0_SA_DQ<12>")
	)
	(segment
		(start 420.736014 -301.01667)
		(end 420.11219 -301.01667)
		(width 0.18288)
		(layer "In4.Cu")
		(net "M_F_CPU0_SA_DQ<12>")
	)
	(segment
		(start 405.148288 -293.472108)
		(end 402.009102 -290.332922)
		(width 0.18288)
		(layer "In4.Cu")
		(net "M_F_CPU0_SA_DQ<12>")
	)
	(segment
		(start 380.550166 -269.13459)
		(end 380.47803 -269.206726)
		(width 0.088646)
		(layer "In4.Cu")
		(net "M_F_CPU0_SA_DQ<12>")
	)
	(segment
		(start 382.902714 -269.059152)
		(end 382.896872 -269.05585)
		(width 0.088646)
		(layer "In4.Cu")
		(net "M_F_CPU0_SA_DQ<12>")
	)
	(segment
		(start 387.9469 -270.481298)
		(end 387.840728 -270.225266)
		(width 0.088646)
		(layer "In4.Cu")
		(net "M_F_CPU0_SA_DQ<12>")
	)
	(segment
		(start 409.212034 -295.711626)
		(end 408.908758 -295.585896)
		(width 0.18288)
		(layer "In4.Cu")
		(net "M_F_CPU0_SA_DQ<12>")
	)
	(segment
		(start 411.109922 -296.508678)
		(end 410.90469 -296.303446)
		(width 0.18288)
		(layer "In4.Cu")
		(net "M_F_CPU0_SA_DQ<12>")
	)
	(segment
		(start 411.585664 -297.344592)
		(end 411.332172 -297.344592)
		(width 0.18288)
		(layer "In4.Cu")
		(net "M_F_CPU0_SA_DQ<12>")
	)
	(segment
		(start 378.110242 -269.38351)
		(end 378.016262 -269.38351)
		(width 0.088646)
		(layer "In4.Cu")
		(net "M_F_CPU0_SA_DQ<12>")
	)
	(segment
		(start 381.028956 -269.062708)
		(end 381.023114 -269.059152)
		(width 0.088646)
		(layer "In4.Cu")
		(net "M_F_CPU0_SA_DQ<12>")
	)
	(segment
		(start 410.33573 -296.120566)
		(end 410.33573 -295.689274)
		(width 0.18288)
		(layer "In4.Cu")
		(net "M_F_CPU0_SA_DQ<12>")
	)
	(segment
		(start 381.962914 -269.059152)
		(end 381.957072 -269.05585)
		(width 0.088646)
		(layer "In4.Cu")
		(net "M_F_CPU0_SA_DQ<12>")
	)
	(segment
		(start 397.249142 -278.842216)
		(end 391.480548 -273.073622)
		(width 0.18288)
		(layer "In4.Cu")
		(net "M_F_CPU0_SA_DQ<12>")
	)
	(segment
		(start 406.906476 -294.397176)
		(end 406.656286 -293.929562)
		(width 0.18288)
		(layer "In4.Cu")
		(net "M_F_CPU0_SA_DQ<12>")
	)
	(segment
		(start 418.440362 -301.112936)
		(end 418.181282 -301.112936)
		(width 0.18288)
		(layer "In4.Cu")
		(net "M_F_CPU0_SA_DQ<12>")
	)
	(segment
		(start 416.814254 -301.477426)
		(end 415.852356 -300.515528)
		(width 0.18288)
		(layer "In4.Cu")
		(net "M_F_CPU0_SA_DQ<12>")
	)
	(segment
		(start 382.907286 -269.061946)
		(end 382.902714 -269.059152)
		(width 0.088646)
		(layer "In4.Cu")
		(net "M_F_CPU0_SA_DQ<12>")
	)
	(segment
		(start 415.852356 -299.944282)
		(end 415.524696 -299.616622)
		(width 0.18288)
		(layer "In4.Cu")
		(net "M_F_CPU0_SA_DQ<12>")
	)
	(segment
		(start 387.840728 -270.225266)
		(end 387.66115 -270.045688)
		(width 0.088646)
		(layer "In4.Cu")
		(net "M_F_CPU0_SA_DQ<12>")
	)
	(segment
		(start 407.67 -294.236648)
		(end 407.202386 -294.487092)
		(width 0.18288)
		(layer "In4.Cu")
		(net "M_F_CPU0_SA_DQ<12>")
	)
	(segment
		(start 413.705294 -298.259246)
		(end 413.39516 -297.949112)
		(width 0.18288)
		(layer "In4.Cu")
		(net "M_F_CPU0_SA_DQ<12>")
	)
	(segment
		(start 408.196288 -294.396414)
		(end 407.67 -294.236648)
		(width 0.18288)
		(layer "In4.Cu")
		(net "M_F_CPU0_SA_DQ<12>")
	)
	(segment
		(start 410.33573 -295.689274)
		(end 409.96616 -295.319704)
		(width 0.18288)
		(layer "In4.Cu")
		(net "M_F_CPU0_SA_DQ<12>")
	)
	(segment
		(start 412.075376 -297.11396)
		(end 411.816296 -297.11396)
		(width 0.18288)
		(layer "In4.Cu")
		(net "M_F_CPU0_SA_DQ<12>")
	)
	(segment
		(start 410.51861 -296.303446)
		(end 410.33573 -296.120566)
		(width 0.18288)
		(layer "In4.Cu")
		(net "M_F_CPU0_SA_DQ<12>")
	)
	(segment
		(start 418.767006 -301.43958)
		(end 418.440362 -301.112936)
		(width 0.18288)
		(layer "In4.Cu")
		(net "M_F_CPU0_SA_DQ<12>")
	)
	(segment
		(start 383.84226 -269.059152)
		(end 383.842514 -269.059152)
		(width 0.088646)
		(layer "In4.Cu")
		(net "M_F_CPU0_SA_DQ<12>")
	)
	(segment
		(start 417.816792 -301.477426)
		(end 416.814254 -301.477426)
		(width 0.18288)
		(layer "In4.Cu")
		(net "M_F_CPU0_SA_DQ<12>")
	)
	(segment
		(start 411.816296 -297.11396)
		(end 411.585664 -297.344592)
		(width 0.18288)
		(layer "In4.Cu")
		(net "M_F_CPU0_SA_DQ<12>")
	)
	(segment
		(start 409.96616 -295.319704)
		(end 409.798266 -295.249854)
		(width 0.18288)
		(layer "In4.Cu")
		(net "M_F_CPU0_SA_DQ<12>")
	)
	(segment
		(start 380.08687 -269.70609)
		(end 380.078742 -269.710662)
		(width 0.088646)
		(layer "In4.Cu")
		(net "M_F_CPU0_SA_DQ<12>")
	)
	(segment
		(start 410.90469 -296.303446)
		(end 410.51861 -296.303446)
		(width 0.18288)
		(layer "In4.Cu")
		(net "M_F_CPU0_SA_DQ<12>")
	)
	(segment
		(start 402.009102 -290.332922)
		(end 397.249142 -278.842216)
		(width 0.18288)
		(layer "In4.Cu")
		(net "M_F_CPU0_SA_DQ<12>")
	)
	(segment
		(start 390.539224 -273.073622)
		(end 388.45236 -270.986758)
		(width 0.18288)
		(layer "In4.Cu")
		(net "M_F_CPU0_SA_DQ<12>")
	)
	(segment
		(start 381.968756 -269.062708)
		(end 381.962914 -269.059152)
		(width 0.088646)
		(layer "In4.Cu")
		(net "M_F_CPU0_SA_DQ<12>")
	)
	(segment
		(start 381.023114 -269.059152)
		(end 381.017272 -269.05585)
		(width 0.088646)
		(layer "In4.Cu")
		(net "M_F_CPU0_SA_DQ<12>")
	)
	(segment
		(start 413.705294 -298.730162)
		(end 413.705294 -298.259246)
		(width 0.18288)
		(layer "In4.Cu")
		(net "M_F_CPU0_SA_DQ<12>")
	)
	(segment
		(start 379.811026 -269.780766)
		(end 379.040644 -269.780766)
		(width 0.088646)
		(layer "In4.Cu")
		(net "M_F_CPU0_SA_DQ<12>")
	)
	(segment
		(start 391.480548 -273.073622)
		(end 390.539224 -273.073622)
		(width 0.18288)
		(layer "In4.Cu")
		(net "M_F_CPU0_SA_DQ<12>")
	)
	(segment
		(start 408.908758 -295.585896)
		(end 408.809698 -295.347136)
		(width 0.18288)
		(layer "In4.Cu")
		(net "M_F_CPU0_SA_DQ<12>")
	)
	(segment
		(start 414.591754 -299.616622)
		(end 413.705294 -298.730162)
		(width 0.18288)
		(layer "In4.Cu")
		(net "M_F_CPU0_SA_DQ<12>")
	)
	(segment
		(start 419.68928 -301.43958)
		(end 418.767006 -301.43958)
		(width 0.18288)
		(layer "In4.Cu")
		(net "M_F_CPU0_SA_DQ<12>")
	)
	(segment
		(start 420.11219 -301.01667)
		(end 419.68928 -301.43958)
		(width 0.18288)
		(layer "In4.Cu")
		(net "M_F_CPU0_SA_DQ<12>")
	)
	(segment
		(start 387.51129 -270.045688)
		(end 386.863082 -269.39748)
		(width 0.088646)
		(layer "In4.Cu")
		(net "M_F_CPU0_SA_DQ<12>")
	)
	(segment
		(start 386.67055 -269.064232)
		(end 386.66166 -269.059152)
		(width 0.088646)
		(layer "In4.Cu")
		(net "M_F_CPU0_SA_DQ<12>")
	)
	(segment
		(start 412.910528 -297.949112)
		(end 412.075376 -297.11396)
		(width 0.18288)
		(layer "In4.Cu")
		(net "M_F_CPU0_SA_DQ<12>")
	)
	(segment
		(start 409.798266 -295.249854)
		(end 409.55976 -295.348914)
		(width 0.18288)
		(layer "In4.Cu")
		(net "M_F_CPU0_SA_DQ<12>")
	)
	(segment
		(start 408.918918 -295.083484)
		(end 408.819858 -294.844724)
		(width 0.18288)
		(layer "In4.Cu")
		(net "M_F_CPU0_SA_DQ<12>")
	)
	(segment
		(start 408.809698 -295.347136)
		(end 408.918918 -295.083484)
		(width 0.18288)
		(layer "In4.Cu")
		(net "M_F_CPU0_SA_DQ<12>")
	)
	(segment
		(start 378.716794 -269.671546)
		(end 378.575062 -269.552674)
		(width 0.088646)
		(layer "In4.Cu")
		(net "M_F_CPU0_SA_DQ<12>")
	)
	(segment
		(start 413.39516 -297.949112)
		(end 412.910528 -297.949112)
		(width 0.18288)
		(layer "In4.Cu")
		(net "M_F_CPU0_SA_DQ<12>")
	)
	(arc
		(start 386.834126 -269.32763)
		(mid 386.823329 -269.253097)
		(end 386.791962 -269.184628)
		(width 0.088646)
		(layer "In4.Cu")
		(net "M_F_CPU0_SA_DQ<12>")
	)
	(arc
		(start 384.78206 -269.059152)
		(mid 384.594862 -269.009009)
		(end 384.407664 -269.059152)
		(width 0.088646)
		(layer "In4.Cu")
		(net "M_F_CPU0_SA_DQ<12>")
	)
	(arc
		(start 384.407664 -269.059152)
		(mid 384.124962 -269.134928)
		(end 383.84226 -269.059152)
		(width 0.088646)
		(layer "In4.Cu")
		(net "M_F_CPU0_SA_DQ<12>")
	)
	(arc
		(start 382.528064 -269.059152)
		(mid 382.24889 -269.134917)
		(end 381.968756 -269.062708)
		(width 0.088646)
		(layer "In4.Cu")
		(net "M_F_CPU0_SA_DQ<12>")
	)
	(arc
		(start 380.648464 -269.059152)
		(mid 380.596838 -269.093644)
		(end 380.550166 -269.13459)
		(width 0.088646)
		(layer "In4.Cu")
		(net "M_F_CPU0_SA_DQ<12>")
	)
	(arc
		(start 380.47803 -269.206726)
		(mid 380.463915 -269.223937)
		(end 380.453392 -269.243556)
		(width 0.088646)
		(layer "In4.Cu")
		(net "M_F_CPU0_SA_DQ<12>")
	)
	(arc
		(start 380.256034 -269.576042)
		(mid 380.175708 -269.646604)
		(end 380.08687 -269.70609)
		(width 0.088646)
		(layer "In4.Cu")
		(net "M_F_CPU0_SA_DQ<12>")
	)
	(arc
		(start 378.885704 -269.752318)
		(mid 378.796273 -269.722338)
		(end 378.716794 -269.671546)
		(width 0.088646)
		(layer "In4.Cu")
		(net "M_F_CPU0_SA_DQ<12>")
	)
	(arc
		(start 386.287264 -269.059152)
		(mid 386.004562 -269.134928)
		(end 385.72186 -269.059152)
		(width 0.088646)
		(layer "In4.Cu")
		(net "M_F_CPU0_SA_DQ<12>")
	)
	(arc
		(start 380.078742 -269.710662)
		(mid 379.949404 -269.762986)
		(end 379.811026 -269.780766)
		(width 0.088646)
		(layer "In4.Cu")
		(net "M_F_CPU0_SA_DQ<12>")
	)
	(arc
		(start 380.41326 -269.340838)
		(mid 380.346226 -269.466179)
		(end 380.256034 -269.576042)
		(width 0.088646)
		(layer "In4.Cu")
		(net "M_F_CPU0_SA_DQ<12>")
	)
	(arc
		(start 381.588264 -269.059152)
		(mid 381.30909 -269.134917)
		(end 381.028956 -269.062708)
		(width 0.088646)
		(layer "In4.Cu")
		(net "M_F_CPU0_SA_DQ<12>")
	)
	(arc
		(start 385.347464 -269.059152)
		(mid 385.064762 -269.134928)
		(end 384.78206 -269.059152)
		(width 0.088646)
		(layer "In4.Cu")
		(net "M_F_CPU0_SA_DQ<12>")
	)
	(arc
		(start 378.948442 -269.768066)
		(mid 378.917241 -269.759524)
		(end 378.885704 -269.752318)
		(width 0.088646)
		(layer "In4.Cu")
		(net "M_F_CPU0_SA_DQ<12>")
	)
	(arc
		(start 381.017272 -269.05585)
		(mid 380.832417 -269.0089)
		(end 380.648464 -269.059152)
		(width 0.088646)
		(layer "In4.Cu")
		(net "M_F_CPU0_SA_DQ<12>")
	)
	(arc
		(start 382.896872 -269.05585)
		(mid 382.712017 -269.0089)
		(end 382.528064 -269.059152)
		(width 0.088646)
		(layer "In4.Cu")
		(net "M_F_CPU0_SA_DQ<12>")
	)
	(arc
		(start 386.789676 -269.180818)
		(mid 386.736678 -269.115817)
		(end 386.67055 -269.064232)
		(width 0.088646)
		(layer "In4.Cu")
		(net "M_F_CPU0_SA_DQ<12>")
	)
	(arc
		(start 386.66166 -269.059152)
		(mid 386.474462 -269.009009)
		(end 386.287264 -269.059152)
		(width 0.088646)
		(layer "In4.Cu")
		(net "M_F_CPU0_SA_DQ<12>")
	)
	(arc
		(start 383.467864 -269.059152)
		(mid 383.18795 -269.134921)
		(end 382.907286 -269.061946)
		(width 0.088646)
		(layer "In4.Cu")
		(net "M_F_CPU0_SA_DQ<12>")
	)
	(arc
		(start 381.957072 -269.05585)
		(mid 381.772217 -269.0089)
		(end 381.588264 -269.059152)
		(width 0.088646)
		(layer "In4.Cu")
		(net "M_F_CPU0_SA_DQ<12>")
	)
	(arc
		(start 383.842514 -269.059152)
		(mid 383.655206 -269.009009)
		(end 383.467864 -269.059152)
		(width 0.088646)
		(layer "In4.Cu")
		(net "M_F_CPU0_SA_DQ<12>")
	)
	(arc
		(start 378.575062 -269.552674)
		(mid 378.357556 -269.427151)
		(end 378.110242 -269.38351)
		(width 0.088646)
		(layer "In4.Cu")
		(net "M_F_CPU0_SA_DQ<12>")
	)
	(arc
		(start 379.040644 -269.780766)
		(mid 378.994069 -269.777846)
		(end 378.948442 -269.768066)
		(width 0.088646)
		(layer "In4.Cu")
		(net "M_F_CPU0_SA_DQ<12>")
	)
	(arc
		(start 386.863082 -269.39748)
		(mid 386.841669 -269.365433)
		(end 386.834126 -269.32763)
		(width 0.088646)
		(layer "In4.Cu")
		(net "M_F_CPU0_SA_DQ<12>")
	)
	(arc
		(start 385.72186 -269.059152)
		(mid 385.534662 -269.009009)
		(end 385.347464 -269.059152)
		(width 0.088646)
		(layer "In4.Cu")
		(net "M_F_CPU0_SA_DQ<12>")
	)
	(segment
		(start 379.896116 -270.475456)
		(end 379.896116 -271.011142)
		(width 0.20066)
		(layer "F.Cu")
		(net "M_F_CPU0_SA_DQ<11>")
	)
	(segment
		(start 430.395126 -304.853848)
		(end 431.076354 -304.853848)
		(width 0.20066)
		(layer "F.Cu")
		(net "M_F_CPU0_SA_DQ<11>")
	)
	(segment
		(start 428.07128 -304.848768)
		(end 428.363126 -304.848768)
		(width 0.20066)
		(layer "F.Cu")
		(net "M_F_CPU0_SA_DQ<11>")
	)
	(segment
		(start 431.514504 -304.164746)
		(end 431.898552 -304.164746)
		(width 0.20066)
		(layer "F.Cu")
		(net "M_F_CPU0_SA_DQ<11>")
	)
	(segment
		(start 428.363126 -304.848768)
		(end 428.367952 -304.848768)
		(width 0.101854)
		(layer "F.Cu")
		(net "M_F_CPU0_SA_DQ<11>")
	)
	(segment
		(start 428.367952 -304.848768)
		(end 428.375064 -304.841656)
		(width 0.1016)
		(layer "F.Cu")
		(net "M_F_CPU0_SA_DQ<11>")
	)
	(segment
		(start 431.280316 -304.398934)
		(end 431.514504 -304.164746)
		(width 0.20066)
		(layer "F.Cu")
		(net "M_F_CPU0_SA_DQ<11>")
	)
	(segment
		(start 425.940982 -304.416714)
		(end 427.639226 -304.416714)
		(width 0.20066)
		(layer "F.Cu")
		(net "M_F_CPU0_SA_DQ<11>")
	)
	(segment
		(start 424.836082 -304.416714)
		(end 425.940982 -304.416714)
		(width 0.20066)
		(layer "F.Cu")
		(net "M_F_CPU0_SA_DQ<11>")
	)
	(segment
		(start 431.898552 -304.164746)
		(end 432.15052 -304.416714)
		(width 0.20066)
		(layer "F.Cu")
		(net "M_F_CPU0_SA_DQ<11>")
	)
	(segment
		(start 431.280316 -304.649886)
		(end 431.280316 -304.398934)
		(width 0.20066)
		(layer "F.Cu")
		(net "M_F_CPU0_SA_DQ<11>")
	)
	(segment
		(start 428.375064 -304.841656)
		(end 430.382934 -304.841656)
		(width 0.1016)
		(layer "F.Cu")
		(net "M_F_CPU0_SA_DQ<11>")
	)
	(segment
		(start 432.15052 -304.416714)
		(end 433.484782 -304.416714)
		(width 0.20066)
		(layer "F.Cu")
		(net "M_F_CPU0_SA_DQ<11>")
	)
	(segment
		(start 430.382934 -304.841656)
		(end 430.395126 -304.853848)
		(width 0.1016)
		(layer "F.Cu")
		(net "M_F_CPU0_SA_DQ<11>")
	)
	(segment
		(start 379.896116 -271.011142)
		(end 379.895862 -271.011396)
		(width 0.20066)
		(layer "F.Cu")
		(net "M_F_CPU0_SA_DQ<11>")
	)
	(segment
		(start 431.076354 -304.853848)
		(end 431.280316 -304.649886)
		(width 0.20066)
		(layer "F.Cu")
		(net "M_F_CPU0_SA_DQ<11>")
	)
	(segment
		(start 427.639226 -304.416714)
		(end 428.07128 -304.848768)
		(width 0.20066)
		(layer "F.Cu")
		(net "M_F_CPU0_SA_DQ<11>")
	)
	(segment
		(start 385.347464 -271.335754)
		(end 385.332732 -271.327118)
		(width 0.088646)
		(layer "In4.Cu")
		(net "M_F_CPU0_SA_DQ<11>")
	)
	(segment
		(start 395.208252 -279.831038)
		(end 390.239758 -274.863306)
		(width 0.18288)
		(layer "In4.Cu")
		(net "M_F_CPU0_SA_DQ<11>")
	)
	(segment
		(start 416.931094 -304.169826)
		(end 416.551364 -303.790096)
		(width 0.18288)
		(layer "In4.Cu")
		(net "M_F_CPU0_SA_DQ<11>")
	)
	(segment
		(start 409.224734 -300.59249)
		(end 406.16251 -297.530266)
		(width 0.18288)
		(layer "In4.Cu")
		(net "M_F_CPU0_SA_DQ<11>")
	)
	(segment
		(start 385.35356 -271.33931)
		(end 385.347464 -271.335754)
		(width 0.088646)
		(layer "In4.Cu")
		(net "M_F_CPU0_SA_DQ<11>")
	)
	(segment
		(start 412.712154 -302.429926)
		(end 410.874718 -300.59249)
		(width 0.18288)
		(layer "In4.Cu")
		(net "M_F_CPU0_SA_DQ<11>")
	)
	(segment
		(start 387.137148 -272.63852)
		(end 387.073394 -272.574766)
		(width 0.088646)
		(layer "In4.Cu")
		(net "M_F_CPU0_SA_DQ<11>")
	)
	(segment
		(start 390.239758 -274.863306)
		(end 390.101328 -274.724876)
		(width 0.18288)
		(layer "In4.Cu")
		(net "M_F_CPU0_SA_DQ<11>")
	)
	(segment
		(start 387.392672 -272.63852)
		(end 387.137148 -272.63852)
		(width 0.088646)
		(layer "In4.Cu")
		(net "M_F_CPU0_SA_DQ<11>")
	)
	(segment
		(start 423.738802 -304.842418)
		(end 420.51859 -304.842418)
		(width 0.18288)
		(layer "In4.Cu")
		(net "M_F_CPU0_SA_DQ<11>")
	)
	(segment
		(start 419.845998 -304.169826)
		(end 416.931094 -304.169826)
		(width 0.18288)
		(layer "In4.Cu")
		(net "M_F_CPU0_SA_DQ<11>")
	)
	(segment
		(start 382.902714 -271.335754)
		(end 382.896872 -271.33931)
		(width 0.088646)
		(layer "In4.Cu")
		(net "M_F_CPU0_SA_DQ<11>")
	)
	(segment
		(start 381.962914 -271.335754)
		(end 381.957072 -271.33931)
		(width 0.088646)
		(layer "In4.Cu")
		(net "M_F_CPU0_SA_DQ<11>")
	)
	(segment
		(start 413.372554 -302.429926)
		(end 412.712154 -302.429926)
		(width 0.18288)
		(layer "In4.Cu")
		(net "M_F_CPU0_SA_DQ<11>")
	)
	(segment
		(start 406.16251 -297.530266)
		(end 405.282146 -297.165268)
		(width 0.18288)
		(layer "In4.Cu")
		(net "M_F_CPU0_SA_DQ<11>")
	)
	(segment
		(start 384.407664 -271.335754)
		(end 384.392932 -271.327118)
		(width 0.088646)
		(layer "In4.Cu")
		(net "M_F_CPU0_SA_DQ<11>")
	)
	(segment
		(start 382.907286 -271.333214)
		(end 382.902714 -271.335754)
		(width 0.088646)
		(layer "In4.Cu")
		(net "M_F_CPU0_SA_DQ<11>")
	)
	(segment
		(start 381.023114 -271.335754)
		(end 381.017272 -271.33931)
		(width 0.088646)
		(layer "In4.Cu")
		(net "M_F_CPU0_SA_DQ<11>")
	)
	(segment
		(start 424.164506 -304.416714)
		(end 423.738802 -304.842418)
		(width 0.18288)
		(layer "In4.Cu")
		(net "M_F_CPU0_SA_DQ<11>")
	)
	(segment
		(start 410.874718 -300.59249)
		(end 409.224734 -300.59249)
		(width 0.18288)
		(layer "In4.Cu")
		(net "M_F_CPU0_SA_DQ<11>")
	)
	(segment
		(start 381.028956 -271.332452)
		(end 381.023114 -271.335754)
		(width 0.088646)
		(layer "In4.Cu")
		(net "M_F_CPU0_SA_DQ<11>")
	)
	(segment
		(start 390.101328 -274.724876)
		(end 389.777732 -274.724876)
		(width 0.18288)
		(layer "In4.Cu")
		(net "M_F_CPU0_SA_DQ<11>")
	)
	(segment
		(start 414.732724 -303.790096)
		(end 413.372554 -302.429926)
		(width 0.18288)
		(layer "In4.Cu")
		(net "M_F_CPU0_SA_DQ<11>")
	)
	(segment
		(start 389.777732 -274.724876)
		(end 387.691376 -272.63852)
		(width 0.18288)
		(layer "In4.Cu")
		(net "M_F_CPU0_SA_DQ<11>")
	)
	(segment
		(start 387.073394 -272.574766)
		(end 386.981954 -272.389346)
		(width 0.088646)
		(layer "In4.Cu")
		(net "M_F_CPU0_SA_DQ<11>")
	)
	(segment
		(start 424.836082 -304.416714)
		(end 424.164506 -304.416714)
		(width 0.18288)
		(layer "In4.Cu")
		(net "M_F_CPU0_SA_DQ<11>")
	)
	(segment
		(start 385.817618 -272.14957)
		(end 385.808728 -272.14449)
		(width 0.088646)
		(layer "In4.Cu")
		(net "M_F_CPU0_SA_DQ<11>")
	)
	(segment
		(start 386.206746 -272.140934)
		(end 386.192014 -272.14957)
		(width 0.088646)
		(layer "In4.Cu")
		(net "M_F_CPU0_SA_DQ<11>")
	)
	(segment
		(start 381.968756 -271.332452)
		(end 381.962914 -271.335754)
		(width 0.088646)
		(layer "In4.Cu")
		(net "M_F_CPU0_SA_DQ<11>")
	)
	(segment
		(start 405.282146 -297.165268)
		(end 400.3421 -292.226238)
		(width 0.18288)
		(layer "In4.Cu")
		(net "M_F_CPU0_SA_DQ<11>")
	)
	(segment
		(start 420.51859 -304.842418)
		(end 419.845998 -304.169826)
		(width 0.18288)
		(layer "In4.Cu")
		(net "M_F_CPU0_SA_DQ<11>")
	)
	(segment
		(start 416.551364 -303.790096)
		(end 414.732724 -303.790096)
		(width 0.18288)
		(layer "In4.Cu")
		(net "M_F_CPU0_SA_DQ<11>")
	)
	(segment
		(start 387.691376 -272.63852)
		(end 387.392672 -272.63852)
		(width 0.18288)
		(layer "In4.Cu")
		(net "M_F_CPU0_SA_DQ<11>")
	)
	(segment
		(start 400.3421 -292.226238)
		(end 395.208252 -279.831038)
		(width 0.18288)
		(layer "In4.Cu")
		(net "M_F_CPU0_SA_DQ<11>")
	)
	(arc
		(start 382.896872 -271.33931)
		(mid 382.712017 -271.386228)
		(end 382.528064 -271.336008)
		(width 0.088646)
		(layer "In4.Cu")
		(net "M_F_CPU0_SA_DQ<11>")
	)
	(arc
		(start 386.192014 -272.14957)
		(mid 386.004816 -272.199713)
		(end 385.817618 -272.14957)
		(width 0.088646)
		(layer "In4.Cu")
		(net "M_F_CPU0_SA_DQ<11>")
	)
	(arc
		(start 386.757418 -272.14957)
		(mid 386.483189 -272.073645)
		(end 386.206746 -272.140934)
		(width 0.088646)
		(layer "In4.Cu")
		(net "M_F_CPU0_SA_DQ<11>")
	)
	(arc
		(start 381.588264 -271.336008)
		(mid 381.30909 -271.260209)
		(end 381.028956 -271.332452)
		(width 0.088646)
		(layer "In4.Cu")
		(net "M_F_CPU0_SA_DQ<11>")
	)
	(arc
		(start 385.332732 -271.327118)
		(mid 385.056257 -271.259798)
		(end 384.78206 -271.335754)
		(width 0.088646)
		(layer "In4.Cu")
		(net "M_F_CPU0_SA_DQ<11>")
	)
	(arc
		(start 384.392932 -271.327118)
		(mid 384.116457 -271.259798)
		(end 383.84226 -271.335754)
		(width 0.088646)
		(layer "In4.Cu")
		(net "M_F_CPU0_SA_DQ<11>")
	)
	(arc
		(start 384.78206 -271.335754)
		(mid 384.594862 -271.385897)
		(end 384.407664 -271.335754)
		(width 0.088646)
		(layer "In4.Cu")
		(net "M_F_CPU0_SA_DQ<11>")
	)
	(arc
		(start 380.648464 -271.336008)
		(mid 380.281579 -271.151871)
		(end 379.895862 -271.011396)
		(width 0.088646)
		(layer "In4.Cu")
		(net "M_F_CPU0_SA_DQ<11>")
	)
	(arc
		(start 382.528064 -271.336008)
		(mid 382.24889 -271.260209)
		(end 381.968756 -271.332452)
		(width 0.088646)
		(layer "In4.Cu")
		(net "M_F_CPU0_SA_DQ<11>")
	)
	(arc
		(start 381.957072 -271.33931)
		(mid 381.772217 -271.386228)
		(end 381.588264 -271.336008)
		(width 0.088646)
		(layer "In4.Cu")
		(net "M_F_CPU0_SA_DQ<11>")
	)
	(arc
		(start 385.808728 -272.14449)
		(mid 385.677814 -272.00813)
		(end 385.630166 -271.825212)
		(width 0.088646)
		(layer "In4.Cu")
		(net "M_F_CPU0_SA_DQ<11>")
	)
	(arc
		(start 386.981954 -272.389346)
		(mid 386.887448 -272.252834)
		(end 386.757418 -272.14957)
		(width 0.088646)
		(layer "In4.Cu")
		(net "M_F_CPU0_SA_DQ<11>")
	)
	(arc
		(start 381.017272 -271.33931)
		(mid 380.832417 -271.386228)
		(end 380.648464 -271.336008)
		(width 0.088646)
		(layer "In4.Cu")
		(net "M_F_CPU0_SA_DQ<11>")
	)
	(arc
		(start 383.84226 -271.335754)
		(mid 383.655062 -271.385897)
		(end 383.467864 -271.335754)
		(width 0.088646)
		(layer "In4.Cu")
		(net "M_F_CPU0_SA_DQ<11>")
	)
	(arc
		(start 385.630166 -271.825212)
		(mid 385.556175 -271.545646)
		(end 385.35356 -271.33931)
		(width 0.088646)
		(layer "In4.Cu")
		(net "M_F_CPU0_SA_DQ<11>")
	)
	(arc
		(start 383.467864 -271.335754)
		(mid 383.18792 -271.26011)
		(end 382.907286 -271.333214)
		(width 0.088646)
		(layer "In4.Cu")
		(net "M_F_CPU0_SA_DQ<11>")
	)
	(segment
		(start 431.898552 -305.864768)
		(end 432.15052 -306.116736)
		(width 0.20066)
		(layer "F.Cu")
		(net "M_F_CPU0_SA_DQ<10>")
	)
	(segment
		(start 427.639226 -306.116736)
		(end 428.07128 -306.54879)
		(width 0.20066)
		(layer "F.Cu")
		(net "M_F_CPU0_SA_DQ<10>")
	)
	(segment
		(start 428.363126 -306.54879)
		(end 428.367952 -306.54879)
		(width 0.101854)
		(layer "F.Cu")
		(net "M_F_CPU0_SA_DQ<10>")
	)
	(segment
		(start 430.382934 -306.541678)
		(end 430.395126 -306.55387)
		(width 0.1016)
		(layer "F.Cu")
		(net "M_F_CPU0_SA_DQ<10>")
	)
	(segment
		(start 430.395126 -306.55387)
		(end 431.076354 -306.55387)
		(width 0.20066)
		(layer "F.Cu")
		(net "M_F_CPU0_SA_DQ<10>")
	)
	(segment
		(start 431.076354 -306.55387)
		(end 431.280316 -306.349908)
		(width 0.20066)
		(layer "F.Cu")
		(net "M_F_CPU0_SA_DQ<10>")
	)
	(segment
		(start 428.375064 -306.541678)
		(end 430.382934 -306.541678)
		(width 0.1016)
		(layer "F.Cu")
		(net "M_F_CPU0_SA_DQ<10>")
	)
	(segment
		(start 431.280316 -306.098956)
		(end 431.514504 -305.864768)
		(width 0.20066)
		(layer "F.Cu")
		(net "M_F_CPU0_SA_DQ<10>")
	)
	(segment
		(start 379.425962 -271.289272)
		(end 379.426216 -271.825212)
		(width 0.20066)
		(layer "F.Cu")
		(net "M_F_CPU0_SA_DQ<10>")
	)
	(segment
		(start 425.940982 -306.116736)
		(end 427.639226 -306.116736)
		(width 0.20066)
		(layer "F.Cu")
		(net "M_F_CPU0_SA_DQ<10>")
	)
	(segment
		(start 431.280316 -306.349908)
		(end 431.280316 -306.098956)
		(width 0.20066)
		(layer "F.Cu")
		(net "M_F_CPU0_SA_DQ<10>")
	)
	(segment
		(start 428.367952 -306.54879)
		(end 428.375064 -306.541678)
		(width 0.1016)
		(layer "F.Cu")
		(net "M_F_CPU0_SA_DQ<10>")
	)
	(segment
		(start 432.15052 -306.116736)
		(end 433.484782 -306.116736)
		(width 0.20066)
		(layer "F.Cu")
		(net "M_F_CPU0_SA_DQ<10>")
	)
	(segment
		(start 431.514504 -305.864768)
		(end 431.898552 -305.864768)
		(width 0.20066)
		(layer "F.Cu")
		(net "M_F_CPU0_SA_DQ<10>")
	)
	(segment
		(start 424.836082 -306.116736)
		(end 425.940982 -306.116736)
		(width 0.20066)
		(layer "F.Cu")
		(net "M_F_CPU0_SA_DQ<10>")
	)
	(segment
		(start 428.07128 -306.54879)
		(end 428.363126 -306.54879)
		(width 0.20066)
		(layer "F.Cu")
		(net "M_F_CPU0_SA_DQ<10>")
	)
	(segment
		(start 385.347464 -272.96364)
		(end 385.338574 -272.95856)
		(width 0.088646)
		(layer "In4.Cu")
		(net "M_F_CPU0_SA_DQ<10>")
	)
	(segment
		(start 424.517312 -306.216812)
		(end 423.56151 -306.54244)
		(width 0.18288)
		(layer "In4.Cu")
		(net "M_F_CPU0_SA_DQ<10>")
	)
	(segment
		(start 385.160012 -272.639282)
		(end 385.160012 -272.617184)
		(width 0.088646)
		(layer "In4.Cu")
		(net "M_F_CPU0_SA_DQ<10>")
	)
	(segment
		(start 399.53311 -292.960298)
		(end 394.313156 -280.357326)
		(width 0.18288)
		(layer "In4.Cu")
		(net "M_F_CPU0_SA_DQ<10>")
	)
	(segment
		(start 423.56151 -306.54244)
		(end 420.377874 -306.54244)
		(width 0.18288)
		(layer "In4.Cu")
		(net "M_F_CPU0_SA_DQ<10>")
	)
	(segment
		(start 407.520648 -301.312072)
		(end 406.580848 -300.372272)
		(width 0.18288)
		(layer "In4.Cu")
		(net "M_F_CPU0_SA_DQ<10>")
	)
	(segment
		(start 389.287004 -275.31695)
		(end 387.520942 -273.550888)
		(width 0.18288)
		(layer "In4.Cu")
		(net "M_F_CPU0_SA_DQ<10>")
	)
	(segment
		(start 424.825668 -306.111656)
		(end 424.517312 -306.216812)
		(width 0.18288)
		(layer "In4.Cu")
		(net "M_F_CPU0_SA_DQ<10>")
	)
	(segment
		(start 413.370014 -303.903126)
		(end 412.755334 -303.903126)
		(width 0.18288)
		(layer "In4.Cu")
		(net "M_F_CPU0_SA_DQ<10>")
	)
	(segment
		(start 409.205684 -303.008792)
		(end 408.969464 -302.689006)
		(width 0.18288)
		(layer "In4.Cu")
		(net "M_F_CPU0_SA_DQ<10>")
	)
	(segment
		(start 408.660854 -301.639986)
		(end 408.33294 -301.312072)
		(width 0.18288)
		(layer "In4.Cu")
		(net "M_F_CPU0_SA_DQ<10>")
	)
	(segment
		(start 415.648394 -305.643026)
		(end 415.396934 -305.643026)
		(width 0.18288)
		(layer "In4.Cu")
		(net "M_F_CPU0_SA_DQ<10>")
	)
	(segment
		(start 424.836082 -306.116736)
		(end 424.825668 -306.111656)
		(width 0.18288)
		(layer "In4.Cu")
		(net "M_F_CPU0_SA_DQ<10>")
	)
	(segment
		(start 418.553646 -306.276502)
		(end 415.648394 -305.643026)
		(width 0.18288)
		(layer "In4.Cu")
		(net "M_F_CPU0_SA_DQ<10>")
	)
	(segment
		(start 410.156914 -303.142396)
		(end 409.387294 -303.142396)
		(width 0.18288)
		(layer "In4.Cu")
		(net "M_F_CPU0_SA_DQ<10>")
	)
	(segment
		(start 412.547054 -304.111406)
		(end 411.88513 -304.111406)
		(width 0.18288)
		(layer "In4.Cu")
		(net "M_F_CPU0_SA_DQ<10>")
	)
	(segment
		(start 382.058164 -272.149824)
		(end 382.050798 -272.145506)
		(width 0.088646)
		(layer "In4.Cu")
		(net "M_F_CPU0_SA_DQ<10>")
	)
	(segment
		(start 420.377874 -306.54244)
		(end 419.82517 -306.443634)
		(width 0.18288)
		(layer "In4.Cu")
		(net "M_F_CPU0_SA_DQ<10>")
	)
	(segment
		(start 389.297164 -275.341334)
		(end 389.287004 -275.31695)
		(width 0.18288)
		(layer "In4.Cu")
		(net "M_F_CPU0_SA_DQ<10>")
	)
	(segment
		(start 383.938018 -272.14957)
		(end 383.937764 -272.149824)
		(width 0.088646)
		(layer "In4.Cu")
		(net "M_F_CPU0_SA_DQ<10>")
	)
	(segment
		(start 406.580848 -299.670216)
		(end 405.801068 -298.890436)
		(width 0.18288)
		(layer "In4.Cu")
		(net "M_F_CPU0_SA_DQ<10>")
	)
	(segment
		(start 394.313156 -280.357326)
		(end 389.297164 -275.341334)
		(width 0.18288)
		(layer "In4.Cu")
		(net "M_F_CPU0_SA_DQ<10>")
	)
	(segment
		(start 380.183136 -272.152364)
		(end 380.178564 -272.149824)
		(width 0.088646)
		(layer "In4.Cu")
		(net "M_F_CPU0_SA_DQ<10>")
	)
	(segment
		(start 381.118364 -272.149824)
		(end 381.110998 -272.145506)
		(width 0.088646)
		(layer "In4.Cu")
		(net "M_F_CPU0_SA_DQ<10>")
	)
	(segment
		(start 419.82517 -306.443634)
		(end 418.553646 -306.276502)
		(width 0.18288)
		(layer "In4.Cu")
		(net "M_F_CPU0_SA_DQ<10>")
	)
	(segment
		(start 387.520942 -273.550888)
		(end 387.392672 -273.550888)
		(width 0.18288)
		(layer "In4.Cu")
		(net "M_F_CPU0_SA_DQ<10>")
	)
	(segment
		(start 387.392672 -273.550888)
		(end 386.929122 -273.550888)
		(width 0.088646)
		(layer "In4.Cu")
		(net "M_F_CPU0_SA_DQ<10>")
	)
	(segment
		(start 382.997964 -272.149824)
		(end 382.990598 -272.145506)
		(width 0.088646)
		(layer "In4.Cu")
		(net "M_F_CPU0_SA_DQ<10>")
	)
	(segment
		(start 381.122936 -272.152364)
		(end 381.118364 -272.149824)
		(width 0.088646)
		(layer "In4.Cu")
		(net "M_F_CPU0_SA_DQ<10>")
	)
	(segment
		(start 409.387294 -303.142396)
		(end 409.205684 -303.008792)
		(width 0.18288)
		(layer "In4.Cu")
		(net "M_F_CPU0_SA_DQ<10>")
	)
	(segment
		(start 408.33294 -301.312072)
		(end 407.520648 -301.312072)
		(width 0.18288)
		(layer "In4.Cu")
		(net "M_F_CPU0_SA_DQ<10>")
	)
	(segment
		(start 405.463248 -298.890436)
		(end 399.53311 -292.960298)
		(width 0.18288)
		(layer "In4.Cu")
		(net "M_F_CPU0_SA_DQ<10>")
	)
	(segment
		(start 380.178564 -272.149824)
		(end 380.148592 -272.132298)
		(width 0.088646)
		(layer "In4.Cu")
		(net "M_F_CPU0_SA_DQ<10>")
	)
	(segment
		(start 414.9979 -305.531012)
		(end 413.370014 -303.903126)
		(width 0.18288)
		(layer "In4.Cu")
		(net "M_F_CPU0_SA_DQ<10>")
	)
	(segment
		(start 383.001774 -272.151856)
		(end 382.997964 -272.149824)
		(width 0.088646)
		(layer "In4.Cu")
		(net "M_F_CPU0_SA_DQ<10>")
	)
	(segment
		(start 415.396934 -305.643026)
		(end 414.9979 -305.531012)
		(width 0.18288)
		(layer "In4.Cu")
		(net "M_F_CPU0_SA_DQ<10>")
	)
	(segment
		(start 410.82468 -303.424844)
		(end 410.156914 -303.142396)
		(width 0.18288)
		(layer "In4.Cu")
		(net "M_F_CPU0_SA_DQ<10>")
	)
	(segment
		(start 382.062736 -272.152364)
		(end 382.058164 -272.149824)
		(width 0.088646)
		(layer "In4.Cu")
		(net "M_F_CPU0_SA_DQ<10>")
	)
	(segment
		(start 386.929122 -273.550888)
		(end 386.41655 -273.038316)
		(width 0.088646)
		(layer "In4.Cu")
		(net "M_F_CPU0_SA_DQ<10>")
	)
	(segment
		(start 384.327146 -272.140934)
		(end 384.312414 -272.14957)
		(width 0.088646)
		(layer "In4.Cu")
		(net "M_F_CPU0_SA_DQ<10>")
	)
	(segment
		(start 412.755334 -303.903126)
		(end 412.547054 -304.111406)
		(width 0.18288)
		(layer "In4.Cu")
		(net "M_F_CPU0_SA_DQ<10>")
	)
	(segment
		(start 386.41655 -273.038316)
		(end 386.287264 -272.96364)
		(width 0.088646)
		(layer "In4.Cu")
		(net "M_F_CPU0_SA_DQ<10>")
	)
	(segment
		(start 406.580848 -300.372272)
		(end 406.580848 -299.670216)
		(width 0.18288)
		(layer "In4.Cu")
		(net "M_F_CPU0_SA_DQ<10>")
	)
	(segment
		(start 405.801068 -298.890436)
		(end 405.463248 -298.890436)
		(width 0.18288)
		(layer "In4.Cu")
		(net "M_F_CPU0_SA_DQ<10>")
	)
	(segment
		(start 408.969464 -302.689006)
		(end 408.660854 -301.639986)
		(width 0.18288)
		(layer "In4.Cu")
		(net "M_F_CPU0_SA_DQ<10>")
	)
	(segment
		(start 411.88513 -304.111406)
		(end 410.82468 -303.424844)
		(width 0.18288)
		(layer "In4.Cu")
		(net "M_F_CPU0_SA_DQ<10>")
	)
	(arc
		(start 385.338574 -272.95856)
		(mid 385.20766 -272.8222)
		(end 385.160012 -272.639282)
		(width 0.088646)
		(layer "In4.Cu")
		(net "M_F_CPU0_SA_DQ<10>")
	)
	(arc
		(start 382.050798 -272.145506)
		(mid 381.771337 -272.074069)
		(end 381.493014 -272.149824)
		(width 0.088646)
		(layer "In4.Cu")
		(net "M_F_CPU0_SA_DQ<10>")
	)
	(arc
		(start 383.937764 -272.149824)
		(mid 383.655206 -272.074175)
		(end 383.372614 -272.149824)
		(width 0.088646)
		(layer "In4.Cu")
		(net "M_F_CPU0_SA_DQ<10>")
	)
	(arc
		(start 384.877818 -272.14957)
		(mid 384.603589 -272.073645)
		(end 384.327146 -272.140934)
		(width 0.088646)
		(layer "In4.Cu")
		(net "M_F_CPU0_SA_DQ<10>")
	)
	(arc
		(start 382.990598 -272.145506)
		(mid 382.711137 -272.074069)
		(end 382.432814 -272.149824)
		(width 0.088646)
		(layer "In4.Cu")
		(net "M_F_CPU0_SA_DQ<10>")
	)
	(arc
		(start 382.432814 -272.149824)
		(mid 382.24812 -272.199925)
		(end 382.062736 -272.152364)
		(width 0.088646)
		(layer "In4.Cu")
		(net "M_F_CPU0_SA_DQ<10>")
	)
	(arc
		(start 380.148592 -272.132298)
		(mid 379.797182 -271.955753)
		(end 379.426216 -271.825212)
		(width 0.088646)
		(layer "In4.Cu")
		(net "M_F_CPU0_SA_DQ<10>")
	)
	(arc
		(start 381.110998 -272.145506)
		(mid 380.831537 -272.074069)
		(end 380.553214 -272.149824)
		(width 0.088646)
		(layer "In4.Cu")
		(net "M_F_CPU0_SA_DQ<10>")
	)
	(arc
		(start 385.72186 -272.96364)
		(mid 385.534662 -273.013783)
		(end 385.347464 -272.96364)
		(width 0.088646)
		(layer "In4.Cu")
		(net "M_F_CPU0_SA_DQ<10>")
	)
	(arc
		(start 386.287264 -272.96364)
		(mid 386.004562 -272.887864)
		(end 385.72186 -272.96364)
		(width 0.088646)
		(layer "In4.Cu")
		(net "M_F_CPU0_SA_DQ<10>")
	)
	(arc
		(start 384.312414 -272.14957)
		(mid 384.125216 -272.199713)
		(end 383.938018 -272.14957)
		(width 0.088646)
		(layer "In4.Cu")
		(net "M_F_CPU0_SA_DQ<10>")
	)
	(arc
		(start 385.160012 -272.617184)
		(mid 385.079101 -272.347056)
		(end 384.877818 -272.14957)
		(width 0.088646)
		(layer "In4.Cu")
		(net "M_F_CPU0_SA_DQ<10>")
	)
	(arc
		(start 381.493014 -272.149824)
		(mid 381.30832 -272.199925)
		(end 381.122936 -272.152364)
		(width 0.088646)
		(layer "In4.Cu")
		(net "M_F_CPU0_SA_DQ<10>")
	)
	(arc
		(start 380.553214 -272.149824)
		(mid 380.36852 -272.199925)
		(end 380.183136 -272.152364)
		(width 0.088646)
		(layer "In4.Cu")
		(net "M_F_CPU0_SA_DQ<10>")
	)
	(arc
		(start 383.372614 -272.149824)
		(mid 383.187464 -272.199928)
		(end 383.001774 -272.151856)
		(width 0.088646)
		(layer "In4.Cu")
		(net "M_F_CPU0_SA_DQ<10>")
	)
	(segment
		(start 380.365762 -277.800562)
		(end 380.365762 -278.336248)
		(width 0.20066)
		(layer "F.Cu")
		(net "M_F_CPU0_SA_DQ<0>")
	)
	(segment
		(start 424.273472 -316.37732)
		(end 424.085512 -316.56528)
		(width 0.20066)
		(layer "F.Cu")
		(net "M_F_CPU0_SA_DQ<0>")
	)
	(segment
		(start 423.610278 -316.56528)
		(end 423.361612 -316.316614)
		(width 0.20066)
		(layer "F.Cu")
		(net "M_F_CPU0_SA_DQ<0>")
	)
	(segment
		(start 429.38446 -316.316868)
		(end 427.792896 -316.316868)
		(width 0.20066)
		(layer "F.Cu")
		(net "M_F_CPU0_SA_DQ<0>")
	)
	(segment
		(start 424.73626 -315.891672)
		(end 424.391582 -315.891672)
		(width 0.20066)
		(layer "F.Cu")
		(net "M_F_CPU0_SA_DQ<0>")
	)
	(segment
		(start 424.391582 -315.891672)
		(end 424.273472 -316.009782)
		(width 0.20066)
		(layer "F.Cu")
		(net "M_F_CPU0_SA_DQ<0>")
	)
	(segment
		(start 426.951394 -315.885322)
		(end 426.945044 -315.891672)
		(width 0.1016)
		(layer "F.Cu")
		(net "M_F_CPU0_SA_DQ<0>")
	)
	(segment
		(start 421.840914 -316.316614)
		(end 420.736014 -316.316614)
		(width 0.20066)
		(layer "F.Cu")
		(net "M_F_CPU0_SA_DQ<0>")
	)
	(segment
		(start 380.365762 -278.336248)
		(end 380.366016 -278.336502)
		(width 0.20066)
		(layer "F.Cu")
		(net "M_F_CPU0_SA_DQ<0>")
	)
	(segment
		(start 424.273472 -316.009782)
		(end 424.273472 -316.37732)
		(width 0.20066)
		(layer "F.Cu")
		(net "M_F_CPU0_SA_DQ<0>")
	)
	(segment
		(start 424.085512 -316.56528)
		(end 423.610278 -316.56528)
		(width 0.20066)
		(layer "F.Cu")
		(net "M_F_CPU0_SA_DQ<0>")
	)
	(segment
		(start 429.384714 -316.316614)
		(end 429.38446 -316.316868)
		(width 0.20066)
		(layer "F.Cu")
		(net "M_F_CPU0_SA_DQ<0>")
	)
	(segment
		(start 426.945044 -315.891672)
		(end 424.78325 -315.891672)
		(width 0.1016)
		(layer "F.Cu")
		(net "M_F_CPU0_SA_DQ<0>")
	)
	(segment
		(start 424.78325 -315.891672)
		(end 424.73626 -315.891672)
		(width 0.101854)
		(layer "F.Cu")
		(net "M_F_CPU0_SA_DQ<0>")
	)
	(segment
		(start 423.361612 -316.316614)
		(end 421.840914 -316.316614)
		(width 0.20066)
		(layer "F.Cu")
		(net "M_F_CPU0_SA_DQ<0>")
	)
	(segment
		(start 427.792896 -316.316868)
		(end 427.36135 -315.885322)
		(width 0.20066)
		(layer "F.Cu")
		(net "M_F_CPU0_SA_DQ<0>")
	)
	(segment
		(start 427.36135 -315.885322)
		(end 426.951394 -315.885322)
		(width 0.20066)
		(layer "F.Cu")
		(net "M_F_CPU0_SA_DQ<0>")
	)
	(segment
		(start 392.210544 -295.852342)
		(end 390.291574 -293.933372)
		(width 0.18288)
		(layer "In2.Cu")
		(net "M_F_CPU0_SA_DQ<0>")
	)
	(segment
		(start 380.678944 -278.336502)
		(end 380.366016 -278.336502)
		(width 0.088646)
		(layer "In2.Cu")
		(net "M_F_CPU0_SA_DQ<0>")
	)
	(segment
		(start 381.210312 -279.150318)
		(end 381.210312 -279.141682)
		(width 0.088646)
		(layer "In2.Cu")
		(net "M_F_CPU0_SA_DQ<0>")
	)
	(segment
		(start 412.269432 -316.743334)
		(end 411.563566 -316.743334)
		(width 0.18288)
		(layer "In2.Cu")
		(net "M_F_CPU0_SA_DQ<0>")
	)
	(segment
		(start 409.44673 -316.743334)
		(end 409.112466 -316.40907)
		(width 0.18288)
		(layer "In2.Cu")
		(net "M_F_CPU0_SA_DQ<0>")
	)
	(segment
		(start 380.744222 -278.40178)
		(end 380.678944 -278.336502)
		(width 0.088646)
		(layer "In2.Cu")
		(net "M_F_CPU0_SA_DQ<0>")
	)
	(segment
		(start 418.143944 -316.39129)
		(end 417.792408 -316.742826)
		(width 0.18288)
		(layer "In2.Cu")
		(net "M_F_CPU0_SA_DQ<0>")
	)
	(segment
		(start 412.445708 -316.567058)
		(end 412.269432 -316.743334)
		(width 0.18288)
		(layer "In2.Cu")
		(net "M_F_CPU0_SA_DQ<0>")
	)
	(segment
		(start 387.799072 -282.150566)
		(end 387.390132 -281.163014)
		(width 0.18288)
		(layer "In2.Cu")
		(net "M_F_CPU0_SA_DQ<0>")
	)
	(segment
		(start 393.446254 -304.857658)
		(end 393.446254 -298.835826)
		(width 0.18288)
		(layer "In2.Cu")
		(net "M_F_CPU0_SA_DQ<0>")
	)
	(segment
		(start 418.776404 -316.39129)
		(end 418.143944 -316.39129)
		(width 0.18288)
		(layer "In2.Cu")
		(net "M_F_CPU0_SA_DQ<0>")
	)
	(segment
		(start 409.112466 -316.40907)
		(end 408.028902 -316.40907)
		(width 0.18288)
		(layer "In2.Cu")
		(net "M_F_CPU0_SA_DQ<0>")
	)
	(segment
		(start 417.792408 -316.742826)
		(end 416.837876 -316.742826)
		(width 0.18288)
		(layer "In2.Cu")
		(net "M_F_CPU0_SA_DQ<0>")
	)
	(segment
		(start 387.9469 -282.507182)
		(end 387.799072 -282.150566)
		(width 0.18288)
		(layer "In2.Cu")
		(net "M_F_CPU0_SA_DQ<0>")
	)
	(segment
		(start 382.528064 -280.453846)
		(end 382.513332 -280.462482)
		(width 0.088646)
		(layer "In2.Cu")
		(net "M_F_CPU0_SA_DQ<0>")
	)
	(segment
		(start 381.501904 -279.644856)
		(end 381.486918 -279.63622)
		(width 0.088646)
		(layer "In2.Cu")
		(net "M_F_CPU0_SA_DQ<0>")
	)
	(segment
		(start 387.088126 -280.861008)
		(end 386.62991 -280.402792)
		(width 0.088646)
		(layer "In2.Cu")
		(net "M_F_CPU0_SA_DQ<0>")
	)
	(segment
		(start 385.732274 -280.459942)
		(end 385.72186 -280.453846)
		(width 0.088646)
		(layer "In2.Cu")
		(net "M_F_CPU0_SA_DQ<0>")
	)
	(segment
		(start 388.711694 -284.35427)
		(end 387.9469 -282.507182)
		(width 0.18288)
		(layer "In2.Cu")
		(net "M_F_CPU0_SA_DQ<0>")
	)
	(segment
		(start 390.291574 -293.933372)
		(end 388.801102 -290.334954)
		(width 0.18288)
		(layer "In2.Cu")
		(net "M_F_CPU0_SA_DQ<0>")
	)
	(segment
		(start 420.736014 -316.316614)
		(end 420.297356 -316.755272)
		(width 0.18288)
		(layer "In2.Cu")
		(net "M_F_CPU0_SA_DQ<0>")
	)
	(segment
		(start 405.961342 -316.725046)
		(end 405.313642 -316.725046)
		(width 0.18288)
		(layer "In2.Cu")
		(net "M_F_CPU0_SA_DQ<0>")
	)
	(segment
		(start 405.313642 -316.725046)
		(end 393.446254 -304.857658)
		(width 0.18288)
		(layer "In2.Cu")
		(net "M_F_CPU0_SA_DQ<0>")
	)
	(segment
		(start 388.801102 -290.334954)
		(end 388.801102 -284.570424)
		(width 0.18288)
		(layer "In2.Cu")
		(net "M_F_CPU0_SA_DQ<0>")
	)
	(segment
		(start 388.801102 -284.570424)
		(end 388.711694 -284.35427)
		(width 0.18288)
		(layer "In2.Cu")
		(net "M_F_CPU0_SA_DQ<0>")
	)
	(segment
		(start 382.917192 -280.462482)
		(end 382.90246 -280.453846)
		(width 0.088646)
		(layer "In2.Cu")
		(net "M_F_CPU0_SA_DQ<0>")
	)
	(segment
		(start 407.712926 -316.725046)
		(end 407.44013 -316.725046)
		(width 0.18288)
		(layer "In2.Cu")
		(net "M_F_CPU0_SA_DQ<0>")
	)
	(segment
		(start 387.390132 -281.163014)
		(end 387.088126 -280.861008)
		(width 0.18288)
		(layer "In2.Cu")
		(net "M_F_CPU0_SA_DQ<0>")
	)
	(segment
		(start 381.680466 -279.986232)
		(end 381.680466 -279.964134)
		(width 0.088646)
		(layer "In2.Cu")
		(net "M_F_CPU0_SA_DQ<0>")
	)
	(segment
		(start 420.297356 -316.755272)
		(end 419.140386 -316.755272)
		(width 0.18288)
		(layer "In2.Cu")
		(net "M_F_CPU0_SA_DQ<0>")
	)
	(segment
		(start 408.028902 -316.40907)
		(end 407.712926 -316.725046)
		(width 0.18288)
		(layer "In2.Cu")
		(net "M_F_CPU0_SA_DQ<0>")
	)
	(segment
		(start 386.62991 -280.402792)
		(end 386.47497 -280.402792)
		(width 0.088646)
		(layer "In2.Cu")
		(net "M_F_CPU0_SA_DQ<0>")
	)
	(segment
		(start 413.832802 -317.155068)
		(end 413.244792 -316.567058)
		(width 0.18288)
		(layer "In2.Cu")
		(net "M_F_CPU0_SA_DQ<0>")
	)
	(segment
		(start 410.51353 -316.37859)
		(end 410.148786 -316.743334)
		(width 0.18288)
		(layer "In2.Cu")
		(net "M_F_CPU0_SA_DQ<0>")
	)
	(segment
		(start 413.244792 -316.567058)
		(end 412.445708 -316.567058)
		(width 0.18288)
		(layer "In2.Cu")
		(net "M_F_CPU0_SA_DQ<0>")
	)
	(segment
		(start 407.44013 -316.725046)
		(end 407.174446 -316.99073)
		(width 0.18288)
		(layer "In2.Cu")
		(net "M_F_CPU0_SA_DQ<0>")
	)
	(segment
		(start 410.148786 -316.743334)
		(end 409.44673 -316.743334)
		(width 0.18288)
		(layer "In2.Cu")
		(net "M_F_CPU0_SA_DQ<0>")
	)
	(segment
		(start 393.446254 -298.835826)
		(end 392.210544 -295.852342)
		(width 0.18288)
		(layer "In2.Cu")
		(net "M_F_CPU0_SA_DQ<0>")
	)
	(segment
		(start 415.359342 -316.40907)
		(end 414.613344 -317.155068)
		(width 0.18288)
		(layer "In2.Cu")
		(net "M_F_CPU0_SA_DQ<0>")
	)
	(segment
		(start 414.613344 -317.155068)
		(end 413.832802 -317.155068)
		(width 0.18288)
		(layer "In2.Cu")
		(net "M_F_CPU0_SA_DQ<0>")
	)
	(segment
		(start 416.50412 -316.40907)
		(end 415.359342 -316.40907)
		(width 0.18288)
		(layer "In2.Cu")
		(net "M_F_CPU0_SA_DQ<0>")
	)
	(segment
		(start 419.140386 -316.755272)
		(end 418.776404 -316.39129)
		(width 0.18288)
		(layer "In2.Cu")
		(net "M_F_CPU0_SA_DQ<0>")
	)
	(segment
		(start 411.563566 -316.743334)
		(end 411.198822 -316.37859)
		(width 0.18288)
		(layer "In2.Cu")
		(net "M_F_CPU0_SA_DQ<0>")
	)
	(segment
		(start 416.837876 -316.742826)
		(end 416.50412 -316.40907)
		(width 0.18288)
		(layer "In2.Cu")
		(net "M_F_CPU0_SA_DQ<0>")
	)
	(segment
		(start 407.174446 -316.99073)
		(end 406.227026 -316.99073)
		(width 0.18288)
		(layer "In2.Cu")
		(net "M_F_CPU0_SA_DQ<0>")
	)
	(segment
		(start 406.227026 -316.99073)
		(end 405.961342 -316.725046)
		(width 0.18288)
		(layer "In2.Cu")
		(net "M_F_CPU0_SA_DQ<0>")
	)
	(segment
		(start 411.198822 -316.37859)
		(end 410.51353 -316.37859)
		(width 0.18288)
		(layer "In2.Cu")
		(net "M_F_CPU0_SA_DQ<0>")
	)
	(arc
		(start 381.023114 -278.82596)
		(mid 380.833364 -278.646946)
		(end 380.744222 -278.40178)
		(width 0.088646)
		(layer "In2.Cu")
		(net "M_F_CPU0_SA_DQ<0>")
	)
	(arc
		(start 382.513332 -280.462482)
		(mid 382.236891 -280.529648)
		(end 381.96266 -280.453846)
		(width 0.088646)
		(layer "In2.Cu")
		(net "M_F_CPU0_SA_DQ<0>")
	)
	(arc
		(start 384.78206 -280.453846)
		(mid 384.594862 -280.403703)
		(end 384.407664 -280.453846)
		(width 0.088646)
		(layer "In2.Cu")
		(net "M_F_CPU0_SA_DQ<0>")
	)
	(arc
		(start 383.84226 -280.453846)
		(mid 383.655062 -280.403703)
		(end 383.467864 -280.453846)
		(width 0.088646)
		(layer "In2.Cu")
		(net "M_F_CPU0_SA_DQ<0>")
	)
	(arc
		(start 384.407664 -280.453846)
		(mid 384.124962 -280.529588)
		(end 383.84226 -280.453846)
		(width 0.088646)
		(layer "In2.Cu")
		(net "M_F_CPU0_SA_DQ<0>")
	)
	(arc
		(start 382.90246 -280.453846)
		(mid 382.715262 -280.403703)
		(end 382.528064 -280.453846)
		(width 0.088646)
		(layer "In2.Cu")
		(net "M_F_CPU0_SA_DQ<0>")
	)
	(arc
		(start 381.680466 -279.964134)
		(mid 381.632787 -279.781234)
		(end 381.501904 -279.644856)
		(width 0.088646)
		(layer "In2.Cu")
		(net "M_F_CPU0_SA_DQ<0>")
	)
	(arc
		(start 381.210312 -279.141682)
		(mid 381.158042 -278.959317)
		(end 381.023114 -278.82596)
		(width 0.088646)
		(layer "In2.Cu")
		(net "M_F_CPU0_SA_DQ<0>")
	)
	(arc
		(start 385.72186 -280.453846)
		(mid 385.534662 -280.403703)
		(end 385.347464 -280.453846)
		(width 0.088646)
		(layer "In2.Cu")
		(net "M_F_CPU0_SA_DQ<0>")
	)
	(arc
		(start 381.96266 -280.453846)
		(mid 381.761378 -280.256359)
		(end 381.680466 -279.986232)
		(width 0.088646)
		(layer "In2.Cu")
		(net "M_F_CPU0_SA_DQ<0>")
	)
	(arc
		(start 385.347464 -280.453846)
		(mid 385.064762 -280.529588)
		(end 384.78206 -280.453846)
		(width 0.088646)
		(layer "In2.Cu")
		(net "M_F_CPU0_SA_DQ<0>")
	)
	(arc
		(start 383.467864 -280.453846)
		(mid 383.193635 -280.529771)
		(end 382.917192 -280.462482)
		(width 0.088646)
		(layer "In2.Cu")
		(net "M_F_CPU0_SA_DQ<0>")
	)
	(arc
		(start 381.486918 -279.63622)
		(mid 381.284331 -279.429869)
		(end 381.210312 -279.150318)
		(width 0.088646)
		(layer "In2.Cu")
		(net "M_F_CPU0_SA_DQ<0>")
	)
	(arc
		(start 386.287518 -280.453846)
		(mid 386.010705 -280.529682)
		(end 385.732274 -280.459942)
		(width 0.088646)
		(layer "In2.Cu")
		(net "M_F_CPU0_SA_DQ<0>")
	)
	(arc
		(start 386.47497 -280.402792)
		(mid 386.377889 -280.415988)
		(end 386.287518 -280.453846)
		(width 0.088646)
		(layer "In2.Cu")
		(net "M_F_CPU0_SA_DQ<0>")
	)
	(segment
		(start 425.940982 -267.016738)
		(end 424.836082 -267.016738)
		(width 0.20066)
		(layer "F.Cu")
		(net "M_F_CPU0_SA_CS_N<3>")
	)
	(segment
		(start 381.305562 -258.2672)
		(end 381.305816 -258.267454)
		(width 0.20066)
		(layer "F.Cu")
		(net "M_F_CPU0_SA_CS_N<3>")
	)
	(segment
		(start 381.305816 -258.267454)
		(end 381.305816 -258.80314)
		(width 0.20066)
		(layer "F.Cu")
		(net "M_F_CPU0_SA_CS_N<3>")
	)
	(segment
		(start 387.567932 -259.051552)
		(end 387.422644 -259.051552)
		(width 0.088646)
		(layer "In2.Cu")
		(net "M_F_CPU0_SA_CS_N<3>")
	)
	(segment
		(start 383.012188 -259.135626)
		(end 382.997964 -259.127498)
		(width 0.088646)
		(layer "In2.Cu")
		(net "M_F_CPU0_SA_CS_N<3>")
	)
	(segment
		(start 420.626286 -267.441172)
		(end 420.626032 -267.440918)
		(width 0.18288)
		(layer "In2.Cu")
		(net "M_F_CPU0_SA_CS_N<3>")
	)
	(segment
		(start 394.822426 -259.18668)
		(end 394.034264 -258.86029)
		(width 0.18288)
		(layer "In2.Cu")
		(net "M_F_CPU0_SA_CS_N<3>")
	)
	(segment
		(start 412.52267 -265.163046)
		(end 412.083504 -265.163046)
		(width 0.18288)
		(layer "In2.Cu")
		(net "M_F_CPU0_SA_CS_N<3>")
	)
	(segment
		(start 418.145214 -266.280646)
		(end 417.786058 -266.639802)
		(width 0.18288)
		(layer "In2.Cu")
		(net "M_F_CPU0_SA_CS_N<3>")
	)
	(segment
		(start 415.605722 -264.876026)
		(end 413.4358 -264.876026)
		(width 0.18288)
		(layer "In2.Cu")
		(net "M_F_CPU0_SA_CS_N<3>")
	)
	(segment
		(start 417.786058 -266.639802)
		(end 417.108894 -266.639802)
		(width 0.18288)
		(layer "In2.Cu")
		(net "M_F_CPU0_SA_CS_N<3>")
	)
	(segment
		(start 382.443228 -259.121402)
		(end 382.432814 -259.127498)
		(width 0.088646)
		(layer "In2.Cu")
		(net "M_F_CPU0_SA_CS_N<3>")
	)
	(segment
		(start 423.344594 -267.440918)
		(end 422.297352 -267.440918)
		(width 0.18288)
		(layer "In2.Cu")
		(net "M_F_CPU0_SA_CS_N<3>")
	)
	(segment
		(start 424.596306 -267.256514)
		(end 423.528998 -267.256514)
		(width 0.18288)
		(layer "In2.Cu")
		(net "M_F_CPU0_SA_CS_N<3>")
	)
	(segment
		(start 384.326892 -259.118862)
		(end 384.31216 -259.127498)
		(width 0.088646)
		(layer "In2.Cu")
		(net "M_F_CPU0_SA_CS_N<3>")
	)
	(segment
		(start 411.83687 -264.916412)
		(end 409.505404 -264.916412)
		(width 0.18288)
		(layer "In2.Cu")
		(net "M_F_CPU0_SA_CS_N<3>")
	)
	(segment
		(start 387.759194 -258.86029)
		(end 387.567932 -259.051552)
		(width 0.088646)
		(layer "In2.Cu")
		(net "M_F_CPU0_SA_CS_N<3>")
	)
	(segment
		(start 416.795204 -266.326112)
		(end 416.795204 -266.065508)
		(width 0.18288)
		(layer "In2.Cu")
		(net "M_F_CPU0_SA_CS_N<3>")
	)
	(segment
		(start 412.619952 -264.81786)
		(end 412.619952 -265.065764)
		(width 0.18288)
		(layer "In2.Cu")
		(net "M_F_CPU0_SA_CS_N<3>")
	)
	(segment
		(start 381.312166 -258.818126)
		(end 381.305816 -258.80314)
		(width 0.088646)
		(layer "In2.Cu")
		(net "M_F_CPU0_SA_CS_N<3>")
	)
	(segment
		(start 405.371046 -264.060178)
		(end 403.908006 -262.597138)
		(width 0.18288)
		(layer "In2.Cu")
		(net "M_F_CPU0_SA_CS_N<3>")
	)
	(segment
		(start 413.184594 -264.62482)
		(end 412.812992 -264.62482)
		(width 0.18288)
		(layer "In2.Cu")
		(net "M_F_CPU0_SA_CS_N<3>")
	)
	(segment
		(start 403.908006 -262.597138)
		(end 403.408896 -262.597138)
		(width 0.18288)
		(layer "In2.Cu")
		(net "M_F_CPU0_SA_CS_N<3>")
	)
	(segment
		(start 418.529262 -266.280646)
		(end 418.145214 -266.280646)
		(width 0.18288)
		(layer "In2.Cu")
		(net "M_F_CPU0_SA_CS_N<3>")
	)
	(segment
		(start 383.384552 -259.12064)
		(end 383.372614 -259.127498)
		(width 0.088646)
		(layer "In2.Cu")
		(net "M_F_CPU0_SA_CS_N<3>")
	)
	(segment
		(start 420.46398 -267.440918)
		(end 419.672008 -266.648946)
		(width 0.18288)
		(layer "In2.Cu")
		(net "M_F_CPU0_SA_CS_N<3>")
	)
	(segment
		(start 417.108894 -266.639802)
		(end 416.795204 -266.326112)
		(width 0.18288)
		(layer "In2.Cu")
		(net "M_F_CPU0_SA_CS_N<3>")
	)
	(segment
		(start 422.297352 -267.440918)
		(end 421.978074 -267.12164)
		(width 0.18288)
		(layer "In2.Cu")
		(net "M_F_CPU0_SA_CS_N<3>")
	)
	(segment
		(start 382.058418 -259.127498)
		(end 381.312166 -258.818126)
		(width 0.088646)
		(layer "In2.Cu")
		(net "M_F_CPU0_SA_CS_N<3>")
	)
	(segment
		(start 421.337232 -267.441172)
		(end 420.626286 -267.441172)
		(width 0.18288)
		(layer "In2.Cu")
		(net "M_F_CPU0_SA_CS_N<3>")
	)
	(segment
		(start 421.656764 -267.12164)
		(end 421.337232 -267.441172)
		(width 0.18288)
		(layer "In2.Cu")
		(net "M_F_CPU0_SA_CS_N<3>")
	)
	(segment
		(start 409.505404 -264.916412)
		(end 408.64917 -264.060178)
		(width 0.18288)
		(layer "In2.Cu")
		(net "M_F_CPU0_SA_CS_N<3>")
	)
	(segment
		(start 418.897562 -266.648946)
		(end 418.529262 -266.280646)
		(width 0.18288)
		(layer "In2.Cu")
		(net "M_F_CPU0_SA_CS_N<3>")
	)
	(segment
		(start 412.083504 -265.163046)
		(end 411.83687 -264.916412)
		(width 0.18288)
		(layer "In2.Cu")
		(net "M_F_CPU0_SA_CS_N<3>")
	)
	(segment
		(start 394.034264 -258.86029)
		(end 388.840218 -258.86029)
		(width 0.18288)
		(layer "In2.Cu")
		(net "M_F_CPU0_SA_CS_N<3>")
	)
	(segment
		(start 383.024888 -259.141722)
		(end 383.012188 -259.135626)
		(width 0.088646)
		(layer "In2.Cu")
		(net "M_F_CPU0_SA_CS_N<3>")
	)
	(segment
		(start 408.64917 -264.060178)
		(end 405.371046 -264.060178)
		(width 0.18288)
		(layer "In2.Cu")
		(net "M_F_CPU0_SA_CS_N<3>")
	)
	(segment
		(start 413.4358 -264.876026)
		(end 413.184594 -264.62482)
		(width 0.18288)
		(layer "In2.Cu")
		(net "M_F_CPU0_SA_CS_N<3>")
	)
	(segment
		(start 419.672008 -266.648946)
		(end 418.897562 -266.648946)
		(width 0.18288)
		(layer "In2.Cu")
		(net "M_F_CPU0_SA_CS_N<3>")
	)
	(segment
		(start 386.206492 -259.118862)
		(end 386.19176 -259.127498)
		(width 0.088646)
		(layer "In2.Cu")
		(net "M_F_CPU0_SA_CS_N<3>")
	)
	(segment
		(start 412.619952 -265.065764)
		(end 412.52267 -265.163046)
		(width 0.18288)
		(layer "In2.Cu")
		(net "M_F_CPU0_SA_CS_N<3>")
	)
	(segment
		(start 387.146292 -259.118862)
		(end 387.13156 -259.127498)
		(width 0.088646)
		(layer "In2.Cu")
		(net "M_F_CPU0_SA_CS_N<3>")
	)
	(segment
		(start 416.795204 -266.065508)
		(end 415.605722 -264.876026)
		(width 0.18288)
		(layer "In2.Cu")
		(net "M_F_CPU0_SA_CS_N<3>")
	)
	(segment
		(start 423.528998 -267.256514)
		(end 423.344594 -267.440918)
		(width 0.18288)
		(layer "In2.Cu")
		(net "M_F_CPU0_SA_CS_N<3>")
	)
	(segment
		(start 385.266692 -259.118862)
		(end 385.25196 -259.127498)
		(width 0.088646)
		(layer "In2.Cu")
		(net "M_F_CPU0_SA_CS_N<3>")
	)
	(segment
		(start 403.408896 -262.597138)
		(end 401.157948 -260.34619)
		(width 0.18288)
		(layer "In2.Cu")
		(net "M_F_CPU0_SA_CS_N<3>")
	)
	(segment
		(start 421.978074 -267.12164)
		(end 421.656764 -267.12164)
		(width 0.18288)
		(layer "In2.Cu")
		(net "M_F_CPU0_SA_CS_N<3>")
	)
	(segment
		(start 388.840218 -258.86029)
		(end 387.759194 -258.86029)
		(width 0.088646)
		(layer "In2.Cu")
		(net "M_F_CPU0_SA_CS_N<3>")
	)
	(segment
		(start 412.812992 -264.62482)
		(end 412.619952 -264.81786)
		(width 0.18288)
		(layer "In2.Cu")
		(net "M_F_CPU0_SA_CS_N<3>")
	)
	(segment
		(start 395.981936 -260.34619)
		(end 394.822426 -259.18668)
		(width 0.18288)
		(layer "In2.Cu")
		(net "M_F_CPU0_SA_CS_N<3>")
	)
	(segment
		(start 401.157948 -260.34619)
		(end 395.981936 -260.34619)
		(width 0.18288)
		(layer "In2.Cu")
		(net "M_F_CPU0_SA_CS_N<3>")
	)
	(segment
		(start 420.626032 -267.440918)
		(end 420.46398 -267.440918)
		(width 0.18288)
		(layer "In2.Cu")
		(net "M_F_CPU0_SA_CS_N<3>")
	)
	(segment
		(start 424.836082 -267.016738)
		(end 424.596306 -267.256514)
		(width 0.18288)
		(layer "In2.Cu")
		(net "M_F_CPU0_SA_CS_N<3>")
	)
	(segment
		(start 383.937764 -259.127498)
		(end 383.93751 -259.127498)
		(width 0.088646)
		(layer "In2.Cu")
		(net "M_F_CPU0_SA_CS_N<3>")
	)
	(arc
		(start 386.19176 -259.127498)
		(mid 386.004562 -259.177641)
		(end 385.817364 -259.127498)
		(width 0.088646)
		(layer "In2.Cu")
		(net "M_F_CPU0_SA_CS_N<3>")
	)
	(arc
		(start 387.422644 -259.051552)
		(mid 387.280169 -259.067553)
		(end 387.146292 -259.118862)
		(width 0.088646)
		(layer "In2.Cu")
		(net "M_F_CPU0_SA_CS_N<3>")
	)
	(arc
		(start 383.93751 -259.127498)
		(mid 383.936367 -259.126989)
		(end 383.935224 -259.126482)
		(width 0.088646)
		(layer "In2.Cu")
		(net "M_F_CPU0_SA_CS_N<3>")
	)
	(arc
		(start 387.13156 -259.127498)
		(mid 386.944362 -259.177641)
		(end 386.757164 -259.127498)
		(width 0.088646)
		(layer "In2.Cu")
		(net "M_F_CPU0_SA_CS_N<3>")
	)
	(arc
		(start 386.757164 -259.127498)
		(mid 386.482965 -259.051663)
		(end 386.206492 -259.118862)
		(width 0.088646)
		(layer "In2.Cu")
		(net "M_F_CPU0_SA_CS_N<3>")
	)
	(arc
		(start 382.997964 -259.127498)
		(mid 382.721405 -259.051755)
		(end 382.443228 -259.121402)
		(width 0.088646)
		(layer "In2.Cu")
		(net "M_F_CPU0_SA_CS_N<3>")
	)
	(arc
		(start 385.25196 -259.127498)
		(mid 385.064762 -259.177641)
		(end 384.877564 -259.127498)
		(width 0.088646)
		(layer "In2.Cu")
		(net "M_F_CPU0_SA_CS_N<3>")
	)
	(arc
		(start 382.432814 -259.127498)
		(mid 382.245616 -259.177641)
		(end 382.058418 -259.127498)
		(width 0.088646)
		(layer "In2.Cu")
		(net "M_F_CPU0_SA_CS_N<3>")
	)
	(arc
		(start 384.877564 -259.127498)
		(mid 384.603365 -259.051663)
		(end 384.326892 -259.118862)
		(width 0.088646)
		(layer "In2.Cu")
		(net "M_F_CPU0_SA_CS_N<3>")
	)
	(arc
		(start 384.31216 -259.127498)
		(mid 384.124962 -259.177641)
		(end 383.937764 -259.127498)
		(width 0.088646)
		(layer "In2.Cu")
		(net "M_F_CPU0_SA_CS_N<3>")
	)
	(arc
		(start 385.817364 -259.127498)
		(mid 385.543165 -259.051663)
		(end 385.266692 -259.118862)
		(width 0.088646)
		(layer "In2.Cu")
		(net "M_F_CPU0_SA_CS_N<3>")
	)
	(arc
		(start 383.346706 -259.14096)
		(mid 383.344418 -259.142099)
		(end 383.342134 -259.143246)
		(width 0.088646)
		(layer "In2.Cu")
		(net "M_F_CPU0_SA_CS_N<3>")
	)
	(arc
		(start 383.935224 -259.126482)
		(mid 383.664102 -259.051935)
		(end 383.390648 -259.117338)
		(width 0.088646)
		(layer "In2.Cu")
		(net "M_F_CPU0_SA_CS_N<3>")
	)
	(arc
		(start 383.390648 -259.117338)
		(mid 383.387585 -259.11896)
		(end 383.384552 -259.12064)
		(width 0.088646)
		(layer "In2.Cu")
		(net "M_F_CPU0_SA_CS_N<3>")
	)
	(arc
		(start 383.372614 -259.127498)
		(mid 383.35979 -259.134479)
		(end 383.346706 -259.14096)
		(width 0.088646)
		(layer "In2.Cu")
		(net "M_F_CPU0_SA_CS_N<3>")
	)
	(arc
		(start 383.342134 -259.143246)
		(mid 383.183344 -259.177718)
		(end 383.024888 -259.141722)
		(width 0.088646)
		(layer "In2.Cu")
		(net "M_F_CPU0_SA_CS_N<3>")
	)
	(segment
		(start 420.659814 -267.866622)
		(end 421.840914 -267.866622)
		(width 0.20066)
		(layer "F.Cu")
		(net "M_F_CPU0_SA_CS_N<2>")
	)
	(segment
		(start 381.775716 -259.081016)
		(end 381.775716 -259.616702)
		(width 0.20066)
		(layer "F.Cu")
		(net "M_F_CPU0_SA_CS_N<2>")
	)
	(segment
		(start 381.775716 -259.616702)
		(end 381.775462 -259.616956)
		(width 0.20066)
		(layer "F.Cu")
		(net "M_F_CPU0_SA_CS_N<2>")
	)
	(segment
		(start 382.125982 -259.470144)
		(end 381.775462 -259.616956)
		(width 0.088646)
		(layer "In2.Cu")
		(net "M_F_CPU0_SA_CS_N<2>")
	)
	(segment
		(start 395.902688 -260.862572)
		(end 394.61059 -259.570474)
		(width 0.18288)
		(layer "In2.Cu")
		(net "M_F_CPU0_SA_CS_N<2>")
	)
	(segment
		(start 415.638234 -266.630658)
		(end 415.638234 -266.369038)
		(width 0.18288)
		(layer "In2.Cu")
		(net "M_F_CPU0_SA_CS_N<2>")
	)
	(segment
		(start 408.705558 -265.513058)
		(end 408.705558 -264.881106)
		(width 0.18288)
		(layer "In2.Cu")
		(net "M_F_CPU0_SA_CS_N<2>")
	)
	(segment
		(start 383.479548 -259.28574)
		(end 383.46761 -259.292598)
		(width 0.088646)
		(layer "In2.Cu")
		(net "M_F_CPU0_SA_CS_N<2>")
	)
	(segment
		(start 418.960808 -267.740384)
		(end 417.80206 -267.740384)
		(width 0.18288)
		(layer "In2.Cu")
		(net "M_F_CPU0_SA_CS_N<2>")
	)
	(segment
		(start 409.386786 -265.815572)
		(end 409.008072 -265.815572)
		(width 0.18288)
		(layer "In2.Cu")
		(net "M_F_CPU0_SA_CS_N<2>")
	)
	(segment
		(start 416.479228 -266.770612)
		(end 416.253168 -266.770612)
		(width 0.18288)
		(layer "In2.Cu")
		(net "M_F_CPU0_SA_CS_N<2>")
	)
	(segment
		(start 416.905948 -267.197332)
		(end 416.479228 -266.770612)
		(width 0.18288)
		(layer "In2.Cu")
		(net "M_F_CPU0_SA_CS_N<2>")
	)
	(segment
		(start 408.705558 -264.881106)
		(end 408.42311 -264.598658)
		(width 0.18288)
		(layer "In2.Cu")
		(net "M_F_CPU0_SA_CS_N<2>")
	)
	(segment
		(start 411.428692 -266.048998)
		(end 410.3751 -266.048998)
		(width 0.18288)
		(layer "In2.Cu")
		(net "M_F_CPU0_SA_CS_N<2>")
	)
	(segment
		(start 382.902714 -259.292598)
		(end 382.90246 -259.292598)
		(width 0.088646)
		(layer "In2.Cu")
		(net "M_F_CPU0_SA_CS_N<2>")
	)
	(segment
		(start 413.374078 -265.746738)
		(end 413.374078 -266.281662)
		(width 0.18288)
		(layer "In2.Cu")
		(net "M_F_CPU0_SA_CS_N<2>")
	)
	(segment
		(start 409.62707 -265.575288)
		(end 409.386786 -265.815572)
		(width 0.18288)
		(layer "In2.Cu")
		(net "M_F_CPU0_SA_CS_N<2>")
	)
	(segment
		(start 419.339268 -267.361924)
		(end 418.960808 -267.740384)
		(width 0.18288)
		(layer "In2.Cu")
		(net "M_F_CPU0_SA_CS_N<2>")
	)
	(segment
		(start 404.804372 -264.850372)
		(end 404.555706 -264.601706)
		(width 0.18288)
		(layer "In2.Cu")
		(net "M_F_CPU0_SA_CS_N<2>")
	)
	(segment
		(start 394.61059 -259.570474)
		(end 393.73429 -259.207508)
		(width 0.18288)
		(layer "In2.Cu")
		(net "M_F_CPU0_SA_CS_N<2>")
	)
	(segment
		(start 387.22681 -259.292598)
		(end 387.212078 -259.301234)
		(width 0.088646)
		(layer "In2.Cu")
		(net "M_F_CPU0_SA_CS_N<2>")
	)
	(segment
		(start 412.172658 -265.739372)
		(end 411.738318 -265.739372)
		(width 0.18288)
		(layer "In2.Cu")
		(net "M_F_CPU0_SA_CS_N<2>")
	)
	(segment
		(start 387.688582 -259.207508)
		(end 387.65353 -259.24256)
		(width 0.088646)
		(layer "In2.Cu")
		(net "M_F_CPU0_SA_CS_N<2>")
	)
	(segment
		(start 409.008072 -265.815572)
		(end 408.705558 -265.513058)
		(width 0.18288)
		(layer "In2.Cu")
		(net "M_F_CPU0_SA_CS_N<2>")
	)
	(segment
		(start 385.34721 -259.292598)
		(end 385.332478 -259.301234)
		(width 0.088646)
		(layer "In2.Cu")
		(net "M_F_CPU0_SA_CS_N<2>")
	)
	(segment
		(start 388.840218 -259.207508)
		(end 387.688582 -259.207508)
		(width 0.088646)
		(layer "In2.Cu")
		(net "M_F_CPU0_SA_CS_N<2>")
	)
	(segment
		(start 412.907988 -266.474702)
		(end 412.172658 -265.739372)
		(width 0.18288)
		(layer "In2.Cu")
		(net "M_F_CPU0_SA_CS_N<2>")
	)
	(segment
		(start 405.825452 -264.850372)
		(end 404.804372 -264.850372)
		(width 0.18288)
		(layer "In2.Cu")
		(net "M_F_CPU0_SA_CS_N<2>")
	)
	(segment
		(start 419.612572 -267.361924)
		(end 419.339268 -267.361924)
		(width 0.18288)
		(layer "In2.Cu")
		(net "M_F_CPU0_SA_CS_N<2>")
	)
	(segment
		(start 406.672288 -264.995406)
		(end 406.490678 -265.177016)
		(width 0.18288)
		(layer "In2.Cu")
		(net "M_F_CPU0_SA_CS_N<2>")
	)
	(segment
		(start 400.816572 -260.862572)
		(end 395.902688 -260.862572)
		(width 0.18288)
		(layer "In2.Cu")
		(net "M_F_CPU0_SA_CS_N<2>")
	)
	(segment
		(start 413.181038 -266.474702)
		(end 412.907988 -266.474702)
		(width 0.18288)
		(layer "In2.Cu")
		(net "M_F_CPU0_SA_CS_N<2>")
	)
	(segment
		(start 413.374078 -266.281662)
		(end 413.181038 -266.474702)
		(width 0.18288)
		(layer "In2.Cu")
		(net "M_F_CPU0_SA_CS_N<2>")
	)
	(segment
		(start 411.738318 -265.739372)
		(end 411.428692 -266.048998)
		(width 0.18288)
		(layer "In2.Cu")
		(net "M_F_CPU0_SA_CS_N<2>")
	)
	(segment
		(start 416.128708 -266.895072)
		(end 415.902648 -266.895072)
		(width 0.18288)
		(layer "In2.Cu")
		(net "M_F_CPU0_SA_CS_N<2>")
	)
	(segment
		(start 416.253168 -266.770612)
		(end 416.128708 -266.895072)
		(width 0.18288)
		(layer "In2.Cu")
		(net "M_F_CPU0_SA_CS_N<2>")
	)
	(segment
		(start 417.80206 -267.740384)
		(end 417.259008 -267.197332)
		(width 0.18288)
		(layer "In2.Cu")
		(net "M_F_CPU0_SA_CS_N<2>")
	)
	(segment
		(start 415.648394 -265.80719)
		(end 415.224468 -265.80719)
		(width 0.18288)
		(layer "In2.Cu")
		(net "M_F_CPU0_SA_CS_N<2>")
	)
	(segment
		(start 404.555706 -264.142982)
		(end 404.286974 -263.87425)
		(width 0.18288)
		(layer "In2.Cu")
		(net "M_F_CPU0_SA_CS_N<2>")
	)
	(segment
		(start 410.3751 -266.048998)
		(end 409.90139 -265.575288)
		(width 0.18288)
		(layer "In2.Cu")
		(net "M_F_CPU0_SA_CS_N<2>")
	)
	(segment
		(start 384.40741 -259.292598)
		(end 384.392678 -259.301234)
		(width 0.088646)
		(layer "In2.Cu")
		(net "M_F_CPU0_SA_CS_N<2>")
	)
	(segment
		(start 404.555706 -264.601706)
		(end 404.555706 -264.142982)
		(width 0.18288)
		(layer "In2.Cu")
		(net "M_F_CPU0_SA_CS_N<2>")
	)
	(segment
		(start 406.152096 -265.177016)
		(end 405.825452 -264.850372)
		(width 0.18288)
		(layer "In2.Cu")
		(net "M_F_CPU0_SA_CS_N<2>")
	)
	(segment
		(start 420.11727 -267.866622)
		(end 419.612572 -267.361924)
		(width 0.18288)
		(layer "In2.Cu")
		(net "M_F_CPU0_SA_CS_N<2>")
	)
	(segment
		(start 415.224468 -265.80719)
		(end 414.87979 -265.462512)
		(width 0.18288)
		(layer "In2.Cu")
		(net "M_F_CPU0_SA_CS_N<2>")
	)
	(segment
		(start 382.528064 -259.292598)
		(end 382.513332 -259.301234)
		(width 0.088646)
		(layer "In2.Cu")
		(net "M_F_CPU0_SA_CS_N<2>")
	)
	(segment
		(start 414.87979 -265.462512)
		(end 413.658304 -265.462512)
		(width 0.18288)
		(layer "In2.Cu")
		(net "M_F_CPU0_SA_CS_N<2>")
	)
	(segment
		(start 407.402538 -264.995406)
		(end 406.672288 -264.995406)
		(width 0.18288)
		(layer "In2.Cu")
		(net "M_F_CPU0_SA_CS_N<2>")
	)
	(segment
		(start 408.42311 -264.598658)
		(end 407.799286 -264.598658)
		(width 0.18288)
		(layer "In2.Cu")
		(net "M_F_CPU0_SA_CS_N<2>")
	)
	(segment
		(start 413.658304 -265.462512)
		(end 413.374078 -265.746738)
		(width 0.18288)
		(layer "In2.Cu")
		(net "M_F_CPU0_SA_CS_N<2>")
	)
	(segment
		(start 415.902648 -266.895072)
		(end 415.638234 -266.630658)
		(width 0.18288)
		(layer "In2.Cu")
		(net "M_F_CPU0_SA_CS_N<2>")
	)
	(segment
		(start 415.809938 -265.968734)
		(end 415.648394 -265.80719)
		(width 0.18288)
		(layer "In2.Cu")
		(net "M_F_CPU0_SA_CS_N<2>")
	)
	(segment
		(start 420.659814 -267.866622)
		(end 420.11727 -267.866622)
		(width 0.18288)
		(layer "In2.Cu")
		(net "M_F_CPU0_SA_CS_N<2>")
	)
	(segment
		(start 406.490678 -265.177016)
		(end 406.152096 -265.177016)
		(width 0.18288)
		(layer "In2.Cu")
		(net "M_F_CPU0_SA_CS_N<2>")
	)
	(segment
		(start 415.638234 -266.369038)
		(end 415.809938 -266.197334)
		(width 0.18288)
		(layer "In2.Cu")
		(net "M_F_CPU0_SA_CS_N<2>")
	)
	(segment
		(start 403.82825 -263.87425)
		(end 400.816572 -260.862572)
		(width 0.18288)
		(layer "In2.Cu")
		(net "M_F_CPU0_SA_CS_N<2>")
	)
	(segment
		(start 409.90139 -265.575288)
		(end 409.62707 -265.575288)
		(width 0.18288)
		(layer "In2.Cu")
		(net "M_F_CPU0_SA_CS_N<2>")
	)
	(segment
		(start 386.28701 -259.292598)
		(end 386.272278 -259.301234)
		(width 0.088646)
		(layer "In2.Cu")
		(net "M_F_CPU0_SA_CS_N<2>")
	)
	(segment
		(start 404.286974 -263.87425)
		(end 403.82825 -263.87425)
		(width 0.18288)
		(layer "In2.Cu")
		(net "M_F_CPU0_SA_CS_N<2>")
	)
	(segment
		(start 393.73429 -259.207508)
		(end 388.840218 -259.207508)
		(width 0.18288)
		(layer "In2.Cu")
		(net "M_F_CPU0_SA_CS_N<2>")
	)
	(segment
		(start 382.307846 -259.365242)
		(end 382.125982 -259.470144)
		(width 0.088646)
		(layer "In2.Cu")
		(net "M_F_CPU0_SA_CS_N<2>")
	)
	(segment
		(start 417.259008 -267.197332)
		(end 416.905948 -267.197332)
		(width 0.18288)
		(layer "In2.Cu")
		(net "M_F_CPU0_SA_CS_N<2>")
	)
	(segment
		(start 415.809938 -266.197334)
		(end 415.809938 -265.968734)
		(width 0.18288)
		(layer "In2.Cu")
		(net "M_F_CPU0_SA_CS_N<2>")
	)
	(segment
		(start 387.65353 -259.24256)
		(end 387.414008 -259.24256)
		(width 0.088646)
		(layer "In2.Cu")
		(net "M_F_CPU0_SA_CS_N<2>")
	)
	(segment
		(start 407.799286 -264.598658)
		(end 407.402538 -264.995406)
		(width 0.18288)
		(layer "In2.Cu")
		(net "M_F_CPU0_SA_CS_N<2>")
	)
	(arc
		(start 383.842006 -259.292598)
		(mid 383.661659 -259.242395)
		(end 383.479548 -259.28574)
		(width 0.088646)
		(layer "In2.Cu")
		(net "M_F_CPU0_SA_CS_N<2>")
	)
	(arc
		(start 383.46761 -259.292598)
		(mid 383.185162 -259.368247)
		(end 382.902714 -259.292598)
		(width 0.088646)
		(layer "In2.Cu")
		(net "M_F_CPU0_SA_CS_N<2>")
	)
	(arc
		(start 384.781806 -259.292598)
		(mid 384.594608 -259.242455)
		(end 384.40741 -259.292598)
		(width 0.088646)
		(layer "In2.Cu")
		(net "M_F_CPU0_SA_CS_N<2>")
	)
	(arc
		(start 387.212078 -259.301234)
		(mid 386.935603 -259.368554)
		(end 386.661406 -259.292598)
		(width 0.088646)
		(layer "In2.Cu")
		(net "M_F_CPU0_SA_CS_N<2>")
	)
	(arc
		(start 387.414008 -259.24256)
		(mid 387.317111 -259.255248)
		(end 387.22681 -259.292598)
		(width 0.088646)
		(layer "In2.Cu")
		(net "M_F_CPU0_SA_CS_N<2>")
	)
	(arc
		(start 382.90246 -259.292598)
		(mid 382.715262 -259.242455)
		(end 382.528064 -259.292598)
		(width 0.088646)
		(layer "In2.Cu")
		(net "M_F_CPU0_SA_CS_N<2>")
	)
	(arc
		(start 384.392678 -259.301234)
		(mid 384.116203 -259.368554)
		(end 383.842006 -259.292598)
		(width 0.088646)
		(layer "In2.Cu")
		(net "M_F_CPU0_SA_CS_N<2>")
	)
	(arc
		(start 385.332478 -259.301234)
		(mid 385.056003 -259.368554)
		(end 384.781806 -259.292598)
		(width 0.088646)
		(layer "In2.Cu")
		(net "M_F_CPU0_SA_CS_N<2>")
	)
	(arc
		(start 386.272278 -259.301234)
		(mid 385.995803 -259.368554)
		(end 385.721606 -259.292598)
		(width 0.088646)
		(layer "In2.Cu")
		(net "M_F_CPU0_SA_CS_N<2>")
	)
	(arc
		(start 386.661406 -259.292598)
		(mid 386.474208 -259.242455)
		(end 386.28701 -259.292598)
		(width 0.088646)
		(layer "In2.Cu")
		(net "M_F_CPU0_SA_CS_N<2>")
	)
	(arc
		(start 385.721606 -259.292598)
		(mid 385.534408 -259.242455)
		(end 385.34721 -259.292598)
		(width 0.088646)
		(layer "In2.Cu")
		(net "M_F_CPU0_SA_CS_N<2>")
	)
	(arc
		(start 382.513332 -259.301234)
		(mid 382.413657 -259.343077)
		(end 382.307846 -259.365242)
		(width 0.088646)
		(layer "In2.Cu")
		(net "M_F_CPU0_SA_CS_N<2>")
	)
	(segment
		(start 433.484782 -267.016738)
		(end 432.379882 -267.016738)
		(width 0.20066)
		(layer "F.Cu")
		(net "M_F_CPU0_SA_CS_N<1>")
	)
	(segment
		(start 383.185162 -258.2672)
		(end 383.185162 -258.80314)
		(width 0.20066)
		(layer "F.Cu")
		(net "M_F_CPU0_SA_CS_N<1>")
	)
	(segment
		(start 411.843728 -263.880092)
		(end 411.372558 -264.351262)
		(width 0.18288)
		(layer "In2.Cu")
		(net "M_F_CPU0_SA_CS_N<1>")
	)
	(segment
		(start 383.937764 -258.478782)
		(end 383.54127 -258.70789)
		(width 0.088646)
		(layer "In2.Cu")
		(net "M_F_CPU0_SA_CS_N<1>")
	)
	(segment
		(start 428.469298 -266.480544)
		(end 428.020988 -266.480544)
		(width 0.18288)
		(layer "In2.Cu")
		(net "M_F_CPU0_SA_CS_N<1>")
	)
	(segment
		(start 408.52725 -263.179814)
		(end 407.594054 -263.179814)
		(width 0.18288)
		(layer "In2.Cu")
		(net "M_F_CPU0_SA_CS_N<1>")
	)
	(segment
		(start 428.753016 -266.764262)
		(end 428.469298 -266.480544)
		(width 0.18288)
		(layer "In2.Cu")
		(net "M_F_CPU0_SA_CS_N<1>")
	)
	(segment
		(start 409.997402 -264.034016)
		(end 409.381452 -264.034016)
		(width 0.18288)
		(layer "In2.Cu")
		(net "M_F_CPU0_SA_CS_N<1>")
	)
	(segment
		(start 385.817364 -258.478782)
		(end 385.802632 -258.487418)
		(width 0.088646)
		(layer "In2.Cu")
		(net "M_F_CPU0_SA_CS_N<1>")
	)
	(segment
		(start 412.214568 -263.880092)
		(end 411.843728 -263.880092)
		(width 0.18288)
		(layer "In2.Cu")
		(net "M_F_CPU0_SA_CS_N<1>")
	)
	(segment
		(start 401.359624 -259.803138)
		(end 396.010384 -259.803138)
		(width 0.18288)
		(layer "In2.Cu")
		(net "M_F_CPU0_SA_CS_N<1>")
	)
	(segment
		(start 407.594054 -263.179814)
		(end 407.321004 -263.452864)
		(width 0.18288)
		(layer "In2.Cu")
		(net "M_F_CPU0_SA_CS_N<1>")
	)
	(segment
		(start 412.412688 -264.078212)
		(end 412.214568 -263.880092)
		(width 0.18288)
		(layer "In2.Cu")
		(net "M_F_CPU0_SA_CS_N<1>")
	)
	(segment
		(start 428.020988 -266.480544)
		(end 427.827948 -266.673584)
		(width 0.18288)
		(layer "In2.Cu")
		(net "M_F_CPU0_SA_CS_N<1>")
	)
	(segment
		(start 405.045418 -263.003284)
		(end 404.107142 -262.065008)
		(width 0.18288)
		(layer "In2.Cu")
		(net "M_F_CPU0_SA_CS_N<1>")
	)
	(segment
		(start 427.078648 -266.78382)
		(end 426.885608 -266.59078)
		(width 0.18288)
		(layer "In2.Cu")
		(net "M_F_CPU0_SA_CS_N<1>")
	)
	(segment
		(start 404.107142 -262.065008)
		(end 403.621494 -262.065008)
		(width 0.18288)
		(layer "In2.Cu")
		(net "M_F_CPU0_SA_CS_N<1>")
	)
	(segment
		(start 406.18029 -263.452864)
		(end 405.73071 -263.003284)
		(width 0.18288)
		(layer "In2.Cu")
		(net "M_F_CPU0_SA_CS_N<1>")
	)
	(segment
		(start 420.139622 -266.32916)
		(end 420.139622 -266.15644)
		(width 0.18288)
		(layer "In2.Cu")
		(net "M_F_CPU0_SA_CS_N<1>")
	)
	(segment
		(start 430.035208 -266.806426)
		(end 430.035208 -267.179298)
		(width 0.18288)
		(layer "In2.Cu")
		(net "M_F_CPU0_SA_CS_N<1>")
	)
	(segment
		(start 405.73071 -263.003284)
		(end 405.045418 -263.003284)
		(width 0.18288)
		(layer "In2.Cu")
		(net "M_F_CPU0_SA_CS_N<1>")
	)
	(segment
		(start 432.379882 -267.016738)
		(end 431.858928 -266.495784)
		(width 0.18288)
		(layer "In2.Cu")
		(net "M_F_CPU0_SA_CS_N<1>")
	)
	(segment
		(start 431.858928 -266.495784)
		(end 430.34585 -266.495784)
		(width 0.18288)
		(layer "In2.Cu")
		(net "M_F_CPU0_SA_CS_N<1>")
	)
	(segment
		(start 419.699694 -265.716512)
		(end 417.56965 -265.716512)
		(width 0.18288)
		(layer "In2.Cu")
		(net "M_F_CPU0_SA_CS_N<1>")
	)
	(segment
		(start 429.842168 -267.372338)
		(end 428.946056 -267.372338)
		(width 0.18288)
		(layer "In2.Cu")
		(net "M_F_CPU0_SA_CS_N<1>")
	)
	(segment
		(start 420.398702 -266.58824)
		(end 420.139622 -266.32916)
		(width 0.18288)
		(layer "In2.Cu")
		(net "M_F_CPU0_SA_CS_N<1>")
	)
	(segment
		(start 426.885608 -266.59078)
		(end 423.633646 -266.59078)
		(width 0.18288)
		(layer "In2.Cu")
		(net "M_F_CPU0_SA_CS_N<1>")
	)
	(segment
		(start 422.712896 -266.58824)
		(end 420.398702 -266.58824)
		(width 0.18288)
		(layer "In2.Cu")
		(net "M_F_CPU0_SA_CS_N<1>")
	)
	(segment
		(start 427.827948 -267.109702)
		(end 427.667928 -267.269722)
		(width 0.18288)
		(layer "In2.Cu")
		(net "M_F_CPU0_SA_CS_N<1>")
	)
	(segment
		(start 427.078648 -267.053822)
		(end 427.078648 -266.78382)
		(width 0.18288)
		(layer "In2.Cu")
		(net "M_F_CPU0_SA_CS_N<1>")
	)
	(segment
		(start 395.048994 -258.841748)
		(end 394.164566 -258.47548)
		(width 0.18288)
		(layer "In2.Cu")
		(net "M_F_CPU0_SA_CS_N<1>")
	)
	(segment
		(start 423.530776 -266.48791)
		(end 422.813226 -266.48791)
		(width 0.18288)
		(layer "In2.Cu")
		(net "M_F_CPU0_SA_CS_N<1>")
	)
	(segment
		(start 417.37534 -265.522202)
		(end 416.973004 -265.522202)
		(width 0.18288)
		(layer "In2.Cu")
		(net "M_F_CPU0_SA_CS_N<1>")
	)
	(segment
		(start 415.529014 -264.078212)
		(end 412.412688 -264.078212)
		(width 0.18288)
		(layer "In2.Cu")
		(net "M_F_CPU0_SA_CS_N<1>")
	)
	(segment
		(start 394.164566 -258.47548)
		(end 388.840218 -258.47548)
		(width 0.18288)
		(layer "In2.Cu")
		(net "M_F_CPU0_SA_CS_N<1>")
	)
	(segment
		(start 427.667928 -267.269722)
		(end 427.294548 -267.269722)
		(width 0.18288)
		(layer "In2.Cu")
		(net "M_F_CPU0_SA_CS_N<1>")
	)
	(segment
		(start 428.946056 -267.372338)
		(end 428.753016 -267.179298)
		(width 0.18288)
		(layer "In2.Cu")
		(net "M_F_CPU0_SA_CS_N<1>")
	)
	(segment
		(start 416.973004 -265.522202)
		(end 415.529014 -264.078212)
		(width 0.18288)
		(layer "In2.Cu")
		(net "M_F_CPU0_SA_CS_N<1>")
	)
	(segment
		(start 428.753016 -267.179298)
		(end 428.753016 -266.764262)
		(width 0.18288)
		(layer "In2.Cu")
		(net "M_F_CPU0_SA_CS_N<1>")
	)
	(segment
		(start 410.314648 -264.351262)
		(end 409.997402 -264.034016)
		(width 0.18288)
		(layer "In2.Cu")
		(net "M_F_CPU0_SA_CS_N<1>")
	)
	(segment
		(start 403.621494 -262.065008)
		(end 401.359624 -259.803138)
		(width 0.18288)
		(layer "In2.Cu")
		(net "M_F_CPU0_SA_CS_N<1>")
	)
	(segment
		(start 420.139622 -266.15644)
		(end 419.699694 -265.716512)
		(width 0.18288)
		(layer "In2.Cu")
		(net "M_F_CPU0_SA_CS_N<1>")
	)
	(segment
		(start 409.381452 -264.034016)
		(end 408.52725 -263.179814)
		(width 0.18288)
		(layer "In2.Cu")
		(net "M_F_CPU0_SA_CS_N<1>")
	)
	(segment
		(start 417.56965 -265.716512)
		(end 417.37534 -265.522202)
		(width 0.18288)
		(layer "In2.Cu")
		(net "M_F_CPU0_SA_CS_N<1>")
	)
	(segment
		(start 396.010384 -259.803138)
		(end 395.048994 -258.841748)
		(width 0.18288)
		(layer "In2.Cu")
		(net "M_F_CPU0_SA_CS_N<1>")
	)
	(segment
		(start 422.813226 -266.48791)
		(end 422.712896 -266.58824)
		(width 0.18288)
		(layer "In2.Cu")
		(net "M_F_CPU0_SA_CS_N<1>")
	)
	(segment
		(start 388.840218 -258.47548)
		(end 387.722872 -258.47548)
		(width 0.088646)
		(layer "In2.Cu")
		(net "M_F_CPU0_SA_CS_N<1>")
	)
	(segment
		(start 423.633646 -266.59078)
		(end 423.530776 -266.48791)
		(width 0.18288)
		(layer "In2.Cu")
		(net "M_F_CPU0_SA_CS_N<1>")
	)
	(segment
		(start 427.294548 -267.269722)
		(end 427.078648 -267.053822)
		(width 0.18288)
		(layer "In2.Cu")
		(net "M_F_CPU0_SA_CS_N<1>")
	)
	(segment
		(start 427.827948 -266.673584)
		(end 427.827948 -267.109702)
		(width 0.18288)
		(layer "In2.Cu")
		(net "M_F_CPU0_SA_CS_N<1>")
	)
	(segment
		(start 430.035208 -267.179298)
		(end 429.842168 -267.372338)
		(width 0.18288)
		(layer "In2.Cu")
		(net "M_F_CPU0_SA_CS_N<1>")
	)
	(segment
		(start 407.321004 -263.452864)
		(end 406.18029 -263.452864)
		(width 0.18288)
		(layer "In2.Cu")
		(net "M_F_CPU0_SA_CS_N<1>")
	)
	(segment
		(start 411.372558 -264.351262)
		(end 410.314648 -264.351262)
		(width 0.18288)
		(layer "In2.Cu")
		(net "M_F_CPU0_SA_CS_N<1>")
	)
	(segment
		(start 384.877564 -258.478782)
		(end 384.862832 -258.487418)
		(width 0.088646)
		(layer "In2.Cu")
		(net "M_F_CPU0_SA_CS_N<1>")
	)
	(segment
		(start 386.757164 -258.478782)
		(end 386.742432 -258.487418)
		(width 0.088646)
		(layer "In2.Cu")
		(net "M_F_CPU0_SA_CS_N<1>")
	)
	(segment
		(start 430.34585 -266.495784)
		(end 430.035208 -266.806426)
		(width 0.18288)
		(layer "In2.Cu")
		(net "M_F_CPU0_SA_CS_N<1>")
	)
	(arc
		(start 386.19176 -258.478782)
		(mid 386.004562 -258.428639)
		(end 385.817364 -258.478782)
		(width 0.088646)
		(layer "In2.Cu")
		(net "M_F_CPU0_SA_CS_N<1>")
	)
	(arc
		(start 387.722872 -258.47548)
		(mid 387.701693 -258.478525)
		(end 387.682232 -258.487418)
		(width 0.088646)
		(layer "In2.Cu")
		(net "M_F_CPU0_SA_CS_N<1>")
	)
	(arc
		(start 384.31216 -258.478782)
		(mid 384.124962 -258.428639)
		(end 383.937764 -258.478782)
		(width 0.088646)
		(layer "In2.Cu")
		(net "M_F_CPU0_SA_CS_N<1>")
	)
	(arc
		(start 385.802632 -258.487418)
		(mid 385.526191 -258.554584)
		(end 385.25196 -258.478782)
		(width 0.088646)
		(layer "In2.Cu")
		(net "M_F_CPU0_SA_CS_N<1>")
	)
	(arc
		(start 385.25196 -258.478782)
		(mid 385.064762 -258.428639)
		(end 384.877564 -258.478782)
		(width 0.088646)
		(layer "In2.Cu")
		(net "M_F_CPU0_SA_CS_N<1>")
	)
	(arc
		(start 387.13156 -258.478782)
		(mid 386.944362 -258.428639)
		(end 386.757164 -258.478782)
		(width 0.088646)
		(layer "In2.Cu")
		(net "M_F_CPU0_SA_CS_N<1>")
	)
	(arc
		(start 384.862832 -258.487418)
		(mid 384.586391 -258.554584)
		(end 384.31216 -258.478782)
		(width 0.088646)
		(layer "In2.Cu")
		(net "M_F_CPU0_SA_CS_N<1>")
	)
	(arc
		(start 386.742432 -258.487418)
		(mid 386.465991 -258.554584)
		(end 386.19176 -258.478782)
		(width 0.088646)
		(layer "In2.Cu")
		(net "M_F_CPU0_SA_CS_N<1>")
	)
	(arc
		(start 387.682232 -258.487418)
		(mid 387.405791 -258.554584)
		(end 387.13156 -258.478782)
		(width 0.088646)
		(layer "In2.Cu")
		(net "M_F_CPU0_SA_CS_N<1>")
	)
	(arc
		(start 383.54127 -258.70789)
		(mid 383.369491 -258.778988)
		(end 383.185162 -258.80314)
		(width 0.088646)
		(layer "In2.Cu")
		(net "M_F_CPU0_SA_CS_N<1>")
	)
	(segment
		(start 382.715516 -259.081016)
		(end 382.715516 -259.093462)
		(width 0.20066)
		(layer "F.Cu")
		(net "M_F_CPU0_SA_CS_N<0>")
	)
	(segment
		(start 429.384714 -267.866622)
		(end 428.279814 -267.866622)
		(width 0.20066)
		(layer "F.Cu")
		(net "M_F_CPU0_SA_CS_N<0>")
	)
	(segment
		(start 382.715516 -259.093462)
		(end 382.715262 -259.616956)
		(width 0.20066)
		(layer "F.Cu")
		(net "M_F_CPU0_SA_CS_N<0>")
	)
	(segment
		(start 421.103806 -268.294612)
		(end 420.513256 -268.294612)
		(width 0.18288)
		(layer "In2.Cu")
		(net "M_F_CPU0_SA_CS_N<0>")
	)
	(segment
		(start 404.971758 -265.749532)
		(end 400.595592 -261.373366)
		(width 0.18288)
		(layer "In2.Cu")
		(net "M_F_CPU0_SA_CS_N<0>")
	)
	(segment
		(start 400.595592 -261.373366)
		(end 395.862048 -261.373366)
		(width 0.18288)
		(layer "In2.Cu")
		(net "M_F_CPU0_SA_CS_N<0>")
	)
	(segment
		(start 393.48029 -259.555996)
		(end 388.840218 -259.555996)
		(width 0.18288)
		(layer "In2.Cu")
		(net "M_F_CPU0_SA_CS_N<0>")
	)
	(segment
		(start 383.467864 -259.941314)
		(end 383.46761 -259.941314)
		(width 0.088646)
		(layer "In2.Cu")
		(net "M_F_CPU0_SA_CS_N<0>")
	)
	(segment
		(start 421.449246 -269.152878)
		(end 421.273986 -268.977618)
		(width 0.18288)
		(layer "In2.Cu")
		(net "M_F_CPU0_SA_CS_N<0>")
	)
	(segment
		(start 424.199558 -268.0843)
		(end 423.991024 -267.875766)
		(width 0.18288)
		(layer "In2.Cu")
		(net "M_F_CPU0_SA_CS_N<0>")
	)
	(segment
		(start 395.862048 -261.373366)
		(end 394.443966 -259.955284)
		(width 0.18288)
		(layer "In2.Cu")
		(net "M_F_CPU0_SA_CS_N<0>")
	)
	(segment
		(start 414.880044 -267.125704)
		(end 413.716724 -267.125704)
		(width 0.18288)
		(layer "In2.Cu")
		(net "M_F_CPU0_SA_CS_N<0>")
	)
	(segment
		(start 427.864778 -267.866622)
		(end 427.717966 -268.013434)
		(width 0.18288)
		(layer "In2.Cu")
		(net "M_F_CPU0_SA_CS_N<0>")
	)
	(segment
		(start 421.273986 -268.977618)
		(end 421.273986 -268.464792)
		(width 0.18288)
		(layer "In2.Cu")
		(net "M_F_CPU0_SA_CS_N<0>")
	)
	(segment
		(start 426.628306 -268.11224)
		(end 425.225972 -268.11224)
		(width 0.18288)
		(layer "In2.Cu")
		(net "M_F_CPU0_SA_CS_N<0>")
	)
	(segment
		(start 425.225972 -268.11224)
		(end 424.953176 -268.385036)
		(width 0.18288)
		(layer "In2.Cu")
		(net "M_F_CPU0_SA_CS_N<0>")
	)
	(segment
		(start 424.953176 -268.87805)
		(end 424.760136 -269.07109)
		(width 0.18288)
		(layer "In2.Cu")
		(net "M_F_CPU0_SA_CS_N<0>")
	)
	(segment
		(start 428.279814 -267.866622)
		(end 427.864778 -267.866622)
		(width 0.18288)
		(layer "In2.Cu")
		(net "M_F_CPU0_SA_CS_N<0>")
	)
	(segment
		(start 424.199558 -268.878558)
		(end 424.199558 -268.0843)
		(width 0.18288)
		(layer "In2.Cu")
		(net "M_F_CPU0_SA_CS_N<0>")
	)
	(segment
		(start 427.452536 -269.07109)
		(end 427.087538 -269.07109)
		(width 0.18288)
		(layer "In2.Cu")
		(net "M_F_CPU0_SA_CS_N<0>")
	)
	(segment
		(start 385.34721 -259.941314)
		(end 385.332478 -259.932678)
		(width 0.088646)
		(layer "In2.Cu")
		(net "M_F_CPU0_SA_CS_N<0>")
	)
	(segment
		(start 427.087538 -269.07109)
		(end 426.894498 -268.87805)
		(width 0.18288)
		(layer "In2.Cu")
		(net "M_F_CPU0_SA_CS_N<0>")
	)
	(segment
		(start 426.894498 -268.87805)
		(end 426.894498 -268.378432)
		(width 0.18288)
		(layer "In2.Cu")
		(net "M_F_CPU0_SA_CS_N<0>")
	)
	(segment
		(start 424.39209 -269.07109)
		(end 424.199558 -268.878558)
		(width 0.18288)
		(layer "In2.Cu")
		(net "M_F_CPU0_SA_CS_N<0>")
	)
	(segment
		(start 416.741864 -268.069314)
		(end 416.741864 -267.827506)
		(width 0.18288)
		(layer "In2.Cu")
		(net "M_F_CPU0_SA_CS_N<0>")
	)
	(segment
		(start 412.15564 -266.615672)
		(end 409.0035 -266.615672)
		(width 0.18288)
		(layer "In2.Cu")
		(net "M_F_CPU0_SA_CS_N<0>")
	)
	(segment
		(start 383.46761 -259.941314)
		(end 383.438908 -259.92455)
		(width 0.088646)
		(layer "In2.Cu")
		(net "M_F_CPU0_SA_CS_N<0>")
	)
	(segment
		(start 388.840218 -259.555996)
		(end 387.950456 -259.555996)
		(width 0.088646)
		(layer "In2.Cu")
		(net "M_F_CPU0_SA_CS_N<0>")
	)
	(segment
		(start 413.364172 -267.478256)
		(end 413.018224 -267.478256)
		(width 0.18288)
		(layer "In2.Cu")
		(net "M_F_CPU0_SA_CS_N<0>")
	)
	(segment
		(start 419.381686 -268.304772)
		(end 416.977322 -268.304772)
		(width 0.18288)
		(layer "In2.Cu")
		(net "M_F_CPU0_SA_CS_N<0>")
	)
	(segment
		(start 424.953176 -268.385036)
		(end 424.953176 -268.87805)
		(width 0.18288)
		(layer "In2.Cu")
		(net "M_F_CPU0_SA_CS_N<0>")
	)
	(segment
		(start 423.457624 -268.815058)
		(end 423.119804 -269.152878)
		(width 0.18288)
		(layer "In2.Cu")
		(net "M_F_CPU0_SA_CS_N<0>")
	)
	(segment
		(start 394.443966 -259.955284)
		(end 393.48029 -259.555996)
		(width 0.18288)
		(layer "In2.Cu")
		(net "M_F_CPU0_SA_CS_N<0>")
	)
	(segment
		(start 413.018224 -267.478256)
		(end 412.15564 -266.615672)
		(width 0.18288)
		(layer "In2.Cu")
		(net "M_F_CPU0_SA_CS_N<0>")
	)
	(segment
		(start 383.438908 -259.92455)
		(end 382.715262 -259.616956)
		(width 0.088646)
		(layer "In2.Cu")
		(net "M_F_CPU0_SA_CS_N<0>")
	)
	(segment
		(start 386.28701 -259.941314)
		(end 386.272278 -259.932678)
		(width 0.088646)
		(layer "In2.Cu")
		(net "M_F_CPU0_SA_CS_N<0>")
	)
	(segment
		(start 420.262304 -268.545564)
		(end 419.622478 -268.545564)
		(width 0.18288)
		(layer "In2.Cu")
		(net "M_F_CPU0_SA_CS_N<0>")
	)
	(segment
		(start 416.426396 -267.512038)
		(end 415.266378 -267.512038)
		(width 0.18288)
		(layer "In2.Cu")
		(net "M_F_CPU0_SA_CS_N<0>")
	)
	(segment
		(start 426.894498 -268.378432)
		(end 426.628306 -268.11224)
		(width 0.18288)
		(layer "In2.Cu")
		(net "M_F_CPU0_SA_CS_N<0>")
	)
	(segment
		(start 423.617644 -267.875766)
		(end 423.457624 -268.035786)
		(width 0.18288)
		(layer "In2.Cu")
		(net "M_F_CPU0_SA_CS_N<0>")
	)
	(segment
		(start 387.950456 -259.555996)
		(end 387.566916 -259.933948)
		(width 0.088646)
		(layer "In2.Cu")
		(net "M_F_CPU0_SA_CS_N<0>")
	)
	(segment
		(start 423.991024 -267.875766)
		(end 423.617644 -267.875766)
		(width 0.18288)
		(layer "In2.Cu")
		(net "M_F_CPU0_SA_CS_N<0>")
	)
	(segment
		(start 419.622478 -268.545564)
		(end 419.381686 -268.304772)
		(width 0.18288)
		(layer "In2.Cu")
		(net "M_F_CPU0_SA_CS_N<0>")
	)
	(segment
		(start 408.13736 -265.749532)
		(end 404.971758 -265.749532)
		(width 0.18288)
		(layer "In2.Cu")
		(net "M_F_CPU0_SA_CS_N<0>")
	)
	(segment
		(start 384.40741 -259.941314)
		(end 384.392678 -259.932678)
		(width 0.088646)
		(layer "In2.Cu")
		(net "M_F_CPU0_SA_CS_N<0>")
	)
	(segment
		(start 415.266378 -267.512038)
		(end 414.880044 -267.125704)
		(width 0.18288)
		(layer "In2.Cu")
		(net "M_F_CPU0_SA_CS_N<0>")
	)
	(segment
		(start 423.119804 -269.152878)
		(end 421.449246 -269.152878)
		(width 0.18288)
		(layer "In2.Cu")
		(net "M_F_CPU0_SA_CS_N<0>")
	)
	(segment
		(start 427.717966 -268.80566)
		(end 427.452536 -269.07109)
		(width 0.18288)
		(layer "In2.Cu")
		(net "M_F_CPU0_SA_CS_N<0>")
	)
	(segment
		(start 427.717966 -268.013434)
		(end 427.717966 -268.80566)
		(width 0.18288)
		(layer "In2.Cu")
		(net "M_F_CPU0_SA_CS_N<0>")
	)
	(segment
		(start 416.741864 -267.827506)
		(end 416.426396 -267.512038)
		(width 0.18288)
		(layer "In2.Cu")
		(net "M_F_CPU0_SA_CS_N<0>")
	)
	(segment
		(start 420.513256 -268.294612)
		(end 420.262304 -268.545564)
		(width 0.18288)
		(layer "In2.Cu")
		(net "M_F_CPU0_SA_CS_N<0>")
	)
	(segment
		(start 423.457624 -268.035786)
		(end 423.457624 -268.815058)
		(width 0.18288)
		(layer "In2.Cu")
		(net "M_F_CPU0_SA_CS_N<0>")
	)
	(segment
		(start 416.977322 -268.304772)
		(end 416.741864 -268.069314)
		(width 0.18288)
		(layer "In2.Cu")
		(net "M_F_CPU0_SA_CS_N<0>")
	)
	(segment
		(start 421.273986 -268.464792)
		(end 421.103806 -268.294612)
		(width 0.18288)
		(layer "In2.Cu")
		(net "M_F_CPU0_SA_CS_N<0>")
	)
	(segment
		(start 409.0035 -266.615672)
		(end 408.13736 -265.749532)
		(width 0.18288)
		(layer "In2.Cu")
		(net "M_F_CPU0_SA_CS_N<0>")
	)
	(segment
		(start 424.760136 -269.07109)
		(end 424.39209 -269.07109)
		(width 0.18288)
		(layer "In2.Cu")
		(net "M_F_CPU0_SA_CS_N<0>")
	)
	(segment
		(start 413.716724 -267.125704)
		(end 413.364172 -267.478256)
		(width 0.18288)
		(layer "In2.Cu")
		(net "M_F_CPU0_SA_CS_N<0>")
	)
	(arc
		(start 385.721606 -259.941314)
		(mid 385.534408 -259.991457)
		(end 385.34721 -259.941314)
		(width 0.088646)
		(layer "In2.Cu")
		(net "M_F_CPU0_SA_CS_N<0>")
	)
	(arc
		(start 386.661406 -259.941314)
		(mid 386.474208 -259.991457)
		(end 386.28701 -259.941314)
		(width 0.088646)
		(layer "In2.Cu")
		(net "M_F_CPU0_SA_CS_N<0>")
	)
	(arc
		(start 384.392678 -259.932678)
		(mid 384.116203 -259.865358)
		(end 383.842006 -259.941314)
		(width 0.088646)
		(layer "In2.Cu")
		(net "M_F_CPU0_SA_CS_N<0>")
	)
	(arc
		(start 383.842006 -259.941314)
		(mid 383.654952 -259.991364)
		(end 383.467864 -259.941314)
		(width 0.088646)
		(layer "In2.Cu")
		(net "M_F_CPU0_SA_CS_N<0>")
	)
	(arc
		(start 384.781806 -259.941314)
		(mid 384.594608 -259.991457)
		(end 384.40741 -259.941314)
		(width 0.088646)
		(layer "In2.Cu")
		(net "M_F_CPU0_SA_CS_N<0>")
	)
	(arc
		(start 387.566916 -259.933948)
		(mid 387.389333 -259.981112)
		(end 387.212078 -259.932678)
		(width 0.088646)
		(layer "In2.Cu")
		(net "M_F_CPU0_SA_CS_N<0>")
	)
	(arc
		(start 387.212078 -259.932678)
		(mid 386.935603 -259.865358)
		(end 386.661406 -259.941314)
		(width 0.088646)
		(layer "In2.Cu")
		(net "M_F_CPU0_SA_CS_N<0>")
	)
	(arc
		(start 386.272278 -259.932678)
		(mid 385.995803 -259.865358)
		(end 385.721606 -259.941314)
		(width 0.088646)
		(layer "In2.Cu")
		(net "M_F_CPU0_SA_CS_N<0>")
	)
	(arc
		(start 385.332478 -259.932678)
		(mid 385.056003 -259.865358)
		(end 384.781806 -259.941314)
		(width 0.088646)
		(layer "In2.Cu")
		(net "M_F_CPU0_SA_CS_N<0>")
	)
	(segment
		(start 382.715516 -260.708902)
		(end 382.715516 -261.244334)
		(width 0.20066)
		(layer "F.Cu")
		(net "M_F_CPU0_SA_CB<7>")
	)
	(segment
		(start 382.715262 -261.244588)
		(end 382.715262 -261.244842)
		(width 0.20066)
		(layer "F.Cu")
		(net "M_F_CPU0_SA_CB<7>")
	)
	(segment
		(start 430.382934 -270.841724)
		(end 430.395126 -270.853916)
		(width 0.1016)
		(layer "F.Cu")
		(net "M_F_CPU0_SA_CB<7>")
	)
	(segment
		(start 432.15052 -270.416782)
		(end 433.484782 -270.416782)
		(width 0.20066)
		(layer "F.Cu")
		(net "M_F_CPU0_SA_CB<7>")
	)
	(segment
		(start 431.514504 -270.164814)
		(end 431.898552 -270.164814)
		(width 0.20066)
		(layer "F.Cu")
		(net "M_F_CPU0_SA_CB<7>")
	)
	(segment
		(start 424.836082 -270.416782)
		(end 425.940982 -270.416782)
		(width 0.20066)
		(layer "F.Cu")
		(net "M_F_CPU0_SA_CB<7>")
	)
	(segment
		(start 431.898552 -270.164814)
		(end 432.15052 -270.416782)
		(width 0.20066)
		(layer "F.Cu")
		(net "M_F_CPU0_SA_CB<7>")
	)
	(segment
		(start 431.076354 -270.853916)
		(end 431.280316 -270.649954)
		(width 0.20066)
		(layer "F.Cu")
		(net "M_F_CPU0_SA_CB<7>")
	)
	(segment
		(start 431.280316 -270.649954)
		(end 431.280316 -270.399002)
		(width 0.20066)
		(layer "F.Cu")
		(net "M_F_CPU0_SA_CB<7>")
	)
	(segment
		(start 425.940982 -270.416782)
		(end 427.639226 -270.416782)
		(width 0.20066)
		(layer "F.Cu")
		(net "M_F_CPU0_SA_CB<7>")
	)
	(segment
		(start 427.639226 -270.416782)
		(end 428.07128 -270.848836)
		(width 0.20066)
		(layer "F.Cu")
		(net "M_F_CPU0_SA_CB<7>")
	)
	(segment
		(start 428.367952 -270.848836)
		(end 428.375064 -270.841724)
		(width 0.1016)
		(layer "F.Cu")
		(net "M_F_CPU0_SA_CB<7>")
	)
	(segment
		(start 430.395126 -270.853916)
		(end 431.076354 -270.853916)
		(width 0.20066)
		(layer "F.Cu")
		(net "M_F_CPU0_SA_CB<7>")
	)
	(segment
		(start 382.715516 -261.244334)
		(end 382.715262 -261.244588)
		(width 0.20066)
		(layer "F.Cu")
		(net "M_F_CPU0_SA_CB<7>")
	)
	(segment
		(start 428.363126 -270.848836)
		(end 428.367952 -270.848836)
		(width 0.101854)
		(layer "F.Cu")
		(net "M_F_CPU0_SA_CB<7>")
	)
	(segment
		(start 428.07128 -270.848836)
		(end 428.363126 -270.848836)
		(width 0.20066)
		(layer "F.Cu")
		(net "M_F_CPU0_SA_CB<7>")
	)
	(segment
		(start 431.280316 -270.399002)
		(end 431.514504 -270.164814)
		(width 0.20066)
		(layer "F.Cu")
		(net "M_F_CPU0_SA_CB<7>")
	)
	(segment
		(start 428.375064 -270.841724)
		(end 430.382934 -270.841724)
		(width 0.1016)
		(layer "F.Cu")
		(net "M_F_CPU0_SA_CB<7>")
	)
	(segment
		(start 405.358092 -268.282928)
		(end 399.934938 -262.859774)
		(width 0.18288)
		(layer "In2.Cu")
		(net "M_F_CPU0_SA_CB<7>")
	)
	(segment
		(start 423.206926 -271.04721)
		(end 422.818306 -271.04721)
		(width 0.18288)
		(layer "In2.Cu")
		(net "M_F_CPU0_SA_CB<7>")
	)
	(segment
		(start 411.301184 -269.53464)
		(end 410.855414 -269.53464)
		(width 0.18288)
		(layer "In2.Cu")
		(net "M_F_CPU0_SA_CB<7>")
	)
	(segment
		(start 424.450256 -270.6243)
		(end 424.257216 -270.43126)
		(width 0.18288)
		(layer "In2.Cu")
		(net "M_F_CPU0_SA_CB<7>")
	)
	(segment
		(start 416.578034 -270.03883)
		(end 415.73323 -269.194026)
		(width 0.18288)
		(layer "In2.Cu")
		(net "M_F_CPU0_SA_CB<7>")
	)
	(segment
		(start 388.287006 -260.900926)
		(end 388.192264 -260.806184)
		(width 0.088646)
		(layer "In2.Cu")
		(net "M_F_CPU0_SA_CB<7>")
	)
	(segment
		(start 413.311594 -269.321026)
		(end 412.395924 -269.321026)
		(width 0.18288)
		(layer "In2.Cu")
		(net "M_F_CPU0_SA_CB<7>")
	)
	(segment
		(start 423.399966 -270.85417)
		(end 423.206926 -271.04721)
		(width 0.18288)
		(layer "In2.Cu")
		(net "M_F_CPU0_SA_CB<7>")
	)
	(segment
		(start 424.257216 -270.43126)
		(end 424.257216 -270.18361)
		(width 0.18288)
		(layer "In2.Cu")
		(net "M_F_CPU0_SA_CB<7>")
	)
	(segment
		(start 424.628564 -270.6243)
		(end 424.450256 -270.6243)
		(width 0.18288)
		(layer "In2.Cu")
		(net "M_F_CPU0_SA_CB<7>")
	)
	(segment
		(start 388.192264 -260.806184)
		(end 387.884416 -260.806184)
		(width 0.088646)
		(layer "In2.Cu")
		(net "M_F_CPU0_SA_CB<7>")
	)
	(segment
		(start 382.528064 -261.5692)
		(end 382.519174 -261.56412)
		(width 0.088646)
		(layer "In2.Cu")
		(net "M_F_CPU0_SA_CB<7>")
	)
	(segment
		(start 411.811724 -269.0241)
		(end 411.301184 -269.53464)
		(width 0.18288)
		(layer "In2.Cu")
		(net "M_F_CPU0_SA_CB<7>")
	)
	(segment
		(start 412.098998 -269.0241)
		(end 411.811724 -269.0241)
		(width 0.18288)
		(layer "In2.Cu")
		(net "M_F_CPU0_SA_CB<7>")
	)
	(segment
		(start 399.934938 -262.859774)
		(end 395.226286 -262.859774)
		(width 0.18288)
		(layer "In2.Cu")
		(net "M_F_CPU0_SA_CB<7>")
	)
	(segment
		(start 393.645136 -261.278624)
		(end 392.733022 -260.900926)
		(width 0.18288)
		(layer "In2.Cu")
		(net "M_F_CPU0_SA_CB<7>")
	)
	(segment
		(start 413.438594 -269.194026)
		(end 413.311594 -269.321026)
		(width 0.18288)
		(layer "In2.Cu")
		(net "M_F_CPU0_SA_CB<7>")
	)
	(segment
		(start 424.836082 -270.416782)
		(end 424.628564 -270.6243)
		(width 0.18288)
		(layer "In2.Cu")
		(net "M_F_CPU0_SA_CB<7>")
	)
	(segment
		(start 424.064176 -269.99057)
		(end 423.593006 -269.99057)
		(width 0.18288)
		(layer "In2.Cu")
		(net "M_F_CPU0_SA_CB<7>")
	)
	(segment
		(start 423.399966 -270.18361)
		(end 423.399966 -270.85417)
		(width 0.18288)
		(layer "In2.Cu")
		(net "M_F_CPU0_SA_CB<7>")
	)
	(segment
		(start 392.733022 -260.900926)
		(end 388.840218 -260.900926)
		(width 0.18288)
		(layer "In2.Cu")
		(net "M_F_CPU0_SA_CB<7>")
	)
	(segment
		(start 412.395924 -269.321026)
		(end 412.098998 -269.0241)
		(width 0.18288)
		(layer "In2.Cu")
		(net "M_F_CPU0_SA_CB<7>")
	)
	(segment
		(start 424.257216 -270.18361)
		(end 424.064176 -269.99057)
		(width 0.18288)
		(layer "In2.Cu")
		(net "M_F_CPU0_SA_CB<7>")
	)
	(segment
		(start 422.612566 -270.84147)
		(end 420.552626 -270.84147)
		(width 0.18288)
		(layer "In2.Cu")
		(net "M_F_CPU0_SA_CB<7>")
	)
	(segment
		(start 395.226286 -262.859774)
		(end 393.645136 -261.278624)
		(width 0.18288)
		(layer "In2.Cu")
		(net "M_F_CPU0_SA_CB<7>")
	)
	(segment
		(start 422.818306 -271.04721)
		(end 422.612566 -270.84147)
		(width 0.18288)
		(layer "In2.Cu")
		(net "M_F_CPU0_SA_CB<7>")
	)
	(segment
		(start 410.03347 -269.136114)
		(end 409.396184 -268.498828)
		(width 0.18288)
		(layer "In2.Cu")
		(net "M_F_CPU0_SA_CB<7>")
	)
	(segment
		(start 409.396184 -268.498828)
		(end 408.747214 -268.498828)
		(width 0.18288)
		(layer "In2.Cu")
		(net "M_F_CPU0_SA_CB<7>")
	)
	(segment
		(start 382.345184 -261.301992)
		(end 382.402334 -261.244842)
		(width 0.088646)
		(layer "In2.Cu")
		(net "M_F_CPU0_SA_CB<7>")
	)
	(segment
		(start 382.91135 -261.56412)
		(end 382.90246 -261.5692)
		(width 0.088646)
		(layer "In2.Cu")
		(net "M_F_CPU0_SA_CB<7>")
	)
	(segment
		(start 383.089912 -261.2263)
		(end 383.089912 -261.244842)
		(width 0.088646)
		(layer "In2.Cu")
		(net "M_F_CPU0_SA_CB<7>")
	)
	(segment
		(start 408.747214 -268.498828)
		(end 408.531314 -268.282928)
		(width 0.18288)
		(layer "In2.Cu")
		(net "M_F_CPU0_SA_CB<7>")
	)
	(segment
		(start 410.456888 -269.136114)
		(end 410.03347 -269.136114)
		(width 0.18288)
		(layer "In2.Cu")
		(net "M_F_CPU0_SA_CB<7>")
	)
	(segment
		(start 408.531314 -268.282928)
		(end 405.358092 -268.282928)
		(width 0.18288)
		(layer "In2.Cu")
		(net "M_F_CPU0_SA_CB<7>")
	)
	(segment
		(start 423.593006 -269.99057)
		(end 423.399966 -270.18361)
		(width 0.18288)
		(layer "In2.Cu")
		(net "M_F_CPU0_SA_CB<7>")
	)
	(segment
		(start 382.402334 -261.244842)
		(end 382.715262 -261.244842)
		(width 0.088646)
		(layer "In2.Cu")
		(net "M_F_CPU0_SA_CB<7>")
	)
	(segment
		(start 419.749986 -270.03883)
		(end 416.578034 -270.03883)
		(width 0.18288)
		(layer "In2.Cu")
		(net "M_F_CPU0_SA_CB<7>")
	)
	(segment
		(start 410.855414 -269.53464)
		(end 410.456888 -269.136114)
		(width 0.18288)
		(layer "In2.Cu")
		(net "M_F_CPU0_SA_CB<7>")
	)
	(segment
		(start 415.73323 -269.194026)
		(end 413.438594 -269.194026)
		(width 0.18288)
		(layer "In2.Cu")
		(net "M_F_CPU0_SA_CB<7>")
	)
	(segment
		(start 388.840218 -260.900926)
		(end 388.287006 -260.900926)
		(width 0.088646)
		(layer "In2.Cu")
		(net "M_F_CPU0_SA_CB<7>")
	)
	(segment
		(start 420.552626 -270.84147)
		(end 419.749986 -270.03883)
		(width 0.18288)
		(layer "In2.Cu")
		(net "M_F_CPU0_SA_CB<7>")
	)
	(arc
		(start 383.37236 -260.75513)
		(mid 383.170074 -260.954111)
		(end 383.089912 -261.2263)
		(width 0.088646)
		(layer "In2.Cu")
		(net "M_F_CPU0_SA_CB<7>")
	)
	(arc
		(start 385.817364 -260.75513)
		(mid 385.534662 -260.679388)
		(end 385.25196 -260.75513)
		(width 0.088646)
		(layer "In2.Cu")
		(net "M_F_CPU0_SA_CB<7>")
	)
	(arc
		(start 384.877564 -260.75513)
		(mid 384.594862 -260.679388)
		(end 384.31216 -260.75513)
		(width 0.088646)
		(layer "In2.Cu")
		(net "M_F_CPU0_SA_CB<7>")
	)
	(arc
		(start 383.089912 -261.244842)
		(mid 383.042233 -261.427742)
		(end 382.91135 -261.56412)
		(width 0.088646)
		(layer "In2.Cu")
		(net "M_F_CPU0_SA_CB<7>")
	)
	(arc
		(start 382.519174 -261.56412)
		(mid 382.403365 -261.452191)
		(end 382.345184 -261.301992)
		(width 0.088646)
		(layer "In2.Cu")
		(net "M_F_CPU0_SA_CB<7>")
	)
	(arc
		(start 387.884416 -260.806184)
		(mid 387.787335 -260.792988)
		(end 387.696964 -260.75513)
		(width 0.088646)
		(layer "In2.Cu")
		(net "M_F_CPU0_SA_CB<7>")
	)
	(arc
		(start 387.696964 -260.75513)
		(mid 387.414262 -260.679388)
		(end 387.13156 -260.75513)
		(width 0.088646)
		(layer "In2.Cu")
		(net "M_F_CPU0_SA_CB<7>")
	)
	(arc
		(start 385.25196 -260.75513)
		(mid 385.064762 -260.805273)
		(end 384.877564 -260.75513)
		(width 0.088646)
		(layer "In2.Cu")
		(net "M_F_CPU0_SA_CB<7>")
	)
	(arc
		(start 383.937764 -260.75513)
		(mid 383.655062 -260.679388)
		(end 383.37236 -260.75513)
		(width 0.088646)
		(layer "In2.Cu")
		(net "M_F_CPU0_SA_CB<7>")
	)
	(arc
		(start 387.13156 -260.75513)
		(mid 386.944362 -260.805273)
		(end 386.757164 -260.75513)
		(width 0.088646)
		(layer "In2.Cu")
		(net "M_F_CPU0_SA_CB<7>")
	)
	(arc
		(start 382.90246 -261.5692)
		(mid 382.715262 -261.619343)
		(end 382.528064 -261.5692)
		(width 0.088646)
		(layer "In2.Cu")
		(net "M_F_CPU0_SA_CB<7>")
	)
	(arc
		(start 386.757164 -260.75513)
		(mid 386.474462 -260.679388)
		(end 386.19176 -260.75513)
		(width 0.088646)
		(layer "In2.Cu")
		(net "M_F_CPU0_SA_CB<7>")
	)
	(arc
		(start 384.31216 -260.75513)
		(mid 384.124962 -260.805273)
		(end 383.937764 -260.75513)
		(width 0.088646)
		(layer "In2.Cu")
		(net "M_F_CPU0_SA_CB<7>")
	)
	(arc
		(start 386.19176 -260.75513)
		(mid 386.004562 -260.805273)
		(end 385.817364 -260.75513)
		(width 0.088646)
		(layer "In2.Cu")
		(net "M_F_CPU0_SA_CB<7>")
	)
	(segment
		(start 427.639226 -272.116804)
		(end 425.940982 -272.116804)
		(width 0.20066)
		(layer "F.Cu")
		(net "M_F_CPU0_SA_CB<6>")
	)
	(segment
		(start 431.280316 -272.349976)
		(end 431.076354 -272.553938)
		(width 0.20066)
		(layer "F.Cu")
		(net "M_F_CPU0_SA_CB<6>")
	)
	(segment
		(start 383.185162 -261.522718)
		(end 383.185162 -262.058658)
		(width 0.20066)
		(layer "F.Cu")
		(net "M_F_CPU0_SA_CB<6>")
	)
	(segment
		(start 425.940728 -272.11655)
		(end 425.940982 -272.116804)
		(width 0.20066)
		(layer "F.Cu")
		(net "M_F_CPU0_SA_CB<6>")
	)
	(segment
		(start 430.382934 -272.541746)
		(end 428.375064 -272.541746)
		(width 0.1016)
		(layer "F.Cu")
		(net "M_F_CPU0_SA_CB<6>")
	)
	(segment
		(start 431.280316 -272.099024)
		(end 431.280316 -272.349976)
		(width 0.20066)
		(layer "F.Cu")
		(net "M_F_CPU0_SA_CB<6>")
	)
	(segment
		(start 433.484782 -272.116804)
		(end 432.15052 -272.116804)
		(width 0.20066)
		(layer "F.Cu")
		(net "M_F_CPU0_SA_CB<6>")
	)
	(segment
		(start 432.15052 -272.116804)
		(end 431.898552 -271.864836)
		(width 0.20066)
		(layer "F.Cu")
		(net "M_F_CPU0_SA_CB<6>")
	)
	(segment
		(start 431.076354 -272.553938)
		(end 430.395126 -272.553938)
		(width 0.20066)
		(layer "F.Cu")
		(net "M_F_CPU0_SA_CB<6>")
	)
	(segment
		(start 431.514504 -271.864836)
		(end 431.280316 -272.099024)
		(width 0.20066)
		(layer "F.Cu")
		(net "M_F_CPU0_SA_CB<6>")
	)
	(segment
		(start 428.375064 -272.541746)
		(end 428.367952 -272.548858)
		(width 0.1016)
		(layer "F.Cu")
		(net "M_F_CPU0_SA_CB<6>")
	)
	(segment
		(start 430.395126 -272.553938)
		(end 430.382934 -272.541746)
		(width 0.1016)
		(layer "F.Cu")
		(net "M_F_CPU0_SA_CB<6>")
	)
	(segment
		(start 424.836082 -272.11655)
		(end 425.940728 -272.11655)
		(width 0.20066)
		(layer "F.Cu")
		(net "M_F_CPU0_SA_CB<6>")
	)
	(segment
		(start 428.367952 -272.548858)
		(end 428.363126 -272.548858)
		(width 0.101854)
		(layer "F.Cu")
		(net "M_F_CPU0_SA_CB<6>")
	)
	(segment
		(start 428.363126 -272.548858)
		(end 428.07128 -272.548858)
		(width 0.20066)
		(layer "F.Cu")
		(net "M_F_CPU0_SA_CB<6>")
	)
	(segment
		(start 428.07128 -272.548858)
		(end 427.639226 -272.116804)
		(width 0.20066)
		(layer "F.Cu")
		(net "M_F_CPU0_SA_CB<6>")
	)
	(segment
		(start 431.898552 -271.864836)
		(end 431.514504 -271.864836)
		(width 0.20066)
		(layer "F.Cu")
		(net "M_F_CPU0_SA_CB<6>")
	)
	(segment
		(start 408.985212 -270.81099)
		(end 408.024076 -269.849854)
		(width 0.18288)
		(layer "In2.Cu")
		(net "M_F_CPU0_SA_CB<6>")
	)
	(segment
		(start 388.357872 -261.493254)
		(end 387.884416 -261.493254)
		(width 0.088646)
		(layer "In2.Cu")
		(net "M_F_CPU0_SA_CB<6>")
	)
	(segment
		(start 415.427668 -271.394682)
		(end 415.128202 -271.694148)
		(width 0.18288)
		(layer "In2.Cu")
		(net "M_F_CPU0_SA_CB<6>")
	)
	(segment
		(start 416.864038 -271.51457)
		(end 415.82086 -271.51457)
		(width 0.18288)
		(layer "In2.Cu")
		(net "M_F_CPU0_SA_CB<6>")
	)
	(segment
		(start 421.475154 -271.851374)
		(end 421.315134 -271.691354)
		(width 0.18288)
		(layer "In2.Cu")
		(net "M_F_CPU0_SA_CB<6>")
	)
	(segment
		(start 411.781752 -270.75638)
		(end 411.648402 -270.88973)
		(width 0.18288)
		(layer "In2.Cu")
		(net "M_F_CPU0_SA_CB<6>")
	)
	(segment
		(start 424.625262 -271.90573)
		(end 424.398948 -271.90573)
		(width 0.18288)
		(layer "In2.Cu")
		(net "M_F_CPU0_SA_CB<6>")
	)
	(segment
		(start 424.238928 -272.06575)
		(end 424.238928 -272.34261)
		(width 0.18288)
		(layer "In2.Cu")
		(net "M_F_CPU0_SA_CB<6>")
	)
	(segment
		(start 422.279572 -272.52803)
		(end 421.651684 -272.52803)
		(width 0.18288)
		(layer "In2.Cu")
		(net "M_F_CPU0_SA_CB<6>")
	)
	(segment
		(start 415.700972 -271.394682)
		(end 415.427668 -271.394682)
		(width 0.18288)
		(layer "In2.Cu")
		(net "M_F_CPU0_SA_CB<6>")
	)
	(segment
		(start 395.09827 -263.875774)
		(end 393.025122 -261.802626)
		(width 0.18288)
		(layer "In2.Cu")
		(net "M_F_CPU0_SA_CB<6>")
	)
	(segment
		(start 423.441114 -271.716246)
		(end 423.281094 -271.556226)
		(width 0.18288)
		(layer "In2.Cu")
		(net "M_F_CPU0_SA_CB<6>")
	)
	(segment
		(start 399.504916 -263.875774)
		(end 395.09827 -263.875774)
		(width 0.18288)
		(layer "In2.Cu")
		(net "M_F_CPU0_SA_CB<6>")
	)
	(segment
		(start 383.84226 -261.5692)
		(end 383.814066 -261.585456)
		(width 0.088646)
		(layer "In2.Cu")
		(net "M_F_CPU0_SA_CB<6>")
	)
	(segment
		(start 424.836082 -272.11655)
		(end 424.625262 -271.90573)
		(width 0.18288)
		(layer "In2.Cu")
		(net "M_F_CPU0_SA_CB<6>")
	)
	(segment
		(start 405.214836 -269.992094)
		(end 400.207226 -264.984484)
		(width 0.18288)
		(layer "In2.Cu")
		(net "M_F_CPU0_SA_CB<6>")
	)
	(segment
		(start 393.025122 -261.802626)
		(end 392.582908 -261.619238)
		(width 0.18288)
		(layer "In2.Cu")
		(net "M_F_CPU0_SA_CB<6>")
	)
	(segment
		(start 409.978098 -270.88973)
		(end 409.899358 -270.81099)
		(width 0.18288)
		(layer "In2.Cu")
		(net "M_F_CPU0_SA_CB<6>")
	)
	(segment
		(start 424.03903 -272.542508)
		(end 423.662094 -272.542508)
		(width 0.18288)
		(layer "In2.Cu")
		(net "M_F_CPU0_SA_CB<6>")
	)
	(segment
		(start 400.207226 -264.578084)
		(end 399.504916 -263.875774)
		(width 0.18288)
		(layer "In2.Cu")
		(net "M_F_CPU0_SA_CB<6>")
	)
	(segment
		(start 423.662094 -272.542508)
		(end 423.441114 -272.321528)
		(width 0.18288)
		(layer "In2.Cu")
		(net "M_F_CPU0_SA_CB<6>")
	)
	(segment
		(start 411.648402 -270.88973)
		(end 409.978098 -270.88973)
		(width 0.18288)
		(layer "In2.Cu")
		(net "M_F_CPU0_SA_CB<6>")
	)
	(segment
		(start 423.281094 -271.556226)
		(end 422.840658 -271.556226)
		(width 0.18288)
		(layer "In2.Cu")
		(net "M_F_CPU0_SA_CB<6>")
	)
	(segment
		(start 415.128202 -271.694148)
		(end 413.476948 -271.694148)
		(width 0.18288)
		(layer "In2.Cu")
		(net "M_F_CPU0_SA_CB<6>")
	)
	(segment
		(start 421.315134 -271.691354)
		(end 420.529766 -271.691354)
		(width 0.18288)
		(layer "In2.Cu")
		(net "M_F_CPU0_SA_CB<6>")
	)
	(segment
		(start 388.483856 -261.619238)
		(end 388.357872 -261.493254)
		(width 0.088646)
		(layer "In2.Cu")
		(net "M_F_CPU0_SA_CB<6>")
	)
	(segment
		(start 422.472612 -272.33499)
		(end 422.279572 -272.52803)
		(width 0.18288)
		(layer "In2.Cu")
		(net "M_F_CPU0_SA_CB<6>")
	)
	(segment
		(start 424.398948 -271.90573)
		(end 424.238928 -272.06575)
		(width 0.18288)
		(layer "In2.Cu")
		(net "M_F_CPU0_SA_CB<6>")
	)
	(segment
		(start 420.487094 -271.734026)
		(end 417.083494 -271.734026)
		(width 0.18288)
		(layer "In2.Cu")
		(net "M_F_CPU0_SA_CB<6>")
	)
	(segment
		(start 407.714958 -269.849854)
		(end 407.572718 -269.992094)
		(width 0.18288)
		(layer "In2.Cu")
		(net "M_F_CPU0_SA_CB<6>")
	)
	(segment
		(start 420.529766 -271.691354)
		(end 420.487094 -271.734026)
		(width 0.18288)
		(layer "In2.Cu")
		(net "M_F_CPU0_SA_CB<6>")
	)
	(segment
		(start 422.472612 -271.924272)
		(end 422.472612 -272.33499)
		(width 0.18288)
		(layer "In2.Cu")
		(net "M_F_CPU0_SA_CB<6>")
	)
	(segment
		(start 424.238928 -272.34261)
		(end 424.03903 -272.542508)
		(width 0.18288)
		(layer "In2.Cu")
		(net "M_F_CPU0_SA_CB<6>")
	)
	(segment
		(start 417.083494 -271.734026)
		(end 416.864038 -271.51457)
		(width 0.18288)
		(layer "In2.Cu")
		(net "M_F_CPU0_SA_CB<6>")
	)
	(segment
		(start 422.840658 -271.556226)
		(end 422.472612 -271.924272)
		(width 0.18288)
		(layer "In2.Cu")
		(net "M_F_CPU0_SA_CB<6>")
	)
	(segment
		(start 388.840218 -261.619238)
		(end 388.483856 -261.619238)
		(width 0.088646)
		(layer "In2.Cu")
		(net "M_F_CPU0_SA_CB<6>")
	)
	(segment
		(start 413.476948 -271.694148)
		(end 412.53918 -270.75638)
		(width 0.18288)
		(layer "In2.Cu")
		(net "M_F_CPU0_SA_CB<6>")
	)
	(segment
		(start 408.024076 -269.849854)
		(end 407.714958 -269.849854)
		(width 0.18288)
		(layer "In2.Cu")
		(net "M_F_CPU0_SA_CB<6>")
	)
	(segment
		(start 383.814066 -261.585456)
		(end 383.185162 -262.058658)
		(width 0.088646)
		(layer "In2.Cu")
		(net "M_F_CPU0_SA_CB<6>")
	)
	(segment
		(start 415.82086 -271.51457)
		(end 415.700972 -271.394682)
		(width 0.18288)
		(layer "In2.Cu")
		(net "M_F_CPU0_SA_CB<6>")
	)
	(segment
		(start 412.53918 -270.75638)
		(end 411.781752 -270.75638)
		(width 0.18288)
		(layer "In2.Cu")
		(net "M_F_CPU0_SA_CB<6>")
	)
	(segment
		(start 392.582908 -261.619238)
		(end 388.840218 -261.619238)
		(width 0.18288)
		(layer "In2.Cu")
		(net "M_F_CPU0_SA_CB<6>")
	)
	(segment
		(start 407.572718 -269.992094)
		(end 405.214836 -269.992094)
		(width 0.18288)
		(layer "In2.Cu")
		(net "M_F_CPU0_SA_CB<6>")
	)
	(segment
		(start 421.651684 -272.52803)
		(end 421.475154 -272.3515)
		(width 0.18288)
		(layer "In2.Cu")
		(net "M_F_CPU0_SA_CB<6>")
	)
	(segment
		(start 400.207226 -264.984484)
		(end 400.207226 -264.578084)
		(width 0.18288)
		(layer "In2.Cu")
		(net "M_F_CPU0_SA_CB<6>")
	)
	(segment
		(start 421.475154 -272.3515)
		(end 421.475154 -271.851374)
		(width 0.18288)
		(layer "In2.Cu")
		(net "M_F_CPU0_SA_CB<6>")
	)
	(segment
		(start 409.899358 -270.81099)
		(end 408.985212 -270.81099)
		(width 0.18288)
		(layer "In2.Cu")
		(net "M_F_CPU0_SA_CB<6>")
	)
	(segment
		(start 423.441114 -272.321528)
		(end 423.441114 -271.716246)
		(width 0.18288)
		(layer "In2.Cu")
		(net "M_F_CPU0_SA_CB<6>")
	)
	(arc
		(start 384.78206 -261.5692)
		(mid 384.594862 -261.619343)
		(end 384.407664 -261.5692)
		(width 0.088646)
		(layer "In2.Cu")
		(net "M_F_CPU0_SA_CB<6>")
	)
	(arc
		(start 385.347464 -261.5692)
		(mid 385.064762 -261.493424)
		(end 384.78206 -261.5692)
		(width 0.088646)
		(layer "In2.Cu")
		(net "M_F_CPU0_SA_CB<6>")
	)
	(arc
		(start 386.287264 -261.5692)
		(mid 386.004562 -261.493424)
		(end 385.72186 -261.5692)
		(width 0.088646)
		(layer "In2.Cu")
		(net "M_F_CPU0_SA_CB<6>")
	)
	(arc
		(start 384.407664 -261.5692)
		(mid 384.124962 -261.493458)
		(end 383.84226 -261.5692)
		(width 0.088646)
		(layer "In2.Cu")
		(net "M_F_CPU0_SA_CB<6>")
	)
	(arc
		(start 385.72186 -261.5692)
		(mid 385.534662 -261.619343)
		(end 385.347464 -261.5692)
		(width 0.088646)
		(layer "In2.Cu")
		(net "M_F_CPU0_SA_CB<6>")
	)
	(arc
		(start 386.66166 -261.5692)
		(mid 386.474462 -261.619343)
		(end 386.287264 -261.5692)
		(width 0.088646)
		(layer "In2.Cu")
		(net "M_F_CPU0_SA_CB<6>")
	)
	(arc
		(start 387.227064 -261.5692)
		(mid 386.944362 -261.493424)
		(end 386.66166 -261.5692)
		(width 0.088646)
		(layer "In2.Cu")
		(net "M_F_CPU0_SA_CB<6>")
	)
	(arc
		(start 387.884416 -261.493254)
		(mid 387.737929 -261.512569)
		(end 387.60146 -261.5692)
		(width 0.088646)
		(layer "In2.Cu")
		(net "M_F_CPU0_SA_CB<6>")
	)
	(arc
		(start 387.60146 -261.5692)
		(mid 387.414262 -261.619343)
		(end 387.227064 -261.5692)
		(width 0.088646)
		(layer "In2.Cu")
		(net "M_F_CPU0_SA_CB<6>")
	)
	(segment
		(start 429.384714 -271.266666)
		(end 429.38446 -271.26692)
		(width 0.20066)
		(layer "F.Cu")
		(net "M_F_CPU0_SA_CB<5>")
	)
	(segment
		(start 424.085512 -271.515332)
		(end 423.610278 -271.515332)
		(width 0.20066)
		(layer "F.Cu")
		(net "M_F_CPU0_SA_CB<5>")
	)
	(segment
		(start 429.38446 -271.26692)
		(end 427.792896 -271.26692)
		(width 0.20066)
		(layer "F.Cu")
		(net "M_F_CPU0_SA_CB<5>")
	)
	(segment
		(start 424.273472 -270.959834)
		(end 424.273472 -271.327372)
		(width 0.20066)
		(layer "F.Cu")
		(net "M_F_CPU0_SA_CB<5>")
	)
	(segment
		(start 424.73626 -270.841724)
		(end 424.391582 -270.841724)
		(width 0.20066)
		(layer "F.Cu")
		(net "M_F_CPU0_SA_CB<5>")
	)
	(segment
		(start 423.610278 -271.515332)
		(end 423.361612 -271.266666)
		(width 0.20066)
		(layer "F.Cu")
		(net "M_F_CPU0_SA_CB<5>")
	)
	(segment
		(start 424.273472 -271.327372)
		(end 424.085512 -271.515332)
		(width 0.20066)
		(layer "F.Cu")
		(net "M_F_CPU0_SA_CB<5>")
	)
	(segment
		(start 381.775716 -260.708902)
		(end 381.775716 -261.244334)
		(width 0.20066)
		(layer "F.Cu")
		(net "M_F_CPU0_SA_CB<5>")
	)
	(segment
		(start 424.756326 -270.841724)
		(end 424.73626 -270.841724)
		(width 0.101854)
		(layer "F.Cu")
		(net "M_F_CPU0_SA_CB<5>")
	)
	(segment
		(start 381.775462 -261.244588)
		(end 381.775462 -261.244842)
		(width 0.20066)
		(layer "F.Cu")
		(net "M_F_CPU0_SA_CB<5>")
	)
	(segment
		(start 423.361612 -271.266666)
		(end 421.840914 -271.266666)
		(width 0.20066)
		(layer "F.Cu")
		(net "M_F_CPU0_SA_CB<5>")
	)
	(segment
		(start 427.36135 -270.835374)
		(end 426.951394 -270.835374)
		(width 0.20066)
		(layer "F.Cu")
		(net "M_F_CPU0_SA_CB<5>")
	)
	(segment
		(start 381.775716 -261.244334)
		(end 381.775462 -261.244588)
		(width 0.20066)
		(layer "F.Cu")
		(net "M_F_CPU0_SA_CB<5>")
	)
	(segment
		(start 421.840914 -271.266666)
		(end 420.736014 -271.266666)
		(width 0.20066)
		(layer "F.Cu")
		(net "M_F_CPU0_SA_CB<5>")
	)
	(segment
		(start 424.391582 -270.841724)
		(end 424.273472 -270.959834)
		(width 0.20066)
		(layer "F.Cu")
		(net "M_F_CPU0_SA_CB<5>")
	)
	(segment
		(start 427.792896 -271.26692)
		(end 427.36135 -270.835374)
		(width 0.20066)
		(layer "F.Cu")
		(net "M_F_CPU0_SA_CB<5>")
	)
	(segment
		(start 426.951394 -270.835374)
		(end 426.945044 -270.841724)
		(width 0.1016)
		(layer "F.Cu")
		(net "M_F_CPU0_SA_CB<5>")
	)
	(segment
		(start 426.945044 -270.841724)
		(end 424.756326 -270.841724)
		(width 0.1016)
		(layer "F.Cu")
		(net "M_F_CPU0_SA_CB<5>")
	)
	(segment
		(start 414.739582 -270.854932)
		(end 413.925258 -270.854932)
		(width 0.18288)
		(layer "In2.Cu")
		(net "M_F_CPU0_SA_CB<5>")
	)
	(segment
		(start 416.92068 -270.553942)
		(end 416.468052 -271.00657)
		(width 0.18288)
		(layer "In2.Cu")
		(net "M_F_CPU0_SA_CB<5>")
	)
	(segment
		(start 406.28951 -268.875002)
		(end 406.023826 -269.140686)
		(width 0.18288)
		(layer "In2.Cu")
		(net "M_F_CPU0_SA_CB<5>")
	)
	(segment
		(start 405.084788 -269.140686)
		(end 404.705566 -268.761464)
		(width 0.18288)
		(layer "In2.Cu")
		(net "M_F_CPU0_SA_CB<5>")
	)
	(segment
		(start 417.193984 -270.553942)
		(end 416.92068 -270.553942)
		(width 0.18288)
		(layer "In2.Cu")
		(net "M_F_CPU0_SA_CB<5>")
	)
	(segment
		(start 409.67533 -270.29029)
		(end 409.37434 -270.29029)
		(width 0.18288)
		(layer "In2.Cu")
		(net "M_F_CPU0_SA_CB<5>")
	)
	(segment
		(start 415.851848 -270.80845)
		(end 415.851848 -270.03121)
		(width 0.18288)
		(layer "In2.Cu")
		(net "M_F_CPU0_SA_CB<5>")
	)
	(segment
		(start 388.840218 -261.25805)
		(end 388.37489 -261.25805)
		(width 0.088646)
		(layer "In2.Cu")
		(net "M_F_CPU0_SA_CB<5>")
	)
	(segment
		(start 408.888184 -269.006828)
		(end 408.232864 -269.006828)
		(width 0.18288)
		(layer "In2.Cu")
		(net "M_F_CPU0_SA_CB<5>")
	)
	(segment
		(start 402.71319 -266.769088)
		(end 402.71319 -266.356592)
		(width 0.18288)
		(layer "In2.Cu")
		(net "M_F_CPU0_SA_CB<5>")
	)
	(segment
		(start 409.37434 -270.29029)
		(end 409.081224 -269.997174)
		(width 0.18288)
		(layer "In2.Cu")
		(net "M_F_CPU0_SA_CB<5>")
	)
	(segment
		(start 404.001224 -268.057122)
		(end 403.709378 -267.765276)
		(width 0.18288)
		(layer "In2.Cu")
		(net "M_F_CPU0_SA_CB<5>")
	)
	(segment
		(start 402.008848 -266.064746)
		(end 401.717002 -265.7729)
		(width 0.18288)
		(layer "In2.Cu")
		(net "M_F_CPU0_SA_CB<5>")
	)
	(segment
		(start 383.467864 -260.920484)
		(end 383.458974 -260.925564)
		(width 0.088646)
		(layer "In2.Cu")
		(net "M_F_CPU0_SA_CB<5>")
	)
	(segment
		(start 420.736014 -271.266666)
		(end 420.193724 -271.266666)
		(width 0.18288)
		(layer "In2.Cu")
		(net "M_F_CPU0_SA_CB<5>")
	)
	(segment
		(start 383.280412 -261.244842)
		(end 383.280412 -261.254748)
		(width 0.088646)
		(layer "In2.Cu")
		(net "M_F_CPU0_SA_CB<5>")
	)
	(segment
		(start 407.258774 -268.875002)
		(end 406.28951 -268.875002)
		(width 0.18288)
		(layer "In2.Cu")
		(net "M_F_CPU0_SA_CB<5>")
	)
	(segment
		(start 419.626034 -270.698976)
		(end 419.343586 -270.698976)
		(width 0.18288)
		(layer "In2.Cu")
		(net "M_F_CPU0_SA_CB<5>")
	)
	(segment
		(start 382.432814 -261.7343)
		(end 382.426718 -261.730744)
		(width 0.088646)
		(layer "In2.Cu")
		(net "M_F_CPU0_SA_CB<5>")
	)
	(segment
		(start 413.675322 -270.135096)
		(end 413.379158 -269.838932)
		(width 0.18288)
		(layer "In2.Cu")
		(net "M_F_CPU0_SA_CB<5>")
	)
	(segment
		(start 412.970472 -269.838932)
		(end 412.777178 -270.032226)
		(width 0.18288)
		(layer "In2.Cu")
		(net "M_F_CPU0_SA_CB<5>")
	)
	(segment
		(start 411.848808 -270.04264)
		(end 409.92298 -270.04264)
		(width 0.18288)
		(layer "In2.Cu")
		(net "M_F_CPU0_SA_CB<5>")
	)
	(segment
		(start 401.717002 -265.7729)
		(end 401.717002 -265.360404)
		(width 0.18288)
		(layer "In2.Cu")
		(net "M_F_CPU0_SA_CB<5>")
	)
	(segment
		(start 400.720814 -264.364216)
		(end 399.724372 -263.367774)
		(width 0.18288)
		(layer "In2.Cu")
		(net "M_F_CPU0_SA_CB<5>")
	)
	(segment
		(start 413.379158 -269.838932)
		(end 412.970472 -269.838932)
		(width 0.18288)
		(layer "In2.Cu")
		(net "M_F_CPU0_SA_CB<5>")
	)
	(segment
		(start 392.687302 -261.25805)
		(end 388.840218 -261.25805)
		(width 0.18288)
		(layer "In2.Cu")
		(net "M_F_CPU0_SA_CB<5>")
	)
	(segment
		(start 402.421344 -266.064746)
		(end 402.008848 -266.064746)
		(width 0.18288)
		(layer "In2.Cu")
		(net "M_F_CPU0_SA_CB<5>")
	)
	(segment
		(start 408.083766 -269.155926)
		(end 407.539698 -269.155926)
		(width 0.18288)
		(layer "In2.Cu")
		(net "M_F_CPU0_SA_CB<5>")
	)
	(segment
		(start 399.724372 -263.367774)
		(end 395.142466 -263.367774)
		(width 0.18288)
		(layer "In2.Cu")
		(net "M_F_CPU0_SA_CB<5>")
	)
	(segment
		(start 404.41372 -268.057122)
		(end 404.001224 -268.057122)
		(width 0.18288)
		(layer "In2.Cu")
		(net "M_F_CPU0_SA_CB<5>")
	)
	(segment
		(start 406.023826 -269.140686)
		(end 405.084788 -269.140686)
		(width 0.18288)
		(layer "In2.Cu")
		(net "M_F_CPU0_SA_CB<5>")
	)
	(segment
		(start 403.709378 -267.35278)
		(end 403.417532 -267.060934)
		(width 0.18288)
		(layer "In2.Cu")
		(net "M_F_CPU0_SA_CB<5>")
	)
	(segment
		(start 418.816536 -271.226026)
		(end 417.866068 -271.226026)
		(width 0.18288)
		(layer "In2.Cu")
		(net "M_F_CPU0_SA_CB<5>")
	)
	(segment
		(start 419.343586 -270.698976)
		(end 418.816536 -271.226026)
		(width 0.18288)
		(layer "In2.Cu")
		(net "M_F_CPU0_SA_CB<5>")
	)
	(segment
		(start 416.049968 -271.00657)
		(end 415.851848 -270.80845)
		(width 0.18288)
		(layer "In2.Cu")
		(net "M_F_CPU0_SA_CB<5>")
	)
	(segment
		(start 414.972246 -270.622268)
		(end 414.739582 -270.854932)
		(width 0.18288)
		(layer "In2.Cu")
		(net "M_F_CPU0_SA_CB<5>")
	)
	(segment
		(start 407.539698 -269.155926)
		(end 407.258774 -268.875002)
		(width 0.18288)
		(layer "In2.Cu")
		(net "M_F_CPU0_SA_CB<5>")
	)
	(segment
		(start 402.71319 -266.356592)
		(end 402.421344 -266.064746)
		(width 0.18288)
		(layer "In2.Cu")
		(net "M_F_CPU0_SA_CB<5>")
	)
	(segment
		(start 415.851848 -270.03121)
		(end 415.623502 -269.802864)
		(width 0.18288)
		(layer "In2.Cu")
		(net "M_F_CPU0_SA_CB<5>")
	)
	(segment
		(start 413.675322 -270.604996)
		(end 413.675322 -270.135096)
		(width 0.18288)
		(layer "In2.Cu")
		(net "M_F_CPU0_SA_CB<5>")
	)
	(segment
		(start 395.142466 -263.367774)
		(end 393.276836 -261.502144)
		(width 0.18288)
		(layer "In2.Cu")
		(net "M_F_CPU0_SA_CB<5>")
	)
	(segment
		(start 415.623502 -269.802864)
		(end 415.255964 -269.802864)
		(width 0.18288)
		(layer "In2.Cu")
		(net "M_F_CPU0_SA_CB<5>")
	)
	(segment
		(start 408.232864 -269.006828)
		(end 408.083766 -269.155926)
		(width 0.18288)
		(layer "In2.Cu")
		(net "M_F_CPU0_SA_CB<5>")
	)
	(segment
		(start 382.443228 -261.740396)
		(end 382.432814 -261.7343)
		(width 0.088646)
		(layer "In2.Cu")
		(net "M_F_CPU0_SA_CB<5>")
	)
	(segment
		(start 382.153922 -261.310374)
		(end 382.08839 -261.244842)
		(width 0.088646)
		(layer "In2.Cu")
		(net "M_F_CPU0_SA_CB<5>")
	)
	(segment
		(start 404.705566 -268.348968)
		(end 404.41372 -268.057122)
		(width 0.18288)
		(layer "In2.Cu")
		(net "M_F_CPU0_SA_CB<5>")
	)
	(segment
		(start 412.054548 -270.24838)
		(end 411.848808 -270.04264)
		(width 0.18288)
		(layer "In2.Cu")
		(net "M_F_CPU0_SA_CB<5>")
	)
	(segment
		(start 393.276836 -261.502144)
		(end 392.687302 -261.25805)
		(width 0.18288)
		(layer "In2.Cu")
		(net "M_F_CPU0_SA_CB<5>")
	)
	(segment
		(start 415.255964 -269.802864)
		(end 414.972246 -270.086582)
		(width 0.18288)
		(layer "In2.Cu")
		(net "M_F_CPU0_SA_CB<5>")
	)
	(segment
		(start 403.417532 -267.060934)
		(end 403.005036 -267.060934)
		(width 0.18288)
		(layer "In2.Cu")
		(net "M_F_CPU0_SA_CB<5>")
	)
	(segment
		(start 409.081224 -269.997174)
		(end 409.081224 -269.199868)
		(width 0.18288)
		(layer "In2.Cu")
		(net "M_F_CPU0_SA_CB<5>")
	)
	(segment
		(start 388.11327 -260.99643)
		(end 387.884416 -260.99643)
		(width 0.088646)
		(layer "In2.Cu")
		(net "M_F_CPU0_SA_CB<5>")
	)
	(segment
		(start 420.193724 -271.266666)
		(end 419.626034 -270.698976)
		(width 0.18288)
		(layer "In2.Cu")
		(net "M_F_CPU0_SA_CB<5>")
	)
	(segment
		(start 409.92298 -270.04264)
		(end 409.67533 -270.29029)
		(width 0.18288)
		(layer "In2.Cu")
		(net "M_F_CPU0_SA_CB<5>")
	)
	(segment
		(start 400.720814 -264.776712)
		(end 400.720814 -264.364216)
		(width 0.18288)
		(layer "In2.Cu")
		(net "M_F_CPU0_SA_CB<5>")
	)
	(segment
		(start 412.777178 -270.032226)
		(end 412.777178 -270.109442)
		(width 0.18288)
		(layer "In2.Cu")
		(net "M_F_CPU0_SA_CB<5>")
	)
	(segment
		(start 401.425156 -265.068558)
		(end 401.01266 -265.068558)
		(width 0.18288)
		(layer "In2.Cu")
		(net "M_F_CPU0_SA_CB<5>")
	)
	(segment
		(start 409.081224 -269.199868)
		(end 408.888184 -269.006828)
		(width 0.18288)
		(layer "In2.Cu")
		(net "M_F_CPU0_SA_CB<5>")
	)
	(segment
		(start 413.925258 -270.854932)
		(end 413.675322 -270.604996)
		(width 0.18288)
		(layer "In2.Cu")
		(net "M_F_CPU0_SA_CB<5>")
	)
	(segment
		(start 382.08839 -261.244842)
		(end 381.775462 -261.244842)
		(width 0.088646)
		(layer "In2.Cu")
		(net "M_F_CPU0_SA_CB<5>")
	)
	(segment
		(start 404.705566 -268.761464)
		(end 404.705566 -268.348968)
		(width 0.18288)
		(layer "In2.Cu")
		(net "M_F_CPU0_SA_CB<5>")
	)
	(segment
		(start 401.717002 -265.360404)
		(end 401.425156 -265.068558)
		(width 0.18288)
		(layer "In2.Cu")
		(net "M_F_CPU0_SA_CB<5>")
	)
	(segment
		(start 403.005036 -267.060934)
		(end 402.71319 -266.769088)
		(width 0.18288)
		(layer "In2.Cu")
		(net "M_F_CPU0_SA_CB<5>")
	)
	(segment
		(start 388.37489 -261.25805)
		(end 388.11327 -260.99643)
		(width 0.088646)
		(layer "In2.Cu")
		(net "M_F_CPU0_SA_CB<5>")
	)
	(segment
		(start 403.709378 -267.765276)
		(end 403.709378 -267.35278)
		(width 0.18288)
		(layer "In2.Cu")
		(net "M_F_CPU0_SA_CB<5>")
	)
	(segment
		(start 412.63824 -270.24838)
		(end 412.054548 -270.24838)
		(width 0.18288)
		(layer "In2.Cu")
		(net "M_F_CPU0_SA_CB<5>")
	)
	(segment
		(start 417.866068 -271.226026)
		(end 417.193984 -270.553942)
		(width 0.18288)
		(layer "In2.Cu")
		(net "M_F_CPU0_SA_CB<5>")
	)
	(segment
		(start 416.468052 -271.00657)
		(end 416.049968 -271.00657)
		(width 0.18288)
		(layer "In2.Cu")
		(net "M_F_CPU0_SA_CB<5>")
	)
	(segment
		(start 401.01266 -265.068558)
		(end 400.720814 -264.776712)
		(width 0.18288)
		(layer "In2.Cu")
		(net "M_F_CPU0_SA_CB<5>")
	)
	(segment
		(start 414.972246 -270.086582)
		(end 414.972246 -270.622268)
		(width 0.18288)
		(layer "In2.Cu")
		(net "M_F_CPU0_SA_CB<5>")
	)
	(segment
		(start 412.777178 -270.109442)
		(end 412.63824 -270.24838)
		(width 0.18288)
		(layer "In2.Cu")
		(net "M_F_CPU0_SA_CB<5>")
	)
	(arc
		(start 385.72186 -260.920484)
		(mid 385.534662 -260.870341)
		(end 385.347464 -260.920484)
		(width 0.088646)
		(layer "In2.Cu")
		(net "M_F_CPU0_SA_CB<5>")
	)
	(arc
		(start 382.426718 -261.730744)
		(mid 382.241195 -261.552443)
		(end 382.153922 -261.310374)
		(width 0.088646)
		(layer "In2.Cu")
		(net "M_F_CPU0_SA_CB<5>")
	)
	(arc
		(start 383.84226 -260.920484)
		(mid 383.655062 -260.870341)
		(end 383.467864 -260.920484)
		(width 0.088646)
		(layer "In2.Cu")
		(net "M_F_CPU0_SA_CB<5>")
	)
	(arc
		(start 385.347464 -260.920484)
		(mid 385.064762 -260.996226)
		(end 384.78206 -260.920484)
		(width 0.088646)
		(layer "In2.Cu")
		(net "M_F_CPU0_SA_CB<5>")
	)
	(arc
		(start 383.458974 -260.925564)
		(mid 383.32806 -261.061924)
		(end 383.280412 -261.244842)
		(width 0.088646)
		(layer "In2.Cu")
		(net "M_F_CPU0_SA_CB<5>")
	)
	(arc
		(start 383.280412 -261.254748)
		(mid 383.202301 -261.531697)
		(end 382.997964 -261.7343)
		(width 0.088646)
		(layer "In2.Cu")
		(net "M_F_CPU0_SA_CB<5>")
	)
	(arc
		(start 386.66166 -260.920484)
		(mid 386.474462 -260.870341)
		(end 386.287264 -260.920484)
		(width 0.088646)
		(layer "In2.Cu")
		(net "M_F_CPU0_SA_CB<5>")
	)
	(arc
		(start 384.407664 -260.920484)
		(mid 384.124962 -260.996226)
		(end 383.84226 -260.920484)
		(width 0.088646)
		(layer "In2.Cu")
		(net "M_F_CPU0_SA_CB<5>")
	)
	(arc
		(start 382.997964 -261.7343)
		(mid 382.721405 -261.810043)
		(end 382.443228 -261.740396)
		(width 0.088646)
		(layer "In2.Cu")
		(net "M_F_CPU0_SA_CB<5>")
	)
	(arc
		(start 384.78206 -260.920484)
		(mid 384.594862 -260.870341)
		(end 384.407664 -260.920484)
		(width 0.088646)
		(layer "In2.Cu")
		(net "M_F_CPU0_SA_CB<5>")
	)
	(arc
		(start 387.884416 -260.99643)
		(mid 387.737946 -260.97707)
		(end 387.60146 -260.920484)
		(width 0.088646)
		(layer "In2.Cu")
		(net "M_F_CPU0_SA_CB<5>")
	)
	(arc
		(start 386.287264 -260.920484)
		(mid 386.004562 -260.996226)
		(end 385.72186 -260.920484)
		(width 0.088646)
		(layer "In2.Cu")
		(net "M_F_CPU0_SA_CB<5>")
	)
	(arc
		(start 387.227064 -260.920484)
		(mid 386.944362 -260.996226)
		(end 386.66166 -260.920484)
		(width 0.088646)
		(layer "In2.Cu")
		(net "M_F_CPU0_SA_CB<5>")
	)
	(arc
		(start 387.60146 -260.920484)
		(mid 387.414262 -260.870341)
		(end 387.227064 -260.920484)
		(width 0.088646)
		(layer "In2.Cu")
		(net "M_F_CPU0_SA_CB<5>")
	)
	(segment
		(start 421.840914 -272.966688)
		(end 420.736014 -272.966688)
		(width 0.20066)
		(layer "F.Cu")
		(net "M_F_CPU0_SA_CB<4>")
	)
	(segment
		(start 424.73626 -272.541746)
		(end 424.391582 -272.541746)
		(width 0.20066)
		(layer "F.Cu")
		(net "M_F_CPU0_SA_CB<4>")
	)
	(segment
		(start 381.305816 -261.522972)
		(end 381.305816 -262.058658)
		(width 0.20066)
		(layer "F.Cu")
		(net "M_F_CPU0_SA_CB<4>")
	)
	(segment
		(start 424.273472 -273.027394)
		(end 424.085512 -273.215354)
		(width 0.20066)
		(layer "F.Cu")
		(net "M_F_CPU0_SA_CB<4>")
	)
	(segment
		(start 423.610278 -273.215354)
		(end 423.361612 -272.966688)
		(width 0.20066)
		(layer "F.Cu")
		(net "M_F_CPU0_SA_CB<4>")
	)
	(segment
		(start 424.78325 -272.541746)
		(end 424.73626 -272.541746)
		(width 0.101854)
		(layer "F.Cu")
		(net "M_F_CPU0_SA_CB<4>")
	)
	(segment
		(start 427.792896 -272.966942)
		(end 427.36135 -272.535396)
		(width 0.20066)
		(layer "F.Cu")
		(net "M_F_CPU0_SA_CB<4>")
	)
	(segment
		(start 427.36135 -272.535396)
		(end 426.951394 -272.535396)
		(width 0.20066)
		(layer "F.Cu")
		(net "M_F_CPU0_SA_CB<4>")
	)
	(segment
		(start 424.085512 -273.215354)
		(end 423.610278 -273.215354)
		(width 0.20066)
		(layer "F.Cu")
		(net "M_F_CPU0_SA_CB<4>")
	)
	(segment
		(start 424.273472 -272.659856)
		(end 424.273472 -273.027394)
		(width 0.20066)
		(layer "F.Cu")
		(net "M_F_CPU0_SA_CB<4>")
	)
	(segment
		(start 426.951394 -272.535396)
		(end 426.945044 -272.541746)
		(width 0.1016)
		(layer "F.Cu")
		(net "M_F_CPU0_SA_CB<4>")
	)
	(segment
		(start 426.945044 -272.541746)
		(end 424.78325 -272.541746)
		(width 0.1016)
		(layer "F.Cu")
		(net "M_F_CPU0_SA_CB<4>")
	)
	(segment
		(start 423.361612 -272.966688)
		(end 421.840914 -272.966688)
		(width 0.20066)
		(layer "F.Cu")
		(net "M_F_CPU0_SA_CB<4>")
	)
	(segment
		(start 381.305562 -261.522718)
		(end 381.305816 -261.522972)
		(width 0.20066)
		(layer "F.Cu")
		(net "M_F_CPU0_SA_CB<4>")
	)
	(segment
		(start 429.38446 -272.966942)
		(end 427.792896 -272.966942)
		(width 0.20066)
		(layer "F.Cu")
		(net "M_F_CPU0_SA_CB<4>")
	)
	(segment
		(start 429.384714 -272.966688)
		(end 429.38446 -272.966942)
		(width 0.20066)
		(layer "F.Cu")
		(net "M_F_CPU0_SA_CB<4>")
	)
	(segment
		(start 424.391582 -272.541746)
		(end 424.273472 -272.659856)
		(width 0.20066)
		(layer "F.Cu")
		(net "M_F_CPU0_SA_CB<4>")
	)
	(segment
		(start 420.370762 -272.546826)
		(end 420.065962 -272.242026)
		(width 0.18288)
		(layer "In2.Cu")
		(net "M_F_CPU0_SA_CB<4>")
	)
	(segment
		(start 411.70733 -271.693386)
		(end 411.411674 -271.39773)
		(width 0.18288)
		(layer "In2.Cu")
		(net "M_F_CPU0_SA_CB<4>")
	)
	(segment
		(start 414.196784 -272.34896)
		(end 414.049972 -272.202148)
		(width 0.18288)
		(layer "In2.Cu")
		(net "M_F_CPU0_SA_CB<4>")
	)
	(segment
		(start 407.38552 -270.716248)
		(end 407.179526 -270.510254)
		(width 0.18288)
		(layer "In2.Cu")
		(net "M_F_CPU0_SA_CB<4>")
	)
	(segment
		(start 416.64128 -272.02257)
		(end 416.251136 -272.02257)
		(width 0.18288)
		(layer "In2.Cu")
		(net "M_F_CPU0_SA_CB<4>")
	)
	(segment
		(start 416.8648 -272.24609)
		(end 416.64128 -272.02257)
		(width 0.18288)
		(layer "In2.Cu")
		(net "M_F_CPU0_SA_CB<4>")
	)
	(segment
		(start 383.937764 -261.7343)
		(end 383.93751 -261.734554)
		(width 0.088646)
		(layer "In2.Cu")
		(net "M_F_CPU0_SA_CB<4>")
	)
	(segment
		(start 417.19246 -272.24609)
		(end 416.8648 -272.24609)
		(width 0.18288)
		(layer "In2.Cu")
		(net "M_F_CPU0_SA_CB<4>")
	)
	(segment
		(start 410.344366 -271.39773)
		(end 409.783026 -271.95907)
		(width 0.18288)
		(layer "In2.Cu")
		(net "M_F_CPU0_SA_CB<4>")
	)
	(segment
		(start 415.508186 -272.85823)
		(end 414.871154 -272.221198)
		(width 0.18288)
		(layer "In2.Cu")
		(net "M_F_CPU0_SA_CB<4>")
	)
	(segment
		(start 388.194804 -261.6835)
		(end 387.884416 -261.6835)
		(width 0.088646)
		(layer "In2.Cu")
		(net "M_F_CPU0_SA_CB<4>")
	)
	(segment
		(start 414.049972 -272.202148)
		(end 413.776668 -272.202148)
		(width 0.18288)
		(layer "In2.Cu")
		(net "M_F_CPU0_SA_CB<4>")
	)
	(segment
		(start 407.859738 -271.160748)
		(end 407.736548 -270.862298)
		(width 0.18288)
		(layer "In2.Cu")
		(net "M_F_CPU0_SA_CB<4>")
	)
	(segment
		(start 417.449 -272.50263)
		(end 417.19246 -272.24609)
		(width 0.18288)
		(layer "In2.Cu")
		(net "M_F_CPU0_SA_CB<4>")
	)
	(segment
		(start 383.658364 -262.217662)
		(end 383.37236 -262.383016)
		(width 0.088646)
		(layer "In2.Cu")
		(net "M_F_CPU0_SA_CB<4>")
	)
	(segment
		(start 406.17902 -270.510254)
		(end 405.517604 -271.17167)
		(width 0.18288)
		(layer "In2.Cu")
		(net "M_F_CPU0_SA_CB<4>")
	)
	(segment
		(start 407.736548 -270.862298)
		(end 407.38552 -270.716248)
		(width 0.18288)
		(layer "In2.Cu")
		(net "M_F_CPU0_SA_CB<4>")
	)
	(segment
		(start 409.202636 -271.800066)
		(end 409.07335 -271.487646)
		(width 0.18288)
		(layer "In2.Cu")
		(net "M_F_CPU0_SA_CB<4>")
	)
	(segment
		(start 408.488642 -271.45488)
		(end 408.419554 -271.62125)
		(width 0.18288)
		(layer "In2.Cu")
		(net "M_F_CPU0_SA_CB<4>")
	)
	(segment
		(start 395.123416 -264.38987)
		(end 392.901932 -262.168386)
		(width 0.18288)
		(layer "In2.Cu")
		(net "M_F_CPU0_SA_CB<4>")
	)
	(segment
		(start 392.901932 -262.168386)
		(end 392.417554 -261.967726)
		(width 0.18288)
		(layer "In2.Cu")
		(net "M_F_CPU0_SA_CB<4>")
	)
	(segment
		(start 416.048444 -272.66519)
		(end 415.855404 -272.85823)
		(width 0.18288)
		(layer "In2.Cu")
		(net "M_F_CPU0_SA_CB<4>")
	)
	(segment
		(start 416.048444 -272.225262)
		(end 416.048444 -272.66519)
		(width 0.18288)
		(layer "In2.Cu")
		(net "M_F_CPU0_SA_CB<4>")
	)
	(segment
		(start 404.929848 -271.022572)
		(end 404.508208 -270.004794)
		(width 0.18288)
		(layer "In2.Cu")
		(net "M_F_CPU0_SA_CB<4>")
	)
	(segment
		(start 412.44647 -271.693386)
		(end 411.70733 -271.693386)
		(width 0.18288)
		(layer "In2.Cu")
		(net "M_F_CPU0_SA_CB<4>")
	)
	(segment
		(start 382.997964 -262.383016)
		(end 382.983232 -262.37438)
		(width 0.088646)
		(layer "In2.Cu")
		(net "M_F_CPU0_SA_CB<4>")
	)
	(segment
		(start 420.58336 -272.546826)
		(end 420.370762 -272.546826)
		(width 0.18288)
		(layer "In2.Cu")
		(net "M_F_CPU0_SA_CB<4>")
	)
	(segment
		(start 388.840472 -261.967726)
		(end 388.47903 -261.967726)
		(width 0.088646)
		(layer "In2.Cu")
		(net "M_F_CPU0_SA_CB<4>")
	)
	(segment
		(start 388.47903 -261.967726)
		(end 388.194804 -261.6835)
		(width 0.088646)
		(layer "In2.Cu")
		(net "M_F_CPU0_SA_CB<4>")
	)
	(segment
		(start 399.641822 -265.138408)
		(end 399.641822 -264.74928)
		(width 0.18288)
		(layer "In2.Cu")
		(net "M_F_CPU0_SA_CB<4>")
	)
	(segment
		(start 408.741118 -271.349978)
		(end 408.488642 -271.45488)
		(width 0.18288)
		(layer "In2.Cu")
		(net "M_F_CPU0_SA_CB<4>")
	)
	(segment
		(start 392.417554 -261.967726)
		(end 388.840472 -261.967726)
		(width 0.18288)
		(layer "In2.Cu")
		(net "M_F_CPU0_SA_CB<4>")
	)
	(segment
		(start 412.862776 -272.84299)
		(end 412.639764 -272.619978)
		(width 0.18288)
		(layer "In2.Cu")
		(net "M_F_CPU0_SA_CB<4>")
	)
	(segment
		(start 414.59785 -272.221198)
		(end 414.470088 -272.34896)
		(width 0.18288)
		(layer "In2.Cu")
		(net "M_F_CPU0_SA_CB<4>")
	)
	(segment
		(start 399.282412 -264.38987)
		(end 395.123416 -264.38987)
		(width 0.18288)
		(layer "In2.Cu")
		(net "M_F_CPU0_SA_CB<4>")
	)
	(segment
		(start 415.855404 -272.85823)
		(end 415.508186 -272.85823)
		(width 0.18288)
		(layer "In2.Cu")
		(net "M_F_CPU0_SA_CB<4>")
	)
	(segment
		(start 412.639764 -271.88668)
		(end 412.44647 -271.693386)
		(width 0.18288)
		(layer "In2.Cu")
		(net "M_F_CPU0_SA_CB<4>")
	)
	(segment
		(start 414.470088 -272.34896)
		(end 414.196784 -272.34896)
		(width 0.18288)
		(layer "In2.Cu")
		(net "M_F_CPU0_SA_CB<4>")
	)
	(segment
		(start 414.871154 -272.221198)
		(end 414.59785 -272.221198)
		(width 0.18288)
		(layer "In2.Cu")
		(net "M_F_CPU0_SA_CB<4>")
	)
	(segment
		(start 382.154176 -262.457692)
		(end 381.54737 -262.457692)
		(width 0.088646)
		(layer "In2.Cu")
		(net "M_F_CPU0_SA_CB<4>")
	)
	(segment
		(start 409.783026 -271.95907)
		(end 409.441142 -271.95907)
		(width 0.18288)
		(layer "In2.Cu")
		(net "M_F_CPU0_SA_CB<4>")
	)
	(segment
		(start 411.411674 -271.39773)
		(end 410.344366 -271.39773)
		(width 0.18288)
		(layer "In2.Cu")
		(net "M_F_CPU0_SA_CB<4>")
	)
	(segment
		(start 409.07335 -271.487646)
		(end 408.741118 -271.349978)
		(width 0.18288)
		(layer "In2.Cu")
		(net "M_F_CPU0_SA_CB<4>")
	)
	(segment
		(start 381.404368 -262.354568)
		(end 381.305816 -262.058658)
		(width 0.088646)
		(layer "In2.Cu")
		(net "M_F_CPU0_SA_CB<4>")
	)
	(segment
		(start 413.135826 -272.84299)
		(end 412.862776 -272.84299)
		(width 0.18288)
		(layer "In2.Cu")
		(net "M_F_CPU0_SA_CB<4>")
	)
	(segment
		(start 409.441142 -271.95907)
		(end 409.202636 -271.800066)
		(width 0.18288)
		(layer "In2.Cu")
		(net "M_F_CPU0_SA_CB<4>")
	)
	(segment
		(start 407.179526 -270.510254)
		(end 406.17902 -270.510254)
		(width 0.18288)
		(layer "In2.Cu")
		(net "M_F_CPU0_SA_CB<4>")
	)
	(segment
		(start 420.736014 -272.966688)
		(end 420.736014 -272.69948)
		(width 0.18288)
		(layer "In2.Cu")
		(net "M_F_CPU0_SA_CB<4>")
	)
	(segment
		(start 408.21102 -271.707864)
		(end 407.86558 -271.564862)
		(width 0.18288)
		(layer "In2.Cu")
		(net "M_F_CPU0_SA_CB<4>")
	)
	(segment
		(start 407.778966 -271.356074)
		(end 407.859738 -271.160748)
		(width 0.18288)
		(layer "In2.Cu")
		(net "M_F_CPU0_SA_CB<4>")
	)
	(segment
		(start 420.736014 -272.69948)
		(end 420.58336 -272.546826)
		(width 0.18288)
		(layer "In2.Cu")
		(net "M_F_CPU0_SA_CB<4>")
	)
	(segment
		(start 419.33241 -272.50263)
		(end 417.449 -272.50263)
		(width 0.18288)
		(layer "In2.Cu")
		(net "M_F_CPU0_SA_CB<4>")
	)
	(segment
		(start 405.517604 -271.17167)
		(end 405.078946 -271.17167)
		(width 0.18288)
		(layer "In2.Cu")
		(net "M_F_CPU0_SA_CB<4>")
	)
	(segment
		(start 419.593014 -272.242026)
		(end 419.33241 -272.50263)
		(width 0.18288)
		(layer "In2.Cu")
		(net "M_F_CPU0_SA_CB<4>")
	)
	(segment
		(start 399.641822 -264.74928)
		(end 399.282412 -264.38987)
		(width 0.18288)
		(layer "In2.Cu")
		(net "M_F_CPU0_SA_CB<4>")
	)
	(segment
		(start 420.065962 -272.242026)
		(end 419.593014 -272.242026)
		(width 0.18288)
		(layer "In2.Cu")
		(net "M_F_CPU0_SA_CB<4>")
	)
	(segment
		(start 404.508208 -270.004794)
		(end 399.641822 -265.138408)
		(width 0.18288)
		(layer "In2.Cu")
		(net "M_F_CPU0_SA_CB<4>")
	)
	(segment
		(start 413.776668 -272.202148)
		(end 413.135826 -272.84299)
		(width 0.18288)
		(layer "In2.Cu")
		(net "M_F_CPU0_SA_CB<4>")
	)
	(segment
		(start 407.86558 -271.564862)
		(end 407.778966 -271.356074)
		(width 0.18288)
		(layer "In2.Cu")
		(net "M_F_CPU0_SA_CB<4>")
	)
	(segment
		(start 405.078946 -271.17167)
		(end 404.929848 -271.022572)
		(width 0.18288)
		(layer "In2.Cu")
		(net "M_F_CPU0_SA_CB<4>")
	)
	(segment
		(start 408.419554 -271.62125)
		(end 408.21102 -271.707864)
		(width 0.18288)
		(layer "In2.Cu")
		(net "M_F_CPU0_SA_CB<4>")
	)
	(segment
		(start 412.639764 -272.619978)
		(end 412.639764 -271.88668)
		(width 0.18288)
		(layer "In2.Cu")
		(net "M_F_CPU0_SA_CB<4>")
	)
	(segment
		(start 416.251136 -272.02257)
		(end 416.048444 -272.225262)
		(width 0.18288)
		(layer "In2.Cu")
		(net "M_F_CPU0_SA_CB<4>")
	)
	(arc
		(start 383.37236 -262.383016)
		(mid 383.185162 -262.433159)
		(end 382.997964 -262.383016)
		(width 0.088646)
		(layer "In2.Cu")
		(net "M_F_CPU0_SA_CB<4>")
	)
	(arc
		(start 386.19176 -261.7343)
		(mid 386.004562 -261.684157)
		(end 385.817364 -261.7343)
		(width 0.088646)
		(layer "In2.Cu")
		(net "M_F_CPU0_SA_CB<4>")
	)
	(arc
		(start 387.13156 -261.7343)
		(mid 386.944362 -261.684157)
		(end 386.757164 -261.7343)
		(width 0.088646)
		(layer "In2.Cu")
		(net "M_F_CPU0_SA_CB<4>")
	)
	(arc
		(start 381.54737 -262.457692)
		(mid 381.459235 -262.429214)
		(end 381.404368 -262.354568)
		(width 0.088646)
		(layer "In2.Cu")
		(net "M_F_CPU0_SA_CB<4>")
	)
	(arc
		(start 382.590294 -262.386826)
		(mid 382.375095 -262.439858)
		(end 382.154176 -262.457692)
		(width 0.088646)
		(layer "In2.Cu")
		(net "M_F_CPU0_SA_CB<4>")
	)
	(arc
		(start 386.757164 -261.7343)
		(mid 386.474462 -261.810076)
		(end 386.19176 -261.7343)
		(width 0.088646)
		(layer "In2.Cu")
		(net "M_F_CPU0_SA_CB<4>")
	)
	(arc
		(start 385.25196 -261.7343)
		(mid 385.064762 -261.684157)
		(end 384.877564 -261.7343)
		(width 0.088646)
		(layer "In2.Cu")
		(net "M_F_CPU0_SA_CB<4>")
	)
	(arc
		(start 384.31216 -261.7343)
		(mid 384.124962 -261.684123)
		(end 383.937764 -261.7343)
		(width 0.088646)
		(layer "In2.Cu")
		(net "M_F_CPU0_SA_CB<4>")
	)
	(arc
		(start 387.884416 -261.6835)
		(mid 387.787346 -261.696557)
		(end 387.696964 -261.7343)
		(width 0.088646)
		(layer "In2.Cu")
		(net "M_F_CPU0_SA_CB<4>")
	)
	(arc
		(start 383.750312 -262.058658)
		(mid 383.725664 -262.150487)
		(end 383.658364 -262.217662)
		(width 0.088646)
		(layer "In2.Cu")
		(net "M_F_CPU0_SA_CB<4>")
	)
	(arc
		(start 385.817364 -261.7343)
		(mid 385.534662 -261.810076)
		(end 385.25196 -261.7343)
		(width 0.088646)
		(layer "In2.Cu")
		(net "M_F_CPU0_SA_CB<4>")
	)
	(arc
		(start 384.877564 -261.7343)
		(mid 384.594862 -261.810076)
		(end 384.31216 -261.7343)
		(width 0.088646)
		(layer "In2.Cu")
		(net "M_F_CPU0_SA_CB<4>")
	)
	(arc
		(start 383.93751 -261.734554)
		(mid 383.800465 -261.871514)
		(end 383.750312 -262.058658)
		(width 0.088646)
		(layer "In2.Cu")
		(net "M_F_CPU0_SA_CB<4>")
	)
	(arc
		(start 387.696964 -261.7343)
		(mid 387.414262 -261.810076)
		(end 387.13156 -261.7343)
		(width 0.088646)
		(layer "In2.Cu")
		(net "M_F_CPU0_SA_CB<4>")
	)
	(arc
		(start 382.983232 -262.37438)
		(mid 382.785847 -262.351832)
		(end 382.590294 -262.386826)
		(width 0.088646)
		(layer "In2.Cu")
		(net "M_F_CPU0_SA_CB<4>")
	)
	(segment
		(start 431.076354 -276.803866)
		(end 431.280316 -276.599904)
		(width 0.20066)
		(layer "F.Cu")
		(net "M_F_CPU0_SA_CB<3>")
	)
	(segment
		(start 432.15052 -276.366732)
		(end 433.484782 -276.366732)
		(width 0.20066)
		(layer "F.Cu")
		(net "M_F_CPU0_SA_CB<3>")
	)
	(segment
		(start 430.395126 -276.803866)
		(end 431.076354 -276.803866)
		(width 0.20066)
		(layer "F.Cu")
		(net "M_F_CPU0_SA_CB<3>")
	)
	(segment
		(start 424.836082 -276.366732)
		(end 425.940982 -276.366732)
		(width 0.20066)
		(layer "F.Cu")
		(net "M_F_CPU0_SA_CB<3>")
	)
	(segment
		(start 430.382934 -276.791674)
		(end 430.395126 -276.803866)
		(width 0.1016)
		(layer "F.Cu")
		(net "M_F_CPU0_SA_CB<3>")
	)
	(segment
		(start 431.280316 -276.599904)
		(end 431.280316 -276.348952)
		(width 0.20066)
		(layer "F.Cu")
		(net "M_F_CPU0_SA_CB<3>")
	)
	(segment
		(start 427.639226 -276.366732)
		(end 428.07128 -276.798786)
		(width 0.20066)
		(layer "F.Cu")
		(net "M_F_CPU0_SA_CB<3>")
	)
	(segment
		(start 425.940982 -276.366732)
		(end 427.639226 -276.366732)
		(width 0.20066)
		(layer "F.Cu")
		(net "M_F_CPU0_SA_CB<3>")
	)
	(segment
		(start 431.898552 -276.114764)
		(end 432.15052 -276.366732)
		(width 0.20066)
		(layer "F.Cu")
		(net "M_F_CPU0_SA_CB<3>")
	)
	(segment
		(start 383.185162 -263.150604)
		(end 383.185162 -263.686544)
		(width 0.20066)
		(layer "F.Cu")
		(net "M_F_CPU0_SA_CB<3>")
	)
	(segment
		(start 428.363126 -276.798786)
		(end 428.367952 -276.798786)
		(width 0.101854)
		(layer "F.Cu")
		(net "M_F_CPU0_SA_CB<3>")
	)
	(segment
		(start 428.375064 -276.791674)
		(end 430.382934 -276.791674)
		(width 0.1016)
		(layer "F.Cu")
		(net "M_F_CPU0_SA_CB<3>")
	)
	(segment
		(start 431.514504 -276.114764)
		(end 431.898552 -276.114764)
		(width 0.20066)
		(layer "F.Cu")
		(net "M_F_CPU0_SA_CB<3>")
	)
	(segment
		(start 428.07128 -276.798786)
		(end 428.363126 -276.798786)
		(width 0.20066)
		(layer "F.Cu")
		(net "M_F_CPU0_SA_CB<3>")
	)
	(segment
		(start 428.367952 -276.798786)
		(end 428.375064 -276.791674)
		(width 0.1016)
		(layer "F.Cu")
		(net "M_F_CPU0_SA_CB<3>")
	)
	(segment
		(start 431.280316 -276.348952)
		(end 431.514504 -276.114764)
		(width 0.20066)
		(layer "F.Cu")
		(net "M_F_CPU0_SA_CB<3>")
	)
	(segment
		(start 422.143682 -276.534372)
		(end 421.648382 -276.534372)
		(width 0.18288)
		(layer "In2.Cu")
		(net "M_F_CPU0_SA_CB<3>")
	)
	(segment
		(start 415.833814 -276.82063)
		(end 412.225998 -276.82063)
		(width 0.18288)
		(layer "In2.Cu")
		(net "M_F_CPU0_SA_CB<3>")
	)
	(segment
		(start 420.334694 -275.839174)
		(end 420.06139 -275.839174)
		(width 0.18288)
		(layer "In2.Cu")
		(net "M_F_CPU0_SA_CB<3>")
	)
	(segment
		(start 412.17723 -276.771862)
		(end 410.028898 -276.771862)
		(width 0.18288)
		(layer "In2.Cu")
		(net "M_F_CPU0_SA_CB<3>")
	)
	(segment
		(start 417.439094 -276.102826)
		(end 416.551618 -276.102826)
		(width 0.18288)
		(layer "In2.Cu")
		(net "M_F_CPU0_SA_CB<3>")
	)
	(segment
		(start 388.44982 -263.842246)
		(end 388.230364 -264.061702)
		(width 0.088646)
		(layer "In2.Cu")
		(net "M_F_CPU0_SA_CB<3>")
	)
	(segment
		(start 402.669756 -271.53489)
		(end 397.928084 -266.793218)
		(width 0.18288)
		(layer "In2.Cu")
		(net "M_F_CPU0_SA_CB<3>")
	)
	(segment
		(start 408.638756 -275.09724)
		(end 405.59355 -275.09724)
		(width 0.18288)
		(layer "In2.Cu")
		(net "M_F_CPU0_SA_CB<3>")
	)
	(segment
		(start 409.005024 -275.463508)
		(end 408.638756 -275.09724)
		(width 0.18288)
		(layer "In2.Cu")
		(net "M_F_CPU0_SA_CB<3>")
	)
	(segment
		(start 424.323002 -275.853652)
		(end 422.824402 -275.853652)
		(width 0.18288)
		(layer "In2.Cu")
		(net "M_F_CPU0_SA_CB<3>")
	)
	(segment
		(start 383.937764 -264.010902)
		(end 383.54508 -263.783064)
		(width 0.088646)
		(layer "In2.Cu")
		(net "M_F_CPU0_SA_CB<3>")
	)
	(segment
		(start 417.55187 -275.99005)
		(end 417.439094 -276.102826)
		(width 0.18288)
		(layer "In2.Cu")
		(net "M_F_CPU0_SA_CB<3>")
	)
	(segment
		(start 397.928084 -266.793218)
		(end 395.149324 -266.793218)
		(width 0.18288)
		(layer "In2.Cu")
		(net "M_F_CPU0_SA_CB<3>")
	)
	(segment
		(start 388.230364 -264.061702)
		(end 387.884416 -264.061702)
		(width 0.088646)
		(layer "In2.Cu")
		(net "M_F_CPU0_SA_CB<3>")
	)
	(segment
		(start 392.535918 -264.179812)
		(end 391.721594 -263.842246)
		(width 0.18288)
		(layer "In2.Cu")
		(net "M_F_CPU0_SA_CB<3>")
	)
	(segment
		(start 420.436802 -275.941282)
		(end 420.334694 -275.839174)
		(width 0.18288)
		(layer "In2.Cu")
		(net "M_F_CPU0_SA_CB<3>")
	)
	(segment
		(start 424.836082 -276.366732)
		(end 424.323002 -275.853652)
		(width 0.18288)
		(layer "In2.Cu")
		(net "M_F_CPU0_SA_CB<3>")
	)
	(segment
		(start 412.225998 -276.82063)
		(end 412.17723 -276.771862)
		(width 0.18288)
		(layer "In2.Cu")
		(net "M_F_CPU0_SA_CB<3>")
	)
	(segment
		(start 395.149324 -266.793218)
		(end 392.535918 -264.179812)
		(width 0.18288)
		(layer "In2.Cu")
		(net "M_F_CPU0_SA_CB<3>")
	)
	(segment
		(start 421.43807 -276.32406)
		(end 421.43807 -276.101302)
		(width 0.18288)
		(layer "In2.Cu")
		(net "M_F_CPU0_SA_CB<3>")
	)
	(segment
		(start 405.59355 -275.09724)
		(end 404.97252 -274.47621)
		(width 0.18288)
		(layer "In2.Cu")
		(net "M_F_CPU0_SA_CB<3>")
	)
	(segment
		(start 421.648382 -276.534372)
		(end 421.43807 -276.32406)
		(width 0.18288)
		(layer "In2.Cu")
		(net "M_F_CPU0_SA_CB<3>")
	)
	(segment
		(start 403.639274 -273.8755)
		(end 402.669756 -271.53489)
		(width 0.18288)
		(layer "In2.Cu")
		(net "M_F_CPU0_SA_CB<3>")
	)
	(segment
		(start 410.028898 -276.771862)
		(end 409.005024 -275.747988)
		(width 0.18288)
		(layer "In2.Cu")
		(net "M_F_CPU0_SA_CB<3>")
	)
	(segment
		(start 419.910514 -275.99005)
		(end 417.55187 -275.99005)
		(width 0.18288)
		(layer "In2.Cu")
		(net "M_F_CPU0_SA_CB<3>")
	)
	(segment
		(start 404.97252 -274.47621)
		(end 404.239984 -274.47621)
		(width 0.18288)
		(layer "In2.Cu")
		(net "M_F_CPU0_SA_CB<3>")
	)
	(segment
		(start 416.551618 -276.102826)
		(end 415.833814 -276.82063)
		(width 0.18288)
		(layer "In2.Cu")
		(net "M_F_CPU0_SA_CB<3>")
	)
	(segment
		(start 422.824402 -275.853652)
		(end 422.143682 -276.534372)
		(width 0.18288)
		(layer "In2.Cu")
		(net "M_F_CPU0_SA_CB<3>")
	)
	(segment
		(start 391.721594 -263.842246)
		(end 388.840472 -263.842246)
		(width 0.18288)
		(layer "In2.Cu")
		(net "M_F_CPU0_SA_CB<3>")
	)
	(segment
		(start 388.840472 -263.842246)
		(end 388.44982 -263.842246)
		(width 0.088646)
		(layer "In2.Cu")
		(net "M_F_CPU0_SA_CB<3>")
	)
	(segment
		(start 420.06139 -275.839174)
		(end 419.910514 -275.99005)
		(width 0.18288)
		(layer "In2.Cu")
		(net "M_F_CPU0_SA_CB<3>")
	)
	(segment
		(start 409.005024 -275.747988)
		(end 409.005024 -275.463508)
		(width 0.18288)
		(layer "In2.Cu")
		(net "M_F_CPU0_SA_CB<3>")
	)
	(segment
		(start 404.239984 -274.47621)
		(end 403.639274 -273.8755)
		(width 0.18288)
		(layer "In2.Cu")
		(net "M_F_CPU0_SA_CB<3>")
	)
	(segment
		(start 421.27805 -275.941282)
		(end 420.436802 -275.941282)
		(width 0.18288)
		(layer "In2.Cu")
		(net "M_F_CPU0_SA_CB<3>")
	)
	(segment
		(start 421.43807 -276.101302)
		(end 421.27805 -275.941282)
		(width 0.18288)
		(layer "In2.Cu")
		(net "M_F_CPU0_SA_CB<3>")
	)
	(arc
		(start 384.877564 -264.010902)
		(mid 384.594862 -263.935126)
		(end 384.31216 -264.010902)
		(width 0.088646)
		(layer "In2.Cu")
		(net "M_F_CPU0_SA_CB<3>")
	)
	(arc
		(start 386.19176 -264.010902)
		(mid 386.004562 -264.061045)
		(end 385.817364 -264.010902)
		(width 0.088646)
		(layer "In2.Cu")
		(net "M_F_CPU0_SA_CB<3>")
	)
	(arc
		(start 386.757164 -264.010902)
		(mid 386.474462 -263.935126)
		(end 386.19176 -264.010902)
		(width 0.088646)
		(layer "In2.Cu")
		(net "M_F_CPU0_SA_CB<3>")
	)
	(arc
		(start 385.25196 -264.010902)
		(mid 385.064762 -264.061045)
		(end 384.877564 -264.010902)
		(width 0.088646)
		(layer "In2.Cu")
		(net "M_F_CPU0_SA_CB<3>")
	)
	(arc
		(start 385.817364 -264.010902)
		(mid 385.534662 -263.935126)
		(end 385.25196 -264.010902)
		(width 0.088646)
		(layer "In2.Cu")
		(net "M_F_CPU0_SA_CB<3>")
	)
	(arc
		(start 387.13156 -264.010902)
		(mid 386.944362 -264.061045)
		(end 386.757164 -264.010902)
		(width 0.088646)
		(layer "In2.Cu")
		(net "M_F_CPU0_SA_CB<3>")
	)
	(arc
		(start 383.54508 -263.783064)
		(mid 383.371499 -263.711015)
		(end 383.185162 -263.686544)
		(width 0.088646)
		(layer "In2.Cu")
		(net "M_F_CPU0_SA_CB<3>")
	)
	(arc
		(start 387.696964 -264.010902)
		(mid 387.414262 -263.935126)
		(end 387.13156 -264.010902)
		(width 0.088646)
		(layer "In2.Cu")
		(net "M_F_CPU0_SA_CB<3>")
	)
	(arc
		(start 384.31216 -264.010902)
		(mid 384.124962 -264.061045)
		(end 383.937764 -264.010902)
		(width 0.088646)
		(layer "In2.Cu")
		(net "M_F_CPU0_SA_CB<3>")
	)
	(arc
		(start 387.884416 -264.061702)
		(mid 387.787346 -264.048645)
		(end 387.696964 -264.010902)
		(width 0.088646)
		(layer "In2.Cu")
		(net "M_F_CPU0_SA_CB<3>")
	)
	(segment
		(start 431.280316 -278.048974)
		(end 431.514504 -277.814786)
		(width 0.20066)
		(layer "F.Cu")
		(net "M_F_CPU0_SA_CB<2>")
	)
	(segment
		(start 382.715516 -264.500106)
		(end 382.715262 -264.50036)
		(width 0.20066)
		(layer "F.Cu")
		(net "M_F_CPU0_SA_CB<2>")
	)
	(segment
		(start 431.076354 -278.503888)
		(end 431.280316 -278.299926)
		(width 0.20066)
		(layer "F.Cu")
		(net "M_F_CPU0_SA_CB<2>")
	)
	(segment
		(start 431.514504 -277.814786)
		(end 431.898552 -277.814786)
		(width 0.20066)
		(layer "F.Cu")
		(net "M_F_CPU0_SA_CB<2>")
	)
	(segment
		(start 428.07128 -278.498808)
		(end 428.363126 -278.498808)
		(width 0.20066)
		(layer "F.Cu")
		(net "M_F_CPU0_SA_CB<2>")
	)
	(segment
		(start 428.363126 -278.498808)
		(end 428.367952 -278.498808)
		(width 0.101854)
		(layer "F.Cu")
		(net "M_F_CPU0_SA_CB<2>")
	)
	(segment
		(start 427.639226 -278.066754)
		(end 428.07128 -278.498808)
		(width 0.20066)
		(layer "F.Cu")
		(net "M_F_CPU0_SA_CB<2>")
	)
	(segment
		(start 428.367952 -278.498808)
		(end 428.375064 -278.491696)
		(width 0.1016)
		(layer "F.Cu")
		(net "M_F_CPU0_SA_CB<2>")
	)
	(segment
		(start 382.715516 -263.96442)
		(end 382.715516 -264.500106)
		(width 0.20066)
		(layer "F.Cu")
		(net "M_F_CPU0_SA_CB<2>")
	)
	(segment
		(start 428.375064 -278.491696)
		(end 430.382934 -278.491696)
		(width 0.1016)
		(layer "F.Cu")
		(net "M_F_CPU0_SA_CB<2>")
	)
	(segment
		(start 430.382934 -278.491696)
		(end 430.395126 -278.503888)
		(width 0.1016)
		(layer "F.Cu")
		(net "M_F_CPU0_SA_CB<2>")
	)
	(segment
		(start 431.898552 -277.814786)
		(end 432.15052 -278.066754)
		(width 0.20066)
		(layer "F.Cu")
		(net "M_F_CPU0_SA_CB<2>")
	)
	(segment
		(start 424.836082 -278.066754)
		(end 425.940982 -278.066754)
		(width 0.20066)
		(layer "F.Cu")
		(net "M_F_CPU0_SA_CB<2>")
	)
	(segment
		(start 430.395126 -278.503888)
		(end 431.076354 -278.503888)
		(width 0.20066)
		(layer "F.Cu")
		(net "M_F_CPU0_SA_CB<2>")
	)
	(segment
		(start 425.940982 -278.066754)
		(end 427.639226 -278.066754)
		(width 0.20066)
		(layer "F.Cu")
		(net "M_F_CPU0_SA_CB<2>")
	)
	(segment
		(start 432.15052 -278.066754)
		(end 433.484782 -278.066754)
		(width 0.20066)
		(layer "F.Cu")
		(net "M_F_CPU0_SA_CB<2>")
	)
	(segment
		(start 431.280316 -278.299926)
		(end 431.280316 -278.048974)
		(width 0.20066)
		(layer "F.Cu")
		(net "M_F_CPU0_SA_CB<2>")
	)
	(segment
		(start 413.504888 -278.41321)
		(end 413.20593 -278.712168)
		(width 0.18288)
		(layer "In2.Cu")
		(net "M_F_CPU0_SA_CB<2>")
	)
	(segment
		(start 388.103872 -264.748518)
		(end 387.884924 -264.748518)
		(width 0.088646)
		(layer "In2.Cu")
		(net "M_F_CPU0_SA_CB<2>")
	)
	(segment
		(start 387.227064 -264.824718)
		(end 387.212332 -264.816082)
		(width 0.088646)
		(layer "In2.Cu")
		(net "M_F_CPU0_SA_CB<2>")
	)
	(segment
		(start 424.269154 -277.499826)
		(end 422.919906 -277.499826)
		(width 0.18288)
		(layer "In2.Cu")
		(net "M_F_CPU0_SA_CB<2>")
	)
	(segment
		(start 420.652702 -277.642828)
		(end 420.207694 -277.642828)
		(width 0.18288)
		(layer "In2.Cu")
		(net "M_F_CPU0_SA_CB<2>")
	)
	(segment
		(start 419.496494 -277.703026)
		(end 417.562538 -277.703026)
		(width 0.18288)
		(layer "In2.Cu")
		(net "M_F_CPU0_SA_CB<2>")
	)
	(segment
		(start 422.778428 -277.641304)
		(end 420.654226 -277.641304)
		(width 0.18288)
		(layer "In2.Cu")
		(net "M_F_CPU0_SA_CB<2>")
	)
	(segment
		(start 408.765248 -277.516844)
		(end 408.054556 -276.806152)
		(width 0.18288)
		(layer "In2.Cu")
		(net "M_F_CPU0_SA_CB<2>")
	)
	(segment
		(start 415.252916 -278.530812)
		(end 415.135314 -278.41321)
		(width 0.18288)
		(layer "In2.Cu")
		(net "M_F_CPU0_SA_CB<2>")
	)
	(segment
		(start 420.654226 -277.641304)
		(end 420.652702 -277.642828)
		(width 0.18288)
		(layer "In2.Cu")
		(net "M_F_CPU0_SA_CB<2>")
	)
	(segment
		(start 388.840472 -264.622026)
		(end 388.230364 -264.622026)
		(width 0.088646)
		(layer "In2.Cu")
		(net "M_F_CPU0_SA_CB<2>")
	)
	(segment
		(start 384.407664 -264.824718)
		(end 384.392932 -264.816082)
		(width 0.088646)
		(layer "In2.Cu")
		(net "M_F_CPU0_SA_CB<2>")
	)
	(segment
		(start 405.132286 -276.806152)
		(end 402.778214 -274.45208)
		(width 0.18288)
		(layer "In2.Cu")
		(net "M_F_CPU0_SA_CB<2>")
	)
	(segment
		(start 420.207694 -277.642828)
		(end 419.496494 -277.703026)
		(width 0.18288)
		(layer "In2.Cu")
		(net "M_F_CPU0_SA_CB<2>")
	)
	(segment
		(start 395.184122 -267.815568)
		(end 392.352022 -264.983468)
		(width 0.18288)
		(layer "In2.Cu")
		(net "M_F_CPU0_SA_CB<2>")
	)
	(segment
		(start 397.513302 -267.815568)
		(end 395.184122 -267.815568)
		(width 0.18288)
		(layer "In2.Cu")
		(net "M_F_CPU0_SA_CB<2>")
	)
	(segment
		(start 410.024072 -278.473154)
		(end 409.387294 -278.252682)
		(width 0.18288)
		(layer "In2.Cu")
		(net "M_F_CPU0_SA_CB<2>")
	)
	(segment
		(start 422.919906 -277.499826)
		(end 422.778428 -277.641304)
		(width 0.18288)
		(layer "In2.Cu")
		(net "M_F_CPU0_SA_CB<2>")
	)
	(segment
		(start 408.765248 -277.630636)
		(end 408.765248 -277.516844)
		(width 0.18288)
		(layer "In2.Cu")
		(net "M_F_CPU0_SA_CB<2>")
	)
	(segment
		(start 412.682436 -278.712168)
		(end 412.443422 -278.473154)
		(width 0.18288)
		(layer "In2.Cu")
		(net "M_F_CPU0_SA_CB<2>")
	)
	(segment
		(start 417.562538 -277.703026)
		(end 415.56432 -278.530812)
		(width 0.18288)
		(layer "In2.Cu")
		(net "M_F_CPU0_SA_CB<2>")
	)
	(segment
		(start 391.479024 -264.622026)
		(end 388.840472 -264.622026)
		(width 0.18288)
		(layer "In2.Cu")
		(net "M_F_CPU0_SA_CB<2>")
	)
	(segment
		(start 408.054556 -276.806152)
		(end 405.132286 -276.806152)
		(width 0.18288)
		(layer "In2.Cu")
		(net "M_F_CPU0_SA_CB<2>")
	)
	(segment
		(start 392.352022 -264.983468)
		(end 391.479024 -264.622026)
		(width 0.18288)
		(layer "In2.Cu")
		(net "M_F_CPU0_SA_CB<2>")
	)
	(segment
		(start 388.230364 -264.622026)
		(end 388.103872 -264.748518)
		(width 0.088646)
		(layer "In2.Cu")
		(net "M_F_CPU0_SA_CB<2>")
	)
	(segment
		(start 402.778214 -274.45208)
		(end 401.808188 -272.110454)
		(width 0.18288)
		(layer "In2.Cu")
		(net "M_F_CPU0_SA_CB<2>")
	)
	(segment
		(start 401.808188 -272.110454)
		(end 397.513302 -267.815568)
		(width 0.18288)
		(layer "In2.Cu")
		(net "M_F_CPU0_SA_CB<2>")
	)
	(segment
		(start 412.443422 -278.473154)
		(end 410.024072 -278.473154)
		(width 0.18288)
		(layer "In2.Cu")
		(net "M_F_CPU0_SA_CB<2>")
	)
	(segment
		(start 385.347464 -264.824718)
		(end 385.332732 -264.816082)
		(width 0.088646)
		(layer "In2.Cu")
		(net "M_F_CPU0_SA_CB<2>")
	)
	(segment
		(start 386.287264 -264.824718)
		(end 386.272532 -264.816082)
		(width 0.088646)
		(layer "In2.Cu")
		(net "M_F_CPU0_SA_CB<2>")
	)
	(segment
		(start 415.135314 -278.41321)
		(end 413.504888 -278.41321)
		(width 0.18288)
		(layer "In2.Cu")
		(net "M_F_CPU0_SA_CB<2>")
	)
	(segment
		(start 415.56432 -278.530812)
		(end 415.252916 -278.530812)
		(width 0.18288)
		(layer "In2.Cu")
		(net "M_F_CPU0_SA_CB<2>")
	)
	(segment
		(start 424.836082 -278.066754)
		(end 424.269154 -277.499826)
		(width 0.18288)
		(layer "In2.Cu")
		(net "M_F_CPU0_SA_CB<2>")
	)
	(segment
		(start 409.387294 -278.252682)
		(end 408.765248 -277.630636)
		(width 0.18288)
		(layer "In2.Cu")
		(net "M_F_CPU0_SA_CB<2>")
	)
	(segment
		(start 413.20593 -278.712168)
		(end 412.682436 -278.712168)
		(width 0.18288)
		(layer "In2.Cu")
		(net "M_F_CPU0_SA_CB<2>")
	)
	(arc
		(start 387.884924 -264.748518)
		(mid 387.738159 -264.767898)
		(end 387.60146 -264.824718)
		(width 0.088646)
		(layer "In2.Cu")
		(net "M_F_CPU0_SA_CB<2>")
	)
	(arc
		(start 384.392932 -264.816082)
		(mid 384.116457 -264.748762)
		(end 383.84226 -264.824718)
		(width 0.088646)
		(layer "In2.Cu")
		(net "M_F_CPU0_SA_CB<2>")
	)
	(arc
		(start 386.272532 -264.816082)
		(mid 385.996057 -264.748762)
		(end 385.72186 -264.824718)
		(width 0.088646)
		(layer "In2.Cu")
		(net "M_F_CPU0_SA_CB<2>")
	)
	(arc
		(start 385.72186 -264.824718)
		(mid 385.534662 -264.874861)
		(end 385.347464 -264.824718)
		(width 0.088646)
		(layer "In2.Cu")
		(net "M_F_CPU0_SA_CB<2>")
	)
	(arc
		(start 387.212332 -264.816082)
		(mid 386.935857 -264.748762)
		(end 386.66166 -264.824718)
		(width 0.088646)
		(layer "In2.Cu")
		(net "M_F_CPU0_SA_CB<2>")
	)
	(arc
		(start 385.332732 -264.816082)
		(mid 385.056257 -264.748762)
		(end 384.78206 -264.824718)
		(width 0.088646)
		(layer "In2.Cu")
		(net "M_F_CPU0_SA_CB<2>")
	)
	(arc
		(start 386.66166 -264.824718)
		(mid 386.474462 -264.874861)
		(end 386.287264 -264.824718)
		(width 0.088646)
		(layer "In2.Cu")
		(net "M_F_CPU0_SA_CB<2>")
	)
	(arc
		(start 387.60146 -264.824718)
		(mid 387.414262 -264.874861)
		(end 387.227064 -264.824718)
		(width 0.088646)
		(layer "In2.Cu")
		(net "M_F_CPU0_SA_CB<2>")
	)
	(arc
		(start 383.84226 -264.824718)
		(mid 383.655062 -264.874861)
		(end 383.467864 -264.824718)
		(width 0.088646)
		(layer "In2.Cu")
		(net "M_F_CPU0_SA_CB<2>")
	)
	(arc
		(start 383.467864 -264.824718)
		(mid 383.101167 -264.640254)
		(end 382.715262 -264.50036)
		(width 0.088646)
		(layer "In2.Cu")
		(net "M_F_CPU0_SA_CB<2>")
	)
	(arc
		(start 384.78206 -264.824718)
		(mid 384.594862 -264.874861)
		(end 384.407664 -264.824718)
		(width 0.088646)
		(layer "In2.Cu")
		(net "M_F_CPU0_SA_CB<2>")
	)
	(segment
		(start 427.36135 -276.785324)
		(end 426.951394 -276.785324)
		(width 0.20066)
		(layer "F.Cu")
		(net "M_F_CPU0_SA_CB<1>")
	)
	(segment
		(start 424.756326 -276.791674)
		(end 424.73626 -276.791674)
		(width 0.101854)
		(layer "F.Cu")
		(net "M_F_CPU0_SA_CB<1>")
	)
	(segment
		(start 381.305562 -263.150604)
		(end 381.305816 -263.150858)
		(width 0.20066)
		(layer "F.Cu")
		(net "M_F_CPU0_SA_CB<1>")
	)
	(segment
		(start 423.610278 -277.465282)
		(end 423.361612 -277.216616)
		(width 0.20066)
		(layer "F.Cu")
		(net "M_F_CPU0_SA_CB<1>")
	)
	(segment
		(start 427.792896 -277.21687)
		(end 427.36135 -276.785324)
		(width 0.20066)
		(layer "F.Cu")
		(net "M_F_CPU0_SA_CB<1>")
	)
	(segment
		(start 424.273472 -276.909784)
		(end 424.273472 -277.277322)
		(width 0.20066)
		(layer "F.Cu")
		(net "M_F_CPU0_SA_CB<1>")
	)
	(segment
		(start 426.945044 -276.791674)
		(end 424.756326 -276.791674)
		(width 0.1016)
		(layer "F.Cu")
		(net "M_F_CPU0_SA_CB<1>")
	)
	(segment
		(start 421.840914 -277.216616)
		(end 420.736014 -277.216616)
		(width 0.20066)
		(layer "F.Cu")
		(net "M_F_CPU0_SA_CB<1>")
	)
	(segment
		(start 423.361612 -277.216616)
		(end 421.840914 -277.216616)
		(width 0.20066)
		(layer "F.Cu")
		(net "M_F_CPU0_SA_CB<1>")
	)
	(segment
		(start 424.73626 -276.791674)
		(end 424.391582 -276.791674)
		(width 0.20066)
		(layer "F.Cu")
		(net "M_F_CPU0_SA_CB<1>")
	)
	(segment
		(start 381.305816 -263.150858)
		(end 381.305816 -263.686544)
		(width 0.20066)
		(layer "F.Cu")
		(net "M_F_CPU0_SA_CB<1>")
	)
	(segment
		(start 429.38446 -277.21687)
		(end 427.792896 -277.21687)
		(width 0.20066)
		(layer "F.Cu")
		(net "M_F_CPU0_SA_CB<1>")
	)
	(segment
		(start 424.273472 -277.277322)
		(end 424.085512 -277.465282)
		(width 0.20066)
		(layer "F.Cu")
		(net "M_F_CPU0_SA_CB<1>")
	)
	(segment
		(start 429.384714 -277.216616)
		(end 429.38446 -277.21687)
		(width 0.20066)
		(layer "F.Cu")
		(net "M_F_CPU0_SA_CB<1>")
	)
	(segment
		(start 424.391582 -276.791674)
		(end 424.273472 -276.909784)
		(width 0.20066)
		(layer "F.Cu")
		(net "M_F_CPU0_SA_CB<1>")
	)
	(segment
		(start 426.951394 -276.785324)
		(end 426.945044 -276.791674)
		(width 0.1016)
		(layer "F.Cu")
		(net "M_F_CPU0_SA_CB<1>")
	)
	(segment
		(start 424.085512 -277.465282)
		(end 423.610278 -277.465282)
		(width 0.20066)
		(layer "F.Cu")
		(net "M_F_CPU0_SA_CB<1>")
	)
	(segment
		(start 412.245048 -277.943564)
		(end 411.971998 -277.943564)
		(width 0.18288)
		(layer "In2.Cu")
		(net "M_F_CPU0_SA_CB<1>")
	)
	(segment
		(start 383.84226 -264.176002)
		(end 383.842514 -264.175748)
		(width 0.088646)
		(layer "In2.Cu")
		(net "M_F_CPU0_SA_CB<1>")
	)
	(segment
		(start 403.208744 -274.16379)
		(end 402.238972 -271.822672)
		(width 0.18288)
		(layer "In2.Cu")
		(net "M_F_CPU0_SA_CB<1>")
	)
	(segment
		(start 409.556966 -277.677626)
		(end 409.33243 -277.45309)
		(width 0.18288)
		(layer "In2.Cu")
		(net "M_F_CPU0_SA_CB<1>")
	)
	(segment
		(start 420.416228 -276.89683)
		(end 420.416228 -276.743414)
		(width 0.18288)
		(layer "In2.Cu")
		(net "M_F_CPU0_SA_CB<1>")
	)
	(segment
		(start 404.984966 -275.746972)
		(end 404.984966 -275.207476)
		(width 0.18288)
		(layer "In2.Cu")
		(net "M_F_CPU0_SA_CB<1>")
	)
	(segment
		(start 405.178006 -275.940012)
		(end 404.984966 -275.746972)
		(width 0.18288)
		(layer "In2.Cu")
		(net "M_F_CPU0_SA_CB<1>")
	)
	(segment
		(start 405.891746 -275.940012)
		(end 405.178006 -275.940012)
		(width 0.18288)
		(layer "In2.Cu")
		(net "M_F_CPU0_SA_CB<1>")
	)
	(segment
		(start 417.900612 -277.195026)
		(end 417.327588 -276.622002)
		(width 0.18288)
		(layer "In2.Cu")
		(net "M_F_CPU0_SA_CB<1>")
	)
	(segment
		(start 397.723868 -267.307568)
		(end 395.174724 -267.307568)
		(width 0.18288)
		(layer "In2.Cu")
		(net "M_F_CPU0_SA_CB<1>")
	)
	(segment
		(start 416.5727 -277.423626)
		(end 416.3949 -277.601426)
		(width 0.18288)
		(layer "In2.Cu")
		(net "M_F_CPU0_SA_CB<1>")
	)
	(segment
		(start 410.143452 -277.677626)
		(end 409.556966 -277.677626)
		(width 0.18288)
		(layer "In2.Cu")
		(net "M_F_CPU0_SA_CB<1>")
	)
	(segment
		(start 391.669778 -264.251948)
		(end 388.840472 -264.251948)
		(width 0.18288)
		(layer "In2.Cu")
		(net "M_F_CPU0_SA_CB<1>")
	)
	(segment
		(start 407.317194 -276.298152)
		(end 406.249886 -276.298152)
		(width 0.18288)
		(layer "In2.Cu")
		(net "M_F_CPU0_SA_CB<1>")
	)
	(segment
		(start 408.300428 -275.762212)
		(end 407.853134 -275.762212)
		(width 0.18288)
		(layer "In2.Cu")
		(net "M_F_CPU0_SA_CB<1>")
	)
	(segment
		(start 418.859716 -277.195026)
		(end 417.900612 -277.195026)
		(width 0.18288)
		(layer "In2.Cu")
		(net "M_F_CPU0_SA_CB<1>")
	)
	(segment
		(start 402.238972 -271.822672)
		(end 397.723868 -267.307568)
		(width 0.18288)
		(layer "In2.Cu")
		(net "M_F_CPU0_SA_CB<1>")
	)
	(segment
		(start 412.779718 -277.408894)
		(end 412.245048 -277.943564)
		(width 0.18288)
		(layer "In2.Cu")
		(net "M_F_CPU0_SA_CB<1>")
	)
	(segment
		(start 392.437366 -264.57021)
		(end 391.669778 -264.251948)
		(width 0.18288)
		(layer "In2.Cu")
		(net "M_F_CPU0_SA_CB<1>")
	)
	(segment
		(start 383.49809 -264.083292)
		(end 382.263396 -264.083292)
		(width 0.088646)
		(layer "In2.Cu")
		(net "M_F_CPU0_SA_CB<1>")
	)
	(segment
		(start 419.480492 -276.57425)
		(end 418.859716 -277.195026)
		(width 0.18288)
		(layer "In2.Cu")
		(net "M_F_CPU0_SA_CB<1>")
	)
	(segment
		(start 420.736014 -277.216616)
		(end 420.416228 -276.89683)
		(width 0.18288)
		(layer "In2.Cu")
		(net "M_F_CPU0_SA_CB<1>")
	)
	(segment
		(start 407.853134 -275.762212)
		(end 407.317194 -276.298152)
		(width 0.18288)
		(layer "In2.Cu")
		(net "M_F_CPU0_SA_CB<1>")
	)
	(segment
		(start 395.174724 -267.307568)
		(end 392.437366 -264.57021)
		(width 0.18288)
		(layer "In2.Cu")
		(net "M_F_CPU0_SA_CB<1>")
	)
	(segment
		(start 411.971998 -277.943564)
		(end 411.308296 -277.279862)
		(width 0.18288)
		(layer "In2.Cu")
		(net "M_F_CPU0_SA_CB<1>")
	)
	(segment
		(start 404.7617 -274.98421)
		(end 404.029164 -274.98421)
		(width 0.18288)
		(layer "In2.Cu")
		(net "M_F_CPU0_SA_CB<1>")
	)
	(segment
		(start 416.885374 -276.622002)
		(end 416.5727 -276.934676)
		(width 0.18288)
		(layer "In2.Cu")
		(net "M_F_CPU0_SA_CB<1>")
	)
	(segment
		(start 415.224722 -277.601426)
		(end 414.920938 -277.90521)
		(width 0.18288)
		(layer "In2.Cu")
		(net "M_F_CPU0_SA_CB<1>")
	)
	(segment
		(start 420.247064 -276.57425)
		(end 419.480492 -276.57425)
		(width 0.18288)
		(layer "In2.Cu")
		(net "M_F_CPU0_SA_CB<1>")
	)
	(segment
		(start 409.33243 -277.45309)
		(end 408.866594 -276.328378)
		(width 0.18288)
		(layer "In2.Cu")
		(net "M_F_CPU0_SA_CB<1>")
	)
	(segment
		(start 404.029164 -274.98421)
		(end 403.208744 -274.16379)
		(width 0.18288)
		(layer "In2.Cu")
		(net "M_F_CPU0_SA_CB<1>")
	)
	(segment
		(start 420.416228 -276.743414)
		(end 420.247064 -276.57425)
		(width 0.18288)
		(layer "In2.Cu")
		(net "M_F_CPU0_SA_CB<1>")
	)
	(segment
		(start 413.19323 -277.408894)
		(end 412.779718 -277.408894)
		(width 0.18288)
		(layer "In2.Cu")
		(net "M_F_CPU0_SA_CB<1>")
	)
	(segment
		(start 411.308296 -277.279862)
		(end 410.541216 -277.279862)
		(width 0.18288)
		(layer "In2.Cu")
		(net "M_F_CPU0_SA_CB<1>")
	)
	(segment
		(start 410.541216 -277.279862)
		(end 410.143452 -277.677626)
		(width 0.18288)
		(layer "In2.Cu")
		(net "M_F_CPU0_SA_CB<1>")
	)
	(segment
		(start 417.327588 -276.622002)
		(end 416.885374 -276.622002)
		(width 0.18288)
		(layer "In2.Cu")
		(net "M_F_CPU0_SA_CB<1>")
	)
	(segment
		(start 416.5727 -276.934676)
		(end 416.5727 -277.423626)
		(width 0.18288)
		(layer "In2.Cu")
		(net "M_F_CPU0_SA_CB<1>")
	)
	(segment
		(start 404.984966 -275.207476)
		(end 404.7617 -274.98421)
		(width 0.18288)
		(layer "In2.Cu")
		(net "M_F_CPU0_SA_CB<1>")
	)
	(segment
		(start 413.689546 -277.90521)
		(end 413.19323 -277.408894)
		(width 0.18288)
		(layer "In2.Cu")
		(net "M_F_CPU0_SA_CB<1>")
	)
	(segment
		(start 388.840472 -264.251948)
		(end 387.884162 -264.251948)
		(width 0.088646)
		(layer "In2.Cu")
		(net "M_F_CPU0_SA_CB<1>")
	)
	(segment
		(start 408.866594 -276.328378)
		(end 408.300428 -275.762212)
		(width 0.18288)
		(layer "In2.Cu")
		(net "M_F_CPU0_SA_CB<1>")
	)
	(segment
		(start 406.249886 -276.298152)
		(end 405.891746 -275.940012)
		(width 0.18288)
		(layer "In2.Cu")
		(net "M_F_CPU0_SA_CB<1>")
	)
	(segment
		(start 416.3949 -277.601426)
		(end 415.224722 -277.601426)
		(width 0.18288)
		(layer "In2.Cu")
		(net "M_F_CPU0_SA_CB<1>")
	)
	(segment
		(start 414.920938 -277.90521)
		(end 413.689546 -277.90521)
		(width 0.18288)
		(layer "In2.Cu")
		(net "M_F_CPU0_SA_CB<1>")
	)
	(arc
		(start 385.72186 -264.176002)
		(mid 385.534662 -264.125859)
		(end 385.347464 -264.176002)
		(width 0.088646)
		(layer "In2.Cu")
		(net "M_F_CPU0_SA_CB<1>")
	)
	(arc
		(start 385.347464 -264.176002)
		(mid 385.064762 -264.251778)
		(end 384.78206 -264.176002)
		(width 0.088646)
		(layer "In2.Cu")
		(net "M_F_CPU0_SA_CB<1>")
	)
	(arc
		(start 387.227064 -264.176002)
		(mid 386.944362 -264.251778)
		(end 386.66166 -264.176002)
		(width 0.088646)
		(layer "In2.Cu")
		(net "M_F_CPU0_SA_CB<1>")
	)
	(arc
		(start 387.884162 -264.251948)
		(mid 387.859629 -264.25146)
		(end 387.83514 -264.249916)
		(width 0.088646)
		(layer "In2.Cu")
		(net "M_F_CPU0_SA_CB<1>")
	)
	(arc
		(start 387.83514 -264.249916)
		(mid 387.714236 -264.225797)
		(end 387.60146 -264.176002)
		(width 0.088646)
		(layer "In2.Cu")
		(net "M_F_CPU0_SA_CB<1>")
	)
	(arc
		(start 386.287264 -264.176002)
		(mid 386.004562 -264.251778)
		(end 385.72186 -264.176002)
		(width 0.088646)
		(layer "In2.Cu")
		(net "M_F_CPU0_SA_CB<1>")
	)
	(arc
		(start 384.407664 -264.176002)
		(mid 384.124962 -264.251778)
		(end 383.84226 -264.176002)
		(width 0.088646)
		(layer "In2.Cu")
		(net "M_F_CPU0_SA_CB<1>")
	)
	(arc
		(start 382.263396 -264.083292)
		(mid 381.745131 -263.980185)
		(end 381.305816 -263.686544)
		(width 0.088646)
		(layer "In2.Cu")
		(net "M_F_CPU0_SA_CB<1>")
	)
	(arc
		(start 384.78206 -264.176002)
		(mid 384.594862 -264.125859)
		(end 384.407664 -264.176002)
		(width 0.088646)
		(layer "In2.Cu")
		(net "M_F_CPU0_SA_CB<1>")
	)
	(arc
		(start 383.842514 -264.175748)
		(mid 383.676393 -264.10684)
		(end 383.49809 -264.083292)
		(width 0.088646)
		(layer "In2.Cu")
		(net "M_F_CPU0_SA_CB<1>")
	)
	(arc
		(start 387.60146 -264.176002)
		(mid 387.414262 -264.125859)
		(end 387.227064 -264.176002)
		(width 0.088646)
		(layer "In2.Cu")
		(net "M_F_CPU0_SA_CB<1>")
	)
	(arc
		(start 386.66166 -264.176002)
		(mid 386.474462 -264.125859)
		(end 386.287264 -264.176002)
		(width 0.088646)
		(layer "In2.Cu")
		(net "M_F_CPU0_SA_CB<1>")
	)
	(segment
		(start 426.945044 -278.491696)
		(end 424.78325 -278.491696)
		(width 0.1016)
		(layer "F.Cu")
		(net "M_F_CPU0_SA_CB<0>")
	)
	(segment
		(start 423.361612 -278.916638)
		(end 421.840914 -278.916638)
		(width 0.20066)
		(layer "F.Cu")
		(net "M_F_CPU0_SA_CB<0>")
	)
	(segment
		(start 424.73626 -278.491696)
		(end 424.391582 -278.491696)
		(width 0.20066)
		(layer "F.Cu")
		(net "M_F_CPU0_SA_CB<0>")
	)
	(segment
		(start 423.610278 -279.165304)
		(end 423.361612 -278.916638)
		(width 0.20066)
		(layer "F.Cu")
		(net "M_F_CPU0_SA_CB<0>")
	)
	(segment
		(start 381.775716 -264.500106)
		(end 381.775462 -264.50036)
		(width 0.20066)
		(layer "F.Cu")
		(net "M_F_CPU0_SA_CB<0>")
	)
	(segment
		(start 429.384714 -278.916638)
		(end 429.38446 -278.916892)
		(width 0.20066)
		(layer "F.Cu")
		(net "M_F_CPU0_SA_CB<0>")
	)
	(segment
		(start 424.085512 -279.165304)
		(end 423.610278 -279.165304)
		(width 0.20066)
		(layer "F.Cu")
		(net "M_F_CPU0_SA_CB<0>")
	)
	(segment
		(start 424.273472 -278.609806)
		(end 424.273472 -278.977344)
		(width 0.20066)
		(layer "F.Cu")
		(net "M_F_CPU0_SA_CB<0>")
	)
	(segment
		(start 427.36135 -278.485346)
		(end 426.951394 -278.485346)
		(width 0.20066)
		(layer "F.Cu")
		(net "M_F_CPU0_SA_CB<0>")
	)
	(segment
		(start 427.792896 -278.916892)
		(end 427.36135 -278.485346)
		(width 0.20066)
		(layer "F.Cu")
		(net "M_F_CPU0_SA_CB<0>")
	)
	(segment
		(start 381.775716 -263.96442)
		(end 381.775716 -264.500106)
		(width 0.20066)
		(layer "F.Cu")
		(net "M_F_CPU0_SA_CB<0>")
	)
	(segment
		(start 421.840914 -278.916638)
		(end 420.736014 -278.916638)
		(width 0.20066)
		(layer "F.Cu")
		(net "M_F_CPU0_SA_CB<0>")
	)
	(segment
		(start 424.273472 -278.977344)
		(end 424.085512 -279.165304)
		(width 0.20066)
		(layer "F.Cu")
		(net "M_F_CPU0_SA_CB<0>")
	)
	(segment
		(start 429.38446 -278.916892)
		(end 427.792896 -278.916892)
		(width 0.20066)
		(layer "F.Cu")
		(net "M_F_CPU0_SA_CB<0>")
	)
	(segment
		(start 426.951394 -278.485346)
		(end 426.945044 -278.491696)
		(width 0.1016)
		(layer "F.Cu")
		(net "M_F_CPU0_SA_CB<0>")
	)
	(segment
		(start 424.391582 -278.491696)
		(end 424.273472 -278.609806)
		(width 0.20066)
		(layer "F.Cu")
		(net "M_F_CPU0_SA_CB<0>")
	)
	(segment
		(start 424.78325 -278.491696)
		(end 424.73626 -278.491696)
		(width 0.101854)
		(layer "F.Cu")
		(net "M_F_CPU0_SA_CB<0>")
	)
	(segment
		(start 420.736014 -278.916638)
		(end 420.090346 -278.27097)
		(width 0.18288)
		(layer "In2.Cu")
		(net "M_F_CPU0_SA_CB<0>")
	)
	(segment
		(start 416.821366 -280.256742)
		(end 416.429698 -280.256742)
		(width 0.18288)
		(layer "In2.Cu")
		(net "M_F_CPU0_SA_CB<0>")
	)
	(segment
		(start 419.09873 -278.668226)
		(end 418.16782 -278.668226)
		(width 0.18288)
		(layer "In2.Cu")
		(net "M_F_CPU0_SA_CB<0>")
	)
	(segment
		(start 413.72536 -279.508204)
		(end 413.438848 -279.221692)
		(width 0.18288)
		(layer "In2.Cu")
		(net "M_F_CPU0_SA_CB<0>")
	)
	(segment
		(start 408.01417 -277.57628)
		(end 405.663654 -277.57628)
		(width 0.18288)
		(layer "In2.Cu")
		(net "M_F_CPU0_SA_CB<0>")
	)
	(segment
		(start 388.840472 -265.010392)
		(end 388.301992 -265.010392)
		(width 0.088646)
		(layer "In2.Cu")
		(net "M_F_CPU0_SA_CB<0>")
	)
	(segment
		(start 405.663654 -277.57628)
		(end 404.811738 -277.22322)
		(width 0.18288)
		(layer "In2.Cu")
		(net "M_F_CPU0_SA_CB<0>")
	)
	(segment
		(start 414.929066 -279.566116)
		(end 414.929066 -279.942544)
		(width 0.18288)
		(layer "In2.Cu")
		(net "M_F_CPU0_SA_CB<0>")
	)
	(segment
		(start 413.438848 -279.221692)
		(end 412.701994 -279.221692)
		(width 0.18288)
		(layer "In2.Cu")
		(net "M_F_CPU0_SA_CB<0>")
	)
	(segment
		(start 411.769306 -279.367234)
		(end 411.578298 -279.176226)
		(width 0.18288)
		(layer "In2.Cu")
		(net "M_F_CPU0_SA_CB<0>")
	)
	(segment
		(start 386.206746 -264.998454)
		(end 386.192014 -264.989818)
		(width 0.088646)
		(layer "In2.Cu")
		(net "M_F_CPU0_SA_CB<0>")
	)
	(segment
		(start 409.503372 -279.352248)
		(end 408.529282 -278.378158)
		(width 0.18288)
		(layer "In2.Cu")
		(net "M_F_CPU0_SA_CB<0>")
	)
	(segment
		(start 414.929066 -279.942544)
		(end 414.736026 -280.135584)
		(width 0.18288)
		(layer "In2.Cu")
		(net "M_F_CPU0_SA_CB<0>")
	)
	(segment
		(start 417.014406 -280.063702)
		(end 416.821366 -280.256742)
		(width 0.18288)
		(layer "In2.Cu")
		(net "M_F_CPU0_SA_CB<0>")
	)
	(segment
		(start 383.387346 -264.998454)
		(end 383.372614 -264.989818)
		(width 0.088646)
		(layer "In2.Cu")
		(net "M_F_CPU0_SA_CB<0>")
	)
	(segment
		(start 392.22172 -265.341862)
		(end 391.42035 -265.010392)
		(width 0.18288)
		(layer "In2.Cu")
		(net "M_F_CPU0_SA_CB<0>")
	)
	(segment
		(start 418.16782 -278.668226)
		(end 417.014406 -279.82164)
		(width 0.18288)
		(layer "In2.Cu")
		(net "M_F_CPU0_SA_CB<0>")
	)
	(segment
		(start 414.736026 -280.135584)
		(end 413.938466 -280.135584)
		(width 0.18288)
		(layer "In2.Cu")
		(net "M_F_CPU0_SA_CB<0>")
	)
	(segment
		(start 419.495986 -278.27097)
		(end 419.09873 -278.668226)
		(width 0.18288)
		(layer "In2.Cu")
		(net "M_F_CPU0_SA_CB<0>")
	)
	(segment
		(start 413.72536 -279.922478)
		(end 413.72536 -279.508204)
		(width 0.18288)
		(layer "In2.Cu")
		(net "M_F_CPU0_SA_CB<0>")
	)
	(segment
		(start 382.447546 -264.998454)
		(end 382.432814 -264.989818)
		(width 0.088646)
		(layer "In2.Cu")
		(net "M_F_CPU0_SA_CB<0>")
	)
	(segment
		(start 397.318738 -268.33957)
		(end 395.219428 -268.33957)
		(width 0.18288)
		(layer "In2.Cu")
		(net "M_F_CPU0_SA_CB<0>")
	)
	(segment
		(start 412.556452 -279.367234)
		(end 411.769306 -279.367234)
		(width 0.18288)
		(layer "In2.Cu")
		(net "M_F_CPU0_SA_CB<0>")
	)
	(segment
		(start 404.811738 -277.22322)
		(end 402.360638 -274.77212)
		(width 0.18288)
		(layer "In2.Cu")
		(net "M_F_CPU0_SA_CB<0>")
	)
	(segment
		(start 417.014406 -279.82164)
		(end 417.014406 -280.063702)
		(width 0.18288)
		(layer "In2.Cu")
		(net "M_F_CPU0_SA_CB<0>")
	)
	(segment
		(start 412.701994 -279.221692)
		(end 412.556452 -279.367234)
		(width 0.18288)
		(layer "In2.Cu")
		(net "M_F_CPU0_SA_CB<0>")
	)
	(segment
		(start 388.230364 -264.938764)
		(end 387.884924 -264.938764)
		(width 0.088646)
		(layer "In2.Cu")
		(net "M_F_CPU0_SA_CB<0>")
	)
	(segment
		(start 420.090346 -278.27097)
		(end 419.495986 -278.27097)
		(width 0.18288)
		(layer "In2.Cu")
		(net "M_F_CPU0_SA_CB<0>")
	)
	(segment
		(start 415.285682 -279.2095)
		(end 414.929066 -279.566116)
		(width 0.18288)
		(layer "In2.Cu")
		(net "M_F_CPU0_SA_CB<0>")
	)
	(segment
		(start 388.301992 -265.010392)
		(end 388.230364 -264.938764)
		(width 0.088646)
		(layer "In2.Cu")
		(net "M_F_CPU0_SA_CB<0>")
	)
	(segment
		(start 416.257232 -279.506172)
		(end 415.96056 -279.2095)
		(width 0.18288)
		(layer "In2.Cu")
		(net "M_F_CPU0_SA_CB<0>")
	)
	(segment
		(start 416.257232 -280.084276)
		(end 416.257232 -279.506172)
		(width 0.18288)
		(layer "In2.Cu")
		(net "M_F_CPU0_SA_CB<0>")
	)
	(segment
		(start 387.146546 -264.998454)
		(end 387.131814 -264.989818)
		(width 0.088646)
		(layer "In2.Cu")
		(net "M_F_CPU0_SA_CB<0>")
	)
	(segment
		(start 411.578298 -279.176226)
		(end 410.111194 -279.176226)
		(width 0.18288)
		(layer "In2.Cu")
		(net "M_F_CPU0_SA_CB<0>")
	)
	(segment
		(start 415.96056 -279.2095)
		(end 415.285682 -279.2095)
		(width 0.18288)
		(layer "In2.Cu")
		(net "M_F_CPU0_SA_CB<0>")
	)
	(segment
		(start 416.429698 -280.256742)
		(end 416.257232 -280.084276)
		(width 0.18288)
		(layer "In2.Cu")
		(net "M_F_CPU0_SA_CB<0>")
	)
	(segment
		(start 409.935172 -279.352248)
		(end 409.503372 -279.352248)
		(width 0.18288)
		(layer "In2.Cu")
		(net "M_F_CPU0_SA_CB<0>")
	)
	(segment
		(start 382.432814 -264.989818)
		(end 382.426718 -264.986262)
		(width 0.088646)
		(layer "In2.Cu")
		(net "M_F_CPU0_SA_CB<0>")
	)
	(segment
		(start 413.938466 -280.135584)
		(end 413.72536 -279.922478)
		(width 0.18288)
		(layer "In2.Cu")
		(net "M_F_CPU0_SA_CB<0>")
	)
	(segment
		(start 401.37715 -272.397982)
		(end 397.318738 -268.33957)
		(width 0.18288)
		(layer "In2.Cu")
		(net "M_F_CPU0_SA_CB<0>")
	)
	(segment
		(start 408.326336 -277.888446)
		(end 408.01417 -277.57628)
		(width 0.18288)
		(layer "In2.Cu")
		(net "M_F_CPU0_SA_CB<0>")
	)
	(segment
		(start 391.42035 -265.010392)
		(end 388.840472 -265.010392)
		(width 0.18288)
		(layer "In2.Cu")
		(net "M_F_CPU0_SA_CB<0>")
	)
	(segment
		(start 410.111194 -279.176226)
		(end 409.935172 -279.352248)
		(width 0.18288)
		(layer "In2.Cu")
		(net "M_F_CPU0_SA_CB<0>")
	)
	(segment
		(start 384.327146 -264.998454)
		(end 384.312414 -264.989818)
		(width 0.088646)
		(layer "In2.Cu")
		(net "M_F_CPU0_SA_CB<0>")
	)
	(segment
		(start 395.219428 -268.33957)
		(end 392.22172 -265.341862)
		(width 0.18288)
		(layer "In2.Cu")
		(net "M_F_CPU0_SA_CB<0>")
	)
	(segment
		(start 408.529282 -278.378158)
		(end 408.326336 -277.888446)
		(width 0.18288)
		(layer "In2.Cu")
		(net "M_F_CPU0_SA_CB<0>")
	)
	(segment
		(start 402.360638 -274.77212)
		(end 401.37715 -272.397982)
		(width 0.18288)
		(layer "In2.Cu")
		(net "M_F_CPU0_SA_CB<0>")
	)
	(segment
		(start 385.266946 -264.998454)
		(end 385.252214 -264.989818)
		(width 0.088646)
		(layer "In2.Cu")
		(net "M_F_CPU0_SA_CB<0>")
	)
	(arc
		(start 384.877818 -264.989818)
		(mid 384.603619 -265.065653)
		(end 384.327146 -264.998454)
		(width 0.088646)
		(layer "In2.Cu")
		(net "M_F_CPU0_SA_CB<0>")
	)
	(arc
		(start 386.192014 -264.989818)
		(mid 386.004816 -264.939675)
		(end 385.817618 -264.989818)
		(width 0.088646)
		(layer "In2.Cu")
		(net "M_F_CPU0_SA_CB<0>")
	)
	(arc
		(start 387.131814 -264.989818)
		(mid 386.944616 -264.939675)
		(end 386.757418 -264.989818)
		(width 0.088646)
		(layer "In2.Cu")
		(net "M_F_CPU0_SA_CB<0>")
	)
	(arc
		(start 383.938018 -264.989818)
		(mid 383.663819 -265.065653)
		(end 383.387346 -264.998454)
		(width 0.088646)
		(layer "In2.Cu")
		(net "M_F_CPU0_SA_CB<0>")
	)
	(arc
		(start 385.252214 -264.989818)
		(mid 385.065016 -264.939675)
		(end 384.877818 -264.989818)
		(width 0.088646)
		(layer "In2.Cu")
		(net "M_F_CPU0_SA_CB<0>")
	)
	(arc
		(start 382.426718 -264.986262)
		(mid 382.087354 -264.761721)
		(end 381.775462 -264.50036)
		(width 0.088646)
		(layer "In2.Cu")
		(net "M_F_CPU0_SA_CB<0>")
	)
	(arc
		(start 386.757418 -264.989818)
		(mid 386.483219 -265.065653)
		(end 386.206746 -264.998454)
		(width 0.088646)
		(layer "In2.Cu")
		(net "M_F_CPU0_SA_CB<0>")
	)
	(arc
		(start 387.884924 -264.938764)
		(mid 387.787707 -264.95192)
		(end 387.697218 -264.989818)
		(width 0.088646)
		(layer "In2.Cu")
		(net "M_F_CPU0_SA_CB<0>")
	)
	(arc
		(start 383.372614 -264.989818)
		(mid 383.185416 -264.939675)
		(end 382.998218 -264.989818)
		(width 0.088646)
		(layer "In2.Cu")
		(net "M_F_CPU0_SA_CB<0>")
	)
	(arc
		(start 387.697218 -264.989818)
		(mid 387.423019 -265.065653)
		(end 387.146546 -264.998454)
		(width 0.088646)
		(layer "In2.Cu")
		(net "M_F_CPU0_SA_CB<0>")
	)
	(arc
		(start 382.998218 -264.989818)
		(mid 382.724019 -265.065653)
		(end 382.447546 -264.998454)
		(width 0.088646)
		(layer "In2.Cu")
		(net "M_F_CPU0_SA_CB<0>")
	)
	(arc
		(start 384.312414 -264.989818)
		(mid 384.125216 -264.939675)
		(end 383.938018 -264.989818)
		(width 0.088646)
		(layer "In2.Cu")
		(net "M_F_CPU0_SA_CB<0>")
	)
	(arc
		(start 385.817618 -264.989818)
		(mid 385.543419 -265.065653)
		(end 385.266946 -264.998454)
		(width 0.088646)
		(layer "In2.Cu")
		(net "M_F_CPU0_SA_CB<0>")
	)
	(segment
		(start 379.425962 -256.639314)
		(end 379.425962 -257.175)
		(width 0.20066)
		(layer "F.Cu")
		(net "M_F_CPU0_SA_CA<6>")
	)
	(segment
		(start 429.38446 -261.066534)
		(end 429.384714 -261.066788)
		(width 0.20066)
		(layer "F.Cu")
		(net "M_F_CPU0_SA_CA<6>")
	)
	(segment
		(start 427.805088 -261.066534)
		(end 429.38446 -261.066534)
		(width 0.20066)
		(layer "F.Cu")
		(net "M_F_CPU0_SA_CA<6>")
	)
	(segment
		(start 424.766486 -261.49173)
		(end 426.938948 -261.49173)
		(width 0.1016)
		(layer "F.Cu")
		(net "M_F_CPU0_SA_CA<6>")
	)
	(segment
		(start 422.906444 -261.066788)
		(end 423.400728 -260.572504)
		(width 0.20066)
		(layer "F.Cu")
		(net "M_F_CPU0_SA_CA<6>")
	)
	(segment
		(start 379.425962 -257.175)
		(end 379.426216 -257.175254)
		(width 0.20066)
		(layer "F.Cu")
		(net "M_F_CPU0_SA_CA<6>")
	)
	(segment
		(start 423.726102 -260.572504)
		(end 424.645328 -261.49173)
		(width 0.20066)
		(layer "F.Cu")
		(net "M_F_CPU0_SA_CA<6>")
	)
	(segment
		(start 421.840914 -261.066788)
		(end 422.906444 -261.066788)
		(width 0.20066)
		(layer "F.Cu")
		(net "M_F_CPU0_SA_CA<6>")
	)
	(segment
		(start 427.367446 -261.504176)
		(end 427.805088 -261.066534)
		(width 0.20066)
		(layer "F.Cu")
		(net "M_F_CPU0_SA_CA<6>")
	)
	(segment
		(start 424.645328 -261.49173)
		(end 424.75277 -261.49173)
		(width 0.20066)
		(layer "F.Cu")
		(net "M_F_CPU0_SA_CA<6>")
	)
	(segment
		(start 426.938948 -261.49173)
		(end 426.951394 -261.504176)
		(width 0.1016)
		(layer "F.Cu")
		(net "M_F_CPU0_SA_CA<6>")
	)
	(segment
		(start 426.951394 -261.504176)
		(end 427.367446 -261.504176)
		(width 0.20066)
		(layer "F.Cu")
		(net "M_F_CPU0_SA_CA<6>")
	)
	(segment
		(start 424.75277 -261.49173)
		(end 424.766486 -261.49173)
		(width 0.101854)
		(layer "F.Cu")
		(net "M_F_CPU0_SA_CA<6>")
	)
	(segment
		(start 423.400728 -260.572504)
		(end 423.726102 -260.572504)
		(width 0.20066)
		(layer "F.Cu")
		(net "M_F_CPU0_SA_CA<6>")
	)
	(segment
		(start 420.659814 -261.066788)
		(end 421.840914 -261.066788)
		(width 0.20066)
		(layer "F.Cu")
		(net "M_F_CPU0_SA_CA<6>")
	)
	(segment
		(start 419.887908 -258.979416)
		(end 419.249352 -258.979416)
		(width 0.18288)
		(layer "In2.Cu")
		(net "M_F_CPU0_SA_CA<6>")
	)
	(segment
		(start 385.266946 -255.231646)
		(end 385.252214 -255.22301)
		(width 0.088646)
		(layer "In2.Cu")
		(net "M_F_CPU0_SA_CA<6>")
	)
	(segment
		(start 420.659814 -261.066788)
		(end 420.659814 -260.793484)
		(width 0.18288)
		(layer "In2.Cu")
		(net "M_F_CPU0_SA_CA<6>")
	)
	(segment
		(start 381.588264 -256.03708)
		(end 381.579374 -256.04216)
		(width 0.088646)
		(layer "In2.Cu")
		(net "M_F_CPU0_SA_CA<6>")
	)
	(segment
		(start 381.400812 -256.361438)
		(end 381.400812 -256.376932)
		(width 0.088646)
		(layer "In2.Cu")
		(net "M_F_CPU0_SA_CA<6>")
	)
	(segment
		(start 402.133054 -255.740916)
		(end 401.807426 -256.066544)
		(width 0.18288)
		(layer "In2.Cu")
		(net "M_F_CPU0_SA_CA<6>")
	)
	(segment
		(start 420.080948 -260.214618)
		(end 420.080948 -259.172456)
		(width 0.18288)
		(layer "In2.Cu")
		(net "M_F_CPU0_SA_CA<6>")
	)
	(segment
		(start 419.249352 -258.979416)
		(end 418.362638 -258.092702)
		(width 0.18288)
		(layer "In2.Cu")
		(net "M_F_CPU0_SA_CA<6>")
	)
	(segment
		(start 401.103338 -255.740916)
		(end 400.724878 -255.740916)
		(width 0.18288)
		(layer "In2.Cu")
		(net "M_F_CPU0_SA_CA<6>")
	)
	(segment
		(start 386.345684 -255.17221)
		(end 386.004816 -255.17221)
		(width 0.088646)
		(layer "In2.Cu")
		(net "M_F_CPU0_SA_CA<6>")
	)
	(segment
		(start 417.059618 -257.932936)
		(end 416.863022 -258.129532)
		(width 0.18288)
		(layer "In2.Cu")
		(net "M_F_CPU0_SA_CA<6>")
	)
	(segment
		(start 387.97357 -255.300226)
		(end 386.474208 -255.300226)
		(width 0.088646)
		(layer "In2.Cu")
		(net "M_F_CPU0_SA_CA<6>")
	)
	(segment
		(start 382.058418 -255.223264)
		(end 382.049528 -255.228344)
		(width 0.088646)
		(layer "In2.Cu")
		(net "M_F_CPU0_SA_CA<6>")
	)
	(segment
		(start 380.178564 -256.850896)
		(end 380.163832 -256.859532)
		(width 0.088646)
		(layer "In2.Cu")
		(net "M_F_CPU0_SA_CA<6>")
	)
	(segment
		(start 396.232634 -255.740916)
		(end 395.656054 -255.979676)
		(width 0.18288)
		(layer "In2.Cu")
		(net "M_F_CPU0_SA_CA<6>")
	)
	(segment
		(start 397.204438 -256.066544)
		(end 396.87881 -255.740916)
		(width 0.18288)
		(layer "In2.Cu")
		(net "M_F_CPU0_SA_CA<6>")
	)
	(segment
		(start 398.991074 -256.066544)
		(end 398.612614 -256.066544)
		(width 0.18288)
		(layer "In2.Cu")
		(net "M_F_CPU0_SA_CA<6>")
	)
	(segment
		(start 407.404062 -257.578352)
		(end 402.96846 -255.740916)
		(width 0.18288)
		(layer "In2.Cu")
		(net "M_F_CPU0_SA_CA<6>")
	)
	(segment
		(start 388.137908 -255.464564)
		(end 387.97357 -255.300226)
		(width 0.088646)
		(layer "In2.Cu")
		(net "M_F_CPU0_SA_CA<6>")
	)
	(segment
		(start 400.39925 -256.066544)
		(end 400.02079 -256.066544)
		(width 0.18288)
		(layer "In2.Cu")
		(net "M_F_CPU0_SA_CA<6>")
	)
	(segment
		(start 398.286986 -255.740916)
		(end 397.908526 -255.740916)
		(width 0.18288)
		(layer "In2.Cu")
		(net "M_F_CPU0_SA_CA<6>")
	)
	(segment
		(start 382.443228 -255.22936)
		(end 382.432814 -255.223264)
		(width 0.088646)
		(layer "In2.Cu")
		(net "M_F_CPU0_SA_CA<6>")
	)
	(segment
		(start 397.908526 -255.740916)
		(end 397.582898 -256.066544)
		(width 0.18288)
		(layer "In2.Cu")
		(net "M_F_CPU0_SA_CA<6>")
	)
	(segment
		(start 399.695162 -255.740916)
		(end 399.316702 -255.740916)
		(width 0.18288)
		(layer "In2.Cu")
		(net "M_F_CPU0_SA_CA<6>")
	)
	(segment
		(start 417.558982 -257.932936)
		(end 417.059618 -257.932936)
		(width 0.18288)
		(layer "In2.Cu")
		(net "M_F_CPU0_SA_CA<6>")
	)
	(segment
		(start 400.724878 -255.740916)
		(end 400.39925 -256.066544)
		(width 0.18288)
		(layer "In2.Cu")
		(net "M_F_CPU0_SA_CA<6>")
	)
	(segment
		(start 416.863022 -258.129532)
		(end 416.456622 -258.129532)
		(width 0.18288)
		(layer "In2.Cu")
		(net "M_F_CPU0_SA_CA<6>")
	)
	(segment
		(start 395.656054 -255.979676)
		(end 391.929112 -255.979676)
		(width 0.18288)
		(layer "In2.Cu")
		(net "M_F_CPU0_SA_CA<6>")
	)
	(segment
		(start 415.629598 -257.578352)
		(end 407.404062 -257.578352)
		(width 0.18288)
		(layer "In2.Cu")
		(net "M_F_CPU0_SA_CA<6>")
	)
	(segment
		(start 401.807426 -256.066544)
		(end 401.428966 -256.066544)
		(width 0.18288)
		(layer "In2.Cu")
		(net "M_F_CPU0_SA_CA<6>")
	)
	(segment
		(start 388.459218 -255.464564)
		(end 388.137908 -255.464564)
		(width 0.088646)
		(layer "In2.Cu")
		(net "M_F_CPU0_SA_CA<6>")
	)
	(segment
		(start 418.362638 -258.092702)
		(end 417.558982 -257.932936)
		(width 0.18288)
		(layer "In2.Cu")
		(net "M_F_CPU0_SA_CA<6>")
	)
	(segment
		(start 379.67158 -256.88036)
		(end 379.582426 -256.904236)
		(width 0.088646)
		(layer "In2.Cu")
		(net "M_F_CPU0_SA_CA<6>")
	)
	(segment
		(start 416.456622 -258.129532)
		(end 416.100768 -257.773678)
		(width 0.18288)
		(layer "In2.Cu")
		(net "M_F_CPU0_SA_CA<6>")
	)
	(segment
		(start 391.929112 -255.979676)
		(end 389.33882 -255.464564)
		(width 0.18288)
		(layer "In2.Cu")
		(net "M_F_CPU0_SA_CA<6>")
	)
	(segment
		(start 379.582426 -256.904236)
		(end 379.426216 -257.175254)
		(width 0.088646)
		(layer "In2.Cu")
		(net "M_F_CPU0_SA_CA<6>")
	)
	(segment
		(start 399.316702 -255.740916)
		(end 398.991074 -256.066544)
		(width 0.18288)
		(layer "In2.Cu")
		(net "M_F_CPU0_SA_CA<6>")
	)
	(segment
		(start 384.877818 -255.22301)
		(end 384.877564 -255.223264)
		(width 0.088646)
		(layer "In2.Cu")
		(net "M_F_CPU0_SA_CA<6>")
	)
	(segment
		(start 416.100768 -257.773678)
		(end 415.629598 -257.578352)
		(width 0.18288)
		(layer "In2.Cu")
		(net "M_F_CPU0_SA_CA<6>")
	)
	(segment
		(start 420.080948 -259.172456)
		(end 419.887908 -258.979416)
		(width 0.18288)
		(layer "In2.Cu")
		(net "M_F_CPU0_SA_CA<6>")
	)
	(segment
		(start 389.33882 -255.464564)
		(end 388.459218 -255.464564)
		(width 0.18288)
		(layer "In2.Cu")
		(net "M_F_CPU0_SA_CA<6>")
	)
	(segment
		(start 397.582898 -256.066544)
		(end 397.204438 -256.066544)
		(width 0.18288)
		(layer "In2.Cu")
		(net "M_F_CPU0_SA_CA<6>")
	)
	(segment
		(start 402.96846 -255.740916)
		(end 402.133054 -255.740916)
		(width 0.18288)
		(layer "In2.Cu")
		(net "M_F_CPU0_SA_CA<6>")
	)
	(segment
		(start 380.563374 -256.856992)
		(end 380.55296 -256.850896)
		(width 0.088646)
		(layer "In2.Cu")
		(net "M_F_CPU0_SA_CA<6>")
	)
	(segment
		(start 381.600456 -256.029968)
		(end 381.588264 -256.03708)
		(width 0.088646)
		(layer "In2.Cu")
		(net "M_F_CPU0_SA_CA<6>")
	)
	(segment
		(start 386.4737 -255.300226)
		(end 386.345684 -255.17221)
		(width 0.088646)
		(layer "In2.Cu")
		(net "M_F_CPU0_SA_CA<6>")
	)
	(segment
		(start 420.659814 -260.793484)
		(end 420.080948 -260.214618)
		(width 0.18288)
		(layer "In2.Cu")
		(net "M_F_CPU0_SA_CA<6>")
	)
	(segment
		(start 398.612614 -256.066544)
		(end 398.286986 -255.740916)
		(width 0.18288)
		(layer "In2.Cu")
		(net "M_F_CPU0_SA_CA<6>")
	)
	(segment
		(start 400.02079 -256.066544)
		(end 399.695162 -255.740916)
		(width 0.18288)
		(layer "In2.Cu")
		(net "M_F_CPU0_SA_CA<6>")
	)
	(segment
		(start 396.87881 -255.740916)
		(end 396.232634 -255.740916)
		(width 0.18288)
		(layer "In2.Cu")
		(net "M_F_CPU0_SA_CA<6>")
	)
	(segment
		(start 401.428966 -256.066544)
		(end 401.103338 -255.740916)
		(width 0.18288)
		(layer "In2.Cu")
		(net "M_F_CPU0_SA_CA<6>")
	)
	(arc
		(start 382.997964 -255.223264)
		(mid 382.721405 -255.298973)
		(end 382.443228 -255.22936)
		(width 0.088646)
		(layer "In2.Cu")
		(net "M_F_CPU0_SA_CA<6>")
	)
	(arc
		(start 380.55296 -256.850896)
		(mid 380.365762 -256.800753)
		(end 380.178564 -256.850896)
		(width 0.088646)
		(layer "In2.Cu")
		(net "M_F_CPU0_SA_CA<6>")
	)
	(arc
		(start 383.37236 -255.223264)
		(mid 383.185162 -255.173121)
		(end 382.997964 -255.223264)
		(width 0.088646)
		(layer "In2.Cu")
		(net "M_F_CPU0_SA_CA<6>")
	)
	(arc
		(start 381.118618 -256.850896)
		(mid 380.841805 -256.926766)
		(end 380.563374 -256.856992)
		(width 0.088646)
		(layer "In2.Cu")
		(net "M_F_CPU0_SA_CA<6>")
	)
	(arc
		(start 381.870966 -255.547622)
		(mid 381.798731 -255.824146)
		(end 381.600456 -256.029968)
		(width 0.088646)
		(layer "In2.Cu")
		(net "M_F_CPU0_SA_CA<6>")
	)
	(arc
		(start 382.432814 -255.223264)
		(mid 382.245616 -255.173121)
		(end 382.058418 -255.223264)
		(width 0.088646)
		(layer "In2.Cu")
		(net "M_F_CPU0_SA_CA<6>")
	)
	(arc
		(start 386.474208 -255.300226)
		(mid 386.473954 -255.300226)
		(end 386.4737 -255.300226)
		(width 0.088646)
		(layer "In2.Cu")
		(net "M_F_CPU0_SA_CA<6>")
	)
	(arc
		(start 382.049528 -255.228344)
		(mid 381.918614 -255.364704)
		(end 381.870966 -255.547622)
		(width 0.088646)
		(layer "In2.Cu")
		(net "M_F_CPU0_SA_CA<6>")
	)
	(arc
		(start 381.579374 -256.04216)
		(mid 381.44846 -256.17852)
		(end 381.400812 -256.361438)
		(width 0.088646)
		(layer "In2.Cu")
		(net "M_F_CPU0_SA_CA<6>")
	)
	(arc
		(start 380.163832 -256.859532)
		(mid 379.920088 -256.926411)
		(end 379.67158 -256.88036)
		(width 0.088646)
		(layer "In2.Cu")
		(net "M_F_CPU0_SA_CA<6>")
	)
	(arc
		(start 381.400812 -256.376932)
		(mid 381.321442 -256.650666)
		(end 381.118618 -256.850896)
		(width 0.088646)
		(layer "In2.Cu")
		(net "M_F_CPU0_SA_CA<6>")
	)
	(arc
		(start 385.817618 -255.22301)
		(mid 385.543419 -255.298845)
		(end 385.266946 -255.231646)
		(width 0.088646)
		(layer "In2.Cu")
		(net "M_F_CPU0_SA_CA<6>")
	)
	(arc
		(start 386.004816 -255.17221)
		(mid 385.907877 -255.1853)
		(end 385.817618 -255.22301)
		(width 0.088646)
		(layer "In2.Cu")
		(net "M_F_CPU0_SA_CA<6>")
	)
	(arc
		(start 383.937764 -255.223264)
		(mid 383.655062 -255.299006)
		(end 383.37236 -255.223264)
		(width 0.088646)
		(layer "In2.Cu")
		(net "M_F_CPU0_SA_CA<6>")
	)
	(arc
		(start 384.877564 -255.223264)
		(mid 384.594862 -255.299006)
		(end 384.31216 -255.223264)
		(width 0.088646)
		(layer "In2.Cu")
		(net "M_F_CPU0_SA_CA<6>")
	)
	(arc
		(start 385.252214 -255.22301)
		(mid 385.065016 -255.172867)
		(end 384.877818 -255.22301)
		(width 0.088646)
		(layer "In2.Cu")
		(net "M_F_CPU0_SA_CA<6>")
	)
	(arc
		(start 384.31216 -255.223264)
		(mid 384.124962 -255.173121)
		(end 383.937764 -255.223264)
		(width 0.088646)
		(layer "In2.Cu")
		(net "M_F_CPU0_SA_CA<6>")
	)
	(segment
		(start 428.012352 -262.352282)
		(end 428.363126 -262.352282)
		(width 0.20066)
		(layer "F.Cu")
		(net "M_F_CPU0_SA_CA<5>")
	)
	(segment
		(start 428.363126 -262.352282)
		(end 428.367952 -262.352282)
		(width 0.101854)
		(layer "F.Cu")
		(net "M_F_CPU0_SA_CA<5>")
	)
	(segment
		(start 382.715516 -255.825498)
		(end 382.715516 -256.361184)
		(width 0.20066)
		(layer "F.Cu")
		(net "M_F_CPU0_SA_CA<5>")
	)
	(segment
		(start 424.836082 -261.916672)
		(end 425.940982 -261.916672)
		(width 0.20066)
		(layer "F.Cu")
		(net "M_F_CPU0_SA_CA<5>")
	)
	(segment
		(start 425.940982 -261.916672)
		(end 427.576742 -261.916672)
		(width 0.20066)
		(layer "F.Cu")
		(net "M_F_CPU0_SA_CA<5>")
	)
	(segment
		(start 430.38776 -262.341614)
		(end 430.395126 -262.34898)
		(width 0.1016)
		(layer "F.Cu")
		(net "M_F_CPU0_SA_CA<5>")
	)
	(segment
		(start 428.37862 -262.341614)
		(end 430.38776 -262.341614)
		(width 0.1016)
		(layer "F.Cu")
		(net "M_F_CPU0_SA_CA<5>")
	)
	(segment
		(start 431.534062 -261.48411)
		(end 431.937668 -261.48411)
		(width 0.20066)
		(layer "F.Cu")
		(net "M_F_CPU0_SA_CA<5>")
	)
	(segment
		(start 432.37023 -261.916672)
		(end 433.484782 -261.916672)
		(width 0.20066)
		(layer "F.Cu")
		(net "M_F_CPU0_SA_CA<5>")
	)
	(segment
		(start 427.576742 -261.916672)
		(end 428.012352 -262.352282)
		(width 0.20066)
		(layer "F.Cu")
		(net "M_F_CPU0_SA_CA<5>")
	)
	(segment
		(start 431.937668 -261.48411)
		(end 432.37023 -261.916672)
		(width 0.20066)
		(layer "F.Cu")
		(net "M_F_CPU0_SA_CA<5>")
	)
	(segment
		(start 430.395126 -262.34898)
		(end 430.669192 -262.34898)
		(width 0.20066)
		(layer "F.Cu")
		(net "M_F_CPU0_SA_CA<5>")
	)
	(segment
		(start 428.367952 -262.352282)
		(end 428.37862 -262.341614)
		(width 0.1016)
		(layer "F.Cu")
		(net "M_F_CPU0_SA_CA<5>")
	)
	(segment
		(start 430.669192 -262.34898)
		(end 431.534062 -261.48411)
		(width 0.20066)
		(layer "F.Cu")
		(net "M_F_CPU0_SA_CA<5>")
	)
	(segment
		(start 382.715516 -256.361184)
		(end 382.715262 -256.361438)
		(width 0.20066)
		(layer "F.Cu")
		(net "M_F_CPU0_SA_CA<5>")
	)
	(segment
		(start 387.46049 -255.79451)
		(end 386.622798 -255.79451)
		(width 0.088646)
		(layer "In2.Cu")
		(net "M_F_CPU0_SA_CA<5>")
	)
	(segment
		(start 420.33571 -261.491222)
		(end 420.017194 -261.172706)
		(width 0.18288)
		(layer "In2.Cu")
		(net "M_F_CPU0_SA_CA<5>")
	)
	(segment
		(start 387.900418 -255.948688)
		(end 387.614668 -255.948688)
		(width 0.088646)
		(layer "In2.Cu")
		(net "M_F_CPU0_SA_CA<5>")
	)
	(segment
		(start 417.245038 -259.18287)
		(end 416.763708 -258.70154)
		(width 0.18288)
		(layer "In2.Cu")
		(net "M_F_CPU0_SA_CA<5>")
	)
	(segment
		(start 420.017194 -260.888226)
		(end 419.748716 -260.619748)
		(width 0.18288)
		(layer "In2.Cu")
		(net "M_F_CPU0_SA_CA<5>")
	)
	(segment
		(start 383.344166 -255.888236)
		(end 382.715262 -256.361438)
		(width 0.088646)
		(layer "In2.Cu")
		(net "M_F_CPU0_SA_CA<5>")
	)
	(segment
		(start 424.025568 -260.641084)
		(end 423.415714 -261.250938)
		(width 0.18288)
		(layer "In2.Cu")
		(net "M_F_CPU0_SA_CA<5>")
	)
	(segment
		(start 426.283374 -261.44982)
		(end 426.443394 -261.2898)
		(width 0.18288)
		(layer "In2.Cu")
		(net "M_F_CPU0_SA_CA<5>")
	)
	(segment
		(start 415.501074 -258.088384)
		(end 407.262584 -258.088384)
		(width 0.18288)
		(layer "In2.Cu")
		(net "M_F_CPU0_SA_CA<5>")
	)
	(segment
		(start 403.632924 -256.585212)
		(end 396.050516 -256.585212)
		(width 0.18288)
		(layer "In2.Cu")
		(net "M_F_CPU0_SA_CA<5>")
	)
	(segment
		(start 422.880282 -261.250938)
		(end 422.639998 -261.491222)
		(width 0.18288)
		(layer "In2.Cu")
		(net "M_F_CPU0_SA_CA<5>")
	)
	(segment
		(start 386.624322 -255.796034)
		(end 386.474462 -255.796034)
		(width 0.088646)
		(layer "In2.Cu")
		(net "M_F_CPU0_SA_CA<5>")
	)
	(segment
		(start 426.443394 -260.801104)
		(end 426.283374 -260.641084)
		(width 0.18288)
		(layer "In2.Cu")
		(net "M_F_CPU0_SA_CA<5>")
	)
	(segment
		(start 426.443394 -261.2898)
		(end 426.443394 -260.801104)
		(width 0.18288)
		(layer "In2.Cu")
		(net "M_F_CPU0_SA_CA<5>")
	)
	(segment
		(start 387.614668 -255.948688)
		(end 387.46049 -255.79451)
		(width 0.088646)
		(layer "In2.Cu")
		(net "M_F_CPU0_SA_CA<5>")
	)
	(segment
		(start 419.748716 -260.619748)
		(end 417.571428 -260.619748)
		(width 0.18288)
		(layer "In2.Cu")
		(net "M_F_CPU0_SA_CA<5>")
	)
	(segment
		(start 423.415714 -261.250938)
		(end 422.880282 -261.250938)
		(width 0.18288)
		(layer "In2.Cu")
		(net "M_F_CPU0_SA_CA<5>")
	)
	(segment
		(start 417.245038 -260.293358)
		(end 417.245038 -259.18287)
		(width 0.18288)
		(layer "In2.Cu")
		(net "M_F_CPU0_SA_CA<5>")
	)
	(segment
		(start 389.64489 -255.948688)
		(end 387.900418 -255.948688)
		(width 0.18288)
		(layer "In2.Cu")
		(net "M_F_CPU0_SA_CA<5>")
	)
	(segment
		(start 416.763708 -258.70154)
		(end 416.277044 -258.70154)
		(width 0.18288)
		(layer "In2.Cu")
		(net "M_F_CPU0_SA_CA<5>")
	)
	(segment
		(start 407.262584 -258.088384)
		(end 403.632924 -256.585212)
		(width 0.18288)
		(layer "In2.Cu")
		(net "M_F_CPU0_SA_CA<5>")
	)
	(segment
		(start 422.639998 -261.491222)
		(end 420.33571 -261.491222)
		(width 0.18288)
		(layer "In2.Cu")
		(net "M_F_CPU0_SA_CA<5>")
	)
	(segment
		(start 420.017194 -261.172706)
		(end 420.017194 -260.888226)
		(width 0.18288)
		(layer "In2.Cu")
		(net "M_F_CPU0_SA_CA<5>")
	)
	(segment
		(start 395.437868 -256.331212)
		(end 391.56894 -256.331212)
		(width 0.18288)
		(layer "In2.Cu")
		(net "M_F_CPU0_SA_CA<5>")
	)
	(segment
		(start 417.571428 -260.619748)
		(end 417.245038 -260.293358)
		(width 0.18288)
		(layer "In2.Cu")
		(net "M_F_CPU0_SA_CA<5>")
	)
	(segment
		(start 385.266946 -255.86309)
		(end 385.252214 -255.871726)
		(width 0.088646)
		(layer "In2.Cu")
		(net "M_F_CPU0_SA_CA<5>")
	)
	(segment
		(start 424.836082 -261.916672)
		(end 424.836082 -261.64286)
		(width 0.18288)
		(layer "In2.Cu")
		(net "M_F_CPU0_SA_CA<5>")
	)
	(segment
		(start 424.836082 -261.64286)
		(end 425.029122 -261.44982)
		(width 0.18288)
		(layer "In2.Cu")
		(net "M_F_CPU0_SA_CA<5>")
	)
	(segment
		(start 425.029122 -261.44982)
		(end 426.283374 -261.44982)
		(width 0.18288)
		(layer "In2.Cu")
		(net "M_F_CPU0_SA_CA<5>")
	)
	(segment
		(start 415.778696 -258.203192)
		(end 415.501074 -258.088384)
		(width 0.18288)
		(layer "In2.Cu")
		(net "M_F_CPU0_SA_CA<5>")
	)
	(segment
		(start 386.622798 -255.79451)
		(end 386.624322 -255.796034)
		(width 0.088646)
		(layer "In2.Cu")
		(net "M_F_CPU0_SA_CA<5>")
	)
	(segment
		(start 396.050516 -256.585212)
		(end 395.437868 -256.331212)
		(width 0.18288)
		(layer "In2.Cu")
		(net "M_F_CPU0_SA_CA<5>")
	)
	(segment
		(start 384.32105 -255.866646)
		(end 384.31216 -255.87198)
		(width 0.088646)
		(layer "In2.Cu")
		(net "M_F_CPU0_SA_CA<5>")
	)
	(segment
		(start 391.56894 -256.331212)
		(end 389.64489 -255.948688)
		(width 0.18288)
		(layer "In2.Cu")
		(net "M_F_CPU0_SA_CA<5>")
	)
	(segment
		(start 426.283374 -260.641084)
		(end 424.025568 -260.641084)
		(width 0.18288)
		(layer "In2.Cu")
		(net "M_F_CPU0_SA_CA<5>")
	)
	(segment
		(start 383.37236 -255.87198)
		(end 383.344166 -255.888236)
		(width 0.088646)
		(layer "In2.Cu")
		(net "M_F_CPU0_SA_CA<5>")
	)
	(segment
		(start 416.277044 -258.70154)
		(end 415.778696 -258.203192)
		(width 0.18288)
		(layer "In2.Cu")
		(net "M_F_CPU0_SA_CA<5>")
	)
	(arc
		(start 385.252214 -255.871726)
		(mid 385.065016 -255.921869)
		(end 384.877818 -255.871726)
		(width 0.088646)
		(layer "In2.Cu")
		(net "M_F_CPU0_SA_CA<5>")
	)
	(arc
		(start 384.31216 -255.87198)
		(mid 384.124962 -255.922123)
		(end 383.937764 -255.87198)
		(width 0.088646)
		(layer "In2.Cu")
		(net "M_F_CPU0_SA_CA<5>")
	)
	(arc
		(start 385.817618 -255.871726)
		(mid 385.543389 -255.795801)
		(end 385.266946 -255.86309)
		(width 0.088646)
		(layer "In2.Cu")
		(net "M_F_CPU0_SA_CA<5>")
	)
	(arc
		(start 386.192014 -255.871726)
		(mid 386.004816 -255.921869)
		(end 385.817618 -255.871726)
		(width 0.088646)
		(layer "In2.Cu")
		(net "M_F_CPU0_SA_CA<5>")
	)
	(arc
		(start 384.877818 -255.871726)
		(mid 384.600092 -255.795881)
		(end 384.32105 -255.866646)
		(width 0.088646)
		(layer "In2.Cu")
		(net "M_F_CPU0_SA_CA<5>")
	)
	(arc
		(start 383.937764 -255.87198)
		(mid 383.655062 -255.796238)
		(end 383.37236 -255.87198)
		(width 0.088646)
		(layer "In2.Cu")
		(net "M_F_CPU0_SA_CA<5>")
	)
	(arc
		(start 386.474462 -255.796034)
		(mid 386.328266 -255.815321)
		(end 386.192014 -255.871726)
		(width 0.088646)
		(layer "In2.Cu")
		(net "M_F_CPU0_SA_CA<5>")
	)
	(segment
		(start 424.38574 -263.191752)
		(end 423.488104 -262.294116)
		(width 0.20066)
		(layer "F.Cu")
		(net "M_F_CPU0_SA_CA<4>")
	)
	(segment
		(start 420.659814 -262.766556)
		(end 421.84066 -262.766556)
		(width 0.20066)
		(layer "F.Cu")
		(net "M_F_CPU0_SA_CA<4>")
	)
	(segment
		(start 427.805088 -262.766556)
		(end 427.367446 -263.204198)
		(width 0.20066)
		(layer "F.Cu")
		(net "M_F_CPU0_SA_CA<4>")
	)
	(segment
		(start 424.684444 -263.191752)
		(end 424.655234 -263.191752)
		(width 0.101854)
		(layer "F.Cu")
		(net "M_F_CPU0_SA_CA<4>")
	)
	(segment
		(start 429.384714 -262.76681)
		(end 429.38446 -262.766556)
		(width 0.20066)
		(layer "F.Cu")
		(net "M_F_CPU0_SA_CA<4>")
	)
	(segment
		(start 423.203878 -262.294116)
		(end 422.731184 -262.76681)
		(width 0.20066)
		(layer "F.Cu")
		(net "M_F_CPU0_SA_CA<4>")
	)
	(segment
		(start 426.938948 -263.191752)
		(end 424.684444 -263.191752)
		(width 0.1016)
		(layer "F.Cu")
		(net "M_F_CPU0_SA_CA<4>")
	)
	(segment
		(start 427.367446 -263.204198)
		(end 426.951394 -263.204198)
		(width 0.20066)
		(layer "F.Cu")
		(net "M_F_CPU0_SA_CA<4>")
	)
	(segment
		(start 424.655234 -263.191752)
		(end 424.38574 -263.191752)
		(width 0.20066)
		(layer "F.Cu")
		(net "M_F_CPU0_SA_CA<4>")
	)
	(segment
		(start 423.488104 -262.294116)
		(end 423.203878 -262.294116)
		(width 0.20066)
		(layer "F.Cu")
		(net "M_F_CPU0_SA_CA<4>")
	)
	(segment
		(start 381.775462 -255.825752)
		(end 381.775462 -256.361438)
		(width 0.20066)
		(layer "F.Cu")
		(net "M_F_CPU0_SA_CA<4>")
	)
	(segment
		(start 421.84066 -262.766556)
		(end 421.840914 -262.76681)
		(width 0.20066)
		(layer "F.Cu")
		(net "M_F_CPU0_SA_CA<4>")
	)
	(segment
		(start 422.731184 -262.76681)
		(end 421.840914 -262.76681)
		(width 0.20066)
		(layer "F.Cu")
		(net "M_F_CPU0_SA_CA<4>")
	)
	(segment
		(start 429.38446 -262.766556)
		(end 427.805088 -262.766556)
		(width 0.20066)
		(layer "F.Cu")
		(net "M_F_CPU0_SA_CA<4>")
	)
	(segment
		(start 426.951394 -263.204198)
		(end 426.938948 -263.191752)
		(width 0.1016)
		(layer "F.Cu")
		(net "M_F_CPU0_SA_CA<4>")
	)
	(segment
		(start 381.775716 -255.825498)
		(end 381.775462 -255.825752)
		(width 0.20066)
		(layer "F.Cu")
		(net "M_F_CPU0_SA_CA<4>")
	)
	(segment
		(start 412.018226 -259.010404)
		(end 411.702758 -259.010404)
		(width 0.18288)
		(layer "In2.Cu")
		(net "M_F_CPU0_SA_CA<4>")
	)
	(segment
		(start 386.287264 -256.03708)
		(end 386.272532 -256.045716)
		(width 0.088646)
		(layer "In2.Cu")
		(net "M_F_CPU0_SA_CA<4>")
	)
	(segment
		(start 415.475928 -259.209794)
		(end 414.93694 -258.670806)
		(width 0.18288)
		(layer "In2.Cu")
		(net "M_F_CPU0_SA_CA<4>")
	)
	(segment
		(start 412.895034 -259.55117)
		(end 412.686246 -259.759958)
		(width 0.18288)
		(layer "In2.Cu")
		(net "M_F_CPU0_SA_CA<4>")
	)
	(segment
		(start 413.659574 -258.670806)
		(end 413.28594 -259.04444)
		(width 0.18288)
		(layer "In2.Cu")
		(net "M_F_CPU0_SA_CA<4>")
	)
	(segment
		(start 409.86202 -259.680202)
		(end 409.702 -259.840222)
		(width 0.18288)
		(layer "In2.Cu")
		(net "M_F_CPU0_SA_CA<4>")
	)
	(segment
		(start 416.337496 -259.912612)
		(end 416.559746 -259.912612)
		(width 0.18288)
		(layer "In2.Cu")
		(net "M_F_CPU0_SA_CA<4>")
	)
	(segment
		(start 403.50567 -257.098292)
		(end 396.24381 -257.098292)
		(width 0.18288)
		(layer "In2.Cu")
		(net "M_F_CPU0_SA_CA<4>")
	)
	(segment
		(start 387.655054 -256.325116)
		(end 387.314694 -255.984756)
		(width 0.088646)
		(layer "In2.Cu")
		(net "M_F_CPU0_SA_CA<4>")
	)
	(segment
		(start 409.86202 -259.026406)
		(end 409.86202 -259.680202)
		(width 0.18288)
		(layer "In2.Cu")
		(net "M_F_CPU0_SA_CA<4>")
	)
	(segment
		(start 417.171124 -261.568184)
		(end 416.785044 -261.182104)
		(width 0.18288)
		(layer "In2.Cu")
		(net "M_F_CPU0_SA_CA<4>")
	)
	(segment
		(start 384.78206 -256.03708)
		(end 384.782314 -256.03708)
		(width 0.088646)
		(layer "In2.Cu")
		(net "M_F_CPU0_SA_CA<4>")
	)
	(segment
		(start 416.785044 -260.80212)
		(end 416.625024 -260.6421)
		(width 0.18288)
		(layer "In2.Cu")
		(net "M_F_CPU0_SA_CA<4>")
	)
	(segment
		(start 413.088074 -259.04444)
		(end 412.895034 -259.23748)
		(width 0.18288)
		(layer "In2.Cu")
		(net "M_F_CPU0_SA_CA<4>")
	)
	(segment
		(start 396.24381 -257.098292)
		(end 395.239748 -256.68224)
		(width 0.18288)
		(layer "In2.Cu")
		(net "M_F_CPU0_SA_CA<4>")
	)
	(segment
		(start 410.02966 -258.858766)
		(end 409.86202 -259.026406)
		(width 0.18288)
		(layer "In2.Cu")
		(net "M_F_CPU0_SA_CA<4>")
	)
	(segment
		(start 412.686246 -259.759958)
		(end 412.338266 -259.759958)
		(width 0.18288)
		(layer "In2.Cu")
		(net "M_F_CPU0_SA_CA<4>")
	)
	(segment
		(start 414.93694 -258.670806)
		(end 413.659574 -258.670806)
		(width 0.18288)
		(layer "In2.Cu")
		(net "M_F_CPU0_SA_CA<4>")
	)
	(segment
		(start 409.702 -259.840222)
		(end 409.258008 -259.840222)
		(width 0.18288)
		(layer "In2.Cu")
		(net "M_F_CPU0_SA_CA<4>")
	)
	(segment
		(start 416.785044 -261.182104)
		(end 416.785044 -260.80212)
		(width 0.18288)
		(layer "In2.Cu")
		(net "M_F_CPU0_SA_CA<4>")
	)
	(segment
		(start 383.188464 -256.520442)
		(end 382.90246 -256.685796)
		(width 0.088646)
		(layer "In2.Cu")
		(net "M_F_CPU0_SA_CA<4>")
	)
	(segment
		(start 417.419536 -261.568184)
		(end 417.171124 -261.568184)
		(width 0.18288)
		(layer "In2.Cu")
		(net "M_F_CPU0_SA_CA<4>")
	)
	(segment
		(start 419.62578 -261.568184)
		(end 419.351206 -261.568184)
		(width 0.18288)
		(layer "In2.Cu")
		(net "M_F_CPU0_SA_CA<4>")
	)
	(segment
		(start 412.338266 -259.759958)
		(end 412.178246 -259.599938)
		(width 0.18288)
		(layer "In2.Cu")
		(net "M_F_CPU0_SA_CA<4>")
	)
	(segment
		(start 389.616442 -256.325116)
		(end 387.900418 -256.325116)
		(width 0.18288)
		(layer "In2.Cu")
		(net "M_F_CPU0_SA_CA<4>")
	)
	(segment
		(start 409.064968 -259.647182)
		(end 409.064968 -259.2705)
		(width 0.18288)
		(layer "In2.Cu")
		(net "M_F_CPU0_SA_CA<4>")
	)
	(segment
		(start 391.41273 -256.68224)
		(end 389.616442 -256.325116)
		(width 0.18288)
		(layer "In2.Cu")
		(net "M_F_CPU0_SA_CA<4>")
	)
	(segment
		(start 387.314694 -255.984756)
		(end 387.082284 -255.984756)
		(width 0.088646)
		(layer "In2.Cu")
		(net "M_F_CPU0_SA_CA<4>")
	)
	(segment
		(start 382.500124 -256.66954)
		(end 381.775462 -256.361438)
		(width 0.088646)
		(layer "In2.Cu")
		(net "M_F_CPU0_SA_CA<4>")
	)
	(segment
		(start 387.082284 -255.984756)
		(end 387.083808 -255.98628)
		(width 0.088646)
		(layer "In2.Cu")
		(net "M_F_CPU0_SA_CA<4>")
	)
	(segment
		(start 409.064968 -259.2705)
		(end 408.786838 -258.99237)
		(width 0.18288)
		(layer "In2.Cu")
		(net "M_F_CPU0_SA_CA<4>")
	)
	(segment
		(start 416.526726 -259.209794)
		(end 415.475928 -259.209794)
		(width 0.18288)
		(layer "In2.Cu")
		(net "M_F_CPU0_SA_CA<4>")
	)
	(segment
		(start 416.276028 -260.6421)
		(end 416.116008 -260.48208)
		(width 0.18288)
		(layer "In2.Cu")
		(net "M_F_CPU0_SA_CA<4>")
	)
	(segment
		(start 416.116008 -260.48208)
		(end 416.116008 -260.1341)
		(width 0.18288)
		(layer "In2.Cu")
		(net "M_F_CPU0_SA_CA<4>")
	)
	(segment
		(start 395.239748 -256.68224)
		(end 391.41273 -256.68224)
		(width 0.18288)
		(layer "In2.Cu")
		(net "M_F_CPU0_SA_CA<4>")
	)
	(segment
		(start 411.55112 -258.858766)
		(end 410.02966 -258.858766)
		(width 0.18288)
		(layer "In2.Cu")
		(net "M_F_CPU0_SA_CA<4>")
	)
	(segment
		(start 416.625024 -260.6421)
		(end 416.276028 -260.6421)
		(width 0.18288)
		(layer "In2.Cu")
		(net "M_F_CPU0_SA_CA<4>")
	)
	(segment
		(start 416.559746 -259.912612)
		(end 416.719766 -259.752592)
		(width 0.18288)
		(layer "In2.Cu")
		(net "M_F_CPU0_SA_CA<4>")
	)
	(segment
		(start 387.900418 -256.325116)
		(end 387.655054 -256.325116)
		(width 0.088646)
		(layer "In2.Cu")
		(net "M_F_CPU0_SA_CA<4>")
	)
	(segment
		(start 409.258008 -259.840222)
		(end 409.064968 -259.647182)
		(width 0.18288)
		(layer "In2.Cu")
		(net "M_F_CPU0_SA_CA<4>")
	)
	(segment
		(start 420.544244 -262.486648)
		(end 419.62578 -261.568184)
		(width 0.18288)
		(layer "In2.Cu")
		(net "M_F_CPU0_SA_CA<4>")
	)
	(segment
		(start 419.351206 -261.568184)
		(end 419.166548 -261.383526)
		(width 0.18288)
		(layer "In2.Cu")
		(net "M_F_CPU0_SA_CA<4>")
	)
	(segment
		(start 416.719766 -259.402834)
		(end 416.526726 -259.209794)
		(width 0.18288)
		(layer "In2.Cu")
		(net "M_F_CPU0_SA_CA<4>")
	)
	(segment
		(start 419.166548 -261.383526)
		(end 417.604194 -261.383526)
		(width 0.18288)
		(layer "In2.Cu")
		(net "M_F_CPU0_SA_CA<4>")
	)
	(segment
		(start 385.347464 -256.03708)
		(end 385.332732 -256.045716)
		(width 0.088646)
		(layer "In2.Cu")
		(net "M_F_CPU0_SA_CA<4>")
	)
	(segment
		(start 412.178246 -259.170424)
		(end 412.018226 -259.010404)
		(width 0.18288)
		(layer "In2.Cu")
		(net "M_F_CPU0_SA_CA<4>")
	)
	(segment
		(start 383.467864 -256.03708)
		(end 383.46761 -256.037334)
		(width 0.088646)
		(layer "In2.Cu")
		(net "M_F_CPU0_SA_CA<4>")
	)
	(segment
		(start 416.116008 -260.1341)
		(end 416.337496 -259.912612)
		(width 0.18288)
		(layer "In2.Cu")
		(net "M_F_CPU0_SA_CA<4>")
	)
	(segment
		(start 412.178246 -259.599938)
		(end 412.178246 -259.170424)
		(width 0.18288)
		(layer "In2.Cu")
		(net "M_F_CPU0_SA_CA<4>")
	)
	(segment
		(start 417.604194 -261.383526)
		(end 417.419536 -261.568184)
		(width 0.18288)
		(layer "In2.Cu")
		(net "M_F_CPU0_SA_CA<4>")
	)
	(segment
		(start 416.719766 -259.752592)
		(end 416.719766 -259.402834)
		(width 0.18288)
		(layer "In2.Cu")
		(net "M_F_CPU0_SA_CA<4>")
	)
	(segment
		(start 408.786838 -258.99237)
		(end 407.667206 -258.99237)
		(width 0.18288)
		(layer "In2.Cu")
		(net "M_F_CPU0_SA_CA<4>")
	)
	(segment
		(start 407.667206 -258.99237)
		(end 407.377392 -258.702556)
		(width 0.18288)
		(layer "In2.Cu")
		(net "M_F_CPU0_SA_CA<4>")
	)
	(segment
		(start 412.895034 -259.23748)
		(end 412.895034 -259.55117)
		(width 0.18288)
		(layer "In2.Cu")
		(net "M_F_CPU0_SA_CA<4>")
	)
	(segment
		(start 411.702758 -259.010404)
		(end 411.55112 -258.858766)
		(width 0.18288)
		(layer "In2.Cu")
		(net "M_F_CPU0_SA_CA<4>")
	)
	(segment
		(start 407.377392 -258.702556)
		(end 403.50567 -257.098292)
		(width 0.18288)
		(layer "In2.Cu")
		(net "M_F_CPU0_SA_CA<4>")
	)
	(segment
		(start 420.659814 -262.766556)
		(end 420.544244 -262.486648)
		(width 0.18288)
		(layer "In2.Cu")
		(net "M_F_CPU0_SA_CA<4>")
	)
	(segment
		(start 382.528064 -256.685796)
		(end 382.500124 -256.66954)
		(width 0.088646)
		(layer "In2.Cu")
		(net "M_F_CPU0_SA_CA<4>")
	)
	(segment
		(start 413.28594 -259.04444)
		(end 413.088074 -259.04444)
		(width 0.18288)
		(layer "In2.Cu")
		(net "M_F_CPU0_SA_CA<4>")
	)
	(segment
		(start 387.083808 -255.98628)
		(end 386.474716 -255.98628)
		(width 0.088646)
		(layer "In2.Cu")
		(net "M_F_CPU0_SA_CA<4>")
	)
	(segment
		(start 383.842514 -256.03708)
		(end 383.84226 -256.03708)
		(width 0.088646)
		(layer "In2.Cu")
		(net "M_F_CPU0_SA_CA<4>")
	)
	(arc
		(start 385.332732 -256.045716)
		(mid 385.056291 -256.112882)
		(end 384.78206 -256.03708)
		(width 0.088646)
		(layer "In2.Cu")
		(net "M_F_CPU0_SA_CA<4>")
	)
	(arc
		(start 383.280412 -256.361438)
		(mid 383.255764 -256.453267)
		(end 383.188464 -256.520442)
		(width 0.088646)
		(layer "In2.Cu")
		(net "M_F_CPU0_SA_CA<4>")
	)
	(arc
		(start 385.72186 -256.03708)
		(mid 385.534662 -255.986937)
		(end 385.347464 -256.03708)
		(width 0.088646)
		(layer "In2.Cu")
		(net "M_F_CPU0_SA_CA<4>")
	)
	(arc
		(start 383.46761 -256.037334)
		(mid 383.330565 -256.174294)
		(end 383.280412 -256.361438)
		(width 0.088646)
		(layer "In2.Cu")
		(net "M_F_CPU0_SA_CA<4>")
	)
	(arc
		(start 383.84226 -256.03708)
		(mid 383.655062 -255.986937)
		(end 383.467864 -256.03708)
		(width 0.088646)
		(layer "In2.Cu")
		(net "M_F_CPU0_SA_CA<4>")
	)
	(arc
		(start 384.782314 -256.03708)
		(mid 384.595116 -255.986937)
		(end 384.407918 -256.03708)
		(width 0.088646)
		(layer "In2.Cu")
		(net "M_F_CPU0_SA_CA<4>")
	)
	(arc
		(start 386.272532 -256.045716)
		(mid 385.996091 -256.112882)
		(end 385.72186 -256.03708)
		(width 0.088646)
		(layer "In2.Cu")
		(net "M_F_CPU0_SA_CA<4>")
	)
	(arc
		(start 384.407918 -256.03708)
		(mid 384.125216 -256.112856)
		(end 383.842514 -256.03708)
		(width 0.088646)
		(layer "In2.Cu")
		(net "M_F_CPU0_SA_CA<4>")
	)
	(arc
		(start 386.474716 -255.98628)
		(mid 386.377641 -255.999329)
		(end 386.287264 -256.03708)
		(width 0.088646)
		(layer "In2.Cu")
		(net "M_F_CPU0_SA_CA<4>")
	)
	(arc
		(start 382.90246 -256.685796)
		(mid 382.715262 -256.735973)
		(end 382.528064 -256.685796)
		(width 0.088646)
		(layer "In2.Cu")
		(net "M_F_CPU0_SA_CA<4>")
	)
	(segment
		(start 428.367952 -264.052304)
		(end 428.37862 -264.041636)
		(width 0.1016)
		(layer "F.Cu")
		(net "M_F_CPU0_SA_CA<3>")
	)
	(segment
		(start 428.37862 -264.041636)
		(end 430.38776 -264.041636)
		(width 0.1016)
		(layer "F.Cu")
		(net "M_F_CPU0_SA_CA<3>")
	)
	(segment
		(start 424.759882 -263.616694)
		(end 425.940982 -263.616694)
		(width 0.20066)
		(layer "F.Cu")
		(net "M_F_CPU0_SA_CA<3>")
	)
	(segment
		(start 425.940982 -263.616694)
		(end 427.576742 -263.616694)
		(width 0.20066)
		(layer "F.Cu")
		(net "M_F_CPU0_SA_CA<3>")
	)
	(segment
		(start 428.363126 -264.052304)
		(end 428.367952 -264.052304)
		(width 0.101854)
		(layer "F.Cu")
		(net "M_F_CPU0_SA_CA<3>")
	)
	(segment
		(start 430.38776 -264.041636)
		(end 430.395126 -264.049002)
		(width 0.1016)
		(layer "F.Cu")
		(net "M_F_CPU0_SA_CA<3>")
	)
	(segment
		(start 432.37023 -263.616694)
		(end 433.484782 -263.616694)
		(width 0.20066)
		(layer "F.Cu")
		(net "M_F_CPU0_SA_CA<3>")
	)
	(segment
		(start 430.669192 -264.049002)
		(end 431.534062 -263.184132)
		(width 0.20066)
		(layer "F.Cu")
		(net "M_F_CPU0_SA_CA<3>")
	)
	(segment
		(start 383.185162 -257.175254)
		(end 383.185162 -256.639314)
		(width 0.20066)
		(layer "F.Cu")
		(net "M_F_CPU0_SA_CA<3>")
	)
	(segment
		(start 428.012352 -264.052304)
		(end 428.363126 -264.052304)
		(width 0.20066)
		(layer "F.Cu")
		(net "M_F_CPU0_SA_CA<3>")
	)
	(segment
		(start 431.534062 -263.184132)
		(end 431.937668 -263.184132)
		(width 0.20066)
		(layer "F.Cu")
		(net "M_F_CPU0_SA_CA<3>")
	)
	(segment
		(start 427.576742 -263.616694)
		(end 428.012352 -264.052304)
		(width 0.20066)
		(layer "F.Cu")
		(net "M_F_CPU0_SA_CA<3>")
	)
	(segment
		(start 431.937668 -263.184132)
		(end 432.37023 -263.616694)
		(width 0.20066)
		(layer "F.Cu")
		(net "M_F_CPU0_SA_CA<3>")
	)
	(segment
		(start 430.395126 -264.049002)
		(end 430.669192 -264.049002)
		(width 0.20066)
		(layer "F.Cu")
		(net "M_F_CPU0_SA_CA<3>")
	)
	(segment
		(start 409.004262 -260.313424)
		(end 408.63266 -260.313424)
		(width 0.18288)
		(layer "In2.Cu")
		(net "M_F_CPU0_SA_CA<3>")
	)
	(segment
		(start 422.1988 -263.684258)
		(end 421.978836 -263.904222)
		(width 0.18288)
		(layer "In2.Cu")
		(net "M_F_CPU0_SA_CA<3>")
	)
	(segment
		(start 421.630856 -263.904222)
		(end 421.470836 -263.744202)
		(width 0.18288)
		(layer "In2.Cu")
		(net "M_F_CPU0_SA_CA<3>")
	)
	(segment
		(start 409.326842 -260.636004)
		(end 409.004262 -260.313424)
		(width 0.18288)
		(layer "In2.Cu")
		(net "M_F_CPU0_SA_CA<3>")
	)
	(segment
		(start 415.205926 -260.70179)
		(end 414.628076 -260.12394)
		(width 0.18288)
		(layer "In2.Cu")
		(net "M_F_CPU0_SA_CA<3>")
	)
	(segment
		(start 423.74439 -261.781036)
		(end 423.556684 -261.968742)
		(width 0.18288)
		(layer "In2.Cu")
		(net "M_F_CPU0_SA_CA<3>")
	)
	(segment
		(start 424.137328 -261.781036)
		(end 423.74439 -261.781036)
		(width 0.18288)
		(layer "In2.Cu")
		(net "M_F_CPU0_SA_CA<3>")
	)
	(segment
		(start 421.470836 -263.744202)
		(end 421.470836 -263.351264)
		(width 0.18288)
		(layer "In2.Cu")
		(net "M_F_CPU0_SA_CA<3>")
	)
	(segment
		(start 424.759882 -263.616694)
		(end 424.297348 -263.15416)
		(width 0.18288)
		(layer "In2.Cu")
		(net "M_F_CPU0_SA_CA<3>")
	)
	(segment
		(start 420.341806 -263.191244)
		(end 419.93566 -262.785098)
		(width 0.18288)
		(layer "In2.Cu")
		(net "M_F_CPU0_SA_CA<3>")
	)
	(segment
		(start 404.227284 -258.126484)
		(end 403.083522 -257.652774)
		(width 0.18288)
		(layer "In2.Cu")
		(net "M_F_CPU0_SA_CA<3>")
	)
	(segment
		(start 421.310816 -263.191244)
		(end 420.341806 -263.191244)
		(width 0.18288)
		(layer "In2.Cu")
		(net "M_F_CPU0_SA_CA<3>")
	)
	(segment
		(start 422.35882 -263.191244)
		(end 422.1988 -263.351264)
		(width 0.18288)
		(layer "In2.Cu")
		(net "M_F_CPU0_SA_CA<3>")
	)
	(segment
		(start 383.620518 -257.015742)
		(end 383.248916 -257.116072)
		(width 0.088646)
		(layer "In2.Cu")
		(net "M_F_CPU0_SA_CA<3>")
	)
	(segment
		(start 419.93566 -262.596884)
		(end 419.650418 -262.311642)
		(width 0.18288)
		(layer "In2.Cu")
		(net "M_F_CPU0_SA_CA<3>")
	)
	(segment
		(start 422.1988 -263.351264)
		(end 422.1988 -263.684258)
		(width 0.18288)
		(layer "In2.Cu")
		(net "M_F_CPU0_SA_CA<3>")
	)
	(segment
		(start 412.902908 -260.693916)
		(end 412.715456 -260.506464)
		(width 0.18288)
		(layer "In2.Cu")
		(net "M_F_CPU0_SA_CA<3>")
	)
	(segment
		(start 408.63266 -260.313424)
		(end 408.062176 -259.74294)
		(width 0.18288)
		(layer "In2.Cu")
		(net "M_F_CPU0_SA_CA<3>")
	)
	(segment
		(start 424.297348 -263.15416)
		(end 424.297348 -261.941056)
		(width 0.18288)
		(layer "In2.Cu")
		(net "M_F_CPU0_SA_CA<3>")
	)
	(segment
		(start 403.083522 -257.652774)
		(end 396.239492 -257.652774)
		(width 0.18288)
		(layer "In2.Cu")
		(net "M_F_CPU0_SA_CA<3>")
	)
	(segment
		(start 413.909764 -260.12394)
		(end 413.339788 -260.693916)
		(width 0.18288)
		(layer "In2.Cu")
		(net "M_F_CPU0_SA_CA<3>")
	)
	(segment
		(start 383.937764 -256.850896)
		(end 383.737104 -256.967228)
		(width 0.088646)
		(layer "In2.Cu")
		(net "M_F_CPU0_SA_CA<3>")
	)
	(segment
		(start 396.239492 -257.652774)
		(end 396.145258 -257.55854)
		(width 0.18288)
		(layer "In2.Cu")
		(net "M_F_CPU0_SA_CA<3>")
	)
	(segment
		(start 423.556684 -261.968742)
		(end 423.556684 -262.359902)
		(width 0.18288)
		(layer "In2.Cu")
		(net "M_F_CPU0_SA_CA<3>")
	)
	(segment
		(start 419.93566 -262.785098)
		(end 419.93566 -262.596884)
		(width 0.18288)
		(layer "In2.Cu")
		(net "M_F_CPU0_SA_CA<3>")
	)
	(segment
		(start 383.195068 -257.157728)
		(end 383.185162 -257.175254)
		(width 0.088646)
		(layer "In2.Cu")
		(net "M_F_CPU0_SA_CA<3>")
	)
	(segment
		(start 411.861762 -260.506464)
		(end 411.732222 -260.636004)
		(width 0.18288)
		(layer "In2.Cu")
		(net "M_F_CPU0_SA_CA<3>")
	)
	(segment
		(start 405.84374 -259.74294)
		(end 404.227284 -258.126484)
		(width 0.18288)
		(layer "In2.Cu")
		(net "M_F_CPU0_SA_CA<3>")
	)
	(segment
		(start 423.556684 -262.359902)
		(end 422.725342 -263.191244)
		(width 0.18288)
		(layer "In2.Cu")
		(net "M_F_CPU0_SA_CA<3>")
	)
	(segment
		(start 413.339788 -260.693916)
		(end 412.902908 -260.693916)
		(width 0.18288)
		(layer "In2.Cu")
		(net "M_F_CPU0_SA_CA<3>")
	)
	(segment
		(start 394.882624 -257.035554)
		(end 388.840218 -257.035554)
		(width 0.18288)
		(layer "In2.Cu")
		(net "M_F_CPU0_SA_CA<3>")
	)
	(segment
		(start 412.715456 -260.506464)
		(end 411.861762 -260.506464)
		(width 0.18288)
		(layer "In2.Cu")
		(net "M_F_CPU0_SA_CA<3>")
	)
	(segment
		(start 411.732222 -260.636004)
		(end 409.326842 -260.636004)
		(width 0.18288)
		(layer "In2.Cu")
		(net "M_F_CPU0_SA_CA<3>")
	)
	(segment
		(start 419.650418 -262.311642)
		(end 417.167314 -262.311642)
		(width 0.18288)
		(layer "In2.Cu")
		(net "M_F_CPU0_SA_CA<3>")
	)
	(segment
		(start 408.062176 -259.74294)
		(end 405.84374 -259.74294)
		(width 0.18288)
		(layer "In2.Cu")
		(net "M_F_CPU0_SA_CA<3>")
	)
	(segment
		(start 415.557462 -260.70179)
		(end 415.205926 -260.70179)
		(width 0.18288)
		(layer "In2.Cu")
		(net "M_F_CPU0_SA_CA<3>")
	)
	(segment
		(start 414.628076 -260.12394)
		(end 413.909764 -260.12394)
		(width 0.18288)
		(layer "In2.Cu")
		(net "M_F_CPU0_SA_CA<3>")
	)
	(segment
		(start 422.725342 -263.191244)
		(end 422.35882 -263.191244)
		(width 0.18288)
		(layer "In2.Cu")
		(net "M_F_CPU0_SA_CA<3>")
	)
	(segment
		(start 421.978836 -263.904222)
		(end 421.630856 -263.904222)
		(width 0.18288)
		(layer "In2.Cu")
		(net "M_F_CPU0_SA_CA<3>")
	)
	(segment
		(start 417.167314 -262.311642)
		(end 415.557462 -260.70179)
		(width 0.18288)
		(layer "In2.Cu")
		(net "M_F_CPU0_SA_CA<3>")
	)
	(segment
		(start 396.145258 -257.55854)
		(end 394.882624 -257.035554)
		(width 0.18288)
		(layer "In2.Cu")
		(net "M_F_CPU0_SA_CA<3>")
	)
	(segment
		(start 424.297348 -261.941056)
		(end 424.137328 -261.781036)
		(width 0.18288)
		(layer "In2.Cu")
		(net "M_F_CPU0_SA_CA<3>")
	)
	(segment
		(start 421.470836 -263.351264)
		(end 421.310816 -263.191244)
		(width 0.18288)
		(layer "In2.Cu")
		(net "M_F_CPU0_SA_CA<3>")
	)
	(segment
		(start 387.460744 -257.035554)
		(end 387.286246 -256.91211)
		(width 0.088646)
		(layer "In2.Cu")
		(net "M_F_CPU0_SA_CA<3>")
	)
	(segment
		(start 388.840218 -257.035554)
		(end 387.460744 -257.035554)
		(width 0.088646)
		(layer "In2.Cu")
		(net "M_F_CPU0_SA_CA<3>")
	)
	(arc
		(start 384.877564 -256.850896)
		(mid 384.594862 -256.926672)
		(end 384.31216 -256.850896)
		(width 0.088646)
		(layer "In2.Cu")
		(net "M_F_CPU0_SA_CA<3>")
	)
	(arc
		(start 383.248916 -257.116072)
		(mid 383.217818 -257.131511)
		(end 383.195068 -257.157728)
		(width 0.088646)
		(layer "In2.Cu")
		(net "M_F_CPU0_SA_CA<3>")
	)
	(arc
		(start 385.817364 -256.850896)
		(mid 385.534662 -256.926672)
		(end 385.25196 -256.850896)
		(width 0.088646)
		(layer "In2.Cu")
		(net "M_F_CPU0_SA_CA<3>")
	)
	(arc
		(start 386.19176 -256.850896)
		(mid 386.004562 -256.800753)
		(end 385.817364 -256.850896)
		(width 0.088646)
		(layer "In2.Cu")
		(net "M_F_CPU0_SA_CA<3>")
	)
	(arc
		(start 387.286246 -256.91211)
		(mid 387.206648 -256.887205)
		(end 387.13156 -256.850896)
		(width 0.088646)
		(layer "In2.Cu")
		(net "M_F_CPU0_SA_CA<3>")
	)
	(arc
		(start 385.25196 -256.850896)
		(mid 385.064762 -256.800753)
		(end 384.877564 -256.850896)
		(width 0.088646)
		(layer "In2.Cu")
		(net "M_F_CPU0_SA_CA<3>")
	)
	(arc
		(start 383.737104 -256.967228)
		(mid 383.680396 -256.995291)
		(end 383.620518 -257.015742)
		(width 0.088646)
		(layer "In2.Cu")
		(net "M_F_CPU0_SA_CA<3>")
	)
	(arc
		(start 384.31216 -256.850896)
		(mid 384.124962 -256.800753)
		(end 383.937764 -256.850896)
		(width 0.088646)
		(layer "In2.Cu")
		(net "M_F_CPU0_SA_CA<3>")
	)
	(arc
		(start 387.13156 -256.850896)
		(mid 386.944362 -256.800753)
		(end 386.757164 -256.850896)
		(width 0.088646)
		(layer "In2.Cu")
		(net "M_F_CPU0_SA_CA<3>")
	)
	(arc
		(start 386.757164 -256.850896)
		(mid 386.474462 -256.926672)
		(end 386.19176 -256.850896)
		(width 0.088646)
		(layer "In2.Cu")
		(net "M_F_CPU0_SA_CA<3>")
	)
	(segment
		(start 426.938948 -264.89152)
		(end 426.951394 -264.903966)
		(width 0.1016)
		(layer "F.Cu")
		(net "M_F_CPU0_SA_CA<2>")
	)
	(segment
		(start 429.38446 -264.466324)
		(end 429.384714 -264.466578)
		(width 0.20066)
		(layer "F.Cu")
		(net "M_F_CPU0_SA_CA<2>")
	)
	(segment
		(start 423.515536 -263.996424)
		(end 424.410632 -264.89152)
		(width 0.20066)
		(layer "F.Cu")
		(net "M_F_CPU0_SA_CA<2>")
	)
	(segment
		(start 427.805088 -264.466324)
		(end 429.38446 -264.466324)
		(width 0.20066)
		(layer "F.Cu")
		(net "M_F_CPU0_SA_CA<2>")
	)
	(segment
		(start 422.761156 -264.466578)
		(end 423.23131 -263.996424)
		(width 0.20066)
		(layer "F.Cu")
		(net "M_F_CPU0_SA_CA<2>")
	)
	(segment
		(start 420.659814 -264.466578)
		(end 421.840914 -264.466578)
		(width 0.20066)
		(layer "F.Cu")
		(net "M_F_CPU0_SA_CA<2>")
	)
	(segment
		(start 421.840914 -264.466578)
		(end 422.761156 -264.466578)
		(width 0.20066)
		(layer "F.Cu")
		(net "M_F_CPU0_SA_CA<2>")
	)
	(segment
		(start 381.305562 -256.639314)
		(end 381.305562 -257.175)
		(width 0.20066)
		(layer "F.Cu")
		(net "M_F_CPU0_SA_CA<2>")
	)
	(segment
		(start 424.410632 -264.89152)
		(end 424.631104 -264.89152)
		(width 0.20066)
		(layer "F.Cu")
		(net "M_F_CPU0_SA_CA<2>")
	)
	(segment
		(start 424.631104 -264.89152)
		(end 424.673522 -264.89152)
		(width 0.101854)
		(layer "F.Cu")
		(net "M_F_CPU0_SA_CA<2>")
	)
	(segment
		(start 423.23131 -263.996424)
		(end 423.515536 -263.996424)
		(width 0.20066)
		(layer "F.Cu")
		(net "M_F_CPU0_SA_CA<2>")
	)
	(segment
		(start 424.673522 -264.89152)
		(end 426.938948 -264.89152)
		(width 0.1016)
		(layer "F.Cu")
		(net "M_F_CPU0_SA_CA<2>")
	)
	(segment
		(start 381.305562 -257.175)
		(end 381.305816 -257.175254)
		(width 0.20066)
		(layer "F.Cu")
		(net "M_F_CPU0_SA_CA<2>")
	)
	(segment
		(start 426.951394 -264.903966)
		(end 427.367446 -264.903966)
		(width 0.20066)
		(layer "F.Cu")
		(net "M_F_CPU0_SA_CA<2>")
	)
	(segment
		(start 427.367446 -264.903966)
		(end 427.805088 -264.466324)
		(width 0.20066)
		(layer "F.Cu")
		(net "M_F_CPU0_SA_CA<2>")
	)
	(segment
		(start 410.272992 -261.204456)
		(end 409.916376 -261.561072)
		(width 0.18288)
		(layer "In2.Cu")
		(net "M_F_CPU0_SA_CA<2>")
	)
	(segment
		(start 396.084298 -257.982212)
		(end 394.697458 -257.407918)
		(width 0.18288)
		(layer "In2.Cu")
		(net "M_F_CPU0_SA_CA<2>")
	)
	(segment
		(start 381.576072 -257.175254)
		(end 381.305816 -257.175254)
		(width 0.088646)
		(layer "In2.Cu")
		(net "M_F_CPU0_SA_CA<2>")
	)
	(segment
		(start 419.86327 -263.504172)
		(end 419.581076 -263.504172)
		(width 0.18288)
		(layer "In2.Cu")
		(net "M_F_CPU0_SA_CA<2>")
	)
	(segment
		(start 404.321772 -259.692902)
		(end 404.075392 -259.446522)
		(width 0.18288)
		(layer "In2.Cu")
		(net "M_F_CPU0_SA_CA<2>")
	)
	(segment
		(start 420.33825 -263.878568)
		(end 420.237666 -263.878568)
		(width 0.18288)
		(layer "In2.Cu")
		(net "M_F_CPU0_SA_CA<2>")
	)
	(segment
		(start 394.697458 -257.407918)
		(end 388.840218 -257.407918)
		(width 0.18288)
		(layer "In2.Cu")
		(net "M_F_CPU0_SA_CA<2>")
	)
	(segment
		(start 408.914092 -261.409434)
		(end 408.914092 -260.950964)
		(width 0.18288)
		(layer "In2.Cu")
		(net "M_F_CPU0_SA_CA<2>")
	)
	(segment
		(start 412.590996 -261.223252)
		(end 412.489142 -261.325106)
		(width 0.18288)
		(layer "In2.Cu")
		(net "M_F_CPU0_SA_CA<2>")
	)
	(segment
		(start 417.931092 -262.833612)
		(end 417.47948 -263.285224)
		(width 0.18288)
		(layer "In2.Cu")
		(net "M_F_CPU0_SA_CA<2>")
	)
	(segment
		(start 420.659814 -264.200132)
		(end 420.33825 -263.878568)
		(width 0.18288)
		(layer "In2.Cu")
		(net "M_F_CPU0_SA_CA<2>")
	)
	(segment
		(start 412.489142 -261.325106)
		(end 412.489142 -261.601712)
		(width 0.18288)
		(layer "In2.Cu")
		(net "M_F_CPU0_SA_CA<2>")
	)
	(segment
		(start 404.547832 -259.692902)
		(end 404.321772 -259.692902)
		(width 0.18288)
		(layer "In2.Cu")
		(net "M_F_CPU0_SA_CA<2>")
	)
	(segment
		(start 404.218902 -259.076698)
		(end 404.218902 -258.850638)
		(width 0.18288)
		(layer "In2.Cu")
		(net "M_F_CPU0_SA_CA<2>")
	)
	(segment
		(start 386.757164 -257.499612)
		(end 386.742432 -257.490976)
		(width 0.088646)
		(layer "In2.Cu")
		(net "M_F_CPU0_SA_CA<2>")
	)
	(segment
		(start 415.993834 -262.072882)
		(end 415.993834 -261.857998)
		(width 0.18288)
		(layer "In2.Cu")
		(net "M_F_CPU0_SA_CA<2>")
	)
	(segment
		(start 411.420564 -261.204456)
		(end 410.272992 -261.204456)
		(width 0.18288)
		(layer "In2.Cu")
		(net "M_F_CPU0_SA_CA<2>")
	)
	(segment
		(start 417.47948 -263.285224)
		(end 417.206176 -263.285224)
		(width 0.18288)
		(layer "In2.Cu")
		(net "M_F_CPU0_SA_CA<2>")
	)
	(segment
		(start 420.237666 -263.878568)
		(end 419.86327 -263.504172)
		(width 0.18288)
		(layer "In2.Cu")
		(net "M_F_CPU0_SA_CA<2>")
	)
	(segment
		(start 402.967698 -258.170172)
		(end 396.272258 -258.170172)
		(width 0.18288)
		(layer "In2.Cu")
		(net "M_F_CPU0_SA_CA<2>")
	)
	(segment
		(start 404.075392 -259.220462)
		(end 404.218902 -259.076698)
		(width 0.18288)
		(layer "In2.Cu")
		(net "M_F_CPU0_SA_CA<2>")
	)
	(segment
		(start 405.163782 -260.021578)
		(end 405.163782 -259.795518)
		(width 0.18288)
		(layer "In2.Cu")
		(net "M_F_CPU0_SA_CA<2>")
	)
	(segment
		(start 408.800554 -260.837426)
		(end 407.83891 -260.837426)
		(width 0.18288)
		(layer "In2.Cu")
		(net "M_F_CPU0_SA_CA<2>")
	)
	(segment
		(start 413.748728 -261.832852)
		(end 413.139128 -261.223252)
		(width 0.18288)
		(layer "In2.Cu")
		(net "M_F_CPU0_SA_CA<2>")
	)
	(segment
		(start 382.997964 -257.499612)
		(end 382.983232 -257.490976)
		(width 0.088646)
		(layer "In2.Cu")
		(net "M_F_CPU0_SA_CA<2>")
	)
	(segment
		(start 419.581076 -263.504172)
		(end 418.910516 -262.833612)
		(width 0.18288)
		(layer "In2.Cu")
		(net "M_F_CPU0_SA_CA<2>")
	)
	(segment
		(start 384.877564 -257.499612)
		(end 384.862832 -257.490976)
		(width 0.088646)
		(layer "In2.Cu")
		(net "M_F_CPU0_SA_CA<2>")
	)
	(segment
		(start 405.020272 -260.165342)
		(end 405.163782 -260.021578)
		(width 0.18288)
		(layer "In2.Cu")
		(net "M_F_CPU0_SA_CA<2>")
	)
	(segment
		(start 405.163782 -259.795518)
		(end 404.917402 -259.549138)
		(width 0.18288)
		(layer "In2.Cu")
		(net "M_F_CPU0_SA_CA<2>")
	)
	(segment
		(start 420.659814 -264.466578)
		(end 420.659814 -264.200132)
		(width 0.18288)
		(layer "In2.Cu")
		(net "M_F_CPU0_SA_CA<2>")
	)
	(segment
		(start 404.691342 -259.549138)
		(end 404.547832 -259.692902)
		(width 0.18288)
		(layer "In2.Cu")
		(net "M_F_CPU0_SA_CA<2>")
	)
	(segment
		(start 407.274776 -260.273292)
		(end 406.228296 -260.273292)
		(width 0.18288)
		(layer "In2.Cu")
		(net "M_F_CPU0_SA_CA<2>")
	)
	(segment
		(start 387.331712 -257.407918)
		(end 387.146546 -257.484626)
		(width 0.088646)
		(layer "In2.Cu")
		(net "M_F_CPU0_SA_CA<2>")
	)
	(segment
		(start 418.910516 -262.833612)
		(end 417.931092 -262.833612)
		(width 0.18288)
		(layer "In2.Cu")
		(net "M_F_CPU0_SA_CA<2>")
	)
	(segment
		(start 409.06573 -261.561072)
		(end 408.914092 -261.409434)
		(width 0.18288)
		(layer "In2.Cu")
		(net "M_F_CPU0_SA_CA<2>")
	)
	(segment
		(start 388.840218 -257.407918)
		(end 387.331712 -257.407918)
		(width 0.088646)
		(layer "In2.Cu")
		(net "M_F_CPU0_SA_CA<2>")
	)
	(segment
		(start 405.808942 -260.692646)
		(end 405.321516 -260.692646)
		(width 0.18288)
		(layer "In2.Cu")
		(net "M_F_CPU0_SA_CA<2>")
	)
	(segment
		(start 404.075392 -259.446522)
		(end 404.075392 -259.220462)
		(width 0.18288)
		(layer "In2.Cu")
		(net "M_F_CPU0_SA_CA<2>")
	)
	(segment
		(start 415.266124 -261.403338)
		(end 414.83661 -261.832852)
		(width 0.18288)
		(layer "In2.Cu")
		(net "M_F_CPU0_SA_CA<2>")
	)
	(segment
		(start 385.817364 -257.499612)
		(end 385.802632 -257.490976)
		(width 0.088646)
		(layer "In2.Cu")
		(net "M_F_CPU0_SA_CA<2>")
	)
	(segment
		(start 414.83661 -261.832852)
		(end 413.748728 -261.832852)
		(width 0.18288)
		(layer "In2.Cu")
		(net "M_F_CPU0_SA_CA<2>")
	)
	(segment
		(start 412.329122 -261.761732)
		(end 411.97784 -261.761732)
		(width 0.18288)
		(layer "In2.Cu")
		(net "M_F_CPU0_SA_CA<2>")
	)
	(segment
		(start 417.206176 -263.285224)
		(end 415.993834 -262.072882)
		(width 0.18288)
		(layer "In2.Cu")
		(net "M_F_CPU0_SA_CA<2>")
	)
	(segment
		(start 415.993834 -261.857998)
		(end 415.539174 -261.403338)
		(width 0.18288)
		(layer "In2.Cu")
		(net "M_F_CPU0_SA_CA<2>")
	)
	(segment
		(start 408.914092 -260.950964)
		(end 408.800554 -260.837426)
		(width 0.18288)
		(layer "In2.Cu")
		(net "M_F_CPU0_SA_CA<2>")
	)
	(segment
		(start 381.67691 -257.276092)
		(end 381.576072 -257.175254)
		(width 0.088646)
		(layer "In2.Cu")
		(net "M_F_CPU0_SA_CA<2>")
	)
	(segment
		(start 411.97784 -261.761732)
		(end 411.420564 -261.204456)
		(width 0.18288)
		(layer "In2.Cu")
		(net "M_F_CPU0_SA_CA<2>")
	)
	(segment
		(start 412.489142 -261.601712)
		(end 412.329122 -261.761732)
		(width 0.18288)
		(layer "In2.Cu")
		(net "M_F_CPU0_SA_CA<2>")
	)
	(segment
		(start 409.916376 -261.561072)
		(end 409.06573 -261.561072)
		(width 0.18288)
		(layer "In2.Cu")
		(net "M_F_CPU0_SA_CA<2>")
	)
	(segment
		(start 413.139128 -261.223252)
		(end 412.590996 -261.223252)
		(width 0.18288)
		(layer "In2.Cu")
		(net "M_F_CPU0_SA_CA<2>")
	)
	(segment
		(start 406.228296 -260.273292)
		(end 405.808942 -260.692646)
		(width 0.18288)
		(layer "In2.Cu")
		(net "M_F_CPU0_SA_CA<2>")
	)
	(segment
		(start 407.83891 -260.837426)
		(end 407.274776 -260.273292)
		(width 0.18288)
		(layer "In2.Cu")
		(net "M_F_CPU0_SA_CA<2>")
	)
	(segment
		(start 404.917402 -259.549138)
		(end 404.691342 -259.549138)
		(width 0.18288)
		(layer "In2.Cu")
		(net "M_F_CPU0_SA_CA<2>")
	)
	(segment
		(start 415.539174 -261.403338)
		(end 415.266124 -261.403338)
		(width 0.18288)
		(layer "In2.Cu")
		(net "M_F_CPU0_SA_CA<2>")
	)
	(segment
		(start 382.058164 -257.499612)
		(end 381.67691 -257.276092)
		(width 0.088646)
		(layer "In2.Cu")
		(net "M_F_CPU0_SA_CA<2>")
	)
	(segment
		(start 387.146546 -257.484626)
		(end 387.13156 -257.499612)
		(width 0.088646)
		(layer "In2.Cu")
		(net "M_F_CPU0_SA_CA<2>")
	)
	(segment
		(start 396.272258 -258.170172)
		(end 396.084298 -257.982212)
		(width 0.18288)
		(layer "In2.Cu")
		(net "M_F_CPU0_SA_CA<2>")
	)
	(segment
		(start 404.218902 -258.850638)
		(end 403.942042 -258.573778)
		(width 0.18288)
		(layer "In2.Cu")
		(net "M_F_CPU0_SA_CA<2>")
	)
	(segment
		(start 405.321516 -260.692646)
		(end 405.020272 -260.391402)
		(width 0.18288)
		(layer "In2.Cu")
		(net "M_F_CPU0_SA_CA<2>")
	)
	(segment
		(start 403.942042 -258.573778)
		(end 402.967698 -258.170172)
		(width 0.18288)
		(layer "In2.Cu")
		(net "M_F_CPU0_SA_CA<2>")
	)
	(segment
		(start 405.020272 -260.391402)
		(end 405.020272 -260.165342)
		(width 0.18288)
		(layer "In2.Cu")
		(net "M_F_CPU0_SA_CA<2>")
	)
	(arc
		(start 383.37236 -257.499612)
		(mid 383.185162 -257.549755)
		(end 382.997964 -257.499612)
		(width 0.088646)
		(layer "In2.Cu")
		(net "M_F_CPU0_SA_CA<2>")
	)
	(arc
		(start 385.802632 -257.490976)
		(mid 385.526157 -257.423656)
		(end 385.25196 -257.499612)
		(width 0.088646)
		(layer "In2.Cu")
		(net "M_F_CPU0_SA_CA<2>")
	)
	(arc
		(start 382.43256 -257.499612)
		(mid 382.245362 -257.549755)
		(end 382.058164 -257.499612)
		(width 0.088646)
		(layer "In2.Cu")
		(net "M_F_CPU0_SA_CA<2>")
	)
	(arc
		(start 382.983232 -257.490976)
		(mid 382.706757 -257.423656)
		(end 382.43256 -257.499612)
		(width 0.088646)
		(layer "In2.Cu")
		(net "M_F_CPU0_SA_CA<2>")
	)
	(arc
		(start 383.937764 -257.499612)
		(mid 383.655062 -257.423836)
		(end 383.37236 -257.499612)
		(width 0.088646)
		(layer "In2.Cu")
		(net "M_F_CPU0_SA_CA<2>")
	)
	(arc
		(start 386.742432 -257.490976)
		(mid 386.465957 -257.423656)
		(end 386.19176 -257.499612)
		(width 0.088646)
		(layer "In2.Cu")
		(net "M_F_CPU0_SA_CA<2>")
	)
	(arc
		(start 384.862832 -257.490976)
		(mid 384.586357 -257.423656)
		(end 384.31216 -257.499612)
		(width 0.088646)
		(layer "In2.Cu")
		(net "M_F_CPU0_SA_CA<2>")
	)
	(arc
		(start 385.25196 -257.499612)
		(mid 385.064762 -257.549755)
		(end 384.877564 -257.499612)
		(width 0.088646)
		(layer "In2.Cu")
		(net "M_F_CPU0_SA_CA<2>")
	)
	(arc
		(start 386.19176 -257.499612)
		(mid 386.004562 -257.549755)
		(end 385.817364 -257.499612)
		(width 0.088646)
		(layer "In2.Cu")
		(net "M_F_CPU0_SA_CA<2>")
	)
	(arc
		(start 384.31216 -257.499612)
		(mid 384.124962 -257.549755)
		(end 383.937764 -257.499612)
		(width 0.088646)
		(layer "In2.Cu")
		(net "M_F_CPU0_SA_CA<2>")
	)
	(arc
		(start 387.13156 -257.499612)
		(mid 386.944362 -257.549755)
		(end 386.757164 -257.499612)
		(width 0.088646)
		(layer "In2.Cu")
		(net "M_F_CPU0_SA_CA<2>")
	)
	(segment
		(start 424.759882 -265.316716)
		(end 425.940982 -265.316716)
		(width 0.20066)
		(layer "F.Cu")
		(net "M_F_CPU0_SA_CA<1>")
	)
	(segment
		(start 430.669192 -265.749024)
		(end 431.534062 -264.884154)
		(width 0.20066)
		(layer "F.Cu")
		(net "M_F_CPU0_SA_CA<1>")
	)
	(segment
		(start 428.37862 -265.741658)
		(end 430.38776 -265.741658)
		(width 0.1016)
		(layer "F.Cu")
		(net "M_F_CPU0_SA_CA<1>")
	)
	(segment
		(start 428.012352 -265.752326)
		(end 428.363126 -265.752326)
		(width 0.20066)
		(layer "F.Cu")
		(net "M_F_CPU0_SA_CA<1>")
	)
	(segment
		(start 428.367952 -265.752326)
		(end 428.37862 -265.741658)
		(width 0.1016)
		(layer "F.Cu")
		(net "M_F_CPU0_SA_CA<1>")
	)
	(segment
		(start 428.363126 -265.752326)
		(end 428.367952 -265.752326)
		(width 0.101854)
		(layer "F.Cu")
		(net "M_F_CPU0_SA_CA<1>")
	)
	(segment
		(start 383.655062 -257.45313)
		(end 383.655062 -257.98907)
		(width 0.20066)
		(layer "F.Cu")
		(net "M_F_CPU0_SA_CA<1>")
	)
	(segment
		(start 432.37023 -265.316716)
		(end 433.484782 -265.316716)
		(width 0.20066)
		(layer "F.Cu")
		(net "M_F_CPU0_SA_CA<1>")
	)
	(segment
		(start 431.937668 -264.884154)
		(end 432.37023 -265.316716)
		(width 0.20066)
		(layer "F.Cu")
		(net "M_F_CPU0_SA_CA<1>")
	)
	(segment
		(start 431.534062 -264.884154)
		(end 431.937668 -264.884154)
		(width 0.20066)
		(layer "F.Cu")
		(net "M_F_CPU0_SA_CA<1>")
	)
	(segment
		(start 425.940982 -265.316716)
		(end 427.576742 -265.316716)
		(width 0.20066)
		(layer "F.Cu")
		(net "M_F_CPU0_SA_CA<1>")
	)
	(segment
		(start 430.395126 -265.749024)
		(end 430.669192 -265.749024)
		(width 0.20066)
		(layer "F.Cu")
		(net "M_F_CPU0_SA_CA<1>")
	)
	(segment
		(start 430.38776 -265.741658)
		(end 430.395126 -265.749024)
		(width 0.1016)
		(layer "F.Cu")
		(net "M_F_CPU0_SA_CA<1>")
	)
	(segment
		(start 427.576742 -265.316716)
		(end 428.012352 -265.752326)
		(width 0.20066)
		(layer "F.Cu")
		(net "M_F_CPU0_SA_CA<1>")
	)
	(segment
		(start 417.20516 -264.012426)
		(end 415.631122 -262.438388)
		(width 0.18288)
		(layer "In2.Cu")
		(net "M_F_CPU0_SA_CA<1>")
	)
	(segment
		(start 384.797046 -257.673348)
		(end 384.782314 -257.664712)
		(width 0.088646)
		(layer "In2.Cu")
		(net "M_F_CPU0_SA_CA<1>")
	)
	(segment
		(start 423.141394 -264.541762)
		(end 422.79189 -264.891266)
		(width 0.18288)
		(layer "In2.Cu")
		(net "M_F_CPU0_SA_CA<1>")
	)
	(segment
		(start 421.37838 -265.303762)
		(end 421.37838 -265.051286)
		(width 0.18288)
		(layer "In2.Cu")
		(net "M_F_CPU0_SA_CA<1>")
	)
	(segment
		(start 423.536364 -263.668256)
		(end 423.141394 -264.063226)
		(width 0.18288)
		(layer "In2.Cu")
		(net "M_F_CPU0_SA_CA<1>")
	)
	(segment
		(start 421.5384 -265.463782)
		(end 421.37838 -265.303762)
		(width 0.18288)
		(layer "In2.Cu")
		(net "M_F_CPU0_SA_CA<1>")
	)
	(segment
		(start 422.100502 -265.084306)
		(end 422.100502 -265.270742)
		(width 0.18288)
		(layer "In2.Cu")
		(net "M_F_CPU0_SA_CA<1>")
	)
	(segment
		(start 405.948388 -261.472172)
		(end 405.377904 -261.472172)
		(width 0.18288)
		(layer "In2.Cu")
		(net "M_F_CPU0_SA_CA<1>")
	)
	(segment
		(start 422.293542 -264.891266)
		(end 422.100502 -265.084306)
		(width 0.18288)
		(layer "In2.Cu")
		(net "M_F_CPU0_SA_CA<1>")
	)
	(segment
		(start 421.21836 -264.891266)
		(end 420.391082 -264.891266)
		(width 0.18288)
		(layer "In2.Cu")
		(net "M_F_CPU0_SA_CA<1>")
	)
	(segment
		(start 423.997374 -263.668256)
		(end 423.536364 -263.668256)
		(width 0.18288)
		(layer "In2.Cu")
		(net "M_F_CPU0_SA_CA<1>")
	)
	(segment
		(start 419.652196 -264.012426)
		(end 417.20516 -264.012426)
		(width 0.18288)
		(layer "In2.Cu")
		(net "M_F_CPU0_SA_CA<1>")
	)
	(segment
		(start 408.333194 -261.947406)
		(end 408.333194 -261.518146)
		(width 0.18288)
		(layer "In2.Cu")
		(net "M_F_CPU0_SA_CA<1>")
	)
	(segment
		(start 411.754574 -262.29945)
		(end 411.596586 -262.457438)
		(width 0.18288)
		(layer "In2.Cu")
		(net "M_F_CPU0_SA_CA<1>")
	)
	(segment
		(start 395.65707 -258.254246)
		(end 394.472414 -257.763518)
		(width 0.18288)
		(layer "In2.Cu")
		(net "M_F_CPU0_SA_CA<1>")
	)
	(segment
		(start 408.333194 -261.518146)
		(end 408.173174 -261.358126)
		(width 0.18288)
		(layer "In2.Cu")
		(net "M_F_CPU0_SA_CA<1>")
	)
	(segment
		(start 415.250122 -262.438388)
		(end 415.16173 -262.349996)
		(width 0.18288)
		(layer "In2.Cu")
		(net "M_F_CPU0_SA_CA<1>")
	)
	(segment
		(start 421.37838 -265.051286)
		(end 421.21836 -264.891266)
		(width 0.18288)
		(layer "In2.Cu")
		(net "M_F_CPU0_SA_CA<1>")
	)
	(segment
		(start 422.79189 -264.891266)
		(end 422.293542 -264.891266)
		(width 0.18288)
		(layer "In2.Cu")
		(net "M_F_CPU0_SA_CA<1>")
	)
	(segment
		(start 415.16173 -262.349996)
		(end 412.659322 -262.349996)
		(width 0.18288)
		(layer "In2.Cu")
		(net "M_F_CPU0_SA_CA<1>")
	)
	(segment
		(start 412.659322 -262.349996)
		(end 412.608776 -262.29945)
		(width 0.18288)
		(layer "In2.Cu")
		(net "M_F_CPU0_SA_CA<1>")
	)
	(segment
		(start 424.157394 -264.435082)
		(end 424.157394 -263.828276)
		(width 0.18288)
		(layer "In2.Cu")
		(net "M_F_CPU0_SA_CA<1>")
	)
	(segment
		(start 407.685494 -261.358126)
		(end 407.418794 -261.624826)
		(width 0.18288)
		(layer "In2.Cu")
		(net "M_F_CPU0_SA_CA<1>")
	)
	(segment
		(start 420.125144 -264.625328)
		(end 420.125144 -264.485374)
		(width 0.18288)
		(layer "In2.Cu")
		(net "M_F_CPU0_SA_CA<1>")
	)
	(segment
		(start 424.759882 -265.316716)
		(end 424.759882 -265.03757)
		(width 0.18288)
		(layer "In2.Cu")
		(net "M_F_CPU0_SA_CA<1>")
	)
	(segment
		(start 421.907462 -265.463782)
		(end 421.5384 -265.463782)
		(width 0.18288)
		(layer "In2.Cu")
		(net "M_F_CPU0_SA_CA<1>")
	)
	(segment
		(start 410.112718 -262.457438)
		(end 409.762706 -262.107426)
		(width 0.18288)
		(layer "In2.Cu")
		(net "M_F_CPU0_SA_CA<1>")
	)
	(segment
		(start 408.493214 -262.107426)
		(end 408.333194 -261.947406)
		(width 0.18288)
		(layer "In2.Cu")
		(net "M_F_CPU0_SA_CA<1>")
	)
	(segment
		(start 423.141394 -264.063226)
		(end 423.141394 -264.541762)
		(width 0.18288)
		(layer "In2.Cu")
		(net "M_F_CPU0_SA_CA<1>")
	)
	(segment
		(start 394.472414 -257.763518)
		(end 388.840218 -257.763518)
		(width 0.18288)
		(layer "In2.Cu")
		(net "M_F_CPU0_SA_CA<1>")
	)
	(segment
		(start 409.762706 -262.107426)
		(end 408.493214 -262.107426)
		(width 0.18288)
		(layer "In2.Cu")
		(net "M_F_CPU0_SA_CA<1>")
	)
	(segment
		(start 384.407918 -257.664712)
		(end 384.01879 -257.891026)
		(width 0.088646)
		(layer "In2.Cu")
		(net "M_F_CPU0_SA_CA<1>")
	)
	(segment
		(start 424.759882 -265.03757)
		(end 424.157394 -264.435082)
		(width 0.18288)
		(layer "In2.Cu")
		(net "M_F_CPU0_SA_CA<1>")
	)
	(segment
		(start 406.101042 -261.624826)
		(end 405.948388 -261.472172)
		(width 0.18288)
		(layer "In2.Cu")
		(net "M_F_CPU0_SA_CA<1>")
	)
	(segment
		(start 422.100502 -265.270742)
		(end 421.907462 -265.463782)
		(width 0.18288)
		(layer "In2.Cu")
		(net "M_F_CPU0_SA_CA<1>")
	)
	(segment
		(start 385.736846 -257.673348)
		(end 385.722114 -257.664712)
		(width 0.088646)
		(layer "In2.Cu")
		(net "M_F_CPU0_SA_CA<1>")
	)
	(segment
		(start 420.125144 -264.485374)
		(end 419.652196 -264.012426)
		(width 0.18288)
		(layer "In2.Cu")
		(net "M_F_CPU0_SA_CA<1>")
	)
	(segment
		(start 388.004304 -257.613912)
		(end 387.417056 -257.613912)
		(width 0.088646)
		(layer "In2.Cu")
		(net "M_F_CPU0_SA_CA<1>")
	)
	(segment
		(start 388.840218 -257.763518)
		(end 388.15391 -257.763518)
		(width 0.088646)
		(layer "In2.Cu")
		(net "M_F_CPU0_SA_CA<1>")
	)
	(segment
		(start 408.173174 -261.358126)
		(end 407.685494 -261.358126)
		(width 0.18288)
		(layer "In2.Cu")
		(net "M_F_CPU0_SA_CA<1>")
	)
	(segment
		(start 388.15391 -257.763518)
		(end 388.004304 -257.613912)
		(width 0.088646)
		(layer "In2.Cu")
		(net "M_F_CPU0_SA_CA<1>")
	)
	(segment
		(start 396.194026 -258.700524)
		(end 396.193772 -258.700778)
		(width 0.18288)
		(layer "In2.Cu")
		(net "M_F_CPU0_SA_CA<1>")
	)
	(segment
		(start 396.193772 -258.700778)
		(end 396.103602 -258.700778)
		(width 0.18288)
		(layer "In2.Cu")
		(net "M_F_CPU0_SA_CA<1>")
	)
	(segment
		(start 386.676646 -257.673348)
		(end 386.661914 -257.664712)
		(width 0.088646)
		(layer "In2.Cu")
		(net "M_F_CPU0_SA_CA<1>")
	)
	(segment
		(start 405.377904 -261.472172)
		(end 402.606256 -258.700524)
		(width 0.18288)
		(layer "In2.Cu")
		(net "M_F_CPU0_SA_CA<1>")
	)
	(segment
		(start 415.631122 -262.438388)
		(end 415.250122 -262.438388)
		(width 0.18288)
		(layer "In2.Cu")
		(net "M_F_CPU0_SA_CA<1>")
	)
	(segment
		(start 420.391082 -264.891266)
		(end 420.125144 -264.625328)
		(width 0.18288)
		(layer "In2.Cu")
		(net "M_F_CPU0_SA_CA<1>")
	)
	(segment
		(start 402.606256 -258.700524)
		(end 396.194026 -258.700524)
		(width 0.18288)
		(layer "In2.Cu")
		(net "M_F_CPU0_SA_CA<1>")
	)
	(segment
		(start 424.157394 -263.828276)
		(end 423.997374 -263.668256)
		(width 0.18288)
		(layer "In2.Cu")
		(net "M_F_CPU0_SA_CA<1>")
	)
	(segment
		(start 411.596586 -262.457438)
		(end 410.112718 -262.457438)
		(width 0.18288)
		(layer "In2.Cu")
		(net "M_F_CPU0_SA_CA<1>")
	)
	(segment
		(start 407.418794 -261.624826)
		(end 406.101042 -261.624826)
		(width 0.18288)
		(layer "In2.Cu")
		(net "M_F_CPU0_SA_CA<1>")
	)
	(segment
		(start 412.608776 -262.29945)
		(end 411.754574 -262.29945)
		(width 0.18288)
		(layer "In2.Cu")
		(net "M_F_CPU0_SA_CA<1>")
	)
	(segment
		(start 396.103602 -258.700778)
		(end 395.65707 -258.254246)
		(width 0.18288)
		(layer "In2.Cu")
		(net "M_F_CPU0_SA_CA<1>")
	)
	(arc
		(start 385.722114 -257.664712)
		(mid 385.534916 -257.614569)
		(end 385.347718 -257.664712)
		(width 0.088646)
		(layer "In2.Cu")
		(net "M_F_CPU0_SA_CA<1>")
	)
	(arc
		(start 386.287518 -257.664712)
		(mid 386.013319 -257.740547)
		(end 385.736846 -257.673348)
		(width 0.088646)
		(layer "In2.Cu")
		(net "M_F_CPU0_SA_CA<1>")
	)
	(arc
		(start 387.417056 -257.613912)
		(mid 387.31885 -257.62684)
		(end 387.227318 -257.664712)
		(width 0.088646)
		(layer "In2.Cu")
		(net "M_F_CPU0_SA_CA<1>")
	)
	(arc
		(start 387.227318 -257.664712)
		(mid 386.953119 -257.740547)
		(end 386.676646 -257.673348)
		(width 0.088646)
		(layer "In2.Cu")
		(net "M_F_CPU0_SA_CA<1>")
	)
	(arc
		(start 386.661914 -257.664712)
		(mid 386.474716 -257.614569)
		(end 386.287518 -257.664712)
		(width 0.088646)
		(layer "In2.Cu")
		(net "M_F_CPU0_SA_CA<1>")
	)
	(arc
		(start 384.01879 -257.891026)
		(mid 383.843423 -257.964161)
		(end 383.655062 -257.98907)
		(width 0.088646)
		(layer "In2.Cu")
		(net "M_F_CPU0_SA_CA<1>")
	)
	(arc
		(start 385.347718 -257.664712)
		(mid 385.073519 -257.740547)
		(end 384.797046 -257.673348)
		(width 0.088646)
		(layer "In2.Cu")
		(net "M_F_CPU0_SA_CA<1>")
	)
	(arc
		(start 384.782314 -257.664712)
		(mid 384.595116 -257.614569)
		(end 384.407918 -257.664712)
		(width 0.088646)
		(layer "In2.Cu")
		(net "M_F_CPU0_SA_CA<1>")
	)
	(segment
		(start 423.400728 -265.672316)
		(end 423.726102 -265.672316)
		(width 0.20066)
		(layer "F.Cu")
		(net "M_F_CPU0_SA_CA<0>")
	)
	(segment
		(start 423.726102 -265.672316)
		(end 424.645328 -266.591542)
		(width 0.20066)
		(layer "F.Cu")
		(net "M_F_CPU0_SA_CA<0>")
	)
	(segment
		(start 426.938948 -266.591542)
		(end 426.951394 -266.603988)
		(width 0.1016)
		(layer "F.Cu")
		(net "M_F_CPU0_SA_CA<0>")
	)
	(segment
		(start 427.367446 -266.603988)
		(end 427.805088 -266.166346)
		(width 0.20066)
		(layer "F.Cu")
		(net "M_F_CPU0_SA_CA<0>")
	)
	(segment
		(start 422.906444 -266.1666)
		(end 423.400728 -265.672316)
		(width 0.20066)
		(layer "F.Cu")
		(net "M_F_CPU0_SA_CA<0>")
	)
	(segment
		(start 427.805088 -266.166346)
		(end 429.38446 -266.166346)
		(width 0.20066)
		(layer "F.Cu")
		(net "M_F_CPU0_SA_CA<0>")
	)
	(segment
		(start 421.840914 -266.1666)
		(end 422.906444 -266.1666)
		(width 0.20066)
		(layer "F.Cu")
		(net "M_F_CPU0_SA_CA<0>")
	)
	(segment
		(start 424.645328 -266.591542)
		(end 424.75277 -266.591542)
		(width 0.20066)
		(layer "F.Cu")
		(net "M_F_CPU0_SA_CA<0>")
	)
	(segment
		(start 424.75277 -266.591542)
		(end 424.766486 -266.591542)
		(width 0.101854)
		(layer "F.Cu")
		(net "M_F_CPU0_SA_CA<0>")
	)
	(segment
		(start 429.38446 -266.166346)
		(end 429.384714 -266.1666)
		(width 0.20066)
		(layer "F.Cu")
		(net "M_F_CPU0_SA_CA<0>")
	)
	(segment
		(start 424.766486 -266.591542)
		(end 426.938948 -266.591542)
		(width 0.1016)
		(layer "F.Cu")
		(net "M_F_CPU0_SA_CA<0>")
	)
	(segment
		(start 426.951394 -266.603988)
		(end 427.367446 -266.603988)
		(width 0.20066)
		(layer "F.Cu")
		(net "M_F_CPU0_SA_CA<0>")
	)
	(segment
		(start 380.835916 -257.988816)
		(end 380.835662 -257.98907)
		(width 0.20066)
		(layer "F.Cu")
		(net "M_F_CPU0_SA_CA<0>")
	)
	(segment
		(start 380.835916 -257.45313)
		(end 380.835916 -257.988816)
		(width 0.20066)
		(layer "F.Cu")
		(net "M_F_CPU0_SA_CA<0>")
	)
	(segment
		(start 420.659814 -266.1666)
		(end 421.840914 -266.1666)
		(width 0.20066)
		(layer "F.Cu")
		(net "M_F_CPU0_SA_CA<0>")
	)
	(segment
		(start 419.930072 -265.169396)
		(end 419.499288 -265.169396)
		(width 0.18288)
		(layer "In2.Cu")
		(net "M_F_CPU0_SA_CA<0>")
	)
	(segment
		(start 419.499288 -265.169396)
		(end 418.855144 -264.525252)
		(width 0.18288)
		(layer "In2.Cu")
		(net "M_F_CPU0_SA_CA<0>")
	)
	(segment
		(start 405.820626 -262.443214)
		(end 405.219916 -262.443214)
		(width 0.18288)
		(layer "In2.Cu")
		(net "M_F_CPU0_SA_CA<0>")
	)
	(segment
		(start 409.762706 -263.404096)
		(end 409.489656 -263.404096)
		(width 0.18288)
		(layer "In2.Cu")
		(net "M_F_CPU0_SA_CA<0>")
	)
	(segment
		(start 405.219916 -262.443214)
		(end 404.789894 -262.013192)
		(width 0.18288)
		(layer "In2.Cu")
		(net "M_F_CPU0_SA_CA<0>")
	)
	(segment
		(start 420.659814 -266.1666)
		(end 420.659814 -265.899138)
		(width 0.18288)
		(layer "In2.Cu")
		(net "M_F_CPU0_SA_CA<0>")
	)
	(segment
		(start 388.267448 -258.113276)
		(end 388.216648 -258.164076)
		(width 0.088646)
		(layer "In2.Cu")
		(net "M_F_CPU0_SA_CA<0>")
	)
	(segment
		(start 413.759904 -263.555226)
		(end 413.083248 -262.87857)
		(width 0.18288)
		(layer "In2.Cu")
		(net "M_F_CPU0_SA_CA<0>")
	)
	(segment
		(start 394.359892 -258.113276)
		(end 388.840218 -258.113276)
		(width 0.18288)
		(layer "In2.Cu")
		(net "M_F_CPU0_SA_CA<0>")
	)
	(segment
		(start 402.591524 -260.043422)
		(end 402.766022 -259.868924)
		(width 0.18288)
		(layer "In2.Cu")
		(net "M_F_CPU0_SA_CA<0>")
	)
	(segment
		(start 412.479744 -262.87857)
		(end 412.08198 -263.276334)
		(width 0.18288)
		(layer "In2.Cu")
		(net "M_F_CPU0_SA_CA<0>")
	)
	(segment
		(start 404.085806 -261.537704)
		(end 403.81301 -261.537704)
		(width 0.18288)
		(layer "In2.Cu")
		(net "M_F_CPU0_SA_CA<0>")
	)
	(segment
		(start 413.083248 -262.87857)
		(end 412.479744 -262.87857)
		(width 0.18288)
		(layer "In2.Cu")
		(net "M_F_CPU0_SA_CA<0>")
	)
	(segment
		(start 407.571194 -262.310626)
		(end 405.953214 -262.310626)
		(width 0.18288)
		(layer "In2.Cu")
		(net "M_F_CPU0_SA_CA<0>")
	)
	(segment
		(start 403.76221 -260.592316)
		(end 403.536912 -260.367018)
		(width 0.18288)
		(layer "In2.Cu")
		(net "M_F_CPU0_SA_CA<0>")
	)
	(segment
		(start 388.840218 -258.113276)
		(end 388.267448 -258.113276)
		(width 0.088646)
		(layer "In2.Cu")
		(net "M_F_CPU0_SA_CA<0>")
	)
	(segment
		(start 382.480566 -258.396232)
		(end 382.479804 -258.395978)
		(width 0.088646)
		(layer "In2.Cu")
		(net "M_F_CPU0_SA_CA<0>")
	)
	(segment
		(start 396.048484 -259.23113)
		(end 395.334236 -258.516882)
		(width 0.18288)
		(layer "In2.Cu")
		(net "M_F_CPU0_SA_CA<0>")
	)
	(segment
		(start 402.816822 -260.541516)
		(end 402.591524 -260.316218)
		(width 0.18288)
		(layer "In2.Cu")
		(net "M_F_CPU0_SA_CA<0>")
	)
	(segment
		(start 403.81301 -261.537704)
		(end 403.587712 -261.312406)
		(width 0.18288)
		(layer "In2.Cu")
		(net "M_F_CPU0_SA_CA<0>")
	)
	(segment
		(start 411.80893 -263.276334)
		(end 411.518608 -262.986012)
		(width 0.18288)
		(layer "In2.Cu")
		(net "M_F_CPU0_SA_CA<0>")
	)
	(segment
		(start 403.76221 -260.865112)
		(end 403.76221 -260.592316)
		(width 0.18288)
		(layer "In2.Cu")
		(net "M_F_CPU0_SA_CA<0>")
	)
	(segment
		(start 403.587712 -261.03961)
		(end 403.76221 -260.865112)
		(width 0.18288)
		(layer "In2.Cu")
		(net "M_F_CPU0_SA_CA<0>")
	)
	(segment
		(start 402.766022 -259.868924)
		(end 402.766022 -259.596128)
		(width 0.18288)
		(layer "In2.Cu")
		(net "M_F_CPU0_SA_CA<0>")
	)
	(segment
		(start 403.587712 -261.312406)
		(end 403.587712 -261.03961)
		(width 0.18288)
		(layer "In2.Cu")
		(net "M_F_CPU0_SA_CA<0>")
	)
	(segment
		(start 414.694116 -263.555226)
		(end 413.759904 -263.555226)
		(width 0.18288)
		(layer "In2.Cu")
		(net "M_F_CPU0_SA_CA<0>")
	)
	(segment
		(start 396.194026 -259.230876)
		(end 396.193772 -259.23113)
		(width 0.18288)
		(layer "In2.Cu")
		(net "M_F_CPU0_SA_CA<0>")
	)
	(segment
		(start 403.536912 -260.367018)
		(end 403.264116 -260.367018)
		(width 0.18288)
		(layer "In2.Cu")
		(net "M_F_CPU0_SA_CA<0>")
	)
	(segment
		(start 402.591524 -260.316218)
		(end 402.591524 -260.043422)
		(width 0.18288)
		(layer "In2.Cu")
		(net "M_F_CPU0_SA_CA<0>")
	)
	(segment
		(start 415.578544 -263.139174)
		(end 415.110168 -263.139174)
		(width 0.18288)
		(layer "In2.Cu")
		(net "M_F_CPU0_SA_CA<0>")
	)
	(segment
		(start 388.216648 -258.164076)
		(end 388.158482 -258.164076)
		(width 0.088646)
		(layer "In2.Cu")
		(net "M_F_CPU0_SA_CA<0>")
	)
	(segment
		(start 416.685984 -264.514584)
		(end 416.685984 -264.246614)
		(width 0.18288)
		(layer "In2.Cu")
		(net "M_F_CPU0_SA_CA<0>")
	)
	(segment
		(start 385.736846 -258.304792)
		(end 385.722114 -258.313428)
		(width 0.088646)
		(layer "In2.Cu")
		(net "M_F_CPU0_SA_CA<0>")
	)
	(segment
		(start 417.780978 -264.90295)
		(end 417.07435 -264.90295)
		(width 0.18288)
		(layer "In2.Cu")
		(net "M_F_CPU0_SA_CA<0>")
	)
	(segment
		(start 396.193772 -259.23113)
		(end 396.048484 -259.23113)
		(width 0.18288)
		(layer "In2.Cu")
		(net "M_F_CPU0_SA_CA<0>")
	)
	(segment
		(start 404.789894 -261.62)
		(end 404.5331 -261.363206)
		(width 0.18288)
		(layer "In2.Cu")
		(net "M_F_CPU0_SA_CA<0>")
	)
	(segment
		(start 395.334236 -258.516882)
		(end 394.359892 -258.113276)
		(width 0.18288)
		(layer "In2.Cu")
		(net "M_F_CPU0_SA_CA<0>")
	)
	(segment
		(start 407.88844 -262.627872)
		(end 407.571194 -262.310626)
		(width 0.18288)
		(layer "In2.Cu")
		(net "M_F_CPU0_SA_CA<0>")
	)
	(segment
		(start 386.676646 -258.304792)
		(end 386.661914 -258.313428)
		(width 0.088646)
		(layer "In2.Cu")
		(net "M_F_CPU0_SA_CA<0>")
	)
	(segment
		(start 403.264116 -260.367018)
		(end 403.089618 -260.541516)
		(width 0.18288)
		(layer "In2.Cu")
		(net "M_F_CPU0_SA_CA<0>")
	)
	(segment
		(start 381.540766 -258.395978)
		(end 381.540766 -258.396232)
		(width 0.088646)
		(layer "In2.Cu")
		(net "M_F_CPU0_SA_CA<0>")
	)
	(segment
		(start 417.07435 -264.90295)
		(end 416.685984 -264.514584)
		(width 0.18288)
		(layer "In2.Cu")
		(net "M_F_CPU0_SA_CA<0>")
	)
	(segment
		(start 383.852674 -258.307332)
		(end 383.84226 -258.313428)
		(width 0.088646)
		(layer "In2.Cu")
		(net "M_F_CPU0_SA_CA<0>")
	)
	(segment
		(start 411.518608 -262.986012)
		(end 410.18079 -262.986012)
		(width 0.18288)
		(layer "In2.Cu")
		(net "M_F_CPU0_SA_CA<0>")
	)
	(segment
		(start 402.766022 -259.596128)
		(end 402.40077 -259.230876)
		(width 0.18288)
		(layer "In2.Cu")
		(net "M_F_CPU0_SA_CA<0>")
	)
	(segment
		(start 381.540766 -258.396232)
		(end 380.835662 -257.98907)
		(width 0.088646)
		(layer "In2.Cu")
		(net "M_F_CPU0_SA_CA<0>")
	)
	(segment
		(start 418.855144 -264.525252)
		(end 418.158676 -264.525252)
		(width 0.18288)
		(layer "In2.Cu")
		(net "M_F_CPU0_SA_CA<0>")
	)
	(segment
		(start 416.685984 -264.246614)
		(end 415.578544 -263.139174)
		(width 0.18288)
		(layer "In2.Cu")
		(net "M_F_CPU0_SA_CA<0>")
	)
	(segment
		(start 405.953214 -262.310626)
		(end 405.820626 -262.443214)
		(width 0.18288)
		(layer "In2.Cu")
		(net "M_F_CPU0_SA_CA<0>")
	)
	(segment
		(start 415.110168 -263.139174)
		(end 414.694116 -263.555226)
		(width 0.18288)
		(layer "In2.Cu")
		(net "M_F_CPU0_SA_CA<0>")
	)
	(segment
		(start 404.789894 -262.013192)
		(end 404.789894 -261.62)
		(width 0.18288)
		(layer "In2.Cu")
		(net "M_F_CPU0_SA_CA<0>")
	)
	(segment
		(start 408.713432 -262.627872)
		(end 407.88844 -262.627872)
		(width 0.18288)
		(layer "In2.Cu")
		(net "M_F_CPU0_SA_CA<0>")
	)
	(segment
		(start 403.089618 -260.541516)
		(end 402.816822 -260.541516)
		(width 0.18288)
		(layer "In2.Cu")
		(net "M_F_CPU0_SA_CA<0>")
	)
	(segment
		(start 409.489656 -263.404096)
		(end 408.713432 -262.627872)
		(width 0.18288)
		(layer "In2.Cu")
		(net "M_F_CPU0_SA_CA<0>")
	)
	(segment
		(start 410.18079 -262.986012)
		(end 409.762706 -263.404096)
		(width 0.18288)
		(layer "In2.Cu")
		(net "M_F_CPU0_SA_CA<0>")
	)
	(segment
		(start 418.158676 -264.525252)
		(end 417.780978 -264.90295)
		(width 0.18288)
		(layer "In2.Cu")
		(net "M_F_CPU0_SA_CA<0>")
	)
	(segment
		(start 402.40077 -259.230876)
		(end 396.194026 -259.230876)
		(width 0.18288)
		(layer "In2.Cu")
		(net "M_F_CPU0_SA_CA<0>")
	)
	(segment
		(start 420.659814 -265.899138)
		(end 419.930072 -265.169396)
		(width 0.18288)
		(layer "In2.Cu")
		(net "M_F_CPU0_SA_CA<0>")
	)
	(segment
		(start 404.5331 -261.363206)
		(end 404.260304 -261.363206)
		(width 0.18288)
		(layer "In2.Cu")
		(net "M_F_CPU0_SA_CA<0>")
	)
	(segment
		(start 404.260304 -261.363206)
		(end 404.085806 -261.537704)
		(width 0.18288)
		(layer "In2.Cu")
		(net "M_F_CPU0_SA_CA<0>")
	)
	(segment
		(start 384.797046 -258.304792)
		(end 384.782314 -258.313428)
		(width 0.088646)
		(layer "In2.Cu")
		(net "M_F_CPU0_SA_CA<0>")
	)
	(segment
		(start 412.08198 -263.276334)
		(end 411.80893 -263.276334)
		(width 0.18288)
		(layer "In2.Cu")
		(net "M_F_CPU0_SA_CA<0>")
	)
	(arc
		(start 385.722114 -258.313428)
		(mid 385.534916 -258.363571)
		(end 385.347718 -258.313428)
		(width 0.088646)
		(layer "In2.Cu")
		(net "M_F_CPU0_SA_CA<0>")
	)
	(arc
		(start 383.467864 -258.313428)
		(mid 383.201403 -258.30711)
		(end 382.950212 -258.396232)
		(width 0.088646)
		(layer "In2.Cu")
		(net "M_F_CPU0_SA_CA<0>")
	)
	(arc
		(start 382.479804 -258.395978)
		(mid 382.245252 -258.333204)
		(end 382.010666 -258.395978)
		(width 0.088646)
		(layer "In2.Cu")
		(net "M_F_CPU0_SA_CA<0>")
	)
	(arc
		(start 386.661914 -258.313428)
		(mid 386.474716 -258.363571)
		(end 386.287518 -258.313428)
		(width 0.088646)
		(layer "In2.Cu")
		(net "M_F_CPU0_SA_CA<0>")
	)
	(arc
		(start 387.601714 -258.313428)
		(mid 387.414516 -258.363571)
		(end 387.227318 -258.313428)
		(width 0.088646)
		(layer "In2.Cu")
		(net "M_F_CPU0_SA_CA<0>")
	)
	(arc
		(start 388.158482 -258.164076)
		(mid 387.870251 -258.202053)
		(end 387.601714 -258.313428)
		(width 0.088646)
		(layer "In2.Cu")
		(net "M_F_CPU0_SA_CA<0>")
	)
	(arc
		(start 385.347718 -258.313428)
		(mid 385.073489 -258.237503)
		(end 384.797046 -258.304792)
		(width 0.088646)
		(layer "In2.Cu")
		(net "M_F_CPU0_SA_CA<0>")
	)
	(arc
		(start 382.950212 -258.396232)
		(mid 382.715406 -258.459065)
		(end 382.480566 -258.396232)
		(width 0.088646)
		(layer "In2.Cu")
		(net "M_F_CPU0_SA_CA<0>")
	)
	(arc
		(start 387.227318 -258.313428)
		(mid 386.953089 -258.237503)
		(end 386.676646 -258.304792)
		(width 0.088646)
		(layer "In2.Cu")
		(net "M_F_CPU0_SA_CA<0>")
	)
	(arc
		(start 383.84226 -258.313428)
		(mid 383.655062 -258.363571)
		(end 383.467864 -258.313428)
		(width 0.088646)
		(layer "In2.Cu")
		(net "M_F_CPU0_SA_CA<0>")
	)
	(arc
		(start 386.287518 -258.313428)
		(mid 386.013289 -258.237503)
		(end 385.736846 -258.304792)
		(width 0.088646)
		(layer "In2.Cu")
		(net "M_F_CPU0_SA_CA<0>")
	)
	(arc
		(start 384.782314 -258.313428)
		(mid 384.595116 -258.363571)
		(end 384.407918 -258.313428)
		(width 0.088646)
		(layer "In2.Cu")
		(net "M_F_CPU0_SA_CA<0>")
	)
	(arc
		(start 384.407918 -258.313428)
		(mid 384.131105 -258.237592)
		(end 383.852674 -258.307332)
		(width 0.088646)
		(layer "In2.Cu")
		(net "M_F_CPU0_SA_CA<0>")
	)
	(arc
		(start 382.010666 -258.395978)
		(mid 381.775716 -258.458938)
		(end 381.540766 -258.395978)
		(width 0.088646)
		(layer "In2.Cu")
		(net "M_F_CPU0_SA_CA<0>")
	)
	(segment
		(start 425.940982 -260.21665)
		(end 424.836082 -260.21665)
		(width 0.20066)
		(layer "F.Cu")
		(net "M_F_CPU0_CLK_DP<1>")
	)
	(segment
		(start 377.546362 -255.011682)
		(end 377.546362 -255.547368)
		(width 0.20066)
		(layer "F.Cu")
		(net "M_F_CPU0_CLK_DP<1>")
	)
	(segment
		(start 377.546362 -255.547368)
		(end 377.546616 -255.547622)
		(width 0.20066)
		(layer "F.Cu")
		(net "M_F_CPU0_CLK_DP<1>")
	)
	(segment
		(start 396.248382 -254.695706)
		(end 394.933424 -255.240282)
		(width 0.18288)
		(layer "In2.Cu")
		(net "M_F_CPU0_CLK_DP<1>")
	)
	(segment
		(start 388.141972 -254.579882)
		(end 387.756908 -254.739394)
		(width 0.088646)
		(layer "In2.Cu")
		(net "M_F_CPU0_CLK_DP<1>")
	)
	(segment
		(start 379.708664 -256.03708)
		(end 379.693932 -256.045716)
		(width 0.088646)
		(layer "In2.Cu")
		(net "M_F_CPU0_CLK_DP<1>")
	)
	(segment
		(start 417.568888 -256.803398)
		(end 415.862516 -256.554732)
		(width 0.18288)
		(layer "In2.Cu")
		(net "M_F_CPU0_CLK_DP<1>")
	)
	(segment
		(start 423.230802 -258.15798)
		(end 422.251886 -257.817112)
		(width 0.18288)
		(layer "In2.Cu")
		(net "M_F_CPU0_CLK_DP<1>")
	)
	(segment
		(start 388.459218 -254.644906)
		(end 388.394194 -254.579882)
		(width 0.088646)
		(layer "In2.Cu")
		(net "M_F_CPU0_CLK_DP<1>")
	)
	(segment
		(start 407.729182 -256.554732)
		(end 403.241256 -254.695706)
		(width 0.18288)
		(layer "In2.Cu")
		(net "M_F_CPU0_CLK_DP<1>")
	)
	(segment
		(start 377.85929 -255.547622)
		(end 377.546616 -255.547622)
		(width 0.088646)
		(layer "In2.Cu")
		(net "M_F_CPU0_CLK_DP<1>")
	)
	(segment
		(start 424.256454 -259.920232)
		(end 423.95013 -259.613908)
		(width 0.18288)
		(layer "In2.Cu")
		(net "M_F_CPU0_CLK_DP<1>")
	)
	(segment
		(start 423.95013 -259.613908)
		(end 423.408094 -258.335272)
		(width 0.18288)
		(layer "In2.Cu")
		(net "M_F_CPU0_CLK_DP<1>")
	)
	(segment
		(start 424.836082 -260.21665)
		(end 424.539664 -259.920232)
		(width 0.18288)
		(layer "In2.Cu")
		(net "M_F_CPU0_CLK_DP<1>")
	)
	(segment
		(start 392.288776 -255.142746)
		(end 392.288776 -255.143)
		(width 0.18288)
		(layer "In2.Cu")
		(net "M_F_CPU0_CLK_DP<1>")
	)
	(segment
		(start 423.408094 -258.335272)
		(end 423.230802 -258.15798)
		(width 0.18288)
		(layer "In2.Cu")
		(net "M_F_CPU0_CLK_DP<1>")
	)
	(segment
		(start 382.528064 -254.409194)
		(end 382.513332 -254.41783)
		(width 0.088646)
		(layer "In2.Cu")
		(net "M_F_CPU0_CLK_DP<1>")
	)
	(segment
		(start 422.251886 -257.817112)
		(end 419.910514 -257.310382)
		(width 0.18288)
		(layer "In2.Cu")
		(net "M_F_CPU0_CLK_DP<1>")
	)
	(segment
		(start 394.933424 -255.240282)
		(end 393.11834 -255.240282)
		(width 0.18288)
		(layer "In2.Cu")
		(net "M_F_CPU0_CLK_DP<1>")
	)
	(segment
		(start 377.924822 -255.613154)
		(end 377.85929 -255.547622)
		(width 0.088646)
		(layer "In2.Cu")
		(net "M_F_CPU0_CLK_DP<1>")
	)
	(segment
		(start 381.118364 -255.223264)
		(end 381.109474 -255.228344)
		(width 0.088646)
		(layer "In2.Cu")
		(net "M_F_CPU0_CLK_DP<1>")
	)
	(segment
		(start 389.636508 -254.644906)
		(end 388.459218 -254.644906)
		(width 0.18288)
		(layer "In2.Cu")
		(net "M_F_CPU0_CLK_DP<1>")
	)
	(segment
		(start 403.241256 -254.695706)
		(end 396.248382 -254.695706)
		(width 0.18288)
		(layer "In2.Cu")
		(net "M_F_CPU0_CLK_DP<1>")
	)
	(segment
		(start 380.930912 -255.547622)
		(end 380.930912 -255.557528)
		(width 0.088646)
		(layer "In2.Cu")
		(net "M_F_CPU0_CLK_DP<1>")
	)
	(segment
		(start 424.539664 -259.920232)
		(end 424.256454 -259.920232)
		(width 0.18288)
		(layer "In2.Cu")
		(net "M_F_CPU0_CLK_DP<1>")
	)
	(segment
		(start 388.394194 -254.579882)
		(end 388.141972 -254.579882)
		(width 0.088646)
		(layer "In2.Cu")
		(net "M_F_CPU0_CLK_DP<1>")
	)
	(segment
		(start 393.11834 -255.240282)
		(end 392.288776 -255.142746)
		(width 0.18288)
		(layer "In2.Cu")
		(net "M_F_CPU0_CLK_DP<1>")
	)
	(segment
		(start 387.291834 -254.739394)
		(end 387.007862 -254.609854)
		(width 0.088646)
		(layer "In2.Cu")
		(net "M_F_CPU0_CLK_DP<1>")
	)
	(segment
		(start 392.288776 -255.143)
		(end 392.288522 -255.142746)
		(width 0.18288)
		(layer "In2.Cu")
		(net "M_F_CPU0_CLK_DP<1>")
	)
	(segment
		(start 378.768864 -256.03708)
		(end 378.754132 -256.045716)
		(width 0.088646)
		(layer "In2.Cu")
		(net "M_F_CPU0_CLK_DP<1>")
	)
	(segment
		(start 387.007862 -254.609854)
		(end 386.661914 -254.40894)
		(width 0.088646)
		(layer "In2.Cu")
		(net "M_F_CPU0_CLK_DP<1>")
	)
	(segment
		(start 387.756908 -254.739394)
		(end 387.291834 -254.739394)
		(width 0.088646)
		(layer "In2.Cu")
		(net "M_F_CPU0_CLK_DP<1>")
	)
	(segment
		(start 419.910514 -257.310382)
		(end 419.910514 -257.310636)
		(width 0.18288)
		(layer "In2.Cu")
		(net "M_F_CPU0_CLK_DP<1>")
	)
	(segment
		(start 391.461244 -255.04521)
		(end 389.636508 -254.644906)
		(width 0.18288)
		(layer "In2.Cu")
		(net "M_F_CPU0_CLK_DP<1>")
	)
	(segment
		(start 415.862516 -256.554732)
		(end 407.729182 -256.554732)
		(width 0.18288)
		(layer "In2.Cu")
		(net "M_F_CPU0_CLK_DP<1>")
	)
	(segment
		(start 381.401066 -254.724916)
		(end 381.401066 -254.747776)
		(width 0.088646)
		(layer "In2.Cu")
		(net "M_F_CPU0_CLK_DP<1>")
	)
	(segment
		(start 386.286756 -254.40894)
		(end 386.28701 -254.409448)
		(width 0.088646)
		(layer "In2.Cu")
		(net "M_F_CPU0_CLK_DP<1>")
	)
	(segment
		(start 392.288522 -255.142746)
		(end 391.461244 -255.04521)
		(width 0.18288)
		(layer "In2.Cu")
		(net "M_F_CPU0_CLK_DP<1>")
	)
	(segment
		(start 419.910514 -257.310636)
		(end 417.568888 -256.803398)
		(width 0.18288)
		(layer "In2.Cu")
		(net "M_F_CPU0_CLK_DP<1>")
	)
	(arc
		(start 379.693932 -256.045716)
		(mid 379.417457 -256.113036)
		(end 379.14326 -256.03708)
		(width 0.088646)
		(layer "In2.Cu")
		(net "M_F_CPU0_CLK_DP<1>")
	)
	(arc
		(start 378.754132 -256.045716)
		(mid 378.234399 -256.05384)
		(end 377.927616 -255.634236)
		(width 0.088646)
		(layer "In2.Cu")
		(net "M_F_CPU0_CLK_DP<1>")
	)
	(arc
		(start 381.401066 -254.747776)
		(mid 381.321847 -255.022461)
		(end 381.118364 -255.223264)
		(width 0.088646)
		(layer "In2.Cu")
		(net "M_F_CPU0_CLK_DP<1>")
	)
	(arc
		(start 380.930912 -255.557528)
		(mid 380.644037 -256.039613)
		(end 380.08306 -256.03708)
		(width 0.088646)
		(layer "In2.Cu")
		(net "M_F_CPU0_CLK_DP<1>")
	)
	(arc
		(start 384.78206 -254.409194)
		(mid 384.594862 -254.359051)
		(end 384.407664 -254.409194)
		(width 0.088646)
		(layer "In2.Cu")
		(net "M_F_CPU0_CLK_DP<1>")
	)
	(arc
		(start 380.08306 -256.03708)
		(mid 379.895862 -255.986937)
		(end 379.708664 -256.03708)
		(width 0.088646)
		(layer "In2.Cu")
		(net "M_F_CPU0_CLK_DP<1>")
	)
	(arc
		(start 385.347464 -254.409194)
		(mid 385.064762 -254.48497)
		(end 384.78206 -254.409194)
		(width 0.088646)
		(layer "In2.Cu")
		(net "M_F_CPU0_CLK_DP<1>")
	)
	(arc
		(start 386.661914 -254.40894)
		(mid 386.474352 -254.358704)
		(end 386.286756 -254.40894)
		(width 0.088646)
		(layer "In2.Cu")
		(net "M_F_CPU0_CLK_DP<1>")
	)
	(arc
		(start 383.467864 -254.409194)
		(mid 383.185162 -254.48497)
		(end 382.90246 -254.409194)
		(width 0.088646)
		(layer "In2.Cu")
		(net "M_F_CPU0_CLK_DP<1>")
	)
	(arc
		(start 382.90246 -254.409194)
		(mid 382.715262 -254.359051)
		(end 382.528064 -254.409194)
		(width 0.088646)
		(layer "In2.Cu")
		(net "M_F_CPU0_CLK_DP<1>")
	)
	(arc
		(start 384.407664 -254.409194)
		(mid 384.124962 -254.48497)
		(end 383.84226 -254.409194)
		(width 0.088646)
		(layer "In2.Cu")
		(net "M_F_CPU0_CLK_DP<1>")
	)
	(arc
		(start 381.96266 -254.409194)
		(mid 381.591937 -254.407102)
		(end 381.401066 -254.724916)
		(width 0.088646)
		(layer "In2.Cu")
		(net "M_F_CPU0_CLK_DP<1>")
	)
	(arc
		(start 383.84226 -254.409194)
		(mid 383.655062 -254.359051)
		(end 383.467864 -254.409194)
		(width 0.088646)
		(layer "In2.Cu")
		(net "M_F_CPU0_CLK_DP<1>")
	)
	(arc
		(start 382.513332 -254.41783)
		(mid 382.236857 -254.48515)
		(end 381.96266 -254.409194)
		(width 0.088646)
		(layer "In2.Cu")
		(net "M_F_CPU0_CLK_DP<1>")
	)
	(arc
		(start 385.72186 -254.409194)
		(mid 385.534662 -254.359051)
		(end 385.347464 -254.409194)
		(width 0.088646)
		(layer "In2.Cu")
		(net "M_F_CPU0_CLK_DP<1>")
	)
	(arc
		(start 377.927616 -255.634236)
		(mid 377.92612 -255.623708)
		(end 377.924822 -255.613154)
		(width 0.088646)
		(layer "In2.Cu")
		(net "M_F_CPU0_CLK_DP<1>")
	)
	(arc
		(start 381.109474 -255.228344)
		(mid 380.97856 -255.364704)
		(end 380.930912 -255.547622)
		(width 0.088646)
		(layer "In2.Cu")
		(net "M_F_CPU0_CLK_DP<1>")
	)
	(arc
		(start 379.14326 -256.03708)
		(mid 378.956062 -255.986937)
		(end 378.768864 -256.03708)
		(width 0.088646)
		(layer "In2.Cu")
		(net "M_F_CPU0_CLK_DP<1>")
	)
	(arc
		(start 386.28701 -254.409448)
		(mid 386.004389 -254.485063)
		(end 385.72186 -254.409194)
		(width 0.088646)
		(layer "In2.Cu")
		(net "M_F_CPU0_CLK_DP<1>")
	)
	(segment
		(start 380.365762 -255.011682)
		(end 380.365762 -255.547368)
		(width 0.20066)
		(layer "F.Cu")
		(net "M_F_CPU0_CLK_DP<0>")
	)
	(segment
		(start 433.484782 -260.21665)
		(end 432.379882 -260.21665)
		(width 0.20066)
		(layer "F.Cu")
		(net "M_F_CPU0_CLK_DP<0>")
	)
	(segment
		(start 380.365762 -255.547368)
		(end 380.366016 -255.547622)
		(width 0.20066)
		(layer "F.Cu")
		(net "M_F_CPU0_CLK_DP<0>")
	)
	(segment
		(start 380.46152 -254.724916)
		(end 380.46152 -254.747776)
		(width 0.088646)
		(layer "In2.Cu")
		(net "M_F_CPU0_CLK_DP<0>")
	)
	(segment
		(start 424.923204 -257.153664)
		(end 424.133264 -256.934208)
		(width 0.18288)
		(layer "In2.Cu")
		(net "M_F_CPU0_CLK_DP<0>")
	)
	(segment
		(start 426.98035 -257.725164)
		(end 425.67225 -257.361944)
		(width 0.18288)
		(layer "In2.Cu")
		(net "M_F_CPU0_CLK_DP<0>")
	)
	(segment
		(start 428.00524 -257.725164)
		(end 426.98035 -257.725164)
		(width 0.18288)
		(layer "In2.Cu")
		(net "M_F_CPU0_CLK_DP<0>")
	)
	(segment
		(start 395.587474 -254.109728)
		(end 394.947648 -254.393446)
		(width 0.18288)
		(layer "In2.Cu")
		(net "M_F_CPU0_CLK_DP<0>")
	)
	(segment
		(start 380.661672 -254.401066)
		(end 380.661926 -254.401574)
		(width 0.088646)
		(layer "In2.Cu")
		(net "M_F_CPU0_CLK_DP<0>")
	)
	(segment
		(start 380.654814 -254.405638)
		(end 380.65329 -254.4064)
		(width 0.088646)
		(layer "In2.Cu")
		(net "M_F_CPU0_CLK_DP<0>")
	)
	(segment
		(start 382.265428 -253.33198)
		(end 382.15316 -253.33198)
		(width 0.088646)
		(layer "In2.Cu")
		(net "M_F_CPU0_CLK_DP<0>")
	)
	(segment
		(start 380.65329 -254.4064)
		(end 380.648718 -254.409194)
		(width 0.088646)
		(layer "In2.Cu")
		(net "M_F_CPU0_CLK_DP<0>")
	)
	(segment
		(start 431.743612 -259.958078)
		(end 431.279046 -259.493512)
		(width 0.18288)
		(layer "In2.Cu")
		(net "M_F_CPU0_CLK_DP<0>")
	)
	(segment
		(start 379.995938 -255.490472)
		(end 380.053088 -255.547622)
		(width 0.088646)
		(layer "In2.Cu")
		(net "M_F_CPU0_CLK_DP<0>")
	)
	(segment
		(start 432.379882 -260.21665)
		(end 432.357022 -260.21665)
		(width 0.18288)
		(layer "In2.Cu")
		(net "M_F_CPU0_CLK_DP<0>")
	)
	(segment
		(start 425.522136 -257.44678)
		(end 425.00804 -257.304032)
		(width 0.18288)
		(layer "In2.Cu")
		(net "M_F_CPU0_CLK_DP<0>")
	)
	(segment
		(start 381.14605 -253.331726)
		(end 380.930658 -253.547118)
		(width 0.088646)
		(layer "In2.Cu")
		(net "M_F_CPU0_CLK_DP<0>")
	)
	(segment
		(start 407.934668 -255.708404)
		(end 403.166072 -253.733808)
		(width 0.18288)
		(layer "In2.Cu")
		(net "M_F_CPU0_CLK_DP<0>")
	)
	(segment
		(start 415.916364 -255.708404)
		(end 407.934668 -255.708404)
		(width 0.18288)
		(layer "In2.Cu")
		(net "M_F_CPU0_CLK_DP<0>")
	)
	(segment
		(start 425.00804 -257.304032)
		(end 424.923204 -257.153664)
		(width 0.18288)
		(layer "In2.Cu")
		(net "M_F_CPU0_CLK_DP<0>")
	)
	(segment
		(start 394.947648 -254.393446)
		(end 394.549122 -254.558292)
		(width 0.18288)
		(layer "In2.Cu")
		(net "M_F_CPU0_CLK_DP<0>")
	)
	(segment
		(start 432.357022 -260.21665)
		(end 432.09845 -259.958078)
		(width 0.18288)
		(layer "In2.Cu")
		(net "M_F_CPU0_CLK_DP<0>")
	)
	(segment
		(start 429.9712 -257.847084)
		(end 429.4378 -257.847084)
		(width 0.18288)
		(layer "In2.Cu")
		(net "M_F_CPU0_CLK_DP<0>")
	)
	(segment
		(start 428.12716 -257.847084)
		(end 428.00524 -257.725164)
		(width 0.18288)
		(layer "In2.Cu")
		(net "M_F_CPU0_CLK_DP<0>")
	)
	(segment
		(start 429.31588 -257.725164)
		(end 428.78248 -257.725164)
		(width 0.18288)
		(layer "In2.Cu")
		(net "M_F_CPU0_CLK_DP<0>")
	)
	(segment
		(start 430.09312 -257.725164)
		(end 429.9712 -257.847084)
		(width 0.18288)
		(layer "In2.Cu")
		(net "M_F_CPU0_CLK_DP<0>")
	)
	(segment
		(start 431.279046 -258.37769)
		(end 430.62652 -257.725164)
		(width 0.18288)
		(layer "In2.Cu")
		(net "M_F_CPU0_CLK_DP<0>")
	)
	(segment
		(start 432.09845 -259.958078)
		(end 431.743612 -259.958078)
		(width 0.18288)
		(layer "In2.Cu")
		(net "M_F_CPU0_CLK_DP<0>")
	)
	(segment
		(start 380.178818 -255.223264)
		(end 380.169928 -255.228344)
		(width 0.088646)
		(layer "In2.Cu")
		(net "M_F_CPU0_CLK_DP<0>")
	)
	(segment
		(start 396.434818 -253.733808)
		(end 395.587474 -254.109728)
		(width 0.18288)
		(layer "In2.Cu")
		(net "M_F_CPU0_CLK_DP<0>")
	)
	(segment
		(start 403.166072 -253.733808)
		(end 396.434818 -253.733808)
		(width 0.18288)
		(layer "In2.Cu")
		(net "M_F_CPU0_CLK_DP<0>")
	)
	(segment
		(start 424.133264 -256.934208)
		(end 415.916364 -255.708404)
		(width 0.18288)
		(layer "In2.Cu")
		(net "M_F_CPU0_CLK_DP<0>")
	)
	(segment
		(start 380.930658 -253.547118)
		(end 380.930658 -253.919736)
		(width 0.088646)
		(layer "In2.Cu")
		(net "M_F_CPU0_CLK_DP<0>")
	)
	(segment
		(start 431.279046 -259.493512)
		(end 431.279046 -258.37769)
		(width 0.18288)
		(layer "In2.Cu")
		(net "M_F_CPU0_CLK_DP<0>")
	)
	(segment
		(start 392.57224 -254.375158)
		(end 387.908038 -253.39167)
		(width 0.18288)
		(layer "In2.Cu")
		(net "M_F_CPU0_CLK_DP<0>")
	)
	(segment
		(start 425.67225 -257.361944)
		(end 425.522136 -257.44678)
		(width 0.18288)
		(layer "In2.Cu")
		(net "M_F_CPU0_CLK_DP<0>")
	)
	(segment
		(start 394.549122 -254.558292)
		(end 393.441174 -254.558292)
		(width 0.18288)
		(layer "In2.Cu")
		(net "M_F_CPU0_CLK_DP<0>")
	)
	(segment
		(start 382.152906 -253.331726)
		(end 381.14605 -253.331726)
		(width 0.088646)
		(layer "In2.Cu")
		(net "M_F_CPU0_CLK_DP<0>")
	)
	(segment
		(start 387.908038 -253.39167)
		(end 382.325118 -253.39167)
		(width 0.18288)
		(layer "In2.Cu")
		(net "M_F_CPU0_CLK_DP<0>")
	)
	(segment
		(start 382.15316 -253.33198)
		(end 382.152906 -253.331726)
		(width 0.088646)
		(layer "In2.Cu")
		(net "M_F_CPU0_CLK_DP<0>")
	)
	(segment
		(start 429.4378 -257.847084)
		(end 429.31588 -257.725164)
		(width 0.18288)
		(layer "In2.Cu")
		(net "M_F_CPU0_CLK_DP<0>")
	)
	(segment
		(start 430.62652 -257.725164)
		(end 430.09312 -257.725164)
		(width 0.18288)
		(layer "In2.Cu")
		(net "M_F_CPU0_CLK_DP<0>")
	)
	(segment
		(start 380.053088 -255.547622)
		(end 380.366016 -255.547622)
		(width 0.088646)
		(layer "In2.Cu")
		(net "M_F_CPU0_CLK_DP<0>")
	)
	(segment
		(start 393.441174 -254.558292)
		(end 392.57224 -254.375158)
		(width 0.18288)
		(layer "In2.Cu")
		(net "M_F_CPU0_CLK_DP<0>")
	)
	(segment
		(start 428.78248 -257.725164)
		(end 428.66056 -257.847084)
		(width 0.18288)
		(layer "In2.Cu")
		(net "M_F_CPU0_CLK_DP<0>")
	)
	(segment
		(start 428.66056 -257.847084)
		(end 428.12716 -257.847084)
		(width 0.18288)
		(layer "In2.Cu")
		(net "M_F_CPU0_CLK_DP<0>")
	)
	(segment
		(start 382.325118 -253.39167)
		(end 382.265428 -253.33198)
		(width 0.088646)
		(layer "In2.Cu")
		(net "M_F_CPU0_CLK_DP<0>")
	)
	(arc
		(start 380.930658 -253.919736)
		(mid 380.85885 -254.195432)
		(end 380.661672 -254.401066)
		(width 0.088646)
		(layer "In2.Cu")
		(net "M_F_CPU0_CLK_DP<0>")
	)
	(arc
		(start 380.661926 -254.401574)
		(mid 380.658377 -254.403618)
		(end 380.654814 -254.405638)
		(width 0.088646)
		(layer "In2.Cu")
		(net "M_F_CPU0_CLK_DP<0>")
	)
	(arc
		(start 380.169928 -255.228344)
		(mid 380.054119 -255.340273)
		(end 379.995938 -255.490472)
		(width 0.088646)
		(layer "In2.Cu")
		(net "M_F_CPU0_CLK_DP<0>")
	)
	(arc
		(start 380.648718 -254.409194)
		(mid 380.513785 -254.542548)
		(end 380.46152 -254.724916)
		(width 0.088646)
		(layer "In2.Cu")
		(net "M_F_CPU0_CLK_DP<0>")
	)
	(arc
		(start 380.46152 -254.747776)
		(mid 380.382301 -255.022461)
		(end 380.178818 -255.223264)
		(width 0.088646)
		(layer "In2.Cu")
		(net "M_F_CPU0_CLK_DP<0>")
	)
	(segment
		(start 425.940982 -259.366766)
		(end 424.836082 -259.366766)
		(width 0.20066)
		(layer "F.Cu")
		(net "M_F_CPU0_CLK_DN<1>")
	)
	(segment
		(start 378.486162 -255.011682)
		(end 378.486162 -255.547368)
		(width 0.20066)
		(layer "F.Cu")
		(net "M_F_CPU0_CLK_DN<1>")
	)
	(segment
		(start 378.486162 -255.547368)
		(end 378.486416 -255.547622)
		(width 0.20066)
		(layer "F.Cu")
		(net "M_F_CPU0_CLK_DN<1>")
	)
	(segment
		(start 415.885122 -256.244852)
		(end 407.790904 -256.244852)
		(width 0.18288)
		(layer "In2.Cu")
		(net "M_F_CPU0_CLK_DN<1>")
	)
	(segment
		(start 388.414768 -254.389636)
		(end 388.103872 -254.389636)
		(width 0.088646)
		(layer "In2.Cu")
		(net "M_F_CPU0_CLK_DN<1>")
	)
	(segment
		(start 424.836082 -259.366766)
		(end 424.813476 -259.366766)
		(width 0.18288)
		(layer "In2.Cu")
		(net "M_F_CPU0_CLK_DN<1>")
	)
	(segment
		(start 399.501614 -254.385826)
		(end 398.968214 -254.385826)
		(width 0.18288)
		(layer "In2.Cu")
		(net "M_F_CPU0_CLK_DN<1>")
	)
	(segment
		(start 396.18666 -254.385826)
		(end 394.871702 -254.930402)
		(width 0.18288)
		(layer "In2.Cu")
		(net "M_F_CPU0_CLK_DN<1>")
	)
	(segment
		(start 398.190974 -254.385826)
		(end 397.657574 -254.385826)
		(width 0.18288)
		(layer "In2.Cu")
		(net "M_F_CPU0_CLK_DN<1>")
	)
	(segment
		(start 398.968214 -254.385826)
		(end 398.846294 -254.263906)
		(width 0.18288)
		(layer "In2.Cu")
		(net "M_F_CPU0_CLK_DN<1>")
	)
	(segment
		(start 388.103872 -254.389636)
		(end 387.719062 -254.549148)
		(width 0.088646)
		(layer "In2.Cu")
		(net "M_F_CPU0_CLK_DN<1>")
	)
	(segment
		(start 393.136628 -254.930402)
		(end 391.512806 -254.73914)
		(width 0.18288)
		(layer "In2.Cu")
		(net "M_F_CPU0_CLK_DN<1>")
	)
	(segment
		(start 381.507746 -254.235458)
		(end 381.486918 -254.24765)
		(width 0.088646)
		(layer "In2.Cu")
		(net "M_F_CPU0_CLK_DN<1>")
	)
	(segment
		(start 397.535654 -254.263906)
		(end 397.002254 -254.263906)
		(width 0.18288)
		(layer "In2.Cu")
		(net "M_F_CPU0_CLK_DN<1>")
	)
	(segment
		(start 399.623534 -254.263906)
		(end 399.501614 -254.385826)
		(width 0.18288)
		(layer "In2.Cu")
		(net "M_F_CPU0_CLK_DN<1>")
	)
	(segment
		(start 398.312894 -254.263906)
		(end 398.190974 -254.385826)
		(width 0.18288)
		(layer "In2.Cu")
		(net "M_F_CPU0_CLK_DN<1>")
	)
	(segment
		(start 423.399966 -257.888486)
		(end 422.33596 -257.518154)
		(width 0.18288)
		(layer "In2.Cu")
		(net "M_F_CPU0_CLK_DN<1>")
	)
	(segment
		(start 424.56989 -259.610352)
		(end 424.384978 -259.610352)
		(width 0.18288)
		(layer "In2.Cu")
		(net "M_F_CPU0_CLK_DN<1>")
	)
	(segment
		(start 423.669968 -258.158742)
		(end 423.399966 -257.888486)
		(width 0.18288)
		(layer "In2.Cu")
		(net "M_F_CPU0_CLK_DN<1>")
	)
	(segment
		(start 398.846294 -254.263906)
		(end 398.312894 -254.263906)
		(width 0.18288)
		(layer "In2.Cu")
		(net "M_F_CPU0_CLK_DN<1>")
	)
	(segment
		(start 378.173742 -255.547622)
		(end 378.486416 -255.547622)
		(width 0.088646)
		(layer "In2.Cu")
		(net "M_F_CPU0_CLK_DN<1>")
	)
	(segment
		(start 380.740412 -255.533398)
		(end 380.740412 -255.547622)
		(width 0.088646)
		(layer "In2.Cu")
		(net "M_F_CPU0_CLK_DN<1>")
	)
	(segment
		(start 382.443228 -254.237998)
		(end 382.432814 -254.244094)
		(width 0.088646)
		(layer "In2.Cu")
		(net "M_F_CPU0_CLK_DN<1>")
	)
	(segment
		(start 397.002254 -254.263906)
		(end 396.880334 -254.385826)
		(width 0.18288)
		(layer "In2.Cu")
		(net "M_F_CPU0_CLK_DN<1>")
	)
	(segment
		(start 389.67029 -254.335026)
		(end 388.469378 -254.335026)
		(width 0.18288)
		(layer "In2.Cu")
		(net "M_F_CPU0_CLK_DN<1>")
	)
	(segment
		(start 400.278854 -254.385826)
		(end 400.156934 -254.263906)
		(width 0.18288)
		(layer "In2.Cu")
		(net "M_F_CPU0_CLK_DN<1>")
	)
	(segment
		(start 379.623828 -255.865884)
		(end 379.613414 -255.87198)
		(width 0.088646)
		(layer "In2.Cu")
		(net "M_F_CPU0_CLK_DN<1>")
	)
	(segment
		(start 397.657574 -254.385826)
		(end 397.535654 -254.263906)
		(width 0.18288)
		(layer "In2.Cu")
		(net "M_F_CPU0_CLK_DN<1>")
	)
	(segment
		(start 424.212004 -259.437378)
		(end 423.669968 -258.158742)
		(width 0.18288)
		(layer "In2.Cu")
		(net "M_F_CPU0_CLK_DN<1>")
	)
	(segment
		(start 381.210312 -254.733552)
		(end 381.210312 -254.742188)
		(width 0.088646)
		(layer "In2.Cu")
		(net "M_F_CPU0_CLK_DN<1>")
	)
	(segment
		(start 417.62426 -256.49809)
		(end 415.885122 -256.244852)
		(width 0.18288)
		(layer "In2.Cu")
		(net "M_F_CPU0_CLK_DN<1>")
	)
	(segment
		(start 387.333236 -254.549148)
		(end 387.095492 -254.440436)
		(width 0.088646)
		(layer "In2.Cu")
		(net "M_F_CPU0_CLK_DN<1>")
	)
	(segment
		(start 407.790904 -256.244852)
		(end 403.302978 -254.385826)
		(width 0.18288)
		(layer "In2.Cu")
		(net "M_F_CPU0_CLK_DN<1>")
	)
	(segment
		(start 396.880334 -254.385826)
		(end 396.18666 -254.385826)
		(width 0.18288)
		(layer "In2.Cu")
		(net "M_F_CPU0_CLK_DN<1>")
	)
	(segment
		(start 391.512806 -254.73914)
		(end 389.67029 -254.335026)
		(width 0.18288)
		(layer "In2.Cu")
		(net "M_F_CPU0_CLK_DN<1>")
	)
	(segment
		(start 378.688346 -255.863344)
		(end 378.673614 -255.87198)
		(width 0.088646)
		(layer "In2.Cu")
		(net "M_F_CPU0_CLK_DN<1>")
	)
	(segment
		(start 424.813476 -259.366766)
		(end 424.56989 -259.610352)
		(width 0.18288)
		(layer "In2.Cu")
		(net "M_F_CPU0_CLK_DN<1>")
	)
	(segment
		(start 422.33596 -257.518154)
		(end 417.62426 -256.49809)
		(width 0.18288)
		(layer "In2.Cu")
		(net "M_F_CPU0_CLK_DN<1>")
	)
	(segment
		(start 403.302978 -254.385826)
		(end 400.278854 -254.385826)
		(width 0.18288)
		(layer "In2.Cu")
		(net "M_F_CPU0_CLK_DN<1>")
	)
	(segment
		(start 387.095492 -254.440436)
		(end 386.757418 -254.244348)
		(width 0.088646)
		(layer "In2.Cu")
		(net "M_F_CPU0_CLK_DN<1>")
	)
	(segment
		(start 400.156934 -254.263906)
		(end 399.623534 -254.263906)
		(width 0.18288)
		(layer "In2.Cu")
		(net "M_F_CPU0_CLK_DN<1>")
	)
	(segment
		(start 387.719062 -254.549148)
		(end 387.333236 -254.549148)
		(width 0.088646)
		(layer "In2.Cu")
		(net "M_F_CPU0_CLK_DN<1>")
	)
	(segment
		(start 378.116338 -255.605026)
		(end 378.173742 -255.547622)
		(width 0.088646)
		(layer "In2.Cu")
		(net "M_F_CPU0_CLK_DN<1>")
	)
	(segment
		(start 388.469378 -254.335026)
		(end 388.414768 -254.389636)
		(width 0.088646)
		(layer "In2.Cu")
		(net "M_F_CPU0_CLK_DN<1>")
	)
	(segment
		(start 424.384978 -259.610352)
		(end 424.212004 -259.437378)
		(width 0.18288)
		(layer "In2.Cu")
		(net "M_F_CPU0_CLK_DN<1>")
	)
	(segment
		(start 394.871702 -254.930402)
		(end 393.136628 -254.930402)
		(width 0.18288)
		(layer "In2.Cu")
		(net "M_F_CPU0_CLK_DN<1>")
	)
	(arc
		(start 384.31216 -254.244094)
		(mid 384.124962 -254.294237)
		(end 383.937764 -254.244094)
		(width 0.088646)
		(layer "In2.Cu")
		(net "M_F_CPU0_CLK_DN<1>")
	)
	(arc
		(start 380.740412 -255.547622)
		(mid 380.553113 -255.872063)
		(end 380.178564 -255.87198)
		(width 0.088646)
		(layer "In2.Cu")
		(net "M_F_CPU0_CLK_DN<1>")
	)
	(arc
		(start 385.25196 -254.244094)
		(mid 385.064762 -254.294237)
		(end 384.877564 -254.244094)
		(width 0.088646)
		(layer "In2.Cu")
		(net "M_F_CPU0_CLK_DN<1>")
	)
	(arc
		(start 381.486918 -254.24765)
		(mid 381.284331 -254.454001)
		(end 381.210312 -254.733552)
		(width 0.088646)
		(layer "In2.Cu")
		(net "M_F_CPU0_CLK_DN<1>")
	)
	(arc
		(start 380.178564 -255.87198)
		(mid 379.902005 -255.796237)
		(end 379.623828 -255.865884)
		(width 0.088646)
		(layer "In2.Cu")
		(net "M_F_CPU0_CLK_DN<1>")
	)
	(arc
		(start 381.210312 -254.742188)
		(mid 381.158042 -254.924553)
		(end 381.023114 -255.05791)
		(width 0.088646)
		(layer "In2.Cu")
		(net "M_F_CPU0_CLK_DN<1>")
	)
	(arc
		(start 379.613414 -255.87198)
		(mid 379.426216 -255.922123)
		(end 379.239018 -255.87198)
		(width 0.088646)
		(layer "In2.Cu")
		(net "M_F_CPU0_CLK_DN<1>")
	)
	(arc
		(start 382.058418 -254.244094)
		(mid 381.784219 -254.168259)
		(end 381.507746 -254.235458)
		(width 0.088646)
		(layer "In2.Cu")
		(net "M_F_CPU0_CLK_DN<1>")
	)
	(arc
		(start 382.997964 -254.244094)
		(mid 382.721405 -254.168351)
		(end 382.443228 -254.237998)
		(width 0.088646)
		(layer "In2.Cu")
		(net "M_F_CPU0_CLK_DN<1>")
	)
	(arc
		(start 379.239018 -255.87198)
		(mid 378.964819 -255.796145)
		(end 378.688346 -255.863344)
		(width 0.088646)
		(layer "In2.Cu")
		(net "M_F_CPU0_CLK_DN<1>")
	)
	(arc
		(start 386.757418 -254.244348)
		(mid 386.474635 -254.168411)
		(end 386.19176 -254.244094)
		(width 0.088646)
		(layer "In2.Cu")
		(net "M_F_CPU0_CLK_DN<1>")
	)
	(arc
		(start 386.19176 -254.244094)
		(mid 386.004562 -254.294237)
		(end 385.817364 -254.244094)
		(width 0.088646)
		(layer "In2.Cu")
		(net "M_F_CPU0_CLK_DN<1>")
	)
	(arc
		(start 383.37236 -254.244094)
		(mid 383.185162 -254.294237)
		(end 382.997964 -254.244094)
		(width 0.088646)
		(layer "In2.Cu")
		(net "M_F_CPU0_CLK_DN<1>")
	)
	(arc
		(start 385.817364 -254.244094)
		(mid 385.534662 -254.168318)
		(end 385.25196 -254.244094)
		(width 0.088646)
		(layer "In2.Cu")
		(net "M_F_CPU0_CLK_DN<1>")
	)
	(arc
		(start 382.432814 -254.244094)
		(mid 382.245616 -254.294237)
		(end 382.058418 -254.244094)
		(width 0.088646)
		(layer "In2.Cu")
		(net "M_F_CPU0_CLK_DN<1>")
	)
	(arc
		(start 378.673614 -255.87198)
		(mid 378.324622 -255.88537)
		(end 378.116338 -255.605026)
		(width 0.088646)
		(layer "In2.Cu")
		(net "M_F_CPU0_CLK_DN<1>")
	)
	(arc
		(start 383.937764 -254.244094)
		(mid 383.655062 -254.168318)
		(end 383.37236 -254.244094)
		(width 0.088646)
		(layer "In2.Cu")
		(net "M_F_CPU0_CLK_DN<1>")
	)
	(arc
		(start 381.023114 -255.05791)
		(mid 380.819633 -255.258714)
		(end 380.740412 -255.533398)
		(width 0.088646)
		(layer "In2.Cu")
		(net "M_F_CPU0_CLK_DN<1>")
	)
	(arc
		(start 384.877564 -254.244094)
		(mid 384.594862 -254.168318)
		(end 384.31216 -254.244094)
		(width 0.088646)
		(layer "In2.Cu")
		(net "M_F_CPU0_CLK_DN<1>")
	)
	(segment
		(start 379.425962 -255.011682)
		(end 379.425962 -255.547368)
		(width 0.20066)
		(layer "F.Cu")
		(net "M_F_CPU0_CLK_DN<0>")
	)
	(segment
		(start 379.425962 -255.547368)
		(end 379.426216 -255.547622)
		(width 0.20066)
		(layer "F.Cu")
		(net "M_F_CPU0_CLK_DN<0>")
	)
	(segment
		(start 433.484782 -259.366766)
		(end 432.379882 -259.366766)
		(width 0.20066)
		(layer "F.Cu")
		(net "M_F_CPU0_CLK_DN<0>")
	)
	(segment
		(start 407.99639 -255.398524)
		(end 403.227794 -253.423928)
		(width 0.18288)
		(layer "In2.Cu")
		(net "M_F_CPU0_CLK_DN<0>")
	)
	(segment
		(start 381.067056 -253.14148)
		(end 380.740412 -253.468124)
		(width 0.088646)
		(layer "In2.Cu")
		(net "M_F_CPU0_CLK_DN<0>")
	)
	(segment
		(start 431.872136 -259.648198)
		(end 431.588926 -259.364988)
		(width 0.18288)
		(layer "In2.Cu")
		(net "M_F_CPU0_CLK_DN<0>")
	)
	(segment
		(start 415.939478 -255.398524)
		(end 407.99639 -255.398524)
		(width 0.18288)
		(layer "In2.Cu")
		(net "M_F_CPU0_CLK_DN<0>")
	)
	(segment
		(start 424.19778 -256.630424)
		(end 415.939478 -255.398524)
		(width 0.18288)
		(layer "In2.Cu")
		(net "M_F_CPU0_CLK_DN<0>")
	)
	(segment
		(start 379.739144 -255.547622)
		(end 379.426216 -255.547622)
		(width 0.088646)
		(layer "In2.Cu")
		(net "M_F_CPU0_CLK_DN<0>")
	)
	(segment
		(start 403.227794 -253.423928)
		(end 396.369032 -253.423928)
		(width 0.18288)
		(layer "In2.Cu")
		(net "M_F_CPU0_CLK_DN<0>")
	)
	(segment
		(start 394.487146 -254.248412)
		(end 393.473686 -254.248412)
		(width 0.18288)
		(layer "In2.Cu")
		(net "M_F_CPU0_CLK_DN<0>")
	)
	(segment
		(start 382.325118 -253.08179)
		(end 382.265428 -253.14148)
		(width 0.088646)
		(layer "In2.Cu")
		(net "M_F_CPU0_CLK_DN<0>")
	)
	(segment
		(start 393.473686 -254.248412)
		(end 392.83386 -254.113538)
		(width 0.18288)
		(layer "In2.Cu")
		(net "M_F_CPU0_CLK_DN<0>")
	)
	(segment
		(start 431.588926 -258.249166)
		(end 430.755044 -257.415284)
		(width 0.18288)
		(layer "In2.Cu")
		(net "M_F_CPU0_CLK_DN<0>")
	)
	(segment
		(start 430.755044 -257.415284)
		(end 427.022768 -257.415284)
		(width 0.18288)
		(layer "In2.Cu")
		(net "M_F_CPU0_CLK_DN<0>")
	)
	(segment
		(start 396.369032 -253.423928)
		(end 395.461744 -253.826264)
		(width 0.18288)
		(layer "In2.Cu")
		(net "M_F_CPU0_CLK_DN<0>")
	)
	(segment
		(start 395.461744 -253.826264)
		(end 394.825474 -254.108458)
		(width 0.18288)
		(layer "In2.Cu")
		(net "M_F_CPU0_CLK_DN<0>")
	)
	(segment
		(start 432.379882 -259.366766)
		(end 432.09845 -259.648198)
		(width 0.18288)
		(layer "In2.Cu")
		(net "M_F_CPU0_CLK_DN<0>")
	)
	(segment
		(start 380.553976 -254.243586)
		(end 380.55296 -254.244094)
		(width 0.088646)
		(layer "In2.Cu")
		(net "M_F_CPU0_CLK_DN<0>")
	)
	(segment
		(start 380.083822 -255.058164)
		(end 380.083568 -255.05791)
		(width 0.088646)
		(layer "In2.Cu")
		(net "M_F_CPU0_CLK_DN<0>")
	)
	(segment
		(start 380.56185 -254.239014)
		(end 380.553976 -254.243586)
		(width 0.088646)
		(layer "In2.Cu")
		(net "M_F_CPU0_CLK_DN<0>")
	)
	(segment
		(start 380.270766 -254.718058)
		(end 380.270766 -254.733552)
		(width 0.088646)
		(layer "In2.Cu")
		(net "M_F_CPU0_CLK_DN<0>")
	)
	(segment
		(start 394.825474 -254.108458)
		(end 394.487146 -254.248412)
		(width 0.18288)
		(layer "In2.Cu")
		(net "M_F_CPU0_CLK_DN<0>")
	)
	(segment
		(start 380.270766 -254.733552)
		(end 380.271274 -254.744982)
		(width 0.088646)
		(layer "In2.Cu")
		(net "M_F_CPU0_CLK_DN<0>")
	)
	(segment
		(start 431.588926 -259.364988)
		(end 431.588926 -258.249166)
		(width 0.18288)
		(layer "In2.Cu")
		(net "M_F_CPU0_CLK_DN<0>")
	)
	(segment
		(start 380.740412 -253.468124)
		(end 380.740412 -253.919736)
		(width 0.088646)
		(layer "In2.Cu")
		(net "M_F_CPU0_CLK_DN<0>")
	)
	(segment
		(start 379.804422 -255.482344)
		(end 379.739144 -255.547622)
		(width 0.088646)
		(layer "In2.Cu")
		(net "M_F_CPU0_CLK_DN<0>")
	)
	(segment
		(start 380.083822 -255.058418)
		(end 380.083822 -255.058164)
		(width 0.088646)
		(layer "In2.Cu")
		(net "M_F_CPU0_CLK_DN<0>")
	)
	(segment
		(start 392.83386 -254.113538)
		(end 387.94055 -253.08179)
		(width 0.18288)
		(layer "In2.Cu")
		(net "M_F_CPU0_CLK_DN<0>")
	)
	(segment
		(start 382.265428 -253.14148)
		(end 381.067056 -253.14148)
		(width 0.088646)
		(layer "In2.Cu")
		(net "M_F_CPU0_CLK_DN<0>")
	)
	(segment
		(start 432.09845 -259.648198)
		(end 431.872136 -259.648198)
		(width 0.18288)
		(layer "In2.Cu")
		(net "M_F_CPU0_CLK_DN<0>")
	)
	(segment
		(start 427.022768 -257.415284)
		(end 424.19778 -256.630424)
		(width 0.18288)
		(layer "In2.Cu")
		(net "M_F_CPU0_CLK_DN<0>")
	)
	(segment
		(start 387.94055 -253.08179)
		(end 382.325118 -253.08179)
		(width 0.18288)
		(layer "In2.Cu")
		(net "M_F_CPU0_CLK_DN<0>")
	)
	(arc
		(start 379.807216 -255.461262)
		(mid 379.80572 -255.47179)
		(end 379.804422 -255.482344)
		(width 0.088646)
		(layer "In2.Cu")
		(net "M_F_CPU0_CLK_DN<0>")
	)
	(arc
		(start 380.083568 -255.05791)
		(mid 379.899586 -255.228188)
		(end 379.807216 -255.461262)
		(width 0.088646)
		(layer "In2.Cu")
		(net "M_F_CPU0_CLK_DN<0>")
	)
	(arc
		(start 380.740412 -253.919736)
		(mid 380.692733 -254.102636)
		(end 380.56185 -254.239014)
		(width 0.088646)
		(layer "In2.Cu")
		(net "M_F_CPU0_CLK_DN<0>")
	)
	(arc
		(start 380.55296 -254.244094)
		(mid 380.350137 -254.444325)
		(end 380.270766 -254.718058)
		(width 0.088646)
		(layer "In2.Cu")
		(net "M_F_CPU0_CLK_DN<0>")
	)
	(arc
		(start 380.271274 -254.744982)
		(mid 380.218277 -254.92606)
		(end 380.083822 -255.058418)
		(width 0.088646)
		(layer "In2.Cu")
		(net "M_F_CPU0_CLK_DN<0>")
	)
	(segment
		(start 369.558316 -254.733298)
		(end 369.558062 -254.733552)
		(width 0.20066)
		(layer "F.Cu")
		(net "M_F_CPU0_ALERT_N")
	)
	(segment
		(start 424.273472 -269.62735)
		(end 424.273472 -269.259812)
		(width 0.20066)
		(layer "F.Cu")
		(net "M_F_CPU0_ALERT_N")
	)
	(segment
		(start 426.951394 -269.135352)
		(end 427.266862 -269.135352)
		(width 0.20066)
		(layer "F.Cu")
		(net "M_F_CPU0_ALERT_N")
	)
	(segment
		(start 427.9011 -269.76959)
		(end 428.677832 -269.76959)
		(width 0.20066)
		(layer "F.Cu")
		(net "M_F_CPU0_ALERT_N")
	)
	(segment
		(start 426.945044 -269.141702)
		(end 426.951394 -269.135352)
		(width 0.1016)
		(layer "F.Cu")
		(net "M_F_CPU0_ALERT_N")
	)
	(segment
		(start 424.92422 -269.127224)
		(end 424.938698 -269.141702)
		(width 0.1016)
		(layer "F.Cu")
		(net "M_F_CPU0_ALERT_N")
	)
	(segment
		(start 424.870626 -269.127224)
		(end 424.92422 -269.127224)
		(width 0.101854)
		(layer "F.Cu")
		(net "M_F_CPU0_ALERT_N")
	)
	(segment
		(start 428.880778 -269.566644)
		(end 429.384714 -269.566644)
		(width 0.20066)
		(layer "F.Cu")
		(net "M_F_CPU0_ALERT_N")
	)
	(segment
		(start 421.840914 -269.566644)
		(end 422.39438 -269.566644)
		(width 0.20066)
		(layer "F.Cu")
		(net "M_F_CPU0_ALERT_N")
	)
	(segment
		(start 369.558316 -254.197612)
		(end 369.558316 -254.733298)
		(width 0.20066)
		(layer "F.Cu")
		(net "M_F_CPU0_ALERT_N")
	)
	(segment
		(start 424.40606 -269.127224)
		(end 424.870626 -269.127224)
		(width 0.20066)
		(layer "F.Cu")
		(net "M_F_CPU0_ALERT_N")
	)
	(segment
		(start 424.085512 -269.81531)
		(end 424.273472 -269.62735)
		(width 0.20066)
		(layer "F.Cu")
		(net "M_F_CPU0_ALERT_N")
	)
	(segment
		(start 428.677832 -269.76959)
		(end 428.880778 -269.566644)
		(width 0.20066)
		(layer "F.Cu")
		(net "M_F_CPU0_ALERT_N")
	)
	(segment
		(start 422.643046 -269.81531)
		(end 424.085512 -269.81531)
		(width 0.20066)
		(layer "F.Cu")
		(net "M_F_CPU0_ALERT_N")
	)
	(segment
		(start 422.39438 -269.566644)
		(end 422.643046 -269.81531)
		(width 0.20066)
		(layer "F.Cu")
		(net "M_F_CPU0_ALERT_N")
	)
	(segment
		(start 424.938698 -269.141702)
		(end 426.945044 -269.141702)
		(width 0.1016)
		(layer "F.Cu")
		(net "M_F_CPU0_ALERT_N")
	)
	(segment
		(start 420.736014 -269.566644)
		(end 421.840914 -269.566644)
		(width 0.20066)
		(layer "F.Cu")
		(net "M_F_CPU0_ALERT_N")
	)
	(segment
		(start 424.273472 -269.259812)
		(end 424.40606 -269.127224)
		(width 0.20066)
		(layer "F.Cu")
		(net "M_F_CPU0_ALERT_N")
	)
	(segment
		(start 427.266862 -269.135352)
		(end 427.9011 -269.76959)
		(width 0.20066)
		(layer "F.Cu")
		(net "M_F_CPU0_ALERT_N")
	)
	(via
		(at 375.667016 -255.547622)
		(size 0.4318)
		(drill 0.2032)
		(layers "F.Cu" "B.Cu")
		(net "M_F_CPU0_ALERT_N")
	)
	(via
		(at 420.736014 -269.566644)
		(size 0.4572)
		(drill 0.2032)
		(layers "F.Cu" "B.Cu")
		(net "M_F_CPU0_ALERT_N")
	)
	(via
		(at 369.558062 -254.733552)
		(size 0.4572)
		(drill 0.2032)
		(layers "F.Cu" "B.Cu")
		(net "M_F_CPU0_ALERT_N")
	)
	(segment
		(start 370.252498 -255.134364)
		(end 369.890548 -255.087628)
		(width 0.20066)
		(layer "B.Cu")
		(net "M_F_CPU0_ALERT_N")
	)
	(segment
		(start 371.202712 -255.14046)
		(end 371.18925 -255.132586)
		(width 0.20066)
		(layer "B.Cu")
		(net "M_F_CPU0_ALERT_N")
	)
	(segment
		(start 375.667016 -255.547622)
		(end 375.663968 -255.536446)
		(width 0.20066)
		(layer "B.Cu")
		(net "M_F_CPU0_ALERT_N")
	)
	(segment
		(start 375.663968 -255.536446)
		(end 374.978422 -255.14046)
		(width 0.20066)
		(layer "B.Cu")
		(net "M_F_CPU0_ALERT_N")
	)
	(segment
		(start 370.262912 -255.14046)
		(end 370.252498 -255.134364)
		(width 0.20066)
		(layer "B.Cu")
		(net "M_F_CPU0_ALERT_N")
	)
	(segment
		(start 374.492012 -255.14046)
		(end 374.46585 -255.155446)
		(width 0.20066)
		(layer "B.Cu")
		(net "M_F_CPU0_ALERT_N")
	)
	(segment
		(start 369.783868 -255.026414)
		(end 369.558062 -254.733552)
		(width 0.20066)
		(layer "B.Cu")
		(net "M_F_CPU0_ALERT_N")
	)
	(segment
		(start 374.048528 -255.155446)
		(end 374.012714 -255.134872)
		(width 0.20066)
		(layer "B.Cu")
		(net "M_F_CPU0_ALERT_N")
	)
	(segment
		(start 372.142766 -255.14046)
		(end 372.133114 -255.134872)
		(width 0.20066)
		(layer "B.Cu")
		(net "M_F_CPU0_ALERT_N")
	)
	(segment
		(start 372.612412 -255.14046)
		(end 372.60276 -255.146048)
		(width 0.20066)
		(layer "B.Cu")
		(net "M_F_CPU0_ALERT_N")
	)
	(arc
		(start 370.732812 -255.14046)
		(mid 370.497862 -255.20342)
		(end 370.262912 -255.14046)
		(width 0.20066)
		(layer "B.Cu")
		(net "M_F_CPU0_ALERT_N")
	)
	(arc
		(start 374.012714 -255.134872)
		(mid 373.781729 -255.077421)
		(end 373.552212 -255.14046)
		(width 0.20066)
		(layer "B.Cu")
		(net "M_F_CPU0_ALERT_N")
	)
	(arc
		(start 373.552212 -255.14046)
		(mid 373.317262 -255.20342)
		(end 373.082312 -255.14046)
		(width 0.20066)
		(layer "B.Cu")
		(net "M_F_CPU0_ALERT_N")
	)
	(arc
		(start 371.18925 -255.132586)
		(mid 370.959997 -255.077372)
		(end 370.732812 -255.14046)
		(width 0.20066)
		(layer "B.Cu")
		(net "M_F_CPU0_ALERT_N")
	)
	(arc
		(start 374.46585 -255.155446)
		(mid 374.257206 -255.211425)
		(end 374.048528 -255.155446)
		(width 0.20066)
		(layer "B.Cu")
		(net "M_F_CPU0_ALERT_N")
	)
	(arc
		(start 374.978422 -255.14046)
		(mid 374.735234 -255.075376)
		(end 374.492012 -255.14046)
		(width 0.20066)
		(layer "B.Cu")
		(net "M_F_CPU0_ALERT_N")
	)
	(arc
		(start 372.60276 -255.146048)
		(mid 372.372029 -255.203409)
		(end 372.142766 -255.14046)
		(width 0.20066)
		(layer "B.Cu")
		(net "M_F_CPU0_ALERT_N")
	)
	(arc
		(start 373.082312 -255.14046)
		(mid 372.847362 -255.077534)
		(end 372.612412 -255.14046)
		(width 0.20066)
		(layer "B.Cu")
		(net "M_F_CPU0_ALERT_N")
	)
	(arc
		(start 371.672612 -255.14046)
		(mid 371.437662 -255.20342)
		(end 371.202712 -255.14046)
		(width 0.20066)
		(layer "B.Cu")
		(net "M_F_CPU0_ALERT_N")
	)
	(arc
		(start 372.133114 -255.134872)
		(mid 371.902129 -255.077421)
		(end 371.672612 -255.14046)
		(width 0.20066)
		(layer "B.Cu")
		(net "M_F_CPU0_ALERT_N")
	)
	(arc
		(start 369.890548 -255.087628)
		(mid 369.831113 -255.067636)
		(end 369.783868 -255.026414)
		(width 0.20066)
		(layer "B.Cu")
		(net "M_F_CPU0_ALERT_N")
	)
	(segment
		(start 376.295412 -256.020824)
		(end 375.667016 -255.547622)
		(width 0.088646)
		(layer "In2.Cu")
		(net "M_F_CPU0_ALERT_N")
	)
	(segment
		(start 378.673614 -258.478782)
		(end 378.67336 -258.478782)
		(width 0.088646)
		(layer "In2.Cu")
		(net "M_F_CPU0_ALERT_N")
	)
	(segment
		(start 376.32386 -256.03708)
		(end 376.324114 -256.03708)
		(width 0.088646)
		(layer "In2.Cu")
		(net "M_F_CPU0_ALERT_N")
	)
	(segment
		(start 379.613414 -258.479036)
		(end 379.613414 -258.478782)
		(width 0.088646)
		(layer "In2.Cu")
		(net "M_F_CPU0_ALERT_N")
	)
	(segment
		(start 395.648688 -261.893812)
		(end 393.958826 -260.20395)
		(width 0.18288)
		(layer "In2.Cu")
		(net "M_F_CPU0_ALERT_N")
	)
	(segment
		(start 377.733814 -258.478782)
		(end 377.73356 -258.478782)
		(width 0.088646)
		(layer "In2.Cu")
		(net "M_F_CPU0_ALERT_N")
	)
	(segment
		(start 379.613414 -258.478782)
		(end 379.61316 -258.478782)
		(width 0.088646)
		(layer "In2.Cu")
		(net "M_F_CPU0_ALERT_N")
	)
	(segment
		(start 379.800866 -258.803648)
		(end 379.800866 -258.80314)
		(width 0.088646)
		(layer "In2.Cu")
		(net "M_F_CPU0_ALERT_N")
	)
	(segment
		(start 393.958826 -260.20395)
		(end 393.231878 -259.902706)
		(width 0.18288)
		(layer "In2.Cu")
		(net "M_F_CPU0_ALERT_N")
	)
	(segment
		(start 376.981466 -257.190748)
		(end 376.981466 -257.175254)
		(width 0.088646)
		(layer "In2.Cu")
		(net "M_F_CPU0_ALERT_N")
	)
	(segment
		(start 386.206492 -260.11505)
		(end 386.19176 -260.106414)
		(width 0.088646)
		(layer "In2.Cu")
		(net "M_F_CPU0_ALERT_N")
	)
	(segment
		(start 420.252398 -269.083028)
		(end 416.973258 -269.083028)
		(width 0.18288)
		(layer "In2.Cu")
		(net "M_F_CPU0_ALERT_N")
	)
	(segment
		(start 382.443228 -260.11251)
		(end 382.432814 -260.106414)
		(width 0.088646)
		(layer "In2.Cu")
		(net "M_F_CPU0_ALERT_N")
	)
	(segment
		(start 413.031432 -268.236192)
		(end 412.170372 -267.375132)
		(width 0.18288)
		(layer "In2.Cu")
		(net "M_F_CPU0_ALERT_N")
	)
	(segment
		(start 380.553976 -260.106414)
		(end 380.553214 -260.10616)
		(width 0.088646)
		(layer "In2.Cu")
		(net "M_F_CPU0_ALERT_N")
	)
	(segment
		(start 400.38147 -261.893812)
		(end 395.648688 -261.893812)
		(width 0.18288)
		(layer "In2.Cu")
		(net "M_F_CPU0_ALERT_N")
	)
	(segment
		(start 387.900672 -259.902706)
		(end 387.696964 -260.106414)
		(width 0.088646)
		(layer "In2.Cu")
		(net "M_F_CPU0_ALERT_N")
	)
	(segment
		(start 376.33275 -256.04216)
		(end 376.32386 -256.03708)
		(width 0.088646)
		(layer "In2.Cu")
		(net "M_F_CPU0_ALERT_N")
	)
	(segment
		(start 384.326892 -260.11505)
		(end 384.31216 -260.106414)
		(width 0.088646)
		(layer "In2.Cu")
		(net "M_F_CPU0_ALERT_N")
	)
	(segment
		(start 416.973258 -269.083028)
		(end 416.126422 -268.236192)
		(width 0.18288)
		(layer "In2.Cu")
		(net "M_F_CPU0_ALERT_N")
	)
	(segment
		(start 388.840218 -259.902706)
		(end 387.900672 -259.902706)
		(width 0.088646)
		(layer "In2.Cu")
		(net "M_F_CPU0_ALERT_N")
	)
	(segment
		(start 376.324114 -256.03708)
		(end 376.295412 -256.020824)
		(width 0.088646)
		(layer "In2.Cu")
		(net "M_F_CPU0_ALERT_N")
	)
	(segment
		(start 377.27255 -257.669792)
		(end 377.26366 -257.664712)
		(width 0.088646)
		(layer "In2.Cu")
		(net "M_F_CPU0_ALERT_N")
	)
	(segment
		(start 405.068024 -266.580366)
		(end 400.38147 -261.893812)
		(width 0.18288)
		(layer "In2.Cu")
		(net "M_F_CPU0_ALERT_N")
	)
	(segment
		(start 387.146292 -260.11505)
		(end 387.13156 -260.106414)
		(width 0.088646)
		(layer "In2.Cu")
		(net "M_F_CPU0_ALERT_N")
	)
	(segment
		(start 377.451112 -257.989578)
		(end 377.451112 -257.98907)
		(width 0.088646)
		(layer "In2.Cu")
		(net "M_F_CPU0_ALERT_N")
	)
	(segment
		(start 376.794014 -256.850896)
		(end 376.781822 -256.843784)
		(width 0.088646)
		(layer "In2.Cu")
		(net "M_F_CPU0_ALERT_N")
	)
	(segment
		(start 381.503174 -260.11251)
		(end 381.49276 -260.106414)
		(width 0.088646)
		(layer "In2.Cu")
		(net "M_F_CPU0_ALERT_N")
	)
	(segment
		(start 393.231878 -259.902706)
		(end 388.840218 -259.902706)
		(width 0.18288)
		(layer "In2.Cu")
		(net "M_F_CPU0_ALERT_N")
	)
	(segment
		(start 412.170372 -267.375132)
		(end 408.959812 -267.375132)
		(width 0.18288)
		(layer "In2.Cu")
		(net "M_F_CPU0_ALERT_N")
	)
	(segment
		(start 416.126422 -268.236192)
		(end 413.031432 -268.236192)
		(width 0.18288)
		(layer "In2.Cu")
		(net "M_F_CPU0_ALERT_N")
	)
	(segment
		(start 383.37236 -260.106414)
		(end 383.372106 -260.106414)
		(width 0.088646)
		(layer "In2.Cu")
		(net "M_F_CPU0_ALERT_N")
	)
	(segment
		(start 420.736014 -269.566644)
		(end 420.252398 -269.083028)
		(width 0.18288)
		(layer "In2.Cu")
		(net "M_F_CPU0_ALERT_N")
	)
	(segment
		(start 380.09195 -259.297678)
		(end 380.08306 -259.292598)
		(width 0.088646)
		(layer "In2.Cu")
		(net "M_F_CPU0_ALERT_N")
	)
	(segment
		(start 408.959812 -267.375132)
		(end 408.165046 -266.580366)
		(width 0.18288)
		(layer "In2.Cu")
		(net "M_F_CPU0_ALERT_N")
	)
	(segment
		(start 408.165046 -266.580366)
		(end 405.068024 -266.580366)
		(width 0.18288)
		(layer "In2.Cu")
		(net "M_F_CPU0_ALERT_N")
	)
	(segment
		(start 376.794268 -256.85115)
		(end 376.794014 -256.850896)
		(width 0.088646)
		(layer "In2.Cu")
		(net "M_F_CPU0_ALERT_N")
	)
	(segment
		(start 385.266692 -260.11505)
		(end 385.25196 -260.106414)
		(width 0.088646)
		(layer "In2.Cu")
		(net "M_F_CPU0_ALERT_N")
	)
	(arc
		(start 384.31216 -260.106414)
		(mid 384.124962 -260.056271)
		(end 383.937764 -260.106414)
		(width 0.088646)
		(layer "In2.Cu")
		(net "M_F_CPU0_ALERT_N")
	)
	(arc
		(start 385.817364 -260.106414)
		(mid 385.543165 -260.182249)
		(end 385.266692 -260.11505)
		(width 0.088646)
		(layer "In2.Cu")
		(net "M_F_CPU0_ALERT_N")
	)
	(arc
		(start 382.997964 -260.106414)
		(mid 382.721405 -260.182157)
		(end 382.443228 -260.11251)
		(width 0.088646)
		(layer "In2.Cu")
		(net "M_F_CPU0_ALERT_N")
	)
	(arc
		(start 383.372106 -260.106414)
		(mid 383.185052 -260.056364)
		(end 382.997964 -260.106414)
		(width 0.088646)
		(layer "In2.Cu")
		(net "M_F_CPU0_ALERT_N")
	)
	(arc
		(start 378.299218 -258.478782)
		(mid 378.016516 -258.554524)
		(end 377.733814 -258.478782)
		(width 0.088646)
		(layer "In2.Cu")
		(net "M_F_CPU0_ALERT_N")
	)
	(arc
		(start 376.781822 -256.843784)
		(mid 376.583594 -256.637936)
		(end 376.511312 -256.361438)
		(width 0.088646)
		(layer "In2.Cu")
		(net "M_F_CPU0_ALERT_N")
	)
	(arc
		(start 382.432814 -260.106414)
		(mid 382.245616 -260.056271)
		(end 382.058418 -260.106414)
		(width 0.088646)
		(layer "In2.Cu")
		(net "M_F_CPU0_ALERT_N")
	)
	(arc
		(start 379.800866 -258.80314)
		(mid 379.750573 -258.615964)
		(end 379.613414 -258.479036)
		(width 0.088646)
		(layer "In2.Cu")
		(net "M_F_CPU0_ALERT_N")
	)
	(arc
		(start 380.270512 -259.616956)
		(mid 380.222833 -259.434056)
		(end 380.09195 -259.297678)
		(width 0.088646)
		(layer "In2.Cu")
		(net "M_F_CPU0_ALERT_N")
	)
	(arc
		(start 378.67336 -258.478782)
		(mid 378.486306 -258.428732)
		(end 378.299218 -258.478782)
		(width 0.088646)
		(layer "In2.Cu")
		(net "M_F_CPU0_ALERT_N")
	)
	(arc
		(start 386.19176 -260.106414)
		(mid 386.004562 -260.056271)
		(end 385.817364 -260.106414)
		(width 0.088646)
		(layer "In2.Cu")
		(net "M_F_CPU0_ALERT_N")
	)
	(arc
		(start 376.981466 -257.175254)
		(mid 376.931302 -256.988116)
		(end 376.794268 -256.85115)
		(width 0.088646)
		(layer "In2.Cu")
		(net "M_F_CPU0_ALERT_N")
	)
	(arc
		(start 381.118364 -260.106414)
		(mid 380.83617 -260.182004)
		(end 380.553976 -260.106414)
		(width 0.088646)
		(layer "In2.Cu")
		(net "M_F_CPU0_ALERT_N")
	)
	(arc
		(start 384.877564 -260.106414)
		(mid 384.603365 -260.182249)
		(end 384.326892 -260.11505)
		(width 0.088646)
		(layer "In2.Cu")
		(net "M_F_CPU0_ALERT_N")
	)
	(arc
		(start 377.451112 -257.98907)
		(mid 377.403433 -257.80617)
		(end 377.27255 -257.669792)
		(width 0.088646)
		(layer "In2.Cu")
		(net "M_F_CPU0_ALERT_N")
	)
	(arc
		(start 380.553214 -260.10616)
		(mid 380.34627 -259.89945)
		(end 380.270512 -259.616956)
		(width 0.088646)
		(layer "In2.Cu")
		(net "M_F_CPU0_ALERT_N")
	)
	(arc
		(start 379.239018 -258.478782)
		(mid 378.956316 -258.554524)
		(end 378.673614 -258.478782)
		(width 0.088646)
		(layer "In2.Cu")
		(net "M_F_CPU0_ALERT_N")
	)
	(arc
		(start 377.26366 -257.664712)
		(mid 377.060837 -257.464481)
		(end 376.981466 -257.190748)
		(width 0.088646)
		(layer "In2.Cu")
		(net "M_F_CPU0_ALERT_N")
	)
	(arc
		(start 380.08306 -259.292598)
		(mid 379.876459 -259.085924)
		(end 379.800866 -258.803648)
		(width 0.088646)
		(layer "In2.Cu")
		(net "M_F_CPU0_ALERT_N")
	)
	(arc
		(start 381.49276 -260.106414)
		(mid 381.305562 -260.056237)
		(end 381.118364 -260.106414)
		(width 0.088646)
		(layer "In2.Cu")
		(net "M_F_CPU0_ALERT_N")
	)
	(arc
		(start 383.937764 -260.106414)
		(mid 383.655062 -260.182156)
		(end 383.37236 -260.106414)
		(width 0.088646)
		(layer "In2.Cu")
		(net "M_F_CPU0_ALERT_N")
	)
	(arc
		(start 376.511312 -256.361438)
		(mid 376.463633 -256.178538)
		(end 376.33275 -256.04216)
		(width 0.088646)
		(layer "In2.Cu")
		(net "M_F_CPU0_ALERT_N")
	)
	(arc
		(start 387.13156 -260.106414)
		(mid 386.944362 -260.056271)
		(end 386.757164 -260.106414)
		(width 0.088646)
		(layer "In2.Cu")
		(net "M_F_CPU0_ALERT_N")
	)
	(arc
		(start 387.696964 -260.106414)
		(mid 387.422765 -260.182249)
		(end 387.146292 -260.11505)
		(width 0.088646)
		(layer "In2.Cu")
		(net "M_F_CPU0_ALERT_N")
	)
	(arc
		(start 386.757164 -260.106414)
		(mid 386.482965 -260.182249)
		(end 386.206492 -260.11505)
		(width 0.088646)
		(layer "In2.Cu")
		(net "M_F_CPU0_ALERT_N")
	)
	(arc
		(start 382.058418 -260.106414)
		(mid 381.781605 -260.182284)
		(end 381.503174 -260.11251)
		(width 0.088646)
		(layer "In2.Cu")
		(net "M_F_CPU0_ALERT_N")
	)
	(arc
		(start 377.73356 -258.478782)
		(mid 377.5268 -258.272019)
		(end 377.451112 -257.989578)
		(width 0.088646)
		(layer "In2.Cu")
		(net "M_F_CPU0_ALERT_N")
	)
	(arc
		(start 379.61316 -258.478782)
		(mid 379.426106 -258.428732)
		(end 379.239018 -258.478782)
		(width 0.088646)
		(layer "In2.Cu")
		(net "M_F_CPU0_ALERT_N")
	)
	(arc
		(start 385.25196 -260.106414)
		(mid 385.064762 -260.056271)
		(end 384.877564 -260.106414)
		(width 0.088646)
		(layer "In2.Cu")
		(net "M_F_CPU0_ALERT_N")
	)
	(segment
		(start 125.267466 -248.528078)
		(end 125.267212 -248.527824)
		(width 0.20066)
		(layer "F.Cu")
		(net "M_E_CPU1_SB_RSP<1>")
	)
	(segment
		(start 157.682946 -243.216684)
		(end 158.813246 -243.216684)
		(width 0.20066)
		(layer "F.Cu")
		(net "M_E_CPU1_SB_RSP<1>")
	)
	(segment
		(start 125.267212 -248.527824)
		(end 125.267212 -247.992138)
		(width 0.20066)
		(layer "F.Cu")
		(net "M_E_CPU1_SB_RSP<1>")
	)
	(segment
		(start 127.899414 -248.316496)
		(end 127.884682 -248.30786)
		(width 0.088646)
		(layer "In6.Cu")
		(net "M_E_CPU1_SB_RSP<1>")
	)
	(segment
		(start 138.878564 -246.843804)
		(end 138.878564 -247.02389)
		(width 0.18288)
		(layer "In6.Cu")
		(net "M_E_CPU1_SB_RSP<1>")
	)
	(segment
		(start 136.445498 -247.34901)
		(end 135.979916 -247.814592)
		(width 0.088646)
		(layer "In6.Cu")
		(net "M_E_CPU1_SB_RSP<1>")
	)
	(segment
		(start 135.979916 -247.814592)
		(end 135.979916 -247.992138)
		(width 0.088646)
		(layer "In6.Cu")
		(net "M_E_CPU1_SB_RSP<1>")
	)
	(segment
		(start 152.927558 -243.63172)
		(end 151.072342 -245.486936)
		(width 0.18288)
		(layer "In6.Cu")
		(net "M_E_CPU1_SB_RSP<1>")
	)
	(segment
		(start 139.845796 -246.56796)
		(end 139.566142 -246.683784)
		(width 0.18288)
		(layer "In6.Cu")
		(net "M_E_CPU1_SB_RSP<1>")
	)
	(segment
		(start 151.072342 -245.486936)
		(end 141.990572 -245.486936)
		(width 0.18288)
		(layer "In6.Cu")
		(net "M_E_CPU1_SB_RSP<1>")
	)
	(segment
		(start 139.038584 -246.683784)
		(end 138.878564 -246.843804)
		(width 0.18288)
		(layer "In6.Cu")
		(net "M_E_CPU1_SB_RSP<1>")
	)
	(segment
		(start 137.239502 -246.737632)
		(end 136.8044 -246.737632)
		(width 0.18288)
		(layer "In6.Cu")
		(net "M_E_CPU1_SB_RSP<1>")
	)
	(segment
		(start 130.719068 -248.316496)
		(end 130.708654 -248.3104)
		(width 0.088646)
		(layer "In6.Cu")
		(net "M_E_CPU1_SB_RSP<1>")
	)
	(segment
		(start 156.518102 -243.216684)
		(end 156.103066 -243.63172)
		(width 0.18288)
		(layer "In6.Cu")
		(net "M_E_CPU1_SB_RSP<1>")
	)
	(segment
		(start 137.68578 -247.18391)
		(end 137.239502 -246.737632)
		(width 0.18288)
		(layer "In6.Cu")
		(net "M_E_CPU1_SB_RSP<1>")
	)
	(segment
		(start 125.99162 -248.299732)
		(end 125.267212 -247.992138)
		(width 0.088646)
		(layer "In6.Cu")
		(net "M_E_CPU1_SB_RSP<1>")
	)
	(segment
		(start 157.682946 -243.216684)
		(end 156.518102 -243.216684)
		(width 0.18288)
		(layer "In6.Cu")
		(net "M_E_CPU1_SB_RSP<1>")
	)
	(segment
		(start 131.658614 -248.316496)
		(end 131.6482 -248.3104)
		(width 0.088646)
		(layer "In6.Cu")
		(net "M_E_CPU1_SB_RSP<1>")
	)
	(segment
		(start 140.909548 -246.56796)
		(end 139.845796 -246.56796)
		(width 0.18288)
		(layer "In6.Cu")
		(net "M_E_CPU1_SB_RSP<1>")
	)
	(segment
		(start 136.8044 -246.737632)
		(end 136.599676 -246.737632)
		(width 0.088646)
		(layer "In6.Cu")
		(net "M_E_CPU1_SB_RSP<1>")
	)
	(segment
		(start 141.990572 -245.486936)
		(end 140.909548 -246.56796)
		(width 0.18288)
		(layer "In6.Cu")
		(net "M_E_CPU1_SB_RSP<1>")
	)
	(segment
		(start 138.878564 -247.02389)
		(end 138.718544 -247.18391)
		(width 0.18288)
		(layer "In6.Cu")
		(net "M_E_CPU1_SB_RSP<1>")
	)
	(segment
		(start 139.566142 -246.683784)
		(end 139.038584 -246.683784)
		(width 0.18288)
		(layer "In6.Cu")
		(net "M_E_CPU1_SB_RSP<1>")
	)
	(segment
		(start 138.718544 -247.18391)
		(end 137.68578 -247.18391)
		(width 0.18288)
		(layer "In6.Cu")
		(net "M_E_CPU1_SB_RSP<1>")
	)
	(segment
		(start 132.598668 -248.316496)
		(end 132.588254 -248.3104)
		(width 0.088646)
		(layer "In6.Cu")
		(net "M_E_CPU1_SB_RSP<1>")
	)
	(segment
		(start 128.839214 -248.316496)
		(end 128.824482 -248.30786)
		(width 0.088646)
		(layer "In6.Cu")
		(net "M_E_CPU1_SB_RSP<1>")
	)
	(segment
		(start 136.599676 -246.737632)
		(end 136.445498 -246.89181)
		(width 0.088646)
		(layer "In6.Cu")
		(net "M_E_CPU1_SB_RSP<1>")
	)
	(segment
		(start 136.445498 -246.89181)
		(end 136.445498 -247.34901)
		(width 0.088646)
		(layer "In6.Cu")
		(net "M_E_CPU1_SB_RSP<1>")
	)
	(segment
		(start 126.020068 -248.316496)
		(end 125.99162 -248.299732)
		(width 0.088646)
		(layer "In6.Cu")
		(net "M_E_CPU1_SB_RSP<1>")
	)
	(segment
		(start 135.801354 -248.311416)
		(end 135.792464 -248.316496)
		(width 0.088646)
		(layer "In6.Cu")
		(net "M_E_CPU1_SB_RSP<1>")
	)
	(segment
		(start 156.103066 -243.63172)
		(end 152.927558 -243.63172)
		(width 0.18288)
		(layer "In6.Cu")
		(net "M_E_CPU1_SB_RSP<1>")
	)
	(segment
		(start 126.959614 -248.316496)
		(end 126.9492 -248.3104)
		(width 0.088646)
		(layer "In6.Cu")
		(net "M_E_CPU1_SB_RSP<1>")
	)
	(arc
		(start 132.973064 -248.316496)
		(mid 132.785866 -248.366639)
		(end 132.598668 -248.316496)
		(width 0.088646)
		(layer "In6.Cu")
		(net "M_E_CPU1_SB_RSP<1>")
	)
	(arc
		(start 133.538468 -248.316496)
		(mid 133.255766 -248.240754)
		(end 132.973064 -248.316496)
		(width 0.088646)
		(layer "In6.Cu")
		(net "M_E_CPU1_SB_RSP<1>")
	)
	(arc
		(start 135.792464 -248.316496)
		(mid 135.605266 -248.366639)
		(end 135.418068 -248.316496)
		(width 0.088646)
		(layer "In6.Cu")
		(net "M_E_CPU1_SB_RSP<1>")
	)
	(arc
		(start 131.093464 -248.316496)
		(mid 130.906266 -248.366639)
		(end 130.719068 -248.316496)
		(width 0.088646)
		(layer "In6.Cu")
		(net "M_E_CPU1_SB_RSP<1>")
	)
	(arc
		(start 134.478268 -248.316496)
		(mid 134.195566 -248.240754)
		(end 133.912864 -248.316496)
		(width 0.088646)
		(layer "In6.Cu")
		(net "M_E_CPU1_SB_RSP<1>")
	)
	(arc
		(start 128.27381 -248.316496)
		(mid 128.086612 -248.366639)
		(end 127.899414 -248.316496)
		(width 0.088646)
		(layer "In6.Cu")
		(net "M_E_CPU1_SB_RSP<1>")
	)
	(arc
		(start 133.912864 -248.316496)
		(mid 133.725666 -248.366639)
		(end 133.538468 -248.316496)
		(width 0.088646)
		(layer "In6.Cu")
		(net "M_E_CPU1_SB_RSP<1>")
	)
	(arc
		(start 135.979916 -247.992138)
		(mid 135.932237 -248.175038)
		(end 135.801354 -248.311416)
		(width 0.088646)
		(layer "In6.Cu")
		(net "M_E_CPU1_SB_RSP<1>")
	)
	(arc
		(start 129.779014 -248.316496)
		(mid 129.496312 -248.240754)
		(end 129.21361 -248.316496)
		(width 0.088646)
		(layer "In6.Cu")
		(net "M_E_CPU1_SB_RSP<1>")
	)
	(arc
		(start 132.588254 -248.3104)
		(mid 132.309822 -248.240586)
		(end 132.03301 -248.316496)
		(width 0.088646)
		(layer "In6.Cu")
		(net "M_E_CPU1_SB_RSP<1>")
	)
	(arc
		(start 131.6482 -248.3104)
		(mid 131.370022 -248.240708)
		(end 131.093464 -248.316496)
		(width 0.088646)
		(layer "In6.Cu")
		(net "M_E_CPU1_SB_RSP<1>")
	)
	(arc
		(start 134.852664 -248.316496)
		(mid 134.665466 -248.366639)
		(end 134.478268 -248.316496)
		(width 0.088646)
		(layer "In6.Cu")
		(net "M_E_CPU1_SB_RSP<1>")
	)
	(arc
		(start 130.708654 -248.3104)
		(mid 130.430222 -248.240586)
		(end 130.15341 -248.316496)
		(width 0.088646)
		(layer "In6.Cu")
		(net "M_E_CPU1_SB_RSP<1>")
	)
	(arc
		(start 129.21361 -248.316496)
		(mid 129.026412 -248.366639)
		(end 128.839214 -248.316496)
		(width 0.088646)
		(layer "In6.Cu")
		(net "M_E_CPU1_SB_RSP<1>")
	)
	(arc
		(start 126.394464 -248.316496)
		(mid 126.207266 -248.366639)
		(end 126.020068 -248.316496)
		(width 0.088646)
		(layer "In6.Cu")
		(net "M_E_CPU1_SB_RSP<1>")
	)
	(arc
		(start 127.33401 -248.316496)
		(mid 127.146812 -248.366639)
		(end 126.959614 -248.316496)
		(width 0.088646)
		(layer "In6.Cu")
		(net "M_E_CPU1_SB_RSP<1>")
	)
	(arc
		(start 126.9492 -248.3104)
		(mid 126.671022 -248.240708)
		(end 126.394464 -248.316496)
		(width 0.088646)
		(layer "In6.Cu")
		(net "M_E_CPU1_SB_RSP<1>")
	)
	(arc
		(start 127.884682 -248.30786)
		(mid 127.608241 -248.240694)
		(end 127.33401 -248.316496)
		(width 0.088646)
		(layer "In6.Cu")
		(net "M_E_CPU1_SB_RSP<1>")
	)
	(arc
		(start 135.418068 -248.316496)
		(mid 135.135366 -248.240754)
		(end 134.852664 -248.316496)
		(width 0.088646)
		(layer "In6.Cu")
		(net "M_E_CPU1_SB_RSP<1>")
	)
	(arc
		(start 132.03301 -248.316496)
		(mid 131.845812 -248.366639)
		(end 131.658614 -248.316496)
		(width 0.088646)
		(layer "In6.Cu")
		(net "M_E_CPU1_SB_RSP<1>")
	)
	(arc
		(start 128.824482 -248.30786)
		(mid 128.548041 -248.240694)
		(end 128.27381 -248.316496)
		(width 0.088646)
		(layer "In6.Cu")
		(net "M_E_CPU1_SB_RSP<1>")
	)
	(arc
		(start 130.15341 -248.316496)
		(mid 129.966212 -248.366639)
		(end 129.779014 -248.316496)
		(width 0.088646)
		(layer "In6.Cu")
		(net "M_E_CPU1_SB_RSP<1>")
	)
	(segment
		(start 124.797312 -249.342148)
		(end 124.797566 -249.341894)
		(width 0.20066)
		(layer "F.Cu")
		(net "M_E_CPU1_SB_RSP<0>")
	)
	(segment
		(start 124.797566 -249.341894)
		(end 124.797566 -248.806208)
		(width 0.20066)
		(layer "F.Cu")
		(net "M_E_CPU1_SB_RSP<0>")
	)
	(segment
		(start 165.226746 -243.216684)
		(end 166.357046 -243.216684)
		(width 0.20066)
		(layer "F.Cu")
		(net "M_E_CPU1_SB_RSP<0>")
	)
	(segment
		(start 151.518112 -246.482616)
		(end 142.504414 -246.482616)
		(width 0.18288)
		(layer "In6.Cu")
		(net "M_E_CPU1_SB_RSP<0>")
	)
	(segment
		(start 159.389572 -244.699028)
		(end 159.204406 -244.872002)
		(width 0.18288)
		(layer "In6.Cu")
		(net "M_E_CPU1_SB_RSP<0>")
	)
	(segment
		(start 161.619438 -243.642134)
		(end 161.533586 -243.677694)
		(width 0.18288)
		(layer "In6.Cu")
		(net "M_E_CPU1_SB_RSP<0>")
	)
	(segment
		(start 152.121362 -245.879366)
		(end 151.518112 -246.482616)
		(width 0.18288)
		(layer "In6.Cu")
		(net "M_E_CPU1_SB_RSP<0>")
	)
	(segment
		(start 130.638296 -249.12193)
		(end 130.623564 -249.130566)
		(width 0.088646)
		(layer "In6.Cu")
		(net "M_E_CPU1_SB_RSP<0>")
	)
	(segment
		(start 164.801296 -243.642134)
		(end 161.619438 -243.642134)
		(width 0.18288)
		(layer "In6.Cu")
		(net "M_E_CPU1_SB_RSP<0>")
	)
	(segment
		(start 126.879096 -249.12193)
		(end 126.864364 -249.130566)
		(width 0.088646)
		(layer "In6.Cu")
		(net "M_E_CPU1_SB_RSP<0>")
	)
	(segment
		(start 156.771848 -245.879366)
		(end 152.121362 -245.879366)
		(width 0.18288)
		(layer "In6.Cu")
		(net "M_E_CPU1_SB_RSP<0>")
	)
	(segment
		(start 125.939296 -249.12193)
		(end 125.924564 -249.130566)
		(width 0.088646)
		(layer "In6.Cu")
		(net "M_E_CPU1_SB_RSP<0>")
	)
	(segment
		(start 139.866116 -248.09831)
		(end 139.713462 -248.250964)
		(width 0.18288)
		(layer "In6.Cu")
		(net "M_E_CPU1_SB_RSP<0>")
	)
	(segment
		(start 165.226746 -243.216684)
		(end 164.801296 -243.642134)
		(width 0.18288)
		(layer "In6.Cu")
		(net "M_E_CPU1_SB_RSP<0>")
	)
	(segment
		(start 137.691622 -248.250964)
		(end 136.812274 -248.250964)
		(width 0.088646)
		(layer "In6.Cu")
		(net "M_E_CPU1_SB_RSP<0>")
	)
	(segment
		(start 125.550168 -249.130566)
		(end 125.521212 -249.113548)
		(width 0.088646)
		(layer "In6.Cu")
		(net "M_E_CPU1_SB_RSP<0>")
	)
	(segment
		(start 135.898636 -249.45467)
		(end 135.299704 -249.45467)
		(width 0.088646)
		(layer "In6.Cu")
		(net "M_E_CPU1_SB_RSP<0>")
	)
	(segment
		(start 136.812274 -248.250964)
		(end 136.200388 -248.86285)
		(width 0.088646)
		(layer "In6.Cu")
		(net "M_E_CPU1_SB_RSP<0>")
	)
	(segment
		(start 136.200388 -249.152918)
		(end 135.898636 -249.45467)
		(width 0.088646)
		(layer "In6.Cu")
		(net "M_E_CPU1_SB_RSP<0>")
	)
	(segment
		(start 159.617156 -244.471444)
		(end 159.389572 -244.699028)
		(width 0.18288)
		(layer "In6.Cu")
		(net "M_E_CPU1_SB_RSP<0>")
	)
	(segment
		(start 129.693924 -249.12447)
		(end 129.68351 -249.130566)
		(width 0.088646)
		(layer "In6.Cu")
		(net "M_E_CPU1_SB_RSP<0>")
	)
	(segment
		(start 125.521212 -249.113548)
		(end 124.797566 -248.806208)
		(width 0.088646)
		(layer "In6.Cu")
		(net "M_E_CPU1_SB_RSP<0>")
	)
	(segment
		(start 159.204406 -244.872002)
		(end 156.771848 -245.879366)
		(width 0.18288)
		(layer "In6.Cu")
		(net "M_E_CPU1_SB_RSP<0>")
	)
	(segment
		(start 161.533586 -243.677694)
		(end 159.617156 -244.471444)
		(width 0.18288)
		(layer "In6.Cu")
		(net "M_E_CPU1_SB_RSP<0>")
	)
	(segment
		(start 128.754378 -249.12447)
		(end 128.743964 -249.130566)
		(width 0.088646)
		(layer "In6.Cu")
		(net "M_E_CPU1_SB_RSP<0>")
	)
	(segment
		(start 139.713462 -248.250964)
		(end 137.691622 -248.250964)
		(width 0.18288)
		(layer "In6.Cu")
		(net "M_E_CPU1_SB_RSP<0>")
	)
	(segment
		(start 142.504414 -246.482616)
		(end 140.88872 -248.09831)
		(width 0.18288)
		(layer "In6.Cu")
		(net "M_E_CPU1_SB_RSP<0>")
	)
	(segment
		(start 140.88872 -248.09831)
		(end 139.866116 -248.09831)
		(width 0.18288)
		(layer "In6.Cu")
		(net "M_E_CPU1_SB_RSP<0>")
	)
	(segment
		(start 135.299704 -249.45467)
		(end 135.065262 -249.220228)
		(width 0.088646)
		(layer "In6.Cu")
		(net "M_E_CPU1_SB_RSP<0>")
	)
	(segment
		(start 136.200388 -248.86285)
		(end 136.200388 -249.152918)
		(width 0.088646)
		(layer "In6.Cu")
		(net "M_E_CPU1_SB_RSP<0>")
	)
	(segment
		(start 127.818896 -249.12193)
		(end 127.804164 -249.130566)
		(width 0.088646)
		(layer "In6.Cu")
		(net "M_E_CPU1_SB_RSP<0>")
	)
	(arc
		(start 130.249168 -249.130566)
		(mid 129.972355 -249.054696)
		(end 129.693924 -249.12447)
		(width 0.088646)
		(layer "In6.Cu")
		(net "M_E_CPU1_SB_RSP<0>")
	)
	(arc
		(start 133.442964 -249.130566)
		(mid 133.255766 -249.180709)
		(end 133.068568 -249.130566)
		(width 0.088646)
		(layer "In6.Cu")
		(net "M_E_CPU1_SB_RSP<0>")
	)
	(arc
		(start 126.489968 -249.130566)
		(mid 126.215769 -249.054731)
		(end 125.939296 -249.12193)
		(width 0.088646)
		(layer "In6.Cu")
		(net "M_E_CPU1_SB_RSP<0>")
	)
	(arc
		(start 129.68351 -249.130566)
		(mid 129.496312 -249.180709)
		(end 129.309114 -249.130566)
		(width 0.088646)
		(layer "In6.Cu")
		(net "M_E_CPU1_SB_RSP<0>")
	)
	(arc
		(start 128.369568 -249.130566)
		(mid 128.095369 -249.054731)
		(end 127.818896 -249.12193)
		(width 0.088646)
		(layer "In6.Cu")
		(net "M_E_CPU1_SB_RSP<0>")
	)
	(arc
		(start 127.804164 -249.130566)
		(mid 127.616966 -249.180709)
		(end 127.429768 -249.130566)
		(width 0.088646)
		(layer "In6.Cu")
		(net "M_E_CPU1_SB_RSP<0>")
	)
	(arc
		(start 134.948168 -249.130566)
		(mid 134.665466 -249.05479)
		(end 134.382764 -249.130566)
		(width 0.088646)
		(layer "In6.Cu")
		(net "M_E_CPU1_SB_RSP<0>")
	)
	(arc
		(start 131.188968 -249.130566)
		(mid 130.914769 -249.054731)
		(end 130.638296 -249.12193)
		(width 0.088646)
		(layer "In6.Cu")
		(net "M_E_CPU1_SB_RSP<0>")
	)
	(arc
		(start 132.503164 -249.130566)
		(mid 132.315966 -249.180709)
		(end 132.128768 -249.130566)
		(width 0.088646)
		(layer "In6.Cu")
		(net "M_E_CPU1_SB_RSP<0>")
	)
	(arc
		(start 127.429768 -249.130566)
		(mid 127.155569 -249.054731)
		(end 126.879096 -249.12193)
		(width 0.088646)
		(layer "In6.Cu")
		(net "M_E_CPU1_SB_RSP<0>")
	)
	(arc
		(start 134.382764 -249.130566)
		(mid 134.195566 -249.180709)
		(end 134.008368 -249.130566)
		(width 0.088646)
		(layer "In6.Cu")
		(net "M_E_CPU1_SB_RSP<0>")
	)
	(arc
		(start 125.924564 -249.130566)
		(mid 125.737366 -249.180709)
		(end 125.550168 -249.130566)
		(width 0.088646)
		(layer "In6.Cu")
		(net "M_E_CPU1_SB_RSP<0>")
	)
	(arc
		(start 129.309114 -249.130566)
		(mid 129.032555 -249.054823)
		(end 128.754378 -249.12447)
		(width 0.088646)
		(layer "In6.Cu")
		(net "M_E_CPU1_SB_RSP<0>")
	)
	(arc
		(start 134.008368 -249.130566)
		(mid 133.725666 -249.05479)
		(end 133.442964 -249.130566)
		(width 0.088646)
		(layer "In6.Cu")
		(net "M_E_CPU1_SB_RSP<0>")
	)
	(arc
		(start 126.864364 -249.130566)
		(mid 126.677166 -249.180709)
		(end 126.489968 -249.130566)
		(width 0.088646)
		(layer "In6.Cu")
		(net "M_E_CPU1_SB_RSP<0>")
	)
	(arc
		(start 131.563364 -249.130566)
		(mid 131.376166 -249.180709)
		(end 131.188968 -249.130566)
		(width 0.088646)
		(layer "In6.Cu")
		(net "M_E_CPU1_SB_RSP<0>")
	)
	(arc
		(start 130.623564 -249.130566)
		(mid 130.436366 -249.180709)
		(end 130.249168 -249.130566)
		(width 0.088646)
		(layer "In6.Cu")
		(net "M_E_CPU1_SB_RSP<0>")
	)
	(arc
		(start 133.068568 -249.130566)
		(mid 132.785866 -249.05479)
		(end 132.503164 -249.130566)
		(width 0.088646)
		(layer "In6.Cu")
		(net "M_E_CPU1_SB_RSP<0>")
	)
	(arc
		(start 128.743964 -249.130566)
		(mid 128.556766 -249.180709)
		(end 128.369568 -249.130566)
		(width 0.088646)
		(layer "In6.Cu")
		(net "M_E_CPU1_SB_RSP<0>")
	)
	(arc
		(start 132.128768 -249.130566)
		(mid 131.846066 -249.05479)
		(end 131.563364 -249.130566)
		(width 0.088646)
		(layer "In6.Cu")
		(net "M_E_CPU1_SB_RSP<0>")
	)
	(arc
		(start 135.065262 -249.220228)
		(mid 135.009657 -249.171554)
		(end 134.948168 -249.130566)
		(width 0.088646)
		(layer "In6.Cu")
		(net "M_E_CPU1_SB_RSP<0>")
	)
	(segment
		(start 138.232388 -247.307354)
		(end 138.396218 -247.307354)
		(width 0.088646)
		(layer "F.Cu")
		(net "M_E_CPU1_SB_PAR")
	)
	(segment
		(start 168.683686 -247.25503)
		(end 168.483026 -247.45569)
		(width 0.20066)
		(layer "F.Cu")
		(net "M_E_CPU1_SB_PAR")
	)
	(segment
		(start 157.82798 -247.054116)
		(end 157.840426 -247.04167)
		(width 0.1016)
		(layer "F.Cu")
		(net "M_E_CPU1_SB_PAR")
	)
	(segment
		(start 160.520126 -247.271286)
		(end 160.520126 -247.377966)
		(width 0.20066)
		(layer "F.Cu")
		(net "M_E_CPU1_SB_PAR")
	)
	(segment
		(start 163.100766 -246.616728)
		(end 162.913314 -246.616728)
		(width 0.20066)
		(layer "F.Cu")
		(net "M_E_CPU1_SB_PAR")
	)
	(segment
		(start 137.954766 -247.714262)
		(end 137.627106 -247.714262)
		(width 0.088646)
		(layer "F.Cu")
		(net "M_E_CPU1_SB_PAR")
	)
	(segment
		(start 139.333732 -247.16105)
		(end 139.601956 -247.429274)
		(width 0.088646)
		(layer "F.Cu")
		(net "M_E_CPU1_SB_PAR")
	)
	(segment
		(start 165.368732 -247.04167)
		(end 165.352984 -247.057418)
		(width 0.1016)
		(layer "F.Cu")
		(net "M_E_CPU1_SB_PAR")
	)
	(segment
		(start 167.592502 -247.05437)
		(end 167.367458 -247.05437)
		(width 0.20066)
		(layer "F.Cu")
		(net "M_E_CPU1_SB_PAR")
	)
	(segment
		(start 165.335458 -247.057418)
		(end 164.165026 -247.057418)
		(width 0.20066)
		(layer "F.Cu")
		(net "M_E_CPU1_SB_PAR")
	)
	(segment
		(start 159.759396 -247.04167)
		(end 159.778954 -247.061228)
		(width 0.1016)
		(layer "F.Cu")
		(net "M_E_CPU1_SB_PAR")
	)
	(segment
		(start 140.582904 -246.884952)
		(end 140.77315 -246.884952)
		(width 0.088646)
		(layer "F.Cu")
		(net "M_E_CPU1_SB_PAR")
	)
	(segment
		(start 137.80008 -247.166384)
		(end 137.990834 -247.166384)
		(width 0.088646)
		(layer "F.Cu")
		(net "M_E_CPU1_SB_PAR")
	)
	(segment
		(start 138.711432 -247.16105)
		(end 139.333732 -247.16105)
		(width 0.088646)
		(layer "F.Cu")
		(net "M_E_CPU1_SB_PAR")
	)
	(segment
		(start 164.165026 -247.057418)
		(end 163.100766 -246.616728)
		(width 0.20066)
		(layer "F.Cu")
		(net "M_E_CPU1_SB_PAR")
	)
	(segment
		(start 151.745442 -247.531382)
		(end 156.632148 -247.531382)
		(width 0.20066)
		(layer "F.Cu")
		(net "M_E_CPU1_SB_PAR")
	)
	(segment
		(start 161.111438 -247.494552)
		(end 161.611564 -246.994426)
		(width 0.20066)
		(layer "F.Cu")
		(net "M_E_CPU1_SB_PAR")
	)
	(segment
		(start 162.305746 -246.616728)
		(end 162.913314 -246.616728)
		(width 0.20066)
		(layer "F.Cu")
		(net "M_E_CPU1_SB_PAR")
	)
	(segment
		(start 140.038582 -247.429274)
		(end 140.582904 -246.884952)
		(width 0.088646)
		(layer "F.Cu")
		(net "M_E_CPU1_SB_PAR")
	)
	(segment
		(start 160.520126 -247.377966)
		(end 160.636712 -247.494552)
		(width 0.20066)
		(layer "F.Cu")
		(net "M_E_CPU1_SB_PAR")
	)
	(segment
		(start 149.750272 -245.536212)
		(end 151.745442 -247.531382)
		(width 0.20066)
		(layer "F.Cu")
		(net "M_E_CPU1_SB_PAR")
	)
	(segment
		(start 156.632148 -247.531382)
		(end 157.109414 -247.054116)
		(width 0.20066)
		(layer "F.Cu")
		(net "M_E_CPU1_SB_PAR")
	)
	(segment
		(start 138.159236 -247.23598)
		(end 138.228832 -247.30583)
		(width 0.088646)
		(layer "F.Cu")
		(net "M_E_CPU1_SB_PAR")
	)
	(segment
		(start 146.562064 -245.536212)
		(end 149.750272 -245.536212)
		(width 0.20066)
		(layer "F.Cu")
		(net "M_E_CPU1_SB_PAR")
	)
	(segment
		(start 160.636712 -247.494552)
		(end 161.111438 -247.494552)
		(width 0.20066)
		(layer "F.Cu")
		(net "M_E_CPU1_SB_PAR")
	)
	(segment
		(start 169.066718 -246.616728)
		(end 168.683686 -246.99976)
		(width 0.20066)
		(layer "F.Cu")
		(net "M_E_CPU1_SB_PAR")
	)
	(segment
		(start 160.310068 -247.061228)
		(end 160.520126 -247.271286)
		(width 0.20066)
		(layer "F.Cu")
		(net "M_E_CPU1_SB_PAR")
	)
	(segment
		(start 168.483026 -247.45569)
		(end 167.993822 -247.45569)
		(width 0.20066)
		(layer "F.Cu")
		(net "M_E_CPU1_SB_PAR")
	)
	(segment
		(start 167.367458 -247.05437)
		(end 167.354758 -247.04167)
		(width 0.1016)
		(layer "F.Cu")
		(net "M_E_CPU1_SB_PAR")
	)
	(segment
		(start 157.840426 -247.04167)
		(end 159.759396 -247.04167)
		(width 0.1016)
		(layer "F.Cu")
		(net "M_E_CPU1_SB_PAR")
	)
	(segment
		(start 157.823154 -247.054116)
		(end 157.82798 -247.054116)
		(width 0.101854)
		(layer "F.Cu")
		(net "M_E_CPU1_SB_PAR")
	)
	(segment
		(start 168.683686 -246.99976)
		(end 168.683686 -247.25503)
		(width 0.20066)
		(layer "F.Cu")
		(net "M_E_CPU1_SB_PAR")
	)
	(segment
		(start 139.601956 -247.429274)
		(end 140.038582 -247.429274)
		(width 0.088646)
		(layer "F.Cu")
		(net "M_E_CPU1_SB_PAR")
	)
	(segment
		(start 161.611564 -246.994426)
		(end 161.928048 -246.994426)
		(width 0.20066)
		(layer "F.Cu")
		(net "M_E_CPU1_SB_PAR")
	)
	(segment
		(start 161.928048 -246.994426)
		(end 162.305746 -246.616728)
		(width 0.20066)
		(layer "F.Cu")
		(net "M_E_CPU1_SB_PAR")
	)
	(segment
		(start 159.778954 -247.061228)
		(end 160.310068 -247.061228)
		(width 0.20066)
		(layer "F.Cu")
		(net "M_E_CPU1_SB_PAR")
	)
	(segment
		(start 145.544032 -246.554244)
		(end 146.562064 -245.536212)
		(width 0.20066)
		(layer "F.Cu")
		(net "M_E_CPU1_SB_PAR")
	)
	(segment
		(start 140.77315 -246.884952)
		(end 145.213324 -246.884952)
		(width 0.1016)
		(layer "F.Cu")
		(net "M_E_CPU1_SB_PAR")
	)
	(segment
		(start 165.352984 -247.057418)
		(end 165.335458 -247.057418)
		(width 0.101854)
		(layer "F.Cu")
		(net "M_E_CPU1_SB_PAR")
	)
	(segment
		(start 145.213324 -246.884952)
		(end 145.544032 -246.554244)
		(width 0.1016)
		(layer "F.Cu")
		(net "M_E_CPU1_SB_PAR")
	)
	(segment
		(start 157.109414 -247.054116)
		(end 157.823154 -247.054116)
		(width 0.20066)
		(layer "F.Cu")
		(net "M_E_CPU1_SB_PAR")
	)
	(segment
		(start 170.457114 -246.616728)
		(end 169.066718 -246.616728)
		(width 0.20066)
		(layer "F.Cu")
		(net "M_E_CPU1_SB_PAR")
	)
	(segment
		(start 167.993822 -247.45569)
		(end 167.592502 -247.05437)
		(width 0.20066)
		(layer "F.Cu")
		(net "M_E_CPU1_SB_PAR")
	)
	(segment
		(start 167.354758 -247.04167)
		(end 165.368732 -247.04167)
		(width 0.1016)
		(layer "F.Cu")
		(net "M_E_CPU1_SB_PAR")
	)
	(segment
		(start 137.552176 -247.367552)
		(end 137.720324 -247.199404)
		(width 0.088646)
		(layer "F.Cu")
		(net "M_E_CPU1_SB_PAR")
	)
	(arc
		(start 138.66495 -247.17121)
		(mid 138.687648 -247.163643)
		(end 138.711432 -247.16105)
		(width 0.088646)
		(layer "F.Cu")
		(net "M_E_CPU1_SB_PAR")
	)
	(arc
		(start 138.62431 -247.202452)
		(mid 138.645191 -247.18756)
		(end 138.66495 -247.17121)
		(width 0.088646)
		(layer "F.Cu")
		(net "M_E_CPU1_SB_PAR")
	)
	(arc
		(start 137.552176 -247.683274)
		(mid 137.48684 -247.52545)
		(end 137.552176 -247.367552)
		(width 0.088646)
		(layer "F.Cu")
		(net "M_E_CPU1_SB_PAR")
	)
	(arc
		(start 137.720324 -247.199404)
		(mid 137.756916 -247.174954)
		(end 137.80008 -247.166384)
		(width 0.088646)
		(layer "F.Cu")
		(net "M_E_CPU1_SB_PAR")
	)
	(arc
		(start 137.990834 -247.166384)
		(mid 138.081966 -247.184418)
		(end 138.159236 -247.23598)
		(width 0.088646)
		(layer "F.Cu")
		(net "M_E_CPU1_SB_PAR")
	)
	(arc
		(start 138.228832 -247.30583)
		(mid 138.230464 -247.30692)
		(end 138.232388 -247.307354)
		(width 0.088646)
		(layer "F.Cu")
		(net "M_E_CPU1_SB_PAR")
	)
	(arc
		(start 137.627106 -247.714262)
		(mid 137.586573 -247.706199)
		(end 137.552176 -247.683274)
		(width 0.088646)
		(layer "F.Cu")
		(net "M_E_CPU1_SB_PAR")
	)
	(arc
		(start 138.396218 -247.307354)
		(mid 138.514278 -247.263634)
		(end 138.62431 -247.202452)
		(width 0.088646)
		(layer "F.Cu")
		(net "M_E_CPU1_SB_PAR")
	)
	(segment
		(start 139.563602 -243.110766)
		(end 140.13307 -243.110766)
		(width 0.088646)
		(layer "F.Cu")
		(net "M_E_CPU1_SB_DQS_DP<9>")
	)
	(segment
		(start 138.958574 -243.396008)
		(end 139.27836 -243.396008)
		(width 0.088646)
		(layer "F.Cu")
		(net "M_E_CPU1_SB_DQS_DP<9>")
	)
	(segment
		(start 149.714204 -238.229394)
		(end 150.316184 -238.229394)
		(width 0.20066)
		(layer "F.Cu")
		(net "M_E_CPU1_SB_DQS_DP<9>")
	)
	(segment
		(start 153.221944 -238.229394)
		(end 153.346404 -238.353854)
		(width 0.20066)
		(layer "F.Cu")
		(net "M_E_CPU1_SB_DQS_DP<9>")
	)
	(segment
		(start 157.699964 -238.029242)
		(end 157.786578 -238.116618)
		(width 0.20066)
		(layer "F.Cu")
		(net "M_E_CPU1_SB_DQS_DP<9>")
	)
	(segment
		(start 137.014712 -242.795806)
		(end 137.063988 -242.74653)
		(width 0.088646)
		(layer "F.Cu")
		(net "M_E_CPU1_SB_DQS_DP<9>")
	)
	(segment
		(start 156.318204 -238.229394)
		(end 156.95295 -237.594648)
		(width 0.20066)
		(layer "F.Cu")
		(net "M_E_CPU1_SB_DQS_DP<9>")
	)
	(segment
		(start 149.589744 -238.353854)
		(end 149.714204 -238.229394)
		(width 0.20066)
		(layer "F.Cu")
		(net "M_E_CPU1_SB_DQS_DP<9>")
	)
	(segment
		(start 161.089594 -238.277654)
		(end 160.782 -238.277654)
		(width 0.20066)
		(layer "F.Cu")
		(net "M_E_CPU1_SB_DQS_DP<9>")
	)
	(segment
		(start 161.487612 -238.561118)
		(end 161.373058 -238.561118)
		(width 0.20066)
		(layer "F.Cu")
		(net "M_E_CPU1_SB_DQS_DP<9>")
	)
	(segment
		(start 164.338508 -238.541814)
		(end 163.905438 -238.541814)
		(width 0.101854)
		(layer "F.Cu")
		(net "M_E_CPU1_SB_DQS_DP<9>")
	)
	(segment
		(start 147.200366 -238.192564)
		(end 147.886166 -238.192564)
		(width 0.1524)
		(layer "F.Cu")
		(net "M_E_CPU1_SB_DQS_DP<9>")
	)
	(segment
		(start 139.27836 -243.396008)
		(end 139.563602 -243.110766)
		(width 0.088646)
		(layer "F.Cu")
		(net "M_E_CPU1_SB_DQS_DP<9>")
	)
	(segment
		(start 155.525724 -238.229394)
		(end 156.318204 -238.229394)
		(width 0.20066)
		(layer "F.Cu")
		(net "M_E_CPU1_SB_DQS_DP<9>")
	)
	(segment
		(start 151.769064 -238.229394)
		(end 151.893524 -238.353854)
		(width 0.20066)
		(layer "F.Cu")
		(net "M_E_CPU1_SB_DQS_DP<9>")
	)
	(segment
		(start 151.167084 -238.229394)
		(end 151.769064 -238.229394)
		(width 0.20066)
		(layer "F.Cu")
		(net "M_E_CPU1_SB_DQS_DP<9>")
	)
	(segment
		(start 148.863304 -238.229394)
		(end 148.987764 -238.353854)
		(width 0.20066)
		(layer "F.Cu")
		(net "M_E_CPU1_SB_DQS_DP<9>")
	)
	(segment
		(start 160.782 -238.277654)
		(end 160.380426 -237.87608)
		(width 0.20066)
		(layer "F.Cu")
		(net "M_E_CPU1_SB_DQS_DP<9>")
	)
	(segment
		(start 153.948384 -238.353854)
		(end 154.072844 -238.229394)
		(width 0.20066)
		(layer "F.Cu")
		(net "M_E_CPU1_SB_DQS_DP<9>")
	)
	(segment
		(start 140.13307 -243.110766)
		(end 140.75537 -242.488466)
		(width 0.088646)
		(layer "F.Cu")
		(net "M_E_CPU1_SB_DQS_DP<9>")
	)
	(segment
		(start 156.95295 -237.594648)
		(end 157.571694 -237.594648)
		(width 0.20066)
		(layer "F.Cu")
		(net "M_E_CPU1_SB_DQS_DP<9>")
	)
	(segment
		(start 151.042624 -238.353854)
		(end 151.167084 -238.229394)
		(width 0.20066)
		(layer "F.Cu")
		(net "M_E_CPU1_SB_DQS_DP<9>")
	)
	(segment
		(start 154.072844 -238.229394)
		(end 154.674824 -238.229394)
		(width 0.20066)
		(layer "F.Cu")
		(net "M_E_CPU1_SB_DQS_DP<9>")
	)
	(segment
		(start 147.961096 -238.229394)
		(end 148.863304 -238.229394)
		(width 0.20066)
		(layer "F.Cu")
		(net "M_E_CPU1_SB_DQS_DP<9>")
	)
	(segment
		(start 143.987774 -241.405156)
		(end 147.200366 -238.192564)
		(width 0.1524)
		(layer "F.Cu")
		(net "M_E_CPU1_SB_DQS_DP<9>")
	)
	(segment
		(start 147.886166 -238.192564)
		(end 147.922996 -238.229394)
		(width 0.1524)
		(layer "F.Cu")
		(net "M_E_CPU1_SB_DQS_DP<9>")
	)
	(segment
		(start 137.270744 -242.811046)
		(end 137.394696 -242.988592)
		(width 0.088646)
		(layer "F.Cu")
		(net "M_E_CPU1_SB_DQS_DP<9>")
	)
	(segment
		(start 138.95832 -243.396262)
		(end 138.958574 -243.396008)
		(width 0.088646)
		(layer "F.Cu")
		(net "M_E_CPU1_SB_DQS_DP<9>")
	)
	(segment
		(start 165.725094 -237.899194)
		(end 165.441122 -237.899194)
		(width 0.20066)
		(layer "F.Cu")
		(net "M_E_CPU1_SB_DQS_DP<9>")
	)
	(segment
		(start 155.401264 -238.353854)
		(end 155.525724 -238.229394)
		(width 0.20066)
		(layer "F.Cu")
		(net "M_E_CPU1_SB_DQS_DP<9>")
	)
	(segment
		(start 154.674824 -238.229394)
		(end 154.799284 -238.353854)
		(width 0.20066)
		(layer "F.Cu")
		(net "M_E_CPU1_SB_DQS_DP<9>")
	)
	(segment
		(start 164.448744 -238.541814)
		(end 164.338508 -238.541814)
		(width 0.20066)
		(layer "F.Cu")
		(net "M_E_CPU1_SB_DQS_DP<9>")
	)
	(segment
		(start 161.915856 -238.541814)
		(end 161.506916 -238.541814)
		(width 0.101854)
		(layer "F.Cu")
		(net "M_E_CPU1_SB_DQS_DP<9>")
	)
	(segment
		(start 163.905438 -238.541814)
		(end 161.915856 -238.541814)
		(width 0.1016)
		(layer "F.Cu")
		(net "M_E_CPU1_SB_DQS_DP<9>")
	)
	(segment
		(start 159.643064 -237.87608)
		(end 159.402526 -238.116618)
		(width 0.20066)
		(layer "F.Cu")
		(net "M_E_CPU1_SB_DQS_DP<9>")
	)
	(segment
		(start 138.894312 -243.396262)
		(end 138.95832 -243.396262)
		(width 0.088646)
		(layer "F.Cu")
		(net "M_E_CPU1_SB_DQS_DP<9>")
	)
	(segment
		(start 160.380426 -237.87608)
		(end 159.643064 -237.87608)
		(width 0.20066)
		(layer "F.Cu")
		(net "M_E_CPU1_SB_DQS_DP<9>")
	)
	(segment
		(start 165.121082 -238.219234)
		(end 164.771324 -238.219234)
		(width 0.20066)
		(layer "F.Cu")
		(net "M_E_CPU1_SB_DQS_DP<9>")
	)
	(segment
		(start 148.987764 -238.353854)
		(end 149.589744 -238.353854)
		(width 0.20066)
		(layer "F.Cu")
		(net "M_E_CPU1_SB_DQS_DP<9>")
	)
	(segment
		(start 140.75537 -242.488466)
		(end 140.800582 -242.488466)
		(width 0.088646)
		(layer "F.Cu")
		(net "M_E_CPU1_SB_DQS_DP<9>")
	)
	(segment
		(start 140.800582 -242.488466)
		(end 140.816076 -242.472972)
		(width 0.088646)
		(layer "F.Cu")
		(net "M_E_CPU1_SB_DQS_DP<9>")
	)
	(segment
		(start 157.571694 -237.594648)
		(end 157.699964 -237.722918)
		(width 0.20066)
		(layer "F.Cu")
		(net "M_E_CPU1_SB_DQS_DP<9>")
	)
	(segment
		(start 164.771324 -238.219234)
		(end 164.448744 -238.541814)
		(width 0.20066)
		(layer "F.Cu")
		(net "M_E_CPU1_SB_DQS_DP<9>")
	)
	(segment
		(start 166.357046 -238.116618)
		(end 165.942518 -238.116618)
		(width 0.20066)
		(layer "F.Cu")
		(net "M_E_CPU1_SB_DQS_DP<9>")
	)
	(segment
		(start 151.893524 -238.353854)
		(end 152.495504 -238.353854)
		(width 0.20066)
		(layer "F.Cu")
		(net "M_E_CPU1_SB_DQS_DP<9>")
	)
	(segment
		(start 150.316184 -238.229394)
		(end 150.440644 -238.353854)
		(width 0.20066)
		(layer "F.Cu")
		(net "M_E_CPU1_SB_DQS_DP<9>")
	)
	(segment
		(start 159.402526 -238.116618)
		(end 158.813246 -238.116618)
		(width 0.20066)
		(layer "F.Cu")
		(net "M_E_CPU1_SB_DQS_DP<9>")
	)
	(segment
		(start 152.495504 -238.353854)
		(end 152.619964 -238.229394)
		(width 0.20066)
		(layer "F.Cu")
		(net "M_E_CPU1_SB_DQS_DP<9>")
	)
	(segment
		(start 137.642854 -243.303806)
		(end 137.672064 -243.32057)
		(width 0.088646)
		(layer "F.Cu")
		(net "M_E_CPU1_SB_DQS_DP<9>")
	)
	(segment
		(start 137.47877 -243.16817)
		(end 137.521696 -243.211096)
		(width 0.088646)
		(layer "F.Cu")
		(net "M_E_CPU1_SB_DQS_DP<9>")
	)
	(segment
		(start 153.346404 -238.353854)
		(end 153.948384 -238.353854)
		(width 0.20066)
		(layer "F.Cu")
		(net "M_E_CPU1_SB_DQS_DP<9>")
	)
	(segment
		(start 154.799284 -238.353854)
		(end 155.401264 -238.353854)
		(width 0.20066)
		(layer "F.Cu")
		(net "M_E_CPU1_SB_DQS_DP<9>")
	)
	(segment
		(start 147.922996 -238.229394)
		(end 147.961096 -238.229394)
		(width 0.1524)
		(layer "F.Cu")
		(net "M_E_CPU1_SB_DQS_DP<9>")
	)
	(segment
		(start 152.619964 -238.229394)
		(end 153.221944 -238.229394)
		(width 0.20066)
		(layer "F.Cu")
		(net "M_E_CPU1_SB_DQS_DP<9>")
	)
	(segment
		(start 137.014712 -242.830858)
		(end 137.014712 -242.795806)
		(width 0.088646)
		(layer "F.Cu")
		(net "M_E_CPU1_SB_DQS_DP<9>")
	)
	(segment
		(start 140.816076 -242.472972)
		(end 141.883892 -241.405156)
		(width 0.1524)
		(layer "F.Cu")
		(net "M_E_CPU1_SB_DQS_DP<9>")
	)
	(segment
		(start 161.506916 -238.541814)
		(end 161.487612 -238.561118)
		(width 0.101854)
		(layer "F.Cu")
		(net "M_E_CPU1_SB_DQS_DP<9>")
	)
	(segment
		(start 157.699964 -237.722918)
		(end 157.699964 -238.029242)
		(width 0.20066)
		(layer "F.Cu")
		(net "M_E_CPU1_SB_DQS_DP<9>")
	)
	(segment
		(start 157.786578 -238.116618)
		(end 158.813246 -238.116618)
		(width 0.20066)
		(layer "F.Cu")
		(net "M_E_CPU1_SB_DQS_DP<9>")
	)
	(segment
		(start 141.883892 -241.405156)
		(end 143.987774 -241.405156)
		(width 0.1524)
		(layer "F.Cu")
		(net "M_E_CPU1_SB_DQS_DP<9>")
	)
	(segment
		(start 161.373058 -238.561118)
		(end 161.089594 -238.277654)
		(width 0.20066)
		(layer "F.Cu")
		(net "M_E_CPU1_SB_DQS_DP<9>")
	)
	(segment
		(start 165.942518 -238.116618)
		(end 165.725094 -237.899194)
		(width 0.20066)
		(layer "F.Cu")
		(net "M_E_CPU1_SB_DQS_DP<9>")
	)
	(segment
		(start 150.440644 -238.353854)
		(end 151.042624 -238.353854)
		(width 0.20066)
		(layer "F.Cu")
		(net "M_E_CPU1_SB_DQS_DP<9>")
	)
	(segment
		(start 165.441122 -237.899194)
		(end 165.121082 -238.219234)
		(width 0.20066)
		(layer "F.Cu")
		(net "M_E_CPU1_SB_DQS_DP<9>")
	)
	(arc
		(start 137.428224 -243.071142)
		(mid 137.44602 -243.12355)
		(end 137.47877 -243.16817)
		(width 0.088646)
		(layer "F.Cu")
		(net "M_E_CPU1_SB_DQS_DP<9>")
	)
	(arc
		(start 137.672064 -243.32057)
		(mid 137.954766 -243.396312)
		(end 138.237468 -243.32057)
		(width 0.088646)
		(layer "F.Cu")
		(net "M_E_CPU1_SB_DQS_DP<9>")
	)
	(arc
		(start 138.611864 -243.32057)
		(mid 138.748106 -243.377004)
		(end 138.894312 -243.396262)
		(width 0.088646)
		(layer "F.Cu")
		(net "M_E_CPU1_SB_DQS_DP<9>")
	)
	(arc
		(start 138.237468 -243.32057)
		(mid 138.424666 -243.270427)
		(end 138.611864 -243.32057)
		(width 0.088646)
		(layer "F.Cu")
		(net "M_E_CPU1_SB_DQS_DP<9>")
	)
	(arc
		(start 137.394696 -242.988592)
		(mid 137.415939 -243.028046)
		(end 137.428224 -243.071142)
		(width 0.088646)
		(layer "F.Cu")
		(net "M_E_CPU1_SB_DQS_DP<9>")
	)
	(arc
		(start 137.154666 -242.724686)
		(mid 137.219718 -242.758434)
		(end 137.270744 -242.811046)
		(width 0.088646)
		(layer "F.Cu")
		(net "M_E_CPU1_SB_DQS_DP<9>")
	)
	(arc
		(start 137.521696 -243.211096)
		(mid 137.579217 -243.261445)
		(end 137.642854 -243.303806)
		(width 0.088646)
		(layer "F.Cu")
		(net "M_E_CPU1_SB_DQS_DP<9>")
	)
	(arc
		(start 137.063988 -242.74653)
		(mid 137.106232 -242.722818)
		(end 137.154666 -242.724686)
		(width 0.088646)
		(layer "F.Cu")
		(net "M_E_CPU1_SB_DQS_DP<9>")
	)
	(segment
		(start 140.162534 -227.314506)
		(end 140.162534 -227.269802)
		(width 0.088646)
		(layer "F.Cu")
		(net "M_E_CPU1_SB_DQS_DP<8>")
	)
	(segment
		(start 167.360092 -198.591678)
		(end 165.347396 -198.591678)
		(width 0.1016)
		(layer "F.Cu")
		(net "M_E_CPU1_SB_DQS_DP<8>")
	)
	(segment
		(start 159.811974 -198.570596)
		(end 159.823658 -198.570596)
		(width 0.101854)
		(layer "F.Cu")
		(net "M_E_CPU1_SB_DQS_DP<8>")
	)
	(segment
		(start 168.597834 -198.839328)
		(end 167.944292 -198.839328)
		(width 0.20066)
		(layer "F.Cu")
		(net "M_E_CPU1_SB_DQS_DP<8>")
	)
	(segment
		(start 144.853406 -202.407012)
		(end 146.068288 -202.407012)
		(width 0.20066)
		(layer "F.Cu")
		(net "M_E_CPU1_SB_DQS_DP<8>")
	)
	(segment
		(start 169.88917 -199.01662)
		(end 169.620946 -199.284844)
		(width 0.20066)
		(layer "F.Cu")
		(net "M_E_CPU1_SB_DQS_DP<8>")
	)
	(segment
		(start 167.367458 -198.584312)
		(end 167.360092 -198.591678)
		(width 0.1016)
		(layer "F.Cu")
		(net "M_E_CPU1_SB_DQS_DP<8>")
	)
	(segment
		(start 140.206476 -211.185252)
		(end 140.206476 -211.147152)
		(width 0.1524)
		(layer "F.Cu")
		(net "M_E_CPU1_SB_DQS_DP<8>")
	)
	(segment
		(start 138.708384 -227.856542)
		(end 138.78687 -227.813362)
		(width 0.088646)
		(layer "F.Cu")
		(net "M_E_CPU1_SB_DQS_DP<8>")
	)
	(segment
		(start 139.663932 -227.813362)
		(end 140.162534 -227.314506)
		(width 0.088646)
		(layer "F.Cu")
		(net "M_E_CPU1_SB_DQS_DP<8>")
	)
	(segment
		(start 165.335458 -198.584566)
		(end 165.024308 -198.584566)
		(width 0.20066)
		(layer "F.Cu")
		(net "M_E_CPU1_SB_DQS_DP<8>")
	)
	(segment
		(start 165.024308 -198.584566)
		(end 164.76599 -198.842884)
		(width 0.20066)
		(layer "F.Cu")
		(net "M_E_CPU1_SB_DQS_DP<8>")
	)
	(segment
		(start 159.790892 -198.591678)
		(end 159.811974 -198.570596)
		(width 0.1016)
		(layer "F.Cu")
		(net "M_E_CPU1_SB_DQS_DP<8>")
	)
	(segment
		(start 146.068288 -202.407012)
		(end 146.584162 -202.193398)
		(width 0.20066)
		(layer "F.Cu")
		(net "M_E_CPU1_SB_DQS_DP<8>")
	)
	(segment
		(start 157.810708 -198.591678)
		(end 159.790892 -198.591678)
		(width 0.1016)
		(layer "F.Cu")
		(net "M_E_CPU1_SB_DQS_DP<8>")
	)
	(segment
		(start 160.130998 -198.570596)
		(end 160.42894 -198.868538)
		(width 0.20066)
		(layer "F.Cu")
		(net "M_E_CPU1_SB_DQS_DP<8>")
	)
	(segment
		(start 140.951712 -226.480624)
		(end 140.951712 -213.739984)
		(width 0.1524)
		(layer "F.Cu")
		(net "M_E_CPU1_SB_DQS_DP<8>")
	)
	(segment
		(start 159.823658 -198.570596)
		(end 160.130998 -198.570596)
		(width 0.20066)
		(layer "F.Cu")
		(net "M_E_CPU1_SB_DQS_DP<8>")
	)
	(segment
		(start 138.78687 -227.813362)
		(end 139.663932 -227.813362)
		(width 0.088646)
		(layer "F.Cu")
		(net "M_E_CPU1_SB_DQS_DP<8>")
	)
	(segment
		(start 143.841978 -202.825858)
		(end 144.853406 -202.407012)
		(width 0.20066)
		(layer "F.Cu")
		(net "M_E_CPU1_SB_DQS_DP<8>")
	)
	(segment
		(start 138.128248 -228.1809)
		(end 138.136122 -228.173026)
		(width 0.088646)
		(layer "F.Cu")
		(net "M_E_CPU1_SB_DQS_DP<8>")
	)
	(segment
		(start 140.206476 -211.147152)
		(end 140.206476 -208.905856)
		(width 0.20066)
		(layer "F.Cu")
		(net "M_E_CPU1_SB_DQS_DP<8>")
	)
	(segment
		(start 140.178028 -227.254308)
		(end 140.951712 -226.480624)
		(width 0.1524)
		(layer "F.Cu")
		(net "M_E_CPU1_SB_DQS_DP<8>")
	)
	(segment
		(start 140.951712 -213.739984)
		(end 140.761466 -212.780626)
		(width 0.1524)
		(layer "F.Cu")
		(net "M_E_CPU1_SB_DQS_DP<8>")
	)
	(segment
		(start 164.062664 -199.267826)
		(end 163.66744 -199.267826)
		(width 0.20066)
		(layer "F.Cu")
		(net "M_E_CPU1_SB_DQS_DP<8>")
	)
	(segment
		(start 162.157664 -199.267572)
		(end 162.408616 -199.01662)
		(width 0.20066)
		(layer "F.Cu")
		(net "M_E_CPU1_SB_DQS_DP<8>")
	)
	(segment
		(start 157.17266 -198.81977)
		(end 157.414722 -198.577708)
		(width 0.20066)
		(layer "F.Cu")
		(net "M_E_CPU1_SB_DQS_DP<8>")
	)
	(segment
		(start 170.457114 -199.01662)
		(end 169.88917 -199.01662)
		(width 0.20066)
		(layer "F.Cu")
		(net "M_E_CPU1_SB_DQS_DP<8>")
	)
	(segment
		(start 149.401784 -199.375776)
		(end 155.55595 -199.375776)
		(width 0.20066)
		(layer "F.Cu")
		(net "M_E_CPU1_SB_DQS_DP<8>")
	)
	(segment
		(start 137.954766 -228.1809)
		(end 138.128248 -228.1809)
		(width 0.088646)
		(layer "F.Cu")
		(net "M_E_CPU1_SB_DQS_DP<8>")
	)
	(segment
		(start 165.340284 -198.584566)
		(end 165.335458 -198.584566)
		(width 0.101854)
		(layer "F.Cu")
		(net "M_E_CPU1_SB_DQS_DP<8>")
	)
	(segment
		(start 160.96615 -198.868538)
		(end 161.92881 -199.267572)
		(width 0.20066)
		(layer "F.Cu")
		(net "M_E_CPU1_SB_DQS_DP<8>")
	)
	(segment
		(start 140.761466 -212.780626)
		(end 140.243306 -211.530692)
		(width 0.1524)
		(layer "F.Cu")
		(net "M_E_CPU1_SB_DQS_DP<8>")
	)
	(segment
		(start 163.416234 -199.01662)
		(end 162.913314 -199.01662)
		(width 0.20066)
		(layer "F.Cu")
		(net "M_E_CPU1_SB_DQS_DP<8>")
	)
	(segment
		(start 138.180572 -228.161088)
		(end 138.708384 -227.856542)
		(width 0.088646)
		(layer "F.Cu")
		(net "M_E_CPU1_SB_DQS_DP<8>")
	)
	(segment
		(start 167.944292 -198.839328)
		(end 167.689276 -198.584312)
		(width 0.20066)
		(layer "F.Cu")
		(net "M_E_CPU1_SB_DQS_DP<8>")
	)
	(segment
		(start 161.92881 -199.267572)
		(end 162.157664 -199.267572)
		(width 0.20066)
		(layer "F.Cu")
		(net "M_E_CPU1_SB_DQS_DP<8>")
	)
	(segment
		(start 140.243306 -211.530692)
		(end 140.243306 -211.222082)
		(width 0.1524)
		(layer "F.Cu")
		(net "M_E_CPU1_SB_DQS_DP<8>")
	)
	(segment
		(start 157.791658 -198.577708)
		(end 157.796738 -198.577708)
		(width 0.101854)
		(layer "F.Cu")
		(net "M_E_CPU1_SB_DQS_DP<8>")
	)
	(segment
		(start 156.897832 -198.81977)
		(end 157.17266 -198.81977)
		(width 0.20066)
		(layer "F.Cu")
		(net "M_E_CPU1_SB_DQS_DP<8>")
	)
	(segment
		(start 165.347396 -198.591678)
		(end 165.340284 -198.584566)
		(width 0.1016)
		(layer "F.Cu")
		(net "M_E_CPU1_SB_DQS_DP<8>")
	)
	(segment
		(start 169.620946 -199.284844)
		(end 169.04335 -199.284844)
		(width 0.20066)
		(layer "F.Cu")
		(net "M_E_CPU1_SB_DQS_DP<8>")
	)
	(segment
		(start 146.584162 -202.193398)
		(end 149.401784 -199.375776)
		(width 0.20066)
		(layer "F.Cu")
		(net "M_E_CPU1_SB_DQS_DP<8>")
	)
	(segment
		(start 140.700252 -206.990442)
		(end 141.423644 -205.244192)
		(width 0.20066)
		(layer "F.Cu")
		(net "M_E_CPU1_SB_DQS_DP<8>")
	)
	(segment
		(start 160.42894 -198.868538)
		(end 160.96615 -198.868538)
		(width 0.20066)
		(layer "F.Cu")
		(net "M_E_CPU1_SB_DQS_DP<8>")
	)
	(segment
		(start 140.48359 -207.513174)
		(end 140.699998 -206.990696)
		(width 0.20066)
		(layer "F.Cu")
		(net "M_E_CPU1_SB_DQS_DP<8>")
	)
	(segment
		(start 140.243306 -211.222082)
		(end 140.206476 -211.185252)
		(width 0.1524)
		(layer "F.Cu")
		(net "M_E_CPU1_SB_DQS_DP<8>")
	)
	(segment
		(start 163.66744 -199.267826)
		(end 163.416234 -199.01662)
		(width 0.20066)
		(layer "F.Cu")
		(net "M_E_CPU1_SB_DQS_DP<8>")
	)
	(segment
		(start 141.423644 -205.244192)
		(end 143.841978 -202.825858)
		(width 0.20066)
		(layer "F.Cu")
		(net "M_E_CPU1_SB_DQS_DP<8>")
	)
	(segment
		(start 164.76599 -198.842884)
		(end 164.487606 -198.842884)
		(width 0.20066)
		(layer "F.Cu")
		(net "M_E_CPU1_SB_DQS_DP<8>")
	)
	(segment
		(start 140.162534 -227.269802)
		(end 140.178028 -227.254308)
		(width 0.088646)
		(layer "F.Cu")
		(net "M_E_CPU1_SB_DQS_DP<8>")
	)
	(segment
		(start 157.414722 -198.577708)
		(end 157.791658 -198.577708)
		(width 0.20066)
		(layer "F.Cu")
		(net "M_E_CPU1_SB_DQS_DP<8>")
	)
	(segment
		(start 162.408616 -199.01662)
		(end 162.913314 -199.01662)
		(width 0.20066)
		(layer "F.Cu")
		(net "M_E_CPU1_SB_DQS_DP<8>")
	)
	(segment
		(start 157.796738 -198.577708)
		(end 157.810708 -198.591678)
		(width 0.1016)
		(layer "F.Cu")
		(net "M_E_CPU1_SB_DQS_DP<8>")
	)
	(segment
		(start 155.55595 -199.375776)
		(end 156.897832 -198.81977)
		(width 0.20066)
		(layer "F.Cu")
		(net "M_E_CPU1_SB_DQS_DP<8>")
	)
	(segment
		(start 140.206476 -208.905856)
		(end 140.48359 -207.513174)
		(width 0.20066)
		(layer "F.Cu")
		(net "M_E_CPU1_SB_DQS_DP<8>")
	)
	(segment
		(start 164.487606 -198.842884)
		(end 164.062664 -199.267826)
		(width 0.20066)
		(layer "F.Cu")
		(net "M_E_CPU1_SB_DQS_DP<8>")
	)
	(segment
		(start 169.04335 -199.284844)
		(end 168.597834 -198.839328)
		(width 0.20066)
		(layer "F.Cu")
		(net "M_E_CPU1_SB_DQS_DP<8>")
	)
	(segment
		(start 167.689276 -198.584312)
		(end 167.367458 -198.584312)
		(width 0.20066)
		(layer "F.Cu")
		(net "M_E_CPU1_SB_DQS_DP<8>")
	)
	(segment
		(start 140.699998 -206.990696)
		(end 140.700252 -206.990442)
		(width 0.20066)
		(layer "F.Cu")
		(net "M_E_CPU1_SB_DQS_DP<8>")
	)
	(arc
		(start 138.136122 -228.173026)
		(mid 138.159138 -228.169995)
		(end 138.180572 -228.161088)
		(width 0.088646)
		(layer "F.Cu")
		(net "M_E_CPU1_SB_DQS_DP<8>")
	)
	(segment
		(start 163.431728 -208.366614)
		(end 162.913314 -208.366614)
		(width 0.20066)
		(layer "F.Cu")
		(net "M_E_CPU1_SB_DQS_DP<7>")
	)
	(segment
		(start 167.367458 -207.935068)
		(end 167.360854 -207.941672)
		(width 0.1016)
		(layer "F.Cu")
		(net "M_E_CPU1_SB_DQS_DP<7>")
	)
	(segment
		(start 140.469112 -232.525062)
		(end 144.863312 -228.130862)
		(width 0.1524)
		(layer "F.Cu")
		(net "M_E_CPU1_SB_DQS_DP<7>")
	)
	(segment
		(start 160.379156 -208.214214)
		(end 160.566608 -208.214214)
		(width 0.20066)
		(layer "F.Cu")
		(net "M_E_CPU1_SB_DQS_DP<7>")
	)
	(segment
		(start 140.453618 -232.540556)
		(end 140.469112 -232.525062)
		(width 0.088646)
		(layer "F.Cu")
		(net "M_E_CPU1_SB_DQS_DP<7>")
	)
	(segment
		(start 159.819594 -207.936338)
		(end 159.823658 -207.936338)
		(width 0.1016)
		(layer "F.Cu")
		(net "M_E_CPU1_SB_DQS_DP<7>")
	)
	(segment
		(start 169.690034 -208.634584)
		(end 169.260266 -208.634584)
		(width 0.20066)
		(layer "F.Cu")
		(net "M_E_CPU1_SB_DQS_DP<7>")
	)
	(segment
		(start 138.929364 -232.695496)
		(end 140.343636 -232.695496)
		(width 0.088646)
		(layer "F.Cu")
		(net "M_E_CPU1_SB_DQS_DP<7>")
	)
	(segment
		(start 165.381686 -207.941672)
		(end 165.361366 -207.921352)
		(width 0.1016)
		(layer "F.Cu")
		(net "M_E_CPU1_SB_DQS_DP<7>")
	)
	(segment
		(start 162.266122 -208.65211)
		(end 162.551618 -208.366614)
		(width 0.20066)
		(layer "F.Cu")
		(net "M_E_CPU1_SB_DQS_DP<7>")
	)
	(segment
		(start 152.34412 -208.527904)
		(end 153.331672 -208.118964)
		(width 0.20066)
		(layer "F.Cu")
		(net "M_E_CPU1_SB_DQS_DP<7>")
	)
	(segment
		(start 145.315686 -215.556338)
		(end 145.34261 -215.529414)
		(width 0.1524)
		(layer "F.Cu")
		(net "M_E_CPU1_SB_DQS_DP<7>")
	)
	(segment
		(start 137.954766 -233.064304)
		(end 138.491468 -232.856278)
		(width 0.088646)
		(layer "F.Cu")
		(net "M_E_CPU1_SB_DQS_DP<7>")
	)
	(segment
		(start 169.260266 -208.634584)
		(end 168.81475 -208.189068)
		(width 0.20066)
		(layer "F.Cu")
		(net "M_E_CPU1_SB_DQS_DP<7>")
	)
	(segment
		(start 163.888928 -208.617566)
		(end 163.68268 -208.617566)
		(width 0.20066)
		(layer "F.Cu")
		(net "M_E_CPU1_SB_DQS_DP<7>")
	)
	(segment
		(start 140.343636 -232.695496)
		(end 140.453618 -232.585514)
		(width 0.088646)
		(layer "F.Cu")
		(net "M_E_CPU1_SB_DQS_DP<7>")
	)
	(segment
		(start 163.68268 -208.617566)
		(end 163.431728 -208.366614)
		(width 0.20066)
		(layer "F.Cu")
		(net "M_E_CPU1_SB_DQS_DP<7>")
	)
	(segment
		(start 138.783822 -232.71988)
		(end 138.7856 -232.719372)
		(width 0.088646)
		(layer "F.Cu")
		(net "M_E_CPU1_SB_DQS_DP<7>")
	)
	(segment
		(start 165.335458 -207.921352)
		(end 165.030658 -207.921352)
		(width 0.20066)
		(layer "F.Cu")
		(net "M_E_CPU1_SB_DQS_DP<7>")
	)
	(segment
		(start 164.78123 -208.17078)
		(end 164.335714 -208.17078)
		(width 0.20066)
		(layer "F.Cu")
		(net "M_E_CPU1_SB_DQS_DP<7>")
	)
	(segment
		(start 145.34261 -215.529414)
		(end 152.34412 -208.527904)
		(width 0.20066)
		(layer "F.Cu")
		(net "M_E_CPU1_SB_DQS_DP<7>")
	)
	(segment
		(start 159.52597 -207.941672)
		(end 159.81426 -207.941672)
		(width 0.1016)
		(layer "F.Cu")
		(net "M_E_CPU1_SB_DQS_DP<7>")
	)
	(segment
		(start 168.132252 -208.189068)
		(end 167.878252 -207.935068)
		(width 0.20066)
		(layer "F.Cu")
		(net "M_E_CPU1_SB_DQS_DP<7>")
	)
	(segment
		(start 160.566608 -208.214214)
		(end 162.00882 -208.65211)
		(width 0.20066)
		(layer "F.Cu")
		(net "M_E_CPU1_SB_DQS_DP<7>")
	)
	(segment
		(start 165.030658 -207.921352)
		(end 164.78123 -208.17078)
		(width 0.20066)
		(layer "F.Cu")
		(net "M_E_CPU1_SB_DQS_DP<7>")
	)
	(segment
		(start 162.00882 -208.65211)
		(end 162.266122 -208.65211)
		(width 0.20066)
		(layer "F.Cu")
		(net "M_E_CPU1_SB_DQS_DP<7>")
	)
	(segment
		(start 157.520894 -207.931004)
		(end 157.791658 -207.931004)
		(width 0.20066)
		(layer "F.Cu")
		(net "M_E_CPU1_SB_DQS_DP<7>")
	)
	(segment
		(start 162.551618 -208.366614)
		(end 162.913314 -208.366614)
		(width 0.20066)
		(layer "F.Cu")
		(net "M_E_CPU1_SB_DQS_DP<7>")
	)
	(segment
		(start 157.802326 -207.941672)
		(end 158.049722 -207.941672)
		(width 0.101854)
		(layer "F.Cu")
		(net "M_E_CPU1_SB_DQS_DP<7>")
	)
	(segment
		(start 167.878252 -207.935068)
		(end 167.367458 -207.935068)
		(width 0.20066)
		(layer "F.Cu")
		(net "M_E_CPU1_SB_DQS_DP<7>")
	)
	(segment
		(start 145.315686 -215.608916)
		(end 145.315686 -215.556338)
		(width 0.1524)
		(layer "F.Cu")
		(net "M_E_CPU1_SB_DQS_DP<7>")
	)
	(segment
		(start 159.12592 -207.941672)
		(end 159.52597 -207.941672)
		(width 0.101854)
		(layer "F.Cu")
		(net "M_E_CPU1_SB_DQS_DP<7>")
	)
	(segment
		(start 170.457114 -208.366614)
		(end 169.958004 -208.366614)
		(width 0.20066)
		(layer "F.Cu")
		(net "M_E_CPU1_SB_DQS_DP<7>")
	)
	(segment
		(start 140.453618 -232.585514)
		(end 140.453618 -232.540556)
		(width 0.088646)
		(layer "F.Cu")
		(net "M_E_CPU1_SB_DQS_DP<7>")
	)
	(segment
		(start 157.791658 -207.931004)
		(end 157.802326 -207.941672)
		(width 0.101854)
		(layer "F.Cu")
		(net "M_E_CPU1_SB_DQS_DP<7>")
	)
	(segment
		(start 157.332934 -208.118964)
		(end 157.520894 -207.931004)
		(width 0.20066)
		(layer "F.Cu")
		(net "M_E_CPU1_SB_DQS_DP<7>")
	)
	(segment
		(start 153.331672 -208.118964)
		(end 157.332934 -208.118964)
		(width 0.20066)
		(layer "F.Cu")
		(net "M_E_CPU1_SB_DQS_DP<7>")
	)
	(segment
		(start 165.361366 -207.921352)
		(end 165.356286 -207.921352)
		(width 0.1016)
		(layer "F.Cu")
		(net "M_E_CPU1_SB_DQS_DP<7>")
	)
	(segment
		(start 159.823658 -207.936338)
		(end 160.10128 -207.936338)
		(width 0.20066)
		(layer "F.Cu")
		(net "M_E_CPU1_SB_DQS_DP<7>")
	)
	(segment
		(start 168.81475 -208.189068)
		(end 168.132252 -208.189068)
		(width 0.20066)
		(layer "F.Cu")
		(net "M_E_CPU1_SB_DQS_DP<7>")
	)
	(segment
		(start 160.10128 -207.936338)
		(end 160.379156 -208.214214)
		(width 0.20066)
		(layer "F.Cu")
		(net "M_E_CPU1_SB_DQS_DP<7>")
	)
	(segment
		(start 158.049722 -207.941672)
		(end 159.12592 -207.941672)
		(width 0.1016)
		(layer "F.Cu")
		(net "M_E_CPU1_SB_DQS_DP<7>")
	)
	(segment
		(start 167.360854 -207.941672)
		(end 165.381686 -207.941672)
		(width 0.1016)
		(layer "F.Cu")
		(net "M_E_CPU1_SB_DQS_DP<7>")
	)
	(segment
		(start 144.863312 -216.06129)
		(end 145.315686 -215.608916)
		(width 0.1524)
		(layer "F.Cu")
		(net "M_E_CPU1_SB_DQS_DP<7>")
	)
	(segment
		(start 164.335714 -208.17078)
		(end 163.888928 -208.617566)
		(width 0.20066)
		(layer "F.Cu")
		(net "M_E_CPU1_SB_DQS_DP<7>")
	)
	(segment
		(start 165.356286 -207.921352)
		(end 165.335458 -207.921352)
		(width 0.101854)
		(layer "F.Cu")
		(net "M_E_CPU1_SB_DQS_DP<7>")
	)
	(segment
		(start 159.81426 -207.941672)
		(end 159.819594 -207.936338)
		(width 0.1016)
		(layer "F.Cu")
		(net "M_E_CPU1_SB_DQS_DP<7>")
	)
	(segment
		(start 144.863312 -228.130862)
		(end 144.863312 -216.06129)
		(width 0.1524)
		(layer "F.Cu")
		(net "M_E_CPU1_SB_DQS_DP<7>")
	)
	(segment
		(start 169.958004 -208.366614)
		(end 169.690034 -208.634584)
		(width 0.20066)
		(layer "F.Cu")
		(net "M_E_CPU1_SB_DQS_DP<7>")
	)
	(arc
		(start 138.615674 -232.796588)
		(mid 138.697862 -232.754099)
		(end 138.783822 -232.71988)
		(width 0.088646)
		(layer "F.Cu")
		(net "M_E_CPU1_SB_DQS_DP<7>")
	)
	(arc
		(start 138.491468 -232.856278)
		(mid 138.554738 -232.828862)
		(end 138.615674 -232.796588)
		(width 0.088646)
		(layer "F.Cu")
		(net "M_E_CPU1_SB_DQS_DP<7>")
	)
	(arc
		(start 138.7856 -232.719372)
		(mid 138.856497 -232.701505)
		(end 138.929364 -232.695496)
		(width 0.088646)
		(layer "F.Cu")
		(net "M_E_CPU1_SB_DQS_DP<7>")
	)
	(segment
		(start 170.457114 -217.716608)
		(end 169.88917 -217.716608)
		(width 0.20066)
		(layer "F.Cu")
		(net "M_E_CPU1_SB_DQS_DP<6>")
	)
	(segment
		(start 156.901388 -217.27541)
		(end 157.791658 -217.27541)
		(width 0.20066)
		(layer "F.Cu")
		(net "M_E_CPU1_SB_DQS_DP<6>")
	)
	(segment
		(start 165.347396 -217.291666)
		(end 165.340284 -217.284554)
		(width 0.1016)
		(layer "F.Cu")
		(net "M_E_CPU1_SB_DQS_DP<6>")
	)
	(segment
		(start 167.944292 -217.539316)
		(end 167.689276 -217.2843)
		(width 0.20066)
		(layer "F.Cu")
		(net "M_E_CPU1_SB_DQS_DP<6>")
	)
	(segment
		(start 160.660588 -217.568526)
		(end 160.96615 -217.568526)
		(width 0.20066)
		(layer "F.Cu")
		(net "M_E_CPU1_SB_DQS_DP<6>")
	)
	(segment
		(start 152.656032 -223.928686)
		(end 152.656032 -221.295722)
		(width 0.20066)
		(layer "F.Cu")
		(net "M_E_CPU1_SB_DQS_DP<6>")
	)
	(segment
		(start 141.100048 -236.660436)
		(end 141.131798 -236.628686)
		(width 0.088646)
		(layer "F.Cu")
		(net "M_E_CPU1_SB_DQS_DP<6>")
	)
	(segment
		(start 161.92881 -217.96756)
		(end 162.157664 -217.96756)
		(width 0.20066)
		(layer "F.Cu")
		(net "M_E_CPU1_SB_DQS_DP<6>")
	)
	(segment
		(start 167.689276 -217.2843)
		(end 167.367458 -217.2843)
		(width 0.20066)
		(layer "F.Cu")
		(net "M_E_CPU1_SB_DQS_DP<6>")
	)
	(segment
		(start 138.829288 -237.589568)
		(end 139.62761 -237.589568)
		(width 0.088646)
		(layer "F.Cu")
		(net "M_E_CPU1_SB_DQS_DP<6>")
	)
	(segment
		(start 159.6898 -217.291666)
		(end 159.823658 -217.291666)
		(width 0.101854)
		(layer "F.Cu")
		(net "M_E_CPU1_SB_DQS_DP<6>")
	)
	(segment
		(start 157.81274 -217.291666)
		(end 159.6898 -217.291666)
		(width 0.1016)
		(layer "F.Cu")
		(net "M_E_CPU1_SB_DQS_DP<6>")
	)
	(segment
		(start 137.954766 -237.947454)
		(end 137.955274 -237.94593)
		(width 0.088646)
		(layer "F.Cu")
		(net "M_E_CPU1_SB_DQS_DP<6>")
	)
	(segment
		(start 149.643084 -226.941634)
		(end 152.656032 -223.928686)
		(width 0.20066)
		(layer "F.Cu")
		(net "M_E_CPU1_SB_DQS_DP<6>")
	)
	(segment
		(start 149.61616 -226.968558)
		(end 149.643084 -226.941634)
		(width 0.1524)
		(layer "F.Cu")
		(net "M_E_CPU1_SB_DQS_DP<6>")
	)
	(segment
		(start 167.367458 -217.2843)
		(end 167.360092 -217.291666)
		(width 0.1016)
		(layer "F.Cu")
		(net "M_E_CPU1_SB_DQS_DP<6>")
	)
	(segment
		(start 160.372806 -217.280744)
		(end 160.660588 -217.568526)
		(width 0.20066)
		(layer "F.Cu")
		(net "M_E_CPU1_SB_DQS_DP<6>")
	)
	(segment
		(start 141.131798 -236.628686)
		(end 141.153896 -236.628686)
		(width 0.088646)
		(layer "F.Cu")
		(net "M_E_CPU1_SB_DQS_DP<6>")
	)
	(segment
		(start 139.62761 -237.589568)
		(end 140.556742 -236.660436)
		(width 0.088646)
		(layer "F.Cu")
		(net "M_E_CPU1_SB_DQS_DP<6>")
	)
	(segment
		(start 157.796484 -217.27541)
		(end 157.81274 -217.291666)
		(width 0.1016)
		(layer "F.Cu")
		(net "M_E_CPU1_SB_DQS_DP<6>")
	)
	(segment
		(start 163.827206 -217.967814)
		(end 163.671504 -217.967814)
		(width 0.20066)
		(layer "F.Cu")
		(net "M_E_CPU1_SB_DQS_DP<6>")
	)
	(segment
		(start 162.157664 -217.96756)
		(end 162.408616 -217.716608)
		(width 0.20066)
		(layer "F.Cu")
		(net "M_E_CPU1_SB_DQS_DP<6>")
	)
	(segment
		(start 149.61616 -227.020374)
		(end 149.61616 -226.968558)
		(width 0.1524)
		(layer "F.Cu")
		(net "M_E_CPU1_SB_DQS_DP<6>")
	)
	(segment
		(start 169.620946 -217.984832)
		(end 169.04335 -217.984832)
		(width 0.20066)
		(layer "F.Cu")
		(net "M_E_CPU1_SB_DQS_DP<6>")
	)
	(segment
		(start 164.76599 -217.542872)
		(end 164.487606 -217.542872)
		(width 0.20066)
		(layer "F.Cu")
		(net "M_E_CPU1_SB_DQS_DP<6>")
	)
	(segment
		(start 167.360092 -217.291666)
		(end 165.347396 -217.291666)
		(width 0.1016)
		(layer "F.Cu")
		(net "M_E_CPU1_SB_DQS_DP<6>")
	)
	(segment
		(start 160.96615 -217.568526)
		(end 161.92881 -217.96756)
		(width 0.20066)
		(layer "F.Cu")
		(net "M_E_CPU1_SB_DQS_DP<6>")
	)
	(segment
		(start 149.249638 -227.386896)
		(end 149.61616 -227.020374)
		(width 0.1524)
		(layer "F.Cu")
		(net "M_E_CPU1_SB_DQS_DP<6>")
	)
	(segment
		(start 152.656032 -221.295722)
		(end 156.061918 -217.889836)
		(width 0.20066)
		(layer "F.Cu")
		(net "M_E_CPU1_SB_DQS_DP<6>")
	)
	(segment
		(start 168.597834 -217.539316)
		(end 167.944292 -217.539316)
		(width 0.20066)
		(layer "F.Cu")
		(net "M_E_CPU1_SB_DQS_DP<6>")
	)
	(segment
		(start 165.335458 -217.284554)
		(end 165.024308 -217.284554)
		(width 0.20066)
		(layer "F.Cu")
		(net "M_E_CPU1_SB_DQS_DP<6>")
	)
	(segment
		(start 159.83458 -217.280744)
		(end 160.372806 -217.280744)
		(width 0.20066)
		(layer "F.Cu")
		(net "M_E_CPU1_SB_DQS_DP<6>")
	)
	(segment
		(start 141.953488 -236.628686)
		(end 148.774912 -229.807262)
		(width 0.1524)
		(layer "F.Cu")
		(net "M_E_CPU1_SB_DQS_DP<6>")
	)
	(segment
		(start 156.454602 -217.291412)
		(end 156.885386 -217.291412)
		(width 0.20066)
		(layer "F.Cu")
		(net "M_E_CPU1_SB_DQS_DP<6>")
	)
	(segment
		(start 169.88917 -217.716608)
		(end 169.620946 -217.984832)
		(width 0.20066)
		(layer "F.Cu")
		(net "M_E_CPU1_SB_DQS_DP<6>")
	)
	(segment
		(start 163.671504 -217.967814)
		(end 163.420298 -217.716608)
		(width 0.20066)
		(layer "F.Cu")
		(net "M_E_CPU1_SB_DQS_DP<6>")
	)
	(segment
		(start 141.153896 -236.628686)
		(end 141.953488 -236.628686)
		(width 0.1524)
		(layer "F.Cu")
		(net "M_E_CPU1_SB_DQS_DP<6>")
	)
	(segment
		(start 148.774912 -228.534214)
		(end 149.249638 -227.386896)
		(width 0.1524)
		(layer "F.Cu")
		(net "M_E_CPU1_SB_DQS_DP<6>")
	)
	(segment
		(start 169.04335 -217.984832)
		(end 168.597834 -217.539316)
		(width 0.20066)
		(layer "F.Cu")
		(net "M_E_CPU1_SB_DQS_DP<6>")
	)
	(segment
		(start 148.774912 -229.807262)
		(end 148.774912 -228.534214)
		(width 0.1524)
		(layer "F.Cu")
		(net "M_E_CPU1_SB_DQS_DP<6>")
	)
	(segment
		(start 156.885386 -217.291412)
		(end 156.901388 -217.27541)
		(width 0.20066)
		(layer "F.Cu")
		(net "M_E_CPU1_SB_DQS_DP<6>")
	)
	(segment
		(start 165.024308 -217.284554)
		(end 164.76599 -217.542872)
		(width 0.20066)
		(layer "F.Cu")
		(net "M_E_CPU1_SB_DQS_DP<6>")
	)
	(segment
		(start 159.823658 -217.291666)
		(end 159.83458 -217.280744)
		(width 0.20066)
		(layer "F.Cu")
		(net "M_E_CPU1_SB_DQS_DP<6>")
	)
	(segment
		(start 163.420298 -217.716608)
		(end 162.913314 -217.716608)
		(width 0.20066)
		(layer "F.Cu")
		(net "M_E_CPU1_SB_DQS_DP<6>")
	)
	(segment
		(start 156.061918 -217.684096)
		(end 156.454602 -217.291412)
		(width 0.20066)
		(layer "F.Cu")
		(net "M_E_CPU1_SB_DQS_DP<6>")
	)
	(segment
		(start 162.408616 -217.716608)
		(end 162.913314 -217.716608)
		(width 0.20066)
		(layer "F.Cu")
		(net "M_E_CPU1_SB_DQS_DP<6>")
	)
	(segment
		(start 137.955274 -237.94593)
		(end 138.829288 -237.589568)
		(width 0.088646)
		(layer "F.Cu")
		(net "M_E_CPU1_SB_DQS_DP<6>")
	)
	(segment
		(start 157.791658 -217.27541)
		(end 157.796484 -217.27541)
		(width 0.101854)
		(layer "F.Cu")
		(net "M_E_CPU1_SB_DQS_DP<6>")
	)
	(segment
		(start 156.061918 -217.889836)
		(end 156.061918 -217.684096)
		(width 0.20066)
		(layer "F.Cu")
		(net "M_E_CPU1_SB_DQS_DP<6>")
	)
	(segment
		(start 164.229288 -217.80119)
		(end 163.827206 -217.967814)
		(width 0.20066)
		(layer "F.Cu")
		(net "M_E_CPU1_SB_DQS_DP<6>")
	)
	(segment
		(start 165.340284 -217.284554)
		(end 165.335458 -217.284554)
		(width 0.101854)
		(layer "F.Cu")
		(net "M_E_CPU1_SB_DQS_DP<6>")
	)
	(segment
		(start 140.556742 -236.660436)
		(end 141.100048 -236.660436)
		(width 0.088646)
		(layer "F.Cu")
		(net "M_E_CPU1_SB_DQS_DP<6>")
	)
	(segment
		(start 164.487606 -217.542872)
		(end 164.229288 -217.80119)
		(width 0.20066)
		(layer "F.Cu")
		(net "M_E_CPU1_SB_DQS_DP<6>")
	)
	(segment
		(start 169.88917 -227.066602)
		(end 169.620946 -227.334826)
		(width 0.20066)
		(layer "F.Cu")
		(net "M_E_CPU1_SB_DQS_DP<5>")
	)
	(segment
		(start 161.783014 -227.066602)
		(end 162.913314 -227.066602)
		(width 0.20066)
		(layer "F.Cu")
		(net "M_E_CPU1_SB_DQS_DP<5>")
	)
	(segment
		(start 165.024308 -226.634548)
		(end 164.76599 -226.892866)
		(width 0.20066)
		(layer "F.Cu")
		(net "M_E_CPU1_SB_DQS_DP<5>")
	)
	(segment
		(start 163.757864 -227.317808)
		(end 163.506658 -227.066602)
		(width 0.20066)
		(layer "F.Cu")
		(net "M_E_CPU1_SB_DQS_DP<5>")
	)
	(segment
		(start 167.944292 -226.88931)
		(end 167.689276 -226.634294)
		(width 0.20066)
		(layer "F.Cu")
		(net "M_E_CPU1_SB_DQS_DP<5>")
	)
	(segment
		(start 164.062664 -227.317808)
		(end 163.757864 -227.317808)
		(width 0.20066)
		(layer "F.Cu")
		(net "M_E_CPU1_SB_DQS_DP<5>")
	)
	(segment
		(start 169.620946 -227.334826)
		(end 169.04335 -227.334826)
		(width 0.20066)
		(layer "F.Cu")
		(net "M_E_CPU1_SB_DQS_DP<5>")
	)
	(segment
		(start 165.335458 -226.634548)
		(end 165.024308 -226.634548)
		(width 0.20066)
		(layer "F.Cu")
		(net "M_E_CPU1_SB_DQS_DP<5>")
	)
	(segment
		(start 165.340284 -226.634548)
		(end 165.335458 -226.634548)
		(width 0.101854)
		(layer "F.Cu")
		(net "M_E_CPU1_SB_DQS_DP<5>")
	)
	(segment
		(start 164.76599 -226.892866)
		(end 164.487606 -226.892866)
		(width 0.20066)
		(layer "F.Cu")
		(net "M_E_CPU1_SB_DQS_DP<5>")
	)
	(segment
		(start 169.04335 -227.334826)
		(end 168.597834 -226.88931)
		(width 0.20066)
		(layer "F.Cu")
		(net "M_E_CPU1_SB_DQS_DP<5>")
	)
	(segment
		(start 165.347396 -226.64166)
		(end 165.340284 -226.634548)
		(width 0.1016)
		(layer "F.Cu")
		(net "M_E_CPU1_SB_DQS_DP<5>")
	)
	(segment
		(start 134.665466 -235.506006)
		(end 134.665466 -234.970066)
		(width 0.20066)
		(layer "F.Cu")
		(net "M_E_CPU1_SB_DQS_DP<5>")
	)
	(segment
		(start 167.689276 -226.634294)
		(end 167.367458 -226.634294)
		(width 0.20066)
		(layer "F.Cu")
		(net "M_E_CPU1_SB_DQS_DP<5>")
	)
	(segment
		(start 168.597834 -226.88931)
		(end 167.944292 -226.88931)
		(width 0.20066)
		(layer "F.Cu")
		(net "M_E_CPU1_SB_DQS_DP<5>")
	)
	(segment
		(start 167.360092 -226.64166)
		(end 165.347396 -226.64166)
		(width 0.1016)
		(layer "F.Cu")
		(net "M_E_CPU1_SB_DQS_DP<5>")
	)
	(segment
		(start 170.457114 -227.066602)
		(end 169.88917 -227.066602)
		(width 0.20066)
		(layer "F.Cu")
		(net "M_E_CPU1_SB_DQS_DP<5>")
	)
	(segment
		(start 163.506658 -227.066602)
		(end 162.913314 -227.066602)
		(width 0.20066)
		(layer "F.Cu")
		(net "M_E_CPU1_SB_DQS_DP<5>")
	)
	(segment
		(start 164.487606 -226.892866)
		(end 164.062664 -227.317808)
		(width 0.20066)
		(layer "F.Cu")
		(net "M_E_CPU1_SB_DQS_DP<5>")
	)
	(segment
		(start 167.367458 -226.634294)
		(end 167.360092 -226.64166)
		(width 0.1016)
		(layer "F.Cu")
		(net "M_E_CPU1_SB_DQS_DP<5>")
	)
	(segment
		(start 136.136126 -234.532678)
		(end 136.02081 -234.532678)
		(width 0.088646)
		(layer "In2.Cu")
		(net "M_E_CPU1_SB_DQS_DP<5>")
	)
	(segment
		(start 159.398462 -226.880928)
		(end 158.1658 -226.880928)
		(width 0.18288)
		(layer "In2.Cu")
		(net "M_E_CPU1_SB_DQS_DP<5>")
	)
	(segment
		(start 139.397994 -233.861864)
		(end 138.913362 -234.346496)
		(width 0.18288)
		(layer "In2.Cu")
		(net "M_E_CPU1_SB_DQS_DP<5>")
	)
	(segment
		(start 135.178038 -234.970066)
		(end 134.665466 -234.970066)
		(width 0.088646)
		(layer "In2.Cu")
		(net "M_E_CPU1_SB_DQS_DP<5>")
	)
	(segment
		(start 136.151874 -234.528614)
		(end 136.136126 -234.532678)
		(width 0.088646)
		(layer "In2.Cu")
		(net "M_E_CPU1_SB_DQS_DP<5>")
	)
	(segment
		(start 158.1658 -226.880928)
		(end 157.92704 -226.642168)
		(width 0.18288)
		(layer "In2.Cu")
		(net "M_E_CPU1_SB_DQS_DP<5>")
	)
	(segment
		(start 136.153652 -234.527852)
		(end 136.153398 -234.528106)
		(width 0.088646)
		(layer "In2.Cu")
		(net "M_E_CPU1_SB_DQS_DP<5>")
	)
	(segment
		(start 159.978598 -227.46081)
		(end 159.398462 -226.880928)
		(width 0.18288)
		(layer "In2.Cu")
		(net "M_E_CPU1_SB_DQS_DP<5>")
	)
	(segment
		(start 157.230826 -226.897692)
		(end 156.798518 -226.897692)
		(width 0.18288)
		(layer "In2.Cu")
		(net "M_E_CPU1_SB_DQS_DP<5>")
	)
	(segment
		(start 160.394142 -227.510086)
		(end 160.097216 -227.510086)
		(width 0.18288)
		(layer "In2.Cu")
		(net "M_E_CPU1_SB_DQS_DP<5>")
	)
	(segment
		(start 161.783014 -227.066602)
		(end 161.527744 -227.321872)
		(width 0.18288)
		(layer "In2.Cu")
		(net "M_E_CPU1_SB_DQS_DP<5>")
	)
	(segment
		(start 138.410696 -234.346496)
		(end 138.350752 -234.40644)
		(width 0.088646)
		(layer "In2.Cu")
		(net "M_E_CPU1_SB_DQS_DP<5>")
	)
	(segment
		(start 136.232646 -234.49788)
		(end 136.171178 -234.523534)
		(width 0.088646)
		(layer "In2.Cu")
		(net "M_E_CPU1_SB_DQS_DP<5>")
	)
	(segment
		(start 135.235188 -234.912916)
		(end 135.178038 -234.970066)
		(width 0.088646)
		(layer "In2.Cu")
		(net "M_E_CPU1_SB_DQS_DP<5>")
	)
	(segment
		(start 157.92704 -226.642168)
		(end 157.48635 -226.642168)
		(width 0.18288)
		(layer "In2.Cu")
		(net "M_E_CPU1_SB_DQS_DP<5>")
	)
	(segment
		(start 156.798518 -226.897692)
		(end 155.997656 -227.229162)
		(width 0.18288)
		(layer "In2.Cu")
		(net "M_E_CPU1_SB_DQS_DP<5>")
	)
	(segment
		(start 136.277096 -234.471972)
		(end 136.232646 -234.49788)
		(width 0.088646)
		(layer "In2.Cu")
		(net "M_E_CPU1_SB_DQS_DP<5>")
	)
	(segment
		(start 157.48635 -226.642168)
		(end 157.230826 -226.897692)
		(width 0.18288)
		(layer "In2.Cu")
		(net "M_E_CPU1_SB_DQS_DP<5>")
	)
	(segment
		(start 161.527744 -227.321872)
		(end 161.34334 -227.321872)
		(width 0.18288)
		(layer "In2.Cu")
		(net "M_E_CPU1_SB_DQS_DP<5>")
	)
	(segment
		(start 160.097216 -227.510086)
		(end 159.978598 -227.46081)
		(width 0.18288)
		(layer "In2.Cu")
		(net "M_E_CPU1_SB_DQS_DP<5>")
	)
	(segment
		(start 155.997656 -227.229162)
		(end 149.695154 -233.531664)
		(width 0.18288)
		(layer "In2.Cu")
		(net "M_E_CPU1_SB_DQS_DP<5>")
	)
	(segment
		(start 135.886444 -234.493308)
		(end 135.68553 -234.50423)
		(width 0.088646)
		(layer "In2.Cu")
		(net "M_E_CPU1_SB_DQS_DP<5>")
	)
	(segment
		(start 161.34334 -227.321872)
		(end 160.394142 -227.510086)
		(width 0.18288)
		(layer "In2.Cu")
		(net "M_E_CPU1_SB_DQS_DP<5>")
	)
	(segment
		(start 148.89861 -233.861864)
		(end 139.397994 -233.861864)
		(width 0.18288)
		(layer "In2.Cu")
		(net "M_E_CPU1_SB_DQS_DP<5>")
	)
	(segment
		(start 138.913362 -234.346496)
		(end 138.410696 -234.346496)
		(width 0.18288)
		(layer "In2.Cu")
		(net "M_E_CPU1_SB_DQS_DP<5>")
	)
	(segment
		(start 135.68553 -234.50423)
		(end 135.57758 -234.549188)
		(width 0.088646)
		(layer "In2.Cu")
		(net "M_E_CPU1_SB_DQS_DP<5>")
	)
	(segment
		(start 135.418068 -234.645708)
		(end 135.409178 -234.650788)
		(width 0.088646)
		(layer "In2.Cu")
		(net "M_E_CPU1_SB_DQS_DP<5>")
	)
	(segment
		(start 138.350752 -234.40644)
		(end 137.479532 -234.40644)
		(width 0.088646)
		(layer "In2.Cu")
		(net "M_E_CPU1_SB_DQS_DP<5>")
	)
	(segment
		(start 135.57758 -234.549188)
		(end 135.486648 -234.614974)
		(width 0.088646)
		(layer "In2.Cu")
		(net "M_E_CPU1_SB_DQS_DP<5>")
	)
	(segment
		(start 136.171178 -234.523534)
		(end 136.153652 -234.527852)
		(width 0.088646)
		(layer "In2.Cu")
		(net "M_E_CPU1_SB_DQS_DP<5>")
	)
	(segment
		(start 136.153398 -234.528106)
		(end 136.151874 -234.528614)
		(width 0.088646)
		(layer "In2.Cu")
		(net "M_E_CPU1_SB_DQS_DP<5>")
	)
	(segment
		(start 136.02081 -234.532678)
		(end 135.886444 -234.493308)
		(width 0.088646)
		(layer "In2.Cu")
		(net "M_E_CPU1_SB_DQS_DP<5>")
	)
	(segment
		(start 149.695154 -233.531664)
		(end 148.89861 -233.861864)
		(width 0.18288)
		(layer "In2.Cu")
		(net "M_E_CPU1_SB_DQS_DP<5>")
	)
	(arc
		(start 137.479532 -234.40644)
		(mid 137.335979 -234.425309)
		(end 137.202164 -234.480608)
		(width 0.088646)
		(layer "In2.Cu")
		(net "M_E_CPU1_SB_DQS_DP<5>")
	)
	(arc
		(start 137.202164 -234.480608)
		(mid 137.014966 -234.530751)
		(end 136.827768 -234.480608)
		(width 0.088646)
		(layer "In2.Cu")
		(net "M_E_CPU1_SB_DQS_DP<5>")
	)
	(arc
		(start 136.827768 -234.480608)
		(mid 136.553569 -234.404773)
		(end 136.277096 -234.471972)
		(width 0.088646)
		(layer "In2.Cu")
		(net "M_E_CPU1_SB_DQS_DP<5>")
	)
	(arc
		(start 135.409178 -234.650788)
		(mid 135.293369 -234.762717)
		(end 135.235188 -234.912916)
		(width 0.088646)
		(layer "In2.Cu")
		(net "M_E_CPU1_SB_DQS_DP<5>")
	)
	(arc
		(start 135.486648 -234.614974)
		(mid 135.451587 -234.628619)
		(end 135.418068 -234.645708)
		(width 0.088646)
		(layer "In2.Cu")
		(net "M_E_CPU1_SB_DQS_DP<5>")
	)
	(segment
		(start 159.79521 -235.991654)
		(end 160.280858 -235.991654)
		(width 0.101854)
		(layer "F.Cu")
		(net "M_E_CPU1_SB_DQS_DP<4>")
	)
	(segment
		(start 141.941296 -240.54054)
		(end 143.630396 -240.54054)
		(width 0.1524)
		(layer "F.Cu")
		(net "M_E_CPU1_SB_DQS_DP<4>")
	)
	(segment
		(start 147.322794 -236.848142)
		(end 147.886166 -236.848142)
		(width 0.1524)
		(layer "F.Cu")
		(net "M_E_CPU1_SB_DQS_DP<4>")
	)
	(segment
		(start 167.360092 -235.991654)
		(end 165.347396 -235.991654)
		(width 0.1016)
		(layer "F.Cu")
		(net "M_E_CPU1_SB_DQS_DP<4>")
	)
	(segment
		(start 168.1988 -236.239304)
		(end 167.943784 -235.984288)
		(width 0.20066)
		(layer "F.Cu")
		(net "M_E_CPU1_SB_DQS_DP<4>")
	)
	(segment
		(start 164.910262 -235.991654)
		(end 164.798756 -235.991654)
		(width 0.20066)
		(layer "F.Cu")
		(net "M_E_CPU1_SB_DQS_DP<4>")
	)
	(segment
		(start 147.922996 -236.811312)
		(end 147.961096 -236.811312)
		(width 0.1524)
		(layer "F.Cu")
		(net "M_E_CPU1_SB_DQS_DP<4>")
	)
	(segment
		(start 143.630396 -240.54054)
		(end 147.322794 -236.848142)
		(width 0.1524)
		(layer "F.Cu")
		(net "M_E_CPU1_SB_DQS_DP<4>")
	)
	(segment
		(start 147.961096 -236.811312)
		(end 155.513532 -236.811312)
		(width 0.20066)
		(layer "F.Cu")
		(net "M_E_CPU1_SB_DQS_DP<4>")
	)
	(segment
		(start 169.300398 -236.671612)
		(end 168.86809 -236.239304)
		(width 0.20066)
		(layer "F.Cu")
		(net "M_E_CPU1_SB_DQS_DP<4>")
	)
	(segment
		(start 157.803342 -235.991654)
		(end 159.79521 -235.991654)
		(width 0.1016)
		(layer "F.Cu")
		(net "M_E_CPU1_SB_DQS_DP<4>")
	)
	(segment
		(start 141.919198 -240.54054)
		(end 141.941296 -240.54054)
		(width 0.088646)
		(layer "F.Cu")
		(net "M_E_CPU1_SB_DQS_DP<4>")
	)
	(segment
		(start 164.163756 -236.24413)
		(end 163.740084 -236.667802)
		(width 0.20066)
		(layer "F.Cu")
		(net "M_E_CPU1_SB_DQS_DP<4>")
	)
	(segment
		(start 161.92881 -236.667548)
		(end 162.157664 -236.667548)
		(width 0.20066)
		(layer "F.Cu")
		(net "M_E_CPU1_SB_DQS_DP<4>")
	)
	(segment
		(start 139.887452 -242.31092)
		(end 141.626082 -240.57229)
		(width 0.088646)
		(layer "F.Cu")
		(net "M_E_CPU1_SB_DQS_DP<4>")
	)
	(segment
		(start 168.86809 -236.239304)
		(end 168.1988 -236.239304)
		(width 0.20066)
		(layer "F.Cu")
		(net "M_E_CPU1_SB_DQS_DP<4>")
	)
	(segment
		(start 167.75811 -235.991654)
		(end 167.360092 -235.991654)
		(width 0.101854)
		(layer "F.Cu")
		(net "M_E_CPU1_SB_DQS_DP<4>")
	)
	(segment
		(start 170.457114 -236.416596)
		(end 169.88917 -236.416596)
		(width 0.20066)
		(layer "F.Cu")
		(net "M_E_CPU1_SB_DQS_DP<4>")
	)
	(segment
		(start 137.954766 -242.831112)
		(end 138.537696 -242.60937)
		(width 0.088646)
		(layer "F.Cu")
		(net "M_E_CPU1_SB_DQS_DP<4>")
	)
	(segment
		(start 162.408616 -236.416596)
		(end 162.913314 -236.416596)
		(width 0.20066)
		(layer "F.Cu")
		(net "M_E_CPU1_SB_DQS_DP<4>")
	)
	(segment
		(start 169.634154 -236.671612)
		(end 169.300398 -236.671612)
		(width 0.20066)
		(layer "F.Cu")
		(net "M_E_CPU1_SB_DQS_DP<4>")
	)
	(segment
		(start 163.281614 -236.416596)
		(end 162.913314 -236.416596)
		(width 0.20066)
		(layer "F.Cu")
		(net "M_E_CPU1_SB_DQS_DP<4>")
	)
	(segment
		(start 141.887448 -240.57229)
		(end 141.919198 -240.54054)
		(width 0.088646)
		(layer "F.Cu")
		(net "M_E_CPU1_SB_DQS_DP<4>")
	)
	(segment
		(start 147.886166 -236.848142)
		(end 147.922996 -236.811312)
		(width 0.1524)
		(layer "F.Cu")
		(net "M_E_CPU1_SB_DQS_DP<4>")
	)
	(segment
		(start 163.53282 -236.667802)
		(end 163.281614 -236.416596)
		(width 0.20066)
		(layer "F.Cu")
		(net "M_E_CPU1_SB_DQS_DP<4>")
	)
	(segment
		(start 137.954766 -242.830858)
		(end 137.954766 -242.831112)
		(width 0.088646)
		(layer "F.Cu")
		(net "M_E_CPU1_SB_DQS_DP<4>")
	)
	(segment
		(start 160.280858 -235.991654)
		(end 160.382712 -235.991654)
		(width 0.20066)
		(layer "F.Cu")
		(net "M_E_CPU1_SB_DQS_DP<4>")
	)
	(segment
		(start 167.943784 -235.984288)
		(end 167.765476 -235.984288)
		(width 0.20066)
		(layer "F.Cu")
		(net "M_E_CPU1_SB_DQS_DP<4>")
	)
	(segment
		(start 139.742672 -242.31092)
		(end 139.887452 -242.31092)
		(width 0.088646)
		(layer "F.Cu")
		(net "M_E_CPU1_SB_DQS_DP<4>")
	)
	(segment
		(start 167.765476 -235.984288)
		(end 167.75811 -235.991654)
		(width 0.101854)
		(layer "F.Cu")
		(net "M_E_CPU1_SB_DQS_DP<4>")
	)
	(segment
		(start 157.290516 -235.991654)
		(end 157.803342 -235.991654)
		(width 0.101854)
		(layer "F.Cu")
		(net "M_E_CPU1_SB_DQS_DP<4>")
	)
	(segment
		(start 162.157664 -236.667548)
		(end 162.408616 -236.416596)
		(width 0.20066)
		(layer "F.Cu")
		(net "M_E_CPU1_SB_DQS_DP<4>")
	)
	(segment
		(start 139.055094 -242.310666)
		(end 139.742418 -242.310666)
		(width 0.088646)
		(layer "F.Cu")
		(net "M_E_CPU1_SB_DQS_DP<4>")
	)
	(segment
		(start 138.537696 -242.60937)
		(end 139.055094 -242.310666)
		(width 0.088646)
		(layer "F.Cu")
		(net "M_E_CPU1_SB_DQS_DP<4>")
	)
	(segment
		(start 165.347396 -235.991654)
		(end 164.910262 -235.991654)
		(width 0.101854)
		(layer "F.Cu")
		(net "M_E_CPU1_SB_DQS_DP<4>")
	)
	(segment
		(start 160.659572 -236.268514)
		(end 160.966404 -236.268514)
		(width 0.20066)
		(layer "F.Cu")
		(net "M_E_CPU1_SB_DQS_DP<4>")
	)
	(segment
		(start 164.798756 -235.991654)
		(end 164.54628 -236.24413)
		(width 0.20066)
		(layer "F.Cu")
		(net "M_E_CPU1_SB_DQS_DP<4>")
	)
	(segment
		(start 169.88917 -236.416596)
		(end 169.634154 -236.671612)
		(width 0.20066)
		(layer "F.Cu")
		(net "M_E_CPU1_SB_DQS_DP<4>")
	)
	(segment
		(start 155.513532 -236.811312)
		(end 156.33319 -235.991654)
		(width 0.20066)
		(layer "F.Cu")
		(net "M_E_CPU1_SB_DQS_DP<4>")
	)
	(segment
		(start 139.742418 -242.310666)
		(end 139.742672 -242.31092)
		(width 0.088646)
		(layer "F.Cu")
		(net "M_E_CPU1_SB_DQS_DP<4>")
	)
	(segment
		(start 164.54628 -236.24413)
		(end 164.163756 -236.24413)
		(width 0.20066)
		(layer "F.Cu")
		(net "M_E_CPU1_SB_DQS_DP<4>")
	)
	(segment
		(start 156.33319 -235.991654)
		(end 157.290516 -235.991654)
		(width 0.20066)
		(layer "F.Cu")
		(net "M_E_CPU1_SB_DQS_DP<4>")
	)
	(segment
		(start 160.382712 -235.991654)
		(end 160.659572 -236.268514)
		(width 0.20066)
		(layer "F.Cu")
		(net "M_E_CPU1_SB_DQS_DP<4>")
	)
	(segment
		(start 163.740084 -236.667802)
		(end 163.53282 -236.667802)
		(width 0.20066)
		(layer "F.Cu")
		(net "M_E_CPU1_SB_DQS_DP<4>")
	)
	(segment
		(start 141.626082 -240.57229)
		(end 141.887448 -240.57229)
		(width 0.088646)
		(layer "F.Cu")
		(net "M_E_CPU1_SB_DQS_DP<4>")
	)
	(segment
		(start 160.966404 -236.268514)
		(end 161.92881 -236.667548)
		(width 0.20066)
		(layer "F.Cu")
		(net "M_E_CPU1_SB_DQS_DP<4>")
	)
	(segment
		(start 155.637484 -200.7997)
		(end 156.429456 -200.7997)
		(width 0.20066)
		(layer "F.Cu")
		(net "M_E_CPU1_SB_DQS_DP<3>")
	)
	(segment
		(start 157.746954 -200.19645)
		(end 158.267146 -200.716642)
		(width 0.20066)
		(layer "F.Cu")
		(net "M_E_CPU1_SB_DQS_DP<3>")
	)
	(segment
		(start 142.61592 -206.079598)
		(end 142.992094 -205.703424)
		(width 0.20066)
		(layer "F.Cu")
		(net "M_E_CPU1_SB_DQS_DP<3>")
	)
	(segment
		(start 137.140188 -228.153976)
		(end 137.286746 -228.248718)
		(width 0.088646)
		(layer "F.Cu")
		(net "M_E_CPU1_SB_DQS_DP<3>")
	)
	(segment
		(start 141.6304 -210.903566)
		(end 141.6304 -210.865212)
		(width 0.1524)
		(layer "F.Cu")
		(net "M_E_CPU1_SB_DQS_DP<3>")
	)
	(segment
		(start 156.885894 -200.343262)
		(end 157.067504 -200.268078)
		(width 0.20066)
		(layer "F.Cu")
		(net "M_E_CPU1_SB_DQS_DP<3>")
	)
	(segment
		(start 156.429456 -200.7997)
		(end 156.885894 -200.343262)
		(width 0.20066)
		(layer "F.Cu")
		(net "M_E_CPU1_SB_DQS_DP<3>")
	)
	(segment
		(start 150.452328 -200.92416)
		(end 151.054308 -200.92416)
		(width 0.20066)
		(layer "F.Cu")
		(net "M_E_CPU1_SB_DQS_DP<3>")
	)
	(segment
		(start 138.654536 -228.694234)
		(end 138.72845 -228.731318)
		(width 0.088646)
		(layer "F.Cu")
		(net "M_E_CPU1_SB_DQS_DP<3>")
	)
	(segment
		(start 140.56614 -228.050598)
		(end 140.61186 -228.050598)
		(width 0.088646)
		(layer "F.Cu")
		(net "M_E_CPU1_SB_DQS_DP<3>")
	)
	(segment
		(start 159.402526 -200.716642)
		(end 158.813246 -200.716642)
		(width 0.20066)
		(layer "F.Cu")
		(net "M_E_CPU1_SB_DQS_DP<3>")
	)
	(segment
		(start 141.59357 -210.940396)
		(end 141.6304 -210.903566)
		(width 0.1524)
		(layer "F.Cu")
		(net "M_E_CPU1_SB_DQS_DP<3>")
	)
	(segment
		(start 141.59357 -212.046566)
		(end 141.59357 -210.940396)
		(width 0.1524)
		(layer "F.Cu")
		(net "M_E_CPU1_SB_DQS_DP<3>")
	)
	(segment
		(start 144.195546 -204.675994)
		(end 144.621504 -204.250036)
		(width 0.20066)
		(layer "F.Cu")
		(net "M_E_CPU1_SB_DQS_DP<3>")
	)
	(segment
		(start 152.631648 -200.7997)
		(end 153.333704 -200.7997)
		(width 0.20066)
		(layer "F.Cu")
		(net "M_E_CPU1_SB_DQS_DP<3>")
	)
	(segment
		(start 149.988524 -200.7997)
		(end 150.327868 -200.7997)
		(width 0.20066)
		(layer "F.Cu")
		(net "M_E_CPU1_SB_DQS_DP<3>")
	)
	(segment
		(start 139.527534 -228.651562)
		(end 139.769596 -228.551486)
		(width 0.088646)
		(layer "F.Cu")
		(net "M_E_CPU1_SB_DQS_DP<3>")
	)
	(segment
		(start 144.019524 -204.675994)
		(end 144.195546 -204.675994)
		(width 0.20066)
		(layer "F.Cu")
		(net "M_E_CPU1_SB_DQS_DP<3>")
	)
	(segment
		(start 165.808406 -200.716642)
		(end 165.52672 -200.434956)
		(width 0.20066)
		(layer "F.Cu")
		(net "M_E_CPU1_SB_DQS_DP<3>")
	)
	(segment
		(start 163.913566 -201.141838)
		(end 161.914078 -201.141838)
		(width 0.1016)
		(layer "F.Cu")
		(net "M_E_CPU1_SB_DQS_DP<3>")
	)
	(segment
		(start 140.61186 -228.050598)
		(end 140.627354 -228.035104)
		(width 0.088646)
		(layer "F.Cu")
		(net "M_E_CPU1_SB_DQS_DP<3>")
	)
	(segment
		(start 141.815312 -213.163404)
		(end 141.59357 -212.046566)
		(width 0.1524)
		(layer "F.Cu")
		(net "M_E_CPU1_SB_DQS_DP<3>")
	)
	(segment
		(start 161.068766 -200.890632)
		(end 160.067752 -200.476104)
		(width 0.20066)
		(layer "F.Cu")
		(net "M_E_CPU1_SB_DQS_DP<3>")
	)
	(segment
		(start 143.594074 -205.277466)
		(end 143.594074 -205.101444)
		(width 0.20066)
		(layer "F.Cu")
		(net "M_E_CPU1_SB_DQS_DP<3>")
	)
	(segment
		(start 137.286746 -228.248718)
		(end 137.51052 -228.5492)
		(width 0.088646)
		(layer "F.Cu")
		(net "M_E_CPU1_SB_DQS_DP<3>")
	)
	(segment
		(start 143.594074 -205.101444)
		(end 144.019524 -204.675994)
		(width 0.20066)
		(layer "F.Cu")
		(net "M_E_CPU1_SB_DQS_DP<3>")
	)
	(segment
		(start 161.614104 -201.160888)
		(end 161.343848 -200.890632)
		(width 0.20066)
		(layer "F.Cu")
		(net "M_E_CPU1_SB_DQS_DP<3>")
	)
	(segment
		(start 153.333704 -200.7997)
		(end 153.458164 -200.92416)
		(width 0.20066)
		(layer "F.Cu")
		(net "M_E_CPU1_SB_DQS_DP<3>")
	)
	(segment
		(start 157.067504 -200.268078)
		(end 157.19044 -200.217024)
		(width 0.20066)
		(layer "F.Cu")
		(net "M_E_CPU1_SB_DQS_DP<3>")
	)
	(segment
		(start 139.40155 -228.599238)
		(end 139.527534 -228.651562)
		(width 0.088646)
		(layer "F.Cu")
		(net "M_E_CPU1_SB_DQS_DP<3>")
	)
	(segment
		(start 147.51177 -203.276454)
		(end 147.687792 -203.276454)
		(width 0.20066)
		(layer "F.Cu")
		(net "M_E_CPU1_SB_DQS_DP<3>")
	)
	(segment
		(start 151.905208 -200.92416)
		(end 152.507188 -200.92416)
		(width 0.20066)
		(layer "F.Cu")
		(net "M_E_CPU1_SB_DQS_DP<3>")
	)
	(segment
		(start 151.178768 -200.7997)
		(end 151.780748 -200.7997)
		(width 0.20066)
		(layer "F.Cu")
		(net "M_E_CPU1_SB_DQS_DP<3>")
	)
	(segment
		(start 139.82192 -228.424994)
		(end 140.092938 -228.312726)
		(width 0.088646)
		(layer "F.Cu")
		(net "M_E_CPU1_SB_DQS_DP<3>")
	)
	(segment
		(start 138.72845 -228.731318)
		(end 139.082272 -228.731318)
		(width 0.088646)
		(layer "F.Cu")
		(net "M_E_CPU1_SB_DQS_DP<3>")
	)
	(segment
		(start 148.715222 -202.249024)
		(end 149.14118 -201.823066)
		(width 0.20066)
		(layer "F.Cu")
		(net "M_E_CPU1_SB_DQS_DP<3>")
	)
	(segment
		(start 141.815312 -226.847146)
		(end 141.815312 -213.163404)
		(width 0.1524)
		(layer "F.Cu")
		(net "M_E_CPU1_SB_DQS_DP<3>")
	)
	(segment
		(start 163.923726 -201.151998)
		(end 163.913566 -201.141838)
		(width 0.1016)
		(layer "F.Cu")
		(net "M_E_CPU1_SB_DQS_DP<3>")
	)
	(segment
		(start 157.244034 -200.19645)
		(end 157.746954 -200.19645)
		(width 0.20066)
		(layer "F.Cu")
		(net "M_E_CPU1_SB_DQS_DP<3>")
	)
	(segment
		(start 154.786584 -200.7997)
		(end 154.911044 -200.92416)
		(width 0.20066)
		(layer "F.Cu")
		(net "M_E_CPU1_SB_DQS_DP<3>")
	)
	(segment
		(start 148.5392 -202.249024)
		(end 148.715222 -202.249024)
		(width 0.20066)
		(layer "F.Cu")
		(net "M_E_CPU1_SB_DQS_DP<3>")
	)
	(segment
		(start 161.895028 -201.160888)
		(end 161.891726 -201.160888)
		(width 0.101854)
		(layer "F.Cu")
		(net "M_E_CPU1_SB_DQS_DP<3>")
	)
	(segment
		(start 150.327868 -200.7997)
		(end 150.452328 -200.92416)
		(width 0.20066)
		(layer "F.Cu")
		(net "M_E_CPU1_SB_DQS_DP<3>")
	)
	(segment
		(start 158.267146 -200.716642)
		(end 158.813246 -200.716642)
		(width 0.20066)
		(layer "F.Cu")
		(net "M_E_CPU1_SB_DQS_DP<3>")
	)
	(segment
		(start 140.304012 -228.312726)
		(end 140.56614 -228.050598)
		(width 0.088646)
		(layer "F.Cu")
		(net "M_E_CPU1_SB_DQS_DP<3>")
	)
	(segment
		(start 160.067752 -200.476104)
		(end 159.643064 -200.476104)
		(width 0.20066)
		(layer "F.Cu")
		(net "M_E_CPU1_SB_DQS_DP<3>")
	)
	(segment
		(start 166.357046 -200.716642)
		(end 165.808406 -200.716642)
		(width 0.20066)
		(layer "F.Cu")
		(net "M_E_CPU1_SB_DQS_DP<3>")
	)
	(segment
		(start 151.780748 -200.7997)
		(end 151.905208 -200.92416)
		(width 0.20066)
		(layer "F.Cu")
		(net "M_E_CPU1_SB_DQS_DP<3>")
	)
	(segment
		(start 161.891726 -201.160888)
		(end 161.614104 -201.160888)
		(width 0.20066)
		(layer "F.Cu")
		(net "M_E_CPU1_SB_DQS_DP<3>")
	)
	(segment
		(start 152.507188 -200.92416)
		(end 152.631648 -200.7997)
		(width 0.20066)
		(layer "F.Cu")
		(net "M_E_CPU1_SB_DQS_DP<3>")
	)
	(segment
		(start 141.6304 -208.895696)
		(end 141.6304 -208.458816)
		(width 0.20066)
		(layer "F.Cu")
		(net "M_E_CPU1_SB_DQS_DP<3>")
	)
	(segment
		(start 139.769596 -228.551486)
		(end 139.82192 -228.424994)
		(width 0.088646)
		(layer "F.Cu")
		(net "M_E_CPU1_SB_DQS_DP<3>")
	)
	(segment
		(start 142.992094 -205.703424)
		(end 143.168116 -205.703424)
		(width 0.20066)
		(layer "F.Cu")
		(net "M_E_CPU1_SB_DQS_DP<3>")
	)
	(segment
		(start 154.911044 -200.92416)
		(end 155.513024 -200.92416)
		(width 0.20066)
		(layer "F.Cu")
		(net "M_E_CPU1_SB_DQS_DP<3>")
	)
	(segment
		(start 164.87013 -200.895458)
		(end 164.50056 -200.895458)
		(width 0.20066)
		(layer "F.Cu")
		(net "M_E_CPU1_SB_DQS_DP<3>")
	)
	(segment
		(start 137.014712 -228.1809)
		(end 137.140188 -228.153976)
		(width 0.088646)
		(layer "F.Cu")
		(net "M_E_CPU1_SB_DQS_DP<3>")
	)
	(segment
		(start 140.627354 -228.035104)
		(end 141.815312 -226.847146)
		(width 0.1524)
		(layer "F.Cu")
		(net "M_E_CPU1_SB_DQS_DP<3>")
	)
	(segment
		(start 143.168116 -205.703424)
		(end 143.594074 -205.277466)
		(width 0.20066)
		(layer "F.Cu")
		(net "M_E_CPU1_SB_DQS_DP<3>")
	)
	(segment
		(start 138.233912 -228.673152)
		(end 138.28268 -228.645212)
		(width 0.088646)
		(layer "F.Cu")
		(net "M_E_CPU1_SB_DQS_DP<3>")
	)
	(segment
		(start 154.184604 -200.7997)
		(end 154.786584 -200.7997)
		(width 0.20066)
		(layer "F.Cu")
		(net "M_E_CPU1_SB_DQS_DP<3>")
	)
	(segment
		(start 140.092938 -228.312726)
		(end 140.304012 -228.312726)
		(width 0.088646)
		(layer "F.Cu")
		(net "M_E_CPU1_SB_DQS_DP<3>")
	)
	(segment
		(start 161.914078 -201.141838)
		(end 161.895028 -201.160888)
		(width 0.1016)
		(layer "F.Cu")
		(net "M_E_CPU1_SB_DQS_DP<3>")
	)
	(segment
		(start 141.6304 -210.865212)
		(end 141.6304 -209.746596)
		(width 0.20066)
		(layer "F.Cu")
		(net "M_E_CPU1_SB_DQS_DP<3>")
	)
	(segment
		(start 155.513024 -200.92416)
		(end 155.637484 -200.7997)
		(width 0.20066)
		(layer "F.Cu")
		(net "M_E_CPU1_SB_DQS_DP<3>")
	)
	(segment
		(start 141.75486 -209.020156)
		(end 141.6304 -208.895696)
		(width 0.20066)
		(layer "F.Cu")
		(net "M_E_CPU1_SB_DQS_DP<3>")
	)
	(segment
		(start 149.14118 -201.823066)
		(end 149.14118 -201.647044)
		(width 0.20066)
		(layer "F.Cu")
		(net "M_E_CPU1_SB_DQS_DP<3>")
	)
	(segment
		(start 149.14118 -201.647044)
		(end 149.988524 -200.7997)
		(width 0.20066)
		(layer "F.Cu")
		(net "M_E_CPU1_SB_DQS_DP<3>")
	)
	(segment
		(start 164.24402 -201.151998)
		(end 163.923726 -201.151998)
		(width 0.20066)
		(layer "F.Cu")
		(net "M_E_CPU1_SB_DQS_DP<3>")
	)
	(segment
		(start 139.082272 -228.731318)
		(end 139.40155 -228.599238)
		(width 0.088646)
		(layer "F.Cu")
		(net "M_E_CPU1_SB_DQS_DP<3>")
	)
	(segment
		(start 147.08632 -203.701904)
		(end 147.51177 -203.276454)
		(width 0.20066)
		(layer "F.Cu")
		(net "M_E_CPU1_SB_DQS_DP<3>")
	)
	(segment
		(start 141.6304 -209.746596)
		(end 141.75486 -209.622136)
		(width 0.20066)
		(layer "F.Cu")
		(net "M_E_CPU1_SB_DQS_DP<3>")
	)
	(segment
		(start 153.458164 -200.92416)
		(end 154.060144 -200.92416)
		(width 0.20066)
		(layer "F.Cu")
		(net "M_E_CPU1_SB_DQS_DP<3>")
	)
	(segment
		(start 161.343848 -200.890632)
		(end 161.068766 -200.890632)
		(width 0.20066)
		(layer "F.Cu")
		(net "M_E_CPU1_SB_DQS_DP<3>")
	)
	(segment
		(start 154.060144 -200.92416)
		(end 154.184604 -200.7997)
		(width 0.20066)
		(layer "F.Cu")
		(net "M_E_CPU1_SB_DQS_DP<3>")
	)
	(segment
		(start 141.6304 -208.458816)
		(end 142.61592 -206.079598)
		(width 0.20066)
		(layer "F.Cu")
		(net "M_E_CPU1_SB_DQS_DP<3>")
	)
	(segment
		(start 165.52672 -200.434956)
		(end 165.330632 -200.434956)
		(width 0.20066)
		(layer "F.Cu")
		(net "M_E_CPU1_SB_DQS_DP<3>")
	)
	(segment
		(start 144.853152 -203.842366)
		(end 145.192242 -203.701904)
		(width 0.20066)
		(layer "F.Cu")
		(net "M_E_CPU1_SB_DQS_DP<3>")
	)
	(segment
		(start 165.330632 -200.434956)
		(end 164.87013 -200.895458)
		(width 0.20066)
		(layer "F.Cu")
		(net "M_E_CPU1_SB_DQS_DP<3>")
	)
	(segment
		(start 145.192242 -203.701904)
		(end 147.08632 -203.701904)
		(width 0.20066)
		(layer "F.Cu")
		(net "M_E_CPU1_SB_DQS_DP<3>")
	)
	(segment
		(start 147.687792 -203.276454)
		(end 148.11375 -202.850496)
		(width 0.20066)
		(layer "F.Cu")
		(net "M_E_CPU1_SB_DQS_DP<3>")
	)
	(segment
		(start 138.232896 -228.67366)
		(end 138.233912 -228.673152)
		(width 0.088646)
		(layer "F.Cu")
		(net "M_E_CPU1_SB_DQS_DP<3>")
	)
	(segment
		(start 137.51052 -228.5492)
		(end 137.562082 -228.59619)
		(width 0.088646)
		(layer "F.Cu")
		(net "M_E_CPU1_SB_DQS_DP<3>")
	)
	(segment
		(start 148.11375 -202.850496)
		(end 148.11375 -202.674474)
		(width 0.20066)
		(layer "F.Cu")
		(net "M_E_CPU1_SB_DQS_DP<3>")
	)
	(segment
		(start 144.621504 -204.074014)
		(end 144.853152 -203.842366)
		(width 0.20066)
		(layer "F.Cu")
		(net "M_E_CPU1_SB_DQS_DP<3>")
	)
	(segment
		(start 138.594084 -228.65969)
		(end 138.654536 -228.694234)
		(width 0.088646)
		(layer "F.Cu")
		(net "M_E_CPU1_SB_DQS_DP<3>")
	)
	(segment
		(start 141.75486 -209.622136)
		(end 141.75486 -209.020156)
		(width 0.20066)
		(layer "F.Cu")
		(net "M_E_CPU1_SB_DQS_DP<3>")
	)
	(segment
		(start 164.50056 -200.895458)
		(end 164.24402 -201.151998)
		(width 0.20066)
		(layer "F.Cu")
		(net "M_E_CPU1_SB_DQS_DP<3>")
	)
	(segment
		(start 159.643064 -200.476104)
		(end 159.402526 -200.716642)
		(width 0.20066)
		(layer "F.Cu")
		(net "M_E_CPU1_SB_DQS_DP<3>")
	)
	(segment
		(start 157.19044 -200.217024)
		(end 157.244034 -200.19645)
		(width 0.20066)
		(layer "F.Cu")
		(net "M_E_CPU1_SB_DQS_DP<3>")
	)
	(segment
		(start 144.621504 -204.250036)
		(end 144.621504 -204.074014)
		(width 0.20066)
		(layer "F.Cu")
		(net "M_E_CPU1_SB_DQS_DP<3>")
	)
	(segment
		(start 151.054308 -200.92416)
		(end 151.178768 -200.7997)
		(width 0.20066)
		(layer "F.Cu")
		(net "M_E_CPU1_SB_DQS_DP<3>")
	)
	(segment
		(start 148.11375 -202.674474)
		(end 148.5392 -202.249024)
		(width 0.20066)
		(layer "F.Cu")
		(net "M_E_CPU1_SB_DQS_DP<3>")
	)
	(arc
		(start 138.28268 -228.645212)
		(mid 138.307254 -228.633207)
		(end 138.333226 -228.624638)
		(width 0.088646)
		(layer "F.Cu")
		(net "M_E_CPU1_SB_DQS_DP<3>")
	)
	(arc
		(start 137.562082 -228.59619)
		(mid 137.884977 -228.743359)
		(end 138.232896 -228.67366)
		(width 0.088646)
		(layer "F.Cu")
		(net "M_E_CPU1_SB_DQS_DP<3>")
	)
	(arc
		(start 138.333226 -228.624638)
		(mid 138.467062 -228.616755)
		(end 138.594084 -228.65969)
		(width 0.088646)
		(layer "F.Cu")
		(net "M_E_CPU1_SB_DQS_DP<3>")
	)
	(segment
		(start 150.27402 -212.639148)
		(end 150.69947 -212.213698)
		(width 0.20066)
		(layer "F.Cu")
		(net "M_E_CPU1_SB_DQS_DP<2>")
	)
	(segment
		(start 148.21916 -214.87003)
		(end 148.21916 -214.694008)
		(width 0.20066)
		(layer "F.Cu")
		(net "M_E_CPU1_SB_DQS_DP<2>")
	)
	(segment
		(start 138.561064 -233.502708)
		(end 138.666728 -233.608372)
		(width 0.088646)
		(layer "F.Cu")
		(net "M_E_CPU1_SB_DQS_DP<2>")
	)
	(segment
		(start 151.30145 -211.78774)
		(end 151.30145 -211.611718)
		(width 0.20066)
		(layer "F.Cu")
		(net "M_E_CPU1_SB_DQS_DP<2>")
	)
	(segment
		(start 146.064986 -216.848182)
		(end 146.58975 -216.323418)
		(width 0.20066)
		(layer "F.Cu")
		(net "M_E_CPU1_SB_DQS_DP<2>")
	)
	(segment
		(start 156.70276 -209.87512)
		(end 157.30474 -209.87512)
		(width 0.20066)
		(layer "F.Cu")
		(net "M_E_CPU1_SB_DQS_DP<2>")
	)
	(segment
		(start 165.419024 -209.78495)
		(end 164.981128 -210.222846)
		(width 0.20066)
		(layer "F.Cu")
		(net "M_E_CPU1_SB_DQS_DP<2>")
	)
	(segment
		(start 161.89833 -210.50758)
		(end 161.891726 -210.50758)
		(width 0.101854)
		(layer "F.Cu")
		(net "M_E_CPU1_SB_DQS_DP<2>")
	)
	(segment
		(start 140.100812 -233.530648)
		(end 140.331952 -233.530648)
		(width 0.088646)
		(layer "F.Cu")
		(net "M_E_CPU1_SB_DQS_DP<2>")
	)
	(segment
		(start 140.65377 -233.562652)
		(end 145.726912 -228.48951)
		(width 0.1524)
		(layer "F.Cu")
		(net "M_E_CPU1_SB_DQS_DP<2>")
	)
	(segment
		(start 137.349484 -233.323638)
		(end 137.643362 -233.543856)
		(width 0.088646)
		(layer "F.Cu")
		(net "M_E_CPU1_SB_DQS_DP<2>")
	)
	(segment
		(start 155.12542 -209.75066)
		(end 155.24988 -209.87512)
		(width 0.20066)
		(layer "F.Cu")
		(net "M_E_CPU1_SB_DQS_DP<2>")
	)
	(segment
		(start 154.39898 -209.87512)
		(end 154.52344 -209.75066)
		(width 0.20066)
		(layer "F.Cu")
		(net "M_E_CPU1_SB_DQS_DP<2>")
	)
	(segment
		(start 139.58062 -233.63936)
		(end 139.758674 -233.63936)
		(width 0.088646)
		(layer "F.Cu")
		(net "M_E_CPU1_SB_DQS_DP<2>")
	)
	(segment
		(start 159.643064 -209.826098)
		(end 159.402526 -210.066636)
		(width 0.20066)
		(layer "F.Cu")
		(net "M_E_CPU1_SB_DQS_DP<2>")
	)
	(segment
		(start 145.726912 -228.48951)
		(end 145.726912 -217.133932)
		(width 0.1524)
		(layer "F.Cu")
		(net "M_E_CPU1_SB_DQS_DP<2>")
	)
	(segment
		(start 139.213336 -233.608372)
		(end 139.290806 -233.530902)
		(width 0.088646)
		(layer "F.Cu")
		(net "M_E_CPU1_SB_DQS_DP<2>")
	)
	(segment
		(start 160.375346 -209.826098)
		(end 159.643064 -209.826098)
		(width 0.20066)
		(layer "F.Cu")
		(net "M_E_CPU1_SB_DQS_DP<2>")
	)
	(segment
		(start 140.363956 -233.562652)
		(end 140.386054 -233.562652)
		(width 0.088646)
		(layer "F.Cu")
		(net "M_E_CPU1_SB_DQS_DP<2>")
	)
	(segment
		(start 153.162508 -209.75066)
		(end 153.67254 -209.75066)
		(width 0.20066)
		(layer "F.Cu")
		(net "M_E_CPU1_SB_DQS_DP<2>")
	)
	(segment
		(start 145.726912 -217.133932)
		(end 145.985738 -216.875106)
		(width 0.1524)
		(layer "F.Cu")
		(net "M_E_CPU1_SB_DQS_DP<2>")
	)
	(segment
		(start 164.205158 -210.510882)
		(end 163.923726 -210.510882)
		(width 0.20066)
		(layer "F.Cu")
		(net "M_E_CPU1_SB_DQS_DP<2>")
	)
	(segment
		(start 165.632892 -209.78495)
		(end 165.419024 -209.78495)
		(width 0.20066)
		(layer "F.Cu")
		(net "M_E_CPU1_SB_DQS_DP<2>")
	)
	(segment
		(start 137.643362 -233.543856)
		(end 137.89025 -233.638344)
		(width 0.088646)
		(layer "F.Cu")
		(net "M_E_CPU1_SB_DQS_DP<2>")
	)
	(segment
		(start 140.331952 -233.530648)
		(end 140.363956 -233.562652)
		(width 0.088646)
		(layer "F.Cu")
		(net "M_E_CPU1_SB_DQS_DP<2>")
	)
	(segment
		(start 138.666728 -233.608372)
		(end 139.213336 -233.608372)
		(width 0.088646)
		(layer "F.Cu")
		(net "M_E_CPU1_SB_DQS_DP<2>")
	)
	(segment
		(start 156.5783 -209.75066)
		(end 156.70276 -209.87512)
		(width 0.20066)
		(layer "F.Cu")
		(net "M_E_CPU1_SB_DQS_DP<2>")
	)
	(segment
		(start 148.64461 -214.268558)
		(end 148.820632 -214.268558)
		(width 0.20066)
		(layer "F.Cu")
		(net "M_E_CPU1_SB_DQS_DP<2>")
	)
	(segment
		(start 145.985738 -216.875106)
		(end 146.038062 -216.875106)
		(width 0.1524)
		(layer "F.Cu")
		(net "M_E_CPU1_SB_DQS_DP<2>")
	)
	(segment
		(start 139.290806 -233.530902)
		(end 139.472162 -233.530902)
		(width 0.088646)
		(layer "F.Cu")
		(net "M_E_CPU1_SB_DQS_DP<2>")
	)
	(segment
		(start 147.61718 -215.295988)
		(end 147.793202 -215.295988)
		(width 0.20066)
		(layer "F.Cu")
		(net "M_E_CPU1_SB_DQS_DP<2>")
	)
	(segment
		(start 137.89025 -233.638344)
		(end 138.053318 -233.638344)
		(width 0.088646)
		(layer "F.Cu")
		(net "M_E_CPU1_SB_DQS_DP<2>")
	)
	(segment
		(start 157.4292 -209.75066)
		(end 158.038038 -209.75066)
		(width 0.20066)
		(layer "F.Cu")
		(net "M_E_CPU1_SB_DQS_DP<2>")
	)
	(segment
		(start 150.27402 -212.81517)
		(end 150.27402 -212.639148)
		(width 0.20066)
		(layer "F.Cu")
		(net "M_E_CPU1_SB_DQS_DP<2>")
	)
	(segment
		(start 148.820632 -214.268558)
		(end 149.24659 -213.8426)
		(width 0.20066)
		(layer "F.Cu")
		(net "M_E_CPU1_SB_DQS_DP<2>")
	)
	(segment
		(start 161.003996 -210.199986)
		(end 160.568894 -210.019646)
		(width 0.20066)
		(layer "F.Cu")
		(net "M_E_CPU1_SB_DQS_DP<2>")
	)
	(segment
		(start 146.58975 -216.323418)
		(end 146.765772 -216.323418)
		(width 0.20066)
		(layer "F.Cu")
		(net "M_E_CPU1_SB_DQS_DP<2>")
	)
	(segment
		(start 163.89985 -210.491832)
		(end 161.914078 -210.491832)
		(width 0.1016)
		(layer "F.Cu")
		(net "M_E_CPU1_SB_DQS_DP<2>")
	)
	(segment
		(start 160.568894 -210.019646)
		(end 160.375346 -209.826098)
		(width 0.20066)
		(layer "F.Cu")
		(net "M_E_CPU1_SB_DQS_DP<2>")
	)
	(segment
		(start 163.9189 -210.510882)
		(end 163.89985 -210.491832)
		(width 0.1016)
		(layer "F.Cu")
		(net "M_E_CPU1_SB_DQS_DP<2>")
	)
	(segment
		(start 138.378184 -233.502708)
		(end 138.561064 -233.502708)
		(width 0.088646)
		(layer "F.Cu")
		(net "M_E_CPU1_SB_DQS_DP<2>")
	)
	(segment
		(start 137.349484 -233.131106)
		(end 137.349484 -233.323638)
		(width 0.088646)
		(layer "F.Cu")
		(net "M_E_CPU1_SB_DQS_DP<2>")
	)
	(segment
		(start 151.7269 -211.186268)
		(end 151.902922 -211.186268)
		(width 0.20066)
		(layer "F.Cu")
		(net "M_E_CPU1_SB_DQS_DP<2>")
	)
	(segment
		(start 147.19173 -215.721438)
		(end 147.61718 -215.295988)
		(width 0.20066)
		(layer "F.Cu")
		(net "M_E_CPU1_SB_DQS_DP<2>")
	)
	(segment
		(start 137.014712 -233.064304)
		(end 137.282682 -233.064304)
		(width 0.088646)
		(layer "F.Cu")
		(net "M_E_CPU1_SB_DQS_DP<2>")
	)
	(segment
		(start 164.493194 -210.222846)
		(end 164.205158 -210.510882)
		(width 0.20066)
		(layer "F.Cu")
		(net "M_E_CPU1_SB_DQS_DP<2>")
	)
	(segment
		(start 153.67254 -209.75066)
		(end 153.797 -209.87512)
		(width 0.20066)
		(layer "F.Cu")
		(net "M_E_CPU1_SB_DQS_DP<2>")
	)
	(segment
		(start 149.848062 -213.241128)
		(end 150.27402 -212.81517)
		(width 0.20066)
		(layer "F.Cu")
		(net "M_E_CPU1_SB_DQS_DP<2>")
	)
	(segment
		(start 140.100558 -233.530902)
		(end 140.100812 -233.530648)
		(width 0.088646)
		(layer "F.Cu")
		(net "M_E_CPU1_SB_DQS_DP<2>")
	)
	(segment
		(start 158.354014 -210.066636)
		(end 158.813246 -210.066636)
		(width 0.20066)
		(layer "F.Cu")
		(net "M_E_CPU1_SB_DQS_DP<2>")
	)
	(segment
		(start 151.902922 -211.186268)
		(end 152.32888 -210.76031)
		(width 0.20066)
		(layer "F.Cu")
		(net "M_E_CPU1_SB_DQS_DP<2>")
	)
	(segment
		(start 166.357046 -210.066636)
		(end 165.914578 -210.066636)
		(width 0.20066)
		(layer "F.Cu")
		(net "M_E_CPU1_SB_DQS_DP<2>")
	)
	(segment
		(start 151.30145 -211.611718)
		(end 151.7269 -211.186268)
		(width 0.20066)
		(layer "F.Cu")
		(net "M_E_CPU1_SB_DQS_DP<2>")
	)
	(segment
		(start 139.867132 -233.530902)
		(end 140.100558 -233.530902)
		(width 0.088646)
		(layer "F.Cu")
		(net "M_E_CPU1_SB_DQS_DP<2>")
	)
	(segment
		(start 164.981128 -210.222846)
		(end 164.493194 -210.222846)
		(width 0.20066)
		(layer "F.Cu")
		(net "M_E_CPU1_SB_DQS_DP<2>")
	)
	(segment
		(start 137.282682 -233.064304)
		(end 137.349484 -233.131106)
		(width 0.088646)
		(layer "F.Cu")
		(net "M_E_CPU1_SB_DQS_DP<2>")
	)
	(segment
		(start 147.19173 -215.89746)
		(end 147.19173 -215.721438)
		(width 0.20066)
		(layer "F.Cu")
		(net "M_E_CPU1_SB_DQS_DP<2>")
	)
	(segment
		(start 146.038062 -216.875106)
		(end 146.064986 -216.848182)
		(width 0.1524)
		(layer "F.Cu")
		(net "M_E_CPU1_SB_DQS_DP<2>")
	)
	(segment
		(start 152.32888 -210.76031)
		(end 152.32888 -210.584288)
		(width 0.20066)
		(layer "F.Cu")
		(net "M_E_CPU1_SB_DQS_DP<2>")
	)
	(segment
		(start 161.914078 -210.491832)
		(end 161.89833 -210.50758)
		(width 0.1016)
		(layer "F.Cu")
		(net "M_E_CPU1_SB_DQS_DP<2>")
	)
	(segment
		(start 161.617914 -210.50758)
		(end 161.31032 -210.199986)
		(width 0.20066)
		(layer "F.Cu")
		(net "M_E_CPU1_SB_DQS_DP<2>")
	)
	(segment
		(start 161.891726 -210.50758)
		(end 161.617914 -210.50758)
		(width 0.20066)
		(layer "F.Cu")
		(net "M_E_CPU1_SB_DQS_DP<2>")
	)
	(segment
		(start 154.52344 -209.75066)
		(end 155.12542 -209.75066)
		(width 0.20066)
		(layer "F.Cu")
		(net "M_E_CPU1_SB_DQS_DP<2>")
	)
	(segment
		(start 138.053318 -233.638344)
		(end 138.378184 -233.502708)
		(width 0.088646)
		(layer "F.Cu")
		(net "M_E_CPU1_SB_DQS_DP<2>")
	)
	(segment
		(start 149.24659 -213.8426)
		(end 149.24659 -213.666578)
		(width 0.20066)
		(layer "F.Cu")
		(net "M_E_CPU1_SB_DQS_DP<2>")
	)
	(segment
		(start 150.875492 -212.213698)
		(end 151.30145 -211.78774)
		(width 0.20066)
		(layer "F.Cu")
		(net "M_E_CPU1_SB_DQS_DP<2>")
	)
	(segment
		(start 146.765772 -216.323418)
		(end 147.19173 -215.89746)
		(width 0.20066)
		(layer "F.Cu")
		(net "M_E_CPU1_SB_DQS_DP<2>")
	)
	(segment
		(start 150.69947 -212.213698)
		(end 150.875492 -212.213698)
		(width 0.20066)
		(layer "F.Cu")
		(net "M_E_CPU1_SB_DQS_DP<2>")
	)
	(segment
		(start 161.31032 -210.199986)
		(end 161.003996 -210.199986)
		(width 0.20066)
		(layer "F.Cu")
		(net "M_E_CPU1_SB_DQS_DP<2>")
	)
	(segment
		(start 159.402526 -210.066636)
		(end 158.813246 -210.066636)
		(width 0.20066)
		(layer "F.Cu")
		(net "M_E_CPU1_SB_DQS_DP<2>")
	)
	(segment
		(start 158.038038 -209.75066)
		(end 158.354014 -210.066636)
		(width 0.20066)
		(layer "F.Cu")
		(net "M_E_CPU1_SB_DQS_DP<2>")
	)
	(segment
		(start 165.914578 -210.066636)
		(end 165.632892 -209.78495)
		(width 0.20066)
		(layer "F.Cu")
		(net "M_E_CPU1_SB_DQS_DP<2>")
	)
	(segment
		(start 155.24988 -209.87512)
		(end 155.85186 -209.87512)
		(width 0.20066)
		(layer "F.Cu")
		(net "M_E_CPU1_SB_DQS_DP<2>")
	)
	(segment
		(start 157.30474 -209.87512)
		(end 157.4292 -209.75066)
		(width 0.20066)
		(layer "F.Cu")
		(net "M_E_CPU1_SB_DQS_DP<2>")
	)
	(segment
		(start 139.472162 -233.530902)
		(end 139.58062 -233.63936)
		(width 0.088646)
		(layer "F.Cu")
		(net "M_E_CPU1_SB_DQS_DP<2>")
	)
	(segment
		(start 155.97632 -209.75066)
		(end 156.5783 -209.75066)
		(width 0.20066)
		(layer "F.Cu")
		(net "M_E_CPU1_SB_DQS_DP<2>")
	)
	(segment
		(start 140.386054 -233.562652)
		(end 140.65377 -233.562652)
		(width 0.1524)
		(layer "F.Cu")
		(net "M_E_CPU1_SB_DQS_DP<2>")
	)
	(segment
		(start 163.923726 -210.510882)
		(end 163.9189 -210.510882)
		(width 0.101854)
		(layer "F.Cu")
		(net "M_E_CPU1_SB_DQS_DP<2>")
	)
	(segment
		(start 152.32888 -210.584288)
		(end 153.162508 -209.75066)
		(width 0.20066)
		(layer "F.Cu")
		(net "M_E_CPU1_SB_DQS_DP<2>")
	)
	(segment
		(start 148.21916 -214.694008)
		(end 148.64461 -214.268558)
		(width 0.20066)
		(layer "F.Cu")
		(net "M_E_CPU1_SB_DQS_DP<2>")
	)
	(segment
		(start 147.793202 -215.295988)
		(end 148.21916 -214.87003)
		(width 0.20066)
		(layer "F.Cu")
		(net "M_E_CPU1_SB_DQS_DP<2>")
	)
	(segment
		(start 153.797 -209.87512)
		(end 154.39898 -209.87512)
		(width 0.20066)
		(layer "F.Cu")
		(net "M_E_CPU1_SB_DQS_DP<2>")
	)
	(segment
		(start 149.24659 -213.666578)
		(end 149.67204 -213.241128)
		(width 0.20066)
		(layer "F.Cu")
		(net "M_E_CPU1_SB_DQS_DP<2>")
	)
	(segment
		(start 139.758674 -233.63936)
		(end 139.867132 -233.530902)
		(width 0.088646)
		(layer "F.Cu")
		(net "M_E_CPU1_SB_DQS_DP<2>")
	)
	(segment
		(start 155.85186 -209.87512)
		(end 155.97632 -209.75066)
		(width 0.20066)
		(layer "F.Cu")
		(net "M_E_CPU1_SB_DQS_DP<2>")
	)
	(segment
		(start 149.67204 -213.241128)
		(end 149.848062 -213.241128)
		(width 0.20066)
		(layer "F.Cu")
		(net "M_E_CPU1_SB_DQS_DP<2>")
	)
	(segment
		(start 140.759688 -237.492286)
		(end 142.311882 -237.492286)
		(width 0.1524)
		(layer "F.Cu")
		(net "M_E_CPU1_SB_DQS_DP<1>")
	)
	(segment
		(start 140.362686 -237.691168)
		(end 140.594588 -237.459266)
		(width 0.088646)
		(layer "F.Cu")
		(net "M_E_CPU1_SB_DQS_DP<1>")
	)
	(segment
		(start 140.726668 -237.459266)
		(end 140.759688 -237.492286)
		(width 0.088646)
		(layer "F.Cu")
		(net "M_E_CPU1_SB_DQS_DP<1>")
	)
	(segment
		(start 163.923726 -219.858082)
		(end 163.90747 -219.841826)
		(width 0.1016)
		(layer "F.Cu")
		(net "M_E_CPU1_SB_DQS_DP<1>")
	)
	(segment
		(start 165.52672 -219.134944)
		(end 165.330632 -219.134944)
		(width 0.20066)
		(layer "F.Cu")
		(net "M_E_CPU1_SB_DQS_DP<1>")
	)
	(segment
		(start 155.252928 -221.45244)
		(end 155.704032 -221.001336)
		(width 0.20066)
		(layer "F.Cu")
		(net "M_E_CPU1_SB_DQS_DP<1>")
	)
	(segment
		(start 138.237468 -238.437166)
		(end 138.290554 -238.406432)
		(width 0.088646)
		(layer "F.Cu")
		(net "M_E_CPU1_SB_DQS_DP<1>")
	)
	(segment
		(start 161.40938 -219.85478)
		(end 161.14522 -219.59062)
		(width 0.20066)
		(layer "F.Cu")
		(net "M_E_CPU1_SB_DQS_DP<1>")
	)
	(segment
		(start 157.533086 -218.893898)
		(end 157.73146 -219.092272)
		(width 0.20066)
		(layer "F.Cu")
		(net "M_E_CPU1_SB_DQS_DP<1>")
	)
	(segment
		(start 137.37082 -238.128048)
		(end 137.565892 -238.341154)
		(width 0.088646)
		(layer "F.Cu")
		(net "M_E_CPU1_SB_DQS_DP<1>")
	)
	(segment
		(start 140.114528 -237.939326)
		(end 140.25499 -237.939326)
		(width 0.088646)
		(layer "F.Cu")
		(net "M_E_CPU1_SB_DQS_DP<1>")
	)
	(segment
		(start 150.433532 -228.550978)
		(end 150.910798 -228.073712)
		(width 0.20066)
		(layer "F.Cu")
		(net "M_E_CPU1_SB_DQS_DP<1>")
	)
	(segment
		(start 161.920428 -219.841826)
		(end 161.907474 -219.85478)
		(width 0.1016)
		(layer "F.Cu")
		(net "M_E_CPU1_SB_DQS_DP<1>")
	)
	(segment
		(start 139.758166 -238.29518)
		(end 139.899136 -238.29518)
		(width 0.088646)
		(layer "F.Cu")
		(net "M_E_CPU1_SB_DQS_DP<1>")
	)
	(segment
		(start 140.006832 -238.187484)
		(end 140.006832 -238.047022)
		(width 0.088646)
		(layer "F.Cu")
		(net "M_E_CPU1_SB_DQS_DP<1>")
	)
	(segment
		(start 137.565892 -238.341154)
		(end 137.672318 -238.436658)
		(width 0.088646)
		(layer "F.Cu")
		(net "M_E_CPU1_SB_DQS_DP<1>")
	)
	(segment
		(start 154.82697 -222.05442)
		(end 155.252928 -221.628462)
		(width 0.20066)
		(layer "F.Cu")
		(net "M_E_CPU1_SB_DQS_DP<1>")
	)
	(segment
		(start 151.938228 -227.046282)
		(end 152.11425 -227.046282)
		(width 0.20066)
		(layer "F.Cu")
		(net "M_E_CPU1_SB_DQS_DP<1>")
	)
	(segment
		(start 154.222704 -224.159826)
		(end 154.347164 -224.035366)
		(width 0.20066)
		(layer "F.Cu")
		(net "M_E_CPU1_SB_DQS_DP<1>")
	)
	(segment
		(start 156.306012 -220.575378)
		(end 156.306012 -220.399356)
		(width 0.20066)
		(layer "F.Cu")
		(net "M_E_CPU1_SB_DQS_DP<1>")
	)
	(segment
		(start 142.311882 -237.492286)
		(end 149.638512 -230.165656)
		(width 0.1524)
		(layer "F.Cu")
		(net "M_E_CPU1_SB_DQS_DP<1>")
	)
	(segment
		(start 151.512778 -227.471732)
		(end 151.938228 -227.046282)
		(width 0.20066)
		(layer "F.Cu")
		(net "M_E_CPU1_SB_DQS_DP<1>")
	)
	(segment
		(start 161.14522 -219.59062)
		(end 160.595056 -219.59062)
		(width 0.20066)
		(layer "F.Cu")
		(net "M_E_CPU1_SB_DQS_DP<1>")
	)
	(segment
		(start 161.891726 -219.85478)
		(end 161.40938 -219.85478)
		(width 0.20066)
		(layer "F.Cu")
		(net "M_E_CPU1_SB_DQS_DP<1>")
	)
	(segment
		(start 155.252928 -221.628462)
		(end 155.252928 -221.45244)
		(width 0.20066)
		(layer "F.Cu")
		(net "M_E_CPU1_SB_DQS_DP<1>")
	)
	(segment
		(start 160.180528 -219.176092)
		(end 159.643064 -219.176092)
		(width 0.20066)
		(layer "F.Cu")
		(net "M_E_CPU1_SB_DQS_DP<1>")
	)
	(segment
		(start 139.899136 -238.29518)
		(end 140.006832 -238.187484)
		(width 0.088646)
		(layer "F.Cu")
		(net "M_E_CPU1_SB_DQS_DP<1>")
	)
	(segment
		(start 154.347164 -224.035366)
		(end 154.347164 -223.433386)
		(width 0.20066)
		(layer "F.Cu")
		(net "M_E_CPU1_SB_DQS_DP<1>")
	)
	(segment
		(start 149.638512 -230.165656)
		(end 149.638512 -229.293674)
		(width 0.1524)
		(layer "F.Cu")
		(net "M_E_CPU1_SB_DQS_DP<1>")
	)
	(segment
		(start 165.808406 -219.41663)
		(end 165.52672 -219.134944)
		(width 0.20066)
		(layer "F.Cu")
		(net "M_E_CPU1_SB_DQS_DP<1>")
	)
	(segment
		(start 150.354284 -228.577902)
		(end 150.406608 -228.577902)
		(width 0.1524)
		(layer "F.Cu")
		(net "M_E_CPU1_SB_DQS_DP<1>")
	)
	(segment
		(start 154.222704 -222.482664)
		(end 154.650948 -222.05442)
		(width 0.20066)
		(layer "F.Cu")
		(net "M_E_CPU1_SB_DQS_DP<1>")
	)
	(segment
		(start 138.882882 -238.493046)
		(end 139.21613 -238.493046)
		(width 0.088646)
		(layer "F.Cu")
		(net "M_E_CPU1_SB_DQS_DP<1>")
	)
	(segment
		(start 159.402526 -219.41663)
		(end 158.813246 -219.41663)
		(width 0.20066)
		(layer "F.Cu")
		(net "M_E_CPU1_SB_DQS_DP<1>")
	)
	(segment
		(start 165.330632 -219.134944)
		(end 164.935662 -219.529914)
		(width 0.20066)
		(layer "F.Cu")
		(net "M_E_CPU1_SB_DQS_DP<1>")
	)
	(segment
		(start 139.699238 -238.354108)
		(end 139.758166 -238.29518)
		(width 0.088646)
		(layer "F.Cu")
		(net "M_E_CPU1_SB_DQS_DP<1>")
	)
	(segment
		(start 166.357046 -219.41663)
		(end 165.808406 -219.41663)
		(width 0.20066)
		(layer "F.Cu")
		(net "M_E_CPU1_SB_DQS_DP<1>")
	)
	(segment
		(start 160.595056 -219.59062)
		(end 160.180528 -219.176092)
		(width 0.20066)
		(layer "F.Cu")
		(net "M_E_CPU1_SB_DQS_DP<1>")
	)
	(segment
		(start 163.90747 -219.841826)
		(end 161.920428 -219.841826)
		(width 0.1016)
		(layer "F.Cu")
		(net "M_E_CPU1_SB_DQS_DP<1>")
	)
	(segment
		(start 149.638512 -229.293674)
		(end 150.354284 -228.577902)
		(width 0.1524)
		(layer "F.Cu")
		(net "M_E_CPU1_SB_DQS_DP<1>")
	)
	(segment
		(start 157.842204 -219.41663)
		(end 158.813246 -219.41663)
		(width 0.20066)
		(layer "F.Cu")
		(net "M_E_CPU1_SB_DQS_DP<1>")
	)
	(segment
		(start 137.014712 -237.947454)
		(end 137.148062 -237.918752)
		(width 0.088646)
		(layer "F.Cu")
		(net "M_E_CPU1_SB_DQS_DP<1>")
	)
	(segment
		(start 157.11424 -218.893898)
		(end 157.533086 -218.893898)
		(width 0.20066)
		(layer "F.Cu")
		(net "M_E_CPU1_SB_DQS_DP<1>")
	)
	(segment
		(start 156.82595 -219.182188)
		(end 157.11424 -218.893898)
		(width 0.20066)
		(layer "F.Cu")
		(net "M_E_CPU1_SB_DQS_DP<1>")
	)
	(segment
		(start 154.222704 -224.761806)
		(end 154.222704 -224.159826)
		(width 0.20066)
		(layer "F.Cu")
		(net "M_E_CPU1_SB_DQS_DP<1>")
	)
	(segment
		(start 152.11425 -227.046282)
		(end 152.540208 -226.620324)
		(width 0.20066)
		(layer "F.Cu")
		(net "M_E_CPU1_SB_DQS_DP<1>")
	)
	(segment
		(start 152.540208 -226.444302)
		(end 152.965658 -226.018852)
		(width 0.20066)
		(layer "F.Cu")
		(net "M_E_CPU1_SB_DQS_DP<1>")
	)
	(segment
		(start 152.965658 -226.018852)
		(end 153.14168 -226.018852)
		(width 0.20066)
		(layer "F.Cu")
		(net "M_E_CPU1_SB_DQS_DP<1>")
	)
	(segment
		(start 151.08682 -228.073712)
		(end 151.512778 -227.647754)
		(width 0.20066)
		(layer "F.Cu")
		(net "M_E_CPU1_SB_DQS_DP<1>")
	)
	(segment
		(start 156.306012 -220.399356)
		(end 156.82595 -219.879418)
		(width 0.20066)
		(layer "F.Cu")
		(net "M_E_CPU1_SB_DQS_DP<1>")
	)
	(segment
		(start 154.650948 -222.05442)
		(end 154.82697 -222.05442)
		(width 0.20066)
		(layer "F.Cu")
		(net "M_E_CPU1_SB_DQS_DP<1>")
	)
	(segment
		(start 155.880054 -221.001336)
		(end 156.306012 -220.575378)
		(width 0.20066)
		(layer "F.Cu")
		(net "M_E_CPU1_SB_DQS_DP<1>")
	)
	(segment
		(start 150.406608 -228.577902)
		(end 150.433532 -228.550978)
		(width 0.1524)
		(layer "F.Cu")
		(net "M_E_CPU1_SB_DQS_DP<1>")
	)
	(segment
		(start 153.567638 -225.416872)
		(end 154.222704 -224.761806)
		(width 0.20066)
		(layer "F.Cu")
		(net "M_E_CPU1_SB_DQS_DP<1>")
	)
	(segment
		(start 161.907474 -219.85478)
		(end 161.902394 -219.85478)
		(width 0.1016)
		(layer "F.Cu")
		(net "M_E_CPU1_SB_DQS_DP<1>")
	)
	(segment
		(start 153.567638 -225.592894)
		(end 153.567638 -225.416872)
		(width 0.20066)
		(layer "F.Cu")
		(net "M_E_CPU1_SB_DQS_DP<1>")
	)
	(segment
		(start 154.347164 -223.433386)
		(end 154.222704 -223.308926)
		(width 0.20066)
		(layer "F.Cu")
		(net "M_E_CPU1_SB_DQS_DP<1>")
	)
	(segment
		(start 157.73146 -219.092272)
		(end 157.73146 -219.305886)
		(width 0.20066)
		(layer "F.Cu")
		(net "M_E_CPU1_SB_DQS_DP<1>")
	)
	(segment
		(start 156.82595 -219.879418)
		(end 156.82595 -219.182188)
		(width 0.20066)
		(layer "F.Cu")
		(net "M_E_CPU1_SB_DQS_DP<1>")
	)
	(segment
		(start 140.006832 -238.047022)
		(end 140.114528 -237.939326)
		(width 0.088646)
		(layer "F.Cu")
		(net "M_E_CPU1_SB_DQS_DP<1>")
	)
	(segment
		(start 152.540208 -226.620324)
		(end 152.540208 -226.444302)
		(width 0.20066)
		(layer "F.Cu")
		(net "M_E_CPU1_SB_DQS_DP<1>")
	)
	(segment
		(start 164.585396 -219.529914)
		(end 164.257228 -219.858082)
		(width 0.20066)
		(layer "F.Cu")
		(net "M_E_CPU1_SB_DQS_DP<1>")
	)
	(segment
		(start 151.512778 -227.647754)
		(end 151.512778 -227.471732)
		(width 0.20066)
		(layer "F.Cu")
		(net "M_E_CPU1_SB_DQS_DP<1>")
	)
	(segment
		(start 139.641834 -238.38281)
		(end 139.699238 -238.354108)
		(width 0.088646)
		(layer "F.Cu")
		(net "M_E_CPU1_SB_DQS_DP<1>")
	)
	(segment
		(start 161.902394 -219.85478)
		(end 161.891726 -219.85478)
		(width 0.101854)
		(layer "F.Cu")
		(net "M_E_CPU1_SB_DQS_DP<1>")
	)
	(segment
		(start 150.910798 -228.073712)
		(end 151.08682 -228.073712)
		(width 0.20066)
		(layer "F.Cu")
		(net "M_E_CPU1_SB_DQS_DP<1>")
	)
	(segment
		(start 137.148062 -237.918752)
		(end 137.27684 -238.002064)
		(width 0.088646)
		(layer "F.Cu")
		(net "M_E_CPU1_SB_DQS_DP<1>")
	)
	(segment
		(start 153.14168 -226.018852)
		(end 153.567638 -225.592894)
		(width 0.20066)
		(layer "F.Cu")
		(net "M_E_CPU1_SB_DQS_DP<1>")
	)
	(segment
		(start 154.222704 -223.308926)
		(end 154.222704 -222.482664)
		(width 0.20066)
		(layer "F.Cu")
		(net "M_E_CPU1_SB_DQS_DP<1>")
	)
	(segment
		(start 155.704032 -221.001336)
		(end 155.880054 -221.001336)
		(width 0.20066)
		(layer "F.Cu")
		(net "M_E_CPU1_SB_DQS_DP<1>")
	)
	(segment
		(start 157.73146 -219.305886)
		(end 157.842204 -219.41663)
		(width 0.20066)
		(layer "F.Cu")
		(net "M_E_CPU1_SB_DQS_DP<1>")
	)
	(segment
		(start 164.257228 -219.858082)
		(end 163.923726 -219.858082)
		(width 0.20066)
		(layer "F.Cu")
		(net "M_E_CPU1_SB_DQS_DP<1>")
	)
	(segment
		(start 140.25499 -237.939326)
		(end 140.362686 -237.83163)
		(width 0.088646)
		(layer "F.Cu")
		(net "M_E_CPU1_SB_DQS_DP<1>")
	)
	(segment
		(start 138.23696 -238.436658)
		(end 138.237468 -238.437166)
		(width 0.088646)
		(layer "F.Cu")
		(net "M_E_CPU1_SB_DQS_DP<1>")
	)
	(segment
		(start 137.27684 -238.002064)
		(end 137.37082 -238.128048)
		(width 0.088646)
		(layer "F.Cu")
		(net "M_E_CPU1_SB_DQS_DP<1>")
	)
	(segment
		(start 159.643064 -219.176092)
		(end 159.402526 -219.41663)
		(width 0.20066)
		(layer "F.Cu")
		(net "M_E_CPU1_SB_DQS_DP<1>")
	)
	(segment
		(start 140.362686 -237.83163)
		(end 140.362686 -237.691168)
		(width 0.088646)
		(layer "F.Cu")
		(net "M_E_CPU1_SB_DQS_DP<1>")
	)
	(segment
		(start 164.935662 -219.529914)
		(end 164.585396 -219.529914)
		(width 0.20066)
		(layer "F.Cu")
		(net "M_E_CPU1_SB_DQS_DP<1>")
	)
	(segment
		(start 139.21613 -238.493046)
		(end 139.478512 -238.450628)
		(width 0.088646)
		(layer "F.Cu")
		(net "M_E_CPU1_SB_DQS_DP<1>")
	)
	(segment
		(start 140.594588 -237.459266)
		(end 140.726668 -237.459266)
		(width 0.088646)
		(layer "F.Cu")
		(net "M_E_CPU1_SB_DQS_DP<1>")
	)
	(arc
		(start 137.672318 -238.436658)
		(mid 137.954656 -238.512341)
		(end 138.23696 -238.436658)
		(width 0.088646)
		(layer "F.Cu")
		(net "M_E_CPU1_SB_DQS_DP<1>")
	)
	(arc
		(start 138.559032 -238.406178)
		(mid 138.715245 -238.470915)
		(end 138.882882 -238.493046)
		(width 0.088646)
		(layer "F.Cu")
		(net "M_E_CPU1_SB_DQS_DP<1>")
	)
	(arc
		(start 139.478512 -238.450628)
		(mid 139.561387 -238.419643)
		(end 139.641834 -238.38281)
		(width 0.088646)
		(layer "F.Cu")
		(net "M_E_CPU1_SB_DQS_DP<1>")
	)
	(arc
		(start 138.290554 -238.406432)
		(mid 138.424747 -238.370386)
		(end 138.559032 -238.406178)
		(width 0.088646)
		(layer "F.Cu")
		(net "M_E_CPU1_SB_DQS_DP<1>")
	)
	(segment
		(start 161.595054 -229.19182)
		(end 161.343848 -228.940614)
		(width 0.20066)
		(layer "F.Cu")
		(net "M_E_CPU1_SB_DQS_DP<0>")
	)
	(segment
		(start 160.626298 -228.940614)
		(end 160.21177 -228.526086)
		(width 0.20066)
		(layer "F.Cu")
		(net "M_E_CPU1_SB_DQS_DP<0>")
	)
	(segment
		(start 165.53434 -228.492558)
		(end 165.316408 -228.492558)
		(width 0.20066)
		(layer "F.Cu")
		(net "M_E_CPU1_SB_DQS_DP<0>")
	)
	(segment
		(start 165.808406 -228.766624)
		(end 165.53434 -228.492558)
		(width 0.20066)
		(layer "F.Cu")
		(net "M_E_CPU1_SB_DQS_DP<0>")
	)
	(segment
		(start 132.785612 -235.505752)
		(end 132.785612 -234.970066)
		(width 0.20066)
		(layer "F.Cu")
		(net "M_E_CPU1_SB_DQS_DP<0>")
	)
	(segment
		(start 161.701988 -229.19182)
		(end 161.595054 -229.19182)
		(width 0.20066)
		(layer "F.Cu")
		(net "M_E_CPU1_SB_DQS_DP<0>")
	)
	(segment
		(start 132.785866 -235.506006)
		(end 132.785612 -235.505752)
		(width 0.20066)
		(layer "F.Cu")
		(net "M_E_CPU1_SB_DQS_DP<0>")
	)
	(segment
		(start 161.708084 -229.19182)
		(end 161.701988 -229.19182)
		(width 0.101854)
		(layer "F.Cu")
		(net "M_E_CPU1_SB_DQS_DP<0>")
	)
	(segment
		(start 157.682946 -228.766624)
		(end 158.813246 -228.766624)
		(width 0.20066)
		(layer "F.Cu")
		(net "M_E_CPU1_SB_DQS_DP<0>")
	)
	(segment
		(start 161.343848 -228.940614)
		(end 160.626298 -228.940614)
		(width 0.20066)
		(layer "F.Cu")
		(net "M_E_CPU1_SB_DQS_DP<0>")
	)
	(segment
		(start 163.923726 -229.210616)
		(end 163.90493 -229.19182)
		(width 0.1016)
		(layer "F.Cu")
		(net "M_E_CPU1_SB_DQS_DP<0>")
	)
	(segment
		(start 164.493448 -228.951536)
		(end 164.234368 -229.210616)
		(width 0.20066)
		(layer "F.Cu")
		(net "M_E_CPU1_SB_DQS_DP<0>")
	)
	(segment
		(start 164.234368 -229.210616)
		(end 163.923726 -229.210616)
		(width 0.20066)
		(layer "F.Cu")
		(net "M_E_CPU1_SB_DQS_DP<0>")
	)
	(segment
		(start 163.90493 -229.19182)
		(end 161.708084 -229.19182)
		(width 0.1016)
		(layer "F.Cu")
		(net "M_E_CPU1_SB_DQS_DP<0>")
	)
	(segment
		(start 164.85743 -228.951536)
		(end 164.493448 -228.951536)
		(width 0.20066)
		(layer "F.Cu")
		(net "M_E_CPU1_SB_DQS_DP<0>")
	)
	(segment
		(start 159.643064 -228.526086)
		(end 159.402526 -228.766624)
		(width 0.20066)
		(layer "F.Cu")
		(net "M_E_CPU1_SB_DQS_DP<0>")
	)
	(segment
		(start 160.21177 -228.526086)
		(end 159.643064 -228.526086)
		(width 0.20066)
		(layer "F.Cu")
		(net "M_E_CPU1_SB_DQS_DP<0>")
	)
	(segment
		(start 166.357046 -228.766624)
		(end 165.808406 -228.766624)
		(width 0.20066)
		(layer "F.Cu")
		(net "M_E_CPU1_SB_DQS_DP<0>")
	)
	(segment
		(start 165.316408 -228.492558)
		(end 164.85743 -228.951536)
		(width 0.20066)
		(layer "F.Cu")
		(net "M_E_CPU1_SB_DQS_DP<0>")
	)
	(segment
		(start 159.402526 -228.766624)
		(end 158.813246 -228.766624)
		(width 0.20066)
		(layer "F.Cu")
		(net "M_E_CPU1_SB_DQS_DP<0>")
	)
	(segment
		(start 157.682946 -228.766624)
		(end 157.396434 -228.480112)
		(width 0.18288)
		(layer "In2.Cu")
		(net "M_E_CPU1_SB_DQS_DP<0>")
	)
	(segment
		(start 140.696696 -235.167424)
		(end 140.636752 -235.10748)
		(width 0.088646)
		(layer "In2.Cu")
		(net "M_E_CPU1_SB_DQS_DP<0>")
	)
	(segment
		(start 157.396434 -228.480112)
		(end 156.53512 -228.480112)
		(width 0.18288)
		(layer "In2.Cu")
		(net "M_E_CPU1_SB_DQS_DP<0>")
	)
	(segment
		(start 140.124942 -235.10748)
		(end 139.697206 -235.535216)
		(width 0.088646)
		(layer "In2.Cu")
		(net "M_E_CPU1_SB_DQS_DP<0>")
	)
	(segment
		(start 133.09854 -234.970066)
		(end 132.785612 -234.970066)
		(width 0.088646)
		(layer "In2.Cu")
		(net "M_E_CPU1_SB_DQS_DP<0>")
	)
	(segment
		(start 139.697206 -235.535216)
		(end 139.363958 -235.535216)
		(width 0.088646)
		(layer "In2.Cu")
		(net "M_E_CPU1_SB_DQS_DP<0>")
	)
	(segment
		(start 150.60803 -234.407202)
		(end 148.77288 -235.167424)
		(width 0.18288)
		(layer "In2.Cu")
		(net "M_E_CPU1_SB_DQS_DP<0>")
	)
	(segment
		(start 133.164072 -235.035598)
		(end 133.09854 -234.970066)
		(width 0.088646)
		(layer "In2.Cu")
		(net "M_E_CPU1_SB_DQS_DP<0>")
	)
	(segment
		(start 138.156696 -235.46816)
		(end 138.141964 -235.459524)
		(width 0.088646)
		(layer "In2.Cu")
		(net "M_E_CPU1_SB_DQS_DP<0>")
	)
	(segment
		(start 133.442964 -235.459524)
		(end 133.430772 -235.452412)
		(width 0.088646)
		(layer "In2.Cu")
		(net "M_E_CPU1_SB_DQS_DP<0>")
	)
	(segment
		(start 148.77288 -235.167424)
		(end 140.696696 -235.167424)
		(width 0.18288)
		(layer "In2.Cu")
		(net "M_E_CPU1_SB_DQS_DP<0>")
	)
	(segment
		(start 140.636752 -235.10748)
		(end 140.124942 -235.10748)
		(width 0.088646)
		(layer "In2.Cu")
		(net "M_E_CPU1_SB_DQS_DP<0>")
	)
	(segment
		(start 136.277096 -235.46816)
		(end 136.262364 -235.459524)
		(width 0.088646)
		(layer "In2.Cu")
		(net "M_E_CPU1_SB_DQS_DP<0>")
	)
	(segment
		(start 137.216896 -235.46816)
		(end 137.202164 -235.459524)
		(width 0.088646)
		(layer "In2.Cu")
		(net "M_E_CPU1_SB_DQS_DP<0>")
	)
	(segment
		(start 156.53512 -228.480112)
		(end 150.60803 -234.407202)
		(width 0.18288)
		(layer "In2.Cu")
		(net "M_E_CPU1_SB_DQS_DP<0>")
	)
	(arc
		(start 138.141964 -235.459524)
		(mid 137.954766 -235.409381)
		(end 137.767568 -235.459524)
		(width 0.088646)
		(layer "In2.Cu")
		(net "M_E_CPU1_SB_DQS_DP<0>")
	)
	(arc
		(start 134.008368 -235.459524)
		(mid 133.725666 -235.5353)
		(end 133.442964 -235.459524)
		(width 0.088646)
		(layer "In2.Cu")
		(net "M_E_CPU1_SB_DQS_DP<0>")
	)
	(arc
		(start 137.767568 -235.459524)
		(mid 137.493369 -235.535359)
		(end 137.216896 -235.46816)
		(width 0.088646)
		(layer "In2.Cu")
		(net "M_E_CPU1_SB_DQS_DP<0>")
	)
	(arc
		(start 135.887968 -235.459524)
		(mid 135.605266 -235.5353)
		(end 135.322564 -235.459524)
		(width 0.088646)
		(layer "In2.Cu")
		(net "M_E_CPU1_SB_DQS_DP<0>")
	)
	(arc
		(start 138.707368 -235.459524)
		(mid 138.433169 -235.535359)
		(end 138.156696 -235.46816)
		(width 0.088646)
		(layer "In2.Cu")
		(net "M_E_CPU1_SB_DQS_DP<0>")
	)
	(arc
		(start 135.322564 -235.459524)
		(mid 135.135366 -235.409381)
		(end 134.948168 -235.459524)
		(width 0.088646)
		(layer "In2.Cu")
		(net "M_E_CPU1_SB_DQS_DP<0>")
	)
	(arc
		(start 139.363958 -235.535216)
		(mid 139.217877 -235.515942)
		(end 139.081764 -235.459524)
		(width 0.088646)
		(layer "In2.Cu")
		(net "M_E_CPU1_SB_DQS_DP<0>")
	)
	(arc
		(start 136.827768 -235.459524)
		(mid 136.553569 -235.535359)
		(end 136.277096 -235.46816)
		(width 0.088646)
		(layer "In2.Cu")
		(net "M_E_CPU1_SB_DQS_DP<0>")
	)
	(arc
		(start 134.948168 -235.459524)
		(mid 134.665466 -235.5353)
		(end 134.382764 -235.459524)
		(width 0.088646)
		(layer "In2.Cu")
		(net "M_E_CPU1_SB_DQS_DP<0>")
	)
	(arc
		(start 134.382764 -235.459524)
		(mid 134.195566 -235.409381)
		(end 134.008368 -235.459524)
		(width 0.088646)
		(layer "In2.Cu")
		(net "M_E_CPU1_SB_DQS_DP<0>")
	)
	(arc
		(start 136.262364 -235.459524)
		(mid 136.075166 -235.409381)
		(end 135.887968 -235.459524)
		(width 0.088646)
		(layer "In2.Cu")
		(net "M_E_CPU1_SB_DQS_DP<0>")
	)
	(arc
		(start 133.166866 -235.056426)
		(mid 133.165372 -235.046025)
		(end 133.164072 -235.035598)
		(width 0.088646)
		(layer "In2.Cu")
		(net "M_E_CPU1_SB_DQS_DP<0>")
	)
	(arc
		(start 133.430772 -235.452412)
		(mid 133.25517 -235.28352)
		(end 133.166866 -235.056426)
		(width 0.088646)
		(layer "In2.Cu")
		(net "M_E_CPU1_SB_DQS_DP<0>")
	)
	(arc
		(start 137.202164 -235.459524)
		(mid 137.014966 -235.409381)
		(end 136.827768 -235.459524)
		(width 0.088646)
		(layer "In2.Cu")
		(net "M_E_CPU1_SB_DQS_DP<0>")
	)
	(arc
		(start 139.081764 -235.459524)
		(mid 138.894566 -235.409381)
		(end 138.707368 -235.459524)
		(width 0.088646)
		(layer "In2.Cu")
		(net "M_E_CPU1_SB_DQS_DP<0>")
	)
	(segment
		(start 165.535102 -237.571534)
		(end 165.305232 -237.571534)
		(width 0.20066)
		(layer "F.Cu")
		(net "M_E_CPU1_SB_DQS_DN<9>")
	)
	(segment
		(start 159.643572 -237.54842)
		(end 159.361886 -237.266734)
		(width 0.20066)
		(layer "F.Cu")
		(net "M_E_CPU1_SB_DQS_DN<9>")
	)
	(segment
		(start 136.827514 -242.5065)
		(end 136.79805 -242.523772)
		(width 0.088646)
		(layer "F.Cu")
		(net "M_E_CPU1_SB_DQS_DN<9>")
	)
	(segment
		(start 161.504376 -237.691676)
		(end 161.487612 -237.674912)
		(width 0.101854)
		(layer "F.Cu")
		(net "M_E_CPU1_SB_DQS_DN<9>")
	)
	(segment
		(start 161.487612 -237.674912)
		(end 161.408618 -237.674912)
		(width 0.20066)
		(layer "F.Cu")
		(net "M_E_CPU1_SB_DQS_DN<9>")
	)
	(segment
		(start 138.919204 -243.205762)
		(end 138.91895 -243.206016)
		(width 0.088646)
		(layer "F.Cu")
		(net "M_E_CPU1_SB_DQS_DN<9>")
	)
	(segment
		(start 139.199366 -243.205762)
		(end 138.919204 -243.205762)
		(width 0.088646)
		(layer "F.Cu")
		(net "M_E_CPU1_SB_DQS_DN<9>")
	)
	(segment
		(start 137.577576 -242.92052)
		(end 137.508488 -242.80114)
		(width 0.088646)
		(layer "F.Cu")
		(net "M_E_CPU1_SB_DQS_DN<9>")
	)
	(segment
		(start 140.636498 -242.29314)
		(end 140.621004 -242.308634)
		(width 0.088646)
		(layer "F.Cu")
		(net "M_E_CPU1_SB_DQS_DN<9>")
	)
	(segment
		(start 161.408618 -237.674912)
		(end 161.133536 -237.949994)
		(width 0.20066)
		(layer "F.Cu")
		(net "M_E_CPU1_SB_DQS_DN<9>")
	)
	(segment
		(start 137.20191 -242.506754)
		(end 137.201402 -242.506754)
		(width 0.088646)
		(layer "F.Cu")
		(net "M_E_CPU1_SB_DQS_DN<9>")
	)
	(segment
		(start 138.91895 -243.206016)
		(end 138.894312 -243.206016)
		(width 0.088646)
		(layer "F.Cu")
		(net "M_E_CPU1_SB_DQS_DN<9>")
	)
	(segment
		(start 165.839902 -237.266734)
		(end 165.535102 -237.571534)
		(width 0.20066)
		(layer "F.Cu")
		(net "M_E_CPU1_SB_DQS_DN<9>")
	)
	(segment
		(start 136.79805 -242.523772)
		(end 136.075166 -242.831112)
		(width 0.088646)
		(layer "F.Cu")
		(net "M_E_CPU1_SB_DQS_DN<9>")
	)
	(segment
		(start 147.886166 -237.938564)
		(end 147.094956 -237.938564)
		(width 0.1524)
		(layer "F.Cu")
		(net "M_E_CPU1_SB_DQS_DN<9>")
	)
	(segment
		(start 143.882364 -241.151156)
		(end 141.778482 -241.151156)
		(width 0.1524)
		(layer "F.Cu")
		(net "M_E_CPU1_SB_DQS_DN<9>")
	)
	(segment
		(start 146.946112 -238.087408)
		(end 143.882364 -241.151156)
		(width 0.1524)
		(layer "F.Cu")
		(net "M_E_CPU1_SB_DQS_DN<9>")
	)
	(segment
		(start 156.81706 -237.266988)
		(end 156.182314 -237.901734)
		(width 0.20066)
		(layer "F.Cu")
		(net "M_E_CPU1_SB_DQS_DN<9>")
	)
	(segment
		(start 164.470588 -237.691676)
		(end 164.338508 -237.691676)
		(width 0.20066)
		(layer "F.Cu")
		(net "M_E_CPU1_SB_DQS_DN<9>")
	)
	(segment
		(start 147.094956 -237.938564)
		(end 146.946366 -238.087154)
		(width 0.1524)
		(layer "F.Cu")
		(net "M_E_CPU1_SB_DQS_DN<9>")
	)
	(segment
		(start 137.767314 -243.155724)
		(end 137.767314 -243.155216)
		(width 0.088646)
		(layer "F.Cu")
		(net "M_E_CPU1_SB_DQS_DN<9>")
	)
	(segment
		(start 164.338508 -237.691676)
		(end 163.902898 -237.691676)
		(width 0.101854)
		(layer "F.Cu")
		(net "M_E_CPU1_SB_DQS_DN<9>")
	)
	(segment
		(start 160.516316 -237.54842)
		(end 159.643572 -237.54842)
		(width 0.20066)
		(layer "F.Cu")
		(net "M_E_CPU1_SB_DQS_DN<9>")
	)
	(segment
		(start 140.621004 -242.353592)
		(end 140.054076 -242.92052)
		(width 0.088646)
		(layer "F.Cu")
		(net "M_E_CPU1_SB_DQS_DN<9>")
	)
	(segment
		(start 164.985192 -237.891574)
		(end 164.670486 -237.891574)
		(width 0.20066)
		(layer "F.Cu")
		(net "M_E_CPU1_SB_DQS_DN<9>")
	)
	(segment
		(start 146.946112 -238.087154)
		(end 146.946112 -238.087408)
		(width 0.1524)
		(layer "F.Cu")
		(net "M_E_CPU1_SB_DQS_DN<9>")
	)
	(segment
		(start 159.361886 -237.266734)
		(end 158.813246 -237.266734)
		(width 0.20066)
		(layer "F.Cu")
		(net "M_E_CPU1_SB_DQS_DN<9>")
	)
	(segment
		(start 156.182314 -237.901734)
		(end 147.961096 -237.901734)
		(width 0.20066)
		(layer "F.Cu")
		(net "M_E_CPU1_SB_DQS_DN<9>")
	)
	(segment
		(start 147.922996 -237.901734)
		(end 147.886166 -237.938564)
		(width 0.1524)
		(layer "F.Cu")
		(net "M_E_CPU1_SB_DQS_DN<9>")
	)
	(segment
		(start 164.670486 -237.891574)
		(end 164.470588 -237.691676)
		(width 0.20066)
		(layer "F.Cu")
		(net "M_E_CPU1_SB_DQS_DN<9>")
	)
	(segment
		(start 146.946366 -238.087154)
		(end 146.946112 -238.087154)
		(width 0.1524)
		(layer "F.Cu")
		(net "M_E_CPU1_SB_DQS_DN<9>")
	)
	(segment
		(start 166.357046 -237.266734)
		(end 165.839902 -237.266734)
		(width 0.20066)
		(layer "F.Cu")
		(net "M_E_CPU1_SB_DQS_DN<9>")
	)
	(segment
		(start 140.054076 -242.92052)
		(end 139.484608 -242.92052)
		(width 0.088646)
		(layer "F.Cu")
		(net "M_E_CPU1_SB_DQS_DN<9>")
	)
	(segment
		(start 137.23112 -242.523772)
		(end 137.20191 -242.506754)
		(width 0.088646)
		(layer "F.Cu")
		(net "M_E_CPU1_SB_DQS_DN<9>")
	)
	(segment
		(start 136.075166 -242.831112)
		(end 136.075166 -242.830858)
		(width 0.088646)
		(layer "F.Cu")
		(net "M_E_CPU1_SB_DQS_DN<9>")
	)
	(segment
		(start 147.961096 -237.901734)
		(end 147.922996 -237.901734)
		(width 0.1524)
		(layer "F.Cu")
		(net "M_E_CPU1_SB_DQS_DN<9>")
	)
	(segment
		(start 161.133536 -237.949994)
		(end 160.91789 -237.949994)
		(width 0.20066)
		(layer "F.Cu")
		(net "M_E_CPU1_SB_DQS_DN<9>")
	)
	(segment
		(start 158.813246 -237.266734)
		(end 158.812992 -237.266988)
		(width 0.20066)
		(layer "F.Cu")
		(net "M_E_CPU1_SB_DQS_DN<9>")
	)
	(segment
		(start 165.305232 -237.571534)
		(end 164.985192 -237.891574)
		(width 0.20066)
		(layer "F.Cu")
		(net "M_E_CPU1_SB_DQS_DN<9>")
	)
	(segment
		(start 161.913316 -237.691676)
		(end 161.504376 -237.691676)
		(width 0.101854)
		(layer "F.Cu")
		(net "M_E_CPU1_SB_DQS_DN<9>")
	)
	(segment
		(start 140.621004 -242.308634)
		(end 140.621004 -242.353592)
		(width 0.088646)
		(layer "F.Cu")
		(net "M_E_CPU1_SB_DQS_DN<9>")
	)
	(segment
		(start 163.902898 -237.691676)
		(end 161.913316 -237.691676)
		(width 0.1016)
		(layer "F.Cu")
		(net "M_E_CPU1_SB_DQS_DN<9>")
	)
	(segment
		(start 160.91789 -237.949994)
		(end 160.516316 -237.54842)
		(width 0.20066)
		(layer "F.Cu")
		(net "M_E_CPU1_SB_DQS_DN<9>")
	)
	(segment
		(start 139.484608 -242.92052)
		(end 139.199366 -243.205762)
		(width 0.088646)
		(layer "F.Cu")
		(net "M_E_CPU1_SB_DQS_DN<9>")
	)
	(segment
		(start 141.778482 -241.151156)
		(end 140.636498 -242.29314)
		(width 0.1524)
		(layer "F.Cu")
		(net "M_E_CPU1_SB_DQS_DN<9>")
	)
	(segment
		(start 158.812992 -237.266988)
		(end 156.81706 -237.266988)
		(width 0.20066)
		(layer "F.Cu")
		(net "M_E_CPU1_SB_DQS_DN<9>")
	)
	(arc
		(start 138.142472 -243.155724)
		(mid 137.95491 -243.205926)
		(end 137.767314 -243.155724)
		(width 0.088646)
		(layer "F.Cu")
		(net "M_E_CPU1_SB_DQS_DN<9>")
	)
	(arc
		(start 137.61974 -242.99926)
		(mid 137.599236 -242.959581)
		(end 137.577576 -242.92052)
		(width 0.088646)
		(layer "F.Cu")
		(net "M_E_CPU1_SB_DQS_DN<9>")
	)
	(arc
		(start 138.894312 -243.206016)
		(mid 138.797273 -243.193222)
		(end 138.70686 -243.155724)
		(width 0.088646)
		(layer "F.Cu")
		(net "M_E_CPU1_SB_DQS_DN<9>")
	)
	(arc
		(start 138.70686 -243.155724)
		(mid 138.424666 -243.080168)
		(end 138.142472 -243.155724)
		(width 0.088646)
		(layer "F.Cu")
		(net "M_E_CPU1_SB_DQS_DN<9>")
	)
	(arc
		(start 137.508488 -242.80114)
		(mid 137.388025 -242.644235)
		(end 137.23112 -242.523772)
		(width 0.088646)
		(layer "F.Cu")
		(net "M_E_CPU1_SB_DQS_DN<9>")
	)
	(arc
		(start 137.632186 -243.02212)
		(mid 137.625766 -243.010797)
		(end 137.61974 -242.99926)
		(width 0.088646)
		(layer "F.Cu")
		(net "M_E_CPU1_SB_DQS_DN<9>")
	)
	(arc
		(start 137.201402 -242.506754)
		(mid 137.014487 -242.456543)
		(end 136.827514 -242.5065)
		(width 0.088646)
		(layer "F.Cu")
		(net "M_E_CPU1_SB_DQS_DN<9>")
	)
	(arc
		(start 137.767314 -243.155216)
		(mid 137.691154 -243.09739)
		(end 137.632186 -243.02212)
		(width 0.088646)
		(layer "F.Cu")
		(net "M_E_CPU1_SB_DQS_DN<9>")
	)
	(segment
		(start 156.96311 -199.14743)
		(end 157.19806 -199.14743)
		(width 0.20066)
		(layer "F.Cu")
		(net "M_E_CPU1_SB_DQS_DN<8>")
	)
	(segment
		(start 140.658596 -209.43951)
		(end 140.534136 -209.31505)
		(width 0.20066)
		(layer "F.Cu")
		(net "M_E_CPU1_SB_DQS_DN<8>")
	)
	(segment
		(start 140.534136 -211.185506)
		(end 140.534136 -211.147406)
		(width 0.1524)
		(layer "F.Cu")
		(net "M_E_CPU1_SB_DQS_DN<8>")
	)
	(segment
		(start 140.658596 -210.04149)
		(end 140.658596 -209.43951)
		(width 0.20066)
		(layer "F.Cu")
		(net "M_E_CPU1_SB_DQS_DN<8>")
	)
	(segment
		(start 155.085034 -199.827896)
		(end 155.209494 -199.703436)
		(width 0.20066)
		(layer "F.Cu")
		(net "M_E_CPU1_SB_DQS_DN<8>")
	)
	(segment
		(start 139.742926 -228.003608)
		(end 140.297154 -227.44938)
		(width 0.088646)
		(layer "F.Cu")
		(net "M_E_CPU1_SB_DQS_DN<8>")
	)
	(segment
		(start 155.621228 -199.703436)
		(end 156.96311 -199.14743)
		(width 0.20066)
		(layer "F.Cu")
		(net "M_E_CPU1_SB_DQS_DN<8>")
	)
	(segment
		(start 149.537674 -199.703436)
		(end 149.999954 -199.703436)
		(width 0.20066)
		(layer "F.Cu")
		(net "M_E_CPU1_SB_DQS_DN<8>")
	)
	(segment
		(start 141.205712 -213.714838)
		(end 141.005814 -212.706458)
		(width 0.1524)
		(layer "F.Cu")
		(net "M_E_CPU1_SB_DQS_DN<8>")
	)
	(segment
		(start 165.34638 -199.441816)
		(end 165.340284 -199.447912)
		(width 0.1016)
		(layer "F.Cu")
		(net "M_E_CPU1_SB_DQS_DN<8>")
	)
	(segment
		(start 141.005814 -212.706458)
		(end 140.497306 -211.479892)
		(width 0.1524)
		(layer "F.Cu")
		(net "M_E_CPU1_SB_DQS_DN<8>")
	)
	(segment
		(start 168.461944 -199.166988)
		(end 167.971978 -199.166988)
		(width 0.20066)
		(layer "F.Cu")
		(net "M_E_CPU1_SB_DQS_DN<8>")
	)
	(segment
		(start 164.623496 -199.170544)
		(end 164.198554 -199.595486)
		(width 0.20066)
		(layer "F.Cu")
		(net "M_E_CPU1_SB_DQS_DN<8>")
	)
	(segment
		(start 153.632154 -199.827896)
		(end 153.756614 -199.703436)
		(width 0.20066)
		(layer "F.Cu")
		(net "M_E_CPU1_SB_DQS_DN<8>")
	)
	(segment
		(start 147.870418 -201.370692)
		(end 148.295868 -200.945242)
		(width 0.20066)
		(layer "F.Cu")
		(net "M_E_CPU1_SB_DQS_DN<8>")
	)
	(segment
		(start 157.796484 -199.462644)
		(end 157.817566 -199.441562)
		(width 0.1016)
		(layer "F.Cu")
		(net "M_E_CPU1_SB_DQS_DN<8>")
	)
	(segment
		(start 148.295868 -200.945242)
		(end 148.47189 -200.945242)
		(width 0.20066)
		(layer "F.Cu")
		(net "M_E_CPU1_SB_DQS_DN<8>")
	)
	(segment
		(start 162.13582 -199.595232)
		(end 162.407346 -199.866758)
		(width 0.20066)
		(layer "F.Cu")
		(net "M_E_CPU1_SB_DQS_DN<8>")
	)
	(segment
		(start 146.133566 -202.734672)
		(end 146.769836 -202.471274)
		(width 0.20066)
		(layer "F.Cu")
		(net "M_E_CPU1_SB_DQS_DN<8>")
	)
	(segment
		(start 141.205712 -226.586034)
		(end 141.205712 -213.714838)
		(width 0.1524)
		(layer "F.Cu")
		(net "M_E_CPU1_SB_DQS_DN<8>")
	)
	(segment
		(start 142.548102 -204.583284)
		(end 142.973552 -204.157834)
		(width 0.20066)
		(layer "F.Cu")
		(net "M_E_CPU1_SB_DQS_DN<8>")
	)
	(segment
		(start 140.297154 -227.44938)
		(end 140.342366 -227.44938)
		(width 0.088646)
		(layer "F.Cu")
		(net "M_E_CPU1_SB_DQS_DN<8>")
	)
	(segment
		(start 144.918684 -202.734672)
		(end 146.133566 -202.734672)
		(width 0.20066)
		(layer "F.Cu")
		(net "M_E_CPU1_SB_DQS_DN<8>")
	)
	(segment
		(start 141.70152 -205.429866)
		(end 141.946122 -205.185264)
		(width 0.20066)
		(layer "F.Cu")
		(net "M_E_CPU1_SB_DQS_DN<8>")
	)
	(segment
		(start 148.897848 -200.343262)
		(end 149.537674 -199.703436)
		(width 0.20066)
		(layer "F.Cu")
		(net "M_E_CPU1_SB_DQS_DN<8>")
	)
	(segment
		(start 141.276832 -206.455264)
		(end 141.70152 -205.429866)
		(width 0.20066)
		(layer "F.Cu")
		(net "M_E_CPU1_SB_DQS_DN<8>")
	)
	(segment
		(start 140.95095 -207.241648)
		(end 141.11351 -207.174338)
		(width 0.20066)
		(layer "F.Cu")
		(net "M_E_CPU1_SB_DQS_DN<8>")
	)
	(segment
		(start 148.47189 -200.945242)
		(end 148.897848 -200.519284)
		(width 0.20066)
		(layer "F.Cu")
		(net "M_E_CPU1_SB_DQS_DN<8>")
	)
	(segment
		(start 141.946122 -205.185264)
		(end 142.122144 -205.185264)
		(width 0.20066)
		(layer "F.Cu")
		(net "M_E_CPU1_SB_DQS_DN<8>")
	)
	(segment
		(start 165.023292 -199.447912)
		(end 164.745924 -199.170544)
		(width 0.20066)
		(layer "F.Cu")
		(net "M_E_CPU1_SB_DQS_DN<8>")
	)
	(segment
		(start 167.971978 -199.166988)
		(end 167.686228 -199.452738)
		(width 0.20066)
		(layer "F.Cu")
		(net "M_E_CPU1_SB_DQS_DN<8>")
	)
	(segment
		(start 164.198554 -199.595486)
		(end 163.715192 -199.595486)
		(width 0.20066)
		(layer "F.Cu")
		(net "M_E_CPU1_SB_DQS_DN<8>")
	)
	(segment
		(start 146.769836 -202.471274)
		(end 147.268438 -201.972672)
		(width 0.20066)
		(layer "F.Cu")
		(net "M_E_CPU1_SB_DQS_DN<8>")
	)
	(segment
		(start 159.806132 -199.441562)
		(end 159.823658 -199.459088)
		(width 0.1016)
		(layer "F.Cu")
		(net "M_E_CPU1_SB_DQS_DN<8>")
	)
	(segment
		(start 162.407346 -199.866758)
		(end 162.913314 -199.866758)
		(width 0.20066)
		(layer "F.Cu")
		(net "M_E_CPU1_SB_DQS_DN<8>")
	)
	(segment
		(start 157.791658 -199.462644)
		(end 157.796484 -199.462644)
		(width 0.101854)
		(layer "F.Cu")
		(net "M_E_CPU1_SB_DQS_DN<8>")
	)
	(segment
		(start 142.973552 -204.157834)
		(end 143.149574 -204.157834)
		(width 0.20066)
		(layer "F.Cu")
		(net "M_E_CPU1_SB_DQS_DN<8>")
	)
	(segment
		(start 160.900872 -199.196198)
		(end 161.863532 -199.595232)
		(width 0.20066)
		(layer "F.Cu")
		(net "M_E_CPU1_SB_DQS_DN<8>")
	)
	(segment
		(start 152.303734 -199.703436)
		(end 152.905714 -199.703436)
		(width 0.20066)
		(layer "F.Cu")
		(net "M_E_CPU1_SB_DQS_DN<8>")
	)
	(segment
		(start 167.356536 -199.441816)
		(end 165.34638 -199.441816)
		(width 0.1016)
		(layer "F.Cu")
		(net "M_E_CPU1_SB_DQS_DN<8>")
	)
	(segment
		(start 140.342366 -227.44938)
		(end 140.35786 -227.433886)
		(width 0.088646)
		(layer "F.Cu")
		(net "M_E_CPU1_SB_DQS_DN<8>")
	)
	(segment
		(start 153.756614 -199.703436)
		(end 154.358594 -199.703436)
		(width 0.20066)
		(layer "F.Cu")
		(net "M_E_CPU1_SB_DQS_DN<8>")
	)
	(segment
		(start 149.999954 -199.703436)
		(end 150.124414 -199.827896)
		(width 0.20066)
		(layer "F.Cu")
		(net "M_E_CPU1_SB_DQS_DN<8>")
	)
	(segment
		(start 152.905714 -199.703436)
		(end 153.030174 -199.827896)
		(width 0.20066)
		(layer "F.Cu")
		(net "M_E_CPU1_SB_DQS_DN<8>")
	)
	(segment
		(start 170.457114 -199.866758)
		(end 169.953432 -199.866758)
		(width 0.20066)
		(layer "F.Cu")
		(net "M_E_CPU1_SB_DQS_DN<8>")
	)
	(segment
		(start 165.335458 -199.447912)
		(end 165.023292 -199.447912)
		(width 0.20066)
		(layer "F.Cu")
		(net "M_E_CPU1_SB_DQS_DN<8>")
	)
	(segment
		(start 140.497306 -211.479892)
		(end 140.497306 -211.222336)
		(width 0.1524)
		(layer "F.Cu")
		(net "M_E_CPU1_SB_DQS_DN<8>")
	)
	(segment
		(start 169.699178 -199.612504)
		(end 168.90746 -199.612504)
		(width 0.20066)
		(layer "F.Cu")
		(net "M_E_CPU1_SB_DQS_DN<8>")
	)
	(segment
		(start 160.411414 -199.196198)
		(end 160.900872 -199.196198)
		(width 0.20066)
		(layer "F.Cu")
		(net "M_E_CPU1_SB_DQS_DN<8>")
	)
	(segment
		(start 140.534136 -208.938368)
		(end 140.798804 -207.608932)
		(width 0.20066)
		(layer "F.Cu")
		(net "M_E_CPU1_SB_DQS_DN<8>")
	)
	(segment
		(start 147.44446 -201.972672)
		(end 147.870418 -201.546714)
		(width 0.20066)
		(layer "F.Cu")
		(net "M_E_CPU1_SB_DQS_DN<8>")
	)
	(segment
		(start 168.90746 -199.612504)
		(end 168.461944 -199.166988)
		(width 0.20066)
		(layer "F.Cu")
		(net "M_E_CPU1_SB_DQS_DN<8>")
	)
	(segment
		(start 139.073128 -228.003608)
		(end 139.742926 -228.003608)
		(width 0.088646)
		(layer "F.Cu")
		(net "M_E_CPU1_SB_DQS_DN<8>")
	)
	(segment
		(start 141.344142 -206.617824)
		(end 141.276832 -206.455264)
		(width 0.20066)
		(layer "F.Cu")
		(net "M_E_CPU1_SB_DQS_DN<8>")
	)
	(segment
		(start 164.745924 -199.170544)
		(end 164.623496 -199.170544)
		(width 0.20066)
		(layer "F.Cu")
		(net "M_E_CPU1_SB_DQS_DN<8>")
	)
	(segment
		(start 142.122144 -205.185264)
		(end 142.548102 -204.759306)
		(width 0.20066)
		(layer "F.Cu")
		(net "M_E_CPU1_SB_DQS_DN<8>")
	)
	(segment
		(start 141.11351 -207.174338)
		(end 141.344142 -206.617824)
		(width 0.20066)
		(layer "F.Cu")
		(net "M_E_CPU1_SB_DQS_DN<8>")
	)
	(segment
		(start 167.686228 -199.452738)
		(end 167.367458 -199.452738)
		(width 0.20066)
		(layer "F.Cu")
		(net "M_E_CPU1_SB_DQS_DN<8>")
	)
	(segment
		(start 143.575532 -203.731876)
		(end 143.575532 -203.555854)
		(width 0.20066)
		(layer "F.Cu")
		(net "M_E_CPU1_SB_DQS_DN<8>")
	)
	(segment
		(start 160.148524 -199.459088)
		(end 160.411414 -199.196198)
		(width 0.20066)
		(layer "F.Cu")
		(net "M_E_CPU1_SB_DQS_DN<8>")
	)
	(segment
		(start 150.850854 -199.703436)
		(end 151.452834 -199.703436)
		(width 0.20066)
		(layer "F.Cu")
		(net "M_E_CPU1_SB_DQS_DN<8>")
	)
	(segment
		(start 154.483054 -199.827896)
		(end 155.085034 -199.827896)
		(width 0.20066)
		(layer "F.Cu")
		(net "M_E_CPU1_SB_DQS_DN<8>")
	)
	(segment
		(start 140.534136 -211.147406)
		(end 140.534136 -210.16595)
		(width 0.20066)
		(layer "F.Cu")
		(net "M_E_CPU1_SB_DQS_DN<8>")
	)
	(segment
		(start 140.497306 -211.222336)
		(end 140.534136 -211.185506)
		(width 0.1524)
		(layer "F.Cu")
		(net "M_E_CPU1_SB_DQS_DN<8>")
	)
	(segment
		(start 151.452834 -199.703436)
		(end 151.577294 -199.827896)
		(width 0.20066)
		(layer "F.Cu")
		(net "M_E_CPU1_SB_DQS_DN<8>")
	)
	(segment
		(start 140.798804 -207.608932)
		(end 140.95095 -207.241648)
		(width 0.20066)
		(layer "F.Cu")
		(net "M_E_CPU1_SB_DQS_DN<8>")
	)
	(segment
		(start 140.534136 -209.31505)
		(end 140.534136 -208.938368)
		(width 0.20066)
		(layer "F.Cu")
		(net "M_E_CPU1_SB_DQS_DN<8>")
	)
	(segment
		(start 165.340284 -199.447912)
		(end 165.335458 -199.447912)
		(width 0.101854)
		(layer "F.Cu")
		(net "M_E_CPU1_SB_DQS_DN<8>")
	)
	(segment
		(start 152.179274 -199.827896)
		(end 152.303734 -199.703436)
		(width 0.20066)
		(layer "F.Cu")
		(net "M_E_CPU1_SB_DQS_DN<8>")
	)
	(segment
		(start 155.209494 -199.703436)
		(end 155.621228 -199.703436)
		(width 0.20066)
		(layer "F.Cu")
		(net "M_E_CPU1_SB_DQS_DN<8>")
	)
	(segment
		(start 148.897848 -200.519284)
		(end 148.897848 -200.343262)
		(width 0.20066)
		(layer "F.Cu")
		(net "M_E_CPU1_SB_DQS_DN<8>")
	)
	(segment
		(start 159.823658 -199.459088)
		(end 160.148524 -199.459088)
		(width 0.20066)
		(layer "F.Cu")
		(net "M_E_CPU1_SB_DQS_DN<8>")
	)
	(segment
		(start 169.953432 -199.866758)
		(end 169.699178 -199.612504)
		(width 0.20066)
		(layer "F.Cu")
		(net "M_E_CPU1_SB_DQS_DN<8>")
	)
	(segment
		(start 157.817566 -199.441562)
		(end 159.806132 -199.441562)
		(width 0.1016)
		(layer "F.Cu")
		(net "M_E_CPU1_SB_DQS_DN<8>")
	)
	(segment
		(start 163.715192 -199.595486)
		(end 163.44392 -199.866758)
		(width 0.20066)
		(layer "F.Cu")
		(net "M_E_CPU1_SB_DQS_DN<8>")
	)
	(segment
		(start 153.030174 -199.827896)
		(end 153.632154 -199.827896)
		(width 0.20066)
		(layer "F.Cu")
		(net "M_E_CPU1_SB_DQS_DN<8>")
	)
	(segment
		(start 161.863532 -199.595232)
		(end 162.13582 -199.595232)
		(width 0.20066)
		(layer "F.Cu")
		(net "M_E_CPU1_SB_DQS_DN<8>")
	)
	(segment
		(start 147.268438 -201.972672)
		(end 147.44446 -201.972672)
		(width 0.20066)
		(layer "F.Cu")
		(net "M_E_CPU1_SB_DQS_DN<8>")
	)
	(segment
		(start 143.575532 -203.555854)
		(end 144.027652 -203.103734)
		(width 0.20066)
		(layer "F.Cu")
		(net "M_E_CPU1_SB_DQS_DN<8>")
	)
	(segment
		(start 151.577294 -199.827896)
		(end 152.179274 -199.827896)
		(width 0.20066)
		(layer "F.Cu")
		(net "M_E_CPU1_SB_DQS_DN<8>")
	)
	(segment
		(start 142.548102 -204.759306)
		(end 142.548102 -204.583284)
		(width 0.20066)
		(layer "F.Cu")
		(net "M_E_CPU1_SB_DQS_DN<8>")
	)
	(segment
		(start 144.027652 -203.103734)
		(end 144.918684 -202.734672)
		(width 0.20066)
		(layer "F.Cu")
		(net "M_E_CPU1_SB_DQS_DN<8>")
	)
	(segment
		(start 150.726394 -199.827896)
		(end 150.850854 -199.703436)
		(width 0.20066)
		(layer "F.Cu")
		(net "M_E_CPU1_SB_DQS_DN<8>")
	)
	(segment
		(start 143.149574 -204.157834)
		(end 143.575532 -203.731876)
		(width 0.20066)
		(layer "F.Cu")
		(net "M_E_CPU1_SB_DQS_DN<8>")
	)
	(segment
		(start 157.19806 -199.14743)
		(end 157.513274 -199.462644)
		(width 0.20066)
		(layer "F.Cu")
		(net "M_E_CPU1_SB_DQS_DN<8>")
	)
	(segment
		(start 150.124414 -199.827896)
		(end 150.726394 -199.827896)
		(width 0.20066)
		(layer "F.Cu")
		(net "M_E_CPU1_SB_DQS_DN<8>")
	)
	(segment
		(start 167.367458 -199.452738)
		(end 167.356536 -199.441816)
		(width 0.1016)
		(layer "F.Cu")
		(net "M_E_CPU1_SB_DQS_DN<8>")
	)
	(segment
		(start 157.513274 -199.462644)
		(end 157.791658 -199.462644)
		(width 0.20066)
		(layer "F.Cu")
		(net "M_E_CPU1_SB_DQS_DN<8>")
	)
	(segment
		(start 140.534136 -210.16595)
		(end 140.658596 -210.04149)
		(width 0.20066)
		(layer "F.Cu")
		(net "M_E_CPU1_SB_DQS_DN<8>")
	)
	(segment
		(start 163.44392 -199.866758)
		(end 162.913314 -199.866758)
		(width 0.20066)
		(layer "F.Cu")
		(net "M_E_CPU1_SB_DQS_DN<8>")
	)
	(segment
		(start 138.896344 -228.179884)
		(end 139.073128 -228.003608)
		(width 0.088646)
		(layer "F.Cu")
		(net "M_E_CPU1_SB_DQS_DN<8>")
	)
	(segment
		(start 140.35786 -227.433886)
		(end 141.205712 -226.586034)
		(width 0.1524)
		(layer "F.Cu")
		(net "M_E_CPU1_SB_DQS_DN<8>")
	)
	(segment
		(start 154.358594 -199.703436)
		(end 154.483054 -199.827896)
		(width 0.20066)
		(layer "F.Cu")
		(net "M_E_CPU1_SB_DQS_DN<8>")
	)
	(segment
		(start 147.870418 -201.546714)
		(end 147.870418 -201.370692)
		(width 0.20066)
		(layer "F.Cu")
		(net "M_E_CPU1_SB_DQS_DN<8>")
	)
	(arc
		(start 138.894312 -228.1809)
		(mid 138.895448 -228.180632)
		(end 138.896344 -228.179884)
		(width 0.088646)
		(layer "F.Cu")
		(net "M_E_CPU1_SB_DQS_DN<8>")
	)
	(segment
		(start 168.150794 -208.516728)
		(end 167.86606 -208.801462)
		(width 0.20066)
		(layer "F.Cu")
		(net "M_E_CPU1_SB_DQS_DN<7>")
	)
	(segment
		(start 157.798262 -208.791556)
		(end 158.1785 -208.791556)
		(width 0.101854)
		(layer "F.Cu")
		(net "M_E_CPU1_SB_DQS_DN<7>")
	)
	(segment
		(start 163.659312 -208.945226)
		(end 163.387786 -209.216752)
		(width 0.20066)
		(layer "F.Cu")
		(net "M_E_CPU1_SB_DQS_DN<7>")
	)
	(segment
		(start 148.680932 -212.830664)
		(end 149.10689 -212.404706)
		(width 0.20066)
		(layer "F.Cu")
		(net "M_E_CPU1_SB_DQS_DN<7>")
	)
	(segment
		(start 147.05203 -214.283544)
		(end 147.47748 -213.858094)
		(width 0.20066)
		(layer "F.Cu")
		(net "M_E_CPU1_SB_DQS_DN<7>")
	)
	(segment
		(start 168.67886 -208.516728)
		(end 168.150794 -208.516728)
		(width 0.20066)
		(layer "F.Cu")
		(net "M_E_CPU1_SB_DQS_DN<7>")
	)
	(segment
		(start 160.364678 -208.541874)
		(end 160.51784 -208.541874)
		(width 0.20066)
		(layer "F.Cu")
		(net "M_E_CPU1_SB_DQS_DN<7>")
	)
	(segment
		(start 156.35478 -208.571084)
		(end 156.47924 -208.446624)
		(width 0.20066)
		(layer "F.Cu")
		(net "M_E_CPU1_SB_DQS_DN<7>")
	)
	(segment
		(start 163.387786 -209.216752)
		(end 162.913314 -209.216752)
		(width 0.20066)
		(layer "F.Cu")
		(net "M_E_CPU1_SB_DQS_DN<7>")
	)
	(segment
		(start 167.357552 -208.791556)
		(end 167.050212 -208.791556)
		(width 0.1016)
		(layer "F.Cu")
		(net "M_E_CPU1_SB_DQS_DN<7>")
	)
	(segment
		(start 150.13432 -211.201254)
		(end 150.55977 -210.775804)
		(width 0.20066)
		(layer "F.Cu")
		(net "M_E_CPU1_SB_DQS_DN<7>")
	)
	(segment
		(start 149.53234 -211.803234)
		(end 149.708362 -211.803234)
		(width 0.20066)
		(layer "F.Cu")
		(net "M_E_CPU1_SB_DQS_DN<7>")
	)
	(segment
		(start 147.47748 -213.858094)
		(end 147.653502 -213.858094)
		(width 0.20066)
		(layer "F.Cu")
		(net "M_E_CPU1_SB_DQS_DN<7>")
	)
	(segment
		(start 166.650924 -208.791556)
		(end 165.467792 -208.791556)
		(width 0.1016)
		(layer "F.Cu")
		(net "M_E_CPU1_SB_DQS_DN<7>")
	)
	(segment
		(start 162.414712 -209.216752)
		(end 162.913314 -209.216752)
		(width 0.20066)
		(layer "F.Cu")
		(net "M_E_CPU1_SB_DQS_DN<7>")
	)
	(segment
		(start 151.16175 -210.173824)
		(end 151.5872 -209.748374)
		(width 0.20066)
		(layer "F.Cu")
		(net "M_E_CPU1_SB_DQS_DN<7>")
	)
	(segment
		(start 152.188926 -209.32267)
		(end 152.188926 -209.146648)
		(width 0.20066)
		(layer "F.Cu")
		(net "M_E_CPU1_SB_DQS_DN<7>")
	)
	(segment
		(start 146.450304 -214.885524)
		(end 146.626072 -214.885524)
		(width 0.20066)
		(layer "F.Cu")
		(net "M_E_CPU1_SB_DQS_DN<7>")
	)
	(segment
		(start 150.13432 -211.377276)
		(end 150.13432 -211.201254)
		(width 0.20066)
		(layer "F.Cu")
		(net "M_E_CPU1_SB_DQS_DN<7>")
	)
	(segment
		(start 149.10689 -212.404706)
		(end 149.10689 -212.228684)
		(width 0.20066)
		(layer "F.Cu")
		(net "M_E_CPU1_SB_DQS_DN<7>")
	)
	(segment
		(start 154.17546 -208.446624)
		(end 154.29992 -208.571084)
		(width 0.20066)
		(layer "F.Cu")
		(net "M_E_CPU1_SB_DQS_DN<7>")
	)
	(segment
		(start 145.547588 -215.78824)
		(end 145.574512 -215.761316)
		(width 0.1524)
		(layer "F.Cu")
		(net "M_E_CPU1_SB_DQS_DN<7>")
	)
	(segment
		(start 148.07946 -213.256114)
		(end 148.50491 -212.830664)
		(width 0.20066)
		(layer "F.Cu")
		(net "M_E_CPU1_SB_DQS_DN<7>")
	)
	(segment
		(start 152.529794 -208.80578)
		(end 153.39695 -208.446624)
		(width 0.20066)
		(layer "F.Cu")
		(net "M_E_CPU1_SB_DQS_DN<7>")
	)
	(segment
		(start 148.07946 -213.432136)
		(end 148.07946 -213.256114)
		(width 0.20066)
		(layer "F.Cu")
		(net "M_E_CPU1_SB_DQS_DN<7>")
	)
	(segment
		(start 157.174946 -208.446624)
		(end 157.526482 -208.79816)
		(width 0.20066)
		(layer "F.Cu")
		(net "M_E_CPU1_SB_DQS_DN<7>")
	)
	(segment
		(start 151.16175 -210.349846)
		(end 151.16175 -210.173824)
		(width 0.20066)
		(layer "F.Cu")
		(net "M_E_CPU1_SB_DQS_DN<7>")
	)
	(segment
		(start 150.55977 -210.775804)
		(end 150.735792 -210.775804)
		(width 0.20066)
		(layer "F.Cu")
		(net "M_E_CPU1_SB_DQS_DN<7>")
	)
	(segment
		(start 152.188926 -209.146648)
		(end 152.529794 -208.80578)
		(width 0.20066)
		(layer "F.Cu")
		(net "M_E_CPU1_SB_DQS_DN<7>")
	)
	(segment
		(start 138.983466 -232.885742)
		(end 140.42263 -232.885742)
		(width 0.088646)
		(layer "F.Cu")
		(net "M_E_CPU1_SB_DQS_DN<7>")
	)
	(segment
		(start 145.495772 -215.78824)
		(end 145.547588 -215.78824)
		(width 0.1524)
		(layer "F.Cu")
		(net "M_E_CPU1_SB_DQS_DN<7>")
	)
	(segment
		(start 151.5872 -209.748374)
		(end 151.763222 -209.748374)
		(width 0.20066)
		(layer "F.Cu")
		(net "M_E_CPU1_SB_DQS_DN<7>")
	)
	(segment
		(start 157.526482 -208.79816)
		(end 157.791658 -208.79816)
		(width 0.20066)
		(layer "F.Cu")
		(net "M_E_CPU1_SB_DQS_DN<7>")
	)
	(segment
		(start 149.10689 -212.228684)
		(end 149.53234 -211.803234)
		(width 0.20066)
		(layer "F.Cu")
		(net "M_E_CPU1_SB_DQS_DN<7>")
	)
	(segment
		(start 169.124376 -208.962244)
		(end 168.67886 -208.516728)
		(width 0.20066)
		(layer "F.Cu")
		(net "M_E_CPU1_SB_DQS_DN<7>")
	)
	(segment
		(start 157.791658 -208.79816)
		(end 157.798262 -208.791556)
		(width 0.101854)
		(layer "F.Cu")
		(net "M_E_CPU1_SB_DQS_DN<7>")
	)
	(segment
		(start 138.894312 -232.974896)
		(end 138.983466 -232.885742)
		(width 0.088646)
		(layer "F.Cu")
		(net "M_E_CPU1_SB_DQS_DN<7>")
	)
	(segment
		(start 145.117312 -228.236272)
		(end 145.117312 -216.1667)
		(width 0.1524)
		(layer "F.Cu")
		(net "M_E_CPU1_SB_DQS_DN<7>")
	)
	(segment
		(start 165.052502 -208.797398)
		(end 164.753544 -208.49844)
		(width 0.20066)
		(layer "F.Cu")
		(net "M_E_CPU1_SB_DQS_DN<7>")
	)
	(segment
		(start 153.39695 -208.446624)
		(end 154.17546 -208.446624)
		(width 0.20066)
		(layer "F.Cu")
		(net "M_E_CPU1_SB_DQS_DN<7>")
	)
	(segment
		(start 156.47924 -208.446624)
		(end 157.174946 -208.446624)
		(width 0.20066)
		(layer "F.Cu")
		(net "M_E_CPU1_SB_DQS_DN<7>")
	)
	(segment
		(start 155.7528 -208.571084)
		(end 156.35478 -208.571084)
		(width 0.20066)
		(layer "F.Cu")
		(net "M_E_CPU1_SB_DQS_DN<7>")
	)
	(segment
		(start 167.367458 -208.801462)
		(end 167.357552 -208.791556)
		(width 0.1016)
		(layer "F.Cu")
		(net "M_E_CPU1_SB_DQS_DN<7>")
	)
	(segment
		(start 170.457114 -209.216752)
		(end 169.989754 -209.216752)
		(width 0.20066)
		(layer "F.Cu")
		(net "M_E_CPU1_SB_DQS_DN<7>")
	)
	(segment
		(start 169.989754 -209.216752)
		(end 169.735246 -208.962244)
		(width 0.20066)
		(layer "F.Cu")
		(net "M_E_CPU1_SB_DQS_DN<7>")
	)
	(segment
		(start 159.816292 -208.806034)
		(end 159.823658 -208.806034)
		(width 0.101854)
		(layer "F.Cu")
		(net "M_E_CPU1_SB_DQS_DN<7>")
	)
	(segment
		(start 164.024818 -208.945226)
		(end 163.659312 -208.945226)
		(width 0.20066)
		(layer "F.Cu")
		(net "M_E_CPU1_SB_DQS_DN<7>")
	)
	(segment
		(start 148.50491 -212.830664)
		(end 148.680932 -212.830664)
		(width 0.20066)
		(layer "F.Cu")
		(net "M_E_CPU1_SB_DQS_DN<7>")
	)
	(segment
		(start 160.100518 -208.806034)
		(end 160.364678 -208.541874)
		(width 0.20066)
		(layer "F.Cu")
		(net "M_E_CPU1_SB_DQS_DN<7>")
	)
	(segment
		(start 155.02636 -208.446624)
		(end 155.62834 -208.446624)
		(width 0.20066)
		(layer "F.Cu")
		(net "M_E_CPU1_SB_DQS_DN<7>")
	)
	(segment
		(start 155.62834 -208.446624)
		(end 155.7528 -208.571084)
		(width 0.20066)
		(layer "F.Cu")
		(net "M_E_CPU1_SB_DQS_DN<7>")
	)
	(segment
		(start 154.9019 -208.571084)
		(end 155.02636 -208.446624)
		(width 0.20066)
		(layer "F.Cu")
		(net "M_E_CPU1_SB_DQS_DN<7>")
	)
	(segment
		(start 165.335458 -208.797398)
		(end 165.052502 -208.797398)
		(width 0.20066)
		(layer "F.Cu")
		(net "M_E_CPU1_SB_DQS_DN<7>")
	)
	(segment
		(start 147.653502 -213.858094)
		(end 148.07946 -213.432136)
		(width 0.20066)
		(layer "F.Cu")
		(net "M_E_CPU1_SB_DQS_DN<7>")
	)
	(segment
		(start 160.51784 -208.541874)
		(end 161.960052 -208.97977)
		(width 0.20066)
		(layer "F.Cu")
		(net "M_E_CPU1_SB_DQS_DN<7>")
	)
	(segment
		(start 165.467792 -208.791556)
		(end 165.342316 -208.791556)
		(width 0.101854)
		(layer "F.Cu")
		(net "M_E_CPU1_SB_DQS_DN<7>")
	)
	(segment
		(start 165.336474 -208.797398)
		(end 165.335458 -208.797398)
		(width 0.101854)
		(layer "F.Cu")
		(net "M_E_CPU1_SB_DQS_DN<7>")
	)
	(segment
		(start 145.117312 -216.1667)
		(end 145.495772 -215.78824)
		(width 0.1524)
		(layer "F.Cu")
		(net "M_E_CPU1_SB_DQS_DN<7>")
	)
	(segment
		(start 167.050212 -208.791556)
		(end 166.650924 -208.791556)
		(width 0.101854)
		(layer "F.Cu")
		(net "M_E_CPU1_SB_DQS_DN<7>")
	)
	(segment
		(start 146.626072 -214.885524)
		(end 147.05203 -214.459566)
		(width 0.20066)
		(layer "F.Cu")
		(net "M_E_CPU1_SB_DQS_DN<7>")
	)
	(segment
		(start 167.86606 -208.801462)
		(end 167.367458 -208.801462)
		(width 0.20066)
		(layer "F.Cu")
		(net "M_E_CPU1_SB_DQS_DN<7>")
	)
	(segment
		(start 138.894312 -233.064304)
		(end 138.894312 -232.974896)
		(width 0.088646)
		(layer "F.Cu")
		(net "M_E_CPU1_SB_DQS_DN<7>")
	)
	(segment
		(start 154.29992 -208.571084)
		(end 154.9019 -208.571084)
		(width 0.20066)
		(layer "F.Cu")
		(net "M_E_CPU1_SB_DQS_DN<7>")
	)
	(segment
		(start 145.574512 -215.761316)
		(end 146.450304 -214.885524)
		(width 0.20066)
		(layer "F.Cu")
		(net "M_E_CPU1_SB_DQS_DN<7>")
	)
	(segment
		(start 140.42263 -232.885742)
		(end 140.588238 -232.720134)
		(width 0.088646)
		(layer "F.Cu")
		(net "M_E_CPU1_SB_DQS_DN<7>")
	)
	(segment
		(start 158.1785 -208.791556)
		(end 159.801814 -208.791556)
		(width 0.1016)
		(layer "F.Cu")
		(net "M_E_CPU1_SB_DQS_DN<7>")
	)
	(segment
		(start 140.648944 -232.70464)
		(end 145.117312 -228.236272)
		(width 0.1524)
		(layer "F.Cu")
		(net "M_E_CPU1_SB_DQS_DN<7>")
	)
	(segment
		(start 147.05203 -214.459566)
		(end 147.05203 -214.283544)
		(width 0.20066)
		(layer "F.Cu")
		(net "M_E_CPU1_SB_DQS_DN<7>")
	)
	(segment
		(start 169.735246 -208.962244)
		(end 169.124376 -208.962244)
		(width 0.20066)
		(layer "F.Cu")
		(net "M_E_CPU1_SB_DQS_DN<7>")
	)
	(segment
		(start 159.801814 -208.791556)
		(end 159.816292 -208.806034)
		(width 0.1016)
		(layer "F.Cu")
		(net "M_E_CPU1_SB_DQS_DN<7>")
	)
	(segment
		(start 140.63345 -232.720134)
		(end 140.648944 -232.70464)
		(width 0.088646)
		(layer "F.Cu")
		(net "M_E_CPU1_SB_DQS_DN<7>")
	)
	(segment
		(start 151.763222 -209.748374)
		(end 152.188926 -209.32267)
		(width 0.20066)
		(layer "F.Cu")
		(net "M_E_CPU1_SB_DQS_DN<7>")
	)
	(segment
		(start 149.708362 -211.803234)
		(end 150.13432 -211.377276)
		(width 0.20066)
		(layer "F.Cu")
		(net "M_E_CPU1_SB_DQS_DN<7>")
	)
	(segment
		(start 164.753544 -208.49844)
		(end 164.471604 -208.49844)
		(width 0.20066)
		(layer "F.Cu")
		(net "M_E_CPU1_SB_DQS_DN<7>")
	)
	(segment
		(start 164.471604 -208.49844)
		(end 164.024818 -208.945226)
		(width 0.20066)
		(layer "F.Cu")
		(net "M_E_CPU1_SB_DQS_DN<7>")
	)
	(segment
		(start 159.823658 -208.806034)
		(end 160.100518 -208.806034)
		(width 0.20066)
		(layer "F.Cu")
		(net "M_E_CPU1_SB_DQS_DN<7>")
	)
	(segment
		(start 165.342316 -208.791556)
		(end 165.336474 -208.797398)
		(width 0.101854)
		(layer "F.Cu")
		(net "M_E_CPU1_SB_DQS_DN<7>")
	)
	(segment
		(start 161.960052 -208.97977)
		(end 162.17773 -208.97977)
		(width 0.20066)
		(layer "F.Cu")
		(net "M_E_CPU1_SB_DQS_DN<7>")
	)
	(segment
		(start 162.17773 -208.97977)
		(end 162.414712 -209.216752)
		(width 0.20066)
		(layer "F.Cu")
		(net "M_E_CPU1_SB_DQS_DN<7>")
	)
	(segment
		(start 150.735792 -210.775804)
		(end 151.16175 -210.349846)
		(width 0.20066)
		(layer "F.Cu")
		(net "M_E_CPU1_SB_DQS_DN<7>")
	)
	(segment
		(start 140.588238 -232.720134)
		(end 140.63345 -232.720134)
		(width 0.088646)
		(layer "F.Cu")
		(net "M_E_CPU1_SB_DQS_DN<7>")
	)
	(segment
		(start 152.983692 -223.245426)
		(end 153.108152 -223.120966)
		(width 0.20066)
		(layer "F.Cu")
		(net "M_E_CPU1_SB_DQS_DN<6>")
	)
	(segment
		(start 156.18079 -218.234514)
		(end 156.389578 -218.025726)
		(width 0.20066)
		(layer "F.Cu")
		(net "M_E_CPU1_SB_DQS_DN<6>")
	)
	(segment
		(start 152.558242 -224.49028)
		(end 152.983692 -224.06483)
		(width 0.20066)
		(layer "F.Cu")
		(net "M_E_CPU1_SB_DQS_DN<6>")
	)
	(segment
		(start 138.983212 -237.779814)
		(end 139.706604 -237.779814)
		(width 0.088646)
		(layer "F.Cu")
		(net "M_E_CPU1_SB_DQS_DN<6>")
	)
	(segment
		(start 153.87193 -220.543374)
		(end 154.29738 -220.117924)
		(width 0.20066)
		(layer "F.Cu")
		(net "M_E_CPU1_SB_DQS_DN<6>")
	)
	(segment
		(start 163.715192 -218.295474)
		(end 163.44392 -218.566746)
		(width 0.20066)
		(layer "F.Cu")
		(net "M_E_CPU1_SB_DQS_DN<6>")
	)
	(segment
		(start 168.461944 -217.866976)
		(end 167.971978 -217.866976)
		(width 0.20066)
		(layer "F.Cu")
		(net "M_E_CPU1_SB_DQS_DN<6>")
	)
	(segment
		(start 141.153896 -236.882686)
		(end 142.058898 -236.882686)
		(width 0.1524)
		(layer "F.Cu")
		(net "M_E_CPU1_SB_DQS_DN<6>")
	)
	(segment
		(start 152.132284 -225.09226)
		(end 152.558242 -224.666302)
		(width 0.20066)
		(layer "F.Cu")
		(net "M_E_CPU1_SB_DQS_DN<6>")
	)
	(segment
		(start 153.108152 -222.518986)
		(end 152.983692 -222.394526)
		(width 0.20066)
		(layer "F.Cu")
		(net "M_E_CPU1_SB_DQS_DN<6>")
	)
	(segment
		(start 151.956262 -225.09226)
		(end 152.132284 -225.09226)
		(width 0.20066)
		(layer "F.Cu")
		(net "M_E_CPU1_SB_DQS_DN<6>")
	)
	(segment
		(start 152.558242 -224.666302)
		(end 152.558242 -224.49028)
		(width 0.20066)
		(layer "F.Cu")
		(net "M_E_CPU1_SB_DQS_DN<6>")
	)
	(segment
		(start 154.89936 -219.691966)
		(end 154.89936 -219.516198)
		(width 0.20066)
		(layer "F.Cu")
		(net "M_E_CPU1_SB_DQS_DN<6>")
	)
	(segment
		(start 141.099794 -236.850682)
		(end 141.131798 -236.882686)
		(width 0.088646)
		(layer "F.Cu")
		(net "M_E_CPU1_SB_DQS_DN<6>")
	)
	(segment
		(start 152.983692 -224.06483)
		(end 152.983692 -223.245426)
		(width 0.20066)
		(layer "F.Cu")
		(net "M_E_CPU1_SB_DQS_DN<6>")
	)
	(segment
		(start 149.465538 -227.530406)
		(end 149.795484 -227.20046)
		(width 0.1524)
		(layer "F.Cu")
		(net "M_E_CPU1_SB_DQS_DN<6>")
	)
	(segment
		(start 167.367458 -218.152726)
		(end 167.356536 -218.141804)
		(width 0.1016)
		(layer "F.Cu")
		(net "M_E_CPU1_SB_DQS_DN<6>")
	)
	(segment
		(start 162.13582 -218.29522)
		(end 162.407346 -218.566746)
		(width 0.20066)
		(layer "F.Cu")
		(net "M_E_CPU1_SB_DQS_DN<6>")
	)
	(segment
		(start 141.131798 -236.882686)
		(end 141.153896 -236.882686)
		(width 0.088646)
		(layer "F.Cu")
		(net "M_E_CPU1_SB_DQS_DN<6>")
	)
	(segment
		(start 155.579064 -218.836494)
		(end 155.755086 -218.836494)
		(width 0.20066)
		(layer "F.Cu")
		(net "M_E_CPU1_SB_DQS_DN<6>")
	)
	(segment
		(start 151.104854 -226.11969)
		(end 151.530812 -225.693732)
		(width 0.20066)
		(layer "F.Cu")
		(net "M_E_CPU1_SB_DQS_DN<6>")
	)
	(segment
		(start 156.874464 -217.619072)
		(end 157.075124 -217.819732)
		(width 0.20066)
		(layer "F.Cu")
		(net "M_E_CPU1_SB_DQS_DN<6>")
	)
	(segment
		(start 167.356536 -218.141804)
		(end 165.34638 -218.141804)
		(width 0.1016)
		(layer "F.Cu")
		(net "M_E_CPU1_SB_DQS_DN<6>")
	)
	(segment
		(start 149.874986 -227.173536)
		(end 150.928832 -226.11969)
		(width 0.20066)
		(layer "F.Cu")
		(net "M_E_CPU1_SB_DQS_DN<6>")
	)
	(segment
		(start 151.530812 -225.693732)
		(end 151.530812 -225.51771)
		(width 0.20066)
		(layer "F.Cu")
		(net "M_E_CPU1_SB_DQS_DN<6>")
	)
	(segment
		(start 138.894312 -237.947454)
		(end 138.894312 -237.868714)
		(width 0.088646)
		(layer "F.Cu")
		(net "M_E_CPU1_SB_DQS_DN<6>")
	)
	(segment
		(start 156.590492 -217.619072)
		(end 156.874464 -217.619072)
		(width 0.20066)
		(layer "F.Cu")
		(net "M_E_CPU1_SB_DQS_DN<6>")
	)
	(segment
		(start 154.89936 -219.516198)
		(end 155.579064 -218.836494)
		(width 0.20066)
		(layer "F.Cu")
		(net "M_E_CPU1_SB_DQS_DN<6>")
	)
	(segment
		(start 162.407346 -218.566746)
		(end 162.913314 -218.566746)
		(width 0.20066)
		(layer "F.Cu")
		(net "M_E_CPU1_SB_DQS_DN<6>")
	)
	(segment
		(start 139.706604 -237.779814)
		(end 140.635736 -236.850682)
		(width 0.088646)
		(layer "F.Cu")
		(net "M_E_CPU1_SB_DQS_DN<6>")
	)
	(segment
		(start 169.953432 -218.566746)
		(end 169.699178 -218.312492)
		(width 0.20066)
		(layer "F.Cu")
		(net "M_E_CPU1_SB_DQS_DN<6>")
	)
	(segment
		(start 165.340284 -218.1479)
		(end 165.335458 -218.1479)
		(width 0.101854)
		(layer "F.Cu")
		(net "M_E_CPU1_SB_DQS_DN<6>")
	)
	(segment
		(start 164.414962 -218.079066)
		(end 163.892484 -218.295474)
		(width 0.20066)
		(layer "F.Cu")
		(net "M_E_CPU1_SB_DQS_DN<6>")
	)
	(segment
		(start 153.445972 -221.145354)
		(end 153.87193 -220.719396)
		(width 0.20066)
		(layer "F.Cu")
		(net "M_E_CPU1_SB_DQS_DN<6>")
	)
	(segment
		(start 165.335458 -218.1479)
		(end 165.023292 -218.1479)
		(width 0.20066)
		(layer "F.Cu")
		(net "M_E_CPU1_SB_DQS_DN<6>")
	)
	(segment
		(start 164.745924 -217.870532)
		(end 164.623496 -217.870532)
		(width 0.20066)
		(layer "F.Cu")
		(net "M_E_CPU1_SB_DQS_DN<6>")
	)
	(segment
		(start 156.18079 -218.41079)
		(end 156.18079 -218.234514)
		(width 0.20066)
		(layer "F.Cu")
		(net "M_E_CPU1_SB_DQS_DN<6>")
	)
	(segment
		(start 153.26995 -221.145354)
		(end 153.445972 -221.145354)
		(width 0.20066)
		(layer "F.Cu")
		(net "M_E_CPU1_SB_DQS_DN<6>")
	)
	(segment
		(start 170.457114 -218.566746)
		(end 169.953432 -218.566746)
		(width 0.20066)
		(layer "F.Cu")
		(net "M_E_CPU1_SB_DQS_DN<6>")
	)
	(segment
		(start 138.894312 -237.868714)
		(end 138.983212 -237.779814)
		(width 0.088646)
		(layer "F.Cu")
		(net "M_E_CPU1_SB_DQS_DN<6>")
	)
	(segment
		(start 159.823658 -218.14155)
		(end 159.997648 -218.14155)
		(width 0.20066)
		(layer "F.Cu")
		(net "M_E_CPU1_SB_DQS_DN<6>")
	)
	(segment
		(start 153.87193 -220.719396)
		(end 153.87193 -220.543374)
		(width 0.20066)
		(layer "F.Cu")
		(net "M_E_CPU1_SB_DQS_DN<6>")
	)
	(segment
		(start 142.058898 -236.882686)
		(end 149.028912 -229.912672)
		(width 0.1524)
		(layer "F.Cu")
		(net "M_E_CPU1_SB_DQS_DN<6>")
	)
	(segment
		(start 157.075124 -217.93454)
		(end 157.3022 -218.161616)
		(width 0.20066)
		(layer "F.Cu")
		(net "M_E_CPU1_SB_DQS_DN<6>")
	)
	(segment
		(start 149.848062 -227.20046)
		(end 149.874986 -227.173536)
		(width 0.1524)
		(layer "F.Cu")
		(net "M_E_CPU1_SB_DQS_DN<6>")
	)
	(segment
		(start 149.795484 -227.20046)
		(end 149.848062 -227.20046)
		(width 0.1524)
		(layer "F.Cu")
		(net "M_E_CPU1_SB_DQS_DN<6>")
	)
	(segment
		(start 163.44392 -218.566746)
		(end 162.913314 -218.566746)
		(width 0.20066)
		(layer "F.Cu")
		(net "M_E_CPU1_SB_DQS_DN<6>")
	)
	(segment
		(start 159.997648 -218.14155)
		(end 160.00984 -218.153742)
		(width 0.20066)
		(layer "F.Cu")
		(net "M_E_CPU1_SB_DQS_DN<6>")
	)
	(segment
		(start 152.983692 -221.431612)
		(end 153.26995 -221.145354)
		(width 0.20066)
		(layer "F.Cu")
		(net "M_E_CPU1_SB_DQS_DN<6>")
	)
	(segment
		(start 157.075124 -217.819732)
		(end 157.075124 -217.93454)
		(width 0.20066)
		(layer "F.Cu")
		(net "M_E_CPU1_SB_DQS_DN<6>")
	)
	(segment
		(start 165.023292 -218.1479)
		(end 164.745924 -217.870532)
		(width 0.20066)
		(layer "F.Cu")
		(net "M_E_CPU1_SB_DQS_DN<6>")
	)
	(segment
		(start 149.028912 -228.58476)
		(end 149.465538 -227.530406)
		(width 0.1524)
		(layer "F.Cu")
		(net "M_E_CPU1_SB_DQS_DN<6>")
	)
	(segment
		(start 140.635736 -236.850682)
		(end 141.099794 -236.850682)
		(width 0.088646)
		(layer "F.Cu")
		(net "M_E_CPU1_SB_DQS_DN<6>")
	)
	(segment
		(start 160.00984 -218.153742)
		(end 160.362138 -218.153742)
		(width 0.20066)
		(layer "F.Cu")
		(net "M_E_CPU1_SB_DQS_DN<6>")
	)
	(segment
		(start 152.983692 -222.394526)
		(end 152.983692 -221.431612)
		(width 0.20066)
		(layer "F.Cu")
		(net "M_E_CPU1_SB_DQS_DN<6>")
	)
	(segment
		(start 154.473402 -220.117924)
		(end 154.89936 -219.691966)
		(width 0.20066)
		(layer "F.Cu")
		(net "M_E_CPU1_SB_DQS_DN<6>")
	)
	(segment
		(start 151.530812 -225.51771)
		(end 151.956262 -225.09226)
		(width 0.20066)
		(layer "F.Cu")
		(net "M_E_CPU1_SB_DQS_DN<6>")
	)
	(segment
		(start 157.811724 -218.14155)
		(end 159.823658 -218.14155)
		(width 0.1016)
		(layer "F.Cu")
		(net "M_E_CPU1_SB_DQS_DN<6>")
	)
	(segment
		(start 156.389578 -217.819986)
		(end 156.590492 -217.619072)
		(width 0.20066)
		(layer "F.Cu")
		(net "M_E_CPU1_SB_DQS_DN<6>")
	)
	(segment
		(start 165.34638 -218.141804)
		(end 165.340284 -218.1479)
		(width 0.1016)
		(layer "F.Cu")
		(net "M_E_CPU1_SB_DQS_DN<6>")
	)
	(segment
		(start 167.971978 -217.866976)
		(end 167.686228 -218.152726)
		(width 0.20066)
		(layer "F.Cu")
		(net "M_E_CPU1_SB_DQS_DN<6>")
	)
	(segment
		(start 160.900872 -217.896186)
		(end 161.863532 -218.29522)
		(width 0.20066)
		(layer "F.Cu")
		(net "M_E_CPU1_SB_DQS_DN<6>")
	)
	(segment
		(start 155.755086 -218.836494)
		(end 156.18079 -218.41079)
		(width 0.20066)
		(layer "F.Cu")
		(net "M_E_CPU1_SB_DQS_DN<6>")
	)
	(segment
		(start 168.90746 -218.312492)
		(end 168.461944 -217.866976)
		(width 0.20066)
		(layer "F.Cu")
		(net "M_E_CPU1_SB_DQS_DN<6>")
	)
	(segment
		(start 167.686228 -218.152726)
		(end 167.367458 -218.152726)
		(width 0.20066)
		(layer "F.Cu")
		(net "M_E_CPU1_SB_DQS_DN<6>")
	)
	(segment
		(start 161.863532 -218.29522)
		(end 162.13582 -218.29522)
		(width 0.20066)
		(layer "F.Cu")
		(net "M_E_CPU1_SB_DQS_DN<6>")
	)
	(segment
		(start 154.29738 -220.117924)
		(end 154.473402 -220.117924)
		(width 0.20066)
		(layer "F.Cu")
		(net "M_E_CPU1_SB_DQS_DN<6>")
	)
	(segment
		(start 149.028912 -229.912672)
		(end 149.028912 -228.58476)
		(width 0.1524)
		(layer "F.Cu")
		(net "M_E_CPU1_SB_DQS_DN<6>")
	)
	(segment
		(start 163.892484 -218.295474)
		(end 163.715192 -218.295474)
		(width 0.20066)
		(layer "F.Cu")
		(net "M_E_CPU1_SB_DQS_DN<6>")
	)
	(segment
		(start 150.928832 -226.11969)
		(end 151.104854 -226.11969)
		(width 0.20066)
		(layer "F.Cu")
		(net "M_E_CPU1_SB_DQS_DN<6>")
	)
	(segment
		(start 157.791658 -218.161616)
		(end 157.811724 -218.14155)
		(width 0.101854)
		(layer "F.Cu")
		(net "M_E_CPU1_SB_DQS_DN<6>")
	)
	(segment
		(start 160.362138 -218.153742)
		(end 160.619694 -217.896186)
		(width 0.20066)
		(layer "F.Cu")
		(net "M_E_CPU1_SB_DQS_DN<6>")
	)
	(segment
		(start 160.619694 -217.896186)
		(end 160.900872 -217.896186)
		(width 0.20066)
		(layer "F.Cu")
		(net "M_E_CPU1_SB_DQS_DN<6>")
	)
	(segment
		(start 156.389578 -218.025726)
		(end 156.389578 -217.819986)
		(width 0.20066)
		(layer "F.Cu")
		(net "M_E_CPU1_SB_DQS_DN<6>")
	)
	(segment
		(start 164.623496 -217.870532)
		(end 164.414962 -218.079066)
		(width 0.20066)
		(layer "F.Cu")
		(net "M_E_CPU1_SB_DQS_DN<6>")
	)
	(segment
		(start 153.108152 -223.120966)
		(end 153.108152 -222.518986)
		(width 0.20066)
		(layer "F.Cu")
		(net "M_E_CPU1_SB_DQS_DN<6>")
	)
	(segment
		(start 157.3022 -218.161616)
		(end 157.791658 -218.161616)
		(width 0.20066)
		(layer "F.Cu")
		(net "M_E_CPU1_SB_DQS_DN<6>")
	)
	(segment
		(start 169.699178 -218.312492)
		(end 168.90746 -218.312492)
		(width 0.20066)
		(layer "F.Cu")
		(net "M_E_CPU1_SB_DQS_DN<6>")
	)
	(segment
		(start 165.34638 -227.491798)
		(end 165.340284 -227.497894)
		(width 0.1016)
		(layer "F.Cu")
		(net "M_E_CPU1_SB_DQS_DN<5>")
	)
	(segment
		(start 163.44392 -227.91674)
		(end 162.913314 -227.91674)
		(width 0.20066)
		(layer "F.Cu")
		(net "M_E_CPU1_SB_DQS_DN<5>")
	)
	(segment
		(start 135.605266 -235.506006)
		(end 135.605266 -234.970066)
		(width 0.20066)
		(layer "F.Cu")
		(net "M_E_CPU1_SB_DQS_DN<5>")
	)
	(segment
		(start 165.340284 -227.497894)
		(end 165.335458 -227.497894)
		(width 0.101854)
		(layer "F.Cu")
		(net "M_E_CPU1_SB_DQS_DN<5>")
	)
	(segment
		(start 165.023292 -227.497894)
		(end 164.745924 -227.220526)
		(width 0.20066)
		(layer "F.Cu")
		(net "M_E_CPU1_SB_DQS_DN<5>")
	)
	(segment
		(start 167.356536 -227.491798)
		(end 165.34638 -227.491798)
		(width 0.1016)
		(layer "F.Cu")
		(net "M_E_CPU1_SB_DQS_DN<5>")
	)
	(segment
		(start 164.623496 -227.220526)
		(end 164.198554 -227.645468)
		(width 0.20066)
		(layer "F.Cu")
		(net "M_E_CPU1_SB_DQS_DN<5>")
	)
	(segment
		(start 170.457114 -227.91674)
		(end 169.953432 -227.91674)
		(width 0.20066)
		(layer "F.Cu")
		(net "M_E_CPU1_SB_DQS_DN<5>")
	)
	(segment
		(start 165.335458 -227.497894)
		(end 165.023292 -227.497894)
		(width 0.20066)
		(layer "F.Cu")
		(net "M_E_CPU1_SB_DQS_DN<5>")
	)
	(segment
		(start 169.699178 -227.662486)
		(end 168.90746 -227.662486)
		(width 0.20066)
		(layer "F.Cu")
		(net "M_E_CPU1_SB_DQS_DN<5>")
	)
	(segment
		(start 168.90746 -227.662486)
		(end 168.461944 -227.21697)
		(width 0.20066)
		(layer "F.Cu")
		(net "M_E_CPU1_SB_DQS_DN<5>")
	)
	(segment
		(start 164.198554 -227.645468)
		(end 163.715192 -227.645468)
		(width 0.20066)
		(layer "F.Cu")
		(net "M_E_CPU1_SB_DQS_DN<5>")
	)
	(segment
		(start 169.953432 -227.91674)
		(end 169.699178 -227.662486)
		(width 0.20066)
		(layer "F.Cu")
		(net "M_E_CPU1_SB_DQS_DN<5>")
	)
	(segment
		(start 167.686228 -227.50272)
		(end 167.367458 -227.50272)
		(width 0.20066)
		(layer "F.Cu")
		(net "M_E_CPU1_SB_DQS_DN<5>")
	)
	(segment
		(start 164.745924 -227.220526)
		(end 164.623496 -227.220526)
		(width 0.20066)
		(layer "F.Cu")
		(net "M_E_CPU1_SB_DQS_DN<5>")
	)
	(segment
		(start 163.715192 -227.645468)
		(end 163.44392 -227.91674)
		(width 0.20066)
		(layer "F.Cu")
		(net "M_E_CPU1_SB_DQS_DN<5>")
	)
	(segment
		(start 167.367458 -227.50272)
		(end 167.356536 -227.491798)
		(width 0.1016)
		(layer "F.Cu")
		(net "M_E_CPU1_SB_DQS_DN<5>")
	)
	(segment
		(start 168.461944 -227.21697)
		(end 167.971978 -227.21697)
		(width 0.20066)
		(layer "F.Cu")
		(net "M_E_CPU1_SB_DQS_DN<5>")
	)
	(segment
		(start 161.783014 -227.91674)
		(end 162.913314 -227.91674)
		(width 0.20066)
		(layer "F.Cu")
		(net "M_E_CPU1_SB_DQS_DN<5>")
	)
	(segment
		(start 167.971978 -227.21697)
		(end 167.686228 -227.50272)
		(width 0.20066)
		(layer "F.Cu")
		(net "M_E_CPU1_SB_DQS_DN<5>")
	)
	(segment
		(start 148.961348 -234.171744)
		(end 148.082508 -234.171744)
		(width 0.18288)
		(layer "In2.Cu")
		(net "M_E_CPU1_SB_DQS_DN<5>")
	)
	(segment
		(start 158.21406 -227.190808)
		(end 157.9118 -227.493068)
		(width 0.18288)
		(layer "In2.Cu")
		(net "M_E_CPU1_SB_DQS_DN<5>")
	)
	(segment
		(start 135.864346 -234.685078)
		(end 135.728456 -234.692444)
		(width 0.088646)
		(layer "In2.Cu")
		(net "M_E_CPU1_SB_DQS_DN<5>")
	)
	(segment
		(start 143.919448 -234.296204)
		(end 143.370808 -234.296204)
		(width 0.18288)
		(layer "In2.Cu")
		(net "M_E_CPU1_SB_DQS_DN<5>")
	)
	(segment
		(start 151.774398 -232.0671)
		(end 151.386286 -232.455212)
		(width 0.18288)
		(layer "In2.Cu")
		(net "M_E_CPU1_SB_DQS_DN<5>")
	)
	(segment
		(start 136.23163 -234.704382)
		(end 136.219438 -234.707684)
		(width 0.088646)
		(layer "In2.Cu")
		(net "M_E_CPU1_SB_DQS_DN<5>")
	)
	(segment
		(start 136.732518 -234.646216)
		(end 136.73201 -234.645708)
		(width 0.088646)
		(layer "In2.Cu")
		(net "M_E_CPU1_SB_DQS_DN<5>")
	)
	(segment
		(start 143.370808 -234.296204)
		(end 143.246348 -234.171744)
		(width 0.18288)
		(layer "In2.Cu")
		(net "M_E_CPU1_SB_DQS_DN<5>")
	)
	(segment
		(start 148.082508 -234.171744)
		(end 147.958048 -234.296204)
		(width 0.18288)
		(layer "In2.Cu")
		(net "M_E_CPU1_SB_DQS_DN<5>")
	)
	(segment
		(start 157.185106 -227.207572)
		(end 156.861256 -227.207572)
		(width 0.18288)
		(layer "In2.Cu")
		(net "M_E_CPU1_SB_DQS_DN<5>")
	)
	(segment
		(start 135.622792 -234.751372)
		(end 135.605266 -234.970066)
		(width 0.088646)
		(layer "In2.Cu")
		(net "M_E_CPU1_SB_DQS_DN<5>")
	)
	(segment
		(start 161.498026 -227.631752)
		(end 161.375852 -227.631752)
		(width 0.18288)
		(layer "In2.Cu")
		(net "M_E_CPU1_SB_DQS_DN<5>")
	)
	(segment
		(start 145.390108 -234.171744)
		(end 145.265648 -234.296204)
		(width 0.18288)
		(layer "In2.Cu")
		(net "M_E_CPU1_SB_DQS_DN<5>")
	)
	(segment
		(start 136.732772 -234.645454)
		(end 136.732518 -234.646216)
		(width 0.088646)
		(layer "In2.Cu")
		(net "M_E_CPU1_SB_DQS_DN<5>")
	)
	(segment
		(start 144.717008 -234.296204)
		(end 144.592548 -234.171744)
		(width 0.18288)
		(layer "In2.Cu")
		(net "M_E_CPU1_SB_DQS_DN<5>")
	)
	(segment
		(start 135.728456 -234.692444)
		(end 135.671306 -234.716574)
		(width 0.088646)
		(layer "In2.Cu")
		(net "M_E_CPU1_SB_DQS_DN<5>")
	)
	(segment
		(start 152.72639 -230.939086)
		(end 152.72639 -231.115108)
		(width 0.18288)
		(layer "In2.Cu")
		(net "M_E_CPU1_SB_DQS_DN<5>")
	)
	(segment
		(start 139.526518 -234.171744)
		(end 139.041886 -234.656376)
		(width 0.18288)
		(layer "In2.Cu")
		(net "M_E_CPU1_SB_DQS_DN<5>")
	)
	(segment
		(start 136.357106 -234.645708)
		(end 136.317482 -234.668822)
		(width 0.088646)
		(layer "In2.Cu")
		(net "M_E_CPU1_SB_DQS_DN<5>")
	)
	(segment
		(start 146.611848 -234.296204)
		(end 146.063208 -234.296204)
		(width 0.18288)
		(layer "In2.Cu")
		(net "M_E_CPU1_SB_DQS_DN<5>")
	)
	(segment
		(start 144.043908 -234.171744)
		(end 143.919448 -234.296204)
		(width 0.18288)
		(layer "In2.Cu")
		(net "M_E_CPU1_SB_DQS_DN<5>")
	)
	(segment
		(start 157.9118 -227.493068)
		(end 157.470602 -227.493068)
		(width 0.18288)
		(layer "In2.Cu")
		(net "M_E_CPU1_SB_DQS_DN<5>")
	)
	(segment
		(start 150.258272 -233.407204)
		(end 149.870414 -233.795062)
		(width 0.18288)
		(layer "In2.Cu")
		(net "M_E_CPU1_SB_DQS_DN<5>")
	)
	(segment
		(start 150.434294 -233.407204)
		(end 150.258272 -233.407204)
		(width 0.18288)
		(layer "In2.Cu")
		(net "M_E_CPU1_SB_DQS_DN<5>")
	)
	(segment
		(start 142.024608 -234.296204)
		(end 141.900148 -234.171744)
		(width 0.18288)
		(layer "In2.Cu")
		(net "M_E_CPU1_SB_DQS_DN<5>")
	)
	(segment
		(start 145.938748 -234.171744)
		(end 145.390108 -234.171744)
		(width 0.18288)
		(layer "In2.Cu")
		(net "M_E_CPU1_SB_DQS_DN<5>")
	)
	(segment
		(start 136.218676 -234.707938)
		(end 136.218422 -234.707938)
		(width 0.088646)
		(layer "In2.Cu")
		(net "M_E_CPU1_SB_DQS_DN<5>")
	)
	(segment
		(start 147.284948 -234.171744)
		(end 146.736308 -234.171744)
		(width 0.18288)
		(layer "In2.Cu")
		(net "M_E_CPU1_SB_DQS_DN<5>")
	)
	(segment
		(start 149.870414 -233.795062)
		(end 148.961348 -234.171744)
		(width 0.18288)
		(layer "In2.Cu")
		(net "M_E_CPU1_SB_DQS_DN<5>")
	)
	(segment
		(start 152.338278 -231.50322)
		(end 152.162256 -231.50322)
		(width 0.18288)
		(layer "In2.Cu")
		(net "M_E_CPU1_SB_DQS_DN<5>")
	)
	(segment
		(start 139.041886 -234.656376)
		(end 138.410696 -234.656376)
		(width 0.18288)
		(layer "In2.Cu")
		(net "M_E_CPU1_SB_DQS_DN<5>")
	)
	(segment
		(start 147.958048 -234.296204)
		(end 147.409408 -234.296204)
		(width 0.18288)
		(layer "In2.Cu")
		(net "M_E_CPU1_SB_DQS_DN<5>")
	)
	(segment
		(start 136.231376 -234.704636)
		(end 136.23163 -234.704382)
		(width 0.088646)
		(layer "In2.Cu")
		(net "M_E_CPU1_SB_DQS_DN<5>")
	)
	(segment
		(start 156.172916 -227.49256)
		(end 152.72639 -230.939086)
		(width 0.18288)
		(layer "In2.Cu")
		(net "M_E_CPU1_SB_DQS_DN<5>")
	)
	(segment
		(start 136.161018 -234.722924)
		(end 135.993378 -234.722924)
		(width 0.088646)
		(layer "In2.Cu")
		(net "M_E_CPU1_SB_DQS_DN<5>")
	)
	(segment
		(start 151.774398 -231.891078)
		(end 151.774398 -232.0671)
		(width 0.18288)
		(layer "In2.Cu")
		(net "M_E_CPU1_SB_DQS_DN<5>")
	)
	(segment
		(start 146.736308 -234.171744)
		(end 146.611848 -234.296204)
		(width 0.18288)
		(layer "In2.Cu")
		(net "M_E_CPU1_SB_DQS_DN<5>")
	)
	(segment
		(start 152.72639 -231.115108)
		(end 152.338278 -231.50322)
		(width 0.18288)
		(layer "In2.Cu")
		(net "M_E_CPU1_SB_DQS_DN<5>")
	)
	(segment
		(start 151.210264 -232.455212)
		(end 150.822406 -232.84307)
		(width 0.18288)
		(layer "In2.Cu")
		(net "M_E_CPU1_SB_DQS_DN<5>")
	)
	(segment
		(start 161.375852 -227.631752)
		(end 160.426654 -227.819966)
		(width 0.18288)
		(layer "In2.Cu")
		(net "M_E_CPU1_SB_DQS_DN<5>")
	)
	(segment
		(start 147.409408 -234.296204)
		(end 147.284948 -234.171744)
		(width 0.18288)
		(layer "In2.Cu")
		(net "M_E_CPU1_SB_DQS_DN<5>")
	)
	(segment
		(start 151.386286 -232.455212)
		(end 151.210264 -232.455212)
		(width 0.18288)
		(layer "In2.Cu")
		(net "M_E_CPU1_SB_DQS_DN<5>")
	)
	(segment
		(start 152.162256 -231.50322)
		(end 151.774398 -231.891078)
		(width 0.18288)
		(layer "In2.Cu")
		(net "M_E_CPU1_SB_DQS_DN<5>")
	)
	(segment
		(start 160.03524 -227.819966)
		(end 159.803084 -227.723954)
		(width 0.18288)
		(layer "In2.Cu")
		(net "M_E_CPU1_SB_DQS_DN<5>")
	)
	(segment
		(start 141.900148 -234.171744)
		(end 139.526518 -234.171744)
		(width 0.18288)
		(layer "In2.Cu")
		(net "M_E_CPU1_SB_DQS_DN<5>")
	)
	(segment
		(start 142.697708 -234.171744)
		(end 142.573248 -234.296204)
		(width 0.18288)
		(layer "In2.Cu")
		(net "M_E_CPU1_SB_DQS_DN<5>")
	)
	(segment
		(start 145.265648 -234.296204)
		(end 144.717008 -234.296204)
		(width 0.18288)
		(layer "In2.Cu")
		(net "M_E_CPU1_SB_DQS_DN<5>")
	)
	(segment
		(start 160.426654 -227.819966)
		(end 160.03524 -227.819966)
		(width 0.18288)
		(layer "In2.Cu")
		(net "M_E_CPU1_SB_DQS_DN<5>")
	)
	(segment
		(start 136.219438 -234.707684)
		(end 136.218676 -234.707938)
		(width 0.088646)
		(layer "In2.Cu")
		(net "M_E_CPU1_SB_DQS_DN<5>")
	)
	(segment
		(start 138.410696 -234.656376)
		(end 138.351006 -234.596686)
		(width 0.088646)
		(layer "In2.Cu")
		(net "M_E_CPU1_SB_DQS_DN<5>")
	)
	(segment
		(start 144.592548 -234.171744)
		(end 144.043908 -234.171744)
		(width 0.18288)
		(layer "In2.Cu")
		(net "M_E_CPU1_SB_DQS_DN<5>")
	)
	(segment
		(start 138.351006 -234.596686)
		(end 137.479278 -234.596686)
		(width 0.088646)
		(layer "In2.Cu")
		(net "M_E_CPU1_SB_DQS_DN<5>")
	)
	(segment
		(start 142.573248 -234.296204)
		(end 142.024608 -234.296204)
		(width 0.18288)
		(layer "In2.Cu")
		(net "M_E_CPU1_SB_DQS_DN<5>")
	)
	(segment
		(start 150.822406 -233.019092)
		(end 150.434294 -233.407204)
		(width 0.18288)
		(layer "In2.Cu")
		(net "M_E_CPU1_SB_DQS_DN<5>")
	)
	(segment
		(start 161.783014 -227.91674)
		(end 161.498026 -227.631752)
		(width 0.18288)
		(layer "In2.Cu")
		(net "M_E_CPU1_SB_DQS_DN<5>")
	)
	(segment
		(start 135.993378 -234.722924)
		(end 135.864346 -234.685078)
		(width 0.088646)
		(layer "In2.Cu")
		(net "M_E_CPU1_SB_DQS_DN<5>")
	)
	(segment
		(start 159.269938 -227.190808)
		(end 158.21406 -227.190808)
		(width 0.18288)
		(layer "In2.Cu")
		(net "M_E_CPU1_SB_DQS_DN<5>")
	)
	(segment
		(start 143.246348 -234.171744)
		(end 142.697708 -234.171744)
		(width 0.18288)
		(layer "In2.Cu")
		(net "M_E_CPU1_SB_DQS_DN<5>")
	)
	(segment
		(start 136.357614 -234.645708)
		(end 136.357106 -234.645708)
		(width 0.088646)
		(layer "In2.Cu")
		(net "M_E_CPU1_SB_DQS_DN<5>")
	)
	(segment
		(start 136.317482 -234.668822)
		(end 136.231376 -234.704636)
		(width 0.088646)
		(layer "In2.Cu")
		(net "M_E_CPU1_SB_DQS_DN<5>")
	)
	(segment
		(start 150.822406 -232.84307)
		(end 150.822406 -233.019092)
		(width 0.18288)
		(layer "In2.Cu")
		(net "M_E_CPU1_SB_DQS_DN<5>")
	)
	(segment
		(start 135.671306 -234.716574)
		(end 135.622792 -234.751372)
		(width 0.088646)
		(layer "In2.Cu")
		(net "M_E_CPU1_SB_DQS_DN<5>")
	)
	(segment
		(start 156.861256 -227.207572)
		(end 156.172916 -227.49256)
		(width 0.18288)
		(layer "In2.Cu")
		(net "M_E_CPU1_SB_DQS_DN<5>")
	)
	(segment
		(start 136.218422 -234.707938)
		(end 136.161018 -234.722924)
		(width 0.088646)
		(layer "In2.Cu")
		(net "M_E_CPU1_SB_DQS_DN<5>")
	)
	(segment
		(start 146.063208 -234.296204)
		(end 145.938748 -234.171744)
		(width 0.18288)
		(layer "In2.Cu")
		(net "M_E_CPU1_SB_DQS_DN<5>")
	)
	(segment
		(start 159.803084 -227.723954)
		(end 159.269938 -227.190808)
		(width 0.18288)
		(layer "In2.Cu")
		(net "M_E_CPU1_SB_DQS_DN<5>")
	)
	(segment
		(start 157.470602 -227.493068)
		(end 157.185106 -227.207572)
		(width 0.18288)
		(layer "In2.Cu")
		(net "M_E_CPU1_SB_DQS_DN<5>")
	)
	(arc
		(start 137.29716 -234.645454)
		(mid 137.014966 -234.72101)
		(end 136.732772 -234.645454)
		(width 0.088646)
		(layer "In2.Cu")
		(net "M_E_CPU1_SB_DQS_DN<5>")
	)
	(arc
		(start 137.479278 -234.596686)
		(mid 137.385022 -234.609125)
		(end 137.29716 -234.645454)
		(width 0.088646)
		(layer "In2.Cu")
		(net "M_E_CPU1_SB_DQS_DN<5>")
	)
	(arc
		(start 136.73201 -234.645708)
		(mid 136.544812 -234.595565)
		(end 136.357614 -234.645708)
		(width 0.088646)
		(layer "In2.Cu")
		(net "M_E_CPU1_SB_DQS_DN<5>")
	)
	(segment
		(start 139.742672 -242.501166)
		(end 139.966446 -242.501166)
		(width 0.088646)
		(layer "F.Cu")
		(net "M_E_CPU1_SB_DQS_DN<4>")
	)
	(segment
		(start 154.924252 -237.262162)
		(end 155.047442 -237.138972)
		(width 0.20066)
		(layer "F.Cu")
		(net "M_E_CPU1_SB_DQS_DN<4>")
	)
	(segment
		(start 155.649422 -237.138972)
		(end 156.46908 -236.319314)
		(width 0.20066)
		(layer "F.Cu")
		(net "M_E_CPU1_SB_DQS_DN<4>")
	)
	(segment
		(start 156.952188 -236.653578)
		(end 157.161484 -236.862874)
		(width 0.20066)
		(layer "F.Cu")
		(net "M_E_CPU1_SB_DQS_DN<4>")
	)
	(segment
		(start 163.875974 -236.995462)
		(end 163.545012 -236.995462)
		(width 0.20066)
		(layer "F.Cu")
		(net "M_E_CPU1_SB_DQS_DN<4>")
	)
	(segment
		(start 167.905684 -236.852714)
		(end 167.765476 -236.852714)
		(width 0.20066)
		(layer "F.Cu")
		(net "M_E_CPU1_SB_DQS_DN<4>")
	)
	(segment
		(start 150.696422 -237.138972)
		(end 151.298402 -237.138972)
		(width 0.20066)
		(layer "F.Cu")
		(net "M_E_CPU1_SB_DQS_DN<4>")
	)
	(segment
		(start 141.941296 -240.79454)
		(end 143.735806 -240.79454)
		(width 0.1524)
		(layer "F.Cu")
		(net "M_E_CPU1_SB_DQS_DN<4>")
	)
	(segment
		(start 170.457114 -237.266734)
		(end 169.953432 -237.266734)
		(width 0.20066)
		(layer "F.Cu")
		(net "M_E_CPU1_SB_DQS_DN<4>")
	)
	(segment
		(start 162.407346 -237.266734)
		(end 162.913314 -237.266734)
		(width 0.20066)
		(layer "F.Cu")
		(net "M_E_CPU1_SB_DQS_DN<4>")
	)
	(segment
		(start 160.40227 -236.841538)
		(end 160.647634 -236.596174)
		(width 0.20066)
		(layer "F.Cu")
		(net "M_E_CPU1_SB_DQS_DN<4>")
	)
	(segment
		(start 149.971252 -237.262162)
		(end 150.573232 -237.262162)
		(width 0.20066)
		(layer "F.Cu")
		(net "M_E_CPU1_SB_DQS_DN<4>")
	)
	(segment
		(start 160.280858 -236.841538)
		(end 160.40227 -236.841538)
		(width 0.20066)
		(layer "F.Cu")
		(net "M_E_CPU1_SB_DQS_DN<4>")
	)
	(segment
		(start 139.362688 -242.501166)
		(end 139.455652 -242.59413)
		(width 0.088646)
		(layer "F.Cu")
		(net "M_E_CPU1_SB_DQS_DN<4>")
	)
	(segment
		(start 152.871932 -237.262162)
		(end 153.473912 -237.262162)
		(width 0.20066)
		(layer "F.Cu")
		(net "M_E_CPU1_SB_DQS_DN<4>")
	)
	(segment
		(start 149.848062 -237.138972)
		(end 149.971252 -237.262162)
		(width 0.20066)
		(layer "F.Cu")
		(net "M_E_CPU1_SB_DQS_DN<4>")
	)
	(segment
		(start 141.705076 -240.762536)
		(end 141.887194 -240.762536)
		(width 0.088646)
		(layer "F.Cu")
		(net "M_E_CPU1_SB_DQS_DN<4>")
	)
	(segment
		(start 169.68597 -236.999272)
		(end 169.164508 -236.999272)
		(width 0.20066)
		(layer "F.Cu")
		(net "M_E_CPU1_SB_DQS_DN<4>")
	)
	(segment
		(start 167.765476 -236.852714)
		(end 167.754554 -236.841792)
		(width 0.101854)
		(layer "F.Cu")
		(net "M_E_CPU1_SB_DQS_DN<4>")
	)
	(segment
		(start 147.922996 -237.138972)
		(end 147.961096 -237.138972)
		(width 0.1524)
		(layer "F.Cu")
		(net "M_E_CPU1_SB_DQS_DN<4>")
	)
	(segment
		(start 156.46908 -236.319314)
		(end 156.751782 -236.319314)
		(width 0.20066)
		(layer "F.Cu")
		(net "M_E_CPU1_SB_DQS_DN<4>")
	)
	(segment
		(start 139.966446 -242.501166)
		(end 141.705076 -240.762536)
		(width 0.088646)
		(layer "F.Cu")
		(net "M_E_CPU1_SB_DQS_DN<4>")
	)
	(segment
		(start 163.27374 -237.266734)
		(end 162.913314 -237.266734)
		(width 0.20066)
		(layer "F.Cu")
		(net "M_E_CPU1_SB_DQS_DN<4>")
	)
	(segment
		(start 157.311852 -236.841538)
		(end 157.854396 -236.841538)
		(width 0.101854)
		(layer "F.Cu")
		(net "M_E_CPU1_SB_DQS_DN<4>")
	)
	(segment
		(start 167.356536 -236.841792)
		(end 165.34638 -236.841792)
		(width 0.1016)
		(layer "F.Cu")
		(net "M_E_CPU1_SB_DQS_DN<4>")
	)
	(segment
		(start 153.597102 -237.138972)
		(end 154.199082 -237.138972)
		(width 0.20066)
		(layer "F.Cu")
		(net "M_E_CPU1_SB_DQS_DN<4>")
	)
	(segment
		(start 164.299646 -236.57179)
		(end 163.875974 -236.995462)
		(width 0.20066)
		(layer "F.Cu")
		(net "M_E_CPU1_SB_DQS_DN<4>")
	)
	(segment
		(start 157.854396 -236.841538)
		(end 159.805624 -236.841538)
		(width 0.1016)
		(layer "F.Cu")
		(net "M_E_CPU1_SB_DQS_DN<4>")
	)
	(segment
		(start 155.047442 -237.138972)
		(end 155.649422 -237.138972)
		(width 0.20066)
		(layer "F.Cu")
		(net "M_E_CPU1_SB_DQS_DN<4>")
	)
	(segment
		(start 157.290516 -236.862874)
		(end 157.311852 -236.841538)
		(width 0.101854)
		(layer "F.Cu")
		(net "M_E_CPU1_SB_DQS_DN<4>")
	)
	(segment
		(start 139.455652 -242.59413)
		(end 139.649708 -242.59413)
		(width 0.088646)
		(layer "F.Cu")
		(net "M_E_CPU1_SB_DQS_DN<4>")
	)
	(segment
		(start 138.894312 -242.830858)
		(end 138.894312 -242.741958)
		(width 0.088646)
		(layer "F.Cu")
		(net "M_E_CPU1_SB_DQS_DN<4>")
	)
	(segment
		(start 139.135104 -242.501166)
		(end 139.362688 -242.501166)
		(width 0.088646)
		(layer "F.Cu")
		(net "M_E_CPU1_SB_DQS_DN<4>")
	)
	(segment
		(start 156.751782 -236.319314)
		(end 156.952188 -236.51972)
		(width 0.20066)
		(layer "F.Cu")
		(net "M_E_CPU1_SB_DQS_DN<4>")
	)
	(segment
		(start 168.191434 -236.566964)
		(end 167.905684 -236.852714)
		(width 0.20066)
		(layer "F.Cu")
		(net "M_E_CPU1_SB_DQS_DN<4>")
	)
	(segment
		(start 147.961096 -237.138972)
		(end 149.848062 -237.138972)
		(width 0.20066)
		(layer "F.Cu")
		(net "M_E_CPU1_SB_DQS_DN<4>")
	)
	(segment
		(start 152.023572 -237.262162)
		(end 152.146762 -237.138972)
		(width 0.20066)
		(layer "F.Cu")
		(net "M_E_CPU1_SB_DQS_DN<4>")
	)
	(segment
		(start 162.13582 -236.995208)
		(end 162.407346 -237.266734)
		(width 0.20066)
		(layer "F.Cu")
		(net "M_E_CPU1_SB_DQS_DN<4>")
	)
	(segment
		(start 160.901126 -236.596174)
		(end 161.863532 -236.995208)
		(width 0.20066)
		(layer "F.Cu")
		(net "M_E_CPU1_SB_DQS_DN<4>")
	)
	(segment
		(start 150.573232 -237.262162)
		(end 150.696422 -237.138972)
		(width 0.20066)
		(layer "F.Cu")
		(net "M_E_CPU1_SB_DQS_DN<4>")
	)
	(segment
		(start 159.805624 -236.841538)
		(end 160.280858 -236.841538)
		(width 0.101854)
		(layer "F.Cu")
		(net "M_E_CPU1_SB_DQS_DN<4>")
	)
	(segment
		(start 143.735806 -240.79454)
		(end 147.428204 -237.102142)
		(width 0.1524)
		(layer "F.Cu")
		(net "M_E_CPU1_SB_DQS_DN<4>")
	)
	(segment
		(start 152.748742 -237.138972)
		(end 152.871932 -237.262162)
		(width 0.20066)
		(layer "F.Cu")
		(net "M_E_CPU1_SB_DQS_DN<4>")
	)
	(segment
		(start 147.886166 -237.102142)
		(end 147.922996 -237.138972)
		(width 0.1524)
		(layer "F.Cu")
		(net "M_E_CPU1_SB_DQS_DN<4>")
	)
	(segment
		(start 160.647634 -236.596174)
		(end 160.901126 -236.596174)
		(width 0.20066)
		(layer "F.Cu")
		(net "M_E_CPU1_SB_DQS_DN<4>")
	)
	(segment
		(start 156.952188 -236.51972)
		(end 156.952188 -236.653578)
		(width 0.20066)
		(layer "F.Cu")
		(net "M_E_CPU1_SB_DQS_DN<4>")
	)
	(segment
		(start 164.916358 -236.841792)
		(end 164.910262 -236.847888)
		(width 0.101854)
		(layer "F.Cu")
		(net "M_E_CPU1_SB_DQS_DN<4>")
	)
	(segment
		(start 141.887194 -240.762536)
		(end 141.919198 -240.79454)
		(width 0.088646)
		(layer "F.Cu")
		(net "M_E_CPU1_SB_DQS_DN<4>")
	)
	(segment
		(start 169.953432 -237.266734)
		(end 169.68597 -236.999272)
		(width 0.20066)
		(layer "F.Cu")
		(net "M_E_CPU1_SB_DQS_DN<4>")
	)
	(segment
		(start 164.806884 -236.847888)
		(end 164.530786 -236.57179)
		(width 0.20066)
		(layer "F.Cu")
		(net "M_E_CPU1_SB_DQS_DN<4>")
	)
	(segment
		(start 169.164508 -236.999272)
		(end 168.7322 -236.566964)
		(width 0.20066)
		(layer "F.Cu")
		(net "M_E_CPU1_SB_DQS_DN<4>")
	)
	(segment
		(start 151.421592 -237.262162)
		(end 152.023572 -237.262162)
		(width 0.20066)
		(layer "F.Cu")
		(net "M_E_CPU1_SB_DQS_DN<4>")
	)
	(segment
		(start 139.649708 -242.59413)
		(end 139.742672 -242.501166)
		(width 0.088646)
		(layer "F.Cu")
		(net "M_E_CPU1_SB_DQS_DN<4>")
	)
	(segment
		(start 141.919198 -240.79454)
		(end 141.941296 -240.79454)
		(width 0.088646)
		(layer "F.Cu")
		(net "M_E_CPU1_SB_DQS_DN<4>")
	)
	(segment
		(start 161.863532 -236.995208)
		(end 162.13582 -236.995208)
		(width 0.20066)
		(layer "F.Cu")
		(net "M_E_CPU1_SB_DQS_DN<4>")
	)
	(segment
		(start 154.322272 -237.262162)
		(end 154.924252 -237.262162)
		(width 0.20066)
		(layer "F.Cu")
		(net "M_E_CPU1_SB_DQS_DN<4>")
	)
	(segment
		(start 151.298402 -237.138972)
		(end 151.421592 -237.262162)
		(width 0.20066)
		(layer "F.Cu")
		(net "M_E_CPU1_SB_DQS_DN<4>")
	)
	(segment
		(start 154.199082 -237.138972)
		(end 154.322272 -237.262162)
		(width 0.20066)
		(layer "F.Cu")
		(net "M_E_CPU1_SB_DQS_DN<4>")
	)
	(segment
		(start 147.428204 -237.102142)
		(end 147.886166 -237.102142)
		(width 0.1524)
		(layer "F.Cu")
		(net "M_E_CPU1_SB_DQS_DN<4>")
	)
	(segment
		(start 164.910262 -236.847888)
		(end 164.806884 -236.847888)
		(width 0.20066)
		(layer "F.Cu")
		(net "M_E_CPU1_SB_DQS_DN<4>")
	)
	(segment
		(start 163.545012 -236.995462)
		(end 163.27374 -237.266734)
		(width 0.20066)
		(layer "F.Cu")
		(net "M_E_CPU1_SB_DQS_DN<4>")
	)
	(segment
		(start 165.34638 -236.841792)
		(end 164.916358 -236.841792)
		(width 0.101854)
		(layer "F.Cu")
		(net "M_E_CPU1_SB_DQS_DN<4>")
	)
	(segment
		(start 138.894312 -242.741958)
		(end 139.135104 -242.501166)
		(width 0.088646)
		(layer "F.Cu")
		(net "M_E_CPU1_SB_DQS_DN<4>")
	)
	(segment
		(start 157.161484 -236.862874)
		(end 157.290516 -236.862874)
		(width 0.20066)
		(layer "F.Cu")
		(net "M_E_CPU1_SB_DQS_DN<4>")
	)
	(segment
		(start 153.473912 -237.262162)
		(end 153.597102 -237.138972)
		(width 0.20066)
		(layer "F.Cu")
		(net "M_E_CPU1_SB_DQS_DN<4>")
	)
	(segment
		(start 164.530786 -236.57179)
		(end 164.299646 -236.57179)
		(width 0.20066)
		(layer "F.Cu")
		(net "M_E_CPU1_SB_DQS_DN<4>")
	)
	(segment
		(start 168.7322 -236.566964)
		(end 168.191434 -236.566964)
		(width 0.20066)
		(layer "F.Cu")
		(net "M_E_CPU1_SB_DQS_DN<4>")
	)
	(segment
		(start 167.754554 -236.841792)
		(end 167.356536 -236.841792)
		(width 0.101854)
		(layer "F.Cu")
		(net "M_E_CPU1_SB_DQS_DN<4>")
	)
	(segment
		(start 152.146762 -237.138972)
		(end 152.748742 -237.138972)
		(width 0.20066)
		(layer "F.Cu")
		(net "M_E_CPU1_SB_DQS_DN<4>")
	)
	(segment
		(start 165.527228 -200.107296)
		(end 165.194742 -200.107296)
		(width 0.20066)
		(layer "F.Cu")
		(net "M_E_CPU1_SB_DQS_DN<3>")
	)
	(segment
		(start 141.349222 -212.120226)
		(end 141.33957 -212.096858)
		(width 0.1524)
		(layer "F.Cu")
		(net "M_E_CPU1_SB_DQS_DN<3>")
	)
	(segment
		(start 157.55874 -199.86879)
		(end 157.560772 -199.866758)
		(width 0.20066)
		(layer "F.Cu")
		(net "M_E_CPU1_SB_DQS_DN<3>")
	)
	(segment
		(start 161.134044 -200.562972)
		(end 160.13303 -200.148444)
		(width 0.20066)
		(layer "F.Cu")
		(net "M_E_CPU1_SB_DQS_DN<3>")
	)
	(segment
		(start 166.357046 -199.866758)
		(end 165.767766 -199.866758)
		(width 0.20066)
		(layer "F.Cu")
		(net "M_E_CPU1_SB_DQS_DN<3>")
	)
	(segment
		(start 140.432028 -227.91547)
		(end 140.432028 -227.870766)
		(width 0.088646)
		(layer "F.Cu")
		(net "M_E_CPU1_SB_DQS_DN<3>")
	)
	(segment
		(start 164.529262 -200.567798)
		(end 164.245036 -200.283572)
		(width 0.20066)
		(layer "F.Cu")
		(net "M_E_CPU1_SB_DQS_DN<3>")
	)
	(segment
		(start 156.293566 -200.47204)
		(end 156.699966 -200.065386)
		(width 0.20066)
		(layer "F.Cu")
		(net "M_E_CPU1_SB_DQS_DN<3>")
	)
	(segment
		(start 138.143234 -228.505258)
		(end 138.143742 -228.505004)
		(width 0.088646)
		(layer "F.Cu")
		(net "M_E_CPU1_SB_DQS_DN<3>")
	)
	(segment
		(start 165.194742 -200.107296)
		(end 164.73424 -200.567798)
		(width 0.20066)
		(layer "F.Cu")
		(net "M_E_CPU1_SB_DQS_DN<3>")
	)
	(segment
		(start 137.24763 -227.902516)
		(end 137.289286 -227.93706)
		(width 0.088646)
		(layer "F.Cu")
		(net "M_E_CPU1_SB_DQS_DN<3>")
	)
	(segment
		(start 141.561312 -213.18855)
		(end 141.349222 -212.120226)
		(width 0.1524)
		(layer "F.Cu")
		(net "M_E_CPU1_SB_DQS_DN<3>")
	)
	(segment
		(start 139.328652 -228.422962)
		(end 139.749022 -228.249226)
		(width 0.088646)
		(layer "F.Cu")
		(net "M_E_CPU1_SB_DQS_DN<3>")
	)
	(segment
		(start 141.561312 -226.741482)
		(end 141.561312 -213.18855)
		(width 0.1524)
		(layer "F.Cu")
		(net "M_E_CPU1_SB_DQS_DN<3>")
	)
	(segment
		(start 140.447522 -227.855272)
		(end 141.561312 -226.741482)
		(width 0.1524)
		(layer "F.Cu")
		(net "M_E_CPU1_SB_DQS_DN<3>")
	)
	(segment
		(start 142.338044 -205.893924)
		(end 142.856204 -205.375764)
		(width 0.20066)
		(layer "F.Cu")
		(net "M_E_CPU1_SB_DQS_DN<3>")
	)
	(segment
		(start 142.85595 -205.375764)
		(end 144.667478 -203.56449)
		(width 0.20066)
		(layer "F.Cu")
		(net "M_E_CPU1_SB_DQS_DN<3>")
	)
	(segment
		(start 142.856204 -205.375764)
		(end 142.85595 -205.375764)
		(width 0.20066)
		(layer "F.Cu")
		(net "M_E_CPU1_SB_DQS_DN<3>")
	)
	(segment
		(start 161.896552 -200.278492)
		(end 161.891726 -200.278492)
		(width 0.101854)
		(layer "F.Cu")
		(net "M_E_CPU1_SB_DQS_DN<3>")
	)
	(segment
		(start 159.361886 -199.866758)
		(end 158.813246 -199.866758)
		(width 0.20066)
		(layer "F.Cu")
		(net "M_E_CPU1_SB_DQS_DN<3>")
	)
	(segment
		(start 159.643572 -200.148444)
		(end 159.361886 -199.866758)
		(width 0.20066)
		(layer "F.Cu")
		(net "M_E_CPU1_SB_DQS_DN<3>")
	)
	(segment
		(start 145.126964 -203.374244)
		(end 146.95043 -203.374244)
		(width 0.20066)
		(layer "F.Cu")
		(net "M_E_CPU1_SB_DQS_DN<3>")
	)
	(segment
		(start 137.652252 -228.420422)
		(end 137.690606 -228.45522)
		(width 0.088646)
		(layer "F.Cu")
		(net "M_E_CPU1_SB_DQS_DN<3>")
	)
	(segment
		(start 144.667478 -203.56449)
		(end 145.126964 -203.374244)
		(width 0.20066)
		(layer "F.Cu")
		(net "M_E_CPU1_SB_DQS_DN<3>")
	)
	(segment
		(start 161.90976 -200.2917)
		(end 161.896552 -200.278492)
		(width 0.1016)
		(layer "F.Cu")
		(net "M_E_CPU1_SB_DQS_DN<3>")
	)
	(segment
		(start 141.30274 -210.865212)
		(end 141.30274 -208.393538)
		(width 0.20066)
		(layer "F.Cu")
		(net "M_E_CPU1_SB_DQS_DN<3>")
	)
	(segment
		(start 136.987026 -227.81514)
		(end 137.0457 -227.819966)
		(width 0.088646)
		(layer "F.Cu")
		(net "M_E_CPU1_SB_DQS_DN<3>")
	)
	(segment
		(start 157.560772 -199.866758)
		(end 158.813246 -199.866758)
		(width 0.20066)
		(layer "F.Cu")
		(net "M_E_CPU1_SB_DQS_DN<3>")
	)
	(segment
		(start 138.750294 -228.529134)
		(end 138.773662 -228.541072)
		(width 0.088646)
		(layer "F.Cu")
		(net "M_E_CPU1_SB_DQS_DN<3>")
	)
	(segment
		(start 161.586926 -200.278492)
		(end 161.302446 -200.562972)
		(width 0.20066)
		(layer "F.Cu")
		(net "M_E_CPU1_SB_DQS_DN<3>")
	)
	(segment
		(start 138.688826 -228.494082)
		(end 138.750294 -228.529134)
		(width 0.088646)
		(layer "F.Cu")
		(net "M_E_CPU1_SB_DQS_DN<3>")
	)
	(segment
		(start 139.044426 -228.541072)
		(end 139.328652 -228.42347)
		(width 0.088646)
		(layer "F.Cu")
		(net "M_E_CPU1_SB_DQS_DN<3>")
	)
	(segment
		(start 156.699966 -200.065386)
		(end 157.067504 -199.912986)
		(width 0.20066)
		(layer "F.Cu")
		(net "M_E_CPU1_SB_DQS_DN<3>")
	)
	(segment
		(start 138.14298 -228.505258)
		(end 138.143234 -228.505258)
		(width 0.088646)
		(layer "F.Cu")
		(net "M_E_CPU1_SB_DQS_DN<3>")
	)
	(segment
		(start 157.067504 -199.912986)
		(end 157.069028 -199.912478)
		(width 0.20066)
		(layer "F.Cu")
		(net "M_E_CPU1_SB_DQS_DN<3>")
	)
	(segment
		(start 164.245036 -200.283572)
		(end 163.923726 -200.283572)
		(width 0.20066)
		(layer "F.Cu")
		(net "M_E_CPU1_SB_DQS_DN<3>")
	)
	(segment
		(start 137.690606 -228.45522)
		(end 137.690606 -228.455474)
		(width 0.088646)
		(layer "F.Cu")
		(net "M_E_CPU1_SB_DQS_DN<3>")
	)
	(segment
		(start 161.891726 -200.278492)
		(end 161.586926 -200.278492)
		(width 0.20066)
		(layer "F.Cu")
		(net "M_E_CPU1_SB_DQS_DN<3>")
	)
	(segment
		(start 138.139678 -228.50729)
		(end 138.14298 -228.505258)
		(width 0.088646)
		(layer "F.Cu")
		(net "M_E_CPU1_SB_DQS_DN<3>")
	)
	(segment
		(start 141.33957 -212.096858)
		(end 141.33957 -210.940396)
		(width 0.1524)
		(layer "F.Cu")
		(net "M_E_CPU1_SB_DQS_DN<3>")
	)
	(segment
		(start 139.328652 -228.42347)
		(end 139.328652 -228.422962)
		(width 0.088646)
		(layer "F.Cu")
		(net "M_E_CPU1_SB_DQS_DN<3>")
	)
	(segment
		(start 146.95043 -203.374244)
		(end 149.852634 -200.47204)
		(width 0.20066)
		(layer "F.Cu")
		(net "M_E_CPU1_SB_DQS_DN<3>")
	)
	(segment
		(start 164.73424 -200.567798)
		(end 164.529262 -200.567798)
		(width 0.20066)
		(layer "F.Cu")
		(net "M_E_CPU1_SB_DQS_DN<3>")
	)
	(segment
		(start 160.13303 -200.148444)
		(end 159.643572 -200.148444)
		(width 0.20066)
		(layer "F.Cu")
		(net "M_E_CPU1_SB_DQS_DN<3>")
	)
	(segment
		(start 140.055092 -228.12248)
		(end 140.225018 -228.12248)
		(width 0.088646)
		(layer "F.Cu")
		(net "M_E_CPU1_SB_DQS_DN<3>")
	)
	(segment
		(start 165.767766 -199.866758)
		(end 165.527228 -200.107296)
		(width 0.20066)
		(layer "F.Cu")
		(net "M_E_CPU1_SB_DQS_DN<3>")
	)
	(segment
		(start 141.33957 -210.940396)
		(end 141.30274 -210.903566)
		(width 0.1524)
		(layer "F.Cu")
		(net "M_E_CPU1_SB_DQS_DN<3>")
	)
	(segment
		(start 163.915598 -200.2917)
		(end 161.90976 -200.2917)
		(width 0.1016)
		(layer "F.Cu")
		(net "M_E_CPU1_SB_DQS_DN<3>")
	)
	(segment
		(start 138.143742 -228.505004)
		(end 138.187938 -228.479604)
		(width 0.088646)
		(layer "F.Cu")
		(net "M_E_CPU1_SB_DQS_DN<3>")
	)
	(segment
		(start 161.302446 -200.562972)
		(end 161.134044 -200.562972)
		(width 0.20066)
		(layer "F.Cu")
		(net "M_E_CPU1_SB_DQS_DN<3>")
	)
	(segment
		(start 139.749022 -228.249226)
		(end 140.055092 -228.12248)
		(width 0.088646)
		(layer "F.Cu")
		(net "M_E_CPU1_SB_DQS_DN<3>")
	)
	(segment
		(start 141.30274 -210.903566)
		(end 141.30274 -210.865212)
		(width 0.1524)
		(layer "F.Cu")
		(net "M_E_CPU1_SB_DQS_DN<3>")
	)
	(segment
		(start 138.773662 -228.541072)
		(end 139.044426 -228.541072)
		(width 0.088646)
		(layer "F.Cu")
		(net "M_E_CPU1_SB_DQS_DN<3>")
	)
	(segment
		(start 140.432028 -227.870766)
		(end 140.447522 -227.855272)
		(width 0.088646)
		(layer "F.Cu")
		(net "M_E_CPU1_SB_DQS_DN<3>")
	)
	(segment
		(start 141.30274 -208.393538)
		(end 142.338044 -205.893924)
		(width 0.20066)
		(layer "F.Cu")
		(net "M_E_CPU1_SB_DQS_DN<3>")
	)
	(segment
		(start 157.183074 -199.86879)
		(end 157.55874 -199.86879)
		(width 0.20066)
		(layer "F.Cu")
		(net "M_E_CPU1_SB_DQS_DN<3>")
	)
	(segment
		(start 140.225018 -228.12248)
		(end 140.432028 -227.91547)
		(width 0.088646)
		(layer "F.Cu")
		(net "M_E_CPU1_SB_DQS_DN<3>")
	)
	(segment
		(start 157.069028 -199.912478)
		(end 157.183074 -199.86879)
		(width 0.20066)
		(layer "F.Cu")
		(net "M_E_CPU1_SB_DQS_DN<3>")
	)
	(segment
		(start 149.852634 -200.47204)
		(end 156.293566 -200.47204)
		(width 0.20066)
		(layer "F.Cu")
		(net "M_E_CPU1_SB_DQS_DN<3>")
	)
	(segment
		(start 163.923726 -200.283572)
		(end 163.915598 -200.2917)
		(width 0.1016)
		(layer "F.Cu")
		(net "M_E_CPU1_SB_DQS_DN<3>")
	)
	(segment
		(start 136.075166 -228.1809)
		(end 136.799574 -227.847906)
		(width 0.088646)
		(layer "F.Cu")
		(net "M_E_CPU1_SB_DQS_DN<3>")
	)
	(segment
		(start 137.302494 -227.95103)
		(end 137.652252 -228.420422)
		(width 0.088646)
		(layer "F.Cu")
		(net "M_E_CPU1_SB_DQS_DN<3>")
	)
	(arc
		(start 136.799574 -227.847906)
		(mid 136.89117 -227.819336)
		(end 136.987026 -227.81514)
		(width 0.088646)
		(layer "F.Cu")
		(net "M_E_CPU1_SB_DQS_DN<3>")
	)
	(arc
		(start 138.187938 -228.479604)
		(mid 138.2355 -228.456503)
		(end 138.285728 -228.43998)
		(width 0.088646)
		(layer "F.Cu")
		(net "M_E_CPU1_SB_DQS_DN<3>")
	)
	(arc
		(start 138.285728 -228.43998)
		(mid 138.492555 -228.4277)
		(end 138.688826 -228.494082)
		(width 0.088646)
		(layer "F.Cu")
		(net "M_E_CPU1_SB_DQS_DN<3>")
	)
	(arc
		(start 137.289286 -227.93706)
		(mid 137.296307 -227.943651)
		(end 137.302494 -227.95103)
		(width 0.088646)
		(layer "F.Cu")
		(net "M_E_CPU1_SB_DQS_DN<3>")
	)
	(arc
		(start 137.690606 -228.455474)
		(mid 137.906759 -228.553888)
		(end 138.139678 -228.50729)
		(width 0.088646)
		(layer "F.Cu")
		(net "M_E_CPU1_SB_DQS_DN<3>")
	)
	(arc
		(start 137.0457 -227.819966)
		(mid 137.153028 -227.845676)
		(end 137.24763 -227.902516)
		(width 0.088646)
		(layer "F.Cu")
		(net "M_E_CPU1_SB_DQS_DN<3>")
	)
	(segment
		(start 145.610834 -216.890346)
		(end 145.806668 -216.694512)
		(width 0.1524)
		(layer "F.Cu")
		(net "M_E_CPU1_SB_DQS_DN<2>")
	)
	(segment
		(start 140.363956 -233.308652)
		(end 140.386054 -233.308652)
		(width 0.088646)
		(layer "F.Cu")
		(net "M_E_CPU1_SB_DQS_DN<2>")
	)
	(segment
		(start 158.27756 -209.216752)
		(end 158.813246 -209.216752)
		(width 0.20066)
		(layer "F.Cu")
		(net "M_E_CPU1_SB_DQS_DN<2>")
	)
	(segment
		(start 139.134342 -233.418126)
		(end 139.211812 -233.340656)
		(width 0.088646)
		(layer "F.Cu")
		(net "M_E_CPU1_SB_DQS_DN<2>")
	)
	(segment
		(start 145.806668 -216.694512)
		(end 145.806414 -216.643204)
		(width 0.1524)
		(layer "F.Cu")
		(net "M_E_CPU1_SB_DQS_DN<2>")
	)
	(segment
		(start 137.736326 -233.375454)
		(end 137.736326 -233.375708)
		(width 0.088646)
		(layer "F.Cu")
		(net "M_E_CPU1_SB_DQS_DN<2>")
	)
	(segment
		(start 140.386054 -233.308652)
		(end 140.54836 -233.308652)
		(width 0.1524)
		(layer "F.Cu")
		(net "M_E_CPU1_SB_DQS_DN<2>")
	)
	(segment
		(start 137.442702 -232.91419)
		(end 137.540492 -233.01198)
		(width 0.088646)
		(layer "F.Cu")
		(net "M_E_CPU1_SB_DQS_DN<2>")
	)
	(segment
		(start 161.896552 -209.612484)
		(end 161.891726 -209.612484)
		(width 0.101854)
		(layer "F.Cu")
		(net "M_E_CPU1_SB_DQS_DN<2>")
	)
	(segment
		(start 145.806414 -216.643204)
		(end 145.833338 -216.61628)
		(width 0.1524)
		(layer "F.Cu")
		(net "M_E_CPU1_SB_DQS_DN<2>")
	)
	(segment
		(start 138.33983 -233.312462)
		(end 138.640058 -233.312462)
		(width 0.088646)
		(layer "F.Cu")
		(net "M_E_CPU1_SB_DQS_DN<2>")
	)
	(segment
		(start 165.876478 -209.216752)
		(end 165.63594 -209.45729)
		(width 0.20066)
		(layer "F.Cu")
		(net "M_E_CPU1_SB_DQS_DN<2>")
	)
	(segment
		(start 138.745722 -233.418126)
		(end 139.134342 -233.418126)
		(width 0.088646)
		(layer "F.Cu")
		(net "M_E_CPU1_SB_DQS_DN<2>")
	)
	(segment
		(start 164.235638 -209.63128)
		(end 163.923726 -209.63128)
		(width 0.20066)
		(layer "F.Cu")
		(net "M_E_CPU1_SB_DQS_DN<2>")
	)
	(segment
		(start 165.283134 -209.45729)
		(end 164.845238 -209.895186)
		(width 0.20066)
		(layer "F.Cu")
		(net "M_E_CPU1_SB_DQS_DN<2>")
	)
	(segment
		(start 166.357046 -209.216752)
		(end 165.876478 -209.216752)
		(width 0.20066)
		(layer "F.Cu")
		(net "M_E_CPU1_SB_DQS_DN<2>")
	)
	(segment
		(start 145.472912 -228.3841)
		(end 145.472912 -217.028522)
		(width 0.1524)
		(layer "F.Cu")
		(net "M_E_CPU1_SB_DQS_DN<2>")
	)
	(segment
		(start 137.095484 -232.691432)
		(end 137.169144 -232.722166)
		(width 0.088646)
		(layer "F.Cu")
		(net "M_E_CPU1_SB_DQS_DN<2>")
	)
	(segment
		(start 164.845238 -209.895186)
		(end 164.499544 -209.895186)
		(width 0.20066)
		(layer "F.Cu")
		(net "M_E_CPU1_SB_DQS_DN<2>")
	)
	(segment
		(start 137.540492 -233.01198)
		(end 137.540492 -233.029252)
		(width 0.088646)
		(layer "F.Cu")
		(net "M_E_CPU1_SB_DQS_DN<2>")
	)
	(segment
		(start 145.833338 -216.61628)
		(end 153.026618 -209.423)
		(width 0.20066)
		(layer "F.Cu")
		(net "M_E_CPU1_SB_DQS_DN<2>")
	)
	(segment
		(start 139.211812 -233.340656)
		(end 140.005816 -233.340656)
		(width 0.088646)
		(layer "F.Cu")
		(net "M_E_CPU1_SB_DQS_DN<2>")
	)
	(segment
		(start 159.643572 -209.498438)
		(end 159.361886 -209.216752)
		(width 0.20066)
		(layer "F.Cu")
		(net "M_E_CPU1_SB_DQS_DN<2>")
	)
	(segment
		(start 153.026618 -209.423)
		(end 158.071312 -209.423)
		(width 0.20066)
		(layer "F.Cu")
		(net "M_E_CPU1_SB_DQS_DN<2>")
	)
	(segment
		(start 140.332206 -233.340402)
		(end 140.363956 -233.308652)
		(width 0.088646)
		(layer "F.Cu")
		(net "M_E_CPU1_SB_DQS_DN<2>")
	)
	(segment
		(start 140.005816 -233.340656)
		(end 140.00607 -233.340402)
		(width 0.088646)
		(layer "F.Cu")
		(net "M_E_CPU1_SB_DQS_DN<2>")
	)
	(segment
		(start 136.472676 -232.957878)
		(end 136.946894 -232.683812)
		(width 0.088646)
		(layer "F.Cu")
		(net "M_E_CPU1_SB_DQS_DN<2>")
	)
	(segment
		(start 137.53973 -233.228388)
		(end 137.736326 -233.375454)
		(width 0.088646)
		(layer "F.Cu")
		(net "M_E_CPU1_SB_DQS_DN<2>")
	)
	(segment
		(start 161.925762 -209.641694)
		(end 161.896552 -209.612484)
		(width 0.1016)
		(layer "F.Cu")
		(net "M_E_CPU1_SB_DQS_DN<2>")
	)
	(segment
		(start 140.00607 -233.340402)
		(end 140.332206 -233.340402)
		(width 0.088646)
		(layer "F.Cu")
		(net "M_E_CPU1_SB_DQS_DN<2>")
	)
	(segment
		(start 137.925556 -233.448098)
		(end 138.014964 -233.448098)
		(width 0.088646)
		(layer "F.Cu")
		(net "M_E_CPU1_SB_DQS_DN<2>")
	)
	(segment
		(start 138.014964 -233.448098)
		(end 138.33983 -233.312462)
		(width 0.088646)
		(layer "F.Cu")
		(net "M_E_CPU1_SB_DQS_DN<2>")
	)
	(segment
		(start 137.169144 -232.722166)
		(end 137.28319 -232.78338)
		(width 0.088646)
		(layer "F.Cu")
		(net "M_E_CPU1_SB_DQS_DN<2>")
	)
	(segment
		(start 140.54836 -233.308652)
		(end 145.472912 -228.3841)
		(width 0.1524)
		(layer "F.Cu")
		(net "M_E_CPU1_SB_DQS_DN<2>")
	)
	(segment
		(start 164.499544 -209.895186)
		(end 164.235638 -209.63128)
		(width 0.20066)
		(layer "F.Cu")
		(net "M_E_CPU1_SB_DQS_DN<2>")
	)
	(segment
		(start 137.540492 -233.029252)
		(end 137.53973 -233.030014)
		(width 0.088646)
		(layer "F.Cu")
		(net "M_E_CPU1_SB_DQS_DN<2>")
	)
	(segment
		(start 137.736326 -233.375708)
		(end 137.925556 -233.448098)
		(width 0.088646)
		(layer "F.Cu")
		(net "M_E_CPU1_SB_DQS_DN<2>")
	)
	(segment
		(start 161.601404 -209.612484)
		(end 161.341562 -209.872326)
		(width 0.20066)
		(layer "F.Cu")
		(net "M_E_CPU1_SB_DQS_DN<2>")
	)
	(segment
		(start 163.923726 -209.63128)
		(end 163.917884 -209.63128)
		(width 0.101854)
		(layer "F.Cu")
		(net "M_E_CPU1_SB_DQS_DN<2>")
	)
	(segment
		(start 137.53973 -233.030014)
		(end 137.53973 -233.228388)
		(width 0.088646)
		(layer "F.Cu")
		(net "M_E_CPU1_SB_DQS_DN<2>")
	)
	(segment
		(start 160.511236 -209.498438)
		(end 159.643572 -209.498438)
		(width 0.20066)
		(layer "F.Cu")
		(net "M_E_CPU1_SB_DQS_DN<2>")
	)
	(segment
		(start 137.28319 -232.78338)
		(end 137.442702 -232.91419)
		(width 0.088646)
		(layer "F.Cu")
		(net "M_E_CPU1_SB_DQS_DN<2>")
	)
	(segment
		(start 160.754568 -209.74177)
		(end 160.511236 -209.498438)
		(width 0.20066)
		(layer "F.Cu")
		(net "M_E_CPU1_SB_DQS_DN<2>")
	)
	(segment
		(start 161.069528 -209.872326)
		(end 160.754568 -209.74177)
		(width 0.20066)
		(layer "F.Cu")
		(net "M_E_CPU1_SB_DQS_DN<2>")
	)
	(segment
		(start 145.610834 -216.8906)
		(end 145.610834 -216.890346)
		(width 0.1524)
		(layer "F.Cu")
		(net "M_E_CPU1_SB_DQS_DN<2>")
	)
	(segment
		(start 165.63594 -209.45729)
		(end 165.283134 -209.45729)
		(width 0.20066)
		(layer "F.Cu")
		(net "M_E_CPU1_SB_DQS_DN<2>")
	)
	(segment
		(start 145.472912 -217.028522)
		(end 145.610834 -216.8906)
		(width 0.1524)
		(layer "F.Cu")
		(net "M_E_CPU1_SB_DQS_DN<2>")
	)
	(segment
		(start 138.640058 -233.312462)
		(end 138.745722 -233.418126)
		(width 0.088646)
		(layer "F.Cu")
		(net "M_E_CPU1_SB_DQS_DN<2>")
	)
	(segment
		(start 159.361886 -209.216752)
		(end 158.813246 -209.216752)
		(width 0.20066)
		(layer "F.Cu")
		(net "M_E_CPU1_SB_DQS_DN<2>")
	)
	(segment
		(start 161.341562 -209.872326)
		(end 161.069528 -209.872326)
		(width 0.20066)
		(layer "F.Cu")
		(net "M_E_CPU1_SB_DQS_DN<2>")
	)
	(segment
		(start 163.90747 -209.641694)
		(end 161.925762 -209.641694)
		(width 0.1016)
		(layer "F.Cu")
		(net "M_E_CPU1_SB_DQS_DN<2>")
	)
	(segment
		(start 161.891726 -209.612484)
		(end 161.601404 -209.612484)
		(width 0.20066)
		(layer "F.Cu")
		(net "M_E_CPU1_SB_DQS_DN<2>")
	)
	(segment
		(start 158.071312 -209.423)
		(end 158.27756 -209.216752)
		(width 0.20066)
		(layer "F.Cu")
		(net "M_E_CPU1_SB_DQS_DN<2>")
	)
	(segment
		(start 163.917884 -209.63128)
		(end 163.90747 -209.641694)
		(width 0.1016)
		(layer "F.Cu")
		(net "M_E_CPU1_SB_DQS_DN<2>")
	)
	(arc
		(start 136.946894 -232.683812)
		(mid 137.021492 -232.681693)
		(end 137.095484 -232.691432)
		(width 0.088646)
		(layer "F.Cu")
		(net "M_E_CPU1_SB_DQS_DN<2>")
	)
	(arc
		(start 136.075166 -233.064304)
		(mid 136.280935 -233.037296)
		(end 136.472676 -232.957878)
		(width 0.088646)
		(layer "F.Cu")
		(net "M_E_CPU1_SB_DQS_DN<2>")
	)
	(segment
		(start 142.206472 -237.238286)
		(end 149.384512 -230.060246)
		(width 0.1524)
		(layer "F.Cu")
		(net "M_E_CPU1_SB_DQS_DN<1>")
	)
	(segment
		(start 153.895044 -224.625662)
		(end 153.895044 -222.346774)
		(width 0.20066)
		(layer "F.Cu")
		(net "M_E_CPU1_SB_DQS_DN<1>")
	)
	(segment
		(start 165.194742 -218.807284)
		(end 164.799772 -219.202254)
		(width 0.20066)
		(layer "F.Cu")
		(net "M_E_CPU1_SB_DQS_DN<1>")
	)
	(segment
		(start 139.586462 -238.197644)
		(end 140.228066 -237.556294)
		(width 0.088646)
		(layer "F.Cu")
		(net "M_E_CPU1_SB_DQS_DN<1>")
	)
	(segment
		(start 165.527228 -218.807284)
		(end 165.194742 -218.807284)
		(width 0.20066)
		(layer "F.Cu")
		(net "M_E_CPU1_SB_DQS_DN<1>")
	)
	(segment
		(start 149.384512 -230.060246)
		(end 149.384512 -229.18801)
		(width 0.1524)
		(layer "F.Cu")
		(net "M_E_CPU1_SB_DQS_DN<1>")
	)
	(segment
		(start 140.515594 -237.26902)
		(end 140.728954 -237.26902)
		(width 0.088646)
		(layer "F.Cu")
		(net "M_E_CPU1_SB_DQS_DN<1>")
	)
	(segment
		(start 163.923726 -218.974924)
		(end 163.906962 -218.991688)
		(width 0.1016)
		(layer "F.Cu")
		(net "M_E_CPU1_SB_DQS_DN<1>")
	)
	(segment
		(start 138.883136 -238.3028)
		(end 139.200636 -238.3028)
		(width 0.088646)
		(layer "F.Cu")
		(net "M_E_CPU1_SB_DQS_DN<1>")
	)
	(segment
		(start 137.24763 -237.66907)
		(end 137.289286 -237.703614)
		(width 0.088646)
		(layer "F.Cu")
		(net "M_E_CPU1_SB_DQS_DN<1>")
	)
	(segment
		(start 157.834076 -218.566238)
		(end 157.834584 -218.566746)
		(width 0.20066)
		(layer "F.Cu")
		(net "M_E_CPU1_SB_DQS_DN<1>")
	)
	(segment
		(start 140.728954 -237.26902)
		(end 140.759688 -237.238286)
		(width 0.088646)
		(layer "F.Cu")
		(net "M_E_CPU1_SB_DQS_DN<1>")
	)
	(segment
		(start 160.316418 -218.848432)
		(end 159.643572 -218.848432)
		(width 0.20066)
		(layer "F.Cu")
		(net "M_E_CPU1_SB_DQS_DN<1>")
	)
	(segment
		(start 157.834584 -218.566746)
		(end 158.813246 -218.566746)
		(width 0.20066)
		(layer "F.Cu")
		(net "M_E_CPU1_SB_DQS_DN<1>")
	)
	(segment
		(start 150.20163 -228.319076)
		(end 153.895044 -224.625662)
		(width 0.20066)
		(layer "F.Cu")
		(net "M_E_CPU1_SB_DQS_DN<1>")
	)
	(segment
		(start 139.555982 -238.212884)
		(end 139.571222 -238.20501)
		(width 0.088646)
		(layer "F.Cu")
		(net "M_E_CPU1_SB_DQS_DN<1>")
	)
	(segment
		(start 164.799772 -219.202254)
		(end 164.515546 -219.202254)
		(width 0.20066)
		(layer "F.Cu")
		(net "M_E_CPU1_SB_DQS_DN<1>")
	)
	(segment
		(start 164.288216 -218.974924)
		(end 163.923726 -218.974924)
		(width 0.20066)
		(layer "F.Cu")
		(net "M_E_CPU1_SB_DQS_DN<1>")
	)
	(segment
		(start 137.302494 -237.717584)
		(end 137.409428 -237.860586)
		(width 0.088646)
		(layer "F.Cu")
		(net "M_E_CPU1_SB_DQS_DN<1>")
	)
	(segment
		(start 156.49829 -219.743528)
		(end 156.49829 -219.046298)
		(width 0.20066)
		(layer "F.Cu")
		(net "M_E_CPU1_SB_DQS_DN<1>")
	)
	(segment
		(start 159.361886 -218.566746)
		(end 158.813246 -218.566746)
		(width 0.20066)
		(layer "F.Cu")
		(net "M_E_CPU1_SB_DQS_DN<1>")
	)
	(segment
		(start 137.40892 -237.86084)
		(end 137.517632 -238.006636)
		(width 0.088646)
		(layer "F.Cu")
		(net "M_E_CPU1_SB_DQS_DN<1>")
	)
	(segment
		(start 161.15665 -219.26296)
		(end 160.730946 -219.26296)
		(width 0.20066)
		(layer "F.Cu")
		(net "M_E_CPU1_SB_DQS_DN<1>")
	)
	(segment
		(start 150.174706 -228.397816)
		(end 150.174706 -228.346)
		(width 0.1524)
		(layer "F.Cu")
		(net "M_E_CPU1_SB_DQS_DN<1>")
	)
	(segment
		(start 137.517632 -238.006636)
		(end 137.700004 -238.205772)
		(width 0.088646)
		(layer "F.Cu")
		(net "M_E_CPU1_SB_DQS_DN<1>")
	)
	(segment
		(start 165.767766 -218.566746)
		(end 165.527228 -218.807284)
		(width 0.20066)
		(layer "F.Cu")
		(net "M_E_CPU1_SB_DQS_DN<1>")
	)
	(segment
		(start 138.190478 -238.243618)
		(end 138.190732 -238.243618)
		(width 0.088646)
		(layer "F.Cu")
		(net "M_E_CPU1_SB_DQS_DN<1>")
	)
	(segment
		(start 138.141964 -238.271812)
		(end 138.190478 -238.243618)
		(width 0.088646)
		(layer "F.Cu")
		(net "M_E_CPU1_SB_DQS_DN<1>")
	)
	(segment
		(start 149.384512 -229.18801)
		(end 150.174706 -228.397816)
		(width 0.1524)
		(layer "F.Cu")
		(net "M_E_CPU1_SB_DQS_DN<1>")
	)
	(segment
		(start 161.454846 -218.964764)
		(end 161.15665 -219.26296)
		(width 0.20066)
		(layer "F.Cu")
		(net "M_E_CPU1_SB_DQS_DN<1>")
	)
	(segment
		(start 153.895044 -222.346774)
		(end 156.49829 -219.743528)
		(width 0.20066)
		(layer "F.Cu")
		(net "M_E_CPU1_SB_DQS_DN<1>")
	)
	(segment
		(start 140.759688 -237.238286)
		(end 142.206472 -237.238286)
		(width 0.1524)
		(layer "F.Cu")
		(net "M_E_CPU1_SB_DQS_DN<1>")
	)
	(segment
		(start 163.906962 -218.991688)
		(end 161.91865 -218.991688)
		(width 0.1016)
		(layer "F.Cu")
		(net "M_E_CPU1_SB_DQS_DN<1>")
	)
	(segment
		(start 156.97835 -218.566238)
		(end 157.834076 -218.566238)
		(width 0.20066)
		(layer "F.Cu")
		(net "M_E_CPU1_SB_DQS_DN<1>")
	)
	(segment
		(start 164.515546 -219.202254)
		(end 164.288216 -218.974924)
		(width 0.20066)
		(layer "F.Cu")
		(net "M_E_CPU1_SB_DQS_DN<1>")
	)
	(segment
		(start 139.571222 -238.20501)
		(end 139.586208 -238.197644)
		(width 0.088646)
		(layer "F.Cu")
		(net "M_E_CPU1_SB_DQS_DN<1>")
	)
	(segment
		(start 140.228066 -237.556294)
		(end 140.228066 -237.556548)
		(width 0.088646)
		(layer "F.Cu")
		(net "M_E_CPU1_SB_DQS_DN<1>")
	)
	(segment
		(start 139.200636 -238.3028)
		(end 139.432284 -238.265208)
		(width 0.088646)
		(layer "F.Cu")
		(net "M_E_CPU1_SB_DQS_DN<1>")
	)
	(segment
		(start 161.91865 -218.991688)
		(end 161.891726 -218.964764)
		(width 0.1016)
		(layer "F.Cu")
		(net "M_E_CPU1_SB_DQS_DN<1>")
	)
	(segment
		(start 140.228066 -237.556548)
		(end 140.515594 -237.26902)
		(width 0.088646)
		(layer "F.Cu")
		(net "M_E_CPU1_SB_DQS_DN<1>")
	)
	(segment
		(start 136.075166 -237.947454)
		(end 136.73074 -237.64621)
		(width 0.088646)
		(layer "F.Cu")
		(net "M_E_CPU1_SB_DQS_DN<1>")
	)
	(segment
		(start 156.49829 -219.046298)
		(end 156.97835 -218.566238)
		(width 0.20066)
		(layer "F.Cu")
		(net "M_E_CPU1_SB_DQS_DN<1>")
	)
	(segment
		(start 137.700004 -238.205772)
		(end 137.783316 -238.280194)
		(width 0.088646)
		(layer "F.Cu")
		(net "M_E_CPU1_SB_DQS_DN<1>")
	)
	(segment
		(start 161.891726 -218.964764)
		(end 161.454846 -218.964764)
		(width 0.20066)
		(layer "F.Cu")
		(net "M_E_CPU1_SB_DQS_DN<1>")
	)
	(segment
		(start 159.643572 -218.848432)
		(end 159.361886 -218.566746)
		(width 0.20066)
		(layer "F.Cu")
		(net "M_E_CPU1_SB_DQS_DN<1>")
	)
	(segment
		(start 139.586208 -238.197644)
		(end 139.586462 -238.197644)
		(width 0.088646)
		(layer "F.Cu")
		(net "M_E_CPU1_SB_DQS_DN<1>")
	)
	(segment
		(start 160.730946 -219.26296)
		(end 160.316418 -218.848432)
		(width 0.20066)
		(layer "F.Cu")
		(net "M_E_CPU1_SB_DQS_DN<1>")
	)
	(segment
		(start 150.174706 -228.346)
		(end 150.20163 -228.319076)
		(width 0.1524)
		(layer "F.Cu")
		(net "M_E_CPU1_SB_DQS_DN<1>")
	)
	(segment
		(start 138.190732 -238.243618)
		(end 138.195558 -238.241586)
		(width 0.088646)
		(layer "F.Cu")
		(net "M_E_CPU1_SB_DQS_DN<1>")
	)
	(segment
		(start 166.357046 -218.566746)
		(end 165.767766 -218.566746)
		(width 0.20066)
		(layer "F.Cu")
		(net "M_E_CPU1_SB_DQS_DN<1>")
	)
	(segment
		(start 137.409428 -237.860586)
		(end 137.40892 -237.86084)
		(width 0.088646)
		(layer "F.Cu")
		(net "M_E_CPU1_SB_DQS_DN<1>")
	)
	(arc
		(start 138.654028 -238.241332)
		(mid 138.764536 -238.287152)
		(end 138.883136 -238.3028)
		(width 0.088646)
		(layer "F.Cu")
		(net "M_E_CPU1_SB_DQS_DN<1>")
	)
	(arc
		(start 136.73074 -237.64621)
		(mid 136.884486 -237.596645)
		(end 137.0457 -237.58652)
		(width 0.088646)
		(layer "F.Cu")
		(net "M_E_CPU1_SB_DQS_DN<1>")
	)
	(arc
		(start 138.195558 -238.241586)
		(mid 138.424747 -238.180127)
		(end 138.654028 -238.241332)
		(width 0.088646)
		(layer "F.Cu")
		(net "M_E_CPU1_SB_DQS_DN<1>")
	)
	(arc
		(start 139.432284 -238.265208)
		(mid 139.494975 -238.241037)
		(end 139.555982 -238.212884)
		(width 0.088646)
		(layer "F.Cu")
		(net "M_E_CPU1_SB_DQS_DN<1>")
	)
	(arc
		(start 137.289286 -237.703614)
		(mid 137.296307 -237.710205)
		(end 137.302494 -237.717584)
		(width 0.088646)
		(layer "F.Cu")
		(net "M_E_CPU1_SB_DQS_DN<1>")
	)
	(arc
		(start 137.0457 -237.58652)
		(mid 137.153028 -237.61223)
		(end 137.24763 -237.66907)
		(width 0.088646)
		(layer "F.Cu")
		(net "M_E_CPU1_SB_DQS_DN<1>")
	)
	(arc
		(start 137.783316 -238.280194)
		(mid 137.963717 -238.321783)
		(end 138.141964 -238.271812)
		(width 0.088646)
		(layer "F.Cu")
		(net "M_E_CPU1_SB_DQS_DN<1>")
	)
	(segment
		(start 165.180518 -228.164898)
		(end 164.72154 -228.623876)
		(width 0.20066)
		(layer "F.Cu")
		(net "M_E_CPU1_SB_DQS_DN<0>")
	)
	(segment
		(start 161.706814 -228.341682)
		(end 161.696146 -228.341682)
		(width 0.101854)
		(layer "F.Cu")
		(net "M_E_CPU1_SB_DQS_DN<0>")
	)
	(segment
		(start 164.492686 -228.623876)
		(end 164.186362 -228.317552)
		(width 0.20066)
		(layer "F.Cu")
		(net "M_E_CPU1_SB_DQS_DN<0>")
	)
	(segment
		(start 161.696146 -228.341682)
		(end 161.586926 -228.341682)
		(width 0.20066)
		(layer "F.Cu")
		(net "M_E_CPU1_SB_DQS_DN<0>")
	)
	(segment
		(start 166.357046 -227.91674)
		(end 165.767766 -227.91674)
		(width 0.20066)
		(layer "F.Cu")
		(net "M_E_CPU1_SB_DQS_DN<0>")
	)
	(segment
		(start 160.34766 -228.198426)
		(end 159.643572 -228.198426)
		(width 0.20066)
		(layer "F.Cu")
		(net "M_E_CPU1_SB_DQS_DN<0>")
	)
	(segment
		(start 165.767766 -227.91674)
		(end 165.519608 -228.164898)
		(width 0.20066)
		(layer "F.Cu")
		(net "M_E_CPU1_SB_DQS_DN<0>")
	)
	(segment
		(start 161.586926 -228.341682)
		(end 161.315654 -228.612954)
		(width 0.20066)
		(layer "F.Cu")
		(net "M_E_CPU1_SB_DQS_DN<0>")
	)
	(segment
		(start 163.90493 -228.317552)
		(end 163.8808 -228.341682)
		(width 0.1016)
		(layer "F.Cu")
		(net "M_E_CPU1_SB_DQS_DN<0>")
	)
	(segment
		(start 133.725666 -235.506006)
		(end 133.725666 -234.970066)
		(width 0.20066)
		(layer "F.Cu")
		(net "M_E_CPU1_SB_DQS_DN<0>")
	)
	(segment
		(start 165.519608 -228.164898)
		(end 165.180518 -228.164898)
		(width 0.20066)
		(layer "F.Cu")
		(net "M_E_CPU1_SB_DQS_DN<0>")
	)
	(segment
		(start 159.361886 -227.91674)
		(end 158.813246 -227.91674)
		(width 0.20066)
		(layer "F.Cu")
		(net "M_E_CPU1_SB_DQS_DN<0>")
	)
	(segment
		(start 160.762188 -228.612954)
		(end 160.34766 -228.198426)
		(width 0.20066)
		(layer "F.Cu")
		(net "M_E_CPU1_SB_DQS_DN<0>")
	)
	(segment
		(start 164.186362 -228.317552)
		(end 163.923726 -228.317552)
		(width 0.20066)
		(layer "F.Cu")
		(net "M_E_CPU1_SB_DQS_DN<0>")
	)
	(segment
		(start 161.315654 -228.612954)
		(end 160.762188 -228.612954)
		(width 0.20066)
		(layer "F.Cu")
		(net "M_E_CPU1_SB_DQS_DN<0>")
	)
	(segment
		(start 157.682946 -227.91674)
		(end 158.813246 -227.91674)
		(width 0.20066)
		(layer "F.Cu")
		(net "M_E_CPU1_SB_DQS_DN<0>")
	)
	(segment
		(start 159.643572 -228.198426)
		(end 159.361886 -227.91674)
		(width 0.20066)
		(layer "F.Cu")
		(net "M_E_CPU1_SB_DQS_DN<0>")
	)
	(segment
		(start 163.8808 -228.341682)
		(end 161.706814 -228.341682)
		(width 0.1016)
		(layer "F.Cu")
		(net "M_E_CPU1_SB_DQS_DN<0>")
	)
	(segment
		(start 164.72154 -228.623876)
		(end 164.492686 -228.623876)
		(width 0.20066)
		(layer "F.Cu")
		(net "M_E_CPU1_SB_DQS_DN<0>")
	)
	(segment
		(start 163.923726 -228.317552)
		(end 163.90493 -228.317552)
		(width 0.101854)
		(layer "F.Cu")
		(net "M_E_CPU1_SB_DQS_DN<0>")
	)
	(segment
		(start 154.502612 -230.074216)
		(end 154.114754 -230.462074)
		(width 0.18288)
		(layer "In2.Cu")
		(net "M_E_CPU1_SB_DQS_DN<0>")
	)
	(segment
		(start 140.696696 -234.857544)
		(end 140.637006 -234.917234)
		(width 0.088646)
		(layer "In2.Cu")
		(net "M_E_CPU1_SB_DQS_DN<0>")
	)
	(segment
		(start 155.454604 -229.122224)
		(end 155.066746 -229.510082)
		(width 0.18288)
		(layer "In2.Cu")
		(net "M_E_CPU1_SB_DQS_DN<0>")
	)
	(segment
		(start 148.710142 -234.857544)
		(end 140.696696 -234.857544)
		(width 0.18288)
		(layer "In2.Cu")
		(net "M_E_CPU1_SB_DQS_DN<0>")
	)
	(segment
		(start 150.43277 -234.143804)
		(end 148.710142 -234.857544)
		(width 0.18288)
		(layer "In2.Cu")
		(net "M_E_CPU1_SB_DQS_DN<0>")
	)
	(segment
		(start 133.355588 -235.027216)
		(end 133.412738 -234.970066)
		(width 0.088646)
		(layer "In2.Cu")
		(net "M_E_CPU1_SB_DQS_DN<0>")
	)
	(segment
		(start 153.938732 -230.462074)
		(end 153.55062 -230.850186)
		(width 0.18288)
		(layer "In2.Cu")
		(net "M_E_CPU1_SB_DQS_DN<0>")
	)
	(segment
		(start 140.045948 -234.917234)
		(end 139.618212 -235.34497)
		(width 0.088646)
		(layer "In2.Cu")
		(net "M_E_CPU1_SB_DQS_DN<0>")
	)
	(segment
		(start 155.454604 -228.946202)
		(end 155.454604 -229.122224)
		(width 0.18288)
		(layer "In2.Cu")
		(net "M_E_CPU1_SB_DQS_DN<0>")
	)
	(segment
		(start 154.890724 -229.510082)
		(end 154.502612 -229.898194)
		(width 0.18288)
		(layer "In2.Cu")
		(net "M_E_CPU1_SB_DQS_DN<0>")
	)
	(segment
		(start 156.018738 -228.55809)
		(end 155.842716 -228.55809)
		(width 0.18288)
		(layer "In2.Cu")
		(net "M_E_CPU1_SB_DQS_DN<0>")
	)
	(segment
		(start 137.297414 -235.294424)
		(end 137.282682 -235.285788)
		(width 0.088646)
		(layer "In2.Cu")
		(net "M_E_CPU1_SB_DQS_DN<0>")
	)
	(segment
		(start 154.502612 -229.898194)
		(end 154.502612 -230.074216)
		(width 0.18288)
		(layer "In2.Cu")
		(net "M_E_CPU1_SB_DQS_DN<0>")
	)
	(segment
		(start 139.618212 -235.34497)
		(end 139.364212 -235.34497)
		(width 0.088646)
		(layer "In2.Cu")
		(net "M_E_CPU1_SB_DQS_DN<0>")
	)
	(segment
		(start 154.114754 -230.462074)
		(end 153.938732 -230.462074)
		(width 0.18288)
		(layer "In2.Cu")
		(net "M_E_CPU1_SB_DQS_DN<0>")
	)
	(segment
		(start 155.066746 -229.510082)
		(end 154.890724 -229.510082)
		(width 0.18288)
		(layer "In2.Cu")
		(net "M_E_CPU1_SB_DQS_DN<0>")
	)
	(segment
		(start 136.357614 -235.294424)
		(end 136.3472 -235.288328)
		(width 0.088646)
		(layer "In2.Cu")
		(net "M_E_CPU1_SB_DQS_DN<0>")
	)
	(segment
		(start 157.682946 -227.91674)
		(end 157.429454 -228.170232)
		(width 0.18288)
		(layer "In2.Cu")
		(net "M_E_CPU1_SB_DQS_DN<0>")
	)
	(segment
		(start 155.842716 -228.55809)
		(end 155.454604 -228.946202)
		(width 0.18288)
		(layer "In2.Cu")
		(net "M_E_CPU1_SB_DQS_DN<0>")
	)
	(segment
		(start 156.406596 -228.170232)
		(end 156.018738 -228.55809)
		(width 0.18288)
		(layer "In2.Cu")
		(net "M_E_CPU1_SB_DQS_DN<0>")
	)
	(segment
		(start 133.538468 -235.294424)
		(end 133.529578 -235.289344)
		(width 0.088646)
		(layer "In2.Cu")
		(net "M_E_CPU1_SB_DQS_DN<0>")
	)
	(segment
		(start 138.237214 -235.294424)
		(end 138.222482 -235.285788)
		(width 0.088646)
		(layer "In2.Cu")
		(net "M_E_CPU1_SB_DQS_DN<0>")
	)
	(segment
		(start 157.429454 -228.170232)
		(end 156.406596 -228.170232)
		(width 0.18288)
		(layer "In2.Cu")
		(net "M_E_CPU1_SB_DQS_DN<0>")
	)
	(segment
		(start 153.55062 -231.026208)
		(end 150.43277 -234.143804)
		(width 0.18288)
		(layer "In2.Cu")
		(net "M_E_CPU1_SB_DQS_DN<0>")
	)
	(segment
		(start 133.412738 -234.970066)
		(end 133.725666 -234.970066)
		(width 0.088646)
		(layer "In2.Cu")
		(net "M_E_CPU1_SB_DQS_DN<0>")
	)
	(segment
		(start 153.55062 -230.850186)
		(end 153.55062 -231.026208)
		(width 0.18288)
		(layer "In2.Cu")
		(net "M_E_CPU1_SB_DQS_DN<0>")
	)
	(segment
		(start 140.637006 -234.917234)
		(end 140.045948 -234.917234)
		(width 0.088646)
		(layer "In2.Cu")
		(net "M_E_CPU1_SB_DQS_DN<0>")
	)
	(arc
		(start 134.478268 -235.294424)
		(mid 134.195566 -235.218648)
		(end 133.912864 -235.294424)
		(width 0.088646)
		(layer "In2.Cu")
		(net "M_E_CPU1_SB_DQS_DN<0>")
	)
	(arc
		(start 137.282682 -235.285788)
		(mid 137.006207 -235.218468)
		(end 136.73201 -235.294424)
		(width 0.088646)
		(layer "In2.Cu")
		(net "M_E_CPU1_SB_DQS_DN<0>")
	)
	(arc
		(start 139.364212 -235.34497)
		(mid 139.267164 -235.332191)
		(end 139.17676 -235.294678)
		(width 0.088646)
		(layer "In2.Cu")
		(net "M_E_CPU1_SB_DQS_DN<0>")
	)
	(arc
		(start 136.73201 -235.294424)
		(mid 136.544812 -235.344567)
		(end 136.357614 -235.294424)
		(width 0.088646)
		(layer "In2.Cu")
		(net "M_E_CPU1_SB_DQS_DN<0>")
	)
	(arc
		(start 136.3472 -235.288328)
		(mid 136.069022 -235.218605)
		(end 135.792464 -235.294424)
		(width 0.088646)
		(layer "In2.Cu")
		(net "M_E_CPU1_SB_DQS_DN<0>")
	)
	(arc
		(start 133.912864 -235.294424)
		(mid 133.725666 -235.344567)
		(end 133.538468 -235.294424)
		(width 0.088646)
		(layer "In2.Cu")
		(net "M_E_CPU1_SB_DQS_DN<0>")
	)
	(arc
		(start 135.792464 -235.294424)
		(mid 135.605266 -235.344567)
		(end 135.418068 -235.294424)
		(width 0.088646)
		(layer "In2.Cu")
		(net "M_E_CPU1_SB_DQS_DN<0>")
	)
	(arc
		(start 139.17676 -235.294678)
		(mid 139.169472 -235.290314)
		(end 139.162282 -235.285788)
		(width 0.088646)
		(layer "In2.Cu")
		(net "M_E_CPU1_SB_DQS_DN<0>")
	)
	(arc
		(start 134.852664 -235.294424)
		(mid 134.665466 -235.344567)
		(end 134.478268 -235.294424)
		(width 0.088646)
		(layer "In2.Cu")
		(net "M_E_CPU1_SB_DQS_DN<0>")
	)
	(arc
		(start 137.67181 -235.294424)
		(mid 137.484612 -235.344567)
		(end 137.297414 -235.294424)
		(width 0.088646)
		(layer "In2.Cu")
		(net "M_E_CPU1_SB_DQS_DN<0>")
	)
	(arc
		(start 138.222482 -235.285788)
		(mid 137.946007 -235.218468)
		(end 137.67181 -235.294424)
		(width 0.088646)
		(layer "In2.Cu")
		(net "M_E_CPU1_SB_DQS_DN<0>")
	)
	(arc
		(start 139.162282 -235.285788)
		(mid 138.885807 -235.218468)
		(end 138.61161 -235.294424)
		(width 0.088646)
		(layer "In2.Cu")
		(net "M_E_CPU1_SB_DQS_DN<0>")
	)
	(arc
		(start 133.529578 -235.289344)
		(mid 133.413769 -235.177415)
		(end 133.355588 -235.027216)
		(width 0.088646)
		(layer "In2.Cu")
		(net "M_E_CPU1_SB_DQS_DN<0>")
	)
	(arc
		(start 135.418068 -235.294424)
		(mid 135.135366 -235.218648)
		(end 134.852664 -235.294424)
		(width 0.088646)
		(layer "In2.Cu")
		(net "M_E_CPU1_SB_DQS_DN<0>")
	)
	(arc
		(start 138.61161 -235.294424)
		(mid 138.424412 -235.344567)
		(end 138.237214 -235.294424)
		(width 0.088646)
		(layer "In2.Cu")
		(net "M_E_CPU1_SB_DQS_DN<0>")
	)
	(segment
		(start 155.810204 -223.105726)
		(end 157.56509 -221.35084)
		(width 0.20066)
		(layer "F.Cu")
		(net "M_E_CPU1_SB_DQ<9>")
	)
	(segment
		(start 163.923726 -220.676978)
		(end 163.907978 -220.676978)
		(width 0.101854)
		(layer "F.Cu")
		(net "M_E_CPU1_SB_DQ<9>")
	)
	(segment
		(start 142.575534 -238.127286)
		(end 150.61184 -230.091996)
		(width 0.1016)
		(layer "F.Cu")
		(net "M_E_CPU1_SB_DQ<9>")
	)
	(segment
		(start 138.609324 -239.088168)
		(end 138.741658 -239.01019)
		(width 0.088646)
		(layer "F.Cu")
		(net "M_E_CPU1_SB_DQ<9>")
	)
	(segment
		(start 155.26004 -230.03891)
		(end 155.473908 -229.825042)
		(width 0.20066)
		(layer "F.Cu")
		(net "M_E_CPU1_SB_DQ<9>")
	)
	(segment
		(start 161.031682 -221.152466)
		(end 160.81121 -221.372938)
		(width 0.20066)
		(layer "F.Cu")
		(net "M_E_CPU1_SB_DQ<9>")
	)
	(segment
		(start 140.950696 -238.127286)
		(end 142.575534 -238.127286)
		(width 0.1016)
		(layer "F.Cu")
		(net "M_E_CPU1_SB_DQ<9>")
	)
	(segment
		(start 155.273248 -229.339902)
		(end 154.222196 -229.339902)
		(width 0.20066)
		(layer "F.Cu")
		(net "M_E_CPU1_SB_DQ<9>")
	)
	(segment
		(start 136.546336 -239.04956)
		(end 136.635236 -239.13846)
		(width 0.088646)
		(layer "F.Cu")
		(net "M_E_CPU1_SB_DQ<9>")
	)
	(segment
		(start 137.889996 -238.968026)
		(end 138.067542 -238.968026)
		(width 0.088646)
		(layer "F.Cu")
		(net "M_E_CPU1_SB_DQ<9>")
	)
	(segment
		(start 138.15949 -239.059974)
		(end 138.263122 -239.100614)
		(width 0.088646)
		(layer "F.Cu")
		(net "M_E_CPU1_SB_DQ<9>")
	)
	(segment
		(start 136.635236 -239.13846)
		(end 136.779762 -239.13846)
		(width 0.088646)
		(layer "F.Cu")
		(net "M_E_CPU1_SB_DQ<9>")
	)
	(segment
		(start 138.427206 -239.136174)
		(end 138.607292 -239.089184)
		(width 0.088646)
		(layer "F.Cu")
		(net "M_E_CPU1_SB_DQ<9>")
	)
	(segment
		(start 139.934188 -239.01019)
		(end 140.817092 -238.127286)
		(width 0.088646)
		(layer "F.Cu")
		(net "M_E_CPU1_SB_DQ<9>")
	)
	(segment
		(start 157.56509 -221.35084)
		(end 157.716474 -221.35084)
		(width 0.20066)
		(layer "F.Cu")
		(net "M_E_CPU1_SB_DQ<9>")
	)
	(segment
		(start 161.896552 -220.683074)
		(end 161.891726 -220.683074)
		(width 0.101854)
		(layer "F.Cu")
		(net "M_E_CPU1_SB_DQ<9>")
	)
	(segment
		(start 137.363962 -239.222026)
		(end 137.635996 -239.222026)
		(width 0.088646)
		(layer "F.Cu")
		(net "M_E_CPU1_SB_DQ<9>")
	)
	(segment
		(start 154.021536 -229.139242)
		(end 154.021536 -228.854762)
		(width 0.20066)
		(layer "F.Cu")
		(net "M_E_CPU1_SB_DQ<9>")
	)
	(segment
		(start 154.222196 -229.339902)
		(end 154.021536 -229.139242)
		(width 0.20066)
		(layer "F.Cu")
		(net "M_E_CPU1_SB_DQ<9>")
	)
	(segment
		(start 151.237442 -230.03891)
		(end 155.26004 -230.03891)
		(width 0.20066)
		(layer "F.Cu")
		(net "M_E_CPU1_SB_DQ<9>")
	)
	(segment
		(start 138.607292 -239.089184)
		(end 138.609324 -239.088168)
		(width 0.088646)
		(layer "F.Cu")
		(net "M_E_CPU1_SB_DQ<9>")
	)
	(segment
		(start 161.031682 -220.83268)
		(end 161.031682 -221.152466)
		(width 0.20066)
		(layer "F.Cu")
		(net "M_E_CPU1_SB_DQ<9>")
	)
	(segment
		(start 166.357046 -221.116652)
		(end 164.638482 -221.116652)
		(width 0.20066)
		(layer "F.Cu")
		(net "M_E_CPU1_SB_DQ<9>")
	)
	(segment
		(start 161.181288 -220.683074)
		(end 161.031682 -220.83268)
		(width 0.20066)
		(layer "F.Cu")
		(net "M_E_CPU1_SB_DQ<9>")
	)
	(segment
		(start 138.263122 -239.100614)
		(end 138.27887 -239.106456)
		(width 0.088646)
		(layer "F.Cu")
		(net "M_E_CPU1_SB_DQ<9>")
	)
	(segment
		(start 161.891726 -220.683074)
		(end 161.181288 -220.683074)
		(width 0.20066)
		(layer "F.Cu")
		(net "M_E_CPU1_SB_DQ<9>")
	)
	(segment
		(start 138.067542 -238.968026)
		(end 138.15949 -239.059974)
		(width 0.088646)
		(layer "F.Cu")
		(net "M_E_CPU1_SB_DQ<9>")
	)
	(segment
		(start 155.810204 -228.453442)
		(end 155.810204 -223.105726)
		(width 0.20066)
		(layer "F.Cu")
		(net "M_E_CPU1_SB_DQ<9>")
	)
	(segment
		(start 137.135362 -238.993426)
		(end 137.363962 -239.222026)
		(width 0.088646)
		(layer "F.Cu")
		(net "M_E_CPU1_SB_DQ<9>")
	)
	(segment
		(start 155.473908 -229.540562)
		(end 155.273248 -229.339902)
		(width 0.20066)
		(layer "F.Cu")
		(net "M_E_CPU1_SB_DQ<9>")
	)
	(segment
		(start 136.779762 -239.13846)
		(end 136.924796 -238.993426)
		(width 0.088646)
		(layer "F.Cu")
		(net "M_E_CPU1_SB_DQ<9>")
	)
	(segment
		(start 136.545066 -238.761524)
		(end 136.545066 -239.046512)
		(width 0.088646)
		(layer "F.Cu")
		(net "M_E_CPU1_SB_DQ<9>")
	)
	(segment
		(start 138.291824 -239.111282)
		(end 138.423904 -239.136174)
		(width 0.088646)
		(layer "F.Cu")
		(net "M_E_CPU1_SB_DQ<9>")
	)
	(segment
		(start 138.27887 -239.106456)
		(end 138.279632 -239.10671)
		(width 0.088646)
		(layer "F.Cu")
		(net "M_E_CPU1_SB_DQ<9>")
	)
	(segment
		(start 154.021536 -228.854762)
		(end 154.222196 -228.654102)
		(width 0.20066)
		(layer "F.Cu")
		(net "M_E_CPU1_SB_DQ<9>")
	)
	(segment
		(start 164.638482 -221.116652)
		(end 164.198808 -220.676978)
		(width 0.20066)
		(layer "F.Cu")
		(net "M_E_CPU1_SB_DQ<9>")
	)
	(segment
		(start 154.222196 -228.654102)
		(end 155.609544 -228.654102)
		(width 0.20066)
		(layer "F.Cu")
		(net "M_E_CPU1_SB_DQ<9>")
	)
	(segment
		(start 164.198808 -220.676978)
		(end 163.923726 -220.676978)
		(width 0.20066)
		(layer "F.Cu")
		(net "M_E_CPU1_SB_DQ<9>")
	)
	(segment
		(start 157.950662 -221.116652)
		(end 158.813246 -221.116652)
		(width 0.20066)
		(layer "F.Cu")
		(net "M_E_CPU1_SB_DQ<9>")
	)
	(segment
		(start 161.905188 -220.69171)
		(end 161.896552 -220.683074)
		(width 0.1016)
		(layer "F.Cu")
		(net "M_E_CPU1_SB_DQ<9>")
	)
	(segment
		(start 159.717486 -221.116652)
		(end 158.813246 -221.116652)
		(width 0.20066)
		(layer "F.Cu")
		(net "M_E_CPU1_SB_DQ<9>")
	)
	(segment
		(start 155.609544 -228.654102)
		(end 155.810204 -228.453442)
		(width 0.20066)
		(layer "F.Cu")
		(net "M_E_CPU1_SB_DQ<9>")
	)
	(segment
		(start 136.924796 -238.993426)
		(end 137.135362 -238.993426)
		(width 0.088646)
		(layer "F.Cu")
		(net "M_E_CPU1_SB_DQ<9>")
	)
	(segment
		(start 138.741658 -239.01019)
		(end 139.934188 -239.01019)
		(width 0.088646)
		(layer "F.Cu")
		(net "M_E_CPU1_SB_DQ<9>")
	)
	(segment
		(start 163.893246 -220.69171)
		(end 161.905188 -220.69171)
		(width 0.1016)
		(layer "F.Cu")
		(net "M_E_CPU1_SB_DQ<9>")
	)
	(segment
		(start 163.907978 -220.676978)
		(end 163.893246 -220.69171)
		(width 0.101854)
		(layer "F.Cu")
		(net "M_E_CPU1_SB_DQ<9>")
	)
	(segment
		(start 137.635996 -239.222026)
		(end 137.889996 -238.968026)
		(width 0.088646)
		(layer "F.Cu")
		(net "M_E_CPU1_SB_DQ<9>")
	)
	(segment
		(start 159.973772 -221.372938)
		(end 159.717486 -221.116652)
		(width 0.20066)
		(layer "F.Cu")
		(net "M_E_CPU1_SB_DQ<9>")
	)
	(segment
		(start 150.61184 -230.091996)
		(end 150.664926 -230.03891)
		(width 0.1016)
		(layer "F.Cu")
		(net "M_E_CPU1_SB_DQ<9>")
	)
	(segment
		(start 138.279632 -239.10671)
		(end 138.291824 -239.111282)
		(width 0.088646)
		(layer "F.Cu")
		(net "M_E_CPU1_SB_DQ<9>")
	)
	(segment
		(start 157.716474 -221.35084)
		(end 157.950662 -221.116652)
		(width 0.20066)
		(layer "F.Cu")
		(net "M_E_CPU1_SB_DQ<9>")
	)
	(segment
		(start 138.423904 -239.136174)
		(end 138.427206 -239.136174)
		(width 0.088646)
		(layer "F.Cu")
		(net "M_E_CPU1_SB_DQ<9>")
	)
	(segment
		(start 140.817092 -238.127286)
		(end 140.950696 -238.127286)
		(width 0.088646)
		(layer "F.Cu")
		(net "M_E_CPU1_SB_DQ<9>")
	)
	(segment
		(start 150.664926 -230.03891)
		(end 151.237442 -230.03891)
		(width 0.1016)
		(layer "F.Cu")
		(net "M_E_CPU1_SB_DQ<9>")
	)
	(segment
		(start 160.81121 -221.372938)
		(end 159.973772 -221.372938)
		(width 0.20066)
		(layer "F.Cu")
		(net "M_E_CPU1_SB_DQ<9>")
	)
	(segment
		(start 155.473908 -229.825042)
		(end 155.473908 -229.540562)
		(width 0.20066)
		(layer "F.Cu")
		(net "M_E_CPU1_SB_DQ<9>")
	)
	(arc
		(start 136.545066 -239.046512)
		(mid 136.545395 -239.048164)
		(end 136.546336 -239.04956)
		(width 0.088646)
		(layer "F.Cu")
		(net "M_E_CPU1_SB_DQ<9>")
	)
	(segment
		(start 160.134554 -222.816674)
		(end 158.813246 -222.816674)
		(width 0.20066)
		(layer "F.Cu")
		(net "M_E_CPU1_SB_DQ<8>")
	)
	(segment
		(start 138.803888 -239.971072)
		(end 139.186412 -240.353596)
		(width 0.088646)
		(layer "F.Cu")
		(net "M_E_CPU1_SB_DQ<8>")
	)
	(segment
		(start 150.019258 -231.547924)
		(end 151.136096 -231.547924)
		(width 0.1016)
		(layer "F.Cu")
		(net "M_E_CPU1_SB_DQ<8>")
	)
	(segment
		(start 156.881322 -231.637332)
		(end 156.29255 -231.637332)
		(width 0.20066)
		(layer "F.Cu")
		(net "M_E_CPU1_SB_DQ<8>")
	)
	(segment
		(start 151.136096 -231.547924)
		(end 153.564844 -231.547924)
		(width 0.20066)
		(layer "F.Cu")
		(net "M_E_CPU1_SB_DQ<8>")
	)
	(segment
		(start 137.895076 -239.971072)
		(end 138.803888 -239.971072)
		(width 0.088646)
		(layer "F.Cu")
		(net "M_E_CPU1_SB_DQ<8>")
	)
	(segment
		(start 156.29255 -230.951532)
		(end 156.90469 -230.951532)
		(width 0.20066)
		(layer "F.Cu")
		(net "M_E_CPU1_SB_DQ<8>")
	)
	(segment
		(start 160.39084 -223.07296)
		(end 160.134554 -222.816674)
		(width 0.20066)
		(layer "F.Cu")
		(net "M_E_CPU1_SB_DQ<8>")
	)
	(segment
		(start 154.340052 -232.323132)
		(end 156.881322 -232.323132)
		(width 0.20066)
		(layer "F.Cu")
		(net "M_E_CPU1_SB_DQ<8>")
	)
	(segment
		(start 161.031682 -222.852488)
		(end 160.81121 -223.07296)
		(width 0.20066)
		(layer "F.Cu")
		(net "M_E_CPU1_SB_DQ<8>")
	)
	(segment
		(start 161.891726 -222.38208)
		(end 161.182304 -222.38208)
		(width 0.20066)
		(layer "F.Cu")
		(net "M_E_CPU1_SB_DQ<8>")
	)
	(segment
		(start 137.014712 -239.57534)
		(end 137.226802 -239.545368)
		(width 0.088646)
		(layer "F.Cu")
		(net "M_E_CPU1_SB_DQ<8>")
	)
	(segment
		(start 163.893246 -222.391732)
		(end 161.906204 -222.391732)
		(width 0.1016)
		(layer "F.Cu")
		(net "M_E_CPU1_SB_DQ<8>")
	)
	(segment
		(start 140.958316 -238.736886)
		(end 141.280896 -238.736886)
		(width 0.088646)
		(layer "F.Cu")
		(net "M_E_CPU1_SB_DQ<8>")
	)
	(segment
		(start 156.881322 -232.323132)
		(end 157.081982 -232.122472)
		(width 0.20066)
		(layer "F.Cu")
		(net "M_E_CPU1_SB_DQ<8>")
	)
	(segment
		(start 139.186412 -240.353596)
		(end 139.55268 -240.353596)
		(width 0.088646)
		(layer "F.Cu")
		(net "M_E_CPU1_SB_DQ<8>")
	)
	(segment
		(start 157.120844 -223.632522)
		(end 157.936692 -222.816674)
		(width 0.20066)
		(layer "F.Cu")
		(net "M_E_CPU1_SB_DQ<8>")
	)
	(segment
		(start 157.081982 -231.837992)
		(end 156.881322 -231.637332)
		(width 0.20066)
		(layer "F.Cu")
		(net "M_E_CPU1_SB_DQ<8>")
	)
	(segment
		(start 164.787834 -222.816674)
		(end 164.78123 -222.823278)
		(width 0.20066)
		(layer "F.Cu")
		(net "M_E_CPU1_SB_DQ<8>")
	)
	(segment
		(start 163.907978 -222.377)
		(end 163.893246 -222.391732)
		(width 0.101854)
		(layer "F.Cu")
		(net "M_E_CPU1_SB_DQ<8>")
	)
	(segment
		(start 164.334952 -222.377)
		(end 163.923726 -222.377)
		(width 0.20066)
		(layer "F.Cu")
		(net "M_E_CPU1_SB_DQ<8>")
	)
	(segment
		(start 156.29255 -231.637332)
		(end 156.09189 -231.436672)
		(width 0.20066)
		(layer "F.Cu")
		(net "M_E_CPU1_SB_DQ<8>")
	)
	(segment
		(start 142.830296 -238.736886)
		(end 150.019258 -231.547924)
		(width 0.1016)
		(layer "F.Cu")
		(net "M_E_CPU1_SB_DQ<8>")
	)
	(segment
		(start 157.120844 -230.735378)
		(end 157.120844 -223.632522)
		(width 0.20066)
		(layer "F.Cu")
		(net "M_E_CPU1_SB_DQ<8>")
	)
	(segment
		(start 161.896552 -222.38208)
		(end 161.891726 -222.38208)
		(width 0.101854)
		(layer "F.Cu")
		(net "M_E_CPU1_SB_DQ<8>")
	)
	(segment
		(start 163.923726 -222.377)
		(end 163.907978 -222.377)
		(width 0.101854)
		(layer "F.Cu")
		(net "M_E_CPU1_SB_DQ<8>")
	)
	(segment
		(start 156.90469 -230.951532)
		(end 157.120844 -230.735378)
		(width 0.20066)
		(layer "F.Cu")
		(net "M_E_CPU1_SB_DQ<8>")
	)
	(segment
		(start 156.09189 -231.152192)
		(end 156.29255 -230.951532)
		(width 0.20066)
		(layer "F.Cu")
		(net "M_E_CPU1_SB_DQ<8>")
	)
	(segment
		(start 161.031682 -222.532702)
		(end 161.031682 -222.852488)
		(width 0.20066)
		(layer "F.Cu")
		(net "M_E_CPU1_SB_DQ<8>")
	)
	(segment
		(start 139.72286 -240.183416)
		(end 139.769088 -240.114074)
		(width 0.088646)
		(layer "F.Cu")
		(net "M_E_CPU1_SB_DQ<8>")
	)
	(segment
		(start 139.55268 -240.353596)
		(end 139.72286 -240.183416)
		(width 0.088646)
		(layer "F.Cu")
		(net "M_E_CPU1_SB_DQ<8>")
	)
	(segment
		(start 139.769088 -240.114074)
		(end 139.769088 -239.926114)
		(width 0.088646)
		(layer "F.Cu")
		(net "M_E_CPU1_SB_DQ<8>")
	)
	(segment
		(start 160.81121 -223.07296)
		(end 160.39084 -223.07296)
		(width 0.20066)
		(layer "F.Cu")
		(net "M_E_CPU1_SB_DQ<8>")
	)
	(segment
		(start 157.936692 -222.816674)
		(end 158.813246 -222.816674)
		(width 0.20066)
		(layer "F.Cu")
		(net "M_E_CPU1_SB_DQ<8>")
	)
	(segment
		(start 137.310876 -239.566958)
		(end 137.812272 -239.943386)
		(width 0.088646)
		(layer "F.Cu")
		(net "M_E_CPU1_SB_DQ<8>")
	)
	(segment
		(start 141.280896 -238.736886)
		(end 142.830296 -238.736886)
		(width 0.1016)
		(layer "F.Cu")
		(net "M_E_CPU1_SB_DQ<8>")
	)
	(segment
		(start 166.357046 -222.816674)
		(end 164.787834 -222.816674)
		(width 0.20066)
		(layer "F.Cu")
		(net "M_E_CPU1_SB_DQ<8>")
	)
	(segment
		(start 153.564844 -231.547924)
		(end 154.340052 -232.323132)
		(width 0.20066)
		(layer "F.Cu")
		(net "M_E_CPU1_SB_DQ<8>")
	)
	(segment
		(start 161.906204 -222.391732)
		(end 161.896552 -222.38208)
		(width 0.1016)
		(layer "F.Cu")
		(net "M_E_CPU1_SB_DQ<8>")
	)
	(segment
		(start 157.081982 -232.122472)
		(end 157.081982 -231.837992)
		(width 0.20066)
		(layer "F.Cu")
		(net "M_E_CPU1_SB_DQ<8>")
	)
	(segment
		(start 139.769088 -239.926114)
		(end 140.958316 -238.736886)
		(width 0.088646)
		(layer "F.Cu")
		(net "M_E_CPU1_SB_DQ<8>")
	)
	(segment
		(start 161.182304 -222.38208)
		(end 161.031682 -222.532702)
		(width 0.20066)
		(layer "F.Cu")
		(net "M_E_CPU1_SB_DQ<8>")
	)
	(segment
		(start 156.09189 -231.436672)
		(end 156.09189 -231.152192)
		(width 0.20066)
		(layer "F.Cu")
		(net "M_E_CPU1_SB_DQ<8>")
	)
	(segment
		(start 164.78123 -222.823278)
		(end 164.334952 -222.377)
		(width 0.20066)
		(layer "F.Cu")
		(net "M_E_CPU1_SB_DQ<8>")
	)
	(arc
		(start 137.812272 -239.943386)
		(mid 137.851429 -239.96393)
		(end 137.895076 -239.971072)
		(width 0.088646)
		(layer "F.Cu")
		(net "M_E_CPU1_SB_DQ<8>")
	)
	(arc
		(start 137.226802 -239.545368)
		(mid 137.27099 -239.547792)
		(end 137.310876 -239.566958)
		(width 0.088646)
		(layer "F.Cu")
		(net "M_E_CPU1_SB_DQ<8>")
	)
	(segment
		(start 168.499536 -223.41459)
		(end 168.265348 -223.648778)
		(width 0.20066)
		(layer "F.Cu")
		(net "M_E_CPU1_SB_DQ<7>")
	)
	(segment
		(start 168.091866 -224.110296)
		(end 167.367458 -224.110296)
		(width 0.20066)
		(layer "F.Cu")
		(net "M_E_CPU1_SB_DQ<7>")
	)
	(segment
		(start 168.265348 -223.648778)
		(end 168.265348 -223.936814)
		(width 0.20066)
		(layer "F.Cu")
		(net "M_E_CPU1_SB_DQ<7>")
	)
	(segment
		(start 165.360096 -224.0915)
		(end 165.345618 -224.105978)
		(width 0.1016)
		(layer "F.Cu")
		(net "M_E_CPU1_SB_DQ<7>")
	)
	(segment
		(start 165.00983 -224.105978)
		(end 164.57041 -223.666558)
		(width 0.20066)
		(layer "F.Cu")
		(net "M_E_CPU1_SB_DQ<7>")
	)
	(segment
		(start 164.57041 -223.666558)
		(end 162.913314 -223.666558)
		(width 0.20066)
		(layer "F.Cu")
		(net "M_E_CPU1_SB_DQ<7>")
	)
	(segment
		(start 167.367458 -224.110296)
		(end 167.334692 -224.110296)
		(width 0.101854)
		(layer "F.Cu")
		(net "M_E_CPU1_SB_DQ<7>")
	)
	(segment
		(start 169.135552 -223.666558)
		(end 168.883584 -223.41459)
		(width 0.20066)
		(layer "F.Cu")
		(net "M_E_CPU1_SB_DQ<7>")
	)
	(segment
		(start 134.665466 -233.87812)
		(end 134.665466 -233.34218)
		(width 0.20066)
		(layer "F.Cu")
		(net "M_E_CPU1_SB_DQ<7>")
	)
	(segment
		(start 161.783014 -223.666558)
		(end 162.913314 -223.666558)
		(width 0.20066)
		(layer "F.Cu")
		(net "M_E_CPU1_SB_DQ<7>")
	)
	(segment
		(start 167.334692 -224.110296)
		(end 167.315896 -224.0915)
		(width 0.101854)
		(layer "F.Cu")
		(net "M_E_CPU1_SB_DQ<7>")
	)
	(segment
		(start 168.265348 -223.936814)
		(end 168.091866 -224.110296)
		(width 0.20066)
		(layer "F.Cu")
		(net "M_E_CPU1_SB_DQ<7>")
	)
	(segment
		(start 165.345618 -224.105978)
		(end 165.335458 -224.105978)
		(width 0.101854)
		(layer "F.Cu")
		(net "M_E_CPU1_SB_DQ<7>")
	)
	(segment
		(start 167.315896 -224.0915)
		(end 165.360096 -224.0915)
		(width 0.1016)
		(layer "F.Cu")
		(net "M_E_CPU1_SB_DQ<7>")
	)
	(segment
		(start 165.335458 -224.105978)
		(end 165.00983 -224.105978)
		(width 0.20066)
		(layer "F.Cu")
		(net "M_E_CPU1_SB_DQ<7>")
	)
	(segment
		(start 168.883584 -223.41459)
		(end 168.499536 -223.41459)
		(width 0.20066)
		(layer "F.Cu")
		(net "M_E_CPU1_SB_DQ<7>")
	)
	(segment
		(start 170.457114 -223.666558)
		(end 169.135552 -223.666558)
		(width 0.20066)
		(layer "F.Cu")
		(net "M_E_CPU1_SB_DQ<7>")
	)
	(segment
		(start 147.476972 -231.807766)
		(end 140.645642 -231.807766)
		(width 0.18288)
		(layer "In2.Cu")
		(net "M_E_CPU1_SB_DQ<7>")
	)
	(segment
		(start 157.371288 -224.007172)
		(end 155.277566 -224.007172)
		(width 0.18288)
		(layer "In2.Cu")
		(net "M_E_CPU1_SB_DQ<7>")
	)
	(segment
		(start 159.324548 -224.120202)
		(end 159.033972 -223.829626)
		(width 0.18288)
		(layer "In2.Cu")
		(net "M_E_CPU1_SB_DQ<7>")
	)
	(segment
		(start 161.783014 -223.927162)
		(end 161.589974 -224.120202)
		(width 0.18288)
		(layer "In2.Cu")
		(net "M_E_CPU1_SB_DQ<7>")
	)
	(segment
		(start 159.033972 -223.829626)
		(end 158.433516 -223.829626)
		(width 0.18288)
		(layer "In2.Cu")
		(net "M_E_CPU1_SB_DQ<7>")
	)
	(segment
		(start 134.925308 -233.082338)
		(end 134.665466 -233.34218)
		(width 0.088646)
		(layer "In2.Cu")
		(net "M_E_CPU1_SB_DQ<7>")
	)
	(segment
		(start 158.433516 -223.829626)
		(end 158.172404 -224.090738)
		(width 0.18288)
		(layer "In2.Cu")
		(net "M_E_CPU1_SB_DQ<7>")
	)
	(segment
		(start 158.172404 -224.090738)
		(end 157.454854 -224.090738)
		(width 0.18288)
		(layer "In2.Cu")
		(net "M_E_CPU1_SB_DQ<7>")
	)
	(segment
		(start 161.589974 -224.120202)
		(end 159.324548 -224.120202)
		(width 0.18288)
		(layer "In2.Cu")
		(net "M_E_CPU1_SB_DQ<7>")
	)
	(segment
		(start 140.043154 -232.089452)
		(end 139.364466 -232.089452)
		(width 0.088646)
		(layer "In2.Cu")
		(net "M_E_CPU1_SB_DQ<7>")
	)
	(segment
		(start 135.322564 -232.852722)
		(end 134.925308 -233.082338)
		(width 0.088646)
		(layer "In2.Cu")
		(net "M_E_CPU1_SB_DQ<7>")
	)
	(segment
		(start 155.277566 -224.007172)
		(end 147.476972 -231.807766)
		(width 0.18288)
		(layer "In2.Cu")
		(net "M_E_CPU1_SB_DQ<7>")
	)
	(segment
		(start 140.645642 -231.807766)
		(end 140.32484 -231.807766)
		(width 0.088646)
		(layer "In2.Cu")
		(net "M_E_CPU1_SB_DQ<7>")
	)
	(segment
		(start 161.783014 -223.666558)
		(end 161.783014 -223.927162)
		(width 0.18288)
		(layer "In2.Cu")
		(net "M_E_CPU1_SB_DQ<7>")
	)
	(segment
		(start 138.150854 -232.847642)
		(end 138.141964 -232.852722)
		(width 0.088646)
		(layer "In2.Cu")
		(net "M_E_CPU1_SB_DQ<7>")
	)
	(segment
		(start 140.32484 -231.807766)
		(end 140.043154 -232.089452)
		(width 0.088646)
		(layer "In2.Cu")
		(net "M_E_CPU1_SB_DQ<7>")
	)
	(segment
		(start 157.454854 -224.090738)
		(end 157.371288 -224.007172)
		(width 0.18288)
		(layer "In2.Cu")
		(net "M_E_CPU1_SB_DQ<7>")
	)
	(segment
		(start 138.329416 -232.518458)
		(end 138.329416 -232.528364)
		(width 0.088646)
		(layer "In2.Cu")
		(net "M_E_CPU1_SB_DQ<7>")
	)
	(arc
		(start 136.827768 -232.852722)
		(mid 136.545066 -232.776946)
		(end 136.262364 -232.852722)
		(width 0.088646)
		(layer "In2.Cu")
		(net "M_E_CPU1_SB_DQ<7>")
	)
	(arc
		(start 137.767568 -232.852722)
		(mid 137.484866 -232.776946)
		(end 137.202164 -232.852722)
		(width 0.088646)
		(layer "In2.Cu")
		(net "M_E_CPU1_SB_DQ<7>")
	)
	(arc
		(start 135.887968 -232.852722)
		(mid 135.605266 -232.776946)
		(end 135.322564 -232.852722)
		(width 0.088646)
		(layer "In2.Cu")
		(net "M_E_CPU1_SB_DQ<7>")
	)
	(arc
		(start 138.141964 -232.852722)
		(mid 137.954766 -232.902865)
		(end 137.767568 -232.852722)
		(width 0.088646)
		(layer "In2.Cu")
		(net "M_E_CPU1_SB_DQ<7>")
	)
	(arc
		(start 138.329416 -232.528364)
		(mid 138.281737 -232.711264)
		(end 138.150854 -232.847642)
		(width 0.088646)
		(layer "In2.Cu")
		(net "M_E_CPU1_SB_DQ<7>")
	)
	(arc
		(start 138.611864 -232.038906)
		(mid 138.407529 -232.241511)
		(end 138.329416 -232.518458)
		(width 0.088646)
		(layer "In2.Cu")
		(net "M_E_CPU1_SB_DQ<7>")
	)
	(arc
		(start 139.364466 -232.089452)
		(mid 139.267543 -232.076494)
		(end 139.177268 -232.038906)
		(width 0.088646)
		(layer "In2.Cu")
		(net "M_E_CPU1_SB_DQ<7>")
	)
	(arc
		(start 137.202164 -232.852722)
		(mid 137.014966 -232.902865)
		(end 136.827768 -232.852722)
		(width 0.088646)
		(layer "In2.Cu")
		(net "M_E_CPU1_SB_DQ<7>")
	)
	(arc
		(start 136.262364 -232.852722)
		(mid 136.075166 -232.902865)
		(end 135.887968 -232.852722)
		(width 0.088646)
		(layer "In2.Cu")
		(net "M_E_CPU1_SB_DQ<7>")
	)
	(arc
		(start 139.177268 -232.038906)
		(mid 138.894566 -231.96313)
		(end 138.611864 -232.038906)
		(width 0.088646)
		(layer "In2.Cu")
		(net "M_E_CPU1_SB_DQ<7>")
	)
	(segment
		(start 168.883584 -225.114612)
		(end 168.499536 -225.114612)
		(width 0.20066)
		(layer "F.Cu")
		(net "M_E_CPU1_SB_DQ<6>")
	)
	(segment
		(start 165.345618 -225.806)
		(end 165.335458 -225.806)
		(width 0.101854)
		(layer "F.Cu")
		(net "M_E_CPU1_SB_DQ<6>")
	)
	(segment
		(start 165.360096 -225.791522)
		(end 165.345618 -225.806)
		(width 0.1016)
		(layer "F.Cu")
		(net "M_E_CPU1_SB_DQ<6>")
	)
	(segment
		(start 161.783014 -225.36658)
		(end 162.913314 -225.36658)
		(width 0.20066)
		(layer "F.Cu")
		(net "M_E_CPU1_SB_DQ<6>")
	)
	(segment
		(start 168.499536 -225.114612)
		(end 168.265348 -225.3488)
		(width 0.20066)
		(layer "F.Cu")
		(net "M_E_CPU1_SB_DQ<6>")
	)
	(segment
		(start 168.091866 -225.810318)
		(end 167.367458 -225.810318)
		(width 0.20066)
		(layer "F.Cu")
		(net "M_E_CPU1_SB_DQ<6>")
	)
	(segment
		(start 169.135552 -225.36658)
		(end 168.883584 -225.114612)
		(width 0.20066)
		(layer "F.Cu")
		(net "M_E_CPU1_SB_DQ<6>")
	)
	(segment
		(start 168.265348 -225.636836)
		(end 168.091866 -225.810318)
		(width 0.20066)
		(layer "F.Cu")
		(net "M_E_CPU1_SB_DQ<6>")
	)
	(segment
		(start 164.53485 -225.36658)
		(end 162.913314 -225.36658)
		(width 0.20066)
		(layer "F.Cu")
		(net "M_E_CPU1_SB_DQ<6>")
	)
	(segment
		(start 170.457114 -225.36658)
		(end 169.135552 -225.36658)
		(width 0.20066)
		(layer "F.Cu")
		(net "M_E_CPU1_SB_DQ<6>")
	)
	(segment
		(start 164.97427 -225.806)
		(end 164.53485 -225.36658)
		(width 0.20066)
		(layer "F.Cu")
		(net "M_E_CPU1_SB_DQ<6>")
	)
	(segment
		(start 168.265348 -225.3488)
		(end 168.265348 -225.636836)
		(width 0.20066)
		(layer "F.Cu")
		(net "M_E_CPU1_SB_DQ<6>")
	)
	(segment
		(start 167.334692 -225.810318)
		(end 167.315896 -225.791522)
		(width 0.101854)
		(layer "F.Cu")
		(net "M_E_CPU1_SB_DQ<6>")
	)
	(segment
		(start 135.135112 -234.156504)
		(end 135.135366 -234.15625)
		(width 0.20066)
		(layer "F.Cu")
		(net "M_E_CPU1_SB_DQ<6>")
	)
	(segment
		(start 167.315896 -225.791522)
		(end 165.360096 -225.791522)
		(width 0.1016)
		(layer "F.Cu")
		(net "M_E_CPU1_SB_DQ<6>")
	)
	(segment
		(start 165.335458 -225.806)
		(end 164.97427 -225.806)
		(width 0.20066)
		(layer "F.Cu")
		(net "M_E_CPU1_SB_DQ<6>")
	)
	(segment
		(start 167.367458 -225.810318)
		(end 167.334692 -225.810318)
		(width 0.101854)
		(layer "F.Cu")
		(net "M_E_CPU1_SB_DQ<6>")
	)
	(segment
		(start 135.135112 -234.69219)
		(end 135.135112 -234.156504)
		(width 0.20066)
		(layer "F.Cu")
		(net "M_E_CPU1_SB_DQ<6>")
	)
	(segment
		(start 140.204952 -232.77703)
		(end 139.364466 -232.77703)
		(width 0.088646)
		(layer "In2.Cu")
		(net "M_E_CPU1_SB_DQ<6>")
	)
	(segment
		(start 135.792464 -233.666538)
		(end 135.719058 -233.708702)
		(width 0.088646)
		(layer "In2.Cu")
		(net "M_E_CPU1_SB_DQ<6>")
	)
	(segment
		(start 140.645896 -232.824528)
		(end 140.25245 -232.824528)
		(width 0.088646)
		(layer "In2.Cu")
		(net "M_E_CPU1_SB_DQ<6>")
	)
	(segment
		(start 156.646118 -225.130614)
		(end 152.452832 -229.3239)
		(width 0.18288)
		(layer "In2.Cu")
		(net "M_E_CPU1_SB_DQ<6>")
	)
	(segment
		(start 138.620754 -233.661458)
		(end 138.611864 -233.666538)
		(width 0.088646)
		(layer "In2.Cu")
		(net "M_E_CPU1_SB_DQ<6>")
	)
	(segment
		(start 159.380428 -225.118168)
		(end 159.2072 -224.94494)
		(width 0.18288)
		(layer "In2.Cu")
		(net "M_E_CPU1_SB_DQ<6>")
	)
	(segment
		(start 140.25245 -232.824528)
		(end 140.204952 -232.77703)
		(width 0.088646)
		(layer "In2.Cu")
		(net "M_E_CPU1_SB_DQ<6>")
	)
	(segment
		(start 161.783014 -225.36658)
		(end 161.3027 -225.846894)
		(width 0.18288)
		(layer "In2.Cu")
		(net "M_E_CPU1_SB_DQ<6>")
	)
	(segment
		(start 138.799316 -233.332274)
		(end 138.799316 -233.34218)
		(width 0.088646)
		(layer "In2.Cu")
		(net "M_E_CPU1_SB_DQ<6>")
	)
	(segment
		(start 159.380428 -225.565716)
		(end 159.380428 -225.118168)
		(width 0.18288)
		(layer "In2.Cu")
		(net "M_E_CPU1_SB_DQ<6>")
	)
	(segment
		(start 157.274514 -225.130614)
		(end 156.646118 -225.130614)
		(width 0.18288)
		(layer "In2.Cu")
		(net "M_E_CPU1_SB_DQ<6>")
	)
	(segment
		(start 159.2072 -224.94494)
		(end 157.460188 -224.94494)
		(width 0.18288)
		(layer "In2.Cu")
		(net "M_E_CPU1_SB_DQ<6>")
	)
	(segment
		(start 161.3027 -225.846894)
		(end 159.661606 -225.846894)
		(width 0.18288)
		(layer "In2.Cu")
		(net "M_E_CPU1_SB_DQ<6>")
	)
	(segment
		(start 147.974812 -232.824528)
		(end 140.645896 -232.824528)
		(width 0.18288)
		(layer "In2.Cu")
		(net "M_E_CPU1_SB_DQ<6>")
	)
	(segment
		(start 157.460188 -224.94494)
		(end 157.274514 -225.130614)
		(width 0.18288)
		(layer "In2.Cu")
		(net "M_E_CPU1_SB_DQ<6>")
	)
	(segment
		(start 152.452832 -229.3239)
		(end 151.47544 -229.3239)
		(width 0.18288)
		(layer "In2.Cu")
		(net "M_E_CPU1_SB_DQ<6>")
	)
	(segment
		(start 135.13562 -234.155996)
		(end 135.135366 -234.15625)
		(width 0.088646)
		(layer "In2.Cu")
		(net "M_E_CPU1_SB_DQ<6>")
	)
	(segment
		(start 159.661606 -225.846894)
		(end 159.380428 -225.565716)
		(width 0.18288)
		(layer "In2.Cu")
		(net "M_E_CPU1_SB_DQ<6>")
	)
	(segment
		(start 151.47544 -229.3239)
		(end 147.974812 -232.824528)
		(width 0.18288)
		(layer "In2.Cu")
		(net "M_E_CPU1_SB_DQ<6>")
	)
	(arc
		(start 135.719058 -233.708702)
		(mid 135.412595 -233.913118)
		(end 135.13562 -234.155996)
		(width 0.088646)
		(layer "In2.Cu")
		(net "M_E_CPU1_SB_DQ<6>")
	)
	(arc
		(start 138.237468 -233.666538)
		(mid 137.954766 -233.590796)
		(end 137.672064 -233.666538)
		(width 0.088646)
		(layer "In2.Cu")
		(net "M_E_CPU1_SB_DQ<6>")
	)
	(arc
		(start 138.611864 -233.666538)
		(mid 138.424666 -233.716681)
		(end 138.237468 -233.666538)
		(width 0.088646)
		(layer "In2.Cu")
		(net "M_E_CPU1_SB_DQ<6>")
	)
	(arc
		(start 136.357868 -233.666538)
		(mid 136.075166 -233.590796)
		(end 135.792464 -233.666538)
		(width 0.088646)
		(layer "In2.Cu")
		(net "M_E_CPU1_SB_DQ<6>")
	)
	(arc
		(start 137.672064 -233.666538)
		(mid 137.484866 -233.716681)
		(end 137.297668 -233.666538)
		(width 0.088646)
		(layer "In2.Cu")
		(net "M_E_CPU1_SB_DQ<6>")
	)
	(arc
		(start 136.732264 -233.666538)
		(mid 136.545066 -233.716681)
		(end 136.357868 -233.666538)
		(width 0.088646)
		(layer "In2.Cu")
		(net "M_E_CPU1_SB_DQ<6>")
	)
	(arc
		(start 139.364466 -232.77703)
		(mid 138.968362 -232.939072)
		(end 138.799316 -233.332274)
		(width 0.088646)
		(layer "In2.Cu")
		(net "M_E_CPU1_SB_DQ<6>")
	)
	(arc
		(start 137.297668 -233.666538)
		(mid 137.014966 -233.590796)
		(end 136.732264 -233.666538)
		(width 0.088646)
		(layer "In2.Cu")
		(net "M_E_CPU1_SB_DQ<6>")
	)
	(arc
		(start 138.799316 -233.34218)
		(mid 138.751637 -233.52508)
		(end 138.620754 -233.661458)
		(width 0.088646)
		(layer "In2.Cu")
		(net "M_E_CPU1_SB_DQ<6>")
	)
	(segment
		(start 133.725666 -233.87812)
		(end 133.725666 -233.34218)
		(width 0.20066)
		(layer "F.Cu")
		(net "M_E_CPU1_SB_DQ<5>")
	)
	(segment
		(start 163.917376 -224.091754)
		(end 161.728658 -224.091754)
		(width 0.1016)
		(layer "F.Cu")
		(net "M_E_CPU1_SB_DQ<5>")
	)
	(segment
		(start 161.728658 -224.091754)
		(end 161.708592 -224.091754)
		(width 0.101854)
		(layer "F.Cu")
		(net "M_E_CPU1_SB_DQ<5>")
	)
	(segment
		(start 163.923726 -224.085404)
		(end 163.917376 -224.091754)
		(width 0.1016)
		(layer "F.Cu")
		(net "M_E_CPU1_SB_DQ<5>")
	)
	(segment
		(start 166.357046 -224.516696)
		(end 166.356792 -224.51695)
		(width 0.20066)
		(layer "F.Cu")
		(net "M_E_CPU1_SB_DQ<5>")
	)
	(segment
		(start 160.58261 -224.765362)
		(end 160.333944 -224.516696)
		(width 0.20066)
		(layer "F.Cu")
		(net "M_E_CPU1_SB_DQ<5>")
	)
	(segment
		(start 157.682946 -224.516696)
		(end 158.813246 -224.516696)
		(width 0.20066)
		(layer "F.Cu")
		(net "M_E_CPU1_SB_DQ<5>")
	)
	(segment
		(start 161.057844 -224.765362)
		(end 160.58261 -224.765362)
		(width 0.20066)
		(layer "F.Cu")
		(net "M_E_CPU1_SB_DQ<5>")
	)
	(segment
		(start 164.765228 -224.51695)
		(end 164.333682 -224.085404)
		(width 0.20066)
		(layer "F.Cu")
		(net "M_E_CPU1_SB_DQ<5>")
	)
	(segment
		(start 161.245804 -224.577402)
		(end 161.057844 -224.765362)
		(width 0.20066)
		(layer "F.Cu")
		(net "M_E_CPU1_SB_DQ<5>")
	)
	(segment
		(start 166.356792 -224.51695)
		(end 164.765228 -224.51695)
		(width 0.20066)
		(layer "F.Cu")
		(net "M_E_CPU1_SB_DQ<5>")
	)
	(segment
		(start 161.708592 -224.091754)
		(end 161.363914 -224.091754)
		(width 0.20066)
		(layer "F.Cu")
		(net "M_E_CPU1_SB_DQ<5>")
	)
	(segment
		(start 161.363914 -224.091754)
		(end 161.245804 -224.209864)
		(width 0.20066)
		(layer "F.Cu")
		(net "M_E_CPU1_SB_DQ<5>")
	)
	(segment
		(start 160.333944 -224.516696)
		(end 158.813246 -224.516696)
		(width 0.20066)
		(layer "F.Cu")
		(net "M_E_CPU1_SB_DQ<5>")
	)
	(segment
		(start 161.245804 -224.209864)
		(end 161.245804 -224.577402)
		(width 0.20066)
		(layer "F.Cu")
		(net "M_E_CPU1_SB_DQ<5>")
	)
	(segment
		(start 164.333682 -224.085404)
		(end 163.923726 -224.085404)
		(width 0.20066)
		(layer "F.Cu")
		(net "M_E_CPU1_SB_DQ<5>")
	)
	(segment
		(start 155.577286 -225.193098)
		(end 155.577286 -225.465894)
		(width 0.18288)
		(layer "In2.Cu")
		(net "M_E_CPU1_SB_DQ<5>")
	)
	(segment
		(start 152.588722 -228.181662)
		(end 152.588722 -228.454458)
		(width 0.18288)
		(layer "In2.Cu")
		(net "M_E_CPU1_SB_DQ<5>")
	)
	(segment
		(start 157.682946 -224.516696)
		(end 156.526484 -224.516696)
		(width 0.18288)
		(layer "In2.Cu")
		(net "M_E_CPU1_SB_DQ<5>")
	)
	(segment
		(start 154.581098 -226.462082)
		(end 154.3558 -226.68738)
		(width 0.18288)
		(layer "In2.Cu")
		(net "M_E_CPU1_SB_DQ<5>")
	)
	(segment
		(start 140.645642 -232.316274)
		(end 139.500864 -232.316274)
		(width 0.088646)
		(layer "In2.Cu")
		(net "M_E_CPU1_SB_DQ<5>")
	)
	(segment
		(start 134.104126 -233.407966)
		(end 134.03834 -233.34218)
		(width 0.088646)
		(layer "In2.Cu")
		(net "M_E_CPU1_SB_DQ<5>")
	)
	(segment
		(start 154.083004 -226.68738)
		(end 153.907998 -226.512374)
		(width 0.18288)
		(layer "In2.Cu")
		(net "M_E_CPU1_SB_DQ<5>")
	)
	(segment
		(start 152.228296 -228.814884)
		(end 151.237696 -228.814884)
		(width 0.18288)
		(layer "In2.Cu")
		(net "M_E_CPU1_SB_DQ<5>")
	)
	(segment
		(start 154.63139 -225.516186)
		(end 154.406092 -225.741484)
		(width 0.18288)
		(layer "In2.Cu")
		(net "M_E_CPU1_SB_DQ<5>")
	)
	(segment
		(start 152.413716 -228.006656)
		(end 152.588722 -228.181662)
		(width 0.18288)
		(layer "In2.Cu")
		(net "M_E_CPU1_SB_DQ<5>")
	)
	(segment
		(start 156.526484 -224.516696)
		(end 156.348176 -224.695004)
		(width 0.18288)
		(layer "In2.Cu")
		(net "M_E_CPU1_SB_DQ<5>")
	)
	(segment
		(start 153.907998 -226.512374)
		(end 153.635202 -226.512374)
		(width 0.18288)
		(layer "In2.Cu")
		(net "M_E_CPU1_SB_DQ<5>")
	)
	(segment
		(start 152.639014 -227.508562)
		(end 152.413716 -227.73386)
		(width 0.18288)
		(layer "In2.Cu")
		(net "M_E_CPU1_SB_DQ<5>")
	)
	(segment
		(start 135.230616 -233.338878)
		(end 135.230616 -233.34218)
		(width 0.088646)
		(layer "In2.Cu")
		(net "M_E_CPU1_SB_DQ<5>")
	)
	(segment
		(start 154.904186 -225.516186)
		(end 154.63139 -225.516186)
		(width 0.18288)
		(layer "In2.Cu")
		(net "M_E_CPU1_SB_DQ<5>")
	)
	(segment
		(start 156.07538 -224.695004)
		(end 155.900374 -224.519998)
		(width 0.18288)
		(layer "In2.Cu")
		(net "M_E_CPU1_SB_DQ<5>")
	)
	(segment
		(start 152.413716 -227.73386)
		(end 152.413716 -228.006656)
		(width 0.18288)
		(layer "In2.Cu")
		(net "M_E_CPU1_SB_DQ<5>")
	)
	(segment
		(start 151.237696 -228.814884)
		(end 147.736306 -232.316274)
		(width 0.18288)
		(layer "In2.Cu")
		(net "M_E_CPU1_SB_DQ<5>")
	)
	(segment
		(start 155.079192 -225.691192)
		(end 154.904186 -225.516186)
		(width 0.18288)
		(layer "In2.Cu")
		(net "M_E_CPU1_SB_DQ<5>")
	)
	(segment
		(start 155.40228 -224.745296)
		(end 155.40228 -225.018092)
		(width 0.18288)
		(layer "In2.Cu")
		(net "M_E_CPU1_SB_DQ<5>")
	)
	(segment
		(start 153.086816 -227.683568)
		(end 152.91181 -227.508562)
		(width 0.18288)
		(layer "In2.Cu")
		(net "M_E_CPU1_SB_DQ<5>")
	)
	(segment
		(start 154.406092 -225.741484)
		(end 154.406092 -226.01428)
		(width 0.18288)
		(layer "In2.Cu")
		(net "M_E_CPU1_SB_DQ<5>")
	)
	(segment
		(start 155.351988 -225.691192)
		(end 155.079192 -225.691192)
		(width 0.18288)
		(layer "In2.Cu")
		(net "M_E_CPU1_SB_DQ<5>")
	)
	(segment
		(start 153.359612 -227.683568)
		(end 153.086816 -227.683568)
		(width 0.18288)
		(layer "In2.Cu")
		(net "M_E_CPU1_SB_DQ<5>")
	)
	(segment
		(start 152.588722 -228.454458)
		(end 152.228296 -228.814884)
		(width 0.18288)
		(layer "In2.Cu")
		(net "M_E_CPU1_SB_DQ<5>")
	)
	(segment
		(start 155.627578 -224.519998)
		(end 155.40228 -224.745296)
		(width 0.18288)
		(layer "In2.Cu")
		(net "M_E_CPU1_SB_DQ<5>")
	)
	(segment
		(start 152.91181 -227.508562)
		(end 152.639014 -227.508562)
		(width 0.18288)
		(layer "In2.Cu")
		(net "M_E_CPU1_SB_DQ<5>")
	)
	(segment
		(start 153.409904 -226.737672)
		(end 153.409904 -227.010468)
		(width 0.18288)
		(layer "In2.Cu")
		(net "M_E_CPU1_SB_DQ<5>")
	)
	(segment
		(start 138.707368 -232.204006)
		(end 138.698478 -232.209086)
		(width 0.088646)
		(layer "In2.Cu")
		(net "M_E_CPU1_SB_DQ<5>")
	)
	(segment
		(start 147.736306 -232.316274)
		(end 140.645642 -232.316274)
		(width 0.18288)
		(layer "In2.Cu")
		(net "M_E_CPU1_SB_DQ<5>")
	)
	(segment
		(start 154.3558 -226.68738)
		(end 154.083004 -226.68738)
		(width 0.18288)
		(layer "In2.Cu")
		(net "M_E_CPU1_SB_DQ<5>")
	)
	(segment
		(start 153.58491 -227.185474)
		(end 153.58491 -227.45827)
		(width 0.18288)
		(layer "In2.Cu")
		(net "M_E_CPU1_SB_DQ<5>")
	)
	(segment
		(start 155.577286 -225.465894)
		(end 155.351988 -225.691192)
		(width 0.18288)
		(layer "In2.Cu")
		(net "M_E_CPU1_SB_DQ<5>")
	)
	(segment
		(start 153.635202 -226.512374)
		(end 153.409904 -226.737672)
		(width 0.18288)
		(layer "In2.Cu")
		(net "M_E_CPU1_SB_DQ<5>")
	)
	(segment
		(start 156.348176 -224.695004)
		(end 156.07538 -224.695004)
		(width 0.18288)
		(layer "In2.Cu")
		(net "M_E_CPU1_SB_DQ<5>")
	)
	(segment
		(start 153.58491 -227.45827)
		(end 153.359612 -227.683568)
		(width 0.18288)
		(layer "In2.Cu")
		(net "M_E_CPU1_SB_DQ<5>")
	)
	(segment
		(start 155.40228 -225.018092)
		(end 155.577286 -225.193098)
		(width 0.18288)
		(layer "In2.Cu")
		(net "M_E_CPU1_SB_DQ<5>")
	)
	(segment
		(start 134.03834 -233.34218)
		(end 133.725666 -233.34218)
		(width 0.088646)
		(layer "In2.Cu")
		(net "M_E_CPU1_SB_DQ<5>")
	)
	(segment
		(start 154.581098 -226.189286)
		(end 154.581098 -226.462082)
		(width 0.18288)
		(layer "In2.Cu")
		(net "M_E_CPU1_SB_DQ<5>")
	)
	(segment
		(start 154.406092 -226.01428)
		(end 154.581098 -226.189286)
		(width 0.18288)
		(layer "In2.Cu")
		(net "M_E_CPU1_SB_DQ<5>")
	)
	(segment
		(start 135.418068 -233.017822)
		(end 135.417814 -233.017822)
		(width 0.088646)
		(layer "In2.Cu")
		(net "M_E_CPU1_SB_DQ<5>")
	)
	(segment
		(start 138.519916 -232.528364)
		(end 138.519916 -232.53827)
		(width 0.088646)
		(layer "In2.Cu")
		(net "M_E_CPU1_SB_DQ<5>")
	)
	(segment
		(start 155.900374 -224.519998)
		(end 155.627578 -224.519998)
		(width 0.18288)
		(layer "In2.Cu")
		(net "M_E_CPU1_SB_DQ<5>")
	)
	(segment
		(start 153.409904 -227.010468)
		(end 153.58491 -227.185474)
		(width 0.18288)
		(layer "In2.Cu")
		(net "M_E_CPU1_SB_DQ<5>")
	)
	(arc
		(start 138.698478 -232.209086)
		(mid 138.567564 -232.345446)
		(end 138.519916 -232.528364)
		(width 0.088646)
		(layer "In2.Cu")
		(net "M_E_CPU1_SB_DQ<5>")
	)
	(arc
		(start 135.792464 -233.017822)
		(mid 135.605266 -232.967679)
		(end 135.418068 -233.017822)
		(width 0.088646)
		(layer "In2.Cu")
		(net "M_E_CPU1_SB_DQ<5>")
	)
	(arc
		(start 137.297668 -233.017822)
		(mid 137.014966 -233.093598)
		(end 136.732264 -233.017822)
		(width 0.088646)
		(layer "In2.Cu")
		(net "M_E_CPU1_SB_DQ<5>")
	)
	(arc
		(start 136.732264 -233.017822)
		(mid 136.545066 -232.967679)
		(end 136.357868 -233.017822)
		(width 0.088646)
		(layer "In2.Cu")
		(net "M_E_CPU1_SB_DQ<5>")
	)
	(arc
		(start 135.417814 -233.017822)
		(mid 135.281617 -233.153507)
		(end 135.230616 -233.338878)
		(width 0.088646)
		(layer "In2.Cu")
		(net "M_E_CPU1_SB_DQ<5>")
	)
	(arc
		(start 135.230616 -233.34218)
		(mid 134.698413 -233.906369)
		(end 134.104126 -233.407966)
		(width 0.088646)
		(layer "In2.Cu")
		(net "M_E_CPU1_SB_DQ<5>")
	)
	(arc
		(start 139.500864 -232.316274)
		(mid 139.283929 -232.287715)
		(end 139.081764 -232.204006)
		(width 0.088646)
		(layer "In2.Cu")
		(net "M_E_CPU1_SB_DQ<5>")
	)
	(arc
		(start 138.237468 -233.017822)
		(mid 137.954766 -233.093598)
		(end 137.672064 -233.017822)
		(width 0.088646)
		(layer "In2.Cu")
		(net "M_E_CPU1_SB_DQ<5>")
	)
	(arc
		(start 137.672064 -233.017822)
		(mid 137.484866 -232.967679)
		(end 137.297668 -233.017822)
		(width 0.088646)
		(layer "In2.Cu")
		(net "M_E_CPU1_SB_DQ<5>")
	)
	(arc
		(start 138.519916 -232.53827)
		(mid 138.441805 -232.815219)
		(end 138.237468 -233.017822)
		(width 0.088646)
		(layer "In2.Cu")
		(net "M_E_CPU1_SB_DQ<5>")
	)
	(arc
		(start 139.081764 -232.204006)
		(mid 138.894566 -232.153863)
		(end 138.707368 -232.204006)
		(width 0.088646)
		(layer "In2.Cu")
		(net "M_E_CPU1_SB_DQ<5>")
	)
	(arc
		(start 136.357868 -233.017822)
		(mid 136.075166 -233.093598)
		(end 135.792464 -233.017822)
		(width 0.088646)
		(layer "In2.Cu")
		(net "M_E_CPU1_SB_DQ<5>")
	)
	(segment
		(start 161.057844 -226.465384)
		(end 160.58261 -226.465384)
		(width 0.20066)
		(layer "F.Cu")
		(net "M_E_CPU1_SB_DQ<4>")
	)
	(segment
		(start 160.58261 -226.465384)
		(end 160.333944 -226.216718)
		(width 0.20066)
		(layer "F.Cu")
		(net "M_E_CPU1_SB_DQ<4>")
	)
	(segment
		(start 133.255512 -234.69219)
		(end 133.255766 -234.691936)
		(width 0.20066)
		(layer "F.Cu")
		(net "M_E_CPU1_SB_DQ<4>")
	)
	(segment
		(start 161.245804 -225.909886)
		(end 161.245804 -226.277424)
		(width 0.20066)
		(layer "F.Cu")
		(net "M_E_CPU1_SB_DQ<4>")
	)
	(segment
		(start 157.682946 -226.216718)
		(end 158.813246 -226.216718)
		(width 0.20066)
		(layer "F.Cu")
		(net "M_E_CPU1_SB_DQ<4>")
	)
	(segment
		(start 161.245804 -226.277424)
		(end 161.057844 -226.465384)
		(width 0.20066)
		(layer "F.Cu")
		(net "M_E_CPU1_SB_DQ<4>")
	)
	(segment
		(start 166.356792 -226.216972)
		(end 164.765228 -226.216972)
		(width 0.20066)
		(layer "F.Cu")
		(net "M_E_CPU1_SB_DQ<4>")
	)
	(segment
		(start 164.765228 -226.216972)
		(end 164.333682 -225.785426)
		(width 0.20066)
		(layer "F.Cu")
		(net "M_E_CPU1_SB_DQ<4>")
	)
	(segment
		(start 161.363914 -225.791776)
		(end 161.245804 -225.909886)
		(width 0.20066)
		(layer "F.Cu")
		(net "M_E_CPU1_SB_DQ<4>")
	)
	(segment
		(start 163.923726 -225.785426)
		(end 163.917376 -225.791776)
		(width 0.1016)
		(layer "F.Cu")
		(net "M_E_CPU1_SB_DQ<4>")
	)
	(segment
		(start 161.755582 -225.791776)
		(end 161.708592 -225.791776)
		(width 0.101854)
		(layer "F.Cu")
		(net "M_E_CPU1_SB_DQ<4>")
	)
	(segment
		(start 160.333944 -226.216718)
		(end 158.813246 -226.216718)
		(width 0.20066)
		(layer "F.Cu")
		(net "M_E_CPU1_SB_DQ<4>")
	)
	(segment
		(start 164.333682 -225.785426)
		(end 163.923726 -225.785426)
		(width 0.20066)
		(layer "F.Cu")
		(net "M_E_CPU1_SB_DQ<4>")
	)
	(segment
		(start 133.255766 -234.691936)
		(end 133.255766 -234.15625)
		(width 0.20066)
		(layer "F.Cu")
		(net "M_E_CPU1_SB_DQ<4>")
	)
	(segment
		(start 161.708592 -225.791776)
		(end 161.363914 -225.791776)
		(width 0.20066)
		(layer "F.Cu")
		(net "M_E_CPU1_SB_DQ<4>")
	)
	(segment
		(start 166.357046 -226.216718)
		(end 166.356792 -226.216972)
		(width 0.20066)
		(layer "F.Cu")
		(net "M_E_CPU1_SB_DQ<4>")
	)
	(segment
		(start 163.917376 -225.791776)
		(end 161.755582 -225.791776)
		(width 0.1016)
		(layer "F.Cu")
		(net "M_E_CPU1_SB_DQ<4>")
	)
	(segment
		(start 149.55393 -232.941368)
		(end 149.409912 -233.085386)
		(width 0.18288)
		(layer "In2.Cu")
		(net "M_E_CPU1_SB_DQ<4>")
	)
	(segment
		(start 139.876276 -232.967276)
		(end 139.364212 -232.967276)
		(width 0.088646)
		(layer "In2.Cu")
		(net "M_E_CPU1_SB_DQ<4>")
	)
	(segment
		(start 140.244322 -233.335322)
		(end 139.876276 -232.967276)
		(width 0.088646)
		(layer "In2.Cu")
		(net "M_E_CPU1_SB_DQ<4>")
	)
	(segment
		(start 149.350984 -232.465626)
		(end 149.55393 -232.668572)
		(width 0.18288)
		(layer "In2.Cu")
		(net "M_E_CPU1_SB_DQ<4>")
	)
	(segment
		(start 150.347172 -231.196642)
		(end 150.347172 -231.469438)
		(width 0.18288)
		(layer "In2.Cu")
		(net "M_E_CPU1_SB_DQ<4>")
	)
	(segment
		(start 152.317196 -230.178102)
		(end 152.0444 -230.178102)
		(width 0.18288)
		(layer "In2.Cu")
		(net "M_E_CPU1_SB_DQ<4>")
	)
	(segment
		(start 135.887968 -233.831892)
		(end 135.879078 -233.836972)
		(width 0.088646)
		(layer "In2.Cu")
		(net "M_E_CPU1_SB_DQ<4>")
	)
	(segment
		(start 134.947914 -234.480608)
		(end 134.943342 -234.477814)
		(width 0.088646)
		(layer "In2.Cu")
		(net "M_E_CPU1_SB_DQ<4>")
	)
	(segment
		(start 135.748268 -233.97337)
		(end 135.648192 -234.15244)
		(width 0.088646)
		(layer "In2.Cu")
		(net "M_E_CPU1_SB_DQ<4>")
	)
	(segment
		(start 150.550118 -231.94518)
		(end 150.32482 -232.170478)
		(width 0.18288)
		(layer "In2.Cu")
		(net "M_E_CPU1_SB_DQ<4>")
	)
	(segment
		(start 149.849078 -231.967532)
		(end 149.576282 -231.967532)
		(width 0.18288)
		(layer "In2.Cu")
		(net "M_E_CPU1_SB_DQ<4>")
	)
	(segment
		(start 151.568658 -229.975156)
		(end 151.34336 -230.200454)
		(width 0.18288)
		(layer "In2.Cu")
		(net "M_E_CPU1_SB_DQ<4>")
	)
	(segment
		(start 150.052024 -232.170478)
		(end 149.849078 -231.967532)
		(width 0.18288)
		(layer "In2.Cu")
		(net "M_E_CPU1_SB_DQ<4>")
	)
	(segment
		(start 140.645896 -233.335322)
		(end 140.244322 -233.335322)
		(width 0.088646)
		(layer "In2.Cu")
		(net "M_E_CPU1_SB_DQ<4>")
	)
	(segment
		(start 150.845266 -230.971344)
		(end 150.57247 -230.971344)
		(width 0.18288)
		(layer "In2.Cu")
		(net "M_E_CPU1_SB_DQ<4>")
	)
	(segment
		(start 151.048212 -231.17429)
		(end 150.845266 -230.971344)
		(width 0.18288)
		(layer "In2.Cu")
		(net "M_E_CPU1_SB_DQ<4>")
	)
	(segment
		(start 151.546306 -230.948992)
		(end 151.321008 -231.17429)
		(width 0.18288)
		(layer "In2.Cu")
		(net "M_E_CPU1_SB_DQ<4>")
	)
	(segment
		(start 151.34336 -230.200454)
		(end 151.34336 -230.47325)
		(width 0.18288)
		(layer "In2.Cu")
		(net "M_E_CPU1_SB_DQ<4>")
	)
	(segment
		(start 150.550118 -231.672384)
		(end 150.550118 -231.94518)
		(width 0.18288)
		(layer "In2.Cu")
		(net "M_E_CPU1_SB_DQ<4>")
	)
	(segment
		(start 149.350984 -232.19283)
		(end 149.350984 -232.465626)
		(width 0.18288)
		(layer "In2.Cu")
		(net "M_E_CPU1_SB_DQ<4>")
	)
	(segment
		(start 157.5054 -226.039172)
		(end 156.456126 -226.039172)
		(width 0.18288)
		(layer "In2.Cu")
		(net "M_E_CPU1_SB_DQ<4>")
	)
	(segment
		(start 151.546306 -230.676196)
		(end 151.546306 -230.948992)
		(width 0.18288)
		(layer "In2.Cu")
		(net "M_E_CPU1_SB_DQ<4>")
	)
	(segment
		(start 149.409912 -233.085386)
		(end 148.806408 -233.335322)
		(width 0.18288)
		(layer "In2.Cu")
		(net "M_E_CPU1_SB_DQ<4>")
	)
	(segment
		(start 150.57247 -230.971344)
		(end 150.347172 -231.196642)
		(width 0.18288)
		(layer "In2.Cu")
		(net "M_E_CPU1_SB_DQ<4>")
	)
	(segment
		(start 151.321008 -231.17429)
		(end 151.048212 -231.17429)
		(width 0.18288)
		(layer "In2.Cu")
		(net "M_E_CPU1_SB_DQ<4>")
	)
	(segment
		(start 148.806408 -233.335322)
		(end 140.645896 -233.335322)
		(width 0.18288)
		(layer "In2.Cu")
		(net "M_E_CPU1_SB_DQ<4>")
	)
	(segment
		(start 151.841454 -229.975156)
		(end 151.568658 -229.975156)
		(width 0.18288)
		(layer "In2.Cu")
		(net "M_E_CPU1_SB_DQ<4>")
	)
	(segment
		(start 156.456126 -226.039172)
		(end 152.317196 -230.178102)
		(width 0.18288)
		(layer "In2.Cu")
		(net "M_E_CPU1_SB_DQ<4>")
	)
	(segment
		(start 151.34336 -230.47325)
		(end 151.546306 -230.676196)
		(width 0.18288)
		(layer "In2.Cu")
		(net "M_E_CPU1_SB_DQ<4>")
	)
	(segment
		(start 157.682946 -226.216718)
		(end 157.5054 -226.039172)
		(width 0.18288)
		(layer "In2.Cu")
		(net "M_E_CPU1_SB_DQ<4>")
	)
	(segment
		(start 152.0444 -230.178102)
		(end 151.841454 -229.975156)
		(width 0.18288)
		(layer "In2.Cu")
		(net "M_E_CPU1_SB_DQ<4>")
	)
	(segment
		(start 150.32482 -232.170478)
		(end 150.052024 -232.170478)
		(width 0.18288)
		(layer "In2.Cu")
		(net "M_E_CPU1_SB_DQ<4>")
	)
	(segment
		(start 138.989816 -233.34218)
		(end 138.989816 -233.360722)
		(width 0.088646)
		(layer "In2.Cu")
		(net "M_E_CPU1_SB_DQ<4>")
	)
	(segment
		(start 134.008114 -234.480608)
		(end 133.60781 -234.25023)
		(width 0.088646)
		(layer "In2.Cu")
		(net "M_E_CPU1_SB_DQ<4>")
	)
	(segment
		(start 150.347172 -231.469438)
		(end 150.550118 -231.672384)
		(width 0.18288)
		(layer "In2.Cu")
		(net "M_E_CPU1_SB_DQ<4>")
	)
	(segment
		(start 149.55393 -232.668572)
		(end 149.55393 -232.941368)
		(width 0.18288)
		(layer "In2.Cu")
		(net "M_E_CPU1_SB_DQ<4>")
	)
	(segment
		(start 149.576282 -231.967532)
		(end 149.350984 -232.19283)
		(width 0.18288)
		(layer "In2.Cu")
		(net "M_E_CPU1_SB_DQ<4>")
	)
	(segment
		(start 135.523732 -234.313984)
		(end 135.466328 -234.371134)
		(width 0.088646)
		(layer "In2.Cu")
		(net "M_E_CPU1_SB_DQ<4>")
	)
	(segment
		(start 135.326882 -234.478068)
		(end 135.322564 -234.480608)
		(width 0.088646)
		(layer "In2.Cu")
		(net "M_E_CPU1_SB_DQ<4>")
	)
	(segment
		(start 134.953756 -234.48391)
		(end 134.947914 -234.480608)
		(width 0.088646)
		(layer "In2.Cu")
		(net "M_E_CPU1_SB_DQ<4>")
	)
	(arc
		(start 134.382764 -234.480608)
		(mid 134.195456 -234.530751)
		(end 134.008114 -234.480608)
		(width 0.088646)
		(layer "In2.Cu")
		(net "M_E_CPU1_SB_DQ<4>")
	)
	(arc
		(start 137.767568 -233.831892)
		(mid 137.484866 -233.907634)
		(end 137.202164 -233.831892)
		(width 0.088646)
		(layer "In2.Cu")
		(net "M_E_CPU1_SB_DQ<4>")
	)
	(arc
		(start 134.943342 -234.477814)
		(mid 134.662678 -234.404806)
		(end 134.382764 -234.480608)
		(width 0.088646)
		(layer "In2.Cu")
		(net "M_E_CPU1_SB_DQ<4>")
	)
	(arc
		(start 135.648192 -234.15244)
		(mid 135.622013 -234.192666)
		(end 135.590534 -234.228894)
		(width 0.088646)
		(layer "In2.Cu")
		(net "M_E_CPU1_SB_DQ<4>")
	)
	(arc
		(start 135.590534 -234.228894)
		(mid 135.559627 -234.273397)
		(end 135.523732 -234.313984)
		(width 0.088646)
		(layer "In2.Cu")
		(net "M_E_CPU1_SB_DQ<4>")
	)
	(arc
		(start 138.707368 -233.831892)
		(mid 138.424666 -233.907634)
		(end 138.141964 -233.831892)
		(width 0.088646)
		(layer "In2.Cu")
		(net "M_E_CPU1_SB_DQ<4>")
	)
	(arc
		(start 135.879078 -233.836972)
		(mid 135.80496 -233.896809)
		(end 135.748268 -233.97337)
		(width 0.088646)
		(layer "In2.Cu")
		(net "M_E_CPU1_SB_DQ<4>")
	)
	(arc
		(start 137.202164 -233.831892)
		(mid 137.014966 -233.781749)
		(end 136.827768 -233.831892)
		(width 0.088646)
		(layer "In2.Cu")
		(net "M_E_CPU1_SB_DQ<4>")
	)
	(arc
		(start 133.60781 -234.25023)
		(mid 133.437966 -234.180087)
		(end 133.255766 -234.15625)
		(width 0.088646)
		(layer "In2.Cu")
		(net "M_E_CPU1_SB_DQ<4>")
	)
	(arc
		(start 136.827768 -233.831892)
		(mid 136.545066 -233.907634)
		(end 136.262364 -233.831892)
		(width 0.088646)
		(layer "In2.Cu")
		(net "M_E_CPU1_SB_DQ<4>")
	)
	(arc
		(start 138.989816 -233.360722)
		(mid 138.909654 -233.632911)
		(end 138.707368 -233.831892)
		(width 0.088646)
		(layer "In2.Cu")
		(net "M_E_CPU1_SB_DQ<4>")
	)
	(arc
		(start 139.364212 -232.967276)
		(mid 139.099443 -233.077262)
		(end 138.989816 -233.34218)
		(width 0.088646)
		(layer "In2.Cu")
		(net "M_E_CPU1_SB_DQ<4>")
	)
	(arc
		(start 136.262364 -233.831892)
		(mid 136.075166 -233.781749)
		(end 135.887968 -233.831892)
		(width 0.088646)
		(layer "In2.Cu")
		(net "M_E_CPU1_SB_DQ<4>")
	)
	(arc
		(start 135.322564 -234.480608)
		(mid 135.13861 -234.530737)
		(end 134.953756 -234.48391)
		(width 0.088646)
		(layer "In2.Cu")
		(net "M_E_CPU1_SB_DQ<4>")
	)
	(arc
		(start 135.466328 -234.371134)
		(mid 135.40011 -234.429172)
		(end 135.326882 -234.478068)
		(width 0.088646)
		(layer "In2.Cu")
		(net "M_E_CPU1_SB_DQ<4>")
	)
	(arc
		(start 138.141964 -233.831892)
		(mid 137.954766 -233.781749)
		(end 137.767568 -233.831892)
		(width 0.088646)
		(layer "In2.Cu")
		(net "M_E_CPU1_SB_DQ<4>")
	)
	(segment
		(start 168.06926 -230.064818)
		(end 167.367458 -230.064818)
		(width 0.20066)
		(layer "F.Cu")
		(net "M_E_CPU1_SB_DQ<3>")
	)
	(segment
		(start 168.265348 -229.598982)
		(end 168.265348 -229.86873)
		(width 0.20066)
		(layer "F.Cu")
		(net "M_E_CPU1_SB_DQ<3>")
	)
	(segment
		(start 167.344344 -230.041704)
		(end 165.366954 -230.041704)
		(width 0.1016)
		(layer "F.Cu")
		(net "M_E_CPU1_SB_DQ<3>")
	)
	(segment
		(start 168.883584 -229.364794)
		(end 168.499536 -229.364794)
		(width 0.20066)
		(layer "F.Cu")
		(net "M_E_CPU1_SB_DQ<3>")
	)
	(segment
		(start 170.457114 -229.616762)
		(end 169.135552 -229.616762)
		(width 0.20066)
		(layer "F.Cu")
		(net "M_E_CPU1_SB_DQ<3>")
	)
	(segment
		(start 167.367458 -230.064818)
		(end 167.344344 -230.041704)
		(width 0.1016)
		(layer "F.Cu")
		(net "M_E_CPU1_SB_DQ<3>")
	)
	(segment
		(start 165.335458 -230.055674)
		(end 165.043866 -230.055674)
		(width 0.20066)
		(layer "F.Cu")
		(net "M_E_CPU1_SB_DQ<3>")
	)
	(segment
		(start 169.135552 -229.616762)
		(end 168.883584 -229.364794)
		(width 0.20066)
		(layer "F.Cu")
		(net "M_E_CPU1_SB_DQ<3>")
	)
	(segment
		(start 164.604954 -229.616762)
		(end 162.913314 -229.616762)
		(width 0.20066)
		(layer "F.Cu")
		(net "M_E_CPU1_SB_DQ<3>")
	)
	(segment
		(start 165.366954 -230.041704)
		(end 165.352984 -230.055674)
		(width 0.1016)
		(layer "F.Cu")
		(net "M_E_CPU1_SB_DQ<3>")
	)
	(segment
		(start 135.135112 -236.319822)
		(end 135.135112 -235.784136)
		(width 0.20066)
		(layer "F.Cu")
		(net "M_E_CPU1_SB_DQ<3>")
	)
	(segment
		(start 168.265348 -229.86873)
		(end 168.06926 -230.064818)
		(width 0.20066)
		(layer "F.Cu")
		(net "M_E_CPU1_SB_DQ<3>")
	)
	(segment
		(start 168.499536 -229.364794)
		(end 168.265348 -229.598982)
		(width 0.20066)
		(layer "F.Cu")
		(net "M_E_CPU1_SB_DQ<3>")
	)
	(segment
		(start 165.352984 -230.055674)
		(end 165.335458 -230.055674)
		(width 0.101854)
		(layer "F.Cu")
		(net "M_E_CPU1_SB_DQ<3>")
	)
	(segment
		(start 165.043866 -230.055674)
		(end 164.604954 -229.616762)
		(width 0.20066)
		(layer "F.Cu")
		(net "M_E_CPU1_SB_DQ<3>")
	)
	(segment
		(start 135.135112 -235.784136)
		(end 135.135366 -235.783882)
		(width 0.20066)
		(layer "F.Cu")
		(net "M_E_CPU1_SB_DQ<3>")
	)
	(segment
		(start 161.783014 -229.616762)
		(end 162.913314 -229.616762)
		(width 0.20066)
		(layer "F.Cu")
		(net "M_E_CPU1_SB_DQ<3>")
	)
	(segment
		(start 159.176974 -229.37597)
		(end 159.176974 -229.746556)
		(width 0.18288)
		(layer "In2.Cu")
		(net "M_E_CPU1_SB_DQ<3>")
	)
	(segment
		(start 161.357056 -229.190804)
		(end 160.675828 -229.190804)
		(width 0.18288)
		(layer "In2.Cu")
		(net "M_E_CPU1_SB_DQ<3>")
	)
	(segment
		(start 159.789876 -229.030784)
		(end 159.629856 -229.190804)
		(width 0.18288)
		(layer "In2.Cu")
		(net "M_E_CPU1_SB_DQ<3>")
	)
	(segment
		(start 160.355788 -228.407214)
		(end 159.949896 -228.407214)
		(width 0.18288)
		(layer "In2.Cu")
		(net "M_E_CPU1_SB_DQ<3>")
	)
	(segment
		(start 158.966408 -229.957122)
		(end 158.618428 -229.957122)
		(width 0.18288)
		(layer "In2.Cu")
		(net "M_E_CPU1_SB_DQ<3>")
	)
	(segment
		(start 140.021056 -235.684314)
		(end 139.632436 -236.072934)
		(width 0.088646)
		(layer "In2.Cu")
		(net "M_E_CPU1_SB_DQ<3>")
	)
	(segment
		(start 137.216896 -236.099604)
		(end 137.202164 -236.10824)
		(width 0.088646)
		(layer "In2.Cu")
		(net "M_E_CPU1_SB_DQ<3>")
	)
	(segment
		(start 159.789876 -228.567234)
		(end 159.789876 -229.030784)
		(width 0.18288)
		(layer "In2.Cu")
		(net "M_E_CPU1_SB_DQ<3>")
	)
	(segment
		(start 158.458408 -229.350824)
		(end 158.298388 -229.190804)
		(width 0.18288)
		(layer "In2.Cu")
		(net "M_E_CPU1_SB_DQ<3>")
	)
	(segment
		(start 135.887968 -236.10824)
		(end 135.707374 -236.0041)
		(width 0.088646)
		(layer "In2.Cu")
		(net "M_E_CPU1_SB_DQ<3>")
	)
	(segment
		(start 158.458408 -229.797102)
		(end 158.458408 -229.350824)
		(width 0.18288)
		(layer "In2.Cu")
		(net "M_E_CPU1_SB_DQ<3>")
	)
	(segment
		(start 161.783014 -229.616762)
		(end 161.357056 -229.190804)
		(width 0.18288)
		(layer "In2.Cu")
		(net "M_E_CPU1_SB_DQ<3>")
	)
	(segment
		(start 148.919184 -235.684314)
		(end 140.264896 -235.684314)
		(width 0.18288)
		(layer "In2.Cu")
		(net "M_E_CPU1_SB_DQ<3>")
	)
	(segment
		(start 136.277096 -236.099604)
		(end 136.262364 -236.10824)
		(width 0.088646)
		(layer "In2.Cu")
		(net "M_E_CPU1_SB_DQ<3>")
	)
	(segment
		(start 140.264896 -235.684314)
		(end 140.021056 -235.684314)
		(width 0.088646)
		(layer "In2.Cu")
		(net "M_E_CPU1_SB_DQ<3>")
	)
	(segment
		(start 139.096496 -236.099604)
		(end 139.081764 -236.10824)
		(width 0.088646)
		(layer "In2.Cu")
		(net "M_E_CPU1_SB_DQ<3>")
	)
	(segment
		(start 159.629856 -229.190804)
		(end 159.36214 -229.190804)
		(width 0.18288)
		(layer "In2.Cu")
		(net "M_E_CPU1_SB_DQ<3>")
	)
	(segment
		(start 160.515808 -229.030784)
		(end 160.515808 -228.567234)
		(width 0.18288)
		(layer "In2.Cu")
		(net "M_E_CPU1_SB_DQ<3>")
	)
	(segment
		(start 156.55544 -229.190804)
		(end 150.870158 -234.876086)
		(width 0.18288)
		(layer "In2.Cu")
		(net "M_E_CPU1_SB_DQ<3>")
	)
	(segment
		(start 159.949896 -228.407214)
		(end 159.789876 -228.567234)
		(width 0.18288)
		(layer "In2.Cu")
		(net "M_E_CPU1_SB_DQ<3>")
	)
	(segment
		(start 135.707374 -236.0041)
		(end 135.494014 -235.880402)
		(width 0.088646)
		(layer "In2.Cu")
		(net "M_E_CPU1_SB_DQ<3>")
	)
	(segment
		(start 150.870158 -234.876086)
		(end 148.919184 -235.684314)
		(width 0.18288)
		(layer "In2.Cu")
		(net "M_E_CPU1_SB_DQ<3>")
	)
	(segment
		(start 159.36214 -229.190804)
		(end 159.176974 -229.37597)
		(width 0.18288)
		(layer "In2.Cu")
		(net "M_E_CPU1_SB_DQ<3>")
	)
	(segment
		(start 160.515808 -228.567234)
		(end 160.355788 -228.407214)
		(width 0.18288)
		(layer "In2.Cu")
		(net "M_E_CPU1_SB_DQ<3>")
	)
	(segment
		(start 159.176974 -229.746556)
		(end 158.966408 -229.957122)
		(width 0.18288)
		(layer "In2.Cu")
		(net "M_E_CPU1_SB_DQ<3>")
	)
	(segment
		(start 139.632436 -236.072934)
		(end 139.574778 -236.072934)
		(width 0.088646)
		(layer "In2.Cu")
		(net "M_E_CPU1_SB_DQ<3>")
	)
	(segment
		(start 158.298388 -229.190804)
		(end 156.55544 -229.190804)
		(width 0.18288)
		(layer "In2.Cu")
		(net "M_E_CPU1_SB_DQ<3>")
	)
	(segment
		(start 160.675828 -229.190804)
		(end 160.515808 -229.030784)
		(width 0.18288)
		(layer "In2.Cu")
		(net "M_E_CPU1_SB_DQ<3>")
	)
	(segment
		(start 158.618428 -229.957122)
		(end 158.458408 -229.797102)
		(width 0.18288)
		(layer "In2.Cu")
		(net "M_E_CPU1_SB_DQ<3>")
	)
	(segment
		(start 138.156696 -236.099604)
		(end 138.141964 -236.10824)
		(width 0.088646)
		(layer "In2.Cu")
		(net "M_E_CPU1_SB_DQ<3>")
	)
	(arc
		(start 137.202164 -236.10824)
		(mid 137.014966 -236.158383)
		(end 136.827768 -236.10824)
		(width 0.088646)
		(layer "In2.Cu")
		(net "M_E_CPU1_SB_DQ<3>")
	)
	(arc
		(start 139.574778 -236.072934)
		(mid 139.33268 -236.033162)
		(end 139.096496 -236.099604)
		(width 0.088646)
		(layer "In2.Cu")
		(net "M_E_CPU1_SB_DQ<3>")
	)
	(arc
		(start 138.707368 -236.10824)
		(mid 138.433139 -236.032315)
		(end 138.156696 -236.099604)
		(width 0.088646)
		(layer "In2.Cu")
		(net "M_E_CPU1_SB_DQ<3>")
	)
	(arc
		(start 136.827768 -236.10824)
		(mid 136.553539 -236.032315)
		(end 136.277096 -236.099604)
		(width 0.088646)
		(layer "In2.Cu")
		(net "M_E_CPU1_SB_DQ<3>")
	)
	(arc
		(start 136.262364 -236.10824)
		(mid 136.075166 -236.158383)
		(end 135.887968 -236.10824)
		(width 0.088646)
		(layer "In2.Cu")
		(net "M_E_CPU1_SB_DQ<3>")
	)
	(arc
		(start 138.141964 -236.10824)
		(mid 137.954766 -236.158383)
		(end 137.767568 -236.10824)
		(width 0.088646)
		(layer "In2.Cu")
		(net "M_E_CPU1_SB_DQ<3>")
	)
	(arc
		(start 139.081764 -236.10824)
		(mid 138.894566 -236.158383)
		(end 138.707368 -236.10824)
		(width 0.088646)
		(layer "In2.Cu")
		(net "M_E_CPU1_SB_DQ<3>")
	)
	(arc
		(start 137.767568 -236.10824)
		(mid 137.493339 -236.032315)
		(end 137.216896 -236.099604)
		(width 0.088646)
		(layer "In2.Cu")
		(net "M_E_CPU1_SB_DQ<3>")
	)
	(arc
		(start 135.494014 -235.880402)
		(mid 135.321062 -235.808465)
		(end 135.135366 -235.783882)
		(width 0.088646)
		(layer "In2.Cu")
		(net "M_E_CPU1_SB_DQ<3>")
	)
	(segment
		(start 137.647934 -212.034628)
		(end 137.647934 -208.24063)
		(width 0.20066)
		(layer "F.Cu")
		(net "M_E_CPU1_SB_DQ<31>")
	)
	(segment
		(start 147.20443 -197.468236)
		(end 148.59635 -196.809614)
		(width 0.20066)
		(layer "F.Cu")
		(net "M_E_CPU1_SB_DQ<31>")
	)
	(segment
		(start 150.039324 -196.371972)
		(end 152.194768 -196.052186)
		(width 0.20066)
		(layer "F.Cu")
		(net "M_E_CPU1_SB_DQ<31>")
	)
	(segment
		(start 159.823658 -196.05752)
		(end 160.265364 -196.05752)
		(width 0.20066)
		(layer "F.Cu")
		(net "M_E_CPU1_SB_DQ<31>")
	)
	(segment
		(start 168.265348 -195.598796)
		(end 168.265348 -195.861432)
		(width 0.20066)
		(layer "F.Cu")
		(net "M_E_CPU1_SB_DQ<31>")
	)
	(segment
		(start 137.865104 -207.14843)
		(end 139.29106 -203.706222)
		(width 0.20066)
		(layer "F.Cu")
		(net "M_E_CPU1_SB_DQ<31>")
	)
	(segment
		(start 137.647934 -208.24063)
		(end 137.865104 -207.14843)
		(width 0.20066)
		(layer "F.Cu")
		(net "M_E_CPU1_SB_DQ<31>")
	)
	(segment
		(start 169.135552 -195.616576)
		(end 168.883584 -195.364608)
		(width 0.20066)
		(layer "F.Cu")
		(net "M_E_CPU1_SB_DQ<31>")
	)
	(segment
		(start 148.59635 -196.809614)
		(end 150.039324 -196.371972)
		(width 0.20066)
		(layer "F.Cu")
		(net "M_E_CPU1_SB_DQ<31>")
	)
	(segment
		(start 139.707112 -215.287098)
		(end 139.26439 -214.844376)
		(width 0.1016)
		(layer "F.Cu")
		(net "M_E_CPU1_SB_DQ<31>")
	)
	(segment
		(start 139.707112 -224.825052)
		(end 139.707112 -215.287098)
		(width 0.1016)
		(layer "F.Cu")
		(net "M_E_CPU1_SB_DQ<31>")
	)
	(segment
		(start 139.244578 -225.287586)
		(end 139.41298 -225.119184)
		(width 0.088646)
		(layer "F.Cu")
		(net "M_E_CPU1_SB_DQ<31>")
	)
	(segment
		(start 167.367458 -196.05752)
		(end 167.351456 -196.041518)
		(width 0.1016)
		(layer "F.Cu")
		(net "M_E_CPU1_SB_DQ<31>")
	)
	(segment
		(start 168.499536 -195.364608)
		(end 168.265348 -195.598796)
		(width 0.20066)
		(layer "F.Cu")
		(net "M_E_CPU1_SB_DQ<31>")
	)
	(segment
		(start 142.155672 -200.84161)
		(end 147.20443 -197.468236)
		(width 0.20066)
		(layer "F.Cu")
		(net "M_E_CPU1_SB_DQ<31>")
	)
	(segment
		(start 168.265348 -195.861432)
		(end 168.06926 -196.05752)
		(width 0.20066)
		(layer "F.Cu")
		(net "M_E_CPU1_SB_DQ<31>")
	)
	(segment
		(start 138.689588 -226.00412)
		(end 138.949938 -225.74377)
		(width 0.088646)
		(layer "F.Cu")
		(net "M_E_CPU1_SB_DQ<31>")
	)
	(segment
		(start 157.825694 -196.052186)
		(end 157.836362 -196.041518)
		(width 0.101854)
		(layer "F.Cu")
		(net "M_E_CPU1_SB_DQ<31>")
	)
	(segment
		(start 164.604954 -195.616576)
		(end 162.913314 -195.616576)
		(width 0.20066)
		(layer "F.Cu")
		(net "M_E_CPU1_SB_DQ<31>")
	)
	(segment
		(start 168.883584 -195.364608)
		(end 168.499536 -195.364608)
		(width 0.20066)
		(layer "F.Cu")
		(net "M_E_CPU1_SB_DQ<31>")
	)
	(segment
		(start 138.54049 -226.104704)
		(end 138.611864 -226.063556)
		(width 0.088646)
		(layer "F.Cu")
		(net "M_E_CPU1_SB_DQ<31>")
	)
	(segment
		(start 165.369494 -196.052186)
		(end 165.335458 -196.052186)
		(width 0.101854)
		(layer "F.Cu")
		(net "M_E_CPU1_SB_DQ<31>")
	)
	(segment
		(start 157.791658 -196.052186)
		(end 157.825694 -196.052186)
		(width 0.101854)
		(layer "F.Cu")
		(net "M_E_CPU1_SB_DQ<31>")
	)
	(segment
		(start 159.807656 -196.041518)
		(end 159.823658 -196.05752)
		(width 0.1016)
		(layer "F.Cu")
		(net "M_E_CPU1_SB_DQ<31>")
	)
	(segment
		(start 161.330132 -195.616576)
		(end 162.913314 -195.616576)
		(width 0.20066)
		(layer "F.Cu")
		(net "M_E_CPU1_SB_DQ<31>")
	)
	(segment
		(start 139.41298 -225.119184)
		(end 139.707112 -224.825052)
		(width 0.1016)
		(layer "F.Cu")
		(net "M_E_CPU1_SB_DQ<31>")
	)
	(segment
		(start 138.949938 -225.74377)
		(end 139.244578 -225.287586)
		(width 0.088646)
		(layer "F.Cu")
		(net "M_E_CPU1_SB_DQ<31>")
	)
	(segment
		(start 170.457114 -195.616576)
		(end 169.135552 -195.616576)
		(width 0.20066)
		(layer "F.Cu")
		(net "M_E_CPU1_SB_DQ<31>")
	)
	(segment
		(start 139.29106 -203.706222)
		(end 142.155672 -200.84161)
		(width 0.20066)
		(layer "F.Cu")
		(net "M_E_CPU1_SB_DQ<31>")
	)
	(segment
		(start 165.040564 -196.052186)
		(end 164.604954 -195.616576)
		(width 0.20066)
		(layer "F.Cu")
		(net "M_E_CPU1_SB_DQ<31>")
	)
	(segment
		(start 168.06926 -196.05752)
		(end 167.367458 -196.05752)
		(width 0.20066)
		(layer "F.Cu")
		(net "M_E_CPU1_SB_DQ<31>")
	)
	(segment
		(start 138.491468 -214.071454)
		(end 137.647934 -212.034628)
		(width 0.20066)
		(layer "F.Cu")
		(net "M_E_CPU1_SB_DQ<31>")
	)
	(segment
		(start 160.265364 -196.05752)
		(end 161.330132 -195.616576)
		(width 0.20066)
		(layer "F.Cu")
		(net "M_E_CPU1_SB_DQ<31>")
	)
	(segment
		(start 139.26439 -214.844376)
		(end 138.491468 -214.071454)
		(width 0.20066)
		(layer "F.Cu")
		(net "M_E_CPU1_SB_DQ<31>")
	)
	(segment
		(start 165.335458 -196.052186)
		(end 165.040564 -196.052186)
		(width 0.20066)
		(layer "F.Cu")
		(net "M_E_CPU1_SB_DQ<31>")
	)
	(segment
		(start 167.351456 -196.041518)
		(end 165.380162 -196.041518)
		(width 0.1016)
		(layer "F.Cu")
		(net "M_E_CPU1_SB_DQ<31>")
	)
	(segment
		(start 157.836362 -196.041518)
		(end 159.807656 -196.041518)
		(width 0.1016)
		(layer "F.Cu")
		(net "M_E_CPU1_SB_DQ<31>")
	)
	(segment
		(start 165.380162 -196.041518)
		(end 165.369494 -196.052186)
		(width 0.101854)
		(layer "F.Cu")
		(net "M_E_CPU1_SB_DQ<31>")
	)
	(segment
		(start 152.194768 -196.052186)
		(end 157.791658 -196.052186)
		(width 0.20066)
		(layer "F.Cu")
		(net "M_E_CPU1_SB_DQ<31>")
	)
	(arc
		(start 137.954766 -226.553268)
		(mid 138.232837 -226.309674)
		(end 138.54049 -226.104704)
		(width 0.088646)
		(layer "F.Cu")
		(net "M_E_CPU1_SB_DQ<31>")
	)
	(arc
		(start 138.611864 -226.063556)
		(mid 138.652673 -226.036384)
		(end 138.689588 -226.00412)
		(width 0.088646)
		(layer "F.Cu")
		(net "M_E_CPU1_SB_DQ<31>")
	)
	(segment
		(start 169.135552 -197.316598)
		(end 168.883584 -197.06463)
		(width 0.20066)
		(layer "F.Cu")
		(net "M_E_CPU1_SB_DQ<30>")
	)
	(segment
		(start 164.604954 -197.316598)
		(end 162.913314 -197.316598)
		(width 0.20066)
		(layer "F.Cu")
		(net "M_E_CPU1_SB_DQ<30>")
	)
	(segment
		(start 140.215874 -213.87816)
		(end 139.499594 -213.16188)
		(width 0.20066)
		(layer "F.Cu")
		(net "M_E_CPU1_SB_DQ<30>")
	)
	(segment
		(start 140.316712 -226.11588)
		(end 140.316712 -213.978998)
		(width 0.1016)
		(layer "F.Cu")
		(net "M_E_CPU1_SB_DQ<30>")
	)
	(segment
		(start 157.064456 -197.335902)
		(end 157.48 -197.751446)
		(width 0.20066)
		(layer "F.Cu")
		(net "M_E_CPU1_SB_DQ<30>")
	)
	(segment
		(start 165.369494 -197.752208)
		(end 165.335458 -197.752208)
		(width 0.101854)
		(layer "F.Cu")
		(net "M_E_CPU1_SB_DQ<30>")
	)
	(segment
		(start 157.750764 -197.74154)
		(end 158.083504 -197.74154)
		(width 0.101854)
		(layer "F.Cu")
		(net "M_E_CPU1_SB_DQ<30>")
	)
	(segment
		(start 155.852622 -197.335902)
		(end 157.064456 -197.335902)
		(width 0.20066)
		(layer "F.Cu")
		(net "M_E_CPU1_SB_DQ<30>")
	)
	(segment
		(start 148.60016 -198.223378)
		(end 149.069806 -198.080884)
		(width 0.20066)
		(layer "F.Cu")
		(net "M_E_CPU1_SB_DQ<30>")
	)
	(segment
		(start 147.837906 -198.584058)
		(end 148.60016 -198.223378)
		(width 0.20066)
		(layer "F.Cu")
		(net "M_E_CPU1_SB_DQ<30>")
	)
	(segment
		(start 158.083504 -197.74154)
		(end 159.807656 -197.74154)
		(width 0.1016)
		(layer "F.Cu")
		(net "M_E_CPU1_SB_DQ<30>")
	)
	(segment
		(start 138.927078 -211.779866)
		(end 138.927078 -208.3689)
		(width 0.20066)
		(layer "F.Cu")
		(net "M_E_CPU1_SB_DQ<30>")
	)
	(segment
		(start 165.380162 -197.74154)
		(end 165.369494 -197.752208)
		(width 0.101854)
		(layer "F.Cu")
		(net "M_E_CPU1_SB_DQ<30>")
	)
	(segment
		(start 168.265348 -197.298818)
		(end 168.265348 -197.556882)
		(width 0.20066)
		(layer "F.Cu")
		(net "M_E_CPU1_SB_DQ<30>")
	)
	(segment
		(start 140.316712 -213.978998)
		(end 140.215874 -213.87816)
		(width 0.1016)
		(layer "F.Cu")
		(net "M_E_CPU1_SB_DQ<30>")
	)
	(segment
		(start 140.058394 -226.374198)
		(end 140.316712 -226.11588)
		(width 0.1016)
		(layer "F.Cu")
		(net "M_E_CPU1_SB_DQ<30>")
	)
	(segment
		(start 168.883584 -197.06463)
		(end 168.499536 -197.06463)
		(width 0.20066)
		(layer "F.Cu")
		(net "M_E_CPU1_SB_DQ<30>")
	)
	(segment
		(start 138.927078 -208.3689)
		(end 139.095988 -207.520032)
		(width 0.20066)
		(layer "F.Cu")
		(net "M_E_CPU1_SB_DQ<30>")
	)
	(segment
		(start 140.359384 -204.47)
		(end 143.03883 -201.790554)
		(width 0.20066)
		(layer "F.Cu")
		(net "M_E_CPU1_SB_DQ<30>")
	)
	(segment
		(start 157.740858 -197.751446)
		(end 157.750764 -197.74154)
		(width 0.101854)
		(layer "F.Cu")
		(net "M_E_CPU1_SB_DQ<30>")
	)
	(segment
		(start 170.457114 -197.316598)
		(end 169.135552 -197.316598)
		(width 0.20066)
		(layer "F.Cu")
		(net "M_E_CPU1_SB_DQ<30>")
	)
	(segment
		(start 168.265348 -197.556882)
		(end 168.064688 -197.757542)
		(width 0.20066)
		(layer "F.Cu")
		(net "M_E_CPU1_SB_DQ<30>")
	)
	(segment
		(start 160.72612 -197.316598)
		(end 162.913314 -197.316598)
		(width 0.20066)
		(layer "F.Cu")
		(net "M_E_CPU1_SB_DQ<30>")
	)
	(segment
		(start 165.335458 -197.752208)
		(end 165.040564 -197.752208)
		(width 0.20066)
		(layer "F.Cu")
		(net "M_E_CPU1_SB_DQ<30>")
	)
	(segment
		(start 155.10764 -198.080884)
		(end 155.852622 -197.335902)
		(width 0.20066)
		(layer "F.Cu")
		(net "M_E_CPU1_SB_DQ<30>")
	)
	(segment
		(start 168.064688 -197.757542)
		(end 167.367458 -197.757542)
		(width 0.20066)
		(layer "F.Cu")
		(net "M_E_CPU1_SB_DQ<30>")
	)
	(segment
		(start 165.040564 -197.752208)
		(end 164.604954 -197.316598)
		(width 0.20066)
		(layer "F.Cu")
		(net "M_E_CPU1_SB_DQ<30>")
	)
	(segment
		(start 157.48 -197.751446)
		(end 157.740858 -197.751446)
		(width 0.20066)
		(layer "F.Cu")
		(net "M_E_CPU1_SB_DQ<30>")
	)
	(segment
		(start 168.499536 -197.06463)
		(end 168.265348 -197.298818)
		(width 0.20066)
		(layer "F.Cu")
		(net "M_E_CPU1_SB_DQ<30>")
	)
	(segment
		(start 159.899858 -197.757542)
		(end 160.285176 -197.757542)
		(width 0.20066)
		(layer "F.Cu")
		(net "M_E_CPU1_SB_DQ<30>")
	)
	(segment
		(start 138.424666 -227.367084)
		(end 138.87958 -226.91217)
		(width 0.088646)
		(layer "F.Cu")
		(net "M_E_CPU1_SB_DQ<30>")
	)
	(segment
		(start 167.367458 -197.757542)
		(end 167.351456 -197.74154)
		(width 0.1016)
		(layer "F.Cu")
		(net "M_E_CPU1_SB_DQ<30>")
	)
	(segment
		(start 139.520422 -226.91217)
		(end 140.058394 -226.374198)
		(width 0.088646)
		(layer "F.Cu")
		(net "M_E_CPU1_SB_DQ<30>")
	)
	(segment
		(start 160.285176 -197.757542)
		(end 160.72612 -197.316598)
		(width 0.20066)
		(layer "F.Cu")
		(net "M_E_CPU1_SB_DQ<30>")
	)
	(segment
		(start 143.03883 -201.790554)
		(end 147.837906 -198.584058)
		(width 0.20066)
		(layer "F.Cu")
		(net "M_E_CPU1_SB_DQ<30>")
	)
	(segment
		(start 138.87958 -226.91217)
		(end 139.520422 -226.91217)
		(width 0.088646)
		(layer "F.Cu")
		(net "M_E_CPU1_SB_DQ<30>")
	)
	(segment
		(start 139.499594 -213.16188)
		(end 138.927078 -211.779866)
		(width 0.20066)
		(layer "F.Cu")
		(net "M_E_CPU1_SB_DQ<30>")
	)
	(segment
		(start 139.095988 -207.520032)
		(end 140.359384 -204.47)
		(width 0.20066)
		(layer "F.Cu")
		(net "M_E_CPU1_SB_DQ<30>")
	)
	(segment
		(start 159.807656 -197.74154)
		(end 159.823658 -197.757542)
		(width 0.1016)
		(layer "F.Cu")
		(net "M_E_CPU1_SB_DQ<30>")
	)
	(segment
		(start 159.823658 -197.757542)
		(end 159.899858 -197.757542)
		(width 0.101854)
		(layer "F.Cu")
		(net "M_E_CPU1_SB_DQ<30>")
	)
	(segment
		(start 149.069806 -198.080884)
		(end 155.10764 -198.080884)
		(width 0.20066)
		(layer "F.Cu")
		(net "M_E_CPU1_SB_DQ<30>")
	)
	(segment
		(start 167.351456 -197.74154)
		(end 165.380162 -197.74154)
		(width 0.1016)
		(layer "F.Cu")
		(net "M_E_CPU1_SB_DQ<30>")
	)
	(segment
		(start 167.354504 -231.741726)
		(end 165.366954 -231.741726)
		(width 0.1016)
		(layer "F.Cu")
		(net "M_E_CPU1_SB_DQ<2>")
	)
	(segment
		(start 165.044882 -231.756712)
		(end 164.604954 -231.316784)
		(width 0.20066)
		(layer "F.Cu")
		(net "M_E_CPU1_SB_DQ<2>")
	)
	(segment
		(start 165.351968 -231.756712)
		(end 165.335458 -231.756712)
		(width 0.101854)
		(layer "F.Cu")
		(net "M_E_CPU1_SB_DQ<2>")
	)
	(segment
		(start 168.265348 -231.299004)
		(end 168.265348 -231.558592)
		(width 0.20066)
		(layer "F.Cu")
		(net "M_E_CPU1_SB_DQ<2>")
	)
	(segment
		(start 169.135552 -231.316784)
		(end 168.883584 -231.064816)
		(width 0.20066)
		(layer "F.Cu")
		(net "M_E_CPU1_SB_DQ<2>")
	)
	(segment
		(start 168.883584 -231.064816)
		(end 168.499536 -231.064816)
		(width 0.20066)
		(layer "F.Cu")
		(net "M_E_CPU1_SB_DQ<2>")
	)
	(segment
		(start 167.367458 -231.75468)
		(end 167.354504 -231.741726)
		(width 0.1016)
		(layer "F.Cu")
		(net "M_E_CPU1_SB_DQ<2>")
	)
	(segment
		(start 165.335458 -231.756712)
		(end 165.044882 -231.756712)
		(width 0.20066)
		(layer "F.Cu")
		(net "M_E_CPU1_SB_DQ<2>")
	)
	(segment
		(start 168.265348 -231.558592)
		(end 168.06926 -231.75468)
		(width 0.20066)
		(layer "F.Cu")
		(net "M_E_CPU1_SB_DQ<2>")
	)
	(segment
		(start 134.665466 -237.133892)
		(end 134.665466 -236.597952)
		(width 0.20066)
		(layer "F.Cu")
		(net "M_E_CPU1_SB_DQ<2>")
	)
	(segment
		(start 168.06926 -231.75468)
		(end 167.367458 -231.75468)
		(width 0.20066)
		(layer "F.Cu")
		(net "M_E_CPU1_SB_DQ<2>")
	)
	(segment
		(start 170.457114 -231.316784)
		(end 169.135552 -231.316784)
		(width 0.20066)
		(layer "F.Cu")
		(net "M_E_CPU1_SB_DQ<2>")
	)
	(segment
		(start 164.604954 -231.316784)
		(end 162.913314 -231.316784)
		(width 0.20066)
		(layer "F.Cu")
		(net "M_E_CPU1_SB_DQ<2>")
	)
	(segment
		(start 168.499536 -231.064816)
		(end 168.265348 -231.299004)
		(width 0.20066)
		(layer "F.Cu")
		(net "M_E_CPU1_SB_DQ<2>")
	)
	(segment
		(start 165.366954 -231.741726)
		(end 165.351968 -231.756712)
		(width 0.1016)
		(layer "F.Cu")
		(net "M_E_CPU1_SB_DQ<2>")
	)
	(segment
		(start 161.783014 -231.316784)
		(end 162.913314 -231.316784)
		(width 0.20066)
		(layer "F.Cu")
		(net "M_E_CPU1_SB_DQ<2>")
	)
	(segment
		(start 154.557984 -232.991152)
		(end 154.27198 -232.991152)
		(width 0.18288)
		(layer "In2.Cu")
		(net "M_E_CPU1_SB_DQ<2>")
	)
	(segment
		(start 136.357614 -236.922056)
		(end 136.342882 -236.91342)
		(width 0.088646)
		(layer "In2.Cu")
		(net "M_E_CPU1_SB_DQ<2>")
	)
	(segment
		(start 155.475432 -233.330496)
		(end 154.897328 -233.330496)
		(width 0.18288)
		(layer "In2.Cu")
		(net "M_E_CPU1_SB_DQ<2>")
	)
	(segment
		(start 157.631638 -230.890826)
		(end 157.631384 -230.890572)
		(width 0.18288)
		(layer "In2.Cu")
		(net "M_E_CPU1_SB_DQ<2>")
	)
	(segment
		(start 160.015682 -230.49357)
		(end 159.618426 -230.890826)
		(width 0.18288)
		(layer "In2.Cu")
		(net "M_E_CPU1_SB_DQ<2>")
	)
	(segment
		(start 135.417814 -236.922056)
		(end 135.4074 -236.91596)
		(width 0.088646)
		(layer "In2.Cu")
		(net "M_E_CPU1_SB_DQ<2>")
	)
	(segment
		(start 150.76805 -236.036866)
		(end 149.14626 -236.708442)
		(width 0.18288)
		(layer "In2.Cu")
		(net "M_E_CPU1_SB_DQ<2>")
	)
	(segment
		(start 137.297414 -236.922056)
		(end 137.282682 -236.91342)
		(width 0.088646)
		(layer "In2.Cu")
		(net "M_E_CPU1_SB_DQ<2>")
	)
	(segment
		(start 139.839192 -236.97311)
		(end 139.680696 -236.97311)
		(width 0.18288)
		(layer "In2.Cu")
		(net "M_E_CPU1_SB_DQ<2>")
	)
	(segment
		(start 140.10386 -236.708442)
		(end 139.839192 -236.97311)
		(width 0.18288)
		(layer "In2.Cu")
		(net "M_E_CPU1_SB_DQ<2>")
	)
	(segment
		(start 154.27198 -232.991152)
		(end 154.01925 -233.243882)
		(width 0.18288)
		(layer "In2.Cu")
		(net "M_E_CPU1_SB_DQ<2>")
	)
	(segment
		(start 161.327338 -230.84282)
		(end 160.978088 -230.49357)
		(width 0.18288)
		(layer "In2.Cu")
		(net "M_E_CPU1_SB_DQ<2>")
	)
	(segment
		(start 160.978088 -230.49357)
		(end 160.015682 -230.49357)
		(width 0.18288)
		(layer "In2.Cu")
		(net "M_E_CPU1_SB_DQ<2>")
	)
	(segment
		(start 151.753316 -236.036866)
		(end 150.76805 -236.036866)
		(width 0.18288)
		(layer "In2.Cu")
		(net "M_E_CPU1_SB_DQ<2>")
	)
	(segment
		(start 154.01925 -233.770932)
		(end 151.753316 -236.036866)
		(width 0.18288)
		(layer "In2.Cu")
		(net "M_E_CPU1_SB_DQ<2>")
	)
	(segment
		(start 134.295388 -236.655102)
		(end 134.352538 -236.597952)
		(width 0.088646)
		(layer "In2.Cu")
		(net "M_E_CPU1_SB_DQ<2>")
	)
	(segment
		(start 157.631384 -230.890572)
		(end 157.197298 -230.890572)
		(width 0.18288)
		(layer "In2.Cu")
		(net "M_E_CPU1_SB_DQ<2>")
	)
	(segment
		(start 159.618426 -230.890826)
		(end 157.631638 -230.890826)
		(width 0.18288)
		(layer "In2.Cu")
		(net "M_E_CPU1_SB_DQ<2>")
	)
	(segment
		(start 139.680696 -236.97311)
		(end 138.42492 -236.97311)
		(width 0.088646)
		(layer "In2.Cu")
		(net "M_E_CPU1_SB_DQ<2>")
	)
	(segment
		(start 149.14626 -236.708442)
		(end 140.10386 -236.708442)
		(width 0.18288)
		(layer "In2.Cu")
		(net "M_E_CPU1_SB_DQ<2>")
	)
	(segment
		(start 161.589974 -230.84282)
		(end 161.327338 -230.84282)
		(width 0.18288)
		(layer "In2.Cu")
		(net "M_E_CPU1_SB_DQ<2>")
	)
	(segment
		(start 161.783014 -231.316784)
		(end 161.783014 -231.03586)
		(width 0.18288)
		(layer "In2.Cu")
		(net "M_E_CPU1_SB_DQ<2>")
	)
	(segment
		(start 154.897328 -233.330496)
		(end 154.557984 -232.991152)
		(width 0.18288)
		(layer "In2.Cu")
		(net "M_E_CPU1_SB_DQ<2>")
	)
	(segment
		(start 156.10078 -232.705148)
		(end 155.475432 -233.330496)
		(width 0.18288)
		(layer "In2.Cu")
		(net "M_E_CPU1_SB_DQ<2>")
	)
	(segment
		(start 134.478268 -236.922056)
		(end 134.464044 -236.913928)
		(width 0.088646)
		(layer "In2.Cu")
		(net "M_E_CPU1_SB_DQ<2>")
	)
	(segment
		(start 161.783014 -231.03586)
		(end 161.589974 -230.84282)
		(width 0.18288)
		(layer "In2.Cu")
		(net "M_E_CPU1_SB_DQ<2>")
	)
	(segment
		(start 154.01925 -233.243882)
		(end 154.01925 -233.770932)
		(width 0.18288)
		(layer "In2.Cu")
		(net "M_E_CPU1_SB_DQ<2>")
	)
	(segment
		(start 134.352538 -236.597952)
		(end 134.665466 -236.597952)
		(width 0.088646)
		(layer "In2.Cu")
		(net "M_E_CPU1_SB_DQ<2>")
	)
	(segment
		(start 156.10078 -231.98709)
		(end 156.10078 -232.705148)
		(width 0.18288)
		(layer "In2.Cu")
		(net "M_E_CPU1_SB_DQ<2>")
	)
	(segment
		(start 157.197298 -230.890572)
		(end 156.10078 -231.98709)
		(width 0.18288)
		(layer "In2.Cu")
		(net "M_E_CPU1_SB_DQ<2>")
	)
	(arc
		(start 135.79221 -236.922056)
		(mid 135.605012 -236.972233)
		(end 135.417814 -236.922056)
		(width 0.088646)
		(layer "In2.Cu")
		(net "M_E_CPU1_SB_DQ<2>")
	)
	(arc
		(start 137.282682 -236.91342)
		(mid 137.006207 -236.8461)
		(end 136.73201 -236.922056)
		(width 0.088646)
		(layer "In2.Cu")
		(net "M_E_CPU1_SB_DQ<2>")
	)
	(arc
		(start 135.4074 -236.91596)
		(mid 135.129222 -236.846237)
		(end 134.852664 -236.922056)
		(width 0.088646)
		(layer "In2.Cu")
		(net "M_E_CPU1_SB_DQ<2>")
	)
	(arc
		(start 137.67181 -236.922056)
		(mid 137.484612 -236.972233)
		(end 137.297414 -236.922056)
		(width 0.088646)
		(layer "In2.Cu")
		(net "M_E_CPU1_SB_DQ<2>")
	)
	(arc
		(start 138.42492 -236.97311)
		(mid 138.319406 -236.957818)
		(end 138.222482 -236.91342)
		(width 0.088646)
		(layer "In2.Cu")
		(net "M_E_CPU1_SB_DQ<2>")
	)
	(arc
		(start 136.342882 -236.91342)
		(mid 136.066407 -236.8461)
		(end 135.79221 -236.922056)
		(width 0.088646)
		(layer "In2.Cu")
		(net "M_E_CPU1_SB_DQ<2>")
	)
	(arc
		(start 134.464044 -236.913928)
		(mid 134.351816 -236.8027)
		(end 134.295388 -236.655102)
		(width 0.088646)
		(layer "In2.Cu")
		(net "M_E_CPU1_SB_DQ<2>")
	)
	(arc
		(start 138.222482 -236.91342)
		(mid 137.946007 -236.8461)
		(end 137.67181 -236.922056)
		(width 0.088646)
		(layer "In2.Cu")
		(net "M_E_CPU1_SB_DQ<2>")
	)
	(arc
		(start 134.852664 -236.922056)
		(mid 134.665466 -236.972233)
		(end 134.478268 -236.922056)
		(width 0.088646)
		(layer "In2.Cu")
		(net "M_E_CPU1_SB_DQ<2>")
	)
	(arc
		(start 136.73201 -236.922056)
		(mid 136.544812 -236.972233)
		(end 136.357614 -236.922056)
		(width 0.088646)
		(layer "In2.Cu")
		(net "M_E_CPU1_SB_DQ<2>")
	)
	(segment
		(start 147.522184 -198.025766)
		(end 148.618702 -197.506844)
		(width 0.20066)
		(layer "F.Cu")
		(net "M_E_CPU1_SB_DQ<29>")
	)
	(segment
		(start 140.011912 -214.67318)
		(end 139.71651 -214.377778)
		(width 0.1016)
		(layer "F.Cu")
		(net "M_E_CPU1_SB_DQ<29>")
	)
	(segment
		(start 160.866074 -196.690996)
		(end 160.641792 -196.466714)
		(width 0.20066)
		(layer "F.Cu")
		(net "M_E_CPU1_SB_DQ<29>")
	)
	(segment
		(start 152.113742 -197.224904)
		(end 152.113742 -196.922644)
		(width 0.20066)
		(layer "F.Cu")
		(net "M_E_CPU1_SB_DQ<29>")
	)
	(segment
		(start 153.000202 -197.425564)
		(end 153.284682 -197.425564)
		(width 0.20066)
		(layer "F.Cu")
		(net "M_E_CPU1_SB_DQ<29>")
	)
	(segment
		(start 139.457176 -225.704146)
		(end 139.727686 -225.433636)
		(width 0.088646)
		(layer "F.Cu")
		(net "M_E_CPU1_SB_DQ<29>")
	)
	(segment
		(start 152.799542 -196.922644)
		(end 152.799542 -197.224904)
		(width 0.20066)
		(layer "F.Cu")
		(net "M_E_CPU1_SB_DQ<29>")
	)
	(segment
		(start 153.485342 -197.224904)
		(end 153.485342 -196.94271)
		(width 0.20066)
		(layer "F.Cu")
		(net "M_E_CPU1_SB_DQ<29>")
	)
	(segment
		(start 153.686002 -196.74205)
		(end 153.970482 -196.74205)
		(width 0.20066)
		(layer "F.Cu")
		(net "M_E_CPU1_SB_DQ<29>")
	)
	(segment
		(start 163.907724 -196.041772)
		(end 161.93643 -196.041772)
		(width 0.1016)
		(layer "F.Cu")
		(net "M_E_CPU1_SB_DQ<29>")
	)
	(segment
		(start 157.820868 -196.466714)
		(end 158.813246 -196.466714)
		(width 0.20066)
		(layer "F.Cu")
		(net "M_E_CPU1_SB_DQ<29>")
	)
	(segment
		(start 139.71651 -214.377778)
		(end 139.023852 -213.68512)
		(width 0.20066)
		(layer "F.Cu")
		(net "M_E_CPU1_SB_DQ<29>")
	)
	(segment
		(start 152.799542 -197.224904)
		(end 153.000202 -197.425564)
		(width 0.20066)
		(layer "F.Cu")
		(net "M_E_CPU1_SB_DQ<29>")
	)
	(segment
		(start 163.923726 -196.02577)
		(end 163.907724 -196.041772)
		(width 0.1016)
		(layer "F.Cu")
		(net "M_E_CPU1_SB_DQ<29>")
	)
	(segment
		(start 139.37742 -225.704146)
		(end 139.457176 -225.704146)
		(width 0.088646)
		(layer "F.Cu")
		(net "M_E_CPU1_SB_DQ<29>")
	)
	(segment
		(start 153.485342 -196.94271)
		(end 153.686002 -196.74205)
		(width 0.20066)
		(layer "F.Cu")
		(net "M_E_CPU1_SB_DQ<29>")
	)
	(segment
		(start 139.727686 -225.433636)
		(end 140.011912 -225.14941)
		(width 0.1016)
		(layer "F.Cu")
		(net "M_E_CPU1_SB_DQ<29>")
	)
	(segment
		(start 142.597378 -201.316082)
		(end 147.522184 -198.025766)
		(width 0.20066)
		(layer "F.Cu")
		(net "M_E_CPU1_SB_DQ<29>")
	)
	(segment
		(start 155.11272 -196.69633)
		(end 157.591252 -196.69633)
		(width 0.20066)
		(layer "F.Cu")
		(net "M_E_CPU1_SB_DQ<29>")
	)
	(segment
		(start 164.787326 -196.466714)
		(end 164.346382 -196.02577)
		(width 0.20066)
		(layer "F.Cu")
		(net "M_E_CPU1_SB_DQ<29>")
	)
	(segment
		(start 138.189716 -226.960176)
		(end 138.344656 -226.804982)
		(width 0.088646)
		(layer "F.Cu")
		(net "M_E_CPU1_SB_DQ<29>")
	)
	(segment
		(start 137.014712 -226.553268)
		(end 137.719816 -226.960176)
		(width 0.088646)
		(layer "F.Cu")
		(net "M_E_CPU1_SB_DQ<29>")
	)
	(segment
		(start 153.970482 -196.74205)
		(end 154.171142 -196.94271)
		(width 0.20066)
		(layer "F.Cu")
		(net "M_E_CPU1_SB_DQ<29>")
	)
	(segment
		(start 154.171142 -196.94271)
		(end 154.171142 -197.224904)
		(width 0.20066)
		(layer "F.Cu")
		(net "M_E_CPU1_SB_DQ<29>")
	)
	(segment
		(start 160.641792 -196.466714)
		(end 158.813246 -196.466714)
		(width 0.20066)
		(layer "F.Cu")
		(net "M_E_CPU1_SB_DQ<29>")
	)
	(segment
		(start 154.916632 -197.211188)
		(end 154.916632 -196.892418)
		(width 0.20066)
		(layer "F.Cu")
		(net "M_E_CPU1_SB_DQ<29>")
	)
	(segment
		(start 152.314402 -196.721984)
		(end 152.598882 -196.721984)
		(width 0.20066)
		(layer "F.Cu")
		(net "M_E_CPU1_SB_DQ<29>")
	)
	(segment
		(start 161.925762 -196.031104)
		(end 161.891726 -196.031104)
		(width 0.101854)
		(layer "F.Cu")
		(net "M_E_CPU1_SB_DQ<29>")
	)
	(segment
		(start 154.371802 -197.425564)
		(end 154.702256 -197.425564)
		(width 0.20066)
		(layer "F.Cu")
		(net "M_E_CPU1_SB_DQ<29>")
	)
	(segment
		(start 138.409426 -226.649026)
		(end 138.409426 -226.639628)
		(width 0.088646)
		(layer "F.Cu")
		(net "M_E_CPU1_SB_DQ<29>")
	)
	(segment
		(start 161.93643 -196.041772)
		(end 161.925762 -196.031104)
		(width 0.101854)
		(layer "F.Cu")
		(net "M_E_CPU1_SB_DQ<29>")
	)
	(segment
		(start 139.023852 -213.68512)
		(end 138.287506 -211.90712)
		(width 0.20066)
		(layer "F.Cu")
		(net "M_E_CPU1_SB_DQ<29>")
	)
	(segment
		(start 150.936198 -197.030848)
		(end 151.220678 -197.030848)
		(width 0.20066)
		(layer "F.Cu")
		(net "M_E_CPU1_SB_DQ<29>")
	)
	(segment
		(start 157.591252 -196.69633)
		(end 157.820868 -196.466714)
		(width 0.20066)
		(layer "F.Cu")
		(net "M_E_CPU1_SB_DQ<29>")
	)
	(segment
		(start 152.113742 -196.922644)
		(end 152.314402 -196.721984)
		(width 0.20066)
		(layer "F.Cu")
		(net "M_E_CPU1_SB_DQ<29>")
	)
	(segment
		(start 140.011912 -225.14941)
		(end 140.011912 -214.67318)
		(width 0.1016)
		(layer "F.Cu")
		(net "M_E_CPU1_SB_DQ<29>")
	)
	(segment
		(start 166.357046 -196.466714)
		(end 164.787326 -196.466714)
		(width 0.20066)
		(layer "F.Cu")
		(net "M_E_CPU1_SB_DQ<29>")
	)
	(segment
		(start 138.287506 -208.304638)
		(end 138.480546 -207.334358)
		(width 0.20066)
		(layer "F.Cu")
		(net "M_E_CPU1_SB_DQ<29>")
	)
	(segment
		(start 154.702256 -197.425564)
		(end 154.916632 -197.211188)
		(width 0.20066)
		(layer "F.Cu")
		(net "M_E_CPU1_SB_DQ<29>")
	)
	(segment
		(start 153.284682 -197.425564)
		(end 153.485342 -197.224904)
		(width 0.20066)
		(layer "F.Cu")
		(net "M_E_CPU1_SB_DQ<29>")
	)
	(segment
		(start 148.886418 -197.425564)
		(end 150.541482 -197.425564)
		(width 0.20066)
		(layer "F.Cu")
		(net "M_E_CPU1_SB_DQ<29>")
	)
	(segment
		(start 161.446464 -196.031104)
		(end 161.245804 -196.231764)
		(width 0.20066)
		(layer "F.Cu")
		(net "M_E_CPU1_SB_DQ<29>")
	)
	(segment
		(start 152.598882 -196.721984)
		(end 152.799542 -196.922644)
		(width 0.20066)
		(layer "F.Cu")
		(net "M_E_CPU1_SB_DQ<29>")
	)
	(segment
		(start 138.287506 -211.90712)
		(end 138.287506 -208.304638)
		(width 0.20066)
		(layer "F.Cu")
		(net "M_E_CPU1_SB_DQ<29>")
	)
	(segment
		(start 154.171142 -197.224904)
		(end 154.371802 -197.425564)
		(width 0.20066)
		(layer "F.Cu")
		(net "M_E_CPU1_SB_DQ<29>")
	)
	(segment
		(start 161.891726 -196.031104)
		(end 161.446464 -196.031104)
		(width 0.20066)
		(layer "F.Cu")
		(net "M_E_CPU1_SB_DQ<29>")
	)
	(segment
		(start 138.50366 -226.412044)
		(end 138.62939 -226.286314)
		(width 0.088646)
		(layer "F.Cu")
		(net "M_E_CPU1_SB_DQ<29>")
	)
	(segment
		(start 151.220678 -197.030848)
		(end 151.615394 -197.425564)
		(width 0.20066)
		(layer "F.Cu")
		(net "M_E_CPU1_SB_DQ<29>")
	)
	(segment
		(start 161.245804 -196.231764)
		(end 161.245804 -196.52742)
		(width 0.20066)
		(layer "F.Cu")
		(net "M_E_CPU1_SB_DQ<29>")
	)
	(segment
		(start 150.541482 -197.425564)
		(end 150.936198 -197.030848)
		(width 0.20066)
		(layer "F.Cu")
		(net "M_E_CPU1_SB_DQ<29>")
	)
	(segment
		(start 138.93165 -226.149916)
		(end 139.37742 -225.704146)
		(width 0.088646)
		(layer "F.Cu")
		(net "M_E_CPU1_SB_DQ<29>")
	)
	(segment
		(start 148.618702 -197.506844)
		(end 148.886418 -197.425564)
		(width 0.20066)
		(layer "F.Cu")
		(net "M_E_CPU1_SB_DQ<29>")
	)
	(segment
		(start 151.913082 -197.425564)
		(end 152.113742 -197.224904)
		(width 0.20066)
		(layer "F.Cu")
		(net "M_E_CPU1_SB_DQ<29>")
	)
	(segment
		(start 161.082228 -196.690996)
		(end 160.866074 -196.690996)
		(width 0.20066)
		(layer "F.Cu")
		(net "M_E_CPU1_SB_DQ<29>")
	)
	(segment
		(start 154.916632 -196.892418)
		(end 155.11272 -196.69633)
		(width 0.20066)
		(layer "F.Cu")
		(net "M_E_CPU1_SB_DQ<29>")
	)
	(segment
		(start 164.346382 -196.02577)
		(end 163.923726 -196.02577)
		(width 0.20066)
		(layer "F.Cu")
		(net "M_E_CPU1_SB_DQ<29>")
	)
	(segment
		(start 138.480546 -207.334358)
		(end 139.825222 -204.088238)
		(width 0.20066)
		(layer "F.Cu")
		(net "M_E_CPU1_SB_DQ<29>")
	)
	(segment
		(start 151.615394 -197.425564)
		(end 151.913082 -197.425564)
		(width 0.20066)
		(layer "F.Cu")
		(net "M_E_CPU1_SB_DQ<29>")
	)
	(segment
		(start 161.245804 -196.52742)
		(end 161.082228 -196.690996)
		(width 0.20066)
		(layer "F.Cu")
		(net "M_E_CPU1_SB_DQ<29>")
	)
	(segment
		(start 139.825222 -204.088238)
		(end 142.597378 -201.316082)
		(width 0.20066)
		(layer "F.Cu")
		(net "M_E_CPU1_SB_DQ<29>")
	)
	(arc
		(start 138.851132 -226.188016)
		(mid 138.893451 -226.173324)
		(end 138.93165 -226.149916)
		(width 0.088646)
		(layer "F.Cu")
		(net "M_E_CPU1_SB_DQ<29>")
	)
	(arc
		(start 138.62939 -226.286314)
		(mid 138.68292 -226.244347)
		(end 138.74496 -226.216464)
		(width 0.088646)
		(layer "F.Cu")
		(net "M_E_CPU1_SB_DQ<29>")
	)
	(arc
		(start 137.719816 -226.960176)
		(mid 137.954766 -227.023136)
		(end 138.189716 -226.960176)
		(width 0.088646)
		(layer "F.Cu")
		(net "M_E_CPU1_SB_DQ<29>")
	)
	(arc
		(start 138.344656 -226.804982)
		(mid 138.392549 -226.733444)
		(end 138.409426 -226.649026)
		(width 0.088646)
		(layer "F.Cu")
		(net "M_E_CPU1_SB_DQ<29>")
	)
	(arc
		(start 138.409426 -226.639628)
		(mid 138.433923 -226.516474)
		(end 138.50366 -226.412044)
		(width 0.088646)
		(layer "F.Cu")
		(net "M_E_CPU1_SB_DQ<29>")
	)
	(arc
		(start 138.74496 -226.216464)
		(mid 138.797793 -226.201296)
		(end 138.851132 -226.188016)
		(width 0.088646)
		(layer "F.Cu")
		(net "M_E_CPU1_SB_DQ<29>")
	)
	(segment
		(start 146.975322 -200.801478)
		(end 147.21205 -200.643236)
		(width 0.20066)
		(layer "F.Cu")
		(net "M_E_CPU1_SB_DQ<28>")
	)
	(segment
		(start 147.21205 -200.643236)
		(end 147.267422 -200.365106)
		(width 0.20066)
		(layer "F.Cu")
		(net "M_E_CPU1_SB_DQ<28>")
	)
	(segment
		(start 144.125188 -201.833988)
		(end 144.386554 -201.886312)
		(width 0.20066)
		(layer "F.Cu")
		(net "M_E_CPU1_SB_DQ<28>")
	)
	(segment
		(start 147.143216 -199.818244)
		(end 147.897342 -199.314308)
		(width 0.20066)
		(layer "F.Cu")
		(net "M_E_CPU1_SB_DQ<28>")
	)
	(segment
		(start 144.727168 -201.658728)
		(end 144.778984 -201.397362)
		(width 0.20066)
		(layer "F.Cu")
		(net "M_E_CPU1_SB_DQ<28>")
	)
	(segment
		(start 146.25447 -201.318622)
		(end 145.946876 -200.858374)
		(width 0.20066)
		(layer "F.Cu")
		(net "M_E_CPU1_SB_DQ<28>")
	)
	(segment
		(start 146.002248 -200.580498)
		(end 146.239484 -200.422002)
		(width 0.20066)
		(layer "F.Cu")
		(net "M_E_CPU1_SB_DQ<28>")
	)
	(segment
		(start 160.641792 -198.166736)
		(end 158.813246 -198.166736)
		(width 0.20066)
		(layer "F.Cu")
		(net "M_E_CPU1_SB_DQ<28>")
	)
	(segment
		(start 161.538158 -197.731126)
		(end 161.337498 -197.931786)
		(width 0.20066)
		(layer "F.Cu")
		(net "M_E_CPU1_SB_DQ<28>")
	)
	(segment
		(start 146.696938 -200.746106)
		(end 146.975322 -200.801478)
		(width 0.20066)
		(layer "F.Cu")
		(net "M_E_CPU1_SB_DQ<28>")
	)
	(segment
		(start 160.866074 -198.391018)
		(end 160.641792 -198.166736)
		(width 0.20066)
		(layer "F.Cu")
		(net "M_E_CPU1_SB_DQ<28>")
	)
	(segment
		(start 146.239484 -200.422002)
		(end 146.51736 -200.477374)
		(width 0.20066)
		(layer "F.Cu")
		(net "M_E_CPU1_SB_DQ<28>")
	)
	(segment
		(start 140.8938 -204.851508)
		(end 143.479774 -202.265534)
		(width 0.20066)
		(layer "F.Cu")
		(net "M_E_CPU1_SB_DQ<28>")
	)
	(segment
		(start 163.907724 -197.741794)
		(end 161.93643 -197.741794)
		(width 0.1016)
		(layer "F.Cu")
		(net "M_E_CPU1_SB_DQ<28>")
	)
	(segment
		(start 145.098516 -201.184002)
		(end 145.376392 -201.239374)
		(width 0.20066)
		(layer "F.Cu")
		(net "M_E_CPU1_SB_DQ<28>")
	)
	(segment
		(start 137.571226 -227.776786)
		(end 138.278108 -227.776786)
		(width 0.088646)
		(layer "F.Cu")
		(net "M_E_CPU1_SB_DQ<28>")
	)
	(segment
		(start 161.891726 -197.731126)
		(end 161.538158 -197.731126)
		(width 0.20066)
		(layer "F.Cu")
		(net "M_E_CPU1_SB_DQ<28>")
	)
	(segment
		(start 140.033248 -212.778086)
		(end 139.566904 -211.652358)
		(width 0.20066)
		(layer "F.Cu")
		(net "M_E_CPU1_SB_DQ<28>")
	)
	(segment
		(start 138.655552 -227.663502)
		(end 139.026138 -227.419154)
		(width 0.088646)
		(layer "F.Cu")
		(net "M_E_CPU1_SB_DQ<28>")
	)
	(segment
		(start 140.621512 -226.32162)
		(end 140.621512 -213.78291)
		(width 0.1016)
		(layer "F.Cu")
		(net "M_E_CPU1_SB_DQ<28>")
	)
	(segment
		(start 157.026864 -198.166736)
		(end 158.813246 -198.166736)
		(width 0.20066)
		(layer "F.Cu")
		(net "M_E_CPU1_SB_DQ<28>")
	)
	(segment
		(start 149.131274 -198.730616)
		(end 155.379674 -198.730616)
		(width 0.20066)
		(layer "F.Cu")
		(net "M_E_CPU1_SB_DQ<28>")
	)
	(segment
		(start 139.269978 -227.550726)
		(end 139.392406 -227.550726)
		(width 0.088646)
		(layer "F.Cu")
		(net "M_E_CPU1_SB_DQ<28>")
	)
	(segment
		(start 161.136584 -198.391018)
		(end 160.866074 -198.391018)
		(width 0.20066)
		(layer "F.Cu")
		(net "M_E_CPU1_SB_DQ<28>")
	)
	(segment
		(start 139.566904 -211.652358)
		(end 139.566904 -208.431638)
		(width 0.20066)
		(layer "F.Cu")
		(net "M_E_CPU1_SB_DQ<28>")
	)
	(segment
		(start 139.392406 -227.550726)
		(end 140.313664 -226.629468)
		(width 0.088646)
		(layer "F.Cu")
		(net "M_E_CPU1_SB_DQ<28>")
	)
	(segment
		(start 139.026138 -227.419154)
		(end 139.151106 -227.431854)
		(width 0.088646)
		(layer "F.Cu")
		(net "M_E_CPU1_SB_DQ<28>")
	)
	(segment
		(start 145.946876 -200.858374)
		(end 146.002248 -200.580498)
		(width 0.20066)
		(layer "F.Cu")
		(net "M_E_CPU1_SB_DQ<28>")
	)
	(segment
		(start 139.151106 -227.431854)
		(end 139.269978 -227.550726)
		(width 0.088646)
		(layer "F.Cu")
		(net "M_E_CPU1_SB_DQ<28>")
	)
	(segment
		(start 143.479774 -202.265534)
		(end 144.125188 -201.833988)
		(width 0.20066)
		(layer "F.Cu")
		(net "M_E_CPU1_SB_DQ<28>")
	)
	(segment
		(start 161.337498 -197.931786)
		(end 161.337498 -198.190104)
		(width 0.20066)
		(layer "F.Cu")
		(net "M_E_CPU1_SB_DQ<28>")
	)
	(segment
		(start 145.683986 -201.699622)
		(end 145.962116 -201.754994)
		(width 0.20066)
		(layer "F.Cu")
		(net "M_E_CPU1_SB_DQ<28>")
	)
	(segment
		(start 163.923726 -197.725792)
		(end 163.907724 -197.741794)
		(width 0.1016)
		(layer "F.Cu")
		(net "M_E_CPU1_SB_DQ<28>")
	)
	(segment
		(start 164.346382 -197.725792)
		(end 163.923726 -197.725792)
		(width 0.20066)
		(layer "F.Cu")
		(net "M_E_CPU1_SB_DQ<28>")
	)
	(segment
		(start 144.386554 -201.886312)
		(end 144.727168 -201.658728)
		(width 0.20066)
		(layer "F.Cu")
		(net "M_E_CPU1_SB_DQ<28>")
	)
	(segment
		(start 147.087844 -200.096374)
		(end 147.143216 -199.818244)
		(width 0.20066)
		(layer "F.Cu")
		(net "M_E_CPU1_SB_DQ<28>")
	)
	(segment
		(start 161.337498 -198.190104)
		(end 161.136584 -198.391018)
		(width 0.20066)
		(layer "F.Cu")
		(net "M_E_CPU1_SB_DQ<28>")
	)
	(segment
		(start 155.379674 -198.730616)
		(end 156.134816 -197.975474)
		(width 0.20066)
		(layer "F.Cu")
		(net "M_E_CPU1_SB_DQ<28>")
	)
	(segment
		(start 156.134816 -197.975474)
		(end 156.835602 -197.975474)
		(width 0.20066)
		(layer "F.Cu")
		(net "M_E_CPU1_SB_DQ<28>")
	)
	(segment
		(start 164.787326 -198.166736)
		(end 164.346382 -197.725792)
		(width 0.20066)
		(layer "F.Cu")
		(net "M_E_CPU1_SB_DQ<28>")
	)
	(segment
		(start 156.835602 -197.975474)
		(end 157.026864 -198.166736)
		(width 0.20066)
		(layer "F.Cu")
		(net "M_E_CPU1_SB_DQ<28>")
	)
	(segment
		(start 166.357046 -198.166736)
		(end 164.787326 -198.166736)
		(width 0.20066)
		(layer "F.Cu")
		(net "M_E_CPU1_SB_DQ<28>")
	)
	(segment
		(start 145.376392 -201.239374)
		(end 145.683986 -201.699622)
		(width 0.20066)
		(layer "F.Cu")
		(net "M_E_CPU1_SB_DQ<28>")
	)
	(segment
		(start 140.621512 -213.78291)
		(end 140.32738 -213.072218)
		(width 0.1016)
		(layer "F.Cu")
		(net "M_E_CPU1_SB_DQ<28>")
	)
	(segment
		(start 145.962116 -201.754994)
		(end 146.199098 -201.596752)
		(width 0.20066)
		(layer "F.Cu")
		(net "M_E_CPU1_SB_DQ<28>")
	)
	(segment
		(start 147.267422 -200.365106)
		(end 147.087844 -200.096374)
		(width 0.20066)
		(layer "F.Cu")
		(net "M_E_CPU1_SB_DQ<28>")
	)
	(segment
		(start 147.897342 -199.314308)
		(end 149.131274 -198.730616)
		(width 0.20066)
		(layer "F.Cu")
		(net "M_E_CPU1_SB_DQ<28>")
	)
	(segment
		(start 161.93643 -197.741794)
		(end 161.925762 -197.731126)
		(width 0.101854)
		(layer "F.Cu")
		(net "M_E_CPU1_SB_DQ<28>")
	)
	(segment
		(start 140.103098 -212.847936)
		(end 140.033248 -212.778086)
		(width 0.20066)
		(layer "F.Cu")
		(net "M_E_CPU1_SB_DQ<28>")
	)
	(segment
		(start 146.199098 -201.596752)
		(end 146.25447 -201.318622)
		(width 0.20066)
		(layer "F.Cu")
		(net "M_E_CPU1_SB_DQ<28>")
	)
	(segment
		(start 161.925762 -197.731126)
		(end 161.891726 -197.731126)
		(width 0.101854)
		(layer "F.Cu")
		(net "M_E_CPU1_SB_DQ<28>")
	)
	(segment
		(start 140.313664 -226.629468)
		(end 140.621512 -226.32162)
		(width 0.1016)
		(layer "F.Cu")
		(net "M_E_CPU1_SB_DQ<28>")
	)
	(segment
		(start 139.711176 -207.706468)
		(end 140.8938 -204.851508)
		(width 0.20066)
		(layer "F.Cu")
		(net "M_E_CPU1_SB_DQ<28>")
	)
	(segment
		(start 146.51736 -200.477374)
		(end 146.696938 -200.746106)
		(width 0.20066)
		(layer "F.Cu")
		(net "M_E_CPU1_SB_DQ<28>")
	)
	(segment
		(start 140.32738 -213.072218)
		(end 140.103098 -212.847936)
		(width 0.1016)
		(layer "F.Cu")
		(net "M_E_CPU1_SB_DQ<28>")
	)
	(segment
		(start 136.889998 -227.458778)
		(end 137.335768 -227.714048)
		(width 0.088646)
		(layer "F.Cu")
		(net "M_E_CPU1_SB_DQ<28>")
	)
	(segment
		(start 139.566904 -208.431638)
		(end 139.711176 -207.706468)
		(width 0.20066)
		(layer "F.Cu")
		(net "M_E_CPU1_SB_DQ<28>")
	)
	(segment
		(start 144.778984 -201.397362)
		(end 145.098516 -201.184002)
		(width 0.20066)
		(layer "F.Cu")
		(net "M_E_CPU1_SB_DQ<28>")
	)
	(arc
		(start 137.335768 -227.714048)
		(mid 137.449398 -227.760784)
		(end 137.571226 -227.776786)
		(width 0.088646)
		(layer "F.Cu")
		(net "M_E_CPU1_SB_DQ<28>")
	)
	(arc
		(start 136.545066 -227.367084)
		(mid 136.723514 -227.390412)
		(end 136.889998 -227.458778)
		(width 0.088646)
		(layer "F.Cu")
		(net "M_E_CPU1_SB_DQ<28>")
	)
	(arc
		(start 138.278108 -227.776786)
		(mid 138.475168 -227.747907)
		(end 138.655552 -227.663502)
		(width 0.088646)
		(layer "F.Cu")
		(net "M_E_CPU1_SB_DQ<28>")
	)
	(segment
		(start 155.848558 -201.471784)
		(end 156.133038 -201.471784)
		(width 0.20066)
		(layer "F.Cu")
		(net "M_E_CPU1_SB_DQ<27>")
	)
	(segment
		(start 142.44701 -209.638392)
		(end 142.44701 -208.244186)
		(width 0.20066)
		(layer "F.Cu")
		(net "M_E_CPU1_SB_DQ<27>")
	)
	(segment
		(start 159.807656 -201.991722)
		(end 159.823658 -202.007724)
		(width 0.1016)
		(layer "F.Cu")
		(net "M_E_CPU1_SB_DQ<27>")
	)
	(segment
		(start 138.424666 -228.99497)
		(end 139.07008 -228.99497)
		(width 0.088646)
		(layer "F.Cu")
		(net "M_E_CPU1_SB_DQ<27>")
	)
	(segment
		(start 167.367458 -202.007724)
		(end 167.351456 -201.991722)
		(width 0.1016)
		(layer "F.Cu")
		(net "M_E_CPU1_SB_DQ<27>")
	)
	(segment
		(start 139.07008 -228.99497)
		(end 139.15898 -228.90607)
		(width 0.088646)
		(layer "F.Cu")
		(net "M_E_CPU1_SB_DQ<27>")
	)
	(segment
		(start 159.823658 -202.007724)
		(end 159.942022 -202.007724)
		(width 0.20066)
		(layer "F.Cu")
		(net "M_E_CPU1_SB_DQ<27>")
	)
	(segment
		(start 139.66063 -228.99497)
		(end 139.723368 -228.932232)
		(width 0.088646)
		(layer "F.Cu")
		(net "M_E_CPU1_SB_DQ<27>")
	)
	(segment
		(start 142.44701 -209.837274)
		(end 142.44701 -209.638392)
		(width 0.1016)
		(layer "F.Cu")
		(net "M_E_CPU1_SB_DQ<27>")
	)
	(segment
		(start 168.265348 -201.80681)
		(end 168.064434 -202.007724)
		(width 0.20066)
		(layer "F.Cu")
		(net "M_E_CPU1_SB_DQ<27>")
	)
	(segment
		(start 156.786072 -202.379072)
		(end 157.084268 -202.255374)
		(width 0.20066)
		(layer "F.Cu")
		(net "M_E_CPU1_SB_DQ<27>")
	)
	(segment
		(start 165.380162 -201.991722)
		(end 165.369494 -202.00239)
		(width 0.101854)
		(layer "F.Cu")
		(net "M_E_CPU1_SB_DQ<27>")
	)
	(segment
		(start 168.064434 -202.007724)
		(end 167.367458 -202.007724)
		(width 0.20066)
		(layer "F.Cu")
		(net "M_E_CPU1_SB_DQ<27>")
	)
	(segment
		(start 142.145512 -210.138772)
		(end 142.44701 -209.837274)
		(width 0.1016)
		(layer "F.Cu")
		(net "M_E_CPU1_SB_DQ<27>")
	)
	(segment
		(start 157.836362 -201.991722)
		(end 159.807656 -201.991722)
		(width 0.1016)
		(layer "F.Cu")
		(net "M_E_CPU1_SB_DQ<27>")
	)
	(segment
		(start 164.604954 -201.56678)
		(end 162.913314 -201.56678)
		(width 0.20066)
		(layer "F.Cu")
		(net "M_E_CPU1_SB_DQ<27>")
	)
	(segment
		(start 155.447238 -202.472798)
		(end 155.647898 -202.272138)
		(width 0.20066)
		(layer "F.Cu")
		(net "M_E_CPU1_SB_DQ<27>")
	)
	(segment
		(start 157.337252 -202.00239)
		(end 157.791658 -202.00239)
		(width 0.20066)
		(layer "F.Cu")
		(net "M_E_CPU1_SB_DQ<27>")
	)
	(segment
		(start 155.056586 -202.472798)
		(end 155.447238 -202.472798)
		(width 0.20066)
		(layer "F.Cu")
		(net "M_E_CPU1_SB_DQ<27>")
	)
	(segment
		(start 160.433258 -201.357738)
		(end 160.539684 -201.251312)
		(width 0.20066)
		(layer "F.Cu")
		(net "M_E_CPU1_SB_DQ<27>")
	)
	(segment
		(start 167.351456 -201.991722)
		(end 165.380162 -201.991722)
		(width 0.1016)
		(layer "F.Cu")
		(net "M_E_CPU1_SB_DQ<27>")
	)
	(segment
		(start 160.00984 -202.075542)
		(end 160.294066 -202.075542)
		(width 0.20066)
		(layer "F.Cu")
		(net "M_E_CPU1_SB_DQ<27>")
	)
	(segment
		(start 139.412726 -228.90607)
		(end 139.501626 -228.99497)
		(width 0.088646)
		(layer "F.Cu")
		(net "M_E_CPU1_SB_DQ<27>")
	)
	(segment
		(start 159.942022 -202.007724)
		(end 160.00984 -202.075542)
		(width 0.20066)
		(layer "F.Cu")
		(net "M_E_CPU1_SB_DQ<27>")
	)
	(segment
		(start 139.723368 -228.932232)
		(end 139.723368 -228.839522)
		(width 0.088646)
		(layer "F.Cu")
		(net "M_E_CPU1_SB_DQ<27>")
	)
	(segment
		(start 157.084268 -202.255374)
		(end 157.337252 -202.00239)
		(width 0.20066)
		(layer "F.Cu")
		(net "M_E_CPU1_SB_DQ<27>")
	)
	(segment
		(start 139.15898 -228.90607)
		(end 139.412726 -228.90607)
		(width 0.088646)
		(layer "F.Cu")
		(net "M_E_CPU1_SB_DQ<27>")
	)
	(segment
		(start 165.369494 -202.00239)
		(end 165.335458 -202.00239)
		(width 0.101854)
		(layer "F.Cu")
		(net "M_E_CPU1_SB_DQ<27>")
	)
	(segment
		(start 165.335458 -202.00239)
		(end 165.040564 -202.00239)
		(width 0.20066)
		(layer "F.Cu")
		(net "M_E_CPU1_SB_DQ<27>")
	)
	(segment
		(start 142.145512 -226.98456)
		(end 142.145512 -210.138772)
		(width 0.1016)
		(layer "F.Cu")
		(net "M_E_CPU1_SB_DQ<27>")
	)
	(segment
		(start 170.457114 -201.56678)
		(end 169.135552 -201.56678)
		(width 0.20066)
		(layer "F.Cu")
		(net "M_E_CPU1_SB_DQ<27>")
	)
	(segment
		(start 161.172144 -201.56678)
		(end 162.913314 -201.56678)
		(width 0.20066)
		(layer "F.Cu")
		(net "M_E_CPU1_SB_DQ<27>")
	)
	(segment
		(start 156.133038 -201.471784)
		(end 156.333698 -201.672444)
		(width 0.20066)
		(layer "F.Cu")
		(net "M_E_CPU1_SB_DQ<27>")
	)
	(segment
		(start 147.533614 -204.351128)
		(end 150.146004 -201.738738)
		(width 0.20066)
		(layer "F.Cu")
		(net "M_E_CPU1_SB_DQ<27>")
	)
	(segment
		(start 140.388086 -228.741986)
		(end 140.823188 -228.306884)
		(width 0.088646)
		(layer "F.Cu")
		(net "M_E_CPU1_SB_DQ<27>")
	)
	(segment
		(start 157.791658 -202.00239)
		(end 157.825694 -202.00239)
		(width 0.101854)
		(layer "F.Cu")
		(net "M_E_CPU1_SB_DQ<27>")
	)
	(segment
		(start 160.539684 -201.251312)
		(end 160.856676 -201.251312)
		(width 0.20066)
		(layer "F.Cu")
		(net "M_E_CPU1_SB_DQ<27>")
	)
	(segment
		(start 142.44701 -208.244186)
		(end 143.06169 -206.760064)
		(width 0.20066)
		(layer "F.Cu")
		(net "M_E_CPU1_SB_DQ<27>")
	)
	(segment
		(start 160.856676 -201.251312)
		(end 161.172144 -201.56678)
		(width 0.20066)
		(layer "F.Cu")
		(net "M_E_CPU1_SB_DQ<27>")
	)
	(segment
		(start 156.534358 -202.379072)
		(end 156.786072 -202.379072)
		(width 0.20066)
		(layer "F.Cu")
		(net "M_E_CPU1_SB_DQ<27>")
	)
	(segment
		(start 139.723368 -228.839522)
		(end 139.820904 -228.741986)
		(width 0.088646)
		(layer "F.Cu")
		(net "M_E_CPU1_SB_DQ<27>")
	)
	(segment
		(start 160.294066 -202.075542)
		(end 160.433258 -201.93635)
		(width 0.20066)
		(layer "F.Cu")
		(net "M_E_CPU1_SB_DQ<27>")
	)
	(segment
		(start 139.501626 -228.99497)
		(end 139.66063 -228.99497)
		(width 0.088646)
		(layer "F.Cu")
		(net "M_E_CPU1_SB_DQ<27>")
	)
	(segment
		(start 140.823188 -228.306884)
		(end 142.145512 -226.98456)
		(width 0.1016)
		(layer "F.Cu")
		(net "M_E_CPU1_SB_DQ<27>")
	)
	(segment
		(start 168.265348 -201.549)
		(end 168.265348 -201.80681)
		(width 0.20066)
		(layer "F.Cu")
		(net "M_E_CPU1_SB_DQ<27>")
	)
	(segment
		(start 160.433258 -201.93635)
		(end 160.433258 -201.357738)
		(width 0.20066)
		(layer "F.Cu")
		(net "M_E_CPU1_SB_DQ<27>")
	)
	(segment
		(start 143.06169 -206.760064)
		(end 145.470626 -204.351128)
		(width 0.20066)
		(layer "F.Cu")
		(net "M_E_CPU1_SB_DQ<27>")
	)
	(segment
		(start 168.883584 -201.314812)
		(end 168.499536 -201.314812)
		(width 0.20066)
		(layer "F.Cu")
		(net "M_E_CPU1_SB_DQ<27>")
	)
	(segment
		(start 145.470626 -204.351128)
		(end 147.533614 -204.351128)
		(width 0.20066)
		(layer "F.Cu")
		(net "M_E_CPU1_SB_DQ<27>")
	)
	(segment
		(start 154.148536 -201.564748)
		(end 155.056586 -202.472798)
		(width 0.20066)
		(layer "F.Cu")
		(net "M_E_CPU1_SB_DQ<27>")
	)
	(segment
		(start 155.647898 -201.672444)
		(end 155.848558 -201.471784)
		(width 0.20066)
		(layer "F.Cu")
		(net "M_E_CPU1_SB_DQ<27>")
	)
	(segment
		(start 155.647898 -202.272138)
		(end 155.647898 -201.672444)
		(width 0.20066)
		(layer "F.Cu")
		(net "M_E_CPU1_SB_DQ<27>")
	)
	(segment
		(start 169.135552 -201.56678)
		(end 168.883584 -201.314812)
		(width 0.20066)
		(layer "F.Cu")
		(net "M_E_CPU1_SB_DQ<27>")
	)
	(segment
		(start 139.820904 -228.741986)
		(end 140.388086 -228.741986)
		(width 0.088646)
		(layer "F.Cu")
		(net "M_E_CPU1_SB_DQ<27>")
	)
	(segment
		(start 151.484584 -201.564748)
		(end 154.148536 -201.564748)
		(width 0.20066)
		(layer "F.Cu")
		(net "M_E_CPU1_SB_DQ<27>")
	)
	(segment
		(start 156.333698 -201.672444)
		(end 156.333698 -202.178412)
		(width 0.20066)
		(layer "F.Cu")
		(net "M_E_CPU1_SB_DQ<27>")
	)
	(segment
		(start 168.499536 -201.314812)
		(end 168.265348 -201.549)
		(width 0.20066)
		(layer "F.Cu")
		(net "M_E_CPU1_SB_DQ<27>")
	)
	(segment
		(start 151.310594 -201.738738)
		(end 151.484584 -201.564748)
		(width 0.20066)
		(layer "F.Cu")
		(net "M_E_CPU1_SB_DQ<27>")
	)
	(segment
		(start 150.146004 -201.738738)
		(end 151.310594 -201.738738)
		(width 0.20066)
		(layer "F.Cu")
		(net "M_E_CPU1_SB_DQ<27>")
	)
	(segment
		(start 157.825694 -202.00239)
		(end 157.836362 -201.991722)
		(width 0.101854)
		(layer "F.Cu")
		(net "M_E_CPU1_SB_DQ<27>")
	)
	(segment
		(start 156.333698 -202.178412)
		(end 156.534358 -202.379072)
		(width 0.20066)
		(layer "F.Cu")
		(net "M_E_CPU1_SB_DQ<27>")
	)
	(segment
		(start 165.040564 -202.00239)
		(end 164.604954 -201.56678)
		(width 0.20066)
		(layer "F.Cu")
		(net "M_E_CPU1_SB_DQ<27>")
	)
	(segment
		(start 165.380162 -203.691744)
		(end 165.369494 -203.702412)
		(width 0.101854)
		(layer "F.Cu")
		(net "M_E_CPU1_SB_DQ<26>")
	)
	(segment
		(start 160.503108 -203.374752)
		(end 160.611058 -203.266802)
		(width 0.20066)
		(layer "F.Cu")
		(net "M_E_CPU1_SB_DQ<26>")
	)
	(segment
		(start 152.755092 -203.75245)
		(end 153.039572 -203.75245)
		(width 0.20066)
		(layer "F.Cu")
		(net "M_E_CPU1_SB_DQ<26>")
	)
	(segment
		(start 151.073612 -204.163676)
		(end 151.073612 -203.819506)
		(width 0.20066)
		(layer "F.Cu")
		(net "M_E_CPU1_SB_DQ<26>")
	)
	(segment
		(start 168.883584 -203.014834)
		(end 168.499536 -203.014834)
		(width 0.20066)
		(layer "F.Cu")
		(net "M_E_CPU1_SB_DQ<26>")
	)
	(segment
		(start 148.374862 -206.518256)
		(end 150.342854 -204.550264)
		(width 0.20066)
		(layer "F.Cu")
		(net "M_E_CPU1_SB_DQ<26>")
	)
	(segment
		(start 150.342854 -204.550264)
		(end 150.687024 -204.550264)
		(width 0.20066)
		(layer "F.Cu")
		(net "M_E_CPU1_SB_DQ<26>")
	)
	(segment
		(start 138.818874 -229.417372)
		(end 140.575284 -229.417372)
		(width 0.088646)
		(layer "F.Cu")
		(net "M_E_CPU1_SB_DQ<26>")
	)
	(segment
		(start 153.240232 -203.55179)
		(end 153.240232 -203.151486)
		(width 0.20066)
		(layer "F.Cu")
		(net "M_E_CPU1_SB_DQ<26>")
	)
	(segment
		(start 157.524704 -203.702412)
		(end 157.791658 -203.702412)
		(width 0.20066)
		(layer "F.Cu")
		(net "M_E_CPU1_SB_DQ<26>")
	)
	(segment
		(start 141.270482 -228.722174)
		(end 142.755112 -227.237544)
		(width 0.1016)
		(layer "F.Cu")
		(net "M_E_CPU1_SB_DQ<26>")
	)
	(segment
		(start 150.687024 -204.550264)
		(end 151.073612 -204.163676)
		(width 0.20066)
		(layer "F.Cu")
		(net "M_E_CPU1_SB_DQ<26>")
	)
	(segment
		(start 152.554432 -203.31938)
		(end 152.554432 -203.55179)
		(width 0.20066)
		(layer "F.Cu")
		(net "M_E_CPU1_SB_DQ<26>")
	)
	(segment
		(start 165.335458 -203.702412)
		(end 165.040564 -203.702412)
		(width 0.20066)
		(layer "F.Cu")
		(net "M_E_CPU1_SB_DQ<26>")
	)
	(segment
		(start 143.786606 -208.440782)
		(end 144.144492 -207.576928)
		(width 0.20066)
		(layer "F.Cu")
		(net "M_E_CPU1_SB_DQ<26>")
	)
	(segment
		(start 142.755112 -227.237544)
		(end 142.755112 -211.440268)
		(width 0.1016)
		(layer "F.Cu")
		(net "M_E_CPU1_SB_DQ<26>")
	)
	(segment
		(start 159.807656 -203.691744)
		(end 159.823658 -203.707746)
		(width 0.1016)
		(layer "F.Cu")
		(net "M_E_CPU1_SB_DQ<26>")
	)
	(segment
		(start 167.367458 -203.707746)
		(end 167.351456 -203.691744)
		(width 0.1016)
		(layer "F.Cu")
		(net "M_E_CPU1_SB_DQ<26>")
	)
	(segment
		(start 143.52524 -210.208114)
		(end 143.97482 -209.758534)
		(width 0.20066)
		(layer "F.Cu")
		(net "M_E_CPU1_SB_DQ<26>")
	)
	(segment
		(start 168.265348 -203.249022)
		(end 168.265348 -203.506832)
		(width 0.20066)
		(layer "F.Cu")
		(net "M_E_CPU1_SB_DQ<26>")
	)
	(segment
		(start 152.554432 -203.55179)
		(end 152.755092 -203.75245)
		(width 0.20066)
		(layer "F.Cu")
		(net "M_E_CPU1_SB_DQ<26>")
	)
	(segment
		(start 153.926032 -203.551282)
		(end 154.126692 -203.751942)
		(width 0.20066)
		(layer "F.Cu")
		(net "M_E_CPU1_SB_DQ<26>")
	)
	(segment
		(start 161.532316 -202.85202)
		(end 161.964116 -202.85202)
		(width 0.20066)
		(layer "F.Cu")
		(net "M_E_CPU1_SB_DQ<26>")
	)
	(segment
		(start 140.575284 -229.417372)
		(end 141.270482 -228.722174)
		(width 0.088646)
		(layer "F.Cu")
		(net "M_E_CPU1_SB_DQ<26>")
	)
	(segment
		(start 161.964116 -202.85202)
		(end 162.378898 -203.266802)
		(width 0.20066)
		(layer "F.Cu")
		(net "M_E_CPU1_SB_DQ<26>")
	)
	(segment
		(start 157.791658 -203.702412)
		(end 157.825694 -203.702412)
		(width 0.101854)
		(layer "F.Cu")
		(net "M_E_CPU1_SB_DQ<26>")
	)
	(segment
		(start 168.499536 -203.014834)
		(end 168.265348 -203.249022)
		(width 0.20066)
		(layer "F.Cu")
		(net "M_E_CPU1_SB_DQ<26>")
	)
	(segment
		(start 153.039572 -203.75245)
		(end 153.240232 -203.55179)
		(width 0.20066)
		(layer "F.Cu")
		(net "M_E_CPU1_SB_DQ<26>")
	)
	(segment
		(start 151.073612 -203.819506)
		(end 151.774906 -203.118212)
		(width 0.20066)
		(layer "F.Cu")
		(net "M_E_CPU1_SB_DQ<26>")
	)
	(segment
		(start 154.126692 -203.751942)
		(end 157.475174 -203.751942)
		(width 0.20066)
		(layer "F.Cu")
		(net "M_E_CPU1_SB_DQ<26>")
	)
	(segment
		(start 138.71067 -229.482904)
		(end 138.818874 -229.417372)
		(width 0.088646)
		(layer "F.Cu")
		(net "M_E_CPU1_SB_DQ<26>")
	)
	(segment
		(start 168.265348 -203.506832)
		(end 168.064434 -203.707746)
		(width 0.20066)
		(layer "F.Cu")
		(net "M_E_CPU1_SB_DQ<26>")
	)
	(segment
		(start 144.144492 -207.576928)
		(end 146.069812 -205.651608)
		(width 0.20066)
		(layer "F.Cu")
		(net "M_E_CPU1_SB_DQ<26>")
	)
	(segment
		(start 170.457114 -203.266802)
		(end 169.135552 -203.266802)
		(width 0.20066)
		(layer "F.Cu")
		(net "M_E_CPU1_SB_DQ<26>")
	)
	(segment
		(start 161.278316 -203.266802)
		(end 161.405316 -203.139802)
		(width 0.20066)
		(layer "F.Cu")
		(net "M_E_CPU1_SB_DQ<26>")
	)
	(segment
		(start 153.440892 -202.950826)
		(end 153.725372 -202.950826)
		(width 0.20066)
		(layer "F.Cu")
		(net "M_E_CPU1_SB_DQ<26>")
	)
	(segment
		(start 143.081502 -210.651852)
		(end 143.52524 -210.208114)
		(width 0.1016)
		(layer "F.Cu")
		(net "M_E_CPU1_SB_DQ<26>")
	)
	(segment
		(start 165.369494 -203.702412)
		(end 165.335458 -203.702412)
		(width 0.101854)
		(layer "F.Cu")
		(net "M_E_CPU1_SB_DQ<26>")
	)
	(segment
		(start 153.926032 -203.151486)
		(end 153.926032 -203.551282)
		(width 0.20066)
		(layer "F.Cu")
		(net "M_E_CPU1_SB_DQ<26>")
	)
	(segment
		(start 169.135552 -203.266802)
		(end 168.883584 -203.014834)
		(width 0.20066)
		(layer "F.Cu")
		(net "M_E_CPU1_SB_DQ<26>")
	)
	(segment
		(start 162.378898 -203.266802)
		(end 162.913314 -203.266802)
		(width 0.20066)
		(layer "F.Cu")
		(net "M_E_CPU1_SB_DQ<26>")
	)
	(segment
		(start 146.928332 -205.651608)
		(end 147.79498 -206.518256)
		(width 0.20066)
		(layer "F.Cu")
		(net "M_E_CPU1_SB_DQ<26>")
	)
	(segment
		(start 161.405316 -203.139802)
		(end 161.405316 -202.97902)
		(width 0.20066)
		(layer "F.Cu")
		(net "M_E_CPU1_SB_DQ<26>")
	)
	(segment
		(start 143.97482 -209.758534)
		(end 143.97482 -209.474562)
		(width 0.20066)
		(layer "F.Cu")
		(net "M_E_CPU1_SB_DQ<26>")
	)
	(segment
		(start 164.604954 -203.266802)
		(end 162.913314 -203.266802)
		(width 0.20066)
		(layer "F.Cu")
		(net "M_E_CPU1_SB_DQ<26>")
	)
	(segment
		(start 160.503108 -203.734924)
		(end 160.503108 -203.374752)
		(width 0.20066)
		(layer "F.Cu")
		(net "M_E_CPU1_SB_DQ<26>")
	)
	(segment
		(start 142.755112 -211.440268)
		(end 143.081502 -210.651852)
		(width 0.1016)
		(layer "F.Cu")
		(net "M_E_CPU1_SB_DQ<26>")
	)
	(segment
		(start 167.351456 -203.691744)
		(end 165.380162 -203.691744)
		(width 0.1016)
		(layer "F.Cu")
		(net "M_E_CPU1_SB_DQ<26>")
	)
	(segment
		(start 160.090866 -203.85659)
		(end 160.381442 -203.85659)
		(width 0.20066)
		(layer "F.Cu")
		(net "M_E_CPU1_SB_DQ<26>")
	)
	(segment
		(start 138.2522 -229.73284)
		(end 138.71067 -229.482904)
		(width 0.088646)
		(layer "F.Cu")
		(net "M_E_CPU1_SB_DQ<26>")
	)
	(segment
		(start 157.825694 -203.702412)
		(end 157.836362 -203.691744)
		(width 0.101854)
		(layer "F.Cu")
		(net "M_E_CPU1_SB_DQ<26>")
	)
	(segment
		(start 147.79498 -206.518256)
		(end 148.374862 -206.518256)
		(width 0.20066)
		(layer "F.Cu")
		(net "M_E_CPU1_SB_DQ<26>")
	)
	(segment
		(start 143.97482 -209.474562)
		(end 143.786606 -209.286348)
		(width 0.20066)
		(layer "F.Cu")
		(net "M_E_CPU1_SB_DQ<26>")
	)
	(segment
		(start 152.353264 -203.118212)
		(end 152.554432 -203.31938)
		(width 0.20066)
		(layer "F.Cu")
		(net "M_E_CPU1_SB_DQ<26>")
	)
	(segment
		(start 168.064434 -203.707746)
		(end 167.367458 -203.707746)
		(width 0.20066)
		(layer "F.Cu")
		(net "M_E_CPU1_SB_DQ<26>")
	)
	(segment
		(start 159.823658 -203.707746)
		(end 159.942022 -203.707746)
		(width 0.20066)
		(layer "F.Cu")
		(net "M_E_CPU1_SB_DQ<26>")
	)
	(segment
		(start 161.405316 -202.97902)
		(end 161.532316 -202.85202)
		(width 0.20066)
		(layer "F.Cu")
		(net "M_E_CPU1_SB_DQ<26>")
	)
	(segment
		(start 165.040564 -203.702412)
		(end 164.604954 -203.266802)
		(width 0.20066)
		(layer "F.Cu")
		(net "M_E_CPU1_SB_DQ<26>")
	)
	(segment
		(start 153.240232 -203.151486)
		(end 153.440892 -202.950826)
		(width 0.20066)
		(layer "F.Cu")
		(net "M_E_CPU1_SB_DQ<26>")
	)
	(segment
		(start 159.942022 -203.707746)
		(end 160.090866 -203.85659)
		(width 0.20066)
		(layer "F.Cu")
		(net "M_E_CPU1_SB_DQ<26>")
	)
	(segment
		(start 160.381442 -203.85659)
		(end 160.503108 -203.734924)
		(width 0.20066)
		(layer "F.Cu")
		(net "M_E_CPU1_SB_DQ<26>")
	)
	(segment
		(start 153.725372 -202.950826)
		(end 153.926032 -203.151486)
		(width 0.20066)
		(layer "F.Cu")
		(net "M_E_CPU1_SB_DQ<26>")
	)
	(segment
		(start 151.774906 -203.118212)
		(end 152.353264 -203.118212)
		(width 0.20066)
		(layer "F.Cu")
		(net "M_E_CPU1_SB_DQ<26>")
	)
	(segment
		(start 146.069812 -205.651608)
		(end 146.928332 -205.651608)
		(width 0.20066)
		(layer "F.Cu")
		(net "M_E_CPU1_SB_DQ<26>")
	)
	(segment
		(start 157.475174 -203.751942)
		(end 157.524704 -203.702412)
		(width 0.20066)
		(layer "F.Cu")
		(net "M_E_CPU1_SB_DQ<26>")
	)
	(segment
		(start 143.786606 -209.286348)
		(end 143.786606 -208.440782)
		(width 0.20066)
		(layer "F.Cu")
		(net "M_E_CPU1_SB_DQ<26>")
	)
	(segment
		(start 157.836362 -203.691744)
		(end 159.807656 -203.691744)
		(width 0.1016)
		(layer "F.Cu")
		(net "M_E_CPU1_SB_DQ<26>")
	)
	(segment
		(start 160.611058 -203.266802)
		(end 161.278316 -203.266802)
		(width 0.20066)
		(layer "F.Cu")
		(net "M_E_CPU1_SB_DQ<26>")
	)
	(arc
		(start 137.954766 -229.808786)
		(mid 138.108245 -229.789466)
		(end 138.2522 -229.73284)
		(width 0.088646)
		(layer "F.Cu")
		(net "M_E_CPU1_SB_DQ<26>")
	)
	(segment
		(start 148.477224 -204.346302)
		(end 148.761196 -204.346302)
		(width 0.20066)
		(layer "F.Cu")
		(net "M_E_CPU1_SB_DQ<25>")
	)
	(segment
		(start 143.599154 -207.177894)
		(end 145.786348 -204.9907)
		(width 0.20066)
		(layer "F.Cu")
		(net "M_E_CPU1_SB_DQ<25>")
	)
	(segment
		(start 163.907724 -201.991722)
		(end 161.93643 -201.991722)
		(width 0.1016)
		(layer "F.Cu")
		(net "M_E_CPU1_SB_DQ<25>")
	)
	(segment
		(start 150.20798 -202.882246)
		(end 150.20798 -202.598274)
		(width 0.20066)
		(layer "F.Cu")
		(net "M_E_CPU1_SB_DQ<25>")
	)
	(segment
		(start 137.157968 -229.388162)
		(end 137.271506 -229.454964)
		(width 0.088646)
		(layer "F.Cu")
		(net "M_E_CPU1_SB_DQ<25>")
	)
	(segment
		(start 161.00298 -202.480672)
		(end 160.842706 -202.640946)
		(width 0.20066)
		(layer "F.Cu")
		(net "M_E_CPU1_SB_DQ<25>")
	)
	(segment
		(start 136.545066 -229.308914)
		(end 136.416034 -229.437946)
		(width 0.088646)
		(layer "F.Cu")
		(net "M_E_CPU1_SB_DQ<25>")
	)
	(segment
		(start 145.786348 -204.9907)
		(end 147.172172 -204.9907)
		(width 0.20066)
		(layer "F.Cu")
		(net "M_E_CPU1_SB_DQ<25>")
	)
	(segment
		(start 152.371552 -202.440032)
		(end 153.055828 -202.440032)
		(width 0.20066)
		(layer "F.Cu")
		(net "M_E_CPU1_SB_DQ<25>")
	)
	(segment
		(start 136.61771 -229.67569)
		(end 136.905238 -229.388162)
		(width 0.088646)
		(layer "F.Cu")
		(net "M_E_CPU1_SB_DQ<25>")
	)
	(segment
		(start 161.925762 -201.981054)
		(end 161.891726 -201.981054)
		(width 0.101854)
		(layer "F.Cu")
		(net "M_E_CPU1_SB_DQ<25>")
	)
	(segment
		(start 148.557234 -205.396592)
		(end 148.557234 -205.11262)
		(width 0.20066)
		(layer "F.Cu")
		(net "M_E_CPU1_SB_DQ<25>")
	)
	(segment
		(start 143.138398 -209.789268)
		(end 143.138398 -209.638392)
		(width 0.1016)
		(layer "F.Cu")
		(net "M_E_CPU1_SB_DQ<25>")
	)
	(segment
		(start 137.835894 -229.397306)
		(end 138.308842 -229.397306)
		(width 0.088646)
		(layer "F.Cu")
		(net "M_E_CPU1_SB_DQ<25>")
	)
	(segment
		(start 163.923726 -201.97572)
		(end 163.907724 -201.991722)
		(width 0.1016)
		(layer "F.Cu")
		(net "M_E_CPU1_SB_DQ<25>")
	)
	(segment
		(start 149.461982 -203.3905)
		(end 149.745954 -203.3905)
		(width 0.20066)
		(layer "F.Cu")
		(net "M_E_CPU1_SB_DQ<25>")
	)
	(segment
		(start 148.276056 -204.54747)
		(end 148.477224 -204.346302)
		(width 0.20066)
		(layer "F.Cu")
		(net "M_E_CPU1_SB_DQ<25>")
	)
	(segment
		(start 136.905238 -229.388162)
		(end 137.157968 -229.388162)
		(width 0.088646)
		(layer "F.Cu")
		(net "M_E_CPU1_SB_DQ<25>")
	)
	(segment
		(start 166.357046 -202.416664)
		(end 164.690806 -202.416664)
		(width 0.20066)
		(layer "F.Cu")
		(net "M_E_CPU1_SB_DQ<25>")
	)
	(segment
		(start 140.61948 -228.941884)
		(end 142.450312 -227.111052)
		(width 0.1016)
		(layer "F.Cu")
		(net "M_E_CPU1_SB_DQ<25>")
	)
	(segment
		(start 157.611318 -202.741022)
		(end 157.935676 -202.416664)
		(width 0.20066)
		(layer "F.Cu")
		(net "M_E_CPU1_SB_DQ<25>")
	)
	(segment
		(start 156.714698 -203.11237)
		(end 157.575504 -202.755754)
		(width 0.20066)
		(layer "F.Cu")
		(net "M_E_CPU1_SB_DQ<25>")
	)
	(segment
		(start 151.266906 -202.68692)
		(end 151.72817 -202.225656)
		(width 0.20066)
		(layer "F.Cu")
		(net "M_E_CPU1_SB_DQ<25>")
	)
	(segment
		(start 153.270204 -202.225656)
		(end 153.904696 -202.225656)
		(width 0.20066)
		(layer "F.Cu")
		(net "M_E_CPU1_SB_DQ<25>")
	)
	(segment
		(start 149.527514 -204.426312)
		(end 149.527514 -204.14234)
		(width 0.20066)
		(layer "F.Cu")
		(net "M_E_CPU1_SB_DQ<25>")
	)
	(segment
		(start 149.260814 -203.87564)
		(end 149.260814 -203.591668)
		(width 0.20066)
		(layer "F.Cu")
		(net "M_E_CPU1_SB_DQ<25>")
	)
	(segment
		(start 161.93643 -201.991722)
		(end 161.925762 -201.981054)
		(width 0.101854)
		(layer "F.Cu")
		(net "M_E_CPU1_SB_DQ<25>")
	)
	(segment
		(start 157.575504 -202.755754)
		(end 157.611318 -202.741022)
		(width 0.20066)
		(layer "F.Cu")
		(net "M_E_CPU1_SB_DQ<25>")
	)
	(segment
		(start 149.326346 -204.62748)
		(end 149.527514 -204.426312)
		(width 0.20066)
		(layer "F.Cu")
		(net "M_E_CPU1_SB_DQ<25>")
	)
	(segment
		(start 161.00298 -202.13193)
		(end 161.00298 -202.480672)
		(width 0.20066)
		(layer "F.Cu")
		(net "M_E_CPU1_SB_DQ<25>")
	)
	(segment
		(start 149.260814 -203.591668)
		(end 149.461982 -203.3905)
		(width 0.20066)
		(layer "F.Cu")
		(net "M_E_CPU1_SB_DQ<25>")
	)
	(segment
		(start 139.996672 -229.102666)
		(end 140.458698 -229.102666)
		(width 0.088646)
		(layer "F.Cu")
		(net "M_E_CPU1_SB_DQ<25>")
	)
	(segment
		(start 150.69312 -202.397106)
		(end 150.982934 -202.68692)
		(width 0.20066)
		(layer "F.Cu")
		(net "M_E_CPU1_SB_DQ<25>")
	)
	(segment
		(start 149.527514 -204.14234)
		(end 149.260814 -203.87564)
		(width 0.20066)
		(layer "F.Cu")
		(net "M_E_CPU1_SB_DQ<25>")
	)
	(segment
		(start 161.153856 -201.981054)
		(end 161.00298 -202.13193)
		(width 0.20066)
		(layer "F.Cu")
		(net "M_E_CPU1_SB_DQ<25>")
	)
	(segment
		(start 147.172172 -204.9907)
		(end 147.925536 -205.744064)
		(width 0.20066)
		(layer "F.Cu")
		(net "M_E_CPU1_SB_DQ<25>")
	)
	(segment
		(start 138.823192 -229.191566)
		(end 139.781788 -229.191566)
		(width 0.088646)
		(layer "F.Cu")
		(net "M_E_CPU1_SB_DQ<25>")
	)
	(segment
		(start 142.450312 -227.111052)
		(end 142.450312 -210.477354)
		(width 0.1016)
		(layer "F.Cu")
		(net "M_E_CPU1_SB_DQ<25>")
	)
	(segment
		(start 139.781788 -229.191566)
		(end 139.996672 -229.102666)
		(width 0.088646)
		(layer "F.Cu")
		(net "M_E_CPU1_SB_DQ<25>")
	)
	(segment
		(start 138.634724 -229.30612)
		(end 138.823192 -229.191566)
		(width 0.088646)
		(layer "F.Cu")
		(net "M_E_CPU1_SB_DQ<25>")
	)
	(segment
		(start 149.745954 -203.3905)
		(end 150.012654 -203.6572)
		(width 0.20066)
		(layer "F.Cu")
		(net "M_E_CPU1_SB_DQ<25>")
	)
	(segment
		(start 143.138398 -208.29016)
		(end 143.599154 -207.177894)
		(width 0.20066)
		(layer "F.Cu")
		(net "M_E_CPU1_SB_DQ<25>")
	)
	(segment
		(start 148.276056 -204.831442)
		(end 148.276056 -204.54747)
		(width 0.20066)
		(layer "F.Cu")
		(net "M_E_CPU1_SB_DQ<25>")
	)
	(segment
		(start 154.79141 -203.11237)
		(end 156.714698 -203.11237)
		(width 0.20066)
		(layer "F.Cu")
		(net "M_E_CPU1_SB_DQ<25>")
	)
	(segment
		(start 161.891726 -201.981054)
		(end 161.153856 -201.981054)
		(width 0.20066)
		(layer "F.Cu")
		(net "M_E_CPU1_SB_DQ<25>")
	)
	(segment
		(start 164.249862 -201.97572)
		(end 163.923726 -201.97572)
		(width 0.20066)
		(layer "F.Cu")
		(net "M_E_CPU1_SB_DQ<25>")
	)
	(segment
		(start 136.416034 -229.437946)
		(end 136.416034 -229.584758)
		(width 0.088646)
		(layer "F.Cu")
		(net "M_E_CPU1_SB_DQ<25>")
	)
	(segment
		(start 164.690806 -202.416664)
		(end 164.249862 -201.97572)
		(width 0.20066)
		(layer "F.Cu")
		(net "M_E_CPU1_SB_DQ<25>")
	)
	(segment
		(start 153.055828 -202.440032)
		(end 153.270204 -202.225656)
		(width 0.20066)
		(layer "F.Cu")
		(net "M_E_CPU1_SB_DQ<25>")
	)
	(segment
		(start 159.951674 -202.640946)
		(end 159.727392 -202.416664)
		(width 0.20066)
		(layer "F.Cu")
		(net "M_E_CPU1_SB_DQ<25>")
	)
	(segment
		(start 150.497794 -203.456032)
		(end 150.497794 -203.17206)
		(width 0.20066)
		(layer "F.Cu")
		(net "M_E_CPU1_SB_DQ<25>")
	)
	(segment
		(start 159.727392 -202.416664)
		(end 158.813246 -202.416664)
		(width 0.20066)
		(layer "F.Cu")
		(net "M_E_CPU1_SB_DQ<25>")
	)
	(segment
		(start 149.042374 -204.62748)
		(end 149.326346 -204.62748)
		(width 0.20066)
		(layer "F.Cu")
		(net "M_E_CPU1_SB_DQ<25>")
	)
	(segment
		(start 157.935676 -202.416664)
		(end 158.813246 -202.416664)
		(width 0.20066)
		(layer "F.Cu")
		(net "M_E_CPU1_SB_DQ<25>")
	)
	(segment
		(start 150.296626 -203.6572)
		(end 150.497794 -203.456032)
		(width 0.20066)
		(layer "F.Cu")
		(net "M_E_CPU1_SB_DQ<25>")
	)
	(segment
		(start 150.497794 -203.17206)
		(end 150.20798 -202.882246)
		(width 0.20066)
		(layer "F.Cu")
		(net "M_E_CPU1_SB_DQ<25>")
	)
	(segment
		(start 136.506966 -229.67569)
		(end 136.61771 -229.67569)
		(width 0.088646)
		(layer "F.Cu")
		(net "M_E_CPU1_SB_DQ<25>")
	)
	(segment
		(start 140.458698 -229.102666)
		(end 140.61948 -228.941884)
		(width 0.088646)
		(layer "F.Cu")
		(net "M_E_CPU1_SB_DQ<25>")
	)
	(segment
		(start 153.904696 -202.225656)
		(end 154.79141 -203.11237)
		(width 0.20066)
		(layer "F.Cu")
		(net "M_E_CPU1_SB_DQ<25>")
	)
	(segment
		(start 150.20798 -202.598274)
		(end 150.409148 -202.397106)
		(width 0.20066)
		(layer "F.Cu")
		(net "M_E_CPU1_SB_DQ<25>")
	)
	(segment
		(start 148.557234 -205.11262)
		(end 148.276056 -204.831442)
		(width 0.20066)
		(layer "F.Cu")
		(net "M_E_CPU1_SB_DQ<25>")
	)
	(segment
		(start 147.925536 -205.744064)
		(end 148.209762 -205.744064)
		(width 0.20066)
		(layer "F.Cu")
		(net "M_E_CPU1_SB_DQ<25>")
	)
	(segment
		(start 150.982934 -202.68692)
		(end 151.266906 -202.68692)
		(width 0.20066)
		(layer "F.Cu")
		(net "M_E_CPU1_SB_DQ<25>")
	)
	(segment
		(start 148.209762 -205.744064)
		(end 148.557234 -205.396592)
		(width 0.20066)
		(layer "F.Cu")
		(net "M_E_CPU1_SB_DQ<25>")
	)
	(segment
		(start 150.012654 -203.6572)
		(end 150.296626 -203.6572)
		(width 0.20066)
		(layer "F.Cu")
		(net "M_E_CPU1_SB_DQ<25>")
	)
	(segment
		(start 136.416034 -229.584758)
		(end 136.506966 -229.67569)
		(width 0.088646)
		(layer "F.Cu")
		(net "M_E_CPU1_SB_DQ<25>")
	)
	(segment
		(start 152.157176 -202.225656)
		(end 152.371552 -202.440032)
		(width 0.20066)
		(layer "F.Cu")
		(net "M_E_CPU1_SB_DQ<25>")
	)
	(segment
		(start 148.761196 -204.346302)
		(end 149.042374 -204.62748)
		(width 0.20066)
		(layer "F.Cu")
		(net "M_E_CPU1_SB_DQ<25>")
	)
	(segment
		(start 150.409148 -202.397106)
		(end 150.69312 -202.397106)
		(width 0.20066)
		(layer "F.Cu")
		(net "M_E_CPU1_SB_DQ<25>")
	)
	(segment
		(start 151.72817 -202.225656)
		(end 152.157176 -202.225656)
		(width 0.20066)
		(layer "F.Cu")
		(net "M_E_CPU1_SB_DQ<25>")
	)
	(segment
		(start 137.73277 -229.456996)
		(end 137.835894 -229.397306)
		(width 0.088646)
		(layer "F.Cu")
		(net "M_E_CPU1_SB_DQ<25>")
	)
	(segment
		(start 136.545066 -228.99497)
		(end 136.545066 -229.308914)
		(width 0.088646)
		(layer "F.Cu")
		(net "M_E_CPU1_SB_DQ<25>")
	)
	(segment
		(start 142.450312 -210.477354)
		(end 143.138398 -209.789268)
		(width 0.1016)
		(layer "F.Cu")
		(net "M_E_CPU1_SB_DQ<25>")
	)
	(segment
		(start 143.138398 -209.638392)
		(end 143.138398 -208.29016)
		(width 0.20066)
		(layer "F.Cu")
		(net "M_E_CPU1_SB_DQ<25>")
	)
	(segment
		(start 160.842706 -202.640946)
		(end 159.951674 -202.640946)
		(width 0.20066)
		(layer "F.Cu")
		(net "M_E_CPU1_SB_DQ<25>")
	)
	(arc
		(start 138.308842 -229.397306)
		(mid 138.478036 -229.374071)
		(end 138.634724 -229.30612)
		(width 0.088646)
		(layer "F.Cu")
		(net "M_E_CPU1_SB_DQ<25>")
	)
	(arc
		(start 137.271506 -229.454964)
		(mid 137.501868 -229.51837)
		(end 137.73277 -229.456996)
		(width 0.088646)
		(layer "F.Cu")
		(net "M_E_CPU1_SB_DQ<25>")
	)
	(segment
		(start 146.878802 -206.790544)
		(end 145.212308 -208.457038)
		(width 0.20066)
		(layer "F.Cu")
		(net "M_E_CPU1_SB_DQ<24>")
	)
	(segment
		(start 163.923726 -203.675742)
		(end 163.907724 -203.691744)
		(width 0.1016)
		(layer "F.Cu")
		(net "M_E_CPU1_SB_DQ<24>")
	)
	(segment
		(start 146.393662 -206.305404)
		(end 146.677634 -206.305404)
		(width 0.20066)
		(layer "F.Cu")
		(net "M_E_CPU1_SB_DQ<24>")
	)
	(segment
		(start 151.744934 -204.71511)
		(end 151.641302 -204.464666)
		(width 0.20066)
		(layer "F.Cu")
		(net "M_E_CPU1_SB_DQ<24>")
	)
	(segment
		(start 139.977114 -230.446834)
		(end 141.470126 -228.953822)
		(width 0.088646)
		(layer "F.Cu")
		(net "M_E_CPU1_SB_DQ<24>")
	)
	(segment
		(start 160.78581 -204.340968)
		(end 160.000442 -204.340968)
		(width 0.20066)
		(layer "F.Cu")
		(net "M_E_CPU1_SB_DQ<24>")
	)
	(segment
		(start 146.878802 -206.506572)
		(end 146.878802 -206.790544)
		(width 0.20066)
		(layer "F.Cu")
		(net "M_E_CPU1_SB_DQ<24>")
	)
	(segment
		(start 150.2791 -205.538578)
		(end 151.636476 -204.976984)
		(width 0.20066)
		(layer "F.Cu")
		(net "M_E_CPU1_SB_DQ<24>")
	)
	(segment
		(start 161.00298 -203.831952)
		(end 161.00298 -204.123798)
		(width 0.20066)
		(layer "F.Cu")
		(net "M_E_CPU1_SB_DQ<24>")
	)
	(segment
		(start 148.436584 -207.381094)
		(end 150.2791 -205.538578)
		(width 0.20066)
		(layer "F.Cu")
		(net "M_E_CPU1_SB_DQ<24>")
	)
	(segment
		(start 159.77616 -204.116686)
		(end 158.813246 -204.116686)
		(width 0.20066)
		(layer "F.Cu")
		(net "M_E_CPU1_SB_DQ<24>")
	)
	(segment
		(start 164.249862 -203.675742)
		(end 163.923726 -203.675742)
		(width 0.20066)
		(layer "F.Cu")
		(net "M_E_CPU1_SB_DQ<24>")
	)
	(segment
		(start 147.258532 -207.381094)
		(end 148.436584 -207.381094)
		(width 0.20066)
		(layer "F.Cu")
		(net "M_E_CPU1_SB_DQ<24>")
	)
	(segment
		(start 163.907724 -203.691744)
		(end 161.93643 -203.691744)
		(width 0.1016)
		(layer "F.Cu")
		(net "M_E_CPU1_SB_DQ<24>")
	)
	(segment
		(start 151.636476 -204.976984)
		(end 151.744934 -204.71511)
		(width 0.20066)
		(layer "F.Cu")
		(net "M_E_CPU1_SB_DQ<24>")
	)
	(segment
		(start 144.92097 -209.435192)
		(end 144.464786 -208.979008)
		(width 0.20066)
		(layer "F.Cu")
		(net "M_E_CPU1_SB_DQ<24>")
	)
	(segment
		(start 152.378664 -204.452474)
		(end 152.640538 -204.560932)
		(width 0.20066)
		(layer "F.Cu")
		(net "M_E_CPU1_SB_DQ<24>")
	)
	(segment
		(start 151.641302 -204.464666)
		(end 151.74976 -204.202538)
		(width 0.20066)
		(layer "F.Cu")
		(net "M_E_CPU1_SB_DQ<24>")
	)
	(segment
		(start 152.013158 -204.093318)
		(end 152.274778 -204.201776)
		(width 0.20066)
		(layer "F.Cu")
		(net "M_E_CPU1_SB_DQ<24>")
	)
	(segment
		(start 145.697448 -208.942178)
		(end 147.258532 -207.381094)
		(width 0.20066)
		(layer "F.Cu")
		(net "M_E_CPU1_SB_DQ<24>")
	)
	(segment
		(start 144.92097 -209.860642)
		(end 144.92097 -209.435192)
		(width 0.20066)
		(layer "F.Cu")
		(net "M_E_CPU1_SB_DQ<24>")
	)
	(segment
		(start 145.413476 -208.942178)
		(end 145.697448 -208.942178)
		(width 0.20066)
		(layer "F.Cu")
		(net "M_E_CPU1_SB_DQ<24>")
	)
	(segment
		(start 143.059912 -227.364036)
		(end 143.059912 -213.142576)
		(width 0.1016)
		(layer "F.Cu")
		(net "M_E_CPU1_SB_DQ<24>")
	)
	(segment
		(start 152.274778 -204.201776)
		(end 152.378664 -204.452474)
		(width 0.20066)
		(layer "F.Cu")
		(net "M_E_CPU1_SB_DQ<24>")
	)
	(segment
		(start 157.568392 -204.404976)
		(end 157.856682 -204.116686)
		(width 0.20066)
		(layer "F.Cu")
		(net "M_E_CPU1_SB_DQ<24>")
	)
	(segment
		(start 153.016966 -204.404976)
		(end 157.568392 -204.404976)
		(width 0.20066)
		(layer "F.Cu")
		(net "M_E_CPU1_SB_DQ<24>")
	)
	(segment
		(start 138.950954 -230.49484)
		(end 139.861036 -230.49484)
		(width 0.088646)
		(layer "F.Cu")
		(net "M_E_CPU1_SB_DQ<24>")
	)
	(segment
		(start 161.00298 -204.123798)
		(end 160.78581 -204.340968)
		(width 0.20066)
		(layer "F.Cu")
		(net "M_E_CPU1_SB_DQ<24>")
	)
	(segment
		(start 146.677634 -206.305404)
		(end 146.878802 -206.506572)
		(width 0.20066)
		(layer "F.Cu")
		(net "M_E_CPU1_SB_DQ<24>")
	)
	(segment
		(start 145.212308 -208.457038)
		(end 145.212308 -208.74101)
		(width 0.20066)
		(layer "F.Cu")
		(net "M_E_CPU1_SB_DQ<24>")
	)
	(segment
		(start 138.188954 -230.219504)
		(end 138.192002 -230.217726)
		(width 0.088646)
		(layer "F.Cu")
		(net "M_E_CPU1_SB_DQ<24>")
	)
	(segment
		(start 143.17218 -211.60867)
		(end 143.311372 -211.469478)
		(width 0.1016)
		(layer "F.Cu")
		(net "M_E_CPU1_SB_DQ<24>")
	)
	(segment
		(start 144.635474 -208.063592)
		(end 146.393662 -206.305404)
		(width 0.20066)
		(layer "F.Cu")
		(net "M_E_CPU1_SB_DQ<24>")
	)
	(segment
		(start 143.17218 -213.030308)
		(end 143.17218 -211.60867)
		(width 0.101854)
		(layer "F.Cu")
		(net "M_E_CPU1_SB_DQ<24>")
	)
	(segment
		(start 161.153856 -203.681076)
		(end 161.00298 -203.831952)
		(width 0.20066)
		(layer "F.Cu")
		(net "M_E_CPU1_SB_DQ<24>")
	)
	(segment
		(start 143.059912 -213.142576)
		(end 143.17218 -213.030308)
		(width 0.101854)
		(layer "F.Cu")
		(net "M_E_CPU1_SB_DQ<24>")
	)
	(segment
		(start 145.212308 -208.74101)
		(end 145.413476 -208.942178)
		(width 0.20066)
		(layer "F.Cu")
		(net "M_E_CPU1_SB_DQ<24>")
	)
	(segment
		(start 161.925762 -203.681076)
		(end 161.891726 -203.681076)
		(width 0.101854)
		(layer "F.Cu")
		(net "M_E_CPU1_SB_DQ<24>")
	)
	(segment
		(start 143.311372 -211.469478)
		(end 144.92097 -209.860642)
		(width 0.20066)
		(layer "F.Cu")
		(net "M_E_CPU1_SB_DQ<24>")
	)
	(segment
		(start 138.627104 -230.17099)
		(end 138.950954 -230.49484)
		(width 0.088646)
		(layer "F.Cu")
		(net "M_E_CPU1_SB_DQ<24>")
	)
	(segment
		(start 139.861036 -230.49484)
		(end 139.977114 -230.446834)
		(width 0.088646)
		(layer "F.Cu")
		(net "M_E_CPU1_SB_DQ<24>")
	)
	(segment
		(start 144.464786 -208.47558)
		(end 144.635474 -208.063592)
		(width 0.20066)
		(layer "F.Cu")
		(net "M_E_CPU1_SB_DQ<24>")
	)
	(segment
		(start 137.597134 -230.166418)
		(end 137.63371 -230.178356)
		(width 0.088646)
		(layer "F.Cu")
		(net "M_E_CPU1_SB_DQ<24>")
	)
	(segment
		(start 152.640538 -204.560932)
		(end 153.016966 -204.404976)
		(width 0.20066)
		(layer "F.Cu")
		(net "M_E_CPU1_SB_DQ<24>")
	)
	(segment
		(start 141.470126 -228.953822)
		(end 143.059912 -227.364036)
		(width 0.1016)
		(layer "F.Cu")
		(net "M_E_CPU1_SB_DQ<24>")
	)
	(segment
		(start 161.93643 -203.691744)
		(end 161.925762 -203.681076)
		(width 0.101854)
		(layer "F.Cu")
		(net "M_E_CPU1_SB_DQ<24>")
	)
	(segment
		(start 144.464786 -208.979008)
		(end 144.464786 -208.47558)
		(width 0.20066)
		(layer "F.Cu")
		(net "M_E_CPU1_SB_DQ<24>")
	)
	(segment
		(start 157.856682 -204.116686)
		(end 158.813246 -204.116686)
		(width 0.20066)
		(layer "F.Cu")
		(net "M_E_CPU1_SB_DQ<24>")
	)
	(segment
		(start 164.690806 -204.116686)
		(end 164.249862 -203.675742)
		(width 0.20066)
		(layer "F.Cu")
		(net "M_E_CPU1_SB_DQ<24>")
	)
	(segment
		(start 151.74976 -204.202538)
		(end 152.013158 -204.093318)
		(width 0.20066)
		(layer "F.Cu")
		(net "M_E_CPU1_SB_DQ<24>")
	)
	(segment
		(start 160.000442 -204.340968)
		(end 159.77616 -204.116686)
		(width 0.20066)
		(layer "F.Cu")
		(net "M_E_CPU1_SB_DQ<24>")
	)
	(segment
		(start 161.891726 -203.681076)
		(end 161.153856 -203.681076)
		(width 0.20066)
		(layer "F.Cu")
		(net "M_E_CPU1_SB_DQ<24>")
	)
	(segment
		(start 166.357046 -204.116686)
		(end 164.690806 -204.116686)
		(width 0.20066)
		(layer "F.Cu")
		(net "M_E_CPU1_SB_DQ<24>")
	)
	(arc
		(start 138.192002 -230.217726)
		(mid 138.328589 -230.165206)
		(end 138.474704 -230.157274)
		(width 0.088646)
		(layer "F.Cu")
		(net "M_E_CPU1_SB_DQ<24>")
	)
	(arc
		(start 138.474704 -230.157274)
		(mid 138.550865 -230.164566)
		(end 138.627104 -230.17099)
		(width 0.088646)
		(layer "F.Cu")
		(net "M_E_CPU1_SB_DQ<24>")
	)
	(arc
		(start 137.014712 -229.808786)
		(mid 137.284842 -230.02193)
		(end 137.597134 -230.166418)
		(width 0.088646)
		(layer "F.Cu")
		(net "M_E_CPU1_SB_DQ<24>")
	)
	(arc
		(start 137.63371 -230.178356)
		(mid 137.678921 -230.195762)
		(end 137.722102 -230.217726)
		(width 0.088646)
		(layer "F.Cu")
		(net "M_E_CPU1_SB_DQ<24>")
	)
	(arc
		(start 137.722102 -230.217726)
		(mid 137.955288 -230.280682)
		(end 138.188954 -230.219504)
		(width 0.088646)
		(layer "F.Cu")
		(net "M_E_CPU1_SB_DQ<24>")
	)
	(segment
		(start 140.202666 -231.030526)
		(end 140.591794 -230.641398)
		(width 0.088646)
		(layer "F.Cu")
		(net "M_E_CPU1_SB_DQ<23>")
	)
	(segment
		(start 169.135552 -204.96657)
		(end 168.883584 -204.714602)
		(width 0.20066)
		(layer "F.Cu")
		(net "M_E_CPU1_SB_DQ<23>")
	)
	(segment
		(start 143.618712 -213.490556)
		(end 143.753332 -213.355936)
		(width 0.1016)
		(layer "F.Cu")
		(net "M_E_CPU1_SB_DQ<23>")
	)
	(segment
		(start 157.825694 -205.40218)
		(end 157.836362 -205.391512)
		(width 0.101854)
		(layer "F.Cu")
		(net "M_E_CPU1_SB_DQ<23>")
	)
	(segment
		(start 153.254964 -205.291436)
		(end 156.94787 -205.291436)
		(width 0.20066)
		(layer "F.Cu")
		(net "M_E_CPU1_SB_DQ<23>")
	)
	(segment
		(start 165.074092 -205.40218)
		(end 164.638482 -204.96657)
		(width 0.20066)
		(layer "F.Cu")
		(net "M_E_CPU1_SB_DQ<23>")
	)
	(segment
		(start 168.499536 -204.714602)
		(end 168.265348 -204.94879)
		(width 0.20066)
		(layer "F.Cu")
		(net "M_E_CPU1_SB_DQ<23>")
	)
	(segment
		(start 164.638482 -204.96657)
		(end 162.913314 -204.96657)
		(width 0.20066)
		(layer "F.Cu")
		(net "M_E_CPU1_SB_DQ<23>")
	)
	(segment
		(start 157.836362 -205.391512)
		(end 159.807656 -205.391512)
		(width 0.1016)
		(layer "F.Cu")
		(net "M_E_CPU1_SB_DQ<23>")
	)
	(segment
		(start 157.058614 -205.40218)
		(end 157.791658 -205.40218)
		(width 0.20066)
		(layer "F.Cu")
		(net "M_E_CPU1_SB_DQ<23>")
	)
	(segment
		(start 165.369494 -205.40218)
		(end 165.335458 -205.40218)
		(width 0.101854)
		(layer "F.Cu")
		(net "M_E_CPU1_SB_DQ<23>")
	)
	(segment
		(start 160.450784 -205.407514)
		(end 160.891728 -204.96657)
		(width 0.20066)
		(layer "F.Cu")
		(net "M_E_CPU1_SB_DQ<23>")
	)
	(segment
		(start 165.380162 -205.391512)
		(end 165.369494 -205.40218)
		(width 0.101854)
		(layer "F.Cu")
		(net "M_E_CPU1_SB_DQ<23>")
	)
	(segment
		(start 143.753332 -213.355936)
		(end 143.93545 -213.173818)
		(width 0.20066)
		(layer "F.Cu")
		(net "M_E_CPU1_SB_DQ<23>")
	)
	(segment
		(start 150.762462 -206.323692)
		(end 153.254964 -205.291436)
		(width 0.20066)
		(layer "F.Cu")
		(net "M_E_CPU1_SB_DQ<23>")
	)
	(segment
		(start 137.954766 -231.436418)
		(end 138.934698 -231.030526)
		(width 0.088646)
		(layer "F.Cu")
		(net "M_E_CPU1_SB_DQ<23>")
	)
	(segment
		(start 148.8186 -208.267554)
		(end 150.762462 -206.323692)
		(width 0.20066)
		(layer "F.Cu")
		(net "M_E_CPU1_SB_DQ<23>")
	)
	(segment
		(start 159.823658 -205.407514)
		(end 160.450784 -205.407514)
		(width 0.20066)
		(layer "F.Cu")
		(net "M_E_CPU1_SB_DQ<23>")
	)
	(segment
		(start 168.064688 -205.407514)
		(end 167.367458 -205.407514)
		(width 0.20066)
		(layer "F.Cu")
		(net "M_E_CPU1_SB_DQ<23>")
	)
	(segment
		(start 143.93545 -213.173818)
		(end 143.93545 -212.10016)
		(width 0.20066)
		(layer "F.Cu")
		(net "M_E_CPU1_SB_DQ<23>")
	)
	(segment
		(start 165.335458 -205.40218)
		(end 165.074092 -205.40218)
		(width 0.20066)
		(layer "F.Cu")
		(net "M_E_CPU1_SB_DQ<23>")
	)
	(segment
		(start 159.807656 -205.391512)
		(end 159.823658 -205.407514)
		(width 0.1016)
		(layer "F.Cu")
		(net "M_E_CPU1_SB_DQ<23>")
	)
	(segment
		(start 168.265348 -205.206854)
		(end 168.064688 -205.407514)
		(width 0.20066)
		(layer "F.Cu")
		(net "M_E_CPU1_SB_DQ<23>")
	)
	(segment
		(start 157.791658 -205.40218)
		(end 157.825694 -205.40218)
		(width 0.101854)
		(layer "F.Cu")
		(net "M_E_CPU1_SB_DQ<23>")
	)
	(segment
		(start 168.265348 -204.94879)
		(end 168.265348 -205.206854)
		(width 0.20066)
		(layer "F.Cu")
		(net "M_E_CPU1_SB_DQ<23>")
	)
	(segment
		(start 170.457114 -204.96657)
		(end 169.135552 -204.96657)
		(width 0.20066)
		(layer "F.Cu")
		(net "M_E_CPU1_SB_DQ<23>")
	)
	(segment
		(start 160.891728 -204.96657)
		(end 162.913314 -204.96657)
		(width 0.20066)
		(layer "F.Cu")
		(net "M_E_CPU1_SB_DQ<23>")
	)
	(segment
		(start 143.618712 -227.61448)
		(end 143.618712 -213.490556)
		(width 0.1016)
		(layer "F.Cu")
		(net "M_E_CPU1_SB_DQ<23>")
	)
	(segment
		(start 140.591794 -230.641398)
		(end 143.618712 -227.61448)
		(width 0.1016)
		(layer "F.Cu")
		(net "M_E_CPU1_SB_DQ<23>")
	)
	(segment
		(start 147.768056 -208.267554)
		(end 148.8186 -208.267554)
		(width 0.20066)
		(layer "F.Cu")
		(net "M_E_CPU1_SB_DQ<23>")
	)
	(segment
		(start 167.351456 -205.391512)
		(end 165.380162 -205.391512)
		(width 0.1016)
		(layer "F.Cu")
		(net "M_E_CPU1_SB_DQ<23>")
	)
	(segment
		(start 168.883584 -204.714602)
		(end 168.499536 -204.714602)
		(width 0.20066)
		(layer "F.Cu")
		(net "M_E_CPU1_SB_DQ<23>")
	)
	(segment
		(start 138.934698 -231.030526)
		(end 140.202666 -231.030526)
		(width 0.088646)
		(layer "F.Cu")
		(net "M_E_CPU1_SB_DQ<23>")
	)
	(segment
		(start 143.93545 -212.10016)
		(end 147.768056 -208.267554)
		(width 0.20066)
		(layer "F.Cu")
		(net "M_E_CPU1_SB_DQ<23>")
	)
	(segment
		(start 167.367458 -205.407514)
		(end 167.351456 -205.391512)
		(width 0.1016)
		(layer "F.Cu")
		(net "M_E_CPU1_SB_DQ<23>")
	)
	(segment
		(start 156.94787 -205.291436)
		(end 157.058614 -205.40218)
		(width 0.20066)
		(layer "F.Cu")
		(net "M_E_CPU1_SB_DQ<23>")
	)
	(segment
		(start 139.812014 -232.283762)
		(end 141.023086 -231.07269)
		(width 0.088646)
		(layer "F.Cu")
		(net "M_E_CPU1_SB_DQ<22>")
	)
	(segment
		(start 160.763712 -207.107536)
		(end 161.204656 -206.666592)
		(width 0.20066)
		(layer "F.Cu")
		(net "M_E_CPU1_SB_DQ<22>")
	)
	(segment
		(start 165.335458 -207.102202)
		(end 165.068504 -207.102202)
		(width 0.20066)
		(layer "F.Cu")
		(net "M_E_CPU1_SB_DQ<22>")
	)
	(segment
		(start 170.457114 -206.666592)
		(end 169.135552 -206.666592)
		(width 0.20066)
		(layer "F.Cu")
		(net "M_E_CPU1_SB_DQ<22>")
	)
	(segment
		(start 157.791658 -207.102202)
		(end 157.825694 -207.102202)
		(width 0.101854)
		(layer "F.Cu")
		(net "M_E_CPU1_SB_DQ<22>")
	)
	(segment
		(start 141.023086 -231.07269)
		(end 144.228312 -227.867464)
		(width 0.1016)
		(layer "F.Cu")
		(net "M_E_CPU1_SB_DQ<22>")
	)
	(segment
		(start 148.051774 -210.950556)
		(end 151.623014 -207.379316)
		(width 0.20066)
		(layer "F.Cu")
		(net "M_E_CPU1_SB_DQ<22>")
	)
	(segment
		(start 151.623014 -207.379316)
		(end 153.092404 -206.770732)
		(width 0.20066)
		(layer "F.Cu")
		(net "M_E_CPU1_SB_DQ<22>")
	)
	(segment
		(start 157.836362 -207.091534)
		(end 159.807656 -207.091534)
		(width 0.1016)
		(layer "F.Cu")
		(net "M_E_CPU1_SB_DQ<22>")
	)
	(segment
		(start 138.424666 -232.250488)
		(end 138.448796 -232.274618)
		(width 0.088646)
		(layer "F.Cu")
		(net "M_E_CPU1_SB_DQ<22>")
	)
	(segment
		(start 161.204656 -206.666592)
		(end 162.913314 -206.666592)
		(width 0.20066)
		(layer "F.Cu")
		(net "M_E_CPU1_SB_DQ<22>")
	)
	(segment
		(start 168.265348 -206.648812)
		(end 168.265348 -206.906876)
		(width 0.20066)
		(layer "F.Cu")
		(net "M_E_CPU1_SB_DQ<22>")
	)
	(segment
		(start 167.367458 -207.107536)
		(end 167.351456 -207.091534)
		(width 0.1016)
		(layer "F.Cu")
		(net "M_E_CPU1_SB_DQ<22>")
	)
	(segment
		(start 165.068504 -207.102202)
		(end 164.632894 -206.666592)
		(width 0.20066)
		(layer "F.Cu")
		(net "M_E_CPU1_SB_DQ<22>")
	)
	(segment
		(start 145.251424 -213.722458)
		(end 145.251424 -212.64753)
		(width 0.20066)
		(layer "F.Cu")
		(net "M_E_CPU1_SB_DQ<22>")
	)
	(segment
		(start 156.985208 -206.770732)
		(end 157.316678 -207.102202)
		(width 0.20066)
		(layer "F.Cu")
		(net "M_E_CPU1_SB_DQ<22>")
	)
	(segment
		(start 164.632894 -206.666592)
		(end 162.913314 -206.666592)
		(width 0.20066)
		(layer "F.Cu")
		(net "M_E_CPU1_SB_DQ<22>")
	)
	(segment
		(start 153.092404 -206.770732)
		(end 156.985208 -206.770732)
		(width 0.20066)
		(layer "F.Cu")
		(net "M_E_CPU1_SB_DQ<22>")
	)
	(segment
		(start 167.351456 -207.091534)
		(end 165.380162 -207.091534)
		(width 0.1016)
		(layer "F.Cu")
		(net "M_E_CPU1_SB_DQ<22>")
	)
	(segment
		(start 157.825694 -207.102202)
		(end 157.836362 -207.091534)
		(width 0.101854)
		(layer "F.Cu")
		(net "M_E_CPU1_SB_DQ<22>")
	)
	(segment
		(start 168.883584 -206.414624)
		(end 168.499536 -206.414624)
		(width 0.20066)
		(layer "F.Cu")
		(net "M_E_CPU1_SB_DQ<22>")
	)
	(segment
		(start 159.823658 -207.107536)
		(end 160.763712 -207.107536)
		(width 0.20066)
		(layer "F.Cu")
		(net "M_E_CPU1_SB_DQ<22>")
	)
	(segment
		(start 168.265348 -206.906876)
		(end 168.064688 -207.107536)
		(width 0.20066)
		(layer "F.Cu")
		(net "M_E_CPU1_SB_DQ<22>")
	)
	(segment
		(start 169.135552 -206.666592)
		(end 168.883584 -206.414624)
		(width 0.20066)
		(layer "F.Cu")
		(net "M_E_CPU1_SB_DQ<22>")
	)
	(segment
		(start 144.228312 -214.74557)
		(end 144.480788 -214.493094)
		(width 0.1016)
		(layer "F.Cu")
		(net "M_E_CPU1_SB_DQ<22>")
	)
	(segment
		(start 138.471148 -232.283762)
		(end 139.812014 -232.283762)
		(width 0.088646)
		(layer "F.Cu")
		(net "M_E_CPU1_SB_DQ<22>")
	)
	(segment
		(start 159.807656 -207.091534)
		(end 159.823658 -207.107536)
		(width 0.1016)
		(layer "F.Cu")
		(net "M_E_CPU1_SB_DQ<22>")
	)
	(segment
		(start 145.251424 -212.64753)
		(end 146.948398 -210.950556)
		(width 0.20066)
		(layer "F.Cu")
		(net "M_E_CPU1_SB_DQ<22>")
	)
	(segment
		(start 157.316678 -207.102202)
		(end 157.791658 -207.102202)
		(width 0.20066)
		(layer "F.Cu")
		(net "M_E_CPU1_SB_DQ<22>")
	)
	(segment
		(start 165.369494 -207.102202)
		(end 165.335458 -207.102202)
		(width 0.101854)
		(layer "F.Cu")
		(net "M_E_CPU1_SB_DQ<22>")
	)
	(segment
		(start 168.064688 -207.107536)
		(end 167.367458 -207.107536)
		(width 0.20066)
		(layer "F.Cu")
		(net "M_E_CPU1_SB_DQ<22>")
	)
	(segment
		(start 144.228312 -227.867464)
		(end 144.228312 -214.74557)
		(width 0.1016)
		(layer "F.Cu")
		(net "M_E_CPU1_SB_DQ<22>")
	)
	(segment
		(start 168.499536 -206.414624)
		(end 168.265348 -206.648812)
		(width 0.20066)
		(layer "F.Cu")
		(net "M_E_CPU1_SB_DQ<22>")
	)
	(segment
		(start 146.948398 -210.950556)
		(end 148.051774 -210.950556)
		(width 0.20066)
		(layer "F.Cu")
		(net "M_E_CPU1_SB_DQ<22>")
	)
	(segment
		(start 144.480788 -214.493094)
		(end 145.251424 -213.722458)
		(width 0.20066)
		(layer "F.Cu")
		(net "M_E_CPU1_SB_DQ<22>")
	)
	(segment
		(start 165.380162 -207.091534)
		(end 165.369494 -207.102202)
		(width 0.101854)
		(layer "F.Cu")
		(net "M_E_CPU1_SB_DQ<22>")
	)
	(arc
		(start 138.448796 -232.274618)
		(mid 138.459051 -232.28147)
		(end 138.471148 -232.283762)
		(width 0.088646)
		(layer "F.Cu")
		(net "M_E_CPU1_SB_DQ<22>")
	)
	(segment
		(start 143.923512 -227.740972)
		(end 143.923512 -214.127588)
		(width 0.1016)
		(layer "F.Cu")
		(net "M_E_CPU1_SB_DQ<21>")
	)
	(segment
		(start 161.93643 -205.391512)
		(end 161.925762 -205.380844)
		(width 0.101854)
		(layer "F.Cu")
		(net "M_E_CPU1_SB_DQ<21>")
	)
	(segment
		(start 148.101812 -209.940398)
		(end 148.101812 -209.656934)
		(width 0.20066)
		(layer "F.Cu")
		(net "M_E_CPU1_SB_DQ<21>")
	)
	(segment
		(start 161.925762 -205.380844)
		(end 161.891726 -205.380844)
		(width 0.101854)
		(layer "F.Cu")
		(net "M_E_CPU1_SB_DQ<21>")
	)
	(segment
		(start 151.196548 -206.845662)
		(end 153.405078 -205.931008)
		(width 0.20066)
		(layer "F.Cu")
		(net "M_E_CPU1_SB_DQ<21>")
	)
	(segment
		(start 144.597882 -213.453218)
		(end 144.597882 -212.364828)
		(width 0.20066)
		(layer "F.Cu")
		(net "M_E_CPU1_SB_DQ<21>")
	)
	(segment
		(start 147.789392 -210.252818)
		(end 148.101812 -209.940398)
		(width 0.20066)
		(layer "F.Cu")
		(net "M_E_CPU1_SB_DQ<21>")
	)
	(segment
		(start 139.142216 -232.089706)
		(end 139.574778 -232.089706)
		(width 0.088646)
		(layer "F.Cu")
		(net "M_E_CPU1_SB_DQ<21>")
	)
	(segment
		(start 148.586952 -209.171794)
		(end 148.870416 -209.171794)
		(width 0.20066)
		(layer "F.Cu")
		(net "M_E_CPU1_SB_DQ<21>")
	)
	(segment
		(start 143.923512 -214.127588)
		(end 144.224248 -213.826852)
		(width 0.1016)
		(layer "F.Cu")
		(net "M_E_CPU1_SB_DQ<21>")
	)
	(segment
		(start 161.105596 -205.877414)
		(end 160.94202 -206.04099)
		(width 0.20066)
		(layer "F.Cu")
		(net "M_E_CPU1_SB_DQ<21>")
	)
	(segment
		(start 161.292032 -205.380844)
		(end 161.105596 -205.56728)
		(width 0.20066)
		(layer "F.Cu")
		(net "M_E_CPU1_SB_DQ<21>")
	)
	(segment
		(start 137.752582 -231.932226)
		(end 138.155426 -231.932226)
		(width 0.088646)
		(layer "F.Cu")
		(net "M_E_CPU1_SB_DQ<21>")
	)
	(segment
		(start 164.911024 -205.816962)
		(end 164.469572 -205.37551)
		(width 0.20066)
		(layer "F.Cu")
		(net "M_E_CPU1_SB_DQ<21>")
	)
	(segment
		(start 147.450048 -210.252818)
		(end 147.789392 -210.252818)
		(width 0.20066)
		(layer "F.Cu")
		(net "M_E_CPU1_SB_DQ<21>")
	)
	(segment
		(start 166.357046 -205.816708)
		(end 164.911278 -205.816708)
		(width 0.20066)
		(layer "F.Cu")
		(net "M_E_CPU1_SB_DQ<21>")
	)
	(segment
		(start 156.599382 -205.931008)
		(end 156.673296 -206.004922)
		(width 0.20066)
		(layer "F.Cu")
		(net "M_E_CPU1_SB_DQ<21>")
	)
	(segment
		(start 148.038566 -208.907126)
		(end 148.32203 -208.907126)
		(width 0.20066)
		(layer "F.Cu")
		(net "M_E_CPU1_SB_DQ<21>")
	)
	(segment
		(start 163.907724 -205.391512)
		(end 161.93643 -205.391512)
		(width 0.1016)
		(layer "F.Cu")
		(net "M_E_CPU1_SB_DQ<21>")
	)
	(segment
		(start 147.221956 -210.024726)
		(end 147.450048 -210.252818)
		(width 0.20066)
		(layer "F.Cu")
		(net "M_E_CPU1_SB_DQ<21>")
	)
	(segment
		(start 137.49147 -231.671114)
		(end 137.752582 -231.932226)
		(width 0.088646)
		(layer "F.Cu")
		(net "M_E_CPU1_SB_DQ<21>")
	)
	(segment
		(start 163.923726 -205.37551)
		(end 163.907724 -205.391512)
		(width 0.1016)
		(layer "F.Cu")
		(net "M_E_CPU1_SB_DQ<21>")
	)
	(segment
		(start 147.83689 -209.108802)
		(end 148.038566 -208.907126)
		(width 0.20066)
		(layer "F.Cu")
		(net "M_E_CPU1_SB_DQ<21>")
	)
	(segment
		(start 137.389616 -231.436418)
		(end 137.49147 -231.538272)
		(width 0.088646)
		(layer "F.Cu")
		(net "M_E_CPU1_SB_DQ<21>")
	)
	(segment
		(start 160.725866 -206.04099)
		(end 160.501584 -205.816708)
		(width 0.20066)
		(layer "F.Cu")
		(net "M_E_CPU1_SB_DQ<21>")
	)
	(segment
		(start 164.911278 -205.816708)
		(end 164.911024 -205.816962)
		(width 0.20066)
		(layer "F.Cu")
		(net "M_E_CPU1_SB_DQ<21>")
	)
	(segment
		(start 144.224248 -213.826852)
		(end 144.597882 -213.453218)
		(width 0.20066)
		(layer "F.Cu")
		(net "M_E_CPU1_SB_DQ<21>")
	)
	(segment
		(start 157.8991 -205.816708)
		(end 158.813246 -205.816708)
		(width 0.20066)
		(layer "F.Cu")
		(net "M_E_CPU1_SB_DQ<21>")
	)
	(segment
		(start 164.469572 -205.37551)
		(end 163.923726 -205.37551)
		(width 0.20066)
		(layer "F.Cu")
		(net "M_E_CPU1_SB_DQ<21>")
	)
	(segment
		(start 161.105596 -205.56728)
		(end 161.105596 -205.877414)
		(width 0.20066)
		(layer "F.Cu")
		(net "M_E_CPU1_SB_DQ<21>")
	)
	(segment
		(start 148.870416 -209.171794)
		(end 151.196548 -206.845662)
		(width 0.20066)
		(layer "F.Cu")
		(net "M_E_CPU1_SB_DQ<21>")
	)
	(segment
		(start 148.32203 -208.907126)
		(end 148.586952 -209.171794)
		(width 0.20066)
		(layer "F.Cu")
		(net "M_E_CPU1_SB_DQ<21>")
	)
	(segment
		(start 147.83689 -209.392266)
		(end 147.83689 -209.108802)
		(width 0.20066)
		(layer "F.Cu")
		(net "M_E_CPU1_SB_DQ<21>")
	)
	(segment
		(start 161.891726 -205.380844)
		(end 161.292032 -205.380844)
		(width 0.20066)
		(layer "F.Cu")
		(net "M_E_CPU1_SB_DQ<21>")
	)
	(segment
		(start 137.49147 -231.538272)
		(end 137.49147 -231.671114)
		(width 0.088646)
		(layer "F.Cu")
		(net "M_E_CPU1_SB_DQ<21>")
	)
	(segment
		(start 160.501584 -205.816708)
		(end 158.813246 -205.816708)
		(width 0.20066)
		(layer "F.Cu")
		(net "M_E_CPU1_SB_DQ<21>")
	)
	(segment
		(start 138.267694 -231.818942)
		(end 138.871452 -231.818942)
		(width 0.088646)
		(layer "F.Cu")
		(net "M_E_CPU1_SB_DQ<21>")
	)
	(segment
		(start 139.574778 -232.089706)
		(end 140.80744 -230.857044)
		(width 0.088646)
		(layer "F.Cu")
		(net "M_E_CPU1_SB_DQ<21>")
	)
	(segment
		(start 157.710886 -206.004922)
		(end 157.8991 -205.816708)
		(width 0.20066)
		(layer "F.Cu")
		(net "M_E_CPU1_SB_DQ<21>")
	)
	(segment
		(start 140.80744 -230.857044)
		(end 143.923512 -227.740972)
		(width 0.1016)
		(layer "F.Cu")
		(net "M_E_CPU1_SB_DQ<21>")
	)
	(segment
		(start 138.155426 -231.932226)
		(end 138.267694 -231.818942)
		(width 0.088646)
		(layer "F.Cu")
		(net "M_E_CPU1_SB_DQ<21>")
	)
	(segment
		(start 160.94202 -206.04099)
		(end 160.725866 -206.04099)
		(width 0.20066)
		(layer "F.Cu")
		(net "M_E_CPU1_SB_DQ<21>")
	)
	(segment
		(start 153.405078 -205.931008)
		(end 156.599382 -205.931008)
		(width 0.20066)
		(layer "F.Cu")
		(net "M_E_CPU1_SB_DQ<21>")
	)
	(segment
		(start 137.014712 -231.436418)
		(end 137.389616 -231.436418)
		(width 0.088646)
		(layer "F.Cu")
		(net "M_E_CPU1_SB_DQ<21>")
	)
	(segment
		(start 148.101812 -209.656934)
		(end 147.83689 -209.392266)
		(width 0.20066)
		(layer "F.Cu")
		(net "M_E_CPU1_SB_DQ<21>")
	)
	(segment
		(start 144.597882 -212.364828)
		(end 146.937984 -210.024726)
		(width 0.20066)
		(layer "F.Cu")
		(net "M_E_CPU1_SB_DQ<21>")
	)
	(segment
		(start 138.871452 -231.818942)
		(end 139.142216 -232.089706)
		(width 0.088646)
		(layer "F.Cu")
		(net "M_E_CPU1_SB_DQ<21>")
	)
	(segment
		(start 146.937984 -210.024726)
		(end 147.221956 -210.024726)
		(width 0.20066)
		(layer "F.Cu")
		(net "M_E_CPU1_SB_DQ<21>")
	)
	(segment
		(start 156.673296 -206.004922)
		(end 157.710886 -206.004922)
		(width 0.20066)
		(layer "F.Cu")
		(net "M_E_CPU1_SB_DQ<21>")
	)
	(segment
		(start 166.357046 -207.51673)
		(end 164.898578 -207.51673)
		(width 0.20066)
		(layer "F.Cu")
		(net "M_E_CPU1_SB_DQ<20>")
	)
	(segment
		(start 136.647428 -232.619042)
		(end 136.729978 -232.570528)
		(width 0.088646)
		(layer "F.Cu")
		(net "M_E_CPU1_SB_DQ<20>")
	)
	(segment
		(start 138.6078 -232.58018)
		(end 138.61415 -232.57764)
		(width 0.088646)
		(layer "F.Cu")
		(net "M_E_CPU1_SB_DQ<20>")
	)
	(segment
		(start 161.245804 -207.577436)
		(end 161.082228 -207.741012)
		(width 0.20066)
		(layer "F.Cu")
		(net "M_E_CPU1_SB_DQ<20>")
	)
	(segment
		(start 153.306526 -207.419702)
		(end 156.965904 -207.419702)
		(width 0.20066)
		(layer "F.Cu")
		(net "M_E_CPU1_SB_DQ<20>")
	)
	(segment
		(start 147.01901 -212.081872)
		(end 147.01901 -211.7979)
		(width 0.20066)
		(layer "F.Cu")
		(net "M_E_CPU1_SB_DQ<20>")
	)
	(segment
		(start 140.239496 -232.287572)
		(end 144.533112 -227.993956)
		(width 0.1016)
		(layer "F.Cu")
		(net "M_E_CPU1_SB_DQ<20>")
	)
	(segment
		(start 144.864582 -215.051132)
		(end 146.31416 -213.601554)
		(width 0.20066)
		(layer "F.Cu")
		(net "M_E_CPU1_SB_DQ<20>")
	)
	(segment
		(start 144.533112 -215.382602)
		(end 144.864582 -215.051132)
		(width 0.1016)
		(layer "F.Cu")
		(net "M_E_CPU1_SB_DQ<20>")
	)
	(segment
		(start 146.249898 -212.567012)
		(end 146.53387 -212.567012)
		(width 0.20066)
		(layer "F.Cu")
		(net "M_E_CPU1_SB_DQ<20>")
	)
	(segment
		(start 147.220178 -211.596732)
		(end 147.50415 -211.596732)
		(width 0.20066)
		(layer "F.Cu")
		(net "M_E_CPU1_SB_DQ<20>")
	)
	(segment
		(start 164.898578 -207.51673)
		(end 164.45738 -207.075532)
		(width 0.20066)
		(layer "F.Cu")
		(net "M_E_CPU1_SB_DQ<20>")
	)
	(segment
		(start 147.28444 -212.347302)
		(end 147.01901 -212.081872)
		(width 0.20066)
		(layer "F.Cu")
		(net "M_E_CPU1_SB_DQ<20>")
	)
	(segment
		(start 146.04873 -212.76818)
		(end 146.249898 -212.567012)
		(width 0.20066)
		(layer "F.Cu")
		(net "M_E_CPU1_SB_DQ<20>")
	)
	(segment
		(start 161.43224 -207.080866)
		(end 161.245804 -207.267302)
		(width 0.20066)
		(layer "F.Cu")
		(net "M_E_CPU1_SB_DQ<20>")
	)
	(segment
		(start 140.023342 -232.503726)
		(end 140.239496 -232.287572)
		(width 0.088646)
		(layer "F.Cu")
		(net "M_E_CPU1_SB_DQ<20>")
	)
	(segment
		(start 136.289542 -232.619042)
		(end 136.647428 -232.619042)
		(width 0.088646)
		(layer "F.Cu")
		(net "M_E_CPU1_SB_DQ<20>")
	)
	(segment
		(start 164.45738 -207.075532)
		(end 163.923726 -207.075532)
		(width 0.20066)
		(layer "F.Cu")
		(net "M_E_CPU1_SB_DQ<20>")
	)
	(segment
		(start 136.199118 -232.299002)
		(end 136.199118 -232.528618)
		(width 0.088646)
		(layer "F.Cu")
		(net "M_E_CPU1_SB_DQ<20>")
	)
	(segment
		(start 156.965904 -207.419702)
		(end 157.062932 -207.51673)
		(width 0.20066)
		(layer "F.Cu")
		(net "M_E_CPU1_SB_DQ<20>")
	)
	(segment
		(start 160.641792 -207.51673)
		(end 158.813246 -207.51673)
		(width 0.20066)
		(layer "F.Cu")
		(net "M_E_CPU1_SB_DQ<20>")
	)
	(segment
		(start 137.186416 -232.496614)
		(end 137.46226 -232.656126)
		(width 0.088646)
		(layer "F.Cu")
		(net "M_E_CPU1_SB_DQ<20>")
	)
	(segment
		(start 147.28444 -212.631274)
		(end 147.28444 -212.347302)
		(width 0.20066)
		(layer "F.Cu")
		(net "M_E_CPU1_SB_DQ<20>")
	)
	(segment
		(start 146.53387 -212.567012)
		(end 146.7993 -212.832442)
		(width 0.20066)
		(layer "F.Cu")
		(net "M_E_CPU1_SB_DQ<20>")
	)
	(segment
		(start 147.50415 -211.596732)
		(end 147.76958 -211.862162)
		(width 0.20066)
		(layer "F.Cu")
		(net "M_E_CPU1_SB_DQ<20>")
	)
	(segment
		(start 148.053552 -211.862162)
		(end 151.922988 -207.992726)
		(width 0.20066)
		(layer "F.Cu")
		(net "M_E_CPU1_SB_DQ<20>")
	)
	(segment
		(start 163.923726 -207.075532)
		(end 163.907724 -207.091534)
		(width 0.1016)
		(layer "F.Cu")
		(net "M_E_CPU1_SB_DQ<20>")
	)
	(segment
		(start 161.245804 -207.267302)
		(end 161.245804 -207.577436)
		(width 0.20066)
		(layer "F.Cu")
		(net "M_E_CPU1_SB_DQ<20>")
	)
	(segment
		(start 146.04873 -213.052152)
		(end 146.04873 -212.76818)
		(width 0.20066)
		(layer "F.Cu")
		(net "M_E_CPU1_SB_DQ<20>")
	)
	(segment
		(start 161.925762 -207.080866)
		(end 161.891726 -207.080866)
		(width 0.101854)
		(layer "F.Cu")
		(net "M_E_CPU1_SB_DQ<20>")
	)
	(segment
		(start 147.01901 -211.7979)
		(end 147.220178 -211.596732)
		(width 0.20066)
		(layer "F.Cu")
		(net "M_E_CPU1_SB_DQ<20>")
	)
	(segment
		(start 146.31416 -213.317582)
		(end 146.04873 -213.052152)
		(width 0.20066)
		(layer "F.Cu")
		(net "M_E_CPU1_SB_DQ<20>")
	)
	(segment
		(start 136.729978 -232.570528)
		(end 136.87425 -232.492296)
		(width 0.088646)
		(layer "F.Cu")
		(net "M_E_CPU1_SB_DQ<20>")
	)
	(segment
		(start 157.062932 -207.51673)
		(end 158.813246 -207.51673)
		(width 0.20066)
		(layer "F.Cu")
		(net "M_E_CPU1_SB_DQ<20>")
	)
	(segment
		(start 147.76958 -211.862162)
		(end 148.053552 -211.862162)
		(width 0.20066)
		(layer "F.Cu")
		(net "M_E_CPU1_SB_DQ<20>")
	)
	(segment
		(start 151.922988 -207.992726)
		(end 153.306526 -207.419702)
		(width 0.20066)
		(layer "F.Cu")
		(net "M_E_CPU1_SB_DQ<20>")
	)
	(segment
		(start 161.93643 -207.091534)
		(end 161.925762 -207.080866)
		(width 0.101854)
		(layer "F.Cu")
		(net "M_E_CPU1_SB_DQ<20>")
	)
	(segment
		(start 161.082228 -207.741012)
		(end 160.866074 -207.741012)
		(width 0.20066)
		(layer "F.Cu")
		(net "M_E_CPU1_SB_DQ<20>")
	)
	(segment
		(start 144.533112 -227.993956)
		(end 144.533112 -215.382602)
		(width 0.1016)
		(layer "F.Cu")
		(net "M_E_CPU1_SB_DQ<20>")
	)
	(segment
		(start 136.545066 -232.250488)
		(end 136.247632 -232.250488)
		(width 0.088646)
		(layer "F.Cu")
		(net "M_E_CPU1_SB_DQ<20>")
	)
	(segment
		(start 136.199118 -232.528618)
		(end 136.289542 -232.619042)
		(width 0.088646)
		(layer "F.Cu")
		(net "M_E_CPU1_SB_DQ<20>")
	)
	(segment
		(start 160.866074 -207.741012)
		(end 160.641792 -207.51673)
		(width 0.20066)
		(layer "F.Cu")
		(net "M_E_CPU1_SB_DQ<20>")
	)
	(segment
		(start 147.083272 -212.832442)
		(end 147.28444 -212.631274)
		(width 0.20066)
		(layer "F.Cu")
		(net "M_E_CPU1_SB_DQ<20>")
	)
	(segment
		(start 138.431524 -232.656126)
		(end 138.6078 -232.58018)
		(width 0.088646)
		(layer "F.Cu")
		(net "M_E_CPU1_SB_DQ<20>")
	)
	(segment
		(start 163.907724 -207.091534)
		(end 161.93643 -207.091534)
		(width 0.1016)
		(layer "F.Cu")
		(net "M_E_CPU1_SB_DQ<20>")
	)
	(segment
		(start 146.31416 -213.601554)
		(end 146.31416 -213.317582)
		(width 0.20066)
		(layer "F.Cu")
		(net "M_E_CPU1_SB_DQ<20>")
	)
	(segment
		(start 137.46226 -232.656126)
		(end 138.431524 -232.656126)
		(width 0.088646)
		(layer "F.Cu")
		(net "M_E_CPU1_SB_DQ<20>")
	)
	(segment
		(start 136.247632 -232.250488)
		(end 136.199118 -232.299002)
		(width 0.088646)
		(layer "F.Cu")
		(net "M_E_CPU1_SB_DQ<20>")
	)
	(segment
		(start 161.891726 -207.080866)
		(end 161.43224 -207.080866)
		(width 0.20066)
		(layer "F.Cu")
		(net "M_E_CPU1_SB_DQ<20>")
	)
	(segment
		(start 146.7993 -212.832442)
		(end 147.083272 -212.832442)
		(width 0.20066)
		(layer "F.Cu")
		(net "M_E_CPU1_SB_DQ<20>")
	)
	(segment
		(start 138.741912 -232.503726)
		(end 140.023342 -232.503726)
		(width 0.088646)
		(layer "F.Cu")
		(net "M_E_CPU1_SB_DQ<20>")
	)
	(segment
		(start 138.61415 -232.57764)
		(end 138.741912 -232.503726)
		(width 0.088646)
		(layer "F.Cu")
		(net "M_E_CPU1_SB_DQ<20>")
	)
	(arc
		(start 136.87425 -232.492296)
		(mid 137.030885 -232.453681)
		(end 137.186416 -232.496614)
		(width 0.088646)
		(layer "F.Cu")
		(net "M_E_CPU1_SB_DQ<20>")
	)
	(segment
		(start 164.333682 -230.035354)
		(end 163.923726 -230.035354)
		(width 0.20066)
		(layer "F.Cu")
		(net "M_E_CPU1_SB_DQ<1>")
	)
	(segment
		(start 161.728658 -230.041704)
		(end 161.708592 -230.041704)
		(width 0.101854)
		(layer "F.Cu")
		(net "M_E_CPU1_SB_DQ<1>")
	)
	(segment
		(start 133.255512 -236.319822)
		(end 133.255766 -236.319568)
		(width 0.20066)
		(layer "F.Cu")
		(net "M_E_CPU1_SB_DQ<1>")
	)
	(segment
		(start 166.356792 -230.4669)
		(end 164.765228 -230.4669)
		(width 0.20066)
		(layer "F.Cu")
		(net "M_E_CPU1_SB_DQ<1>")
	)
	(segment
		(start 157.682946 -230.466646)
		(end 158.813246 -230.466646)
		(width 0.20066)
		(layer "F.Cu")
		(net "M_E_CPU1_SB_DQ<1>")
	)
	(segment
		(start 166.357046 -230.466646)
		(end 166.356792 -230.4669)
		(width 0.20066)
		(layer "F.Cu")
		(net "M_E_CPU1_SB_DQ<1>")
	)
	(segment
		(start 161.363914 -230.041704)
		(end 161.245804 -230.159814)
		(width 0.20066)
		(layer "F.Cu")
		(net "M_E_CPU1_SB_DQ<1>")
	)
	(segment
		(start 160.333944 -230.466646)
		(end 158.813246 -230.466646)
		(width 0.20066)
		(layer "F.Cu")
		(net "M_E_CPU1_SB_DQ<1>")
	)
	(segment
		(start 164.765228 -230.4669)
		(end 164.333682 -230.035354)
		(width 0.20066)
		(layer "F.Cu")
		(net "M_E_CPU1_SB_DQ<1>")
	)
	(segment
		(start 163.923726 -230.035354)
		(end 163.917376 -230.041704)
		(width 0.1016)
		(layer "F.Cu")
		(net "M_E_CPU1_SB_DQ<1>")
	)
	(segment
		(start 161.057844 -230.715312)
		(end 160.58261 -230.715312)
		(width 0.20066)
		(layer "F.Cu")
		(net "M_E_CPU1_SB_DQ<1>")
	)
	(segment
		(start 161.245804 -230.527352)
		(end 161.057844 -230.715312)
		(width 0.20066)
		(layer "F.Cu")
		(net "M_E_CPU1_SB_DQ<1>")
	)
	(segment
		(start 163.917376 -230.041704)
		(end 161.728658 -230.041704)
		(width 0.1016)
		(layer "F.Cu")
		(net "M_E_CPU1_SB_DQ<1>")
	)
	(segment
		(start 161.245804 -230.159814)
		(end 161.245804 -230.527352)
		(width 0.20066)
		(layer "F.Cu")
		(net "M_E_CPU1_SB_DQ<1>")
	)
	(segment
		(start 160.58261 -230.715312)
		(end 160.333944 -230.466646)
		(width 0.20066)
		(layer "F.Cu")
		(net "M_E_CPU1_SB_DQ<1>")
	)
	(segment
		(start 133.255766 -236.319568)
		(end 133.255766 -235.783882)
		(width 0.20066)
		(layer "F.Cu")
		(net "M_E_CPU1_SB_DQ<1>")
	)
	(segment
		(start 161.708592 -230.041704)
		(end 161.363914 -230.041704)
		(width 0.20066)
		(layer "F.Cu")
		(net "M_E_CPU1_SB_DQ<1>")
	)
	(segment
		(start 139.77239 -236.27715)
		(end 139.564618 -236.27715)
		(width 0.088646)
		(layer "In2.Cu")
		(net "M_E_CPU1_SB_DQ<1>")
	)
	(segment
		(start 155.109926 -231.361488)
		(end 155.109926 -231.734868)
		(width 0.18288)
		(layer "In2.Cu")
		(net "M_E_CPU1_SB_DQ<1>")
	)
	(segment
		(start 156.362908 -230.719884)
		(end 156.362908 -230.99268)
		(width 0.18288)
		(layer "In2.Cu")
		(net "M_E_CPU1_SB_DQ<1>")
	)
	(segment
		(start 135.79221 -236.273594)
		(end 135.789924 -236.271816)
		(width 0.088646)
		(layer "In2.Cu")
		(net "M_E_CPU1_SB_DQ<1>")
	)
	(segment
		(start 152.494742 -233.970576)
		(end 152.494742 -234.502452)
		(width 0.18288)
		(layer "In2.Cu")
		(net "M_E_CPU1_SB_DQ<1>")
	)
	(segment
		(start 155.695396 -231.048814)
		(end 155.4226 -231.048814)
		(width 0.18288)
		(layer "In2.Cu")
		(net "M_E_CPU1_SB_DQ<1>")
	)
	(segment
		(start 155.066746 -232.687622)
		(end 154.565604 -232.18648)
		(width 0.18288)
		(layer "In2.Cu")
		(net "M_E_CPU1_SB_DQ<1>")
	)
	(segment
		(start 156.362908 -230.99268)
		(end 156.13761 -231.217978)
		(width 0.18288)
		(layer "In2.Cu")
		(net "M_E_CPU1_SB_DQ<1>")
	)
	(segment
		(start 157.682946 -230.466646)
		(end 157.36316 -230.14686)
		(width 0.18288)
		(layer "In2.Cu")
		(net "M_E_CPU1_SB_DQ<1>")
	)
	(segment
		(start 155.56484 -232.189782)
		(end 155.56484 -232.462324)
		(width 0.18288)
		(layer "In2.Cu")
		(net "M_E_CPU1_SB_DQ<1>")
	)
	(segment
		(start 152.494742 -234.502452)
		(end 152.262586 -234.734608)
		(width 0.18288)
		(layer "In2.Cu")
		(net "M_E_CPU1_SB_DQ<1>")
	)
	(segment
		(start 156.75864 -229.712774)
		(end 156.19349 -230.277924)
		(width 0.18288)
		(layer "In2.Cu")
		(net "M_E_CPU1_SB_DQ<1>")
	)
	(segment
		(start 155.339542 -232.687622)
		(end 155.066746 -232.687622)
		(width 0.18288)
		(layer "In2.Cu")
		(net "M_E_CPU1_SB_DQ<1>")
	)
	(segment
		(start 136.357614 -236.273594)
		(end 136.342882 -236.28223)
		(width 0.088646)
		(layer "In2.Cu")
		(net "M_E_CPU1_SB_DQ<1>")
	)
	(segment
		(start 155.109926 -231.734868)
		(end 155.56484 -232.189782)
		(width 0.18288)
		(layer "In2.Cu")
		(net "M_E_CPU1_SB_DQ<1>")
	)
	(segment
		(start 139.853162 -236.196378)
		(end 139.77239 -236.27715)
		(width 0.088646)
		(layer "In2.Cu")
		(net "M_E_CPU1_SB_DQ<1>")
	)
	(segment
		(start 153.49093 -232.974388)
		(end 153.49093 -233.506264)
		(width 0.18288)
		(layer "In2.Cu")
		(net "M_E_CPU1_SB_DQ<1>")
	)
	(segment
		(start 139.177014 -236.273594)
		(end 139.162282 -236.28223)
		(width 0.088646)
		(layer "In2.Cu")
		(net "M_E_CPU1_SB_DQ<1>")
	)
	(segment
		(start 155.56484 -232.462324)
		(end 155.339542 -232.687622)
		(width 0.18288)
		(layer "In2.Cu")
		(net "M_E_CPU1_SB_DQ<1>")
	)
	(segment
		(start 133.912864 -236.27334)
		(end 133.82625 -236.223048)
		(width 0.088646)
		(layer "In2.Cu")
		(net "M_E_CPU1_SB_DQ<1>")
	)
	(segment
		(start 149.016974 -236.196378)
		(end 140.264896 -236.196378)
		(width 0.18288)
		(layer "In2.Cu")
		(net "M_E_CPU1_SB_DQ<1>")
	)
	(segment
		(start 156.13761 -231.217978)
		(end 155.864814 -231.217978)
		(width 0.18288)
		(layer "In2.Cu")
		(net "M_E_CPU1_SB_DQ<1>")
	)
	(segment
		(start 140.264896 -236.196378)
		(end 139.853162 -236.196378)
		(width 0.088646)
		(layer "In2.Cu")
		(net "M_E_CPU1_SB_DQ<1>")
	)
	(segment
		(start 151.305514 -235.518198)
		(end 150.654512 -235.518198)
		(width 0.18288)
		(layer "In2.Cu")
		(net "M_E_CPU1_SB_DQ<1>")
	)
	(segment
		(start 137.297414 -236.273594)
		(end 137.282682 -236.28223)
		(width 0.088646)
		(layer "In2.Cu")
		(net "M_E_CPU1_SB_DQ<1>")
	)
	(segment
		(start 151.498554 -234.966764)
		(end 151.498554 -235.325158)
		(width 0.18288)
		(layer "In2.Cu")
		(net "M_E_CPU1_SB_DQ<1>")
	)
	(segment
		(start 154.278838 -232.18648)
		(end 153.49093 -232.974388)
		(width 0.18288)
		(layer "In2.Cu")
		(net "M_E_CPU1_SB_DQ<1>")
	)
	(segment
		(start 157.36316 -229.946454)
		(end 157.12948 -229.712774)
		(width 0.18288)
		(layer "In2.Cu")
		(net "M_E_CPU1_SB_DQ<1>")
	)
	(segment
		(start 157.12948 -229.712774)
		(end 156.75864 -229.712774)
		(width 0.18288)
		(layer "In2.Cu")
		(net "M_E_CPU1_SB_DQ<1>")
	)
	(segment
		(start 152.262586 -234.734608)
		(end 151.73071 -234.734608)
		(width 0.18288)
		(layer "In2.Cu")
		(net "M_E_CPU1_SB_DQ<1>")
	)
	(segment
		(start 151.498554 -235.325158)
		(end 151.305514 -235.518198)
		(width 0.18288)
		(layer "In2.Cu")
		(net "M_E_CPU1_SB_DQ<1>")
	)
	(segment
		(start 150.654512 -235.518198)
		(end 149.016974 -236.196378)
		(width 0.18288)
		(layer "In2.Cu")
		(net "M_E_CPU1_SB_DQ<1>")
	)
	(segment
		(start 155.864814 -231.217978)
		(end 155.695396 -231.048814)
		(width 0.18288)
		(layer "In2.Cu")
		(net "M_E_CPU1_SB_DQ<1>")
	)
	(segment
		(start 153.49093 -233.506264)
		(end 153.258774 -233.73842)
		(width 0.18288)
		(layer "In2.Cu")
		(net "M_E_CPU1_SB_DQ<1>")
	)
	(segment
		(start 154.565604 -232.18648)
		(end 154.278838 -232.18648)
		(width 0.18288)
		(layer "In2.Cu")
		(net "M_E_CPU1_SB_DQ<1>")
	)
	(segment
		(start 152.726898 -233.73842)
		(end 152.494742 -233.970576)
		(width 0.18288)
		(layer "In2.Cu")
		(net "M_E_CPU1_SB_DQ<1>")
	)
	(segment
		(start 151.73071 -234.734608)
		(end 151.498554 -234.966764)
		(width 0.18288)
		(layer "In2.Cu")
		(net "M_E_CPU1_SB_DQ<1>")
	)
	(segment
		(start 134.852664 -236.27334)
		(end 134.848854 -236.271308)
		(width 0.088646)
		(layer "In2.Cu")
		(net "M_E_CPU1_SB_DQ<1>")
	)
	(segment
		(start 134.86003 -236.277658)
		(end 134.852664 -236.27334)
		(width 0.088646)
		(layer "In2.Cu")
		(net "M_E_CPU1_SB_DQ<1>")
	)
	(segment
		(start 138.237214 -236.273594)
		(end 138.222482 -236.28223)
		(width 0.088646)
		(layer "In2.Cu")
		(net "M_E_CPU1_SB_DQ<1>")
	)
	(segment
		(start 155.4226 -231.048814)
		(end 155.109926 -231.361488)
		(width 0.18288)
		(layer "In2.Cu")
		(net "M_E_CPU1_SB_DQ<1>")
	)
	(segment
		(start 157.36316 -230.14686)
		(end 157.36316 -229.946454)
		(width 0.18288)
		(layer "In2.Cu")
		(net "M_E_CPU1_SB_DQ<1>")
	)
	(segment
		(start 133.25602 -235.784136)
		(end 133.255766 -235.783882)
		(width 0.088646)
		(layer "In2.Cu")
		(net "M_E_CPU1_SB_DQ<1>")
	)
	(segment
		(start 156.19349 -230.55072)
		(end 156.362908 -230.719884)
		(width 0.18288)
		(layer "In2.Cu")
		(net "M_E_CPU1_SB_DQ<1>")
	)
	(segment
		(start 156.19349 -230.277924)
		(end 156.19349 -230.55072)
		(width 0.18288)
		(layer "In2.Cu")
		(net "M_E_CPU1_SB_DQ<1>")
	)
	(segment
		(start 153.258774 -233.73842)
		(end 152.726898 -233.73842)
		(width 0.18288)
		(layer "In2.Cu")
		(net "M_E_CPU1_SB_DQ<1>")
	)
	(arc
		(start 133.82625 -236.223048)
		(mid 133.526921 -236.022059)
		(end 133.25602 -235.784136)
		(width 0.088646)
		(layer "In2.Cu")
		(net "M_E_CPU1_SB_DQ<1>")
	)
	(arc
		(start 135.417814 -236.27334)
		(mid 135.139491 -236.349099)
		(end 134.86003 -236.277658)
		(width 0.088646)
		(layer "In2.Cu")
		(net "M_E_CPU1_SB_DQ<1>")
	)
	(arc
		(start 134.478014 -236.27334)
		(mid 134.195456 -236.348989)
		(end 133.912864 -236.27334)
		(width 0.088646)
		(layer "In2.Cu")
		(net "M_E_CPU1_SB_DQ<1>")
	)
	(arc
		(start 139.162282 -236.28223)
		(mid 138.885841 -236.349396)
		(end 138.61161 -236.273594)
		(width 0.088646)
		(layer "In2.Cu")
		(net "M_E_CPU1_SB_DQ<1>")
	)
	(arc
		(start 135.789924 -236.271816)
		(mid 135.603675 -236.223171)
		(end 135.417814 -236.27334)
		(width 0.088646)
		(layer "In2.Cu")
		(net "M_E_CPU1_SB_DQ<1>")
	)
	(arc
		(start 134.848854 -236.271308)
		(mid 134.663164 -236.22323)
		(end 134.478014 -236.27334)
		(width 0.088646)
		(layer "In2.Cu")
		(net "M_E_CPU1_SB_DQ<1>")
	)
	(arc
		(start 139.564618 -236.27715)
		(mid 139.557777 -236.276249)
		(end 139.55141 -236.273594)
		(width 0.088646)
		(layer "In2.Cu")
		(net "M_E_CPU1_SB_DQ<1>")
	)
	(arc
		(start 138.222482 -236.28223)
		(mid 137.946041 -236.349396)
		(end 137.67181 -236.273594)
		(width 0.088646)
		(layer "In2.Cu")
		(net "M_E_CPU1_SB_DQ<1>")
	)
	(arc
		(start 138.61161 -236.273594)
		(mid 138.424412 -236.223451)
		(end 138.237214 -236.273594)
		(width 0.088646)
		(layer "In2.Cu")
		(net "M_E_CPU1_SB_DQ<1>")
	)
	(arc
		(start 137.282682 -236.28223)
		(mid 137.006241 -236.349396)
		(end 136.73201 -236.273594)
		(width 0.088646)
		(layer "In2.Cu")
		(net "M_E_CPU1_SB_DQ<1>")
	)
	(arc
		(start 136.73201 -236.273594)
		(mid 136.544812 -236.223451)
		(end 136.357614 -236.273594)
		(width 0.088646)
		(layer "In2.Cu")
		(net "M_E_CPU1_SB_DQ<1>")
	)
	(arc
		(start 139.55141 -236.273594)
		(mid 139.364212 -236.223451)
		(end 139.177014 -236.273594)
		(width 0.088646)
		(layer "In2.Cu")
		(net "M_E_CPU1_SB_DQ<1>")
	)
	(arc
		(start 137.67181 -236.273594)
		(mid 137.484612 -236.223451)
		(end 137.297414 -236.273594)
		(width 0.088646)
		(layer "In2.Cu")
		(net "M_E_CPU1_SB_DQ<1>")
	)
	(arc
		(start 136.342882 -236.28223)
		(mid 136.066441 -236.349396)
		(end 135.79221 -236.273594)
		(width 0.088646)
		(layer "In2.Cu")
		(net "M_E_CPU1_SB_DQ<1>")
	)
	(segment
		(start 165.040564 -211.352384)
		(end 164.604954 -210.916774)
		(width 0.20066)
		(layer "F.Cu")
		(net "M_E_CPU1_SB_DQ<19>")
	)
	(segment
		(start 160.513014 -210.622388)
		(end 160.859978 -210.622388)
		(width 0.20066)
		(layer "F.Cu")
		(net "M_E_CPU1_SB_DQ<19>")
	)
	(segment
		(start 148.282406 -216.18321)
		(end 148.809202 -216.710006)
		(width 0.20066)
		(layer "F.Cu")
		(net "M_E_CPU1_SB_DQ<19>")
	)
	(segment
		(start 168.265348 -210.86445)
		(end 168.265348 -211.161376)
		(width 0.20066)
		(layer "F.Cu")
		(net "M_E_CPU1_SB_DQ<19>")
	)
	(segment
		(start 168.069006 -211.357718)
		(end 167.367458 -211.357718)
		(width 0.20066)
		(layer "F.Cu")
		(net "M_E_CPU1_SB_DQ<19>")
	)
	(segment
		(start 160.385252 -211.089748)
		(end 160.385252 -210.75015)
		(width 0.20066)
		(layer "F.Cu")
		(net "M_E_CPU1_SB_DQ<19>")
	)
	(segment
		(start 168.464992 -210.664806)
		(end 168.265348 -210.86445)
		(width 0.20066)
		(layer "F.Cu")
		(net "M_E_CPU1_SB_DQ<19>")
	)
	(segment
		(start 149.294342 -216.508838)
		(end 149.294342 -216.224866)
		(width 0.20066)
		(layer "F.Cu")
		(net "M_E_CPU1_SB_DQ<19>")
	)
	(segment
		(start 165.369494 -211.352384)
		(end 165.335458 -211.352384)
		(width 0.101854)
		(layer "F.Cu")
		(net "M_E_CPU1_SB_DQ<19>")
	)
	(segment
		(start 160.118298 -211.356702)
		(end 160.385252 -211.089748)
		(width 0.20066)
		(layer "F.Cu")
		(net "M_E_CPU1_SB_DQ<19>")
	)
	(segment
		(start 148.767546 -215.414098)
		(end 153.387552 -210.794092)
		(width 0.20066)
		(layer "F.Cu")
		(net "M_E_CPU1_SB_DQ<19>")
	)
	(segment
		(start 156.759656 -210.794092)
		(end 157.314392 -211.348828)
		(width 0.20066)
		(layer "F.Cu")
		(net "M_E_CPU1_SB_DQ<19>")
	)
	(segment
		(start 165.335458 -211.352384)
		(end 165.040564 -211.352384)
		(width 0.20066)
		(layer "F.Cu")
		(net "M_E_CPU1_SB_DQ<19>")
	)
	(segment
		(start 159.800036 -211.341716)
		(end 159.815022 -211.356702)
		(width 0.1016)
		(layer "F.Cu")
		(net "M_E_CPU1_SB_DQ<19>")
	)
	(segment
		(start 159.815022 -211.356702)
		(end 159.823658 -211.356702)
		(width 0.1016)
		(layer "F.Cu")
		(net "M_E_CPU1_SB_DQ<19>")
	)
	(segment
		(start 148.767546 -215.69807)
		(end 148.767546 -215.414098)
		(width 0.20066)
		(layer "F.Cu")
		(net "M_E_CPU1_SB_DQ<19>")
	)
	(segment
		(start 157.314392 -211.348828)
		(end 157.791658 -211.348828)
		(width 0.20066)
		(layer "F.Cu")
		(net "M_E_CPU1_SB_DQ<19>")
	)
	(segment
		(start 149.093174 -216.710006)
		(end 149.294342 -216.508838)
		(width 0.20066)
		(layer "F.Cu")
		(net "M_E_CPU1_SB_DQ<19>")
	)
	(segment
		(start 138.451844 -233.905298)
		(end 140.341096 -233.905298)
		(width 0.088646)
		(layer "F.Cu")
		(net "M_E_CPU1_SB_DQ<19>")
	)
	(segment
		(start 159.823658 -211.356702)
		(end 160.118298 -211.356702)
		(width 0.20066)
		(layer "F.Cu")
		(net "M_E_CPU1_SB_DQ<19>")
	)
	(segment
		(start 169.135552 -210.916774)
		(end 168.883584 -210.664806)
		(width 0.20066)
		(layer "F.Cu")
		(net "M_E_CPU1_SB_DQ<19>")
	)
	(segment
		(start 170.457114 -210.916774)
		(end 169.135552 -210.916774)
		(width 0.20066)
		(layer "F.Cu")
		(net "M_E_CPU1_SB_DQ<19>")
	)
	(segment
		(start 161.154364 -210.916774)
		(end 162.913314 -210.916774)
		(width 0.20066)
		(layer "F.Cu")
		(net "M_E_CPU1_SB_DQ<19>")
	)
	(segment
		(start 146.884898 -217.296746)
		(end 147.998434 -216.18321)
		(width 0.20066)
		(layer "F.Cu")
		(net "M_E_CPU1_SB_DQ<19>")
	)
	(segment
		(start 146.057112 -228.626924)
		(end 146.057112 -218.124532)
		(width 0.1016)
		(layer "F.Cu")
		(net "M_E_CPU1_SB_DQ<19>")
	)
	(segment
		(start 168.883584 -210.664806)
		(end 168.464992 -210.664806)
		(width 0.20066)
		(layer "F.Cu")
		(net "M_E_CPU1_SB_DQ<19>")
	)
	(segment
		(start 153.387552 -210.794092)
		(end 156.759656 -210.794092)
		(width 0.20066)
		(layer "F.Cu")
		(net "M_E_CPU1_SB_DQ<19>")
	)
	(segment
		(start 167.367458 -211.357718)
		(end 167.351456 -211.341716)
		(width 0.1016)
		(layer "F.Cu")
		(net "M_E_CPU1_SB_DQ<19>")
	)
	(segment
		(start 165.380162 -211.341716)
		(end 165.369494 -211.352384)
		(width 0.101854)
		(layer "F.Cu")
		(net "M_E_CPU1_SB_DQ<19>")
	)
	(segment
		(start 167.351456 -211.341716)
		(end 165.380162 -211.341716)
		(width 0.1016)
		(layer "F.Cu")
		(net "M_E_CPU1_SB_DQ<19>")
	)
	(segment
		(start 160.385252 -210.75015)
		(end 160.513014 -210.622388)
		(width 0.20066)
		(layer "F.Cu")
		(net "M_E_CPU1_SB_DQ<19>")
	)
	(segment
		(start 149.294342 -216.224866)
		(end 148.767546 -215.69807)
		(width 0.20066)
		(layer "F.Cu")
		(net "M_E_CPU1_SB_DQ<19>")
	)
	(segment
		(start 138.424666 -233.87812)
		(end 138.451844 -233.905298)
		(width 0.088646)
		(layer "F.Cu")
		(net "M_E_CPU1_SB_DQ<19>")
	)
	(segment
		(start 164.604954 -210.916774)
		(end 162.913314 -210.916774)
		(width 0.20066)
		(layer "F.Cu")
		(net "M_E_CPU1_SB_DQ<19>")
	)
	(segment
		(start 168.265348 -211.161376)
		(end 168.069006 -211.357718)
		(width 0.20066)
		(layer "F.Cu")
		(net "M_E_CPU1_SB_DQ<19>")
	)
	(segment
		(start 157.791658 -211.348828)
		(end 157.79877 -211.341716)
		(width 0.101854)
		(layer "F.Cu")
		(net "M_E_CPU1_SB_DQ<19>")
	)
	(segment
		(start 160.859978 -210.622388)
		(end 161.154364 -210.916774)
		(width 0.20066)
		(layer "F.Cu")
		(net "M_E_CPU1_SB_DQ<19>")
	)
	(segment
		(start 157.79877 -211.341716)
		(end 159.800036 -211.341716)
		(width 0.1016)
		(layer "F.Cu")
		(net "M_E_CPU1_SB_DQ<19>")
	)
	(segment
		(start 148.809202 -216.710006)
		(end 149.093174 -216.710006)
		(width 0.20066)
		(layer "F.Cu")
		(net "M_E_CPU1_SB_DQ<19>")
	)
	(segment
		(start 140.778738 -233.905298)
		(end 146.057112 -228.626924)
		(width 0.1016)
		(layer "F.Cu")
		(net "M_E_CPU1_SB_DQ<19>")
	)
	(segment
		(start 147.998434 -216.18321)
		(end 148.282406 -216.18321)
		(width 0.20066)
		(layer "F.Cu")
		(net "M_E_CPU1_SB_DQ<19>")
	)
	(segment
		(start 140.341096 -233.905298)
		(end 140.778738 -233.905298)
		(width 0.1016)
		(layer "F.Cu")
		(net "M_E_CPU1_SB_DQ<19>")
	)
	(segment
		(start 146.057112 -218.124532)
		(end 146.884898 -217.296746)
		(width 0.1016)
		(layer "F.Cu")
		(net "M_E_CPU1_SB_DQ<19>")
	)
	(segment
		(start 160.794192 -212.141562)
		(end 161.068004 -212.141562)
		(width 0.20066)
		(layer "F.Cu")
		(net "M_E_CPU1_SB_DQ<18>")
	)
	(segment
		(start 141.023086 -234.523534)
		(end 146.666712 -228.879908)
		(width 0.1016)
		(layer "F.Cu")
		(net "M_E_CPU1_SB_DQ<18>")
	)
	(segment
		(start 169.135552 -212.616796)
		(end 168.79189 -212.273134)
		(width 0.20066)
		(layer "F.Cu")
		(net "M_E_CPU1_SB_DQ<18>")
	)
	(segment
		(start 164.604954 -212.616796)
		(end 162.913314 -212.616796)
		(width 0.20066)
		(layer "F.Cu")
		(net "M_E_CPU1_SB_DQ<18>")
	)
	(segment
		(start 161.068004 -212.141562)
		(end 161.352992 -212.42655)
		(width 0.20066)
		(layer "F.Cu")
		(net "M_E_CPU1_SB_DQ<18>")
	)
	(segment
		(start 137.954766 -234.69219)
		(end 138.24585 -234.69219)
		(width 0.088646)
		(layer "F.Cu")
		(net "M_E_CPU1_SB_DQ<18>")
	)
	(segment
		(start 159.804862 -213.04758)
		(end 159.823658 -213.04758)
		(width 0.1016)
		(layer "F.Cu")
		(net "M_E_CPU1_SB_DQ<18>")
	)
	(segment
		(start 138.24585 -234.69219)
		(end 138.38301 -234.55503)
		(width 0.088646)
		(layer "F.Cu")
		(net "M_E_CPU1_SB_DQ<18>")
	)
	(segment
		(start 153.522426 -212.506306)
		(end 155.934664 -212.506306)
		(width 0.20066)
		(layer "F.Cu")
		(net "M_E_CPU1_SB_DQ<18>")
	)
	(segment
		(start 162.422078 -212.616796)
		(end 162.913314 -212.616796)
		(width 0.20066)
		(layer "F.Cu")
		(net "M_E_CPU1_SB_DQ<18>")
	)
	(segment
		(start 168.79189 -212.273134)
		(end 168.466008 -212.273134)
		(width 0.20066)
		(layer "F.Cu")
		(net "M_E_CPU1_SB_DQ<18>")
	)
	(segment
		(start 165.369494 -213.052406)
		(end 165.335458 -213.052406)
		(width 0.101854)
		(layer "F.Cu")
		(net "M_E_CPU1_SB_DQ<18>")
	)
	(segment
		(start 165.380162 -213.041738)
		(end 165.369494 -213.052406)
		(width 0.101854)
		(layer "F.Cu")
		(net "M_E_CPU1_SB_DQ<18>")
	)
	(segment
		(start 146.666712 -219.888054)
		(end 146.867372 -219.687394)
		(width 0.1016)
		(layer "F.Cu")
		(net "M_E_CPU1_SB_DQ<18>")
	)
	(segment
		(start 162.030918 -212.225636)
		(end 162.422078 -212.616796)
		(width 0.20066)
		(layer "F.Cu")
		(net "M_E_CPU1_SB_DQ<18>")
	)
	(segment
		(start 167.367458 -213.05774)
		(end 167.351456 -213.041738)
		(width 0.1016)
		(layer "F.Cu")
		(net "M_E_CPU1_SB_DQ<18>")
	)
	(segment
		(start 155.934664 -212.506306)
		(end 156.49067 -213.062312)
		(width 0.20066)
		(layer "F.Cu")
		(net "M_E_CPU1_SB_DQ<18>")
	)
	(segment
		(start 165.335458 -213.052406)
		(end 165.040564 -213.052406)
		(width 0.20066)
		(layer "F.Cu")
		(net "M_E_CPU1_SB_DQ<18>")
	)
	(segment
		(start 160.242758 -213.230714)
		(end 160.455356 -213.230714)
		(width 0.20066)
		(layer "F.Cu")
		(net "M_E_CPU1_SB_DQ<18>")
	)
	(segment
		(start 160.059624 -213.04758)
		(end 160.242758 -213.230714)
		(width 0.20066)
		(layer "F.Cu")
		(net "M_E_CPU1_SB_DQ<18>")
	)
	(segment
		(start 151.552148 -216.197688)
		(end 150.971758 -215.617298)
		(width 0.20066)
		(layer "F.Cu")
		(net "M_E_CPU1_SB_DQ<18>")
	)
	(segment
		(start 147.046442 -219.687394)
		(end 148.346414 -219.687394)
		(width 0.20066)
		(layer "F.Cu")
		(net "M_E_CPU1_SB_DQ<18>")
	)
	(segment
		(start 161.602928 -212.42655)
		(end 161.803842 -212.225636)
		(width 0.20066)
		(layer "F.Cu")
		(net "M_E_CPU1_SB_DQ<18>")
	)
	(segment
		(start 157.817058 -213.041738)
		(end 159.79902 -213.041738)
		(width 0.1016)
		(layer "F.Cu")
		(net "M_E_CPU1_SB_DQ<18>")
	)
	(segment
		(start 165.040564 -213.052406)
		(end 164.604954 -212.616796)
		(width 0.20066)
		(layer "F.Cu")
		(net "M_E_CPU1_SB_DQ<18>")
	)
	(segment
		(start 160.455356 -213.230714)
		(end 160.600644 -213.085426)
		(width 0.20066)
		(layer "F.Cu")
		(net "M_E_CPU1_SB_DQ<18>")
	)
	(segment
		(start 139.659614 -234.305094)
		(end 139.878054 -234.523534)
		(width 0.088646)
		(layer "F.Cu")
		(net "M_E_CPU1_SB_DQ<18>")
	)
	(segment
		(start 160.600644 -213.085426)
		(end 160.600644 -212.33511)
		(width 0.20066)
		(layer "F.Cu")
		(net "M_E_CPU1_SB_DQ<18>")
	)
	(segment
		(start 151.552148 -216.48166)
		(end 151.552148 -216.197688)
		(width 0.20066)
		(layer "F.Cu")
		(net "M_E_CPU1_SB_DQ<18>")
	)
	(segment
		(start 168.064434 -213.05774)
		(end 167.367458 -213.05774)
		(width 0.20066)
		(layer "F.Cu")
		(net "M_E_CPU1_SB_DQ<18>")
	)
	(segment
		(start 168.466008 -212.273134)
		(end 168.265348 -212.473794)
		(width 0.20066)
		(layer "F.Cu")
		(net "M_E_CPU1_SB_DQ<18>")
	)
	(segment
		(start 168.265348 -212.473794)
		(end 168.265348 -212.856826)
		(width 0.20066)
		(layer "F.Cu")
		(net "M_E_CPU1_SB_DQ<18>")
	)
	(segment
		(start 167.351456 -213.041738)
		(end 165.380162 -213.041738)
		(width 0.1016)
		(layer "F.Cu")
		(net "M_E_CPU1_SB_DQ<18>")
	)
	(segment
		(start 138.815826 -234.305094)
		(end 139.659614 -234.305094)
		(width 0.088646)
		(layer "F.Cu")
		(net "M_E_CPU1_SB_DQ<18>")
	)
	(segment
		(start 138.38301 -234.55503)
		(end 138.815826 -234.305094)
		(width 0.088646)
		(layer "F.Cu")
		(net "M_E_CPU1_SB_DQ<18>")
	)
	(segment
		(start 150.971758 -215.056974)
		(end 153.522426 -212.506306)
		(width 0.20066)
		(layer "F.Cu")
		(net "M_E_CPU1_SB_DQ<18>")
	)
	(segment
		(start 146.867372 -219.687394)
		(end 147.046442 -219.687394)
		(width 0.1016)
		(layer "F.Cu")
		(net "M_E_CPU1_SB_DQ<18>")
	)
	(segment
		(start 159.823658 -213.04758)
		(end 160.059624 -213.04758)
		(width 0.20066)
		(layer "F.Cu")
		(net "M_E_CPU1_SB_DQ<18>")
	)
	(segment
		(start 140.341096 -234.523534)
		(end 141.023086 -234.523534)
		(width 0.1016)
		(layer "F.Cu")
		(net "M_E_CPU1_SB_DQ<18>")
	)
	(segment
		(start 159.79902 -213.041738)
		(end 159.804862 -213.04758)
		(width 0.1016)
		(layer "F.Cu")
		(net "M_E_CPU1_SB_DQ<18>")
	)
	(segment
		(start 146.666712 -228.879908)
		(end 146.666712 -219.888054)
		(width 0.1016)
		(layer "F.Cu")
		(net "M_E_CPU1_SB_DQ<18>")
	)
	(segment
		(start 157.796484 -213.062312)
		(end 157.817058 -213.041738)
		(width 0.1016)
		(layer "F.Cu")
		(net "M_E_CPU1_SB_DQ<18>")
	)
	(segment
		(start 150.971758 -215.617298)
		(end 150.971758 -215.056974)
		(width 0.20066)
		(layer "F.Cu")
		(net "M_E_CPU1_SB_DQ<18>")
	)
	(segment
		(start 157.791658 -213.062312)
		(end 157.796484 -213.062312)
		(width 0.101854)
		(layer "F.Cu")
		(net "M_E_CPU1_SB_DQ<18>")
	)
	(segment
		(start 148.346414 -219.687394)
		(end 151.552148 -216.48166)
		(width 0.20066)
		(layer "F.Cu")
		(net "M_E_CPU1_SB_DQ<18>")
	)
	(segment
		(start 156.49067 -213.062312)
		(end 157.791658 -213.062312)
		(width 0.20066)
		(layer "F.Cu")
		(net "M_E_CPU1_SB_DQ<18>")
	)
	(segment
		(start 161.803842 -212.225636)
		(end 162.030918 -212.225636)
		(width 0.20066)
		(layer "F.Cu")
		(net "M_E_CPU1_SB_DQ<18>")
	)
	(segment
		(start 160.600644 -212.33511)
		(end 160.794192 -212.141562)
		(width 0.20066)
		(layer "F.Cu")
		(net "M_E_CPU1_SB_DQ<18>")
	)
	(segment
		(start 139.878054 -234.523534)
		(end 140.341096 -234.523534)
		(width 0.088646)
		(layer "F.Cu")
		(net "M_E_CPU1_SB_DQ<18>")
	)
	(segment
		(start 170.457114 -212.616796)
		(end 169.135552 -212.616796)
		(width 0.20066)
		(layer "F.Cu")
		(net "M_E_CPU1_SB_DQ<18>")
	)
	(segment
		(start 168.265348 -212.856826)
		(end 168.064434 -213.05774)
		(width 0.20066)
		(layer "F.Cu")
		(net "M_E_CPU1_SB_DQ<18>")
	)
	(segment
		(start 161.352992 -212.42655)
		(end 161.602928 -212.42655)
		(width 0.20066)
		(layer "F.Cu")
		(net "M_E_CPU1_SB_DQ<18>")
	)
	(segment
		(start 140.90523 -234.210098)
		(end 146.361912 -228.753416)
		(width 0.1016)
		(layer "F.Cu")
		(net "M_E_CPU1_SB_DQ<17>")
	)
	(segment
		(start 160.371282 -211.690966)
		(end 159.914844 -212.147404)
		(width 0.20066)
		(layer "F.Cu")
		(net "M_E_CPU1_SB_DQ<17>")
	)
	(segment
		(start 136.93648 -234.028996)
		(end 137.034016 -234.028996)
		(width 0.088646)
		(layer "F.Cu")
		(net "M_E_CPU1_SB_DQ<17>")
	)
	(segment
		(start 163.908994 -211.341716)
		(end 161.962846 -211.341716)
		(width 0.1016)
		(layer "F.Cu")
		(net "M_E_CPU1_SB_DQ<17>")
	)
	(segment
		(start 139.859004 -234.209844)
		(end 140.045186 -234.209844)
		(width 0.088646)
		(layer "F.Cu")
		(net "M_E_CPU1_SB_DQ<17>")
	)
	(segment
		(start 148.373846 -217.713306)
		(end 147.934172 -218.15298)
		(width 0.20066)
		(layer "F.Cu")
		(net "M_E_CPU1_SB_DQ<17>")
	)
	(segment
		(start 136.545066 -233.87812)
		(end 136.453626 -234.0991)
		(width 0.088646)
		(layer "F.Cu")
		(net "M_E_CPU1_SB_DQ<17>")
	)
	(segment
		(start 137.291826 -234.286806)
		(end 138.301222 -234.286806)
		(width 0.088646)
		(layer "F.Cu")
		(net "M_E_CPU1_SB_DQ<17>")
	)
	(segment
		(start 136.542272 -234.453684)
		(end 136.667748 -234.453684)
		(width 0.088646)
		(layer "F.Cu")
		(net "M_E_CPU1_SB_DQ<17>")
	)
	(segment
		(start 161.947352 -211.326222)
		(end 161.896552 -211.326222)
		(width 0.1016)
		(layer "F.Cu")
		(net "M_E_CPU1_SB_DQ<17>")
	)
	(segment
		(start 147.934172 -218.15298)
		(end 147.934172 -218.436952)
		(width 0.20066)
		(layer "F.Cu")
		(net "M_E_CPU1_SB_DQ<17>")
	)
	(segment
		(start 159.730186 -212.147404)
		(end 159.34944 -211.766658)
		(width 0.20066)
		(layer "F.Cu")
		(net "M_E_CPU1_SB_DQ<17>")
	)
	(segment
		(start 161.962846 -211.341716)
		(end 161.947352 -211.326222)
		(width 0.1016)
		(layer "F.Cu")
		(net "M_E_CPU1_SB_DQ<17>")
	)
	(segment
		(start 150.506176 -216.213944)
		(end 150.024084 -215.731852)
		(width 0.20066)
		(layer "F.Cu")
		(net "M_E_CPU1_SB_DQ<17>")
	)
	(segment
		(start 163.923726 -211.326984)
		(end 163.908994 -211.341716)
		(width 0.1016)
		(layer "F.Cu")
		(net "M_E_CPU1_SB_DQ<17>")
	)
	(segment
		(start 148.419312 -218.63812)
		(end 150.506176 -216.551256)
		(width 0.20066)
		(layer "F.Cu")
		(net "M_E_CPU1_SB_DQ<17>")
	)
	(segment
		(start 140.04544 -234.210098)
		(end 140.341096 -234.210098)
		(width 0.088646)
		(layer "F.Cu")
		(net "M_E_CPU1_SB_DQ<17>")
	)
	(segment
		(start 165.348158 -211.95411)
		(end 164.974778 -211.95411)
		(width 0.20066)
		(layer "F.Cu")
		(net "M_E_CPU1_SB_DQ<17>")
	)
	(segment
		(start 165.53561 -211.766658)
		(end 165.348158 -211.95411)
		(width 0.20066)
		(layer "F.Cu")
		(net "M_E_CPU1_SB_DQ<17>")
	)
	(segment
		(start 150.024084 -215.092788)
		(end 153.512774 -211.604098)
		(width 0.20066)
		(layer "F.Cu")
		(net "M_E_CPU1_SB_DQ<17>")
	)
	(segment
		(start 147.888706 -217.228166)
		(end 148.172678 -217.228166)
		(width 0.20066)
		(layer "F.Cu")
		(net "M_E_CPU1_SB_DQ<17>")
	)
	(segment
		(start 146.361912 -228.753416)
		(end 146.361912 -218.75496)
		(width 0.1016)
		(layer "F.Cu")
		(net "M_E_CPU1_SB_DQ<17>")
	)
	(segment
		(start 148.172678 -217.228166)
		(end 148.373846 -217.429334)
		(width 0.20066)
		(layer "F.Cu")
		(net "M_E_CPU1_SB_DQ<17>")
	)
	(segment
		(start 161.470594 -211.326222)
		(end 161.10585 -211.690966)
		(width 0.20066)
		(layer "F.Cu")
		(net "M_E_CPU1_SB_DQ<17>")
	)
	(segment
		(start 157.50667 -212.163152)
		(end 157.903164 -211.766658)
		(width 0.20066)
		(layer "F.Cu")
		(net "M_E_CPU1_SB_DQ<17>")
	)
	(segment
		(start 156.329888 -211.604098)
		(end 156.888942 -212.163152)
		(width 0.20066)
		(layer "F.Cu")
		(net "M_E_CPU1_SB_DQ<17>")
	)
	(segment
		(start 136.758426 -234.363006)
		(end 136.758426 -234.20705)
		(width 0.088646)
		(layer "F.Cu")
		(net "M_E_CPU1_SB_DQ<17>")
	)
	(segment
		(start 159.914844 -212.147404)
		(end 159.730186 -212.147404)
		(width 0.20066)
		(layer "F.Cu")
		(net "M_E_CPU1_SB_DQ<17>")
	)
	(segment
		(start 140.341096 -234.210098)
		(end 140.90523 -234.210098)
		(width 0.1016)
		(layer "F.Cu")
		(net "M_E_CPU1_SB_DQ<17>")
	)
	(segment
		(start 138.611864 -234.202478)
		(end 138.763502 -234.113578)
		(width 0.088646)
		(layer "F.Cu")
		(net "M_E_CPU1_SB_DQ<17>")
	)
	(segment
		(start 161.891726 -211.326222)
		(end 161.470594 -211.326222)
		(width 0.20066)
		(layer "F.Cu")
		(net "M_E_CPU1_SB_DQ<17>")
	)
	(segment
		(start 137.034016 -234.028996)
		(end 137.291826 -234.286806)
		(width 0.088646)
		(layer "F.Cu")
		(net "M_E_CPU1_SB_DQ<17>")
	)
	(segment
		(start 164.974778 -211.95411)
		(end 164.347652 -211.326984)
		(width 0.20066)
		(layer "F.Cu")
		(net "M_E_CPU1_SB_DQ<17>")
	)
	(segment
		(start 150.024084 -215.731852)
		(end 150.024084 -215.092788)
		(width 0.20066)
		(layer "F.Cu")
		(net "M_E_CPU1_SB_DQ<17>")
	)
	(segment
		(start 148.13534 -218.63812)
		(end 148.419312 -218.63812)
		(width 0.20066)
		(layer "F.Cu")
		(net "M_E_CPU1_SB_DQ<17>")
	)
	(segment
		(start 159.34944 -211.766658)
		(end 158.813246 -211.766658)
		(width 0.20066)
		(layer "F.Cu")
		(net "M_E_CPU1_SB_DQ<17>")
	)
	(segment
		(start 136.453626 -234.365038)
		(end 136.542272 -234.453684)
		(width 0.088646)
		(layer "F.Cu")
		(net "M_E_CPU1_SB_DQ<17>")
	)
	(segment
		(start 148.373846 -217.429334)
		(end 148.373846 -217.713306)
		(width 0.20066)
		(layer "F.Cu")
		(net "M_E_CPU1_SB_DQ<17>")
	)
	(segment
		(start 136.453626 -234.0991)
		(end 136.453626 -234.365038)
		(width 0.088646)
		(layer "F.Cu")
		(net "M_E_CPU1_SB_DQ<17>")
	)
	(segment
		(start 146.361912 -218.75496)
		(end 146.779488 -218.337384)
		(width 0.1016)
		(layer "F.Cu")
		(net "M_E_CPU1_SB_DQ<17>")
	)
	(segment
		(start 156.888942 -212.163152)
		(end 157.50667 -212.163152)
		(width 0.20066)
		(layer "F.Cu")
		(net "M_E_CPU1_SB_DQ<17>")
	)
	(segment
		(start 157.903164 -211.766658)
		(end 158.813246 -211.766658)
		(width 0.20066)
		(layer "F.Cu")
		(net "M_E_CPU1_SB_DQ<17>")
	)
	(segment
		(start 140.045186 -234.209844)
		(end 140.04544 -234.210098)
		(width 0.088646)
		(layer "F.Cu")
		(net "M_E_CPU1_SB_DQ<17>")
	)
	(segment
		(start 166.357046 -211.766658)
		(end 165.53561 -211.766658)
		(width 0.20066)
		(layer "F.Cu")
		(net "M_E_CPU1_SB_DQ<17>")
	)
	(segment
		(start 150.506176 -216.551256)
		(end 150.506176 -216.213944)
		(width 0.20066)
		(layer "F.Cu")
		(net "M_E_CPU1_SB_DQ<17>")
	)
	(segment
		(start 138.763502 -234.113578)
		(end 139.762738 -234.113578)
		(width 0.088646)
		(layer "F.Cu")
		(net "M_E_CPU1_SB_DQ<17>")
	)
	(segment
		(start 147.934172 -218.436952)
		(end 148.13534 -218.63812)
		(width 0.20066)
		(layer "F.Cu")
		(net "M_E_CPU1_SB_DQ<17>")
	)
	(segment
		(start 139.762738 -234.113578)
		(end 139.859004 -234.209844)
		(width 0.088646)
		(layer "F.Cu")
		(net "M_E_CPU1_SB_DQ<17>")
	)
	(segment
		(start 146.779488 -218.337384)
		(end 147.888706 -217.228166)
		(width 0.20066)
		(layer "F.Cu")
		(net "M_E_CPU1_SB_DQ<17>")
	)
	(segment
		(start 161.10585 -211.690966)
		(end 160.371282 -211.690966)
		(width 0.20066)
		(layer "F.Cu")
		(net "M_E_CPU1_SB_DQ<17>")
	)
	(segment
		(start 153.512774 -211.604098)
		(end 156.329888 -211.604098)
		(width 0.20066)
		(layer "F.Cu")
		(net "M_E_CPU1_SB_DQ<17>")
	)
	(segment
		(start 164.347652 -211.326984)
		(end 163.923726 -211.326984)
		(width 0.20066)
		(layer "F.Cu")
		(net "M_E_CPU1_SB_DQ<17>")
	)
	(segment
		(start 136.667748 -234.453684)
		(end 136.758426 -234.363006)
		(width 0.088646)
		(layer "F.Cu")
		(net "M_E_CPU1_SB_DQ<17>")
	)
	(segment
		(start 161.896552 -211.326222)
		(end 161.891726 -211.326222)
		(width 0.101854)
		(layer "F.Cu")
		(net "M_E_CPU1_SB_DQ<17>")
	)
	(segment
		(start 136.758426 -234.20705)
		(end 136.93648 -234.028996)
		(width 0.088646)
		(layer "F.Cu")
		(net "M_E_CPU1_SB_DQ<17>")
	)
	(arc
		(start 138.301222 -234.286806)
		(mid 138.462162 -234.265344)
		(end 138.611864 -234.202478)
		(width 0.088646)
		(layer "F.Cu")
		(net "M_E_CPU1_SB_DQ<17>")
	)
	(segment
		(start 154.088338 -214.173308)
		(end 153.804874 -214.173308)
		(width 0.20066)
		(layer "F.Cu")
		(net "M_E_CPU1_SB_DQ<16>")
	)
	(segment
		(start 161.245804 -213.357206)
		(end 160.814766 -213.788244)
		(width 0.20066)
		(layer "F.Cu")
		(net "M_E_CPU1_SB_DQ<16>")
	)
	(segment
		(start 154.28976 -214.658194)
		(end 154.28976 -214.37473)
		(width 0.20066)
		(layer "F.Cu")
		(net "M_E_CPU1_SB_DQ<16>")
	)
	(segment
		(start 137.578338 -234.853226)
		(end 137.667238 -234.942126)
		(width 0.088646)
		(layer "F.Cu")
		(net "M_E_CPU1_SB_DQ<16>")
	)
	(segment
		(start 157.492954 -213.83625)
		(end 157.862524 -213.46668)
		(width 0.20066)
		(layer "F.Cu")
		(net "M_E_CPU1_SB_DQ<16>")
	)
	(segment
		(start 146.971512 -221.243652)
		(end 147.33778 -220.877384)
		(width 0.1016)
		(layer "F.Cu")
		(net "M_E_CPU1_SB_DQ<16>")
	)
	(segment
		(start 164.347652 -213.027006)
		(end 163.923726 -213.027006)
		(width 0.20066)
		(layer "F.Cu")
		(net "M_E_CPU1_SB_DQ<16>")
	)
	(segment
		(start 161.896552 -213.02853)
		(end 161.891726 -213.02853)
		(width 0.101854)
		(layer "F.Cu")
		(net "M_E_CPU1_SB_DQ<16>")
	)
	(segment
		(start 161.446464 -213.02853)
		(end 161.245804 -213.22919)
		(width 0.20066)
		(layer "F.Cu")
		(net "M_E_CPU1_SB_DQ<16>")
	)
	(segment
		(start 163.908994 -213.041738)
		(end 161.90976 -213.041738)
		(width 0.1016)
		(layer "F.Cu")
		(net "M_E_CPU1_SB_DQ<16>")
	)
	(segment
		(start 151.827992 -215.464136)
		(end 151.827992 -215.180418)
		(width 0.20066)
		(layer "F.Cu")
		(net "M_E_CPU1_SB_DQ<16>")
	)
	(segment
		(start 140.341096 -234.844336)
		(end 141.133576 -234.844336)
		(width 0.1016)
		(layer "F.Cu")
		(net "M_E_CPU1_SB_DQ<16>")
	)
	(segment
		(start 137.667238 -234.942126)
		(end 137.667238 -235.101892)
		(width 0.088646)
		(layer "F.Cu")
		(net "M_E_CPU1_SB_DQ<16>")
	)
	(segment
		(start 138.476228 -235.038646)
		(end 139.24661 -235.35767)
		(width 0.088646)
		(layer "F.Cu")
		(net "M_E_CPU1_SB_DQ<16>")
	)
	(segment
		(start 159.635444 -213.46668)
		(end 158.813246 -213.46668)
		(width 0.20066)
		(layer "F.Cu")
		(net "M_E_CPU1_SB_DQ<16>")
	)
	(segment
		(start 161.90976 -213.041738)
		(end 161.896552 -213.02853)
		(width 0.1016)
		(layer "F.Cu")
		(net "M_E_CPU1_SB_DQ<16>")
	)
	(segment
		(start 153.804874 -214.173308)
		(end 152.312878 -215.665304)
		(width 0.20066)
		(layer "F.Cu")
		(net "M_E_CPU1_SB_DQ<16>")
	)
	(segment
		(start 157.862524 -213.46668)
		(end 158.813246 -213.46668)
		(width 0.20066)
		(layer "F.Cu")
		(net "M_E_CPU1_SB_DQ<16>")
	)
	(segment
		(start 155.833572 -213.39302)
		(end 156.276802 -213.83625)
		(width 0.20066)
		(layer "F.Cu")
		(net "M_E_CPU1_SB_DQ<16>")
	)
	(segment
		(start 136.920478 -235.054902)
		(end 137.025126 -235.15955)
		(width 0.088646)
		(layer "F.Cu")
		(net "M_E_CPU1_SB_DQ<16>")
	)
	(segment
		(start 137.431526 -234.853226)
		(end 137.578338 -234.853226)
		(width 0.088646)
		(layer "F.Cu")
		(net "M_E_CPU1_SB_DQ<16>")
	)
	(segment
		(start 136.920478 -234.919774)
		(end 136.920478 -235.054902)
		(width 0.088646)
		(layer "F.Cu")
		(net "M_E_CPU1_SB_DQ<16>")
	)
	(segment
		(start 160.814766 -213.788244)
		(end 159.957008 -213.788244)
		(width 0.20066)
		(layer "F.Cu")
		(net "M_E_CPU1_SB_DQ<16>")
	)
	(segment
		(start 154.28976 -214.37473)
		(end 154.088338 -214.173308)
		(width 0.20066)
		(layer "F.Cu")
		(net "M_E_CPU1_SB_DQ<16>")
	)
	(segment
		(start 137.342626 -235.033566)
		(end 137.342626 -234.942126)
		(width 0.088646)
		(layer "F.Cu")
		(net "M_E_CPU1_SB_DQ<16>")
	)
	(segment
		(start 151.827992 -215.180418)
		(end 153.614882 -213.39302)
		(width 0.20066)
		(layer "F.Cu")
		(net "M_E_CPU1_SB_DQ<16>")
	)
	(segment
		(start 161.891726 -213.02853)
		(end 161.446464 -213.02853)
		(width 0.20066)
		(layer "F.Cu")
		(net "M_E_CPU1_SB_DQ<16>")
	)
	(segment
		(start 139.24661 -235.35767)
		(end 139.606274 -235.35767)
		(width 0.088646)
		(layer "F.Cu")
		(net "M_E_CPU1_SB_DQ<16>")
	)
	(segment
		(start 137.014712 -234.69219)
		(end 136.920478 -234.919774)
		(width 0.088646)
		(layer "F.Cu")
		(net "M_E_CPU1_SB_DQ<16>")
	)
	(segment
		(start 166.357046 -213.46668)
		(end 164.787834 -213.46668)
		(width 0.20066)
		(layer "F.Cu")
		(net "M_E_CPU1_SB_DQ<16>")
	)
	(segment
		(start 153.614882 -213.39302)
		(end 155.833572 -213.39302)
		(width 0.20066)
		(layer "F.Cu")
		(net "M_E_CPU1_SB_DQ<16>")
	)
	(segment
		(start 152.02916 -215.665304)
		(end 151.827992 -215.464136)
		(width 0.20066)
		(layer "F.Cu")
		(net "M_E_CPU1_SB_DQ<16>")
	)
	(segment
		(start 137.785348 -235.220002)
		(end 138.071098 -235.220002)
		(width 0.088646)
		(layer "F.Cu")
		(net "M_E_CPU1_SB_DQ<16>")
	)
	(segment
		(start 161.245804 -213.22919)
		(end 161.245804 -213.357206)
		(width 0.20066)
		(layer "F.Cu")
		(net "M_E_CPU1_SB_DQ<16>")
	)
	(segment
		(start 137.667238 -235.101892)
		(end 137.785348 -235.220002)
		(width 0.088646)
		(layer "F.Cu")
		(net "M_E_CPU1_SB_DQ<16>")
	)
	(segment
		(start 152.312878 -215.665304)
		(end 152.02916 -215.665304)
		(width 0.20066)
		(layer "F.Cu")
		(net "M_E_CPU1_SB_DQ<16>")
	)
	(segment
		(start 140.119608 -234.844336)
		(end 140.341096 -234.844336)
		(width 0.088646)
		(layer "F.Cu")
		(net "M_E_CPU1_SB_DQ<16>")
	)
	(segment
		(start 137.025126 -235.15955)
		(end 137.216642 -235.15955)
		(width 0.088646)
		(layer "F.Cu")
		(net "M_E_CPU1_SB_DQ<16>")
	)
	(segment
		(start 164.78758 -213.466934)
		(end 164.347652 -213.027006)
		(width 0.20066)
		(layer "F.Cu")
		(net "M_E_CPU1_SB_DQ<16>")
	)
	(segment
		(start 137.216642 -235.15955)
		(end 137.342626 -235.033566)
		(width 0.088646)
		(layer "F.Cu")
		(net "M_E_CPU1_SB_DQ<16>")
	)
	(segment
		(start 148.222462 -220.726762)
		(end 154.28976 -214.658194)
		(width 0.20066)
		(layer "F.Cu")
		(net "M_E_CPU1_SB_DQ<16>")
	)
	(segment
		(start 147.33778 -220.877384)
		(end 147.338034 -220.877384)
		(width 0.1016)
		(layer "F.Cu")
		(net "M_E_CPU1_SB_DQ<16>")
	)
	(segment
		(start 147.338034 -220.877384)
		(end 147.48764 -220.727778)
		(width 0.20066)
		(layer "F.Cu")
		(net "M_E_CPU1_SB_DQ<16>")
	)
	(segment
		(start 159.957008 -213.788244)
		(end 159.635444 -213.46668)
		(width 0.20066)
		(layer "F.Cu")
		(net "M_E_CPU1_SB_DQ<16>")
	)
	(segment
		(start 164.787834 -213.46668)
		(end 164.78758 -213.466934)
		(width 0.20066)
		(layer "F.Cu")
		(net "M_E_CPU1_SB_DQ<16>")
	)
	(segment
		(start 139.606274 -235.35767)
		(end 140.119608 -234.844336)
		(width 0.088646)
		(layer "F.Cu")
		(net "M_E_CPU1_SB_DQ<16>")
	)
	(segment
		(start 146.971512 -229.0064)
		(end 146.971512 -221.243652)
		(width 0.1016)
		(layer "F.Cu")
		(net "M_E_CPU1_SB_DQ<16>")
	)
	(segment
		(start 147.48764 -220.727778)
		(end 148.222462 -220.726762)
		(width 0.20066)
		(layer "F.Cu")
		(net "M_E_CPU1_SB_DQ<16>")
	)
	(segment
		(start 156.276802 -213.83625)
		(end 157.492954 -213.83625)
		(width 0.20066)
		(layer "F.Cu")
		(net "M_E_CPU1_SB_DQ<16>")
	)
	(segment
		(start 137.342626 -234.942126)
		(end 137.431526 -234.853226)
		(width 0.088646)
		(layer "F.Cu")
		(net "M_E_CPU1_SB_DQ<16>")
	)
	(segment
		(start 163.923726 -213.027006)
		(end 163.908994 -213.041738)
		(width 0.1016)
		(layer "F.Cu")
		(net "M_E_CPU1_SB_DQ<16>")
	)
	(segment
		(start 141.133576 -234.844336)
		(end 146.971512 -229.0064)
		(width 0.1016)
		(layer "F.Cu")
		(net "M_E_CPU1_SB_DQ<16>")
	)
	(arc
		(start 138.071098 -235.220002)
		(mid 138.138484 -235.206656)
		(end 138.195558 -235.16844)
		(width 0.088646)
		(layer "F.Cu")
		(net "M_E_CPU1_SB_DQ<16>")
	)
	(arc
		(start 138.195558 -235.16844)
		(mid 138.284716 -235.098416)
		(end 138.38809 -235.051854)
		(width 0.088646)
		(layer "F.Cu")
		(net "M_E_CPU1_SB_DQ<16>")
	)
	(arc
		(start 138.38809 -235.051854)
		(mid 138.431661 -235.041925)
		(end 138.476228 -235.038646)
		(width 0.088646)
		(layer "F.Cu")
		(net "M_E_CPU1_SB_DQ<16>")
	)
	(segment
		(start 165.369494 -214.752174)
		(end 165.335458 -214.752174)
		(width 0.101854)
		(layer "F.Cu")
		(net "M_E_CPU1_SB_DQ<15>")
	)
	(segment
		(start 138.894058 -235.754672)
		(end 140.242798 -235.754672)
		(width 0.088646)
		(layer "F.Cu")
		(net "M_E_CPU1_SB_DQ<15>")
	)
	(segment
		(start 168.883584 -214.064596)
		(end 168.499536 -214.064596)
		(width 0.20066)
		(layer "F.Cu")
		(net "M_E_CPU1_SB_DQ<15>")
	)
	(segment
		(start 164.604954 -214.316564)
		(end 162.913314 -214.316564)
		(width 0.20066)
		(layer "F.Cu")
		(net "M_E_CPU1_SB_DQ<15>")
	)
	(segment
		(start 157.81528 -214.741506)
		(end 159.813498 -214.741506)
		(width 0.1016)
		(layer "F.Cu")
		(net "M_E_CPU1_SB_DQ<15>")
	)
	(segment
		(start 141.103096 -235.384086)
		(end 141.437106 -235.384086)
		(width 0.1016)
		(layer "F.Cu")
		(net "M_E_CPU1_SB_DQ<15>")
	)
	(segment
		(start 168.064688 -214.757508)
		(end 167.367458 -214.757508)
		(width 0.20066)
		(layer "F.Cu")
		(net "M_E_CPU1_SB_DQ<15>")
	)
	(segment
		(start 165.380162 -214.741506)
		(end 165.369494 -214.752174)
		(width 0.101854)
		(layer "F.Cu")
		(net "M_E_CPU1_SB_DQ<15>")
	)
	(segment
		(start 159.823658 -214.751666)
		(end 160.769554 -214.751666)
		(width 0.20066)
		(layer "F.Cu")
		(net "M_E_CPU1_SB_DQ<15>")
	)
	(segment
		(start 165.040564 -214.752174)
		(end 164.604954 -214.316564)
		(width 0.20066)
		(layer "F.Cu")
		(net "M_E_CPU1_SB_DQ<15>")
	)
	(segment
		(start 147.530312 -229.29088)
		(end 147.530312 -223.82226)
		(width 0.1016)
		(layer "F.Cu")
		(net "M_E_CPU1_SB_DQ<15>")
	)
	(segment
		(start 140.242798 -235.754672)
		(end 140.613384 -235.384086)
		(width 0.088646)
		(layer "F.Cu")
		(net "M_E_CPU1_SB_DQ<15>")
	)
	(segment
		(start 155.454604 -214.760302)
		(end 157.791658 -214.760302)
		(width 0.20066)
		(layer "F.Cu")
		(net "M_E_CPU1_SB_DQ<15>")
	)
	(segment
		(start 167.351456 -214.741506)
		(end 165.380162 -214.741506)
		(width 0.1016)
		(layer "F.Cu")
		(net "M_E_CPU1_SB_DQ<15>")
	)
	(segment
		(start 168.499536 -214.064596)
		(end 168.265348 -214.298784)
		(width 0.20066)
		(layer "F.Cu")
		(net "M_E_CPU1_SB_DQ<15>")
	)
	(segment
		(start 165.335458 -214.752174)
		(end 165.040564 -214.752174)
		(width 0.20066)
		(layer "F.Cu")
		(net "M_E_CPU1_SB_DQ<15>")
	)
	(segment
		(start 147.752816 -222.46209)
		(end 155.454604 -214.760302)
		(width 0.20066)
		(layer "F.Cu")
		(net "M_E_CPU1_SB_DQ<15>")
	)
	(segment
		(start 147.530312 -223.82226)
		(end 147.752816 -223.599756)
		(width 0.1016)
		(layer "F.Cu")
		(net "M_E_CPU1_SB_DQ<15>")
	)
	(segment
		(start 140.613384 -235.384086)
		(end 141.103096 -235.384086)
		(width 0.088646)
		(layer "F.Cu")
		(net "M_E_CPU1_SB_DQ<15>")
	)
	(segment
		(start 157.796484 -214.760302)
		(end 157.81528 -214.741506)
		(width 0.1016)
		(layer "F.Cu")
		(net "M_E_CPU1_SB_DQ<15>")
	)
	(segment
		(start 138.205972 -236.215682)
		(end 138.447018 -235.974636)
		(width 0.088646)
		(layer "F.Cu")
		(net "M_E_CPU1_SB_DQ<15>")
	)
	(segment
		(start 169.135552 -214.316564)
		(end 168.883584 -214.064596)
		(width 0.20066)
		(layer "F.Cu")
		(net "M_E_CPU1_SB_DQ<15>")
	)
	(segment
		(start 157.791658 -214.760302)
		(end 157.796484 -214.760302)
		(width 0.101854)
		(layer "F.Cu")
		(net "M_E_CPU1_SB_DQ<15>")
	)
	(segment
		(start 167.367458 -214.757508)
		(end 167.351456 -214.741506)
		(width 0.1016)
		(layer "F.Cu")
		(net "M_E_CPU1_SB_DQ<15>")
	)
	(segment
		(start 161.204656 -214.316564)
		(end 162.913314 -214.316564)
		(width 0.20066)
		(layer "F.Cu")
		(net "M_E_CPU1_SB_DQ<15>")
	)
	(segment
		(start 141.437106 -235.384086)
		(end 147.530312 -229.29088)
		(width 0.1016)
		(layer "F.Cu")
		(net "M_E_CPU1_SB_DQ<15>")
	)
	(segment
		(start 159.813498 -214.741506)
		(end 159.823658 -214.751666)
		(width 0.1016)
		(layer "F.Cu")
		(net "M_E_CPU1_SB_DQ<15>")
	)
	(segment
		(start 137.954766 -236.319822)
		(end 138.205972 -236.215682)
		(width 0.088646)
		(layer "F.Cu")
		(net "M_E_CPU1_SB_DQ<15>")
	)
	(segment
		(start 170.457114 -214.316564)
		(end 169.135552 -214.316564)
		(width 0.20066)
		(layer "F.Cu")
		(net "M_E_CPU1_SB_DQ<15>")
	)
	(segment
		(start 147.752816 -223.599756)
		(end 147.752816 -223.328992)
		(width 0.1016)
		(layer "F.Cu")
		(net "M_E_CPU1_SB_DQ<15>")
	)
	(segment
		(start 168.265348 -214.556848)
		(end 168.064688 -214.757508)
		(width 0.20066)
		(layer "F.Cu")
		(net "M_E_CPU1_SB_DQ<15>")
	)
	(segment
		(start 160.769554 -214.751666)
		(end 161.204656 -214.316564)
		(width 0.20066)
		(layer "F.Cu")
		(net "M_E_CPU1_SB_DQ<15>")
	)
	(segment
		(start 168.265348 -214.298784)
		(end 168.265348 -214.556848)
		(width 0.20066)
		(layer "F.Cu")
		(net "M_E_CPU1_SB_DQ<15>")
	)
	(segment
		(start 147.752816 -223.328992)
		(end 147.752816 -222.46209)
		(width 0.20066)
		(layer "F.Cu")
		(net "M_E_CPU1_SB_DQ<15>")
	)
	(arc
		(start 138.857228 -235.755688)
		(mid 138.875635 -235.754878)
		(end 138.894058 -235.754672)
		(width 0.088646)
		(layer "F.Cu")
		(net "M_E_CPU1_SB_DQ<15>")
	)
	(arc
		(start 138.447018 -235.974636)
		(mid 138.519725 -235.896754)
		(end 138.605768 -235.83392)
		(width 0.088646)
		(layer "F.Cu")
		(net "M_E_CPU1_SB_DQ<15>")
	)
	(arc
		(start 138.605768 -235.83392)
		(mid 138.726875 -235.779939)
		(end 138.857228 -235.755688)
		(width 0.088646)
		(layer "F.Cu")
		(net "M_E_CPU1_SB_DQ<15>")
	)
	(segment
		(start 160.028636 -216.455752)
		(end 160.634426 -216.455752)
		(width 0.20066)
		(layer "F.Cu")
		(net "M_E_CPU1_SB_DQ<14>")
	)
	(segment
		(start 167.330882 -216.441528)
		(end 165.356032 -216.441528)
		(width 0.1016)
		(layer "F.Cu")
		(net "M_E_CPU1_SB_DQ<14>")
	)
	(segment
		(start 168.064688 -216.455244)
		(end 167.367458 -216.455244)
		(width 0.20066)
		(layer "F.Cu")
		(net "M_E_CPU1_SB_DQ<14>")
	)
	(segment
		(start 151.253698 -221.440756)
		(end 151.253698 -220.848936)
		(width 0.20066)
		(layer "F.Cu")
		(net "M_E_CPU1_SB_DQ<14>")
	)
	(segment
		(start 141.103096 -235.993686)
		(end 141.69009 -235.993686)
		(width 0.1016)
		(layer "F.Cu")
		(net "M_E_CPU1_SB_DQ<14>")
	)
	(segment
		(start 157.08757 -216.453466)
		(end 157.7848 -216.453466)
		(width 0.20066)
		(layer "F.Cu")
		(net "M_E_CPU1_SB_DQ<14>")
	)
	(segment
		(start 170.457114 -216.016586)
		(end 169.135552 -216.016586)
		(width 0.20066)
		(layer "F.Cu")
		(net "M_E_CPU1_SB_DQ<14>")
	)
	(segment
		(start 151.253698 -220.848936)
		(end 155.893008 -216.209626)
		(width 0.20066)
		(layer "F.Cu")
		(net "M_E_CPU1_SB_DQ<14>")
	)
	(segment
		(start 160.014666 -216.441782)
		(end 160.028636 -216.455752)
		(width 0.20066)
		(layer "F.Cu")
		(net "M_E_CPU1_SB_DQ<14>")
	)
	(segment
		(start 168.265348 -216.254584)
		(end 168.064688 -216.455244)
		(width 0.20066)
		(layer "F.Cu")
		(net "M_E_CPU1_SB_DQ<14>")
	)
	(segment
		(start 148.139912 -229.543864)
		(end 148.139912 -226.17811)
		(width 0.1016)
		(layer "F.Cu")
		(net "M_E_CPU1_SB_DQ<14>")
	)
	(segment
		(start 167.344598 -216.455244)
		(end 167.330882 -216.441528)
		(width 0.1016)
		(layer "F.Cu")
		(net "M_E_CPU1_SB_DQ<14>")
	)
	(segment
		(start 141.69009 -235.993686)
		(end 148.139912 -229.543864)
		(width 0.1016)
		(layer "F.Cu")
		(net "M_E_CPU1_SB_DQ<14>")
	)
	(segment
		(start 150.215092 -224.10293)
		(end 150.215092 -223.657414)
		(width 0.20066)
		(layer "F.Cu")
		(net "M_E_CPU1_SB_DQ<14>")
	)
	(segment
		(start 148.839936 -225.478086)
		(end 150.215092 -224.10293)
		(width 0.20066)
		(layer "F.Cu")
		(net "M_E_CPU1_SB_DQ<14>")
	)
	(segment
		(start 157.791658 -216.446608)
		(end 157.796484 -216.441782)
		(width 0.101854)
		(layer "F.Cu")
		(net "M_E_CPU1_SB_DQ<14>")
	)
	(segment
		(start 168.265348 -215.998806)
		(end 168.265348 -216.254584)
		(width 0.20066)
		(layer "F.Cu")
		(net "M_E_CPU1_SB_DQ<14>")
	)
	(segment
		(start 168.499536 -215.764618)
		(end 168.265348 -215.998806)
		(width 0.20066)
		(layer "F.Cu")
		(net "M_E_CPU1_SB_DQ<14>")
	)
	(segment
		(start 149.862794 -222.83166)
		(end 151.253698 -221.440756)
		(width 0.20066)
		(layer "F.Cu")
		(net "M_E_CPU1_SB_DQ<14>")
	)
	(segment
		(start 150.215092 -223.657414)
		(end 149.862794 -223.305116)
		(width 0.20066)
		(layer "F.Cu")
		(net "M_E_CPU1_SB_DQ<14>")
	)
	(segment
		(start 164.642546 -216.016586)
		(end 162.913314 -216.016586)
		(width 0.20066)
		(layer "F.Cu")
		(net "M_E_CPU1_SB_DQ<14>")
	)
	(segment
		(start 149.862794 -223.305116)
		(end 149.862794 -222.83166)
		(width 0.20066)
		(layer "F.Cu")
		(net "M_E_CPU1_SB_DQ<14>")
	)
	(segment
		(start 139.535916 -237.133892)
		(end 140.676122 -235.993686)
		(width 0.088646)
		(layer "F.Cu")
		(net "M_E_CPU1_SB_DQ<14>")
	)
	(segment
		(start 148.139912 -226.17811)
		(end 148.839936 -225.478086)
		(width 0.1016)
		(layer "F.Cu")
		(net "M_E_CPU1_SB_DQ<14>")
	)
	(segment
		(start 169.135552 -216.016586)
		(end 168.883584 -215.764618)
		(width 0.20066)
		(layer "F.Cu")
		(net "M_E_CPU1_SB_DQ<14>")
	)
	(segment
		(start 138.424666 -237.133892)
		(end 139.535916 -237.133892)
		(width 0.088646)
		(layer "F.Cu")
		(net "M_E_CPU1_SB_DQ<14>")
	)
	(segment
		(start 165.339522 -216.458038)
		(end 165.335458 -216.458038)
		(width 0.101854)
		(layer "F.Cu")
		(net "M_E_CPU1_SB_DQ<14>")
	)
	(segment
		(start 157.796484 -216.441782)
		(end 159.823658 -216.441782)
		(width 0.1016)
		(layer "F.Cu")
		(net "M_E_CPU1_SB_DQ<14>")
	)
	(segment
		(start 140.676122 -235.993686)
		(end 141.103096 -235.993686)
		(width 0.088646)
		(layer "F.Cu")
		(net "M_E_CPU1_SB_DQ<14>")
	)
	(segment
		(start 156.84373 -216.209626)
		(end 157.08757 -216.453466)
		(width 0.20066)
		(layer "F.Cu")
		(net "M_E_CPU1_SB_DQ<14>")
	)
	(segment
		(start 155.893008 -216.209626)
		(end 156.84373 -216.209626)
		(width 0.20066)
		(layer "F.Cu")
		(net "M_E_CPU1_SB_DQ<14>")
	)
	(segment
		(start 157.7848 -216.453466)
		(end 157.791658 -216.446608)
		(width 0.20066)
		(layer "F.Cu")
		(net "M_E_CPU1_SB_DQ<14>")
	)
	(segment
		(start 168.883584 -215.764618)
		(end 168.499536 -215.764618)
		(width 0.20066)
		(layer "F.Cu")
		(net "M_E_CPU1_SB_DQ<14>")
	)
	(segment
		(start 159.823658 -216.441782)
		(end 160.014666 -216.441782)
		(width 0.20066)
		(layer "F.Cu")
		(net "M_E_CPU1_SB_DQ<14>")
	)
	(segment
		(start 165.083998 -216.458038)
		(end 164.642546 -216.016586)
		(width 0.20066)
		(layer "F.Cu")
		(net "M_E_CPU1_SB_DQ<14>")
	)
	(segment
		(start 165.335458 -216.458038)
		(end 165.083998 -216.458038)
		(width 0.20066)
		(layer "F.Cu")
		(net "M_E_CPU1_SB_DQ<14>")
	)
	(segment
		(start 161.073592 -216.016586)
		(end 162.913314 -216.016586)
		(width 0.20066)
		(layer "F.Cu")
		(net "M_E_CPU1_SB_DQ<14>")
	)
	(segment
		(start 167.367458 -216.455244)
		(end 167.344598 -216.455244)
		(width 0.101854)
		(layer "F.Cu")
		(net "M_E_CPU1_SB_DQ<14>")
	)
	(segment
		(start 165.356032 -216.441528)
		(end 165.339522 -216.458038)
		(width 0.1016)
		(layer "F.Cu")
		(net "M_E_CPU1_SB_DQ<14>")
	)
	(segment
		(start 160.634426 -216.455752)
		(end 161.073592 -216.016586)
		(width 0.20066)
		(layer "F.Cu")
		(net "M_E_CPU1_SB_DQ<14>")
	)
	(segment
		(start 163.892484 -214.74176)
		(end 161.924746 -214.74176)
		(width 0.1016)
		(layer "F.Cu")
		(net "M_E_CPU1_SB_DQ<13>")
	)
	(segment
		(start 164.787326 -215.166702)
		(end 164.356542 -214.735918)
		(width 0.20066)
		(layer "F.Cu")
		(net "M_E_CPU1_SB_DQ<13>")
	)
	(segment
		(start 149.640544 -221.54007)
		(end 150.183596 -221.54007)
		(width 0.20066)
		(layer "F.Cu")
		(net "M_E_CPU1_SB_DQ<13>")
	)
	(segment
		(start 161.245804 -215.227408)
		(end 161.082228 -215.390984)
		(width 0.20066)
		(layer "F.Cu")
		(net "M_E_CPU1_SB_DQ<13>")
	)
	(segment
		(start 150.39721 -221.326456)
		(end 150.39721 -220.783404)
		(width 0.20066)
		(layer "F.Cu")
		(net "M_E_CPU1_SB_DQ<13>")
	)
	(segment
		(start 157.861 -215.166702)
		(end 158.813246 -215.166702)
		(width 0.20066)
		(layer "F.Cu")
		(net "M_E_CPU1_SB_DQ<13>")
	)
	(segment
		(start 148.20265 -225.198178)
		(end 148.381466 -225.019362)
		(width 0.1016)
		(layer "F.Cu")
		(net "M_E_CPU1_SB_DQ<13>")
	)
	(segment
		(start 148.381466 -225.019362)
		(end 148.456904 -224.943924)
		(width 0.20066)
		(layer "F.Cu")
		(net "M_E_CPU1_SB_DQ<13>")
	)
	(segment
		(start 161.446464 -214.726266)
		(end 161.245804 -214.926926)
		(width 0.20066)
		(layer "F.Cu")
		(net "M_E_CPU1_SB_DQ<13>")
	)
	(segment
		(start 138.894312 -235.944918)
		(end 140.327888 -235.944918)
		(width 0.088646)
		(layer "F.Cu")
		(net "M_E_CPU1_SB_DQ<13>")
	)
	(segment
		(start 141.103096 -235.688886)
		(end 141.563598 -235.688886)
		(width 0.1016)
		(layer "F.Cu")
		(net "M_E_CPU1_SB_DQ<13>")
	)
	(segment
		(start 148.670264 -222.51035)
		(end 149.213316 -222.51035)
		(width 0.20066)
		(layer "F.Cu")
		(net "M_E_CPU1_SB_DQ<13>")
	)
	(segment
		(start 163.897564 -214.73668)
		(end 163.892484 -214.74176)
		(width 0.1016)
		(layer "F.Cu")
		(net "M_E_CPU1_SB_DQ<13>")
	)
	(segment
		(start 149.42693 -222.296736)
		(end 149.42693 -221.753684)
		(width 0.20066)
		(layer "F.Cu")
		(net "M_E_CPU1_SB_DQ<13>")
	)
	(segment
		(start 148.664676 -223.513904)
		(end 148.464016 -223.313244)
		(width 0.20066)
		(layer "F.Cu")
		(net "M_E_CPU1_SB_DQ<13>")
	)
	(segment
		(start 141.563598 -235.688886)
		(end 147.835112 -229.417372)
		(width 0.1016)
		(layer "F.Cu")
		(net "M_E_CPU1_SB_DQ<13>")
	)
	(segment
		(start 149.42693 -221.753684)
		(end 149.640544 -221.54007)
		(width 0.20066)
		(layer "F.Cu")
		(net "M_E_CPU1_SB_DQ<13>")
	)
	(segment
		(start 161.245804 -214.926926)
		(end 161.245804 -215.227408)
		(width 0.20066)
		(layer "F.Cu")
		(net "M_E_CPU1_SB_DQ<13>")
	)
	(segment
		(start 149.169882 -223.513904)
		(end 148.664676 -223.513904)
		(width 0.20066)
		(layer "F.Cu")
		(net "M_E_CPU1_SB_DQ<13>")
	)
	(segment
		(start 164.356542 -214.735918)
		(end 163.924488 -214.735918)
		(width 0.20066)
		(layer "F.Cu")
		(net "M_E_CPU1_SB_DQ<13>")
	)
	(segment
		(start 137.014712 -236.319822)
		(end 137.325608 -236.319822)
		(width 0.088646)
		(layer "F.Cu")
		(net "M_E_CPU1_SB_DQ<13>")
	)
	(segment
		(start 157.487366 -215.540336)
		(end 157.861 -215.166702)
		(width 0.20066)
		(layer "F.Cu")
		(net "M_E_CPU1_SB_DQ<13>")
	)
	(segment
		(start 161.891726 -214.726266)
		(end 161.446464 -214.726266)
		(width 0.20066)
		(layer "F.Cu")
		(net "M_E_CPU1_SB_DQ<13>")
	)
	(segment
		(start 148.20265 -225.198432)
		(end 148.20265 -225.198178)
		(width 0.1016)
		(layer "F.Cu")
		(net "M_E_CPU1_SB_DQ<13>")
	)
	(segment
		(start 140.58392 -235.688886)
		(end 141.103096 -235.688886)
		(width 0.088646)
		(layer "F.Cu")
		(net "M_E_CPU1_SB_DQ<13>")
	)
	(segment
		(start 148.464016 -223.313244)
		(end 148.464016 -222.716598)
		(width 0.20066)
		(layer "F.Cu")
		(net "M_E_CPU1_SB_DQ<13>")
	)
	(segment
		(start 148.749258 -224.199704)
		(end 149.169882 -224.199704)
		(width 0.20066)
		(layer "F.Cu")
		(net "M_E_CPU1_SB_DQ<13>")
	)
	(segment
		(start 160.358836 -215.166702)
		(end 158.813246 -215.166702)
		(width 0.20066)
		(layer "F.Cu")
		(net "M_E_CPU1_SB_DQ<13>")
	)
	(segment
		(start 163.923726 -214.73668)
		(end 163.897564 -214.73668)
		(width 0.101854)
		(layer "F.Cu")
		(net "M_E_CPU1_SB_DQ<13>")
	)
	(segment
		(start 166.357046 -215.166702)
		(end 164.787326 -215.166702)
		(width 0.20066)
		(layer "F.Cu")
		(net "M_E_CPU1_SB_DQ<13>")
	)
	(segment
		(start 149.370542 -223.714564)
		(end 149.169882 -223.513904)
		(width 0.20066)
		(layer "F.Cu")
		(net "M_E_CPU1_SB_DQ<13>")
	)
	(segment
		(start 149.213316 -222.51035)
		(end 149.42693 -222.296736)
		(width 0.20066)
		(layer "F.Cu")
		(net "M_E_CPU1_SB_DQ<13>")
	)
	(segment
		(start 149.169882 -224.199704)
		(end 149.370542 -223.999044)
		(width 0.20066)
		(layer "F.Cu")
		(net "M_E_CPU1_SB_DQ<13>")
	)
	(segment
		(start 147.835112 -225.56597)
		(end 148.20265 -225.198432)
		(width 0.1016)
		(layer "F.Cu")
		(net "M_E_CPU1_SB_DQ<13>")
	)
	(segment
		(start 161.90722 -214.74176)
		(end 161.891726 -214.726266)
		(width 0.101854)
		(layer "F.Cu")
		(net "M_E_CPU1_SB_DQ<13>")
	)
	(segment
		(start 148.456904 -224.492058)
		(end 148.749258 -224.199704)
		(width 0.20066)
		(layer "F.Cu")
		(net "M_E_CPU1_SB_DQ<13>")
	)
	(segment
		(start 161.924746 -214.74176)
		(end 161.90722 -214.74176)
		(width 0.101854)
		(layer "F.Cu")
		(net "M_E_CPU1_SB_DQ<13>")
	)
	(segment
		(start 147.835112 -229.417372)
		(end 147.835112 -225.56597)
		(width 0.1016)
		(layer "F.Cu")
		(net "M_E_CPU1_SB_DQ<13>")
	)
	(segment
		(start 150.39721 -220.783404)
		(end 155.640278 -215.540336)
		(width 0.20066)
		(layer "F.Cu")
		(net "M_E_CPU1_SB_DQ<13>")
	)
	(segment
		(start 140.327888 -235.944918)
		(end 140.58392 -235.688886)
		(width 0.088646)
		(layer "F.Cu")
		(net "M_E_CPU1_SB_DQ<13>")
	)
	(segment
		(start 148.464016 -222.716598)
		(end 148.670264 -222.51035)
		(width 0.20066)
		(layer "F.Cu")
		(net "M_E_CPU1_SB_DQ<13>")
	)
	(segment
		(start 137.325608 -236.319822)
		(end 137.393172 -236.387386)
		(width 0.088646)
		(layer "F.Cu")
		(net "M_E_CPU1_SB_DQ<13>")
	)
	(segment
		(start 148.456904 -224.943924)
		(end 148.456904 -224.492058)
		(width 0.20066)
		(layer "F.Cu")
		(net "M_E_CPU1_SB_DQ<13>")
	)
	(segment
		(start 149.370542 -223.999044)
		(end 149.370542 -223.714564)
		(width 0.20066)
		(layer "F.Cu")
		(net "M_E_CPU1_SB_DQ<13>")
	)
	(segment
		(start 138.519916 -236.338364)
		(end 138.519916 -236.311186)
		(width 0.088646)
		(layer "F.Cu")
		(net "M_E_CPU1_SB_DQ<13>")
	)
	(segment
		(start 163.924488 -214.735918)
		(end 163.923726 -214.73668)
		(width 0.20066)
		(layer "F.Cu")
		(net "M_E_CPU1_SB_DQ<13>")
	)
	(segment
		(start 161.082228 -215.390984)
		(end 160.583118 -215.390984)
		(width 0.20066)
		(layer "F.Cu")
		(net "M_E_CPU1_SB_DQ<13>")
	)
	(segment
		(start 160.583118 -215.390984)
		(end 160.358836 -215.166702)
		(width 0.20066)
		(layer "F.Cu")
		(net "M_E_CPU1_SB_DQ<13>")
	)
	(segment
		(start 155.640278 -215.540336)
		(end 157.487366 -215.540336)
		(width 0.20066)
		(layer "F.Cu")
		(net "M_E_CPU1_SB_DQ<13>")
	)
	(segment
		(start 150.183596 -221.54007)
		(end 150.39721 -221.326456)
		(width 0.20066)
		(layer "F.Cu")
		(net "M_E_CPU1_SB_DQ<13>")
	)
	(arc
		(start 138.519916 -236.311186)
		(mid 138.572186 -236.128821)
		(end 138.707114 -235.995464)
		(width 0.088646)
		(layer "F.Cu")
		(net "M_E_CPU1_SB_DQ<13>")
	)
	(arc
		(start 138.237468 -236.809534)
		(mid 138.439754 -236.610553)
		(end 138.519916 -236.338364)
		(width 0.088646)
		(layer "F.Cu")
		(net "M_E_CPU1_SB_DQ<13>")
	)
	(arc
		(start 138.707114 -235.995464)
		(mid 138.797386 -235.957865)
		(end 138.894312 -235.944918)
		(width 0.088646)
		(layer "F.Cu")
		(net "M_E_CPU1_SB_DQ<13>")
	)
	(arc
		(start 137.672064 -236.809534)
		(mid 137.954766 -236.885276)
		(end 138.237468 -236.809534)
		(width 0.088646)
		(layer "F.Cu")
		(net "M_E_CPU1_SB_DQ<13>")
	)
	(arc
		(start 137.393172 -236.387386)
		(mid 137.482737 -236.631423)
		(end 137.672064 -236.809534)
		(width 0.088646)
		(layer "F.Cu")
		(net "M_E_CPU1_SB_DQ<13>")
	)
	(segment
		(start 138.028426 -237.266226)
		(end 138.142726 -237.380526)
		(width 0.088646)
		(layer "F.Cu")
		(net "M_E_CPU1_SB_DQ<12>")
	)
	(segment
		(start 164.901118 -216.866724)
		(end 164.458904 -216.42451)
		(width 0.20066)
		(layer "F.Cu")
		(net "M_E_CPU1_SB_DQ<12>")
	)
	(segment
		(start 138.689334 -237.39856)
		(end 139.549378 -237.39856)
		(width 0.088646)
		(layer "F.Cu")
		(net "M_E_CPU1_SB_DQ<12>")
	)
	(segment
		(start 137.749026 -237.393226)
		(end 137.876026 -237.266226)
		(width 0.088646)
		(layer "F.Cu")
		(net "M_E_CPU1_SB_DQ<12>")
	)
	(segment
		(start 150.192994 -225.382836)
		(end 151.99487 -223.58096)
		(width 0.20066)
		(layer "F.Cu")
		(net "M_E_CPU1_SB_DQ<12>")
	)
	(segment
		(start 148.444712 -229.670356)
		(end 148.444712 -226.882706)
		(width 0.1016)
		(layer "F.Cu")
		(net "M_E_CPU1_SB_DQ<12>")
	)
	(segment
		(start 160.977834 -217.095832)
		(end 160.76168 -217.095832)
		(width 0.20066)
		(layer "F.Cu")
		(net "M_E_CPU1_SB_DQ<12>")
	)
	(segment
		(start 151.197564 -223.407986)
		(end 150.913592 -223.407986)
		(width 0.20066)
		(layer "F.Cu")
		(net "M_E_CPU1_SB_DQ<12>")
	)
	(segment
		(start 149.344634 -225.982784)
		(end 149.944582 -225.382836)
		(width 0.20066)
		(layer "F.Cu")
		(net "M_E_CPU1_SB_DQ<12>")
	)
	(segment
		(start 163.906454 -216.441782)
		(end 161.938208 -216.441782)
		(width 0.1016)
		(layer "F.Cu")
		(net "M_E_CPU1_SB_DQ<12>")
	)
	(segment
		(start 138.142726 -237.456726)
		(end 138.218926 -237.532926)
		(width 0.088646)
		(layer "F.Cu")
		(net "M_E_CPU1_SB_DQ<12>")
	)
	(segment
		(start 151.99487 -223.296988)
		(end 151.793702 -223.09582)
		(width 0.20066)
		(layer "F.Cu")
		(net "M_E_CPU1_SB_DQ<12>")
	)
	(segment
		(start 161.349182 -216.428066)
		(end 161.148268 -216.62898)
		(width 0.20066)
		(layer "F.Cu")
		(net "M_E_CPU1_SB_DQ<12>")
	)
	(segment
		(start 151.794464 -222.411544)
		(end 151.995124 -222.210884)
		(width 0.20066)
		(layer "F.Cu")
		(net "M_E_CPU1_SB_DQ<12>")
	)
	(segment
		(start 137.601706 -237.588806)
		(end 137.616946 -237.588806)
		(width 0.088646)
		(layer "F.Cu")
		(net "M_E_CPU1_SB_DQ<12>")
	)
	(segment
		(start 149.944582 -225.382836)
		(end 150.192994 -225.382836)
		(width 0.20066)
		(layer "F.Cu")
		(net "M_E_CPU1_SB_DQ<12>")
	)
	(segment
		(start 150.913592 -223.407986)
		(end 150.712424 -223.206818)
		(width 0.20066)
		(layer "F.Cu")
		(net "M_E_CPU1_SB_DQ<12>")
	)
	(segment
		(start 150.712424 -222.922846)
		(end 151.223726 -222.411544)
		(width 0.20066)
		(layer "F.Cu")
		(net "M_E_CPU1_SB_DQ<12>")
	)
	(segment
		(start 161.148268 -216.62898)
		(end 161.148268 -216.925398)
		(width 0.20066)
		(layer "F.Cu")
		(net "M_E_CPU1_SB_DQ<12>")
	)
	(segment
		(start 151.995124 -222.210884)
		(end 151.995124 -221.022926)
		(width 0.20066)
		(layer "F.Cu")
		(net "M_E_CPU1_SB_DQ<12>")
	)
	(segment
		(start 137.297668 -237.457996)
		(end 137.456418 -237.549944)
		(width 0.088646)
		(layer "F.Cu")
		(net "M_E_CPU1_SB_DQ<12>")
	)
	(segment
		(start 138.218926 -237.532926)
		(end 138.292586 -237.532926)
		(width 0.088646)
		(layer "F.Cu")
		(net "M_E_CPU1_SB_DQ<12>")
	)
	(segment
		(start 137.876026 -237.266226)
		(end 138.028426 -237.266226)
		(width 0.088646)
		(layer "F.Cu")
		(net "M_E_CPU1_SB_DQ<12>")
	)
	(segment
		(start 141.103096 -236.298486)
		(end 141.816582 -236.298486)
		(width 0.1016)
		(layer "F.Cu")
		(net "M_E_CPU1_SB_DQ<12>")
	)
	(segment
		(start 156.151326 -216.866724)
		(end 158.813246 -216.866724)
		(width 0.20066)
		(layer "F.Cu")
		(net "M_E_CPU1_SB_DQ<12>")
	)
	(segment
		(start 138.337798 -237.529116)
		(end 138.488928 -237.5027)
		(width 0.088646)
		(layer "F.Cu")
		(net "M_E_CPU1_SB_DQ<12>")
	)
	(segment
		(start 150.712424 -223.206818)
		(end 150.712424 -222.922846)
		(width 0.20066)
		(layer "F.Cu")
		(net "M_E_CPU1_SB_DQ<12>")
	)
	(segment
		(start 151.50973 -223.09582)
		(end 151.197564 -223.407986)
		(width 0.20066)
		(layer "F.Cu")
		(net "M_E_CPU1_SB_DQ<12>")
	)
	(segment
		(start 161.891726 -216.428066)
		(end 161.349182 -216.428066)
		(width 0.20066)
		(layer "F.Cu")
		(net "M_E_CPU1_SB_DQ<12>")
	)
	(segment
		(start 166.357046 -216.866724)
		(end 164.901118 -216.866724)
		(width 0.20066)
		(layer "F.Cu")
		(net "M_E_CPU1_SB_DQ<12>")
	)
	(segment
		(start 140.64996 -236.298486)
		(end 141.103096 -236.298486)
		(width 0.088646)
		(layer "F.Cu")
		(net "M_E_CPU1_SB_DQ<12>")
	)
	(segment
		(start 163.923726 -216.42451)
		(end 163.906454 -216.441782)
		(width 0.101854)
		(layer "F.Cu")
		(net "M_E_CPU1_SB_DQ<12>")
	)
	(segment
		(start 151.793702 -223.09582)
		(end 151.50973 -223.09582)
		(width 0.20066)
		(layer "F.Cu")
		(net "M_E_CPU1_SB_DQ<12>")
	)
	(segment
		(start 161.924492 -216.428066)
		(end 161.891726 -216.428066)
		(width 0.101854)
		(layer "F.Cu")
		(net "M_E_CPU1_SB_DQ<12>")
	)
	(segment
		(start 160.76168 -217.095832)
		(end 160.532572 -216.866724)
		(width 0.20066)
		(layer "F.Cu")
		(net "M_E_CPU1_SB_DQ<12>")
	)
	(segment
		(start 151.99487 -223.58096)
		(end 151.99487 -223.296988)
		(width 0.20066)
		(layer "F.Cu")
		(net "M_E_CPU1_SB_DQ<12>")
	)
	(segment
		(start 138.142726 -237.380526)
		(end 138.142726 -237.456726)
		(width 0.088646)
		(layer "F.Cu")
		(net "M_E_CPU1_SB_DQ<12>")
	)
	(segment
		(start 160.532572 -216.866724)
		(end 158.813246 -216.866724)
		(width 0.20066)
		(layer "F.Cu")
		(net "M_E_CPU1_SB_DQ<12>")
	)
	(segment
		(start 151.995124 -221.022926)
		(end 156.151326 -216.866724)
		(width 0.20066)
		(layer "F.Cu")
		(net "M_E_CPU1_SB_DQ<12>")
	)
	(segment
		(start 139.549378 -237.39856)
		(end 140.649706 -236.298232)
		(width 0.088646)
		(layer "F.Cu")
		(net "M_E_CPU1_SB_DQ<12>")
	)
	(segment
		(start 137.700512 -237.562644)
		(end 137.749026 -237.51413)
		(width 0.088646)
		(layer "F.Cu")
		(net "M_E_CPU1_SB_DQ<12>")
	)
	(segment
		(start 161.938208 -216.441782)
		(end 161.924492 -216.428066)
		(width 0.1016)
		(layer "F.Cu")
		(net "M_E_CPU1_SB_DQ<12>")
	)
	(segment
		(start 161.148268 -216.925398)
		(end 160.977834 -217.095832)
		(width 0.20066)
		(layer "F.Cu")
		(net "M_E_CPU1_SB_DQ<12>")
	)
	(segment
		(start 148.444712 -226.882706)
		(end 149.344634 -225.982784)
		(width 0.1016)
		(layer "F.Cu")
		(net "M_E_CPU1_SB_DQ<12>")
	)
	(segment
		(start 164.458904 -216.42451)
		(end 163.923726 -216.42451)
		(width 0.20066)
		(layer "F.Cu")
		(net "M_E_CPU1_SB_DQ<12>")
	)
	(segment
		(start 137.749026 -237.51413)
		(end 137.749026 -237.393226)
		(width 0.088646)
		(layer "F.Cu")
		(net "M_E_CPU1_SB_DQ<12>")
	)
	(segment
		(start 151.223726 -222.411544)
		(end 151.794464 -222.411544)
		(width 0.20066)
		(layer "F.Cu")
		(net "M_E_CPU1_SB_DQ<12>")
	)
	(segment
		(start 141.816582 -236.298486)
		(end 148.444712 -229.670356)
		(width 0.1016)
		(layer "F.Cu")
		(net "M_E_CPU1_SB_DQ<12>")
	)
	(segment
		(start 140.649706 -236.298232)
		(end 140.64996 -236.298486)
		(width 0.088646)
		(layer "F.Cu")
		(net "M_E_CPU1_SB_DQ<12>")
	)
	(arc
		(start 138.292586 -237.532926)
		(mid 138.315272 -237.531973)
		(end 138.337798 -237.529116)
		(width 0.088646)
		(layer "F.Cu")
		(net "M_E_CPU1_SB_DQ<12>")
	)
	(arc
		(start 138.488928 -237.5027)
		(mid 138.597193 -237.466132)
		(end 138.689334 -237.39856)
		(width 0.088646)
		(layer "F.Cu")
		(net "M_E_CPU1_SB_DQ<12>")
	)
	(arc
		(start 137.616946 -237.588806)
		(mid 137.660716 -237.582074)
		(end 137.700512 -237.562644)
		(width 0.088646)
		(layer "F.Cu")
		(net "M_E_CPU1_SB_DQ<12>")
	)
	(arc
		(start 136.545066 -237.133892)
		(mid 136.930971 -237.273643)
		(end 137.297668 -237.457996)
		(width 0.088646)
		(layer "F.Cu")
		(net "M_E_CPU1_SB_DQ<12>")
	)
	(arc
		(start 137.456418 -237.549944)
		(mid 137.5265 -237.578955)
		(end 137.601706 -237.588806)
		(width 0.088646)
		(layer "F.Cu")
		(net "M_E_CPU1_SB_DQ<12>")
	)
	(segment
		(start 154.632406 -227.241608)
		(end 155.145232 -226.728782)
		(width 0.20066)
		(layer "F.Cu")
		(net "M_E_CPU1_SB_DQ<11>")
	)
	(segment
		(start 165.360096 -220.69171)
		(end 165.345618 -220.706188)
		(width 0.1016)
		(layer "F.Cu")
		(net "M_E_CPU1_SB_DQ<11>")
	)
	(segment
		(start 150.070566 -229.774496)
		(end 150.462996 -229.382066)
		(width 0.1016)
		(layer "F.Cu")
		(net "M_E_CPU1_SB_DQ<11>")
	)
	(segment
		(start 157.809692 -220.69171)
		(end 159.813752 -220.69171)
		(width 0.1016)
		(layer "F.Cu")
		(net "M_E_CPU1_SB_DQ<11>")
	)
	(segment
		(start 152.893014 -228.697028)
		(end 152.646888 -228.450902)
		(width 0.20066)
		(layer "F.Cu")
		(net "M_E_CPU1_SB_DQ<11>")
	)
	(segment
		(start 152.848056 -227.965762)
		(end 153.132028 -227.965762)
		(width 0.20066)
		(layer "F.Cu")
		(net "M_E_CPU1_SB_DQ<11>")
	)
	(segment
		(start 160.733232 -220.266768)
		(end 162.913314 -220.266768)
		(width 0.20066)
		(layer "F.Cu")
		(net "M_E_CPU1_SB_DQ<11>")
	)
	(segment
		(start 154.348434 -227.241608)
		(end 154.632406 -227.241608)
		(width 0.20066)
		(layer "F.Cu")
		(net "M_E_CPU1_SB_DQ<11>")
	)
	(segment
		(start 139.836906 -238.76381)
		(end 140.77823 -237.822486)
		(width 0.088646)
		(layer "F.Cu")
		(net "M_E_CPU1_SB_DQ<11>")
	)
	(segment
		(start 167.315896 -220.69171)
		(end 165.360096 -220.69171)
		(width 0.1016)
		(layer "F.Cu")
		(net "M_E_CPU1_SB_DQ<11>")
	)
	(segment
		(start 153.863294 -227.726748)
		(end 153.617168 -227.480622)
		(width 0.20066)
		(layer "F.Cu")
		(net "M_E_CPU1_SB_DQ<11>")
	)
	(segment
		(start 152.893014 -228.981)
		(end 152.893014 -228.697028)
		(width 0.20066)
		(layer "F.Cu")
		(net "M_E_CPU1_SB_DQ<11>")
	)
	(segment
		(start 159.813752 -220.69171)
		(end 159.823658 -220.701616)
		(width 0.1016)
		(layer "F.Cu")
		(net "M_E_CPU1_SB_DQ<11>")
	)
	(segment
		(start 153.818336 -226.995482)
		(end 154.102308 -226.995482)
		(width 0.20066)
		(layer "F.Cu")
		(net "M_E_CPU1_SB_DQ<11>")
	)
	(segment
		(start 155.145232 -222.83801)
		(end 157.278324 -220.704918)
		(width 0.20066)
		(layer "F.Cu")
		(net "M_E_CPU1_SB_DQ<11>")
	)
	(segment
		(start 165.345618 -220.706188)
		(end 165.335458 -220.706188)
		(width 0.101854)
		(layer "F.Cu")
		(net "M_E_CPU1_SB_DQ<11>")
	)
	(segment
		(start 165.335458 -220.706188)
		(end 164.812726 -220.706188)
		(width 0.20066)
		(layer "F.Cu")
		(net "M_E_CPU1_SB_DQ<11>")
	)
	(segment
		(start 154.102308 -226.995482)
		(end 154.348434 -227.241608)
		(width 0.20066)
		(layer "F.Cu")
		(net "M_E_CPU1_SB_DQ<11>")
	)
	(segment
		(start 153.662126 -228.211888)
		(end 153.863294 -228.01072)
		(width 0.20066)
		(layer "F.Cu")
		(net "M_E_CPU1_SB_DQ<11>")
	)
	(segment
		(start 168.265348 -220.537024)
		(end 168.091866 -220.710506)
		(width 0.20066)
		(layer "F.Cu")
		(net "M_E_CPU1_SB_DQ<11>")
	)
	(segment
		(start 138.426952 -238.76381)
		(end 139.836906 -238.76381)
		(width 0.088646)
		(layer "F.Cu")
		(net "M_E_CPU1_SB_DQ<11>")
	)
	(segment
		(start 157.278324 -220.704918)
		(end 157.791658 -220.704918)
		(width 0.20066)
		(layer "F.Cu")
		(net "M_E_CPU1_SB_DQ<11>")
	)
	(segment
		(start 152.646888 -228.450902)
		(end 152.646888 -228.16693)
		(width 0.20066)
		(layer "F.Cu")
		(net "M_E_CPU1_SB_DQ<11>")
	)
	(segment
		(start 169.135552 -220.266768)
		(end 168.883584 -220.0148)
		(width 0.20066)
		(layer "F.Cu")
		(net "M_E_CPU1_SB_DQ<11>")
	)
	(segment
		(start 152.491948 -229.382066)
		(end 152.893014 -228.981)
		(width 0.20066)
		(layer "F.Cu")
		(net "M_E_CPU1_SB_DQ<11>")
	)
	(segment
		(start 140.950696 -237.822486)
		(end 142.449042 -237.822486)
		(width 0.1016)
		(layer "F.Cu")
		(net "M_E_CPU1_SB_DQ<11>")
	)
	(segment
		(start 160.298384 -220.701616)
		(end 160.733232 -220.266768)
		(width 0.20066)
		(layer "F.Cu")
		(net "M_E_CPU1_SB_DQ<11>")
	)
	(segment
		(start 153.617168 -227.480622)
		(end 153.617168 -227.19665)
		(width 0.20066)
		(layer "F.Cu")
		(net "M_E_CPU1_SB_DQ<11>")
	)
	(segment
		(start 153.617168 -227.19665)
		(end 153.818336 -226.995482)
		(width 0.20066)
		(layer "F.Cu")
		(net "M_E_CPU1_SB_DQ<11>")
	)
	(segment
		(start 168.499536 -220.0148)
		(end 168.265348 -220.248988)
		(width 0.20066)
		(layer "F.Cu")
		(net "M_E_CPU1_SB_DQ<11>")
	)
	(segment
		(start 138.424666 -238.761524)
		(end 138.426952 -238.76381)
		(width 0.088646)
		(layer "F.Cu")
		(net "M_E_CPU1_SB_DQ<11>")
	)
	(segment
		(start 150.462996 -229.382066)
		(end 151.237442 -229.382066)
		(width 0.1016)
		(layer "F.Cu")
		(net "M_E_CPU1_SB_DQ<11>")
	)
	(segment
		(start 152.646888 -228.16693)
		(end 152.848056 -227.965762)
		(width 0.20066)
		(layer "F.Cu")
		(net "M_E_CPU1_SB_DQ<11>")
	)
	(segment
		(start 151.237442 -229.382066)
		(end 152.491948 -229.382066)
		(width 0.20066)
		(layer "F.Cu")
		(net "M_E_CPU1_SB_DQ<11>")
	)
	(segment
		(start 142.449042 -237.822486)
		(end 150.070566 -230.200962)
		(width 0.1016)
		(layer "F.Cu")
		(net "M_E_CPU1_SB_DQ<11>")
	)
	(segment
		(start 153.132028 -227.965762)
		(end 153.378154 -228.211888)
		(width 0.20066)
		(layer "F.Cu")
		(net "M_E_CPU1_SB_DQ<11>")
	)
	(segment
		(start 168.883584 -220.0148)
		(end 168.499536 -220.0148)
		(width 0.20066)
		(layer "F.Cu")
		(net "M_E_CPU1_SB_DQ<11>")
	)
	(segment
		(start 155.145232 -226.728782)
		(end 155.145232 -222.83801)
		(width 0.20066)
		(layer "F.Cu")
		(net "M_E_CPU1_SB_DQ<11>")
	)
	(segment
		(start 168.091866 -220.710506)
		(end 167.367458 -220.710506)
		(width 0.20066)
		(layer "F.Cu")
		(net "M_E_CPU1_SB_DQ<11>")
	)
	(segment
		(start 159.823658 -220.701616)
		(end 160.298384 -220.701616)
		(width 0.20066)
		(layer "F.Cu")
		(net "M_E_CPU1_SB_DQ<11>")
	)
	(segment
		(start 157.791658 -220.704918)
		(end 157.796484 -220.704918)
		(width 0.101854)
		(layer "F.Cu")
		(net "M_E_CPU1_SB_DQ<11>")
	)
	(segment
		(start 164.812726 -220.706188)
		(end 164.373306 -220.266768)
		(width 0.20066)
		(layer "F.Cu")
		(net "M_E_CPU1_SB_DQ<11>")
	)
	(segment
		(start 164.373306 -220.266768)
		(end 162.913314 -220.266768)
		(width 0.20066)
		(layer "F.Cu")
		(net "M_E_CPU1_SB_DQ<11>")
	)
	(segment
		(start 153.378154 -228.211888)
		(end 153.662126 -228.211888)
		(width 0.20066)
		(layer "F.Cu")
		(net "M_E_CPU1_SB_DQ<11>")
	)
	(segment
		(start 150.070566 -230.200962)
		(end 150.070566 -229.774496)
		(width 0.1016)
		(layer "F.Cu")
		(net "M_E_CPU1_SB_DQ<11>")
	)
	(segment
		(start 140.77823 -237.822486)
		(end 140.950696 -237.822486)
		(width 0.088646)
		(layer "F.Cu")
		(net "M_E_CPU1_SB_DQ<11>")
	)
	(segment
		(start 157.796484 -220.704918)
		(end 157.809692 -220.69171)
		(width 0.1016)
		(layer "F.Cu")
		(net "M_E_CPU1_SB_DQ<11>")
	)
	(segment
		(start 168.265348 -220.248988)
		(end 168.265348 -220.537024)
		(width 0.20066)
		(layer "F.Cu")
		(net "M_E_CPU1_SB_DQ<11>")
	)
	(segment
		(start 153.863294 -228.01072)
		(end 153.863294 -227.726748)
		(width 0.20066)
		(layer "F.Cu")
		(net "M_E_CPU1_SB_DQ<11>")
	)
	(segment
		(start 167.334692 -220.710506)
		(end 167.315896 -220.69171)
		(width 0.101854)
		(layer "F.Cu")
		(net "M_E_CPU1_SB_DQ<11>")
	)
	(segment
		(start 170.457114 -220.266768)
		(end 169.135552 -220.266768)
		(width 0.20066)
		(layer "F.Cu")
		(net "M_E_CPU1_SB_DQ<11>")
	)
	(segment
		(start 167.367458 -220.710506)
		(end 167.334692 -220.710506)
		(width 0.101854)
		(layer "F.Cu")
		(net "M_E_CPU1_SB_DQ<11>")
	)
	(segment
		(start 167.334692 -222.410528)
		(end 167.315896 -222.391732)
		(width 0.101854)
		(layer "F.Cu")
		(net "M_E_CPU1_SB_DQ<10>")
	)
	(segment
		(start 138.895582 -239.200436)
		(end 139.259818 -239.200436)
		(width 0.088646)
		(layer "F.Cu")
		(net "M_E_CPU1_SB_DQ<10>")
	)
	(segment
		(start 170.457114 -221.96679)
		(end 169.135552 -221.96679)
		(width 0.20066)
		(layer "F.Cu")
		(net "M_E_CPU1_SB_DQ<10>")
	)
	(segment
		(start 168.265348 -221.94901)
		(end 168.265348 -222.237046)
		(width 0.20066)
		(layer "F.Cu")
		(net "M_E_CPU1_SB_DQ<10>")
	)
	(segment
		(start 156.459682 -229.763574)
		(end 156.459682 -223.378268)
		(width 0.20066)
		(layer "F.Cu")
		(net "M_E_CPU1_SB_DQ<10>")
	)
	(segment
		(start 165.360096 -222.391732)
		(end 165.345618 -222.40621)
		(width 0.1016)
		(layer "F.Cu")
		(net "M_E_CPU1_SB_DQ<10>")
	)
	(segment
		(start 169.135552 -221.96679)
		(end 168.883584 -221.714822)
		(width 0.20066)
		(layer "F.Cu")
		(net "M_E_CPU1_SB_DQ<10>")
	)
	(segment
		(start 157.8102 -222.391732)
		(end 159.815022 -222.391732)
		(width 0.1016)
		(layer "F.Cu")
		(net "M_E_CPU1_SB_DQ<10>")
	)
	(segment
		(start 140.842492 -238.432086)
		(end 140.950696 -238.432086)
		(width 0.088646)
		(layer "F.Cu")
		(net "M_E_CPU1_SB_DQ<10>")
	)
	(segment
		(start 168.883584 -221.714822)
		(end 168.499536 -221.714822)
		(width 0.20066)
		(layer "F.Cu")
		(net "M_E_CPU1_SB_DQ<10>")
	)
	(segment
		(start 157.432502 -222.405448)
		(end 157.791658 -222.405448)
		(width 0.20066)
		(layer "F.Cu")
		(net "M_E_CPU1_SB_DQ<10>")
	)
	(segment
		(start 151.135842 -230.74122)
		(end 153.797762 -230.74122)
		(width 0.20066)
		(layer "F.Cu")
		(net "M_E_CPU1_SB_DQ<10>")
	)
	(segment
		(start 150.394416 -230.74122)
		(end 151.135842 -230.74122)
		(width 0.1016)
		(layer "F.Cu")
		(net "M_E_CPU1_SB_DQ<10>")
	)
	(segment
		(start 139.549632 -239.49025)
		(end 139.784328 -239.49025)
		(width 0.088646)
		(layer "F.Cu")
		(net "M_E_CPU1_SB_DQ<10>")
	)
	(segment
		(start 157.796484 -222.405448)
		(end 157.8102 -222.391732)
		(width 0.1016)
		(layer "F.Cu")
		(net "M_E_CPU1_SB_DQ<10>")
	)
	(segment
		(start 167.315896 -222.391732)
		(end 165.360096 -222.391732)
		(width 0.1016)
		(layer "F.Cu")
		(net "M_E_CPU1_SB_DQ<10>")
	)
	(segment
		(start 165.335458 -222.40621)
		(end 165.001702 -222.40621)
		(width 0.20066)
		(layer "F.Cu")
		(net "M_E_CPU1_SB_DQ<10>")
	)
	(segment
		(start 159.823658 -222.400368)
		(end 160.564322 -222.400368)
		(width 0.20066)
		(layer "F.Cu")
		(net "M_E_CPU1_SB_DQ<10>")
	)
	(segment
		(start 165.001702 -222.40621)
		(end 164.562282 -221.96679)
		(width 0.20066)
		(layer "F.Cu")
		(net "M_E_CPU1_SB_DQ<10>")
	)
	(segment
		(start 153.797762 -230.74122)
		(end 154.461464 -231.404922)
		(width 0.20066)
		(layer "F.Cu")
		(net "M_E_CPU1_SB_DQ<10>")
	)
	(segment
		(start 139.784328 -239.49025)
		(end 140.842492 -238.432086)
		(width 0.088646)
		(layer "F.Cu")
		(net "M_E_CPU1_SB_DQ<10>")
	)
	(segment
		(start 137.954766 -239.57534)
		(end 138.203432 -239.326674)
		(width 0.088646)
		(layer "F.Cu")
		(net "M_E_CPU1_SB_DQ<10>")
	)
	(segment
		(start 165.345618 -222.40621)
		(end 165.335458 -222.40621)
		(width 0.101854)
		(layer "F.Cu")
		(net "M_E_CPU1_SB_DQ<10>")
	)
	(segment
		(start 154.461464 -231.404922)
		(end 154.818334 -231.404922)
		(width 0.20066)
		(layer "F.Cu")
		(net "M_E_CPU1_SB_DQ<10>")
	)
	(segment
		(start 160.564322 -222.400368)
		(end 160.9979 -221.96679)
		(width 0.20066)
		(layer "F.Cu")
		(net "M_E_CPU1_SB_DQ<10>")
	)
	(segment
		(start 167.367458 -222.410528)
		(end 167.334692 -222.410528)
		(width 0.101854)
		(layer "F.Cu")
		(net "M_E_CPU1_SB_DQ<10>")
	)
	(segment
		(start 160.9979 -221.96679)
		(end 162.913314 -221.96679)
		(width 0.20066)
		(layer "F.Cu")
		(net "M_E_CPU1_SB_DQ<10>")
	)
	(segment
		(start 154.818334 -231.404922)
		(end 156.459682 -229.763574)
		(width 0.20066)
		(layer "F.Cu")
		(net "M_E_CPU1_SB_DQ<10>")
	)
	(segment
		(start 140.950696 -238.432086)
		(end 142.70355 -238.432086)
		(width 0.1016)
		(layer "F.Cu")
		(net "M_E_CPU1_SB_DQ<10>")
	)
	(segment
		(start 139.259818 -239.200436)
		(end 139.549632 -239.49025)
		(width 0.088646)
		(layer "F.Cu")
		(net "M_E_CPU1_SB_DQ<10>")
	)
	(segment
		(start 168.499536 -221.714822)
		(end 168.265348 -221.94901)
		(width 0.20066)
		(layer "F.Cu")
		(net "M_E_CPU1_SB_DQ<10>")
	)
	(segment
		(start 138.203432 -239.326674)
		(end 138.426698 -239.326674)
		(width 0.088646)
		(layer "F.Cu")
		(net "M_E_CPU1_SB_DQ<10>")
	)
	(segment
		(start 156.459682 -223.378268)
		(end 157.432502 -222.405448)
		(width 0.20066)
		(layer "F.Cu")
		(net "M_E_CPU1_SB_DQ<10>")
	)
	(segment
		(start 157.791658 -222.405448)
		(end 157.796484 -222.405448)
		(width 0.101854)
		(layer "F.Cu")
		(net "M_E_CPU1_SB_DQ<10>")
	)
	(segment
		(start 164.562282 -221.96679)
		(end 162.913314 -221.96679)
		(width 0.20066)
		(layer "F.Cu")
		(net "M_E_CPU1_SB_DQ<10>")
	)
	(segment
		(start 142.70355 -238.432086)
		(end 150.394416 -230.74122)
		(width 0.1016)
		(layer "F.Cu")
		(net "M_E_CPU1_SB_DQ<10>")
	)
	(segment
		(start 168.265348 -222.237046)
		(end 168.091866 -222.410528)
		(width 0.20066)
		(layer "F.Cu")
		(net "M_E_CPU1_SB_DQ<10>")
	)
	(segment
		(start 159.815022 -222.391732)
		(end 159.823658 -222.400368)
		(width 0.1016)
		(layer "F.Cu")
		(net "M_E_CPU1_SB_DQ<10>")
	)
	(segment
		(start 168.091866 -222.410528)
		(end 167.367458 -222.410528)
		(width 0.20066)
		(layer "F.Cu")
		(net "M_E_CPU1_SB_DQ<10>")
	)
	(arc
		(start 138.426698 -239.326674)
		(mid 138.569965 -239.307947)
		(end 138.703812 -239.253522)
		(width 0.088646)
		(layer "F.Cu")
		(net "M_E_CPU1_SB_DQ<10>")
	)
	(arc
		(start 138.703812 -239.253522)
		(mid 138.796112 -239.214034)
		(end 138.895582 -239.200436)
		(width 0.088646)
		(layer "F.Cu")
		(net "M_E_CPU1_SB_DQ<10>")
	)
	(segment
		(start 161.755582 -231.741726)
		(end 161.708592 -231.741726)
		(width 0.101854)
		(layer "F.Cu")
		(net "M_E_CPU1_SB_DQ<0>")
	)
	(segment
		(start 160.333944 -232.166668)
		(end 158.813246 -232.166668)
		(width 0.20066)
		(layer "F.Cu")
		(net "M_E_CPU1_SB_DQ<0>")
	)
	(segment
		(start 161.057844 -232.381298)
		(end 160.548574 -232.381298)
		(width 0.20066)
		(layer "F.Cu")
		(net "M_E_CPU1_SB_DQ<0>")
	)
	(segment
		(start 161.245804 -231.859836)
		(end 161.245804 -232.193338)
		(width 0.20066)
		(layer "F.Cu")
		(net "M_E_CPU1_SB_DQ<0>")
	)
	(segment
		(start 164.340032 -231.741726)
		(end 164.133276 -231.741726)
		(width 0.20066)
		(layer "F.Cu")
		(net "M_E_CPU1_SB_DQ<0>")
	)
	(segment
		(start 164.765228 -232.166922)
		(end 164.340032 -231.741726)
		(width 0.20066)
		(layer "F.Cu")
		(net "M_E_CPU1_SB_DQ<0>")
	)
	(segment
		(start 161.245804 -232.193338)
		(end 161.057844 -232.381298)
		(width 0.20066)
		(layer "F.Cu")
		(net "M_E_CPU1_SB_DQ<0>")
	)
	(segment
		(start 166.357046 -232.166668)
		(end 166.356792 -232.166922)
		(width 0.20066)
		(layer "F.Cu")
		(net "M_E_CPU1_SB_DQ<0>")
	)
	(segment
		(start 164.133276 -231.741726)
		(end 163.917376 -231.741726)
		(width 0.101854)
		(layer "F.Cu")
		(net "M_E_CPU1_SB_DQ<0>")
	)
	(segment
		(start 161.708592 -231.741726)
		(end 161.363914 -231.741726)
		(width 0.20066)
		(layer "F.Cu")
		(net "M_E_CPU1_SB_DQ<0>")
	)
	(segment
		(start 133.725666 -237.133892)
		(end 133.725666 -236.597952)
		(width 0.20066)
		(layer "F.Cu")
		(net "M_E_CPU1_SB_DQ<0>")
	)
	(segment
		(start 161.363914 -231.741726)
		(end 161.245804 -231.859836)
		(width 0.20066)
		(layer "F.Cu")
		(net "M_E_CPU1_SB_DQ<0>")
	)
	(segment
		(start 166.356792 -232.166922)
		(end 164.765228 -232.166922)
		(width 0.20066)
		(layer "F.Cu")
		(net "M_E_CPU1_SB_DQ<0>")
	)
	(segment
		(start 163.917376 -231.741726)
		(end 161.755582 -231.741726)
		(width 0.1016)
		(layer "F.Cu")
		(net "M_E_CPU1_SB_DQ<0>")
	)
	(segment
		(start 160.548574 -232.381298)
		(end 160.333944 -232.166668)
		(width 0.20066)
		(layer "F.Cu")
		(net "M_E_CPU1_SB_DQ<0>")
	)
	(segment
		(start 157.682946 -232.166668)
		(end 158.813246 -232.166668)
		(width 0.20066)
		(layer "F.Cu")
		(net "M_E_CPU1_SB_DQ<0>")
	)
	(segment
		(start 152.080468 -237.196884)
		(end 151.452326 -236.568742)
		(width 0.18288)
		(layer "In2.Cu")
		(net "M_E_CPU1_SB_DQ<0>")
	)
	(segment
		(start 152.443434 -236.35589)
		(end 152.682702 -236.595158)
		(width 0.18288)
		(layer "In2.Cu")
		(net "M_E_CPU1_SB_DQ<0>")
	)
	(segment
		(start 154.43581 -234.090718)
		(end 154.43581 -234.363514)
		(width 0.18288)
		(layer "In2.Cu")
		(net "M_E_CPU1_SB_DQ<0>")
	)
	(segment
		(start 153.67889 -235.871766)
		(end 153.453592 -236.097064)
		(width 0.18288)
		(layer "In2.Cu")
		(net "M_E_CPU1_SB_DQ<0>")
	)
	(segment
		(start 152.682702 -236.867954)
		(end 152.353772 -237.196884)
		(width 0.18288)
		(layer "In2.Cu")
		(net "M_E_CPU1_SB_DQ<0>")
	)
	(segment
		(start 136.277096 -237.096046)
		(end 136.262364 -237.08741)
		(width 0.088646)
		(layer "In2.Cu")
		(net "M_E_CPU1_SB_DQ<0>")
	)
	(segment
		(start 149.98573 -237.217712)
		(end 140.359892 -237.217712)
		(width 0.18288)
		(layer "In2.Cu")
		(net "M_E_CPU1_SB_DQ<0>")
	)
	(segment
		(start 152.682702 -236.595158)
		(end 152.682702 -236.867954)
		(width 0.18288)
		(layer "In2.Cu")
		(net "M_E_CPU1_SB_DQ<0>")
	)
	(segment
		(start 154.661108 -233.86542)
		(end 154.43581 -234.090718)
		(width 0.18288)
		(layer "In2.Cu")
		(net "M_E_CPU1_SB_DQ<0>")
	)
	(segment
		(start 151.452326 -236.568742)
		(end 150.88997 -236.568742)
		(width 0.18288)
		(layer "In2.Cu")
		(net "M_E_CPU1_SB_DQ<0>")
	)
	(segment
		(start 156.619448 -232.199942)
		(end 156.619448 -232.931208)
		(width 0.18288)
		(layer "In2.Cu")
		(net "M_E_CPU1_SB_DQ<0>")
	)
	(segment
		(start 154.43581 -234.363514)
		(end 154.675078 -234.602782)
		(width 0.18288)
		(layer "In2.Cu")
		(net "M_E_CPU1_SB_DQ<0>")
	)
	(segment
		(start 140.088366 -237.489238)
		(end 139.680696 -237.489238)
		(width 0.18288)
		(layer "In2.Cu")
		(net "M_E_CPU1_SB_DQ<0>")
	)
	(segment
		(start 154.675078 -234.875578)
		(end 154.44978 -235.100876)
		(width 0.18288)
		(layer "In2.Cu")
		(net "M_E_CPU1_SB_DQ<0>")
	)
	(segment
		(start 152.941528 -235.857796)
		(end 152.668732 -235.857796)
		(width 0.18288)
		(layer "In2.Cu")
		(net "M_E_CPU1_SB_DQ<0>")
	)
	(segment
		(start 155.445968 -234.104688)
		(end 155.173172 -234.104688)
		(width 0.18288)
		(layer "In2.Cu")
		(net "M_E_CPU1_SB_DQ<0>")
	)
	(segment
		(start 157.429962 -231.662478)
		(end 157.156912 -231.662478)
		(width 0.18288)
		(layer "In2.Cu")
		(net "M_E_CPU1_SB_DQ<0>")
	)
	(segment
		(start 139.680696 -237.489238)
		(end 139.000738 -237.489238)
		(width 0.088646)
		(layer "In2.Cu")
		(net "M_E_CPU1_SB_DQ<0>")
	)
	(segment
		(start 157.156912 -231.662478)
		(end 156.619448 -232.199942)
		(width 0.18288)
		(layer "In2.Cu")
		(net "M_E_CPU1_SB_DQ<0>")
	)
	(segment
		(start 152.353772 -237.196884)
		(end 152.080468 -237.196884)
		(width 0.18288)
		(layer "In2.Cu")
		(net "M_E_CPU1_SB_DQ<0>")
	)
	(segment
		(start 134.038594 -236.597952)
		(end 133.725666 -236.597952)
		(width 0.088646)
		(layer "In2.Cu")
		(net "M_E_CPU1_SB_DQ<0>")
	)
	(segment
		(start 154.675078 -234.602782)
		(end 154.675078 -234.875578)
		(width 0.18288)
		(layer "In2.Cu")
		(net "M_E_CPU1_SB_DQ<0>")
	)
	(segment
		(start 153.180796 -236.097064)
		(end 152.941528 -235.857796)
		(width 0.18288)
		(layer "In2.Cu")
		(net "M_E_CPU1_SB_DQ<0>")
	)
	(segment
		(start 154.44978 -235.100876)
		(end 154.176984 -235.100876)
		(width 0.18288)
		(layer "In2.Cu")
		(net "M_E_CPU1_SB_DQ<0>")
	)
	(segment
		(start 135.337296 -237.096046)
		(end 135.322564 -237.08741)
		(width 0.088646)
		(layer "In2.Cu")
		(net "M_E_CPU1_SB_DQ<0>")
	)
	(segment
		(start 155.173172 -234.104688)
		(end 154.933904 -233.86542)
		(width 0.18288)
		(layer "In2.Cu")
		(net "M_E_CPU1_SB_DQ<0>")
	)
	(segment
		(start 150.454106 -236.749336)
		(end 149.98573 -237.217712)
		(width 0.18288)
		(layer "In2.Cu")
		(net "M_E_CPU1_SB_DQ<0>")
	)
	(segment
		(start 152.668732 -235.857796)
		(end 152.443434 -236.083094)
		(width 0.18288)
		(layer "In2.Cu")
		(net "M_E_CPU1_SB_DQ<0>")
	)
	(segment
		(start 154.176984 -235.100876)
		(end 153.937716 -234.861608)
		(width 0.18288)
		(layer "In2.Cu")
		(net "M_E_CPU1_SB_DQ<0>")
	)
	(segment
		(start 140.359892 -237.217712)
		(end 140.088366 -237.489238)
		(width 0.18288)
		(layer "In2.Cu")
		(net "M_E_CPU1_SB_DQ<0>")
	)
	(segment
		(start 153.439622 -235.359702)
		(end 153.67889 -235.59897)
		(width 0.18288)
		(layer "In2.Cu")
		(net "M_E_CPU1_SB_DQ<0>")
	)
	(segment
		(start 137.216896 -237.096046)
		(end 137.202164 -237.08741)
		(width 0.088646)
		(layer "In2.Cu")
		(net "M_E_CPU1_SB_DQ<0>")
	)
	(segment
		(start 152.443434 -236.083094)
		(end 152.443434 -236.35589)
		(width 0.18288)
		(layer "In2.Cu")
		(net "M_E_CPU1_SB_DQ<0>")
	)
	(segment
		(start 153.66492 -234.861608)
		(end 153.439622 -235.086906)
		(width 0.18288)
		(layer "In2.Cu")
		(net "M_E_CPU1_SB_DQ<0>")
	)
	(segment
		(start 150.88997 -236.568742)
		(end 150.454106 -236.749336)
		(width 0.18288)
		(layer "In2.Cu")
		(net "M_E_CPU1_SB_DQ<0>")
	)
	(segment
		(start 153.453592 -236.097064)
		(end 153.180796 -236.097064)
		(width 0.18288)
		(layer "In2.Cu")
		(net "M_E_CPU1_SB_DQ<0>")
	)
	(segment
		(start 153.439622 -235.086906)
		(end 153.439622 -235.359702)
		(width 0.18288)
		(layer "In2.Cu")
		(net "M_E_CPU1_SB_DQ<0>")
	)
	(segment
		(start 138.674856 -237.163356)
		(end 138.424666 -237.163356)
		(width 0.088646)
		(layer "In2.Cu")
		(net "M_E_CPU1_SB_DQ<0>")
	)
	(segment
		(start 156.619448 -232.931208)
		(end 155.445968 -234.104688)
		(width 0.18288)
		(layer "In2.Cu")
		(net "M_E_CPU1_SB_DQ<0>")
	)
	(segment
		(start 139.000738 -237.489238)
		(end 138.674856 -237.163356)
		(width 0.088646)
		(layer "In2.Cu")
		(net "M_E_CPU1_SB_DQ<0>")
	)
	(segment
		(start 134.103872 -236.66323)
		(end 134.038594 -236.597952)
		(width 0.088646)
		(layer "In2.Cu")
		(net "M_E_CPU1_SB_DQ<0>")
	)
	(segment
		(start 154.933904 -233.86542)
		(end 154.661108 -233.86542)
		(width 0.18288)
		(layer "In2.Cu")
		(net "M_E_CPU1_SB_DQ<0>")
	)
	(segment
		(start 153.937716 -234.861608)
		(end 153.66492 -234.861608)
		(width 0.18288)
		(layer "In2.Cu")
		(net "M_E_CPU1_SB_DQ<0>")
	)
	(segment
		(start 153.67889 -235.59897)
		(end 153.67889 -235.871766)
		(width 0.18288)
		(layer "In2.Cu")
		(net "M_E_CPU1_SB_DQ<0>")
	)
	(segment
		(start 157.682946 -232.166668)
		(end 157.682946 -231.915462)
		(width 0.18288)
		(layer "In2.Cu")
		(net "M_E_CPU1_SB_DQ<0>")
	)
	(segment
		(start 157.682946 -231.915462)
		(end 157.429962 -231.662478)
		(width 0.18288)
		(layer "In2.Cu")
		(net "M_E_CPU1_SB_DQ<0>")
	)
	(arc
		(start 138.424666 -237.163356)
		(mid 138.278327 -237.143963)
		(end 138.141964 -237.08741)
		(width 0.088646)
		(layer "In2.Cu")
		(net "M_E_CPU1_SB_DQ<0>")
	)
	(arc
		(start 138.141964 -237.08741)
		(mid 137.954766 -237.037233)
		(end 137.767568 -237.08741)
		(width 0.088646)
		(layer "In2.Cu")
		(net "M_E_CPU1_SB_DQ<0>")
	)
	(arc
		(start 137.202164 -237.08741)
		(mid 137.014966 -237.037233)
		(end 136.827768 -237.08741)
		(width 0.088646)
		(layer "In2.Cu")
		(net "M_E_CPU1_SB_DQ<0>")
	)
	(arc
		(start 134.382764 -237.08741)
		(mid 134.193014 -236.908396)
		(end 134.103872 -236.66323)
		(width 0.088646)
		(layer "In2.Cu")
		(net "M_E_CPU1_SB_DQ<0>")
	)
	(arc
		(start 134.948168 -237.08741)
		(mid 134.665466 -237.163186)
		(end 134.382764 -237.08741)
		(width 0.088646)
		(layer "In2.Cu")
		(net "M_E_CPU1_SB_DQ<0>")
	)
	(arc
		(start 136.827768 -237.08741)
		(mid 136.553569 -237.163245)
		(end 136.277096 -237.096046)
		(width 0.088646)
		(layer "In2.Cu")
		(net "M_E_CPU1_SB_DQ<0>")
	)
	(arc
		(start 135.322564 -237.08741)
		(mid 135.135366 -237.037233)
		(end 134.948168 -237.08741)
		(width 0.088646)
		(layer "In2.Cu")
		(net "M_E_CPU1_SB_DQ<0>")
	)
	(arc
		(start 136.262364 -237.08741)
		(mid 136.075166 -237.037233)
		(end 135.887968 -237.08741)
		(width 0.088646)
		(layer "In2.Cu")
		(net "M_E_CPU1_SB_DQ<0>")
	)
	(arc
		(start 137.767568 -237.08741)
		(mid 137.493369 -237.163245)
		(end 137.216896 -237.096046)
		(width 0.088646)
		(layer "In2.Cu")
		(net "M_E_CPU1_SB_DQ<0>")
	)
	(arc
		(start 135.887968 -237.08741)
		(mid 135.613769 -237.163245)
		(end 135.337296 -237.096046)
		(width 0.088646)
		(layer "In2.Cu")
		(net "M_E_CPU1_SB_DQ<0>")
	)
	(segment
		(start 140.315696 -245.665752)
		(end 138.5824 -245.665752)
		(width 0.088646)
		(layer "F.Cu")
		(net "M_E_CPU1_SB_CS_N<3>")
	)
	(segment
		(start 137.421366 -245.681246)
		(end 136.885426 -245.681246)
		(width 0.088646)
		(layer "F.Cu")
		(net "M_E_CPU1_SB_CS_N<3>")
	)
	(segment
		(start 160.248854 -242.81765)
		(end 159.778954 -242.81765)
		(width 0.20066)
		(layer "F.Cu")
		(net "M_E_CPU1_SB_CS_N<3>")
	)
	(segment
		(start 157.251908 -242.791742)
		(end 156.24683 -243.79682)
		(width 0.20066)
		(layer "F.Cu")
		(net "M_E_CPU1_SB_CS_N<3>")
	)
	(segment
		(start 142.626588 -245.665752)
		(end 140.315696 -245.665752)
		(width 0.1016)
		(layer "F.Cu")
		(net "M_E_CPU1_SB_CS_N<3>")
	)
	(segment
		(start 160.619186 -242.117626)
		(end 160.443926 -242.292886)
		(width 0.20066)
		(layer "F.Cu")
		(net "M_E_CPU1_SB_CS_N<3>")
	)
	(segment
		(start 157.606238 -242.791742)
		(end 157.584902 -242.791742)
		(width 0.101854)
		(layer "F.Cu")
		(net "M_E_CPU1_SB_CS_N<3>")
	)
	(segment
		(start 136.661906 -245.904766)
		(end 136.545066 -246.367046)
		(width 0.088646)
		(layer "F.Cu")
		(net "M_E_CPU1_SB_CS_N<3>")
	)
	(segment
		(start 160.443926 -242.622578)
		(end 160.248854 -242.81765)
		(width 0.20066)
		(layer "F.Cu")
		(net "M_E_CPU1_SB_CS_N<3>")
	)
	(segment
		(start 150.810468 -242.977924)
		(end 145.314416 -242.977924)
		(width 0.20066)
		(layer "F.Cu")
		(net "M_E_CPU1_SB_CS_N<3>")
	)
	(segment
		(start 137.672064 -245.596918)
		(end 137.616438 -245.628922)
		(width 0.088646)
		(layer "F.Cu")
		(net "M_E_CPU1_SB_CS_N<3>")
	)
	(segment
		(start 160.443926 -242.292886)
		(end 160.443926 -242.622578)
		(width 0.20066)
		(layer "F.Cu")
		(net "M_E_CPU1_SB_CS_N<3>")
	)
	(segment
		(start 156.24683 -243.79682)
		(end 155.672282 -244.034818)
		(width 0.20066)
		(layer "F.Cu")
		(net "M_E_CPU1_SB_CS_N<3>")
	)
	(segment
		(start 159.753046 -242.791742)
		(end 157.606238 -242.791742)
		(width 0.1016)
		(layer "F.Cu")
		(net "M_E_CPU1_SB_CS_N<3>")
	)
	(segment
		(start 143.131794 -245.160546)
		(end 142.626588 -245.665752)
		(width 0.1016)
		(layer "F.Cu")
		(net "M_E_CPU1_SB_CS_N<3>")
	)
	(segment
		(start 162.913314 -244.916706)
		(end 161.96183 -244.916706)
		(width 0.20066)
		(layer "F.Cu")
		(net "M_E_CPU1_SB_CS_N<3>")
	)
	(segment
		(start 161.081466 -242.117626)
		(end 160.619186 -242.117626)
		(width 0.20066)
		(layer "F.Cu")
		(net "M_E_CPU1_SB_CS_N<3>")
	)
	(segment
		(start 151.867362 -244.034818)
		(end 150.810468 -242.977924)
		(width 0.20066)
		(layer "F.Cu")
		(net "M_E_CPU1_SB_CS_N<3>")
	)
	(segment
		(start 161.96183 -244.916706)
		(end 161.256726 -244.211602)
		(width 0.20066)
		(layer "F.Cu")
		(net "M_E_CPU1_SB_CS_N<3>")
	)
	(segment
		(start 145.314416 -242.977924)
		(end 143.131794 -245.160546)
		(width 0.20066)
		(layer "F.Cu")
		(net "M_E_CPU1_SB_CS_N<3>")
	)
	(segment
		(start 136.545066 -246.367046)
		(end 136.545066 -246.900446)
		(width 0.088646)
		(layer "F.Cu")
		(net "M_E_CPU1_SB_CS_N<3>")
	)
	(segment
		(start 159.778954 -242.81765)
		(end 159.753046 -242.791742)
		(width 0.1016)
		(layer "F.Cu")
		(net "M_E_CPU1_SB_CS_N<3>")
	)
	(segment
		(start 157.584902 -242.791742)
		(end 157.251908 -242.791742)
		(width 0.20066)
		(layer "F.Cu")
		(net "M_E_CPU1_SB_CS_N<3>")
	)
	(segment
		(start 161.256726 -244.211602)
		(end 161.256726 -242.292886)
		(width 0.20066)
		(layer "F.Cu")
		(net "M_E_CPU1_SB_CS_N<3>")
	)
	(segment
		(start 155.672282 -244.034818)
		(end 151.867362 -244.034818)
		(width 0.20066)
		(layer "F.Cu")
		(net "M_E_CPU1_SB_CS_N<3>")
	)
	(segment
		(start 136.885426 -245.681246)
		(end 136.661906 -245.904766)
		(width 0.088646)
		(layer "F.Cu")
		(net "M_E_CPU1_SB_CS_N<3>")
	)
	(segment
		(start 138.5824 -245.665752)
		(end 138.306556 -245.621302)
		(width 0.088646)
		(layer "F.Cu")
		(net "M_E_CPU1_SB_CS_N<3>")
	)
	(segment
		(start 161.256726 -242.292886)
		(end 161.081466 -242.117626)
		(width 0.20066)
		(layer "F.Cu")
		(net "M_E_CPU1_SB_CS_N<3>")
	)
	(arc
		(start 137.616438 -245.628922)
		(mid 137.522347 -245.667939)
		(end 137.421366 -245.681246)
		(width 0.088646)
		(layer "F.Cu")
		(net "M_E_CPU1_SB_CS_N<3>")
	)
	(arc
		(start 138.237468 -245.596918)
		(mid 137.954766 -245.521176)
		(end 137.672064 -245.596918)
		(width 0.088646)
		(layer "F.Cu")
		(net "M_E_CPU1_SB_CS_N<3>")
	)
	(arc
		(start 138.306556 -245.621302)
		(mid 138.270898 -245.612265)
		(end 138.237468 -245.596918)
		(width 0.088646)
		(layer "F.Cu")
		(net "M_E_CPU1_SB_CS_N<3>")
	)
	(segment
		(start 137.572242 -245.92661)
		(end 137.401046 -245.92661)
		(width 0.088646)
		(layer "F.Cu")
		(net "M_E_CPU1_SB_CS_N<2>")
	)
	(segment
		(start 156.892752 -245.516146)
		(end 156.586428 -245.82247)
		(width 0.20066)
		(layer "F.Cu")
		(net "M_E_CPU1_SB_CS_N<2>")
	)
	(segment
		(start 137.694416 -245.804436)
		(end 137.572242 -245.92661)
		(width 0.088646)
		(layer "F.Cu")
		(net "M_E_CPU1_SB_CS_N<2>")
	)
	(segment
		(start 158.22676 -245.76659)
		(end 157.976316 -245.516146)
		(width 0.20066)
		(layer "F.Cu")
		(net "M_E_CPU1_SB_CS_N<2>")
	)
	(segment
		(start 146.002248 -244.257068)
		(end 144.522698 -245.736618)
		(width 0.20066)
		(layer "F.Cu")
		(net "M_E_CPU1_SB_CS_N<2>")
	)
	(segment
		(start 138.680444 -246.409972)
		(end 138.574272 -246.355362)
		(width 0.088646)
		(layer "F.Cu")
		(net "M_E_CPU1_SB_CS_N<2>")
	)
	(segment
		(start 138.574272 -246.355362)
		(end 138.47191 -246.253)
		(width 0.088646)
		(layer "F.Cu")
		(net "M_E_CPU1_SB_CS_N<2>")
	)
	(segment
		(start 155.274264 -245.327932)
		(end 154.434032 -245.327932)
		(width 0.20066)
		(layer "F.Cu")
		(net "M_E_CPU1_SB_CS_N<2>")
	)
	(segment
		(start 137.401046 -245.92661)
		(end 137.014712 -246.08663)
		(width 0.088646)
		(layer "F.Cu")
		(net "M_E_CPU1_SB_CS_N<2>")
	)
	(segment
		(start 137.954766 -245.711472)
		(end 137.769854 -245.761256)
		(width 0.088646)
		(layer "F.Cu")
		(net "M_E_CPU1_SB_CS_N<2>")
	)
	(segment
		(start 153.300684 -245.327932)
		(end 152.993344 -245.327932)
		(width 0.20066)
		(layer "F.Cu")
		(net "M_E_CPU1_SB_CS_N<2>")
	)
	(segment
		(start 143.983964 -246.275352)
		(end 140.31595 -246.275352)
		(width 0.1016)
		(layer "F.Cu")
		(net "M_E_CPU1_SB_CS_N<2>")
	)
	(segment
		(start 139.616942 -246.275352)
		(end 139.449048 -246.443246)
		(width 0.088646)
		(layer "F.Cu")
		(net "M_E_CPU1_SB_CS_N<2>")
	)
	(segment
		(start 155.768802 -245.82247)
		(end 155.274264 -245.327932)
		(width 0.20066)
		(layer "F.Cu")
		(net "M_E_CPU1_SB_CS_N<2>")
	)
	(segment
		(start 156.586428 -245.82247)
		(end 155.768802 -245.82247)
		(width 0.20066)
		(layer "F.Cu")
		(net "M_E_CPU1_SB_CS_N<2>")
	)
	(segment
		(start 140.31595 -246.275352)
		(end 139.616942 -246.275352)
		(width 0.088646)
		(layer "F.Cu")
		(net "M_E_CPU1_SB_CS_N<2>")
	)
	(segment
		(start 138.47191 -246.091202)
		(end 138.142472 -245.761764)
		(width 0.088646)
		(layer "F.Cu")
		(net "M_E_CPU1_SB_CS_N<2>")
	)
	(segment
		(start 152.498806 -245.82247)
		(end 151.845772 -245.82247)
		(width 0.20066)
		(layer "F.Cu")
		(net "M_E_CPU1_SB_CS_N<2>")
	)
	(segment
		(start 138.47191 -246.253)
		(end 138.47191 -246.091202)
		(width 0.088646)
		(layer "F.Cu")
		(net "M_E_CPU1_SB_CS_N<2>")
	)
	(segment
		(start 152.993344 -245.327932)
		(end 152.498806 -245.82247)
		(width 0.20066)
		(layer "F.Cu")
		(net "M_E_CPU1_SB_CS_N<2>")
	)
	(segment
		(start 138.142472 -245.761764)
		(end 137.954766 -245.711472)
		(width 0.088646)
		(layer "F.Cu")
		(net "M_E_CPU1_SB_CS_N<2>")
	)
	(segment
		(start 154.434032 -245.327932)
		(end 154.009344 -245.75262)
		(width 0.20066)
		(layer "F.Cu")
		(net "M_E_CPU1_SB_CS_N<2>")
	)
	(segment
		(start 151.845772 -245.82247)
		(end 150.28037 -244.257068)
		(width 0.20066)
		(layer "F.Cu")
		(net "M_E_CPU1_SB_CS_N<2>")
	)
	(segment
		(start 139.449048 -246.443246)
		(end 138.81735 -246.443246)
		(width 0.088646)
		(layer "F.Cu")
		(net "M_E_CPU1_SB_CS_N<2>")
	)
	(segment
		(start 158.813246 -245.76659)
		(end 158.22676 -245.76659)
		(width 0.20066)
		(layer "F.Cu")
		(net "M_E_CPU1_SB_CS_N<2>")
	)
	(segment
		(start 144.522698 -245.736618)
		(end 143.983964 -246.275352)
		(width 0.1016)
		(layer "F.Cu")
		(net "M_E_CPU1_SB_CS_N<2>")
	)
	(segment
		(start 154.009344 -245.75262)
		(end 153.725372 -245.75262)
		(width 0.20066)
		(layer "F.Cu")
		(net "M_E_CPU1_SB_CS_N<2>")
	)
	(segment
		(start 137.769854 -245.761256)
		(end 137.694416 -245.804436)
		(width 0.088646)
		(layer "F.Cu")
		(net "M_E_CPU1_SB_CS_N<2>")
	)
	(segment
		(start 150.28037 -244.257068)
		(end 146.002248 -244.257068)
		(width 0.20066)
		(layer "F.Cu")
		(net "M_E_CPU1_SB_CS_N<2>")
	)
	(segment
		(start 157.976316 -245.516146)
		(end 156.892752 -245.516146)
		(width 0.20066)
		(layer "F.Cu")
		(net "M_E_CPU1_SB_CS_N<2>")
	)
	(segment
		(start 153.725372 -245.75262)
		(end 153.300684 -245.327932)
		(width 0.20066)
		(layer "F.Cu")
		(net "M_E_CPU1_SB_CS_N<2>")
	)
	(arc
		(start 138.81735 -246.443246)
		(mid 138.746899 -246.434819)
		(end 138.680444 -246.409972)
		(width 0.088646)
		(layer "F.Cu")
		(net "M_E_CPU1_SB_CS_N<2>")
	)
	(segment
		(start 167.33266 -244.482112)
		(end 167.323262 -244.49151)
		(width 0.1016)
		(layer "F.Cu")
		(net "M_E_CPU1_SB_CS_N<1>")
	)
	(segment
		(start 164.113718 -245.31701)
		(end 163.923726 -245.31701)
		(width 0.20066)
		(layer "F.Cu")
		(net "M_E_CPU1_SB_CS_N<1>")
	)
	(segment
		(start 168.816274 -244.916706)
		(end 168.64203 -244.742462)
		(width 0.20066)
		(layer "F.Cu")
		(net "M_E_CPU1_SB_CS_N<1>")
	)
	(segment
		(start 163.899088 -245.341648)
		(end 161.91357 -245.341648)
		(width 0.1016)
		(layer "F.Cu")
		(net "M_E_CPU1_SB_CS_N<1>")
	)
	(segment
		(start 140.315696 -245.970552)
		(end 139.389358 -245.970552)
		(width 0.088646)
		(layer "F.Cu")
		(net "M_E_CPU1_SB_CS_N<1>")
	)
	(segment
		(start 167.657526 -244.482112)
		(end 167.367458 -244.482112)
		(width 0.20066)
		(layer "F.Cu")
		(net "M_E_CPU1_SB_CS_N<1>")
	)
	(segment
		(start 167.323262 -244.49151)
		(end 165.15207 -244.49151)
		(width 0.1016)
		(layer "F.Cu")
		(net "M_E_CPU1_SB_CS_N<1>")
	)
	(segment
		(start 161.901632 -245.32971)
		(end 161.891726 -245.32971)
		(width 0.101854)
		(layer "F.Cu")
		(net "M_E_CPU1_SB_CS_N<1>")
	)
	(segment
		(start 150.545546 -243.617496)
		(end 145.586196 -243.617496)
		(width 0.20066)
		(layer "F.Cu")
		(net "M_E_CPU1_SB_CS_N<1>")
	)
	(segment
		(start 170.457114 -244.916706)
		(end 168.816274 -244.916706)
		(width 0.20066)
		(layer "F.Cu")
		(net "M_E_CPU1_SB_CS_N<1>")
	)
	(segment
		(start 161.91357 -245.341648)
		(end 161.901632 -245.32971)
		(width 0.1016)
		(layer "F.Cu")
		(net "M_E_CPU1_SB_CS_N<1>")
	)
	(segment
		(start 160.051496 -243.641626)
		(end 159.804354 -243.641626)
		(width 0.20066)
		(layer "F.Cu")
		(net "M_E_CPU1_SB_CS_N<1>")
	)
	(segment
		(start 143.23314 -245.970552)
		(end 140.315696 -245.970552)
		(width 0.1016)
		(layer "F.Cu")
		(net "M_E_CPU1_SB_CS_N<1>")
	)
	(segment
		(start 165.15207 -244.49151)
		(end 165.141656 -244.49151)
		(width 0.101854)
		(layer "F.Cu")
		(net "M_E_CPU1_SB_CS_N<1>")
	)
	(segment
		(start 164.939218 -244.49151)
		(end 164.113718 -245.31701)
		(width 0.20066)
		(layer "F.Cu")
		(net "M_E_CPU1_SB_CS_N<1>")
	)
	(segment
		(start 144.043146 -245.160546)
		(end 143.23314 -245.970552)
		(width 0.1016)
		(layer "F.Cu")
		(net "M_E_CPU1_SB_CS_N<1>")
	)
	(segment
		(start 168.64203 -244.742462)
		(end 168.64203 -243.956586)
		(width 0.20066)
		(layer "F.Cu")
		(net "M_E_CPU1_SB_CS_N<1>")
	)
	(segment
		(start 168.441116 -243.755672)
		(end 168.07053 -243.755672)
		(width 0.20066)
		(layer "F.Cu")
		(net "M_E_CPU1_SB_CS_N<1>")
	)
	(segment
		(start 163.923726 -245.31701)
		(end 163.899088 -245.341648)
		(width 0.1016)
		(layer "F.Cu")
		(net "M_E_CPU1_SB_CS_N<1>")
	)
	(segment
		(start 161.73958 -245.32971)
		(end 160.051496 -243.641626)
		(width 0.20066)
		(layer "F.Cu")
		(net "M_E_CPU1_SB_CS_N<1>")
	)
	(segment
		(start 168.07053 -243.755672)
		(end 167.86987 -243.956332)
		(width 0.20066)
		(layer "F.Cu")
		(net "M_E_CPU1_SB_CS_N<1>")
	)
	(segment
		(start 157.59557 -243.641626)
		(end 157.374336 -243.641626)
		(width 0.20066)
		(layer "F.Cu")
		(net "M_E_CPU1_SB_CS_N<1>")
	)
	(segment
		(start 165.141656 -244.49151)
		(end 164.939218 -244.49151)
		(width 0.20066)
		(layer "F.Cu")
		(net "M_E_CPU1_SB_CS_N<1>")
	)
	(segment
		(start 167.367458 -244.482112)
		(end 167.33266 -244.482112)
		(width 0.101854)
		(layer "F.Cu")
		(net "M_E_CPU1_SB_CS_N<1>")
	)
	(segment
		(start 155.839668 -244.68836)
		(end 151.61641 -244.68836)
		(width 0.20066)
		(layer "F.Cu")
		(net "M_E_CPU1_SB_CS_N<1>")
	)
	(segment
		(start 161.891726 -245.32971)
		(end 161.73958 -245.32971)
		(width 0.20066)
		(layer "F.Cu")
		(net "M_E_CPU1_SB_CS_N<1>")
	)
	(segment
		(start 139.389358 -245.970552)
		(end 139.27328 -246.08663)
		(width 0.088646)
		(layer "F.Cu")
		(net "M_E_CPU1_SB_CS_N<1>")
	)
	(segment
		(start 168.64203 -243.956586)
		(end 168.441116 -243.755672)
		(width 0.20066)
		(layer "F.Cu")
		(net "M_E_CPU1_SB_CS_N<1>")
	)
	(segment
		(start 157.374336 -243.641626)
		(end 156.672788 -244.343174)
		(width 0.20066)
		(layer "F.Cu")
		(net "M_E_CPU1_SB_CS_N<1>")
	)
	(segment
		(start 159.804354 -243.641626)
		(end 157.59557 -243.641626)
		(width 0.1016)
		(layer "F.Cu")
		(net "M_E_CPU1_SB_CS_N<1>")
	)
	(segment
		(start 167.86987 -243.956332)
		(end 167.86987 -244.269768)
		(width 0.20066)
		(layer "F.Cu")
		(net "M_E_CPU1_SB_CS_N<1>")
	)
	(segment
		(start 167.86987 -244.269768)
		(end 167.657526 -244.482112)
		(width 0.20066)
		(layer "F.Cu")
		(net "M_E_CPU1_SB_CS_N<1>")
	)
	(segment
		(start 156.672788 -244.343174)
		(end 155.839668 -244.68836)
		(width 0.20066)
		(layer "F.Cu")
		(net "M_E_CPU1_SB_CS_N<1>")
	)
	(segment
		(start 145.586196 -243.617496)
		(end 144.043146 -245.160546)
		(width 0.20066)
		(layer "F.Cu")
		(net "M_E_CPU1_SB_CS_N<1>")
	)
	(segment
		(start 151.61641 -244.68836)
		(end 150.545546 -243.617496)
		(width 0.20066)
		(layer "F.Cu")
		(net "M_E_CPU1_SB_CS_N<1>")
	)
	(segment
		(start 139.27328 -246.08663)
		(end 138.894312 -246.08663)
		(width 0.088646)
		(layer "F.Cu")
		(net "M_E_CPU1_SB_CS_N<1>")
	)
	(segment
		(start 159.76981 -246.103902)
		(end 159.68218 -246.191532)
		(width 0.1016)
		(layer "F.Cu")
		(net "M_E_CPU1_SB_CS_N<0>")
	)
	(segment
		(start 159.904684 -245.969028)
		(end 159.797496 -246.076216)
		(width 0.20066)
		(layer "F.Cu")
		(net "M_E_CPU1_SB_CS_N<0>")
	)
	(segment
		(start 160.784794 -246.828818)
		(end 160.534858 -246.578882)
		(width 0.20066)
		(layer "F.Cu")
		(net "M_E_CPU1_SB_CS_N<0>")
	)
	(segment
		(start 139.53363 -246.635778)
		(end 138.781028 -246.635778)
		(width 0.088646)
		(layer "F.Cu")
		(net "M_E_CPU1_SB_CS_N<0>")
	)
	(segment
		(start 157.85338 -246.171466)
		(end 157.791658 -246.171466)
		(width 0.101854)
		(layer "F.Cu")
		(net "M_E_CPU1_SB_CS_N<0>")
	)
	(segment
		(start 160.783778 -245.048278)
		(end 160.535874 -245.048278)
		(width 0.20066)
		(layer "F.Cu")
		(net "M_E_CPU1_SB_CS_N<0>")
	)
	(segment
		(start 151.580596 -246.462042)
		(end 150.015194 -244.89664)
		(width 0.20066)
		(layer "F.Cu")
		(net "M_E_CPU1_SB_CS_N<0>")
	)
	(segment
		(start 166.357046 -245.76659)
		(end 165.405054 -245.76659)
		(width 0.20066)
		(layer "F.Cu")
		(net "M_E_CPU1_SB_CS_N<0>")
	)
	(segment
		(start 156.85135 -246.462042)
		(end 151.580596 -246.462042)
		(width 0.20066)
		(layer "F.Cu")
		(net "M_E_CPU1_SB_CS_N<0>")
	)
	(segment
		(start 161.92119 -246.191532)
		(end 161.896552 -246.21617)
		(width 0.1016)
		(layer "F.Cu")
		(net "M_E_CPU1_SB_CS_N<0>")
	)
	(segment
		(start 146.271996 -244.89664)
		(end 144.926558 -246.242078)
		(width 0.20066)
		(layer "F.Cu")
		(net "M_E_CPU1_SB_CS_N<0>")
	)
	(segment
		(start 157.141926 -246.171466)
		(end 156.85135 -246.462042)
		(width 0.20066)
		(layer "F.Cu")
		(net "M_E_CPU1_SB_CS_N<0>")
	)
	(segment
		(start 159.904684 -245.679468)
		(end 159.904684 -245.969028)
		(width 0.20066)
		(layer "F.Cu")
		(net "M_E_CPU1_SB_CS_N<0>")
	)
	(segment
		(start 138.590274 -246.578374)
		(end 138.37158 -246.466106)
		(width 0.088646)
		(layer "F.Cu")
		(net "M_E_CPU1_SB_CS_N<0>")
	)
	(segment
		(start 160.534858 -246.578882)
		(end 160.535366 -246.277384)
		(width 0.20066)
		(layer "F.Cu")
		(net "M_E_CPU1_SB_CS_N<0>")
	)
	(segment
		(start 163.898834 -246.191532)
		(end 163.556696 -246.191532)
		(width 0.101854)
		(layer "F.Cu")
		(net "M_E_CPU1_SB_CS_N<0>")
	)
	(segment
		(start 161.891726 -246.21617)
		(end 161.681414 -246.21617)
		(width 0.20066)
		(layer "F.Cu")
		(net "M_E_CPU1_SB_CS_N<0>")
	)
	(segment
		(start 165.405054 -245.76659)
		(end 164.95522 -246.216424)
		(width 0.20066)
		(layer "F.Cu")
		(net "M_E_CPU1_SB_CS_N<0>")
	)
	(segment
		(start 161.681414 -246.21617)
		(end 161.068766 -246.828818)
		(width 0.20066)
		(layer "F.Cu")
		(net "M_E_CPU1_SB_CS_N<0>")
	)
	(segment
		(start 139.589256 -246.580152)
		(end 139.53363 -246.635778)
		(width 0.088646)
		(layer "F.Cu")
		(net "M_E_CPU1_SB_CS_N<0>")
	)
	(segment
		(start 138.37158 -246.466106)
		(end 138.043666 -246.466106)
		(width 0.088646)
		(layer "F.Cu")
		(net "M_E_CPU1_SB_CS_N<0>")
	)
	(segment
		(start 157.791658 -246.171466)
		(end 157.141926 -246.171466)
		(width 0.20066)
		(layer "F.Cu")
		(net "M_E_CPU1_SB_CS_N<0>")
	)
	(segment
		(start 160.535874 -245.048278)
		(end 159.904684 -245.679468)
		(width 0.20066)
		(layer "F.Cu")
		(net "M_E_CPU1_SB_CS_N<0>")
	)
	(segment
		(start 138.043666 -246.466106)
		(end 137.954766 -246.377206)
		(width 0.088646)
		(layer "F.Cu")
		(net "M_E_CPU1_SB_CS_N<0>")
	)
	(segment
		(start 137.954766 -246.377206)
		(end 137.954766 -246.08663)
		(width 0.088646)
		(layer "F.Cu")
		(net "M_E_CPU1_SB_CS_N<0>")
	)
	(segment
		(start 157.873446 -246.191532)
		(end 157.85338 -246.171466)
		(width 0.1016)
		(layer "F.Cu")
		(net "M_E_CPU1_SB_CS_N<0>")
	)
	(segment
		(start 159.797496 -246.076216)
		(end 159.76981 -246.103902)
		(width 0.101854)
		(layer "F.Cu")
		(net "M_E_CPU1_SB_CS_N<0>")
	)
	(segment
		(start 150.015194 -244.89664)
		(end 146.271996 -244.89664)
		(width 0.20066)
		(layer "F.Cu")
		(net "M_E_CPU1_SB_CS_N<0>")
	)
	(segment
		(start 144.588484 -246.580152)
		(end 140.31595 -246.580152)
		(width 0.1016)
		(layer "F.Cu")
		(net "M_E_CPU1_SB_CS_N<0>")
	)
	(segment
		(start 160.535366 -246.277384)
		(end 161.133028 -245.681754)
		(width 0.20066)
		(layer "F.Cu")
		(net "M_E_CPU1_SB_CS_N<0>")
	)
	(segment
		(start 163.923726 -246.216424)
		(end 163.898834 -246.191532)
		(width 0.101854)
		(layer "F.Cu")
		(net "M_E_CPU1_SB_CS_N<0>")
	)
	(segment
		(start 161.896552 -246.21617)
		(end 161.891726 -246.21617)
		(width 0.101854)
		(layer "F.Cu")
		(net "M_E_CPU1_SB_CS_N<0>")
	)
	(segment
		(start 161.133028 -245.397528)
		(end 160.783778 -245.048278)
		(width 0.20066)
		(layer "F.Cu")
		(net "M_E_CPU1_SB_CS_N<0>")
	)
	(segment
		(start 161.133028 -245.681754)
		(end 161.133028 -245.397528)
		(width 0.20066)
		(layer "F.Cu")
		(net "M_E_CPU1_SB_CS_N<0>")
	)
	(segment
		(start 144.926558 -246.242078)
		(end 144.588484 -246.580152)
		(width 0.1016)
		(layer "F.Cu")
		(net "M_E_CPU1_SB_CS_N<0>")
	)
	(segment
		(start 159.68218 -246.191532)
		(end 157.873446 -246.191532)
		(width 0.1016)
		(layer "F.Cu")
		(net "M_E_CPU1_SB_CS_N<0>")
	)
	(segment
		(start 140.31595 -246.580152)
		(end 139.589256 -246.580152)
		(width 0.088646)
		(layer "F.Cu")
		(net "M_E_CPU1_SB_CS_N<0>")
	)
	(segment
		(start 164.95522 -246.216424)
		(end 163.923726 -246.216424)
		(width 0.20066)
		(layer "F.Cu")
		(net "M_E_CPU1_SB_CS_N<0>")
	)
	(segment
		(start 161.068766 -246.828818)
		(end 160.784794 -246.828818)
		(width 0.20066)
		(layer "F.Cu")
		(net "M_E_CPU1_SB_CS_N<0>")
	)
	(segment
		(start 163.556696 -246.191532)
		(end 161.92119 -246.191532)
		(width 0.1016)
		(layer "F.Cu")
		(net "M_E_CPU1_SB_CS_N<0>")
	)
	(arc
		(start 138.693144 -246.621808)
		(mid 138.640872 -246.602073)
		(end 138.590274 -246.578374)
		(width 0.088646)
		(layer "F.Cu")
		(net "M_E_CPU1_SB_CS_N<0>")
	)
	(arc
		(start 138.781028 -246.635778)
		(mid 138.736525 -246.632324)
		(end 138.693144 -246.621808)
		(width 0.088646)
		(layer "F.Cu")
		(net "M_E_CPU1_SB_CS_N<0>")
	)
	(segment
		(start 151.995378 -239.739424)
		(end 152.196038 -239.538764)
		(width 0.20066)
		(layer "F.Cu")
		(net "M_E_CPU1_SB_CB<7>")
	)
	(segment
		(start 154.052778 -239.043718)
		(end 154.253438 -239.244378)
		(width 0.20066)
		(layer "F.Cu")
		(net "M_E_CPU1_SB_CB<7>")
	)
	(segment
		(start 142.021052 -241.735356)
		(end 144.124934 -241.735356)
		(width 0.1016)
		(layer "F.Cu")
		(net "M_E_CPU1_SB_CB<7>")
	)
	(segment
		(start 153.567638 -239.244378)
		(end 153.768298 -239.043718)
		(width 0.20066)
		(layer "F.Cu")
		(net "M_E_CPU1_SB_CB<7>")
	)
	(segment
		(start 155.740862 -239.739424)
		(end 157.12186 -238.358426)
		(width 0.20066)
		(layer "F.Cu")
		(net "M_E_CPU1_SB_CB<7>")
	)
	(segment
		(start 157.628336 -238.54156)
		(end 157.791658 -238.54156)
		(width 0.20066)
		(layer "F.Cu")
		(net "M_E_CPU1_SB_CB<7>")
	)
	(segment
		(start 151.468328 -239.739424)
		(end 151.995378 -239.739424)
		(width 0.20066)
		(layer "F.Cu")
		(net "M_E_CPU1_SB_CB<7>")
	)
	(segment
		(start 152.196038 -239.244378)
		(end 152.396698 -239.043718)
		(width 0.20066)
		(layer "F.Cu")
		(net "M_E_CPU1_SB_CB<7>")
	)
	(segment
		(start 167.979598 -239.41532)
		(end 167.567356 -239.41532)
		(width 0.20066)
		(layer "F.Cu")
		(net "M_E_CPU1_SB_CB<7>")
	)
	(segment
		(start 139.455398 -243.648738)
		(end 139.695936 -243.4082)
		(width 0.088646)
		(layer "F.Cu")
		(net "M_E_CPU1_SB_CB<7>")
	)
	(segment
		(start 168.156636 -239.238282)
		(end 167.979598 -239.41532)
		(width 0.20066)
		(layer "F.Cu")
		(net "M_E_CPU1_SB_CB<7>")
	)
	(segment
		(start 154.253438 -239.244378)
		(end 154.253438 -239.538764)
		(width 0.20066)
		(layer "F.Cu")
		(net "M_E_CPU1_SB_CB<7>")
	)
	(segment
		(start 146.65452 -239.20577)
		(end 147.326096 -239.20577)
		(width 0.1016)
		(layer "F.Cu")
		(net "M_E_CPU1_SB_CB<7>")
	)
	(segment
		(start 165.149276 -239.40135)
		(end 164.976302 -239.40135)
		(width 0.20066)
		(layer "F.Cu")
		(net "M_E_CPU1_SB_CB<7>")
	)
	(segment
		(start 168.641268 -238.68507)
		(end 168.357296 -238.68507)
		(width 0.20066)
		(layer "F.Cu")
		(net "M_E_CPU1_SB_CB<7>")
	)
	(segment
		(start 157.12186 -238.358426)
		(end 157.445202 -238.358426)
		(width 0.20066)
		(layer "F.Cu")
		(net "M_E_CPU1_SB_CB<7>")
	)
	(segment
		(start 152.196038 -239.538764)
		(end 152.196038 -239.244378)
		(width 0.20066)
		(layer "F.Cu")
		(net "M_E_CPU1_SB_CB<7>")
	)
	(segment
		(start 152.881838 -239.244378)
		(end 152.881838 -239.538764)
		(width 0.20066)
		(layer "F.Cu")
		(net "M_E_CPU1_SB_CB<7>")
	)
	(segment
		(start 167.567356 -239.41532)
		(end 167.543734 -239.391698)
		(width 0.101854)
		(layer "F.Cu")
		(net "M_E_CPU1_SB_CB<7>")
	)
	(segment
		(start 153.366978 -239.739424)
		(end 153.567638 -239.538764)
		(width 0.20066)
		(layer "F.Cu")
		(net "M_E_CPU1_SB_CB<7>")
	)
	(segment
		(start 167.543734 -239.391698)
		(end 167.347138 -239.391698)
		(width 0.101854)
		(layer "F.Cu")
		(net "M_E_CPU1_SB_CB<7>")
	)
	(segment
		(start 157.796484 -238.54156)
		(end 159.793178 -238.54156)
		(width 0.1016)
		(layer "F.Cu")
		(net "M_E_CPU1_SB_CB<7>")
	)
	(segment
		(start 167.347138 -239.391698)
		(end 165.362636 -239.391698)
		(width 0.1016)
		(layer "F.Cu")
		(net "M_E_CPU1_SB_CB<7>")
	)
	(segment
		(start 160.863026 -238.966756)
		(end 162.913314 -238.966756)
		(width 0.20066)
		(layer "F.Cu")
		(net "M_E_CPU1_SB_CB<7>")
	)
	(segment
		(start 154.454098 -239.739424)
		(end 155.740862 -239.739424)
		(width 0.20066)
		(layer "F.Cu")
		(net "M_E_CPU1_SB_CB<7>")
	)
	(segment
		(start 140.163296 -243.4082)
		(end 140.348208 -243.4082)
		(width 0.1016)
		(layer "F.Cu")
		(net "M_E_CPU1_SB_CB<7>")
	)
	(segment
		(start 157.791658 -238.54156)
		(end 157.796484 -238.54156)
		(width 0.101854)
		(layer "F.Cu")
		(net "M_E_CPU1_SB_CB<7>")
	)
	(segment
		(start 157.445202 -238.358426)
		(end 157.628336 -238.54156)
		(width 0.20066)
		(layer "F.Cu")
		(net "M_E_CPU1_SB_CB<7>")
	)
	(segment
		(start 170.457114 -238.966756)
		(end 168.922954 -238.966756)
		(width 0.20066)
		(layer "F.Cu")
		(net "M_E_CPU1_SB_CB<7>")
	)
	(segment
		(start 160.421828 -238.525558)
		(end 160.863026 -238.966756)
		(width 0.20066)
		(layer "F.Cu")
		(net "M_E_CPU1_SB_CB<7>")
	)
	(segment
		(start 152.396698 -239.043718)
		(end 152.681178 -239.043718)
		(width 0.20066)
		(layer "F.Cu")
		(net "M_E_CPU1_SB_CB<7>")
	)
	(segment
		(start 152.681178 -239.043718)
		(end 152.881838 -239.244378)
		(width 0.20066)
		(layer "F.Cu")
		(net "M_E_CPU1_SB_CB<7>")
	)
	(segment
		(start 147.326096 -239.20577)
		(end 150.934674 -239.20577)
		(width 0.20066)
		(layer "F.Cu")
		(net "M_E_CPU1_SB_CB<7>")
	)
	(segment
		(start 144.124934 -241.735356)
		(end 146.65452 -239.20577)
		(width 0.1016)
		(layer "F.Cu")
		(net "M_E_CPU1_SB_CB<7>")
	)
	(segment
		(start 159.823658 -238.525558)
		(end 160.421828 -238.525558)
		(width 0.20066)
		(layer "F.Cu")
		(net "M_E_CPU1_SB_CB<7>")
	)
	(segment
		(start 152.881838 -239.538764)
		(end 153.082498 -239.739424)
		(width 0.20066)
		(layer "F.Cu")
		(net "M_E_CPU1_SB_CB<7>")
	)
	(segment
		(start 153.567638 -239.538764)
		(end 153.567638 -239.244378)
		(width 0.20066)
		(layer "F.Cu")
		(net "M_E_CPU1_SB_CB<7>")
	)
	(segment
		(start 153.082498 -239.739424)
		(end 153.366978 -239.739424)
		(width 0.20066)
		(layer "F.Cu")
		(net "M_E_CPU1_SB_CB<7>")
	)
	(segment
		(start 164.976302 -239.40135)
		(end 164.541708 -238.966756)
		(width 0.20066)
		(layer "F.Cu")
		(net "M_E_CPU1_SB_CB<7>")
	)
	(segment
		(start 168.922954 -238.966756)
		(end 168.641268 -238.68507)
		(width 0.20066)
		(layer "F.Cu")
		(net "M_E_CPU1_SB_CB<7>")
	)
	(segment
		(start 159.793178 -238.54156)
		(end 159.80918 -238.525558)
		(width 0.1016)
		(layer "F.Cu")
		(net "M_E_CPU1_SB_CB<7>")
	)
	(segment
		(start 168.357296 -238.68507)
		(end 168.156636 -238.88573)
		(width 0.20066)
		(layer "F.Cu")
		(net "M_E_CPU1_SB_CB<7>")
	)
	(segment
		(start 165.158928 -239.391698)
		(end 165.149276 -239.40135)
		(width 0.101854)
		(layer "F.Cu")
		(net "M_E_CPU1_SB_CB<7>")
	)
	(segment
		(start 139.695936 -243.4082)
		(end 140.163296 -243.4082)
		(width 0.088646)
		(layer "F.Cu")
		(net "M_E_CPU1_SB_CB<7>")
	)
	(segment
		(start 159.80918 -238.525558)
		(end 159.823658 -238.525558)
		(width 0.101854)
		(layer "F.Cu")
		(net "M_E_CPU1_SB_CB<7>")
	)
	(segment
		(start 140.348208 -243.4082)
		(end 142.021052 -241.735356)
		(width 0.1016)
		(layer "F.Cu")
		(net "M_E_CPU1_SB_CB<7>")
	)
	(segment
		(start 150.934674 -239.20577)
		(end 151.468328 -239.739424)
		(width 0.20066)
		(layer "F.Cu")
		(net "M_E_CPU1_SB_CB<7>")
	)
	(segment
		(start 153.768298 -239.043718)
		(end 154.052778 -239.043718)
		(width 0.20066)
		(layer "F.Cu")
		(net "M_E_CPU1_SB_CB<7>")
	)
	(segment
		(start 138.424666 -243.644928)
		(end 139.455398 -243.648738)
		(width 0.088646)
		(layer "F.Cu")
		(net "M_E_CPU1_SB_CB<7>")
	)
	(segment
		(start 154.253438 -239.538764)
		(end 154.454098 -239.739424)
		(width 0.20066)
		(layer "F.Cu")
		(net "M_E_CPU1_SB_CB<7>")
	)
	(segment
		(start 168.156636 -238.88573)
		(end 168.156636 -239.238282)
		(width 0.20066)
		(layer "F.Cu")
		(net "M_E_CPU1_SB_CB<7>")
	)
	(segment
		(start 165.362636 -239.391698)
		(end 165.158928 -239.391698)
		(width 0.101854)
		(layer "F.Cu")
		(net "M_E_CPU1_SB_CB<7>")
	)
	(segment
		(start 164.541708 -238.966756)
		(end 162.913314 -238.966756)
		(width 0.20066)
		(layer "F.Cu")
		(net "M_E_CPU1_SB_CB<7>")
	)
	(segment
		(start 167.632126 -239.95888)
		(end 167.46474 -240.126266)
		(width 0.20066)
		(layer "F.Cu")
		(net "M_E_CPU1_SB_CB<6>")
	)
	(segment
		(start 159.7914 -240.241582)
		(end 159.951166 -240.241582)
		(width 0.101854)
		(layer "F.Cu")
		(net "M_E_CPU1_SB_CB<6>")
	)
	(segment
		(start 169.07383 -240.666778)
		(end 168.871646 -240.868962)
		(width 0.20066)
		(layer "F.Cu")
		(net "M_E_CPU1_SB_CB<6>")
	)
	(segment
		(start 155.360624 -242.04422)
		(end 157.185614 -240.21923)
		(width 0.20066)
		(layer "F.Cu")
		(net "M_E_CPU1_SB_CB<6>")
	)
	(segment
		(start 157.578806 -240.21923)
		(end 157.582108 -240.222532)
		(width 0.20066)
		(layer "F.Cu")
		(net "M_E_CPU1_SB_CB<6>")
	)
	(segment
		(start 168.156382 -239.95888)
		(end 167.632126 -239.95888)
		(width 0.20066)
		(layer "F.Cu")
		(net "M_E_CPU1_SB_CB<6>")
	)
	(segment
		(start 164.66439 -240.57102)
		(end 163.816792 -240.57102)
		(width 0.20066)
		(layer "F.Cu")
		(net "M_E_CPU1_SB_CB<6>")
	)
	(segment
		(start 159.951166 -240.241582)
		(end 159.970216 -240.222532)
		(width 0.101854)
		(layer "F.Cu")
		(net "M_E_CPU1_SB_CB<6>")
	)
	(segment
		(start 138.313922 -244.36705)
		(end 138.714226 -244.135656)
		(width 0.088646)
		(layer "F.Cu")
		(net "M_E_CPU1_SB_CB<6>")
	)
	(segment
		(start 167.46474 -240.126266)
		(end 167.367458 -240.223548)
		(width 0.101854)
		(layer "F.Cu")
		(net "M_E_CPU1_SB_CB<6>")
	)
	(segment
		(start 144.377918 -242.344956)
		(end 146.200368 -240.522506)
		(width 0.1016)
		(layer "F.Cu")
		(net "M_E_CPU1_SB_CB<6>")
	)
	(segment
		(start 160.885632 -240.666778)
		(end 162.913314 -240.666778)
		(width 0.20066)
		(layer "F.Cu")
		(net "M_E_CPU1_SB_CB<6>")
	)
	(segment
		(start 151.393906 -241.09299)
		(end 152.444958 -242.144042)
		(width 0.20066)
		(layer "F.Cu")
		(net "M_E_CPU1_SB_CB<6>")
	)
	(segment
		(start 138.900408 -244.085872)
		(end 139.592304 -244.085872)
		(width 0.088646)
		(layer "F.Cu")
		(net "M_E_CPU1_SB_CB<6>")
	)
	(segment
		(start 163.721034 -240.666778)
		(end 162.913314 -240.666778)
		(width 0.20066)
		(layer "F.Cu")
		(net "M_E_CPU1_SB_CB<6>")
	)
	(segment
		(start 168.557702 -240.868962)
		(end 168.357042 -240.668302)
		(width 0.20066)
		(layer "F.Cu")
		(net "M_E_CPU1_SB_CB<6>")
	)
	(segment
		(start 157.601158 -240.241582)
		(end 157.82163 -240.241582)
		(width 0.101854)
		(layer "F.Cu")
		(net "M_E_CPU1_SB_CB<6>")
	)
	(segment
		(start 163.816792 -240.57102)
		(end 163.721034 -240.666778)
		(width 0.20066)
		(layer "F.Cu")
		(net "M_E_CPU1_SB_CB<6>")
	)
	(segment
		(start 139.592304 -244.085872)
		(end 139.660376 -244.0178)
		(width 0.088646)
		(layer "F.Cu")
		(net "M_E_CPU1_SB_CB<6>")
	)
	(segment
		(start 157.82163 -240.241582)
		(end 159.7914 -240.241582)
		(width 0.1016)
		(layer "F.Cu")
		(net "M_E_CPU1_SB_CB<6>")
	)
	(segment
		(start 165.368224 -240.241836)
		(end 165.158674 -240.241836)
		(width 0.101854)
		(layer "F.Cu")
		(net "M_E_CPU1_SB_CB<6>")
	)
	(segment
		(start 168.357042 -240.15954)
		(end 168.156382 -239.95888)
		(width 0.20066)
		(layer "F.Cu")
		(net "M_E_CPU1_SB_CB<6>")
	)
	(segment
		(start 157.185614 -240.21923)
		(end 157.578806 -240.21923)
		(width 0.20066)
		(layer "F.Cu")
		(net "M_E_CPU1_SB_CB<6>")
	)
	(segment
		(start 142.274036 -242.344956)
		(end 144.377918 -242.344956)
		(width 0.1016)
		(layer "F.Cu")
		(net "M_E_CPU1_SB_CB<6>")
	)
	(segment
		(start 139.660376 -244.0178)
		(end 140.163296 -244.0178)
		(width 0.088646)
		(layer "F.Cu")
		(net "M_E_CPU1_SB_CB<6>")
	)
	(segment
		(start 167.34917 -240.241836)
		(end 165.368224 -240.241836)
		(width 0.1016)
		(layer "F.Cu")
		(net "M_E_CPU1_SB_CB<6>")
	)
	(segment
		(start 137.954766 -244.458744)
		(end 138.313922 -244.36705)
		(width 0.088646)
		(layer "F.Cu")
		(net "M_E_CPU1_SB_CB<6>")
	)
	(segment
		(start 167.367458 -240.223548)
		(end 167.34917 -240.241836)
		(width 0.1016)
		(layer "F.Cu")
		(net "M_E_CPU1_SB_CB<6>")
	)
	(segment
		(start 170.457114 -240.666778)
		(end 169.07383 -240.666778)
		(width 0.20066)
		(layer "F.Cu")
		(net "M_E_CPU1_SB_CB<6>")
	)
	(segment
		(start 140.163296 -244.0178)
		(end 140.601192 -244.0178)
		(width 0.1016)
		(layer "F.Cu")
		(net "M_E_CPU1_SB_CB<6>")
	)
	(segment
		(start 146.200368 -240.522506)
		(end 146.970496 -240.522506)
		(width 0.1016)
		(layer "F.Cu")
		(net "M_E_CPU1_SB_CB<6>")
	)
	(segment
		(start 168.871646 -240.868962)
		(end 168.557702 -240.868962)
		(width 0.20066)
		(layer "F.Cu")
		(net "M_E_CPU1_SB_CB<6>")
	)
	(segment
		(start 155.119578 -242.144042)
		(end 155.360624 -242.04422)
		(width 0.20066)
		(layer "F.Cu")
		(net "M_E_CPU1_SB_CB<6>")
	)
	(segment
		(start 159.970216 -240.222532)
		(end 160.441386 -240.222532)
		(width 0.20066)
		(layer "F.Cu")
		(net "M_E_CPU1_SB_CB<6>")
	)
	(segment
		(start 150.640542 -241.09299)
		(end 151.393906 -241.09299)
		(width 0.20066)
		(layer "F.Cu")
		(net "M_E_CPU1_SB_CB<6>")
	)
	(segment
		(start 168.357042 -240.668302)
		(end 168.357042 -240.15954)
		(width 0.20066)
		(layer "F.Cu")
		(net "M_E_CPU1_SB_CB<6>")
	)
	(segment
		(start 160.441386 -240.222532)
		(end 160.885632 -240.666778)
		(width 0.20066)
		(layer "F.Cu")
		(net "M_E_CPU1_SB_CB<6>")
	)
	(segment
		(start 140.601192 -244.0178)
		(end 142.274036 -242.344956)
		(width 0.1016)
		(layer "F.Cu")
		(net "M_E_CPU1_SB_CB<6>")
	)
	(segment
		(start 146.970496 -240.522506)
		(end 150.070058 -240.522506)
		(width 0.20066)
		(layer "F.Cu")
		(net "M_E_CPU1_SB_CB<6>")
	)
	(segment
		(start 152.444958 -242.144042)
		(end 155.119578 -242.144042)
		(width 0.20066)
		(layer "F.Cu")
		(net "M_E_CPU1_SB_CB<6>")
	)
	(segment
		(start 165.158674 -240.241836)
		(end 164.993574 -240.241836)
		(width 0.20066)
		(layer "F.Cu")
		(net "M_E_CPU1_SB_CB<6>")
	)
	(segment
		(start 164.993574 -240.241836)
		(end 164.66439 -240.57102)
		(width 0.20066)
		(layer "F.Cu")
		(net "M_E_CPU1_SB_CB<6>")
	)
	(segment
		(start 150.070058 -240.522506)
		(end 150.640542 -241.09299)
		(width 0.20066)
		(layer "F.Cu")
		(net "M_E_CPU1_SB_CB<6>")
	)
	(segment
		(start 157.582108 -240.222532)
		(end 157.601158 -240.241582)
		(width 0.101854)
		(layer "F.Cu")
		(net "M_E_CPU1_SB_CB<6>")
	)
	(arc
		(start 138.714226 -244.135656)
		(mid 138.804038 -244.098503)
		(end 138.900408 -244.085872)
		(width 0.088646)
		(layer "F.Cu")
		(net "M_E_CPU1_SB_CB<6>")
	)
	(segment
		(start 136.50722 -244.260624)
		(end 136.68121 -244.260624)
		(width 0.088646)
		(layer "F.Cu")
		(net "M_E_CPU1_SB_CB<5>")
	)
	(segment
		(start 154.837638 -241.497358)
		(end 155.09748 -241.389662)
		(width 0.20066)
		(layer "F.Cu")
		(net "M_E_CPU1_SB_CB<5>")
	)
	(segment
		(start 160.000696 -239.42548)
		(end 159.609282 -239.816894)
		(width 0.20066)
		(layer "F.Cu")
		(net "M_E_CPU1_SB_CB<5>")
	)
	(segment
		(start 161.558732 -239.372648)
		(end 161.038286 -239.893094)
		(width 0.20066)
		(layer "F.Cu")
		(net "M_E_CPU1_SB_CB<5>")
	)
	(segment
		(start 159.609282 -239.816894)
		(end 158.8135 -239.816894)
		(width 0.20066)
		(layer "F.Cu")
		(net "M_E_CPU1_SB_CB<5>")
	)
	(segment
		(start 155.09748 -241.389662)
		(end 156.93263 -239.554512)
		(width 0.20066)
		(layer "F.Cu")
		(net "M_E_CPU1_SB_CB<5>")
	)
	(segment
		(start 164.11702 -239.373156)
		(end 164.098478 -239.391698)
		(width 0.101854)
		(layer "F.Cu")
		(net "M_E_CPU1_SB_CB<5>")
	)
	(segment
		(start 156.93263 -239.554512)
		(end 158.01467 -239.554512)
		(width 0.20066)
		(layer "F.Cu")
		(net "M_E_CPU1_SB_CB<5>")
	)
	(segment
		(start 158.276798 -239.81664)
		(end 158.813246 -239.81664)
		(width 0.20066)
		(layer "F.Cu")
		(net "M_E_CPU1_SB_CB<5>")
	)
	(segment
		(start 139.490704 -243.882672)
		(end 139.660376 -243.713)
		(width 0.088646)
		(layer "F.Cu")
		(net "M_E_CPU1_SB_CB<5>")
	)
	(segment
		(start 158.8135 -239.816894)
		(end 158.813246 -239.81664)
		(width 0.20066)
		(layer "F.Cu")
		(net "M_E_CPU1_SB_CB<5>")
	)
	(segment
		(start 160.686496 -239.893094)
		(end 160.559496 -239.766094)
		(width 0.20066)
		(layer "F.Cu")
		(net "M_E_CPU1_SB_CB<5>")
	)
	(segment
		(start 136.453626 -244.20703)
		(end 136.50722 -244.260624)
		(width 0.088646)
		(layer "F.Cu")
		(net "M_E_CPU1_SB_CB<5>")
	)
	(segment
		(start 166.357046 -239.81664)
		(end 164.694108 -239.81664)
		(width 0.20066)
		(layer "F.Cu")
		(net "M_E_CPU1_SB_CB<5>")
	)
	(segment
		(start 137.991088 -243.88953)
		(end 138.163046 -244.061488)
		(width 0.088646)
		(layer "F.Cu")
		(net "M_E_CPU1_SB_CB<5>")
	)
	(segment
		(start 164.250624 -239.373156)
		(end 164.11702 -239.373156)
		(width 0.20066)
		(layer "F.Cu")
		(net "M_E_CPU1_SB_CB<5>")
	)
	(segment
		(start 144.251426 -242.040156)
		(end 146.42338 -239.868202)
		(width 0.1016)
		(layer "F.Cu")
		(net "M_E_CPU1_SB_CB<5>")
	)
	(segment
		(start 153.843736 -240.45926)
		(end 154.044396 -240.65992)
		(width 0.20066)
		(layer "F.Cu")
		(net "M_E_CPU1_SB_CB<5>")
	)
	(segment
		(start 151.079454 -240.413286)
		(end 151.629618 -240.413286)
		(width 0.20066)
		(layer "F.Cu")
		(net "M_E_CPU1_SB_CB<5>")
	)
	(segment
		(start 164.098478 -239.391698)
		(end 163.905184 -239.391698)
		(width 0.101854)
		(layer "F.Cu")
		(net "M_E_CPU1_SB_CB<5>")
	)
	(segment
		(start 150.53437 -239.868202)
		(end 151.079454 -240.413286)
		(width 0.20066)
		(layer "F.Cu")
		(net "M_E_CPU1_SB_CB<5>")
	)
	(segment
		(start 153.157936 -241.497358)
		(end 153.358596 -241.296698)
		(width 0.20066)
		(layer "F.Cu")
		(net "M_E_CPU1_SB_CB<5>")
	)
	(segment
		(start 136.453626 -243.865908)
		(end 136.453626 -244.20703)
		(width 0.088646)
		(layer "F.Cu")
		(net "M_E_CPU1_SB_CB<5>")
	)
	(segment
		(start 160.559496 -239.766094)
		(end 160.559496 -239.60328)
		(width 0.20066)
		(layer "F.Cu")
		(net "M_E_CPU1_SB_CB<5>")
	)
	(segment
		(start 137.865104 -243.88953)
		(end 137.991088 -243.88953)
		(width 0.088646)
		(layer "F.Cu")
		(net "M_E_CPU1_SB_CB<5>")
	)
	(segment
		(start 160.381696 -239.42548)
		(end 160.000696 -239.42548)
		(width 0.20066)
		(layer "F.Cu")
		(net "M_E_CPU1_SB_CB<5>")
	)
	(segment
		(start 164.694108 -239.81664)
		(end 164.250624 -239.373156)
		(width 0.20066)
		(layer "F.Cu")
		(net "M_E_CPU1_SB_CB<5>")
	)
	(segment
		(start 161.73958 -239.391698)
		(end 161.72053 -239.372648)
		(width 0.101854)
		(layer "F.Cu")
		(net "M_E_CPU1_SB_CB<5>")
	)
	(segment
		(start 153.358596 -241.296698)
		(end 153.358596 -240.65992)
		(width 0.20066)
		(layer "F.Cu")
		(net "M_E_CPU1_SB_CB<5>")
	)
	(segment
		(start 153.358596 -240.65992)
		(end 153.559256 -240.45926)
		(width 0.20066)
		(layer "F.Cu")
		(net "M_E_CPU1_SB_CB<5>")
	)
	(segment
		(start 152.71369 -241.497358)
		(end 153.157936 -241.497358)
		(width 0.20066)
		(layer "F.Cu")
		(net "M_E_CPU1_SB_CB<5>")
	)
	(segment
		(start 146.42338 -239.868202)
		(end 147.326096 -239.868202)
		(width 0.1016)
		(layer "F.Cu")
		(net "M_E_CPU1_SB_CB<5>")
	)
	(segment
		(start 140.4747 -243.713)
		(end 142.147544 -242.040156)
		(width 0.1016)
		(layer "F.Cu")
		(net "M_E_CPU1_SB_CB<5>")
	)
	(segment
		(start 136.545066 -243.644928)
		(end 136.453626 -243.865908)
		(width 0.088646)
		(layer "F.Cu")
		(net "M_E_CPU1_SB_CB<5>")
	)
	(segment
		(start 163.905184 -239.391698)
		(end 161.920428 -239.391698)
		(width 0.1016)
		(layer "F.Cu")
		(net "M_E_CPU1_SB_CB<5>")
	)
	(segment
		(start 136.68121 -244.260624)
		(end 136.830816 -244.111018)
		(width 0.088646)
		(layer "F.Cu")
		(net "M_E_CPU1_SB_CB<5>")
	)
	(segment
		(start 154.044396 -240.65992)
		(end 154.044396 -241.296698)
		(width 0.20066)
		(layer "F.Cu")
		(net "M_E_CPU1_SB_CB<5>")
	)
	(segment
		(start 137.045446 -243.847366)
		(end 137.403078 -244.197886)
		(width 0.088646)
		(layer "F.Cu")
		(net "M_E_CPU1_SB_CB<5>")
	)
	(segment
		(start 161.038286 -239.893094)
		(end 160.686496 -239.893094)
		(width 0.20066)
		(layer "F.Cu")
		(net "M_E_CPU1_SB_CB<5>")
	)
	(segment
		(start 154.044396 -241.296698)
		(end 154.245056 -241.497358)
		(width 0.20066)
		(layer "F.Cu")
		(net "M_E_CPU1_SB_CB<5>")
	)
	(segment
		(start 138.456416 -244.064536)
		(end 138.614404 -243.97335)
		(width 0.088646)
		(layer "F.Cu")
		(net "M_E_CPU1_SB_CB<5>")
	)
	(segment
		(start 137.403078 -244.197886)
		(end 137.556748 -244.197886)
		(width 0.088646)
		(layer "F.Cu")
		(net "M_E_CPU1_SB_CB<5>")
	)
	(segment
		(start 139.660376 -243.713)
		(end 140.163296 -243.713)
		(width 0.088646)
		(layer "F.Cu")
		(net "M_E_CPU1_SB_CB<5>")
	)
	(segment
		(start 160.559496 -239.60328)
		(end 160.381696 -239.42548)
		(width 0.20066)
		(layer "F.Cu")
		(net "M_E_CPU1_SB_CB<5>")
	)
	(segment
		(start 140.163296 -243.713)
		(end 140.4747 -243.713)
		(width 0.1016)
		(layer "F.Cu")
		(net "M_E_CPU1_SB_CB<5>")
	)
	(segment
		(start 151.629618 -240.413286)
		(end 152.71369 -241.497358)
		(width 0.20066)
		(layer "F.Cu")
		(net "M_E_CPU1_SB_CB<5>")
	)
	(segment
		(start 154.245056 -241.497358)
		(end 154.837638 -241.497358)
		(width 0.20066)
		(layer "F.Cu")
		(net "M_E_CPU1_SB_CB<5>")
	)
	(segment
		(start 161.72053 -239.372648)
		(end 161.558732 -239.372648)
		(width 0.20066)
		(layer "F.Cu")
		(net "M_E_CPU1_SB_CB<5>")
	)
	(segment
		(start 147.326096 -239.868202)
		(end 150.53437 -239.868202)
		(width 0.20066)
		(layer "F.Cu")
		(net "M_E_CPU1_SB_CB<5>")
	)
	(segment
		(start 136.919716 -243.847366)
		(end 137.045446 -243.847366)
		(width 0.088646)
		(layer "F.Cu")
		(net "M_E_CPU1_SB_CB<5>")
	)
	(segment
		(start 142.147544 -242.040156)
		(end 144.251426 -242.040156)
		(width 0.1016)
		(layer "F.Cu")
		(net "M_E_CPU1_SB_CB<5>")
	)
	(segment
		(start 136.830816 -244.111018)
		(end 136.830816 -243.936266)
		(width 0.088646)
		(layer "F.Cu")
		(net "M_E_CPU1_SB_CB<5>")
	)
	(segment
		(start 153.559256 -240.45926)
		(end 153.843736 -240.45926)
		(width 0.20066)
		(layer "F.Cu")
		(net "M_E_CPU1_SB_CB<5>")
	)
	(segment
		(start 161.920428 -239.391698)
		(end 161.73958 -239.391698)
		(width 0.101854)
		(layer "F.Cu")
		(net "M_E_CPU1_SB_CB<5>")
	)
	(segment
		(start 158.01467 -239.554512)
		(end 158.276798 -239.81664)
		(width 0.20066)
		(layer "F.Cu")
		(net "M_E_CPU1_SB_CB<5>")
	)
	(segment
		(start 136.830816 -243.936266)
		(end 136.919716 -243.847366)
		(width 0.088646)
		(layer "F.Cu")
		(net "M_E_CPU1_SB_CB<5>")
	)
	(segment
		(start 138.952732 -243.882672)
		(end 139.490704 -243.882672)
		(width 0.088646)
		(layer "F.Cu")
		(net "M_E_CPU1_SB_CB<5>")
	)
	(segment
		(start 137.556748 -244.197886)
		(end 137.865104 -243.88953)
		(width 0.088646)
		(layer "F.Cu")
		(net "M_E_CPU1_SB_CB<5>")
	)
	(segment
		(start 138.163046 -244.061488)
		(end 138.168126 -244.064282)
		(width 0.088646)
		(layer "F.Cu")
		(net "M_E_CPU1_SB_CB<5>")
	)
	(arc
		(start 138.168126 -244.064282)
		(mid 138.312225 -244.102967)
		(end 138.456416 -244.064536)
		(width 0.088646)
		(layer "F.Cu")
		(net "M_E_CPU1_SB_CB<5>")
	)
	(arc
		(start 138.614404 -243.97335)
		(mid 138.7776 -243.905749)
		(end 138.952732 -243.882672)
		(width 0.088646)
		(layer "F.Cu")
		(net "M_E_CPU1_SB_CB<5>")
	)
	(segment
		(start 165.316154 -241.636296)
		(end 164.935662 -241.636296)
		(width 0.20066)
		(layer "F.Cu")
		(net "M_E_CPU1_SB_CB<4>")
	)
	(segment
		(start 161.221674 -241.401854)
		(end 160.937448 -241.401854)
		(width 0.20066)
		(layer "F.Cu")
		(net "M_E_CPU1_SB_CB<4>")
	)
	(segment
		(start 164.735002 -241.270536)
		(end 164.534342 -241.069876)
		(width 0.20066)
		(layer "F.Cu")
		(net "M_E_CPU1_SB_CB<4>")
	)
	(segment
		(start 146.335496 -241.19205)
		(end 146.524726 -241.19205)
		(width 0.20066)
		(layer "F.Cu")
		(net "M_E_CPU1_SB_CB<4>")
	)
	(segment
		(start 147.434046 -241.39271)
		(end 147.634706 -241.19205)
		(width 0.20066)
		(layer "F.Cu")
		(net "M_E_CPU1_SB_CB<4>")
	)
	(segment
		(start 144.50441 -242.649756)
		(end 145.962116 -241.19205)
		(width 0.1016)
		(layer "F.Cu")
		(net "M_E_CPU1_SB_CB<4>")
	)
	(segment
		(start 164.01669 -241.09172)
		(end 163.725352 -241.09172)
		(width 0.101854)
		(layer "F.Cu")
		(net "M_E_CPU1_SB_CB<4>")
	)
	(segment
		(start 160.649158 -241.113564)
		(end 160.365186 -241.113564)
		(width 0.20066)
		(layer "F.Cu")
		(net "M_E_CPU1_SB_CB<4>")
	)
	(segment
		(start 161.531808 -241.09172)
		(end 161.221674 -241.401854)
		(width 0.20066)
		(layer "F.Cu")
		(net "M_E_CPU1_SB_CB<4>")
	)
	(segment
		(start 139.900914 -245.170198)
		(end 140.00099 -245.070122)
		(width 0.088646)
		(layer "F.Cu")
		(net "M_E_CPU1_SB_CB<4>")
	)
	(segment
		(start 138.262614 -244.686074)
		(end 138.38174 -244.566948)
		(width 0.088646)
		(layer "F.Cu")
		(net "M_E_CPU1_SB_CB<4>")
	)
	(segment
		(start 142.400528 -242.649756)
		(end 144.50441 -242.649756)
		(width 0.1016)
		(layer "F.Cu")
		(net "M_E_CPU1_SB_CB<4>")
	)
	(segment
		(start 161.912808 -241.09172)
		(end 161.68497 -241.09172)
		(width 0.101854)
		(layer "F.Cu")
		(net "M_E_CPU1_SB_CB<4>")
	)
	(segment
		(start 147.942046 -241.19205)
		(end 148.142706 -241.39271)
		(width 0.20066)
		(layer "F.Cu")
		(net "M_E_CPU1_SB_CB<4>")
	)
	(segment
		(start 149.813772 -241.19205)
		(end 150.443184 -241.821462)
		(width 0.20066)
		(layer "F.Cu")
		(net "M_E_CPU1_SB_CB<4>")
	)
	(segment
		(start 160.937448 -241.401854)
		(end 160.649158 -241.113564)
		(width 0.20066)
		(layer "F.Cu")
		(net "M_E_CPU1_SB_CB<4>")
	)
	(segment
		(start 148.343366 -241.940334)
		(end 148.650706 -241.940334)
		(width 0.20066)
		(layer "F.Cu")
		(net "M_E_CPU1_SB_CB<4>")
	)
	(segment
		(start 139.12215 -244.807486)
		(end 139.35837 -244.807486)
		(width 0.088646)
		(layer "F.Cu")
		(net "M_E_CPU1_SB_CB<4>")
	)
	(segment
		(start 138.135614 -244.967506)
		(end 138.262614 -244.840506)
		(width 0.088646)
		(layer "F.Cu")
		(net "M_E_CPU1_SB_CB<4>")
	)
	(segment
		(start 138.959082 -244.970554)
		(end 139.12215 -244.807486)
		(width 0.088646)
		(layer "F.Cu")
		(net "M_E_CPU1_SB_CB<4>")
	)
	(segment
		(start 146.926046 -241.940334)
		(end 147.233386 -241.940334)
		(width 0.20066)
		(layer "F.Cu")
		(net "M_E_CPU1_SB_CB<4>")
	)
	(segment
		(start 160.365186 -241.113564)
		(end 159.961834 -241.516916)
		(width 0.20066)
		(layer "F.Cu")
		(net "M_E_CPU1_SB_CB<4>")
	)
	(segment
		(start 147.233386 -241.940334)
		(end 147.434046 -241.739674)
		(width 0.20066)
		(layer "F.Cu")
		(net "M_E_CPU1_SB_CB<4>")
	)
	(segment
		(start 138.50747 -244.566948)
		(end 138.618976 -244.678454)
		(width 0.088646)
		(layer "F.Cu")
		(net "M_E_CPU1_SB_CB<4>")
	)
	(segment
		(start 148.851366 -241.39271)
		(end 149.052026 -241.19205)
		(width 0.20066)
		(layer "F.Cu")
		(net "M_E_CPU1_SB_CB<4>")
	)
	(segment
		(start 148.650706 -241.940334)
		(end 148.851366 -241.739674)
		(width 0.20066)
		(layer "F.Cu")
		(net "M_E_CPU1_SB_CB<4>")
	)
	(segment
		(start 164.534342 -241.069876)
		(end 164.038534 -241.069876)
		(width 0.20066)
		(layer "F.Cu")
		(net "M_E_CPU1_SB_CB<4>")
	)
	(segment
		(start 138.618976 -244.678454)
		(end 138.618976 -244.915944)
		(width 0.088646)
		(layer "F.Cu")
		(net "M_E_CPU1_SB_CB<4>")
	)
	(segment
		(start 166.357046 -241.516662)
		(end 165.435788 -241.516662)
		(width 0.20066)
		(layer "F.Cu")
		(net "M_E_CPU1_SB_CB<4>")
	)
	(segment
		(start 138.262614 -244.840506)
		(end 138.262614 -244.686074)
		(width 0.088646)
		(layer "F.Cu")
		(net "M_E_CPU1_SB_CB<4>")
	)
	(segment
		(start 140.310108 -244.740176)
		(end 142.400528 -242.649756)
		(width 0.1016)
		(layer "F.Cu")
		(net "M_E_CPU1_SB_CB<4>")
	)
	(segment
		(start 140.00099 -245.070122)
		(end 140.00099 -244.828822)
		(width 0.088646)
		(layer "F.Cu")
		(net "M_E_CPU1_SB_CB<4>")
	)
	(segment
		(start 140.00099 -244.828822)
		(end 140.089636 -244.740176)
		(width 0.088646)
		(layer "F.Cu")
		(net "M_E_CPU1_SB_CB<4>")
	)
	(segment
		(start 164.935662 -241.636296)
		(end 164.735002 -241.435636)
		(width 0.20066)
		(layer "F.Cu")
		(net "M_E_CPU1_SB_CB<4>")
	)
	(segment
		(start 163.725352 -241.09172)
		(end 161.912808 -241.09172)
		(width 0.1016)
		(layer "F.Cu")
		(net "M_E_CPU1_SB_CB<4>")
	)
	(segment
		(start 146.725386 -241.39271)
		(end 146.725386 -241.739674)
		(width 0.20066)
		(layer "F.Cu")
		(net "M_E_CPU1_SB_CB<4>")
	)
	(segment
		(start 145.962116 -241.19205)
		(end 146.335496 -241.19205)
		(width 0.1016)
		(layer "F.Cu")
		(net "M_E_CPU1_SB_CB<4>")
	)
	(segment
		(start 146.524726 -241.19205)
		(end 146.725386 -241.39271)
		(width 0.20066)
		(layer "F.Cu")
		(net "M_E_CPU1_SB_CB<4>")
	)
	(segment
		(start 159.961834 -241.516916)
		(end 158.8135 -241.516916)
		(width 0.20066)
		(layer "F.Cu")
		(net "M_E_CPU1_SB_CB<4>")
	)
	(segment
		(start 147.634706 -241.19205)
		(end 147.942046 -241.19205)
		(width 0.20066)
		(layer "F.Cu")
		(net "M_E_CPU1_SB_CB<4>")
	)
	(segment
		(start 146.725386 -241.739674)
		(end 146.926046 -241.940334)
		(width 0.20066)
		(layer "F.Cu")
		(net "M_E_CPU1_SB_CB<4>")
	)
	(segment
		(start 137.456418 -244.458744)
		(end 137.554462 -244.556788)
		(width 0.088646)
		(layer "F.Cu")
		(net "M_E_CPU1_SB_CB<4>")
	)
	(segment
		(start 155.722828 -242.847876)
		(end 157.054042 -241.516662)
		(width 0.20066)
		(layer "F.Cu")
		(net "M_E_CPU1_SB_CB<4>")
	)
	(segment
		(start 148.142706 -241.739674)
		(end 148.343366 -241.940334)
		(width 0.20066)
		(layer "F.Cu")
		(net "M_E_CPU1_SB_CB<4>")
	)
	(segment
		(start 137.554462 -244.556788)
		(end 137.554462 -244.827044)
		(width 0.088646)
		(layer "F.Cu")
		(net "M_E_CPU1_SB_CB<4>")
	)
	(segment
		(start 138.618976 -244.915944)
		(end 138.673586 -244.970554)
		(width 0.088646)
		(layer "F.Cu")
		(net "M_E_CPU1_SB_CB<4>")
	)
	(segment
		(start 152.283922 -242.986052)
		(end 155.389326 -242.986052)
		(width 0.20066)
		(layer "F.Cu")
		(net "M_E_CPU1_SB_CB<4>")
	)
	(segment
		(start 138.673586 -244.970554)
		(end 138.959082 -244.970554)
		(width 0.088646)
		(layer "F.Cu")
		(net "M_E_CPU1_SB_CB<4>")
	)
	(segment
		(start 139.721082 -245.170198)
		(end 139.900914 -245.170198)
		(width 0.088646)
		(layer "F.Cu")
		(net "M_E_CPU1_SB_CB<4>")
	)
	(segment
		(start 165.435788 -241.516662)
		(end 165.316154 -241.636296)
		(width 0.20066)
		(layer "F.Cu")
		(net "M_E_CPU1_SB_CB<4>")
	)
	(segment
		(start 158.8135 -241.516916)
		(end 158.813246 -241.516662)
		(width 0.20066)
		(layer "F.Cu")
		(net "M_E_CPU1_SB_CB<4>")
	)
	(segment
		(start 155.389326 -242.986052)
		(end 155.722828 -242.847876)
		(width 0.20066)
		(layer "F.Cu")
		(net "M_E_CPU1_SB_CB<4>")
	)
	(segment
		(start 151.119332 -241.821462)
		(end 152.283922 -242.986052)
		(width 0.20066)
		(layer "F.Cu")
		(net "M_E_CPU1_SB_CB<4>")
	)
	(segment
		(start 157.054042 -241.516662)
		(end 158.813246 -241.516662)
		(width 0.20066)
		(layer "F.Cu")
		(net "M_E_CPU1_SB_CB<4>")
	)
	(segment
		(start 139.35837 -244.807486)
		(end 139.721082 -245.170198)
		(width 0.088646)
		(layer "F.Cu")
		(net "M_E_CPU1_SB_CB<4>")
	)
	(segment
		(start 140.089636 -244.740176)
		(end 140.147548 -244.740176)
		(width 0.088646)
		(layer "F.Cu")
		(net "M_E_CPU1_SB_CB<4>")
	)
	(segment
		(start 161.68497 -241.09172)
		(end 161.531808 -241.09172)
		(width 0.20066)
		(layer "F.Cu")
		(net "M_E_CPU1_SB_CB<4>")
	)
	(segment
		(start 148.851366 -241.739674)
		(end 148.851366 -241.39271)
		(width 0.20066)
		(layer "F.Cu")
		(net "M_E_CPU1_SB_CB<4>")
	)
	(segment
		(start 137.554462 -244.827044)
		(end 137.694924 -244.967506)
		(width 0.088646)
		(layer "F.Cu")
		(net "M_E_CPU1_SB_CB<4>")
	)
	(segment
		(start 150.443184 -241.821462)
		(end 151.119332 -241.821462)
		(width 0.20066)
		(layer "F.Cu")
		(net "M_E_CPU1_SB_CB<4>")
	)
	(segment
		(start 147.434046 -241.739674)
		(end 147.434046 -241.39271)
		(width 0.20066)
		(layer "F.Cu")
		(net "M_E_CPU1_SB_CB<4>")
	)
	(segment
		(start 164.735002 -241.435636)
		(end 164.735002 -241.270536)
		(width 0.20066)
		(layer "F.Cu")
		(net "M_E_CPU1_SB_CB<4>")
	)
	(segment
		(start 164.038534 -241.069876)
		(end 164.01669 -241.09172)
		(width 0.101854)
		(layer "F.Cu")
		(net "M_E_CPU1_SB_CB<4>")
	)
	(segment
		(start 138.38174 -244.566948)
		(end 138.50747 -244.566948)
		(width 0.088646)
		(layer "F.Cu")
		(net "M_E_CPU1_SB_CB<4>")
	)
	(segment
		(start 140.147548 -244.740176)
		(end 140.310108 -244.740176)
		(width 0.1016)
		(layer "F.Cu")
		(net "M_E_CPU1_SB_CB<4>")
	)
	(segment
		(start 137.014712 -244.458744)
		(end 137.456418 -244.458744)
		(width 0.088646)
		(layer "F.Cu")
		(net "M_E_CPU1_SB_CB<4>")
	)
	(segment
		(start 137.694924 -244.967506)
		(end 138.135614 -244.967506)
		(width 0.088646)
		(layer "F.Cu")
		(net "M_E_CPU1_SB_CB<4>")
	)
	(segment
		(start 149.052026 -241.19205)
		(end 149.813772 -241.19205)
		(width 0.20066)
		(layer "F.Cu")
		(net "M_E_CPU1_SB_CB<4>")
	)
	(segment
		(start 148.142706 -241.39271)
		(end 148.142706 -241.739674)
		(width 0.20066)
		(layer "F.Cu")
		(net "M_E_CPU1_SB_CB<4>")
	)
	(segment
		(start 163.787582 -233.01706)
		(end 162.913568 -233.01706)
		(width 0.20066)
		(layer "F.Cu")
		(net "M_E_CPU1_SB_CB<3>")
	)
	(segment
		(start 169.357548 -233.016806)
		(end 168.857676 -232.516934)
		(width 0.20066)
		(layer "F.Cu")
		(net "M_E_CPU1_SB_CB<3>")
	)
	(segment
		(start 140.075666 -240.380774)
		(end 140.339318 -240.117122)
		(width 0.088646)
		(layer "F.Cu")
		(net "M_E_CPU1_SB_CB<3>")
	)
	(segment
		(start 165.132004 -233.441748)
		(end 165.031928 -233.441748)
		(width 0.20066)
		(layer "F.Cu")
		(net "M_E_CPU1_SB_CB<3>")
	)
	(segment
		(start 157.11932 -233.461814)
		(end 157.600396 -233.461814)
		(width 0.20066)
		(layer "F.Cu")
		(net "M_E_CPU1_SB_CB<3>")
	)
	(segment
		(start 140.339318 -240.117122)
		(end 141.1605 -239.29594)
		(width 0.1016)
		(layer "F.Cu")
		(net "M_E_CPU1_SB_CB<3>")
	)
	(segment
		(start 168.267888 -233.244136)
		(end 168.070276 -233.441748)
		(width 0.20066)
		(layer "F.Cu")
		(net "M_E_CPU1_SB_CB<3>")
	)
	(segment
		(start 153.134568 -232.462578)
		(end 154.013408 -233.341418)
		(width 0.20066)
		(layer "F.Cu")
		(net "M_E_CPU1_SB_CB<3>")
	)
	(segment
		(start 168.267888 -232.934764)
		(end 168.267888 -233.244136)
		(width 0.20066)
		(layer "F.Cu")
		(net "M_E_CPU1_SB_CB<3>")
	)
	(segment
		(start 157.620462 -233.441748)
		(end 157.813248 -233.441748)
		(width 0.101854)
		(layer "F.Cu")
		(net "M_E_CPU1_SB_CB<3>")
	)
	(segment
		(start 150.014178 -232.462578)
		(end 153.134568 -232.462578)
		(width 0.20066)
		(layer "F.Cu")
		(net "M_E_CPU1_SB_CB<3>")
	)
	(segment
		(start 148.27123 -234.205526)
		(end 150.014178 -232.462578)
		(width 0.20066)
		(layer "F.Cu")
		(net "M_E_CPU1_SB_CB<3>")
	)
	(segment
		(start 164.531802 -232.941622)
		(end 163.86302 -232.941622)
		(width 0.20066)
		(layer "F.Cu")
		(net "M_E_CPU1_SB_CB<3>")
	)
	(segment
		(start 167.588438 -233.441748)
		(end 167.341042 -233.441748)
		(width 0.101854)
		(layer "F.Cu")
		(net "M_E_CPU1_SB_CB<3>")
	)
	(segment
		(start 159.809434 -233.441748)
		(end 160.03143 -233.441748)
		(width 0.101854)
		(layer "F.Cu")
		(net "M_E_CPU1_SB_CB<3>")
	)
	(segment
		(start 167.341042 -233.441748)
		(end 165.374828 -233.441748)
		(width 0.1016)
		(layer "F.Cu")
		(net "M_E_CPU1_SB_CB<3>")
	)
	(segment
		(start 157.813248 -233.441748)
		(end 159.809434 -233.441748)
		(width 0.1016)
		(layer "F.Cu")
		(net "M_E_CPU1_SB_CB<3>")
	)
	(segment
		(start 168.501822 -232.516934)
		(end 168.26611 -232.752646)
		(width 0.20066)
		(layer "F.Cu")
		(net "M_E_CPU1_SB_CB<3>")
	)
	(segment
		(start 160.03143 -233.441748)
		(end 160.16478 -233.441748)
		(width 0.20066)
		(layer "F.Cu")
		(net "M_E_CPU1_SB_CB<3>")
	)
	(segment
		(start 168.857676 -232.516934)
		(end 168.501822 -232.516934)
		(width 0.20066)
		(layer "F.Cu")
		(net "M_E_CPU1_SB_CB<3>")
	)
	(segment
		(start 168.26611 -232.932986)
		(end 168.267888 -232.934764)
		(width 0.20066)
		(layer "F.Cu")
		(net "M_E_CPU1_SB_CB<3>")
	)
	(segment
		(start 160.589722 -233.016806)
		(end 162.913314 -233.016806)
		(width 0.20066)
		(layer "F.Cu")
		(net "M_E_CPU1_SB_CB<3>")
	)
	(segment
		(start 141.1605 -239.29594)
		(end 143.112998 -239.29594)
		(width 0.1016)
		(layer "F.Cu")
		(net "M_E_CPU1_SB_CB<3>")
	)
	(segment
		(start 160.16478 -233.441748)
		(end 160.589722 -233.016806)
		(width 0.20066)
		(layer "F.Cu")
		(net "M_E_CPU1_SB_CB<3>")
	)
	(segment
		(start 165.031928 -233.441748)
		(end 164.531802 -232.941622)
		(width 0.20066)
		(layer "F.Cu")
		(net "M_E_CPU1_SB_CB<3>")
	)
	(segment
		(start 143.112998 -239.29594)
		(end 148.013928 -234.39501)
		(width 0.1016)
		(layer "F.Cu")
		(net "M_E_CPU1_SB_CB<3>")
	)
	(segment
		(start 157.600396 -233.461814)
		(end 157.620462 -233.441748)
		(width 0.101854)
		(layer "F.Cu")
		(net "M_E_CPU1_SB_CB<3>")
	)
	(segment
		(start 148.081746 -234.39501)
		(end 148.27123 -234.205526)
		(width 0.1016)
		(layer "F.Cu")
		(net "M_E_CPU1_SB_CB<3>")
	)
	(segment
		(start 154.013408 -233.341418)
		(end 156.998924 -233.341418)
		(width 0.20066)
		(layer "F.Cu")
		(net "M_E_CPU1_SB_CB<3>")
	)
	(segment
		(start 168.070276 -233.441748)
		(end 167.588438 -233.441748)
		(width 0.20066)
		(layer "F.Cu")
		(net "M_E_CPU1_SB_CB<3>")
	)
	(segment
		(start 163.86302 -232.941622)
		(end 163.787582 -233.01706)
		(width 0.20066)
		(layer "F.Cu")
		(net "M_E_CPU1_SB_CB<3>")
	)
	(segment
		(start 168.26611 -232.752646)
		(end 168.26611 -232.932986)
		(width 0.20066)
		(layer "F.Cu")
		(net "M_E_CPU1_SB_CB<3>")
	)
	(segment
		(start 162.913568 -233.01706)
		(end 162.913314 -233.016806)
		(width 0.20066)
		(layer "F.Cu")
		(net "M_E_CPU1_SB_CB<3>")
	)
	(segment
		(start 170.457114 -233.016806)
		(end 169.357548 -233.016806)
		(width 0.20066)
		(layer "F.Cu")
		(net "M_E_CPU1_SB_CB<3>")
	)
	(segment
		(start 165.374828 -233.441748)
		(end 165.132004 -233.441748)
		(width 0.101854)
		(layer "F.Cu")
		(net "M_E_CPU1_SB_CB<3>")
	)
	(segment
		(start 148.013928 -234.39501)
		(end 148.081746 -234.39501)
		(width 0.1016)
		(layer "F.Cu")
		(net "M_E_CPU1_SB_CB<3>")
	)
	(segment
		(start 139.114784 -240.779046)
		(end 140.075666 -240.380774)
		(width 0.088646)
		(layer "F.Cu")
		(net "M_E_CPU1_SB_CB<3>")
	)
	(segment
		(start 156.998924 -233.341418)
		(end 157.11932 -233.461814)
		(width 0.20066)
		(layer "F.Cu")
		(net "M_E_CPU1_SB_CB<3>")
	)
	(segment
		(start 138.978894 -240.779046)
		(end 139.114784 -240.779046)
		(width 0.088646)
		(layer "F.Cu")
		(net "M_E_CPU1_SB_CB<3>")
	)
	(segment
		(start 137.954766 -241.203226)
		(end 138.978894 -240.779046)
		(width 0.088646)
		(layer "F.Cu")
		(net "M_E_CPU1_SB_CB<3>")
	)
	(segment
		(start 148.265896 -235.494322)
		(end 148.92528 -235.494322)
		(width 0.20066)
		(layer "F.Cu")
		(net "M_E_CPU1_SB_CB<2>")
	)
	(segment
		(start 165.366954 -235.14177)
		(end 165.171628 -235.14177)
		(width 0.101854)
		(layer "F.Cu")
		(net "M_E_CPU1_SB_CB<2>")
	)
	(segment
		(start 154.755596 -235.24718)
		(end 154.755596 -234.879896)
		(width 0.20066)
		(layer "F.Cu")
		(net "M_E_CPU1_SB_CB<2>")
	)
	(segment
		(start 167.356282 -235.14177)
		(end 165.366954 -235.14177)
		(width 0.1016)
		(layer "F.Cu")
		(net "M_E_CPU1_SB_CB<2>")
	)
	(segment
		(start 157.41396 -234.282742)
		(end 157.621986 -234.282742)
		(width 0.20066)
		(layer "F.Cu")
		(net "M_E_CPU1_SB_CB<2>")
	)
	(segment
		(start 159.950658 -234.291632)
		(end 159.971486 -234.270804)
		(width 0.101854)
		(layer "F.Cu")
		(net "M_E_CPU1_SB_CB<2>")
	)
	(segment
		(start 168.343326 -234.601766)
		(end 168.343326 -234.957874)
		(width 0.20066)
		(layer "F.Cu")
		(net "M_E_CPU1_SB_CB<2>")
	)
	(segment
		(start 162.913822 -234.717082)
		(end 162.913314 -234.716574)
		(width 0.20066)
		(layer "F.Cu")
		(net "M_E_CPU1_SB_CB<2>")
	)
	(segment
		(start 159.971486 -234.270804)
		(end 160.14065 -234.270804)
		(width 0.20066)
		(layer "F.Cu")
		(net "M_E_CPU1_SB_CB<2>")
	)
	(segment
		(start 168.865804 -234.401106)
		(end 168.543986 -234.401106)
		(width 0.20066)
		(layer "F.Cu")
		(net "M_E_CPU1_SB_CB<2>")
	)
	(segment
		(start 143.365982 -239.90554)
		(end 147.7772 -235.494322)
		(width 0.1016)
		(layer "F.Cu")
		(net "M_E_CPU1_SB_CB<2>")
	)
	(segment
		(start 164.502338 -234.626404)
		(end 163.956492 -234.626404)
		(width 0.20066)
		(layer "F.Cu")
		(net "M_E_CPU1_SB_CB<2>")
	)
	(segment
		(start 163.865814 -234.717082)
		(end 162.913822 -234.717082)
		(width 0.20066)
		(layer "F.Cu")
		(net "M_E_CPU1_SB_CB<2>")
	)
	(segment
		(start 167.84193 -235.14177)
		(end 167.356282 -235.14177)
		(width 0.101854)
		(layer "F.Cu")
		(net "M_E_CPU1_SB_CB<2>")
	)
	(segment
		(start 154.222196 -235.405422)
		(end 154.597354 -235.405422)
		(width 0.20066)
		(layer "F.Cu")
		(net "M_E_CPU1_SB_CB<2>")
	)
	(segment
		(start 141.43482 -239.90554)
		(end 143.365982 -239.90554)
		(width 0.1016)
		(layer "F.Cu")
		(net "M_E_CPU1_SB_CB<2>")
	)
	(segment
		(start 154.755596 -234.879896)
		(end 154.956256 -234.679236)
		(width 0.20066)
		(layer "F.Cu")
		(net "M_E_CPU1_SB_CB<2>")
	)
	(segment
		(start 140.24737 -241.09299)
		(end 140.451078 -240.889282)
		(width 0.088646)
		(layer "F.Cu")
		(net "M_E_CPU1_SB_CB<2>")
	)
	(segment
		(start 157.017466 -234.679236)
		(end 157.41396 -234.282742)
		(width 0.20066)
		(layer "F.Cu")
		(net "M_E_CPU1_SB_CB<2>")
	)
	(segment
		(start 138.424666 -242.017042)
		(end 138.425174 -242.017296)
		(width 0.088646)
		(layer "F.Cu")
		(net "M_E_CPU1_SB_CB<2>")
	)
	(segment
		(start 170.457114 -234.716574)
		(end 169.181272 -234.716574)
		(width 0.20066)
		(layer "F.Cu")
		(net "M_E_CPU1_SB_CB<2>")
	)
	(segment
		(start 161.997898 -234.617768)
		(end 162.096704 -234.716574)
		(width 0.20066)
		(layer "F.Cu")
		(net "M_E_CPU1_SB_CB<2>")
	)
	(segment
		(start 165.031674 -235.15574)
		(end 164.502338 -234.626404)
		(width 0.20066)
		(layer "F.Cu")
		(net "M_E_CPU1_SB_CB<2>")
	)
	(segment
		(start 140.24737 -241.324638)
		(end 140.24737 -241.09299)
		(width 0.088646)
		(layer "F.Cu")
		(net "M_E_CPU1_SB_CB<2>")
	)
	(segment
		(start 139.703302 -241.868706)
		(end 140.24737 -241.324638)
		(width 0.088646)
		(layer "F.Cu")
		(net "M_E_CPU1_SB_CB<2>")
	)
	(segment
		(start 169.181272 -234.716574)
		(end 168.865804 -234.401106)
		(width 0.20066)
		(layer "F.Cu")
		(net "M_E_CPU1_SB_CB<2>")
	)
	(segment
		(start 153.48585 -234.669076)
		(end 154.222196 -235.405422)
		(width 0.20066)
		(layer "F.Cu")
		(net "M_E_CPU1_SB_CB<2>")
	)
	(segment
		(start 168.343326 -234.957874)
		(end 168.142666 -235.158534)
		(width 0.20066)
		(layer "F.Cu")
		(net "M_E_CPU1_SB_CB<2>")
	)
	(segment
		(start 168.543986 -234.401106)
		(end 168.343326 -234.601766)
		(width 0.20066)
		(layer "F.Cu")
		(net "M_E_CPU1_SB_CB<2>")
	)
	(segment
		(start 138.425174 -242.017296)
		(end 138.692636 -241.906806)
		(width 0.088646)
		(layer "F.Cu")
		(net "M_E_CPU1_SB_CB<2>")
	)
	(segment
		(start 140.451078 -240.889282)
		(end 141.43482 -239.90554)
		(width 0.1016)
		(layer "F.Cu")
		(net "M_E_CPU1_SB_CB<2>")
	)
	(segment
		(start 138.884152 -241.868706)
		(end 139.703302 -241.868706)
		(width 0.088646)
		(layer "F.Cu")
		(net "M_E_CPU1_SB_CB<2>")
	)
	(segment
		(start 165.157658 -235.15574)
		(end 165.031674 -235.15574)
		(width 0.20066)
		(layer "F.Cu")
		(net "M_E_CPU1_SB_CB<2>")
	)
	(segment
		(start 167.858694 -235.158534)
		(end 167.84193 -235.14177)
		(width 0.101854)
		(layer "F.Cu")
		(net "M_E_CPU1_SB_CB<2>")
	)
	(segment
		(start 165.171628 -235.14177)
		(end 165.157658 -235.15574)
		(width 0.101854)
		(layer "F.Cu")
		(net "M_E_CPU1_SB_CB<2>")
	)
	(segment
		(start 162.096704 -234.716574)
		(end 162.913314 -234.716574)
		(width 0.20066)
		(layer "F.Cu")
		(net "M_E_CPU1_SB_CB<2>")
	)
	(segment
		(start 160.14065 -234.270804)
		(end 160.487614 -234.617768)
		(width 0.20066)
		(layer "F.Cu")
		(net "M_E_CPU1_SB_CB<2>")
	)
	(segment
		(start 163.956492 -234.626404)
		(end 163.865814 -234.717082)
		(width 0.20066)
		(layer "F.Cu")
		(net "M_E_CPU1_SB_CB<2>")
	)
	(segment
		(start 147.7772 -235.494322)
		(end 148.265896 -235.494322)
		(width 0.1016)
		(layer "F.Cu")
		(net "M_E_CPU1_SB_CB<2>")
	)
	(segment
		(start 149.750526 -234.669076)
		(end 153.48585 -234.669076)
		(width 0.20066)
		(layer "F.Cu")
		(net "M_E_CPU1_SB_CB<2>")
	)
	(segment
		(start 159.808418 -234.291632)
		(end 159.950658 -234.291632)
		(width 0.101854)
		(layer "F.Cu")
		(net "M_E_CPU1_SB_CB<2>")
	)
	(segment
		(start 148.92528 -235.494322)
		(end 149.750526 -234.669076)
		(width 0.20066)
		(layer "F.Cu")
		(net "M_E_CPU1_SB_CB<2>")
	)
	(segment
		(start 168.142666 -235.158534)
		(end 167.858694 -235.158534)
		(width 0.20066)
		(layer "F.Cu")
		(net "M_E_CPU1_SB_CB<2>")
	)
	(segment
		(start 154.956256 -234.679236)
		(end 157.017466 -234.679236)
		(width 0.20066)
		(layer "F.Cu")
		(net "M_E_CPU1_SB_CB<2>")
	)
	(segment
		(start 157.621986 -234.282742)
		(end 157.630876 -234.291632)
		(width 0.101854)
		(layer "F.Cu")
		(net "M_E_CPU1_SB_CB<2>")
	)
	(segment
		(start 157.630876 -234.291632)
		(end 157.805374 -234.291632)
		(width 0.101854)
		(layer "F.Cu")
		(net "M_E_CPU1_SB_CB<2>")
	)
	(segment
		(start 160.487614 -234.617768)
		(end 161.997898 -234.617768)
		(width 0.20066)
		(layer "F.Cu")
		(net "M_E_CPU1_SB_CB<2>")
	)
	(segment
		(start 154.597354 -235.405422)
		(end 154.755596 -235.24718)
		(width 0.20066)
		(layer "F.Cu")
		(net "M_E_CPU1_SB_CB<2>")
	)
	(segment
		(start 157.805374 -234.291632)
		(end 159.808418 -234.291632)
		(width 0.1016)
		(layer "F.Cu")
		(net "M_E_CPU1_SB_CB<2>")
	)
	(arc
		(start 138.692636 -241.906806)
		(mid 138.786518 -241.878318)
		(end 138.884152 -241.868706)
		(width 0.088646)
		(layer "F.Cu")
		(net "M_E_CPU1_SB_CB<2>")
	)
	(segment
		(start 143.23949 -239.60074)
		(end 147.98929 -234.85094)
		(width 0.1016)
		(layer "F.Cu")
		(net "M_E_CPU1_SB_CB<1>")
	)
	(segment
		(start 139.612624 -241.650266)
		(end 139.899136 -241.363754)
		(width 0.088646)
		(layer "F.Cu")
		(net "M_E_CPU1_SB_CB<1>")
	)
	(segment
		(start 161.90976 -233.441748)
		(end 161.733484 -233.441748)
		(width 0.101854)
		(layer "F.Cu")
		(net "M_E_CPU1_SB_CB<1>")
	)
	(segment
		(start 137.014712 -241.203226)
		(end 137.410698 -241.203226)
		(width 0.088646)
		(layer "F.Cu")
		(net "M_E_CPU1_SB_CB<1>")
	)
	(segment
		(start 161.161984 -233.927904)
		(end 160.963102 -234.126786)
		(width 0.20066)
		(layer "F.Cu")
		(net "M_E_CPU1_SB_CB<1>")
	)
	(segment
		(start 147.98929 -234.85094)
		(end 148.265896 -234.85094)
		(width 0.1016)
		(layer "F.Cu")
		(net "M_E_CPU1_SB_CB<1>")
	)
	(segment
		(start 137.655554 -241.650266)
		(end 139.612624 -241.650266)
		(width 0.088646)
		(layer "F.Cu")
		(net "M_E_CPU1_SB_CB<1>")
	)
	(segment
		(start 139.899136 -241.009932)
		(end 140.235432 -240.673636)
		(width 0.088646)
		(layer "F.Cu")
		(net "M_E_CPU1_SB_CB<1>")
	)
	(segment
		(start 161.362644 -233.42854)
		(end 161.161984 -233.6292)
		(width 0.20066)
		(layer "F.Cu")
		(net "M_E_CPU1_SB_CB<1>")
	)
	(segment
		(start 152.115266 -233.305096)
		(end 152.315926 -233.104436)
		(width 0.20066)
		(layer "F.Cu")
		(net "M_E_CPU1_SB_CB<1>")
	)
	(segment
		(start 150.743666 -233.305096)
		(end 150.944326 -233.104436)
		(width 0.20066)
		(layer "F.Cu")
		(net "M_E_CPU1_SB_CB<1>")
	)
	(segment
		(start 156.938726 -233.86669)
		(end 158.813246 -233.86669)
		(width 0.20066)
		(layer "F.Cu")
		(net "M_E_CPU1_SB_CB<1>")
	)
	(segment
		(start 161.733484 -233.441748)
		(end 161.720276 -233.42854)
		(width 0.101854)
		(layer "F.Cu")
		(net "M_E_CPU1_SB_CB<1>")
	)
	(segment
		(start 161.161984 -233.6292)
		(end 161.161984 -233.927904)
		(width 0.20066)
		(layer "F.Cu")
		(net "M_E_CPU1_SB_CB<1>")
	)
	(segment
		(start 165.407594 -233.86669)
		(end 165.320472 -233.953812)
		(width 0.20066)
		(layer "F.Cu")
		(net "M_E_CPU1_SB_CB<1>")
	)
	(segment
		(start 137.410698 -241.203226)
		(end 137.504678 -241.297206)
		(width 0.088646)
		(layer "F.Cu")
		(net "M_E_CPU1_SB_CB<1>")
	)
	(segment
		(start 151.228806 -233.104436)
		(end 151.429466 -233.305096)
		(width 0.20066)
		(layer "F.Cu")
		(net "M_E_CPU1_SB_CB<1>")
	)
	(segment
		(start 139.899136 -241.363754)
		(end 139.899136 -241.009932)
		(width 0.088646)
		(layer "F.Cu")
		(net "M_E_CPU1_SB_CB<1>")
	)
	(segment
		(start 150.543006 -234.029504)
		(end 150.743666 -233.828844)
		(width 0.20066)
		(layer "F.Cu")
		(net "M_E_CPU1_SB_CB<1>")
	)
	(segment
		(start 152.315926 -233.104436)
		(end 152.600406 -233.104436)
		(width 0.20066)
		(layer "F.Cu")
		(net "M_E_CPU1_SB_CB<1>")
	)
	(segment
		(start 148.65223 -234.85094)
		(end 149.473666 -234.029504)
		(width 0.20066)
		(layer "F.Cu")
		(net "M_E_CPU1_SB_CB<1>")
	)
	(segment
		(start 149.473666 -234.029504)
		(end 150.543006 -234.029504)
		(width 0.20066)
		(layer "F.Cu")
		(net "M_E_CPU1_SB_CB<1>")
	)
	(segment
		(start 150.743666 -233.828844)
		(end 150.743666 -233.305096)
		(width 0.20066)
		(layer "F.Cu")
		(net "M_E_CPU1_SB_CB<1>")
	)
	(segment
		(start 163.877244 -233.441748)
		(end 161.90976 -233.441748)
		(width 0.1016)
		(layer "F.Cu")
		(net "M_E_CPU1_SB_CB<1>")
	)
	(segment
		(start 160.67913 -234.126786)
		(end 160.419288 -233.866944)
		(width 0.20066)
		(layer "F.Cu")
		(net "M_E_CPU1_SB_CB<1>")
	)
	(segment
		(start 160.963102 -234.126786)
		(end 160.67913 -234.126786)
		(width 0.20066)
		(layer "F.Cu")
		(net "M_E_CPU1_SB_CB<1>")
	)
	(segment
		(start 151.630126 -234.029504)
		(end 151.914606 -234.029504)
		(width 0.20066)
		(layer "F.Cu")
		(net "M_E_CPU1_SB_CB<1>")
	)
	(segment
		(start 137.504678 -241.49939)
		(end 137.655554 -241.650266)
		(width 0.088646)
		(layer "F.Cu")
		(net "M_E_CPU1_SB_CB<1>")
	)
	(segment
		(start 164.069268 -233.441748)
		(end 163.877244 -233.441748)
		(width 0.101854)
		(layer "F.Cu")
		(net "M_E_CPU1_SB_CB<1>")
	)
	(segment
		(start 164.960554 -233.953812)
		(end 164.430964 -233.424222)
		(width 0.20066)
		(layer "F.Cu")
		(net "M_E_CPU1_SB_CB<1>")
	)
	(segment
		(start 164.430964 -233.424222)
		(end 164.086794 -233.424222)
		(width 0.20066)
		(layer "F.Cu")
		(net "M_E_CPU1_SB_CB<1>")
	)
	(segment
		(start 160.419288 -233.866944)
		(end 158.8135 -233.866944)
		(width 0.20066)
		(layer "F.Cu")
		(net "M_E_CPU1_SB_CB<1>")
	)
	(segment
		(start 152.600406 -233.104436)
		(end 152.801066 -233.305096)
		(width 0.20066)
		(layer "F.Cu")
		(net "M_E_CPU1_SB_CB<1>")
	)
	(segment
		(start 152.801066 -233.305096)
		(end 152.801066 -233.828844)
		(width 0.20066)
		(layer "F.Cu")
		(net "M_E_CPU1_SB_CB<1>")
	)
	(segment
		(start 156.775912 -234.029504)
		(end 156.938726 -233.86669)
		(width 0.20066)
		(layer "F.Cu")
		(net "M_E_CPU1_SB_CB<1>")
	)
	(segment
		(start 151.429466 -233.305096)
		(end 151.429466 -233.828844)
		(width 0.20066)
		(layer "F.Cu")
		(net "M_E_CPU1_SB_CB<1>")
	)
	(segment
		(start 148.265896 -234.85094)
		(end 148.65223 -234.85094)
		(width 0.20066)
		(layer "F.Cu")
		(net "M_E_CPU1_SB_CB<1>")
	)
	(segment
		(start 152.801066 -233.828844)
		(end 153.001726 -234.029504)
		(width 0.20066)
		(layer "F.Cu")
		(net "M_E_CPU1_SB_CB<1>")
	)
	(segment
		(start 158.8135 -233.866944)
		(end 158.813246 -233.86669)
		(width 0.20066)
		(layer "F.Cu")
		(net "M_E_CPU1_SB_CB<1>")
	)
	(segment
		(start 137.504678 -241.297206)
		(end 137.504678 -241.49939)
		(width 0.088646)
		(layer "F.Cu")
		(net "M_E_CPU1_SB_CB<1>")
	)
	(segment
		(start 164.086794 -233.424222)
		(end 164.069268 -233.441748)
		(width 0.101854)
		(layer "F.Cu")
		(net "M_E_CPU1_SB_CB<1>")
	)
	(segment
		(start 166.357046 -233.86669)
		(end 165.407594 -233.86669)
		(width 0.20066)
		(layer "F.Cu")
		(net "M_E_CPU1_SB_CB<1>")
	)
	(segment
		(start 150.944326 -233.104436)
		(end 151.228806 -233.104436)
		(width 0.20066)
		(layer "F.Cu")
		(net "M_E_CPU1_SB_CB<1>")
	)
	(segment
		(start 141.308328 -239.60074)
		(end 143.23949 -239.60074)
		(width 0.1016)
		(layer "F.Cu")
		(net "M_E_CPU1_SB_CB<1>")
	)
	(segment
		(start 140.235432 -240.673636)
		(end 141.308328 -239.60074)
		(width 0.1016)
		(layer "F.Cu")
		(net "M_E_CPU1_SB_CB<1>")
	)
	(segment
		(start 153.001726 -234.029504)
		(end 156.775912 -234.029504)
		(width 0.20066)
		(layer "F.Cu")
		(net "M_E_CPU1_SB_CB<1>")
	)
	(segment
		(start 165.320472 -233.953812)
		(end 164.960554 -233.953812)
		(width 0.20066)
		(layer "F.Cu")
		(net "M_E_CPU1_SB_CB<1>")
	)
	(segment
		(start 161.720276 -233.42854)
		(end 161.362644 -233.42854)
		(width 0.20066)
		(layer "F.Cu")
		(net "M_E_CPU1_SB_CB<1>")
	)
	(segment
		(start 151.429466 -233.828844)
		(end 151.630126 -234.029504)
		(width 0.20066)
		(layer "F.Cu")
		(net "M_E_CPU1_SB_CB<1>")
	)
	(segment
		(start 151.914606 -234.029504)
		(end 152.115266 -233.828844)
		(width 0.20066)
		(layer "F.Cu")
		(net "M_E_CPU1_SB_CB<1>")
	)
	(segment
		(start 152.115266 -233.828844)
		(end 152.115266 -233.305096)
		(width 0.20066)
		(layer "F.Cu")
		(net "M_E_CPU1_SB_CB<1>")
	)
	(segment
		(start 163.91255 -235.14177)
		(end 161.927286 -235.14177)
		(width 0.1016)
		(layer "F.Cu")
		(net "M_E_CPU1_SB_CB<0>")
	)
	(segment
		(start 150.718774 -235.95457)
		(end 150.919434 -236.15523)
		(width 0.20066)
		(layer "F.Cu")
		(net "M_E_CPU1_SB_CB<0>")
	)
	(segment
		(start 164.446458 -235.14177)
		(end 164.236908 -235.14177)
		(width 0.20066)
		(layer "F.Cu")
		(net "M_E_CPU1_SB_CB<0>")
	)
	(segment
		(start 155.148788 -236.09173)
		(end 155.349448 -235.89107)
		(width 0.20066)
		(layer "F.Cu")
		(net "M_E_CPU1_SB_CB<0>")
	)
	(segment
		(start 155.349448 -235.529628)
		(end 155.550108 -235.328968)
		(width 0.20066)
		(layer "F.Cu")
		(net "M_E_CPU1_SB_CB<0>")
	)
	(segment
		(start 151.404574 -235.95457)
		(end 151.404574 -235.509308)
		(width 0.20066)
		(layer "F.Cu")
		(net "M_E_CPU1_SB_CB<0>")
	)
	(segment
		(start 161.927286 -235.14177)
		(end 161.47923 -235.14177)
		(width 0.101854)
		(layer "F.Cu")
		(net "M_E_CPU1_SB_CB<0>")
	)
	(segment
		(start 138.203686 -242.442746)
		(end 138.264646 -242.442746)
		(width 0.088646)
		(layer "F.Cu")
		(net "M_E_CPU1_SB_CB<0>")
	)
	(segment
		(start 138.63955 -242.320572)
		(end 138.887708 -242.074446)
		(width 0.088646)
		(layer "F.Cu")
		(net "M_E_CPU1_SB_CB<0>")
	)
	(segment
		(start 140.546074 -241.228626)
		(end 140.668502 -241.106198)
		(width 0.088646)
		(layer "F.Cu")
		(net "M_E_CPU1_SB_CB<0>")
	)
	(segment
		(start 161.347404 -235.116116)
		(end 160.893252 -235.570268)
		(width 0.20066)
		(layer "F.Cu")
		(net "M_E_CPU1_SB_CB<0>")
	)
	(segment
		(start 137.150602 -242.244626)
		(end 137.389362 -242.382802)
		(width 0.088646)
		(layer "F.Cu")
		(net "M_E_CPU1_SB_CB<0>")
	)
	(segment
		(start 150.032974 -235.509308)
		(end 150.233634 -235.308648)
		(width 0.20066)
		(layer "F.Cu")
		(net "M_E_CPU1_SB_CB<0>")
	)
	(segment
		(start 161.453576 -235.116116)
		(end 161.347404 -235.116116)
		(width 0.20066)
		(layer "F.Cu")
		(net "M_E_CPU1_SB_CB<0>")
	)
	(segment
		(start 136.538716 -242.023392)
		(end 136.538716 -242.155726)
		(width 0.088646)
		(layer "F.Cu")
		(net "M_E_CPU1_SB_CB<0>")
	)
	(segment
		(start 159.36849 -235.566712)
		(end 158.813246 -235.566712)
		(width 0.20066)
		(layer "F.Cu")
		(net "M_E_CPU1_SB_CB<0>")
	)
	(segment
		(start 150.032974 -235.951776)
		(end 150.032974 -235.509308)
		(width 0.20066)
		(layer "F.Cu")
		(net "M_E_CPU1_SB_CB<0>")
	)
	(segment
		(start 152.090374 -235.90631)
		(end 152.291034 -236.10697)
		(width 0.20066)
		(layer "F.Cu")
		(net "M_E_CPU1_SB_CB<0>")
	)
	(segment
		(start 150.919434 -236.15523)
		(end 151.203914 -236.15523)
		(width 0.20066)
		(layer "F.Cu")
		(net "M_E_CPU1_SB_CB<0>")
	)
	(segment
		(start 153.461974 -235.549694)
		(end 153.461974 -235.89107)
		(width 0.20066)
		(layer "F.Cu")
		(net "M_E_CPU1_SB_CB<0>")
	)
	(segment
		(start 150.518114 -235.308648)
		(end 150.718774 -235.509308)
		(width 0.20066)
		(layer "F.Cu")
		(net "M_E_CPU1_SB_CB<0>")
	)
	(segment
		(start 160.60928 -235.570268)
		(end 160.192974 -235.153962)
		(width 0.20066)
		(layer "F.Cu")
		(net "M_E_CPU1_SB_CB<0>")
	)
	(segment
		(start 138.488166 -242.39982)
		(end 138.565128 -242.36934)
		(width 0.088646)
		(layer "F.Cu")
		(net "M_E_CPU1_SB_CB<0>")
	)
	(segment
		(start 157.409642 -235.566712)
		(end 158.813246 -235.566712)
		(width 0.20066)
		(layer "F.Cu")
		(net "M_E_CPU1_SB_CB<0>")
	)
	(segment
		(start 153.261314 -235.349034)
		(end 153.461974 -235.549694)
		(width 0.20066)
		(layer "F.Cu")
		(net "M_E_CPU1_SB_CB<0>")
	)
	(segment
		(start 152.976834 -235.349034)
		(end 153.261314 -235.349034)
		(width 0.20066)
		(layer "F.Cu")
		(net "M_E_CPU1_SB_CB<0>")
	)
	(segment
		(start 149.832314 -236.152436)
		(end 150.032974 -235.951776)
		(width 0.20066)
		(layer "F.Cu")
		(net "M_E_CPU1_SB_CB<0>")
	)
	(segment
		(start 153.461974 -235.89107)
		(end 153.662634 -236.09173)
		(width 0.20066)
		(layer "F.Cu")
		(net "M_E_CPU1_SB_CB<0>")
	)
	(segment
		(start 160.192974 -235.153962)
		(end 159.78124 -235.153962)
		(width 0.20066)
		(layer "F.Cu")
		(net "M_E_CPU1_SB_CB<0>")
	)
	(segment
		(start 153.662634 -236.09173)
		(end 155.148788 -236.09173)
		(width 0.20066)
		(layer "F.Cu")
		(net "M_E_CPU1_SB_CB<0>")
	)
	(segment
		(start 152.776174 -235.549694)
		(end 152.976834 -235.349034)
		(width 0.20066)
		(layer "F.Cu")
		(net "M_E_CPU1_SB_CB<0>")
	)
	(segment
		(start 147.550378 -236.152436)
		(end 147.961096 -236.152436)
		(width 0.1016)
		(layer "F.Cu")
		(net "M_E_CPU1_SB_CB<0>")
	)
	(segment
		(start 151.404574 -235.509308)
		(end 151.605234 -235.308648)
		(width 0.20066)
		(layer "F.Cu")
		(net "M_E_CPU1_SB_CB<0>")
	)
	(segment
		(start 161.47923 -235.14177)
		(end 161.453576 -235.116116)
		(width 0.101854)
		(layer "F.Cu")
		(net "M_E_CPU1_SB_CB<0>")
	)
	(segment
		(start 140.546074 -241.317018)
		(end 140.546074 -241.228626)
		(width 0.088646)
		(layer "F.Cu")
		(net "M_E_CPU1_SB_CB<0>")
	)
	(segment
		(start 152.291034 -236.10697)
		(end 152.575514 -236.10697)
		(width 0.20066)
		(layer "F.Cu")
		(net "M_E_CPU1_SB_CB<0>")
	)
	(segment
		(start 155.349448 -235.89107)
		(end 155.349448 -235.529628)
		(width 0.20066)
		(layer "F.Cu")
		(net "M_E_CPU1_SB_CB<0>")
	)
	(segment
		(start 138.887708 -242.074446)
		(end 139.788646 -242.074446)
		(width 0.088646)
		(layer "F.Cu")
		(net "M_E_CPU1_SB_CB<0>")
	)
	(segment
		(start 140.668502 -241.106198)
		(end 141.56436 -240.21034)
		(width 0.1016)
		(layer "F.Cu")
		(net "M_E_CPU1_SB_CB<0>")
	)
	(segment
		(start 150.718774 -235.509308)
		(end 150.718774 -235.95457)
		(width 0.20066)
		(layer "F.Cu")
		(net "M_E_CPU1_SB_CB<0>")
	)
	(segment
		(start 136.545066 -242.017042)
		(end 136.538716 -242.023392)
		(width 0.088646)
		(layer "F.Cu")
		(net "M_E_CPU1_SB_CB<0>")
	)
	(segment
		(start 136.627616 -242.244626)
		(end 137.150602 -242.244626)
		(width 0.088646)
		(layer "F.Cu")
		(net "M_E_CPU1_SB_CB<0>")
	)
	(segment
		(start 152.575514 -236.10697)
		(end 152.776174 -235.90631)
		(width 0.20066)
		(layer "F.Cu")
		(net "M_E_CPU1_SB_CB<0>")
	)
	(segment
		(start 159.78124 -235.153962)
		(end 159.36849 -235.566712)
		(width 0.20066)
		(layer "F.Cu")
		(net "M_E_CPU1_SB_CB<0>")
	)
	(segment
		(start 151.203914 -236.15523)
		(end 151.404574 -235.95457)
		(width 0.20066)
		(layer "F.Cu")
		(net "M_E_CPU1_SB_CB<0>")
	)
	(segment
		(start 151.605234 -235.308648)
		(end 151.889714 -235.308648)
		(width 0.20066)
		(layer "F.Cu")
		(net "M_E_CPU1_SB_CB<0>")
	)
	(segment
		(start 152.776174 -235.90631)
		(end 152.776174 -235.549694)
		(width 0.20066)
		(layer "F.Cu")
		(net "M_E_CPU1_SB_CB<0>")
	)
	(segment
		(start 143.492474 -240.21034)
		(end 147.550378 -236.152436)
		(width 0.1016)
		(layer "F.Cu")
		(net "M_E_CPU1_SB_CB<0>")
	)
	(segment
		(start 137.580116 -242.450874)
		(end 137.598658 -242.453922)
		(width 0.088646)
		(layer "F.Cu")
		(net "M_E_CPU1_SB_CB<0>")
	)
	(segment
		(start 151.889714 -235.308648)
		(end 152.090374 -235.509308)
		(width 0.20066)
		(layer "F.Cu")
		(net "M_E_CPU1_SB_CB<0>")
	)
	(segment
		(start 164.8714 -235.566712)
		(end 164.446458 -235.14177)
		(width 0.20066)
		(layer "F.Cu")
		(net "M_E_CPU1_SB_CB<0>")
	)
	(segment
		(start 164.236908 -235.14177)
		(end 163.91255 -235.14177)
		(width 0.101854)
		(layer "F.Cu")
		(net "M_E_CPU1_SB_CB<0>")
	)
	(segment
		(start 150.233634 -235.308648)
		(end 150.518114 -235.308648)
		(width 0.20066)
		(layer "F.Cu")
		(net "M_E_CPU1_SB_CB<0>")
	)
	(segment
		(start 139.788646 -242.074446)
		(end 140.546074 -241.317018)
		(width 0.088646)
		(layer "F.Cu")
		(net "M_E_CPU1_SB_CB<0>")
	)
	(segment
		(start 147.961096 -236.152436)
		(end 149.832314 -236.152436)
		(width 0.20066)
		(layer "F.Cu")
		(net "M_E_CPU1_SB_CB<0>")
	)
	(segment
		(start 136.538716 -242.155726)
		(end 136.627616 -242.244626)
		(width 0.088646)
		(layer "F.Cu")
		(net "M_E_CPU1_SB_CB<0>")
	)
	(segment
		(start 152.090374 -235.509308)
		(end 152.090374 -235.90631)
		(width 0.20066)
		(layer "F.Cu")
		(net "M_E_CPU1_SB_CB<0>")
	)
	(segment
		(start 160.893252 -235.570268)
		(end 160.60928 -235.570268)
		(width 0.20066)
		(layer "F.Cu")
		(net "M_E_CPU1_SB_CB<0>")
	)
	(segment
		(start 141.56436 -240.21034)
		(end 143.492474 -240.21034)
		(width 0.1016)
		(layer "F.Cu")
		(net "M_E_CPU1_SB_CB<0>")
	)
	(segment
		(start 166.357046 -235.566712)
		(end 164.8714 -235.566712)
		(width 0.20066)
		(layer "F.Cu")
		(net "M_E_CPU1_SB_CB<0>")
	)
	(segment
		(start 157.171898 -235.328968)
		(end 157.409642 -235.566712)
		(width 0.20066)
		(layer "F.Cu")
		(net "M_E_CPU1_SB_CB<0>")
	)
	(segment
		(start 155.550108 -235.328968)
		(end 157.171898 -235.328968)
		(width 0.20066)
		(layer "F.Cu")
		(net "M_E_CPU1_SB_CB<0>")
	)
	(arc
		(start 138.099546 -242.399566)
		(mid 138.147326 -242.431491)
		(end 138.203686 -242.442746)
		(width 0.088646)
		(layer "F.Cu")
		(net "M_E_CPU1_SB_CB<0>")
	)
	(arc
		(start 138.264646 -242.442746)
		(mid 138.378446 -242.431899)
		(end 138.488166 -242.39982)
		(width 0.088646)
		(layer "F.Cu")
		(net "M_E_CPU1_SB_CB<0>")
	)
	(arc
		(start 137.598658 -242.453922)
		(mid 137.68929 -242.447017)
		(end 137.766806 -242.399566)
		(width 0.088646)
		(layer "F.Cu")
		(net "M_E_CPU1_SB_CB<0>")
	)
	(arc
		(start 137.389362 -242.382802)
		(mid 137.481632 -242.425542)
		(end 137.580116 -242.450874)
		(width 0.088646)
		(layer "F.Cu")
		(net "M_E_CPU1_SB_CB<0>")
	)
	(arc
		(start 137.766806 -242.399566)
		(mid 137.933176 -242.330653)
		(end 138.099546 -242.399566)
		(width 0.088646)
		(layer "F.Cu")
		(net "M_E_CPU1_SB_CB<0>")
	)
	(arc
		(start 138.565128 -242.36934)
		(mid 138.604797 -242.348712)
		(end 138.63955 -242.320572)
		(width 0.088646)
		(layer "F.Cu")
		(net "M_E_CPU1_SB_CB<0>")
	)
	(segment
		(start 146.834352 -246.175784)
		(end 149.485096 -246.175784)
		(width 0.20066)
		(layer "F.Cu")
		(net "M_E_CPU1_SB_CA<6>")
	)
	(segment
		(start 159.302704 -247.466612)
		(end 158.813246 -247.466612)
		(width 0.20066)
		(layer "F.Cu")
		(net "M_E_CPU1_SB_CA<6>")
	)
	(segment
		(start 160.185608 -247.850914)
		(end 159.687006 -247.850914)
		(width 0.20066)
		(layer "F.Cu")
		(net "M_E_CPU1_SB_CA<6>")
	)
	(segment
		(start 140.471652 -247.70588)
		(end 140.77315 -247.404382)
		(width 0.088646)
		(layer "F.Cu")
		(net "M_E_CPU1_SB_CA<6>")
	)
	(segment
		(start 151.480266 -248.170954)
		(end 157.103572 -248.170954)
		(width 0.20066)
		(layer "F.Cu")
		(net "M_E_CPU1_SB_CA<6>")
	)
	(segment
		(start 161.402014 -247.905778)
		(end 160.9979 -248.309892)
		(width 0.20066)
		(layer "F.Cu")
		(net "M_E_CPU1_SB_CA<6>")
	)
	(segment
		(start 161.891726 -247.905778)
		(end 161.402014 -247.905778)
		(width 0.20066)
		(layer "F.Cu")
		(net "M_E_CPU1_SB_CA<6>")
	)
	(segment
		(start 137.757154 -248.032524)
		(end 137.767568 -248.03862)
		(width 0.088646)
		(layer "F.Cu")
		(net "M_E_CPU1_SB_CA<6>")
	)
	(segment
		(start 166.357046 -247.466612)
		(end 165.449758 -247.466612)
		(width 0.20066)
		(layer "F.Cu")
		(net "M_E_CPU1_SB_CA<6>")
	)
	(segment
		(start 159.687006 -247.850914)
		(end 159.302704 -247.466612)
		(width 0.20066)
		(layer "F.Cu")
		(net "M_E_CPU1_SB_CA<6>")
	)
	(segment
		(start 164.339524 -247.901206)
		(end 163.923726 -247.901206)
		(width 0.20066)
		(layer "F.Cu")
		(net "M_E_CPU1_SB_CA<6>")
	)
	(segment
		(start 157.103572 -248.170954)
		(end 157.461204 -247.813322)
		(width 0.20066)
		(layer "F.Cu")
		(net "M_E_CPU1_SB_CA<6>")
	)
	(segment
		(start 163.923726 -247.901206)
		(end 163.914074 -247.891554)
		(width 0.1016)
		(layer "F.Cu")
		(net "M_E_CPU1_SB_CA<6>")
	)
	(segment
		(start 164.81933 -248.09704)
		(end 164.535358 -248.09704)
		(width 0.20066)
		(layer "F.Cu")
		(net "M_E_CPU1_SB_CA<6>")
	)
	(segment
		(start 157.905958 -247.466612)
		(end 158.813246 -247.466612)
		(width 0.20066)
		(layer "F.Cu")
		(net "M_E_CPU1_SB_CA<6>")
	)
	(segment
		(start 139.149582 -247.366536)
		(end 139.488926 -247.70588)
		(width 0.088646)
		(layer "F.Cu")
		(net "M_E_CPU1_SB_CA<6>")
	)
	(segment
		(start 136.387586 -248.026682)
		(end 136.783826 -248.026682)
		(width 0.088646)
		(layer "F.Cu")
		(net "M_E_CPU1_SB_CA<6>")
	)
	(segment
		(start 161.910776 -247.891554)
		(end 161.896552 -247.905778)
		(width 0.1016)
		(layer "F.Cu")
		(net "M_E_CPU1_SB_CA<6>")
	)
	(segment
		(start 140.77315 -247.404382)
		(end 140.98778 -247.189752)
		(width 0.1016)
		(layer "F.Cu")
		(net "M_E_CPU1_SB_CA<6>")
	)
	(segment
		(start 160.9979 -248.309892)
		(end 160.644586 -248.309892)
		(width 0.20066)
		(layer "F.Cu")
		(net "M_E_CPU1_SB_CA<6>")
	)
	(segment
		(start 163.914074 -247.891554)
		(end 161.910776 -247.891554)
		(width 0.1016)
		(layer "F.Cu")
		(net "M_E_CPU1_SB_CA<6>")
	)
	(segment
		(start 146.101562 -246.908574)
		(end 146.834352 -246.175784)
		(width 0.20066)
		(layer "F.Cu")
		(net "M_E_CPU1_SB_CA<6>")
	)
	(segment
		(start 164.535358 -248.09704)
		(end 164.339524 -247.901206)
		(width 0.20066)
		(layer "F.Cu")
		(net "M_E_CPU1_SB_CA<6>")
	)
	(segment
		(start 139.488926 -247.70588)
		(end 140.471652 -247.70588)
		(width 0.088646)
		(layer "F.Cu")
		(net "M_E_CPU1_SB_CA<6>")
	)
	(segment
		(start 157.461204 -247.813322)
		(end 157.559248 -247.813322)
		(width 0.20066)
		(layer "F.Cu")
		(net "M_E_CPU1_SB_CA<6>")
	)
	(segment
		(start 140.98778 -247.189752)
		(end 145.820384 -247.189752)
		(width 0.1016)
		(layer "F.Cu")
		(net "M_E_CPU1_SB_CA<6>")
	)
	(segment
		(start 160.644586 -248.309892)
		(end 160.185608 -247.850914)
		(width 0.20066)
		(layer "F.Cu")
		(net "M_E_CPU1_SB_CA<6>")
	)
	(segment
		(start 149.485096 -246.175784)
		(end 151.480266 -248.170954)
		(width 0.20066)
		(layer "F.Cu")
		(net "M_E_CPU1_SB_CA<6>")
	)
	(segment
		(start 136.075166 -247.714262)
		(end 136.387586 -248.026682)
		(width 0.088646)
		(layer "F.Cu")
		(net "M_E_CPU1_SB_CA<6>")
	)
	(segment
		(start 136.783826 -248.026682)
		(end 136.881362 -248.06402)
		(width 0.088646)
		(layer "F.Cu")
		(net "M_E_CPU1_SB_CA<6>")
	)
	(segment
		(start 161.896552 -247.905778)
		(end 161.891726 -247.905778)
		(width 0.101854)
		(layer "F.Cu")
		(net "M_E_CPU1_SB_CA<6>")
	)
	(segment
		(start 138.824462 -247.366536)
		(end 139.149582 -247.366536)
		(width 0.088646)
		(layer "F.Cu")
		(net "M_E_CPU1_SB_CA<6>")
	)
	(segment
		(start 138.421364 -247.555004)
		(end 138.824462 -247.366536)
		(width 0.088646)
		(layer "F.Cu")
		(net "M_E_CPU1_SB_CA<6>")
	)
	(segment
		(start 165.449758 -247.466612)
		(end 164.81933 -248.09704)
		(width 0.20066)
		(layer "F.Cu")
		(net "M_E_CPU1_SB_CA<6>")
	)
	(segment
		(start 145.820384 -247.189752)
		(end 146.101562 -246.908574)
		(width 0.1016)
		(layer "F.Cu")
		(net "M_E_CPU1_SB_CA<6>")
	)
	(segment
		(start 157.559248 -247.813322)
		(end 157.905958 -247.466612)
		(width 0.20066)
		(layer "F.Cu")
		(net "M_E_CPU1_SB_CA<6>")
	)
	(arc
		(start 137.20191 -248.03862)
		(mid 137.478723 -247.96275)
		(end 137.757154 -248.032524)
		(width 0.088646)
		(layer "F.Cu")
		(net "M_E_CPU1_SB_CA<6>")
	)
	(arc
		(start 136.881362 -248.06402)
		(mid 137.044507 -248.087502)
		(end 137.20191 -248.03862)
		(width 0.088646)
		(layer "F.Cu")
		(net "M_E_CPU1_SB_CA<6>")
	)
	(arc
		(start 137.767568 -248.03862)
		(mid 137.954766 -248.088763)
		(end 138.141964 -248.03862)
		(width 0.088646)
		(layer "F.Cu")
		(net "M_E_CPU1_SB_CA<6>")
	)
	(arc
		(start 138.141964 -248.03862)
		(mid 138.278989 -247.901507)
		(end 138.329162 -247.714262)
		(width 0.088646)
		(layer "F.Cu")
		(net "M_E_CPU1_SB_CA<6>")
	)
	(arc
		(start 138.329162 -247.714262)
		(mid 138.35395 -247.622308)
		(end 138.421364 -247.555004)
		(width 0.088646)
		(layer "F.Cu")
		(net "M_E_CPU1_SB_CA<6>")
	)
	(segment
		(start 161.691066 -248.31675)
		(end 162.913314 -248.31675)
		(width 0.20066)
		(layer "F.Cu")
		(net "M_E_CPU1_SB_CA<5>")
	)
	(segment
		(start 159.823658 -248.760234)
		(end 161.365438 -248.760234)
		(width 0.20066)
		(layer "F.Cu")
		(net "M_E_CPU1_SB_CA<5>")
	)
	(segment
		(start 140.99794 -247.712992)
		(end 141.21638 -247.494552)
		(width 0.1016)
		(layer "F.Cu")
		(net "M_E_CPU1_SB_CA<5>")
	)
	(segment
		(start 157.791658 -248.765568)
		(end 157.815026 -248.765568)
		(width 0.101854)
		(layer "F.Cu")
		(net "M_E_CPU1_SB_CA<5>")
	)
	(segment
		(start 138.894312 -247.714262)
		(end 138.995912 -247.714262)
		(width 0.088646)
		(layer "F.Cu")
		(net "M_E_CPU1_SB_CA<5>")
	)
	(segment
		(start 140.7287 -247.982232)
		(end 140.99794 -247.712992)
		(width 0.088646)
		(layer "F.Cu")
		(net "M_E_CPU1_SB_CA<5>")
	)
	(segment
		(start 165.36289 -248.741692)
		(end 165.354762 -248.74982)
		(width 0.1016)
		(layer "F.Cu")
		(net "M_E_CPU1_SB_CA<5>")
	)
	(segment
		(start 159.78378 -248.760234)
		(end 159.823658 -248.760234)
		(width 0.101854)
		(layer "F.Cu")
		(net "M_E_CPU1_SB_CA<5>")
	)
	(segment
		(start 168.080436 -248.264172)
		(end 167.98798 -248.356628)
		(width 0.20066)
		(layer "F.Cu")
		(net "M_E_CPU1_SB_CA<5>")
	)
	(segment
		(start 161.510726 -248.614946)
		(end 161.510726 -248.49709)
		(width 0.20066)
		(layer "F.Cu")
		(net "M_E_CPU1_SB_CA<5>")
	)
	(segment
		(start 141.21638 -247.494552)
		(end 146.428968 -247.494552)
		(width 0.1016)
		(layer "F.Cu")
		(net "M_E_CPU1_SB_CA<5>")
	)
	(segment
		(start 165.354762 -248.74982)
		(end 165.335458 -248.74982)
		(width 0.101854)
		(layer "F.Cu")
		(net "M_E_CPU1_SB_CA<5>")
	)
	(segment
		(start 161.510726 -248.49709)
		(end 161.691066 -248.31675)
		(width 0.20066)
		(layer "F.Cu")
		(net "M_E_CPU1_SB_CA<5>")
	)
	(segment
		(start 139.263882 -247.982232)
		(end 140.7287 -247.982232)
		(width 0.088646)
		(layer "F.Cu")
		(net "M_E_CPU1_SB_CA<5>")
	)
	(segment
		(start 170.457114 -248.31675)
		(end 169.624502 -248.31675)
		(width 0.20066)
		(layer "F.Cu")
		(net "M_E_CPU1_SB_CA<5>")
	)
	(segment
		(start 146.558254 -247.365266)
		(end 147.108164 -246.815356)
		(width 0.20066)
		(layer "F.Cu")
		(net "M_E_CPU1_SB_CA<5>")
	)
	(segment
		(start 167.367458 -248.765314)
		(end 167.343836 -248.741692)
		(width 0.1016)
		(layer "F.Cu")
		(net "M_E_CPU1_SB_CA<5>")
	)
	(segment
		(start 167.343836 -248.741692)
		(end 165.36289 -248.741692)
		(width 0.1016)
		(layer "F.Cu")
		(net "M_E_CPU1_SB_CA<5>")
	)
	(segment
		(start 168.8719 -248.566432)
		(end 168.56964 -248.264172)
		(width 0.20066)
		(layer "F.Cu")
		(net "M_E_CPU1_SB_CA<5>")
	)
	(segment
		(start 161.365438 -248.760234)
		(end 161.510726 -248.614946)
		(width 0.20066)
		(layer "F.Cu")
		(net "M_E_CPU1_SB_CA<5>")
	)
	(segment
		(start 165.335458 -248.74982)
		(end 164.280596 -248.74982)
		(width 0.20066)
		(layer "F.Cu")
		(net "M_E_CPU1_SB_CA<5>")
	)
	(segment
		(start 167.98798 -248.356628)
		(end 167.98798 -248.536968)
		(width 0.20066)
		(layer "F.Cu")
		(net "M_E_CPU1_SB_CA<5>")
	)
	(segment
		(start 168.56964 -248.264172)
		(end 168.080436 -248.264172)
		(width 0.20066)
		(layer "F.Cu")
		(net "M_E_CPU1_SB_CA<5>")
	)
	(segment
		(start 149.220174 -246.815356)
		(end 151.215344 -248.810526)
		(width 0.20066)
		(layer "F.Cu")
		(net "M_E_CPU1_SB_CA<5>")
	)
	(segment
		(start 159.765238 -248.741692)
		(end 159.78378 -248.760234)
		(width 0.1016)
		(layer "F.Cu")
		(net "M_E_CPU1_SB_CA<5>")
	)
	(segment
		(start 164.280596 -248.74982)
		(end 163.847526 -248.31675)
		(width 0.20066)
		(layer "F.Cu")
		(net "M_E_CPU1_SB_CA<5>")
	)
	(segment
		(start 151.215344 -248.810526)
		(end 157.37967 -248.810526)
		(width 0.20066)
		(layer "F.Cu")
		(net "M_E_CPU1_SB_CA<5>")
	)
	(segment
		(start 147.108164 -246.815356)
		(end 149.220174 -246.815356)
		(width 0.20066)
		(layer "F.Cu")
		(net "M_E_CPU1_SB_CA<5>")
	)
	(segment
		(start 157.838902 -248.741692)
		(end 159.765238 -248.741692)
		(width 0.1016)
		(layer "F.Cu")
		(net "M_E_CPU1_SB_CA<5>")
	)
	(segment
		(start 138.995912 -247.714262)
		(end 139.263882 -247.982232)
		(width 0.088646)
		(layer "F.Cu")
		(net "M_E_CPU1_SB_CA<5>")
	)
	(segment
		(start 167.759634 -248.765314)
		(end 167.367458 -248.765314)
		(width 0.20066)
		(layer "F.Cu")
		(net "M_E_CPU1_SB_CA<5>")
	)
	(segment
		(start 146.428968 -247.494552)
		(end 146.558254 -247.365266)
		(width 0.1016)
		(layer "F.Cu")
		(net "M_E_CPU1_SB_CA<5>")
	)
	(segment
		(start 167.98798 -248.536968)
		(end 167.759634 -248.765314)
		(width 0.20066)
		(layer "F.Cu")
		(net "M_E_CPU1_SB_CA<5>")
	)
	(segment
		(start 163.847526 -248.31675)
		(end 162.913314 -248.31675)
		(width 0.20066)
		(layer "F.Cu")
		(net "M_E_CPU1_SB_CA<5>")
	)
	(segment
		(start 169.624502 -248.31675)
		(end 169.37482 -248.566432)
		(width 0.20066)
		(layer "F.Cu")
		(net "M_E_CPU1_SB_CA<5>")
	)
	(segment
		(start 157.37967 -248.810526)
		(end 157.424628 -248.765568)
		(width 0.20066)
		(layer "F.Cu")
		(net "M_E_CPU1_SB_CA<5>")
	)
	(segment
		(start 157.424628 -248.765568)
		(end 157.791658 -248.765568)
		(width 0.20066)
		(layer "F.Cu")
		(net "M_E_CPU1_SB_CA<5>")
	)
	(segment
		(start 157.815026 -248.765568)
		(end 157.838902 -248.741692)
		(width 0.1016)
		(layer "F.Cu")
		(net "M_E_CPU1_SB_CA<5>")
	)
	(segment
		(start 169.37482 -248.566432)
		(end 168.8719 -248.566432)
		(width 0.20066)
		(layer "F.Cu")
		(net "M_E_CPU1_SB_CA<5>")
	)
	(segment
		(start 159.76473 -249.166634)
		(end 158.813246 -249.166634)
		(width 0.20066)
		(layer "F.Cu")
		(net "M_E_CPU1_SB_CA<4>")
	)
	(segment
		(start 161.896552 -249.612912)
		(end 161.891726 -249.612912)
		(width 0.101854)
		(layer "F.Cu")
		(net "M_E_CPU1_SB_CA<4>")
	)
	(segment
		(start 165.038024 -249.61088)
		(end 163.923726 -249.61088)
		(width 0.20066)
		(layer "F.Cu")
		(net "M_E_CPU1_SB_CA<4>")
	)
	(segment
		(start 160.78962 -249.430794)
		(end 160.78962 -249.549412)
		(width 0.20066)
		(layer "F.Cu")
		(net "M_E_CPU1_SB_CA<4>")
	)
	(segment
		(start 165.48227 -249.166634)
		(end 165.038024 -249.61088)
		(width 0.20066)
		(layer "F.Cu")
		(net "M_E_CPU1_SB_CA<4>")
	)
	(segment
		(start 163.923726 -249.61088)
		(end 163.904422 -249.591576)
		(width 0.1016)
		(layer "F.Cu")
		(net "M_E_CPU1_SB_CA<4>")
	)
	(segment
		(start 158.021274 -249.166634)
		(end 158.813246 -249.166634)
		(width 0.20066)
		(layer "F.Cu")
		(net "M_E_CPU1_SB_CA<4>")
	)
	(segment
		(start 147.114006 -247.717818)
		(end 147.370038 -247.461786)
		(width 0.20066)
		(layer "F.Cu")
		(net "M_E_CPU1_SB_CA<4>")
	)
	(segment
		(start 138.602212 -248.949464)
		(end 138.877548 -249.22988)
		(width 0.088646)
		(layer "F.Cu")
		(net "M_E_CPU1_SB_CA<4>")
	)
	(segment
		(start 166.357046 -249.166634)
		(end 165.48227 -249.166634)
		(width 0.20066)
		(layer "F.Cu")
		(net "M_E_CPU1_SB_CA<4>")
	)
	(segment
		(start 138.272012 -248.94667)
		(end 138.602212 -248.949464)
		(width 0.088646)
		(layer "F.Cu")
		(net "M_E_CPU1_SB_CA<4>")
	)
	(segment
		(start 160.78962 -249.549412)
		(end 160.63976 -249.699272)
		(width 0.20066)
		(layer "F.Cu")
		(net "M_E_CPU1_SB_CA<4>")
	)
	(segment
		(start 141.346936 -248.007124)
		(end 141.554708 -247.799352)
		(width 0.1016)
		(layer "F.Cu")
		(net "M_E_CPU1_SB_CA<4>")
	)
	(segment
		(start 160.63976 -249.699272)
		(end 160.297368 -249.699272)
		(width 0.20066)
		(layer "F.Cu")
		(net "M_E_CPU1_SB_CA<4>")
	)
	(segment
		(start 137.67181 -248.20372)
		(end 137.672064 -248.20372)
		(width 0.088646)
		(layer "F.Cu")
		(net "M_E_CPU1_SB_CA<4>")
	)
	(segment
		(start 137.268966 -248.220484)
		(end 137.297668 -248.20372)
		(width 0.088646)
		(layer "F.Cu")
		(net "M_E_CPU1_SB_CA<4>")
	)
	(segment
		(start 161.59226 -249.612912)
		(end 161.316162 -249.336814)
		(width 0.20066)
		(layer "F.Cu")
		(net "M_E_CPU1_SB_CA<4>")
	)
	(segment
		(start 138.877548 -249.22988)
		(end 140.12418 -249.22988)
		(width 0.088646)
		(layer "F.Cu")
		(net "M_E_CPU1_SB_CA<4>")
	)
	(segment
		(start 161.316162 -249.336814)
		(end 160.8836 -249.336814)
		(width 0.20066)
		(layer "F.Cu")
		(net "M_E_CPU1_SB_CA<4>")
	)
	(segment
		(start 160.297368 -249.699272)
		(end 159.76473 -249.166634)
		(width 0.20066)
		(layer "F.Cu")
		(net "M_E_CPU1_SB_CA<4>")
	)
	(segment
		(start 163.904422 -249.591576)
		(end 161.917888 -249.591576)
		(width 0.1016)
		(layer "F.Cu")
		(net "M_E_CPU1_SB_CA<4>")
	)
	(segment
		(start 148.961856 -247.461786)
		(end 151.075644 -249.575574)
		(width 0.20066)
		(layer "F.Cu")
		(net "M_E_CPU1_SB_CA<4>")
	)
	(segment
		(start 161.891726 -249.612912)
		(end 161.59226 -249.612912)
		(width 0.20066)
		(layer "F.Cu")
		(net "M_E_CPU1_SB_CA<4>")
	)
	(segment
		(start 137.672064 -248.20372)
		(end 137.672318 -248.203974)
		(width 0.088646)
		(layer "F.Cu")
		(net "M_E_CPU1_SB_CA<4>")
	)
	(segment
		(start 161.917888 -249.591576)
		(end 161.896552 -249.612912)
		(width 0.1016)
		(layer "F.Cu")
		(net "M_E_CPU1_SB_CA<4>")
	)
	(segment
		(start 160.8836 -249.336814)
		(end 160.78962 -249.430794)
		(width 0.20066)
		(layer "F.Cu")
		(net "M_E_CPU1_SB_CA<4>")
	)
	(segment
		(start 151.075644 -249.575574)
		(end 157.612334 -249.575574)
		(width 0.20066)
		(layer "F.Cu")
		(net "M_E_CPU1_SB_CA<4>")
	)
	(segment
		(start 141.554708 -247.799352)
		(end 147.032472 -247.799352)
		(width 0.1016)
		(layer "F.Cu")
		(net "M_E_CPU1_SB_CA<4>")
	)
	(segment
		(start 147.032472 -247.799352)
		(end 147.114006 -247.717818)
		(width 0.1016)
		(layer "F.Cu")
		(net "M_E_CPU1_SB_CA<4>")
	)
	(segment
		(start 137.859516 -248.528078)
		(end 138.272012 -248.94667)
		(width 0.088646)
		(layer "F.Cu")
		(net "M_E_CPU1_SB_CA<4>")
	)
	(segment
		(start 140.12418 -249.22988)
		(end 141.346936 -248.007124)
		(width 0.088646)
		(layer "F.Cu")
		(net "M_E_CPU1_SB_CA<4>")
	)
	(segment
		(start 147.370038 -247.461786)
		(end 148.961856 -247.461786)
		(width 0.20066)
		(layer "F.Cu")
		(net "M_E_CPU1_SB_CA<4>")
	)
	(segment
		(start 157.612334 -249.575574)
		(end 158.021274 -249.166634)
		(width 0.20066)
		(layer "F.Cu")
		(net "M_E_CPU1_SB_CA<4>")
	)
	(segment
		(start 136.545066 -248.528078)
		(end 137.268966 -248.220484)
		(width 0.088646)
		(layer "F.Cu")
		(net "M_E_CPU1_SB_CA<4>")
	)
	(arc
		(start 137.672318 -248.203974)
		(mid 137.809363 -248.340934)
		(end 137.859516 -248.528078)
		(width 0.088646)
		(layer "F.Cu")
		(net "M_E_CPU1_SB_CA<4>")
	)
	(arc
		(start 137.297668 -248.20372)
		(mid 137.484756 -248.153509)
		(end 137.67181 -248.20372)
		(width 0.088646)
		(layer "F.Cu")
		(net "M_E_CPU1_SB_CA<4>")
	)
	(segment
		(start 164.68979 -250.451112)
		(end 164.47135 -250.232672)
		(width 0.20066)
		(layer "F.Cu")
		(net "M_E_CPU1_SB_CA<3>")
	)
	(segment
		(start 140.09878 -249.68708)
		(end 141.56055 -248.22531)
		(width 0.088646)
		(layer "F.Cu")
		(net "M_E_CPU1_SB_CA<3>")
	)
	(segment
		(start 168.26738 -250.454414)
		(end 167.367458 -250.454414)
		(width 0.20066)
		(layer "F.Cu")
		(net "M_E_CPU1_SB_CA<3>")
	)
	(segment
		(start 169.28338 -250.016772)
		(end 168.99128 -249.724672)
		(width 0.20066)
		(layer "F.Cu")
		(net "M_E_CPU1_SB_CA<3>")
	)
	(segment
		(start 157.815534 -250.441714)
		(end 159.773112 -250.441714)
		(width 0.1016)
		(layer "F.Cu")
		(net "M_E_CPU1_SB_CA<3>")
	)
	(segment
		(start 168.39438 -249.978672)
		(end 168.39438 -250.327414)
		(width 0.20066)
		(layer "F.Cu")
		(net "M_E_CPU1_SB_CA<3>")
	)
	(segment
		(start 157.793436 -250.463812)
		(end 157.815534 -250.441714)
		(width 0.101854)
		(layer "F.Cu")
		(net "M_E_CPU1_SB_CA<3>")
	)
	(segment
		(start 148.620734 -248.11609)
		(end 148.621496 -248.116852)
		(width 0.20066)
		(layer "F.Cu")
		(net "M_E_CPU1_SB_CA<3>")
	)
	(segment
		(start 167.367458 -250.454414)
		(end 167.354758 -250.441714)
		(width 0.1016)
		(layer "F.Cu")
		(net "M_E_CPU1_SB_CA<3>")
	)
	(segment
		(start 157.791658 -250.463812)
		(end 157.793436 -250.463812)
		(width 0.101854)
		(layer "F.Cu")
		(net "M_E_CPU1_SB_CA<3>")
	)
	(segment
		(start 138.433302 -249.342148)
		(end 138.778234 -249.68708)
		(width 0.088646)
		(layer "F.Cu")
		(net "M_E_CPU1_SB_CA<3>")
	)
	(segment
		(start 164.47135 -250.232672)
		(end 163.693094 -250.232672)
		(width 0.20066)
		(layer "F.Cu")
		(net "M_E_CPU1_SB_CA<3>")
	)
	(segment
		(start 148.608796 -248.104152)
		(end 148.620734 -248.11609)
		(width 0.101854)
		(layer "F.Cu")
		(net "M_E_CPU1_SB_CA<3>")
	)
	(segment
		(start 165.352984 -250.451112)
		(end 165.335458 -250.451112)
		(width 0.101854)
		(layer "F.Cu")
		(net "M_E_CPU1_SB_CA<3>")
	)
	(segment
		(start 141.681708 -248.104152)
		(end 148.608796 -248.104152)
		(width 0.1016)
		(layer "F.Cu")
		(net "M_E_CPU1_SB_CA<3>")
	)
	(segment
		(start 151.059388 -250.463812)
		(end 157.791658 -250.463812)
		(width 0.20066)
		(layer "F.Cu")
		(net "M_E_CPU1_SB_CA<3>")
	)
	(segment
		(start 161.31667 -250.452382)
		(end 161.75228 -250.016772)
		(width 0.20066)
		(layer "F.Cu")
		(net "M_E_CPU1_SB_CA<3>")
	)
	(segment
		(start 148.621496 -248.116852)
		(end 148.712428 -248.116852)
		(width 0.20066)
		(layer "F.Cu")
		(net "M_E_CPU1_SB_CA<3>")
	)
	(segment
		(start 168.99128 -249.724672)
		(end 168.64838 -249.724672)
		(width 0.20066)
		(layer "F.Cu")
		(net "M_E_CPU1_SB_CA<3>")
	)
	(segment
		(start 141.56055 -248.22531)
		(end 141.681708 -248.104152)
		(width 0.1016)
		(layer "F.Cu")
		(net "M_E_CPU1_SB_CA<3>")
	)
	(segment
		(start 167.354758 -250.441714)
		(end 165.362382 -250.441714)
		(width 0.1016)
		(layer "F.Cu")
		(net "M_E_CPU1_SB_CA<3>")
	)
	(segment
		(start 163.693094 -250.232672)
		(end 163.477194 -250.016772)
		(width 0.20066)
		(layer "F.Cu")
		(net "M_E_CPU1_SB_CA<3>")
	)
	(segment
		(start 168.64838 -249.724672)
		(end 168.39438 -249.978672)
		(width 0.20066)
		(layer "F.Cu")
		(net "M_E_CPU1_SB_CA<3>")
	)
	(segment
		(start 163.477194 -250.016772)
		(end 162.913314 -250.016772)
		(width 0.20066)
		(layer "F.Cu")
		(net "M_E_CPU1_SB_CA<3>")
	)
	(segment
		(start 159.823658 -250.452382)
		(end 161.31667 -250.452382)
		(width 0.20066)
		(layer "F.Cu")
		(net "M_E_CPU1_SB_CA<3>")
	)
	(segment
		(start 168.39438 -250.327414)
		(end 168.26738 -250.454414)
		(width 0.20066)
		(layer "F.Cu")
		(net "M_E_CPU1_SB_CA<3>")
	)
	(segment
		(start 148.712428 -248.116852)
		(end 151.059388 -250.463812)
		(width 0.20066)
		(layer "F.Cu")
		(net "M_E_CPU1_SB_CA<3>")
	)
	(segment
		(start 159.773112 -250.441714)
		(end 159.78378 -250.452382)
		(width 0.1016)
		(layer "F.Cu")
		(net "M_E_CPU1_SB_CA<3>")
	)
	(segment
		(start 137.954766 -249.342148)
		(end 138.433302 -249.342148)
		(width 0.088646)
		(layer "F.Cu")
		(net "M_E_CPU1_SB_CA<3>")
	)
	(segment
		(start 159.78378 -250.452382)
		(end 159.823658 -250.452382)
		(width 0.101854)
		(layer "F.Cu")
		(net "M_E_CPU1_SB_CA<3>")
	)
	(segment
		(start 170.457114 -250.016772)
		(end 169.28338 -250.016772)
		(width 0.20066)
		(layer "F.Cu")
		(net "M_E_CPU1_SB_CA<3>")
	)
	(segment
		(start 165.335458 -250.451112)
		(end 164.68979 -250.451112)
		(width 0.20066)
		(layer "F.Cu")
		(net "M_E_CPU1_SB_CA<3>")
	)
	(segment
		(start 165.362382 -250.441714)
		(end 165.352984 -250.451112)
		(width 0.1016)
		(layer "F.Cu")
		(net "M_E_CPU1_SB_CA<3>")
	)
	(segment
		(start 138.778234 -249.68708)
		(end 140.09878 -249.68708)
		(width 0.088646)
		(layer "F.Cu")
		(net "M_E_CPU1_SB_CA<3>")
	)
	(segment
		(start 161.75228 -250.016772)
		(end 162.913314 -250.016772)
		(width 0.20066)
		(layer "F.Cu")
		(net "M_E_CPU1_SB_CA<3>")
	)
	(segment
		(start 148.620734 -248.929652)
		(end 151.052784 -251.361702)
		(width 0.20066)
		(layer "F.Cu")
		(net "M_E_CPU1_SB_CA<2>")
	)
	(segment
		(start 161.064956 -251.604272)
		(end 160.645094 -251.604272)
		(width 0.20066)
		(layer "F.Cu")
		(net "M_E_CPU1_SB_CA<2>")
	)
	(segment
		(start 152.156414 -251.78512)
		(end 152.579832 -251.361702)
		(width 0.20066)
		(layer "F.Cu")
		(net "M_E_CPU1_SB_CA<2>")
	)
	(segment
		(start 166.357046 -250.866656)
		(end 164.995606 -250.866656)
		(width 0.20066)
		(layer "F.Cu")
		(net "M_E_CPU1_SB_CA<2>")
	)
	(segment
		(start 141.808708 -248.408952)
		(end 148.100034 -248.408952)
		(width 0.1016)
		(layer "F.Cu")
		(net "M_E_CPU1_SB_CA<2>")
	)
	(segment
		(start 163.923726 -251.305314)
		(end 163.91001 -251.291598)
		(width 0.1016)
		(layer "F.Cu")
		(net "M_E_CPU1_SB_CA<2>")
	)
	(segment
		(start 153.481532 -251.361702)
		(end 153.868882 -251.749052)
		(width 0.20066)
		(layer "F.Cu")
		(net "M_E_CPU1_SB_CA<2>")
	)
	(segment
		(start 154.3431 -251.749052)
		(end 154.73045 -251.361702)
		(width 0.20066)
		(layer "F.Cu")
		(net "M_E_CPU1_SB_CA<2>")
	)
	(segment
		(start 160.125664 -250.866656)
		(end 158.813246 -250.866656)
		(width 0.20066)
		(layer "F.Cu")
		(net "M_E_CPU1_SB_CA<2>")
	)
	(segment
		(start 161.891726 -251.304806)
		(end 161.364422 -251.304806)
		(width 0.20066)
		(layer "F.Cu")
		(net "M_E_CPU1_SB_CA<2>")
	)
	(segment
		(start 152.579832 -251.361702)
		(end 153.481532 -251.361702)
		(width 0.20066)
		(layer "F.Cu")
		(net "M_E_CPU1_SB_CA<2>")
	)
	(segment
		(start 138.32586 -249.69216)
		(end 138.67638 -250.04268)
		(width 0.088646)
		(layer "F.Cu")
		(net "M_E_CPU1_SB_CA<2>")
	)
	(segment
		(start 148.100034 -248.408952)
		(end 148.620734 -248.929652)
		(width 0.1016)
		(layer "F.Cu")
		(net "M_E_CPU1_SB_CA<2>")
	)
	(segment
		(start 138.67638 -250.04268)
		(end 140.17498 -250.04268)
		(width 0.088646)
		(layer "F.Cu")
		(net "M_E_CPU1_SB_CA<2>")
	)
	(segment
		(start 160.645094 -251.604272)
		(end 160.48228 -251.441458)
		(width 0.20066)
		(layer "F.Cu")
		(net "M_E_CPU1_SB_CA<2>")
	)
	(segment
		(start 141.664182 -248.553478)
		(end 141.808708 -248.408952)
		(width 0.1016)
		(layer "F.Cu")
		(net "M_E_CPU1_SB_CA<2>")
	)
	(segment
		(start 160.48228 -251.223272)
		(end 160.125664 -250.866656)
		(width 0.20066)
		(layer "F.Cu")
		(net "M_E_CPU1_SB_CA<2>")
	)
	(segment
		(start 137.364724 -249.69216)
		(end 138.32586 -249.69216)
		(width 0.088646)
		(layer "F.Cu")
		(net "M_E_CPU1_SB_CA<2>")
	)
	(segment
		(start 164.995606 -250.866656)
		(end 164.556948 -251.305314)
		(width 0.20066)
		(layer "F.Cu")
		(net "M_E_CPU1_SB_CA<2>")
	)
	(segment
		(start 154.73045 -251.361702)
		(end 157.200092 -251.361702)
		(width 0.20066)
		(layer "F.Cu")
		(net "M_E_CPU1_SB_CA<2>")
	)
	(segment
		(start 151.428196 -251.361702)
		(end 151.851614 -251.78512)
		(width 0.20066)
		(layer "F.Cu")
		(net "M_E_CPU1_SB_CA<2>")
	)
	(segment
		(start 160.48228 -251.441458)
		(end 160.48228 -251.223272)
		(width 0.20066)
		(layer "F.Cu")
		(net "M_E_CPU1_SB_CA<2>")
	)
	(segment
		(start 161.364422 -251.304806)
		(end 161.064956 -251.604272)
		(width 0.20066)
		(layer "F.Cu")
		(net "M_E_CPU1_SB_CA<2>")
	)
	(segment
		(start 157.200092 -251.361702)
		(end 157.364938 -251.196856)
		(width 0.20066)
		(layer "F.Cu")
		(net "M_E_CPU1_SB_CA<2>")
	)
	(segment
		(start 158.27883 -250.866656)
		(end 158.813246 -250.866656)
		(width 0.20066)
		(layer "F.Cu")
		(net "M_E_CPU1_SB_CA<2>")
	)
	(segment
		(start 137.014712 -249.342148)
		(end 137.364724 -249.69216)
		(width 0.088646)
		(layer "F.Cu")
		(net "M_E_CPU1_SB_CA<2>")
	)
	(segment
		(start 164.556948 -251.305314)
		(end 163.923726 -251.305314)
		(width 0.20066)
		(layer "F.Cu")
		(net "M_E_CPU1_SB_CA<2>")
	)
	(segment
		(start 151.052784 -251.361702)
		(end 151.428196 -251.361702)
		(width 0.20066)
		(layer "F.Cu")
		(net "M_E_CPU1_SB_CA<2>")
	)
	(segment
		(start 161.90976 -251.291598)
		(end 161.896552 -251.304806)
		(width 0.1016)
		(layer "F.Cu")
		(net "M_E_CPU1_SB_CA<2>")
	)
	(segment
		(start 140.17498 -250.04268)
		(end 141.664182 -248.553478)
		(width 0.088646)
		(layer "F.Cu")
		(net "M_E_CPU1_SB_CA<2>")
	)
	(segment
		(start 157.94863 -251.196856)
		(end 158.27883 -250.866656)
		(width 0.20066)
		(layer "F.Cu")
		(net "M_E_CPU1_SB_CA<2>")
	)
	(segment
		(start 157.364938 -251.196856)
		(end 157.94863 -251.196856)
		(width 0.20066)
		(layer "F.Cu")
		(net "M_E_CPU1_SB_CA<2>")
	)
	(segment
		(start 161.896552 -251.304806)
		(end 161.891726 -251.304806)
		(width 0.101854)
		(layer "F.Cu")
		(net "M_E_CPU1_SB_CA<2>")
	)
	(segment
		(start 153.868882 -251.749052)
		(end 154.3431 -251.749052)
		(width 0.20066)
		(layer "F.Cu")
		(net "M_E_CPU1_SB_CA<2>")
	)
	(segment
		(start 163.91001 -251.291598)
		(end 161.90976 -251.291598)
		(width 0.1016)
		(layer "F.Cu")
		(net "M_E_CPU1_SB_CA<2>")
	)
	(segment
		(start 151.851614 -251.78512)
		(end 152.156414 -251.78512)
		(width 0.20066)
		(layer "F.Cu")
		(net "M_E_CPU1_SB_CA<2>")
	)
	(segment
		(start 168.63568 -252.650752)
		(end 168.18356 -252.650752)
		(width 0.20066)
		(layer "F.Cu")
		(net "M_E_CPU1_SB_CA<1>")
	)
	(segment
		(start 157.883606 -252.141736)
		(end 159.503618 -252.141736)
		(width 0.1016)
		(layer "F.Cu")
		(net "M_E_CPU1_SB_CA<1>")
	)
	(segment
		(start 157.791658 -252.233684)
		(end 157.832298 -252.193044)
		(width 0.101854)
		(layer "F.Cu")
		(net "M_E_CPU1_SB_CA<1>")
	)
	(segment
		(start 135.86079 -249.643138)
		(end 135.879078 -249.661426)
		(width 0.088646)
		(layer "F.Cu")
		(net "M_E_CPU1_SB_CA<1>")
	)
	(segment
		(start 135.905494 -249.677174)
		(end 135.906764 -249.677936)
		(width 0.088646)
		(layer "F.Cu")
		(net "M_E_CPU1_SB_CA<1>")
	)
	(segment
		(start 135.906764 -249.677936)
		(end 135.908288 -249.678698)
		(width 0.088646)
		(layer "F.Cu")
		(net "M_E_CPU1_SB_CA<1>")
	)
	(segment
		(start 164.493702 -251.716794)
		(end 162.913314 -251.716794)
		(width 0.20066)
		(layer "F.Cu")
		(net "M_E_CPU1_SB_CA<1>")
	)
	(segment
		(start 141.935708 -248.713752)
		(end 147.50034 -248.713752)
		(width 0.1016)
		(layer "F.Cu")
		(net "M_E_CPU1_SB_CA<1>")
	)
	(segment
		(start 159.823658 -252.15977)
		(end 161.195258 -252.15977)
		(width 0.20066)
		(layer "F.Cu")
		(net "M_E_CPU1_SB_CA<1>")
	)
	(segment
		(start 151.2189 -252.432312)
		(end 157.59303 -252.432312)
		(width 0.20066)
		(layer "F.Cu")
		(net "M_E_CPU1_SB_CA<1>")
	)
	(segment
		(start 147.706334 -248.919746)
		(end 151.2189 -252.432312)
		(width 0.20066)
		(layer "F.Cu")
		(net "M_E_CPU1_SB_CA<1>")
	)
	(segment
		(start 138.406124 -250.53036)
		(end 138.589004 -250.34748)
		(width 0.088646)
		(layer "F.Cu")
		(net "M_E_CPU1_SB_CA<1>")
	)
	(segment
		(start 161.638234 -251.716794)
		(end 162.913314 -251.716794)
		(width 0.20066)
		(layer "F.Cu")
		(net "M_E_CPU1_SB_CA<1>")
	)
	(segment
		(start 167.367458 -252.154944)
		(end 167.35425 -252.141736)
		(width 0.1016)
		(layer "F.Cu")
		(net "M_E_CPU1_SB_CA<1>")
	)
	(segment
		(start 169.569638 -251.716794)
		(end 168.63568 -252.650752)
		(width 0.20066)
		(layer "F.Cu")
		(net "M_E_CPU1_SB_CA<1>")
	)
	(segment
		(start 165.368224 -252.141736)
		(end 165.348666 -252.161294)
		(width 0.1016)
		(layer "F.Cu")
		(net "M_E_CPU1_SB_CA<1>")
	)
	(segment
		(start 157.59303 -252.432312)
		(end 157.791658 -252.233684)
		(width 0.20066)
		(layer "F.Cu")
		(net "M_E_CPU1_SB_CA<1>")
	)
	(segment
		(start 161.195258 -252.15977)
		(end 161.638234 -251.716794)
		(width 0.20066)
		(layer "F.Cu")
		(net "M_E_CPU1_SB_CA<1>")
	)
	(segment
		(start 135.879078 -249.66168)
		(end 135.905494 -249.677174)
		(width 0.088646)
		(layer "F.Cu")
		(net "M_E_CPU1_SB_CA<1>")
	)
	(segment
		(start 138.76655 -250.34748)
		(end 140.30198 -250.34748)
		(width 0.1016)
		(layer "F.Cu")
		(net "M_E_CPU1_SB_CA<1>")
	)
	(segment
		(start 136.554718 -250.53036)
		(end 138.406124 -250.53036)
		(width 0.088646)
		(layer "F.Cu")
		(net "M_E_CPU1_SB_CA<1>")
	)
	(segment
		(start 136.170416 -249.998992)
		(end 136.170416 -250.146058)
		(width 0.088646)
		(layer "F.Cu")
		(net "M_E_CPU1_SB_CA<1>")
	)
	(segment
		(start 168.18356 -252.650752)
		(end 167.687752 -252.154944)
		(width 0.20066)
		(layer "F.Cu")
		(net "M_E_CPU1_SB_CA<1>")
	)
	(segment
		(start 167.35425 -252.141736)
		(end 165.368224 -252.141736)
		(width 0.1016)
		(layer "F.Cu")
		(net "M_E_CPU1_SB_CA<1>")
	)
	(segment
		(start 140.30198 -250.34748)
		(end 141.935708 -248.713752)
		(width 0.1016)
		(layer "F.Cu")
		(net "M_E_CPU1_SB_CA<1>")
	)
	(segment
		(start 147.50034 -248.713752)
		(end 147.706334 -248.919746)
		(width 0.1016)
		(layer "F.Cu")
		(net "M_E_CPU1_SB_CA<1>")
	)
	(segment
		(start 157.832298 -252.193044)
		(end 157.883606 -252.141736)
		(width 0.1016)
		(layer "F.Cu")
		(net "M_E_CPU1_SB_CA<1>")
	)
	(segment
		(start 167.687752 -252.154944)
		(end 167.367458 -252.154944)
		(width 0.20066)
		(layer "F.Cu")
		(net "M_E_CPU1_SB_CA<1>")
	)
	(segment
		(start 170.457114 -251.716794)
		(end 169.569638 -251.716794)
		(width 0.20066)
		(layer "F.Cu")
		(net "M_E_CPU1_SB_CA<1>")
	)
	(segment
		(start 165.335458 -252.161294)
		(end 164.938202 -252.161294)
		(width 0.20066)
		(layer "F.Cu")
		(net "M_E_CPU1_SB_CA<1>")
	)
	(segment
		(start 164.938202 -252.161294)
		(end 164.493702 -251.716794)
		(width 0.20066)
		(layer "F.Cu")
		(net "M_E_CPU1_SB_CA<1>")
	)
	(segment
		(start 135.879078 -249.661426)
		(end 135.879078 -249.66168)
		(width 0.088646)
		(layer "F.Cu")
		(net "M_E_CPU1_SB_CA<1>")
	)
	(segment
		(start 159.805624 -252.141736)
		(end 159.823658 -252.15977)
		(width 0.101854)
		(layer "F.Cu")
		(net "M_E_CPU1_SB_CA<1>")
	)
	(segment
		(start 138.589004 -250.34748)
		(end 138.76655 -250.34748)
		(width 0.088646)
		(layer "F.Cu")
		(net "M_E_CPU1_SB_CA<1>")
	)
	(segment
		(start 165.348666 -252.161294)
		(end 165.335458 -252.161294)
		(width 0.101854)
		(layer "F.Cu")
		(net "M_E_CPU1_SB_CA<1>")
	)
	(segment
		(start 159.503618 -252.141736)
		(end 159.805624 -252.141736)
		(width 0.101854)
		(layer "F.Cu")
		(net "M_E_CPU1_SB_CA<1>")
	)
	(arc
		(start 136.13384 -249.877326)
		(mid 136.161178 -249.935442)
		(end 136.170416 -249.998992)
		(width 0.088646)
		(layer "F.Cu")
		(net "M_E_CPU1_SB_CA<1>")
	)
	(arc
		(start 136.170416 -250.146058)
		(mid 136.288763 -250.412013)
		(end 136.554718 -250.53036)
		(width 0.088646)
		(layer "F.Cu")
		(net "M_E_CPU1_SB_CA<1>")
	)
	(arc
		(start 135.135112 -249.342148)
		(mid 135.506266 -249.472594)
		(end 135.86079 -249.643138)
		(width 0.088646)
		(layer "F.Cu")
		(net "M_E_CPU1_SB_CA<1>")
	)
	(arc
		(start 135.908288 -249.678698)
		(mid 136.03408 -249.763239)
		(end 136.13384 -249.877326)
		(width 0.088646)
		(layer "F.Cu")
		(net "M_E_CPU1_SB_CA<1>")
	)
	(segment
		(start 137.09015 -250.841764)
		(end 138.577066 -250.841764)
		(width 0.1016)
		(layer "F.Cu")
		(net "M_E_CPU1_SB_CA<0>")
	)
	(segment
		(start 147.111974 -249.234452)
		(end 150.999952 -253.12243)
		(width 0.20066)
		(layer "F.Cu")
		(net "M_E_CPU1_SB_CA<0>")
	)
	(segment
		(start 135.979662 -250.143772)
		(end 135.98017 -250.152154)
		(width 0.088646)
		(layer "F.Cu")
		(net "M_E_CPU1_SB_CA<0>")
	)
	(segment
		(start 135.980424 -250.155964)
		(end 135.98017 -250.155964)
		(width 0.088646)
		(layer "F.Cu")
		(net "M_E_CPU1_SB_CA<0>")
	)
	(segment
		(start 161.764726 -252.684026)
		(end 161.358326 -253.090426)
		(width 0.20066)
		(layer "F.Cu")
		(net "M_E_CPU1_SB_CA<0>")
	)
	(segment
		(start 162.084004 -252.141736)
		(end 161.896552 -252.329188)
		(width 0.1016)
		(layer "F.Cu")
		(net "M_E_CPU1_SB_CA<0>")
	)
	(segment
		(start 164.66566 -252.566678)
		(end 164.240718 -252.141736)
		(width 0.20066)
		(layer "F.Cu")
		(net "M_E_CPU1_SB_CA<0>")
	)
	(segment
		(start 135.823198 -249.849132)
		(end 135.86079 -249.882152)
		(width 0.088646)
		(layer "F.Cu")
		(net "M_E_CPU1_SB_CA<0>")
	)
	(segment
		(start 136.550146 -250.720606)
		(end 136.721342 -250.720606)
		(width 0.088646)
		(layer "F.Cu")
		(net "M_E_CPU1_SB_CA<0>")
	)
	(segment
		(start 135.808212 -249.841004)
		(end 135.81507 -249.844814)
		(width 0.088646)
		(layer "F.Cu")
		(net "M_E_CPU1_SB_CA<0>")
	)
	(segment
		(start 138.698224 -250.720606)
		(end 140.386054 -250.720606)
		(width 0.1016)
		(layer "F.Cu")
		(net "M_E_CPU1_SB_CA<0>")
	)
	(segment
		(start 137.01395 -250.841764)
		(end 137.09015 -250.841764)
		(width 0.088646)
		(layer "F.Cu")
		(net "M_E_CPU1_SB_CA<0>")
	)
	(segment
		(start 161.358326 -253.090426)
		(end 159.892238 -253.090426)
		(width 0.20066)
		(layer "F.Cu")
		(net "M_E_CPU1_SB_CA<0>")
	)
	(segment
		(start 135.86079 -249.882152)
		(end 135.979662 -250.001024)
		(width 0.088646)
		(layer "F.Cu")
		(net "M_E_CPU1_SB_CA<0>")
	)
	(segment
		(start 140.386054 -250.720606)
		(end 142.088108 -249.018552)
		(width 0.1016)
		(layer "F.Cu")
		(net "M_E_CPU1_SB_CA<0>")
	)
	(segment
		(start 163.81857 -252.141736)
		(end 162.084004 -252.141736)
		(width 0.1016)
		(layer "F.Cu")
		(net "M_E_CPU1_SB_CA<0>")
	)
	(segment
		(start 135.066786 -249.768106)
		(end 135.684006 -249.768106)
		(width 0.088646)
		(layer "F.Cu")
		(net "M_E_CPU1_SB_CA<0>")
	)
	(segment
		(start 135.979662 -250.001024)
		(end 135.979662 -250.143772)
		(width 0.088646)
		(layer "F.Cu")
		(net "M_E_CPU1_SB_CA<0>")
	)
	(segment
		(start 161.891726 -252.334014)
		(end 161.764726 -252.461014)
		(width 0.20066)
		(layer "F.Cu")
		(net "M_E_CPU1_SB_CA<0>")
	)
	(segment
		(start 142.088108 -249.018552)
		(end 146.896074 -249.018552)
		(width 0.1016)
		(layer "F.Cu")
		(net "M_E_CPU1_SB_CA<0>")
	)
	(segment
		(start 138.577066 -250.841764)
		(end 138.698224 -250.720606)
		(width 0.1016)
		(layer "F.Cu")
		(net "M_E_CPU1_SB_CA<0>")
	)
	(segment
		(start 163.923726 -252.141736)
		(end 163.81857 -252.141736)
		(width 0.101854)
		(layer "F.Cu")
		(net "M_E_CPU1_SB_CA<0>")
	)
	(segment
		(start 166.357046 -252.566678)
		(end 164.66566 -252.566678)
		(width 0.20066)
		(layer "F.Cu")
		(net "M_E_CPU1_SB_CA<0>")
	)
	(segment
		(start 164.240718 -252.141736)
		(end 163.923726 -252.141736)
		(width 0.20066)
		(layer "F.Cu")
		(net "M_E_CPU1_SB_CA<0>")
	)
	(segment
		(start 158.317946 -252.566678)
		(end 158.813246 -252.566678)
		(width 0.20066)
		(layer "F.Cu")
		(net "M_E_CPU1_SB_CA<0>")
	)
	(segment
		(start 134.665466 -248.528078)
		(end 134.665466 -249.428762)
		(width 0.088646)
		(layer "F.Cu")
		(net "M_E_CPU1_SB_CA<0>")
	)
	(segment
		(start 159.36849 -252.566678)
		(end 158.813246 -252.566678)
		(width 0.20066)
		(layer "F.Cu")
		(net "M_E_CPU1_SB_CA<0>")
	)
	(segment
		(start 136.721342 -250.720606)
		(end 137.01395 -250.841764)
		(width 0.088646)
		(layer "F.Cu")
		(net "M_E_CPU1_SB_CA<0>")
	)
	(segment
		(start 146.896074 -249.018552)
		(end 147.111974 -249.234452)
		(width 0.1016)
		(layer "F.Cu")
		(net "M_E_CPU1_SB_CA<0>")
	)
	(segment
		(start 157.762194 -253.12243)
		(end 158.317946 -252.566678)
		(width 0.20066)
		(layer "F.Cu")
		(net "M_E_CPU1_SB_CA<0>")
	)
	(segment
		(start 135.81507 -249.844814)
		(end 135.823198 -249.849132)
		(width 0.088646)
		(layer "F.Cu")
		(net "M_E_CPU1_SB_CA<0>")
	)
	(segment
		(start 159.892238 -253.090426)
		(end 159.36849 -252.566678)
		(width 0.20066)
		(layer "F.Cu")
		(net "M_E_CPU1_SB_CA<0>")
	)
	(segment
		(start 161.896552 -252.329188)
		(end 161.891726 -252.334014)
		(width 0.101854)
		(layer "F.Cu")
		(net "M_E_CPU1_SB_CA<0>")
	)
	(segment
		(start 150.999952 -253.12243)
		(end 157.762194 -253.12243)
		(width 0.20066)
		(layer "F.Cu")
		(net "M_E_CPU1_SB_CA<0>")
	)
	(segment
		(start 134.736586 -249.600466)
		(end 134.789418 -249.653044)
		(width 0.088646)
		(layer "F.Cu")
		(net "M_E_CPU1_SB_CA<0>")
	)
	(segment
		(start 135.684006 -249.768106)
		(end 135.808212 -249.841004)
		(width 0.088646)
		(layer "F.Cu")
		(net "M_E_CPU1_SB_CA<0>")
	)
	(segment
		(start 161.764726 -252.461014)
		(end 161.764726 -252.684026)
		(width 0.20066)
		(layer "F.Cu")
		(net "M_E_CPU1_SB_CA<0>")
	)
	(arc
		(start 134.665466 -249.428762)
		(mid 134.68395 -249.521687)
		(end 134.736586 -249.600466)
		(width 0.088646)
		(layer "F.Cu")
		(net "M_E_CPU1_SB_CA<0>")
	)
	(arc
		(start 135.98017 -250.155964)
		(mid 136.156029 -250.548448)
		(end 136.550146 -250.720606)
		(width 0.088646)
		(layer "F.Cu")
		(net "M_E_CPU1_SB_CA<0>")
	)
	(arc
		(start 135.98017 -250.152154)
		(mid 135.980294 -250.154059)
		(end 135.980424 -250.155964)
		(width 0.088646)
		(layer "F.Cu")
		(net "M_E_CPU1_SB_CA<0>")
	)
	(arc
		(start 134.789418 -249.653044)
		(mid 134.91666 -249.738158)
		(end 135.066786 -249.768106)
		(width 0.088646)
		(layer "F.Cu")
		(net "M_E_CPU1_SB_CA<0>")
	)
	(segment
		(start 123.387612 -248.527824)
		(end 123.387612 -247.992138)
		(width 0.20066)
		(layer "F.Cu")
		(net "M_E_CPU1_SA_RSP<1>")
	)
	(segment
		(start 123.387866 -248.528078)
		(end 123.387612 -248.527824)
		(width 0.20066)
		(layer "F.Cu")
		(net "M_E_CPU1_SA_RSP<1>")
	)
	(segment
		(start 157.682946 -244.066568)
		(end 158.813246 -244.066568)
		(width 0.20066)
		(layer "F.Cu")
		(net "M_E_CPU1_SA_RSP<1>")
	)
	(segment
		(start 156.564584 -244.066568)
		(end 156.156406 -244.474746)
		(width 0.18288)
		(layer "In6.Cu")
		(net "M_E_CPU1_SA_RSP<1>")
	)
	(segment
		(start 138.941556 -247.744742)
		(end 136.530334 -247.744742)
		(width 0.18288)
		(layer "In6.Cu")
		(net "M_E_CPU1_SA_RSP<1>")
	)
	(segment
		(start 156.156406 -245.197122)
		(end 155.973526 -245.380002)
		(width 0.18288)
		(layer "In6.Cu")
		(net "M_E_CPU1_SA_RSP<1>")
	)
	(segment
		(start 127.818896 -248.490486)
		(end 127.804164 -248.48185)
		(width 0.088646)
		(layer "In6.Cu")
		(net "M_E_CPU1_SA_RSP<1>")
	)
	(segment
		(start 139.096242 -247.590056)
		(end 138.941556 -247.744742)
		(width 0.18288)
		(layer "In6.Cu")
		(net "M_E_CPU1_SA_RSP<1>")
	)
	(segment
		(start 151.900128 -245.380002)
		(end 151.295354 -245.984776)
		(width 0.18288)
		(layer "In6.Cu")
		(net "M_E_CPU1_SA_RSP<1>")
	)
	(segment
		(start 124.059696 -248.490486)
		(end 124.044964 -248.48185)
		(width 0.088646)
		(layer "In6.Cu")
		(net "M_E_CPU1_SA_RSP<1>")
	)
	(segment
		(start 151.295354 -245.984776)
		(end 142.198344 -245.984776)
		(width 0.18288)
		(layer "In6.Cu")
		(net "M_E_CPU1_SA_RSP<1>")
	)
	(segment
		(start 157.682946 -244.066568)
		(end 156.564584 -244.066568)
		(width 0.18288)
		(layer "In6.Cu")
		(net "M_E_CPU1_SA_RSP<1>")
	)
	(segment
		(start 124.999496 -248.490486)
		(end 124.984764 -248.48185)
		(width 0.088646)
		(layer "In6.Cu")
		(net "M_E_CPU1_SA_RSP<1>")
	)
	(segment
		(start 136.530334 -247.744742)
		(end 136.347708 -247.744742)
		(width 0.088646)
		(layer "In6.Cu")
		(net "M_E_CPU1_SA_RSP<1>")
	)
	(segment
		(start 124.016008 -248.46534)
		(end 123.387612 -247.992138)
		(width 0.088646)
		(layer "In6.Cu")
		(net "M_E_CPU1_SA_RSP<1>")
	)
	(segment
		(start 140.593064 -247.590056)
		(end 139.096242 -247.590056)
		(width 0.18288)
		(layer "In6.Cu")
		(net "M_E_CPU1_SA_RSP<1>")
	)
	(segment
		(start 131.578096 -248.490486)
		(end 131.563364 -248.48185)
		(width 0.088646)
		(layer "In6.Cu")
		(net "M_E_CPU1_SA_RSP<1>")
	)
	(segment
		(start 136.170416 -247.922034)
		(end 136.170416 -248.01068)
		(width 0.088646)
		(layer "In6.Cu")
		(net "M_E_CPU1_SA_RSP<1>")
	)
	(segment
		(start 129.693924 -248.487946)
		(end 129.68351 -248.48185)
		(width 0.088646)
		(layer "In6.Cu")
		(net "M_E_CPU1_SA_RSP<1>")
	)
	(segment
		(start 128.754378 -248.487946)
		(end 128.743964 -248.48185)
		(width 0.088646)
		(layer "In6.Cu")
		(net "M_E_CPU1_SA_RSP<1>")
	)
	(segment
		(start 124.044964 -248.48185)
		(end 124.016008 -248.46534)
		(width 0.088646)
		(layer "In6.Cu")
		(net "M_E_CPU1_SA_RSP<1>")
	)
	(segment
		(start 155.973526 -245.380002)
		(end 151.900128 -245.380002)
		(width 0.18288)
		(layer "In6.Cu")
		(net "M_E_CPU1_SA_RSP<1>")
	)
	(segment
		(start 156.156406 -244.474746)
		(end 156.156406 -245.197122)
		(width 0.18288)
		(layer "In6.Cu")
		(net "M_E_CPU1_SA_RSP<1>")
	)
	(segment
		(start 142.198344 -245.984776)
		(end 140.593064 -247.590056)
		(width 0.18288)
		(layer "In6.Cu")
		(net "M_E_CPU1_SA_RSP<1>")
	)
	(segment
		(start 126.879096 -248.490486)
		(end 126.864364 -248.48185)
		(width 0.088646)
		(layer "In6.Cu")
		(net "M_E_CPU1_SA_RSP<1>")
	)
	(segment
		(start 136.347708 -247.744742)
		(end 136.170416 -247.922034)
		(width 0.088646)
		(layer "In6.Cu")
		(net "M_E_CPU1_SA_RSP<1>")
	)
	(arc
		(start 124.984764 -248.48185)
		(mid 124.797566 -248.431707)
		(end 124.610368 -248.48185)
		(width 0.088646)
		(layer "In6.Cu")
		(net "M_E_CPU1_SA_RSP<1>")
	)
	(arc
		(start 126.864364 -248.48185)
		(mid 126.677166 -248.431707)
		(end 126.489968 -248.48185)
		(width 0.088646)
		(layer "In6.Cu")
		(net "M_E_CPU1_SA_RSP<1>")
	)
	(arc
		(start 124.610368 -248.48185)
		(mid 124.336139 -248.557775)
		(end 124.059696 -248.490486)
		(width 0.088646)
		(layer "In6.Cu")
		(net "M_E_CPU1_SA_RSP<1>")
	)
	(arc
		(start 136.170416 -248.01068)
		(mid 135.879938 -248.486399)
		(end 135.322564 -248.48185)
		(width 0.088646)
		(layer "In6.Cu")
		(net "M_E_CPU1_SA_RSP<1>")
	)
	(arc
		(start 125.924564 -248.48185)
		(mid 125.737366 -248.431707)
		(end 125.550168 -248.48185)
		(width 0.088646)
		(layer "In6.Cu")
		(net "M_E_CPU1_SA_RSP<1>")
	)
	(arc
		(start 131.188968 -248.48185)
		(mid 130.906266 -248.557592)
		(end 130.623564 -248.48185)
		(width 0.088646)
		(layer "In6.Cu")
		(net "M_E_CPU1_SA_RSP<1>")
	)
	(arc
		(start 128.743964 -248.48185)
		(mid 128.556766 -248.431707)
		(end 128.369568 -248.48185)
		(width 0.088646)
		(layer "In6.Cu")
		(net "M_E_CPU1_SA_RSP<1>")
	)
	(arc
		(start 134.948168 -248.48185)
		(mid 134.665466 -248.557592)
		(end 134.382764 -248.48185)
		(width 0.088646)
		(layer "In6.Cu")
		(net "M_E_CPU1_SA_RSP<1>")
	)
	(arc
		(start 126.489968 -248.48185)
		(mid 126.207266 -248.557592)
		(end 125.924564 -248.48185)
		(width 0.088646)
		(layer "In6.Cu")
		(net "M_E_CPU1_SA_RSP<1>")
	)
	(arc
		(start 128.369568 -248.48185)
		(mid 128.095339 -248.557775)
		(end 127.818896 -248.490486)
		(width 0.088646)
		(layer "In6.Cu")
		(net "M_E_CPU1_SA_RSP<1>")
	)
	(arc
		(start 135.322564 -248.48185)
		(mid 135.135366 -248.431707)
		(end 134.948168 -248.48185)
		(width 0.088646)
		(layer "In6.Cu")
		(net "M_E_CPU1_SA_RSP<1>")
	)
	(arc
		(start 129.68351 -248.48185)
		(mid 129.496312 -248.431707)
		(end 129.309114 -248.48185)
		(width 0.088646)
		(layer "In6.Cu")
		(net "M_E_CPU1_SA_RSP<1>")
	)
	(arc
		(start 134.008368 -248.48185)
		(mid 133.725666 -248.557592)
		(end 133.442964 -248.48185)
		(width 0.088646)
		(layer "In6.Cu")
		(net "M_E_CPU1_SA_RSP<1>")
	)
	(arc
		(start 129.309114 -248.48185)
		(mid 129.032555 -248.557559)
		(end 128.754378 -248.487946)
		(width 0.088646)
		(layer "In6.Cu")
		(net "M_E_CPU1_SA_RSP<1>")
	)
	(arc
		(start 132.503164 -248.48185)
		(mid 132.315966 -248.431707)
		(end 132.128768 -248.48185)
		(width 0.088646)
		(layer "In6.Cu")
		(net "M_E_CPU1_SA_RSP<1>")
	)
	(arc
		(start 131.563364 -248.48185)
		(mid 131.376166 -248.431707)
		(end 131.188968 -248.48185)
		(width 0.088646)
		(layer "In6.Cu")
		(net "M_E_CPU1_SA_RSP<1>")
	)
	(arc
		(start 130.623564 -248.48185)
		(mid 130.436366 -248.431707)
		(end 130.249168 -248.48185)
		(width 0.088646)
		(layer "In6.Cu")
		(net "M_E_CPU1_SA_RSP<1>")
	)
	(arc
		(start 130.249168 -248.48185)
		(mid 129.972355 -248.557686)
		(end 129.693924 -248.487946)
		(width 0.088646)
		(layer "In6.Cu")
		(net "M_E_CPU1_SA_RSP<1>")
	)
	(arc
		(start 133.442964 -248.48185)
		(mid 133.255766 -248.431707)
		(end 133.068568 -248.48185)
		(width 0.088646)
		(layer "In6.Cu")
		(net "M_E_CPU1_SA_RSP<1>")
	)
	(arc
		(start 125.550168 -248.48185)
		(mid 125.275939 -248.557775)
		(end 124.999496 -248.490486)
		(width 0.088646)
		(layer "In6.Cu")
		(net "M_E_CPU1_SA_RSP<1>")
	)
	(arc
		(start 134.382764 -248.48185)
		(mid 134.195566 -248.431707)
		(end 134.008368 -248.48185)
		(width 0.088646)
		(layer "In6.Cu")
		(net "M_E_CPU1_SA_RSP<1>")
	)
	(arc
		(start 133.068568 -248.48185)
		(mid 132.785866 -248.557592)
		(end 132.503164 -248.48185)
		(width 0.088646)
		(layer "In6.Cu")
		(net "M_E_CPU1_SA_RSP<1>")
	)
	(arc
		(start 132.128768 -248.48185)
		(mid 131.854539 -248.557775)
		(end 131.578096 -248.490486)
		(width 0.088646)
		(layer "In6.Cu")
		(net "M_E_CPU1_SA_RSP<1>")
	)
	(arc
		(start 127.429768 -248.48185)
		(mid 127.155539 -248.557775)
		(end 126.879096 -248.490486)
		(width 0.088646)
		(layer "In6.Cu")
		(net "M_E_CPU1_SA_RSP<1>")
	)
	(arc
		(start 127.804164 -248.48185)
		(mid 127.616966 -248.431707)
		(end 127.429768 -248.48185)
		(width 0.088646)
		(layer "In6.Cu")
		(net "M_E_CPU1_SA_RSP<1>")
	)
	(segment
		(start 123.857512 -249.342148)
		(end 123.857766 -249.341894)
		(width 0.20066)
		(layer "F.Cu")
		(net "M_E_CPU1_SA_RSP<0>")
	)
	(segment
		(start 123.857766 -249.341894)
		(end 123.857766 -248.806208)
		(width 0.20066)
		(layer "F.Cu")
		(net "M_E_CPU1_SA_RSP<0>")
	)
	(segment
		(start 165.226746 -244.066568)
		(end 166.357046 -244.066568)
		(width 0.20066)
		(layer "F.Cu")
		(net "M_E_CPU1_SA_RSP<0>")
	)
	(segment
		(start 135.226044 -249.65025)
		(end 134.930642 -249.354848)
		(width 0.088646)
		(layer "In6.Cu")
		(net "M_E_CPU1_SA_RSP<0>")
	)
	(segment
		(start 131.658868 -249.295666)
		(end 131.648454 -249.301762)
		(width 0.088646)
		(layer "In6.Cu")
		(net "M_E_CPU1_SA_RSP<0>")
	)
	(segment
		(start 127.899414 -249.295666)
		(end 127.884682 -249.304302)
		(width 0.088646)
		(layer "In6.Cu")
		(net "M_E_CPU1_SA_RSP<0>")
	)
	(segment
		(start 128.839214 -249.295666)
		(end 128.824482 -249.304302)
		(width 0.088646)
		(layer "In6.Cu")
		(net "M_E_CPU1_SA_RSP<0>")
	)
	(segment
		(start 124.486162 -249.27941)
		(end 123.857766 -248.806208)
		(width 0.088646)
		(layer "In6.Cu")
		(net "M_E_CPU1_SA_RSP<0>")
	)
	(segment
		(start 157.902656 -245.964456)
		(end 157.742636 -246.025924)
		(width 0.18288)
		(layer "In6.Cu")
		(net "M_E_CPU1_SA_RSP<0>")
	)
	(segment
		(start 125.080268 -249.295666)
		(end 125.069854 -249.301762)
		(width 0.088646)
		(layer "In6.Cu")
		(net "M_E_CPU1_SA_RSP<0>")
	)
	(segment
		(start 124.51461 -249.295666)
		(end 124.486162 -249.27941)
		(width 0.088646)
		(layer "In6.Cu")
		(net "M_E_CPU1_SA_RSP<0>")
	)
	(segment
		(start 139.121896 -248.83491)
		(end 137.677144 -248.83491)
		(width 0.18288)
		(layer "In6.Cu")
		(net "M_E_CPU1_SA_RSP<0>")
	)
	(segment
		(start 151.647144 -246.980456)
		(end 142.89786 -246.980456)
		(width 0.18288)
		(layer "In6.Cu")
		(net "M_E_CPU1_SA_RSP<0>")
	)
	(segment
		(start 156.560266 -246.515636)
		(end 152.76957 -246.515636)
		(width 0.18288)
		(layer "In6.Cu")
		(net "M_E_CPU1_SA_RSP<0>")
	)
	(segment
		(start 158.865062 -245.964456)
		(end 157.902656 -245.964456)
		(width 0.18288)
		(layer "In6.Cu")
		(net "M_E_CPU1_SA_RSP<0>")
	)
	(segment
		(start 137.17397 -249.183652)
		(end 136.438894 -249.183652)
		(width 0.088646)
		(layer "In6.Cu")
		(net "M_E_CPU1_SA_RSP<0>")
	)
	(segment
		(start 136.438894 -249.183652)
		(end 135.972296 -249.65025)
		(width 0.088646)
		(layer "In6.Cu")
		(net "M_E_CPU1_SA_RSP<0>")
	)
	(segment
		(start 165.226746 -244.066568)
		(end 164.802566 -244.490748)
		(width 0.18288)
		(layer "In6.Cu")
		(net "M_E_CPU1_SA_RSP<0>")
	)
	(segment
		(start 130.718814 -249.295666)
		(end 130.704082 -249.304302)
		(width 0.088646)
		(layer "In6.Cu")
		(net "M_E_CPU1_SA_RSP<0>")
	)
	(segment
		(start 126.959614 -249.295666)
		(end 126.944882 -249.304302)
		(width 0.088646)
		(layer "In6.Cu")
		(net "M_E_CPU1_SA_RSP<0>")
	)
	(segment
		(start 139.470638 -249.183652)
		(end 139.121896 -248.83491)
		(width 0.18288)
		(layer "In6.Cu")
		(net "M_E_CPU1_SA_RSP<0>")
	)
	(segment
		(start 162.42284 -244.490748)
		(end 158.865062 -245.964456)
		(width 0.18288)
		(layer "In6.Cu")
		(net "M_E_CPU1_SA_RSP<0>")
	)
	(segment
		(start 137.677144 -248.83491)
		(end 137.522712 -248.83491)
		(width 0.088646)
		(layer "In6.Cu")
		(net "M_E_CPU1_SA_RSP<0>")
	)
	(segment
		(start 126.019814 -249.295666)
		(end 126.0094 -249.301762)
		(width 0.088646)
		(layer "In6.Cu")
		(net "M_E_CPU1_SA_RSP<0>")
	)
	(segment
		(start 164.802566 -244.490748)
		(end 162.42284 -244.490748)
		(width 0.18288)
		(layer "In6.Cu")
		(net "M_E_CPU1_SA_RSP<0>")
	)
	(segment
		(start 152.76957 -246.515636)
		(end 151.647144 -246.980456)
		(width 0.18288)
		(layer "In6.Cu")
		(net "M_E_CPU1_SA_RSP<0>")
	)
	(segment
		(start 137.522712 -248.83491)
		(end 137.17397 -249.183652)
		(width 0.088646)
		(layer "In6.Cu")
		(net "M_E_CPU1_SA_RSP<0>")
	)
	(segment
		(start 142.89786 -246.980456)
		(end 140.694664 -249.183652)
		(width 0.18288)
		(layer "In6.Cu")
		(net "M_E_CPU1_SA_RSP<0>")
	)
	(segment
		(start 157.742636 -246.025924)
		(end 156.560266 -246.515636)
		(width 0.18288)
		(layer "In6.Cu")
		(net "M_E_CPU1_SA_RSP<0>")
	)
	(segment
		(start 135.972296 -249.65025)
		(end 135.226044 -249.65025)
		(width 0.088646)
		(layer "In6.Cu")
		(net "M_E_CPU1_SA_RSP<0>")
	)
	(segment
		(start 140.694664 -249.183652)
		(end 139.470638 -249.183652)
		(width 0.18288)
		(layer "In6.Cu")
		(net "M_E_CPU1_SA_RSP<0>")
	)
	(arc
		(start 134.852664 -249.295666)
		(mid 134.665466 -249.245523)
		(end 134.478268 -249.295666)
		(width 0.088646)
		(layer "In6.Cu")
		(net "M_E_CPU1_SA_RSP<0>")
	)
	(arc
		(start 126.944882 -249.304302)
		(mid 126.668407 -249.371622)
		(end 126.39421 -249.295666)
		(width 0.088646)
		(layer "In6.Cu")
		(net "M_E_CPU1_SA_RSP<0>")
	)
	(arc
		(start 131.648454 -249.301762)
		(mid 131.370022 -249.371608)
		(end 131.09321 -249.295666)
		(width 0.088646)
		(layer "In6.Cu")
		(net "M_E_CPU1_SA_RSP<0>")
	)
	(arc
		(start 130.704082 -249.304302)
		(mid 130.427607 -249.371622)
		(end 130.15341 -249.295666)
		(width 0.088646)
		(layer "In6.Cu")
		(net "M_E_CPU1_SA_RSP<0>")
	)
	(arc
		(start 128.824482 -249.304302)
		(mid 128.548007 -249.371622)
		(end 128.27381 -249.295666)
		(width 0.088646)
		(layer "In6.Cu")
		(net "M_E_CPU1_SA_RSP<0>")
	)
	(arc
		(start 129.21361 -249.295666)
		(mid 129.026412 -249.245523)
		(end 128.839214 -249.295666)
		(width 0.088646)
		(layer "In6.Cu")
		(net "M_E_CPU1_SA_RSP<0>")
	)
	(arc
		(start 132.033264 -249.295666)
		(mid 131.846066 -249.245523)
		(end 131.658868 -249.295666)
		(width 0.088646)
		(layer "In6.Cu")
		(net "M_E_CPU1_SA_RSP<0>")
	)
	(arc
		(start 125.454664 -249.295666)
		(mid 125.267466 -249.245523)
		(end 125.080268 -249.295666)
		(width 0.088646)
		(layer "In6.Cu")
		(net "M_E_CPU1_SA_RSP<0>")
	)
	(arc
		(start 134.478268 -249.295666)
		(mid 134.195566 -249.371442)
		(end 133.912864 -249.295666)
		(width 0.088646)
		(layer "In6.Cu")
		(net "M_E_CPU1_SA_RSP<0>")
	)
	(arc
		(start 126.39421 -249.295666)
		(mid 126.207012 -249.245523)
		(end 126.019814 -249.295666)
		(width 0.088646)
		(layer "In6.Cu")
		(net "M_E_CPU1_SA_RSP<0>")
	)
	(arc
		(start 127.33401 -249.295666)
		(mid 127.146812 -249.245523)
		(end 126.959614 -249.295666)
		(width 0.088646)
		(layer "In6.Cu")
		(net "M_E_CPU1_SA_RSP<0>")
	)
	(arc
		(start 127.884682 -249.304302)
		(mid 127.608207 -249.371622)
		(end 127.33401 -249.295666)
		(width 0.088646)
		(layer "In6.Cu")
		(net "M_E_CPU1_SA_RSP<0>")
	)
	(arc
		(start 128.27381 -249.295666)
		(mid 128.086612 -249.245523)
		(end 127.899414 -249.295666)
		(width 0.088646)
		(layer "In6.Cu")
		(net "M_E_CPU1_SA_RSP<0>")
	)
	(arc
		(start 129.779014 -249.295666)
		(mid 129.496312 -249.371442)
		(end 129.21361 -249.295666)
		(width 0.088646)
		(layer "In6.Cu")
		(net "M_E_CPU1_SA_RSP<0>")
	)
	(arc
		(start 125.069854 -249.301762)
		(mid 124.791422 -249.371608)
		(end 124.51461 -249.295666)
		(width 0.088646)
		(layer "In6.Cu")
		(net "M_E_CPU1_SA_RSP<0>")
	)
	(arc
		(start 126.0094 -249.301762)
		(mid 125.731222 -249.371485)
		(end 125.454664 -249.295666)
		(width 0.088646)
		(layer "In6.Cu")
		(net "M_E_CPU1_SA_RSP<0>")
	)
	(arc
		(start 131.09321 -249.295666)
		(mid 130.906012 -249.245523)
		(end 130.718814 -249.295666)
		(width 0.088646)
		(layer "In6.Cu")
		(net "M_E_CPU1_SA_RSP<0>")
	)
	(arc
		(start 132.598668 -249.295666)
		(mid 132.315966 -249.371442)
		(end 132.033264 -249.295666)
		(width 0.088646)
		(layer "In6.Cu")
		(net "M_E_CPU1_SA_RSP<0>")
	)
	(arc
		(start 134.930642 -249.354848)
		(mid 134.893592 -249.322702)
		(end 134.852664 -249.295666)
		(width 0.088646)
		(layer "In6.Cu")
		(net "M_E_CPU1_SA_RSP<0>")
	)
	(arc
		(start 132.973064 -249.295666)
		(mid 132.785866 -249.245523)
		(end 132.598668 -249.295666)
		(width 0.088646)
		(layer "In6.Cu")
		(net "M_E_CPU1_SA_RSP<0>")
	)
	(arc
		(start 133.538468 -249.295666)
		(mid 133.255766 -249.371442)
		(end 132.973064 -249.295666)
		(width 0.088646)
		(layer "In6.Cu")
		(net "M_E_CPU1_SA_RSP<0>")
	)
	(arc
		(start 130.15341 -249.295666)
		(mid 129.966212 -249.245523)
		(end 129.779014 -249.295666)
		(width 0.088646)
		(layer "In6.Cu")
		(net "M_E_CPU1_SA_RSP<0>")
	)
	(arc
		(start 133.912864 -249.295666)
		(mid 133.725666 -249.245523)
		(end 133.538468 -249.295666)
		(width 0.088646)
		(layer "In6.Cu")
		(net "M_E_CPU1_SA_RSP<0>")
	)
	(segment
		(start 132.598668 -249.831606)
		(end 132.589778 -249.836686)
		(width 0.088646)
		(layer "F.Cu")
		(net "M_E_CPU1_SA_PAR")
	)
	(segment
		(start 135.03656 -251.851922)
		(end 135.308086 -251.964444)
		(width 0.088646)
		(layer "F.Cu")
		(net "M_E_CPU1_SA_PAR")
	)
	(segment
		(start 138.096498 -252.597412)
		(end 140.618464 -253.09957)
		(width 0.1016)
		(layer "F.Cu")
		(net "M_E_CPU1_SA_PAR")
	)
	(segment
		(start 133.533642 -249.579892)
		(end 133.45922 -249.662188)
		(width 0.088646)
		(layer "F.Cu")
		(net "M_E_CPU1_SA_PAR")
	)
	(segment
		(start 133.725666 -248.528078)
		(end 133.623558 -249.403108)
		(width 0.088646)
		(layer "F.Cu")
		(net "M_E_CPU1_SA_PAR")
	)
	(segment
		(start 132.71881 -250.621292)
		(end 133.700266 -251.190506)
		(width 0.088646)
		(layer "F.Cu")
		(net "M_E_CPU1_SA_PAR")
	)
	(segment
		(start 133.623558 -249.403108)
		(end 133.58114 -249.505216)
		(width 0.088646)
		(layer "F.Cu")
		(net "M_E_CPU1_SA_PAR")
	)
	(segment
		(start 132.473192 -250.3678)
		(end 132.526024 -250.43384)
		(width 0.088646)
		(layer "F.Cu")
		(net "M_E_CPU1_SA_PAR")
	)
	(segment
		(start 144.630394 -256.18821)
		(end 145.16735 -256.18821)
		(width 0.1016)
		(layer "F.Cu")
		(net "M_E_CPU1_SA_PAR")
	)
	(segment
		(start 142.194534 -253.75235)
		(end 144.630394 -256.18821)
		(width 0.1016)
		(layer "F.Cu")
		(net "M_E_CPU1_SA_PAR")
	)
	(segment
		(start 163.887912 -260.526276)
		(end 163.772596 -260.641592)
		(width 0.1016)
		(layer "F.Cu")
		(net "M_E_CPU1_SA_PAR")
	)
	(segment
		(start 132.439918 -250.313698)
		(end 132.473192 -250.3678)
		(width 0.088646)
		(layer "F.Cu")
		(net "M_E_CPU1_SA_PAR")
	)
	(segment
		(start 133.700266 -251.190506)
		(end 135.03656 -251.851922)
		(width 0.088646)
		(layer "F.Cu")
		(net "M_E_CPU1_SA_PAR")
	)
	(segment
		(start 161.65957 -260.478524)
		(end 160.547812 -259.366766)
		(width 0.20066)
		(layer "F.Cu")
		(net "M_E_CPU1_SA_PAR")
	)
	(segment
		(start 149.323552 -256.18821)
		(end 156.997146 -259.366766)
		(width 0.20066)
		(layer "F.Cu")
		(net "M_E_CPU1_SA_PAR")
	)
	(segment
		(start 165.047422 -259.366766)
		(end 163.887912 -260.526276)
		(width 0.20066)
		(layer "F.Cu")
		(net "M_E_CPU1_SA_PAR")
	)
	(segment
		(start 140.618464 -253.09957)
		(end 142.194534 -253.75235)
		(width 0.1016)
		(layer "F.Cu")
		(net "M_E_CPU1_SA_PAR")
	)
	(segment
		(start 132.411216 -250.212606)
		(end 132.439918 -250.313698)
		(width 0.088646)
		(layer "F.Cu")
		(net "M_E_CPU1_SA_PAR")
	)
	(segment
		(start 136.95426 -252.485144)
		(end 138.096498 -252.597412)
		(width 0.1016)
		(layer "F.Cu")
		(net "M_E_CPU1_SA_PAR")
	)
	(segment
		(start 156.997146 -259.366766)
		(end 158.813246 -259.366766)
		(width 0.20066)
		(layer "F.Cu")
		(net "M_E_CPU1_SA_PAR")
	)
	(segment
		(start 161.938462 -260.526276)
		(end 161.89071 -260.478524)
		(width 0.20066)
		(layer "F.Cu")
		(net "M_E_CPU1_SA_PAR")
	)
	(segment
		(start 162.053778 -260.641592)
		(end 161.938462 -260.526276)
		(width 0.1016)
		(layer "F.Cu")
		(net "M_E_CPU1_SA_PAR")
	)
	(segment
		(start 161.89071 -260.478524)
		(end 161.65957 -260.478524)
		(width 0.20066)
		(layer "F.Cu")
		(net "M_E_CPU1_SA_PAR")
	)
	(segment
		(start 145.241518 -256.18821)
		(end 149.323552 -256.18821)
		(width 0.20066)
		(layer "F.Cu")
		(net "M_E_CPU1_SA_PAR")
	)
	(segment
		(start 163.772596 -260.641592)
		(end 162.053778 -260.641592)
		(width 0.1016)
		(layer "F.Cu")
		(net "M_E_CPU1_SA_PAR")
	)
	(segment
		(start 166.357046 -259.366766)
		(end 165.047422 -259.366766)
		(width 0.20066)
		(layer "F.Cu")
		(net "M_E_CPU1_SA_PAR")
	)
	(segment
		(start 132.526024 -250.43384)
		(end 132.71881 -250.621292)
		(width 0.088646)
		(layer "F.Cu")
		(net "M_E_CPU1_SA_PAR")
	)
	(segment
		(start 160.547812 -259.366766)
		(end 158.813246 -259.366766)
		(width 0.20066)
		(layer "F.Cu")
		(net "M_E_CPU1_SA_PAR")
	)
	(segment
		(start 135.308086 -251.964444)
		(end 136.200642 -252.335284)
		(width 0.1016)
		(layer "F.Cu")
		(net "M_E_CPU1_SA_PAR")
	)
	(segment
		(start 133.166866 -249.747786)
		(end 132.91439 -249.747786)
		(width 0.088646)
		(layer "F.Cu")
		(net "M_E_CPU1_SA_PAR")
	)
	(segment
		(start 132.411216 -250.155964)
		(end 132.411216 -250.212606)
		(width 0.088646)
		(layer "F.Cu")
		(net "M_E_CPU1_SA_PAR")
	)
	(segment
		(start 136.200642 -252.335284)
		(end 136.95426 -252.485144)
		(width 0.1016)
		(layer "F.Cu")
		(net "M_E_CPU1_SA_PAR")
	)
	(segment
		(start 145.16735 -256.18821)
		(end 145.241518 -256.18821)
		(width 0.101854)
		(layer "F.Cu")
		(net "M_E_CPU1_SA_PAR")
	)
	(arc
		(start 132.91439 -249.747786)
		(mid 132.751065 -249.769105)
		(end 132.598668 -249.831606)
		(width 0.088646)
		(layer "F.Cu")
		(net "M_E_CPU1_SA_PAR")
	)
	(arc
		(start 133.45922 -249.662188)
		(mid 133.425262 -249.69153)
		(end 133.385052 -249.711464)
		(width 0.088646)
		(layer "F.Cu")
		(net "M_E_CPU1_SA_PAR")
	)
	(arc
		(start 133.385052 -249.711464)
		(mid 133.277474 -249.738732)
		(end 133.166866 -249.747786)
		(width 0.088646)
		(layer "F.Cu")
		(net "M_E_CPU1_SA_PAR")
	)
	(arc
		(start 132.589778 -249.836686)
		(mid 132.458864 -249.973046)
		(end 132.411216 -250.155964)
		(width 0.088646)
		(layer "F.Cu")
		(net "M_E_CPU1_SA_PAR")
	)
	(arc
		(start 133.58114 -249.505216)
		(mid 133.560578 -249.54458)
		(end 133.533642 -249.579892)
		(width 0.088646)
		(layer "F.Cu")
		(net "M_E_CPU1_SA_PAR")
	)
	(segment
		(start 163.578032 -274.067778)
		(end 163.326826 -273.816572)
		(width 0.20066)
		(layer "F.Cu")
		(net "M_E_CPU1_SA_DQS_DP<9>")
	)
	(segment
		(start 152.157938 -273.463004)
		(end 152.607264 -273.703288)
		(width 0.1524)
		(layer "F.Cu")
		(net "M_E_CPU1_SA_DQS_DP<9>")
	)
	(segment
		(start 162.408616 -273.816572)
		(end 162.913314 -273.816572)
		(width 0.20066)
		(layer "F.Cu")
		(net "M_E_CPU1_SA_DQS_DP<9>")
	)
	(segment
		(start 164.585904 -273.656298)
		(end 164.454586 -273.656298)
		(width 0.20066)
		(layer "F.Cu")
		(net "M_E_CPU1_SA_DQS_DP<9>")
	)
	(segment
		(start 138.810238 -259.574792)
		(end 138.81735 -259.570728)
		(width 0.088646)
		(layer "F.Cu")
		(net "M_E_CPU1_SA_DQS_DP<9>")
	)
	(segment
		(start 165.347396 -273.39163)
		(end 164.972238 -273.39163)
		(width 0.101854)
		(layer "F.Cu")
		(net "M_E_CPU1_SA_DQS_DP<9>")
	)
	(segment
		(start 142.209266 -261.846568)
		(end 142.22476 -261.862062)
		(width 0.088646)
		(layer "F.Cu")
		(net "M_E_CPU1_SA_DQS_DP<9>")
	)
	(segment
		(start 141.76883 -261.451344)
		(end 142.164816 -261.84606)
		(width 0.088646)
		(layer "F.Cu")
		(net "M_E_CPU1_SA_DQS_DP<9>")
	)
	(segment
		(start 151.826468 -272.968212)
		(end 152.157938 -273.463004)
		(width 0.1524)
		(layer "F.Cu")
		(net "M_E_CPU1_SA_DQS_DP<9>")
	)
	(segment
		(start 169.62755 -274.078192)
		(end 169.207434 -274.078192)
		(width 0.20066)
		(layer "F.Cu")
		(net "M_E_CPU1_SA_DQS_DP<9>")
	)
	(segment
		(start 168.133268 -273.63928)
		(end 167.885618 -273.39163)
		(width 0.20066)
		(layer "F.Cu")
		(net "M_E_CPU1_SA_DQS_DP<9>")
	)
	(segment
		(start 159.96158 -273.369786)
		(end 160.152588 -273.369786)
		(width 0.20066)
		(layer "F.Cu")
		(net "M_E_CPU1_SA_DQS_DP<9>")
	)
	(segment
		(start 167.360092 -273.39163)
		(end 165.347396 -273.39163)
		(width 0.1016)
		(layer "F.Cu")
		(net "M_E_CPU1_SA_DQS_DP<9>")
	)
	(segment
		(start 153.321004 -273.666458)
		(end 156.149548 -273.666458)
		(width 0.20066)
		(layer "F.Cu")
		(net "M_E_CPU1_SA_DQS_DP<9>")
	)
	(segment
		(start 169.207434 -274.078192)
		(end 168.768522 -273.63928)
		(width 0.20066)
		(layer "F.Cu")
		(net "M_E_CPU1_SA_DQS_DP<9>")
	)
	(segment
		(start 139.09421 -259.519928)
		(end 139.187682 -259.522214)
		(width 0.088646)
		(layer "F.Cu")
		(net "M_E_CPU1_SA_DQS_DP<9>")
	)
	(segment
		(start 162.157664 -274.067524)
		(end 162.408616 -273.816572)
		(width 0.20066)
		(layer "F.Cu")
		(net "M_E_CPU1_SA_DQS_DP<9>")
	)
	(segment
		(start 164.850572 -273.39163)
		(end 164.585904 -273.656298)
		(width 0.20066)
		(layer "F.Cu")
		(net "M_E_CPU1_SA_DQS_DP<9>")
	)
	(segment
		(start 151.451056 -271.088612)
		(end 151.826468 -272.968212)
		(width 0.1524)
		(layer "F.Cu")
		(net "M_E_CPU1_SA_DQS_DP<9>")
	)
	(segment
		(start 164.972238 -273.39163)
		(end 164.850572 -273.39163)
		(width 0.20066)
		(layer "F.Cu")
		(net "M_E_CPU1_SA_DQS_DP<9>")
	)
	(segment
		(start 159.939736 -273.39163)
		(end 159.96158 -273.369786)
		(width 0.101854)
		(layer "F.Cu")
		(net "M_E_CPU1_SA_DQS_DP<9>")
	)
	(segment
		(start 169.88917 -273.816572)
		(end 169.62755 -274.078192)
		(width 0.20066)
		(layer "F.Cu")
		(net "M_E_CPU1_SA_DQS_DP<9>")
	)
	(segment
		(start 157.796484 -273.391376)
		(end 157.796738 -273.39163)
		(width 0.1016)
		(layer "F.Cu")
		(net "M_E_CPU1_SA_DQS_DP<9>")
	)
	(segment
		(start 139.8397 -259.522214)
		(end 141.76883 -261.451344)
		(width 0.088646)
		(layer "F.Cu")
		(net "M_E_CPU1_SA_DQS_DP<9>")
	)
	(segment
		(start 170.457114 -273.816572)
		(end 169.88917 -273.816572)
		(width 0.20066)
		(layer "F.Cu")
		(net "M_E_CPU1_SA_DQS_DP<9>")
	)
	(segment
		(start 157.515052 -273.391376)
		(end 157.796484 -273.391376)
		(width 0.101854)
		(layer "F.Cu")
		(net "M_E_CPU1_SA_DQS_DP<9>")
	)
	(segment
		(start 160.816544 -273.66849)
		(end 161.215578 -274.067524)
		(width 0.20066)
		(layer "F.Cu")
		(net "M_E_CPU1_SA_DQS_DP<9>")
	)
	(segment
		(start 163.76904 -274.067778)
		(end 163.578032 -274.067778)
		(width 0.20066)
		(layer "F.Cu")
		(net "M_E_CPU1_SA_DQS_DP<9>")
	)
	(segment
		(start 160.152588 -273.369786)
		(end 160.451292 -273.66849)
		(width 0.20066)
		(layer "F.Cu")
		(net "M_E_CPU1_SA_DQS_DP<9>")
	)
	(segment
		(start 139.187682 -259.522214)
		(end 139.8397 -259.522214)
		(width 0.088646)
		(layer "F.Cu")
		(net "M_E_CPU1_SA_DQS_DP<9>")
	)
	(segment
		(start 163.326826 -273.816572)
		(end 162.913314 -273.816572)
		(width 0.20066)
		(layer "F.Cu")
		(net "M_E_CPU1_SA_DQS_DP<9>")
	)
	(segment
		(start 160.451292 -273.66849)
		(end 160.816544 -273.66849)
		(width 0.20066)
		(layer "F.Cu")
		(net "M_E_CPU1_SA_DQS_DP<9>")
	)
	(segment
		(start 161.215578 -274.067524)
		(end 162.157664 -274.067524)
		(width 0.20066)
		(layer "F.Cu")
		(net "M_E_CPU1_SA_DQS_DP<9>")
	)
	(segment
		(start 153.246074 -273.703288)
		(end 153.282904 -273.666458)
		(width 0.1524)
		(layer "F.Cu")
		(net "M_E_CPU1_SA_DQS_DP<9>")
	)
	(segment
		(start 156.149548 -273.666458)
		(end 156.42463 -273.391376)
		(width 0.20066)
		(layer "F.Cu")
		(net "M_E_CPU1_SA_DQS_DP<9>")
	)
	(segment
		(start 146.81073 -266.448032)
		(end 146.810476 -266.448032)
		(width 0.1524)
		(layer "F.Cu")
		(net "M_E_CPU1_SA_DQS_DP<9>")
	)
	(segment
		(start 142.22476 -261.862062)
		(end 146.81073 -266.448032)
		(width 0.1524)
		(layer "F.Cu")
		(net "M_E_CPU1_SA_DQS_DP<9>")
	)
	(segment
		(start 138.064494 -259.894832)
		(end 138.556492 -259.706872)
		(width 0.088646)
		(layer "F.Cu")
		(net "M_E_CPU1_SA_DQS_DP<9>")
	)
	(segment
		(start 153.282904 -273.666458)
		(end 153.321004 -273.666458)
		(width 0.1524)
		(layer "F.Cu")
		(net "M_E_CPU1_SA_DQS_DP<9>")
	)
	(segment
		(start 159.801814 -273.39163)
		(end 159.939736 -273.39163)
		(width 0.101854)
		(layer "F.Cu")
		(net "M_E_CPU1_SA_DQS_DP<9>")
	)
	(segment
		(start 142.164816 -261.84606)
		(end 142.209266 -261.846568)
		(width 0.088646)
		(layer "F.Cu")
		(net "M_E_CPU1_SA_DQS_DP<9>")
	)
	(segment
		(start 168.768522 -273.63928)
		(end 168.133268 -273.63928)
		(width 0.20066)
		(layer "F.Cu")
		(net "M_E_CPU1_SA_DQS_DP<9>")
	)
	(segment
		(start 157.796738 -273.39163)
		(end 159.801814 -273.39163)
		(width 0.1016)
		(layer "F.Cu")
		(net "M_E_CPU1_SA_DQS_DP<9>")
	)
	(segment
		(start 167.804084 -273.39163)
		(end 167.360092 -273.39163)
		(width 0.101854)
		(layer "F.Cu")
		(net "M_E_CPU1_SA_DQS_DP<9>")
	)
	(segment
		(start 164.454586 -273.656298)
		(end 163.986718 -273.8501)
		(width 0.20066)
		(layer "F.Cu")
		(net "M_E_CPU1_SA_DQS_DP<9>")
	)
	(segment
		(start 167.885618 -273.39163)
		(end 167.804084 -273.39163)
		(width 0.20066)
		(layer "F.Cu")
		(net "M_E_CPU1_SA_DQS_DP<9>")
	)
	(segment
		(start 163.986718 -273.8501)
		(end 163.76904 -274.067778)
		(width 0.20066)
		(layer "F.Cu")
		(net "M_E_CPU1_SA_DQS_DP<9>")
	)
	(segment
		(start 146.810476 -266.448032)
		(end 151.451056 -271.088612)
		(width 0.1524)
		(layer "F.Cu")
		(net "M_E_CPU1_SA_DQS_DP<9>")
	)
	(segment
		(start 152.607264 -273.703288)
		(end 153.246074 -273.703288)
		(width 0.1524)
		(layer "F.Cu")
		(net "M_E_CPU1_SA_DQS_DP<9>")
	)
	(segment
		(start 156.42463 -273.391376)
		(end 157.515052 -273.391376)
		(width 0.20066)
		(layer "F.Cu")
		(net "M_E_CPU1_SA_DQS_DP<9>")
	)
	(arc
		(start 138.556492 -259.706872)
		(mid 138.684241 -259.642516)
		(end 138.810238 -259.574792)
		(width 0.088646)
		(layer "F.Cu")
		(net "M_E_CPU1_SA_DQS_DP<9>")
	)
	(arc
		(start 138.81735 -259.570728)
		(mid 138.821679 -259.568334)
		(end 138.825986 -259.565902)
		(width 0.088646)
		(layer "F.Cu")
		(net "M_E_CPU1_SA_DQS_DP<9>")
	)
	(arc
		(start 138.825986 -259.565902)
		(mid 138.882882 -259.53992)
		(end 138.944096 -259.52704)
		(width 0.088646)
		(layer "F.Cu")
		(net "M_E_CPU1_SA_DQS_DP<9>")
	)
	(arc
		(start 138.944096 -259.52704)
		(mid 139.019069 -259.521718)
		(end 139.09421 -259.519928)
		(width 0.088646)
		(layer "F.Cu")
		(net "M_E_CPU1_SA_DQS_DP<9>")
	)
	(segment
		(start 164.76599 -282.99283)
		(end 164.487606 -282.99283)
		(width 0.20066)
		(layer "F.Cu")
		(net "M_E_CPU1_SA_DQS_DP<8>")
	)
	(segment
		(start 160.656016 -283.018484)
		(end 160.96615 -283.018484)
		(width 0.20066)
		(layer "F.Cu")
		(net "M_E_CPU1_SA_DQS_DP<8>")
	)
	(segment
		(start 155.088844 -283.907738)
		(end 155.325318 -283.809694)
		(width 0.20066)
		(layer "F.Cu")
		(net "M_E_CPU1_SA_DQS_DP<8>")
	)
	(segment
		(start 167.367458 -282.734258)
		(end 167.360092 -282.741624)
		(width 0.1016)
		(layer "F.Cu")
		(net "M_E_CPU1_SA_DQS_DP<8>")
	)
	(segment
		(start 167.360092 -282.741624)
		(end 165.347396 -282.741624)
		(width 0.1016)
		(layer "F.Cu")
		(net "M_E_CPU1_SA_DQS_DP<8>")
	)
	(segment
		(start 149.984206 -281.121104)
		(end 150.010876 -281.147774)
		(width 0.1524)
		(layer "F.Cu")
		(net "M_E_CPU1_SA_DQS_DP<8>")
	)
	(segment
		(start 149.787356 -280.97607)
		(end 149.93239 -281.121104)
		(width 0.1524)
		(layer "F.Cu")
		(net "M_E_CPU1_SA_DQS_DP<8>")
	)
	(segment
		(start 167.944292 -282.989274)
		(end 167.689276 -282.734258)
		(width 0.20066)
		(layer "F.Cu")
		(net "M_E_CPU1_SA_DQS_DP<8>")
	)
	(segment
		(start 140.429488 -265.615674)
		(end 140.946632 -266.132818)
		(width 0.088646)
		(layer "F.Cu")
		(net "M_E_CPU1_SA_DQS_DP<8>")
	)
	(segment
		(start 164.062664 -283.417772)
		(end 163.757864 -283.417772)
		(width 0.20066)
		(layer "F.Cu")
		(net "M_E_CPU1_SA_DQS_DP<8>")
	)
	(segment
		(start 152.305258 -283.442156)
		(end 152.892252 -283.83484)
		(width 0.20066)
		(layer "F.Cu")
		(net "M_E_CPU1_SA_DQS_DP<8>")
	)
	(segment
		(start 157.798262 -282.734766)
		(end 157.80512 -282.741624)
		(width 0.1016)
		(layer "F.Cu")
		(net "M_E_CPU1_SA_DQS_DP<8>")
	)
	(segment
		(start 170.457114 -283.166566)
		(end 169.88917 -283.166566)
		(width 0.20066)
		(layer "F.Cu")
		(net "M_E_CPU1_SA_DQS_DP<8>")
	)
	(segment
		(start 156.400246 -282.734766)
		(end 157.791658 -282.734766)
		(width 0.20066)
		(layer "F.Cu")
		(net "M_E_CPU1_SA_DQS_DP<8>")
	)
	(segment
		(start 163.506658 -283.166566)
		(end 162.913314 -283.166566)
		(width 0.20066)
		(layer "F.Cu")
		(net "M_E_CPU1_SA_DQS_DP<8>")
	)
	(segment
		(start 165.347396 -282.741624)
		(end 165.340284 -282.734512)
		(width 0.1016)
		(layer "F.Cu")
		(net "M_E_CPU1_SA_DQS_DP<8>")
	)
	(segment
		(start 157.80512 -282.741624)
		(end 159.800798 -282.741624)
		(width 0.1016)
		(layer "F.Cu")
		(net "M_E_CPU1_SA_DQS_DP<8>")
	)
	(segment
		(start 159.821372 -282.72105)
		(end 159.823658 -282.72105)
		(width 0.101854)
		(layer "F.Cu")
		(net "M_E_CPU1_SA_DQS_DP<8>")
	)
	(segment
		(start 140.991844 -266.132818)
		(end 141.007338 -266.148312)
		(width 0.088646)
		(layer "F.Cu")
		(net "M_E_CPU1_SA_DQS_DP<8>")
	)
	(segment
		(start 161.803842 -283.365702)
		(end 162.20948 -283.365702)
		(width 0.20066)
		(layer "F.Cu")
		(net "M_E_CPU1_SA_DQS_DP<8>")
	)
	(segment
		(start 167.689276 -282.734258)
		(end 167.367458 -282.734258)
		(width 0.20066)
		(layer "F.Cu")
		(net "M_E_CPU1_SA_DQS_DP<8>")
	)
	(segment
		(start 160.96615 -283.018484)
		(end 161.803842 -283.365702)
		(width 0.20066)
		(layer "F.Cu")
		(net "M_E_CPU1_SA_DQS_DP<8>")
	)
	(segment
		(start 162.20948 -283.365702)
		(end 162.408616 -283.166566)
		(width 0.20066)
		(layer "F.Cu")
		(net "M_E_CPU1_SA_DQS_DP<8>")
	)
	(segment
		(start 149.130258 -279.874218)
		(end 149.545294 -280.650442)
		(width 0.1524)
		(layer "F.Cu")
		(net "M_E_CPU1_SA_DQS_DP<8>")
	)
	(segment
		(start 140.429742 -265.615674)
		(end 140.429488 -265.615674)
		(width 0.088646)
		(layer "F.Cu")
		(net "M_E_CPU1_SA_DQS_DP<8>")
	)
	(segment
		(start 162.408616 -283.166566)
		(end 162.913314 -283.166566)
		(width 0.20066)
		(layer "F.Cu")
		(net "M_E_CPU1_SA_DQS_DP<8>")
	)
	(segment
		(start 139.274042 -264.460228)
		(end 140.429742 -265.615674)
		(width 0.088646)
		(layer "F.Cu")
		(net "M_E_CPU1_SA_DQS_DP<8>")
	)
	(segment
		(start 159.800798 -282.741624)
		(end 159.821372 -282.72105)
		(width 0.1016)
		(layer "F.Cu")
		(net "M_E_CPU1_SA_DQS_DP<8>")
	)
	(segment
		(start 169.88917 -283.166566)
		(end 169.620946 -283.43479)
		(width 0.20066)
		(layer "F.Cu")
		(net "M_E_CPU1_SA_DQS_DP<8>")
	)
	(segment
		(start 147.729702 -272.870676)
		(end 149.130258 -279.874218)
		(width 0.1524)
		(layer "F.Cu")
		(net "M_E_CPU1_SA_DQS_DP<8>")
	)
	(segment
		(start 165.335458 -282.734512)
		(end 165.024308 -282.734512)
		(width 0.20066)
		(layer "F.Cu")
		(net "M_E_CPU1_SA_DQS_DP<8>")
	)
	(segment
		(start 155.325318 -283.809694)
		(end 156.400246 -282.734766)
		(width 0.20066)
		(layer "F.Cu")
		(net "M_E_CPU1_SA_DQS_DP<8>")
	)
	(segment
		(start 149.545294 -280.650442)
		(end 149.787356 -280.97607)
		(width 0.1524)
		(layer "F.Cu")
		(net "M_E_CPU1_SA_DQS_DP<8>")
	)
	(segment
		(start 152.892252 -283.83484)
		(end 153.068528 -283.907738)
		(width 0.20066)
		(layer "F.Cu")
		(net "M_E_CPU1_SA_DQS_DP<8>")
	)
	(segment
		(start 141.007338 -266.148312)
		(end 147.729702 -272.870676)
		(width 0.1524)
		(layer "F.Cu")
		(net "M_E_CPU1_SA_DQS_DP<8>")
	)
	(segment
		(start 165.024308 -282.734512)
		(end 164.76599 -282.99283)
		(width 0.20066)
		(layer "F.Cu")
		(net "M_E_CPU1_SA_DQS_DP<8>")
	)
	(segment
		(start 164.487606 -282.99283)
		(end 164.062664 -283.417772)
		(width 0.20066)
		(layer "F.Cu")
		(net "M_E_CPU1_SA_DQS_DP<8>")
	)
	(segment
		(start 169.620946 -283.43479)
		(end 169.04335 -283.43479)
		(width 0.20066)
		(layer "F.Cu")
		(net "M_E_CPU1_SA_DQS_DP<8>")
	)
	(segment
		(start 169.04335 -283.43479)
		(end 168.597834 -282.989274)
		(width 0.20066)
		(layer "F.Cu")
		(net "M_E_CPU1_SA_DQS_DP<8>")
	)
	(segment
		(start 140.946632 -266.132818)
		(end 140.991844 -266.132818)
		(width 0.088646)
		(layer "F.Cu")
		(net "M_E_CPU1_SA_DQS_DP<8>")
	)
	(segment
		(start 165.340284 -282.734512)
		(end 165.335458 -282.734512)
		(width 0.101854)
		(layer "F.Cu")
		(net "M_E_CPU1_SA_DQS_DP<8>")
	)
	(segment
		(start 149.93239 -281.121104)
		(end 149.984206 -281.121104)
		(width 0.1524)
		(layer "F.Cu")
		(net "M_E_CPU1_SA_DQS_DP<8>")
	)
	(segment
		(start 138.907774 -264.426192)
		(end 139.191746 -264.426192)
		(width 0.088646)
		(layer "F.Cu")
		(net "M_E_CPU1_SA_DQS_DP<8>")
	)
	(segment
		(start 163.757864 -283.417772)
		(end 163.506658 -283.166566)
		(width 0.20066)
		(layer "F.Cu")
		(net "M_E_CPU1_SA_DQS_DP<8>")
	)
	(segment
		(start 168.597834 -282.989274)
		(end 167.944292 -282.989274)
		(width 0.20066)
		(layer "F.Cu")
		(net "M_E_CPU1_SA_DQS_DP<8>")
	)
	(segment
		(start 150.010876 -281.147774)
		(end 152.305258 -283.442156)
		(width 0.20066)
		(layer "F.Cu")
		(net "M_E_CPU1_SA_DQS_DP<8>")
	)
	(segment
		(start 139.191746 -264.426192)
		(end 139.274042 -264.460228)
		(width 0.088646)
		(layer "F.Cu")
		(net "M_E_CPU1_SA_DQS_DP<8>")
	)
	(segment
		(start 160.358582 -282.72105)
		(end 160.656016 -283.018484)
		(width 0.20066)
		(layer "F.Cu")
		(net "M_E_CPU1_SA_DQS_DP<8>")
	)
	(segment
		(start 157.791658 -282.734766)
		(end 157.798262 -282.734766)
		(width 0.101854)
		(layer "F.Cu")
		(net "M_E_CPU1_SA_DQS_DP<8>")
	)
	(segment
		(start 159.823658 -282.72105)
		(end 160.358582 -282.72105)
		(width 0.20066)
		(layer "F.Cu")
		(net "M_E_CPU1_SA_DQS_DP<8>")
	)
	(segment
		(start 153.068528 -283.907738)
		(end 155.088844 -283.907738)
		(width 0.20066)
		(layer "F.Cu")
		(net "M_E_CPU1_SA_DQS_DP<8>")
	)
	(segment
		(start 138.064494 -264.778236)
		(end 138.907774 -264.426192)
		(width 0.088646)
		(layer "F.Cu")
		(net "M_E_CPU1_SA_DQS_DP<8>")
	)
	(segment
		(start 155.072588 -294.43426)
		(end 156.227526 -293.279322)
		(width 0.20066)
		(layer "F.Cu")
		(net "M_E_CPU1_SA_DQS_DP<7>")
	)
	(segment
		(start 167.944292 -292.339268)
		(end 167.68953 -292.084506)
		(width 0.20066)
		(layer "F.Cu")
		(net "M_E_CPU1_SA_DQS_DP<7>")
	)
	(segment
		(start 157.8102 -292.091618)
		(end 159.800036 -292.091618)
		(width 0.1016)
		(layer "F.Cu")
		(net "M_E_CPU1_SA_DQS_DP<7>")
	)
	(segment
		(start 161.92881 -292.767512)
		(end 162.157664 -292.767512)
		(width 0.20066)
		(layer "F.Cu")
		(net "M_E_CPU1_SA_DQS_DP<7>")
	)
	(segment
		(start 137.652506 -269.291562)
		(end 137.67435 -269.269464)
		(width 0.088646)
		(layer "F.Cu")
		(net "M_E_CPU1_SA_DQS_DP<7>")
	)
	(segment
		(start 167.367458 -292.084506)
		(end 167.360092 -292.091872)
		(width 0.1016)
		(layer "F.Cu")
		(net "M_E_CPU1_SA_DQS_DP<7>")
	)
	(segment
		(start 164.76599 -292.342824)
		(end 164.44849 -292.342824)
		(width 0.20066)
		(layer "F.Cu")
		(net "M_E_CPU1_SA_DQS_DP<7>")
	)
	(segment
		(start 157.531816 -292.078156)
		(end 157.791658 -292.078156)
		(width 0.20066)
		(layer "F.Cu")
		(net "M_E_CPU1_SA_DQS_DP<7>")
	)
	(segment
		(start 139.279884 -269.32636)
		(end 139.985242 -270.031718)
		(width 0.088646)
		(layer "F.Cu")
		(net "M_E_CPU1_SA_DQS_DP<7>")
	)
	(segment
		(start 156.580332 -292.75151)
		(end 156.650436 -292.581584)
		(width 0.20066)
		(layer "F.Cu")
		(net "M_E_CPU1_SA_DQS_DP<7>")
	)
	(segment
		(start 156.650436 -292.581584)
		(end 156.924502 -292.307518)
		(width 0.20066)
		(layer "F.Cu")
		(net "M_E_CPU1_SA_DQS_DP<7>")
	)
	(segment
		(start 168.598342 -292.339268)
		(end 167.944292 -292.339268)
		(width 0.20066)
		(layer "F.Cu")
		(net "M_E_CPU1_SA_DQS_DP<7>")
	)
	(segment
		(start 170.457114 -292.516814)
		(end 169.888916 -292.516814)
		(width 0.20066)
		(layer "F.Cu")
		(net "M_E_CPU1_SA_DQS_DP<7>")
	)
	(segment
		(start 145.19656 -280.24582)
		(end 145.19656 -288.533332)
		(width 0.1524)
		(layer "F.Cu")
		(net "M_E_CPU1_SA_DQS_DP<7>")
	)
	(segment
		(start 137.124694 -269.66164)
		(end 137.279888 -269.930626)
		(width 0.088646)
		(layer "F.Cu")
		(net "M_E_CPU1_SA_DQS_DP<7>")
	)
	(segment
		(start 156.924502 -292.307518)
		(end 157.302454 -292.307518)
		(width 0.20066)
		(layer "F.Cu")
		(net "M_E_CPU1_SA_DQS_DP<7>")
	)
	(segment
		(start 140.206222 -270.950182)
		(end 140.334746 -271.143222)
		(width 0.088646)
		(layer "F.Cu")
		(net "M_E_CPU1_SA_DQS_DP<7>")
	)
	(segment
		(start 140.334746 -271.143222)
		(end 140.37564 -271.143222)
		(width 0.088646)
		(layer "F.Cu")
		(net "M_E_CPU1_SA_DQS_DP<7>")
	)
	(segment
		(start 145.366486 -288.650934)
		(end 145.39341 -288.677858)
		(width 0.1524)
		(layer "F.Cu")
		(net "M_E_CPU1_SA_DQS_DP<7>")
	)
	(segment
		(start 140.37564 -271.143222)
		(end 140.391134 -271.158716)
		(width 0.088646)
		(layer "F.Cu")
		(net "M_E_CPU1_SA_DQS_DP<7>")
	)
	(segment
		(start 139.99972 -270.06677)
		(end 140.118084 -270.351504)
		(width 0.088646)
		(layer "F.Cu")
		(net "M_E_CPU1_SA_DQS_DP<7>")
	)
	(segment
		(start 169.223944 -292.784784)
		(end 168.91635 -292.657276)
		(width 0.20066)
		(layer "F.Cu")
		(net "M_E_CPU1_SA_DQS_DP<7>")
	)
	(segment
		(start 169.620946 -292.784784)
		(end 169.223944 -292.784784)
		(width 0.20066)
		(layer "F.Cu")
		(net "M_E_CPU1_SA_DQS_DP<7>")
	)
	(segment
		(start 163.506912 -292.516814)
		(end 162.913314 -292.516814)
		(width 0.20066)
		(layer "F.Cu")
		(net "M_E_CPU1_SA_DQS_DP<7>")
	)
	(segment
		(start 139.99972 -270.066516)
		(end 139.99972 -270.06677)
		(width 0.088646)
		(layer "F.Cu")
		(net "M_E_CPU1_SA_DQS_DP<7>")
	)
	(segment
		(start 159.800036 -292.091618)
		(end 159.821118 -292.070536)
		(width 0.1016)
		(layer "F.Cu")
		(net "M_E_CPU1_SA_DQS_DP<7>")
	)
	(segment
		(start 137.499598 -269.668244)
		(end 137.499598 -269.662148)
		(width 0.088646)
		(layer "F.Cu")
		(net "M_E_CPU1_SA_DQS_DP<7>")
	)
	(segment
		(start 137.360914 -269.952216)
		(end 137.361168 -269.952724)
		(width 0.088646)
		(layer "F.Cu")
		(net "M_E_CPU1_SA_DQS_DP<7>")
	)
	(segment
		(start 162.408362 -292.516814)
		(end 162.913314 -292.516814)
		(width 0.20066)
		(layer "F.Cu")
		(net "M_E_CPU1_SA_DQS_DP<7>")
	)
	(segment
		(start 152.01519 -294.93591)
		(end 152.337262 -295.000172)
		(width 0.20066)
		(layer "F.Cu")
		(net "M_E_CPU1_SA_DQS_DP<7>")
	)
	(segment
		(start 165.347396 -292.091872)
		(end 165.340284 -292.08476)
		(width 0.1016)
		(layer "F.Cu")
		(net "M_E_CPU1_SA_DQS_DP<7>")
	)
	(segment
		(start 165.024054 -292.08476)
		(end 164.76599 -292.342824)
		(width 0.20066)
		(layer "F.Cu")
		(net "M_E_CPU1_SA_DQS_DP<7>")
	)
	(segment
		(start 157.791658 -292.078156)
		(end 157.796738 -292.078156)
		(width 0.101854)
		(layer "F.Cu")
		(net "M_E_CPU1_SA_DQS_DP<7>")
	)
	(segment
		(start 156.227526 -293.279322)
		(end 156.580332 -292.75151)
		(width 0.20066)
		(layer "F.Cu")
		(net "M_E_CPU1_SA_DQS_DP<7>")
	)
	(segment
		(start 159.821118 -292.070536)
		(end 159.823658 -292.070536)
		(width 0.101854)
		(layer "F.Cu")
		(net "M_E_CPU1_SA_DQS_DP<7>")
	)
	(segment
		(start 145.314162 -288.650934)
		(end 145.366486 -288.650934)
		(width 0.1524)
		(layer "F.Cu")
		(net "M_E_CPU1_SA_DQS_DP<7>")
	)
	(segment
		(start 157.302454 -292.307518)
		(end 157.531816 -292.078156)
		(width 0.20066)
		(layer "F.Cu")
		(net "M_E_CPU1_SA_DQS_DP<7>")
	)
	(segment
		(start 152.337262 -295.000172)
		(end 154.011376 -295.000172)
		(width 0.20066)
		(layer "F.Cu")
		(net "M_E_CPU1_SA_DQS_DP<7>")
	)
	(segment
		(start 167.360092 -292.091872)
		(end 165.347396 -292.091872)
		(width 0.1016)
		(layer "F.Cu")
		(net "M_E_CPU1_SA_DQS_DP<7>")
	)
	(segment
		(start 169.888916 -292.516814)
		(end 169.620946 -292.784784)
		(width 0.20066)
		(layer "F.Cu")
		(net "M_E_CPU1_SA_DQS_DP<7>")
	)
	(segment
		(start 137.279888 -269.930626)
		(end 137.360914 -269.952216)
		(width 0.088646)
		(layer "F.Cu")
		(net "M_E_CPU1_SA_DQS_DP<7>")
	)
	(segment
		(start 140.118084 -270.737584)
		(end 140.206222 -270.950182)
		(width 0.088646)
		(layer "F.Cu")
		(net "M_E_CPU1_SA_DQS_DP<7>")
	)
	(segment
		(start 157.796738 -292.078156)
		(end 157.8102 -292.091618)
		(width 0.1016)
		(layer "F.Cu")
		(net "M_E_CPU1_SA_DQS_DP<7>")
	)
	(segment
		(start 160.92805 -292.35273)
		(end 161.92881 -292.767512)
		(width 0.20066)
		(layer "F.Cu")
		(net "M_E_CPU1_SA_DQS_DP<7>")
	)
	(segment
		(start 159.823658 -292.070536)
		(end 160.14827 -292.070536)
		(width 0.20066)
		(layer "F.Cu")
		(net "M_E_CPU1_SA_DQS_DP<7>")
	)
	(segment
		(start 145.39341 -288.677858)
		(end 151.310848 -294.595296)
		(width 0.20066)
		(layer "F.Cu")
		(net "M_E_CPU1_SA_DQS_DP<7>")
	)
	(segment
		(start 138.061192 -269.109444)
		(end 138.165332 -269.109444)
		(width 0.088646)
		(layer "F.Cu")
		(net "M_E_CPU1_SA_DQS_DP<7>")
	)
	(segment
		(start 163.757864 -292.767766)
		(end 163.506912 -292.516814)
		(width 0.20066)
		(layer "F.Cu")
		(net "M_E_CPU1_SA_DQS_DP<7>")
	)
	(segment
		(start 165.340284 -292.08476)
		(end 165.335458 -292.08476)
		(width 0.101854)
		(layer "F.Cu")
		(net "M_E_CPU1_SA_DQS_DP<7>")
	)
	(segment
		(start 160.14827 -292.070536)
		(end 160.430464 -292.35273)
		(width 0.20066)
		(layer "F.Cu")
		(net "M_E_CPU1_SA_DQS_DP<7>")
	)
	(segment
		(start 154.574494 -294.767254)
		(end 155.072588 -294.43426)
		(width 0.20066)
		(layer "F.Cu")
		(net "M_E_CPU1_SA_DQS_DP<7>")
	)
	(segment
		(start 167.68953 -292.084506)
		(end 167.367458 -292.084506)
		(width 0.20066)
		(layer "F.Cu")
		(net "M_E_CPU1_SA_DQS_DP<7>")
	)
	(segment
		(start 165.335458 -292.08476)
		(end 165.024054 -292.08476)
		(width 0.20066)
		(layer "F.Cu")
		(net "M_E_CPU1_SA_DQS_DP<7>")
	)
	(segment
		(start 160.430464 -292.35273)
		(end 160.92805 -292.35273)
		(width 0.20066)
		(layer "F.Cu")
		(net "M_E_CPU1_SA_DQS_DP<7>")
	)
	(segment
		(start 168.91635 -292.657276)
		(end 168.598342 -292.339268)
		(width 0.20066)
		(layer "F.Cu")
		(net "M_E_CPU1_SA_DQS_DP<7>")
	)
	(segment
		(start 164.023548 -292.767766)
		(end 163.757864 -292.767766)
		(width 0.20066)
		(layer "F.Cu")
		(net "M_E_CPU1_SA_DQS_DP<7>")
	)
	(segment
		(start 138.946636 -269.188438)
		(end 139.279884 -269.32636)
		(width 0.088646)
		(layer "F.Cu")
		(net "M_E_CPU1_SA_DQS_DP<7>")
	)
	(segment
		(start 139.985242 -270.031718)
		(end 139.99972 -270.066516)
		(width 0.088646)
		(layer "F.Cu")
		(net "M_E_CPU1_SA_DQS_DP<7>")
	)
	(segment
		(start 140.391134 -271.158716)
		(end 144.123664 -274.891246)
		(width 0.1524)
		(layer "F.Cu")
		(net "M_E_CPU1_SA_DQS_DP<7>")
	)
	(segment
		(start 145.19656 -288.533332)
		(end 145.314162 -288.650934)
		(width 0.1524)
		(layer "F.Cu")
		(net "M_E_CPU1_SA_DQS_DP<7>")
	)
	(segment
		(start 138.48207 -269.188438)
		(end 138.946636 -269.188438)
		(width 0.088646)
		(layer "F.Cu")
		(net "M_E_CPU1_SA_DQS_DP<7>")
	)
	(segment
		(start 162.157664 -292.767512)
		(end 162.408362 -292.516814)
		(width 0.20066)
		(layer "F.Cu")
		(net "M_E_CPU1_SA_DQS_DP<7>")
	)
	(segment
		(start 140.118084 -270.351504)
		(end 140.118084 -270.737584)
		(width 0.088646)
		(layer "F.Cu")
		(net "M_E_CPU1_SA_DQS_DP<7>")
	)
	(segment
		(start 154.011376 -295.000172)
		(end 154.574494 -294.767254)
		(width 0.20066)
		(layer "F.Cu")
		(net "M_E_CPU1_SA_DQS_DP<7>")
	)
	(segment
		(start 164.44849 -292.342824)
		(end 164.023548 -292.767766)
		(width 0.20066)
		(layer "F.Cu")
		(net "M_E_CPU1_SA_DQS_DP<7>")
	)
	(segment
		(start 151.499316 -294.721534)
		(end 152.01519 -294.93591)
		(width 0.20066)
		(layer "F.Cu")
		(net "M_E_CPU1_SA_DQS_DP<7>")
	)
	(segment
		(start 144.123664 -274.891246)
		(end 145.19656 -280.24582)
		(width 0.1524)
		(layer "F.Cu")
		(net "M_E_CPU1_SA_DQS_DP<7>")
	)
	(segment
		(start 151.310848 -294.595296)
		(end 151.499316 -294.721534)
		(width 0.20066)
		(layer "F.Cu")
		(net "M_E_CPU1_SA_DQS_DP<7>")
	)
	(arc
		(start 137.499598 -269.662148)
		(mid 137.499588 -269.658719)
		(end 137.499598 -269.65529)
		(width 0.088646)
		(layer "F.Cu")
		(net "M_E_CPU1_SA_DQS_DP<7>")
	)
	(arc
		(start 138.165332 -269.109444)
		(mid 138.24686 -269.119445)
		(end 138.323574 -269.148814)
		(width 0.088646)
		(layer "F.Cu")
		(net "M_E_CPU1_SA_DQS_DP<7>")
	)
	(arc
		(start 137.67435 -269.269464)
		(mid 137.851823 -269.150907)
		(end 138.061192 -269.109444)
		(width 0.088646)
		(layer "F.Cu")
		(net "M_E_CPU1_SA_DQS_DP<7>")
	)
	(arc
		(start 137.499598 -269.65529)
		(mid 137.540469 -269.458461)
		(end 137.652506 -269.291562)
		(width 0.088646)
		(layer "F.Cu")
		(net "M_E_CPU1_SA_DQS_DP<7>")
	)
	(arc
		(start 138.323574 -269.148814)
		(mid 138.400387 -269.17836)
		(end 138.48207 -269.188438)
		(width 0.088646)
		(layer "F.Cu")
		(net "M_E_CPU1_SA_DQS_DP<7>")
	)
	(arc
		(start 137.361168 -269.952724)
		(mid 137.461888 -269.825806)
		(end 137.499598 -269.668244)
		(width 0.088646)
		(layer "F.Cu")
		(net "M_E_CPU1_SA_DQS_DP<7>")
	)
	(segment
		(start 165.335458 -301.436024)
		(end 165.022784 -301.436024)
		(width 0.20066)
		(layer "F.Cu")
		(net "M_E_CPU1_SA_DQS_DP<6>")
	)
	(segment
		(start 164.487606 -301.692818)
		(end 164.062664 -302.11776)
		(width 0.20066)
		(layer "F.Cu")
		(net "M_E_CPU1_SA_DQS_DP<6>")
	)
	(segment
		(start 167.367458 -301.436786)
		(end 167.362378 -301.441866)
		(width 0.1016)
		(layer "F.Cu")
		(net "M_E_CPU1_SA_DQS_DP<6>")
	)
	(segment
		(start 167.691054 -301.436024)
		(end 167.36822 -301.436024)
		(width 0.20066)
		(layer "F.Cu")
		(net "M_E_CPU1_SA_DQS_DP<6>")
	)
	(segment
		(start 170.457114 -301.866808)
		(end 169.888916 -301.866808)
		(width 0.20066)
		(layer "F.Cu")
		(net "M_E_CPU1_SA_DQS_DP<6>")
	)
	(segment
		(start 165.022784 -301.436024)
		(end 164.76599 -301.692818)
		(width 0.20066)
		(layer "F.Cu")
		(net "M_E_CPU1_SA_DQS_DP<6>")
	)
	(segment
		(start 164.062664 -302.11776)
		(end 163.757864 -302.11776)
		(width 0.20066)
		(layer "F.Cu")
		(net "M_E_CPU1_SA_DQS_DP<6>")
	)
	(segment
		(start 168.818814 -301.689262)
		(end 167.944292 -301.689262)
		(width 0.20066)
		(layer "F.Cu")
		(net "M_E_CPU1_SA_DQS_DP<6>")
	)
	(segment
		(start 167.36822 -301.436024)
		(end 167.367458 -301.436786)
		(width 0.20066)
		(layer "F.Cu")
		(net "M_E_CPU1_SA_DQS_DP<6>")
	)
	(segment
		(start 163.506912 -301.866808)
		(end 162.913314 -301.866808)
		(width 0.20066)
		(layer "F.Cu")
		(net "M_E_CPU1_SA_DQS_DP<6>")
	)
	(segment
		(start 134.775448 -272.639028)
		(end 134.775194 -272.639282)
		(width 0.20066)
		(layer "F.Cu")
		(net "M_E_CPU1_SA_DQS_DP<6>")
	)
	(segment
		(start 165.34003 -301.436786)
		(end 165.339268 -301.436024)
		(width 0.101854)
		(layer "F.Cu")
		(net "M_E_CPU1_SA_DQS_DP<6>")
	)
	(segment
		(start 164.76599 -301.692818)
		(end 164.487606 -301.692818)
		(width 0.20066)
		(layer "F.Cu")
		(net "M_E_CPU1_SA_DQS_DP<6>")
	)
	(segment
		(start 169.888916 -301.866808)
		(end 169.620946 -302.134778)
		(width 0.20066)
		(layer "F.Cu")
		(net "M_E_CPU1_SA_DQS_DP<6>")
	)
	(segment
		(start 162.913314 -301.866808)
		(end 162.91306 -301.866554)
		(width 0.20066)
		(layer "F.Cu")
		(net "M_E_CPU1_SA_DQS_DP<6>")
	)
	(segment
		(start 167.944292 -301.689262)
		(end 167.691054 -301.436024)
		(width 0.20066)
		(layer "F.Cu")
		(net "M_E_CPU1_SA_DQS_DP<6>")
	)
	(segment
		(start 165.340284 -301.436786)
		(end 165.34003 -301.436786)
		(width 0.101854)
		(layer "F.Cu")
		(net "M_E_CPU1_SA_DQS_DP<6>")
	)
	(segment
		(start 162.91306 -301.866554)
		(end 161.783014 -301.866554)
		(width 0.20066)
		(layer "F.Cu")
		(net "M_E_CPU1_SA_DQS_DP<6>")
	)
	(segment
		(start 163.757864 -302.11776)
		(end 163.506912 -301.866808)
		(width 0.20066)
		(layer "F.Cu")
		(net "M_E_CPU1_SA_DQS_DP<6>")
	)
	(segment
		(start 165.339268 -301.436024)
		(end 165.335458 -301.436024)
		(width 0.101854)
		(layer "F.Cu")
		(net "M_E_CPU1_SA_DQS_DP<6>")
	)
	(segment
		(start 165.345364 -301.441866)
		(end 165.340284 -301.436786)
		(width 0.1016)
		(layer "F.Cu")
		(net "M_E_CPU1_SA_DQS_DP<6>")
	)
	(segment
		(start 169.26433 -302.134778)
		(end 168.818814 -301.689262)
		(width 0.20066)
		(layer "F.Cu")
		(net "M_E_CPU1_SA_DQS_DP<6>")
	)
	(segment
		(start 167.362378 -301.441866)
		(end 165.345364 -301.441866)
		(width 0.1016)
		(layer "F.Cu")
		(net "M_E_CPU1_SA_DQS_DP<6>")
	)
	(segment
		(start 134.775448 -272.103342)
		(end 134.775448 -272.639028)
		(width 0.20066)
		(layer "F.Cu")
		(net "M_E_CPU1_SA_DQS_DP<6>")
	)
	(segment
		(start 169.620946 -302.134778)
		(end 169.26433 -302.134778)
		(width 0.20066)
		(layer "F.Cu")
		(net "M_E_CPU1_SA_DQS_DP<6>")
	)
	(segment
		(start 158.202376 -301.687992)
		(end 157.959552 -301.445168)
		(width 0.18288)
		(layer "In2.Cu")
		(net "M_E_CPU1_SA_DQS_DP<6>")
	)
	(segment
		(start 136.387078 -272.140934)
		(end 136.372346 -272.14957)
		(width 0.088646)
		(layer "In2.Cu")
		(net "M_E_CPU1_SA_DQS_DP<6>")
	)
	(segment
		(start 160.480248 -302.298608)
		(end 160.090104 -302.298608)
		(width 0.18288)
		(layer "In2.Cu")
		(net "M_E_CPU1_SA_DQS_DP<6>")
	)
	(segment
		(start 140.900658 -272.84299)
		(end 140.840714 -272.902934)
		(width 0.088646)
		(layer "In2.Cu")
		(net "M_E_CPU1_SA_DQS_DP<6>")
	)
	(segment
		(start 135.929624 -272.200624)
		(end 135.779764 -272.230342)
		(width 0.088646)
		(layer "In2.Cu")
		(net "M_E_CPU1_SA_DQS_DP<6>")
	)
	(segment
		(start 137.326878 -272.140934)
		(end 137.312146 -272.14957)
		(width 0.088646)
		(layer "In2.Cu")
		(net "M_E_CPU1_SA_DQS_DP<6>")
	)
	(segment
		(start 136.179306 -272.200624)
		(end 135.929624 -272.200624)
		(width 0.088646)
		(layer "In2.Cu")
		(net "M_E_CPU1_SA_DQS_DP<6>")
	)
	(segment
		(start 150.326344 -283.223208)
		(end 146.493484 -279.390094)
		(width 0.18288)
		(layer "In2.Cu")
		(net "M_E_CPU1_SA_DQS_DP<6>")
	)
	(segment
		(start 157.0355 -301.656496)
		(end 156.76118 -301.381922)
		(width 0.18288)
		(layer "In2.Cu")
		(net "M_E_CPU1_SA_DQS_DP<6>")
	)
	(segment
		(start 153.663142 -290.130738)
		(end 151.107394 -287.575244)
		(width 0.18288)
		(layer "In2.Cu")
		(net "M_E_CPU1_SA_DQS_DP<6>")
	)
	(segment
		(start 151.107394 -287.575244)
		(end 150.326344 -285.689294)
		(width 0.18288)
		(layer "In2.Cu")
		(net "M_E_CPU1_SA_DQS_DP<6>")
	)
	(segment
		(start 156.123132 -296.070274)
		(end 153.663142 -290.130738)
		(width 0.18288)
		(layer "In2.Cu")
		(net "M_E_CPU1_SA_DQS_DP<6>")
	)
	(segment
		(start 156.76118 -301.381922)
		(end 156.123132 -299.841158)
		(width 0.18288)
		(layer "In2.Cu")
		(net "M_E_CPU1_SA_DQS_DP<6>")
	)
	(segment
		(start 139.525502 -272.200624)
		(end 139.004548 -272.200624)
		(width 0.088646)
		(layer "In2.Cu")
		(net "M_E_CPU1_SA_DQS_DP<6>")
	)
	(segment
		(start 141.638782 -272.84299)
		(end 140.900658 -272.84299)
		(width 0.18288)
		(layer "In2.Cu")
		(net "M_E_CPU1_SA_DQS_DP<6>")
	)
	(segment
		(start 159.933386 -302.233584)
		(end 159.683196 -301.983394)
		(width 0.18288)
		(layer "In2.Cu")
		(net "M_E_CPU1_SA_DQS_DP<6>")
	)
	(segment
		(start 136.371584 -272.150586)
		(end 136.370568 -272.151094)
		(width 0.088646)
		(layer "In2.Cu")
		(net "M_E_CPU1_SA_DQS_DP<6>")
	)
	(segment
		(start 136.372346 -272.14957)
		(end 136.371584 -272.150586)
		(width 0.088646)
		(layer "In2.Cu")
		(net "M_E_CPU1_SA_DQS_DP<6>")
	)
	(segment
		(start 135.527796 -272.314924)
		(end 135.518906 -272.320004)
		(width 0.088646)
		(layer "In2.Cu")
		(net "M_E_CPU1_SA_DQS_DP<6>")
	)
	(segment
		(start 160.090104 -302.298608)
		(end 159.933386 -302.233584)
		(width 0.18288)
		(layer "In2.Cu")
		(net "M_E_CPU1_SA_DQS_DP<6>")
	)
	(segment
		(start 135.344916 -272.582132)
		(end 135.287766 -272.639282)
		(width 0.088646)
		(layer "In2.Cu")
		(net "M_E_CPU1_SA_DQS_DP<6>")
	)
	(segment
		(start 159.683196 -301.983394)
		(end 158.969202 -301.687992)
		(width 0.18288)
		(layer "In2.Cu")
		(net "M_E_CPU1_SA_DQS_DP<6>")
	)
	(segment
		(start 160.86582 -302.138842)
		(end 160.480248 -302.298608)
		(width 0.18288)
		(layer "In2.Cu")
		(net "M_E_CPU1_SA_DQS_DP<6>")
	)
	(segment
		(start 135.779764 -272.230342)
		(end 135.72109 -272.242026)
		(width 0.088646)
		(layer "In2.Cu")
		(net "M_E_CPU1_SA_DQS_DP<6>")
	)
	(segment
		(start 156.123132 -299.841158)
		(end 156.123132 -296.070274)
		(width 0.18288)
		(layer "In2.Cu")
		(net "M_E_CPU1_SA_DQS_DP<6>")
	)
	(segment
		(start 150.326344 -285.689294)
		(end 150.326344 -283.223208)
		(width 0.18288)
		(layer "In2.Cu")
		(net "M_E_CPU1_SA_DQS_DP<6>")
	)
	(segment
		(start 145.296636 -276.500844)
		(end 141.638782 -272.84299)
		(width 0.18288)
		(layer "In2.Cu")
		(net "M_E_CPU1_SA_DQS_DP<6>")
	)
	(segment
		(start 136.36879 -272.15211)
		(end 136.3599 -272.157444)
		(width 0.088646)
		(layer "In2.Cu")
		(net "M_E_CPU1_SA_DQS_DP<6>")
	)
	(segment
		(start 138.266678 -272.140934)
		(end 138.251946 -272.14957)
		(width 0.088646)
		(layer "In2.Cu")
		(net "M_E_CPU1_SA_DQS_DP<6>")
	)
	(segment
		(start 136.370568 -272.151094)
		(end 136.36879 -272.15211)
		(width 0.088646)
		(layer "In2.Cu")
		(net "M_E_CPU1_SA_DQS_DP<6>")
	)
	(segment
		(start 157.215586 -301.656496)
		(end 157.0355 -301.656496)
		(width 0.18288)
		(layer "In2.Cu")
		(net "M_E_CPU1_SA_DQS_DP<6>")
	)
	(segment
		(start 157.959552 -301.445168)
		(end 157.426914 -301.445168)
		(width 0.18288)
		(layer "In2.Cu")
		(net "M_E_CPU1_SA_DQS_DP<6>")
	)
	(segment
		(start 140.227812 -272.902934)
		(end 139.525502 -272.200624)
		(width 0.088646)
		(layer "In2.Cu")
		(net "M_E_CPU1_SA_DQS_DP<6>")
	)
	(segment
		(start 135.287766 -272.639282)
		(end 134.775194 -272.639282)
		(width 0.088646)
		(layer "In2.Cu")
		(net "M_E_CPU1_SA_DQS_DP<6>")
	)
	(segment
		(start 140.840714 -272.902934)
		(end 140.227812 -272.902934)
		(width 0.088646)
		(layer "In2.Cu")
		(net "M_E_CPU1_SA_DQS_DP<6>")
	)
	(segment
		(start 161.510472 -302.138842)
		(end 160.86582 -302.138842)
		(width 0.18288)
		(layer "In2.Cu")
		(net "M_E_CPU1_SA_DQS_DP<6>")
	)
	(segment
		(start 158.969202 -301.687992)
		(end 158.202376 -301.687992)
		(width 0.18288)
		(layer "In2.Cu")
		(net "M_E_CPU1_SA_DQS_DP<6>")
	)
	(segment
		(start 157.426914 -301.445168)
		(end 157.215586 -301.656496)
		(width 0.18288)
		(layer "In2.Cu")
		(net "M_E_CPU1_SA_DQS_DP<6>")
	)
	(segment
		(start 161.783014 -301.866554)
		(end 161.510472 -302.138842)
		(width 0.18288)
		(layer "In2.Cu")
		(net "M_E_CPU1_SA_DQS_DP<6>")
	)
	(segment
		(start 146.493484 -279.390094)
		(end 145.296636 -276.500844)
		(width 0.18288)
		(layer "In2.Cu")
		(net "M_E_CPU1_SA_DQS_DP<6>")
	)
	(arc
		(start 138.81735 -272.14957)
		(mid 138.543121 -272.073645)
		(end 138.266678 -272.140934)
		(width 0.088646)
		(layer "In2.Cu")
		(net "M_E_CPU1_SA_DQS_DP<6>")
	)
	(arc
		(start 135.72109 -272.242026)
		(mid 135.672976 -272.248382)
		(end 135.628126 -272.266918)
		(width 0.088646)
		(layer "In2.Cu")
		(net "M_E_CPU1_SA_DQS_DP<6>")
	)
	(arc
		(start 139.004548 -272.200624)
		(mid 138.907598 -272.187395)
		(end 138.81735 -272.14957)
		(width 0.088646)
		(layer "In2.Cu")
		(net "M_E_CPU1_SA_DQS_DP<6>")
	)
	(arc
		(start 137.87755 -272.14957)
		(mid 137.603321 -272.073645)
		(end 137.326878 -272.140934)
		(width 0.088646)
		(layer "In2.Cu")
		(net "M_E_CPU1_SA_DQS_DP<6>")
	)
	(arc
		(start 136.93775 -272.14957)
		(mid 136.663521 -272.073645)
		(end 136.387078 -272.140934)
		(width 0.088646)
		(layer "In2.Cu")
		(net "M_E_CPU1_SA_DQS_DP<6>")
	)
	(arc
		(start 138.251946 -272.14957)
		(mid 138.064748 -272.199713)
		(end 137.87755 -272.14957)
		(width 0.088646)
		(layer "In2.Cu")
		(net "M_E_CPU1_SA_DQS_DP<6>")
	)
	(arc
		(start 137.312146 -272.14957)
		(mid 137.124948 -272.199713)
		(end 136.93775 -272.14957)
		(width 0.088646)
		(layer "In2.Cu")
		(net "M_E_CPU1_SA_DQS_DP<6>")
	)
	(arc
		(start 136.3599 -272.157444)
		(mid 136.272311 -272.190341)
		(end 136.179306 -272.200624)
		(width 0.088646)
		(layer "In2.Cu")
		(net "M_E_CPU1_SA_DQS_DP<6>")
	)
	(arc
		(start 135.628126 -272.266918)
		(mid 135.603421 -272.279785)
		(end 135.577834 -272.290794)
		(width 0.088646)
		(layer "In2.Cu")
		(net "M_E_CPU1_SA_DQS_DP<6>")
	)
	(arc
		(start 135.577834 -272.290794)
		(mid 135.552365 -272.301927)
		(end 135.527796 -272.314924)
		(width 0.088646)
		(layer "In2.Cu")
		(net "M_E_CPU1_SA_DQS_DP<6>")
	)
	(arc
		(start 135.518906 -272.320004)
		(mid 135.403097 -272.431933)
		(end 135.344916 -272.582132)
		(width 0.088646)
		(layer "In2.Cu")
		(net "M_E_CPU1_SA_DQS_DP<6>")
	)
	(segment
		(start 168.812718 -311.229248)
		(end 168.353994 -311.039256)
		(width 0.20066)
		(layer "F.Cu")
		(net "M_E_CPU1_SA_DQS_DP<5>")
	)
	(segment
		(start 169.215562 -311.484772)
		(end 168.963848 -311.380378)
		(width 0.20066)
		(layer "F.Cu")
		(net "M_E_CPU1_SA_DQS_DP<5>")
	)
	(segment
		(start 169.690034 -311.484772)
		(end 169.215562 -311.484772)
		(width 0.20066)
		(layer "F.Cu")
		(net "M_E_CPU1_SA_DQS_DP<5>")
	)
	(segment
		(start 168.963848 -311.380378)
		(end 168.812718 -311.229248)
		(width 0.20066)
		(layer "F.Cu")
		(net "M_E_CPU1_SA_DQS_DP<5>")
	)
	(segment
		(start 150.32609 -304.434494)
		(end 150.326344 -304.610516)
		(width 0.20066)
		(layer "F.Cu")
		(net "M_E_CPU1_SA_DQS_DP<5>")
	)
	(segment
		(start 138.76274 -275.837904)
		(end 138.76274 -275.838158)
		(width 0.088646)
		(layer "F.Cu")
		(net "M_E_CPU1_SA_DQS_DP<5>")
	)
	(segment
		(start 142.244318 -295.972484)
		(end 142.271496 -295.999662)
		(width 0.1524)
		(layer "F.Cu")
		(net "M_E_CPU1_SA_DQS_DP<5>")
	)
	(segment
		(start 140.54328 -277.078694)
		(end 141.240256 -280.561034)
		(width 0.1524)
		(layer "F.Cu")
		(net "M_E_CPU1_SA_DQS_DP<5>")
	)
	(segment
		(start 141.240256 -280.561034)
		(end 141.240256 -291.250624)
		(width 0.1524)
		(layer "F.Cu")
		(net "M_E_CPU1_SA_DQS_DP<5>")
	)
	(segment
		(start 163.431728 -311.216802)
		(end 162.913314 -311.216802)
		(width 0.20066)
		(layer "F.Cu")
		(net "M_E_CPU1_SA_DQS_DP<5>")
	)
	(segment
		(start 139.999466 -276.53488)
		(end 140.01496 -276.550374)
		(width 0.088646)
		(layer "F.Cu")
		(net "M_E_CPU1_SA_DQS_DP<5>")
	)
	(segment
		(start 164.611304 -311.01665)
		(end 164.26942 -311.01665)
		(width 0.20066)
		(layer "F.Cu")
		(net "M_E_CPU1_SA_DQS_DP<5>")
	)
	(segment
		(start 159.12592 -310.791606)
		(end 159.52597 -310.791606)
		(width 0.101854)
		(layer "F.Cu")
		(net "M_E_CPU1_SA_DQS_DP<5>")
	)
	(segment
		(start 148.69541 -302.982376)
		(end 148.871432 -302.982376)
		(width 0.20066)
		(layer "F.Cu")
		(net "M_E_CPU1_SA_DQS_DP<5>")
	)
	(segment
		(start 141.27353 -291.562536)
		(end 141.910816 -295.344596)
		(width 0.1524)
		(layer "F.Cu")
		(net "M_E_CPU1_SA_DQS_DP<5>")
	)
	(segment
		(start 150.326344 -304.610516)
		(end 155.12161 -309.3974)
		(width 0.20066)
		(layer "F.Cu")
		(net "M_E_CPU1_SA_DQS_DP<5>")
	)
	(segment
		(start 169.958004 -311.216802)
		(end 169.690034 -311.484772)
		(width 0.20066)
		(layer "F.Cu")
		(net "M_E_CPU1_SA_DQS_DP<5>")
	)
	(segment
		(start 165.36543 -310.780938)
		(end 165.359842 -310.786526)
		(width 0.101854)
		(layer "F.Cu")
		(net "M_E_CPU1_SA_DQS_DP<5>")
	)
	(segment
		(start 165.381432 -310.79186)
		(end 165.37051 -310.780938)
		(width 0.1016)
		(layer "F.Cu")
		(net "M_E_CPU1_SA_DQS_DP<5>")
	)
	(segment
		(start 138.236452 -275.639784)
		(end 138.76274 -275.837904)
		(width 0.088646)
		(layer "F.Cu")
		(net "M_E_CPU1_SA_DQS_DP<5>")
	)
	(segment
		(start 163.68268 -311.467754)
		(end 163.431728 -311.216802)
		(width 0.20066)
		(layer "F.Cu")
		(net "M_E_CPU1_SA_DQS_DP<5>")
	)
	(segment
		(start 137.594594 -275.35886)
		(end 138.057128 -275.601176)
		(width 0.088646)
		(layer "F.Cu")
		(net "M_E_CPU1_SA_DQS_DP<5>")
	)
	(segment
		(start 149.297898 -303.407826)
		(end 149.297898 -303.583848)
		(width 0.20066)
		(layer "F.Cu")
		(net "M_E_CPU1_SA_DQS_DP<5>")
	)
	(segment
		(start 142.192502 -295.972484)
		(end 142.244318 -295.972484)
		(width 0.1524)
		(layer "F.Cu")
		(net "M_E_CPU1_SA_DQS_DP<5>")
	)
	(segment
		(start 147.666964 -301.955708)
		(end 147.842986 -301.955708)
		(width 0.20066)
		(layer "F.Cu")
		(net "M_E_CPU1_SA_DQS_DP<5>")
	)
	(segment
		(start 165.335458 -310.786526)
		(end 164.841428 -310.786526)
		(width 0.20066)
		(layer "F.Cu")
		(net "M_E_CPU1_SA_DQS_DP<5>")
	)
	(segment
		(start 167.360854 -310.79186)
		(end 165.381432 -310.79186)
		(width 0.1016)
		(layer "F.Cu")
		(net "M_E_CPU1_SA_DQS_DP<5>")
	)
	(segment
		(start 139.953746 -276.53488)
		(end 139.999466 -276.53488)
		(width 0.088646)
		(layer "F.Cu")
		(net "M_E_CPU1_SA_DQS_DP<5>")
	)
	(segment
		(start 140.01496 -276.550374)
		(end 140.54328 -277.078694)
		(width 0.1524)
		(layer "F.Cu")
		(net "M_E_CPU1_SA_DQS_DP<5>")
	)
	(segment
		(start 157.13456 -311.040272)
		(end 157.271212 -311.040272)
		(width 0.20066)
		(layer "F.Cu")
		(net "M_E_CPU1_SA_DQS_DP<5>")
	)
	(segment
		(start 141.240256 -291.250624)
		(end 141.27353 -291.562536)
		(width 0.1524)
		(layer "F.Cu")
		(net "M_E_CPU1_SA_DQS_DP<5>")
	)
	(segment
		(start 159.52597 -310.791606)
		(end 159.81426 -310.791606)
		(width 0.1016)
		(layer "F.Cu")
		(net "M_E_CPU1_SA_DQS_DP<5>")
	)
	(segment
		(start 160.622234 -311.088532)
		(end 161.984944 -311.502298)
		(width 0.20066)
		(layer "F.Cu")
		(net "M_E_CPU1_SA_DQS_DP<5>")
	)
	(segment
		(start 170.457114 -311.216802)
		(end 169.958004 -311.216802)
		(width 0.20066)
		(layer "F.Cu")
		(net "M_E_CPU1_SA_DQS_DP<5>")
	)
	(segment
		(start 164.26942 -311.01665)
		(end 163.818316 -311.467754)
		(width 0.20066)
		(layer "F.Cu")
		(net "M_E_CPU1_SA_DQS_DP<5>")
	)
	(segment
		(start 138.76528 -275.839174)
		(end 138.765026 -275.83892)
		(width 0.088646)
		(layer "F.Cu")
		(net "M_E_CPU1_SA_DQS_DP<5>")
	)
	(segment
		(start 155.55087 -309.785766)
		(end 156.584904 -310.63311)
		(width 0.20066)
		(layer "F.Cu")
		(net "M_E_CPU1_SA_DQS_DP<5>")
	)
	(segment
		(start 138.76909 -275.840698)
		(end 139.156186 -276.001226)
		(width 0.088646)
		(layer "F.Cu")
		(net "M_E_CPU1_SA_DQS_DP<5>")
	)
	(segment
		(start 157.271212 -311.040272)
		(end 157.524958 -310.786526)
		(width 0.20066)
		(layer "F.Cu")
		(net "M_E_CPU1_SA_DQS_DP<5>")
	)
	(segment
		(start 145.610072 -299.902626)
		(end 145.786094 -299.902626)
		(width 0.20066)
		(layer "F.Cu")
		(net "M_E_CPU1_SA_DQS_DP<5>")
	)
	(segment
		(start 146.21256 -300.328076)
		(end 146.21256 -300.504098)
		(width 0.20066)
		(layer "F.Cu")
		(net "M_E_CPU1_SA_DQS_DP<5>")
	)
	(segment
		(start 148.269452 -302.55718)
		(end 148.69541 -302.982376)
		(width 0.20066)
		(layer "F.Cu")
		(net "M_E_CPU1_SA_DQS_DP<5>")
	)
	(segment
		(start 142.271496 -295.999662)
		(end 142.667228 -296.395394)
		(width 0.20066)
		(layer "F.Cu")
		(net "M_E_CPU1_SA_DQS_DP<5>")
	)
	(segment
		(start 168.353994 -311.039256)
		(end 168.106852 -311.039256)
		(width 0.20066)
		(layer "F.Cu")
		(net "M_E_CPU1_SA_DQS_DP<5>")
	)
	(segment
		(start 145.786094 -299.902626)
		(end 146.21256 -300.328076)
		(width 0.20066)
		(layer "F.Cu")
		(net "M_E_CPU1_SA_DQS_DP<5>")
	)
	(segment
		(start 155.12161 -309.3974)
		(end 155.55087 -309.785766)
		(width 0.20066)
		(layer "F.Cu")
		(net "M_E_CPU1_SA_DQS_DP<5>")
	)
	(segment
		(start 146.81454 -300.92904)
		(end 147.241006 -301.35449)
		(width 0.20066)
		(layer "F.Cu")
		(net "M_E_CPU1_SA_DQS_DP<5>")
	)
	(segment
		(start 138.057128 -275.601176)
		(end 138.085322 -275.608796)
		(width 0.088646)
		(layer "F.Cu")
		(net "M_E_CPU1_SA_DQS_DP<5>")
	)
	(segment
		(start 167.367458 -310.785256)
		(end 167.360854 -310.79186)
		(width 0.1016)
		(layer "F.Cu")
		(net "M_E_CPU1_SA_DQS_DP<5>")
	)
	(segment
		(start 148.269452 -302.381158)
		(end 148.269452 -302.55718)
		(width 0.20066)
		(layer "F.Cu")
		(net "M_E_CPU1_SA_DQS_DP<5>")
	)
	(segment
		(start 149.723856 -304.009044)
		(end 149.899878 -304.00879)
		(width 0.20066)
		(layer "F.Cu")
		(net "M_E_CPU1_SA_DQS_DP<5>")
	)
	(segment
		(start 157.801818 -310.791606)
		(end 159.12592 -310.791606)
		(width 0.1016)
		(layer "F.Cu")
		(net "M_E_CPU1_SA_DQS_DP<5>")
	)
	(segment
		(start 159.819594 -310.786272)
		(end 159.823658 -310.786272)
		(width 0.1016)
		(layer "F.Cu")
		(net "M_E_CPU1_SA_DQS_DP<5>")
	)
	(segment
		(start 157.524958 -310.786526)
		(end 157.791658 -310.786526)
		(width 0.20066)
		(layer "F.Cu")
		(net "M_E_CPU1_SA_DQS_DP<5>")
	)
	(segment
		(start 163.818316 -311.467754)
		(end 163.68268 -311.467754)
		(width 0.20066)
		(layer "F.Cu")
		(net "M_E_CPU1_SA_DQS_DP<5>")
	)
	(segment
		(start 168.106852 -311.039256)
		(end 167.852852 -310.785256)
		(width 0.20066)
		(layer "F.Cu")
		(net "M_E_CPU1_SA_DQS_DP<5>")
	)
	(segment
		(start 156.584904 -310.63311)
		(end 157.13456 -311.040272)
		(width 0.20066)
		(layer "F.Cu")
		(net "M_E_CPU1_SA_DQS_DP<5>")
	)
	(segment
		(start 161.984944 -311.502298)
		(end 162.10915 -311.502298)
		(width 0.20066)
		(layer "F.Cu")
		(net "M_E_CPU1_SA_DQS_DP<5>")
	)
	(segment
		(start 149.899878 -304.00879)
		(end 150.32609 -304.434494)
		(width 0.20066)
		(layer "F.Cu")
		(net "M_E_CPU1_SA_DQS_DP<5>")
	)
	(segment
		(start 145.265648 -299.55871)
		(end 145.610072 -299.902626)
		(width 0.20066)
		(layer "F.Cu")
		(net "M_E_CPU1_SA_DQS_DP<5>")
	)
	(segment
		(start 160.425638 -311.088532)
		(end 160.622234 -311.088532)
		(width 0.20066)
		(layer "F.Cu")
		(net "M_E_CPU1_SA_DQS_DP<5>")
	)
	(segment
		(start 149.297898 -303.583848)
		(end 149.723856 -304.009044)
		(width 0.20066)
		(layer "F.Cu")
		(net "M_E_CPU1_SA_DQS_DP<5>")
	)
	(segment
		(start 146.21256 -300.504098)
		(end 146.638518 -300.929294)
		(width 0.20066)
		(layer "F.Cu")
		(net "M_E_CPU1_SA_DQS_DP<5>")
	)
	(segment
		(start 159.823658 -310.786272)
		(end 160.123378 -310.786272)
		(width 0.20066)
		(layer "F.Cu")
		(net "M_E_CPU1_SA_DQS_DP<5>")
	)
	(segment
		(start 142.108428 -295.888156)
		(end 142.192502 -295.972484)
		(width 0.1524)
		(layer "F.Cu")
		(net "M_E_CPU1_SA_DQS_DP<5>")
	)
	(segment
		(start 165.37051 -310.780938)
		(end 165.36543 -310.780938)
		(width 0.1016)
		(layer "F.Cu")
		(net "M_E_CPU1_SA_DQS_DP<5>")
	)
	(segment
		(start 167.852852 -310.785256)
		(end 167.367458 -310.785256)
		(width 0.20066)
		(layer "F.Cu")
		(net "M_E_CPU1_SA_DQS_DP<5>")
	)
	(segment
		(start 164.841428 -310.786526)
		(end 164.611304 -311.01665)
		(width 0.20066)
		(layer "F.Cu")
		(net "M_E_CPU1_SA_DQS_DP<5>")
	)
	(segment
		(start 139.156186 -276.001226)
		(end 139.723368 -276.304502)
		(width 0.088646)
		(layer "F.Cu")
		(net "M_E_CPU1_SA_DQS_DP<5>")
	)
	(segment
		(start 142.667228 -296.395394)
		(end 145.265648 -299.55871)
		(width 0.20066)
		(layer "F.Cu")
		(net "M_E_CPU1_SA_DQS_DP<5>")
	)
	(segment
		(start 162.10915 -311.502298)
		(end 162.394646 -311.216802)
		(width 0.20066)
		(layer "F.Cu")
		(net "M_E_CPU1_SA_DQS_DP<5>")
	)
	(segment
		(start 148.871432 -302.982376)
		(end 149.297898 -303.407826)
		(width 0.20066)
		(layer "F.Cu")
		(net "M_E_CPU1_SA_DQS_DP<5>")
	)
	(segment
		(start 157.791658 -310.786526)
		(end 157.796738 -310.786526)
		(width 0.101854)
		(layer "F.Cu")
		(net "M_E_CPU1_SA_DQS_DP<5>")
	)
	(segment
		(start 139.723368 -276.304502)
		(end 139.953746 -276.53488)
		(width 0.088646)
		(layer "F.Cu")
		(net "M_E_CPU1_SA_DQS_DP<5>")
	)
	(segment
		(start 146.638518 -300.929294)
		(end 146.81454 -300.92904)
		(width 0.20066)
		(layer "F.Cu")
		(net "M_E_CPU1_SA_DQS_DP<5>")
	)
	(segment
		(start 159.81426 -310.791606)
		(end 159.819594 -310.786272)
		(width 0.1016)
		(layer "F.Cu")
		(net "M_E_CPU1_SA_DQS_DP<5>")
	)
	(segment
		(start 141.910816 -295.344596)
		(end 142.108428 -295.888156)
		(width 0.1524)
		(layer "F.Cu")
		(net "M_E_CPU1_SA_DQS_DP<5>")
	)
	(segment
		(start 147.241006 -301.35449)
		(end 147.241006 -301.530512)
		(width 0.20066)
		(layer "F.Cu")
		(net "M_E_CPU1_SA_DQS_DP<5>")
	)
	(segment
		(start 138.765026 -275.83892)
		(end 138.76909 -275.840698)
		(width 0.088646)
		(layer "F.Cu")
		(net "M_E_CPU1_SA_DQS_DP<5>")
	)
	(segment
		(start 138.76274 -275.838158)
		(end 138.76528 -275.839174)
		(width 0.088646)
		(layer "F.Cu")
		(net "M_E_CPU1_SA_DQS_DP<5>")
	)
	(segment
		(start 160.123378 -310.786272)
		(end 160.425638 -311.088532)
		(width 0.20066)
		(layer "F.Cu")
		(net "M_E_CPU1_SA_DQS_DP<5>")
	)
	(segment
		(start 157.796738 -310.786526)
		(end 157.801818 -310.791606)
		(width 0.1016)
		(layer "F.Cu")
		(net "M_E_CPU1_SA_DQS_DP<5>")
	)
	(segment
		(start 162.394646 -311.216802)
		(end 162.913314 -311.216802)
		(width 0.20066)
		(layer "F.Cu")
		(net "M_E_CPU1_SA_DQS_DP<5>")
	)
	(segment
		(start 147.241006 -301.530512)
		(end 147.666964 -301.955708)
		(width 0.20066)
		(layer "F.Cu")
		(net "M_E_CPU1_SA_DQS_DP<5>")
	)
	(segment
		(start 165.359842 -310.786526)
		(end 165.335458 -310.786526)
		(width 0.101854)
		(layer "F.Cu")
		(net "M_E_CPU1_SA_DQS_DP<5>")
	)
	(segment
		(start 147.842986 -301.955708)
		(end 148.269452 -302.381158)
		(width 0.20066)
		(layer "F.Cu")
		(net "M_E_CPU1_SA_DQS_DP<5>")
	)
	(arc
		(start 138.085322 -275.608796)
		(mid 138.162108 -275.61834)
		(end 138.236452 -275.639784)
		(width 0.088646)
		(layer "F.Cu")
		(net "M_E_CPU1_SA_DQS_DP<5>")
	)
	(segment
		(start 161.907728 -275.94179)
		(end 161.545016 -275.94179)
		(width 0.101854)
		(layer "F.Cu")
		(net "M_E_CPU1_SA_DQS_DP<4>")
	)
	(segment
		(start 161.291778 -275.952966)
		(end 161.011108 -275.672296)
		(width 0.20066)
		(layer "F.Cu")
		(net "M_E_CPU1_SA_DQS_DP<4>")
	)
	(segment
		(start 139.708128 -260.558534)
		(end 139.778232 -260.593078)
		(width 0.088646)
		(layer "F.Cu")
		(net "M_E_CPU1_SA_DQS_DP<4>")
	)
	(segment
		(start 164.549582 -275.645372)
		(end 164.23259 -275.962364)
		(width 0.20066)
		(layer "F.Cu")
		(net "M_E_CPU1_SA_DQS_DP<4>")
	)
	(segment
		(start 156.388816 -275.141944)
		(end 156.562806 -275.315934)
		(width 0.20066)
		(layer "F.Cu")
		(net "M_E_CPU1_SA_DQS_DP<4>")
	)
	(segment
		(start 152.317958 -275.141944)
		(end 152.356058 -275.141944)
		(width 0.1524)
		(layer "F.Cu")
		(net "M_E_CPU1_SA_DQS_DP<4>")
	)
	(segment
		(start 159.643064 -275.276056)
		(end 159.402526 -275.516594)
		(width 0.20066)
		(layer "F.Cu")
		(net "M_E_CPU1_SA_DQS_DP<4>")
	)
	(segment
		(start 164.077396 -275.962364)
		(end 164.056822 -275.94179)
		(width 0.101854)
		(layer "F.Cu")
		(net "M_E_CPU1_SA_DQS_DP<4>")
	)
	(segment
		(start 151.325834 -274.794726)
		(end 151.636222 -275.105114)
		(width 0.1524)
		(layer "F.Cu")
		(net "M_E_CPU1_SA_DQS_DP<4>")
	)
	(segment
		(start 138.99007 -260.459982)
		(end 139.708128 -260.558534)
		(width 0.088646)
		(layer "F.Cu")
		(net "M_E_CPU1_SA_DQS_DP<4>")
	)
	(segment
		(start 160.147762 -275.276056)
		(end 159.643064 -275.276056)
		(width 0.20066)
		(layer "F.Cu")
		(net "M_E_CPU1_SA_DQS_DP<4>")
	)
	(segment
		(start 156.863034 -275.440394)
		(end 157.04693 -275.516594)
		(width 0.20066)
		(layer "F.Cu")
		(net "M_E_CPU1_SA_DQS_DP<4>")
	)
	(segment
		(start 150.637494 -271.497298)
		(end 151.22652 -274.440396)
		(width 0.1524)
		(layer "F.Cu")
		(net "M_E_CPU1_SA_DQS_DP<4>")
	)
	(segment
		(start 159.402526 -275.516594)
		(end 158.813246 -275.516594)
		(width 0.20066)
		(layer "F.Cu")
		(net "M_E_CPU1_SA_DQS_DP<4>")
	)
	(segment
		(start 164.23259 -275.962364)
		(end 164.077396 -275.962364)
		(width 0.20066)
		(layer "F.Cu")
		(net "M_E_CPU1_SA_DQS_DP<4>")
	)
	(segment
		(start 166.357046 -275.516594)
		(end 165.794182 -275.516594)
		(width 0.20066)
		(layer "F.Cu")
		(net "M_E_CPU1_SA_DQS_DP<4>")
	)
	(segment
		(start 152.281128 -275.105114)
		(end 152.317958 -275.141944)
		(width 0.1524)
		(layer "F.Cu")
		(net "M_E_CPU1_SA_DQS_DP<4>")
	)
	(segment
		(start 137.782808 -260.384798)
		(end 137.781792 -260.384544)
		(width 0.088646)
		(layer "F.Cu")
		(net "M_E_CPU1_SA_DQS_DP<4>")
	)
	(segment
		(start 152.356058 -275.141944)
		(end 156.388816 -275.141944)
		(width 0.20066)
		(layer "F.Cu")
		(net "M_E_CPU1_SA_DQS_DP<4>")
	)
	(segment
		(start 161.53384 -275.952966)
		(end 161.291778 -275.952966)
		(width 0.20066)
		(layer "F.Cu")
		(net "M_E_CPU1_SA_DQS_DP<4>")
	)
	(segment
		(start 139.778232 -260.593078)
		(end 140.993368 -261.80796)
		(width 0.088646)
		(layer "F.Cu")
		(net "M_E_CPU1_SA_DQS_DP<4>")
	)
	(segment
		(start 140.993368 -261.80796)
		(end 140.993368 -261.853172)
		(width 0.088646)
		(layer "F.Cu")
		(net "M_E_CPU1_SA_DQS_DP<4>")
	)
	(segment
		(start 157.04693 -275.516594)
		(end 158.813246 -275.516594)
		(width 0.20066)
		(layer "F.Cu")
		(net "M_E_CPU1_SA_DQS_DP<4>")
	)
	(segment
		(start 163.864544 -275.94179)
		(end 161.907728 -275.94179)
		(width 0.1016)
		(layer "F.Cu")
		(net "M_E_CPU1_SA_DQS_DP<4>")
	)
	(segment
		(start 165.794182 -275.516594)
		(end 165.519608 -275.24202)
		(width 0.20066)
		(layer "F.Cu")
		(net "M_E_CPU1_SA_DQS_DP<4>")
	)
	(segment
		(start 165.32352 -275.24202)
		(end 164.920168 -275.645372)
		(width 0.20066)
		(layer "F.Cu")
		(net "M_E_CPU1_SA_DQS_DP<4>")
	)
	(segment
		(start 156.562806 -275.315934)
		(end 156.863034 -275.440394)
		(width 0.20066)
		(layer "F.Cu")
		(net "M_E_CPU1_SA_DQS_DP<4>")
	)
	(segment
		(start 137.639298 -260.301994)
		(end 137.782808 -260.384798)
		(width 0.088646)
		(layer "F.Cu")
		(net "M_E_CPU1_SA_DQS_DP<4>")
	)
	(segment
		(start 161.545016 -275.94179)
		(end 161.53384 -275.952966)
		(width 0.101854)
		(layer "F.Cu")
		(net "M_E_CPU1_SA_DQS_DP<4>")
	)
	(segment
		(start 151.636222 -275.105114)
		(end 152.281128 -275.105114)
		(width 0.1524)
		(layer "F.Cu")
		(net "M_E_CPU1_SA_DQS_DP<4>")
	)
	(segment
		(start 137.129266 -260.282436)
		(end 137.339832 -260.282436)
		(width 0.088646)
		(layer "F.Cu")
		(net "M_E_CPU1_SA_DQS_DP<4>")
	)
	(segment
		(start 164.056822 -275.94179)
		(end 163.864544 -275.94179)
		(width 0.101854)
		(layer "F.Cu")
		(net "M_E_CPU1_SA_DQS_DP<4>")
	)
	(segment
		(start 161.011108 -275.672296)
		(end 160.544002 -275.672296)
		(width 0.20066)
		(layer "F.Cu")
		(net "M_E_CPU1_SA_DQS_DP<4>")
	)
	(segment
		(start 165.519608 -275.24202)
		(end 165.32352 -275.24202)
		(width 0.20066)
		(layer "F.Cu")
		(net "M_E_CPU1_SA_DQS_DP<4>")
	)
	(segment
		(start 140.993368 -261.853172)
		(end 150.637494 -271.497298)
		(width 0.1524)
		(layer "F.Cu")
		(net "M_E_CPU1_SA_DQS_DP<4>")
	)
	(segment
		(start 151.22652 -274.440396)
		(end 151.325834 -274.794726)
		(width 0.1524)
		(layer "F.Cu")
		(net "M_E_CPU1_SA_DQS_DP<4>")
	)
	(segment
		(start 164.920168 -275.645372)
		(end 164.549582 -275.645372)
		(width 0.20066)
		(layer "F.Cu")
		(net "M_E_CPU1_SA_DQS_DP<4>")
	)
	(segment
		(start 137.781792 -260.384544)
		(end 137.792206 -260.39064)
		(width 0.088646)
		(layer "F.Cu")
		(net "M_E_CPU1_SA_DQS_DP<4>")
	)
	(segment
		(start 160.544002 -275.672296)
		(end 160.147762 -275.276056)
		(width 0.20066)
		(layer "F.Cu")
		(net "M_E_CPU1_SA_DQS_DP<4>")
	)
	(segment
		(start 136.184894 -259.894832)
		(end 137.042906 -260.264656)
		(width 0.088646)
		(layer "F.Cu")
		(net "M_E_CPU1_SA_DQS_DP<4>")
	)
	(arc
		(start 137.437368 -260.27126)
		(mid 137.541231 -260.267558)
		(end 137.639298 -260.301994)
		(width 0.088646)
		(layer "F.Cu")
		(net "M_E_CPU1_SA_DQS_DP<4>")
	)
	(arc
		(start 137.339832 -260.282436)
		(mid 137.388914 -260.279582)
		(end 137.437368 -260.27126)
		(width 0.088646)
		(layer "F.Cu")
		(net "M_E_CPU1_SA_DQS_DP<4>")
	)
	(arc
		(start 137.042906 -260.264656)
		(mid 137.08518 -260.277937)
		(end 137.129266 -260.282436)
		(width 0.088646)
		(layer "F.Cu")
		(net "M_E_CPU1_SA_DQS_DP<4>")
	)
	(arc
		(start 138.721846 -260.384544)
		(mid 138.851238 -260.439046)
		(end 138.99007 -260.459982)
		(width 0.088646)
		(layer "F.Cu")
		(net "M_E_CPU1_SA_DQS_DP<4>")
	)
	(arc
		(start 138.34745 -260.384544)
		(mid 138.534648 -260.334401)
		(end 138.721846 -260.384544)
		(width 0.088646)
		(layer "F.Cu")
		(net "M_E_CPU1_SA_DQS_DP<4>")
	)
	(arc
		(start 137.792206 -260.39064)
		(mid 138.070638 -260.460454)
		(end 138.34745 -260.384544)
		(width 0.088646)
		(layer "F.Cu")
		(net "M_E_CPU1_SA_DQS_DP<4>")
	)
	(segment
		(start 150.116794 -283.092906)
		(end 150.542244 -283.518356)
		(width 0.20066)
		(layer "F.Cu")
		(net "M_E_CPU1_SA_DQS_DP<3>")
	)
	(segment
		(start 155.872942 -285.211774)
		(end 155.963112 -285.151576)
		(width 0.20066)
		(layer "F.Cu")
		(net "M_E_CPU1_SA_DQS_DP<3>")
	)
	(segment
		(start 139.697206 -266.052554)
		(end 139.697206 -266.124436)
		(width 0.088646)
		(layer "F.Cu")
		(net "M_E_CPU1_SA_DQS_DP<3>")
	)
	(segment
		(start 146.940016 -273.340322)
		(end 148.571458 -281.4955)
		(width 0.1524)
		(layer "F.Cu")
		(net "M_E_CPU1_SA_DQS_DP<3>")
	)
	(segment
		(start 137.769346 -265.260074)
		(end 137.780776 -265.266678)
		(width 0.088646)
		(layer "F.Cu")
		(net "M_E_CPU1_SA_DQS_DP<3>")
	)
	(segment
		(start 139.269216 -265.696446)
		(end 139.413234 -265.840464)
		(width 0.088646)
		(layer "F.Cu")
		(net "M_E_CPU1_SA_DQS_DP<3>")
	)
	(segment
		(start 165.808406 -284.866588)
		(end 165.52672 -284.584902)
		(width 0.20066)
		(layer "F.Cu")
		(net "M_E_CPU1_SA_DQS_DP<3>")
	)
	(segment
		(start 155.699968 -285.327344)
		(end 155.872942 -285.211774)
		(width 0.20066)
		(layer "F.Cu")
		(net "M_E_CPU1_SA_DQS_DP<3>")
	)
	(segment
		(start 161.891726 -285.303468)
		(end 161.606738 -285.303468)
		(width 0.20066)
		(layer "F.Cu")
		(net "M_E_CPU1_SA_DQS_DP<3>")
	)
	(segment
		(start 161.606738 -285.303468)
		(end 161.343848 -285.040578)
		(width 0.20066)
		(layer "F.Cu")
		(net "M_E_CPU1_SA_DQS_DP<3>")
	)
	(segment
		(start 151.142446 -284.118558)
		(end 151.820626 -284.796738)
		(width 0.20066)
		(layer "F.Cu")
		(net "M_E_CPU1_SA_DQS_DP<3>")
	)
	(segment
		(start 159.402526 -284.866588)
		(end 158.813246 -284.866588)
		(width 0.20066)
		(layer "F.Cu")
		(net "M_E_CPU1_SA_DQS_DP<3>")
	)
	(segment
		(start 163.923726 -285.310326)
		(end 163.905184 -285.291784)
		(width 0.1016)
		(layer "F.Cu")
		(net "M_E_CPU1_SA_DQS_DP<3>")
	)
	(segment
		(start 149.516592 -282.666948)
		(end 149.94255 -283.092906)
		(width 0.20066)
		(layer "F.Cu")
		(net "M_E_CPU1_SA_DQS_DP<3>")
	)
	(segment
		(start 139.413234 -265.840464)
		(end 139.485116 -265.840464)
		(width 0.088646)
		(layer "F.Cu")
		(net "M_E_CPU1_SA_DQS_DP<3>")
	)
	(segment
		(start 140.400278 -266.755372)
		(end 140.400278 -266.800584)
		(width 0.088646)
		(layer "F.Cu")
		(net "M_E_CPU1_SA_DQS_DP<3>")
	)
	(segment
		(start 139.91336 -266.268454)
		(end 140.400278 -266.755372)
		(width 0.088646)
		(layer "F.Cu")
		(net "M_E_CPU1_SA_DQS_DP<3>")
	)
	(segment
		(start 140.415772 -266.816078)
		(end 146.940016 -273.340322)
		(width 0.1524)
		(layer "F.Cu")
		(net "M_E_CPU1_SA_DQS_DP<3>")
	)
	(segment
		(start 137.410952 -265.051032)
		(end 137.549382 -265.189462)
		(width 0.088646)
		(layer "F.Cu")
		(net "M_E_CPU1_SA_DQS_DP<3>")
	)
	(segment
		(start 139.485116 -265.840464)
		(end 139.697206 -266.052554)
		(width 0.088646)
		(layer "F.Cu")
		(net "M_E_CPU1_SA_DQS_DP<3>")
	)
	(segment
		(start 161.908236 -285.291784)
		(end 161.896552 -285.303468)
		(width 0.1016)
		(layer "F.Cu")
		(net "M_E_CPU1_SA_DQS_DP<3>")
	)
	(segment
		(start 150.542244 -283.6926)
		(end 150.968202 -284.118558)
		(width 0.20066)
		(layer "F.Cu")
		(net "M_E_CPU1_SA_DQS_DP<3>")
	)
	(segment
		(start 137.410952 -264.855452)
		(end 137.410952 -265.051032)
		(width 0.088646)
		(layer "F.Cu")
		(net "M_E_CPU1_SA_DQS_DP<3>")
	)
	(segment
		(start 164.549582 -284.995366)
		(end 164.234622 -285.310326)
		(width 0.20066)
		(layer "F.Cu")
		(net "M_E_CPU1_SA_DQS_DP<3>")
	)
	(segment
		(start 149.064218 -282.04033)
		(end 149.091142 -282.067254)
		(width 0.1524)
		(layer "F.Cu")
		(net "M_E_CPU1_SA_DQS_DP<3>")
	)
	(segment
		(start 165.52672 -284.584902)
		(end 165.330632 -284.584902)
		(width 0.20066)
		(layer "F.Cu")
		(net "M_E_CPU1_SA_DQS_DP<3>")
	)
	(segment
		(start 148.571458 -281.4955)
		(end 149.064218 -281.988006)
		(width 0.1524)
		(layer "F.Cu")
		(net "M_E_CPU1_SA_DQS_DP<3>")
	)
	(segment
		(start 165.330632 -284.584902)
		(end 164.920168 -284.995366)
		(width 0.20066)
		(layer "F.Cu")
		(net "M_E_CPU1_SA_DQS_DP<3>")
	)
	(segment
		(start 149.064218 -281.988006)
		(end 149.064218 -282.04033)
		(width 0.1524)
		(layer "F.Cu")
		(net "M_E_CPU1_SA_DQS_DP<3>")
	)
	(segment
		(start 160.75025 -285.040578)
		(end 160.335722 -284.62605)
		(width 0.20066)
		(layer "F.Cu")
		(net "M_E_CPU1_SA_DQS_DP<3>")
	)
	(segment
		(start 149.516592 -282.492704)
		(end 149.516592 -282.666948)
		(width 0.20066)
		(layer "F.Cu")
		(net "M_E_CPU1_SA_DQS_DP<3>")
	)
	(segment
		(start 156.135832 -285.185866)
		(end 156.636466 -284.851348)
		(width 0.20066)
		(layer "F.Cu")
		(net "M_E_CPU1_SA_DQS_DP<3>")
	)
	(segment
		(start 156.636466 -284.851348)
		(end 156.67101 -284.678628)
		(width 0.20066)
		(layer "F.Cu")
		(net "M_E_CPU1_SA_DQS_DP<3>")
	)
	(segment
		(start 157.787594 -284.442154)
		(end 157.787594 -284.785054)
		(width 0.20066)
		(layer "F.Cu")
		(net "M_E_CPU1_SA_DQS_DP<3>")
	)
	(segment
		(start 157.123892 -284.376114)
		(end 157.721554 -284.376114)
		(width 0.20066)
		(layer "F.Cu")
		(net "M_E_CPU1_SA_DQS_DP<3>")
	)
	(segment
		(start 157.869128 -284.866588)
		(end 158.813246 -284.866588)
		(width 0.20066)
		(layer "F.Cu")
		(net "M_E_CPU1_SA_DQS_DP<3>")
	)
	(segment
		(start 166.357046 -284.866588)
		(end 165.808406 -284.866588)
		(width 0.20066)
		(layer "F.Cu")
		(net "M_E_CPU1_SA_DQS_DP<3>")
	)
	(segment
		(start 157.721554 -284.376114)
		(end 157.787594 -284.442154)
		(width 0.20066)
		(layer "F.Cu")
		(net "M_E_CPU1_SA_DQS_DP<3>")
	)
	(segment
		(start 137.124694 -264.778236)
		(end 137.289794 -264.734294)
		(width 0.088646)
		(layer "F.Cu")
		(net "M_E_CPU1_SA_DQS_DP<3>")
	)
	(segment
		(start 160.335722 -284.62605)
		(end 159.643064 -284.62605)
		(width 0.20066)
		(layer "F.Cu")
		(net "M_E_CPU1_SA_DQS_DP<3>")
	)
	(segment
		(start 159.643064 -284.62605)
		(end 159.402526 -284.866588)
		(width 0.20066)
		(layer "F.Cu")
		(net "M_E_CPU1_SA_DQS_DP<3>")
	)
	(segment
		(start 138.848338 -265.324844)
		(end 138.866372 -265.342116)
		(width 0.088646)
		(layer "F.Cu")
		(net "M_E_CPU1_SA_DQS_DP<3>")
	)
	(segment
		(start 156.67101 -284.678628)
		(end 157.123892 -284.376114)
		(width 0.20066)
		(layer "F.Cu")
		(net "M_E_CPU1_SA_DQS_DP<3>")
	)
	(segment
		(start 153.101802 -285.327344)
		(end 155.699968 -285.327344)
		(width 0.20066)
		(layer "F.Cu")
		(net "M_E_CPU1_SA_DQS_DP<3>")
	)
	(segment
		(start 139.125706 -265.481054)
		(end 139.269216 -265.624564)
		(width 0.088646)
		(layer "F.Cu")
		(net "M_E_CPU1_SA_DQS_DP<3>")
	)
	(segment
		(start 150.968202 -284.118558)
		(end 151.142446 -284.118558)
		(width 0.20066)
		(layer "F.Cu")
		(net "M_E_CPU1_SA_DQS_DP<3>")
	)
	(segment
		(start 163.905184 -285.291784)
		(end 161.908236 -285.291784)
		(width 0.1016)
		(layer "F.Cu")
		(net "M_E_CPU1_SA_DQS_DP<3>")
	)
	(segment
		(start 139.841224 -266.268454)
		(end 139.91336 -266.268454)
		(width 0.088646)
		(layer "F.Cu")
		(net "M_E_CPU1_SA_DQS_DP<3>")
	)
	(segment
		(start 161.343848 -285.040578)
		(end 160.75025 -285.040578)
		(width 0.20066)
		(layer "F.Cu")
		(net "M_E_CPU1_SA_DQS_DP<3>")
	)
	(segment
		(start 137.769092 -265.25982)
		(end 137.769346 -265.260074)
		(width 0.088646)
		(layer "F.Cu")
		(net "M_E_CPU1_SA_DQS_DP<3>")
	)
	(segment
		(start 139.269216 -265.624564)
		(end 139.269216 -265.696446)
		(width 0.088646)
		(layer "F.Cu")
		(net "M_E_CPU1_SA_DQS_DP<3>")
	)
	(segment
		(start 157.787594 -284.785054)
		(end 157.869128 -284.866588)
		(width 0.20066)
		(layer "F.Cu")
		(net "M_E_CPU1_SA_DQS_DP<3>")
	)
	(segment
		(start 150.542244 -283.518356)
		(end 150.542244 -283.6926)
		(width 0.20066)
		(layer "F.Cu")
		(net "M_E_CPU1_SA_DQS_DP<3>")
	)
	(segment
		(start 149.091142 -282.067254)
		(end 149.516592 -282.492704)
		(width 0.20066)
		(layer "F.Cu")
		(net "M_E_CPU1_SA_DQS_DP<3>")
	)
	(segment
		(start 137.549382 -265.189462)
		(end 137.676382 -265.189462)
		(width 0.088646)
		(layer "F.Cu")
		(net "M_E_CPU1_SA_DQS_DP<3>")
	)
	(segment
		(start 140.400278 -266.800584)
		(end 140.415772 -266.816078)
		(width 0.088646)
		(layer "F.Cu")
		(net "M_E_CPU1_SA_DQS_DP<3>")
	)
	(segment
		(start 161.896552 -285.303468)
		(end 161.891726 -285.303468)
		(width 0.101854)
		(layer "F.Cu")
		(net "M_E_CPU1_SA_DQS_DP<3>")
	)
	(segment
		(start 139.697206 -266.124436)
		(end 139.841224 -266.268454)
		(width 0.088646)
		(layer "F.Cu")
		(net "M_E_CPU1_SA_DQS_DP<3>")
	)
	(segment
		(start 155.963112 -285.151576)
		(end 156.135832 -285.185866)
		(width 0.20066)
		(layer "F.Cu")
		(net "M_E_CPU1_SA_DQS_DP<3>")
	)
	(segment
		(start 151.820626 -284.796738)
		(end 153.101802 -285.327344)
		(width 0.20066)
		(layer "F.Cu")
		(net "M_E_CPU1_SA_DQS_DP<3>")
	)
	(segment
		(start 164.234622 -285.310326)
		(end 163.923726 -285.310326)
		(width 0.20066)
		(layer "F.Cu")
		(net "M_E_CPU1_SA_DQS_DP<3>")
	)
	(segment
		(start 164.920168 -284.995366)
		(end 164.549582 -284.995366)
		(width 0.20066)
		(layer "F.Cu")
		(net "M_E_CPU1_SA_DQS_DP<3>")
	)
	(segment
		(start 137.780776 -265.266678)
		(end 137.7823 -265.26744)
		(width 0.088646)
		(layer "F.Cu")
		(net "M_E_CPU1_SA_DQS_DP<3>")
	)
	(segment
		(start 137.289794 -264.734294)
		(end 137.410952 -264.855452)
		(width 0.088646)
		(layer "F.Cu")
		(net "M_E_CPU1_SA_DQS_DP<3>")
	)
	(segment
		(start 138.866372 -265.342116)
		(end 139.125706 -265.481054)
		(width 0.088646)
		(layer "F.Cu")
		(net "M_E_CPU1_SA_DQS_DP<3>")
	)
	(segment
		(start 149.94255 -283.092906)
		(end 150.116794 -283.092906)
		(width 0.20066)
		(layer "F.Cu")
		(net "M_E_CPU1_SA_DQS_DP<3>")
	)
	(arc
		(start 137.676382 -265.189462)
		(mid 137.67689 -265.188954)
		(end 137.677398 -265.188446)
		(width 0.088646)
		(layer "F.Cu")
		(net "M_E_CPU1_SA_DQS_DP<3>")
	)
	(arc
		(start 137.677398 -265.188446)
		(mid 137.721179 -265.226788)
		(end 137.769092 -265.25982)
		(width 0.088646)
		(layer "F.Cu")
		(net "M_E_CPU1_SA_DQS_DP<3>")
	)
	(arc
		(start 138.346942 -265.26744)
		(mid 138.607147 -265.213274)
		(end 138.848338 -265.324844)
		(width 0.088646)
		(layer "F.Cu")
		(net "M_E_CPU1_SA_DQS_DP<3>")
	)
	(arc
		(start 137.7823 -265.26744)
		(mid 138.064638 -265.343123)
		(end 138.346942 -265.26744)
		(width 0.088646)
		(layer "F.Cu")
		(net "M_E_CPU1_SA_DQS_DP<3>")
	)
	(segment
		(start 160.335722 -293.976044)
		(end 159.643064 -293.976044)
		(width 0.20066)
		(layer "F.Cu")
		(net "M_E_CPU1_SA_DQS_DP<2>")
	)
	(segment
		(start 158.216346 -294.214296)
		(end 158.813246 -294.216582)
		(width 0.20066)
		(layer "F.Cu")
		(net "M_E_CPU1_SA_DQS_DP<2>")
	)
	(segment
		(start 164.549582 -294.34536)
		(end 164.234622 -294.66032)
		(width 0.20066)
		(layer "F.Cu")
		(net "M_E_CPU1_SA_DQS_DP<2>")
	)
	(segment
		(start 144.593056 -289.711892)
		(end 144.61998 -289.738816)
		(width 0.1524)
		(layer "F.Cu")
		(net "M_E_CPU1_SA_DQS_DP<2>")
	)
	(segment
		(start 157.457648 -294.026336)
		(end 158.02991 -294.026336)
		(width 0.20066)
		(layer "F.Cu")
		(net "M_E_CPU1_SA_DQS_DP<2>")
	)
	(segment
		(start 161.606738 -294.653462)
		(end 161.343848 -294.390572)
		(width 0.20066)
		(layer "F.Cu")
		(net "M_E_CPU1_SA_DQS_DP<2>")
	)
	(segment
		(start 163.905184 -294.641778)
		(end 161.908236 -294.641778)
		(width 0.1016)
		(layer "F.Cu")
		(net "M_E_CPU1_SA_DQS_DP<2>")
	)
	(segment
		(start 138.138662 -270.623792)
		(end 138.138662 -270.623538)
		(width 0.088646)
		(layer "F.Cu")
		(net "M_E_CPU1_SA_DQS_DP<2>")
	)
	(segment
		(start 161.908236 -294.641778)
		(end 161.896552 -294.653462)
		(width 0.1016)
		(layer "F.Cu")
		(net "M_E_CPU1_SA_DQS_DP<2>")
	)
	(segment
		(start 139.060174 -270.747998)
		(end 139.060682 -270.748506)
		(width 0.088646)
		(layer "F.Cu")
		(net "M_E_CPU1_SA_DQS_DP<2>")
	)
	(segment
		(start 139.67206 -271.63649)
		(end 139.67206 -271.662144)
		(width 0.088646)
		(layer "F.Cu")
		(net "M_E_CPU1_SA_DQS_DP<2>")
	)
	(segment
		(start 160.75025 -294.390572)
		(end 160.335722 -293.976044)
		(width 0.20066)
		(layer "F.Cu")
		(net "M_E_CPU1_SA_DQS_DP<2>")
	)
	(segment
		(start 139.037568 -270.70685)
		(end 139.060174 -270.74749)
		(width 0.088646)
		(layer "F.Cu")
		(net "M_E_CPU1_SA_DQS_DP<2>")
	)
	(segment
		(start 165.808406 -294.216582)
		(end 165.52672 -293.934896)
		(width 0.20066)
		(layer "F.Cu")
		(net "M_E_CPU1_SA_DQS_DP<2>")
	)
	(segment
		(start 161.891726 -294.653462)
		(end 161.606738 -294.653462)
		(width 0.20066)
		(layer "F.Cu")
		(net "M_E_CPU1_SA_DQS_DP<2>")
	)
	(segment
		(start 136.655048 -270.475456)
		(end 136.499854 -270.20647)
		(width 0.088646)
		(layer "F.Cu")
		(net "M_E_CPU1_SA_DQS_DP<2>")
	)
	(segment
		(start 136.499854 -270.20647)
		(end 136.521698 -270.125698)
		(width 0.088646)
		(layer "F.Cu")
		(net "M_E_CPU1_SA_DQS_DP<2>")
	)
	(segment
		(start 164.234622 -294.66032)
		(end 163.923726 -294.66032)
		(width 0.20066)
		(layer "F.Cu")
		(net "M_E_CPU1_SA_DQS_DP<2>")
	)
	(segment
		(start 139.060174 -270.74749)
		(end 139.060174 -270.747998)
		(width 0.088646)
		(layer "F.Cu")
		(net "M_E_CPU1_SA_DQS_DP<2>")
	)
	(segment
		(start 144.593056 -289.659568)
		(end 144.593056 -289.711892)
		(width 0.1524)
		(layer "F.Cu")
		(net "M_E_CPU1_SA_DQS_DP<2>")
	)
	(segment
		(start 138.786108 -270.170656)
		(end 138.788902 -270.17218)
		(width 0.088646)
		(layer "F.Cu")
		(net "M_E_CPU1_SA_DQS_DP<2>")
	)
	(segment
		(start 165.330632 -293.934896)
		(end 164.920168 -294.34536)
		(width 0.20066)
		(layer "F.Cu")
		(net "M_E_CPU1_SA_DQS_DP<2>")
	)
	(segment
		(start 137.301224 -270.955008)
		(end 137.30605 -270.958056)
		(width 0.088646)
		(layer "F.Cu")
		(net "M_E_CPU1_SA_DQS_DP<2>")
	)
	(segment
		(start 139.394438 -271.26057)
		(end 139.56411 -271.49044)
		(width 0.088646)
		(layer "F.Cu")
		(net "M_E_CPU1_SA_DQS_DP<2>")
	)
	(segment
		(start 161.343848 -294.390572)
		(end 160.75025 -294.390572)
		(width 0.20066)
		(layer "F.Cu")
		(net "M_E_CPU1_SA_DQS_DP<2>")
	)
	(segment
		(start 166.357046 -294.216582)
		(end 165.808406 -294.216582)
		(width 0.20066)
		(layer "F.Cu")
		(net "M_E_CPU1_SA_DQS_DP<2>")
	)
	(segment
		(start 143.317976 -275.30806)
		(end 144.32915 -280.361898)
		(width 0.1524)
		(layer "F.Cu")
		(net "M_E_CPU1_SA_DQS_DP<2>")
	)
	(segment
		(start 158.02991 -294.026336)
		(end 158.216346 -294.214296)
		(width 0.20066)
		(layer "F.Cu")
		(net "M_E_CPU1_SA_DQS_DP<2>")
	)
	(segment
		(start 161.896552 -294.653462)
		(end 161.891726 -294.653462)
		(width 0.101854)
		(layer "F.Cu")
		(net "M_E_CPU1_SA_DQS_DP<2>")
	)
	(segment
		(start 155.17495 -296.309034)
		(end 157.457648 -294.026336)
		(width 0.20066)
		(layer "F.Cu")
		(net "M_E_CPU1_SA_DQS_DP<2>")
	)
	(segment
		(start 139.67206 -271.662144)
		(end 143.317976 -275.30806)
		(width 0.1524)
		(layer "F.Cu")
		(net "M_E_CPU1_SA_DQS_DP<2>")
	)
	(segment
		(start 138.880088 -270.242792)
		(end 138.882374 -270.245078)
		(width 0.088646)
		(layer "F.Cu")
		(net "M_E_CPU1_SA_DQS_DP<2>")
	)
	(segment
		(start 139.020296 -270.665702)
		(end 139.037568 -270.70685)
		(width 0.088646)
		(layer "F.Cu")
		(net "M_E_CPU1_SA_DQS_DP<2>")
	)
	(segment
		(start 164.920168 -294.34536)
		(end 164.549582 -294.34536)
		(width 0.20066)
		(layer "F.Cu")
		(net "M_E_CPU1_SA_DQS_DP<2>")
	)
	(segment
		(start 151.190198 -296.309034)
		(end 155.17495 -296.309034)
		(width 0.20066)
		(layer "F.Cu")
		(net "M_E_CPU1_SA_DQS_DP<2>")
	)
	(segment
		(start 165.52672 -293.934896)
		(end 165.330632 -293.934896)
		(width 0.20066)
		(layer "F.Cu")
		(net "M_E_CPU1_SA_DQS_DP<2>")
	)
	(segment
		(start 163.923726 -294.66032)
		(end 163.905184 -294.641778)
		(width 0.1016)
		(layer "F.Cu")
		(net "M_E_CPU1_SA_DQS_DP<2>")
	)
	(segment
		(start 144.61998 -289.738816)
		(end 151.190198 -296.309034)
		(width 0.20066)
		(layer "F.Cu")
		(net "M_E_CPU1_SA_DQS_DP<2>")
	)
	(segment
		(start 138.544554 -270.137636)
		(end 138.655044 -270.137636)
		(width 0.088646)
		(layer "F.Cu")
		(net "M_E_CPU1_SA_DQS_DP<2>")
	)
	(segment
		(start 138.138662 -270.623538)
		(end 138.153902 -270.575278)
		(width 0.088646)
		(layer "F.Cu")
		(net "M_E_CPU1_SA_DQS_DP<2>")
	)
	(segment
		(start 144.32915 -289.395662)
		(end 144.593056 -289.659568)
		(width 0.1524)
		(layer "F.Cu")
		(net "M_E_CPU1_SA_DQS_DP<2>")
	)
	(segment
		(start 159.402526 -294.216582)
		(end 158.813246 -294.216582)
		(width 0.20066)
		(layer "F.Cu")
		(net "M_E_CPU1_SA_DQS_DP<2>")
	)
	(segment
		(start 159.643064 -293.976044)
		(end 159.402526 -294.216582)
		(width 0.20066)
		(layer "F.Cu")
		(net "M_E_CPU1_SA_DQS_DP<2>")
	)
	(segment
		(start 139.645136 -271.571466)
		(end 139.67206 -271.63649)
		(width 0.088646)
		(layer "F.Cu")
		(net "M_E_CPU1_SA_DQS_DP<2>")
	)
	(segment
		(start 139.060682 -270.748506)
		(end 139.074906 -270.782034)
		(width 0.088646)
		(layer "F.Cu")
		(net "M_E_CPU1_SA_DQS_DP<2>")
	)
	(segment
		(start 139.56411 -271.49044)
		(end 139.645136 -271.571466)
		(width 0.088646)
		(layer "F.Cu")
		(net "M_E_CPU1_SA_DQS_DP<2>")
	)
	(segment
		(start 144.32915 -280.361898)
		(end 144.32915 -289.395662)
		(width 0.1524)
		(layer "F.Cu")
		(net "M_E_CPU1_SA_DQS_DP<2>")
	)
	(segment
		(start 139.074906 -270.782034)
		(end 139.394438 -271.26057)
		(width 0.088646)
		(layer "F.Cu")
		(net "M_E_CPU1_SA_DQS_DP<2>")
	)
	(arc
		(start 136.521698 -270.125698)
		(mid 136.583875 -270.107882)
		(end 136.64819 -270.10106)
		(width 0.088646)
		(layer "F.Cu")
		(net "M_E_CPU1_SA_DQS_DP<2>")
	)
	(arc
		(start 138.882374 -270.245078)
		(mid 138.883392 -270.246092)
		(end 138.884406 -270.24711)
		(width 0.088646)
		(layer "F.Cu")
		(net "M_E_CPU1_SA_DQS_DP<2>")
	)
	(arc
		(start 138.655044 -270.137636)
		(mid 138.72262 -270.146025)
		(end 138.786108 -270.170656)
		(width 0.088646)
		(layer "F.Cu")
		(net "M_E_CPU1_SA_DQS_DP<2>")
	)
	(arc
		(start 138.975846 -270.452088)
		(mid 138.987856 -270.561022)
		(end 139.020296 -270.665702)
		(width 0.088646)
		(layer "F.Cu")
		(net "M_E_CPU1_SA_DQS_DP<2>")
	)
	(arc
		(start 138.153902 -270.575278)
		(mid 138.165229 -270.531094)
		(end 138.171174 -270.48587)
		(width 0.088646)
		(layer "F.Cu")
		(net "M_E_CPU1_SA_DQS_DP<2>")
	)
	(arc
		(start 138.788902 -270.17218)
		(mid 138.837008 -270.204242)
		(end 138.880088 -270.242792)
		(width 0.088646)
		(layer "F.Cu")
		(net "M_E_CPU1_SA_DQS_DP<2>")
	)
	(arc
		(start 137.04189 -270.493998)
		(mid 137.115088 -270.756273)
		(end 137.301224 -270.955008)
		(width 0.088646)
		(layer "F.Cu")
		(net "M_E_CPU1_SA_DQS_DP<2>")
	)
	(arc
		(start 138.171174 -270.48587)
		(mid 138.289304 -270.238272)
		(end 138.544554 -270.137636)
		(width 0.088646)
		(layer "F.Cu")
		(net "M_E_CPU1_SA_DQS_DP<2>")
	)
	(arc
		(start 136.785858 -270.124682)
		(mid 136.854931 -270.159614)
		(end 136.915144 -270.208248)
		(width 0.088646)
		(layer "F.Cu")
		(net "M_E_CPU1_SA_DQS_DP<2>")
	)
	(arc
		(start 136.915144 -270.208248)
		(mid 136.985255 -270.299633)
		(end 137.02919 -270.406114)
		(width 0.088646)
		(layer "F.Cu")
		(net "M_E_CPU1_SA_DQS_DP<2>")
	)
	(arc
		(start 137.389362 -270.998696)
		(mid 137.842939 -270.968992)
		(end 138.138662 -270.623792)
		(width 0.088646)
		(layer "F.Cu")
		(net "M_E_CPU1_SA_DQS_DP<2>")
	)
	(arc
		(start 136.64819 -270.10106)
		(mid 136.718161 -270.106255)
		(end 136.785858 -270.124682)
		(width 0.088646)
		(layer "F.Cu")
		(net "M_E_CPU1_SA_DQS_DP<2>")
	)
	(arc
		(start 137.30605 -270.958056)
		(mid 137.34646 -270.980929)
		(end 137.389362 -270.998696)
		(width 0.088646)
		(layer "F.Cu")
		(net "M_E_CPU1_SA_DQS_DP<2>")
	)
	(arc
		(start 138.884406 -270.24711)
		(mid 138.951722 -270.33996)
		(end 138.975846 -270.452088)
		(width 0.088646)
		(layer "F.Cu")
		(net "M_E_CPU1_SA_DQS_DP<2>")
	)
	(arc
		(start 137.02919 -270.406114)
		(mid 137.038043 -270.449694)
		(end 137.04189 -270.493998)
		(width 0.088646)
		(layer "F.Cu")
		(net "M_E_CPU1_SA_DQS_DP<2>")
	)
	(segment
		(start 159.643064 -303.326038)
		(end 159.402526 -303.566576)
		(width 0.20066)
		(layer "F.Cu")
		(net "M_E_CPU1_SA_DQS_DP<1>")
	)
	(segment
		(start 163.923726 -304.003202)
		(end 163.911788 -304.003202)
		(width 0.101854)
		(layer "F.Cu")
		(net "M_E_CPU1_SA_DQS_DP<1>")
	)
	(segment
		(start 166.357046 -303.566576)
		(end 165.808406 -303.566576)
		(width 0.20066)
		(layer "F.Cu")
		(net "M_E_CPU1_SA_DQS_DP<1>")
	)
	(segment
		(start 159.402526 -303.566576)
		(end 158.813246 -303.566576)
		(width 0.20066)
		(layer "F.Cu")
		(net "M_E_CPU1_SA_DQS_DP<1>")
	)
	(segment
		(start 160.267904 -303.326038)
		(end 159.643064 -303.326038)
		(width 0.20066)
		(layer "F.Cu")
		(net "M_E_CPU1_SA_DQS_DP<1>")
	)
	(segment
		(start 163.911788 -304.003202)
		(end 163.900358 -303.991772)
		(width 0.1016)
		(layer "F.Cu")
		(net "M_E_CPU1_SA_DQS_DP<1>")
	)
	(segment
		(start 161.69386 -303.991772)
		(end 161.595054 -303.991772)
		(width 0.20066)
		(layer "F.Cu")
		(net "M_E_CPU1_SA_DQS_DP<1>")
	)
	(segment
		(start 164.190426 -304.003202)
		(end 163.923726 -304.003202)
		(width 0.20066)
		(layer "F.Cu")
		(net "M_E_CPU1_SA_DQS_DP<1>")
	)
	(segment
		(start 157.682946 -303.566576)
		(end 158.813246 -303.566576)
		(width 0.20066)
		(layer "F.Cu")
		(net "M_E_CPU1_SA_DQS_DP<1>")
	)
	(segment
		(start 161.595054 -303.991772)
		(end 161.343848 -303.740566)
		(width 0.20066)
		(layer "F.Cu")
		(net "M_E_CPU1_SA_DQS_DP<1>")
	)
	(segment
		(start 164.950648 -303.695354)
		(end 164.498274 -303.695354)
		(width 0.20066)
		(layer "F.Cu")
		(net "M_E_CPU1_SA_DQS_DP<1>")
	)
	(segment
		(start 161.343848 -303.740566)
		(end 160.682432 -303.740566)
		(width 0.20066)
		(layer "F.Cu")
		(net "M_E_CPU1_SA_DQS_DP<1>")
	)
	(segment
		(start 133.835648 -272.639028)
		(end 133.835394 -272.639282)
		(width 0.20066)
		(layer "F.Cu")
		(net "M_E_CPU1_SA_DQS_DP<1>")
	)
	(segment
		(start 165.808406 -303.566576)
		(end 165.536372 -303.294542)
		(width 0.20066)
		(layer "F.Cu")
		(net "M_E_CPU1_SA_DQS_DP<1>")
	)
	(segment
		(start 165.35146 -303.294542)
		(end 164.950648 -303.695354)
		(width 0.20066)
		(layer "F.Cu")
		(net "M_E_CPU1_SA_DQS_DP<1>")
	)
	(segment
		(start 133.835648 -272.103342)
		(end 133.835648 -272.639028)
		(width 0.20066)
		(layer "F.Cu")
		(net "M_E_CPU1_SA_DQS_DP<1>")
	)
	(segment
		(start 160.682432 -303.740566)
		(end 160.267904 -303.326038)
		(width 0.20066)
		(layer "F.Cu")
		(net "M_E_CPU1_SA_DQS_DP<1>")
	)
	(segment
		(start 161.896552 -303.991772)
		(end 161.69386 -303.991772)
		(width 0.101854)
		(layer "F.Cu")
		(net "M_E_CPU1_SA_DQS_DP<1>")
	)
	(segment
		(start 164.498274 -303.695354)
		(end 164.190426 -304.003202)
		(width 0.20066)
		(layer "F.Cu")
		(net "M_E_CPU1_SA_DQS_DP<1>")
	)
	(segment
		(start 165.536372 -303.294542)
		(end 165.35146 -303.294542)
		(width 0.20066)
		(layer "F.Cu")
		(net "M_E_CPU1_SA_DQS_DP<1>")
	)
	(segment
		(start 163.900358 -303.991772)
		(end 161.896552 -303.991772)
		(width 0.1016)
		(layer "F.Cu")
		(net "M_E_CPU1_SA_DQS_DP<1>")
	)
	(segment
		(start 154.822144 -300.712886)
		(end 154.697684 -300.588426)
		(width 0.18288)
		(layer "In2.Cu")
		(net "M_E_CPU1_SA_DQS_DP<1>")
	)
	(segment
		(start 154.24023 -295.1607)
		(end 154.307794 -294.99814)
		(width 0.18288)
		(layer "In2.Cu")
		(net "M_E_CPU1_SA_DQS_DP<1>")
	)
	(segment
		(start 151.25954 -289.526726)
		(end 151.083518 -289.526726)
		(width 0.18288)
		(layer "In2.Cu")
		(net "M_E_CPU1_SA_DQS_DP<1>")
	)
	(segment
		(start 140.900658 -273.98345)
		(end 140.840968 -273.92376)
		(width 0.088646)
		(layer "In2.Cu")
		(net "M_E_CPU1_SA_DQS_DP<1>")
	)
	(segment
		(start 153.21153 -292.672516)
		(end 153.279094 -292.509956)
		(width 0.18288)
		(layer "In2.Cu")
		(net "M_E_CPU1_SA_DQS_DP<1>")
	)
	(segment
		(start 153.72588 -293.916608)
		(end 153.793444 -293.754048)
		(width 0.18288)
		(layer "In2.Cu")
		(net "M_E_CPU1_SA_DQS_DP<1>")
	)
	(segment
		(start 149.743414 -288.0106)
		(end 149.188424 -287.45561)
		(width 0.18288)
		(layer "In2.Cu")
		(net "M_E_CPU1_SA_DQS_DP<1>")
	)
	(segment
		(start 150.695406 -288.962592)
		(end 150.307548 -288.574734)
		(width 0.18288)
		(layer "In2.Cu")
		(net "M_E_CPU1_SA_DQS_DP<1>")
	)
	(segment
		(start 154.697684 -300.588426)
		(end 154.697684 -300.039786)
		(width 0.18288)
		(layer "In2.Cu")
		(net "M_E_CPU1_SA_DQS_DP<1>")
	)
	(segment
		(start 150.131526 -288.574734)
		(end 149.743414 -288.186622)
		(width 0.18288)
		(layer "In2.Cu")
		(net "M_E_CPU1_SA_DQS_DP<1>")
	)
	(segment
		(start 153.93543 -294.423846)
		(end 153.72588 -293.916608)
		(width 0.18288)
		(layer "In2.Cu")
		(net "M_E_CPU1_SA_DQS_DP<1>")
	)
	(segment
		(start 155.88869 -302.328072)
		(end 154.822144 -301.261526)
		(width 0.18288)
		(layer "In2.Cu")
		(net "M_E_CPU1_SA_DQS_DP<1>")
	)
	(segment
		(start 154.44978 -295.667938)
		(end 154.24023 -295.1607)
		(width 0.18288)
		(layer "In2.Cu")
		(net "M_E_CPU1_SA_DQS_DP<1>")
	)
	(segment
		(start 154.822144 -299.915326)
		(end 154.822144 -299.366686)
		(width 0.18288)
		(layer "In2.Cu")
		(net "M_E_CPU1_SA_DQS_DP<1>")
	)
	(segment
		(start 154.612594 -295.735248)
		(end 154.44978 -295.667938)
		(width 0.18288)
		(layer "In2.Cu")
		(net "M_E_CPU1_SA_DQS_DP<1>")
	)
	(segment
		(start 149.063964 -284.440122)
		(end 149.188424 -284.315662)
		(width 0.18288)
		(layer "In2.Cu")
		(net "M_E_CPU1_SA_DQS_DP<1>")
	)
	(segment
		(start 149.188424 -285.113222)
		(end 149.063964 -284.988762)
		(width 0.18288)
		(layer "In2.Cu")
		(net "M_E_CPU1_SA_DQS_DP<1>")
	)
	(segment
		(start 154.822144 -301.261526)
		(end 154.822144 -300.712886)
		(width 0.18288)
		(layer "In2.Cu")
		(net "M_E_CPU1_SA_DQS_DP<1>")
	)
	(segment
		(start 157.682946 -303.566576)
		(end 157.396434 -303.280064)
		(width 0.18288)
		(layer "In2.Cu")
		(net "M_E_CPU1_SA_DQS_DP<1>")
	)
	(segment
		(start 154.822144 -298.020486)
		(end 154.697684 -297.896026)
		(width 0.18288)
		(layer "In2.Cu")
		(net "M_E_CPU1_SA_DQS_DP<1>")
	)
	(segment
		(start 134.507478 -273.137376)
		(end 134.399274 -273.074638)
		(width 0.088646)
		(layer "In2.Cu")
		(net "M_E_CPU1_SA_DQS_DP<1>")
	)
	(segment
		(start 149.188424 -287.45561)
		(end 149.188424 -286.459422)
		(width 0.18288)
		(layer "In2.Cu")
		(net "M_E_CPU1_SA_DQS_DP<1>")
	)
	(segment
		(start 154.098244 -294.491156)
		(end 153.93543 -294.423846)
		(width 0.18288)
		(layer "In2.Cu")
		(net "M_E_CPU1_SA_DQS_DP<1>")
	)
	(segment
		(start 151.647398 -289.914584)
		(end 151.25954 -289.526726)
		(width 0.18288)
		(layer "In2.Cu")
		(net "M_E_CPU1_SA_DQS_DP<1>")
	)
	(segment
		(start 134.399274 -273.074638)
		(end 134.070598 -272.663158)
		(width 0.088646)
		(layer "In2.Cu")
		(net "M_E_CPU1_SA_DQS_DP<1>")
	)
	(segment
		(start 151.083518 -289.526726)
		(end 150.695406 -289.138614)
		(width 0.18288)
		(layer "In2.Cu")
		(net "M_E_CPU1_SA_DQS_DP<1>")
	)
	(segment
		(start 153.583894 -293.247064)
		(end 153.42108 -293.179754)
		(width 0.18288)
		(layer "In2.Cu")
		(net "M_E_CPU1_SA_DQS_DP<1>")
	)
	(segment
		(start 152.599898 -290.867084)
		(end 152.211532 -290.478718)
		(width 0.18288)
		(layer "In2.Cu")
		(net "M_E_CPU1_SA_DQS_DP<1>")
	)
	(segment
		(start 149.188424 -285.661862)
		(end 149.188424 -285.113222)
		(width 0.18288)
		(layer "In2.Cu")
		(net "M_E_CPU1_SA_DQS_DP<1>")
	)
	(segment
		(start 135.44296 -273.134836)
		(end 135.432546 -273.12874)
		(width 0.088646)
		(layer "In2.Cu")
		(net "M_E_CPU1_SA_DQS_DP<1>")
	)
	(segment
		(start 154.822144 -299.366686)
		(end 154.697684 -299.242226)
		(width 0.18288)
		(layer "In2.Cu")
		(net "M_E_CPU1_SA_DQS_DP<1>")
	)
	(segment
		(start 154.822144 -296.242232)
		(end 154.612594 -295.735248)
		(width 0.18288)
		(layer "In2.Cu")
		(net "M_E_CPU1_SA_DQS_DP<1>")
	)
	(segment
		(start 150.695406 -289.138614)
		(end 150.695406 -288.962592)
		(width 0.18288)
		(layer "In2.Cu")
		(net "M_E_CPU1_SA_DQS_DP<1>")
	)
	(segment
		(start 140.005054 -273.92376)
		(end 139.26947 -273.188176)
		(width 0.088646)
		(layer "In2.Cu")
		(net "M_E_CPU1_SA_DQS_DP<1>")
	)
	(segment
		(start 144.472152 -277.062946)
		(end 141.392656 -273.98345)
		(width 0.18288)
		(layer "In2.Cu")
		(net "M_E_CPU1_SA_DQS_DP<1>")
	)
	(segment
		(start 141.392656 -273.98345)
		(end 140.900658 -273.98345)
		(width 0.18288)
		(layer "In2.Cu")
		(net "M_E_CPU1_SA_DQS_DP<1>")
	)
	(segment
		(start 154.822144 -298.569126)
		(end 154.822144 -298.020486)
		(width 0.18288)
		(layer "In2.Cu")
		(net "M_E_CPU1_SA_DQS_DP<1>")
	)
	(segment
		(start 153.42108 -293.179754)
		(end 153.21153 -292.672516)
		(width 0.18288)
		(layer "In2.Cu")
		(net "M_E_CPU1_SA_DQS_DP<1>")
	)
	(segment
		(start 154.307794 -294.99814)
		(end 154.098244 -294.491156)
		(width 0.18288)
		(layer "In2.Cu")
		(net "M_E_CPU1_SA_DQS_DP<1>")
	)
	(segment
		(start 149.188424 -284.315662)
		(end 149.188424 -283.51607)
		(width 0.18288)
		(layer "In2.Cu")
		(net "M_E_CPU1_SA_DQS_DP<1>")
	)
	(segment
		(start 156.276802 -302.892206)
		(end 155.88869 -302.504094)
		(width 0.18288)
		(layer "In2.Cu")
		(net "M_E_CPU1_SA_DQS_DP<1>")
	)
	(segment
		(start 154.697684 -300.039786)
		(end 154.822144 -299.915326)
		(width 0.18288)
		(layer "In2.Cu")
		(net "M_E_CPU1_SA_DQS_DP<1>")
	)
	(segment
		(start 152.211532 -290.478718)
		(end 152.03551 -290.478718)
		(width 0.18288)
		(layer "In2.Cu")
		(net "M_E_CPU1_SA_DQS_DP<1>")
	)
	(segment
		(start 157.396434 -303.280064)
		(end 156.840682 -303.280064)
		(width 0.18288)
		(layer "In2.Cu")
		(net "M_E_CPU1_SA_DQS_DP<1>")
	)
	(segment
		(start 156.452824 -302.892206)
		(end 156.276802 -302.892206)
		(width 0.18288)
		(layer "In2.Cu")
		(net "M_E_CPU1_SA_DQS_DP<1>")
	)
	(segment
		(start 149.063964 -285.786322)
		(end 149.188424 -285.661862)
		(width 0.18288)
		(layer "In2.Cu")
		(net "M_E_CPU1_SA_DQS_DP<1>")
	)
	(segment
		(start 154.697684 -297.896026)
		(end 154.697684 -297.347386)
		(width 0.18288)
		(layer "In2.Cu")
		(net "M_E_CPU1_SA_DQS_DP<1>")
	)
	(segment
		(start 153.279094 -292.509956)
		(end 152.599898 -290.867084)
		(width 0.18288)
		(layer "In2.Cu")
		(net "M_E_CPU1_SA_DQS_DP<1>")
	)
	(segment
		(start 152.03551 -290.478718)
		(end 151.647398 -290.090606)
		(width 0.18288)
		(layer "In2.Cu")
		(net "M_E_CPU1_SA_DQS_DP<1>")
	)
	(segment
		(start 149.188424 -283.51607)
		(end 145.701004 -280.028904)
		(width 0.18288)
		(layer "In2.Cu")
		(net "M_E_CPU1_SA_DQS_DP<1>")
	)
	(segment
		(start 155.88869 -302.504094)
		(end 155.88869 -302.328072)
		(width 0.18288)
		(layer "In2.Cu")
		(net "M_E_CPU1_SA_DQS_DP<1>")
	)
	(segment
		(start 153.793444 -293.754048)
		(end 153.583894 -293.247064)
		(width 0.18288)
		(layer "In2.Cu")
		(net "M_E_CPU1_SA_DQS_DP<1>")
	)
	(segment
		(start 156.840682 -303.280064)
		(end 156.452824 -302.892206)
		(width 0.18288)
		(layer "In2.Cu")
		(net "M_E_CPU1_SA_DQS_DP<1>")
	)
	(segment
		(start 154.822144 -297.222926)
		(end 154.822144 -296.242232)
		(width 0.18288)
		(layer "In2.Cu")
		(net "M_E_CPU1_SA_DQS_DP<1>")
	)
	(segment
		(start 154.697684 -298.693586)
		(end 154.822144 -298.569126)
		(width 0.18288)
		(layer "In2.Cu")
		(net "M_E_CPU1_SA_DQS_DP<1>")
	)
	(segment
		(start 154.697684 -297.347386)
		(end 154.822144 -297.222926)
		(width 0.18288)
		(layer "In2.Cu")
		(net "M_E_CPU1_SA_DQS_DP<1>")
	)
	(segment
		(start 140.840968 -273.92376)
		(end 140.005054 -273.92376)
		(width 0.088646)
		(layer "In2.Cu")
		(net "M_E_CPU1_SA_DQS_DP<1>")
	)
	(segment
		(start 151.647398 -290.090606)
		(end 151.647398 -289.914584)
		(width 0.18288)
		(layer "In2.Cu")
		(net "M_E_CPU1_SA_DQS_DP<1>")
	)
	(segment
		(start 150.307548 -288.574734)
		(end 150.131526 -288.574734)
		(width 0.18288)
		(layer "In2.Cu")
		(net "M_E_CPU1_SA_DQS_DP<1>")
	)
	(segment
		(start 149.188424 -286.459422)
		(end 149.063964 -286.334962)
		(width 0.18288)
		(layer "In2.Cu")
		(net "M_E_CPU1_SA_DQS_DP<1>")
	)
	(segment
		(start 154.697684 -299.242226)
		(end 154.697684 -298.693586)
		(width 0.18288)
		(layer "In2.Cu")
		(net "M_E_CPU1_SA_DQS_DP<1>")
	)
	(segment
		(start 149.743414 -288.186622)
		(end 149.743414 -288.0106)
		(width 0.18288)
		(layer "In2.Cu")
		(net "M_E_CPU1_SA_DQS_DP<1>")
	)
	(segment
		(start 149.063964 -284.988762)
		(end 149.063964 -284.440122)
		(width 0.18288)
		(layer "In2.Cu")
		(net "M_E_CPU1_SA_DQS_DP<1>")
	)
	(segment
		(start 149.063964 -286.334962)
		(end 149.063964 -285.786322)
		(width 0.18288)
		(layer "In2.Cu")
		(net "M_E_CPU1_SA_DQS_DP<1>")
	)
	(segment
		(start 134.046722 -272.639282)
		(end 133.835394 -272.639282)
		(width 0.088646)
		(layer "In2.Cu")
		(net "M_E_CPU1_SA_DQS_DP<1>")
	)
	(segment
		(start 145.701004 -280.028904)
		(end 144.472152 -277.062946)
		(width 0.18288)
		(layer "In2.Cu")
		(net "M_E_CPU1_SA_DQS_DP<1>")
	)
	(segment
		(start 134.070598 -272.663158)
		(end 134.046722 -272.639282)
		(width 0.088646)
		(layer "In2.Cu")
		(net "M_E_CPU1_SA_DQS_DP<1>")
	)
	(arc
		(start 135.997696 -273.12874)
		(mid 135.721137 -273.204483)
		(end 135.44296 -273.134836)
		(width 0.088646)
		(layer "In2.Cu")
		(net "M_E_CPU1_SA_DQS_DP<1>")
	)
	(arc
		(start 138.251692 -273.12874)
		(mid 138.064494 -273.078597)
		(end 137.877296 -273.12874)
		(width 0.088646)
		(layer "In2.Cu")
		(net "M_E_CPU1_SA_DQS_DP<1>")
	)
	(arc
		(start 139.192 -273.128486)
		(mid 139.004294 -273.078123)
		(end 138.816588 -273.128486)
		(width 0.088646)
		(layer "In2.Cu")
		(net "M_E_CPU1_SA_DQS_DP<1>")
	)
	(arc
		(start 136.937496 -273.12874)
		(mid 136.654794 -273.204516)
		(end 136.372092 -273.12874)
		(width 0.088646)
		(layer "In2.Cu")
		(net "M_E_CPU1_SA_DQS_DP<1>")
	)
	(arc
		(start 137.877296 -273.12874)
		(mid 137.594594 -273.204516)
		(end 137.311892 -273.12874)
		(width 0.088646)
		(layer "In2.Cu")
		(net "M_E_CPU1_SA_DQS_DP<1>")
	)
	(arc
		(start 135.432546 -273.12874)
		(mid 135.245348 -273.078597)
		(end 135.05815 -273.12874)
		(width 0.088646)
		(layer "In2.Cu")
		(net "M_E_CPU1_SA_DQS_DP<1>")
	)
	(arc
		(start 139.26947 -273.188176)
		(mid 139.232691 -273.155792)
		(end 139.192 -273.128486)
		(width 0.088646)
		(layer "In2.Cu")
		(net "M_E_CPU1_SA_DQS_DP<1>")
	)
	(arc
		(start 137.311892 -273.12874)
		(mid 137.124694 -273.078597)
		(end 136.937496 -273.12874)
		(width 0.088646)
		(layer "In2.Cu")
		(net "M_E_CPU1_SA_DQS_DP<1>")
	)
	(arc
		(start 136.372092 -273.12874)
		(mid 136.184894 -273.078597)
		(end 135.997696 -273.12874)
		(width 0.088646)
		(layer "In2.Cu")
		(net "M_E_CPU1_SA_DQS_DP<1>")
	)
	(arc
		(start 135.05815 -273.12874)
		(mid 134.783951 -273.204575)
		(end 134.507478 -273.137376)
		(width 0.088646)
		(layer "In2.Cu")
		(net "M_E_CPU1_SA_DQS_DP<1>")
	)
	(arc
		(start 138.816588 -273.128486)
		(mid 138.534169 -273.204296)
		(end 138.251692 -273.12874)
		(width 0.088646)
		(layer "In2.Cu")
		(net "M_E_CPU1_SA_DQS_DP<1>")
	)
	(segment
		(start 139.32916 -277.335488)
		(end 139.692126 -277.698454)
		(width 0.1524)
		(layer "F.Cu")
		(net "M_E_CPU1_SA_DQS_DP<0>")
	)
	(segment
		(start 159.933894 -312.676032)
		(end 159.643064 -312.676032)
		(width 0.20066)
		(layer "F.Cu")
		(net "M_E_CPU1_SA_DQS_DP<0>")
	)
	(segment
		(start 140.904214 -296.264076)
		(end 141.08303 -296.598594)
		(width 0.1524)
		(layer "F.Cu")
		(net "M_E_CPU1_SA_DQS_DP<0>")
	)
	(segment
		(start 166.357046 -312.91657)
		(end 165.914578 -312.91657)
		(width 0.20066)
		(layer "F.Cu")
		(net "M_E_CPU1_SA_DQS_DP<0>")
	)
	(segment
		(start 139.069572 -276.831044)
		(end 139.069572 -277.030688)
		(width 0.088646)
		(layer "F.Cu")
		(net "M_E_CPU1_SA_DQS_DP<0>")
	)
	(segment
		(start 161.120328 -313.09056)
		(end 160.348422 -313.09056)
		(width 0.20066)
		(layer "F.Cu")
		(net "M_E_CPU1_SA_DQS_DP<0>")
	)
	(segment
		(start 164.981128 -313.07278)
		(end 164.69741 -313.07278)
		(width 0.20066)
		(layer "F.Cu")
		(net "M_E_CPU1_SA_DQS_DP<0>")
	)
	(segment
		(start 161.891726 -313.341766)
		(end 161.371534 -313.341766)
		(width 0.20066)
		(layer "F.Cu")
		(net "M_E_CPU1_SA_DQS_DP<0>")
	)
	(segment
		(start 137.654284 -276.742906)
		(end 137.842498 -276.692868)
		(width 0.088646)
		(layer "F.Cu")
		(net "M_E_CPU1_SA_DQS_DP<0>")
	)
	(segment
		(start 165.419024 -312.634884)
		(end 164.981128 -313.07278)
		(width 0.20066)
		(layer "F.Cu")
		(net "M_E_CPU1_SA_DQS_DP<0>")
	)
	(segment
		(start 138.71194 -276.611588)
		(end 138.948414 -276.709886)
		(width 0.088646)
		(layer "F.Cu")
		(net "M_E_CPU1_SA_DQS_DP<0>")
	)
	(segment
		(start 141.324838 -296.892218)
		(end 141.351762 -296.919142)
		(width 0.1524)
		(layer "F.Cu")
		(net "M_E_CPU1_SA_DQS_DP<0>")
	)
	(segment
		(start 139.692126 -277.698454)
		(end 140.371576 -280.64587)
		(width 0.1524)
		(layer "F.Cu")
		(net "M_E_CPU1_SA_DQS_DP<0>")
	)
	(segment
		(start 137.56894 -276.890734)
		(end 137.654284 -276.742906)
		(width 0.088646)
		(layer "F.Cu")
		(net "M_E_CPU1_SA_DQS_DP<0>")
	)
	(segment
		(start 160.348422 -313.09056)
		(end 159.933894 -312.676032)
		(width 0.20066)
		(layer "F.Cu")
		(net "M_E_CPU1_SA_DQS_DP<0>")
	)
	(segment
		(start 161.371534 -313.341766)
		(end 161.120328 -313.09056)
		(width 0.20066)
		(layer "F.Cu")
		(net "M_E_CPU1_SA_DQS_DP<0>")
	)
	(segment
		(start 138.534648 -276.611588)
		(end 138.71194 -276.611588)
		(width 0.088646)
		(layer "F.Cu")
		(net "M_E_CPU1_SA_DQS_DP<0>")
	)
	(segment
		(start 158.238952 -312.91657)
		(end 158.813246 -312.91657)
		(width 0.20066)
		(layer "F.Cu")
		(net "M_E_CPU1_SA_DQS_DP<0>")
	)
	(segment
		(start 163.923726 -313.346592)
		(end 163.9189 -313.341766)
		(width 0.1016)
		(layer "F.Cu")
		(net "M_E_CPU1_SA_DQS_DP<0>")
	)
	(segment
		(start 165.914578 -312.91657)
		(end 165.632892 -312.634884)
		(width 0.20066)
		(layer "F.Cu")
		(net "M_E_CPU1_SA_DQS_DP<0>")
	)
	(segment
		(start 141.675612 -297.242992)
		(end 145.77822 -302.241458)
		(width 0.20066)
		(layer "F.Cu")
		(net "M_E_CPU1_SA_DQS_DP<0>")
	)
	(segment
		(start 145.77822 -302.241458)
		(end 154.704796 -311.168034)
		(width 0.20066)
		(layer "F.Cu")
		(net "M_E_CPU1_SA_DQS_DP<0>")
	)
	(segment
		(start 159.643064 -312.676032)
		(end 159.402526 -312.91657)
		(width 0.20066)
		(layer "F.Cu")
		(net "M_E_CPU1_SA_DQS_DP<0>")
	)
	(segment
		(start 137.594594 -276.986492)
		(end 137.56894 -276.890734)
		(width 0.088646)
		(layer "F.Cu")
		(net "M_E_CPU1_SA_DQS_DP<0>")
	)
	(segment
		(start 154.704796 -311.168034)
		(end 156.435298 -312.323734)
		(width 0.20066)
		(layer "F.Cu")
		(net "M_E_CPU1_SA_DQS_DP<0>")
	)
	(segment
		(start 161.896552 -313.341766)
		(end 161.891726 -313.341766)
		(width 0.101854)
		(layer "F.Cu")
		(net "M_E_CPU1_SA_DQS_DP<0>")
	)
	(segment
		(start 141.08303 -296.598594)
		(end 141.324838 -296.840402)
		(width 0.1524)
		(layer "F.Cu")
		(net "M_E_CPU1_SA_DQS_DP<0>")
	)
	(segment
		(start 140.371576 -293.588694)
		(end 140.904214 -296.264076)
		(width 0.1524)
		(layer "F.Cu")
		(net "M_E_CPU1_SA_DQS_DP<0>")
	)
	(segment
		(start 139.069572 -277.030688)
		(end 139.313666 -277.274782)
		(width 0.088646)
		(layer "F.Cu")
		(net "M_E_CPU1_SA_DQS_DP<0>")
	)
	(segment
		(start 163.924488 -313.347354)
		(end 163.923726 -313.346592)
		(width 0.20066)
		(layer "F.Cu")
		(net "M_E_CPU1_SA_DQS_DP<0>")
	)
	(segment
		(start 164.422836 -313.347354)
		(end 163.924488 -313.347354)
		(width 0.20066)
		(layer "F.Cu")
		(net "M_E_CPU1_SA_DQS_DP<0>")
	)
	(segment
		(start 163.9189 -313.341766)
		(end 161.896552 -313.341766)
		(width 0.1016)
		(layer "F.Cu")
		(net "M_E_CPU1_SA_DQS_DP<0>")
	)
	(segment
		(start 139.313666 -277.319994)
		(end 139.32916 -277.335488)
		(width 0.088646)
		(layer "F.Cu")
		(net "M_E_CPU1_SA_DQS_DP<0>")
	)
	(segment
		(start 157.099 -312.623962)
		(end 157.946344 -312.623962)
		(width 0.20066)
		(layer "F.Cu")
		(net "M_E_CPU1_SA_DQS_DP<0>")
	)
	(segment
		(start 141.324838 -296.840402)
		(end 141.324838 -296.892218)
		(width 0.1524)
		(layer "F.Cu")
		(net "M_E_CPU1_SA_DQS_DP<0>")
	)
	(segment
		(start 138.948414 -276.709886)
		(end 139.069572 -276.831044)
		(width 0.088646)
		(layer "F.Cu")
		(net "M_E_CPU1_SA_DQS_DP<0>")
	)
	(segment
		(start 139.313666 -277.274782)
		(end 139.313666 -277.319994)
		(width 0.088646)
		(layer "F.Cu")
		(net "M_E_CPU1_SA_DQS_DP<0>")
	)
	(segment
		(start 157.946344 -312.623962)
		(end 158.238952 -312.91657)
		(width 0.20066)
		(layer "F.Cu")
		(net "M_E_CPU1_SA_DQS_DP<0>")
	)
	(segment
		(start 141.351762 -296.919142)
		(end 141.675612 -297.242992)
		(width 0.20066)
		(layer "F.Cu")
		(net "M_E_CPU1_SA_DQS_DP<0>")
	)
	(segment
		(start 159.402526 -312.91657)
		(end 158.813246 -312.91657)
		(width 0.20066)
		(layer "F.Cu")
		(net "M_E_CPU1_SA_DQS_DP<0>")
	)
	(segment
		(start 164.69741 -313.07278)
		(end 164.422836 -313.347354)
		(width 0.20066)
		(layer "F.Cu")
		(net "M_E_CPU1_SA_DQS_DP<0>")
	)
	(segment
		(start 140.371576 -280.64587)
		(end 140.371576 -293.588694)
		(width 0.1524)
		(layer "F.Cu")
		(net "M_E_CPU1_SA_DQS_DP<0>")
	)
	(segment
		(start 156.435298 -312.323734)
		(end 157.099 -312.623962)
		(width 0.20066)
		(layer "F.Cu")
		(net "M_E_CPU1_SA_DQS_DP<0>")
	)
	(segment
		(start 165.632892 -312.634884)
		(end 165.419024 -312.634884)
		(width 0.20066)
		(layer "F.Cu")
		(net "M_E_CPU1_SA_DQS_DP<0>")
	)
	(arc
		(start 137.842498 -276.692868)
		(mid 137.852744 -276.697158)
		(end 137.863072 -276.70125)
		(width 0.088646)
		(layer "F.Cu")
		(net "M_E_CPU1_SA_DQS_DP<0>")
	)
	(arc
		(start 137.863072 -276.70125)
		(mid 138.109687 -276.736424)
		(end 138.34745 -276.662134)
		(width 0.088646)
		(layer "F.Cu")
		(net "M_E_CPU1_SA_DQS_DP<0>")
	)
	(arc
		(start 138.512804 -276.61235)
		(mid 138.523721 -276.611813)
		(end 138.534648 -276.611588)
		(width 0.088646)
		(layer "F.Cu")
		(net "M_E_CPU1_SA_DQS_DP<0>")
	)
	(arc
		(start 138.34745 -276.662134)
		(mid 138.42722 -276.627592)
		(end 138.512804 -276.61235)
		(width 0.088646)
		(layer "F.Cu")
		(net "M_E_CPU1_SA_DQS_DP<0>")
	)
	(segment
		(start 139.094718 -259.712714)
		(end 139.187428 -259.712714)
		(width 0.088646)
		(layer "F.Cu")
		(net "M_E_CPU1_SA_DQS_DN<9>")
	)
	(segment
		(start 140.335508 -260.43128)
		(end 140.479272 -260.575044)
		(width 0.088646)
		(layer "F.Cu")
		(net "M_E_CPU1_SA_DQS_DN<9>")
	)
	(segment
		(start 159.80283 -274.241514)
		(end 159.941006 -274.241514)
		(width 0.101854)
		(layer "F.Cu")
		(net "M_E_CPU1_SA_DQS_DN<9>")
	)
	(segment
		(start 164.852604 -274.241768)
		(end 164.594794 -273.983958)
		(width 0.20066)
		(layer "F.Cu")
		(net "M_E_CPU1_SA_DQS_DN<9>")
	)
	(segment
		(start 157.196282 -274.241514)
		(end 157.515052 -274.241514)
		(width 0.20066)
		(layer "F.Cu")
		(net "M_E_CPU1_SA_DQS_DN<9>")
	)
	(segment
		(start 169.692574 -274.405852)
		(end 169.071544 -274.405852)
		(width 0.20066)
		(layer "F.Cu")
		(net "M_E_CPU1_SA_DQS_DN<9>")
	)
	(segment
		(start 153.282904 -273.994118)
		(end 153.321004 -273.994118)
		(width 0.1524)
		(layer "F.Cu")
		(net "M_E_CPU1_SA_DQS_DN<9>")
	)
	(segment
		(start 167.871394 -274.241768)
		(end 167.786812 -274.241768)
		(width 0.20066)
		(layer "F.Cu")
		(net "M_E_CPU1_SA_DQS_DN<9>")
	)
	(segment
		(start 139.187682 -259.71246)
		(end 139.760706 -259.71246)
		(width 0.088646)
		(layer "F.Cu")
		(net "M_E_CPU1_SA_DQS_DN<9>")
	)
	(segment
		(start 160.415478 -273.99615)
		(end 160.680654 -273.99615)
		(width 0.20066)
		(layer "F.Cu")
		(net "M_E_CPU1_SA_DQS_DN<9>")
	)
	(segment
		(start 140.04798 -260.143752)
		(end 140.191998 -260.143752)
		(width 0.088646)
		(layer "F.Cu")
		(net "M_E_CPU1_SA_DQS_DN<9>")
	)
	(segment
		(start 140.7668 -260.718554)
		(end 140.7668 -260.862572)
		(width 0.088646)
		(layer "F.Cu")
		(net "M_E_CPU1_SA_DQS_DN<9>")
	)
	(segment
		(start 157.070298 -274.11553)
		(end 157.196282 -274.241514)
		(width 0.20066)
		(layer "F.Cu")
		(net "M_E_CPU1_SA_DQS_DN<9>")
	)
	(segment
		(start 164.977572 -274.241768)
		(end 164.852604 -274.241768)
		(width 0.20066)
		(layer "F.Cu")
		(net "M_E_CPU1_SA_DQS_DN<9>")
	)
	(segment
		(start 156.285438 -273.994118)
		(end 156.56052 -273.719036)
		(width 0.20066)
		(layer "F.Cu")
		(net "M_E_CPU1_SA_DQS_DN<9>")
	)
	(segment
		(start 139.760706 -259.71246)
		(end 139.904216 -259.85597)
		(width 0.088646)
		(layer "F.Cu")
		(net "M_E_CPU1_SA_DQS_DN<9>")
	)
	(segment
		(start 161.079688 -274.395184)
		(end 162.13582 -274.395184)
		(width 0.20066)
		(layer "F.Cu")
		(net "M_E_CPU1_SA_DQS_DN<9>")
	)
	(segment
		(start 142.027402 -262.024368)
		(end 142.042896 -262.039862)
		(width 0.088646)
		(layer "F.Cu")
		(net "M_E_CPU1_SA_DQS_DN<9>")
	)
	(segment
		(start 138.993626 -259.813806)
		(end 139.094718 -259.712714)
		(width 0.088646)
		(layer "F.Cu")
		(net "M_E_CPU1_SA_DQS_DN<9>")
	)
	(segment
		(start 157.796484 -274.241514)
		(end 159.80283 -274.241514)
		(width 0.1016)
		(layer "F.Cu")
		(net "M_E_CPU1_SA_DQS_DN<9>")
	)
	(segment
		(start 163.319968 -274.66671)
		(end 162.913314 -274.66671)
		(width 0.20066)
		(layer "F.Cu")
		(net "M_E_CPU1_SA_DQS_DN<9>")
	)
	(segment
		(start 169.071544 -274.405852)
		(end 168.632632 -273.96694)
		(width 0.20066)
		(layer "F.Cu")
		(net "M_E_CPU1_SA_DQS_DN<9>")
	)
	(segment
		(start 169.953432 -274.66671)
		(end 169.692574 -274.405852)
		(width 0.20066)
		(layer "F.Cu")
		(net "M_E_CPU1_SA_DQS_DN<9>")
	)
	(segment
		(start 140.479272 -260.575044)
		(end 140.62329 -260.575044)
		(width 0.088646)
		(layer "F.Cu")
		(net "M_E_CPU1_SA_DQS_DN<9>")
	)
	(segment
		(start 157.070298 -273.818604)
		(end 157.070298 -274.11553)
		(width 0.20066)
		(layer "F.Cu")
		(net "M_E_CPU1_SA_DQS_DN<9>")
	)
	(segment
		(start 159.941006 -274.241514)
		(end 159.959294 -274.259802)
		(width 0.101854)
		(layer "F.Cu")
		(net "M_E_CPU1_SA_DQS_DN<9>")
	)
	(segment
		(start 168.146222 -273.96694)
		(end 167.871394 -274.241768)
		(width 0.20066)
		(layer "F.Cu")
		(net "M_E_CPU1_SA_DQS_DN<9>")
	)
	(segment
		(start 141.261084 -261.356856)
		(end 141.40434 -261.356856)
		(width 0.088646)
		(layer "F.Cu")
		(net "M_E_CPU1_SA_DQS_DN<9>")
	)
	(segment
		(start 140.62329 -260.575044)
		(end 140.7668 -260.718554)
		(width 0.088646)
		(layer "F.Cu")
		(net "M_E_CPU1_SA_DQS_DN<9>")
	)
	(segment
		(start 141.40434 -261.356856)
		(end 142.028164 -261.978902)
		(width 0.088646)
		(layer "F.Cu")
		(net "M_E_CPU1_SA_DQS_DN<9>")
	)
	(segment
		(start 142.042896 -262.039862)
		(end 151.216868 -271.213834)
		(width 0.1524)
		(layer "F.Cu")
		(net "M_E_CPU1_SA_DQS_DN<9>")
	)
	(segment
		(start 141.16431 -261.116064)
		(end 141.16431 -261.260082)
		(width 0.088646)
		(layer "F.Cu")
		(net "M_E_CPU1_SA_DQS_DN<9>")
	)
	(segment
		(start 164.172392 -274.127976)
		(end 163.90493 -274.395438)
		(width 0.20066)
		(layer "F.Cu")
		(net "M_E_CPU1_SA_DQS_DN<9>")
	)
	(segment
		(start 139.004294 -259.894832)
		(end 138.993626 -259.884164)
		(width 0.088646)
		(layer "F.Cu")
		(net "M_E_CPU1_SA_DQS_DN<9>")
	)
	(segment
		(start 164.594794 -273.983958)
		(end 164.519864 -273.983958)
		(width 0.20066)
		(layer "F.Cu")
		(net "M_E_CPU1_SA_DQS_DN<9>")
	)
	(segment
		(start 157.515052 -274.241514)
		(end 157.796484 -274.241514)
		(width 0.101854)
		(layer "F.Cu")
		(net "M_E_CPU1_SA_DQS_DN<9>")
	)
	(segment
		(start 165.34638 -274.241768)
		(end 164.977572 -274.241768)
		(width 0.101854)
		(layer "F.Cu")
		(net "M_E_CPU1_SA_DQS_DN<9>")
	)
	(segment
		(start 138.993626 -259.884164)
		(end 138.993626 -259.813806)
		(width 0.088646)
		(layer "F.Cu")
		(net "M_E_CPU1_SA_DQS_DN<9>")
	)
	(segment
		(start 139.904216 -259.85597)
		(end 139.904216 -259.999988)
		(width 0.088646)
		(layer "F.Cu")
		(net "M_E_CPU1_SA_DQS_DN<9>")
	)
	(segment
		(start 153.246074 -273.957288)
		(end 153.282904 -273.994118)
		(width 0.1524)
		(layer "F.Cu")
		(net "M_E_CPU1_SA_DQS_DN<9>")
	)
	(segment
		(start 162.13582 -274.395184)
		(end 162.407346 -274.66671)
		(width 0.20066)
		(layer "F.Cu")
		(net "M_E_CPU1_SA_DQS_DN<9>")
	)
	(segment
		(start 160.680654 -273.99615)
		(end 161.079688 -274.395184)
		(width 0.20066)
		(layer "F.Cu")
		(net "M_E_CPU1_SA_DQS_DN<9>")
	)
	(segment
		(start 141.054582 -261.006336)
		(end 141.16431 -261.116064)
		(width 0.088646)
		(layer "F.Cu")
		(net "M_E_CPU1_SA_DQS_DN<9>")
	)
	(segment
		(start 164.519864 -273.983958)
		(end 164.172392 -274.127976)
		(width 0.20066)
		(layer "F.Cu")
		(net "M_E_CPU1_SA_DQS_DN<9>")
	)
	(segment
		(start 151.216868 -271.213834)
		(end 151.5872 -273.067526)
		(width 0.1524)
		(layer "F.Cu")
		(net "M_E_CPU1_SA_DQS_DN<9>")
	)
	(segment
		(start 163.90493 -274.395438)
		(end 163.59124 -274.395438)
		(width 0.20066)
		(layer "F.Cu")
		(net "M_E_CPU1_SA_DQS_DN<9>")
	)
	(segment
		(start 140.191998 -260.143752)
		(end 140.335508 -260.287262)
		(width 0.088646)
		(layer "F.Cu")
		(net "M_E_CPU1_SA_DQS_DN<9>")
	)
	(segment
		(start 168.632632 -273.96694)
		(end 168.146222 -273.96694)
		(width 0.20066)
		(layer "F.Cu")
		(net "M_E_CPU1_SA_DQS_DN<9>")
	)
	(segment
		(start 159.959294 -274.259802)
		(end 160.151826 -274.259802)
		(width 0.20066)
		(layer "F.Cu")
		(net "M_E_CPU1_SA_DQS_DN<9>")
	)
	(segment
		(start 139.187428 -259.712714)
		(end 139.187682 -259.71246)
		(width 0.088646)
		(layer "F.Cu")
		(net "M_E_CPU1_SA_DQS_DN<9>")
	)
	(segment
		(start 163.59124 -274.395438)
		(end 163.319968 -274.66671)
		(width 0.20066)
		(layer "F.Cu")
		(net "M_E_CPU1_SA_DQS_DN<9>")
	)
	(segment
		(start 170.457114 -274.66671)
		(end 169.953432 -274.66671)
		(width 0.20066)
		(layer "F.Cu")
		(net "M_E_CPU1_SA_DQS_DN<9>")
	)
	(segment
		(start 140.910564 -261.006336)
		(end 141.054582 -261.006336)
		(width 0.088646)
		(layer "F.Cu")
		(net "M_E_CPU1_SA_DQS_DN<9>")
	)
	(segment
		(start 139.904216 -259.999988)
		(end 140.04798 -260.143752)
		(width 0.088646)
		(layer "F.Cu")
		(net "M_E_CPU1_SA_DQS_DN<9>")
	)
	(segment
		(start 151.98217 -273.657314)
		(end 152.54351 -273.957288)
		(width 0.1524)
		(layer "F.Cu")
		(net "M_E_CPU1_SA_DQS_DN<9>")
	)
	(segment
		(start 140.7668 -260.862572)
		(end 140.910564 -261.006336)
		(width 0.088646)
		(layer "F.Cu")
		(net "M_E_CPU1_SA_DQS_DN<9>")
	)
	(segment
		(start 167.356536 -274.241768)
		(end 165.34638 -274.241768)
		(width 0.1016)
		(layer "F.Cu")
		(net "M_E_CPU1_SA_DQS_DN<9>")
	)
	(segment
		(start 142.028164 -261.978902)
		(end 142.027402 -262.024368)
		(width 0.088646)
		(layer "F.Cu")
		(net "M_E_CPU1_SA_DQS_DN<9>")
	)
	(segment
		(start 153.321004 -273.994118)
		(end 156.285438 -273.994118)
		(width 0.20066)
		(layer "F.Cu")
		(net "M_E_CPU1_SA_DQS_DN<9>")
	)
	(segment
		(start 156.97073 -273.719036)
		(end 157.070298 -273.818604)
		(width 0.20066)
		(layer "F.Cu")
		(net "M_E_CPU1_SA_DQS_DN<9>")
	)
	(segment
		(start 160.151826 -274.259802)
		(end 160.415478 -273.99615)
		(width 0.20066)
		(layer "F.Cu")
		(net "M_E_CPU1_SA_DQS_DN<9>")
	)
	(segment
		(start 167.786812 -274.241768)
		(end 167.356536 -274.241768)
		(width 0.101854)
		(layer "F.Cu")
		(net "M_E_CPU1_SA_DQS_DN<9>")
	)
	(segment
		(start 151.5872 -273.067526)
		(end 151.98217 -273.657314)
		(width 0.1524)
		(layer "F.Cu")
		(net "M_E_CPU1_SA_DQS_DN<9>")
	)
	(segment
		(start 162.407346 -274.66671)
		(end 162.913314 -274.66671)
		(width 0.20066)
		(layer "F.Cu")
		(net "M_E_CPU1_SA_DQS_DN<9>")
	)
	(segment
		(start 156.56052 -273.719036)
		(end 156.97073 -273.719036)
		(width 0.20066)
		(layer "F.Cu")
		(net "M_E_CPU1_SA_DQS_DN<9>")
	)
	(segment
		(start 152.54351 -273.957288)
		(end 153.246074 -273.957288)
		(width 0.1524)
		(layer "F.Cu")
		(net "M_E_CPU1_SA_DQS_DN<9>")
	)
	(segment
		(start 141.16431 -261.260082)
		(end 141.261084 -261.356856)
		(width 0.088646)
		(layer "F.Cu")
		(net "M_E_CPU1_SA_DQS_DN<9>")
	)
	(segment
		(start 140.335508 -260.287262)
		(end 140.335508 -260.43128)
		(width 0.088646)
		(layer "F.Cu")
		(net "M_E_CPU1_SA_DQS_DN<9>")
	)
	(segment
		(start 156.529532 -283.06903)
		(end 156.894276 -283.06903)
		(width 0.20066)
		(layer "F.Cu")
		(net "M_E_CPU1_SA_DQS_DN<8>")
	)
	(segment
		(start 140.045694 -265.501374)
		(end 140.045694 -265.642344)
		(width 0.088646)
		(layer "F.Cu")
		(net "M_E_CPU1_SA_DQS_DN<8>")
	)
	(segment
		(start 157.064456 -283.418026)
		(end 157.265116 -283.618686)
		(width 0.20066)
		(layer "F.Cu")
		(net "M_E_CPU1_SA_DQS_DN<8>")
	)
	(segment
		(start 159.805624 -283.591508)
		(end 159.823658 -283.609542)
		(width 0.1016)
		(layer "F.Cu")
		(net "M_E_CPU1_SA_DQS_DN<8>")
	)
	(segment
		(start 165.340284 -283.597858)
		(end 165.335458 -283.597858)
		(width 0.101854)
		(layer "F.Cu")
		(net "M_E_CPU1_SA_DQS_DN<8>")
	)
	(segment
		(start 157.064456 -283.23921)
		(end 157.064456 -283.418026)
		(width 0.20066)
		(layer "F.Cu")
		(net "M_E_CPU1_SA_DQS_DN<8>")
	)
	(segment
		(start 155.875228 -283.899356)
		(end 156.301186 -283.473398)
		(width 0.20066)
		(layer "F.Cu")
		(net "M_E_CPU1_SA_DQS_DN<8>")
	)
	(segment
		(start 149.330156 -280.78684)
		(end 149.594316 -281.142694)
		(width 0.1524)
		(layer "F.Cu")
		(net "M_E_CPU1_SA_DQS_DN<8>")
	)
	(segment
		(start 139.798298 -265.39444)
		(end 139.93876 -265.39444)
		(width 0.088646)
		(layer "F.Cu")
		(net "M_E_CPU1_SA_DQS_DN<8>")
	)
	(segment
		(start 139.690602 -265.146282)
		(end 139.690602 -265.28649)
		(width 0.088646)
		(layer "F.Cu")
		(net "M_E_CPU1_SA_DQS_DN<8>")
	)
	(segment
		(start 161.738564 -283.693362)
		(end 162.084004 -283.693362)
		(width 0.20066)
		(layer "F.Cu")
		(net "M_E_CPU1_SA_DQS_DN<8>")
	)
	(segment
		(start 140.045694 -265.642344)
		(end 140.154152 -265.750294)
		(width 0.088646)
		(layer "F.Cu")
		(net "M_E_CPU1_SA_DQS_DN<8>")
	)
	(segment
		(start 149.752558 -281.353006)
		(end 149.778974 -281.379422)
		(width 0.1524)
		(layer "F.Cu")
		(net "M_E_CPU1_SA_DQS_DN<8>")
	)
	(segment
		(start 139.93876 -265.39444)
		(end 140.045694 -265.501374)
		(width 0.088646)
		(layer "F.Cu")
		(net "M_E_CPU1_SA_DQS_DN<8>")
	)
	(segment
		(start 139.582906 -265.038586)
		(end 139.690602 -265.146282)
		(width 0.088646)
		(layer "F.Cu")
		(net "M_E_CPU1_SA_DQS_DN<8>")
	)
	(segment
		(start 156.301186 -283.297376)
		(end 156.529532 -283.06903)
		(width 0.20066)
		(layer "F.Cu")
		(net "M_E_CPU1_SA_DQS_DN<8>")
	)
	(segment
		(start 165.34638 -283.591762)
		(end 165.340284 -283.597858)
		(width 0.1016)
		(layer "F.Cu")
		(net "M_E_CPU1_SA_DQS_DN<8>")
	)
	(segment
		(start 153.806906 -284.359858)
		(end 154.408886 -284.359858)
		(width 0.20066)
		(layer "F.Cu")
		(net "M_E_CPU1_SA_DQS_DN<8>")
	)
	(segment
		(start 160.635442 -283.346144)
		(end 160.900872 -283.346144)
		(width 0.20066)
		(layer "F.Cu")
		(net "M_E_CPU1_SA_DQS_DN<8>")
	)
	(segment
		(start 147.495514 -272.996152)
		(end 148.88845 -279.960832)
		(width 0.1524)
		(layer "F.Cu")
		(net "M_E_CPU1_SA_DQS_DN<8>")
	)
	(segment
		(start 167.367458 -283.602684)
		(end 167.356536 -283.591762)
		(width 0.1016)
		(layer "F.Cu")
		(net "M_E_CPU1_SA_DQS_DN<8>")
	)
	(segment
		(start 140.812012 -266.31265)
		(end 140.827506 -266.328144)
		(width 0.088646)
		(layer "F.Cu")
		(net "M_E_CPU1_SA_DQS_DN<8>")
	)
	(segment
		(start 139.004294 -264.763504)
		(end 139.093194 -264.674604)
		(width 0.088646)
		(layer "F.Cu")
		(net "M_E_CPU1_SA_DQS_DN<8>")
	)
	(segment
		(start 139.218924 -264.674604)
		(end 139.334748 -264.790428)
		(width 0.088646)
		(layer "F.Cu")
		(net "M_E_CPU1_SA_DQS_DN<8>")
	)
	(segment
		(start 167.356536 -283.591762)
		(end 165.34638 -283.591762)
		(width 0.1016)
		(layer "F.Cu")
		(net "M_E_CPU1_SA_DQS_DN<8>")
	)
	(segment
		(start 168.461944 -283.316934)
		(end 167.971978 -283.316934)
		(width 0.20066)
		(layer "F.Cu")
		(net "M_E_CPU1_SA_DQS_DN<8>")
	)
	(segment
		(start 170.457114 -284.016704)
		(end 169.953432 -284.016704)
		(width 0.20066)
		(layer "F.Cu")
		(net "M_E_CPU1_SA_DQS_DN<8>")
	)
	(segment
		(start 164.623496 -283.32049)
		(end 164.198554 -283.745432)
		(width 0.20066)
		(layer "F.Cu")
		(net "M_E_CPU1_SA_DQS_DN<8>")
	)
	(segment
		(start 169.699178 -283.76245)
		(end 168.90746 -283.76245)
		(width 0.20066)
		(layer "F.Cu")
		(net "M_E_CPU1_SA_DQS_DN<8>")
	)
	(segment
		(start 139.334748 -264.930636)
		(end 139.442444 -265.038586)
		(width 0.088646)
		(layer "F.Cu")
		(net "M_E_CPU1_SA_DQS_DN<8>")
	)
	(segment
		(start 153.682446 -284.235398)
		(end 153.806906 -284.359858)
		(width 0.20066)
		(layer "F.Cu")
		(net "M_E_CPU1_SA_DQS_DN<8>")
	)
	(segment
		(start 139.093194 -264.674604)
		(end 139.218924 -264.674604)
		(width 0.088646)
		(layer "F.Cu")
		(net "M_E_CPU1_SA_DQS_DN<8>")
	)
	(segment
		(start 148.88845 -279.960832)
		(end 149.330156 -280.78684)
		(width 0.1524)
		(layer "F.Cu")
		(net "M_E_CPU1_SA_DQS_DN<8>")
	)
	(segment
		(start 154.408886 -284.359858)
		(end 154.533346 -284.235398)
		(width 0.20066)
		(layer "F.Cu")
		(net "M_E_CPU1_SA_DQS_DN<8>")
	)
	(segment
		(start 152.096978 -283.697426)
		(end 152.737058 -284.125416)
		(width 0.20066)
		(layer "F.Cu")
		(net "M_E_CPU1_SA_DQS_DN<8>")
	)
	(segment
		(start 149.752558 -281.300936)
		(end 149.752558 -281.353006)
		(width 0.1524)
		(layer "F.Cu")
		(net "M_E_CPU1_SA_DQS_DN<8>")
	)
	(segment
		(start 167.971978 -283.316934)
		(end 167.686228 -283.602684)
		(width 0.20066)
		(layer "F.Cu")
		(net "M_E_CPU1_SA_DQS_DN<8>")
	)
	(segment
		(start 154.533346 -284.235398)
		(end 155.154122 -284.235398)
		(width 0.20066)
		(layer "F.Cu")
		(net "M_E_CPU1_SA_DQS_DN<8>")
	)
	(segment
		(start 168.90746 -283.76245)
		(end 168.461944 -283.316934)
		(width 0.20066)
		(layer "F.Cu")
		(net "M_E_CPU1_SA_DQS_DN<8>")
	)
	(segment
		(start 149.594316 -281.142694)
		(end 149.752558 -281.300936)
		(width 0.1524)
		(layer "F.Cu")
		(net "M_E_CPU1_SA_DQS_DN<8>")
	)
	(segment
		(start 164.745924 -283.32049)
		(end 164.623496 -283.32049)
		(width 0.20066)
		(layer "F.Cu")
		(net "M_E_CPU1_SA_DQS_DN<8>")
	)
	(segment
		(start 152.737058 -284.125416)
		(end 153.00325 -284.235398)
		(width 0.20066)
		(layer "F.Cu")
		(net "M_E_CPU1_SA_DQS_DN<8>")
	)
	(segment
		(start 140.827506 -266.328144)
		(end 147.495514 -272.996152)
		(width 0.1524)
		(layer "F.Cu")
		(net "M_E_CPU1_SA_DQS_DN<8>")
	)
	(segment
		(start 139.690602 -265.28649)
		(end 139.798298 -265.39444)
		(width 0.088646)
		(layer "F.Cu")
		(net "M_E_CPU1_SA_DQS_DN<8>")
	)
	(segment
		(start 155.510992 -284.08757)
		(end 155.699206 -283.899356)
		(width 0.20066)
		(layer "F.Cu")
		(net "M_E_CPU1_SA_DQS_DN<8>")
	)
	(segment
		(start 139.442444 -265.038586)
		(end 139.582906 -265.038586)
		(width 0.088646)
		(layer "F.Cu")
		(net "M_E_CPU1_SA_DQS_DN<8>")
	)
	(segment
		(start 164.198554 -283.745432)
		(end 163.715192 -283.745432)
		(width 0.20066)
		(layer "F.Cu")
		(net "M_E_CPU1_SA_DQS_DN<8>")
	)
	(segment
		(start 157.791658 -283.618686)
		(end 157.818836 -283.591508)
		(width 0.1016)
		(layer "F.Cu")
		(net "M_E_CPU1_SA_DQS_DN<8>")
	)
	(segment
		(start 139.004294 -264.778236)
		(end 139.004294 -264.763504)
		(width 0.088646)
		(layer "F.Cu")
		(net "M_E_CPU1_SA_DQS_DN<8>")
	)
	(segment
		(start 156.301186 -283.473398)
		(end 156.301186 -283.297376)
		(width 0.20066)
		(layer "F.Cu")
		(net "M_E_CPU1_SA_DQS_DN<8>")
	)
	(segment
		(start 165.023292 -283.597858)
		(end 164.745924 -283.32049)
		(width 0.20066)
		(layer "F.Cu")
		(net "M_E_CPU1_SA_DQS_DN<8>")
	)
	(segment
		(start 160.372044 -283.609542)
		(end 160.635442 -283.346144)
		(width 0.20066)
		(layer "F.Cu")
		(net "M_E_CPU1_SA_DQS_DN<8>")
	)
	(segment
		(start 140.154152 -265.750294)
		(end 140.294868 -265.750294)
		(width 0.088646)
		(layer "F.Cu")
		(net "M_E_CPU1_SA_DQS_DN<8>")
	)
	(segment
		(start 155.154122 -284.235398)
		(end 155.510992 -284.08757)
		(width 0.20066)
		(layer "F.Cu")
		(net "M_E_CPU1_SA_DQS_DN<8>")
	)
	(segment
		(start 163.715192 -283.745432)
		(end 163.44392 -284.016704)
		(width 0.20066)
		(layer "F.Cu")
		(net "M_E_CPU1_SA_DQS_DN<8>")
	)
	(segment
		(start 159.823658 -283.609542)
		(end 160.372044 -283.609542)
		(width 0.20066)
		(layer "F.Cu")
		(net "M_E_CPU1_SA_DQS_DN<8>")
	)
	(segment
		(start 162.407346 -284.016704)
		(end 162.913314 -284.016704)
		(width 0.20066)
		(layer "F.Cu")
		(net "M_E_CPU1_SA_DQS_DN<8>")
	)
	(segment
		(start 140.294868 -265.750294)
		(end 140.812012 -266.267438)
		(width 0.088646)
		(layer "F.Cu")
		(net "M_E_CPU1_SA_DQS_DN<8>")
	)
	(segment
		(start 165.335458 -283.597858)
		(end 165.023292 -283.597858)
		(width 0.20066)
		(layer "F.Cu")
		(net "M_E_CPU1_SA_DQS_DN<8>")
	)
	(segment
		(start 139.334748 -264.790428)
		(end 139.334748 -264.930636)
		(width 0.088646)
		(layer "F.Cu")
		(net "M_E_CPU1_SA_DQS_DN<8>")
	)
	(segment
		(start 157.818836 -283.591508)
		(end 159.805624 -283.591508)
		(width 0.1016)
		(layer "F.Cu")
		(net "M_E_CPU1_SA_DQS_DN<8>")
	)
	(segment
		(start 155.699206 -283.899356)
		(end 155.875228 -283.899356)
		(width 0.20066)
		(layer "F.Cu")
		(net "M_E_CPU1_SA_DQS_DN<8>")
	)
	(segment
		(start 163.44392 -284.016704)
		(end 162.913314 -284.016704)
		(width 0.20066)
		(layer "F.Cu")
		(net "M_E_CPU1_SA_DQS_DN<8>")
	)
	(segment
		(start 149.778974 -281.379422)
		(end 152.096978 -283.697426)
		(width 0.20066)
		(layer "F.Cu")
		(net "M_E_CPU1_SA_DQS_DN<8>")
	)
	(segment
		(start 167.686228 -283.602684)
		(end 167.367458 -283.602684)
		(width 0.20066)
		(layer "F.Cu")
		(net "M_E_CPU1_SA_DQS_DN<8>")
	)
	(segment
		(start 140.812012 -266.267438)
		(end 140.812012 -266.31265)
		(width 0.088646)
		(layer "F.Cu")
		(net "M_E_CPU1_SA_DQS_DN<8>")
	)
	(segment
		(start 162.084004 -283.693362)
		(end 162.407346 -284.016704)
		(width 0.20066)
		(layer "F.Cu")
		(net "M_E_CPU1_SA_DQS_DN<8>")
	)
	(segment
		(start 160.900872 -283.346144)
		(end 161.738564 -283.693362)
		(width 0.20066)
		(layer "F.Cu")
		(net "M_E_CPU1_SA_DQS_DN<8>")
	)
	(segment
		(start 156.894276 -283.06903)
		(end 157.064456 -283.23921)
		(width 0.20066)
		(layer "F.Cu")
		(net "M_E_CPU1_SA_DQS_DN<8>")
	)
	(segment
		(start 169.953432 -284.016704)
		(end 169.699178 -283.76245)
		(width 0.20066)
		(layer "F.Cu")
		(net "M_E_CPU1_SA_DQS_DN<8>")
	)
	(segment
		(start 153.00325 -284.235398)
		(end 153.682446 -284.235398)
		(width 0.20066)
		(layer "F.Cu")
		(net "M_E_CPU1_SA_DQS_DN<8>")
	)
	(segment
		(start 157.265116 -283.618686)
		(end 157.791658 -283.618686)
		(width 0.20066)
		(layer "F.Cu")
		(net "M_E_CPU1_SA_DQS_DN<8>")
	)
	(segment
		(start 157.798008 -292.954456)
		(end 157.810708 -292.941756)
		(width 0.1016)
		(layer "F.Cu")
		(net "M_E_CPU1_SA_DQS_DN<7>")
	)
	(segment
		(start 162.13582 -293.095172)
		(end 162.407346 -293.366698)
		(width 0.20066)
		(layer "F.Cu")
		(net "M_E_CPU1_SA_DQS_DN<7>")
	)
	(segment
		(start 137.689844 -269.671546)
		(end 137.689844 -269.66164)
		(width 0.088646)
		(layer "F.Cu")
		(net "M_E_CPU1_SA_DQS_DN<7>")
	)
	(segment
		(start 168.730676 -292.935152)
		(end 168.462452 -292.666928)
		(width 0.20066)
		(layer "F.Cu")
		(net "M_E_CPU1_SA_DQS_DN<7>")
	)
	(segment
		(start 165.335458 -292.947852)
		(end 165.023292 -292.947852)
		(width 0.20066)
		(layer "F.Cu")
		(net "M_E_CPU1_SA_DQS_DN<7>")
	)
	(segment
		(start 155.28163 -294.689022)
		(end 156.482288 -293.488364)
		(width 0.20066)
		(layer "F.Cu")
		(net "M_E_CPU1_SA_DQS_DN<7>")
	)
	(segment
		(start 156.870908 -292.90645)
		(end 156.928566 -292.767258)
		(width 0.20066)
		(layer "F.Cu")
		(net "M_E_CPU1_SA_DQS_DN<7>")
	)
	(segment
		(start 155.00604 -294.873172)
		(end 155.28163 -294.689022)
		(width 0.20066)
		(layer "F.Cu")
		(net "M_E_CPU1_SA_DQS_DN<7>")
	)
	(segment
		(start 157.218126 -292.635432)
		(end 157.53715 -292.954456)
		(width 0.20066)
		(layer "F.Cu")
		(net "M_E_CPU1_SA_DQS_DN<7>")
	)
	(segment
		(start 154.729688 -295.05783)
		(end 155.00604 -294.873172)
		(width 0.20066)
		(layer "F.Cu")
		(net "M_E_CPU1_SA_DQS_DN<7>")
	)
	(segment
		(start 138.481816 -269.378684)
		(end 138.908536 -269.378684)
		(width 0.088646)
		(layer "F.Cu")
		(net "M_E_CPU1_SA_DQS_DN<7>")
	)
	(segment
		(start 165.34638 -292.941756)
		(end 165.340284 -292.947852)
		(width 0.1016)
		(layer "F.Cu")
		(net "M_E_CPU1_SA_DQS_DN<7>")
	)
	(segment
		(start 138.908536 -269.378684)
		(end 139.171934 -269.487904)
		(width 0.088646)
		(layer "F.Cu")
		(net "M_E_CPU1_SA_DQS_DN<7>")
	)
	(segment
		(start 156.928566 -292.767258)
		(end 157.060392 -292.635432)
		(width 0.20066)
		(layer "F.Cu")
		(net "M_E_CPU1_SA_DQS_DN<7>")
	)
	(segment
		(start 164.58438 -292.670484)
		(end 164.159438 -293.095426)
		(width 0.20066)
		(layer "F.Cu")
		(net "M_E_CPU1_SA_DQS_DN<7>")
	)
	(segment
		(start 140.195808 -271.277842)
		(end 140.195808 -271.323054)
		(width 0.088646)
		(layer "F.Cu")
		(net "M_E_CPU1_SA_DQS_DN<7>")
	)
	(segment
		(start 169.699178 -293.112444)
		(end 169.158666 -293.112444)
		(width 0.20066)
		(layer "F.Cu")
		(net "M_E_CPU1_SA_DQS_DN<7>")
	)
	(segment
		(start 144.94256 -280.27122)
		(end 144.94256 -288.638742)
		(width 0.1524)
		(layer "F.Cu")
		(net "M_E_CPU1_SA_DQS_DN<7>")
	)
	(segment
		(start 169.953432 -293.366698)
		(end 169.699178 -293.112444)
		(width 0.20066)
		(layer "F.Cu")
		(net "M_E_CPU1_SA_DQS_DN<7>")
	)
	(segment
		(start 159.770826 -292.941756)
		(end 159.777176 -292.948106)
		(width 0.101854)
		(layer "F.Cu")
		(net "M_E_CPU1_SA_DQS_DN<7>")
	)
	(segment
		(start 145.134584 -288.830766)
		(end 145.134584 -288.882836)
		(width 0.1524)
		(layer "F.Cu")
		(net "M_E_CPU1_SA_DQS_DN<7>")
	)
	(segment
		(start 152.30475 -295.327832)
		(end 154.076654 -295.327832)
		(width 0.20066)
		(layer "F.Cu")
		(net "M_E_CPU1_SA_DQS_DN<7>")
	)
	(segment
		(start 137.787634 -269.425928)
		(end 137.809478 -269.40383)
		(width 0.088646)
		(layer "F.Cu")
		(net "M_E_CPU1_SA_DQS_DN<7>")
	)
	(segment
		(start 167.971978 -292.666928)
		(end 167.686228 -292.952678)
		(width 0.20066)
		(layer "F.Cu")
		(net "M_E_CPU1_SA_DQS_DN<7>")
	)
	(segment
		(start 164.159438 -293.095426)
		(end 163.715192 -293.095426)
		(width 0.20066)
		(layer "F.Cu")
		(net "M_E_CPU1_SA_DQS_DN<7>")
	)
	(segment
		(start 137.594594 -270.475456)
		(end 137.4394 -270.20647)
		(width 0.088646)
		(layer "F.Cu")
		(net "M_E_CPU1_SA_DQS_DN<7>")
	)
	(segment
		(start 162.407346 -293.366698)
		(end 162.913314 -293.366698)
		(width 0.20066)
		(layer "F.Cu")
		(net "M_E_CPU1_SA_DQS_DN<7>")
	)
	(segment
		(start 167.686228 -292.952678)
		(end 167.367458 -292.952678)
		(width 0.20066)
		(layer "F.Cu")
		(net "M_E_CPU1_SA_DQS_DN<7>")
	)
	(segment
		(start 145.134584 -288.882836)
		(end 145.161508 -288.90976)
		(width 0.1524)
		(layer "F.Cu")
		(net "M_E_CPU1_SA_DQS_DN<7>")
	)
	(segment
		(start 160.862772 -292.68039)
		(end 161.863532 -293.095172)
		(width 0.20066)
		(layer "F.Cu")
		(net "M_E_CPU1_SA_DQS_DN<7>")
	)
	(segment
		(start 165.023292 -292.947852)
		(end 164.745924 -292.670484)
		(width 0.20066)
		(layer "F.Cu")
		(net "M_E_CPU1_SA_DQS_DN<7>")
	)
	(segment
		(start 139.823952 -270.139668)
		(end 139.927838 -270.389604)
		(width 0.088646)
		(layer "F.Cu")
		(net "M_E_CPU1_SA_DQS_DN<7>")
	)
	(segment
		(start 140.195808 -271.323054)
		(end 140.211302 -271.338548)
		(width 0.088646)
		(layer "F.Cu")
		(net "M_E_CPU1_SA_DQS_DN<7>")
	)
	(segment
		(start 170.457114 -293.366698)
		(end 169.953432 -293.366698)
		(width 0.20066)
		(layer "F.Cu")
		(net "M_E_CPU1_SA_DQS_DN<7>")
	)
	(segment
		(start 140.037312 -271.040352)
		(end 140.195808 -271.277842)
		(width 0.088646)
		(layer "F.Cu")
		(net "M_E_CPU1_SA_DQS_DN<7>")
	)
	(segment
		(start 159.777176 -292.948106)
		(end 159.823658 -292.948106)
		(width 0.101854)
		(layer "F.Cu")
		(net "M_E_CPU1_SA_DQS_DN<7>")
	)
	(segment
		(start 151.101044 -294.849296)
		(end 151.343614 -295.011856)
		(width 0.20066)
		(layer "F.Cu")
		(net "M_E_CPU1_SA_DQS_DN<7>")
	)
	(segment
		(start 145.161508 -288.90976)
		(end 151.101044 -294.849296)
		(width 0.20066)
		(layer "F.Cu")
		(net "M_E_CPU1_SA_DQS_DN<7>")
	)
	(segment
		(start 151.919178 -295.251124)
		(end 152.30475 -295.327832)
		(width 0.20066)
		(layer "F.Cu")
		(net "M_E_CPU1_SA_DQS_DN<7>")
	)
	(segment
		(start 157.810708 -292.941756)
		(end 159.770826 -292.941756)
		(width 0.1016)
		(layer "F.Cu")
		(net "M_E_CPU1_SA_DQS_DN<7>")
	)
	(segment
		(start 139.927838 -270.389604)
		(end 139.927838 -270.77543)
		(width 0.088646)
		(layer "F.Cu")
		(net "M_E_CPU1_SA_DQS_DN<7>")
	)
	(segment
		(start 165.340284 -292.947852)
		(end 165.335458 -292.947852)
		(width 0.101854)
		(layer "F.Cu")
		(net "M_E_CPU1_SA_DQS_DN<7>")
	)
	(segment
		(start 139.927838 -270.77543)
		(end 140.037312 -271.040352)
		(width 0.088646)
		(layer "F.Cu")
		(net "M_E_CPU1_SA_DQS_DN<7>")
	)
	(segment
		(start 140.211302 -271.338548)
		(end 143.889476 -275.016722)
		(width 0.1524)
		(layer "F.Cu")
		(net "M_E_CPU1_SA_DQS_DN<7>")
	)
	(segment
		(start 144.94256 -288.638742)
		(end 145.134584 -288.830766)
		(width 0.1524)
		(layer "F.Cu")
		(net "M_E_CPU1_SA_DQS_DN<7>")
	)
	(segment
		(start 157.791658 -292.954456)
		(end 157.798008 -292.954456)
		(width 0.101854)
		(layer "F.Cu")
		(net "M_E_CPU1_SA_DQS_DN<7>")
	)
	(segment
		(start 137.4394 -270.20647)
		(end 137.464546 -270.113506)
		(width 0.088646)
		(layer "F.Cu")
		(net "M_E_CPU1_SA_DQS_DN<7>")
	)
	(segment
		(start 168.462452 -292.666928)
		(end 167.971978 -292.666928)
		(width 0.20066)
		(layer "F.Cu")
		(net "M_E_CPU1_SA_DQS_DN<7>")
	)
	(segment
		(start 154.076654 -295.327832)
		(end 154.729688 -295.05783)
		(width 0.20066)
		(layer "F.Cu")
		(net "M_E_CPU1_SA_DQS_DN<7>")
	)
	(segment
		(start 163.44392 -293.366698)
		(end 162.913314 -293.366698)
		(width 0.20066)
		(layer "F.Cu")
		(net "M_E_CPU1_SA_DQS_DN<7>")
	)
	(segment
		(start 167.367458 -292.952678)
		(end 167.356536 -292.941756)
		(width 0.1016)
		(layer "F.Cu")
		(net "M_E_CPU1_SA_DQS_DN<7>")
	)
	(segment
		(start 139.171934 -269.487904)
		(end 139.823952 -270.139668)
		(width 0.088646)
		(layer "F.Cu")
		(net "M_E_CPU1_SA_DQS_DN<7>")
	)
	(segment
		(start 157.060392 -292.635432)
		(end 157.218126 -292.635432)
		(width 0.20066)
		(layer "F.Cu")
		(net "M_E_CPU1_SA_DQS_DN<7>")
	)
	(segment
		(start 167.356536 -292.941756)
		(end 165.34638 -292.941756)
		(width 0.1016)
		(layer "F.Cu")
		(net "M_E_CPU1_SA_DQS_DN<7>")
	)
	(segment
		(start 164.745924 -292.670484)
		(end 164.58438 -292.670484)
		(width 0.20066)
		(layer "F.Cu")
		(net "M_E_CPU1_SA_DQS_DN<7>")
	)
	(segment
		(start 160.40989 -292.68039)
		(end 160.862772 -292.68039)
		(width 0.20066)
		(layer "F.Cu")
		(net "M_E_CPU1_SA_DQS_DN<7>")
	)
	(segment
		(start 160.142174 -292.948106)
		(end 160.40989 -292.68039)
		(width 0.20066)
		(layer "F.Cu")
		(net "M_E_CPU1_SA_DQS_DN<7>")
	)
	(segment
		(start 156.482288 -293.488364)
		(end 156.870908 -292.90645)
		(width 0.20066)
		(layer "F.Cu")
		(net "M_E_CPU1_SA_DQS_DN<7>")
	)
	(segment
		(start 143.889476 -275.016722)
		(end 144.94256 -280.27122)
		(width 0.1524)
		(layer "F.Cu")
		(net "M_E_CPU1_SA_DQS_DN<7>")
	)
	(segment
		(start 161.863532 -293.095172)
		(end 162.13582 -293.095172)
		(width 0.20066)
		(layer "F.Cu")
		(net "M_E_CPU1_SA_DQS_DN<7>")
	)
	(segment
		(start 138.060938 -269.29969)
		(end 138.165078 -269.29969)
		(width 0.088646)
		(layer "F.Cu")
		(net "M_E_CPU1_SA_DQS_DN<7>")
	)
	(segment
		(start 151.343614 -295.011856)
		(end 151.919178 -295.251124)
		(width 0.20066)
		(layer "F.Cu")
		(net "M_E_CPU1_SA_DQS_DN<7>")
	)
	(segment
		(start 169.158666 -293.112444)
		(end 168.730676 -292.935152)
		(width 0.20066)
		(layer "F.Cu")
		(net "M_E_CPU1_SA_DQS_DN<7>")
	)
	(segment
		(start 159.823658 -292.948106)
		(end 160.142174 -292.948106)
		(width 0.20066)
		(layer "F.Cu")
		(net "M_E_CPU1_SA_DQS_DN<7>")
	)
	(segment
		(start 163.715192 -293.095426)
		(end 163.44392 -293.366698)
		(width 0.20066)
		(layer "F.Cu")
		(net "M_E_CPU1_SA_DQS_DN<7>")
	)
	(segment
		(start 157.53715 -292.954456)
		(end 157.791658 -292.954456)
		(width 0.20066)
		(layer "F.Cu")
		(net "M_E_CPU1_SA_DQS_DN<7>")
	)
	(arc
		(start 138.233912 -269.316708)
		(mid 138.354053 -269.362947)
		(end 138.481816 -269.378684)
		(width 0.088646)
		(layer "F.Cu")
		(net "M_E_CPU1_SA_DQS_DN<7>")
	)
	(arc
		(start 137.809478 -269.40383)
		(mid 137.924849 -269.326742)
		(end 138.060938 -269.29969)
		(width 0.088646)
		(layer "F.Cu")
		(net "M_E_CPU1_SA_DQS_DN<7>")
	)
	(arc
		(start 138.165078 -269.29969)
		(mid 138.200544 -269.303967)
		(end 138.233912 -269.316708)
		(width 0.088646)
		(layer "F.Cu")
		(net "M_E_CPU1_SA_DQS_DN<7>")
	)
	(arc
		(start 137.689844 -269.66164)
		(mid 137.715313 -269.534068)
		(end 137.787634 -269.425928)
		(width 0.088646)
		(layer "F.Cu")
		(net "M_E_CPU1_SA_DQS_DN<7>")
	)
	(arc
		(start 137.48131 -270.100298)
		(mid 137.63295 -269.908975)
		(end 137.689844 -269.671546)
		(width 0.088646)
		(layer "F.Cu")
		(net "M_E_CPU1_SA_DQS_DN<7>")
	)
	(arc
		(start 137.464546 -270.113506)
		(mid 137.472991 -270.106982)
		(end 137.48131 -270.100298)
		(width 0.088646)
		(layer "F.Cu")
		(net "M_E_CPU1_SA_DQS_DN<7>")
	)
	(segment
		(start 169.953432 -302.716692)
		(end 169.699178 -302.462438)
		(width 0.20066)
		(layer "F.Cu")
		(net "M_E_CPU1_SA_DQS_DN<6>")
	)
	(segment
		(start 167.691308 -302.297592)
		(end 167.36822 -302.297592)
		(width 0.20066)
		(layer "F.Cu")
		(net "M_E_CPU1_SA_DQS_DN<6>")
	)
	(segment
		(start 167.971978 -302.016922)
		(end 167.691308 -302.297592)
		(width 0.20066)
		(layer "F.Cu")
		(net "M_E_CPU1_SA_DQS_DN<6>")
	)
	(segment
		(start 167.362378 -302.29175)
		(end 165.345364 -302.29175)
		(width 0.1016)
		(layer "F.Cu")
		(net "M_E_CPU1_SA_DQS_DN<6>")
	)
	(segment
		(start 165.023038 -302.297592)
		(end 164.745924 -302.020478)
		(width 0.20066)
		(layer "F.Cu")
		(net "M_E_CPU1_SA_DQS_DN<6>")
	)
	(segment
		(start 170.457114 -302.716692)
		(end 169.953432 -302.716692)
		(width 0.20066)
		(layer "F.Cu")
		(net "M_E_CPU1_SA_DQS_DN<6>")
	)
	(segment
		(start 161.783014 -302.716692)
		(end 162.913314 -302.716692)
		(width 0.20066)
		(layer "F.Cu")
		(net "M_E_CPU1_SA_DQS_DN<6>")
	)
	(segment
		(start 165.334696 -302.297592)
		(end 165.023038 -302.297592)
		(width 0.20066)
		(layer "F.Cu")
		(net "M_E_CPU1_SA_DQS_DN<6>")
	)
	(segment
		(start 165.345364 -302.29175)
		(end 165.340284 -302.29683)
		(width 0.1016)
		(layer "F.Cu")
		(net "M_E_CPU1_SA_DQS_DN<6>")
	)
	(segment
		(start 169.699178 -302.462438)
		(end 169.12844 -302.462438)
		(width 0.20066)
		(layer "F.Cu")
		(net "M_E_CPU1_SA_DQS_DN<6>")
	)
	(segment
		(start 164.745924 -302.020478)
		(end 164.623496 -302.020478)
		(width 0.20066)
		(layer "F.Cu")
		(net "M_E_CPU1_SA_DQS_DN<6>")
	)
	(segment
		(start 164.623496 -302.020478)
		(end 164.198554 -302.44542)
		(width 0.20066)
		(layer "F.Cu")
		(net "M_E_CPU1_SA_DQS_DN<6>")
	)
	(segment
		(start 168.682924 -302.016922)
		(end 167.971978 -302.016922)
		(width 0.20066)
		(layer "F.Cu")
		(net "M_E_CPU1_SA_DQS_DN<6>")
	)
	(segment
		(start 164.198554 -302.44542)
		(end 163.715192 -302.44542)
		(width 0.20066)
		(layer "F.Cu")
		(net "M_E_CPU1_SA_DQS_DN<6>")
	)
	(segment
		(start 165.335458 -302.29683)
		(end 165.334696 -302.297592)
		(width 0.20066)
		(layer "F.Cu")
		(net "M_E_CPU1_SA_DQS_DN<6>")
	)
	(segment
		(start 167.36822 -302.297592)
		(end 167.367458 -302.29683)
		(width 0.20066)
		(layer "F.Cu")
		(net "M_E_CPU1_SA_DQS_DN<6>")
	)
	(segment
		(start 163.715192 -302.44542)
		(end 163.44392 -302.716692)
		(width 0.20066)
		(layer "F.Cu")
		(net "M_E_CPU1_SA_DQS_DN<6>")
	)
	(segment
		(start 167.367458 -302.29683)
		(end 167.362378 -302.29175)
		(width 0.1016)
		(layer "F.Cu")
		(net "M_E_CPU1_SA_DQS_DN<6>")
	)
	(segment
		(start 165.340284 -302.29683)
		(end 165.335458 -302.29683)
		(width 0.101854)
		(layer "F.Cu")
		(net "M_E_CPU1_SA_DQS_DN<6>")
	)
	(segment
		(start 163.44392 -302.716692)
		(end 162.913314 -302.716692)
		(width 0.20066)
		(layer "F.Cu")
		(net "M_E_CPU1_SA_DQS_DN<6>")
	)
	(segment
		(start 169.12844 -302.462438)
		(end 168.682924 -302.016922)
		(width 0.20066)
		(layer "F.Cu")
		(net "M_E_CPU1_SA_DQS_DN<6>")
	)
	(segment
		(start 135.714994 -272.103342)
		(end 135.714994 -272.639282)
		(width 0.20066)
		(layer "F.Cu")
		(net "M_E_CPU1_SA_DQS_DN<6>")
	)
	(segment
		(start 155.455366 -295.593516)
		(end 155.230576 -295.050718)
		(width 0.18288)
		(layer "In2.Cu")
		(net "M_E_CPU1_SA_DQS_DN<6>")
	)
	(segment
		(start 155.813252 -299.355256)
		(end 155.688792 -299.230796)
		(width 0.18288)
		(layer "In2.Cu")
		(net "M_E_CPU1_SA_DQS_DN<6>")
	)
	(segment
		(start 154.057604 -291.893752)
		(end 153.89479 -291.826442)
		(width 0.18288)
		(layer "In2.Cu")
		(net "M_E_CPU1_SA_DQS_DN<6>")
	)
	(segment
		(start 153.011632 -289.91814)
		(end 152.83561 -289.91814)
		(width 0.18288)
		(layer "In2.Cu")
		(net "M_E_CPU1_SA_DQS_DN<6>")
	)
	(segment
		(start 159.758126 -302.496982)
		(end 159.507936 -302.246792)
		(width 0.18288)
		(layer "In2.Cu")
		(net "M_E_CPU1_SA_DQS_DN<6>")
	)
	(segment
		(start 151.495506 -288.402014)
		(end 150.843996 -287.750504)
		(width 0.18288)
		(layer "In2.Cu")
		(net "M_E_CPU1_SA_DQS_DN<6>")
	)
	(segment
		(start 154.267408 -292.400482)
		(end 154.057604 -291.893752)
		(width 0.18288)
		(layer "In2.Cu")
		(net "M_E_CPU1_SA_DQS_DN<6>")
	)
	(segment
		(start 141.510258 -273.15287)
		(end 140.900658 -273.15287)
		(width 0.18288)
		(layer "In2.Cu")
		(net "M_E_CPU1_SA_DQS_DN<6>")
	)
	(segment
		(start 153.89479 -291.826442)
		(end 153.684732 -291.319204)
		(width 0.18288)
		(layer "In2.Cu")
		(net "M_E_CPU1_SA_DQS_DN<6>")
	)
	(segment
		(start 146.230086 -279.565354)
		(end 145.033238 -276.676104)
		(width 0.18288)
		(layer "In2.Cu")
		(net "M_E_CPU1_SA_DQS_DN<6>")
	)
	(segment
		(start 155.230576 -295.050718)
		(end 155.297886 -294.888158)
		(width 0.18288)
		(layer "In2.Cu")
		(net "M_E_CPU1_SA_DQS_DN<6>")
	)
	(segment
		(start 156.497782 -301.557182)
		(end 155.813252 -299.903896)
		(width 0.18288)
		(layer "In2.Cu")
		(net "M_E_CPU1_SA_DQS_DN<6>")
	)
	(segment
		(start 155.688792 -297.335956)
		(end 155.813252 -297.211496)
		(width 0.18288)
		(layer "In2.Cu")
		(net "M_E_CPU1_SA_DQS_DN<6>")
	)
	(segment
		(start 155.617926 -295.660572)
		(end 155.455366 -295.593516)
		(width 0.18288)
		(layer "In2.Cu")
		(net "M_E_CPU1_SA_DQS_DN<6>")
	)
	(segment
		(start 155.813252 -298.009056)
		(end 155.688792 -297.884596)
		(width 0.18288)
		(layer "In2.Cu")
		(net "M_E_CPU1_SA_DQS_DN<6>")
	)
	(segment
		(start 153.399998 -290.305998)
		(end 153.39949 -290.305998)
		(width 0.18288)
		(layer "In2.Cu")
		(net "M_E_CPU1_SA_DQS_DN<6>")
	)
	(segment
		(start 135.83539 -272.413476)
		(end 135.833866 -272.41373)
		(width 0.088646)
		(layer "In2.Cu")
		(net "M_E_CPU1_SA_DQS_DN<6>")
	)
	(segment
		(start 158.90748 -301.997872)
		(end 158.1912 -301.997872)
		(width 0.18288)
		(layer "In2.Cu")
		(net "M_E_CPU1_SA_DQS_DN<6>")
	)
	(segment
		(start 161.515044 -302.448722)
		(end 160.928558 -302.448722)
		(width 0.18288)
		(layer "In2.Cu")
		(net "M_E_CPU1_SA_DQS_DN<6>")
	)
	(segment
		(start 155.813252 -296.131996)
		(end 155.617926 -295.660572)
		(width 0.18288)
		(layer "In2.Cu")
		(net "M_E_CPU1_SA_DQS_DN<6>")
	)
	(segment
		(start 157.199838 -301.966376)
		(end 156.906976 -301.966376)
		(width 0.18288)
		(layer "In2.Cu")
		(net "M_E_CPU1_SA_DQS_DN<6>")
	)
	(segment
		(start 157.895544 -302.293528)
		(end 157.52699 -302.293528)
		(width 0.18288)
		(layer "In2.Cu")
		(net "M_E_CPU1_SA_DQS_DN<6>")
	)
	(segment
		(start 145.033238 -276.676104)
		(end 141.807438 -273.45005)
		(width 0.18288)
		(layer "In2.Cu")
		(net "M_E_CPU1_SA_DQS_DN<6>")
	)
	(segment
		(start 150.843996 -287.750504)
		(end 150.016464 -285.752032)
		(width 0.18288)
		(layer "In2.Cu")
		(net "M_E_CPU1_SA_DQS_DN<6>")
	)
	(segment
		(start 151.495506 -288.578036)
		(end 151.495506 -288.402014)
		(width 0.18288)
		(layer "In2.Cu")
		(net "M_E_CPU1_SA_DQS_DN<6>")
	)
	(segment
		(start 151.883618 -288.966148)
		(end 151.495506 -288.578036)
		(width 0.18288)
		(layer "In2.Cu")
		(net "M_E_CPU1_SA_DQS_DN<6>")
	)
	(segment
		(start 136.465056 -272.316448)
		(end 136.462262 -272.318226)
		(width 0.088646)
		(layer "In2.Cu")
		(net "M_E_CPU1_SA_DQS_DN<6>")
	)
	(segment
		(start 154.199844 -292.563042)
		(end 154.267408 -292.400482)
		(width 0.18288)
		(layer "In2.Cu")
		(net "M_E_CPU1_SA_DQS_DN<6>")
	)
	(segment
		(start 155.813252 -298.557696)
		(end 155.813252 -298.009056)
		(width 0.18288)
		(layer "In2.Cu")
		(net "M_E_CPU1_SA_DQS_DN<6>")
	)
	(segment
		(start 152.83561 -289.91814)
		(end 152.447498 -289.530028)
		(width 0.18288)
		(layer "In2.Cu")
		(net "M_E_CPU1_SA_DQS_DN<6>")
	)
	(segment
		(start 137.407396 -272.314924)
		(end 137.392664 -272.32356)
		(width 0.088646)
		(layer "In2.Cu")
		(net "M_E_CPU1_SA_DQS_DN<6>")
	)
	(segment
		(start 155.688792 -297.884596)
		(end 155.688792 -297.335956)
		(width 0.18288)
		(layer "In2.Cu")
		(net "M_E_CPU1_SA_DQS_DN<6>")
	)
	(segment
		(start 135.833866 -272.41373)
		(end 135.789416 -272.432272)
		(width 0.088646)
		(layer "In2.Cu")
		(net "M_E_CPU1_SA_DQS_DN<6>")
	)
	(segment
		(start 154.925268 -294.314118)
		(end 154.71521 -293.80688)
		(width 0.18288)
		(layer "In2.Cu")
		(net "M_E_CPU1_SA_DQS_DN<6>")
	)
	(segment
		(start 160.928558 -302.448722)
		(end 160.542986 -302.608488)
		(width 0.18288)
		(layer "In2.Cu")
		(net "M_E_CPU1_SA_DQS_DN<6>")
	)
	(segment
		(start 155.688792 -299.230796)
		(end 155.688792 -298.682156)
		(width 0.18288)
		(layer "In2.Cu")
		(net "M_E_CPU1_SA_DQS_DN<6>")
	)
	(segment
		(start 154.78252 -293.64432)
		(end 154.572716 -293.13759)
		(width 0.18288)
		(layer "In2.Cu")
		(net "M_E_CPU1_SA_DQS_DN<6>")
	)
	(segment
		(start 140.900658 -273.15287)
		(end 140.840968 -273.09318)
		(width 0.088646)
		(layer "In2.Cu")
		(net "M_E_CPU1_SA_DQS_DN<6>")
	)
	(segment
		(start 159.207454 -302.122332)
		(end 158.90748 -301.997872)
		(width 0.18288)
		(layer "In2.Cu")
		(net "M_E_CPU1_SA_DQS_DN<6>")
	)
	(segment
		(start 136.466834 -272.315432)
		(end 136.465056 -272.316448)
		(width 0.088646)
		(layer "In2.Cu")
		(net "M_E_CPU1_SA_DQS_DN<6>")
	)
	(segment
		(start 135.835898 -272.413476)
		(end 135.83539 -272.413476)
		(width 0.088646)
		(layer "In2.Cu")
		(net "M_E_CPU1_SA_DQS_DN<6>")
	)
	(segment
		(start 153.684732 -291.319204)
		(end 153.752296 -291.156644)
		(width 0.18288)
		(layer "In2.Cu")
		(net "M_E_CPU1_SA_DQS_DN<6>")
	)
	(segment
		(start 155.297886 -294.888158)
		(end 155.088082 -294.381428)
		(width 0.18288)
		(layer "In2.Cu")
		(net "M_E_CPU1_SA_DQS_DN<6>")
	)
	(segment
		(start 158.1912 -301.997872)
		(end 157.895544 -302.293528)
		(width 0.18288)
		(layer "In2.Cu")
		(net "M_E_CPU1_SA_DQS_DN<6>")
	)
	(segment
		(start 155.088082 -294.381428)
		(end 154.925268 -294.314118)
		(width 0.18288)
		(layer "In2.Cu")
		(net "M_E_CPU1_SA_DQS_DN<6>")
	)
	(segment
		(start 153.400252 -290.306506)
		(end 153.399998 -290.305998)
		(width 0.18288)
		(layer "In2.Cu")
		(net "M_E_CPU1_SA_DQS_DN<6>")
	)
	(segment
		(start 136.462262 -272.318226)
		(end 136.448546 -272.325846)
		(width 0.088646)
		(layer "In2.Cu")
		(net "M_E_CPU1_SA_DQS_DN<6>")
	)
	(segment
		(start 139.446508 -272.39087)
		(end 139.004548 -272.39087)
		(width 0.088646)
		(layer "In2.Cu")
		(net "M_E_CPU1_SA_DQS_DN<6>")
	)
	(segment
		(start 159.507936 -302.246792)
		(end 159.207454 -302.122332)
		(width 0.18288)
		(layer "In2.Cu")
		(net "M_E_CPU1_SA_DQS_DN<6>")
	)
	(segment
		(start 154.572716 -293.13759)
		(end 154.409902 -293.07028)
		(width 0.18288)
		(layer "In2.Cu")
		(net "M_E_CPU1_SA_DQS_DN<6>")
	)
	(segment
		(start 138.347196 -272.314924)
		(end 138.332464 -272.32356)
		(width 0.088646)
		(layer "In2.Cu")
		(net "M_E_CPU1_SA_DQS_DN<6>")
	)
	(segment
		(start 157.52699 -302.293528)
		(end 157.199838 -301.966376)
		(width 0.18288)
		(layer "In2.Cu")
		(net "M_E_CPU1_SA_DQS_DN<6>")
	)
	(segment
		(start 136.467596 -272.314924)
		(end 136.466834 -272.315432)
		(width 0.088646)
		(layer "In2.Cu")
		(net "M_E_CPU1_SA_DQS_DN<6>")
	)
	(segment
		(start 150.016464 -285.752032)
		(end 150.016464 -283.351732)
		(width 0.18288)
		(layer "In2.Cu")
		(net "M_E_CPU1_SA_DQS_DN<6>")
	)
	(segment
		(start 135.726932 -272.48993)
		(end 135.714994 -272.639282)
		(width 0.088646)
		(layer "In2.Cu")
		(net "M_E_CPU1_SA_DQS_DN<6>")
	)
	(segment
		(start 160.027366 -302.608488)
		(end 159.758126 -302.496982)
		(width 0.18288)
		(layer "In2.Cu")
		(net "M_E_CPU1_SA_DQS_DN<6>")
	)
	(segment
		(start 152.05964 -288.966148)
		(end 151.883618 -288.966148)
		(width 0.18288)
		(layer "In2.Cu")
		(net "M_E_CPU1_SA_DQS_DN<6>")
	)
	(segment
		(start 152.447498 -289.530028)
		(end 152.447498 -289.354006)
		(width 0.18288)
		(layer "In2.Cu")
		(net "M_E_CPU1_SA_DQS_DN<6>")
	)
	(segment
		(start 154.409902 -293.07028)
		(end 154.199844 -292.563042)
		(width 0.18288)
		(layer "In2.Cu")
		(net "M_E_CPU1_SA_DQS_DN<6>")
	)
	(segment
		(start 153.39949 -290.305998)
		(end 153.011632 -289.91814)
		(width 0.18288)
		(layer "In2.Cu")
		(net "M_E_CPU1_SA_DQS_DN<6>")
	)
	(segment
		(start 160.542986 -302.608488)
		(end 160.027366 -302.608488)
		(width 0.18288)
		(layer "In2.Cu")
		(net "M_E_CPU1_SA_DQS_DN<6>")
	)
	(segment
		(start 150.016464 -283.351732)
		(end 146.230086 -279.565354)
		(width 0.18288)
		(layer "In2.Cu")
		(net "M_E_CPU1_SA_DQS_DN<6>")
	)
	(segment
		(start 155.813252 -297.211496)
		(end 155.813252 -296.131996)
		(width 0.18288)
		(layer "In2.Cu")
		(net "M_E_CPU1_SA_DQS_DN<6>")
	)
	(segment
		(start 140.148818 -273.09318)
		(end 139.446508 -272.39087)
		(width 0.088646)
		(layer "In2.Cu")
		(net "M_E_CPU1_SA_DQS_DN<6>")
	)
	(segment
		(start 141.807438 -273.45005)
		(end 141.510258 -273.15287)
		(width 0.18288)
		(layer "In2.Cu")
		(net "M_E_CPU1_SA_DQS_DN<6>")
	)
	(segment
		(start 153.752296 -291.156644)
		(end 153.400252 -290.306506)
		(width 0.18288)
		(layer "In2.Cu")
		(net "M_E_CPU1_SA_DQS_DN<6>")
	)
	(segment
		(start 161.783014 -302.716692)
		(end 161.515044 -302.448722)
		(width 0.18288)
		(layer "In2.Cu")
		(net "M_E_CPU1_SA_DQS_DN<6>")
	)
	(segment
		(start 154.71521 -293.80688)
		(end 154.78252 -293.64432)
		(width 0.18288)
		(layer "In2.Cu")
		(net "M_E_CPU1_SA_DQS_DN<6>")
	)
	(segment
		(start 155.688792 -298.682156)
		(end 155.813252 -298.557696)
		(width 0.18288)
		(layer "In2.Cu")
		(net "M_E_CPU1_SA_DQS_DN<6>")
	)
	(segment
		(start 156.906976 -301.966376)
		(end 156.497782 -301.557182)
		(width 0.18288)
		(layer "In2.Cu")
		(net "M_E_CPU1_SA_DQS_DN<6>")
	)
	(segment
		(start 136.176512 -272.39087)
		(end 135.94842 -272.39087)
		(width 0.088646)
		(layer "In2.Cu")
		(net "M_E_CPU1_SA_DQS_DN<6>")
	)
	(segment
		(start 152.447498 -289.354006)
		(end 152.05964 -288.966148)
		(width 0.18288)
		(layer "In2.Cu")
		(net "M_E_CPU1_SA_DQS_DN<6>")
	)
	(segment
		(start 135.94842 -272.39087)
		(end 135.835898 -272.413476)
		(width 0.088646)
		(layer "In2.Cu")
		(net "M_E_CPU1_SA_DQS_DN<6>")
	)
	(segment
		(start 155.813252 -299.903896)
		(end 155.813252 -299.355256)
		(width 0.18288)
		(layer "In2.Cu")
		(net "M_E_CPU1_SA_DQS_DN<6>")
	)
	(segment
		(start 140.840968 -273.09318)
		(end 140.148818 -273.09318)
		(width 0.088646)
		(layer "In2.Cu")
		(net "M_E_CPU1_SA_DQS_DN<6>")
	)
	(arc
		(start 139.004548 -272.39087)
		(mid 138.858078 -272.37151)
		(end 138.721592 -272.314924)
		(width 0.088646)
		(layer "In2.Cu")
		(net "M_E_CPU1_SA_DQS_DN<6>")
	)
	(arc
		(start 135.789416 -272.432272)
		(mid 135.746889 -272.448885)
		(end 135.726932 -272.48993)
		(width 0.088646)
		(layer "In2.Cu")
		(net "M_E_CPU1_SA_DQS_DN<6>")
	)
	(arc
		(start 136.448546 -272.325846)
		(mid 136.316609 -272.375422)
		(end 136.176512 -272.39087)
		(width 0.088646)
		(layer "In2.Cu")
		(net "M_E_CPU1_SA_DQS_DN<6>")
	)
	(arc
		(start 137.781792 -272.314924)
		(mid 137.594594 -272.264781)
		(end 137.407396 -272.314924)
		(width 0.088646)
		(layer "In2.Cu")
		(net "M_E_CPU1_SA_DQS_DN<6>")
	)
	(arc
		(start 137.392664 -272.32356)
		(mid 137.116223 -272.390726)
		(end 136.841992 -272.314924)
		(width 0.088646)
		(layer "In2.Cu")
		(net "M_E_CPU1_SA_DQS_DN<6>")
	)
	(arc
		(start 138.721592 -272.314924)
		(mid 138.534394 -272.264781)
		(end 138.347196 -272.314924)
		(width 0.088646)
		(layer "In2.Cu")
		(net "M_E_CPU1_SA_DQS_DN<6>")
	)
	(arc
		(start 138.332464 -272.32356)
		(mid 138.056023 -272.390726)
		(end 137.781792 -272.314924)
		(width 0.088646)
		(layer "In2.Cu")
		(net "M_E_CPU1_SA_DQS_DN<6>")
	)
	(arc
		(start 136.841992 -272.314924)
		(mid 136.654794 -272.264781)
		(end 136.467596 -272.314924)
		(width 0.088646)
		(layer "In2.Cu")
		(net "M_E_CPU1_SA_DQS_DN<6>")
	)
	(segment
		(start 157.796484 -311.648348)
		(end 157.803088 -311.641744)
		(width 0.1016)
		(layer "F.Cu")
		(net "M_E_CPU1_SA_DQS_DN<5>")
	)
	(segment
		(start 169.69105 -311.812432)
		(end 169.150284 -311.812432)
		(width 0.20066)
		(layer "F.Cu")
		(net "M_E_CPU1_SA_DQS_DN<5>")
	)
	(segment
		(start 142.012924 -296.20464)
		(end 142.039848 -296.231564)
		(width 0.1524)
		(layer "F.Cu")
		(net "M_E_CPU1_SA_DQS_DN<5>")
	)
	(segment
		(start 157.246066 -311.367932)
		(end 157.526482 -311.648348)
		(width 0.20066)
		(layer "F.Cu")
		(net "M_E_CPU1_SA_DQS_DN<5>")
	)
	(segment
		(start 142.423896 -296.615866)
		(end 145.02257 -299.779436)
		(width 0.20066)
		(layer "F.Cu")
		(net "M_E_CPU1_SA_DQS_DN<5>")
	)
	(segment
		(start 157.526482 -311.648348)
		(end 157.791658 -311.648348)
		(width 0.20066)
		(layer "F.Cu")
		(net "M_E_CPU1_SA_DQS_DN<5>")
	)
	(segment
		(start 167.357552 -311.641744)
		(end 167.050212 -311.641744)
		(width 0.1016)
		(layer "F.Cu")
		(net "M_E_CPU1_SA_DQS_DN<5>")
	)
	(segment
		(start 139.819634 -276.670008)
		(end 139.819634 -276.714712)
		(width 0.088646)
		(layer "F.Cu")
		(net "M_E_CPU1_SA_DQS_DN<5>")
	)
	(segment
		(start 142.039848 -296.231564)
		(end 142.423896 -296.615866)
		(width 0.20066)
		(layer "F.Cu")
		(net "M_E_CPU1_SA_DQS_DN<5>")
	)
	(segment
		(start 165.368478 -311.641744)
		(end 165.360858 -311.649364)
		(width 0.101854)
		(layer "F.Cu")
		(net "M_E_CPU1_SA_DQS_DN<5>")
	)
	(segment
		(start 157.026356 -311.367932)
		(end 157.246066 -311.367932)
		(width 0.20066)
		(layer "F.Cu")
		(net "M_E_CPU1_SA_DQS_DN<5>")
	)
	(segment
		(start 164.59073 -311.34431)
		(end 164.40531 -311.34431)
		(width 0.20066)
		(layer "F.Cu")
		(net "M_E_CPU1_SA_DQS_DN<5>")
	)
	(segment
		(start 169.945304 -312.066686)
		(end 169.69105 -311.812432)
		(width 0.20066)
		(layer "F.Cu")
		(net "M_E_CPU1_SA_DQS_DN<5>")
	)
	(segment
		(start 157.791658 -311.648348)
		(end 157.796484 -311.648348)
		(width 0.101854)
		(layer "F.Cu")
		(net "M_E_CPU1_SA_DQS_DN<5>")
	)
	(segment
		(start 141.888718 -296.02811)
		(end 142.012924 -296.152316)
		(width 0.1524)
		(layer "F.Cu")
		(net "M_E_CPU1_SA_DQS_DN<5>")
	)
	(segment
		(start 170.457114 -312.066686)
		(end 169.945304 -312.066686)
		(width 0.20066)
		(layer "F.Cu")
		(net "M_E_CPU1_SA_DQS_DN<5>")
	)
	(segment
		(start 138.696192 -276.016466)
		(end 139.074652 -276.173438)
		(width 0.088646)
		(layer "F.Cu")
		(net "M_E_CPU1_SA_DQS_DN<5>")
	)
	(segment
		(start 141.021562 -291.59708)
		(end 141.664182 -295.40962)
		(width 0.1524)
		(layer "F.Cu")
		(net "M_E_CPU1_SA_DQS_DN<5>")
	)
	(segment
		(start 168.132506 -311.366916)
		(end 167.847772 -311.65165)
		(width 0.20066)
		(layer "F.Cu")
		(net "M_E_CPU1_SA_DQS_DN<5>")
	)
	(segment
		(start 162.170618 -311.829958)
		(end 162.407346 -312.066686)
		(width 0.20066)
		(layer "F.Cu")
		(net "M_E_CPU1_SA_DQS_DN<5>")
	)
	(segment
		(start 167.847772 -311.65165)
		(end 167.367458 -311.65165)
		(width 0.20066)
		(layer "F.Cu")
		(net "M_E_CPU1_SA_DQS_DN<5>")
	)
	(segment
		(start 156.383482 -310.891682)
		(end 157.026356 -311.367932)
		(width 0.20066)
		(layer "F.Cu")
		(net "M_E_CPU1_SA_DQS_DN<5>")
	)
	(segment
		(start 165.360858 -311.649364)
		(end 165.335458 -311.649364)
		(width 0.101854)
		(layer "F.Cu")
		(net "M_E_CPU1_SA_DQS_DN<5>")
	)
	(segment
		(start 160.363916 -311.416192)
		(end 160.573466 -311.416192)
		(width 0.20066)
		(layer "F.Cu")
		(net "M_E_CPU1_SA_DQS_DN<5>")
	)
	(segment
		(start 163.954206 -311.795414)
		(end 163.659312 -311.795414)
		(width 0.20066)
		(layer "F.Cu")
		(net "M_E_CPU1_SA_DQS_DN<5>")
	)
	(segment
		(start 155.337002 -310.034178)
		(end 156.383482 -310.891682)
		(width 0.20066)
		(layer "F.Cu")
		(net "M_E_CPU1_SA_DQS_DN<5>")
	)
	(segment
		(start 140.986256 -280.586688)
		(end 140.986256 -291.264086)
		(width 0.1524)
		(layer "F.Cu")
		(net "M_E_CPU1_SA_DQS_DN<5>")
	)
	(segment
		(start 161.936176 -311.829958)
		(end 162.170618 -311.829958)
		(width 0.20066)
		(layer "F.Cu")
		(net "M_E_CPU1_SA_DQS_DN<5>")
	)
	(segment
		(start 157.803088 -311.641744)
		(end 159.818578 -311.641744)
		(width 0.1016)
		(layer "F.Cu")
		(net "M_E_CPU1_SA_DQS_DN<5>")
	)
	(segment
		(start 167.050212 -311.641744)
		(end 166.650924 -311.641744)
		(width 0.101854)
		(layer "F.Cu")
		(net "M_E_CPU1_SA_DQS_DN<5>")
	)
	(segment
		(start 163.659312 -311.795414)
		(end 163.38804 -312.066686)
		(width 0.20066)
		(layer "F.Cu")
		(net "M_E_CPU1_SA_DQS_DN<5>")
	)
	(segment
		(start 145.02257 -299.779436)
		(end 154.89555 -309.635144)
		(width 0.20066)
		(layer "F.Cu")
		(net "M_E_CPU1_SA_DQS_DN<5>")
	)
	(segment
		(start 164.40531 -311.34431)
		(end 163.954206 -311.795414)
		(width 0.20066)
		(layer "F.Cu")
		(net "M_E_CPU1_SA_DQS_DN<5>")
	)
	(segment
		(start 168.627044 -311.507124)
		(end 168.288716 -311.366916)
		(width 0.20066)
		(layer "F.Cu")
		(net "M_E_CPU1_SA_DQS_DN<5>")
	)
	(segment
		(start 142.012924 -296.152316)
		(end 142.012924 -296.20464)
		(width 0.1524)
		(layer "F.Cu")
		(net "M_E_CPU1_SA_DQS_DN<5>")
	)
	(segment
		(start 163.38804 -312.066686)
		(end 162.913314 -312.066686)
		(width 0.20066)
		(layer "F.Cu")
		(net "M_E_CPU1_SA_DQS_DN<5>")
	)
	(segment
		(start 165.335458 -311.649364)
		(end 164.895784 -311.649364)
		(width 0.20066)
		(layer "F.Cu")
		(net "M_E_CPU1_SA_DQS_DN<5>")
	)
	(segment
		(start 168.288716 -311.366916)
		(end 168.132506 -311.366916)
		(width 0.20066)
		(layer "F.Cu")
		(net "M_E_CPU1_SA_DQS_DN<5>")
	)
	(segment
		(start 159.823658 -311.646824)
		(end 159.82442 -311.647586)
		(width 0.20066)
		(layer "F.Cu")
		(net "M_E_CPU1_SA_DQS_DN<5>")
	)
	(segment
		(start 139.60856 -276.458934)
		(end 139.819634 -276.670008)
		(width 0.088646)
		(layer "F.Cu")
		(net "M_E_CPU1_SA_DQS_DN<5>")
	)
	(segment
		(start 141.664182 -295.40962)
		(end 141.888718 -296.02811)
		(width 0.1524)
		(layer "F.Cu")
		(net "M_E_CPU1_SA_DQS_DN<5>")
	)
	(segment
		(start 139.835128 -276.730206)
		(end 140.309346 -277.204424)
		(width 0.1524)
		(layer "F.Cu")
		(net "M_E_CPU1_SA_DQS_DN<5>")
	)
	(segment
		(start 169.150284 -311.812432)
		(end 168.778174 -311.658254)
		(width 0.20066)
		(layer "F.Cu")
		(net "M_E_CPU1_SA_DQS_DN<5>")
	)
	(segment
		(start 164.895784 -311.649364)
		(end 164.59073 -311.34431)
		(width 0.20066)
		(layer "F.Cu")
		(net "M_E_CPU1_SA_DQS_DN<5>")
	)
	(segment
		(start 154.89555 -309.635144)
		(end 155.337002 -310.034178)
		(width 0.20066)
		(layer "F.Cu")
		(net "M_E_CPU1_SA_DQS_DN<5>")
	)
	(segment
		(start 139.819634 -276.714712)
		(end 139.835128 -276.730206)
		(width 0.088646)
		(layer "F.Cu")
		(net "M_E_CPU1_SA_DQS_DN<5>")
	)
	(segment
		(start 166.650924 -311.641744)
		(end 165.368478 -311.641744)
		(width 0.1016)
		(layer "F.Cu")
		(net "M_E_CPU1_SA_DQS_DN<5>")
	)
	(segment
		(start 140.309346 -277.204424)
		(end 140.986256 -280.586688)
		(width 0.1524)
		(layer "F.Cu")
		(net "M_E_CPU1_SA_DQS_DN<5>")
	)
	(segment
		(start 159.818578 -311.641744)
		(end 159.823658 -311.646824)
		(width 0.1016)
		(layer "F.Cu")
		(net "M_E_CPU1_SA_DQS_DN<5>")
	)
	(segment
		(start 140.986256 -291.264086)
		(end 141.021562 -291.59708)
		(width 0.1524)
		(layer "F.Cu")
		(net "M_E_CPU1_SA_DQS_DN<5>")
	)
	(segment
		(start 168.778174 -311.658254)
		(end 168.627044 -311.507124)
		(width 0.20066)
		(layer "F.Cu")
		(net "M_E_CPU1_SA_DQS_DN<5>")
	)
	(segment
		(start 139.074652 -276.173438)
		(end 139.60856 -276.458934)
		(width 0.088646)
		(layer "F.Cu")
		(net "M_E_CPU1_SA_DQS_DN<5>")
	)
	(segment
		(start 162.407346 -312.066686)
		(end 162.913314 -312.066686)
		(width 0.20066)
		(layer "F.Cu")
		(net "M_E_CPU1_SA_DQS_DN<5>")
	)
	(segment
		(start 137.124694 -276.172676)
		(end 137.943082 -275.823172)
		(width 0.088646)
		(layer "F.Cu")
		(net "M_E_CPU1_SA_DQS_DN<5>")
	)
	(segment
		(start 167.367458 -311.65165)
		(end 167.357552 -311.641744)
		(width 0.1016)
		(layer "F.Cu")
		(net "M_E_CPU1_SA_DQS_DN<5>")
	)
	(segment
		(start 160.132522 -311.647586)
		(end 160.363916 -311.416192)
		(width 0.20066)
		(layer "F.Cu")
		(net "M_E_CPU1_SA_DQS_DN<5>")
	)
	(segment
		(start 159.82442 -311.647586)
		(end 160.132522 -311.647586)
		(width 0.20066)
		(layer "F.Cu")
		(net "M_E_CPU1_SA_DQS_DN<5>")
	)
	(segment
		(start 138.169396 -275.818092)
		(end 138.696192 -276.016466)
		(width 0.088646)
		(layer "F.Cu")
		(net "M_E_CPU1_SA_DQS_DN<5>")
	)
	(segment
		(start 160.573466 -311.416192)
		(end 161.936176 -311.829958)
		(width 0.20066)
		(layer "F.Cu")
		(net "M_E_CPU1_SA_DQS_DN<5>")
	)
	(arc
		(start 137.943082 -275.823172)
		(mid 138.055742 -275.798811)
		(end 138.169396 -275.818092)
		(width 0.088646)
		(layer "F.Cu")
		(net "M_E_CPU1_SA_DQS_DN<5>")
	)
	(segment
		(start 141.127988 -261.67334)
		(end 141.1732 -261.67334)
		(width 0.088646)
		(layer "F.Cu")
		(net "M_E_CPU1_SA_DQS_DN<4>")
	)
	(segment
		(start 165.194742 -274.907248)
		(end 164.784278 -275.317712)
		(width 0.20066)
		(layer "F.Cu")
		(net "M_E_CPU1_SA_DQS_DN<4>")
	)
	(segment
		(start 140.286232 -260.831584)
		(end 140.43025 -260.831584)
		(width 0.088646)
		(layer "F.Cu")
		(net "M_E_CPU1_SA_DQS_DN<4>")
	)
	(segment
		(start 139.004294 -260.269736)
		(end 139.764516 -260.37413)
		(width 0.088646)
		(layer "F.Cu")
		(net "M_E_CPU1_SA_DQS_DN<4>")
	)
	(segment
		(start 140.95095 -261.496302)
		(end 141.127988 -261.67334)
		(width 0.088646)
		(layer "F.Cu")
		(net "M_E_CPU1_SA_DQS_DN<4>")
	)
	(segment
		(start 164.077396 -275.078952)
		(end 164.064696 -275.091652)
		(width 0.101854)
		(layer "F.Cu")
		(net "M_E_CPU1_SA_DQS_DN<4>")
	)
	(segment
		(start 159.361886 -274.66671)
		(end 158.813246 -274.66671)
		(width 0.20066)
		(layer "F.Cu")
		(net "M_E_CPU1_SA_DQS_DN<4>")
	)
	(segment
		(start 157.112208 -275.188934)
		(end 157.7086 -275.188934)
		(width 0.20066)
		(layer "F.Cu")
		(net "M_E_CPU1_SA_DQS_DN<4>")
	)
	(segment
		(start 160.679892 -275.344636)
		(end 160.283652 -274.948396)
		(width 0.20066)
		(layer "F.Cu")
		(net "M_E_CPU1_SA_DQS_DN<4>")
	)
	(segment
		(start 164.479224 -275.317712)
		(end 164.240464 -275.078952)
		(width 0.20066)
		(layer "F.Cu")
		(net "M_E_CPU1_SA_DQS_DN<4>")
	)
	(segment
		(start 161.008314 -275.344636)
		(end 160.679892 -275.344636)
		(width 0.20066)
		(layer "F.Cu")
		(net "M_E_CPU1_SA_DQS_DN<4>")
	)
	(segment
		(start 137.614152 -260.037326)
		(end 137.68451 -260.107684)
		(width 0.088646)
		(layer "F.Cu")
		(net "M_E_CPU1_SA_DQS_DN<4>")
	)
	(segment
		(start 153.344118 -274.689824)
		(end 153.468578 -274.814284)
		(width 0.20066)
		(layer "F.Cu")
		(net "M_E_CPU1_SA_DQS_DN<4>")
	)
	(segment
		(start 137.699496 -260.115812)
		(end 137.8712 -260.215126)
		(width 0.088646)
		(layer "F.Cu")
		(net "M_E_CPU1_SA_DQS_DN<4>")
	)
	(segment
		(start 155.012898 -274.814284)
		(end 155.137358 -274.689824)
		(width 0.20066)
		(layer "F.Cu")
		(net "M_E_CPU1_SA_DQS_DN<4>")
	)
	(segment
		(start 160.283652 -274.948396)
		(end 159.643572 -274.948396)
		(width 0.20066)
		(layer "F.Cu")
		(net "M_E_CPU1_SA_DQS_DN<4>")
	)
	(segment
		(start 165.808406 -274.66671)
		(end 165.567868 -274.907248)
		(width 0.20066)
		(layer "F.Cu")
		(net "M_E_CPU1_SA_DQS_DN<4>")
	)
	(segment
		(start 155.693618 -274.814284)
		(end 156.524706 -274.814284)
		(width 0.20066)
		(layer "F.Cu")
		(net "M_E_CPU1_SA_DQS_DN<4>")
	)
	(segment
		(start 141.1732 -261.67334)
		(end 150.871682 -271.371822)
		(width 0.1524)
		(layer "F.Cu")
		(net "M_E_CPU1_SA_DQS_DN<4>")
	)
	(segment
		(start 157.795722 -275.101812)
		(end 157.795722 -274.752816)
		(width 0.20066)
		(layer "F.Cu")
		(net "M_E_CPU1_SA_DQS_DN<4>")
	)
	(segment
		(start 166.357046 -274.66671)
		(end 165.808406 -274.66671)
		(width 0.20066)
		(layer "F.Cu")
		(net "M_E_CPU1_SA_DQS_DN<4>")
	)
	(segment
		(start 154.581098 -274.814284)
		(end 155.012898 -274.814284)
		(width 0.20066)
		(layer "F.Cu")
		(net "M_E_CPU1_SA_DQS_DN<4>")
	)
	(segment
		(start 164.784278 -275.317712)
		(end 164.479224 -275.317712)
		(width 0.20066)
		(layer "F.Cu")
		(net "M_E_CPU1_SA_DQS_DN<4>")
	)
	(segment
		(start 154.024838 -274.689824)
		(end 154.456638 -274.689824)
		(width 0.20066)
		(layer "F.Cu")
		(net "M_E_CPU1_SA_DQS_DN<4>")
	)
	(segment
		(start 151.472138 -274.37207)
		(end 151.552656 -274.662138)
		(width 0.1524)
		(layer "F.Cu")
		(net "M_E_CPU1_SA_DQS_DN<4>")
	)
	(segment
		(start 152.281128 -274.851114)
		(end 152.317958 -274.814284)
		(width 0.1524)
		(layer "F.Cu")
		(net "M_E_CPU1_SA_DQS_DN<4>")
	)
	(segment
		(start 163.891722 -275.091652)
		(end 161.9123 -275.091652)
		(width 0.1016)
		(layer "F.Cu")
		(net "M_E_CPU1_SA_DQS_DN<4>")
	)
	(segment
		(start 140.681456 -261.226808)
		(end 140.82522 -261.226808)
		(width 0.088646)
		(layer "F.Cu")
		(net "M_E_CPU1_SA_DQS_DN<4>")
	)
	(segment
		(start 164.240464 -275.078952)
		(end 164.077396 -275.078952)
		(width 0.20066)
		(layer "F.Cu")
		(net "M_E_CPU1_SA_DQS_DN<4>")
	)
	(segment
		(start 156.74848 -275.038058)
		(end 156.863034 -275.085556)
		(width 0.20066)
		(layer "F.Cu")
		(net "M_E_CPU1_SA_DQS_DN<4>")
	)
	(segment
		(start 157.881828 -274.66671)
		(end 158.813246 -274.66671)
		(width 0.20066)
		(layer "F.Cu")
		(net "M_E_CPU1_SA_DQS_DN<4>")
	)
	(segment
		(start 155.569158 -274.689824)
		(end 155.693618 -274.814284)
		(width 0.20066)
		(layer "F.Cu")
		(net "M_E_CPU1_SA_DQS_DN<4>")
	)
	(segment
		(start 154.456638 -274.689824)
		(end 154.581098 -274.814284)
		(width 0.20066)
		(layer "F.Cu")
		(net "M_E_CPU1_SA_DQS_DN<4>")
	)
	(segment
		(start 152.787858 -274.814284)
		(end 152.912318 -274.689824)
		(width 0.20066)
		(layer "F.Cu")
		(net "M_E_CPU1_SA_DQS_DN<4>")
	)
	(segment
		(start 157.795722 -274.752816)
		(end 157.881828 -274.66671)
		(width 0.20066)
		(layer "F.Cu")
		(net "M_E_CPU1_SA_DQS_DN<4>")
	)
	(segment
		(start 139.764516 -260.37413)
		(end 139.8905 -260.435852)
		(width 0.088646)
		(layer "F.Cu")
		(net "M_E_CPU1_SA_DQS_DN<4>")
	)
	(segment
		(start 140.82522 -261.226808)
		(end 140.95095 -261.352538)
		(width 0.088646)
		(layer "F.Cu")
		(net "M_E_CPU1_SA_DQS_DN<4>")
	)
	(segment
		(start 140.55598 -261.101332)
		(end 140.681456 -261.226808)
		(width 0.088646)
		(layer "F.Cu")
		(net "M_E_CPU1_SA_DQS_DN<4>")
	)
	(segment
		(start 139.8905 -260.435852)
		(end 140.286232 -260.831584)
		(width 0.088646)
		(layer "F.Cu")
		(net "M_E_CPU1_SA_DQS_DN<4>")
	)
	(segment
		(start 137.124694 -259.894832)
		(end 137.236454 -259.848604)
		(width 0.088646)
		(layer "F.Cu")
		(net "M_E_CPU1_SA_DQS_DN<4>")
	)
	(segment
		(start 151.741632 -274.851114)
		(end 152.281128 -274.851114)
		(width 0.1524)
		(layer "F.Cu")
		(net "M_E_CPU1_SA_DQS_DN<4>")
	)
	(segment
		(start 161.528506 -275.075904)
		(end 161.277046 -275.075904)
		(width 0.20066)
		(layer "F.Cu")
		(net "M_E_CPU1_SA_DQS_DN<4>")
	)
	(segment
		(start 161.9123 -275.091652)
		(end 161.544254 -275.091652)
		(width 0.101854)
		(layer "F.Cu")
		(net "M_E_CPU1_SA_DQS_DN<4>")
	)
	(segment
		(start 152.912318 -274.689824)
		(end 153.344118 -274.689824)
		(width 0.20066)
		(layer "F.Cu")
		(net "M_E_CPU1_SA_DQS_DN<4>")
	)
	(segment
		(start 156.524706 -274.814284)
		(end 156.74848 -275.038058)
		(width 0.20066)
		(layer "F.Cu")
		(net "M_E_CPU1_SA_DQS_DN<4>")
	)
	(segment
		(start 159.643572 -274.948396)
		(end 159.361886 -274.66671)
		(width 0.20066)
		(layer "F.Cu")
		(net "M_E_CPU1_SA_DQS_DN<4>")
	)
	(segment
		(start 140.95095 -261.352538)
		(end 140.95095 -261.496302)
		(width 0.088646)
		(layer "F.Cu")
		(net "M_E_CPU1_SA_DQS_DN<4>")
	)
	(segment
		(start 151.552656 -274.662138)
		(end 151.741632 -274.851114)
		(width 0.1524)
		(layer "F.Cu")
		(net "M_E_CPU1_SA_DQS_DN<4>")
	)
	(segment
		(start 157.7086 -275.188934)
		(end 157.795722 -275.101812)
		(width 0.20066)
		(layer "F.Cu")
		(net "M_E_CPU1_SA_DQS_DN<4>")
	)
	(segment
		(start 137.8712 -260.215126)
		(end 137.877296 -260.21919)
		(width 0.088646)
		(layer "F.Cu")
		(net "M_E_CPU1_SA_DQS_DN<4>")
	)
	(segment
		(start 150.871682 -271.371822)
		(end 151.472138 -274.37207)
		(width 0.1524)
		(layer "F.Cu")
		(net "M_E_CPU1_SA_DQS_DN<4>")
	)
	(segment
		(start 161.544254 -275.091652)
		(end 161.528506 -275.075904)
		(width 0.101854)
		(layer "F.Cu")
		(net "M_E_CPU1_SA_DQS_DN<4>")
	)
	(segment
		(start 164.064696 -275.091652)
		(end 163.891722 -275.091652)
		(width 0.101854)
		(layer "F.Cu")
		(net "M_E_CPU1_SA_DQS_DN<4>")
	)
	(segment
		(start 137.236454 -259.848604)
		(end 137.485374 -259.848604)
		(width 0.088646)
		(layer "F.Cu")
		(net "M_E_CPU1_SA_DQS_DN<4>")
	)
	(segment
		(start 153.468578 -274.814284)
		(end 153.900378 -274.814284)
		(width 0.20066)
		(layer "F.Cu")
		(net "M_E_CPU1_SA_DQS_DN<4>")
	)
	(segment
		(start 137.614152 -259.977382)
		(end 137.614152 -260.037326)
		(width 0.088646)
		(layer "F.Cu")
		(net "M_E_CPU1_SA_DQS_DN<4>")
	)
	(segment
		(start 156.863034 -275.085556)
		(end 157.112208 -275.188934)
		(width 0.20066)
		(layer "F.Cu")
		(net "M_E_CPU1_SA_DQS_DN<4>")
	)
	(segment
		(start 137.485374 -259.848604)
		(end 137.614152 -259.977382)
		(width 0.088646)
		(layer "F.Cu")
		(net "M_E_CPU1_SA_DQS_DN<4>")
	)
	(segment
		(start 140.55598 -260.957314)
		(end 140.55598 -261.101332)
		(width 0.088646)
		(layer "F.Cu")
		(net "M_E_CPU1_SA_DQS_DN<4>")
	)
	(segment
		(start 153.900378 -274.814284)
		(end 154.024838 -274.689824)
		(width 0.20066)
		(layer "F.Cu")
		(net "M_E_CPU1_SA_DQS_DN<4>")
	)
	(segment
		(start 140.43025 -260.831584)
		(end 140.55598 -260.957314)
		(width 0.088646)
		(layer "F.Cu")
		(net "M_E_CPU1_SA_DQS_DN<4>")
	)
	(segment
		(start 161.277046 -275.075904)
		(end 161.008314 -275.344636)
		(width 0.20066)
		(layer "F.Cu")
		(net "M_E_CPU1_SA_DQS_DN<4>")
	)
	(segment
		(start 152.317958 -274.814284)
		(end 152.356058 -274.814284)
		(width 0.1524)
		(layer "F.Cu")
		(net "M_E_CPU1_SA_DQS_DN<4>")
	)
	(segment
		(start 152.356058 -274.814284)
		(end 152.787858 -274.814284)
		(width 0.20066)
		(layer "F.Cu")
		(net "M_E_CPU1_SA_DQS_DN<4>")
	)
	(segment
		(start 155.137358 -274.689824)
		(end 155.569158 -274.689824)
		(width 0.20066)
		(layer "F.Cu")
		(net "M_E_CPU1_SA_DQS_DN<4>")
	)
	(segment
		(start 165.567868 -274.907248)
		(end 165.194742 -274.907248)
		(width 0.20066)
		(layer "F.Cu")
		(net "M_E_CPU1_SA_DQS_DN<4>")
	)
	(arc
		(start 138.252454 -260.219698)
		(mid 138.534475 -260.144142)
		(end 138.816588 -260.219444)
		(width 0.088646)
		(layer "F.Cu")
		(net "M_E_CPU1_SA_DQS_DN<4>")
	)
	(arc
		(start 138.816588 -260.219444)
		(mid 138.907121 -260.256998)
		(end 139.004294 -260.269736)
		(width 0.088646)
		(layer "F.Cu")
		(net "M_E_CPU1_SA_DQS_DN<4>")
	)
	(arc
		(start 138.251692 -260.21919)
		(mid 138.252073 -260.219444)
		(end 138.252454 -260.219698)
		(width 0.088646)
		(layer "F.Cu")
		(net "M_E_CPU1_SA_DQS_DN<4>")
	)
	(arc
		(start 137.68451 -260.107684)
		(mid 137.692077 -260.111612)
		(end 137.699496 -260.115812)
		(width 0.088646)
		(layer "F.Cu")
		(net "M_E_CPU1_SA_DQS_DN<4>")
	)
	(arc
		(start 137.877296 -260.21919)
		(mid 138.064494 -260.269333)
		(end 138.251692 -260.21919)
		(width 0.088646)
		(layer "F.Cu")
		(net "M_E_CPU1_SA_DQS_DN<4>")
	)
	(segment
		(start 164.784278 -284.667706)
		(end 164.479224 -284.667706)
		(width 0.20066)
		(layer "F.Cu")
		(net "M_E_CPU1_SA_DQS_DN<3>")
	)
	(segment
		(start 137.873232 -265.100308)
		(end 137.875264 -265.101324)
		(width 0.088646)
		(layer "F.Cu")
		(net "M_E_CPU1_SA_DQS_DN<3>")
	)
	(segment
		(start 165.567868 -284.257242)
		(end 165.194742 -284.257242)
		(width 0.20066)
		(layer "F.Cu")
		(net "M_E_CPU1_SA_DQS_DN<3>")
	)
	(segment
		(start 149.243796 -281.808174)
		(end 149.243796 -281.80792)
		(width 0.1524)
		(layer "F.Cu")
		(net "M_E_CPU1_SA_DQS_DN<3>")
	)
	(segment
		(start 149.29612 -281.808682)
		(end 149.323044 -281.835606)
		(width 0.1524)
		(layer "F.Cu")
		(net "M_E_CPU1_SA_DQS_DN<3>")
	)
	(segment
		(start 165.194742 -284.257242)
		(end 164.784278 -284.667706)
		(width 0.20066)
		(layer "F.Cu")
		(net "M_E_CPU1_SA_DQS_DN<3>")
	)
	(segment
		(start 137.870946 -265.098784)
		(end 137.873232 -265.100308)
		(width 0.088646)
		(layer "F.Cu")
		(net "M_E_CPU1_SA_DQS_DN<3>")
	)
	(segment
		(start 157.857444 -284.048454)
		(end 157.889194 -284.016704)
		(width 0.20066)
		(layer "F.Cu")
		(net "M_E_CPU1_SA_DQS_DN<3>")
	)
	(segment
		(start 164.24656 -284.435042)
		(end 163.923726 -284.435042)
		(width 0.20066)
		(layer "F.Cu")
		(net "M_E_CPU1_SA_DQS_DN<3>")
	)
	(segment
		(start 138.978386 -265.185906)
		(end 139.240514 -265.326368)
		(width 0.088646)
		(layer "F.Cu")
		(net "M_E_CPU1_SA_DQS_DN<3>")
	)
	(segment
		(start 137.386822 -264.50925)
		(end 137.784586 -265.022838)
		(width 0.088646)
		(layer "F.Cu")
		(net "M_E_CPU1_SA_DQS_DN<3>")
	)
	(segment
		(start 161.896552 -284.425898)
		(end 161.891726 -284.425898)
		(width 0.101854)
		(layer "F.Cu")
		(net "M_E_CPU1_SA_DQS_DN<3>")
	)
	(segment
		(start 140.58011 -266.620752)
		(end 140.595604 -266.636246)
		(width 0.088646)
		(layer "F.Cu")
		(net "M_E_CPU1_SA_DQS_DN<3>")
	)
	(segment
		(start 153.16708 -284.999684)
		(end 155.6004 -284.999684)
		(width 0.20066)
		(layer "F.Cu")
		(net "M_E_CPU1_SA_DQS_DN<3>")
	)
	(segment
		(start 137.868406 -265.097514)
		(end 137.870946 -265.098784)
		(width 0.088646)
		(layer "F.Cu")
		(net "M_E_CPU1_SA_DQS_DN<3>")
	)
	(segment
		(start 136.184894 -264.778236)
		(end 136.79424 -264.536428)
		(width 0.088646)
		(layer "F.Cu")
		(net "M_E_CPU1_SA_DQS_DN<3>")
	)
	(segment
		(start 147.174204 -273.214846)
		(end 148.805646 -281.370024)
		(width 0.1524)
		(layer "F.Cu")
		(net "M_E_CPU1_SA_DQS_DN<3>")
	)
	(segment
		(start 155.6004 -284.999684)
		(end 156.375862 -284.481524)
		(width 0.20066)
		(layer "F.Cu")
		(net "M_E_CPU1_SA_DQS_DN<3>")
	)
	(segment
		(start 160.471612 -284.29839)
		(end 159.643572 -284.29839)
		(width 0.20066)
		(layer "F.Cu")
		(net "M_E_CPU1_SA_DQS_DN<3>")
	)
	(segment
		(start 160.88614 -284.712918)
		(end 160.471612 -284.29839)
		(width 0.20066)
		(layer "F.Cu")
		(net "M_E_CPU1_SA_DQS_DN<3>")
	)
	(segment
		(start 161.602674 -284.425898)
		(end 161.315654 -284.712918)
		(width 0.20066)
		(layer "F.Cu")
		(net "M_E_CPU1_SA_DQS_DN<3>")
	)
	(segment
		(start 149.243796 -281.80792)
		(end 149.244558 -281.808682)
		(width 0.1524)
		(layer "F.Cu")
		(net "M_E_CPU1_SA_DQS_DN<3>")
	)
	(segment
		(start 148.805646 -281.370024)
		(end 149.243796 -281.808174)
		(width 0.1524)
		(layer "F.Cu")
		(net "M_E_CPU1_SA_DQS_DN<3>")
	)
	(segment
		(start 149.244558 -281.808682)
		(end 149.29612 -281.808682)
		(width 0.1524)
		(layer "F.Cu")
		(net "M_E_CPU1_SA_DQS_DN<3>")
	)
	(segment
		(start 136.79424 -264.536428)
		(end 136.982962 -264.443972)
		(width 0.088646)
		(layer "F.Cu")
		(net "M_E_CPU1_SA_DQS_DN<3>")
	)
	(segment
		(start 166.357046 -284.016704)
		(end 165.808406 -284.016704)
		(width 0.20066)
		(layer "F.Cu")
		(net "M_E_CPU1_SA_DQS_DN<3>")
	)
	(segment
		(start 139.240514 -265.326368)
		(end 140.534898 -266.620752)
		(width 0.088646)
		(layer "F.Cu")
		(net "M_E_CPU1_SA_DQS_DN<3>")
	)
	(segment
		(start 161.891726 -284.425898)
		(end 161.602674 -284.425898)
		(width 0.20066)
		(layer "F.Cu")
		(net "M_E_CPU1_SA_DQS_DN<3>")
	)
	(segment
		(start 163.917122 -284.441646)
		(end 161.9123 -284.441646)
		(width 0.1016)
		(layer "F.Cu")
		(net "M_E_CPU1_SA_DQS_DN<3>")
	)
	(segment
		(start 159.361886 -284.016704)
		(end 158.813246 -284.016704)
		(width 0.20066)
		(layer "F.Cu")
		(net "M_E_CPU1_SA_DQS_DN<3>")
	)
	(segment
		(start 163.923726 -284.435042)
		(end 163.917122 -284.441646)
		(width 0.1016)
		(layer "F.Cu")
		(net "M_E_CPU1_SA_DQS_DN<3>")
	)
	(segment
		(start 157.889194 -284.016704)
		(end 158.813246 -284.016704)
		(width 0.20066)
		(layer "F.Cu")
		(net "M_E_CPU1_SA_DQS_DN<3>")
	)
	(segment
		(start 149.323044 -281.835606)
		(end 152.0063 -284.518862)
		(width 0.20066)
		(layer "F.Cu")
		(net "M_E_CPU1_SA_DQS_DN<3>")
	)
	(segment
		(start 140.534898 -266.620752)
		(end 140.58011 -266.620752)
		(width 0.088646)
		(layer "F.Cu")
		(net "M_E_CPU1_SA_DQS_DN<3>")
	)
	(segment
		(start 161.315654 -284.712918)
		(end 160.88614 -284.712918)
		(width 0.20066)
		(layer "F.Cu")
		(net "M_E_CPU1_SA_DQS_DN<3>")
	)
	(segment
		(start 157.024324 -284.048454)
		(end 157.857444 -284.048454)
		(width 0.20066)
		(layer "F.Cu")
		(net "M_E_CPU1_SA_DQS_DN<3>")
	)
	(segment
		(start 161.9123 -284.441646)
		(end 161.896552 -284.425898)
		(width 0.1016)
		(layer "F.Cu")
		(net "M_E_CPU1_SA_DQS_DN<3>")
	)
	(segment
		(start 164.479224 -284.667706)
		(end 164.24656 -284.435042)
		(width 0.20066)
		(layer "F.Cu")
		(net "M_E_CPU1_SA_DQS_DN<3>")
	)
	(segment
		(start 140.595604 -266.636246)
		(end 147.174204 -273.214846)
		(width 0.1524)
		(layer "F.Cu")
		(net "M_E_CPU1_SA_DQS_DN<3>")
	)
	(segment
		(start 152.0063 -284.518862)
		(end 153.16708 -284.999684)
		(width 0.20066)
		(layer "F.Cu")
		(net "M_E_CPU1_SA_DQS_DN<3>")
	)
	(segment
		(start 159.643572 -284.29839)
		(end 159.361886 -284.016704)
		(width 0.20066)
		(layer "F.Cu")
		(net "M_E_CPU1_SA_DQS_DN<3>")
	)
	(segment
		(start 165.808406 -284.016704)
		(end 165.567868 -284.257242)
		(width 0.20066)
		(layer "F.Cu")
		(net "M_E_CPU1_SA_DQS_DN<3>")
	)
	(segment
		(start 156.375862 -284.481524)
		(end 156.376116 -284.48127)
		(width 0.20066)
		(layer "F.Cu")
		(net "M_E_CPU1_SA_DQS_DN<3>")
	)
	(segment
		(start 156.376116 -284.48127)
		(end 157.024324 -284.048454)
		(width 0.20066)
		(layer "F.Cu")
		(net "M_E_CPU1_SA_DQS_DN<3>")
	)
	(segment
		(start 137.875264 -265.101324)
		(end 137.877296 -265.102594)
		(width 0.088646)
		(layer "F.Cu")
		(net "M_E_CPU1_SA_DQS_DN<3>")
	)
	(arc
		(start 136.982962 -264.443972)
		(mid 137.19408 -264.419703)
		(end 137.386822 -264.50925)
		(width 0.088646)
		(layer "F.Cu")
		(net "M_E_CPU1_SA_DQS_DN<3>")
	)
	(arc
		(start 138.251692 -265.102594)
		(mid 138.628776 -265.024278)
		(end 138.978386 -265.185906)
		(width 0.088646)
		(layer "F.Cu")
		(net "M_E_CPU1_SA_DQS_DN<3>")
	)
	(arc
		(start 137.877296 -265.102594)
		(mid 138.064494 -265.152737)
		(end 138.251692 -265.102594)
		(width 0.088646)
		(layer "F.Cu")
		(net "M_E_CPU1_SA_DQS_DN<3>")
	)
	(arc
		(start 137.784586 -265.022838)
		(mid 137.823153 -265.063925)
		(end 137.868406 -265.097514)
		(width 0.088646)
		(layer "F.Cu")
		(net "M_E_CPU1_SA_DQS_DN<3>")
	)
	(segment
		(start 165.194742 -293.607236)
		(end 164.784278 -294.0177)
		(width 0.20066)
		(layer "F.Cu")
		(net "M_E_CPU1_SA_DQS_DN<2>")
	)
	(segment
		(start 164.24656 -293.785036)
		(end 163.923726 -293.785036)
		(width 0.20066)
		(layer "F.Cu")
		(net "M_E_CPU1_SA_DQS_DN<2>")
	)
	(segment
		(start 165.567868 -293.607236)
		(end 165.194742 -293.607236)
		(width 0.20066)
		(layer "F.Cu")
		(net "M_E_CPU1_SA_DQS_DN<2>")
	)
	(segment
		(start 157.321758 -293.698676)
		(end 157.908244 -293.698676)
		(width 0.20066)
		(layer "F.Cu")
		(net "M_E_CPU1_SA_DQS_DN<2>")
	)
	(segment
		(start 139.70889 -271.365726)
		(end 139.820396 -271.477232)
		(width 0.088646)
		(layer "F.Cu")
		(net "M_E_CPU1_SA_DQS_DN<2>")
	)
	(segment
		(start 163.923726 -293.785036)
		(end 163.917122 -293.79164)
		(width 0.1016)
		(layer "F.Cu")
		(net "M_E_CPU1_SA_DQS_DN<2>")
	)
	(segment
		(start 151.326088 -295.98112)
		(end 151.326088 -295.981374)
		(width 0.20066)
		(layer "F.Cu")
		(net "M_E_CPU1_SA_DQS_DN<2>")
	)
	(segment
		(start 161.9123 -293.79164)
		(end 161.896552 -293.775892)
		(width 0.1016)
		(layer "F.Cu")
		(net "M_E_CPU1_SA_DQS_DN<2>")
	)
	(segment
		(start 137.957306 -270.56588)
		(end 137.972546 -270.51762)
		(width 0.088646)
		(layer "F.Cu")
		(net "M_E_CPU1_SA_DQS_DN<2>")
	)
	(segment
		(start 139.846812 -271.477232)
		(end 143.552164 -275.182584)
		(width 0.1524)
		(layer "F.Cu")
		(net "M_E_CPU1_SA_DQS_DN<2>")
	)
	(segment
		(start 161.896552 -293.775892)
		(end 161.891726 -293.775892)
		(width 0.101854)
		(layer "F.Cu")
		(net "M_E_CPU1_SA_DQS_DN<2>")
	)
	(segment
		(start 136.184894 -269.66164)
		(end 136.853422 -269.945866)
		(width 0.088646)
		(layer "F.Cu")
		(net "M_E_CPU1_SA_DQS_DN<2>")
	)
	(segment
		(start 144.58315 -289.290252)
		(end 144.797526 -289.504882)
		(width 0.1524)
		(layer "F.Cu")
		(net "M_E_CPU1_SA_DQS_DN<2>")
	)
	(segment
		(start 144.797526 -289.504882)
		(end 144.84985 -289.504882)
		(width 0.1524)
		(layer "F.Cu")
		(net "M_E_CPU1_SA_DQS_DN<2>")
	)
	(segment
		(start 137.972546 -270.51762)
		(end 137.972546 -270.517112)
		(width 0.088646)
		(layer "F.Cu")
		(net "M_E_CPU1_SA_DQS_DN<2>")
	)
	(segment
		(start 137.405364 -270.79575)
		(end 137.408666 -270.797782)
		(width 0.088646)
		(layer "F.Cu")
		(net "M_E_CPU1_SA_DQS_DN<2>")
	)
	(segment
		(start 164.784278 -294.0177)
		(end 164.479224 -294.0177)
		(width 0.20066)
		(layer "F.Cu")
		(net "M_E_CPU1_SA_DQS_DN<2>")
	)
	(segment
		(start 151.326088 -295.981374)
		(end 155.03906 -295.981374)
		(width 0.20066)
		(layer "F.Cu")
		(net "M_E_CPU1_SA_DQS_DN<2>")
	)
	(segment
		(start 165.808406 -293.366698)
		(end 165.567868 -293.607236)
		(width 0.20066)
		(layer "F.Cu")
		(net "M_E_CPU1_SA_DQS_DN<2>")
	)
	(segment
		(start 155.03906 -295.981374)
		(end 157.321758 -293.698676)
		(width 0.20066)
		(layer "F.Cu")
		(net "M_E_CPU1_SA_DQS_DN<2>")
	)
	(segment
		(start 161.602674 -293.775892)
		(end 161.315654 -294.062912)
		(width 0.20066)
		(layer "F.Cu")
		(net "M_E_CPU1_SA_DQS_DN<2>")
	)
	(segment
		(start 164.479224 -294.0177)
		(end 164.24656 -293.785036)
		(width 0.20066)
		(layer "F.Cu")
		(net "M_E_CPU1_SA_DQS_DN<2>")
	)
	(segment
		(start 139.55014 -271.151096)
		(end 139.70889 -271.365726)
		(width 0.088646)
		(layer "F.Cu")
		(net "M_E_CPU1_SA_DQS_DN<2>")
	)
	(segment
		(start 163.917122 -293.79164)
		(end 161.9123 -293.79164)
		(width 0.1016)
		(layer "F.Cu")
		(net "M_E_CPU1_SA_DQS_DN<2>")
	)
	(segment
		(start 157.908244 -293.698676)
		(end 158.240222 -293.366698)
		(width 0.20066)
		(layer "F.Cu")
		(net "M_E_CPU1_SA_DQS_DN<2>")
	)
	(segment
		(start 161.315654 -294.062912)
		(end 160.88614 -294.062912)
		(width 0.20066)
		(layer "F.Cu")
		(net "M_E_CPU1_SA_DQS_DN<2>")
	)
	(segment
		(start 159.643572 -293.648384)
		(end 159.361886 -293.366698)
		(width 0.20066)
		(layer "F.Cu")
		(net "M_E_CPU1_SA_DQS_DN<2>")
	)
	(segment
		(start 143.552164 -275.182584)
		(end 144.58315 -280.336498)
		(width 0.1524)
		(layer "F.Cu")
		(net "M_E_CPU1_SA_DQS_DN<2>")
	)
	(segment
		(start 139.19581 -270.592296)
		(end 139.209272 -270.624046)
		(width 0.088646)
		(layer "F.Cu")
		(net "M_E_CPU1_SA_DQS_DN<2>")
	)
	(segment
		(start 166.357046 -293.366698)
		(end 165.808406 -293.366698)
		(width 0.20066)
		(layer "F.Cu")
		(net "M_E_CPU1_SA_DQS_DN<2>")
	)
	(segment
		(start 138.544554 -269.94739)
		(end 138.655044 -269.94739)
		(width 0.088646)
		(layer "F.Cu")
		(net "M_E_CPU1_SA_DQS_DN<2>")
	)
	(segment
		(start 137.408666 -270.797782)
		(end 137.409936 -270.79829)
		(width 0.088646)
		(layer "F.Cu")
		(net "M_E_CPU1_SA_DQS_DN<2>")
	)
	(segment
		(start 144.58315 -280.336498)
		(end 144.58315 -289.290252)
		(width 0.1524)
		(layer "F.Cu")
		(net "M_E_CPU1_SA_DQS_DN<2>")
	)
	(segment
		(start 137.213086 -270.357346)
		(end 137.21334 -270.357346)
		(width 0.088646)
		(layer "F.Cu")
		(net "M_E_CPU1_SA_DQS_DN<2>")
	)
	(segment
		(start 160.88614 -294.062912)
		(end 160.471612 -293.648384)
		(width 0.20066)
		(layer "F.Cu")
		(net "M_E_CPU1_SA_DQS_DN<2>")
	)
	(segment
		(start 139.820396 -271.477232)
		(end 139.846812 -271.477232)
		(width 0.088646)
		(layer "F.Cu")
		(net "M_E_CPU1_SA_DQS_DN<2>")
	)
	(segment
		(start 139.015724 -270.108934)
		(end 139.016232 -270.109442)
		(width 0.088646)
		(layer "F.Cu")
		(net "M_E_CPU1_SA_DQS_DN<2>")
	)
	(segment
		(start 139.232132 -270.665194)
		(end 139.239752 -270.68272)
		(width 0.088646)
		(layer "F.Cu")
		(net "M_E_CPU1_SA_DQS_DN<2>")
	)
	(segment
		(start 139.016232 -270.109442)
		(end 139.015978 -270.109442)
		(width 0.088646)
		(layer "F.Cu")
		(net "M_E_CPU1_SA_DQS_DN<2>")
	)
	(segment
		(start 159.361886 -293.366698)
		(end 158.813246 -293.366698)
		(width 0.20066)
		(layer "F.Cu")
		(net "M_E_CPU1_SA_DQS_DN<2>")
	)
	(segment
		(start 144.84985 -289.504882)
		(end 151.326088 -295.98112)
		(width 0.20066)
		(layer "F.Cu")
		(net "M_E_CPU1_SA_DQS_DN<2>")
	)
	(segment
		(start 158.240222 -293.366698)
		(end 158.813246 -293.366698)
		(width 0.20066)
		(layer "F.Cu")
		(net "M_E_CPU1_SA_DQS_DN<2>")
	)
	(segment
		(start 139.243308 -270.691356)
		(end 139.55014 -271.151096)
		(width 0.088646)
		(layer "F.Cu")
		(net "M_E_CPU1_SA_DQS_DN<2>")
	)
	(segment
		(start 161.891726 -293.775892)
		(end 161.602674 -293.775892)
		(width 0.20066)
		(layer "F.Cu")
		(net "M_E_CPU1_SA_DQS_DN<2>")
	)
	(segment
		(start 139.209272 -270.624046)
		(end 139.232132 -270.665194)
		(width 0.088646)
		(layer "F.Cu")
		(net "M_E_CPU1_SA_DQS_DN<2>")
	)
	(segment
		(start 160.471612 -293.648384)
		(end 159.643572 -293.648384)
		(width 0.20066)
		(layer "F.Cu")
		(net "M_E_CPU1_SA_DQS_DN<2>")
	)
	(segment
		(start 139.239752 -270.68272)
		(end 139.243308 -270.691356)
		(width 0.088646)
		(layer "F.Cu")
		(net "M_E_CPU1_SA_DQS_DN<2>")
	)
	(segment
		(start 136.853422 -269.945866)
		(end 136.853168 -269.946628)
		(width 0.088646)
		(layer "F.Cu")
		(net "M_E_CPU1_SA_DQS_DN<2>")
	)
	(segment
		(start 138.87704 -270.00327)
		(end 138.881358 -270.00581)
		(width 0.088646)
		(layer "F.Cu")
		(net "M_E_CPU1_SA_DQS_DN<2>")
	)
	(arc
		(start 139.166092 -270.450056)
		(mid 139.174189 -270.522589)
		(end 139.19581 -270.592296)
		(width 0.088646)
		(layer "F.Cu")
		(net "M_E_CPU1_SA_DQS_DN<2>")
	)
	(arc
		(start 137.232136 -270.488156)
		(mid 137.281091 -270.663158)
		(end 137.405364 -270.79575)
		(width 0.088646)
		(layer "F.Cu")
		(net "M_E_CPU1_SA_DQS_DN<2>")
	)
	(arc
		(start 138.881358 -270.00581)
		(mid 138.952202 -270.052601)
		(end 139.015724 -270.108934)
		(width 0.088646)
		(layer "F.Cu")
		(net "M_E_CPU1_SA_DQS_DN<2>")
	)
	(arc
		(start 137.451338 -270.81861)
		(mid 137.757514 -270.798773)
		(end 137.957306 -270.56588)
		(width 0.088646)
		(layer "F.Cu")
		(net "M_E_CPU1_SA_DQS_DN<2>")
	)
	(arc
		(start 137.981182 -270.472408)
		(mid 138.15955 -270.099067)
		(end 138.544554 -269.94739)
		(width 0.088646)
		(layer "F.Cu")
		(net "M_E_CPU1_SA_DQS_DN<2>")
	)
	(arc
		(start 137.049764 -270.073374)
		(mid 137.150227 -270.204543)
		(end 137.213086 -270.357346)
		(width 0.088646)
		(layer "F.Cu")
		(net "M_E_CPU1_SA_DQS_DN<2>")
	)
	(arc
		(start 137.409936 -270.79829)
		(mid 137.43001 -270.809727)
		(end 137.451338 -270.81861)
		(width 0.088646)
		(layer "F.Cu")
		(net "M_E_CPU1_SA_DQS_DN<2>")
	)
	(arc
		(start 137.21334 -270.357346)
		(mid 137.226463 -270.422215)
		(end 137.232136 -270.488156)
		(width 0.088646)
		(layer "F.Cu")
		(net "M_E_CPU1_SA_DQS_DN<2>")
	)
	(arc
		(start 137.972546 -270.517112)
		(mid 137.978221 -270.495021)
		(end 137.981182 -270.472408)
		(width 0.088646)
		(layer "F.Cu")
		(net "M_E_CPU1_SA_DQS_DN<2>")
	)
	(arc
		(start 138.655044 -269.94739)
		(mid 138.769519 -269.961514)
		(end 138.87704 -270.00327)
		(width 0.088646)
		(layer "F.Cu")
		(net "M_E_CPU1_SA_DQS_DN<2>")
	)
	(arc
		(start 139.015978 -270.109442)
		(mid 139.126301 -270.264196)
		(end 139.166092 -270.450056)
		(width 0.088646)
		(layer "F.Cu")
		(net "M_E_CPU1_SA_DQS_DN<2>")
	)
	(arc
		(start 136.853168 -269.946628)
		(mid 136.958168 -269.999603)
		(end 137.049764 -270.073374)
		(width 0.088646)
		(layer "F.Cu")
		(net "M_E_CPU1_SA_DQS_DN<2>")
	)
	(segment
		(start 132.895848 -272.639028)
		(end 132.895594 -272.639282)
		(width 0.20066)
		(layer "F.Cu")
		(net "M_E_CPU1_SA_DQS_DN<1>")
	)
	(segment
		(start 159.361886 -302.716692)
		(end 158.813246 -302.716692)
		(width 0.20066)
		(layer "F.Cu")
		(net "M_E_CPU1_SA_DQS_DN<1>")
	)
	(segment
		(start 163.907216 -303.141634)
		(end 161.896552 -303.141634)
		(width 0.1016)
		(layer "F.Cu")
		(net "M_E_CPU1_SA_DQS_DN<1>")
	)
	(segment
		(start 165.517576 -302.966882)
		(end 165.21557 -302.966882)
		(width 0.20066)
		(layer "F.Cu")
		(net "M_E_CPU1_SA_DQS_DN<1>")
	)
	(segment
		(start 161.315654 -303.412906)
		(end 160.818322 -303.412906)
		(width 0.20066)
		(layer "F.Cu")
		(net "M_E_CPU1_SA_DQS_DN<1>")
	)
	(segment
		(start 132.895848 -272.103342)
		(end 132.895848 -272.639028)
		(width 0.20066)
		(layer "F.Cu")
		(net "M_E_CPU1_SA_DQS_DN<1>")
	)
	(segment
		(start 164.814758 -303.367694)
		(end 164.479224 -303.367694)
		(width 0.20066)
		(layer "F.Cu")
		(net "M_E_CPU1_SA_DQS_DN<1>")
	)
	(segment
		(start 164.236654 -303.125124)
		(end 163.923726 -303.125124)
		(width 0.20066)
		(layer "F.Cu")
		(net "M_E_CPU1_SA_DQS_DN<1>")
	)
	(segment
		(start 160.403794 -302.998378)
		(end 159.643572 -302.998378)
		(width 0.20066)
		(layer "F.Cu")
		(net "M_E_CPU1_SA_DQS_DN<1>")
	)
	(segment
		(start 159.643572 -302.998378)
		(end 159.361886 -302.716692)
		(width 0.20066)
		(layer "F.Cu")
		(net "M_E_CPU1_SA_DQS_DN<1>")
	)
	(segment
		(start 163.923726 -303.125124)
		(end 163.907216 -303.141634)
		(width 0.1016)
		(layer "F.Cu")
		(net "M_E_CPU1_SA_DQS_DN<1>")
	)
	(segment
		(start 160.818322 -303.412906)
		(end 160.403794 -302.998378)
		(width 0.20066)
		(layer "F.Cu")
		(net "M_E_CPU1_SA_DQS_DN<1>")
	)
	(segment
		(start 165.21557 -302.966882)
		(end 164.814758 -303.367694)
		(width 0.20066)
		(layer "F.Cu")
		(net "M_E_CPU1_SA_DQS_DN<1>")
	)
	(segment
		(start 164.479224 -303.367694)
		(end 164.236654 -303.125124)
		(width 0.20066)
		(layer "F.Cu")
		(net "M_E_CPU1_SA_DQS_DN<1>")
	)
	(segment
		(start 161.69386 -303.141634)
		(end 161.586926 -303.141634)
		(width 0.20066)
		(layer "F.Cu")
		(net "M_E_CPU1_SA_DQS_DN<1>")
	)
	(segment
		(start 161.586926 -303.141634)
		(end 161.315654 -303.412906)
		(width 0.20066)
		(layer "F.Cu")
		(net "M_E_CPU1_SA_DQS_DN<1>")
	)
	(segment
		(start 161.896552 -303.141634)
		(end 161.69386 -303.141634)
		(width 0.101854)
		(layer "F.Cu")
		(net "M_E_CPU1_SA_DQS_DN<1>")
	)
	(segment
		(start 157.682946 -302.716692)
		(end 158.813246 -302.716692)
		(width 0.20066)
		(layer "F.Cu")
		(net "M_E_CPU1_SA_DQS_DN<1>")
	)
	(segment
		(start 166.357046 -302.716692)
		(end 165.767766 -302.716692)
		(width 0.20066)
		(layer "F.Cu")
		(net "M_E_CPU1_SA_DQS_DN<1>")
	)
	(segment
		(start 165.767766 -302.716692)
		(end 165.517576 -302.966882)
		(width 0.20066)
		(layer "F.Cu")
		(net "M_E_CPU1_SA_DQS_DN<1>")
	)
	(segment
		(start 135.52551 -272.96237)
		(end 135.516366 -272.957036)
		(width 0.088646)
		(layer "In2.Cu")
		(net "M_E_CPU1_SA_DQS_DN<1>")
	)
	(segment
		(start 133.408166 -272.639282)
		(end 132.895594 -272.639282)
		(width 0.088646)
		(layer "In2.Cu")
		(net "M_E_CPU1_SA_DQS_DN<1>")
	)
	(segment
		(start 134.196836 -272.515838)
		(end 134.15899 -272.450306)
		(width 0.088646)
		(layer "In2.Cu")
		(net "M_E_CPU1_SA_DQS_DN<1>")
	)
	(segment
		(start 157.682946 -302.716692)
		(end 157.429454 -302.970184)
		(width 0.18288)
		(layer "In2.Cu")
		(net "M_E_CPU1_SA_DQS_DN<1>")
	)
	(segment
		(start 135.516366 -272.957036)
		(end 135.513064 -272.955004)
		(width 0.088646)
		(layer "In2.Cu")
		(net "M_E_CPU1_SA_DQS_DN<1>")
	)
	(segment
		(start 149.498304 -287.327086)
		(end 149.498304 -283.387546)
		(width 0.18288)
		(layer "In2.Cu")
		(net "M_E_CPU1_SA_DQS_DN<1>")
	)
	(segment
		(start 134.523734 -272.925286)
		(end 134.196836 -272.515838)
		(width 0.088646)
		(layer "In2.Cu")
		(net "M_E_CPU1_SA_DQS_DN<1>")
	)
	(segment
		(start 144.73555 -276.887686)
		(end 141.52118 -273.67357)
		(width 0.18288)
		(layer "In2.Cu")
		(net "M_E_CPU1_SA_DQS_DN<1>")
	)
	(segment
		(start 152.862788 -290.69157)
		(end 149.498304 -287.327086)
		(width 0.18288)
		(layer "In2.Cu")
		(net "M_E_CPU1_SA_DQS_DN<1>")
	)
	(segment
		(start 140.084302 -273.733514)
		(end 139.40409 -273.053302)
		(width 0.088646)
		(layer "In2.Cu")
		(net "M_E_CPU1_SA_DQS_DN<1>")
	)
	(segment
		(start 157.429454 -302.970184)
		(end 156.969206 -302.970184)
		(width 0.18288)
		(layer "In2.Cu")
		(net "M_E_CPU1_SA_DQS_DN<1>")
	)
	(segment
		(start 156.969206 -302.970184)
		(end 155.132024 -301.133002)
		(width 0.18288)
		(layer "In2.Cu")
		(net "M_E_CPU1_SA_DQS_DN<1>")
	)
	(segment
		(start 134.599934 -272.971006)
		(end 134.523734 -272.925286)
		(width 0.088646)
		(layer "In2.Cu")
		(net "M_E_CPU1_SA_DQS_DN<1>")
	)
	(segment
		(start 134.962646 -272.963386)
		(end 134.9629 -272.963894)
		(width 0.088646)
		(layer "In2.Cu")
		(net "M_E_CPU1_SA_DQS_DN<1>")
	)
	(segment
		(start 141.52118 -273.67357)
		(end 140.900658 -273.67357)
		(width 0.18288)
		(layer "In2.Cu")
		(net "M_E_CPU1_SA_DQS_DN<1>")
	)
	(segment
		(start 149.498304 -283.387546)
		(end 145.964402 -279.853644)
		(width 0.18288)
		(layer "In2.Cu")
		(net "M_E_CPU1_SA_DQS_DN<1>")
	)
	(segment
		(start 140.900658 -273.67357)
		(end 140.840714 -273.733514)
		(width 0.088646)
		(layer "In2.Cu")
		(net "M_E_CPU1_SA_DQS_DN<1>")
	)
	(segment
		(start 145.964402 -279.853644)
		(end 144.73555 -276.887686)
		(width 0.18288)
		(layer "In2.Cu")
		(net "M_E_CPU1_SA_DQS_DN<1>")
	)
	(segment
		(start 133.465316 -272.582132)
		(end 133.408166 -272.639282)
		(width 0.088646)
		(layer "In2.Cu")
		(net "M_E_CPU1_SA_DQS_DN<1>")
	)
	(segment
		(start 155.132024 -296.18051)
		(end 152.862788 -290.69157)
		(width 0.18288)
		(layer "In2.Cu")
		(net "M_E_CPU1_SA_DQS_DN<1>")
	)
	(segment
		(start 135.527796 -272.96364)
		(end 135.52551 -272.96237)
		(width 0.088646)
		(layer "In2.Cu")
		(net "M_E_CPU1_SA_DQS_DN<1>")
	)
	(segment
		(start 140.840714 -273.733514)
		(end 140.084302 -273.733514)
		(width 0.088646)
		(layer "In2.Cu")
		(net "M_E_CPU1_SA_DQS_DN<1>")
	)
	(segment
		(start 155.132024 -301.133002)
		(end 155.132024 -296.18051)
		(width 0.18288)
		(layer "In2.Cu")
		(net "M_E_CPU1_SA_DQS_DN<1>")
	)
	(arc
		(start 137.781792 -272.96364)
		(mid 137.594594 -273.013783)
		(end 137.407396 -272.96364)
		(width 0.088646)
		(layer "In2.Cu")
		(net "M_E_CPU1_SA_DQS_DN<1>")
	)
	(arc
		(start 134.9629 -272.963894)
		(mid 134.782329 -273.014312)
		(end 134.599934 -272.971006)
		(width 0.088646)
		(layer "In2.Cu")
		(net "M_E_CPU1_SA_DQS_DN<1>")
	)
	(arc
		(start 136.467596 -272.96364)
		(mid 136.184894 -272.887864)
		(end 135.902192 -272.96364)
		(width 0.088646)
		(layer "In2.Cu")
		(net "M_E_CPU1_SA_DQS_DN<1>")
	)
	(arc
		(start 138.347196 -272.96364)
		(mid 138.064494 -272.887864)
		(end 137.781792 -272.96364)
		(width 0.088646)
		(layer "In2.Cu")
		(net "M_E_CPU1_SA_DQS_DN<1>")
	)
	(arc
		(start 138.721592 -272.96364)
		(mid 138.534394 -273.013783)
		(end 138.347196 -272.96364)
		(width 0.088646)
		(layer "In2.Cu")
		(net "M_E_CPU1_SA_DQS_DN<1>")
	)
	(arc
		(start 134.15899 -272.450306)
		(mid 134.093395 -272.36727)
		(end 134.007098 -272.306034)
		(width 0.088646)
		(layer "In2.Cu")
		(net "M_E_CPU1_SA_DQS_DN<1>")
	)
	(arc
		(start 135.902192 -272.96364)
		(mid 135.714994 -273.013783)
		(end 135.527796 -272.96364)
		(width 0.088646)
		(layer "In2.Cu")
		(net "M_E_CPU1_SA_DQS_DN<1>")
	)
	(arc
		(start 136.841992 -272.96364)
		(mid 136.654794 -273.013783)
		(end 136.467596 -272.96364)
		(width 0.088646)
		(layer "In2.Cu")
		(net "M_E_CPU1_SA_DQS_DN<1>")
	)
	(arc
		(start 137.407396 -272.96364)
		(mid 137.124694 -272.887864)
		(end 136.841992 -272.96364)
		(width 0.088646)
		(layer "In2.Cu")
		(net "M_E_CPU1_SA_DQS_DN<1>")
	)
	(arc
		(start 134.007098 -272.306034)
		(mid 133.665544 -272.305345)
		(end 133.465316 -272.582132)
		(width 0.088646)
		(layer "In2.Cu")
		(net "M_E_CPU1_SA_DQS_DN<1>")
	)
	(arc
		(start 139.40409 -273.053302)
		(mid 139.348485 -273.004628)
		(end 139.286996 -272.96364)
		(width 0.088646)
		(layer "In2.Cu")
		(net "M_E_CPU1_SA_DQS_DN<1>")
	)
	(arc
		(start 135.513064 -272.955004)
		(mid 135.236762 -272.887682)
		(end 134.962646 -272.963386)
		(width 0.088646)
		(layer "In2.Cu")
		(net "M_E_CPU1_SA_DQS_DN<1>")
	)
	(arc
		(start 139.286996 -272.96364)
		(mid 139.004294 -272.887864)
		(end 138.721592 -272.96364)
		(width 0.088646)
		(layer "In2.Cu")
		(net "M_E_CPU1_SA_DQS_DN<1>")
	)
	(segment
		(start 153.044398 -308.868064)
		(end 153.470356 -309.294022)
		(width 0.20066)
		(layer "F.Cu")
		(net "M_E_CPU1_SA_DQS_DN<0>")
	)
	(segment
		(start 161.891726 -312.462418)
		(end 161.337752 -312.462418)
		(width 0.20066)
		(layer "F.Cu")
		(net "M_E_CPU1_SA_DQS_DN<0>")
	)
	(segment
		(start 154.497786 -310.321452)
		(end 154.497786 -310.49722)
		(width 0.20066)
		(layer "F.Cu")
		(net "M_E_CPU1_SA_DQS_DN<0>")
	)
	(segment
		(start 139.056364 -276.548596)
		(end 139.259818 -276.75205)
		(width 0.088646)
		(layer "F.Cu")
		(net "M_E_CPU1_SA_DQS_DN<0>")
	)
	(segment
		(start 161.337752 -312.462418)
		(end 161.03727 -312.7629)
		(width 0.20066)
		(layer "F.Cu")
		(net "M_E_CPU1_SA_DQS_DN<0>")
	)
	(segment
		(start 139.056364 -276.548342)
		(end 139.056364 -276.548596)
		(width 0.088646)
		(layer "F.Cu")
		(net "M_E_CPU1_SA_DQS_DN<0>")
	)
	(segment
		(start 165.843966 -312.066686)
		(end 165.603428 -312.307224)
		(width 0.20066)
		(layer "F.Cu")
		(net "M_E_CPU1_SA_DQS_DN<0>")
	)
	(segment
		(start 160.484312 -312.7629)
		(end 160.069784 -312.348372)
		(width 0.20066)
		(layer "F.Cu")
		(net "M_E_CPU1_SA_DQS_DN<0>")
	)
	(segment
		(start 159.361886 -312.066686)
		(end 158.813246 -312.066686)
		(width 0.20066)
		(layer "F.Cu")
		(net "M_E_CPU1_SA_DQS_DN<0>")
	)
	(segment
		(start 165.603428 -312.307224)
		(end 165.283134 -312.307224)
		(width 0.20066)
		(layer "F.Cu")
		(net "M_E_CPU1_SA_DQS_DN<0>")
	)
	(segment
		(start 137.962386 -276.200108)
		(end 137.881868 -276.339808)
		(width 0.088646)
		(layer "F.Cu")
		(net "M_E_CPU1_SA_DQS_DN<0>")
	)
	(segment
		(start 153.470356 -309.470044)
		(end 153.895806 -309.895494)
		(width 0.20066)
		(layer "F.Cu")
		(net "M_E_CPU1_SA_DQS_DN<0>")
	)
	(segment
		(start 153.895806 -309.895494)
		(end 154.071828 -309.895494)
		(width 0.20066)
		(layer "F.Cu")
		(net "M_E_CPU1_SA_DQS_DN<0>")
	)
	(segment
		(start 163.923726 -312.485786)
		(end 163.917884 -312.491628)
		(width 0.1016)
		(layer "F.Cu")
		(net "M_E_CPU1_SA_DQS_DN<0>")
	)
	(segment
		(start 154.913838 -310.913272)
		(end 156.59481 -312.036206)
		(width 0.20066)
		(layer "F.Cu")
		(net "M_E_CPU1_SA_DQS_DN<0>")
	)
	(segment
		(start 141.504416 -296.660316)
		(end 141.55674 -296.660316)
		(width 0.1524)
		(layer "F.Cu")
		(net "M_E_CPU1_SA_DQS_DN<0>")
	)
	(segment
		(start 141.583664 -296.68724)
		(end 141.918944 -297.02252)
		(width 0.20066)
		(layer "F.Cu")
		(net "M_E_CPU1_SA_DQS_DN<0>")
	)
	(segment
		(start 161.896552 -312.462418)
		(end 161.891726 -312.462418)
		(width 0.101854)
		(layer "F.Cu")
		(net "M_E_CPU1_SA_DQS_DN<0>")
	)
	(segment
		(start 140.625576 -293.563548)
		(end 141.146022 -296.177462)
		(width 0.1524)
		(layer "F.Cu")
		(net "M_E_CPU1_SA_DQS_DN<0>")
	)
	(segment
		(start 154.071828 -309.895494)
		(end 154.497786 -310.321452)
		(width 0.20066)
		(layer "F.Cu")
		(net "M_E_CPU1_SA_DQS_DN<0>")
	)
	(segment
		(start 164.406834 -312.485786)
		(end 163.923726 -312.485786)
		(width 0.20066)
		(layer "F.Cu")
		(net "M_E_CPU1_SA_DQS_DN<0>")
	)
	(segment
		(start 141.918944 -297.02252)
		(end 146.021552 -302.020986)
		(width 0.20066)
		(layer "F.Cu")
		(net "M_E_CPU1_SA_DQS_DN<0>")
	)
	(segment
		(start 166.357046 -312.066686)
		(end 165.843966 -312.066686)
		(width 0.20066)
		(layer "F.Cu")
		(net "M_E_CPU1_SA_DQS_DN<0>")
	)
	(segment
		(start 141.146022 -296.177462)
		(end 141.289024 -296.444924)
		(width 0.1524)
		(layer "F.Cu")
		(net "M_E_CPU1_SA_DQS_DN<0>")
	)
	(segment
		(start 139.259818 -276.75205)
		(end 139.259818 -276.951694)
		(width 0.088646)
		(layer "F.Cu")
		(net "M_E_CPU1_SA_DQS_DN<0>")
	)
	(segment
		(start 157.991048 -312.296302)
		(end 158.220664 -312.066686)
		(width 0.20066)
		(layer "F.Cu")
		(net "M_E_CPU1_SA_DQS_DN<0>")
	)
	(segment
		(start 164.845238 -312.74512)
		(end 164.666168 -312.74512)
		(width 0.20066)
		(layer "F.Cu")
		(net "M_E_CPU1_SA_DQS_DN<0>")
	)
	(segment
		(start 159.643572 -312.348372)
		(end 159.361886 -312.066686)
		(width 0.20066)
		(layer "F.Cu")
		(net "M_E_CPU1_SA_DQS_DN<0>")
	)
	(segment
		(start 163.917884 -312.491628)
		(end 161.925762 -312.491628)
		(width 0.1016)
		(layer "F.Cu")
		(net "M_E_CPU1_SA_DQS_DN<0>")
	)
	(segment
		(start 156.59481 -312.036206)
		(end 157.169866 -312.296302)
		(width 0.20066)
		(layer "F.Cu")
		(net "M_E_CPU1_SA_DQS_DN<0>")
	)
	(segment
		(start 146.021552 -302.020986)
		(end 152.86863 -308.868064)
		(width 0.20066)
		(layer "F.Cu")
		(net "M_E_CPU1_SA_DQS_DN<0>")
	)
	(segment
		(start 160.069784 -312.348372)
		(end 159.643572 -312.348372)
		(width 0.20066)
		(layer "F.Cu")
		(net "M_E_CPU1_SA_DQS_DN<0>")
	)
	(segment
		(start 138.75004 -276.421342)
		(end 139.056364 -276.548342)
		(width 0.088646)
		(layer "F.Cu")
		(net "M_E_CPU1_SA_DQS_DN<0>")
	)
	(segment
		(start 141.55674 -296.660316)
		(end 141.583664 -296.68724)
		(width 0.1524)
		(layer "F.Cu")
		(net "M_E_CPU1_SA_DQS_DN<0>")
	)
	(segment
		(start 161.925762 -312.491628)
		(end 161.896552 -312.462418)
		(width 0.1016)
		(layer "F.Cu")
		(net "M_E_CPU1_SA_DQS_DN<0>")
	)
	(segment
		(start 164.666168 -312.74512)
		(end 164.406834 -312.485786)
		(width 0.20066)
		(layer "F.Cu")
		(net "M_E_CPU1_SA_DQS_DN<0>")
	)
	(segment
		(start 161.03727 -312.7629)
		(end 160.484312 -312.7629)
		(width 0.20066)
		(layer "F.Cu")
		(net "M_E_CPU1_SA_DQS_DN<0>")
	)
	(segment
		(start 154.497786 -310.49722)
		(end 154.913838 -310.913272)
		(width 0.20066)
		(layer "F.Cu")
		(net "M_E_CPU1_SA_DQS_DN<0>")
	)
	(segment
		(start 157.169866 -312.296302)
		(end 157.991048 -312.296302)
		(width 0.20066)
		(layer "F.Cu")
		(net "M_E_CPU1_SA_DQS_DN<0>")
	)
	(segment
		(start 139.259818 -276.951694)
		(end 139.448286 -277.140162)
		(width 0.088646)
		(layer "F.Cu")
		(net "M_E_CPU1_SA_DQS_DN<0>")
	)
	(segment
		(start 138.064494 -276.172676)
		(end 137.962386 -276.200108)
		(width 0.088646)
		(layer "F.Cu")
		(net "M_E_CPU1_SA_DQS_DN<0>")
	)
	(segment
		(start 153.470356 -309.294022)
		(end 153.470356 -309.470044)
		(width 0.20066)
		(layer "F.Cu")
		(net "M_E_CPU1_SA_DQS_DN<0>")
	)
	(segment
		(start 139.493498 -277.140162)
		(end 139.508992 -277.155656)
		(width 0.088646)
		(layer "F.Cu")
		(net "M_E_CPU1_SA_DQS_DN<0>")
	)
	(segment
		(start 141.289024 -296.444924)
		(end 141.504416 -296.660316)
		(width 0.1524)
		(layer "F.Cu")
		(net "M_E_CPU1_SA_DQS_DN<0>")
	)
	(segment
		(start 152.86863 -308.868064)
		(end 153.044398 -308.868064)
		(width 0.20066)
		(layer "F.Cu")
		(net "M_E_CPU1_SA_DQS_DN<0>")
	)
	(segment
		(start 158.220664 -312.066686)
		(end 158.813246 -312.066686)
		(width 0.20066)
		(layer "F.Cu")
		(net "M_E_CPU1_SA_DQS_DN<0>")
	)
	(segment
		(start 138.53414 -276.421342)
		(end 138.75004 -276.421342)
		(width 0.088646)
		(layer "F.Cu")
		(net "M_E_CPU1_SA_DQS_DN<0>")
	)
	(segment
		(start 137.881868 -276.339808)
		(end 137.931144 -276.522434)
		(width 0.088646)
		(layer "F.Cu")
		(net "M_E_CPU1_SA_DQS_DN<0>")
	)
	(segment
		(start 165.283134 -312.307224)
		(end 164.845238 -312.74512)
		(width 0.20066)
		(layer "F.Cu")
		(net "M_E_CPU1_SA_DQS_DN<0>")
	)
	(segment
		(start 140.625576 -280.616914)
		(end 140.625576 -293.563548)
		(width 0.1524)
		(layer "F.Cu")
		(net "M_E_CPU1_SA_DQS_DN<0>")
	)
	(segment
		(start 139.508992 -277.155656)
		(end 139.92352 -277.570184)
		(width 0.1524)
		(layer "F.Cu")
		(net "M_E_CPU1_SA_DQS_DN<0>")
	)
	(segment
		(start 139.448286 -277.140162)
		(end 139.493498 -277.140162)
		(width 0.088646)
		(layer "F.Cu")
		(net "M_E_CPU1_SA_DQS_DN<0>")
	)
	(segment
		(start 139.92352 -277.570184)
		(end 140.625576 -280.616914)
		(width 0.1524)
		(layer "F.Cu")
		(net "M_E_CPU1_SA_DQS_DN<0>")
	)
	(arc
		(start 137.931144 -276.522434)
		(mid 138.094289 -276.545916)
		(end 138.251692 -276.497034)
		(width 0.088646)
		(layer "F.Cu")
		(net "M_E_CPU1_SA_DQS_DN<0>")
	)
	(arc
		(start 138.251692 -276.497034)
		(mid 138.372156 -276.444985)
		(end 138.501374 -276.422104)
		(width 0.088646)
		(layer "F.Cu")
		(net "M_E_CPU1_SA_DQS_DN<0>")
	)
	(arc
		(start 138.533632 -276.421342)
		(mid 138.533886 -276.421342)
		(end 138.53414 -276.421342)
		(width 0.088646)
		(layer "F.Cu")
		(net "M_E_CPU1_SA_DQS_DN<0>")
	)
	(arc
		(start 138.501374 -276.422104)
		(mid 138.517498 -276.421493)
		(end 138.533632 -276.421342)
		(width 0.088646)
		(layer "F.Cu")
		(net "M_E_CPU1_SA_DQS_DN<0>")
	)
	(segment
		(start 166.357046 -305.266598)
		(end 164.712142 -305.266598)
		(width 0.20066)
		(layer "F.Cu")
		(net "M_E_CPU1_SA_DQ<9>")
	)
	(segment
		(start 161.896552 -304.841656)
		(end 161.710624 -304.841656)
		(width 0.101854)
		(layer "F.Cu")
		(net "M_E_CPU1_SA_DQ<9>")
	)
	(segment
		(start 160.173924 -305.266598)
		(end 158.813246 -305.266598)
		(width 0.20066)
		(layer "F.Cu")
		(net "M_E_CPU1_SA_DQ<9>")
	)
	(segment
		(start 161.245804 -304.994818)
		(end 161.245804 -305.493928)
		(width 0.20066)
		(layer "F.Cu")
		(net "M_E_CPU1_SA_DQ<9>")
	)
	(segment
		(start 157.682946 -305.266598)
		(end 158.813246 -305.266598)
		(width 0.20066)
		(layer "F.Cu")
		(net "M_E_CPU1_SA_DQ<9>")
	)
	(segment
		(start 161.398966 -304.841656)
		(end 161.245804 -304.994818)
		(width 0.20066)
		(layer "F.Cu")
		(net "M_E_CPU1_SA_DQ<9>")
	)
	(segment
		(start 133.365494 -272.917158)
		(end 133.365494 -273.452844)
		(width 0.20066)
		(layer "F.Cu")
		(net "M_E_CPU1_SA_DQ<9>")
	)
	(segment
		(start 164.27831 -304.832766)
		(end 163.923726 -304.832766)
		(width 0.20066)
		(layer "F.Cu")
		(net "M_E_CPU1_SA_DQ<9>")
	)
	(segment
		(start 163.914836 -304.841656)
		(end 161.896552 -304.841656)
		(width 0.1016)
		(layer "F.Cu")
		(net "M_E_CPU1_SA_DQ<9>")
	)
	(segment
		(start 160.61309 -305.705764)
		(end 160.173924 -305.266598)
		(width 0.20066)
		(layer "F.Cu")
		(net "M_E_CPU1_SA_DQ<9>")
	)
	(segment
		(start 161.710624 -304.841656)
		(end 161.398966 -304.841656)
		(width 0.20066)
		(layer "F.Cu")
		(net "M_E_CPU1_SA_DQ<9>")
	)
	(segment
		(start 161.245804 -305.493928)
		(end 161.033968 -305.705764)
		(width 0.20066)
		(layer "F.Cu")
		(net "M_E_CPU1_SA_DQ<9>")
	)
	(segment
		(start 161.033968 -305.705764)
		(end 160.61309 -305.705764)
		(width 0.20066)
		(layer "F.Cu")
		(net "M_E_CPU1_SA_DQ<9>")
	)
	(segment
		(start 163.923726 -304.832766)
		(end 163.914836 -304.841656)
		(width 0.1016)
		(layer "F.Cu")
		(net "M_E_CPU1_SA_DQ<9>")
	)
	(segment
		(start 164.712142 -305.266598)
		(end 164.27831 -304.832766)
		(width 0.20066)
		(layer "F.Cu")
		(net "M_E_CPU1_SA_DQ<9>")
	)
	(segment
		(start 133.365494 -273.452844)
		(end 133.365748 -273.453098)
		(width 0.20066)
		(layer "F.Cu")
		(net "M_E_CPU1_SA_DQ<9>")
	)
	(segment
		(start 139.303252 -274.018502)
		(end 139.004294 -274.018502)
		(width 0.088646)
		(layer "In2.Cu")
		(net "M_E_CPU1_SA_DQ<9>")
	)
	(segment
		(start 145.156174 -280.533094)
		(end 143.893032 -277.48357)
		(width 0.18288)
		(layer "In2.Cu")
		(net "M_E_CPU1_SA_DQ<9>")
	)
	(segment
		(start 157.36316 -304.946812)
		(end 157.36316 -304.810922)
		(width 0.18288)
		(layer "In2.Cu")
		(net "M_E_CPU1_SA_DQ<9>")
	)
	(segment
		(start 153.440638 -301.074328)
		(end 153.633678 -300.881288)
		(width 0.18288)
		(layer "In2.Cu")
		(net "M_E_CPU1_SA_DQ<9>")
	)
	(segment
		(start 153.440638 -300.1772)
		(end 153.440638 -299.666152)
		(width 0.18288)
		(layer "In2.Cu")
		(net "M_E_CPU1_SA_DQ<9>")
	)
	(segment
		(start 153.633678 -297.553888)
		(end 153.440638 -297.360848)
		(width 0.18288)
		(layer "In2.Cu")
		(net "M_E_CPU1_SA_DQ<9>")
	)
	(segment
		(start 151.686514 -291.682932)
		(end 151.306276 -291.525452)
		(width 0.18288)
		(layer "In2.Cu")
		(net "M_E_CPU1_SA_DQ<9>")
	)
	(segment
		(start 153.440638 -298.769024)
		(end 153.440638 -298.257976)
		(width 0.18288)
		(layer "In2.Cu")
		(net "M_E_CPU1_SA_DQ<9>")
	)
	(segment
		(start 141.239748 -274.830286)
		(end 140.900658 -274.830286)
		(width 0.18288)
		(layer "In2.Cu")
		(net "M_E_CPU1_SA_DQ<9>")
	)
	(segment
		(start 151.845772 -292.82644)
		(end 151.687276 -292.444424)
		(width 0.18288)
		(layer "In2.Cu")
		(net "M_E_CPU1_SA_DQ<9>")
	)
	(segment
		(start 140.115036 -274.830286)
		(end 139.303252 -274.018502)
		(width 0.088646)
		(layer "In2.Cu")
		(net "M_E_CPU1_SA_DQ<9>")
	)
	(segment
		(start 157.36316 -304.810922)
		(end 156.878528 -304.32629)
		(width 0.18288)
		(layer "In2.Cu")
		(net "M_E_CPU1_SA_DQ<9>")
	)
	(segment
		(start 151.084534 -290.990782)
		(end 148.413216 -288.319464)
		(width 0.18288)
		(layer "In2.Cu")
		(net "M_E_CPU1_SA_DQ<9>")
	)
	(segment
		(start 134.587996 -273.942556)
		(end 134.587742 -273.942556)
		(width 0.088646)
		(layer "In2.Cu")
		(net "M_E_CPU1_SA_DQ<9>")
	)
	(segment
		(start 151.844756 -292.06444)
		(end 151.686514 -291.682932)
		(width 0.18288)
		(layer "In2.Cu")
		(net "M_E_CPU1_SA_DQ<9>")
	)
	(segment
		(start 154.677618 -302.583596)
		(end 153.992834 -301.898812)
		(width 0.18288)
		(layer "In2.Cu")
		(net "M_E_CPU1_SA_DQ<9>")
	)
	(segment
		(start 152.766268 -295.0464)
		(end 152.923748 -294.666416)
		(width 0.18288)
		(layer "In2.Cu")
		(net "M_E_CPU1_SA_DQ<9>")
	)
	(segment
		(start 133.994144 -273.9263)
		(end 133.365748 -273.453098)
		(width 0.088646)
		(layer "In2.Cu")
		(net "M_E_CPU1_SA_DQ<9>")
	)
	(segment
		(start 152.765506 -294.284908)
		(end 152.385268 -294.127428)
		(width 0.18288)
		(layer "In2.Cu")
		(net "M_E_CPU1_SA_DQ<9>")
	)
	(segment
		(start 153.633678 -298.064936)
		(end 153.633678 -297.553888)
		(width 0.18288)
		(layer "In2.Cu")
		(net "M_E_CPU1_SA_DQ<9>")
	)
	(segment
		(start 153.440638 -298.257976)
		(end 153.633678 -298.064936)
		(width 0.18288)
		(layer "In2.Cu")
		(net "M_E_CPU1_SA_DQ<9>")
	)
	(segment
		(start 151.687276 -292.444424)
		(end 151.844756 -292.06444)
		(width 0.18288)
		(layer "In2.Cu")
		(net "M_E_CPU1_SA_DQ<9>")
	)
	(segment
		(start 153.633678 -300.881288)
		(end 153.633678 -300.37024)
		(width 0.18288)
		(layer "In2.Cu")
		(net "M_E_CPU1_SA_DQ<9>")
	)
	(segment
		(start 152.226772 -293.745412)
		(end 152.384252 -293.365428)
		(width 0.18288)
		(layer "In2.Cu")
		(net "M_E_CPU1_SA_DQ<9>")
	)
	(segment
		(start 154.677618 -302.75022)
		(end 154.677618 -302.583596)
		(width 0.18288)
		(layer "In2.Cu")
		(net "M_E_CPU1_SA_DQ<9>")
	)
	(segment
		(start 153.633678 -300.37024)
		(end 153.440638 -300.1772)
		(width 0.18288)
		(layer "In2.Cu")
		(net "M_E_CPU1_SA_DQ<9>")
	)
	(segment
		(start 157.682946 -305.266598)
		(end 157.36316 -304.946812)
		(width 0.18288)
		(layer "In2.Cu")
		(net "M_E_CPU1_SA_DQ<9>")
	)
	(segment
		(start 153.633678 -298.962064)
		(end 153.440638 -298.769024)
		(width 0.18288)
		(layer "In2.Cu")
		(net "M_E_CPU1_SA_DQ<9>")
	)
	(segment
		(start 153.305002 -295.585896)
		(end 152.924764 -295.428416)
		(width 0.18288)
		(layer "In2.Cu")
		(net "M_E_CPU1_SA_DQ<9>")
	)
	(segment
		(start 152.923748 -294.666416)
		(end 152.765506 -294.284908)
		(width 0.18288)
		(layer "In2.Cu")
		(net "M_E_CPU1_SA_DQ<9>")
	)
	(segment
		(start 148.171154 -288.319464)
		(end 148.044154 -288.192464)
		(width 0.18288)
		(layer "In2.Cu")
		(net "M_E_CPU1_SA_DQ<9>")
	)
	(segment
		(start 148.413216 -288.319464)
		(end 148.171154 -288.319464)
		(width 0.18288)
		(layer "In2.Cu")
		(net "M_E_CPU1_SA_DQ<9>")
	)
	(segment
		(start 156.878528 -304.32629)
		(end 156.253688 -304.32629)
		(width 0.18288)
		(layer "In2.Cu")
		(net "M_E_CPU1_SA_DQ<9>")
	)
	(segment
		(start 140.900658 -274.830286)
		(end 140.115036 -274.830286)
		(width 0.088646)
		(layer "In2.Cu")
		(net "M_E_CPU1_SA_DQ<9>")
	)
	(segment
		(start 135.527796 -273.942556)
		(end 135.513064 -273.951192)
		(width 0.088646)
		(layer "In2.Cu")
		(net "M_E_CPU1_SA_DQ<9>")
	)
	(segment
		(start 153.633678 -299.473112)
		(end 153.633678 -298.962064)
		(width 0.18288)
		(layer "In2.Cu")
		(net "M_E_CPU1_SA_DQ<9>")
	)
	(segment
		(start 153.440638 -296.672508)
		(end 153.305764 -296.347388)
		(width 0.18288)
		(layer "In2.Cu")
		(net "M_E_CPU1_SA_DQ<9>")
	)
	(segment
		(start 153.440638 -299.666152)
		(end 153.633678 -299.473112)
		(width 0.18288)
		(layer "In2.Cu")
		(net "M_E_CPU1_SA_DQ<9>")
	)
	(segment
		(start 152.385268 -294.127428)
		(end 152.226772 -293.745412)
		(width 0.18288)
		(layer "In2.Cu")
		(net "M_E_CPU1_SA_DQ<9>")
	)
	(segment
		(start 153.440638 -301.51324)
		(end 153.440638 -301.074328)
		(width 0.18288)
		(layer "In2.Cu")
		(net "M_E_CPU1_SA_DQ<9>")
	)
	(segment
		(start 148.044154 -288.192464)
		(end 148.044154 -283.421074)
		(width 0.18288)
		(layer "In2.Cu")
		(net "M_E_CPU1_SA_DQ<9>")
	)
	(segment
		(start 153.440638 -297.360848)
		(end 153.440638 -296.672508)
		(width 0.18288)
		(layer "In2.Cu")
		(net "M_E_CPU1_SA_DQ<9>")
	)
	(segment
		(start 151.306276 -291.525452)
		(end 151.084534 -290.990782)
		(width 0.18288)
		(layer "In2.Cu")
		(net "M_E_CPU1_SA_DQ<9>")
	)
	(segment
		(start 152.924764 -295.428416)
		(end 152.766268 -295.0464)
		(width 0.18288)
		(layer "In2.Cu")
		(net "M_E_CPU1_SA_DQ<9>")
	)
	(segment
		(start 152.384252 -293.365428)
		(end 152.22601 -292.98392)
		(width 0.18288)
		(layer "In2.Cu")
		(net "M_E_CPU1_SA_DQ<9>")
	)
	(segment
		(start 156.253688 -304.32629)
		(end 154.677618 -302.75022)
		(width 0.18288)
		(layer "In2.Cu")
		(net "M_E_CPU1_SA_DQ<9>")
	)
	(segment
		(start 153.82621 -301.898812)
		(end 153.440638 -301.51324)
		(width 0.18288)
		(layer "In2.Cu")
		(net "M_E_CPU1_SA_DQ<9>")
	)
	(segment
		(start 143.893032 -277.48357)
		(end 141.239748 -274.830286)
		(width 0.18288)
		(layer "In2.Cu")
		(net "M_E_CPU1_SA_DQ<9>")
	)
	(segment
		(start 134.022846 -273.942556)
		(end 133.994144 -273.9263)
		(width 0.088646)
		(layer "In2.Cu")
		(net "M_E_CPU1_SA_DQ<9>")
	)
	(segment
		(start 152.22601 -292.98392)
		(end 151.845772 -292.82644)
		(width 0.18288)
		(layer "In2.Cu")
		(net "M_E_CPU1_SA_DQ<9>")
	)
	(segment
		(start 153.992834 -301.898812)
		(end 153.82621 -301.898812)
		(width 0.18288)
		(layer "In2.Cu")
		(net "M_E_CPU1_SA_DQ<9>")
	)
	(segment
		(start 153.305764 -296.347388)
		(end 153.463244 -295.967404)
		(width 0.18288)
		(layer "In2.Cu")
		(net "M_E_CPU1_SA_DQ<9>")
	)
	(segment
		(start 148.044154 -283.421074)
		(end 145.156174 -280.533094)
		(width 0.18288)
		(layer "In2.Cu")
		(net "M_E_CPU1_SA_DQ<9>")
	)
	(segment
		(start 153.463244 -295.967404)
		(end 153.305002 -295.585896)
		(width 0.18288)
		(layer "In2.Cu")
		(net "M_E_CPU1_SA_DQ<9>")
	)
	(arc
		(start 138.721592 -273.942556)
		(mid 138.534394 -273.892413)
		(end 138.347196 -273.942556)
		(width 0.088646)
		(layer "In2.Cu")
		(net "M_E_CPU1_SA_DQ<9>")
	)
	(arc
		(start 135.902192 -273.942556)
		(mid 135.714994 -273.892413)
		(end 135.527796 -273.942556)
		(width 0.088646)
		(layer "In2.Cu")
		(net "M_E_CPU1_SA_DQ<9>")
	)
	(arc
		(start 138.955272 -274.01647)
		(mid 138.834368 -273.992351)
		(end 138.721592 -273.942556)
		(width 0.088646)
		(layer "In2.Cu")
		(net "M_E_CPU1_SA_DQ<9>")
	)
	(arc
		(start 137.781792 -273.942556)
		(mid 137.594594 -273.892413)
		(end 137.407396 -273.942556)
		(width 0.088646)
		(layer "In2.Cu")
		(net "M_E_CPU1_SA_DQ<9>")
	)
	(arc
		(start 134.962392 -273.942556)
		(mid 134.775194 -273.892413)
		(end 134.587996 -273.942556)
		(width 0.088646)
		(layer "In2.Cu")
		(net "M_E_CPU1_SA_DQ<9>")
	)
	(arc
		(start 136.467596 -273.942556)
		(mid 136.184894 -274.018332)
		(end 135.902192 -273.942556)
		(width 0.088646)
		(layer "In2.Cu")
		(net "M_E_CPU1_SA_DQ<9>")
	)
	(arc
		(start 138.347196 -273.942556)
		(mid 138.064494 -274.018332)
		(end 137.781792 -273.942556)
		(width 0.088646)
		(layer "In2.Cu")
		(net "M_E_CPU1_SA_DQ<9>")
	)
	(arc
		(start 134.587742 -273.942556)
		(mid 134.305294 -274.018239)
		(end 134.022846 -273.942556)
		(width 0.088646)
		(layer "In2.Cu")
		(net "M_E_CPU1_SA_DQ<9>")
	)
	(arc
		(start 136.841992 -273.942556)
		(mid 136.654794 -273.892413)
		(end 136.467596 -273.942556)
		(width 0.088646)
		(layer "In2.Cu")
		(net "M_E_CPU1_SA_DQ<9>")
	)
	(arc
		(start 139.004294 -274.018502)
		(mid 138.979761 -274.018014)
		(end 138.955272 -274.01647)
		(width 0.088646)
		(layer "In2.Cu")
		(net "M_E_CPU1_SA_DQ<9>")
	)
	(arc
		(start 137.407396 -273.942556)
		(mid 137.124694 -274.018332)
		(end 136.841992 -273.942556)
		(width 0.088646)
		(layer "In2.Cu")
		(net "M_E_CPU1_SA_DQ<9>")
	)
	(arc
		(start 135.513064 -273.951192)
		(mid 135.236589 -274.018512)
		(end 134.962392 -273.942556)
		(width 0.088646)
		(layer "In2.Cu")
		(net "M_E_CPU1_SA_DQ<9>")
	)
	(segment
		(start 164.875972 -307.13807)
		(end 164.269928 -306.532026)
		(width 0.20066)
		(layer "F.Cu")
		(net "M_E_CPU1_SA_DQ<8>")
	)
	(segment
		(start 160.02635 -306.96662)
		(end 158.813246 -306.96662)
		(width 0.20066)
		(layer "F.Cu")
		(net "M_E_CPU1_SA_DQ<8>")
	)
	(segment
		(start 163.914074 -306.541678)
		(end 161.896552 -306.541678)
		(width 0.1016)
		(layer "F.Cu")
		(net "M_E_CPU1_SA_DQ<8>")
	)
	(segment
		(start 161.896552 -306.541678)
		(end 161.642298 -306.541678)
		(width 0.101854)
		(layer "F.Cu")
		(net "M_E_CPU1_SA_DQ<8>")
	)
	(segment
		(start 157.682946 -306.96662)
		(end 158.813246 -306.96662)
		(width 0.20066)
		(layer "F.Cu")
		(net "M_E_CPU1_SA_DQ<8>")
	)
	(segment
		(start 165.317932 -307.13807)
		(end 164.875972 -307.13807)
		(width 0.20066)
		(layer "F.Cu")
		(net "M_E_CPU1_SA_DQ<8>")
	)
	(segment
		(start 165.489382 -306.96662)
		(end 165.317932 -307.13807)
		(width 0.20066)
		(layer "F.Cu")
		(net "M_E_CPU1_SA_DQ<8>")
	)
	(segment
		(start 160.626298 -306.23129)
		(end 160.347914 -306.509674)
		(width 0.20066)
		(layer "F.Cu")
		(net "M_E_CPU1_SA_DQ<8>")
	)
	(segment
		(start 161.642298 -306.541678)
		(end 161.407094 -306.541678)
		(width 0.20066)
		(layer "F.Cu")
		(net "M_E_CPU1_SA_DQ<8>")
	)
	(segment
		(start 161.096706 -306.23129)
		(end 160.626298 -306.23129)
		(width 0.20066)
		(layer "F.Cu")
		(net "M_E_CPU1_SA_DQ<8>")
	)
	(segment
		(start 133.835648 -274.26666)
		(end 133.835394 -274.266914)
		(width 0.20066)
		(layer "F.Cu")
		(net "M_E_CPU1_SA_DQ<8>")
	)
	(segment
		(start 164.269928 -306.532026)
		(end 163.923726 -306.532026)
		(width 0.20066)
		(layer "F.Cu")
		(net "M_E_CPU1_SA_DQ<8>")
	)
	(segment
		(start 160.347914 -306.509674)
		(end 160.347914 -306.645056)
		(width 0.20066)
		(layer "F.Cu")
		(net "M_E_CPU1_SA_DQ<8>")
	)
	(segment
		(start 160.347914 -306.645056)
		(end 160.02635 -306.96662)
		(width 0.20066)
		(layer "F.Cu")
		(net "M_E_CPU1_SA_DQ<8>")
	)
	(segment
		(start 166.357046 -306.96662)
		(end 165.489382 -306.96662)
		(width 0.20066)
		(layer "F.Cu")
		(net "M_E_CPU1_SA_DQ<8>")
	)
	(segment
		(start 161.407094 -306.541678)
		(end 161.096706 -306.23129)
		(width 0.20066)
		(layer "F.Cu")
		(net "M_E_CPU1_SA_DQ<8>")
	)
	(segment
		(start 163.923726 -306.532026)
		(end 163.914074 -306.541678)
		(width 0.1016)
		(layer "F.Cu")
		(net "M_E_CPU1_SA_DQ<8>")
	)
	(segment
		(start 133.835648 -273.730974)
		(end 133.835648 -274.26666)
		(width 0.20066)
		(layer "F.Cu")
		(net "M_E_CPU1_SA_DQ<8>")
	)
	(segment
		(start 152.391364 -302.026066)
		(end 152.391364 -296.875708)
		(width 0.18288)
		(layer "In2.Cu")
		(net "M_E_CPU1_SA_DQ<8>")
	)
	(segment
		(start 149.994366 -291.396674)
		(end 149.461474 -291.396674)
		(width 0.18288)
		(layer "In2.Cu")
		(net "M_E_CPU1_SA_DQ<8>")
	)
	(segment
		(start 136.387078 -274.765262)
		(end 136.372346 -274.756626)
		(width 0.088646)
		(layer "In2.Cu")
		(net "M_E_CPU1_SA_DQ<8>")
	)
	(segment
		(start 148.233638 -290.168838)
		(end 148.233638 -289.635946)
		(width 0.18288)
		(layer "In2.Cu")
		(net "M_E_CPU1_SA_DQ<8>")
	)
	(segment
		(start 148.998178 -290.400486)
		(end 148.465286 -290.400486)
		(width 0.18288)
		(layer "In2.Cu")
		(net "M_E_CPU1_SA_DQ<8>")
	)
	(segment
		(start 141.145768 -275.747226)
		(end 140.900658 -275.747226)
		(width 0.18288)
		(layer "In2.Cu")
		(net "M_E_CPU1_SA_DQ<8>")
	)
	(segment
		(start 148.00199 -289.404298)
		(end 147.469098 -289.404298)
		(width 0.18288)
		(layer "In2.Cu")
		(net "M_E_CPU1_SA_DQ<8>")
	)
	(segment
		(start 143.330422 -277.93188)
		(end 141.145768 -275.747226)
		(width 0.18288)
		(layer "In2.Cu")
		(net "M_E_CPU1_SA_DQ<8>")
	)
	(segment
		(start 138.266678 -274.765262)
		(end 138.251946 -274.756626)
		(width 0.088646)
		(layer "In2.Cu")
		(net "M_E_CPU1_SA_DQ<8>")
	)
	(segment
		(start 140.20165 -275.747226)
		(end 139.269978 -274.815554)
		(width 0.088646)
		(layer "In2.Cu")
		(net "M_E_CPU1_SA_DQ<8>")
	)
	(segment
		(start 135.447278 -274.765262)
		(end 135.432546 -274.756626)
		(width 0.088646)
		(layer "In2.Cu")
		(net "M_E_CPU1_SA_DQ<8>")
	)
	(segment
		(start 156.579062 -305.728624)
		(end 156.323538 -305.4731)
		(width 0.18288)
		(layer "In2.Cu")
		(net "M_E_CPU1_SA_DQ<8>")
	)
	(segment
		(start 156.79293 -306.427632)
		(end 156.579062 -306.213764)
		(width 0.18288)
		(layer "In2.Cu")
		(net "M_E_CPU1_SA_DQ<8>")
	)
	(segment
		(start 149.461474 -291.396674)
		(end 149.229826 -291.165026)
		(width 0.18288)
		(layer "In2.Cu")
		(net "M_E_CPU1_SA_DQ<8>")
	)
	(segment
		(start 147.469098 -289.404298)
		(end 147.028154 -288.963354)
		(width 0.18288)
		(layer "In2.Cu")
		(net "M_E_CPU1_SA_DQ<8>")
	)
	(segment
		(start 148.233638 -289.635946)
		(end 148.00199 -289.404298)
		(width 0.18288)
		(layer "In2.Cu")
		(net "M_E_CPU1_SA_DQ<8>")
	)
	(segment
		(start 156.323538 -305.4731)
		(end 155.838398 -305.4731)
		(width 0.18288)
		(layer "In2.Cu")
		(net "M_E_CPU1_SA_DQ<8>")
	)
	(segment
		(start 134.213854 -274.332446)
		(end 134.148322 -274.266914)
		(width 0.088646)
		(layer "In2.Cu")
		(net "M_E_CPU1_SA_DQ<8>")
	)
	(segment
		(start 147.028154 -283.382466)
		(end 144.569942 -280.924254)
		(width 0.18288)
		(layer "In2.Cu")
		(net "M_E_CPU1_SA_DQ<8>")
	)
	(segment
		(start 149.229826 -291.165026)
		(end 149.229826 -290.632134)
		(width 0.18288)
		(layer "In2.Cu")
		(net "M_E_CPU1_SA_DQ<8>")
	)
	(segment
		(start 134.512812 -274.768056)
		(end 134.492746 -274.756372)
		(width 0.088646)
		(layer "In2.Cu")
		(net "M_E_CPU1_SA_DQ<8>")
	)
	(segment
		(start 134.148322 -274.266914)
		(end 133.835394 -274.266914)
		(width 0.088646)
		(layer "In2.Cu")
		(net "M_E_CPU1_SA_DQ<8>")
	)
	(segment
		(start 157.682946 -306.717446)
		(end 157.393132 -306.427632)
		(width 0.18288)
		(layer "In2.Cu")
		(net "M_E_CPU1_SA_DQ<8>")
	)
	(segment
		(start 155.838398 -305.4731)
		(end 152.391364 -302.026066)
		(width 0.18288)
		(layer "In2.Cu")
		(net "M_E_CPU1_SA_DQ<8>")
	)
	(segment
		(start 137.326878 -274.765262)
		(end 137.312146 -274.756626)
		(width 0.088646)
		(layer "In2.Cu")
		(net "M_E_CPU1_SA_DQ<8>")
	)
	(segment
		(start 134.492746 -274.756372)
		(end 134.487158 -274.75307)
		(width 0.088646)
		(layer "In2.Cu")
		(net "M_E_CPU1_SA_DQ<8>")
	)
	(segment
		(start 144.569942 -280.924254)
		(end 143.330422 -277.93188)
		(width 0.18288)
		(layer "In2.Cu")
		(net "M_E_CPU1_SA_DQ<8>")
	)
	(segment
		(start 157.682946 -306.96662)
		(end 157.682946 -306.717446)
		(width 0.18288)
		(layer "In2.Cu")
		(net "M_E_CPU1_SA_DQ<8>")
	)
	(segment
		(start 149.229826 -290.632134)
		(end 148.998178 -290.400486)
		(width 0.18288)
		(layer "In2.Cu")
		(net "M_E_CPU1_SA_DQ<8>")
	)
	(segment
		(start 134.487158 -274.75307)
		(end 134.48665 -274.752816)
		(width 0.088646)
		(layer "In2.Cu")
		(net "M_E_CPU1_SA_DQ<8>")
	)
	(segment
		(start 152.391364 -296.875708)
		(end 150.587964 -292.523164)
		(width 0.18288)
		(layer "In2.Cu")
		(net "M_E_CPU1_SA_DQ<8>")
	)
	(segment
		(start 147.028154 -288.963354)
		(end 147.028154 -283.382466)
		(width 0.18288)
		(layer "In2.Cu")
		(net "M_E_CPU1_SA_DQ<8>")
	)
	(segment
		(start 140.900658 -275.747226)
		(end 140.20165 -275.747226)
		(width 0.088646)
		(layer "In2.Cu")
		(net "M_E_CPU1_SA_DQ<8>")
	)
	(segment
		(start 156.579062 -306.213764)
		(end 156.579062 -305.728624)
		(width 0.18288)
		(layer "In2.Cu")
		(net "M_E_CPU1_SA_DQ<8>")
	)
	(segment
		(start 150.226014 -291.628322)
		(end 149.994366 -291.396674)
		(width 0.18288)
		(layer "In2.Cu")
		(net "M_E_CPU1_SA_DQ<8>")
	)
	(segment
		(start 150.226014 -292.161214)
		(end 150.226014 -291.628322)
		(width 0.18288)
		(layer "In2.Cu")
		(net "M_E_CPU1_SA_DQ<8>")
	)
	(segment
		(start 148.465286 -290.400486)
		(end 148.233638 -290.168838)
		(width 0.18288)
		(layer "In2.Cu")
		(net "M_E_CPU1_SA_DQ<8>")
	)
	(segment
		(start 150.587964 -292.523164)
		(end 150.226014 -292.161214)
		(width 0.18288)
		(layer "In2.Cu")
		(net "M_E_CPU1_SA_DQ<8>")
	)
	(segment
		(start 157.393132 -306.427632)
		(end 156.79293 -306.427632)
		(width 0.18288)
		(layer "In2.Cu")
		(net "M_E_CPU1_SA_DQ<8>")
	)
	(arc
		(start 136.93775 -274.756626)
		(mid 136.663521 -274.832551)
		(end 136.387078 -274.765262)
		(width 0.088646)
		(layer "In2.Cu")
		(net "M_E_CPU1_SA_DQ<8>")
	)
	(arc
		(start 139.191746 -274.756626)
		(mid 139.004548 -274.706483)
		(end 138.81735 -274.756626)
		(width 0.088646)
		(layer "In2.Cu")
		(net "M_E_CPU1_SA_DQ<8>")
	)
	(arc
		(start 135.432546 -274.756626)
		(mid 135.245348 -274.706483)
		(end 135.05815 -274.756626)
		(width 0.088646)
		(layer "In2.Cu")
		(net "M_E_CPU1_SA_DQ<8>")
	)
	(arc
		(start 138.81735 -274.756626)
		(mid 138.543121 -274.832551)
		(end 138.266678 -274.765262)
		(width 0.088646)
		(layer "In2.Cu")
		(net "M_E_CPU1_SA_DQ<8>")
	)
	(arc
		(start 137.312146 -274.756626)
		(mid 137.124948 -274.706483)
		(end 136.93775 -274.756626)
		(width 0.088646)
		(layer "In2.Cu")
		(net "M_E_CPU1_SA_DQ<8>")
	)
	(arc
		(start 137.87755 -274.756626)
		(mid 137.603321 -274.832551)
		(end 137.326878 -274.765262)
		(width 0.088646)
		(layer "In2.Cu")
		(net "M_E_CPU1_SA_DQ<8>")
	)
	(arc
		(start 134.48665 -274.752816)
		(mid 134.301127 -274.574515)
		(end 134.213854 -274.332446)
		(width 0.088646)
		(layer "In2.Cu")
		(net "M_E_CPU1_SA_DQ<8>")
	)
	(arc
		(start 139.269978 -274.815554)
		(mid 139.232787 -274.783536)
		(end 139.191746 -274.756626)
		(width 0.088646)
		(layer "In2.Cu")
		(net "M_E_CPU1_SA_DQ<8>")
	)
	(arc
		(start 135.99795 -274.756626)
		(mid 135.723721 -274.832551)
		(end 135.447278 -274.765262)
		(width 0.088646)
		(layer "In2.Cu")
		(net "M_E_CPU1_SA_DQ<8>")
	)
	(arc
		(start 138.251946 -274.756626)
		(mid 138.064748 -274.706483)
		(end 137.87755 -274.756626)
		(width 0.088646)
		(layer "In2.Cu")
		(net "M_E_CPU1_SA_DQ<8>")
	)
	(arc
		(start 135.05815 -274.756626)
		(mid 134.786961 -274.832373)
		(end 134.512812 -274.768056)
		(width 0.088646)
		(layer "In2.Cu")
		(net "M_E_CPU1_SA_DQ<8>")
	)
	(arc
		(start 136.372346 -274.756626)
		(mid 136.185148 -274.706483)
		(end 135.99795 -274.756626)
		(width 0.088646)
		(layer "In2.Cu")
		(net "M_E_CPU1_SA_DQ<8>")
	)
	(segment
		(start 165.358064 -308.2417)
		(end 165.352984 -308.24678)
		(width 0.1016)
		(layer "F.Cu")
		(net "M_E_CPU1_SA_DQ<7>")
	)
	(segment
		(start 143.211042 -293.30396)
		(end 143.428466 -293.521384)
		(width 0.1016)
		(layer "F.Cu")
		(net "M_E_CPU1_SA_DQ<7>")
	)
	(segment
		(start 157.343094 -308.063646)
		(end 157.527752 -308.248304)
		(width 0.20066)
		(layer "F.Cu")
		(net "M_E_CPU1_SA_DQ<7>")
	)
	(segment
		(start 166.815516 -308.2417)
		(end 165.358064 -308.2417)
		(width 0.1016)
		(layer "F.Cu")
		(net "M_E_CPU1_SA_DQ<7>")
	)
	(segment
		(start 165.352984 -308.24678)
		(end 165.335458 -308.24678)
		(width 0.101854)
		(layer "F.Cu")
		(net "M_E_CPU1_SA_DQ<7>")
	)
	(segment
		(start 140.332968 -274.950428)
		(end 141.652498 -276.269958)
		(width 0.1016)
		(layer "F.Cu")
		(net "M_E_CPU1_SA_DQ<7>")
	)
	(segment
		(start 157.014164 -307.544216)
		(end 157.208474 -307.738526)
		(width 0.20066)
		(layer "F.Cu")
		(net "M_E_CPU1_SA_DQ<7>")
	)
	(segment
		(start 157.803088 -308.2417)
		(end 159.817054 -308.2417)
		(width 0.1016)
		(layer "F.Cu")
		(net "M_E_CPU1_SA_DQ<7>")
	)
	(segment
		(start 157.208474 -307.738526)
		(end 157.343094 -308.063646)
		(width 0.20066)
		(layer "F.Cu")
		(net "M_E_CPU1_SA_DQ<7>")
	)
	(segment
		(start 156.298646 -302.22571)
		(end 156.7815 -302.22571)
		(width 0.20066)
		(layer "F.Cu")
		(net "M_E_CPU1_SA_DQ<7>")
	)
	(segment
		(start 157.014164 -302.458374)
		(end 157.014164 -307.544216)
		(width 0.20066)
		(layer "F.Cu")
		(net "M_E_CPU1_SA_DQ<7>")
	)
	(segment
		(start 168.265348 -308.046374)
		(end 168.064688 -308.247034)
		(width 0.20066)
		(layer "F.Cu")
		(net "M_E_CPU1_SA_DQ<7>")
	)
	(segment
		(start 168.064688 -308.247034)
		(end 167.367458 -308.247034)
		(width 0.20066)
		(layer "F.Cu")
		(net "M_E_CPU1_SA_DQ<7>")
	)
	(segment
		(start 160.802574 -307.816758)
		(end 162.913314 -307.816758)
		(width 0.20066)
		(layer "F.Cu")
		(net "M_E_CPU1_SA_DQ<7>")
	)
	(segment
		(start 152.000966 -302.093884)
		(end 155.179268 -302.093884)
		(width 0.20066)
		(layer "F.Cu")
		(net "M_E_CPU1_SA_DQ<7>")
	)
	(segment
		(start 157.527752 -308.248304)
		(end 157.791658 -308.248304)
		(width 0.20066)
		(layer "F.Cu")
		(net "M_E_CPU1_SA_DQ<7>")
	)
	(segment
		(start 159.823658 -308.248304)
		(end 160.371028 -308.248304)
		(width 0.20066)
		(layer "F.Cu")
		(net "M_E_CPU1_SA_DQ<7>")
	)
	(segment
		(start 139.169648 -273.787108)
		(end 140.332968 -274.950428)
		(width 0.088646)
		(layer "F.Cu")
		(net "M_E_CPU1_SA_DQ<7>")
	)
	(segment
		(start 142.484856 -290.336986)
		(end 142.995142 -292.9001)
		(width 0.1016)
		(layer "F.Cu")
		(net "M_E_CPU1_SA_DQ<7>")
	)
	(segment
		(start 143.428466 -293.521384)
		(end 152.000966 -302.093884)
		(width 0.20066)
		(layer "F.Cu")
		(net "M_E_CPU1_SA_DQ<7>")
	)
	(segment
		(start 168.499536 -307.56479)
		(end 168.265348 -307.798978)
		(width 0.20066)
		(layer "F.Cu")
		(net "M_E_CPU1_SA_DQ<7>")
	)
	(segment
		(start 139.034266 -273.730974)
		(end 139.169648 -273.787108)
		(width 0.088646)
		(layer "F.Cu")
		(net "M_E_CPU1_SA_DQ<7>")
	)
	(segment
		(start 160.371028 -308.248304)
		(end 160.802574 -307.816758)
		(width 0.20066)
		(layer "F.Cu")
		(net "M_E_CPU1_SA_DQ<7>")
	)
	(segment
		(start 168.883584 -307.56479)
		(end 168.499536 -307.56479)
		(width 0.20066)
		(layer "F.Cu")
		(net "M_E_CPU1_SA_DQ<7>")
	)
	(segment
		(start 165.335458 -308.24678)
		(end 165.33495 -308.247288)
		(width 0.20066)
		(layer "F.Cu")
		(net "M_E_CPU1_SA_DQ<7>")
	)
	(segment
		(start 167.362124 -308.2417)
		(end 166.815516 -308.2417)
		(width 0.101854)
		(layer "F.Cu")
		(net "M_E_CPU1_SA_DQ<7>")
	)
	(segment
		(start 138.534648 -273.730974)
		(end 139.034266 -273.730974)
		(width 0.088646)
		(layer "F.Cu")
		(net "M_E_CPU1_SA_DQ<7>")
	)
	(segment
		(start 141.652498 -276.269958)
		(end 142.484856 -280.428446)
		(width 0.1016)
		(layer "F.Cu")
		(net "M_E_CPU1_SA_DQ<7>")
	)
	(segment
		(start 159.817054 -308.2417)
		(end 159.823658 -308.248304)
		(width 0.1016)
		(layer "F.Cu")
		(net "M_E_CPU1_SA_DQ<7>")
	)
	(segment
		(start 165.03904 -308.247288)
		(end 164.60851 -307.816758)
		(width 0.20066)
		(layer "F.Cu")
		(net "M_E_CPU1_SA_DQ<7>")
	)
	(segment
		(start 168.265348 -307.798978)
		(end 168.265348 -308.046374)
		(width 0.20066)
		(layer "F.Cu")
		(net "M_E_CPU1_SA_DQ<7>")
	)
	(segment
		(start 169.135552 -307.816758)
		(end 168.883584 -307.56479)
		(width 0.20066)
		(layer "F.Cu")
		(net "M_E_CPU1_SA_DQ<7>")
	)
	(segment
		(start 167.367458 -308.247034)
		(end 167.362124 -308.2417)
		(width 0.101854)
		(layer "F.Cu")
		(net "M_E_CPU1_SA_DQ<7>")
	)
	(segment
		(start 155.63723 -302.551846)
		(end 155.97251 -302.551846)
		(width 0.20066)
		(layer "F.Cu")
		(net "M_E_CPU1_SA_DQ<7>")
	)
	(segment
		(start 156.7815 -302.22571)
		(end 157.014164 -302.458374)
		(width 0.20066)
		(layer "F.Cu")
		(net "M_E_CPU1_SA_DQ<7>")
	)
	(segment
		(start 157.791658 -308.248304)
		(end 157.796484 -308.248304)
		(width 0.101854)
		(layer "F.Cu")
		(net "M_E_CPU1_SA_DQ<7>")
	)
	(segment
		(start 170.457114 -307.816758)
		(end 169.135552 -307.816758)
		(width 0.20066)
		(layer "F.Cu")
		(net "M_E_CPU1_SA_DQ<7>")
	)
	(segment
		(start 142.995142 -292.9001)
		(end 143.211042 -293.30396)
		(width 0.1016)
		(layer "F.Cu")
		(net "M_E_CPU1_SA_DQ<7>")
	)
	(segment
		(start 155.97251 -302.551846)
		(end 156.298646 -302.22571)
		(width 0.20066)
		(layer "F.Cu")
		(net "M_E_CPU1_SA_DQ<7>")
	)
	(segment
		(start 142.484856 -280.428446)
		(end 142.484856 -290.336986)
		(width 0.1016)
		(layer "F.Cu")
		(net "M_E_CPU1_SA_DQ<7>")
	)
	(segment
		(start 165.33495 -308.247288)
		(end 165.03904 -308.247288)
		(width 0.20066)
		(layer "F.Cu")
		(net "M_E_CPU1_SA_DQ<7>")
	)
	(segment
		(start 157.796484 -308.248304)
		(end 157.803088 -308.2417)
		(width 0.1016)
		(layer "F.Cu")
		(net "M_E_CPU1_SA_DQ<7>")
	)
	(segment
		(start 164.60851 -307.816758)
		(end 162.913314 -307.816758)
		(width 0.20066)
		(layer "F.Cu")
		(net "M_E_CPU1_SA_DQ<7>")
	)
	(segment
		(start 155.179268 -302.093884)
		(end 155.63723 -302.551846)
		(width 0.20066)
		(layer "F.Cu")
		(net "M_E_CPU1_SA_DQ<7>")
	)
	(segment
		(start 140.141198 -275.625306)
		(end 141.090904 -276.575012)
		(width 0.1016)
		(layer "F.Cu")
		(net "M_E_CPU1_SA_DQ<6>")
	)
	(segment
		(start 157.859222 -309.091584)
		(end 159.773874 -309.091584)
		(width 0.1016)
		(layer "F.Cu")
		(net "M_E_CPU1_SA_DQ<6>")
	)
	(segment
		(start 138.064494 -274.54479)
		(end 138.38174 -274.413472)
		(width 0.088646)
		(layer "F.Cu")
		(net "M_E_CPU1_SA_DQ<6>")
	)
	(segment
		(start 155.201874 -307.55971)
		(end 156.74594 -309.103776)
		(width 0.20066)
		(layer "F.Cu")
		(net "M_E_CPU1_SA_DQ<6>")
	)
	(segment
		(start 141.090904 -276.575012)
		(end 141.875256 -280.494232)
		(width 0.1016)
		(layer "F.Cu")
		(net "M_E_CPU1_SA_DQ<6>")
	)
	(segment
		(start 168.420288 -309.229252)
		(end 168.265348 -309.384192)
		(width 0.20066)
		(layer "F.Cu")
		(net "M_E_CPU1_SA_DQ<6>")
	)
	(segment
		(start 142.727934 -294.630602)
		(end 142.88262 -294.785288)
		(width 0.1016)
		(layer "F.Cu")
		(net "M_E_CPU1_SA_DQ<6>")
	)
	(segment
		(start 154.499056 -306.032408)
		(end 155.269692 -306.032408)
		(width 0.20066)
		(layer "F.Cu")
		(net "M_E_CPU1_SA_DQ<6>")
	)
	(segment
		(start 157.487874 -309.085742)
		(end 157.848554 -309.085742)
		(width 0.20066)
		(layer "F.Cu")
		(net "M_E_CPU1_SA_DQ<6>")
	)
	(segment
		(start 159.778954 -309.086504)
		(end 160.154874 -309.086504)
		(width 0.20066)
		(layer "F.Cu")
		(net "M_E_CPU1_SA_DQ<6>")
	)
	(segment
		(start 139.144502 -274.413472)
		(end 139.55903 -274.828)
		(width 0.088646)
		(layer "F.Cu")
		(net "M_E_CPU1_SA_DQ<6>")
	)
	(segment
		(start 155.42768 -306.54117)
		(end 155.201874 -306.766976)
		(width 0.20066)
		(layer "F.Cu")
		(net "M_E_CPU1_SA_DQ<6>")
	)
	(segment
		(start 167.367458 -309.953406)
		(end 167.355774 -309.941722)
		(width 0.101854)
		(layer "F.Cu")
		(net "M_E_CPU1_SA_DQ<6>")
	)
	(segment
		(start 165.377114 -309.948326)
		(end 165.36162 -309.948326)
		(width 0.1016)
		(layer "F.Cu")
		(net "M_E_CPU1_SA_DQ<6>")
	)
	(segment
		(start 155.269692 -306.032408)
		(end 155.42768 -306.190396)
		(width 0.20066)
		(layer "F.Cu")
		(net "M_E_CPU1_SA_DQ<6>")
	)
	(segment
		(start 169.135552 -309.51678)
		(end 168.848024 -309.229252)
		(width 0.20066)
		(layer "F.Cu")
		(net "M_E_CPU1_SA_DQ<6>")
	)
	(segment
		(start 164.633402 -309.51678)
		(end 162.913314 -309.51678)
		(width 0.20066)
		(layer "F.Cu")
		(net "M_E_CPU1_SA_DQ<6>")
	)
	(segment
		(start 142.88262 -294.785288)
		(end 151.47036 -303.373028)
		(width 0.20066)
		(layer "F.Cu")
		(net "M_E_CPU1_SA_DQ<6>")
	)
	(segment
		(start 142.613126 -294.415972)
		(end 142.727934 -294.630602)
		(width 0.1016)
		(layer "F.Cu")
		(net "M_E_CPU1_SA_DQ<6>")
	)
	(segment
		(start 165.36162 -309.948326)
		(end 165.335458 -309.948326)
		(width 0.101854)
		(layer "F.Cu")
		(net "M_E_CPU1_SA_DQ<6>")
	)
	(segment
		(start 165.064948 -309.948326)
		(end 164.633402 -309.51678)
		(width 0.20066)
		(layer "F.Cu")
		(net "M_E_CPU1_SA_DQ<6>")
	)
	(segment
		(start 157.026864 -309.291736)
		(end 157.188408 -309.275988)
		(width 0.20066)
		(layer "F.Cu")
		(net "M_E_CPU1_SA_DQ<6>")
	)
	(segment
		(start 138.38174 -274.413472)
		(end 139.144502 -274.413472)
		(width 0.088646)
		(layer "F.Cu")
		(net "M_E_CPU1_SA_DQ<6>")
	)
	(segment
		(start 160.58515 -309.51678)
		(end 162.913314 -309.51678)
		(width 0.20066)
		(layer "F.Cu")
		(net "M_E_CPU1_SA_DQ<6>")
	)
	(segment
		(start 165.400228 -309.941722)
		(end 165.377114 -309.948326)
		(width 0.1016)
		(layer "F.Cu")
		(net "M_E_CPU1_SA_DQ<6>")
	)
	(segment
		(start 157.85338 -309.085742)
		(end 157.859222 -309.091584)
		(width 0.1016)
		(layer "F.Cu")
		(net "M_E_CPU1_SA_DQ<6>")
	)
	(segment
		(start 168.265348 -309.384192)
		(end 168.265348 -309.753762)
		(width 0.20066)
		(layer "F.Cu")
		(net "M_E_CPU1_SA_DQ<6>")
	)
	(segment
		(start 139.711176 -275.195284)
		(end 140.141198 -275.625306)
		(width 0.088646)
		(layer "F.Cu")
		(net "M_E_CPU1_SA_DQ<6>")
	)
	(segment
		(start 154.298396 -304.349912)
		(end 154.298396 -305.831748)
		(width 0.20066)
		(layer "F.Cu")
		(net "M_E_CPU1_SA_DQ<6>")
	)
	(segment
		(start 166.643558 -309.941722)
		(end 165.400228 -309.941722)
		(width 0.1016)
		(layer "F.Cu")
		(net "M_E_CPU1_SA_DQ<6>")
	)
	(segment
		(start 151.47036 -303.373028)
		(end 153.321512 -303.373028)
		(width 0.20066)
		(layer "F.Cu")
		(net "M_E_CPU1_SA_DQ<6>")
	)
	(segment
		(start 155.42768 -306.190396)
		(end 155.42768 -306.54117)
		(width 0.20066)
		(layer "F.Cu")
		(net "M_E_CPU1_SA_DQ<6>")
	)
	(segment
		(start 154.298396 -305.831748)
		(end 154.499056 -306.032408)
		(width 0.20066)
		(layer "F.Cu")
		(net "M_E_CPU1_SA_DQ<6>")
	)
	(segment
		(start 170.457114 -309.51678)
		(end 169.135552 -309.51678)
		(width 0.20066)
		(layer "F.Cu")
		(net "M_E_CPU1_SA_DQ<6>")
	)
	(segment
		(start 160.154874 -309.086504)
		(end 160.58515 -309.51678)
		(width 0.20066)
		(layer "F.Cu")
		(net "M_E_CPU1_SA_DQ<6>")
	)
	(segment
		(start 157.188408 -309.275988)
		(end 157.309566 -309.26405)
		(width 0.20066)
		(layer "F.Cu")
		(net "M_E_CPU1_SA_DQ<6>")
	)
	(segment
		(start 141.875256 -290.703)
		(end 142.613126 -294.415972)
		(width 0.1016)
		(layer "F.Cu")
		(net "M_E_CPU1_SA_DQ<6>")
	)
	(segment
		(start 141.875256 -280.494232)
		(end 141.875256 -290.703)
		(width 0.1016)
		(layer "F.Cu")
		(net "M_E_CPU1_SA_DQ<6>")
	)
	(segment
		(start 157.848554 -309.085742)
		(end 157.85338 -309.085742)
		(width 0.101854)
		(layer "F.Cu")
		(net "M_E_CPU1_SA_DQ<6>")
	)
	(segment
		(start 165.335458 -309.948326)
		(end 165.064948 -309.948326)
		(width 0.20066)
		(layer "F.Cu")
		(net "M_E_CPU1_SA_DQ<6>")
	)
	(segment
		(start 168.265348 -309.753762)
		(end 168.065704 -309.953406)
		(width 0.20066)
		(layer "F.Cu")
		(net "M_E_CPU1_SA_DQ<6>")
	)
	(segment
		(start 167.355774 -309.941722)
		(end 166.643558 -309.941722)
		(width 0.101854)
		(layer "F.Cu")
		(net "M_E_CPU1_SA_DQ<6>")
	)
	(segment
		(start 157.309566 -309.26405)
		(end 157.487874 -309.085742)
		(width 0.20066)
		(layer "F.Cu")
		(net "M_E_CPU1_SA_DQ<6>")
	)
	(segment
		(start 153.321512 -303.373028)
		(end 154.298396 -304.349912)
		(width 0.20066)
		(layer "F.Cu")
		(net "M_E_CPU1_SA_DQ<6>")
	)
	(segment
		(start 156.74594 -309.103776)
		(end 157.026864 -309.291736)
		(width 0.20066)
		(layer "F.Cu")
		(net "M_E_CPU1_SA_DQ<6>")
	)
	(segment
		(start 139.55903 -274.828)
		(end 139.711176 -275.195284)
		(width 0.088646)
		(layer "F.Cu")
		(net "M_E_CPU1_SA_DQ<6>")
	)
	(segment
		(start 155.201874 -306.766976)
		(end 155.201874 -307.55971)
		(width 0.20066)
		(layer "F.Cu")
		(net "M_E_CPU1_SA_DQ<6>")
	)
	(segment
		(start 168.065704 -309.953406)
		(end 167.367458 -309.953406)
		(width 0.20066)
		(layer "F.Cu")
		(net "M_E_CPU1_SA_DQ<6>")
	)
	(segment
		(start 159.773874 -309.091584)
		(end 159.778954 -309.086504)
		(width 0.1016)
		(layer "F.Cu")
		(net "M_E_CPU1_SA_DQ<6>")
	)
	(segment
		(start 168.848024 -309.229252)
		(end 168.420288 -309.229252)
		(width 0.20066)
		(layer "F.Cu")
		(net "M_E_CPU1_SA_DQ<6>")
	)
	(segment
		(start 156.110432 -304.66665)
		(end 155.203144 -304.66665)
		(width 0.20066)
		(layer "F.Cu")
		(net "M_E_CPU1_SA_DQ<5>")
	)
	(segment
		(start 165.490906 -308.666642)
		(end 165.274498 -308.88305)
		(width 0.20066)
		(layer "F.Cu")
		(net "M_E_CPU1_SA_DQ<5>")
	)
	(segment
		(start 154.494992 -303.35728)
		(end 154.695652 -303.55794)
		(width 0.20066)
		(layer "F.Cu")
		(net "M_E_CPU1_SA_DQ<5>")
	)
	(segment
		(start 165.274498 -308.88305)
		(end 164.922454 -308.88305)
		(width 0.20066)
		(layer "F.Cu")
		(net "M_E_CPU1_SA_DQ<5>")
	)
	(segment
		(start 161.90214 -308.2417)
		(end 161.896552 -308.236112)
		(width 0.1016)
		(layer "F.Cu")
		(net "M_E_CPU1_SA_DQ<5>")
	)
	(segment
		(start 164.922454 -308.88305)
		(end 164.275516 -308.236112)
		(width 0.20066)
		(layer "F.Cu")
		(net "M_E_CPU1_SA_DQ<5>")
	)
	(segment
		(start 156.347668 -305.55311)
		(end 156.347668 -307.789072)
		(width 0.20066)
		(layer "F.Cu")
		(net "M_E_CPU1_SA_DQ<5>")
	)
	(segment
		(start 154.294332 -302.733456)
		(end 154.494992 -302.934116)
		(width 0.20066)
		(layer "F.Cu")
		(net "M_E_CPU1_SA_DQ<5>")
	)
	(segment
		(start 156.09951 -303.55794)
		(end 156.347668 -303.806098)
		(width 0.20066)
		(layer "F.Cu")
		(net "M_E_CPU1_SA_DQ<5>")
	)
	(segment
		(start 163.923726 -308.236112)
		(end 163.918138 -308.2417)
		(width 0.1016)
		(layer "F.Cu")
		(net "M_E_CPU1_SA_DQ<5>")
	)
	(segment
		(start 161.891726 -308.236112)
		(end 161.43224 -308.236112)
		(width 0.20066)
		(layer "F.Cu")
		(net "M_E_CPU1_SA_DQ<5>")
	)
	(segment
		(start 142.180056 -280.460958)
		(end 142.180056 -290.523422)
		(width 0.1016)
		(layer "F.Cu")
		(net "M_E_CPU1_SA_DQ<5>")
	)
	(segment
		(start 156.347668 -304.429414)
		(end 156.110432 -304.66665)
		(width 0.20066)
		(layer "F.Cu")
		(net "M_E_CPU1_SA_DQ<5>")
	)
	(segment
		(start 160.667954 -308.883812)
		(end 160.450784 -308.666642)
		(width 0.20066)
		(layer "F.Cu")
		(net "M_E_CPU1_SA_DQ<5>")
	)
	(segment
		(start 166.357046 -308.666642)
		(end 165.490906 -308.666642)
		(width 0.20066)
		(layer "F.Cu")
		(net "M_E_CPU1_SA_DQ<5>")
	)
	(segment
		(start 160.450784 -308.666642)
		(end 158.813246 -308.666642)
		(width 0.20066)
		(layer "F.Cu")
		(net "M_E_CPU1_SA_DQ<5>")
	)
	(segment
		(start 154.494992 -302.934116)
		(end 154.494992 -303.35728)
		(width 0.20066)
		(layer "F.Cu")
		(net "M_E_CPU1_SA_DQ<5>")
	)
	(segment
		(start 140.116814 -275.166582)
		(end 141.37132 -276.421088)
		(width 0.1016)
		(layer "F.Cu")
		(net "M_E_CPU1_SA_DQ<5>")
	)
	(segment
		(start 161.245804 -308.683152)
		(end 161.045144 -308.883812)
		(width 0.20066)
		(layer "F.Cu")
		(net "M_E_CPU1_SA_DQ<5>")
	)
	(segment
		(start 141.37132 -276.421088)
		(end 142.180056 -280.460958)
		(width 0.1016)
		(layer "F.Cu")
		(net "M_E_CPU1_SA_DQ<5>")
	)
	(segment
		(start 139.882118 -274.845018)
		(end 139.882118 -274.931886)
		(width 0.088646)
		(layer "F.Cu")
		(net "M_E_CPU1_SA_DQ<5>")
	)
	(segment
		(start 161.045144 -308.883812)
		(end 160.667954 -308.883812)
		(width 0.20066)
		(layer "F.Cu")
		(net "M_E_CPU1_SA_DQ<5>")
	)
	(segment
		(start 136.201912 -274.540218)
		(end 136.889744 -274.137882)
		(width 0.088646)
		(layer "F.Cu")
		(net "M_E_CPU1_SA_DQ<5>")
	)
	(segment
		(start 139.882118 -274.931886)
		(end 140.116814 -275.166582)
		(width 0.088646)
		(layer "F.Cu")
		(net "M_E_CPU1_SA_DQ<5>")
	)
	(segment
		(start 161.896552 -308.236112)
		(end 161.891726 -308.236112)
		(width 0.101854)
		(layer "F.Cu")
		(net "M_E_CPU1_SA_DQ<5>")
	)
	(segment
		(start 138.422126 -274.164044)
		(end 139.201144 -274.164044)
		(width 0.088646)
		(layer "F.Cu")
		(net "M_E_CPU1_SA_DQ<5>")
	)
	(segment
		(start 161.43224 -308.236112)
		(end 161.245804 -308.422548)
		(width 0.20066)
		(layer "F.Cu")
		(net "M_E_CPU1_SA_DQ<5>")
	)
	(segment
		(start 156.147008 -305.35245)
		(end 156.347668 -305.55311)
		(width 0.20066)
		(layer "F.Cu")
		(net "M_E_CPU1_SA_DQ<5>")
	)
	(segment
		(start 143.335248 -294.33266)
		(end 151.736044 -302.733456)
		(width 0.20066)
		(layer "F.Cu")
		(net "M_E_CPU1_SA_DQ<5>")
	)
	(segment
		(start 161.245804 -308.422548)
		(end 161.245804 -308.683152)
		(width 0.20066)
		(layer "F.Cu")
		(net "M_E_CPU1_SA_DQ<5>")
	)
	(segment
		(start 142.94231 -293.939722)
		(end 143.335248 -294.33266)
		(width 0.1016)
		(layer "F.Cu")
		(net "M_E_CPU1_SA_DQ<5>")
	)
	(segment
		(start 155.002484 -304.86731)
		(end 155.002484 -305.15179)
		(width 0.20066)
		(layer "F.Cu")
		(net "M_E_CPU1_SA_DQ<5>")
	)
	(segment
		(start 155.203144 -305.35245)
		(end 156.147008 -305.35245)
		(width 0.20066)
		(layer "F.Cu")
		(net "M_E_CPU1_SA_DQ<5>")
	)
	(segment
		(start 151.736044 -302.733456)
		(end 154.294332 -302.733456)
		(width 0.20066)
		(layer "F.Cu")
		(net "M_E_CPU1_SA_DQ<5>")
	)
	(segment
		(start 155.002484 -305.15179)
		(end 155.203144 -305.35245)
		(width 0.20066)
		(layer "F.Cu")
		(net "M_E_CPU1_SA_DQ<5>")
	)
	(segment
		(start 157.225238 -308.666642)
		(end 158.813246 -308.666642)
		(width 0.20066)
		(layer "F.Cu")
		(net "M_E_CPU1_SA_DQ<5>")
	)
	(segment
		(start 142.180056 -290.523422)
		(end 142.782798 -293.554658)
		(width 0.1016)
		(layer "F.Cu")
		(net "M_E_CPU1_SA_DQ<5>")
	)
	(segment
		(start 138.308588 -274.141438)
		(end 138.422126 -274.164044)
		(width 0.088646)
		(layer "F.Cu")
		(net "M_E_CPU1_SA_DQ<5>")
	)
	(segment
		(start 155.203144 -304.66665)
		(end 155.002484 -304.86731)
		(width 0.20066)
		(layer "F.Cu")
		(net "M_E_CPU1_SA_DQ<5>")
	)
	(segment
		(start 163.918138 -308.2417)
		(end 161.90214 -308.2417)
		(width 0.1016)
		(layer "F.Cu")
		(net "M_E_CPU1_SA_DQ<5>")
	)
	(segment
		(start 154.695652 -303.55794)
		(end 156.09951 -303.55794)
		(width 0.20066)
		(layer "F.Cu")
		(net "M_E_CPU1_SA_DQ<5>")
	)
	(segment
		(start 164.275516 -308.236112)
		(end 163.923726 -308.236112)
		(width 0.20066)
		(layer "F.Cu")
		(net "M_E_CPU1_SA_DQ<5>")
	)
	(segment
		(start 142.782798 -293.554658)
		(end 142.94231 -293.939722)
		(width 0.101854)
		(layer "F.Cu")
		(net "M_E_CPU1_SA_DQ<5>")
	)
	(segment
		(start 139.201144 -274.164044)
		(end 139.882118 -274.845018)
		(width 0.088646)
		(layer "F.Cu")
		(net "M_E_CPU1_SA_DQ<5>")
	)
	(segment
		(start 156.347668 -307.789072)
		(end 157.225238 -308.666642)
		(width 0.20066)
		(layer "F.Cu")
		(net "M_E_CPU1_SA_DQ<5>")
	)
	(segment
		(start 156.347668 -303.806098)
		(end 156.347668 -304.429414)
		(width 0.20066)
		(layer "F.Cu")
		(net "M_E_CPU1_SA_DQ<5>")
	)
	(arc
		(start 138.299444 -274.137882)
		(mid 138.303874 -274.140021)
		(end 138.308588 -274.141438)
		(width 0.088646)
		(layer "F.Cu")
		(net "M_E_CPU1_SA_DQ<5>")
	)
	(arc
		(start 137.829544 -274.137882)
		(mid 138.064494 -274.074922)
		(end 138.299444 -274.137882)
		(width 0.088646)
		(layer "F.Cu")
		(net "M_E_CPU1_SA_DQ<5>")
	)
	(arc
		(start 136.889744 -274.137882)
		(mid 137.124694 -274.074922)
		(end 137.359644 -274.137882)
		(width 0.088646)
		(layer "F.Cu")
		(net "M_E_CPU1_SA_DQ<5>")
	)
	(arc
		(start 137.359644 -274.137882)
		(mid 137.594594 -274.200842)
		(end 137.829544 -274.137882)
		(width 0.088646)
		(layer "F.Cu")
		(net "M_E_CPU1_SA_DQ<5>")
	)
	(arc
		(start 136.184894 -274.54479)
		(mid 136.193702 -274.543622)
		(end 136.201912 -274.540218)
		(width 0.088646)
		(layer "F.Cu")
		(net "M_E_CPU1_SA_DQ<5>")
	)
	(segment
		(start 141.593316 -291.284406)
		(end 142.079726 -294.072056)
		(width 0.1016)
		(layer "F.Cu")
		(net "M_E_CPU1_SA_DQ<4>")
	)
	(segment
		(start 151.992838 -304.21326)
		(end 152.193498 -304.0126)
		(width 0.20066)
		(layer "F.Cu")
		(net "M_E_CPU1_SA_DQ<4>")
	)
	(segment
		(start 138.876532 -274.705572)
		(end 139.164314 -274.705572)
		(width 0.088646)
		(layer "F.Cu")
		(net "M_E_CPU1_SA_DQ<4>")
	)
	(segment
		(start 139.323826 -274.865084)
		(end 139.555474 -275.423884)
		(width 0.088646)
		(layer "F.Cu")
		(net "M_E_CPU1_SA_DQ<4>")
	)
	(segment
		(start 160.67024 -310.582564)
		(end 160.339532 -310.251856)
		(width 0.20066)
		(layer "F.Cu")
		(net "M_E_CPU1_SA_DQ<4>")
	)
	(segment
		(start 153.140664 -304.282348)
		(end 153.140664 -304.644552)
		(width 0.20066)
		(layer "F.Cu")
		(net "M_E_CPU1_SA_DQ<4>")
	)
	(segment
		(start 137.197084 -275.007832)
		(end 137.427462 -274.919948)
		(width 0.088646)
		(layer "F.Cu")
		(net "M_E_CPU1_SA_DQ<4>")
	)
	(segment
		(start 140.80998 -276.727412)
		(end 141.570456 -280.526744)
		(width 0.1016)
		(layer "F.Cu")
		(net "M_E_CPU1_SA_DQ<4>")
	)
	(segment
		(start 153.152856 -305.60264)
		(end 153.45156 -305.60264)
		(width 0.20066)
		(layer "F.Cu")
		(net "M_E_CPU1_SA_DQ<4>")
	)
	(segment
		(start 161.05251 -310.418988)
		(end 160.888934 -310.582564)
		(width 0.20066)
		(layer "F.Cu")
		(net "M_E_CPU1_SA_DQ<4>")
	)
	(segment
		(start 139.924536 -275.841968)
		(end 140.80998 -276.727412)
		(width 0.1016)
		(layer "F.Cu")
		(net "M_E_CPU1_SA_DQ<4>")
	)
	(segment
		(start 161.891726 -309.9308)
		(end 161.195004 -309.9308)
		(width 0.20066)
		(layer "F.Cu")
		(net "M_E_CPU1_SA_DQ<4>")
	)
	(segment
		(start 142.574518 -295.397428)
		(end 142.737586 -295.560496)
		(width 0.1016)
		(layer "F.Cu")
		(net "M_E_CPU1_SA_DQ<4>")
	)
	(segment
		(start 141.570456 -291.019738)
		(end 141.593316 -291.284406)
		(width 0.1016)
		(layer "F.Cu")
		(net "M_E_CPU1_SA_DQ<4>")
	)
	(segment
		(start 161.05251 -310.073294)
		(end 161.05251 -310.418988)
		(width 0.20066)
		(layer "F.Cu")
		(net "M_E_CPU1_SA_DQ<4>")
	)
	(segment
		(start 152.593548 -305.877976)
		(end 152.87752 -305.877976)
		(width 0.20066)
		(layer "F.Cu")
		(net "M_E_CPU1_SA_DQ<4>")
	)
	(segment
		(start 160.888934 -310.582564)
		(end 160.67024 -310.582564)
		(width 0.20066)
		(layer "F.Cu")
		(net "M_E_CPU1_SA_DQ<4>")
	)
	(segment
		(start 153.652728 -306.08778)
		(end 153.370026 -306.370482)
		(width 0.20066)
		(layer "F.Cu")
		(net "M_E_CPU1_SA_DQ<4>")
	)
	(segment
		(start 163.914074 -309.941722)
		(end 161.907474 -309.941722)
		(width 0.1016)
		(layer "F.Cu")
		(net "M_E_CPU1_SA_DQ<4>")
	)
	(segment
		(start 161.195004 -309.9308)
		(end 161.05251 -310.073294)
		(width 0.20066)
		(layer "F.Cu")
		(net "M_E_CPU1_SA_DQ<4>")
	)
	(segment
		(start 139.555474 -275.423884)
		(end 139.653772 -275.571204)
		(width 0.088646)
		(layer "F.Cu")
		(net "M_E_CPU1_SA_DQ<4>")
	)
	(segment
		(start 159.628332 -310.366664)
		(end 158.813246 -310.366664)
		(width 0.20066)
		(layer "F.Cu")
		(net "M_E_CPU1_SA_DQ<4>")
	)
	(segment
		(start 151.507698 -304.817272)
		(end 151.792178 -304.817272)
		(width 0.20066)
		(layer "F.Cu")
		(net "M_E_CPU1_SA_DQ<4>")
	)
	(segment
		(start 153.370026 -306.654454)
		(end 156.200348 -309.484776)
		(width 0.20066)
		(layer "F.Cu")
		(net "M_E_CPU1_SA_DQ<4>")
	)
	(segment
		(start 151.307038 -304.129948)
		(end 151.307038 -304.616612)
		(width 0.20066)
		(layer "F.Cu")
		(net "M_E_CPU1_SA_DQ<4>")
	)
	(segment
		(start 164.431472 -309.93207)
		(end 163.923726 -309.93207)
		(width 0.20066)
		(layer "F.Cu")
		(net "M_E_CPU1_SA_DQ<4>")
	)
	(segment
		(start 153.652728 -305.803808)
		(end 153.652728 -306.08778)
		(width 0.20066)
		(layer "F.Cu")
		(net "M_E_CPU1_SA_DQ<4>")
	)
	(segment
		(start 160.339532 -310.251856)
		(end 159.74314 -310.251856)
		(width 0.20066)
		(layer "F.Cu")
		(net "M_E_CPU1_SA_DQ<4>")
	)
	(segment
		(start 151.307038 -304.616612)
		(end 151.507698 -304.817272)
		(width 0.20066)
		(layer "F.Cu")
		(net "M_E_CPU1_SA_DQ<4>")
	)
	(segment
		(start 151.792178 -304.817272)
		(end 151.992838 -304.616612)
		(width 0.20066)
		(layer "F.Cu")
		(net "M_E_CPU1_SA_DQ<4>")
	)
	(segment
		(start 152.870916 -304.0126)
		(end 153.140664 -304.282348)
		(width 0.20066)
		(layer "F.Cu")
		(net "M_E_CPU1_SA_DQ<4>")
	)
	(segment
		(start 138.17473 -275.00199)
		(end 138.876532 -274.705572)
		(width 0.088646)
		(layer "F.Cu")
		(net "M_E_CPU1_SA_DQ<4>")
	)
	(segment
		(start 152.39238 -305.676808)
		(end 152.593548 -305.877976)
		(width 0.20066)
		(layer "F.Cu")
		(net "M_E_CPU1_SA_DQ<4>")
	)
	(segment
		(start 142.079726 -294.072056)
		(end 142.43939 -295.137078)
		(width 0.1016)
		(layer "F.Cu")
		(net "M_E_CPU1_SA_DQ<4>")
	)
	(segment
		(start 152.39238 -305.392836)
		(end 152.39238 -305.676808)
		(width 0.20066)
		(layer "F.Cu")
		(net "M_E_CPU1_SA_DQ<4>")
	)
	(segment
		(start 142.737586 -295.560496)
		(end 151.307038 -304.129948)
		(width 0.20066)
		(layer "F.Cu")
		(net "M_E_CPU1_SA_DQ<4>")
	)
	(segment
		(start 166.357046 -310.366664)
		(end 164.866066 -310.366664)
		(width 0.20066)
		(layer "F.Cu")
		(net "M_E_CPU1_SA_DQ<4>")
	)
	(segment
		(start 157.65272 -310.366664)
		(end 158.813246 -310.366664)
		(width 0.20066)
		(layer "F.Cu")
		(net "M_E_CPU1_SA_DQ<4>")
	)
	(segment
		(start 156.200348 -309.484776)
		(end 156.395928 -309.645304)
		(width 0.20066)
		(layer "F.Cu")
		(net "M_E_CPU1_SA_DQ<4>")
	)
	(segment
		(start 152.193498 -304.0126)
		(end 152.870916 -304.0126)
		(width 0.20066)
		(layer "F.Cu")
		(net "M_E_CPU1_SA_DQ<4>")
	)
	(segment
		(start 157.188408 -310.17464)
		(end 157.65272 -310.366664)
		(width 0.20066)
		(layer "F.Cu")
		(net "M_E_CPU1_SA_DQ<4>")
	)
	(segment
		(start 161.907474 -309.941722)
		(end 161.896552 -309.9308)
		(width 0.1016)
		(layer "F.Cu")
		(net "M_E_CPU1_SA_DQ<4>")
	)
	(segment
		(start 153.45156 -305.60264)
		(end 153.652728 -305.803808)
		(width 0.20066)
		(layer "F.Cu")
		(net "M_E_CPU1_SA_DQ<4>")
	)
	(segment
		(start 153.370026 -306.370482)
		(end 153.370026 -306.654454)
		(width 0.20066)
		(layer "F.Cu")
		(net "M_E_CPU1_SA_DQ<4>")
	)
	(segment
		(start 159.74314 -310.251856)
		(end 159.628332 -310.366664)
		(width 0.20066)
		(layer "F.Cu")
		(net "M_E_CPU1_SA_DQ<4>")
	)
	(segment
		(start 156.395928 -309.645304)
		(end 157.188408 -310.17464)
		(width 0.20066)
		(layer "F.Cu")
		(net "M_E_CPU1_SA_DQ<4>")
	)
	(segment
		(start 139.164314 -274.705572)
		(end 139.323826 -274.865084)
		(width 0.088646)
		(layer "F.Cu")
		(net "M_E_CPU1_SA_DQ<4>")
	)
	(segment
		(start 152.87752 -305.877976)
		(end 153.152856 -305.60264)
		(width 0.20066)
		(layer "F.Cu")
		(net "M_E_CPU1_SA_DQ<4>")
	)
	(segment
		(start 153.140664 -304.644552)
		(end 152.39238 -305.392836)
		(width 0.20066)
		(layer "F.Cu")
		(net "M_E_CPU1_SA_DQ<4>")
	)
	(segment
		(start 161.896552 -309.9308)
		(end 161.891726 -309.9308)
		(width 0.101854)
		(layer "F.Cu")
		(net "M_E_CPU1_SA_DQ<4>")
	)
	(segment
		(start 142.43939 -295.137078)
		(end 142.574518 -295.397428)
		(width 0.1016)
		(layer "F.Cu")
		(net "M_E_CPU1_SA_DQ<4>")
	)
	(segment
		(start 151.992838 -304.616612)
		(end 151.992838 -304.21326)
		(width 0.20066)
		(layer "F.Cu")
		(net "M_E_CPU1_SA_DQ<4>")
	)
	(segment
		(start 141.570456 -280.526744)
		(end 141.570456 -291.019738)
		(width 0.1016)
		(layer "F.Cu")
		(net "M_E_CPU1_SA_DQ<4>")
	)
	(segment
		(start 139.653772 -275.571204)
		(end 139.924536 -275.841968)
		(width 0.088646)
		(layer "F.Cu")
		(net "M_E_CPU1_SA_DQ<4>")
	)
	(segment
		(start 163.923726 -309.93207)
		(end 163.914074 -309.941722)
		(width 0.1016)
		(layer "F.Cu")
		(net "M_E_CPU1_SA_DQ<4>")
	)
	(segment
		(start 164.866066 -310.366664)
		(end 164.431472 -309.93207)
		(width 0.20066)
		(layer "F.Cu")
		(net "M_E_CPU1_SA_DQ<4>")
	)
	(arc
		(start 137.427462 -274.919948)
		(mid 137.632114 -274.89061)
		(end 137.829544 -274.951952)
		(width 0.088646)
		(layer "F.Cu")
		(net "M_E_CPU1_SA_DQ<4>")
	)
	(arc
		(start 136.655048 -275.35886)
		(mid 136.907519 -275.154708)
		(end 137.197084 -275.007832)
		(width 0.088646)
		(layer "F.Cu")
		(net "M_E_CPU1_SA_DQ<4>")
	)
	(arc
		(start 137.829544 -274.951952)
		(mid 137.997323 -275.010177)
		(end 138.17473 -275.00199)
		(width 0.088646)
		(layer "F.Cu")
		(net "M_E_CPU1_SA_DQ<4>")
	)
	(segment
		(start 157.188408 -314.14847)
		(end 157.332426 -314.20816)
		(width 0.20066)
		(layer "F.Cu")
		(net "M_E_CPU1_SA_DQ<3>")
	)
	(segment
		(start 140.765022 -296.946574)
		(end 140.765022 -297.327828)
		(width 0.1016)
		(layer "F.Cu")
		(net "M_E_CPU1_SA_DQ<3>")
	)
	(segment
		(start 139.896596 -280.034746)
		(end 140.041376 -280.759154)
		(width 0.088646)
		(layer "F.Cu")
		(net "M_E_CPU1_SA_DQ<3>")
	)
	(segment
		(start 138.534648 -276.986492)
		(end 138.625326 -277.001986)
		(width 0.088646)
		(layer "F.Cu")
		(net "M_E_CPU1_SA_DQ<3>")
	)
	(segment
		(start 140.041376 -296.222928)
		(end 140.765022 -296.946574)
		(width 0.1016)
		(layer "F.Cu")
		(net "M_E_CPU1_SA_DQ<3>")
	)
	(segment
		(start 159.804608 -314.19165)
		(end 159.813752 -314.200794)
		(width 0.101854)
		(layer "F.Cu")
		(net "M_E_CPU1_SA_DQ<3>")
	)
	(segment
		(start 169.135552 -313.766708)
		(end 168.81094 -313.442096)
		(width 0.20066)
		(layer "F.Cu")
		(net "M_E_CPU1_SA_DQ<3>")
	)
	(segment
		(start 140.765022 -298.18711)
		(end 155.347162 -312.76925)
		(width 0.20066)
		(layer "F.Cu")
		(net "M_E_CPU1_SA_DQ<3>")
	)
	(segment
		(start 157.791658 -314.20816)
		(end 157.796484 -314.20816)
		(width 0.101854)
		(layer "F.Cu")
		(net "M_E_CPU1_SA_DQ<3>")
	)
	(segment
		(start 139.53617 -278.473408)
		(end 139.607036 -278.874982)
		(width 0.088646)
		(layer "F.Cu")
		(net "M_E_CPU1_SA_DQ<3>")
	)
	(segment
		(start 155.347162 -312.76925)
		(end 156.32176 -313.569096)
		(width 0.20066)
		(layer "F.Cu")
		(net "M_E_CPU1_SA_DQ<3>")
	)
	(segment
		(start 167.338502 -314.19165)
		(end 165.36289 -314.19165)
		(width 0.1016)
		(layer "F.Cu")
		(net "M_E_CPU1_SA_DQ<3>")
	)
	(segment
		(start 168.81094 -313.442096)
		(end 168.392348 -313.442096)
		(width 0.20066)
		(layer "F.Cu")
		(net "M_E_CPU1_SA_DQ<3>")
	)
	(segment
		(start 157.796484 -314.20816)
		(end 157.812994 -314.19165)
		(width 0.1016)
		(layer "F.Cu")
		(net "M_E_CPU1_SA_DQ<3>")
	)
	(segment
		(start 161.190432 -313.766708)
		(end 162.913314 -313.766708)
		(width 0.20066)
		(layer "F.Cu")
		(net "M_E_CPU1_SA_DQ<3>")
	)
	(segment
		(start 140.041376 -281.063446)
		(end 140.041376 -296.222928)
		(width 0.1016)
		(layer "F.Cu")
		(net "M_E_CPU1_SA_DQ<3>")
	)
	(segment
		(start 159.623506 -314.19165)
		(end 159.804608 -314.19165)
		(width 0.101854)
		(layer "F.Cu")
		(net "M_E_CPU1_SA_DQ<3>")
	)
	(segment
		(start 168.265348 -314.009024)
		(end 168.07307 -314.201302)
		(width 0.20066)
		(layer "F.Cu")
		(net "M_E_CPU1_SA_DQ<3>")
	)
	(segment
		(start 156.32176 -313.569096)
		(end 157.188408 -314.14847)
		(width 0.20066)
		(layer "F.Cu")
		(net "M_E_CPU1_SA_DQ<3>")
	)
	(segment
		(start 140.041376 -280.759154)
		(end 140.041376 -281.063446)
		(width 0.088646)
		(layer "F.Cu")
		(net "M_E_CPU1_SA_DQ<3>")
	)
	(segment
		(start 168.265348 -313.569096)
		(end 168.265348 -314.009024)
		(width 0.20066)
		(layer "F.Cu")
		(net "M_E_CPU1_SA_DQ<3>")
	)
	(segment
		(start 159.813752 -314.200794)
		(end 159.823658 -314.200794)
		(width 0.101854)
		(layer "F.Cu")
		(net "M_E_CPU1_SA_DQ<3>")
	)
	(segment
		(start 157.812994 -314.19165)
		(end 159.623506 -314.19165)
		(width 0.1016)
		(layer "F.Cu")
		(net "M_E_CPU1_SA_DQ<3>")
	)
	(segment
		(start 167.348154 -314.201302)
		(end 167.338502 -314.19165)
		(width 0.101854)
		(layer "F.Cu")
		(net "M_E_CPU1_SA_DQ<3>")
	)
	(segment
		(start 138.625326 -277.001986)
		(end 139.348972 -278.023828)
		(width 0.088646)
		(layer "F.Cu")
		(net "M_E_CPU1_SA_DQ<3>")
	)
	(segment
		(start 168.07307 -314.201302)
		(end 167.367458 -314.201302)
		(width 0.20066)
		(layer "F.Cu")
		(net "M_E_CPU1_SA_DQ<3>")
	)
	(segment
		(start 139.607036 -279.080468)
		(end 139.896596 -280.034746)
		(width 0.088646)
		(layer "F.Cu")
		(net "M_E_CPU1_SA_DQ<3>")
	)
	(segment
		(start 164.815266 -314.201556)
		(end 164.380418 -313.766708)
		(width 0.20066)
		(layer "F.Cu")
		(net "M_E_CPU1_SA_DQ<3>")
	)
	(segment
		(start 140.765022 -297.327828)
		(end 140.765022 -298.18711)
		(width 0.20066)
		(layer "F.Cu")
		(net "M_E_CPU1_SA_DQ<3>")
	)
	(segment
		(start 159.823658 -314.200794)
		(end 160.756346 -314.200794)
		(width 0.20066)
		(layer "F.Cu")
		(net "M_E_CPU1_SA_DQ<3>")
	)
	(segment
		(start 139.607036 -278.874982)
		(end 139.607036 -279.080468)
		(width 0.088646)
		(layer "F.Cu")
		(net "M_E_CPU1_SA_DQ<3>")
	)
	(segment
		(start 167.367458 -314.201302)
		(end 167.348154 -314.201302)
		(width 0.101854)
		(layer "F.Cu")
		(net "M_E_CPU1_SA_DQ<3>")
	)
	(segment
		(start 170.457114 -313.766708)
		(end 169.135552 -313.766708)
		(width 0.20066)
		(layer "F.Cu")
		(net "M_E_CPU1_SA_DQ<3>")
	)
	(segment
		(start 165.352984 -314.201556)
		(end 165.335458 -314.201556)
		(width 0.101854)
		(layer "F.Cu")
		(net "M_E_CPU1_SA_DQ<3>")
	)
	(segment
		(start 168.392348 -313.442096)
		(end 168.265348 -313.569096)
		(width 0.20066)
		(layer "F.Cu")
		(net "M_E_CPU1_SA_DQ<3>")
	)
	(segment
		(start 157.332426 -314.20816)
		(end 157.791658 -314.20816)
		(width 0.20066)
		(layer "F.Cu")
		(net "M_E_CPU1_SA_DQ<3>")
	)
	(segment
		(start 160.756346 -314.200794)
		(end 161.190432 -313.766708)
		(width 0.20066)
		(layer "F.Cu")
		(net "M_E_CPU1_SA_DQ<3>")
	)
	(segment
		(start 164.380418 -313.766708)
		(end 162.913314 -313.766708)
		(width 0.20066)
		(layer "F.Cu")
		(net "M_E_CPU1_SA_DQ<3>")
	)
	(segment
		(start 165.36289 -314.19165)
		(end 165.352984 -314.201556)
		(width 0.1016)
		(layer "F.Cu")
		(net "M_E_CPU1_SA_DQ<3>")
	)
	(segment
		(start 165.335458 -314.201556)
		(end 164.815266 -314.201556)
		(width 0.20066)
		(layer "F.Cu")
		(net "M_E_CPU1_SA_DQ<3>")
	)
	(segment
		(start 139.348972 -278.023828)
		(end 139.53617 -278.473408)
		(width 0.088646)
		(layer "F.Cu")
		(net "M_E_CPU1_SA_DQ<3>")
	)
	(segment
		(start 168.022524 -279.999186)
		(end 167.821864 -280.199846)
		(width 0.20066)
		(layer "F.Cu")
		(net "M_E_CPU1_SA_DQ<31>")
	)
	(segment
		(start 157.809438 -280.191718)
		(end 159.77616 -280.191718)
		(width 0.1016)
		(layer "F.Cu")
		(net "M_E_CPU1_SA_DQ<31>")
	)
	(segment
		(start 167.35933 -280.191718)
		(end 165.361112 -280.191718)
		(width 0.1016)
		(layer "F.Cu")
		(net "M_E_CPU1_SA_DQ<31>")
	)
	(segment
		(start 157.193234 -279.990804)
		(end 157.394148 -280.191718)
		(width 0.20066)
		(layer "F.Cu")
		(net "M_E_CPU1_SA_DQ<31>")
	)
	(segment
		(start 141.151356 -264.53084)
		(end 148.891244 -272.270728)
		(width 0.1016)
		(layer "F.Cu")
		(net "M_E_CPU1_SA_DQ<31>")
	)
	(segment
		(start 164.22116 -279.766776)
		(end 162.913314 -279.766776)
		(width 0.20066)
		(layer "F.Cu")
		(net "M_E_CPU1_SA_DQ<31>")
	)
	(segment
		(start 157.624018 -280.191718)
		(end 157.809438 -280.191718)
		(width 0.101854)
		(layer "F.Cu")
		(net "M_E_CPU1_SA_DQ<31>")
	)
	(segment
		(start 165.352984 -280.199846)
		(end 165.335458 -280.199846)
		(width 0.101854)
		(layer "F.Cu")
		(net "M_E_CPU1_SA_DQ<31>")
	)
	(segment
		(start 161.178494 -279.093422)
		(end 161.379154 -279.294082)
		(width 0.20066)
		(layer "F.Cu")
		(net "M_E_CPU1_SA_DQ<31>")
	)
	(segment
		(start 152.669748 -279.822656)
		(end 152.889712 -279.602692)
		(width 0.20066)
		(layer "F.Cu")
		(net "M_E_CPU1_SA_DQ<31>")
	)
	(segment
		(start 154.504136 -279.067514)
		(end 154.865578 -279.067514)
		(width 0.20066)
		(layer "F.Cu")
		(net "M_E_CPU1_SA_DQ<31>")
	)
	(segment
		(start 161.379154 -279.976834)
		(end 161.559494 -280.157174)
		(width 0.20066)
		(layer "F.Cu")
		(net "M_E_CPU1_SA_DQ<31>")
	)
	(segment
		(start 157.025848 -279.419304)
		(end 157.193234 -279.58669)
		(width 0.20066)
		(layer "F.Cu")
		(net "M_E_CPU1_SA_DQ<31>")
	)
	(segment
		(start 168.857676 -279.968706)
		(end 168.857676 -279.708356)
		(width 0.20066)
		(layer "F.Cu")
		(net "M_E_CPU1_SA_DQ<31>")
	)
	(segment
		(start 155.298902 -279.419304)
		(end 157.025848 -279.419304)
		(width 0.20066)
		(layer "F.Cu")
		(net "M_E_CPU1_SA_DQ<31>")
	)
	(segment
		(start 170.457114 -279.766776)
		(end 169.861992 -279.766776)
		(width 0.20066)
		(layer "F.Cu")
		(net "M_E_CPU1_SA_DQ<31>")
	)
	(segment
		(start 152.385522 -279.822656)
		(end 152.669748 -279.822656)
		(width 0.20066)
		(layer "F.Cu")
		(net "M_E_CPU1_SA_DQ<31>")
	)
	(segment
		(start 150.918926 -278.35606)
		(end 151.301958 -278.739092)
		(width 0.1016)
		(layer "F.Cu")
		(net "M_E_CPU1_SA_DQ<31>")
	)
	(segment
		(start 153.481532 -279.293066)
		(end 153.502868 -279.314402)
		(width 0.20066)
		(layer "F.Cu")
		(net "M_E_CPU1_SA_DQ<31>")
	)
	(segment
		(start 168.65981 -279.51049)
		(end 168.223184 -279.51049)
		(width 0.20066)
		(layer "F.Cu")
		(net "M_E_CPU1_SA_DQ<31>")
	)
	(segment
		(start 154.865578 -279.067514)
		(end 155.15971 -279.361646)
		(width 0.20066)
		(layer "F.Cu")
		(net "M_E_CPU1_SA_DQ<31>")
	)
	(segment
		(start 160.115504 -280.223976)
		(end 160.30321 -280.223976)
		(width 0.20066)
		(layer "F.Cu")
		(net "M_E_CPU1_SA_DQ<31>")
	)
	(segment
		(start 139.341352 -263.525508)
		(end 139.43838 -263.42848)
		(width 0.088646)
		(layer "F.Cu")
		(net "M_E_CPU1_SA_DQ<31>")
	)
	(segment
		(start 152.889712 -279.50414)
		(end 153.100786 -279.293066)
		(width 0.20066)
		(layer "F.Cu")
		(net "M_E_CPU1_SA_DQ<31>")
	)
	(segment
		(start 160.502346 -279.294082)
		(end 160.703006 -279.093422)
		(width 0.20066)
		(layer "F.Cu")
		(net "M_E_CPU1_SA_DQ<31>")
	)
	(segment
		(start 139.43838 -263.42848)
		(end 140.048996 -263.42848)
		(width 0.088646)
		(layer "F.Cu")
		(net "M_E_CPU1_SA_DQ<31>")
	)
	(segment
		(start 139.004294 -263.525508)
		(end 139.341352 -263.525508)
		(width 0.088646)
		(layer "F.Cu")
		(net "M_E_CPU1_SA_DQ<31>")
	)
	(segment
		(start 169.049446 -280.160476)
		(end 168.857676 -279.968706)
		(width 0.20066)
		(layer "F.Cu")
		(net "M_E_CPU1_SA_DQ<31>")
	)
	(segment
		(start 160.30321 -280.223976)
		(end 160.502346 -280.02484)
		(width 0.20066)
		(layer "F.Cu")
		(net "M_E_CPU1_SA_DQ<31>")
	)
	(segment
		(start 140.048996 -263.42848)
		(end 141.151356 -264.53084)
		(width 0.088646)
		(layer "F.Cu")
		(net "M_E_CPU1_SA_DQ<31>")
	)
	(segment
		(start 162.008566 -280.157174)
		(end 162.398964 -279.766776)
		(width 0.20066)
		(layer "F.Cu")
		(net "M_E_CPU1_SA_DQ<31>")
	)
	(segment
		(start 165.361112 -280.191718)
		(end 165.352984 -280.199846)
		(width 0.1016)
		(layer "F.Cu")
		(net "M_E_CPU1_SA_DQ<31>")
	)
	(segment
		(start 164.65423 -280.199846)
		(end 164.22116 -279.766776)
		(width 0.20066)
		(layer "F.Cu")
		(net "M_E_CPU1_SA_DQ<31>")
	)
	(segment
		(start 165.335458 -280.199846)
		(end 164.65423 -280.199846)
		(width 0.20066)
		(layer "F.Cu")
		(net "M_E_CPU1_SA_DQ<31>")
	)
	(segment
		(start 168.022524 -279.71115)
		(end 168.022524 -279.999186)
		(width 0.20066)
		(layer "F.Cu")
		(net "M_E_CPU1_SA_DQ<31>")
	)
	(segment
		(start 151.301958 -278.739092)
		(end 152.385522 -279.822656)
		(width 0.20066)
		(layer "F.Cu")
		(net "M_E_CPU1_SA_DQ<31>")
	)
	(segment
		(start 152.889712 -279.602692)
		(end 152.889712 -279.50414)
		(width 0.20066)
		(layer "F.Cu")
		(net "M_E_CPU1_SA_DQ<31>")
	)
	(segment
		(start 157.394148 -280.191718)
		(end 157.624018 -280.191718)
		(width 0.20066)
		(layer "F.Cu")
		(net "M_E_CPU1_SA_DQ<31>")
	)
	(segment
		(start 159.823658 -280.223976)
		(end 160.115504 -280.223976)
		(width 0.101854)
		(layer "F.Cu")
		(net "M_E_CPU1_SA_DQ<31>")
	)
	(segment
		(start 159.808418 -280.223976)
		(end 159.823658 -280.223976)
		(width 0.1016)
		(layer "F.Cu")
		(net "M_E_CPU1_SA_DQ<31>")
	)
	(segment
		(start 160.502346 -280.02484)
		(end 160.502346 -279.294082)
		(width 0.20066)
		(layer "F.Cu")
		(net "M_E_CPU1_SA_DQ<31>")
	)
	(segment
		(start 162.398964 -279.766776)
		(end 162.913314 -279.766776)
		(width 0.20066)
		(layer "F.Cu")
		(net "M_E_CPU1_SA_DQ<31>")
	)
	(segment
		(start 155.15971 -279.361646)
		(end 155.298902 -279.419304)
		(width 0.20066)
		(layer "F.Cu")
		(net "M_E_CPU1_SA_DQ<31>")
	)
	(segment
		(start 159.77616 -280.191718)
		(end 159.808418 -280.223976)
		(width 0.1016)
		(layer "F.Cu")
		(net "M_E_CPU1_SA_DQ<31>")
	)
	(segment
		(start 149.949408 -277.561548)
		(end 150.918926 -278.35606)
		(width 0.1016)
		(layer "F.Cu")
		(net "M_E_CPU1_SA_DQ<31>")
	)
	(segment
		(start 169.861992 -279.766776)
		(end 169.468292 -280.160476)
		(width 0.20066)
		(layer "F.Cu")
		(net "M_E_CPU1_SA_DQ<31>")
	)
	(segment
		(start 167.821864 -280.199846)
		(end 167.367458 -280.199846)
		(width 0.20066)
		(layer "F.Cu")
		(net "M_E_CPU1_SA_DQ<31>")
	)
	(segment
		(start 167.367458 -280.199846)
		(end 167.35933 -280.191718)
		(width 0.1016)
		(layer "F.Cu")
		(net "M_E_CPU1_SA_DQ<31>")
	)
	(segment
		(start 169.468292 -280.160476)
		(end 169.049446 -280.160476)
		(width 0.20066)
		(layer "F.Cu")
		(net "M_E_CPU1_SA_DQ<31>")
	)
	(segment
		(start 148.891244 -272.270728)
		(end 149.949408 -277.561548)
		(width 0.1016)
		(layer "F.Cu")
		(net "M_E_CPU1_SA_DQ<31>")
	)
	(segment
		(start 161.559494 -280.157174)
		(end 162.008566 -280.157174)
		(width 0.20066)
		(layer "F.Cu")
		(net "M_E_CPU1_SA_DQ<31>")
	)
	(segment
		(start 160.703006 -279.093422)
		(end 161.178494 -279.093422)
		(width 0.20066)
		(layer "F.Cu")
		(net "M_E_CPU1_SA_DQ<31>")
	)
	(segment
		(start 153.100786 -279.293066)
		(end 153.481532 -279.293066)
		(width 0.20066)
		(layer "F.Cu")
		(net "M_E_CPU1_SA_DQ<31>")
	)
	(segment
		(start 161.379154 -279.294082)
		(end 161.379154 -279.976834)
		(width 0.20066)
		(layer "F.Cu")
		(net "M_E_CPU1_SA_DQ<31>")
	)
	(segment
		(start 168.223184 -279.51049)
		(end 168.022524 -279.71115)
		(width 0.20066)
		(layer "F.Cu")
		(net "M_E_CPU1_SA_DQ<31>")
	)
	(segment
		(start 138.515598 -263.282684)
		(end 138.802364 -263.466326)
		(width 0.088646)
		(layer "F.Cu")
		(net "M_E_CPU1_SA_DQ<31>")
	)
	(segment
		(start 157.193234 -279.58669)
		(end 157.193234 -279.990804)
		(width 0.20066)
		(layer "F.Cu")
		(net "M_E_CPU1_SA_DQ<31>")
	)
	(segment
		(start 153.502868 -279.314402)
		(end 154.257248 -279.314402)
		(width 0.20066)
		(layer "F.Cu")
		(net "M_E_CPU1_SA_DQ<31>")
	)
	(segment
		(start 168.857676 -279.708356)
		(end 168.65981 -279.51049)
		(width 0.20066)
		(layer "F.Cu")
		(net "M_E_CPU1_SA_DQ<31>")
	)
	(segment
		(start 154.257248 -279.314402)
		(end 154.504136 -279.067514)
		(width 0.20066)
		(layer "F.Cu")
		(net "M_E_CPU1_SA_DQ<31>")
	)
	(arc
		(start 138.802364 -263.466326)
		(mid 138.899091 -263.510378)
		(end 139.004294 -263.525508)
		(width 0.088646)
		(layer "F.Cu")
		(net "M_E_CPU1_SA_DQ<31>")
	)
	(arc
		(start 138.064494 -263.150604)
		(mid 138.298453 -263.187936)
		(end 138.515598 -263.282684)
		(width 0.088646)
		(layer "F.Cu")
		(net "M_E_CPU1_SA_DQ<31>")
	)
	(segment
		(start 155.585414 -281.340052)
		(end 155.585414 -281.08402)
		(width 0.20066)
		(layer "F.Cu")
		(net "M_E_CPU1_SA_DQ<30>")
	)
	(segment
		(start 165.036246 -281.90063)
		(end 164.602414 -281.466798)
		(width 0.20066)
		(layer "F.Cu")
		(net "M_E_CPU1_SA_DQ<30>")
	)
	(segment
		(start 167.38092 -281.897836)
		(end 167.377364 -281.89682)
		(width 0.20066)
		(layer "F.Cu")
		(net "M_E_CPU1_SA_DQ<30>")
	)
	(segment
		(start 159.811212 -281.89174)
		(end 159.823658 -281.904186)
		(width 0.1016)
		(layer "F.Cu")
		(net "M_E_CPU1_SA_DQ<30>")
	)
	(segment
		(start 165.335458 -281.90063)
		(end 165.036246 -281.90063)
		(width 0.20066)
		(layer "F.Cu")
		(net "M_E_CPU1_SA_DQ<30>")
	)
	(segment
		(start 150.20671 -279.684734)
		(end 150.409402 -279.684734)
		(width 0.1016)
		(layer "F.Cu")
		(net "M_E_CPU1_SA_DQ<30>")
	)
	(segment
		(start 138.81227 -263.967214)
		(end 138.869674 -263.910826)
		(width 0.088646)
		(layer "F.Cu")
		(net "M_E_CPU1_SA_DQ<30>")
	)
	(segment
		(start 160.657032 -281.095196)
		(end 160.993582 -281.095196)
		(width 0.20066)
		(layer "F.Cu")
		(net "M_E_CPU1_SA_DQ<30>")
	)
	(segment
		(start 160.418018 -281.69108)
		(end 160.418018 -281.33421)
		(width 0.20066)
		(layer "F.Cu")
		(net "M_E_CPU1_SA_DQ<30>")
	)
	(segment
		(start 164.602414 -281.466798)
		(end 162.913314 -281.466798)
		(width 0.20066)
		(layer "F.Cu")
		(net "M_E_CPU1_SA_DQ<30>")
	)
	(segment
		(start 168.265348 -281.698192)
		(end 168.065704 -281.897836)
		(width 0.20066)
		(layer "F.Cu")
		(net "M_E_CPU1_SA_DQ<30>")
	)
	(segment
		(start 160.993582 -281.095196)
		(end 161.365184 -281.466798)
		(width 0.20066)
		(layer "F.Cu")
		(net "M_E_CPU1_SA_DQ<30>")
	)
	(segment
		(start 169.135552 -281.466798)
		(end 168.807384 -281.13863)
		(width 0.20066)
		(layer "F.Cu")
		(net "M_E_CPU1_SA_DQ<30>")
	)
	(segment
		(start 167.372538 -281.899106)
		(end 167.367458 -281.899106)
		(width 0.20066)
		(layer "F.Cu")
		(net "M_E_CPU1_SA_DQ<30>")
	)
	(segment
		(start 160.204912 -281.904186)
		(end 160.418018 -281.69108)
		(width 0.20066)
		(layer "F.Cu")
		(net "M_E_CPU1_SA_DQ<30>")
	)
	(segment
		(start 168.474136 -281.13863)
		(end 168.265348 -281.347418)
		(width 0.20066)
		(layer "F.Cu")
		(net "M_E_CPU1_SA_DQ<30>")
	)
	(segment
		(start 156.316934 -280.705306)
		(end 157.512258 -281.90063)
		(width 0.20066)
		(layer "F.Cu")
		(net "M_E_CPU1_SA_DQ<30>")
	)
	(segment
		(start 157.804612 -281.90063)
		(end 157.809692 -281.90063)
		(width 0.1016)
		(layer "F.Cu")
		(net "M_E_CPU1_SA_DQ<30>")
	)
	(segment
		(start 160.418018 -281.33421)
		(end 160.657032 -281.095196)
		(width 0.20066)
		(layer "F.Cu")
		(net "M_E_CPU1_SA_DQ<30>")
	)
	(segment
		(start 138.534648 -263.96442)
		(end 138.81227 -263.967214)
		(width 0.088646)
		(layer "F.Cu")
		(net "M_E_CPU1_SA_DQ<30>")
	)
	(segment
		(start 155.964128 -280.705306)
		(end 156.316934 -280.705306)
		(width 0.20066)
		(layer "F.Cu")
		(net "M_E_CPU1_SA_DQ<30>")
	)
	(segment
		(start 168.807384 -281.13863)
		(end 168.474136 -281.13863)
		(width 0.20066)
		(layer "F.Cu")
		(net "M_E_CPU1_SA_DQ<30>")
	)
	(segment
		(start 150.527512 -279.802844)
		(end 152.776174 -282.051506)
		(width 0.20066)
		(layer "F.Cu")
		(net "M_E_CPU1_SA_DQ<30>")
	)
	(segment
		(start 157.791658 -281.90063)
		(end 157.804612 -281.90063)
		(width 0.101854)
		(layer "F.Cu")
		(net "M_E_CPU1_SA_DQ<30>")
	)
	(segment
		(start 155.585414 -281.08402)
		(end 155.964128 -280.705306)
		(width 0.20066)
		(layer "F.Cu")
		(net "M_E_CPU1_SA_DQ<30>")
	)
	(segment
		(start 155.363164 -281.8765)
		(end 155.585414 -281.340052)
		(width 0.20066)
		(layer "F.Cu")
		(net "M_E_CPU1_SA_DQ<30>")
	)
	(segment
		(start 165.352984 -281.90063)
		(end 165.335458 -281.90063)
		(width 0.101854)
		(layer "F.Cu")
		(net "M_E_CPU1_SA_DQ<30>")
	)
	(segment
		(start 154.448256 -282.051506)
		(end 154.676094 -282.279344)
		(width 0.20066)
		(layer "F.Cu")
		(net "M_E_CPU1_SA_DQ<30>")
	)
	(segment
		(start 167.360092 -281.89174)
		(end 165.361874 -281.89174)
		(width 0.1016)
		(layer "F.Cu")
		(net "M_E_CPU1_SA_DQ<30>")
	)
	(segment
		(start 168.265348 -281.347418)
		(end 168.265348 -281.698192)
		(width 0.20066)
		(layer "F.Cu")
		(net "M_E_CPU1_SA_DQ<30>")
	)
	(segment
		(start 167.377364 -281.89682)
		(end 167.372538 -281.899106)
		(width 0.20066)
		(layer "F.Cu")
		(net "M_E_CPU1_SA_DQ<30>")
	)
	(segment
		(start 167.367458 -281.899106)
		(end 167.360092 -281.89174)
		(width 0.1016)
		(layer "F.Cu")
		(net "M_E_CPU1_SA_DQ<30>")
	)
	(segment
		(start 157.512258 -281.90063)
		(end 157.791658 -281.90063)
		(width 0.20066)
		(layer "F.Cu")
		(net "M_E_CPU1_SA_DQ<30>")
	)
	(segment
		(start 154.96032 -282.279344)
		(end 155.363164 -281.8765)
		(width 0.20066)
		(layer "F.Cu")
		(net "M_E_CPU1_SA_DQ<30>")
	)
	(segment
		(start 152.776174 -282.051506)
		(end 154.448256 -282.051506)
		(width 0.20066)
		(layer "F.Cu")
		(net "M_E_CPU1_SA_DQ<30>")
	)
	(segment
		(start 159.823658 -281.904186)
		(end 160.204912 -281.904186)
		(width 0.20066)
		(layer "F.Cu")
		(net "M_E_CPU1_SA_DQ<30>")
	)
	(segment
		(start 138.869674 -263.910826)
		(end 139.66825 -263.910826)
		(width 0.088646)
		(layer "F.Cu")
		(net "M_E_CPU1_SA_DQ<30>")
	)
	(segment
		(start 161.365184 -281.466798)
		(end 162.913314 -281.466798)
		(width 0.20066)
		(layer "F.Cu")
		(net "M_E_CPU1_SA_DQ<30>")
	)
	(segment
		(start 165.361874 -281.89174)
		(end 165.352984 -281.90063)
		(width 0.1016)
		(layer "F.Cu")
		(net "M_E_CPU1_SA_DQ<30>")
	)
	(segment
		(start 168.065704 -281.897836)
		(end 167.38092 -281.897836)
		(width 0.20066)
		(layer "F.Cu")
		(net "M_E_CPU1_SA_DQ<30>")
	)
	(segment
		(start 157.818582 -281.89174)
		(end 159.811212 -281.89174)
		(width 0.1016)
		(layer "F.Cu")
		(net "M_E_CPU1_SA_DQ<30>")
	)
	(segment
		(start 170.457114 -281.466798)
		(end 169.135552 -281.466798)
		(width 0.20066)
		(layer "F.Cu")
		(net "M_E_CPU1_SA_DQ<30>")
	)
	(segment
		(start 140.71981 -264.962386)
		(end 148.329142 -272.571718)
		(width 0.1016)
		(layer "F.Cu")
		(net "M_E_CPU1_SA_DQ<30>")
	)
	(segment
		(start 148.329142 -272.571718)
		(end 149.638766 -279.11679)
		(width 0.1016)
		(layer "F.Cu")
		(net "M_E_CPU1_SA_DQ<30>")
	)
	(segment
		(start 149.638766 -279.11679)
		(end 150.20671 -279.684734)
		(width 0.1016)
		(layer "F.Cu")
		(net "M_E_CPU1_SA_DQ<30>")
	)
	(segment
		(start 150.409402 -279.684734)
		(end 150.527512 -279.802844)
		(width 0.1016)
		(layer "F.Cu")
		(net "M_E_CPU1_SA_DQ<30>")
	)
	(segment
		(start 139.66825 -263.910826)
		(end 140.71981 -264.962386)
		(width 0.088646)
		(layer "F.Cu")
		(net "M_E_CPU1_SA_DQ<30>")
	)
	(segment
		(start 154.676094 -282.279344)
		(end 154.96032 -282.279344)
		(width 0.20066)
		(layer "F.Cu")
		(net "M_E_CPU1_SA_DQ<30>")
	)
	(segment
		(start 157.809692 -281.90063)
		(end 157.818582 -281.89174)
		(width 0.1016)
		(layer "F.Cu")
		(net "M_E_CPU1_SA_DQ<30>")
	)
	(segment
		(start 167.30726 -315.90361)
		(end 167.295322 -315.891672)
		(width 0.101854)
		(layer "F.Cu")
		(net "M_E_CPU1_SA_DQ<2>")
	)
	(segment
		(start 139.431776 -281.063446)
		(end 139.431776 -296.678604)
		(width 0.1016)
		(layer "F.Cu")
		(net "M_E_CPU1_SA_DQ<2>")
	)
	(segment
		(start 163.908232 -315.301884)
		(end 163.743386 -315.46673)
		(width 0.20066)
		(layer "F.Cu")
		(net "M_E_CPU1_SA_DQ<2>")
	)
	(segment
		(start 139.48283 -296.729658)
		(end 139.48283 -297.327828)
		(width 0.1016)
		(layer "F.Cu")
		(net "M_E_CPU1_SA_DQ<2>")
	)
	(segment
		(start 165.402514 -315.903864)
		(end 165.335458 -315.903864)
		(width 0.101854)
		(layer "F.Cu")
		(net "M_E_CPU1_SA_DQ<2>")
	)
	(segment
		(start 169.135552 -315.46673)
		(end 168.883584 -315.214762)
		(width 0.20066)
		(layer "F.Cu")
		(net "M_E_CPU1_SA_DQ<2>")
	)
	(segment
		(start 160.205166 -315.901578)
		(end 161.405824 -315.404246)
		(width 0.20066)
		(layer "F.Cu")
		(net "M_E_CPU1_SA_DQ<2>")
	)
	(segment
		(start 159.686498 -315.891672)
		(end 159.787082 -315.891672)
		(width 0.101854)
		(layer "F.Cu")
		(net "M_E_CPU1_SA_DQ<2>")
	)
	(segment
		(start 159.787082 -315.891672)
		(end 159.796988 -315.901578)
		(width 0.101854)
		(layer "F.Cu")
		(net "M_E_CPU1_SA_DQ<2>")
	)
	(segment
		(start 167.295322 -315.891672)
		(end 167.256206 -315.891672)
		(width 0.101854)
		(layer "F.Cu")
		(net "M_E_CPU1_SA_DQ<2>")
	)
	(segment
		(start 138.064494 -279.428194)
		(end 138.748262 -279.502362)
		(width 0.088646)
		(layer "F.Cu")
		(net "M_E_CPU1_SA_DQ<2>")
	)
	(segment
		(start 168.059354 -315.90361)
		(end 167.367458 -315.90361)
		(width 0.20066)
		(layer "F.Cu")
		(net "M_E_CPU1_SA_DQ<2>")
	)
	(segment
		(start 159.823658 -315.901578)
		(end 160.205166 -315.901578)
		(width 0.20066)
		(layer "F.Cu")
		(net "M_E_CPU1_SA_DQ<2>")
	)
	(segment
		(start 167.256206 -315.891672)
		(end 165.414706 -315.891672)
		(width 0.1016)
		(layer "F.Cu")
		(net "M_E_CPU1_SA_DQ<2>")
	)
	(segment
		(start 161.405824 -315.404246)
		(end 162.011614 -315.404246)
		(width 0.20066)
		(layer "F.Cu")
		(net "M_E_CPU1_SA_DQ<2>")
	)
	(segment
		(start 157.791658 -315.897514)
		(end 157.81147 -315.897514)
		(width 0.101854)
		(layer "F.Cu")
		(net "M_E_CPU1_SA_DQ<2>")
	)
	(segment
		(start 165.335458 -315.903864)
		(end 165.03904 -315.903864)
		(width 0.20066)
		(layer "F.Cu")
		(net "M_E_CPU1_SA_DQ<2>")
	)
	(segment
		(start 168.883584 -315.214762)
		(end 168.499536 -315.214762)
		(width 0.20066)
		(layer "F.Cu")
		(net "M_E_CPU1_SA_DQ<2>")
	)
	(segment
		(start 139.48283 -297.327828)
		(end 139.48283 -298.648882)
		(width 0.20066)
		(layer "F.Cu")
		(net "M_E_CPU1_SA_DQ<2>")
	)
	(segment
		(start 163.743386 -315.46673)
		(end 162.913314 -315.46673)
		(width 0.20066)
		(layer "F.Cu")
		(net "M_E_CPU1_SA_DQ<2>")
	)
	(segment
		(start 157.81147 -315.897514)
		(end 157.817312 -315.891672)
		(width 0.101854)
		(layer "F.Cu")
		(net "M_E_CPU1_SA_DQ<2>")
	)
	(segment
		(start 139.48283 -298.648882)
		(end 139.808204 -299.43425)
		(width 0.20066)
		(layer "F.Cu")
		(net "M_E_CPU1_SA_DQ<2>")
	)
	(segment
		(start 165.03904 -315.903864)
		(end 164.43706 -315.301884)
		(width 0.20066)
		(layer "F.Cu")
		(net "M_E_CPU1_SA_DQ<2>")
	)
	(segment
		(start 162.074098 -315.46673)
		(end 162.913314 -315.46673)
		(width 0.20066)
		(layer "F.Cu")
		(net "M_E_CPU1_SA_DQ<2>")
	)
	(segment
		(start 159.796988 -315.901578)
		(end 159.823658 -315.901578)
		(width 0.101854)
		(layer "F.Cu")
		(net "M_E_CPU1_SA_DQ<2>")
	)
	(segment
		(start 168.265348 -315.44895)
		(end 168.265348 -315.697616)
		(width 0.20066)
		(layer "F.Cu")
		(net "M_E_CPU1_SA_DQ<2>")
	)
	(segment
		(start 157.395418 -315.897514)
		(end 157.791658 -315.897514)
		(width 0.20066)
		(layer "F.Cu")
		(net "M_E_CPU1_SA_DQ<2>")
	)
	(segment
		(start 138.748262 -279.502362)
		(end 139.247372 -280.001472)
		(width 0.088646)
		(layer "F.Cu")
		(net "M_E_CPU1_SA_DQ<2>")
	)
	(segment
		(start 164.43706 -315.301884)
		(end 163.908232 -315.301884)
		(width 0.20066)
		(layer "F.Cu")
		(net "M_E_CPU1_SA_DQ<2>")
	)
	(segment
		(start 139.247372 -280.001472)
		(end 139.431776 -280.44648)
		(width 0.088646)
		(layer "F.Cu")
		(net "M_E_CPU1_SA_DQ<2>")
	)
	(segment
		(start 157.817312 -315.891672)
		(end 158.056834 -315.891672)
		(width 0.101854)
		(layer "F.Cu")
		(net "M_E_CPU1_SA_DQ<2>")
	)
	(segment
		(start 170.457114 -315.46673)
		(end 169.135552 -315.46673)
		(width 0.20066)
		(layer "F.Cu")
		(net "M_E_CPU1_SA_DQ<2>")
	)
	(segment
		(start 167.367458 -315.90361)
		(end 167.30726 -315.90361)
		(width 0.101854)
		(layer "F.Cu")
		(net "M_E_CPU1_SA_DQ<2>")
	)
	(segment
		(start 165.414706 -315.891672)
		(end 165.402514 -315.903864)
		(width 0.101854)
		(layer "F.Cu")
		(net "M_E_CPU1_SA_DQ<2>")
	)
	(segment
		(start 139.431776 -296.678604)
		(end 139.48283 -296.729658)
		(width 0.101854)
		(layer "F.Cu")
		(net "M_E_CPU1_SA_DQ<2>")
	)
	(segment
		(start 156.478986 -315.518038)
		(end 157.188408 -315.811916)
		(width 0.20066)
		(layer "F.Cu")
		(net "M_E_CPU1_SA_DQ<2>")
	)
	(segment
		(start 168.265348 -315.697616)
		(end 168.059354 -315.90361)
		(width 0.20066)
		(layer "F.Cu")
		(net "M_E_CPU1_SA_DQ<2>")
	)
	(segment
		(start 162.011614 -315.404246)
		(end 162.074098 -315.46673)
		(width 0.20066)
		(layer "F.Cu")
		(net "M_E_CPU1_SA_DQ<2>")
	)
	(segment
		(start 168.499536 -315.214762)
		(end 168.265348 -315.44895)
		(width 0.20066)
		(layer "F.Cu")
		(net "M_E_CPU1_SA_DQ<2>")
	)
	(segment
		(start 139.808204 -299.43425)
		(end 154.712162 -314.338208)
		(width 0.20066)
		(layer "F.Cu")
		(net "M_E_CPU1_SA_DQ<2>")
	)
	(segment
		(start 154.712162 -314.338208)
		(end 156.478986 -315.518038)
		(width 0.20066)
		(layer "F.Cu")
		(net "M_E_CPU1_SA_DQ<2>")
	)
	(segment
		(start 158.056834 -315.891672)
		(end 159.686498 -315.891672)
		(width 0.1016)
		(layer "F.Cu")
		(net "M_E_CPU1_SA_DQ<2>")
	)
	(segment
		(start 157.188408 -315.811916)
		(end 157.395418 -315.897514)
		(width 0.20066)
		(layer "F.Cu")
		(net "M_E_CPU1_SA_DQ<2>")
	)
	(segment
		(start 139.431776 -280.44648)
		(end 139.431776 -281.063446)
		(width 0.088646)
		(layer "F.Cu")
		(net "M_E_CPU1_SA_DQ<2>")
	)
	(segment
		(start 137.764774 -263.622028)
		(end 138.215624 -263.622028)
		(width 0.088646)
		(layer "F.Cu")
		(net "M_E_CPU1_SA_DQ<29>")
	)
	(segment
		(start 138.215624 -263.622028)
		(end 138.307826 -263.529826)
		(width 0.088646)
		(layer "F.Cu")
		(net "M_E_CPU1_SA_DQ<29>")
	)
	(segment
		(start 150.08225 -278.668988)
		(end 150.21433 -278.801068)
		(width 0.1016)
		(layer "F.Cu")
		(net "M_E_CPU1_SA_DQ<29>")
	)
	(segment
		(start 160.626552 -280.531316)
		(end 160.126934 -281.030934)
		(width 0.20066)
		(layer "F.Cu")
		(net "M_E_CPU1_SA_DQ<29>")
	)
	(segment
		(start 155.2575 -280.224738)
		(end 155.541726 -280.224738)
		(width 0.20066)
		(layer "F.Cu")
		(net "M_E_CPU1_SA_DQ<29>")
	)
	(segment
		(start 140.93571 -264.74674)
		(end 148.610066 -272.421096)
		(width 0.1016)
		(layer "F.Cu")
		(net "M_E_CPU1_SA_DQ<29>")
	)
	(segment
		(start 138.65352 -263.600692)
		(end 138.721846 -263.640062)
		(width 0.088646)
		(layer "F.Cu")
		(net "M_E_CPU1_SA_DQ<29>")
	)
	(segment
		(start 155.704794 -280.06167)
		(end 156.626306 -280.06167)
		(width 0.20066)
		(layer "F.Cu")
		(net "M_E_CPU1_SA_DQ<29>")
	)
	(segment
		(start 157.597348 -281.032712)
		(end 157.825948 -281.032712)
		(width 0.20066)
		(layer "F.Cu")
		(net "M_E_CPU1_SA_DQ<29>")
	)
	(segment
		(start 158.242 -280.61666)
		(end 158.813246 -280.61666)
		(width 0.20066)
		(layer "F.Cu")
		(net "M_E_CPU1_SA_DQ<29>")
	)
	(segment
		(start 157.825948 -281.032712)
		(end 158.242 -280.61666)
		(width 0.20066)
		(layer "F.Cu")
		(net "M_E_CPU1_SA_DQ<29>")
	)
	(segment
		(start 150.21433 -278.801068)
		(end 150.452074 -278.801068)
		(width 0.1016)
		(layer "F.Cu")
		(net "M_E_CPU1_SA_DQ<29>")
	)
	(segment
		(start 154.945842 -281.211274)
		(end 154.945842 -280.926794)
		(width 0.20066)
		(layer "F.Cu")
		(net "M_E_CPU1_SA_DQ<29>")
	)
	(segment
		(start 163.91382 -281.041602)
		(end 161.911284 -281.041602)
		(width 0.1016)
		(layer "F.Cu")
		(net "M_E_CPU1_SA_DQ<29>")
	)
	(segment
		(start 161.89325 -281.059636)
		(end 161.891726 -281.059636)
		(width 0.101854)
		(layer "F.Cu")
		(net "M_E_CPU1_SA_DQ<29>")
	)
	(segment
		(start 153.06294 -281.411934)
		(end 154.745182 -281.411934)
		(width 0.20066)
		(layer "F.Cu")
		(net "M_E_CPU1_SA_DQ<29>")
	)
	(segment
		(start 159.325056 -280.61666)
		(end 158.813246 -280.61666)
		(width 0.20066)
		(layer "F.Cu")
		(net "M_E_CPU1_SA_DQ<29>")
	)
	(segment
		(start 153.164286 -280.525474)
		(end 153.164286 -280.240994)
		(width 0.20066)
		(layer "F.Cu")
		(net "M_E_CPU1_SA_DQ<29>")
	)
	(segment
		(start 164.638228 -280.61666)
		(end 164.20338 -281.051508)
		(width 0.20066)
		(layer "F.Cu")
		(net "M_E_CPU1_SA_DQ<29>")
	)
	(segment
		(start 155.073096 -280.040334)
		(end 155.2575 -280.224738)
		(width 0.20066)
		(layer "F.Cu")
		(net "M_E_CPU1_SA_DQ<29>")
	)
	(segment
		(start 149.709124 -277.914862)
		(end 150.08225 -278.287988)
		(width 0.1016)
		(layer "F.Cu")
		(net "M_E_CPU1_SA_DQ<29>")
	)
	(segment
		(start 161.891726 -281.059636)
		(end 161.560764 -281.059636)
		(width 0.20066)
		(layer "F.Cu")
		(net "M_E_CPU1_SA_DQ<29>")
	)
	(segment
		(start 150.08225 -278.287988)
		(end 150.08225 -278.668988)
		(width 0.1016)
		(layer "F.Cu")
		(net "M_E_CPU1_SA_DQ<29>")
	)
	(segment
		(start 139.004294 -263.715754)
		(end 139.904724 -263.715754)
		(width 0.088646)
		(layer "F.Cu")
		(net "M_E_CPU1_SA_DQ<29>")
	)
	(segment
		(start 161.911284 -281.041602)
		(end 161.89325 -281.059636)
		(width 0.1016)
		(layer "F.Cu")
		(net "M_E_CPU1_SA_DQ<29>")
	)
	(segment
		(start 155.541726 -280.224738)
		(end 155.704794 -280.06167)
		(width 0.20066)
		(layer "F.Cu")
		(net "M_E_CPU1_SA_DQ<29>")
	)
	(segment
		(start 138.307826 -263.529826)
		(end 138.390122 -263.529826)
		(width 0.088646)
		(layer "F.Cu")
		(net "M_E_CPU1_SA_DQ<29>")
	)
	(segment
		(start 166.357046 -280.61666)
		(end 164.638228 -280.61666)
		(width 0.20066)
		(layer "F.Cu")
		(net "M_E_CPU1_SA_DQ<29>")
	)
	(segment
		(start 153.164286 -280.240994)
		(end 153.364946 -280.040334)
		(width 0.20066)
		(layer "F.Cu")
		(net "M_E_CPU1_SA_DQ<29>")
	)
	(segment
		(start 154.745182 -280.726134)
		(end 153.364946 -280.726134)
		(width 0.20066)
		(layer "F.Cu")
		(net "M_E_CPU1_SA_DQ<29>")
	)
	(segment
		(start 160.126934 -281.030934)
		(end 159.73933 -281.030934)
		(width 0.20066)
		(layer "F.Cu")
		(net "M_E_CPU1_SA_DQ<29>")
	)
	(segment
		(start 156.626306 -280.06167)
		(end 157.597348 -281.032712)
		(width 0.20066)
		(layer "F.Cu")
		(net "M_E_CPU1_SA_DQ<29>")
	)
	(segment
		(start 137.124694 -263.150604)
		(end 137.41273 -263.269984)
		(width 0.088646)
		(layer "F.Cu")
		(net "M_E_CPU1_SA_DQ<29>")
	)
	(segment
		(start 153.364946 -280.726134)
		(end 153.164286 -280.525474)
		(width 0.20066)
		(layer "F.Cu")
		(net "M_E_CPU1_SA_DQ<29>")
	)
	(segment
		(start 148.610066 -272.421096)
		(end 149.709124 -277.914862)
		(width 0.1016)
		(layer "F.Cu")
		(net "M_E_CPU1_SA_DQ<29>")
	)
	(segment
		(start 161.560764 -281.059636)
		(end 161.032444 -280.531316)
		(width 0.20066)
		(layer "F.Cu")
		(net "M_E_CPU1_SA_DQ<29>")
	)
	(segment
		(start 137.41273 -263.269984)
		(end 137.764774 -263.622028)
		(width 0.088646)
		(layer "F.Cu")
		(net "M_E_CPU1_SA_DQ<29>")
	)
	(segment
		(start 159.73933 -281.030934)
		(end 159.325056 -280.61666)
		(width 0.20066)
		(layer "F.Cu")
		(net "M_E_CPU1_SA_DQ<29>")
	)
	(segment
		(start 161.032444 -280.531316)
		(end 160.626552 -280.531316)
		(width 0.20066)
		(layer "F.Cu")
		(net "M_E_CPU1_SA_DQ<29>")
	)
	(segment
		(start 150.452074 -278.801068)
		(end 150.693628 -279.042622)
		(width 0.1016)
		(layer "F.Cu")
		(net "M_E_CPU1_SA_DQ<29>")
	)
	(segment
		(start 163.923726 -281.051508)
		(end 163.91382 -281.041602)
		(width 0.1016)
		(layer "F.Cu")
		(net "M_E_CPU1_SA_DQ<29>")
	)
	(segment
		(start 164.20338 -281.051508)
		(end 163.923726 -281.051508)
		(width 0.20066)
		(layer "F.Cu")
		(net "M_E_CPU1_SA_DQ<29>")
	)
	(segment
		(start 154.945842 -280.926794)
		(end 154.745182 -280.726134)
		(width 0.20066)
		(layer "F.Cu")
		(net "M_E_CPU1_SA_DQ<29>")
	)
	(segment
		(start 154.745182 -281.411934)
		(end 154.945842 -281.211274)
		(width 0.20066)
		(layer "F.Cu")
		(net "M_E_CPU1_SA_DQ<29>")
	)
	(segment
		(start 139.904724 -263.715754)
		(end 140.93571 -264.74674)
		(width 0.088646)
		(layer "F.Cu")
		(net "M_E_CPU1_SA_DQ<29>")
	)
	(segment
		(start 150.693628 -279.042622)
		(end 153.06294 -281.411934)
		(width 0.20066)
		(layer "F.Cu")
		(net "M_E_CPU1_SA_DQ<29>")
	)
	(segment
		(start 153.364946 -280.040334)
		(end 155.073096 -280.040334)
		(width 0.20066)
		(layer "F.Cu")
		(net "M_E_CPU1_SA_DQ<29>")
	)
	(arc
		(start 138.721846 -263.640062)
		(mid 138.858088 -263.696496)
		(end 139.004294 -263.715754)
		(width 0.088646)
		(layer "F.Cu")
		(net "M_E_CPU1_SA_DQ<29>")
	)
	(arc
		(start 138.390122 -263.529826)
		(mid 138.526494 -263.547888)
		(end 138.65352 -263.600692)
		(width 0.088646)
		(layer "F.Cu")
		(net "M_E_CPU1_SA_DQ<29>")
	)
	(segment
		(start 161.371788 -282.42387)
		(end 161.196274 -282.599384)
		(width 0.20066)
		(layer "F.Cu")
		(net "M_E_CPU1_SA_DQ<28>")
	)
	(segment
		(start 164.774626 -282.316682)
		(end 164.33038 -281.872436)
		(width 0.20066)
		(layer "F.Cu")
		(net "M_E_CPU1_SA_DQ<28>")
	)
	(segment
		(start 156.180536 -281.757628)
		(end 156.464762 -281.757628)
		(width 0.20066)
		(layer "F.Cu")
		(net "M_E_CPU1_SA_DQ<28>")
	)
	(segment
		(start 155.334462 -282.895802)
		(end 155.334462 -282.80995)
		(width 0.20066)
		(layer "F.Cu")
		(net "M_E_CPU1_SA_DQ<28>")
	)
	(segment
		(start 164.33038 -281.872436)
		(end 163.923726 -281.872436)
		(width 0.20066)
		(layer "F.Cu")
		(net "M_E_CPU1_SA_DQ<28>")
	)
	(segment
		(start 160.860232 -282.599384)
		(end 160.57753 -282.316682)
		(width 0.20066)
		(layer "F.Cu")
		(net "M_E_CPU1_SA_DQ<28>")
	)
	(segment
		(start 161.196274 -282.599384)
		(end 160.860232 -282.599384)
		(width 0.20066)
		(layer "F.Cu")
		(net "M_E_CPU1_SA_DQ<28>")
	)
	(segment
		(start 154.17673 -282.691078)
		(end 154.383232 -282.89758)
		(width 0.20066)
		(layer "F.Cu")
		(net "M_E_CPU1_SA_DQ<28>")
	)
	(segment
		(start 136.655048 -263.96442)
		(end 136.41578 -264.06348)
		(width 0.088646)
		(layer "F.Cu")
		(net "M_E_CPU1_SA_DQ<28>")
	)
	(segment
		(start 137.558018 -264.368026)
		(end 137.684002 -264.49401)
		(width 0.088646)
		(layer "F.Cu")
		(net "M_E_CPU1_SA_DQ<28>")
	)
	(segment
		(start 137.349738 -264.248138)
		(end 137.558018 -264.368026)
		(width 0.088646)
		(layer "F.Cu")
		(net "M_E_CPU1_SA_DQ<28>")
	)
	(segment
		(start 149.90699 -280.092404)
		(end 150.527258 -280.712672)
		(width 0.1016)
		(layer "F.Cu")
		(net "M_E_CPU1_SA_DQ<28>")
	)
	(segment
		(start 137.064496 -264.08888)
		(end 137.19048 -264.08888)
		(width 0.088646)
		(layer "F.Cu")
		(net "M_E_CPU1_SA_DQ<28>")
	)
	(segment
		(start 155.334462 -282.80995)
		(end 155.905454 -282.238958)
		(width 0.20066)
		(layer "F.Cu")
		(net "M_E_CPU1_SA_DQ<28>")
	)
	(segment
		(start 161.581846 -281.882342)
		(end 161.371788 -282.0924)
		(width 0.20066)
		(layer "F.Cu")
		(net "M_E_CPU1_SA_DQ<28>")
	)
	(segment
		(start 150.527258 -280.712672)
		(end 152.505664 -282.691078)
		(width 0.20066)
		(layer "F.Cu")
		(net "M_E_CPU1_SA_DQ<28>")
	)
	(segment
		(start 153.881836 -282.691078)
		(end 154.17673 -282.691078)
		(width 0.20066)
		(layer "F.Cu")
		(net "M_E_CPU1_SA_DQ<28>")
	)
	(segment
		(start 137.96518 -264.11428)
		(end 138.100816 -264.11428)
		(width 0.088646)
		(layer "F.Cu")
		(net "M_E_CPU1_SA_DQ<28>")
	)
	(segment
		(start 137.876026 -264.203434)
		(end 137.96518 -264.11428)
		(width 0.088646)
		(layer "F.Cu")
		(net "M_E_CPU1_SA_DQ<28>")
	)
	(segment
		(start 139.030456 -264.11809)
		(end 139.444222 -264.11809)
		(width 0.088646)
		(layer "F.Cu")
		(net "M_E_CPU1_SA_DQ<28>")
	)
	(segment
		(start 153.196036 -283.268166)
		(end 153.480516 -283.268166)
		(width 0.20066)
		(layer "F.Cu")
		(net "M_E_CPU1_SA_DQ<28>")
	)
	(segment
		(start 161.896552 -281.882342)
		(end 161.891726 -281.882342)
		(width 0.101854)
		(layer "F.Cu")
		(net "M_E_CPU1_SA_DQ<28>")
	)
	(segment
		(start 157.34411 -282.316682)
		(end 158.813246 -282.316682)
		(width 0.20066)
		(layer "F.Cu")
		(net "M_E_CPU1_SA_DQ<28>")
	)
	(segment
		(start 139.932918 -264.606786)
		(end 148.047964 -272.721832)
		(width 0.1016)
		(layer "F.Cu")
		(net "M_E_CPU1_SA_DQ<28>")
	)
	(segment
		(start 156.464762 -281.757628)
		(end 156.911548 -282.204414)
		(width 0.20066)
		(layer "F.Cu")
		(net "M_E_CPU1_SA_DQ<28>")
	)
	(segment
		(start 148.047964 -272.721832)
		(end 149.447504 -279.715722)
		(width 0.1016)
		(layer "F.Cu")
		(net "M_E_CPU1_SA_DQ<28>")
	)
	(segment
		(start 153.480516 -283.268166)
		(end 153.681176 -283.067506)
		(width 0.20066)
		(layer "F.Cu")
		(net "M_E_CPU1_SA_DQ<28>")
	)
	(segment
		(start 152.794462 -282.691078)
		(end 152.995376 -282.891992)
		(width 0.20066)
		(layer "F.Cu")
		(net "M_E_CPU1_SA_DQ<28>")
	)
	(segment
		(start 160.57753 -282.316682)
		(end 158.813246 -282.316682)
		(width 0.20066)
		(layer "F.Cu")
		(net "M_E_CPU1_SA_DQ<28>")
	)
	(segment
		(start 136.41578 -264.06348)
		(end 136.148064 -264.06348)
		(width 0.088646)
		(layer "F.Cu")
		(net "M_E_CPU1_SA_DQ<28>")
	)
	(segment
		(start 136.071864 -264.311384)
		(end 136.171686 -264.411206)
		(width 0.088646)
		(layer "F.Cu")
		(net "M_E_CPU1_SA_DQ<28>")
	)
	(segment
		(start 137.876026 -264.414254)
		(end 137.876026 -264.203434)
		(width 0.088646)
		(layer "F.Cu")
		(net "M_E_CPU1_SA_DQ<28>")
	)
	(segment
		(start 154.96286 -283.267404)
		(end 155.334462 -282.895802)
		(width 0.20066)
		(layer "F.Cu")
		(net "M_E_CPU1_SA_DQ<28>")
	)
	(segment
		(start 136.071864 -264.13968)
		(end 136.071864 -264.311384)
		(width 0.088646)
		(layer "F.Cu")
		(net "M_E_CPU1_SA_DQ<28>")
	)
	(segment
		(start 156.911548 -282.204414)
		(end 157.231842 -282.204414)
		(width 0.20066)
		(layer "F.Cu")
		(net "M_E_CPU1_SA_DQ<28>")
	)
	(segment
		(start 163.923726 -281.872436)
		(end 163.904422 -281.89174)
		(width 0.1016)
		(layer "F.Cu")
		(net "M_E_CPU1_SA_DQ<28>")
	)
	(segment
		(start 138.75639 -264.278618)
		(end 139.030456 -264.11809)
		(width 0.088646)
		(layer "F.Cu")
		(net "M_E_CPU1_SA_DQ<28>")
	)
	(segment
		(start 136.843516 -264.288778)
		(end 136.894316 -264.25906)
		(width 0.088646)
		(layer "F.Cu")
		(net "M_E_CPU1_SA_DQ<28>")
	)
	(segment
		(start 161.891726 -281.882342)
		(end 161.581846 -281.882342)
		(width 0.20066)
		(layer "F.Cu")
		(net "M_E_CPU1_SA_DQ<28>")
	)
	(segment
		(start 161.90595 -281.89174)
		(end 161.896552 -281.882342)
		(width 0.1016)
		(layer "F.Cu")
		(net "M_E_CPU1_SA_DQ<28>")
	)
	(segment
		(start 136.148064 -264.06348)
		(end 136.071864 -264.13968)
		(width 0.088646)
		(layer "F.Cu")
		(net "M_E_CPU1_SA_DQ<28>")
	)
	(segment
		(start 139.444222 -264.11809)
		(end 139.932918 -264.606786)
		(width 0.088646)
		(layer "F.Cu")
		(net "M_E_CPU1_SA_DQ<28>")
	)
	(segment
		(start 156.051504 -281.88666)
		(end 156.180536 -281.757628)
		(width 0.20066)
		(layer "F.Cu")
		(net "M_E_CPU1_SA_DQ<28>")
	)
	(segment
		(start 137.684002 -264.49401)
		(end 137.79627 -264.49401)
		(width 0.088646)
		(layer "F.Cu")
		(net "M_E_CPU1_SA_DQ<28>")
	)
	(segment
		(start 136.171686 -264.411206)
		(end 136.386062 -264.411206)
		(width 0.088646)
		(layer "F.Cu")
		(net "M_E_CPU1_SA_DQ<28>")
	)
	(segment
		(start 152.995376 -283.067506)
		(end 153.196036 -283.268166)
		(width 0.20066)
		(layer "F.Cu")
		(net "M_E_CPU1_SA_DQ<28>")
	)
	(segment
		(start 166.357046 -282.316682)
		(end 164.774626 -282.316682)
		(width 0.20066)
		(layer "F.Cu")
		(net "M_E_CPU1_SA_DQ<28>")
	)
	(segment
		(start 137.19048 -264.08888)
		(end 137.349738 -264.248138)
		(width 0.088646)
		(layer "F.Cu")
		(net "M_E_CPU1_SA_DQ<28>")
	)
	(segment
		(start 154.383232 -282.89758)
		(end 154.383232 -283.066744)
		(width 0.20066)
		(layer "F.Cu")
		(net "M_E_CPU1_SA_DQ<28>")
	)
	(segment
		(start 138.32078 -264.334244)
		(end 138.551412 -264.334244)
		(width 0.088646)
		(layer "F.Cu")
		(net "M_E_CPU1_SA_DQ<28>")
	)
	(segment
		(start 157.231842 -282.204414)
		(end 157.34411 -282.316682)
		(width 0.20066)
		(layer "F.Cu")
		(net "M_E_CPU1_SA_DQ<28>")
	)
	(segment
		(start 152.995376 -282.891992)
		(end 152.995376 -283.067506)
		(width 0.20066)
		(layer "F.Cu")
		(net "M_E_CPU1_SA_DQ<28>")
	)
	(segment
		(start 154.383232 -283.066744)
		(end 154.583892 -283.267404)
		(width 0.20066)
		(layer "F.Cu")
		(net "M_E_CPU1_SA_DQ<28>")
	)
	(segment
		(start 161.371788 -282.0924)
		(end 161.371788 -282.42387)
		(width 0.20066)
		(layer "F.Cu")
		(net "M_E_CPU1_SA_DQ<28>")
	)
	(segment
		(start 136.894316 -264.25906)
		(end 137.064496 -264.08888)
		(width 0.088646)
		(layer "F.Cu")
		(net "M_E_CPU1_SA_DQ<28>")
	)
	(segment
		(start 152.505664 -282.691078)
		(end 152.794462 -282.691078)
		(width 0.20066)
		(layer "F.Cu")
		(net "M_E_CPU1_SA_DQ<28>")
	)
	(segment
		(start 138.100816 -264.11428)
		(end 138.32078 -264.334244)
		(width 0.088646)
		(layer "F.Cu")
		(net "M_E_CPU1_SA_DQ<28>")
	)
	(segment
		(start 137.79627 -264.49401)
		(end 137.876026 -264.414254)
		(width 0.088646)
		(layer "F.Cu")
		(net "M_E_CPU1_SA_DQ<28>")
	)
	(segment
		(start 153.681176 -283.067506)
		(end 153.681176 -282.891738)
		(width 0.20066)
		(layer "F.Cu")
		(net "M_E_CPU1_SA_DQ<28>")
	)
	(segment
		(start 149.447504 -279.715722)
		(end 149.90699 -280.092404)
		(width 0.1016)
		(layer "F.Cu")
		(net "M_E_CPU1_SA_DQ<28>")
	)
	(segment
		(start 154.583892 -283.267404)
		(end 154.96286 -283.267404)
		(width 0.20066)
		(layer "F.Cu")
		(net "M_E_CPU1_SA_DQ<28>")
	)
	(segment
		(start 155.905454 -282.238958)
		(end 156.051504 -281.88666)
		(width 0.20066)
		(layer "F.Cu")
		(net "M_E_CPU1_SA_DQ<28>")
	)
	(segment
		(start 153.681176 -282.891738)
		(end 153.881836 -282.691078)
		(width 0.20066)
		(layer "F.Cu")
		(net "M_E_CPU1_SA_DQ<28>")
	)
	(segment
		(start 163.904422 -281.89174)
		(end 161.90595 -281.89174)
		(width 0.1016)
		(layer "F.Cu")
		(net "M_E_CPU1_SA_DQ<28>")
	)
	(arc
		(start 136.386062 -264.411206)
		(mid 136.622835 -264.380064)
		(end 136.843516 -264.288778)
		(width 0.088646)
		(layer "F.Cu")
		(net "M_E_CPU1_SA_DQ<28>")
	)
	(arc
		(start 138.551412 -264.334244)
		(mid 138.657606 -264.320088)
		(end 138.75639 -264.278618)
		(width 0.088646)
		(layer "F.Cu")
		(net "M_E_CPU1_SA_DQ<28>")
	)
	(segment
		(start 164.947346 -286.149034)
		(end 164.515038 -285.716726)
		(width 0.20066)
		(layer "F.Cu")
		(net "M_E_CPU1_SA_DQ<27>")
	)
	(segment
		(start 168.883584 -285.464758)
		(end 168.499536 -285.464758)
		(width 0.20066)
		(layer "F.Cu")
		(net "M_E_CPU1_SA_DQ<27>")
	)
	(segment
		(start 152.621742 -285.968694)
		(end 157.048454 -285.968694)
		(width 0.20066)
		(layer "F.Cu")
		(net "M_E_CPU1_SA_DQ<27>")
	)
	(segment
		(start 167.356028 -286.141668)
		(end 166.558214 -286.141668)
		(width 0.101854)
		(layer "F.Cu")
		(net "M_E_CPU1_SA_DQ<27>")
	)
	(segment
		(start 148.395944 -282.302966)
		(end 148.7297 -282.804362)
		(width 0.1016)
		(layer "F.Cu")
		(net "M_E_CPU1_SA_DQ<27>")
	)
	(segment
		(start 161.220912 -285.592266)
		(end 161.345372 -285.716726)
		(width 0.20066)
		(layer "F.Cu")
		(net "M_E_CPU1_SA_DQ<27>")
	)
	(segment
		(start 168.265348 -285.970472)
		(end 168.082722 -286.153098)
		(width 0.20066)
		(layer "F.Cu")
		(net "M_E_CPU1_SA_DQ<27>")
	)
	(segment
		(start 168.499536 -285.464758)
		(end 168.265348 -285.698946)
		(width 0.20066)
		(layer "F.Cu")
		(net "M_E_CPU1_SA_DQ<27>")
	)
	(segment
		(start 149.113494 -283.188156)
		(end 151.379428 -285.45409)
		(width 0.20066)
		(layer "F.Cu")
		(net "M_E_CPU1_SA_DQ<27>")
	)
	(segment
		(start 165.36035 -286.141668)
		(end 165.352984 -286.149034)
		(width 0.1016)
		(layer "F.Cu")
		(net "M_E_CPU1_SA_DQ<27>")
	)
	(segment
		(start 140.486892 -267.354304)
		(end 146.635216 -273.502628)
		(width 0.1016)
		(layer "F.Cu")
		(net "M_E_CPU1_SA_DQ<27>")
	)
	(segment
		(start 168.082722 -286.153098)
		(end 167.367458 -286.153098)
		(width 0.20066)
		(layer "F.Cu")
		(net "M_E_CPU1_SA_DQ<27>")
	)
	(segment
		(start 148.7297 -282.804362)
		(end 149.113494 -283.188156)
		(width 0.1016)
		(layer "F.Cu")
		(net "M_E_CPU1_SA_DQ<27>")
	)
	(segment
		(start 168.265348 -285.698946)
		(end 168.265348 -285.970472)
		(width 0.20066)
		(layer "F.Cu")
		(net "M_E_CPU1_SA_DQ<27>")
	)
	(segment
		(start 159.823658 -286.159194)
		(end 160.127188 -286.159194)
		(width 0.20066)
		(layer "F.Cu")
		(net "M_E_CPU1_SA_DQ<27>")
	)
	(segment
		(start 160.127188 -286.159194)
		(end 160.257744 -286.28975)
		(width 0.20066)
		(layer "F.Cu")
		(net "M_E_CPU1_SA_DQ<27>")
	)
	(segment
		(start 160.742376 -286.08909)
		(end 160.742376 -285.78683)
		(width 0.20066)
		(layer "F.Cu")
		(net "M_E_CPU1_SA_DQ<27>")
	)
	(segment
		(start 160.541716 -286.28975)
		(end 160.742376 -286.08909)
		(width 0.20066)
		(layer "F.Cu")
		(net "M_E_CPU1_SA_DQ<27>")
	)
	(segment
		(start 151.379428 -285.45409)
		(end 152.621742 -285.968694)
		(width 0.20066)
		(layer "F.Cu")
		(net "M_E_CPU1_SA_DQ<27>")
	)
	(segment
		(start 160.93694 -285.592266)
		(end 161.220912 -285.592266)
		(width 0.20066)
		(layer "F.Cu")
		(net "M_E_CPU1_SA_DQ<27>")
	)
	(segment
		(start 146.635216 -273.502628)
		(end 148.395944 -282.302966)
		(width 0.1016)
		(layer "F.Cu")
		(net "M_E_CPU1_SA_DQ<27>")
	)
	(segment
		(start 170.457114 -285.716726)
		(end 169.135552 -285.716726)
		(width 0.20066)
		(layer "F.Cu")
		(net "M_E_CPU1_SA_DQ<27>")
	)
	(segment
		(start 167.367458 -286.153098)
		(end 167.356028 -286.141668)
		(width 0.101854)
		(layer "F.Cu")
		(net "M_E_CPU1_SA_DQ<27>")
	)
	(segment
		(start 169.135552 -285.716726)
		(end 168.883584 -285.464758)
		(width 0.20066)
		(layer "F.Cu")
		(net "M_E_CPU1_SA_DQ<27>")
	)
	(segment
		(start 165.352984 -286.149034)
		(end 165.335458 -286.149034)
		(width 0.101854)
		(layer "F.Cu")
		(net "M_E_CPU1_SA_DQ<27>")
	)
	(segment
		(start 159.806132 -286.141668)
		(end 159.823658 -286.159194)
		(width 0.1016)
		(layer "F.Cu")
		(net "M_E_CPU1_SA_DQ<27>")
	)
	(segment
		(start 157.796484 -286.175704)
		(end 157.83052 -286.141668)
		(width 0.1016)
		(layer "F.Cu")
		(net "M_E_CPU1_SA_DQ<27>")
	)
	(segment
		(start 166.558214 -286.141668)
		(end 165.36035 -286.141668)
		(width 0.1016)
		(layer "F.Cu")
		(net "M_E_CPU1_SA_DQ<27>")
	)
	(segment
		(start 157.791658 -286.175704)
		(end 157.796484 -286.175704)
		(width 0.101854)
		(layer "F.Cu")
		(net "M_E_CPU1_SA_DQ<27>")
	)
	(segment
		(start 165.335458 -286.149034)
		(end 164.947346 -286.149034)
		(width 0.20066)
		(layer "F.Cu")
		(net "M_E_CPU1_SA_DQ<27>")
	)
	(segment
		(start 138.534648 -265.592306)
		(end 138.859514 -265.726926)
		(width 0.088646)
		(layer "F.Cu")
		(net "M_E_CPU1_SA_DQ<27>")
	)
	(segment
		(start 160.742376 -285.78683)
		(end 160.93694 -285.592266)
		(width 0.20066)
		(layer "F.Cu")
		(net "M_E_CPU1_SA_DQ<27>")
	)
	(segment
		(start 157.255464 -286.175704)
		(end 157.791658 -286.175704)
		(width 0.20066)
		(layer "F.Cu")
		(net "M_E_CPU1_SA_DQ<27>")
	)
	(segment
		(start 164.515038 -285.716726)
		(end 162.913314 -285.716726)
		(width 0.20066)
		(layer "F.Cu")
		(net "M_E_CPU1_SA_DQ<27>")
	)
	(segment
		(start 138.859514 -265.726926)
		(end 140.486892 -267.354304)
		(width 0.088646)
		(layer "F.Cu")
		(net "M_E_CPU1_SA_DQ<27>")
	)
	(segment
		(start 161.345372 -285.716726)
		(end 162.913314 -285.716726)
		(width 0.20066)
		(layer "F.Cu")
		(net "M_E_CPU1_SA_DQ<27>")
	)
	(segment
		(start 157.048454 -285.968694)
		(end 157.255464 -286.175704)
		(width 0.20066)
		(layer "F.Cu")
		(net "M_E_CPU1_SA_DQ<27>")
	)
	(segment
		(start 160.257744 -286.28975)
		(end 160.541716 -286.28975)
		(width 0.20066)
		(layer "F.Cu")
		(net "M_E_CPU1_SA_DQ<27>")
	)
	(segment
		(start 157.83052 -286.141668)
		(end 159.806132 -286.141668)
		(width 0.1016)
		(layer "F.Cu")
		(net "M_E_CPU1_SA_DQ<27>")
	)
	(segment
		(start 157.796484 -287.867344)
		(end 157.822138 -287.84169)
		(width 0.1016)
		(layer "F.Cu")
		(net "M_E_CPU1_SA_DQ<26>")
	)
	(segment
		(start 138.313922 -266.453366)
		(end 138.988292 -266.718288)
		(width 0.088646)
		(layer "F.Cu")
		(net "M_E_CPU1_SA_DQ<26>")
	)
	(segment
		(start 157.822138 -287.84169)
		(end 159.810196 -287.84169)
		(width 0.1016)
		(layer "F.Cu")
		(net "M_E_CPU1_SA_DQ<26>")
	)
	(segment
		(start 151.814276 -287.725358)
		(end 157.398466 -287.725358)
		(width 0.20066)
		(layer "F.Cu")
		(net "M_E_CPU1_SA_DQ<26>")
	)
	(segment
		(start 167.367458 -287.85312)
		(end 167.356028 -287.84169)
		(width 0.101854)
		(layer "F.Cu")
		(net "M_E_CPU1_SA_DQ<26>")
	)
	(segment
		(start 138.988292 -266.718288)
		(end 139.7127 -267.442696)
		(width 0.088646)
		(layer "F.Cu")
		(net "M_E_CPU1_SA_DQ<26>")
	)
	(segment
		(start 166.558214 -287.84169)
		(end 165.36035 -287.84169)
		(width 0.1016)
		(layer "F.Cu")
		(net "M_E_CPU1_SA_DQ<26>")
	)
	(segment
		(start 139.7127 -267.442696)
		(end 146.07286 -273.802856)
		(width 0.1016)
		(layer "F.Cu")
		(net "M_E_CPU1_SA_DQ<26>")
	)
	(segment
		(start 138.064494 -266.405868)
		(end 138.313922 -266.453366)
		(width 0.088646)
		(layer "F.Cu")
		(net "M_E_CPU1_SA_DQ<26>")
	)
	(segment
		(start 165.352984 -287.849056)
		(end 165.335458 -287.849056)
		(width 0.101854)
		(layer "F.Cu")
		(net "M_E_CPU1_SA_DQ<26>")
	)
	(segment
		(start 168.265348 -287.687004)
		(end 168.099232 -287.85312)
		(width 0.20066)
		(layer "F.Cu")
		(net "M_E_CPU1_SA_DQ<26>")
	)
	(segment
		(start 160.787334 -287.416748)
		(end 162.913314 -287.416748)
		(width 0.20066)
		(layer "F.Cu")
		(net "M_E_CPU1_SA_DQ<26>")
	)
	(segment
		(start 157.791658 -287.867344)
		(end 157.796484 -287.867344)
		(width 0.101854)
		(layer "F.Cu")
		(net "M_E_CPU1_SA_DQ<26>")
	)
	(segment
		(start 170.457114 -287.416748)
		(end 169.135552 -287.416748)
		(width 0.20066)
		(layer "F.Cu")
		(net "M_E_CPU1_SA_DQ<26>")
	)
	(segment
		(start 147.668742 -281.780996)
		(end 147.668742 -282.360878)
		(width 0.1016)
		(layer "F.Cu")
		(net "M_E_CPU1_SA_DQ<26>")
	)
	(segment
		(start 164.723826 -287.416748)
		(end 162.913314 -287.416748)
		(width 0.20066)
		(layer "F.Cu")
		(net "M_E_CPU1_SA_DQ<26>")
	)
	(segment
		(start 168.099232 -287.85312)
		(end 167.367458 -287.85312)
		(width 0.20066)
		(layer "F.Cu")
		(net "M_E_CPU1_SA_DQ<26>")
	)
	(segment
		(start 148.195284 -284.106366)
		(end 151.814276 -287.725358)
		(width 0.20066)
		(layer "F.Cu")
		(net "M_E_CPU1_SA_DQ<26>")
	)
	(segment
		(start 165.36035 -287.84169)
		(end 165.352984 -287.849056)
		(width 0.1016)
		(layer "F.Cu")
		(net "M_E_CPU1_SA_DQ<26>")
	)
	(segment
		(start 160.130998 -287.855152)
		(end 160.787334 -287.416748)
		(width 0.20066)
		(layer "F.Cu")
		(net "M_E_CPU1_SA_DQ<26>")
	)
	(segment
		(start 168.883584 -287.16478)
		(end 168.499536 -287.16478)
		(width 0.20066)
		(layer "F.Cu")
		(net "M_E_CPU1_SA_DQ<26>")
	)
	(segment
		(start 165.335458 -287.849056)
		(end 165.156134 -287.849056)
		(width 0.20066)
		(layer "F.Cu")
		(net "M_E_CPU1_SA_DQ<26>")
	)
	(segment
		(start 169.135552 -287.416748)
		(end 168.883584 -287.16478)
		(width 0.20066)
		(layer "F.Cu")
		(net "M_E_CPU1_SA_DQ<26>")
	)
	(segment
		(start 147.96389 -283.874972)
		(end 148.195284 -284.106366)
		(width 0.1016)
		(layer "F.Cu")
		(net "M_E_CPU1_SA_DQ<26>")
	)
	(segment
		(start 168.265348 -287.398968)
		(end 168.265348 -287.687004)
		(width 0.20066)
		(layer "F.Cu")
		(net "M_E_CPU1_SA_DQ<26>")
	)
	(segment
		(start 165.156134 -287.849056)
		(end 164.723826 -287.416748)
		(width 0.20066)
		(layer "F.Cu")
		(net "M_E_CPU1_SA_DQ<26>")
	)
	(segment
		(start 147.668742 -282.360878)
		(end 147.96389 -283.874972)
		(width 0.1016)
		(layer "F.Cu")
		(net "M_E_CPU1_SA_DQ<26>")
	)
	(segment
		(start 157.398466 -287.725358)
		(end 157.540452 -287.867344)
		(width 0.20066)
		(layer "F.Cu")
		(net "M_E_CPU1_SA_DQ<26>")
	)
	(segment
		(start 168.499536 -287.16478)
		(end 168.265348 -287.398968)
		(width 0.20066)
		(layer "F.Cu")
		(net "M_E_CPU1_SA_DQ<26>")
	)
	(segment
		(start 159.823658 -287.855152)
		(end 160.130998 -287.855152)
		(width 0.20066)
		(layer "F.Cu")
		(net "M_E_CPU1_SA_DQ<26>")
	)
	(segment
		(start 167.356028 -287.84169)
		(end 166.558214 -287.84169)
		(width 0.101854)
		(layer "F.Cu")
		(net "M_E_CPU1_SA_DQ<26>")
	)
	(segment
		(start 146.07286 -273.802856)
		(end 147.668742 -281.780996)
		(width 0.1016)
		(layer "F.Cu")
		(net "M_E_CPU1_SA_DQ<26>")
	)
	(segment
		(start 159.810196 -287.84169)
		(end 159.823658 -287.855152)
		(width 0.1016)
		(layer "F.Cu")
		(net "M_E_CPU1_SA_DQ<26>")
	)
	(segment
		(start 157.540452 -287.867344)
		(end 157.791658 -287.867344)
		(width 0.20066)
		(layer "F.Cu")
		(net "M_E_CPU1_SA_DQ<26>")
	)
	(segment
		(start 152.079452 -287.085786)
		(end 152.894284 -287.085786)
		(width 0.20066)
		(layer "F.Cu")
		(net "M_E_CPU1_SA_DQ<25>")
	)
	(segment
		(start 161.891726 -286.130492)
		(end 161.446464 -286.130492)
		(width 0.20066)
		(layer "F.Cu")
		(net "M_E_CPU1_SA_DQ<25>")
	)
	(segment
		(start 137.926064 -265.817604)
		(end 138.274552 -265.817604)
		(width 0.088646)
		(layer "F.Cu")
		(net "M_E_CPU1_SA_DQ<25>")
	)
	(segment
		(start 161.082228 -286.790892)
		(end 159.95777 -286.790892)
		(width 0.20066)
		(layer "F.Cu")
		(net "M_E_CPU1_SA_DQ<25>")
	)
	(segment
		(start 158.009336 -286.841184)
		(end 158.28391 -286.56661)
		(width 0.20066)
		(layer "F.Cu")
		(net "M_E_CPU1_SA_DQ<25>")
	)
	(segment
		(start 151.331422 -286.310832)
		(end 151.668988 -286.310832)
		(width 0.20066)
		(layer "F.Cu")
		(net "M_E_CPU1_SA_DQ<25>")
	)
	(segment
		(start 151.869648 -286.511492)
		(end 151.869648 -286.875982)
		(width 0.20066)
		(layer "F.Cu")
		(net "M_E_CPU1_SA_DQ<25>")
	)
	(segment
		(start 136.549638 -265.849608)
		(end 136.549892 -265.91006)
		(width 0.088646)
		(layer "F.Cu")
		(net "M_E_CPU1_SA_DQ<25>")
	)
	(segment
		(start 155.587192 -287.085786)
		(end 155.961588 -287.085786)
		(width 0.20066)
		(layer "F.Cu")
		(net "M_E_CPU1_SA_DQ<25>")
	)
	(segment
		(start 139.928346 -267.22705)
		(end 146.353784 -273.652488)
		(width 0.1016)
		(layer "F.Cu")
		(net "M_E_CPU1_SA_DQ<25>")
	)
	(segment
		(start 147.973542 -282.207716)
		(end 148.42109 -283.4005)
		(width 0.1016)
		(layer "F.Cu")
		(net "M_E_CPU1_SA_DQ<25>")
	)
	(segment
		(start 156.387292 -286.660082)
		(end 156.671264 -286.660082)
		(width 0.20066)
		(layer "F.Cu")
		(net "M_E_CPU1_SA_DQ<25>")
	)
	(segment
		(start 158.28391 -286.56661)
		(end 158.813246 -286.56661)
		(width 0.20066)
		(layer "F.Cu")
		(net "M_E_CPU1_SA_DQ<25>")
	)
	(segment
		(start 151.668988 -286.310832)
		(end 151.869648 -286.511492)
		(width 0.20066)
		(layer "F.Cu")
		(net "M_E_CPU1_SA_DQ<25>")
	)
	(segment
		(start 157.347158 -287.052004)
		(end 157.557978 -286.841184)
		(width 0.20066)
		(layer "F.Cu")
		(net "M_E_CPU1_SA_DQ<25>")
	)
	(segment
		(start 161.896552 -286.130492)
		(end 161.891726 -286.130492)
		(width 0.101854)
		(layer "F.Cu")
		(net "M_E_CPU1_SA_DQ<25>")
	)
	(segment
		(start 164.68471 -286.56661)
		(end 164.24275 -286.12465)
		(width 0.20066)
		(layer "F.Cu")
		(net "M_E_CPU1_SA_DQ<25>")
	)
	(segment
		(start 138.274552 -265.817604)
		(end 138.455654 -265.998706)
		(width 0.088646)
		(layer "F.Cu")
		(net "M_E_CPU1_SA_DQ<25>")
	)
	(segment
		(start 152.894284 -287.085786)
		(end 153.36774 -286.61233)
		(width 0.20066)
		(layer "F.Cu")
		(net "M_E_CPU1_SA_DQ<25>")
	)
	(segment
		(start 146.353784 -273.652488)
		(end 147.973542 -281.746198)
		(width 0.1016)
		(layer "F.Cu")
		(net "M_E_CPU1_SA_DQ<25>")
	)
	(segment
		(start 157.557978 -286.841184)
		(end 158.009336 -286.841184)
		(width 0.20066)
		(layer "F.Cu")
		(net "M_E_CPU1_SA_DQ<25>")
	)
	(segment
		(start 164.24275 -286.12465)
		(end 163.923726 -286.12465)
		(width 0.20066)
		(layer "F.Cu")
		(net "M_E_CPU1_SA_DQ<25>")
	)
	(segment
		(start 148.66112 -283.64053)
		(end 151.331422 -286.310832)
		(width 0.20066)
		(layer "F.Cu")
		(net "M_E_CPU1_SA_DQ<25>")
	)
	(segment
		(start 166.357046 -286.56661)
		(end 164.68471 -286.56661)
		(width 0.20066)
		(layer "F.Cu")
		(net "M_E_CPU1_SA_DQ<25>")
	)
	(segment
		(start 161.245804 -286.331152)
		(end 161.245804 -286.627316)
		(width 0.20066)
		(layer "F.Cu")
		(net "M_E_CPU1_SA_DQ<25>")
	)
	(segment
		(start 159.95777 -286.790892)
		(end 159.733488 -286.56661)
		(width 0.20066)
		(layer "F.Cu")
		(net "M_E_CPU1_SA_DQ<25>")
	)
	(segment
		(start 157.063186 -287.052004)
		(end 157.347158 -287.052004)
		(width 0.20066)
		(layer "F.Cu")
		(net "M_E_CPU1_SA_DQ<25>")
	)
	(segment
		(start 155.961588 -287.085786)
		(end 156.387292 -286.660082)
		(width 0.20066)
		(layer "F.Cu")
		(net "M_E_CPU1_SA_DQ<25>")
	)
	(segment
		(start 159.733488 -286.56661)
		(end 158.813246 -286.56661)
		(width 0.20066)
		(layer "F.Cu")
		(net "M_E_CPU1_SA_DQ<25>")
	)
	(segment
		(start 161.446464 -286.130492)
		(end 161.245804 -286.331152)
		(width 0.20066)
		(layer "F.Cu")
		(net "M_E_CPU1_SA_DQ<25>")
	)
	(segment
		(start 138.455654 -265.998706)
		(end 138.700002 -265.998706)
		(width 0.088646)
		(layer "F.Cu")
		(net "M_E_CPU1_SA_DQ<25>")
	)
	(segment
		(start 136.655048 -265.592306)
		(end 136.549638 -265.849608)
		(width 0.088646)
		(layer "F.Cu")
		(net "M_E_CPU1_SA_DQ<25>")
	)
	(segment
		(start 153.65222 -286.61233)
		(end 154.104594 -287.064704)
		(width 0.20066)
		(layer "F.Cu")
		(net "M_E_CPU1_SA_DQ<25>")
	)
	(segment
		(start 155.12796 -286.626554)
		(end 155.587192 -287.085786)
		(width 0.20066)
		(layer "F.Cu")
		(net "M_E_CPU1_SA_DQ<25>")
	)
	(segment
		(start 137.744962 -265.998706)
		(end 137.926064 -265.817604)
		(width 0.088646)
		(layer "F.Cu")
		(net "M_E_CPU1_SA_DQ<25>")
	)
	(segment
		(start 161.245804 -286.627316)
		(end 161.082228 -286.790892)
		(width 0.20066)
		(layer "F.Cu")
		(net "M_E_CPU1_SA_DQ<25>")
	)
	(segment
		(start 136.638792 -265.998706)
		(end 137.744962 -265.998706)
		(width 0.088646)
		(layer "F.Cu")
		(net "M_E_CPU1_SA_DQ<25>")
	)
	(segment
		(start 154.388566 -287.064704)
		(end 154.826716 -286.626554)
		(width 0.20066)
		(layer "F.Cu")
		(net "M_E_CPU1_SA_DQ<25>")
	)
	(segment
		(start 161.907728 -286.141668)
		(end 161.896552 -286.130492)
		(width 0.1016)
		(layer "F.Cu")
		(net "M_E_CPU1_SA_DQ<25>")
	)
	(segment
		(start 156.671264 -286.660082)
		(end 157.063186 -287.052004)
		(width 0.20066)
		(layer "F.Cu")
		(net "M_E_CPU1_SA_DQ<25>")
	)
	(segment
		(start 163.906708 -286.141668)
		(end 161.907728 -286.141668)
		(width 0.1016)
		(layer "F.Cu")
		(net "M_E_CPU1_SA_DQ<25>")
	)
	(segment
		(start 147.973542 -281.746198)
		(end 147.973542 -282.207716)
		(width 0.1016)
		(layer "F.Cu")
		(net "M_E_CPU1_SA_DQ<25>")
	)
	(segment
		(start 136.549892 -265.91006)
		(end 136.638792 -265.998706)
		(width 0.088646)
		(layer "F.Cu")
		(net "M_E_CPU1_SA_DQ<25>")
	)
	(segment
		(start 163.923726 -286.12465)
		(end 163.906708 -286.141668)
		(width 0.1016)
		(layer "F.Cu")
		(net "M_E_CPU1_SA_DQ<25>")
	)
	(segment
		(start 153.36774 -286.61233)
		(end 153.65222 -286.61233)
		(width 0.20066)
		(layer "F.Cu")
		(net "M_E_CPU1_SA_DQ<25>")
	)
	(segment
		(start 154.826716 -286.626554)
		(end 155.12796 -286.626554)
		(width 0.20066)
		(layer "F.Cu")
		(net "M_E_CPU1_SA_DQ<25>")
	)
	(segment
		(start 138.700002 -265.998706)
		(end 139.928346 -267.22705)
		(width 0.088646)
		(layer "F.Cu")
		(net "M_E_CPU1_SA_DQ<25>")
	)
	(segment
		(start 154.104594 -287.064704)
		(end 154.388566 -287.064704)
		(width 0.20066)
		(layer "F.Cu")
		(net "M_E_CPU1_SA_DQ<25>")
	)
	(segment
		(start 148.42109 -283.4005)
		(end 148.66112 -283.64053)
		(width 0.1016)
		(layer "F.Cu")
		(net "M_E_CPU1_SA_DQ<25>")
	)
	(segment
		(start 151.869648 -286.875982)
		(end 152.079452 -287.085786)
		(width 0.20066)
		(layer "F.Cu")
		(net "M_E_CPU1_SA_DQ<25>")
	)
	(segment
		(start 158.217108 -288.266632)
		(end 158.813246 -288.266632)
		(width 0.20066)
		(layer "F.Cu")
		(net "M_E_CPU1_SA_DQ<24>")
	)
	(segment
		(start 164.722302 -288.050224)
		(end 164.521134 -287.849056)
		(width 0.20066)
		(layer "F.Cu")
		(net "M_E_CPU1_SA_DQ<24>")
	)
	(segment
		(start 166.357046 -288.266632)
		(end 165.43274 -288.266632)
		(width 0.20066)
		(layer "F.Cu")
		(net "M_E_CPU1_SA_DQ<24>")
	)
	(segment
		(start 138.832336 -266.912598)
		(end 139.15263 -267.232892)
		(width 0.088646)
		(layer "F.Cu")
		(net "M_E_CPU1_SA_DQ<24>")
	)
	(segment
		(start 137.081514 -266.362688)
		(end 136.712198 -266.362688)
		(width 0.088646)
		(layer "F.Cu")
		(net "M_E_CPU1_SA_DQ<24>")
	)
	(segment
		(start 157.82036 -288.66338)
		(end 158.217108 -288.266632)
		(width 0.20066)
		(layer "F.Cu")
		(net "M_E_CPU1_SA_DQ<24>")
	)
	(segment
		(start 161.900362 -287.84169)
		(end 161.891726 -287.833054)
		(width 0.101854)
		(layer "F.Cu")
		(net "M_E_CPU1_SA_DQ<24>")
	)
	(segment
		(start 139.15263 -267.313918)
		(end 139.497054 -267.658342)
		(width 0.088646)
		(layer "F.Cu")
		(net "M_E_CPU1_SA_DQ<24>")
	)
	(segment
		(start 157.242002 -288.369248)
		(end 157.536134 -288.66338)
		(width 0.20066)
		(layer "F.Cu")
		(net "M_E_CPU1_SA_DQ<24>")
	)
	(segment
		(start 163.923726 -287.849056)
		(end 163.91382 -287.849056)
		(width 0.101854)
		(layer "F.Cu")
		(net "M_E_CPU1_SA_DQ<24>")
	)
	(segment
		(start 147.352512 -284.168342)
		(end 147.74291 -284.55874)
		(width 0.1016)
		(layer "F.Cu")
		(net "M_E_CPU1_SA_DQ<24>")
	)
	(segment
		(start 137.124694 -266.405868)
		(end 137.081514 -266.362688)
		(width 0.088646)
		(layer "F.Cu")
		(net "M_E_CPU1_SA_DQ<24>")
	)
	(segment
		(start 163.91382 -287.849056)
		(end 163.906454 -287.84169)
		(width 0.1016)
		(layer "F.Cu")
		(net "M_E_CPU1_SA_DQ<24>")
	)
	(segment
		(start 139.15263 -267.232892)
		(end 139.15263 -267.313918)
		(width 0.088646)
		(layer "F.Cu")
		(net "M_E_CPU1_SA_DQ<24>")
	)
	(segment
		(start 136.62406 -266.450826)
		(end 136.62406 -266.628118)
		(width 0.088646)
		(layer "F.Cu")
		(net "M_E_CPU1_SA_DQ<24>")
	)
	(segment
		(start 138.396218 -266.798044)
		(end 138.832336 -266.912598)
		(width 0.088646)
		(layer "F.Cu")
		(net "M_E_CPU1_SA_DQ<24>")
	)
	(segment
		(start 159.73806 -288.266632)
		(end 158.813246 -288.266632)
		(width 0.20066)
		(layer "F.Cu")
		(net "M_E_CPU1_SA_DQ<24>")
	)
	(segment
		(start 164.826442 -288.485072)
		(end 164.722302 -288.380932)
		(width 0.20066)
		(layer "F.Cu")
		(net "M_E_CPU1_SA_DQ<24>")
	)
	(segment
		(start 147.352512 -281.755088)
		(end 147.352512 -284.168342)
		(width 0.1016)
		(layer "F.Cu")
		(net "M_E_CPU1_SA_DQ<24>")
	)
	(segment
		(start 162.712146 -287.84169)
		(end 161.900362 -287.84169)
		(width 0.101854)
		(layer "F.Cu")
		(net "M_E_CPU1_SA_DQ<24>")
	)
	(segment
		(start 165.43274 -288.266632)
		(end 165.2143 -288.485072)
		(width 0.20066)
		(layer "F.Cu")
		(net "M_E_CPU1_SA_DQ<24>")
	)
	(segment
		(start 136.712198 -266.362688)
		(end 136.62406 -266.450826)
		(width 0.088646)
		(layer "F.Cu")
		(net "M_E_CPU1_SA_DQ<24>")
	)
	(segment
		(start 136.793986 -266.798044)
		(end 138.396218 -266.798044)
		(width 0.088646)
		(layer "F.Cu")
		(net "M_E_CPU1_SA_DQ<24>")
	)
	(segment
		(start 157.536134 -288.66338)
		(end 157.82036 -288.66338)
		(width 0.20066)
		(layer "F.Cu")
		(net "M_E_CPU1_SA_DQ<24>")
	)
	(segment
		(start 147.74291 -284.55874)
		(end 151.553418 -288.369248)
		(width 0.20066)
		(layer "F.Cu")
		(net "M_E_CPU1_SA_DQ<24>")
	)
	(segment
		(start 139.497054 -267.658342)
		(end 145.791936 -273.953224)
		(width 0.1016)
		(layer "F.Cu")
		(net "M_E_CPU1_SA_DQ<24>")
	)
	(segment
		(start 161.190686 -287.833054)
		(end 160.438084 -288.585656)
		(width 0.20066)
		(layer "F.Cu")
		(net "M_E_CPU1_SA_DQ<24>")
	)
	(segment
		(start 165.2143 -288.485072)
		(end 164.826442 -288.485072)
		(width 0.20066)
		(layer "F.Cu")
		(net "M_E_CPU1_SA_DQ<24>")
	)
	(segment
		(start 164.521134 -287.849056)
		(end 163.923726 -287.849056)
		(width 0.20066)
		(layer "F.Cu")
		(net "M_E_CPU1_SA_DQ<24>")
	)
	(segment
		(start 160.057084 -288.585656)
		(end 159.73806 -288.266632)
		(width 0.20066)
		(layer "F.Cu")
		(net "M_E_CPU1_SA_DQ<24>")
	)
	(segment
		(start 163.906454 -287.84169)
		(end 162.712146 -287.84169)
		(width 0.1016)
		(layer "F.Cu")
		(net "M_E_CPU1_SA_DQ<24>")
	)
	(segment
		(start 151.553418 -288.369248)
		(end 157.242002 -288.369248)
		(width 0.20066)
		(layer "F.Cu")
		(net "M_E_CPU1_SA_DQ<24>")
	)
	(segment
		(start 164.722302 -288.380932)
		(end 164.722302 -288.050224)
		(width 0.20066)
		(layer "F.Cu")
		(net "M_E_CPU1_SA_DQ<24>")
	)
	(segment
		(start 136.62406 -266.628118)
		(end 136.793986 -266.798044)
		(width 0.088646)
		(layer "F.Cu")
		(net "M_E_CPU1_SA_DQ<24>")
	)
	(segment
		(start 161.891726 -287.833054)
		(end 161.190686 -287.833054)
		(width 0.20066)
		(layer "F.Cu")
		(net "M_E_CPU1_SA_DQ<24>")
	)
	(segment
		(start 145.791936 -273.953224)
		(end 147.352512 -281.755088)
		(width 0.1016)
		(layer "F.Cu")
		(net "M_E_CPU1_SA_DQ<24>")
	)
	(segment
		(start 160.438084 -288.585656)
		(end 160.057084 -288.585656)
		(width 0.20066)
		(layer "F.Cu")
		(net "M_E_CPU1_SA_DQ<24>")
	)
	(segment
		(start 168.265348 -289.09899)
		(end 168.265348 -289.358578)
		(width 0.20066)
		(layer "F.Cu")
		(net "M_E_CPU1_SA_DQ<23>")
	)
	(segment
		(start 164.612066 -289.11677)
		(end 162.913314 -289.11677)
		(width 0.20066)
		(layer "F.Cu")
		(net "M_E_CPU1_SA_DQ<23>")
	)
	(segment
		(start 154.14371 -290.627308)
		(end 154.34437 -290.426648)
		(width 0.20066)
		(layer "F.Cu")
		(net "M_E_CPU1_SA_DQ<23>")
	)
	(segment
		(start 153.46045 -289.255708)
		(end 153.66111 -289.456368)
		(width 0.20066)
		(layer "F.Cu")
		(net "M_E_CPU1_SA_DQ<23>")
	)
	(segment
		(start 157.833822 -289.541712)
		(end 159.795718 -289.541712)
		(width 0.1016)
		(layer "F.Cu")
		(net "M_E_CPU1_SA_DQ<23>")
	)
	(segment
		(start 138.298174 -268.130528)
		(end 138.780266 -268.130528)
		(width 0.088646)
		(layer "F.Cu")
		(net "M_E_CPU1_SA_DQ<23>")
	)
	(segment
		(start 147.153884 -285.223712)
		(end 151.18588 -289.255708)
		(width 0.20066)
		(layer "F.Cu")
		(net "M_E_CPU1_SA_DQ<23>")
	)
	(segment
		(start 146.44116 -284.510988)
		(end 147.153884 -285.223712)
		(width 0.1016)
		(layer "F.Cu")
		(net "M_E_CPU1_SA_DQ<23>")
	)
	(segment
		(start 168.265348 -289.358578)
		(end 168.070784 -289.553142)
		(width 0.20066)
		(layer "F.Cu")
		(net "M_E_CPU1_SA_DQ<23>")
	)
	(segment
		(start 165.352984 -289.549078)
		(end 165.335458 -289.549078)
		(width 0.101854)
		(layer "F.Cu")
		(net "M_E_CPU1_SA_DQ<23>")
	)
	(segment
		(start 161.064194 -288.86404)
		(end 161.231072 -288.697162)
		(width 0.20066)
		(layer "F.Cu")
		(net "M_E_CPU1_SA_DQ<23>")
	)
	(segment
		(start 151.314912 -290.142168)
		(end 151.314912 -290.426648)
		(width 0.20066)
		(layer "F.Cu")
		(net "M_E_CPU1_SA_DQ<23>")
	)
	(segment
		(start 151.314912 -290.426648)
		(end 151.515572 -290.627308)
		(width 0.20066)
		(layer "F.Cu")
		(net "M_E_CPU1_SA_DQ<23>")
	)
	(segment
		(start 151.515572 -290.627308)
		(end 154.14371 -290.627308)
		(width 0.20066)
		(layer "F.Cu")
		(net "M_E_CPU1_SA_DQ<23>")
	)
	(segment
		(start 165.335458 -289.549078)
		(end 165.044374 -289.549078)
		(width 0.20066)
		(layer "F.Cu")
		(net "M_E_CPU1_SA_DQ<23>")
	)
	(segment
		(start 168.499536 -288.864802)
		(end 168.265348 -289.09899)
		(width 0.20066)
		(layer "F.Cu")
		(net "M_E_CPU1_SA_DQ<23>")
	)
	(segment
		(start 145.28165 -274.286472)
		(end 146.44116 -280.083514)
		(width 0.1016)
		(layer "F.Cu")
		(net "M_E_CPU1_SA_DQ<23>")
	)
	(segment
		(start 170.457114 -289.11677)
		(end 169.135552 -289.11677)
		(width 0.20066)
		(layer "F.Cu")
		(net "M_E_CPU1_SA_DQ<23>")
	)
	(segment
		(start 168.883584 -288.864802)
		(end 168.499536 -288.864802)
		(width 0.20066)
		(layer "F.Cu")
		(net "M_E_CPU1_SA_DQ<23>")
	)
	(segment
		(start 166.558214 -289.541712)
		(end 165.36035 -289.541712)
		(width 0.1016)
		(layer "F.Cu")
		(net "M_E_CPU1_SA_DQ<23>")
	)
	(segment
		(start 165.36035 -289.541712)
		(end 165.352984 -289.549078)
		(width 0.1016)
		(layer "F.Cu")
		(net "M_E_CPU1_SA_DQ<23>")
	)
	(segment
		(start 151.18588 -289.255708)
		(end 153.46045 -289.255708)
		(width 0.20066)
		(layer "F.Cu")
		(net "M_E_CPU1_SA_DQ<23>")
	)
	(segment
		(start 138.064494 -268.033754)
		(end 138.298174 -268.130528)
		(width 0.088646)
		(layer "F.Cu")
		(net "M_E_CPU1_SA_DQ<23>")
	)
	(segment
		(start 157.42158 -289.57905)
		(end 157.791658 -289.57905)
		(width 0.20066)
		(layer "F.Cu")
		(net "M_E_CPU1_SA_DQ<23>")
	)
	(segment
		(start 153.46045 -289.941508)
		(end 151.515572 -289.941508)
		(width 0.20066)
		(layer "F.Cu")
		(net "M_E_CPU1_SA_DQ<23>")
	)
	(segment
		(start 157.796484 -289.57905)
		(end 157.833822 -289.541712)
		(width 0.1016)
		(layer "F.Cu")
		(net "M_E_CPU1_SA_DQ<23>")
	)
	(segment
		(start 139.035028 -268.001242)
		(end 140.912596 -269.878302)
		(width 0.088646)
		(layer "F.Cu")
		(net "M_E_CPU1_SA_DQ<23>")
	)
	(segment
		(start 161.064194 -289.272726)
		(end 161.064194 -288.86404)
		(width 0.20066)
		(layer "F.Cu")
		(net "M_E_CPU1_SA_DQ<23>")
	)
	(segment
		(start 138.780266 -268.130528)
		(end 138.909552 -268.001242)
		(width 0.088646)
		(layer "F.Cu")
		(net "M_E_CPU1_SA_DQ<23>")
	)
	(segment
		(start 162.396678 -289.11677)
		(end 162.913314 -289.11677)
		(width 0.20066)
		(layer "F.Cu")
		(net "M_E_CPU1_SA_DQ<23>")
	)
	(segment
		(start 154.34437 -290.426648)
		(end 154.34437 -289.45205)
		(width 0.20066)
		(layer "F.Cu")
		(net "M_E_CPU1_SA_DQ<23>")
	)
	(segment
		(start 160.963356 -289.373564)
		(end 161.064194 -289.272726)
		(width 0.20066)
		(layer "F.Cu")
		(net "M_E_CPU1_SA_DQ<23>")
	)
	(segment
		(start 169.135552 -289.11677)
		(end 168.883584 -288.864802)
		(width 0.20066)
		(layer "F.Cu")
		(net "M_E_CPU1_SA_DQ<23>")
	)
	(segment
		(start 168.070784 -289.553142)
		(end 167.367458 -289.553142)
		(width 0.20066)
		(layer "F.Cu")
		(net "M_E_CPU1_SA_DQ<23>")
	)
	(segment
		(start 165.044374 -289.549078)
		(end 164.612066 -289.11677)
		(width 0.20066)
		(layer "F.Cu")
		(net "M_E_CPU1_SA_DQ<23>")
	)
	(segment
		(start 159.795718 -289.541712)
		(end 159.823658 -289.569652)
		(width 0.1016)
		(layer "F.Cu")
		(net "M_E_CPU1_SA_DQ<23>")
	)
	(segment
		(start 161.97707 -288.697162)
		(end 162.396678 -289.11677)
		(width 0.20066)
		(layer "F.Cu")
		(net "M_E_CPU1_SA_DQ<23>")
	)
	(segment
		(start 138.909552 -268.001242)
		(end 139.035028 -268.001242)
		(width 0.088646)
		(layer "F.Cu")
		(net "M_E_CPU1_SA_DQ<23>")
	)
	(segment
		(start 153.66111 -289.740848)
		(end 153.46045 -289.941508)
		(width 0.20066)
		(layer "F.Cu")
		(net "M_E_CPU1_SA_DQ<23>")
	)
	(segment
		(start 167.367458 -289.553142)
		(end 167.356028 -289.541712)
		(width 0.101854)
		(layer "F.Cu")
		(net "M_E_CPU1_SA_DQ<23>")
	)
	(segment
		(start 157.098238 -289.255708)
		(end 157.42158 -289.57905)
		(width 0.20066)
		(layer "F.Cu")
		(net "M_E_CPU1_SA_DQ<23>")
	)
	(segment
		(start 154.34437 -289.45205)
		(end 154.540712 -289.255708)
		(width 0.20066)
		(layer "F.Cu")
		(net "M_E_CPU1_SA_DQ<23>")
	)
	(segment
		(start 141.018514 -270.023336)
		(end 145.28165 -274.286472)
		(width 0.1016)
		(layer "F.Cu")
		(net "M_E_CPU1_SA_DQ<23>")
	)
	(segment
		(start 157.791658 -289.57905)
		(end 157.796484 -289.57905)
		(width 0.101854)
		(layer "F.Cu")
		(net "M_E_CPU1_SA_DQ<23>")
	)
	(segment
		(start 161.231072 -288.697162)
		(end 161.97707 -288.697162)
		(width 0.20066)
		(layer "F.Cu")
		(net "M_E_CPU1_SA_DQ<23>")
	)
	(segment
		(start 159.823658 -289.569652)
		(end 160.118552 -289.569652)
		(width 0.20066)
		(layer "F.Cu")
		(net "M_E_CPU1_SA_DQ<23>")
	)
	(segment
		(start 140.912596 -269.878302)
		(end 140.912596 -269.917418)
		(width 0.088646)
		(layer "F.Cu")
		(net "M_E_CPU1_SA_DQ<23>")
	)
	(segment
		(start 153.66111 -289.456368)
		(end 153.66111 -289.740848)
		(width 0.20066)
		(layer "F.Cu")
		(net "M_E_CPU1_SA_DQ<23>")
	)
	(segment
		(start 167.356028 -289.541712)
		(end 166.558214 -289.541712)
		(width 0.101854)
		(layer "F.Cu")
		(net "M_E_CPU1_SA_DQ<23>")
	)
	(segment
		(start 160.31464 -289.373564)
		(end 160.963356 -289.373564)
		(width 0.20066)
		(layer "F.Cu")
		(net "M_E_CPU1_SA_DQ<23>")
	)
	(segment
		(start 160.118552 -289.569652)
		(end 160.31464 -289.373564)
		(width 0.20066)
		(layer "F.Cu")
		(net "M_E_CPU1_SA_DQ<23>")
	)
	(segment
		(start 154.540712 -289.255708)
		(end 157.098238 -289.255708)
		(width 0.20066)
		(layer "F.Cu")
		(net "M_E_CPU1_SA_DQ<23>")
	)
	(segment
		(start 140.912596 -269.917418)
		(end 141.018514 -270.023336)
		(width 0.088646)
		(layer "F.Cu")
		(net "M_E_CPU1_SA_DQ<23>")
	)
	(segment
		(start 151.515572 -289.941508)
		(end 151.314912 -290.142168)
		(width 0.20066)
		(layer "F.Cu")
		(net "M_E_CPU1_SA_DQ<23>")
	)
	(segment
		(start 146.44116 -280.083514)
		(end 146.44116 -284.510988)
		(width 0.1016)
		(layer "F.Cu")
		(net "M_E_CPU1_SA_DQ<23>")
	)
	(segment
		(start 157.80893 -291.241734)
		(end 157.986984 -291.241734)
		(width 0.101854)
		(layer "F.Cu")
		(net "M_E_CPU1_SA_DQ<22>")
	)
	(segment
		(start 166.558214 -291.241734)
		(end 165.36035 -291.241734)
		(width 0.1016)
		(layer "F.Cu")
		(net "M_E_CPU1_SA_DQ<22>")
	)
	(segment
		(start 170.457114 -290.816792)
		(end 169.135552 -290.816792)
		(width 0.20066)
		(layer "F.Cu")
		(net "M_E_CPU1_SA_DQ<22>")
	)
	(segment
		(start 140.501116 -270.368776)
		(end 140.790168 -270.657828)
		(width 0.088646)
		(layer "F.Cu")
		(net "M_E_CPU1_SA_DQ<22>")
	)
	(segment
		(start 161.849054 -290.458144)
		(end 162.133026 -290.458144)
		(width 0.20066)
		(layer "F.Cu")
		(net "M_E_CPU1_SA_DQ<22>")
	)
	(segment
		(start 157.791658 -291.259006)
		(end 157.80893 -291.241734)
		(width 0.101854)
		(layer "F.Cu")
		(net "M_E_CPU1_SA_DQ<22>")
	)
	(segment
		(start 140.790168 -270.657828)
		(end 144.719294 -274.586954)
		(width 0.1016)
		(layer "F.Cu")
		(net "M_E_CPU1_SA_DQ<22>")
	)
	(segment
		(start 144.719294 -274.586954)
		(end 145.83156 -280.148538)
		(width 0.1016)
		(layer "F.Cu")
		(net "M_E_CPU1_SA_DQ<22>")
	)
	(segment
		(start 162.491674 -290.816792)
		(end 162.913314 -290.816792)
		(width 0.20066)
		(layer "F.Cu")
		(net "M_E_CPU1_SA_DQ<22>")
	)
	(segment
		(start 155.420314 -291.1602)
		(end 155.666948 -290.913566)
		(width 0.20066)
		(layer "F.Cu")
		(net "M_E_CPU1_SA_DQ<22>")
	)
	(segment
		(start 145.83156 -286.43199)
		(end 145.865088 -286.465518)
		(width 0.1016)
		(layer "F.Cu")
		(net "M_E_CPU1_SA_DQ<22>")
	)
	(segment
		(start 136.773412 -268.588236)
		(end 136.902952 -268.553946)
		(width 0.088646)
		(layer "F.Cu")
		(net "M_E_CPU1_SA_DQ<22>")
	)
	(segment
		(start 145.865088 -286.465518)
		(end 145.865088 -287.338262)
		(width 0.1016)
		(layer "F.Cu")
		(net "M_E_CPU1_SA_DQ<22>")
	)
	(segment
		(start 155.144724 -292.447726)
		(end 155.420314 -292.172136)
		(width 0.20066)
		(layer "F.Cu")
		(net "M_E_CPU1_SA_DQ<22>")
	)
	(segment
		(start 168.499536 -290.564824)
		(end 168.265348 -290.799012)
		(width 0.20066)
		(layer "F.Cu")
		(net "M_E_CPU1_SA_DQ<22>")
	)
	(segment
		(start 161.079434 -290.517072)
		(end 161.079434 -290.689792)
		(width 0.20066)
		(layer "F.Cu")
		(net "M_E_CPU1_SA_DQ<22>")
	)
	(segment
		(start 150.706328 -292.179502)
		(end 151.091646 -292.179502)
		(width 0.20066)
		(layer "F.Cu")
		(net "M_E_CPU1_SA_DQ<22>")
	)
	(segment
		(start 157.986984 -291.241734)
		(end 159.803592 -291.241734)
		(width 0.1016)
		(layer "F.Cu")
		(net "M_E_CPU1_SA_DQ<22>")
	)
	(segment
		(start 167.367458 -291.253164)
		(end 167.356028 -291.241734)
		(width 0.101854)
		(layer "F.Cu")
		(net "M_E_CPU1_SA_DQ<22>")
	)
	(segment
		(start 162.133026 -290.458144)
		(end 162.491674 -290.816792)
		(width 0.20066)
		(layer "F.Cu")
		(net "M_E_CPU1_SA_DQ<22>")
	)
	(segment
		(start 168.265348 -290.799012)
		(end 168.265348 -291.052504)
		(width 0.20066)
		(layer "F.Cu")
		(net "M_E_CPU1_SA_DQ<22>")
	)
	(segment
		(start 154.445208 -292.032436)
		(end 154.860498 -292.447726)
		(width 0.20066)
		(layer "F.Cu")
		(net "M_E_CPU1_SA_DQ<22>")
	)
	(segment
		(start 161.490406 -290.816792)
		(end 161.849054 -290.458144)
		(width 0.20066)
		(layer "F.Cu")
		(net "M_E_CPU1_SA_DQ<22>")
	)
	(segment
		(start 137.781792 -268.523212)
		(end 137.841736 -268.557756)
		(width 0.088646)
		(layer "F.Cu")
		(net "M_E_CPU1_SA_DQ<22>")
	)
	(segment
		(start 159.803592 -291.241734)
		(end 159.823658 -291.2618)
		(width 0.1016)
		(layer "F.Cu")
		(net "M_E_CPU1_SA_DQ<22>")
	)
	(segment
		(start 160.946084 -290.383722)
		(end 161.079434 -290.517072)
		(width 0.20066)
		(layer "F.Cu")
		(net "M_E_CPU1_SA_DQ<22>")
	)
	(segment
		(start 154.860498 -292.447726)
		(end 155.144724 -292.447726)
		(width 0.20066)
		(layer "F.Cu")
		(net "M_E_CPU1_SA_DQ<22>")
	)
	(segment
		(start 157.505908 -291.259006)
		(end 157.791658 -291.259006)
		(width 0.20066)
		(layer "F.Cu")
		(net "M_E_CPU1_SA_DQ<22>")
	)
	(segment
		(start 161.079434 -290.689792)
		(end 161.206434 -290.816792)
		(width 0.20066)
		(layer "F.Cu")
		(net "M_E_CPU1_SA_DQ<22>")
	)
	(segment
		(start 169.135552 -290.816792)
		(end 168.883584 -290.564824)
		(width 0.20066)
		(layer "F.Cu")
		(net "M_E_CPU1_SA_DQ<22>")
	)
	(segment
		(start 151.091646 -292.179502)
		(end 151.238712 -292.032436)
		(width 0.20066)
		(layer "F.Cu")
		(net "M_E_CPU1_SA_DQ<22>")
	)
	(segment
		(start 160.151318 -291.2618)
		(end 160.38703 -291.026088)
		(width 0.20066)
		(layer "F.Cu")
		(net "M_E_CPU1_SA_DQ<22>")
	)
	(segment
		(start 136.655048 -268.84757)
		(end 136.645142 -268.81074)
		(width 0.088646)
		(layer "F.Cu")
		(net "M_E_CPU1_SA_DQ<22>")
	)
	(segment
		(start 167.356028 -291.241734)
		(end 166.558214 -291.241734)
		(width 0.101854)
		(layer "F.Cu")
		(net "M_E_CPU1_SA_DQ<22>")
	)
	(segment
		(start 163.449762 -290.816792)
		(end 162.913314 -290.816792)
		(width 0.20066)
		(layer "F.Cu")
		(net "M_E_CPU1_SA_DQ<22>")
	)
	(segment
		(start 136.645142 -268.81074)
		(end 136.773412 -268.588236)
		(width 0.088646)
		(layer "F.Cu")
		(net "M_E_CPU1_SA_DQ<22>")
	)
	(segment
		(start 165.36035 -291.241734)
		(end 165.352984 -291.2491)
		(width 0.1016)
		(layer "F.Cu")
		(net "M_E_CPU1_SA_DQ<22>")
	)
	(segment
		(start 164.902134 -291.2491)
		(end 164.237924 -290.58489)
		(width 0.20066)
		(layer "F.Cu")
		(net "M_E_CPU1_SA_DQ<22>")
	)
	(segment
		(start 165.335458 -291.2491)
		(end 164.902134 -291.2491)
		(width 0.20066)
		(layer "F.Cu")
		(net "M_E_CPU1_SA_DQ<22>")
	)
	(segment
		(start 155.666948 -290.913566)
		(end 155.666948 -290.739068)
		(width 0.20066)
		(layer "F.Cu")
		(net "M_E_CPU1_SA_DQ<22>")
	)
	(segment
		(start 156.534358 -290.538408)
		(end 156.96946 -290.97351)
		(width 0.20066)
		(layer "F.Cu")
		(net "M_E_CPU1_SA_DQ<22>")
	)
	(segment
		(start 160.552384 -290.383722)
		(end 160.946084 -290.383722)
		(width 0.20066)
		(layer "F.Cu")
		(net "M_E_CPU1_SA_DQ<22>")
	)
	(segment
		(start 165.352984 -291.2491)
		(end 165.335458 -291.2491)
		(width 0.101854)
		(layer "F.Cu")
		(net "M_E_CPU1_SA_DQ<22>")
	)
	(segment
		(start 155.867608 -290.538408)
		(end 156.534358 -290.538408)
		(width 0.20066)
		(layer "F.Cu")
		(net "M_E_CPU1_SA_DQ<22>")
	)
	(segment
		(start 164.237924 -290.58489)
		(end 163.681664 -290.58489)
		(width 0.20066)
		(layer "F.Cu")
		(net "M_E_CPU1_SA_DQ<22>")
	)
	(segment
		(start 168.883584 -290.564824)
		(end 168.499536 -290.564824)
		(width 0.20066)
		(layer "F.Cu")
		(net "M_E_CPU1_SA_DQ<22>")
	)
	(segment
		(start 155.420314 -292.172136)
		(end 155.420314 -291.1602)
		(width 0.20066)
		(layer "F.Cu")
		(net "M_E_CPU1_SA_DQ<22>")
	)
	(segment
		(start 157.220412 -290.97351)
		(end 157.505908 -291.259006)
		(width 0.20066)
		(layer "F.Cu")
		(net "M_E_CPU1_SA_DQ<22>")
	)
	(segment
		(start 159.823658 -291.2618)
		(end 160.151318 -291.2618)
		(width 0.20066)
		(layer "F.Cu")
		(net "M_E_CPU1_SA_DQ<22>")
	)
	(segment
		(start 160.38703 -290.549076)
		(end 160.552384 -290.383722)
		(width 0.20066)
		(layer "F.Cu")
		(net "M_E_CPU1_SA_DQ<22>")
	)
	(segment
		(start 145.980658 -287.453832)
		(end 150.706328 -292.179502)
		(width 0.20066)
		(layer "F.Cu")
		(net "M_E_CPU1_SA_DQ<22>")
	)
	(segment
		(start 161.206434 -290.816792)
		(end 161.490406 -290.816792)
		(width 0.20066)
		(layer "F.Cu")
		(net "M_E_CPU1_SA_DQ<22>")
	)
	(segment
		(start 145.83156 -280.148538)
		(end 145.83156 -286.43199)
		(width 0.1016)
		(layer "F.Cu")
		(net "M_E_CPU1_SA_DQ<22>")
	)
	(segment
		(start 138.19251 -268.61389)
		(end 138.440922 -268.51102)
		(width 0.088646)
		(layer "F.Cu")
		(net "M_E_CPU1_SA_DQ<22>")
	)
	(segment
		(start 155.666948 -290.739068)
		(end 155.867608 -290.538408)
		(width 0.20066)
		(layer "F.Cu")
		(net "M_E_CPU1_SA_DQ<22>")
	)
	(segment
		(start 138.440922 -268.51102)
		(end 139.006072 -268.51102)
		(width 0.088646)
		(layer "F.Cu")
		(net "M_E_CPU1_SA_DQ<22>")
	)
	(segment
		(start 168.265348 -291.052504)
		(end 168.064688 -291.253164)
		(width 0.20066)
		(layer "F.Cu")
		(net "M_E_CPU1_SA_DQ<22>")
	)
	(segment
		(start 168.064688 -291.253164)
		(end 167.367458 -291.253164)
		(width 0.20066)
		(layer "F.Cu")
		(net "M_E_CPU1_SA_DQ<22>")
	)
	(segment
		(start 145.865088 -287.338262)
		(end 145.980658 -287.453832)
		(width 0.1016)
		(layer "F.Cu")
		(net "M_E_CPU1_SA_DQ<22>")
	)
	(segment
		(start 151.238712 -292.032436)
		(end 154.445208 -292.032436)
		(width 0.20066)
		(layer "F.Cu")
		(net "M_E_CPU1_SA_DQ<22>")
	)
	(segment
		(start 160.38703 -291.026088)
		(end 160.38703 -290.549076)
		(width 0.20066)
		(layer "F.Cu")
		(net "M_E_CPU1_SA_DQ<22>")
	)
	(segment
		(start 138.051286 -268.61389)
		(end 138.19251 -268.61389)
		(width 0.088646)
		(layer "F.Cu")
		(net "M_E_CPU1_SA_DQ<22>")
	)
	(segment
		(start 140.501116 -270.006064)
		(end 140.501116 -270.368776)
		(width 0.088646)
		(layer "F.Cu")
		(net "M_E_CPU1_SA_DQ<22>")
	)
	(segment
		(start 163.681664 -290.58489)
		(end 163.449762 -290.816792)
		(width 0.20066)
		(layer "F.Cu")
		(net "M_E_CPU1_SA_DQ<22>")
	)
	(segment
		(start 156.96946 -290.97351)
		(end 157.220412 -290.97351)
		(width 0.20066)
		(layer "F.Cu")
		(net "M_E_CPU1_SA_DQ<22>")
	)
	(segment
		(start 139.006072 -268.51102)
		(end 140.501116 -270.006064)
		(width 0.088646)
		(layer "F.Cu")
		(net "M_E_CPU1_SA_DQ<22>")
	)
	(arc
		(start 137.841736 -268.557756)
		(mid 137.942815 -268.599623)
		(end 138.051286 -268.61389)
		(width 0.088646)
		(layer "F.Cu")
		(net "M_E_CPU1_SA_DQ<22>")
	)
	(arc
		(start 136.902952 -268.553946)
		(mid 137.158802 -268.598111)
		(end 137.407396 -268.523212)
		(width 0.088646)
		(layer "F.Cu")
		(net "M_E_CPU1_SA_DQ<22>")
	)
	(arc
		(start 137.407396 -268.523212)
		(mid 137.594594 -268.473069)
		(end 137.781792 -268.523212)
		(width 0.088646)
		(layer "F.Cu")
		(net "M_E_CPU1_SA_DQ<22>")
	)
	(segment
		(start 154.983942 -290.691824)
		(end 154.983942 -290.103306)
		(width 0.20066)
		(layer "F.Cu")
		(net "M_E_CPU1_SA_DQ<21>")
	)
	(segment
		(start 154.983942 -290.103306)
		(end 155.191968 -289.89528)
		(width 0.20066)
		(layer "F.Cu")
		(net "M_E_CPU1_SA_DQ<21>")
	)
	(segment
		(start 146.620484 -287.15462)
		(end 146.904456 -287.15462)
		(width 0.20066)
		(layer "F.Cu")
		(net "M_E_CPU1_SA_DQ<21>")
	)
	(segment
		(start 157.195774 -290.248594)
		(end 157.962346 -290.248594)
		(width 0.20066)
		(layer "F.Cu")
		(net "M_E_CPU1_SA_DQ<21>")
	)
	(segment
		(start 137.079736 -268.045692)
		(end 136.957308 -268.258036)
		(width 0.088646)
		(layer "F.Cu")
		(net "M_E_CPU1_SA_DQ<21>")
	)
	(segment
		(start 159.577024 -290.244276)
		(end 159.299402 -289.966654)
		(width 0.20066)
		(layer "F.Cu")
		(net "M_E_CPU1_SA_DQ<21>")
	)
	(segment
		(start 156.84246 -289.89528)
		(end 157.195774 -290.248594)
		(width 0.20066)
		(layer "F.Cu")
		(net "M_E_CPU1_SA_DQ<21>")
	)
	(segment
		(start 146.902932 -285.901638)
		(end 146.902932 -286.185864)
		(width 0.20066)
		(layer "F.Cu")
		(net "M_E_CPU1_SA_DQ<21>")
	)
	(segment
		(start 146.689572 -285.688278)
		(end 146.902932 -285.901638)
		(width 0.20066)
		(layer "F.Cu")
		(net "M_E_CPU1_SA_DQ<21>")
	)
	(segment
		(start 146.13636 -285.135066)
		(end 146.689572 -285.688278)
		(width 0.1016)
		(layer "F.Cu")
		(net "M_E_CPU1_SA_DQ<21>")
	)
	(segment
		(start 149.82571 -288.800794)
		(end 149.82571 -289.084766)
		(width 0.20066)
		(layer "F.Cu")
		(net "M_E_CPU1_SA_DQ<21>")
	)
	(segment
		(start 161.924492 -289.541712)
		(end 161.917888 -289.535108)
		(width 0.101854)
		(layer "F.Cu")
		(net "M_E_CPU1_SA_DQ<21>")
	)
	(segment
		(start 147.88515 -287.144206)
		(end 147.389596 -287.63976)
		(width 0.20066)
		(layer "F.Cu")
		(net "M_E_CPU1_SA_DQ<21>")
	)
	(segment
		(start 149.624542 -288.599626)
		(end 149.82571 -288.800794)
		(width 0.20066)
		(layer "F.Cu")
		(net "M_E_CPU1_SA_DQ<21>")
	)
	(segment
		(start 159.944562 -290.244276)
		(end 159.577024 -290.244276)
		(width 0.20066)
		(layer "F.Cu")
		(net "M_E_CPU1_SA_DQ<21>")
	)
	(segment
		(start 149.34057 -288.599626)
		(end 149.624542 -288.599626)
		(width 0.20066)
		(layer "F.Cu")
		(net "M_E_CPU1_SA_DQ<21>")
	)
	(segment
		(start 136.957308 -268.258036)
		(end 136.991344 -268.383512)
		(width 0.088646)
		(layer "F.Cu")
		(net "M_E_CPU1_SA_DQ<21>")
	)
	(segment
		(start 148.359876 -288.894012)
		(end 148.561044 -289.09518)
		(width 0.20066)
		(layer "F.Cu")
		(net "M_E_CPU1_SA_DQ<21>")
	)
	(segment
		(start 150.300436 -290.834572)
		(end 150.850092 -291.384228)
		(width 0.20066)
		(layer "F.Cu")
		(net "M_E_CPU1_SA_DQ<21>")
	)
	(segment
		(start 147.683982 -286.659066)
		(end 147.88515 -286.860234)
		(width 0.20066)
		(layer "F.Cu")
		(net "M_E_CPU1_SA_DQ<21>")
	)
	(segment
		(start 138.292078 -268.336522)
		(end 138.307826 -268.320774)
		(width 0.088646)
		(layer "F.Cu")
		(net "M_E_CPU1_SA_DQ<21>")
	)
	(segment
		(start 149.330156 -289.58032)
		(end 149.330156 -289.864292)
		(width 0.20066)
		(layer "F.Cu")
		(net "M_E_CPU1_SA_DQ<21>")
	)
	(segment
		(start 150.850092 -291.384228)
		(end 154.291538 -291.384228)
		(width 0.20066)
		(layer "F.Cu")
		(net "M_E_CPU1_SA_DQ<21>")
	)
	(segment
		(start 161.373058 -289.839654)
		(end 161.246058 -289.966654)
		(width 0.20066)
		(layer "F.Cu")
		(net "M_E_CPU1_SA_DQ<21>")
	)
	(segment
		(start 165.317424 -290.094924)
		(end 164.914072 -290.094924)
		(width 0.20066)
		(layer "F.Cu")
		(net "M_E_CPU1_SA_DQ<21>")
	)
	(segment
		(start 149.330156 -289.864292)
		(end 149.531324 -290.06546)
		(width 0.20066)
		(layer "F.Cu")
		(net "M_E_CPU1_SA_DQ<21>")
	)
	(segment
		(start 148.85543 -287.830514)
		(end 148.85543 -288.114486)
		(width 0.20066)
		(layer "F.Cu")
		(net "M_E_CPU1_SA_DQ<21>")
	)
	(segment
		(start 150.1902 -289.690556)
		(end 150.474172 -289.690556)
		(width 0.20066)
		(layer "F.Cu")
		(net "M_E_CPU1_SA_DQ<21>")
	)
	(segment
		(start 161.506662 -289.535108)
		(end 161.373058 -289.668712)
		(width 0.20066)
		(layer "F.Cu")
		(net "M_E_CPU1_SA_DQ<21>")
	)
	(segment
		(start 158.244286 -289.966654)
		(end 158.813246 -289.966654)
		(width 0.20066)
		(layer "F.Cu")
		(net "M_E_CPU1_SA_DQ<21>")
	)
	(segment
		(start 140.706856 -270.143224)
		(end 140.802614 -270.238982)
		(width 0.088646)
		(layer "F.Cu")
		(net "M_E_CPU1_SA_DQ<21>")
	)
	(segment
		(start 147.389596 -287.63976)
		(end 147.389596 -287.923732)
		(width 0.20066)
		(layer "F.Cu")
		(net "M_E_CPU1_SA_DQ<21>")
	)
	(segment
		(start 140.802614 -270.238982)
		(end 145.000472 -274.43684)
		(width 0.1016)
		(layer "F.Cu")
		(net "M_E_CPU1_SA_DQ<21>")
	)
	(segment
		(start 146.904456 -287.15462)
		(end 147.40001 -286.659066)
		(width 0.20066)
		(layer "F.Cu")
		(net "M_E_CPU1_SA_DQ<21>")
	)
	(segment
		(start 149.815296 -290.06546)
		(end 150.1902 -289.690556)
		(width 0.20066)
		(layer "F.Cu")
		(net "M_E_CPU1_SA_DQ<21>")
	)
	(segment
		(start 148.85543 -288.114486)
		(end 148.359876 -288.61004)
		(width 0.20066)
		(layer "F.Cu")
		(net "M_E_CPU1_SA_DQ<21>")
	)
	(segment
		(start 155.191968 -289.89528)
		(end 156.84246 -289.89528)
		(width 0.20066)
		(layer "F.Cu")
		(net "M_E_CPU1_SA_DQ<21>")
	)
	(segment
		(start 161.917888 -289.535108)
		(end 161.891726 -289.535108)
		(width 0.101854)
		(layer "F.Cu")
		(net "M_E_CPU1_SA_DQ<21>")
	)
	(segment
		(start 162.712146 -289.541712)
		(end 161.924492 -289.541712)
		(width 0.101854)
		(layer "F.Cu")
		(net "M_E_CPU1_SA_DQ<21>")
	)
	(segment
		(start 163.914836 -289.541712)
		(end 162.712146 -289.541712)
		(width 0.1016)
		(layer "F.Cu")
		(net "M_E_CPU1_SA_DQ<21>")
	)
	(segment
		(start 163.923726 -289.532822)
		(end 163.914836 -289.541712)
		(width 0.101854)
		(layer "F.Cu")
		(net "M_E_CPU1_SA_DQ<21>")
	)
	(segment
		(start 149.531324 -290.06546)
		(end 149.815296 -290.06546)
		(width 0.20066)
		(layer "F.Cu")
		(net "M_E_CPU1_SA_DQ<21>")
	)
	(segment
		(start 163.92398 -289.532568)
		(end 163.923726 -289.532822)
		(width 0.20066)
		(layer "F.Cu")
		(net "M_E_CPU1_SA_DQ<21>")
	)
	(segment
		(start 161.246058 -289.966654)
		(end 160.222184 -289.966654)
		(width 0.20066)
		(layer "F.Cu")
		(net "M_E_CPU1_SA_DQ<21>")
	)
	(segment
		(start 150.67534 -290.175696)
		(end 150.300436 -290.5506)
		(width 0.20066)
		(layer "F.Cu")
		(net "M_E_CPU1_SA_DQ<21>")
	)
	(segment
		(start 150.300436 -290.5506)
		(end 150.300436 -290.834572)
		(width 0.20066)
		(layer "F.Cu")
		(net "M_E_CPU1_SA_DQ<21>")
	)
	(segment
		(start 159.299402 -289.966654)
		(end 158.813246 -289.966654)
		(width 0.20066)
		(layer "F.Cu")
		(net "M_E_CPU1_SA_DQ<21>")
	)
	(segment
		(start 166.357046 -289.966654)
		(end 165.445694 -289.966654)
		(width 0.20066)
		(layer "F.Cu")
		(net "M_E_CPU1_SA_DQ<21>")
	)
	(segment
		(start 147.874736 -288.1249)
		(end 148.37029 -287.629346)
		(width 0.20066)
		(layer "F.Cu")
		(net "M_E_CPU1_SA_DQ<21>")
	)
	(segment
		(start 148.845016 -289.09518)
		(end 149.34057 -288.599626)
		(width 0.20066)
		(layer "F.Cu")
		(net "M_E_CPU1_SA_DQ<21>")
	)
	(segment
		(start 147.389596 -287.923732)
		(end 147.590764 -288.1249)
		(width 0.20066)
		(layer "F.Cu")
		(net "M_E_CPU1_SA_DQ<21>")
	)
	(segment
		(start 138.307826 -268.320774)
		(end 139.08532 -268.320774)
		(width 0.088646)
		(layer "F.Cu")
		(net "M_E_CPU1_SA_DQ<21>")
	)
	(segment
		(start 147.88515 -286.860234)
		(end 147.88515 -287.144206)
		(width 0.20066)
		(layer "F.Cu")
		(net "M_E_CPU1_SA_DQ<21>")
	)
	(segment
		(start 148.37029 -287.629346)
		(end 148.654262 -287.629346)
		(width 0.20066)
		(layer "F.Cu")
		(net "M_E_CPU1_SA_DQ<21>")
	)
	(segment
		(start 148.359876 -288.61004)
		(end 148.359876 -288.894012)
		(width 0.20066)
		(layer "F.Cu")
		(net "M_E_CPU1_SA_DQ<21>")
	)
	(segment
		(start 147.590764 -288.1249)
		(end 147.874736 -288.1249)
		(width 0.20066)
		(layer "F.Cu")
		(net "M_E_CPU1_SA_DQ<21>")
	)
	(segment
		(start 146.13636 -280.114502)
		(end 146.13636 -285.135066)
		(width 0.1016)
		(layer "F.Cu")
		(net "M_E_CPU1_SA_DQ<21>")
	)
	(segment
		(start 157.962346 -290.248594)
		(end 158.244286 -289.966654)
		(width 0.20066)
		(layer "F.Cu")
		(net "M_E_CPU1_SA_DQ<21>")
	)
	(segment
		(start 137.124694 -268.033754)
		(end 137.079736 -268.045692)
		(width 0.088646)
		(layer "F.Cu")
		(net "M_E_CPU1_SA_DQ<21>")
	)
	(segment
		(start 164.351716 -289.532568)
		(end 163.92398 -289.532568)
		(width 0.20066)
		(layer "F.Cu")
		(net "M_E_CPU1_SA_DQ<21>")
	)
	(segment
		(start 161.891726 -289.535108)
		(end 161.506662 -289.535108)
		(width 0.20066)
		(layer "F.Cu")
		(net "M_E_CPU1_SA_DQ<21>")
	)
	(segment
		(start 149.82571 -289.084766)
		(end 149.330156 -289.58032)
		(width 0.20066)
		(layer "F.Cu")
		(net "M_E_CPU1_SA_DQ<21>")
	)
	(segment
		(start 139.08532 -268.320774)
		(end 140.673836 -269.90929)
		(width 0.088646)
		(layer "F.Cu")
		(net "M_E_CPU1_SA_DQ<21>")
	)
	(segment
		(start 148.561044 -289.09518)
		(end 148.845016 -289.09518)
		(width 0.20066)
		(layer "F.Cu")
		(net "M_E_CPU1_SA_DQ<21>")
	)
	(segment
		(start 146.419316 -286.953452)
		(end 146.620484 -287.15462)
		(width 0.20066)
		(layer "F.Cu")
		(net "M_E_CPU1_SA_DQ<21>")
	)
	(segment
		(start 150.67534 -289.891724)
		(end 150.67534 -290.175696)
		(width 0.20066)
		(layer "F.Cu")
		(net "M_E_CPU1_SA_DQ<21>")
	)
	(segment
		(start 164.914072 -290.094924)
		(end 164.351716 -289.532568)
		(width 0.20066)
		(layer "F.Cu")
		(net "M_E_CPU1_SA_DQ<21>")
	)
	(segment
		(start 148.654262 -287.629346)
		(end 148.85543 -287.830514)
		(width 0.20066)
		(layer "F.Cu")
		(net "M_E_CPU1_SA_DQ<21>")
	)
	(segment
		(start 161.373058 -289.668712)
		(end 161.373058 -289.839654)
		(width 0.20066)
		(layer "F.Cu")
		(net "M_E_CPU1_SA_DQ<21>")
	)
	(segment
		(start 147.40001 -286.659066)
		(end 147.683982 -286.659066)
		(width 0.20066)
		(layer "F.Cu")
		(net "M_E_CPU1_SA_DQ<21>")
	)
	(segment
		(start 146.902932 -286.185864)
		(end 146.419316 -286.66948)
		(width 0.20066)
		(layer "F.Cu")
		(net "M_E_CPU1_SA_DQ<21>")
	)
	(segment
		(start 154.291538 -291.384228)
		(end 154.983942 -290.691824)
		(width 0.20066)
		(layer "F.Cu")
		(net "M_E_CPU1_SA_DQ<21>")
	)
	(segment
		(start 140.706856 -269.988792)
		(end 140.706856 -270.143224)
		(width 0.088646)
		(layer "F.Cu")
		(net "M_E_CPU1_SA_DQ<21>")
	)
	(segment
		(start 140.673836 -269.90929)
		(end 140.706856 -269.988792)
		(width 0.088646)
		(layer "F.Cu")
		(net "M_E_CPU1_SA_DQ<21>")
	)
	(segment
		(start 165.445694 -289.966654)
		(end 165.317424 -290.094924)
		(width 0.20066)
		(layer "F.Cu")
		(net "M_E_CPU1_SA_DQ<21>")
	)
	(segment
		(start 160.222184 -289.966654)
		(end 159.944562 -290.244276)
		(width 0.20066)
		(layer "F.Cu")
		(net "M_E_CPU1_SA_DQ<21>")
	)
	(segment
		(start 146.419316 -286.66948)
		(end 146.419316 -286.953452)
		(width 0.20066)
		(layer "F.Cu")
		(net "M_E_CPU1_SA_DQ<21>")
	)
	(segment
		(start 150.474172 -289.690556)
		(end 150.67534 -289.891724)
		(width 0.20066)
		(layer "F.Cu")
		(net "M_E_CPU1_SA_DQ<21>")
	)
	(segment
		(start 145.000472 -274.43684)
		(end 146.13636 -280.114502)
		(width 0.1016)
		(layer "F.Cu")
		(net "M_E_CPU1_SA_DQ<21>")
	)
	(arc
		(start 136.991344 -268.383512)
		(mid 137.154489 -268.406994)
		(end 137.311892 -268.358112)
		(width 0.088646)
		(layer "F.Cu")
		(net "M_E_CPU1_SA_DQ<21>")
	)
	(arc
		(start 137.877296 -268.358112)
		(mid 138.087882 -268.408735)
		(end 138.292078 -268.336522)
		(width 0.088646)
		(layer "F.Cu")
		(net "M_E_CPU1_SA_DQ<21>")
	)
	(arc
		(start 137.311892 -268.358112)
		(mid 137.594594 -268.282336)
		(end 137.877296 -268.358112)
		(width 0.088646)
		(layer "F.Cu")
		(net "M_E_CPU1_SA_DQ<21>")
	)
	(segment
		(start 154.429714 -292.92169)
		(end 154.429714 -293.20617)
		(width 0.20066)
		(layer "F.Cu")
		(net "M_E_CPU1_SA_DQ<20>")
	)
	(segment
		(start 161.930588 -291.241734)
		(end 161.92246 -291.233606)
		(width 0.101854)
		(layer "F.Cu")
		(net "M_E_CPU1_SA_DQ<20>")
	)
	(segment
		(start 161.92246 -291.233606)
		(end 161.891726 -291.233606)
		(width 0.101854)
		(layer "F.Cu")
		(net "M_E_CPU1_SA_DQ<20>")
	)
	(segment
		(start 161.891726 -291.233606)
		(end 161.507424 -291.233606)
		(width 0.20066)
		(layer "F.Cu")
		(net "M_E_CPU1_SA_DQ<20>")
	)
	(segment
		(start 140.57376 -270.874236)
		(end 144.43837 -274.737322)
		(width 0.1016)
		(layer "F.Cu")
		(net "M_E_CPU1_SA_DQ<20>")
	)
	(segment
		(start 140.310616 -270.611092)
		(end 140.57376 -270.874236)
		(width 0.088646)
		(layer "F.Cu")
		(net "M_E_CPU1_SA_DQ<20>")
	)
	(segment
		(start 154.271472 -294.200326)
		(end 154.664918 -293.937436)
		(width 0.20066)
		(layer "F.Cu")
		(net "M_E_CPU1_SA_DQ<20>")
	)
	(segment
		(start 151.712676 -294.09263)
		(end 152.123648 -294.09263)
		(width 0.20066)
		(layer "F.Cu")
		(net "M_E_CPU1_SA_DQ<20>")
	)
	(segment
		(start 155.730702 -292.871652)
		(end 155.987242 -292.487858)
		(width 0.20066)
		(layer "F.Cu")
		(net "M_E_CPU1_SA_DQ<20>")
	)
	(segment
		(start 151.432006 -292.72103)
		(end 154.229054 -292.72103)
		(width 0.20066)
		(layer "F.Cu")
		(net "M_E_CPU1_SA_DQ<20>")
	)
	(segment
		(start 140.310616 -270.086074)
		(end 140.310616 -270.611092)
		(width 0.088646)
		(layer "F.Cu")
		(net "M_E_CPU1_SA_DQ<20>")
	)
	(segment
		(start 152.816814 -294.356028)
		(end 153.072846 -294.099996)
		(width 0.20066)
		(layer "F.Cu")
		(net "M_E_CPU1_SA_DQ<20>")
	)
	(segment
		(start 156.58592 -291.548566)
		(end 156.870654 -291.666676)
		(width 0.20066)
		(layer "F.Cu")
		(net "M_E_CPU1_SA_DQ<20>")
	)
	(segment
		(start 138.534648 -268.79677)
		(end 138.630152 -268.701266)
		(width 0.088646)
		(layer "F.Cu")
		(net "M_E_CPU1_SA_DQ<20>")
	)
	(segment
		(start 145.52676 -287.904428)
		(end 145.675858 -288.053526)
		(width 0.1016)
		(layer "F.Cu")
		(net "M_E_CPU1_SA_DQ<20>")
	)
	(segment
		(start 153.657046 -294.356028)
		(end 153.895044 -294.356028)
		(width 0.20066)
		(layer "F.Cu")
		(net "M_E_CPU1_SA_DQ<20>")
	)
	(segment
		(start 161.357056 -291.383974)
		(end 161.357056 -291.763958)
		(width 0.20066)
		(layer "F.Cu")
		(net "M_E_CPU1_SA_DQ<20>")
	)
	(segment
		(start 162.712146 -291.241734)
		(end 161.930588 -291.241734)
		(width 0.101854)
		(layer "F.Cu")
		(net "M_E_CPU1_SA_DQ<20>")
	)
	(segment
		(start 163.919662 -291.241734)
		(end 162.712146 -291.241734)
		(width 0.1016)
		(layer "F.Cu")
		(net "M_E_CPU1_SA_DQ<20>")
	)
	(segment
		(start 150.745698 -293.123366)
		(end 151.02967 -293.123366)
		(width 0.20066)
		(layer "F.Cu")
		(net "M_E_CPU1_SA_DQ<20>")
	)
	(segment
		(start 161.507424 -291.233606)
		(end 161.357056 -291.383974)
		(width 0.20066)
		(layer "F.Cu")
		(net "M_E_CPU1_SA_DQ<20>")
	)
	(segment
		(start 156.059886 -292.312344)
		(end 156.059886 -291.891212)
		(width 0.20066)
		(layer "F.Cu")
		(net "M_E_CPU1_SA_DQ<20>")
	)
	(segment
		(start 155.987242 -292.487858)
		(end 156.059886 -292.312344)
		(width 0.20066)
		(layer "F.Cu")
		(net "M_E_CPU1_SA_DQ<20>")
	)
	(segment
		(start 152.123648 -294.09263)
		(end 152.387046 -294.356028)
		(width 0.20066)
		(layer "F.Cu")
		(net "M_E_CPU1_SA_DQ<20>")
	)
	(segment
		(start 138.927078 -268.701266)
		(end 140.310616 -270.086074)
		(width 0.088646)
		(layer "F.Cu")
		(net "M_E_CPU1_SA_DQ<20>")
	)
	(segment
		(start 161.193988 -291.927026)
		(end 160.909762 -291.927026)
		(width 0.20066)
		(layer "F.Cu")
		(net "M_E_CPU1_SA_DQ<20>")
	)
	(segment
		(start 164.240464 -291.235638)
		(end 163.925758 -291.235638)
		(width 0.20066)
		(layer "F.Cu")
		(net "M_E_CPU1_SA_DQ<20>")
	)
	(segment
		(start 163.923726 -291.23767)
		(end 163.919662 -291.241734)
		(width 0.101854)
		(layer "F.Cu")
		(net "M_E_CPU1_SA_DQ<20>")
	)
	(segment
		(start 164.671502 -291.666676)
		(end 164.240464 -291.235638)
		(width 0.20066)
		(layer "F.Cu")
		(net "M_E_CPU1_SA_DQ<20>")
	)
	(segment
		(start 160.909762 -291.927026)
		(end 160.649412 -291.666676)
		(width 0.20066)
		(layer "F.Cu")
		(net "M_E_CPU1_SA_DQ<20>")
	)
	(segment
		(start 154.664918 -293.937436)
		(end 155.730702 -292.871652)
		(width 0.20066)
		(layer "F.Cu")
		(net "M_E_CPU1_SA_DQ<20>")
	)
	(segment
		(start 154.229054 -293.40683)
		(end 151.712676 -293.40683)
		(width 0.20066)
		(layer "F.Cu")
		(net "M_E_CPU1_SA_DQ<20>")
	)
	(segment
		(start 151.512016 -293.60749)
		(end 151.512016 -293.89197)
		(width 0.20066)
		(layer "F.Cu")
		(net "M_E_CPU1_SA_DQ<20>")
	)
	(segment
		(start 151.512016 -293.89197)
		(end 151.712676 -294.09263)
		(width 0.20066)
		(layer "F.Cu")
		(net "M_E_CPU1_SA_DQ<20>")
	)
	(segment
		(start 153.072846 -294.099996)
		(end 153.401014 -294.099996)
		(width 0.20066)
		(layer "F.Cu")
		(net "M_E_CPU1_SA_DQ<20>")
	)
	(segment
		(start 154.229054 -292.72103)
		(end 154.429714 -292.92169)
		(width 0.20066)
		(layer "F.Cu")
		(net "M_E_CPU1_SA_DQ<20>")
	)
	(segment
		(start 145.675858 -288.053526)
		(end 150.745698 -293.123366)
		(width 0.20066)
		(layer "F.Cu")
		(net "M_E_CPU1_SA_DQ<20>")
	)
	(segment
		(start 151.712676 -293.40683)
		(end 151.512016 -293.60749)
		(width 0.20066)
		(layer "F.Cu")
		(net "M_E_CPU1_SA_DQ<20>")
	)
	(segment
		(start 154.429714 -293.20617)
		(end 154.229054 -293.40683)
		(width 0.20066)
		(layer "F.Cu")
		(net "M_E_CPU1_SA_DQ<20>")
	)
	(segment
		(start 152.387046 -294.356028)
		(end 152.816814 -294.356028)
		(width 0.20066)
		(layer "F.Cu")
		(net "M_E_CPU1_SA_DQ<20>")
	)
	(segment
		(start 144.43837 -274.737322)
		(end 145.52676 -280.183844)
		(width 0.1016)
		(layer "F.Cu")
		(net "M_E_CPU1_SA_DQ<20>")
	)
	(segment
		(start 138.630152 -268.701266)
		(end 138.927078 -268.701266)
		(width 0.088646)
		(layer "F.Cu")
		(net "M_E_CPU1_SA_DQ<20>")
	)
	(segment
		(start 153.895044 -294.356028)
		(end 154.271472 -294.200326)
		(width 0.20066)
		(layer "F.Cu")
		(net "M_E_CPU1_SA_DQ<20>")
	)
	(segment
		(start 163.925758 -291.235638)
		(end 163.923726 -291.23767)
		(width 0.20066)
		(layer "F.Cu")
		(net "M_E_CPU1_SA_DQ<20>")
	)
	(segment
		(start 156.059886 -291.891212)
		(end 156.402532 -291.548566)
		(width 0.20066)
		(layer "F.Cu")
		(net "M_E_CPU1_SA_DQ<20>")
	)
	(segment
		(start 138.534648 -268.84757)
		(end 138.534648 -268.79677)
		(width 0.088646)
		(layer "F.Cu")
		(net "M_E_CPU1_SA_DQ<20>")
	)
	(segment
		(start 156.870654 -291.666676)
		(end 158.813246 -291.666676)
		(width 0.20066)
		(layer "F.Cu")
		(net "M_E_CPU1_SA_DQ<20>")
	)
	(segment
		(start 153.401014 -294.099996)
		(end 153.657046 -294.356028)
		(width 0.20066)
		(layer "F.Cu")
		(net "M_E_CPU1_SA_DQ<20>")
	)
	(segment
		(start 160.649412 -291.666676)
		(end 158.813246 -291.666676)
		(width 0.20066)
		(layer "F.Cu")
		(net "M_E_CPU1_SA_DQ<20>")
	)
	(segment
		(start 166.357046 -291.666676)
		(end 164.671502 -291.666676)
		(width 0.20066)
		(layer "F.Cu")
		(net "M_E_CPU1_SA_DQ<20>")
	)
	(segment
		(start 156.402532 -291.548566)
		(end 156.58592 -291.548566)
		(width 0.20066)
		(layer "F.Cu")
		(net "M_E_CPU1_SA_DQ<20>")
	)
	(segment
		(start 151.02967 -293.123366)
		(end 151.432006 -292.72103)
		(width 0.20066)
		(layer "F.Cu")
		(net "M_E_CPU1_SA_DQ<20>")
	)
	(segment
		(start 161.357056 -291.763958)
		(end 161.193988 -291.927026)
		(width 0.20066)
		(layer "F.Cu")
		(net "M_E_CPU1_SA_DQ<20>")
	)
	(segment
		(start 145.52676 -280.183844)
		(end 145.52676 -287.904428)
		(width 0.1016)
		(layer "F.Cu")
		(net "M_E_CPU1_SA_DQ<20>")
	)
	(segment
		(start 157.188408 -314.961016)
		(end 157.287468 -315.002164)
		(width 0.20066)
		(layer "F.Cu")
		(net "M_E_CPU1_SA_DQ<1>")
	)
	(segment
		(start 142.391384 -300.779942)
		(end 142.391384 -301.109634)
		(width 0.20066)
		(layer "F.Cu")
		(net "M_E_CPU1_SA_DQ<1>")
	)
	(segment
		(start 138.552174 -279.028398)
		(end 138.735562 -279.028398)
		(width 0.088646)
		(layer "F.Cu")
		(net "M_E_CPU1_SA_DQ<1>")
	)
	(segment
		(start 153.71445 -312.103008)
		(end 154.034744 -312.423302)
		(width 0.20066)
		(layer "F.Cu")
		(net "M_E_CPU1_SA_DQ<1>")
	)
	(segment
		(start 160.020508 -314.95238)
		(end 159.68472 -314.616592)
		(width 0.20066)
		(layer "F.Cu")
		(net "M_E_CPU1_SA_DQ<1>")
	)
	(segment
		(start 152.094184 -310.482742)
		(end 152.094184 -310.731662)
		(width 0.20066)
		(layer "F.Cu")
		(net "M_E_CPU1_SA_DQ<1>")
	)
	(segment
		(start 141.421104 -299.809662)
		(end 141.421104 -300.139354)
		(width 0.20066)
		(layer "F.Cu")
		(net "M_E_CPU1_SA_DQ<1>")
	)
	(segment
		(start 150.153624 -308.871874)
		(end 150.473918 -309.192168)
		(width 0.20066)
		(layer "F.Cu")
		(net "M_E_CPU1_SA_DQ<1>")
	)
	(segment
		(start 138.735562 -279.028398)
		(end 139.075668 -279.169368)
		(width 0.088646)
		(layer "F.Cu")
		(net "M_E_CPU1_SA_DQ<1>")
	)
	(segment
		(start 148.213064 -306.601622)
		(end 148.213064 -306.931314)
		(width 0.20066)
		(layer "F.Cu")
		(net "M_E_CPU1_SA_DQ<1>")
	)
	(segment
		(start 161.896552 -314.18276)
		(end 161.891726 -314.18276)
		(width 0.101854)
		(layer "F.Cu")
		(net "M_E_CPU1_SA_DQ<1>")
	)
	(segment
		(start 142.711678 -301.429928)
		(end 143.04137 -301.429928)
		(width 0.20066)
		(layer "F.Cu")
		(net "M_E_CPU1_SA_DQ<1>")
	)
	(segment
		(start 143.04137 -301.429928)
		(end 143.361664 -301.750222)
		(width 0.20066)
		(layer "F.Cu")
		(net "M_E_CPU1_SA_DQ<1>")
	)
	(segment
		(start 147.563078 -306.281328)
		(end 147.89277 -306.281328)
		(width 0.20066)
		(layer "F.Cu")
		(net "M_E_CPU1_SA_DQ<1>")
	)
	(segment
		(start 151.77389 -310.162448)
		(end 152.094184 -310.482742)
		(width 0.20066)
		(layer "F.Cu")
		(net "M_E_CPU1_SA_DQ<1>")
	)
	(segment
		(start 148.86305 -307.251608)
		(end 149.183344 -307.571902)
		(width 0.20066)
		(layer "F.Cu")
		(net "M_E_CPU1_SA_DQ<1>")
	)
	(segment
		(start 144.98193 -303.370488)
		(end 145.302224 -303.690782)
		(width 0.20066)
		(layer "F.Cu")
		(net "M_E_CPU1_SA_DQ<1>")
	)
	(segment
		(start 140.124434 -296.848022)
		(end 140.124434 -297.327828)
		(width 0.1016)
		(layer "F.Cu")
		(net "M_E_CPU1_SA_DQ<1>")
	)
	(segment
		(start 164.64407 -314.616592)
		(end 164.209222 -314.181744)
		(width 0.20066)
		(layer "F.Cu")
		(net "M_E_CPU1_SA_DQ<1>")
	)
	(segment
		(start 145.622518 -304.340768)
		(end 145.95221 -304.340768)
		(width 0.20066)
		(layer "F.Cu")
		(net "M_E_CPU1_SA_DQ<1>")
	)
	(segment
		(start 146.272504 -304.661062)
		(end 146.272504 -304.990754)
		(width 0.20066)
		(layer "F.Cu")
		(net "M_E_CPU1_SA_DQ<1>")
	)
	(segment
		(start 139.736576 -280.642568)
		(end 139.736576 -281.063446)
		(width 0.088646)
		(layer "F.Cu")
		(net "M_E_CPU1_SA_DQ<1>")
	)
	(segment
		(start 150.473918 -309.192168)
		(end 150.80361 -309.192168)
		(width 0.20066)
		(layer "F.Cu")
		(net "M_E_CPU1_SA_DQ<1>")
	)
	(segment
		(start 144.01165 -302.400208)
		(end 144.331944 -302.720502)
		(width 0.20066)
		(layer "F.Cu")
		(net "M_E_CPU1_SA_DQ<1>")
	)
	(segment
		(start 157.59938 -315.002164)
		(end 157.984952 -314.616592)
		(width 0.20066)
		(layer "F.Cu")
		(net "M_E_CPU1_SA_DQ<1>")
	)
	(segment
		(start 151.123904 -309.805578)
		(end 151.480774 -310.162448)
		(width 0.20066)
		(layer "F.Cu")
		(net "M_E_CPU1_SA_DQ<1>")
	)
	(segment
		(start 139.736576 -296.460164)
		(end 140.124434 -296.848022)
		(width 0.1016)
		(layer "F.Cu")
		(net "M_E_CPU1_SA_DQ<1>")
	)
	(segment
		(start 149.183344 -307.571902)
		(end 149.183344 -307.901594)
		(width 0.20066)
		(layer "F.Cu")
		(net "M_E_CPU1_SA_DQ<1>")
	)
	(segment
		(start 146.592798 -305.311048)
		(end 146.92249 -305.311048)
		(width 0.20066)
		(layer "F.Cu")
		(net "M_E_CPU1_SA_DQ<1>")
	)
	(segment
		(start 154.41041 -313.073288)
		(end 154.68473 -313.073288)
		(width 0.20066)
		(layer "F.Cu")
		(net "M_E_CPU1_SA_DQ<1>")
	)
	(segment
		(start 151.480774 -310.162448)
		(end 151.77389 -310.162448)
		(width 0.20066)
		(layer "F.Cu")
		(net "M_E_CPU1_SA_DQ<1>")
	)
	(segment
		(start 161.04489 -314.95238)
		(end 160.020508 -314.95238)
		(width 0.20066)
		(layer "F.Cu")
		(net "M_E_CPU1_SA_DQ<1>")
	)
	(segment
		(start 148.213064 -306.931314)
		(end 148.533358 -307.251608)
		(width 0.20066)
		(layer "F.Cu")
		(net "M_E_CPU1_SA_DQ<1>")
	)
	(segment
		(start 139.075668 -279.169368)
		(end 139.344654 -279.438354)
		(width 0.088646)
		(layer "F.Cu")
		(net "M_E_CPU1_SA_DQ<1>")
	)
	(segment
		(start 152.094184 -310.731662)
		(end 152.49525 -311.132728)
		(width 0.20066)
		(layer "F.Cu")
		(net "M_E_CPU1_SA_DQ<1>")
	)
	(segment
		(start 157.287468 -315.002164)
		(end 157.59938 -315.002164)
		(width 0.20066)
		(layer "F.Cu")
		(net "M_E_CPU1_SA_DQ<1>")
	)
	(segment
		(start 143.361664 -301.750222)
		(end 143.361664 -302.079914)
		(width 0.20066)
		(layer "F.Cu")
		(net "M_E_CPU1_SA_DQ<1>")
	)
	(segment
		(start 143.361664 -302.079914)
		(end 143.681958 -302.400208)
		(width 0.20066)
		(layer "F.Cu")
		(net "M_E_CPU1_SA_DQ<1>")
	)
	(segment
		(start 141.741398 -300.459648)
		(end 142.07109 -300.459648)
		(width 0.20066)
		(layer "F.Cu")
		(net "M_E_CPU1_SA_DQ<1>")
	)
	(segment
		(start 157.984952 -314.616592)
		(end 158.813246 -314.616592)
		(width 0.20066)
		(layer "F.Cu")
		(net "M_E_CPU1_SA_DQ<1>")
	)
	(segment
		(start 154.034744 -312.697622)
		(end 154.41041 -313.073288)
		(width 0.20066)
		(layer "F.Cu")
		(net "M_E_CPU1_SA_DQ<1>")
	)
	(segment
		(start 139.637516 -280.144982)
		(end 139.736576 -280.642568)
		(width 0.088646)
		(layer "F.Cu")
		(net "M_E_CPU1_SA_DQ<1>")
	)
	(segment
		(start 153.064464 -311.453022)
		(end 153.064464 -311.690766)
		(width 0.20066)
		(layer "F.Cu")
		(net "M_E_CPU1_SA_DQ<1>")
	)
	(segment
		(start 140.124434 -298.512992)
		(end 141.421104 -299.809662)
		(width 0.20066)
		(layer "F.Cu")
		(net "M_E_CPU1_SA_DQ<1>")
	)
	(segment
		(start 138.355832 -278.947118)
		(end 138.552174 -279.028398)
		(width 0.088646)
		(layer "F.Cu")
		(net "M_E_CPU1_SA_DQ<1>")
	)
	(segment
		(start 153.064464 -311.690766)
		(end 153.476706 -312.103008)
		(width 0.20066)
		(layer "F.Cu")
		(net "M_E_CPU1_SA_DQ<1>")
	)
	(segment
		(start 143.681958 -302.400208)
		(end 144.01165 -302.400208)
		(width 0.20066)
		(layer "F.Cu")
		(net "M_E_CPU1_SA_DQ<1>")
	)
	(segment
		(start 166.357046 -314.616592)
		(end 164.64407 -314.616592)
		(width 0.20066)
		(layer "F.Cu")
		(net "M_E_CPU1_SA_DQ<1>")
	)
	(segment
		(start 147.242784 -305.631342)
		(end 147.242784 -305.961034)
		(width 0.20066)
		(layer "F.Cu")
		(net "M_E_CPU1_SA_DQ<1>")
	)
	(segment
		(start 149.503638 -308.221888)
		(end 149.83333 -308.221888)
		(width 0.20066)
		(layer "F.Cu")
		(net "M_E_CPU1_SA_DQ<1>")
	)
	(segment
		(start 144.331944 -303.050194)
		(end 144.652238 -303.370488)
		(width 0.20066)
		(layer "F.Cu")
		(net "M_E_CPU1_SA_DQ<1>")
	)
	(segment
		(start 151.123904 -309.512462)
		(end 151.123904 -309.805578)
		(width 0.20066)
		(layer "F.Cu")
		(net "M_E_CPU1_SA_DQ<1>")
	)
	(segment
		(start 161.446464 -314.18276)
		(end 161.245804 -314.38342)
		(width 0.20066)
		(layer "F.Cu")
		(net "M_E_CPU1_SA_DQ<1>")
	)
	(segment
		(start 144.331944 -302.720502)
		(end 144.331944 -303.050194)
		(width 0.20066)
		(layer "F.Cu")
		(net "M_E_CPU1_SA_DQ<1>")
	)
	(segment
		(start 138.34745 -278.938736)
		(end 138.355832 -278.947118)
		(width 0.088646)
		(layer "F.Cu")
		(net "M_E_CPU1_SA_DQ<1>")
	)
	(segment
		(start 142.07109 -300.459648)
		(end 142.391384 -300.779942)
		(width 0.20066)
		(layer "F.Cu")
		(net "M_E_CPU1_SA_DQ<1>")
	)
	(segment
		(start 147.89277 -306.281328)
		(end 148.213064 -306.601622)
		(width 0.20066)
		(layer "F.Cu")
		(net "M_E_CPU1_SA_DQ<1>")
	)
	(segment
		(start 147.242784 -305.961034)
		(end 147.563078 -306.281328)
		(width 0.20066)
		(layer "F.Cu")
		(net "M_E_CPU1_SA_DQ<1>")
	)
	(segment
		(start 146.92249 -305.311048)
		(end 147.242784 -305.631342)
		(width 0.20066)
		(layer "F.Cu")
		(net "M_E_CPU1_SA_DQ<1>")
	)
	(segment
		(start 152.49525 -311.132728)
		(end 152.74417 -311.132728)
		(width 0.20066)
		(layer "F.Cu")
		(net "M_E_CPU1_SA_DQ<1>")
	)
	(segment
		(start 145.302224 -304.020474)
		(end 145.622518 -304.340768)
		(width 0.20066)
		(layer "F.Cu")
		(net "M_E_CPU1_SA_DQ<1>")
	)
	(segment
		(start 139.736576 -281.063446)
		(end 139.736576 -296.460164)
		(width 0.1016)
		(layer "F.Cu")
		(net "M_E_CPU1_SA_DQ<1>")
	)
	(segment
		(start 140.124434 -297.327828)
		(end 140.124434 -298.512992)
		(width 0.20066)
		(layer "F.Cu")
		(net "M_E_CPU1_SA_DQ<1>")
	)
	(segment
		(start 145.302224 -303.690782)
		(end 145.302224 -304.020474)
		(width 0.20066)
		(layer "F.Cu")
		(net "M_E_CPU1_SA_DQ<1>")
	)
	(segment
		(start 144.652238 -303.370488)
		(end 144.98193 -303.370488)
		(width 0.20066)
		(layer "F.Cu")
		(net "M_E_CPU1_SA_DQ<1>")
	)
	(segment
		(start 150.80361 -309.192168)
		(end 151.123904 -309.512462)
		(width 0.20066)
		(layer "F.Cu")
		(net "M_E_CPU1_SA_DQ<1>")
	)
	(segment
		(start 154.68473 -313.073288)
		(end 155.779978 -314.168536)
		(width 0.20066)
		(layer "F.Cu")
		(net "M_E_CPU1_SA_DQ<1>")
	)
	(segment
		(start 161.245804 -314.751466)
		(end 161.04489 -314.95238)
		(width 0.20066)
		(layer "F.Cu")
		(net "M_E_CPU1_SA_DQ<1>")
	)
	(segment
		(start 148.533358 -307.251608)
		(end 148.86305 -307.251608)
		(width 0.20066)
		(layer "F.Cu")
		(net "M_E_CPU1_SA_DQ<1>")
	)
	(segment
		(start 145.95221 -304.340768)
		(end 146.272504 -304.661062)
		(width 0.20066)
		(layer "F.Cu")
		(net "M_E_CPU1_SA_DQ<1>")
	)
	(segment
		(start 142.391384 -301.109634)
		(end 142.711678 -301.429928)
		(width 0.20066)
		(layer "F.Cu")
		(net "M_E_CPU1_SA_DQ<1>")
	)
	(segment
		(start 159.68472 -314.616592)
		(end 158.813246 -314.616592)
		(width 0.20066)
		(layer "F.Cu")
		(net "M_E_CPU1_SA_DQ<1>")
	)
	(segment
		(start 155.779978 -314.168536)
		(end 156.6037 -314.718954)
		(width 0.20066)
		(layer "F.Cu")
		(net "M_E_CPU1_SA_DQ<1>")
	)
	(segment
		(start 137.781792 -278.938736)
		(end 137.792206 -278.93264)
		(width 0.088646)
		(layer "F.Cu")
		(net "M_E_CPU1_SA_DQ<1>")
	)
	(segment
		(start 137.124694 -277.800562)
		(end 137.220198 -278.031194)
		(width 0.088646)
		(layer "F.Cu")
		(net "M_E_CPU1_SA_DQ<1>")
	)
	(segment
		(start 161.245804 -314.38342)
		(end 161.245804 -314.751466)
		(width 0.20066)
		(layer "F.Cu")
		(net "M_E_CPU1_SA_DQ<1>")
	)
	(segment
		(start 141.421104 -300.139354)
		(end 141.741398 -300.459648)
		(width 0.20066)
		(layer "F.Cu")
		(net "M_E_CPU1_SA_DQ<1>")
	)
	(segment
		(start 146.272504 -304.990754)
		(end 146.592798 -305.311048)
		(width 0.20066)
		(layer "F.Cu")
		(net "M_E_CPU1_SA_DQ<1>")
	)
	(segment
		(start 152.74417 -311.132728)
		(end 153.064464 -311.453022)
		(width 0.20066)
		(layer "F.Cu")
		(net "M_E_CPU1_SA_DQ<1>")
	)
	(segment
		(start 154.034744 -312.423302)
		(end 154.034744 -312.697622)
		(width 0.20066)
		(layer "F.Cu")
		(net "M_E_CPU1_SA_DQ<1>")
	)
	(segment
		(start 161.905442 -314.19165)
		(end 161.896552 -314.18276)
		(width 0.1016)
		(layer "F.Cu")
		(net "M_E_CPU1_SA_DQ<1>")
	)
	(segment
		(start 139.344654 -279.438354)
		(end 139.637516 -280.144982)
		(width 0.088646)
		(layer "F.Cu")
		(net "M_E_CPU1_SA_DQ<1>")
	)
	(segment
		(start 156.6037 -314.718954)
		(end 157.188408 -314.961016)
		(width 0.20066)
		(layer "F.Cu")
		(net "M_E_CPU1_SA_DQ<1>")
	)
	(segment
		(start 161.891726 -314.18276)
		(end 161.446464 -314.18276)
		(width 0.20066)
		(layer "F.Cu")
		(net "M_E_CPU1_SA_DQ<1>")
	)
	(segment
		(start 163.923726 -314.181744)
		(end 163.91382 -314.19165)
		(width 0.1016)
		(layer "F.Cu")
		(net "M_E_CPU1_SA_DQ<1>")
	)
	(segment
		(start 137.220198 -278.031194)
		(end 137.220198 -278.623014)
		(width 0.088646)
		(layer "F.Cu")
		(net "M_E_CPU1_SA_DQ<1>")
	)
	(segment
		(start 163.91382 -314.19165)
		(end 161.905442 -314.19165)
		(width 0.1016)
		(layer "F.Cu")
		(net "M_E_CPU1_SA_DQ<1>")
	)
	(segment
		(start 150.153624 -308.542182)
		(end 150.153624 -308.871874)
		(width 0.20066)
		(layer "F.Cu")
		(net "M_E_CPU1_SA_DQ<1>")
	)
	(segment
		(start 149.183344 -307.901594)
		(end 149.503638 -308.221888)
		(width 0.20066)
		(layer "F.Cu")
		(net "M_E_CPU1_SA_DQ<1>")
	)
	(segment
		(start 164.209222 -314.181744)
		(end 163.923726 -314.181744)
		(width 0.20066)
		(layer "F.Cu")
		(net "M_E_CPU1_SA_DQ<1>")
	)
	(segment
		(start 149.83333 -308.221888)
		(end 150.153624 -308.542182)
		(width 0.20066)
		(layer "F.Cu")
		(net "M_E_CPU1_SA_DQ<1>")
	)
	(segment
		(start 153.476706 -312.103008)
		(end 153.71445 -312.103008)
		(width 0.20066)
		(layer "F.Cu")
		(net "M_E_CPU1_SA_DQ<1>")
	)
	(arc
		(start 137.220198 -278.623014)
		(mid 137.272468 -278.805379)
		(end 137.407396 -278.938736)
		(width 0.088646)
		(layer "F.Cu")
		(net "M_E_CPU1_SA_DQ<1>")
	)
	(arc
		(start 137.407396 -278.938736)
		(mid 137.594594 -278.988879)
		(end 137.781792 -278.938736)
		(width 0.088646)
		(layer "F.Cu")
		(net "M_E_CPU1_SA_DQ<1>")
	)
	(arc
		(start 137.792206 -278.93264)
		(mid 138.070638 -278.862794)
		(end 138.34745 -278.938736)
		(width 0.088646)
		(layer "F.Cu")
		(net "M_E_CPU1_SA_DQ<1>")
	)
	(segment
		(start 157.725872 -295.59631)
		(end 157.791658 -295.530524)
		(width 0.20066)
		(layer "F.Cu")
		(net "M_E_CPU1_SA_DQ<19>")
	)
	(segment
		(start 153.309828 -297.840908)
		(end 153.109168 -297.640248)
		(width 0.20066)
		(layer "F.Cu")
		(net "M_E_CPU1_SA_DQ<19>")
	)
	(segment
		(start 139.378944 -271.78635)
		(end 139.378944 -271.841468)
		(width 0.088646)
		(layer "F.Cu")
		(net "M_E_CPU1_SA_DQ<19>")
	)
	(segment
		(start 159.823658 -295.491662)
		(end 160.245806 -295.491662)
		(width 0.20066)
		(layer "F.Cu")
		(net "M_E_CPU1_SA_DQ<19>")
	)
	(segment
		(start 165.36035 -295.491662)
		(end 165.352984 -295.499028)
		(width 0.1016)
		(layer "F.Cu")
		(net "M_E_CPU1_SA_DQ<19>")
	)
	(segment
		(start 165.352984 -295.499028)
		(end 165.335458 -295.499028)
		(width 0.101854)
		(layer "F.Cu")
		(net "M_E_CPU1_SA_DQ<19>")
	)
	(segment
		(start 165.335458 -295.499028)
		(end 164.902134 -295.499028)
		(width 0.20066)
		(layer "F.Cu")
		(net "M_E_CPU1_SA_DQ<19>")
	)
	(segment
		(start 155.43403 -296.954448)
		(end 156.792168 -295.59631)
		(width 0.20066)
		(layer "F.Cu")
		(net "M_E_CPU1_SA_DQ<19>")
	)
	(segment
		(start 152.41651 -297.155108)
		(end 152.61717 -296.954448)
		(width 0.20066)
		(layer "F.Cu")
		(net "M_E_CPU1_SA_DQ<19>")
	)
	(segment
		(start 167.367458 -295.503092)
		(end 167.356028 -295.491662)
		(width 0.101854)
		(layer "F.Cu")
		(net "M_E_CPU1_SA_DQ<19>")
	)
	(segment
		(start 143.99895 -289.491928)
		(end 144.387824 -290.430712)
		(width 0.1016)
		(layer "F.Cu")
		(net "M_E_CPU1_SA_DQ<19>")
	)
	(segment
		(start 139.349988 -271.673828)
		(end 139.369038 -271.73682)
		(width 0.088646)
		(layer "F.Cu")
		(net "M_E_CPU1_SA_DQ<19>")
	)
	(segment
		(start 138.586464 -270.475456)
		(end 138.810238 -270.69923)
		(width 0.088646)
		(layer "F.Cu")
		(net "M_E_CPU1_SA_DQ<19>")
	)
	(segment
		(start 168.265348 -294.965628)
		(end 168.265348 -295.272968)
		(width 0.20066)
		(layer "F.Cu")
		(net "M_E_CPU1_SA_DQ<19>")
	)
	(segment
		(start 139.378944 -271.841468)
		(end 141.321536 -273.78406)
		(width 0.088646)
		(layer "F.Cu")
		(net "M_E_CPU1_SA_DQ<19>")
	)
	(segment
		(start 152.41651 -297.439588)
		(end 152.41651 -297.155108)
		(width 0.20066)
		(layer "F.Cu")
		(net "M_E_CPU1_SA_DQ<19>")
	)
	(segment
		(start 160.245806 -295.491662)
		(end 160.670748 -295.06672)
		(width 0.20066)
		(layer "F.Cu")
		(net "M_E_CPU1_SA_DQ<19>")
	)
	(segment
		(start 152.61717 -296.954448)
		(end 155.43403 -296.954448)
		(width 0.20066)
		(layer "F.Cu")
		(net "M_E_CPU1_SA_DQ<19>")
	)
	(segment
		(start 160.670748 -295.06672)
		(end 162.913314 -295.06672)
		(width 0.20066)
		(layer "F.Cu")
		(net "M_E_CPU1_SA_DQ<19>")
	)
	(segment
		(start 139.015978 -271.307306)
		(end 139.326874 -271.618202)
		(width 0.088646)
		(layer "F.Cu")
		(net "M_E_CPU1_SA_DQ<19>")
	)
	(segment
		(start 156.792168 -295.59631)
		(end 157.725872 -295.59631)
		(width 0.20066)
		(layer "F.Cu")
		(net "M_E_CPU1_SA_DQ<19>")
	)
	(segment
		(start 144.387824 -290.430712)
		(end 145.110708 -291.153596)
		(width 0.1016)
		(layer "F.Cu")
		(net "M_E_CPU1_SA_DQ<19>")
	)
	(segment
		(start 138.91768 -271.070324)
		(end 139.015978 -271.307306)
		(width 0.088646)
		(layer "F.Cu")
		(net "M_E_CPU1_SA_DQ<19>")
	)
	(segment
		(start 138.940794 -271.014444)
		(end 138.91768 -271.070324)
		(width 0.088646)
		(layer "F.Cu")
		(net "M_E_CPU1_SA_DQ<19>")
	)
	(segment
		(start 143.014954 -275.477478)
		(end 143.99895 -280.403046)
		(width 0.1016)
		(layer "F.Cu")
		(net "M_E_CPU1_SA_DQ<19>")
	)
	(segment
		(start 164.469826 -295.06672)
		(end 162.913314 -295.06672)
		(width 0.20066)
		(layer "F.Cu")
		(net "M_E_CPU1_SA_DQ<19>")
	)
	(segment
		(start 152.61717 -297.640248)
		(end 152.41651 -297.439588)
		(width 0.20066)
		(layer "F.Cu")
		(net "M_E_CPU1_SA_DQ<19>")
	)
	(segment
		(start 168.480486 -294.75049)
		(end 168.265348 -294.965628)
		(width 0.20066)
		(layer "F.Cu")
		(net "M_E_CPU1_SA_DQ<19>")
	)
	(segment
		(start 168.265348 -295.272968)
		(end 168.035224 -295.503092)
		(width 0.20066)
		(layer "F.Cu")
		(net "M_E_CPU1_SA_DQ<19>")
	)
	(segment
		(start 138.810238 -270.69923)
		(end 138.940794 -271.014444)
		(width 0.088646)
		(layer "F.Cu")
		(net "M_E_CPU1_SA_DQ<19>")
	)
	(segment
		(start 153.109168 -298.326048)
		(end 153.309828 -298.125388)
		(width 0.20066)
		(layer "F.Cu")
		(net "M_E_CPU1_SA_DQ<19>")
	)
	(segment
		(start 170.457114 -295.06672)
		(end 169.135552 -295.06672)
		(width 0.20066)
		(layer "F.Cu")
		(net "M_E_CPU1_SA_DQ<19>")
	)
	(segment
		(start 167.356028 -295.491662)
		(end 166.558214 -295.491662)
		(width 0.101854)
		(layer "F.Cu")
		(net "M_E_CPU1_SA_DQ<19>")
	)
	(segment
		(start 138.534648 -270.475456)
		(end 138.586464 -270.475456)
		(width 0.088646)
		(layer "F.Cu")
		(net "M_E_CPU1_SA_DQ<19>")
	)
	(segment
		(start 166.558214 -295.491662)
		(end 165.36035 -295.491662)
		(width 0.1016)
		(layer "F.Cu")
		(net "M_E_CPU1_SA_DQ<19>")
	)
	(segment
		(start 153.109168 -297.640248)
		(end 152.61717 -297.640248)
		(width 0.20066)
		(layer "F.Cu")
		(net "M_E_CPU1_SA_DQ<19>")
	)
	(segment
		(start 168.035224 -295.503092)
		(end 167.367458 -295.503092)
		(width 0.20066)
		(layer "F.Cu")
		(net "M_E_CPU1_SA_DQ<19>")
	)
	(segment
		(start 152.28316 -298.326048)
		(end 153.109168 -298.326048)
		(width 0.20066)
		(layer "F.Cu")
		(net "M_E_CPU1_SA_DQ<19>")
	)
	(segment
		(start 145.110708 -291.153596)
		(end 152.28316 -298.326048)
		(width 0.20066)
		(layer "F.Cu")
		(net "M_E_CPU1_SA_DQ<19>")
	)
	(segment
		(start 168.819322 -294.75049)
		(end 168.480486 -294.75049)
		(width 0.20066)
		(layer "F.Cu")
		(net "M_E_CPU1_SA_DQ<19>")
	)
	(segment
		(start 141.321536 -273.78406)
		(end 143.014954 -275.477478)
		(width 0.1016)
		(layer "F.Cu")
		(net "M_E_CPU1_SA_DQ<19>")
	)
	(segment
		(start 139.369038 -271.73682)
		(end 139.378944 -271.78635)
		(width 0.088646)
		(layer "F.Cu")
		(net "M_E_CPU1_SA_DQ<19>")
	)
	(segment
		(start 157.83052 -295.491662)
		(end 159.823658 -295.491662)
		(width 0.1016)
		(layer "F.Cu")
		(net "M_E_CPU1_SA_DQ<19>")
	)
	(segment
		(start 164.902134 -295.499028)
		(end 164.469826 -295.06672)
		(width 0.20066)
		(layer "F.Cu")
		(net "M_E_CPU1_SA_DQ<19>")
	)
	(segment
		(start 153.309828 -298.125388)
		(end 153.309828 -297.840908)
		(width 0.20066)
		(layer "F.Cu")
		(net "M_E_CPU1_SA_DQ<19>")
	)
	(segment
		(start 139.326874 -271.618202)
		(end 139.349988 -271.673828)
		(width 0.088646)
		(layer "F.Cu")
		(net "M_E_CPU1_SA_DQ<19>")
	)
	(segment
		(start 143.99895 -280.403046)
		(end 143.99895 -289.491928)
		(width 0.1016)
		(layer "F.Cu")
		(net "M_E_CPU1_SA_DQ<19>")
	)
	(segment
		(start 169.135552 -295.06672)
		(end 168.819322 -294.75049)
		(width 0.20066)
		(layer "F.Cu")
		(net "M_E_CPU1_SA_DQ<19>")
	)
	(segment
		(start 157.791658 -295.530524)
		(end 157.83052 -295.491662)
		(width 0.101854)
		(layer "F.Cu")
		(net "M_E_CPU1_SA_DQ<19>")
	)
	(segment
		(start 168.883584 -296.514774)
		(end 168.499536 -296.514774)
		(width 0.20066)
		(layer "F.Cu")
		(net "M_E_CPU1_SA_DQ<18>")
	)
	(segment
		(start 168.499536 -296.514774)
		(end 168.265348 -296.748962)
		(width 0.20066)
		(layer "F.Cu")
		(net "M_E_CPU1_SA_DQ<18>")
	)
	(segment
		(start 167.367458 -297.203114)
		(end 167.356028 -297.191684)
		(width 0.101854)
		(layer "F.Cu")
		(net "M_E_CPU1_SA_DQ<18>")
	)
	(segment
		(start 165.335458 -297.19905)
		(end 164.93871 -297.19905)
		(width 0.20066)
		(layer "F.Cu")
		(net "M_E_CPU1_SA_DQ<18>")
	)
	(segment
		(start 157.6324 -297.355768)
		(end 157.791658 -297.19651)
		(width 0.20066)
		(layer "F.Cu")
		(net "M_E_CPU1_SA_DQ<18>")
	)
	(segment
		(start 137.865104 -272.341594)
		(end 139.067032 -273.138646)
		(width 0.088646)
		(layer "F.Cu")
		(net "M_E_CPU1_SA_DQ<18>")
	)
	(segment
		(start 151.81453 -299.73397)
		(end 155.86329 -299.73397)
		(width 0.20066)
		(layer "F.Cu")
		(net "M_E_CPU1_SA_DQ<18>")
	)
	(segment
		(start 160.743392 -297.228006)
		(end 161.204656 -296.766742)
		(width 0.20066)
		(layer "F.Cu")
		(net "M_E_CPU1_SA_DQ<18>")
	)
	(segment
		(start 168.265348 -297.002454)
		(end 168.064688 -297.203114)
		(width 0.20066)
		(layer "F.Cu")
		(net "M_E_CPU1_SA_DQ<18>")
	)
	(segment
		(start 156.260292 -299.336968)
		(end 156.260292 -297.937428)
		(width 0.20066)
		(layer "F.Cu")
		(net "M_E_CPU1_SA_DQ<18>")
	)
	(segment
		(start 140.34008 -273.665696)
		(end 140.88999 -274.215606)
		(width 0.088646)
		(layer "F.Cu")
		(net "M_E_CPU1_SA_DQ<18>")
	)
	(segment
		(start 168.265348 -296.748962)
		(end 168.265348 -297.002454)
		(width 0.20066)
		(layer "F.Cu")
		(net "M_E_CPU1_SA_DQ<18>")
	)
	(segment
		(start 164.93871 -297.19905)
		(end 164.506402 -296.766742)
		(width 0.20066)
		(layer "F.Cu")
		(net "M_E_CPU1_SA_DQ<18>")
	)
	(segment
		(start 159.663384 -297.191684)
		(end 159.76854 -297.228006)
		(width 0.1016)
		(layer "F.Cu")
		(net "M_E_CPU1_SA_DQ<18>")
	)
	(segment
		(start 155.86329 -299.73397)
		(end 156.260292 -299.336968)
		(width 0.20066)
		(layer "F.Cu")
		(net "M_E_CPU1_SA_DQ<18>")
	)
	(segment
		(start 142.451582 -275.777198)
		(end 143.38935 -280.465022)
		(width 0.1016)
		(layer "F.Cu")
		(net "M_E_CPU1_SA_DQ<18>")
	)
	(segment
		(start 140.88999 -274.215606)
		(end 142.451582 -275.777198)
		(width 0.1016)
		(layer "F.Cu")
		(net "M_E_CPU1_SA_DQ<18>")
	)
	(segment
		(start 139.067032 -273.138646)
		(end 140.34008 -273.665696)
		(width 0.088646)
		(layer "F.Cu")
		(net "M_E_CPU1_SA_DQ<18>")
	)
	(segment
		(start 165.352984 -297.19905)
		(end 165.335458 -297.19905)
		(width 0.101854)
		(layer "F.Cu")
		(net "M_E_CPU1_SA_DQ<18>")
	)
	(segment
		(start 143.38935 -289.79749)
		(end 143.455136 -290.12769)
		(width 0.1016)
		(layer "F.Cu")
		(net "M_E_CPU1_SA_DQ<18>")
	)
	(segment
		(start 165.36035 -297.191684)
		(end 165.352984 -297.19905)
		(width 0.1016)
		(layer "F.Cu")
		(net "M_E_CPU1_SA_DQ<18>")
	)
	(segment
		(start 170.457114 -296.766742)
		(end 169.135552 -296.766742)
		(width 0.20066)
		(layer "F.Cu")
		(net "M_E_CPU1_SA_DQ<18>")
	)
	(segment
		(start 143.38935 -280.465022)
		(end 143.38935 -289.79749)
		(width 0.1016)
		(layer "F.Cu")
		(net "M_E_CPU1_SA_DQ<18>")
	)
	(segment
		(start 167.356028 -297.191684)
		(end 166.558214 -297.191684)
		(width 0.101854)
		(layer "F.Cu")
		(net "M_E_CPU1_SA_DQ<18>")
	)
	(segment
		(start 156.841952 -297.355768)
		(end 157.6324 -297.355768)
		(width 0.20066)
		(layer "F.Cu")
		(net "M_E_CPU1_SA_DQ<18>")
	)
	(segment
		(start 156.260292 -297.937428)
		(end 156.841952 -297.355768)
		(width 0.20066)
		(layer "F.Cu")
		(net "M_E_CPU1_SA_DQ<18>")
	)
	(segment
		(start 169.135552 -296.766742)
		(end 168.883584 -296.514774)
		(width 0.20066)
		(layer "F.Cu")
		(net "M_E_CPU1_SA_DQ<18>")
	)
	(segment
		(start 157.791658 -297.19651)
		(end 157.796484 -297.191684)
		(width 0.101854)
		(layer "F.Cu")
		(net "M_E_CPU1_SA_DQ<18>")
	)
	(segment
		(start 143.455136 -290.12769)
		(end 143.99768 -291.91712)
		(width 0.1016)
		(layer "F.Cu")
		(net "M_E_CPU1_SA_DQ<18>")
	)
	(segment
		(start 164.506402 -296.766742)
		(end 162.913314 -296.766742)
		(width 0.20066)
		(layer "F.Cu")
		(net "M_E_CPU1_SA_DQ<18>")
	)
	(segment
		(start 166.558214 -297.191684)
		(end 165.36035 -297.191684)
		(width 0.1016)
		(layer "F.Cu")
		(net "M_E_CPU1_SA_DQ<18>")
	)
	(segment
		(start 143.99768 -291.91712)
		(end 144.172432 -292.091872)
		(width 0.1016)
		(layer "F.Cu")
		(net "M_E_CPU1_SA_DQ<18>")
	)
	(segment
		(start 137.594594 -272.103342)
		(end 137.865104 -272.341594)
		(width 0.088646)
		(layer "F.Cu")
		(net "M_E_CPU1_SA_DQ<18>")
	)
	(segment
		(start 168.064688 -297.203114)
		(end 167.367458 -297.203114)
		(width 0.20066)
		(layer "F.Cu")
		(net "M_E_CPU1_SA_DQ<18>")
	)
	(segment
		(start 144.172432 -292.091872)
		(end 151.81453 -299.73397)
		(width 0.20066)
		(layer "F.Cu")
		(net "M_E_CPU1_SA_DQ<18>")
	)
	(segment
		(start 157.796484 -297.191684)
		(end 159.663384 -297.191684)
		(width 0.1016)
		(layer "F.Cu")
		(net "M_E_CPU1_SA_DQ<18>")
	)
	(segment
		(start 161.204656 -296.766742)
		(end 162.913314 -296.766742)
		(width 0.20066)
		(layer "F.Cu")
		(net "M_E_CPU1_SA_DQ<18>")
	)
	(segment
		(start 159.823658 -297.228006)
		(end 160.743392 -297.228006)
		(width 0.20066)
		(layer "F.Cu")
		(net "M_E_CPU1_SA_DQ<18>")
	)
	(segment
		(start 159.76854 -297.228006)
		(end 159.823658 -297.228006)
		(width 0.1016)
		(layer "F.Cu")
		(net "M_E_CPU1_SA_DQ<18>")
	)
	(segment
		(start 163.912296 -295.491662)
		(end 163.114482 -295.491662)
		(width 0.101854)
		(layer "F.Cu")
		(net "M_E_CPU1_SA_DQ<17>")
	)
	(segment
		(start 137.420604 -271.67078)
		(end 137.976864 -271.67078)
		(width 0.088646)
		(layer "F.Cu")
		(net "M_E_CPU1_SA_DQ<17>")
	)
	(segment
		(start 161.909252 -295.484296)
		(end 161.891726 -295.484296)
		(width 0.101854)
		(layer "F.Cu")
		(net "M_E_CPU1_SA_DQ<17>")
	)
	(segment
		(start 137.124694 -271.289272)
		(end 136.86155 -271.398238)
		(width 0.088646)
		(layer "F.Cu")
		(net "M_E_CPU1_SA_DQ<17>")
	)
	(segment
		(start 136.743186 -271.642078)
		(end 137.02284 -271.921732)
		(width 0.088646)
		(layer "F.Cu")
		(net "M_E_CPU1_SA_DQ<17>")
	)
	(segment
		(start 157.973522 -295.916604)
		(end 158.813246 -295.916604)
		(width 0.20066)
		(layer "F.Cu")
		(net "M_E_CPU1_SA_DQ<17>")
	)
	(segment
		(start 142.733268 -275.627592)
		(end 143.69415 -280.434288)
		(width 0.1016)
		(layer "F.Cu")
		(net "M_E_CPU1_SA_DQ<17>")
	)
	(segment
		(start 137.976864 -271.67078)
		(end 138.113262 -271.807178)
		(width 0.088646)
		(layer "F.Cu")
		(net "M_E_CPU1_SA_DQ<17>")
	)
	(segment
		(start 152.107138 -299.094398)
		(end 153.938224 -299.094398)
		(width 0.20066)
		(layer "F.Cu")
		(net "M_E_CPU1_SA_DQ<17>")
	)
	(segment
		(start 140.20419 -273.098514)
		(end 142.733268 -275.627592)
		(width 0.1016)
		(layer "F.Cu")
		(net "M_E_CPU1_SA_DQ<17>")
	)
	(segment
		(start 163.114482 -295.491662)
		(end 161.916618 -295.491662)
		(width 0.1016)
		(layer "F.Cu")
		(net "M_E_CPU1_SA_DQ<17>")
	)
	(segment
		(start 154.138884 -298.893738)
		(end 154.138884 -297.806872)
		(width 0.20066)
		(layer "F.Cu")
		(net "M_E_CPU1_SA_DQ<17>")
	)
	(segment
		(start 160.422082 -296.646854)
		(end 159.691832 -295.916604)
		(width 0.20066)
		(layer "F.Cu")
		(net "M_E_CPU1_SA_DQ<17>")
	)
	(segment
		(start 161.288984 -295.69029)
		(end 161.288984 -296.157904)
		(width 0.20066)
		(layer "F.Cu")
		(net "M_E_CPU1_SA_DQ<17>")
	)
	(segment
		(start 164.251386 -295.480232)
		(end 163.923726 -295.480232)
		(width 0.20066)
		(layer "F.Cu")
		(net "M_E_CPU1_SA_DQ<17>")
	)
	(segment
		(start 164.687758 -295.916604)
		(end 164.251386 -295.480232)
		(width 0.20066)
		(layer "F.Cu")
		(net "M_E_CPU1_SA_DQ<17>")
	)
	(segment
		(start 138.113262 -271.807178)
		(end 138.113262 -272.19148)
		(width 0.088646)
		(layer "F.Cu")
		(net "M_E_CPU1_SA_DQ<17>")
	)
	(segment
		(start 140.12926 -273.023584)
		(end 140.20419 -273.098514)
		(width 0.088646)
		(layer "F.Cu")
		(net "M_E_CPU1_SA_DQ<17>")
	)
	(segment
		(start 163.923726 -295.480232)
		(end 163.912296 -295.491662)
		(width 0.101854)
		(layer "F.Cu")
		(net "M_E_CPU1_SA_DQ<17>")
	)
	(segment
		(start 161.288984 -296.157904)
		(end 161.177732 -296.269156)
		(width 0.20066)
		(layer "F.Cu")
		(net "M_E_CPU1_SA_DQ<17>")
	)
	(segment
		(start 155.025344 -299.094398)
		(end 155.42006 -299.094398)
		(width 0.20066)
		(layer "F.Cu")
		(net "M_E_CPU1_SA_DQ<17>")
	)
	(segment
		(start 156.839412 -296.45356)
		(end 157.243272 -296.45356)
		(width 0.20066)
		(layer "F.Cu")
		(net "M_E_CPU1_SA_DQ<17>")
	)
	(segment
		(start 138.113262 -272.19148)
		(end 138.23315 -272.311368)
		(width 0.088646)
		(layer "F.Cu")
		(net "M_E_CPU1_SA_DQ<17>")
	)
	(segment
		(start 161.177732 -296.269156)
		(end 161.026094 -296.269156)
		(width 0.20066)
		(layer "F.Cu")
		(net "M_E_CPU1_SA_DQ<17>")
	)
	(segment
		(start 153.938224 -299.094398)
		(end 154.138884 -298.893738)
		(width 0.20066)
		(layer "F.Cu")
		(net "M_E_CPU1_SA_DQ<17>")
	)
	(segment
		(start 159.691832 -295.916604)
		(end 158.813246 -295.916604)
		(width 0.20066)
		(layer "F.Cu")
		(net "M_E_CPU1_SA_DQ<17>")
	)
	(segment
		(start 161.891726 -295.484296)
		(end 161.494978 -295.484296)
		(width 0.20066)
		(layer "F.Cu")
		(net "M_E_CPU1_SA_DQ<17>")
	)
	(segment
		(start 160.648396 -296.646854)
		(end 160.422082 -296.646854)
		(width 0.20066)
		(layer "F.Cu")
		(net "M_E_CPU1_SA_DQ<17>")
	)
	(segment
		(start 154.138884 -297.806872)
		(end 154.339544 -297.606212)
		(width 0.20066)
		(layer "F.Cu")
		(net "M_E_CPU1_SA_DQ<17>")
	)
	(segment
		(start 144.388078 -291.375338)
		(end 144.638522 -291.625782)
		(width 0.1016)
		(layer "F.Cu")
		(net "M_E_CPU1_SA_DQ<17>")
	)
	(segment
		(start 136.86155 -271.398238)
		(end 136.743186 -271.516602)
		(width 0.088646)
		(layer "F.Cu")
		(net "M_E_CPU1_SA_DQ<17>")
	)
	(segment
		(start 161.916618 -295.491662)
		(end 161.909252 -295.484296)
		(width 0.1016)
		(layer "F.Cu")
		(net "M_E_CPU1_SA_DQ<17>")
	)
	(segment
		(start 136.743186 -271.516602)
		(end 136.743186 -271.642078)
		(width 0.088646)
		(layer "F.Cu")
		(net "M_E_CPU1_SA_DQ<17>")
	)
	(segment
		(start 143.69415 -280.434288)
		(end 143.69415 -289.699446)
		(width 0.1016)
		(layer "F.Cu")
		(net "M_E_CPU1_SA_DQ<17>")
	)
	(segment
		(start 154.824684 -298.893738)
		(end 155.025344 -299.094398)
		(width 0.20066)
		(layer "F.Cu")
		(net "M_E_CPU1_SA_DQ<17>")
	)
	(segment
		(start 155.42006 -299.094398)
		(end 155.62072 -298.893738)
		(width 0.20066)
		(layer "F.Cu")
		(net "M_E_CPU1_SA_DQ<17>")
	)
	(segment
		(start 155.62072 -298.893738)
		(end 155.62072 -297.672252)
		(width 0.20066)
		(layer "F.Cu")
		(net "M_E_CPU1_SA_DQ<17>")
	)
	(segment
		(start 155.62072 -297.672252)
		(end 156.839412 -296.45356)
		(width 0.20066)
		(layer "F.Cu")
		(net "M_E_CPU1_SA_DQ<17>")
	)
	(segment
		(start 139.013692 -272.737326)
		(end 139.43838 -272.737326)
		(width 0.088646)
		(layer "F.Cu")
		(net "M_E_CPU1_SA_DQ<17>")
	)
	(segment
		(start 154.824684 -297.806872)
		(end 154.824684 -298.893738)
		(width 0.20066)
		(layer "F.Cu")
		(net "M_E_CPU1_SA_DQ<17>")
	)
	(segment
		(start 166.357046 -295.916604)
		(end 164.687758 -295.916604)
		(width 0.20066)
		(layer "F.Cu")
		(net "M_E_CPU1_SA_DQ<17>")
	)
	(segment
		(start 138.23315 -272.311368)
		(end 138.435334 -272.461228)
		(width 0.088646)
		(layer "F.Cu")
		(net "M_E_CPU1_SA_DQ<17>")
	)
	(segment
		(start 137.169652 -271.921732)
		(end 137.420604 -271.67078)
		(width 0.088646)
		(layer "F.Cu")
		(net "M_E_CPU1_SA_DQ<17>")
	)
	(segment
		(start 157.459426 -296.237406)
		(end 157.65272 -296.237406)
		(width 0.20066)
		(layer "F.Cu")
		(net "M_E_CPU1_SA_DQ<17>")
	)
	(segment
		(start 138.60145 -272.566384)
		(end 139.013692 -272.737326)
		(width 0.088646)
		(layer "F.Cu")
		(net "M_E_CPU1_SA_DQ<17>")
	)
	(segment
		(start 143.69415 -289.699446)
		(end 144.388078 -291.375338)
		(width 0.1016)
		(layer "F.Cu")
		(net "M_E_CPU1_SA_DQ<17>")
	)
	(segment
		(start 154.339544 -297.606212)
		(end 154.624024 -297.606212)
		(width 0.20066)
		(layer "F.Cu")
		(net "M_E_CPU1_SA_DQ<17>")
	)
	(segment
		(start 137.02284 -271.921732)
		(end 137.169652 -271.921732)
		(width 0.088646)
		(layer "F.Cu")
		(net "M_E_CPU1_SA_DQ<17>")
	)
	(segment
		(start 154.624024 -297.606212)
		(end 154.824684 -297.806872)
		(width 0.20066)
		(layer "F.Cu")
		(net "M_E_CPU1_SA_DQ<17>")
	)
	(segment
		(start 157.65272 -296.237406)
		(end 157.973522 -295.916604)
		(width 0.20066)
		(layer "F.Cu")
		(net "M_E_CPU1_SA_DQ<17>")
	)
	(segment
		(start 144.638522 -291.625782)
		(end 152.107138 -299.094398)
		(width 0.20066)
		(layer "F.Cu")
		(net "M_E_CPU1_SA_DQ<17>")
	)
	(segment
		(start 161.026094 -296.269156)
		(end 160.648396 -296.646854)
		(width 0.20066)
		(layer "F.Cu")
		(net "M_E_CPU1_SA_DQ<17>")
	)
	(segment
		(start 138.435334 -272.461228)
		(end 138.60145 -272.566384)
		(width 0.088646)
		(layer "F.Cu")
		(net "M_E_CPU1_SA_DQ<17>")
	)
	(segment
		(start 157.243272 -296.45356)
		(end 157.459426 -296.237406)
		(width 0.20066)
		(layer "F.Cu")
		(net "M_E_CPU1_SA_DQ<17>")
	)
	(segment
		(start 161.494978 -295.484296)
		(end 161.288984 -295.69029)
		(width 0.20066)
		(layer "F.Cu")
		(net "M_E_CPU1_SA_DQ<17>")
	)
	(segment
		(start 139.43838 -272.737326)
		(end 140.12926 -273.023584)
		(width 0.088646)
		(layer "F.Cu")
		(net "M_E_CPU1_SA_DQ<17>")
	)
	(segment
		(start 159.897318 -297.865292)
		(end 159.648652 -297.616626)
		(width 0.20066)
		(layer "F.Cu")
		(net "M_E_CPU1_SA_DQ<16>")
	)
	(segment
		(start 140.075666 -273.832574)
		(end 140.674344 -274.431252)
		(width 0.088646)
		(layer "F.Cu")
		(net "M_E_CPU1_SA_DQ<16>")
	)
	(segment
		(start 138.755374 -273.285712)
		(end 140.075666 -273.832574)
		(width 0.088646)
		(layer "F.Cu")
		(net "M_E_CPU1_SA_DQ<16>")
	)
	(segment
		(start 153.96083 -300.574202)
		(end 153.96083 -300.985428)
		(width 0.20066)
		(layer "F.Cu")
		(net "M_E_CPU1_SA_DQ<16>")
	)
	(segment
		(start 142.170658 -275.927566)
		(end 143.08455 -280.504138)
		(width 0.1016)
		(layer "F.Cu")
		(net "M_E_CPU1_SA_DQ<16>")
	)
	(segment
		(start 137.77468 -273.280378)
		(end 137.99058 -273.496278)
		(width 0.088646)
		(layer "F.Cu")
		(net "M_E_CPU1_SA_DQ<16>")
	)
	(segment
		(start 143.687038 -292.526466)
		(end 151.539448 -300.373542)
		(width 0.20066)
		(layer "F.Cu")
		(net "M_E_CPU1_SA_DQ<16>")
	)
	(segment
		(start 157.99435 -297.616626)
		(end 158.813246 -297.616626)
		(width 0.20066)
		(layer "F.Cu")
		(net "M_E_CPU1_SA_DQ<16>")
	)
	(segment
		(start 154.44597 -301.186088)
		(end 154.64663 -300.985428)
		(width 0.20066)
		(layer "F.Cu")
		(net "M_E_CPU1_SA_DQ<16>")
	)
	(segment
		(start 154.16149 -301.186088)
		(end 154.44597 -301.186088)
		(width 0.20066)
		(layer "F.Cu")
		(net "M_E_CPU1_SA_DQ<16>")
	)
	(segment
		(start 157.593792 -298.017184)
		(end 157.99435 -297.616626)
		(width 0.20066)
		(layer "F.Cu")
		(net "M_E_CPU1_SA_DQ<16>")
	)
	(segment
		(start 152.58923 -300.985428)
		(end 152.78989 -301.186088)
		(width 0.20066)
		(layer "F.Cu")
		(net "M_E_CPU1_SA_DQ<16>")
	)
	(segment
		(start 156.899864 -300.036738)
		(end 156.899864 -298.345098)
		(width 0.20066)
		(layer "F.Cu")
		(net "M_E_CPU1_SA_DQ<16>")
	)
	(segment
		(start 163.114482 -297.191684)
		(end 161.916618 -297.191684)
		(width 0.1016)
		(layer "F.Cu")
		(net "M_E_CPU1_SA_DQ<16>")
	)
	(segment
		(start 155.13177 -300.373542)
		(end 155.33243 -300.574202)
		(width 0.20066)
		(layer "F.Cu")
		(net "M_E_CPU1_SA_DQ<16>")
	)
	(segment
		(start 156.899864 -298.345098)
		(end 157.227778 -298.017184)
		(width 0.20066)
		(layer "F.Cu")
		(net "M_E_CPU1_SA_DQ<16>")
	)
	(segment
		(start 157.227778 -298.017184)
		(end 157.593792 -298.017184)
		(width 0.20066)
		(layer "F.Cu")
		(net "M_E_CPU1_SA_DQ<16>")
	)
	(segment
		(start 156.01823 -300.574202)
		(end 156.21889 -300.373542)
		(width 0.20066)
		(layer "F.Cu")
		(net "M_E_CPU1_SA_DQ<16>")
	)
	(segment
		(start 143.08455 -280.504138)
		(end 143.08455 -290.379912)
		(width 0.1016)
		(layer "F.Cu")
		(net "M_E_CPU1_SA_DQ<16>")
	)
	(segment
		(start 166.357046 -297.616626)
		(end 164.72789 -297.616626)
		(width 0.20066)
		(layer "F.Cu")
		(net "M_E_CPU1_SA_DQ<16>")
	)
	(segment
		(start 152.38857 -300.373542)
		(end 152.58923 -300.574202)
		(width 0.20066)
		(layer "F.Cu")
		(net "M_E_CPU1_SA_DQ<16>")
	)
	(segment
		(start 161.916618 -297.191684)
		(end 161.909252 -297.184318)
		(width 0.1016)
		(layer "F.Cu")
		(net "M_E_CPU1_SA_DQ<16>")
	)
	(segment
		(start 163.912296 -297.191684)
		(end 163.114482 -297.191684)
		(width 0.101854)
		(layer "F.Cu")
		(net "M_E_CPU1_SA_DQ<16>")
	)
	(segment
		(start 154.64663 -300.985428)
		(end 154.64663 -300.574202)
		(width 0.20066)
		(layer "F.Cu")
		(net "M_E_CPU1_SA_DQ<16>")
	)
	(segment
		(start 156.21889 -300.373542)
		(end 156.56306 -300.373542)
		(width 0.20066)
		(layer "F.Cu")
		(net "M_E_CPU1_SA_DQ<16>")
	)
	(segment
		(start 152.58923 -300.574202)
		(end 152.58923 -300.985428)
		(width 0.20066)
		(layer "F.Cu")
		(net "M_E_CPU1_SA_DQ<16>")
	)
	(segment
		(start 151.539448 -300.373542)
		(end 152.38857 -300.373542)
		(width 0.20066)
		(layer "F.Cu")
		(net "M_E_CPU1_SA_DQ<16>")
	)
	(segment
		(start 138.609578 -273.285712)
		(end 138.755374 -273.285712)
		(width 0.088646)
		(layer "F.Cu")
		(net "M_E_CPU1_SA_DQ<16>")
	)
	(segment
		(start 159.648652 -297.616626)
		(end 158.813246 -297.616626)
		(width 0.20066)
		(layer "F.Cu")
		(net "M_E_CPU1_SA_DQ<16>")
	)
	(segment
		(start 161.891726 -297.184318)
		(end 161.456116 -297.184318)
		(width 0.20066)
		(layer "F.Cu")
		(net "M_E_CPU1_SA_DQ<16>")
	)
	(segment
		(start 155.81757 -301.186088)
		(end 156.01823 -300.985428)
		(width 0.20066)
		(layer "F.Cu")
		(net "M_E_CPU1_SA_DQ<16>")
	)
	(segment
		(start 143.468344 -292.30828)
		(end 143.687038 -292.526466)
		(width 0.1016)
		(layer "F.Cu")
		(net "M_E_CPU1_SA_DQ<16>")
	)
	(segment
		(start 155.33243 -300.985428)
		(end 155.53309 -301.186088)
		(width 0.20066)
		(layer "F.Cu")
		(net "M_E_CPU1_SA_DQ<16>")
	)
	(segment
		(start 161.057844 -297.865292)
		(end 159.897318 -297.865292)
		(width 0.20066)
		(layer "F.Cu")
		(net "M_E_CPU1_SA_DQ<16>")
	)
	(segment
		(start 153.96083 -300.985428)
		(end 154.16149 -301.186088)
		(width 0.20066)
		(layer "F.Cu")
		(net "M_E_CPU1_SA_DQ<16>")
	)
	(segment
		(start 153.27503 -300.985428)
		(end 153.27503 -300.574202)
		(width 0.20066)
		(layer "F.Cu")
		(net "M_E_CPU1_SA_DQ<16>")
	)
	(segment
		(start 137.4902 -273.280378)
		(end 137.77468 -273.280378)
		(width 0.088646)
		(layer "F.Cu")
		(net "M_E_CPU1_SA_DQ<16>")
	)
	(segment
		(start 138.10107 -273.496278)
		(end 138.609578 -273.285712)
		(width 0.088646)
		(layer "F.Cu")
		(net "M_E_CPU1_SA_DQ<16>")
	)
	(segment
		(start 164.72789 -297.616626)
		(end 164.291518 -297.180254)
		(width 0.20066)
		(layer "F.Cu")
		(net "M_E_CPU1_SA_DQ<16>")
	)
	(segment
		(start 161.245804 -297.677332)
		(end 161.057844 -297.865292)
		(width 0.20066)
		(layer "F.Cu")
		(net "M_E_CPU1_SA_DQ<16>")
	)
	(segment
		(start 156.56306 -300.373542)
		(end 156.899864 -300.036738)
		(width 0.20066)
		(layer "F.Cu")
		(net "M_E_CPU1_SA_DQ<16>")
	)
	(segment
		(start 143.08455 -290.379912)
		(end 143.468344 -292.30828)
		(width 0.1016)
		(layer "F.Cu")
		(net "M_E_CPU1_SA_DQ<16>")
	)
	(segment
		(start 155.53309 -301.186088)
		(end 155.81757 -301.186088)
		(width 0.20066)
		(layer "F.Cu")
		(net "M_E_CPU1_SA_DQ<16>")
	)
	(segment
		(start 137.124694 -272.917158)
		(end 137.12698 -272.917158)
		(width 0.088646)
		(layer "F.Cu")
		(net "M_E_CPU1_SA_DQ<16>")
	)
	(segment
		(start 164.291518 -297.180254)
		(end 163.923726 -297.180254)
		(width 0.20066)
		(layer "F.Cu")
		(net "M_E_CPU1_SA_DQ<16>")
	)
	(segment
		(start 153.47569 -300.373542)
		(end 153.76017 -300.373542)
		(width 0.20066)
		(layer "F.Cu")
		(net "M_E_CPU1_SA_DQ<16>")
	)
	(segment
		(start 156.01823 -300.985428)
		(end 156.01823 -300.574202)
		(width 0.20066)
		(layer "F.Cu")
		(net "M_E_CPU1_SA_DQ<16>")
	)
	(segment
		(start 161.909252 -297.184318)
		(end 161.891726 -297.184318)
		(width 0.101854)
		(layer "F.Cu")
		(net "M_E_CPU1_SA_DQ<16>")
	)
	(segment
		(start 155.33243 -300.574202)
		(end 155.33243 -300.985428)
		(width 0.20066)
		(layer "F.Cu")
		(net "M_E_CPU1_SA_DQ<16>")
	)
	(segment
		(start 154.64663 -300.574202)
		(end 154.84729 -300.373542)
		(width 0.20066)
		(layer "F.Cu")
		(net "M_E_CPU1_SA_DQ<16>")
	)
	(segment
		(start 153.76017 -300.373542)
		(end 153.96083 -300.574202)
		(width 0.20066)
		(layer "F.Cu")
		(net "M_E_CPU1_SA_DQ<16>")
	)
	(segment
		(start 153.27503 -300.574202)
		(end 153.47569 -300.373542)
		(width 0.20066)
		(layer "F.Cu")
		(net "M_E_CPU1_SA_DQ<16>")
	)
	(segment
		(start 152.78989 -301.186088)
		(end 153.07437 -301.186088)
		(width 0.20066)
		(layer "F.Cu")
		(net "M_E_CPU1_SA_DQ<16>")
	)
	(segment
		(start 163.923726 -297.180254)
		(end 163.912296 -297.191684)
		(width 0.101854)
		(layer "F.Cu")
		(net "M_E_CPU1_SA_DQ<16>")
	)
	(segment
		(start 161.456116 -297.184318)
		(end 161.245804 -297.39463)
		(width 0.20066)
		(layer "F.Cu")
		(net "M_E_CPU1_SA_DQ<16>")
	)
	(segment
		(start 137.12698 -272.917158)
		(end 137.4902 -273.280378)
		(width 0.088646)
		(layer "F.Cu")
		(net "M_E_CPU1_SA_DQ<16>")
	)
	(segment
		(start 161.245804 -297.39463)
		(end 161.245804 -297.677332)
		(width 0.20066)
		(layer "F.Cu")
		(net "M_E_CPU1_SA_DQ<16>")
	)
	(segment
		(start 153.07437 -301.186088)
		(end 153.27503 -300.985428)
		(width 0.20066)
		(layer "F.Cu")
		(net "M_E_CPU1_SA_DQ<16>")
	)
	(segment
		(start 137.99058 -273.496278)
		(end 138.10107 -273.496278)
		(width 0.088646)
		(layer "F.Cu")
		(net "M_E_CPU1_SA_DQ<16>")
	)
	(segment
		(start 154.84729 -300.373542)
		(end 155.13177 -300.373542)
		(width 0.20066)
		(layer "F.Cu")
		(net "M_E_CPU1_SA_DQ<16>")
	)
	(segment
		(start 140.674344 -274.431252)
		(end 142.170658 -275.927566)
		(width 0.1016)
		(layer "F.Cu")
		(net "M_E_CPU1_SA_DQ<16>")
	)
	(segment
		(start 169.135552 -298.466764)
		(end 168.883584 -298.214796)
		(width 0.20066)
		(layer "F.Cu")
		(net "M_E_CPU1_SA_DQ<15>")
	)
	(segment
		(start 165.352984 -298.899072)
		(end 165.335458 -298.899072)
		(width 0.101854)
		(layer "F.Cu")
		(net "M_E_CPU1_SA_DQ<15>")
	)
	(segment
		(start 167.356028 -298.891706)
		(end 166.558214 -298.891706)
		(width 0.101854)
		(layer "F.Cu")
		(net "M_E_CPU1_SA_DQ<15>")
	)
	(segment
		(start 165.335458 -298.899072)
		(end 165.072822 -298.899072)
		(width 0.20066)
		(layer "F.Cu")
		(net "M_E_CPU1_SA_DQ<15>")
	)
	(segment
		(start 161.783014 -298.466764)
		(end 162.913314 -298.466764)
		(width 0.20066)
		(layer "F.Cu")
		(net "M_E_CPU1_SA_DQ<15>")
	)
	(segment
		(start 168.499536 -298.214796)
		(end 168.265348 -298.448984)
		(width 0.20066)
		(layer "F.Cu")
		(net "M_E_CPU1_SA_DQ<15>")
	)
	(segment
		(start 167.367458 -298.903136)
		(end 167.356028 -298.891706)
		(width 0.101854)
		(layer "F.Cu")
		(net "M_E_CPU1_SA_DQ<15>")
	)
	(segment
		(start 168.883584 -298.214796)
		(end 168.499536 -298.214796)
		(width 0.20066)
		(layer "F.Cu")
		(net "M_E_CPU1_SA_DQ<15>")
	)
	(segment
		(start 134.775448 -270.475456)
		(end 134.775448 -271.011142)
		(width 0.20066)
		(layer "F.Cu")
		(net "M_E_CPU1_SA_DQ<15>")
	)
	(segment
		(start 164.640514 -298.466764)
		(end 162.913314 -298.466764)
		(width 0.20066)
		(layer "F.Cu")
		(net "M_E_CPU1_SA_DQ<15>")
	)
	(segment
		(start 168.265348 -298.448984)
		(end 168.265348 -298.727368)
		(width 0.20066)
		(layer "F.Cu")
		(net "M_E_CPU1_SA_DQ<15>")
	)
	(segment
		(start 168.265348 -298.727368)
		(end 168.08958 -298.903136)
		(width 0.20066)
		(layer "F.Cu")
		(net "M_E_CPU1_SA_DQ<15>")
	)
	(segment
		(start 170.457114 -298.466764)
		(end 169.135552 -298.466764)
		(width 0.20066)
		(layer "F.Cu")
		(net "M_E_CPU1_SA_DQ<15>")
	)
	(segment
		(start 165.072822 -298.899072)
		(end 164.640514 -298.466764)
		(width 0.20066)
		(layer "F.Cu")
		(net "M_E_CPU1_SA_DQ<15>")
	)
	(segment
		(start 166.558214 -298.891706)
		(end 165.36035 -298.891706)
		(width 0.1016)
		(layer "F.Cu")
		(net "M_E_CPU1_SA_DQ<15>")
	)
	(segment
		(start 165.36035 -298.891706)
		(end 165.352984 -298.899072)
		(width 0.1016)
		(layer "F.Cu")
		(net "M_E_CPU1_SA_DQ<15>")
	)
	(segment
		(start 168.08958 -298.903136)
		(end 167.367458 -298.903136)
		(width 0.20066)
		(layer "F.Cu")
		(net "M_E_CPU1_SA_DQ<15>")
	)
	(segment
		(start 134.775448 -271.011142)
		(end 134.775194 -271.011396)
		(width 0.20066)
		(layer "F.Cu")
		(net "M_E_CPU1_SA_DQ<15>")
	)
	(segment
		(start 161.2646 -297.7515)
		(end 161.071814 -297.558206)
		(width 0.18288)
		(layer "In2.Cu")
		(net "M_E_CPU1_SA_DQ<15>")
	)
	(segment
		(start 161.783014 -298.466764)
		(end 161.2646 -297.948096)
		(width 0.18288)
		(layer "In2.Cu")
		(net "M_E_CPU1_SA_DQ<15>")
	)
	(segment
		(start 138.995404 -270.565372)
		(end 138.933936 -270.565372)
		(width 0.088646)
		(layer "In2.Cu")
		(net "M_E_CPU1_SA_DQ<15>")
	)
	(segment
		(start 160.41116 -295.39057)
		(end 160.6042 -295.19753)
		(width 0.18288)
		(layer "In2.Cu")
		(net "M_E_CPU1_SA_DQ<15>")
	)
	(segment
		(start 138.266678 -270.513302)
		(end 138.251946 -270.521938)
		(width 0.088646)
		(layer "In2.Cu")
		(net "M_E_CPU1_SA_DQ<15>")
	)
	(segment
		(start 152.363424 -285.046166)
		(end 152.363424 -283.251656)
		(width 0.18288)
		(layer "In2.Cu")
		(net "M_E_CPU1_SA_DQ<15>")
	)
	(segment
		(start 161.264854 -294.594026)
		(end 160.87217 -294.201342)
		(width 0.18288)
		(layer "In2.Cu")
		(net "M_E_CPU1_SA_DQ<15>")
	)
	(segment
		(start 158.937198 -292.26637)
		(end 158.06928 -292.26637)
		(width 0.18288)
		(layer "In2.Cu")
		(net "M_E_CPU1_SA_DQ<15>")
	)
	(segment
		(start 134.462266 -271.011396)
		(end 134.775194 -271.011396)
		(width 0.088646)
		(layer "In2.Cu")
		(net "M_E_CPU1_SA_DQ<15>")
	)
	(segment
		(start 152.983438 -286.54375)
		(end 152.363424 -285.046166)
		(width 0.18288)
		(layer "In2.Cu")
		(net "M_E_CPU1_SA_DQ<15>")
	)
	(segment
		(start 161.358072 -296.182288)
		(end 161.158428 -295.982644)
		(width 0.18288)
		(layer "In2.Cu")
		(net "M_E_CPU1_SA_DQ<15>")
	)
	(segment
		(start 157.65907 -291.85616)
		(end 157.409388 -291.253672)
		(width 0.18288)
		(layer "In2.Cu")
		(net "M_E_CPU1_SA_DQ<15>")
	)
	(segment
		(start 156.96692 -290.957762)
		(end 156.663136 -290.223448)
		(width 0.18288)
		(layer "In2.Cu")
		(net "M_E_CPU1_SA_DQ<15>")
	)
	(segment
		(start 160.41116 -295.789604)
		(end 160.41116 -295.39057)
		(width 0.18288)
		(layer "In2.Cu")
		(net "M_E_CPU1_SA_DQ<15>")
	)
	(segment
		(start 158.06928 -292.26637)
		(end 157.65907 -291.85616)
		(width 0.18288)
		(layer "In2.Cu")
		(net "M_E_CPU1_SA_DQ<15>")
	)
	(segment
		(start 160.6042 -295.982644)
		(end 160.41116 -295.789604)
		(width 0.18288)
		(layer "In2.Cu")
		(net "M_E_CPU1_SA_DQ<15>")
	)
	(segment
		(start 160.704022 -296.745914)
		(end 161.165032 -296.745914)
		(width 0.18288)
		(layer "In2.Cu")
		(net "M_E_CPU1_SA_DQ<15>")
	)
	(segment
		(start 152.363424 -283.251656)
		(end 147.677632 -278.565864)
		(width 0.18288)
		(layer "In2.Cu")
		(net "M_E_CPU1_SA_DQ<15>")
	)
	(segment
		(start 160.264094 -294.201342)
		(end 160.0708 -294.008048)
		(width 0.18288)
		(layer "In2.Cu")
		(net "M_E_CPU1_SA_DQ<15>")
	)
	(segment
		(start 147.677632 -278.565864)
		(end 146.51355 -275.755862)
		(width 0.18288)
		(layer "In2.Cu")
		(net "M_E_CPU1_SA_DQ<15>")
	)
	(segment
		(start 136.387078 -270.513302)
		(end 136.372346 -270.521938)
		(width 0.088646)
		(layer "In2.Cu")
		(net "M_E_CPU1_SA_DQ<15>")
	)
	(segment
		(start 161.358072 -296.552874)
		(end 161.358072 -296.182288)
		(width 0.18288)
		(layer "In2.Cu")
		(net "M_E_CPU1_SA_DQ<15>")
	)
	(segment
		(start 139.281408 -270.851376)
		(end 138.995404 -270.565372)
		(width 0.088646)
		(layer "In2.Cu")
		(net "M_E_CPU1_SA_DQ<15>")
	)
	(segment
		(start 161.158428 -295.982644)
		(end 160.6042 -295.982644)
		(width 0.18288)
		(layer "In2.Cu")
		(net "M_E_CPU1_SA_DQ<15>")
	)
	(segment
		(start 146.51355 -275.755862)
		(end 141.803374 -271.045686)
		(width 0.18288)
		(layer "In2.Cu")
		(net "M_E_CPU1_SA_DQ<15>")
	)
	(segment
		(start 160.544002 -297.365166)
		(end 160.544002 -296.905934)
		(width 0.18288)
		(layer "In2.Cu")
		(net "M_E_CPU1_SA_DQ<15>")
	)
	(segment
		(start 140.900404 -271.045686)
		(end 140.221716 -271.045686)
		(width 0.088646)
		(layer "In2.Cu")
		(net "M_E_CPU1_SA_DQ<15>")
	)
	(segment
		(start 160.87217 -294.201342)
		(end 160.264094 -294.201342)
		(width 0.18288)
		(layer "In2.Cu")
		(net "M_E_CPU1_SA_DQ<15>")
	)
	(segment
		(start 135.447278 -270.513302)
		(end 135.432546 -270.521938)
		(width 0.088646)
		(layer "In2.Cu")
		(net "M_E_CPU1_SA_DQ<15>")
	)
	(segment
		(start 160.737042 -297.558206)
		(end 160.544002 -297.365166)
		(width 0.18288)
		(layer "In2.Cu")
		(net "M_E_CPU1_SA_DQ<15>")
	)
	(segment
		(start 137.326878 -270.513302)
		(end 137.312146 -270.521938)
		(width 0.088646)
		(layer "In2.Cu")
		(net "M_E_CPU1_SA_DQ<15>")
	)
	(segment
		(start 160.6042 -295.19753)
		(end 161.071814 -295.19753)
		(width 0.18288)
		(layer "In2.Cu")
		(net "M_E_CPU1_SA_DQ<15>")
	)
	(segment
		(start 161.165032 -296.745914)
		(end 161.358072 -296.552874)
		(width 0.18288)
		(layer "In2.Cu")
		(net "M_E_CPU1_SA_DQ<15>")
	)
	(segment
		(start 135.432546 -270.521938)
		(end 135.42645 -270.525494)
		(width 0.088646)
		(layer "In2.Cu")
		(net "M_E_CPU1_SA_DQ<15>")
	)
	(segment
		(start 161.071814 -295.19753)
		(end 161.264854 -295.00449)
		(width 0.18288)
		(layer "In2.Cu")
		(net "M_E_CPU1_SA_DQ<15>")
	)
	(segment
		(start 161.264854 -295.00449)
		(end 161.264854 -294.594026)
		(width 0.18288)
		(layer "In2.Cu")
		(net "M_E_CPU1_SA_DQ<15>")
	)
	(segment
		(start 157.409388 -291.253672)
		(end 156.96692 -290.957762)
		(width 0.18288)
		(layer "In2.Cu")
		(net "M_E_CPU1_SA_DQ<15>")
	)
	(segment
		(start 161.071814 -297.558206)
		(end 160.737042 -297.558206)
		(width 0.18288)
		(layer "In2.Cu")
		(net "M_E_CPU1_SA_DQ<15>")
	)
	(segment
		(start 140.027406 -270.851376)
		(end 139.281408 -270.851376)
		(width 0.088646)
		(layer "In2.Cu")
		(net "M_E_CPU1_SA_DQ<15>")
	)
	(segment
		(start 160.0708 -293.399972)
		(end 158.937198 -292.26637)
		(width 0.18288)
		(layer "In2.Cu")
		(net "M_E_CPU1_SA_DQ<15>")
	)
	(segment
		(start 160.0708 -294.008048)
		(end 160.0708 -293.399972)
		(width 0.18288)
		(layer "In2.Cu")
		(net "M_E_CPU1_SA_DQ<15>")
	)
	(segment
		(start 134.405116 -271.068546)
		(end 134.462266 -271.011396)
		(width 0.088646)
		(layer "In2.Cu")
		(net "M_E_CPU1_SA_DQ<15>")
	)
	(segment
		(start 156.663136 -290.223448)
		(end 152.983438 -286.54375)
		(width 0.18288)
		(layer "In2.Cu")
		(net "M_E_CPU1_SA_DQ<15>")
	)
	(segment
		(start 160.544002 -296.905934)
		(end 160.704022 -296.745914)
		(width 0.18288)
		(layer "In2.Cu")
		(net "M_E_CPU1_SA_DQ<15>")
	)
	(segment
		(start 134.587996 -271.335754)
		(end 134.579106 -271.330674)
		(width 0.088646)
		(layer "In2.Cu")
		(net "M_E_CPU1_SA_DQ<15>")
	)
	(segment
		(start 141.803374 -271.045686)
		(end 140.900404 -271.045686)
		(width 0.18288)
		(layer "In2.Cu")
		(net "M_E_CPU1_SA_DQ<15>")
	)
	(segment
		(start 161.2646 -297.948096)
		(end 161.2646 -297.7515)
		(width 0.18288)
		(layer "In2.Cu")
		(net "M_E_CPU1_SA_DQ<15>")
	)
	(segment
		(start 140.221716 -271.045686)
		(end 140.027406 -270.851376)
		(width 0.088646)
		(layer "In2.Cu")
		(net "M_E_CPU1_SA_DQ<15>")
	)
	(segment
		(start 134.971282 -271.330674)
		(end 134.962392 -271.335754)
		(width 0.088646)
		(layer "In2.Cu")
		(net "M_E_CPU1_SA_DQ<15>")
	)
	(arc
		(start 138.251946 -270.521938)
		(mid 138.064748 -270.572081)
		(end 137.87755 -270.521938)
		(width 0.088646)
		(layer "In2.Cu")
		(net "M_E_CPU1_SA_DQ<15>")
	)
	(arc
		(start 136.372346 -270.521938)
		(mid 136.185148 -270.572081)
		(end 135.99795 -270.521938)
		(width 0.088646)
		(layer "In2.Cu")
		(net "M_E_CPU1_SA_DQ<15>")
	)
	(arc
		(start 138.81735 -270.521938)
		(mid 138.543151 -270.446103)
		(end 138.266678 -270.513302)
		(width 0.088646)
		(layer "In2.Cu")
		(net "M_E_CPU1_SA_DQ<15>")
	)
	(arc
		(start 135.149844 -271.011396)
		(mid 135.102165 -271.194296)
		(end 134.971282 -271.330674)
		(width 0.088646)
		(layer "In2.Cu")
		(net "M_E_CPU1_SA_DQ<15>")
	)
	(arc
		(start 137.312146 -270.521938)
		(mid 137.124948 -270.572081)
		(end 136.93775 -270.521938)
		(width 0.088646)
		(layer "In2.Cu")
		(net "M_E_CPU1_SA_DQ<15>")
	)
	(arc
		(start 137.87755 -270.521938)
		(mid 137.603351 -270.446103)
		(end 137.326878 -270.513302)
		(width 0.088646)
		(layer "In2.Cu")
		(net "M_E_CPU1_SA_DQ<15>")
	)
	(arc
		(start 138.933936 -270.565372)
		(mid 138.873825 -270.548534)
		(end 138.81735 -270.521938)
		(width 0.088646)
		(layer "In2.Cu")
		(net "M_E_CPU1_SA_DQ<15>")
	)
	(arc
		(start 135.99795 -270.521938)
		(mid 135.723751 -270.446103)
		(end 135.447278 -270.513302)
		(width 0.088646)
		(layer "In2.Cu")
		(net "M_E_CPU1_SA_DQ<15>")
	)
	(arc
		(start 134.579106 -271.330674)
		(mid 134.463297 -271.218745)
		(end 134.405116 -271.068546)
		(width 0.088646)
		(layer "In2.Cu")
		(net "M_E_CPU1_SA_DQ<15>")
	)
	(arc
		(start 135.42645 -270.525494)
		(mid 135.223863 -270.731845)
		(end 135.149844 -271.011396)
		(width 0.088646)
		(layer "In2.Cu")
		(net "M_E_CPU1_SA_DQ<15>")
	)
	(arc
		(start 134.962392 -271.335754)
		(mid 134.775194 -271.385897)
		(end 134.587996 -271.335754)
		(width 0.088646)
		(layer "In2.Cu")
		(net "M_E_CPU1_SA_DQ<15>")
	)
	(arc
		(start 136.93775 -270.521938)
		(mid 136.663551 -270.446103)
		(end 136.387078 -270.513302)
		(width 0.088646)
		(layer "In2.Cu")
		(net "M_E_CPU1_SA_DQ<15>")
	)
	(segment
		(start 170.457114 -300.166786)
		(end 169.135552 -300.166786)
		(width 0.20066)
		(layer "F.Cu")
		(net "M_E_CPU1_SA_DQ<14>")
	)
	(segment
		(start 164.930836 -300.597316)
		(end 164.500306 -300.166786)
		(width 0.20066)
		(layer "F.Cu")
		(net "M_E_CPU1_SA_DQ<14>")
	)
	(segment
		(start 168.265348 -300.40072)
		(end 168.064688 -300.60138)
		(width 0.20066)
		(layer "F.Cu")
		(net "M_E_CPU1_SA_DQ<14>")
	)
	(segment
		(start 168.883584 -299.914818)
		(end 168.499536 -299.914818)
		(width 0.20066)
		(layer "F.Cu")
		(net "M_E_CPU1_SA_DQ<14>")
	)
	(segment
		(start 166.751 -300.591728)
		(end 165.358572 -300.591728)
		(width 0.1016)
		(layer "F.Cu")
		(net "M_E_CPU1_SA_DQ<14>")
	)
	(segment
		(start 168.064688 -300.60138)
		(end 167.367458 -300.60138)
		(width 0.20066)
		(layer "F.Cu")
		(net "M_E_CPU1_SA_DQ<14>")
	)
	(segment
		(start 169.135552 -300.166786)
		(end 168.883584 -299.914818)
		(width 0.20066)
		(layer "F.Cu")
		(net "M_E_CPU1_SA_DQ<14>")
	)
	(segment
		(start 165.358572 -300.591728)
		(end 165.352984 -300.597316)
		(width 0.1016)
		(layer "F.Cu")
		(net "M_E_CPU1_SA_DQ<14>")
	)
	(segment
		(start 167.357806 -300.591728)
		(end 166.751 -300.591728)
		(width 0.101854)
		(layer "F.Cu")
		(net "M_E_CPU1_SA_DQ<14>")
	)
	(segment
		(start 167.367458 -300.60138)
		(end 167.357806 -300.591728)
		(width 0.101854)
		(layer "F.Cu")
		(net "M_E_CPU1_SA_DQ<14>")
	)
	(segment
		(start 168.265348 -300.149006)
		(end 168.265348 -300.40072)
		(width 0.20066)
		(layer "F.Cu")
		(net "M_E_CPU1_SA_DQ<14>")
	)
	(segment
		(start 168.499536 -299.914818)
		(end 168.265348 -300.149006)
		(width 0.20066)
		(layer "F.Cu")
		(net "M_E_CPU1_SA_DQ<14>")
	)
	(segment
		(start 165.335458 -300.597316)
		(end 164.930836 -300.597316)
		(width 0.20066)
		(layer "F.Cu")
		(net "M_E_CPU1_SA_DQ<14>")
	)
	(segment
		(start 135.245094 -271.289272)
		(end 135.245348 -271.825212)
		(width 0.20066)
		(layer "F.Cu")
		(net "M_E_CPU1_SA_DQ<14>")
	)
	(segment
		(start 165.352984 -300.597316)
		(end 165.335458 -300.597316)
		(width 0.101854)
		(layer "F.Cu")
		(net "M_E_CPU1_SA_DQ<14>")
	)
	(segment
		(start 164.500306 -300.166786)
		(end 162.913314 -300.166786)
		(width 0.20066)
		(layer "F.Cu")
		(net "M_E_CPU1_SA_DQ<14>")
	)
	(segment
		(start 161.783014 -300.166786)
		(end 162.913314 -300.166786)
		(width 0.20066)
		(layer "F.Cu")
		(net "M_E_CPU1_SA_DQ<14>")
	)
	(segment
		(start 139.79779 -271.34058)
		(end 139.295378 -271.34058)
		(width 0.088646)
		(layer "In2.Cu")
		(net "M_E_CPU1_SA_DQ<14>")
	)
	(segment
		(start 158.198312 -299.739558)
		(end 157.354524 -299.739558)
		(width 0.18288)
		(layer "In2.Cu")
		(net "M_E_CPU1_SA_DQ<14>")
	)
	(segment
		(start 156.797248 -292.982904)
		(end 156.33827 -291.87521)
		(width 0.18288)
		(layer "In2.Cu")
		(net "M_E_CPU1_SA_DQ<14>")
	)
	(segment
		(start 161.282126 -300.006766)
		(end 161.282126 -298.870116)
		(width 0.18288)
		(layer "In2.Cu")
		(net "M_E_CPU1_SA_DQ<14>")
	)
	(segment
		(start 158.358332 -299.899578)
		(end 158.198312 -299.739558)
		(width 0.18288)
		(layer "In2.Cu")
		(net "M_E_CPU1_SA_DQ<14>")
	)
	(segment
		(start 155.748482 -290.759896)
		(end 152.016968 -287.028382)
		(width 0.18288)
		(layer "In2.Cu")
		(net "M_E_CPU1_SA_DQ<14>")
	)
	(segment
		(start 140.341096 -271.883886)
		(end 139.79779 -271.34058)
		(width 0.088646)
		(layer "In2.Cu")
		(net "M_E_CPU1_SA_DQ<14>")
	)
	(segment
		(start 157.354524 -299.739558)
		(end 157.158182 -299.543216)
		(width 0.18288)
		(layer "In2.Cu")
		(net "M_E_CPU1_SA_DQ<14>")
	)
	(segment
		(start 159.211264 -300.237652)
		(end 158.518352 -300.237652)
		(width 0.18288)
		(layer "In2.Cu")
		(net "M_E_CPU1_SA_DQ<14>")
	)
	(segment
		(start 161.783014 -300.166786)
		(end 161.442146 -300.166786)
		(width 0.18288)
		(layer "In2.Cu")
		(net "M_E_CPU1_SA_DQ<14>")
	)
	(segment
		(start 135.873744 -271.35201)
		(end 135.245348 -271.825212)
		(width 0.088646)
		(layer "In2.Cu")
		(net "M_E_CPU1_SA_DQ<14>")
	)
	(segment
		(start 161.282126 -298.870116)
		(end 161.122106 -298.710096)
		(width 0.18288)
		(layer "In2.Cu")
		(net "M_E_CPU1_SA_DQ<14>")
	)
	(segment
		(start 157.158182 -299.543216)
		(end 157.158182 -294.823388)
		(width 0.18288)
		(layer "In2.Cu")
		(net "M_E_CPU1_SA_DQ<14>")
	)
	(segment
		(start 159.834072 -299.161708)
		(end 159.834072 -299.614844)
		(width 0.18288)
		(layer "In2.Cu")
		(net "M_E_CPU1_SA_DQ<14>")
	)
	(segment
		(start 160.285684 -298.710096)
		(end 159.834072 -299.161708)
		(width 0.18288)
		(layer "In2.Cu")
		(net "M_E_CPU1_SA_DQ<14>")
	)
	(segment
		(start 151.347424 -285.411926)
		(end 151.347424 -283.252164)
		(width 0.18288)
		(layer "In2.Cu")
		(net "M_E_CPU1_SA_DQ<14>")
	)
	(segment
		(start 158.518352 -300.237652)
		(end 158.358332 -300.077632)
		(width 0.18288)
		(layer "In2.Cu")
		(net "M_E_CPU1_SA_DQ<14>")
	)
	(segment
		(start 139.286996 -271.335754)
		(end 139.272264 -271.327118)
		(width 0.088646)
		(layer "In2.Cu")
		(net "M_E_CPU1_SA_DQ<14>")
	)
	(segment
		(start 141.664182 -271.883886)
		(end 140.900404 -271.883886)
		(width 0.18288)
		(layer "In2.Cu")
		(net "M_E_CPU1_SA_DQ<14>")
	)
	(segment
		(start 136.467596 -271.335754)
		(end 136.467342 -271.335754)
		(width 0.088646)
		(layer "In2.Cu")
		(net "M_E_CPU1_SA_DQ<14>")
	)
	(segment
		(start 156.33827 -291.87521)
		(end 156.120084 -291.657024)
		(width 0.18288)
		(layer "In2.Cu")
		(net "M_E_CPU1_SA_DQ<14>")
	)
	(segment
		(start 140.900404 -271.883886)
		(end 140.341096 -271.883886)
		(width 0.088646)
		(layer "In2.Cu")
		(net "M_E_CPU1_SA_DQ<14>")
	)
	(segment
		(start 147.077938 -278.982678)
		(end 145.886678 -276.106382)
		(width 0.18288)
		(layer "In2.Cu")
		(net "M_E_CPU1_SA_DQ<14>")
	)
	(segment
		(start 145.886678 -276.106382)
		(end 141.664182 -271.883886)
		(width 0.18288)
		(layer "In2.Cu")
		(net "M_E_CPU1_SA_DQ<14>")
	)
	(segment
		(start 159.834072 -299.614844)
		(end 159.211264 -300.237652)
		(width 0.18288)
		(layer "In2.Cu")
		(net "M_E_CPU1_SA_DQ<14>")
	)
	(segment
		(start 135.902446 -271.335754)
		(end 135.873744 -271.35201)
		(width 0.088646)
		(layer "In2.Cu")
		(net "M_E_CPU1_SA_DQ<14>")
	)
	(segment
		(start 156.120084 -291.657024)
		(end 155.748482 -290.759896)
		(width 0.18288)
		(layer "In2.Cu")
		(net "M_E_CPU1_SA_DQ<14>")
	)
	(segment
		(start 151.347424 -283.252164)
		(end 147.077938 -278.982678)
		(width 0.18288)
		(layer "In2.Cu")
		(net "M_E_CPU1_SA_DQ<14>")
	)
	(segment
		(start 139.295378 -271.34058)
		(end 139.286996 -271.335754)
		(width 0.088646)
		(layer "In2.Cu")
		(net "M_E_CPU1_SA_DQ<14>")
	)
	(segment
		(start 157.427422 -294.554148)
		(end 157.427422 -293.613078)
		(width 0.18288)
		(layer "In2.Cu")
		(net "M_E_CPU1_SA_DQ<14>")
	)
	(segment
		(start 157.427422 -293.613078)
		(end 156.797248 -292.982904)
		(width 0.18288)
		(layer "In2.Cu")
		(net "M_E_CPU1_SA_DQ<14>")
	)
	(segment
		(start 138.347196 -271.335754)
		(end 138.332464 -271.327118)
		(width 0.088646)
		(layer "In2.Cu")
		(net "M_E_CPU1_SA_DQ<14>")
	)
	(segment
		(start 137.407396 -271.335754)
		(end 137.392664 -271.327118)
		(width 0.088646)
		(layer "In2.Cu")
		(net "M_E_CPU1_SA_DQ<14>")
	)
	(segment
		(start 158.358332 -300.077632)
		(end 158.358332 -299.899578)
		(width 0.18288)
		(layer "In2.Cu")
		(net "M_E_CPU1_SA_DQ<14>")
	)
	(segment
		(start 161.122106 -298.710096)
		(end 160.285684 -298.710096)
		(width 0.18288)
		(layer "In2.Cu")
		(net "M_E_CPU1_SA_DQ<14>")
	)
	(segment
		(start 161.442146 -300.166786)
		(end 161.282126 -300.006766)
		(width 0.18288)
		(layer "In2.Cu")
		(net "M_E_CPU1_SA_DQ<14>")
	)
	(segment
		(start 152.016968 -287.028382)
		(end 151.347424 -285.411926)
		(width 0.18288)
		(layer "In2.Cu")
		(net "M_E_CPU1_SA_DQ<14>")
	)
	(segment
		(start 157.158182 -294.823388)
		(end 157.427422 -294.554148)
		(width 0.18288)
		(layer "In2.Cu")
		(net "M_E_CPU1_SA_DQ<14>")
	)
	(arc
		(start 136.841992 -271.335754)
		(mid 136.654794 -271.385897)
		(end 136.467596 -271.335754)
		(width 0.088646)
		(layer "In2.Cu")
		(net "M_E_CPU1_SA_DQ<14>")
	)
	(arc
		(start 137.392664 -271.327118)
		(mid 137.116189 -271.259798)
		(end 136.841992 -271.335754)
		(width 0.088646)
		(layer "In2.Cu")
		(net "M_E_CPU1_SA_DQ<14>")
	)
	(arc
		(start 138.721592 -271.335754)
		(mid 138.534394 -271.385897)
		(end 138.347196 -271.335754)
		(width 0.088646)
		(layer "In2.Cu")
		(net "M_E_CPU1_SA_DQ<14>")
	)
	(arc
		(start 138.332464 -271.327118)
		(mid 138.055989 -271.259798)
		(end 137.781792 -271.335754)
		(width 0.088646)
		(layer "In2.Cu")
		(net "M_E_CPU1_SA_DQ<14>")
	)
	(arc
		(start 136.467342 -271.335754)
		(mid 136.184894 -271.260071)
		(end 135.902446 -271.335754)
		(width 0.088646)
		(layer "In2.Cu")
		(net "M_E_CPU1_SA_DQ<14>")
	)
	(arc
		(start 137.781792 -271.335754)
		(mid 137.594594 -271.385897)
		(end 137.407396 -271.335754)
		(width 0.088646)
		(layer "In2.Cu")
		(net "M_E_CPU1_SA_DQ<14>")
	)
	(arc
		(start 139.272264 -271.327118)
		(mid 138.995789 -271.259798)
		(end 138.721592 -271.335754)
		(width 0.088646)
		(layer "In2.Cu")
		(net "M_E_CPU1_SA_DQ<14>")
	)
	(segment
		(start 160.333944 -299.316648)
		(end 158.813246 -299.316648)
		(width 0.20066)
		(layer "F.Cu")
		(net "M_E_CPU1_SA_DQ<13>")
	)
	(segment
		(start 133.835648 -271.011142)
		(end 133.835394 -271.011396)
		(width 0.20066)
		(layer "F.Cu")
		(net "M_E_CPU1_SA_DQ<13>")
	)
	(segment
		(start 164.333682 -298.885356)
		(end 163.923726 -298.885356)
		(width 0.20066)
		(layer "F.Cu")
		(net "M_E_CPU1_SA_DQ<13>")
	)
	(segment
		(start 161.245804 -299.377354)
		(end 161.057844 -299.565314)
		(width 0.20066)
		(layer "F.Cu")
		(net "M_E_CPU1_SA_DQ<13>")
	)
	(segment
		(start 166.357046 -299.316648)
		(end 166.356792 -299.316902)
		(width 0.20066)
		(layer "F.Cu")
		(net "M_E_CPU1_SA_DQ<13>")
	)
	(segment
		(start 161.057844 -299.565314)
		(end 160.58261 -299.565314)
		(width 0.20066)
		(layer "F.Cu")
		(net "M_E_CPU1_SA_DQ<13>")
	)
	(segment
		(start 133.835648 -270.475456)
		(end 133.835648 -271.011142)
		(width 0.20066)
		(layer "F.Cu")
		(net "M_E_CPU1_SA_DQ<13>")
	)
	(segment
		(start 160.58261 -299.565314)
		(end 160.333944 -299.316648)
		(width 0.20066)
		(layer "F.Cu")
		(net "M_E_CPU1_SA_DQ<13>")
	)
	(segment
		(start 161.363914 -298.891706)
		(end 161.245804 -299.009816)
		(width 0.20066)
		(layer "F.Cu")
		(net "M_E_CPU1_SA_DQ<13>")
	)
	(segment
		(start 164.765228 -299.316902)
		(end 164.333682 -298.885356)
		(width 0.20066)
		(layer "F.Cu")
		(net "M_E_CPU1_SA_DQ<13>")
	)
	(segment
		(start 161.728658 -298.891706)
		(end 161.708592 -298.891706)
		(width 0.101854)
		(layer "F.Cu")
		(net "M_E_CPU1_SA_DQ<13>")
	)
	(segment
		(start 161.708592 -298.891706)
		(end 161.363914 -298.891706)
		(width 0.20066)
		(layer "F.Cu")
		(net "M_E_CPU1_SA_DQ<13>")
	)
	(segment
		(start 161.245804 -299.009816)
		(end 161.245804 -299.377354)
		(width 0.20066)
		(layer "F.Cu")
		(net "M_E_CPU1_SA_DQ<13>")
	)
	(segment
		(start 163.923726 -298.885356)
		(end 163.917376 -298.891706)
		(width 0.1016)
		(layer "F.Cu")
		(net "M_E_CPU1_SA_DQ<13>")
	)
	(segment
		(start 166.356792 -299.316902)
		(end 164.765228 -299.316902)
		(width 0.20066)
		(layer "F.Cu")
		(net "M_E_CPU1_SA_DQ<13>")
	)
	(segment
		(start 163.917376 -298.891706)
		(end 161.728658 -298.891706)
		(width 0.1016)
		(layer "F.Cu")
		(net "M_E_CPU1_SA_DQ<13>")
	)
	(segment
		(start 157.682946 -299.316648)
		(end 158.813246 -299.316648)
		(width 0.20066)
		(layer "F.Cu")
		(net "M_E_CPU1_SA_DQ<13>")
	)
	(segment
		(start 134.148322 -271.011396)
		(end 133.835394 -271.011396)
		(width 0.088646)
		(layer "In2.Cu")
		(net "M_E_CPU1_SA_DQ<13>")
	)
	(segment
		(start 158.168848 -296.565574)
		(end 157.803088 -296.199814)
		(width 0.18288)
		(layer "In2.Cu")
		(net "M_E_CPU1_SA_DQ<13>")
	)
	(segment
		(start 135.340344 -271.011396)
		(end 135.340344 -271.02689)
		(width 0.088646)
		(layer "In2.Cu")
		(net "M_E_CPU1_SA_DQ<13>")
	)
	(segment
		(start 152.501346 -286.788098)
		(end 151.855424 -285.228538)
		(width 0.18288)
		(layer "In2.Cu")
		(net "M_E_CPU1_SA_DQ<13>")
	)
	(segment
		(start 159.096202 -298.846494)
		(end 159.289242 -298.653454)
		(width 0.18288)
		(layer "In2.Cu")
		(net "M_E_CPU1_SA_DQ<13>")
	)
	(segment
		(start 158.499302 -298.604686)
		(end 158.74111 -298.846494)
		(width 0.18288)
		(layer "In2.Cu")
		(net "M_E_CPU1_SA_DQ<13>")
	)
	(segment
		(start 151.855424 -285.228538)
		(end 151.855424 -283.259276)
		(width 0.18288)
		(layer "In2.Cu")
		(net "M_E_CPU1_SA_DQ<13>")
	)
	(segment
		(start 135.527796 -270.687038)
		(end 135.518906 -270.692118)
		(width 0.088646)
		(layer "In2.Cu")
		(net "M_E_CPU1_SA_DQ<13>")
	)
	(segment
		(start 159.289242 -298.44746)
		(end 159.98571 -297.750992)
		(width 0.18288)
		(layer "In2.Cu")
		(net "M_E_CPU1_SA_DQ<13>")
	)
	(segment
		(start 151.855424 -283.259276)
		(end 147.362672 -278.766524)
		(width 0.18288)
		(layer "In2.Cu")
		(net "M_E_CPU1_SA_DQ<13>")
	)
	(segment
		(start 159.98571 -297.750992)
		(end 159.98571 -297.477942)
		(width 0.18288)
		(layer "In2.Cu")
		(net "M_E_CPU1_SA_DQ<13>")
	)
	(segment
		(start 157.802326 -299.028358)
		(end 158.225998 -298.604686)
		(width 0.18288)
		(layer "In2.Cu")
		(net "M_E_CPU1_SA_DQ<13>")
	)
	(segment
		(start 139.920472 -271.041622)
		(end 139.186666 -271.041622)
		(width 0.088646)
		(layer "In2.Cu")
		(net "M_E_CPU1_SA_DQ<13>")
	)
	(segment
		(start 158.361888 -297.077638)
		(end 158.168848 -296.884598)
		(width 0.18288)
		(layer "In2.Cu")
		(net "M_E_CPU1_SA_DQ<13>")
	)
	(segment
		(start 158.79191 -294.716708)
		(end 158.124398 -294.716708)
		(width 0.18288)
		(layer "In2.Cu")
		(net "M_E_CPU1_SA_DQ<13>")
	)
	(segment
		(start 140.320776 -271.441926)
		(end 139.920472 -271.041622)
		(width 0.088646)
		(layer "In2.Cu")
		(net "M_E_CPU1_SA_DQ<13>")
	)
	(segment
		(start 159.289242 -298.653454)
		(end 159.289242 -298.44746)
		(width 0.18288)
		(layer "In2.Cu")
		(net "M_E_CPU1_SA_DQ<13>")
	)
	(segment
		(start 134.213854 -271.076928)
		(end 134.148322 -271.011396)
		(width 0.088646)
		(layer "In2.Cu")
		(net "M_E_CPU1_SA_DQ<13>")
	)
	(segment
		(start 141.710918 -271.441926)
		(end 140.900404 -271.441926)
		(width 0.18288)
		(layer "In2.Cu")
		(net "M_E_CPU1_SA_DQ<13>")
	)
	(segment
		(start 157.241748 -292.702742)
		(end 156.744162 -291.501576)
		(width 0.18288)
		(layer "In2.Cu")
		(net "M_E_CPU1_SA_DQ<13>")
	)
	(segment
		(start 158.124398 -294.716708)
		(end 157.936184 -294.528494)
		(width 0.18288)
		(layer "In2.Cu")
		(net "M_E_CPU1_SA_DQ<13>")
	)
	(segment
		(start 139.186666 -271.041622)
		(end 138.897868 -270.752824)
		(width 0.088646)
		(layer "In2.Cu")
		(net "M_E_CPU1_SA_DQ<13>")
	)
	(segment
		(start 157.803088 -296.199814)
		(end 157.803088 -295.619424)
		(width 0.18288)
		(layer "In2.Cu")
		(net "M_E_CPU1_SA_DQ<13>")
	)
	(segment
		(start 158.74111 -298.846494)
		(end 159.096202 -298.846494)
		(width 0.18288)
		(layer "In2.Cu")
		(net "M_E_CPU1_SA_DQ<13>")
	)
	(segment
		(start 157.936184 -294.528494)
		(end 157.936184 -293.397178)
		(width 0.18288)
		(layer "In2.Cu")
		(net "M_E_CPU1_SA_DQ<13>")
	)
	(segment
		(start 134.507478 -271.50949)
		(end 134.492746 -271.500854)
		(width 0.088646)
		(layer "In2.Cu")
		(net "M_E_CPU1_SA_DQ<13>")
	)
	(segment
		(start 146.180048 -275.911056)
		(end 141.710918 -271.441926)
		(width 0.18288)
		(layer "In2.Cu")
		(net "M_E_CPU1_SA_DQ<13>")
	)
	(segment
		(start 156.532834 -291.290248)
		(end 156.200094 -290.486846)
		(width 0.18288)
		(layer "In2.Cu")
		(net "M_E_CPU1_SA_DQ<13>")
	)
	(segment
		(start 159.585406 -297.077638)
		(end 158.361888 -297.077638)
		(width 0.18288)
		(layer "In2.Cu")
		(net "M_E_CPU1_SA_DQ<13>")
	)
	(segment
		(start 158.225998 -298.604686)
		(end 158.499302 -298.604686)
		(width 0.18288)
		(layer "In2.Cu")
		(net "M_E_CPU1_SA_DQ<13>")
	)
	(segment
		(start 156.744162 -291.501576)
		(end 156.532834 -291.290248)
		(width 0.18288)
		(layer "In2.Cu")
		(net "M_E_CPU1_SA_DQ<13>")
	)
	(segment
		(start 134.492746 -271.500854)
		(end 134.48665 -271.497298)
		(width 0.088646)
		(layer "In2.Cu")
		(net "M_E_CPU1_SA_DQ<13>")
	)
	(segment
		(start 159.98571 -297.477942)
		(end 159.585406 -297.077638)
		(width 0.18288)
		(layer "In2.Cu")
		(net "M_E_CPU1_SA_DQ<13>")
	)
	(segment
		(start 156.200094 -290.486846)
		(end 152.501346 -286.788098)
		(width 0.18288)
		(layer "In2.Cu")
		(net "M_E_CPU1_SA_DQ<13>")
	)
	(segment
		(start 157.682946 -299.316648)
		(end 157.802326 -299.028358)
		(width 0.18288)
		(layer "In2.Cu")
		(net "M_E_CPU1_SA_DQ<13>")
	)
	(segment
		(start 147.362672 -278.766524)
		(end 146.180048 -275.911056)
		(width 0.18288)
		(layer "In2.Cu")
		(net "M_E_CPU1_SA_DQ<13>")
	)
	(segment
		(start 158.168848 -296.884598)
		(end 158.168848 -296.565574)
		(width 0.18288)
		(layer "In2.Cu")
		(net "M_E_CPU1_SA_DQ<13>")
	)
	(segment
		(start 140.900404 -271.441926)
		(end 140.320776 -271.441926)
		(width 0.088646)
		(layer "In2.Cu")
		(net "M_E_CPU1_SA_DQ<13>")
	)
	(segment
		(start 138.347196 -270.687038)
		(end 138.332464 -270.695674)
		(width 0.088646)
		(layer "In2.Cu")
		(net "M_E_CPU1_SA_DQ<13>")
	)
	(segment
		(start 137.407396 -270.687038)
		(end 137.392664 -270.695674)
		(width 0.088646)
		(layer "In2.Cu")
		(net "M_E_CPU1_SA_DQ<13>")
	)
	(segment
		(start 157.970982 -295.45153)
		(end 158.767272 -295.45153)
		(width 0.18288)
		(layer "In2.Cu")
		(net "M_E_CPU1_SA_DQ<13>")
	)
	(segment
		(start 157.936184 -293.397178)
		(end 157.241748 -292.702742)
		(width 0.18288)
		(layer "In2.Cu")
		(net "M_E_CPU1_SA_DQ<13>")
	)
	(segment
		(start 157.803088 -295.619424)
		(end 157.970982 -295.45153)
		(width 0.18288)
		(layer "In2.Cu")
		(net "M_E_CPU1_SA_DQ<13>")
	)
	(segment
		(start 158.960312 -294.88511)
		(end 158.79191 -294.716708)
		(width 0.18288)
		(layer "In2.Cu")
		(net "M_E_CPU1_SA_DQ<13>")
	)
	(segment
		(start 158.767272 -295.45153)
		(end 158.960312 -295.25849)
		(width 0.18288)
		(layer "In2.Cu")
		(net "M_E_CPU1_SA_DQ<13>")
	)
	(segment
		(start 136.467596 -270.687038)
		(end 136.452864 -270.695674)
		(width 0.088646)
		(layer "In2.Cu")
		(net "M_E_CPU1_SA_DQ<13>")
	)
	(segment
		(start 158.960312 -295.25849)
		(end 158.960312 -294.88511)
		(width 0.18288)
		(layer "In2.Cu")
		(net "M_E_CPU1_SA_DQ<13>")
	)
	(arc
		(start 135.902192 -270.687038)
		(mid 135.714994 -270.636895)
		(end 135.527796 -270.687038)
		(width 0.088646)
		(layer "In2.Cu")
		(net "M_E_CPU1_SA_DQ<13>")
	)
	(arc
		(start 135.05815 -271.500854)
		(mid 134.783951 -271.576689)
		(end 134.507478 -271.50949)
		(width 0.088646)
		(layer "In2.Cu")
		(net "M_E_CPU1_SA_DQ<13>")
	)
	(arc
		(start 134.48665 -271.497298)
		(mid 134.301127 -271.318997)
		(end 134.213854 -271.076928)
		(width 0.088646)
		(layer "In2.Cu")
		(net "M_E_CPU1_SA_DQ<13>")
	)
	(arc
		(start 135.518906 -270.692118)
		(mid 135.387992 -270.828478)
		(end 135.340344 -271.011396)
		(width 0.088646)
		(layer "In2.Cu")
		(net "M_E_CPU1_SA_DQ<13>")
	)
	(arc
		(start 137.392664 -270.695674)
		(mid 137.116189 -270.762994)
		(end 136.841992 -270.687038)
		(width 0.088646)
		(layer "In2.Cu")
		(net "M_E_CPU1_SA_DQ<13>")
	)
	(arc
		(start 136.841992 -270.687038)
		(mid 136.654794 -270.636895)
		(end 136.467596 -270.687038)
		(width 0.088646)
		(layer "In2.Cu")
		(net "M_E_CPU1_SA_DQ<13>")
	)
	(arc
		(start 138.897868 -270.752824)
		(mid 138.806966 -270.727333)
		(end 138.721592 -270.687038)
		(width 0.088646)
		(layer "In2.Cu")
		(net "M_E_CPU1_SA_DQ<13>")
	)
	(arc
		(start 135.340344 -271.02689)
		(mid 135.260974 -271.300624)
		(end 135.05815 -271.500854)
		(width 0.088646)
		(layer "In2.Cu")
		(net "M_E_CPU1_SA_DQ<13>")
	)
	(arc
		(start 136.452864 -270.695674)
		(mid 136.176389 -270.762994)
		(end 135.902192 -270.687038)
		(width 0.088646)
		(layer "In2.Cu")
		(net "M_E_CPU1_SA_DQ<13>")
	)
	(arc
		(start 137.781792 -270.687038)
		(mid 137.594594 -270.636895)
		(end 137.407396 -270.687038)
		(width 0.088646)
		(layer "In2.Cu")
		(net "M_E_CPU1_SA_DQ<13>")
	)
	(arc
		(start 138.721592 -270.687038)
		(mid 138.534394 -270.636895)
		(end 138.347196 -270.687038)
		(width 0.088646)
		(layer "In2.Cu")
		(net "M_E_CPU1_SA_DQ<13>")
	)
	(arc
		(start 138.332464 -270.695674)
		(mid 138.055989 -270.762994)
		(end 137.781792 -270.687038)
		(width 0.088646)
		(layer "In2.Cu")
		(net "M_E_CPU1_SA_DQ<13>")
	)
	(segment
		(start 160.333944 -301.01667)
		(end 158.813246 -301.01667)
		(width 0.20066)
		(layer "F.Cu")
		(net "M_E_CPU1_SA_DQ<12>")
	)
	(segment
		(start 161.755582 -300.591728)
		(end 161.708592 -300.591728)
		(width 0.101854)
		(layer "F.Cu")
		(net "M_E_CPU1_SA_DQ<12>")
	)
	(segment
		(start 133.365494 -271.289272)
		(end 133.365748 -271.825212)
		(width 0.20066)
		(layer "F.Cu")
		(net "M_E_CPU1_SA_DQ<12>")
	)
	(segment
		(start 161.708592 -300.591728)
		(end 161.363914 -300.591728)
		(width 0.20066)
		(layer "F.Cu")
		(net "M_E_CPU1_SA_DQ<12>")
	)
	(segment
		(start 163.917376 -300.591728)
		(end 161.755582 -300.591728)
		(width 0.1016)
		(layer "F.Cu")
		(net "M_E_CPU1_SA_DQ<12>")
	)
	(segment
		(start 164.765228 -301.016924)
		(end 164.333682 -300.585378)
		(width 0.20066)
		(layer "F.Cu")
		(net "M_E_CPU1_SA_DQ<12>")
	)
	(segment
		(start 166.356792 -301.016924)
		(end 164.765228 -301.016924)
		(width 0.20066)
		(layer "F.Cu")
		(net "M_E_CPU1_SA_DQ<12>")
	)
	(segment
		(start 161.245804 -301.077376)
		(end 161.057844 -301.265336)
		(width 0.20066)
		(layer "F.Cu")
		(net "M_E_CPU1_SA_DQ<12>")
	)
	(segment
		(start 161.363914 -300.591728)
		(end 161.245804 -300.709838)
		(width 0.20066)
		(layer "F.Cu")
		(net "M_E_CPU1_SA_DQ<12>")
	)
	(segment
		(start 161.245804 -300.709838)
		(end 161.245804 -301.077376)
		(width 0.20066)
		(layer "F.Cu")
		(net "M_E_CPU1_SA_DQ<12>")
	)
	(segment
		(start 163.923726 -300.585378)
		(end 163.917376 -300.591728)
		(width 0.1016)
		(layer "F.Cu")
		(net "M_E_CPU1_SA_DQ<12>")
	)
	(segment
		(start 160.58261 -301.265336)
		(end 160.333944 -301.01667)
		(width 0.20066)
		(layer "F.Cu")
		(net "M_E_CPU1_SA_DQ<12>")
	)
	(segment
		(start 164.333682 -300.585378)
		(end 163.923726 -300.585378)
		(width 0.20066)
		(layer "F.Cu")
		(net "M_E_CPU1_SA_DQ<12>")
	)
	(segment
		(start 166.357046 -301.01667)
		(end 166.356792 -301.016924)
		(width 0.20066)
		(layer "F.Cu")
		(net "M_E_CPU1_SA_DQ<12>")
	)
	(segment
		(start 161.057844 -301.265336)
		(end 160.58261 -301.265336)
		(width 0.20066)
		(layer "F.Cu")
		(net "M_E_CPU1_SA_DQ<12>")
	)
	(segment
		(start 157.682946 -301.01667)
		(end 158.813246 -301.01667)
		(width 0.20066)
		(layer "F.Cu")
		(net "M_E_CPU1_SA_DQ<12>")
	)
	(segment
		(start 155.402026 -292.4556)
		(end 155.150058 -292.350952)
		(width 0.18288)
		(layer "In2.Cu")
		(net "M_E_CPU1_SA_DQ<12>")
	)
	(segment
		(start 154.863038 -291.154612)
		(end 154.61107 -291.049964)
		(width 0.18288)
		(layer "In2.Cu")
		(net "M_E_CPU1_SA_DQ<12>")
	)
	(segment
		(start 135.99795 -271.500854)
		(end 135.997696 -271.501108)
		(width 0.088646)
		(layer "In2.Cu")
		(net "M_E_CPU1_SA_DQ<12>")
	)
	(segment
		(start 139.262612 -271.541748)
		(end 139.191746 -271.500854)
		(width 0.088646)
		(layer "In2.Cu")
		(net "M_E_CPU1_SA_DQ<12>")
	)
	(segment
		(start 150.839424 -283.239972)
		(end 146.790156 -279.190704)
		(width 0.18288)
		(layer "In2.Cu")
		(net "M_E_CPU1_SA_DQ<12>")
	)
	(segment
		(start 139.662916 -271.540986)
		(end 139.269216 -271.540986)
		(width 0.088646)
		(layer "In2.Cu")
		(net "M_E_CPU1_SA_DQ<12>")
	)
	(segment
		(start 138.266678 -271.50949)
		(end 138.251946 -271.500854)
		(width 0.088646)
		(layer "In2.Cu")
		(net "M_E_CPU1_SA_DQ<12>")
	)
	(segment
		(start 156.848048 -293.933372)
		(end 156.726382 -293.639748)
		(width 0.18288)
		(layer "In2.Cu")
		(net "M_E_CPU1_SA_DQ<12>")
	)
	(segment
		(start 135.432546 -272.149316)
		(end 135.432546 -272.14957)
		(width 0.088646)
		(layer "In2.Cu")
		(net "M_E_CPU1_SA_DQ<12>")
	)
	(segment
		(start 155.339034 -291.719254)
		(end 155.443682 -291.467286)
		(width 0.18288)
		(layer "In2.Cu")
		(net "M_E_CPU1_SA_DQ<12>")
	)
	(segment
		(start 139.269216 -271.540986)
		(end 139.262612 -271.541748)
		(width 0.088646)
		(layer "In2.Cu")
		(net "M_E_CPU1_SA_DQ<12>")
	)
	(segment
		(start 141.653006 -272.361406)
		(end 140.900658 -272.361406)
		(width 0.18288)
		(layer "In2.Cu")
		(net "M_E_CPU1_SA_DQ<12>")
	)
	(segment
		(start 155.132278 -291.805106)
		(end 155.339034 -291.719254)
		(width 0.18288)
		(layer "In2.Cu")
		(net "M_E_CPU1_SA_DQ<12>")
	)
	(segment
		(start 134.493 -272.14957)
		(end 134.492746 -272.14957)
		(width 0.088646)
		(layer "In2.Cu")
		(net "M_E_CPU1_SA_DQ<12>")
	)
	(segment
		(start 134.11835 -272.14957)
		(end 134.118096 -272.149824)
		(width 0.088646)
		(layer "In2.Cu")
		(net "M_E_CPU1_SA_DQ<12>")
	)
	(segment
		(start 155.941014 -293.756588)
		(end 155.689046 -293.65194)
		(width 0.18288)
		(layer "In2.Cu")
		(net "M_E_CPU1_SA_DQ<12>")
	)
	(segment
		(start 156.922978 -300.393354)
		(end 156.646118 -299.724826)
		(width 0.18288)
		(layer "In2.Cu")
		(net "M_E_CPU1_SA_DQ<12>")
	)
	(segment
		(start 134.118096 -272.149824)
		(end 134.088886 -272.132806)
		(width 0.088646)
		(layer "In2.Cu")
		(net "M_E_CPU1_SA_DQ<12>")
	)
	(segment
		(start 156.726382 -293.639748)
		(end 156.473906 -293.535354)
		(width 0.18288)
		(layer "In2.Cu")
		(net "M_E_CPU1_SA_DQ<12>")
	)
	(segment
		(start 156.29509 -295.115488)
		(end 156.10586 -294.65905)
		(width 0.18288)
		(layer "In2.Cu")
		(net "M_E_CPU1_SA_DQ<12>")
	)
	(segment
		(start 154.502866 -290.789106)
		(end 154.502866 -290.23945)
		(width 0.18288)
		(layer "In2.Cu")
		(net "M_E_CPU1_SA_DQ<12>")
	)
	(segment
		(start 135.828024 -271.690846)
		(end 135.561578 -272.057876)
		(width 0.088646)
		(layer "In2.Cu")
		(net "M_E_CPU1_SA_DQ<12>")
	)
	(segment
		(start 154.502866 -290.23945)
		(end 151.551894 -287.288478)
		(width 0.18288)
		(layer "In2.Cu")
		(net "M_E_CPU1_SA_DQ<12>")
	)
	(segment
		(start 156.473906 -293.535354)
		(end 155.941014 -293.756588)
		(width 0.18288)
		(layer "In2.Cu")
		(net "M_E_CPU1_SA_DQ<12>")
	)
	(segment
		(start 156.130244 -292.70706)
		(end 156.008324 -292.413182)
		(width 0.18288)
		(layer "In2.Cu")
		(net "M_E_CPU1_SA_DQ<12>")
	)
	(segment
		(start 156.646118 -295.466516)
		(end 156.29509 -295.115488)
		(width 0.18288)
		(layer "In2.Cu")
		(net "M_E_CPU1_SA_DQ<12>")
	)
	(segment
		(start 155.671266 -293.106094)
		(end 156.025596 -292.959028)
		(width 0.18288)
		(layer "In2.Cu")
		(net "M_E_CPU1_SA_DQ<12>")
	)
	(segment
		(start 156.210508 -294.407082)
		(end 156.743908 -294.186102)
		(width 0.18288)
		(layer "In2.Cu")
		(net "M_E_CPU1_SA_DQ<12>")
	)
	(segment
		(start 155.06954 -291.06876)
		(end 154.863038 -291.154612)
		(width 0.18288)
		(layer "In2.Cu")
		(net "M_E_CPU1_SA_DQ<12>")
	)
	(segment
		(start 155.028138 -292.05682)
		(end 155.132278 -291.805106)
		(width 0.18288)
		(layer "In2.Cu")
		(net "M_E_CPU1_SA_DQ<12>")
	)
	(segment
		(start 136.3726 -271.500854)
		(end 136.372346 -271.500854)
		(width 0.088646)
		(layer "In2.Cu")
		(net "M_E_CPU1_SA_DQ<12>")
	)
	(segment
		(start 140.900658 -272.361406)
		(end 140.483336 -272.361406)
		(width 0.088646)
		(layer "In2.Cu")
		(net "M_E_CPU1_SA_DQ<12>")
	)
	(segment
		(start 150.839424 -285.568644)
		(end 150.839424 -283.239972)
		(width 0.18288)
		(layer "In2.Cu")
		(net "M_E_CPU1_SA_DQ<12>")
	)
	(segment
		(start 157.494478 -300.560994)
		(end 157.090618 -300.560994)
		(width 0.18288)
		(layer "In2.Cu")
		(net "M_E_CPU1_SA_DQ<12>")
	)
	(segment
		(start 134.088886 -272.132806)
		(end 133.365748 -271.825212)
		(width 0.088646)
		(layer "In2.Cu")
		(net "M_E_CPU1_SA_DQ<12>")
	)
	(segment
		(start 155.321762 -291.173408)
		(end 155.06954 -291.06876)
		(width 0.18288)
		(layer "In2.Cu")
		(net "M_E_CPU1_SA_DQ<12>")
	)
	(segment
		(start 146.790156 -279.190704)
		(end 145.593816 -276.302216)
		(width 0.18288)
		(layer "In2.Cu")
		(net "M_E_CPU1_SA_DQ<12>")
	)
	(segment
		(start 156.743908 -294.186102)
		(end 156.848048 -293.933372)
		(width 0.18288)
		(layer "In2.Cu")
		(net "M_E_CPU1_SA_DQ<12>")
	)
	(segment
		(start 155.756102 -292.308534)
		(end 155.402026 -292.4556)
		(width 0.18288)
		(layer "In2.Cu")
		(net "M_E_CPU1_SA_DQ<12>")
	)
	(segment
		(start 137.312146 -271.500854)
		(end 137.311892 -271.500854)
		(width 0.088646)
		(layer "In2.Cu")
		(net "M_E_CPU1_SA_DQ<12>")
	)
	(segment
		(start 155.689046 -293.65194)
		(end 155.567126 -293.357808)
		(width 0.18288)
		(layer "In2.Cu")
		(net "M_E_CPU1_SA_DQ<12>")
	)
	(segment
		(start 157.682946 -300.749462)
		(end 157.494478 -300.560994)
		(width 0.18288)
		(layer "In2.Cu")
		(net "M_E_CPU1_SA_DQ<12>")
	)
	(segment
		(start 156.10586 -294.65905)
		(end 156.210508 -294.407082)
		(width 0.18288)
		(layer "In2.Cu")
		(net "M_E_CPU1_SA_DQ<12>")
	)
	(segment
		(start 156.008324 -292.413182)
		(end 155.756102 -292.308534)
		(width 0.18288)
		(layer "In2.Cu")
		(net "M_E_CPU1_SA_DQ<12>")
	)
	(segment
		(start 151.551894 -287.288478)
		(end 150.839424 -285.568644)
		(width 0.18288)
		(layer "In2.Cu")
		(net "M_E_CPU1_SA_DQ<12>")
	)
	(segment
		(start 145.593816 -276.302216)
		(end 141.653006 -272.361406)
		(width 0.18288)
		(layer "In2.Cu")
		(net "M_E_CPU1_SA_DQ<12>")
	)
	(segment
		(start 157.090618 -300.560994)
		(end 156.922978 -300.393354)
		(width 0.18288)
		(layer "In2.Cu")
		(net "M_E_CPU1_SA_DQ<12>")
	)
	(segment
		(start 156.025596 -292.959028)
		(end 156.130244 -292.70706)
		(width 0.18288)
		(layer "In2.Cu")
		(net "M_E_CPU1_SA_DQ<12>")
	)
	(segment
		(start 157.682946 -301.01667)
		(end 157.682946 -300.749462)
		(width 0.18288)
		(layer "In2.Cu")
		(net "M_E_CPU1_SA_DQ<12>")
	)
	(segment
		(start 155.567126 -293.357808)
		(end 155.671266 -293.106094)
		(width 0.18288)
		(layer "In2.Cu")
		(net "M_E_CPU1_SA_DQ<12>")
	)
	(segment
		(start 155.443682 -291.467286)
		(end 155.321762 -291.173408)
		(width 0.18288)
		(layer "In2.Cu")
		(net "M_E_CPU1_SA_DQ<12>")
	)
	(segment
		(start 137.326878 -271.50949)
		(end 137.312146 -271.500854)
		(width 0.088646)
		(layer "In2.Cu")
		(net "M_E_CPU1_SA_DQ<12>")
	)
	(segment
		(start 156.646118 -299.724826)
		(end 156.646118 -295.466516)
		(width 0.18288)
		(layer "In2.Cu")
		(net "M_E_CPU1_SA_DQ<12>")
	)
	(segment
		(start 140.483336 -272.361406)
		(end 139.662916 -271.540986)
		(width 0.088646)
		(layer "In2.Cu")
		(net "M_E_CPU1_SA_DQ<12>")
	)
	(segment
		(start 154.61107 -291.049964)
		(end 154.502866 -290.789106)
		(width 0.18288)
		(layer "In2.Cu")
		(net "M_E_CPU1_SA_DQ<12>")
	)
	(segment
		(start 155.150058 -292.350952)
		(end 155.028138 -292.05682)
		(width 0.18288)
		(layer "In2.Cu")
		(net "M_E_CPU1_SA_DQ<12>")
	)
	(arc
		(start 135.544306 -272.07591)
		(mid 135.489547 -272.11432)
		(end 135.432546 -272.149316)
		(width 0.088646)
		(layer "In2.Cu")
		(net "M_E_CPU1_SA_DQ<12>")
	)
	(arc
		(start 137.87755 -271.500854)
		(mid 137.603351 -271.576689)
		(end 137.326878 -271.50949)
		(width 0.088646)
		(layer "In2.Cu")
		(net "M_E_CPU1_SA_DQ<12>")
	)
	(arc
		(start 135.561578 -272.057876)
		(mid 135.553618 -272.06754)
		(end 135.544306 -272.07591)
		(width 0.088646)
		(layer "In2.Cu")
		(net "M_E_CPU1_SA_DQ<12>")
	)
	(arc
		(start 136.93775 -271.500854)
		(mid 136.655192 -271.576503)
		(end 136.3726 -271.500854)
		(width 0.088646)
		(layer "In2.Cu")
		(net "M_E_CPU1_SA_DQ<12>")
	)
	(arc
		(start 138.81735 -271.500854)
		(mid 138.543151 -271.576689)
		(end 138.266678 -271.50949)
		(width 0.088646)
		(layer "In2.Cu")
		(net "M_E_CPU1_SA_DQ<12>")
	)
	(arc
		(start 134.492746 -272.14957)
		(mid 134.305548 -272.199713)
		(end 134.11835 -272.14957)
		(width 0.088646)
		(layer "In2.Cu")
		(net "M_E_CPU1_SA_DQ<12>")
	)
	(arc
		(start 136.372346 -271.500854)
		(mid 136.185148 -271.450711)
		(end 135.99795 -271.500854)
		(width 0.088646)
		(layer "In2.Cu")
		(net "M_E_CPU1_SA_DQ<12>")
	)
	(arc
		(start 135.854694 -271.64792)
		(mid 135.84208 -271.669831)
		(end 135.828024 -271.690846)
		(width 0.088646)
		(layer "In2.Cu")
		(net "M_E_CPU1_SA_DQ<12>")
	)
	(arc
		(start 137.311892 -271.500854)
		(mid 137.124838 -271.450804)
		(end 136.93775 -271.500854)
		(width 0.088646)
		(layer "In2.Cu")
		(net "M_E_CPU1_SA_DQ<12>")
	)
	(arc
		(start 138.251946 -271.500854)
		(mid 138.064748 -271.450711)
		(end 137.87755 -271.500854)
		(width 0.088646)
		(layer "In2.Cu")
		(net "M_E_CPU1_SA_DQ<12>")
	)
	(arc
		(start 135.432546 -272.14957)
		(mid 135.245348 -272.199713)
		(end 135.05815 -272.14957)
		(width 0.088646)
		(layer "In2.Cu")
		(net "M_E_CPU1_SA_DQ<12>")
	)
	(arc
		(start 135.05815 -272.14957)
		(mid 134.775592 -272.073921)
		(end 134.493 -272.14957)
		(width 0.088646)
		(layer "In2.Cu")
		(net "M_E_CPU1_SA_DQ<12>")
	)
	(arc
		(start 139.191746 -271.500854)
		(mid 139.004548 -271.450711)
		(end 138.81735 -271.500854)
		(width 0.088646)
		(layer "In2.Cu")
		(net "M_E_CPU1_SA_DQ<12>")
	)
	(arc
		(start 135.997696 -271.501108)
		(mid 135.915958 -271.564542)
		(end 135.854694 -271.64792)
		(width 0.088646)
		(layer "In2.Cu")
		(net "M_E_CPU1_SA_DQ<12>")
	)
	(segment
		(start 168.265348 -304.649378)
		(end 168.06164 -304.853086)
		(width 0.20066)
		(layer "F.Cu")
		(net "M_E_CPU1_SA_DQ<11>")
	)
	(segment
		(start 135.245094 -273.452844)
		(end 135.245348 -273.453098)
		(width 0.20066)
		(layer "F.Cu")
		(net "M_E_CPU1_SA_DQ<11>")
	)
	(segment
		(start 165.335458 -304.852324)
		(end 165.028372 -304.852324)
		(width 0.20066)
		(layer "F.Cu")
		(net "M_E_CPU1_SA_DQ<11>")
	)
	(segment
		(start 165.028372 -304.852324)
		(end 164.592762 -304.416714)
		(width 0.20066)
		(layer "F.Cu")
		(net "M_E_CPU1_SA_DQ<11>")
	)
	(segment
		(start 168.06164 -304.853086)
		(end 167.367458 -304.853086)
		(width 0.20066)
		(layer "F.Cu")
		(net "M_E_CPU1_SA_DQ<11>")
	)
	(segment
		(start 170.457114 -304.416714)
		(end 169.135552 -304.416714)
		(width 0.20066)
		(layer "F.Cu")
		(net "M_E_CPU1_SA_DQ<11>")
	)
	(segment
		(start 168.883584 -304.164746)
		(end 168.499536 -304.164746)
		(width 0.20066)
		(layer "F.Cu")
		(net "M_E_CPU1_SA_DQ<11>")
	)
	(segment
		(start 165.352984 -304.852324)
		(end 165.335458 -304.852324)
		(width 0.101854)
		(layer "F.Cu")
		(net "M_E_CPU1_SA_DQ<11>")
	)
	(segment
		(start 167.356028 -304.841656)
		(end 166.555674 -304.841656)
		(width 0.101854)
		(layer "F.Cu")
		(net "M_E_CPU1_SA_DQ<11>")
	)
	(segment
		(start 169.135552 -304.416714)
		(end 168.883584 -304.164746)
		(width 0.20066)
		(layer "F.Cu")
		(net "M_E_CPU1_SA_DQ<11>")
	)
	(segment
		(start 168.499536 -304.164746)
		(end 168.265348 -304.398934)
		(width 0.20066)
		(layer "F.Cu")
		(net "M_E_CPU1_SA_DQ<11>")
	)
	(segment
		(start 165.363652 -304.841656)
		(end 165.352984 -304.852324)
		(width 0.1016)
		(layer "F.Cu")
		(net "M_E_CPU1_SA_DQ<11>")
	)
	(segment
		(start 164.592762 -304.416714)
		(end 162.913314 -304.416714)
		(width 0.20066)
		(layer "F.Cu")
		(net "M_E_CPU1_SA_DQ<11>")
	)
	(segment
		(start 166.555674 -304.841656)
		(end 165.363652 -304.841656)
		(width 0.1016)
		(layer "F.Cu")
		(net "M_E_CPU1_SA_DQ<11>")
	)
	(segment
		(start 135.245094 -272.917158)
		(end 135.245094 -273.452844)
		(width 0.20066)
		(layer "F.Cu")
		(net "M_E_CPU1_SA_DQ<11>")
	)
	(segment
		(start 161.783014 -304.416714)
		(end 162.913314 -304.416714)
		(width 0.20066)
		(layer "F.Cu")
		(net "M_E_CPU1_SA_DQ<11>")
	)
	(segment
		(start 167.367458 -304.853086)
		(end 167.356028 -304.841656)
		(width 0.101854)
		(layer "F.Cu")
		(net "M_E_CPU1_SA_DQ<11>")
	)
	(segment
		(start 168.265348 -304.398934)
		(end 168.265348 -304.649378)
		(width 0.20066)
		(layer "F.Cu")
		(net "M_E_CPU1_SA_DQ<11>")
	)
	(segment
		(start 161.046414 -304.416714)
		(end 160.557718 -303.928018)
		(width 0.18288)
		(layer "In2.Cu")
		(net "M_E_CPU1_SA_DQ<11>")
	)
	(segment
		(start 139.394946 -273.828256)
		(end 139.004548 -273.828256)
		(width 0.088646)
		(layer "In2.Cu")
		(net "M_E_CPU1_SA_DQ<11>")
	)
	(segment
		(start 159.764222 -303.928018)
		(end 159.241744 -304.450496)
		(width 0.18288)
		(layer "In2.Cu")
		(net "M_E_CPU1_SA_DQ<11>")
	)
	(segment
		(start 154.165554 -296.314114)
		(end 152.05837 -291.226494)
		(width 0.18288)
		(layer "In2.Cu")
		(net "M_E_CPU1_SA_DQ<11>")
	)
	(segment
		(start 157.927802 -303.992534)
		(end 157.346142 -303.992534)
		(width 0.18288)
		(layer "In2.Cu")
		(net "M_E_CPU1_SA_DQ<11>")
	)
	(segment
		(start 152.05837 -291.226494)
		(end 148.552154 -287.720278)
		(width 0.18288)
		(layer "In2.Cu")
		(net "M_E_CPU1_SA_DQ<11>")
	)
	(segment
		(start 144.179798 -277.273004)
		(end 141.2621 -274.355306)
		(width 0.18288)
		(layer "In2.Cu")
		(net "M_E_CPU1_SA_DQ<11>")
	)
	(segment
		(start 161.783014 -304.416714)
		(end 161.046414 -304.416714)
		(width 0.18288)
		(layer "In2.Cu")
		(net "M_E_CPU1_SA_DQ<11>")
	)
	(segment
		(start 157.154626 -303.801018)
		(end 156.453586 -303.801018)
		(width 0.18288)
		(layer "In2.Cu")
		(net "M_E_CPU1_SA_DQ<11>")
	)
	(segment
		(start 154.165554 -301.340266)
		(end 154.165554 -296.314114)
		(width 0.18288)
		(layer "In2.Cu")
		(net "M_E_CPU1_SA_DQ<11>")
	)
	(segment
		(start 159.241744 -304.450496)
		(end 158.385764 -304.450496)
		(width 0.18288)
		(layer "In2.Cu")
		(net "M_E_CPU1_SA_DQ<11>")
	)
	(segment
		(start 155.329128 -302.50384)
		(end 154.165554 -301.340266)
		(width 0.18288)
		(layer "In2.Cu")
		(net "M_E_CPU1_SA_DQ<11>")
	)
	(segment
		(start 139.921996 -274.355306)
		(end 139.394946 -273.828256)
		(width 0.088646)
		(layer "In2.Cu")
		(net "M_E_CPU1_SA_DQ<11>")
	)
	(segment
		(start 141.2621 -274.355306)
		(end 140.900658 -274.355306)
		(width 0.18288)
		(layer "In2.Cu")
		(net "M_E_CPU1_SA_DQ<11>")
	)
	(segment
		(start 140.900658 -274.355306)
		(end 139.921996 -274.355306)
		(width 0.088646)
		(layer "In2.Cu")
		(net "M_E_CPU1_SA_DQ<11>")
	)
	(segment
		(start 158.385764 -304.450496)
		(end 157.927802 -303.992534)
		(width 0.18288)
		(layer "In2.Cu")
		(net "M_E_CPU1_SA_DQ<11>")
	)
	(segment
		(start 155.329128 -302.67656)
		(end 155.329128 -302.50384)
		(width 0.18288)
		(layer "In2.Cu")
		(net "M_E_CPU1_SA_DQ<11>")
	)
	(segment
		(start 157.346142 -303.992534)
		(end 157.154626 -303.801018)
		(width 0.18288)
		(layer "In2.Cu")
		(net "M_E_CPU1_SA_DQ<11>")
	)
	(segment
		(start 148.552154 -283.440378)
		(end 145.44929 -280.337514)
		(width 0.18288)
		(layer "In2.Cu")
		(net "M_E_CPU1_SA_DQ<11>")
	)
	(segment
		(start 135.997696 -273.777456)
		(end 135.969756 -273.7612)
		(width 0.088646)
		(layer "In2.Cu")
		(net "M_E_CPU1_SA_DQ<11>")
	)
	(segment
		(start 135.969756 -273.7612)
		(end 135.245348 -273.453098)
		(width 0.088646)
		(layer "In2.Cu")
		(net "M_E_CPU1_SA_DQ<11>")
	)
	(segment
		(start 145.44929 -280.337514)
		(end 144.179798 -277.273004)
		(width 0.18288)
		(layer "In2.Cu")
		(net "M_E_CPU1_SA_DQ<11>")
	)
	(segment
		(start 160.557718 -303.928018)
		(end 159.764222 -303.928018)
		(width 0.18288)
		(layer "In2.Cu")
		(net "M_E_CPU1_SA_DQ<11>")
	)
	(segment
		(start 148.552154 -287.720278)
		(end 148.552154 -283.440378)
		(width 0.18288)
		(layer "In2.Cu")
		(net "M_E_CPU1_SA_DQ<11>")
	)
	(segment
		(start 156.453586 -303.801018)
		(end 155.329128 -302.67656)
		(width 0.18288)
		(layer "In2.Cu")
		(net "M_E_CPU1_SA_DQ<11>")
	)
	(arc
		(start 138.817096 -273.777456)
		(mid 138.534394 -273.70168)
		(end 138.251692 -273.777456)
		(width 0.088646)
		(layer "In2.Cu")
		(net "M_E_CPU1_SA_DQ<11>")
	)
	(arc
		(start 137.877296 -273.777456)
		(mid 137.594594 -273.70168)
		(end 137.311892 -273.777456)
		(width 0.088646)
		(layer "In2.Cu")
		(net "M_E_CPU1_SA_DQ<11>")
	)
	(arc
		(start 139.004548 -273.828256)
		(mid 138.907478 -273.815199)
		(end 138.817096 -273.777456)
		(width 0.088646)
		(layer "In2.Cu")
		(net "M_E_CPU1_SA_DQ<11>")
	)
	(arc
		(start 138.251692 -273.777456)
		(mid 138.064494 -273.827599)
		(end 137.877296 -273.777456)
		(width 0.088646)
		(layer "In2.Cu")
		(net "M_E_CPU1_SA_DQ<11>")
	)
	(arc
		(start 137.311892 -273.777456)
		(mid 137.124694 -273.827599)
		(end 136.937496 -273.777456)
		(width 0.088646)
		(layer "In2.Cu")
		(net "M_E_CPU1_SA_DQ<11>")
	)
	(arc
		(start 136.937496 -273.777456)
		(mid 136.654794 -273.70168)
		(end 136.372092 -273.777456)
		(width 0.088646)
		(layer "In2.Cu")
		(net "M_E_CPU1_SA_DQ<11>")
	)
	(arc
		(start 136.372092 -273.777456)
		(mid 136.184894 -273.827599)
		(end 135.997696 -273.777456)
		(width 0.088646)
		(layer "In2.Cu")
		(net "M_E_CPU1_SA_DQ<11>")
	)
	(segment
		(start 169.135552 -306.116736)
		(end 168.883584 -305.864768)
		(width 0.20066)
		(layer "F.Cu")
		(net "M_E_CPU1_SA_DQ<10>")
	)
	(segment
		(start 161.783014 -306.116736)
		(end 162.913314 -306.116736)
		(width 0.20066)
		(layer "F.Cu")
		(net "M_E_CPU1_SA_DQ<10>")
	)
	(segment
		(start 166.719504 -306.541678)
		(end 165.362128 -306.541678)
		(width 0.1016)
		(layer "F.Cu")
		(net "M_E_CPU1_SA_DQ<10>")
	)
	(segment
		(start 165.362128 -306.541678)
		(end 165.352984 -306.550822)
		(width 0.1016)
		(layer "F.Cu")
		(net "M_E_CPU1_SA_DQ<10>")
	)
	(segment
		(start 165.335458 -306.550822)
		(end 164.97808 -306.550822)
		(width 0.20066)
		(layer "F.Cu")
		(net "M_E_CPU1_SA_DQ<10>")
	)
	(segment
		(start 168.065704 -306.553362)
		(end 167.367458 -306.553362)
		(width 0.20066)
		(layer "F.Cu")
		(net "M_E_CPU1_SA_DQ<10>")
	)
	(segment
		(start 167.355774 -306.541678)
		(end 166.719504 -306.541678)
		(width 0.101854)
		(layer "F.Cu")
		(net "M_E_CPU1_SA_DQ<10>")
	)
	(segment
		(start 167.367458 -306.553362)
		(end 167.355774 -306.541678)
		(width 0.101854)
		(layer "F.Cu")
		(net "M_E_CPU1_SA_DQ<10>")
	)
	(segment
		(start 134.775448 -273.730974)
		(end 134.775448 -274.26666)
		(width 0.20066)
		(layer "F.Cu")
		(net "M_E_CPU1_SA_DQ<10>")
	)
	(segment
		(start 164.543994 -306.116736)
		(end 162.913314 -306.116736)
		(width 0.20066)
		(layer "F.Cu")
		(net "M_E_CPU1_SA_DQ<10>")
	)
	(segment
		(start 170.457114 -306.116736)
		(end 169.135552 -306.116736)
		(width 0.20066)
		(layer "F.Cu")
		(net "M_E_CPU1_SA_DQ<10>")
	)
	(segment
		(start 168.883584 -305.864768)
		(end 168.499536 -305.864768)
		(width 0.20066)
		(layer "F.Cu")
		(net "M_E_CPU1_SA_DQ<10>")
	)
	(segment
		(start 164.97808 -306.550822)
		(end 164.543994 -306.116736)
		(width 0.20066)
		(layer "F.Cu")
		(net "M_E_CPU1_SA_DQ<10>")
	)
	(segment
		(start 134.775448 -274.26666)
		(end 134.775194 -274.266914)
		(width 0.20066)
		(layer "F.Cu")
		(net "M_E_CPU1_SA_DQ<10>")
	)
	(segment
		(start 168.265348 -306.353718)
		(end 168.065704 -306.553362)
		(width 0.20066)
		(layer "F.Cu")
		(net "M_E_CPU1_SA_DQ<10>")
	)
	(segment
		(start 168.265348 -306.098956)
		(end 168.265348 -306.353718)
		(width 0.20066)
		(layer "F.Cu")
		(net "M_E_CPU1_SA_DQ<10>")
	)
	(segment
		(start 165.352984 -306.550822)
		(end 165.335458 -306.550822)
		(width 0.101854)
		(layer "F.Cu")
		(net "M_E_CPU1_SA_DQ<10>")
	)
	(segment
		(start 168.499536 -305.864768)
		(end 168.265348 -306.098956)
		(width 0.20066)
		(layer "F.Cu")
		(net "M_E_CPU1_SA_DQ<10>")
	)
	(segment
		(start 160.700466 -305.471068)
		(end 159.89681 -305.471068)
		(width 0.18288)
		(layer "In2.Cu")
		(net "M_E_CPU1_SA_DQ<10>")
	)
	(segment
		(start 134.405116 -274.324064)
		(end 134.462266 -274.266914)
		(width 0.088646)
		(layer "In2.Cu")
		(net "M_E_CPU1_SA_DQ<10>")
	)
	(segment
		(start 156.002228 -304.8381)
		(end 152.908762 -301.744634)
		(width 0.18288)
		(layer "In2.Cu")
		(net "M_E_CPU1_SA_DQ<10>")
	)
	(segment
		(start 161.03727 -305.807872)
		(end 160.700466 -305.471068)
		(width 0.18288)
		(layer "In2.Cu")
		(net "M_E_CPU1_SA_DQ<10>")
	)
	(segment
		(start 159.89681 -305.471068)
		(end 159.674306 -305.693572)
		(width 0.18288)
		(layer "In2.Cu")
		(net "M_E_CPU1_SA_DQ<10>")
	)
	(segment
		(start 152.908762 -301.744634)
		(end 152.908762 -296.726864)
		(width 0.18288)
		(layer "In2.Cu")
		(net "M_E_CPU1_SA_DQ<10>")
	)
	(segment
		(start 143.617442 -277.721568)
		(end 141.204188 -275.308314)
		(width 0.18288)
		(layer "In2.Cu")
		(net "M_E_CPU1_SA_DQ<10>")
	)
	(segment
		(start 147.887944 -288.838132)
		(end 147.536154 -288.486342)
		(width 0.18288)
		(layer "In2.Cu")
		(net "M_E_CPU1_SA_DQ<10>")
	)
	(segment
		(start 144.863312 -280.728928)
		(end 143.617442 -277.721568)
		(width 0.18288)
		(layer "In2.Cu")
		(net "M_E_CPU1_SA_DQ<10>")
	)
	(segment
		(start 135.527796 -274.591272)
		(end 135.513064 -274.582636)
		(width 0.088646)
		(layer "In2.Cu")
		(net "M_E_CPU1_SA_DQ<10>")
	)
	(segment
		(start 148.19376 -288.838132)
		(end 147.887944 -288.838132)
		(width 0.18288)
		(layer "In2.Cu")
		(net "M_E_CPU1_SA_DQ<10>")
	)
	(segment
		(start 147.536154 -283.40177)
		(end 144.863312 -280.728928)
		(width 0.18288)
		(layer "In2.Cu")
		(net "M_E_CPU1_SA_DQ<10>")
	)
	(segment
		(start 157.381448 -305.693572)
		(end 156.525976 -304.8381)
		(width 0.18288)
		(layer "In2.Cu")
		(net "M_E_CPU1_SA_DQ<10>")
	)
	(segment
		(start 152.908762 -296.726864)
		(end 150.664418 -291.30879)
		(width 0.18288)
		(layer "In2.Cu")
		(net "M_E_CPU1_SA_DQ<10>")
	)
	(segment
		(start 138.347196 -274.591272)
		(end 138.332464 -274.582636)
		(width 0.088646)
		(layer "In2.Cu")
		(net "M_E_CPU1_SA_DQ<10>")
	)
	(segment
		(start 136.467596 -274.591272)
		(end 136.452864 -274.582636)
		(width 0.088646)
		(layer "In2.Cu")
		(net "M_E_CPU1_SA_DQ<10>")
	)
	(segment
		(start 147.536154 -288.486342)
		(end 147.536154 -283.40177)
		(width 0.18288)
		(layer "In2.Cu")
		(net "M_E_CPU1_SA_DQ<10>")
	)
	(segment
		(start 134.462266 -274.266914)
		(end 134.775194 -274.266914)
		(width 0.088646)
		(layer "In2.Cu")
		(net "M_E_CPU1_SA_DQ<10>")
	)
	(segment
		(start 140.900658 -275.308314)
		(end 140.031978 -275.308314)
		(width 0.088646)
		(layer "In2.Cu")
		(net "M_E_CPU1_SA_DQ<10>")
	)
	(segment
		(start 141.204188 -275.308314)
		(end 140.900658 -275.308314)
		(width 0.18288)
		(layer "In2.Cu")
		(net "M_E_CPU1_SA_DQ<10>")
	)
	(segment
		(start 156.525976 -304.8381)
		(end 156.002228 -304.8381)
		(width 0.18288)
		(layer "In2.Cu")
		(net "M_E_CPU1_SA_DQ<10>")
	)
	(segment
		(start 159.674306 -305.693572)
		(end 157.381448 -305.693572)
		(width 0.18288)
		(layer "In2.Cu")
		(net "M_E_CPU1_SA_DQ<10>")
	)
	(segment
		(start 134.587996 -274.591272)
		(end 134.579106 -274.586192)
		(width 0.088646)
		(layer "In2.Cu")
		(net "M_E_CPU1_SA_DQ<10>")
	)
	(segment
		(start 137.407396 -274.591272)
		(end 137.392664 -274.582636)
		(width 0.088646)
		(layer "In2.Cu")
		(net "M_E_CPU1_SA_DQ<10>")
	)
	(segment
		(start 161.783014 -306.116736)
		(end 161.03727 -305.807872)
		(width 0.18288)
		(layer "In2.Cu")
		(net "M_E_CPU1_SA_DQ<10>")
	)
	(segment
		(start 150.664418 -291.30879)
		(end 148.19376 -288.838132)
		(width 0.18288)
		(layer "In2.Cu")
		(net "M_E_CPU1_SA_DQ<10>")
	)
	(segment
		(start 140.031978 -275.308314)
		(end 139.404598 -274.680934)
		(width 0.088646)
		(layer "In2.Cu")
		(net "M_E_CPU1_SA_DQ<10>")
	)
	(arc
		(start 137.781792 -274.591272)
		(mid 137.594594 -274.641415)
		(end 137.407396 -274.591272)
		(width 0.088646)
		(layer "In2.Cu")
		(net "M_E_CPU1_SA_DQ<10>")
	)
	(arc
		(start 138.721592 -274.591272)
		(mid 138.534394 -274.641415)
		(end 138.347196 -274.591272)
		(width 0.088646)
		(layer "In2.Cu")
		(net "M_E_CPU1_SA_DQ<10>")
	)
	(arc
		(start 138.332464 -274.582636)
		(mid 138.056023 -274.51547)
		(end 137.781792 -274.591272)
		(width 0.088646)
		(layer "In2.Cu")
		(net "M_E_CPU1_SA_DQ<10>")
	)
	(arc
		(start 136.841992 -274.591272)
		(mid 136.654794 -274.641415)
		(end 136.467596 -274.591272)
		(width 0.088646)
		(layer "In2.Cu")
		(net "M_E_CPU1_SA_DQ<10>")
	)
	(arc
		(start 135.902192 -274.591272)
		(mid 135.714994 -274.641415)
		(end 135.527796 -274.591272)
		(width 0.088646)
		(layer "In2.Cu")
		(net "M_E_CPU1_SA_DQ<10>")
	)
	(arc
		(start 139.404598 -274.680934)
		(mid 139.342029 -274.626941)
		(end 139.272264 -274.582636)
		(width 0.088646)
		(layer "In2.Cu")
		(net "M_E_CPU1_SA_DQ<10>")
	)
	(arc
		(start 136.452864 -274.582636)
		(mid 136.176423 -274.51547)
		(end 135.902192 -274.591272)
		(width 0.088646)
		(layer "In2.Cu")
		(net "M_E_CPU1_SA_DQ<10>")
	)
	(arc
		(start 135.513064 -274.582636)
		(mid 135.236623 -274.51547)
		(end 134.962392 -274.591272)
		(width 0.088646)
		(layer "In2.Cu")
		(net "M_E_CPU1_SA_DQ<10>")
	)
	(arc
		(start 139.272264 -274.582636)
		(mid 138.995823 -274.51547)
		(end 138.721592 -274.591272)
		(width 0.088646)
		(layer "In2.Cu")
		(net "M_E_CPU1_SA_DQ<10>")
	)
	(arc
		(start 137.392664 -274.582636)
		(mid 137.116223 -274.51547)
		(end 136.841992 -274.591272)
		(width 0.088646)
		(layer "In2.Cu")
		(net "M_E_CPU1_SA_DQ<10>")
	)
	(arc
		(start 134.962392 -274.591272)
		(mid 134.775194 -274.641415)
		(end 134.587996 -274.591272)
		(width 0.088646)
		(layer "In2.Cu")
		(net "M_E_CPU1_SA_DQ<10>")
	)
	(arc
		(start 134.579106 -274.586192)
		(mid 134.463297 -274.474263)
		(end 134.405116 -274.324064)
		(width 0.088646)
		(layer "In2.Cu")
		(net "M_E_CPU1_SA_DQ<10>")
	)
	(segment
		(start 139.126976 -296.258234)
		(end 139.034266 -296.350944)
		(width 0.1016)
		(layer "F.Cu")
		(net "M_E_CPU1_SA_DQ<0>")
	)
	(segment
		(start 161.947352 -315.854334)
		(end 161.896552 -315.854334)
		(width 0.1016)
		(layer "F.Cu")
		(net "M_E_CPU1_SA_DQ<0>")
	)
	(segment
		(start 161.00933 -316.598554)
		(end 159.675068 -316.598554)
		(width 0.20066)
		(layer "F.Cu")
		(net "M_E_CPU1_SA_DQ<0>")
	)
	(segment
		(start 154.736546 -315.57468)
		(end 154.845004 -315.836554)
		(width 0.20066)
		(layer "F.Cu")
		(net "M_E_CPU1_SA_DQ<0>")
	)
	(segment
		(start 139.126976 -281.063446)
		(end 139.126976 -296.258234)
		(width 0.1016)
		(layer "F.Cu")
		(net "M_E_CPU1_SA_DQ<0>")
	)
	(segment
		(start 155.121102 -316.438788)
		(end 155.382976 -316.33033)
		(width 0.20066)
		(layer "F.Cu")
		(net "M_E_CPU1_SA_DQ<0>")
	)
	(segment
		(start 154.857704 -316.329568)
		(end 155.121102 -316.438788)
		(width 0.20066)
		(layer "F.Cu")
		(net "M_E_CPU1_SA_DQ<0>")
	)
	(segment
		(start 155.478734 -316.09919)
		(end 155.740608 -315.990732)
		(width 0.20066)
		(layer "F.Cu")
		(net "M_E_CPU1_SA_DQ<0>")
	)
	(segment
		(start 137.248392 -279.067514)
		(end 137.320782 -279.108916)
		(width 0.088646)
		(layer "F.Cu")
		(net "M_E_CPU1_SA_DQ<0>")
	)
	(segment
		(start 164.315648 -315.88202)
		(end 163.923726 -315.88202)
		(width 0.20066)
		(layer "F.Cu")
		(net "M_E_CPU1_SA_DQ<0>")
	)
	(segment
		(start 139.003786 -280.062686)
		(end 139.126976 -280.359866)
		(width 0.088646)
		(layer "F.Cu")
		(net "M_E_CPU1_SA_DQ<0>")
	)
	(segment
		(start 138.709146 -297.142408)
		(end 138.709146 -299.930312)
		(width 0.20066)
		(layer "F.Cu")
		(net "M_E_CPU1_SA_DQ<0>")
	)
	(segment
		(start 139.034266 -296.350944)
		(end 139.034266 -296.817288)
		(width 0.1016)
		(layer "F.Cu")
		(net "M_E_CPU1_SA_DQ<0>")
	)
	(segment
		(start 156.880052 -316.462664)
		(end 157.757368 -316.462664)
		(width 0.20066)
		(layer "F.Cu")
		(net "M_E_CPU1_SA_DQ<0>")
	)
	(segment
		(start 138.564112 -279.87752)
		(end 138.771884 -279.87752)
		(width 0.088646)
		(layer "F.Cu")
		(net "M_E_CPU1_SA_DQ<0>")
	)
	(segment
		(start 154.845004 -315.836554)
		(end 154.749246 -316.067694)
		(width 0.20066)
		(layer "F.Cu")
		(net "M_E_CPU1_SA_DQ<0>")
	)
	(segment
		(start 154.082496 -315.303662)
		(end 154.736546 -315.57468)
		(width 0.20066)
		(layer "F.Cu")
		(net "M_E_CPU1_SA_DQ<0>")
	)
	(segment
		(start 161.891726 -315.854334)
		(end 161.468562 -315.854334)
		(width 0.20066)
		(layer "F.Cu")
		(net "M_E_CPU1_SA_DQ<0>")
	)
	(segment
		(start 161.264346 -316.05855)
		(end 161.264346 -316.343538)
		(width 0.20066)
		(layer "F.Cu")
		(net "M_E_CPU1_SA_DQ<0>")
	)
	(segment
		(start 157.903418 -316.316614)
		(end 158.813246 -316.316614)
		(width 0.20066)
		(layer "F.Cu")
		(net "M_E_CPU1_SA_DQ<0>")
	)
	(segment
		(start 138.85164 -279.91054)
		(end 139.003786 -280.062686)
		(width 0.088646)
		(layer "F.Cu")
		(net "M_E_CPU1_SA_DQ<0>")
	)
	(segment
		(start 161.98469 -315.891672)
		(end 161.947352 -315.854334)
		(width 0.1016)
		(layer "F.Cu")
		(net "M_E_CPU1_SA_DQ<0>")
	)
	(segment
		(start 159.393128 -316.316614)
		(end 158.813246 -316.316614)
		(width 0.20066)
		(layer "F.Cu")
		(net "M_E_CPU1_SA_DQ<0>")
	)
	(segment
		(start 164.750242 -316.316614)
		(end 164.315648 -315.88202)
		(width 0.20066)
		(layer "F.Cu")
		(net "M_E_CPU1_SA_DQ<0>")
	)
	(segment
		(start 163.662614 -315.891672)
		(end 161.98469 -315.891672)
		(width 0.1016)
		(layer "F.Cu")
		(net "M_E_CPU1_SA_DQ<0>")
	)
	(segment
		(start 138.709146 -299.930312)
		(end 154.082496 -315.303662)
		(width 0.20066)
		(layer "F.Cu")
		(net "M_E_CPU1_SA_DQ<0>")
	)
	(segment
		(start 155.740608 -315.990732)
		(end 156.880052 -316.462664)
		(width 0.20066)
		(layer "F.Cu")
		(net "M_E_CPU1_SA_DQ<0>")
	)
	(segment
		(start 163.923726 -315.88202)
		(end 163.912296 -315.88202)
		(width 0.101854)
		(layer "F.Cu")
		(net "M_E_CPU1_SA_DQ<0>")
	)
	(segment
		(start 166.357046 -316.316614)
		(end 164.750242 -316.316614)
		(width 0.20066)
		(layer "F.Cu")
		(net "M_E_CPU1_SA_DQ<0>")
	)
	(segment
		(start 137.499344 -279.428194)
		(end 137.499344 -279.446736)
		(width 0.088646)
		(layer "F.Cu")
		(net "M_E_CPU1_SA_DQ<0>")
	)
	(segment
		(start 161.468562 -315.854334)
		(end 161.264346 -316.05855)
		(width 0.20066)
		(layer "F.Cu")
		(net "M_E_CPU1_SA_DQ<0>")
	)
	(segment
		(start 154.749246 -316.067694)
		(end 154.857704 -316.329568)
		(width 0.20066)
		(layer "F.Cu")
		(net "M_E_CPU1_SA_DQ<0>")
	)
	(segment
		(start 157.757368 -316.462664)
		(end 157.903418 -316.316614)
		(width 0.20066)
		(layer "F.Cu")
		(net "M_E_CPU1_SA_DQ<0>")
	)
	(segment
		(start 155.382976 -316.33033)
		(end 155.478734 -316.09919)
		(width 0.20066)
		(layer "F.Cu")
		(net "M_E_CPU1_SA_DQ<0>")
	)
	(segment
		(start 138.825732 -297.025822)
		(end 138.709146 -297.142408)
		(width 0.20066)
		(layer "F.Cu")
		(net "M_E_CPU1_SA_DQ<0>")
	)
	(segment
		(start 161.264346 -316.343538)
		(end 161.00933 -316.598554)
		(width 0.20066)
		(layer "F.Cu")
		(net "M_E_CPU1_SA_DQ<0>")
	)
	(segment
		(start 163.902644 -315.891672)
		(end 163.662614 -315.891672)
		(width 0.101854)
		(layer "F.Cu")
		(net "M_E_CPU1_SA_DQ<0>")
	)
	(segment
		(start 137.781792 -279.917906)
		(end 137.792206 -279.924002)
		(width 0.088646)
		(layer "F.Cu")
		(net "M_E_CPU1_SA_DQ<0>")
	)
	(segment
		(start 161.896552 -315.854334)
		(end 161.891726 -315.854334)
		(width 0.101854)
		(layer "F.Cu")
		(net "M_E_CPU1_SA_DQ<0>")
	)
	(segment
		(start 163.912296 -315.88202)
		(end 163.902644 -315.891672)
		(width 0.101854)
		(layer "F.Cu")
		(net "M_E_CPU1_SA_DQ<0>")
	)
	(segment
		(start 139.126976 -280.359866)
		(end 139.126976 -281.063446)
		(width 0.088646)
		(layer "F.Cu")
		(net "M_E_CPU1_SA_DQ<0>")
	)
	(segment
		(start 159.675068 -316.598554)
		(end 159.393128 -316.316614)
		(width 0.20066)
		(layer "F.Cu")
		(net "M_E_CPU1_SA_DQ<0>")
	)
	(segment
		(start 139.034266 -296.817288)
		(end 138.825732 -297.025822)
		(width 0.1016)
		(layer "F.Cu")
		(net "M_E_CPU1_SA_DQ<0>")
	)
	(arc
		(start 138.771884 -279.87752)
		(mid 138.815042 -279.886105)
		(end 138.85164 -279.91054)
		(width 0.088646)
		(layer "F.Cu")
		(net "M_E_CPU1_SA_DQ<0>")
	)
	(arc
		(start 138.31443 -279.935686)
		(mid 138.435927 -279.892232)
		(end 138.564112 -279.87752)
		(width 0.088646)
		(layer "F.Cu")
		(net "M_E_CPU1_SA_DQ<0>")
	)
	(arc
		(start 137.320782 -279.108916)
		(mid 137.451696 -279.245276)
		(end 137.499344 -279.428194)
		(width 0.088646)
		(layer "F.Cu")
		(net "M_E_CPU1_SA_DQ<0>")
	)
	(arc
		(start 136.655048 -278.614378)
		(mid 136.936618 -278.86072)
		(end 137.248392 -279.067514)
		(width 0.088646)
		(layer "F.Cu")
		(net "M_E_CPU1_SA_DQ<0>")
	)
	(arc
		(start 137.499344 -279.446736)
		(mid 137.579506 -279.718925)
		(end 137.781792 -279.917906)
		(width 0.088646)
		(layer "F.Cu")
		(net "M_E_CPU1_SA_DQ<0>")
	)
	(arc
		(start 137.792206 -279.924002)
		(mid 138.051884 -279.993709)
		(end 138.31443 -279.935686)
		(width 0.088646)
		(layer "F.Cu")
		(net "M_E_CPU1_SA_DQ<0>")
	)
	(segment
		(start 160.61563 -266.743942)
		(end 160.61563 -266.493752)
		(width 0.20066)
		(layer "F.Cu")
		(net "M_E_CPU1_SA_CS_N<3>")
	)
	(segment
		(start 155.589224 -266.10818)
		(end 153.48458 -264.003536)
		(width 0.20066)
		(layer "F.Cu")
		(net "M_E_CPU1_SA_CS_N<3>")
	)
	(segment
		(start 161.158428 -266.92098)
		(end 160.792668 -266.92098)
		(width 0.20066)
		(layer "F.Cu")
		(net "M_E_CPU1_SA_CS_N<3>")
	)
	(segment
		(start 161.254186 -267.016738)
		(end 161.158428 -266.92098)
		(width 0.20066)
		(layer "F.Cu")
		(net "M_E_CPU1_SA_CS_N<3>")
	)
	(segment
		(start 136.41705 -256.262632)
		(end 136.26719 -256.112772)
		(width 0.088646)
		(layer "F.Cu")
		(net "M_E_CPU1_SA_CS_N<3>")
	)
	(segment
		(start 136.26719 -256.022348)
		(end 136.328658 -255.96088)
		(width 0.088646)
		(layer "F.Cu")
		(net "M_E_CPU1_SA_CS_N<3>")
	)
	(segment
		(start 145.894806 -260.08076)
		(end 144.868392 -259.876544)
		(width 0.1016)
		(layer "F.Cu")
		(net "M_E_CPU1_SA_CS_N<3>")
	)
	(segment
		(start 162.913314 -267.016738)
		(end 161.254186 -267.016738)
		(width 0.20066)
		(layer "F.Cu")
		(net "M_E_CPU1_SA_CS_N<3>")
	)
	(segment
		(start 147.224496 -261.41045)
		(end 146.101054 -260.287008)
		(width 0.20066)
		(layer "F.Cu")
		(net "M_E_CPU1_SA_CS_N<3>")
	)
	(segment
		(start 141.216634 -256.224786)
		(end 139.98575 -256.224786)
		(width 0.1016)
		(layer "F.Cu")
		(net "M_E_CPU1_SA_CS_N<3>")
	)
	(segment
		(start 160.529778 -266.4079)
		(end 160.182052 -266.4079)
		(width 0.20066)
		(layer "F.Cu")
		(net "M_E_CPU1_SA_CS_N<3>")
	)
	(segment
		(start 146.039332 -260.225286)
		(end 145.894806 -260.08076)
		(width 0.1016)
		(layer "F.Cu")
		(net "M_E_CPU1_SA_CS_N<3>")
	)
	(segment
		(start 160.792668 -266.92098)
		(end 160.61563 -266.743942)
		(width 0.20066)
		(layer "F.Cu")
		(net "M_E_CPU1_SA_CS_N<3>")
	)
	(segment
		(start 136.970516 -256.262632)
		(end 136.41705 -256.262632)
		(width 0.088646)
		(layer "F.Cu")
		(net "M_E_CPU1_SA_CS_N<3>")
	)
	(segment
		(start 157.809438 -266.591542)
		(end 157.796484 -266.578588)
		(width 0.1016)
		(layer "F.Cu")
		(net "M_E_CPU1_SA_CS_N<3>")
	)
	(segment
		(start 136.26719 -256.112772)
		(end 136.26719 -256.022348)
		(width 0.088646)
		(layer "F.Cu")
		(net "M_E_CPU1_SA_CS_N<3>")
	)
	(segment
		(start 160.182052 -266.4079)
		(end 160.016698 -266.573254)
		(width 0.20066)
		(layer "F.Cu")
		(net "M_E_CPU1_SA_CS_N<3>")
	)
	(segment
		(start 160.61563 -266.493752)
		(end 160.529778 -266.4079)
		(width 0.20066)
		(layer "F.Cu")
		(net "M_E_CPU1_SA_CS_N<3>")
	)
	(segment
		(start 159.823658 -266.573254)
		(end 159.80537 -266.591542)
		(width 0.1016)
		(layer "F.Cu")
		(net "M_E_CPU1_SA_CS_N<3>")
	)
	(segment
		(start 137.033508 -256.19964)
		(end 136.970516 -256.262632)
		(width 0.088646)
		(layer "F.Cu")
		(net "M_E_CPU1_SA_CS_N<3>")
	)
	(segment
		(start 137.608818 -256.19964)
		(end 137.033508 -256.19964)
		(width 0.088646)
		(layer "F.Cu")
		(net "M_E_CPU1_SA_CS_N<3>")
	)
	(segment
		(start 153.48458 -264.003536)
		(end 147.224496 -261.41045)
		(width 0.20066)
		(layer "F.Cu")
		(net "M_E_CPU1_SA_CS_N<3>")
	)
	(segment
		(start 137.782046 -256.149856)
		(end 137.781792 -256.149856)
		(width 0.088646)
		(layer "F.Cu")
		(net "M_E_CPU1_SA_CS_N<3>")
	)
	(segment
		(start 139.98575 -256.224786)
		(end 138.62685 -256.224786)
		(width 0.088646)
		(layer "F.Cu")
		(net "M_E_CPU1_SA_CS_N<3>")
	)
	(segment
		(start 157.149038 -266.10818)
		(end 155.589224 -266.10818)
		(width 0.20066)
		(layer "F.Cu")
		(net "M_E_CPU1_SA_CS_N<3>")
	)
	(segment
		(start 146.101054 -260.287008)
		(end 146.039332 -260.225286)
		(width 0.101854)
		(layer "F.Cu")
		(net "M_E_CPU1_SA_CS_N<3>")
	)
	(segment
		(start 157.796484 -266.578588)
		(end 157.791658 -266.578588)
		(width 0.101854)
		(layer "F.Cu")
		(net "M_E_CPU1_SA_CS_N<3>")
	)
	(segment
		(start 157.619446 -266.578588)
		(end 157.149038 -266.10818)
		(width 0.20066)
		(layer "F.Cu")
		(net "M_E_CPU1_SA_CS_N<3>")
	)
	(segment
		(start 157.791658 -266.578588)
		(end 157.619446 -266.578588)
		(width 0.20066)
		(layer "F.Cu")
		(net "M_E_CPU1_SA_CS_N<3>")
	)
	(segment
		(start 159.80537 -266.591542)
		(end 157.809438 -266.591542)
		(width 0.1016)
		(layer "F.Cu")
		(net "M_E_CPU1_SA_CS_N<3>")
	)
	(segment
		(start 136.328658 -255.96088)
		(end 136.655048 -255.825498)
		(width 0.088646)
		(layer "F.Cu")
		(net "M_E_CPU1_SA_CS_N<3>")
	)
	(segment
		(start 160.016698 -266.573254)
		(end 159.823658 -266.573254)
		(width 0.20066)
		(layer "F.Cu")
		(net "M_E_CPU1_SA_CS_N<3>")
	)
	(segment
		(start 144.868392 -259.876544)
		(end 141.216634 -256.224786)
		(width 0.1016)
		(layer "F.Cu")
		(net "M_E_CPU1_SA_CS_N<3>")
	)
	(arc
		(start 138.62685 -256.224786)
		(mid 138.482219 -256.205718)
		(end 138.34745 -256.149856)
		(width 0.088646)
		(layer "F.Cu")
		(net "M_E_CPU1_SA_CS_N<3>")
	)
	(arc
		(start 138.34745 -256.149856)
		(mid 138.064748 -256.07408)
		(end 137.782046 -256.149856)
		(width 0.088646)
		(layer "F.Cu")
		(net "M_E_CPU1_SA_CS_N<3>")
	)
	(arc
		(start 137.781792 -256.149856)
		(mid 137.698339 -256.185284)
		(end 137.608818 -256.19964)
		(width 0.088646)
		(layer "F.Cu")
		(net "M_E_CPU1_SA_CS_N<3>")
	)
	(segment
		(start 146.608546 -262.653526)
		(end 145.281904 -261.326884)
		(width 0.20066)
		(layer "F.Cu")
		(net "M_E_CPU1_SA_CS_N<2>")
	)
	(segment
		(start 136.693148 -256.918968)
		(end 136.693148 -256.63906)
		(width 0.088646)
		(layer "F.Cu")
		(net "M_E_CPU1_SA_CS_N<2>")
	)
	(segment
		(start 139.98575 -256.979166)
		(end 139.125198 -256.979166)
		(width 0.088646)
		(layer "F.Cu")
		(net "M_E_CPU1_SA_CS_N<2>")
	)
	(segment
		(start 139.121896 -256.975864)
		(end 138.971528 -256.975864)
		(width 0.088646)
		(layer "F.Cu")
		(net "M_E_CPU1_SA_CS_N<2>")
	)
	(segment
		(start 158.813246 -267.866622)
		(end 156.924502 -267.866622)
		(width 0.20066)
		(layer "F.Cu")
		(net "M_E_CPU1_SA_CS_N<2>")
	)
	(segment
		(start 144.873218 -260.743954)
		(end 141.10843 -256.979166)
		(width 0.1016)
		(layer "F.Cu")
		(net "M_E_CPU1_SA_CS_N<2>")
	)
	(segment
		(start 138.832082 -256.975102)
		(end 138.775694 -256.946654)
		(width 0.088646)
		(layer "F.Cu")
		(net "M_E_CPU1_SA_CS_N<2>")
	)
	(segment
		(start 137.732516 -256.41046)
		(end 137.732516 -256.420874)
		(width 0.088646)
		(layer "F.Cu")
		(net "M_E_CPU1_SA_CS_N<2>")
	)
	(segment
		(start 136.693148 -256.63906)
		(end 136.788398 -256.54381)
		(width 0.088646)
		(layer "F.Cu")
		(net "M_E_CPU1_SA_CS_N<2>")
	)
	(segment
		(start 137.36574 -257.111754)
		(end 136.885934 -257.111754)
		(width 0.088646)
		(layer "F.Cu")
		(net "M_E_CPU1_SA_CS_N<2>")
	)
	(segment
		(start 156.476192 -267.418312)
		(end 155.032456 -267.418312)
		(width 0.20066)
		(layer "F.Cu")
		(net "M_E_CPU1_SA_CS_N<2>")
	)
	(segment
		(start 136.894062 -256.54381)
		(end 137.124694 -256.639314)
		(width 0.088646)
		(layer "F.Cu")
		(net "M_E_CPU1_SA_CS_N<2>")
	)
	(segment
		(start 144.996662 -261.041642)
		(end 144.873218 -260.743954)
		(width 0.1016)
		(layer "F.Cu")
		(net "M_E_CPU1_SA_CS_N<2>")
	)
	(segment
		(start 137.624058 -256.529332)
		(end 137.624058 -256.853436)
		(width 0.088646)
		(layer "F.Cu")
		(net "M_E_CPU1_SA_CS_N<2>")
	)
	(segment
		(start 138.604244 -256.735072)
		(end 138.604244 -256.639314)
		(width 0.088646)
		(layer "F.Cu")
		(net "M_E_CPU1_SA_CS_N<2>")
	)
	(segment
		(start 141.10843 -256.979166)
		(end 139.98575 -256.979166)
		(width 0.1016)
		(layer "F.Cu")
		(net "M_E_CPU1_SA_CS_N<2>")
	)
	(segment
		(start 152.855168 -265.241024)
		(end 146.608546 -262.653526)
		(width 0.20066)
		(layer "F.Cu")
		(net "M_E_CPU1_SA_CS_N<2>")
	)
	(segment
		(start 137.624058 -256.853436)
		(end 137.36574 -257.111754)
		(width 0.088646)
		(layer "F.Cu")
		(net "M_E_CPU1_SA_CS_N<2>")
	)
	(segment
		(start 156.924502 -267.866622)
		(end 156.476192 -267.418312)
		(width 0.20066)
		(layer "F.Cu")
		(net "M_E_CPU1_SA_CS_N<2>")
	)
	(segment
		(start 139.125198 -256.979166)
		(end 139.121896 -256.975864)
		(width 0.088646)
		(layer "F.Cu")
		(net "M_E_CPU1_SA_CS_N<2>")
	)
	(segment
		(start 137.861294 -256.325116)
		(end 137.732516 -256.41046)
		(width 0.088646)
		(layer "F.Cu")
		(net "M_E_CPU1_SA_CS_N<2>")
	)
	(segment
		(start 145.281904 -261.326884)
		(end 144.996662 -261.041642)
		(width 0.1016)
		(layer "F.Cu")
		(net "M_E_CPU1_SA_CS_N<2>")
	)
	(segment
		(start 155.032456 -267.418312)
		(end 152.855168 -265.241024)
		(width 0.20066)
		(layer "F.Cu")
		(net "M_E_CPU1_SA_CS_N<2>")
	)
	(segment
		(start 136.885934 -257.111754)
		(end 136.693148 -256.918968)
		(width 0.088646)
		(layer "F.Cu")
		(net "M_E_CPU1_SA_CS_N<2>")
	)
	(segment
		(start 137.732516 -256.420874)
		(end 137.624058 -256.529332)
		(width 0.088646)
		(layer "F.Cu")
		(net "M_E_CPU1_SA_CS_N<2>")
	)
	(segment
		(start 136.788398 -256.54381)
		(end 136.894062 -256.54381)
		(width 0.088646)
		(layer "F.Cu")
		(net "M_E_CPU1_SA_CS_N<2>")
	)
	(arc
		(start 138.251692 -256.314956)
		(mid 138.099588 -256.266291)
		(end 137.94105 -256.285492)
		(width 0.088646)
		(layer "F.Cu")
		(net "M_E_CPU1_SA_CS_N<2>")
	)
	(arc
		(start 138.434826 -256.392426)
		(mid 138.340844 -256.359399)
		(end 138.251692 -256.314956)
		(width 0.088646)
		(layer "F.Cu")
		(net "M_E_CPU1_SA_CS_N<2>")
	)
	(arc
		(start 138.775694 -256.946654)
		(mid 138.667751 -256.858877)
		(end 138.604244 -256.735072)
		(width 0.088646)
		(layer "F.Cu")
		(net "M_E_CPU1_SA_CS_N<2>")
	)
	(arc
		(start 137.94105 -256.285492)
		(mid 137.899932 -256.302809)
		(end 137.861294 -256.325116)
		(width 0.088646)
		(layer "F.Cu")
		(net "M_E_CPU1_SA_CS_N<2>")
	)
	(arc
		(start 138.971528 -256.975864)
		(mid 138.901701 -256.992065)
		(end 138.832082 -256.975102)
		(width 0.088646)
		(layer "F.Cu")
		(net "M_E_CPU1_SA_CS_N<2>")
	)
	(arc
		(start 138.604244 -256.639314)
		(mid 138.564162 -256.485241)
		(end 138.434826 -256.392426)
		(width 0.088646)
		(layer "F.Cu")
		(net "M_E_CPU1_SA_CS_N<2>")
	)
	(segment
		(start 163.819078 -267.416534)
		(end 163.793932 -267.44168)
		(width 0.1016)
		(layer "F.Cu")
		(net "M_E_CPU1_SA_CS_N<1>")
	)
	(segment
		(start 168.356026 -266.829286)
		(end 168.356026 -267.12926)
		(width 0.20066)
		(layer "F.Cu")
		(net "M_E_CPU1_SA_CS_N<1>")
	)
	(segment
		(start 161.981642 -267.44168)
		(end 161.96818 -267.428218)
		(width 0.1016)
		(layer "F.Cu")
		(net "M_E_CPU1_SA_CS_N<1>")
	)
	(segment
		(start 163.793932 -267.44168)
		(end 161.981642 -267.44168)
		(width 0.1016)
		(layer "F.Cu")
		(net "M_E_CPU1_SA_CS_N<1>")
	)
	(segment
		(start 168.838626 -266.654026)
		(end 168.531286 -266.654026)
		(width 0.20066)
		(layer "F.Cu")
		(net "M_E_CPU1_SA_CS_N<1>")
	)
	(segment
		(start 168.025064 -267.460222)
		(end 167.367458 -267.460222)
		(width 0.20066)
		(layer "F.Cu")
		(net "M_E_CPU1_SA_CS_N<1>")
	)
	(segment
		(start 146.887692 -262.012684)
		(end 145.631662 -260.756654)
		(width 0.20066)
		(layer "F.Cu")
		(net "M_E_CPU1_SA_CS_N<1>")
	)
	(segment
		(start 165.378892 -267.44168)
		(end 165.37178 -267.448792)
		(width 0.1016)
		(layer "F.Cu")
		(net "M_E_CPU1_SA_CS_N<1>")
	)
	(segment
		(start 139.98575 -256.639314)
		(end 139.004294 -256.639314)
		(width 0.088646)
		(layer "F.Cu")
		(net "M_E_CPU1_SA_CS_N<1>")
	)
	(segment
		(start 157.81147 -267.44168)
		(end 157.796484 -267.456666)
		(width 0.1016)
		(layer "F.Cu")
		(net "M_E_CPU1_SA_CS_N<1>")
	)
	(segment
		(start 169.201338 -267.016738)
		(end 168.838626 -266.654026)
		(width 0.20066)
		(layer "F.Cu")
		(net "M_E_CPU1_SA_CS_N<1>")
	)
	(segment
		(start 167.367458 -267.460222)
		(end 167.348916 -267.44168)
		(width 0.101854)
		(layer "F.Cu")
		(net "M_E_CPU1_SA_CS_N<1>")
	)
	(segment
		(start 157.437328 -267.456666)
		(end 156.73832 -266.757658)
		(width 0.20066)
		(layer "F.Cu")
		(net "M_E_CPU1_SA_CS_N<1>")
	)
	(segment
		(start 167.348916 -267.44168)
		(end 166.888668 -267.44168)
		(width 0.101854)
		(layer "F.Cu")
		(net "M_E_CPU1_SA_CS_N<1>")
	)
	(segment
		(start 163.842954 -267.416534)
		(end 163.819078 -267.416534)
		(width 0.101854)
		(layer "F.Cu")
		(net "M_E_CPU1_SA_CS_N<1>")
	)
	(segment
		(start 165.37178 -267.448792)
		(end 165.366954 -267.448792)
		(width 0.101854)
		(layer "F.Cu")
		(net "M_E_CPU1_SA_CS_N<1>")
	)
	(segment
		(start 161.963354 -267.428218)
		(end 161.053526 -267.428218)
		(width 0.20066)
		(layer "F.Cu")
		(net "M_E_CPU1_SA_CS_N<1>")
	)
	(segment
		(start 141.19987 -256.639314)
		(end 139.98575 -256.639314)
		(width 0.1016)
		(layer "F.Cu")
		(net "M_E_CPU1_SA_CS_N<1>")
	)
	(segment
		(start 170.457114 -267.016738)
		(end 169.201338 -267.016738)
		(width 0.20066)
		(layer "F.Cu")
		(net "M_E_CPU1_SA_CS_N<1>")
	)
	(segment
		(start 165.366954 -267.448792)
		(end 164.89299 -267.448792)
		(width 0.20066)
		(layer "F.Cu")
		(net "M_E_CPU1_SA_CS_N<1>")
	)
	(segment
		(start 168.356026 -267.12926)
		(end 168.025064 -267.460222)
		(width 0.20066)
		(layer "F.Cu")
		(net "M_E_CPU1_SA_CS_N<1>")
	)
	(segment
		(start 168.531286 -266.654026)
		(end 168.356026 -266.829286)
		(width 0.20066)
		(layer "F.Cu")
		(net "M_E_CPU1_SA_CS_N<1>")
	)
	(segment
		(start 153.147268 -264.605516)
		(end 146.887692 -262.012684)
		(width 0.20066)
		(layer "F.Cu")
		(net "M_E_CPU1_SA_CS_N<1>")
	)
	(segment
		(start 164.89299 -267.448792)
		(end 164.860732 -267.416534)
		(width 0.20066)
		(layer "F.Cu")
		(net "M_E_CPU1_SA_CS_N<1>")
	)
	(segment
		(start 145.40738 -260.532372)
		(end 144.870424 -260.309868)
		(width 0.1016)
		(layer "F.Cu")
		(net "M_E_CPU1_SA_CS_N<1>")
	)
	(segment
		(start 157.796484 -267.456666)
		(end 157.791658 -267.456666)
		(width 0.101854)
		(layer "F.Cu")
		(net "M_E_CPU1_SA_CS_N<1>")
	)
	(segment
		(start 145.631662 -260.756654)
		(end 145.499836 -260.624828)
		(width 0.101854)
		(layer "F.Cu")
		(net "M_E_CPU1_SA_CS_N<1>")
	)
	(segment
		(start 159.823658 -267.456666)
		(end 159.808672 -267.44168)
		(width 0.101854)
		(layer "F.Cu")
		(net "M_E_CPU1_SA_CS_N<1>")
	)
	(segment
		(start 156.73832 -266.757658)
		(end 155.29941 -266.757658)
		(width 0.20066)
		(layer "F.Cu")
		(net "M_E_CPU1_SA_CS_N<1>")
	)
	(segment
		(start 159.40659 -267.44168)
		(end 157.81147 -267.44168)
		(width 0.1016)
		(layer "F.Cu")
		(net "M_E_CPU1_SA_CS_N<1>")
	)
	(segment
		(start 164.860732 -267.416534)
		(end 163.842954 -267.416534)
		(width 0.20066)
		(layer "F.Cu")
		(net "M_E_CPU1_SA_CS_N<1>")
	)
	(segment
		(start 160.15843 -267.456666)
		(end 159.823658 -267.456666)
		(width 0.20066)
		(layer "F.Cu")
		(net "M_E_CPU1_SA_CS_N<1>")
	)
	(segment
		(start 144.870424 -260.309868)
		(end 141.19987 -256.639314)
		(width 0.1016)
		(layer "F.Cu")
		(net "M_E_CPU1_SA_CS_N<1>")
	)
	(segment
		(start 161.053526 -267.428218)
		(end 161.016696 -267.391388)
		(width 0.20066)
		(layer "F.Cu")
		(net "M_E_CPU1_SA_CS_N<1>")
	)
	(segment
		(start 166.888668 -267.44168)
		(end 165.378892 -267.44168)
		(width 0.1016)
		(layer "F.Cu")
		(net "M_E_CPU1_SA_CS_N<1>")
	)
	(segment
		(start 145.499836 -260.624828)
		(end 145.40738 -260.532372)
		(width 0.1016)
		(layer "F.Cu")
		(net "M_E_CPU1_SA_CS_N<1>")
	)
	(segment
		(start 159.808672 -267.44168)
		(end 159.40659 -267.44168)
		(width 0.101854)
		(layer "F.Cu")
		(net "M_E_CPU1_SA_CS_N<1>")
	)
	(segment
		(start 155.29941 -266.757658)
		(end 153.147268 -264.605516)
		(width 0.20066)
		(layer "F.Cu")
		(net "M_E_CPU1_SA_CS_N<1>")
	)
	(segment
		(start 161.016696 -267.391388)
		(end 160.223708 -267.391388)
		(width 0.20066)
		(layer "F.Cu")
		(net "M_E_CPU1_SA_CS_N<1>")
	)
	(segment
		(start 157.791658 -267.456666)
		(end 157.437328 -267.456666)
		(width 0.20066)
		(layer "F.Cu")
		(net "M_E_CPU1_SA_CS_N<1>")
	)
	(segment
		(start 160.223708 -267.391388)
		(end 160.15843 -267.456666)
		(width 0.20066)
		(layer "F.Cu")
		(net "M_E_CPU1_SA_CS_N<1>")
	)
	(segment
		(start 161.96818 -267.428218)
		(end 161.963354 -267.428218)
		(width 0.101854)
		(layer "F.Cu")
		(net "M_E_CPU1_SA_CS_N<1>")
	)
	(segment
		(start 146.375374 -263.333992)
		(end 144.817084 -261.775702)
		(width 0.20066)
		(layer "F.Cu")
		(net "M_E_CPU1_SA_CS_N<0>")
	)
	(segment
		(start 161.952686 -268.291564)
		(end 161.94278 -268.30147)
		(width 0.1016)
		(layer "F.Cu")
		(net "M_E_CPU1_SA_CS_N<0>")
	)
	(segment
		(start 160.022032 -268.273276)
		(end 159.823658 -268.273276)
		(width 0.20066)
		(layer "F.Cu")
		(net "M_E_CPU1_SA_CS_N<0>")
	)
	(segment
		(start 161.494216 -268.30147)
		(end 161.29127 -268.098524)
		(width 0.20066)
		(layer "F.Cu")
		(net "M_E_CPU1_SA_CS_N<0>")
	)
	(segment
		(start 163.868354 -268.303502)
		(end 163.856416 -268.291564)
		(width 0.1016)
		(layer "F.Cu")
		(net "M_E_CPU1_SA_CS_N<0>")
	)
	(segment
		(start 156.188918 -268.0589)
		(end 154.74569 -268.0589)
		(width 0.20066)
		(layer "F.Cu")
		(net "M_E_CPU1_SA_CS_N<0>")
	)
	(segment
		(start 160.860232 -268.098524)
		(end 160.725358 -267.96365)
		(width 0.20066)
		(layer "F.Cu")
		(net "M_E_CPU1_SA_CS_N<0>")
	)
	(segment
		(start 144.683734 -261.642352)
		(end 144.219676 -260.521958)
		(width 0.1016)
		(layer "F.Cu")
		(net "M_E_CPU1_SA_CS_N<0>")
	)
	(segment
		(start 144.817084 -261.775702)
		(end 144.683734 -261.642352)
		(width 0.1016)
		(layer "F.Cu")
		(net "M_E_CPU1_SA_CS_N<0>")
	)
	(segment
		(start 160.725358 -267.96365)
		(end 160.331658 -267.96365)
		(width 0.20066)
		(layer "F.Cu")
		(net "M_E_CPU1_SA_CS_N<0>")
	)
	(segment
		(start 161.94278 -268.30147)
		(end 161.937954 -268.30147)
		(width 0.101854)
		(layer "F.Cu")
		(net "M_E_CPU1_SA_CS_N<0>")
	)
	(segment
		(start 152.59812 -265.911584)
		(end 146.375374 -263.333992)
		(width 0.20066)
		(layer "F.Cu")
		(net "M_E_CPU1_SA_CS_N<0>")
	)
	(segment
		(start 144.219676 -260.521958)
		(end 140.9954 -257.297682)
		(width 0.1016)
		(layer "F.Cu")
		(net "M_E_CPU1_SA_CS_N<0>")
	)
	(segment
		(start 156.64307 -268.513052)
		(end 156.188918 -268.0589)
		(width 0.20066)
		(layer "F.Cu")
		(net "M_E_CPU1_SA_CS_N<0>")
	)
	(segment
		(start 163.856416 -268.291564)
		(end 161.952686 -268.291564)
		(width 0.1016)
		(layer "F.Cu")
		(net "M_E_CPU1_SA_CS_N<0>")
	)
	(segment
		(start 159.803846 -268.291564)
		(end 157.80639 -268.291564)
		(width 0.1016)
		(layer "F.Cu")
		(net "M_E_CPU1_SA_CS_N<0>")
	)
	(segment
		(start 154.568652 -267.881862)
		(end 154.568652 -267.882116)
		(width 0.20066)
		(layer "F.Cu")
		(net "M_E_CPU1_SA_CS_N<0>")
	)
	(segment
		(start 166.357046 -267.866622)
		(end 164.675058 -267.866622)
		(width 0.20066)
		(layer "F.Cu")
		(net "M_E_CPU1_SA_CS_N<0>")
	)
	(segment
		(start 157.796484 -268.281658)
		(end 157.791658 -268.281658)
		(width 0.101854)
		(layer "F.Cu")
		(net "M_E_CPU1_SA_CS_N<0>")
	)
	(segment
		(start 154.74569 -268.0589)
		(end 154.568652 -267.881862)
		(width 0.20066)
		(layer "F.Cu")
		(net "M_E_CPU1_SA_CS_N<0>")
	)
	(segment
		(start 160.331658 -267.96365)
		(end 160.022032 -268.273276)
		(width 0.20066)
		(layer "F.Cu")
		(net "M_E_CPU1_SA_CS_N<0>")
	)
	(segment
		(start 164.238178 -268.303502)
		(end 163.868354 -268.303502)
		(width 0.20066)
		(layer "F.Cu")
		(net "M_E_CPU1_SA_CS_N<0>")
	)
	(segment
		(start 159.823658 -268.273276)
		(end 159.822134 -268.273276)
		(width 0.101854)
		(layer "F.Cu")
		(net "M_E_CPU1_SA_CS_N<0>")
	)
	(segment
		(start 138.038586 -256.927096)
		(end 138.038586 -256.665222)
		(width 0.088646)
		(layer "F.Cu")
		(net "M_E_CPU1_SA_CS_N<0>")
	)
	(segment
		(start 154.568652 -267.882116)
		(end 152.59812 -265.911584)
		(width 0.20066)
		(layer "F.Cu")
		(net "M_E_CPU1_SA_CS_N<0>")
	)
	(segment
		(start 161.29127 -268.098524)
		(end 160.860232 -268.098524)
		(width 0.20066)
		(layer "F.Cu")
		(net "M_E_CPU1_SA_CS_N<0>")
	)
	(segment
		(start 157.80639 -268.291564)
		(end 157.796484 -268.281658)
		(width 0.1016)
		(layer "F.Cu")
		(net "M_E_CPU1_SA_CS_N<0>")
	)
	(segment
		(start 157.434788 -268.281658)
		(end 157.203394 -268.513052)
		(width 0.20066)
		(layer "F.Cu")
		(net "M_E_CPU1_SA_CS_N<0>")
	)
	(segment
		(start 157.791658 -268.281658)
		(end 157.434788 -268.281658)
		(width 0.20066)
		(layer "F.Cu")
		(net "M_E_CPU1_SA_CS_N<0>")
	)
	(segment
		(start 138.101578 -256.990088)
		(end 138.038586 -256.927096)
		(width 0.088646)
		(layer "F.Cu")
		(net "M_E_CPU1_SA_CS_N<0>")
	)
	(segment
		(start 138.038586 -256.665222)
		(end 138.064494 -256.639314)
		(width 0.088646)
		(layer "F.Cu")
		(net "M_E_CPU1_SA_CS_N<0>")
	)
	(segment
		(start 164.675058 -267.866622)
		(end 164.238178 -268.303502)
		(width 0.20066)
		(layer "F.Cu")
		(net "M_E_CPU1_SA_CS_N<0>")
	)
	(segment
		(start 161.937954 -268.30147)
		(end 161.494216 -268.30147)
		(width 0.20066)
		(layer "F.Cu")
		(net "M_E_CPU1_SA_CS_N<0>")
	)
	(segment
		(start 139.98575 -257.297682)
		(end 139.163552 -257.297682)
		(width 0.088646)
		(layer "F.Cu")
		(net "M_E_CPU1_SA_CS_N<0>")
	)
	(segment
		(start 140.9954 -257.297682)
		(end 139.98575 -257.297682)
		(width 0.1016)
		(layer "F.Cu")
		(net "M_E_CPU1_SA_CS_N<0>")
	)
	(segment
		(start 159.822134 -268.273276)
		(end 159.803846 -268.291564)
		(width 0.1016)
		(layer "F.Cu")
		(net "M_E_CPU1_SA_CS_N<0>")
	)
	(segment
		(start 138.88339 -257.225546)
		(end 138.68146 -257.113786)
		(width 0.088646)
		(layer "F.Cu")
		(net "M_E_CPU1_SA_CS_N<0>")
	)
	(segment
		(start 157.203394 -268.513052)
		(end 156.64307 -268.513052)
		(width 0.20066)
		(layer "F.Cu")
		(net "M_E_CPU1_SA_CS_N<0>")
	)
	(segment
		(start 138.526266 -256.990088)
		(end 138.101578 -256.990088)
		(width 0.088646)
		(layer "F.Cu")
		(net "M_E_CPU1_SA_CS_N<0>")
	)
	(arc
		(start 138.68146 -257.113786)
		(mid 138.597719 -257.059643)
		(end 138.526266 -256.990088)
		(width 0.088646)
		(layer "F.Cu")
		(net "M_E_CPU1_SA_CS_N<0>")
	)
	(arc
		(start 139.163552 -257.297682)
		(mid 139.018898 -257.279382)
		(end 138.88339 -257.225546)
		(width 0.088646)
		(layer "F.Cu")
		(net "M_E_CPU1_SA_CS_N<0>")
	)
	(segment
		(start 156.249624 -269.586202)
		(end 156.8323 -269.586202)
		(width 0.20066)
		(layer "F.Cu")
		(net "M_E_CPU1_SA_CB<7>")
	)
	(segment
		(start 152.528524 -267.313918)
		(end 154.325828 -269.111222)
		(width 0.20066)
		(layer "F.Cu")
		(net "M_E_CPU1_SA_CB<7>")
	)
	(segment
		(start 140.033756 -258.459986)
		(end 140.58392 -258.459986)
		(width 0.088646)
		(layer "F.Cu")
		(net "M_E_CPU1_SA_CB<7>")
	)
	(segment
		(start 157.789118 -270.841724)
		(end 159.817816 -270.841724)
		(width 0.1016)
		(layer "F.Cu")
		(net "M_E_CPU1_SA_CB<7>")
	)
	(segment
		(start 160.614614 -269.713202)
		(end 161.192972 -269.713202)
		(width 0.20066)
		(layer "F.Cu")
		(net "M_E_CPU1_SA_CB<7>")
	)
	(segment
		(start 161.896552 -270.416782)
		(end 162.913314 -270.416782)
		(width 0.20066)
		(layer "F.Cu")
		(net "M_E_CPU1_SA_CB<7>")
	)
	(segment
		(start 151.421592 -267.923518)
		(end 151.421592 -267.69441)
		(width 0.20066)
		(layer "F.Cu")
		(net "M_E_CPU1_SA_CB<7>")
	)
	(segment
		(start 160.23336 -270.841724)
		(end 160.434274 -270.64081)
		(width 0.20066)
		(layer "F.Cu")
		(net "M_E_CPU1_SA_CB<7>")
	)
	(segment
		(start 157.142688 -269.89659)
		(end 157.142688 -270.472916)
		(width 0.20066)
		(layer "F.Cu")
		(net "M_E_CPU1_SA_CB<7>")
	)
	(segment
		(start 151.421592 -267.69441)
		(end 151.802084 -267.313918)
		(width 0.20066)
		(layer "F.Cu")
		(net "M_E_CPU1_SA_CB<7>")
	)
	(segment
		(start 160.434274 -270.64081)
		(end 160.434274 -269.893542)
		(width 0.20066)
		(layer "F.Cu")
		(net "M_E_CPU1_SA_CB<7>")
	)
	(segment
		(start 168.295828 -270.429736)
		(end 168.295828 -270.641064)
		(width 0.20066)
		(layer "F.Cu")
		(net "M_E_CPU1_SA_CB<7>")
	)
	(segment
		(start 154.325828 -269.111222)
		(end 155.774644 -269.111222)
		(width 0.20066)
		(layer "F.Cu")
		(net "M_E_CPU1_SA_CB<7>")
	)
	(segment
		(start 151.802084 -267.313918)
		(end 152.528524 -267.313918)
		(width 0.20066)
		(layer "F.Cu")
		(net "M_E_CPU1_SA_CB<7>")
	)
	(segment
		(start 169.210736 -270.416782)
		(end 168.984168 -270.190214)
		(width 0.20066)
		(layer "F.Cu")
		(net "M_E_CPU1_SA_CB<7>")
	)
	(segment
		(start 168.53535 -270.190214)
		(end 168.295828 -270.429736)
		(width 0.20066)
		(layer "F.Cu")
		(net "M_E_CPU1_SA_CB<7>")
	)
	(segment
		(start 138.387582 -258.399026)
		(end 138.59256 -258.399026)
		(width 0.088646)
		(layer "F.Cu")
		(net "M_E_CPU1_SA_CB<7>")
	)
	(segment
		(start 138.064494 -258.2672)
		(end 138.387582 -258.399026)
		(width 0.088646)
		(layer "F.Cu")
		(net "M_E_CPU1_SA_CB<7>")
	)
	(segment
		(start 138.739626 -258.546092)
		(end 138.818366 -258.591558)
		(width 0.088646)
		(layer "F.Cu")
		(net "M_E_CPU1_SA_CB<7>")
	)
	(segment
		(start 164.965888 -270.841724)
		(end 164.450776 -270.326612)
		(width 0.20066)
		(layer "F.Cu")
		(net "M_E_CPU1_SA_CB<7>")
	)
	(segment
		(start 141.858238 -259.734304)
		(end 150.220426 -268.096492)
		(width 0.1016)
		(layer "F.Cu")
		(net "M_E_CPU1_SA_CB<7>")
	)
	(segment
		(start 155.774644 -269.111222)
		(end 156.249624 -269.586202)
		(width 0.20066)
		(layer "F.Cu")
		(net "M_E_CPU1_SA_CB<7>")
	)
	(segment
		(start 139.567666 -258.653026)
		(end 140.033756 -258.459986)
		(width 0.088646)
		(layer "F.Cu")
		(net "M_E_CPU1_SA_CB<7>")
	)
	(segment
		(start 160.017968 -270.841724)
		(end 160.23336 -270.841724)
		(width 0.20066)
		(layer "F.Cu")
		(net "M_E_CPU1_SA_CB<7>")
	)
	(segment
		(start 168.984168 -270.190214)
		(end 168.53535 -270.190214)
		(width 0.20066)
		(layer "F.Cu")
		(net "M_E_CPU1_SA_CB<7>")
	)
	(segment
		(start 168.095168 -270.841724)
		(end 167.659304 -270.841724)
		(width 0.20066)
		(layer "F.Cu")
		(net "M_E_CPU1_SA_CB<7>")
	)
	(segment
		(start 167.659304 -270.841724)
		(end 167.291766 -270.841724)
		(width 0.101854)
		(layer "F.Cu")
		(net "M_E_CPU1_SA_CB<7>")
	)
	(segment
		(start 140.58392 -258.459986)
		(end 141.858238 -259.734304)
		(width 0.088646)
		(layer "F.Cu")
		(net "M_E_CPU1_SA_CB<7>")
	)
	(segment
		(start 167.291766 -270.841724)
		(end 165.382194 -270.841724)
		(width 0.1016)
		(layer "F.Cu")
		(net "M_E_CPU1_SA_CB<7>")
	)
	(segment
		(start 163.956238 -270.326612)
		(end 163.865814 -270.417036)
		(width 0.20066)
		(layer "F.Cu")
		(net "M_E_CPU1_SA_CB<7>")
	)
	(segment
		(start 150.220426 -268.096492)
		(end 151.073104 -268.096492)
		(width 0.1016)
		(layer "F.Cu")
		(net "M_E_CPU1_SA_CB<7>")
	)
	(segment
		(start 151.248618 -268.096492)
		(end 151.421592 -267.923518)
		(width 0.20066)
		(layer "F.Cu")
		(net "M_E_CPU1_SA_CB<7>")
	)
	(segment
		(start 161.192972 -269.713202)
		(end 161.896552 -270.416782)
		(width 0.20066)
		(layer "F.Cu")
		(net "M_E_CPU1_SA_CB<7>")
	)
	(segment
		(start 165.167818 -270.841724)
		(end 164.965888 -270.841724)
		(width 0.20066)
		(layer "F.Cu")
		(net "M_E_CPU1_SA_CB<7>")
	)
	(segment
		(start 160.434274 -269.893542)
		(end 160.614614 -269.713202)
		(width 0.20066)
		(layer "F.Cu")
		(net "M_E_CPU1_SA_CB<7>")
	)
	(segment
		(start 151.073104 -268.096492)
		(end 151.248618 -268.096492)
		(width 0.20066)
		(layer "F.Cu")
		(net "M_E_CPU1_SA_CB<7>")
	)
	(segment
		(start 157.511496 -270.841724)
		(end 157.624018 -270.841724)
		(width 0.20066)
		(layer "F.Cu")
		(net "M_E_CPU1_SA_CB<7>")
	)
	(segment
		(start 157.624018 -270.841724)
		(end 157.789118 -270.841724)
		(width 0.101854)
		(layer "F.Cu")
		(net "M_E_CPU1_SA_CB<7>")
	)
	(segment
		(start 157.142688 -270.472916)
		(end 157.511496 -270.841724)
		(width 0.20066)
		(layer "F.Cu")
		(net "M_E_CPU1_SA_CB<7>")
	)
	(segment
		(start 165.382194 -270.841724)
		(end 165.167818 -270.841724)
		(width 0.101854)
		(layer "F.Cu")
		(net "M_E_CPU1_SA_CB<7>")
	)
	(segment
		(start 170.457114 -270.416782)
		(end 169.210736 -270.416782)
		(width 0.20066)
		(layer "F.Cu")
		(net "M_E_CPU1_SA_CB<7>")
	)
	(segment
		(start 164.450776 -270.326612)
		(end 163.956238 -270.326612)
		(width 0.20066)
		(layer "F.Cu")
		(net "M_E_CPU1_SA_CB<7>")
	)
	(segment
		(start 159.817816 -270.841724)
		(end 160.017968 -270.841724)
		(width 0.101854)
		(layer "F.Cu")
		(net "M_E_CPU1_SA_CB<7>")
	)
	(segment
		(start 138.59256 -258.399026)
		(end 138.739626 -258.546092)
		(width 0.088646)
		(layer "F.Cu")
		(net "M_E_CPU1_SA_CB<7>")
	)
	(segment
		(start 168.295828 -270.641064)
		(end 168.095168 -270.841724)
		(width 0.20066)
		(layer "F.Cu")
		(net "M_E_CPU1_SA_CB<7>")
	)
	(segment
		(start 156.8323 -269.586202)
		(end 157.142688 -269.89659)
		(width 0.20066)
		(layer "F.Cu")
		(net "M_E_CPU1_SA_CB<7>")
	)
	(segment
		(start 163.865814 -270.417036)
		(end 162.913568 -270.417036)
		(width 0.20066)
		(layer "F.Cu")
		(net "M_E_CPU1_SA_CB<7>")
	)
	(segment
		(start 162.913568 -270.417036)
		(end 162.913314 -270.416782)
		(width 0.20066)
		(layer "F.Cu")
		(net "M_E_CPU1_SA_CB<7>")
	)
	(segment
		(start 139.046966 -258.653026)
		(end 139.567666 -258.653026)
		(width 0.088646)
		(layer "F.Cu")
		(net "M_E_CPU1_SA_CB<7>")
	)
	(arc
		(start 138.818366 -258.591558)
		(mid 138.928608 -258.63738)
		(end 139.046966 -258.653026)
		(width 0.088646)
		(layer "F.Cu")
		(net "M_E_CPU1_SA_CB<7>")
	)
	(segment
		(start 140.607288 -259.57022)
		(end 140.924026 -259.886958)
		(width 0.088646)
		(layer "F.Cu")
		(net "M_E_CPU1_SA_CB<6>")
	)
	(segment
		(start 161.243518 -271.998694)
		(end 161.9885 -271.998694)
		(width 0.20066)
		(layer "F.Cu")
		(net "M_E_CPU1_SA_CB<6>")
	)
	(segment
		(start 157.237938 -271.691608)
		(end 157.386782 -271.691608)
		(width 0.20066)
		(layer "F.Cu")
		(net "M_E_CPU1_SA_CB<6>")
	)
	(segment
		(start 141.439646 -260.178296)
		(end 152.330404 -271.069054)
		(width 0.1016)
		(layer "F.Cu")
		(net "M_E_CPU1_SA_CB<6>")
	)
	(segment
		(start 163.508182 -272.023586)
		(end 163.41471 -272.117058)
		(width 0.20066)
		(layer "F.Cu")
		(net "M_E_CPU1_SA_CB<6>")
	)
	(segment
		(start 138.534648 -259.081016)
		(end 138.79449 -259.078222)
		(width 0.088646)
		(layer "F.Cu")
		(net "M_E_CPU1_SA_CB<6>")
	)
	(segment
		(start 165.067996 -272.541746)
		(end 164.549836 -272.023586)
		(width 0.20066)
		(layer "F.Cu")
		(net "M_E_CPU1_SA_CB<6>")
	)
	(segment
		(start 162.913568 -272.117058)
		(end 162.913314 -272.116804)
		(width 0.20066)
		(layer "F.Cu")
		(net "M_E_CPU1_SA_CB<6>")
	)
	(segment
		(start 168.04513 -272.541746)
		(end 167.659304 -272.541746)
		(width 0.20066)
		(layer "F.Cu")
		(net "M_E_CPU1_SA_CB<6>")
	)
	(segment
		(start 157.386782 -271.691608)
		(end 157.699456 -271.691608)
		(width 0.101854)
		(layer "F.Cu")
		(net "M_E_CPU1_SA_CB<6>")
	)
	(segment
		(start 163.41471 -272.117058)
		(end 162.913568 -272.117058)
		(width 0.20066)
		(layer "F.Cu")
		(net "M_E_CPU1_SA_CB<6>")
	)
	(segment
		(start 165.368224 -272.541746)
		(end 165.167818 -272.541746)
		(width 0.101854)
		(layer "F.Cu")
		(net "M_E_CPU1_SA_CB<6>")
	)
	(segment
		(start 170.457114 -272.116804)
		(end 169.663618 -272.116804)
		(width 0.20066)
		(layer "F.Cu")
		(net "M_E_CPU1_SA_CB<6>")
	)
	(segment
		(start 168.351708 -271.638014)
		(end 168.26611 -271.723612)
		(width 0.20066)
		(layer "F.Cu")
		(net "M_E_CPU1_SA_CB<6>")
	)
	(segment
		(start 156.191966 -271.633188)
		(end 156.191966 -271.866868)
		(width 0.20066)
		(layer "F.Cu")
		(net "M_E_CPU1_SA_CB<6>")
	)
	(segment
		(start 168.737534 -271.638014)
		(end 168.351708 -271.638014)
		(width 0.20066)
		(layer "F.Cu")
		(net "M_E_CPU1_SA_CB<6>")
	)
	(segment
		(start 138.856974 -259.139436)
		(end 140.38072 -259.139436)
		(width 0.088646)
		(layer "F.Cu")
		(net "M_E_CPU1_SA_CB<6>")
	)
	(segment
		(start 152.627076 -271.68221)
		(end 152.769062 -271.824196)
		(width 0.20066)
		(layer "F.Cu")
		(net "M_E_CPU1_SA_CB<6>")
	)
	(segment
		(start 165.167818 -272.541746)
		(end 165.067996 -272.541746)
		(width 0.20066)
		(layer "F.Cu")
		(net "M_E_CPU1_SA_CB<6>")
	)
	(segment
		(start 152.627076 -271.365726)
		(end 152.627076 -271.68221)
		(width 0.20066)
		(layer "F.Cu")
		(net "M_E_CPU1_SA_CB<6>")
	)
	(segment
		(start 168.26611 -272.320766)
		(end 168.04513 -272.541746)
		(width 0.20066)
		(layer "F.Cu")
		(net "M_E_CPU1_SA_CB<6>")
	)
	(segment
		(start 140.924026 -259.886958)
		(end 141.148308 -259.886958)
		(width 0.088646)
		(layer "F.Cu")
		(net "M_E_CPU1_SA_CB<6>")
	)
	(segment
		(start 152.330404 -271.069054)
		(end 152.627076 -271.365726)
		(width 0.20066)
		(layer "F.Cu")
		(net "M_E_CPU1_SA_CB<6>")
	)
	(segment
		(start 160.368742 -271.691608)
		(end 160.542732 -271.865598)
		(width 0.20066)
		(layer "F.Cu")
		(net "M_E_CPU1_SA_CB<6>")
	)
	(segment
		(start 169.56278 -272.217642)
		(end 169.317162 -272.217642)
		(width 0.20066)
		(layer "F.Cu")
		(net "M_E_CPU1_SA_CB<6>")
	)
	(segment
		(start 167.659304 -272.541746)
		(end 167.355012 -272.541746)
		(width 0.101854)
		(layer "F.Cu")
		(net "M_E_CPU1_SA_CB<6>")
	)
	(segment
		(start 152.769062 -271.824196)
		(end 153.2382 -271.824196)
		(width 0.20066)
		(layer "F.Cu")
		(net "M_E_CPU1_SA_CB<6>")
	)
	(segment
		(start 153.2382 -271.824196)
		(end 153.345642 -271.716754)
		(width 0.20066)
		(layer "F.Cu")
		(net "M_E_CPU1_SA_CB<6>")
	)
	(segment
		(start 160.734502 -272.209768)
		(end 161.032444 -272.209768)
		(width 0.20066)
		(layer "F.Cu")
		(net "M_E_CPU1_SA_CB<6>")
	)
	(segment
		(start 156.191966 -271.866868)
		(end 156.408882 -272.083784)
		(width 0.20066)
		(layer "F.Cu")
		(net "M_E_CPU1_SA_CB<6>")
	)
	(segment
		(start 168.26611 -271.723612)
		(end 168.26611 -272.320766)
		(width 0.20066)
		(layer "F.Cu")
		(net "M_E_CPU1_SA_CB<6>")
	)
	(segment
		(start 162.10661 -272.116804)
		(end 162.913314 -272.116804)
		(width 0.20066)
		(layer "F.Cu")
		(net "M_E_CPU1_SA_CB<6>")
	)
	(segment
		(start 160.542732 -271.865598)
		(end 160.542732 -272.017998)
		(width 0.20066)
		(layer "F.Cu")
		(net "M_E_CPU1_SA_CB<6>")
	)
	(segment
		(start 164.549836 -272.023586)
		(end 163.508182 -272.023586)
		(width 0.20066)
		(layer "F.Cu")
		(net "M_E_CPU1_SA_CB<6>")
	)
	(segment
		(start 159.806386 -271.691608)
		(end 160.211008 -271.691608)
		(width 0.101854)
		(layer "F.Cu")
		(net "M_E_CPU1_SA_CB<6>")
	)
	(segment
		(start 138.79449 -259.078222)
		(end 138.856974 -259.139436)
		(width 0.088646)
		(layer "F.Cu")
		(net "M_E_CPU1_SA_CB<6>")
	)
	(segment
		(start 140.38072 -259.139436)
		(end 140.607288 -259.366004)
		(width 0.088646)
		(layer "F.Cu")
		(net "M_E_CPU1_SA_CB<6>")
	)
	(segment
		(start 141.148308 -259.886958)
		(end 141.439646 -260.178296)
		(width 0.088646)
		(layer "F.Cu")
		(net "M_E_CPU1_SA_CB<6>")
	)
	(segment
		(start 140.607288 -259.366004)
		(end 140.607288 -259.57022)
		(width 0.088646)
		(layer "F.Cu")
		(net "M_E_CPU1_SA_CB<6>")
	)
	(segment
		(start 161.032444 -272.209768)
		(end 161.243518 -271.998694)
		(width 0.20066)
		(layer "F.Cu")
		(net "M_E_CPU1_SA_CB<6>")
	)
	(segment
		(start 167.355012 -272.541746)
		(end 165.368224 -272.541746)
		(width 0.1016)
		(layer "F.Cu")
		(net "M_E_CPU1_SA_CB<6>")
	)
	(segment
		(start 157.699456 -271.691608)
		(end 159.806386 -271.691608)
		(width 0.1016)
		(layer "F.Cu")
		(net "M_E_CPU1_SA_CB<6>")
	)
	(segment
		(start 169.317162 -272.217642)
		(end 168.737534 -271.638014)
		(width 0.20066)
		(layer "F.Cu")
		(net "M_E_CPU1_SA_CB<6>")
	)
	(segment
		(start 153.345642 -271.337278)
		(end 154.249628 -270.433292)
		(width 0.20066)
		(layer "F.Cu")
		(net "M_E_CPU1_SA_CB<6>")
	)
	(segment
		(start 160.211008 -271.691608)
		(end 160.368742 -271.691608)
		(width 0.20066)
		(layer "F.Cu")
		(net "M_E_CPU1_SA_CB<6>")
	)
	(segment
		(start 169.663618 -272.116804)
		(end 169.56278 -272.217642)
		(width 0.20066)
		(layer "F.Cu")
		(net "M_E_CPU1_SA_CB<6>")
	)
	(segment
		(start 156.408882 -272.083784)
		(end 156.845762 -272.083784)
		(width 0.20066)
		(layer "F.Cu")
		(net "M_E_CPU1_SA_CB<6>")
	)
	(segment
		(start 153.345642 -271.716754)
		(end 153.345642 -271.337278)
		(width 0.20066)
		(layer "F.Cu")
		(net "M_E_CPU1_SA_CB<6>")
	)
	(segment
		(start 154.99207 -270.433292)
		(end 156.191966 -271.633188)
		(width 0.20066)
		(layer "F.Cu")
		(net "M_E_CPU1_SA_CB<6>")
	)
	(segment
		(start 156.845762 -272.083784)
		(end 157.237938 -271.691608)
		(width 0.20066)
		(layer "F.Cu")
		(net "M_E_CPU1_SA_CB<6>")
	)
	(segment
		(start 160.542732 -272.017998)
		(end 160.734502 -272.209768)
		(width 0.20066)
		(layer "F.Cu")
		(net "M_E_CPU1_SA_CB<6>")
	)
	(segment
		(start 154.249628 -270.433292)
		(end 154.99207 -270.433292)
		(width 0.20066)
		(layer "F.Cu")
		(net "M_E_CPU1_SA_CB<6>")
	)
	(segment
		(start 161.9885 -271.998694)
		(end 162.10661 -272.116804)
		(width 0.20066)
		(layer "F.Cu")
		(net "M_E_CPU1_SA_CB<6>")
	)
	(segment
		(start 156.20619 -270.25854)
		(end 156.507942 -270.560292)
		(width 0.20066)
		(layer "F.Cu")
		(net "M_E_CPU1_SA_CB<5>")
	)
	(segment
		(start 139.490196 -258.856226)
		(end 140.548868 -258.856226)
		(width 0.088646)
		(layer "F.Cu")
		(net "M_E_CPU1_SA_CB<5>")
	)
	(segment
		(start 150.585932 -268.89329)
		(end 151.111204 -268.89329)
		(width 0.1016)
		(layer "F.Cu")
		(net "M_E_CPU1_SA_CB<5>")
	)
	(segment
		(start 137.436606 -258.396486)
		(end 137.728706 -258.688586)
		(width 0.088646)
		(layer "F.Cu")
		(net "M_E_CPU1_SA_CB<5>")
	)
	(segment
		(start 163.903406 -270.841724)
		(end 161.975546 -270.841724)
		(width 0.1016)
		(layer "F.Cu")
		(net "M_E_CPU1_SA_CB<5>")
	)
	(segment
		(start 155.438348 -269.789402)
		(end 155.907486 -270.25854)
		(width 0.20066)
		(layer "F.Cu")
		(net "M_E_CPU1_SA_CB<5>")
	)
	(segment
		(start 151.973788 -268.633956)
		(end 151.973788 -268.349984)
		(width 0.20066)
		(layer "F.Cu")
		(net "M_E_CPU1_SA_CB<5>")
	)
	(segment
		(start 164.783008 -271.266666)
		(end 164.358066 -270.841724)
		(width 0.20066)
		(layer "F.Cu")
		(net "M_E_CPU1_SA_CB<5>")
	)
	(segment
		(start 166.357046 -271.266666)
		(end 164.783008 -271.266666)
		(width 0.20066)
		(layer "F.Cu")
		(net "M_E_CPU1_SA_CB<5>")
	)
	(segment
		(start 153.376884 -270.321024)
		(end 153.376884 -270.037052)
		(width 0.20066)
		(layer "F.Cu")
		(net "M_E_CPU1_SA_CB<5>")
	)
	(segment
		(start 164.358066 -270.841724)
		(end 164.102542 -270.841724)
		(width 0.20066)
		(layer "F.Cu")
		(net "M_E_CPU1_SA_CB<5>")
	)
	(segment
		(start 152.174956 -268.148816)
		(end 152.458928 -268.148816)
		(width 0.20066)
		(layer "F.Cu")
		(net "M_E_CPU1_SA_CB<5>")
	)
	(segment
		(start 161.975546 -270.841724)
		(end 161.691066 -270.841724)
		(width 0.101854)
		(layer "F.Cu")
		(net "M_E_CPU1_SA_CB<5>")
	)
	(segment
		(start 151.262842 -268.89329)
		(end 152.891744 -270.522192)
		(width 0.20066)
		(layer "F.Cu")
		(net "M_E_CPU1_SA_CB<5>")
	)
	(segment
		(start 160.86709 -271.091406)
		(end 160.69183 -271.266666)
		(width 0.20066)
		(layer "F.Cu")
		(net "M_E_CPU1_SA_CB<5>")
	)
	(segment
		(start 152.891744 -270.522192)
		(end 153.175716 -270.522192)
		(width 0.20066)
		(layer "F.Cu")
		(net "M_E_CPU1_SA_CB<5>")
	)
	(segment
		(start 152.458928 -268.148816)
		(end 154.099514 -269.789402)
		(width 0.20066)
		(layer "F.Cu")
		(net "M_E_CPU1_SA_CB<5>")
	)
	(segment
		(start 138.880596 -258.881626)
		(end 138.931396 -258.932426)
		(width 0.088646)
		(layer "F.Cu")
		(net "M_E_CPU1_SA_CB<5>")
	)
	(segment
		(start 156.507942 -270.560292)
		(end 156.507942 -270.747236)
		(width 0.20066)
		(layer "F.Cu")
		(net "M_E_CPU1_SA_CB<5>")
	)
	(segment
		(start 138.718544 -258.753864)
		(end 138.880596 -258.881626)
		(width 0.088646)
		(layer "F.Cu")
		(net "M_E_CPU1_SA_CB<5>")
	)
	(segment
		(start 154.099514 -269.789402)
		(end 155.438348 -269.789402)
		(width 0.20066)
		(layer "F.Cu")
		(net "M_E_CPU1_SA_CB<5>")
	)
	(segment
		(start 156.507942 -270.747236)
		(end 157.027372 -271.266666)
		(width 0.20066)
		(layer "F.Cu")
		(net "M_E_CPU1_SA_CB<5>")
	)
	(segment
		(start 164.102542 -270.841724)
		(end 163.903406 -270.841724)
		(width 0.101854)
		(layer "F.Cu")
		(net "M_E_CPU1_SA_CB<5>")
	)
	(segment
		(start 160.973008 -270.332708)
		(end 160.86709 -270.438626)
		(width 0.20066)
		(layer "F.Cu")
		(net "M_E_CPU1_SA_CB<5>")
	)
	(segment
		(start 160.86709 -270.438626)
		(end 160.86709 -271.091406)
		(width 0.20066)
		(layer "F.Cu")
		(net "M_E_CPU1_SA_CB<5>")
	)
	(segment
		(start 140.548868 -258.856226)
		(end 141.655292 -259.96265)
		(width 0.088646)
		(layer "F.Cu")
		(net "M_E_CPU1_SA_CB<5>")
	)
	(segment
		(start 155.907486 -270.25854)
		(end 156.20619 -270.25854)
		(width 0.20066)
		(layer "F.Cu")
		(net "M_E_CPU1_SA_CB<5>")
	)
	(segment
		(start 138.931396 -258.932426)
		(end 139.413996 -258.932426)
		(width 0.088646)
		(layer "F.Cu")
		(net "M_E_CPU1_SA_CB<5>")
	)
	(segment
		(start 153.376884 -270.037052)
		(end 151.973788 -268.633956)
		(width 0.20066)
		(layer "F.Cu")
		(net "M_E_CPU1_SA_CB<5>")
	)
	(segment
		(start 137.728706 -258.688586)
		(end 138.4681 -258.688586)
		(width 0.088646)
		(layer "F.Cu")
		(net "M_E_CPU1_SA_CB<5>")
	)
	(segment
		(start 161.691066 -270.841724)
		(end 161.611056 -270.761714)
		(width 0.101854)
		(layer "F.Cu")
		(net "M_E_CPU1_SA_CB<5>")
	)
	(segment
		(start 151.111204 -268.89329)
		(end 151.262842 -268.89329)
		(width 0.20066)
		(layer "F.Cu")
		(net "M_E_CPU1_SA_CB<5>")
	)
	(segment
		(start 151.973788 -268.349984)
		(end 152.174956 -268.148816)
		(width 0.20066)
		(layer "F.Cu")
		(net "M_E_CPU1_SA_CB<5>")
	)
	(segment
		(start 137.124694 -258.2672)
		(end 137.436606 -258.396486)
		(width 0.088646)
		(layer "F.Cu")
		(net "M_E_CPU1_SA_CB<5>")
	)
	(segment
		(start 157.027372 -271.266666)
		(end 158.813246 -271.266666)
		(width 0.20066)
		(layer "F.Cu")
		(net "M_E_CPU1_SA_CB<5>")
	)
	(segment
		(start 141.655292 -259.96265)
		(end 150.585932 -268.89329)
		(width 0.1016)
		(layer "F.Cu")
		(net "M_E_CPU1_SA_CB<5>")
	)
	(segment
		(start 161.18205 -270.332708)
		(end 160.973008 -270.332708)
		(width 0.20066)
		(layer "F.Cu")
		(net "M_E_CPU1_SA_CB<5>")
	)
	(segment
		(start 161.611056 -270.761714)
		(end 161.18205 -270.332708)
		(width 0.20066)
		(layer "F.Cu")
		(net "M_E_CPU1_SA_CB<5>")
	)
	(segment
		(start 160.69183 -271.266666)
		(end 158.813246 -271.266666)
		(width 0.20066)
		(layer "F.Cu")
		(net "M_E_CPU1_SA_CB<5>")
	)
	(segment
		(start 139.413996 -258.932426)
		(end 139.490196 -258.856226)
		(width 0.088646)
		(layer "F.Cu")
		(net "M_E_CPU1_SA_CB<5>")
	)
	(segment
		(start 153.175716 -270.522192)
		(end 153.376884 -270.321024)
		(width 0.20066)
		(layer "F.Cu")
		(net "M_E_CPU1_SA_CB<5>")
	)
	(arc
		(start 138.4681 -258.688586)
		(mid 138.597498 -258.705188)
		(end 138.718544 -258.753864)
		(width 0.088646)
		(layer "F.Cu")
		(net "M_E_CPU1_SA_CB<5>")
	)
	(segment
		(start 156.032962 -272.844768)
		(end 156.150818 -272.726912)
		(width 0.20066)
		(layer "F.Cu")
		(net "M_E_CPU1_SA_CB<4>")
	)
	(segment
		(start 152.951434 -273.00047)
		(end 153.152094 -272.79981)
		(width 0.20066)
		(layer "F.Cu")
		(net "M_E_CPU1_SA_CB<4>")
	)
	(segment
		(start 154.041348 -271.555972)
		(end 154.242008 -271.355312)
		(width 0.20066)
		(layer "F.Cu")
		(net "M_E_CPU1_SA_CB<4>")
	)
	(segment
		(start 154.15895 -272.989294)
		(end 154.476196 -272.989294)
		(width 0.20066)
		(layer "F.Cu")
		(net "M_E_CPU1_SA_CB<4>")
	)
	(segment
		(start 164.311076 -272.541746)
		(end 163.749736 -272.541746)
		(width 0.101854)
		(layer "F.Cu")
		(net "M_E_CPU1_SA_CB<4>")
	)
	(segment
		(start 157.214824 -272.966688)
		(end 158.813246 -272.966688)
		(width 0.20066)
		(layer "F.Cu")
		(net "M_E_CPU1_SA_CB<4>")
	)
	(segment
		(start 138.80084 -259.345938)
		(end 138.817096 -259.329682)
		(width 0.088646)
		(layer "F.Cu")
		(net "M_E_CPU1_SA_CB<4>")
	)
	(segment
		(start 154.851608 -271.355312)
		(end 155.54833 -272.052034)
		(width 0.20066)
		(layer "F.Cu")
		(net "M_E_CPU1_SA_CB<4>")
	)
	(segment
		(start 152.054306 -272.38706)
		(end 152.224994 -272.557748)
		(width 0.1016)
		(layer "F.Cu")
		(net "M_E_CPU1_SA_CB<4>")
	)
	(segment
		(start 159.925766 -272.846038)
		(end 159.805116 -272.966688)
		(width 0.20066)
		(layer "F.Cu")
		(net "M_E_CPU1_SA_CB<4>")
	)
	(segment
		(start 154.242008 -272.041112)
		(end 154.041348 -271.840452)
		(width 0.20066)
		(layer "F.Cu")
		(net "M_E_CPU1_SA_CB<4>")
	)
	(segment
		(start 140.8684 -260.164326)
		(end 140.994384 -260.164326)
		(width 0.088646)
		(layer "F.Cu")
		(net "M_E_CPU1_SA_CB<4>")
	)
	(segment
		(start 161.48685 -272.541746)
		(end 161.379662 -272.541746)
		(width 0.20066)
		(layer "F.Cu")
		(net "M_E_CPU1_SA_CB<4>")
	)
	(segment
		(start 166.357046 -272.966688)
		(end 164.918136 -272.966688)
		(width 0.20066)
		(layer "F.Cu")
		(net "M_E_CPU1_SA_CB<4>")
	)
	(segment
		(start 155.54833 -272.644108)
		(end 155.74899 -272.844768)
		(width 0.20066)
		(layer "F.Cu")
		(net "M_E_CPU1_SA_CB<4>")
	)
	(segment
		(start 154.56535 -272.041112)
		(end 154.242008 -272.041112)
		(width 0.20066)
		(layer "F.Cu")
		(net "M_E_CPU1_SA_CB<4>")
	)
	(segment
		(start 164.493194 -272.541746)
		(end 164.311076 -272.541746)
		(width 0.20066)
		(layer "F.Cu")
		(net "M_E_CPU1_SA_CB<4>")
	)
	(segment
		(start 141.216634 -260.386576)
		(end 151.764238 -270.93418)
		(width 0.1016)
		(layer "F.Cu")
		(net "M_E_CPU1_SA_CB<4>")
	)
	(segment
		(start 154.852878 -272.612612)
		(end 154.852878 -272.32864)
		(width 0.20066)
		(layer "F.Cu")
		(net "M_E_CPU1_SA_CB<4>")
	)
	(segment
		(start 161.905696 -272.541746)
		(end 161.48685 -272.541746)
		(width 0.101854)
		(layer "F.Cu")
		(net "M_E_CPU1_SA_CB<4>")
	)
	(segment
		(start 136.666986 -259.109718)
		(end 137.410698 -259.41782)
		(width 0.088646)
		(layer "F.Cu")
		(net "M_E_CPU1_SA_CB<4>")
	)
	(segment
		(start 137.410698 -259.41782)
		(end 137.73404 -259.482082)
		(width 0.088646)
		(layer "F.Cu")
		(net "M_E_CPU1_SA_CB<4>")
	)
	(segment
		(start 159.805116 -272.966688)
		(end 158.813246 -272.966688)
		(width 0.20066)
		(layer "F.Cu")
		(net "M_E_CPU1_SA_CB<4>")
	)
	(segment
		(start 138.817096 -259.329682)
		(end 140.033756 -259.329682)
		(width 0.088646)
		(layer "F.Cu")
		(net "M_E_CPU1_SA_CB<4>")
	)
	(segment
		(start 152.224994 -272.558002)
		(end 152.667462 -273.00047)
		(width 0.20066)
		(layer "F.Cu")
		(net "M_E_CPU1_SA_CB<4>")
	)
	(segment
		(start 160.94456 -273.175476)
		(end 160.626044 -273.175476)
		(width 0.20066)
		(layer "F.Cu")
		(net "M_E_CPU1_SA_CB<4>")
	)
	(segment
		(start 153.152094 -272.79981)
		(end 153.152094 -272.668238)
		(width 0.20066)
		(layer "F.Cu")
		(net "M_E_CPU1_SA_CB<4>")
	)
	(segment
		(start 163.749736 -272.541746)
		(end 161.905696 -272.541746)
		(width 0.1016)
		(layer "F.Cu")
		(net "M_E_CPU1_SA_CB<4>")
	)
	(segment
		(start 161.379662 -272.541746)
		(end 161.145474 -272.775934)
		(width 0.20066)
		(layer "F.Cu")
		(net "M_E_CPU1_SA_CB<4>")
	)
	(segment
		(start 153.352754 -272.467578)
		(end 153.637234 -272.467578)
		(width 0.20066)
		(layer "F.Cu")
		(net "M_E_CPU1_SA_CB<4>")
	)
	(segment
		(start 161.145474 -272.974562)
		(end 160.94456 -273.175476)
		(width 0.20066)
		(layer "F.Cu")
		(net "M_E_CPU1_SA_CB<4>")
	)
	(segment
		(start 156.150818 -272.726912)
		(end 156.975048 -272.726912)
		(width 0.20066)
		(layer "F.Cu")
		(net "M_E_CPU1_SA_CB<4>")
	)
	(segment
		(start 140.033756 -259.329682)
		(end 140.8684 -260.164326)
		(width 0.088646)
		(layer "F.Cu")
		(net "M_E_CPU1_SA_CB<4>")
	)
	(segment
		(start 138.717274 -259.408676)
		(end 138.723116 -259.405374)
		(width 0.088646)
		(layer "F.Cu")
		(net "M_E_CPU1_SA_CB<4>")
	)
	(segment
		(start 154.852878 -272.32864)
		(end 154.56535 -272.041112)
		(width 0.20066)
		(layer "F.Cu")
		(net "M_E_CPU1_SA_CB<4>")
	)
	(segment
		(start 155.54833 -272.052034)
		(end 155.54833 -272.644108)
		(width 0.20066)
		(layer "F.Cu")
		(net "M_E_CPU1_SA_CB<4>")
	)
	(segment
		(start 161.145474 -272.775934)
		(end 161.145474 -272.974562)
		(width 0.20066)
		(layer "F.Cu")
		(net "M_E_CPU1_SA_CB<4>")
	)
	(segment
		(start 153.637234 -272.467578)
		(end 154.15895 -272.989294)
		(width 0.20066)
		(layer "F.Cu")
		(net "M_E_CPU1_SA_CB<4>")
	)
	(segment
		(start 156.975048 -272.726912)
		(end 157.214824 -272.966688)
		(width 0.20066)
		(layer "F.Cu")
		(net "M_E_CPU1_SA_CB<4>")
	)
	(segment
		(start 137.73404 -259.482082)
		(end 138.484356 -259.482082)
		(width 0.088646)
		(layer "F.Cu")
		(net "M_E_CPU1_SA_CB<4>")
	)
	(segment
		(start 152.667462 -273.00047)
		(end 152.951434 -273.00047)
		(width 0.20066)
		(layer "F.Cu")
		(net "M_E_CPU1_SA_CB<4>")
	)
	(segment
		(start 160.626044 -273.175476)
		(end 160.296606 -272.846038)
		(width 0.20066)
		(layer "F.Cu")
		(net "M_E_CPU1_SA_CB<4>")
	)
	(segment
		(start 154.041348 -271.840452)
		(end 154.041348 -271.555972)
		(width 0.20066)
		(layer "F.Cu")
		(net "M_E_CPU1_SA_CB<4>")
	)
	(segment
		(start 155.74899 -272.844768)
		(end 156.032962 -272.844768)
		(width 0.20066)
		(layer "F.Cu")
		(net "M_E_CPU1_SA_CB<4>")
	)
	(segment
		(start 160.296606 -272.846038)
		(end 159.925766 -272.846038)
		(width 0.20066)
		(layer "F.Cu")
		(net "M_E_CPU1_SA_CB<4>")
	)
	(segment
		(start 140.994384 -260.164326)
		(end 141.216634 -260.386576)
		(width 0.088646)
		(layer "F.Cu")
		(net "M_E_CPU1_SA_CB<4>")
	)
	(segment
		(start 151.764238 -270.93418)
		(end 152.054306 -272.38706)
		(width 0.1016)
		(layer "F.Cu")
		(net "M_E_CPU1_SA_CB<4>")
	)
	(segment
		(start 153.152094 -272.668238)
		(end 153.352754 -272.467578)
		(width 0.20066)
		(layer "F.Cu")
		(net "M_E_CPU1_SA_CB<4>")
	)
	(segment
		(start 152.224994 -272.557748)
		(end 152.224994 -272.558002)
		(width 0.101854)
		(layer "F.Cu")
		(net "M_E_CPU1_SA_CB<4>")
	)
	(segment
		(start 154.242008 -271.355312)
		(end 154.851608 -271.355312)
		(width 0.20066)
		(layer "F.Cu")
		(net "M_E_CPU1_SA_CB<4>")
	)
	(segment
		(start 154.476196 -272.989294)
		(end 154.852878 -272.612612)
		(width 0.20066)
		(layer "F.Cu")
		(net "M_E_CPU1_SA_CB<4>")
	)
	(segment
		(start 164.918136 -272.966688)
		(end 164.493194 -272.541746)
		(width 0.20066)
		(layer "F.Cu")
		(net "M_E_CPU1_SA_CB<4>")
	)
	(segment
		(start 136.655048 -259.081016)
		(end 136.666986 -259.109718)
		(width 0.088646)
		(layer "F.Cu")
		(net "M_E_CPU1_SA_CB<4>")
	)
	(arc
		(start 138.572494 -259.469636)
		(mid 138.646663 -259.443379)
		(end 138.717274 -259.408676)
		(width 0.088646)
		(layer "F.Cu")
		(net "M_E_CPU1_SA_CB<4>")
	)
	(arc
		(start 138.723116 -259.405374)
		(mid 138.763937 -259.378216)
		(end 138.80084 -259.345938)
		(width 0.088646)
		(layer "F.Cu")
		(net "M_E_CPU1_SA_CB<4>")
	)
	(arc
		(start 138.484356 -259.482082)
		(mid 138.528865 -259.478973)
		(end 138.572494 -259.469636)
		(width 0.088646)
		(layer "F.Cu")
		(net "M_E_CPU1_SA_CB<4>")
	)
	(segment
		(start 151.009858 -275.044154)
		(end 151.757888 -275.792184)
		(width 0.1016)
		(layer "F.Cu")
		(net "M_E_CPU1_SA_CB<3>")
	)
	(segment
		(start 168.016936 -276.791674)
		(end 167.9067 -276.791674)
		(width 0.20066)
		(layer "F.Cu")
		(net "M_E_CPU1_SA_CB<3>")
	)
	(segment
		(start 168.217596 -276.290786)
		(end 168.217596 -276.591014)
		(width 0.20066)
		(layer "F.Cu")
		(net "M_E_CPU1_SA_CB<3>")
	)
	(segment
		(start 150.34133 -271.700498)
		(end 151.009858 -275.044154)
		(width 0.1016)
		(layer "F.Cu")
		(net "M_E_CPU1_SA_CB<3>")
	)
	(segment
		(start 168.978834 -276.366732)
		(end 168.702228 -276.090126)
		(width 0.20066)
		(layer "F.Cu")
		(net "M_E_CPU1_SA_CB<3>")
	)
	(segment
		(start 164.36848 -276.366732)
		(end 162.913314 -276.366732)
		(width 0.20066)
		(layer "F.Cu")
		(net "M_E_CPU1_SA_CB<3>")
	)
	(segment
		(start 165.370256 -276.791674)
		(end 164.977572 -276.791674)
		(width 0.101854)
		(layer "F.Cu")
		(net "M_E_CPU1_SA_CB<3>")
	)
	(segment
		(start 156.012134 -275.792184)
		(end 156.382974 -276.163024)
		(width 0.20066)
		(layer "F.Cu")
		(net "M_E_CPU1_SA_CB<3>")
	)
	(segment
		(start 168.702228 -276.090126)
		(end 168.418256 -276.090126)
		(width 0.20066)
		(layer "F.Cu")
		(net "M_E_CPU1_SA_CB<3>")
	)
	(segment
		(start 152.356058 -275.792184)
		(end 156.012134 -275.792184)
		(width 0.20066)
		(layer "F.Cu")
		(net "M_E_CPU1_SA_CB<3>")
	)
	(segment
		(start 167.262048 -276.791674)
		(end 165.370256 -276.791674)
		(width 0.1016)
		(layer "F.Cu")
		(net "M_E_CPU1_SA_CB<3>")
	)
	(segment
		(start 157.07741 -275.941536)
		(end 157.510988 -275.941536)
		(width 0.20066)
		(layer "F.Cu")
		(net "M_E_CPU1_SA_CB<3>")
	)
	(segment
		(start 168.217596 -276.591014)
		(end 168.016936 -276.791674)
		(width 0.20066)
		(layer "F.Cu")
		(net "M_E_CPU1_SA_CB<3>")
	)
	(segment
		(start 164.793422 -276.791674)
		(end 164.36848 -276.366732)
		(width 0.20066)
		(layer "F.Cu")
		(net "M_E_CPU1_SA_CB<3>")
	)
	(segment
		(start 140.596874 -261.816596)
		(end 140.596874 -261.924038)
		(width 0.088646)
		(layer "F.Cu")
		(net "M_E_CPU1_SA_CB<3>")
	)
	(segment
		(start 160.638236 -276.366732)
		(end 162.913314 -276.366732)
		(width 0.20066)
		(layer "F.Cu")
		(net "M_E_CPU1_SA_CB<3>")
	)
	(segment
		(start 157.510988 -275.941536)
		(end 157.818582 -275.941536)
		(width 0.101854)
		(layer "F.Cu")
		(net "M_E_CPU1_SA_CB<3>")
	)
	(segment
		(start 170.457114 -276.366732)
		(end 168.978834 -276.366732)
		(width 0.20066)
		(layer "F.Cu")
		(net "M_E_CPU1_SA_CB<3>")
	)
	(segment
		(start 160.002474 -275.941536)
		(end 160.21304 -275.941536)
		(width 0.20066)
		(layer "F.Cu")
		(net "M_E_CPU1_SA_CB<3>")
	)
	(segment
		(start 156.382974 -276.163024)
		(end 156.855922 -276.163024)
		(width 0.20066)
		(layer "F.Cu")
		(net "M_E_CPU1_SA_CB<3>")
	)
	(segment
		(start 138.904472 -260.862064)
		(end 139.642342 -260.862064)
		(width 0.088646)
		(layer "F.Cu")
		(net "M_E_CPU1_SA_CB<3>")
	)
	(segment
		(start 150.304754 -271.631918)
		(end 150.34133 -271.700498)
		(width 0.1016)
		(layer "F.Cu")
		(net "M_E_CPU1_SA_CB<3>")
	)
	(segment
		(start 151.757888 -275.792184)
		(end 152.356058 -275.792184)
		(width 0.1016)
		(layer "F.Cu")
		(net "M_E_CPU1_SA_CB<3>")
	)
	(segment
		(start 168.418256 -276.090126)
		(end 168.217596 -276.290786)
		(width 0.20066)
		(layer "F.Cu")
		(net "M_E_CPU1_SA_CB<3>")
	)
	(segment
		(start 156.855922 -276.163024)
		(end 157.07741 -275.941536)
		(width 0.20066)
		(layer "F.Cu")
		(net "M_E_CPU1_SA_CB<3>")
	)
	(segment
		(start 159.807148 -275.941536)
		(end 160.002474 -275.941536)
		(width 0.101854)
		(layer "F.Cu")
		(net "M_E_CPU1_SA_CB<3>")
	)
	(segment
		(start 157.818582 -275.941536)
		(end 159.807148 -275.941536)
		(width 0.1016)
		(layer "F.Cu")
		(net "M_E_CPU1_SA_CB<3>")
	)
	(segment
		(start 138.534648 -260.708902)
		(end 138.904472 -260.862064)
		(width 0.088646)
		(layer "F.Cu")
		(net "M_E_CPU1_SA_CB<3>")
	)
	(segment
		(start 139.642342 -260.862064)
		(end 140.596874 -261.816596)
		(width 0.088646)
		(layer "F.Cu")
		(net "M_E_CPU1_SA_CB<3>")
	)
	(segment
		(start 160.21304 -275.941536)
		(end 160.638236 -276.366732)
		(width 0.20066)
		(layer "F.Cu")
		(net "M_E_CPU1_SA_CB<3>")
	)
	(segment
		(start 140.894816 -262.22198)
		(end 150.304754 -271.631918)
		(width 0.1016)
		(layer "F.Cu")
		(net "M_E_CPU1_SA_CB<3>")
	)
	(segment
		(start 164.977572 -276.791674)
		(end 164.793422 -276.791674)
		(width 0.20066)
		(layer "F.Cu")
		(net "M_E_CPU1_SA_CB<3>")
	)
	(segment
		(start 140.596874 -261.924038)
		(end 140.894816 -262.22198)
		(width 0.088646)
		(layer "F.Cu")
		(net "M_E_CPU1_SA_CB<3>")
	)
	(segment
		(start 167.9067 -276.791674)
		(end 167.262048 -276.791674)
		(width 0.101854)
		(layer "F.Cu")
		(net "M_E_CPU1_SA_CB<3>")
	)
	(segment
		(start 150.96363 -276.763734)
		(end 151.535384 -277.113238)
		(width 0.1016)
		(layer "F.Cu")
		(net "M_E_CPU1_SA_CB<2>")
	)
	(segment
		(start 150.631906 -276.266402)
		(end 150.96363 -276.763734)
		(width 0.1016)
		(layer "F.Cu")
		(net "M_E_CPU1_SA_CB<2>")
	)
	(segment
		(start 140.45057 -262.640318)
		(end 149.7711 -271.960848)
		(width 0.1016)
		(layer "F.Cu")
		(net "M_E_CPU1_SA_CB<2>")
	)
	(segment
		(start 168.911524 -278.066754)
		(end 168.648126 -277.803356)
		(width 0.20066)
		(layer "F.Cu")
		(net "M_E_CPU1_SA_CB<2>")
	)
	(segment
		(start 167.609266 -277.358856)
		(end 167.43934 -277.528782)
		(width 0.20066)
		(layer "F.Cu")
		(net "M_E_CPU1_SA_CB<2>")
	)
	(segment
		(start 168.648126 -277.523956)
		(end 168.483026 -277.358856)
		(width 0.20066)
		(layer "F.Cu")
		(net "M_E_CPU1_SA_CB<2>")
	)
	(segment
		(start 140.27658 -262.466328)
		(end 140.45057 -262.640318)
		(width 0.088646)
		(layer "F.Cu")
		(net "M_E_CPU1_SA_CB<2>")
	)
	(segment
		(start 168.483026 -277.358856)
		(end 167.609266 -277.358856)
		(width 0.20066)
		(layer "F.Cu")
		(net "M_E_CPU1_SA_CB<2>")
	)
	(segment
		(start 157.123638 -277.864824)
		(end 157.346904 -277.641558)
		(width 0.20066)
		(layer "F.Cu")
		(net "M_E_CPU1_SA_CB<2>")
	)
	(segment
		(start 160.199324 -277.641558)
		(end 160.542732 -277.984966)
		(width 0.20066)
		(layer "F.Cu")
		(net "M_E_CPU1_SA_CB<2>")
	)
	(segment
		(start 153.775156 -277.284688)
		(end 155.241498 -277.284688)
		(width 0.20066)
		(layer "F.Cu")
		(net "M_E_CPU1_SA_CB<2>")
	)
	(segment
		(start 149.7711 -271.960848)
		(end 150.631906 -276.266402)
		(width 0.1016)
		(layer "F.Cu")
		(net "M_E_CPU1_SA_CB<2>")
	)
	(segment
		(start 157.510988 -277.641558)
		(end 157.824678 -277.641558)
		(width 0.101854)
		(layer "F.Cu")
		(net "M_E_CPU1_SA_CB<2>")
	)
	(segment
		(start 165.054788 -277.641812)
		(end 164.606986 -277.641812)
		(width 0.20066)
		(layer "F.Cu")
		(net "M_E_CPU1_SA_CB<2>")
	)
	(segment
		(start 160.542732 -277.984966)
		(end 161.396934 -277.984966)
		(width 0.20066)
		(layer "F.Cu")
		(net "M_E_CPU1_SA_CB<2>")
	)
	(segment
		(start 138.416284 -261.616698)
		(end 138.817096 -261.847076)
		(width 0.088646)
		(layer "F.Cu")
		(net "M_E_CPU1_SA_CB<2>")
	)
	(segment
		(start 168.648126 -277.803356)
		(end 168.648126 -277.523956)
		(width 0.20066)
		(layer "F.Cu")
		(net "M_E_CPU1_SA_CB<2>")
	)
	(segment
		(start 155.241498 -277.284688)
		(end 155.821634 -277.864824)
		(width 0.20066)
		(layer "F.Cu")
		(net "M_E_CPU1_SA_CB<2>")
	)
	(segment
		(start 152.356312 -277.113238)
		(end 153.603706 -277.113238)
		(width 0.20066)
		(layer "F.Cu")
		(net "M_E_CPU1_SA_CB<2>")
	)
	(segment
		(start 157.824678 -277.641558)
		(end 159.790638 -277.641558)
		(width 0.1016)
		(layer "F.Cu")
		(net "M_E_CPU1_SA_CB<2>")
	)
	(segment
		(start 161.396934 -277.984966)
		(end 161.988754 -278.066754)
		(width 0.20066)
		(layer "F.Cu")
		(net "M_E_CPU1_SA_CB<2>")
	)
	(segment
		(start 167.32631 -277.641812)
		(end 165.362128 -277.641812)
		(width 0.1016)
		(layer "F.Cu")
		(net "M_E_CPU1_SA_CB<2>")
	)
	(segment
		(start 160.002474 -277.641558)
		(end 160.199324 -277.641558)
		(width 0.20066)
		(layer "F.Cu")
		(net "M_E_CPU1_SA_CB<2>")
	)
	(segment
		(start 159.790638 -277.641558)
		(end 160.002474 -277.641558)
		(width 0.101854)
		(layer "F.Cu")
		(net "M_E_CPU1_SA_CB<2>")
	)
	(segment
		(start 138.948414 -261.95147)
		(end 139.39266 -262.251952)
		(width 0.088646)
		(layer "F.Cu")
		(net "M_E_CPU1_SA_CB<2>")
	)
	(segment
		(start 153.603706 -277.113238)
		(end 153.775156 -277.284688)
		(width 0.20066)
		(layer "F.Cu")
		(net "M_E_CPU1_SA_CB<2>")
	)
	(segment
		(start 139.39266 -262.251952)
		(end 139.585954 -262.3185)
		(width 0.088646)
		(layer "F.Cu")
		(net "M_E_CPU1_SA_CB<2>")
	)
	(segment
		(start 167.43934 -277.528782)
		(end 167.32631 -277.641812)
		(width 0.101854)
		(layer "F.Cu")
		(net "M_E_CPU1_SA_CB<2>")
	)
	(segment
		(start 163.621974 -277.966678)
		(end 163.521898 -278.066754)
		(width 0.20066)
		(layer "F.Cu")
		(net "M_E_CPU1_SA_CB<2>")
	)
	(segment
		(start 151.535384 -277.113238)
		(end 152.356312 -277.113238)
		(width 0.1016)
		(layer "F.Cu")
		(net "M_E_CPU1_SA_CB<2>")
	)
	(segment
		(start 170.457114 -278.066754)
		(end 168.911524 -278.066754)
		(width 0.20066)
		(layer "F.Cu")
		(net "M_E_CPU1_SA_CB<2>")
	)
	(segment
		(start 164.28212 -277.966678)
		(end 163.621974 -277.966678)
		(width 0.20066)
		(layer "F.Cu")
		(net "M_E_CPU1_SA_CB<2>")
	)
	(segment
		(start 163.521898 -278.066754)
		(end 162.913314 -278.066754)
		(width 0.20066)
		(layer "F.Cu")
		(net "M_E_CPU1_SA_CB<2>")
	)
	(segment
		(start 157.346904 -277.641558)
		(end 157.510988 -277.641558)
		(width 0.20066)
		(layer "F.Cu")
		(net "M_E_CPU1_SA_CB<2>")
	)
	(segment
		(start 155.821634 -277.864824)
		(end 157.123638 -277.864824)
		(width 0.20066)
		(layer "F.Cu")
		(net "M_E_CPU1_SA_CB<2>")
	)
	(segment
		(start 164.606986 -277.641812)
		(end 164.28212 -277.966678)
		(width 0.20066)
		(layer "F.Cu")
		(net "M_E_CPU1_SA_CB<2>")
	)
	(segment
		(start 165.362128 -277.641812)
		(end 165.054788 -277.641812)
		(width 0.101854)
		(layer "F.Cu")
		(net "M_E_CPU1_SA_CB<2>")
	)
	(segment
		(start 139.867386 -262.466328)
		(end 140.27658 -262.466328)
		(width 0.088646)
		(layer "F.Cu")
		(net "M_E_CPU1_SA_CB<2>")
	)
	(segment
		(start 161.988754 -278.066754)
		(end 162.913314 -278.066754)
		(width 0.20066)
		(layer "F.Cu")
		(net "M_E_CPU1_SA_CB<2>")
	)
	(arc
		(start 139.762992 -262.386572)
		(mid 139.817516 -262.423405)
		(end 139.867386 -262.466328)
		(width 0.088646)
		(layer "F.Cu")
		(net "M_E_CPU1_SA_CB<2>")
	)
	(arc
		(start 138.064494 -261.522718)
		(mid 138.246565 -261.546604)
		(end 138.416284 -261.616698)
		(width 0.088646)
		(layer "F.Cu")
		(net "M_E_CPU1_SA_CB<2>")
	)
	(arc
		(start 138.817096 -261.847076)
		(mid 138.869852 -261.881452)
		(end 138.918442 -261.921498)
		(width 0.088646)
		(layer "F.Cu")
		(net "M_E_CPU1_SA_CB<2>")
	)
	(arc
		(start 138.918442 -261.921498)
		(mid 138.933709 -261.936203)
		(end 138.948414 -261.95147)
		(width 0.088646)
		(layer "F.Cu")
		(net "M_E_CPU1_SA_CB<2>")
	)
	(arc
		(start 139.585954 -262.3185)
		(mid 139.677355 -262.345044)
		(end 139.762992 -262.386572)
		(width 0.088646)
		(layer "F.Cu")
		(net "M_E_CPU1_SA_CB<2>")
	)
	(segment
		(start 161.903918 -276.791674)
		(end 161.611056 -276.791674)
		(width 0.101854)
		(layer "F.Cu")
		(net "M_E_CPU1_SA_CB<1>")
	)
	(segment
		(start 156.8704 -276.933406)
		(end 157.243526 -276.933406)
		(width 0.20066)
		(layer "F.Cu")
		(net "M_E_CPU1_SA_CB<1>")
	)
	(segment
		(start 151.321262 -276.366986)
		(end 151.576278 -276.536912)
		(width 0.1016)
		(layer "F.Cu")
		(net "M_E_CPU1_SA_CB<1>")
	)
	(segment
		(start 157.526736 -277.216616)
		(end 158.813246 -277.216616)
		(width 0.20066)
		(layer "F.Cu")
		(net "M_E_CPU1_SA_CB<1>")
	)
	(segment
		(start 152.356312 -276.447758)
		(end 154.173682 -276.447758)
		(width 0.20066)
		(layer "F.Cu")
		(net "M_E_CPU1_SA_CB<1>")
	)
	(segment
		(start 136.875266 -261.206488)
		(end 137.049764 -261.03199)
		(width 0.088646)
		(layer "F.Cu")
		(net "M_E_CPU1_SA_CB<1>")
	)
	(segment
		(start 161.357056 -277.279608)
		(end 161.156396 -277.480268)
		(width 0.20066)
		(layer "F.Cu")
		(net "M_E_CPU1_SA_CB<1>")
	)
	(segment
		(start 140.364718 -262.123174)
		(end 140.670026 -262.428482)
		(width 0.088646)
		(layer "F.Cu")
		(net "M_E_CPU1_SA_CB<1>")
	)
	(segment
		(start 158.8135 -277.21687)
		(end 158.813246 -277.216616)
		(width 0.20066)
		(layer "F.Cu")
		(net "M_E_CPU1_SA_CB<1>")
	)
	(segment
		(start 160.137348 -277.07082)
		(end 159.991298 -277.21687)
		(width 0.20066)
		(layer "F.Cu")
		(net "M_E_CPU1_SA_CB<1>")
	)
	(segment
		(start 137.334498 -261.113524)
		(end 137.76833 -261.113524)
		(width 0.088646)
		(layer "F.Cu")
		(net "M_E_CPU1_SA_CB<1>")
	)
	(segment
		(start 138.145012 -260.86943)
		(end 138.389106 -261.113524)
		(width 0.088646)
		(layer "F.Cu")
		(net "M_E_CPU1_SA_CB<1>")
	)
	(segment
		(start 137.049764 -261.03199)
		(end 137.252964 -261.03199)
		(width 0.088646)
		(layer "F.Cu")
		(net "M_E_CPU1_SA_CB<1>")
	)
	(segment
		(start 154.354022 -276.628098)
		(end 155.15082 -276.628098)
		(width 0.20066)
		(layer "F.Cu")
		(net "M_E_CPU1_SA_CB<1>")
	)
	(segment
		(start 137.252964 -261.03199)
		(end 137.334498 -261.113524)
		(width 0.088646)
		(layer "F.Cu")
		(net "M_E_CPU1_SA_CB<1>")
	)
	(segment
		(start 161.357056 -276.933152)
		(end 161.357056 -277.279608)
		(width 0.20066)
		(layer "F.Cu")
		(net "M_E_CPU1_SA_CB<1>")
	)
	(segment
		(start 164.102542 -276.791674)
		(end 163.91128 -276.791674)
		(width 0.101854)
		(layer "F.Cu")
		(net "M_E_CPU1_SA_CB<1>")
	)
	(segment
		(start 159.991298 -277.21687)
		(end 158.8135 -277.21687)
		(width 0.20066)
		(layer "F.Cu")
		(net "M_E_CPU1_SA_CB<1>")
	)
	(segment
		(start 155.15082 -276.628098)
		(end 155.33116 -276.447758)
		(width 0.20066)
		(layer "F.Cu")
		(net "M_E_CPU1_SA_CB<1>")
	)
	(segment
		(start 139.575286 -261.113524)
		(end 140.364718 -261.902956)
		(width 0.088646)
		(layer "F.Cu")
		(net "M_E_CPU1_SA_CB<1>")
	)
	(segment
		(start 156.082238 -277.209504)
		(end 156.594302 -277.209504)
		(width 0.20066)
		(layer "F.Cu")
		(net "M_E_CPU1_SA_CB<1>")
	)
	(segment
		(start 166.357046 -277.216616)
		(end 164.63518 -277.216616)
		(width 0.20066)
		(layer "F.Cu")
		(net "M_E_CPU1_SA_CB<1>")
	)
	(segment
		(start 136.654794 -261.206488)
		(end 136.875266 -261.206488)
		(width 0.088646)
		(layer "F.Cu")
		(net "M_E_CPU1_SA_CB<1>")
	)
	(segment
		(start 136.552432 -261.104126)
		(end 136.654794 -261.206488)
		(width 0.088646)
		(layer "F.Cu")
		(net "M_E_CPU1_SA_CB<1>")
	)
	(segment
		(start 150.819358 -275.647404)
		(end 151.232108 -275.922232)
		(width 0.1016)
		(layer "F.Cu")
		(net "M_E_CPU1_SA_CB<1>")
	)
	(segment
		(start 155.897834 -276.648418)
		(end 155.897834 -277.0251)
		(width 0.20066)
		(layer "F.Cu")
		(net "M_E_CPU1_SA_CB<1>")
	)
	(segment
		(start 161.156396 -277.480268)
		(end 160.831022 -277.480268)
		(width 0.20066)
		(layer "F.Cu")
		(net "M_E_CPU1_SA_CB<1>")
	)
	(segment
		(start 155.33116 -276.447758)
		(end 155.697174 -276.447758)
		(width 0.20066)
		(layer "F.Cu")
		(net "M_E_CPU1_SA_CB<1>")
	)
	(segment
		(start 151.576278 -276.536912)
		(end 152.021032 -276.447758)
		(width 0.1016)
		(layer "F.Cu")
		(net "M_E_CPU1_SA_CB<1>")
	)
	(segment
		(start 160.831022 -277.480268)
		(end 160.421574 -277.07082)
		(width 0.20066)
		(layer "F.Cu")
		(net "M_E_CPU1_SA_CB<1>")
	)
	(segment
		(start 151.232108 -275.922232)
		(end 151.321262 -276.366986)
		(width 0.1016)
		(layer "F.Cu")
		(net "M_E_CPU1_SA_CB<1>")
	)
	(segment
		(start 163.91128 -276.791674)
		(end 161.903918 -276.791674)
		(width 0.1016)
		(layer "F.Cu")
		(net "M_E_CPU1_SA_CB<1>")
	)
	(segment
		(start 155.897834 -277.0251)
		(end 156.082238 -277.209504)
		(width 0.20066)
		(layer "F.Cu")
		(net "M_E_CPU1_SA_CB<1>")
	)
	(segment
		(start 164.63518 -277.216616)
		(end 164.210238 -276.791674)
		(width 0.20066)
		(layer "F.Cu")
		(net "M_E_CPU1_SA_CB<1>")
	)
	(segment
		(start 136.552432 -260.811518)
		(end 136.552432 -261.104126)
		(width 0.088646)
		(layer "F.Cu")
		(net "M_E_CPU1_SA_CB<1>")
	)
	(segment
		(start 138.389106 -261.113524)
		(end 139.575286 -261.113524)
		(width 0.088646)
		(layer "F.Cu")
		(net "M_E_CPU1_SA_CB<1>")
	)
	(segment
		(start 160.421574 -277.07082)
		(end 160.137348 -277.07082)
		(width 0.20066)
		(layer "F.Cu")
		(net "M_E_CPU1_SA_CB<1>")
	)
	(segment
		(start 161.611056 -276.791674)
		(end 161.498534 -276.791674)
		(width 0.20066)
		(layer "F.Cu")
		(net "M_E_CPU1_SA_CB<1>")
	)
	(segment
		(start 155.697174 -276.447758)
		(end 155.897834 -276.648418)
		(width 0.20066)
		(layer "F.Cu")
		(net "M_E_CPU1_SA_CB<1>")
	)
	(segment
		(start 154.173682 -276.447758)
		(end 154.354022 -276.628098)
		(width 0.20066)
		(layer "F.Cu")
		(net "M_E_CPU1_SA_CB<1>")
	)
	(segment
		(start 150.052532 -271.810988)
		(end 150.819358 -275.647404)
		(width 0.1016)
		(layer "F.Cu")
		(net "M_E_CPU1_SA_CB<1>")
	)
	(segment
		(start 140.670026 -262.428482)
		(end 150.052532 -271.810988)
		(width 0.1016)
		(layer "F.Cu")
		(net "M_E_CPU1_SA_CB<1>")
	)
	(segment
		(start 156.594302 -277.209504)
		(end 156.8704 -276.933406)
		(width 0.20066)
		(layer "F.Cu")
		(net "M_E_CPU1_SA_CB<1>")
	)
	(segment
		(start 140.364718 -261.902956)
		(end 140.364718 -262.123174)
		(width 0.088646)
		(layer "F.Cu")
		(net "M_E_CPU1_SA_CB<1>")
	)
	(segment
		(start 161.498534 -276.791674)
		(end 161.357056 -276.933152)
		(width 0.20066)
		(layer "F.Cu")
		(net "M_E_CPU1_SA_CB<1>")
	)
	(segment
		(start 137.76833 -261.113524)
		(end 138.012424 -260.86943)
		(width 0.088646)
		(layer "F.Cu")
		(net "M_E_CPU1_SA_CB<1>")
	)
	(segment
		(start 164.210238 -276.791674)
		(end 164.102542 -276.791674)
		(width 0.20066)
		(layer "F.Cu")
		(net "M_E_CPU1_SA_CB<1>")
	)
	(segment
		(start 138.012424 -260.86943)
		(end 138.145012 -260.86943)
		(width 0.088646)
		(layer "F.Cu")
		(net "M_E_CPU1_SA_CB<1>")
	)
	(segment
		(start 152.021032 -276.447758)
		(end 152.356312 -276.447758)
		(width 0.1016)
		(layer "F.Cu")
		(net "M_E_CPU1_SA_CB<1>")
	)
	(segment
		(start 136.655048 -260.708902)
		(end 136.552432 -260.811518)
		(width 0.088646)
		(layer "F.Cu")
		(net "M_E_CPU1_SA_CB<1>")
	)
	(segment
		(start 157.243526 -276.933406)
		(end 157.526736 -277.216616)
		(width 0.20066)
		(layer "F.Cu")
		(net "M_E_CPU1_SA_CB<1>")
	)
	(segment
		(start 152.931622 -277.76043)
		(end 153.216102 -277.76043)
		(width 0.20066)
		(layer "F.Cu")
		(net "M_E_CPU1_SA_CB<0>")
	)
	(segment
		(start 139.764262 -262.635238)
		(end 139.822174 -262.69315)
		(width 0.088646)
		(layer "F.Cu")
		(net "M_E_CPU1_SA_CB<0>")
	)
	(segment
		(start 160.470342 -278.426926)
		(end 159.980376 -278.916892)
		(width 0.20066)
		(layer "F.Cu")
		(net "M_E_CPU1_SA_CB<0>")
	)
	(segment
		(start 153.416762 -277.96109)
		(end 153.416762 -278.21636)
		(width 0.20066)
		(layer "F.Cu")
		(net "M_E_CPU1_SA_CB<0>")
	)
	(segment
		(start 164.462968 -278.894286)
		(end 164.462968 -278.590248)
		(width 0.20066)
		(layer "F.Cu")
		(net "M_E_CPU1_SA_CB<0>")
	)
	(segment
		(start 164.663882 -279.0952)
		(end 164.462968 -278.894286)
		(width 0.20066)
		(layer "F.Cu")
		(net "M_E_CPU1_SA_CB<0>")
	)
	(segment
		(start 150.49754 -277.150068)
		(end 151.089868 -277.742396)
		(width 0.1016)
		(layer "F.Cu")
		(net "M_E_CPU1_SA_CB<0>")
	)
	(segment
		(start 139.822174 -262.69315)
		(end 140.07211 -262.69315)
		(width 0.088646)
		(layer "F.Cu")
		(net "M_E_CPU1_SA_CB<0>")
	)
	(segment
		(start 153.901902 -278.41702)
		(end 154.37866 -277.940262)
		(width 0.20066)
		(layer "F.Cu")
		(net "M_E_CPU1_SA_CB<0>")
	)
	(segment
		(start 154.992324 -277.940262)
		(end 155.57754 -278.525478)
		(width 0.20066)
		(layer "F.Cu")
		(net "M_E_CPU1_SA_CB<0>")
	)
	(segment
		(start 153.216102 -277.76043)
		(end 153.416762 -277.96109)
		(width 0.20066)
		(layer "F.Cu")
		(net "M_E_CPU1_SA_CB<0>")
	)
	(segment
		(start 158.012638 -278.916638)
		(end 158.813246 -278.916638)
		(width 0.20066)
		(layer "F.Cu")
		(net "M_E_CPU1_SA_CB<0>")
	)
	(segment
		(start 154.37866 -277.940262)
		(end 154.992324 -277.940262)
		(width 0.20066)
		(layer "F.Cu")
		(net "M_E_CPU1_SA_CB<0>")
	)
	(segment
		(start 152.530302 -278.41702)
		(end 152.730962 -278.21636)
		(width 0.20066)
		(layer "F.Cu")
		(net "M_E_CPU1_SA_CB<0>")
	)
	(segment
		(start 137.124694 -261.522718)
		(end 137.125964 -261.522718)
		(width 0.088646)
		(layer "F.Cu")
		(net "M_E_CPU1_SA_CB<0>")
	)
	(segment
		(start 140.235686 -262.856726)
		(end 149.489414 -272.110454)
		(width 0.1016)
		(layer "F.Cu")
		(net "M_E_CPU1_SA_CB<0>")
	)
	(segment
		(start 138.657076 -261.974838)
		(end 138.721846 -262.012176)
		(width 0.088646)
		(layer "F.Cu")
		(net "M_E_CPU1_SA_CB<0>")
	)
	(segment
		(start 159.980376 -278.916892)
		(end 158.8135 -278.916892)
		(width 0.20066)
		(layer "F.Cu")
		(net "M_E_CPU1_SA_CB<0>")
	)
	(segment
		(start 151.314912 -277.742396)
		(end 151.571706 -277.742396)
		(width 0.20066)
		(layer "F.Cu")
		(net "M_E_CPU1_SA_CB<0>")
	)
	(segment
		(start 157.908244 -279.021032)
		(end 158.012638 -278.916638)
		(width 0.20066)
		(layer "F.Cu")
		(net "M_E_CPU1_SA_CB<0>")
	)
	(segment
		(start 164.462968 -278.590248)
		(end 164.262308 -278.389588)
		(width 0.20066)
		(layer "F.Cu")
		(net "M_E_CPU1_SA_CB<0>")
	)
	(segment
		(start 152.730962 -278.21636)
		(end 152.730962 -277.96109)
		(width 0.20066)
		(layer "F.Cu")
		(net "M_E_CPU1_SA_CB<0>")
	)
	(segment
		(start 164.975794 -279.0952)
		(end 164.663882 -279.0952)
		(width 0.20066)
		(layer "F.Cu")
		(net "M_E_CPU1_SA_CB<0>")
	)
	(segment
		(start 152.24633 -278.41702)
		(end 152.530302 -278.41702)
		(width 0.20066)
		(layer "F.Cu")
		(net "M_E_CPU1_SA_CB<0>")
	)
	(segment
		(start 163.745418 -278.491696)
		(end 161.907982 -278.491696)
		(width 0.1016)
		(layer "F.Cu")
		(net "M_E_CPU1_SA_CB<0>")
	)
	(segment
		(start 153.617422 -278.41702)
		(end 153.901902 -278.41702)
		(width 0.20066)
		(layer "F.Cu")
		(net "M_E_CPU1_SA_CB<0>")
	)
	(segment
		(start 153.416762 -278.21636)
		(end 153.617422 -278.41702)
		(width 0.20066)
		(layer "F.Cu")
		(net "M_E_CPU1_SA_CB<0>")
	)
	(segment
		(start 164.102542 -278.389588)
		(end 163.847526 -278.389588)
		(width 0.101854)
		(layer "F.Cu")
		(net "M_E_CPU1_SA_CB<0>")
	)
	(segment
		(start 158.8135 -278.916892)
		(end 158.813246 -278.916638)
		(width 0.20066)
		(layer "F.Cu")
		(net "M_E_CPU1_SA_CB<0>")
	)
	(segment
		(start 138.79957 -262.071612)
		(end 138.846306 -262.128762)
		(width 0.088646)
		(layer "F.Cu")
		(net "M_E_CPU1_SA_CB<0>")
	)
	(segment
		(start 140.07211 -262.69315)
		(end 140.235686 -262.856726)
		(width 0.088646)
		(layer "F.Cu")
		(net "M_E_CPU1_SA_CB<0>")
	)
	(segment
		(start 155.57754 -278.525478)
		(end 157.128464 -278.525478)
		(width 0.20066)
		(layer "F.Cu")
		(net "M_E_CPU1_SA_CB<0>")
	)
	(segment
		(start 166.357046 -278.916638)
		(end 165.154356 -278.916638)
		(width 0.20066)
		(layer "F.Cu")
		(net "M_E_CPU1_SA_CB<0>")
	)
	(segment
		(start 138.339576 -261.916926)
		(end 138.439906 -261.916926)
		(width 0.088646)
		(layer "F.Cu")
		(net "M_E_CPU1_SA_CB<0>")
	)
	(segment
		(start 165.154356 -278.916638)
		(end 164.975794 -279.0952)
		(width 0.20066)
		(layer "F.Cu")
		(net "M_E_CPU1_SA_CB<0>")
	)
	(segment
		(start 139.248388 -262.41502)
		(end 139.474448 -262.497824)
		(width 0.088646)
		(layer "F.Cu")
		(net "M_E_CPU1_SA_CB<0>")
	)
	(segment
		(start 161.37382 -278.491696)
		(end 161.30905 -278.426926)
		(width 0.20066)
		(layer "F.Cu")
		(net "M_E_CPU1_SA_CB<0>")
	)
	(segment
		(start 151.089868 -277.742396)
		(end 151.314912 -277.742396)
		(width 0.1016)
		(layer "F.Cu")
		(net "M_E_CPU1_SA_CB<0>")
	)
	(segment
		(start 163.847526 -278.389588)
		(end 163.745418 -278.491696)
		(width 0.1016)
		(layer "F.Cu")
		(net "M_E_CPU1_SA_CB<0>")
	)
	(segment
		(start 161.907982 -278.491696)
		(end 161.611056 -278.491696)
		(width 0.101854)
		(layer "F.Cu")
		(net "M_E_CPU1_SA_CB<0>")
	)
	(segment
		(start 161.611056 -278.491696)
		(end 161.37382 -278.491696)
		(width 0.20066)
		(layer "F.Cu")
		(net "M_E_CPU1_SA_CB<0>")
	)
	(segment
		(start 138.846306 -262.128762)
		(end 139.248388 -262.41502)
		(width 0.088646)
		(layer "F.Cu")
		(net "M_E_CPU1_SA_CB<0>")
	)
	(segment
		(start 149.489414 -272.110454)
		(end 150.49754 -277.150068)
		(width 0.1016)
		(layer "F.Cu")
		(net "M_E_CPU1_SA_CB<0>")
	)
	(segment
		(start 151.571706 -277.742396)
		(end 152.24633 -278.41702)
		(width 0.20066)
		(layer "F.Cu")
		(net "M_E_CPU1_SA_CB<0>")
	)
	(segment
		(start 152.730962 -277.96109)
		(end 152.931622 -277.76043)
		(width 0.20066)
		(layer "F.Cu")
		(net "M_E_CPU1_SA_CB<0>")
	)
	(segment
		(start 161.30905 -278.426926)
		(end 160.470342 -278.426926)
		(width 0.20066)
		(layer "F.Cu")
		(net "M_E_CPU1_SA_CB<0>")
	)
	(segment
		(start 157.624018 -279.021032)
		(end 157.908244 -279.021032)
		(width 0.20066)
		(layer "F.Cu")
		(net "M_E_CPU1_SA_CB<0>")
	)
	(segment
		(start 157.128464 -278.525478)
		(end 157.624018 -279.021032)
		(width 0.20066)
		(layer "F.Cu")
		(net "M_E_CPU1_SA_CB<0>")
	)
	(segment
		(start 164.262308 -278.389588)
		(end 164.102542 -278.389588)
		(width 0.20066)
		(layer "F.Cu")
		(net "M_E_CPU1_SA_CB<0>")
	)
	(segment
		(start 137.125964 -261.522718)
		(end 137.41019 -261.806944)
		(width 0.088646)
		(layer "F.Cu")
		(net "M_E_CPU1_SA_CB<0>")
	)
	(arc
		(start 137.41019 -261.806944)
		(mid 137.442895 -261.837311)
		(end 137.478008 -261.864856)
		(width 0.088646)
		(layer "F.Cu")
		(net "M_E_CPU1_SA_CB<0>")
	)
	(arc
		(start 137.478008 -261.864856)
		(mid 137.842664 -262.007972)
		(end 138.231626 -261.96163)
		(width 0.088646)
		(layer "F.Cu")
		(net "M_E_CPU1_SA_CB<0>")
	)
	(arc
		(start 138.721846 -262.012176)
		(mid 138.762655 -262.039348)
		(end 138.79957 -262.071612)
		(width 0.088646)
		(layer "F.Cu")
		(net "M_E_CPU1_SA_CB<0>")
	)
	(arc
		(start 138.231626 -261.96163)
		(mid 138.281154 -261.928537)
		(end 138.339576 -261.916926)
		(width 0.088646)
		(layer "F.Cu")
		(net "M_E_CPU1_SA_CB<0>")
	)
	(arc
		(start 138.439906 -261.916926)
		(mid 138.552301 -261.931608)
		(end 138.657076 -261.974838)
		(width 0.088646)
		(layer "F.Cu")
		(net "M_E_CPU1_SA_CB<0>")
	)
	(arc
		(start 139.670536 -262.553196)
		(mid 139.720821 -262.590305)
		(end 139.764262 -262.635238)
		(width 0.088646)
		(layer "F.Cu")
		(net "M_E_CPU1_SA_CB<0>")
	)
	(arc
		(start 139.474448 -262.497824)
		(mid 139.576326 -262.511932)
		(end 139.670536 -262.553196)
		(width 0.088646)
		(layer "F.Cu")
		(net "M_E_CPU1_SA_CB<0>")
	)
	(segment
		(start 157.107382 -260.712458)
		(end 157.90799 -260.712458)
		(width 0.20066)
		(layer "F.Cu")
		(net "M_E_CPU1_SA_CA<6>")
	)
	(segment
		(start 136.732518 -252.78842)
		(end 137.262616 -252.84049)
		(width 0.1016)
		(layer "F.Cu")
		(net "M_E_CPU1_SA_CA<6>")
	)
	(segment
		(start 136.614916 -252.769878)
		(end 136.732518 -252.78842)
		(width 0.1016)
		(layer "F.Cu")
		(net "M_E_CPU1_SA_CA<6>")
	)
	(segment
		(start 159.32531 -261.066788)
		(end 158.813246 -261.066788)
		(width 0.20066)
		(layer "F.Cu")
		(net "M_E_CPU1_SA_CA<6>")
	)
	(segment
		(start 159.745172 -260.646926)
		(end 159.32531 -261.066788)
		(width 0.20066)
		(layer "F.Cu")
		(net "M_E_CPU1_SA_CA<6>")
	)
	(segment
		(start 132.220716 -250.231656)
		(end 132.235956 -250.304808)
		(width 0.088646)
		(layer "F.Cu")
		(net "M_E_CPU1_SA_CA<6>")
	)
	(segment
		(start 149.096222 -256.827782)
		(end 156.140658 -259.745734)
		(width 0.20066)
		(layer "F.Cu")
		(net "M_E_CPU1_SA_CA<6>")
	)
	(segment
		(start 132.220716 -250.14047)
		(end 132.220716 -250.231656)
		(width 0.088646)
		(layer "F.Cu")
		(net "M_E_CPU1_SA_CA<6>")
	)
	(segment
		(start 161.600134 -261.530592)
		(end 161.307018 -261.237476)
		(width 0.20066)
		(layer "F.Cu")
		(net "M_E_CPU1_SA_CA<6>")
	)
	(segment
		(start 160.428686 -260.439916)
		(end 160.221676 -260.646926)
		(width 0.20066)
		(layer "F.Cu")
		(net "M_E_CPU1_SA_CA<6>")
	)
	(segment
		(start 166.357046 -261.066788)
		(end 165.01999 -261.066788)
		(width 0.20066)
		(layer "F.Cu")
		(net "M_E_CPU1_SA_CA<6>")
	)
	(segment
		(start 142.169896 -254.159004)
		(end 144.838674 -256.827782)
		(width 0.1016)
		(layer "F.Cu")
		(net "M_E_CPU1_SA_CA<6>")
	)
	(segment
		(start 156.140658 -259.745734)
		(end 157.107382 -260.712458)
		(width 0.20066)
		(layer "F.Cu")
		(net "M_E_CPU1_SA_CA<6>")
	)
	(segment
		(start 132.351018 -250.525788)
		(end 132.522722 -250.71578)
		(width 0.088646)
		(layer "F.Cu")
		(net "M_E_CPU1_SA_CA<6>")
	)
	(segment
		(start 136.347454 -252.727206)
		(end 136.516364 -252.75413)
		(width 0.088646)
		(layer "F.Cu")
		(net "M_E_CPU1_SA_CA<6>")
	)
	(segment
		(start 132.782056 -249.521472)
		(end 132.624576 -249.596148)
		(width 0.088646)
		(layer "F.Cu")
		(net "M_E_CPU1_SA_CA<6>")
	)
	(segment
		(start 145.241518 -256.827782)
		(end 145.337276 -256.827782)
		(width 0.101854)
		(layer "F.Cu")
		(net "M_E_CPU1_SA_CA<6>")
	)
	(segment
		(start 132.624576 -249.596148)
		(end 132.50291 -249.666506)
		(width 0.088646)
		(layer "F.Cu")
		(net "M_E_CPU1_SA_CA<6>")
	)
	(segment
		(start 144.838674 -256.827782)
		(end 145.241518 -256.827782)
		(width 0.1016)
		(layer "F.Cu")
		(net "M_E_CPU1_SA_CA<6>")
	)
	(segment
		(start 165.01999 -261.066788)
		(end 164.578538 -261.50824)
		(width 0.20066)
		(layer "F.Cu")
		(net "M_E_CPU1_SA_CA<6>")
	)
	(segment
		(start 160.221676 -260.646926)
		(end 159.745172 -260.646926)
		(width 0.20066)
		(layer "F.Cu")
		(net "M_E_CPU1_SA_CA<6>")
	)
	(segment
		(start 135.962136 -252.612652)
		(end 136.347454 -252.727206)
		(width 0.088646)
		(layer "F.Cu")
		(net "M_E_CPU1_SA_CA<6>")
	)
	(segment
		(start 138.15949 -252.973586)
		(end 140.117576 -253.363476)
		(width 0.1016)
		(layer "F.Cu")
		(net "M_E_CPU1_SA_CA<6>")
	)
	(segment
		(start 161.891726 -261.530592)
		(end 161.600134 -261.530592)
		(width 0.20066)
		(layer "F.Cu")
		(net "M_E_CPU1_SA_CA<6>")
	)
	(segment
		(start 145.337276 -256.827782)
		(end 149.096222 -256.827782)
		(width 0.20066)
		(layer "F.Cu")
		(net "M_E_CPU1_SA_CA<6>")
	)
	(segment
		(start 157.90799 -260.712458)
		(end 158.26232 -261.066788)
		(width 0.20066)
		(layer "F.Cu")
		(net "M_E_CPU1_SA_CA<6>")
	)
	(segment
		(start 140.453364 -253.447804)
		(end 142.169896 -254.159004)
		(width 0.1016)
		(layer "F.Cu")
		(net "M_E_CPU1_SA_CA<6>")
	)
	(segment
		(start 132.522722 -250.71578)
		(end 132.625338 -250.807474)
		(width 0.088646)
		(layer "F.Cu")
		(net "M_E_CPU1_SA_CA<6>")
	)
	(segment
		(start 137.262616 -252.84049)
		(end 138.15949 -252.973586)
		(width 0.1016)
		(layer "F.Cu")
		(net "M_E_CPU1_SA_CA<6>")
	)
	(segment
		(start 161.307018 -261.237476)
		(end 161.307018 -260.73735)
		(width 0.20066)
		(layer "F.Cu")
		(net "M_E_CPU1_SA_CA<6>")
	)
	(segment
		(start 133.715506 -251.472446)
		(end 135.34263 -252.321314)
		(width 0.088646)
		(layer "F.Cu")
		(net "M_E_CPU1_SA_CA<6>")
	)
	(segment
		(start 163.907216 -261.49173)
		(end 161.963608 -261.49173)
		(width 0.1016)
		(layer "F.Cu")
		(net "M_E_CPU1_SA_CA<6>")
	)
	(segment
		(start 132.271516 -250.41606)
		(end 132.351018 -250.525788)
		(width 0.088646)
		(layer "F.Cu")
		(net "M_E_CPU1_SA_CA<6>")
	)
	(segment
		(start 135.34263 -252.321314)
		(end 135.469376 -252.38075)
		(width 0.088646)
		(layer "F.Cu")
		(net "M_E_CPU1_SA_CA<6>")
	)
	(segment
		(start 135.469376 -252.38075)
		(end 135.962136 -252.612652)
		(width 0.088646)
		(layer "F.Cu")
		(net "M_E_CPU1_SA_CA<6>")
	)
	(segment
		(start 164.578538 -261.50824)
		(end 163.923726 -261.50824)
		(width 0.20066)
		(layer "F.Cu")
		(net "M_E_CPU1_SA_CA<6>")
	)
	(segment
		(start 132.625338 -250.807474)
		(end 132.710174 -250.866148)
		(width 0.088646)
		(layer "F.Cu")
		(net "M_E_CPU1_SA_CA<6>")
	)
	(segment
		(start 161.009584 -260.439916)
		(end 160.428686 -260.439916)
		(width 0.20066)
		(layer "F.Cu")
		(net "M_E_CPU1_SA_CA<6>")
	)
	(segment
		(start 132.235956 -250.304808)
		(end 132.271516 -250.41606)
		(width 0.088646)
		(layer "F.Cu")
		(net "M_E_CPU1_SA_CA<6>")
	)
	(segment
		(start 163.923726 -261.50824)
		(end 163.907216 -261.49173)
		(width 0.1016)
		(layer "F.Cu")
		(net "M_E_CPU1_SA_CA<6>")
	)
	(segment
		(start 140.117576 -253.363476)
		(end 140.453364 -253.447804)
		(width 0.1016)
		(layer "F.Cu")
		(net "M_E_CPU1_SA_CA<6>")
	)
	(segment
		(start 132.710174 -250.866148)
		(end 133.715506 -251.472446)
		(width 0.088646)
		(layer "F.Cu")
		(net "M_E_CPU1_SA_CA<6>")
	)
	(segment
		(start 161.963608 -261.49173)
		(end 161.924746 -261.530592)
		(width 0.1016)
		(layer "F.Cu")
		(net "M_E_CPU1_SA_CA<6>")
	)
	(segment
		(start 133.255512 -249.342148)
		(end 132.782056 -249.521472)
		(width 0.088646)
		(layer "F.Cu")
		(net "M_E_CPU1_SA_CA<6>")
	)
	(segment
		(start 136.516364 -252.75413)
		(end 136.614916 -252.769878)
		(width 0.1016)
		(layer "F.Cu")
		(net "M_E_CPU1_SA_CA<6>")
	)
	(segment
		(start 161.924746 -261.530592)
		(end 161.896552 -261.530592)
		(width 0.1016)
		(layer "F.Cu")
		(net "M_E_CPU1_SA_CA<6>")
	)
	(segment
		(start 161.896552 -261.530592)
		(end 161.891726 -261.530592)
		(width 0.101854)
		(layer "F.Cu")
		(net "M_E_CPU1_SA_CA<6>")
	)
	(segment
		(start 161.307018 -260.73735)
		(end 161.009584 -260.439916)
		(width 0.20066)
		(layer "F.Cu")
		(net "M_E_CPU1_SA_CA<6>")
	)
	(segment
		(start 158.26232 -261.066788)
		(end 158.813246 -261.066788)
		(width 0.20066)
		(layer "F.Cu")
		(net "M_E_CPU1_SA_CA<6>")
	)
	(arc
		(start 132.50291 -249.666506)
		(mid 132.300087 -249.866737)
		(end 132.220716 -250.14047)
		(width 0.088646)
		(layer "F.Cu")
		(net "M_E_CPU1_SA_CA<6>")
	)
	(segment
		(start 155.583128 -260.239256)
		(end 156.825188 -261.481316)
		(width 0.20066)
		(layer "F.Cu")
		(net "M_E_CPU1_SA_CA<5>")
	)
	(segment
		(start 160.86963 -261.187946)
		(end 160.86963 -261.38251)
		(width 0.20066)
		(layer "F.Cu")
		(net "M_E_CPU1_SA_CA<5>")
	)
	(segment
		(start 138.064494 -253.383796)
		(end 138.523218 -253.38405)
		(width 0.088646)
		(layer "F.Cu")
		(net "M_E_CPU1_SA_CA<5>")
	)
	(segment
		(start 156.825188 -261.481316)
		(end 157.791658 -261.481316)
		(width 0.20066)
		(layer "F.Cu")
		(net "M_E_CPU1_SA_CA<5>")
	)
	(segment
		(start 170.457114 -261.916672)
		(end 169.3418 -261.916672)
		(width 0.20066)
		(layer "F.Cu")
		(net "M_E_CPU1_SA_CA<5>")
	)
	(segment
		(start 167.630602 -262.35787)
		(end 167.367458 -262.35787)
		(width 0.20066)
		(layer "F.Cu")
		(net "M_E_CPU1_SA_CA<5>")
	)
	(segment
		(start 164.733986 -262.357362)
		(end 164.293296 -261.916672)
		(width 0.20066)
		(layer "F.Cu")
		(net "M_E_CPU1_SA_CA<5>")
	)
	(segment
		(start 167.351202 -262.341614)
		(end 165.356286 -262.341614)
		(width 0.1016)
		(layer "F.Cu")
		(net "M_E_CPU1_SA_CA<5>")
	)
	(segment
		(start 140.41755 -253.779274)
		(end 142.024862 -254.445262)
		(width 0.1016)
		(layer "F.Cu")
		(net "M_E_CPU1_SA_CA<5>")
	)
	(segment
		(start 159.823658 -261.386574)
		(end 160.124394 -261.085838)
		(width 0.20066)
		(layer "F.Cu")
		(net "M_E_CPU1_SA_CA<5>")
	)
	(segment
		(start 139.636246 -253.605284)
		(end 139.943332 -253.698248)
		(width 0.088646)
		(layer "F.Cu")
		(net "M_E_CPU1_SA_CA<5>")
	)
	(segment
		(start 160.618932 -262.206232)
		(end 161.798762 -262.206232)
		(width 0.20066)
		(layer "F.Cu")
		(net "M_E_CPU1_SA_CA<5>")
	)
	(segment
		(start 168.49852 -261.489952)
		(end 167.630602 -262.35787)
		(width 0.20066)
		(layer "F.Cu")
		(net "M_E_CPU1_SA_CA<5>")
	)
	(segment
		(start 140.222478 -253.698248)
		(end 140.378688 -253.763272)
		(width 0.088646)
		(layer "F.Cu")
		(net "M_E_CPU1_SA_CA<5>")
	)
	(segment
		(start 145.337276 -257.467354)
		(end 148.891244 -257.467354)
		(width 0.20066)
		(layer "F.Cu")
		(net "M_E_CPU1_SA_CA<5>")
	)
	(segment
		(start 145.241518 -257.467354)
		(end 145.337276 -257.467354)
		(width 0.101854)
		(layer "F.Cu")
		(net "M_E_CPU1_SA_CA<5>")
	)
	(segment
		(start 139.943332 -253.698248)
		(end 140.222478 -253.698248)
		(width 0.088646)
		(layer "F.Cu")
		(net "M_E_CPU1_SA_CA<5>")
	)
	(segment
		(start 157.819344 -261.49173)
		(end 159.718502 -261.49173)
		(width 0.1016)
		(layer "F.Cu")
		(net "M_E_CPU1_SA_CA<5>")
	)
	(segment
		(start 148.891244 -257.467354)
		(end 155.583128 -260.239256)
		(width 0.20066)
		(layer "F.Cu")
		(net "M_E_CPU1_SA_CA<5>")
	)
	(segment
		(start 160.86963 -261.38251)
		(end 160.456626 -261.795514)
		(width 0.20066)
		(layer "F.Cu")
		(net "M_E_CPU1_SA_CA<5>")
	)
	(segment
		(start 161.798762 -262.206232)
		(end 162.088322 -261.916672)
		(width 0.20066)
		(layer "F.Cu")
		(net "M_E_CPU1_SA_CA<5>")
	)
	(segment
		(start 169.3418 -261.916672)
		(end 168.91508 -261.489952)
		(width 0.20066)
		(layer "F.Cu")
		(net "M_E_CPU1_SA_CA<5>")
	)
	(segment
		(start 160.124394 -261.085838)
		(end 160.767522 -261.085838)
		(width 0.20066)
		(layer "F.Cu")
		(net "M_E_CPU1_SA_CA<5>")
	)
	(segment
		(start 142.024862 -254.445262)
		(end 145.046954 -257.467354)
		(width 0.1016)
		(layer "F.Cu")
		(net "M_E_CPU1_SA_CA<5>")
	)
	(segment
		(start 165.340538 -262.357362)
		(end 165.335458 -262.357362)
		(width 0.101854)
		(layer "F.Cu")
		(net "M_E_CPU1_SA_CA<5>")
	)
	(segment
		(start 145.046954 -257.467354)
		(end 145.241518 -257.467354)
		(width 0.1016)
		(layer "F.Cu")
		(net "M_E_CPU1_SA_CA<5>")
	)
	(segment
		(start 157.791658 -261.481316)
		(end 157.80893 -261.481316)
		(width 0.101854)
		(layer "F.Cu")
		(net "M_E_CPU1_SA_CA<5>")
	)
	(segment
		(start 160.456626 -262.043926)
		(end 160.618932 -262.206232)
		(width 0.20066)
		(layer "F.Cu")
		(net "M_E_CPU1_SA_CA<5>")
	)
	(segment
		(start 160.456626 -261.795514)
		(end 160.456626 -262.043926)
		(width 0.20066)
		(layer "F.Cu")
		(net "M_E_CPU1_SA_CA<5>")
	)
	(segment
		(start 168.91508 -261.489952)
		(end 168.49852 -261.489952)
		(width 0.20066)
		(layer "F.Cu")
		(net "M_E_CPU1_SA_CA<5>")
	)
	(segment
		(start 164.293296 -261.916672)
		(end 162.913314 -261.916672)
		(width 0.20066)
		(layer "F.Cu")
		(net "M_E_CPU1_SA_CA<5>")
	)
	(segment
		(start 165.356286 -262.341614)
		(end 165.340538 -262.357362)
		(width 0.1016)
		(layer "F.Cu")
		(net "M_E_CPU1_SA_CA<5>")
	)
	(segment
		(start 165.335458 -262.357362)
		(end 164.733986 -262.357362)
		(width 0.20066)
		(layer "F.Cu")
		(net "M_E_CPU1_SA_CA<5>")
	)
	(segment
		(start 157.80893 -261.481316)
		(end 157.819344 -261.49173)
		(width 0.1016)
		(layer "F.Cu")
		(net "M_E_CPU1_SA_CA<5>")
	)
	(segment
		(start 159.718502 -261.49173)
		(end 159.823658 -261.386574)
		(width 0.1016)
		(layer "F.Cu")
		(net "M_E_CPU1_SA_CA<5>")
	)
	(segment
		(start 162.088322 -261.916672)
		(end 162.913314 -261.916672)
		(width 0.20066)
		(layer "F.Cu")
		(net "M_E_CPU1_SA_CA<5>")
	)
	(segment
		(start 167.367458 -262.35787)
		(end 167.351202 -262.341614)
		(width 0.1016)
		(layer "F.Cu")
		(net "M_E_CPU1_SA_CA<5>")
	)
	(segment
		(start 140.378688 -253.763272)
		(end 140.41755 -253.779274)
		(width 0.088646)
		(layer "F.Cu")
		(net "M_E_CPU1_SA_CA<5>")
	)
	(segment
		(start 160.767522 -261.085838)
		(end 160.86963 -261.187946)
		(width 0.20066)
		(layer "F.Cu")
		(net "M_E_CPU1_SA_CA<5>")
	)
	(segment
		(start 138.523218 -253.38405)
		(end 139.636246 -253.605284)
		(width 0.088646)
		(layer "F.Cu")
		(net "M_E_CPU1_SA_CA<5>")
	)
	(segment
		(start 161.913824 -263.191752)
		(end 161.891726 -263.21385)
		(width 0.1016)
		(layer "F.Cu")
		(net "M_E_CPU1_SA_CA<4>")
	)
	(segment
		(start 161.6202 -263.21385)
		(end 161.073846 -262.667496)
		(width 0.20066)
		(layer "F.Cu")
		(net "M_E_CPU1_SA_CA<4>")
	)
	(segment
		(start 164.827458 -263.221216)
		(end 163.923726 -263.221216)
		(width 0.20066)
		(layer "F.Cu")
		(net "M_E_CPU1_SA_CA<4>")
	)
	(segment
		(start 137.782046 -253.873)
		(end 137.510012 -253.493016)
		(width 0.088646)
		(layer "F.Cu")
		(net "M_E_CPU1_SA_CA<4>")
	)
	(segment
		(start 138.436096 -253.701042)
		(end 138.34745 -253.873254)
		(width 0.088646)
		(layer "F.Cu")
		(net "M_E_CPU1_SA_CA<4>")
	)
	(segment
		(start 140.960094 -254.347726)
		(end 140.87475 -254.347726)
		(width 0.1016)
		(layer "F.Cu")
		(net "M_E_CPU1_SA_CA<4>")
	)
	(segment
		(start 139.783566 -253.882652)
		(end 139.68349 -253.831344)
		(width 0.088646)
		(layer "F.Cu")
		(net "M_E_CPU1_SA_CA<4>")
	)
	(segment
		(start 166.23538 -262.888476)
		(end 165.160198 -262.888476)
		(width 0.20066)
		(layer "F.Cu")
		(net "M_E_CPU1_SA_CA<4>")
	)
	(segment
		(start 160.39846 -262.667496)
		(end 160.099248 -262.368284)
		(width 0.20066)
		(layer "F.Cu")
		(net "M_E_CPU1_SA_CA<4>")
	)
	(segment
		(start 156.477208 -262.298434)
		(end 154.964892 -260.782562)
		(width 0.20066)
		(layer "F.Cu")
		(net "M_E_CPU1_SA_CA<4>")
	)
	(segment
		(start 157.95244 -262.48106)
		(end 157.341062 -262.48106)
		(width 0.20066)
		(layer "F.Cu")
		(net "M_E_CPU1_SA_CA<4>")
	)
	(segment
		(start 137.510012 -253.493016)
		(end 137.400792 -253.383796)
		(width 0.088646)
		(layer "F.Cu")
		(net "M_E_CPU1_SA_CA<4>")
	)
	(segment
		(start 140.24864 -254.347726)
		(end 139.783566 -253.882652)
		(width 0.088646)
		(layer "F.Cu")
		(net "M_E_CPU1_SA_CA<4>")
	)
	(segment
		(start 165.160198 -262.888476)
		(end 164.827458 -263.221216)
		(width 0.20066)
		(layer "F.Cu")
		(net "M_E_CPU1_SA_CA<4>")
	)
	(segment
		(start 140.87475 -254.347726)
		(end 140.24864 -254.347726)
		(width 0.088646)
		(layer "F.Cu")
		(net "M_E_CPU1_SA_CA<4>")
	)
	(segment
		(start 148.63699 -258.161282)
		(end 148.533358 -258.05765)
		(width 0.1016)
		(layer "F.Cu")
		(net "M_E_CPU1_SA_CA<4>")
	)
	(segment
		(start 157.341062 -262.48106)
		(end 157.158436 -262.298434)
		(width 0.20066)
		(layer "F.Cu")
		(net "M_E_CPU1_SA_CA<4>")
	)
	(segment
		(start 141.875256 -254.726948)
		(end 140.960094 -254.347726)
		(width 0.1016)
		(layer "F.Cu")
		(net "M_E_CPU1_SA_CA<4>")
	)
	(segment
		(start 159.75838 -262.368284)
		(end 159.359854 -262.76681)
		(width 0.20066)
		(layer "F.Cu")
		(net "M_E_CPU1_SA_CA<4>")
	)
	(segment
		(start 160.099248 -262.368284)
		(end 159.75838 -262.368284)
		(width 0.20066)
		(layer "F.Cu")
		(net "M_E_CPU1_SA_CA<4>")
	)
	(segment
		(start 158.23819 -262.76681)
		(end 157.95244 -262.48106)
		(width 0.20066)
		(layer "F.Cu")
		(net "M_E_CPU1_SA_CA<4>")
	)
	(segment
		(start 138.549126 -253.644654)
		(end 138.436096 -253.701042)
		(width 0.088646)
		(layer "F.Cu")
		(net "M_E_CPU1_SA_CA<4>")
	)
	(segment
		(start 148.815044 -258.234942)
		(end 148.63699 -258.161282)
		(width 0.101854)
		(layer "F.Cu")
		(net "M_E_CPU1_SA_CA<4>")
	)
	(segment
		(start 157.158436 -262.298434)
		(end 156.477208 -262.298434)
		(width 0.20066)
		(layer "F.Cu")
		(net "M_E_CPU1_SA_CA<4>")
	)
	(segment
		(start 154.964892 -260.782562)
		(end 148.815044 -258.234942)
		(width 0.20066)
		(layer "F.Cu")
		(net "M_E_CPU1_SA_CA<4>")
	)
	(segment
		(start 137.782046 -253.873254)
		(end 137.782046 -253.873)
		(width 0.088646)
		(layer "F.Cu")
		(net "M_E_CPU1_SA_CA<4>")
	)
	(segment
		(start 166.357046 -262.76681)
		(end 166.23538 -262.888476)
		(width 0.20066)
		(layer "F.Cu")
		(net "M_E_CPU1_SA_CA<4>")
	)
	(segment
		(start 161.891726 -263.21385)
		(end 161.6202 -263.21385)
		(width 0.20066)
		(layer "F.Cu")
		(net "M_E_CPU1_SA_CA<4>")
	)
	(segment
		(start 161.073846 -262.667496)
		(end 160.39846 -262.667496)
		(width 0.20066)
		(layer "F.Cu")
		(net "M_E_CPU1_SA_CA<4>")
	)
	(segment
		(start 137.400792 -253.383796)
		(end 137.124694 -253.383796)
		(width 0.088646)
		(layer "F.Cu")
		(net "M_E_CPU1_SA_CA<4>")
	)
	(segment
		(start 139.53363 -253.781306)
		(end 138.638534 -253.630938)
		(width 0.088646)
		(layer "F.Cu")
		(net "M_E_CPU1_SA_CA<4>")
	)
	(segment
		(start 159.359854 -262.76681)
		(end 158.813246 -262.76681)
		(width 0.20066)
		(layer "F.Cu")
		(net "M_E_CPU1_SA_CA<4>")
	)
	(segment
		(start 158.813246 -262.76681)
		(end 158.23819 -262.76681)
		(width 0.20066)
		(layer "F.Cu")
		(net "M_E_CPU1_SA_CA<4>")
	)
	(segment
		(start 163.923726 -263.221216)
		(end 163.894262 -263.191752)
		(width 0.1016)
		(layer "F.Cu")
		(net "M_E_CPU1_SA_CA<4>")
	)
	(segment
		(start 148.533358 -258.05765)
		(end 145.205958 -258.05765)
		(width 0.1016)
		(layer "F.Cu")
		(net "M_E_CPU1_SA_CA<4>")
	)
	(segment
		(start 145.205958 -258.05765)
		(end 141.875256 -254.726948)
		(width 0.1016)
		(layer "F.Cu")
		(net "M_E_CPU1_SA_CA<4>")
	)
	(segment
		(start 163.894262 -263.191752)
		(end 161.913824 -263.191752)
		(width 0.1016)
		(layer "F.Cu")
		(net "M_E_CPU1_SA_CA<4>")
	)
	(arc
		(start 138.34745 -253.873254)
		(mid 138.064748 -253.94903)
		(end 137.782046 -253.873254)
		(width 0.088646)
		(layer "F.Cu")
		(net "M_E_CPU1_SA_CA<4>")
	)
	(arc
		(start 139.68349 -253.831344)
		(mid 139.610504 -253.800504)
		(end 139.53363 -253.781306)
		(width 0.088646)
		(layer "F.Cu")
		(net "M_E_CPU1_SA_CA<4>")
	)
	(arc
		(start 138.638534 -253.630938)
		(mid 138.592735 -253.630623)
		(end 138.549126 -253.644654)
		(width 0.088646)
		(layer "F.Cu")
		(net "M_E_CPU1_SA_CA<4>")
	)
	(segment
		(start 140.906246 -254.667258)
		(end 141.722602 -255.005586)
		(width 0.1016)
		(layer "F.Cu")
		(net "M_E_CPU1_SA_CA<3>")
	)
	(segment
		(start 148.3106 -258.739386)
		(end 148.445728 -258.874514)
		(width 0.20066)
		(layer "F.Cu")
		(net "M_E_CPU1_SA_CA<3>")
	)
	(segment
		(start 161.057844 -263.771126)
		(end 161.184844 -263.898126)
		(width 0.20066)
		(layer "F.Cu")
		(net "M_E_CPU1_SA_CA<3>")
	)
	(segment
		(start 138.726418 -254.525018)
		(end 138.917426 -254.474218)
		(width 0.088646)
		(layer "F.Cu")
		(net "M_E_CPU1_SA_CA<3>")
	)
	(segment
		(start 169.17416 -263.616694)
		(end 168.741598 -263.184132)
		(width 0.20066)
		(layer "F.Cu")
		(net "M_E_CPU1_SA_CA<3>")
	)
	(segment
		(start 161.184844 -263.898126)
		(end 162.018218 -263.898126)
		(width 0.20066)
		(layer "F.Cu")
		(net "M_E_CPU1_SA_CA<3>")
	)
	(segment
		(start 170.457114 -263.616694)
		(end 169.17416 -263.616694)
		(width 0.20066)
		(layer "F.Cu")
		(net "M_E_CPU1_SA_CA<3>")
	)
	(segment
		(start 165.352984 -264.055606)
		(end 165.335458 -264.055606)
		(width 0.101854)
		(layer "F.Cu")
		(net "M_E_CPU1_SA_CA<3>")
	)
	(segment
		(start 168.41978 -263.184132)
		(end 168.2496 -263.354312)
		(width 0.20066)
		(layer "F.Cu")
		(net "M_E_CPU1_SA_CA<3>")
	)
	(segment
		(start 138.917426 -254.474218)
		(end 139.20978 -254.474218)
		(width 0.088646)
		(layer "F.Cu")
		(net "M_E_CPU1_SA_CA<3>")
	)
	(segment
		(start 164.203634 -264.055606)
		(end 163.764722 -263.616694)
		(width 0.20066)
		(layer "F.Cu")
		(net "M_E_CPU1_SA_CA<3>")
	)
	(segment
		(start 156.38526 -263.175496)
		(end 157.791658 -263.175496)
		(width 0.20066)
		(layer "F.Cu")
		(net "M_E_CPU1_SA_CA<3>")
	)
	(segment
		(start 165.335458 -264.055606)
		(end 164.203634 -264.055606)
		(width 0.20066)
		(layer "F.Cu")
		(net "M_E_CPU1_SA_CA<3>")
	)
	(segment
		(start 148.445728 -258.874514)
		(end 154.657298 -261.447534)
		(width 0.20066)
		(layer "F.Cu")
		(net "M_E_CPU1_SA_CA<3>")
	)
	(segment
		(start 145.157698 -258.440682)
		(end 148.011896 -258.440682)
		(width 0.1016)
		(layer "F.Cu")
		(net "M_E_CPU1_SA_CA<3>")
	)
	(segment
		(start 139.451334 -254.578866)
		(end 139.670536 -254.578866)
		(width 0.088646)
		(layer "F.Cu")
		(net "M_E_CPU1_SA_CA<3>")
	)
	(segment
		(start 167.367458 -264.061194)
		(end 167.3479 -264.041636)
		(width 0.1016)
		(layer "F.Cu")
		(net "M_E_CPU1_SA_CA<3>")
	)
	(segment
		(start 157.791658 -263.175496)
		(end 157.807914 -263.191752)
		(width 0.1016)
		(layer "F.Cu")
		(net "M_E_CPU1_SA_CA<3>")
	)
	(segment
		(start 165.366954 -264.041636)
		(end 165.352984 -264.055606)
		(width 0.1016)
		(layer "F.Cu")
		(net "M_E_CPU1_SA_CA<3>")
	)
	(segment
		(start 162.29965 -263.616694)
		(end 162.913314 -263.616694)
		(width 0.20066)
		(layer "F.Cu")
		(net "M_E_CPU1_SA_CA<3>")
	)
	(segment
		(start 139.670536 -254.578866)
		(end 139.758928 -254.667258)
		(width 0.088646)
		(layer "F.Cu")
		(net "M_E_CPU1_SA_CA<3>")
	)
	(segment
		(start 162.018218 -263.898126)
		(end 162.29965 -263.616694)
		(width 0.20066)
		(layer "F.Cu")
		(net "M_E_CPU1_SA_CA<3>")
	)
	(segment
		(start 136.903714 -254.446278)
		(end 137.131552 -254.446278)
		(width 0.088646)
		(layer "F.Cu")
		(net "M_E_CPU1_SA_CA<3>")
	)
	(segment
		(start 168.2496 -263.354312)
		(end 168.2496 -263.860534)
		(width 0.20066)
		(layer "F.Cu")
		(net "M_E_CPU1_SA_CA<3>")
	)
	(segment
		(start 141.722602 -255.005586)
		(end 145.157698 -258.440682)
		(width 0.1016)
		(layer "F.Cu")
		(net "M_E_CPU1_SA_CA<3>")
	)
	(segment
		(start 159.823658 -263.170416)
		(end 160.857184 -263.170416)
		(width 0.20066)
		(layer "F.Cu")
		(net "M_E_CPU1_SA_CA<3>")
	)
	(segment
		(start 168.04894 -264.061194)
		(end 167.367458 -264.061194)
		(width 0.20066)
		(layer "F.Cu")
		(net "M_E_CPU1_SA_CA<3>")
	)
	(segment
		(start 139.20978 -254.474218)
		(end 139.451334 -254.578866)
		(width 0.088646)
		(layer "F.Cu")
		(net "M_E_CPU1_SA_CA<3>")
	)
	(segment
		(start 138.317986 -254.519938)
		(end 138.44524 -254.57277)
		(width 0.088646)
		(layer "F.Cu")
		(net "M_E_CPU1_SA_CA<3>")
	)
	(segment
		(start 140.29055 -254.667258)
		(end 140.906246 -254.667258)
		(width 0.1016)
		(layer "F.Cu")
		(net "M_E_CPU1_SA_CA<3>")
	)
	(segment
		(start 154.657298 -261.447534)
		(end 156.38526 -263.175496)
		(width 0.20066)
		(layer "F.Cu")
		(net "M_E_CPU1_SA_CA<3>")
	)
	(segment
		(start 168.741598 -263.184132)
		(end 168.41978 -263.184132)
		(width 0.20066)
		(layer "F.Cu")
		(net "M_E_CPU1_SA_CA<3>")
	)
	(segment
		(start 163.764722 -263.616694)
		(end 162.913314 -263.616694)
		(width 0.20066)
		(layer "F.Cu")
		(net "M_E_CPU1_SA_CA<3>")
	)
	(segment
		(start 139.758928 -254.667258)
		(end 140.29055 -254.667258)
		(width 0.088646)
		(layer "F.Cu")
		(net "M_E_CPU1_SA_CA<3>")
	)
	(segment
		(start 167.3479 -264.041636)
		(end 165.366954 -264.041636)
		(width 0.1016)
		(layer "F.Cu")
		(net "M_E_CPU1_SA_CA<3>")
	)
	(segment
		(start 159.802322 -263.191752)
		(end 159.823658 -263.170416)
		(width 0.1016)
		(layer "F.Cu")
		(net "M_E_CPU1_SA_CA<3>")
	)
	(segment
		(start 161.057844 -263.371076)
		(end 161.057844 -263.771126)
		(width 0.20066)
		(layer "F.Cu")
		(net "M_E_CPU1_SA_CA<3>")
	)
	(segment
		(start 138.213846 -254.466344)
		(end 138.317986 -254.519938)
		(width 0.088646)
		(layer "F.Cu")
		(net "M_E_CPU1_SA_CA<3>")
	)
	(segment
		(start 138.71448 -254.531876)
		(end 138.726418 -254.525018)
		(width 0.088646)
		(layer "F.Cu")
		(net "M_E_CPU1_SA_CA<3>")
	)
	(segment
		(start 148.228304 -258.65709)
		(end 148.3106 -258.739386)
		(width 0.101854)
		(layer "F.Cu")
		(net "M_E_CPU1_SA_CA<3>")
	)
	(segment
		(start 157.807914 -263.191752)
		(end 159.802322 -263.191752)
		(width 0.1016)
		(layer "F.Cu")
		(net "M_E_CPU1_SA_CA<3>")
	)
	(segment
		(start 168.2496 -263.860534)
		(end 168.04894 -264.061194)
		(width 0.20066)
		(layer "F.Cu")
		(net "M_E_CPU1_SA_CA<3>")
	)
	(segment
		(start 160.857184 -263.170416)
		(end 161.057844 -263.371076)
		(width 0.20066)
		(layer "F.Cu")
		(net "M_E_CPU1_SA_CA<3>")
	)
	(segment
		(start 136.655048 -254.197612)
		(end 136.903714 -254.446278)
		(width 0.088646)
		(layer "F.Cu")
		(net "M_E_CPU1_SA_CA<3>")
	)
	(segment
		(start 148.011896 -258.440682)
		(end 148.228304 -258.65709)
		(width 0.1016)
		(layer "F.Cu")
		(net "M_E_CPU1_SA_CA<3>")
	)
	(arc
		(start 137.781792 -254.52197)
		(mid 137.992248 -254.450862)
		(end 138.213846 -254.466344)
		(width 0.088646)
		(layer "F.Cu")
		(net "M_E_CPU1_SA_CA<3>")
	)
	(arc
		(start 137.131552 -254.446278)
		(mid 137.274338 -254.466397)
		(end 137.407396 -254.52197)
		(width 0.088646)
		(layer "F.Cu")
		(net "M_E_CPU1_SA_CA<3>")
	)
	(arc
		(start 137.407396 -254.52197)
		(mid 137.594594 -254.572113)
		(end 137.781792 -254.52197)
		(width 0.088646)
		(layer "F.Cu")
		(net "M_E_CPU1_SA_CA<3>")
	)
	(arc
		(start 138.44524 -254.57277)
		(mid 138.583716 -254.577688)
		(end 138.71448 -254.531876)
		(width 0.088646)
		(layer "F.Cu")
		(net "M_E_CPU1_SA_CA<3>")
	)
	(segment
		(start 163.923726 -264.901426)
		(end 163.91382 -264.89152)
		(width 0.1016)
		(layer "F.Cu")
		(net "M_E_CPU1_SA_CA<2>")
	)
	(segment
		(start 157.38348 -263.933686)
		(end 157.65399 -264.204196)
		(width 0.20066)
		(layer "F.Cu")
		(net "M_E_CPU1_SA_CA<2>")
	)
	(segment
		(start 138.706606 -254.74422)
		(end 138.942826 -254.664464)
		(width 0.088646)
		(layer "F.Cu")
		(net "M_E_CPU1_SA_CA<2>")
	)
	(segment
		(start 138.942826 -254.664464)
		(end 139.154154 -254.664464)
		(width 0.088646)
		(layer "F.Cu")
		(net "M_E_CPU1_SA_CA<2>")
	)
	(segment
		(start 139.154154 -254.664464)
		(end 139.39647 -254.769366)
		(width 0.088646)
		(layer "F.Cu")
		(net "M_E_CPU1_SA_CA<2>")
	)
	(segment
		(start 139.39647 -254.769366)
		(end 139.581636 -254.769366)
		(width 0.088646)
		(layer "F.Cu")
		(net "M_E_CPU1_SA_CA<2>")
	)
	(segment
		(start 165.233858 -264.466578)
		(end 164.79901 -264.901426)
		(width 0.20066)
		(layer "F.Cu")
		(net "M_E_CPU1_SA_CA<2>")
	)
	(segment
		(start 157.65399 -264.204196)
		(end 157.999684 -264.204196)
		(width 0.20066)
		(layer "F.Cu")
		(net "M_E_CPU1_SA_CA<2>")
	)
	(segment
		(start 159.81553 -264.047478)
		(end 159.39643 -264.466578)
		(width 0.20066)
		(layer "F.Cu")
		(net "M_E_CPU1_SA_CA<2>")
	)
	(segment
		(start 138.14679 -254.64643)
		(end 138.230356 -254.689356)
		(width 0.088646)
		(layer "F.Cu")
		(net "M_E_CPU1_SA_CA<2>")
	)
	(segment
		(start 154.25801 -262.036814)
		(end 155.890976 -263.66978)
		(width 0.20066)
		(layer "F.Cu")
		(net "M_E_CPU1_SA_CA<2>")
	)
	(segment
		(start 160.728914 -264.047478)
		(end 159.81553 -264.047478)
		(width 0.20066)
		(layer "F.Cu")
		(net "M_E_CPU1_SA_CA<2>")
	)
	(segment
		(start 140.844778 -254.972058)
		(end 141.549882 -255.264158)
		(width 0.1016)
		(layer "F.Cu")
		(net "M_E_CPU1_SA_CA<2>")
	)
	(segment
		(start 138.230356 -254.689356)
		(end 138.374882 -254.754126)
		(width 0.088646)
		(layer "F.Cu")
		(net "M_E_CPU1_SA_CA<2>")
	)
	(segment
		(start 145.031206 -258.745482)
		(end 147.411948 -258.745482)
		(width 0.1016)
		(layer "F.Cu")
		(net "M_E_CPU1_SA_CA<2>")
	)
	(segment
		(start 163.91382 -264.89152)
		(end 161.908744 -264.89152)
		(width 0.1016)
		(layer "F.Cu")
		(net "M_E_CPU1_SA_CA<2>")
	)
	(segment
		(start 164.79901 -264.901426)
		(end 163.923726 -264.901426)
		(width 0.20066)
		(layer "F.Cu")
		(net "M_E_CPU1_SA_CA<2>")
	)
	(segment
		(start 139.784328 -254.972058)
		(end 140.29055 -254.972058)
		(width 0.088646)
		(layer "F.Cu")
		(net "M_E_CPU1_SA_CA<2>")
	)
	(segment
		(start 166.357046 -264.466578)
		(end 165.233858 -264.466578)
		(width 0.20066)
		(layer "F.Cu")
		(net "M_E_CPU1_SA_CA<2>")
	)
	(segment
		(start 148.189696 -259.52323)
		(end 154.25801 -262.036814)
		(width 0.20066)
		(layer "F.Cu")
		(net "M_E_CPU1_SA_CA<2>")
	)
	(segment
		(start 136.928606 -254.692404)
		(end 136.937496 -254.687324)
		(width 0.088646)
		(layer "F.Cu")
		(net "M_E_CPU1_SA_CA<2>")
	)
	(segment
		(start 155.890976 -263.66978)
		(end 155.890976 -263.669526)
		(width 0.20066)
		(layer "F.Cu")
		(net "M_E_CPU1_SA_CA<2>")
	)
	(segment
		(start 158.262066 -264.466578)
		(end 158.813246 -264.466578)
		(width 0.20066)
		(layer "F.Cu")
		(net "M_E_CPU1_SA_CA<2>")
	)
	(segment
		(start 147.802092 -259.135626)
		(end 147.858226 -259.19176)
		(width 0.101854)
		(layer "F.Cu")
		(net "M_E_CPU1_SA_CA<2>")
	)
	(segment
		(start 147.411948 -258.745482)
		(end 147.802092 -259.135626)
		(width 0.1016)
		(layer "F.Cu")
		(net "M_E_CPU1_SA_CA<2>")
	)
	(segment
		(start 161.908744 -264.89152)
		(end 161.891726 -264.908538)
		(width 0.1016)
		(layer "F.Cu")
		(net "M_E_CPU1_SA_CA<2>")
	)
	(segment
		(start 161.589974 -264.908538)
		(end 160.728914 -264.047478)
		(width 0.20066)
		(layer "F.Cu")
		(net "M_E_CPU1_SA_CA<2>")
	)
	(segment
		(start 140.29055 -254.972058)
		(end 140.844778 -254.972058)
		(width 0.1016)
		(layer "F.Cu")
		(net "M_E_CPU1_SA_CA<2>")
	)
	(segment
		(start 139.581636 -254.769366)
		(end 139.784328 -254.972058)
		(width 0.088646)
		(layer "F.Cu")
		(net "M_E_CPU1_SA_CA<2>")
	)
	(segment
		(start 157.999684 -264.204196)
		(end 158.262066 -264.466578)
		(width 0.20066)
		(layer "F.Cu")
		(net "M_E_CPU1_SA_CA<2>")
	)
	(segment
		(start 156.155136 -263.933686)
		(end 157.38348 -263.933686)
		(width 0.20066)
		(layer "F.Cu")
		(net "M_E_CPU1_SA_CA<2>")
	)
	(segment
		(start 155.890976 -263.669526)
		(end 156.155136 -263.933686)
		(width 0.20066)
		(layer "F.Cu")
		(net "M_E_CPU1_SA_CA<2>")
	)
	(segment
		(start 159.39643 -264.466578)
		(end 158.813246 -264.466578)
		(width 0.20066)
		(layer "F.Cu")
		(net "M_E_CPU1_SA_CA<2>")
	)
	(segment
		(start 136.8425 -254.77851)
		(end 136.928606 -254.692404)
		(width 0.088646)
		(layer "F.Cu")
		(net "M_E_CPU1_SA_CA<2>")
	)
	(segment
		(start 136.184894 -255.011682)
		(end 136.418066 -254.77851)
		(width 0.088646)
		(layer "F.Cu")
		(net "M_E_CPU1_SA_CA<2>")
	)
	(segment
		(start 147.858226 -259.19176)
		(end 148.189696 -259.52323)
		(width 0.20066)
		(layer "F.Cu")
		(net "M_E_CPU1_SA_CA<2>")
	)
	(segment
		(start 141.549882 -255.264158)
		(end 145.031206 -258.745482)
		(width 0.1016)
		(layer "F.Cu")
		(net "M_E_CPU1_SA_CA<2>")
	)
	(segment
		(start 136.418066 -254.77851)
		(end 136.8425 -254.77851)
		(width 0.088646)
		(layer "F.Cu")
		(net "M_E_CPU1_SA_CA<2>")
	)
	(segment
		(start 161.891726 -264.908538)
		(end 161.589974 -264.908538)
		(width 0.20066)
		(layer "F.Cu")
		(net "M_E_CPU1_SA_CA<2>")
	)
	(arc
		(start 138.374882 -254.754126)
		(mid 138.541481 -254.774029)
		(end 138.706606 -254.74422)
		(width 0.088646)
		(layer "F.Cu")
		(net "M_E_CPU1_SA_CA<2>")
	)
	(arc
		(start 137.311892 -254.687324)
		(mid 137.594594 -254.763066)
		(end 137.877296 -254.687324)
		(width 0.088646)
		(layer "F.Cu")
		(net "M_E_CPU1_SA_CA<2>")
	)
	(arc
		(start 137.877296 -254.687324)
		(mid 138.008192 -254.641437)
		(end 138.14679 -254.64643)
		(width 0.088646)
		(layer "F.Cu")
		(net "M_E_CPU1_SA_CA<2>")
	)
	(arc
		(start 136.937496 -254.687324)
		(mid 137.124694 -254.637181)
		(end 137.311892 -254.687324)
		(width 0.088646)
		(layer "F.Cu")
		(net "M_E_CPU1_SA_CA<2>")
	)
	(segment
		(start 159.823658 -264.877042)
		(end 160.334452 -264.877042)
		(width 0.20066)
		(layer "F.Cu")
		(net "M_E_CPU1_SA_CA<1>")
	)
	(segment
		(start 169.411396 -265.316716)
		(end 169.21226 -265.515852)
		(width 0.20066)
		(layer "F.Cu")
		(net "M_E_CPU1_SA_CA<1>")
	)
	(segment
		(start 164.590984 -265.75004)
		(end 164.15766 -265.316716)
		(width 0.20066)
		(layer "F.Cu")
		(net "M_E_CPU1_SA_CA<1>")
	)
	(segment
		(start 160.334452 -264.877042)
		(end 160.532826 -265.075416)
		(width 0.20066)
		(layer "F.Cu")
		(net "M_E_CPU1_SA_CA<1>")
	)
	(segment
		(start 139.004294 -255.011682)
		(end 139.644628 -255.276858)
		(width 0.088646)
		(layer "F.Cu")
		(net "M_E_CPU1_SA_CA<1>")
	)
	(segment
		(start 161.25444 -265.513312)
		(end 161.451036 -265.316716)
		(width 0.20066)
		(layer "F.Cu")
		(net "M_E_CPU1_SA_CA<1>")
	)
	(segment
		(start 157.12186 -264.606786)
		(end 157.389576 -264.874502)
		(width 0.20066)
		(layer "F.Cu")
		(net "M_E_CPU1_SA_CA<1>")
	)
	(segment
		(start 147.215352 -259.45338)
		(end 147.983448 -260.221476)
		(width 0.20066)
		(layer "F.Cu")
		(net "M_E_CPU1_SA_CA<1>")
	)
	(segment
		(start 168.70426 -265.246612)
		(end 168.14038 -265.246612)
		(width 0.20066)
		(layer "F.Cu")
		(net "M_E_CPU1_SA_CA<1>")
	)
	(segment
		(start 147.150836 -259.388864)
		(end 147.215352 -259.45338)
		(width 0.101854)
		(layer "F.Cu")
		(net "M_E_CPU1_SA_CA<1>")
	)
	(segment
		(start 157.796484 -264.874502)
		(end 157.813502 -264.89152)
		(width 0.1016)
		(layer "F.Cu")
		(net "M_E_CPU1_SA_CA<1>")
	)
	(segment
		(start 170.457114 -265.316716)
		(end 169.411396 -265.316716)
		(width 0.20066)
		(layer "F.Cu")
		(net "M_E_CPU1_SA_CA<1>")
	)
	(segment
		(start 144.904714 -259.050282)
		(end 146.812254 -259.050282)
		(width 0.1016)
		(layer "F.Cu")
		(net "M_E_CPU1_SA_CA<1>")
	)
	(segment
		(start 147.983448 -260.221476)
		(end 154.046174 -262.732774)
		(width 0.20066)
		(layer "F.Cu")
		(net "M_E_CPU1_SA_CA<1>")
	)
	(segment
		(start 139.644628 -255.276858)
		(end 140.29055 -255.276858)
		(width 0.088646)
		(layer "F.Cu")
		(net "M_E_CPU1_SA_CA<1>")
	)
	(segment
		(start 167.367458 -265.763248)
		(end 167.345868 -265.741658)
		(width 0.1016)
		(layer "F.Cu")
		(net "M_E_CPU1_SA_CA<1>")
	)
	(segment
		(start 165.34384 -265.741658)
		(end 165.335458 -265.75004)
		(width 0.101854)
		(layer "F.Cu")
		(net "M_E_CPU1_SA_CA<1>")
	)
	(segment
		(start 140.29055 -255.276858)
		(end 140.722096 -255.276858)
		(width 0.1016)
		(layer "F.Cu")
		(net "M_E_CPU1_SA_CA<1>")
	)
	(segment
		(start 161.451036 -265.316716)
		(end 162.913314 -265.316716)
		(width 0.20066)
		(layer "F.Cu")
		(net "M_E_CPU1_SA_CA<1>")
	)
	(segment
		(start 169.21226 -265.515852)
		(end 168.9735 -265.515852)
		(width 0.20066)
		(layer "F.Cu")
		(net "M_E_CPU1_SA_CA<1>")
	)
	(segment
		(start 140.722096 -255.276858)
		(end 141.42085 -255.566418)
		(width 0.1016)
		(layer "F.Cu")
		(net "M_E_CPU1_SA_CA<1>")
	)
	(segment
		(start 160.532826 -265.37158)
		(end 160.674558 -265.513312)
		(width 0.20066)
		(layer "F.Cu")
		(net "M_E_CPU1_SA_CA<1>")
	)
	(segment
		(start 141.42085 -255.566418)
		(end 144.904714 -259.050282)
		(width 0.1016)
		(layer "F.Cu")
		(net "M_E_CPU1_SA_CA<1>")
	)
	(segment
		(start 168.01846 -265.582908)
		(end 167.83812 -265.763248)
		(width 0.20066)
		(layer "F.Cu")
		(net "M_E_CPU1_SA_CA<1>")
	)
	(segment
		(start 168.9735 -265.515852)
		(end 168.70426 -265.246612)
		(width 0.20066)
		(layer "F.Cu")
		(net "M_E_CPU1_SA_CA<1>")
	)
	(segment
		(start 165.335458 -265.75004)
		(end 164.590984 -265.75004)
		(width 0.20066)
		(layer "F.Cu")
		(net "M_E_CPU1_SA_CA<1>")
	)
	(segment
		(start 154.046174 -262.732774)
		(end 155.920186 -264.606786)
		(width 0.20066)
		(layer "F.Cu")
		(net "M_E_CPU1_SA_CA<1>")
	)
	(segment
		(start 159.772858 -264.877042)
		(end 159.823658 -264.877042)
		(width 0.101854)
		(layer "F.Cu")
		(net "M_E_CPU1_SA_CA<1>")
	)
	(segment
		(start 157.389576 -264.874502)
		(end 157.791658 -264.874502)
		(width 0.20066)
		(layer "F.Cu")
		(net "M_E_CPU1_SA_CA<1>")
	)
	(segment
		(start 159.75838 -264.89152)
		(end 159.772858 -264.877042)
		(width 0.1016)
		(layer "F.Cu")
		(net "M_E_CPU1_SA_CA<1>")
	)
	(segment
		(start 157.791658 -264.874502)
		(end 157.796484 -264.874502)
		(width 0.101854)
		(layer "F.Cu")
		(net "M_E_CPU1_SA_CA<1>")
	)
	(segment
		(start 168.01846 -265.368532)
		(end 168.01846 -265.582908)
		(width 0.20066)
		(layer "F.Cu")
		(net "M_E_CPU1_SA_CA<1>")
	)
	(segment
		(start 155.920186 -264.606786)
		(end 157.12186 -264.606786)
		(width 0.20066)
		(layer "F.Cu")
		(net "M_E_CPU1_SA_CA<1>")
	)
	(segment
		(start 165.48862 -265.741658)
		(end 165.34384 -265.741658)
		(width 0.101854)
		(layer "F.Cu")
		(net "M_E_CPU1_SA_CA<1>")
	)
	(segment
		(start 167.345868 -265.741658)
		(end 165.48862 -265.741658)
		(width 0.1016)
		(layer "F.Cu")
		(net "M_E_CPU1_SA_CA<1>")
	)
	(segment
		(start 160.532826 -265.075416)
		(end 160.532826 -265.37158)
		(width 0.20066)
		(layer "F.Cu")
		(net "M_E_CPU1_SA_CA<1>")
	)
	(segment
		(start 167.83812 -265.763248)
		(end 167.367458 -265.763248)
		(width 0.20066)
		(layer "F.Cu")
		(net "M_E_CPU1_SA_CA<1>")
	)
	(segment
		(start 168.14038 -265.246612)
		(end 168.01846 -265.368532)
		(width 0.20066)
		(layer "F.Cu")
		(net "M_E_CPU1_SA_CA<1>")
	)
	(segment
		(start 164.15766 -265.316716)
		(end 162.913314 -265.316716)
		(width 0.20066)
		(layer "F.Cu")
		(net "M_E_CPU1_SA_CA<1>")
	)
	(segment
		(start 157.813502 -264.89152)
		(end 159.75838 -264.89152)
		(width 0.1016)
		(layer "F.Cu")
		(net "M_E_CPU1_SA_CA<1>")
	)
	(segment
		(start 160.674558 -265.513312)
		(end 161.25444 -265.513312)
		(width 0.20066)
		(layer "F.Cu")
		(net "M_E_CPU1_SA_CA<1>")
	)
	(segment
		(start 146.812254 -259.050282)
		(end 147.150836 -259.388864)
		(width 0.1016)
		(layer "F.Cu")
		(net "M_E_CPU1_SA_CA<1>")
	)
	(segment
		(start 164.783008 -266.23518)
		(end 164.558472 -266.23518)
		(width 0.20066)
		(layer "F.Cu")
		(net "M_E_CPU1_SA_CA<0>")
	)
	(segment
		(start 140.881608 -255.792732)
		(end 141.0208 -255.792732)
		(width 0.1016)
		(layer "F.Cu")
		(net "M_E_CPU1_SA_CA<0>")
	)
	(segment
		(start 161.04108 -266.077446)
		(end 160.93186 -265.968226)
		(width 0.20066)
		(layer "F.Cu")
		(net "M_E_CPU1_SA_CA<0>")
	)
	(segment
		(start 139.410186 -255.668526)
		(end 139.4968 -255.581912)
		(width 0.088646)
		(layer "F.Cu")
		(net "M_E_CPU1_SA_CA<0>")
	)
	(segment
		(start 163.91128 -266.591542)
		(end 161.912554 -266.591542)
		(width 0.1016)
		(layer "F.Cu")
		(net "M_E_CPU1_SA_CA<0>")
	)
	(segment
		(start 139.90955 -255.581912)
		(end 140.016738 -255.581912)
		(width 0.1016)
		(layer "F.Cu")
		(net "M_E_CPU1_SA_CA<0>")
	)
	(segment
		(start 146.429222 -259.682488)
		(end 146.502882 -259.756148)
		(width 0.101854)
		(layer "F.Cu")
		(net "M_E_CPU1_SA_CA<0>")
	)
	(segment
		(start 159.3596 -266.1666)
		(end 158.813246 -266.1666)
		(width 0.20066)
		(layer "F.Cu")
		(net "M_E_CPU1_SA_CA<0>")
	)
	(segment
		(start 144.845024 -259.421884)
		(end 145.468848 -259.421884)
		(width 0.1016)
		(layer "F.Cu")
		(net "M_E_CPU1_SA_CA<0>")
	)
	(segment
		(start 166.357046 -266.1666)
		(end 165.46068 -266.1666)
		(width 0.20066)
		(layer "F.Cu")
		(net "M_E_CPU1_SA_CA<0>")
	)
	(segment
		(start 160.93186 -265.968226)
		(end 159.557974 -265.968226)
		(width 0.20066)
		(layer "F.Cu")
		(net "M_E_CPU1_SA_CA<0>")
	)
	(segment
		(start 141.0208 -255.792732)
		(end 141.353794 -255.930654)
		(width 0.1016)
		(layer "F.Cu")
		(net "M_E_CPU1_SA_CA<0>")
	)
	(segment
		(start 164.959792 -266.411964)
		(end 164.783008 -266.23518)
		(width 0.20066)
		(layer "F.Cu")
		(net "M_E_CPU1_SA_CA<0>")
	)
	(segment
		(start 140.221716 -255.78689)
		(end 140.438886 -255.78689)
		(width 0.1016)
		(layer "F.Cu")
		(net "M_E_CPU1_SA_CA<0>")
	)
	(segment
		(start 140.585444 -255.640332)
		(end 140.729208 -255.640332)
		(width 0.1016)
		(layer "F.Cu")
		(net "M_E_CPU1_SA_CA<0>")
	)
	(segment
		(start 161.128964 -266.482576)
		(end 161.04108 -266.394692)
		(width 0.20066)
		(layer "F.Cu")
		(net "M_E_CPU1_SA_CA<0>")
	)
	(segment
		(start 140.016738 -255.581912)
		(end 140.221716 -255.78689)
		(width 0.1016)
		(layer "F.Cu")
		(net "M_E_CPU1_SA_CA<0>")
	)
	(segment
		(start 139.4968 -255.581912)
		(end 139.90955 -255.581912)
		(width 0.088646)
		(layer "F.Cu")
		(net "M_E_CPU1_SA_CA<0>")
	)
	(segment
		(start 147.522184 -260.77545)
		(end 153.773632 -263.36498)
		(width 0.20066)
		(layer "F.Cu")
		(net "M_E_CPU1_SA_CA<0>")
	)
	(segment
		(start 146.502882 -259.756148)
		(end 147.522184 -260.77545)
		(width 0.20066)
		(layer "F.Cu")
		(net "M_E_CPU1_SA_CA<0>")
	)
	(segment
		(start 158.090362 -265.973814)
		(end 158.283148 -266.1666)
		(width 0.20066)
		(layer "F.Cu")
		(net "M_E_CPU1_SA_CA<0>")
	)
	(segment
		(start 138.064494 -255.011682)
		(end 139.251944 -255.668526)
		(width 0.088646)
		(layer "F.Cu")
		(net "M_E_CPU1_SA_CA<0>")
	)
	(segment
		(start 159.557974 -265.968226)
		(end 159.3596 -266.1666)
		(width 0.20066)
		(layer "F.Cu")
		(net "M_E_CPU1_SA_CA<0>")
	)
	(segment
		(start 153.773632 -263.36498)
		(end 155.72867 -265.320018)
		(width 0.20066)
		(layer "F.Cu")
		(net "M_E_CPU1_SA_CA<0>")
	)
	(segment
		(start 161.48177 -266.482576)
		(end 161.128964 -266.482576)
		(width 0.20066)
		(layer "F.Cu")
		(net "M_E_CPU1_SA_CA<0>")
	)
	(segment
		(start 141.353794 -255.930654)
		(end 144.845024 -259.421884)
		(width 0.1016)
		(layer "F.Cu")
		(net "M_E_CPU1_SA_CA<0>")
	)
	(segment
		(start 146.342354 -259.59562)
		(end 146.429222 -259.682488)
		(width 0.1016)
		(layer "F.Cu")
		(net "M_E_CPU1_SA_CA<0>")
	)
	(segment
		(start 165.215316 -266.411964)
		(end 164.959792 -266.411964)
		(width 0.20066)
		(layer "F.Cu")
		(net "M_E_CPU1_SA_CA<0>")
	)
	(segment
		(start 140.729208 -255.640332)
		(end 140.881608 -255.792732)
		(width 0.1016)
		(layer "F.Cu")
		(net "M_E_CPU1_SA_CA<0>")
	)
	(segment
		(start 140.438886 -255.78689)
		(end 140.585444 -255.640332)
		(width 0.1016)
		(layer "F.Cu")
		(net "M_E_CPU1_SA_CA<0>")
	)
	(segment
		(start 165.46068 -266.1666)
		(end 165.215316 -266.411964)
		(width 0.20066)
		(layer "F.Cu")
		(net "M_E_CPU1_SA_CA<0>")
	)
	(segment
		(start 157.0609 -265.320018)
		(end 157.714696 -265.973814)
		(width 0.20066)
		(layer "F.Cu")
		(net "M_E_CPU1_SA_CA<0>")
	)
	(segment
		(start 139.251944 -255.668526)
		(end 139.410186 -255.668526)
		(width 0.088646)
		(layer "F.Cu")
		(net "M_E_CPU1_SA_CA<0>")
	)
	(segment
		(start 161.04108 -266.394692)
		(end 161.04108 -266.077446)
		(width 0.20066)
		(layer "F.Cu")
		(net "M_E_CPU1_SA_CA<0>")
	)
	(segment
		(start 155.72867 -265.320018)
		(end 157.0609 -265.320018)
		(width 0.20066)
		(layer "F.Cu")
		(net "M_E_CPU1_SA_CA<0>")
	)
	(segment
		(start 161.606738 -266.607544)
		(end 161.48177 -266.482576)
		(width 0.20066)
		(layer "F.Cu")
		(net "M_E_CPU1_SA_CA<0>")
	)
	(segment
		(start 161.912554 -266.591542)
		(end 161.896552 -266.607544)
		(width 0.1016)
		(layer "F.Cu")
		(net "M_E_CPU1_SA_CA<0>")
	)
	(segment
		(start 161.896552 -266.607544)
		(end 161.891726 -266.607544)
		(width 0.101854)
		(layer "F.Cu")
		(net "M_E_CPU1_SA_CA<0>")
	)
	(segment
		(start 163.922964 -266.603226)
		(end 163.91128 -266.591542)
		(width 0.1016)
		(layer "F.Cu")
		(net "M_E_CPU1_SA_CA<0>")
	)
	(segment
		(start 161.891726 -266.607544)
		(end 161.606738 -266.607544)
		(width 0.20066)
		(layer "F.Cu")
		(net "M_E_CPU1_SA_CA<0>")
	)
	(segment
		(start 158.283148 -266.1666)
		(end 158.813246 -266.1666)
		(width 0.20066)
		(layer "F.Cu")
		(net "M_E_CPU1_SA_CA<0>")
	)
	(segment
		(start 164.558472 -266.23518)
		(end 164.190426 -266.603226)
		(width 0.20066)
		(layer "F.Cu")
		(net "M_E_CPU1_SA_CA<0>")
	)
	(segment
		(start 157.714696 -265.973814)
		(end 158.090362 -265.973814)
		(width 0.20066)
		(layer "F.Cu")
		(net "M_E_CPU1_SA_CA<0>")
	)
	(segment
		(start 163.923726 -266.603226)
		(end 163.922964 -266.603226)
		(width 0.101854)
		(layer "F.Cu")
		(net "M_E_CPU1_SA_CA<0>")
	)
	(segment
		(start 145.468848 -259.421884)
		(end 146.342354 -259.59562)
		(width 0.1016)
		(layer "F.Cu")
		(net "M_E_CPU1_SA_CA<0>")
	)
	(segment
		(start 164.190426 -266.603226)
		(end 163.923726 -266.603226)
		(width 0.20066)
		(layer "F.Cu")
		(net "M_E_CPU1_SA_CA<0>")
	)
	(segment
		(start 140.750798 -252.784356)
		(end 137.841482 -252.205998)
		(width 0.1524)
		(layer "F.Cu")
		(net "M_E_CPU1_CLK_DP<1>")
	)
	(segment
		(start 134.17296 -250.989592)
		(end 133.589522 -250.630436)
		(width 0.1524)
		(layer "F.Cu")
		(net "M_E_CPU1_CLK_DP<1>")
	)
	(segment
		(start 144.627854 -255.54305)
		(end 144.071086 -254.986282)
		(width 0.20066)
		(layer "F.Cu")
		(net "M_E_CPU1_CLK_DP<1>")
	)
	(segment
		(start 137.841482 -252.205998)
		(end 136.980422 -252.121162)
		(width 0.1524)
		(layer "F.Cu")
		(net "M_E_CPU1_CLK_DP<1>")
	)
	(segment
		(start 136.980422 -252.121162)
		(end 136.142476 -251.908056)
		(width 0.1524)
		(layer "F.Cu")
		(net "M_E_CPU1_CLK_DP<1>")
	)
	(segment
		(start 143.5608 -254.423926)
		(end 142.391384 -253.463806)
		(width 0.1524)
		(layer "F.Cu")
		(net "M_E_CPU1_CLK_DP<1>")
	)
	(segment
		(start 161.173668 -259.114036)
		(end 160.26765 -258.208018)
		(width 0.20066)
		(layer "F.Cu")
		(net "M_E_CPU1_CLK_DP<1>")
	)
	(segment
		(start 162.091116 -259.934202)
		(end 161.74085 -259.934202)
		(width 0.20066)
		(layer "F.Cu")
		(net "M_E_CPU1_CLK_DP<1>")
	)
	(segment
		(start 161.74085 -259.934202)
		(end 161.339022 -259.532374)
		(width 0.20066)
		(layer "F.Cu")
		(net "M_E_CPU1_CLK_DP<1>")
	)
	(segment
		(start 152.000458 -255.855978)
		(end 152.000458 -255.855724)
		(width 0.20066)
		(layer "F.Cu")
		(net "M_E_CPU1_CLK_DP<1>")
	)
	(segment
		(start 161.339022 -259.532374)
		(end 161.173668 -259.114036)
		(width 0.20066)
		(layer "F.Cu")
		(net "M_E_CPU1_CLK_DP<1>")
	)
	(segment
		(start 133.572758 -250.617736)
		(end 133.263132 -250.411488)
		(width 0.1524)
		(layer "F.Cu")
		(net "M_E_CPU1_CLK_DP<1>")
	)
	(segment
		(start 160.26765 -258.208018)
		(end 159.840422 -257.961384)
		(width 0.20066)
		(layer "F.Cu")
		(net "M_E_CPU1_CLK_DP<1>")
	)
	(segment
		(start 142.391384 -253.463806)
		(end 140.750798 -252.784356)
		(width 0.1524)
		(layer "F.Cu")
		(net "M_E_CPU1_CLK_DP<1>")
	)
	(segment
		(start 150.835868 -255.54305)
		(end 144.627854 -255.54305)
		(width 0.20066)
		(layer "F.Cu")
		(net "M_E_CPU1_CLK_DP<1>")
	)
	(segment
		(start 133.263132 -250.411488)
		(end 132.785866 -250.155964)
		(width 0.1524)
		(layer "F.Cu")
		(net "M_E_CPU1_CLK_DP<1>")
	)
	(segment
		(start 152.000458 -255.855724)
		(end 150.835868 -255.54305)
		(width 0.20066)
		(layer "F.Cu")
		(net "M_E_CPU1_CLK_DP<1>")
	)
	(segment
		(start 162.913314 -260.21665)
		(end 162.373564 -260.21665)
		(width 0.20066)
		(layer "F.Cu")
		(net "M_E_CPU1_CLK_DP<1>")
	)
	(segment
		(start 136.142476 -251.908056)
		(end 135.78459 -251.776484)
		(width 0.1524)
		(layer "F.Cu")
		(net "M_E_CPU1_CLK_DP<1>")
	)
	(segment
		(start 162.373564 -260.21665)
		(end 162.091116 -259.934202)
		(width 0.20066)
		(layer "F.Cu")
		(net "M_E_CPU1_CLK_DP<1>")
	)
	(segment
		(start 133.589522 -250.630436)
		(end 133.572758 -250.617736)
		(width 0.1524)
		(layer "F.Cu")
		(net "M_E_CPU1_CLK_DP<1>")
	)
	(segment
		(start 159.840422 -257.961384)
		(end 152.000458 -255.855978)
		(width 0.20066)
		(layer "F.Cu")
		(net "M_E_CPU1_CLK_DP<1>")
	)
	(segment
		(start 144.071086 -254.986282)
		(end 144.071086 -254.934212)
		(width 0.1524)
		(layer "F.Cu")
		(net "M_E_CPU1_CLK_DP<1>")
	)
	(segment
		(start 144.071086 -254.934212)
		(end 143.5608 -254.423926)
		(width 0.1524)
		(layer "F.Cu")
		(net "M_E_CPU1_CLK_DP<1>")
	)
	(segment
		(start 135.78459 -251.776484)
		(end 134.17296 -250.989592)
		(width 0.1524)
		(layer "F.Cu")
		(net "M_E_CPU1_CLK_DP<1>")
	)
	(segment
		(start 146.630644 -254.452628)
		(end 146.593814 -254.415798)
		(width 0.152654)
		(layer "F.Cu")
		(net "M_E_CPU1_CLK_DP<0>")
	)
	(segment
		(start 143.124174 -253.184152)
		(end 142.819628 -252.980952)
		(width 0.1524)
		(layer "F.Cu")
		(net "M_E_CPU1_CLK_DP<0>")
	)
	(segment
		(start 158.036514 -255.87579)
		(end 157.639512 -255.785112)
		(width 0.20066)
		(layer "F.Cu")
		(net "M_E_CPU1_CLK_DP<0>")
	)
	(segment
		(start 150.669244 -254.490474)
		(end 150.253192 -254.452628)
		(width 0.20066)
		(layer "F.Cu")
		(net "M_E_CPU1_CLK_DP<0>")
	)
	(segment
		(start 170.457114 -260.21665)
		(end 169.99458 -260.21665)
		(width 0.20066)
		(layer "F.Cu")
		(net "M_E_CPU1_CLK_DP<0>")
	)
	(segment
		(start 144.810226 -254.236474)
		(end 143.124174 -253.184152)
		(width 0.1524)
		(layer "F.Cu")
		(net "M_E_CPU1_CLK_DP<0>")
	)
	(segment
		(start 150.253192 -254.452628)
		(end 146.668744 -254.452628)
		(width 0.20066)
		(layer "F.Cu")
		(net "M_E_CPU1_CLK_DP<0>")
	)
	(segment
		(start 157.242256 -255.694434)
		(end 150.669244 -254.490474)
		(width 0.20066)
		(layer "F.Cu")
		(net "M_E_CPU1_CLK_DP<0>")
	)
	(segment
		(start 146.593814 -254.415798)
		(end 146.509232 -254.415798)
		(width 0.152654)
		(layer "F.Cu")
		(net "M_E_CPU1_CLK_DP<0>")
	)
	(segment
		(start 137.879328 -251.563632)
		(end 137.553446 -251.531374)
		(width 0.1524)
		(layer "F.Cu")
		(net "M_E_CPU1_CLK_DP<0>")
	)
	(segment
		(start 145.556732 -254.450342)
		(end 144.810226 -254.236474)
		(width 0.1524)
		(layer "F.Cu")
		(net "M_E_CPU1_CLK_DP<0>")
	)
	(segment
		(start 135.843264 -251.049282)
		(end 135.454898 -250.761754)
		(width 0.1524)
		(layer "F.Cu")
		(net "M_E_CPU1_CLK_DP<0>")
	)
	(segment
		(start 146.509232 -254.415798)
		(end 146.474688 -254.450342)
		(width 0.152654)
		(layer "F.Cu")
		(net "M_E_CPU1_CLK_DP<0>")
	)
	(segment
		(start 134.922768 -250.367038)
		(end 134.665466 -250.155964)
		(width 0.1524)
		(layer "F.Cu")
		(net "M_E_CPU1_CLK_DP<0>")
	)
	(segment
		(start 167.534844 -258.049268)
		(end 167.504364 -258.038092)
		(width 0.20066)
		(layer "F.Cu")
		(net "M_E_CPU1_CLK_DP<0>")
	)
	(segment
		(start 135.454644 -250.761246)
		(end 135.454136 -250.760992)
		(width 0.1524)
		(layer "F.Cu")
		(net "M_E_CPU1_CLK_DP<0>")
	)
	(segment
		(start 167.756078 -258.200906)
		(end 167.740076 -258.183634)
		(width 0.20066)
		(layer "F.Cu")
		(net "M_E_CPU1_CLK_DP<0>")
	)
	(segment
		(start 169.708068 -259.930138)
		(end 169.508932 -259.930138)
		(width 0.20066)
		(layer "F.Cu")
		(net "M_E_CPU1_CLK_DP<0>")
	)
	(segment
		(start 140.801852 -252.14453)
		(end 137.879328 -251.563632)
		(width 0.1524)
		(layer "F.Cu")
		(net "M_E_CPU1_CLK_DP<0>")
	)
	(segment
		(start 142.819628 -252.980952)
		(end 140.801852 -252.14453)
		(width 0.1524)
		(layer "F.Cu")
		(net "M_E_CPU1_CLK_DP<0>")
	)
	(segment
		(start 135.454136 -250.760992)
		(end 134.922768 -250.367038)
		(width 0.1524)
		(layer "F.Cu")
		(net "M_E_CPU1_CLK_DP<0>")
	)
	(segment
		(start 135.454898 -250.761754)
		(end 135.454644 -250.761246)
		(width 0.1524)
		(layer "F.Cu")
		(net "M_E_CPU1_CLK_DP<0>")
	)
	(segment
		(start 167.504364 -258.038092)
		(end 158.03626 -255.876044)
		(width 0.20066)
		(layer "F.Cu")
		(net "M_E_CPU1_CLK_DP<0>")
	)
	(segment
		(start 146.474688 -254.450342)
		(end 145.556732 -254.450342)
		(width 0.152654)
		(layer "F.Cu")
		(net "M_E_CPU1_CLK_DP<0>")
	)
	(segment
		(start 169.99458 -260.21665)
		(end 169.708068 -259.930138)
		(width 0.20066)
		(layer "F.Cu")
		(net "M_E_CPU1_CLK_DP<0>")
	)
	(segment
		(start 169.268648 -259.830316)
		(end 167.756078 -258.200906)
		(width 0.20066)
		(layer "F.Cu")
		(net "M_E_CPU1_CLK_DP<0>")
	)
	(segment
		(start 157.639512 -255.785366)
		(end 157.242256 -255.694434)
		(width 0.20066)
		(layer "F.Cu")
		(net "M_E_CPU1_CLK_DP<0>")
	)
	(segment
		(start 137.553446 -251.531374)
		(end 136.26846 -251.276104)
		(width 0.1524)
		(layer "F.Cu")
		(net "M_E_CPU1_CLK_DP<0>")
	)
	(segment
		(start 157.639512 -255.785112)
		(end 157.639512 -255.785366)
		(width 0.20066)
		(layer "F.Cu")
		(net "M_E_CPU1_CLK_DP<0>")
	)
	(segment
		(start 169.508932 -259.930138)
		(end 169.268648 -259.830316)
		(width 0.20066)
		(layer "F.Cu")
		(net "M_E_CPU1_CLK_DP<0>")
	)
	(segment
		(start 146.668744 -254.452628)
		(end 146.630644 -254.452628)
		(width 0.152654)
		(layer "F.Cu")
		(net "M_E_CPU1_CLK_DP<0>")
	)
	(segment
		(start 136.045448 -251.184664)
		(end 135.843264 -251.049282)
		(width 0.1524)
		(layer "F.Cu")
		(net "M_E_CPU1_CLK_DP<0>")
	)
	(segment
		(start 136.26846 -251.276104)
		(end 136.045448 -251.184664)
		(width 0.1524)
		(layer "F.Cu")
		(net "M_E_CPU1_CLK_DP<0>")
	)
	(segment
		(start 158.03626 -255.876044)
		(end 158.036514 -255.87579)
		(width 0.20066)
		(layer "F.Cu")
		(net "M_E_CPU1_CLK_DP<0>")
	)
	(segment
		(start 167.740076 -258.183634)
		(end 167.534844 -258.049268)
		(width 0.20066)
		(layer "F.Cu")
		(net "M_E_CPU1_CLK_DP<0>")
	)
	(segment
		(start 160.46958 -257.946144)
		(end 159.966406 -257.655314)
		(width 0.20066)
		(layer "F.Cu")
		(net "M_E_CPU1_CLK_DN<1>")
	)
	(segment
		(start 156.295344 -256.669794)
		(end 155.714192 -256.513838)
		(width 0.20066)
		(layer "F.Cu")
		(net "M_E_CPU1_CLK_DN<1>")
	)
	(segment
		(start 146.099276 -255.0922)
		(end 145.497296 -255.0922)
		(width 0.20066)
		(layer "F.Cu")
		(net "M_E_CPU1_CLK_DN<1>")
	)
	(segment
		(start 158.520638 -257.266948)
		(end 158.433008 -257.114802)
		(width 0.20066)
		(layer "F.Cu")
		(net "M_E_CPU1_CLK_DN<1>")
	)
	(segment
		(start 157.117542 -256.890774)
		(end 157.029658 -256.737866)
		(width 0.20066)
		(layer "F.Cu")
		(net "M_E_CPU1_CLK_DN<1>")
	)
	(segment
		(start 155.626308 -256.36093)
		(end 155.044648 -256.204974)
		(width 0.20066)
		(layer "F.Cu")
		(net "M_E_CPU1_CLK_DN<1>")
	)
	(segment
		(start 146.824446 -255.21539)
		(end 146.222466 -255.21539)
		(width 0.20066)
		(layer "F.Cu")
		(net "M_E_CPU1_CLK_DN<1>")
	)
	(segment
		(start 134.295642 -250.76658)
		(end 133.733286 -250.420632)
		(width 0.1524)
		(layer "F.Cu")
		(net "M_E_CPU1_CLK_DN<1>")
	)
	(segment
		(start 154.310842 -256.136902)
		(end 154.222958 -255.984248)
		(width 0.20066)
		(layer "F.Cu")
		(net "M_E_CPU1_CLK_DN<1>")
	)
	(segment
		(start 133.729476 -250.417584)
		(end 133.725666 -250.41479)
		(width 0.1524)
		(layer "F.Cu")
		(net "M_E_CPU1_CLK_DN<1>")
	)
	(segment
		(start 143.731742 -254.235204)
		(end 142.523464 -253.243334)
		(width 0.1524)
		(layer "F.Cu")
		(net "M_E_CPU1_CLK_DN<1>")
	)
	(segment
		(start 133.733286 -250.420632)
		(end 133.729476 -250.417584)
		(width 0.1524)
		(layer "F.Cu")
		(net "M_E_CPU1_CLK_DN<1>")
	)
	(segment
		(start 153.641298 -255.828038)
		(end 153.488644 -255.915922)
		(width 0.20066)
		(layer "F.Cu")
		(net "M_E_CPU1_CLK_DN<1>")
	)
	(segment
		(start 153.488644 -255.915922)
		(end 152.907492 -255.759966)
		(width 0.20066)
		(layer "F.Cu")
		(net "M_E_CPU1_CLK_DN<1>")
	)
	(segment
		(start 136.217914 -251.664978)
		(end 135.884412 -251.54255)
		(width 0.1524)
		(layer "F.Cu")
		(net "M_E_CPU1_CLK_DN<1>")
	)
	(segment
		(start 154.891994 -256.292858)
		(end 154.310842 -256.136902)
		(width 0.20066)
		(layer "F.Cu")
		(net "M_E_CPU1_CLK_DN<1>")
	)
	(segment
		(start 144.302988 -254.754634)
		(end 144.251172 -254.754634)
		(width 0.1524)
		(layer "F.Cu")
		(net "M_E_CPU1_CLK_DN<1>")
	)
	(segment
		(start 155.714192 -256.513838)
		(end 155.626308 -256.36093)
		(width 0.20066)
		(layer "F.Cu")
		(net "M_E_CPU1_CLK_DN<1>")
	)
	(segment
		(start 145.374106 -255.21539)
		(end 144.763744 -255.21539)
		(width 0.20066)
		(layer "F.Cu")
		(net "M_E_CPU1_CLK_DN<1>")
	)
	(segment
		(start 154.222958 -255.984248)
		(end 153.641298 -255.828038)
		(width 0.20066)
		(layer "F.Cu")
		(net "M_E_CPU1_CLK_DN<1>")
	)
	(segment
		(start 145.497296 -255.0922)
		(end 145.374106 -255.21539)
		(width 0.20066)
		(layer "F.Cu")
		(net "M_E_CPU1_CLK_DN<1>")
	)
	(segment
		(start 155.044648 -256.204974)
		(end 154.891994 -256.292858)
		(width 0.20066)
		(layer "F.Cu")
		(net "M_E_CPU1_CLK_DN<1>")
	)
	(segment
		(start 146.947636 -255.0922)
		(end 146.824446 -255.21539)
		(width 0.20066)
		(layer "F.Cu")
		(net "M_E_CPU1_CLK_DN<1>")
	)
	(segment
		(start 148.999956 -255.0922)
		(end 148.397976 -255.0922)
		(width 0.20066)
		(layer "F.Cu")
		(net "M_E_CPU1_CLK_DN<1>")
	)
	(segment
		(start 146.222466 -255.21539)
		(end 146.099276 -255.0922)
		(width 0.20066)
		(layer "F.Cu")
		(net "M_E_CPU1_CLK_DN<1>")
	)
	(segment
		(start 144.763744 -255.21539)
		(end 144.302988 -254.754634)
		(width 0.20066)
		(layer "F.Cu")
		(net "M_E_CPU1_CLK_DN<1>")
	)
	(segment
		(start 147.672806 -255.21539)
		(end 147.549616 -255.0922)
		(width 0.20066)
		(layer "F.Cu")
		(net "M_E_CPU1_CLK_DN<1>")
	)
	(segment
		(start 137.024364 -251.87021)
		(end 136.217914 -251.664978)
		(width 0.1524)
		(layer "F.Cu")
		(net "M_E_CPU1_CLK_DN<1>")
	)
	(segment
		(start 159.966406 -257.655314)
		(end 158.520638 -257.266948)
		(width 0.20066)
		(layer "F.Cu")
		(net "M_E_CPU1_CLK_DN<1>")
	)
	(segment
		(start 162.099244 -259.606542)
		(end 161.876994 -259.606542)
		(width 0.20066)
		(layer "F.Cu")
		(net "M_E_CPU1_CLK_DN<1>")
	)
	(segment
		(start 144.251172 -254.754634)
		(end 143.731742 -254.235204)
		(width 0.1524)
		(layer "F.Cu")
		(net "M_E_CPU1_CLK_DN<1>")
	)
	(segment
		(start 148.397976 -255.0922)
		(end 148.274786 -255.21539)
		(width 0.20066)
		(layer "F.Cu")
		(net "M_E_CPU1_CLK_DN<1>")
	)
	(segment
		(start 161.876994 -259.606542)
		(end 161.61893 -259.348478)
		(width 0.20066)
		(layer "F.Cu")
		(net "M_E_CPU1_CLK_DN<1>")
	)
	(segment
		(start 161.453068 -258.929632)
		(end 160.46958 -257.946144)
		(width 0.20066)
		(layer "F.Cu")
		(net "M_E_CPU1_CLK_DN<1>")
	)
	(segment
		(start 162.913314 -259.366766)
		(end 162.33902 -259.366766)
		(width 0.20066)
		(layer "F.Cu")
		(net "M_E_CPU1_CLK_DN<1>")
	)
	(segment
		(start 152.237948 -255.451356)
		(end 152.085548 -255.53924)
		(width 0.20066)
		(layer "F.Cu")
		(net "M_E_CPU1_CLK_DN<1>")
	)
	(segment
		(start 147.549616 -255.0922)
		(end 146.947636 -255.0922)
		(width 0.20066)
		(layer "F.Cu")
		(net "M_E_CPU1_CLK_DN<1>")
	)
	(segment
		(start 137.87882 -251.954284)
		(end 137.024364 -251.87021)
		(width 0.1524)
		(layer "F.Cu")
		(net "M_E_CPU1_CLK_DN<1>")
	)
	(segment
		(start 133.725666 -250.41479)
		(end 133.725666 -250.155964)
		(width 0.1524)
		(layer "F.Cu")
		(net "M_E_CPU1_CLK_DN<1>")
	)
	(segment
		(start 142.523464 -253.243334)
		(end 140.824966 -252.540008)
		(width 0.1524)
		(layer "F.Cu")
		(net "M_E_CPU1_CLK_DN<1>")
	)
	(segment
		(start 157.851348 -256.958846)
		(end 157.698694 -257.04673)
		(width 0.20066)
		(layer "F.Cu")
		(net "M_E_CPU1_CLK_DN<1>")
	)
	(segment
		(start 152.085548 -255.53924)
		(end 150.879302 -255.21539)
		(width 0.20066)
		(layer "F.Cu")
		(net "M_E_CPU1_CLK_DN<1>")
	)
	(segment
		(start 156.447998 -256.58191)
		(end 156.295344 -256.669794)
		(width 0.20066)
		(layer "F.Cu")
		(net "M_E_CPU1_CLK_DN<1>")
	)
	(segment
		(start 149.123146 -255.21539)
		(end 148.999956 -255.0922)
		(width 0.20066)
		(layer "F.Cu")
		(net "M_E_CPU1_CLK_DN<1>")
	)
	(segment
		(start 157.029658 -256.737866)
		(end 156.447998 -256.58191)
		(width 0.20066)
		(layer "F.Cu")
		(net "M_E_CPU1_CLK_DN<1>")
	)
	(segment
		(start 140.824966 -252.540008)
		(end 137.87882 -251.954284)
		(width 0.1524)
		(layer "F.Cu")
		(net "M_E_CPU1_CLK_DN<1>")
	)
	(segment
		(start 152.819608 -255.607312)
		(end 152.237948 -255.451356)
		(width 0.20066)
		(layer "F.Cu")
		(net "M_E_CPU1_CLK_DN<1>")
	)
	(segment
		(start 161.61893 -259.348478)
		(end 161.453068 -258.929632)
		(width 0.20066)
		(layer "F.Cu")
		(net "M_E_CPU1_CLK_DN<1>")
	)
	(segment
		(start 162.33902 -259.366766)
		(end 162.099244 -259.606542)
		(width 0.20066)
		(layer "F.Cu")
		(net "M_E_CPU1_CLK_DN<1>")
	)
	(segment
		(start 150.879302 -255.21539)
		(end 149.123146 -255.21539)
		(width 0.20066)
		(layer "F.Cu")
		(net "M_E_CPU1_CLK_DN<1>")
	)
	(segment
		(start 135.884412 -251.54255)
		(end 134.295642 -250.76658)
		(width 0.1524)
		(layer "F.Cu")
		(net "M_E_CPU1_CLK_DN<1>")
	)
	(segment
		(start 152.907492 -255.759966)
		(end 152.819608 -255.607312)
		(width 0.20066)
		(layer "F.Cu")
		(net "M_E_CPU1_CLK_DN<1>")
	)
	(segment
		(start 157.698694 -257.04673)
		(end 157.117542 -256.890774)
		(width 0.20066)
		(layer "F.Cu")
		(net "M_E_CPU1_CLK_DN<1>")
	)
	(segment
		(start 158.433008 -257.114802)
		(end 157.851348 -256.958846)
		(width 0.20066)
		(layer "F.Cu")
		(net "M_E_CPU1_CLK_DN<1>")
	)
	(segment
		(start 148.274786 -255.21539)
		(end 147.672806 -255.21539)
		(width 0.20066)
		(layer "F.Cu")
		(net "M_E_CPU1_CLK_DN<1>")
	)
	(segment
		(start 162.344608 -256.523236)
		(end 161.757868 -256.389378)
		(width 0.20066)
		(layer "F.Cu")
		(net "M_E_CPU1_CLK_DN<0>")
	)
	(segment
		(start 143.104108 -252.865128)
		(end 142.940024 -252.755654)
		(width 0.1524)
		(layer "F.Cu")
		(net "M_E_CPU1_CLK_DN<0>")
	)
	(segment
		(start 161.078926 -256.109216)
		(end 160.932876 -256.20091)
		(width 0.20066)
		(layer "F.Cu")
		(net "M_E_CPU1_CLK_DN<0>")
	)
	(segment
		(start 160.346136 -256.067052)
		(end 160.254442 -255.920748)
		(width 0.20066)
		(layer "F.Cu")
		(net "M_E_CPU1_CLK_DN<0>")
	)
	(segment
		(start 149.6949 -254.124968)
		(end 149.57171 -254.001778)
		(width 0.20066)
		(layer "F.Cu")
		(net "M_E_CPU1_CLK_DN<0>")
	)
	(segment
		(start 163.75634 -256.845562)
		(end 163.1696 -256.711704)
		(width 0.20066)
		(layer "F.Cu")
		(net "M_E_CPU1_CLK_DN<0>")
	)
	(segment
		(start 168.203626 -258.200906)
		(end 167.953436 -257.931412)
		(width 0.20066)
		(layer "F.Cu")
		(net "M_E_CPU1_CLK_DN<0>")
	)
	(segment
		(start 169.460164 -259.55498)
		(end 168.203626 -258.200906)
		(width 0.20066)
		(layer "F.Cu")
		(net "M_E_CPU1_CLK_DN<0>")
	)
	(segment
		(start 165.900862 -257.210306)
		(end 165.313868 -257.076194)
		(width 0.20066)
		(layer "F.Cu")
		(net "M_E_CPU1_CLK_DN<0>")
	)
	(segment
		(start 163.077906 -256.5654)
		(end 162.490658 -256.431542)
		(width 0.20066)
		(layer "F.Cu")
		(net "M_E_CPU1_CLK_DN<0>")
	)
	(segment
		(start 162.490658 -256.431542)
		(end 162.344608 -256.523236)
		(width 0.20066)
		(layer "F.Cu")
		(net "M_E_CPU1_CLK_DN<0>")
	)
	(segment
		(start 159.521144 -255.878584)
		(end 158.934404 -255.744726)
		(width 0.20066)
		(layer "F.Cu")
		(net "M_E_CPU1_CLK_DN<0>")
	)
	(segment
		(start 148.86432 -254.124968)
		(end 146.668744 -254.124968)
		(width 0.20066)
		(layer "F.Cu")
		(net "M_E_CPU1_CLK_DN<0>")
	)
	(segment
		(start 169.713656 -259.602478)
		(end 169.574464 -259.602478)
		(width 0.20066)
		(layer "F.Cu")
		(net "M_E_CPU1_CLK_DN<0>")
	)
	(segment
		(start 145.592038 -254.196088)
		(end 144.91589 -254.00254)
		(width 0.1524)
		(layer "F.Cu")
		(net "M_E_CPU1_CLK_DN<0>")
	)
	(segment
		(start 160.254442 -255.920748)
		(end 159.667194 -255.78689)
		(width 0.20066)
		(layer "F.Cu")
		(net "M_E_CPU1_CLK_DN<0>")
	)
	(segment
		(start 136.16559 -250.959366)
		(end 135.989568 -250.84151)
		(width 0.1524)
		(layer "F.Cu")
		(net "M_E_CPU1_CLK_DN<0>")
	)
	(segment
		(start 165.167818 -257.167888)
		(end 164.581078 -257.03403)
		(width 0.20066)
		(layer "F.Cu")
		(net "M_E_CPU1_CLK_DN<0>")
	)
	(segment
		(start 164.489384 -256.887726)
		(end 163.902136 -256.753868)
		(width 0.20066)
		(layer "F.Cu")
		(net "M_E_CPU1_CLK_DN<0>")
	)
	(segment
		(start 137.59053 -251.27966)
		(end 136.341358 -251.031756)
		(width 0.1524)
		(layer "F.Cu")
		(net "M_E_CPU1_CLK_DN<0>")
	)
	(segment
		(start 167.596312 -257.722624)
		(end 165.992556 -257.35661)
		(width 0.20066)
		(layer "F.Cu")
		(net "M_E_CPU1_CLK_DN<0>")
	)
	(segment
		(start 169.574464 -259.602478)
		(end 169.460164 -259.55498)
		(width 0.20066)
		(layer "F.Cu")
		(net "M_E_CPU1_CLK_DN<0>")
	)
	(segment
		(start 161.666174 -256.243074)
		(end 161.078926 -256.109216)
		(width 0.20066)
		(layer "F.Cu")
		(net "M_E_CPU1_CLK_DN<0>")
	)
	(segment
		(start 157.308296 -255.373378)
		(end 150.713694 -254.165354)
		(width 0.20066)
		(layer "F.Cu")
		(net "M_E_CPU1_CLK_DN<0>")
	)
	(segment
		(start 169.949368 -259.366766)
		(end 169.713656 -259.602478)
		(width 0.20066)
		(layer "F.Cu")
		(net "M_E_CPU1_CLK_DN<0>")
	)
	(segment
		(start 158.84271 -255.598422)
		(end 158.255462 -255.464564)
		(width 0.20066)
		(layer "F.Cu")
		(net "M_E_CPU1_CLK_DN<0>")
	)
	(segment
		(start 137.918444 -251.312172)
		(end 137.59053 -251.27966)
		(width 0.1524)
		(layer "F.Cu")
		(net "M_E_CPU1_CLK_DN<0>")
	)
	(segment
		(start 136.341358 -251.031756)
		(end 136.16559 -250.959366)
		(width 0.1524)
		(layer "F.Cu")
		(net "M_E_CPU1_CLK_DN<0>")
	)
	(segment
		(start 135.654796 -250.593606)
		(end 135.605266 -250.495054)
		(width 0.1524)
		(layer "F.Cu")
		(net "M_E_CPU1_CLK_DN<0>")
	)
	(segment
		(start 163.902136 -256.753868)
		(end 163.75634 -256.845562)
		(width 0.20066)
		(layer "F.Cu")
		(net "M_E_CPU1_CLK_DN<0>")
	)
	(segment
		(start 170.457114 -259.366766)
		(end 169.949368 -259.366766)
		(width 0.20066)
		(layer "F.Cu")
		(net "M_E_CPU1_CLK_DN<0>")
	)
	(segment
		(start 158.934404 -255.744726)
		(end 158.84271 -255.598422)
		(width 0.20066)
		(layer "F.Cu")
		(net "M_E_CPU1_CLK_DN<0>")
	)
	(segment
		(start 146.41576 -254.161544)
		(end 146.381216 -254.196088)
		(width 0.1524)
		(layer "F.Cu")
		(net "M_E_CPU1_CLK_DN<0>")
	)
	(segment
		(start 140.87602 -251.900182)
		(end 137.918444 -251.312172)
		(width 0.1524)
		(layer "F.Cu")
		(net "M_E_CPU1_CLK_DN<0>")
	)
	(segment
		(start 163.1696 -256.711704)
		(end 163.077906 -256.5654)
		(width 0.20066)
		(layer "F.Cu")
		(net "M_E_CPU1_CLK_DN<0>")
	)
	(segment
		(start 150.713694 -254.165354)
		(end 150.268178 -254.124968)
		(width 0.20066)
		(layer "F.Cu")
		(net "M_E_CPU1_CLK_DN<0>")
	)
	(segment
		(start 149.57171 -254.001778)
		(end 148.98751 -254.001778)
		(width 0.20066)
		(layer "F.Cu")
		(net "M_E_CPU1_CLK_DN<0>")
	)
	(segment
		(start 158.109412 -255.556258)
		(end 157.308296 -255.373378)
		(width 0.20066)
		(layer "F.Cu")
		(net "M_E_CPU1_CLK_DN<0>")
	)
	(segment
		(start 144.91589 -254.00254)
		(end 143.104108 -252.865128)
		(width 0.1524)
		(layer "F.Cu")
		(net "M_E_CPU1_CLK_DN<0>")
	)
	(segment
		(start 159.667194 -255.78689)
		(end 159.521144 -255.878584)
		(width 0.20066)
		(layer "F.Cu")
		(net "M_E_CPU1_CLK_DN<0>")
	)
	(segment
		(start 148.98751 -254.001778)
		(end 148.86432 -254.124968)
		(width 0.20066)
		(layer "F.Cu")
		(net "M_E_CPU1_CLK_DN<0>")
	)
	(segment
		(start 164.581078 -257.03403)
		(end 164.489384 -256.887726)
		(width 0.20066)
		(layer "F.Cu")
		(net "M_E_CPU1_CLK_DN<0>")
	)
	(segment
		(start 160.932876 -256.20091)
		(end 160.346136 -256.067052)
		(width 0.20066)
		(layer "F.Cu")
		(net "M_E_CPU1_CLK_DN<0>")
	)
	(segment
		(start 167.683434 -257.754628)
		(end 167.596312 -257.722624)
		(width 0.20066)
		(layer "F.Cu")
		(net "M_E_CPU1_CLK_DN<0>")
	)
	(segment
		(start 167.953436 -257.931412)
		(end 167.683434 -257.754628)
		(width 0.20066)
		(layer "F.Cu")
		(net "M_E_CPU1_CLK_DN<0>")
	)
	(segment
		(start 135.605266 -250.495054)
		(end 135.605266 -250.155964)
		(width 0.1524)
		(layer "F.Cu")
		(net "M_E_CPU1_CLK_DN<0>")
	)
	(segment
		(start 146.381216 -254.196088)
		(end 145.592038 -254.196088)
		(width 0.1524)
		(layer "F.Cu")
		(net "M_E_CPU1_CLK_DN<0>")
	)
	(segment
		(start 146.668744 -254.124968)
		(end 146.630644 -254.124968)
		(width 0.152654)
		(layer "F.Cu")
		(net "M_E_CPU1_CLK_DN<0>")
	)
	(segment
		(start 135.989568 -250.84151)
		(end 135.654796 -250.593606)
		(width 0.1524)
		(layer "F.Cu")
		(net "M_E_CPU1_CLK_DN<0>")
	)
	(segment
		(start 146.594068 -254.161544)
		(end 146.41576 -254.161544)
		(width 0.1524)
		(layer "F.Cu")
		(net "M_E_CPU1_CLK_DN<0>")
	)
	(segment
		(start 165.992556 -257.35661)
		(end 165.900862 -257.210306)
		(width 0.20066)
		(layer "F.Cu")
		(net "M_E_CPU1_CLK_DN<0>")
	)
	(segment
		(start 146.630644 -254.124968)
		(end 146.594068 -254.161544)
		(width 0.1524)
		(layer "F.Cu")
		(net "M_E_CPU1_CLK_DN<0>")
	)
	(segment
		(start 150.268178 -254.124968)
		(end 149.6949 -254.124968)
		(width 0.20066)
		(layer "F.Cu")
		(net "M_E_CPU1_CLK_DN<0>")
	)
	(segment
		(start 142.940024 -252.755654)
		(end 140.87602 -251.900182)
		(width 0.1524)
		(layer "F.Cu")
		(net "M_E_CPU1_CLK_DN<0>")
	)
	(segment
		(start 158.255462 -255.464564)
		(end 158.109412 -255.556258)
		(width 0.20066)
		(layer "F.Cu")
		(net "M_E_CPU1_CLK_DN<0>")
	)
	(segment
		(start 165.313868 -257.076194)
		(end 165.167818 -257.167888)
		(width 0.20066)
		(layer "F.Cu")
		(net "M_E_CPU1_CLK_DN<0>")
	)
	(segment
		(start 161.757868 -256.389378)
		(end 161.666174 -256.243074)
		(width 0.20066)
		(layer "F.Cu")
		(net "M_E_CPU1_CLK_DN<0>")
	)
	(segment
		(start 159.76092 -269.566644)
		(end 158.813246 -269.566644)
		(width 0.20066)
		(layer "F.Cu")
		(net "M_E_CPU1_ALERT_N")
	)
	(segment
		(start 161.922968 -269.141702)
		(end 161.708592 -269.141702)
		(width 0.101854)
		(layer "F.Cu")
		(net "M_E_CPU1_ALERT_N")
	)
	(segment
		(start 160.513014 -268.81455)
		(end 159.76092 -269.566644)
		(width 0.20066)
		(layer "F.Cu")
		(net "M_E_CPU1_ALERT_N")
	)
	(segment
		(start 122.087894 -253.919482)
		(end 122.088148 -253.919736)
		(width 0.20066)
		(layer "F.Cu")
		(net "M_E_CPU1_ALERT_N")
	)
	(segment
		(start 164.570664 -269.527528)
		(end 164.570664 -269.362428)
		(width 0.20066)
		(layer "F.Cu")
		(net "M_E_CPU1_ALERT_N")
	)
	(segment
		(start 165.766496 -269.566644)
		(end 165.361112 -269.972028)
		(width 0.20066)
		(layer "F.Cu")
		(net "M_E_CPU1_ALERT_N")
	)
	(segment
		(start 122.087894 -253.383796)
		(end 122.087894 -253.919482)
		(width 0.20066)
		(layer "F.Cu")
		(net "M_E_CPU1_ALERT_N")
	)
	(segment
		(start 165.361112 -269.972028)
		(end 165.015164 -269.972028)
		(width 0.20066)
		(layer "F.Cu")
		(net "M_E_CPU1_ALERT_N")
	)
	(segment
		(start 157.708346 -269.566644)
		(end 158.813246 -269.566644)
		(width 0.20066)
		(layer "F.Cu")
		(net "M_E_CPU1_ALERT_N")
	)
	(segment
		(start 164.102542 -269.141702)
		(end 163.741862 -269.141702)
		(width 0.101854)
		(layer "F.Cu")
		(net "M_E_CPU1_ALERT_N")
	)
	(segment
		(start 164.570664 -269.362428)
		(end 164.349938 -269.141702)
		(width 0.20066)
		(layer "F.Cu")
		(net "M_E_CPU1_ALERT_N")
	)
	(segment
		(start 161.198306 -268.81455)
		(end 160.513014 -268.81455)
		(width 0.20066)
		(layer "F.Cu")
		(net "M_E_CPU1_ALERT_N")
	)
	(segment
		(start 163.741862 -269.141702)
		(end 161.922968 -269.141702)
		(width 0.1016)
		(layer "F.Cu")
		(net "M_E_CPU1_ALERT_N")
	)
	(segment
		(start 166.357046 -269.566644)
		(end 165.766496 -269.566644)
		(width 0.20066)
		(layer "F.Cu")
		(net "M_E_CPU1_ALERT_N")
	)
	(segment
		(start 164.349938 -269.141702)
		(end 164.102542 -269.141702)
		(width 0.20066)
		(layer "F.Cu")
		(net "M_E_CPU1_ALERT_N")
	)
	(segment
		(start 161.525458 -269.141702)
		(end 161.198306 -268.81455)
		(width 0.20066)
		(layer "F.Cu")
		(net "M_E_CPU1_ALERT_N")
	)
	(segment
		(start 161.708592 -269.141702)
		(end 161.525458 -269.141702)
		(width 0.20066)
		(layer "F.Cu")
		(net "M_E_CPU1_ALERT_N")
	)
	(segment
		(start 165.015164 -269.972028)
		(end 164.570664 -269.527528)
		(width 0.20066)
		(layer "F.Cu")
		(net "M_E_CPU1_ALERT_N")
	)
	(via
		(at 122.088148 -253.919736)
		(size 0.4572)
		(drill 0.2032)
		(layers "F.Cu" "B.Cu")
		(net "M_E_CPU1_ALERT_N")
	)
	(via
		(at 157.708346 -269.566644)
		(size 0.4572)
		(drill 0.2032)
		(layers "F.Cu" "B.Cu")
		(net "M_E_CPU1_ALERT_N")
	)
	(segment
		(start 125.19025 -257.664712)
		(end 125.179836 -257.670808)
		(width 0.088646)
		(layer "In11.Cu")
		(net "M_E_CPU1_ALERT_N")
	)
	(segment
		(start 142.457678 -260.06171)
		(end 140.823696 -258.427728)
		(width 0.18288)
		(layer "In11.Cu")
		(net "M_E_CPU1_ALERT_N")
	)
	(segment
		(start 132.15366 -257.670808)
		(end 132.143246 -257.664712)
		(width 0.088646)
		(layer "In11.Cu")
		(net "M_E_CPU1_ALERT_N")
	)
	(segment
		(start 125.57506 -257.670808)
		(end 125.564646 -257.664712)
		(width 0.088646)
		(layer "In11.Cu")
		(net "M_E_CPU1_ALERT_N")
	)
	(segment
		(start 131.76885 -257.664712)
		(end 131.758436 -257.670808)
		(width 0.088646)
		(layer "In11.Cu")
		(net "M_E_CPU1_ALERT_N")
	)
	(segment
		(start 121.627392 -257.332988)
		(end 121.627392 -257.22961)
		(width 0.088646)
		(layer "In11.Cu")
		(net "M_E_CPU1_ALERT_N")
	)
	(segment
		(start 121.915936 -256.741676)
		(end 122.088148 -256.325878)
		(width 0.088646)
		(layer "In11.Cu")
		(net "M_E_CPU1_ALERT_N")
	)
	(segment
		(start 121.627392 -257.22961)
		(end 121.768362 -256.88925)
		(width 0.088646)
		(layer "In11.Cu")
		(net "M_E_CPU1_ALERT_N")
	)
	(segment
		(start 123.310396 -257.664712)
		(end 123.295664 -257.673348)
		(width 0.088646)
		(layer "In11.Cu")
		(net "M_E_CPU1_ALERT_N")
	)
	(segment
		(start 122.088148 -256.325878)
		(end 122.088148 -253.919736)
		(width 0.088646)
		(layer "In11.Cu")
		(net "M_E_CPU1_ALERT_N")
	)
	(segment
		(start 139.17295 -258.427728)
		(end 139.0396 -258.427728)
		(width 0.088646)
		(layer "In11.Cu")
		(net "M_E_CPU1_ALERT_N")
	)
	(segment
		(start 133.64845 -257.664712)
		(end 133.638036 -257.670808)
		(width 0.088646)
		(layer "In11.Cu")
		(net "M_E_CPU1_ALERT_N")
	)
	(segment
		(start 138.909298 -258.297426)
		(end 138.909298 -257.98907)
		(width 0.088646)
		(layer "In11.Cu")
		(net "M_E_CPU1_ALERT_N")
	)
	(segment
		(start 157.708346 -269.566644)
		(end 157.708346 -269.291562)
		(width 0.18288)
		(layer "In11.Cu")
		(net "M_E_CPU1_ALERT_N")
	)
	(segment
		(start 157.433518 -269.045944)
		(end 157.239462 -268.884654)
		(width 0.18288)
		(layer "In11.Cu")
		(net "M_E_CPU1_ALERT_N")
	)
	(segment
		(start 140.823696 -258.427728)
		(end 139.17295 -258.427728)
		(width 0.18288)
		(layer "In11.Cu")
		(net "M_E_CPU1_ALERT_N")
	)
	(segment
		(start 124.250196 -257.664712)
		(end 124.235464 -257.673348)
		(width 0.088646)
		(layer "In11.Cu")
		(net "M_E_CPU1_ALERT_N")
	)
	(segment
		(start 157.239462 -268.884654)
		(end 148.416518 -260.06171)
		(width 0.18288)
		(layer "In11.Cu")
		(net "M_E_CPU1_ALERT_N")
	)
	(segment
		(start 148.416518 -260.06171)
		(end 142.457678 -260.06171)
		(width 0.18288)
		(layer "In11.Cu")
		(net "M_E_CPU1_ALERT_N")
	)
	(segment
		(start 138.730736 -257.669792)
		(end 138.721846 -257.664712)
		(width 0.088646)
		(layer "In11.Cu")
		(net "M_E_CPU1_ALERT_N")
	)
	(segment
		(start 127.45466 -257.670808)
		(end 127.444246 -257.664712)
		(width 0.088646)
		(layer "In11.Cu")
		(net "M_E_CPU1_ALERT_N")
	)
	(segment
		(start 139.0396 -258.427728)
		(end 138.909298 -258.297426)
		(width 0.088646)
		(layer "In11.Cu")
		(net "M_E_CPU1_ALERT_N")
	)
	(segment
		(start 129.888996 -257.664712)
		(end 129.874264 -257.673348)
		(width 0.088646)
		(layer "In11.Cu")
		(net "M_E_CPU1_ALERT_N")
	)
	(segment
		(start 137.796778 -257.673348)
		(end 137.782046 -257.664712)
		(width 0.088646)
		(layer "In11.Cu")
		(net "M_E_CPU1_ALERT_N")
	)
	(segment
		(start 128.949196 -257.664712)
		(end 128.934464 -257.673348)
		(width 0.088646)
		(layer "In11.Cu")
		(net "M_E_CPU1_ALERT_N")
	)
	(segment
		(start 157.605476 -269.188692)
		(end 157.433518 -269.045944)
		(width 0.18288)
		(layer "In11.Cu")
		(net "M_E_CPU1_ALERT_N")
	)
	(segment
		(start 121.946416 -257.698748)
		(end 121.660412 -257.412744)
		(width 0.088646)
		(layer "In11.Cu")
		(net "M_E_CPU1_ALERT_N")
	)
	(segment
		(start 136.856978 -257.673348)
		(end 136.842246 -257.664712)
		(width 0.088646)
		(layer "In11.Cu")
		(net "M_E_CPU1_ALERT_N")
	)
	(segment
		(start 127.06985 -257.664712)
		(end 127.059436 -257.670808)
		(width 0.088646)
		(layer "In11.Cu")
		(net "M_E_CPU1_ALERT_N")
	)
	(segment
		(start 121.768362 -256.88925)
		(end 121.915936 -256.741676)
		(width 0.088646)
		(layer "In11.Cu")
		(net "M_E_CPU1_ALERT_N")
	)
	(segment
		(start 122.370596 -257.664712)
		(end 122.355864 -257.673348)
		(width 0.088646)
		(layer "In11.Cu")
		(net "M_E_CPU1_ALERT_N")
	)
	(segment
		(start 130.828796 -257.664712)
		(end 130.814064 -257.673348)
		(width 0.088646)
		(layer "In11.Cu")
		(net "M_E_CPU1_ALERT_N")
	)
	(segment
		(start 135.527542 -257.664458)
		(end 135.527796 -257.664712)
		(width 0.088646)
		(layer "In11.Cu")
		(net "M_E_CPU1_ALERT_N")
	)
	(segment
		(start 135.912606 -257.670808)
		(end 135.902192 -257.664712)
		(width 0.088646)
		(layer "In11.Cu")
		(net "M_E_CPU1_ALERT_N")
	)
	(segment
		(start 135.902192 -257.664712)
		(end 135.902446 -257.664458)
		(width 0.088646)
		(layer "In11.Cu")
		(net "M_E_CPU1_ALERT_N")
	)
	(segment
		(start 157.708346 -269.291562)
		(end 157.605476 -269.188692)
		(width 0.18288)
		(layer "In11.Cu")
		(net "M_E_CPU1_ALERT_N")
	)
	(segment
		(start 134.03326 -257.670808)
		(end 134.022846 -257.664712)
		(width 0.088646)
		(layer "In11.Cu")
		(net "M_E_CPU1_ALERT_N")
	)
	(arc
		(start 134.587996 -257.664712)
		(mid 134.311437 -257.740455)
		(end 134.03326 -257.670808)
		(width 0.088646)
		(layer "In11.Cu")
		(net "M_E_CPU1_ALERT_N")
	)
	(arc
		(start 129.323592 -257.664712)
		(mid 129.136394 -257.614569)
		(end 128.949196 -257.664712)
		(width 0.088646)
		(layer "In11.Cu")
		(net "M_E_CPU1_ALERT_N")
	)
	(arc
		(start 131.203192 -257.664712)
		(mid 131.015994 -257.614569)
		(end 130.828796 -257.664712)
		(width 0.088646)
		(layer "In11.Cu")
		(net "M_E_CPU1_ALERT_N")
	)
	(arc
		(start 124.624592 -257.664712)
		(mid 124.437394 -257.614569)
		(end 124.250196 -257.664712)
		(width 0.088646)
		(layer "In11.Cu")
		(net "M_E_CPU1_ALERT_N")
	)
	(arc
		(start 133.082792 -257.664712)
		(mid 132.895594 -257.614569)
		(end 132.708396 -257.664712)
		(width 0.088646)
		(layer "In11.Cu")
		(net "M_E_CPU1_ALERT_N")
	)
	(arc
		(start 137.40765 -257.664712)
		(mid 137.133451 -257.740547)
		(end 136.856978 -257.673348)
		(width 0.088646)
		(layer "In11.Cu")
		(net "M_E_CPU1_ALERT_N")
	)
	(arc
		(start 138.721846 -257.664712)
		(mid 138.534648 -257.614569)
		(end 138.34745 -257.664712)
		(width 0.088646)
		(layer "In11.Cu")
		(net "M_E_CPU1_ALERT_N")
	)
	(arc
		(start 134.962392 -257.664712)
		(mid 134.775194 -257.614569)
		(end 134.587996 -257.664712)
		(width 0.088646)
		(layer "In11.Cu")
		(net "M_E_CPU1_ALERT_N")
	)
	(arc
		(start 133.638036 -257.670808)
		(mid 133.359604 -257.740654)
		(end 133.082792 -257.664712)
		(width 0.088646)
		(layer "In11.Cu")
		(net "M_E_CPU1_ALERT_N")
	)
	(arc
		(start 136.842246 -257.664712)
		(mid 136.655048 -257.614569)
		(end 136.46785 -257.664712)
		(width 0.088646)
		(layer "In11.Cu")
		(net "M_E_CPU1_ALERT_N")
	)
	(arc
		(start 128.383792 -257.664712)
		(mid 128.196594 -257.614569)
		(end 128.009396 -257.664712)
		(width 0.088646)
		(layer "In11.Cu")
		(net "M_E_CPU1_ALERT_N")
	)
	(arc
		(start 135.902446 -257.664458)
		(mid 135.714994 -257.614222)
		(end 135.527542 -257.664458)
		(width 0.088646)
		(layer "In11.Cu")
		(net "M_E_CPU1_ALERT_N")
	)
	(arc
		(start 128.009396 -257.664712)
		(mid 127.732837 -257.740455)
		(end 127.45466 -257.670808)
		(width 0.088646)
		(layer "In11.Cu")
		(net "M_E_CPU1_ALERT_N")
	)
	(arc
		(start 127.059436 -257.670808)
		(mid 126.781004 -257.740654)
		(end 126.504192 -257.664712)
		(width 0.088646)
		(layer "In11.Cu")
		(net "M_E_CPU1_ALERT_N")
	)
	(arc
		(start 121.660412 -257.412744)
		(mid 121.635962 -257.376152)
		(end 121.627392 -257.332988)
		(width 0.088646)
		(layer "In11.Cu")
		(net "M_E_CPU1_ALERT_N")
	)
	(arc
		(start 135.527796 -257.664712)
		(mid 135.245094 -257.740488)
		(end 134.962392 -257.664712)
		(width 0.088646)
		(layer "In11.Cu")
		(net "M_E_CPU1_ALERT_N")
	)
	(arc
		(start 122.026426 -257.737356)
		(mid 121.98311 -257.724907)
		(end 121.946416 -257.698748)
		(width 0.088646)
		(layer "In11.Cu")
		(net "M_E_CPU1_ALERT_N")
	)
	(arc
		(start 125.179836 -257.670808)
		(mid 124.901404 -257.740654)
		(end 124.624592 -257.664712)
		(width 0.088646)
		(layer "In11.Cu")
		(net "M_E_CPU1_ALERT_N")
	)
	(arc
		(start 124.235464 -257.673348)
		(mid 123.958989 -257.740668)
		(end 123.684792 -257.664712)
		(width 0.088646)
		(layer "In11.Cu")
		(net "M_E_CPU1_ALERT_N")
	)
	(arc
		(start 137.782046 -257.664712)
		(mid 137.594848 -257.614569)
		(end 137.40765 -257.664712)
		(width 0.088646)
		(layer "In11.Cu")
		(net "M_E_CPU1_ALERT_N")
	)
	(arc
		(start 122.355864 -257.673348)
		(mid 122.196003 -257.730355)
		(end 122.026426 -257.737356)
		(width 0.088646)
		(layer "In11.Cu")
		(net "M_E_CPU1_ALERT_N")
	)
	(arc
		(start 127.444246 -257.664712)
		(mid 127.257048 -257.614569)
		(end 127.06985 -257.664712)
		(width 0.088646)
		(layer "In11.Cu")
		(net "M_E_CPU1_ALERT_N")
	)
	(arc
		(start 126.504192 -257.664712)
		(mid 126.316994 -257.614569)
		(end 126.129796 -257.664712)
		(width 0.088646)
		(layer "In11.Cu")
		(net "M_E_CPU1_ALERT_N")
	)
	(arc
		(start 136.46785 -257.664712)
		(mid 136.191037 -257.740582)
		(end 135.912606 -257.670808)
		(width 0.088646)
		(layer "In11.Cu")
		(net "M_E_CPU1_ALERT_N")
	)
	(arc
		(start 138.909298 -257.98907)
		(mid 138.861619 -257.80617)
		(end 138.730736 -257.669792)
		(width 0.088646)
		(layer "In11.Cu")
		(net "M_E_CPU1_ALERT_N")
	)
	(arc
		(start 132.143246 -257.664712)
		(mid 131.956048 -257.614569)
		(end 131.76885 -257.664712)
		(width 0.088646)
		(layer "In11.Cu")
		(net "M_E_CPU1_ALERT_N")
	)
	(arc
		(start 123.295664 -257.673348)
		(mid 123.019189 -257.740668)
		(end 122.744992 -257.664712)
		(width 0.088646)
		(layer "In11.Cu")
		(net "M_E_CPU1_ALERT_N")
	)
	(arc
		(start 126.129796 -257.664712)
		(mid 125.853237 -257.740455)
		(end 125.57506 -257.670808)
		(width 0.088646)
		(layer "In11.Cu")
		(net "M_E_CPU1_ALERT_N")
	)
	(arc
		(start 131.758436 -257.670808)
		(mid 131.480004 -257.740654)
		(end 131.203192 -257.664712)
		(width 0.088646)
		(layer "In11.Cu")
		(net "M_E_CPU1_ALERT_N")
	)
	(arc
		(start 132.708396 -257.664712)
		(mid 132.431837 -257.740455)
		(end 132.15366 -257.670808)
		(width 0.088646)
		(layer "In11.Cu")
		(net "M_E_CPU1_ALERT_N")
	)
	(arc
		(start 138.34745 -257.664712)
		(mid 138.073251 -257.740547)
		(end 137.796778 -257.673348)
		(width 0.088646)
		(layer "In11.Cu")
		(net "M_E_CPU1_ALERT_N")
	)
	(arc
		(start 125.564646 -257.664712)
		(mid 125.377448 -257.614569)
		(end 125.19025 -257.664712)
		(width 0.088646)
		(layer "In11.Cu")
		(net "M_E_CPU1_ALERT_N")
	)
	(arc
		(start 130.263392 -257.664712)
		(mid 130.076194 -257.614569)
		(end 129.888996 -257.664712)
		(width 0.088646)
		(layer "In11.Cu")
		(net "M_E_CPU1_ALERT_N")
	)
	(arc
		(start 129.874264 -257.673348)
		(mid 129.597789 -257.740668)
		(end 129.323592 -257.664712)
		(width 0.088646)
		(layer "In11.Cu")
		(net "M_E_CPU1_ALERT_N")
	)
	(arc
		(start 128.934464 -257.673348)
		(mid 128.657989 -257.740668)
		(end 128.383792 -257.664712)
		(width 0.088646)
		(layer "In11.Cu")
		(net "M_E_CPU1_ALERT_N")
	)
	(arc
		(start 130.814064 -257.673348)
		(mid 130.537589 -257.740668)
		(end 130.263392 -257.664712)
		(width 0.088646)
		(layer "In11.Cu")
		(net "M_E_CPU1_ALERT_N")
	)
	(arc
		(start 134.022846 -257.664712)
		(mid 133.835648 -257.614569)
		(end 133.64845 -257.664712)
		(width 0.088646)
		(layer "In11.Cu")
		(net "M_E_CPU1_ALERT_N")
	)
	(arc
		(start 123.684792 -257.664712)
		(mid 123.497594 -257.614569)
		(end 123.310396 -257.664712)
		(width 0.088646)
		(layer "In11.Cu")
		(net "M_E_CPU1_ALERT_N")
	)
	(arc
		(start 122.744992 -257.664712)
		(mid 122.557794 -257.614569)
		(end 122.370596 -257.664712)
		(width 0.088646)
		(layer "In11.Cu")
		(net "M_E_CPU1_ALERT_N")
	)
	(segment
		(start 406.753314 -243.216684)
		(end 405.623014 -243.216684)
		(width 0.20066)
		(layer "F.Cu")
		(net "M_E_CPU0_SB_RSP<1>")
	)
	(segment
		(start 373.207534 -248.528078)
		(end 373.20728 -248.527824)
		(width 0.20066)
		(layer "F.Cu")
		(net "M_E_CPU0_SB_RSP<1>")
	)
	(segment
		(start 373.20728 -248.527824)
		(end 373.20728 -247.992138)
		(width 0.20066)
		(layer "F.Cu")
		(net "M_E_CPU0_SB_RSP<1>")
	)
	(segment
		(start 384.385566 -246.89181)
		(end 384.385566 -247.34901)
		(width 0.088646)
		(layer "In6.Cu")
		(net "M_E_CPU0_SB_RSP<1>")
	)
	(segment
		(start 379.598682 -248.316496)
		(end 379.588268 -248.3104)
		(width 0.088646)
		(layer "In6.Cu")
		(net "M_E_CPU0_SB_RSP<1>")
	)
	(segment
		(start 386.978652 -246.683784)
		(end 386.818632 -246.843804)
		(width 0.18288)
		(layer "In6.Cu")
		(net "M_E_CPU0_SB_RSP<1>")
	)
	(segment
		(start 389.93064 -245.486936)
		(end 388.849616 -246.56796)
		(width 0.18288)
		(layer "In6.Cu")
		(net "M_E_CPU0_SB_RSP<1>")
	)
	(segment
		(start 384.385566 -247.34901)
		(end 383.919984 -247.814592)
		(width 0.088646)
		(layer "In6.Cu")
		(net "M_E_CPU0_SB_RSP<1>")
	)
	(segment
		(start 374.899682 -248.316496)
		(end 374.889268 -248.3104)
		(width 0.088646)
		(layer "In6.Cu")
		(net "M_E_CPU0_SB_RSP<1>")
	)
	(segment
		(start 380.538736 -248.316496)
		(end 380.528322 -248.3104)
		(width 0.088646)
		(layer "In6.Cu")
		(net "M_E_CPU0_SB_RSP<1>")
	)
	(segment
		(start 386.658612 -247.18391)
		(end 385.625848 -247.18391)
		(width 0.18288)
		(layer "In6.Cu")
		(net "M_E_CPU0_SB_RSP<1>")
	)
	(segment
		(start 400.867626 -243.63172)
		(end 399.01241 -245.486936)
		(width 0.18288)
		(layer "In6.Cu")
		(net "M_E_CPU0_SB_RSP<1>")
	)
	(segment
		(start 373.931688 -248.299732)
		(end 373.20728 -247.992138)
		(width 0.088646)
		(layer "In6.Cu")
		(net "M_E_CPU0_SB_RSP<1>")
	)
	(segment
		(start 384.744468 -246.737632)
		(end 384.539744 -246.737632)
		(width 0.088646)
		(layer "In6.Cu")
		(net "M_E_CPU0_SB_RSP<1>")
	)
	(segment
		(start 385.625848 -247.18391)
		(end 385.17957 -246.737632)
		(width 0.18288)
		(layer "In6.Cu")
		(net "M_E_CPU0_SB_RSP<1>")
	)
	(segment
		(start 383.741422 -248.311416)
		(end 383.732532 -248.316496)
		(width 0.088646)
		(layer "In6.Cu")
		(net "M_E_CPU0_SB_RSP<1>")
	)
	(segment
		(start 386.818632 -246.843804)
		(end 386.818632 -247.02389)
		(width 0.18288)
		(layer "In6.Cu")
		(net "M_E_CPU0_SB_RSP<1>")
	)
	(segment
		(start 376.779282 -248.316496)
		(end 376.76455 -248.30786)
		(width 0.088646)
		(layer "In6.Cu")
		(net "M_E_CPU0_SB_RSP<1>")
	)
	(segment
		(start 384.539744 -246.737632)
		(end 384.385566 -246.89181)
		(width 0.088646)
		(layer "In6.Cu")
		(net "M_E_CPU0_SB_RSP<1>")
	)
	(segment
		(start 404.043134 -243.63172)
		(end 400.867626 -243.63172)
		(width 0.18288)
		(layer "In6.Cu")
		(net "M_E_CPU0_SB_RSP<1>")
	)
	(segment
		(start 399.01241 -245.486936)
		(end 389.93064 -245.486936)
		(width 0.18288)
		(layer "In6.Cu")
		(net "M_E_CPU0_SB_RSP<1>")
	)
	(segment
		(start 385.17957 -246.737632)
		(end 384.744468 -246.737632)
		(width 0.18288)
		(layer "In6.Cu")
		(net "M_E_CPU0_SB_RSP<1>")
	)
	(segment
		(start 405.623014 -243.216684)
		(end 404.45817 -243.216684)
		(width 0.18288)
		(layer "In6.Cu")
		(net "M_E_CPU0_SB_RSP<1>")
	)
	(segment
		(start 373.960136 -248.316496)
		(end 373.931688 -248.299732)
		(width 0.088646)
		(layer "In6.Cu")
		(net "M_E_CPU0_SB_RSP<1>")
	)
	(segment
		(start 388.849616 -246.56796)
		(end 387.785864 -246.56796)
		(width 0.18288)
		(layer "In6.Cu")
		(net "M_E_CPU0_SB_RSP<1>")
	)
	(segment
		(start 404.45817 -243.216684)
		(end 404.043134 -243.63172)
		(width 0.18288)
		(layer "In6.Cu")
		(net "M_E_CPU0_SB_RSP<1>")
	)
	(segment
		(start 387.50621 -246.683784)
		(end 386.978652 -246.683784)
		(width 0.18288)
		(layer "In6.Cu")
		(net "M_E_CPU0_SB_RSP<1>")
	)
	(segment
		(start 378.659136 -248.316496)
		(end 378.648722 -248.3104)
		(width 0.088646)
		(layer "In6.Cu")
		(net "M_E_CPU0_SB_RSP<1>")
	)
	(segment
		(start 387.785864 -246.56796)
		(end 387.50621 -246.683784)
		(width 0.18288)
		(layer "In6.Cu")
		(net "M_E_CPU0_SB_RSP<1>")
	)
	(segment
		(start 386.818632 -247.02389)
		(end 386.658612 -247.18391)
		(width 0.18288)
		(layer "In6.Cu")
		(net "M_E_CPU0_SB_RSP<1>")
	)
	(segment
		(start 375.839482 -248.316496)
		(end 375.82475 -248.30786)
		(width 0.088646)
		(layer "In6.Cu")
		(net "M_E_CPU0_SB_RSP<1>")
	)
	(segment
		(start 383.919984 -247.814592)
		(end 383.919984 -247.992138)
		(width 0.088646)
		(layer "In6.Cu")
		(net "M_E_CPU0_SB_RSP<1>")
	)
	(arc
		(start 382.418336 -248.316496)
		(mid 382.135634 -248.240754)
		(end 381.852932 -248.316496)
		(width 0.088646)
		(layer "In6.Cu")
		(net "M_E_CPU0_SB_RSP<1>")
	)
	(arc
		(start 380.913132 -248.316496)
		(mid 380.725934 -248.366639)
		(end 380.538736 -248.316496)
		(width 0.088646)
		(layer "In6.Cu")
		(net "M_E_CPU0_SB_RSP<1>")
	)
	(arc
		(start 379.973078 -248.316496)
		(mid 379.78588 -248.366639)
		(end 379.598682 -248.316496)
		(width 0.088646)
		(layer "In6.Cu")
		(net "M_E_CPU0_SB_RSP<1>")
	)
	(arc
		(start 376.213878 -248.316496)
		(mid 376.02668 -248.366639)
		(end 375.839482 -248.316496)
		(width 0.088646)
		(layer "In6.Cu")
		(net "M_E_CPU0_SB_RSP<1>")
	)
	(arc
		(start 377.153678 -248.316496)
		(mid 376.96648 -248.366639)
		(end 376.779282 -248.316496)
		(width 0.088646)
		(layer "In6.Cu")
		(net "M_E_CPU0_SB_RSP<1>")
	)
	(arc
		(start 383.919984 -247.992138)
		(mid 383.872305 -248.175038)
		(end 383.741422 -248.311416)
		(width 0.088646)
		(layer "In6.Cu")
		(net "M_E_CPU0_SB_RSP<1>")
	)
	(arc
		(start 378.648722 -248.3104)
		(mid 378.37029 -248.240586)
		(end 378.093478 -248.316496)
		(width 0.088646)
		(layer "In6.Cu")
		(net "M_E_CPU0_SB_RSP<1>")
	)
	(arc
		(start 375.82475 -248.30786)
		(mid 375.548309 -248.240694)
		(end 375.274078 -248.316496)
		(width 0.088646)
		(layer "In6.Cu")
		(net "M_E_CPU0_SB_RSP<1>")
	)
	(arc
		(start 379.033532 -248.316496)
		(mid 378.846334 -248.366639)
		(end 378.659136 -248.316496)
		(width 0.088646)
		(layer "In6.Cu")
		(net "M_E_CPU0_SB_RSP<1>")
	)
	(arc
		(start 375.274078 -248.316496)
		(mid 375.08688 -248.366639)
		(end 374.899682 -248.316496)
		(width 0.088646)
		(layer "In6.Cu")
		(net "M_E_CPU0_SB_RSP<1>")
	)
	(arc
		(start 381.478536 -248.316496)
		(mid 381.195834 -248.240754)
		(end 380.913132 -248.316496)
		(width 0.088646)
		(layer "In6.Cu")
		(net "M_E_CPU0_SB_RSP<1>")
	)
	(arc
		(start 374.889268 -248.3104)
		(mid 374.61109 -248.240708)
		(end 374.334532 -248.316496)
		(width 0.088646)
		(layer "In6.Cu")
		(net "M_E_CPU0_SB_RSP<1>")
	)
	(arc
		(start 378.093478 -248.316496)
		(mid 377.90628 -248.366639)
		(end 377.719082 -248.316496)
		(width 0.088646)
		(layer "In6.Cu")
		(net "M_E_CPU0_SB_RSP<1>")
	)
	(arc
		(start 383.358136 -248.316496)
		(mid 383.075434 -248.240754)
		(end 382.792732 -248.316496)
		(width 0.088646)
		(layer "In6.Cu")
		(net "M_E_CPU0_SB_RSP<1>")
	)
	(arc
		(start 382.792732 -248.316496)
		(mid 382.605534 -248.366639)
		(end 382.418336 -248.316496)
		(width 0.088646)
		(layer "In6.Cu")
		(net "M_E_CPU0_SB_RSP<1>")
	)
	(arc
		(start 383.732532 -248.316496)
		(mid 383.545334 -248.366639)
		(end 383.358136 -248.316496)
		(width 0.088646)
		(layer "In6.Cu")
		(net "M_E_CPU0_SB_RSP<1>")
	)
	(arc
		(start 381.852932 -248.316496)
		(mid 381.665734 -248.366639)
		(end 381.478536 -248.316496)
		(width 0.088646)
		(layer "In6.Cu")
		(net "M_E_CPU0_SB_RSP<1>")
	)
	(arc
		(start 374.334532 -248.316496)
		(mid 374.147334 -248.366639)
		(end 373.960136 -248.316496)
		(width 0.088646)
		(layer "In6.Cu")
		(net "M_E_CPU0_SB_RSP<1>")
	)
	(arc
		(start 379.588268 -248.3104)
		(mid 379.31009 -248.240708)
		(end 379.033532 -248.316496)
		(width 0.088646)
		(layer "In6.Cu")
		(net "M_E_CPU0_SB_RSP<1>")
	)
	(arc
		(start 377.719082 -248.316496)
		(mid 377.43638 -248.240754)
		(end 377.153678 -248.316496)
		(width 0.088646)
		(layer "In6.Cu")
		(net "M_E_CPU0_SB_RSP<1>")
	)
	(arc
		(start 380.528322 -248.3104)
		(mid 380.24989 -248.240586)
		(end 379.973078 -248.316496)
		(width 0.088646)
		(layer "In6.Cu")
		(net "M_E_CPU0_SB_RSP<1>")
	)
	(arc
		(start 376.76455 -248.30786)
		(mid 376.488109 -248.240694)
		(end 376.213878 -248.316496)
		(width 0.088646)
		(layer "In6.Cu")
		(net "M_E_CPU0_SB_RSP<1>")
	)
	(segment
		(start 372.737634 -249.341894)
		(end 372.737634 -248.806208)
		(width 0.20066)
		(layer "F.Cu")
		(net "M_E_CPU0_SB_RSP<0>")
	)
	(segment
		(start 372.73738 -249.342148)
		(end 372.737634 -249.341894)
		(width 0.20066)
		(layer "F.Cu")
		(net "M_E_CPU0_SB_RSP<0>")
	)
	(segment
		(start 414.297114 -243.216684)
		(end 413.166814 -243.216684)
		(width 0.20066)
		(layer "F.Cu")
		(net "M_E_CPU0_SB_RSP<0>")
	)
	(segment
		(start 383.239772 -249.45467)
		(end 383.00533 -249.220228)
		(width 0.088646)
		(layer "In6.Cu")
		(net "M_E_CPU0_SB_RSP<0>")
	)
	(segment
		(start 383.838704 -249.45467)
		(end 383.239772 -249.45467)
		(width 0.088646)
		(layer "In6.Cu")
		(net "M_E_CPU0_SB_RSP<0>")
	)
	(segment
		(start 399.45818 -246.482616)
		(end 390.444482 -246.482616)
		(width 0.18288)
		(layer "In6.Cu")
		(net "M_E_CPU0_SB_RSP<0>")
	)
	(segment
		(start 373.879364 -249.12193)
		(end 373.864632 -249.130566)
		(width 0.088646)
		(layer "In6.Cu")
		(net "M_E_CPU0_SB_RSP<0>")
	)
	(segment
		(start 384.752342 -248.250964)
		(end 384.140456 -248.86285)
		(width 0.088646)
		(layer "In6.Cu")
		(net "M_E_CPU0_SB_RSP<0>")
	)
	(segment
		(start 387.806184 -248.09831)
		(end 387.65353 -248.250964)
		(width 0.18288)
		(layer "In6.Cu")
		(net "M_E_CPU0_SB_RSP<0>")
	)
	(segment
		(start 373.490236 -249.130566)
		(end 373.46128 -249.113548)
		(width 0.088646)
		(layer "In6.Cu")
		(net "M_E_CPU0_SB_RSP<0>")
	)
	(segment
		(start 407.557224 -244.471444)
		(end 407.32964 -244.699028)
		(width 0.18288)
		(layer "In6.Cu")
		(net "M_E_CPU0_SB_RSP<0>")
	)
	(segment
		(start 376.694446 -249.12447)
		(end 376.684032 -249.130566)
		(width 0.088646)
		(layer "In6.Cu")
		(net "M_E_CPU0_SB_RSP<0>")
	)
	(segment
		(start 390.444482 -246.482616)
		(end 388.828788 -248.09831)
		(width 0.18288)
		(layer "In6.Cu")
		(net "M_E_CPU0_SB_RSP<0>")
	)
	(segment
		(start 384.140456 -248.86285)
		(end 384.140456 -249.152918)
		(width 0.088646)
		(layer "In6.Cu")
		(net "M_E_CPU0_SB_RSP<0>")
	)
	(segment
		(start 374.819164 -249.12193)
		(end 374.804432 -249.130566)
		(width 0.088646)
		(layer "In6.Cu")
		(net "M_E_CPU0_SB_RSP<0>")
	)
	(segment
		(start 400.06143 -245.879366)
		(end 399.45818 -246.482616)
		(width 0.18288)
		(layer "In6.Cu")
		(net "M_E_CPU0_SB_RSP<0>")
	)
	(segment
		(start 409.559506 -243.642134)
		(end 409.473654 -243.677694)
		(width 0.18288)
		(layer "In6.Cu")
		(net "M_E_CPU0_SB_RSP<0>")
	)
	(segment
		(start 407.144474 -244.872002)
		(end 404.711916 -245.879366)
		(width 0.18288)
		(layer "In6.Cu")
		(net "M_E_CPU0_SB_RSP<0>")
	)
	(segment
		(start 412.741364 -243.642134)
		(end 409.559506 -243.642134)
		(width 0.18288)
		(layer "In6.Cu")
		(net "M_E_CPU0_SB_RSP<0>")
	)
	(segment
		(start 384.140456 -249.152918)
		(end 383.838704 -249.45467)
		(width 0.088646)
		(layer "In6.Cu")
		(net "M_E_CPU0_SB_RSP<0>")
	)
	(segment
		(start 404.711916 -245.879366)
		(end 400.06143 -245.879366)
		(width 0.18288)
		(layer "In6.Cu")
		(net "M_E_CPU0_SB_RSP<0>")
	)
	(segment
		(start 413.166814 -243.216684)
		(end 412.741364 -243.642134)
		(width 0.18288)
		(layer "In6.Cu")
		(net "M_E_CPU0_SB_RSP<0>")
	)
	(segment
		(start 385.63169 -248.250964)
		(end 384.752342 -248.250964)
		(width 0.088646)
		(layer "In6.Cu")
		(net "M_E_CPU0_SB_RSP<0>")
	)
	(segment
		(start 375.758964 -249.12193)
		(end 375.744232 -249.130566)
		(width 0.088646)
		(layer "In6.Cu")
		(net "M_E_CPU0_SB_RSP<0>")
	)
	(segment
		(start 407.32964 -244.699028)
		(end 407.144474 -244.872002)
		(width 0.18288)
		(layer "In6.Cu")
		(net "M_E_CPU0_SB_RSP<0>")
	)
	(segment
		(start 378.578364 -249.12193)
		(end 378.563632 -249.130566)
		(width 0.088646)
		(layer "In6.Cu")
		(net "M_E_CPU0_SB_RSP<0>")
	)
	(segment
		(start 388.828788 -248.09831)
		(end 387.806184 -248.09831)
		(width 0.18288)
		(layer "In6.Cu")
		(net "M_E_CPU0_SB_RSP<0>")
	)
	(segment
		(start 409.473654 -243.677694)
		(end 407.557224 -244.471444)
		(width 0.18288)
		(layer "In6.Cu")
		(net "M_E_CPU0_SB_RSP<0>")
	)
	(segment
		(start 377.633992 -249.12447)
		(end 377.623578 -249.130566)
		(width 0.088646)
		(layer "In6.Cu")
		(net "M_E_CPU0_SB_RSP<0>")
	)
	(segment
		(start 373.46128 -249.113548)
		(end 372.737634 -248.806208)
		(width 0.088646)
		(layer "In6.Cu")
		(net "M_E_CPU0_SB_RSP<0>")
	)
	(segment
		(start 387.65353 -248.250964)
		(end 385.63169 -248.250964)
		(width 0.18288)
		(layer "In6.Cu")
		(net "M_E_CPU0_SB_RSP<0>")
	)
	(arc
		(start 379.503432 -249.130566)
		(mid 379.316234 -249.180709)
		(end 379.129036 -249.130566)
		(width 0.088646)
		(layer "In6.Cu")
		(net "M_E_CPU0_SB_RSP<0>")
	)
	(arc
		(start 374.804432 -249.130566)
		(mid 374.617234 -249.180709)
		(end 374.430036 -249.130566)
		(width 0.088646)
		(layer "In6.Cu")
		(net "M_E_CPU0_SB_RSP<0>")
	)
	(arc
		(start 379.129036 -249.130566)
		(mid 378.854837 -249.054731)
		(end 378.578364 -249.12193)
		(width 0.088646)
		(layer "In6.Cu")
		(net "M_E_CPU0_SB_RSP<0>")
	)
	(arc
		(start 378.563632 -249.130566)
		(mid 378.376434 -249.180709)
		(end 378.189236 -249.130566)
		(width 0.088646)
		(layer "In6.Cu")
		(net "M_E_CPU0_SB_RSP<0>")
	)
	(arc
		(start 382.888236 -249.130566)
		(mid 382.605534 -249.05479)
		(end 382.322832 -249.130566)
		(width 0.088646)
		(layer "In6.Cu")
		(net "M_E_CPU0_SB_RSP<0>")
	)
	(arc
		(start 381.008636 -249.130566)
		(mid 380.725934 -249.05479)
		(end 380.443232 -249.130566)
		(width 0.088646)
		(layer "In6.Cu")
		(net "M_E_CPU0_SB_RSP<0>")
	)
	(arc
		(start 383.00533 -249.220228)
		(mid 382.949725 -249.171554)
		(end 382.888236 -249.130566)
		(width 0.088646)
		(layer "In6.Cu")
		(net "M_E_CPU0_SB_RSP<0>")
	)
	(arc
		(start 375.369836 -249.130566)
		(mid 375.095637 -249.054731)
		(end 374.819164 -249.12193)
		(width 0.088646)
		(layer "In6.Cu")
		(net "M_E_CPU0_SB_RSP<0>")
	)
	(arc
		(start 380.443232 -249.130566)
		(mid 380.256034 -249.180709)
		(end 380.068836 -249.130566)
		(width 0.088646)
		(layer "In6.Cu")
		(net "M_E_CPU0_SB_RSP<0>")
	)
	(arc
		(start 373.864632 -249.130566)
		(mid 373.677434 -249.180709)
		(end 373.490236 -249.130566)
		(width 0.088646)
		(layer "In6.Cu")
		(net "M_E_CPU0_SB_RSP<0>")
	)
	(arc
		(start 377.249182 -249.130566)
		(mid 376.972623 -249.054823)
		(end 376.694446 -249.12447)
		(width 0.088646)
		(layer "In6.Cu")
		(net "M_E_CPU0_SB_RSP<0>")
	)
	(arc
		(start 374.430036 -249.130566)
		(mid 374.155837 -249.054731)
		(end 373.879364 -249.12193)
		(width 0.088646)
		(layer "In6.Cu")
		(net "M_E_CPU0_SB_RSP<0>")
	)
	(arc
		(start 382.322832 -249.130566)
		(mid 382.135634 -249.180709)
		(end 381.948436 -249.130566)
		(width 0.088646)
		(layer "In6.Cu")
		(net "M_E_CPU0_SB_RSP<0>")
	)
	(arc
		(start 376.684032 -249.130566)
		(mid 376.496834 -249.180709)
		(end 376.309636 -249.130566)
		(width 0.088646)
		(layer "In6.Cu")
		(net "M_E_CPU0_SB_RSP<0>")
	)
	(arc
		(start 381.948436 -249.130566)
		(mid 381.665734 -249.05479)
		(end 381.383032 -249.130566)
		(width 0.088646)
		(layer "In6.Cu")
		(net "M_E_CPU0_SB_RSP<0>")
	)
	(arc
		(start 375.744232 -249.130566)
		(mid 375.557034 -249.180709)
		(end 375.369836 -249.130566)
		(width 0.088646)
		(layer "In6.Cu")
		(net "M_E_CPU0_SB_RSP<0>")
	)
	(arc
		(start 381.383032 -249.130566)
		(mid 381.195834 -249.180709)
		(end 381.008636 -249.130566)
		(width 0.088646)
		(layer "In6.Cu")
		(net "M_E_CPU0_SB_RSP<0>")
	)
	(arc
		(start 380.068836 -249.130566)
		(mid 379.786134 -249.05479)
		(end 379.503432 -249.130566)
		(width 0.088646)
		(layer "In6.Cu")
		(net "M_E_CPU0_SB_RSP<0>")
	)
	(arc
		(start 378.189236 -249.130566)
		(mid 377.912423 -249.054696)
		(end 377.633992 -249.12447)
		(width 0.088646)
		(layer "In6.Cu")
		(net "M_E_CPU0_SB_RSP<0>")
	)
	(arc
		(start 376.309636 -249.130566)
		(mid 376.035437 -249.054731)
		(end 375.758964 -249.12193)
		(width 0.088646)
		(layer "In6.Cu")
		(net "M_E_CPU0_SB_RSP<0>")
	)
	(arc
		(start 377.623578 -249.130566)
		(mid 377.43638 -249.180709)
		(end 377.249182 -249.130566)
		(width 0.088646)
		(layer "In6.Cu")
		(net "M_E_CPU0_SB_RSP<0>")
	)
	(segment
		(start 413.293052 -247.057418)
		(end 413.275526 -247.057418)
		(width 0.101854)
		(layer "F.Cu")
		(net "M_E_CPU0_SB_PAR")
	)
	(segment
		(start 387.542024 -247.429274)
		(end 387.2738 -247.16105)
		(width 0.088646)
		(layer "F.Cu")
		(net "M_E_CPU0_SB_PAR")
	)
	(segment
		(start 415.307526 -247.05437)
		(end 415.294826 -247.04167)
		(width 0.1016)
		(layer "F.Cu")
		(net "M_E_CPU0_SB_PAR")
	)
	(segment
		(start 415.53257 -247.05437)
		(end 415.307526 -247.05437)
		(width 0.20066)
		(layer "F.Cu")
		(net "M_E_CPU0_SB_PAR")
	)
	(segment
		(start 387.97865 -247.429274)
		(end 387.542024 -247.429274)
		(width 0.088646)
		(layer "F.Cu")
		(net "M_E_CPU0_SB_PAR")
	)
	(segment
		(start 397.69034 -245.536212)
		(end 394.502132 -245.536212)
		(width 0.20066)
		(layer "F.Cu")
		(net "M_E_CPU0_SB_PAR")
	)
	(segment
		(start 416.423094 -247.45569)
		(end 415.93389 -247.45569)
		(width 0.20066)
		(layer "F.Cu")
		(net "M_E_CPU0_SB_PAR")
	)
	(segment
		(start 409.051506 -247.494552)
		(end 408.57678 -247.494552)
		(width 0.20066)
		(layer "F.Cu")
		(net "M_E_CPU0_SB_PAR")
	)
	(segment
		(start 386.336286 -247.307354)
		(end 386.172456 -247.307354)
		(width 0.088646)
		(layer "F.Cu")
		(net "M_E_CPU0_SB_PAR")
	)
	(segment
		(start 385.930902 -247.166384)
		(end 385.740148 -247.166384)
		(width 0.088646)
		(layer "F.Cu")
		(net "M_E_CPU0_SB_PAR")
	)
	(segment
		(start 415.93389 -247.45569)
		(end 415.53257 -247.05437)
		(width 0.20066)
		(layer "F.Cu")
		(net "M_E_CPU0_SB_PAR")
	)
	(segment
		(start 416.623754 -247.25503)
		(end 416.423094 -247.45569)
		(width 0.20066)
		(layer "F.Cu")
		(net "M_E_CPU0_SB_PAR")
	)
	(segment
		(start 418.397182 -246.616728)
		(end 417.006786 -246.616728)
		(width 0.20066)
		(layer "F.Cu")
		(net "M_E_CPU0_SB_PAR")
	)
	(segment
		(start 408.250136 -247.061228)
		(end 407.719022 -247.061228)
		(width 0.20066)
		(layer "F.Cu")
		(net "M_E_CPU0_SB_PAR")
	)
	(segment
		(start 413.275526 -247.057418)
		(end 412.105094 -247.057418)
		(width 0.20066)
		(layer "F.Cu")
		(net "M_E_CPU0_SB_PAR")
	)
	(segment
		(start 405.780494 -247.04167)
		(end 405.768048 -247.054116)
		(width 0.1016)
		(layer "F.Cu")
		(net "M_E_CPU0_SB_PAR")
	)
	(segment
		(start 407.699464 -247.04167)
		(end 405.780494 -247.04167)
		(width 0.1016)
		(layer "F.Cu")
		(net "M_E_CPU0_SB_PAR")
	)
	(segment
		(start 411.040834 -246.616728)
		(end 410.853382 -246.616728)
		(width 0.20066)
		(layer "F.Cu")
		(net "M_E_CPU0_SB_PAR")
	)
	(segment
		(start 405.763222 -247.054116)
		(end 405.049482 -247.054116)
		(width 0.20066)
		(layer "F.Cu")
		(net "M_E_CPU0_SB_PAR")
	)
	(segment
		(start 404.572216 -247.531382)
		(end 399.68551 -247.531382)
		(width 0.20066)
		(layer "F.Cu")
		(net "M_E_CPU0_SB_PAR")
	)
	(segment
		(start 408.57678 -247.494552)
		(end 408.460194 -247.377966)
		(width 0.20066)
		(layer "F.Cu")
		(net "M_E_CPU0_SB_PAR")
	)
	(segment
		(start 408.460194 -247.377966)
		(end 408.460194 -247.271286)
		(width 0.20066)
		(layer "F.Cu")
		(net "M_E_CPU0_SB_PAR")
	)
	(segment
		(start 409.868116 -246.994426)
		(end 409.551632 -246.994426)
		(width 0.20066)
		(layer "F.Cu")
		(net "M_E_CPU0_SB_PAR")
	)
	(segment
		(start 417.006786 -246.616728)
		(end 416.623754 -246.99976)
		(width 0.20066)
		(layer "F.Cu")
		(net "M_E_CPU0_SB_PAR")
	)
	(segment
		(start 386.1689 -247.30583)
		(end 386.099304 -247.23598)
		(width 0.088646)
		(layer "F.Cu")
		(net "M_E_CPU0_SB_PAR")
	)
	(segment
		(start 410.853382 -246.616728)
		(end 410.245814 -246.616728)
		(width 0.20066)
		(layer "F.Cu")
		(net "M_E_CPU0_SB_PAR")
	)
	(segment
		(start 412.105094 -247.057418)
		(end 411.040834 -246.616728)
		(width 0.20066)
		(layer "F.Cu")
		(net "M_E_CPU0_SB_PAR")
	)
	(segment
		(start 410.245814 -246.616728)
		(end 409.868116 -246.994426)
		(width 0.20066)
		(layer "F.Cu")
		(net "M_E_CPU0_SB_PAR")
	)
	(segment
		(start 409.551632 -246.994426)
		(end 409.051506 -247.494552)
		(width 0.20066)
		(layer "F.Cu")
		(net "M_E_CPU0_SB_PAR")
	)
	(segment
		(start 388.522972 -246.884952)
		(end 387.97865 -247.429274)
		(width 0.088646)
		(layer "F.Cu")
		(net "M_E_CPU0_SB_PAR")
	)
	(segment
		(start 413.3088 -247.04167)
		(end 413.293052 -247.057418)
		(width 0.1016)
		(layer "F.Cu")
		(net "M_E_CPU0_SB_PAR")
	)
	(segment
		(start 399.68551 -247.531382)
		(end 397.69034 -245.536212)
		(width 0.20066)
		(layer "F.Cu")
		(net "M_E_CPU0_SB_PAR")
	)
	(segment
		(start 387.2738 -247.16105)
		(end 386.6515 -247.16105)
		(width 0.088646)
		(layer "F.Cu")
		(net "M_E_CPU0_SB_PAR")
	)
	(segment
		(start 405.049482 -247.054116)
		(end 404.572216 -247.531382)
		(width 0.20066)
		(layer "F.Cu")
		(net "M_E_CPU0_SB_PAR")
	)
	(segment
		(start 393.153392 -246.884952)
		(end 388.713218 -246.884952)
		(width 0.1016)
		(layer "F.Cu")
		(net "M_E_CPU0_SB_PAR")
	)
	(segment
		(start 394.502132 -245.536212)
		(end 393.4841 -246.554244)
		(width 0.20066)
		(layer "F.Cu")
		(net "M_E_CPU0_SB_PAR")
	)
	(segment
		(start 385.567174 -247.714262)
		(end 385.894834 -247.714262)
		(width 0.088646)
		(layer "F.Cu")
		(net "M_E_CPU0_SB_PAR")
	)
	(segment
		(start 408.460194 -247.271286)
		(end 408.250136 -247.061228)
		(width 0.20066)
		(layer "F.Cu")
		(net "M_E_CPU0_SB_PAR")
	)
	(segment
		(start 405.768048 -247.054116)
		(end 405.763222 -247.054116)
		(width 0.101854)
		(layer "F.Cu")
		(net "M_E_CPU0_SB_PAR")
	)
	(segment
		(start 416.623754 -246.99976)
		(end 416.623754 -247.25503)
		(width 0.20066)
		(layer "F.Cu")
		(net "M_E_CPU0_SB_PAR")
	)
	(segment
		(start 393.4841 -246.554244)
		(end 393.153392 -246.884952)
		(width 0.1016)
		(layer "F.Cu")
		(net "M_E_CPU0_SB_PAR")
	)
	(segment
		(start 407.719022 -247.061228)
		(end 407.699464 -247.04167)
		(width 0.1016)
		(layer "F.Cu")
		(net "M_E_CPU0_SB_PAR")
	)
	(segment
		(start 388.713218 -246.884952)
		(end 388.522972 -246.884952)
		(width 0.088646)
		(layer "F.Cu")
		(net "M_E_CPU0_SB_PAR")
	)
	(segment
		(start 385.660392 -247.199404)
		(end 385.492244 -247.367552)
		(width 0.088646)
		(layer "F.Cu")
		(net "M_E_CPU0_SB_PAR")
	)
	(segment
		(start 415.294826 -247.04167)
		(end 413.3088 -247.04167)
		(width 0.1016)
		(layer "F.Cu")
		(net "M_E_CPU0_SB_PAR")
	)
	(arc
		(start 386.099304 -247.23598)
		(mid 386.022025 -247.184437)
		(end 385.930902 -247.166384)
		(width 0.088646)
		(layer "F.Cu")
		(net "M_E_CPU0_SB_PAR")
	)
	(arc
		(start 385.740148 -247.166384)
		(mid 385.69699 -247.174969)
		(end 385.660392 -247.199404)
		(width 0.088646)
		(layer "F.Cu")
		(net "M_E_CPU0_SB_PAR")
	)
	(arc
		(start 386.6515 -247.16105)
		(mid 386.627717 -247.163647)
		(end 386.605018 -247.17121)
		(width 0.088646)
		(layer "F.Cu")
		(net "M_E_CPU0_SB_PAR")
	)
	(arc
		(start 386.605018 -247.17121)
		(mid 386.585245 -247.187542)
		(end 386.564378 -247.202452)
		(width 0.088646)
		(layer "F.Cu")
		(net "M_E_CPU0_SB_PAR")
	)
	(arc
		(start 386.172456 -247.307354)
		(mid 386.170512 -247.306967)
		(end 386.1689 -247.30583)
		(width 0.088646)
		(layer "F.Cu")
		(net "M_E_CPU0_SB_PAR")
	)
	(arc
		(start 385.492244 -247.367552)
		(mid 385.426803 -247.52545)
		(end 385.492244 -247.683274)
		(width 0.088646)
		(layer "F.Cu")
		(net "M_E_CPU0_SB_PAR")
	)
	(arc
		(start 385.492244 -247.683274)
		(mid 385.526622 -247.706245)
		(end 385.567174 -247.714262)
		(width 0.088646)
		(layer "F.Cu")
		(net "M_E_CPU0_SB_PAR")
	)
	(arc
		(start 386.564378 -247.202452)
		(mid 386.454359 -247.263662)
		(end 386.336286 -247.307354)
		(width 0.088646)
		(layer "F.Cu")
		(net "M_E_CPU0_SB_PAR")
	)
	(segment
		(start 412.388812 -238.541814)
		(end 412.278576 -238.541814)
		(width 0.20066)
		(layer "F.Cu")
		(net "M_E_CPU0_SB_DQS_DP<9>")
	)
	(segment
		(start 403.465792 -238.229394)
		(end 404.258272 -238.229394)
		(width 0.20066)
		(layer "F.Cu")
		(net "M_E_CPU0_SB_DQS_DP<9>")
	)
	(segment
		(start 405.640032 -237.722918)
		(end 405.640032 -238.029242)
		(width 0.20066)
		(layer "F.Cu")
		(net "M_E_CPU0_SB_DQS_DP<9>")
	)
	(segment
		(start 402.614892 -238.229394)
		(end 402.739352 -238.353854)
		(width 0.20066)
		(layer "F.Cu")
		(net "M_E_CPU0_SB_DQS_DP<9>")
	)
	(segment
		(start 388.073138 -243.110766)
		(end 388.695438 -242.488466)
		(width 0.088646)
		(layer "F.Cu")
		(net "M_E_CPU0_SB_DQS_DP<9>")
	)
	(segment
		(start 397.529812 -238.353854)
		(end 397.654272 -238.229394)
		(width 0.20066)
		(layer "F.Cu")
		(net "M_E_CPU0_SB_DQS_DP<9>")
	)
	(segment
		(start 387.218428 -243.396008)
		(end 387.50367 -243.110766)
		(width 0.088646)
		(layer "F.Cu")
		(net "M_E_CPU0_SB_DQS_DP<9>")
	)
	(segment
		(start 400.435572 -238.353854)
		(end 400.560032 -238.229394)
		(width 0.20066)
		(layer "F.Cu")
		(net "M_E_CPU0_SB_DQS_DP<9>")
	)
	(segment
		(start 386.898388 -243.396262)
		(end 386.898642 -243.396008)
		(width 0.088646)
		(layer "F.Cu")
		(net "M_E_CPU0_SB_DQS_DP<9>")
	)
	(segment
		(start 398.982692 -238.353854)
		(end 399.107152 -238.229394)
		(width 0.20066)
		(layer "F.Cu")
		(net "M_E_CPU0_SB_DQS_DP<9>")
	)
	(segment
		(start 385.210812 -242.811046)
		(end 385.334764 -242.988592)
		(width 0.088646)
		(layer "F.Cu")
		(net "M_E_CPU0_SB_DQS_DP<9>")
	)
	(segment
		(start 396.927832 -238.353854)
		(end 397.529812 -238.353854)
		(width 0.20066)
		(layer "F.Cu")
		(net "M_E_CPU0_SB_DQS_DP<9>")
	)
	(segment
		(start 391.927842 -241.405156)
		(end 395.140434 -238.192564)
		(width 0.1524)
		(layer "F.Cu")
		(net "M_E_CPU0_SB_DQS_DP<9>")
	)
	(segment
		(start 404.258272 -238.229394)
		(end 404.893018 -237.594648)
		(width 0.20066)
		(layer "F.Cu")
		(net "M_E_CPU0_SB_DQS_DP<9>")
	)
	(segment
		(start 409.029662 -238.277654)
		(end 408.722068 -238.277654)
		(width 0.20066)
		(layer "F.Cu")
		(net "M_E_CPU0_SB_DQS_DP<9>")
	)
	(segment
		(start 405.640032 -238.029242)
		(end 405.726646 -238.116618)
		(width 0.20066)
		(layer "F.Cu")
		(net "M_E_CPU0_SB_DQS_DP<9>")
	)
	(segment
		(start 413.38119 -237.899194)
		(end 413.06115 -238.219234)
		(width 0.20066)
		(layer "F.Cu")
		(net "M_E_CPU0_SB_DQS_DP<9>")
	)
	(segment
		(start 387.50367 -243.110766)
		(end 388.073138 -243.110766)
		(width 0.088646)
		(layer "F.Cu")
		(net "M_E_CPU0_SB_DQS_DP<9>")
	)
	(segment
		(start 399.709132 -238.229394)
		(end 399.833592 -238.353854)
		(width 0.20066)
		(layer "F.Cu")
		(net "M_E_CPU0_SB_DQS_DP<9>")
	)
	(segment
		(start 412.278576 -238.541814)
		(end 411.845506 -238.541814)
		(width 0.101854)
		(layer "F.Cu")
		(net "M_E_CPU0_SB_DQS_DP<9>")
	)
	(segment
		(start 409.42768 -238.561118)
		(end 409.313126 -238.561118)
		(width 0.20066)
		(layer "F.Cu")
		(net "M_E_CPU0_SB_DQS_DP<9>")
	)
	(segment
		(start 408.722068 -238.277654)
		(end 408.320494 -237.87608)
		(width 0.20066)
		(layer "F.Cu")
		(net "M_E_CPU0_SB_DQS_DP<9>")
	)
	(segment
		(start 388.74065 -242.488466)
		(end 388.756144 -242.472972)
		(width 0.088646)
		(layer "F.Cu")
		(net "M_E_CPU0_SB_DQS_DP<9>")
	)
	(segment
		(start 399.107152 -238.229394)
		(end 399.709132 -238.229394)
		(width 0.20066)
		(layer "F.Cu")
		(net "M_E_CPU0_SB_DQS_DP<9>")
	)
	(segment
		(start 413.06115 -238.219234)
		(end 412.711392 -238.219234)
		(width 0.20066)
		(layer "F.Cu")
		(net "M_E_CPU0_SB_DQS_DP<9>")
	)
	(segment
		(start 413.665162 -237.899194)
		(end 413.38119 -237.899194)
		(width 0.20066)
		(layer "F.Cu")
		(net "M_E_CPU0_SB_DQS_DP<9>")
	)
	(segment
		(start 388.756144 -242.472972)
		(end 389.82396 -241.405156)
		(width 0.1524)
		(layer "F.Cu")
		(net "M_E_CPU0_SB_DQS_DP<9>")
	)
	(segment
		(start 413.882586 -238.116618)
		(end 413.665162 -237.899194)
		(width 0.20066)
		(layer "F.Cu")
		(net "M_E_CPU0_SB_DQS_DP<9>")
	)
	(segment
		(start 389.82396 -241.405156)
		(end 391.927842 -241.405156)
		(width 0.1524)
		(layer "F.Cu")
		(net "M_E_CPU0_SB_DQS_DP<9>")
	)
	(segment
		(start 386.83438 -243.396262)
		(end 386.898388 -243.396262)
		(width 0.088646)
		(layer "F.Cu")
		(net "M_E_CPU0_SB_DQS_DP<9>")
	)
	(segment
		(start 409.446984 -238.541814)
		(end 409.42768 -238.561118)
		(width 0.101854)
		(layer "F.Cu")
		(net "M_E_CPU0_SB_DQS_DP<9>")
	)
	(segment
		(start 412.711392 -238.219234)
		(end 412.388812 -238.541814)
		(width 0.20066)
		(layer "F.Cu")
		(net "M_E_CPU0_SB_DQS_DP<9>")
	)
	(segment
		(start 409.313126 -238.561118)
		(end 409.029662 -238.277654)
		(width 0.20066)
		(layer "F.Cu")
		(net "M_E_CPU0_SB_DQS_DP<9>")
	)
	(segment
		(start 401.888452 -238.353854)
		(end 402.012912 -238.229394)
		(width 0.20066)
		(layer "F.Cu")
		(net "M_E_CPU0_SB_DQS_DP<9>")
	)
	(segment
		(start 395.140434 -238.192564)
		(end 395.826234 -238.192564)
		(width 0.1524)
		(layer "F.Cu")
		(net "M_E_CPU0_SB_DQS_DP<9>")
	)
	(segment
		(start 395.901164 -238.229394)
		(end 396.803372 -238.229394)
		(width 0.20066)
		(layer "F.Cu")
		(net "M_E_CPU0_SB_DQS_DP<9>")
	)
	(segment
		(start 395.826234 -238.192564)
		(end 395.863064 -238.229394)
		(width 0.1524)
		(layer "F.Cu")
		(net "M_E_CPU0_SB_DQS_DP<9>")
	)
	(segment
		(start 411.845506 -238.541814)
		(end 409.855924 -238.541814)
		(width 0.1016)
		(layer "F.Cu")
		(net "M_E_CPU0_SB_DQS_DP<9>")
	)
	(segment
		(start 404.893018 -237.594648)
		(end 405.511762 -237.594648)
		(width 0.20066)
		(layer "F.Cu")
		(net "M_E_CPU0_SB_DQS_DP<9>")
	)
	(segment
		(start 388.695438 -242.488466)
		(end 388.74065 -242.488466)
		(width 0.088646)
		(layer "F.Cu")
		(net "M_E_CPU0_SB_DQS_DP<9>")
	)
	(segment
		(start 407.583132 -237.87608)
		(end 407.342594 -238.116618)
		(width 0.20066)
		(layer "F.Cu")
		(net "M_E_CPU0_SB_DQS_DP<9>")
	)
	(segment
		(start 396.803372 -238.229394)
		(end 396.927832 -238.353854)
		(width 0.20066)
		(layer "F.Cu")
		(net "M_E_CPU0_SB_DQS_DP<9>")
	)
	(segment
		(start 399.833592 -238.353854)
		(end 400.435572 -238.353854)
		(width 0.20066)
		(layer "F.Cu")
		(net "M_E_CPU0_SB_DQS_DP<9>")
	)
	(segment
		(start 414.297114 -238.116618)
		(end 413.882586 -238.116618)
		(width 0.20066)
		(layer "F.Cu")
		(net "M_E_CPU0_SB_DQS_DP<9>")
	)
	(segment
		(start 405.726646 -238.116618)
		(end 406.753314 -238.116618)
		(width 0.20066)
		(layer "F.Cu")
		(net "M_E_CPU0_SB_DQS_DP<9>")
	)
	(segment
		(start 384.95478 -242.830858)
		(end 384.95478 -242.795806)
		(width 0.088646)
		(layer "F.Cu")
		(net "M_E_CPU0_SB_DQS_DP<9>")
	)
	(segment
		(start 386.898642 -243.396008)
		(end 387.218428 -243.396008)
		(width 0.088646)
		(layer "F.Cu")
		(net "M_E_CPU0_SB_DQS_DP<9>")
	)
	(segment
		(start 398.256252 -238.229394)
		(end 398.380712 -238.353854)
		(width 0.20066)
		(layer "F.Cu")
		(net "M_E_CPU0_SB_DQS_DP<9>")
	)
	(segment
		(start 398.380712 -238.353854)
		(end 398.982692 -238.353854)
		(width 0.20066)
		(layer "F.Cu")
		(net "M_E_CPU0_SB_DQS_DP<9>")
	)
	(segment
		(start 402.739352 -238.353854)
		(end 403.341332 -238.353854)
		(width 0.20066)
		(layer "F.Cu")
		(net "M_E_CPU0_SB_DQS_DP<9>")
	)
	(segment
		(start 400.560032 -238.229394)
		(end 401.162012 -238.229394)
		(width 0.20066)
		(layer "F.Cu")
		(net "M_E_CPU0_SB_DQS_DP<9>")
	)
	(segment
		(start 408.320494 -237.87608)
		(end 407.583132 -237.87608)
		(width 0.20066)
		(layer "F.Cu")
		(net "M_E_CPU0_SB_DQS_DP<9>")
	)
	(segment
		(start 409.855924 -238.541814)
		(end 409.446984 -238.541814)
		(width 0.101854)
		(layer "F.Cu")
		(net "M_E_CPU0_SB_DQS_DP<9>")
	)
	(segment
		(start 403.341332 -238.353854)
		(end 403.465792 -238.229394)
		(width 0.20066)
		(layer "F.Cu")
		(net "M_E_CPU0_SB_DQS_DP<9>")
	)
	(segment
		(start 385.582922 -243.303806)
		(end 385.612132 -243.32057)
		(width 0.088646)
		(layer "F.Cu")
		(net "M_E_CPU0_SB_DQS_DP<9>")
	)
	(segment
		(start 395.863064 -238.229394)
		(end 395.901164 -238.229394)
		(width 0.1524)
		(layer "F.Cu")
		(net "M_E_CPU0_SB_DQS_DP<9>")
	)
	(segment
		(start 385.418838 -243.16817)
		(end 385.461764 -243.211096)
		(width 0.088646)
		(layer "F.Cu")
		(net "M_E_CPU0_SB_DQS_DP<9>")
	)
	(segment
		(start 407.342594 -238.116618)
		(end 406.753314 -238.116618)
		(width 0.20066)
		(layer "F.Cu")
		(net "M_E_CPU0_SB_DQS_DP<9>")
	)
	(segment
		(start 401.162012 -238.229394)
		(end 401.286472 -238.353854)
		(width 0.20066)
		(layer "F.Cu")
		(net "M_E_CPU0_SB_DQS_DP<9>")
	)
	(segment
		(start 405.511762 -237.594648)
		(end 405.640032 -237.722918)
		(width 0.20066)
		(layer "F.Cu")
		(net "M_E_CPU0_SB_DQS_DP<9>")
	)
	(segment
		(start 402.012912 -238.229394)
		(end 402.614892 -238.229394)
		(width 0.20066)
		(layer "F.Cu")
		(net "M_E_CPU0_SB_DQS_DP<9>")
	)
	(segment
		(start 401.286472 -238.353854)
		(end 401.888452 -238.353854)
		(width 0.20066)
		(layer "F.Cu")
		(net "M_E_CPU0_SB_DQS_DP<9>")
	)
	(segment
		(start 397.654272 -238.229394)
		(end 398.256252 -238.229394)
		(width 0.20066)
		(layer "F.Cu")
		(net "M_E_CPU0_SB_DQS_DP<9>")
	)
	(segment
		(start 384.95478 -242.795806)
		(end 385.004056 -242.74653)
		(width 0.088646)
		(layer "F.Cu")
		(net "M_E_CPU0_SB_DQS_DP<9>")
	)
	(arc
		(start 385.612132 -243.32057)
		(mid 385.894834 -243.396312)
		(end 386.177536 -243.32057)
		(width 0.088646)
		(layer "F.Cu")
		(net "M_E_CPU0_SB_DQS_DP<9>")
	)
	(arc
		(start 385.461764 -243.211096)
		(mid 385.519285 -243.261445)
		(end 385.582922 -243.303806)
		(width 0.088646)
		(layer "F.Cu")
		(net "M_E_CPU0_SB_DQS_DP<9>")
	)
	(arc
		(start 386.551932 -243.32057)
		(mid 386.688174 -243.377004)
		(end 386.83438 -243.396262)
		(width 0.088646)
		(layer "F.Cu")
		(net "M_E_CPU0_SB_DQS_DP<9>")
	)
	(arc
		(start 386.177536 -243.32057)
		(mid 386.364734 -243.270427)
		(end 386.551932 -243.32057)
		(width 0.088646)
		(layer "F.Cu")
		(net "M_E_CPU0_SB_DQS_DP<9>")
	)
	(arc
		(start 385.368292 -243.071142)
		(mid 385.386088 -243.12355)
		(end 385.418838 -243.16817)
		(width 0.088646)
		(layer "F.Cu")
		(net "M_E_CPU0_SB_DQS_DP<9>")
	)
	(arc
		(start 385.004056 -242.74653)
		(mid 385.0463 -242.722818)
		(end 385.094734 -242.724686)
		(width 0.088646)
		(layer "F.Cu")
		(net "M_E_CPU0_SB_DQS_DP<9>")
	)
	(arc
		(start 385.334764 -242.988592)
		(mid 385.356007 -243.028046)
		(end 385.368292 -243.071142)
		(width 0.088646)
		(layer "F.Cu")
		(net "M_E_CPU0_SB_DQS_DP<9>")
	)
	(arc
		(start 385.094734 -242.724686)
		(mid 385.159786 -242.758434)
		(end 385.210812 -242.811046)
		(width 0.088646)
		(layer "F.Cu")
		(net "M_E_CPU0_SB_DQS_DP<9>")
	)
	(segment
		(start 386.068316 -228.1809)
		(end 386.07619 -228.173026)
		(width 0.088646)
		(layer "F.Cu")
		(net "M_E_CPU0_SB_DQS_DP<8>")
	)
	(segment
		(start 416.537902 -198.839328)
		(end 415.88436 -198.839328)
		(width 0.20066)
		(layer "F.Cu")
		(net "M_E_CPU0_SB_DQS_DP<8>")
	)
	(segment
		(start 389.363712 -205.244192)
		(end 391.782046 -202.825858)
		(width 0.20066)
		(layer "F.Cu")
		(net "M_E_CPU0_SB_DQS_DP<8>")
	)
	(segment
		(start 386.12064 -228.161088)
		(end 386.648452 -227.856542)
		(width 0.088646)
		(layer "F.Cu")
		(net "M_E_CPU0_SB_DQS_DP<8>")
	)
	(segment
		(start 409.868878 -199.267572)
		(end 410.097732 -199.267572)
		(width 0.20066)
		(layer "F.Cu")
		(net "M_E_CPU0_SB_DQS_DP<8>")
	)
	(segment
		(start 388.183374 -211.530692)
		(end 388.183374 -211.222082)
		(width 0.1524)
		(layer "F.Cu")
		(net "M_E_CPU0_SB_DQS_DP<8>")
	)
	(segment
		(start 388.102602 -227.314506)
		(end 388.102602 -227.269802)
		(width 0.088646)
		(layer "F.Cu")
		(net "M_E_CPU0_SB_DQS_DP<8>")
	)
	(segment
		(start 411.607508 -199.267826)
		(end 411.356302 -199.01662)
		(width 0.20066)
		(layer "F.Cu")
		(net "M_E_CPU0_SB_DQS_DP<8>")
	)
	(segment
		(start 405.736806 -198.577708)
		(end 405.750776 -198.591678)
		(width 0.1016)
		(layer "F.Cu")
		(net "M_E_CPU0_SB_DQS_DP<8>")
	)
	(segment
		(start 388.118096 -227.254308)
		(end 388.89178 -226.480624)
		(width 0.1524)
		(layer "F.Cu")
		(net "M_E_CPU0_SB_DQS_DP<8>")
	)
	(segment
		(start 413.280352 -198.584566)
		(end 413.275526 -198.584566)
		(width 0.101854)
		(layer "F.Cu")
		(net "M_E_CPU0_SB_DQS_DP<8>")
	)
	(segment
		(start 416.983418 -199.284844)
		(end 416.537902 -198.839328)
		(width 0.20066)
		(layer "F.Cu")
		(net "M_E_CPU0_SB_DQS_DP<8>")
	)
	(segment
		(start 412.002732 -199.267826)
		(end 411.607508 -199.267826)
		(width 0.20066)
		(layer "F.Cu")
		(net "M_E_CPU0_SB_DQS_DP<8>")
	)
	(segment
		(start 408.369008 -198.868538)
		(end 408.906218 -198.868538)
		(width 0.20066)
		(layer "F.Cu")
		(net "M_E_CPU0_SB_DQS_DP<8>")
	)
	(segment
		(start 407.752042 -198.570596)
		(end 407.763726 -198.570596)
		(width 0.101854)
		(layer "F.Cu")
		(net "M_E_CPU0_SB_DQS_DP<8>")
	)
	(segment
		(start 417.829238 -199.01662)
		(end 417.561014 -199.284844)
		(width 0.20066)
		(layer "F.Cu")
		(net "M_E_CPU0_SB_DQS_DP<8>")
	)
	(segment
		(start 388.102602 -227.269802)
		(end 388.118096 -227.254308)
		(width 0.088646)
		(layer "F.Cu")
		(net "M_E_CPU0_SB_DQS_DP<8>")
	)
	(segment
		(start 388.423658 -207.513174)
		(end 388.640066 -206.990696)
		(width 0.20066)
		(layer "F.Cu")
		(net "M_E_CPU0_SB_DQS_DP<8>")
	)
	(segment
		(start 413.275526 -198.584566)
		(end 412.964376 -198.584566)
		(width 0.20066)
		(layer "F.Cu")
		(net "M_E_CPU0_SB_DQS_DP<8>")
	)
	(segment
		(start 388.146544 -211.147152)
		(end 388.146544 -208.905856)
		(width 0.20066)
		(layer "F.Cu")
		(net "M_E_CPU0_SB_DQS_DP<8>")
	)
	(segment
		(start 412.964376 -198.584566)
		(end 412.706058 -198.842884)
		(width 0.20066)
		(layer "F.Cu")
		(net "M_E_CPU0_SB_DQS_DP<8>")
	)
	(segment
		(start 388.89178 -226.480624)
		(end 388.89178 -213.739984)
		(width 0.1524)
		(layer "F.Cu")
		(net "M_E_CPU0_SB_DQS_DP<8>")
	)
	(segment
		(start 413.287464 -198.591678)
		(end 413.280352 -198.584566)
		(width 0.1016)
		(layer "F.Cu")
		(net "M_E_CPU0_SB_DQS_DP<8>")
	)
	(segment
		(start 404.8379 -198.81977)
		(end 405.112728 -198.81977)
		(width 0.20066)
		(layer "F.Cu")
		(net "M_E_CPU0_SB_DQS_DP<8>")
	)
	(segment
		(start 405.731726 -198.577708)
		(end 405.736806 -198.577708)
		(width 0.101854)
		(layer "F.Cu")
		(net "M_E_CPU0_SB_DQS_DP<8>")
	)
	(segment
		(start 410.097732 -199.267572)
		(end 410.348684 -199.01662)
		(width 0.20066)
		(layer "F.Cu")
		(net "M_E_CPU0_SB_DQS_DP<8>")
	)
	(segment
		(start 415.30016 -198.591678)
		(end 413.287464 -198.591678)
		(width 0.1016)
		(layer "F.Cu")
		(net "M_E_CPU0_SB_DQS_DP<8>")
	)
	(segment
		(start 408.906218 -198.868538)
		(end 409.868878 -199.267572)
		(width 0.20066)
		(layer "F.Cu")
		(net "M_E_CPU0_SB_DQS_DP<8>")
	)
	(segment
		(start 410.348684 -199.01662)
		(end 410.853382 -199.01662)
		(width 0.20066)
		(layer "F.Cu")
		(net "M_E_CPU0_SB_DQS_DP<8>")
	)
	(segment
		(start 405.112728 -198.81977)
		(end 405.35479 -198.577708)
		(width 0.20066)
		(layer "F.Cu")
		(net "M_E_CPU0_SB_DQS_DP<8>")
	)
	(segment
		(start 386.648452 -227.856542)
		(end 386.726938 -227.813362)
		(width 0.088646)
		(layer "F.Cu")
		(net "M_E_CPU0_SB_DQS_DP<8>")
	)
	(segment
		(start 407.763726 -198.570596)
		(end 408.071066 -198.570596)
		(width 0.20066)
		(layer "F.Cu")
		(net "M_E_CPU0_SB_DQS_DP<8>")
	)
	(segment
		(start 394.008356 -202.407012)
		(end 394.52423 -202.193398)
		(width 0.20066)
		(layer "F.Cu")
		(net "M_E_CPU0_SB_DQS_DP<8>")
	)
	(segment
		(start 403.496018 -199.375776)
		(end 404.8379 -198.81977)
		(width 0.20066)
		(layer "F.Cu")
		(net "M_E_CPU0_SB_DQS_DP<8>")
	)
	(segment
		(start 405.35479 -198.577708)
		(end 405.731726 -198.577708)
		(width 0.20066)
		(layer "F.Cu")
		(net "M_E_CPU0_SB_DQS_DP<8>")
	)
	(segment
		(start 388.701534 -212.780626)
		(end 388.183374 -211.530692)
		(width 0.1524)
		(layer "F.Cu")
		(net "M_E_CPU0_SB_DQS_DP<8>")
	)
	(segment
		(start 388.146544 -211.185252)
		(end 388.146544 -211.147152)
		(width 0.1524)
		(layer "F.Cu")
		(net "M_E_CPU0_SB_DQS_DP<8>")
	)
	(segment
		(start 388.640066 -206.990696)
		(end 388.64032 -206.990442)
		(width 0.20066)
		(layer "F.Cu")
		(net "M_E_CPU0_SB_DQS_DP<8>")
	)
	(segment
		(start 387.604 -227.813362)
		(end 388.102602 -227.314506)
		(width 0.088646)
		(layer "F.Cu")
		(net "M_E_CPU0_SB_DQS_DP<8>")
	)
	(segment
		(start 397.341852 -199.375776)
		(end 403.496018 -199.375776)
		(width 0.20066)
		(layer "F.Cu")
		(net "M_E_CPU0_SB_DQS_DP<8>")
	)
	(segment
		(start 386.726938 -227.813362)
		(end 387.604 -227.813362)
		(width 0.088646)
		(layer "F.Cu")
		(net "M_E_CPU0_SB_DQS_DP<8>")
	)
	(segment
		(start 415.88436 -198.839328)
		(end 415.629344 -198.584312)
		(width 0.20066)
		(layer "F.Cu")
		(net "M_E_CPU0_SB_DQS_DP<8>")
	)
	(segment
		(start 385.894834 -228.1809)
		(end 386.068316 -228.1809)
		(width 0.088646)
		(layer "F.Cu")
		(net "M_E_CPU0_SB_DQS_DP<8>")
	)
	(segment
		(start 388.183374 -211.222082)
		(end 388.146544 -211.185252)
		(width 0.1524)
		(layer "F.Cu")
		(net "M_E_CPU0_SB_DQS_DP<8>")
	)
	(segment
		(start 415.629344 -198.584312)
		(end 415.307526 -198.584312)
		(width 0.20066)
		(layer "F.Cu")
		(net "M_E_CPU0_SB_DQS_DP<8>")
	)
	(segment
		(start 394.52423 -202.193398)
		(end 397.341852 -199.375776)
		(width 0.20066)
		(layer "F.Cu")
		(net "M_E_CPU0_SB_DQS_DP<8>")
	)
	(segment
		(start 408.071066 -198.570596)
		(end 408.369008 -198.868538)
		(width 0.20066)
		(layer "F.Cu")
		(net "M_E_CPU0_SB_DQS_DP<8>")
	)
	(segment
		(start 411.356302 -199.01662)
		(end 410.853382 -199.01662)
		(width 0.20066)
		(layer "F.Cu")
		(net "M_E_CPU0_SB_DQS_DP<8>")
	)
	(segment
		(start 418.397182 -199.01662)
		(end 417.829238 -199.01662)
		(width 0.20066)
		(layer "F.Cu")
		(net "M_E_CPU0_SB_DQS_DP<8>")
	)
	(segment
		(start 412.427674 -198.842884)
		(end 412.002732 -199.267826)
		(width 0.20066)
		(layer "F.Cu")
		(net "M_E_CPU0_SB_DQS_DP<8>")
	)
	(segment
		(start 417.561014 -199.284844)
		(end 416.983418 -199.284844)
		(width 0.20066)
		(layer "F.Cu")
		(net "M_E_CPU0_SB_DQS_DP<8>")
	)
	(segment
		(start 388.89178 -213.739984)
		(end 388.701534 -212.780626)
		(width 0.1524)
		(layer "F.Cu")
		(net "M_E_CPU0_SB_DQS_DP<8>")
	)
	(segment
		(start 407.73096 -198.591678)
		(end 407.752042 -198.570596)
		(width 0.1016)
		(layer "F.Cu")
		(net "M_E_CPU0_SB_DQS_DP<8>")
	)
	(segment
		(start 415.307526 -198.584312)
		(end 415.30016 -198.591678)
		(width 0.1016)
		(layer "F.Cu")
		(net "M_E_CPU0_SB_DQS_DP<8>")
	)
	(segment
		(start 392.793474 -202.407012)
		(end 394.008356 -202.407012)
		(width 0.20066)
		(layer "F.Cu")
		(net "M_E_CPU0_SB_DQS_DP<8>")
	)
	(segment
		(start 388.64032 -206.990442)
		(end 389.363712 -205.244192)
		(width 0.20066)
		(layer "F.Cu")
		(net "M_E_CPU0_SB_DQS_DP<8>")
	)
	(segment
		(start 405.750776 -198.591678)
		(end 407.73096 -198.591678)
		(width 0.1016)
		(layer "F.Cu")
		(net "M_E_CPU0_SB_DQS_DP<8>")
	)
	(segment
		(start 388.146544 -208.905856)
		(end 388.423658 -207.513174)
		(width 0.20066)
		(layer "F.Cu")
		(net "M_E_CPU0_SB_DQS_DP<8>")
	)
	(segment
		(start 412.706058 -198.842884)
		(end 412.427674 -198.842884)
		(width 0.20066)
		(layer "F.Cu")
		(net "M_E_CPU0_SB_DQS_DP<8>")
	)
	(segment
		(start 391.782046 -202.825858)
		(end 392.793474 -202.407012)
		(width 0.20066)
		(layer "F.Cu")
		(net "M_E_CPU0_SB_DQS_DP<8>")
	)
	(arc
		(start 386.07619 -228.173026)
		(mid 386.099206 -228.169995)
		(end 386.12064 -228.161088)
		(width 0.088646)
		(layer "F.Cu")
		(net "M_E_CPU0_SB_DQS_DP<8>")
	)
	(segment
		(start 393.255754 -215.556338)
		(end 393.282678 -215.529414)
		(width 0.1524)
		(layer "F.Cu")
		(net "M_E_CPU0_SB_DQS_DP<7>")
	)
	(segment
		(start 388.40918 -232.525062)
		(end 392.80338 -228.130862)
		(width 0.1524)
		(layer "F.Cu")
		(net "M_E_CPU0_SB_DQS_DP<7>")
	)
	(segment
		(start 408.041348 -207.936338)
		(end 408.319224 -208.214214)
		(width 0.20066)
		(layer "F.Cu")
		(net "M_E_CPU0_SB_DQS_DP<7>")
	)
	(segment
		(start 411.622748 -208.617566)
		(end 411.371796 -208.366614)
		(width 0.20066)
		(layer "F.Cu")
		(net "M_E_CPU0_SB_DQS_DP<7>")
	)
	(segment
		(start 418.397182 -208.366614)
		(end 417.898072 -208.366614)
		(width 0.20066)
		(layer "F.Cu")
		(net "M_E_CPU0_SB_DQS_DP<7>")
	)
	(segment
		(start 417.630102 -208.634584)
		(end 417.200334 -208.634584)
		(width 0.20066)
		(layer "F.Cu")
		(net "M_E_CPU0_SB_DQS_DP<7>")
	)
	(segment
		(start 411.828996 -208.617566)
		(end 411.622748 -208.617566)
		(width 0.20066)
		(layer "F.Cu")
		(net "M_E_CPU0_SB_DQS_DP<7>")
	)
	(segment
		(start 392.80338 -216.06129)
		(end 393.255754 -215.608916)
		(width 0.1524)
		(layer "F.Cu")
		(net "M_E_CPU0_SB_DQS_DP<7>")
	)
	(segment
		(start 413.275526 -207.921352)
		(end 412.970726 -207.921352)
		(width 0.20066)
		(layer "F.Cu")
		(net "M_E_CPU0_SB_DQS_DP<7>")
	)
	(segment
		(start 415.300922 -207.941672)
		(end 413.321754 -207.941672)
		(width 0.1016)
		(layer "F.Cu")
		(net "M_E_CPU0_SB_DQS_DP<7>")
	)
	(segment
		(start 407.466038 -207.941672)
		(end 407.754328 -207.941672)
		(width 0.1016)
		(layer "F.Cu")
		(net "M_E_CPU0_SB_DQS_DP<7>")
	)
	(segment
		(start 405.273002 -208.118964)
		(end 405.460962 -207.931004)
		(width 0.20066)
		(layer "F.Cu")
		(net "M_E_CPU0_SB_DQS_DP<7>")
	)
	(segment
		(start 393.255754 -215.608916)
		(end 393.255754 -215.556338)
		(width 0.1524)
		(layer "F.Cu")
		(net "M_E_CPU0_SB_DQS_DP<7>")
	)
	(segment
		(start 393.282678 -215.529414)
		(end 400.284188 -208.527904)
		(width 0.20066)
		(layer "F.Cu")
		(net "M_E_CPU0_SB_DQS_DP<7>")
	)
	(segment
		(start 410.491686 -208.366614)
		(end 410.853382 -208.366614)
		(width 0.20066)
		(layer "F.Cu")
		(net "M_E_CPU0_SB_DQS_DP<7>")
	)
	(segment
		(start 407.759662 -207.936338)
		(end 407.763726 -207.936338)
		(width 0.1016)
		(layer "F.Cu")
		(net "M_E_CPU0_SB_DQS_DP<7>")
	)
	(segment
		(start 400.284188 -208.527904)
		(end 401.27174 -208.118964)
		(width 0.20066)
		(layer "F.Cu")
		(net "M_E_CPU0_SB_DQS_DP<7>")
	)
	(segment
		(start 411.371796 -208.366614)
		(end 410.853382 -208.366614)
		(width 0.20066)
		(layer "F.Cu")
		(net "M_E_CPU0_SB_DQS_DP<7>")
	)
	(segment
		(start 412.721298 -208.17078)
		(end 412.275782 -208.17078)
		(width 0.20066)
		(layer "F.Cu")
		(net "M_E_CPU0_SB_DQS_DP<7>")
	)
	(segment
		(start 407.754328 -207.941672)
		(end 407.759662 -207.936338)
		(width 0.1016)
		(layer "F.Cu")
		(net "M_E_CPU0_SB_DQS_DP<7>")
	)
	(segment
		(start 417.898072 -208.366614)
		(end 417.630102 -208.634584)
		(width 0.20066)
		(layer "F.Cu")
		(net "M_E_CPU0_SB_DQS_DP<7>")
	)
	(segment
		(start 386.72389 -232.71988)
		(end 386.725668 -232.719372)
		(width 0.088646)
		(layer "F.Cu")
		(net "M_E_CPU0_SB_DQS_DP<7>")
	)
	(segment
		(start 412.970726 -207.921352)
		(end 412.721298 -208.17078)
		(width 0.20066)
		(layer "F.Cu")
		(net "M_E_CPU0_SB_DQS_DP<7>")
	)
	(segment
		(start 388.393686 -232.585514)
		(end 388.393686 -232.540556)
		(width 0.088646)
		(layer "F.Cu")
		(net "M_E_CPU0_SB_DQS_DP<7>")
	)
	(segment
		(start 408.506676 -208.214214)
		(end 409.948888 -208.65211)
		(width 0.20066)
		(layer "F.Cu")
		(net "M_E_CPU0_SB_DQS_DP<7>")
	)
	(segment
		(start 409.948888 -208.65211)
		(end 410.20619 -208.65211)
		(width 0.20066)
		(layer "F.Cu")
		(net "M_E_CPU0_SB_DQS_DP<7>")
	)
	(segment
		(start 413.296354 -207.921352)
		(end 413.275526 -207.921352)
		(width 0.101854)
		(layer "F.Cu")
		(net "M_E_CPU0_SB_DQS_DP<7>")
	)
	(segment
		(start 388.283704 -232.695496)
		(end 388.393686 -232.585514)
		(width 0.088646)
		(layer "F.Cu")
		(net "M_E_CPU0_SB_DQS_DP<7>")
	)
	(segment
		(start 412.275782 -208.17078)
		(end 411.828996 -208.617566)
		(width 0.20066)
		(layer "F.Cu")
		(net "M_E_CPU0_SB_DQS_DP<7>")
	)
	(segment
		(start 405.742394 -207.941672)
		(end 405.98979 -207.941672)
		(width 0.101854)
		(layer "F.Cu")
		(net "M_E_CPU0_SB_DQS_DP<7>")
	)
	(segment
		(start 401.27174 -208.118964)
		(end 405.273002 -208.118964)
		(width 0.20066)
		(layer "F.Cu")
		(net "M_E_CPU0_SB_DQS_DP<7>")
	)
	(segment
		(start 416.07232 -208.189068)
		(end 415.81832 -207.935068)
		(width 0.20066)
		(layer "F.Cu")
		(net "M_E_CPU0_SB_DQS_DP<7>")
	)
	(segment
		(start 407.763726 -207.936338)
		(end 408.041348 -207.936338)
		(width 0.20066)
		(layer "F.Cu")
		(net "M_E_CPU0_SB_DQS_DP<7>")
	)
	(segment
		(start 417.200334 -208.634584)
		(end 416.754818 -208.189068)
		(width 0.20066)
		(layer "F.Cu")
		(net "M_E_CPU0_SB_DQS_DP<7>")
	)
	(segment
		(start 405.731726 -207.931004)
		(end 405.742394 -207.941672)
		(width 0.101854)
		(layer "F.Cu")
		(net "M_E_CPU0_SB_DQS_DP<7>")
	)
	(segment
		(start 407.065988 -207.941672)
		(end 407.466038 -207.941672)
		(width 0.101854)
		(layer "F.Cu")
		(net "M_E_CPU0_SB_DQS_DP<7>")
	)
	(segment
		(start 385.894834 -233.064304)
		(end 386.431536 -232.856278)
		(width 0.088646)
		(layer "F.Cu")
		(net "M_E_CPU0_SB_DQS_DP<7>")
	)
	(segment
		(start 405.460962 -207.931004)
		(end 405.731726 -207.931004)
		(width 0.20066)
		(layer "F.Cu")
		(net "M_E_CPU0_SB_DQS_DP<7>")
	)
	(segment
		(start 415.307526 -207.935068)
		(end 415.300922 -207.941672)
		(width 0.1016)
		(layer "F.Cu")
		(net "M_E_CPU0_SB_DQS_DP<7>")
	)
	(segment
		(start 415.81832 -207.935068)
		(end 415.307526 -207.935068)
		(width 0.20066)
		(layer "F.Cu")
		(net "M_E_CPU0_SB_DQS_DP<7>")
	)
	(segment
		(start 386.869432 -232.695496)
		(end 388.283704 -232.695496)
		(width 0.088646)
		(layer "F.Cu")
		(net "M_E_CPU0_SB_DQS_DP<7>")
	)
	(segment
		(start 405.98979 -207.941672)
		(end 407.065988 -207.941672)
		(width 0.1016)
		(layer "F.Cu")
		(net "M_E_CPU0_SB_DQS_DP<7>")
	)
	(segment
		(start 416.754818 -208.189068)
		(end 416.07232 -208.189068)
		(width 0.20066)
		(layer "F.Cu")
		(net "M_E_CPU0_SB_DQS_DP<7>")
	)
	(segment
		(start 410.20619 -208.65211)
		(end 410.491686 -208.366614)
		(width 0.20066)
		(layer "F.Cu")
		(net "M_E_CPU0_SB_DQS_DP<7>")
	)
	(segment
		(start 408.319224 -208.214214)
		(end 408.506676 -208.214214)
		(width 0.20066)
		(layer "F.Cu")
		(net "M_E_CPU0_SB_DQS_DP<7>")
	)
	(segment
		(start 413.321754 -207.941672)
		(end 413.301434 -207.921352)
		(width 0.1016)
		(layer "F.Cu")
		(net "M_E_CPU0_SB_DQS_DP<7>")
	)
	(segment
		(start 413.301434 -207.921352)
		(end 413.296354 -207.921352)
		(width 0.1016)
		(layer "F.Cu")
		(net "M_E_CPU0_SB_DQS_DP<7>")
	)
	(segment
		(start 388.393686 -232.540556)
		(end 388.40918 -232.525062)
		(width 0.088646)
		(layer "F.Cu")
		(net "M_E_CPU0_SB_DQS_DP<7>")
	)
	(segment
		(start 392.80338 -228.130862)
		(end 392.80338 -216.06129)
		(width 0.1524)
		(layer "F.Cu")
		(net "M_E_CPU0_SB_DQS_DP<7>")
	)
	(arc
		(start 386.431536 -232.856278)
		(mid 386.494806 -232.828862)
		(end 386.555742 -232.796588)
		(width 0.088646)
		(layer "F.Cu")
		(net "M_E_CPU0_SB_DQS_DP<7>")
	)
	(arc
		(start 386.555742 -232.796588)
		(mid 386.63793 -232.754099)
		(end 386.72389 -232.71988)
		(width 0.088646)
		(layer "F.Cu")
		(net "M_E_CPU0_SB_DQS_DP<7>")
	)
	(arc
		(start 386.725668 -232.719372)
		(mid 386.796565 -232.701505)
		(end 386.869432 -232.695496)
		(width 0.088646)
		(layer "F.Cu")
		(net "M_E_CPU0_SB_DQS_DP<7>")
	)
	(segment
		(start 404.841456 -217.27541)
		(end 405.731726 -217.27541)
		(width 0.20066)
		(layer "F.Cu")
		(net "M_E_CPU0_SB_DQS_DP<6>")
	)
	(segment
		(start 412.964376 -217.284554)
		(end 412.706058 -217.542872)
		(width 0.20066)
		(layer "F.Cu")
		(net "M_E_CPU0_SB_DQS_DP<6>")
	)
	(segment
		(start 407.629868 -217.291666)
		(end 407.763726 -217.291666)
		(width 0.101854)
		(layer "F.Cu")
		(net "M_E_CPU0_SB_DQS_DP<6>")
	)
	(segment
		(start 416.983418 -217.984832)
		(end 416.537902 -217.539316)
		(width 0.20066)
		(layer "F.Cu")
		(net "M_E_CPU0_SB_DQS_DP<6>")
	)
	(segment
		(start 386.769356 -237.589568)
		(end 387.567678 -237.589568)
		(width 0.088646)
		(layer "F.Cu")
		(net "M_E_CPU0_SB_DQS_DP<6>")
	)
	(segment
		(start 410.348684 -217.716608)
		(end 410.853382 -217.716608)
		(width 0.20066)
		(layer "F.Cu")
		(net "M_E_CPU0_SB_DQS_DP<6>")
	)
	(segment
		(start 415.30016 -217.291666)
		(end 413.287464 -217.291666)
		(width 0.1016)
		(layer "F.Cu")
		(net "M_E_CPU0_SB_DQS_DP<6>")
	)
	(segment
		(start 397.189706 -227.386896)
		(end 397.556228 -227.020374)
		(width 0.1524)
		(layer "F.Cu")
		(net "M_E_CPU0_SB_DQS_DP<6>")
	)
	(segment
		(start 385.894834 -237.947454)
		(end 385.895342 -237.94593)
		(width 0.088646)
		(layer "F.Cu")
		(net "M_E_CPU0_SB_DQS_DP<6>")
	)
	(segment
		(start 389.040116 -236.660436)
		(end 389.071866 -236.628686)
		(width 0.088646)
		(layer "F.Cu")
		(net "M_E_CPU0_SB_DQS_DP<6>")
	)
	(segment
		(start 417.829238 -217.716608)
		(end 417.561014 -217.984832)
		(width 0.20066)
		(layer "F.Cu")
		(net "M_E_CPU0_SB_DQS_DP<6>")
	)
	(segment
		(start 409.868878 -217.96756)
		(end 410.097732 -217.96756)
		(width 0.20066)
		(layer "F.Cu")
		(net "M_E_CPU0_SB_DQS_DP<6>")
	)
	(segment
		(start 413.280352 -217.284554)
		(end 413.275526 -217.284554)
		(width 0.101854)
		(layer "F.Cu")
		(net "M_E_CPU0_SB_DQS_DP<6>")
	)
	(segment
		(start 411.360366 -217.716608)
		(end 410.853382 -217.716608)
		(width 0.20066)
		(layer "F.Cu")
		(net "M_E_CPU0_SB_DQS_DP<6>")
	)
	(segment
		(start 397.583152 -226.941634)
		(end 400.5961 -223.928686)
		(width 0.20066)
		(layer "F.Cu")
		(net "M_E_CPU0_SB_DQS_DP<6>")
	)
	(segment
		(start 389.071866 -236.628686)
		(end 389.093964 -236.628686)
		(width 0.088646)
		(layer "F.Cu")
		(net "M_E_CPU0_SB_DQS_DP<6>")
	)
	(segment
		(start 397.556228 -226.968558)
		(end 397.583152 -226.941634)
		(width 0.1524)
		(layer "F.Cu")
		(net "M_E_CPU0_SB_DQS_DP<6>")
	)
	(segment
		(start 412.169356 -217.80119)
		(end 411.767274 -217.967814)
		(width 0.20066)
		(layer "F.Cu")
		(net "M_E_CPU0_SB_DQS_DP<6>")
	)
	(segment
		(start 405.752808 -217.291666)
		(end 407.629868 -217.291666)
		(width 0.1016)
		(layer "F.Cu")
		(net "M_E_CPU0_SB_DQS_DP<6>")
	)
	(segment
		(start 400.5961 -223.928686)
		(end 400.5961 -221.295722)
		(width 0.20066)
		(layer "F.Cu")
		(net "M_E_CPU0_SB_DQS_DP<6>")
	)
	(segment
		(start 411.767274 -217.967814)
		(end 411.611572 -217.967814)
		(width 0.20066)
		(layer "F.Cu")
		(net "M_E_CPU0_SB_DQS_DP<6>")
	)
	(segment
		(start 397.556228 -227.020374)
		(end 397.556228 -226.968558)
		(width 0.1524)
		(layer "F.Cu")
		(net "M_E_CPU0_SB_DQS_DP<6>")
	)
	(segment
		(start 413.275526 -217.284554)
		(end 412.964376 -217.284554)
		(width 0.20066)
		(layer "F.Cu")
		(net "M_E_CPU0_SB_DQS_DP<6>")
	)
	(segment
		(start 410.097732 -217.96756)
		(end 410.348684 -217.716608)
		(width 0.20066)
		(layer "F.Cu")
		(net "M_E_CPU0_SB_DQS_DP<6>")
	)
	(segment
		(start 408.906218 -217.568526)
		(end 409.868878 -217.96756)
		(width 0.20066)
		(layer "F.Cu")
		(net "M_E_CPU0_SB_DQS_DP<6>")
	)
	(segment
		(start 389.093964 -236.628686)
		(end 389.893556 -236.628686)
		(width 0.1524)
		(layer "F.Cu")
		(net "M_E_CPU0_SB_DQS_DP<6>")
	)
	(segment
		(start 407.763726 -217.291666)
		(end 407.774648 -217.280744)
		(width 0.20066)
		(layer "F.Cu")
		(net "M_E_CPU0_SB_DQS_DP<6>")
	)
	(segment
		(start 413.287464 -217.291666)
		(end 413.280352 -217.284554)
		(width 0.1016)
		(layer "F.Cu")
		(net "M_E_CPU0_SB_DQS_DP<6>")
	)
	(segment
		(start 418.397182 -217.716608)
		(end 417.829238 -217.716608)
		(width 0.20066)
		(layer "F.Cu")
		(net "M_E_CPU0_SB_DQS_DP<6>")
	)
	(segment
		(start 412.427674 -217.542872)
		(end 412.169356 -217.80119)
		(width 0.20066)
		(layer "F.Cu")
		(net "M_E_CPU0_SB_DQS_DP<6>")
	)
	(segment
		(start 404.001986 -217.684096)
		(end 404.39467 -217.291412)
		(width 0.20066)
		(layer "F.Cu")
		(net "M_E_CPU0_SB_DQS_DP<6>")
	)
	(segment
		(start 408.312874 -217.280744)
		(end 408.600656 -217.568526)
		(width 0.20066)
		(layer "F.Cu")
		(net "M_E_CPU0_SB_DQS_DP<6>")
	)
	(segment
		(start 389.893556 -236.628686)
		(end 396.71498 -229.807262)
		(width 0.1524)
		(layer "F.Cu")
		(net "M_E_CPU0_SB_DQS_DP<6>")
	)
	(segment
		(start 411.611572 -217.967814)
		(end 411.360366 -217.716608)
		(width 0.20066)
		(layer "F.Cu")
		(net "M_E_CPU0_SB_DQS_DP<6>")
	)
	(segment
		(start 416.537902 -217.539316)
		(end 415.88436 -217.539316)
		(width 0.20066)
		(layer "F.Cu")
		(net "M_E_CPU0_SB_DQS_DP<6>")
	)
	(segment
		(start 407.774648 -217.280744)
		(end 408.312874 -217.280744)
		(width 0.20066)
		(layer "F.Cu")
		(net "M_E_CPU0_SB_DQS_DP<6>")
	)
	(segment
		(start 415.629344 -217.2843)
		(end 415.307526 -217.2843)
		(width 0.20066)
		(layer "F.Cu")
		(net "M_E_CPU0_SB_DQS_DP<6>")
	)
	(segment
		(start 396.71498 -228.534214)
		(end 397.189706 -227.386896)
		(width 0.1524)
		(layer "F.Cu")
		(net "M_E_CPU0_SB_DQS_DP<6>")
	)
	(segment
		(start 388.49681 -236.660436)
		(end 389.040116 -236.660436)
		(width 0.088646)
		(layer "F.Cu")
		(net "M_E_CPU0_SB_DQS_DP<6>")
	)
	(segment
		(start 385.895342 -237.94593)
		(end 386.769356 -237.589568)
		(width 0.088646)
		(layer "F.Cu")
		(net "M_E_CPU0_SB_DQS_DP<6>")
	)
	(segment
		(start 404.39467 -217.291412)
		(end 404.825454 -217.291412)
		(width 0.20066)
		(layer "F.Cu")
		(net "M_E_CPU0_SB_DQS_DP<6>")
	)
	(segment
		(start 396.71498 -229.807262)
		(end 396.71498 -228.534214)
		(width 0.1524)
		(layer "F.Cu")
		(net "M_E_CPU0_SB_DQS_DP<6>")
	)
	(segment
		(start 412.706058 -217.542872)
		(end 412.427674 -217.542872)
		(width 0.20066)
		(layer "F.Cu")
		(net "M_E_CPU0_SB_DQS_DP<6>")
	)
	(segment
		(start 405.736552 -217.27541)
		(end 405.752808 -217.291666)
		(width 0.1016)
		(layer "F.Cu")
		(net "M_E_CPU0_SB_DQS_DP<6>")
	)
	(segment
		(start 387.567678 -237.589568)
		(end 388.49681 -236.660436)
		(width 0.088646)
		(layer "F.Cu")
		(net "M_E_CPU0_SB_DQS_DP<6>")
	)
	(segment
		(start 415.88436 -217.539316)
		(end 415.629344 -217.2843)
		(width 0.20066)
		(layer "F.Cu")
		(net "M_E_CPU0_SB_DQS_DP<6>")
	)
	(segment
		(start 405.731726 -217.27541)
		(end 405.736552 -217.27541)
		(width 0.101854)
		(layer "F.Cu")
		(net "M_E_CPU0_SB_DQS_DP<6>")
	)
	(segment
		(start 404.825454 -217.291412)
		(end 404.841456 -217.27541)
		(width 0.20066)
		(layer "F.Cu")
		(net "M_E_CPU0_SB_DQS_DP<6>")
	)
	(segment
		(start 417.561014 -217.984832)
		(end 416.983418 -217.984832)
		(width 0.20066)
		(layer "F.Cu")
		(net "M_E_CPU0_SB_DQS_DP<6>")
	)
	(segment
		(start 415.307526 -217.2843)
		(end 415.30016 -217.291666)
		(width 0.1016)
		(layer "F.Cu")
		(net "M_E_CPU0_SB_DQS_DP<6>")
	)
	(segment
		(start 404.001986 -217.889836)
		(end 404.001986 -217.684096)
		(width 0.20066)
		(layer "F.Cu")
		(net "M_E_CPU0_SB_DQS_DP<6>")
	)
	(segment
		(start 408.600656 -217.568526)
		(end 408.906218 -217.568526)
		(width 0.20066)
		(layer "F.Cu")
		(net "M_E_CPU0_SB_DQS_DP<6>")
	)
	(segment
		(start 400.5961 -221.295722)
		(end 404.001986 -217.889836)
		(width 0.20066)
		(layer "F.Cu")
		(net "M_E_CPU0_SB_DQS_DP<6>")
	)
	(segment
		(start 412.002732 -227.317808)
		(end 411.697932 -227.317808)
		(width 0.20066)
		(layer "F.Cu")
		(net "M_E_CPU0_SB_DQS_DP<5>")
	)
	(segment
		(start 415.30016 -226.64166)
		(end 413.287464 -226.64166)
		(width 0.1016)
		(layer "F.Cu")
		(net "M_E_CPU0_SB_DQS_DP<5>")
	)
	(segment
		(start 382.605534 -235.506006)
		(end 382.605534 -234.970066)
		(width 0.20066)
		(layer "F.Cu")
		(net "M_E_CPU0_SB_DQS_DP<5>")
	)
	(segment
		(start 411.697932 -227.317808)
		(end 411.446726 -227.066602)
		(width 0.20066)
		(layer "F.Cu")
		(net "M_E_CPU0_SB_DQS_DP<5>")
	)
	(segment
		(start 411.446726 -227.066602)
		(end 410.853382 -227.066602)
		(width 0.20066)
		(layer "F.Cu")
		(net "M_E_CPU0_SB_DQS_DP<5>")
	)
	(segment
		(start 412.964376 -226.634548)
		(end 412.706058 -226.892866)
		(width 0.20066)
		(layer "F.Cu")
		(net "M_E_CPU0_SB_DQS_DP<5>")
	)
	(segment
		(start 412.706058 -226.892866)
		(end 412.427674 -226.892866)
		(width 0.20066)
		(layer "F.Cu")
		(net "M_E_CPU0_SB_DQS_DP<5>")
	)
	(segment
		(start 412.427674 -226.892866)
		(end 412.002732 -227.317808)
		(width 0.20066)
		(layer "F.Cu")
		(net "M_E_CPU0_SB_DQS_DP<5>")
	)
	(segment
		(start 410.853382 -227.066602)
		(end 409.723082 -227.066602)
		(width 0.20066)
		(layer "F.Cu")
		(net "M_E_CPU0_SB_DQS_DP<5>")
	)
	(segment
		(start 415.88436 -226.88931)
		(end 415.629344 -226.634294)
		(width 0.20066)
		(layer "F.Cu")
		(net "M_E_CPU0_SB_DQS_DP<5>")
	)
	(segment
		(start 415.307526 -226.634294)
		(end 415.30016 -226.64166)
		(width 0.1016)
		(layer "F.Cu")
		(net "M_E_CPU0_SB_DQS_DP<5>")
	)
	(segment
		(start 413.280352 -226.634548)
		(end 413.275526 -226.634548)
		(width 0.101854)
		(layer "F.Cu")
		(net "M_E_CPU0_SB_DQS_DP<5>")
	)
	(segment
		(start 413.275526 -226.634548)
		(end 412.964376 -226.634548)
		(width 0.20066)
		(layer "F.Cu")
		(net "M_E_CPU0_SB_DQS_DP<5>")
	)
	(segment
		(start 415.629344 -226.634294)
		(end 415.307526 -226.634294)
		(width 0.20066)
		(layer "F.Cu")
		(net "M_E_CPU0_SB_DQS_DP<5>")
	)
	(segment
		(start 416.537902 -226.88931)
		(end 415.88436 -226.88931)
		(width 0.20066)
		(layer "F.Cu")
		(net "M_E_CPU0_SB_DQS_DP<5>")
	)
	(segment
		(start 416.983418 -227.334826)
		(end 416.537902 -226.88931)
		(width 0.20066)
		(layer "F.Cu")
		(net "M_E_CPU0_SB_DQS_DP<5>")
	)
	(segment
		(start 417.561014 -227.334826)
		(end 416.983418 -227.334826)
		(width 0.20066)
		(layer "F.Cu")
		(net "M_E_CPU0_SB_DQS_DP<5>")
	)
	(segment
		(start 418.397182 -227.066602)
		(end 417.829238 -227.066602)
		(width 0.20066)
		(layer "F.Cu")
		(net "M_E_CPU0_SB_DQS_DP<5>")
	)
	(segment
		(start 413.287464 -226.64166)
		(end 413.280352 -226.634548)
		(width 0.1016)
		(layer "F.Cu")
		(net "M_E_CPU0_SB_DQS_DP<5>")
	)
	(segment
		(start 417.829238 -227.066602)
		(end 417.561014 -227.334826)
		(width 0.20066)
		(layer "F.Cu")
		(net "M_E_CPU0_SB_DQS_DP<5>")
	)
	(segment
		(start 384.076194 -234.532678)
		(end 383.960878 -234.532678)
		(width 0.088646)
		(layer "In2.Cu")
		(net "M_E_CPU0_SB_DQS_DP<5>")
	)
	(segment
		(start 384.091942 -234.528614)
		(end 384.076194 -234.532678)
		(width 0.088646)
		(layer "In2.Cu")
		(net "M_E_CPU0_SB_DQS_DP<5>")
	)
	(segment
		(start 384.172714 -234.49788)
		(end 384.111246 -234.523534)
		(width 0.088646)
		(layer "In2.Cu")
		(net "M_E_CPU0_SB_DQS_DP<5>")
	)
	(segment
		(start 397.635222 -233.531664)
		(end 396.838678 -233.861864)
		(width 0.18288)
		(layer "In2.Cu")
		(net "M_E_CPU0_SB_DQS_DP<5>")
	)
	(segment
		(start 386.350764 -234.346496)
		(end 386.29082 -234.40644)
		(width 0.088646)
		(layer "In2.Cu")
		(net "M_E_CPU0_SB_DQS_DP<5>")
	)
	(segment
		(start 408.037284 -227.510086)
		(end 407.918666 -227.46081)
		(width 0.18288)
		(layer "In2.Cu")
		(net "M_E_CPU0_SB_DQS_DP<5>")
	)
	(segment
		(start 405.170894 -226.897692)
		(end 404.738586 -226.897692)
		(width 0.18288)
		(layer "In2.Cu")
		(net "M_E_CPU0_SB_DQS_DP<5>")
	)
	(segment
		(start 387.338062 -233.861864)
		(end 386.85343 -234.346496)
		(width 0.18288)
		(layer "In2.Cu")
		(net "M_E_CPU0_SB_DQS_DP<5>")
	)
	(segment
		(start 386.29082 -234.40644)
		(end 385.4196 -234.40644)
		(width 0.088646)
		(layer "In2.Cu")
		(net "M_E_CPU0_SB_DQS_DP<5>")
	)
	(segment
		(start 409.723082 -227.066602)
		(end 409.467812 -227.321872)
		(width 0.18288)
		(layer "In2.Cu")
		(net "M_E_CPU0_SB_DQS_DP<5>")
	)
	(segment
		(start 409.467812 -227.321872)
		(end 409.283408 -227.321872)
		(width 0.18288)
		(layer "In2.Cu")
		(net "M_E_CPU0_SB_DQS_DP<5>")
	)
	(segment
		(start 383.358136 -234.645708)
		(end 383.349246 -234.650788)
		(width 0.088646)
		(layer "In2.Cu")
		(net "M_E_CPU0_SB_DQS_DP<5>")
	)
	(segment
		(start 404.738586 -226.897692)
		(end 403.937724 -227.229162)
		(width 0.18288)
		(layer "In2.Cu")
		(net "M_E_CPU0_SB_DQS_DP<5>")
	)
	(segment
		(start 383.826512 -234.493308)
		(end 383.625598 -234.50423)
		(width 0.088646)
		(layer "In2.Cu")
		(net "M_E_CPU0_SB_DQS_DP<5>")
	)
	(segment
		(start 386.85343 -234.346496)
		(end 386.350764 -234.346496)
		(width 0.18288)
		(layer "In2.Cu")
		(net "M_E_CPU0_SB_DQS_DP<5>")
	)
	(segment
		(start 407.918666 -227.46081)
		(end 407.33853 -226.880928)
		(width 0.18288)
		(layer "In2.Cu")
		(net "M_E_CPU0_SB_DQS_DP<5>")
	)
	(segment
		(start 383.625598 -234.50423)
		(end 383.517648 -234.549188)
		(width 0.088646)
		(layer "In2.Cu")
		(net "M_E_CPU0_SB_DQS_DP<5>")
	)
	(segment
		(start 383.118106 -234.970066)
		(end 382.605534 -234.970066)
		(width 0.088646)
		(layer "In2.Cu")
		(net "M_E_CPU0_SB_DQS_DP<5>")
	)
	(segment
		(start 384.09372 -234.527852)
		(end 384.093466 -234.528106)
		(width 0.088646)
		(layer "In2.Cu")
		(net "M_E_CPU0_SB_DQS_DP<5>")
	)
	(segment
		(start 384.217164 -234.471972)
		(end 384.172714 -234.49788)
		(width 0.088646)
		(layer "In2.Cu")
		(net "M_E_CPU0_SB_DQS_DP<5>")
	)
	(segment
		(start 383.517648 -234.549188)
		(end 383.426716 -234.614974)
		(width 0.088646)
		(layer "In2.Cu")
		(net "M_E_CPU0_SB_DQS_DP<5>")
	)
	(segment
		(start 383.175256 -234.912916)
		(end 383.118106 -234.970066)
		(width 0.088646)
		(layer "In2.Cu")
		(net "M_E_CPU0_SB_DQS_DP<5>")
	)
	(segment
		(start 384.111246 -234.523534)
		(end 384.09372 -234.527852)
		(width 0.088646)
		(layer "In2.Cu")
		(net "M_E_CPU0_SB_DQS_DP<5>")
	)
	(segment
		(start 409.283408 -227.321872)
		(end 408.33421 -227.510086)
		(width 0.18288)
		(layer "In2.Cu")
		(net "M_E_CPU0_SB_DQS_DP<5>")
	)
	(segment
		(start 405.864568 -226.639628)
		(end 405.428958 -226.639628)
		(width 0.18288)
		(layer "In2.Cu")
		(net "M_E_CPU0_SB_DQS_DP<5>")
	)
	(segment
		(start 408.33421 -227.510086)
		(end 408.037284 -227.510086)
		(width 0.18288)
		(layer "In2.Cu")
		(net "M_E_CPU0_SB_DQS_DP<5>")
	)
	(segment
		(start 407.33853 -226.880928)
		(end 406.105868 -226.880928)
		(width 0.18288)
		(layer "In2.Cu")
		(net "M_E_CPU0_SB_DQS_DP<5>")
	)
	(segment
		(start 396.838678 -233.861864)
		(end 387.338062 -233.861864)
		(width 0.18288)
		(layer "In2.Cu")
		(net "M_E_CPU0_SB_DQS_DP<5>")
	)
	(segment
		(start 406.105868 -226.880928)
		(end 405.864568 -226.639628)
		(width 0.18288)
		(layer "In2.Cu")
		(net "M_E_CPU0_SB_DQS_DP<5>")
	)
	(segment
		(start 384.093466 -234.528106)
		(end 384.091942 -234.528614)
		(width 0.088646)
		(layer "In2.Cu")
		(net "M_E_CPU0_SB_DQS_DP<5>")
	)
	(segment
		(start 383.960878 -234.532678)
		(end 383.826512 -234.493308)
		(width 0.088646)
		(layer "In2.Cu")
		(net "M_E_CPU0_SB_DQS_DP<5>")
	)
	(segment
		(start 403.937724 -227.229162)
		(end 397.635222 -233.531664)
		(width 0.18288)
		(layer "In2.Cu")
		(net "M_E_CPU0_SB_DQS_DP<5>")
	)
	(segment
		(start 405.428958 -226.639628)
		(end 405.170894 -226.897692)
		(width 0.18288)
		(layer "In2.Cu")
		(net "M_E_CPU0_SB_DQS_DP<5>")
	)
	(arc
		(start 384.767836 -234.480608)
		(mid 384.493637 -234.404773)
		(end 384.217164 -234.471972)
		(width 0.088646)
		(layer "In2.Cu")
		(net "M_E_CPU0_SB_DQS_DP<5>")
	)
	(arc
		(start 383.349246 -234.650788)
		(mid 383.233437 -234.762717)
		(end 383.175256 -234.912916)
		(width 0.088646)
		(layer "In2.Cu")
		(net "M_E_CPU0_SB_DQS_DP<5>")
	)
	(arc
		(start 383.426716 -234.614974)
		(mid 383.391655 -234.628619)
		(end 383.358136 -234.645708)
		(width 0.088646)
		(layer "In2.Cu")
		(net "M_E_CPU0_SB_DQS_DP<5>")
	)
	(arc
		(start 385.142232 -234.480608)
		(mid 384.955034 -234.530751)
		(end 384.767836 -234.480608)
		(width 0.088646)
		(layer "In2.Cu")
		(net "M_E_CPU0_SB_DQS_DP<5>")
	)
	(arc
		(start 385.4196 -234.40644)
		(mid 385.276047 -234.425309)
		(end 385.142232 -234.480608)
		(width 0.088646)
		(layer "In2.Cu")
		(net "M_E_CPU0_SB_DQS_DP<5>")
	)
	(segment
		(start 387.68274 -242.31092)
		(end 387.82752 -242.31092)
		(width 0.088646)
		(layer "F.Cu")
		(net "M_E_CPU0_SB_DQS_DP<4>")
	)
	(segment
		(start 410.097732 -236.667548)
		(end 410.348684 -236.416596)
		(width 0.20066)
		(layer "F.Cu")
		(net "M_E_CPU0_SB_DQS_DP<4>")
	)
	(segment
		(start 408.220926 -235.991654)
		(end 408.32278 -235.991654)
		(width 0.20066)
		(layer "F.Cu")
		(net "M_E_CPU0_SB_DQS_DP<4>")
	)
	(segment
		(start 412.85033 -235.991654)
		(end 412.738824 -235.991654)
		(width 0.20066)
		(layer "F.Cu")
		(net "M_E_CPU0_SB_DQS_DP<4>")
	)
	(segment
		(start 415.705544 -235.984288)
		(end 415.698178 -235.991654)
		(width 0.101854)
		(layer "F.Cu")
		(net "M_E_CPU0_SB_DQS_DP<4>")
	)
	(segment
		(start 412.738824 -235.991654)
		(end 412.486348 -236.24413)
		(width 0.20066)
		(layer "F.Cu")
		(net "M_E_CPU0_SB_DQS_DP<4>")
	)
	(segment
		(start 408.59964 -236.268514)
		(end 408.906472 -236.268514)
		(width 0.20066)
		(layer "F.Cu")
		(net "M_E_CPU0_SB_DQS_DP<4>")
	)
	(segment
		(start 412.486348 -236.24413)
		(end 412.103824 -236.24413)
		(width 0.20066)
		(layer "F.Cu")
		(net "M_E_CPU0_SB_DQS_DP<4>")
	)
	(segment
		(start 410.348684 -236.416596)
		(end 410.853382 -236.416596)
		(width 0.20066)
		(layer "F.Cu")
		(net "M_E_CPU0_SB_DQS_DP<4>")
	)
	(segment
		(start 408.32278 -235.991654)
		(end 408.59964 -236.268514)
		(width 0.20066)
		(layer "F.Cu")
		(net "M_E_CPU0_SB_DQS_DP<4>")
	)
	(segment
		(start 407.735278 -235.991654)
		(end 408.220926 -235.991654)
		(width 0.101854)
		(layer "F.Cu")
		(net "M_E_CPU0_SB_DQS_DP<4>")
	)
	(segment
		(start 409.868878 -236.667548)
		(end 410.097732 -236.667548)
		(width 0.20066)
		(layer "F.Cu")
		(net "M_E_CPU0_SB_DQS_DP<4>")
	)
	(segment
		(start 415.698178 -235.991654)
		(end 415.30016 -235.991654)
		(width 0.101854)
		(layer "F.Cu")
		(net "M_E_CPU0_SB_DQS_DP<4>")
	)
	(segment
		(start 418.397182 -236.416596)
		(end 417.829238 -236.416596)
		(width 0.20066)
		(layer "F.Cu")
		(net "M_E_CPU0_SB_DQS_DP<4>")
	)
	(segment
		(start 413.287464 -235.991654)
		(end 412.85033 -235.991654)
		(width 0.101854)
		(layer "F.Cu")
		(net "M_E_CPU0_SB_DQS_DP<4>")
	)
	(segment
		(start 416.808158 -236.239304)
		(end 416.138868 -236.239304)
		(width 0.20066)
		(layer "F.Cu")
		(net "M_E_CPU0_SB_DQS_DP<4>")
	)
	(segment
		(start 389.827516 -240.57229)
		(end 389.859266 -240.54054)
		(width 0.088646)
		(layer "F.Cu")
		(net "M_E_CPU0_SB_DQS_DP<4>")
	)
	(segment
		(start 391.570464 -240.54054)
		(end 395.262862 -236.848142)
		(width 0.1524)
		(layer "F.Cu")
		(net "M_E_CPU0_SB_DQS_DP<4>")
	)
	(segment
		(start 417.829238 -236.416596)
		(end 417.574222 -236.671612)
		(width 0.20066)
		(layer "F.Cu")
		(net "M_E_CPU0_SB_DQS_DP<4>")
	)
	(segment
		(start 416.138868 -236.239304)
		(end 415.883852 -235.984288)
		(width 0.20066)
		(layer "F.Cu")
		(net "M_E_CPU0_SB_DQS_DP<4>")
	)
	(segment
		(start 387.82752 -242.31092)
		(end 389.56615 -240.57229)
		(width 0.088646)
		(layer "F.Cu")
		(net "M_E_CPU0_SB_DQS_DP<4>")
	)
	(segment
		(start 386.477764 -242.60937)
		(end 386.995162 -242.310666)
		(width 0.088646)
		(layer "F.Cu")
		(net "M_E_CPU0_SB_DQS_DP<4>")
	)
	(segment
		(start 408.906472 -236.268514)
		(end 409.868878 -236.667548)
		(width 0.20066)
		(layer "F.Cu")
		(net "M_E_CPU0_SB_DQS_DP<4>")
	)
	(segment
		(start 405.74341 -235.991654)
		(end 407.735278 -235.991654)
		(width 0.1016)
		(layer "F.Cu")
		(net "M_E_CPU0_SB_DQS_DP<4>")
	)
	(segment
		(start 411.680152 -236.667802)
		(end 411.472888 -236.667802)
		(width 0.20066)
		(layer "F.Cu")
		(net "M_E_CPU0_SB_DQS_DP<4>")
	)
	(segment
		(start 389.56615 -240.57229)
		(end 389.827516 -240.57229)
		(width 0.088646)
		(layer "F.Cu")
		(net "M_E_CPU0_SB_DQS_DP<4>")
	)
	(segment
		(start 417.240466 -236.671612)
		(end 416.808158 -236.239304)
		(width 0.20066)
		(layer "F.Cu")
		(net "M_E_CPU0_SB_DQS_DP<4>")
	)
	(segment
		(start 405.230584 -235.991654)
		(end 405.74341 -235.991654)
		(width 0.101854)
		(layer "F.Cu")
		(net "M_E_CPU0_SB_DQS_DP<4>")
	)
	(segment
		(start 385.894834 -242.830858)
		(end 385.894834 -242.831112)
		(width 0.088646)
		(layer "F.Cu")
		(net "M_E_CPU0_SB_DQS_DP<4>")
	)
	(segment
		(start 395.863064 -236.811312)
		(end 395.901164 -236.811312)
		(width 0.1524)
		(layer "F.Cu")
		(net "M_E_CPU0_SB_DQS_DP<4>")
	)
	(segment
		(start 415.883852 -235.984288)
		(end 415.705544 -235.984288)
		(width 0.20066)
		(layer "F.Cu")
		(net "M_E_CPU0_SB_DQS_DP<4>")
	)
	(segment
		(start 411.472888 -236.667802)
		(end 411.221682 -236.416596)
		(width 0.20066)
		(layer "F.Cu")
		(net "M_E_CPU0_SB_DQS_DP<4>")
	)
	(segment
		(start 415.30016 -235.991654)
		(end 413.287464 -235.991654)
		(width 0.1016)
		(layer "F.Cu")
		(net "M_E_CPU0_SB_DQS_DP<4>")
	)
	(segment
		(start 395.262862 -236.848142)
		(end 395.826234 -236.848142)
		(width 0.1524)
		(layer "F.Cu")
		(net "M_E_CPU0_SB_DQS_DP<4>")
	)
	(segment
		(start 403.4536 -236.811312)
		(end 404.273258 -235.991654)
		(width 0.20066)
		(layer "F.Cu")
		(net "M_E_CPU0_SB_DQS_DP<4>")
	)
	(segment
		(start 411.221682 -236.416596)
		(end 410.853382 -236.416596)
		(width 0.20066)
		(layer "F.Cu")
		(net "M_E_CPU0_SB_DQS_DP<4>")
	)
	(segment
		(start 387.682486 -242.310666)
		(end 387.68274 -242.31092)
		(width 0.088646)
		(layer "F.Cu")
		(net "M_E_CPU0_SB_DQS_DP<4>")
	)
	(segment
		(start 395.901164 -236.811312)
		(end 403.4536 -236.811312)
		(width 0.20066)
		(layer "F.Cu")
		(net "M_E_CPU0_SB_DQS_DP<4>")
	)
	(segment
		(start 395.826234 -236.848142)
		(end 395.863064 -236.811312)
		(width 0.1524)
		(layer "F.Cu")
		(net "M_E_CPU0_SB_DQS_DP<4>")
	)
	(segment
		(start 412.103824 -236.24413)
		(end 411.680152 -236.667802)
		(width 0.20066)
		(layer "F.Cu")
		(net "M_E_CPU0_SB_DQS_DP<4>")
	)
	(segment
		(start 385.894834 -242.831112)
		(end 386.477764 -242.60937)
		(width 0.088646)
		(layer "F.Cu")
		(net "M_E_CPU0_SB_DQS_DP<4>")
	)
	(segment
		(start 389.881364 -240.54054)
		(end 391.570464 -240.54054)
		(width 0.1524)
		(layer "F.Cu")
		(net "M_E_CPU0_SB_DQS_DP<4>")
	)
	(segment
		(start 386.995162 -242.310666)
		(end 387.682486 -242.310666)
		(width 0.088646)
		(layer "F.Cu")
		(net "M_E_CPU0_SB_DQS_DP<4>")
	)
	(segment
		(start 404.273258 -235.991654)
		(end 405.230584 -235.991654)
		(width 0.20066)
		(layer "F.Cu")
		(net "M_E_CPU0_SB_DQS_DP<4>")
	)
	(segment
		(start 417.574222 -236.671612)
		(end 417.240466 -236.671612)
		(width 0.20066)
		(layer "F.Cu")
		(net "M_E_CPU0_SB_DQS_DP<4>")
	)
	(segment
		(start 389.859266 -240.54054)
		(end 389.881364 -240.54054)
		(width 0.088646)
		(layer "F.Cu")
		(net "M_E_CPU0_SB_DQS_DP<4>")
	)
	(segment
		(start 398.392396 -200.92416)
		(end 398.994376 -200.92416)
		(width 0.20066)
		(layer "F.Cu")
		(net "M_E_CPU0_SB_DQS_DP<3>")
	)
	(segment
		(start 387.467602 -228.651562)
		(end 387.709664 -228.551486)
		(width 0.088646)
		(layer "F.Cu")
		(net "M_E_CPU0_SB_DQS_DP<3>")
	)
	(segment
		(start 387.761988 -228.424994)
		(end 388.033006 -228.312726)
		(width 0.088646)
		(layer "F.Cu")
		(net "M_E_CPU0_SB_DQS_DP<3>")
	)
	(segment
		(start 397.928592 -200.7997)
		(end 398.267936 -200.7997)
		(width 0.20066)
		(layer "F.Cu")
		(net "M_E_CPU0_SB_DQS_DP<3>")
	)
	(segment
		(start 409.835096 -201.160888)
		(end 409.831794 -201.160888)
		(width 0.101854)
		(layer "F.Cu")
		(net "M_E_CPU0_SB_DQS_DP<3>")
	)
	(segment
		(start 392.561572 -204.250036)
		(end 392.561572 -204.074014)
		(width 0.20066)
		(layer "F.Cu")
		(net "M_E_CPU0_SB_DQS_DP<3>")
	)
	(segment
		(start 408.00782 -200.476104)
		(end 407.583132 -200.476104)
		(width 0.20066)
		(layer "F.Cu")
		(net "M_E_CPU0_SB_DQS_DP<3>")
	)
	(segment
		(start 396.65529 -202.249024)
		(end 397.081248 -201.823066)
		(width 0.20066)
		(layer "F.Cu")
		(net "M_E_CPU0_SB_DQS_DP<3>")
	)
	(segment
		(start 398.994376 -200.92416)
		(end 399.118836 -200.7997)
		(width 0.20066)
		(layer "F.Cu")
		(net "M_E_CPU0_SB_DQS_DP<3>")
	)
	(segment
		(start 392.561572 -204.074014)
		(end 392.79322 -203.842366)
		(width 0.20066)
		(layer "F.Cu")
		(net "M_E_CPU0_SB_DQS_DP<3>")
	)
	(segment
		(start 388.551928 -228.050598)
		(end 388.567422 -228.035104)
		(width 0.088646)
		(layer "F.Cu")
		(net "M_E_CPU0_SB_DQS_DP<3>")
	)
	(segment
		(start 395.62786 -203.276454)
		(end 396.053818 -202.850496)
		(width 0.20066)
		(layer "F.Cu")
		(net "M_E_CPU0_SB_DQS_DP<3>")
	)
	(segment
		(start 413.466788 -200.434956)
		(end 413.2707 -200.434956)
		(width 0.20066)
		(layer "F.Cu")
		(net "M_E_CPU0_SB_DQS_DP<3>")
	)
	(segment
		(start 402.000212 -200.92416)
		(end 402.124672 -200.7997)
		(width 0.20066)
		(layer "F.Cu")
		(net "M_E_CPU0_SB_DQS_DP<3>")
	)
	(segment
		(start 390.932162 -205.703424)
		(end 391.108184 -205.703424)
		(width 0.20066)
		(layer "F.Cu")
		(net "M_E_CPU0_SB_DQS_DP<3>")
	)
	(segment
		(start 407.342594 -200.716642)
		(end 406.753314 -200.716642)
		(width 0.20066)
		(layer "F.Cu")
		(net "M_E_CPU0_SB_DQS_DP<3>")
	)
	(segment
		(start 388.24408 -228.312726)
		(end 388.506208 -228.050598)
		(width 0.088646)
		(layer "F.Cu")
		(net "M_E_CPU0_SB_DQS_DP<3>")
	)
	(segment
		(start 400.447256 -200.92416)
		(end 400.571716 -200.7997)
		(width 0.20066)
		(layer "F.Cu")
		(net "M_E_CPU0_SB_DQS_DP<3>")
	)
	(segment
		(start 401.273772 -200.7997)
		(end 401.398232 -200.92416)
		(width 0.20066)
		(layer "F.Cu")
		(net "M_E_CPU0_SB_DQS_DP<3>")
	)
	(segment
		(start 395.026388 -203.701904)
		(end 395.451838 -203.276454)
		(width 0.20066)
		(layer "F.Cu")
		(net "M_E_CPU0_SB_DQS_DP<3>")
	)
	(segment
		(start 391.534142 -205.101444)
		(end 391.959592 -204.675994)
		(width 0.20066)
		(layer "F.Cu")
		(net "M_E_CPU0_SB_DQS_DP<3>")
	)
	(segment
		(start 402.851112 -200.92416)
		(end 403.453092 -200.92416)
		(width 0.20066)
		(layer "F.Cu")
		(net "M_E_CPU0_SB_DQS_DP<3>")
	)
	(segment
		(start 401.398232 -200.92416)
		(end 402.000212 -200.92416)
		(width 0.20066)
		(layer "F.Cu")
		(net "M_E_CPU0_SB_DQS_DP<3>")
	)
	(segment
		(start 399.118836 -200.7997)
		(end 399.720816 -200.7997)
		(width 0.20066)
		(layer "F.Cu")
		(net "M_E_CPU0_SB_DQS_DP<3>")
	)
	(segment
		(start 405.130508 -200.217024)
		(end 405.184102 -200.19645)
		(width 0.20066)
		(layer "F.Cu")
		(net "M_E_CPU0_SB_DQS_DP<3>")
	)
	(segment
		(start 389.75538 -213.163404)
		(end 389.533638 -212.046566)
		(width 0.1524)
		(layer "F.Cu")
		(net "M_E_CPU0_SB_DQS_DP<3>")
	)
	(segment
		(start 412.184088 -201.151998)
		(end 411.863794 -201.151998)
		(width 0.20066)
		(layer "F.Cu")
		(net "M_E_CPU0_SB_DQS_DP<3>")
	)
	(segment
		(start 402.726652 -200.7997)
		(end 402.851112 -200.92416)
		(width 0.20066)
		(layer "F.Cu")
		(net "M_E_CPU0_SB_DQS_DP<3>")
	)
	(segment
		(start 388.567422 -228.035104)
		(end 389.75538 -226.847146)
		(width 0.1524)
		(layer "F.Cu")
		(net "M_E_CPU0_SB_DQS_DP<3>")
	)
	(segment
		(start 384.95478 -228.1809)
		(end 385.080256 -228.153976)
		(width 0.088646)
		(layer "F.Cu")
		(net "M_E_CPU0_SB_DQS_DP<3>")
	)
	(segment
		(start 388.033006 -228.312726)
		(end 388.24408 -228.312726)
		(width 0.088646)
		(layer "F.Cu")
		(net "M_E_CPU0_SB_DQS_DP<3>")
	)
	(segment
		(start 409.554172 -201.160888)
		(end 409.283916 -200.890632)
		(width 0.20066)
		(layer "F.Cu")
		(net "M_E_CPU0_SB_DQS_DP<3>")
	)
	(segment
		(start 400.571716 -200.7997)
		(end 401.273772 -200.7997)
		(width 0.20066)
		(layer "F.Cu")
		(net "M_E_CPU0_SB_DQS_DP<3>")
	)
	(segment
		(start 390.555988 -206.079598)
		(end 390.932162 -205.703424)
		(width 0.20066)
		(layer "F.Cu")
		(net "M_E_CPU0_SB_DQS_DP<3>")
	)
	(segment
		(start 396.479268 -202.249024)
		(end 396.65529 -202.249024)
		(width 0.20066)
		(layer "F.Cu")
		(net "M_E_CPU0_SB_DQS_DP<3>")
	)
	(segment
		(start 391.108184 -205.703424)
		(end 391.534142 -205.277466)
		(width 0.20066)
		(layer "F.Cu")
		(net "M_E_CPU0_SB_DQS_DP<3>")
	)
	(segment
		(start 389.694928 -209.020156)
		(end 389.570468 -208.895696)
		(width 0.20066)
		(layer "F.Cu")
		(net "M_E_CPU0_SB_DQS_DP<3>")
	)
	(segment
		(start 405.007572 -200.268078)
		(end 405.130508 -200.217024)
		(width 0.20066)
		(layer "F.Cu")
		(net "M_E_CPU0_SB_DQS_DP<3>")
	)
	(segment
		(start 396.053818 -202.674474)
		(end 396.479268 -202.249024)
		(width 0.20066)
		(layer "F.Cu")
		(net "M_E_CPU0_SB_DQS_DP<3>")
	)
	(segment
		(start 409.283916 -200.890632)
		(end 409.008834 -200.890632)
		(width 0.20066)
		(layer "F.Cu")
		(net "M_E_CPU0_SB_DQS_DP<3>")
	)
	(segment
		(start 404.825962 -200.343262)
		(end 405.007572 -200.268078)
		(width 0.20066)
		(layer "F.Cu")
		(net "M_E_CPU0_SB_DQS_DP<3>")
	)
	(segment
		(start 389.570468 -208.895696)
		(end 389.570468 -208.458816)
		(width 0.20066)
		(layer "F.Cu")
		(net "M_E_CPU0_SB_DQS_DP<3>")
	)
	(segment
		(start 399.845276 -200.92416)
		(end 400.447256 -200.92416)
		(width 0.20066)
		(layer "F.Cu")
		(net "M_E_CPU0_SB_DQS_DP<3>")
	)
	(segment
		(start 397.081248 -201.823066)
		(end 397.081248 -201.647044)
		(width 0.20066)
		(layer "F.Cu")
		(net "M_E_CPU0_SB_DQS_DP<3>")
	)
	(segment
		(start 396.053818 -202.850496)
		(end 396.053818 -202.674474)
		(width 0.20066)
		(layer "F.Cu")
		(net "M_E_CPU0_SB_DQS_DP<3>")
	)
	(segment
		(start 389.533638 -210.940396)
		(end 389.570468 -210.903566)
		(width 0.1524)
		(layer "F.Cu")
		(net "M_E_CPU0_SB_DQS_DP<3>")
	)
	(segment
		(start 406.207214 -200.716642)
		(end 406.753314 -200.716642)
		(width 0.20066)
		(layer "F.Cu")
		(net "M_E_CPU0_SB_DQS_DP<3>")
	)
	(segment
		(start 385.226814 -228.248718)
		(end 385.450588 -228.5492)
		(width 0.088646)
		(layer "F.Cu")
		(net "M_E_CPU0_SB_DQS_DP<3>")
	)
	(segment
		(start 399.720816 -200.7997)
		(end 399.845276 -200.92416)
		(width 0.20066)
		(layer "F.Cu")
		(net "M_E_CPU0_SB_DQS_DP<3>")
	)
	(segment
		(start 409.831794 -201.160888)
		(end 409.554172 -201.160888)
		(width 0.20066)
		(layer "F.Cu")
		(net "M_E_CPU0_SB_DQS_DP<3>")
	)
	(segment
		(start 387.709664 -228.551486)
		(end 387.761988 -228.424994)
		(width 0.088646)
		(layer "F.Cu")
		(net "M_E_CPU0_SB_DQS_DP<3>")
	)
	(segment
		(start 398.267936 -200.7997)
		(end 398.392396 -200.92416)
		(width 0.20066)
		(layer "F.Cu")
		(net "M_E_CPU0_SB_DQS_DP<3>")
	)
	(segment
		(start 413.748474 -200.716642)
		(end 413.466788 -200.434956)
		(width 0.20066)
		(layer "F.Cu")
		(net "M_E_CPU0_SB_DQS_DP<3>")
	)
	(segment
		(start 388.506208 -228.050598)
		(end 388.551928 -228.050598)
		(width 0.088646)
		(layer "F.Cu")
		(net "M_E_CPU0_SB_DQS_DP<3>")
	)
	(segment
		(start 403.453092 -200.92416)
		(end 403.577552 -200.7997)
		(width 0.20066)
		(layer "F.Cu")
		(net "M_E_CPU0_SB_DQS_DP<3>")
	)
	(segment
		(start 393.13231 -203.701904)
		(end 395.026388 -203.701904)
		(width 0.20066)
		(layer "F.Cu")
		(net "M_E_CPU0_SB_DQS_DP<3>")
	)
	(segment
		(start 386.594604 -228.694234)
		(end 386.668518 -228.731318)
		(width 0.088646)
		(layer "F.Cu")
		(net "M_E_CPU0_SB_DQS_DP<3>")
	)
	(segment
		(start 389.570468 -210.903566)
		(end 389.570468 -210.865212)
		(width 0.1524)
		(layer "F.Cu")
		(net "M_E_CPU0_SB_DQS_DP<3>")
	)
	(segment
		(start 402.124672 -200.7997)
		(end 402.726652 -200.7997)
		(width 0.20066)
		(layer "F.Cu")
		(net "M_E_CPU0_SB_DQS_DP<3>")
	)
	(segment
		(start 412.440628 -200.895458)
		(end 412.184088 -201.151998)
		(width 0.20066)
		(layer "F.Cu")
		(net "M_E_CPU0_SB_DQS_DP<3>")
	)
	(segment
		(start 389.570468 -209.746596)
		(end 389.694928 -209.622136)
		(width 0.20066)
		(layer "F.Cu")
		(net "M_E_CPU0_SB_DQS_DP<3>")
	)
	(segment
		(start 405.184102 -200.19645)
		(end 405.687022 -200.19645)
		(width 0.20066)
		(layer "F.Cu")
		(net "M_E_CPU0_SB_DQS_DP<3>")
	)
	(segment
		(start 392.135614 -204.675994)
		(end 392.561572 -204.250036)
		(width 0.20066)
		(layer "F.Cu")
		(net "M_E_CPU0_SB_DQS_DP<3>")
	)
	(segment
		(start 407.583132 -200.476104)
		(end 407.342594 -200.716642)
		(width 0.20066)
		(layer "F.Cu")
		(net "M_E_CPU0_SB_DQS_DP<3>")
	)
	(segment
		(start 386.534152 -228.65969)
		(end 386.594604 -228.694234)
		(width 0.088646)
		(layer "F.Cu")
		(net "M_E_CPU0_SB_DQS_DP<3>")
	)
	(segment
		(start 391.959592 -204.675994)
		(end 392.135614 -204.675994)
		(width 0.20066)
		(layer "F.Cu")
		(net "M_E_CPU0_SB_DQS_DP<3>")
	)
	(segment
		(start 385.450588 -228.5492)
		(end 385.50215 -228.59619)
		(width 0.088646)
		(layer "F.Cu")
		(net "M_E_CPU0_SB_DQS_DP<3>")
	)
	(segment
		(start 392.79322 -203.842366)
		(end 393.13231 -203.701904)
		(width 0.20066)
		(layer "F.Cu")
		(net "M_E_CPU0_SB_DQS_DP<3>")
	)
	(segment
		(start 385.080256 -228.153976)
		(end 385.226814 -228.248718)
		(width 0.088646)
		(layer "F.Cu")
		(net "M_E_CPU0_SB_DQS_DP<3>")
	)
	(segment
		(start 414.297114 -200.716642)
		(end 413.748474 -200.716642)
		(width 0.20066)
		(layer "F.Cu")
		(net "M_E_CPU0_SB_DQS_DP<3>")
	)
	(segment
		(start 395.451838 -203.276454)
		(end 395.62786 -203.276454)
		(width 0.20066)
		(layer "F.Cu")
		(net "M_E_CPU0_SB_DQS_DP<3>")
	)
	(segment
		(start 409.008834 -200.890632)
		(end 408.00782 -200.476104)
		(width 0.20066)
		(layer "F.Cu")
		(net "M_E_CPU0_SB_DQS_DP<3>")
	)
	(segment
		(start 411.863794 -201.151998)
		(end 411.853634 -201.141838)
		(width 0.1016)
		(layer "F.Cu")
		(net "M_E_CPU0_SB_DQS_DP<3>")
	)
	(segment
		(start 411.853634 -201.141838)
		(end 409.854146 -201.141838)
		(width 0.1016)
		(layer "F.Cu")
		(net "M_E_CPU0_SB_DQS_DP<3>")
	)
	(segment
		(start 412.810198 -200.895458)
		(end 412.440628 -200.895458)
		(width 0.20066)
		(layer "F.Cu")
		(net "M_E_CPU0_SB_DQS_DP<3>")
	)
	(segment
		(start 397.081248 -201.647044)
		(end 397.928592 -200.7997)
		(width 0.20066)
		(layer "F.Cu")
		(net "M_E_CPU0_SB_DQS_DP<3>")
	)
	(segment
		(start 389.694928 -209.622136)
		(end 389.694928 -209.020156)
		(width 0.20066)
		(layer "F.Cu")
		(net "M_E_CPU0_SB_DQS_DP<3>")
	)
	(segment
		(start 409.854146 -201.141838)
		(end 409.835096 -201.160888)
		(width 0.1016)
		(layer "F.Cu")
		(net "M_E_CPU0_SB_DQS_DP<3>")
	)
	(segment
		(start 413.2707 -200.434956)
		(end 412.810198 -200.895458)
		(width 0.20066)
		(layer "F.Cu")
		(net "M_E_CPU0_SB_DQS_DP<3>")
	)
	(segment
		(start 403.577552 -200.7997)
		(end 404.369524 -200.7997)
		(width 0.20066)
		(layer "F.Cu")
		(net "M_E_CPU0_SB_DQS_DP<3>")
	)
	(segment
		(start 391.534142 -205.277466)
		(end 391.534142 -205.101444)
		(width 0.20066)
		(layer "F.Cu")
		(net "M_E_CPU0_SB_DQS_DP<3>")
	)
	(segment
		(start 386.172964 -228.67366)
		(end 386.17398 -228.673152)
		(width 0.088646)
		(layer "F.Cu")
		(net "M_E_CPU0_SB_DQS_DP<3>")
	)
	(segment
		(start 387.341618 -228.599238)
		(end 387.467602 -228.651562)
		(width 0.088646)
		(layer "F.Cu")
		(net "M_E_CPU0_SB_DQS_DP<3>")
	)
	(segment
		(start 387.02234 -228.731318)
		(end 387.341618 -228.599238)
		(width 0.088646)
		(layer "F.Cu")
		(net "M_E_CPU0_SB_DQS_DP<3>")
	)
	(segment
		(start 386.668518 -228.731318)
		(end 387.02234 -228.731318)
		(width 0.088646)
		(layer "F.Cu")
		(net "M_E_CPU0_SB_DQS_DP<3>")
	)
	(segment
		(start 389.570468 -208.458816)
		(end 390.555988 -206.079598)
		(width 0.20066)
		(layer "F.Cu")
		(net "M_E_CPU0_SB_DQS_DP<3>")
	)
	(segment
		(start 389.533638 -212.046566)
		(end 389.533638 -210.940396)
		(width 0.1524)
		(layer "F.Cu")
		(net "M_E_CPU0_SB_DQS_DP<3>")
	)
	(segment
		(start 389.570468 -210.865212)
		(end 389.570468 -209.746596)
		(width 0.20066)
		(layer "F.Cu")
		(net "M_E_CPU0_SB_DQS_DP<3>")
	)
	(segment
		(start 389.75538 -226.847146)
		(end 389.75538 -213.163404)
		(width 0.1524)
		(layer "F.Cu")
		(net "M_E_CPU0_SB_DQS_DP<3>")
	)
	(segment
		(start 404.369524 -200.7997)
		(end 404.825962 -200.343262)
		(width 0.20066)
		(layer "F.Cu")
		(net "M_E_CPU0_SB_DQS_DP<3>")
	)
	(segment
		(start 405.687022 -200.19645)
		(end 406.207214 -200.716642)
		(width 0.20066)
		(layer "F.Cu")
		(net "M_E_CPU0_SB_DQS_DP<3>")
	)
	(segment
		(start 386.17398 -228.673152)
		(end 386.222748 -228.645212)
		(width 0.088646)
		(layer "F.Cu")
		(net "M_E_CPU0_SB_DQS_DP<3>")
	)
	(arc
		(start 386.273294 -228.624638)
		(mid 386.40713 -228.616755)
		(end 386.534152 -228.65969)
		(width 0.088646)
		(layer "F.Cu")
		(net "M_E_CPU0_SB_DQS_DP<3>")
	)
	(arc
		(start 385.50215 -228.59619)
		(mid 385.825045 -228.743359)
		(end 386.172964 -228.67366)
		(width 0.088646)
		(layer "F.Cu")
		(net "M_E_CPU0_SB_DQS_DP<3>")
	)
	(arc
		(start 386.222748 -228.645212)
		(mid 386.247322 -228.633207)
		(end 386.273294 -228.624638)
		(width 0.088646)
		(layer "F.Cu")
		(net "M_E_CPU0_SB_DQS_DP<3>")
	)
	(segment
		(start 397.78813 -213.241128)
		(end 398.214088 -212.81517)
		(width 0.20066)
		(layer "F.Cu")
		(net "M_E_CPU0_SB_DQS_DP<2>")
	)
	(segment
		(start 413.854646 -210.066636)
		(end 413.57296 -209.78495)
		(width 0.20066)
		(layer "F.Cu")
		(net "M_E_CPU0_SB_DQS_DP<2>")
	)
	(segment
		(start 401.612608 -209.75066)
		(end 401.737068 -209.87512)
		(width 0.20066)
		(layer "F.Cu")
		(net "M_E_CPU0_SB_DQS_DP<2>")
	)
	(segment
		(start 408.944064 -210.199986)
		(end 408.508962 -210.019646)
		(width 0.20066)
		(layer "F.Cu")
		(net "M_E_CPU0_SB_DQS_DP<2>")
	)
	(segment
		(start 385.289552 -233.131106)
		(end 385.289552 -233.323638)
		(width 0.088646)
		(layer "F.Cu")
		(net "M_E_CPU0_SB_DQS_DP<2>")
	)
	(segment
		(start 386.606796 -233.608372)
		(end 387.153404 -233.608372)
		(width 0.088646)
		(layer "F.Cu")
		(net "M_E_CPU0_SB_DQS_DP<2>")
	)
	(segment
		(start 413.57296 -209.78495)
		(end 413.359092 -209.78495)
		(width 0.20066)
		(layer "F.Cu")
		(net "M_E_CPU0_SB_DQS_DP<2>")
	)
	(segment
		(start 388.326122 -233.562652)
		(end 388.593838 -233.562652)
		(width 0.1524)
		(layer "F.Cu")
		(net "M_E_CPU0_SB_DQS_DP<2>")
	)
	(segment
		(start 397.612108 -213.241128)
		(end 397.78813 -213.241128)
		(width 0.20066)
		(layer "F.Cu")
		(net "M_E_CPU0_SB_DQS_DP<2>")
	)
	(segment
		(start 412.921196 -210.222846)
		(end 412.433262 -210.222846)
		(width 0.20066)
		(layer "F.Cu")
		(net "M_E_CPU0_SB_DQS_DP<2>")
	)
	(segment
		(start 408.508962 -210.019646)
		(end 408.315414 -209.826098)
		(width 0.20066)
		(layer "F.Cu")
		(net "M_E_CPU0_SB_DQS_DP<2>")
	)
	(segment
		(start 385.289552 -233.323638)
		(end 385.58343 -233.543856)
		(width 0.088646)
		(layer "F.Cu")
		(net "M_E_CPU0_SB_DQS_DP<2>")
	)
	(segment
		(start 402.339048 -209.87512)
		(end 402.463508 -209.75066)
		(width 0.20066)
		(layer "F.Cu")
		(net "M_E_CPU0_SB_DQS_DP<2>")
	)
	(segment
		(start 385.58343 -233.543856)
		(end 385.830318 -233.638344)
		(width 0.088646)
		(layer "F.Cu")
		(net "M_E_CPU0_SB_DQS_DP<2>")
	)
	(segment
		(start 388.593838 -233.562652)
		(end 393.66698 -228.48951)
		(width 0.1524)
		(layer "F.Cu")
		(net "M_E_CPU0_SB_DQS_DP<2>")
	)
	(segment
		(start 404.518368 -209.75066)
		(end 404.642828 -209.87512)
		(width 0.20066)
		(layer "F.Cu")
		(net "M_E_CPU0_SB_DQS_DP<2>")
	)
	(segment
		(start 387.153404 -233.608372)
		(end 387.230874 -233.530902)
		(width 0.088646)
		(layer "F.Cu")
		(net "M_E_CPU0_SB_DQS_DP<2>")
	)
	(segment
		(start 384.95478 -233.064304)
		(end 385.22275 -233.064304)
		(width 0.088646)
		(layer "F.Cu")
		(net "M_E_CPU0_SB_DQS_DP<2>")
	)
	(segment
		(start 385.22275 -233.064304)
		(end 385.289552 -233.131106)
		(width 0.088646)
		(layer "F.Cu")
		(net "M_E_CPU0_SB_DQS_DP<2>")
	)
	(segment
		(start 409.557982 -210.50758)
		(end 409.250388 -210.199986)
		(width 0.20066)
		(layer "F.Cu")
		(net "M_E_CPU0_SB_DQS_DP<2>")
	)
	(segment
		(start 407.342594 -210.066636)
		(end 406.753314 -210.066636)
		(width 0.20066)
		(layer "F.Cu")
		(net "M_E_CPU0_SB_DQS_DP<2>")
	)
	(segment
		(start 388.27202 -233.530648)
		(end 388.304024 -233.562652)
		(width 0.088646)
		(layer "F.Cu")
		(net "M_E_CPU0_SB_DQS_DP<2>")
	)
	(segment
		(start 409.250388 -210.199986)
		(end 408.944064 -210.199986)
		(width 0.20066)
		(layer "F.Cu")
		(net "M_E_CPU0_SB_DQS_DP<2>")
	)
	(segment
		(start 394.529818 -216.323418)
		(end 394.70584 -216.323418)
		(width 0.20066)
		(layer "F.Cu")
		(net "M_E_CPU0_SB_DQS_DP<2>")
	)
	(segment
		(start 400.268948 -210.584288)
		(end 401.102576 -209.75066)
		(width 0.20066)
		(layer "F.Cu")
		(net "M_E_CPU0_SB_DQS_DP<2>")
	)
	(segment
		(start 401.102576 -209.75066)
		(end 401.612608 -209.75066)
		(width 0.20066)
		(layer "F.Cu")
		(net "M_E_CPU0_SB_DQS_DP<2>")
	)
	(segment
		(start 398.639538 -212.213698)
		(end 398.81556 -212.213698)
		(width 0.20066)
		(layer "F.Cu")
		(net "M_E_CPU0_SB_DQS_DP<2>")
	)
	(segment
		(start 386.318252 -233.502708)
		(end 386.501132 -233.502708)
		(width 0.088646)
		(layer "F.Cu")
		(net "M_E_CPU0_SB_DQS_DP<2>")
	)
	(segment
		(start 401.737068 -209.87512)
		(end 402.339048 -209.87512)
		(width 0.20066)
		(layer "F.Cu")
		(net "M_E_CPU0_SB_DQS_DP<2>")
	)
	(segment
		(start 409.831794 -210.50758)
		(end 409.557982 -210.50758)
		(width 0.20066)
		(layer "F.Cu")
		(net "M_E_CPU0_SB_DQS_DP<2>")
	)
	(segment
		(start 395.557248 -215.295988)
		(end 395.73327 -215.295988)
		(width 0.20066)
		(layer "F.Cu")
		(net "M_E_CPU0_SB_DQS_DP<2>")
	)
	(segment
		(start 388.304024 -233.562652)
		(end 388.326122 -233.562652)
		(width 0.088646)
		(layer "F.Cu")
		(net "M_E_CPU0_SB_DQS_DP<2>")
	)
	(segment
		(start 397.186658 -213.666578)
		(end 397.612108 -213.241128)
		(width 0.20066)
		(layer "F.Cu")
		(net "M_E_CPU0_SB_DQS_DP<2>")
	)
	(segment
		(start 411.858968 -210.510882)
		(end 411.839918 -210.491832)
		(width 0.1016)
		(layer "F.Cu")
		(net "M_E_CPU0_SB_DQS_DP<2>")
	)
	(segment
		(start 396.159228 -214.694008)
		(end 396.584678 -214.268558)
		(width 0.20066)
		(layer "F.Cu")
		(net "M_E_CPU0_SB_DQS_DP<2>")
	)
	(segment
		(start 386.501132 -233.502708)
		(end 386.606796 -233.608372)
		(width 0.088646)
		(layer "F.Cu")
		(net "M_E_CPU0_SB_DQS_DP<2>")
	)
	(segment
		(start 411.839918 -210.491832)
		(end 409.854146 -210.491832)
		(width 0.1016)
		(layer "F.Cu")
		(net "M_E_CPU0_SB_DQS_DP<2>")
	)
	(segment
		(start 396.7607 -214.268558)
		(end 397.186658 -213.8426)
		(width 0.20066)
		(layer "F.Cu")
		(net "M_E_CPU0_SB_DQS_DP<2>")
	)
	(segment
		(start 403.791928 -209.87512)
		(end 403.916388 -209.75066)
		(width 0.20066)
		(layer "F.Cu")
		(net "M_E_CPU0_SB_DQS_DP<2>")
	)
	(segment
		(start 387.8072 -233.530902)
		(end 388.040626 -233.530902)
		(width 0.088646)
		(layer "F.Cu")
		(net "M_E_CPU0_SB_DQS_DP<2>")
	)
	(segment
		(start 388.04088 -233.530648)
		(end 388.27202 -233.530648)
		(width 0.088646)
		(layer "F.Cu")
		(net "M_E_CPU0_SB_DQS_DP<2>")
	)
	(segment
		(start 405.244808 -209.87512)
		(end 405.369268 -209.75066)
		(width 0.20066)
		(layer "F.Cu")
		(net "M_E_CPU0_SB_DQS_DP<2>")
	)
	(segment
		(start 393.925806 -216.875106)
		(end 393.97813 -216.875106)
		(width 0.1524)
		(layer "F.Cu")
		(net "M_E_CPU0_SB_DQS_DP<2>")
	)
	(segment
		(start 402.463508 -209.75066)
		(end 403.065488 -209.75066)
		(width 0.20066)
		(layer "F.Cu")
		(net "M_E_CPU0_SB_DQS_DP<2>")
	)
	(segment
		(start 399.241518 -211.78774)
		(end 399.241518 -211.611718)
		(width 0.20066)
		(layer "F.Cu")
		(net "M_E_CPU0_SB_DQS_DP<2>")
	)
	(segment
		(start 400.268948 -210.76031)
		(end 400.268948 -210.584288)
		(width 0.20066)
		(layer "F.Cu")
		(net "M_E_CPU0_SB_DQS_DP<2>")
	)
	(segment
		(start 387.520688 -233.63936)
		(end 387.698742 -233.63936)
		(width 0.088646)
		(layer "F.Cu")
		(net "M_E_CPU0_SB_DQS_DP<2>")
	)
	(segment
		(start 407.583132 -209.826098)
		(end 407.342594 -210.066636)
		(width 0.20066)
		(layer "F.Cu")
		(net "M_E_CPU0_SB_DQS_DP<2>")
	)
	(segment
		(start 396.159228 -214.87003)
		(end 396.159228 -214.694008)
		(width 0.20066)
		(layer "F.Cu")
		(net "M_E_CPU0_SB_DQS_DP<2>")
	)
	(segment
		(start 395.73327 -215.295988)
		(end 396.159228 -214.87003)
		(width 0.20066)
		(layer "F.Cu")
		(net "M_E_CPU0_SB_DQS_DP<2>")
	)
	(segment
		(start 387.698742 -233.63936)
		(end 387.8072 -233.530902)
		(width 0.088646)
		(layer "F.Cu")
		(net "M_E_CPU0_SB_DQS_DP<2>")
	)
	(segment
		(start 397.186658 -213.8426)
		(end 397.186658 -213.666578)
		(width 0.20066)
		(layer "F.Cu")
		(net "M_E_CPU0_SB_DQS_DP<2>")
	)
	(segment
		(start 404.642828 -209.87512)
		(end 405.244808 -209.87512)
		(width 0.20066)
		(layer "F.Cu")
		(net "M_E_CPU0_SB_DQS_DP<2>")
	)
	(segment
		(start 412.145226 -210.510882)
		(end 411.863794 -210.510882)
		(width 0.20066)
		(layer "F.Cu")
		(net "M_E_CPU0_SB_DQS_DP<2>")
	)
	(segment
		(start 403.916388 -209.75066)
		(end 404.518368 -209.75066)
		(width 0.20066)
		(layer "F.Cu")
		(net "M_E_CPU0_SB_DQS_DP<2>")
	)
	(segment
		(start 398.214088 -212.639148)
		(end 398.639538 -212.213698)
		(width 0.20066)
		(layer "F.Cu")
		(net "M_E_CPU0_SB_DQS_DP<2>")
	)
	(segment
		(start 388.040626 -233.530902)
		(end 388.04088 -233.530648)
		(width 0.088646)
		(layer "F.Cu")
		(net "M_E_CPU0_SB_DQS_DP<2>")
	)
	(segment
		(start 393.66698 -217.133932)
		(end 393.925806 -216.875106)
		(width 0.1524)
		(layer "F.Cu")
		(net "M_E_CPU0_SB_DQS_DP<2>")
	)
	(segment
		(start 413.359092 -209.78495)
		(end 412.921196 -210.222846)
		(width 0.20066)
		(layer "F.Cu")
		(net "M_E_CPU0_SB_DQS_DP<2>")
	)
	(segment
		(start 394.005054 -216.848182)
		(end 394.529818 -216.323418)
		(width 0.20066)
		(layer "F.Cu")
		(net "M_E_CPU0_SB_DQS_DP<2>")
	)
	(segment
		(start 395.131798 -215.89746)
		(end 395.131798 -215.721438)
		(width 0.20066)
		(layer "F.Cu")
		(net "M_E_CPU0_SB_DQS_DP<2>")
	)
	(segment
		(start 409.838398 -210.50758)
		(end 409.831794 -210.50758)
		(width 0.101854)
		(layer "F.Cu")
		(net "M_E_CPU0_SB_DQS_DP<2>")
	)
	(segment
		(start 399.241518 -211.611718)
		(end 399.666968 -211.186268)
		(width 0.20066)
		(layer "F.Cu")
		(net "M_E_CPU0_SB_DQS_DP<2>")
	)
	(segment
		(start 393.97813 -216.875106)
		(end 394.005054 -216.848182)
		(width 0.1524)
		(layer "F.Cu")
		(net "M_E_CPU0_SB_DQS_DP<2>")
	)
	(segment
		(start 394.70584 -216.323418)
		(end 395.131798 -215.89746)
		(width 0.20066)
		(layer "F.Cu")
		(net "M_E_CPU0_SB_DQS_DP<2>")
	)
	(segment
		(start 387.41223 -233.530902)
		(end 387.520688 -233.63936)
		(width 0.088646)
		(layer "F.Cu")
		(net "M_E_CPU0_SB_DQS_DP<2>")
	)
	(segment
		(start 399.84299 -211.186268)
		(end 400.268948 -210.76031)
		(width 0.20066)
		(layer "F.Cu")
		(net "M_E_CPU0_SB_DQS_DP<2>")
	)
	(segment
		(start 403.189948 -209.87512)
		(end 403.791928 -209.87512)
		(width 0.20066)
		(layer "F.Cu")
		(net "M_E_CPU0_SB_DQS_DP<2>")
	)
	(segment
		(start 414.297114 -210.066636)
		(end 413.854646 -210.066636)
		(width 0.20066)
		(layer "F.Cu")
		(net "M_E_CPU0_SB_DQS_DP<2>")
	)
	(segment
		(start 405.978106 -209.75066)
		(end 406.294082 -210.066636)
		(width 0.20066)
		(layer "F.Cu")
		(net "M_E_CPU0_SB_DQS_DP<2>")
	)
	(segment
		(start 385.993386 -233.638344)
		(end 386.318252 -233.502708)
		(width 0.088646)
		(layer "F.Cu")
		(net "M_E_CPU0_SB_DQS_DP<2>")
	)
	(segment
		(start 385.830318 -233.638344)
		(end 385.993386 -233.638344)
		(width 0.088646)
		(layer "F.Cu")
		(net "M_E_CPU0_SB_DQS_DP<2>")
	)
	(segment
		(start 398.81556 -212.213698)
		(end 399.241518 -211.78774)
		(width 0.20066)
		(layer "F.Cu")
		(net "M_E_CPU0_SB_DQS_DP<2>")
	)
	(segment
		(start 398.214088 -212.81517)
		(end 398.214088 -212.639148)
		(width 0.20066)
		(layer "F.Cu")
		(net "M_E_CPU0_SB_DQS_DP<2>")
	)
	(segment
		(start 399.666968 -211.186268)
		(end 399.84299 -211.186268)
		(width 0.20066)
		(layer "F.Cu")
		(net "M_E_CPU0_SB_DQS_DP<2>")
	)
	(segment
		(start 396.584678 -214.268558)
		(end 396.7607 -214.268558)
		(width 0.20066)
		(layer "F.Cu")
		(net "M_E_CPU0_SB_DQS_DP<2>")
	)
	(segment
		(start 411.863794 -210.510882)
		(end 411.858968 -210.510882)
		(width 0.101854)
		(layer "F.Cu")
		(net "M_E_CPU0_SB_DQS_DP<2>")
	)
	(segment
		(start 408.315414 -209.826098)
		(end 407.583132 -209.826098)
		(width 0.20066)
		(layer "F.Cu")
		(net "M_E_CPU0_SB_DQS_DP<2>")
	)
	(segment
		(start 405.369268 -209.75066)
		(end 405.978106 -209.75066)
		(width 0.20066)
		(layer "F.Cu")
		(net "M_E_CPU0_SB_DQS_DP<2>")
	)
	(segment
		(start 406.294082 -210.066636)
		(end 406.753314 -210.066636)
		(width 0.20066)
		(layer "F.Cu")
		(net "M_E_CPU0_SB_DQS_DP<2>")
	)
	(segment
		(start 409.854146 -210.491832)
		(end 409.838398 -210.50758)
		(width 0.1016)
		(layer "F.Cu")
		(net "M_E_CPU0_SB_DQS_DP<2>")
	)
	(segment
		(start 403.065488 -209.75066)
		(end 403.189948 -209.87512)
		(width 0.20066)
		(layer "F.Cu")
		(net "M_E_CPU0_SB_DQS_DP<2>")
	)
	(segment
		(start 387.230874 -233.530902)
		(end 387.41223 -233.530902)
		(width 0.088646)
		(layer "F.Cu")
		(net "M_E_CPU0_SB_DQS_DP<2>")
	)
	(segment
		(start 395.131798 -215.721438)
		(end 395.557248 -215.295988)
		(width 0.20066)
		(layer "F.Cu")
		(net "M_E_CPU0_SB_DQS_DP<2>")
	)
	(segment
		(start 412.433262 -210.222846)
		(end 412.145226 -210.510882)
		(width 0.20066)
		(layer "F.Cu")
		(net "M_E_CPU0_SB_DQS_DP<2>")
	)
	(segment
		(start 393.66698 -228.48951)
		(end 393.66698 -217.133932)
		(width 0.1524)
		(layer "F.Cu")
		(net "M_E_CPU0_SB_DQS_DP<2>")
	)
	(segment
		(start 413.466788 -219.134944)
		(end 413.2707 -219.134944)
		(width 0.20066)
		(layer "F.Cu")
		(net "M_E_CPU0_SB_DQS_DP<1>")
	)
	(segment
		(start 386.177028 -238.436658)
		(end 386.177536 -238.437166)
		(width 0.088646)
		(layer "F.Cu")
		(net "M_E_CPU0_SB_DQS_DP<1>")
	)
	(segment
		(start 409.842462 -219.85478)
		(end 409.831794 -219.85478)
		(width 0.101854)
		(layer "F.Cu")
		(net "M_E_CPU0_SB_DQS_DP<1>")
	)
	(segment
		(start 402.162772 -224.761806)
		(end 402.162772 -224.159826)
		(width 0.20066)
		(layer "F.Cu")
		(net "M_E_CPU0_SB_DQS_DP<1>")
	)
	(segment
		(start 405.473154 -218.893898)
		(end 405.671528 -219.092272)
		(width 0.20066)
		(layer "F.Cu")
		(net "M_E_CPU0_SB_DQS_DP<1>")
	)
	(segment
		(start 405.782272 -219.41663)
		(end 406.753314 -219.41663)
		(width 0.20066)
		(layer "F.Cu")
		(net "M_E_CPU0_SB_DQS_DP<1>")
	)
	(segment
		(start 387.639306 -238.354108)
		(end 387.698234 -238.29518)
		(width 0.088646)
		(layer "F.Cu")
		(net "M_E_CPU0_SB_DQS_DP<1>")
	)
	(segment
		(start 388.054596 -237.939326)
		(end 388.195058 -237.939326)
		(width 0.088646)
		(layer "F.Cu")
		(net "M_E_CPU0_SB_DQS_DP<1>")
	)
	(segment
		(start 402.287232 -224.035366)
		(end 402.287232 -223.433386)
		(width 0.20066)
		(layer "F.Cu")
		(net "M_E_CPU0_SB_DQS_DP<1>")
	)
	(segment
		(start 411.847538 -219.841826)
		(end 409.860496 -219.841826)
		(width 0.1016)
		(layer "F.Cu")
		(net "M_E_CPU0_SB_DQS_DP<1>")
	)
	(segment
		(start 412.197296 -219.858082)
		(end 411.863794 -219.858082)
		(width 0.20066)
		(layer "F.Cu")
		(net "M_E_CPU0_SB_DQS_DP<1>")
	)
	(segment
		(start 388.302754 -237.691168)
		(end 388.534656 -237.459266)
		(width 0.088646)
		(layer "F.Cu")
		(net "M_E_CPU0_SB_DQS_DP<1>")
	)
	(segment
		(start 387.839204 -238.29518)
		(end 387.9469 -238.187484)
		(width 0.088646)
		(layer "F.Cu")
		(net "M_E_CPU0_SB_DQS_DP<1>")
	)
	(segment
		(start 409.349448 -219.85478)
		(end 409.085288 -219.59062)
		(width 0.20066)
		(layer "F.Cu")
		(net "M_E_CPU0_SB_DQS_DP<1>")
	)
	(segment
		(start 385.216908 -238.002064)
		(end 385.310888 -238.128048)
		(width 0.088646)
		(layer "F.Cu")
		(net "M_E_CPU0_SB_DQS_DP<1>")
	)
	(segment
		(start 398.850866 -228.073712)
		(end 399.026888 -228.073712)
		(width 0.20066)
		(layer "F.Cu")
		(net "M_E_CPU0_SB_DQS_DP<1>")
	)
	(segment
		(start 409.085288 -219.59062)
		(end 408.535124 -219.59062)
		(width 0.20066)
		(layer "F.Cu")
		(net "M_E_CPU0_SB_DQS_DP<1>")
	)
	(segment
		(start 402.591016 -222.05442)
		(end 402.767038 -222.05442)
		(width 0.20066)
		(layer "F.Cu")
		(net "M_E_CPU0_SB_DQS_DP<1>")
	)
	(segment
		(start 404.766018 -219.879418)
		(end 404.766018 -219.182188)
		(width 0.20066)
		(layer "F.Cu")
		(net "M_E_CPU0_SB_DQS_DP<1>")
	)
	(segment
		(start 384.95478 -237.947454)
		(end 385.08813 -237.918752)
		(width 0.088646)
		(layer "F.Cu")
		(net "M_E_CPU0_SB_DQS_DP<1>")
	)
	(segment
		(start 403.6441 -221.001336)
		(end 403.820122 -221.001336)
		(width 0.20066)
		(layer "F.Cu")
		(net "M_E_CPU0_SB_DQS_DP<1>")
	)
	(segment
		(start 390.25195 -237.492286)
		(end 397.57858 -230.165656)
		(width 0.1524)
		(layer "F.Cu")
		(net "M_E_CPU0_SB_DQS_DP<1>")
	)
	(segment
		(start 397.57858 -229.293674)
		(end 398.294352 -228.577902)
		(width 0.1524)
		(layer "F.Cu")
		(net "M_E_CPU0_SB_DQS_DP<1>")
	)
	(segment
		(start 400.054318 -227.046282)
		(end 400.480276 -226.620324)
		(width 0.20066)
		(layer "F.Cu")
		(net "M_E_CPU0_SB_DQS_DP<1>")
	)
	(segment
		(start 387.9469 -238.047022)
		(end 388.054596 -237.939326)
		(width 0.088646)
		(layer "F.Cu")
		(net "M_E_CPU0_SB_DQS_DP<1>")
	)
	(segment
		(start 409.847542 -219.85478)
		(end 409.842462 -219.85478)
		(width 0.1016)
		(layer "F.Cu")
		(net "M_E_CPU0_SB_DQS_DP<1>")
	)
	(segment
		(start 386.82295 -238.493046)
		(end 387.156198 -238.493046)
		(width 0.088646)
		(layer "F.Cu")
		(net "M_E_CPU0_SB_DQS_DP<1>")
	)
	(segment
		(start 412.525464 -219.529914)
		(end 412.197296 -219.858082)
		(width 0.20066)
		(layer "F.Cu")
		(net "M_E_CPU0_SB_DQS_DP<1>")
	)
	(segment
		(start 411.863794 -219.858082)
		(end 411.847538 -219.841826)
		(width 0.1016)
		(layer "F.Cu")
		(net "M_E_CPU0_SB_DQS_DP<1>")
	)
	(segment
		(start 414.297114 -219.41663)
		(end 413.748474 -219.41663)
		(width 0.20066)
		(layer "F.Cu")
		(net "M_E_CPU0_SB_DQS_DP<1>")
	)
	(segment
		(start 386.177536 -238.437166)
		(end 386.230622 -238.406432)
		(width 0.088646)
		(layer "F.Cu")
		(net "M_E_CPU0_SB_DQS_DP<1>")
	)
	(segment
		(start 385.310888 -238.128048)
		(end 385.50596 -238.341154)
		(width 0.088646)
		(layer "F.Cu")
		(net "M_E_CPU0_SB_DQS_DP<1>")
	)
	(segment
		(start 402.162772 -224.159826)
		(end 402.287232 -224.035366)
		(width 0.20066)
		(layer "F.Cu")
		(net "M_E_CPU0_SB_DQS_DP<1>")
	)
	(segment
		(start 400.480276 -226.444302)
		(end 400.905726 -226.018852)
		(width 0.20066)
		(layer "F.Cu")
		(net "M_E_CPU0_SB_DQS_DP<1>")
	)
	(segment
		(start 388.534656 -237.459266)
		(end 388.666736 -237.459266)
		(width 0.088646)
		(layer "F.Cu")
		(net "M_E_CPU0_SB_DQS_DP<1>")
	)
	(segment
		(start 412.87573 -219.529914)
		(end 412.525464 -219.529914)
		(width 0.20066)
		(layer "F.Cu")
		(net "M_E_CPU0_SB_DQS_DP<1>")
	)
	(segment
		(start 399.452846 -227.647754)
		(end 399.452846 -227.471732)
		(width 0.20066)
		(layer "F.Cu")
		(net "M_E_CPU0_SB_DQS_DP<1>")
	)
	(segment
		(start 404.24608 -220.399356)
		(end 404.766018 -219.879418)
		(width 0.20066)
		(layer "F.Cu")
		(net "M_E_CPU0_SB_DQS_DP<1>")
	)
	(segment
		(start 400.480276 -226.620324)
		(end 400.480276 -226.444302)
		(width 0.20066)
		(layer "F.Cu")
		(net "M_E_CPU0_SB_DQS_DP<1>")
	)
	(segment
		(start 398.346676 -228.577902)
		(end 398.3736 -228.550978)
		(width 0.1524)
		(layer "F.Cu")
		(net "M_E_CPU0_SB_DQS_DP<1>")
	)
	(segment
		(start 388.195058 -237.939326)
		(end 388.302754 -237.83163)
		(width 0.088646)
		(layer "F.Cu")
		(net "M_E_CPU0_SB_DQS_DP<1>")
	)
	(segment
		(start 413.2707 -219.134944)
		(end 412.87573 -219.529914)
		(width 0.20066)
		(layer "F.Cu")
		(net "M_E_CPU0_SB_DQS_DP<1>")
	)
	(segment
		(start 407.342594 -219.41663)
		(end 406.753314 -219.41663)
		(width 0.20066)
		(layer "F.Cu")
		(net "M_E_CPU0_SB_DQS_DP<1>")
	)
	(segment
		(start 408.120596 -219.176092)
		(end 407.583132 -219.176092)
		(width 0.20066)
		(layer "F.Cu")
		(net "M_E_CPU0_SB_DQS_DP<1>")
	)
	(segment
		(start 387.581902 -238.38281)
		(end 387.639306 -238.354108)
		(width 0.088646)
		(layer "F.Cu")
		(net "M_E_CPU0_SB_DQS_DP<1>")
	)
	(segment
		(start 405.671528 -219.305886)
		(end 405.782272 -219.41663)
		(width 0.20066)
		(layer "F.Cu")
		(net "M_E_CPU0_SB_DQS_DP<1>")
	)
	(segment
		(start 407.583132 -219.176092)
		(end 407.342594 -219.41663)
		(width 0.20066)
		(layer "F.Cu")
		(net "M_E_CPU0_SB_DQS_DP<1>")
	)
	(segment
		(start 409.831794 -219.85478)
		(end 409.349448 -219.85478)
		(width 0.20066)
		(layer "F.Cu")
		(net "M_E_CPU0_SB_DQS_DP<1>")
	)
	(segment
		(start 404.766018 -219.182188)
		(end 405.054308 -218.893898)
		(width 0.20066)
		(layer "F.Cu")
		(net "M_E_CPU0_SB_DQS_DP<1>")
	)
	(segment
		(start 385.08813 -237.918752)
		(end 385.216908 -238.002064)
		(width 0.088646)
		(layer "F.Cu")
		(net "M_E_CPU0_SB_DQS_DP<1>")
	)
	(segment
		(start 388.302754 -237.83163)
		(end 388.302754 -237.691168)
		(width 0.088646)
		(layer "F.Cu")
		(net "M_E_CPU0_SB_DQS_DP<1>")
	)
	(segment
		(start 404.24608 -220.575378)
		(end 404.24608 -220.399356)
		(width 0.20066)
		(layer "F.Cu")
		(net "M_E_CPU0_SB_DQS_DP<1>")
	)
	(segment
		(start 400.905726 -226.018852)
		(end 401.081748 -226.018852)
		(width 0.20066)
		(layer "F.Cu")
		(net "M_E_CPU0_SB_DQS_DP<1>")
	)
	(segment
		(start 387.698234 -238.29518)
		(end 387.839204 -238.29518)
		(width 0.088646)
		(layer "F.Cu")
		(net "M_E_CPU0_SB_DQS_DP<1>")
	)
	(segment
		(start 401.507706 -225.592894)
		(end 401.507706 -225.416872)
		(width 0.20066)
		(layer "F.Cu")
		(net "M_E_CPU0_SB_DQS_DP<1>")
	)
	(segment
		(start 387.156198 -238.493046)
		(end 387.41858 -238.450628)
		(width 0.088646)
		(layer "F.Cu")
		(net "M_E_CPU0_SB_DQS_DP<1>")
	)
	(segment
		(start 399.452846 -227.471732)
		(end 399.878296 -227.046282)
		(width 0.20066)
		(layer "F.Cu")
		(net "M_E_CPU0_SB_DQS_DP<1>")
	)
	(segment
		(start 402.767038 -222.05442)
		(end 403.192996 -221.628462)
		(width 0.20066)
		(layer "F.Cu")
		(net "M_E_CPU0_SB_DQS_DP<1>")
	)
	(segment
		(start 402.287232 -223.433386)
		(end 402.162772 -223.308926)
		(width 0.20066)
		(layer "F.Cu")
		(net "M_E_CPU0_SB_DQS_DP<1>")
	)
	(segment
		(start 401.507706 -225.416872)
		(end 402.162772 -224.761806)
		(width 0.20066)
		(layer "F.Cu")
		(net "M_E_CPU0_SB_DQS_DP<1>")
	)
	(segment
		(start 405.671528 -219.092272)
		(end 405.671528 -219.305886)
		(width 0.20066)
		(layer "F.Cu")
		(net "M_E_CPU0_SB_DQS_DP<1>")
	)
	(segment
		(start 397.57858 -230.165656)
		(end 397.57858 -229.293674)
		(width 0.1524)
		(layer "F.Cu")
		(net "M_E_CPU0_SB_DQS_DP<1>")
	)
	(segment
		(start 402.162772 -222.482664)
		(end 402.591016 -222.05442)
		(width 0.20066)
		(layer "F.Cu")
		(net "M_E_CPU0_SB_DQS_DP<1>")
	)
	(segment
		(start 408.535124 -219.59062)
		(end 408.120596 -219.176092)
		(width 0.20066)
		(layer "F.Cu")
		(net "M_E_CPU0_SB_DQS_DP<1>")
	)
	(segment
		(start 399.026888 -228.073712)
		(end 399.452846 -227.647754)
		(width 0.20066)
		(layer "F.Cu")
		(net "M_E_CPU0_SB_DQS_DP<1>")
	)
	(segment
		(start 405.054308 -218.893898)
		(end 405.473154 -218.893898)
		(width 0.20066)
		(layer "F.Cu")
		(net "M_E_CPU0_SB_DQS_DP<1>")
	)
	(segment
		(start 388.699756 -237.492286)
		(end 390.25195 -237.492286)
		(width 0.1524)
		(layer "F.Cu")
		(net "M_E_CPU0_SB_DQS_DP<1>")
	)
	(segment
		(start 403.820122 -221.001336)
		(end 404.24608 -220.575378)
		(width 0.20066)
		(layer "F.Cu")
		(net "M_E_CPU0_SB_DQS_DP<1>")
	)
	(segment
		(start 402.162772 -223.308926)
		(end 402.162772 -222.482664)
		(width 0.20066)
		(layer "F.Cu")
		(net "M_E_CPU0_SB_DQS_DP<1>")
	)
	(segment
		(start 401.081748 -226.018852)
		(end 401.507706 -225.592894)
		(width 0.20066)
		(layer "F.Cu")
		(net "M_E_CPU0_SB_DQS_DP<1>")
	)
	(segment
		(start 388.666736 -237.459266)
		(end 388.699756 -237.492286)
		(width 0.088646)
		(layer "F.Cu")
		(net "M_E_CPU0_SB_DQS_DP<1>")
	)
	(segment
		(start 398.294352 -228.577902)
		(end 398.346676 -228.577902)
		(width 0.1524)
		(layer "F.Cu")
		(net "M_E_CPU0_SB_DQS_DP<1>")
	)
	(segment
		(start 409.860496 -219.841826)
		(end 409.847542 -219.85478)
		(width 0.1016)
		(layer "F.Cu")
		(net "M_E_CPU0_SB_DQS_DP<1>")
	)
	(segment
		(start 387.9469 -238.187484)
		(end 387.9469 -238.047022)
		(width 0.088646)
		(layer "F.Cu")
		(net "M_E_CPU0_SB_DQS_DP<1>")
	)
	(segment
		(start 413.748474 -219.41663)
		(end 413.466788 -219.134944)
		(width 0.20066)
		(layer "F.Cu")
		(net "M_E_CPU0_SB_DQS_DP<1>")
	)
	(segment
		(start 403.192996 -221.45244)
		(end 403.6441 -221.001336)
		(width 0.20066)
		(layer "F.Cu")
		(net "M_E_CPU0_SB_DQS_DP<1>")
	)
	(segment
		(start 399.878296 -227.046282)
		(end 400.054318 -227.046282)
		(width 0.20066)
		(layer "F.Cu")
		(net "M_E_CPU0_SB_DQS_DP<1>")
	)
	(segment
		(start 385.50596 -238.341154)
		(end 385.612386 -238.436658)
		(width 0.088646)
		(layer "F.Cu")
		(net "M_E_CPU0_SB_DQS_DP<1>")
	)
	(segment
		(start 403.192996 -221.628462)
		(end 403.192996 -221.45244)
		(width 0.20066)
		(layer "F.Cu")
		(net "M_E_CPU0_SB_DQS_DP<1>")
	)
	(segment
		(start 398.3736 -228.550978)
		(end 398.850866 -228.073712)
		(width 0.20066)
		(layer "F.Cu")
		(net "M_E_CPU0_SB_DQS_DP<1>")
	)
	(arc
		(start 386.230622 -238.406432)
		(mid 386.364815 -238.370386)
		(end 386.4991 -238.406178)
		(width 0.088646)
		(layer "F.Cu")
		(net "M_E_CPU0_SB_DQS_DP<1>")
	)
	(arc
		(start 385.612386 -238.436658)
		(mid 385.894724 -238.512341)
		(end 386.177028 -238.436658)
		(width 0.088646)
		(layer "F.Cu")
		(net "M_E_CPU0_SB_DQS_DP<1>")
	)
	(arc
		(start 386.4991 -238.406178)
		(mid 386.655313 -238.470915)
		(end 386.82295 -238.493046)
		(width 0.088646)
		(layer "F.Cu")
		(net "M_E_CPU0_SB_DQS_DP<1>")
	)
	(arc
		(start 387.41858 -238.450628)
		(mid 387.501455 -238.419643)
		(end 387.581902 -238.38281)
		(width 0.088646)
		(layer "F.Cu")
		(net "M_E_CPU0_SB_DQS_DP<1>")
	)
	(segment
		(start 408.151838 -228.526086)
		(end 407.583132 -228.526086)
		(width 0.20066)
		(layer "F.Cu")
		(net "M_E_CPU0_SB_DQS_DP<0>")
	)
	(segment
		(start 413.256476 -228.492558)
		(end 412.797498 -228.951536)
		(width 0.20066)
		(layer "F.Cu")
		(net "M_E_CPU0_SB_DQS_DP<0>")
	)
	(segment
		(start 412.174436 -229.210616)
		(end 411.863794 -229.210616)
		(width 0.20066)
		(layer "F.Cu")
		(net "M_E_CPU0_SB_DQS_DP<0>")
	)
	(segment
		(start 411.863794 -229.210616)
		(end 411.844998 -229.19182)
		(width 0.1016)
		(layer "F.Cu")
		(net "M_E_CPU0_SB_DQS_DP<0>")
	)
	(segment
		(start 406.753314 -228.766624)
		(end 405.623014 -228.766624)
		(width 0.20066)
		(layer "F.Cu")
		(net "M_E_CPU0_SB_DQS_DP<0>")
	)
	(segment
		(start 413.748474 -228.766624)
		(end 413.474408 -228.492558)
		(width 0.20066)
		(layer "F.Cu")
		(net "M_E_CPU0_SB_DQS_DP<0>")
	)
	(segment
		(start 407.342594 -228.766624)
		(end 406.753314 -228.766624)
		(width 0.20066)
		(layer "F.Cu")
		(net "M_E_CPU0_SB_DQS_DP<0>")
	)
	(segment
		(start 408.566366 -228.940614)
		(end 408.151838 -228.526086)
		(width 0.20066)
		(layer "F.Cu")
		(net "M_E_CPU0_SB_DQS_DP<0>")
	)
	(segment
		(start 409.642056 -229.19182)
		(end 409.535122 -229.19182)
		(width 0.20066)
		(layer "F.Cu")
		(net "M_E_CPU0_SB_DQS_DP<0>")
	)
	(segment
		(start 409.535122 -229.19182)
		(end 409.283916 -228.940614)
		(width 0.20066)
		(layer "F.Cu")
		(net "M_E_CPU0_SB_DQS_DP<0>")
	)
	(segment
		(start 409.283916 -228.940614)
		(end 408.566366 -228.940614)
		(width 0.20066)
		(layer "F.Cu")
		(net "M_E_CPU0_SB_DQS_DP<0>")
	)
	(segment
		(start 412.433516 -228.951536)
		(end 412.174436 -229.210616)
		(width 0.20066)
		(layer "F.Cu")
		(net "M_E_CPU0_SB_DQS_DP<0>")
	)
	(segment
		(start 413.474408 -228.492558)
		(end 413.256476 -228.492558)
		(width 0.20066)
		(layer "F.Cu")
		(net "M_E_CPU0_SB_DQS_DP<0>")
	)
	(segment
		(start 409.648152 -229.19182)
		(end 409.642056 -229.19182)
		(width 0.101854)
		(layer "F.Cu")
		(net "M_E_CPU0_SB_DQS_DP<0>")
	)
	(segment
		(start 414.297114 -228.766624)
		(end 413.748474 -228.766624)
		(width 0.20066)
		(layer "F.Cu")
		(net "M_E_CPU0_SB_DQS_DP<0>")
	)
	(segment
		(start 412.797498 -228.951536)
		(end 412.433516 -228.951536)
		(width 0.20066)
		(layer "F.Cu")
		(net "M_E_CPU0_SB_DQS_DP<0>")
	)
	(segment
		(start 407.583132 -228.526086)
		(end 407.342594 -228.766624)
		(width 0.20066)
		(layer "F.Cu")
		(net "M_E_CPU0_SB_DQS_DP<0>")
	)
	(segment
		(start 380.725934 -235.506006)
		(end 380.72568 -235.505752)
		(width 0.20066)
		(layer "F.Cu")
		(net "M_E_CPU0_SB_DQS_DP<0>")
	)
	(segment
		(start 380.72568 -235.505752)
		(end 380.72568 -234.970066)
		(width 0.20066)
		(layer "F.Cu")
		(net "M_E_CPU0_SB_DQS_DP<0>")
	)
	(segment
		(start 411.844998 -229.19182)
		(end 409.648152 -229.19182)
		(width 0.1016)
		(layer "F.Cu")
		(net "M_E_CPU0_SB_DQS_DP<0>")
	)
	(segment
		(start 405.336502 -228.480112)
		(end 404.475188 -228.480112)
		(width 0.18288)
		(layer "In2.Cu")
		(net "M_E_CPU0_SB_DQS_DP<0>")
	)
	(segment
		(start 388.57682 -235.10748)
		(end 388.06501 -235.10748)
		(width 0.088646)
		(layer "In2.Cu")
		(net "M_E_CPU0_SB_DQS_DP<0>")
	)
	(segment
		(start 385.156964 -235.46816)
		(end 385.142232 -235.459524)
		(width 0.088646)
		(layer "In2.Cu")
		(net "M_E_CPU0_SB_DQS_DP<0>")
	)
	(segment
		(start 386.096764 -235.46816)
		(end 386.082032 -235.459524)
		(width 0.088646)
		(layer "In2.Cu")
		(net "M_E_CPU0_SB_DQS_DP<0>")
	)
	(segment
		(start 388.636764 -235.167424)
		(end 388.57682 -235.10748)
		(width 0.088646)
		(layer "In2.Cu")
		(net "M_E_CPU0_SB_DQS_DP<0>")
	)
	(segment
		(start 381.383032 -235.459524)
		(end 381.37084 -235.452412)
		(width 0.088646)
		(layer "In2.Cu")
		(net "M_E_CPU0_SB_DQS_DP<0>")
	)
	(segment
		(start 398.548098 -234.407202)
		(end 396.712948 -235.167424)
		(width 0.18288)
		(layer "In2.Cu")
		(net "M_E_CPU0_SB_DQS_DP<0>")
	)
	(segment
		(start 381.10414 -235.035598)
		(end 381.038608 -234.970066)
		(width 0.088646)
		(layer "In2.Cu")
		(net "M_E_CPU0_SB_DQS_DP<0>")
	)
	(segment
		(start 405.623014 -228.766624)
		(end 405.336502 -228.480112)
		(width 0.18288)
		(layer "In2.Cu")
		(net "M_E_CPU0_SB_DQS_DP<0>")
	)
	(segment
		(start 384.217164 -235.46816)
		(end 384.202432 -235.459524)
		(width 0.088646)
		(layer "In2.Cu")
		(net "M_E_CPU0_SB_DQS_DP<0>")
	)
	(segment
		(start 388.06501 -235.10748)
		(end 387.637274 -235.535216)
		(width 0.088646)
		(layer "In2.Cu")
		(net "M_E_CPU0_SB_DQS_DP<0>")
	)
	(segment
		(start 387.637274 -235.535216)
		(end 387.304026 -235.535216)
		(width 0.088646)
		(layer "In2.Cu")
		(net "M_E_CPU0_SB_DQS_DP<0>")
	)
	(segment
		(start 381.038608 -234.970066)
		(end 380.72568 -234.970066)
		(width 0.088646)
		(layer "In2.Cu")
		(net "M_E_CPU0_SB_DQS_DP<0>")
	)
	(segment
		(start 404.475188 -228.480112)
		(end 398.548098 -234.407202)
		(width 0.18288)
		(layer "In2.Cu")
		(net "M_E_CPU0_SB_DQS_DP<0>")
	)
	(segment
		(start 396.712948 -235.167424)
		(end 388.636764 -235.167424)
		(width 0.18288)
		(layer "In2.Cu")
		(net "M_E_CPU0_SB_DQS_DP<0>")
	)
	(arc
		(start 381.948436 -235.459524)
		(mid 381.665734 -235.5353)
		(end 381.383032 -235.459524)
		(width 0.088646)
		(layer "In2.Cu")
		(net "M_E_CPU0_SB_DQS_DP<0>")
	)
	(arc
		(start 384.767836 -235.459524)
		(mid 384.493637 -235.535359)
		(end 384.217164 -235.46816)
		(width 0.088646)
		(layer "In2.Cu")
		(net "M_E_CPU0_SB_DQS_DP<0>")
	)
	(arc
		(start 386.647436 -235.459524)
		(mid 386.373237 -235.535359)
		(end 386.096764 -235.46816)
		(width 0.088646)
		(layer "In2.Cu")
		(net "M_E_CPU0_SB_DQS_DP<0>")
	)
	(arc
		(start 387.304026 -235.535216)
		(mid 387.157945 -235.515942)
		(end 387.021832 -235.459524)
		(width 0.088646)
		(layer "In2.Cu")
		(net "M_E_CPU0_SB_DQS_DP<0>")
	)
	(arc
		(start 383.262632 -235.459524)
		(mid 383.075434 -235.409381)
		(end 382.888236 -235.459524)
		(width 0.088646)
		(layer "In2.Cu")
		(net "M_E_CPU0_SB_DQS_DP<0>")
	)
	(arc
		(start 382.888236 -235.459524)
		(mid 382.605534 -235.5353)
		(end 382.322832 -235.459524)
		(width 0.088646)
		(layer "In2.Cu")
		(net "M_E_CPU0_SB_DQS_DP<0>")
	)
	(arc
		(start 382.322832 -235.459524)
		(mid 382.135634 -235.409381)
		(end 381.948436 -235.459524)
		(width 0.088646)
		(layer "In2.Cu")
		(net "M_E_CPU0_SB_DQS_DP<0>")
	)
	(arc
		(start 386.082032 -235.459524)
		(mid 385.894834 -235.409381)
		(end 385.707636 -235.459524)
		(width 0.088646)
		(layer "In2.Cu")
		(net "M_E_CPU0_SB_DQS_DP<0>")
	)
	(arc
		(start 383.828036 -235.459524)
		(mid 383.545334 -235.5353)
		(end 383.262632 -235.459524)
		(width 0.088646)
		(layer "In2.Cu")
		(net "M_E_CPU0_SB_DQS_DP<0>")
	)
	(arc
		(start 385.142232 -235.459524)
		(mid 384.955034 -235.409381)
		(end 384.767836 -235.459524)
		(width 0.088646)
		(layer "In2.Cu")
		(net "M_E_CPU0_SB_DQS_DP<0>")
	)
	(arc
		(start 381.37084 -235.452412)
		(mid 381.195238 -235.28352)
		(end 381.106934 -235.056426)
		(width 0.088646)
		(layer "In2.Cu")
		(net "M_E_CPU0_SB_DQS_DP<0>")
	)
	(arc
		(start 384.202432 -235.459524)
		(mid 384.015234 -235.409381)
		(end 383.828036 -235.459524)
		(width 0.088646)
		(layer "In2.Cu")
		(net "M_E_CPU0_SB_DQS_DP<0>")
	)
	(arc
		(start 387.021832 -235.459524)
		(mid 386.834634 -235.409381)
		(end 386.647436 -235.459524)
		(width 0.088646)
		(layer "In2.Cu")
		(net "M_E_CPU0_SB_DQS_DP<0>")
	)
	(arc
		(start 385.707636 -235.459524)
		(mid 385.433437 -235.535359)
		(end 385.156964 -235.46816)
		(width 0.088646)
		(layer "In2.Cu")
		(net "M_E_CPU0_SB_DQS_DP<0>")
	)
	(arc
		(start 381.106934 -235.056426)
		(mid 381.10544 -235.046025)
		(end 381.10414 -235.035598)
		(width 0.088646)
		(layer "In2.Cu")
		(net "M_E_CPU0_SB_DQS_DP<0>")
	)
	(segment
		(start 407.301954 -237.266734)
		(end 407.58364 -237.54842)
		(width 0.20066)
		(layer "F.Cu")
		(net "M_E_CPU0_SB_DQS_DN<9>")
	)
	(segment
		(start 388.561072 -242.353592)
		(end 388.561072 -242.308634)
		(width 0.088646)
		(layer "F.Cu")
		(net "M_E_CPU0_SB_DQS_DN<9>")
	)
	(segment
		(start 386.859272 -243.205762)
		(end 387.139434 -243.205762)
		(width 0.088646)
		(layer "F.Cu")
		(net "M_E_CPU0_SB_DQS_DN<9>")
	)
	(segment
		(start 395.901164 -237.901734)
		(end 404.122382 -237.901734)
		(width 0.20066)
		(layer "F.Cu")
		(net "M_E_CPU0_SB_DQS_DN<9>")
	)
	(segment
		(start 385.141978 -242.506754)
		(end 385.171188 -242.523772)
		(width 0.088646)
		(layer "F.Cu")
		(net "M_E_CPU0_SB_DQS_DN<9>")
	)
	(segment
		(start 406.75306 -237.266988)
		(end 406.753314 -237.266734)
		(width 0.20066)
		(layer "F.Cu")
		(net "M_E_CPU0_SB_DQS_DN<9>")
	)
	(segment
		(start 412.278576 -237.691676)
		(end 412.410656 -237.691676)
		(width 0.20066)
		(layer "F.Cu")
		(net "M_E_CPU0_SB_DQS_DN<9>")
	)
	(segment
		(start 413.2453 -237.571534)
		(end 413.47517 -237.571534)
		(width 0.20066)
		(layer "F.Cu")
		(net "M_E_CPU0_SB_DQS_DN<9>")
	)
	(segment
		(start 411.842966 -237.691676)
		(end 412.278576 -237.691676)
		(width 0.101854)
		(layer "F.Cu")
		(net "M_E_CPU0_SB_DQS_DN<9>")
	)
	(segment
		(start 394.88618 -238.087408)
		(end 394.88618 -238.087154)
		(width 0.1524)
		(layer "F.Cu")
		(net "M_E_CPU0_SB_DQS_DN<9>")
	)
	(segment
		(start 386.859018 -243.206016)
		(end 386.859272 -243.205762)
		(width 0.088646)
		(layer "F.Cu")
		(net "M_E_CPU0_SB_DQS_DN<9>")
	)
	(segment
		(start 408.857958 -237.949994)
		(end 409.073604 -237.949994)
		(width 0.20066)
		(layer "F.Cu")
		(net "M_E_CPU0_SB_DQS_DN<9>")
	)
	(segment
		(start 387.424676 -242.92052)
		(end 387.994144 -242.92052)
		(width 0.088646)
		(layer "F.Cu")
		(net "M_E_CPU0_SB_DQS_DN<9>")
	)
	(segment
		(start 395.035024 -237.938564)
		(end 395.826234 -237.938564)
		(width 0.1524)
		(layer "F.Cu")
		(net "M_E_CPU0_SB_DQS_DN<9>")
	)
	(segment
		(start 409.42768 -237.674912)
		(end 409.444444 -237.691676)
		(width 0.101854)
		(layer "F.Cu")
		(net "M_E_CPU0_SB_DQS_DN<9>")
	)
	(segment
		(start 413.77997 -237.266734)
		(end 414.297114 -237.266734)
		(width 0.20066)
		(layer "F.Cu")
		(net "M_E_CPU0_SB_DQS_DN<9>")
	)
	(segment
		(start 391.822432 -241.151156)
		(end 394.88618 -238.087408)
		(width 0.1524)
		(layer "F.Cu")
		(net "M_E_CPU0_SB_DQS_DN<9>")
	)
	(segment
		(start 384.015234 -242.831112)
		(end 384.738118 -242.523772)
		(width 0.088646)
		(layer "F.Cu")
		(net "M_E_CPU0_SB_DQS_DN<9>")
	)
	(segment
		(start 394.88618 -238.087154)
		(end 394.886434 -238.087154)
		(width 0.1524)
		(layer "F.Cu")
		(net "M_E_CPU0_SB_DQS_DN<9>")
	)
	(segment
		(start 409.073604 -237.949994)
		(end 409.348686 -237.674912)
		(width 0.20066)
		(layer "F.Cu")
		(net "M_E_CPU0_SB_DQS_DN<9>")
	)
	(segment
		(start 412.610554 -237.891574)
		(end 412.92526 -237.891574)
		(width 0.20066)
		(layer "F.Cu")
		(net "M_E_CPU0_SB_DQS_DN<9>")
	)
	(segment
		(start 407.58364 -237.54842)
		(end 408.456384 -237.54842)
		(width 0.20066)
		(layer "F.Cu")
		(net "M_E_CPU0_SB_DQS_DN<9>")
	)
	(segment
		(start 412.410656 -237.691676)
		(end 412.610554 -237.891574)
		(width 0.20066)
		(layer "F.Cu")
		(net "M_E_CPU0_SB_DQS_DN<9>")
	)
	(segment
		(start 404.122382 -237.901734)
		(end 404.757128 -237.266988)
		(width 0.20066)
		(layer "F.Cu")
		(net "M_E_CPU0_SB_DQS_DN<9>")
	)
	(segment
		(start 395.826234 -237.938564)
		(end 395.863064 -237.901734)
		(width 0.1524)
		(layer "F.Cu")
		(net "M_E_CPU0_SB_DQS_DN<9>")
	)
	(segment
		(start 385.14147 -242.506754)
		(end 385.141978 -242.506754)
		(width 0.088646)
		(layer "F.Cu")
		(net "M_E_CPU0_SB_DQS_DN<9>")
	)
	(segment
		(start 408.456384 -237.54842)
		(end 408.857958 -237.949994)
		(width 0.20066)
		(layer "F.Cu")
		(net "M_E_CPU0_SB_DQS_DN<9>")
	)
	(segment
		(start 385.448556 -242.80114)
		(end 385.517644 -242.92052)
		(width 0.088646)
		(layer "F.Cu")
		(net "M_E_CPU0_SB_DQS_DN<9>")
	)
	(segment
		(start 385.707382 -243.155216)
		(end 385.707382 -243.155724)
		(width 0.088646)
		(layer "F.Cu")
		(net "M_E_CPU0_SB_DQS_DN<9>")
	)
	(segment
		(start 412.92526 -237.891574)
		(end 413.2453 -237.571534)
		(width 0.20066)
		(layer "F.Cu")
		(net "M_E_CPU0_SB_DQS_DN<9>")
	)
	(segment
		(start 386.83438 -243.206016)
		(end 386.859018 -243.206016)
		(width 0.088646)
		(layer "F.Cu")
		(net "M_E_CPU0_SB_DQS_DN<9>")
	)
	(segment
		(start 409.348686 -237.674912)
		(end 409.42768 -237.674912)
		(width 0.20066)
		(layer "F.Cu")
		(net "M_E_CPU0_SB_DQS_DN<9>")
	)
	(segment
		(start 388.561072 -242.308634)
		(end 388.576566 -242.29314)
		(width 0.088646)
		(layer "F.Cu")
		(net "M_E_CPU0_SB_DQS_DN<9>")
	)
	(segment
		(start 394.886434 -238.087154)
		(end 395.035024 -237.938564)
		(width 0.1524)
		(layer "F.Cu")
		(net "M_E_CPU0_SB_DQS_DN<9>")
	)
	(segment
		(start 413.47517 -237.571534)
		(end 413.77997 -237.266734)
		(width 0.20066)
		(layer "F.Cu")
		(net "M_E_CPU0_SB_DQS_DN<9>")
	)
	(segment
		(start 388.576566 -242.29314)
		(end 389.71855 -241.151156)
		(width 0.1524)
		(layer "F.Cu")
		(net "M_E_CPU0_SB_DQS_DN<9>")
	)
	(segment
		(start 409.444444 -237.691676)
		(end 409.853384 -237.691676)
		(width 0.101854)
		(layer "F.Cu")
		(net "M_E_CPU0_SB_DQS_DN<9>")
	)
	(segment
		(start 384.738118 -242.523772)
		(end 384.767582 -242.5065)
		(width 0.088646)
		(layer "F.Cu")
		(net "M_E_CPU0_SB_DQS_DN<9>")
	)
	(segment
		(start 387.994144 -242.92052)
		(end 388.561072 -242.353592)
		(width 0.088646)
		(layer "F.Cu")
		(net "M_E_CPU0_SB_DQS_DN<9>")
	)
	(segment
		(start 395.863064 -237.901734)
		(end 395.901164 -237.901734)
		(width 0.1524)
		(layer "F.Cu")
		(net "M_E_CPU0_SB_DQS_DN<9>")
	)
	(segment
		(start 404.757128 -237.266988)
		(end 406.75306 -237.266988)
		(width 0.20066)
		(layer "F.Cu")
		(net "M_E_CPU0_SB_DQS_DN<9>")
	)
	(segment
		(start 406.753314 -237.266734)
		(end 407.301954 -237.266734)
		(width 0.20066)
		(layer "F.Cu")
		(net "M_E_CPU0_SB_DQS_DN<9>")
	)
	(segment
		(start 384.015234 -242.830858)
		(end 384.015234 -242.831112)
		(width 0.088646)
		(layer "F.Cu")
		(net "M_E_CPU0_SB_DQS_DN<9>")
	)
	(segment
		(start 409.853384 -237.691676)
		(end 411.842966 -237.691676)
		(width 0.1016)
		(layer "F.Cu")
		(net "M_E_CPU0_SB_DQS_DN<9>")
	)
	(segment
		(start 389.71855 -241.151156)
		(end 391.822432 -241.151156)
		(width 0.1524)
		(layer "F.Cu")
		(net "M_E_CPU0_SB_DQS_DN<9>")
	)
	(segment
		(start 387.139434 -243.205762)
		(end 387.424676 -242.92052)
		(width 0.088646)
		(layer "F.Cu")
		(net "M_E_CPU0_SB_DQS_DN<9>")
	)
	(arc
		(start 385.572254 -243.02212)
		(mid 385.631268 -243.097342)
		(end 385.707382 -243.155216)
		(width 0.088646)
		(layer "F.Cu")
		(net "M_E_CPU0_SB_DQS_DN<9>")
	)
	(arc
		(start 385.559808 -242.99926)
		(mid 385.565831 -243.010799)
		(end 385.572254 -243.02212)
		(width 0.088646)
		(layer "F.Cu")
		(net "M_E_CPU0_SB_DQS_DN<9>")
	)
	(arc
		(start 385.171188 -242.523772)
		(mid 385.328093 -242.644235)
		(end 385.448556 -242.80114)
		(width 0.088646)
		(layer "F.Cu")
		(net "M_E_CPU0_SB_DQS_DN<9>")
	)
	(arc
		(start 384.767582 -242.5065)
		(mid 384.954555 -242.456577)
		(end 385.14147 -242.506754)
		(width 0.088646)
		(layer "F.Cu")
		(net "M_E_CPU0_SB_DQS_DN<9>")
	)
	(arc
		(start 385.707382 -243.155724)
		(mid 385.894978 -243.206053)
		(end 386.08254 -243.155724)
		(width 0.088646)
		(layer "F.Cu")
		(net "M_E_CPU0_SB_DQS_DN<9>")
	)
	(arc
		(start 385.517644 -242.92052)
		(mid 385.539308 -242.959578)
		(end 385.559808 -242.99926)
		(width 0.088646)
		(layer "F.Cu")
		(net "M_E_CPU0_SB_DQS_DN<9>")
	)
	(arc
		(start 386.646928 -243.155724)
		(mid 386.737338 -243.193234)
		(end 386.83438 -243.206016)
		(width 0.088646)
		(layer "F.Cu")
		(net "M_E_CPU0_SB_DQS_DN<9>")
	)
	(arc
		(start 386.08254 -243.155724)
		(mid 386.364734 -243.080168)
		(end 386.646928 -243.155724)
		(width 0.088646)
		(layer "F.Cu")
		(net "M_E_CPU0_SB_DQS_DN<9>")
	)
	(segment
		(start 413.286448 -199.441816)
		(end 413.280352 -199.447912)
		(width 0.1016)
		(layer "F.Cu")
		(net "M_E_CPU0_SB_DQS_DN<8>")
	)
	(segment
		(start 389.14578 -213.714838)
		(end 388.945882 -212.706458)
		(width 0.1524)
		(layer "F.Cu")
		(net "M_E_CPU0_SB_DQS_DN<8>")
	)
	(segment
		(start 405.453342 -199.462644)
		(end 405.731726 -199.462644)
		(width 0.20066)
		(layer "F.Cu")
		(net "M_E_CPU0_SB_DQS_DN<8>")
	)
	(segment
		(start 400.970242 -199.827896)
		(end 401.572222 -199.827896)
		(width 0.20066)
		(layer "F.Cu")
		(net "M_E_CPU0_SB_DQS_DN<8>")
	)
	(segment
		(start 410.075888 -199.595232)
		(end 410.347414 -199.866758)
		(width 0.20066)
		(layer "F.Cu")
		(net "M_E_CPU0_SB_DQS_DN<8>")
	)
	(segment
		(start 417.8935 -199.866758)
		(end 417.639246 -199.612504)
		(width 0.20066)
		(layer "F.Cu")
		(net "M_E_CPU0_SB_DQS_DN<8>")
	)
	(segment
		(start 388.437374 -211.479892)
		(end 388.437374 -211.222336)
		(width 0.1524)
		(layer "F.Cu")
		(net "M_E_CPU0_SB_DQS_DN<8>")
	)
	(segment
		(start 390.062212 -205.185264)
		(end 390.48817 -204.759306)
		(width 0.20066)
		(layer "F.Cu")
		(net "M_E_CPU0_SB_DQS_DN<8>")
	)
	(segment
		(start 391.5156 -203.731876)
		(end 391.5156 -203.555854)
		(width 0.20066)
		(layer "F.Cu")
		(net "M_E_CPU0_SB_DQS_DN<8>")
	)
	(segment
		(start 388.437374 -211.222336)
		(end 388.474204 -211.185506)
		(width 0.1524)
		(layer "F.Cu")
		(net "M_E_CPU0_SB_DQS_DN<8>")
	)
	(segment
		(start 389.2169 -206.455264)
		(end 389.641588 -205.429866)
		(width 0.20066)
		(layer "F.Cu")
		(net "M_E_CPU0_SB_DQS_DN<8>")
	)
	(segment
		(start 398.064482 -199.827896)
		(end 398.666462 -199.827896)
		(width 0.20066)
		(layer "F.Cu")
		(net "M_E_CPU0_SB_DQS_DN<8>")
	)
	(segment
		(start 411.383988 -199.866758)
		(end 410.853382 -199.866758)
		(width 0.20066)
		(layer "F.Cu")
		(net "M_E_CPU0_SB_DQS_DN<8>")
	)
	(segment
		(start 392.858752 -202.734672)
		(end 394.073634 -202.734672)
		(width 0.20066)
		(layer "F.Cu")
		(net "M_E_CPU0_SB_DQS_DN<8>")
	)
	(segment
		(start 397.940022 -199.703436)
		(end 398.064482 -199.827896)
		(width 0.20066)
		(layer "F.Cu")
		(net "M_E_CPU0_SB_DQS_DN<8>")
	)
	(segment
		(start 412.96336 -199.447912)
		(end 412.685992 -199.170544)
		(width 0.20066)
		(layer "F.Cu")
		(net "M_E_CPU0_SB_DQS_DN<8>")
	)
	(segment
		(start 388.474204 -211.185506)
		(end 388.474204 -211.147406)
		(width 0.1524)
		(layer "F.Cu")
		(net "M_E_CPU0_SB_DQS_DN<8>")
	)
	(segment
		(start 388.237222 -227.44938)
		(end 388.282434 -227.44938)
		(width 0.088646)
		(layer "F.Cu")
		(net "M_E_CPU0_SB_DQS_DN<8>")
	)
	(segment
		(start 399.392902 -199.703436)
		(end 399.517362 -199.827896)
		(width 0.20066)
		(layer "F.Cu")
		(net "M_E_CPU0_SB_DQS_DN<8>")
	)
	(segment
		(start 405.731726 -199.462644)
		(end 405.736552 -199.462644)
		(width 0.101854)
		(layer "F.Cu")
		(net "M_E_CPU0_SB_DQS_DN<8>")
	)
	(segment
		(start 390.91362 -204.157834)
		(end 391.089642 -204.157834)
		(width 0.20066)
		(layer "F.Cu")
		(net "M_E_CPU0_SB_DQS_DN<8>")
	)
	(segment
		(start 400.119342 -199.827896)
		(end 400.243802 -199.703436)
		(width 0.20066)
		(layer "F.Cu")
		(net "M_E_CPU0_SB_DQS_DN<8>")
	)
	(segment
		(start 391.5156 -203.555854)
		(end 391.96772 -203.103734)
		(width 0.20066)
		(layer "F.Cu")
		(net "M_E_CPU0_SB_DQS_DN<8>")
	)
	(segment
		(start 409.8036 -199.595232)
		(end 410.075888 -199.595232)
		(width 0.20066)
		(layer "F.Cu")
		(net "M_E_CPU0_SB_DQS_DN<8>")
	)
	(segment
		(start 394.073634 -202.734672)
		(end 394.709904 -202.471274)
		(width 0.20066)
		(layer "F.Cu")
		(net "M_E_CPU0_SB_DQS_DN<8>")
	)
	(segment
		(start 395.384528 -201.972672)
		(end 395.810486 -201.546714)
		(width 0.20066)
		(layer "F.Cu")
		(net "M_E_CPU0_SB_DQS_DN<8>")
	)
	(segment
		(start 412.563564 -199.170544)
		(end 412.138622 -199.595486)
		(width 0.20066)
		(layer "F.Cu")
		(net "M_E_CPU0_SB_DQS_DN<8>")
	)
	(segment
		(start 407.7462 -199.441562)
		(end 407.763726 -199.459088)
		(width 0.1016)
		(layer "F.Cu")
		(net "M_E_CPU0_SB_DQS_DN<8>")
	)
	(segment
		(start 397.477742 -199.703436)
		(end 397.940022 -199.703436)
		(width 0.20066)
		(layer "F.Cu")
		(net "M_E_CPU0_SB_DQS_DN<8>")
	)
	(segment
		(start 418.397182 -199.866758)
		(end 417.8935 -199.866758)
		(width 0.20066)
		(layer "F.Cu")
		(net "M_E_CPU0_SB_DQS_DN<8>")
	)
	(segment
		(start 388.891018 -207.241648)
		(end 389.053578 -207.174338)
		(width 0.20066)
		(layer "F.Cu")
		(net "M_E_CPU0_SB_DQS_DN<8>")
	)
	(segment
		(start 403.025102 -199.827896)
		(end 403.149562 -199.703436)
		(width 0.20066)
		(layer "F.Cu")
		(net "M_E_CPU0_SB_DQS_DN<8>")
	)
	(segment
		(start 412.685992 -199.170544)
		(end 412.563564 -199.170544)
		(width 0.20066)
		(layer "F.Cu")
		(net "M_E_CPU0_SB_DQS_DN<8>")
	)
	(segment
		(start 388.738872 -207.608932)
		(end 388.891018 -207.241648)
		(width 0.20066)
		(layer "F.Cu")
		(net "M_E_CPU0_SB_DQS_DN<8>")
	)
	(segment
		(start 388.474204 -210.16595)
		(end 388.598664 -210.04149)
		(width 0.20066)
		(layer "F.Cu")
		(net "M_E_CPU0_SB_DQS_DN<8>")
	)
	(segment
		(start 416.402012 -199.166988)
		(end 415.912046 -199.166988)
		(width 0.20066)
		(layer "F.Cu")
		(net "M_E_CPU0_SB_DQS_DN<8>")
	)
	(segment
		(start 415.296604 -199.441816)
		(end 413.286448 -199.441816)
		(width 0.1016)
		(layer "F.Cu")
		(net "M_E_CPU0_SB_DQS_DN<8>")
	)
	(segment
		(start 401.696682 -199.703436)
		(end 402.298662 -199.703436)
		(width 0.20066)
		(layer "F.Cu")
		(net "M_E_CPU0_SB_DQS_DN<8>")
	)
	(segment
		(start 408.351482 -199.196198)
		(end 408.84094 -199.196198)
		(width 0.20066)
		(layer "F.Cu")
		(net "M_E_CPU0_SB_DQS_DN<8>")
	)
	(segment
		(start 411.65526 -199.595486)
		(end 411.383988 -199.866758)
		(width 0.20066)
		(layer "F.Cu")
		(net "M_E_CPU0_SB_DQS_DN<8>")
	)
	(segment
		(start 389.053578 -207.174338)
		(end 389.28421 -206.617824)
		(width 0.20066)
		(layer "F.Cu")
		(net "M_E_CPU0_SB_DQS_DN<8>")
	)
	(segment
		(start 389.641588 -205.429866)
		(end 389.88619 -205.185264)
		(width 0.20066)
		(layer "F.Cu")
		(net "M_E_CPU0_SB_DQS_DN<8>")
	)
	(segment
		(start 405.138128 -199.14743)
		(end 405.453342 -199.462644)
		(width 0.20066)
		(layer "F.Cu")
		(net "M_E_CPU0_SB_DQS_DN<8>")
	)
	(segment
		(start 396.235936 -200.945242)
		(end 396.411958 -200.945242)
		(width 0.20066)
		(layer "F.Cu")
		(net "M_E_CPU0_SB_DQS_DN<8>")
	)
	(segment
		(start 405.757634 -199.441562)
		(end 407.7462 -199.441562)
		(width 0.1016)
		(layer "F.Cu")
		(net "M_E_CPU0_SB_DQS_DN<8>")
	)
	(segment
		(start 388.297928 -227.433886)
		(end 389.14578 -226.586034)
		(width 0.1524)
		(layer "F.Cu")
		(net "M_E_CPU0_SB_DQS_DN<8>")
	)
	(segment
		(start 403.561296 -199.703436)
		(end 404.903178 -199.14743)
		(width 0.20066)
		(layer "F.Cu")
		(net "M_E_CPU0_SB_DQS_DN<8>")
	)
	(segment
		(start 389.28421 -206.617824)
		(end 389.2169 -206.455264)
		(width 0.20066)
		(layer "F.Cu")
		(net "M_E_CPU0_SB_DQS_DN<8>")
	)
	(segment
		(start 388.474204 -208.938368)
		(end 388.738872 -207.608932)
		(width 0.20066)
		(layer "F.Cu")
		(net "M_E_CPU0_SB_DQS_DN<8>")
	)
	(segment
		(start 388.474204 -211.147406)
		(end 388.474204 -210.16595)
		(width 0.20066)
		(layer "F.Cu")
		(net "M_E_CPU0_SB_DQS_DN<8>")
	)
	(segment
		(start 407.763726 -199.459088)
		(end 408.088592 -199.459088)
		(width 0.20066)
		(layer "F.Cu")
		(net "M_E_CPU0_SB_DQS_DN<8>")
	)
	(segment
		(start 395.810486 -201.370692)
		(end 396.235936 -200.945242)
		(width 0.20066)
		(layer "F.Cu")
		(net "M_E_CPU0_SB_DQS_DN<8>")
	)
	(segment
		(start 388.282434 -227.44938)
		(end 388.297928 -227.433886)
		(width 0.088646)
		(layer "F.Cu")
		(net "M_E_CPU0_SB_DQS_DN<8>")
	)
	(segment
		(start 396.411958 -200.945242)
		(end 396.837916 -200.519284)
		(width 0.20066)
		(layer "F.Cu")
		(net "M_E_CPU0_SB_DQS_DN<8>")
	)
	(segment
		(start 396.837916 -200.343262)
		(end 397.477742 -199.703436)
		(width 0.20066)
		(layer "F.Cu")
		(net "M_E_CPU0_SB_DQS_DN<8>")
	)
	(segment
		(start 398.666462 -199.827896)
		(end 398.790922 -199.703436)
		(width 0.20066)
		(layer "F.Cu")
		(net "M_E_CPU0_SB_DQS_DN<8>")
	)
	(segment
		(start 402.298662 -199.703436)
		(end 402.423122 -199.827896)
		(width 0.20066)
		(layer "F.Cu")
		(net "M_E_CPU0_SB_DQS_DN<8>")
	)
	(segment
		(start 415.626296 -199.452738)
		(end 415.307526 -199.452738)
		(width 0.20066)
		(layer "F.Cu")
		(net "M_E_CPU0_SB_DQS_DN<8>")
	)
	(segment
		(start 391.96772 -203.103734)
		(end 392.858752 -202.734672)
		(width 0.20066)
		(layer "F.Cu")
		(net "M_E_CPU0_SB_DQS_DN<8>")
	)
	(segment
		(start 389.14578 -226.586034)
		(end 389.14578 -213.714838)
		(width 0.1524)
		(layer "F.Cu")
		(net "M_E_CPU0_SB_DQS_DN<8>")
	)
	(segment
		(start 395.810486 -201.546714)
		(end 395.810486 -201.370692)
		(width 0.20066)
		(layer "F.Cu")
		(net "M_E_CPU0_SB_DQS_DN<8>")
	)
	(segment
		(start 400.845782 -199.703436)
		(end 400.970242 -199.827896)
		(width 0.20066)
		(layer "F.Cu")
		(net "M_E_CPU0_SB_DQS_DN<8>")
	)
	(segment
		(start 388.474204 -209.31505)
		(end 388.474204 -208.938368)
		(width 0.20066)
		(layer "F.Cu")
		(net "M_E_CPU0_SB_DQS_DN<8>")
	)
	(segment
		(start 416.847528 -199.612504)
		(end 416.402012 -199.166988)
		(width 0.20066)
		(layer "F.Cu")
		(net "M_E_CPU0_SB_DQS_DN<8>")
	)
	(segment
		(start 390.48817 -204.583284)
		(end 390.91362 -204.157834)
		(width 0.20066)
		(layer "F.Cu")
		(net "M_E_CPU0_SB_DQS_DN<8>")
	)
	(segment
		(start 389.88619 -205.185264)
		(end 390.062212 -205.185264)
		(width 0.20066)
		(layer "F.Cu")
		(net "M_E_CPU0_SB_DQS_DN<8>")
	)
	(segment
		(start 405.736552 -199.462644)
		(end 405.757634 -199.441562)
		(width 0.1016)
		(layer "F.Cu")
		(net "M_E_CPU0_SB_DQS_DN<8>")
	)
	(segment
		(start 390.48817 -204.759306)
		(end 390.48817 -204.583284)
		(width 0.20066)
		(layer "F.Cu")
		(net "M_E_CPU0_SB_DQS_DN<8>")
	)
	(segment
		(start 388.945882 -212.706458)
		(end 388.437374 -211.479892)
		(width 0.1524)
		(layer "F.Cu")
		(net "M_E_CPU0_SB_DQS_DN<8>")
	)
	(segment
		(start 386.836412 -228.179884)
		(end 387.013196 -228.003608)
		(width 0.088646)
		(layer "F.Cu")
		(net "M_E_CPU0_SB_DQS_DN<8>")
	)
	(segment
		(start 410.347414 -199.866758)
		(end 410.853382 -199.866758)
		(width 0.20066)
		(layer "F.Cu")
		(net "M_E_CPU0_SB_DQS_DN<8>")
	)
	(segment
		(start 395.208506 -201.972672)
		(end 395.384528 -201.972672)
		(width 0.20066)
		(layer "F.Cu")
		(net "M_E_CPU0_SB_DQS_DN<8>")
	)
	(segment
		(start 387.013196 -228.003608)
		(end 387.682994 -228.003608)
		(width 0.088646)
		(layer "F.Cu")
		(net "M_E_CPU0_SB_DQS_DN<8>")
	)
	(segment
		(start 391.089642 -204.157834)
		(end 391.5156 -203.731876)
		(width 0.20066)
		(layer "F.Cu")
		(net "M_E_CPU0_SB_DQS_DN<8>")
	)
	(segment
		(start 417.639246 -199.612504)
		(end 416.847528 -199.612504)
		(width 0.20066)
		(layer "F.Cu")
		(net "M_E_CPU0_SB_DQS_DN<8>")
	)
	(segment
		(start 408.088592 -199.459088)
		(end 408.351482 -199.196198)
		(width 0.20066)
		(layer "F.Cu")
		(net "M_E_CPU0_SB_DQS_DN<8>")
	)
	(segment
		(start 394.709904 -202.471274)
		(end 395.208506 -201.972672)
		(width 0.20066)
		(layer "F.Cu")
		(net "M_E_CPU0_SB_DQS_DN<8>")
	)
	(segment
		(start 400.243802 -199.703436)
		(end 400.845782 -199.703436)
		(width 0.20066)
		(layer "F.Cu")
		(net "M_E_CPU0_SB_DQS_DN<8>")
	)
	(segment
		(start 415.307526 -199.452738)
		(end 415.296604 -199.441816)
		(width 0.1016)
		(layer "F.Cu")
		(net "M_E_CPU0_SB_DQS_DN<8>")
	)
	(segment
		(start 413.280352 -199.447912)
		(end 413.275526 -199.447912)
		(width 0.101854)
		(layer "F.Cu")
		(net "M_E_CPU0_SB_DQS_DN<8>")
	)
	(segment
		(start 401.572222 -199.827896)
		(end 401.696682 -199.703436)
		(width 0.20066)
		(layer "F.Cu")
		(net "M_E_CPU0_SB_DQS_DN<8>")
	)
	(segment
		(start 399.517362 -199.827896)
		(end 400.119342 -199.827896)
		(width 0.20066)
		(layer "F.Cu")
		(net "M_E_CPU0_SB_DQS_DN<8>")
	)
	(segment
		(start 388.598664 -209.43951)
		(end 388.474204 -209.31505)
		(width 0.20066)
		(layer "F.Cu")
		(net "M_E_CPU0_SB_DQS_DN<8>")
	)
	(segment
		(start 404.903178 -199.14743)
		(end 405.138128 -199.14743)
		(width 0.20066)
		(layer "F.Cu")
		(net "M_E_CPU0_SB_DQS_DN<8>")
	)
	(segment
		(start 396.837916 -200.519284)
		(end 396.837916 -200.343262)
		(width 0.20066)
		(layer "F.Cu")
		(net "M_E_CPU0_SB_DQS_DN<8>")
	)
	(segment
		(start 413.275526 -199.447912)
		(end 412.96336 -199.447912)
		(width 0.20066)
		(layer "F.Cu")
		(net "M_E_CPU0_SB_DQS_DN<8>")
	)
	(segment
		(start 402.423122 -199.827896)
		(end 403.025102 -199.827896)
		(width 0.20066)
		(layer "F.Cu")
		(net "M_E_CPU0_SB_DQS_DN<8>")
	)
	(segment
		(start 388.598664 -210.04149)
		(end 388.598664 -209.43951)
		(width 0.20066)
		(layer "F.Cu")
		(net "M_E_CPU0_SB_DQS_DN<8>")
	)
	(segment
		(start 415.912046 -199.166988)
		(end 415.626296 -199.452738)
		(width 0.20066)
		(layer "F.Cu")
		(net "M_E_CPU0_SB_DQS_DN<8>")
	)
	(segment
		(start 408.84094 -199.196198)
		(end 409.8036 -199.595232)
		(width 0.20066)
		(layer "F.Cu")
		(net "M_E_CPU0_SB_DQS_DN<8>")
	)
	(segment
		(start 387.682994 -228.003608)
		(end 388.237222 -227.44938)
		(width 0.088646)
		(layer "F.Cu")
		(net "M_E_CPU0_SB_DQS_DN<8>")
	)
	(segment
		(start 412.138622 -199.595486)
		(end 411.65526 -199.595486)
		(width 0.20066)
		(layer "F.Cu")
		(net "M_E_CPU0_SB_DQS_DN<8>")
	)
	(segment
		(start 398.790922 -199.703436)
		(end 399.392902 -199.703436)
		(width 0.20066)
		(layer "F.Cu")
		(net "M_E_CPU0_SB_DQS_DN<8>")
	)
	(segment
		(start 403.149562 -199.703436)
		(end 403.561296 -199.703436)
		(width 0.20066)
		(layer "F.Cu")
		(net "M_E_CPU0_SB_DQS_DN<8>")
	)
	(arc
		(start 386.83438 -228.1809)
		(mid 386.835516 -228.180632)
		(end 386.836412 -228.179884)
		(width 0.088646)
		(layer "F.Cu")
		(net "M_E_CPU0_SB_DQS_DN<8>")
	)
	(segment
		(start 396.621 -212.830664)
		(end 397.046958 -212.404706)
		(width 0.20066)
		(layer "F.Cu")
		(net "M_E_CPU0_SB_DQS_DN<7>")
	)
	(segment
		(start 397.046958 -212.228684)
		(end 397.472408 -211.803234)
		(width 0.20066)
		(layer "F.Cu")
		(net "M_E_CPU0_SB_DQS_DN<7>")
	)
	(segment
		(start 388.362698 -232.885742)
		(end 388.528306 -232.720134)
		(width 0.088646)
		(layer "F.Cu")
		(net "M_E_CPU0_SB_DQS_DN<7>")
	)
	(segment
		(start 386.83438 -232.974896)
		(end 386.923534 -232.885742)
		(width 0.088646)
		(layer "F.Cu")
		(net "M_E_CPU0_SB_DQS_DN<7>")
	)
	(segment
		(start 407.75636 -208.806034)
		(end 407.763726 -208.806034)
		(width 0.101854)
		(layer "F.Cu")
		(net "M_E_CPU0_SB_DQS_DN<7>")
	)
	(segment
		(start 410.117798 -208.97977)
		(end 410.35478 -209.216752)
		(width 0.20066)
		(layer "F.Cu")
		(net "M_E_CPU0_SB_DQS_DN<7>")
	)
	(segment
		(start 396.019528 -213.432136)
		(end 396.019528 -213.256114)
		(width 0.20066)
		(layer "F.Cu")
		(net "M_E_CPU0_SB_DQS_DN<7>")
	)
	(segment
		(start 398.67586 -210.775804)
		(end 399.101818 -210.349846)
		(width 0.20066)
		(layer "F.Cu")
		(net "M_E_CPU0_SB_DQS_DN<7>")
	)
	(segment
		(start 405.731726 -208.79816)
		(end 405.73833 -208.791556)
		(width 0.101854)
		(layer "F.Cu")
		(net "M_E_CPU0_SB_DQS_DN<7>")
	)
	(segment
		(start 408.040586 -208.806034)
		(end 408.304746 -208.541874)
		(width 0.20066)
		(layer "F.Cu")
		(net "M_E_CPU0_SB_DQS_DN<7>")
	)
	(segment
		(start 400.128994 -209.32267)
		(end 400.128994 -209.146648)
		(width 0.20066)
		(layer "F.Cu")
		(net "M_E_CPU0_SB_DQS_DN<7>")
	)
	(segment
		(start 411.964886 -208.945226)
		(end 411.59938 -208.945226)
		(width 0.20066)
		(layer "F.Cu")
		(net "M_E_CPU0_SB_DQS_DN<7>")
	)
	(segment
		(start 399.527268 -209.748374)
		(end 399.70329 -209.748374)
		(width 0.20066)
		(layer "F.Cu")
		(net "M_E_CPU0_SB_DQS_DN<7>")
	)
	(segment
		(start 393.487656 -215.78824)
		(end 393.51458 -215.761316)
		(width 0.1524)
		(layer "F.Cu")
		(net "M_E_CPU0_SB_DQS_DN<7>")
	)
	(segment
		(start 403.568408 -208.446624)
		(end 403.692868 -208.571084)
		(width 0.20066)
		(layer "F.Cu")
		(net "M_E_CPU0_SB_DQS_DN<7>")
	)
	(segment
		(start 398.074388 -211.201254)
		(end 398.499838 -210.775804)
		(width 0.20066)
		(layer "F.Cu")
		(net "M_E_CPU0_SB_DQS_DN<7>")
	)
	(segment
		(start 417.675314 -208.962244)
		(end 417.064444 -208.962244)
		(width 0.20066)
		(layer "F.Cu")
		(net "M_E_CPU0_SB_DQS_DN<7>")
	)
	(segment
		(start 410.35478 -209.216752)
		(end 410.853382 -209.216752)
		(width 0.20066)
		(layer "F.Cu")
		(net "M_E_CPU0_SB_DQS_DN<7>")
	)
	(segment
		(start 404.419308 -208.446624)
		(end 405.115014 -208.446624)
		(width 0.20066)
		(layer "F.Cu")
		(net "M_E_CPU0_SB_DQS_DN<7>")
	)
	(segment
		(start 400.469862 -208.80578)
		(end 401.337018 -208.446624)
		(width 0.20066)
		(layer "F.Cu")
		(net "M_E_CPU0_SB_DQS_DN<7>")
	)
	(segment
		(start 412.411672 -208.49844)
		(end 411.964886 -208.945226)
		(width 0.20066)
		(layer "F.Cu")
		(net "M_E_CPU0_SB_DQS_DN<7>")
	)
	(segment
		(start 386.923534 -232.885742)
		(end 388.362698 -232.885742)
		(width 0.088646)
		(layer "F.Cu")
		(net "M_E_CPU0_SB_DQS_DN<7>")
	)
	(segment
		(start 394.56614 -214.885524)
		(end 394.992098 -214.459566)
		(width 0.20066)
		(layer "F.Cu")
		(net "M_E_CPU0_SB_DQS_DN<7>")
	)
	(segment
		(start 411.59938 -208.945226)
		(end 411.327854 -209.216752)
		(width 0.20066)
		(layer "F.Cu")
		(net "M_E_CPU0_SB_DQS_DN<7>")
	)
	(segment
		(start 395.59357 -213.858094)
		(end 396.019528 -213.432136)
		(width 0.20066)
		(layer "F.Cu")
		(net "M_E_CPU0_SB_DQS_DN<7>")
	)
	(segment
		(start 399.101818 -210.349846)
		(end 399.101818 -210.173824)
		(width 0.20066)
		(layer "F.Cu")
		(net "M_E_CPU0_SB_DQS_DN<7>")
	)
	(segment
		(start 413.282384 -208.791556)
		(end 413.276542 -208.797398)
		(width 0.101854)
		(layer "F.Cu")
		(net "M_E_CPU0_SB_DQS_DN<7>")
	)
	(segment
		(start 388.589012 -232.70464)
		(end 393.05738 -228.236272)
		(width 0.1524)
		(layer "F.Cu")
		(net "M_E_CPU0_SB_DQS_DN<7>")
	)
	(segment
		(start 393.05738 -216.1667)
		(end 393.43584 -215.78824)
		(width 0.1524)
		(layer "F.Cu")
		(net "M_E_CPU0_SB_DQS_DN<7>")
	)
	(segment
		(start 402.841968 -208.571084)
		(end 402.966428 -208.446624)
		(width 0.20066)
		(layer "F.Cu")
		(net "M_E_CPU0_SB_DQS_DN<7>")
	)
	(segment
		(start 398.074388 -211.377276)
		(end 398.074388 -211.201254)
		(width 0.20066)
		(layer "F.Cu")
		(net "M_E_CPU0_SB_DQS_DN<7>")
	)
	(segment
		(start 401.337018 -208.446624)
		(end 402.115528 -208.446624)
		(width 0.20066)
		(layer "F.Cu")
		(net "M_E_CPU0_SB_DQS_DN<7>")
	)
	(segment
		(start 395.417548 -213.858094)
		(end 395.59357 -213.858094)
		(width 0.20066)
		(layer "F.Cu")
		(net "M_E_CPU0_SB_DQS_DN<7>")
	)
	(segment
		(start 397.64843 -211.803234)
		(end 398.074388 -211.377276)
		(width 0.20066)
		(layer "F.Cu")
		(net "M_E_CPU0_SB_DQS_DN<7>")
	)
	(segment
		(start 396.019528 -213.256114)
		(end 396.444978 -212.830664)
		(width 0.20066)
		(layer "F.Cu")
		(net "M_E_CPU0_SB_DQS_DN<7>")
	)
	(segment
		(start 396.444978 -212.830664)
		(end 396.621 -212.830664)
		(width 0.20066)
		(layer "F.Cu")
		(net "M_E_CPU0_SB_DQS_DN<7>")
	)
	(segment
		(start 398.499838 -210.775804)
		(end 398.67586 -210.775804)
		(width 0.20066)
		(layer "F.Cu")
		(net "M_E_CPU0_SB_DQS_DN<7>")
	)
	(segment
		(start 402.239988 -208.571084)
		(end 402.841968 -208.571084)
		(width 0.20066)
		(layer "F.Cu")
		(net "M_E_CPU0_SB_DQS_DN<7>")
	)
	(segment
		(start 399.70329 -209.748374)
		(end 400.128994 -209.32267)
		(width 0.20066)
		(layer "F.Cu")
		(net "M_E_CPU0_SB_DQS_DN<7>")
	)
	(segment
		(start 416.618928 -208.516728)
		(end 416.090862 -208.516728)
		(width 0.20066)
		(layer "F.Cu")
		(net "M_E_CPU0_SB_DQS_DN<7>")
	)
	(segment
		(start 408.304746 -208.541874)
		(end 408.457908 -208.541874)
		(width 0.20066)
		(layer "F.Cu")
		(net "M_E_CPU0_SB_DQS_DN<7>")
	)
	(segment
		(start 408.457908 -208.541874)
		(end 409.90012 -208.97977)
		(width 0.20066)
		(layer "F.Cu")
		(net "M_E_CPU0_SB_DQS_DN<7>")
	)
	(segment
		(start 403.692868 -208.571084)
		(end 404.294848 -208.571084)
		(width 0.20066)
		(layer "F.Cu")
		(net "M_E_CPU0_SB_DQS_DN<7>")
	)
	(segment
		(start 412.693612 -208.49844)
		(end 412.411672 -208.49844)
		(width 0.20066)
		(layer "F.Cu")
		(net "M_E_CPU0_SB_DQS_DN<7>")
	)
	(segment
		(start 415.307526 -208.801462)
		(end 415.29762 -208.791556)
		(width 0.1016)
		(layer "F.Cu")
		(net "M_E_CPU0_SB_DQS_DN<7>")
	)
	(segment
		(start 394.992098 -214.283544)
		(end 395.417548 -213.858094)
		(width 0.20066)
		(layer "F.Cu")
		(net "M_E_CPU0_SB_DQS_DN<7>")
	)
	(segment
		(start 417.064444 -208.962244)
		(end 416.618928 -208.516728)
		(width 0.20066)
		(layer "F.Cu")
		(net "M_E_CPU0_SB_DQS_DN<7>")
	)
	(segment
		(start 417.929822 -209.216752)
		(end 417.675314 -208.962244)
		(width 0.20066)
		(layer "F.Cu")
		(net "M_E_CPU0_SB_DQS_DN<7>")
	)
	(segment
		(start 397.046958 -212.404706)
		(end 397.046958 -212.228684)
		(width 0.20066)
		(layer "F.Cu")
		(net "M_E_CPU0_SB_DQS_DN<7>")
	)
	(segment
		(start 413.275526 -208.797398)
		(end 412.99257 -208.797398)
		(width 0.20066)
		(layer "F.Cu")
		(net "M_E_CPU0_SB_DQS_DN<7>")
	)
	(segment
		(start 407.741882 -208.791556)
		(end 407.75636 -208.806034)
		(width 0.1016)
		(layer "F.Cu")
		(net "M_E_CPU0_SB_DQS_DN<7>")
	)
	(segment
		(start 402.966428 -208.446624)
		(end 403.568408 -208.446624)
		(width 0.20066)
		(layer "F.Cu")
		(net "M_E_CPU0_SB_DQS_DN<7>")
	)
	(segment
		(start 405.73833 -208.791556)
		(end 406.118568 -208.791556)
		(width 0.101854)
		(layer "F.Cu")
		(net "M_E_CPU0_SB_DQS_DN<7>")
	)
	(segment
		(start 388.528306 -232.720134)
		(end 388.573518 -232.720134)
		(width 0.088646)
		(layer "F.Cu")
		(net "M_E_CPU0_SB_DQS_DN<7>")
	)
	(segment
		(start 394.992098 -214.459566)
		(end 394.992098 -214.283544)
		(width 0.20066)
		(layer "F.Cu")
		(net "M_E_CPU0_SB_DQS_DN<7>")
	)
	(segment
		(start 404.294848 -208.571084)
		(end 404.419308 -208.446624)
		(width 0.20066)
		(layer "F.Cu")
		(net "M_E_CPU0_SB_DQS_DN<7>")
	)
	(segment
		(start 416.090862 -208.516728)
		(end 415.806128 -208.801462)
		(width 0.20066)
		(layer "F.Cu")
		(net "M_E_CPU0_SB_DQS_DN<7>")
	)
	(segment
		(start 415.29762 -208.791556)
		(end 414.99028 -208.791556)
		(width 0.1016)
		(layer "F.Cu")
		(net "M_E_CPU0_SB_DQS_DN<7>")
	)
	(segment
		(start 399.101818 -210.173824)
		(end 399.527268 -209.748374)
		(width 0.20066)
		(layer "F.Cu")
		(net "M_E_CPU0_SB_DQS_DN<7>")
	)
	(segment
		(start 414.99028 -208.791556)
		(end 414.590992 -208.791556)
		(width 0.101854)
		(layer "F.Cu")
		(net "M_E_CPU0_SB_DQS_DN<7>")
	)
	(segment
		(start 402.115528 -208.446624)
		(end 402.239988 -208.571084)
		(width 0.20066)
		(layer "F.Cu")
		(net "M_E_CPU0_SB_DQS_DN<7>")
	)
	(segment
		(start 411.327854 -209.216752)
		(end 410.853382 -209.216752)
		(width 0.20066)
		(layer "F.Cu")
		(net "M_E_CPU0_SB_DQS_DN<7>")
	)
	(segment
		(start 405.115014 -208.446624)
		(end 405.46655 -208.79816)
		(width 0.20066)
		(layer "F.Cu")
		(net "M_E_CPU0_SB_DQS_DN<7>")
	)
	(segment
		(start 413.40786 -208.791556)
		(end 413.282384 -208.791556)
		(width 0.101854)
		(layer "F.Cu")
		(net "M_E_CPU0_SB_DQS_DN<7>")
	)
	(segment
		(start 393.05738 -228.236272)
		(end 393.05738 -216.1667)
		(width 0.1524)
		(layer "F.Cu")
		(net "M_E_CPU0_SB_DQS_DN<7>")
	)
	(segment
		(start 386.83438 -233.064304)
		(end 386.83438 -232.974896)
		(width 0.088646)
		(layer "F.Cu")
		(net "M_E_CPU0_SB_DQS_DN<7>")
	)
	(segment
		(start 415.806128 -208.801462)
		(end 415.307526 -208.801462)
		(width 0.20066)
		(layer "F.Cu")
		(net "M_E_CPU0_SB_DQS_DN<7>")
	)
	(segment
		(start 407.763726 -208.806034)
		(end 408.040586 -208.806034)
		(width 0.20066)
		(layer "F.Cu")
		(net "M_E_CPU0_SB_DQS_DN<7>")
	)
	(segment
		(start 400.128994 -209.146648)
		(end 400.469862 -208.80578)
		(width 0.20066)
		(layer "F.Cu")
		(net "M_E_CPU0_SB_DQS_DN<7>")
	)
	(segment
		(start 412.99257 -208.797398)
		(end 412.693612 -208.49844)
		(width 0.20066)
		(layer "F.Cu")
		(net "M_E_CPU0_SB_DQS_DN<7>")
	)
	(segment
		(start 414.590992 -208.791556)
		(end 413.40786 -208.791556)
		(width 0.1016)
		(layer "F.Cu")
		(net "M_E_CPU0_SB_DQS_DN<7>")
	)
	(segment
		(start 418.397182 -209.216752)
		(end 417.929822 -209.216752)
		(width 0.20066)
		(layer "F.Cu")
		(net "M_E_CPU0_SB_DQS_DN<7>")
	)
	(segment
		(start 405.46655 -208.79816)
		(end 405.731726 -208.79816)
		(width 0.20066)
		(layer "F.Cu")
		(net "M_E_CPU0_SB_DQS_DN<7>")
	)
	(segment
		(start 393.43584 -215.78824)
		(end 393.487656 -215.78824)
		(width 0.1524)
		(layer "F.Cu")
		(net "M_E_CPU0_SB_DQS_DN<7>")
	)
	(segment
		(start 394.390372 -214.885524)
		(end 394.56614 -214.885524)
		(width 0.20066)
		(layer "F.Cu")
		(net "M_E_CPU0_SB_DQS_DN<7>")
	)
	(segment
		(start 397.472408 -211.803234)
		(end 397.64843 -211.803234)
		(width 0.20066)
		(layer "F.Cu")
		(net "M_E_CPU0_SB_DQS_DN<7>")
	)
	(segment
		(start 406.118568 -208.791556)
		(end 407.741882 -208.791556)
		(width 0.1016)
		(layer "F.Cu")
		(net "M_E_CPU0_SB_DQS_DN<7>")
	)
	(segment
		(start 388.573518 -232.720134)
		(end 388.589012 -232.70464)
		(width 0.088646)
		(layer "F.Cu")
		(net "M_E_CPU0_SB_DQS_DN<7>")
	)
	(segment
		(start 409.90012 -208.97977)
		(end 410.117798 -208.97977)
		(width 0.20066)
		(layer "F.Cu")
		(net "M_E_CPU0_SB_DQS_DN<7>")
	)
	(segment
		(start 393.51458 -215.761316)
		(end 394.390372 -214.885524)
		(width 0.20066)
		(layer "F.Cu")
		(net "M_E_CPU0_SB_DQS_DN<7>")
	)
	(segment
		(start 413.276542 -208.797398)
		(end 413.275526 -208.797398)
		(width 0.101854)
		(layer "F.Cu")
		(net "M_E_CPU0_SB_DQS_DN<7>")
	)
	(segment
		(start 397.405606 -227.530406)
		(end 397.735552 -227.20046)
		(width 0.1524)
		(layer "F.Cu")
		(net "M_E_CPU0_SB_DQS_DN<6>")
	)
	(segment
		(start 400.92376 -223.245426)
		(end 401.04822 -223.120966)
		(width 0.20066)
		(layer "F.Cu")
		(net "M_E_CPU0_SB_DQS_DN<6>")
	)
	(segment
		(start 407.763726 -218.14155)
		(end 407.937716 -218.14155)
		(width 0.20066)
		(layer "F.Cu")
		(net "M_E_CPU0_SB_DQS_DN<6>")
	)
	(segment
		(start 401.811998 -220.719396)
		(end 401.811998 -220.543374)
		(width 0.20066)
		(layer "F.Cu")
		(net "M_E_CPU0_SB_DQS_DN<6>")
	)
	(segment
		(start 407.949908 -218.153742)
		(end 408.302206 -218.153742)
		(width 0.20066)
		(layer "F.Cu")
		(net "M_E_CPU0_SB_DQS_DN<6>")
	)
	(segment
		(start 411.832552 -218.295474)
		(end 411.65526 -218.295474)
		(width 0.20066)
		(layer "F.Cu")
		(net "M_E_CPU0_SB_DQS_DN<6>")
	)
	(segment
		(start 397.735552 -227.20046)
		(end 397.78813 -227.20046)
		(width 0.1524)
		(layer "F.Cu")
		(net "M_E_CPU0_SB_DQS_DN<6>")
	)
	(segment
		(start 404.53056 -217.619072)
		(end 404.814532 -217.619072)
		(width 0.20066)
		(layer "F.Cu")
		(net "M_E_CPU0_SB_DQS_DN<6>")
	)
	(segment
		(start 401.38604 -221.145354)
		(end 401.811998 -220.719396)
		(width 0.20066)
		(layer "F.Cu")
		(net "M_E_CPU0_SB_DQS_DN<6>")
	)
	(segment
		(start 402.839428 -219.516198)
		(end 403.519132 -218.836494)
		(width 0.20066)
		(layer "F.Cu")
		(net "M_E_CPU0_SB_DQS_DN<6>")
	)
	(segment
		(start 401.811998 -220.543374)
		(end 402.237448 -220.117924)
		(width 0.20066)
		(layer "F.Cu")
		(net "M_E_CPU0_SB_DQS_DN<6>")
	)
	(segment
		(start 405.242268 -218.161616)
		(end 405.731726 -218.161616)
		(width 0.20066)
		(layer "F.Cu")
		(net "M_E_CPU0_SB_DQS_DN<6>")
	)
	(segment
		(start 396.96898 -228.58476)
		(end 397.405606 -227.530406)
		(width 0.1524)
		(layer "F.Cu")
		(net "M_E_CPU0_SB_DQS_DN<6>")
	)
	(segment
		(start 413.286448 -218.141804)
		(end 413.280352 -218.1479)
		(width 0.1016)
		(layer "F.Cu")
		(net "M_E_CPU0_SB_DQS_DN<6>")
	)
	(segment
		(start 409.8036 -218.29522)
		(end 410.075888 -218.29522)
		(width 0.20066)
		(layer "F.Cu")
		(net "M_E_CPU0_SB_DQS_DN<6>")
	)
	(segment
		(start 405.015192 -217.819732)
		(end 405.015192 -217.93454)
		(width 0.20066)
		(layer "F.Cu")
		(net "M_E_CPU0_SB_DQS_DN<6>")
	)
	(segment
		(start 408.84094 -217.896186)
		(end 409.8036 -218.29522)
		(width 0.20066)
		(layer "F.Cu")
		(net "M_E_CPU0_SB_DQS_DN<6>")
	)
	(segment
		(start 405.731726 -218.161616)
		(end 405.751792 -218.14155)
		(width 0.101854)
		(layer "F.Cu")
		(net "M_E_CPU0_SB_DQS_DN<6>")
	)
	(segment
		(start 399.044922 -226.11969)
		(end 399.47088 -225.693732)
		(width 0.20066)
		(layer "F.Cu")
		(net "M_E_CPU0_SB_DQS_DN<6>")
	)
	(segment
		(start 412.96336 -218.1479)
		(end 412.685992 -217.870532)
		(width 0.20066)
		(layer "F.Cu")
		(net "M_E_CPU0_SB_DQS_DN<6>")
	)
	(segment
		(start 389.039862 -236.850682)
		(end 389.071866 -236.882686)
		(width 0.088646)
		(layer "F.Cu")
		(net "M_E_CPU0_SB_DQS_DN<6>")
	)
	(segment
		(start 400.92376 -224.06483)
		(end 400.92376 -223.245426)
		(width 0.20066)
		(layer "F.Cu")
		(net "M_E_CPU0_SB_DQS_DN<6>")
	)
	(segment
		(start 396.96898 -229.912672)
		(end 396.96898 -228.58476)
		(width 0.1524)
		(layer "F.Cu")
		(net "M_E_CPU0_SB_DQS_DN<6>")
	)
	(segment
		(start 410.075888 -218.29522)
		(end 410.347414 -218.566746)
		(width 0.20066)
		(layer "F.Cu")
		(net "M_E_CPU0_SB_DQS_DN<6>")
	)
	(segment
		(start 413.275526 -218.1479)
		(end 412.96336 -218.1479)
		(width 0.20066)
		(layer "F.Cu")
		(net "M_E_CPU0_SB_DQS_DN<6>")
	)
	(segment
		(start 418.397182 -218.566746)
		(end 417.8935 -218.566746)
		(width 0.20066)
		(layer "F.Cu")
		(net "M_E_CPU0_SB_DQS_DN<6>")
	)
	(segment
		(start 389.071866 -236.882686)
		(end 389.093964 -236.882686)
		(width 0.088646)
		(layer "F.Cu")
		(net "M_E_CPU0_SB_DQS_DN<6>")
	)
	(segment
		(start 388.575804 -236.850682)
		(end 389.039862 -236.850682)
		(width 0.088646)
		(layer "F.Cu")
		(net "M_E_CPU0_SB_DQS_DN<6>")
	)
	(segment
		(start 398.8689 -226.11969)
		(end 399.044922 -226.11969)
		(width 0.20066)
		(layer "F.Cu")
		(net "M_E_CPU0_SB_DQS_DN<6>")
	)
	(segment
		(start 389.998966 -236.882686)
		(end 396.96898 -229.912672)
		(width 0.1524)
		(layer "F.Cu")
		(net "M_E_CPU0_SB_DQS_DN<6>")
	)
	(segment
		(start 400.49831 -224.49028)
		(end 400.92376 -224.06483)
		(width 0.20066)
		(layer "F.Cu")
		(net "M_E_CPU0_SB_DQS_DN<6>")
	)
	(segment
		(start 400.072352 -225.09226)
		(end 400.49831 -224.666302)
		(width 0.20066)
		(layer "F.Cu")
		(net "M_E_CPU0_SB_DQS_DN<6>")
	)
	(segment
		(start 399.89633 -225.09226)
		(end 400.072352 -225.09226)
		(width 0.20066)
		(layer "F.Cu")
		(net "M_E_CPU0_SB_DQS_DN<6>")
	)
	(segment
		(start 389.093964 -236.882686)
		(end 389.998966 -236.882686)
		(width 0.1524)
		(layer "F.Cu")
		(net "M_E_CPU0_SB_DQS_DN<6>")
	)
	(segment
		(start 416.402012 -217.866976)
		(end 415.912046 -217.866976)
		(width 0.20066)
		(layer "F.Cu")
		(net "M_E_CPU0_SB_DQS_DN<6>")
	)
	(segment
		(start 412.563564 -217.870532)
		(end 412.35503 -218.079066)
		(width 0.20066)
		(layer "F.Cu")
		(net "M_E_CPU0_SB_DQS_DN<6>")
	)
	(segment
		(start 404.329646 -217.819986)
		(end 404.53056 -217.619072)
		(width 0.20066)
		(layer "F.Cu")
		(net "M_E_CPU0_SB_DQS_DN<6>")
	)
	(segment
		(start 416.847528 -218.312492)
		(end 416.402012 -217.866976)
		(width 0.20066)
		(layer "F.Cu")
		(net "M_E_CPU0_SB_DQS_DN<6>")
	)
	(segment
		(start 411.383988 -218.566746)
		(end 410.853382 -218.566746)
		(width 0.20066)
		(layer "F.Cu")
		(net "M_E_CPU0_SB_DQS_DN<6>")
	)
	(segment
		(start 397.78813 -227.20046)
		(end 397.815054 -227.173536)
		(width 0.1524)
		(layer "F.Cu")
		(net "M_E_CPU0_SB_DQS_DN<6>")
	)
	(segment
		(start 402.41347 -220.117924)
		(end 402.839428 -219.691966)
		(width 0.20066)
		(layer "F.Cu")
		(net "M_E_CPU0_SB_DQS_DN<6>")
	)
	(segment
		(start 412.35503 -218.079066)
		(end 411.832552 -218.295474)
		(width 0.20066)
		(layer "F.Cu")
		(net "M_E_CPU0_SB_DQS_DN<6>")
	)
	(segment
		(start 403.695154 -218.836494)
		(end 404.120858 -218.41079)
		(width 0.20066)
		(layer "F.Cu")
		(net "M_E_CPU0_SB_DQS_DN<6>")
	)
	(segment
		(start 404.814532 -217.619072)
		(end 405.015192 -217.819732)
		(width 0.20066)
		(layer "F.Cu")
		(net "M_E_CPU0_SB_DQS_DN<6>")
	)
	(segment
		(start 402.237448 -220.117924)
		(end 402.41347 -220.117924)
		(width 0.20066)
		(layer "F.Cu")
		(net "M_E_CPU0_SB_DQS_DN<6>")
	)
	(segment
		(start 415.307526 -218.152726)
		(end 415.296604 -218.141804)
		(width 0.1016)
		(layer "F.Cu")
		(net "M_E_CPU0_SB_DQS_DN<6>")
	)
	(segment
		(start 387.646672 -237.779814)
		(end 388.575804 -236.850682)
		(width 0.088646)
		(layer "F.Cu")
		(net "M_E_CPU0_SB_DQS_DN<6>")
	)
	(segment
		(start 399.47088 -225.51771)
		(end 399.89633 -225.09226)
		(width 0.20066)
		(layer "F.Cu")
		(net "M_E_CPU0_SB_DQS_DN<6>")
	)
	(segment
		(start 412.685992 -217.870532)
		(end 412.563564 -217.870532)
		(width 0.20066)
		(layer "F.Cu")
		(net "M_E_CPU0_SB_DQS_DN<6>")
	)
	(segment
		(start 397.815054 -227.173536)
		(end 398.8689 -226.11969)
		(width 0.20066)
		(layer "F.Cu")
		(net "M_E_CPU0_SB_DQS_DN<6>")
	)
	(segment
		(start 417.639246 -218.312492)
		(end 416.847528 -218.312492)
		(width 0.20066)
		(layer "F.Cu")
		(net "M_E_CPU0_SB_DQS_DN<6>")
	)
	(segment
		(start 403.519132 -218.836494)
		(end 403.695154 -218.836494)
		(width 0.20066)
		(layer "F.Cu")
		(net "M_E_CPU0_SB_DQS_DN<6>")
	)
	(segment
		(start 401.04822 -223.120966)
		(end 401.04822 -222.518986)
		(width 0.20066)
		(layer "F.Cu")
		(net "M_E_CPU0_SB_DQS_DN<6>")
	)
	(segment
		(start 405.015192 -217.93454)
		(end 405.242268 -218.161616)
		(width 0.20066)
		(layer "F.Cu")
		(net "M_E_CPU0_SB_DQS_DN<6>")
	)
	(segment
		(start 404.120858 -218.41079)
		(end 404.120858 -218.234514)
		(width 0.20066)
		(layer "F.Cu")
		(net "M_E_CPU0_SB_DQS_DN<6>")
	)
	(segment
		(start 401.04822 -222.518986)
		(end 400.92376 -222.394526)
		(width 0.20066)
		(layer "F.Cu")
		(net "M_E_CPU0_SB_DQS_DN<6>")
	)
	(segment
		(start 400.49831 -224.666302)
		(end 400.49831 -224.49028)
		(width 0.20066)
		(layer "F.Cu")
		(net "M_E_CPU0_SB_DQS_DN<6>")
	)
	(segment
		(start 386.83438 -237.868714)
		(end 386.92328 -237.779814)
		(width 0.088646)
		(layer "F.Cu")
		(net "M_E_CPU0_SB_DQS_DN<6>")
	)
	(segment
		(start 404.329646 -218.025726)
		(end 404.329646 -217.819986)
		(width 0.20066)
		(layer "F.Cu")
		(net "M_E_CPU0_SB_DQS_DN<6>")
	)
	(segment
		(start 407.937716 -218.14155)
		(end 407.949908 -218.153742)
		(width 0.20066)
		(layer "F.Cu")
		(net "M_E_CPU0_SB_DQS_DN<6>")
	)
	(segment
		(start 400.92376 -222.394526)
		(end 400.92376 -221.431612)
		(width 0.20066)
		(layer "F.Cu")
		(net "M_E_CPU0_SB_DQS_DN<6>")
	)
	(segment
		(start 408.559762 -217.896186)
		(end 408.84094 -217.896186)
		(width 0.20066)
		(layer "F.Cu")
		(net "M_E_CPU0_SB_DQS_DN<6>")
	)
	(segment
		(start 386.92328 -237.779814)
		(end 387.646672 -237.779814)
		(width 0.088646)
		(layer "F.Cu")
		(net "M_E_CPU0_SB_DQS_DN<6>")
	)
	(segment
		(start 399.47088 -225.693732)
		(end 399.47088 -225.51771)
		(width 0.20066)
		(layer "F.Cu")
		(net "M_E_CPU0_SB_DQS_DN<6>")
	)
	(segment
		(start 401.210018 -221.145354)
		(end 401.38604 -221.145354)
		(width 0.20066)
		(layer "F.Cu")
		(net "M_E_CPU0_SB_DQS_DN<6>")
	)
	(segment
		(start 415.912046 -217.866976)
		(end 415.626296 -218.152726)
		(width 0.20066)
		(layer "F.Cu")
		(net "M_E_CPU0_SB_DQS_DN<6>")
	)
	(segment
		(start 386.83438 -237.947454)
		(end 386.83438 -237.868714)
		(width 0.088646)
		(layer "F.Cu")
		(net "M_E_CPU0_SB_DQS_DN<6>")
	)
	(segment
		(start 404.120858 -218.234514)
		(end 404.329646 -218.025726)
		(width 0.20066)
		(layer "F.Cu")
		(net "M_E_CPU0_SB_DQS_DN<6>")
	)
	(segment
		(start 405.751792 -218.14155)
		(end 407.763726 -218.14155)
		(width 0.1016)
		(layer "F.Cu")
		(net "M_E_CPU0_SB_DQS_DN<6>")
	)
	(segment
		(start 408.302206 -218.153742)
		(end 408.559762 -217.896186)
		(width 0.20066)
		(layer "F.Cu")
		(net "M_E_CPU0_SB_DQS_DN<6>")
	)
	(segment
		(start 415.626296 -218.152726)
		(end 415.307526 -218.152726)
		(width 0.20066)
		(layer "F.Cu")
		(net "M_E_CPU0_SB_DQS_DN<6>")
	)
	(segment
		(start 402.839428 -219.691966)
		(end 402.839428 -219.516198)
		(width 0.20066)
		(layer "F.Cu")
		(net "M_E_CPU0_SB_DQS_DN<6>")
	)
	(segment
		(start 415.296604 -218.141804)
		(end 413.286448 -218.141804)
		(width 0.1016)
		(layer "F.Cu")
		(net "M_E_CPU0_SB_DQS_DN<6>")
	)
	(segment
		(start 410.347414 -218.566746)
		(end 410.853382 -218.566746)
		(width 0.20066)
		(layer "F.Cu")
		(net "M_E_CPU0_SB_DQS_DN<6>")
	)
	(segment
		(start 400.92376 -221.431612)
		(end 401.210018 -221.145354)
		(width 0.20066)
		(layer "F.Cu")
		(net "M_E_CPU0_SB_DQS_DN<6>")
	)
	(segment
		(start 411.65526 -218.295474)
		(end 411.383988 -218.566746)
		(width 0.20066)
		(layer "F.Cu")
		(net "M_E_CPU0_SB_DQS_DN<6>")
	)
	(segment
		(start 417.8935 -218.566746)
		(end 417.639246 -218.312492)
		(width 0.20066)
		(layer "F.Cu")
		(net "M_E_CPU0_SB_DQS_DN<6>")
	)
	(segment
		(start 413.280352 -218.1479)
		(end 413.275526 -218.1479)
		(width 0.101854)
		(layer "F.Cu")
		(net "M_E_CPU0_SB_DQS_DN<6>")
	)
	(segment
		(start 411.383988 -227.91674)
		(end 410.853382 -227.91674)
		(width 0.20066)
		(layer "F.Cu")
		(net "M_E_CPU0_SB_DQS_DN<5>")
	)
	(segment
		(start 410.853382 -227.91674)
		(end 409.723082 -227.91674)
		(width 0.20066)
		(layer "F.Cu")
		(net "M_E_CPU0_SB_DQS_DN<5>")
	)
	(segment
		(start 412.138622 -227.645468)
		(end 411.65526 -227.645468)
		(width 0.20066)
		(layer "F.Cu")
		(net "M_E_CPU0_SB_DQS_DN<5>")
	)
	(segment
		(start 412.563564 -227.220526)
		(end 412.138622 -227.645468)
		(width 0.20066)
		(layer "F.Cu")
		(net "M_E_CPU0_SB_DQS_DN<5>")
	)
	(segment
		(start 412.96336 -227.497894)
		(end 412.685992 -227.220526)
		(width 0.20066)
		(layer "F.Cu")
		(net "M_E_CPU0_SB_DQS_DN<5>")
	)
	(segment
		(start 418.397182 -227.91674)
		(end 417.8935 -227.91674)
		(width 0.20066)
		(layer "F.Cu")
		(net "M_E_CPU0_SB_DQS_DN<5>")
	)
	(segment
		(start 416.847528 -227.662486)
		(end 416.402012 -227.21697)
		(width 0.20066)
		(layer "F.Cu")
		(net "M_E_CPU0_SB_DQS_DN<5>")
	)
	(segment
		(start 413.280352 -227.497894)
		(end 413.275526 -227.497894)
		(width 0.101854)
		(layer "F.Cu")
		(net "M_E_CPU0_SB_DQS_DN<5>")
	)
	(segment
		(start 415.307526 -227.50272)
		(end 415.296604 -227.491798)
		(width 0.1016)
		(layer "F.Cu")
		(net "M_E_CPU0_SB_DQS_DN<5>")
	)
	(segment
		(start 417.639246 -227.662486)
		(end 416.847528 -227.662486)
		(width 0.20066)
		(layer "F.Cu")
		(net "M_E_CPU0_SB_DQS_DN<5>")
	)
	(segment
		(start 415.626296 -227.50272)
		(end 415.307526 -227.50272)
		(width 0.20066)
		(layer "F.Cu")
		(net "M_E_CPU0_SB_DQS_DN<5>")
	)
	(segment
		(start 416.402012 -227.21697)
		(end 415.912046 -227.21697)
		(width 0.20066)
		(layer "F.Cu")
		(net "M_E_CPU0_SB_DQS_DN<5>")
	)
	(segment
		(start 415.296604 -227.491798)
		(end 413.286448 -227.491798)
		(width 0.1016)
		(layer "F.Cu")
		(net "M_E_CPU0_SB_DQS_DN<5>")
	)
	(segment
		(start 411.65526 -227.645468)
		(end 411.383988 -227.91674)
		(width 0.20066)
		(layer "F.Cu")
		(net "M_E_CPU0_SB_DQS_DN<5>")
	)
	(segment
		(start 417.8935 -227.91674)
		(end 417.639246 -227.662486)
		(width 0.20066)
		(layer "F.Cu")
		(net "M_E_CPU0_SB_DQS_DN<5>")
	)
	(segment
		(start 415.912046 -227.21697)
		(end 415.626296 -227.50272)
		(width 0.20066)
		(layer "F.Cu")
		(net "M_E_CPU0_SB_DQS_DN<5>")
	)
	(segment
		(start 412.685992 -227.220526)
		(end 412.563564 -227.220526)
		(width 0.20066)
		(layer "F.Cu")
		(net "M_E_CPU0_SB_DQS_DN<5>")
	)
	(segment
		(start 413.286448 -227.491798)
		(end 413.280352 -227.497894)
		(width 0.1016)
		(layer "F.Cu")
		(net "M_E_CPU0_SB_DQS_DN<5>")
	)
	(segment
		(start 413.275526 -227.497894)
		(end 412.96336 -227.497894)
		(width 0.20066)
		(layer "F.Cu")
		(net "M_E_CPU0_SB_DQS_DN<5>")
	)
	(segment
		(start 383.545334 -235.506006)
		(end 383.545334 -234.970066)
		(width 0.20066)
		(layer "F.Cu")
		(net "M_E_CPU0_SB_DQS_DN<5>")
	)
	(segment
		(start 397.810482 -233.795062)
		(end 396.901416 -234.171744)
		(width 0.18288)
		(layer "In2.Cu")
		(net "M_E_CPU0_SB_DQS_DN<5>")
	)
	(segment
		(start 384.297174 -234.645708)
		(end 384.25755 -234.668822)
		(width 0.088646)
		(layer "In2.Cu")
		(net "M_E_CPU0_SB_DQS_DN<5>")
	)
	(segment
		(start 395.225016 -234.171744)
		(end 394.676376 -234.171744)
		(width 0.18288)
		(layer "In2.Cu")
		(net "M_E_CPU0_SB_DQS_DN<5>")
	)
	(segment
		(start 394.551916 -234.296204)
		(end 394.003276 -234.296204)
		(width 0.18288)
		(layer "In2.Cu")
		(net "M_E_CPU0_SB_DQS_DN<5>")
	)
	(segment
		(start 407.975308 -227.819966)
		(end 407.743152 -227.723954)
		(width 0.18288)
		(layer "In2.Cu")
		(net "M_E_CPU0_SB_DQS_DN<5>")
	)
	(segment
		(start 405.40686 -227.489258)
		(end 405.125174 -227.207572)
		(width 0.18288)
		(layer "In2.Cu")
		(net "M_E_CPU0_SB_DQS_DN<5>")
	)
	(segment
		(start 400.278346 -231.50322)
		(end 400.102324 -231.50322)
		(width 0.18288)
		(layer "In2.Cu")
		(net "M_E_CPU0_SB_DQS_DN<5>")
	)
	(segment
		(start 393.205716 -234.296204)
		(end 392.657076 -234.296204)
		(width 0.18288)
		(layer "In2.Cu")
		(net "M_E_CPU0_SB_DQS_DN<5>")
	)
	(segment
		(start 383.668524 -234.692444)
		(end 383.611374 -234.716574)
		(width 0.088646)
		(layer "In2.Cu")
		(net "M_E_CPU0_SB_DQS_DN<5>")
	)
	(segment
		(start 404.801324 -227.207572)
		(end 404.112984 -227.49256)
		(width 0.18288)
		(layer "In2.Cu")
		(net "M_E_CPU0_SB_DQS_DN<5>")
	)
	(segment
		(start 395.898116 -234.296204)
		(end 395.349476 -234.296204)
		(width 0.18288)
		(layer "In2.Cu")
		(net "M_E_CPU0_SB_DQS_DN<5>")
	)
	(segment
		(start 400.666458 -230.939086)
		(end 400.666458 -231.115108)
		(width 0.18288)
		(layer "In2.Cu")
		(net "M_E_CPU0_SB_DQS_DN<5>")
	)
	(segment
		(start 391.859516 -234.296204)
		(end 391.310876 -234.296204)
		(width 0.18288)
		(layer "In2.Cu")
		(net "M_E_CPU0_SB_DQS_DN<5>")
	)
	(segment
		(start 391.186416 -234.171744)
		(end 390.637776 -234.171744)
		(width 0.18288)
		(layer "In2.Cu")
		(net "M_E_CPU0_SB_DQS_DN<5>")
	)
	(segment
		(start 384.101086 -234.722924)
		(end 383.933446 -234.722924)
		(width 0.088646)
		(layer "In2.Cu")
		(net "M_E_CPU0_SB_DQS_DN<5>")
	)
	(segment
		(start 393.330176 -234.171744)
		(end 393.205716 -234.296204)
		(width 0.18288)
		(layer "In2.Cu")
		(net "M_E_CPU0_SB_DQS_DN<5>")
	)
	(segment
		(start 384.171698 -234.704382)
		(end 384.159506 -234.707684)
		(width 0.088646)
		(layer "In2.Cu")
		(net "M_E_CPU0_SB_DQS_DN<5>")
	)
	(segment
		(start 399.150332 -232.455212)
		(end 398.762474 -232.84307)
		(width 0.18288)
		(layer "In2.Cu")
		(net "M_E_CPU0_SB_DQS_DN<5>")
	)
	(segment
		(start 386.291074 -234.596686)
		(end 385.419346 -234.596686)
		(width 0.088646)
		(layer "In2.Cu")
		(net "M_E_CPU0_SB_DQS_DN<5>")
	)
	(segment
		(start 391.983976 -234.171744)
		(end 391.859516 -234.296204)
		(width 0.18288)
		(layer "In2.Cu")
		(net "M_E_CPU0_SB_DQS_DN<5>")
	)
	(segment
		(start 404.112984 -227.49256)
		(end 400.666458 -230.939086)
		(width 0.18288)
		(layer "In2.Cu")
		(net "M_E_CPU0_SB_DQS_DN<5>")
	)
	(segment
		(start 407.210006 -227.190808)
		(end 406.154128 -227.190808)
		(width 0.18288)
		(layer "In2.Cu")
		(net "M_E_CPU0_SB_DQS_DN<5>")
	)
	(segment
		(start 409.438094 -227.631752)
		(end 409.31592 -227.631752)
		(width 0.18288)
		(layer "In2.Cu")
		(net "M_E_CPU0_SB_DQS_DN<5>")
	)
	(segment
		(start 398.762474 -233.019092)
		(end 398.374362 -233.407204)
		(width 0.18288)
		(layer "In2.Cu")
		(net "M_E_CPU0_SB_DQS_DN<5>")
	)
	(segment
		(start 384.158744 -234.707938)
		(end 384.15849 -234.707938)
		(width 0.088646)
		(layer "In2.Cu")
		(net "M_E_CPU0_SB_DQS_DN<5>")
	)
	(segment
		(start 384.25755 -234.668822)
		(end 384.171444 -234.704636)
		(width 0.088646)
		(layer "In2.Cu")
		(net "M_E_CPU0_SB_DQS_DN<5>")
	)
	(segment
		(start 384.159506 -234.707684)
		(end 384.158744 -234.707938)
		(width 0.088646)
		(layer "In2.Cu")
		(net "M_E_CPU0_SB_DQS_DN<5>")
	)
	(segment
		(start 384.171444 -234.704636)
		(end 384.171698 -234.704382)
		(width 0.088646)
		(layer "In2.Cu")
		(net "M_E_CPU0_SB_DQS_DN<5>")
	)
	(segment
		(start 407.743152 -227.723954)
		(end 407.210006 -227.190808)
		(width 0.18288)
		(layer "In2.Cu")
		(net "M_E_CPU0_SB_DQS_DN<5>")
	)
	(segment
		(start 409.723082 -227.91674)
		(end 409.438094 -227.631752)
		(width 0.18288)
		(layer "In2.Cu")
		(net "M_E_CPU0_SB_DQS_DN<5>")
	)
	(segment
		(start 384.297682 -234.645708)
		(end 384.297174 -234.645708)
		(width 0.088646)
		(layer "In2.Cu")
		(net "M_E_CPU0_SB_DQS_DN<5>")
	)
	(segment
		(start 394.003276 -234.296204)
		(end 393.878816 -234.171744)
		(width 0.18288)
		(layer "In2.Cu")
		(net "M_E_CPU0_SB_DQS_DN<5>")
	)
	(segment
		(start 400.102324 -231.50322)
		(end 399.714466 -231.891078)
		(width 0.18288)
		(layer "In2.Cu")
		(net "M_E_CPU0_SB_DQS_DN<5>")
	)
	(segment
		(start 396.022576 -234.171744)
		(end 395.898116 -234.296204)
		(width 0.18288)
		(layer "In2.Cu")
		(net "M_E_CPU0_SB_DQS_DN<5>")
	)
	(segment
		(start 386.981954 -234.656376)
		(end 386.350764 -234.656376)
		(width 0.18288)
		(layer "In2.Cu")
		(net "M_E_CPU0_SB_DQS_DN<5>")
	)
	(segment
		(start 395.349476 -234.296204)
		(end 395.225016 -234.171744)
		(width 0.18288)
		(layer "In2.Cu")
		(net "M_E_CPU0_SB_DQS_DN<5>")
	)
	(segment
		(start 384.672586 -234.646216)
		(end 384.672078 -234.645708)
		(width 0.088646)
		(layer "In2.Cu")
		(net "M_E_CPU0_SB_DQS_DN<5>")
	)
	(segment
		(start 392.532616 -234.171744)
		(end 391.983976 -234.171744)
		(width 0.18288)
		(layer "In2.Cu")
		(net "M_E_CPU0_SB_DQS_DN<5>")
	)
	(segment
		(start 409.31592 -227.631752)
		(end 408.366722 -227.819966)
		(width 0.18288)
		(layer "In2.Cu")
		(net "M_E_CPU0_SB_DQS_DN<5>")
	)
	(segment
		(start 398.374362 -233.407204)
		(end 398.19834 -233.407204)
		(width 0.18288)
		(layer "In2.Cu")
		(net "M_E_CPU0_SB_DQS_DN<5>")
	)
	(segment
		(start 405.855678 -227.489258)
		(end 405.40686 -227.489258)
		(width 0.18288)
		(layer "In2.Cu")
		(net "M_E_CPU0_SB_DQS_DN<5>")
	)
	(segment
		(start 400.666458 -231.115108)
		(end 400.278346 -231.50322)
		(width 0.18288)
		(layer "In2.Cu")
		(net "M_E_CPU0_SB_DQS_DN<5>")
	)
	(segment
		(start 406.154128 -227.190808)
		(end 405.855678 -227.489258)
		(width 0.18288)
		(layer "In2.Cu")
		(net "M_E_CPU0_SB_DQS_DN<5>")
	)
	(segment
		(start 390.513316 -234.296204)
		(end 389.964676 -234.296204)
		(width 0.18288)
		(layer "In2.Cu")
		(net "M_E_CPU0_SB_DQS_DN<5>")
	)
	(segment
		(start 383.611374 -234.716574)
		(end 383.56286 -234.751372)
		(width 0.088646)
		(layer "In2.Cu")
		(net "M_E_CPU0_SB_DQS_DN<5>")
	)
	(segment
		(start 390.637776 -234.171744)
		(end 390.513316 -234.296204)
		(width 0.18288)
		(layer "In2.Cu")
		(net "M_E_CPU0_SB_DQS_DN<5>")
	)
	(segment
		(start 384.67284 -234.645454)
		(end 384.672586 -234.646216)
		(width 0.088646)
		(layer "In2.Cu")
		(net "M_E_CPU0_SB_DQS_DN<5>")
	)
	(segment
		(start 383.933446 -234.722924)
		(end 383.804414 -234.685078)
		(width 0.088646)
		(layer "In2.Cu")
		(net "M_E_CPU0_SB_DQS_DN<5>")
	)
	(segment
		(start 383.804414 -234.685078)
		(end 383.668524 -234.692444)
		(width 0.088646)
		(layer "In2.Cu")
		(net "M_E_CPU0_SB_DQS_DN<5>")
	)
	(segment
		(start 393.878816 -234.171744)
		(end 393.330176 -234.171744)
		(width 0.18288)
		(layer "In2.Cu")
		(net "M_E_CPU0_SB_DQS_DN<5>")
	)
	(segment
		(start 394.676376 -234.171744)
		(end 394.551916 -234.296204)
		(width 0.18288)
		(layer "In2.Cu")
		(net "M_E_CPU0_SB_DQS_DN<5>")
	)
	(segment
		(start 399.714466 -232.0671)
		(end 399.326354 -232.455212)
		(width 0.18288)
		(layer "In2.Cu")
		(net "M_E_CPU0_SB_DQS_DN<5>")
	)
	(segment
		(start 408.366722 -227.819966)
		(end 407.975308 -227.819966)
		(width 0.18288)
		(layer "In2.Cu")
		(net "M_E_CPU0_SB_DQS_DN<5>")
	)
	(segment
		(start 386.350764 -234.656376)
		(end 386.291074 -234.596686)
		(width 0.088646)
		(layer "In2.Cu")
		(net "M_E_CPU0_SB_DQS_DN<5>")
	)
	(segment
		(start 384.15849 -234.707938)
		(end 384.101086 -234.722924)
		(width 0.088646)
		(layer "In2.Cu")
		(net "M_E_CPU0_SB_DQS_DN<5>")
	)
	(segment
		(start 399.714466 -231.891078)
		(end 399.714466 -232.0671)
		(width 0.18288)
		(layer "In2.Cu")
		(net "M_E_CPU0_SB_DQS_DN<5>")
	)
	(segment
		(start 391.310876 -234.296204)
		(end 391.186416 -234.171744)
		(width 0.18288)
		(layer "In2.Cu")
		(net "M_E_CPU0_SB_DQS_DN<5>")
	)
	(segment
		(start 399.326354 -232.455212)
		(end 399.150332 -232.455212)
		(width 0.18288)
		(layer "In2.Cu")
		(net "M_E_CPU0_SB_DQS_DN<5>")
	)
	(segment
		(start 389.840216 -234.171744)
		(end 387.466586 -234.171744)
		(width 0.18288)
		(layer "In2.Cu")
		(net "M_E_CPU0_SB_DQS_DN<5>")
	)
	(segment
		(start 387.466586 -234.171744)
		(end 386.981954 -234.656376)
		(width 0.18288)
		(layer "In2.Cu")
		(net "M_E_CPU0_SB_DQS_DN<5>")
	)
	(segment
		(start 405.125174 -227.207572)
		(end 404.801324 -227.207572)
		(width 0.18288)
		(layer "In2.Cu")
		(net "M_E_CPU0_SB_DQS_DN<5>")
	)
	(segment
		(start 398.19834 -233.407204)
		(end 397.810482 -233.795062)
		(width 0.18288)
		(layer "In2.Cu")
		(net "M_E_CPU0_SB_DQS_DN<5>")
	)
	(segment
		(start 396.901416 -234.171744)
		(end 396.022576 -234.171744)
		(width 0.18288)
		(layer "In2.Cu")
		(net "M_E_CPU0_SB_DQS_DN<5>")
	)
	(segment
		(start 389.964676 -234.296204)
		(end 389.840216 -234.171744)
		(width 0.18288)
		(layer "In2.Cu")
		(net "M_E_CPU0_SB_DQS_DN<5>")
	)
	(segment
		(start 392.657076 -234.296204)
		(end 392.532616 -234.171744)
		(width 0.18288)
		(layer "In2.Cu")
		(net "M_E_CPU0_SB_DQS_DN<5>")
	)
	(segment
		(start 383.56286 -234.751372)
		(end 383.545334 -234.970066)
		(width 0.088646)
		(layer "In2.Cu")
		(net "M_E_CPU0_SB_DQS_DN<5>")
	)
	(segment
		(start 398.762474 -232.84307)
		(end 398.762474 -233.019092)
		(width 0.18288)
		(layer "In2.Cu")
		(net "M_E_CPU0_SB_DQS_DN<5>")
	)
	(arc
		(start 385.419346 -234.596686)
		(mid 385.32509 -234.609125)
		(end 385.237228 -234.645454)
		(width 0.088646)
		(layer "In2.Cu")
		(net "M_E_CPU0_SB_DQS_DN<5>")
	)
	(arc
		(start 384.672078 -234.645708)
		(mid 384.48488 -234.595565)
		(end 384.297682 -234.645708)
		(width 0.088646)
		(layer "In2.Cu")
		(net "M_E_CPU0_SB_DQS_DN<5>")
	)
	(arc
		(start 385.237228 -234.645454)
		(mid 384.955034 -234.72101)
		(end 384.67284 -234.645454)
		(width 0.088646)
		(layer "In2.Cu")
		(net "M_E_CPU0_SB_DQS_DN<5>")
	)
	(segment
		(start 386.83438 -242.741958)
		(end 387.075172 -242.501166)
		(width 0.088646)
		(layer "F.Cu")
		(net "M_E_CPU0_SB_DQS_DN<4>")
	)
	(segment
		(start 398.5133 -237.262162)
		(end 398.63649 -237.138972)
		(width 0.20066)
		(layer "F.Cu")
		(net "M_E_CPU0_SB_DQS_DN<4>")
	)
	(segment
		(start 397.78813 -237.138972)
		(end 397.91132 -237.262162)
		(width 0.20066)
		(layer "F.Cu")
		(net "M_E_CPU0_SB_DQS_DN<4>")
	)
	(segment
		(start 402.26234 -237.262162)
		(end 402.86432 -237.262162)
		(width 0.20066)
		(layer "F.Cu")
		(net "M_E_CPU0_SB_DQS_DN<4>")
	)
	(segment
		(start 387.589776 -242.59413)
		(end 387.68274 -242.501166)
		(width 0.088646)
		(layer "F.Cu")
		(net "M_E_CPU0_SB_DQS_DN<4>")
	)
	(segment
		(start 417.104576 -236.999272)
		(end 416.672268 -236.566964)
		(width 0.20066)
		(layer "F.Cu")
		(net "M_E_CPU0_SB_DQS_DN<4>")
	)
	(segment
		(start 404.892256 -236.653578)
		(end 405.101552 -236.862874)
		(width 0.20066)
		(layer "F.Cu")
		(net "M_E_CPU0_SB_DQS_DN<4>")
	)
	(segment
		(start 417.8935 -237.266734)
		(end 417.626038 -236.999272)
		(width 0.20066)
		(layer "F.Cu")
		(net "M_E_CPU0_SB_DQS_DN<4>")
	)
	(segment
		(start 402.86432 -237.262162)
		(end 402.98751 -237.138972)
		(width 0.20066)
		(layer "F.Cu")
		(net "M_E_CPU0_SB_DQS_DN<4>")
	)
	(segment
		(start 418.397182 -237.266734)
		(end 417.8935 -237.266734)
		(width 0.20066)
		(layer "F.Cu")
		(net "M_E_CPU0_SB_DQS_DN<4>")
	)
	(segment
		(start 395.901164 -237.138972)
		(end 397.78813 -237.138972)
		(width 0.20066)
		(layer "F.Cu")
		(net "M_E_CPU0_SB_DQS_DN<4>")
	)
	(segment
		(start 411.48508 -236.995462)
		(end 411.213808 -237.266734)
		(width 0.20066)
		(layer "F.Cu")
		(net "M_E_CPU0_SB_DQS_DN<4>")
	)
	(segment
		(start 405.101552 -236.862874)
		(end 405.230584 -236.862874)
		(width 0.20066)
		(layer "F.Cu")
		(net "M_E_CPU0_SB_DQS_DN<4>")
	)
	(segment
		(start 387.39572 -242.59413)
		(end 387.589776 -242.59413)
		(width 0.088646)
		(layer "F.Cu")
		(net "M_E_CPU0_SB_DQS_DN<4>")
	)
	(segment
		(start 400.812 -237.262162)
		(end 401.41398 -237.262162)
		(width 0.20066)
		(layer "F.Cu")
		(net "M_E_CPU0_SB_DQS_DN<4>")
	)
	(segment
		(start 416.672268 -236.566964)
		(end 416.131502 -236.566964)
		(width 0.20066)
		(layer "F.Cu")
		(net "M_E_CPU0_SB_DQS_DN<4>")
	)
	(segment
		(start 415.694622 -236.841792)
		(end 415.296604 -236.841792)
		(width 0.101854)
		(layer "F.Cu")
		(net "M_E_CPU0_SB_DQS_DN<4>")
	)
	(segment
		(start 404.892256 -236.51972)
		(end 404.892256 -236.653578)
		(width 0.20066)
		(layer "F.Cu")
		(net "M_E_CPU0_SB_DQS_DN<4>")
	)
	(segment
		(start 386.83438 -242.830858)
		(end 386.83438 -242.741958)
		(width 0.088646)
		(layer "F.Cu")
		(net "M_E_CPU0_SB_DQS_DN<4>")
	)
	(segment
		(start 411.816042 -236.995462)
		(end 411.48508 -236.995462)
		(width 0.20066)
		(layer "F.Cu")
		(net "M_E_CPU0_SB_DQS_DN<4>")
	)
	(segment
		(start 413.286448 -236.841792)
		(end 412.856426 -236.841792)
		(width 0.101854)
		(layer "F.Cu")
		(net "M_E_CPU0_SB_DQS_DN<4>")
	)
	(segment
		(start 412.856426 -236.841792)
		(end 412.85033 -236.847888)
		(width 0.101854)
		(layer "F.Cu")
		(net "M_E_CPU0_SB_DQS_DN<4>")
	)
	(segment
		(start 401.53717 -237.138972)
		(end 402.13915 -237.138972)
		(width 0.20066)
		(layer "F.Cu")
		(net "M_E_CPU0_SB_DQS_DN<4>")
	)
	(segment
		(start 408.841194 -236.596174)
		(end 409.8036 -236.995208)
		(width 0.20066)
		(layer "F.Cu")
		(net "M_E_CPU0_SB_DQS_DN<4>")
	)
	(segment
		(start 402.13915 -237.138972)
		(end 402.26234 -237.262162)
		(width 0.20066)
		(layer "F.Cu")
		(net "M_E_CPU0_SB_DQS_DN<4>")
	)
	(segment
		(start 399.36166 -237.262162)
		(end 399.96364 -237.262162)
		(width 0.20066)
		(layer "F.Cu")
		(net "M_E_CPU0_SB_DQS_DN<4>")
	)
	(segment
		(start 395.826234 -237.102142)
		(end 395.863064 -237.138972)
		(width 0.1524)
		(layer "F.Cu")
		(net "M_E_CPU0_SB_DQS_DN<4>")
	)
	(segment
		(start 389.881364 -240.79454)
		(end 391.675874 -240.79454)
		(width 0.1524)
		(layer "F.Cu")
		(net "M_E_CPU0_SB_DQS_DN<4>")
	)
	(segment
		(start 404.69185 -236.319314)
		(end 404.892256 -236.51972)
		(width 0.20066)
		(layer "F.Cu")
		(net "M_E_CPU0_SB_DQS_DN<4>")
	)
	(segment
		(start 399.23847 -237.138972)
		(end 399.36166 -237.262162)
		(width 0.20066)
		(layer "F.Cu")
		(net "M_E_CPU0_SB_DQS_DN<4>")
	)
	(segment
		(start 408.342338 -236.841538)
		(end 408.587702 -236.596174)
		(width 0.20066)
		(layer "F.Cu")
		(net "M_E_CPU0_SB_DQS_DN<4>")
	)
	(segment
		(start 416.131502 -236.566964)
		(end 415.845752 -236.852714)
		(width 0.20066)
		(layer "F.Cu")
		(net "M_E_CPU0_SB_DQS_DN<4>")
	)
	(segment
		(start 389.859266 -240.79454)
		(end 389.881364 -240.79454)
		(width 0.088646)
		(layer "F.Cu")
		(net "M_E_CPU0_SB_DQS_DN<4>")
	)
	(segment
		(start 411.213808 -237.266734)
		(end 410.853382 -237.266734)
		(width 0.20066)
		(layer "F.Cu")
		(net "M_E_CPU0_SB_DQS_DN<4>")
	)
	(segment
		(start 403.58949 -237.138972)
		(end 404.409148 -236.319314)
		(width 0.20066)
		(layer "F.Cu")
		(net "M_E_CPU0_SB_DQS_DN<4>")
	)
	(segment
		(start 387.075172 -242.501166)
		(end 387.302756 -242.501166)
		(width 0.088646)
		(layer "F.Cu")
		(net "M_E_CPU0_SB_DQS_DN<4>")
	)
	(segment
		(start 395.863064 -237.138972)
		(end 395.901164 -237.138972)
		(width 0.1524)
		(layer "F.Cu")
		(net "M_E_CPU0_SB_DQS_DN<4>")
	)
	(segment
		(start 405.794464 -236.841538)
		(end 407.745692 -236.841538)
		(width 0.1016)
		(layer "F.Cu")
		(net "M_E_CPU0_SB_DQS_DN<4>")
	)
	(segment
		(start 415.845752 -236.852714)
		(end 415.705544 -236.852714)
		(width 0.20066)
		(layer "F.Cu")
		(net "M_E_CPU0_SB_DQS_DN<4>")
	)
	(segment
		(start 402.98751 -237.138972)
		(end 403.58949 -237.138972)
		(width 0.20066)
		(layer "F.Cu")
		(net "M_E_CPU0_SB_DQS_DN<4>")
	)
	(segment
		(start 397.91132 -237.262162)
		(end 398.5133 -237.262162)
		(width 0.20066)
		(layer "F.Cu")
		(net "M_E_CPU0_SB_DQS_DN<4>")
	)
	(segment
		(start 389.645144 -240.762536)
		(end 389.827262 -240.762536)
		(width 0.088646)
		(layer "F.Cu")
		(net "M_E_CPU0_SB_DQS_DN<4>")
	)
	(segment
		(start 400.08683 -237.138972)
		(end 400.68881 -237.138972)
		(width 0.20066)
		(layer "F.Cu")
		(net "M_E_CPU0_SB_DQS_DN<4>")
	)
	(segment
		(start 387.906514 -242.501166)
		(end 389.645144 -240.762536)
		(width 0.088646)
		(layer "F.Cu")
		(net "M_E_CPU0_SB_DQS_DN<4>")
	)
	(segment
		(start 415.705544 -236.852714)
		(end 415.694622 -236.841792)
		(width 0.101854)
		(layer "F.Cu")
		(net "M_E_CPU0_SB_DQS_DN<4>")
	)
	(segment
		(start 389.827262 -240.762536)
		(end 389.859266 -240.79454)
		(width 0.088646)
		(layer "F.Cu")
		(net "M_E_CPU0_SB_DQS_DN<4>")
	)
	(segment
		(start 400.68881 -237.138972)
		(end 400.812 -237.262162)
		(width 0.20066)
		(layer "F.Cu")
		(net "M_E_CPU0_SB_DQS_DN<4>")
	)
	(segment
		(start 401.41398 -237.262162)
		(end 401.53717 -237.138972)
		(width 0.20066)
		(layer "F.Cu")
		(net "M_E_CPU0_SB_DQS_DN<4>")
	)
	(segment
		(start 405.230584 -236.862874)
		(end 405.25192 -236.841538)
		(width 0.101854)
		(layer "F.Cu")
		(net "M_E_CPU0_SB_DQS_DN<4>")
	)
	(segment
		(start 408.220926 -236.841538)
		(end 408.342338 -236.841538)
		(width 0.20066)
		(layer "F.Cu")
		(net "M_E_CPU0_SB_DQS_DN<4>")
	)
	(segment
		(start 415.296604 -236.841792)
		(end 413.286448 -236.841792)
		(width 0.1016)
		(layer "F.Cu")
		(net "M_E_CPU0_SB_DQS_DN<4>")
	)
	(segment
		(start 409.8036 -236.995208)
		(end 410.075888 -236.995208)
		(width 0.20066)
		(layer "F.Cu")
		(net "M_E_CPU0_SB_DQS_DN<4>")
	)
	(segment
		(start 391.675874 -240.79454)
		(end 395.368272 -237.102142)
		(width 0.1524)
		(layer "F.Cu")
		(net "M_E_CPU0_SB_DQS_DN<4>")
	)
	(segment
		(start 387.302756 -242.501166)
		(end 387.39572 -242.59413)
		(width 0.088646)
		(layer "F.Cu")
		(net "M_E_CPU0_SB_DQS_DN<4>")
	)
	(segment
		(start 412.85033 -236.847888)
		(end 412.746952 -236.847888)
		(width 0.20066)
		(layer "F.Cu")
		(net "M_E_CPU0_SB_DQS_DN<4>")
	)
	(segment
		(start 399.96364 -237.262162)
		(end 400.08683 -237.138972)
		(width 0.20066)
		(layer "F.Cu")
		(net "M_E_CPU0_SB_DQS_DN<4>")
	)
	(segment
		(start 412.746952 -236.847888)
		(end 412.470854 -236.57179)
		(width 0.20066)
		(layer "F.Cu")
		(net "M_E_CPU0_SB_DQS_DN<4>")
	)
	(segment
		(start 412.470854 -236.57179)
		(end 412.239714 -236.57179)
		(width 0.20066)
		(layer "F.Cu")
		(net "M_E_CPU0_SB_DQS_DN<4>")
	)
	(segment
		(start 408.587702 -236.596174)
		(end 408.841194 -236.596174)
		(width 0.20066)
		(layer "F.Cu")
		(net "M_E_CPU0_SB_DQS_DN<4>")
	)
	(segment
		(start 417.626038 -236.999272)
		(end 417.104576 -236.999272)
		(width 0.20066)
		(layer "F.Cu")
		(net "M_E_CPU0_SB_DQS_DN<4>")
	)
	(segment
		(start 410.347414 -237.266734)
		(end 410.853382 -237.266734)
		(width 0.20066)
		(layer "F.Cu")
		(net "M_E_CPU0_SB_DQS_DN<4>")
	)
	(segment
		(start 412.239714 -236.57179)
		(end 411.816042 -236.995462)
		(width 0.20066)
		(layer "F.Cu")
		(net "M_E_CPU0_SB_DQS_DN<4>")
	)
	(segment
		(start 395.368272 -237.102142)
		(end 395.826234 -237.102142)
		(width 0.1524)
		(layer "F.Cu")
		(net "M_E_CPU0_SB_DQS_DN<4>")
	)
	(segment
		(start 407.745692 -236.841538)
		(end 408.220926 -236.841538)
		(width 0.101854)
		(layer "F.Cu")
		(net "M_E_CPU0_SB_DQS_DN<4>")
	)
	(segment
		(start 387.68274 -242.501166)
		(end 387.906514 -242.501166)
		(width 0.088646)
		(layer "F.Cu")
		(net "M_E_CPU0_SB_DQS_DN<4>")
	)
	(segment
		(start 398.63649 -237.138972)
		(end 399.23847 -237.138972)
		(width 0.20066)
		(layer "F.Cu")
		(net "M_E_CPU0_SB_DQS_DN<4>")
	)
	(segment
		(start 405.25192 -236.841538)
		(end 405.794464 -236.841538)
		(width 0.101854)
		(layer "F.Cu")
		(net "M_E_CPU0_SB_DQS_DN<4>")
	)
	(segment
		(start 410.075888 -236.995208)
		(end 410.347414 -237.266734)
		(width 0.20066)
		(layer "F.Cu")
		(net "M_E_CPU0_SB_DQS_DN<4>")
	)
	(segment
		(start 404.409148 -236.319314)
		(end 404.69185 -236.319314)
		(width 0.20066)
		(layer "F.Cu")
		(net "M_E_CPU0_SB_DQS_DN<4>")
	)
	(segment
		(start 409.242514 -200.562972)
		(end 409.074112 -200.562972)
		(width 0.20066)
		(layer "F.Cu")
		(net "M_E_CPU0_SB_DQS_DN<3>")
	)
	(segment
		(start 386.079746 -228.50729)
		(end 386.083048 -228.505258)
		(width 0.088646)
		(layer "F.Cu")
		(net "M_E_CPU0_SB_DQS_DN<3>")
	)
	(segment
		(start 386.083302 -228.505258)
		(end 386.08381 -228.505004)
		(width 0.088646)
		(layer "F.Cu")
		(net "M_E_CPU0_SB_DQS_DN<3>")
	)
	(segment
		(start 386.984494 -228.541072)
		(end 387.26872 -228.42347)
		(width 0.088646)
		(layer "F.Cu")
		(net "M_E_CPU0_SB_DQS_DN<3>")
	)
	(segment
		(start 389.279638 -212.096858)
		(end 389.279638 -210.940396)
		(width 0.1524)
		(layer "F.Cu")
		(net "M_E_CPU0_SB_DQS_DN<3>")
	)
	(segment
		(start 390.278112 -205.893924)
		(end 390.796272 -205.375764)
		(width 0.20066)
		(layer "F.Cu")
		(net "M_E_CPU0_SB_DQS_DN<3>")
	)
	(segment
		(start 389.242808 -210.903566)
		(end 389.242808 -210.865212)
		(width 0.1524)
		(layer "F.Cu")
		(net "M_E_CPU0_SB_DQS_DN<3>")
	)
	(segment
		(start 409.074112 -200.562972)
		(end 408.073098 -200.148444)
		(width 0.20066)
		(layer "F.Cu")
		(net "M_E_CPU0_SB_DQS_DN<3>")
	)
	(segment
		(start 388.165086 -228.12248)
		(end 388.372096 -227.91547)
		(width 0.088646)
		(layer "F.Cu")
		(net "M_E_CPU0_SB_DQS_DN<3>")
	)
	(segment
		(start 384.927094 -227.81514)
		(end 384.985768 -227.819966)
		(width 0.088646)
		(layer "F.Cu")
		(net "M_E_CPU0_SB_DQS_DN<3>")
	)
	(segment
		(start 412.674308 -200.567798)
		(end 412.46933 -200.567798)
		(width 0.20066)
		(layer "F.Cu")
		(net "M_E_CPU0_SB_DQS_DN<3>")
	)
	(segment
		(start 397.792702 -200.47204)
		(end 404.233634 -200.47204)
		(width 0.20066)
		(layer "F.Cu")
		(net "M_E_CPU0_SB_DQS_DN<3>")
	)
	(segment
		(start 393.067032 -203.374244)
		(end 394.890498 -203.374244)
		(width 0.20066)
		(layer "F.Cu")
		(net "M_E_CPU0_SB_DQS_DN<3>")
	)
	(segment
		(start 405.50084 -199.866758)
		(end 406.753314 -199.866758)
		(width 0.20066)
		(layer "F.Cu")
		(net "M_E_CPU0_SB_DQS_DN<3>")
	)
	(segment
		(start 411.855666 -200.2917)
		(end 409.849828 -200.2917)
		(width 0.1016)
		(layer "F.Cu")
		(net "M_E_CPU0_SB_DQS_DN<3>")
	)
	(segment
		(start 389.50138 -226.741482)
		(end 389.50138 -213.18855)
		(width 0.1524)
		(layer "F.Cu")
		(net "M_E_CPU0_SB_DQS_DN<3>")
	)
	(segment
		(start 387.68909 -228.249226)
		(end 387.99516 -228.12248)
		(width 0.088646)
		(layer "F.Cu")
		(net "M_E_CPU0_SB_DQS_DN<3>")
	)
	(segment
		(start 407.58364 -200.148444)
		(end 407.301954 -199.866758)
		(width 0.20066)
		(layer "F.Cu")
		(net "M_E_CPU0_SB_DQS_DN<3>")
	)
	(segment
		(start 405.123142 -199.86879)
		(end 405.498808 -199.86879)
		(width 0.20066)
		(layer "F.Cu")
		(net "M_E_CPU0_SB_DQS_DN<3>")
	)
	(segment
		(start 407.301954 -199.866758)
		(end 406.753314 -199.866758)
		(width 0.20066)
		(layer "F.Cu")
		(net "M_E_CPU0_SB_DQS_DN<3>")
	)
	(segment
		(start 386.083048 -228.505258)
		(end 386.083302 -228.505258)
		(width 0.088646)
		(layer "F.Cu")
		(net "M_E_CPU0_SB_DQS_DN<3>")
	)
	(segment
		(start 409.526994 -200.278492)
		(end 409.242514 -200.562972)
		(width 0.20066)
		(layer "F.Cu")
		(net "M_E_CPU0_SB_DQS_DN<3>")
	)
	(segment
		(start 389.242808 -210.865212)
		(end 389.242808 -208.393538)
		(width 0.20066)
		(layer "F.Cu")
		(net "M_E_CPU0_SB_DQS_DN<3>")
	)
	(segment
		(start 390.796272 -205.375764)
		(end 390.796018 -205.375764)
		(width 0.20066)
		(layer "F.Cu")
		(net "M_E_CPU0_SB_DQS_DN<3>")
	)
	(segment
		(start 385.242562 -227.95103)
		(end 385.59232 -228.420422)
		(width 0.088646)
		(layer "F.Cu")
		(net "M_E_CPU0_SB_DQS_DN<3>")
	)
	(segment
		(start 388.38759 -227.855272)
		(end 389.50138 -226.741482)
		(width 0.1524)
		(layer "F.Cu")
		(net "M_E_CPU0_SB_DQS_DN<3>")
	)
	(segment
		(start 414.297114 -199.866758)
		(end 413.707834 -199.866758)
		(width 0.20066)
		(layer "F.Cu")
		(net "M_E_CPU0_SB_DQS_DN<3>")
	)
	(segment
		(start 412.46933 -200.567798)
		(end 412.185104 -200.283572)
		(width 0.20066)
		(layer "F.Cu")
		(net "M_E_CPU0_SB_DQS_DN<3>")
	)
	(segment
		(start 388.372096 -227.870766)
		(end 388.38759 -227.855272)
		(width 0.088646)
		(layer "F.Cu")
		(net "M_E_CPU0_SB_DQS_DN<3>")
	)
	(segment
		(start 411.863794 -200.283572)
		(end 411.855666 -200.2917)
		(width 0.1016)
		(layer "F.Cu")
		(net "M_E_CPU0_SB_DQS_DN<3>")
	)
	(segment
		(start 386.08381 -228.505004)
		(end 386.128006 -228.479604)
		(width 0.088646)
		(layer "F.Cu")
		(net "M_E_CPU0_SB_DQS_DN<3>")
	)
	(segment
		(start 385.59232 -228.420422)
		(end 385.630674 -228.45522)
		(width 0.088646)
		(layer "F.Cu")
		(net "M_E_CPU0_SB_DQS_DN<3>")
	)
	(segment
		(start 385.187698 -227.902516)
		(end 385.229354 -227.93706)
		(width 0.088646)
		(layer "F.Cu")
		(net "M_E_CPU0_SB_DQS_DN<3>")
	)
	(segment
		(start 412.185104 -200.283572)
		(end 411.863794 -200.283572)
		(width 0.20066)
		(layer "F.Cu")
		(net "M_E_CPU0_SB_DQS_DN<3>")
	)
	(segment
		(start 404.640034 -200.065386)
		(end 405.007572 -199.912986)
		(width 0.20066)
		(layer "F.Cu")
		(net "M_E_CPU0_SB_DQS_DN<3>")
	)
	(segment
		(start 386.690362 -228.529134)
		(end 386.71373 -228.541072)
		(width 0.088646)
		(layer "F.Cu")
		(net "M_E_CPU0_SB_DQS_DN<3>")
	)
	(segment
		(start 409.831794 -200.278492)
		(end 409.526994 -200.278492)
		(width 0.20066)
		(layer "F.Cu")
		(net "M_E_CPU0_SB_DQS_DN<3>")
	)
	(segment
		(start 394.890498 -203.374244)
		(end 397.792702 -200.47204)
		(width 0.20066)
		(layer "F.Cu")
		(net "M_E_CPU0_SB_DQS_DN<3>")
	)
	(segment
		(start 389.28929 -212.120226)
		(end 389.279638 -212.096858)
		(width 0.1524)
		(layer "F.Cu")
		(net "M_E_CPU0_SB_DQS_DN<3>")
	)
	(segment
		(start 409.83662 -200.278492)
		(end 409.831794 -200.278492)
		(width 0.101854)
		(layer "F.Cu")
		(net "M_E_CPU0_SB_DQS_DN<3>")
	)
	(segment
		(start 390.796018 -205.375764)
		(end 392.607546 -203.56449)
		(width 0.20066)
		(layer "F.Cu")
		(net "M_E_CPU0_SB_DQS_DN<3>")
	)
	(segment
		(start 386.628894 -228.494082)
		(end 386.690362 -228.529134)
		(width 0.088646)
		(layer "F.Cu")
		(net "M_E_CPU0_SB_DQS_DN<3>")
	)
	(segment
		(start 385.630674 -228.45522)
		(end 385.630674 -228.455474)
		(width 0.088646)
		(layer "F.Cu")
		(net "M_E_CPU0_SB_DQS_DN<3>")
	)
	(segment
		(start 387.26872 -228.422962)
		(end 387.68909 -228.249226)
		(width 0.088646)
		(layer "F.Cu")
		(net "M_E_CPU0_SB_DQS_DN<3>")
	)
	(segment
		(start 404.233634 -200.47204)
		(end 404.640034 -200.065386)
		(width 0.20066)
		(layer "F.Cu")
		(net "M_E_CPU0_SB_DQS_DN<3>")
	)
	(segment
		(start 389.242808 -208.393538)
		(end 390.278112 -205.893924)
		(width 0.20066)
		(layer "F.Cu")
		(net "M_E_CPU0_SB_DQS_DN<3>")
	)
	(segment
		(start 405.498808 -199.86879)
		(end 405.50084 -199.866758)
		(width 0.20066)
		(layer "F.Cu")
		(net "M_E_CPU0_SB_DQS_DN<3>")
	)
	(segment
		(start 408.073098 -200.148444)
		(end 407.58364 -200.148444)
		(width 0.20066)
		(layer "F.Cu")
		(net "M_E_CPU0_SB_DQS_DN<3>")
	)
	(segment
		(start 388.372096 -227.91547)
		(end 388.372096 -227.870766)
		(width 0.088646)
		(layer "F.Cu")
		(net "M_E_CPU0_SB_DQS_DN<3>")
	)
	(segment
		(start 409.849828 -200.2917)
		(end 409.83662 -200.278492)
		(width 0.1016)
		(layer "F.Cu")
		(net "M_E_CPU0_SB_DQS_DN<3>")
	)
	(segment
		(start 413.13481 -200.107296)
		(end 412.674308 -200.567798)
		(width 0.20066)
		(layer "F.Cu")
		(net "M_E_CPU0_SB_DQS_DN<3>")
	)
	(segment
		(start 392.607546 -203.56449)
		(end 393.067032 -203.374244)
		(width 0.20066)
		(layer "F.Cu")
		(net "M_E_CPU0_SB_DQS_DN<3>")
	)
	(segment
		(start 389.279638 -210.940396)
		(end 389.242808 -210.903566)
		(width 0.1524)
		(layer "F.Cu")
		(net "M_E_CPU0_SB_DQS_DN<3>")
	)
	(segment
		(start 413.707834 -199.866758)
		(end 413.467296 -200.107296)
		(width 0.20066)
		(layer "F.Cu")
		(net "M_E_CPU0_SB_DQS_DN<3>")
	)
	(segment
		(start 405.009096 -199.912478)
		(end 405.123142 -199.86879)
		(width 0.20066)
		(layer "F.Cu")
		(net "M_E_CPU0_SB_DQS_DN<3>")
	)
	(segment
		(start 386.71373 -228.541072)
		(end 386.984494 -228.541072)
		(width 0.088646)
		(layer "F.Cu")
		(net "M_E_CPU0_SB_DQS_DN<3>")
	)
	(segment
		(start 413.467296 -200.107296)
		(end 413.13481 -200.107296)
		(width 0.20066)
		(layer "F.Cu")
		(net "M_E_CPU0_SB_DQS_DN<3>")
	)
	(segment
		(start 387.26872 -228.42347)
		(end 387.26872 -228.422962)
		(width 0.088646)
		(layer "F.Cu")
		(net "M_E_CPU0_SB_DQS_DN<3>")
	)
	(segment
		(start 389.50138 -213.18855)
		(end 389.28929 -212.120226)
		(width 0.1524)
		(layer "F.Cu")
		(net "M_E_CPU0_SB_DQS_DN<3>")
	)
	(segment
		(start 405.007572 -199.912986)
		(end 405.009096 -199.912478)
		(width 0.20066)
		(layer "F.Cu")
		(net "M_E_CPU0_SB_DQS_DN<3>")
	)
	(segment
		(start 384.015234 -228.1809)
		(end 384.739642 -227.847906)
		(width 0.088646)
		(layer "F.Cu")
		(net "M_E_CPU0_SB_DQS_DN<3>")
	)
	(segment
		(start 387.99516 -228.12248)
		(end 388.165086 -228.12248)
		(width 0.088646)
		(layer "F.Cu")
		(net "M_E_CPU0_SB_DQS_DN<3>")
	)
	(arc
		(start 385.630674 -228.455474)
		(mid 385.846827 -228.553888)
		(end 386.079746 -228.50729)
		(width 0.088646)
		(layer "F.Cu")
		(net "M_E_CPU0_SB_DQS_DN<3>")
	)
	(arc
		(start 384.739642 -227.847906)
		(mid 384.831238 -227.819336)
		(end 384.927094 -227.81514)
		(width 0.088646)
		(layer "F.Cu")
		(net "M_E_CPU0_SB_DQS_DN<3>")
	)
	(arc
		(start 384.985768 -227.819966)
		(mid 385.093096 -227.845676)
		(end 385.187698 -227.902516)
		(width 0.088646)
		(layer "F.Cu")
		(net "M_E_CPU0_SB_DQS_DN<3>")
	)
	(arc
		(start 386.128006 -228.479604)
		(mid 386.175568 -228.456503)
		(end 386.225796 -228.43998)
		(width 0.088646)
		(layer "F.Cu")
		(net "M_E_CPU0_SB_DQS_DN<3>")
	)
	(arc
		(start 385.229354 -227.93706)
		(mid 385.236375 -227.943651)
		(end 385.242562 -227.95103)
		(width 0.088646)
		(layer "F.Cu")
		(net "M_E_CPU0_SB_DQS_DN<3>")
	)
	(arc
		(start 386.225796 -228.43998)
		(mid 386.432623 -228.4277)
		(end 386.628894 -228.494082)
		(width 0.088646)
		(layer "F.Cu")
		(net "M_E_CPU0_SB_DQS_DN<3>")
	)
	(segment
		(start 413.576008 -209.45729)
		(end 413.223202 -209.45729)
		(width 0.20066)
		(layer "F.Cu")
		(net "M_E_CPU0_SB_DQS_DN<2>")
	)
	(segment
		(start 387.15188 -233.340656)
		(end 387.945884 -233.340656)
		(width 0.088646)
		(layer "F.Cu")
		(net "M_E_CPU0_SB_DQS_DN<2>")
	)
	(segment
		(start 411.863794 -209.63128)
		(end 411.857952 -209.63128)
		(width 0.101854)
		(layer "F.Cu")
		(net "M_E_CPU0_SB_DQS_DN<2>")
	)
	(segment
		(start 393.550902 -216.890346)
		(end 393.746736 -216.694512)
		(width 0.1524)
		(layer "F.Cu")
		(net "M_E_CPU0_SB_DQS_DN<2>")
	)
	(segment
		(start 393.41298 -228.3841)
		(end 393.41298 -217.028522)
		(width 0.1524)
		(layer "F.Cu")
		(net "M_E_CPU0_SB_DQS_DN<2>")
	)
	(segment
		(start 385.48056 -233.029252)
		(end 385.479798 -233.030014)
		(width 0.088646)
		(layer "F.Cu")
		(net "M_E_CPU0_SB_DQS_DN<2>")
	)
	(segment
		(start 411.857952 -209.63128)
		(end 411.847538 -209.641694)
		(width 0.1016)
		(layer "F.Cu")
		(net "M_E_CPU0_SB_DQS_DN<2>")
	)
	(segment
		(start 393.773406 -216.61628)
		(end 400.966686 -209.423)
		(width 0.20066)
		(layer "F.Cu")
		(net "M_E_CPU0_SB_DQS_DN<2>")
	)
	(segment
		(start 385.109212 -232.722166)
		(end 385.223258 -232.78338)
		(width 0.088646)
		(layer "F.Cu")
		(net "M_E_CPU0_SB_DQS_DN<2>")
	)
	(segment
		(start 386.68579 -233.418126)
		(end 387.07441 -233.418126)
		(width 0.088646)
		(layer "F.Cu")
		(net "M_E_CPU0_SB_DQS_DN<2>")
	)
	(segment
		(start 409.28163 -209.872326)
		(end 409.009596 -209.872326)
		(width 0.20066)
		(layer "F.Cu")
		(net "M_E_CPU0_SB_DQS_DN<2>")
	)
	(segment
		(start 413.223202 -209.45729)
		(end 412.785306 -209.895186)
		(width 0.20066)
		(layer "F.Cu")
		(net "M_E_CPU0_SB_DQS_DN<2>")
	)
	(segment
		(start 409.831794 -209.612484)
		(end 409.541472 -209.612484)
		(width 0.20066)
		(layer "F.Cu")
		(net "M_E_CPU0_SB_DQS_DN<2>")
	)
	(segment
		(start 385.865624 -233.448098)
		(end 385.955032 -233.448098)
		(width 0.088646)
		(layer "F.Cu")
		(net "M_E_CPU0_SB_DQS_DN<2>")
	)
	(segment
		(start 385.676394 -233.375708)
		(end 385.865624 -233.448098)
		(width 0.088646)
		(layer "F.Cu")
		(net "M_E_CPU0_SB_DQS_DN<2>")
	)
	(segment
		(start 409.541472 -209.612484)
		(end 409.28163 -209.872326)
		(width 0.20066)
		(layer "F.Cu")
		(net "M_E_CPU0_SB_DQS_DN<2>")
	)
	(segment
		(start 388.326122 -233.308652)
		(end 388.488428 -233.308652)
		(width 0.1524)
		(layer "F.Cu")
		(net "M_E_CPU0_SB_DQS_DN<2>")
	)
	(segment
		(start 385.676394 -233.375454)
		(end 385.676394 -233.375708)
		(width 0.088646)
		(layer "F.Cu")
		(net "M_E_CPU0_SB_DQS_DN<2>")
	)
	(segment
		(start 385.48056 -233.01198)
		(end 385.48056 -233.029252)
		(width 0.088646)
		(layer "F.Cu")
		(net "M_E_CPU0_SB_DQS_DN<2>")
	)
	(segment
		(start 411.847538 -209.641694)
		(end 409.86583 -209.641694)
		(width 0.1016)
		(layer "F.Cu")
		(net "M_E_CPU0_SB_DQS_DN<2>")
	)
	(segment
		(start 406.01138 -209.423)
		(end 406.217628 -209.216752)
		(width 0.20066)
		(layer "F.Cu")
		(net "M_E_CPU0_SB_DQS_DN<2>")
	)
	(segment
		(start 412.785306 -209.895186)
		(end 412.439612 -209.895186)
		(width 0.20066)
		(layer "F.Cu")
		(net "M_E_CPU0_SB_DQS_DN<2>")
	)
	(segment
		(start 393.41298 -217.028522)
		(end 393.550902 -216.8906)
		(width 0.1524)
		(layer "F.Cu")
		(net "M_E_CPU0_SB_DQS_DN<2>")
	)
	(segment
		(start 386.580126 -233.312462)
		(end 386.68579 -233.418126)
		(width 0.088646)
		(layer "F.Cu")
		(net "M_E_CPU0_SB_DQS_DN<2>")
	)
	(segment
		(start 385.223258 -232.78338)
		(end 385.38277 -232.91419)
		(width 0.088646)
		(layer "F.Cu")
		(net "M_E_CPU0_SB_DQS_DN<2>")
	)
	(segment
		(start 385.479798 -233.030014)
		(end 385.479798 -233.228388)
		(width 0.088646)
		(layer "F.Cu")
		(net "M_E_CPU0_SB_DQS_DN<2>")
	)
	(segment
		(start 413.816546 -209.216752)
		(end 413.576008 -209.45729)
		(width 0.20066)
		(layer "F.Cu")
		(net "M_E_CPU0_SB_DQS_DN<2>")
	)
	(segment
		(start 393.550902 -216.8906)
		(end 393.550902 -216.890346)
		(width 0.1524)
		(layer "F.Cu")
		(net "M_E_CPU0_SB_DQS_DN<2>")
	)
	(segment
		(start 387.945884 -233.340656)
		(end 387.946138 -233.340402)
		(width 0.088646)
		(layer "F.Cu")
		(net "M_E_CPU0_SB_DQS_DN<2>")
	)
	(segment
		(start 400.966686 -209.423)
		(end 406.01138 -209.423)
		(width 0.20066)
		(layer "F.Cu")
		(net "M_E_CPU0_SB_DQS_DN<2>")
	)
	(segment
		(start 409.83662 -209.612484)
		(end 409.831794 -209.612484)
		(width 0.101854)
		(layer "F.Cu")
		(net "M_E_CPU0_SB_DQS_DN<2>")
	)
	(segment
		(start 384.412744 -232.957878)
		(end 384.886962 -232.683812)
		(width 0.088646)
		(layer "F.Cu")
		(net "M_E_CPU0_SB_DQS_DN<2>")
	)
	(segment
		(start 409.86583 -209.641694)
		(end 409.83662 -209.612484)
		(width 0.1016)
		(layer "F.Cu")
		(net "M_E_CPU0_SB_DQS_DN<2>")
	)
	(segment
		(start 414.297114 -209.216752)
		(end 413.816546 -209.216752)
		(width 0.20066)
		(layer "F.Cu")
		(net "M_E_CPU0_SB_DQS_DN<2>")
	)
	(segment
		(start 393.746482 -216.643204)
		(end 393.773406 -216.61628)
		(width 0.1524)
		(layer "F.Cu")
		(net "M_E_CPU0_SB_DQS_DN<2>")
	)
	(segment
		(start 412.175706 -209.63128)
		(end 411.863794 -209.63128)
		(width 0.20066)
		(layer "F.Cu")
		(net "M_E_CPU0_SB_DQS_DN<2>")
	)
	(segment
		(start 387.07441 -233.418126)
		(end 387.15188 -233.340656)
		(width 0.088646)
		(layer "F.Cu")
		(net "M_E_CPU0_SB_DQS_DN<2>")
	)
	(segment
		(start 407.301954 -209.216752)
		(end 406.753314 -209.216752)
		(width 0.20066)
		(layer "F.Cu")
		(net "M_E_CPU0_SB_DQS_DN<2>")
	)
	(segment
		(start 412.439612 -209.895186)
		(end 412.175706 -209.63128)
		(width 0.20066)
		(layer "F.Cu")
		(net "M_E_CPU0_SB_DQS_DN<2>")
	)
	(segment
		(start 388.488428 -233.308652)
		(end 393.41298 -228.3841)
		(width 0.1524)
		(layer "F.Cu")
		(net "M_E_CPU0_SB_DQS_DN<2>")
	)
	(segment
		(start 385.479798 -233.228388)
		(end 385.676394 -233.375454)
		(width 0.088646)
		(layer "F.Cu")
		(net "M_E_CPU0_SB_DQS_DN<2>")
	)
	(segment
		(start 388.304024 -233.308652)
		(end 388.326122 -233.308652)
		(width 0.088646)
		(layer "F.Cu")
		(net "M_E_CPU0_SB_DQS_DN<2>")
	)
	(segment
		(start 409.009596 -209.872326)
		(end 408.694636 -209.74177)
		(width 0.20066)
		(layer "F.Cu")
		(net "M_E_CPU0_SB_DQS_DN<2>")
	)
	(segment
		(start 385.955032 -233.448098)
		(end 386.279898 -233.312462)
		(width 0.088646)
		(layer "F.Cu")
		(net "M_E_CPU0_SB_DQS_DN<2>")
	)
	(segment
		(start 385.38277 -232.91419)
		(end 385.48056 -233.01198)
		(width 0.088646)
		(layer "F.Cu")
		(net "M_E_CPU0_SB_DQS_DN<2>")
	)
	(segment
		(start 408.451304 -209.498438)
		(end 407.58364 -209.498438)
		(width 0.20066)
		(layer "F.Cu")
		(net "M_E_CPU0_SB_DQS_DN<2>")
	)
	(segment
		(start 406.217628 -209.216752)
		(end 406.753314 -209.216752)
		(width 0.20066)
		(layer "F.Cu")
		(net "M_E_CPU0_SB_DQS_DN<2>")
	)
	(segment
		(start 388.272274 -233.340402)
		(end 388.304024 -233.308652)
		(width 0.088646)
		(layer "F.Cu")
		(net "M_E_CPU0_SB_DQS_DN<2>")
	)
	(segment
		(start 385.035552 -232.691432)
		(end 385.109212 -232.722166)
		(width 0.088646)
		(layer "F.Cu")
		(net "M_E_CPU0_SB_DQS_DN<2>")
	)
	(segment
		(start 408.694636 -209.74177)
		(end 408.451304 -209.498438)
		(width 0.20066)
		(layer "F.Cu")
		(net "M_E_CPU0_SB_DQS_DN<2>")
	)
	(segment
		(start 407.58364 -209.498438)
		(end 407.301954 -209.216752)
		(width 0.20066)
		(layer "F.Cu")
		(net "M_E_CPU0_SB_DQS_DN<2>")
	)
	(segment
		(start 387.946138 -233.340402)
		(end 388.272274 -233.340402)
		(width 0.088646)
		(layer "F.Cu")
		(net "M_E_CPU0_SB_DQS_DN<2>")
	)
	(segment
		(start 393.746736 -216.694512)
		(end 393.746482 -216.643204)
		(width 0.1524)
		(layer "F.Cu")
		(net "M_E_CPU0_SB_DQS_DN<2>")
	)
	(segment
		(start 386.279898 -233.312462)
		(end 386.580126 -233.312462)
		(width 0.088646)
		(layer "F.Cu")
		(net "M_E_CPU0_SB_DQS_DN<2>")
	)
	(arc
		(start 384.886962 -232.683812)
		(mid 384.96156 -232.681693)
		(end 385.035552 -232.691432)
		(width 0.088646)
		(layer "F.Cu")
		(net "M_E_CPU0_SB_DQS_DN<2>")
	)
	(arc
		(start 384.015234 -233.064304)
		(mid 384.221003 -233.037296)
		(end 384.412744 -232.957878)
		(width 0.088646)
		(layer "F.Cu")
		(net "M_E_CPU0_SB_DQS_DN<2>")
	)
	(segment
		(start 385.242562 -237.717584)
		(end 385.349496 -237.860586)
		(width 0.088646)
		(layer "F.Cu")
		(net "M_E_CPU0_SB_DQS_DN<1>")
	)
	(segment
		(start 385.640072 -238.205772)
		(end 385.723384 -238.280194)
		(width 0.088646)
		(layer "F.Cu")
		(net "M_E_CPU0_SB_DQS_DN<1>")
	)
	(segment
		(start 387.52653 -238.197644)
		(end 388.168134 -237.556294)
		(width 0.088646)
		(layer "F.Cu")
		(net "M_E_CPU0_SB_DQS_DN<1>")
	)
	(segment
		(start 386.1308 -238.243618)
		(end 386.135626 -238.241586)
		(width 0.088646)
		(layer "F.Cu")
		(net "M_E_CPU0_SB_DQS_DN<1>")
	)
	(segment
		(start 384.015234 -237.947454)
		(end 384.670808 -237.64621)
		(width 0.088646)
		(layer "F.Cu")
		(net "M_E_CPU0_SB_DQS_DN<1>")
	)
	(segment
		(start 401.835112 -224.625662)
		(end 401.835112 -222.346774)
		(width 0.20066)
		(layer "F.Cu")
		(net "M_E_CPU0_SB_DQS_DN<1>")
	)
	(segment
		(start 404.438358 -219.743528)
		(end 404.438358 -219.046298)
		(width 0.20066)
		(layer "F.Cu")
		(net "M_E_CPU0_SB_DQS_DN<1>")
	)
	(segment
		(start 385.348988 -237.86084)
		(end 385.4577 -238.006636)
		(width 0.088646)
		(layer "F.Cu")
		(net "M_E_CPU0_SB_DQS_DN<1>")
	)
	(segment
		(start 405.774652 -218.566746)
		(end 406.753314 -218.566746)
		(width 0.20066)
		(layer "F.Cu")
		(net "M_E_CPU0_SB_DQS_DN<1>")
	)
	(segment
		(start 412.228284 -218.974924)
		(end 411.863794 -218.974924)
		(width 0.20066)
		(layer "F.Cu")
		(net "M_E_CPU0_SB_DQS_DN<1>")
	)
	(segment
		(start 387.140704 -238.3028)
		(end 387.372352 -238.265208)
		(width 0.088646)
		(layer "F.Cu")
		(net "M_E_CPU0_SB_DQS_DN<1>")
	)
	(segment
		(start 388.699756 -237.238286)
		(end 390.14654 -237.238286)
		(width 0.1524)
		(layer "F.Cu")
		(net "M_E_CPU0_SB_DQS_DN<1>")
	)
	(segment
		(start 409.831794 -218.964764)
		(end 409.394914 -218.964764)
		(width 0.20066)
		(layer "F.Cu")
		(net "M_E_CPU0_SB_DQS_DN<1>")
	)
	(segment
		(start 409.858718 -218.991688)
		(end 409.831794 -218.964764)
		(width 0.1016)
		(layer "F.Cu")
		(net "M_E_CPU0_SB_DQS_DN<1>")
	)
	(segment
		(start 408.671014 -219.26296)
		(end 408.256486 -218.848432)
		(width 0.20066)
		(layer "F.Cu")
		(net "M_E_CPU0_SB_DQS_DN<1>")
	)
	(segment
		(start 385.187698 -237.66907)
		(end 385.229354 -237.703614)
		(width 0.088646)
		(layer "F.Cu")
		(net "M_E_CPU0_SB_DQS_DN<1>")
	)
	(segment
		(start 386.082032 -238.271812)
		(end 386.130546 -238.243618)
		(width 0.088646)
		(layer "F.Cu")
		(net "M_E_CPU0_SB_DQS_DN<1>")
	)
	(segment
		(start 404.918418 -218.566238)
		(end 405.774144 -218.566238)
		(width 0.20066)
		(layer "F.Cu")
		(net "M_E_CPU0_SB_DQS_DN<1>")
	)
	(segment
		(start 388.669022 -237.26902)
		(end 388.699756 -237.238286)
		(width 0.088646)
		(layer "F.Cu")
		(net "M_E_CPU0_SB_DQS_DN<1>")
	)
	(segment
		(start 385.4577 -238.006636)
		(end 385.640072 -238.205772)
		(width 0.088646)
		(layer "F.Cu")
		(net "M_E_CPU0_SB_DQS_DN<1>")
	)
	(segment
		(start 387.526276 -238.197644)
		(end 387.52653 -238.197644)
		(width 0.088646)
		(layer "F.Cu")
		(net "M_E_CPU0_SB_DQS_DN<1>")
	)
	(segment
		(start 401.835112 -222.346774)
		(end 404.438358 -219.743528)
		(width 0.20066)
		(layer "F.Cu")
		(net "M_E_CPU0_SB_DQS_DN<1>")
	)
	(segment
		(start 407.58364 -218.848432)
		(end 407.301954 -218.566746)
		(width 0.20066)
		(layer "F.Cu")
		(net "M_E_CPU0_SB_DQS_DN<1>")
	)
	(segment
		(start 398.114774 -228.397816)
		(end 398.114774 -228.346)
		(width 0.1524)
		(layer "F.Cu")
		(net "M_E_CPU0_SB_DQS_DN<1>")
	)
	(segment
		(start 388.168134 -237.556294)
		(end 388.168134 -237.556548)
		(width 0.088646)
		(layer "F.Cu")
		(net "M_E_CPU0_SB_DQS_DN<1>")
	)
	(segment
		(start 411.863794 -218.974924)
		(end 411.84703 -218.991688)
		(width 0.1016)
		(layer "F.Cu")
		(net "M_E_CPU0_SB_DQS_DN<1>")
	)
	(segment
		(start 385.349496 -237.860586)
		(end 385.348988 -237.86084)
		(width 0.088646)
		(layer "F.Cu")
		(net "M_E_CPU0_SB_DQS_DN<1>")
	)
	(segment
		(start 412.73984 -219.202254)
		(end 412.455614 -219.202254)
		(width 0.20066)
		(layer "F.Cu")
		(net "M_E_CPU0_SB_DQS_DN<1>")
	)
	(segment
		(start 398.114774 -228.346)
		(end 398.141698 -228.319076)
		(width 0.1524)
		(layer "F.Cu")
		(net "M_E_CPU0_SB_DQS_DN<1>")
	)
	(segment
		(start 404.438358 -219.046298)
		(end 404.918418 -218.566238)
		(width 0.20066)
		(layer "F.Cu")
		(net "M_E_CPU0_SB_DQS_DN<1>")
	)
	(segment
		(start 411.84703 -218.991688)
		(end 409.858718 -218.991688)
		(width 0.1016)
		(layer "F.Cu")
		(net "M_E_CPU0_SB_DQS_DN<1>")
	)
	(segment
		(start 413.467296 -218.807284)
		(end 413.13481 -218.807284)
		(width 0.20066)
		(layer "F.Cu")
		(net "M_E_CPU0_SB_DQS_DN<1>")
	)
	(segment
		(start 413.13481 -218.807284)
		(end 412.73984 -219.202254)
		(width 0.20066)
		(layer "F.Cu")
		(net "M_E_CPU0_SB_DQS_DN<1>")
	)
	(segment
		(start 413.707834 -218.566746)
		(end 413.467296 -218.807284)
		(width 0.20066)
		(layer "F.Cu")
		(net "M_E_CPU0_SB_DQS_DN<1>")
	)
	(segment
		(start 414.297114 -218.566746)
		(end 413.707834 -218.566746)
		(width 0.20066)
		(layer "F.Cu")
		(net "M_E_CPU0_SB_DQS_DN<1>")
	)
	(segment
		(start 408.256486 -218.848432)
		(end 407.58364 -218.848432)
		(width 0.20066)
		(layer "F.Cu")
		(net "M_E_CPU0_SB_DQS_DN<1>")
	)
	(segment
		(start 387.49605 -238.212884)
		(end 387.51129 -238.20501)
		(width 0.088646)
		(layer "F.Cu")
		(net "M_E_CPU0_SB_DQS_DN<1>")
	)
	(segment
		(start 405.774144 -218.566238)
		(end 405.774652 -218.566746)
		(width 0.20066)
		(layer "F.Cu")
		(net "M_E_CPU0_SB_DQS_DN<1>")
	)
	(segment
		(start 386.130546 -238.243618)
		(end 386.1308 -238.243618)
		(width 0.088646)
		(layer "F.Cu")
		(net "M_E_CPU0_SB_DQS_DN<1>")
	)
	(segment
		(start 390.14654 -237.238286)
		(end 397.32458 -230.060246)
		(width 0.1524)
		(layer "F.Cu")
		(net "M_E_CPU0_SB_DQS_DN<1>")
	)
	(segment
		(start 407.301954 -218.566746)
		(end 406.753314 -218.566746)
		(width 0.20066)
		(layer "F.Cu")
		(net "M_E_CPU0_SB_DQS_DN<1>")
	)
	(segment
		(start 386.823204 -238.3028)
		(end 387.140704 -238.3028)
		(width 0.088646)
		(layer "F.Cu")
		(net "M_E_CPU0_SB_DQS_DN<1>")
	)
	(segment
		(start 388.455662 -237.26902)
		(end 388.669022 -237.26902)
		(width 0.088646)
		(layer "F.Cu")
		(net "M_E_CPU0_SB_DQS_DN<1>")
	)
	(segment
		(start 409.096718 -219.26296)
		(end 408.671014 -219.26296)
		(width 0.20066)
		(layer "F.Cu")
		(net "M_E_CPU0_SB_DQS_DN<1>")
	)
	(segment
		(start 397.32458 -230.060246)
		(end 397.32458 -229.18801)
		(width 0.1524)
		(layer "F.Cu")
		(net "M_E_CPU0_SB_DQS_DN<1>")
	)
	(segment
		(start 412.455614 -219.202254)
		(end 412.228284 -218.974924)
		(width 0.20066)
		(layer "F.Cu")
		(net "M_E_CPU0_SB_DQS_DN<1>")
	)
	(segment
		(start 388.168134 -237.556548)
		(end 388.455662 -237.26902)
		(width 0.088646)
		(layer "F.Cu")
		(net "M_E_CPU0_SB_DQS_DN<1>")
	)
	(segment
		(start 398.141698 -228.319076)
		(end 401.835112 -224.625662)
		(width 0.20066)
		(layer "F.Cu")
		(net "M_E_CPU0_SB_DQS_DN<1>")
	)
	(segment
		(start 409.394914 -218.964764)
		(end 409.096718 -219.26296)
		(width 0.20066)
		(layer "F.Cu")
		(net "M_E_CPU0_SB_DQS_DN<1>")
	)
	(segment
		(start 397.32458 -229.18801)
		(end 398.114774 -228.397816)
		(width 0.1524)
		(layer "F.Cu")
		(net "M_E_CPU0_SB_DQS_DN<1>")
	)
	(segment
		(start 387.51129 -238.20501)
		(end 387.526276 -238.197644)
		(width 0.088646)
		(layer "F.Cu")
		(net "M_E_CPU0_SB_DQS_DN<1>")
	)
	(arc
		(start 386.135626 -238.241586)
		(mid 386.364815 -238.180127)
		(end 386.594096 -238.241332)
		(width 0.088646)
		(layer "F.Cu")
		(net "M_E_CPU0_SB_DQS_DN<1>")
	)
	(arc
		(start 387.372352 -238.265208)
		(mid 387.435043 -238.241037)
		(end 387.49605 -238.212884)
		(width 0.088646)
		(layer "F.Cu")
		(net "M_E_CPU0_SB_DQS_DN<1>")
	)
	(arc
		(start 385.723384 -238.280194)
		(mid 385.903785 -238.321783)
		(end 386.082032 -238.271812)
		(width 0.088646)
		(layer "F.Cu")
		(net "M_E_CPU0_SB_DQS_DN<1>")
	)
	(arc
		(start 386.594096 -238.241332)
		(mid 386.704604 -238.287152)
		(end 386.823204 -238.3028)
		(width 0.088646)
		(layer "F.Cu")
		(net "M_E_CPU0_SB_DQS_DN<1>")
	)
	(arc
		(start 384.670808 -237.64621)
		(mid 384.824554 -237.596645)
		(end 384.985768 -237.58652)
		(width 0.088646)
		(layer "F.Cu")
		(net "M_E_CPU0_SB_DQS_DN<1>")
	)
	(arc
		(start 384.985768 -237.58652)
		(mid 385.093096 -237.61223)
		(end 385.187698 -237.66907)
		(width 0.088646)
		(layer "F.Cu")
		(net "M_E_CPU0_SB_DQS_DN<1>")
	)
	(arc
		(start 385.229354 -237.703614)
		(mid 385.236375 -237.710205)
		(end 385.242562 -237.717584)
		(width 0.088646)
		(layer "F.Cu")
		(net "M_E_CPU0_SB_DQS_DN<1>")
	)
	(segment
		(start 407.58364 -228.198426)
		(end 407.301954 -227.91674)
		(width 0.20066)
		(layer "F.Cu")
		(net "M_E_CPU0_SB_DQS_DN<0>")
	)
	(segment
		(start 412.12643 -228.317552)
		(end 411.863794 -228.317552)
		(width 0.20066)
		(layer "F.Cu")
		(net "M_E_CPU0_SB_DQS_DN<0>")
	)
	(segment
		(start 381.665734 -235.506006)
		(end 381.665734 -234.970066)
		(width 0.20066)
		(layer "F.Cu")
		(net "M_E_CPU0_SB_DQS_DN<0>")
	)
	(segment
		(start 407.301954 -227.91674)
		(end 406.753314 -227.91674)
		(width 0.20066)
		(layer "F.Cu")
		(net "M_E_CPU0_SB_DQS_DN<0>")
	)
	(segment
		(start 411.844998 -228.317552)
		(end 411.820868 -228.341682)
		(width 0.1016)
		(layer "F.Cu")
		(net "M_E_CPU0_SB_DQS_DN<0>")
	)
	(segment
		(start 413.459676 -228.164898)
		(end 413.120586 -228.164898)
		(width 0.20066)
		(layer "F.Cu")
		(net "M_E_CPU0_SB_DQS_DN<0>")
	)
	(segment
		(start 413.120586 -228.164898)
		(end 412.661608 -228.623876)
		(width 0.20066)
		(layer "F.Cu")
		(net "M_E_CPU0_SB_DQS_DN<0>")
	)
	(segment
		(start 413.707834 -227.91674)
		(end 413.459676 -228.164898)
		(width 0.20066)
		(layer "F.Cu")
		(net "M_E_CPU0_SB_DQS_DN<0>")
	)
	(segment
		(start 408.702256 -228.612954)
		(end 408.287728 -228.198426)
		(width 0.20066)
		(layer "F.Cu")
		(net "M_E_CPU0_SB_DQS_DN<0>")
	)
	(segment
		(start 409.526994 -228.341682)
		(end 409.255722 -228.612954)
		(width 0.20066)
		(layer "F.Cu")
		(net "M_E_CPU0_SB_DQS_DN<0>")
	)
	(segment
		(start 408.287728 -228.198426)
		(end 407.58364 -228.198426)
		(width 0.20066)
		(layer "F.Cu")
		(net "M_E_CPU0_SB_DQS_DN<0>")
	)
	(segment
		(start 411.863794 -228.317552)
		(end 411.844998 -228.317552)
		(width 0.101854)
		(layer "F.Cu")
		(net "M_E_CPU0_SB_DQS_DN<0>")
	)
	(segment
		(start 412.432754 -228.623876)
		(end 412.12643 -228.317552)
		(width 0.20066)
		(layer "F.Cu")
		(net "M_E_CPU0_SB_DQS_DN<0>")
	)
	(segment
		(start 411.820868 -228.341682)
		(end 409.646882 -228.341682)
		(width 0.1016)
		(layer "F.Cu")
		(net "M_E_CPU0_SB_DQS_DN<0>")
	)
	(segment
		(start 409.255722 -228.612954)
		(end 408.702256 -228.612954)
		(width 0.20066)
		(layer "F.Cu")
		(net "M_E_CPU0_SB_DQS_DN<0>")
	)
	(segment
		(start 409.636214 -228.341682)
		(end 409.526994 -228.341682)
		(width 0.20066)
		(layer "F.Cu")
		(net "M_E_CPU0_SB_DQS_DN<0>")
	)
	(segment
		(start 412.661608 -228.623876)
		(end 412.432754 -228.623876)
		(width 0.20066)
		(layer "F.Cu")
		(net "M_E_CPU0_SB_DQS_DN<0>")
	)
	(segment
		(start 414.297114 -227.91674)
		(end 413.707834 -227.91674)
		(width 0.20066)
		(layer "F.Cu")
		(net "M_E_CPU0_SB_DQS_DN<0>")
	)
	(segment
		(start 409.646882 -228.341682)
		(end 409.636214 -228.341682)
		(width 0.101854)
		(layer "F.Cu")
		(net "M_E_CPU0_SB_DQS_DN<0>")
	)
	(segment
		(start 406.753314 -227.91674)
		(end 405.623014 -227.91674)
		(width 0.20066)
		(layer "F.Cu")
		(net "M_E_CPU0_SB_DQS_DN<0>")
	)
	(segment
		(start 381.295656 -235.027216)
		(end 381.352806 -234.970066)
		(width 0.088646)
		(layer "In2.Cu")
		(net "M_E_CPU0_SB_DQS_DN<0>")
	)
	(segment
		(start 403.006814 -229.510082)
		(end 402.830792 -229.510082)
		(width 0.18288)
		(layer "In2.Cu")
		(net "M_E_CPU0_SB_DQS_DN<0>")
	)
	(segment
		(start 403.394672 -228.946202)
		(end 403.394672 -229.122224)
		(width 0.18288)
		(layer "In2.Cu")
		(net "M_E_CPU0_SB_DQS_DN<0>")
	)
	(segment
		(start 402.44268 -230.074216)
		(end 402.054822 -230.462074)
		(width 0.18288)
		(layer "In2.Cu")
		(net "M_E_CPU0_SB_DQS_DN<0>")
	)
	(segment
		(start 386.177282 -235.294424)
		(end 386.16255 -235.285788)
		(width 0.088646)
		(layer "In2.Cu")
		(net "M_E_CPU0_SB_DQS_DN<0>")
	)
	(segment
		(start 405.369522 -228.170232)
		(end 404.346664 -228.170232)
		(width 0.18288)
		(layer "In2.Cu")
		(net "M_E_CPU0_SB_DQS_DN<0>")
	)
	(segment
		(start 405.623014 -227.91674)
		(end 405.369522 -228.170232)
		(width 0.18288)
		(layer "In2.Cu")
		(net "M_E_CPU0_SB_DQS_DN<0>")
	)
	(segment
		(start 403.394672 -229.122224)
		(end 403.006814 -229.510082)
		(width 0.18288)
		(layer "In2.Cu")
		(net "M_E_CPU0_SB_DQS_DN<0>")
	)
	(segment
		(start 403.782784 -228.55809)
		(end 403.394672 -228.946202)
		(width 0.18288)
		(layer "In2.Cu")
		(net "M_E_CPU0_SB_DQS_DN<0>")
	)
	(segment
		(start 402.054822 -230.462074)
		(end 401.8788 -230.462074)
		(width 0.18288)
		(layer "In2.Cu")
		(net "M_E_CPU0_SB_DQS_DN<0>")
	)
	(segment
		(start 401.490688 -230.850186)
		(end 401.490688 -231.026208)
		(width 0.18288)
		(layer "In2.Cu")
		(net "M_E_CPU0_SB_DQS_DN<0>")
	)
	(segment
		(start 381.478536 -235.294424)
		(end 381.469646 -235.289344)
		(width 0.088646)
		(layer "In2.Cu")
		(net "M_E_CPU0_SB_DQS_DN<0>")
	)
	(segment
		(start 404.346664 -228.170232)
		(end 403.958806 -228.55809)
		(width 0.18288)
		(layer "In2.Cu")
		(net "M_E_CPU0_SB_DQS_DN<0>")
	)
	(segment
		(start 384.297682 -235.294424)
		(end 384.287268 -235.288328)
		(width 0.088646)
		(layer "In2.Cu")
		(net "M_E_CPU0_SB_DQS_DN<0>")
	)
	(segment
		(start 387.55828 -235.34497)
		(end 387.30428 -235.34497)
		(width 0.088646)
		(layer "In2.Cu")
		(net "M_E_CPU0_SB_DQS_DN<0>")
	)
	(segment
		(start 398.372838 -234.143804)
		(end 396.65021 -234.857544)
		(width 0.18288)
		(layer "In2.Cu")
		(net "M_E_CPU0_SB_DQS_DN<0>")
	)
	(segment
		(start 388.636764 -234.857544)
		(end 388.577074 -234.917234)
		(width 0.088646)
		(layer "In2.Cu")
		(net "M_E_CPU0_SB_DQS_DN<0>")
	)
	(segment
		(start 402.44268 -229.898194)
		(end 402.44268 -230.074216)
		(width 0.18288)
		(layer "In2.Cu")
		(net "M_E_CPU0_SB_DQS_DN<0>")
	)
	(segment
		(start 388.577074 -234.917234)
		(end 387.986016 -234.917234)
		(width 0.088646)
		(layer "In2.Cu")
		(net "M_E_CPU0_SB_DQS_DN<0>")
	)
	(segment
		(start 401.490688 -231.026208)
		(end 398.372838 -234.143804)
		(width 0.18288)
		(layer "In2.Cu")
		(net "M_E_CPU0_SB_DQS_DN<0>")
	)
	(segment
		(start 385.237482 -235.294424)
		(end 385.22275 -235.285788)
		(width 0.088646)
		(layer "In2.Cu")
		(net "M_E_CPU0_SB_DQS_DN<0>")
	)
	(segment
		(start 403.958806 -228.55809)
		(end 403.782784 -228.55809)
		(width 0.18288)
		(layer "In2.Cu")
		(net "M_E_CPU0_SB_DQS_DN<0>")
	)
	(segment
		(start 402.830792 -229.510082)
		(end 402.44268 -229.898194)
		(width 0.18288)
		(layer "In2.Cu")
		(net "M_E_CPU0_SB_DQS_DN<0>")
	)
	(segment
		(start 401.8788 -230.462074)
		(end 401.490688 -230.850186)
		(width 0.18288)
		(layer "In2.Cu")
		(net "M_E_CPU0_SB_DQS_DN<0>")
	)
	(segment
		(start 387.986016 -234.917234)
		(end 387.55828 -235.34497)
		(width 0.088646)
		(layer "In2.Cu")
		(net "M_E_CPU0_SB_DQS_DN<0>")
	)
	(segment
		(start 396.65021 -234.857544)
		(end 388.636764 -234.857544)
		(width 0.18288)
		(layer "In2.Cu")
		(net "M_E_CPU0_SB_DQS_DN<0>")
	)
	(segment
		(start 381.352806 -234.970066)
		(end 381.665734 -234.970066)
		(width 0.088646)
		(layer "In2.Cu")
		(net "M_E_CPU0_SB_DQS_DN<0>")
	)
	(arc
		(start 383.732532 -235.294424)
		(mid 383.545334 -235.344567)
		(end 383.358136 -235.294424)
		(width 0.088646)
		(layer "In2.Cu")
		(net "M_E_CPU0_SB_DQS_DN<0>")
	)
	(arc
		(start 387.10235 -235.285788)
		(mid 386.825875 -235.218468)
		(end 386.551678 -235.294424)
		(width 0.088646)
		(layer "In2.Cu")
		(net "M_E_CPU0_SB_DQS_DN<0>")
	)
	(arc
		(start 382.792732 -235.294424)
		(mid 382.605534 -235.344567)
		(end 382.418336 -235.294424)
		(width 0.088646)
		(layer "In2.Cu")
		(net "M_E_CPU0_SB_DQS_DN<0>")
	)
	(arc
		(start 387.116828 -235.294678)
		(mid 387.10954 -235.290314)
		(end 387.10235 -235.285788)
		(width 0.088646)
		(layer "In2.Cu")
		(net "M_E_CPU0_SB_DQS_DN<0>")
	)
	(arc
		(start 384.287268 -235.288328)
		(mid 384.00909 -235.218605)
		(end 383.732532 -235.294424)
		(width 0.088646)
		(layer "In2.Cu")
		(net "M_E_CPU0_SB_DQS_DN<0>")
	)
	(arc
		(start 386.16255 -235.285788)
		(mid 385.886075 -235.218468)
		(end 385.611878 -235.294424)
		(width 0.088646)
		(layer "In2.Cu")
		(net "M_E_CPU0_SB_DQS_DN<0>")
	)
	(arc
		(start 385.611878 -235.294424)
		(mid 385.42468 -235.344567)
		(end 385.237482 -235.294424)
		(width 0.088646)
		(layer "In2.Cu")
		(net "M_E_CPU0_SB_DQS_DN<0>")
	)
	(arc
		(start 385.22275 -235.285788)
		(mid 384.946275 -235.218468)
		(end 384.672078 -235.294424)
		(width 0.088646)
		(layer "In2.Cu")
		(net "M_E_CPU0_SB_DQS_DN<0>")
	)
	(arc
		(start 387.30428 -235.34497)
		(mid 387.207232 -235.332191)
		(end 387.116828 -235.294678)
		(width 0.088646)
		(layer "In2.Cu")
		(net "M_E_CPU0_SB_DQS_DN<0>")
	)
	(arc
		(start 384.672078 -235.294424)
		(mid 384.48488 -235.344567)
		(end 384.297682 -235.294424)
		(width 0.088646)
		(layer "In2.Cu")
		(net "M_E_CPU0_SB_DQS_DN<0>")
	)
	(arc
		(start 381.852932 -235.294424)
		(mid 381.665734 -235.344567)
		(end 381.478536 -235.294424)
		(width 0.088646)
		(layer "In2.Cu")
		(net "M_E_CPU0_SB_DQS_DN<0>")
	)
	(arc
		(start 381.469646 -235.289344)
		(mid 381.353837 -235.177415)
		(end 381.295656 -235.027216)
		(width 0.088646)
		(layer "In2.Cu")
		(net "M_E_CPU0_SB_DQS_DN<0>")
	)
	(arc
		(start 382.418336 -235.294424)
		(mid 382.135634 -235.218648)
		(end 381.852932 -235.294424)
		(width 0.088646)
		(layer "In2.Cu")
		(net "M_E_CPU0_SB_DQS_DN<0>")
	)
	(arc
		(start 383.358136 -235.294424)
		(mid 383.075434 -235.218648)
		(end 382.792732 -235.294424)
		(width 0.088646)
		(layer "In2.Cu")
		(net "M_E_CPU0_SB_DQS_DN<0>")
	)
	(arc
		(start 386.551678 -235.294424)
		(mid 386.36448 -235.344567)
		(end 386.177282 -235.294424)
		(width 0.088646)
		(layer "In2.Cu")
		(net "M_E_CPU0_SB_DQS_DN<0>")
	)
	(segment
		(start 405.656542 -221.35084)
		(end 405.89073 -221.116652)
		(width 0.20066)
		(layer "F.Cu")
		(net "M_E_CPU0_SB_DQ<9>")
	)
	(segment
		(start 403.750272 -223.105726)
		(end 405.505158 -221.35084)
		(width 0.20066)
		(layer "F.Cu")
		(net "M_E_CPU0_SB_DQ<9>")
	)
	(segment
		(start 412.57855 -221.116652)
		(end 412.138876 -220.676978)
		(width 0.20066)
		(layer "F.Cu")
		(net "M_E_CPU0_SB_DQ<9>")
	)
	(segment
		(start 402.162264 -228.654102)
		(end 403.549612 -228.654102)
		(width 0.20066)
		(layer "F.Cu")
		(net "M_E_CPU0_SB_DQ<9>")
	)
	(segment
		(start 386.218938 -239.106456)
		(end 386.2197 -239.10671)
		(width 0.088646)
		(layer "F.Cu")
		(net "M_E_CPU0_SB_DQ<9>")
	)
	(segment
		(start 386.20319 -239.100614)
		(end 386.218938 -239.106456)
		(width 0.088646)
		(layer "F.Cu")
		(net "M_E_CPU0_SB_DQ<9>")
	)
	(segment
		(start 385.07543 -238.993426)
		(end 385.30403 -239.222026)
		(width 0.088646)
		(layer "F.Cu")
		(net "M_E_CPU0_SB_DQ<9>")
	)
	(segment
		(start 403.413976 -229.540562)
		(end 403.213316 -229.339902)
		(width 0.20066)
		(layer "F.Cu")
		(net "M_E_CPU0_SB_DQ<9>")
	)
	(segment
		(start 388.890764 -238.127286)
		(end 390.515602 -238.127286)
		(width 0.1016)
		(layer "F.Cu")
		(net "M_E_CPU0_SB_DQ<9>")
	)
	(segment
		(start 386.099558 -239.059974)
		(end 386.20319 -239.100614)
		(width 0.088646)
		(layer "F.Cu")
		(net "M_E_CPU0_SB_DQ<9>")
	)
	(segment
		(start 409.83662 -220.683074)
		(end 409.831794 -220.683074)
		(width 0.101854)
		(layer "F.Cu")
		(net "M_E_CPU0_SB_DQ<9>")
	)
	(segment
		(start 390.515602 -238.127286)
		(end 398.551908 -230.091996)
		(width 0.1016)
		(layer "F.Cu")
		(net "M_E_CPU0_SB_DQ<9>")
	)
	(segment
		(start 409.845256 -220.69171)
		(end 409.83662 -220.683074)
		(width 0.1016)
		(layer "F.Cu")
		(net "M_E_CPU0_SB_DQ<9>")
	)
	(segment
		(start 385.830064 -238.968026)
		(end 386.00761 -238.968026)
		(width 0.088646)
		(layer "F.Cu")
		(net "M_E_CPU0_SB_DQ<9>")
	)
	(segment
		(start 412.138876 -220.676978)
		(end 411.863794 -220.676978)
		(width 0.20066)
		(layer "F.Cu")
		(net "M_E_CPU0_SB_DQ<9>")
	)
	(segment
		(start 401.961604 -228.854762)
		(end 402.162264 -228.654102)
		(width 0.20066)
		(layer "F.Cu")
		(net "M_E_CPU0_SB_DQ<9>")
	)
	(segment
		(start 384.864864 -238.993426)
		(end 385.07543 -238.993426)
		(width 0.088646)
		(layer "F.Cu")
		(net "M_E_CPU0_SB_DQ<9>")
	)
	(segment
		(start 384.575304 -239.13846)
		(end 384.71983 -239.13846)
		(width 0.088646)
		(layer "F.Cu")
		(net "M_E_CPU0_SB_DQ<9>")
	)
	(segment
		(start 386.2197 -239.10671)
		(end 386.231892 -239.111282)
		(width 0.088646)
		(layer "F.Cu")
		(net "M_E_CPU0_SB_DQ<9>")
	)
	(segment
		(start 398.551908 -230.091996)
		(end 398.604994 -230.03891)
		(width 0.1016)
		(layer "F.Cu")
		(net "M_E_CPU0_SB_DQ<9>")
	)
	(segment
		(start 386.681726 -239.01019)
		(end 387.874256 -239.01019)
		(width 0.088646)
		(layer "F.Cu")
		(net "M_E_CPU0_SB_DQ<9>")
	)
	(segment
		(start 403.750272 -228.453442)
		(end 403.750272 -223.105726)
		(width 0.20066)
		(layer "F.Cu")
		(net "M_E_CPU0_SB_DQ<9>")
	)
	(segment
		(start 414.297114 -221.116652)
		(end 412.57855 -221.116652)
		(width 0.20066)
		(layer "F.Cu")
		(net "M_E_CPU0_SB_DQ<9>")
	)
	(segment
		(start 405.89073 -221.116652)
		(end 406.753314 -221.116652)
		(width 0.20066)
		(layer "F.Cu")
		(net "M_E_CPU0_SB_DQ<9>")
	)
	(segment
		(start 407.693114 -221.116652)
		(end 406.753314 -221.116652)
		(width 0.20066)
		(layer "F.Cu")
		(net "M_E_CPU0_SB_DQ<9>")
	)
	(segment
		(start 387.874256 -239.01019)
		(end 388.75716 -238.127286)
		(width 0.088646)
		(layer "F.Cu")
		(net "M_E_CPU0_SB_DQ<9>")
	)
	(segment
		(start 411.863794 -220.676978)
		(end 411.848046 -220.676978)
		(width 0.101854)
		(layer "F.Cu")
		(net "M_E_CPU0_SB_DQ<9>")
	)
	(segment
		(start 386.549392 -239.088168)
		(end 386.681726 -239.01019)
		(width 0.088646)
		(layer "F.Cu")
		(net "M_E_CPU0_SB_DQ<9>")
	)
	(segment
		(start 409.831794 -220.683074)
		(end 409.121356 -220.683074)
		(width 0.20066)
		(layer "F.Cu")
		(net "M_E_CPU0_SB_DQ<9>")
	)
	(segment
		(start 385.576064 -239.222026)
		(end 385.830064 -238.968026)
		(width 0.088646)
		(layer "F.Cu")
		(net "M_E_CPU0_SB_DQ<9>")
	)
	(segment
		(start 411.833314 -220.69171)
		(end 409.845256 -220.69171)
		(width 0.1016)
		(layer "F.Cu")
		(net "M_E_CPU0_SB_DQ<9>")
	)
	(segment
		(start 386.00761 -238.968026)
		(end 386.099558 -239.059974)
		(width 0.088646)
		(layer "F.Cu")
		(net "M_E_CPU0_SB_DQ<9>")
	)
	(segment
		(start 408.97175 -221.152466)
		(end 408.751278 -221.372938)
		(width 0.20066)
		(layer "F.Cu")
		(net "M_E_CPU0_SB_DQ<9>")
	)
	(segment
		(start 403.213316 -229.339902)
		(end 402.162264 -229.339902)
		(width 0.20066)
		(layer "F.Cu")
		(net "M_E_CPU0_SB_DQ<9>")
	)
	(segment
		(start 386.231892 -239.111282)
		(end 386.363972 -239.136174)
		(width 0.088646)
		(layer "F.Cu")
		(net "M_E_CPU0_SB_DQ<9>")
	)
	(segment
		(start 385.30403 -239.222026)
		(end 385.576064 -239.222026)
		(width 0.088646)
		(layer "F.Cu")
		(net "M_E_CPU0_SB_DQ<9>")
	)
	(segment
		(start 408.751278 -221.372938)
		(end 407.9494 -221.372938)
		(width 0.20066)
		(layer "F.Cu")
		(net "M_E_CPU0_SB_DQ<9>")
	)
	(segment
		(start 401.961604 -229.139242)
		(end 401.961604 -228.854762)
		(width 0.20066)
		(layer "F.Cu")
		(net "M_E_CPU0_SB_DQ<9>")
	)
	(segment
		(start 384.71983 -239.13846)
		(end 384.864864 -238.993426)
		(width 0.088646)
		(layer "F.Cu")
		(net "M_E_CPU0_SB_DQ<9>")
	)
	(segment
		(start 386.54736 -239.089184)
		(end 386.549392 -239.088168)
		(width 0.088646)
		(layer "F.Cu")
		(net "M_E_CPU0_SB_DQ<9>")
	)
	(segment
		(start 384.485134 -238.761524)
		(end 384.485134 -239.046512)
		(width 0.088646)
		(layer "F.Cu")
		(net "M_E_CPU0_SB_DQ<9>")
	)
	(segment
		(start 403.413976 -229.825042)
		(end 403.413976 -229.540562)
		(width 0.20066)
		(layer "F.Cu")
		(net "M_E_CPU0_SB_DQ<9>")
	)
	(segment
		(start 403.549612 -228.654102)
		(end 403.750272 -228.453442)
		(width 0.20066)
		(layer "F.Cu")
		(net "M_E_CPU0_SB_DQ<9>")
	)
	(segment
		(start 411.848046 -220.676978)
		(end 411.833314 -220.69171)
		(width 0.101854)
		(layer "F.Cu")
		(net "M_E_CPU0_SB_DQ<9>")
	)
	(segment
		(start 409.121356 -220.683074)
		(end 408.97175 -220.83268)
		(width 0.20066)
		(layer "F.Cu")
		(net "M_E_CPU0_SB_DQ<9>")
	)
	(segment
		(start 388.75716 -238.127286)
		(end 388.890764 -238.127286)
		(width 0.088646)
		(layer "F.Cu")
		(net "M_E_CPU0_SB_DQ<9>")
	)
	(segment
		(start 399.17751 -230.03891)
		(end 403.200108 -230.03891)
		(width 0.20066)
		(layer "F.Cu")
		(net "M_E_CPU0_SB_DQ<9>")
	)
	(segment
		(start 398.604994 -230.03891)
		(end 399.17751 -230.03891)
		(width 0.1016)
		(layer "F.Cu")
		(net "M_E_CPU0_SB_DQ<9>")
	)
	(segment
		(start 407.9494 -221.372938)
		(end 407.693114 -221.116652)
		(width 0.20066)
		(layer "F.Cu")
		(net "M_E_CPU0_SB_DQ<9>")
	)
	(segment
		(start 386.363972 -239.136174)
		(end 386.367274 -239.136174)
		(width 0.088646)
		(layer "F.Cu")
		(net "M_E_CPU0_SB_DQ<9>")
	)
	(segment
		(start 386.367274 -239.136174)
		(end 386.54736 -239.089184)
		(width 0.088646)
		(layer "F.Cu")
		(net "M_E_CPU0_SB_DQ<9>")
	)
	(segment
		(start 408.97175 -220.83268)
		(end 408.97175 -221.152466)
		(width 0.20066)
		(layer "F.Cu")
		(net "M_E_CPU0_SB_DQ<9>")
	)
	(segment
		(start 405.505158 -221.35084)
		(end 405.656542 -221.35084)
		(width 0.20066)
		(layer "F.Cu")
		(net "M_E_CPU0_SB_DQ<9>")
	)
	(segment
		(start 384.486404 -239.04956)
		(end 384.575304 -239.13846)
		(width 0.088646)
		(layer "F.Cu")
		(net "M_E_CPU0_SB_DQ<9>")
	)
	(segment
		(start 403.200108 -230.03891)
		(end 403.413976 -229.825042)
		(width 0.20066)
		(layer "F.Cu")
		(net "M_E_CPU0_SB_DQ<9>")
	)
	(segment
		(start 402.162264 -229.339902)
		(end 401.961604 -229.139242)
		(width 0.20066)
		(layer "F.Cu")
		(net "M_E_CPU0_SB_DQ<9>")
	)
	(arc
		(start 384.485134 -239.046512)
		(mid 384.485463 -239.048164)
		(end 384.486404 -239.04956)
		(width 0.088646)
		(layer "F.Cu")
		(net "M_E_CPU0_SB_DQ<9>")
	)
	(segment
		(start 411.833314 -222.391732)
		(end 409.846272 -222.391732)
		(width 0.1016)
		(layer "F.Cu")
		(net "M_E_CPU0_SB_DQ<8>")
	)
	(segment
		(start 404.82139 -231.637332)
		(end 404.232618 -231.637332)
		(width 0.20066)
		(layer "F.Cu")
		(net "M_E_CPU0_SB_DQ<8>")
	)
	(segment
		(start 409.846272 -222.391732)
		(end 409.83662 -222.38208)
		(width 0.1016)
		(layer "F.Cu")
		(net "M_E_CPU0_SB_DQ<8>")
	)
	(segment
		(start 387.662928 -240.183416)
		(end 387.709156 -240.114074)
		(width 0.088646)
		(layer "F.Cu")
		(net "M_E_CPU0_SB_DQ<8>")
	)
	(segment
		(start 412.727902 -222.816674)
		(end 412.721298 -222.823278)
		(width 0.20066)
		(layer "F.Cu")
		(net "M_E_CPU0_SB_DQ<8>")
	)
	(segment
		(start 385.835144 -239.971072)
		(end 386.743956 -239.971072)
		(width 0.088646)
		(layer "F.Cu")
		(net "M_E_CPU0_SB_DQ<8>")
	)
	(segment
		(start 386.743956 -239.971072)
		(end 387.12648 -240.353596)
		(width 0.088646)
		(layer "F.Cu")
		(net "M_E_CPU0_SB_DQ<8>")
	)
	(segment
		(start 405.87676 -222.816674)
		(end 406.753314 -222.816674)
		(width 0.20066)
		(layer "F.Cu")
		(net "M_E_CPU0_SB_DQ<8>")
	)
	(segment
		(start 387.492748 -240.353596)
		(end 387.662928 -240.183416)
		(width 0.088646)
		(layer "F.Cu")
		(net "M_E_CPU0_SB_DQ<8>")
	)
	(segment
		(start 412.721298 -222.823278)
		(end 412.27502 -222.377)
		(width 0.20066)
		(layer "F.Cu")
		(net "M_E_CPU0_SB_DQ<8>")
	)
	(segment
		(start 405.060912 -223.632522)
		(end 405.87676 -222.816674)
		(width 0.20066)
		(layer "F.Cu")
		(net "M_E_CPU0_SB_DQ<8>")
	)
	(segment
		(start 402.28012 -232.323132)
		(end 404.82139 -232.323132)
		(width 0.20066)
		(layer "F.Cu")
		(net "M_E_CPU0_SB_DQ<8>")
	)
	(segment
		(start 411.848046 -222.377)
		(end 411.833314 -222.391732)
		(width 0.101854)
		(layer "F.Cu")
		(net "M_E_CPU0_SB_DQ<8>")
	)
	(segment
		(start 399.076164 -231.547924)
		(end 401.504912 -231.547924)
		(width 0.20066)
		(layer "F.Cu")
		(net "M_E_CPU0_SB_DQ<8>")
	)
	(segment
		(start 404.031958 -231.436672)
		(end 404.031958 -231.152192)
		(width 0.20066)
		(layer "F.Cu")
		(net "M_E_CPU0_SB_DQ<8>")
	)
	(segment
		(start 408.330908 -223.07296)
		(end 408.074622 -222.816674)
		(width 0.20066)
		(layer "F.Cu")
		(net "M_E_CPU0_SB_DQ<8>")
	)
	(segment
		(start 388.898384 -238.736886)
		(end 389.220964 -238.736886)
		(width 0.088646)
		(layer "F.Cu")
		(net "M_E_CPU0_SB_DQ<8>")
	)
	(segment
		(start 412.27502 -222.377)
		(end 411.863794 -222.377)
		(width 0.20066)
		(layer "F.Cu")
		(net "M_E_CPU0_SB_DQ<8>")
	)
	(segment
		(start 404.844758 -230.951532)
		(end 405.060912 -230.735378)
		(width 0.20066)
		(layer "F.Cu")
		(net "M_E_CPU0_SB_DQ<8>")
	)
	(segment
		(start 387.709156 -239.926114)
		(end 388.898384 -238.736886)
		(width 0.088646)
		(layer "F.Cu")
		(net "M_E_CPU0_SB_DQ<8>")
	)
	(segment
		(start 409.831794 -222.38208)
		(end 409.122372 -222.38208)
		(width 0.20066)
		(layer "F.Cu")
		(net "M_E_CPU0_SB_DQ<8>")
	)
	(segment
		(start 385.250944 -239.566958)
		(end 385.75234 -239.943386)
		(width 0.088646)
		(layer "F.Cu")
		(net "M_E_CPU0_SB_DQ<8>")
	)
	(segment
		(start 408.074622 -222.816674)
		(end 406.753314 -222.816674)
		(width 0.20066)
		(layer "F.Cu")
		(net "M_E_CPU0_SB_DQ<8>")
	)
	(segment
		(start 404.232618 -230.951532)
		(end 404.844758 -230.951532)
		(width 0.20066)
		(layer "F.Cu")
		(net "M_E_CPU0_SB_DQ<8>")
	)
	(segment
		(start 405.02205 -231.837992)
		(end 404.82139 -231.637332)
		(width 0.20066)
		(layer "F.Cu")
		(net "M_E_CPU0_SB_DQ<8>")
	)
	(segment
		(start 408.97175 -222.852488)
		(end 408.751278 -223.07296)
		(width 0.20066)
		(layer "F.Cu")
		(net "M_E_CPU0_SB_DQ<8>")
	)
	(segment
		(start 389.220964 -238.736886)
		(end 390.770364 -238.736886)
		(width 0.1016)
		(layer "F.Cu")
		(net "M_E_CPU0_SB_DQ<8>")
	)
	(segment
		(start 414.297114 -222.816674)
		(end 412.727902 -222.816674)
		(width 0.20066)
		(layer "F.Cu")
		(net "M_E_CPU0_SB_DQ<8>")
	)
	(segment
		(start 409.83662 -222.38208)
		(end 409.831794 -222.38208)
		(width 0.101854)
		(layer "F.Cu")
		(net "M_E_CPU0_SB_DQ<8>")
	)
	(segment
		(start 404.031958 -231.152192)
		(end 404.232618 -230.951532)
		(width 0.20066)
		(layer "F.Cu")
		(net "M_E_CPU0_SB_DQ<8>")
	)
	(segment
		(start 397.959326 -231.547924)
		(end 399.076164 -231.547924)
		(width 0.1016)
		(layer "F.Cu")
		(net "M_E_CPU0_SB_DQ<8>")
	)
	(segment
		(start 401.504912 -231.547924)
		(end 402.28012 -232.323132)
		(width 0.20066)
		(layer "F.Cu")
		(net "M_E_CPU0_SB_DQ<8>")
	)
	(segment
		(start 405.060912 -230.735378)
		(end 405.060912 -223.632522)
		(width 0.20066)
		(layer "F.Cu")
		(net "M_E_CPU0_SB_DQ<8>")
	)
	(segment
		(start 409.122372 -222.38208)
		(end 408.97175 -222.532702)
		(width 0.20066)
		(layer "F.Cu")
		(net "M_E_CPU0_SB_DQ<8>")
	)
	(segment
		(start 387.709156 -240.114074)
		(end 387.709156 -239.926114)
		(width 0.088646)
		(layer "F.Cu")
		(net "M_E_CPU0_SB_DQ<8>")
	)
	(segment
		(start 387.12648 -240.353596)
		(end 387.492748 -240.353596)
		(width 0.088646)
		(layer "F.Cu")
		(net "M_E_CPU0_SB_DQ<8>")
	)
	(segment
		(start 404.232618 -231.637332)
		(end 404.031958 -231.436672)
		(width 0.20066)
		(layer "F.Cu")
		(net "M_E_CPU0_SB_DQ<8>")
	)
	(segment
		(start 390.770364 -238.736886)
		(end 397.959326 -231.547924)
		(width 0.1016)
		(layer "F.Cu")
		(net "M_E_CPU0_SB_DQ<8>")
	)
	(segment
		(start 408.97175 -222.532702)
		(end 408.97175 -222.852488)
		(width 0.20066)
		(layer "F.Cu")
		(net "M_E_CPU0_SB_DQ<8>")
	)
	(segment
		(start 411.863794 -222.377)
		(end 411.848046 -222.377)
		(width 0.101854)
		(layer "F.Cu")
		(net "M_E_CPU0_SB_DQ<8>")
	)
	(segment
		(start 404.82139 -232.323132)
		(end 405.02205 -232.122472)
		(width 0.20066)
		(layer "F.Cu")
		(net "M_E_CPU0_SB_DQ<8>")
	)
	(segment
		(start 405.02205 -232.122472)
		(end 405.02205 -231.837992)
		(width 0.20066)
		(layer "F.Cu")
		(net "M_E_CPU0_SB_DQ<8>")
	)
	(segment
		(start 408.751278 -223.07296)
		(end 408.330908 -223.07296)
		(width 0.20066)
		(layer "F.Cu")
		(net "M_E_CPU0_SB_DQ<8>")
	)
	(segment
		(start 384.95478 -239.57534)
		(end 385.16687 -239.545368)
		(width 0.088646)
		(layer "F.Cu")
		(net "M_E_CPU0_SB_DQ<8>")
	)
	(arc
		(start 385.16687 -239.545368)
		(mid 385.211058 -239.547792)
		(end 385.250944 -239.566958)
		(width 0.088646)
		(layer "F.Cu")
		(net "M_E_CPU0_SB_DQ<8>")
	)
	(arc
		(start 385.75234 -239.943386)
		(mid 385.791497 -239.96393)
		(end 385.835144 -239.971072)
		(width 0.088646)
		(layer "F.Cu")
		(net "M_E_CPU0_SB_DQ<8>")
	)
	(segment
		(start 412.949898 -224.105978)
		(end 412.510478 -223.666558)
		(width 0.20066)
		(layer "F.Cu")
		(net "M_E_CPU0_SB_DQ<7>")
	)
	(segment
		(start 382.605534 -233.87812)
		(end 382.605534 -233.34218)
		(width 0.20066)
		(layer "F.Cu")
		(net "M_E_CPU0_SB_DQ<7>")
	)
	(segment
		(start 415.307526 -224.110296)
		(end 415.27476 -224.110296)
		(width 0.101854)
		(layer "F.Cu")
		(net "M_E_CPU0_SB_DQ<7>")
	)
	(segment
		(start 412.510478 -223.666558)
		(end 410.853382 -223.666558)
		(width 0.20066)
		(layer "F.Cu")
		(net "M_E_CPU0_SB_DQ<7>")
	)
	(segment
		(start 416.205416 -223.936814)
		(end 416.031934 -224.110296)
		(width 0.20066)
		(layer "F.Cu")
		(net "M_E_CPU0_SB_DQ<7>")
	)
	(segment
		(start 416.439604 -223.41459)
		(end 416.205416 -223.648778)
		(width 0.20066)
		(layer "F.Cu")
		(net "M_E_CPU0_SB_DQ<7>")
	)
	(segment
		(start 413.300164 -224.0915)
		(end 413.285686 -224.105978)
		(width 0.1016)
		(layer "F.Cu")
		(net "M_E_CPU0_SB_DQ<7>")
	)
	(segment
		(start 413.285686 -224.105978)
		(end 413.275526 -224.105978)
		(width 0.101854)
		(layer "F.Cu")
		(net "M_E_CPU0_SB_DQ<7>")
	)
	(segment
		(start 416.031934 -224.110296)
		(end 415.307526 -224.110296)
		(width 0.20066)
		(layer "F.Cu")
		(net "M_E_CPU0_SB_DQ<7>")
	)
	(segment
		(start 418.397182 -223.666558)
		(end 417.07562 -223.666558)
		(width 0.20066)
		(layer "F.Cu")
		(net "M_E_CPU0_SB_DQ<7>")
	)
	(segment
		(start 410.853382 -223.666558)
		(end 409.723082 -223.666558)
		(width 0.20066)
		(layer "F.Cu")
		(net "M_E_CPU0_SB_DQ<7>")
	)
	(segment
		(start 416.823652 -223.41459)
		(end 416.439604 -223.41459)
		(width 0.20066)
		(layer "F.Cu")
		(net "M_E_CPU0_SB_DQ<7>")
	)
	(segment
		(start 415.255964 -224.0915)
		(end 413.300164 -224.0915)
		(width 0.1016)
		(layer "F.Cu")
		(net "M_E_CPU0_SB_DQ<7>")
	)
	(segment
		(start 416.205416 -223.648778)
		(end 416.205416 -223.936814)
		(width 0.20066)
		(layer "F.Cu")
		(net "M_E_CPU0_SB_DQ<7>")
	)
	(segment
		(start 413.275526 -224.105978)
		(end 412.949898 -224.105978)
		(width 0.20066)
		(layer "F.Cu")
		(net "M_E_CPU0_SB_DQ<7>")
	)
	(segment
		(start 417.07562 -223.666558)
		(end 416.823652 -223.41459)
		(width 0.20066)
		(layer "F.Cu")
		(net "M_E_CPU0_SB_DQ<7>")
	)
	(segment
		(start 415.27476 -224.110296)
		(end 415.255964 -224.0915)
		(width 0.101854)
		(layer "F.Cu")
		(net "M_E_CPU0_SB_DQ<7>")
	)
	(segment
		(start 409.723082 -223.927162)
		(end 409.530042 -224.120202)
		(width 0.18288)
		(layer "In2.Cu")
		(net "M_E_CPU0_SB_DQ<7>")
	)
	(segment
		(start 388.58571 -231.807766)
		(end 388.264908 -231.807766)
		(width 0.088646)
		(layer "In2.Cu")
		(net "M_E_CPU0_SB_DQ<7>")
	)
	(segment
		(start 406.373584 -223.829626)
		(end 406.112472 -224.090738)
		(width 0.18288)
		(layer "In2.Cu")
		(net "M_E_CPU0_SB_DQ<7>")
	)
	(segment
		(start 406.112472 -224.090738)
		(end 405.394922 -224.090738)
		(width 0.18288)
		(layer "In2.Cu")
		(net "M_E_CPU0_SB_DQ<7>")
	)
	(segment
		(start 386.090922 -232.847642)
		(end 386.082032 -232.852722)
		(width 0.088646)
		(layer "In2.Cu")
		(net "M_E_CPU0_SB_DQ<7>")
	)
	(segment
		(start 405.311356 -224.007172)
		(end 403.217634 -224.007172)
		(width 0.18288)
		(layer "In2.Cu")
		(net "M_E_CPU0_SB_DQ<7>")
	)
	(segment
		(start 406.97404 -223.829626)
		(end 406.373584 -223.829626)
		(width 0.18288)
		(layer "In2.Cu")
		(net "M_E_CPU0_SB_DQ<7>")
	)
	(segment
		(start 386.269484 -232.518458)
		(end 386.269484 -232.528364)
		(width 0.088646)
		(layer "In2.Cu")
		(net "M_E_CPU0_SB_DQ<7>")
	)
	(segment
		(start 388.264908 -231.807766)
		(end 387.983222 -232.089452)
		(width 0.088646)
		(layer "In2.Cu")
		(net "M_E_CPU0_SB_DQ<7>")
	)
	(segment
		(start 383.262632 -232.852722)
		(end 382.865376 -233.082338)
		(width 0.088646)
		(layer "In2.Cu")
		(net "M_E_CPU0_SB_DQ<7>")
	)
	(segment
		(start 407.264616 -224.120202)
		(end 406.97404 -223.829626)
		(width 0.18288)
		(layer "In2.Cu")
		(net "M_E_CPU0_SB_DQ<7>")
	)
	(segment
		(start 405.394922 -224.090738)
		(end 405.311356 -224.007172)
		(width 0.18288)
		(layer "In2.Cu")
		(net "M_E_CPU0_SB_DQ<7>")
	)
	(segment
		(start 387.983222 -232.089452)
		(end 387.304534 -232.089452)
		(width 0.088646)
		(layer "In2.Cu")
		(net "M_E_CPU0_SB_DQ<7>")
	)
	(segment
		(start 409.530042 -224.120202)
		(end 407.264616 -224.120202)
		(width 0.18288)
		(layer "In2.Cu")
		(net "M_E_CPU0_SB_DQ<7>")
	)
	(segment
		(start 395.41704 -231.807766)
		(end 388.58571 -231.807766)
		(width 0.18288)
		(layer "In2.Cu")
		(net "M_E_CPU0_SB_DQ<7>")
	)
	(segment
		(start 382.865376 -233.082338)
		(end 382.605534 -233.34218)
		(width 0.088646)
		(layer "In2.Cu")
		(net "M_E_CPU0_SB_DQ<7>")
	)
	(segment
		(start 403.217634 -224.007172)
		(end 395.41704 -231.807766)
		(width 0.18288)
		(layer "In2.Cu")
		(net "M_E_CPU0_SB_DQ<7>")
	)
	(segment
		(start 409.723082 -223.666558)
		(end 409.723082 -223.927162)
		(width 0.18288)
		(layer "In2.Cu")
		(net "M_E_CPU0_SB_DQ<7>")
	)
	(arc
		(start 385.142232 -232.852722)
		(mid 384.955034 -232.902865)
		(end 384.767836 -232.852722)
		(width 0.088646)
		(layer "In2.Cu")
		(net "M_E_CPU0_SB_DQ<7>")
	)
	(arc
		(start 386.269484 -232.528364)
		(mid 386.221805 -232.711264)
		(end 386.090922 -232.847642)
		(width 0.088646)
		(layer "In2.Cu")
		(net "M_E_CPU0_SB_DQ<7>")
	)
	(arc
		(start 386.551932 -232.038906)
		(mid 386.347597 -232.241511)
		(end 386.269484 -232.518458)
		(width 0.088646)
		(layer "In2.Cu")
		(net "M_E_CPU0_SB_DQ<7>")
	)
	(arc
		(start 386.082032 -232.852722)
		(mid 385.894834 -232.902865)
		(end 385.707636 -232.852722)
		(width 0.088646)
		(layer "In2.Cu")
		(net "M_E_CPU0_SB_DQ<7>")
	)
	(arc
		(start 385.707636 -232.852722)
		(mid 385.424934 -232.776946)
		(end 385.142232 -232.852722)
		(width 0.088646)
		(layer "In2.Cu")
		(net "M_E_CPU0_SB_DQ<7>")
	)
	(arc
		(start 384.202432 -232.852722)
		(mid 384.015234 -232.902865)
		(end 383.828036 -232.852722)
		(width 0.088646)
		(layer "In2.Cu")
		(net "M_E_CPU0_SB_DQ<7>")
	)
	(arc
		(start 383.828036 -232.852722)
		(mid 383.545334 -232.776946)
		(end 383.262632 -232.852722)
		(width 0.088646)
		(layer "In2.Cu")
		(net "M_E_CPU0_SB_DQ<7>")
	)
	(arc
		(start 387.304534 -232.089452)
		(mid 387.207611 -232.076494)
		(end 387.117336 -232.038906)
		(width 0.088646)
		(layer "In2.Cu")
		(net "M_E_CPU0_SB_DQ<7>")
	)
	(arc
		(start 384.767836 -232.852722)
		(mid 384.485134 -232.776946)
		(end 384.202432 -232.852722)
		(width 0.088646)
		(layer "In2.Cu")
		(net "M_E_CPU0_SB_DQ<7>")
	)
	(arc
		(start 387.117336 -232.038906)
		(mid 386.834634 -231.96313)
		(end 386.551932 -232.038906)
		(width 0.088646)
		(layer "In2.Cu")
		(net "M_E_CPU0_SB_DQ<7>")
	)
	(segment
		(start 383.07518 -234.69219)
		(end 383.07518 -234.156504)
		(width 0.20066)
		(layer "F.Cu")
		(net "M_E_CPU0_SB_DQ<6>")
	)
	(segment
		(start 416.031934 -225.810318)
		(end 415.307526 -225.810318)
		(width 0.20066)
		(layer "F.Cu")
		(net "M_E_CPU0_SB_DQ<6>")
	)
	(segment
		(start 410.853382 -225.36658)
		(end 409.723082 -225.36658)
		(width 0.20066)
		(layer "F.Cu")
		(net "M_E_CPU0_SB_DQ<6>")
	)
	(segment
		(start 418.397182 -225.36658)
		(end 417.07562 -225.36658)
		(width 0.20066)
		(layer "F.Cu")
		(net "M_E_CPU0_SB_DQ<6>")
	)
	(segment
		(start 417.07562 -225.36658)
		(end 416.823652 -225.114612)
		(width 0.20066)
		(layer "F.Cu")
		(net "M_E_CPU0_SB_DQ<6>")
	)
	(segment
		(start 415.307526 -225.810318)
		(end 415.27476 -225.810318)
		(width 0.101854)
		(layer "F.Cu")
		(net "M_E_CPU0_SB_DQ<6>")
	)
	(segment
		(start 416.823652 -225.114612)
		(end 416.439604 -225.114612)
		(width 0.20066)
		(layer "F.Cu")
		(net "M_E_CPU0_SB_DQ<6>")
	)
	(segment
		(start 413.285686 -225.806)
		(end 413.275526 -225.806)
		(width 0.101854)
		(layer "F.Cu")
		(net "M_E_CPU0_SB_DQ<6>")
	)
	(segment
		(start 416.439604 -225.114612)
		(end 416.205416 -225.3488)
		(width 0.20066)
		(layer "F.Cu")
		(net "M_E_CPU0_SB_DQ<6>")
	)
	(segment
		(start 415.255964 -225.791522)
		(end 413.300164 -225.791522)
		(width 0.1016)
		(layer "F.Cu")
		(net "M_E_CPU0_SB_DQ<6>")
	)
	(segment
		(start 415.27476 -225.810318)
		(end 415.255964 -225.791522)
		(width 0.101854)
		(layer "F.Cu")
		(net "M_E_CPU0_SB_DQ<6>")
	)
	(segment
		(start 383.07518 -234.156504)
		(end 383.075434 -234.15625)
		(width 0.20066)
		(layer "F.Cu")
		(net "M_E_CPU0_SB_DQ<6>")
	)
	(segment
		(start 416.205416 -225.636836)
		(end 416.031934 -225.810318)
		(width 0.20066)
		(layer "F.Cu")
		(net "M_E_CPU0_SB_DQ<6>")
	)
	(segment
		(start 412.914338 -225.806)
		(end 412.474918 -225.36658)
		(width 0.20066)
		(layer "F.Cu")
		(net "M_E_CPU0_SB_DQ<6>")
	)
	(segment
		(start 412.474918 -225.36658)
		(end 410.853382 -225.36658)
		(width 0.20066)
		(layer "F.Cu")
		(net "M_E_CPU0_SB_DQ<6>")
	)
	(segment
		(start 413.300164 -225.791522)
		(end 413.285686 -225.806)
		(width 0.1016)
		(layer "F.Cu")
		(net "M_E_CPU0_SB_DQ<6>")
	)
	(segment
		(start 416.205416 -225.3488)
		(end 416.205416 -225.636836)
		(width 0.20066)
		(layer "F.Cu")
		(net "M_E_CPU0_SB_DQ<6>")
	)
	(segment
		(start 413.275526 -225.806)
		(end 412.914338 -225.806)
		(width 0.20066)
		(layer "F.Cu")
		(net "M_E_CPU0_SB_DQ<6>")
	)
	(segment
		(start 388.192518 -232.824528)
		(end 388.14502 -232.77703)
		(width 0.088646)
		(layer "In2.Cu")
		(net "M_E_CPU0_SB_DQ<6>")
	)
	(segment
		(start 395.91488 -232.824528)
		(end 388.585964 -232.824528)
		(width 0.18288)
		(layer "In2.Cu")
		(net "M_E_CPU0_SB_DQ<6>")
	)
	(segment
		(start 386.560822 -233.661458)
		(end 386.551932 -233.666538)
		(width 0.088646)
		(layer "In2.Cu")
		(net "M_E_CPU0_SB_DQ<6>")
	)
	(segment
		(start 386.739384 -233.332274)
		(end 386.739384 -233.34218)
		(width 0.088646)
		(layer "In2.Cu")
		(net "M_E_CPU0_SB_DQ<6>")
	)
	(segment
		(start 405.400256 -224.94494)
		(end 405.214582 -225.130614)
		(width 0.18288)
		(layer "In2.Cu")
		(net "M_E_CPU0_SB_DQ<6>")
	)
	(segment
		(start 399.415508 -229.3239)
		(end 395.91488 -232.824528)
		(width 0.18288)
		(layer "In2.Cu")
		(net "M_E_CPU0_SB_DQ<6>")
	)
	(segment
		(start 405.214582 -225.130614)
		(end 404.586186 -225.130614)
		(width 0.18288)
		(layer "In2.Cu")
		(net "M_E_CPU0_SB_DQ<6>")
	)
	(segment
		(start 388.585964 -232.824528)
		(end 388.192518 -232.824528)
		(width 0.088646)
		(layer "In2.Cu")
		(net "M_E_CPU0_SB_DQ<6>")
	)
	(segment
		(start 404.586186 -225.130614)
		(end 400.3929 -229.3239)
		(width 0.18288)
		(layer "In2.Cu")
		(net "M_E_CPU0_SB_DQ<6>")
	)
	(segment
		(start 407.601674 -225.846894)
		(end 407.320496 -225.565716)
		(width 0.18288)
		(layer "In2.Cu")
		(net "M_E_CPU0_SB_DQ<6>")
	)
	(segment
		(start 388.14502 -232.77703)
		(end 387.304534 -232.77703)
		(width 0.088646)
		(layer "In2.Cu")
		(net "M_E_CPU0_SB_DQ<6>")
	)
	(segment
		(start 383.075688 -234.155996)
		(end 383.075434 -234.15625)
		(width 0.088646)
		(layer "In2.Cu")
		(net "M_E_CPU0_SB_DQ<6>")
	)
	(segment
		(start 407.147268 -224.94494)
		(end 405.400256 -224.94494)
		(width 0.18288)
		(layer "In2.Cu")
		(net "M_E_CPU0_SB_DQ<6>")
	)
	(segment
		(start 407.320496 -225.565716)
		(end 407.320496 -225.118168)
		(width 0.18288)
		(layer "In2.Cu")
		(net "M_E_CPU0_SB_DQ<6>")
	)
	(segment
		(start 409.723082 -225.36658)
		(end 409.242768 -225.846894)
		(width 0.18288)
		(layer "In2.Cu")
		(net "M_E_CPU0_SB_DQ<6>")
	)
	(segment
		(start 409.242768 -225.846894)
		(end 407.601674 -225.846894)
		(width 0.18288)
		(layer "In2.Cu")
		(net "M_E_CPU0_SB_DQ<6>")
	)
	(segment
		(start 407.320496 -225.118168)
		(end 407.147268 -224.94494)
		(width 0.18288)
		(layer "In2.Cu")
		(net "M_E_CPU0_SB_DQ<6>")
	)
	(segment
		(start 383.732532 -233.666538)
		(end 383.659126 -233.708702)
		(width 0.088646)
		(layer "In2.Cu")
		(net "M_E_CPU0_SB_DQ<6>")
	)
	(segment
		(start 400.3929 -229.3239)
		(end 399.415508 -229.3239)
		(width 0.18288)
		(layer "In2.Cu")
		(net "M_E_CPU0_SB_DQ<6>")
	)
	(arc
		(start 387.304534 -232.77703)
		(mid 386.90843 -232.939072)
		(end 386.739384 -233.332274)
		(width 0.088646)
		(layer "In2.Cu")
		(net "M_E_CPU0_SB_DQ<6>")
	)
	(arc
		(start 384.672332 -233.666538)
		(mid 384.485134 -233.716681)
		(end 384.297936 -233.666538)
		(width 0.088646)
		(layer "In2.Cu")
		(net "M_E_CPU0_SB_DQ<6>")
	)
	(arc
		(start 386.739384 -233.34218)
		(mid 386.691705 -233.52508)
		(end 386.560822 -233.661458)
		(width 0.088646)
		(layer "In2.Cu")
		(net "M_E_CPU0_SB_DQ<6>")
	)
	(arc
		(start 383.659126 -233.708702)
		(mid 383.352663 -233.913118)
		(end 383.075688 -234.155996)
		(width 0.088646)
		(layer "In2.Cu")
		(net "M_E_CPU0_SB_DQ<6>")
	)
	(arc
		(start 385.237736 -233.666538)
		(mid 384.955034 -233.590796)
		(end 384.672332 -233.666538)
		(width 0.088646)
		(layer "In2.Cu")
		(net "M_E_CPU0_SB_DQ<6>")
	)
	(arc
		(start 386.551932 -233.666538)
		(mid 386.364734 -233.716681)
		(end 386.177536 -233.666538)
		(width 0.088646)
		(layer "In2.Cu")
		(net "M_E_CPU0_SB_DQ<6>")
	)
	(arc
		(start 385.612132 -233.666538)
		(mid 385.424934 -233.716681)
		(end 385.237736 -233.666538)
		(width 0.088646)
		(layer "In2.Cu")
		(net "M_E_CPU0_SB_DQ<6>")
	)
	(arc
		(start 384.297936 -233.666538)
		(mid 384.015234 -233.590796)
		(end 383.732532 -233.666538)
		(width 0.088646)
		(layer "In2.Cu")
		(net "M_E_CPU0_SB_DQ<6>")
	)
	(arc
		(start 386.177536 -233.666538)
		(mid 385.894834 -233.590796)
		(end 385.612132 -233.666538)
		(width 0.088646)
		(layer "In2.Cu")
		(net "M_E_CPU0_SB_DQ<6>")
	)
	(segment
		(start 408.997912 -224.765362)
		(end 409.185872 -224.577402)
		(width 0.20066)
		(layer "F.Cu")
		(net "M_E_CPU0_SB_DQ<5>")
	)
	(segment
		(start 409.668726 -224.091754)
		(end 411.857444 -224.091754)
		(width 0.1016)
		(layer "F.Cu")
		(net "M_E_CPU0_SB_DQ<5>")
	)
	(segment
		(start 409.185872 -224.209864)
		(end 409.303982 -224.091754)
		(width 0.20066)
		(layer "F.Cu")
		(net "M_E_CPU0_SB_DQ<5>")
	)
	(segment
		(start 405.623014 -224.516696)
		(end 406.753314 -224.516696)
		(width 0.20066)
		(layer "F.Cu")
		(net "M_E_CPU0_SB_DQ<5>")
	)
	(segment
		(start 406.753314 -224.516696)
		(end 408.274012 -224.516696)
		(width 0.20066)
		(layer "F.Cu")
		(net "M_E_CPU0_SB_DQ<5>")
	)
	(segment
		(start 409.64866 -224.091754)
		(end 409.668726 -224.091754)
		(width 0.101854)
		(layer "F.Cu")
		(net "M_E_CPU0_SB_DQ<5>")
	)
	(segment
		(start 412.27375 -224.085404)
		(end 412.705296 -224.51695)
		(width 0.20066)
		(layer "F.Cu")
		(net "M_E_CPU0_SB_DQ<5>")
	)
	(segment
		(start 409.185872 -224.577402)
		(end 409.185872 -224.209864)
		(width 0.20066)
		(layer "F.Cu")
		(net "M_E_CPU0_SB_DQ<5>")
	)
	(segment
		(start 412.705296 -224.51695)
		(end 414.29686 -224.51695)
		(width 0.20066)
		(layer "F.Cu")
		(net "M_E_CPU0_SB_DQ<5>")
	)
	(segment
		(start 411.863794 -224.085404)
		(end 412.27375 -224.085404)
		(width 0.20066)
		(layer "F.Cu")
		(net "M_E_CPU0_SB_DQ<5>")
	)
	(segment
		(start 414.29686 -224.51695)
		(end 414.297114 -224.516696)
		(width 0.20066)
		(layer "F.Cu")
		(net "M_E_CPU0_SB_DQ<5>")
	)
	(segment
		(start 381.665734 -233.87812)
		(end 381.665734 -233.34218)
		(width 0.20066)
		(layer "F.Cu")
		(net "M_E_CPU0_SB_DQ<5>")
	)
	(segment
		(start 409.303982 -224.091754)
		(end 409.64866 -224.091754)
		(width 0.20066)
		(layer "F.Cu")
		(net "M_E_CPU0_SB_DQ<5>")
	)
	(segment
		(start 411.857444 -224.091754)
		(end 411.863794 -224.085404)
		(width 0.1016)
		(layer "F.Cu")
		(net "M_E_CPU0_SB_DQ<5>")
	)
	(segment
		(start 408.274012 -224.516696)
		(end 408.522678 -224.765362)
		(width 0.20066)
		(layer "F.Cu")
		(net "M_E_CPU0_SB_DQ<5>")
	)
	(segment
		(start 408.522678 -224.765362)
		(end 408.997912 -224.765362)
		(width 0.20066)
		(layer "F.Cu")
		(net "M_E_CPU0_SB_DQ<5>")
	)
	(segment
		(start 383.358136 -233.017822)
		(end 383.357882 -233.017822)
		(width 0.088646)
		(layer "In2.Cu")
		(net "M_E_CPU0_SB_DQ<5>")
	)
	(segment
		(start 402.521166 -226.462082)
		(end 402.295868 -226.68738)
		(width 0.18288)
		(layer "In2.Cu")
		(net "M_E_CPU0_SB_DQ<5>")
	)
	(segment
		(start 400.168364 -228.814884)
		(end 399.177764 -228.814884)
		(width 0.18288)
		(layer "In2.Cu")
		(net "M_E_CPU0_SB_DQ<5>")
	)
	(segment
		(start 401.57527 -226.512374)
		(end 401.349972 -226.737672)
		(width 0.18288)
		(layer "In2.Cu")
		(net "M_E_CPU0_SB_DQ<5>")
	)
	(segment
		(start 388.58571 -232.316274)
		(end 387.440932 -232.316274)
		(width 0.088646)
		(layer "In2.Cu")
		(net "M_E_CPU0_SB_DQ<5>")
	)
	(segment
		(start 401.524978 -227.185474)
		(end 401.524978 -227.45827)
		(width 0.18288)
		(layer "In2.Cu")
		(net "M_E_CPU0_SB_DQ<5>")
	)
	(segment
		(start 401.349972 -226.737672)
		(end 401.349972 -227.010468)
		(width 0.18288)
		(layer "In2.Cu")
		(net "M_E_CPU0_SB_DQ<5>")
	)
	(segment
		(start 403.567646 -224.519998)
		(end 403.342348 -224.745296)
		(width 0.18288)
		(layer "In2.Cu")
		(net "M_E_CPU0_SB_DQ<5>")
	)
	(segment
		(start 400.52879 -228.181662)
		(end 400.52879 -228.454458)
		(width 0.18288)
		(layer "In2.Cu")
		(net "M_E_CPU0_SB_DQ<5>")
	)
	(segment
		(start 400.353784 -227.73386)
		(end 400.353784 -228.006656)
		(width 0.18288)
		(layer "In2.Cu")
		(net "M_E_CPU0_SB_DQ<5>")
	)
	(segment
		(start 402.34616 -225.741484)
		(end 402.34616 -226.01428)
		(width 0.18288)
		(layer "In2.Cu")
		(net "M_E_CPU0_SB_DQ<5>")
	)
	(segment
		(start 401.29968 -227.683568)
		(end 401.026884 -227.683568)
		(width 0.18288)
		(layer "In2.Cu")
		(net "M_E_CPU0_SB_DQ<5>")
	)
	(segment
		(start 403.01926 -225.691192)
		(end 402.844254 -225.516186)
		(width 0.18288)
		(layer "In2.Cu")
		(net "M_E_CPU0_SB_DQ<5>")
	)
	(segment
		(start 401.349972 -227.010468)
		(end 401.524978 -227.185474)
		(width 0.18288)
		(layer "In2.Cu")
		(net "M_E_CPU0_SB_DQ<5>")
	)
	(segment
		(start 386.459984 -232.528364)
		(end 386.459984 -232.53827)
		(width 0.088646)
		(layer "In2.Cu")
		(net "M_E_CPU0_SB_DQ<5>")
	)
	(segment
		(start 400.52879 -228.454458)
		(end 400.168364 -228.814884)
		(width 0.18288)
		(layer "In2.Cu")
		(net "M_E_CPU0_SB_DQ<5>")
	)
	(segment
		(start 403.517354 -225.193098)
		(end 403.517354 -225.465894)
		(width 0.18288)
		(layer "In2.Cu")
		(net "M_E_CPU0_SB_DQ<5>")
	)
	(segment
		(start 400.851878 -227.508562)
		(end 400.579082 -227.508562)
		(width 0.18288)
		(layer "In2.Cu")
		(net "M_E_CPU0_SB_DQ<5>")
	)
	(segment
		(start 403.840442 -224.519998)
		(end 403.567646 -224.519998)
		(width 0.18288)
		(layer "In2.Cu")
		(net "M_E_CPU0_SB_DQ<5>")
	)
	(segment
		(start 400.353784 -228.006656)
		(end 400.52879 -228.181662)
		(width 0.18288)
		(layer "In2.Cu")
		(net "M_E_CPU0_SB_DQ<5>")
	)
	(segment
		(start 402.023072 -226.68738)
		(end 401.848066 -226.512374)
		(width 0.18288)
		(layer "In2.Cu")
		(net "M_E_CPU0_SB_DQ<5>")
	)
	(segment
		(start 382.044194 -233.407966)
		(end 381.978408 -233.34218)
		(width 0.088646)
		(layer "In2.Cu")
		(net "M_E_CPU0_SB_DQ<5>")
	)
	(segment
		(start 402.34616 -226.01428)
		(end 402.521166 -226.189286)
		(width 0.18288)
		(layer "In2.Cu")
		(net "M_E_CPU0_SB_DQ<5>")
	)
	(segment
		(start 404.015448 -224.695004)
		(end 403.840442 -224.519998)
		(width 0.18288)
		(layer "In2.Cu")
		(net "M_E_CPU0_SB_DQ<5>")
	)
	(segment
		(start 402.844254 -225.516186)
		(end 402.571458 -225.516186)
		(width 0.18288)
		(layer "In2.Cu")
		(net "M_E_CPU0_SB_DQ<5>")
	)
	(segment
		(start 402.295868 -226.68738)
		(end 402.023072 -226.68738)
		(width 0.18288)
		(layer "In2.Cu")
		(net "M_E_CPU0_SB_DQ<5>")
	)
	(segment
		(start 401.848066 -226.512374)
		(end 401.57527 -226.512374)
		(width 0.18288)
		(layer "In2.Cu")
		(net "M_E_CPU0_SB_DQ<5>")
	)
	(segment
		(start 400.579082 -227.508562)
		(end 400.353784 -227.73386)
		(width 0.18288)
		(layer "In2.Cu")
		(net "M_E_CPU0_SB_DQ<5>")
	)
	(segment
		(start 402.571458 -225.516186)
		(end 402.34616 -225.741484)
		(width 0.18288)
		(layer "In2.Cu")
		(net "M_E_CPU0_SB_DQ<5>")
	)
	(segment
		(start 404.288244 -224.695004)
		(end 404.015448 -224.695004)
		(width 0.18288)
		(layer "In2.Cu")
		(net "M_E_CPU0_SB_DQ<5>")
	)
	(segment
		(start 403.342348 -224.745296)
		(end 403.342348 -225.018092)
		(width 0.18288)
		(layer "In2.Cu")
		(net "M_E_CPU0_SB_DQ<5>")
	)
	(segment
		(start 405.623014 -224.516696)
		(end 404.466552 -224.516696)
		(width 0.18288)
		(layer "In2.Cu")
		(net "M_E_CPU0_SB_DQ<5>")
	)
	(segment
		(start 403.292056 -225.691192)
		(end 403.01926 -225.691192)
		(width 0.18288)
		(layer "In2.Cu")
		(net "M_E_CPU0_SB_DQ<5>")
	)
	(segment
		(start 402.521166 -226.189286)
		(end 402.521166 -226.462082)
		(width 0.18288)
		(layer "In2.Cu")
		(net "M_E_CPU0_SB_DQ<5>")
	)
	(segment
		(start 401.524978 -227.45827)
		(end 401.29968 -227.683568)
		(width 0.18288)
		(layer "In2.Cu")
		(net "M_E_CPU0_SB_DQ<5>")
	)
	(segment
		(start 401.026884 -227.683568)
		(end 400.851878 -227.508562)
		(width 0.18288)
		(layer "In2.Cu")
		(net "M_E_CPU0_SB_DQ<5>")
	)
	(segment
		(start 395.676374 -232.316274)
		(end 388.58571 -232.316274)
		(width 0.18288)
		(layer "In2.Cu")
		(net "M_E_CPU0_SB_DQ<5>")
	)
	(segment
		(start 403.342348 -225.018092)
		(end 403.517354 -225.193098)
		(width 0.18288)
		(layer "In2.Cu")
		(net "M_E_CPU0_SB_DQ<5>")
	)
	(segment
		(start 404.466552 -224.516696)
		(end 404.288244 -224.695004)
		(width 0.18288)
		(layer "In2.Cu")
		(net "M_E_CPU0_SB_DQ<5>")
	)
	(segment
		(start 399.177764 -228.814884)
		(end 395.676374 -232.316274)
		(width 0.18288)
		(layer "In2.Cu")
		(net "M_E_CPU0_SB_DQ<5>")
	)
	(segment
		(start 383.170684 -233.338878)
		(end 383.170684 -233.34218)
		(width 0.088646)
		(layer "In2.Cu")
		(net "M_E_CPU0_SB_DQ<5>")
	)
	(segment
		(start 403.517354 -225.465894)
		(end 403.292056 -225.691192)
		(width 0.18288)
		(layer "In2.Cu")
		(net "M_E_CPU0_SB_DQ<5>")
	)
	(segment
		(start 386.647436 -232.204006)
		(end 386.638546 -232.209086)
		(width 0.088646)
		(layer "In2.Cu")
		(net "M_E_CPU0_SB_DQ<5>")
	)
	(segment
		(start 381.978408 -233.34218)
		(end 381.665734 -233.34218)
		(width 0.088646)
		(layer "In2.Cu")
		(net "M_E_CPU0_SB_DQ<5>")
	)
	(arc
		(start 383.732532 -233.017822)
		(mid 383.545334 -232.967679)
		(end 383.358136 -233.017822)
		(width 0.088646)
		(layer "In2.Cu")
		(net "M_E_CPU0_SB_DQ<5>")
	)
	(arc
		(start 387.440932 -232.316274)
		(mid 387.223997 -232.287715)
		(end 387.021832 -232.204006)
		(width 0.088646)
		(layer "In2.Cu")
		(net "M_E_CPU0_SB_DQ<5>")
	)
	(arc
		(start 385.612132 -233.017822)
		(mid 385.424934 -232.967679)
		(end 385.237736 -233.017822)
		(width 0.088646)
		(layer "In2.Cu")
		(net "M_E_CPU0_SB_DQ<5>")
	)
	(arc
		(start 386.177536 -233.017822)
		(mid 385.894834 -233.093598)
		(end 385.612132 -233.017822)
		(width 0.088646)
		(layer "In2.Cu")
		(net "M_E_CPU0_SB_DQ<5>")
	)
	(arc
		(start 383.357882 -233.017822)
		(mid 383.221685 -233.153507)
		(end 383.170684 -233.338878)
		(width 0.088646)
		(layer "In2.Cu")
		(net "M_E_CPU0_SB_DQ<5>")
	)
	(arc
		(start 387.021832 -232.204006)
		(mid 386.834634 -232.153863)
		(end 386.647436 -232.204006)
		(width 0.088646)
		(layer "In2.Cu")
		(net "M_E_CPU0_SB_DQ<5>")
	)
	(arc
		(start 384.297936 -233.017822)
		(mid 384.015234 -233.093598)
		(end 383.732532 -233.017822)
		(width 0.088646)
		(layer "In2.Cu")
		(net "M_E_CPU0_SB_DQ<5>")
	)
	(arc
		(start 383.170684 -233.34218)
		(mid 382.638481 -233.906369)
		(end 382.044194 -233.407966)
		(width 0.088646)
		(layer "In2.Cu")
		(net "M_E_CPU0_SB_DQ<5>")
	)
	(arc
		(start 386.638546 -232.209086)
		(mid 386.507632 -232.345446)
		(end 386.459984 -232.528364)
		(width 0.088646)
		(layer "In2.Cu")
		(net "M_E_CPU0_SB_DQ<5>")
	)
	(arc
		(start 386.459984 -232.53827)
		(mid 386.381873 -232.815219)
		(end 386.177536 -233.017822)
		(width 0.088646)
		(layer "In2.Cu")
		(net "M_E_CPU0_SB_DQ<5>")
	)
	(arc
		(start 384.672332 -233.017822)
		(mid 384.485134 -232.967679)
		(end 384.297936 -233.017822)
		(width 0.088646)
		(layer "In2.Cu")
		(net "M_E_CPU0_SB_DQ<5>")
	)
	(arc
		(start 385.237736 -233.017822)
		(mid 384.955034 -233.093598)
		(end 384.672332 -233.017822)
		(width 0.088646)
		(layer "In2.Cu")
		(net "M_E_CPU0_SB_DQ<5>")
	)
	(segment
		(start 405.623014 -226.216718)
		(end 406.753314 -226.216718)
		(width 0.20066)
		(layer "F.Cu")
		(net "M_E_CPU0_SB_DQ<4>")
	)
	(segment
		(start 409.64866 -225.791776)
		(end 409.69565 -225.791776)
		(width 0.101854)
		(layer "F.Cu")
		(net "M_E_CPU0_SB_DQ<4>")
	)
	(segment
		(start 412.705296 -226.216972)
		(end 414.29686 -226.216972)
		(width 0.20066)
		(layer "F.Cu")
		(net "M_E_CPU0_SB_DQ<4>")
	)
	(segment
		(start 408.522678 -226.465384)
		(end 408.997912 -226.465384)
		(width 0.20066)
		(layer "F.Cu")
		(net "M_E_CPU0_SB_DQ<4>")
	)
	(segment
		(start 409.185872 -225.909886)
		(end 409.303982 -225.791776)
		(width 0.20066)
		(layer "F.Cu")
		(net "M_E_CPU0_SB_DQ<4>")
	)
	(segment
		(start 409.303982 -225.791776)
		(end 409.64866 -225.791776)
		(width 0.20066)
		(layer "F.Cu")
		(net "M_E_CPU0_SB_DQ<4>")
	)
	(segment
		(start 409.185872 -226.277424)
		(end 409.185872 -225.909886)
		(width 0.20066)
		(layer "F.Cu")
		(net "M_E_CPU0_SB_DQ<4>")
	)
	(segment
		(start 411.857444 -225.791776)
		(end 411.863794 -225.785426)
		(width 0.1016)
		(layer "F.Cu")
		(net "M_E_CPU0_SB_DQ<4>")
	)
	(segment
		(start 406.753314 -226.216718)
		(end 408.274012 -226.216718)
		(width 0.20066)
		(layer "F.Cu")
		(net "M_E_CPU0_SB_DQ<4>")
	)
	(segment
		(start 411.863794 -225.785426)
		(end 412.27375 -225.785426)
		(width 0.20066)
		(layer "F.Cu")
		(net "M_E_CPU0_SB_DQ<4>")
	)
	(segment
		(start 408.274012 -226.216718)
		(end 408.522678 -226.465384)
		(width 0.20066)
		(layer "F.Cu")
		(net "M_E_CPU0_SB_DQ<4>")
	)
	(segment
		(start 381.195834 -234.691936)
		(end 381.195834 -234.15625)
		(width 0.20066)
		(layer "F.Cu")
		(net "M_E_CPU0_SB_DQ<4>")
	)
	(segment
		(start 412.27375 -225.785426)
		(end 412.705296 -226.216972)
		(width 0.20066)
		(layer "F.Cu")
		(net "M_E_CPU0_SB_DQ<4>")
	)
	(segment
		(start 409.69565 -225.791776)
		(end 411.857444 -225.791776)
		(width 0.1016)
		(layer "F.Cu")
		(net "M_E_CPU0_SB_DQ<4>")
	)
	(segment
		(start 408.997912 -226.465384)
		(end 409.185872 -226.277424)
		(width 0.20066)
		(layer "F.Cu")
		(net "M_E_CPU0_SB_DQ<4>")
	)
	(segment
		(start 414.29686 -226.216972)
		(end 414.297114 -226.216718)
		(width 0.20066)
		(layer "F.Cu")
		(net "M_E_CPU0_SB_DQ<4>")
	)
	(segment
		(start 381.19558 -234.69219)
		(end 381.195834 -234.691936)
		(width 0.20066)
		(layer "F.Cu")
		(net "M_E_CPU0_SB_DQ<4>")
	)
	(segment
		(start 404.396194 -226.039172)
		(end 400.257264 -230.178102)
		(width 0.18288)
		(layer "In2.Cu")
		(net "M_E_CPU0_SB_DQ<4>")
	)
	(segment
		(start 388.18439 -233.335322)
		(end 387.816344 -232.967276)
		(width 0.088646)
		(layer "In2.Cu")
		(net "M_E_CPU0_SB_DQ<4>")
	)
	(segment
		(start 398.264888 -232.170478)
		(end 397.992092 -232.170478)
		(width 0.18288)
		(layer "In2.Cu")
		(net "M_E_CPU0_SB_DQ<4>")
	)
	(segment
		(start 397.291052 -232.19283)
		(end 397.291052 -232.465626)
		(width 0.18288)
		(layer "In2.Cu")
		(net "M_E_CPU0_SB_DQ<4>")
	)
	(segment
		(start 399.283428 -230.200454)
		(end 399.283428 -230.47325)
		(width 0.18288)
		(layer "In2.Cu")
		(net "M_E_CPU0_SB_DQ<4>")
	)
	(segment
		(start 382.893824 -234.48391)
		(end 382.887982 -234.480608)
		(width 0.088646)
		(layer "In2.Cu")
		(net "M_E_CPU0_SB_DQ<4>")
	)
	(segment
		(start 399.486374 -230.676196)
		(end 399.486374 -230.948992)
		(width 0.18288)
		(layer "In2.Cu")
		(net "M_E_CPU0_SB_DQ<4>")
	)
	(segment
		(start 396.746476 -233.335322)
		(end 388.585964 -233.335322)
		(width 0.18288)
		(layer "In2.Cu")
		(net "M_E_CPU0_SB_DQ<4>")
	)
	(segment
		(start 386.929884 -233.34218)
		(end 386.929884 -233.360722)
		(width 0.088646)
		(layer "In2.Cu")
		(net "M_E_CPU0_SB_DQ<4>")
	)
	(segment
		(start 399.984468 -230.178102)
		(end 399.781522 -229.975156)
		(width 0.18288)
		(layer "In2.Cu")
		(net "M_E_CPU0_SB_DQ<4>")
	)
	(segment
		(start 387.816344 -232.967276)
		(end 387.30428 -232.967276)
		(width 0.088646)
		(layer "In2.Cu")
		(net "M_E_CPU0_SB_DQ<4>")
	)
	(segment
		(start 383.828036 -233.831892)
		(end 383.819146 -233.836972)
		(width 0.088646)
		(layer "In2.Cu")
		(net "M_E_CPU0_SB_DQ<4>")
	)
	(segment
		(start 383.4638 -234.313984)
		(end 383.406396 -234.371134)
		(width 0.088646)
		(layer "In2.Cu")
		(net "M_E_CPU0_SB_DQ<4>")
	)
	(segment
		(start 382.887982 -234.480608)
		(end 382.88341 -234.477814)
		(width 0.088646)
		(layer "In2.Cu")
		(net "M_E_CPU0_SB_DQ<4>")
	)
	(segment
		(start 399.508726 -229.975156)
		(end 399.283428 -230.200454)
		(width 0.18288)
		(layer "In2.Cu")
		(net "M_E_CPU0_SB_DQ<4>")
	)
	(segment
		(start 398.490186 -231.94518)
		(end 398.264888 -232.170478)
		(width 0.18288)
		(layer "In2.Cu")
		(net "M_E_CPU0_SB_DQ<4>")
	)
	(segment
		(start 405.623014 -226.216718)
		(end 405.445468 -226.039172)
		(width 0.18288)
		(layer "In2.Cu")
		(net "M_E_CPU0_SB_DQ<4>")
	)
	(segment
		(start 397.992092 -232.170478)
		(end 397.789146 -231.967532)
		(width 0.18288)
		(layer "In2.Cu")
		(net "M_E_CPU0_SB_DQ<4>")
	)
	(segment
		(start 381.948182 -234.480608)
		(end 381.547878 -234.25023)
		(width 0.088646)
		(layer "In2.Cu")
		(net "M_E_CPU0_SB_DQ<4>")
	)
	(segment
		(start 383.26695 -234.478068)
		(end 383.262632 -234.480608)
		(width 0.088646)
		(layer "In2.Cu")
		(net "M_E_CPU0_SB_DQ<4>")
	)
	(segment
		(start 399.486374 -230.948992)
		(end 399.261076 -231.17429)
		(width 0.18288)
		(layer "In2.Cu")
		(net "M_E_CPU0_SB_DQ<4>")
	)
	(segment
		(start 397.493998 -232.668572)
		(end 397.493998 -232.941368)
		(width 0.18288)
		(layer "In2.Cu")
		(net "M_E_CPU0_SB_DQ<4>")
	)
	(segment
		(start 399.283428 -230.47325)
		(end 399.486374 -230.676196)
		(width 0.18288)
		(layer "In2.Cu")
		(net "M_E_CPU0_SB_DQ<4>")
	)
	(segment
		(start 398.490186 -231.672384)
		(end 398.490186 -231.94518)
		(width 0.18288)
		(layer "In2.Cu")
		(net "M_E_CPU0_SB_DQ<4>")
	)
	(segment
		(start 397.493998 -232.941368)
		(end 397.34998 -233.085386)
		(width 0.18288)
		(layer "In2.Cu")
		(net "M_E_CPU0_SB_DQ<4>")
	)
	(segment
		(start 388.585964 -233.335322)
		(end 388.18439 -233.335322)
		(width 0.088646)
		(layer "In2.Cu")
		(net "M_E_CPU0_SB_DQ<4>")
	)
	(segment
		(start 400.257264 -230.178102)
		(end 399.984468 -230.178102)
		(width 0.18288)
		(layer "In2.Cu")
		(net "M_E_CPU0_SB_DQ<4>")
	)
	(segment
		(start 398.512538 -230.971344)
		(end 398.28724 -231.196642)
		(width 0.18288)
		(layer "In2.Cu")
		(net "M_E_CPU0_SB_DQ<4>")
	)
	(segment
		(start 405.445468 -226.039172)
		(end 404.396194 -226.039172)
		(width 0.18288)
		(layer "In2.Cu")
		(net "M_E_CPU0_SB_DQ<4>")
	)
	(segment
		(start 399.781522 -229.975156)
		(end 399.508726 -229.975156)
		(width 0.18288)
		(layer "In2.Cu")
		(net "M_E_CPU0_SB_DQ<4>")
	)
	(segment
		(start 397.51635 -231.967532)
		(end 397.291052 -232.19283)
		(width 0.18288)
		(layer "In2.Cu")
		(net "M_E_CPU0_SB_DQ<4>")
	)
	(segment
		(start 398.98828 -231.17429)
		(end 398.785334 -230.971344)
		(width 0.18288)
		(layer "In2.Cu")
		(net "M_E_CPU0_SB_DQ<4>")
	)
	(segment
		(start 397.789146 -231.967532)
		(end 397.51635 -231.967532)
		(width 0.18288)
		(layer "In2.Cu")
		(net "M_E_CPU0_SB_DQ<4>")
	)
	(segment
		(start 398.785334 -230.971344)
		(end 398.512538 -230.971344)
		(width 0.18288)
		(layer "In2.Cu")
		(net "M_E_CPU0_SB_DQ<4>")
	)
	(segment
		(start 398.28724 -231.469438)
		(end 398.490186 -231.672384)
		(width 0.18288)
		(layer "In2.Cu")
		(net "M_E_CPU0_SB_DQ<4>")
	)
	(segment
		(start 398.28724 -231.196642)
		(end 398.28724 -231.469438)
		(width 0.18288)
		(layer "In2.Cu")
		(net "M_E_CPU0_SB_DQ<4>")
	)
	(segment
		(start 397.291052 -232.465626)
		(end 397.493998 -232.668572)
		(width 0.18288)
		(layer "In2.Cu")
		(net "M_E_CPU0_SB_DQ<4>")
	)
	(segment
		(start 399.261076 -231.17429)
		(end 398.98828 -231.17429)
		(width 0.18288)
		(layer "In2.Cu")
		(net "M_E_CPU0_SB_DQ<4>")
	)
	(segment
		(start 397.34998 -233.085386)
		(end 396.746476 -233.335322)
		(width 0.18288)
		(layer "In2.Cu")
		(net "M_E_CPU0_SB_DQ<4>")
	)
	(segment
		(start 383.688336 -233.97337)
		(end 383.58826 -234.15244)
		(width 0.088646)
		(layer "In2.Cu")
		(net "M_E_CPU0_SB_DQ<4>")
	)
	(arc
		(start 383.819146 -233.836972)
		(mid 383.745028 -233.896809)
		(end 383.688336 -233.97337)
		(width 0.088646)
		(layer "In2.Cu")
		(net "M_E_CPU0_SB_DQ<4>")
	)
	(arc
		(start 383.262632 -234.480608)
		(mid 383.078678 -234.530737)
		(end 382.893824 -234.48391)
		(width 0.088646)
		(layer "In2.Cu")
		(net "M_E_CPU0_SB_DQ<4>")
	)
	(arc
		(start 382.322832 -234.480608)
		(mid 382.135524 -234.530751)
		(end 381.948182 -234.480608)
		(width 0.088646)
		(layer "In2.Cu")
		(net "M_E_CPU0_SB_DQ<4>")
	)
	(arc
		(start 385.142232 -233.831892)
		(mid 384.955034 -233.781749)
		(end 384.767836 -233.831892)
		(width 0.088646)
		(layer "In2.Cu")
		(net "M_E_CPU0_SB_DQ<4>")
	)
	(arc
		(start 382.88341 -234.477814)
		(mid 382.602746 -234.404806)
		(end 382.322832 -234.480608)
		(width 0.088646)
		(layer "In2.Cu")
		(net "M_E_CPU0_SB_DQ<4>")
	)
	(arc
		(start 385.707636 -233.831892)
		(mid 385.424934 -233.907634)
		(end 385.142232 -233.831892)
		(width 0.088646)
		(layer "In2.Cu")
		(net "M_E_CPU0_SB_DQ<4>")
	)
	(arc
		(start 383.406396 -234.371134)
		(mid 383.340178 -234.429172)
		(end 383.26695 -234.478068)
		(width 0.088646)
		(layer "In2.Cu")
		(net "M_E_CPU0_SB_DQ<4>")
	)
	(arc
		(start 386.647436 -233.831892)
		(mid 386.364734 -233.907634)
		(end 386.082032 -233.831892)
		(width 0.088646)
		(layer "In2.Cu")
		(net "M_E_CPU0_SB_DQ<4>")
	)
	(arc
		(start 384.767836 -233.831892)
		(mid 384.485134 -233.907634)
		(end 384.202432 -233.831892)
		(width 0.088646)
		(layer "In2.Cu")
		(net "M_E_CPU0_SB_DQ<4>")
	)
	(arc
		(start 383.530602 -234.228894)
		(mid 383.499695 -234.273397)
		(end 383.4638 -234.313984)
		(width 0.088646)
		(layer "In2.Cu")
		(net "M_E_CPU0_SB_DQ<4>")
	)
	(arc
		(start 381.547878 -234.25023)
		(mid 381.378034 -234.180087)
		(end 381.195834 -234.15625)
		(width 0.088646)
		(layer "In2.Cu")
		(net "M_E_CPU0_SB_DQ<4>")
	)
	(arc
		(start 384.202432 -233.831892)
		(mid 384.015234 -233.781749)
		(end 383.828036 -233.831892)
		(width 0.088646)
		(layer "In2.Cu")
		(net "M_E_CPU0_SB_DQ<4>")
	)
	(arc
		(start 386.082032 -233.831892)
		(mid 385.894834 -233.781749)
		(end 385.707636 -233.831892)
		(width 0.088646)
		(layer "In2.Cu")
		(net "M_E_CPU0_SB_DQ<4>")
	)
	(arc
		(start 383.58826 -234.15244)
		(mid 383.562081 -234.192666)
		(end 383.530602 -234.228894)
		(width 0.088646)
		(layer "In2.Cu")
		(net "M_E_CPU0_SB_DQ<4>")
	)
	(arc
		(start 387.30428 -232.967276)
		(mid 387.039511 -233.077262)
		(end 386.929884 -233.34218)
		(width 0.088646)
		(layer "In2.Cu")
		(net "M_E_CPU0_SB_DQ<4>")
	)
	(arc
		(start 386.929884 -233.360722)
		(mid 386.849722 -233.632911)
		(end 386.647436 -233.831892)
		(width 0.088646)
		(layer "In2.Cu")
		(net "M_E_CPU0_SB_DQ<4>")
	)
	(segment
		(start 412.983934 -230.055674)
		(end 412.545022 -229.616762)
		(width 0.20066)
		(layer "F.Cu")
		(net "M_E_CPU0_SB_DQ<3>")
	)
	(segment
		(start 413.307022 -230.041704)
		(end 413.293052 -230.055674)
		(width 0.1016)
		(layer "F.Cu")
		(net "M_E_CPU0_SB_DQ<3>")
	)
	(segment
		(start 416.009328 -230.064818)
		(end 415.307526 -230.064818)
		(width 0.20066)
		(layer "F.Cu")
		(net "M_E_CPU0_SB_DQ<3>")
	)
	(segment
		(start 417.07562 -229.616762)
		(end 416.823652 -229.364794)
		(width 0.20066)
		(layer "F.Cu")
		(net "M_E_CPU0_SB_DQ<3>")
	)
	(segment
		(start 410.853382 -229.616762)
		(end 409.723082 -229.616762)
		(width 0.20066)
		(layer "F.Cu")
		(net "M_E_CPU0_SB_DQ<3>")
	)
	(segment
		(start 416.439604 -229.364794)
		(end 416.205416 -229.598982)
		(width 0.20066)
		(layer "F.Cu")
		(net "M_E_CPU0_SB_DQ<3>")
	)
	(segment
		(start 383.07518 -236.319822)
		(end 383.07518 -235.784136)
		(width 0.20066)
		(layer "F.Cu")
		(net "M_E_CPU0_SB_DQ<3>")
	)
	(segment
		(start 412.545022 -229.616762)
		(end 410.853382 -229.616762)
		(width 0.20066)
		(layer "F.Cu")
		(net "M_E_CPU0_SB_DQ<3>")
	)
	(segment
		(start 383.07518 -235.784136)
		(end 383.075434 -235.783882)
		(width 0.20066)
		(layer "F.Cu")
		(net "M_E_CPU0_SB_DQ<3>")
	)
	(segment
		(start 416.205416 -229.86873)
		(end 416.009328 -230.064818)
		(width 0.20066)
		(layer "F.Cu")
		(net "M_E_CPU0_SB_DQ<3>")
	)
	(segment
		(start 416.205416 -229.598982)
		(end 416.205416 -229.86873)
		(width 0.20066)
		(layer "F.Cu")
		(net "M_E_CPU0_SB_DQ<3>")
	)
	(segment
		(start 415.307526 -230.064818)
		(end 415.284412 -230.041704)
		(width 0.1016)
		(layer "F.Cu")
		(net "M_E_CPU0_SB_DQ<3>")
	)
	(segment
		(start 418.397182 -229.616762)
		(end 417.07562 -229.616762)
		(width 0.20066)
		(layer "F.Cu")
		(net "M_E_CPU0_SB_DQ<3>")
	)
	(segment
		(start 416.823652 -229.364794)
		(end 416.439604 -229.364794)
		(width 0.20066)
		(layer "F.Cu")
		(net "M_E_CPU0_SB_DQ<3>")
	)
	(segment
		(start 415.284412 -230.041704)
		(end 413.307022 -230.041704)
		(width 0.1016)
		(layer "F.Cu")
		(net "M_E_CPU0_SB_DQ<3>")
	)
	(segment
		(start 413.275526 -230.055674)
		(end 412.983934 -230.055674)
		(width 0.20066)
		(layer "F.Cu")
		(net "M_E_CPU0_SB_DQ<3>")
	)
	(segment
		(start 413.293052 -230.055674)
		(end 413.275526 -230.055674)
		(width 0.101854)
		(layer "F.Cu")
		(net "M_E_CPU0_SB_DQ<3>")
	)
	(segment
		(start 407.117042 -229.746556)
		(end 406.906476 -229.957122)
		(width 0.18288)
		(layer "In2.Cu")
		(net "M_E_CPU0_SB_DQ<3>")
	)
	(segment
		(start 406.238456 -229.190804)
		(end 404.495508 -229.190804)
		(width 0.18288)
		(layer "In2.Cu")
		(net "M_E_CPU0_SB_DQ<3>")
	)
	(segment
		(start 406.906476 -229.957122)
		(end 406.558496 -229.957122)
		(width 0.18288)
		(layer "In2.Cu")
		(net "M_E_CPU0_SB_DQ<3>")
	)
	(segment
		(start 408.455876 -229.030784)
		(end 408.455876 -228.567234)
		(width 0.18288)
		(layer "In2.Cu")
		(net "M_E_CPU0_SB_DQ<3>")
	)
	(segment
		(start 406.398476 -229.797102)
		(end 406.398476 -229.350824)
		(width 0.18288)
		(layer "In2.Cu")
		(net "M_E_CPU0_SB_DQ<3>")
	)
	(segment
		(start 383.828036 -236.10824)
		(end 383.647442 -236.0041)
		(width 0.088646)
		(layer "In2.Cu")
		(net "M_E_CPU0_SB_DQ<3>")
	)
	(segment
		(start 407.729944 -228.567234)
		(end 407.729944 -229.030784)
		(width 0.18288)
		(layer "In2.Cu")
		(net "M_E_CPU0_SB_DQ<3>")
	)
	(segment
		(start 386.096764 -236.099604)
		(end 386.082032 -236.10824)
		(width 0.088646)
		(layer "In2.Cu")
		(net "M_E_CPU0_SB_DQ<3>")
	)
	(segment
		(start 406.558496 -229.957122)
		(end 406.398476 -229.797102)
		(width 0.18288)
		(layer "In2.Cu")
		(net "M_E_CPU0_SB_DQ<3>")
	)
	(segment
		(start 388.204964 -235.684314)
		(end 387.961124 -235.684314)
		(width 0.088646)
		(layer "In2.Cu")
		(net "M_E_CPU0_SB_DQ<3>")
	)
	(segment
		(start 408.295856 -228.407214)
		(end 407.889964 -228.407214)
		(width 0.18288)
		(layer "In2.Cu")
		(net "M_E_CPU0_SB_DQ<3>")
	)
	(segment
		(start 409.297124 -229.190804)
		(end 408.615896 -229.190804)
		(width 0.18288)
		(layer "In2.Cu")
		(net "M_E_CPU0_SB_DQ<3>")
	)
	(segment
		(start 407.889964 -228.407214)
		(end 407.729944 -228.567234)
		(width 0.18288)
		(layer "In2.Cu")
		(net "M_E_CPU0_SB_DQ<3>")
	)
	(segment
		(start 387.036564 -236.099604)
		(end 387.021832 -236.10824)
		(width 0.088646)
		(layer "In2.Cu")
		(net "M_E_CPU0_SB_DQ<3>")
	)
	(segment
		(start 384.217164 -236.099604)
		(end 384.202432 -236.10824)
		(width 0.088646)
		(layer "In2.Cu")
		(net "M_E_CPU0_SB_DQ<3>")
	)
	(segment
		(start 407.729944 -229.030784)
		(end 407.569924 -229.190804)
		(width 0.18288)
		(layer "In2.Cu")
		(net "M_E_CPU0_SB_DQ<3>")
	)
	(segment
		(start 408.615896 -229.190804)
		(end 408.455876 -229.030784)
		(width 0.18288)
		(layer "In2.Cu")
		(net "M_E_CPU0_SB_DQ<3>")
	)
	(segment
		(start 385.156964 -236.099604)
		(end 385.142232 -236.10824)
		(width 0.088646)
		(layer "In2.Cu")
		(net "M_E_CPU0_SB_DQ<3>")
	)
	(segment
		(start 409.723082 -229.616762)
		(end 409.297124 -229.190804)
		(width 0.18288)
		(layer "In2.Cu")
		(net "M_E_CPU0_SB_DQ<3>")
	)
	(segment
		(start 404.495508 -229.190804)
		(end 398.810226 -234.876086)
		(width 0.18288)
		(layer "In2.Cu")
		(net "M_E_CPU0_SB_DQ<3>")
	)
	(segment
		(start 407.302208 -229.190804)
		(end 407.117042 -229.37597)
		(width 0.18288)
		(layer "In2.Cu")
		(net "M_E_CPU0_SB_DQ<3>")
	)
	(segment
		(start 396.859252 -235.684314)
		(end 388.204964 -235.684314)
		(width 0.18288)
		(layer "In2.Cu")
		(net "M_E_CPU0_SB_DQ<3>")
	)
	(segment
		(start 387.961124 -235.684314)
		(end 387.572504 -236.072934)
		(width 0.088646)
		(layer "In2.Cu")
		(net "M_E_CPU0_SB_DQ<3>")
	)
	(segment
		(start 407.569924 -229.190804)
		(end 407.302208 -229.190804)
		(width 0.18288)
		(layer "In2.Cu")
		(net "M_E_CPU0_SB_DQ<3>")
	)
	(segment
		(start 408.455876 -228.567234)
		(end 408.295856 -228.407214)
		(width 0.18288)
		(layer "In2.Cu")
		(net "M_E_CPU0_SB_DQ<3>")
	)
	(segment
		(start 407.117042 -229.37597)
		(end 407.117042 -229.746556)
		(width 0.18288)
		(layer "In2.Cu")
		(net "M_E_CPU0_SB_DQ<3>")
	)
	(segment
		(start 398.810226 -234.876086)
		(end 396.859252 -235.684314)
		(width 0.18288)
		(layer "In2.Cu")
		(net "M_E_CPU0_SB_DQ<3>")
	)
	(segment
		(start 406.398476 -229.350824)
		(end 406.238456 -229.190804)
		(width 0.18288)
		(layer "In2.Cu")
		(net "M_E_CPU0_SB_DQ<3>")
	)
	(segment
		(start 387.572504 -236.072934)
		(end 387.514846 -236.072934)
		(width 0.088646)
		(layer "In2.Cu")
		(net "M_E_CPU0_SB_DQ<3>")
	)
	(segment
		(start 383.647442 -236.0041)
		(end 383.434082 -235.880402)
		(width 0.088646)
		(layer "In2.Cu")
		(net "M_E_CPU0_SB_DQ<3>")
	)
	(arc
		(start 384.767836 -236.10824)
		(mid 384.493607 -236.032315)
		(end 384.217164 -236.099604)
		(width 0.088646)
		(layer "In2.Cu")
		(net "M_E_CPU0_SB_DQ<3>")
	)
	(arc
		(start 384.202432 -236.10824)
		(mid 384.015234 -236.158383)
		(end 383.828036 -236.10824)
		(width 0.088646)
		(layer "In2.Cu")
		(net "M_E_CPU0_SB_DQ<3>")
	)
	(arc
		(start 386.647436 -236.10824)
		(mid 386.373207 -236.032315)
		(end 386.096764 -236.099604)
		(width 0.088646)
		(layer "In2.Cu")
		(net "M_E_CPU0_SB_DQ<3>")
	)
	(arc
		(start 385.707636 -236.10824)
		(mid 385.433407 -236.032315)
		(end 385.156964 -236.099604)
		(width 0.088646)
		(layer "In2.Cu")
		(net "M_E_CPU0_SB_DQ<3>")
	)
	(arc
		(start 386.082032 -236.10824)
		(mid 385.894834 -236.158383)
		(end 385.707636 -236.10824)
		(width 0.088646)
		(layer "In2.Cu")
		(net "M_E_CPU0_SB_DQ<3>")
	)
	(arc
		(start 387.021832 -236.10824)
		(mid 386.834634 -236.158383)
		(end 386.647436 -236.10824)
		(width 0.088646)
		(layer "In2.Cu")
		(net "M_E_CPU0_SB_DQ<3>")
	)
	(arc
		(start 383.434082 -235.880402)
		(mid 383.26113 -235.808465)
		(end 383.075434 -235.783882)
		(width 0.088646)
		(layer "In2.Cu")
		(net "M_E_CPU0_SB_DQ<3>")
	)
	(arc
		(start 385.142232 -236.10824)
		(mid 384.955034 -236.158383)
		(end 384.767836 -236.10824)
		(width 0.088646)
		(layer "In2.Cu")
		(net "M_E_CPU0_SB_DQ<3>")
	)
	(arc
		(start 387.514846 -236.072934)
		(mid 387.272748 -236.033162)
		(end 387.036564 -236.099604)
		(width 0.088646)
		(layer "In2.Cu")
		(net "M_E_CPU0_SB_DQ<3>")
	)
	(segment
		(start 412.980632 -196.052186)
		(end 412.545022 -195.616576)
		(width 0.20066)
		(layer "F.Cu")
		(net "M_E_CPU0_SB_DQ<31>")
	)
	(segment
		(start 387.231128 -203.706222)
		(end 390.09574 -200.84161)
		(width 0.20066)
		(layer "F.Cu")
		(net "M_E_CPU0_SB_DQ<31>")
	)
	(segment
		(start 400.134836 -196.052186)
		(end 405.731726 -196.052186)
		(width 0.20066)
		(layer "F.Cu")
		(net "M_E_CPU0_SB_DQ<31>")
	)
	(segment
		(start 416.439604 -195.364608)
		(end 416.205416 -195.598796)
		(width 0.20066)
		(layer "F.Cu")
		(net "M_E_CPU0_SB_DQ<31>")
	)
	(segment
		(start 418.397182 -195.616576)
		(end 417.07562 -195.616576)
		(width 0.20066)
		(layer "F.Cu")
		(net "M_E_CPU0_SB_DQ<31>")
	)
	(segment
		(start 405.731726 -196.052186)
		(end 405.765762 -196.052186)
		(width 0.101854)
		(layer "F.Cu")
		(net "M_E_CPU0_SB_DQ<31>")
	)
	(segment
		(start 412.545022 -195.616576)
		(end 410.853382 -195.616576)
		(width 0.20066)
		(layer "F.Cu")
		(net "M_E_CPU0_SB_DQ<31>")
	)
	(segment
		(start 385.588002 -212.034628)
		(end 385.588002 -208.24063)
		(width 0.20066)
		(layer "F.Cu")
		(net "M_E_CPU0_SB_DQ<31>")
	)
	(segment
		(start 407.747724 -196.041518)
		(end 407.763726 -196.05752)
		(width 0.1016)
		(layer "F.Cu")
		(net "M_E_CPU0_SB_DQ<31>")
	)
	(segment
		(start 395.144498 -197.468236)
		(end 396.536418 -196.809614)
		(width 0.20066)
		(layer "F.Cu")
		(net "M_E_CPU0_SB_DQ<31>")
	)
	(segment
		(start 405.765762 -196.052186)
		(end 405.77643 -196.041518)
		(width 0.101854)
		(layer "F.Cu")
		(net "M_E_CPU0_SB_DQ<31>")
	)
	(segment
		(start 415.291524 -196.041518)
		(end 413.32023 -196.041518)
		(width 0.1016)
		(layer "F.Cu")
		(net "M_E_CPU0_SB_DQ<31>")
	)
	(segment
		(start 390.09574 -200.84161)
		(end 395.144498 -197.468236)
		(width 0.20066)
		(layer "F.Cu")
		(net "M_E_CPU0_SB_DQ<31>")
	)
	(segment
		(start 385.588002 -208.24063)
		(end 385.805172 -207.14843)
		(width 0.20066)
		(layer "F.Cu")
		(net "M_E_CPU0_SB_DQ<31>")
	)
	(segment
		(start 386.431536 -214.071454)
		(end 385.588002 -212.034628)
		(width 0.20066)
		(layer "F.Cu")
		(net "M_E_CPU0_SB_DQ<31>")
	)
	(segment
		(start 413.309562 -196.052186)
		(end 413.275526 -196.052186)
		(width 0.101854)
		(layer "F.Cu")
		(net "M_E_CPU0_SB_DQ<31>")
	)
	(segment
		(start 396.536418 -196.809614)
		(end 397.979392 -196.371972)
		(width 0.20066)
		(layer "F.Cu")
		(net "M_E_CPU0_SB_DQ<31>")
	)
	(segment
		(start 397.979392 -196.371972)
		(end 400.134836 -196.052186)
		(width 0.20066)
		(layer "F.Cu")
		(net "M_E_CPU0_SB_DQ<31>")
	)
	(segment
		(start 386.890006 -225.74377)
		(end 387.184646 -225.287586)
		(width 0.088646)
		(layer "F.Cu")
		(net "M_E_CPU0_SB_DQ<31>")
	)
	(segment
		(start 413.32023 -196.041518)
		(end 413.309562 -196.052186)
		(width 0.101854)
		(layer "F.Cu")
		(net "M_E_CPU0_SB_DQ<31>")
	)
	(segment
		(start 405.77643 -196.041518)
		(end 407.747724 -196.041518)
		(width 0.1016)
		(layer "F.Cu")
		(net "M_E_CPU0_SB_DQ<31>")
	)
	(segment
		(start 385.805172 -207.14843)
		(end 387.231128 -203.706222)
		(width 0.20066)
		(layer "F.Cu")
		(net "M_E_CPU0_SB_DQ<31>")
	)
	(segment
		(start 416.205416 -195.861432)
		(end 416.009328 -196.05752)
		(width 0.20066)
		(layer "F.Cu")
		(net "M_E_CPU0_SB_DQ<31>")
	)
	(segment
		(start 386.480558 -226.104704)
		(end 386.551932 -226.063556)
		(width 0.088646)
		(layer "F.Cu")
		(net "M_E_CPU0_SB_DQ<31>")
	)
	(segment
		(start 408.205432 -196.05752)
		(end 409.2702 -195.616576)
		(width 0.20066)
		(layer "F.Cu")
		(net "M_E_CPU0_SB_DQ<31>")
	)
	(segment
		(start 387.353048 -225.119184)
		(end 387.64718 -224.825052)
		(width 0.1016)
		(layer "F.Cu")
		(net "M_E_CPU0_SB_DQ<31>")
	)
	(segment
		(start 386.629656 -226.00412)
		(end 386.890006 -225.74377)
		(width 0.088646)
		(layer "F.Cu")
		(net "M_E_CPU0_SB_DQ<31>")
	)
	(segment
		(start 387.184646 -225.287586)
		(end 387.353048 -225.119184)
		(width 0.088646)
		(layer "F.Cu")
		(net "M_E_CPU0_SB_DQ<31>")
	)
	(segment
		(start 416.823652 -195.364608)
		(end 416.439604 -195.364608)
		(width 0.20066)
		(layer "F.Cu")
		(net "M_E_CPU0_SB_DQ<31>")
	)
	(segment
		(start 413.275526 -196.052186)
		(end 412.980632 -196.052186)
		(width 0.20066)
		(layer "F.Cu")
		(net "M_E_CPU0_SB_DQ<31>")
	)
	(segment
		(start 407.763726 -196.05752)
		(end 408.205432 -196.05752)
		(width 0.20066)
		(layer "F.Cu")
		(net "M_E_CPU0_SB_DQ<31>")
	)
	(segment
		(start 387.64718 -215.287098)
		(end 387.204458 -214.844376)
		(width 0.1016)
		(layer "F.Cu")
		(net "M_E_CPU0_SB_DQ<31>")
	)
	(segment
		(start 387.204458 -214.844376)
		(end 386.431536 -214.071454)
		(width 0.20066)
		(layer "F.Cu")
		(net "M_E_CPU0_SB_DQ<31>")
	)
	(segment
		(start 415.307526 -196.05752)
		(end 415.291524 -196.041518)
		(width 0.1016)
		(layer "F.Cu")
		(net "M_E_CPU0_SB_DQ<31>")
	)
	(segment
		(start 417.07562 -195.616576)
		(end 416.823652 -195.364608)
		(width 0.20066)
		(layer "F.Cu")
		(net "M_E_CPU0_SB_DQ<31>")
	)
	(segment
		(start 416.009328 -196.05752)
		(end 415.307526 -196.05752)
		(width 0.20066)
		(layer "F.Cu")
		(net "M_E_CPU0_SB_DQ<31>")
	)
	(segment
		(start 416.205416 -195.598796)
		(end 416.205416 -195.861432)
		(width 0.20066)
		(layer "F.Cu")
		(net "M_E_CPU0_SB_DQ<31>")
	)
	(segment
		(start 387.64718 -224.825052)
		(end 387.64718 -215.287098)
		(width 0.1016)
		(layer "F.Cu")
		(net "M_E_CPU0_SB_DQ<31>")
	)
	(segment
		(start 409.2702 -195.616576)
		(end 410.853382 -195.616576)
		(width 0.20066)
		(layer "F.Cu")
		(net "M_E_CPU0_SB_DQ<31>")
	)
	(arc
		(start 385.894834 -226.553268)
		(mid 386.172905 -226.309674)
		(end 386.480558 -226.104704)
		(width 0.088646)
		(layer "F.Cu")
		(net "M_E_CPU0_SB_DQ<31>")
	)
	(arc
		(start 386.551932 -226.063556)
		(mid 386.592741 -226.036384)
		(end 386.629656 -226.00412)
		(width 0.088646)
		(layer "F.Cu")
		(net "M_E_CPU0_SB_DQ<31>")
	)
	(segment
		(start 405.690832 -197.74154)
		(end 406.023572 -197.74154)
		(width 0.101854)
		(layer "F.Cu")
		(net "M_E_CPU0_SB_DQ<30>")
	)
	(segment
		(start 388.155942 -213.87816)
		(end 387.439662 -213.16188)
		(width 0.20066)
		(layer "F.Cu")
		(net "M_E_CPU0_SB_DQ<30>")
	)
	(segment
		(start 405.680926 -197.751446)
		(end 405.690832 -197.74154)
		(width 0.101854)
		(layer "F.Cu")
		(net "M_E_CPU0_SB_DQ<30>")
	)
	(segment
		(start 412.545022 -197.316598)
		(end 410.853382 -197.316598)
		(width 0.20066)
		(layer "F.Cu")
		(net "M_E_CPU0_SB_DQ<30>")
	)
	(segment
		(start 405.004524 -197.335902)
		(end 405.420068 -197.751446)
		(width 0.20066)
		(layer "F.Cu")
		(net "M_E_CPU0_SB_DQ<30>")
	)
	(segment
		(start 386.867146 -211.779866)
		(end 386.867146 -208.3689)
		(width 0.20066)
		(layer "F.Cu")
		(net "M_E_CPU0_SB_DQ<30>")
	)
	(segment
		(start 416.439604 -197.06463)
		(end 416.205416 -197.298818)
		(width 0.20066)
		(layer "F.Cu")
		(net "M_E_CPU0_SB_DQ<30>")
	)
	(segment
		(start 407.839926 -197.757542)
		(end 408.225244 -197.757542)
		(width 0.20066)
		(layer "F.Cu")
		(net "M_E_CPU0_SB_DQ<30>")
	)
	(segment
		(start 418.397182 -197.316598)
		(end 417.07562 -197.316598)
		(width 0.20066)
		(layer "F.Cu")
		(net "M_E_CPU0_SB_DQ<30>")
	)
	(segment
		(start 415.307526 -197.757542)
		(end 415.291524 -197.74154)
		(width 0.1016)
		(layer "F.Cu")
		(net "M_E_CPU0_SB_DQ<30>")
	)
	(segment
		(start 386.867146 -208.3689)
		(end 387.036056 -207.520032)
		(width 0.20066)
		(layer "F.Cu")
		(net "M_E_CPU0_SB_DQ<30>")
	)
	(segment
		(start 388.25678 -226.11588)
		(end 388.25678 -213.978998)
		(width 0.1016)
		(layer "F.Cu")
		(net "M_E_CPU0_SB_DQ<30>")
	)
	(segment
		(start 386.819648 -226.91217)
		(end 387.46049 -226.91217)
		(width 0.088646)
		(layer "F.Cu")
		(net "M_E_CPU0_SB_DQ<30>")
	)
	(segment
		(start 416.205416 -197.298818)
		(end 416.205416 -197.556882)
		(width 0.20066)
		(layer "F.Cu")
		(net "M_E_CPU0_SB_DQ<30>")
	)
	(segment
		(start 387.439662 -213.16188)
		(end 386.867146 -211.779866)
		(width 0.20066)
		(layer "F.Cu")
		(net "M_E_CPU0_SB_DQ<30>")
	)
	(segment
		(start 406.023572 -197.74154)
		(end 407.747724 -197.74154)
		(width 0.1016)
		(layer "F.Cu")
		(net "M_E_CPU0_SB_DQ<30>")
	)
	(segment
		(start 413.275526 -197.752208)
		(end 412.980632 -197.752208)
		(width 0.20066)
		(layer "F.Cu")
		(net "M_E_CPU0_SB_DQ<30>")
	)
	(segment
		(start 390.978898 -201.790554)
		(end 395.777974 -198.584058)
		(width 0.20066)
		(layer "F.Cu")
		(net "M_E_CPU0_SB_DQ<30>")
	)
	(segment
		(start 397.009874 -198.080884)
		(end 403.047708 -198.080884)
		(width 0.20066)
		(layer "F.Cu")
		(net "M_E_CPU0_SB_DQ<30>")
	)
	(segment
		(start 396.540228 -198.223378)
		(end 397.009874 -198.080884)
		(width 0.20066)
		(layer "F.Cu")
		(net "M_E_CPU0_SB_DQ<30>")
	)
	(segment
		(start 407.763726 -197.757542)
		(end 407.839926 -197.757542)
		(width 0.101854)
		(layer "F.Cu")
		(net "M_E_CPU0_SB_DQ<30>")
	)
	(segment
		(start 387.46049 -226.91217)
		(end 387.998462 -226.374198)
		(width 0.088646)
		(layer "F.Cu")
		(net "M_E_CPU0_SB_DQ<30>")
	)
	(segment
		(start 386.364734 -227.367084)
		(end 386.819648 -226.91217)
		(width 0.088646)
		(layer "F.Cu")
		(net "M_E_CPU0_SB_DQ<30>")
	)
	(segment
		(start 413.309562 -197.752208)
		(end 413.275526 -197.752208)
		(width 0.101854)
		(layer "F.Cu")
		(net "M_E_CPU0_SB_DQ<30>")
	)
	(segment
		(start 387.036056 -207.520032)
		(end 388.299452 -204.47)
		(width 0.20066)
		(layer "F.Cu")
		(net "M_E_CPU0_SB_DQ<30>")
	)
	(segment
		(start 403.047708 -198.080884)
		(end 403.79269 -197.335902)
		(width 0.20066)
		(layer "F.Cu")
		(net "M_E_CPU0_SB_DQ<30>")
	)
	(segment
		(start 405.420068 -197.751446)
		(end 405.680926 -197.751446)
		(width 0.20066)
		(layer "F.Cu")
		(net "M_E_CPU0_SB_DQ<30>")
	)
	(segment
		(start 408.666188 -197.316598)
		(end 410.853382 -197.316598)
		(width 0.20066)
		(layer "F.Cu")
		(net "M_E_CPU0_SB_DQ<30>")
	)
	(segment
		(start 407.747724 -197.74154)
		(end 407.763726 -197.757542)
		(width 0.1016)
		(layer "F.Cu")
		(net "M_E_CPU0_SB_DQ<30>")
	)
	(segment
		(start 415.291524 -197.74154)
		(end 413.32023 -197.74154)
		(width 0.1016)
		(layer "F.Cu")
		(net "M_E_CPU0_SB_DQ<30>")
	)
	(segment
		(start 413.32023 -197.74154)
		(end 413.309562 -197.752208)
		(width 0.101854)
		(layer "F.Cu")
		(net "M_E_CPU0_SB_DQ<30>")
	)
	(segment
		(start 416.004756 -197.757542)
		(end 415.307526 -197.757542)
		(width 0.20066)
		(layer "F.Cu")
		(net "M_E_CPU0_SB_DQ<30>")
	)
	(segment
		(start 417.07562 -197.316598)
		(end 416.823652 -197.06463)
		(width 0.20066)
		(layer "F.Cu")
		(net "M_E_CPU0_SB_DQ<30>")
	)
	(segment
		(start 416.205416 -197.556882)
		(end 416.004756 -197.757542)
		(width 0.20066)
		(layer "F.Cu")
		(net "M_E_CPU0_SB_DQ<30>")
	)
	(segment
		(start 388.299452 -204.47)
		(end 390.978898 -201.790554)
		(width 0.20066)
		(layer "F.Cu")
		(net "M_E_CPU0_SB_DQ<30>")
	)
	(segment
		(start 416.823652 -197.06463)
		(end 416.439604 -197.06463)
		(width 0.20066)
		(layer "F.Cu")
		(net "M_E_CPU0_SB_DQ<30>")
	)
	(segment
		(start 395.777974 -198.584058)
		(end 396.540228 -198.223378)
		(width 0.20066)
		(layer "F.Cu")
		(net "M_E_CPU0_SB_DQ<30>")
	)
	(segment
		(start 403.79269 -197.335902)
		(end 405.004524 -197.335902)
		(width 0.20066)
		(layer "F.Cu")
		(net "M_E_CPU0_SB_DQ<30>")
	)
	(segment
		(start 412.980632 -197.752208)
		(end 412.545022 -197.316598)
		(width 0.20066)
		(layer "F.Cu")
		(net "M_E_CPU0_SB_DQ<30>")
	)
	(segment
		(start 387.998462 -226.374198)
		(end 388.25678 -226.11588)
		(width 0.1016)
		(layer "F.Cu")
		(net "M_E_CPU0_SB_DQ<30>")
	)
	(segment
		(start 408.225244 -197.757542)
		(end 408.666188 -197.316598)
		(width 0.20066)
		(layer "F.Cu")
		(net "M_E_CPU0_SB_DQ<30>")
	)
	(segment
		(start 388.25678 -213.978998)
		(end 388.155942 -213.87816)
		(width 0.1016)
		(layer "F.Cu")
		(net "M_E_CPU0_SB_DQ<30>")
	)
	(segment
		(start 416.823652 -231.064816)
		(end 416.439604 -231.064816)
		(width 0.20066)
		(layer "F.Cu")
		(net "M_E_CPU0_SB_DQ<2>")
	)
	(segment
		(start 413.275526 -231.756712)
		(end 412.98495 -231.756712)
		(width 0.20066)
		(layer "F.Cu")
		(net "M_E_CPU0_SB_DQ<2>")
	)
	(segment
		(start 412.545022 -231.316784)
		(end 410.853382 -231.316784)
		(width 0.20066)
		(layer "F.Cu")
		(net "M_E_CPU0_SB_DQ<2>")
	)
	(segment
		(start 412.98495 -231.756712)
		(end 412.545022 -231.316784)
		(width 0.20066)
		(layer "F.Cu")
		(net "M_E_CPU0_SB_DQ<2>")
	)
	(segment
		(start 418.397182 -231.316784)
		(end 417.07562 -231.316784)
		(width 0.20066)
		(layer "F.Cu")
		(net "M_E_CPU0_SB_DQ<2>")
	)
	(segment
		(start 416.439604 -231.064816)
		(end 416.205416 -231.299004)
		(width 0.20066)
		(layer "F.Cu")
		(net "M_E_CPU0_SB_DQ<2>")
	)
	(segment
		(start 416.009328 -231.75468)
		(end 415.307526 -231.75468)
		(width 0.20066)
		(layer "F.Cu")
		(net "M_E_CPU0_SB_DQ<2>")
	)
	(segment
		(start 413.307022 -231.741726)
		(end 413.292036 -231.756712)
		(width 0.1016)
		(layer "F.Cu")
		(net "M_E_CPU0_SB_DQ<2>")
	)
	(segment
		(start 416.205416 -231.558592)
		(end 416.009328 -231.75468)
		(width 0.20066)
		(layer "F.Cu")
		(net "M_E_CPU0_SB_DQ<2>")
	)
	(segment
		(start 416.205416 -231.299004)
		(end 416.205416 -231.558592)
		(width 0.20066)
		(layer "F.Cu")
		(net "M_E_CPU0_SB_DQ<2>")
	)
	(segment
		(start 415.294572 -231.741726)
		(end 413.307022 -231.741726)
		(width 0.1016)
		(layer "F.Cu")
		(net "M_E_CPU0_SB_DQ<2>")
	)
	(segment
		(start 413.292036 -231.756712)
		(end 413.275526 -231.756712)
		(width 0.101854)
		(layer "F.Cu")
		(net "M_E_CPU0_SB_DQ<2>")
	)
	(segment
		(start 417.07562 -231.316784)
		(end 416.823652 -231.064816)
		(width 0.20066)
		(layer "F.Cu")
		(net "M_E_CPU0_SB_DQ<2>")
	)
	(segment
		(start 382.605534 -237.133892)
		(end 382.605534 -236.597952)
		(width 0.20066)
		(layer "F.Cu")
		(net "M_E_CPU0_SB_DQ<2>")
	)
	(segment
		(start 415.307526 -231.75468)
		(end 415.294572 -231.741726)
		(width 0.1016)
		(layer "F.Cu")
		(net "M_E_CPU0_SB_DQ<2>")
	)
	(segment
		(start 410.853382 -231.316784)
		(end 409.723082 -231.316784)
		(width 0.20066)
		(layer "F.Cu")
		(net "M_E_CPU0_SB_DQ<2>")
	)
	(segment
		(start 409.723082 -231.316784)
		(end 409.723082 -231.03586)
		(width 0.18288)
		(layer "In2.Cu")
		(net "M_E_CPU0_SB_DQ<2>")
	)
	(segment
		(start 387.620764 -236.97311)
		(end 386.364988 -236.97311)
		(width 0.088646)
		(layer "In2.Cu")
		(net "M_E_CPU0_SB_DQ<2>")
	)
	(segment
		(start 407.558494 -230.890826)
		(end 405.571706 -230.890826)
		(width 0.18288)
		(layer "In2.Cu")
		(net "M_E_CPU0_SB_DQ<2>")
	)
	(segment
		(start 402.498052 -232.991152)
		(end 402.212048 -232.991152)
		(width 0.18288)
		(layer "In2.Cu")
		(net "M_E_CPU0_SB_DQ<2>")
	)
	(segment
		(start 382.418336 -236.922056)
		(end 382.404112 -236.913928)
		(width 0.088646)
		(layer "In2.Cu")
		(net "M_E_CPU0_SB_DQ<2>")
	)
	(segment
		(start 405.571452 -230.890572)
		(end 405.137366 -230.890572)
		(width 0.18288)
		(layer "In2.Cu")
		(net "M_E_CPU0_SB_DQ<2>")
	)
	(segment
		(start 383.357882 -236.922056)
		(end 383.347468 -236.91596)
		(width 0.088646)
		(layer "In2.Cu")
		(net "M_E_CPU0_SB_DQ<2>")
	)
	(segment
		(start 405.137366 -230.890572)
		(end 404.040848 -231.98709)
		(width 0.18288)
		(layer "In2.Cu")
		(net "M_E_CPU0_SB_DQ<2>")
	)
	(segment
		(start 388.043928 -236.708442)
		(end 387.77926 -236.97311)
		(width 0.18288)
		(layer "In2.Cu")
		(net "M_E_CPU0_SB_DQ<2>")
	)
	(segment
		(start 384.297682 -236.922056)
		(end 384.28295 -236.91342)
		(width 0.088646)
		(layer "In2.Cu")
		(net "M_E_CPU0_SB_DQ<2>")
	)
	(segment
		(start 399.693384 -236.036866)
		(end 398.708118 -236.036866)
		(width 0.18288)
		(layer "In2.Cu")
		(net "M_E_CPU0_SB_DQ<2>")
	)
	(segment
		(start 398.708118 -236.036866)
		(end 397.086328 -236.708442)
		(width 0.18288)
		(layer "In2.Cu")
		(net "M_E_CPU0_SB_DQ<2>")
	)
	(segment
		(start 405.571706 -230.890826)
		(end 405.571452 -230.890572)
		(width 0.18288)
		(layer "In2.Cu")
		(net "M_E_CPU0_SB_DQ<2>")
	)
	(segment
		(start 397.086328 -236.708442)
		(end 388.043928 -236.708442)
		(width 0.18288)
		(layer "In2.Cu")
		(net "M_E_CPU0_SB_DQ<2>")
	)
	(segment
		(start 403.4155 -233.330496)
		(end 402.837396 -233.330496)
		(width 0.18288)
		(layer "In2.Cu")
		(net "M_E_CPU0_SB_DQ<2>")
	)
	(segment
		(start 404.040848 -232.705148)
		(end 403.4155 -233.330496)
		(width 0.18288)
		(layer "In2.Cu")
		(net "M_E_CPU0_SB_DQ<2>")
	)
	(segment
		(start 401.959318 -233.243882)
		(end 401.959318 -233.770932)
		(width 0.18288)
		(layer "In2.Cu")
		(net "M_E_CPU0_SB_DQ<2>")
	)
	(segment
		(start 382.235456 -236.655102)
		(end 382.292606 -236.597952)
		(width 0.088646)
		(layer "In2.Cu")
		(net "M_E_CPU0_SB_DQ<2>")
	)
	(segment
		(start 404.040848 -231.98709)
		(end 404.040848 -232.705148)
		(width 0.18288)
		(layer "In2.Cu")
		(net "M_E_CPU0_SB_DQ<2>")
	)
	(segment
		(start 402.837396 -233.330496)
		(end 402.498052 -232.991152)
		(width 0.18288)
		(layer "In2.Cu")
		(net "M_E_CPU0_SB_DQ<2>")
	)
	(segment
		(start 409.530042 -230.84282)
		(end 409.267406 -230.84282)
		(width 0.18288)
		(layer "In2.Cu")
		(net "M_E_CPU0_SB_DQ<2>")
	)
	(segment
		(start 385.237482 -236.922056)
		(end 385.22275 -236.91342)
		(width 0.088646)
		(layer "In2.Cu")
		(net "M_E_CPU0_SB_DQ<2>")
	)
	(segment
		(start 382.292606 -236.597952)
		(end 382.605534 -236.597952)
		(width 0.088646)
		(layer "In2.Cu")
		(net "M_E_CPU0_SB_DQ<2>")
	)
	(segment
		(start 407.95575 -230.49357)
		(end 407.558494 -230.890826)
		(width 0.18288)
		(layer "In2.Cu")
		(net "M_E_CPU0_SB_DQ<2>")
	)
	(segment
		(start 401.959318 -233.770932)
		(end 399.693384 -236.036866)
		(width 0.18288)
		(layer "In2.Cu")
		(net "M_E_CPU0_SB_DQ<2>")
	)
	(segment
		(start 409.267406 -230.84282)
		(end 408.918156 -230.49357)
		(width 0.18288)
		(layer "In2.Cu")
		(net "M_E_CPU0_SB_DQ<2>")
	)
	(segment
		(start 408.918156 -230.49357)
		(end 407.95575 -230.49357)
		(width 0.18288)
		(layer "In2.Cu")
		(net "M_E_CPU0_SB_DQ<2>")
	)
	(segment
		(start 402.212048 -232.991152)
		(end 401.959318 -233.243882)
		(width 0.18288)
		(layer "In2.Cu")
		(net "M_E_CPU0_SB_DQ<2>")
	)
	(segment
		(start 387.77926 -236.97311)
		(end 387.620764 -236.97311)
		(width 0.18288)
		(layer "In2.Cu")
		(net "M_E_CPU0_SB_DQ<2>")
	)
	(segment
		(start 409.723082 -231.03586)
		(end 409.530042 -230.84282)
		(width 0.18288)
		(layer "In2.Cu")
		(net "M_E_CPU0_SB_DQ<2>")
	)
	(arc
		(start 382.792732 -236.922056)
		(mid 382.605534 -236.972233)
		(end 382.418336 -236.922056)
		(width 0.088646)
		(layer "In2.Cu")
		(net "M_E_CPU0_SB_DQ<2>")
	)
	(arc
		(start 385.22275 -236.91342)
		(mid 384.946275 -236.8461)
		(end 384.672078 -236.922056)
		(width 0.088646)
		(layer "In2.Cu")
		(net "M_E_CPU0_SB_DQ<2>")
	)
	(arc
		(start 382.404112 -236.913928)
		(mid 382.291884 -236.8027)
		(end 382.235456 -236.655102)
		(width 0.088646)
		(layer "In2.Cu")
		(net "M_E_CPU0_SB_DQ<2>")
	)
	(arc
		(start 385.611878 -236.922056)
		(mid 385.42468 -236.972233)
		(end 385.237482 -236.922056)
		(width 0.088646)
		(layer "In2.Cu")
		(net "M_E_CPU0_SB_DQ<2>")
	)
	(arc
		(start 383.347468 -236.91596)
		(mid 383.06929 -236.846237)
		(end 382.792732 -236.922056)
		(width 0.088646)
		(layer "In2.Cu")
		(net "M_E_CPU0_SB_DQ<2>")
	)
	(arc
		(start 386.364988 -236.97311)
		(mid 386.259474 -236.957818)
		(end 386.16255 -236.91342)
		(width 0.088646)
		(layer "In2.Cu")
		(net "M_E_CPU0_SB_DQ<2>")
	)
	(arc
		(start 383.732278 -236.922056)
		(mid 383.54508 -236.972233)
		(end 383.357882 -236.922056)
		(width 0.088646)
		(layer "In2.Cu")
		(net "M_E_CPU0_SB_DQ<2>")
	)
	(arc
		(start 384.672078 -236.922056)
		(mid 384.48488 -236.972233)
		(end 384.297682 -236.922056)
		(width 0.088646)
		(layer "In2.Cu")
		(net "M_E_CPU0_SB_DQ<2>")
	)
	(arc
		(start 384.28295 -236.91342)
		(mid 384.006475 -236.8461)
		(end 383.732278 -236.922056)
		(width 0.088646)
		(layer "In2.Cu")
		(net "M_E_CPU0_SB_DQ<2>")
	)
	(arc
		(start 386.16255 -236.91342)
		(mid 385.886075 -236.8461)
		(end 385.611878 -236.922056)
		(width 0.088646)
		(layer "In2.Cu")
		(net "M_E_CPU0_SB_DQ<2>")
	)
	(segment
		(start 386.420614 -207.334358)
		(end 387.76529 -204.088238)
		(width 0.20066)
		(layer "F.Cu")
		(net "M_E_CPU0_SB_DQ<29>")
	)
	(segment
		(start 400.73961 -196.922644)
		(end 400.73961 -197.224904)
		(width 0.20066)
		(layer "F.Cu")
		(net "M_E_CPU0_SB_DQ<29>")
	)
	(segment
		(start 409.831794 -196.031104)
		(end 409.386532 -196.031104)
		(width 0.20066)
		(layer "F.Cu")
		(net "M_E_CPU0_SB_DQ<29>")
	)
	(segment
		(start 399.85315 -197.425564)
		(end 400.05381 -197.224904)
		(width 0.20066)
		(layer "F.Cu")
		(net "M_E_CPU0_SB_DQ<29>")
	)
	(segment
		(start 400.73961 -197.224904)
		(end 400.94027 -197.425564)
		(width 0.20066)
		(layer "F.Cu")
		(net "M_E_CPU0_SB_DQ<29>")
	)
	(segment
		(start 401.62607 -196.74205)
		(end 401.91055 -196.74205)
		(width 0.20066)
		(layer "F.Cu")
		(net "M_E_CPU0_SB_DQ<29>")
	)
	(segment
		(start 387.95198 -214.67318)
		(end 387.656578 -214.377778)
		(width 0.1016)
		(layer "F.Cu")
		(net "M_E_CPU0_SB_DQ<29>")
	)
	(segment
		(start 411.863794 -196.02577)
		(end 411.847792 -196.041772)
		(width 0.1016)
		(layer "F.Cu")
		(net "M_E_CPU0_SB_DQ<29>")
	)
	(segment
		(start 412.28645 -196.02577)
		(end 411.863794 -196.02577)
		(width 0.20066)
		(layer "F.Cu")
		(net "M_E_CPU0_SB_DQ<29>")
	)
	(segment
		(start 386.227574 -208.304638)
		(end 386.420614 -207.334358)
		(width 0.20066)
		(layer "F.Cu")
		(net "M_E_CPU0_SB_DQ<29>")
	)
	(segment
		(start 387.317488 -225.704146)
		(end 387.397244 -225.704146)
		(width 0.088646)
		(layer "F.Cu")
		(net "M_E_CPU0_SB_DQ<29>")
	)
	(segment
		(start 408.806142 -196.690996)
		(end 408.58186 -196.466714)
		(width 0.20066)
		(layer "F.Cu")
		(net "M_E_CPU0_SB_DQ<29>")
	)
	(segment
		(start 386.129784 -226.960176)
		(end 386.284724 -226.804982)
		(width 0.088646)
		(layer "F.Cu")
		(net "M_E_CPU0_SB_DQ<29>")
	)
	(segment
		(start 402.642324 -197.425564)
		(end 402.8567 -197.211188)
		(width 0.20066)
		(layer "F.Cu")
		(net "M_E_CPU0_SB_DQ<29>")
	)
	(segment
		(start 398.48155 -197.425564)
		(end 398.876266 -197.030848)
		(width 0.20066)
		(layer "F.Cu")
		(net "M_E_CPU0_SB_DQ<29>")
	)
	(segment
		(start 396.826486 -197.425564)
		(end 398.48155 -197.425564)
		(width 0.20066)
		(layer "F.Cu")
		(net "M_E_CPU0_SB_DQ<29>")
	)
	(segment
		(start 409.86583 -196.031104)
		(end 409.831794 -196.031104)
		(width 0.101854)
		(layer "F.Cu")
		(net "M_E_CPU0_SB_DQ<29>")
	)
	(segment
		(start 403.052788 -196.69633)
		(end 405.53132 -196.69633)
		(width 0.20066)
		(layer "F.Cu")
		(net "M_E_CPU0_SB_DQ<29>")
	)
	(segment
		(start 398.876266 -197.030848)
		(end 399.160746 -197.030848)
		(width 0.20066)
		(layer "F.Cu")
		(net "M_E_CPU0_SB_DQ<29>")
	)
	(segment
		(start 400.94027 -197.425564)
		(end 401.22475 -197.425564)
		(width 0.20066)
		(layer "F.Cu")
		(net "M_E_CPU0_SB_DQ<29>")
	)
	(segment
		(start 409.876498 -196.041772)
		(end 409.86583 -196.031104)
		(width 0.101854)
		(layer "F.Cu")
		(net "M_E_CPU0_SB_DQ<29>")
	)
	(segment
		(start 387.667754 -225.433636)
		(end 387.95198 -225.14941)
		(width 0.1016)
		(layer "F.Cu")
		(net "M_E_CPU0_SB_DQ<29>")
	)
	(segment
		(start 402.8567 -197.211188)
		(end 402.8567 -196.892418)
		(width 0.20066)
		(layer "F.Cu")
		(net "M_E_CPU0_SB_DQ<29>")
	)
	(segment
		(start 387.95198 -225.14941)
		(end 387.95198 -214.67318)
		(width 0.1016)
		(layer "F.Cu")
		(net "M_E_CPU0_SB_DQ<29>")
	)
	(segment
		(start 386.443728 -226.412044)
		(end 386.569458 -226.286314)
		(width 0.088646)
		(layer "F.Cu")
		(net "M_E_CPU0_SB_DQ<29>")
	)
	(segment
		(start 402.8567 -196.892418)
		(end 403.052788 -196.69633)
		(width 0.20066)
		(layer "F.Cu")
		(net "M_E_CPU0_SB_DQ<29>")
	)
	(segment
		(start 405.760936 -196.466714)
		(end 406.753314 -196.466714)
		(width 0.20066)
		(layer "F.Cu")
		(net "M_E_CPU0_SB_DQ<29>")
	)
	(segment
		(start 399.555462 -197.425564)
		(end 399.85315 -197.425564)
		(width 0.20066)
		(layer "F.Cu")
		(net "M_E_CPU0_SB_DQ<29>")
	)
	(segment
		(start 405.53132 -196.69633)
		(end 405.760936 -196.466714)
		(width 0.20066)
		(layer "F.Cu")
		(net "M_E_CPU0_SB_DQ<29>")
	)
	(segment
		(start 387.397244 -225.704146)
		(end 387.667754 -225.433636)
		(width 0.088646)
		(layer "F.Cu")
		(net "M_E_CPU0_SB_DQ<29>")
	)
	(segment
		(start 387.76529 -204.088238)
		(end 390.537446 -201.316082)
		(width 0.20066)
		(layer "F.Cu")
		(net "M_E_CPU0_SB_DQ<29>")
	)
	(segment
		(start 386.871718 -226.149916)
		(end 387.317488 -225.704146)
		(width 0.088646)
		(layer "F.Cu")
		(net "M_E_CPU0_SB_DQ<29>")
	)
	(segment
		(start 396.55877 -197.506844)
		(end 396.826486 -197.425564)
		(width 0.20066)
		(layer "F.Cu")
		(net "M_E_CPU0_SB_DQ<29>")
	)
	(segment
		(start 400.53895 -196.721984)
		(end 400.73961 -196.922644)
		(width 0.20066)
		(layer "F.Cu")
		(net "M_E_CPU0_SB_DQ<29>")
	)
	(segment
		(start 386.227574 -211.90712)
		(end 386.227574 -208.304638)
		(width 0.20066)
		(layer "F.Cu")
		(net "M_E_CPU0_SB_DQ<29>")
	)
	(segment
		(start 409.386532 -196.031104)
		(end 409.185872 -196.231764)
		(width 0.20066)
		(layer "F.Cu")
		(net "M_E_CPU0_SB_DQ<29>")
	)
	(segment
		(start 387.656578 -214.377778)
		(end 386.96392 -213.68512)
		(width 0.20066)
		(layer "F.Cu")
		(net "M_E_CPU0_SB_DQ<29>")
	)
	(segment
		(start 408.58186 -196.466714)
		(end 406.753314 -196.466714)
		(width 0.20066)
		(layer "F.Cu")
		(net "M_E_CPU0_SB_DQ<29>")
	)
	(segment
		(start 386.96392 -213.68512)
		(end 386.227574 -211.90712)
		(width 0.20066)
		(layer "F.Cu")
		(net "M_E_CPU0_SB_DQ<29>")
	)
	(segment
		(start 409.022296 -196.690996)
		(end 408.806142 -196.690996)
		(width 0.20066)
		(layer "F.Cu")
		(net "M_E_CPU0_SB_DQ<29>")
	)
	(segment
		(start 400.05381 -196.922644)
		(end 400.25447 -196.721984)
		(width 0.20066)
		(layer "F.Cu")
		(net "M_E_CPU0_SB_DQ<29>")
	)
	(segment
		(start 400.25447 -196.721984)
		(end 400.53895 -196.721984)
		(width 0.20066)
		(layer "F.Cu")
		(net "M_E_CPU0_SB_DQ<29>")
	)
	(segment
		(start 402.11121 -196.94271)
		(end 402.11121 -197.224904)
		(width 0.20066)
		(layer "F.Cu")
		(net "M_E_CPU0_SB_DQ<29>")
	)
	(segment
		(start 401.42541 -197.224904)
		(end 401.42541 -196.94271)
		(width 0.20066)
		(layer "F.Cu")
		(net "M_E_CPU0_SB_DQ<29>")
	)
	(segment
		(start 402.11121 -197.224904)
		(end 402.31187 -197.425564)
		(width 0.20066)
		(layer "F.Cu")
		(net "M_E_CPU0_SB_DQ<29>")
	)
	(segment
		(start 401.91055 -196.74205)
		(end 402.11121 -196.94271)
		(width 0.20066)
		(layer "F.Cu")
		(net "M_E_CPU0_SB_DQ<29>")
	)
	(segment
		(start 409.185872 -196.52742)
		(end 409.022296 -196.690996)
		(width 0.20066)
		(layer "F.Cu")
		(net "M_E_CPU0_SB_DQ<29>")
	)
	(segment
		(start 399.160746 -197.030848)
		(end 399.555462 -197.425564)
		(width 0.20066)
		(layer "F.Cu")
		(net "M_E_CPU0_SB_DQ<29>")
	)
	(segment
		(start 412.727394 -196.466714)
		(end 412.28645 -196.02577)
		(width 0.20066)
		(layer "F.Cu")
		(net "M_E_CPU0_SB_DQ<29>")
	)
	(segment
		(start 401.22475 -197.425564)
		(end 401.42541 -197.224904)
		(width 0.20066)
		(layer "F.Cu")
		(net "M_E_CPU0_SB_DQ<29>")
	)
	(segment
		(start 409.185872 -196.231764)
		(end 409.185872 -196.52742)
		(width 0.20066)
		(layer "F.Cu")
		(net "M_E_CPU0_SB_DQ<29>")
	)
	(segment
		(start 395.462252 -198.025766)
		(end 396.55877 -197.506844)
		(width 0.20066)
		(layer "F.Cu")
		(net "M_E_CPU0_SB_DQ<29>")
	)
	(segment
		(start 414.297114 -196.466714)
		(end 412.727394 -196.466714)
		(width 0.20066)
		(layer "F.Cu")
		(net "M_E_CPU0_SB_DQ<29>")
	)
	(segment
		(start 402.31187 -197.425564)
		(end 402.642324 -197.425564)
		(width 0.20066)
		(layer "F.Cu")
		(net "M_E_CPU0_SB_DQ<29>")
	)
	(segment
		(start 384.95478 -226.553268)
		(end 385.659884 -226.960176)
		(width 0.088646)
		(layer "F.Cu")
		(net "M_E_CPU0_SB_DQ<29>")
	)
	(segment
		(start 411.847792 -196.041772)
		(end 409.876498 -196.041772)
		(width 0.1016)
		(layer "F.Cu")
		(net "M_E_CPU0_SB_DQ<29>")
	)
	(segment
		(start 386.349494 -226.649026)
		(end 386.349494 -226.639628)
		(width 0.088646)
		(layer "F.Cu")
		(net "M_E_CPU0_SB_DQ<29>")
	)
	(segment
		(start 390.537446 -201.316082)
		(end 395.462252 -198.025766)
		(width 0.20066)
		(layer "F.Cu")
		(net "M_E_CPU0_SB_DQ<29>")
	)
	(segment
		(start 401.42541 -196.94271)
		(end 401.62607 -196.74205)
		(width 0.20066)
		(layer "F.Cu")
		(net "M_E_CPU0_SB_DQ<29>")
	)
	(segment
		(start 400.05381 -197.224904)
		(end 400.05381 -196.922644)
		(width 0.20066)
		(layer "F.Cu")
		(net "M_E_CPU0_SB_DQ<29>")
	)
	(arc
		(start 386.569458 -226.286314)
		(mid 386.622988 -226.244347)
		(end 386.685028 -226.216464)
		(width 0.088646)
		(layer "F.Cu")
		(net "M_E_CPU0_SB_DQ<29>")
	)
	(arc
		(start 385.659884 -226.960176)
		(mid 385.894834 -227.023136)
		(end 386.129784 -226.960176)
		(width 0.088646)
		(layer "F.Cu")
		(net "M_E_CPU0_SB_DQ<29>")
	)
	(arc
		(start 386.284724 -226.804982)
		(mid 386.332617 -226.733444)
		(end 386.349494 -226.649026)
		(width 0.088646)
		(layer "F.Cu")
		(net "M_E_CPU0_SB_DQ<29>")
	)
	(arc
		(start 386.349494 -226.639628)
		(mid 386.373991 -226.516474)
		(end 386.443728 -226.412044)
		(width 0.088646)
		(layer "F.Cu")
		(net "M_E_CPU0_SB_DQ<29>")
	)
	(arc
		(start 386.685028 -226.216464)
		(mid 386.737861 -226.201296)
		(end 386.7912 -226.188016)
		(width 0.088646)
		(layer "F.Cu")
		(net "M_E_CPU0_SB_DQ<29>")
	)
	(arc
		(start 386.7912 -226.188016)
		(mid 386.833519 -226.173324)
		(end 386.871718 -226.149916)
		(width 0.088646)
		(layer "F.Cu")
		(net "M_E_CPU0_SB_DQ<29>")
	)
	(segment
		(start 395.152118 -200.643236)
		(end 395.20749 -200.365106)
		(width 0.20066)
		(layer "F.Cu")
		(net "M_E_CPU0_SB_DQ<28>")
	)
	(segment
		(start 404.966932 -198.166736)
		(end 406.753314 -198.166736)
		(width 0.20066)
		(layer "F.Cu")
		(net "M_E_CPU0_SB_DQ<28>")
	)
	(segment
		(start 411.847792 -197.741794)
		(end 409.876498 -197.741794)
		(width 0.1016)
		(layer "F.Cu")
		(net "M_E_CPU0_SB_DQ<28>")
	)
	(segment
		(start 385.511294 -227.776786)
		(end 386.218176 -227.776786)
		(width 0.088646)
		(layer "F.Cu")
		(net "M_E_CPU0_SB_DQ<28>")
	)
	(segment
		(start 386.59562 -227.663502)
		(end 386.966206 -227.419154)
		(width 0.088646)
		(layer "F.Cu")
		(net "M_E_CPU0_SB_DQ<28>")
	)
	(segment
		(start 409.076652 -198.391018)
		(end 408.806142 -198.391018)
		(width 0.20066)
		(layer "F.Cu")
		(net "M_E_CPU0_SB_DQ<28>")
	)
	(segment
		(start 388.56158 -213.78291)
		(end 388.267448 -213.072218)
		(width 0.1016)
		(layer "F.Cu")
		(net "M_E_CPU0_SB_DQ<28>")
	)
	(segment
		(start 394.637006 -200.746106)
		(end 394.91539 -200.801478)
		(width 0.20066)
		(layer "F.Cu")
		(net "M_E_CPU0_SB_DQ<28>")
	)
	(segment
		(start 409.478226 -197.731126)
		(end 409.277566 -197.931786)
		(width 0.20066)
		(layer "F.Cu")
		(net "M_E_CPU0_SB_DQ<28>")
	)
	(segment
		(start 409.277566 -197.931786)
		(end 409.277566 -198.190104)
		(width 0.20066)
		(layer "F.Cu")
		(net "M_E_CPU0_SB_DQ<28>")
	)
	(segment
		(start 393.902184 -201.754994)
		(end 394.139166 -201.596752)
		(width 0.20066)
		(layer "F.Cu")
		(net "M_E_CPU0_SB_DQ<28>")
	)
	(segment
		(start 387.091174 -227.431854)
		(end 387.210046 -227.550726)
		(width 0.088646)
		(layer "F.Cu")
		(net "M_E_CPU0_SB_DQ<28>")
	)
	(segment
		(start 403.319742 -198.730616)
		(end 404.074884 -197.975474)
		(width 0.20066)
		(layer "F.Cu")
		(net "M_E_CPU0_SB_DQ<28>")
	)
	(segment
		(start 392.719052 -201.397362)
		(end 393.038584 -201.184002)
		(width 0.20066)
		(layer "F.Cu")
		(net "M_E_CPU0_SB_DQ<28>")
	)
	(segment
		(start 393.942316 -200.580498)
		(end 394.179552 -200.422002)
		(width 0.20066)
		(layer "F.Cu")
		(net "M_E_CPU0_SB_DQ<28>")
	)
	(segment
		(start 409.86583 -197.731126)
		(end 409.831794 -197.731126)
		(width 0.101854)
		(layer "F.Cu")
		(net "M_E_CPU0_SB_DQ<28>")
	)
	(segment
		(start 394.179552 -200.422002)
		(end 394.457428 -200.477374)
		(width 0.20066)
		(layer "F.Cu")
		(net "M_E_CPU0_SB_DQ<28>")
	)
	(segment
		(start 393.038584 -201.184002)
		(end 393.31646 -201.239374)
		(width 0.20066)
		(layer "F.Cu")
		(net "M_E_CPU0_SB_DQ<28>")
	)
	(segment
		(start 409.876498 -197.741794)
		(end 409.86583 -197.731126)
		(width 0.101854)
		(layer "F.Cu")
		(net "M_E_CPU0_SB_DQ<28>")
	)
	(segment
		(start 387.210046 -227.550726)
		(end 387.332474 -227.550726)
		(width 0.088646)
		(layer "F.Cu")
		(net "M_E_CPU0_SB_DQ<28>")
	)
	(segment
		(start 404.77567 -197.975474)
		(end 404.966932 -198.166736)
		(width 0.20066)
		(layer "F.Cu")
		(net "M_E_CPU0_SB_DQ<28>")
	)
	(segment
		(start 387.651244 -207.706468)
		(end 388.833868 -204.851508)
		(width 0.20066)
		(layer "F.Cu")
		(net "M_E_CPU0_SB_DQ<28>")
	)
	(segment
		(start 388.833868 -204.851508)
		(end 391.419842 -202.265534)
		(width 0.20066)
		(layer "F.Cu")
		(net "M_E_CPU0_SB_DQ<28>")
	)
	(segment
		(start 394.91539 -200.801478)
		(end 395.152118 -200.643236)
		(width 0.20066)
		(layer "F.Cu")
		(net "M_E_CPU0_SB_DQ<28>")
	)
	(segment
		(start 394.194538 -201.318622)
		(end 393.886944 -200.858374)
		(width 0.20066)
		(layer "F.Cu")
		(net "M_E_CPU0_SB_DQ<28>")
	)
	(segment
		(start 394.457428 -200.477374)
		(end 394.637006 -200.746106)
		(width 0.20066)
		(layer "F.Cu")
		(net "M_E_CPU0_SB_DQ<28>")
	)
	(segment
		(start 391.419842 -202.265534)
		(end 392.065256 -201.833988)
		(width 0.20066)
		(layer "F.Cu")
		(net "M_E_CPU0_SB_DQ<28>")
	)
	(segment
		(start 409.277566 -198.190104)
		(end 409.076652 -198.391018)
		(width 0.20066)
		(layer "F.Cu")
		(net "M_E_CPU0_SB_DQ<28>")
	)
	(segment
		(start 408.806142 -198.391018)
		(end 408.58186 -198.166736)
		(width 0.20066)
		(layer "F.Cu")
		(net "M_E_CPU0_SB_DQ<28>")
	)
	(segment
		(start 388.253732 -226.629468)
		(end 388.56158 -226.32162)
		(width 0.1016)
		(layer "F.Cu")
		(net "M_E_CPU0_SB_DQ<28>")
	)
	(segment
		(start 411.863794 -197.725792)
		(end 411.847792 -197.741794)
		(width 0.1016)
		(layer "F.Cu")
		(net "M_E_CPU0_SB_DQ<28>")
	)
	(segment
		(start 392.326622 -201.886312)
		(end 392.667236 -201.658728)
		(width 0.20066)
		(layer "F.Cu")
		(net "M_E_CPU0_SB_DQ<28>")
	)
	(segment
		(start 414.297114 -198.166736)
		(end 412.727394 -198.166736)
		(width 0.20066)
		(layer "F.Cu")
		(net "M_E_CPU0_SB_DQ<28>")
	)
	(segment
		(start 387.332474 -227.550726)
		(end 388.253732 -226.629468)
		(width 0.088646)
		(layer "F.Cu")
		(net "M_E_CPU0_SB_DQ<28>")
	)
	(segment
		(start 412.28645 -197.725792)
		(end 411.863794 -197.725792)
		(width 0.20066)
		(layer "F.Cu")
		(net "M_E_CPU0_SB_DQ<28>")
	)
	(segment
		(start 408.58186 -198.166736)
		(end 406.753314 -198.166736)
		(width 0.20066)
		(layer "F.Cu")
		(net "M_E_CPU0_SB_DQ<28>")
	)
	(segment
		(start 386.966206 -227.419154)
		(end 387.091174 -227.431854)
		(width 0.088646)
		(layer "F.Cu")
		(net "M_E_CPU0_SB_DQ<28>")
	)
	(segment
		(start 387.506972 -211.652358)
		(end 387.506972 -208.431638)
		(width 0.20066)
		(layer "F.Cu")
		(net "M_E_CPU0_SB_DQ<28>")
	)
	(segment
		(start 394.139166 -201.596752)
		(end 394.194538 -201.318622)
		(width 0.20066)
		(layer "F.Cu")
		(net "M_E_CPU0_SB_DQ<28>")
	)
	(segment
		(start 409.831794 -197.731126)
		(end 409.478226 -197.731126)
		(width 0.20066)
		(layer "F.Cu")
		(net "M_E_CPU0_SB_DQ<28>")
	)
	(segment
		(start 388.043166 -212.847936)
		(end 387.973316 -212.778086)
		(width 0.20066)
		(layer "F.Cu")
		(net "M_E_CPU0_SB_DQ<28>")
	)
	(segment
		(start 395.027912 -200.096374)
		(end 395.083284 -199.818244)
		(width 0.20066)
		(layer "F.Cu")
		(net "M_E_CPU0_SB_DQ<28>")
	)
	(segment
		(start 393.31646 -201.239374)
		(end 393.624054 -201.699622)
		(width 0.20066)
		(layer "F.Cu")
		(net "M_E_CPU0_SB_DQ<28>")
	)
	(segment
		(start 393.886944 -200.858374)
		(end 393.942316 -200.580498)
		(width 0.20066)
		(layer "F.Cu")
		(net "M_E_CPU0_SB_DQ<28>")
	)
	(segment
		(start 392.667236 -201.658728)
		(end 392.719052 -201.397362)
		(width 0.20066)
		(layer "F.Cu")
		(net "M_E_CPU0_SB_DQ<28>")
	)
	(segment
		(start 404.074884 -197.975474)
		(end 404.77567 -197.975474)
		(width 0.20066)
		(layer "F.Cu")
		(net "M_E_CPU0_SB_DQ<28>")
	)
	(segment
		(start 384.830066 -227.458778)
		(end 385.275836 -227.714048)
		(width 0.088646)
		(layer "F.Cu")
		(net "M_E_CPU0_SB_DQ<28>")
	)
	(segment
		(start 387.506972 -208.431638)
		(end 387.651244 -207.706468)
		(width 0.20066)
		(layer "F.Cu")
		(net "M_E_CPU0_SB_DQ<28>")
	)
	(segment
		(start 387.973316 -212.778086)
		(end 387.506972 -211.652358)
		(width 0.20066)
		(layer "F.Cu")
		(net "M_E_CPU0_SB_DQ<28>")
	)
	(segment
		(start 412.727394 -198.166736)
		(end 412.28645 -197.725792)
		(width 0.20066)
		(layer "F.Cu")
		(net "M_E_CPU0_SB_DQ<28>")
	)
	(segment
		(start 388.267448 -213.072218)
		(end 388.043166 -212.847936)
		(width 0.1016)
		(layer "F.Cu")
		(net "M_E_CPU0_SB_DQ<28>")
	)
	(segment
		(start 388.56158 -226.32162)
		(end 388.56158 -213.78291)
		(width 0.1016)
		(layer "F.Cu")
		(net "M_E_CPU0_SB_DQ<28>")
	)
	(segment
		(start 397.071342 -198.730616)
		(end 403.319742 -198.730616)
		(width 0.20066)
		(layer "F.Cu")
		(net "M_E_CPU0_SB_DQ<28>")
	)
	(segment
		(start 395.083284 -199.818244)
		(end 395.83741 -199.314308)
		(width 0.20066)
		(layer "F.Cu")
		(net "M_E_CPU0_SB_DQ<28>")
	)
	(segment
		(start 393.624054 -201.699622)
		(end 393.902184 -201.754994)
		(width 0.20066)
		(layer "F.Cu")
		(net "M_E_CPU0_SB_DQ<28>")
	)
	(segment
		(start 395.83741 -199.314308)
		(end 397.071342 -198.730616)
		(width 0.20066)
		(layer "F.Cu")
		(net "M_E_CPU0_SB_DQ<28>")
	)
	(segment
		(start 392.065256 -201.833988)
		(end 392.326622 -201.886312)
		(width 0.20066)
		(layer "F.Cu")
		(net "M_E_CPU0_SB_DQ<28>")
	)
	(segment
		(start 395.20749 -200.365106)
		(end 395.027912 -200.096374)
		(width 0.20066)
		(layer "F.Cu")
		(net "M_E_CPU0_SB_DQ<28>")
	)
	(arc
		(start 384.485134 -227.367084)
		(mid 384.663582 -227.390412)
		(end 384.830066 -227.458778)
		(width 0.088646)
		(layer "F.Cu")
		(net "M_E_CPU0_SB_DQ<28>")
	)
	(arc
		(start 385.275836 -227.714048)
		(mid 385.389466 -227.760784)
		(end 385.511294 -227.776786)
		(width 0.088646)
		(layer "F.Cu")
		(net "M_E_CPU0_SB_DQ<28>")
	)
	(arc
		(start 386.218176 -227.776786)
		(mid 386.415236 -227.747907)
		(end 386.59562 -227.663502)
		(width 0.088646)
		(layer "F.Cu")
		(net "M_E_CPU0_SB_DQ<28>")
	)
	(segment
		(start 387.760972 -228.741986)
		(end 388.328154 -228.741986)
		(width 0.088646)
		(layer "F.Cu")
		(net "M_E_CPU0_SB_DQ<27>")
	)
	(segment
		(start 408.373326 -201.93635)
		(end 408.373326 -201.357738)
		(width 0.20066)
		(layer "F.Cu")
		(net "M_E_CPU0_SB_DQ<27>")
	)
	(segment
		(start 409.112212 -201.56678)
		(end 410.853382 -201.56678)
		(width 0.20066)
		(layer "F.Cu")
		(net "M_E_CPU0_SB_DQ<27>")
	)
	(segment
		(start 407.949908 -202.075542)
		(end 408.234134 -202.075542)
		(width 0.20066)
		(layer "F.Cu")
		(net "M_E_CPU0_SB_DQ<27>")
	)
	(segment
		(start 391.001758 -206.760064)
		(end 393.410694 -204.351128)
		(width 0.20066)
		(layer "F.Cu")
		(net "M_E_CPU0_SB_DQ<27>")
	)
	(segment
		(start 386.364734 -228.99497)
		(end 387.010148 -228.99497)
		(width 0.088646)
		(layer "F.Cu")
		(net "M_E_CPU0_SB_DQ<27>")
	)
	(segment
		(start 388.763256 -228.306884)
		(end 390.08558 -226.98456)
		(width 0.1016)
		(layer "F.Cu")
		(net "M_E_CPU0_SB_DQ<27>")
	)
	(segment
		(start 402.088604 -201.564748)
		(end 402.996654 -202.472798)
		(width 0.20066)
		(layer "F.Cu")
		(net "M_E_CPU0_SB_DQ<27>")
	)
	(segment
		(start 407.747724 -201.991722)
		(end 407.763726 -202.007724)
		(width 0.1016)
		(layer "F.Cu")
		(net "M_E_CPU0_SB_DQ<27>")
	)
	(segment
		(start 395.473682 -204.351128)
		(end 398.086072 -201.738738)
		(width 0.20066)
		(layer "F.Cu")
		(net "M_E_CPU0_SB_DQ<27>")
	)
	(segment
		(start 405.024336 -202.255374)
		(end 405.27732 -202.00239)
		(width 0.20066)
		(layer "F.Cu")
		(net "M_E_CPU0_SB_DQ<27>")
	)
	(segment
		(start 404.273766 -201.672444)
		(end 404.273766 -202.178412)
		(width 0.20066)
		(layer "F.Cu")
		(net "M_E_CPU0_SB_DQ<27>")
	)
	(segment
		(start 412.545022 -201.56678)
		(end 410.853382 -201.56678)
		(width 0.20066)
		(layer "F.Cu")
		(net "M_E_CPU0_SB_DQ<27>")
	)
	(segment
		(start 412.980632 -202.00239)
		(end 412.545022 -201.56678)
		(width 0.20066)
		(layer "F.Cu")
		(net "M_E_CPU0_SB_DQ<27>")
	)
	(segment
		(start 387.352794 -228.90607)
		(end 387.441694 -228.99497)
		(width 0.088646)
		(layer "F.Cu")
		(net "M_E_CPU0_SB_DQ<27>")
	)
	(segment
		(start 416.205416 -201.80681)
		(end 416.004502 -202.007724)
		(width 0.20066)
		(layer "F.Cu")
		(net "M_E_CPU0_SB_DQ<27>")
	)
	(segment
		(start 416.004502 -202.007724)
		(end 415.307526 -202.007724)
		(width 0.20066)
		(layer "F.Cu")
		(net "M_E_CPU0_SB_DQ<27>")
	)
	(segment
		(start 413.309562 -202.00239)
		(end 413.275526 -202.00239)
		(width 0.101854)
		(layer "F.Cu")
		(net "M_E_CPU0_SB_DQ<27>")
	)
	(segment
		(start 403.587966 -202.272138)
		(end 403.587966 -201.672444)
		(width 0.20066)
		(layer "F.Cu")
		(net "M_E_CPU0_SB_DQ<27>")
	)
	(segment
		(start 405.77643 -201.991722)
		(end 407.747724 -201.991722)
		(width 0.1016)
		(layer "F.Cu")
		(net "M_E_CPU0_SB_DQ<27>")
	)
	(segment
		(start 413.275526 -202.00239)
		(end 412.980632 -202.00239)
		(width 0.20066)
		(layer "F.Cu")
		(net "M_E_CPU0_SB_DQ<27>")
	)
	(segment
		(start 408.373326 -201.357738)
		(end 408.479752 -201.251312)
		(width 0.20066)
		(layer "F.Cu")
		(net "M_E_CPU0_SB_DQ<27>")
	)
	(segment
		(start 398.086072 -201.738738)
		(end 399.250662 -201.738738)
		(width 0.20066)
		(layer "F.Cu")
		(net "M_E_CPU0_SB_DQ<27>")
	)
	(segment
		(start 390.08558 -210.138772)
		(end 390.387078 -209.837274)
		(width 0.1016)
		(layer "F.Cu")
		(net "M_E_CPU0_SB_DQ<27>")
	)
	(segment
		(start 399.250662 -201.738738)
		(end 399.424652 -201.564748)
		(width 0.20066)
		(layer "F.Cu")
		(net "M_E_CPU0_SB_DQ<27>")
	)
	(segment
		(start 416.205416 -201.549)
		(end 416.205416 -201.80681)
		(width 0.20066)
		(layer "F.Cu")
		(net "M_E_CPU0_SB_DQ<27>")
	)
	(segment
		(start 418.397182 -201.56678)
		(end 417.07562 -201.56678)
		(width 0.20066)
		(layer "F.Cu")
		(net "M_E_CPU0_SB_DQ<27>")
	)
	(segment
		(start 415.307526 -202.007724)
		(end 415.291524 -201.991722)
		(width 0.1016)
		(layer "F.Cu")
		(net "M_E_CPU0_SB_DQ<27>")
	)
	(segment
		(start 388.328154 -228.741986)
		(end 388.763256 -228.306884)
		(width 0.088646)
		(layer "F.Cu")
		(net "M_E_CPU0_SB_DQ<27>")
	)
	(segment
		(start 390.387078 -209.837274)
		(end 390.387078 -209.638392)
		(width 0.1016)
		(layer "F.Cu")
		(net "M_E_CPU0_SB_DQ<27>")
	)
	(segment
		(start 407.763726 -202.007724)
		(end 407.88209 -202.007724)
		(width 0.20066)
		(layer "F.Cu")
		(net "M_E_CPU0_SB_DQ<27>")
	)
	(segment
		(start 416.823652 -201.314812)
		(end 416.439604 -201.314812)
		(width 0.20066)
		(layer "F.Cu")
		(net "M_E_CPU0_SB_DQ<27>")
	)
	(segment
		(start 417.07562 -201.56678)
		(end 416.823652 -201.314812)
		(width 0.20066)
		(layer "F.Cu")
		(net "M_E_CPU0_SB_DQ<27>")
	)
	(segment
		(start 408.796744 -201.251312)
		(end 409.112212 -201.56678)
		(width 0.20066)
		(layer "F.Cu")
		(net "M_E_CPU0_SB_DQ<27>")
	)
	(segment
		(start 387.099048 -228.90607)
		(end 387.352794 -228.90607)
		(width 0.088646)
		(layer "F.Cu")
		(net "M_E_CPU0_SB_DQ<27>")
	)
	(segment
		(start 390.387078 -208.244186)
		(end 391.001758 -206.760064)
		(width 0.20066)
		(layer "F.Cu")
		(net "M_E_CPU0_SB_DQ<27>")
	)
	(segment
		(start 408.234134 -202.075542)
		(end 408.373326 -201.93635)
		(width 0.20066)
		(layer "F.Cu")
		(net "M_E_CPU0_SB_DQ<27>")
	)
	(segment
		(start 387.010148 -228.99497)
		(end 387.099048 -228.90607)
		(width 0.088646)
		(layer "F.Cu")
		(net "M_E_CPU0_SB_DQ<27>")
	)
	(segment
		(start 390.08558 -226.98456)
		(end 390.08558 -210.138772)
		(width 0.1016)
		(layer "F.Cu")
		(net "M_E_CPU0_SB_DQ<27>")
	)
	(segment
		(start 404.474426 -202.379072)
		(end 404.72614 -202.379072)
		(width 0.20066)
		(layer "F.Cu")
		(net "M_E_CPU0_SB_DQ<27>")
	)
	(segment
		(start 404.073106 -201.471784)
		(end 404.273766 -201.672444)
		(width 0.20066)
		(layer "F.Cu")
		(net "M_E_CPU0_SB_DQ<27>")
	)
	(segment
		(start 404.273766 -202.178412)
		(end 404.474426 -202.379072)
		(width 0.20066)
		(layer "F.Cu")
		(net "M_E_CPU0_SB_DQ<27>")
	)
	(segment
		(start 416.439604 -201.314812)
		(end 416.205416 -201.549)
		(width 0.20066)
		(layer "F.Cu")
		(net "M_E_CPU0_SB_DQ<27>")
	)
	(segment
		(start 390.387078 -209.638392)
		(end 390.387078 -208.244186)
		(width 0.20066)
		(layer "F.Cu")
		(net "M_E_CPU0_SB_DQ<27>")
	)
	(segment
		(start 405.765762 -202.00239)
		(end 405.77643 -201.991722)
		(width 0.101854)
		(layer "F.Cu")
		(net "M_E_CPU0_SB_DQ<27>")
	)
	(segment
		(start 404.72614 -202.379072)
		(end 405.024336 -202.255374)
		(width 0.20066)
		(layer "F.Cu")
		(net "M_E_CPU0_SB_DQ<27>")
	)
	(segment
		(start 403.788626 -201.471784)
		(end 404.073106 -201.471784)
		(width 0.20066)
		(layer "F.Cu")
		(net "M_E_CPU0_SB_DQ<27>")
	)
	(segment
		(start 403.587966 -201.672444)
		(end 403.788626 -201.471784)
		(width 0.20066)
		(layer "F.Cu")
		(net "M_E_CPU0_SB_DQ<27>")
	)
	(segment
		(start 402.996654 -202.472798)
		(end 403.387306 -202.472798)
		(width 0.20066)
		(layer "F.Cu")
		(net "M_E_CPU0_SB_DQ<27>")
	)
	(segment
		(start 405.27732 -202.00239)
		(end 405.731726 -202.00239)
		(width 0.20066)
		(layer "F.Cu")
		(net "M_E_CPU0_SB_DQ<27>")
	)
	(segment
		(start 387.663436 -228.839522)
		(end 387.760972 -228.741986)
		(width 0.088646)
		(layer "F.Cu")
		(net "M_E_CPU0_SB_DQ<27>")
	)
	(segment
		(start 413.32023 -201.991722)
		(end 413.309562 -202.00239)
		(width 0.101854)
		(layer "F.Cu")
		(net "M_E_CPU0_SB_DQ<27>")
	)
	(segment
		(start 387.663436 -228.932232)
		(end 387.663436 -228.839522)
		(width 0.088646)
		(layer "F.Cu")
		(net "M_E_CPU0_SB_DQ<27>")
	)
	(segment
		(start 408.479752 -201.251312)
		(end 408.796744 -201.251312)
		(width 0.20066)
		(layer "F.Cu")
		(net "M_E_CPU0_SB_DQ<27>")
	)
	(segment
		(start 415.291524 -201.991722)
		(end 413.32023 -201.991722)
		(width 0.1016)
		(layer "F.Cu")
		(net "M_E_CPU0_SB_DQ<27>")
	)
	(segment
		(start 387.441694 -228.99497)
		(end 387.600698 -228.99497)
		(width 0.088646)
		(layer "F.Cu")
		(net "M_E_CPU0_SB_DQ<27>")
	)
	(segment
		(start 387.600698 -228.99497)
		(end 387.663436 -228.932232)
		(width 0.088646)
		(layer "F.Cu")
		(net "M_E_CPU0_SB_DQ<27>")
	)
	(segment
		(start 399.424652 -201.564748)
		(end 402.088604 -201.564748)
		(width 0.20066)
		(layer "F.Cu")
		(net "M_E_CPU0_SB_DQ<27>")
	)
	(segment
		(start 403.387306 -202.472798)
		(end 403.587966 -202.272138)
		(width 0.20066)
		(layer "F.Cu")
		(net "M_E_CPU0_SB_DQ<27>")
	)
	(segment
		(start 393.410694 -204.351128)
		(end 395.473682 -204.351128)
		(width 0.20066)
		(layer "F.Cu")
		(net "M_E_CPU0_SB_DQ<27>")
	)
	(segment
		(start 407.88209 -202.007724)
		(end 407.949908 -202.075542)
		(width 0.20066)
		(layer "F.Cu")
		(net "M_E_CPU0_SB_DQ<27>")
	)
	(segment
		(start 405.731726 -202.00239)
		(end 405.765762 -202.00239)
		(width 0.101854)
		(layer "F.Cu")
		(net "M_E_CPU0_SB_DQ<27>")
	)
	(segment
		(start 399.01368 -203.819506)
		(end 399.714974 -203.118212)
		(width 0.20066)
		(layer "F.Cu")
		(net "M_E_CPU0_SB_DQ<26>")
	)
	(segment
		(start 408.32151 -203.85659)
		(end 408.443176 -203.734924)
		(width 0.20066)
		(layer "F.Cu")
		(net "M_E_CPU0_SB_DQ<26>")
	)
	(segment
		(start 405.765762 -203.702412)
		(end 405.77643 -203.691744)
		(width 0.101854)
		(layer "F.Cu")
		(net "M_E_CPU0_SB_DQ<26>")
	)
	(segment
		(start 398.282922 -204.550264)
		(end 398.627092 -204.550264)
		(width 0.20066)
		(layer "F.Cu")
		(net "M_E_CPU0_SB_DQ<26>")
	)
	(segment
		(start 395.735048 -206.518256)
		(end 396.31493 -206.518256)
		(width 0.20066)
		(layer "F.Cu")
		(net "M_E_CPU0_SB_DQ<26>")
	)
	(segment
		(start 416.205416 -203.249022)
		(end 416.205416 -203.506832)
		(width 0.20066)
		(layer "F.Cu")
		(net "M_E_CPU0_SB_DQ<26>")
	)
	(segment
		(start 401.38096 -202.950826)
		(end 401.66544 -202.950826)
		(width 0.20066)
		(layer "F.Cu")
		(net "M_E_CPU0_SB_DQ<26>")
	)
	(segment
		(start 398.627092 -204.550264)
		(end 399.01368 -204.163676)
		(width 0.20066)
		(layer "F.Cu")
		(net "M_E_CPU0_SB_DQ<26>")
	)
	(segment
		(start 409.472384 -202.85202)
		(end 409.904184 -202.85202)
		(width 0.20066)
		(layer "F.Cu")
		(net "M_E_CPU0_SB_DQ<26>")
	)
	(segment
		(start 405.731726 -203.702412)
		(end 405.765762 -203.702412)
		(width 0.101854)
		(layer "F.Cu")
		(net "M_E_CPU0_SB_DQ<26>")
	)
	(segment
		(start 394.8684 -205.651608)
		(end 395.735048 -206.518256)
		(width 0.20066)
		(layer "F.Cu")
		(net "M_E_CPU0_SB_DQ<26>")
	)
	(segment
		(start 399.01368 -204.163676)
		(end 399.01368 -203.819506)
		(width 0.20066)
		(layer "F.Cu")
		(net "M_E_CPU0_SB_DQ<26>")
	)
	(segment
		(start 413.275526 -203.702412)
		(end 412.980632 -203.702412)
		(width 0.20066)
		(layer "F.Cu")
		(net "M_E_CPU0_SB_DQ<26>")
	)
	(segment
		(start 415.307526 -203.707746)
		(end 415.291524 -203.691744)
		(width 0.1016)
		(layer "F.Cu")
		(net "M_E_CPU0_SB_DQ<26>")
	)
	(segment
		(start 396.31493 -206.518256)
		(end 398.282922 -204.550264)
		(width 0.20066)
		(layer "F.Cu")
		(net "M_E_CPU0_SB_DQ<26>")
	)
	(segment
		(start 386.650738 -229.482904)
		(end 386.758942 -229.417372)
		(width 0.088646)
		(layer "F.Cu")
		(net "M_E_CPU0_SB_DQ<26>")
	)
	(segment
		(start 401.8661 -203.151486)
		(end 401.8661 -203.551282)
		(width 0.20066)
		(layer "F.Cu")
		(net "M_E_CPU0_SB_DQ<26>")
	)
	(segment
		(start 405.464772 -203.702412)
		(end 405.731726 -203.702412)
		(width 0.20066)
		(layer "F.Cu")
		(net "M_E_CPU0_SB_DQ<26>")
	)
	(segment
		(start 408.551126 -203.266802)
		(end 409.218384 -203.266802)
		(width 0.20066)
		(layer "F.Cu")
		(net "M_E_CPU0_SB_DQ<26>")
	)
	(segment
		(start 410.318966 -203.266802)
		(end 410.853382 -203.266802)
		(width 0.20066)
		(layer "F.Cu")
		(net "M_E_CPU0_SB_DQ<26>")
	)
	(segment
		(start 402.06676 -203.751942)
		(end 405.415242 -203.751942)
		(width 0.20066)
		(layer "F.Cu")
		(net "M_E_CPU0_SB_DQ<26>")
	)
	(segment
		(start 407.88209 -203.707746)
		(end 408.030934 -203.85659)
		(width 0.20066)
		(layer "F.Cu")
		(net "M_E_CPU0_SB_DQ<26>")
	)
	(segment
		(start 415.291524 -203.691744)
		(end 413.32023 -203.691744)
		(width 0.1016)
		(layer "F.Cu")
		(net "M_E_CPU0_SB_DQ<26>")
	)
	(segment
		(start 409.345384 -202.97902)
		(end 409.472384 -202.85202)
		(width 0.20066)
		(layer "F.Cu")
		(net "M_E_CPU0_SB_DQ<26>")
	)
	(segment
		(start 388.515352 -229.417372)
		(end 389.21055 -228.722174)
		(width 0.088646)
		(layer "F.Cu")
		(net "M_E_CPU0_SB_DQ<26>")
	)
	(segment
		(start 391.465308 -210.208114)
		(end 391.914888 -209.758534)
		(width 0.20066)
		(layer "F.Cu")
		(net "M_E_CPU0_SB_DQ<26>")
	)
	(segment
		(start 416.004502 -203.707746)
		(end 415.307526 -203.707746)
		(width 0.20066)
		(layer "F.Cu")
		(net "M_E_CPU0_SB_DQ<26>")
	)
	(segment
		(start 416.439604 -203.014834)
		(end 416.205416 -203.249022)
		(width 0.20066)
		(layer "F.Cu")
		(net "M_E_CPU0_SB_DQ<26>")
	)
	(segment
		(start 409.345384 -203.139802)
		(end 409.345384 -202.97902)
		(width 0.20066)
		(layer "F.Cu")
		(net "M_E_CPU0_SB_DQ<26>")
	)
	(segment
		(start 413.309562 -203.702412)
		(end 413.275526 -203.702412)
		(width 0.101854)
		(layer "F.Cu")
		(net "M_E_CPU0_SB_DQ<26>")
	)
	(segment
		(start 386.758942 -229.417372)
		(end 388.515352 -229.417372)
		(width 0.088646)
		(layer "F.Cu")
		(net "M_E_CPU0_SB_DQ<26>")
	)
	(segment
		(start 389.21055 -228.722174)
		(end 390.69518 -227.237544)
		(width 0.1016)
		(layer "F.Cu")
		(net "M_E_CPU0_SB_DQ<26>")
	)
	(segment
		(start 407.747724 -203.691744)
		(end 407.763726 -203.707746)
		(width 0.1016)
		(layer "F.Cu")
		(net "M_E_CPU0_SB_DQ<26>")
	)
	(segment
		(start 413.32023 -203.691744)
		(end 413.309562 -203.702412)
		(width 0.101854)
		(layer "F.Cu")
		(net "M_E_CPU0_SB_DQ<26>")
	)
	(segment
		(start 390.69518 -227.237544)
		(end 390.69518 -211.440268)
		(width 0.1016)
		(layer "F.Cu")
		(net "M_E_CPU0_SB_DQ<26>")
	)
	(segment
		(start 409.904184 -202.85202)
		(end 410.318966 -203.266802)
		(width 0.20066)
		(layer "F.Cu")
		(net "M_E_CPU0_SB_DQ<26>")
	)
	(segment
		(start 391.726674 -208.440782)
		(end 392.08456 -207.576928)
		(width 0.20066)
		(layer "F.Cu")
		(net "M_E_CPU0_SB_DQ<26>")
	)
	(segment
		(start 405.415242 -203.751942)
		(end 405.464772 -203.702412)
		(width 0.20066)
		(layer "F.Cu")
		(net "M_E_CPU0_SB_DQ<26>")
	)
	(segment
		(start 391.914888 -209.474562)
		(end 391.726674 -209.286348)
		(width 0.20066)
		(layer "F.Cu")
		(net "M_E_CPU0_SB_DQ<26>")
	)
	(segment
		(start 408.443176 -203.734924)
		(end 408.443176 -203.374752)
		(width 0.20066)
		(layer "F.Cu")
		(net "M_E_CPU0_SB_DQ<26>")
	)
	(segment
		(start 408.030934 -203.85659)
		(end 408.32151 -203.85659)
		(width 0.20066)
		(layer "F.Cu")
		(net "M_E_CPU0_SB_DQ<26>")
	)
	(segment
		(start 386.192268 -229.73284)
		(end 386.650738 -229.482904)
		(width 0.088646)
		(layer "F.Cu")
		(net "M_E_CPU0_SB_DQ<26>")
	)
	(segment
		(start 400.69516 -203.75245)
		(end 400.97964 -203.75245)
		(width 0.20066)
		(layer "F.Cu")
		(net "M_E_CPU0_SB_DQ<26>")
	)
	(segment
		(start 392.08456 -207.576928)
		(end 394.00988 -205.651608)
		(width 0.20066)
		(layer "F.Cu")
		(net "M_E_CPU0_SB_DQ<26>")
	)
	(segment
		(start 412.545022 -203.266802)
		(end 410.853382 -203.266802)
		(width 0.20066)
		(layer "F.Cu")
		(net "M_E_CPU0_SB_DQ<26>")
	)
	(segment
		(start 409.218384 -203.266802)
		(end 409.345384 -203.139802)
		(width 0.20066)
		(layer "F.Cu")
		(net "M_E_CPU0_SB_DQ<26>")
	)
	(segment
		(start 407.763726 -203.707746)
		(end 407.88209 -203.707746)
		(width 0.20066)
		(layer "F.Cu")
		(net "M_E_CPU0_SB_DQ<26>")
	)
	(segment
		(start 401.66544 -202.950826)
		(end 401.8661 -203.151486)
		(width 0.20066)
		(layer "F.Cu")
		(net "M_E_CPU0_SB_DQ<26>")
	)
	(segment
		(start 408.443176 -203.374752)
		(end 408.551126 -203.266802)
		(width 0.20066)
		(layer "F.Cu")
		(net "M_E_CPU0_SB_DQ<26>")
	)
	(segment
		(start 416.205416 -203.506832)
		(end 416.004502 -203.707746)
		(width 0.20066)
		(layer "F.Cu")
		(net "M_E_CPU0_SB_DQ<26>")
	)
	(segment
		(start 400.97964 -203.75245)
		(end 401.1803 -203.55179)
		(width 0.20066)
		(layer "F.Cu")
		(net "M_E_CPU0_SB_DQ<26>")
	)
	(segment
		(start 391.02157 -210.651852)
		(end 391.465308 -210.208114)
		(width 0.1016)
		(layer "F.Cu")
		(net "M_E_CPU0_SB_DQ<26>")
	)
	(segment
		(start 412.980632 -203.702412)
		(end 412.545022 -203.266802)
		(width 0.20066)
		(layer "F.Cu")
		(net "M_E_CPU0_SB_DQ<26>")
	)
	(segment
		(start 417.07562 -203.266802)
		(end 416.823652 -203.014834)
		(width 0.20066)
		(layer "F.Cu")
		(net "M_E_CPU0_SB_DQ<26>")
	)
	(segment
		(start 401.1803 -203.151486)
		(end 401.38096 -202.950826)
		(width 0.20066)
		(layer "F.Cu")
		(net "M_E_CPU0_SB_DQ<26>")
	)
	(segment
		(start 400.4945 -203.55179)
		(end 400.69516 -203.75245)
		(width 0.20066)
		(layer "F.Cu")
		(net "M_E_CPU0_SB_DQ<26>")
	)
	(segment
		(start 418.397182 -203.266802)
		(end 417.07562 -203.266802)
		(width 0.20066)
		(layer "F.Cu")
		(net "M_E_CPU0_SB_DQ<26>")
	)
	(segment
		(start 416.823652 -203.014834)
		(end 416.439604 -203.014834)
		(width 0.20066)
		(layer "F.Cu")
		(net "M_E_CPU0_SB_DQ<26>")
	)
	(segment
		(start 400.293332 -203.118212)
		(end 400.4945 -203.31938)
		(width 0.20066)
		(layer "F.Cu")
		(net "M_E_CPU0_SB_DQ<26>")
	)
	(segment
		(start 399.714974 -203.118212)
		(end 400.293332 -203.118212)
		(width 0.20066)
		(layer "F.Cu")
		(net "M_E_CPU0_SB_DQ<26>")
	)
	(segment
		(start 391.914888 -209.758534)
		(end 391.914888 -209.474562)
		(width 0.20066)
		(layer "F.Cu")
		(net "M_E_CPU0_SB_DQ<26>")
	)
	(segment
		(start 401.1803 -203.55179)
		(end 401.1803 -203.151486)
		(width 0.20066)
		(layer "F.Cu")
		(net "M_E_CPU0_SB_DQ<26>")
	)
	(segment
		(start 391.726674 -209.286348)
		(end 391.726674 -208.440782)
		(width 0.20066)
		(layer "F.Cu")
		(net "M_E_CPU0_SB_DQ<26>")
	)
	(segment
		(start 394.00988 -205.651608)
		(end 394.8684 -205.651608)
		(width 0.20066)
		(layer "F.Cu")
		(net "M_E_CPU0_SB_DQ<26>")
	)
	(segment
		(start 405.77643 -203.691744)
		(end 407.747724 -203.691744)
		(width 0.1016)
		(layer "F.Cu")
		(net "M_E_CPU0_SB_DQ<26>")
	)
	(segment
		(start 401.8661 -203.551282)
		(end 402.06676 -203.751942)
		(width 0.20066)
		(layer "F.Cu")
		(net "M_E_CPU0_SB_DQ<26>")
	)
	(segment
		(start 400.4945 -203.31938)
		(end 400.4945 -203.55179)
		(width 0.20066)
		(layer "F.Cu")
		(net "M_E_CPU0_SB_DQ<26>")
	)
	(segment
		(start 390.69518 -211.440268)
		(end 391.02157 -210.651852)
		(width 0.1016)
		(layer "F.Cu")
		(net "M_E_CPU0_SB_DQ<26>")
	)
	(arc
		(start 385.894834 -229.808786)
		(mid 386.048313 -229.789466)
		(end 386.192268 -229.73284)
		(width 0.088646)
		(layer "F.Cu")
		(net "M_E_CPU0_SB_DQ<26>")
	)
	(segment
		(start 398.633188 -202.397106)
		(end 398.923002 -202.68692)
		(width 0.20066)
		(layer "F.Cu")
		(net "M_E_CPU0_SB_DQ<25>")
	)
	(segment
		(start 396.497302 -205.11262)
		(end 396.216124 -204.831442)
		(width 0.20066)
		(layer "F.Cu")
		(net "M_E_CPU0_SB_DQ<25>")
	)
	(segment
		(start 397.200882 -203.591668)
		(end 397.40205 -203.3905)
		(width 0.20066)
		(layer "F.Cu")
		(net "M_E_CPU0_SB_DQ<25>")
	)
	(segment
		(start 401.844764 -202.225656)
		(end 402.731478 -203.11237)
		(width 0.20066)
		(layer "F.Cu")
		(net "M_E_CPU0_SB_DQ<25>")
	)
	(segment
		(start 397.467582 -204.426312)
		(end 397.467582 -204.14234)
		(width 0.20066)
		(layer "F.Cu")
		(net "M_E_CPU0_SB_DQ<25>")
	)
	(segment
		(start 414.297114 -202.416664)
		(end 412.630874 -202.416664)
		(width 0.20066)
		(layer "F.Cu")
		(net "M_E_CPU0_SB_DQ<25>")
	)
	(segment
		(start 396.982442 -204.62748)
		(end 397.266414 -204.62748)
		(width 0.20066)
		(layer "F.Cu")
		(net "M_E_CPU0_SB_DQ<25>")
	)
	(segment
		(start 400.097244 -202.225656)
		(end 400.31162 -202.440032)
		(width 0.20066)
		(layer "F.Cu")
		(net "M_E_CPU0_SB_DQ<25>")
	)
	(segment
		(start 398.437862 -203.456032)
		(end 398.437862 -203.17206)
		(width 0.20066)
		(layer "F.Cu")
		(net "M_E_CPU0_SB_DQ<25>")
	)
	(segment
		(start 396.14983 -205.744064)
		(end 396.497302 -205.396592)
		(width 0.20066)
		(layer "F.Cu")
		(net "M_E_CPU0_SB_DQ<25>")
	)
	(segment
		(start 397.200882 -203.87564)
		(end 397.200882 -203.591668)
		(width 0.20066)
		(layer "F.Cu")
		(net "M_E_CPU0_SB_DQ<25>")
	)
	(segment
		(start 398.923002 -202.68692)
		(end 399.206974 -202.68692)
		(width 0.20066)
		(layer "F.Cu")
		(net "M_E_CPU0_SB_DQ<25>")
	)
	(segment
		(start 395.11224 -204.9907)
		(end 395.865604 -205.744064)
		(width 0.20066)
		(layer "F.Cu")
		(net "M_E_CPU0_SB_DQ<25>")
	)
	(segment
		(start 396.216124 -204.831442)
		(end 396.216124 -204.54747)
		(width 0.20066)
		(layer "F.Cu")
		(net "M_E_CPU0_SB_DQ<25>")
	)
	(segment
		(start 411.863794 -201.97572)
		(end 411.847792 -201.991722)
		(width 0.1016)
		(layer "F.Cu")
		(net "M_E_CPU0_SB_DQ<25>")
	)
	(segment
		(start 388.559548 -228.941884)
		(end 390.39038 -227.111052)
		(width 0.1016)
		(layer "F.Cu")
		(net "M_E_CPU0_SB_DQ<25>")
	)
	(segment
		(start 408.782774 -202.640946)
		(end 407.566622 -202.640946)
		(width 0.20066)
		(layer "F.Cu")
		(net "M_E_CPU0_SB_DQ<25>")
	)
	(segment
		(start 409.86583 -201.981054)
		(end 409.831794 -201.981054)
		(width 0.101854)
		(layer "F.Cu")
		(net "M_E_CPU0_SB_DQ<25>")
	)
	(segment
		(start 391.078466 -209.638392)
		(end 391.078466 -208.29016)
		(width 0.20066)
		(layer "F.Cu")
		(net "M_E_CPU0_SB_DQ<25>")
	)
	(segment
		(start 399.668238 -202.225656)
		(end 400.097244 -202.225656)
		(width 0.20066)
		(layer "F.Cu")
		(net "M_E_CPU0_SB_DQ<25>")
	)
	(segment
		(start 411.847792 -201.991722)
		(end 409.876498 -201.991722)
		(width 0.1016)
		(layer "F.Cu")
		(net "M_E_CPU0_SB_DQ<25>")
	)
	(segment
		(start 384.557778 -229.67569)
		(end 384.845306 -229.388162)
		(width 0.088646)
		(layer "F.Cu")
		(net "M_E_CPU0_SB_DQ<25>")
	)
	(segment
		(start 387.721856 -229.191566)
		(end 387.93674 -229.102666)
		(width 0.088646)
		(layer "F.Cu")
		(net "M_E_CPU0_SB_DQ<25>")
	)
	(segment
		(start 397.266414 -204.62748)
		(end 397.467582 -204.426312)
		(width 0.20066)
		(layer "F.Cu")
		(net "M_E_CPU0_SB_DQ<25>")
	)
	(segment
		(start 385.672838 -229.456996)
		(end 385.775962 -229.397306)
		(width 0.088646)
		(layer "F.Cu")
		(net "M_E_CPU0_SB_DQ<25>")
	)
	(segment
		(start 405.551386 -202.741022)
		(end 405.875744 -202.416664)
		(width 0.20066)
		(layer "F.Cu")
		(net "M_E_CPU0_SB_DQ<25>")
	)
	(segment
		(start 408.943048 -202.480672)
		(end 408.782774 -202.640946)
		(width 0.20066)
		(layer "F.Cu")
		(net "M_E_CPU0_SB_DQ<25>")
	)
	(segment
		(start 396.701264 -204.346302)
		(end 396.982442 -204.62748)
		(width 0.20066)
		(layer "F.Cu")
		(net "M_E_CPU0_SB_DQ<25>")
	)
	(segment
		(start 384.447034 -229.67569)
		(end 384.557778 -229.67569)
		(width 0.088646)
		(layer "F.Cu")
		(net "M_E_CPU0_SB_DQ<25>")
	)
	(segment
		(start 391.078466 -208.29016)
		(end 391.539222 -207.177894)
		(width 0.20066)
		(layer "F.Cu")
		(net "M_E_CPU0_SB_DQ<25>")
	)
	(segment
		(start 409.831794 -201.981054)
		(end 409.093924 -201.981054)
		(width 0.20066)
		(layer "F.Cu")
		(net "M_E_CPU0_SB_DQ<25>")
	)
	(segment
		(start 390.39038 -210.477354)
		(end 391.078466 -209.789268)
		(width 0.1016)
		(layer "F.Cu")
		(net "M_E_CPU0_SB_DQ<25>")
	)
	(segment
		(start 400.31162 -202.440032)
		(end 400.995896 -202.440032)
		(width 0.20066)
		(layer "F.Cu")
		(net "M_E_CPU0_SB_DQ<25>")
	)
	(segment
		(start 384.485134 -228.99497)
		(end 384.485134 -229.308914)
		(width 0.088646)
		(layer "F.Cu")
		(net "M_E_CPU0_SB_DQ<25>")
	)
	(segment
		(start 387.93674 -229.102666)
		(end 388.398766 -229.102666)
		(width 0.088646)
		(layer "F.Cu")
		(net "M_E_CPU0_SB_DQ<25>")
	)
	(segment
		(start 397.952722 -203.6572)
		(end 398.236694 -203.6572)
		(width 0.20066)
		(layer "F.Cu")
		(net "M_E_CPU0_SB_DQ<25>")
	)
	(segment
		(start 397.686022 -203.3905)
		(end 397.952722 -203.6572)
		(width 0.20066)
		(layer "F.Cu")
		(net "M_E_CPU0_SB_DQ<25>")
	)
	(segment
		(start 401.210272 -202.225656)
		(end 401.844764 -202.225656)
		(width 0.20066)
		(layer "F.Cu")
		(net "M_E_CPU0_SB_DQ<25>")
	)
	(segment
		(start 412.18993 -201.97572)
		(end 411.863794 -201.97572)
		(width 0.20066)
		(layer "F.Cu")
		(net "M_E_CPU0_SB_DQ<25>")
	)
	(segment
		(start 384.356102 -229.584758)
		(end 384.447034 -229.67569)
		(width 0.088646)
		(layer "F.Cu")
		(net "M_E_CPU0_SB_DQ<25>")
	)
	(segment
		(start 398.437862 -203.17206)
		(end 398.148048 -202.882246)
		(width 0.20066)
		(layer "F.Cu")
		(net "M_E_CPU0_SB_DQ<25>")
	)
	(segment
		(start 393.726416 -204.9907)
		(end 395.11224 -204.9907)
		(width 0.20066)
		(layer "F.Cu")
		(net "M_E_CPU0_SB_DQ<25>")
	)
	(segment
		(start 398.148048 -202.882246)
		(end 398.148048 -202.598274)
		(width 0.20066)
		(layer "F.Cu")
		(net "M_E_CPU0_SB_DQ<25>")
	)
	(segment
		(start 407.566622 -202.640946)
		(end 407.34234 -202.416664)
		(width 0.20066)
		(layer "F.Cu")
		(net "M_E_CPU0_SB_DQ<25>")
	)
	(segment
		(start 397.40205 -203.3905)
		(end 397.686022 -203.3905)
		(width 0.20066)
		(layer "F.Cu")
		(net "M_E_CPU0_SB_DQ<25>")
	)
	(segment
		(start 396.417292 -204.346302)
		(end 396.701264 -204.346302)
		(width 0.20066)
		(layer "F.Cu")
		(net "M_E_CPU0_SB_DQ<25>")
	)
	(segment
		(start 390.39038 -227.111052)
		(end 390.39038 -210.477354)
		(width 0.1016)
		(layer "F.Cu")
		(net "M_E_CPU0_SB_DQ<25>")
	)
	(segment
		(start 384.356102 -229.437946)
		(end 384.356102 -229.584758)
		(width 0.088646)
		(layer "F.Cu")
		(net "M_E_CPU0_SB_DQ<25>")
	)
	(segment
		(start 395.865604 -205.744064)
		(end 396.14983 -205.744064)
		(width 0.20066)
		(layer "F.Cu")
		(net "M_E_CPU0_SB_DQ<25>")
	)
	(segment
		(start 407.34234 -202.416664)
		(end 406.753314 -202.416664)
		(width 0.20066)
		(layer "F.Cu")
		(net "M_E_CPU0_SB_DQ<25>")
	)
	(segment
		(start 391.539222 -207.177894)
		(end 393.726416 -204.9907)
		(width 0.20066)
		(layer "F.Cu")
		(net "M_E_CPU0_SB_DQ<25>")
	)
	(segment
		(start 409.093924 -201.981054)
		(end 408.943048 -202.13193)
		(width 0.20066)
		(layer "F.Cu")
		(net "M_E_CPU0_SB_DQ<25>")
	)
	(segment
		(start 396.216124 -204.54747)
		(end 396.417292 -204.346302)
		(width 0.20066)
		(layer "F.Cu")
		(net "M_E_CPU0_SB_DQ<25>")
	)
	(segment
		(start 386.574792 -229.30612)
		(end 386.76326 -229.191566)
		(width 0.088646)
		(layer "F.Cu")
		(net "M_E_CPU0_SB_DQ<25>")
	)
	(segment
		(start 412.630874 -202.416664)
		(end 412.18993 -201.97572)
		(width 0.20066)
		(layer "F.Cu")
		(net "M_E_CPU0_SB_DQ<25>")
	)
	(segment
		(start 408.943048 -202.13193)
		(end 408.943048 -202.480672)
		(width 0.20066)
		(layer "F.Cu")
		(net "M_E_CPU0_SB_DQ<25>")
	)
	(segment
		(start 398.349216 -202.397106)
		(end 398.633188 -202.397106)
		(width 0.20066)
		(layer "F.Cu")
		(net "M_E_CPU0_SB_DQ<25>")
	)
	(segment
		(start 385.098036 -229.388162)
		(end 385.211574 -229.454964)
		(width 0.088646)
		(layer "F.Cu")
		(net "M_E_CPU0_SB_DQ<25>")
	)
	(segment
		(start 396.497302 -205.396592)
		(end 396.497302 -205.11262)
		(width 0.20066)
		(layer "F.Cu")
		(net "M_E_CPU0_SB_DQ<25>")
	)
	(segment
		(start 397.467582 -204.14234)
		(end 397.200882 -203.87564)
		(width 0.20066)
		(layer "F.Cu")
		(net "M_E_CPU0_SB_DQ<25>")
	)
	(segment
		(start 386.76326 -229.191566)
		(end 387.721856 -229.191566)
		(width 0.088646)
		(layer "F.Cu")
		(net "M_E_CPU0_SB_DQ<25>")
	)
	(segment
		(start 391.078466 -209.789268)
		(end 391.078466 -209.638392)
		(width 0.1016)
		(layer "F.Cu")
		(net "M_E_CPU0_SB_DQ<25>")
	)
	(segment
		(start 384.485134 -229.308914)
		(end 384.356102 -229.437946)
		(width 0.088646)
		(layer "F.Cu")
		(net "M_E_CPU0_SB_DQ<25>")
	)
	(segment
		(start 385.775962 -229.397306)
		(end 386.24891 -229.397306)
		(width 0.088646)
		(layer "F.Cu")
		(net "M_E_CPU0_SB_DQ<25>")
	)
	(segment
		(start 398.148048 -202.598274)
		(end 398.349216 -202.397106)
		(width 0.20066)
		(layer "F.Cu")
		(net "M_E_CPU0_SB_DQ<25>")
	)
	(segment
		(start 399.206974 -202.68692)
		(end 399.668238 -202.225656)
		(width 0.20066)
		(layer "F.Cu")
		(net "M_E_CPU0_SB_DQ<25>")
	)
	(segment
		(start 409.876498 -201.991722)
		(end 409.86583 -201.981054)
		(width 0.101854)
		(layer "F.Cu")
		(net "M_E_CPU0_SB_DQ<25>")
	)
	(segment
		(start 402.731478 -203.11237)
		(end 404.654766 -203.11237)
		(width 0.20066)
		(layer "F.Cu")
		(net "M_E_CPU0_SB_DQ<25>")
	)
	(segment
		(start 398.236694 -203.6572)
		(end 398.437862 -203.456032)
		(width 0.20066)
		(layer "F.Cu")
		(net "M_E_CPU0_SB_DQ<25>")
	)
	(segment
		(start 404.654766 -203.11237)
		(end 405.515572 -202.755754)
		(width 0.20066)
		(layer "F.Cu")
		(net "M_E_CPU0_SB_DQ<25>")
	)
	(segment
		(start 400.995896 -202.440032)
		(end 401.210272 -202.225656)
		(width 0.20066)
		(layer "F.Cu")
		(net "M_E_CPU0_SB_DQ<25>")
	)
	(segment
		(start 384.845306 -229.388162)
		(end 385.098036 -229.388162)
		(width 0.088646)
		(layer "F.Cu")
		(net "M_E_CPU0_SB_DQ<25>")
	)
	(segment
		(start 405.875744 -202.416664)
		(end 406.753314 -202.416664)
		(width 0.20066)
		(layer "F.Cu")
		(net "M_E_CPU0_SB_DQ<25>")
	)
	(segment
		(start 405.515572 -202.755754)
		(end 405.551386 -202.741022)
		(width 0.20066)
		(layer "F.Cu")
		(net "M_E_CPU0_SB_DQ<25>")
	)
	(segment
		(start 388.398766 -229.102666)
		(end 388.559548 -228.941884)
		(width 0.088646)
		(layer "F.Cu")
		(net "M_E_CPU0_SB_DQ<25>")
	)
	(arc
		(start 385.211574 -229.454964)
		(mid 385.441936 -229.51837)
		(end 385.672838 -229.456996)
		(width 0.088646)
		(layer "F.Cu")
		(net "M_E_CPU0_SB_DQ<25>")
	)
	(arc
		(start 386.24891 -229.397306)
		(mid 386.418104 -229.374071)
		(end 386.574792 -229.30612)
		(width 0.088646)
		(layer "F.Cu")
		(net "M_E_CPU0_SB_DQ<25>")
	)
	(segment
		(start 396.376652 -207.381094)
		(end 398.219168 -205.538578)
		(width 0.20066)
		(layer "F.Cu")
		(net "M_E_CPU0_SB_DQ<24>")
	)
	(segment
		(start 387.917182 -230.446834)
		(end 389.410194 -228.953822)
		(width 0.088646)
		(layer "F.Cu")
		(net "M_E_CPU0_SB_DQ<24>")
	)
	(segment
		(start 386.129022 -230.219504)
		(end 386.13207 -230.217726)
		(width 0.088646)
		(layer "F.Cu")
		(net "M_E_CPU0_SB_DQ<24>")
	)
	(segment
		(start 393.152376 -208.457038)
		(end 393.152376 -208.74101)
		(width 0.20066)
		(layer "F.Cu")
		(net "M_E_CPU0_SB_DQ<24>")
	)
	(segment
		(start 387.801104 -230.49484)
		(end 387.917182 -230.446834)
		(width 0.088646)
		(layer "F.Cu")
		(net "M_E_CPU0_SB_DQ<24>")
	)
	(segment
		(start 409.86583 -203.681076)
		(end 409.831794 -203.681076)
		(width 0.101854)
		(layer "F.Cu")
		(net "M_E_CPU0_SB_DQ<24>")
	)
	(segment
		(start 411.847792 -203.691744)
		(end 409.876498 -203.691744)
		(width 0.1016)
		(layer "F.Cu")
		(net "M_E_CPU0_SB_DQ<24>")
	)
	(segment
		(start 412.630874 -204.116686)
		(end 412.18993 -203.675742)
		(width 0.20066)
		(layer "F.Cu")
		(net "M_E_CPU0_SB_DQ<24>")
	)
	(segment
		(start 389.410194 -228.953822)
		(end 390.99998 -227.364036)
		(width 0.1016)
		(layer "F.Cu")
		(net "M_E_CPU0_SB_DQ<24>")
	)
	(segment
		(start 398.219168 -205.538578)
		(end 399.576544 -204.976984)
		(width 0.20066)
		(layer "F.Cu")
		(net "M_E_CPU0_SB_DQ<24>")
	)
	(segment
		(start 409.831794 -203.681076)
		(end 409.093924 -203.681076)
		(width 0.20066)
		(layer "F.Cu")
		(net "M_E_CPU0_SB_DQ<24>")
	)
	(segment
		(start 412.18993 -203.675742)
		(end 411.863794 -203.675742)
		(width 0.20066)
		(layer "F.Cu")
		(net "M_E_CPU0_SB_DQ<24>")
	)
	(segment
		(start 407.566622 -204.340968)
		(end 407.34234 -204.116686)
		(width 0.20066)
		(layer "F.Cu")
		(net "M_E_CPU0_SB_DQ<24>")
	)
	(segment
		(start 409.093924 -203.681076)
		(end 408.943048 -203.831952)
		(width 0.20066)
		(layer "F.Cu")
		(net "M_E_CPU0_SB_DQ<24>")
	)
	(segment
		(start 395.1986 -207.381094)
		(end 396.376652 -207.381094)
		(width 0.20066)
		(layer "F.Cu")
		(net "M_E_CPU0_SB_DQ<24>")
	)
	(segment
		(start 393.353544 -208.942178)
		(end 393.637516 -208.942178)
		(width 0.20066)
		(layer "F.Cu")
		(net "M_E_CPU0_SB_DQ<24>")
	)
	(segment
		(start 391.25144 -211.469478)
		(end 392.861038 -209.860642)
		(width 0.20066)
		(layer "F.Cu")
		(net "M_E_CPU0_SB_DQ<24>")
	)
	(segment
		(start 393.637516 -208.942178)
		(end 395.1986 -207.381094)
		(width 0.20066)
		(layer "F.Cu")
		(net "M_E_CPU0_SB_DQ<24>")
	)
	(segment
		(start 407.34234 -204.116686)
		(end 406.753314 -204.116686)
		(width 0.20066)
		(layer "F.Cu")
		(net "M_E_CPU0_SB_DQ<24>")
	)
	(segment
		(start 408.943048 -204.123798)
		(end 408.725878 -204.340968)
		(width 0.20066)
		(layer "F.Cu")
		(net "M_E_CPU0_SB_DQ<24>")
	)
	(segment
		(start 394.617702 -206.305404)
		(end 394.81887 -206.506572)
		(width 0.20066)
		(layer "F.Cu")
		(net "M_E_CPU0_SB_DQ<24>")
	)
	(segment
		(start 399.685002 -204.71511)
		(end 399.58137 -204.464666)
		(width 0.20066)
		(layer "F.Cu")
		(net "M_E_CPU0_SB_DQ<24>")
	)
	(segment
		(start 386.567172 -230.17099)
		(end 386.891022 -230.49484)
		(width 0.088646)
		(layer "F.Cu")
		(net "M_E_CPU0_SB_DQ<24>")
	)
	(segment
		(start 391.112248 -213.030308)
		(end 391.112248 -211.60867)
		(width 0.101854)
		(layer "F.Cu")
		(net "M_E_CPU0_SB_DQ<24>")
	)
	(segment
		(start 394.81887 -206.506572)
		(end 394.81887 -206.790544)
		(width 0.20066)
		(layer "F.Cu")
		(net "M_E_CPU0_SB_DQ<24>")
	)
	(segment
		(start 409.876498 -203.691744)
		(end 409.86583 -203.681076)
		(width 0.101854)
		(layer "F.Cu")
		(net "M_E_CPU0_SB_DQ<24>")
	)
	(segment
		(start 399.689828 -204.202538)
		(end 399.953226 -204.093318)
		(width 0.20066)
		(layer "F.Cu")
		(net "M_E_CPU0_SB_DQ<24>")
	)
	(segment
		(start 400.318732 -204.452474)
		(end 400.580606 -204.560932)
		(width 0.20066)
		(layer "F.Cu")
		(net "M_E_CPU0_SB_DQ<24>")
	)
	(segment
		(start 386.891022 -230.49484)
		(end 387.801104 -230.49484)
		(width 0.088646)
		(layer "F.Cu")
		(net "M_E_CPU0_SB_DQ<24>")
	)
	(segment
		(start 414.297114 -204.116686)
		(end 412.630874 -204.116686)
		(width 0.20066)
		(layer "F.Cu")
		(net "M_E_CPU0_SB_DQ<24>")
	)
	(segment
		(start 408.725878 -204.340968)
		(end 407.566622 -204.340968)
		(width 0.20066)
		(layer "F.Cu")
		(net "M_E_CPU0_SB_DQ<24>")
	)
	(segment
		(start 385.537202 -230.166418)
		(end 385.573778 -230.178356)
		(width 0.088646)
		(layer "F.Cu")
		(net "M_E_CPU0_SB_DQ<24>")
	)
	(segment
		(start 405.50846 -204.404976)
		(end 405.79675 -204.116686)
		(width 0.20066)
		(layer "F.Cu")
		(net "M_E_CPU0_SB_DQ<24>")
	)
	(segment
		(start 399.953226 -204.093318)
		(end 400.214846 -204.201776)
		(width 0.20066)
		(layer "F.Cu")
		(net "M_E_CPU0_SB_DQ<24>")
	)
	(segment
		(start 392.861038 -209.860642)
		(end 392.861038 -209.435192)
		(width 0.20066)
		(layer "F.Cu")
		(net "M_E_CPU0_SB_DQ<24>")
	)
	(segment
		(start 392.861038 -209.435192)
		(end 392.404854 -208.979008)
		(width 0.20066)
		(layer "F.Cu")
		(net "M_E_CPU0_SB_DQ<24>")
	)
	(segment
		(start 390.99998 -227.364036)
		(end 390.99998 -213.142576)
		(width 0.1016)
		(layer "F.Cu")
		(net "M_E_CPU0_SB_DQ<24>")
	)
	(segment
		(start 399.576544 -204.976984)
		(end 399.685002 -204.71511)
		(width 0.20066)
		(layer "F.Cu")
		(net "M_E_CPU0_SB_DQ<24>")
	)
	(segment
		(start 393.152376 -208.74101)
		(end 393.353544 -208.942178)
		(width 0.20066)
		(layer "F.Cu")
		(net "M_E_CPU0_SB_DQ<24>")
	)
	(segment
		(start 400.214846 -204.201776)
		(end 400.318732 -204.452474)
		(width 0.20066)
		(layer "F.Cu")
		(net "M_E_CPU0_SB_DQ<24>")
	)
	(segment
		(start 392.404854 -208.47558)
		(end 392.575542 -208.063592)
		(width 0.20066)
		(layer "F.Cu")
		(net "M_E_CPU0_SB_DQ<24>")
	)
	(segment
		(start 392.404854 -208.979008)
		(end 392.404854 -208.47558)
		(width 0.20066)
		(layer "F.Cu")
		(net "M_E_CPU0_SB_DQ<24>")
	)
	(segment
		(start 394.81887 -206.790544)
		(end 393.152376 -208.457038)
		(width 0.20066)
		(layer "F.Cu")
		(net "M_E_CPU0_SB_DQ<24>")
	)
	(segment
		(start 408.943048 -203.831952)
		(end 408.943048 -204.123798)
		(width 0.20066)
		(layer "F.Cu")
		(net "M_E_CPU0_SB_DQ<24>")
	)
	(segment
		(start 392.575542 -208.063592)
		(end 394.33373 -206.305404)
		(width 0.20066)
		(layer "F.Cu")
		(net "M_E_CPU0_SB_DQ<24>")
	)
	(segment
		(start 405.79675 -204.116686)
		(end 406.753314 -204.116686)
		(width 0.20066)
		(layer "F.Cu")
		(net "M_E_CPU0_SB_DQ<24>")
	)
	(segment
		(start 394.33373 -206.305404)
		(end 394.617702 -206.305404)
		(width 0.20066)
		(layer "F.Cu")
		(net "M_E_CPU0_SB_DQ<24>")
	)
	(segment
		(start 390.99998 -213.142576)
		(end 391.112248 -213.030308)
		(width 0.101854)
		(layer "F.Cu")
		(net "M_E_CPU0_SB_DQ<24>")
	)
	(segment
		(start 400.580606 -204.560932)
		(end 400.957034 -204.404976)
		(width 0.20066)
		(layer "F.Cu")
		(net "M_E_CPU0_SB_DQ<24>")
	)
	(segment
		(start 399.58137 -204.464666)
		(end 399.689828 -204.202538)
		(width 0.20066)
		(layer "F.Cu")
		(net "M_E_CPU0_SB_DQ<24>")
	)
	(segment
		(start 411.863794 -203.675742)
		(end 411.847792 -203.691744)
		(width 0.1016)
		(layer "F.Cu")
		(net "M_E_CPU0_SB_DQ<24>")
	)
	(segment
		(start 391.112248 -211.60867)
		(end 391.25144 -211.469478)
		(width 0.1016)
		(layer "F.Cu")
		(net "M_E_CPU0_SB_DQ<24>")
	)
	(segment
		(start 400.957034 -204.404976)
		(end 405.50846 -204.404976)
		(width 0.20066)
		(layer "F.Cu")
		(net "M_E_CPU0_SB_DQ<24>")
	)
	(arc
		(start 384.95478 -229.808786)
		(mid 385.22491 -230.02193)
		(end 385.537202 -230.166418)
		(width 0.088646)
		(layer "F.Cu")
		(net "M_E_CPU0_SB_DQ<24>")
	)
	(arc
		(start 385.66217 -230.217726)
		(mid 385.895356 -230.280682)
		(end 386.129022 -230.219504)
		(width 0.088646)
		(layer "F.Cu")
		(net "M_E_CPU0_SB_DQ<24>")
	)
	(arc
		(start 386.13207 -230.217726)
		(mid 386.268657 -230.165206)
		(end 386.414772 -230.157274)
		(width 0.088646)
		(layer "F.Cu")
		(net "M_E_CPU0_SB_DQ<24>")
	)
	(arc
		(start 385.573778 -230.178356)
		(mid 385.618989 -230.195762)
		(end 385.66217 -230.217726)
		(width 0.088646)
		(layer "F.Cu")
		(net "M_E_CPU0_SB_DQ<24>")
	)
	(arc
		(start 386.414772 -230.157274)
		(mid 386.490933 -230.164566)
		(end 386.567172 -230.17099)
		(width 0.088646)
		(layer "F.Cu")
		(net "M_E_CPU0_SB_DQ<24>")
	)
	(segment
		(start 415.291524 -205.391512)
		(end 413.32023 -205.391512)
		(width 0.1016)
		(layer "F.Cu")
		(net "M_E_CPU0_SB_DQ<23>")
	)
	(segment
		(start 391.875518 -213.173818)
		(end 391.875518 -212.10016)
		(width 0.20066)
		(layer "F.Cu")
		(net "M_E_CPU0_SB_DQ<23>")
	)
	(segment
		(start 408.390852 -205.407514)
		(end 408.831796 -204.96657)
		(width 0.20066)
		(layer "F.Cu")
		(net "M_E_CPU0_SB_DQ<23>")
	)
	(segment
		(start 391.55878 -213.490556)
		(end 391.6934 -213.355936)
		(width 0.1016)
		(layer "F.Cu")
		(net "M_E_CPU0_SB_DQ<23>")
	)
	(segment
		(start 395.708124 -208.267554)
		(end 396.758668 -208.267554)
		(width 0.20066)
		(layer "F.Cu")
		(net "M_E_CPU0_SB_DQ<23>")
	)
	(segment
		(start 413.32023 -205.391512)
		(end 413.309562 -205.40218)
		(width 0.101854)
		(layer "F.Cu")
		(net "M_E_CPU0_SB_DQ<23>")
	)
	(segment
		(start 405.765762 -205.40218)
		(end 405.77643 -205.391512)
		(width 0.101854)
		(layer "F.Cu")
		(net "M_E_CPU0_SB_DQ<23>")
	)
	(segment
		(start 412.57855 -204.96657)
		(end 410.853382 -204.96657)
		(width 0.20066)
		(layer "F.Cu")
		(net "M_E_CPU0_SB_DQ<23>")
	)
	(segment
		(start 396.758668 -208.267554)
		(end 398.70253 -206.323692)
		(width 0.20066)
		(layer "F.Cu")
		(net "M_E_CPU0_SB_DQ<23>")
	)
	(segment
		(start 388.531862 -230.641398)
		(end 391.55878 -227.61448)
		(width 0.1016)
		(layer "F.Cu")
		(net "M_E_CPU0_SB_DQ<23>")
	)
	(segment
		(start 401.195032 -205.291436)
		(end 404.887938 -205.291436)
		(width 0.20066)
		(layer "F.Cu")
		(net "M_E_CPU0_SB_DQ<23>")
	)
	(segment
		(start 391.6934 -213.355936)
		(end 391.875518 -213.173818)
		(width 0.20066)
		(layer "F.Cu")
		(net "M_E_CPU0_SB_DQ<23>")
	)
	(segment
		(start 408.831796 -204.96657)
		(end 410.853382 -204.96657)
		(width 0.20066)
		(layer "F.Cu")
		(net "M_E_CPU0_SB_DQ<23>")
	)
	(segment
		(start 398.70253 -206.323692)
		(end 401.195032 -205.291436)
		(width 0.20066)
		(layer "F.Cu")
		(net "M_E_CPU0_SB_DQ<23>")
	)
	(segment
		(start 413.275526 -205.40218)
		(end 413.01416 -205.40218)
		(width 0.20066)
		(layer "F.Cu")
		(net "M_E_CPU0_SB_DQ<23>")
	)
	(segment
		(start 407.747724 -205.391512)
		(end 407.763726 -205.407514)
		(width 0.1016)
		(layer "F.Cu")
		(net "M_E_CPU0_SB_DQ<23>")
	)
	(segment
		(start 404.998682 -205.40218)
		(end 405.731726 -205.40218)
		(width 0.20066)
		(layer "F.Cu")
		(net "M_E_CPU0_SB_DQ<23>")
	)
	(segment
		(start 391.875518 -212.10016)
		(end 395.708124 -208.267554)
		(width 0.20066)
		(layer "F.Cu")
		(net "M_E_CPU0_SB_DQ<23>")
	)
	(segment
		(start 417.07562 -204.96657)
		(end 416.823652 -204.714602)
		(width 0.20066)
		(layer "F.Cu")
		(net "M_E_CPU0_SB_DQ<23>")
	)
	(segment
		(start 388.142734 -231.030526)
		(end 388.531862 -230.641398)
		(width 0.088646)
		(layer "F.Cu")
		(net "M_E_CPU0_SB_DQ<23>")
	)
	(segment
		(start 413.309562 -205.40218)
		(end 413.275526 -205.40218)
		(width 0.101854)
		(layer "F.Cu")
		(net "M_E_CPU0_SB_DQ<23>")
	)
	(segment
		(start 405.731726 -205.40218)
		(end 405.765762 -205.40218)
		(width 0.101854)
		(layer "F.Cu")
		(net "M_E_CPU0_SB_DQ<23>")
	)
	(segment
		(start 404.887938 -205.291436)
		(end 404.998682 -205.40218)
		(width 0.20066)
		(layer "F.Cu")
		(net "M_E_CPU0_SB_DQ<23>")
	)
	(segment
		(start 385.894834 -231.436418)
		(end 386.874766 -231.030526)
		(width 0.088646)
		(layer "F.Cu")
		(net "M_E_CPU0_SB_DQ<23>")
	)
	(segment
		(start 416.823652 -204.714602)
		(end 416.439604 -204.714602)
		(width 0.20066)
		(layer "F.Cu")
		(net "M_E_CPU0_SB_DQ<23>")
	)
	(segment
		(start 405.77643 -205.391512)
		(end 407.747724 -205.391512)
		(width 0.1016)
		(layer "F.Cu")
		(net "M_E_CPU0_SB_DQ<23>")
	)
	(segment
		(start 415.307526 -205.407514)
		(end 415.291524 -205.391512)
		(width 0.1016)
		(layer "F.Cu")
		(net "M_E_CPU0_SB_DQ<23>")
	)
	(segment
		(start 416.004756 -205.407514)
		(end 415.307526 -205.407514)
		(width 0.20066)
		(layer "F.Cu")
		(net "M_E_CPU0_SB_DQ<23>")
	)
	(segment
		(start 386.874766 -231.030526)
		(end 388.142734 -231.030526)
		(width 0.088646)
		(layer "F.Cu")
		(net "M_E_CPU0_SB_DQ<23>")
	)
	(segment
		(start 391.55878 -227.61448)
		(end 391.55878 -213.490556)
		(width 0.1016)
		(layer "F.Cu")
		(net "M_E_CPU0_SB_DQ<23>")
	)
	(segment
		(start 418.397182 -204.96657)
		(end 417.07562 -204.96657)
		(width 0.20066)
		(layer "F.Cu")
		(net "M_E_CPU0_SB_DQ<23>")
	)
	(segment
		(start 416.439604 -204.714602)
		(end 416.205416 -204.94879)
		(width 0.20066)
		(layer "F.Cu")
		(net "M_E_CPU0_SB_DQ<23>")
	)
	(segment
		(start 413.01416 -205.40218)
		(end 412.57855 -204.96657)
		(width 0.20066)
		(layer "F.Cu")
		(net "M_E_CPU0_SB_DQ<23>")
	)
	(segment
		(start 407.763726 -205.407514)
		(end 408.390852 -205.407514)
		(width 0.20066)
		(layer "F.Cu")
		(net "M_E_CPU0_SB_DQ<23>")
	)
	(segment
		(start 416.205416 -204.94879)
		(end 416.205416 -205.206854)
		(width 0.20066)
		(layer "F.Cu")
		(net "M_E_CPU0_SB_DQ<23>")
	)
	(segment
		(start 416.205416 -205.206854)
		(end 416.004756 -205.407514)
		(width 0.20066)
		(layer "F.Cu")
		(net "M_E_CPU0_SB_DQ<23>")
	)
	(segment
		(start 413.275526 -207.102202)
		(end 413.008572 -207.102202)
		(width 0.20066)
		(layer "F.Cu")
		(net "M_E_CPU0_SB_DQ<22>")
	)
	(segment
		(start 386.364734 -232.250488)
		(end 386.388864 -232.274618)
		(width 0.088646)
		(layer "F.Cu")
		(net "M_E_CPU0_SB_DQ<22>")
	)
	(segment
		(start 395.991842 -210.950556)
		(end 399.563082 -207.379316)
		(width 0.20066)
		(layer "F.Cu")
		(net "M_E_CPU0_SB_DQ<22>")
	)
	(segment
		(start 412.572962 -206.666592)
		(end 410.853382 -206.666592)
		(width 0.20066)
		(layer "F.Cu")
		(net "M_E_CPU0_SB_DQ<22>")
	)
	(segment
		(start 405.765762 -207.102202)
		(end 405.77643 -207.091534)
		(width 0.101854)
		(layer "F.Cu")
		(net "M_E_CPU0_SB_DQ<22>")
	)
	(segment
		(start 404.925276 -206.770732)
		(end 405.256746 -207.102202)
		(width 0.20066)
		(layer "F.Cu")
		(net "M_E_CPU0_SB_DQ<22>")
	)
	(segment
		(start 407.763726 -207.107536)
		(end 408.70378 -207.107536)
		(width 0.20066)
		(layer "F.Cu")
		(net "M_E_CPU0_SB_DQ<22>")
	)
	(segment
		(start 392.420856 -214.493094)
		(end 393.191492 -213.722458)
		(width 0.20066)
		(layer "F.Cu")
		(net "M_E_CPU0_SB_DQ<22>")
	)
	(segment
		(start 393.191492 -213.722458)
		(end 393.191492 -212.64753)
		(width 0.20066)
		(layer "F.Cu")
		(net "M_E_CPU0_SB_DQ<22>")
	)
	(segment
		(start 415.291524 -207.091534)
		(end 413.32023 -207.091534)
		(width 0.1016)
		(layer "F.Cu")
		(net "M_E_CPU0_SB_DQ<22>")
	)
	(segment
		(start 415.307526 -207.107536)
		(end 415.291524 -207.091534)
		(width 0.1016)
		(layer "F.Cu")
		(net "M_E_CPU0_SB_DQ<22>")
	)
	(segment
		(start 405.77643 -207.091534)
		(end 407.747724 -207.091534)
		(width 0.1016)
		(layer "F.Cu")
		(net "M_E_CPU0_SB_DQ<22>")
	)
	(segment
		(start 392.16838 -214.74557)
		(end 392.420856 -214.493094)
		(width 0.1016)
		(layer "F.Cu")
		(net "M_E_CPU0_SB_DQ<22>")
	)
	(segment
		(start 386.411216 -232.283762)
		(end 387.752082 -232.283762)
		(width 0.088646)
		(layer "F.Cu")
		(net "M_E_CPU0_SB_DQ<22>")
	)
	(segment
		(start 387.752082 -232.283762)
		(end 388.963154 -231.07269)
		(width 0.088646)
		(layer "F.Cu")
		(net "M_E_CPU0_SB_DQ<22>")
	)
	(segment
		(start 407.747724 -207.091534)
		(end 407.763726 -207.107536)
		(width 0.1016)
		(layer "F.Cu")
		(net "M_E_CPU0_SB_DQ<22>")
	)
	(segment
		(start 405.256746 -207.102202)
		(end 405.731726 -207.102202)
		(width 0.20066)
		(layer "F.Cu")
		(net "M_E_CPU0_SB_DQ<22>")
	)
	(segment
		(start 408.70378 -207.107536)
		(end 409.144724 -206.666592)
		(width 0.20066)
		(layer "F.Cu")
		(net "M_E_CPU0_SB_DQ<22>")
	)
	(segment
		(start 399.563082 -207.379316)
		(end 401.032472 -206.770732)
		(width 0.20066)
		(layer "F.Cu")
		(net "M_E_CPU0_SB_DQ<22>")
	)
	(segment
		(start 416.004756 -207.107536)
		(end 415.307526 -207.107536)
		(width 0.20066)
		(layer "F.Cu")
		(net "M_E_CPU0_SB_DQ<22>")
	)
	(segment
		(start 413.309562 -207.102202)
		(end 413.275526 -207.102202)
		(width 0.101854)
		(layer "F.Cu")
		(net "M_E_CPU0_SB_DQ<22>")
	)
	(segment
		(start 401.032472 -206.770732)
		(end 404.925276 -206.770732)
		(width 0.20066)
		(layer "F.Cu")
		(net "M_E_CPU0_SB_DQ<22>")
	)
	(segment
		(start 416.205416 -206.906876)
		(end 416.004756 -207.107536)
		(width 0.20066)
		(layer "F.Cu")
		(net "M_E_CPU0_SB_DQ<22>")
	)
	(segment
		(start 392.16838 -227.867464)
		(end 392.16838 -214.74557)
		(width 0.1016)
		(layer "F.Cu")
		(net "M_E_CPU0_SB_DQ<22>")
	)
	(segment
		(start 413.008572 -207.102202)
		(end 412.572962 -206.666592)
		(width 0.20066)
		(layer "F.Cu")
		(net "M_E_CPU0_SB_DQ<22>")
	)
	(segment
		(start 416.439604 -206.414624)
		(end 416.205416 -206.648812)
		(width 0.20066)
		(layer "F.Cu")
		(net "M_E_CPU0_SB_DQ<22>")
	)
	(segment
		(start 417.07562 -206.666592)
		(end 416.823652 -206.414624)
		(width 0.20066)
		(layer "F.Cu")
		(net "M_E_CPU0_SB_DQ<22>")
	)
	(segment
		(start 393.191492 -212.64753)
		(end 394.888466 -210.950556)
		(width 0.20066)
		(layer "F.Cu")
		(net "M_E_CPU0_SB_DQ<22>")
	)
	(segment
		(start 405.731726 -207.102202)
		(end 405.765762 -207.102202)
		(width 0.101854)
		(layer "F.Cu")
		(net "M_E_CPU0_SB_DQ<22>")
	)
	(segment
		(start 418.397182 -206.666592)
		(end 417.07562 -206.666592)
		(width 0.20066)
		(layer "F.Cu")
		(net "M_E_CPU0_SB_DQ<22>")
	)
	(segment
		(start 416.205416 -206.648812)
		(end 416.205416 -206.906876)
		(width 0.20066)
		(layer "F.Cu")
		(net "M_E_CPU0_SB_DQ<22>")
	)
	(segment
		(start 413.32023 -207.091534)
		(end 413.309562 -207.102202)
		(width 0.101854)
		(layer "F.Cu")
		(net "M_E_CPU0_SB_DQ<22>")
	)
	(segment
		(start 416.823652 -206.414624)
		(end 416.439604 -206.414624)
		(width 0.20066)
		(layer "F.Cu")
		(net "M_E_CPU0_SB_DQ<22>")
	)
	(segment
		(start 394.888466 -210.950556)
		(end 395.991842 -210.950556)
		(width 0.20066)
		(layer "F.Cu")
		(net "M_E_CPU0_SB_DQ<22>")
	)
	(segment
		(start 409.144724 -206.666592)
		(end 410.853382 -206.666592)
		(width 0.20066)
		(layer "F.Cu")
		(net "M_E_CPU0_SB_DQ<22>")
	)
	(segment
		(start 388.963154 -231.07269)
		(end 392.16838 -227.867464)
		(width 0.1016)
		(layer "F.Cu")
		(net "M_E_CPU0_SB_DQ<22>")
	)
	(arc
		(start 386.388864 -232.274618)
		(mid 386.399119 -232.28147)
		(end 386.411216 -232.283762)
		(width 0.088646)
		(layer "F.Cu")
		(net "M_E_CPU0_SB_DQ<22>")
	)
	(segment
		(start 395.72946 -210.252818)
		(end 396.04188 -209.940398)
		(width 0.20066)
		(layer "F.Cu")
		(net "M_E_CPU0_SB_DQ<21>")
	)
	(segment
		(start 409.045664 -205.56728)
		(end 409.045664 -205.877414)
		(width 0.20066)
		(layer "F.Cu")
		(net "M_E_CPU0_SB_DQ<21>")
	)
	(segment
		(start 404.613364 -206.004922)
		(end 405.650954 -206.004922)
		(width 0.20066)
		(layer "F.Cu")
		(net "M_E_CPU0_SB_DQ<21>")
	)
	(segment
		(start 396.262098 -208.907126)
		(end 396.52702 -209.171794)
		(width 0.20066)
		(layer "F.Cu")
		(net "M_E_CPU0_SB_DQ<21>")
	)
	(segment
		(start 385.69265 -231.932226)
		(end 386.095494 -231.932226)
		(width 0.088646)
		(layer "F.Cu")
		(net "M_E_CPU0_SB_DQ<21>")
	)
	(segment
		(start 394.878052 -210.024726)
		(end 395.162024 -210.024726)
		(width 0.20066)
		(layer "F.Cu")
		(net "M_E_CPU0_SB_DQ<21>")
	)
	(segment
		(start 396.04188 -209.940398)
		(end 396.04188 -209.656934)
		(width 0.20066)
		(layer "F.Cu")
		(net "M_E_CPU0_SB_DQ<21>")
	)
	(segment
		(start 408.665934 -206.04099)
		(end 408.441652 -205.816708)
		(width 0.20066)
		(layer "F.Cu")
		(net "M_E_CPU0_SB_DQ<21>")
	)
	(segment
		(start 409.876498 -205.391512)
		(end 409.86583 -205.380844)
		(width 0.101854)
		(layer "F.Cu")
		(net "M_E_CPU0_SB_DQ<21>")
	)
	(segment
		(start 414.297114 -205.816708)
		(end 412.851346 -205.816708)
		(width 0.20066)
		(layer "F.Cu")
		(net "M_E_CPU0_SB_DQ<21>")
	)
	(segment
		(start 404.53945 -205.931008)
		(end 404.613364 -206.004922)
		(width 0.20066)
		(layer "F.Cu")
		(net "M_E_CPU0_SB_DQ<21>")
	)
	(segment
		(start 387.514846 -232.089706)
		(end 388.747508 -230.857044)
		(width 0.088646)
		(layer "F.Cu")
		(net "M_E_CPU0_SB_DQ<21>")
	)
	(segment
		(start 395.776958 -209.392266)
		(end 395.776958 -209.108802)
		(width 0.20066)
		(layer "F.Cu")
		(net "M_E_CPU0_SB_DQ<21>")
	)
	(segment
		(start 395.162024 -210.024726)
		(end 395.390116 -210.252818)
		(width 0.20066)
		(layer "F.Cu")
		(net "M_E_CPU0_SB_DQ<21>")
	)
	(segment
		(start 405.839168 -205.816708)
		(end 406.753314 -205.816708)
		(width 0.20066)
		(layer "F.Cu")
		(net "M_E_CPU0_SB_DQ<21>")
	)
	(segment
		(start 409.86583 -205.380844)
		(end 409.831794 -205.380844)
		(width 0.101854)
		(layer "F.Cu")
		(net "M_E_CPU0_SB_DQ<21>")
	)
	(segment
		(start 412.851346 -205.816708)
		(end 412.851092 -205.816962)
		(width 0.20066)
		(layer "F.Cu")
		(net "M_E_CPU0_SB_DQ<21>")
	)
	(segment
		(start 401.345146 -205.931008)
		(end 404.53945 -205.931008)
		(width 0.20066)
		(layer "F.Cu")
		(net "M_E_CPU0_SB_DQ<21>")
	)
	(segment
		(start 386.095494 -231.932226)
		(end 386.207762 -231.818942)
		(width 0.088646)
		(layer "F.Cu")
		(net "M_E_CPU0_SB_DQ<21>")
	)
	(segment
		(start 409.2321 -205.380844)
		(end 409.045664 -205.56728)
		(width 0.20066)
		(layer "F.Cu")
		(net "M_E_CPU0_SB_DQ<21>")
	)
	(segment
		(start 395.390116 -210.252818)
		(end 395.72946 -210.252818)
		(width 0.20066)
		(layer "F.Cu")
		(net "M_E_CPU0_SB_DQ<21>")
	)
	(segment
		(start 409.045664 -205.877414)
		(end 408.882088 -206.04099)
		(width 0.20066)
		(layer "F.Cu")
		(net "M_E_CPU0_SB_DQ<21>")
	)
	(segment
		(start 396.810484 -209.171794)
		(end 399.136616 -206.845662)
		(width 0.20066)
		(layer "F.Cu")
		(net "M_E_CPU0_SB_DQ<21>")
	)
	(segment
		(start 386.81152 -231.818942)
		(end 387.082284 -232.089706)
		(width 0.088646)
		(layer "F.Cu")
		(net "M_E_CPU0_SB_DQ<21>")
	)
	(segment
		(start 392.164316 -213.826852)
		(end 392.53795 -213.453218)
		(width 0.20066)
		(layer "F.Cu")
		(net "M_E_CPU0_SB_DQ<21>")
	)
	(segment
		(start 391.86358 -227.740972)
		(end 391.86358 -214.127588)
		(width 0.1016)
		(layer "F.Cu")
		(net "M_E_CPU0_SB_DQ<21>")
	)
	(segment
		(start 384.95478 -231.436418)
		(end 385.329684 -231.436418)
		(width 0.088646)
		(layer "F.Cu")
		(net "M_E_CPU0_SB_DQ<21>")
	)
	(segment
		(start 395.776958 -209.108802)
		(end 395.978634 -208.907126)
		(width 0.20066)
		(layer "F.Cu")
		(net "M_E_CPU0_SB_DQ<21>")
	)
	(segment
		(start 395.978634 -208.907126)
		(end 396.262098 -208.907126)
		(width 0.20066)
		(layer "F.Cu")
		(net "M_E_CPU0_SB_DQ<21>")
	)
	(segment
		(start 391.86358 -214.127588)
		(end 392.164316 -213.826852)
		(width 0.1016)
		(layer "F.Cu")
		(net "M_E_CPU0_SB_DQ<21>")
	)
	(segment
		(start 411.847792 -205.391512)
		(end 409.876498 -205.391512)
		(width 0.1016)
		(layer "F.Cu")
		(net "M_E_CPU0_SB_DQ<21>")
	)
	(segment
		(start 392.53795 -213.453218)
		(end 392.53795 -212.364828)
		(width 0.20066)
		(layer "F.Cu")
		(net "M_E_CPU0_SB_DQ<21>")
	)
	(segment
		(start 399.136616 -206.845662)
		(end 401.345146 -205.931008)
		(width 0.20066)
		(layer "F.Cu")
		(net "M_E_CPU0_SB_DQ<21>")
	)
	(segment
		(start 385.431538 -231.671114)
		(end 385.69265 -231.932226)
		(width 0.088646)
		(layer "F.Cu")
		(net "M_E_CPU0_SB_DQ<21>")
	)
	(segment
		(start 392.53795 -212.364828)
		(end 394.878052 -210.024726)
		(width 0.20066)
		(layer "F.Cu")
		(net "M_E_CPU0_SB_DQ<21>")
	)
	(segment
		(start 385.329684 -231.436418)
		(end 385.431538 -231.538272)
		(width 0.088646)
		(layer "F.Cu")
		(net "M_E_CPU0_SB_DQ<21>")
	)
	(segment
		(start 412.40964 -205.37551)
		(end 411.863794 -205.37551)
		(width 0.20066)
		(layer "F.Cu")
		(net "M_E_CPU0_SB_DQ<21>")
	)
	(segment
		(start 386.207762 -231.818942)
		(end 386.81152 -231.818942)
		(width 0.088646)
		(layer "F.Cu")
		(net "M_E_CPU0_SB_DQ<21>")
	)
	(segment
		(start 408.441652 -205.816708)
		(end 406.753314 -205.816708)
		(width 0.20066)
		(layer "F.Cu")
		(net "M_E_CPU0_SB_DQ<21>")
	)
	(segment
		(start 411.863794 -205.37551)
		(end 411.847792 -205.391512)
		(width 0.1016)
		(layer "F.Cu")
		(net "M_E_CPU0_SB_DQ<21>")
	)
	(segment
		(start 396.52702 -209.171794)
		(end 396.810484 -209.171794)
		(width 0.20066)
		(layer "F.Cu")
		(net "M_E_CPU0_SB_DQ<21>")
	)
	(segment
		(start 387.082284 -232.089706)
		(end 387.514846 -232.089706)
		(width 0.088646)
		(layer "F.Cu")
		(net "M_E_CPU0_SB_DQ<21>")
	)
	(segment
		(start 405.650954 -206.004922)
		(end 405.839168 -205.816708)
		(width 0.20066)
		(layer "F.Cu")
		(net "M_E_CPU0_SB_DQ<21>")
	)
	(segment
		(start 409.831794 -205.380844)
		(end 409.2321 -205.380844)
		(width 0.20066)
		(layer "F.Cu")
		(net "M_E_CPU0_SB_DQ<21>")
	)
	(segment
		(start 412.851092 -205.816962)
		(end 412.40964 -205.37551)
		(width 0.20066)
		(layer "F.Cu")
		(net "M_E_CPU0_SB_DQ<21>")
	)
	(segment
		(start 388.747508 -230.857044)
		(end 391.86358 -227.740972)
		(width 0.1016)
		(layer "F.Cu")
		(net "M_E_CPU0_SB_DQ<21>")
	)
	(segment
		(start 396.04188 -209.656934)
		(end 395.776958 -209.392266)
		(width 0.20066)
		(layer "F.Cu")
		(net "M_E_CPU0_SB_DQ<21>")
	)
	(segment
		(start 408.882088 -206.04099)
		(end 408.665934 -206.04099)
		(width 0.20066)
		(layer "F.Cu")
		(net "M_E_CPU0_SB_DQ<21>")
	)
	(segment
		(start 385.431538 -231.538272)
		(end 385.431538 -231.671114)
		(width 0.088646)
		(layer "F.Cu")
		(net "M_E_CPU0_SB_DQ<21>")
	)
	(segment
		(start 408.806142 -207.741012)
		(end 408.58186 -207.51673)
		(width 0.20066)
		(layer "F.Cu")
		(net "M_E_CPU0_SB_DQ<20>")
	)
	(segment
		(start 409.876498 -207.091534)
		(end 409.86583 -207.080866)
		(width 0.101854)
		(layer "F.Cu")
		(net "M_E_CPU0_SB_DQ<20>")
	)
	(segment
		(start 387.96341 -232.503726)
		(end 386.68198 -232.503726)
		(width 0.088646)
		(layer "F.Cu")
		(net "M_E_CPU0_SB_DQ<20>")
	)
	(segment
		(start 409.185872 -207.577436)
		(end 409.022296 -207.741012)
		(width 0.20066)
		(layer "F.Cu")
		(net "M_E_CPU0_SB_DQ<20>")
	)
	(segment
		(start 409.185872 -207.267302)
		(end 409.185872 -207.577436)
		(width 0.20066)
		(layer "F.Cu")
		(net "M_E_CPU0_SB_DQ<20>")
	)
	(segment
		(start 395.224508 -212.631274)
		(end 395.02334 -212.832442)
		(width 0.20066)
		(layer "F.Cu")
		(net "M_E_CPU0_SB_DQ<20>")
	)
	(segment
		(start 393.988798 -212.76818)
		(end 393.988798 -213.052152)
		(width 0.20066)
		(layer "F.Cu")
		(net "M_E_CPU0_SB_DQ<20>")
	)
	(segment
		(start 405.003 -207.51673)
		(end 404.905972 -207.419702)
		(width 0.20066)
		(layer "F.Cu")
		(net "M_E_CPU0_SB_DQ<20>")
	)
	(segment
		(start 394.959078 -211.7979)
		(end 394.959078 -212.081872)
		(width 0.20066)
		(layer "F.Cu")
		(net "M_E_CPU0_SB_DQ<20>")
	)
	(segment
		(start 394.254228 -213.601554)
		(end 392.80465 -215.051132)
		(width 0.20066)
		(layer "F.Cu")
		(net "M_E_CPU0_SB_DQ<20>")
	)
	(segment
		(start 388.179564 -232.287572)
		(end 387.96341 -232.503726)
		(width 0.088646)
		(layer "F.Cu")
		(net "M_E_CPU0_SB_DQ<20>")
	)
	(segment
		(start 384.139186 -232.299002)
		(end 384.1877 -232.250488)
		(width 0.088646)
		(layer "F.Cu")
		(net "M_E_CPU0_SB_DQ<20>")
	)
	(segment
		(start 392.80465 -215.051132)
		(end 392.47318 -215.382602)
		(width 0.1016)
		(layer "F.Cu")
		(net "M_E_CPU0_SB_DQ<20>")
	)
	(segment
		(start 412.397448 -207.075532)
		(end 411.863794 -207.075532)
		(width 0.20066)
		(layer "F.Cu")
		(net "M_E_CPU0_SB_DQ<20>")
	)
	(segment
		(start 392.47318 -227.993956)
		(end 388.179564 -232.287572)
		(width 0.1016)
		(layer "F.Cu")
		(net "M_E_CPU0_SB_DQ<20>")
	)
	(segment
		(start 395.160246 -211.596732)
		(end 394.959078 -211.7979)
		(width 0.20066)
		(layer "F.Cu")
		(net "M_E_CPU0_SB_DQ<20>")
	)
	(segment
		(start 386.371592 -232.656126)
		(end 385.402328 -232.656126)
		(width 0.088646)
		(layer "F.Cu")
		(net "M_E_CPU0_SB_DQ<20>")
	)
	(segment
		(start 384.670046 -232.570528)
		(end 384.587496 -232.619042)
		(width 0.088646)
		(layer "F.Cu")
		(net "M_E_CPU0_SB_DQ<20>")
	)
	(segment
		(start 384.22961 -232.619042)
		(end 384.139186 -232.528618)
		(width 0.088646)
		(layer "F.Cu")
		(net "M_E_CPU0_SB_DQ<20>")
	)
	(segment
		(start 404.905972 -207.419702)
		(end 401.246594 -207.419702)
		(width 0.20066)
		(layer "F.Cu")
		(net "M_E_CPU0_SB_DQ<20>")
	)
	(segment
		(start 394.739368 -212.832442)
		(end 394.473938 -212.567012)
		(width 0.20066)
		(layer "F.Cu")
		(net "M_E_CPU0_SB_DQ<20>")
	)
	(segment
		(start 394.473938 -212.567012)
		(end 394.189966 -212.567012)
		(width 0.20066)
		(layer "F.Cu")
		(net "M_E_CPU0_SB_DQ<20>")
	)
	(segment
		(start 386.547868 -232.58018)
		(end 386.371592 -232.656126)
		(width 0.088646)
		(layer "F.Cu")
		(net "M_E_CPU0_SB_DQ<20>")
	)
	(segment
		(start 393.988798 -213.052152)
		(end 394.254228 -213.317582)
		(width 0.20066)
		(layer "F.Cu")
		(net "M_E_CPU0_SB_DQ<20>")
	)
	(segment
		(start 384.587496 -232.619042)
		(end 384.22961 -232.619042)
		(width 0.088646)
		(layer "F.Cu")
		(net "M_E_CPU0_SB_DQ<20>")
	)
	(segment
		(start 394.189966 -212.567012)
		(end 393.988798 -212.76818)
		(width 0.20066)
		(layer "F.Cu")
		(net "M_E_CPU0_SB_DQ<20>")
	)
	(segment
		(start 394.959078 -212.081872)
		(end 395.224508 -212.347302)
		(width 0.20066)
		(layer "F.Cu")
		(net "M_E_CPU0_SB_DQ<20>")
	)
	(segment
		(start 409.86583 -207.080866)
		(end 409.831794 -207.080866)
		(width 0.101854)
		(layer "F.Cu")
		(net "M_E_CPU0_SB_DQ<20>")
	)
	(segment
		(start 395.444218 -211.596732)
		(end 395.160246 -211.596732)
		(width 0.20066)
		(layer "F.Cu")
		(net "M_E_CPU0_SB_DQ<20>")
	)
	(segment
		(start 395.02334 -212.832442)
		(end 394.739368 -212.832442)
		(width 0.20066)
		(layer "F.Cu")
		(net "M_E_CPU0_SB_DQ<20>")
	)
	(segment
		(start 411.863794 -207.075532)
		(end 411.847792 -207.091534)
		(width 0.1016)
		(layer "F.Cu")
		(net "M_E_CPU0_SB_DQ<20>")
	)
	(segment
		(start 401.246594 -207.419702)
		(end 399.863056 -207.992726)
		(width 0.20066)
		(layer "F.Cu")
		(net "M_E_CPU0_SB_DQ<20>")
	)
	(segment
		(start 395.99362 -211.862162)
		(end 395.709648 -211.862162)
		(width 0.20066)
		(layer "F.Cu")
		(net "M_E_CPU0_SB_DQ<20>")
	)
	(segment
		(start 386.68198 -232.503726)
		(end 386.554218 -232.57764)
		(width 0.088646)
		(layer "F.Cu")
		(net "M_E_CPU0_SB_DQ<20>")
	)
	(segment
		(start 411.847792 -207.091534)
		(end 409.876498 -207.091534)
		(width 0.1016)
		(layer "F.Cu")
		(net "M_E_CPU0_SB_DQ<20>")
	)
	(segment
		(start 384.139186 -232.528618)
		(end 384.139186 -232.299002)
		(width 0.088646)
		(layer "F.Cu")
		(net "M_E_CPU0_SB_DQ<20>")
	)
	(segment
		(start 409.372308 -207.080866)
		(end 409.185872 -207.267302)
		(width 0.20066)
		(layer "F.Cu")
		(net "M_E_CPU0_SB_DQ<20>")
	)
	(segment
		(start 384.1877 -232.250488)
		(end 384.485134 -232.250488)
		(width 0.088646)
		(layer "F.Cu")
		(net "M_E_CPU0_SB_DQ<20>")
	)
	(segment
		(start 392.47318 -215.382602)
		(end 392.47318 -227.993956)
		(width 0.1016)
		(layer "F.Cu")
		(net "M_E_CPU0_SB_DQ<20>")
	)
	(segment
		(start 399.863056 -207.992726)
		(end 395.99362 -211.862162)
		(width 0.20066)
		(layer "F.Cu")
		(net "M_E_CPU0_SB_DQ<20>")
	)
	(segment
		(start 395.224508 -212.347302)
		(end 395.224508 -212.631274)
		(width 0.20066)
		(layer "F.Cu")
		(net "M_E_CPU0_SB_DQ<20>")
	)
	(segment
		(start 384.814318 -232.492296)
		(end 384.670046 -232.570528)
		(width 0.088646)
		(layer "F.Cu")
		(net "M_E_CPU0_SB_DQ<20>")
	)
	(segment
		(start 409.831794 -207.080866)
		(end 409.372308 -207.080866)
		(width 0.20066)
		(layer "F.Cu")
		(net "M_E_CPU0_SB_DQ<20>")
	)
	(segment
		(start 414.297114 -207.51673)
		(end 412.838646 -207.51673)
		(width 0.20066)
		(layer "F.Cu")
		(net "M_E_CPU0_SB_DQ<20>")
	)
	(segment
		(start 385.402328 -232.656126)
		(end 385.126484 -232.496614)
		(width 0.088646)
		(layer "F.Cu")
		(net "M_E_CPU0_SB_DQ<20>")
	)
	(segment
		(start 394.254228 -213.317582)
		(end 394.254228 -213.601554)
		(width 0.20066)
		(layer "F.Cu")
		(net "M_E_CPU0_SB_DQ<20>")
	)
	(segment
		(start 406.753314 -207.51673)
		(end 405.003 -207.51673)
		(width 0.20066)
		(layer "F.Cu")
		(net "M_E_CPU0_SB_DQ<20>")
	)
	(segment
		(start 412.838646 -207.51673)
		(end 412.397448 -207.075532)
		(width 0.20066)
		(layer "F.Cu")
		(net "M_E_CPU0_SB_DQ<20>")
	)
	(segment
		(start 408.58186 -207.51673)
		(end 406.753314 -207.51673)
		(width 0.20066)
		(layer "F.Cu")
		(net "M_E_CPU0_SB_DQ<20>")
	)
	(segment
		(start 395.709648 -211.862162)
		(end 395.444218 -211.596732)
		(width 0.20066)
		(layer "F.Cu")
		(net "M_E_CPU0_SB_DQ<20>")
	)
	(segment
		(start 409.022296 -207.741012)
		(end 408.806142 -207.741012)
		(width 0.20066)
		(layer "F.Cu")
		(net "M_E_CPU0_SB_DQ<20>")
	)
	(segment
		(start 386.554218 -232.57764)
		(end 386.547868 -232.58018)
		(width 0.088646)
		(layer "F.Cu")
		(net "M_E_CPU0_SB_DQ<20>")
	)
	(arc
		(start 385.126484 -232.496614)
		(mid 384.970955 -232.453591)
		(end 384.814318 -232.492296)
		(width 0.088646)
		(layer "F.Cu")
		(net "M_E_CPU0_SB_DQ<20>")
	)
	(segment
		(start 408.997912 -230.715312)
		(end 409.185872 -230.527352)
		(width 0.20066)
		(layer "F.Cu")
		(net "M_E_CPU0_SB_DQ<1>")
	)
	(segment
		(start 406.753314 -230.466646)
		(end 408.274012 -230.466646)
		(width 0.20066)
		(layer "F.Cu")
		(net "M_E_CPU0_SB_DQ<1>")
	)
	(segment
		(start 409.185872 -230.159814)
		(end 409.303982 -230.041704)
		(width 0.20066)
		(layer "F.Cu")
		(net "M_E_CPU0_SB_DQ<1>")
	)
	(segment
		(start 411.863794 -230.035354)
		(end 412.27375 -230.035354)
		(width 0.20066)
		(layer "F.Cu")
		(net "M_E_CPU0_SB_DQ<1>")
	)
	(segment
		(start 411.857444 -230.041704)
		(end 411.863794 -230.035354)
		(width 0.1016)
		(layer "F.Cu")
		(net "M_E_CPU0_SB_DQ<1>")
	)
	(segment
		(start 409.64866 -230.041704)
		(end 409.668726 -230.041704)
		(width 0.101854)
		(layer "F.Cu")
		(net "M_E_CPU0_SB_DQ<1>")
	)
	(segment
		(start 408.274012 -230.466646)
		(end 408.522678 -230.715312)
		(width 0.20066)
		(layer "F.Cu")
		(net "M_E_CPU0_SB_DQ<1>")
	)
	(segment
		(start 405.623014 -230.466646)
		(end 406.753314 -230.466646)
		(width 0.20066)
		(layer "F.Cu")
		(net "M_E_CPU0_SB_DQ<1>")
	)
	(segment
		(start 412.27375 -230.035354)
		(end 412.705296 -230.4669)
		(width 0.20066)
		(layer "F.Cu")
		(net "M_E_CPU0_SB_DQ<1>")
	)
	(segment
		(start 409.185872 -230.527352)
		(end 409.185872 -230.159814)
		(width 0.20066)
		(layer "F.Cu")
		(net "M_E_CPU0_SB_DQ<1>")
	)
	(segment
		(start 412.705296 -230.4669)
		(end 414.29686 -230.4669)
		(width 0.20066)
		(layer "F.Cu")
		(net "M_E_CPU0_SB_DQ<1>")
	)
	(segment
		(start 408.522678 -230.715312)
		(end 408.997912 -230.715312)
		(width 0.20066)
		(layer "F.Cu")
		(net "M_E_CPU0_SB_DQ<1>")
	)
	(segment
		(start 414.29686 -230.4669)
		(end 414.297114 -230.466646)
		(width 0.20066)
		(layer "F.Cu")
		(net "M_E_CPU0_SB_DQ<1>")
	)
	(segment
		(start 409.303982 -230.041704)
		(end 409.64866 -230.041704)
		(width 0.20066)
		(layer "F.Cu")
		(net "M_E_CPU0_SB_DQ<1>")
	)
	(segment
		(start 381.19558 -236.319822)
		(end 381.195834 -236.319568)
		(width 0.20066)
		(layer "F.Cu")
		(net "M_E_CPU0_SB_DQ<1>")
	)
	(segment
		(start 409.668726 -230.041704)
		(end 411.857444 -230.041704)
		(width 0.1016)
		(layer "F.Cu")
		(net "M_E_CPU0_SB_DQ<1>")
	)
	(segment
		(start 381.195834 -236.319568)
		(end 381.195834 -235.783882)
		(width 0.20066)
		(layer "F.Cu")
		(net "M_E_CPU0_SB_DQ<1>")
	)
	(segment
		(start 403.362668 -231.048814)
		(end 403.049994 -231.361488)
		(width 0.18288)
		(layer "In2.Cu")
		(net "M_E_CPU0_SB_DQ<1>")
	)
	(segment
		(start 403.504908 -232.189782)
		(end 403.504908 -232.462324)
		(width 0.18288)
		(layer "In2.Cu")
		(net "M_E_CPU0_SB_DQ<1>")
	)
	(segment
		(start 403.049994 -231.734868)
		(end 403.504908 -232.189782)
		(width 0.18288)
		(layer "In2.Cu")
		(net "M_E_CPU0_SB_DQ<1>")
	)
	(segment
		(start 381.196088 -235.784136)
		(end 381.195834 -235.783882)
		(width 0.088646)
		(layer "In2.Cu")
		(net "M_E_CPU0_SB_DQ<1>")
	)
	(segment
		(start 405.303228 -230.14686)
		(end 405.303228 -229.946454)
		(width 0.18288)
		(layer "In2.Cu")
		(net "M_E_CPU0_SB_DQ<1>")
	)
	(segment
		(start 399.438622 -235.325158)
		(end 399.245582 -235.518198)
		(width 0.18288)
		(layer "In2.Cu")
		(net "M_E_CPU0_SB_DQ<1>")
	)
	(segment
		(start 404.698708 -229.712774)
		(end 404.133558 -230.277924)
		(width 0.18288)
		(layer "In2.Cu")
		(net "M_E_CPU0_SB_DQ<1>")
	)
	(segment
		(start 384.297682 -236.273594)
		(end 384.28295 -236.28223)
		(width 0.088646)
		(layer "In2.Cu")
		(net "M_E_CPU0_SB_DQ<1>")
	)
	(segment
		(start 401.430998 -232.974388)
		(end 401.430998 -233.506264)
		(width 0.18288)
		(layer "In2.Cu")
		(net "M_E_CPU0_SB_DQ<1>")
	)
	(segment
		(start 405.069548 -229.712774)
		(end 404.698708 -229.712774)
		(width 0.18288)
		(layer "In2.Cu")
		(net "M_E_CPU0_SB_DQ<1>")
	)
	(segment
		(start 388.204964 -236.196378)
		(end 387.79323 -236.196378)
		(width 0.088646)
		(layer "In2.Cu")
		(net "M_E_CPU0_SB_DQ<1>")
	)
	(segment
		(start 396.957042 -236.196378)
		(end 388.204964 -236.196378)
		(width 0.18288)
		(layer "In2.Cu")
		(net "M_E_CPU0_SB_DQ<1>")
	)
	(segment
		(start 398.59458 -235.518198)
		(end 396.957042 -236.196378)
		(width 0.18288)
		(layer "In2.Cu")
		(net "M_E_CPU0_SB_DQ<1>")
	)
	(segment
		(start 405.623014 -230.466646)
		(end 405.303228 -230.14686)
		(width 0.18288)
		(layer "In2.Cu")
		(net "M_E_CPU0_SB_DQ<1>")
	)
	(segment
		(start 382.800098 -236.277658)
		(end 382.792732 -236.27334)
		(width 0.088646)
		(layer "In2.Cu")
		(net "M_E_CPU0_SB_DQ<1>")
	)
	(segment
		(start 405.303228 -229.946454)
		(end 405.069548 -229.712774)
		(width 0.18288)
		(layer "In2.Cu")
		(net "M_E_CPU0_SB_DQ<1>")
	)
	(segment
		(start 401.198842 -233.73842)
		(end 400.666966 -233.73842)
		(width 0.18288)
		(layer "In2.Cu")
		(net "M_E_CPU0_SB_DQ<1>")
	)
	(segment
		(start 382.792732 -236.27334)
		(end 382.788922 -236.271308)
		(width 0.088646)
		(layer "In2.Cu")
		(net "M_E_CPU0_SB_DQ<1>")
	)
	(segment
		(start 399.670778 -234.734608)
		(end 399.438622 -234.966764)
		(width 0.18288)
		(layer "In2.Cu")
		(net "M_E_CPU0_SB_DQ<1>")
	)
	(segment
		(start 385.237482 -236.273594)
		(end 385.22275 -236.28223)
		(width 0.088646)
		(layer "In2.Cu")
		(net "M_E_CPU0_SB_DQ<1>")
	)
	(segment
		(start 403.27961 -232.687622)
		(end 403.006814 -232.687622)
		(width 0.18288)
		(layer "In2.Cu")
		(net "M_E_CPU0_SB_DQ<1>")
	)
	(segment
		(start 400.202654 -234.734608)
		(end 399.670778 -234.734608)
		(width 0.18288)
		(layer "In2.Cu")
		(net "M_E_CPU0_SB_DQ<1>")
	)
	(segment
		(start 403.635464 -231.048814)
		(end 403.362668 -231.048814)
		(width 0.18288)
		(layer "In2.Cu")
		(net "M_E_CPU0_SB_DQ<1>")
	)
	(segment
		(start 387.79323 -236.196378)
		(end 387.712458 -236.27715)
		(width 0.088646)
		(layer "In2.Cu")
		(net "M_E_CPU0_SB_DQ<1>")
	)
	(segment
		(start 400.43481 -233.970576)
		(end 400.43481 -234.502452)
		(width 0.18288)
		(layer "In2.Cu")
		(net "M_E_CPU0_SB_DQ<1>")
	)
	(segment
		(start 401.430998 -233.506264)
		(end 401.198842 -233.73842)
		(width 0.18288)
		(layer "In2.Cu")
		(net "M_E_CPU0_SB_DQ<1>")
	)
	(segment
		(start 403.049994 -231.361488)
		(end 403.049994 -231.734868)
		(width 0.18288)
		(layer "In2.Cu")
		(net "M_E_CPU0_SB_DQ<1>")
	)
	(segment
		(start 404.302976 -230.719884)
		(end 404.302976 -230.99268)
		(width 0.18288)
		(layer "In2.Cu")
		(net "M_E_CPU0_SB_DQ<1>")
	)
	(segment
		(start 403.006814 -232.687622)
		(end 402.505672 -232.18648)
		(width 0.18288)
		(layer "In2.Cu")
		(net "M_E_CPU0_SB_DQ<1>")
	)
	(segment
		(start 381.852932 -236.27334)
		(end 381.766318 -236.223048)
		(width 0.088646)
		(layer "In2.Cu")
		(net "M_E_CPU0_SB_DQ<1>")
	)
	(segment
		(start 400.666966 -233.73842)
		(end 400.43481 -233.970576)
		(width 0.18288)
		(layer "In2.Cu")
		(net "M_E_CPU0_SB_DQ<1>")
	)
	(segment
		(start 402.505672 -232.18648)
		(end 402.218906 -232.18648)
		(width 0.18288)
		(layer "In2.Cu")
		(net "M_E_CPU0_SB_DQ<1>")
	)
	(segment
		(start 386.177282 -236.273594)
		(end 386.16255 -236.28223)
		(width 0.088646)
		(layer "In2.Cu")
		(net "M_E_CPU0_SB_DQ<1>")
	)
	(segment
		(start 383.732278 -236.273594)
		(end 383.729992 -236.271816)
		(width 0.088646)
		(layer "In2.Cu")
		(net "M_E_CPU0_SB_DQ<1>")
	)
	(segment
		(start 400.43481 -234.502452)
		(end 400.202654 -234.734608)
		(width 0.18288)
		(layer "In2.Cu")
		(net "M_E_CPU0_SB_DQ<1>")
	)
	(segment
		(start 402.218906 -232.18648)
		(end 401.430998 -232.974388)
		(width 0.18288)
		(layer "In2.Cu")
		(net "M_E_CPU0_SB_DQ<1>")
	)
	(segment
		(start 403.804882 -231.217978)
		(end 403.635464 -231.048814)
		(width 0.18288)
		(layer "In2.Cu")
		(net "M_E_CPU0_SB_DQ<1>")
	)
	(segment
		(start 404.302976 -230.99268)
		(end 404.077678 -231.217978)
		(width 0.18288)
		(layer "In2.Cu")
		(net "M_E_CPU0_SB_DQ<1>")
	)
	(segment
		(start 404.133558 -230.55072)
		(end 404.302976 -230.719884)
		(width 0.18288)
		(layer "In2.Cu")
		(net "M_E_CPU0_SB_DQ<1>")
	)
	(segment
		(start 399.438622 -234.966764)
		(end 399.438622 -235.325158)
		(width 0.18288)
		(layer "In2.Cu")
		(net "M_E_CPU0_SB_DQ<1>")
	)
	(segment
		(start 399.245582 -235.518198)
		(end 398.59458 -235.518198)
		(width 0.18288)
		(layer "In2.Cu")
		(net "M_E_CPU0_SB_DQ<1>")
	)
	(segment
		(start 387.117082 -236.273594)
		(end 387.10235 -236.28223)
		(width 0.088646)
		(layer "In2.Cu")
		(net "M_E_CPU0_SB_DQ<1>")
	)
	(segment
		(start 404.077678 -231.217978)
		(end 403.804882 -231.217978)
		(width 0.18288)
		(layer "In2.Cu")
		(net "M_E_CPU0_SB_DQ<1>")
	)
	(segment
		(start 404.133558 -230.277924)
		(end 404.133558 -230.55072)
		(width 0.18288)
		(layer "In2.Cu")
		(net "M_E_CPU0_SB_DQ<1>")
	)
	(segment
		(start 403.504908 -232.462324)
		(end 403.27961 -232.687622)
		(width 0.18288)
		(layer "In2.Cu")
		(net "M_E_CPU0_SB_DQ<1>")
	)
	(segment
		(start 387.712458 -236.27715)
		(end 387.504686 -236.27715)
		(width 0.088646)
		(layer "In2.Cu")
		(net "M_E_CPU0_SB_DQ<1>")
	)
	(arc
		(start 383.729992 -236.271816)
		(mid 383.543743 -236.223171)
		(end 383.357882 -236.27334)
		(width 0.088646)
		(layer "In2.Cu")
		(net "M_E_CPU0_SB_DQ<1>")
	)
	(arc
		(start 384.672078 -236.273594)
		(mid 384.48488 -236.223451)
		(end 384.297682 -236.273594)
		(width 0.088646)
		(layer "In2.Cu")
		(net "M_E_CPU0_SB_DQ<1>")
	)
	(arc
		(start 381.766318 -236.223048)
		(mid 381.466989 -236.022059)
		(end 381.196088 -235.784136)
		(width 0.088646)
		(layer "In2.Cu")
		(net "M_E_CPU0_SB_DQ<1>")
	)
	(arc
		(start 387.504686 -236.27715)
		(mid 387.497845 -236.276249)
		(end 387.491478 -236.273594)
		(width 0.088646)
		(layer "In2.Cu")
		(net "M_E_CPU0_SB_DQ<1>")
	)
	(arc
		(start 386.16255 -236.28223)
		(mid 385.886109 -236.349396)
		(end 385.611878 -236.273594)
		(width 0.088646)
		(layer "In2.Cu")
		(net "M_E_CPU0_SB_DQ<1>")
	)
	(arc
		(start 384.28295 -236.28223)
		(mid 384.006509 -236.349396)
		(end 383.732278 -236.273594)
		(width 0.088646)
		(layer "In2.Cu")
		(net "M_E_CPU0_SB_DQ<1>")
	)
	(arc
		(start 382.788922 -236.271308)
		(mid 382.603232 -236.22323)
		(end 382.418082 -236.27334)
		(width 0.088646)
		(layer "In2.Cu")
		(net "M_E_CPU0_SB_DQ<1>")
	)
	(arc
		(start 385.611878 -236.273594)
		(mid 385.42468 -236.223451)
		(end 385.237482 -236.273594)
		(width 0.088646)
		(layer "In2.Cu")
		(net "M_E_CPU0_SB_DQ<1>")
	)
	(arc
		(start 386.551678 -236.273594)
		(mid 386.36448 -236.223451)
		(end 386.177282 -236.273594)
		(width 0.088646)
		(layer "In2.Cu")
		(net "M_E_CPU0_SB_DQ<1>")
	)
	(arc
		(start 383.357882 -236.27334)
		(mid 383.079559 -236.349099)
		(end 382.800098 -236.277658)
		(width 0.088646)
		(layer "In2.Cu")
		(net "M_E_CPU0_SB_DQ<1>")
	)
	(arc
		(start 385.22275 -236.28223)
		(mid 384.946309 -236.349396)
		(end 384.672078 -236.273594)
		(width 0.088646)
		(layer "In2.Cu")
		(net "M_E_CPU0_SB_DQ<1>")
	)
	(arc
		(start 387.10235 -236.28223)
		(mid 386.825909 -236.349396)
		(end 386.551678 -236.273594)
		(width 0.088646)
		(layer "In2.Cu")
		(net "M_E_CPU0_SB_DQ<1>")
	)
	(arc
		(start 382.418082 -236.27334)
		(mid 382.135524 -236.348989)
		(end 381.852932 -236.27334)
		(width 0.088646)
		(layer "In2.Cu")
		(net "M_E_CPU0_SB_DQ<1>")
	)
	(arc
		(start 387.491478 -236.273594)
		(mid 387.30428 -236.223451)
		(end 387.117082 -236.273594)
		(width 0.088646)
		(layer "In2.Cu")
		(net "M_E_CPU0_SB_DQ<1>")
	)
	(segment
		(start 393.99718 -228.626924)
		(end 393.99718 -218.124532)
		(width 0.1016)
		(layer "F.Cu")
		(net "M_E_CPU0_SB_DQ<19>")
	)
	(segment
		(start 408.058366 -211.356702)
		(end 408.32532 -211.089748)
		(width 0.20066)
		(layer "F.Cu")
		(net "M_E_CPU0_SB_DQ<19>")
	)
	(segment
		(start 416.823652 -210.664806)
		(end 416.40506 -210.664806)
		(width 0.20066)
		(layer "F.Cu")
		(net "M_E_CPU0_SB_DQ<19>")
	)
	(segment
		(start 397.033242 -216.710006)
		(end 397.23441 -216.508838)
		(width 0.20066)
		(layer "F.Cu")
		(net "M_E_CPU0_SB_DQ<19>")
	)
	(segment
		(start 396.707614 -215.69807)
		(end 396.707614 -215.414098)
		(width 0.20066)
		(layer "F.Cu")
		(net "M_E_CPU0_SB_DQ<19>")
	)
	(segment
		(start 388.281164 -233.905298)
		(end 388.718806 -233.905298)
		(width 0.1016)
		(layer "F.Cu")
		(net "M_E_CPU0_SB_DQ<19>")
	)
	(segment
		(start 388.718806 -233.905298)
		(end 393.99718 -228.626924)
		(width 0.1016)
		(layer "F.Cu")
		(net "M_E_CPU0_SB_DQ<19>")
	)
	(segment
		(start 408.453082 -210.622388)
		(end 408.800046 -210.622388)
		(width 0.20066)
		(layer "F.Cu")
		(net "M_E_CPU0_SB_DQ<19>")
	)
	(segment
		(start 405.738838 -211.341716)
		(end 407.740104 -211.341716)
		(width 0.1016)
		(layer "F.Cu")
		(net "M_E_CPU0_SB_DQ<19>")
	)
	(segment
		(start 386.364734 -233.87812)
		(end 386.391912 -233.905298)
		(width 0.088646)
		(layer "F.Cu")
		(net "M_E_CPU0_SB_DQ<19>")
	)
	(segment
		(start 416.205416 -211.161376)
		(end 416.009074 -211.357718)
		(width 0.20066)
		(layer "F.Cu")
		(net "M_E_CPU0_SB_DQ<19>")
	)
	(segment
		(start 393.99718 -218.124532)
		(end 394.824966 -217.296746)
		(width 0.1016)
		(layer "F.Cu")
		(net "M_E_CPU0_SB_DQ<19>")
	)
	(segment
		(start 397.23441 -216.224866)
		(end 396.707614 -215.69807)
		(width 0.20066)
		(layer "F.Cu")
		(net "M_E_CPU0_SB_DQ<19>")
	)
	(segment
		(start 412.545022 -210.916774)
		(end 410.853382 -210.916774)
		(width 0.20066)
		(layer "F.Cu")
		(net "M_E_CPU0_SB_DQ<19>")
	)
	(segment
		(start 416.205416 -210.86445)
		(end 416.205416 -211.161376)
		(width 0.20066)
		(layer "F.Cu")
		(net "M_E_CPU0_SB_DQ<19>")
	)
	(segment
		(start 408.32532 -211.089748)
		(end 408.32532 -210.75015)
		(width 0.20066)
		(layer "F.Cu")
		(net "M_E_CPU0_SB_DQ<19>")
	)
	(segment
		(start 396.222474 -216.18321)
		(end 396.74927 -216.710006)
		(width 0.20066)
		(layer "F.Cu")
		(net "M_E_CPU0_SB_DQ<19>")
	)
	(segment
		(start 397.23441 -216.508838)
		(end 397.23441 -216.224866)
		(width 0.20066)
		(layer "F.Cu")
		(net "M_E_CPU0_SB_DQ<19>")
	)
	(segment
		(start 401.32762 -210.794092)
		(end 404.699724 -210.794092)
		(width 0.20066)
		(layer "F.Cu")
		(net "M_E_CPU0_SB_DQ<19>")
	)
	(segment
		(start 407.75509 -211.356702)
		(end 407.763726 -211.356702)
		(width 0.1016)
		(layer "F.Cu")
		(net "M_E_CPU0_SB_DQ<19>")
	)
	(segment
		(start 416.40506 -210.664806)
		(end 416.205416 -210.86445)
		(width 0.20066)
		(layer "F.Cu")
		(net "M_E_CPU0_SB_DQ<19>")
	)
	(segment
		(start 407.740104 -211.341716)
		(end 407.75509 -211.356702)
		(width 0.1016)
		(layer "F.Cu")
		(net "M_E_CPU0_SB_DQ<19>")
	)
	(segment
		(start 405.25446 -211.348828)
		(end 405.731726 -211.348828)
		(width 0.20066)
		(layer "F.Cu")
		(net "M_E_CPU0_SB_DQ<19>")
	)
	(segment
		(start 413.275526 -211.352384)
		(end 412.980632 -211.352384)
		(width 0.20066)
		(layer "F.Cu")
		(net "M_E_CPU0_SB_DQ<19>")
	)
	(segment
		(start 413.32023 -211.341716)
		(end 413.309562 -211.352384)
		(width 0.101854)
		(layer "F.Cu")
		(net "M_E_CPU0_SB_DQ<19>")
	)
	(segment
		(start 418.397182 -210.916774)
		(end 417.07562 -210.916774)
		(width 0.20066)
		(layer "F.Cu")
		(net "M_E_CPU0_SB_DQ<19>")
	)
	(segment
		(start 394.824966 -217.296746)
		(end 395.938502 -216.18321)
		(width 0.20066)
		(layer "F.Cu")
		(net "M_E_CPU0_SB_DQ<19>")
	)
	(segment
		(start 412.980632 -211.352384)
		(end 412.545022 -210.916774)
		(width 0.20066)
		(layer "F.Cu")
		(net "M_E_CPU0_SB_DQ<19>")
	)
	(segment
		(start 396.74927 -216.710006)
		(end 397.033242 -216.710006)
		(width 0.20066)
		(layer "F.Cu")
		(net "M_E_CPU0_SB_DQ<19>")
	)
	(segment
		(start 413.309562 -211.352384)
		(end 413.275526 -211.352384)
		(width 0.101854)
		(layer "F.Cu")
		(net "M_E_CPU0_SB_DQ<19>")
	)
	(segment
		(start 408.32532 -210.75015)
		(end 408.453082 -210.622388)
		(width 0.20066)
		(layer "F.Cu")
		(net "M_E_CPU0_SB_DQ<19>")
	)
	(segment
		(start 395.938502 -216.18321)
		(end 396.222474 -216.18321)
		(width 0.20066)
		(layer "F.Cu")
		(net "M_E_CPU0_SB_DQ<19>")
	)
	(segment
		(start 396.707614 -215.414098)
		(end 401.32762 -210.794092)
		(width 0.20066)
		(layer "F.Cu")
		(net "M_E_CPU0_SB_DQ<19>")
	)
	(segment
		(start 416.009074 -211.357718)
		(end 415.307526 -211.357718)
		(width 0.20066)
		(layer "F.Cu")
		(net "M_E_CPU0_SB_DQ<19>")
	)
	(segment
		(start 408.800046 -210.622388)
		(end 409.094432 -210.916774)
		(width 0.20066)
		(layer "F.Cu")
		(net "M_E_CPU0_SB_DQ<19>")
	)
	(segment
		(start 405.731726 -211.348828)
		(end 405.738838 -211.341716)
		(width 0.101854)
		(layer "F.Cu")
		(net "M_E_CPU0_SB_DQ<19>")
	)
	(segment
		(start 409.094432 -210.916774)
		(end 410.853382 -210.916774)
		(width 0.20066)
		(layer "F.Cu")
		(net "M_E_CPU0_SB_DQ<19>")
	)
	(segment
		(start 415.307526 -211.357718)
		(end 415.291524 -211.341716)
		(width 0.1016)
		(layer "F.Cu")
		(net "M_E_CPU0_SB_DQ<19>")
	)
	(segment
		(start 386.391912 -233.905298)
		(end 388.281164 -233.905298)
		(width 0.088646)
		(layer "F.Cu")
		(net "M_E_CPU0_SB_DQ<19>")
	)
	(segment
		(start 404.699724 -210.794092)
		(end 405.25446 -211.348828)
		(width 0.20066)
		(layer "F.Cu")
		(net "M_E_CPU0_SB_DQ<19>")
	)
	(segment
		(start 417.07562 -210.916774)
		(end 416.823652 -210.664806)
		(width 0.20066)
		(layer "F.Cu")
		(net "M_E_CPU0_SB_DQ<19>")
	)
	(segment
		(start 415.291524 -211.341716)
		(end 413.32023 -211.341716)
		(width 0.1016)
		(layer "F.Cu")
		(net "M_E_CPU0_SB_DQ<19>")
	)
	(segment
		(start 407.763726 -211.356702)
		(end 408.058366 -211.356702)
		(width 0.20066)
		(layer "F.Cu")
		(net "M_E_CPU0_SB_DQ<19>")
	)
	(segment
		(start 387.599682 -234.305094)
		(end 387.818122 -234.523534)
		(width 0.088646)
		(layer "F.Cu")
		(net "M_E_CPU0_SB_DQ<18>")
	)
	(segment
		(start 407.74493 -213.04758)
		(end 407.763726 -213.04758)
		(width 0.1016)
		(layer "F.Cu")
		(net "M_E_CPU0_SB_DQ<18>")
	)
	(segment
		(start 416.205416 -212.856826)
		(end 416.004502 -213.05774)
		(width 0.20066)
		(layer "F.Cu")
		(net "M_E_CPU0_SB_DQ<18>")
	)
	(segment
		(start 386.185918 -234.69219)
		(end 386.323078 -234.55503)
		(width 0.088646)
		(layer "F.Cu")
		(net "M_E_CPU0_SB_DQ<18>")
	)
	(segment
		(start 409.29306 -212.42655)
		(end 409.542996 -212.42655)
		(width 0.20066)
		(layer "F.Cu")
		(net "M_E_CPU0_SB_DQ<18>")
	)
	(segment
		(start 403.874732 -212.506306)
		(end 404.430738 -213.062312)
		(width 0.20066)
		(layer "F.Cu")
		(net "M_E_CPU0_SB_DQ<18>")
	)
	(segment
		(start 408.73426 -212.141562)
		(end 409.008072 -212.141562)
		(width 0.20066)
		(layer "F.Cu")
		(net "M_E_CPU0_SB_DQ<18>")
	)
	(segment
		(start 417.07562 -212.616796)
		(end 416.731958 -212.273134)
		(width 0.20066)
		(layer "F.Cu")
		(net "M_E_CPU0_SB_DQ<18>")
	)
	(segment
		(start 385.894834 -234.69219)
		(end 386.185918 -234.69219)
		(width 0.088646)
		(layer "F.Cu")
		(net "M_E_CPU0_SB_DQ<18>")
	)
	(segment
		(start 408.540712 -213.085426)
		(end 408.540712 -212.33511)
		(width 0.20066)
		(layer "F.Cu")
		(net "M_E_CPU0_SB_DQ<18>")
	)
	(segment
		(start 415.291524 -213.041738)
		(end 413.32023 -213.041738)
		(width 0.1016)
		(layer "F.Cu")
		(net "M_E_CPU0_SB_DQ<18>")
	)
	(segment
		(start 412.545022 -212.616796)
		(end 410.853382 -212.616796)
		(width 0.20066)
		(layer "F.Cu")
		(net "M_E_CPU0_SB_DQ<18>")
	)
	(segment
		(start 396.286482 -219.687394)
		(end 399.492216 -216.48166)
		(width 0.20066)
		(layer "F.Cu")
		(net "M_E_CPU0_SB_DQ<18>")
	)
	(segment
		(start 405.736552 -213.062312)
		(end 405.757126 -213.041738)
		(width 0.1016)
		(layer "F.Cu")
		(net "M_E_CPU0_SB_DQ<18>")
	)
	(segment
		(start 410.362146 -212.616796)
		(end 410.853382 -212.616796)
		(width 0.20066)
		(layer "F.Cu")
		(net "M_E_CPU0_SB_DQ<18>")
	)
	(segment
		(start 399.492216 -216.197688)
		(end 398.911826 -215.617298)
		(width 0.20066)
		(layer "F.Cu")
		(net "M_E_CPU0_SB_DQ<18>")
	)
	(segment
		(start 409.542996 -212.42655)
		(end 409.74391 -212.225636)
		(width 0.20066)
		(layer "F.Cu")
		(net "M_E_CPU0_SB_DQ<18>")
	)
	(segment
		(start 409.008072 -212.141562)
		(end 409.29306 -212.42655)
		(width 0.20066)
		(layer "F.Cu")
		(net "M_E_CPU0_SB_DQ<18>")
	)
	(segment
		(start 394.60678 -219.888054)
		(end 394.80744 -219.687394)
		(width 0.1016)
		(layer "F.Cu")
		(net "M_E_CPU0_SB_DQ<18>")
	)
	(segment
		(start 416.406076 -212.273134)
		(end 416.205416 -212.473794)
		(width 0.20066)
		(layer "F.Cu")
		(net "M_E_CPU0_SB_DQ<18>")
	)
	(segment
		(start 408.182826 -213.230714)
		(end 408.395424 -213.230714)
		(width 0.20066)
		(layer "F.Cu")
		(net "M_E_CPU0_SB_DQ<18>")
	)
	(segment
		(start 409.74391 -212.225636)
		(end 409.970986 -212.225636)
		(width 0.20066)
		(layer "F.Cu")
		(net "M_E_CPU0_SB_DQ<18>")
	)
	(segment
		(start 413.32023 -213.041738)
		(end 413.309562 -213.052406)
		(width 0.101854)
		(layer "F.Cu")
		(net "M_E_CPU0_SB_DQ<18>")
	)
	(segment
		(start 416.205416 -212.473794)
		(end 416.205416 -212.856826)
		(width 0.20066)
		(layer "F.Cu")
		(net "M_E_CPU0_SB_DQ<18>")
	)
	(segment
		(start 404.430738 -213.062312)
		(end 405.731726 -213.062312)
		(width 0.20066)
		(layer "F.Cu")
		(net "M_E_CPU0_SB_DQ<18>")
	)
	(segment
		(start 415.307526 -213.05774)
		(end 415.291524 -213.041738)
		(width 0.1016)
		(layer "F.Cu")
		(net "M_E_CPU0_SB_DQ<18>")
	)
	(segment
		(start 398.911826 -215.617298)
		(end 398.911826 -215.056974)
		(width 0.20066)
		(layer "F.Cu")
		(net "M_E_CPU0_SB_DQ<18>")
	)
	(segment
		(start 407.999692 -213.04758)
		(end 408.182826 -213.230714)
		(width 0.20066)
		(layer "F.Cu")
		(net "M_E_CPU0_SB_DQ<18>")
	)
	(segment
		(start 387.818122 -234.523534)
		(end 388.281164 -234.523534)
		(width 0.088646)
		(layer "F.Cu")
		(net "M_E_CPU0_SB_DQ<18>")
	)
	(segment
		(start 405.757126 -213.041738)
		(end 407.739088 -213.041738)
		(width 0.1016)
		(layer "F.Cu")
		(net "M_E_CPU0_SB_DQ<18>")
	)
	(segment
		(start 386.755894 -234.305094)
		(end 387.599682 -234.305094)
		(width 0.088646)
		(layer "F.Cu")
		(net "M_E_CPU0_SB_DQ<18>")
	)
	(segment
		(start 407.763726 -213.04758)
		(end 407.999692 -213.04758)
		(width 0.20066)
		(layer "F.Cu")
		(net "M_E_CPU0_SB_DQ<18>")
	)
	(segment
		(start 386.323078 -234.55503)
		(end 386.755894 -234.305094)
		(width 0.088646)
		(layer "F.Cu")
		(net "M_E_CPU0_SB_DQ<18>")
	)
	(segment
		(start 394.98651 -219.687394)
		(end 396.286482 -219.687394)
		(width 0.20066)
		(layer "F.Cu")
		(net "M_E_CPU0_SB_DQ<18>")
	)
	(segment
		(start 412.980632 -213.052406)
		(end 412.545022 -212.616796)
		(width 0.20066)
		(layer "F.Cu")
		(net "M_E_CPU0_SB_DQ<18>")
	)
	(segment
		(start 394.80744 -219.687394)
		(end 394.98651 -219.687394)
		(width 0.1016)
		(layer "F.Cu")
		(net "M_E_CPU0_SB_DQ<18>")
	)
	(segment
		(start 413.309562 -213.052406)
		(end 413.275526 -213.052406)
		(width 0.101854)
		(layer "F.Cu")
		(net "M_E_CPU0_SB_DQ<18>")
	)
	(segment
		(start 388.281164 -234.523534)
		(end 388.963154 -234.523534)
		(width 0.1016)
		(layer "F.Cu")
		(net "M_E_CPU0_SB_DQ<18>")
	)
	(segment
		(start 416.004502 -213.05774)
		(end 415.307526 -213.05774)
		(width 0.20066)
		(layer "F.Cu")
		(net "M_E_CPU0_SB_DQ<18>")
	)
	(segment
		(start 409.970986 -212.225636)
		(end 410.362146 -212.616796)
		(width 0.20066)
		(layer "F.Cu")
		(net "M_E_CPU0_SB_DQ<18>")
	)
	(segment
		(start 408.540712 -212.33511)
		(end 408.73426 -212.141562)
		(width 0.20066)
		(layer "F.Cu")
		(net "M_E_CPU0_SB_DQ<18>")
	)
	(segment
		(start 388.963154 -234.523534)
		(end 394.60678 -228.879908)
		(width 0.1016)
		(layer "F.Cu")
		(net "M_E_CPU0_SB_DQ<18>")
	)
	(segment
		(start 416.731958 -212.273134)
		(end 416.406076 -212.273134)
		(width 0.20066)
		(layer "F.Cu")
		(net "M_E_CPU0_SB_DQ<18>")
	)
	(segment
		(start 407.739088 -213.041738)
		(end 407.74493 -213.04758)
		(width 0.1016)
		(layer "F.Cu")
		(net "M_E_CPU0_SB_DQ<18>")
	)
	(segment
		(start 401.462494 -212.506306)
		(end 403.874732 -212.506306)
		(width 0.20066)
		(layer "F.Cu")
		(net "M_E_CPU0_SB_DQ<18>")
	)
	(segment
		(start 394.60678 -228.879908)
		(end 394.60678 -219.888054)
		(width 0.1016)
		(layer "F.Cu")
		(net "M_E_CPU0_SB_DQ<18>")
	)
	(segment
		(start 399.492216 -216.48166)
		(end 399.492216 -216.197688)
		(width 0.20066)
		(layer "F.Cu")
		(net "M_E_CPU0_SB_DQ<18>")
	)
	(segment
		(start 418.397182 -212.616796)
		(end 417.07562 -212.616796)
		(width 0.20066)
		(layer "F.Cu")
		(net "M_E_CPU0_SB_DQ<18>")
	)
	(segment
		(start 408.395424 -213.230714)
		(end 408.540712 -213.085426)
		(width 0.20066)
		(layer "F.Cu")
		(net "M_E_CPU0_SB_DQ<18>")
	)
	(segment
		(start 413.275526 -213.052406)
		(end 412.980632 -213.052406)
		(width 0.20066)
		(layer "F.Cu")
		(net "M_E_CPU0_SB_DQ<18>")
	)
	(segment
		(start 398.911826 -215.056974)
		(end 401.462494 -212.506306)
		(width 0.20066)
		(layer "F.Cu")
		(net "M_E_CPU0_SB_DQ<18>")
	)
	(segment
		(start 405.731726 -213.062312)
		(end 405.736552 -213.062312)
		(width 0.101854)
		(layer "F.Cu")
		(net "M_E_CPU0_SB_DQ<18>")
	)
	(segment
		(start 384.607816 -234.453684)
		(end 384.698494 -234.363006)
		(width 0.088646)
		(layer "F.Cu")
		(net "M_E_CPU0_SB_DQ<17>")
	)
	(segment
		(start 396.35938 -218.63812)
		(end 398.446244 -216.551256)
		(width 0.20066)
		(layer "F.Cu")
		(net "M_E_CPU0_SB_DQ<17>")
	)
	(segment
		(start 384.393694 -234.365038)
		(end 384.48234 -234.453684)
		(width 0.088646)
		(layer "F.Cu")
		(net "M_E_CPU0_SB_DQ<17>")
	)
	(segment
		(start 409.045918 -211.690966)
		(end 408.31135 -211.690966)
		(width 0.20066)
		(layer "F.Cu")
		(net "M_E_CPU0_SB_DQ<17>")
	)
	(segment
		(start 384.48234 -234.453684)
		(end 384.607816 -234.453684)
		(width 0.088646)
		(layer "F.Cu")
		(net "M_E_CPU0_SB_DQ<17>")
	)
	(segment
		(start 384.698494 -234.20705)
		(end 384.876548 -234.028996)
		(width 0.088646)
		(layer "F.Cu")
		(net "M_E_CPU0_SB_DQ<17>")
	)
	(segment
		(start 395.828774 -217.228166)
		(end 396.112746 -217.228166)
		(width 0.20066)
		(layer "F.Cu")
		(net "M_E_CPU0_SB_DQ<17>")
	)
	(segment
		(start 384.485134 -233.87812)
		(end 384.393694 -234.0991)
		(width 0.088646)
		(layer "F.Cu")
		(net "M_E_CPU0_SB_DQ<17>")
	)
	(segment
		(start 387.702806 -234.113578)
		(end 387.799072 -234.209844)
		(width 0.088646)
		(layer "F.Cu")
		(net "M_E_CPU0_SB_DQ<17>")
	)
	(segment
		(start 409.83662 -211.326222)
		(end 409.831794 -211.326222)
		(width 0.101854)
		(layer "F.Cu")
		(net "M_E_CPU0_SB_DQ<17>")
	)
	(segment
		(start 388.281164 -234.210098)
		(end 388.845298 -234.210098)
		(width 0.1016)
		(layer "F.Cu")
		(net "M_E_CPU0_SB_DQ<17>")
	)
	(segment
		(start 404.82901 -212.163152)
		(end 405.446738 -212.163152)
		(width 0.20066)
		(layer "F.Cu")
		(net "M_E_CPU0_SB_DQ<17>")
	)
	(segment
		(start 397.964152 -215.731852)
		(end 397.964152 -215.092788)
		(width 0.20066)
		(layer "F.Cu")
		(net "M_E_CPU0_SB_DQ<17>")
	)
	(segment
		(start 411.863794 -211.326984)
		(end 411.849062 -211.341716)
		(width 0.1016)
		(layer "F.Cu")
		(net "M_E_CPU0_SB_DQ<17>")
	)
	(segment
		(start 387.985508 -234.210098)
		(end 388.281164 -234.210098)
		(width 0.088646)
		(layer "F.Cu")
		(net "M_E_CPU0_SB_DQ<17>")
	)
	(segment
		(start 387.799072 -234.209844)
		(end 387.985254 -234.209844)
		(width 0.088646)
		(layer "F.Cu")
		(net "M_E_CPU0_SB_DQ<17>")
	)
	(segment
		(start 386.70357 -234.113578)
		(end 387.702806 -234.113578)
		(width 0.088646)
		(layer "F.Cu")
		(net "M_E_CPU0_SB_DQ<17>")
	)
	(segment
		(start 385.231894 -234.286806)
		(end 386.24129 -234.286806)
		(width 0.088646)
		(layer "F.Cu")
		(net "M_E_CPU0_SB_DQ<17>")
	)
	(segment
		(start 409.831794 -211.326222)
		(end 409.410662 -211.326222)
		(width 0.20066)
		(layer "F.Cu")
		(net "M_E_CPU0_SB_DQ<17>")
	)
	(segment
		(start 409.410662 -211.326222)
		(end 409.045918 -211.690966)
		(width 0.20066)
		(layer "F.Cu")
		(net "M_E_CPU0_SB_DQ<17>")
	)
	(segment
		(start 413.288226 -211.95411)
		(end 412.914846 -211.95411)
		(width 0.20066)
		(layer "F.Cu")
		(net "M_E_CPU0_SB_DQ<17>")
	)
	(segment
		(start 398.446244 -216.213944)
		(end 397.964152 -215.731852)
		(width 0.20066)
		(layer "F.Cu")
		(net "M_E_CPU0_SB_DQ<17>")
	)
	(segment
		(start 411.849062 -211.341716)
		(end 409.902914 -211.341716)
		(width 0.1016)
		(layer "F.Cu")
		(net "M_E_CPU0_SB_DQ<17>")
	)
	(segment
		(start 407.854912 -212.147404)
		(end 407.670254 -212.147404)
		(width 0.20066)
		(layer "F.Cu")
		(net "M_E_CPU0_SB_DQ<17>")
	)
	(segment
		(start 394.30198 -228.753416)
		(end 394.30198 -218.75496)
		(width 0.1016)
		(layer "F.Cu")
		(net "M_E_CPU0_SB_DQ<17>")
	)
	(segment
		(start 396.313914 -217.713306)
		(end 395.87424 -218.15298)
		(width 0.20066)
		(layer "F.Cu")
		(net "M_E_CPU0_SB_DQ<17>")
	)
	(segment
		(start 386.551932 -234.202478)
		(end 386.70357 -234.113578)
		(width 0.088646)
		(layer "F.Cu")
		(net "M_E_CPU0_SB_DQ<17>")
	)
	(segment
		(start 405.843232 -211.766658)
		(end 406.753314 -211.766658)
		(width 0.20066)
		(layer "F.Cu")
		(net "M_E_CPU0_SB_DQ<17>")
	)
	(segment
		(start 408.31135 -211.690966)
		(end 407.854912 -212.147404)
		(width 0.20066)
		(layer "F.Cu")
		(net "M_E_CPU0_SB_DQ<17>")
	)
	(segment
		(start 394.30198 -218.75496)
		(end 394.719556 -218.337384)
		(width 0.1016)
		(layer "F.Cu")
		(net "M_E_CPU0_SB_DQ<17>")
	)
	(segment
		(start 407.289508 -211.766658)
		(end 406.753314 -211.766658)
		(width 0.20066)
		(layer "F.Cu")
		(net "M_E_CPU0_SB_DQ<17>")
	)
	(segment
		(start 395.87424 -218.15298)
		(end 395.87424 -218.436952)
		(width 0.20066)
		(layer "F.Cu")
		(net "M_E_CPU0_SB_DQ<17>")
	)
	(segment
		(start 405.446738 -212.163152)
		(end 405.843232 -211.766658)
		(width 0.20066)
		(layer "F.Cu")
		(net "M_E_CPU0_SB_DQ<17>")
	)
	(segment
		(start 407.670254 -212.147404)
		(end 407.289508 -211.766658)
		(width 0.20066)
		(layer "F.Cu")
		(net "M_E_CPU0_SB_DQ<17>")
	)
	(segment
		(start 387.985254 -234.209844)
		(end 387.985508 -234.210098)
		(width 0.088646)
		(layer "F.Cu")
		(net "M_E_CPU0_SB_DQ<17>")
	)
	(segment
		(start 414.297114 -211.766658)
		(end 413.475678 -211.766658)
		(width 0.20066)
		(layer "F.Cu")
		(net "M_E_CPU0_SB_DQ<17>")
	)
	(segment
		(start 396.313914 -217.429334)
		(end 396.313914 -217.713306)
		(width 0.20066)
		(layer "F.Cu")
		(net "M_E_CPU0_SB_DQ<17>")
	)
	(segment
		(start 384.393694 -234.0991)
		(end 384.393694 -234.365038)
		(width 0.088646)
		(layer "F.Cu")
		(net "M_E_CPU0_SB_DQ<17>")
	)
	(segment
		(start 397.964152 -215.092788)
		(end 401.452842 -211.604098)
		(width 0.20066)
		(layer "F.Cu")
		(net "M_E_CPU0_SB_DQ<17>")
	)
	(segment
		(start 396.075408 -218.63812)
		(end 396.35938 -218.63812)
		(width 0.20066)
		(layer "F.Cu")
		(net "M_E_CPU0_SB_DQ<17>")
	)
	(segment
		(start 404.269956 -211.604098)
		(end 404.82901 -212.163152)
		(width 0.20066)
		(layer "F.Cu")
		(net "M_E_CPU0_SB_DQ<17>")
	)
	(segment
		(start 396.112746 -217.228166)
		(end 396.313914 -217.429334)
		(width 0.20066)
		(layer "F.Cu")
		(net "M_E_CPU0_SB_DQ<17>")
	)
	(segment
		(start 388.845298 -234.210098)
		(end 394.30198 -228.753416)
		(width 0.1016)
		(layer "F.Cu")
		(net "M_E_CPU0_SB_DQ<17>")
	)
	(segment
		(start 384.974084 -234.028996)
		(end 385.231894 -234.286806)
		(width 0.088646)
		(layer "F.Cu")
		(net "M_E_CPU0_SB_DQ<17>")
	)
	(segment
		(start 384.876548 -234.028996)
		(end 384.974084 -234.028996)
		(width 0.088646)
		(layer "F.Cu")
		(net "M_E_CPU0_SB_DQ<17>")
	)
	(segment
		(start 412.914846 -211.95411)
		(end 412.28772 -211.326984)
		(width 0.20066)
		(layer "F.Cu")
		(net "M_E_CPU0_SB_DQ<17>")
	)
	(segment
		(start 412.28772 -211.326984)
		(end 411.863794 -211.326984)
		(width 0.20066)
		(layer "F.Cu")
		(net "M_E_CPU0_SB_DQ<17>")
	)
	(segment
		(start 395.87424 -218.436952)
		(end 396.075408 -218.63812)
		(width 0.20066)
		(layer "F.Cu")
		(net "M_E_CPU0_SB_DQ<17>")
	)
	(segment
		(start 409.902914 -211.341716)
		(end 409.88742 -211.326222)
		(width 0.1016)
		(layer "F.Cu")
		(net "M_E_CPU0_SB_DQ<17>")
	)
	(segment
		(start 398.446244 -216.551256)
		(end 398.446244 -216.213944)
		(width 0.20066)
		(layer "F.Cu")
		(net "M_E_CPU0_SB_DQ<17>")
	)
	(segment
		(start 413.475678 -211.766658)
		(end 413.288226 -211.95411)
		(width 0.20066)
		(layer "F.Cu")
		(net "M_E_CPU0_SB_DQ<17>")
	)
	(segment
		(start 384.698494 -234.363006)
		(end 384.698494 -234.20705)
		(width 0.088646)
		(layer "F.Cu")
		(net "M_E_CPU0_SB_DQ<17>")
	)
	(segment
		(start 394.719556 -218.337384)
		(end 395.828774 -217.228166)
		(width 0.20066)
		(layer "F.Cu")
		(net "M_E_CPU0_SB_DQ<17>")
	)
	(segment
		(start 401.452842 -211.604098)
		(end 404.269956 -211.604098)
		(width 0.20066)
		(layer "F.Cu")
		(net "M_E_CPU0_SB_DQ<17>")
	)
	(segment
		(start 409.88742 -211.326222)
		(end 409.83662 -211.326222)
		(width 0.1016)
		(layer "F.Cu")
		(net "M_E_CPU0_SB_DQ<17>")
	)
	(arc
		(start 386.24129 -234.286806)
		(mid 386.40223 -234.265344)
		(end 386.551932 -234.202478)
		(width 0.088646)
		(layer "F.Cu")
		(net "M_E_CPU0_SB_DQ<17>")
	)
	(segment
		(start 385.725416 -235.220002)
		(end 386.011166 -235.220002)
		(width 0.088646)
		(layer "F.Cu")
		(net "M_E_CPU0_SB_DQ<16>")
	)
	(segment
		(start 412.727648 -213.466934)
		(end 412.28772 -213.027006)
		(width 0.20066)
		(layer "F.Cu")
		(net "M_E_CPU0_SB_DQ<16>")
	)
	(segment
		(start 385.607306 -235.101892)
		(end 385.725416 -235.220002)
		(width 0.088646)
		(layer "F.Cu")
		(net "M_E_CPU0_SB_DQ<16>")
	)
	(segment
		(start 385.607306 -234.942126)
		(end 385.607306 -235.101892)
		(width 0.088646)
		(layer "F.Cu")
		(net "M_E_CPU0_SB_DQ<16>")
	)
	(segment
		(start 412.28772 -213.027006)
		(end 411.863794 -213.027006)
		(width 0.20066)
		(layer "F.Cu")
		(net "M_E_CPU0_SB_DQ<16>")
	)
	(segment
		(start 396.16253 -220.726762)
		(end 402.229828 -214.658194)
		(width 0.20066)
		(layer "F.Cu")
		(net "M_E_CPU0_SB_DQ<16>")
	)
	(segment
		(start 409.849828 -213.041738)
		(end 409.83662 -213.02853)
		(width 0.1016)
		(layer "F.Cu")
		(net "M_E_CPU0_SB_DQ<16>")
	)
	(segment
		(start 399.76806 -215.180418)
		(end 401.55495 -213.39302)
		(width 0.20066)
		(layer "F.Cu")
		(net "M_E_CPU0_SB_DQ<16>")
	)
	(segment
		(start 385.15671 -235.15955)
		(end 385.282694 -235.033566)
		(width 0.088646)
		(layer "F.Cu")
		(net "M_E_CPU0_SB_DQ<16>")
	)
	(segment
		(start 385.282694 -234.942126)
		(end 385.371594 -234.853226)
		(width 0.088646)
		(layer "F.Cu")
		(net "M_E_CPU0_SB_DQ<16>")
	)
	(segment
		(start 394.91158 -229.0064)
		(end 394.91158 -221.243652)
		(width 0.1016)
		(layer "F.Cu")
		(net "M_E_CPU0_SB_DQ<16>")
	)
	(segment
		(start 385.371594 -234.853226)
		(end 385.518406 -234.853226)
		(width 0.088646)
		(layer "F.Cu")
		(net "M_E_CPU0_SB_DQ<16>")
	)
	(segment
		(start 386.416296 -235.038646)
		(end 387.186678 -235.35767)
		(width 0.088646)
		(layer "F.Cu")
		(net "M_E_CPU0_SB_DQ<16>")
	)
	(segment
		(start 384.860546 -235.054902)
		(end 384.965194 -235.15955)
		(width 0.088646)
		(layer "F.Cu")
		(net "M_E_CPU0_SB_DQ<16>")
	)
	(segment
		(start 389.073644 -234.844336)
		(end 394.91158 -229.0064)
		(width 0.1016)
		(layer "F.Cu")
		(net "M_E_CPU0_SB_DQ<16>")
	)
	(segment
		(start 395.278102 -220.877384)
		(end 395.427708 -220.727778)
		(width 0.20066)
		(layer "F.Cu")
		(net "M_E_CPU0_SB_DQ<16>")
	)
	(segment
		(start 402.028406 -214.173308)
		(end 401.744942 -214.173308)
		(width 0.20066)
		(layer "F.Cu")
		(net "M_E_CPU0_SB_DQ<16>")
	)
	(segment
		(start 403.77364 -213.39302)
		(end 404.21687 -213.83625)
		(width 0.20066)
		(layer "F.Cu")
		(net "M_E_CPU0_SB_DQ<16>")
	)
	(segment
		(start 404.21687 -213.83625)
		(end 405.433022 -213.83625)
		(width 0.20066)
		(layer "F.Cu")
		(net "M_E_CPU0_SB_DQ<16>")
	)
	(segment
		(start 385.282694 -235.033566)
		(end 385.282694 -234.942126)
		(width 0.088646)
		(layer "F.Cu")
		(net "M_E_CPU0_SB_DQ<16>")
	)
	(segment
		(start 402.229828 -214.658194)
		(end 402.229828 -214.37473)
		(width 0.20066)
		(layer "F.Cu")
		(net "M_E_CPU0_SB_DQ<16>")
	)
	(segment
		(start 409.386532 -213.02853)
		(end 409.185872 -213.22919)
		(width 0.20066)
		(layer "F.Cu")
		(net "M_E_CPU0_SB_DQ<16>")
	)
	(segment
		(start 405.433022 -213.83625)
		(end 405.802592 -213.46668)
		(width 0.20066)
		(layer "F.Cu")
		(net "M_E_CPU0_SB_DQ<16>")
	)
	(segment
		(start 388.059676 -234.844336)
		(end 388.281164 -234.844336)
		(width 0.088646)
		(layer "F.Cu")
		(net "M_E_CPU0_SB_DQ<16>")
	)
	(segment
		(start 407.897076 -213.788244)
		(end 407.575512 -213.46668)
		(width 0.20066)
		(layer "F.Cu")
		(net "M_E_CPU0_SB_DQ<16>")
	)
	(segment
		(start 411.849062 -213.041738)
		(end 409.849828 -213.041738)
		(width 0.1016)
		(layer "F.Cu")
		(net "M_E_CPU0_SB_DQ<16>")
	)
	(segment
		(start 402.229828 -214.37473)
		(end 402.028406 -214.173308)
		(width 0.20066)
		(layer "F.Cu")
		(net "M_E_CPU0_SB_DQ<16>")
	)
	(segment
		(start 388.281164 -234.844336)
		(end 389.073644 -234.844336)
		(width 0.1016)
		(layer "F.Cu")
		(net "M_E_CPU0_SB_DQ<16>")
	)
	(segment
		(start 387.546342 -235.35767)
		(end 388.059676 -234.844336)
		(width 0.088646)
		(layer "F.Cu")
		(net "M_E_CPU0_SB_DQ<16>")
	)
	(segment
		(start 385.518406 -234.853226)
		(end 385.607306 -234.942126)
		(width 0.088646)
		(layer "F.Cu")
		(net "M_E_CPU0_SB_DQ<16>")
	)
	(segment
		(start 405.802592 -213.46668)
		(end 406.753314 -213.46668)
		(width 0.20066)
		(layer "F.Cu")
		(net "M_E_CPU0_SB_DQ<16>")
	)
	(segment
		(start 409.83662 -213.02853)
		(end 409.831794 -213.02853)
		(width 0.101854)
		(layer "F.Cu")
		(net "M_E_CPU0_SB_DQ<16>")
	)
	(segment
		(start 400.252946 -215.665304)
		(end 399.969228 -215.665304)
		(width 0.20066)
		(layer "F.Cu")
		(net "M_E_CPU0_SB_DQ<16>")
	)
	(segment
		(start 394.91158 -221.243652)
		(end 395.277848 -220.877384)
		(width 0.1016)
		(layer "F.Cu")
		(net "M_E_CPU0_SB_DQ<16>")
	)
	(segment
		(start 409.185872 -213.357206)
		(end 408.754834 -213.788244)
		(width 0.20066)
		(layer "F.Cu")
		(net "M_E_CPU0_SB_DQ<16>")
	)
	(segment
		(start 407.575512 -213.46668)
		(end 406.753314 -213.46668)
		(width 0.20066)
		(layer "F.Cu")
		(net "M_E_CPU0_SB_DQ<16>")
	)
	(segment
		(start 384.965194 -235.15955)
		(end 385.15671 -235.15955)
		(width 0.088646)
		(layer "F.Cu")
		(net "M_E_CPU0_SB_DQ<16>")
	)
	(segment
		(start 399.76806 -215.464136)
		(end 399.76806 -215.180418)
		(width 0.20066)
		(layer "F.Cu")
		(net "M_E_CPU0_SB_DQ<16>")
	)
	(segment
		(start 401.55495 -213.39302)
		(end 403.77364 -213.39302)
		(width 0.20066)
		(layer "F.Cu")
		(net "M_E_CPU0_SB_DQ<16>")
	)
	(segment
		(start 384.860546 -234.919774)
		(end 384.860546 -235.054902)
		(width 0.088646)
		(layer "F.Cu")
		(net "M_E_CPU0_SB_DQ<16>")
	)
	(segment
		(start 395.427708 -220.727778)
		(end 396.16253 -220.726762)
		(width 0.20066)
		(layer "F.Cu")
		(net "M_E_CPU0_SB_DQ<16>")
	)
	(segment
		(start 409.185872 -213.22919)
		(end 409.185872 -213.357206)
		(width 0.20066)
		(layer "F.Cu")
		(net "M_E_CPU0_SB_DQ<16>")
	)
	(segment
		(start 414.297114 -213.46668)
		(end 412.727902 -213.46668)
		(width 0.20066)
		(layer "F.Cu")
		(net "M_E_CPU0_SB_DQ<16>")
	)
	(segment
		(start 408.754834 -213.788244)
		(end 407.897076 -213.788244)
		(width 0.20066)
		(layer "F.Cu")
		(net "M_E_CPU0_SB_DQ<16>")
	)
	(segment
		(start 384.95478 -234.69219)
		(end 384.860546 -234.919774)
		(width 0.088646)
		(layer "F.Cu")
		(net "M_E_CPU0_SB_DQ<16>")
	)
	(segment
		(start 401.744942 -214.173308)
		(end 400.252946 -215.665304)
		(width 0.20066)
		(layer "F.Cu")
		(net "M_E_CPU0_SB_DQ<16>")
	)
	(segment
		(start 399.969228 -215.665304)
		(end 399.76806 -215.464136)
		(width 0.20066)
		(layer "F.Cu")
		(net "M_E_CPU0_SB_DQ<16>")
	)
	(segment
		(start 387.186678 -235.35767)
		(end 387.546342 -235.35767)
		(width 0.088646)
		(layer "F.Cu")
		(net "M_E_CPU0_SB_DQ<16>")
	)
	(segment
		(start 409.831794 -213.02853)
		(end 409.386532 -213.02853)
		(width 0.20066)
		(layer "F.Cu")
		(net "M_E_CPU0_SB_DQ<16>")
	)
	(segment
		(start 412.727902 -213.46668)
		(end 412.727648 -213.466934)
		(width 0.20066)
		(layer "F.Cu")
		(net "M_E_CPU0_SB_DQ<16>")
	)
	(segment
		(start 411.863794 -213.027006)
		(end 411.849062 -213.041738)
		(width 0.1016)
		(layer "F.Cu")
		(net "M_E_CPU0_SB_DQ<16>")
	)
	(segment
		(start 395.277848 -220.877384)
		(end 395.278102 -220.877384)
		(width 0.1016)
		(layer "F.Cu")
		(net "M_E_CPU0_SB_DQ<16>")
	)
	(arc
		(start 386.328158 -235.051854)
		(mid 386.371729 -235.041925)
		(end 386.416296 -235.038646)
		(width 0.088646)
		(layer "F.Cu")
		(net "M_E_CPU0_SB_DQ<16>")
	)
	(arc
		(start 386.135626 -235.16844)
		(mid 386.224784 -235.098416)
		(end 386.328158 -235.051854)
		(width 0.088646)
		(layer "F.Cu")
		(net "M_E_CPU0_SB_DQ<16>")
	)
	(arc
		(start 386.011166 -235.220002)
		(mid 386.078552 -235.206656)
		(end 386.135626 -235.16844)
		(width 0.088646)
		(layer "F.Cu")
		(net "M_E_CPU0_SB_DQ<16>")
	)
	(segment
		(start 395.47038 -229.29088)
		(end 395.47038 -223.82226)
		(width 0.1016)
		(layer "F.Cu")
		(net "M_E_CPU0_SB_DQ<15>")
	)
	(segment
		(start 407.753566 -214.741506)
		(end 407.763726 -214.751666)
		(width 0.1016)
		(layer "F.Cu")
		(net "M_E_CPU0_SB_DQ<15>")
	)
	(segment
		(start 417.07562 -214.316564)
		(end 416.823652 -214.064596)
		(width 0.20066)
		(layer "F.Cu")
		(net "M_E_CPU0_SB_DQ<15>")
	)
	(segment
		(start 416.004756 -214.757508)
		(end 415.307526 -214.757508)
		(width 0.20066)
		(layer "F.Cu")
		(net "M_E_CPU0_SB_DQ<15>")
	)
	(segment
		(start 413.275526 -214.752174)
		(end 412.980632 -214.752174)
		(width 0.20066)
		(layer "F.Cu")
		(net "M_E_CPU0_SB_DQ<15>")
	)
	(segment
		(start 395.47038 -223.82226)
		(end 395.692884 -223.599756)
		(width 0.1016)
		(layer "F.Cu")
		(net "M_E_CPU0_SB_DQ<15>")
	)
	(segment
		(start 386.834126 -235.754672)
		(end 388.182866 -235.754672)
		(width 0.088646)
		(layer "F.Cu")
		(net "M_E_CPU0_SB_DQ<15>")
	)
	(segment
		(start 418.397182 -214.316564)
		(end 417.07562 -214.316564)
		(width 0.20066)
		(layer "F.Cu")
		(net "M_E_CPU0_SB_DQ<15>")
	)
	(segment
		(start 388.553452 -235.384086)
		(end 389.043164 -235.384086)
		(width 0.088646)
		(layer "F.Cu")
		(net "M_E_CPU0_SB_DQ<15>")
	)
	(segment
		(start 415.307526 -214.757508)
		(end 415.291524 -214.741506)
		(width 0.1016)
		(layer "F.Cu")
		(net "M_E_CPU0_SB_DQ<15>")
	)
	(segment
		(start 395.692884 -222.46209)
		(end 403.394672 -214.760302)
		(width 0.20066)
		(layer "F.Cu")
		(net "M_E_CPU0_SB_DQ<15>")
	)
	(segment
		(start 408.709622 -214.751666)
		(end 409.144724 -214.316564)
		(width 0.20066)
		(layer "F.Cu")
		(net "M_E_CPU0_SB_DQ<15>")
	)
	(segment
		(start 416.439604 -214.064596)
		(end 416.205416 -214.298784)
		(width 0.20066)
		(layer "F.Cu")
		(net "M_E_CPU0_SB_DQ<15>")
	)
	(segment
		(start 416.823652 -214.064596)
		(end 416.439604 -214.064596)
		(width 0.20066)
		(layer "F.Cu")
		(net "M_E_CPU0_SB_DQ<15>")
	)
	(segment
		(start 405.731726 -214.760302)
		(end 405.736552 -214.760302)
		(width 0.101854)
		(layer "F.Cu")
		(net "M_E_CPU0_SB_DQ<15>")
	)
	(segment
		(start 412.980632 -214.752174)
		(end 412.545022 -214.316564)
		(width 0.20066)
		(layer "F.Cu")
		(net "M_E_CPU0_SB_DQ<15>")
	)
	(segment
		(start 405.736552 -214.760302)
		(end 405.755348 -214.741506)
		(width 0.1016)
		(layer "F.Cu")
		(net "M_E_CPU0_SB_DQ<15>")
	)
	(segment
		(start 416.205416 -214.298784)
		(end 416.205416 -214.556848)
		(width 0.20066)
		(layer "F.Cu")
		(net "M_E_CPU0_SB_DQ<15>")
	)
	(segment
		(start 413.32023 -214.741506)
		(end 413.309562 -214.752174)
		(width 0.101854)
		(layer "F.Cu")
		(net "M_E_CPU0_SB_DQ<15>")
	)
	(segment
		(start 403.394672 -214.760302)
		(end 405.731726 -214.760302)
		(width 0.20066)
		(layer "F.Cu")
		(net "M_E_CPU0_SB_DQ<15>")
	)
	(segment
		(start 413.309562 -214.752174)
		(end 413.275526 -214.752174)
		(width 0.101854)
		(layer "F.Cu")
		(net "M_E_CPU0_SB_DQ<15>")
	)
	(segment
		(start 407.763726 -214.751666)
		(end 408.709622 -214.751666)
		(width 0.20066)
		(layer "F.Cu")
		(net "M_E_CPU0_SB_DQ<15>")
	)
	(segment
		(start 388.182866 -235.754672)
		(end 388.553452 -235.384086)
		(width 0.088646)
		(layer "F.Cu")
		(net "M_E_CPU0_SB_DQ<15>")
	)
	(segment
		(start 385.894834 -236.319822)
		(end 386.14604 -236.215682)
		(width 0.088646)
		(layer "F.Cu")
		(net "M_E_CPU0_SB_DQ<15>")
	)
	(segment
		(start 389.043164 -235.384086)
		(end 389.377174 -235.384086)
		(width 0.1016)
		(layer "F.Cu")
		(net "M_E_CPU0_SB_DQ<15>")
	)
	(segment
		(start 416.205416 -214.556848)
		(end 416.004756 -214.757508)
		(width 0.20066)
		(layer "F.Cu")
		(net "M_E_CPU0_SB_DQ<15>")
	)
	(segment
		(start 405.755348 -214.741506)
		(end 407.753566 -214.741506)
		(width 0.1016)
		(layer "F.Cu")
		(net "M_E_CPU0_SB_DQ<15>")
	)
	(segment
		(start 409.144724 -214.316564)
		(end 410.853382 -214.316564)
		(width 0.20066)
		(layer "F.Cu")
		(net "M_E_CPU0_SB_DQ<15>")
	)
	(segment
		(start 395.692884 -223.599756)
		(end 395.692884 -223.328992)
		(width 0.1016)
		(layer "F.Cu")
		(net "M_E_CPU0_SB_DQ<15>")
	)
	(segment
		(start 395.692884 -223.328992)
		(end 395.692884 -222.46209)
		(width 0.20066)
		(layer "F.Cu")
		(net "M_E_CPU0_SB_DQ<15>")
	)
	(segment
		(start 389.377174 -235.384086)
		(end 395.47038 -229.29088)
		(width 0.1016)
		(layer "F.Cu")
		(net "M_E_CPU0_SB_DQ<15>")
	)
	(segment
		(start 412.545022 -214.316564)
		(end 410.853382 -214.316564)
		(width 0.20066)
		(layer "F.Cu")
		(net "M_E_CPU0_SB_DQ<15>")
	)
	(segment
		(start 415.291524 -214.741506)
		(end 413.32023 -214.741506)
		(width 0.1016)
		(layer "F.Cu")
		(net "M_E_CPU0_SB_DQ<15>")
	)
	(segment
		(start 386.14604 -236.215682)
		(end 386.387086 -235.974636)
		(width 0.088646)
		(layer "F.Cu")
		(net "M_E_CPU0_SB_DQ<15>")
	)
	(arc
		(start 386.387086 -235.974636)
		(mid 386.459793 -235.896754)
		(end 386.545836 -235.83392)
		(width 0.088646)
		(layer "F.Cu")
		(net "M_E_CPU0_SB_DQ<15>")
	)
	(arc
		(start 386.545836 -235.83392)
		(mid 386.666943 -235.779939)
		(end 386.797296 -235.755688)
		(width 0.088646)
		(layer "F.Cu")
		(net "M_E_CPU0_SB_DQ<15>")
	)
	(arc
		(start 386.797296 -235.755688)
		(mid 386.815703 -235.754878)
		(end 386.834126 -235.754672)
		(width 0.088646)
		(layer "F.Cu")
		(net "M_E_CPU0_SB_DQ<15>")
	)
	(segment
		(start 407.968704 -216.455752)
		(end 408.574494 -216.455752)
		(width 0.20066)
		(layer "F.Cu")
		(net "M_E_CPU0_SB_DQ<14>")
	)
	(segment
		(start 415.284666 -216.455244)
		(end 415.27095 -216.441528)
		(width 0.1016)
		(layer "F.Cu")
		(net "M_E_CPU0_SB_DQ<14>")
	)
	(segment
		(start 397.802862 -222.83166)
		(end 399.193766 -221.440756)
		(width 0.20066)
		(layer "F.Cu")
		(net "M_E_CPU0_SB_DQ<14>")
	)
	(segment
		(start 396.07998 -229.543864)
		(end 396.07998 -226.17811)
		(width 0.1016)
		(layer "F.Cu")
		(net "M_E_CPU0_SB_DQ<14>")
	)
	(segment
		(start 416.823652 -215.764618)
		(end 416.439604 -215.764618)
		(width 0.20066)
		(layer "F.Cu")
		(net "M_E_CPU0_SB_DQ<14>")
	)
	(segment
		(start 415.27095 -216.441528)
		(end 413.2961 -216.441528)
		(width 0.1016)
		(layer "F.Cu")
		(net "M_E_CPU0_SB_DQ<14>")
	)
	(segment
		(start 403.833076 -216.209626)
		(end 404.783798 -216.209626)
		(width 0.20066)
		(layer "F.Cu")
		(net "M_E_CPU0_SB_DQ<14>")
	)
	(segment
		(start 416.205416 -216.254584)
		(end 416.004756 -216.455244)
		(width 0.20066)
		(layer "F.Cu")
		(net "M_E_CPU0_SB_DQ<14>")
	)
	(segment
		(start 386.364734 -237.133892)
		(end 387.475984 -237.133892)
		(width 0.088646)
		(layer "F.Cu")
		(net "M_E_CPU0_SB_DQ<14>")
	)
	(segment
		(start 418.397182 -216.016586)
		(end 417.07562 -216.016586)
		(width 0.20066)
		(layer "F.Cu")
		(net "M_E_CPU0_SB_DQ<14>")
	)
	(segment
		(start 399.193766 -221.440756)
		(end 399.193766 -220.848936)
		(width 0.20066)
		(layer "F.Cu")
		(net "M_E_CPU0_SB_DQ<14>")
	)
	(segment
		(start 417.07562 -216.016586)
		(end 416.823652 -215.764618)
		(width 0.20066)
		(layer "F.Cu")
		(net "M_E_CPU0_SB_DQ<14>")
	)
	(segment
		(start 388.61619 -235.993686)
		(end 389.043164 -235.993686)
		(width 0.088646)
		(layer "F.Cu")
		(net "M_E_CPU0_SB_DQ<14>")
	)
	(segment
		(start 397.802862 -223.305116)
		(end 397.802862 -222.83166)
		(width 0.20066)
		(layer "F.Cu")
		(net "M_E_CPU0_SB_DQ<14>")
	)
	(segment
		(start 398.15516 -224.10293)
		(end 398.15516 -223.657414)
		(width 0.20066)
		(layer "F.Cu")
		(net "M_E_CPU0_SB_DQ<14>")
	)
	(segment
		(start 396.07998 -226.17811)
		(end 396.780004 -225.478086)
		(width 0.1016)
		(layer "F.Cu")
		(net "M_E_CPU0_SB_DQ<14>")
	)
	(segment
		(start 415.307526 -216.455244)
		(end 415.284666 -216.455244)
		(width 0.101854)
		(layer "F.Cu")
		(net "M_E_CPU0_SB_DQ<14>")
	)
	(segment
		(start 398.15516 -223.657414)
		(end 397.802862 -223.305116)
		(width 0.20066)
		(layer "F.Cu")
		(net "M_E_CPU0_SB_DQ<14>")
	)
	(segment
		(start 413.27959 -216.458038)
		(end 413.275526 -216.458038)
		(width 0.101854)
		(layer "F.Cu")
		(net "M_E_CPU0_SB_DQ<14>")
	)
	(segment
		(start 405.736552 -216.441782)
		(end 407.763726 -216.441782)
		(width 0.1016)
		(layer "F.Cu")
		(net "M_E_CPU0_SB_DQ<14>")
	)
	(segment
		(start 387.475984 -237.133892)
		(end 388.61619 -235.993686)
		(width 0.088646)
		(layer "F.Cu")
		(net "M_E_CPU0_SB_DQ<14>")
	)
	(segment
		(start 399.193766 -220.848936)
		(end 403.833076 -216.209626)
		(width 0.20066)
		(layer "F.Cu")
		(net "M_E_CPU0_SB_DQ<14>")
	)
	(segment
		(start 408.574494 -216.455752)
		(end 409.01366 -216.016586)
		(width 0.20066)
		(layer "F.Cu")
		(net "M_E_CPU0_SB_DQ<14>")
	)
	(segment
		(start 416.004756 -216.455244)
		(end 415.307526 -216.455244)
		(width 0.20066)
		(layer "F.Cu")
		(net "M_E_CPU0_SB_DQ<14>")
	)
	(segment
		(start 396.780004 -225.478086)
		(end 398.15516 -224.10293)
		(width 0.20066)
		(layer "F.Cu")
		(net "M_E_CPU0_SB_DQ<14>")
	)
	(segment
		(start 409.01366 -216.016586)
		(end 410.853382 -216.016586)
		(width 0.20066)
		(layer "F.Cu")
		(net "M_E_CPU0_SB_DQ<14>")
	)
	(segment
		(start 405.724868 -216.453466)
		(end 405.731726 -216.446608)
		(width 0.20066)
		(layer "F.Cu")
		(net "M_E_CPU0_SB_DQ<14>")
	)
	(segment
		(start 405.731726 -216.446608)
		(end 405.736552 -216.441782)
		(width 0.101854)
		(layer "F.Cu")
		(net "M_E_CPU0_SB_DQ<14>")
	)
	(segment
		(start 412.582614 -216.016586)
		(end 410.853382 -216.016586)
		(width 0.20066)
		(layer "F.Cu")
		(net "M_E_CPU0_SB_DQ<14>")
	)
	(segment
		(start 404.783798 -216.209626)
		(end 405.027638 -216.453466)
		(width 0.20066)
		(layer "F.Cu")
		(net "M_E_CPU0_SB_DQ<14>")
	)
	(segment
		(start 416.205416 -215.998806)
		(end 416.205416 -216.254584)
		(width 0.20066)
		(layer "F.Cu")
		(net "M_E_CPU0_SB_DQ<14>")
	)
	(segment
		(start 407.954734 -216.441782)
		(end 407.968704 -216.455752)
		(width 0.20066)
		(layer "F.Cu")
		(net "M_E_CPU0_SB_DQ<14>")
	)
	(segment
		(start 413.275526 -216.458038)
		(end 413.024066 -216.458038)
		(width 0.20066)
		(layer "F.Cu")
		(net "M_E_CPU0_SB_DQ<14>")
	)
	(segment
		(start 413.2961 -216.441528)
		(end 413.27959 -216.458038)
		(width 0.1016)
		(layer "F.Cu")
		(net "M_E_CPU0_SB_DQ<14>")
	)
	(segment
		(start 405.027638 -216.453466)
		(end 405.724868 -216.453466)
		(width 0.20066)
		(layer "F.Cu")
		(net "M_E_CPU0_SB_DQ<14>")
	)
	(segment
		(start 389.630158 -235.993686)
		(end 396.07998 -229.543864)
		(width 0.1016)
		(layer "F.Cu")
		(net "M_E_CPU0_SB_DQ<14>")
	)
	(segment
		(start 413.024066 -216.458038)
		(end 412.582614 -216.016586)
		(width 0.20066)
		(layer "F.Cu")
		(net "M_E_CPU0_SB_DQ<14>")
	)
	(segment
		(start 407.763726 -216.441782)
		(end 407.954734 -216.441782)
		(width 0.20066)
		(layer "F.Cu")
		(net "M_E_CPU0_SB_DQ<14>")
	)
	(segment
		(start 389.043164 -235.993686)
		(end 389.630158 -235.993686)
		(width 0.1016)
		(layer "F.Cu")
		(net "M_E_CPU0_SB_DQ<14>")
	)
	(segment
		(start 416.439604 -215.764618)
		(end 416.205416 -215.998806)
		(width 0.20066)
		(layer "F.Cu")
		(net "M_E_CPU0_SB_DQ<14>")
	)
	(segment
		(start 396.404084 -223.313244)
		(end 396.404084 -222.716598)
		(width 0.20066)
		(layer "F.Cu")
		(net "M_E_CPU0_SB_DQ<13>")
	)
	(segment
		(start 388.523988 -235.688886)
		(end 389.043164 -235.688886)
		(width 0.088646)
		(layer "F.Cu")
		(net "M_E_CPU0_SB_DQ<13>")
	)
	(segment
		(start 397.31061 -223.714564)
		(end 397.10995 -223.513904)
		(width 0.20066)
		(layer "F.Cu")
		(net "M_E_CPU0_SB_DQ<13>")
	)
	(segment
		(start 389.043164 -235.688886)
		(end 389.503666 -235.688886)
		(width 0.1016)
		(layer "F.Cu")
		(net "M_E_CPU0_SB_DQ<13>")
	)
	(segment
		(start 411.864556 -214.735918)
		(end 411.863794 -214.73668)
		(width 0.20066)
		(layer "F.Cu")
		(net "M_E_CPU0_SB_DQ<13>")
	)
	(segment
		(start 396.689326 -224.199704)
		(end 397.10995 -224.199704)
		(width 0.20066)
		(layer "F.Cu")
		(net "M_E_CPU0_SB_DQ<13>")
	)
	(segment
		(start 396.396972 -224.492058)
		(end 396.689326 -224.199704)
		(width 0.20066)
		(layer "F.Cu")
		(net "M_E_CPU0_SB_DQ<13>")
	)
	(segment
		(start 395.77518 -225.56597)
		(end 396.142718 -225.198432)
		(width 0.1016)
		(layer "F.Cu")
		(net "M_E_CPU0_SB_DQ<13>")
	)
	(segment
		(start 409.831794 -214.726266)
		(end 409.386532 -214.726266)
		(width 0.20066)
		(layer "F.Cu")
		(net "M_E_CPU0_SB_DQ<13>")
	)
	(segment
		(start 409.185872 -214.926926)
		(end 409.185872 -215.227408)
		(width 0.20066)
		(layer "F.Cu")
		(net "M_E_CPU0_SB_DQ<13>")
	)
	(segment
		(start 396.142718 -225.198432)
		(end 396.142718 -225.198178)
		(width 0.1016)
		(layer "F.Cu")
		(net "M_E_CPU0_SB_DQ<13>")
	)
	(segment
		(start 396.604744 -223.513904)
		(end 396.404084 -223.313244)
		(width 0.20066)
		(layer "F.Cu")
		(net "M_E_CPU0_SB_DQ<13>")
	)
	(segment
		(start 409.864814 -214.74176)
		(end 409.847288 -214.74176)
		(width 0.101854)
		(layer "F.Cu")
		(net "M_E_CPU0_SB_DQ<13>")
	)
	(segment
		(start 398.337278 -220.783404)
		(end 403.580346 -215.540336)
		(width 0.20066)
		(layer "F.Cu")
		(net "M_E_CPU0_SB_DQ<13>")
	)
	(segment
		(start 396.321534 -225.019362)
		(end 396.396972 -224.943924)
		(width 0.20066)
		(layer "F.Cu")
		(net "M_E_CPU0_SB_DQ<13>")
	)
	(segment
		(start 398.337278 -221.326456)
		(end 398.337278 -220.783404)
		(width 0.20066)
		(layer "F.Cu")
		(net "M_E_CPU0_SB_DQ<13>")
	)
	(segment
		(start 397.580612 -221.54007)
		(end 398.123664 -221.54007)
		(width 0.20066)
		(layer "F.Cu")
		(net "M_E_CPU0_SB_DQ<13>")
	)
	(segment
		(start 397.153384 -222.51035)
		(end 397.366998 -222.296736)
		(width 0.20066)
		(layer "F.Cu")
		(net "M_E_CPU0_SB_DQ<13>")
	)
	(segment
		(start 388.267956 -235.944918)
		(end 388.523988 -235.688886)
		(width 0.088646)
		(layer "F.Cu")
		(net "M_E_CPU0_SB_DQ<13>")
	)
	(segment
		(start 409.847288 -214.74176)
		(end 409.831794 -214.726266)
		(width 0.101854)
		(layer "F.Cu")
		(net "M_E_CPU0_SB_DQ<13>")
	)
	(segment
		(start 403.580346 -215.540336)
		(end 405.427434 -215.540336)
		(width 0.20066)
		(layer "F.Cu")
		(net "M_E_CPU0_SB_DQ<13>")
	)
	(segment
		(start 397.366998 -221.753684)
		(end 397.580612 -221.54007)
		(width 0.20066)
		(layer "F.Cu")
		(net "M_E_CPU0_SB_DQ<13>")
	)
	(segment
		(start 408.298904 -215.166702)
		(end 406.753314 -215.166702)
		(width 0.20066)
		(layer "F.Cu")
		(net "M_E_CPU0_SB_DQ<13>")
	)
	(segment
		(start 414.297114 -215.166702)
		(end 412.727394 -215.166702)
		(width 0.20066)
		(layer "F.Cu")
		(net "M_E_CPU0_SB_DQ<13>")
	)
	(segment
		(start 389.503666 -235.688886)
		(end 395.77518 -229.417372)
		(width 0.1016)
		(layer "F.Cu")
		(net "M_E_CPU0_SB_DQ<13>")
	)
	(segment
		(start 385.265676 -236.319822)
		(end 385.33324 -236.387386)
		(width 0.088646)
		(layer "F.Cu")
		(net "M_E_CPU0_SB_DQ<13>")
	)
	(segment
		(start 396.142718 -225.198178)
		(end 396.321534 -225.019362)
		(width 0.1016)
		(layer "F.Cu")
		(net "M_E_CPU0_SB_DQ<13>")
	)
	(segment
		(start 409.022296 -215.390984)
		(end 408.523186 -215.390984)
		(width 0.20066)
		(layer "F.Cu")
		(net "M_E_CPU0_SB_DQ<13>")
	)
	(segment
		(start 384.95478 -236.319822)
		(end 385.265676 -236.319822)
		(width 0.088646)
		(layer "F.Cu")
		(net "M_E_CPU0_SB_DQ<13>")
	)
	(segment
		(start 398.123664 -221.54007)
		(end 398.337278 -221.326456)
		(width 0.20066)
		(layer "F.Cu")
		(net "M_E_CPU0_SB_DQ<13>")
	)
	(segment
		(start 408.523186 -215.390984)
		(end 408.298904 -215.166702)
		(width 0.20066)
		(layer "F.Cu")
		(net "M_E_CPU0_SB_DQ<13>")
	)
	(segment
		(start 412.29661 -214.735918)
		(end 411.864556 -214.735918)
		(width 0.20066)
		(layer "F.Cu")
		(net "M_E_CPU0_SB_DQ<13>")
	)
	(segment
		(start 411.837632 -214.73668)
		(end 411.832552 -214.74176)
		(width 0.1016)
		(layer "F.Cu")
		(net "M_E_CPU0_SB_DQ<13>")
	)
	(segment
		(start 397.10995 -224.199704)
		(end 397.31061 -223.999044)
		(width 0.20066)
		(layer "F.Cu")
		(net "M_E_CPU0_SB_DQ<13>")
	)
	(segment
		(start 405.427434 -215.540336)
		(end 405.801068 -215.166702)
		(width 0.20066)
		(layer "F.Cu")
		(net "M_E_CPU0_SB_DQ<13>")
	)
	(segment
		(start 411.832552 -214.74176)
		(end 409.864814 -214.74176)
		(width 0.1016)
		(layer "F.Cu")
		(net "M_E_CPU0_SB_DQ<13>")
	)
	(segment
		(start 386.459984 -236.338364)
		(end 386.459984 -236.311186)
		(width 0.088646)
		(layer "F.Cu")
		(net "M_E_CPU0_SB_DQ<13>")
	)
	(segment
		(start 412.727394 -215.166702)
		(end 412.29661 -214.735918)
		(width 0.20066)
		(layer "F.Cu")
		(net "M_E_CPU0_SB_DQ<13>")
	)
	(segment
		(start 396.404084 -222.716598)
		(end 396.610332 -222.51035)
		(width 0.20066)
		(layer "F.Cu")
		(net "M_E_CPU0_SB_DQ<13>")
	)
	(segment
		(start 411.863794 -214.73668)
		(end 411.837632 -214.73668)
		(width 0.101854)
		(layer "F.Cu")
		(net "M_E_CPU0_SB_DQ<13>")
	)
	(segment
		(start 409.386532 -214.726266)
		(end 409.185872 -214.926926)
		(width 0.20066)
		(layer "F.Cu")
		(net "M_E_CPU0_SB_DQ<13>")
	)
	(segment
		(start 397.10995 -223.513904)
		(end 396.604744 -223.513904)
		(width 0.20066)
		(layer "F.Cu")
		(net "M_E_CPU0_SB_DQ<13>")
	)
	(segment
		(start 409.185872 -215.227408)
		(end 409.022296 -215.390984)
		(width 0.20066)
		(layer "F.Cu")
		(net "M_E_CPU0_SB_DQ<13>")
	)
	(segment
		(start 405.801068 -215.166702)
		(end 406.753314 -215.166702)
		(width 0.20066)
		(layer "F.Cu")
		(net "M_E_CPU0_SB_DQ<13>")
	)
	(segment
		(start 397.366998 -222.296736)
		(end 397.366998 -221.753684)
		(width 0.20066)
		(layer "F.Cu")
		(net "M_E_CPU0_SB_DQ<13>")
	)
	(segment
		(start 395.77518 -229.417372)
		(end 395.77518 -225.56597)
		(width 0.1016)
		(layer "F.Cu")
		(net "M_E_CPU0_SB_DQ<13>")
	)
	(segment
		(start 397.31061 -223.999044)
		(end 397.31061 -223.714564)
		(width 0.20066)
		(layer "F.Cu")
		(net "M_E_CPU0_SB_DQ<13>")
	)
	(segment
		(start 396.396972 -224.943924)
		(end 396.396972 -224.492058)
		(width 0.20066)
		(layer "F.Cu")
		(net "M_E_CPU0_SB_DQ<13>")
	)
	(segment
		(start 386.83438 -235.944918)
		(end 388.267956 -235.944918)
		(width 0.088646)
		(layer "F.Cu")
		(net "M_E_CPU0_SB_DQ<13>")
	)
	(segment
		(start 396.610332 -222.51035)
		(end 397.153384 -222.51035)
		(width 0.20066)
		(layer "F.Cu")
		(net "M_E_CPU0_SB_DQ<13>")
	)
	(arc
		(start 386.647182 -235.995464)
		(mid 386.737454 -235.957865)
		(end 386.83438 -235.944918)
		(width 0.088646)
		(layer "F.Cu")
		(net "M_E_CPU0_SB_DQ<13>")
	)
	(arc
		(start 386.459984 -236.311186)
		(mid 386.512254 -236.128821)
		(end 386.647182 -235.995464)
		(width 0.088646)
		(layer "F.Cu")
		(net "M_E_CPU0_SB_DQ<13>")
	)
	(arc
		(start 385.612132 -236.809534)
		(mid 385.894834 -236.885276)
		(end 386.177536 -236.809534)
		(width 0.088646)
		(layer "F.Cu")
		(net "M_E_CPU0_SB_DQ<13>")
	)
	(arc
		(start 385.33324 -236.387386)
		(mid 385.422805 -236.631423)
		(end 385.612132 -236.809534)
		(width 0.088646)
		(layer "F.Cu")
		(net "M_E_CPU0_SB_DQ<13>")
	)
	(arc
		(start 386.177536 -236.809534)
		(mid 386.379822 -236.610553)
		(end 386.459984 -236.338364)
		(width 0.088646)
		(layer "F.Cu")
		(net "M_E_CPU0_SB_DQ<13>")
	)
	(segment
		(start 385.689094 -237.51413)
		(end 385.689094 -237.393226)
		(width 0.088646)
		(layer "F.Cu")
		(net "M_E_CPU0_SB_DQ<12>")
	)
	(segment
		(start 408.917902 -217.095832)
		(end 408.701748 -217.095832)
		(width 0.20066)
		(layer "F.Cu")
		(net "M_E_CPU0_SB_DQ<12>")
	)
	(segment
		(start 386.082794 -237.456726)
		(end 386.158994 -237.532926)
		(width 0.088646)
		(layer "F.Cu")
		(net "M_E_CPU0_SB_DQ<12>")
	)
	(segment
		(start 385.541774 -237.588806)
		(end 385.557014 -237.588806)
		(width 0.088646)
		(layer "F.Cu")
		(net "M_E_CPU0_SB_DQ<12>")
	)
	(segment
		(start 399.73377 -223.09582)
		(end 399.449798 -223.09582)
		(width 0.20066)
		(layer "F.Cu")
		(net "M_E_CPU0_SB_DQ<12>")
	)
	(segment
		(start 412.841186 -216.866724)
		(end 412.398972 -216.42451)
		(width 0.20066)
		(layer "F.Cu")
		(net "M_E_CPU0_SB_DQ<12>")
	)
	(segment
		(start 411.863794 -216.42451)
		(end 411.846522 -216.441782)
		(width 0.101854)
		(layer "F.Cu")
		(net "M_E_CPU0_SB_DQ<12>")
	)
	(segment
		(start 398.85366 -223.407986)
		(end 398.652492 -223.206818)
		(width 0.20066)
		(layer "F.Cu")
		(net "M_E_CPU0_SB_DQ<12>")
	)
	(segment
		(start 409.831794 -216.428066)
		(end 409.28925 -216.428066)
		(width 0.20066)
		(layer "F.Cu")
		(net "M_E_CPU0_SB_DQ<12>")
	)
	(segment
		(start 398.133062 -225.382836)
		(end 399.934938 -223.58096)
		(width 0.20066)
		(layer "F.Cu")
		(net "M_E_CPU0_SB_DQ<12>")
	)
	(segment
		(start 412.398972 -216.42451)
		(end 411.863794 -216.42451)
		(width 0.20066)
		(layer "F.Cu")
		(net "M_E_CPU0_SB_DQ<12>")
	)
	(segment
		(start 399.137632 -223.407986)
		(end 398.85366 -223.407986)
		(width 0.20066)
		(layer "F.Cu")
		(net "M_E_CPU0_SB_DQ<12>")
	)
	(segment
		(start 408.701748 -217.095832)
		(end 408.47264 -216.866724)
		(width 0.20066)
		(layer "F.Cu")
		(net "M_E_CPU0_SB_DQ<12>")
	)
	(segment
		(start 385.968494 -237.266226)
		(end 386.082794 -237.380526)
		(width 0.088646)
		(layer "F.Cu")
		(net "M_E_CPU0_SB_DQ<12>")
	)
	(segment
		(start 414.297114 -216.866724)
		(end 412.841186 -216.866724)
		(width 0.20066)
		(layer "F.Cu")
		(net "M_E_CPU0_SB_DQ<12>")
	)
	(segment
		(start 409.878276 -216.441782)
		(end 409.86456 -216.428066)
		(width 0.1016)
		(layer "F.Cu")
		(net "M_E_CPU0_SB_DQ<12>")
	)
	(segment
		(start 386.629402 -237.39856)
		(end 387.489446 -237.39856)
		(width 0.088646)
		(layer "F.Cu")
		(net "M_E_CPU0_SB_DQ<12>")
	)
	(segment
		(start 388.590028 -236.298486)
		(end 389.043164 -236.298486)
		(width 0.088646)
		(layer "F.Cu")
		(net "M_E_CPU0_SB_DQ<12>")
	)
	(segment
		(start 396.38478 -229.670356)
		(end 396.38478 -226.882706)
		(width 0.1016)
		(layer "F.Cu")
		(net "M_E_CPU0_SB_DQ<12>")
	)
	(segment
		(start 385.816094 -237.266226)
		(end 385.968494 -237.266226)
		(width 0.088646)
		(layer "F.Cu")
		(net "M_E_CPU0_SB_DQ<12>")
	)
	(segment
		(start 397.284702 -225.982784)
		(end 397.88465 -225.382836)
		(width 0.20066)
		(layer "F.Cu")
		(net "M_E_CPU0_SB_DQ<12>")
	)
	(segment
		(start 389.75665 -236.298486)
		(end 396.38478 -229.670356)
		(width 0.1016)
		(layer "F.Cu")
		(net "M_E_CPU0_SB_DQ<12>")
	)
	(segment
		(start 398.652492 -222.922846)
		(end 399.163794 -222.411544)
		(width 0.20066)
		(layer "F.Cu")
		(net "M_E_CPU0_SB_DQ<12>")
	)
	(segment
		(start 389.043164 -236.298486)
		(end 389.75665 -236.298486)
		(width 0.1016)
		(layer "F.Cu")
		(net "M_E_CPU0_SB_DQ<12>")
	)
	(segment
		(start 386.277866 -237.529116)
		(end 386.428996 -237.5027)
		(width 0.088646)
		(layer "F.Cu")
		(net "M_E_CPU0_SB_DQ<12>")
	)
	(segment
		(start 398.652492 -223.206818)
		(end 398.652492 -222.922846)
		(width 0.20066)
		(layer "F.Cu")
		(net "M_E_CPU0_SB_DQ<12>")
	)
	(segment
		(start 399.934938 -223.296988)
		(end 399.73377 -223.09582)
		(width 0.20066)
		(layer "F.Cu")
		(net "M_E_CPU0_SB_DQ<12>")
	)
	(segment
		(start 408.47264 -216.866724)
		(end 406.753314 -216.866724)
		(width 0.20066)
		(layer "F.Cu")
		(net "M_E_CPU0_SB_DQ<12>")
	)
	(segment
		(start 387.489446 -237.39856)
		(end 388.589774 -236.298232)
		(width 0.088646)
		(layer "F.Cu")
		(net "M_E_CPU0_SB_DQ<12>")
	)
	(segment
		(start 397.88465 -225.382836)
		(end 398.133062 -225.382836)
		(width 0.20066)
		(layer "F.Cu")
		(net "M_E_CPU0_SB_DQ<12>")
	)
	(segment
		(start 399.734532 -222.411544)
		(end 399.935192 -222.210884)
		(width 0.20066)
		(layer "F.Cu")
		(net "M_E_CPU0_SB_DQ<12>")
	)
	(segment
		(start 409.28925 -216.428066)
		(end 409.088336 -216.62898)
		(width 0.20066)
		(layer "F.Cu")
		(net "M_E_CPU0_SB_DQ<12>")
	)
	(segment
		(start 385.689094 -237.393226)
		(end 385.816094 -237.266226)
		(width 0.088646)
		(layer "F.Cu")
		(net "M_E_CPU0_SB_DQ<12>")
	)
	(segment
		(start 409.088336 -216.62898)
		(end 409.088336 -216.925398)
		(width 0.20066)
		(layer "F.Cu")
		(net "M_E_CPU0_SB_DQ<12>")
	)
	(segment
		(start 399.934938 -223.58096)
		(end 399.934938 -223.296988)
		(width 0.20066)
		(layer "F.Cu")
		(net "M_E_CPU0_SB_DQ<12>")
	)
	(segment
		(start 409.088336 -216.925398)
		(end 408.917902 -217.095832)
		(width 0.20066)
		(layer "F.Cu")
		(net "M_E_CPU0_SB_DQ<12>")
	)
	(segment
		(start 386.082794 -237.380526)
		(end 386.082794 -237.456726)
		(width 0.088646)
		(layer "F.Cu")
		(net "M_E_CPU0_SB_DQ<12>")
	)
	(segment
		(start 411.846522 -216.441782)
		(end 409.878276 -216.441782)
		(width 0.1016)
		(layer "F.Cu")
		(net "M_E_CPU0_SB_DQ<12>")
	)
	(segment
		(start 399.163794 -222.411544)
		(end 399.734532 -222.411544)
		(width 0.20066)
		(layer "F.Cu")
		(net "M_E_CPU0_SB_DQ<12>")
	)
	(segment
		(start 404.091394 -216.866724)
		(end 406.753314 -216.866724)
		(width 0.20066)
		(layer "F.Cu")
		(net "M_E_CPU0_SB_DQ<12>")
	)
	(segment
		(start 385.237736 -237.457996)
		(end 385.396486 -237.549944)
		(width 0.088646)
		(layer "F.Cu")
		(net "M_E_CPU0_SB_DQ<12>")
	)
	(segment
		(start 388.589774 -236.298232)
		(end 388.590028 -236.298486)
		(width 0.088646)
		(layer "F.Cu")
		(net "M_E_CPU0_SB_DQ<12>")
	)
	(segment
		(start 385.64058 -237.562644)
		(end 385.689094 -237.51413)
		(width 0.088646)
		(layer "F.Cu")
		(net "M_E_CPU0_SB_DQ<12>")
	)
	(segment
		(start 396.38478 -226.882706)
		(end 397.284702 -225.982784)
		(width 0.1016)
		(layer "F.Cu")
		(net "M_E_CPU0_SB_DQ<12>")
	)
	(segment
		(start 399.449798 -223.09582)
		(end 399.137632 -223.407986)
		(width 0.20066)
		(layer "F.Cu")
		(net "M_E_CPU0_SB_DQ<12>")
	)
	(segment
		(start 399.935192 -221.022926)
		(end 404.091394 -216.866724)
		(width 0.20066)
		(layer "F.Cu")
		(net "M_E_CPU0_SB_DQ<12>")
	)
	(segment
		(start 386.158994 -237.532926)
		(end 386.232654 -237.532926)
		(width 0.088646)
		(layer "F.Cu")
		(net "M_E_CPU0_SB_DQ<12>")
	)
	(segment
		(start 399.935192 -222.210884)
		(end 399.935192 -221.022926)
		(width 0.20066)
		(layer "F.Cu")
		(net "M_E_CPU0_SB_DQ<12>")
	)
	(segment
		(start 409.86456 -216.428066)
		(end 409.831794 -216.428066)
		(width 0.101854)
		(layer "F.Cu")
		(net "M_E_CPU0_SB_DQ<12>")
	)
	(arc
		(start 386.232654 -237.532926)
		(mid 386.25534 -237.531973)
		(end 386.277866 -237.529116)
		(width 0.088646)
		(layer "F.Cu")
		(net "M_E_CPU0_SB_DQ<12>")
	)
	(arc
		(start 385.396486 -237.549944)
		(mid 385.466568 -237.578955)
		(end 385.541774 -237.588806)
		(width 0.088646)
		(layer "F.Cu")
		(net "M_E_CPU0_SB_DQ<12>")
	)
	(arc
		(start 386.428996 -237.5027)
		(mid 386.537261 -237.466132)
		(end 386.629402 -237.39856)
		(width 0.088646)
		(layer "F.Cu")
		(net "M_E_CPU0_SB_DQ<12>")
	)
	(arc
		(start 384.485134 -237.133892)
		(mid 384.871039 -237.273643)
		(end 385.237736 -237.457996)
		(width 0.088646)
		(layer "F.Cu")
		(net "M_E_CPU0_SB_DQ<12>")
	)
	(arc
		(start 385.557014 -237.588806)
		(mid 385.600784 -237.582074)
		(end 385.64058 -237.562644)
		(width 0.088646)
		(layer "F.Cu")
		(net "M_E_CPU0_SB_DQ<12>")
	)
	(segment
		(start 412.313374 -220.266768)
		(end 410.853382 -220.266768)
		(width 0.20066)
		(layer "F.Cu")
		(net "M_E_CPU0_SB_DQ<11>")
	)
	(segment
		(start 390.38911 -237.822486)
		(end 398.010634 -230.200962)
		(width 0.1016)
		(layer "F.Cu")
		(net "M_E_CPU0_SB_DQ<11>")
	)
	(segment
		(start 400.586956 -228.450902)
		(end 400.586956 -228.16693)
		(width 0.20066)
		(layer "F.Cu")
		(net "M_E_CPU0_SB_DQ<11>")
	)
	(segment
		(start 408.238452 -220.701616)
		(end 408.6733 -220.266768)
		(width 0.20066)
		(layer "F.Cu")
		(net "M_E_CPU0_SB_DQ<11>")
	)
	(segment
		(start 401.758404 -226.995482)
		(end 402.042376 -226.995482)
		(width 0.20066)
		(layer "F.Cu")
		(net "M_E_CPU0_SB_DQ<11>")
	)
	(segment
		(start 386.364734 -238.761524)
		(end 386.36702 -238.76381)
		(width 0.088646)
		(layer "F.Cu")
		(net "M_E_CPU0_SB_DQ<11>")
	)
	(segment
		(start 413.300164 -220.69171)
		(end 413.285686 -220.706188)
		(width 0.1016)
		(layer "F.Cu")
		(net "M_E_CPU0_SB_DQ<11>")
	)
	(segment
		(start 417.07562 -220.266768)
		(end 416.823652 -220.0148)
		(width 0.20066)
		(layer "F.Cu")
		(net "M_E_CPU0_SB_DQ<11>")
	)
	(segment
		(start 398.010634 -230.200962)
		(end 398.010634 -229.774496)
		(width 0.1016)
		(layer "F.Cu")
		(net "M_E_CPU0_SB_DQ<11>")
	)
	(segment
		(start 400.833082 -228.697028)
		(end 400.586956 -228.450902)
		(width 0.20066)
		(layer "F.Cu")
		(net "M_E_CPU0_SB_DQ<11>")
	)
	(segment
		(start 387.776974 -238.76381)
		(end 388.718298 -237.822486)
		(width 0.088646)
		(layer "F.Cu")
		(net "M_E_CPU0_SB_DQ<11>")
	)
	(segment
		(start 416.823652 -220.0148)
		(end 416.439604 -220.0148)
		(width 0.20066)
		(layer "F.Cu")
		(net "M_E_CPU0_SB_DQ<11>")
	)
	(segment
		(start 415.27476 -220.710506)
		(end 415.255964 -220.69171)
		(width 0.101854)
		(layer "F.Cu")
		(net "M_E_CPU0_SB_DQ<11>")
	)
	(segment
		(start 413.275526 -220.706188)
		(end 412.752794 -220.706188)
		(width 0.20066)
		(layer "F.Cu")
		(net "M_E_CPU0_SB_DQ<11>")
	)
	(segment
		(start 403.0853 -226.728782)
		(end 403.0853 -222.83801)
		(width 0.20066)
		(layer "F.Cu")
		(net "M_E_CPU0_SB_DQ<11>")
	)
	(segment
		(start 415.255964 -220.69171)
		(end 413.300164 -220.69171)
		(width 0.1016)
		(layer "F.Cu")
		(net "M_E_CPU0_SB_DQ<11>")
	)
	(segment
		(start 398.010634 -229.774496)
		(end 398.403064 -229.382066)
		(width 0.1016)
		(layer "F.Cu")
		(net "M_E_CPU0_SB_DQ<11>")
	)
	(segment
		(start 399.17751 -229.382066)
		(end 400.432016 -229.382066)
		(width 0.20066)
		(layer "F.Cu")
		(net "M_E_CPU0_SB_DQ<11>")
	)
	(segment
		(start 401.602194 -228.211888)
		(end 401.803362 -228.01072)
		(width 0.20066)
		(layer "F.Cu")
		(net "M_E_CPU0_SB_DQ<11>")
	)
	(segment
		(start 402.042376 -226.995482)
		(end 402.288502 -227.241608)
		(width 0.20066)
		(layer "F.Cu")
		(net "M_E_CPU0_SB_DQ<11>")
	)
	(segment
		(start 412.752794 -220.706188)
		(end 412.313374 -220.266768)
		(width 0.20066)
		(layer "F.Cu")
		(net "M_E_CPU0_SB_DQ<11>")
	)
	(segment
		(start 408.6733 -220.266768)
		(end 410.853382 -220.266768)
		(width 0.20066)
		(layer "F.Cu")
		(net "M_E_CPU0_SB_DQ<11>")
	)
	(segment
		(start 398.403064 -229.382066)
		(end 399.17751 -229.382066)
		(width 0.1016)
		(layer "F.Cu")
		(net "M_E_CPU0_SB_DQ<11>")
	)
	(segment
		(start 402.572474 -227.241608)
		(end 403.0853 -226.728782)
		(width 0.20066)
		(layer "F.Cu")
		(net "M_E_CPU0_SB_DQ<11>")
	)
	(segment
		(start 405.731726 -220.704918)
		(end 405.736552 -220.704918)
		(width 0.101854)
		(layer "F.Cu")
		(net "M_E_CPU0_SB_DQ<11>")
	)
	(segment
		(start 401.072096 -227.965762)
		(end 401.318222 -228.211888)
		(width 0.20066)
		(layer "F.Cu")
		(net "M_E_CPU0_SB_DQ<11>")
	)
	(segment
		(start 416.205416 -220.537024)
		(end 416.031934 -220.710506)
		(width 0.20066)
		(layer "F.Cu")
		(net "M_E_CPU0_SB_DQ<11>")
	)
	(segment
		(start 407.75382 -220.69171)
		(end 407.763726 -220.701616)
		(width 0.1016)
		(layer "F.Cu")
		(net "M_E_CPU0_SB_DQ<11>")
	)
	(segment
		(start 418.397182 -220.266768)
		(end 417.07562 -220.266768)
		(width 0.20066)
		(layer "F.Cu")
		(net "M_E_CPU0_SB_DQ<11>")
	)
	(segment
		(start 405.74976 -220.69171)
		(end 407.75382 -220.69171)
		(width 0.1016)
		(layer "F.Cu")
		(net "M_E_CPU0_SB_DQ<11>")
	)
	(segment
		(start 401.803362 -227.726748)
		(end 401.557236 -227.480622)
		(width 0.20066)
		(layer "F.Cu")
		(net "M_E_CPU0_SB_DQ<11>")
	)
	(segment
		(start 401.803362 -228.01072)
		(end 401.803362 -227.726748)
		(width 0.20066)
		(layer "F.Cu")
		(net "M_E_CPU0_SB_DQ<11>")
	)
	(segment
		(start 405.218392 -220.704918)
		(end 405.731726 -220.704918)
		(width 0.20066)
		(layer "F.Cu")
		(net "M_E_CPU0_SB_DQ<11>")
	)
	(segment
		(start 400.586956 -228.16693)
		(end 400.788124 -227.965762)
		(width 0.20066)
		(layer "F.Cu")
		(net "M_E_CPU0_SB_DQ<11>")
	)
	(segment
		(start 401.318222 -228.211888)
		(end 401.602194 -228.211888)
		(width 0.20066)
		(layer "F.Cu")
		(net "M_E_CPU0_SB_DQ<11>")
	)
	(segment
		(start 416.205416 -220.248988)
		(end 416.205416 -220.537024)
		(width 0.20066)
		(layer "F.Cu")
		(net "M_E_CPU0_SB_DQ<11>")
	)
	(segment
		(start 388.718298 -237.822486)
		(end 388.890764 -237.822486)
		(width 0.088646)
		(layer "F.Cu")
		(net "M_E_CPU0_SB_DQ<11>")
	)
	(segment
		(start 416.439604 -220.0148)
		(end 416.205416 -220.248988)
		(width 0.20066)
		(layer "F.Cu")
		(net "M_E_CPU0_SB_DQ<11>")
	)
	(segment
		(start 403.0853 -222.83801)
		(end 405.218392 -220.704918)
		(width 0.20066)
		(layer "F.Cu")
		(net "M_E_CPU0_SB_DQ<11>")
	)
	(segment
		(start 401.557236 -227.19665)
		(end 401.758404 -226.995482)
		(width 0.20066)
		(layer "F.Cu")
		(net "M_E_CPU0_SB_DQ<11>")
	)
	(segment
		(start 401.557236 -227.480622)
		(end 401.557236 -227.19665)
		(width 0.20066)
		(layer "F.Cu")
		(net "M_E_CPU0_SB_DQ<11>")
	)
	(segment
		(start 400.833082 -228.981)
		(end 400.833082 -228.697028)
		(width 0.20066)
		(layer "F.Cu")
		(net "M_E_CPU0_SB_DQ<11>")
	)
	(segment
		(start 415.307526 -220.710506)
		(end 415.27476 -220.710506)
		(width 0.101854)
		(layer "F.Cu")
		(net "M_E_CPU0_SB_DQ<11>")
	)
	(segment
		(start 413.285686 -220.706188)
		(end 413.275526 -220.706188)
		(width 0.101854)
		(layer "F.Cu")
		(net "M_E_CPU0_SB_DQ<11>")
	)
	(segment
		(start 400.432016 -229.382066)
		(end 400.833082 -228.981)
		(width 0.20066)
		(layer "F.Cu")
		(net "M_E_CPU0_SB_DQ<11>")
	)
	(segment
		(start 388.890764 -237.822486)
		(end 390.38911 -237.822486)
		(width 0.1016)
		(layer "F.Cu")
		(net "M_E_CPU0_SB_DQ<11>")
	)
	(segment
		(start 402.288502 -227.241608)
		(end 402.572474 -227.241608)
		(width 0.20066)
		(layer "F.Cu")
		(net "M_E_CPU0_SB_DQ<11>")
	)
	(segment
		(start 386.36702 -238.76381)
		(end 387.776974 -238.76381)
		(width 0.088646)
		(layer "F.Cu")
		(net "M_E_CPU0_SB_DQ<11>")
	)
	(segment
		(start 400.788124 -227.965762)
		(end 401.072096 -227.965762)
		(width 0.20066)
		(layer "F.Cu")
		(net "M_E_CPU0_SB_DQ<11>")
	)
	(segment
		(start 416.031934 -220.710506)
		(end 415.307526 -220.710506)
		(width 0.20066)
		(layer "F.Cu")
		(net "M_E_CPU0_SB_DQ<11>")
	)
	(segment
		(start 405.736552 -220.704918)
		(end 405.74976 -220.69171)
		(width 0.1016)
		(layer "F.Cu")
		(net "M_E_CPU0_SB_DQ<11>")
	)
	(segment
		(start 407.763726 -220.701616)
		(end 408.238452 -220.701616)
		(width 0.20066)
		(layer "F.Cu")
		(net "M_E_CPU0_SB_DQ<11>")
	)
	(segment
		(start 387.724396 -239.49025)
		(end 388.78256 -238.432086)
		(width 0.088646)
		(layer "F.Cu")
		(net "M_E_CPU0_SB_DQ<10>")
	)
	(segment
		(start 412.50235 -221.96679)
		(end 410.853382 -221.96679)
		(width 0.20066)
		(layer "F.Cu")
		(net "M_E_CPU0_SB_DQ<10>")
	)
	(segment
		(start 388.890764 -238.432086)
		(end 390.643618 -238.432086)
		(width 0.1016)
		(layer "F.Cu")
		(net "M_E_CPU0_SB_DQ<10>")
	)
	(segment
		(start 401.73783 -230.74122)
		(end 402.401532 -231.404922)
		(width 0.20066)
		(layer "F.Cu")
		(net "M_E_CPU0_SB_DQ<10>")
	)
	(segment
		(start 418.397182 -221.96679)
		(end 417.07562 -221.96679)
		(width 0.20066)
		(layer "F.Cu")
		(net "M_E_CPU0_SB_DQ<10>")
	)
	(segment
		(start 415.307526 -222.410528)
		(end 415.27476 -222.410528)
		(width 0.101854)
		(layer "F.Cu")
		(net "M_E_CPU0_SB_DQ<10>")
	)
	(segment
		(start 408.50439 -222.400368)
		(end 408.937968 -221.96679)
		(width 0.20066)
		(layer "F.Cu")
		(net "M_E_CPU0_SB_DQ<10>")
	)
	(segment
		(start 415.255964 -222.391732)
		(end 413.300164 -222.391732)
		(width 0.1016)
		(layer "F.Cu")
		(net "M_E_CPU0_SB_DQ<10>")
	)
	(segment
		(start 404.39975 -229.763574)
		(end 404.39975 -223.378268)
		(width 0.20066)
		(layer "F.Cu")
		(net "M_E_CPU0_SB_DQ<10>")
	)
	(segment
		(start 413.275526 -222.40621)
		(end 412.94177 -222.40621)
		(width 0.20066)
		(layer "F.Cu")
		(net "M_E_CPU0_SB_DQ<10>")
	)
	(segment
		(start 408.937968 -221.96679)
		(end 410.853382 -221.96679)
		(width 0.20066)
		(layer "F.Cu")
		(net "M_E_CPU0_SB_DQ<10>")
	)
	(segment
		(start 387.4897 -239.49025)
		(end 387.724396 -239.49025)
		(width 0.088646)
		(layer "F.Cu")
		(net "M_E_CPU0_SB_DQ<10>")
	)
	(segment
		(start 398.334484 -230.74122)
		(end 399.07591 -230.74122)
		(width 0.1016)
		(layer "F.Cu")
		(net "M_E_CPU0_SB_DQ<10>")
	)
	(segment
		(start 405.731726 -222.405448)
		(end 405.736552 -222.405448)
		(width 0.101854)
		(layer "F.Cu")
		(net "M_E_CPU0_SB_DQ<10>")
	)
	(segment
		(start 413.285686 -222.40621)
		(end 413.275526 -222.40621)
		(width 0.101854)
		(layer "F.Cu")
		(net "M_E_CPU0_SB_DQ<10>")
	)
	(segment
		(start 402.758402 -231.404922)
		(end 404.39975 -229.763574)
		(width 0.20066)
		(layer "F.Cu")
		(net "M_E_CPU0_SB_DQ<10>")
	)
	(segment
		(start 413.300164 -222.391732)
		(end 413.285686 -222.40621)
		(width 0.1016)
		(layer "F.Cu")
		(net "M_E_CPU0_SB_DQ<10>")
	)
	(segment
		(start 416.031934 -222.410528)
		(end 415.307526 -222.410528)
		(width 0.20066)
		(layer "F.Cu")
		(net "M_E_CPU0_SB_DQ<10>")
	)
	(segment
		(start 388.78256 -238.432086)
		(end 388.890764 -238.432086)
		(width 0.088646)
		(layer "F.Cu")
		(net "M_E_CPU0_SB_DQ<10>")
	)
	(segment
		(start 405.736552 -222.405448)
		(end 405.750268 -222.391732)
		(width 0.1016)
		(layer "F.Cu")
		(net "M_E_CPU0_SB_DQ<10>")
	)
	(segment
		(start 385.894834 -239.57534)
		(end 386.1435 -239.326674)
		(width 0.088646)
		(layer "F.Cu")
		(net "M_E_CPU0_SB_DQ<10>")
	)
	(segment
		(start 390.643618 -238.432086)
		(end 398.334484 -230.74122)
		(width 0.1016)
		(layer "F.Cu")
		(net "M_E_CPU0_SB_DQ<10>")
	)
	(segment
		(start 416.823652 -221.714822)
		(end 416.439604 -221.714822)
		(width 0.20066)
		(layer "F.Cu")
		(net "M_E_CPU0_SB_DQ<10>")
	)
	(segment
		(start 412.94177 -222.40621)
		(end 412.50235 -221.96679)
		(width 0.20066)
		(layer "F.Cu")
		(net "M_E_CPU0_SB_DQ<10>")
	)
	(segment
		(start 386.83565 -239.200436)
		(end 387.199886 -239.200436)
		(width 0.088646)
		(layer "F.Cu")
		(net "M_E_CPU0_SB_DQ<10>")
	)
	(segment
		(start 415.27476 -222.410528)
		(end 415.255964 -222.391732)
		(width 0.101854)
		(layer "F.Cu")
		(net "M_E_CPU0_SB_DQ<10>")
	)
	(segment
		(start 407.75509 -222.391732)
		(end 407.763726 -222.400368)
		(width 0.1016)
		(layer "F.Cu")
		(net "M_E_CPU0_SB_DQ<10>")
	)
	(segment
		(start 416.205416 -221.94901)
		(end 416.205416 -222.237046)
		(width 0.20066)
		(layer "F.Cu")
		(net "M_E_CPU0_SB_DQ<10>")
	)
	(segment
		(start 386.1435 -239.326674)
		(end 386.366766 -239.326674)
		(width 0.088646)
		(layer "F.Cu")
		(net "M_E_CPU0_SB_DQ<10>")
	)
	(segment
		(start 407.763726 -222.400368)
		(end 408.50439 -222.400368)
		(width 0.20066)
		(layer "F.Cu")
		(net "M_E_CPU0_SB_DQ<10>")
	)
	(segment
		(start 416.205416 -222.237046)
		(end 416.031934 -222.410528)
		(width 0.20066)
		(layer "F.Cu")
		(net "M_E_CPU0_SB_DQ<10>")
	)
	(segment
		(start 404.39975 -223.378268)
		(end 405.37257 -222.405448)
		(width 0.20066)
		(layer "F.Cu")
		(net "M_E_CPU0_SB_DQ<10>")
	)
	(segment
		(start 402.401532 -231.404922)
		(end 402.758402 -231.404922)
		(width 0.20066)
		(layer "F.Cu")
		(net "M_E_CPU0_SB_DQ<10>")
	)
	(segment
		(start 416.439604 -221.714822)
		(end 416.205416 -221.94901)
		(width 0.20066)
		(layer "F.Cu")
		(net "M_E_CPU0_SB_DQ<10>")
	)
	(segment
		(start 387.199886 -239.200436)
		(end 387.4897 -239.49025)
		(width 0.088646)
		(layer "F.Cu")
		(net "M_E_CPU0_SB_DQ<10>")
	)
	(segment
		(start 399.07591 -230.74122)
		(end 401.73783 -230.74122)
		(width 0.20066)
		(layer "F.Cu")
		(net "M_E_CPU0_SB_DQ<10>")
	)
	(segment
		(start 405.750268 -222.391732)
		(end 407.75509 -222.391732)
		(width 0.1016)
		(layer "F.Cu")
		(net "M_E_CPU0_SB_DQ<10>")
	)
	(segment
		(start 417.07562 -221.96679)
		(end 416.823652 -221.714822)
		(width 0.20066)
		(layer "F.Cu")
		(net "M_E_CPU0_SB_DQ<10>")
	)
	(segment
		(start 405.37257 -222.405448)
		(end 405.731726 -222.405448)
		(width 0.20066)
		(layer "F.Cu")
		(net "M_E_CPU0_SB_DQ<10>")
	)
	(arc
		(start 386.64388 -239.253522)
		(mid 386.73618 -239.214034)
		(end 386.83565 -239.200436)
		(width 0.088646)
		(layer "F.Cu")
		(net "M_E_CPU0_SB_DQ<10>")
	)
	(arc
		(start 386.366766 -239.326674)
		(mid 386.510033 -239.307947)
		(end 386.64388 -239.253522)
		(width 0.088646)
		(layer "F.Cu")
		(net "M_E_CPU0_SB_DQ<10>")
	)
	(segment
		(start 408.274012 -232.166668)
		(end 408.488642 -232.381298)
		(width 0.20066)
		(layer "F.Cu")
		(net "M_E_CPU0_SB_DQ<0>")
	)
	(segment
		(start 409.303982 -231.741726)
		(end 409.64866 -231.741726)
		(width 0.20066)
		(layer "F.Cu")
		(net "M_E_CPU0_SB_DQ<0>")
	)
	(segment
		(start 412.705296 -232.166922)
		(end 414.29686 -232.166922)
		(width 0.20066)
		(layer "F.Cu")
		(net "M_E_CPU0_SB_DQ<0>")
	)
	(segment
		(start 381.665734 -237.133892)
		(end 381.665734 -236.597952)
		(width 0.20066)
		(layer "F.Cu")
		(net "M_E_CPU0_SB_DQ<0>")
	)
	(segment
		(start 408.997912 -232.381298)
		(end 409.185872 -232.193338)
		(width 0.20066)
		(layer "F.Cu")
		(net "M_E_CPU0_SB_DQ<0>")
	)
	(segment
		(start 409.185872 -232.193338)
		(end 409.185872 -231.859836)
		(width 0.20066)
		(layer "F.Cu")
		(net "M_E_CPU0_SB_DQ<0>")
	)
	(segment
		(start 411.857444 -231.741726)
		(end 412.073344 -231.741726)
		(width 0.101854)
		(layer "F.Cu")
		(net "M_E_CPU0_SB_DQ<0>")
	)
	(segment
		(start 409.69565 -231.741726)
		(end 411.857444 -231.741726)
		(width 0.1016)
		(layer "F.Cu")
		(net "M_E_CPU0_SB_DQ<0>")
	)
	(segment
		(start 409.64866 -231.741726)
		(end 409.69565 -231.741726)
		(width 0.101854)
		(layer "F.Cu")
		(net "M_E_CPU0_SB_DQ<0>")
	)
	(segment
		(start 409.185872 -231.859836)
		(end 409.303982 -231.741726)
		(width 0.20066)
		(layer "F.Cu")
		(net "M_E_CPU0_SB_DQ<0>")
	)
	(segment
		(start 412.2801 -231.741726)
		(end 412.705296 -232.166922)
		(width 0.20066)
		(layer "F.Cu")
		(net "M_E_CPU0_SB_DQ<0>")
	)
	(segment
		(start 405.623014 -232.166668)
		(end 406.753314 -232.166668)
		(width 0.20066)
		(layer "F.Cu")
		(net "M_E_CPU0_SB_DQ<0>")
	)
	(segment
		(start 412.073344 -231.741726)
		(end 412.2801 -231.741726)
		(width 0.20066)
		(layer "F.Cu")
		(net "M_E_CPU0_SB_DQ<0>")
	)
	(segment
		(start 406.753314 -232.166668)
		(end 408.274012 -232.166668)
		(width 0.20066)
		(layer "F.Cu")
		(net "M_E_CPU0_SB_DQ<0>")
	)
	(segment
		(start 408.488642 -232.381298)
		(end 408.997912 -232.381298)
		(width 0.20066)
		(layer "F.Cu")
		(net "M_E_CPU0_SB_DQ<0>")
	)
	(segment
		(start 414.29686 -232.166922)
		(end 414.297114 -232.166668)
		(width 0.20066)
		(layer "F.Cu")
		(net "M_E_CPU0_SB_DQ<0>")
	)
	(segment
		(start 404.559516 -232.931208)
		(end 403.386036 -234.104688)
		(width 0.18288)
		(layer "In2.Cu")
		(net "M_E_CPU0_SB_DQ<0>")
	)
	(segment
		(start 402.117052 -235.100876)
		(end 401.877784 -234.861608)
		(width 0.18288)
		(layer "In2.Cu")
		(net "M_E_CPU0_SB_DQ<0>")
	)
	(segment
		(start 403.11324 -234.104688)
		(end 402.873972 -233.86542)
		(width 0.18288)
		(layer "In2.Cu")
		(net "M_E_CPU0_SB_DQ<0>")
	)
	(segment
		(start 405.623014 -231.915462)
		(end 405.37003 -231.662478)
		(width 0.18288)
		(layer "In2.Cu")
		(net "M_E_CPU0_SB_DQ<0>")
	)
	(segment
		(start 401.120864 -236.097064)
		(end 400.881596 -235.857796)
		(width 0.18288)
		(layer "In2.Cu")
		(net "M_E_CPU0_SB_DQ<0>")
	)
	(segment
		(start 400.383502 -236.35589)
		(end 400.62277 -236.595158)
		(width 0.18288)
		(layer "In2.Cu")
		(net "M_E_CPU0_SB_DQ<0>")
	)
	(segment
		(start 386.614924 -237.163356)
		(end 386.364734 -237.163356)
		(width 0.088646)
		(layer "In2.Cu")
		(net "M_E_CPU0_SB_DQ<0>")
	)
	(segment
		(start 388.29996 -237.217712)
		(end 388.028434 -237.489238)
		(width 0.18288)
		(layer "In2.Cu")
		(net "M_E_CPU0_SB_DQ<0>")
	)
	(segment
		(start 383.277364 -237.096046)
		(end 383.262632 -237.08741)
		(width 0.088646)
		(layer "In2.Cu")
		(net "M_E_CPU0_SB_DQ<0>")
	)
	(segment
		(start 382.04394 -236.66323)
		(end 381.978662 -236.597952)
		(width 0.088646)
		(layer "In2.Cu")
		(net "M_E_CPU0_SB_DQ<0>")
	)
	(segment
		(start 405.37003 -231.662478)
		(end 405.09698 -231.662478)
		(width 0.18288)
		(layer "In2.Cu")
		(net "M_E_CPU0_SB_DQ<0>")
	)
	(segment
		(start 401.37969 -235.359702)
		(end 401.618958 -235.59897)
		(width 0.18288)
		(layer "In2.Cu")
		(net "M_E_CPU0_SB_DQ<0>")
	)
	(segment
		(start 401.618958 -235.871766)
		(end 401.39366 -236.097064)
		(width 0.18288)
		(layer "In2.Cu")
		(net "M_E_CPU0_SB_DQ<0>")
	)
	(segment
		(start 400.62277 -236.867954)
		(end 400.29384 -237.196884)
		(width 0.18288)
		(layer "In2.Cu")
		(net "M_E_CPU0_SB_DQ<0>")
	)
	(segment
		(start 402.873972 -233.86542)
		(end 402.601176 -233.86542)
		(width 0.18288)
		(layer "In2.Cu")
		(net "M_E_CPU0_SB_DQ<0>")
	)
	(segment
		(start 402.375878 -234.363514)
		(end 402.615146 -234.602782)
		(width 0.18288)
		(layer "In2.Cu")
		(net "M_E_CPU0_SB_DQ<0>")
	)
	(segment
		(start 402.375878 -234.090718)
		(end 402.375878 -234.363514)
		(width 0.18288)
		(layer "In2.Cu")
		(net "M_E_CPU0_SB_DQ<0>")
	)
	(segment
		(start 398.394174 -236.749336)
		(end 397.925798 -237.217712)
		(width 0.18288)
		(layer "In2.Cu")
		(net "M_E_CPU0_SB_DQ<0>")
	)
	(segment
		(start 400.383502 -236.083094)
		(end 400.383502 -236.35589)
		(width 0.18288)
		(layer "In2.Cu")
		(net "M_E_CPU0_SB_DQ<0>")
	)
	(segment
		(start 405.09698 -231.662478)
		(end 404.559516 -232.199942)
		(width 0.18288)
		(layer "In2.Cu")
		(net "M_E_CPU0_SB_DQ<0>")
	)
	(segment
		(start 400.020536 -237.196884)
		(end 399.392394 -236.568742)
		(width 0.18288)
		(layer "In2.Cu")
		(net "M_E_CPU0_SB_DQ<0>")
	)
	(segment
		(start 402.389848 -235.100876)
		(end 402.117052 -235.100876)
		(width 0.18288)
		(layer "In2.Cu")
		(net "M_E_CPU0_SB_DQ<0>")
	)
	(segment
		(start 385.156964 -237.096046)
		(end 385.142232 -237.08741)
		(width 0.088646)
		(layer "In2.Cu")
		(net "M_E_CPU0_SB_DQ<0>")
	)
	(segment
		(start 399.392394 -236.568742)
		(end 398.830038 -236.568742)
		(width 0.18288)
		(layer "In2.Cu")
		(net "M_E_CPU0_SB_DQ<0>")
	)
	(segment
		(start 398.830038 -236.568742)
		(end 398.394174 -236.749336)
		(width 0.18288)
		(layer "In2.Cu")
		(net "M_E_CPU0_SB_DQ<0>")
	)
	(segment
		(start 404.559516 -232.199942)
		(end 404.559516 -232.931208)
		(width 0.18288)
		(layer "In2.Cu")
		(net "M_E_CPU0_SB_DQ<0>")
	)
	(segment
		(start 400.881596 -235.857796)
		(end 400.6088 -235.857796)
		(width 0.18288)
		(layer "In2.Cu")
		(net "M_E_CPU0_SB_DQ<0>")
	)
	(segment
		(start 402.601176 -233.86542)
		(end 402.375878 -234.090718)
		(width 0.18288)
		(layer "In2.Cu")
		(net "M_E_CPU0_SB_DQ<0>")
	)
	(segment
		(start 388.028434 -237.489238)
		(end 387.620764 -237.489238)
		(width 0.18288)
		(layer "In2.Cu")
		(net "M_E_CPU0_SB_DQ<0>")
	)
	(segment
		(start 401.37969 -235.086906)
		(end 401.37969 -235.359702)
		(width 0.18288)
		(layer "In2.Cu")
		(net "M_E_CPU0_SB_DQ<0>")
	)
	(segment
		(start 405.623014 -232.166668)
		(end 405.623014 -231.915462)
		(width 0.18288)
		(layer "In2.Cu")
		(net "M_E_CPU0_SB_DQ<0>")
	)
	(segment
		(start 387.620764 -237.489238)
		(end 386.940806 -237.489238)
		(width 0.088646)
		(layer "In2.Cu")
		(net "M_E_CPU0_SB_DQ<0>")
	)
	(segment
		(start 401.39366 -236.097064)
		(end 401.120864 -236.097064)
		(width 0.18288)
		(layer "In2.Cu")
		(net "M_E_CPU0_SB_DQ<0>")
	)
	(segment
		(start 401.604988 -234.861608)
		(end 401.37969 -235.086906)
		(width 0.18288)
		(layer "In2.Cu")
		(net "M_E_CPU0_SB_DQ<0>")
	)
	(segment
		(start 384.217164 -237.096046)
		(end 384.202432 -237.08741)
		(width 0.088646)
		(layer "In2.Cu")
		(net "M_E_CPU0_SB_DQ<0>")
	)
	(segment
		(start 401.618958 -235.59897)
		(end 401.618958 -235.871766)
		(width 0.18288)
		(layer "In2.Cu")
		(net "M_E_CPU0_SB_DQ<0>")
	)
	(segment
		(start 386.940806 -237.489238)
		(end 386.614924 -237.163356)
		(width 0.088646)
		(layer "In2.Cu")
		(net "M_E_CPU0_SB_DQ<0>")
	)
	(segment
		(start 401.877784 -234.861608)
		(end 401.604988 -234.861608)
		(width 0.18288)
		(layer "In2.Cu")
		(net "M_E_CPU0_SB_DQ<0>")
	)
	(segment
		(start 381.978662 -236.597952)
		(end 381.665734 -236.597952)
		(width 0.088646)
		(layer "In2.Cu")
		(net "M_E_CPU0_SB_DQ<0>")
	)
	(segment
		(start 400.62277 -236.595158)
		(end 400.62277 -236.867954)
		(width 0.18288)
		(layer "In2.Cu")
		(net "M_E_CPU0_SB_DQ<0>")
	)
	(segment
		(start 400.6088 -235.857796)
		(end 400.383502 -236.083094)
		(width 0.18288)
		(layer "In2.Cu")
		(net "M_E_CPU0_SB_DQ<0>")
	)
	(segment
		(start 400.29384 -237.196884)
		(end 400.020536 -237.196884)
		(width 0.18288)
		(layer "In2.Cu")
		(net "M_E_CPU0_SB_DQ<0>")
	)
	(segment
		(start 402.615146 -234.875578)
		(end 402.389848 -235.100876)
		(width 0.18288)
		(layer "In2.Cu")
		(net "M_E_CPU0_SB_DQ<0>")
	)
	(segment
		(start 403.386036 -234.104688)
		(end 403.11324 -234.104688)
		(width 0.18288)
		(layer "In2.Cu")
		(net "M_E_CPU0_SB_DQ<0>")
	)
	(segment
		(start 402.615146 -234.602782)
		(end 402.615146 -234.875578)
		(width 0.18288)
		(layer "In2.Cu")
		(net "M_E_CPU0_SB_DQ<0>")
	)
	(segment
		(start 397.925798 -237.217712)
		(end 388.29996 -237.217712)
		(width 0.18288)
		(layer "In2.Cu")
		(net "M_E_CPU0_SB_DQ<0>")
	)
	(arc
		(start 385.707636 -237.08741)
		(mid 385.433437 -237.163245)
		(end 385.156964 -237.096046)
		(width 0.088646)
		(layer "In2.Cu")
		(net "M_E_CPU0_SB_DQ<0>")
	)
	(arc
		(start 384.202432 -237.08741)
		(mid 384.015234 -237.037233)
		(end 383.828036 -237.08741)
		(width 0.088646)
		(layer "In2.Cu")
		(net "M_E_CPU0_SB_DQ<0>")
	)
	(arc
		(start 386.364734 -237.163356)
		(mid 386.218395 -237.143963)
		(end 386.082032 -237.08741)
		(width 0.088646)
		(layer "In2.Cu")
		(net "M_E_CPU0_SB_DQ<0>")
	)
	(arc
		(start 384.767836 -237.08741)
		(mid 384.493637 -237.163245)
		(end 384.217164 -237.096046)
		(width 0.088646)
		(layer "In2.Cu")
		(net "M_E_CPU0_SB_DQ<0>")
	)
	(arc
		(start 385.142232 -237.08741)
		(mid 384.955034 -237.037233)
		(end 384.767836 -237.08741)
		(width 0.088646)
		(layer "In2.Cu")
		(net "M_E_CPU0_SB_DQ<0>")
	)
	(arc
		(start 383.262632 -237.08741)
		(mid 383.075434 -237.037233)
		(end 382.888236 -237.08741)
		(width 0.088646)
		(layer "In2.Cu")
		(net "M_E_CPU0_SB_DQ<0>")
	)
	(arc
		(start 386.082032 -237.08741)
		(mid 385.894834 -237.037233)
		(end 385.707636 -237.08741)
		(width 0.088646)
		(layer "In2.Cu")
		(net "M_E_CPU0_SB_DQ<0>")
	)
	(arc
		(start 382.888236 -237.08741)
		(mid 382.605534 -237.163186)
		(end 382.322832 -237.08741)
		(width 0.088646)
		(layer "In2.Cu")
		(net "M_E_CPU0_SB_DQ<0>")
	)
	(arc
		(start 382.322832 -237.08741)
		(mid 382.133082 -236.908396)
		(end 382.04394 -236.66323)
		(width 0.088646)
		(layer "In2.Cu")
		(net "M_E_CPU0_SB_DQ<0>")
	)
	(arc
		(start 383.828036 -237.08741)
		(mid 383.553837 -237.163245)
		(end 383.277364 -237.096046)
		(width 0.088646)
		(layer "In2.Cu")
		(net "M_E_CPU0_SB_DQ<0>")
	)
	(segment
		(start 409.196794 -244.211602)
		(end 409.901898 -244.916706)
		(width 0.20066)
		(layer "F.Cu")
		(net "M_E_CPU0_SB_CS_N<3>")
	)
	(segment
		(start 407.693114 -242.791742)
		(end 407.719022 -242.81765)
		(width 0.1016)
		(layer "F.Cu")
		(net "M_E_CPU0_SB_CS_N<3>")
	)
	(segment
		(start 398.750536 -242.977924)
		(end 399.80743 -244.034818)
		(width 0.20066)
		(layer "F.Cu")
		(net "M_E_CPU0_SB_CS_N<3>")
	)
	(segment
		(start 386.522468 -245.665752)
		(end 388.255764 -245.665752)
		(width 0.088646)
		(layer "F.Cu")
		(net "M_E_CPU0_SB_CS_N<3>")
	)
	(segment
		(start 409.901898 -244.916706)
		(end 410.853382 -244.916706)
		(width 0.20066)
		(layer "F.Cu")
		(net "M_E_CPU0_SB_CS_N<3>")
	)
	(segment
		(start 403.61235 -244.034818)
		(end 404.186898 -243.79682)
		(width 0.20066)
		(layer "F.Cu")
		(net "M_E_CPU0_SB_CS_N<3>")
	)
	(segment
		(start 408.383994 -242.292886)
		(end 408.559254 -242.117626)
		(width 0.20066)
		(layer "F.Cu")
		(net "M_E_CPU0_SB_CS_N<3>")
	)
	(segment
		(start 384.485134 -246.367046)
		(end 384.601974 -245.904766)
		(width 0.088646)
		(layer "F.Cu")
		(net "M_E_CPU0_SB_CS_N<3>")
	)
	(segment
		(start 384.485134 -246.900446)
		(end 384.485134 -246.367046)
		(width 0.088646)
		(layer "F.Cu")
		(net "M_E_CPU0_SB_CS_N<3>")
	)
	(segment
		(start 391.071862 -245.160546)
		(end 393.254484 -242.977924)
		(width 0.20066)
		(layer "F.Cu")
		(net "M_E_CPU0_SB_CS_N<3>")
	)
	(segment
		(start 385.556506 -245.628922)
		(end 385.612132 -245.596918)
		(width 0.088646)
		(layer "F.Cu")
		(net "M_E_CPU0_SB_CS_N<3>")
	)
	(segment
		(start 388.255764 -245.665752)
		(end 390.566656 -245.665752)
		(width 0.1016)
		(layer "F.Cu")
		(net "M_E_CPU0_SB_CS_N<3>")
	)
	(segment
		(start 399.80743 -244.034818)
		(end 403.61235 -244.034818)
		(width 0.20066)
		(layer "F.Cu")
		(net "M_E_CPU0_SB_CS_N<3>")
	)
	(segment
		(start 408.188922 -242.81765)
		(end 408.383994 -242.622578)
		(width 0.20066)
		(layer "F.Cu")
		(net "M_E_CPU0_SB_CS_N<3>")
	)
	(segment
		(start 404.186898 -243.79682)
		(end 405.191976 -242.791742)
		(width 0.20066)
		(layer "F.Cu")
		(net "M_E_CPU0_SB_CS_N<3>")
	)
	(segment
		(start 384.601974 -245.904766)
		(end 384.825494 -245.681246)
		(width 0.088646)
		(layer "F.Cu")
		(net "M_E_CPU0_SB_CS_N<3>")
	)
	(segment
		(start 408.383994 -242.622578)
		(end 408.383994 -242.292886)
		(width 0.20066)
		(layer "F.Cu")
		(net "M_E_CPU0_SB_CS_N<3>")
	)
	(segment
		(start 409.196794 -242.292886)
		(end 409.196794 -244.211602)
		(width 0.20066)
		(layer "F.Cu")
		(net "M_E_CPU0_SB_CS_N<3>")
	)
	(segment
		(start 384.825494 -245.681246)
		(end 385.361434 -245.681246)
		(width 0.088646)
		(layer "F.Cu")
		(net "M_E_CPU0_SB_CS_N<3>")
	)
	(segment
		(start 393.254484 -242.977924)
		(end 398.750536 -242.977924)
		(width 0.20066)
		(layer "F.Cu")
		(net "M_E_CPU0_SB_CS_N<3>")
	)
	(segment
		(start 405.191976 -242.791742)
		(end 405.52497 -242.791742)
		(width 0.20066)
		(layer "F.Cu")
		(net "M_E_CPU0_SB_CS_N<3>")
	)
	(segment
		(start 407.719022 -242.81765)
		(end 408.188922 -242.81765)
		(width 0.20066)
		(layer "F.Cu")
		(net "M_E_CPU0_SB_CS_N<3>")
	)
	(segment
		(start 409.021534 -242.117626)
		(end 409.196794 -242.292886)
		(width 0.20066)
		(layer "F.Cu")
		(net "M_E_CPU0_SB_CS_N<3>")
	)
	(segment
		(start 405.546306 -242.791742)
		(end 407.693114 -242.791742)
		(width 0.1016)
		(layer "F.Cu")
		(net "M_E_CPU0_SB_CS_N<3>")
	)
	(segment
		(start 405.52497 -242.791742)
		(end 405.546306 -242.791742)
		(width 0.101854)
		(layer "F.Cu")
		(net "M_E_CPU0_SB_CS_N<3>")
	)
	(segment
		(start 408.559254 -242.117626)
		(end 409.021534 -242.117626)
		(width 0.20066)
		(layer "F.Cu")
		(net "M_E_CPU0_SB_CS_N<3>")
	)
	(segment
		(start 386.246624 -245.621302)
		(end 386.522468 -245.665752)
		(width 0.088646)
		(layer "F.Cu")
		(net "M_E_CPU0_SB_CS_N<3>")
	)
	(segment
		(start 390.566656 -245.665752)
		(end 391.071862 -245.160546)
		(width 0.1016)
		(layer "F.Cu")
		(net "M_E_CPU0_SB_CS_N<3>")
	)
	(arc
		(start 385.612132 -245.596918)
		(mid 385.894834 -245.521176)
		(end 386.177536 -245.596918)
		(width 0.088646)
		(layer "F.Cu")
		(net "M_E_CPU0_SB_CS_N<3>")
	)
	(arc
		(start 385.361434 -245.681246)
		(mid 385.462403 -245.667895)
		(end 385.556506 -245.628922)
		(width 0.088646)
		(layer "F.Cu")
		(net "M_E_CPU0_SB_CS_N<3>")
	)
	(arc
		(start 386.177536 -245.596918)
		(mid 386.210971 -245.612251)
		(end 386.246624 -245.621302)
		(width 0.088646)
		(layer "F.Cu")
		(net "M_E_CPU0_SB_CS_N<3>")
	)
	(segment
		(start 384.95478 -246.08663)
		(end 385.341114 -245.92661)
		(width 0.088646)
		(layer "F.Cu")
		(net "M_E_CPU0_SB_CS_N<2>")
	)
	(segment
		(start 403.70887 -245.82247)
		(end 404.526496 -245.82247)
		(width 0.20066)
		(layer "F.Cu")
		(net "M_E_CPU0_SB_CS_N<2>")
	)
	(segment
		(start 406.166828 -245.76659)
		(end 406.753314 -245.76659)
		(width 0.20066)
		(layer "F.Cu")
		(net "M_E_CPU0_SB_CS_N<2>")
	)
	(segment
		(start 385.51231 -245.92661)
		(end 385.634484 -245.804436)
		(width 0.088646)
		(layer "F.Cu")
		(net "M_E_CPU0_SB_CS_N<2>")
	)
	(segment
		(start 386.08254 -245.761764)
		(end 386.411978 -246.091202)
		(width 0.088646)
		(layer "F.Cu")
		(net "M_E_CPU0_SB_CS_N<2>")
	)
	(segment
		(start 401.66544 -245.75262)
		(end 401.949412 -245.75262)
		(width 0.20066)
		(layer "F.Cu")
		(net "M_E_CPU0_SB_CS_N<2>")
	)
	(segment
		(start 385.634484 -245.804436)
		(end 385.709922 -245.761256)
		(width 0.088646)
		(layer "F.Cu")
		(net "M_E_CPU0_SB_CS_N<2>")
	)
	(segment
		(start 400.438874 -245.82247)
		(end 400.933412 -245.327932)
		(width 0.20066)
		(layer "F.Cu")
		(net "M_E_CPU0_SB_CS_N<2>")
	)
	(segment
		(start 402.3741 -245.327932)
		(end 403.214332 -245.327932)
		(width 0.20066)
		(layer "F.Cu")
		(net "M_E_CPU0_SB_CS_N<2>")
	)
	(segment
		(start 393.942316 -244.257068)
		(end 398.220438 -244.257068)
		(width 0.20066)
		(layer "F.Cu")
		(net "M_E_CPU0_SB_CS_N<2>")
	)
	(segment
		(start 401.949412 -245.75262)
		(end 402.3741 -245.327932)
		(width 0.20066)
		(layer "F.Cu")
		(net "M_E_CPU0_SB_CS_N<2>")
	)
	(segment
		(start 386.51434 -246.355362)
		(end 386.620512 -246.409972)
		(width 0.088646)
		(layer "F.Cu")
		(net "M_E_CPU0_SB_CS_N<2>")
	)
	(segment
		(start 404.83282 -245.516146)
		(end 405.916384 -245.516146)
		(width 0.20066)
		(layer "F.Cu")
		(net "M_E_CPU0_SB_CS_N<2>")
	)
	(segment
		(start 392.462766 -245.736618)
		(end 393.942316 -244.257068)
		(width 0.20066)
		(layer "F.Cu")
		(net "M_E_CPU0_SB_CS_N<2>")
	)
	(segment
		(start 386.411978 -246.091202)
		(end 386.411978 -246.253)
		(width 0.088646)
		(layer "F.Cu")
		(net "M_E_CPU0_SB_CS_N<2>")
	)
	(segment
		(start 388.256018 -246.275352)
		(end 391.924032 -246.275352)
		(width 0.1016)
		(layer "F.Cu")
		(net "M_E_CPU0_SB_CS_N<2>")
	)
	(segment
		(start 385.341114 -245.92661)
		(end 385.51231 -245.92661)
		(width 0.088646)
		(layer "F.Cu")
		(net "M_E_CPU0_SB_CS_N<2>")
	)
	(segment
		(start 404.526496 -245.82247)
		(end 404.83282 -245.516146)
		(width 0.20066)
		(layer "F.Cu")
		(net "M_E_CPU0_SB_CS_N<2>")
	)
	(segment
		(start 387.389116 -246.443246)
		(end 387.55701 -246.275352)
		(width 0.088646)
		(layer "F.Cu")
		(net "M_E_CPU0_SB_CS_N<2>")
	)
	(segment
		(start 386.411978 -246.253)
		(end 386.51434 -246.355362)
		(width 0.088646)
		(layer "F.Cu")
		(net "M_E_CPU0_SB_CS_N<2>")
	)
	(segment
		(start 401.240752 -245.327932)
		(end 401.66544 -245.75262)
		(width 0.20066)
		(layer "F.Cu")
		(net "M_E_CPU0_SB_CS_N<2>")
	)
	(segment
		(start 385.894834 -245.711472)
		(end 386.08254 -245.761764)
		(width 0.088646)
		(layer "F.Cu")
		(net "M_E_CPU0_SB_CS_N<2>")
	)
	(segment
		(start 391.924032 -246.275352)
		(end 392.462766 -245.736618)
		(width 0.1016)
		(layer "F.Cu")
		(net "M_E_CPU0_SB_CS_N<2>")
	)
	(segment
		(start 385.709922 -245.761256)
		(end 385.894834 -245.711472)
		(width 0.088646)
		(layer "F.Cu")
		(net "M_E_CPU0_SB_CS_N<2>")
	)
	(segment
		(start 405.916384 -245.516146)
		(end 406.166828 -245.76659)
		(width 0.20066)
		(layer "F.Cu")
		(net "M_E_CPU0_SB_CS_N<2>")
	)
	(segment
		(start 398.220438 -244.257068)
		(end 399.78584 -245.82247)
		(width 0.20066)
		(layer "F.Cu")
		(net "M_E_CPU0_SB_CS_N<2>")
	)
	(segment
		(start 386.757418 -246.443246)
		(end 387.389116 -246.443246)
		(width 0.088646)
		(layer "F.Cu")
		(net "M_E_CPU0_SB_CS_N<2>")
	)
	(segment
		(start 387.55701 -246.275352)
		(end 388.256018 -246.275352)
		(width 0.088646)
		(layer "F.Cu")
		(net "M_E_CPU0_SB_CS_N<2>")
	)
	(segment
		(start 399.78584 -245.82247)
		(end 400.438874 -245.82247)
		(width 0.20066)
		(layer "F.Cu")
		(net "M_E_CPU0_SB_CS_N<2>")
	)
	(segment
		(start 403.214332 -245.327932)
		(end 403.70887 -245.82247)
		(width 0.20066)
		(layer "F.Cu")
		(net "M_E_CPU0_SB_CS_N<2>")
	)
	(segment
		(start 400.933412 -245.327932)
		(end 401.240752 -245.327932)
		(width 0.20066)
		(layer "F.Cu")
		(net "M_E_CPU0_SB_CS_N<2>")
	)
	(arc
		(start 386.620512 -246.409972)
		(mid 386.686978 -246.434774)
		(end 386.757418 -246.443246)
		(width 0.088646)
		(layer "F.Cu")
		(net "M_E_CPU0_SB_CS_N<2>")
	)
	(segment
		(start 403.779736 -244.68836)
		(end 404.612856 -244.343174)
		(width 0.20066)
		(layer "F.Cu")
		(net "M_E_CPU0_SB_CS_N<1>")
	)
	(segment
		(start 405.535638 -243.641626)
		(end 407.744422 -243.641626)
		(width 0.1016)
		(layer "F.Cu")
		(net "M_E_CPU0_SB_CS_N<1>")
	)
	(segment
		(start 415.272728 -244.482112)
		(end 415.307526 -244.482112)
		(width 0.101854)
		(layer "F.Cu")
		(net "M_E_CPU0_SB_CS_N<1>")
	)
	(segment
		(start 386.83438 -246.08663)
		(end 387.213348 -246.08663)
		(width 0.088646)
		(layer "F.Cu")
		(net "M_E_CPU0_SB_CS_N<1>")
	)
	(segment
		(start 416.381184 -243.755672)
		(end 416.582098 -243.956586)
		(width 0.20066)
		(layer "F.Cu")
		(net "M_E_CPU0_SB_CS_N<1>")
	)
	(segment
		(start 407.991564 -243.641626)
		(end 409.679648 -245.32971)
		(width 0.20066)
		(layer "F.Cu")
		(net "M_E_CPU0_SB_CS_N<1>")
	)
	(segment
		(start 387.213348 -246.08663)
		(end 387.329426 -245.970552)
		(width 0.088646)
		(layer "F.Cu")
		(net "M_E_CPU0_SB_CS_N<1>")
	)
	(segment
		(start 416.756342 -244.916706)
		(end 418.397182 -244.916706)
		(width 0.20066)
		(layer "F.Cu")
		(net "M_E_CPU0_SB_CS_N<1>")
	)
	(segment
		(start 413.092138 -244.49151)
		(end 415.26333 -244.49151)
		(width 0.1016)
		(layer "F.Cu")
		(net "M_E_CPU0_SB_CS_N<1>")
	)
	(segment
		(start 387.329426 -245.970552)
		(end 388.255764 -245.970552)
		(width 0.088646)
		(layer "F.Cu")
		(net "M_E_CPU0_SB_CS_N<1>")
	)
	(segment
		(start 416.582098 -243.956586)
		(end 416.582098 -244.742462)
		(width 0.20066)
		(layer "F.Cu")
		(net "M_E_CPU0_SB_CS_N<1>")
	)
	(segment
		(start 416.010598 -243.755672)
		(end 416.381184 -243.755672)
		(width 0.20066)
		(layer "F.Cu")
		(net "M_E_CPU0_SB_CS_N<1>")
	)
	(segment
		(start 413.081724 -244.49151)
		(end 413.092138 -244.49151)
		(width 0.101854)
		(layer "F.Cu")
		(net "M_E_CPU0_SB_CS_N<1>")
	)
	(segment
		(start 409.853638 -245.341648)
		(end 411.839156 -245.341648)
		(width 0.1016)
		(layer "F.Cu")
		(net "M_E_CPU0_SB_CS_N<1>")
	)
	(segment
		(start 405.314404 -243.641626)
		(end 405.535638 -243.641626)
		(width 0.20066)
		(layer "F.Cu")
		(net "M_E_CPU0_SB_CS_N<1>")
	)
	(segment
		(start 409.831794 -245.32971)
		(end 409.8417 -245.32971)
		(width 0.101854)
		(layer "F.Cu")
		(net "M_E_CPU0_SB_CS_N<1>")
	)
	(segment
		(start 393.526264 -243.617496)
		(end 398.485614 -243.617496)
		(width 0.20066)
		(layer "F.Cu")
		(net "M_E_CPU0_SB_CS_N<1>")
	)
	(segment
		(start 415.809938 -243.956332)
		(end 416.010598 -243.755672)
		(width 0.20066)
		(layer "F.Cu")
		(net "M_E_CPU0_SB_CS_N<1>")
	)
	(segment
		(start 409.679648 -245.32971)
		(end 409.831794 -245.32971)
		(width 0.20066)
		(layer "F.Cu")
		(net "M_E_CPU0_SB_CS_N<1>")
	)
	(segment
		(start 399.556478 -244.68836)
		(end 403.779736 -244.68836)
		(width 0.20066)
		(layer "F.Cu")
		(net "M_E_CPU0_SB_CS_N<1>")
	)
	(segment
		(start 409.8417 -245.32971)
		(end 409.853638 -245.341648)
		(width 0.1016)
		(layer "F.Cu")
		(net "M_E_CPU0_SB_CS_N<1>")
	)
	(segment
		(start 415.307526 -244.482112)
		(end 415.597594 -244.482112)
		(width 0.20066)
		(layer "F.Cu")
		(net "M_E_CPU0_SB_CS_N<1>")
	)
	(segment
		(start 412.053786 -245.31701)
		(end 412.879286 -244.49151)
		(width 0.20066)
		(layer "F.Cu")
		(net "M_E_CPU0_SB_CS_N<1>")
	)
	(segment
		(start 412.879286 -244.49151)
		(end 413.081724 -244.49151)
		(width 0.20066)
		(layer "F.Cu")
		(net "M_E_CPU0_SB_CS_N<1>")
	)
	(segment
		(start 391.983214 -245.160546)
		(end 393.526264 -243.617496)
		(width 0.20066)
		(layer "F.Cu")
		(net "M_E_CPU0_SB_CS_N<1>")
	)
	(segment
		(start 407.744422 -243.641626)
		(end 407.991564 -243.641626)
		(width 0.20066)
		(layer "F.Cu")
		(net "M_E_CPU0_SB_CS_N<1>")
	)
	(segment
		(start 388.255764 -245.970552)
		(end 391.173208 -245.970552)
		(width 0.1016)
		(layer "F.Cu")
		(net "M_E_CPU0_SB_CS_N<1>")
	)
	(segment
		(start 404.612856 -244.343174)
		(end 405.314404 -243.641626)
		(width 0.20066)
		(layer "F.Cu")
		(net "M_E_CPU0_SB_CS_N<1>")
	)
	(segment
		(start 415.26333 -244.49151)
		(end 415.272728 -244.482112)
		(width 0.1016)
		(layer "F.Cu")
		(net "M_E_CPU0_SB_CS_N<1>")
	)
	(segment
		(start 411.863794 -245.31701)
		(end 412.053786 -245.31701)
		(width 0.20066)
		(layer "F.Cu")
		(net "M_E_CPU0_SB_CS_N<1>")
	)
	(segment
		(start 391.173208 -245.970552)
		(end 391.983214 -245.160546)
		(width 0.1016)
		(layer "F.Cu")
		(net "M_E_CPU0_SB_CS_N<1>")
	)
	(segment
		(start 415.809938 -244.269768)
		(end 415.809938 -243.956332)
		(width 0.20066)
		(layer "F.Cu")
		(net "M_E_CPU0_SB_CS_N<1>")
	)
	(segment
		(start 411.839156 -245.341648)
		(end 411.863794 -245.31701)
		(width 0.1016)
		(layer "F.Cu")
		(net "M_E_CPU0_SB_CS_N<1>")
	)
	(segment
		(start 398.485614 -243.617496)
		(end 399.556478 -244.68836)
		(width 0.20066)
		(layer "F.Cu")
		(net "M_E_CPU0_SB_CS_N<1>")
	)
	(segment
		(start 415.597594 -244.482112)
		(end 415.809938 -244.269768)
		(width 0.20066)
		(layer "F.Cu")
		(net "M_E_CPU0_SB_CS_N<1>")
	)
	(segment
		(start 416.582098 -244.742462)
		(end 416.756342 -244.916706)
		(width 0.20066)
		(layer "F.Cu")
		(net "M_E_CPU0_SB_CS_N<1>")
	)
	(segment
		(start 405.813514 -246.191532)
		(end 407.622248 -246.191532)
		(width 0.1016)
		(layer "F.Cu")
		(net "M_E_CPU0_SB_CS_N<0>")
	)
	(segment
		(start 397.955262 -244.89664)
		(end 399.520664 -246.462042)
		(width 0.20066)
		(layer "F.Cu")
		(net "M_E_CPU0_SB_CS_N<0>")
	)
	(segment
		(start 409.073096 -245.681754)
		(end 408.475434 -246.277384)
		(width 0.20066)
		(layer "F.Cu")
		(net "M_E_CPU0_SB_CS_N<0>")
	)
	(segment
		(start 387.529324 -246.580152)
		(end 388.256018 -246.580152)
		(width 0.088646)
		(layer "F.Cu")
		(net "M_E_CPU0_SB_CS_N<0>")
	)
	(segment
		(start 411.496764 -246.191532)
		(end 411.838902 -246.191532)
		(width 0.101854)
		(layer "F.Cu")
		(net "M_E_CPU0_SB_CS_N<0>")
	)
	(segment
		(start 386.721096 -246.635778)
		(end 387.473698 -246.635778)
		(width 0.088646)
		(layer "F.Cu")
		(net "M_E_CPU0_SB_CS_N<0>")
	)
	(segment
		(start 408.724862 -246.828818)
		(end 409.008834 -246.828818)
		(width 0.20066)
		(layer "F.Cu")
		(net "M_E_CPU0_SB_CS_N<0>")
	)
	(segment
		(start 408.723846 -245.048278)
		(end 409.073096 -245.397528)
		(width 0.20066)
		(layer "F.Cu")
		(net "M_E_CPU0_SB_CS_N<0>")
	)
	(segment
		(start 407.622248 -246.191532)
		(end 407.709878 -246.103902)
		(width 0.1016)
		(layer "F.Cu")
		(net "M_E_CPU0_SB_CS_N<0>")
	)
	(segment
		(start 412.895288 -246.216424)
		(end 413.345122 -245.76659)
		(width 0.20066)
		(layer "F.Cu")
		(net "M_E_CPU0_SB_CS_N<0>")
	)
	(segment
		(start 405.793448 -246.171466)
		(end 405.813514 -246.191532)
		(width 0.1016)
		(layer "F.Cu")
		(net "M_E_CPU0_SB_CS_N<0>")
	)
	(segment
		(start 404.791418 -246.462042)
		(end 405.081994 -246.171466)
		(width 0.20066)
		(layer "F.Cu")
		(net "M_E_CPU0_SB_CS_N<0>")
	)
	(segment
		(start 399.520664 -246.462042)
		(end 404.791418 -246.462042)
		(width 0.20066)
		(layer "F.Cu")
		(net "M_E_CPU0_SB_CS_N<0>")
	)
	(segment
		(start 413.345122 -245.76659)
		(end 414.297114 -245.76659)
		(width 0.20066)
		(layer "F.Cu")
		(net "M_E_CPU0_SB_CS_N<0>")
	)
	(segment
		(start 407.844752 -245.679468)
		(end 408.475942 -245.048278)
		(width 0.20066)
		(layer "F.Cu")
		(net "M_E_CPU0_SB_CS_N<0>")
	)
	(segment
		(start 407.844752 -245.969028)
		(end 407.844752 -245.679468)
		(width 0.20066)
		(layer "F.Cu")
		(net "M_E_CPU0_SB_CS_N<0>")
	)
	(segment
		(start 407.737564 -246.076216)
		(end 407.844752 -245.969028)
		(width 0.20066)
		(layer "F.Cu")
		(net "M_E_CPU0_SB_CS_N<0>")
	)
	(segment
		(start 386.311648 -246.466106)
		(end 386.530342 -246.578374)
		(width 0.088646)
		(layer "F.Cu")
		(net "M_E_CPU0_SB_CS_N<0>")
	)
	(segment
		(start 392.866626 -246.242078)
		(end 394.212064 -244.89664)
		(width 0.20066)
		(layer "F.Cu")
		(net "M_E_CPU0_SB_CS_N<0>")
	)
	(segment
		(start 385.983734 -246.466106)
		(end 386.311648 -246.466106)
		(width 0.088646)
		(layer "F.Cu")
		(net "M_E_CPU0_SB_CS_N<0>")
	)
	(segment
		(start 394.212064 -244.89664)
		(end 397.955262 -244.89664)
		(width 0.20066)
		(layer "F.Cu")
		(net "M_E_CPU0_SB_CS_N<0>")
	)
	(segment
		(start 407.709878 -246.103902)
		(end 407.737564 -246.076216)
		(width 0.101854)
		(layer "F.Cu")
		(net "M_E_CPU0_SB_CS_N<0>")
	)
	(segment
		(start 409.008834 -246.828818)
		(end 409.621482 -246.21617)
		(width 0.20066)
		(layer "F.Cu")
		(net "M_E_CPU0_SB_CS_N<0>")
	)
	(segment
		(start 408.475434 -246.277384)
		(end 408.474926 -246.578882)
		(width 0.20066)
		(layer "F.Cu")
		(net "M_E_CPU0_SB_CS_N<0>")
	)
	(segment
		(start 408.474926 -246.578882)
		(end 408.724862 -246.828818)
		(width 0.20066)
		(layer "F.Cu")
		(net "M_E_CPU0_SB_CS_N<0>")
	)
	(segment
		(start 409.621482 -246.21617)
		(end 409.831794 -246.21617)
		(width 0.20066)
		(layer "F.Cu")
		(net "M_E_CPU0_SB_CS_N<0>")
	)
	(segment
		(start 392.528552 -246.580152)
		(end 392.866626 -246.242078)
		(width 0.1016)
		(layer "F.Cu")
		(net "M_E_CPU0_SB_CS_N<0>")
	)
	(segment
		(start 409.83662 -246.21617)
		(end 409.861258 -246.191532)
		(width 0.1016)
		(layer "F.Cu")
		(net "M_E_CPU0_SB_CS_N<0>")
	)
	(segment
		(start 387.473698 -246.635778)
		(end 387.529324 -246.580152)
		(width 0.088646)
		(layer "F.Cu")
		(net "M_E_CPU0_SB_CS_N<0>")
	)
	(segment
		(start 409.861258 -246.191532)
		(end 411.496764 -246.191532)
		(width 0.1016)
		(layer "F.Cu")
		(net "M_E_CPU0_SB_CS_N<0>")
	)
	(segment
		(start 388.256018 -246.580152)
		(end 392.528552 -246.580152)
		(width 0.1016)
		(layer "F.Cu")
		(net "M_E_CPU0_SB_CS_N<0>")
	)
	(segment
		(start 408.475942 -245.048278)
		(end 408.723846 -245.048278)
		(width 0.20066)
		(layer "F.Cu")
		(net "M_E_CPU0_SB_CS_N<0>")
	)
	(segment
		(start 411.863794 -246.216424)
		(end 412.895288 -246.216424)
		(width 0.20066)
		(layer "F.Cu")
		(net "M_E_CPU0_SB_CS_N<0>")
	)
	(segment
		(start 405.731726 -246.171466)
		(end 405.793448 -246.171466)
		(width 0.101854)
		(layer "F.Cu")
		(net "M_E_CPU0_SB_CS_N<0>")
	)
	(segment
		(start 405.081994 -246.171466)
		(end 405.731726 -246.171466)
		(width 0.20066)
		(layer "F.Cu")
		(net "M_E_CPU0_SB_CS_N<0>")
	)
	(segment
		(start 385.894834 -246.08663)
		(end 385.894834 -246.377206)
		(width 0.088646)
		(layer "F.Cu")
		(net "M_E_CPU0_SB_CS_N<0>")
	)
	(segment
		(start 409.831794 -246.21617)
		(end 409.83662 -246.21617)
		(width 0.101854)
		(layer "F.Cu")
		(net "M_E_CPU0_SB_CS_N<0>")
	)
	(segment
		(start 409.073096 -245.397528)
		(end 409.073096 -245.681754)
		(width 0.20066)
		(layer "F.Cu")
		(net "M_E_CPU0_SB_CS_N<0>")
	)
	(segment
		(start 385.894834 -246.377206)
		(end 385.983734 -246.466106)
		(width 0.088646)
		(layer "F.Cu")
		(net "M_E_CPU0_SB_CS_N<0>")
	)
	(segment
		(start 411.838902 -246.191532)
		(end 411.863794 -246.216424)
		(width 0.101854)
		(layer "F.Cu")
		(net "M_E_CPU0_SB_CS_N<0>")
	)
	(arc
		(start 386.530342 -246.578374)
		(mid 386.580946 -246.602059)
		(end 386.633212 -246.621808)
		(width 0.088646)
		(layer "F.Cu")
		(net "M_E_CPU0_SB_CS_N<0>")
	)
	(arc
		(start 386.633212 -246.621808)
		(mid 386.676593 -246.632324)
		(end 386.721096 -246.635778)
		(width 0.088646)
		(layer "F.Cu")
		(net "M_E_CPU0_SB_CS_N<0>")
	)
	(segment
		(start 408.803094 -238.966756)
		(end 410.853382 -238.966756)
		(width 0.20066)
		(layer "F.Cu")
		(net "M_E_CPU0_SB_CB<7>")
	)
	(segment
		(start 386.364734 -243.644928)
		(end 387.395466 -243.648738)
		(width 0.088646)
		(layer "F.Cu")
		(net "M_E_CPU0_SB_CB<7>")
	)
	(segment
		(start 413.089344 -239.40135)
		(end 412.91637 -239.40135)
		(width 0.20066)
		(layer "F.Cu")
		(net "M_E_CPU0_SB_CB<7>")
	)
	(segment
		(start 402.394166 -239.739424)
		(end 403.68093 -239.739424)
		(width 0.20066)
		(layer "F.Cu")
		(net "M_E_CPU0_SB_CB<7>")
	)
	(segment
		(start 405.736552 -238.54156)
		(end 407.733246 -238.54156)
		(width 0.1016)
		(layer "F.Cu")
		(net "M_E_CPU0_SB_CB<7>")
	)
	(segment
		(start 405.38527 -238.358426)
		(end 405.568404 -238.54156)
		(width 0.20066)
		(layer "F.Cu")
		(net "M_E_CPU0_SB_CB<7>")
	)
	(segment
		(start 401.307046 -239.739424)
		(end 401.507706 -239.538764)
		(width 0.20066)
		(layer "F.Cu")
		(net "M_E_CPU0_SB_CB<7>")
	)
	(segment
		(start 416.863022 -238.966756)
		(end 416.581336 -238.68507)
		(width 0.20066)
		(layer "F.Cu")
		(net "M_E_CPU0_SB_CB<7>")
	)
	(segment
		(start 412.91637 -239.40135)
		(end 412.481776 -238.966756)
		(width 0.20066)
		(layer "F.Cu")
		(net "M_E_CPU0_SB_CB<7>")
	)
	(segment
		(start 415.287206 -239.391698)
		(end 413.302704 -239.391698)
		(width 0.1016)
		(layer "F.Cu")
		(net "M_E_CPU0_SB_CB<7>")
	)
	(segment
		(start 399.408396 -239.739424)
		(end 399.935446 -239.739424)
		(width 0.20066)
		(layer "F.Cu")
		(net "M_E_CPU0_SB_CB<7>")
	)
	(segment
		(start 415.919666 -239.41532)
		(end 415.507424 -239.41532)
		(width 0.20066)
		(layer "F.Cu")
		(net "M_E_CPU0_SB_CB<7>")
	)
	(segment
		(start 407.733246 -238.54156)
		(end 407.749248 -238.525558)
		(width 0.1016)
		(layer "F.Cu")
		(net "M_E_CPU0_SB_CB<7>")
	)
	(segment
		(start 413.302704 -239.391698)
		(end 413.098996 -239.391698)
		(width 0.101854)
		(layer "F.Cu")
		(net "M_E_CPU0_SB_CB<7>")
	)
	(segment
		(start 400.136106 -239.538764)
		(end 400.136106 -239.244378)
		(width 0.20066)
		(layer "F.Cu")
		(net "M_E_CPU0_SB_CB<7>")
	)
	(segment
		(start 400.821906 -239.244378)
		(end 400.821906 -239.538764)
		(width 0.20066)
		(layer "F.Cu")
		(net "M_E_CPU0_SB_CB<7>")
	)
	(segment
		(start 388.288276 -243.4082)
		(end 389.96112 -241.735356)
		(width 0.1016)
		(layer "F.Cu")
		(net "M_E_CPU0_SB_CB<7>")
	)
	(segment
		(start 395.266164 -239.20577)
		(end 398.874742 -239.20577)
		(width 0.20066)
		(layer "F.Cu")
		(net "M_E_CPU0_SB_CB<7>")
	)
	(segment
		(start 416.581336 -238.68507)
		(end 416.297364 -238.68507)
		(width 0.20066)
		(layer "F.Cu")
		(net "M_E_CPU0_SB_CB<7>")
	)
	(segment
		(start 401.708366 -239.043718)
		(end 401.992846 -239.043718)
		(width 0.20066)
		(layer "F.Cu")
		(net "M_E_CPU0_SB_CB<7>")
	)
	(segment
		(start 402.193506 -239.244378)
		(end 402.193506 -239.538764)
		(width 0.20066)
		(layer "F.Cu")
		(net "M_E_CPU0_SB_CB<7>")
	)
	(segment
		(start 401.992846 -239.043718)
		(end 402.193506 -239.244378)
		(width 0.20066)
		(layer "F.Cu")
		(net "M_E_CPU0_SB_CB<7>")
	)
	(segment
		(start 399.935446 -239.739424)
		(end 400.136106 -239.538764)
		(width 0.20066)
		(layer "F.Cu")
		(net "M_E_CPU0_SB_CB<7>")
	)
	(segment
		(start 416.096704 -239.238282)
		(end 415.919666 -239.41532)
		(width 0.20066)
		(layer "F.Cu")
		(net "M_E_CPU0_SB_CB<7>")
	)
	(segment
		(start 405.731726 -238.54156)
		(end 405.736552 -238.54156)
		(width 0.101854)
		(layer "F.Cu")
		(net "M_E_CPU0_SB_CB<7>")
	)
	(segment
		(start 416.297364 -238.68507)
		(end 416.096704 -238.88573)
		(width 0.20066)
		(layer "F.Cu")
		(net "M_E_CPU0_SB_CB<7>")
	)
	(segment
		(start 400.336766 -239.043718)
		(end 400.621246 -239.043718)
		(width 0.20066)
		(layer "F.Cu")
		(net "M_E_CPU0_SB_CB<7>")
	)
	(segment
		(start 394.594588 -239.20577)
		(end 395.266164 -239.20577)
		(width 0.1016)
		(layer "F.Cu")
		(net "M_E_CPU0_SB_CB<7>")
	)
	(segment
		(start 402.193506 -239.538764)
		(end 402.394166 -239.739424)
		(width 0.20066)
		(layer "F.Cu")
		(net "M_E_CPU0_SB_CB<7>")
	)
	(segment
		(start 388.103364 -243.4082)
		(end 388.288276 -243.4082)
		(width 0.1016)
		(layer "F.Cu")
		(net "M_E_CPU0_SB_CB<7>")
	)
	(segment
		(start 400.136106 -239.244378)
		(end 400.336766 -239.043718)
		(width 0.20066)
		(layer "F.Cu")
		(net "M_E_CPU0_SB_CB<7>")
	)
	(segment
		(start 415.507424 -239.41532)
		(end 415.483802 -239.391698)
		(width 0.101854)
		(layer "F.Cu")
		(net "M_E_CPU0_SB_CB<7>")
	)
	(segment
		(start 400.821906 -239.538764)
		(end 401.022566 -239.739424)
		(width 0.20066)
		(layer "F.Cu")
		(net "M_E_CPU0_SB_CB<7>")
	)
	(segment
		(start 407.749248 -238.525558)
		(end 407.763726 -238.525558)
		(width 0.101854)
		(layer "F.Cu")
		(net "M_E_CPU0_SB_CB<7>")
	)
	(segment
		(start 398.874742 -239.20577)
		(end 399.408396 -239.739424)
		(width 0.20066)
		(layer "F.Cu")
		(net "M_E_CPU0_SB_CB<7>")
	)
	(segment
		(start 407.763726 -238.525558)
		(end 408.361896 -238.525558)
		(width 0.20066)
		(layer "F.Cu")
		(net "M_E_CPU0_SB_CB<7>")
	)
	(segment
		(start 412.481776 -238.966756)
		(end 410.853382 -238.966756)
		(width 0.20066)
		(layer "F.Cu")
		(net "M_E_CPU0_SB_CB<7>")
	)
	(segment
		(start 389.96112 -241.735356)
		(end 392.065002 -241.735356)
		(width 0.1016)
		(layer "F.Cu")
		(net "M_E_CPU0_SB_CB<7>")
	)
	(segment
		(start 408.361896 -238.525558)
		(end 408.803094 -238.966756)
		(width 0.20066)
		(layer "F.Cu")
		(net "M_E_CPU0_SB_CB<7>")
	)
	(segment
		(start 413.098996 -239.391698)
		(end 413.089344 -239.40135)
		(width 0.101854)
		(layer "F.Cu")
		(net "M_E_CPU0_SB_CB<7>")
	)
	(segment
		(start 401.022566 -239.739424)
		(end 401.307046 -239.739424)
		(width 0.20066)
		(layer "F.Cu")
		(net "M_E_CPU0_SB_CB<7>")
	)
	(segment
		(start 387.395466 -243.648738)
		(end 387.636004 -243.4082)
		(width 0.088646)
		(layer "F.Cu")
		(net "M_E_CPU0_SB_CB<7>")
	)
	(segment
		(start 401.507706 -239.538764)
		(end 401.507706 -239.244378)
		(width 0.20066)
		(layer "F.Cu")
		(net "M_E_CPU0_SB_CB<7>")
	)
	(segment
		(start 405.568404 -238.54156)
		(end 405.731726 -238.54156)
		(width 0.20066)
		(layer "F.Cu")
		(net "M_E_CPU0_SB_CB<7>")
	)
	(segment
		(start 401.507706 -239.244378)
		(end 401.708366 -239.043718)
		(width 0.20066)
		(layer "F.Cu")
		(net "M_E_CPU0_SB_CB<7>")
	)
	(segment
		(start 403.68093 -239.739424)
		(end 405.061928 -238.358426)
		(width 0.20066)
		(layer "F.Cu")
		(net "M_E_CPU0_SB_CB<7>")
	)
	(segment
		(start 400.621246 -239.043718)
		(end 400.821906 -239.244378)
		(width 0.20066)
		(layer "F.Cu")
		(net "M_E_CPU0_SB_CB<7>")
	)
	(segment
		(start 392.065002 -241.735356)
		(end 394.594588 -239.20577)
		(width 0.1016)
		(layer "F.Cu")
		(net "M_E_CPU0_SB_CB<7>")
	)
	(segment
		(start 416.096704 -238.88573)
		(end 416.096704 -239.238282)
		(width 0.20066)
		(layer "F.Cu")
		(net "M_E_CPU0_SB_CB<7>")
	)
	(segment
		(start 387.636004 -243.4082)
		(end 388.103364 -243.4082)
		(width 0.088646)
		(layer "F.Cu")
		(net "M_E_CPU0_SB_CB<7>")
	)
	(segment
		(start 415.483802 -239.391698)
		(end 415.287206 -239.391698)
		(width 0.101854)
		(layer "F.Cu")
		(net "M_E_CPU0_SB_CB<7>")
	)
	(segment
		(start 418.397182 -238.966756)
		(end 416.863022 -238.966756)
		(width 0.20066)
		(layer "F.Cu")
		(net "M_E_CPU0_SB_CB<7>")
	)
	(segment
		(start 405.061928 -238.358426)
		(end 405.38527 -238.358426)
		(width 0.20066)
		(layer "F.Cu")
		(net "M_E_CPU0_SB_CB<7>")
	)
	(segment
		(start 416.29711 -240.15954)
		(end 416.09645 -239.95888)
		(width 0.20066)
		(layer "F.Cu")
		(net "M_E_CPU0_SB_CB<6>")
	)
	(segment
		(start 408.8257 -240.666778)
		(end 410.853382 -240.666778)
		(width 0.20066)
		(layer "F.Cu")
		(net "M_E_CPU0_SB_CB<6>")
	)
	(segment
		(start 413.098742 -240.241836)
		(end 412.933642 -240.241836)
		(width 0.20066)
		(layer "F.Cu")
		(net "M_E_CPU0_SB_CB<6>")
	)
	(segment
		(start 398.010126 -240.522506)
		(end 398.58061 -241.09299)
		(width 0.20066)
		(layer "F.Cu")
		(net "M_E_CPU0_SB_CB<6>")
	)
	(segment
		(start 398.58061 -241.09299)
		(end 399.333974 -241.09299)
		(width 0.20066)
		(layer "F.Cu")
		(net "M_E_CPU0_SB_CB<6>")
	)
	(segment
		(start 411.75686 -240.57102)
		(end 411.661102 -240.666778)
		(width 0.20066)
		(layer "F.Cu")
		(net "M_E_CPU0_SB_CB<6>")
	)
	(segment
		(start 407.910284 -240.222532)
		(end 408.381454 -240.222532)
		(width 0.20066)
		(layer "F.Cu")
		(net "M_E_CPU0_SB_CB<6>")
	)
	(segment
		(start 394.910564 -240.522506)
		(end 398.010126 -240.522506)
		(width 0.20066)
		(layer "F.Cu")
		(net "M_E_CPU0_SB_CB<6>")
	)
	(segment
		(start 405.761698 -240.241582)
		(end 407.731468 -240.241582)
		(width 0.1016)
		(layer "F.Cu")
		(net "M_E_CPU0_SB_CB<6>")
	)
	(segment
		(start 415.289238 -240.241836)
		(end 413.308292 -240.241836)
		(width 0.1016)
		(layer "F.Cu")
		(net "M_E_CPU0_SB_CB<6>")
	)
	(segment
		(start 387.600444 -244.0178)
		(end 388.103364 -244.0178)
		(width 0.088646)
		(layer "F.Cu")
		(net "M_E_CPU0_SB_CB<6>")
	)
	(segment
		(start 411.661102 -240.666778)
		(end 410.853382 -240.666778)
		(width 0.20066)
		(layer "F.Cu")
		(net "M_E_CPU0_SB_CB<6>")
	)
	(segment
		(start 394.140436 -240.522506)
		(end 394.910564 -240.522506)
		(width 0.1016)
		(layer "F.Cu")
		(net "M_E_CPU0_SB_CB<6>")
	)
	(segment
		(start 400.385026 -242.144042)
		(end 403.059646 -242.144042)
		(width 0.20066)
		(layer "F.Cu")
		(net "M_E_CPU0_SB_CB<6>")
	)
	(segment
		(start 403.059646 -242.144042)
		(end 403.300692 -242.04422)
		(width 0.20066)
		(layer "F.Cu")
		(net "M_E_CPU0_SB_CB<6>")
	)
	(segment
		(start 392.317986 -242.344956)
		(end 394.140436 -240.522506)
		(width 0.1016)
		(layer "F.Cu")
		(net "M_E_CPU0_SB_CB<6>")
	)
	(segment
		(start 412.604458 -240.57102)
		(end 411.75686 -240.57102)
		(width 0.20066)
		(layer "F.Cu")
		(net "M_E_CPU0_SB_CB<6>")
	)
	(segment
		(start 417.013898 -240.666778)
		(end 416.811714 -240.868962)
		(width 0.20066)
		(layer "F.Cu")
		(net "M_E_CPU0_SB_CB<6>")
	)
	(segment
		(start 387.532372 -244.085872)
		(end 387.600444 -244.0178)
		(width 0.088646)
		(layer "F.Cu")
		(net "M_E_CPU0_SB_CB<6>")
	)
	(segment
		(start 416.29711 -240.668302)
		(end 416.29711 -240.15954)
		(width 0.20066)
		(layer "F.Cu")
		(net "M_E_CPU0_SB_CB<6>")
	)
	(segment
		(start 385.894834 -244.458744)
		(end 386.25399 -244.36705)
		(width 0.088646)
		(layer "F.Cu")
		(net "M_E_CPU0_SB_CB<6>")
	)
	(segment
		(start 412.933642 -240.241836)
		(end 412.604458 -240.57102)
		(width 0.20066)
		(layer "F.Cu")
		(net "M_E_CPU0_SB_CB<6>")
	)
	(segment
		(start 405.522176 -240.222532)
		(end 405.541226 -240.241582)
		(width 0.101854)
		(layer "F.Cu")
		(net "M_E_CPU0_SB_CB<6>")
	)
	(segment
		(start 405.125682 -240.21923)
		(end 405.518874 -240.21923)
		(width 0.20066)
		(layer "F.Cu")
		(net "M_E_CPU0_SB_CB<6>")
	)
	(segment
		(start 390.214104 -242.344956)
		(end 392.317986 -242.344956)
		(width 0.1016)
		(layer "F.Cu")
		(net "M_E_CPU0_SB_CB<6>")
	)
	(segment
		(start 416.49777 -240.868962)
		(end 416.29711 -240.668302)
		(width 0.20066)
		(layer "F.Cu")
		(net "M_E_CPU0_SB_CB<6>")
	)
	(segment
		(start 386.25399 -244.36705)
		(end 386.654294 -244.135656)
		(width 0.088646)
		(layer "F.Cu")
		(net "M_E_CPU0_SB_CB<6>")
	)
	(segment
		(start 386.840476 -244.085872)
		(end 387.532372 -244.085872)
		(width 0.088646)
		(layer "F.Cu")
		(net "M_E_CPU0_SB_CB<6>")
	)
	(segment
		(start 418.397182 -240.666778)
		(end 417.013898 -240.666778)
		(width 0.20066)
		(layer "F.Cu")
		(net "M_E_CPU0_SB_CB<6>")
	)
	(segment
		(start 405.541226 -240.241582)
		(end 405.761698 -240.241582)
		(width 0.101854)
		(layer "F.Cu")
		(net "M_E_CPU0_SB_CB<6>")
	)
	(segment
		(start 388.103364 -244.0178)
		(end 388.54126 -244.0178)
		(width 0.1016)
		(layer "F.Cu")
		(net "M_E_CPU0_SB_CB<6>")
	)
	(segment
		(start 415.572194 -239.95888)
		(end 415.404808 -240.126266)
		(width 0.20066)
		(layer "F.Cu")
		(net "M_E_CPU0_SB_CB<6>")
	)
	(segment
		(start 388.54126 -244.0178)
		(end 390.214104 -242.344956)
		(width 0.1016)
		(layer "F.Cu")
		(net "M_E_CPU0_SB_CB<6>")
	)
	(segment
		(start 405.518874 -240.21923)
		(end 405.522176 -240.222532)
		(width 0.20066)
		(layer "F.Cu")
		(net "M_E_CPU0_SB_CB<6>")
	)
	(segment
		(start 399.333974 -241.09299)
		(end 400.385026 -242.144042)
		(width 0.20066)
		(layer "F.Cu")
		(net "M_E_CPU0_SB_CB<6>")
	)
	(segment
		(start 403.300692 -242.04422)
		(end 405.125682 -240.21923)
		(width 0.20066)
		(layer "F.Cu")
		(net "M_E_CPU0_SB_CB<6>")
	)
	(segment
		(start 408.381454 -240.222532)
		(end 408.8257 -240.666778)
		(width 0.20066)
		(layer "F.Cu")
		(net "M_E_CPU0_SB_CB<6>")
	)
	(segment
		(start 416.09645 -239.95888)
		(end 415.572194 -239.95888)
		(width 0.20066)
		(layer "F.Cu")
		(net "M_E_CPU0_SB_CB<6>")
	)
	(segment
		(start 415.307526 -240.223548)
		(end 415.289238 -240.241836)
		(width 0.1016)
		(layer "F.Cu")
		(net "M_E_CPU0_SB_CB<6>")
	)
	(segment
		(start 416.811714 -240.868962)
		(end 416.49777 -240.868962)
		(width 0.20066)
		(layer "F.Cu")
		(net "M_E_CPU0_SB_CB<6>")
	)
	(segment
		(start 407.891234 -240.241582)
		(end 407.910284 -240.222532)
		(width 0.101854)
		(layer "F.Cu")
		(net "M_E_CPU0_SB_CB<6>")
	)
	(segment
		(start 413.308292 -240.241836)
		(end 413.098742 -240.241836)
		(width 0.101854)
		(layer "F.Cu")
		(net "M_E_CPU0_SB_CB<6>")
	)
	(segment
		(start 415.404808 -240.126266)
		(end 415.307526 -240.223548)
		(width 0.101854)
		(layer "F.Cu")
		(net "M_E_CPU0_SB_CB<6>")
	)
	(segment
		(start 407.731468 -240.241582)
		(end 407.891234 -240.241582)
		(width 0.101854)
		(layer "F.Cu")
		(net "M_E_CPU0_SB_CB<6>")
	)
	(arc
		(start 386.654294 -244.135656)
		(mid 386.744106 -244.098503)
		(end 386.840476 -244.085872)
		(width 0.088646)
		(layer "F.Cu")
		(net "M_E_CPU0_SB_CB<6>")
	)
	(segment
		(start 411.845252 -239.391698)
		(end 409.860496 -239.391698)
		(width 0.1016)
		(layer "F.Cu")
		(net "M_E_CPU0_SB_CB<5>")
	)
	(segment
		(start 390.087612 -242.040156)
		(end 392.191494 -242.040156)
		(width 0.1016)
		(layer "F.Cu")
		(net "M_E_CPU0_SB_CB<5>")
	)
	(segment
		(start 408.978354 -239.893094)
		(end 408.626564 -239.893094)
		(width 0.20066)
		(layer "F.Cu")
		(net "M_E_CPU0_SB_CB<5>")
	)
	(segment
		(start 400.653758 -241.497358)
		(end 401.098004 -241.497358)
		(width 0.20066)
		(layer "F.Cu")
		(net "M_E_CPU0_SB_CB<5>")
	)
	(segment
		(start 399.569686 -240.413286)
		(end 400.653758 -241.497358)
		(width 0.20066)
		(layer "F.Cu")
		(net "M_E_CPU0_SB_CB<5>")
	)
	(segment
		(start 384.393694 -243.865908)
		(end 384.393694 -244.20703)
		(width 0.088646)
		(layer "F.Cu")
		(net "M_E_CPU0_SB_CB<5>")
	)
	(segment
		(start 387.600444 -243.713)
		(end 388.103364 -243.713)
		(width 0.088646)
		(layer "F.Cu")
		(net "M_E_CPU0_SB_CB<5>")
	)
	(segment
		(start 402.185124 -241.497358)
		(end 402.777706 -241.497358)
		(width 0.20066)
		(layer "F.Cu")
		(net "M_E_CPU0_SB_CB<5>")
	)
	(segment
		(start 406.753568 -239.816894)
		(end 406.753314 -239.81664)
		(width 0.20066)
		(layer "F.Cu")
		(net "M_E_CPU0_SB_CB<5>")
	)
	(segment
		(start 407.54935 -239.816894)
		(end 406.753568 -239.816894)
		(width 0.20066)
		(layer "F.Cu")
		(net "M_E_CPU0_SB_CB<5>")
	)
	(segment
		(start 404.872698 -239.554512)
		(end 405.954738 -239.554512)
		(width 0.20066)
		(layer "F.Cu")
		(net "M_E_CPU0_SB_CB<5>")
	)
	(segment
		(start 407.940764 -239.42548)
		(end 407.54935 -239.816894)
		(width 0.20066)
		(layer "F.Cu")
		(net "M_E_CPU0_SB_CB<5>")
	)
	(segment
		(start 384.770884 -244.111018)
		(end 384.770884 -243.936266)
		(width 0.088646)
		(layer "F.Cu")
		(net "M_E_CPU0_SB_CB<5>")
	)
	(segment
		(start 401.098004 -241.497358)
		(end 401.298664 -241.296698)
		(width 0.20066)
		(layer "F.Cu")
		(net "M_E_CPU0_SB_CB<5>")
	)
	(segment
		(start 401.984464 -241.296698)
		(end 402.185124 -241.497358)
		(width 0.20066)
		(layer "F.Cu")
		(net "M_E_CPU0_SB_CB<5>")
	)
	(segment
		(start 412.057088 -239.373156)
		(end 412.038546 -239.391698)
		(width 0.101854)
		(layer "F.Cu")
		(net "M_E_CPU0_SB_CB<5>")
	)
	(segment
		(start 385.931156 -243.88953)
		(end 386.103114 -244.061488)
		(width 0.088646)
		(layer "F.Cu")
		(net "M_E_CPU0_SB_CB<5>")
	)
	(segment
		(start 385.343146 -244.197886)
		(end 385.496816 -244.197886)
		(width 0.088646)
		(layer "F.Cu")
		(net "M_E_CPU0_SB_CB<5>")
	)
	(segment
		(start 394.363448 -239.868202)
		(end 395.266164 -239.868202)
		(width 0.1016)
		(layer "F.Cu")
		(net "M_E_CPU0_SB_CB<5>")
	)
	(segment
		(start 385.496816 -244.197886)
		(end 385.805172 -243.88953)
		(width 0.088646)
		(layer "F.Cu")
		(net "M_E_CPU0_SB_CB<5>")
	)
	(segment
		(start 409.679648 -239.391698)
		(end 409.660598 -239.372648)
		(width 0.101854)
		(layer "F.Cu")
		(net "M_E_CPU0_SB_CB<5>")
	)
	(segment
		(start 403.037548 -241.389662)
		(end 404.872698 -239.554512)
		(width 0.20066)
		(layer "F.Cu")
		(net "M_E_CPU0_SB_CB<5>")
	)
	(segment
		(start 412.190692 -239.373156)
		(end 412.057088 -239.373156)
		(width 0.20066)
		(layer "F.Cu")
		(net "M_E_CPU0_SB_CB<5>")
	)
	(segment
		(start 384.770884 -243.936266)
		(end 384.859784 -243.847366)
		(width 0.088646)
		(layer "F.Cu")
		(net "M_E_CPU0_SB_CB<5>")
	)
	(segment
		(start 385.805172 -243.88953)
		(end 385.931156 -243.88953)
		(width 0.088646)
		(layer "F.Cu")
		(net "M_E_CPU0_SB_CB<5>")
	)
	(segment
		(start 409.4988 -239.372648)
		(end 408.978354 -239.893094)
		(width 0.20066)
		(layer "F.Cu")
		(net "M_E_CPU0_SB_CB<5>")
	)
	(segment
		(start 388.414768 -243.713)
		(end 390.087612 -242.040156)
		(width 0.1016)
		(layer "F.Cu")
		(net "M_E_CPU0_SB_CB<5>")
	)
	(segment
		(start 386.103114 -244.061488)
		(end 386.108194 -244.064282)
		(width 0.088646)
		(layer "F.Cu")
		(net "M_E_CPU0_SB_CB<5>")
	)
	(segment
		(start 399.019522 -240.413286)
		(end 399.569686 -240.413286)
		(width 0.20066)
		(layer "F.Cu")
		(net "M_E_CPU0_SB_CB<5>")
	)
	(segment
		(start 409.660598 -239.372648)
		(end 409.4988 -239.372648)
		(width 0.20066)
		(layer "F.Cu")
		(net "M_E_CPU0_SB_CB<5>")
	)
	(segment
		(start 386.8928 -243.882672)
		(end 387.430772 -243.882672)
		(width 0.088646)
		(layer "F.Cu")
		(net "M_E_CPU0_SB_CB<5>")
	)
	(segment
		(start 401.298664 -240.65992)
		(end 401.499324 -240.45926)
		(width 0.20066)
		(layer "F.Cu")
		(net "M_E_CPU0_SB_CB<5>")
	)
	(segment
		(start 414.297114 -239.81664)
		(end 412.634176 -239.81664)
		(width 0.20066)
		(layer "F.Cu")
		(net "M_E_CPU0_SB_CB<5>")
	)
	(segment
		(start 412.634176 -239.81664)
		(end 412.190692 -239.373156)
		(width 0.20066)
		(layer "F.Cu")
		(net "M_E_CPU0_SB_CB<5>")
	)
	(segment
		(start 408.499564 -239.766094)
		(end 408.499564 -239.60328)
		(width 0.20066)
		(layer "F.Cu")
		(net "M_E_CPU0_SB_CB<5>")
	)
	(segment
		(start 386.396484 -244.064536)
		(end 386.554472 -243.97335)
		(width 0.088646)
		(layer "F.Cu")
		(net "M_E_CPU0_SB_CB<5>")
	)
	(segment
		(start 392.191494 -242.040156)
		(end 394.363448 -239.868202)
		(width 0.1016)
		(layer "F.Cu")
		(net "M_E_CPU0_SB_CB<5>")
	)
	(segment
		(start 384.621278 -244.260624)
		(end 384.770884 -244.111018)
		(width 0.088646)
		(layer "F.Cu")
		(net "M_E_CPU0_SB_CB<5>")
	)
	(segment
		(start 412.038546 -239.391698)
		(end 411.845252 -239.391698)
		(width 0.101854)
		(layer "F.Cu")
		(net "M_E_CPU0_SB_CB<5>")
	)
	(segment
		(start 384.859784 -243.847366)
		(end 384.985514 -243.847366)
		(width 0.088646)
		(layer "F.Cu")
		(net "M_E_CPU0_SB_CB<5>")
	)
	(segment
		(start 398.474438 -239.868202)
		(end 399.019522 -240.413286)
		(width 0.20066)
		(layer "F.Cu")
		(net "M_E_CPU0_SB_CB<5>")
	)
	(segment
		(start 409.860496 -239.391698)
		(end 409.679648 -239.391698)
		(width 0.101854)
		(layer "F.Cu")
		(net "M_E_CPU0_SB_CB<5>")
	)
	(segment
		(start 401.984464 -240.65992)
		(end 401.984464 -241.296698)
		(width 0.20066)
		(layer "F.Cu")
		(net "M_E_CPU0_SB_CB<5>")
	)
	(segment
		(start 401.499324 -240.45926)
		(end 401.783804 -240.45926)
		(width 0.20066)
		(layer "F.Cu")
		(net "M_E_CPU0_SB_CB<5>")
	)
	(segment
		(start 408.321764 -239.42548)
		(end 407.940764 -239.42548)
		(width 0.20066)
		(layer "F.Cu")
		(net "M_E_CPU0_SB_CB<5>")
	)
	(segment
		(start 401.783804 -240.45926)
		(end 401.984464 -240.65992)
		(width 0.20066)
		(layer "F.Cu")
		(net "M_E_CPU0_SB_CB<5>")
	)
	(segment
		(start 384.447288 -244.260624)
		(end 384.621278 -244.260624)
		(width 0.088646)
		(layer "F.Cu")
		(net "M_E_CPU0_SB_CB<5>")
	)
	(segment
		(start 395.266164 -239.868202)
		(end 398.474438 -239.868202)
		(width 0.20066)
		(layer "F.Cu")
		(net "M_E_CPU0_SB_CB<5>")
	)
	(segment
		(start 405.954738 -239.554512)
		(end 406.216866 -239.81664)
		(width 0.20066)
		(layer "F.Cu")
		(net "M_E_CPU0_SB_CB<5>")
	)
	(segment
		(start 402.777706 -241.497358)
		(end 403.037548 -241.389662)
		(width 0.20066)
		(layer "F.Cu")
		(net "M_E_CPU0_SB_CB<5>")
	)
	(segment
		(start 408.499564 -239.60328)
		(end 408.321764 -239.42548)
		(width 0.20066)
		(layer "F.Cu")
		(net "M_E_CPU0_SB_CB<5>")
	)
	(segment
		(start 401.298664 -241.296698)
		(end 401.298664 -240.65992)
		(width 0.20066)
		(layer "F.Cu")
		(net "M_E_CPU0_SB_CB<5>")
	)
	(segment
		(start 384.985514 -243.847366)
		(end 385.343146 -244.197886)
		(width 0.088646)
		(layer "F.Cu")
		(net "M_E_CPU0_SB_CB<5>")
	)
	(segment
		(start 408.626564 -239.893094)
		(end 408.499564 -239.766094)
		(width 0.20066)
		(layer "F.Cu")
		(net "M_E_CPU0_SB_CB<5>")
	)
	(segment
		(start 384.485134 -243.644928)
		(end 384.393694 -243.865908)
		(width 0.088646)
		(layer "F.Cu")
		(net "M_E_CPU0_SB_CB<5>")
	)
	(segment
		(start 387.430772 -243.882672)
		(end 387.600444 -243.713)
		(width 0.088646)
		(layer "F.Cu")
		(net "M_E_CPU0_SB_CB<5>")
	)
	(segment
		(start 388.103364 -243.713)
		(end 388.414768 -243.713)
		(width 0.1016)
		(layer "F.Cu")
		(net "M_E_CPU0_SB_CB<5>")
	)
	(segment
		(start 406.216866 -239.81664)
		(end 406.753314 -239.81664)
		(width 0.20066)
		(layer "F.Cu")
		(net "M_E_CPU0_SB_CB<5>")
	)
	(segment
		(start 384.393694 -244.20703)
		(end 384.447288 -244.260624)
		(width 0.088646)
		(layer "F.Cu")
		(net "M_E_CPU0_SB_CB<5>")
	)
	(arc
		(start 386.108194 -244.064282)
		(mid 386.252293 -244.102967)
		(end 386.396484 -244.064536)
		(width 0.088646)
		(layer "F.Cu")
		(net "M_E_CPU0_SB_CB<5>")
	)
	(arc
		(start 386.554472 -243.97335)
		(mid 386.717668 -243.905749)
		(end 386.8928 -243.882672)
		(width 0.088646)
		(layer "F.Cu")
		(net "M_E_CPU0_SB_CB<5>")
	)
	(segment
		(start 396.791434 -241.739674)
		(end 396.791434 -241.39271)
		(width 0.20066)
		(layer "F.Cu")
		(net "M_E_CPU0_SB_CB<4>")
	)
	(segment
		(start 392.444478 -242.649756)
		(end 393.902184 -241.19205)
		(width 0.1016)
		(layer "F.Cu")
		(net "M_E_CPU0_SB_CB<4>")
	)
	(segment
		(start 394.665454 -241.39271)
		(end 394.665454 -241.739674)
		(width 0.20066)
		(layer "F.Cu")
		(net "M_E_CPU0_SB_CB<4>")
	)
	(segment
		(start 414.297114 -241.516662)
		(end 413.375856 -241.516662)
		(width 0.20066)
		(layer "F.Cu")
		(net "M_E_CPU0_SB_CB<4>")
	)
	(segment
		(start 385.396486 -244.458744)
		(end 385.49453 -244.556788)
		(width 0.088646)
		(layer "F.Cu")
		(net "M_E_CPU0_SB_CB<4>")
	)
	(segment
		(start 412.87573 -241.636296)
		(end 412.67507 -241.435636)
		(width 0.20066)
		(layer "F.Cu")
		(net "M_E_CPU0_SB_CB<4>")
	)
	(segment
		(start 394.665454 -241.739674)
		(end 394.866114 -241.940334)
		(width 0.20066)
		(layer "F.Cu")
		(net "M_E_CPU0_SB_CB<4>")
	)
	(segment
		(start 384.95478 -244.458744)
		(end 385.396486 -244.458744)
		(width 0.088646)
		(layer "F.Cu")
		(net "M_E_CPU0_SB_CB<4>")
	)
	(segment
		(start 409.471876 -241.09172)
		(end 409.161742 -241.401854)
		(width 0.20066)
		(layer "F.Cu")
		(net "M_E_CPU0_SB_CB<4>")
	)
	(segment
		(start 396.283434 -241.940334)
		(end 396.590774 -241.940334)
		(width 0.20066)
		(layer "F.Cu")
		(net "M_E_CPU0_SB_CB<4>")
	)
	(segment
		(start 385.49453 -244.827044)
		(end 385.634992 -244.967506)
		(width 0.088646)
		(layer "F.Cu")
		(net "M_E_CPU0_SB_CB<4>")
	)
	(segment
		(start 409.625038 -241.09172)
		(end 409.471876 -241.09172)
		(width 0.20066)
		(layer "F.Cu")
		(net "M_E_CPU0_SB_CB<4>")
	)
	(segment
		(start 413.375856 -241.516662)
		(end 413.256222 -241.636296)
		(width 0.20066)
		(layer "F.Cu")
		(net "M_E_CPU0_SB_CB<4>")
	)
	(segment
		(start 409.852876 -241.09172)
		(end 409.625038 -241.09172)
		(width 0.101854)
		(layer "F.Cu")
		(net "M_E_CPU0_SB_CB<4>")
	)
	(segment
		(start 386.202682 -244.686074)
		(end 386.321808 -244.566948)
		(width 0.088646)
		(layer "F.Cu")
		(net "M_E_CPU0_SB_CB<4>")
	)
	(segment
		(start 396.791434 -241.39271)
		(end 396.992094 -241.19205)
		(width 0.20066)
		(layer "F.Cu")
		(net "M_E_CPU0_SB_CB<4>")
	)
	(segment
		(start 396.992094 -241.19205)
		(end 397.75384 -241.19205)
		(width 0.20066)
		(layer "F.Cu")
		(net "M_E_CPU0_SB_CB<4>")
	)
	(segment
		(start 386.447538 -244.566948)
		(end 386.559044 -244.678454)
		(width 0.088646)
		(layer "F.Cu")
		(net "M_E_CPU0_SB_CB<4>")
	)
	(segment
		(start 399.0594 -241.821462)
		(end 400.22399 -242.986052)
		(width 0.20066)
		(layer "F.Cu")
		(net "M_E_CPU0_SB_CB<4>")
	)
	(segment
		(start 386.202682 -244.840506)
		(end 386.202682 -244.686074)
		(width 0.088646)
		(layer "F.Cu")
		(net "M_E_CPU0_SB_CB<4>")
	)
	(segment
		(start 412.67507 -241.435636)
		(end 412.67507 -241.270536)
		(width 0.20066)
		(layer "F.Cu")
		(net "M_E_CPU0_SB_CB<4>")
	)
	(segment
		(start 408.877516 -241.401854)
		(end 408.589226 -241.113564)
		(width 0.20066)
		(layer "F.Cu")
		(net "M_E_CPU0_SB_CB<4>")
	)
	(segment
		(start 388.029704 -244.740176)
		(end 388.087616 -244.740176)
		(width 0.088646)
		(layer "F.Cu")
		(net "M_E_CPU0_SB_CB<4>")
	)
	(segment
		(start 406.753568 -241.516916)
		(end 406.753314 -241.516662)
		(width 0.20066)
		(layer "F.Cu")
		(net "M_E_CPU0_SB_CB<4>")
	)
	(segment
		(start 394.464794 -241.19205)
		(end 394.665454 -241.39271)
		(width 0.20066)
		(layer "F.Cu")
		(net "M_E_CPU0_SB_CB<4>")
	)
	(segment
		(start 395.173454 -241.940334)
		(end 395.374114 -241.739674)
		(width 0.20066)
		(layer "F.Cu")
		(net "M_E_CPU0_SB_CB<4>")
	)
	(segment
		(start 393.902184 -241.19205)
		(end 394.275564 -241.19205)
		(width 0.1016)
		(layer "F.Cu")
		(net "M_E_CPU0_SB_CB<4>")
	)
	(segment
		(start 395.374114 -241.39271)
		(end 395.574774 -241.19205)
		(width 0.20066)
		(layer "F.Cu")
		(net "M_E_CPU0_SB_CB<4>")
	)
	(segment
		(start 396.590774 -241.940334)
		(end 396.791434 -241.739674)
		(width 0.20066)
		(layer "F.Cu")
		(net "M_E_CPU0_SB_CB<4>")
	)
	(segment
		(start 396.082774 -241.39271)
		(end 396.082774 -241.739674)
		(width 0.20066)
		(layer "F.Cu")
		(net "M_E_CPU0_SB_CB<4>")
	)
	(segment
		(start 386.559044 -244.678454)
		(end 386.559044 -244.915944)
		(width 0.088646)
		(layer "F.Cu")
		(net "M_E_CPU0_SB_CB<4>")
	)
	(segment
		(start 385.634992 -244.967506)
		(end 386.075682 -244.967506)
		(width 0.088646)
		(layer "F.Cu")
		(net "M_E_CPU0_SB_CB<4>")
	)
	(segment
		(start 412.47441 -241.069876)
		(end 411.978602 -241.069876)
		(width 0.20066)
		(layer "F.Cu")
		(net "M_E_CPU0_SB_CB<4>")
	)
	(segment
		(start 403.662896 -242.847876)
		(end 404.99411 -241.516662)
		(width 0.20066)
		(layer "F.Cu")
		(net "M_E_CPU0_SB_CB<4>")
	)
	(segment
		(start 386.075682 -244.967506)
		(end 386.202682 -244.840506)
		(width 0.088646)
		(layer "F.Cu")
		(net "M_E_CPU0_SB_CB<4>")
	)
	(segment
		(start 385.49453 -244.556788)
		(end 385.49453 -244.827044)
		(width 0.088646)
		(layer "F.Cu")
		(net "M_E_CPU0_SB_CB<4>")
	)
	(segment
		(start 386.89915 -244.970554)
		(end 387.062218 -244.807486)
		(width 0.088646)
		(layer "F.Cu")
		(net "M_E_CPU0_SB_CB<4>")
	)
	(segment
		(start 387.66115 -245.170198)
		(end 387.840982 -245.170198)
		(width 0.088646)
		(layer "F.Cu")
		(net "M_E_CPU0_SB_CB<4>")
	)
	(segment
		(start 397.75384 -241.19205)
		(end 398.383252 -241.821462)
		(width 0.20066)
		(layer "F.Cu")
		(net "M_E_CPU0_SB_CB<4>")
	)
	(segment
		(start 409.161742 -241.401854)
		(end 408.877516 -241.401854)
		(width 0.20066)
		(layer "F.Cu")
		(net "M_E_CPU0_SB_CB<4>")
	)
	(segment
		(start 394.866114 -241.940334)
		(end 395.173454 -241.940334)
		(width 0.20066)
		(layer "F.Cu")
		(net "M_E_CPU0_SB_CB<4>")
	)
	(segment
		(start 396.082774 -241.739674)
		(end 396.283434 -241.940334)
		(width 0.20066)
		(layer "F.Cu")
		(net "M_E_CPU0_SB_CB<4>")
	)
	(segment
		(start 386.613654 -244.970554)
		(end 386.89915 -244.970554)
		(width 0.088646)
		(layer "F.Cu")
		(net "M_E_CPU0_SB_CB<4>")
	)
	(segment
		(start 387.941058 -244.828822)
		(end 388.029704 -244.740176)
		(width 0.088646)
		(layer "F.Cu")
		(net "M_E_CPU0_SB_CB<4>")
	)
	(segment
		(start 387.298438 -244.807486)
		(end 387.66115 -245.170198)
		(width 0.088646)
		(layer "F.Cu")
		(net "M_E_CPU0_SB_CB<4>")
	)
	(segment
		(start 411.956758 -241.09172)
		(end 411.66542 -241.09172)
		(width 0.101854)
		(layer "F.Cu")
		(net "M_E_CPU0_SB_CB<4>")
	)
	(segment
		(start 386.559044 -244.915944)
		(end 386.613654 -244.970554)
		(width 0.088646)
		(layer "F.Cu")
		(net "M_E_CPU0_SB_CB<4>")
	)
	(segment
		(start 386.321808 -244.566948)
		(end 386.447538 -244.566948)
		(width 0.088646)
		(layer "F.Cu")
		(net "M_E_CPU0_SB_CB<4>")
	)
	(segment
		(start 400.22399 -242.986052)
		(end 403.329394 -242.986052)
		(width 0.20066)
		(layer "F.Cu")
		(net "M_E_CPU0_SB_CB<4>")
	)
	(segment
		(start 403.329394 -242.986052)
		(end 403.662896 -242.847876)
		(width 0.20066)
		(layer "F.Cu")
		(net "M_E_CPU0_SB_CB<4>")
	)
	(segment
		(start 387.840982 -245.170198)
		(end 387.941058 -245.070122)
		(width 0.088646)
		(layer "F.Cu")
		(net "M_E_CPU0_SB_CB<4>")
	)
	(segment
		(start 404.99411 -241.516662)
		(end 406.753314 -241.516662)
		(width 0.20066)
		(layer "F.Cu")
		(net "M_E_CPU0_SB_CB<4>")
	)
	(segment
		(start 412.67507 -241.270536)
		(end 412.47441 -241.069876)
		(width 0.20066)
		(layer "F.Cu")
		(net "M_E_CPU0_SB_CB<4>")
	)
	(segment
		(start 407.901902 -241.516916)
		(end 406.753568 -241.516916)
		(width 0.20066)
		(layer "F.Cu")
		(net "M_E_CPU0_SB_CB<4>")
	)
	(segment
		(start 395.882114 -241.19205)
		(end 396.082774 -241.39271)
		(width 0.20066)
		(layer "F.Cu")
		(net "M_E_CPU0_SB_CB<4>")
	)
	(segment
		(start 390.340596 -242.649756)
		(end 392.444478 -242.649756)
		(width 0.1016)
		(layer "F.Cu")
		(net "M_E_CPU0_SB_CB<4>")
	)
	(segment
		(start 408.305254 -241.113564)
		(end 407.901902 -241.516916)
		(width 0.20066)
		(layer "F.Cu")
		(net "M_E_CPU0_SB_CB<4>")
	)
	(segment
		(start 411.978602 -241.069876)
		(end 411.956758 -241.09172)
		(width 0.101854)
		(layer "F.Cu")
		(net "M_E_CPU0_SB_CB<4>")
	)
	(segment
		(start 398.383252 -241.821462)
		(end 399.0594 -241.821462)
		(width 0.20066)
		(layer "F.Cu")
		(net "M_E_CPU0_SB_CB<4>")
	)
	(segment
		(start 408.589226 -241.113564)
		(end 408.305254 -241.113564)
		(width 0.20066)
		(layer "F.Cu")
		(net "M_E_CPU0_SB_CB<4>")
	)
	(segment
		(start 395.374114 -241.739674)
		(end 395.374114 -241.39271)
		(width 0.20066)
		(layer "F.Cu")
		(net "M_E_CPU0_SB_CB<4>")
	)
	(segment
		(start 387.062218 -244.807486)
		(end 387.298438 -244.807486)
		(width 0.088646)
		(layer "F.Cu")
		(net "M_E_CPU0_SB_CB<4>")
	)
	(segment
		(start 395.574774 -241.19205)
		(end 395.882114 -241.19205)
		(width 0.20066)
		(layer "F.Cu")
		(net "M_E_CPU0_SB_CB<4>")
	)
	(segment
		(start 388.250176 -244.740176)
		(end 390.340596 -242.649756)
		(width 0.1016)
		(layer "F.Cu")
		(net "M_E_CPU0_SB_CB<4>")
	)
	(segment
		(start 387.941058 -245.070122)
		(end 387.941058 -244.828822)
		(width 0.088646)
		(layer "F.Cu")
		(net "M_E_CPU0_SB_CB<4>")
	)
	(segment
		(start 388.087616 -244.740176)
		(end 388.250176 -244.740176)
		(width 0.1016)
		(layer "F.Cu")
		(net "M_E_CPU0_SB_CB<4>")
	)
	(segment
		(start 394.275564 -241.19205)
		(end 394.464794 -241.19205)
		(width 0.20066)
		(layer "F.Cu")
		(net "M_E_CPU0_SB_CB<4>")
	)
	(segment
		(start 411.66542 -241.09172)
		(end 409.852876 -241.09172)
		(width 0.1016)
		(layer "F.Cu")
		(net "M_E_CPU0_SB_CB<4>")
	)
	(segment
		(start 413.256222 -241.636296)
		(end 412.87573 -241.636296)
		(width 0.20066)
		(layer "F.Cu")
		(net "M_E_CPU0_SB_CB<4>")
	)
	(segment
		(start 408.52979 -233.016806)
		(end 410.853382 -233.016806)
		(width 0.20066)
		(layer "F.Cu")
		(net "M_E_CPU0_SB_CB<3>")
	)
	(segment
		(start 388.015734 -240.380774)
		(end 388.279386 -240.117122)
		(width 0.088646)
		(layer "F.Cu")
		(net "M_E_CPU0_SB_CB<3>")
	)
	(segment
		(start 416.207956 -232.934764)
		(end 416.207956 -233.244136)
		(width 0.20066)
		(layer "F.Cu")
		(net "M_E_CPU0_SB_CB<3>")
	)
	(segment
		(start 405.753316 -233.441748)
		(end 407.749502 -233.441748)
		(width 0.1016)
		(layer "F.Cu")
		(net "M_E_CPU0_SB_CB<3>")
	)
	(segment
		(start 396.211298 -234.205526)
		(end 397.954246 -232.462578)
		(width 0.20066)
		(layer "F.Cu")
		(net "M_E_CPU0_SB_CB<3>")
	)
	(segment
		(start 413.314896 -233.441748)
		(end 413.072072 -233.441748)
		(width 0.101854)
		(layer "F.Cu")
		(net "M_E_CPU0_SB_CB<3>")
	)
	(segment
		(start 404.938992 -233.341418)
		(end 405.059388 -233.461814)
		(width 0.20066)
		(layer "F.Cu")
		(net "M_E_CPU0_SB_CB<3>")
	)
	(segment
		(start 395.953996 -234.39501)
		(end 396.021814 -234.39501)
		(width 0.1016)
		(layer "F.Cu")
		(net "M_E_CPU0_SB_CB<3>")
	)
	(segment
		(start 389.100568 -239.29594)
		(end 391.053066 -239.29594)
		(width 0.1016)
		(layer "F.Cu")
		(net "M_E_CPU0_SB_CB<3>")
	)
	(segment
		(start 385.894834 -241.203226)
		(end 386.918962 -240.779046)
		(width 0.088646)
		(layer "F.Cu")
		(net "M_E_CPU0_SB_CB<3>")
	)
	(segment
		(start 407.749502 -233.441748)
		(end 407.971498 -233.441748)
		(width 0.101854)
		(layer "F.Cu")
		(net "M_E_CPU0_SB_CB<3>")
	)
	(segment
		(start 396.021814 -234.39501)
		(end 396.211298 -234.205526)
		(width 0.1016)
		(layer "F.Cu")
		(net "M_E_CPU0_SB_CB<3>")
	)
	(segment
		(start 408.104848 -233.441748)
		(end 408.52979 -233.016806)
		(width 0.20066)
		(layer "F.Cu")
		(net "M_E_CPU0_SB_CB<3>")
	)
	(segment
		(start 405.540464 -233.461814)
		(end 405.56053 -233.441748)
		(width 0.101854)
		(layer "F.Cu")
		(net "M_E_CPU0_SB_CB<3>")
	)
	(segment
		(start 413.072072 -233.441748)
		(end 412.971996 -233.441748)
		(width 0.20066)
		(layer "F.Cu")
		(net "M_E_CPU0_SB_CB<3>")
	)
	(segment
		(start 410.853636 -233.01706)
		(end 410.853382 -233.016806)
		(width 0.20066)
		(layer "F.Cu")
		(net "M_E_CPU0_SB_CB<3>")
	)
	(segment
		(start 412.971996 -233.441748)
		(end 412.47187 -232.941622)
		(width 0.20066)
		(layer "F.Cu")
		(net "M_E_CPU0_SB_CB<3>")
	)
	(segment
		(start 387.054852 -240.779046)
		(end 388.015734 -240.380774)
		(width 0.088646)
		(layer "F.Cu")
		(net "M_E_CPU0_SB_CB<3>")
	)
	(segment
		(start 405.56053 -233.441748)
		(end 405.753316 -233.441748)
		(width 0.101854)
		(layer "F.Cu")
		(net "M_E_CPU0_SB_CB<3>")
	)
	(segment
		(start 416.207956 -233.244136)
		(end 416.010344 -233.441748)
		(width 0.20066)
		(layer "F.Cu")
		(net "M_E_CPU0_SB_CB<3>")
	)
	(segment
		(start 418.397182 -233.016806)
		(end 417.297616 -233.016806)
		(width 0.20066)
		(layer "F.Cu")
		(net "M_E_CPU0_SB_CB<3>")
	)
	(segment
		(start 415.28111 -233.441748)
		(end 413.314896 -233.441748)
		(width 0.1016)
		(layer "F.Cu")
		(net "M_E_CPU0_SB_CB<3>")
	)
	(segment
		(start 417.297616 -233.016806)
		(end 416.797744 -232.516934)
		(width 0.20066)
		(layer "F.Cu")
		(net "M_E_CPU0_SB_CB<3>")
	)
	(segment
		(start 416.206178 -232.752646)
		(end 416.206178 -232.932986)
		(width 0.20066)
		(layer "F.Cu")
		(net "M_E_CPU0_SB_CB<3>")
	)
	(segment
		(start 416.010344 -233.441748)
		(end 415.528506 -233.441748)
		(width 0.20066)
		(layer "F.Cu")
		(net "M_E_CPU0_SB_CB<3>")
	)
	(segment
		(start 416.206178 -232.932986)
		(end 416.207956 -232.934764)
		(width 0.20066)
		(layer "F.Cu")
		(net "M_E_CPU0_SB_CB<3>")
	)
	(segment
		(start 411.72765 -233.01706)
		(end 410.853636 -233.01706)
		(width 0.20066)
		(layer "F.Cu")
		(net "M_E_CPU0_SB_CB<3>")
	)
	(segment
		(start 416.797744 -232.516934)
		(end 416.44189 -232.516934)
		(width 0.20066)
		(layer "F.Cu")
		(net "M_E_CPU0_SB_CB<3>")
	)
	(segment
		(start 415.528506 -233.441748)
		(end 415.28111 -233.441748)
		(width 0.101854)
		(layer "F.Cu")
		(net "M_E_CPU0_SB_CB<3>")
	)
	(segment
		(start 416.44189 -232.516934)
		(end 416.206178 -232.752646)
		(width 0.20066)
		(layer "F.Cu")
		(net "M_E_CPU0_SB_CB<3>")
	)
	(segment
		(start 407.971498 -233.441748)
		(end 408.104848 -233.441748)
		(width 0.20066)
		(layer "F.Cu")
		(net "M_E_CPU0_SB_CB<3>")
	)
	(segment
		(start 405.059388 -233.461814)
		(end 405.540464 -233.461814)
		(width 0.20066)
		(layer "F.Cu")
		(net "M_E_CPU0_SB_CB<3>")
	)
	(segment
		(start 401.953476 -233.341418)
		(end 404.938992 -233.341418)
		(width 0.20066)
		(layer "F.Cu")
		(net "M_E_CPU0_SB_CB<3>")
	)
	(segment
		(start 397.954246 -232.462578)
		(end 401.074636 -232.462578)
		(width 0.20066)
		(layer "F.Cu")
		(net "M_E_CPU0_SB_CB<3>")
	)
	(segment
		(start 401.074636 -232.462578)
		(end 401.953476 -233.341418)
		(width 0.20066)
		(layer "F.Cu")
		(net "M_E_CPU0_SB_CB<3>")
	)
	(segment
		(start 391.053066 -239.29594)
		(end 395.953996 -234.39501)
		(width 0.1016)
		(layer "F.Cu")
		(net "M_E_CPU0_SB_CB<3>")
	)
	(segment
		(start 411.803088 -232.941622)
		(end 411.72765 -233.01706)
		(width 0.20066)
		(layer "F.Cu")
		(net "M_E_CPU0_SB_CB<3>")
	)
	(segment
		(start 412.47187 -232.941622)
		(end 411.803088 -232.941622)
		(width 0.20066)
		(layer "F.Cu")
		(net "M_E_CPU0_SB_CB<3>")
	)
	(segment
		(start 388.279386 -240.117122)
		(end 389.100568 -239.29594)
		(width 0.1016)
		(layer "F.Cu")
		(net "M_E_CPU0_SB_CB<3>")
	)
	(segment
		(start 386.918962 -240.779046)
		(end 387.054852 -240.779046)
		(width 0.088646)
		(layer "F.Cu")
		(net "M_E_CPU0_SB_CB<3>")
	)
	(segment
		(start 416.283394 -234.957874)
		(end 416.082734 -235.158534)
		(width 0.20066)
		(layer "F.Cu")
		(net "M_E_CPU0_SB_CB<2>")
	)
	(segment
		(start 416.283394 -234.601766)
		(end 416.283394 -234.957874)
		(width 0.20066)
		(layer "F.Cu")
		(net "M_E_CPU0_SB_CB<2>")
	)
	(segment
		(start 405.570944 -234.291632)
		(end 405.745442 -234.291632)
		(width 0.101854)
		(layer "F.Cu")
		(net "M_E_CPU0_SB_CB<2>")
	)
	(segment
		(start 391.30605 -239.90554)
		(end 395.717268 -235.494322)
		(width 0.1016)
		(layer "F.Cu")
		(net "M_E_CPU0_SB_CB<2>")
	)
	(segment
		(start 413.111696 -235.14177)
		(end 413.097726 -235.15574)
		(width 0.101854)
		(layer "F.Cu")
		(net "M_E_CPU0_SB_CB<2>")
	)
	(segment
		(start 411.89656 -234.626404)
		(end 411.805882 -234.717082)
		(width 0.20066)
		(layer "F.Cu")
		(net "M_E_CPU0_SB_CB<2>")
	)
	(segment
		(start 415.798762 -235.158534)
		(end 415.781998 -235.14177)
		(width 0.101854)
		(layer "F.Cu")
		(net "M_E_CPU0_SB_CB<2>")
	)
	(segment
		(start 405.562054 -234.282742)
		(end 405.570944 -234.291632)
		(width 0.101854)
		(layer "F.Cu")
		(net "M_E_CPU0_SB_CB<2>")
	)
	(segment
		(start 411.805882 -234.717082)
		(end 410.85389 -234.717082)
		(width 0.20066)
		(layer "F.Cu")
		(net "M_E_CPU0_SB_CB<2>")
	)
	(segment
		(start 405.354028 -234.282742)
		(end 405.562054 -234.282742)
		(width 0.20066)
		(layer "F.Cu")
		(net "M_E_CPU0_SB_CB<2>")
	)
	(segment
		(start 396.865348 -235.494322)
		(end 397.690594 -234.669076)
		(width 0.20066)
		(layer "F.Cu")
		(net "M_E_CPU0_SB_CB<2>")
	)
	(segment
		(start 387.64337 -241.868706)
		(end 388.187438 -241.324638)
		(width 0.088646)
		(layer "F.Cu")
		(net "M_E_CPU0_SB_CB<2>")
	)
	(segment
		(start 407.890726 -234.291632)
		(end 407.911554 -234.270804)
		(width 0.101854)
		(layer "F.Cu")
		(net "M_E_CPU0_SB_CB<2>")
	)
	(segment
		(start 416.082734 -235.158534)
		(end 415.798762 -235.158534)
		(width 0.20066)
		(layer "F.Cu")
		(net "M_E_CPU0_SB_CB<2>")
	)
	(segment
		(start 416.805872 -234.401106)
		(end 416.484054 -234.401106)
		(width 0.20066)
		(layer "F.Cu")
		(net "M_E_CPU0_SB_CB<2>")
	)
	(segment
		(start 417.12134 -234.716574)
		(end 416.805872 -234.401106)
		(width 0.20066)
		(layer "F.Cu")
		(net "M_E_CPU0_SB_CB<2>")
	)
	(segment
		(start 415.781998 -235.14177)
		(end 415.29635 -235.14177)
		(width 0.101854)
		(layer "F.Cu")
		(net "M_E_CPU0_SB_CB<2>")
	)
	(segment
		(start 388.187438 -241.324638)
		(end 388.187438 -241.09299)
		(width 0.088646)
		(layer "F.Cu")
		(net "M_E_CPU0_SB_CB<2>")
	)
	(segment
		(start 388.187438 -241.09299)
		(end 388.391146 -240.889282)
		(width 0.088646)
		(layer "F.Cu")
		(net "M_E_CPU0_SB_CB<2>")
	)
	(segment
		(start 409.937966 -234.617768)
		(end 410.036772 -234.716574)
		(width 0.20066)
		(layer "F.Cu")
		(net "M_E_CPU0_SB_CB<2>")
	)
	(segment
		(start 408.080718 -234.270804)
		(end 408.427682 -234.617768)
		(width 0.20066)
		(layer "F.Cu")
		(net "M_E_CPU0_SB_CB<2>")
	)
	(segment
		(start 408.427682 -234.617768)
		(end 409.937966 -234.617768)
		(width 0.20066)
		(layer "F.Cu")
		(net "M_E_CPU0_SB_CB<2>")
	)
	(segment
		(start 407.911554 -234.270804)
		(end 408.080718 -234.270804)
		(width 0.20066)
		(layer "F.Cu")
		(net "M_E_CPU0_SB_CB<2>")
	)
	(segment
		(start 396.205964 -235.494322)
		(end 396.865348 -235.494322)
		(width 0.20066)
		(layer "F.Cu")
		(net "M_E_CPU0_SB_CB<2>")
	)
	(segment
		(start 397.690594 -234.669076)
		(end 401.425918 -234.669076)
		(width 0.20066)
		(layer "F.Cu")
		(net "M_E_CPU0_SB_CB<2>")
	)
	(segment
		(start 405.745442 -234.291632)
		(end 407.748486 -234.291632)
		(width 0.1016)
		(layer "F.Cu")
		(net "M_E_CPU0_SB_CB<2>")
	)
	(segment
		(start 386.364734 -242.017042)
		(end 386.365242 -242.017296)
		(width 0.088646)
		(layer "F.Cu")
		(net "M_E_CPU0_SB_CB<2>")
	)
	(segment
		(start 410.85389 -234.717082)
		(end 410.853382 -234.716574)
		(width 0.20066)
		(layer "F.Cu")
		(net "M_E_CPU0_SB_CB<2>")
	)
	(segment
		(start 386.365242 -242.017296)
		(end 386.632704 -241.906806)
		(width 0.088646)
		(layer "F.Cu")
		(net "M_E_CPU0_SB_CB<2>")
	)
	(segment
		(start 415.29635 -235.14177)
		(end 413.307022 -235.14177)
		(width 0.1016)
		(layer "F.Cu")
		(net "M_E_CPU0_SB_CB<2>")
	)
	(segment
		(start 388.391146 -240.889282)
		(end 389.374888 -239.90554)
		(width 0.1016)
		(layer "F.Cu")
		(net "M_E_CPU0_SB_CB<2>")
	)
	(segment
		(start 407.748486 -234.291632)
		(end 407.890726 -234.291632)
		(width 0.101854)
		(layer "F.Cu")
		(net "M_E_CPU0_SB_CB<2>")
	)
	(segment
		(start 410.036772 -234.716574)
		(end 410.853382 -234.716574)
		(width 0.20066)
		(layer "F.Cu")
		(net "M_E_CPU0_SB_CB<2>")
	)
	(segment
		(start 418.397182 -234.716574)
		(end 417.12134 -234.716574)
		(width 0.20066)
		(layer "F.Cu")
		(net "M_E_CPU0_SB_CB<2>")
	)
	(segment
		(start 402.695664 -234.879896)
		(end 402.896324 -234.679236)
		(width 0.20066)
		(layer "F.Cu")
		(net "M_E_CPU0_SB_CB<2>")
	)
	(segment
		(start 413.307022 -235.14177)
		(end 413.111696 -235.14177)
		(width 0.101854)
		(layer "F.Cu")
		(net "M_E_CPU0_SB_CB<2>")
	)
	(segment
		(start 412.971742 -235.15574)
		(end 412.442406 -234.626404)
		(width 0.20066)
		(layer "F.Cu")
		(net "M_E_CPU0_SB_CB<2>")
	)
	(segment
		(start 412.442406 -234.626404)
		(end 411.89656 -234.626404)
		(width 0.20066)
		(layer "F.Cu")
		(net "M_E_CPU0_SB_CB<2>")
	)
	(segment
		(start 389.374888 -239.90554)
		(end 391.30605 -239.90554)
		(width 0.1016)
		(layer "F.Cu")
		(net "M_E_CPU0_SB_CB<2>")
	)
	(segment
		(start 402.537422 -235.405422)
		(end 402.695664 -235.24718)
		(width 0.20066)
		(layer "F.Cu")
		(net "M_E_CPU0_SB_CB<2>")
	)
	(segment
		(start 402.695664 -235.24718)
		(end 402.695664 -234.879896)
		(width 0.20066)
		(layer "F.Cu")
		(net "M_E_CPU0_SB_CB<2>")
	)
	(segment
		(start 402.896324 -234.679236)
		(end 404.957534 -234.679236)
		(width 0.20066)
		(layer "F.Cu")
		(net "M_E_CPU0_SB_CB<2>")
	)
	(segment
		(start 386.82422 -241.868706)
		(end 387.64337 -241.868706)
		(width 0.088646)
		(layer "F.Cu")
		(net "M_E_CPU0_SB_CB<2>")
	)
	(segment
		(start 402.162264 -235.405422)
		(end 402.537422 -235.405422)
		(width 0.20066)
		(layer "F.Cu")
		(net "M_E_CPU0_SB_CB<2>")
	)
	(segment
		(start 416.484054 -234.401106)
		(end 416.283394 -234.601766)
		(width 0.20066)
		(layer "F.Cu")
		(net "M_E_CPU0_SB_CB<2>")
	)
	(segment
		(start 404.957534 -234.679236)
		(end 405.354028 -234.282742)
		(width 0.20066)
		(layer "F.Cu")
		(net "M_E_CPU0_SB_CB<2>")
	)
	(segment
		(start 401.425918 -234.669076)
		(end 402.162264 -235.405422)
		(width 0.20066)
		(layer "F.Cu")
		(net "M_E_CPU0_SB_CB<2>")
	)
	(segment
		(start 395.717268 -235.494322)
		(end 396.205964 -235.494322)
		(width 0.1016)
		(layer "F.Cu")
		(net "M_E_CPU0_SB_CB<2>")
	)
	(segment
		(start 413.097726 -235.15574)
		(end 412.971742 -235.15574)
		(width 0.20066)
		(layer "F.Cu")
		(net "M_E_CPU0_SB_CB<2>")
	)
	(arc
		(start 386.632704 -241.906806)
		(mid 386.726586 -241.878318)
		(end 386.82422 -241.868706)
		(width 0.088646)
		(layer "F.Cu")
		(net "M_E_CPU0_SB_CB<2>")
	)
	(segment
		(start 397.413734 -234.029504)
		(end 398.483074 -234.029504)
		(width 0.20066)
		(layer "F.Cu")
		(net "M_E_CPU0_SB_CB<1>")
	)
	(segment
		(start 413.26054 -233.953812)
		(end 412.900622 -233.953812)
		(width 0.20066)
		(layer "F.Cu")
		(net "M_E_CPU0_SB_CB<1>")
	)
	(segment
		(start 413.347662 -233.86669)
		(end 413.26054 -233.953812)
		(width 0.20066)
		(layer "F.Cu")
		(net "M_E_CPU0_SB_CB<1>")
	)
	(segment
		(start 396.205964 -234.85094)
		(end 396.592298 -234.85094)
		(width 0.20066)
		(layer "F.Cu")
		(net "M_E_CPU0_SB_CB<1>")
	)
	(segment
		(start 398.683734 -233.828844)
		(end 398.683734 -233.305096)
		(width 0.20066)
		(layer "F.Cu")
		(net "M_E_CPU0_SB_CB<1>")
	)
	(segment
		(start 385.595622 -241.650266)
		(end 387.552692 -241.650266)
		(width 0.088646)
		(layer "F.Cu")
		(net "M_E_CPU0_SB_CB<1>")
	)
	(segment
		(start 388.1755 -240.673636)
		(end 389.248396 -239.60074)
		(width 0.1016)
		(layer "F.Cu")
		(net "M_E_CPU0_SB_CB<1>")
	)
	(segment
		(start 387.839204 -241.009932)
		(end 388.1755 -240.673636)
		(width 0.088646)
		(layer "F.Cu")
		(net "M_E_CPU0_SB_CB<1>")
	)
	(segment
		(start 400.255994 -233.104436)
		(end 400.540474 -233.104436)
		(width 0.20066)
		(layer "F.Cu")
		(net "M_E_CPU0_SB_CB<1>")
	)
	(segment
		(start 409.660344 -233.42854)
		(end 409.302712 -233.42854)
		(width 0.20066)
		(layer "F.Cu")
		(net "M_E_CPU0_SB_CB<1>")
	)
	(segment
		(start 414.297114 -233.86669)
		(end 413.347662 -233.86669)
		(width 0.20066)
		(layer "F.Cu")
		(net "M_E_CPU0_SB_CB<1>")
	)
	(segment
		(start 400.055334 -233.828844)
		(end 400.055334 -233.305096)
		(width 0.20066)
		(layer "F.Cu")
		(net "M_E_CPU0_SB_CB<1>")
	)
	(segment
		(start 387.839204 -241.363754)
		(end 387.839204 -241.009932)
		(width 0.088646)
		(layer "F.Cu")
		(net "M_E_CPU0_SB_CB<1>")
	)
	(segment
		(start 399.369534 -233.828844)
		(end 399.570194 -234.029504)
		(width 0.20066)
		(layer "F.Cu")
		(net "M_E_CPU0_SB_CB<1>")
	)
	(segment
		(start 408.90317 -234.126786)
		(end 408.619198 -234.126786)
		(width 0.20066)
		(layer "F.Cu")
		(net "M_E_CPU0_SB_CB<1>")
	)
	(segment
		(start 409.102052 -233.927904)
		(end 408.90317 -234.126786)
		(width 0.20066)
		(layer "F.Cu")
		(net "M_E_CPU0_SB_CB<1>")
	)
	(segment
		(start 400.941794 -234.029504)
		(end 404.71598 -234.029504)
		(width 0.20066)
		(layer "F.Cu")
		(net "M_E_CPU0_SB_CB<1>")
	)
	(segment
		(start 412.900622 -233.953812)
		(end 412.371032 -233.424222)
		(width 0.20066)
		(layer "F.Cu")
		(net "M_E_CPU0_SB_CB<1>")
	)
	(segment
		(start 404.71598 -234.029504)
		(end 404.878794 -233.86669)
		(width 0.20066)
		(layer "F.Cu")
		(net "M_E_CPU0_SB_CB<1>")
	)
	(segment
		(start 400.741134 -233.305096)
		(end 400.741134 -233.828844)
		(width 0.20066)
		(layer "F.Cu")
		(net "M_E_CPU0_SB_CB<1>")
	)
	(segment
		(start 409.673552 -233.441748)
		(end 409.660344 -233.42854)
		(width 0.101854)
		(layer "F.Cu")
		(net "M_E_CPU0_SB_CB<1>")
	)
	(segment
		(start 399.570194 -234.029504)
		(end 399.854674 -234.029504)
		(width 0.20066)
		(layer "F.Cu")
		(net "M_E_CPU0_SB_CB<1>")
	)
	(segment
		(start 398.483074 -234.029504)
		(end 398.683734 -233.828844)
		(width 0.20066)
		(layer "F.Cu")
		(net "M_E_CPU0_SB_CB<1>")
	)
	(segment
		(start 404.878794 -233.86669)
		(end 406.753314 -233.86669)
		(width 0.20066)
		(layer "F.Cu")
		(net "M_E_CPU0_SB_CB<1>")
	)
	(segment
		(start 412.026862 -233.424222)
		(end 412.009336 -233.441748)
		(width 0.101854)
		(layer "F.Cu")
		(net "M_E_CPU0_SB_CB<1>")
	)
	(segment
		(start 408.619198 -234.126786)
		(end 408.359356 -233.866944)
		(width 0.20066)
		(layer "F.Cu")
		(net "M_E_CPU0_SB_CB<1>")
	)
	(segment
		(start 412.371032 -233.424222)
		(end 412.026862 -233.424222)
		(width 0.20066)
		(layer "F.Cu")
		(net "M_E_CPU0_SB_CB<1>")
	)
	(segment
		(start 398.683734 -233.305096)
		(end 398.884394 -233.104436)
		(width 0.20066)
		(layer "F.Cu")
		(net "M_E_CPU0_SB_CB<1>")
	)
	(segment
		(start 409.302712 -233.42854)
		(end 409.102052 -233.6292)
		(width 0.20066)
		(layer "F.Cu")
		(net "M_E_CPU0_SB_CB<1>")
	)
	(segment
		(start 409.102052 -233.6292)
		(end 409.102052 -233.927904)
		(width 0.20066)
		(layer "F.Cu")
		(net "M_E_CPU0_SB_CB<1>")
	)
	(segment
		(start 384.95478 -241.203226)
		(end 385.350766 -241.203226)
		(width 0.088646)
		(layer "F.Cu")
		(net "M_E_CPU0_SB_CB<1>")
	)
	(segment
		(start 412.009336 -233.441748)
		(end 411.817312 -233.441748)
		(width 0.101854)
		(layer "F.Cu")
		(net "M_E_CPU0_SB_CB<1>")
	)
	(segment
		(start 411.817312 -233.441748)
		(end 409.849828 -233.441748)
		(width 0.1016)
		(layer "F.Cu")
		(net "M_E_CPU0_SB_CB<1>")
	)
	(segment
		(start 396.592298 -234.85094)
		(end 397.413734 -234.029504)
		(width 0.20066)
		(layer "F.Cu")
		(net "M_E_CPU0_SB_CB<1>")
	)
	(segment
		(start 385.350766 -241.203226)
		(end 385.444746 -241.297206)
		(width 0.088646)
		(layer "F.Cu")
		(net "M_E_CPU0_SB_CB<1>")
	)
	(segment
		(start 389.248396 -239.60074)
		(end 391.179558 -239.60074)
		(width 0.1016)
		(layer "F.Cu")
		(net "M_E_CPU0_SB_CB<1>")
	)
	(segment
		(start 391.179558 -239.60074)
		(end 395.929358 -234.85094)
		(width 0.1016)
		(layer "F.Cu")
		(net "M_E_CPU0_SB_CB<1>")
	)
	(segment
		(start 385.444746 -241.297206)
		(end 385.444746 -241.49939)
		(width 0.088646)
		(layer "F.Cu")
		(net "M_E_CPU0_SB_CB<1>")
	)
	(segment
		(start 385.444746 -241.49939)
		(end 385.595622 -241.650266)
		(width 0.088646)
		(layer "F.Cu")
		(net "M_E_CPU0_SB_CB<1>")
	)
	(segment
		(start 400.540474 -233.104436)
		(end 400.741134 -233.305096)
		(width 0.20066)
		(layer "F.Cu")
		(net "M_E_CPU0_SB_CB<1>")
	)
	(segment
		(start 406.753568 -233.866944)
		(end 406.753314 -233.86669)
		(width 0.20066)
		(layer "F.Cu")
		(net "M_E_CPU0_SB_CB<1>")
	)
	(segment
		(start 408.359356 -233.866944)
		(end 406.753568 -233.866944)
		(width 0.20066)
		(layer "F.Cu")
		(net "M_E_CPU0_SB_CB<1>")
	)
	(segment
		(start 409.849828 -233.441748)
		(end 409.673552 -233.441748)
		(width 0.101854)
		(layer "F.Cu")
		(net "M_E_CPU0_SB_CB<1>")
	)
	(segment
		(start 400.741134 -233.828844)
		(end 400.941794 -234.029504)
		(width 0.20066)
		(layer "F.Cu")
		(net "M_E_CPU0_SB_CB<1>")
	)
	(segment
		(start 399.854674 -234.029504)
		(end 400.055334 -233.828844)
		(width 0.20066)
		(layer "F.Cu")
		(net "M_E_CPU0_SB_CB<1>")
	)
	(segment
		(start 400.055334 -233.305096)
		(end 400.255994 -233.104436)
		(width 0.20066)
		(layer "F.Cu")
		(net "M_E_CPU0_SB_CB<1>")
	)
	(segment
		(start 399.369534 -233.305096)
		(end 399.369534 -233.828844)
		(width 0.20066)
		(layer "F.Cu")
		(net "M_E_CPU0_SB_CB<1>")
	)
	(segment
		(start 395.929358 -234.85094)
		(end 396.205964 -234.85094)
		(width 0.1016)
		(layer "F.Cu")
		(net "M_E_CPU0_SB_CB<1>")
	)
	(segment
		(start 387.552692 -241.650266)
		(end 387.839204 -241.363754)
		(width 0.088646)
		(layer "F.Cu")
		(net "M_E_CPU0_SB_CB<1>")
	)
	(segment
		(start 399.168874 -233.104436)
		(end 399.369534 -233.305096)
		(width 0.20066)
		(layer "F.Cu")
		(net "M_E_CPU0_SB_CB<1>")
	)
	(segment
		(start 398.884394 -233.104436)
		(end 399.168874 -233.104436)
		(width 0.20066)
		(layer "F.Cu")
		(net "M_E_CPU0_SB_CB<1>")
	)
	(segment
		(start 398.458182 -235.308648)
		(end 398.658842 -235.509308)
		(width 0.20066)
		(layer "F.Cu")
		(net "M_E_CPU0_SB_CB<0>")
	)
	(segment
		(start 388.486142 -241.228626)
		(end 388.60857 -241.106198)
		(width 0.088646)
		(layer "F.Cu")
		(net "M_E_CPU0_SB_CB<0>")
	)
	(segment
		(start 385.09067 -242.244626)
		(end 385.32943 -242.382802)
		(width 0.088646)
		(layer "F.Cu")
		(net "M_E_CPU0_SB_CB<0>")
	)
	(segment
		(start 400.716242 -235.90631)
		(end 400.716242 -235.549694)
		(width 0.20066)
		(layer "F.Cu")
		(net "M_E_CPU0_SB_CB<0>")
	)
	(segment
		(start 399.344642 -235.95457)
		(end 399.344642 -235.509308)
		(width 0.20066)
		(layer "F.Cu")
		(net "M_E_CPU0_SB_CB<0>")
	)
	(segment
		(start 387.728714 -242.074446)
		(end 388.486142 -241.317018)
		(width 0.088646)
		(layer "F.Cu")
		(net "M_E_CPU0_SB_CB<0>")
	)
	(segment
		(start 405.34971 -235.566712)
		(end 406.753314 -235.566712)
		(width 0.20066)
		(layer "F.Cu")
		(net "M_E_CPU0_SB_CB<0>")
	)
	(segment
		(start 401.402042 -235.549694)
		(end 401.402042 -235.89107)
		(width 0.20066)
		(layer "F.Cu")
		(net "M_E_CPU0_SB_CB<0>")
	)
	(segment
		(start 384.478784 -242.155726)
		(end 384.567684 -242.244626)
		(width 0.088646)
		(layer "F.Cu")
		(net "M_E_CPU0_SB_CB<0>")
	)
	(segment
		(start 401.402042 -235.89107)
		(end 401.602702 -236.09173)
		(width 0.20066)
		(layer "F.Cu")
		(net "M_E_CPU0_SB_CB<0>")
	)
	(segment
		(start 407.308558 -235.566712)
		(end 406.753314 -235.566712)
		(width 0.20066)
		(layer "F.Cu")
		(net "M_E_CPU0_SB_CB<0>")
	)
	(segment
		(start 407.721308 -235.153962)
		(end 407.308558 -235.566712)
		(width 0.20066)
		(layer "F.Cu")
		(net "M_E_CPU0_SB_CB<0>")
	)
	(segment
		(start 409.393644 -235.116116)
		(end 409.287472 -235.116116)
		(width 0.20066)
		(layer "F.Cu")
		(net "M_E_CPU0_SB_CB<0>")
	)
	(segment
		(start 412.811468 -235.566712)
		(end 412.386526 -235.14177)
		(width 0.20066)
		(layer "F.Cu")
		(net "M_E_CPU0_SB_CB<0>")
	)
	(segment
		(start 400.030442 -235.90631)
		(end 400.231102 -236.10697)
		(width 0.20066)
		(layer "F.Cu")
		(net "M_E_CPU0_SB_CB<0>")
	)
	(segment
		(start 397.973042 -235.951776)
		(end 397.973042 -235.509308)
		(width 0.20066)
		(layer "F.Cu")
		(net "M_E_CPU0_SB_CB<0>")
	)
	(segment
		(start 403.490176 -235.328968)
		(end 405.111966 -235.328968)
		(width 0.20066)
		(layer "F.Cu")
		(net "M_E_CPU0_SB_CB<0>")
	)
	(segment
		(start 409.419298 -235.14177)
		(end 409.393644 -235.116116)
		(width 0.101854)
		(layer "F.Cu")
		(net "M_E_CPU0_SB_CB<0>")
	)
	(segment
		(start 395.490446 -236.152436)
		(end 395.901164 -236.152436)
		(width 0.1016)
		(layer "F.Cu")
		(net "M_E_CPU0_SB_CB<0>")
	)
	(segment
		(start 408.549348 -235.570268)
		(end 408.133042 -235.153962)
		(width 0.20066)
		(layer "F.Cu")
		(net "M_E_CPU0_SB_CB<0>")
	)
	(segment
		(start 389.504428 -240.21034)
		(end 391.432542 -240.21034)
		(width 0.1016)
		(layer "F.Cu")
		(net "M_E_CPU0_SB_CB<0>")
	)
	(segment
		(start 388.60857 -241.106198)
		(end 389.504428 -240.21034)
		(width 0.1016)
		(layer "F.Cu")
		(net "M_E_CPU0_SB_CB<0>")
	)
	(segment
		(start 411.852618 -235.14177)
		(end 409.867354 -235.14177)
		(width 0.1016)
		(layer "F.Cu")
		(net "M_E_CPU0_SB_CB<0>")
	)
	(segment
		(start 386.827776 -242.074446)
		(end 387.728714 -242.074446)
		(width 0.088646)
		(layer "F.Cu")
		(net "M_E_CPU0_SB_CB<0>")
	)
	(segment
		(start 403.289516 -235.89107)
		(end 403.289516 -235.529628)
		(width 0.20066)
		(layer "F.Cu")
		(net "M_E_CPU0_SB_CB<0>")
	)
	(segment
		(start 397.772382 -236.152436)
		(end 397.973042 -235.951776)
		(width 0.20066)
		(layer "F.Cu")
		(net "M_E_CPU0_SB_CB<0>")
	)
	(segment
		(start 400.231102 -236.10697)
		(end 400.515582 -236.10697)
		(width 0.20066)
		(layer "F.Cu")
		(net "M_E_CPU0_SB_CB<0>")
	)
	(segment
		(start 384.478784 -242.023392)
		(end 384.478784 -242.155726)
		(width 0.088646)
		(layer "F.Cu")
		(net "M_E_CPU0_SB_CB<0>")
	)
	(segment
		(start 398.173702 -235.308648)
		(end 398.458182 -235.308648)
		(width 0.20066)
		(layer "F.Cu")
		(net "M_E_CPU0_SB_CB<0>")
	)
	(segment
		(start 386.579618 -242.320572)
		(end 386.827776 -242.074446)
		(width 0.088646)
		(layer "F.Cu")
		(net "M_E_CPU0_SB_CB<0>")
	)
	(segment
		(start 403.289516 -235.529628)
		(end 403.490176 -235.328968)
		(width 0.20066)
		(layer "F.Cu")
		(net "M_E_CPU0_SB_CB<0>")
	)
	(segment
		(start 397.973042 -235.509308)
		(end 398.173702 -235.308648)
		(width 0.20066)
		(layer "F.Cu")
		(net "M_E_CPU0_SB_CB<0>")
	)
	(segment
		(start 384.485134 -242.017042)
		(end 384.478784 -242.023392)
		(width 0.088646)
		(layer "F.Cu")
		(net "M_E_CPU0_SB_CB<0>")
	)
	(segment
		(start 385.520184 -242.450874)
		(end 385.538726 -242.453922)
		(width 0.088646)
		(layer "F.Cu")
		(net "M_E_CPU0_SB_CB<0>")
	)
	(segment
		(start 386.143754 -242.442746)
		(end 386.204714 -242.442746)
		(width 0.088646)
		(layer "F.Cu")
		(net "M_E_CPU0_SB_CB<0>")
	)
	(segment
		(start 409.287472 -235.116116)
		(end 408.83332 -235.570268)
		(width 0.20066)
		(layer "F.Cu")
		(net "M_E_CPU0_SB_CB<0>")
	)
	(segment
		(start 400.515582 -236.10697)
		(end 400.716242 -235.90631)
		(width 0.20066)
		(layer "F.Cu")
		(net "M_E_CPU0_SB_CB<0>")
	)
	(segment
		(start 398.658842 -235.95457)
		(end 398.859502 -236.15523)
		(width 0.20066)
		(layer "F.Cu")
		(net "M_E_CPU0_SB_CB<0>")
	)
	(segment
		(start 412.386526 -235.14177)
		(end 412.176976 -235.14177)
		(width 0.20066)
		(layer "F.Cu")
		(net "M_E_CPU0_SB_CB<0>")
	)
	(segment
		(start 400.916902 -235.349034)
		(end 401.201382 -235.349034)
		(width 0.20066)
		(layer "F.Cu")
		(net "M_E_CPU0_SB_CB<0>")
	)
	(segment
		(start 398.658842 -235.509308)
		(end 398.658842 -235.95457)
		(width 0.20066)
		(layer "F.Cu")
		(net "M_E_CPU0_SB_CB<0>")
	)
	(segment
		(start 399.829782 -235.308648)
		(end 400.030442 -235.509308)
		(width 0.20066)
		(layer "F.Cu")
		(net "M_E_CPU0_SB_CB<0>")
	)
	(segment
		(start 388.486142 -241.317018)
		(end 388.486142 -241.228626)
		(width 0.088646)
		(layer "F.Cu")
		(net "M_E_CPU0_SB_CB<0>")
	)
	(segment
		(start 409.867354 -235.14177)
		(end 409.419298 -235.14177)
		(width 0.101854)
		(layer "F.Cu")
		(net "M_E_CPU0_SB_CB<0>")
	)
	(segment
		(start 395.901164 -236.152436)
		(end 397.772382 -236.152436)
		(width 0.20066)
		(layer "F.Cu")
		(net "M_E_CPU0_SB_CB<0>")
	)
	(segment
		(start 408.133042 -235.153962)
		(end 407.721308 -235.153962)
		(width 0.20066)
		(layer "F.Cu")
		(net "M_E_CPU0_SB_CB<0>")
	)
	(segment
		(start 405.111966 -235.328968)
		(end 405.34971 -235.566712)
		(width 0.20066)
		(layer "F.Cu")
		(net "M_E_CPU0_SB_CB<0>")
	)
	(segment
		(start 384.567684 -242.244626)
		(end 385.09067 -242.244626)
		(width 0.088646)
		(layer "F.Cu")
		(net "M_E_CPU0_SB_CB<0>")
	)
	(segment
		(start 400.030442 -235.509308)
		(end 400.030442 -235.90631)
		(width 0.20066)
		(layer "F.Cu")
		(net "M_E_CPU0_SB_CB<0>")
	)
	(segment
		(start 399.143982 -236.15523)
		(end 399.344642 -235.95457)
		(width 0.20066)
		(layer "F.Cu")
		(net "M_E_CPU0_SB_CB<0>")
	)
	(segment
		(start 386.428234 -242.39982)
		(end 386.505196 -242.36934)
		(width 0.088646)
		(layer "F.Cu")
		(net "M_E_CPU0_SB_CB<0>")
	)
	(segment
		(start 408.83332 -235.570268)
		(end 408.549348 -235.570268)
		(width 0.20066)
		(layer "F.Cu")
		(net "M_E_CPU0_SB_CB<0>")
	)
	(segment
		(start 401.201382 -235.349034)
		(end 401.402042 -235.549694)
		(width 0.20066)
		(layer "F.Cu")
		(net "M_E_CPU0_SB_CB<0>")
	)
	(segment
		(start 412.176976 -235.14177)
		(end 411.852618 -235.14177)
		(width 0.101854)
		(layer "F.Cu")
		(net "M_E_CPU0_SB_CB<0>")
	)
	(segment
		(start 399.344642 -235.509308)
		(end 399.545302 -235.308648)
		(width 0.20066)
		(layer "F.Cu")
		(net "M_E_CPU0_SB_CB<0>")
	)
	(segment
		(start 391.432542 -240.21034)
		(end 395.490446 -236.152436)
		(width 0.1016)
		(layer "F.Cu")
		(net "M_E_CPU0_SB_CB<0>")
	)
	(segment
		(start 403.088856 -236.09173)
		(end 403.289516 -235.89107)
		(width 0.20066)
		(layer "F.Cu")
		(net "M_E_CPU0_SB_CB<0>")
	)
	(segment
		(start 414.297114 -235.566712)
		(end 412.811468 -235.566712)
		(width 0.20066)
		(layer "F.Cu")
		(net "M_E_CPU0_SB_CB<0>")
	)
	(segment
		(start 401.602702 -236.09173)
		(end 403.088856 -236.09173)
		(width 0.20066)
		(layer "F.Cu")
		(net "M_E_CPU0_SB_CB<0>")
	)
	(segment
		(start 400.716242 -235.549694)
		(end 400.916902 -235.349034)
		(width 0.20066)
		(layer "F.Cu")
		(net "M_E_CPU0_SB_CB<0>")
	)
	(segment
		(start 399.545302 -235.308648)
		(end 399.829782 -235.308648)
		(width 0.20066)
		(layer "F.Cu")
		(net "M_E_CPU0_SB_CB<0>")
	)
	(segment
		(start 398.859502 -236.15523)
		(end 399.143982 -236.15523)
		(width 0.20066)
		(layer "F.Cu")
		(net "M_E_CPU0_SB_CB<0>")
	)
	(arc
		(start 386.204714 -242.442746)
		(mid 386.318514 -242.431899)
		(end 386.428234 -242.39982)
		(width 0.088646)
		(layer "F.Cu")
		(net "M_E_CPU0_SB_CB<0>")
	)
	(arc
		(start 386.505196 -242.36934)
		(mid 386.544865 -242.348712)
		(end 386.579618 -242.320572)
		(width 0.088646)
		(layer "F.Cu")
		(net "M_E_CPU0_SB_CB<0>")
	)
	(arc
		(start 386.039614 -242.399566)
		(mid 386.087394 -242.431491)
		(end 386.143754 -242.442746)
		(width 0.088646)
		(layer "F.Cu")
		(net "M_E_CPU0_SB_CB<0>")
	)
	(arc
		(start 385.706874 -242.399566)
		(mid 385.873244 -242.330653)
		(end 386.039614 -242.399566)
		(width 0.088646)
		(layer "F.Cu")
		(net "M_E_CPU0_SB_CB<0>")
	)
	(arc
		(start 385.32943 -242.382802)
		(mid 385.4217 -242.425542)
		(end 385.520184 -242.450874)
		(width 0.088646)
		(layer "F.Cu")
		(net "M_E_CPU0_SB_CB<0>")
	)
	(arc
		(start 385.538726 -242.453922)
		(mid 385.629358 -242.447017)
		(end 385.706874 -242.399566)
		(width 0.088646)
		(layer "F.Cu")
		(net "M_E_CPU0_SB_CB<0>")
	)
	(segment
		(start 397.425164 -246.175784)
		(end 399.420334 -248.170954)
		(width 0.20066)
		(layer "F.Cu")
		(net "M_E_CPU0_SB_CA<6>")
	)
	(segment
		(start 411.854142 -247.891554)
		(end 409.850844 -247.891554)
		(width 0.1016)
		(layer "F.Cu")
		(net "M_E_CPU0_SB_CA<6>")
	)
	(segment
		(start 384.015234 -247.714262)
		(end 384.327654 -248.026682)
		(width 0.088646)
		(layer "F.Cu")
		(net "M_E_CPU0_SB_CA<6>")
	)
	(segment
		(start 409.831794 -247.905778)
		(end 409.342082 -247.905778)
		(width 0.20066)
		(layer "F.Cu")
		(net "M_E_CPU0_SB_CA<6>")
	)
	(segment
		(start 393.760452 -247.189752)
		(end 394.04163 -246.908574)
		(width 0.1016)
		(layer "F.Cu")
		(net "M_E_CPU0_SB_CA<6>")
	)
	(segment
		(start 394.04163 -246.908574)
		(end 394.77442 -246.175784)
		(width 0.20066)
		(layer "F.Cu")
		(net "M_E_CPU0_SB_CA<6>")
	)
	(segment
		(start 407.627074 -247.850914)
		(end 407.242772 -247.466612)
		(width 0.20066)
		(layer "F.Cu")
		(net "M_E_CPU0_SB_CA<6>")
	)
	(segment
		(start 414.297114 -247.466612)
		(end 413.389826 -247.466612)
		(width 0.20066)
		(layer "F.Cu")
		(net "M_E_CPU0_SB_CA<6>")
	)
	(segment
		(start 386.361432 -247.555004)
		(end 386.76453 -247.366536)
		(width 0.088646)
		(layer "F.Cu")
		(net "M_E_CPU0_SB_CA<6>")
	)
	(segment
		(start 388.713218 -247.404382)
		(end 388.927848 -247.189752)
		(width 0.1016)
		(layer "F.Cu")
		(net "M_E_CPU0_SB_CA<6>")
	)
	(segment
		(start 388.41172 -247.70588)
		(end 388.713218 -247.404382)
		(width 0.088646)
		(layer "F.Cu")
		(net "M_E_CPU0_SB_CA<6>")
	)
	(segment
		(start 408.125676 -247.850914)
		(end 407.627074 -247.850914)
		(width 0.20066)
		(layer "F.Cu")
		(net "M_E_CPU0_SB_CA<6>")
	)
	(segment
		(start 411.863794 -247.901206)
		(end 411.854142 -247.891554)
		(width 0.1016)
		(layer "F.Cu")
		(net "M_E_CPU0_SB_CA<6>")
	)
	(segment
		(start 405.401272 -247.813322)
		(end 405.499316 -247.813322)
		(width 0.20066)
		(layer "F.Cu")
		(net "M_E_CPU0_SB_CA<6>")
	)
	(segment
		(start 413.389826 -247.466612)
		(end 412.759398 -248.09704)
		(width 0.20066)
		(layer "F.Cu")
		(net "M_E_CPU0_SB_CA<6>")
	)
	(segment
		(start 405.846026 -247.466612)
		(end 406.753314 -247.466612)
		(width 0.20066)
		(layer "F.Cu")
		(net "M_E_CPU0_SB_CA<6>")
	)
	(segment
		(start 409.342082 -247.905778)
		(end 408.937968 -248.309892)
		(width 0.20066)
		(layer "F.Cu")
		(net "M_E_CPU0_SB_CA<6>")
	)
	(segment
		(start 408.937968 -248.309892)
		(end 408.584654 -248.309892)
		(width 0.20066)
		(layer "F.Cu")
		(net "M_E_CPU0_SB_CA<6>")
	)
	(segment
		(start 388.927848 -247.189752)
		(end 393.760452 -247.189752)
		(width 0.1016)
		(layer "F.Cu")
		(net "M_E_CPU0_SB_CA<6>")
	)
	(segment
		(start 386.76453 -247.366536)
		(end 387.08965 -247.366536)
		(width 0.088646)
		(layer "F.Cu")
		(net "M_E_CPU0_SB_CA<6>")
	)
	(segment
		(start 405.499316 -247.813322)
		(end 405.846026 -247.466612)
		(width 0.20066)
		(layer "F.Cu")
		(net "M_E_CPU0_SB_CA<6>")
	)
	(segment
		(start 387.08965 -247.366536)
		(end 387.428994 -247.70588)
		(width 0.088646)
		(layer "F.Cu")
		(net "M_E_CPU0_SB_CA<6>")
	)
	(segment
		(start 412.759398 -248.09704)
		(end 412.475426 -248.09704)
		(width 0.20066)
		(layer "F.Cu")
		(net "M_E_CPU0_SB_CA<6>")
	)
	(segment
		(start 412.475426 -248.09704)
		(end 412.279592 -247.901206)
		(width 0.20066)
		(layer "F.Cu")
		(net "M_E_CPU0_SB_CA<6>")
	)
	(segment
		(start 408.584654 -248.309892)
		(end 408.125676 -247.850914)
		(width 0.20066)
		(layer "F.Cu")
		(net "M_E_CPU0_SB_CA<6>")
	)
	(segment
		(start 409.850844 -247.891554)
		(end 409.83662 -247.905778)
		(width 0.1016)
		(layer "F.Cu")
		(net "M_E_CPU0_SB_CA<6>")
	)
	(segment
		(start 384.723894 -248.026682)
		(end 384.82143 -248.06402)
		(width 0.088646)
		(layer "F.Cu")
		(net "M_E_CPU0_SB_CA<6>")
	)
	(segment
		(start 387.428994 -247.70588)
		(end 388.41172 -247.70588)
		(width 0.088646)
		(layer "F.Cu")
		(net "M_E_CPU0_SB_CA<6>")
	)
	(segment
		(start 399.420334 -248.170954)
		(end 405.04364 -248.170954)
		(width 0.20066)
		(layer "F.Cu")
		(net "M_E_CPU0_SB_CA<6>")
	)
	(segment
		(start 394.77442 -246.175784)
		(end 397.425164 -246.175784)
		(width 0.20066)
		(layer "F.Cu")
		(net "M_E_CPU0_SB_CA<6>")
	)
	(segment
		(start 385.697222 -248.032524)
		(end 385.707636 -248.03862)
		(width 0.088646)
		(layer "F.Cu")
		(net "M_E_CPU0_SB_CA<6>")
	)
	(segment
		(start 384.327654 -248.026682)
		(end 384.723894 -248.026682)
		(width 0.088646)
		(layer "F.Cu")
		(net "M_E_CPU0_SB_CA<6>")
	)
	(segment
		(start 412.279592 -247.901206)
		(end 411.863794 -247.901206)
		(width 0.20066)
		(layer "F.Cu")
		(net "M_E_CPU0_SB_CA<6>")
	)
	(segment
		(start 405.04364 -248.170954)
		(end 405.401272 -247.813322)
		(width 0.20066)
		(layer "F.Cu")
		(net "M_E_CPU0_SB_CA<6>")
	)
	(segment
		(start 409.83662 -247.905778)
		(end 409.831794 -247.905778)
		(width 0.101854)
		(layer "F.Cu")
		(net "M_E_CPU0_SB_CA<6>")
	)
	(segment
		(start 407.242772 -247.466612)
		(end 406.753314 -247.466612)
		(width 0.20066)
		(layer "F.Cu")
		(net "M_E_CPU0_SB_CA<6>")
	)
	(arc
		(start 386.26923 -247.714262)
		(mid 386.294018 -247.622308)
		(end 386.361432 -247.555004)
		(width 0.088646)
		(layer "F.Cu")
		(net "M_E_CPU0_SB_CA<6>")
	)
	(arc
		(start 386.082032 -248.03862)
		(mid 386.219057 -247.901507)
		(end 386.26923 -247.714262)
		(width 0.088646)
		(layer "F.Cu")
		(net "M_E_CPU0_SB_CA<6>")
	)
	(arc
		(start 384.82143 -248.06402)
		(mid 384.984575 -248.087502)
		(end 385.141978 -248.03862)
		(width 0.088646)
		(layer "F.Cu")
		(net "M_E_CPU0_SB_CA<6>")
	)
	(arc
		(start 385.707636 -248.03862)
		(mid 385.894834 -248.088763)
		(end 386.082032 -248.03862)
		(width 0.088646)
		(layer "F.Cu")
		(net "M_E_CPU0_SB_CA<6>")
	)
	(arc
		(start 385.141978 -248.03862)
		(mid 385.418791 -247.96275)
		(end 385.697222 -248.032524)
		(width 0.088646)
		(layer "F.Cu")
		(net "M_E_CPU0_SB_CA<6>")
	)
	(segment
		(start 411.787594 -248.31675)
		(end 410.853382 -248.31675)
		(width 0.20066)
		(layer "F.Cu")
		(net "M_E_CPU0_SB_CA<5>")
	)
	(segment
		(start 388.938008 -247.712992)
		(end 389.156448 -247.494552)
		(width 0.1016)
		(layer "F.Cu")
		(net "M_E_CPU0_SB_CA<5>")
	)
	(segment
		(start 405.77897 -248.741692)
		(end 407.705306 -248.741692)
		(width 0.1016)
		(layer "F.Cu")
		(net "M_E_CPU0_SB_CA<5>")
	)
	(segment
		(start 407.763726 -248.760234)
		(end 409.305506 -248.760234)
		(width 0.20066)
		(layer "F.Cu")
		(net "M_E_CPU0_SB_CA<5>")
	)
	(segment
		(start 417.56457 -248.31675)
		(end 417.314888 -248.566432)
		(width 0.20066)
		(layer "F.Cu")
		(net "M_E_CPU0_SB_CA<5>")
	)
	(segment
		(start 413.302958 -248.741692)
		(end 413.29483 -248.74982)
		(width 0.1016)
		(layer "F.Cu")
		(net "M_E_CPU0_SB_CA<5>")
	)
	(segment
		(start 416.509708 -248.264172)
		(end 416.020504 -248.264172)
		(width 0.20066)
		(layer "F.Cu")
		(net "M_E_CPU0_SB_CA<5>")
	)
	(segment
		(start 412.220664 -248.74982)
		(end 411.787594 -248.31675)
		(width 0.20066)
		(layer "F.Cu")
		(net "M_E_CPU0_SB_CA<5>")
	)
	(segment
		(start 389.156448 -247.494552)
		(end 394.369036 -247.494552)
		(width 0.1016)
		(layer "F.Cu")
		(net "M_E_CPU0_SB_CA<5>")
	)
	(segment
		(start 397.160242 -246.815356)
		(end 399.155412 -248.810526)
		(width 0.20066)
		(layer "F.Cu")
		(net "M_E_CPU0_SB_CA<5>")
	)
	(segment
		(start 417.314888 -248.566432)
		(end 416.811968 -248.566432)
		(width 0.20066)
		(layer "F.Cu")
		(net "M_E_CPU0_SB_CA<5>")
	)
	(segment
		(start 405.731726 -248.765568)
		(end 405.755094 -248.765568)
		(width 0.101854)
		(layer "F.Cu")
		(net "M_E_CPU0_SB_CA<5>")
	)
	(segment
		(start 415.307526 -248.765314)
		(end 415.283904 -248.741692)
		(width 0.1016)
		(layer "F.Cu")
		(net "M_E_CPU0_SB_CA<5>")
	)
	(segment
		(start 395.048232 -246.815356)
		(end 397.160242 -246.815356)
		(width 0.20066)
		(layer "F.Cu")
		(net "M_E_CPU0_SB_CA<5>")
	)
	(segment
		(start 418.397182 -248.31675)
		(end 417.56457 -248.31675)
		(width 0.20066)
		(layer "F.Cu")
		(net "M_E_CPU0_SB_CA<5>")
	)
	(segment
		(start 399.155412 -248.810526)
		(end 405.319738 -248.810526)
		(width 0.20066)
		(layer "F.Cu")
		(net "M_E_CPU0_SB_CA<5>")
	)
	(segment
		(start 413.29483 -248.74982)
		(end 413.275526 -248.74982)
		(width 0.101854)
		(layer "F.Cu")
		(net "M_E_CPU0_SB_CA<5>")
	)
	(segment
		(start 409.450794 -248.614946)
		(end 409.450794 -248.49709)
		(width 0.20066)
		(layer "F.Cu")
		(net "M_E_CPU0_SB_CA<5>")
	)
	(segment
		(start 415.928048 -248.536968)
		(end 415.699702 -248.765314)
		(width 0.20066)
		(layer "F.Cu")
		(net "M_E_CPU0_SB_CA<5>")
	)
	(segment
		(start 394.369036 -247.494552)
		(end 394.498322 -247.365266)
		(width 0.1016)
		(layer "F.Cu")
		(net "M_E_CPU0_SB_CA<5>")
	)
	(segment
		(start 386.83438 -247.714262)
		(end 386.93598 -247.714262)
		(width 0.088646)
		(layer "F.Cu")
		(net "M_E_CPU0_SB_CA<5>")
	)
	(segment
		(start 407.723848 -248.760234)
		(end 407.763726 -248.760234)
		(width 0.101854)
		(layer "F.Cu")
		(net "M_E_CPU0_SB_CA<5>")
	)
	(segment
		(start 415.699702 -248.765314)
		(end 415.307526 -248.765314)
		(width 0.20066)
		(layer "F.Cu")
		(net "M_E_CPU0_SB_CA<5>")
	)
	(segment
		(start 413.275526 -248.74982)
		(end 412.220664 -248.74982)
		(width 0.20066)
		(layer "F.Cu")
		(net "M_E_CPU0_SB_CA<5>")
	)
	(segment
		(start 409.450794 -248.49709)
		(end 409.631134 -248.31675)
		(width 0.20066)
		(layer "F.Cu")
		(net "M_E_CPU0_SB_CA<5>")
	)
	(segment
		(start 386.93598 -247.714262)
		(end 387.20395 -247.982232)
		(width 0.088646)
		(layer "F.Cu")
		(net "M_E_CPU0_SB_CA<5>")
	)
	(segment
		(start 415.928048 -248.356628)
		(end 415.928048 -248.536968)
		(width 0.20066)
		(layer "F.Cu")
		(net "M_E_CPU0_SB_CA<5>")
	)
	(segment
		(start 416.811968 -248.566432)
		(end 416.509708 -248.264172)
		(width 0.20066)
		(layer "F.Cu")
		(net "M_E_CPU0_SB_CA<5>")
	)
	(segment
		(start 405.755094 -248.765568)
		(end 405.77897 -248.741692)
		(width 0.1016)
		(layer "F.Cu")
		(net "M_E_CPU0_SB_CA<5>")
	)
	(segment
		(start 407.705306 -248.741692)
		(end 407.723848 -248.760234)
		(width 0.1016)
		(layer "F.Cu")
		(net "M_E_CPU0_SB_CA<5>")
	)
	(segment
		(start 409.305506 -248.760234)
		(end 409.450794 -248.614946)
		(width 0.20066)
		(layer "F.Cu")
		(net "M_E_CPU0_SB_CA<5>")
	)
	(segment
		(start 416.020504 -248.264172)
		(end 415.928048 -248.356628)
		(width 0.20066)
		(layer "F.Cu")
		(net "M_E_CPU0_SB_CA<5>")
	)
	(segment
		(start 405.319738 -248.810526)
		(end 405.364696 -248.765568)
		(width 0.20066)
		(layer "F.Cu")
		(net "M_E_CPU0_SB_CA<5>")
	)
	(segment
		(start 388.668768 -247.982232)
		(end 388.938008 -247.712992)
		(width 0.088646)
		(layer "F.Cu")
		(net "M_E_CPU0_SB_CA<5>")
	)
	(segment
		(start 415.283904 -248.741692)
		(end 413.302958 -248.741692)
		(width 0.1016)
		(layer "F.Cu")
		(net "M_E_CPU0_SB_CA<5>")
	)
	(segment
		(start 394.498322 -247.365266)
		(end 395.048232 -246.815356)
		(width 0.20066)
		(layer "F.Cu")
		(net "M_E_CPU0_SB_CA<5>")
	)
	(segment
		(start 409.631134 -248.31675)
		(end 410.853382 -248.31675)
		(width 0.20066)
		(layer "F.Cu")
		(net "M_E_CPU0_SB_CA<5>")
	)
	(segment
		(start 405.364696 -248.765568)
		(end 405.731726 -248.765568)
		(width 0.20066)
		(layer "F.Cu")
		(net "M_E_CPU0_SB_CA<5>")
	)
	(segment
		(start 387.20395 -247.982232)
		(end 388.668768 -247.982232)
		(width 0.088646)
		(layer "F.Cu")
		(net "M_E_CPU0_SB_CA<5>")
	)
	(segment
		(start 399.015712 -249.575574)
		(end 405.552402 -249.575574)
		(width 0.20066)
		(layer "F.Cu")
		(net "M_E_CPU0_SB_CA<4>")
	)
	(segment
		(start 409.25623 -249.336814)
		(end 408.823668 -249.336814)
		(width 0.20066)
		(layer "F.Cu")
		(net "M_E_CPU0_SB_CA<4>")
	)
	(segment
		(start 385.611878 -248.20372)
		(end 385.612132 -248.20372)
		(width 0.088646)
		(layer "F.Cu")
		(net "M_E_CPU0_SB_CA<4>")
	)
	(segment
		(start 388.064248 -249.22988)
		(end 389.287004 -248.007124)
		(width 0.088646)
		(layer "F.Cu")
		(net "M_E_CPU0_SB_CA<4>")
	)
	(segment
		(start 407.704798 -249.166634)
		(end 406.753314 -249.166634)
		(width 0.20066)
		(layer "F.Cu")
		(net "M_E_CPU0_SB_CA<4>")
	)
	(segment
		(start 409.857956 -249.591576)
		(end 409.83662 -249.612912)
		(width 0.1016)
		(layer "F.Cu")
		(net "M_E_CPU0_SB_CA<4>")
	)
	(segment
		(start 411.863794 -249.61088)
		(end 411.84449 -249.591576)
		(width 0.1016)
		(layer "F.Cu")
		(net "M_E_CPU0_SB_CA<4>")
	)
	(segment
		(start 396.901924 -247.461786)
		(end 399.015712 -249.575574)
		(width 0.20066)
		(layer "F.Cu")
		(net "M_E_CPU0_SB_CA<4>")
	)
	(segment
		(start 386.54228 -248.949464)
		(end 386.817616 -249.22988)
		(width 0.088646)
		(layer "F.Cu")
		(net "M_E_CPU0_SB_CA<4>")
	)
	(segment
		(start 394.97254 -247.799352)
		(end 395.054074 -247.717818)
		(width 0.1016)
		(layer "F.Cu")
		(net "M_E_CPU0_SB_CA<4>")
	)
	(segment
		(start 409.83662 -249.612912)
		(end 409.831794 -249.612912)
		(width 0.101854)
		(layer "F.Cu")
		(net "M_E_CPU0_SB_CA<4>")
	)
	(segment
		(start 386.817616 -249.22988)
		(end 388.064248 -249.22988)
		(width 0.088646)
		(layer "F.Cu")
		(net "M_E_CPU0_SB_CA<4>")
	)
	(segment
		(start 409.831794 -249.612912)
		(end 409.532328 -249.612912)
		(width 0.20066)
		(layer "F.Cu")
		(net "M_E_CPU0_SB_CA<4>")
	)
	(segment
		(start 385.612132 -248.20372)
		(end 385.612386 -248.203974)
		(width 0.088646)
		(layer "F.Cu")
		(net "M_E_CPU0_SB_CA<4>")
	)
	(segment
		(start 389.494776 -247.799352)
		(end 394.97254 -247.799352)
		(width 0.1016)
		(layer "F.Cu")
		(net "M_E_CPU0_SB_CA<4>")
	)
	(segment
		(start 408.579828 -249.699272)
		(end 408.237436 -249.699272)
		(width 0.20066)
		(layer "F.Cu")
		(net "M_E_CPU0_SB_CA<4>")
	)
	(segment
		(start 386.21208 -248.94667)
		(end 386.54228 -248.949464)
		(width 0.088646)
		(layer "F.Cu")
		(net "M_E_CPU0_SB_CA<4>")
	)
	(segment
		(start 395.054074 -247.717818)
		(end 395.310106 -247.461786)
		(width 0.20066)
		(layer "F.Cu")
		(net "M_E_CPU0_SB_CA<4>")
	)
	(segment
		(start 408.729688 -249.430794)
		(end 408.729688 -249.549412)
		(width 0.20066)
		(layer "F.Cu")
		(net "M_E_CPU0_SB_CA<4>")
	)
	(segment
		(start 389.287004 -248.007124)
		(end 389.494776 -247.799352)
		(width 0.1016)
		(layer "F.Cu")
		(net "M_E_CPU0_SB_CA<4>")
	)
	(segment
		(start 385.209034 -248.220484)
		(end 385.237736 -248.20372)
		(width 0.088646)
		(layer "F.Cu")
		(net "M_E_CPU0_SB_CA<4>")
	)
	(segment
		(start 409.532328 -249.612912)
		(end 409.25623 -249.336814)
		(width 0.20066)
		(layer "F.Cu")
		(net "M_E_CPU0_SB_CA<4>")
	)
	(segment
		(start 413.422338 -249.166634)
		(end 412.978092 -249.61088)
		(width 0.20066)
		(layer "F.Cu")
		(net "M_E_CPU0_SB_CA<4>")
	)
	(segment
		(start 412.978092 -249.61088)
		(end 411.863794 -249.61088)
		(width 0.20066)
		(layer "F.Cu")
		(net "M_E_CPU0_SB_CA<4>")
	)
	(segment
		(start 408.729688 -249.549412)
		(end 408.579828 -249.699272)
		(width 0.20066)
		(layer "F.Cu")
		(net "M_E_CPU0_SB_CA<4>")
	)
	(segment
		(start 411.84449 -249.591576)
		(end 409.857956 -249.591576)
		(width 0.1016)
		(layer "F.Cu")
		(net "M_E_CPU0_SB_CA<4>")
	)
	(segment
		(start 405.552402 -249.575574)
		(end 405.961342 -249.166634)
		(width 0.20066)
		(layer "F.Cu")
		(net "M_E_CPU0_SB_CA<4>")
	)
	(segment
		(start 414.297114 -249.166634)
		(end 413.422338 -249.166634)
		(width 0.20066)
		(layer "F.Cu")
		(net "M_E_CPU0_SB_CA<4>")
	)
	(segment
		(start 408.237436 -249.699272)
		(end 407.704798 -249.166634)
		(width 0.20066)
		(layer "F.Cu")
		(net "M_E_CPU0_SB_CA<4>")
	)
	(segment
		(start 384.485134 -248.528078)
		(end 385.209034 -248.220484)
		(width 0.088646)
		(layer "F.Cu")
		(net "M_E_CPU0_SB_CA<4>")
	)
	(segment
		(start 395.310106 -247.461786)
		(end 396.901924 -247.461786)
		(width 0.20066)
		(layer "F.Cu")
		(net "M_E_CPU0_SB_CA<4>")
	)
	(segment
		(start 405.961342 -249.166634)
		(end 406.753314 -249.166634)
		(width 0.20066)
		(layer "F.Cu")
		(net "M_E_CPU0_SB_CA<4>")
	)
	(segment
		(start 408.823668 -249.336814)
		(end 408.729688 -249.430794)
		(width 0.20066)
		(layer "F.Cu")
		(net "M_E_CPU0_SB_CA<4>")
	)
	(segment
		(start 385.799584 -248.528078)
		(end 386.21208 -248.94667)
		(width 0.088646)
		(layer "F.Cu")
		(net "M_E_CPU0_SB_CA<4>")
	)
	(arc
		(start 385.237736 -248.20372)
		(mid 385.424824 -248.153509)
		(end 385.611878 -248.20372)
		(width 0.088646)
		(layer "F.Cu")
		(net "M_E_CPU0_SB_CA<4>")
	)
	(arc
		(start 385.612386 -248.203974)
		(mid 385.749431 -248.340934)
		(end 385.799584 -248.528078)
		(width 0.088646)
		(layer "F.Cu")
		(net "M_E_CPU0_SB_CA<4>")
	)
	(segment
		(start 416.207448 -250.454414)
		(end 415.307526 -250.454414)
		(width 0.20066)
		(layer "F.Cu")
		(net "M_E_CPU0_SB_CA<3>")
	)
	(segment
		(start 412.411418 -250.232672)
		(end 411.633162 -250.232672)
		(width 0.20066)
		(layer "F.Cu")
		(net "M_E_CPU0_SB_CA<3>")
	)
	(segment
		(start 389.621776 -248.104152)
		(end 396.548864 -248.104152)
		(width 0.1016)
		(layer "F.Cu")
		(net "M_E_CPU0_SB_CA<3>")
	)
	(segment
		(start 386.718302 -249.68708)
		(end 388.038848 -249.68708)
		(width 0.088646)
		(layer "F.Cu")
		(net "M_E_CPU0_SB_CA<3>")
	)
	(segment
		(start 405.755602 -250.441714)
		(end 407.71318 -250.441714)
		(width 0.1016)
		(layer "F.Cu")
		(net "M_E_CPU0_SB_CA<3>")
	)
	(segment
		(start 413.275526 -250.451112)
		(end 412.629858 -250.451112)
		(width 0.20066)
		(layer "F.Cu")
		(net "M_E_CPU0_SB_CA<3>")
	)
	(segment
		(start 416.334448 -249.978672)
		(end 416.334448 -250.327414)
		(width 0.20066)
		(layer "F.Cu")
		(net "M_E_CPU0_SB_CA<3>")
	)
	(segment
		(start 398.999456 -250.463812)
		(end 405.731726 -250.463812)
		(width 0.20066)
		(layer "F.Cu")
		(net "M_E_CPU0_SB_CA<3>")
	)
	(segment
		(start 388.038848 -249.68708)
		(end 389.500618 -248.22531)
		(width 0.088646)
		(layer "F.Cu")
		(net "M_E_CPU0_SB_CA<3>")
	)
	(segment
		(start 396.561564 -248.116852)
		(end 396.652496 -248.116852)
		(width 0.20066)
		(layer "F.Cu")
		(net "M_E_CPU0_SB_CA<3>")
	)
	(segment
		(start 416.588448 -249.724672)
		(end 416.334448 -249.978672)
		(width 0.20066)
		(layer "F.Cu")
		(net "M_E_CPU0_SB_CA<3>")
	)
	(segment
		(start 413.30245 -250.441714)
		(end 413.293052 -250.451112)
		(width 0.1016)
		(layer "F.Cu")
		(net "M_E_CPU0_SB_CA<3>")
	)
	(segment
		(start 413.293052 -250.451112)
		(end 413.275526 -250.451112)
		(width 0.101854)
		(layer "F.Cu")
		(net "M_E_CPU0_SB_CA<3>")
	)
	(segment
		(start 411.633162 -250.232672)
		(end 411.417262 -250.016772)
		(width 0.20066)
		(layer "F.Cu")
		(net "M_E_CPU0_SB_CA<3>")
	)
	(segment
		(start 385.894834 -249.342148)
		(end 386.37337 -249.342148)
		(width 0.088646)
		(layer "F.Cu")
		(net "M_E_CPU0_SB_CA<3>")
	)
	(segment
		(start 416.334448 -250.327414)
		(end 416.207448 -250.454414)
		(width 0.20066)
		(layer "F.Cu")
		(net "M_E_CPU0_SB_CA<3>")
	)
	(segment
		(start 412.629858 -250.451112)
		(end 412.411418 -250.232672)
		(width 0.20066)
		(layer "F.Cu")
		(net "M_E_CPU0_SB_CA<3>")
	)
	(segment
		(start 415.294826 -250.441714)
		(end 413.30245 -250.441714)
		(width 0.1016)
		(layer "F.Cu")
		(net "M_E_CPU0_SB_CA<3>")
	)
	(segment
		(start 389.500618 -248.22531)
		(end 389.621776 -248.104152)
		(width 0.1016)
		(layer "F.Cu")
		(net "M_E_CPU0_SB_CA<3>")
	)
	(segment
		(start 407.763726 -250.452382)
		(end 409.256738 -250.452382)
		(width 0.20066)
		(layer "F.Cu")
		(net "M_E_CPU0_SB_CA<3>")
	)
	(segment
		(start 418.397182 -250.016772)
		(end 417.223448 -250.016772)
		(width 0.20066)
		(layer "F.Cu")
		(net "M_E_CPU0_SB_CA<3>")
	)
	(segment
		(start 411.417262 -250.016772)
		(end 410.853382 -250.016772)
		(width 0.20066)
		(layer "F.Cu")
		(net "M_E_CPU0_SB_CA<3>")
	)
	(segment
		(start 407.71318 -250.441714)
		(end 407.723848 -250.452382)
		(width 0.1016)
		(layer "F.Cu")
		(net "M_E_CPU0_SB_CA<3>")
	)
	(segment
		(start 405.731726 -250.463812)
		(end 405.733504 -250.463812)
		(width 0.101854)
		(layer "F.Cu")
		(net "M_E_CPU0_SB_CA<3>")
	)
	(segment
		(start 415.307526 -250.454414)
		(end 415.294826 -250.441714)
		(width 0.1016)
		(layer "F.Cu")
		(net "M_E_CPU0_SB_CA<3>")
	)
	(segment
		(start 396.560802 -248.11609)
		(end 396.561564 -248.116852)
		(width 0.20066)
		(layer "F.Cu")
		(net "M_E_CPU0_SB_CA<3>")
	)
	(segment
		(start 409.256738 -250.452382)
		(end 409.692348 -250.016772)
		(width 0.20066)
		(layer "F.Cu")
		(net "M_E_CPU0_SB_CA<3>")
	)
	(segment
		(start 416.931348 -249.724672)
		(end 416.588448 -249.724672)
		(width 0.20066)
		(layer "F.Cu")
		(net "M_E_CPU0_SB_CA<3>")
	)
	(segment
		(start 396.548864 -248.104152)
		(end 396.560802 -248.11609)
		(width 0.101854)
		(layer "F.Cu")
		(net "M_E_CPU0_SB_CA<3>")
	)
	(segment
		(start 396.652496 -248.116852)
		(end 398.999456 -250.463812)
		(width 0.20066)
		(layer "F.Cu")
		(net "M_E_CPU0_SB_CA<3>")
	)
	(segment
		(start 409.692348 -250.016772)
		(end 410.853382 -250.016772)
		(width 0.20066)
		(layer "F.Cu")
		(net "M_E_CPU0_SB_CA<3>")
	)
	(segment
		(start 407.723848 -250.452382)
		(end 407.763726 -250.452382)
		(width 0.101854)
		(layer "F.Cu")
		(net "M_E_CPU0_SB_CA<3>")
	)
	(segment
		(start 405.733504 -250.463812)
		(end 405.755602 -250.441714)
		(width 0.101854)
		(layer "F.Cu")
		(net "M_E_CPU0_SB_CA<3>")
	)
	(segment
		(start 417.223448 -250.016772)
		(end 416.931348 -249.724672)
		(width 0.20066)
		(layer "F.Cu")
		(net "M_E_CPU0_SB_CA<3>")
	)
	(segment
		(start 386.37337 -249.342148)
		(end 386.718302 -249.68708)
		(width 0.088646)
		(layer "F.Cu")
		(net "M_E_CPU0_SB_CA<3>")
	)
	(segment
		(start 411.850078 -251.291598)
		(end 409.849828 -251.291598)
		(width 0.1016)
		(layer "F.Cu")
		(net "M_E_CPU0_SB_CA<2>")
	)
	(segment
		(start 406.218898 -250.866656)
		(end 406.753314 -250.866656)
		(width 0.20066)
		(layer "F.Cu")
		(net "M_E_CPU0_SB_CA<2>")
	)
	(segment
		(start 402.670518 -251.361702)
		(end 405.14016 -251.361702)
		(width 0.20066)
		(layer "F.Cu")
		(net "M_E_CPU0_SB_CA<2>")
	)
	(segment
		(start 399.368264 -251.361702)
		(end 399.791682 -251.78512)
		(width 0.20066)
		(layer "F.Cu")
		(net "M_E_CPU0_SB_CA<2>")
	)
	(segment
		(start 400.5199 -251.361702)
		(end 401.4216 -251.361702)
		(width 0.20066)
		(layer "F.Cu")
		(net "M_E_CPU0_SB_CA<2>")
	)
	(segment
		(start 401.80895 -251.749052)
		(end 402.283168 -251.749052)
		(width 0.20066)
		(layer "F.Cu")
		(net "M_E_CPU0_SB_CA<2>")
	)
	(segment
		(start 412.497016 -251.305314)
		(end 411.863794 -251.305314)
		(width 0.20066)
		(layer "F.Cu")
		(net "M_E_CPU0_SB_CA<2>")
	)
	(segment
		(start 401.4216 -251.361702)
		(end 401.80895 -251.749052)
		(width 0.20066)
		(layer "F.Cu")
		(net "M_E_CPU0_SB_CA<2>")
	)
	(segment
		(start 396.560802 -248.929652)
		(end 398.992852 -251.361702)
		(width 0.20066)
		(layer "F.Cu")
		(net "M_E_CPU0_SB_CA<2>")
	)
	(segment
		(start 405.888698 -251.196856)
		(end 406.218898 -250.866656)
		(width 0.20066)
		(layer "F.Cu")
		(net "M_E_CPU0_SB_CA<2>")
	)
	(segment
		(start 412.935674 -250.866656)
		(end 412.497016 -251.305314)
		(width 0.20066)
		(layer "F.Cu")
		(net "M_E_CPU0_SB_CA<2>")
	)
	(segment
		(start 409.831794 -251.304806)
		(end 409.30449 -251.304806)
		(width 0.20066)
		(layer "F.Cu")
		(net "M_E_CPU0_SB_CA<2>")
	)
	(segment
		(start 399.791682 -251.78512)
		(end 400.096482 -251.78512)
		(width 0.20066)
		(layer "F.Cu")
		(net "M_E_CPU0_SB_CA<2>")
	)
	(segment
		(start 398.992852 -251.361702)
		(end 399.368264 -251.361702)
		(width 0.20066)
		(layer "F.Cu")
		(net "M_E_CPU0_SB_CA<2>")
	)
	(segment
		(start 411.863794 -251.305314)
		(end 411.850078 -251.291598)
		(width 0.1016)
		(layer "F.Cu")
		(net "M_E_CPU0_SB_CA<2>")
	)
	(segment
		(start 388.115048 -250.04268)
		(end 389.60425 -248.553478)
		(width 0.088646)
		(layer "F.Cu")
		(net "M_E_CPU0_SB_CA<2>")
	)
	(segment
		(start 400.096482 -251.78512)
		(end 400.5199 -251.361702)
		(width 0.20066)
		(layer "F.Cu")
		(net "M_E_CPU0_SB_CA<2>")
	)
	(segment
		(start 385.304792 -249.69216)
		(end 386.265928 -249.69216)
		(width 0.088646)
		(layer "F.Cu")
		(net "M_E_CPU0_SB_CA<2>")
	)
	(segment
		(start 409.005024 -251.604272)
		(end 408.585162 -251.604272)
		(width 0.20066)
		(layer "F.Cu")
		(net "M_E_CPU0_SB_CA<2>")
	)
	(segment
		(start 402.283168 -251.749052)
		(end 402.670518 -251.361702)
		(width 0.20066)
		(layer "F.Cu")
		(net "M_E_CPU0_SB_CA<2>")
	)
	(segment
		(start 389.748776 -248.408952)
		(end 396.040102 -248.408952)
		(width 0.1016)
		(layer "F.Cu")
		(net "M_E_CPU0_SB_CA<2>")
	)
	(segment
		(start 405.305006 -251.196856)
		(end 405.888698 -251.196856)
		(width 0.20066)
		(layer "F.Cu")
		(net "M_E_CPU0_SB_CA<2>")
	)
	(segment
		(start 409.849828 -251.291598)
		(end 409.83662 -251.304806)
		(width 0.1016)
		(layer "F.Cu")
		(net "M_E_CPU0_SB_CA<2>")
	)
	(segment
		(start 384.95478 -249.342148)
		(end 385.304792 -249.69216)
		(width 0.088646)
		(layer "F.Cu")
		(net "M_E_CPU0_SB_CA<2>")
	)
	(segment
		(start 389.60425 -248.553478)
		(end 389.748776 -248.408952)
		(width 0.1016)
		(layer "F.Cu")
		(net "M_E_CPU0_SB_CA<2>")
	)
	(segment
		(start 408.422348 -251.223272)
		(end 408.065732 -250.866656)
		(width 0.20066)
		(layer "F.Cu")
		(net "M_E_CPU0_SB_CA<2>")
	)
	(segment
		(start 386.265928 -249.69216)
		(end 386.616448 -250.04268)
		(width 0.088646)
		(layer "F.Cu")
		(net "M_E_CPU0_SB_CA<2>")
	)
	(segment
		(start 405.14016 -251.361702)
		(end 405.305006 -251.196856)
		(width 0.20066)
		(layer "F.Cu")
		(net "M_E_CPU0_SB_CA<2>")
	)
	(segment
		(start 414.297114 -250.866656)
		(end 412.935674 -250.866656)
		(width 0.20066)
		(layer "F.Cu")
		(net "M_E_CPU0_SB_CA<2>")
	)
	(segment
		(start 408.585162 -251.604272)
		(end 408.422348 -251.441458)
		(width 0.20066)
		(layer "F.Cu")
		(net "M_E_CPU0_SB_CA<2>")
	)
	(segment
		(start 409.30449 -251.304806)
		(end 409.005024 -251.604272)
		(width 0.20066)
		(layer "F.Cu")
		(net "M_E_CPU0_SB_CA<2>")
	)
	(segment
		(start 409.83662 -251.304806)
		(end 409.831794 -251.304806)
		(width 0.101854)
		(layer "F.Cu")
		(net "M_E_CPU0_SB_CA<2>")
	)
	(segment
		(start 408.422348 -251.441458)
		(end 408.422348 -251.223272)
		(width 0.20066)
		(layer "F.Cu")
		(net "M_E_CPU0_SB_CA<2>")
	)
	(segment
		(start 386.616448 -250.04268)
		(end 388.115048 -250.04268)
		(width 0.088646)
		(layer "F.Cu")
		(net "M_E_CPU0_SB_CA<2>")
	)
	(segment
		(start 408.065732 -250.866656)
		(end 406.753314 -250.866656)
		(width 0.20066)
		(layer "F.Cu")
		(net "M_E_CPU0_SB_CA<2>")
	)
	(segment
		(start 396.040102 -248.408952)
		(end 396.560802 -248.929652)
		(width 0.1016)
		(layer "F.Cu")
		(net "M_E_CPU0_SB_CA<2>")
	)
	(segment
		(start 409.135326 -252.15977)
		(end 409.578302 -251.716794)
		(width 0.20066)
		(layer "F.Cu")
		(net "M_E_CPU0_SB_CA<1>")
	)
	(segment
		(start 405.533098 -252.432312)
		(end 405.731726 -252.233684)
		(width 0.20066)
		(layer "F.Cu")
		(net "M_E_CPU0_SB_CA<1>")
	)
	(segment
		(start 407.443686 -252.141736)
		(end 407.745692 -252.141736)
		(width 0.101854)
		(layer "F.Cu")
		(net "M_E_CPU0_SB_CA<1>")
	)
	(segment
		(start 407.745692 -252.141736)
		(end 407.763726 -252.15977)
		(width 0.101854)
		(layer "F.Cu")
		(net "M_E_CPU0_SB_CA<1>")
	)
	(segment
		(start 399.158968 -252.432312)
		(end 405.533098 -252.432312)
		(width 0.20066)
		(layer "F.Cu")
		(net "M_E_CPU0_SB_CA<1>")
	)
	(segment
		(start 413.275526 -252.161294)
		(end 412.87827 -252.161294)
		(width 0.20066)
		(layer "F.Cu")
		(net "M_E_CPU0_SB_CA<1>")
	)
	(segment
		(start 386.529072 -250.34748)
		(end 386.706618 -250.34748)
		(width 0.088646)
		(layer "F.Cu")
		(net "M_E_CPU0_SB_CA<1>")
	)
	(segment
		(start 412.87827 -252.161294)
		(end 412.43377 -251.716794)
		(width 0.20066)
		(layer "F.Cu")
		(net "M_E_CPU0_SB_CA<1>")
	)
	(segment
		(start 386.346192 -250.53036)
		(end 386.529072 -250.34748)
		(width 0.088646)
		(layer "F.Cu")
		(net "M_E_CPU0_SB_CA<1>")
	)
	(segment
		(start 383.846832 -249.677936)
		(end 383.848356 -249.678698)
		(width 0.088646)
		(layer "F.Cu")
		(net "M_E_CPU0_SB_CA<1>")
	)
	(segment
		(start 415.294318 -252.141736)
		(end 413.308292 -252.141736)
		(width 0.1016)
		(layer "F.Cu")
		(net "M_E_CPU0_SB_CA<1>")
	)
	(segment
		(start 416.123628 -252.650752)
		(end 415.62782 -252.154944)
		(width 0.20066)
		(layer "F.Cu")
		(net "M_E_CPU0_SB_CA<1>")
	)
	(segment
		(start 383.819146 -249.66168)
		(end 383.845562 -249.677174)
		(width 0.088646)
		(layer "F.Cu")
		(net "M_E_CPU0_SB_CA<1>")
	)
	(segment
		(start 405.731726 -252.233684)
		(end 405.772366 -252.193044)
		(width 0.101854)
		(layer "F.Cu")
		(net "M_E_CPU0_SB_CA<1>")
	)
	(segment
		(start 416.575748 -252.650752)
		(end 416.123628 -252.650752)
		(width 0.20066)
		(layer "F.Cu")
		(net "M_E_CPU0_SB_CA<1>")
	)
	(segment
		(start 383.800858 -249.643138)
		(end 383.819146 -249.661426)
		(width 0.088646)
		(layer "F.Cu")
		(net "M_E_CPU0_SB_CA<1>")
	)
	(segment
		(start 405.772366 -252.193044)
		(end 405.823674 -252.141736)
		(width 0.1016)
		(layer "F.Cu")
		(net "M_E_CPU0_SB_CA<1>")
	)
	(segment
		(start 415.62782 -252.154944)
		(end 415.307526 -252.154944)
		(width 0.20066)
		(layer "F.Cu")
		(net "M_E_CPU0_SB_CA<1>")
	)
	(segment
		(start 409.578302 -251.716794)
		(end 410.853382 -251.716794)
		(width 0.20066)
		(layer "F.Cu")
		(net "M_E_CPU0_SB_CA<1>")
	)
	(segment
		(start 395.646402 -248.919746)
		(end 399.158968 -252.432312)
		(width 0.20066)
		(layer "F.Cu")
		(net "M_E_CPU0_SB_CA<1>")
	)
	(segment
		(start 383.845562 -249.677174)
		(end 383.846832 -249.677936)
		(width 0.088646)
		(layer "F.Cu")
		(net "M_E_CPU0_SB_CA<1>")
	)
	(segment
		(start 412.43377 -251.716794)
		(end 410.853382 -251.716794)
		(width 0.20066)
		(layer "F.Cu")
		(net "M_E_CPU0_SB_CA<1>")
	)
	(segment
		(start 384.110484 -249.998992)
		(end 384.110484 -250.146058)
		(width 0.088646)
		(layer "F.Cu")
		(net "M_E_CPU0_SB_CA<1>")
	)
	(segment
		(start 407.763726 -252.15977)
		(end 409.135326 -252.15977)
		(width 0.20066)
		(layer "F.Cu")
		(net "M_E_CPU0_SB_CA<1>")
	)
	(segment
		(start 386.706618 -250.34748)
		(end 388.242048 -250.34748)
		(width 0.1016)
		(layer "F.Cu")
		(net "M_E_CPU0_SB_CA<1>")
	)
	(segment
		(start 418.397182 -251.716794)
		(end 417.509706 -251.716794)
		(width 0.20066)
		(layer "F.Cu")
		(net "M_E_CPU0_SB_CA<1>")
	)
	(segment
		(start 413.308292 -252.141736)
		(end 413.288734 -252.161294)
		(width 0.1016)
		(layer "F.Cu")
		(net "M_E_CPU0_SB_CA<1>")
	)
	(segment
		(start 388.242048 -250.34748)
		(end 389.875776 -248.713752)
		(width 0.1016)
		(layer "F.Cu")
		(net "M_E_CPU0_SB_CA<1>")
	)
	(segment
		(start 384.494786 -250.53036)
		(end 386.346192 -250.53036)
		(width 0.088646)
		(layer "F.Cu")
		(net "M_E_CPU0_SB_CA<1>")
	)
	(segment
		(start 417.509706 -251.716794)
		(end 416.575748 -252.650752)
		(width 0.20066)
		(layer "F.Cu")
		(net "M_E_CPU0_SB_CA<1>")
	)
	(segment
		(start 395.440408 -248.713752)
		(end 395.646402 -248.919746)
		(width 0.1016)
		(layer "F.Cu")
		(net "M_E_CPU0_SB_CA<1>")
	)
	(segment
		(start 413.288734 -252.161294)
		(end 413.275526 -252.161294)
		(width 0.101854)
		(layer "F.Cu")
		(net "M_E_CPU0_SB_CA<1>")
	)
	(segment
		(start 405.823674 -252.141736)
		(end 407.443686 -252.141736)
		(width 0.1016)
		(layer "F.Cu")
		(net "M_E_CPU0_SB_CA<1>")
	)
	(segment
		(start 415.307526 -252.154944)
		(end 415.294318 -252.141736)
		(width 0.1016)
		(layer "F.Cu")
		(net "M_E_CPU0_SB_CA<1>")
	)
	(segment
		(start 389.875776 -248.713752)
		(end 395.440408 -248.713752)
		(width 0.1016)
		(layer "F.Cu")
		(net "M_E_CPU0_SB_CA<1>")
	)
	(segment
		(start 383.819146 -249.661426)
		(end 383.819146 -249.66168)
		(width 0.088646)
		(layer "F.Cu")
		(net "M_E_CPU0_SB_CA<1>")
	)
	(arc
		(start 384.110484 -250.146058)
		(mid 384.228831 -250.412013)
		(end 384.494786 -250.53036)
		(width 0.088646)
		(layer "F.Cu")
		(net "M_E_CPU0_SB_CA<1>")
	)
	(arc
		(start 384.073908 -249.877326)
		(mid 384.101246 -249.935442)
		(end 384.110484 -249.998992)
		(width 0.088646)
		(layer "F.Cu")
		(net "M_E_CPU0_SB_CA<1>")
	)
	(arc
		(start 383.848356 -249.678698)
		(mid 383.974148 -249.763239)
		(end 384.073908 -249.877326)
		(width 0.088646)
		(layer "F.Cu")
		(net "M_E_CPU0_SB_CA<1>")
	)
	(arc
		(start 383.07518 -249.342148)
		(mid 383.446334 -249.472594)
		(end 383.800858 -249.643138)
		(width 0.088646)
		(layer "F.Cu")
		(net "M_E_CPU0_SB_CA<1>")
	)
	(segment
		(start 383.91973 -250.143772)
		(end 383.920238 -250.152154)
		(width 0.088646)
		(layer "F.Cu")
		(net "M_E_CPU0_SB_CA<0>")
	)
	(segment
		(start 398.94002 -253.12243)
		(end 405.702262 -253.12243)
		(width 0.20066)
		(layer "F.Cu")
		(net "M_E_CPU0_SB_CA<0>")
	)
	(segment
		(start 409.704794 -252.684026)
		(end 409.298394 -253.090426)
		(width 0.20066)
		(layer "F.Cu")
		(net "M_E_CPU0_SB_CA<0>")
	)
	(segment
		(start 386.517134 -250.841764)
		(end 386.638292 -250.720606)
		(width 0.1016)
		(layer "F.Cu")
		(net "M_E_CPU0_SB_CA<0>")
	)
	(segment
		(start 382.676654 -249.600466)
		(end 382.729486 -249.653044)
		(width 0.088646)
		(layer "F.Cu")
		(net "M_E_CPU0_SB_CA<0>")
	)
	(segment
		(start 383.624074 -249.768106)
		(end 383.74828 -249.841004)
		(width 0.088646)
		(layer "F.Cu")
		(net "M_E_CPU0_SB_CA<0>")
	)
	(segment
		(start 385.030218 -250.841764)
		(end 386.517134 -250.841764)
		(width 0.1016)
		(layer "F.Cu")
		(net "M_E_CPU0_SB_CA<0>")
	)
	(segment
		(start 386.638292 -250.720606)
		(end 388.326122 -250.720606)
		(width 0.1016)
		(layer "F.Cu")
		(net "M_E_CPU0_SB_CA<0>")
	)
	(segment
		(start 383.755138 -249.844814)
		(end 383.763266 -249.849132)
		(width 0.088646)
		(layer "F.Cu")
		(net "M_E_CPU0_SB_CA<0>")
	)
	(segment
		(start 388.326122 -250.720606)
		(end 390.028176 -249.018552)
		(width 0.1016)
		(layer "F.Cu")
		(net "M_E_CPU0_SB_CA<0>")
	)
	(segment
		(start 384.490214 -250.720606)
		(end 384.56997 -250.720606)
		(width 0.088646)
		(layer "F.Cu")
		(net "M_E_CPU0_SB_CA<0>")
	)
	(segment
		(start 383.763266 -249.849132)
		(end 383.800858 -249.882152)
		(width 0.088646)
		(layer "F.Cu")
		(net "M_E_CPU0_SB_CA<0>")
	)
	(segment
		(start 412.605728 -252.566678)
		(end 412.180786 -252.141736)
		(width 0.20066)
		(layer "F.Cu")
		(net "M_E_CPU0_SB_CA<0>")
	)
	(segment
		(start 414.297114 -252.566678)
		(end 412.605728 -252.566678)
		(width 0.20066)
		(layer "F.Cu")
		(net "M_E_CPU0_SB_CA<0>")
	)
	(segment
		(start 409.298394 -253.090426)
		(end 407.832306 -253.090426)
		(width 0.20066)
		(layer "F.Cu")
		(net "M_E_CPU0_SB_CA<0>")
	)
	(segment
		(start 411.863794 -252.141736)
		(end 411.758638 -252.141736)
		(width 0.101854)
		(layer "F.Cu")
		(net "M_E_CPU0_SB_CA<0>")
	)
	(segment
		(start 383.006854 -249.768106)
		(end 383.624074 -249.768106)
		(width 0.088646)
		(layer "F.Cu")
		(net "M_E_CPU0_SB_CA<0>")
	)
	(segment
		(start 409.831794 -252.334014)
		(end 409.704794 -252.461014)
		(width 0.20066)
		(layer "F.Cu")
		(net "M_E_CPU0_SB_CA<0>")
	)
	(segment
		(start 390.028176 -249.018552)
		(end 394.836142 -249.018552)
		(width 0.1016)
		(layer "F.Cu")
		(net "M_E_CPU0_SB_CA<0>")
	)
	(segment
		(start 394.836142 -249.018552)
		(end 395.052042 -249.234452)
		(width 0.1016)
		(layer "F.Cu")
		(net "M_E_CPU0_SB_CA<0>")
	)
	(segment
		(start 383.920492 -250.155964)
		(end 383.920238 -250.155964)
		(width 0.088646)
		(layer "F.Cu")
		(net "M_E_CPU0_SB_CA<0>")
	)
	(segment
		(start 405.702262 -253.12243)
		(end 406.258014 -252.566678)
		(width 0.20066)
		(layer "F.Cu")
		(net "M_E_CPU0_SB_CA<0>")
	)
	(segment
		(start 382.605534 -248.528078)
		(end 382.605534 -249.428762)
		(width 0.088646)
		(layer "F.Cu")
		(net "M_E_CPU0_SB_CA<0>")
	)
	(segment
		(start 395.052042 -249.234452)
		(end 398.94002 -253.12243)
		(width 0.20066)
		(layer "F.Cu")
		(net "M_E_CPU0_SB_CA<0>")
	)
	(segment
		(start 383.91973 -250.001024)
		(end 383.91973 -250.143772)
		(width 0.088646)
		(layer "F.Cu")
		(net "M_E_CPU0_SB_CA<0>")
	)
	(segment
		(start 409.704794 -252.461014)
		(end 409.704794 -252.684026)
		(width 0.20066)
		(layer "F.Cu")
		(net "M_E_CPU0_SB_CA<0>")
	)
	(segment
		(start 410.024072 -252.141736)
		(end 409.83662 -252.329188)
		(width 0.1016)
		(layer "F.Cu")
		(net "M_E_CPU0_SB_CA<0>")
	)
	(segment
		(start 407.308558 -252.566678)
		(end 406.753314 -252.566678)
		(width 0.20066)
		(layer "F.Cu")
		(net "M_E_CPU0_SB_CA<0>")
	)
	(segment
		(start 406.258014 -252.566678)
		(end 406.753314 -252.566678)
		(width 0.20066)
		(layer "F.Cu")
		(net "M_E_CPU0_SB_CA<0>")
	)
	(segment
		(start 383.800858 -249.882152)
		(end 383.91973 -250.001024)
		(width 0.088646)
		(layer "F.Cu")
		(net "M_E_CPU0_SB_CA<0>")
	)
	(segment
		(start 407.832306 -253.090426)
		(end 407.308558 -252.566678)
		(width 0.20066)
		(layer "F.Cu")
		(net "M_E_CPU0_SB_CA<0>")
	)
	(segment
		(start 412.180786 -252.141736)
		(end 411.863794 -252.141736)
		(width 0.20066)
		(layer "F.Cu")
		(net "M_E_CPU0_SB_CA<0>")
	)
	(segment
		(start 384.56997 -250.720606)
		(end 384.862578 -250.841764)
		(width 0.088646)
		(layer "F.Cu")
		(net "M_E_CPU0_SB_CA<0>")
	)
	(segment
		(start 411.758638 -252.141736)
		(end 410.024072 -252.141736)
		(width 0.1016)
		(layer "F.Cu")
		(net "M_E_CPU0_SB_CA<0>")
	)
	(segment
		(start 383.74828 -249.841004)
		(end 383.755138 -249.844814)
		(width 0.088646)
		(layer "F.Cu")
		(net "M_E_CPU0_SB_CA<0>")
	)
	(segment
		(start 409.83662 -252.329188)
		(end 409.831794 -252.334014)
		(width 0.101854)
		(layer "F.Cu")
		(net "M_E_CPU0_SB_CA<0>")
	)
	(segment
		(start 384.862578 -250.841764)
		(end 385.030218 -250.841764)
		(width 0.088646)
		(layer "F.Cu")
		(net "M_E_CPU0_SB_CA<0>")
	)
	(arc
		(start 383.920238 -250.152154)
		(mid 383.920362 -250.154059)
		(end 383.920492 -250.155964)
		(width 0.088646)
		(layer "F.Cu")
		(net "M_E_CPU0_SB_CA<0>")
	)
	(arc
		(start 382.605534 -249.428762)
		(mid 382.624018 -249.521687)
		(end 382.676654 -249.600466)
		(width 0.088646)
		(layer "F.Cu")
		(net "M_E_CPU0_SB_CA<0>")
	)
	(arc
		(start 383.920238 -250.155964)
		(mid 384.096097 -250.548448)
		(end 384.490214 -250.720606)
		(width 0.088646)
		(layer "F.Cu")
		(net "M_E_CPU0_SB_CA<0>")
	)
	(arc
		(start 382.729486 -249.653044)
		(mid 382.856728 -249.738158)
		(end 383.006854 -249.768106)
		(width 0.088646)
		(layer "F.Cu")
		(net "M_E_CPU0_SB_CA<0>")
	)
	(segment
		(start 371.32768 -248.527824)
		(end 371.32768 -247.992138)
		(width 0.20066)
		(layer "F.Cu")
		(net "M_E_CPU0_SA_RSP<1>")
	)
	(segment
		(start 406.753314 -244.066568)
		(end 405.623014 -244.066568)
		(width 0.20066)
		(layer "F.Cu")
		(net "M_E_CPU0_SA_RSP<1>")
	)
	(segment
		(start 371.327934 -248.528078)
		(end 371.32768 -248.527824)
		(width 0.20066)
		(layer "F.Cu")
		(net "M_E_CPU0_SA_RSP<1>")
	)
	(segment
		(start 379.518164 -248.490486)
		(end 379.503432 -248.48185)
		(width 0.088646)
		(layer "In6.Cu")
		(net "M_E_CPU0_SA_RSP<1>")
	)
	(segment
		(start 375.758964 -248.490486)
		(end 375.744232 -248.48185)
		(width 0.088646)
		(layer "In6.Cu")
		(net "M_E_CPU0_SA_RSP<1>")
	)
	(segment
		(start 405.623014 -244.066568)
		(end 404.504652 -244.066568)
		(width 0.18288)
		(layer "In6.Cu")
		(net "M_E_CPU0_SA_RSP<1>")
	)
	(segment
		(start 404.096474 -245.197122)
		(end 403.913594 -245.380002)
		(width 0.18288)
		(layer "In6.Cu")
		(net "M_E_CPU0_SA_RSP<1>")
	)
	(segment
		(start 403.913594 -245.380002)
		(end 399.840196 -245.380002)
		(width 0.18288)
		(layer "In6.Cu")
		(net "M_E_CPU0_SA_RSP<1>")
	)
	(segment
		(start 404.504652 -244.066568)
		(end 404.096474 -244.474746)
		(width 0.18288)
		(layer "In6.Cu")
		(net "M_E_CPU0_SA_RSP<1>")
	)
	(segment
		(start 371.985032 -248.48185)
		(end 371.956076 -248.46534)
		(width 0.088646)
		(layer "In6.Cu")
		(net "M_E_CPU0_SA_RSP<1>")
	)
	(segment
		(start 377.633992 -248.487946)
		(end 377.623578 -248.48185)
		(width 0.088646)
		(layer "In6.Cu")
		(net "M_E_CPU0_SA_RSP<1>")
	)
	(segment
		(start 384.470402 -247.744742)
		(end 384.287776 -247.744742)
		(width 0.088646)
		(layer "In6.Cu")
		(net "M_E_CPU0_SA_RSP<1>")
	)
	(segment
		(start 399.235422 -245.984776)
		(end 390.138412 -245.984776)
		(width 0.18288)
		(layer "In6.Cu")
		(net "M_E_CPU0_SA_RSP<1>")
	)
	(segment
		(start 376.694446 -248.487946)
		(end 376.684032 -248.48185)
		(width 0.088646)
		(layer "In6.Cu")
		(net "M_E_CPU0_SA_RSP<1>")
	)
	(segment
		(start 399.840196 -245.380002)
		(end 399.235422 -245.984776)
		(width 0.18288)
		(layer "In6.Cu")
		(net "M_E_CPU0_SA_RSP<1>")
	)
	(segment
		(start 371.999764 -248.490486)
		(end 371.985032 -248.48185)
		(width 0.088646)
		(layer "In6.Cu")
		(net "M_E_CPU0_SA_RSP<1>")
	)
	(segment
		(start 371.956076 -248.46534)
		(end 371.32768 -247.992138)
		(width 0.088646)
		(layer "In6.Cu")
		(net "M_E_CPU0_SA_RSP<1>")
	)
	(segment
		(start 386.881624 -247.744742)
		(end 384.470402 -247.744742)
		(width 0.18288)
		(layer "In6.Cu")
		(net "M_E_CPU0_SA_RSP<1>")
	)
	(segment
		(start 387.03631 -247.590056)
		(end 386.881624 -247.744742)
		(width 0.18288)
		(layer "In6.Cu")
		(net "M_E_CPU0_SA_RSP<1>")
	)
	(segment
		(start 388.533132 -247.590056)
		(end 387.03631 -247.590056)
		(width 0.18288)
		(layer "In6.Cu")
		(net "M_E_CPU0_SA_RSP<1>")
	)
	(segment
		(start 384.287776 -247.744742)
		(end 384.110484 -247.922034)
		(width 0.088646)
		(layer "In6.Cu")
		(net "M_E_CPU0_SA_RSP<1>")
	)
	(segment
		(start 390.138412 -245.984776)
		(end 388.533132 -247.590056)
		(width 0.18288)
		(layer "In6.Cu")
		(net "M_E_CPU0_SA_RSP<1>")
	)
	(segment
		(start 404.096474 -244.474746)
		(end 404.096474 -245.197122)
		(width 0.18288)
		(layer "In6.Cu")
		(net "M_E_CPU0_SA_RSP<1>")
	)
	(segment
		(start 374.819164 -248.490486)
		(end 374.804432 -248.48185)
		(width 0.088646)
		(layer "In6.Cu")
		(net "M_E_CPU0_SA_RSP<1>")
	)
	(segment
		(start 372.939564 -248.490486)
		(end 372.924832 -248.48185)
		(width 0.088646)
		(layer "In6.Cu")
		(net "M_E_CPU0_SA_RSP<1>")
	)
	(segment
		(start 384.110484 -247.922034)
		(end 384.110484 -248.01068)
		(width 0.088646)
		(layer "In6.Cu")
		(net "M_E_CPU0_SA_RSP<1>")
	)
	(arc
		(start 381.948436 -248.48185)
		(mid 381.665734 -248.557592)
		(end 381.383032 -248.48185)
		(width 0.088646)
		(layer "In6.Cu")
		(net "M_E_CPU0_SA_RSP<1>")
	)
	(arc
		(start 373.490236 -248.48185)
		(mid 373.216007 -248.557775)
		(end 372.939564 -248.490486)
		(width 0.088646)
		(layer "In6.Cu")
		(net "M_E_CPU0_SA_RSP<1>")
	)
	(arc
		(start 373.864632 -248.48185)
		(mid 373.677434 -248.431707)
		(end 373.490236 -248.48185)
		(width 0.088646)
		(layer "In6.Cu")
		(net "M_E_CPU0_SA_RSP<1>")
	)
	(arc
		(start 378.563632 -248.48185)
		(mid 378.376434 -248.431707)
		(end 378.189236 -248.48185)
		(width 0.088646)
		(layer "In6.Cu")
		(net "M_E_CPU0_SA_RSP<1>")
	)
	(arc
		(start 380.443232 -248.48185)
		(mid 380.256034 -248.431707)
		(end 380.068836 -248.48185)
		(width 0.088646)
		(layer "In6.Cu")
		(net "M_E_CPU0_SA_RSP<1>")
	)
	(arc
		(start 372.924832 -248.48185)
		(mid 372.737634 -248.431707)
		(end 372.550436 -248.48185)
		(width 0.088646)
		(layer "In6.Cu")
		(net "M_E_CPU0_SA_RSP<1>")
	)
	(arc
		(start 382.322832 -248.48185)
		(mid 382.135634 -248.431707)
		(end 381.948436 -248.48185)
		(width 0.088646)
		(layer "In6.Cu")
		(net "M_E_CPU0_SA_RSP<1>")
	)
	(arc
		(start 376.684032 -248.48185)
		(mid 376.496834 -248.431707)
		(end 376.309636 -248.48185)
		(width 0.088646)
		(layer "In6.Cu")
		(net "M_E_CPU0_SA_RSP<1>")
	)
	(arc
		(start 378.189236 -248.48185)
		(mid 377.912423 -248.557686)
		(end 377.633992 -248.487946)
		(width 0.088646)
		(layer "In6.Cu")
		(net "M_E_CPU0_SA_RSP<1>")
	)
	(arc
		(start 374.804432 -248.48185)
		(mid 374.617234 -248.431707)
		(end 374.430036 -248.48185)
		(width 0.088646)
		(layer "In6.Cu")
		(net "M_E_CPU0_SA_RSP<1>")
	)
	(arc
		(start 381.008636 -248.48185)
		(mid 380.725934 -248.557592)
		(end 380.443232 -248.48185)
		(width 0.088646)
		(layer "In6.Cu")
		(net "M_E_CPU0_SA_RSP<1>")
	)
	(arc
		(start 374.430036 -248.48185)
		(mid 374.147334 -248.557592)
		(end 373.864632 -248.48185)
		(width 0.088646)
		(layer "In6.Cu")
		(net "M_E_CPU0_SA_RSP<1>")
	)
	(arc
		(start 379.503432 -248.48185)
		(mid 379.316234 -248.431707)
		(end 379.129036 -248.48185)
		(width 0.088646)
		(layer "In6.Cu")
		(net "M_E_CPU0_SA_RSP<1>")
	)
	(arc
		(start 382.888236 -248.48185)
		(mid 382.605534 -248.557592)
		(end 382.322832 -248.48185)
		(width 0.088646)
		(layer "In6.Cu")
		(net "M_E_CPU0_SA_RSP<1>")
	)
	(arc
		(start 380.068836 -248.48185)
		(mid 379.794607 -248.557775)
		(end 379.518164 -248.490486)
		(width 0.088646)
		(layer "In6.Cu")
		(net "M_E_CPU0_SA_RSP<1>")
	)
	(arc
		(start 384.110484 -248.01068)
		(mid 383.820006 -248.486399)
		(end 383.262632 -248.48185)
		(width 0.088646)
		(layer "In6.Cu")
		(net "M_E_CPU0_SA_RSP<1>")
	)
	(arc
		(start 376.309636 -248.48185)
		(mid 376.035407 -248.557775)
		(end 375.758964 -248.490486)
		(width 0.088646)
		(layer "In6.Cu")
		(net "M_E_CPU0_SA_RSP<1>")
	)
	(arc
		(start 375.369836 -248.48185)
		(mid 375.095607 -248.557775)
		(end 374.819164 -248.490486)
		(width 0.088646)
		(layer "In6.Cu")
		(net "M_E_CPU0_SA_RSP<1>")
	)
	(arc
		(start 372.550436 -248.48185)
		(mid 372.276207 -248.557775)
		(end 371.999764 -248.490486)
		(width 0.088646)
		(layer "In6.Cu")
		(net "M_E_CPU0_SA_RSP<1>")
	)
	(arc
		(start 375.744232 -248.48185)
		(mid 375.557034 -248.431707)
		(end 375.369836 -248.48185)
		(width 0.088646)
		(layer "In6.Cu")
		(net "M_E_CPU0_SA_RSP<1>")
	)
	(arc
		(start 377.249182 -248.48185)
		(mid 376.972623 -248.557559)
		(end 376.694446 -248.487946)
		(width 0.088646)
		(layer "In6.Cu")
		(net "M_E_CPU0_SA_RSP<1>")
	)
	(arc
		(start 377.623578 -248.48185)
		(mid 377.43638 -248.431707)
		(end 377.249182 -248.48185)
		(width 0.088646)
		(layer "In6.Cu")
		(net "M_E_CPU0_SA_RSP<1>")
	)
	(arc
		(start 383.262632 -248.48185)
		(mid 383.075434 -248.431707)
		(end 382.888236 -248.48185)
		(width 0.088646)
		(layer "In6.Cu")
		(net "M_E_CPU0_SA_RSP<1>")
	)
	(arc
		(start 379.129036 -248.48185)
		(mid 378.846334 -248.557592)
		(end 378.563632 -248.48185)
		(width 0.088646)
		(layer "In6.Cu")
		(net "M_E_CPU0_SA_RSP<1>")
	)
	(arc
		(start 381.383032 -248.48185)
		(mid 381.195834 -248.431707)
		(end 381.008636 -248.48185)
		(width 0.088646)
		(layer "In6.Cu")
		(net "M_E_CPU0_SA_RSP<1>")
	)
	(segment
		(start 414.297114 -244.066568)
		(end 413.166814 -244.066568)
		(width 0.20066)
		(layer "F.Cu")
		(net "M_E_CPU0_SA_RSP<0>")
	)
	(segment
		(start 371.79758 -249.342148)
		(end 371.797834 -249.341894)
		(width 0.20066)
		(layer "F.Cu")
		(net "M_E_CPU0_SA_RSP<0>")
	)
	(segment
		(start 371.797834 -249.341894)
		(end 371.797834 -248.806208)
		(width 0.20066)
		(layer "F.Cu")
		(net "M_E_CPU0_SA_RSP<0>")
	)
	(segment
		(start 383.166112 -249.65025)
		(end 382.87071 -249.354848)
		(width 0.088646)
		(layer "In6.Cu")
		(net "M_E_CPU0_SA_RSP<0>")
	)
	(segment
		(start 374.899682 -249.295666)
		(end 374.88495 -249.304302)
		(width 0.088646)
		(layer "In6.Cu")
		(net "M_E_CPU0_SA_RSP<0>")
	)
	(segment
		(start 404.500334 -246.515636)
		(end 400.709638 -246.515636)
		(width 0.18288)
		(layer "In6.Cu")
		(net "M_E_CPU0_SA_RSP<0>")
	)
	(segment
		(start 406.80513 -245.964456)
		(end 405.842724 -245.964456)
		(width 0.18288)
		(layer "In6.Cu")
		(net "M_E_CPU0_SA_RSP<0>")
	)
	(segment
		(start 376.779282 -249.295666)
		(end 376.76455 -249.304302)
		(width 0.088646)
		(layer "In6.Cu")
		(net "M_E_CPU0_SA_RSP<0>")
	)
	(segment
		(start 385.617212 -248.83491)
		(end 385.46278 -248.83491)
		(width 0.088646)
		(layer "In6.Cu")
		(net "M_E_CPU0_SA_RSP<0>")
	)
	(segment
		(start 378.658882 -249.295666)
		(end 378.64415 -249.304302)
		(width 0.088646)
		(layer "In6.Cu")
		(net "M_E_CPU0_SA_RSP<0>")
	)
	(segment
		(start 387.061964 -248.83491)
		(end 385.617212 -248.83491)
		(width 0.18288)
		(layer "In6.Cu")
		(net "M_E_CPU0_SA_RSP<0>")
	)
	(segment
		(start 405.842724 -245.964456)
		(end 405.682704 -246.025924)
		(width 0.18288)
		(layer "In6.Cu")
		(net "M_E_CPU0_SA_RSP<0>")
	)
	(segment
		(start 373.959882 -249.295666)
		(end 373.949468 -249.301762)
		(width 0.088646)
		(layer "In6.Cu")
		(net "M_E_CPU0_SA_RSP<0>")
	)
	(segment
		(start 372.454678 -249.295666)
		(end 372.42623 -249.27941)
		(width 0.088646)
		(layer "In6.Cu")
		(net "M_E_CPU0_SA_RSP<0>")
	)
	(segment
		(start 373.020336 -249.295666)
		(end 373.009922 -249.301762)
		(width 0.088646)
		(layer "In6.Cu")
		(net "M_E_CPU0_SA_RSP<0>")
	)
	(segment
		(start 388.634732 -249.183652)
		(end 387.410706 -249.183652)
		(width 0.18288)
		(layer "In6.Cu")
		(net "M_E_CPU0_SA_RSP<0>")
	)
	(segment
		(start 375.839482 -249.295666)
		(end 375.82475 -249.304302)
		(width 0.088646)
		(layer "In6.Cu")
		(net "M_E_CPU0_SA_RSP<0>")
	)
	(segment
		(start 372.42623 -249.27941)
		(end 371.797834 -248.806208)
		(width 0.088646)
		(layer "In6.Cu")
		(net "M_E_CPU0_SA_RSP<0>")
	)
	(segment
		(start 383.912364 -249.65025)
		(end 383.166112 -249.65025)
		(width 0.088646)
		(layer "In6.Cu")
		(net "M_E_CPU0_SA_RSP<0>")
	)
	(segment
		(start 410.362908 -244.490748)
		(end 406.80513 -245.964456)
		(width 0.18288)
		(layer "In6.Cu")
		(net "M_E_CPU0_SA_RSP<0>")
	)
	(segment
		(start 390.837928 -246.980456)
		(end 388.634732 -249.183652)
		(width 0.18288)
		(layer "In6.Cu")
		(net "M_E_CPU0_SA_RSP<0>")
	)
	(segment
		(start 384.378962 -249.183652)
		(end 383.912364 -249.65025)
		(width 0.088646)
		(layer "In6.Cu")
		(net "M_E_CPU0_SA_RSP<0>")
	)
	(segment
		(start 405.682704 -246.025924)
		(end 404.500334 -246.515636)
		(width 0.18288)
		(layer "In6.Cu")
		(net "M_E_CPU0_SA_RSP<0>")
	)
	(segment
		(start 385.114038 -249.183652)
		(end 384.378962 -249.183652)
		(width 0.088646)
		(layer "In6.Cu")
		(net "M_E_CPU0_SA_RSP<0>")
	)
	(segment
		(start 399.587212 -246.980456)
		(end 390.837928 -246.980456)
		(width 0.18288)
		(layer "In6.Cu")
		(net "M_E_CPU0_SA_RSP<0>")
	)
	(segment
		(start 379.598936 -249.295666)
		(end 379.588522 -249.301762)
		(width 0.088646)
		(layer "In6.Cu")
		(net "M_E_CPU0_SA_RSP<0>")
	)
	(segment
		(start 412.742634 -244.490748)
		(end 410.362908 -244.490748)
		(width 0.18288)
		(layer "In6.Cu")
		(net "M_E_CPU0_SA_RSP<0>")
	)
	(segment
		(start 413.166814 -244.066568)
		(end 412.742634 -244.490748)
		(width 0.18288)
		(layer "In6.Cu")
		(net "M_E_CPU0_SA_RSP<0>")
	)
	(segment
		(start 400.709638 -246.515636)
		(end 399.587212 -246.980456)
		(width 0.18288)
		(layer "In6.Cu")
		(net "M_E_CPU0_SA_RSP<0>")
	)
	(segment
		(start 387.410706 -249.183652)
		(end 387.061964 -248.83491)
		(width 0.18288)
		(layer "In6.Cu")
		(net "M_E_CPU0_SA_RSP<0>")
	)
	(segment
		(start 385.46278 -248.83491)
		(end 385.114038 -249.183652)
		(width 0.088646)
		(layer "In6.Cu")
		(net "M_E_CPU0_SA_RSP<0>")
	)
	(arc
		(start 375.82475 -249.304302)
		(mid 375.548275 -249.371622)
		(end 375.274078 -249.295666)
		(width 0.088646)
		(layer "In6.Cu")
		(net "M_E_CPU0_SA_RSP<0>")
	)
	(arc
		(start 374.334278 -249.295666)
		(mid 374.14708 -249.245523)
		(end 373.959882 -249.295666)
		(width 0.088646)
		(layer "In6.Cu")
		(net "M_E_CPU0_SA_RSP<0>")
	)
	(arc
		(start 377.719082 -249.295666)
		(mid 377.43638 -249.371442)
		(end 377.153678 -249.295666)
		(width 0.088646)
		(layer "In6.Cu")
		(net "M_E_CPU0_SA_RSP<0>")
	)
	(arc
		(start 382.792732 -249.295666)
		(mid 382.605534 -249.245523)
		(end 382.418336 -249.295666)
		(width 0.088646)
		(layer "In6.Cu")
		(net "M_E_CPU0_SA_RSP<0>")
	)
	(arc
		(start 373.394732 -249.295666)
		(mid 373.207534 -249.245523)
		(end 373.020336 -249.295666)
		(width 0.088646)
		(layer "In6.Cu")
		(net "M_E_CPU0_SA_RSP<0>")
	)
	(arc
		(start 378.093478 -249.295666)
		(mid 377.90628 -249.245523)
		(end 377.719082 -249.295666)
		(width 0.088646)
		(layer "In6.Cu")
		(net "M_E_CPU0_SA_RSP<0>")
	)
	(arc
		(start 379.033278 -249.295666)
		(mid 378.84608 -249.245523)
		(end 378.658882 -249.295666)
		(width 0.088646)
		(layer "In6.Cu")
		(net "M_E_CPU0_SA_RSP<0>")
	)
	(arc
		(start 380.913132 -249.295666)
		(mid 380.725934 -249.245523)
		(end 380.538736 -249.295666)
		(width 0.088646)
		(layer "In6.Cu")
		(net "M_E_CPU0_SA_RSP<0>")
	)
	(arc
		(start 373.949468 -249.301762)
		(mid 373.67129 -249.371485)
		(end 373.394732 -249.295666)
		(width 0.088646)
		(layer "In6.Cu")
		(net "M_E_CPU0_SA_RSP<0>")
	)
	(arc
		(start 380.538736 -249.295666)
		(mid 380.256034 -249.371442)
		(end 379.973332 -249.295666)
		(width 0.088646)
		(layer "In6.Cu")
		(net "M_E_CPU0_SA_RSP<0>")
	)
	(arc
		(start 376.76455 -249.304302)
		(mid 376.488075 -249.371622)
		(end 376.213878 -249.295666)
		(width 0.088646)
		(layer "In6.Cu")
		(net "M_E_CPU0_SA_RSP<0>")
	)
	(arc
		(start 379.973332 -249.295666)
		(mid 379.786134 -249.245523)
		(end 379.598936 -249.295666)
		(width 0.088646)
		(layer "In6.Cu")
		(net "M_E_CPU0_SA_RSP<0>")
	)
	(arc
		(start 378.64415 -249.304302)
		(mid 378.367675 -249.371622)
		(end 378.093478 -249.295666)
		(width 0.088646)
		(layer "In6.Cu")
		(net "M_E_CPU0_SA_RSP<0>")
	)
	(arc
		(start 382.87071 -249.354848)
		(mid 382.83366 -249.322702)
		(end 382.792732 -249.295666)
		(width 0.088646)
		(layer "In6.Cu")
		(net "M_E_CPU0_SA_RSP<0>")
	)
	(arc
		(start 381.478536 -249.295666)
		(mid 381.195834 -249.371442)
		(end 380.913132 -249.295666)
		(width 0.088646)
		(layer "In6.Cu")
		(net "M_E_CPU0_SA_RSP<0>")
	)
	(arc
		(start 377.153678 -249.295666)
		(mid 376.96648 -249.245523)
		(end 376.779282 -249.295666)
		(width 0.088646)
		(layer "In6.Cu")
		(net "M_E_CPU0_SA_RSP<0>")
	)
	(arc
		(start 379.588522 -249.301762)
		(mid 379.31009 -249.371608)
		(end 379.033278 -249.295666)
		(width 0.088646)
		(layer "In6.Cu")
		(net "M_E_CPU0_SA_RSP<0>")
	)
	(arc
		(start 376.213878 -249.295666)
		(mid 376.02668 -249.245523)
		(end 375.839482 -249.295666)
		(width 0.088646)
		(layer "In6.Cu")
		(net "M_E_CPU0_SA_RSP<0>")
	)
	(arc
		(start 375.274078 -249.295666)
		(mid 375.08688 -249.245523)
		(end 374.899682 -249.295666)
		(width 0.088646)
		(layer "In6.Cu")
		(net "M_E_CPU0_SA_RSP<0>")
	)
	(arc
		(start 374.88495 -249.304302)
		(mid 374.608475 -249.371622)
		(end 374.334278 -249.295666)
		(width 0.088646)
		(layer "In6.Cu")
		(net "M_E_CPU0_SA_RSP<0>")
	)
	(arc
		(start 373.009922 -249.301762)
		(mid 372.73149 -249.371608)
		(end 372.454678 -249.295666)
		(width 0.088646)
		(layer "In6.Cu")
		(net "M_E_CPU0_SA_RSP<0>")
	)
	(arc
		(start 382.418336 -249.295666)
		(mid 382.135634 -249.371442)
		(end 381.852932 -249.295666)
		(width 0.088646)
		(layer "In6.Cu")
		(net "M_E_CPU0_SA_RSP<0>")
	)
	(arc
		(start 381.852932 -249.295666)
		(mid 381.665734 -249.245523)
		(end 381.478536 -249.295666)
		(width 0.088646)
		(layer "In6.Cu")
		(net "M_E_CPU0_SA_RSP<0>")
	)
	(segment
		(start 393.181586 -256.18821)
		(end 397.26362 -256.18821)
		(width 0.20066)
		(layer "F.Cu")
		(net "M_E_CPU0_SA_PAR")
	)
	(segment
		(start 386.036566 -252.597412)
		(end 388.558532 -253.09957)
		(width 0.1016)
		(layer "F.Cu")
		(net "M_E_CPU0_SA_PAR")
	)
	(segment
		(start 381.640334 -251.190506)
		(end 382.976628 -251.851922)
		(width 0.088646)
		(layer "F.Cu")
		(net "M_E_CPU0_SA_PAR")
	)
	(segment
		(start 409.830778 -260.478524)
		(end 409.599638 -260.478524)
		(width 0.20066)
		(layer "F.Cu")
		(net "M_E_CPU0_SA_PAR")
	)
	(segment
		(start 411.712664 -260.641592)
		(end 409.993846 -260.641592)
		(width 0.1016)
		(layer "F.Cu")
		(net "M_E_CPU0_SA_PAR")
	)
	(segment
		(start 381.106934 -249.747786)
		(end 380.854458 -249.747786)
		(width 0.088646)
		(layer "F.Cu")
		(net "M_E_CPU0_SA_PAR")
	)
	(segment
		(start 390.134602 -253.75235)
		(end 392.570462 -256.18821)
		(width 0.1016)
		(layer "F.Cu")
		(net "M_E_CPU0_SA_PAR")
	)
	(segment
		(start 380.351284 -250.155964)
		(end 380.351284 -250.212606)
		(width 0.088646)
		(layer "F.Cu")
		(net "M_E_CPU0_SA_PAR")
	)
	(segment
		(start 409.993846 -260.641592)
		(end 409.87853 -260.526276)
		(width 0.1016)
		(layer "F.Cu")
		(net "M_E_CPU0_SA_PAR")
	)
	(segment
		(start 393.107418 -256.18821)
		(end 393.181586 -256.18821)
		(width 0.101854)
		(layer "F.Cu")
		(net "M_E_CPU0_SA_PAR")
	)
	(segment
		(start 397.26362 -256.18821)
		(end 404.937214 -259.366766)
		(width 0.20066)
		(layer "F.Cu")
		(net "M_E_CPU0_SA_PAR")
	)
	(segment
		(start 380.379986 -250.313698)
		(end 380.41326 -250.3678)
		(width 0.088646)
		(layer "F.Cu")
		(net "M_E_CPU0_SA_PAR")
	)
	(segment
		(start 409.599638 -260.478524)
		(end 408.48788 -259.366766)
		(width 0.20066)
		(layer "F.Cu")
		(net "M_E_CPU0_SA_PAR")
	)
	(segment
		(start 380.466092 -250.43384)
		(end 380.658878 -250.621292)
		(width 0.088646)
		(layer "F.Cu")
		(net "M_E_CPU0_SA_PAR")
	)
	(segment
		(start 411.82798 -260.526276)
		(end 411.712664 -260.641592)
		(width 0.1016)
		(layer "F.Cu")
		(net "M_E_CPU0_SA_PAR")
	)
	(segment
		(start 381.563626 -249.403108)
		(end 381.521208 -249.505216)
		(width 0.088646)
		(layer "F.Cu")
		(net "M_E_CPU0_SA_PAR")
	)
	(segment
		(start 380.538736 -249.831606)
		(end 380.529846 -249.836686)
		(width 0.088646)
		(layer "F.Cu")
		(net "M_E_CPU0_SA_PAR")
	)
	(segment
		(start 384.14071 -252.335284)
		(end 384.894328 -252.485144)
		(width 0.1016)
		(layer "F.Cu")
		(net "M_E_CPU0_SA_PAR")
	)
	(segment
		(start 409.87853 -260.526276)
		(end 409.830778 -260.478524)
		(width 0.20066)
		(layer "F.Cu")
		(net "M_E_CPU0_SA_PAR")
	)
	(segment
		(start 381.47371 -249.579892)
		(end 381.399288 -249.662188)
		(width 0.088646)
		(layer "F.Cu")
		(net "M_E_CPU0_SA_PAR")
	)
	(segment
		(start 382.976628 -251.851922)
		(end 383.248154 -251.964444)
		(width 0.088646)
		(layer "F.Cu")
		(net "M_E_CPU0_SA_PAR")
	)
	(segment
		(start 383.248154 -251.964444)
		(end 384.14071 -252.335284)
		(width 0.1016)
		(layer "F.Cu")
		(net "M_E_CPU0_SA_PAR")
	)
	(segment
		(start 412.98749 -259.366766)
		(end 411.82798 -260.526276)
		(width 0.20066)
		(layer "F.Cu")
		(net "M_E_CPU0_SA_PAR")
	)
	(segment
		(start 408.48788 -259.366766)
		(end 406.753314 -259.366766)
		(width 0.20066)
		(layer "F.Cu")
		(net "M_E_CPU0_SA_PAR")
	)
	(segment
		(start 380.351284 -250.212606)
		(end 380.379986 -250.313698)
		(width 0.088646)
		(layer "F.Cu")
		(net "M_E_CPU0_SA_PAR")
	)
	(segment
		(start 381.665734 -248.528078)
		(end 381.563626 -249.403108)
		(width 0.088646)
		(layer "F.Cu")
		(net "M_E_CPU0_SA_PAR")
	)
	(segment
		(start 380.658878 -250.621292)
		(end 381.640334 -251.190506)
		(width 0.088646)
		(layer "F.Cu")
		(net "M_E_CPU0_SA_PAR")
	)
	(segment
		(start 414.297114 -259.366766)
		(end 412.98749 -259.366766)
		(width 0.20066)
		(layer "F.Cu")
		(net "M_E_CPU0_SA_PAR")
	)
	(segment
		(start 404.937214 -259.366766)
		(end 406.753314 -259.366766)
		(width 0.20066)
		(layer "F.Cu")
		(net "M_E_CPU0_SA_PAR")
	)
	(segment
		(start 392.570462 -256.18821)
		(end 393.107418 -256.18821)
		(width 0.1016)
		(layer "F.Cu")
		(net "M_E_CPU0_SA_PAR")
	)
	(segment
		(start 384.894328 -252.485144)
		(end 386.036566 -252.597412)
		(width 0.1016)
		(layer "F.Cu")
		(net "M_E_CPU0_SA_PAR")
	)
	(segment
		(start 380.41326 -250.3678)
		(end 380.466092 -250.43384)
		(width 0.088646)
		(layer "F.Cu")
		(net "M_E_CPU0_SA_PAR")
	)
	(segment
		(start 388.558532 -253.09957)
		(end 390.134602 -253.75235)
		(width 0.1016)
		(layer "F.Cu")
		(net "M_E_CPU0_SA_PAR")
	)
	(arc
		(start 380.854458 -249.747786)
		(mid 380.691133 -249.769105)
		(end 380.538736 -249.831606)
		(width 0.088646)
		(layer "F.Cu")
		(net "M_E_CPU0_SA_PAR")
	)
	(arc
		(start 380.529846 -249.836686)
		(mid 380.398932 -249.973046)
		(end 380.351284 -250.155964)
		(width 0.088646)
		(layer "F.Cu")
		(net "M_E_CPU0_SA_PAR")
	)
	(arc
		(start 381.32512 -249.711464)
		(mid 381.217542 -249.738732)
		(end 381.106934 -249.747786)
		(width 0.088646)
		(layer "F.Cu")
		(net "M_E_CPU0_SA_PAR")
	)
	(arc
		(start 381.521208 -249.505216)
		(mid 381.500646 -249.54458)
		(end 381.47371 -249.579892)
		(width 0.088646)
		(layer "F.Cu")
		(net "M_E_CPU0_SA_PAR")
	)
	(arc
		(start 381.399288 -249.662188)
		(mid 381.36533 -249.69153)
		(end 381.32512 -249.711464)
		(width 0.088646)
		(layer "F.Cu")
		(net "M_E_CPU0_SA_PAR")
	)
	(segment
		(start 401.222972 -273.666458)
		(end 401.261072 -273.666458)
		(width 0.1524)
		(layer "F.Cu")
		(net "M_E_CPU0_SA_DQS_DP<9>")
	)
	(segment
		(start 411.266894 -273.816572)
		(end 410.853382 -273.816572)
		(width 0.20066)
		(layer "F.Cu")
		(net "M_E_CPU0_SA_DQS_DP<9>")
	)
	(segment
		(start 412.912306 -273.39163)
		(end 412.79064 -273.39163)
		(width 0.20066)
		(layer "F.Cu")
		(net "M_E_CPU0_SA_DQS_DP<9>")
	)
	(segment
		(start 411.709108 -274.067778)
		(end 411.5181 -274.067778)
		(width 0.20066)
		(layer "F.Cu")
		(net "M_E_CPU0_SA_DQS_DP<9>")
	)
	(segment
		(start 394.750544 -266.448032)
		(end 399.391124 -271.088612)
		(width 0.1524)
		(layer "F.Cu")
		(net "M_E_CPU0_SA_DQS_DP<9>")
	)
	(segment
		(start 411.926786 -273.8501)
		(end 411.709108 -274.067778)
		(width 0.20066)
		(layer "F.Cu")
		(net "M_E_CPU0_SA_DQS_DP<9>")
	)
	(segment
		(start 417.147502 -274.078192)
		(end 416.70859 -273.63928)
		(width 0.20066)
		(layer "F.Cu")
		(net "M_E_CPU0_SA_DQS_DP<9>")
	)
	(segment
		(start 411.5181 -274.067778)
		(end 411.266894 -273.816572)
		(width 0.20066)
		(layer "F.Cu")
		(net "M_E_CPU0_SA_DQS_DP<9>")
	)
	(segment
		(start 407.741882 -273.39163)
		(end 407.879804 -273.39163)
		(width 0.101854)
		(layer "F.Cu")
		(net "M_E_CPU0_SA_DQS_DP<9>")
	)
	(segment
		(start 407.901648 -273.369786)
		(end 408.092656 -273.369786)
		(width 0.20066)
		(layer "F.Cu")
		(net "M_E_CPU0_SA_DQS_DP<9>")
	)
	(segment
		(start 408.092656 -273.369786)
		(end 408.39136 -273.66849)
		(width 0.20066)
		(layer "F.Cu")
		(net "M_E_CPU0_SA_DQS_DP<9>")
	)
	(segment
		(start 410.097732 -274.067524)
		(end 410.348684 -273.816572)
		(width 0.20066)
		(layer "F.Cu")
		(net "M_E_CPU0_SA_DQS_DP<9>")
	)
	(segment
		(start 412.79064 -273.39163)
		(end 412.525972 -273.656298)
		(width 0.20066)
		(layer "F.Cu")
		(net "M_E_CPU0_SA_DQS_DP<9>")
	)
	(segment
		(start 394.750798 -266.448032)
		(end 394.750544 -266.448032)
		(width 0.1524)
		(layer "F.Cu")
		(net "M_E_CPU0_SA_DQS_DP<9>")
	)
	(segment
		(start 390.104884 -261.84606)
		(end 390.149334 -261.846568)
		(width 0.088646)
		(layer "F.Cu")
		(net "M_E_CPU0_SA_DQS_DP<9>")
	)
	(segment
		(start 417.829238 -273.816572)
		(end 417.567618 -274.078192)
		(width 0.20066)
		(layer "F.Cu")
		(net "M_E_CPU0_SA_DQS_DP<9>")
	)
	(segment
		(start 387.12775 -259.522214)
		(end 387.779768 -259.522214)
		(width 0.088646)
		(layer "F.Cu")
		(net "M_E_CPU0_SA_DQS_DP<9>")
	)
	(segment
		(start 415.825686 -273.39163)
		(end 415.744152 -273.39163)
		(width 0.20066)
		(layer "F.Cu")
		(net "M_E_CPU0_SA_DQS_DP<9>")
	)
	(segment
		(start 405.736552 -273.391376)
		(end 405.736806 -273.39163)
		(width 0.1016)
		(layer "F.Cu")
		(net "M_E_CPU0_SA_DQS_DP<9>")
	)
	(segment
		(start 389.708898 -261.451344)
		(end 390.104884 -261.84606)
		(width 0.088646)
		(layer "F.Cu")
		(net "M_E_CPU0_SA_DQS_DP<9>")
	)
	(segment
		(start 404.089616 -273.666458)
		(end 404.364698 -273.391376)
		(width 0.20066)
		(layer "F.Cu")
		(net "M_E_CPU0_SA_DQS_DP<9>")
	)
	(segment
		(start 390.149334 -261.846568)
		(end 390.164828 -261.862062)
		(width 0.088646)
		(layer "F.Cu")
		(net "M_E_CPU0_SA_DQS_DP<9>")
	)
	(segment
		(start 415.744152 -273.39163)
		(end 415.30016 -273.39163)
		(width 0.101854)
		(layer "F.Cu")
		(net "M_E_CPU0_SA_DQS_DP<9>")
	)
	(segment
		(start 401.186142 -273.703288)
		(end 401.222972 -273.666458)
		(width 0.1524)
		(layer "F.Cu")
		(net "M_E_CPU0_SA_DQS_DP<9>")
	)
	(segment
		(start 415.30016 -273.39163)
		(end 413.287464 -273.39163)
		(width 0.1016)
		(layer "F.Cu")
		(net "M_E_CPU0_SA_DQS_DP<9>")
	)
	(segment
		(start 405.45512 -273.391376)
		(end 405.736552 -273.391376)
		(width 0.101854)
		(layer "F.Cu")
		(net "M_E_CPU0_SA_DQS_DP<9>")
	)
	(segment
		(start 412.525972 -273.656298)
		(end 412.394654 -273.656298)
		(width 0.20066)
		(layer "F.Cu")
		(net "M_E_CPU0_SA_DQS_DP<9>")
	)
	(segment
		(start 410.348684 -273.816572)
		(end 410.853382 -273.816572)
		(width 0.20066)
		(layer "F.Cu")
		(net "M_E_CPU0_SA_DQS_DP<9>")
	)
	(segment
		(start 416.073336 -273.63928)
		(end 415.825686 -273.39163)
		(width 0.20066)
		(layer "F.Cu")
		(net "M_E_CPU0_SA_DQS_DP<9>")
	)
	(segment
		(start 408.756612 -273.66849)
		(end 409.155646 -274.067524)
		(width 0.20066)
		(layer "F.Cu")
		(net "M_E_CPU0_SA_DQS_DP<9>")
	)
	(segment
		(start 405.736806 -273.39163)
		(end 407.741882 -273.39163)
		(width 0.1016)
		(layer "F.Cu")
		(net "M_E_CPU0_SA_DQS_DP<9>")
	)
	(segment
		(start 412.394654 -273.656298)
		(end 411.926786 -273.8501)
		(width 0.20066)
		(layer "F.Cu")
		(net "M_E_CPU0_SA_DQS_DP<9>")
	)
	(segment
		(start 413.287464 -273.39163)
		(end 412.912306 -273.39163)
		(width 0.101854)
		(layer "F.Cu")
		(net "M_E_CPU0_SA_DQS_DP<9>")
	)
	(segment
		(start 418.397182 -273.816572)
		(end 417.829238 -273.816572)
		(width 0.20066)
		(layer "F.Cu")
		(net "M_E_CPU0_SA_DQS_DP<9>")
	)
	(segment
		(start 400.547332 -273.703288)
		(end 401.186142 -273.703288)
		(width 0.1524)
		(layer "F.Cu")
		(net "M_E_CPU0_SA_DQS_DP<9>")
	)
	(segment
		(start 408.39136 -273.66849)
		(end 408.756612 -273.66849)
		(width 0.20066)
		(layer "F.Cu")
		(net "M_E_CPU0_SA_DQS_DP<9>")
	)
	(segment
		(start 401.261072 -273.666458)
		(end 404.089616 -273.666458)
		(width 0.20066)
		(layer "F.Cu")
		(net "M_E_CPU0_SA_DQS_DP<9>")
	)
	(segment
		(start 386.750306 -259.574792)
		(end 386.757418 -259.570728)
		(width 0.088646)
		(layer "F.Cu")
		(net "M_E_CPU0_SA_DQS_DP<9>")
	)
	(segment
		(start 387.034278 -259.519928)
		(end 387.12775 -259.522214)
		(width 0.088646)
		(layer "F.Cu")
		(net "M_E_CPU0_SA_DQS_DP<9>")
	)
	(segment
		(start 399.391124 -271.088612)
		(end 399.766536 -272.968212)
		(width 0.1524)
		(layer "F.Cu")
		(net "M_E_CPU0_SA_DQS_DP<9>")
	)
	(segment
		(start 387.779768 -259.522214)
		(end 389.708898 -261.451344)
		(width 0.088646)
		(layer "F.Cu")
		(net "M_E_CPU0_SA_DQS_DP<9>")
	)
	(segment
		(start 390.164828 -261.862062)
		(end 394.750798 -266.448032)
		(width 0.1524)
		(layer "F.Cu")
		(net "M_E_CPU0_SA_DQS_DP<9>")
	)
	(segment
		(start 386.004562 -259.894832)
		(end 386.49656 -259.706872)
		(width 0.088646)
		(layer "F.Cu")
		(net "M_E_CPU0_SA_DQS_DP<9>")
	)
	(segment
		(start 417.567618 -274.078192)
		(end 417.147502 -274.078192)
		(width 0.20066)
		(layer "F.Cu")
		(net "M_E_CPU0_SA_DQS_DP<9>")
	)
	(segment
		(start 404.364698 -273.391376)
		(end 405.45512 -273.391376)
		(width 0.20066)
		(layer "F.Cu")
		(net "M_E_CPU0_SA_DQS_DP<9>")
	)
	(segment
		(start 399.766536 -272.968212)
		(end 400.098006 -273.463004)
		(width 0.1524)
		(layer "F.Cu")
		(net "M_E_CPU0_SA_DQS_DP<9>")
	)
	(segment
		(start 416.70859 -273.63928)
		(end 416.073336 -273.63928)
		(width 0.20066)
		(layer "F.Cu")
		(net "M_E_CPU0_SA_DQS_DP<9>")
	)
	(segment
		(start 409.155646 -274.067524)
		(end 410.097732 -274.067524)
		(width 0.20066)
		(layer "F.Cu")
		(net "M_E_CPU0_SA_DQS_DP<9>")
	)
	(segment
		(start 407.879804 -273.39163)
		(end 407.901648 -273.369786)
		(width 0.101854)
		(layer "F.Cu")
		(net "M_E_CPU0_SA_DQS_DP<9>")
	)
	(segment
		(start 400.098006 -273.463004)
		(end 400.547332 -273.703288)
		(width 0.1524)
		(layer "F.Cu")
		(net "M_E_CPU0_SA_DQS_DP<9>")
	)
	(arc
		(start 386.757418 -259.570728)
		(mid 386.761747 -259.568334)
		(end 386.766054 -259.565902)
		(width 0.088646)
		(layer "F.Cu")
		(net "M_E_CPU0_SA_DQS_DP<9>")
	)
	(arc
		(start 386.49656 -259.706872)
		(mid 386.624309 -259.642516)
		(end 386.750306 -259.574792)
		(width 0.088646)
		(layer "F.Cu")
		(net "M_E_CPU0_SA_DQS_DP<9>")
	)
	(arc
		(start 386.766054 -259.565902)
		(mid 386.82295 -259.53992)
		(end 386.884164 -259.52704)
		(width 0.088646)
		(layer "F.Cu")
		(net "M_E_CPU0_SA_DQS_DP<9>")
	)
	(arc
		(start 386.884164 -259.52704)
		(mid 386.959137 -259.521718)
		(end 387.034278 -259.519928)
		(width 0.088646)
		(layer "F.Cu")
		(net "M_E_CPU0_SA_DQS_DP<9>")
	)
	(segment
		(start 388.36981 -265.615674)
		(end 388.369556 -265.615674)
		(width 0.088646)
		(layer "F.Cu")
		(net "M_E_CPU0_SA_DQS_DP<8>")
	)
	(segment
		(start 387.21411 -264.460228)
		(end 388.36981 -265.615674)
		(width 0.088646)
		(layer "F.Cu")
		(net "M_E_CPU0_SA_DQS_DP<8>")
	)
	(segment
		(start 400.245326 -283.442156)
		(end 400.83232 -283.83484)
		(width 0.20066)
		(layer "F.Cu")
		(net "M_E_CPU0_SA_DQS_DP<8>")
	)
	(segment
		(start 405.73833 -282.734766)
		(end 405.745188 -282.741624)
		(width 0.1016)
		(layer "F.Cu")
		(net "M_E_CPU0_SA_DQS_DP<8>")
	)
	(segment
		(start 415.629344 -282.734258)
		(end 415.307526 -282.734258)
		(width 0.20066)
		(layer "F.Cu")
		(net "M_E_CPU0_SA_DQS_DP<8>")
	)
	(segment
		(start 409.74391 -283.365702)
		(end 410.149548 -283.365702)
		(width 0.20066)
		(layer "F.Cu")
		(net "M_E_CPU0_SA_DQS_DP<8>")
	)
	(segment
		(start 388.931912 -266.132818)
		(end 388.947406 -266.148312)
		(width 0.088646)
		(layer "F.Cu")
		(net "M_E_CPU0_SA_DQS_DP<8>")
	)
	(segment
		(start 412.706058 -282.99283)
		(end 412.427674 -282.99283)
		(width 0.20066)
		(layer "F.Cu")
		(net "M_E_CPU0_SA_DQS_DP<8>")
	)
	(segment
		(start 408.906218 -283.018484)
		(end 409.74391 -283.365702)
		(width 0.20066)
		(layer "F.Cu")
		(net "M_E_CPU0_SA_DQS_DP<8>")
	)
	(segment
		(start 418.397182 -283.166566)
		(end 417.829238 -283.166566)
		(width 0.20066)
		(layer "F.Cu")
		(net "M_E_CPU0_SA_DQS_DP<8>")
	)
	(segment
		(start 412.002732 -283.417772)
		(end 411.697932 -283.417772)
		(width 0.20066)
		(layer "F.Cu")
		(net "M_E_CPU0_SA_DQS_DP<8>")
	)
	(segment
		(start 397.950944 -281.147774)
		(end 400.245326 -283.442156)
		(width 0.20066)
		(layer "F.Cu")
		(net "M_E_CPU0_SA_DQS_DP<8>")
	)
	(segment
		(start 386.004562 -264.778236)
		(end 386.847842 -264.426192)
		(width 0.088646)
		(layer "F.Cu")
		(net "M_E_CPU0_SA_DQS_DP<8>")
	)
	(segment
		(start 410.348684 -283.166566)
		(end 410.853382 -283.166566)
		(width 0.20066)
		(layer "F.Cu")
		(net "M_E_CPU0_SA_DQS_DP<8>")
	)
	(segment
		(start 416.983418 -283.43479)
		(end 416.537902 -282.989274)
		(width 0.20066)
		(layer "F.Cu")
		(net "M_E_CPU0_SA_DQS_DP<8>")
	)
	(segment
		(start 397.872458 -281.121104)
		(end 397.924274 -281.121104)
		(width 0.1524)
		(layer "F.Cu")
		(net "M_E_CPU0_SA_DQS_DP<8>")
	)
	(segment
		(start 397.485362 -280.650442)
		(end 397.727424 -280.97607)
		(width 0.1524)
		(layer "F.Cu")
		(net "M_E_CPU0_SA_DQS_DP<8>")
	)
	(segment
		(start 397.070326 -279.874218)
		(end 397.485362 -280.650442)
		(width 0.1524)
		(layer "F.Cu")
		(net "M_E_CPU0_SA_DQS_DP<8>")
	)
	(segment
		(start 407.740866 -282.741624)
		(end 407.76144 -282.72105)
		(width 0.1016)
		(layer "F.Cu")
		(net "M_E_CPU0_SA_DQS_DP<8>")
	)
	(segment
		(start 405.745188 -282.741624)
		(end 407.740866 -282.741624)
		(width 0.1016)
		(layer "F.Cu")
		(net "M_E_CPU0_SA_DQS_DP<8>")
	)
	(segment
		(start 417.829238 -283.166566)
		(end 417.561014 -283.43479)
		(width 0.20066)
		(layer "F.Cu")
		(net "M_E_CPU0_SA_DQS_DP<8>")
	)
	(segment
		(start 395.66977 -272.870676)
		(end 397.070326 -279.874218)
		(width 0.1524)
		(layer "F.Cu")
		(net "M_E_CPU0_SA_DQS_DP<8>")
	)
	(segment
		(start 411.697932 -283.417772)
		(end 411.446726 -283.166566)
		(width 0.20066)
		(layer "F.Cu")
		(net "M_E_CPU0_SA_DQS_DP<8>")
	)
	(segment
		(start 386.847842 -264.426192)
		(end 387.131814 -264.426192)
		(width 0.088646)
		(layer "F.Cu")
		(net "M_E_CPU0_SA_DQS_DP<8>")
	)
	(segment
		(start 411.446726 -283.166566)
		(end 410.853382 -283.166566)
		(width 0.20066)
		(layer "F.Cu")
		(net "M_E_CPU0_SA_DQS_DP<8>")
	)
	(segment
		(start 416.537902 -282.989274)
		(end 415.88436 -282.989274)
		(width 0.20066)
		(layer "F.Cu")
		(net "M_E_CPU0_SA_DQS_DP<8>")
	)
	(segment
		(start 415.307526 -282.734258)
		(end 415.30016 -282.741624)
		(width 0.1016)
		(layer "F.Cu")
		(net "M_E_CPU0_SA_DQS_DP<8>")
	)
	(segment
		(start 407.763726 -282.72105)
		(end 408.29865 -282.72105)
		(width 0.20066)
		(layer "F.Cu")
		(net "M_E_CPU0_SA_DQS_DP<8>")
	)
	(segment
		(start 403.265386 -283.809694)
		(end 404.340314 -282.734766)
		(width 0.20066)
		(layer "F.Cu")
		(net "M_E_CPU0_SA_DQS_DP<8>")
	)
	(segment
		(start 401.008596 -283.907738)
		(end 403.028912 -283.907738)
		(width 0.20066)
		(layer "F.Cu")
		(net "M_E_CPU0_SA_DQS_DP<8>")
	)
	(segment
		(start 415.88436 -282.989274)
		(end 415.629344 -282.734258)
		(width 0.20066)
		(layer "F.Cu")
		(net "M_E_CPU0_SA_DQS_DP<8>")
	)
	(segment
		(start 397.924274 -281.121104)
		(end 397.950944 -281.147774)
		(width 0.1524)
		(layer "F.Cu")
		(net "M_E_CPU0_SA_DQS_DP<8>")
	)
	(segment
		(start 413.280352 -282.734512)
		(end 413.275526 -282.734512)
		(width 0.101854)
		(layer "F.Cu")
		(net "M_E_CPU0_SA_DQS_DP<8>")
	)
	(segment
		(start 412.964376 -282.734512)
		(end 412.706058 -282.99283)
		(width 0.20066)
		(layer "F.Cu")
		(net "M_E_CPU0_SA_DQS_DP<8>")
	)
	(segment
		(start 410.149548 -283.365702)
		(end 410.348684 -283.166566)
		(width 0.20066)
		(layer "F.Cu")
		(net "M_E_CPU0_SA_DQS_DP<8>")
	)
	(segment
		(start 408.29865 -282.72105)
		(end 408.596084 -283.018484)
		(width 0.20066)
		(layer "F.Cu")
		(net "M_E_CPU0_SA_DQS_DP<8>")
	)
	(segment
		(start 412.427674 -282.99283)
		(end 412.002732 -283.417772)
		(width 0.20066)
		(layer "F.Cu")
		(net "M_E_CPU0_SA_DQS_DP<8>")
	)
	(segment
		(start 415.30016 -282.741624)
		(end 413.287464 -282.741624)
		(width 0.1016)
		(layer "F.Cu")
		(net "M_E_CPU0_SA_DQS_DP<8>")
	)
	(segment
		(start 408.596084 -283.018484)
		(end 408.906218 -283.018484)
		(width 0.20066)
		(layer "F.Cu")
		(net "M_E_CPU0_SA_DQS_DP<8>")
	)
	(segment
		(start 388.369556 -265.615674)
		(end 388.8867 -266.132818)
		(width 0.088646)
		(layer "F.Cu")
		(net "M_E_CPU0_SA_DQS_DP<8>")
	)
	(segment
		(start 388.947406 -266.148312)
		(end 395.66977 -272.870676)
		(width 0.1524)
		(layer "F.Cu")
		(net "M_E_CPU0_SA_DQS_DP<8>")
	)
	(segment
		(start 404.340314 -282.734766)
		(end 405.731726 -282.734766)
		(width 0.20066)
		(layer "F.Cu")
		(net "M_E_CPU0_SA_DQS_DP<8>")
	)
	(segment
		(start 397.727424 -280.97607)
		(end 397.872458 -281.121104)
		(width 0.1524)
		(layer "F.Cu")
		(net "M_E_CPU0_SA_DQS_DP<8>")
	)
	(segment
		(start 407.76144 -282.72105)
		(end 407.763726 -282.72105)
		(width 0.101854)
		(layer "F.Cu")
		(net "M_E_CPU0_SA_DQS_DP<8>")
	)
	(segment
		(start 400.83232 -283.83484)
		(end 401.008596 -283.907738)
		(width 0.20066)
		(layer "F.Cu")
		(net "M_E_CPU0_SA_DQS_DP<8>")
	)
	(segment
		(start 388.8867 -266.132818)
		(end 388.931912 -266.132818)
		(width 0.088646)
		(layer "F.Cu")
		(net "M_E_CPU0_SA_DQS_DP<8>")
	)
	(segment
		(start 405.731726 -282.734766)
		(end 405.73833 -282.734766)
		(width 0.101854)
		(layer "F.Cu")
		(net "M_E_CPU0_SA_DQS_DP<8>")
	)
	(segment
		(start 403.028912 -283.907738)
		(end 403.265386 -283.809694)
		(width 0.20066)
		(layer "F.Cu")
		(net "M_E_CPU0_SA_DQS_DP<8>")
	)
	(segment
		(start 413.275526 -282.734512)
		(end 412.964376 -282.734512)
		(width 0.20066)
		(layer "F.Cu")
		(net "M_E_CPU0_SA_DQS_DP<8>")
	)
	(segment
		(start 417.561014 -283.43479)
		(end 416.983418 -283.43479)
		(width 0.20066)
		(layer "F.Cu")
		(net "M_E_CPU0_SA_DQS_DP<8>")
	)
	(segment
		(start 413.287464 -282.741624)
		(end 413.280352 -282.734512)
		(width 0.1016)
		(layer "F.Cu")
		(net "M_E_CPU0_SA_DQS_DP<8>")
	)
	(segment
		(start 387.131814 -264.426192)
		(end 387.21411 -264.460228)
		(width 0.088646)
		(layer "F.Cu")
		(net "M_E_CPU0_SA_DQS_DP<8>")
	)
	(segment
		(start 385.300982 -269.952216)
		(end 385.301236 -269.952724)
		(width 0.088646)
		(layer "F.Cu")
		(net "M_E_CPU0_SA_DQS_DP<7>")
	)
	(segment
		(start 408.370532 -292.35273)
		(end 408.868118 -292.35273)
		(width 0.20066)
		(layer "F.Cu")
		(net "M_E_CPU0_SA_DQS_DP<7>")
	)
	(segment
		(start 417.164012 -292.784784)
		(end 416.856418 -292.657276)
		(width 0.20066)
		(layer "F.Cu")
		(net "M_E_CPU0_SA_DQS_DP<7>")
	)
	(segment
		(start 386.00126 -269.109444)
		(end 386.1054 -269.109444)
		(width 0.088646)
		(layer "F.Cu")
		(net "M_E_CPU0_SA_DQS_DP<7>")
	)
	(segment
		(start 388.315708 -271.143222)
		(end 388.331202 -271.158716)
		(width 0.088646)
		(layer "F.Cu")
		(net "M_E_CPU0_SA_DQS_DP<7>")
	)
	(segment
		(start 413.280352 -292.08476)
		(end 413.275526 -292.08476)
		(width 0.101854)
		(layer "F.Cu")
		(net "M_E_CPU0_SA_DQS_DP<7>")
	)
	(segment
		(start 385.219956 -269.930626)
		(end 385.300982 -269.952216)
		(width 0.088646)
		(layer "F.Cu")
		(net "M_E_CPU0_SA_DQS_DP<7>")
	)
	(segment
		(start 415.30016 -292.091872)
		(end 413.287464 -292.091872)
		(width 0.1016)
		(layer "F.Cu")
		(net "M_E_CPU0_SA_DQS_DP<7>")
	)
	(segment
		(start 404.590504 -292.581584)
		(end 404.86457 -292.307518)
		(width 0.20066)
		(layer "F.Cu")
		(net "M_E_CPU0_SA_DQS_DP<7>")
	)
	(segment
		(start 405.242522 -292.307518)
		(end 405.471884 -292.078156)
		(width 0.20066)
		(layer "F.Cu")
		(net "M_E_CPU0_SA_DQS_DP<7>")
	)
	(segment
		(start 410.34843 -292.516814)
		(end 410.853382 -292.516814)
		(width 0.20066)
		(layer "F.Cu")
		(net "M_E_CPU0_SA_DQS_DP<7>")
	)
	(segment
		(start 411.44698 -292.516814)
		(end 410.853382 -292.516814)
		(width 0.20066)
		(layer "F.Cu")
		(net "M_E_CPU0_SA_DQS_DP<7>")
	)
	(segment
		(start 417.828984 -292.516814)
		(end 417.561014 -292.784784)
		(width 0.20066)
		(layer "F.Cu")
		(net "M_E_CPU0_SA_DQS_DP<7>")
	)
	(segment
		(start 385.064762 -269.66164)
		(end 385.219956 -269.930626)
		(width 0.088646)
		(layer "F.Cu")
		(net "M_E_CPU0_SA_DQS_DP<7>")
	)
	(segment
		(start 393.333478 -288.677858)
		(end 399.250916 -294.595296)
		(width 0.20066)
		(layer "F.Cu")
		(net "M_E_CPU0_SA_DQS_DP<7>")
	)
	(segment
		(start 415.307526 -292.084506)
		(end 415.30016 -292.091872)
		(width 0.1016)
		(layer "F.Cu")
		(net "M_E_CPU0_SA_DQS_DP<7>")
	)
	(segment
		(start 408.088338 -292.070536)
		(end 408.370532 -292.35273)
		(width 0.20066)
		(layer "F.Cu")
		(net "M_E_CPU0_SA_DQS_DP<7>")
	)
	(segment
		(start 413.275526 -292.08476)
		(end 412.964122 -292.08476)
		(width 0.20066)
		(layer "F.Cu")
		(net "M_E_CPU0_SA_DQS_DP<7>")
	)
	(segment
		(start 399.439384 -294.721534)
		(end 399.955258 -294.93591)
		(width 0.20066)
		(layer "F.Cu")
		(net "M_E_CPU0_SA_DQS_DP<7>")
	)
	(segment
		(start 418.397182 -292.516814)
		(end 417.828984 -292.516814)
		(width 0.20066)
		(layer "F.Cu")
		(net "M_E_CPU0_SA_DQS_DP<7>")
	)
	(segment
		(start 412.964122 -292.08476)
		(end 412.706058 -292.342824)
		(width 0.20066)
		(layer "F.Cu")
		(net "M_E_CPU0_SA_DQS_DP<7>")
	)
	(segment
		(start 393.306554 -288.650934)
		(end 393.333478 -288.677858)
		(width 0.1524)
		(layer "F.Cu")
		(net "M_E_CPU0_SA_DQS_DP<7>")
	)
	(segment
		(start 402.514562 -294.767254)
		(end 403.012656 -294.43426)
		(width 0.20066)
		(layer "F.Cu")
		(net "M_E_CPU0_SA_DQS_DP<7>")
	)
	(segment
		(start 404.86457 -292.307518)
		(end 405.242522 -292.307518)
		(width 0.20066)
		(layer "F.Cu")
		(net "M_E_CPU0_SA_DQS_DP<7>")
	)
	(segment
		(start 412.388558 -292.342824)
		(end 411.963616 -292.767766)
		(width 0.20066)
		(layer "F.Cu")
		(net "M_E_CPU0_SA_DQS_DP<7>")
	)
	(segment
		(start 410.097732 -292.767512)
		(end 410.34843 -292.516814)
		(width 0.20066)
		(layer "F.Cu")
		(net "M_E_CPU0_SA_DQS_DP<7>")
	)
	(segment
		(start 407.763726 -292.070536)
		(end 408.088338 -292.070536)
		(width 0.20066)
		(layer "F.Cu")
		(net "M_E_CPU0_SA_DQS_DP<7>")
	)
	(segment
		(start 388.125462 -270.998188)
		(end 388.270496 -271.143222)
		(width 0.088646)
		(layer "F.Cu")
		(net "M_E_CPU0_SA_DQS_DP<7>")
	)
	(segment
		(start 392.063732 -274.891246)
		(end 393.136628 -280.24582)
		(width 0.1524)
		(layer "F.Cu")
		(net "M_E_CPU0_SA_DQS_DP<7>")
	)
	(segment
		(start 388.331202 -271.158716)
		(end 392.063732 -274.891246)
		(width 0.1524)
		(layer "F.Cu")
		(net "M_E_CPU0_SA_DQS_DP<7>")
	)
	(segment
		(start 388.058152 -270.835882)
		(end 388.125462 -270.998188)
		(width 0.088646)
		(layer "F.Cu")
		(net "M_E_CPU0_SA_DQS_DP<7>")
	)
	(segment
		(start 399.250916 -294.595296)
		(end 399.439384 -294.721534)
		(width 0.20066)
		(layer "F.Cu")
		(net "M_E_CPU0_SA_DQS_DP<7>")
	)
	(segment
		(start 415.88436 -292.339268)
		(end 415.629598 -292.084506)
		(width 0.20066)
		(layer "F.Cu")
		(net "M_E_CPU0_SA_DQS_DP<7>")
	)
	(segment
		(start 415.629598 -292.084506)
		(end 415.307526 -292.084506)
		(width 0.20066)
		(layer "F.Cu")
		(net "M_E_CPU0_SA_DQS_DP<7>")
	)
	(segment
		(start 404.5204 -292.75151)
		(end 404.590504 -292.581584)
		(width 0.20066)
		(layer "F.Cu")
		(net "M_E_CPU0_SA_DQS_DP<7>")
	)
	(segment
		(start 385.592574 -269.291562)
		(end 385.614418 -269.269464)
		(width 0.088646)
		(layer "F.Cu")
		(net "M_E_CPU0_SA_DQS_DP<7>")
	)
	(segment
		(start 387.92531 -270.031718)
		(end 388.058152 -270.351504)
		(width 0.088646)
		(layer "F.Cu")
		(net "M_E_CPU0_SA_DQS_DP<7>")
	)
	(segment
		(start 411.697932 -292.767766)
		(end 411.44698 -292.516814)
		(width 0.20066)
		(layer "F.Cu")
		(net "M_E_CPU0_SA_DQS_DP<7>")
	)
	(segment
		(start 393.25423 -288.650934)
		(end 393.306554 -288.650934)
		(width 0.1524)
		(layer "F.Cu")
		(net "M_E_CPU0_SA_DQS_DP<7>")
	)
	(segment
		(start 399.955258 -294.93591)
		(end 400.27733 -295.000172)
		(width 0.20066)
		(layer "F.Cu")
		(net "M_E_CPU0_SA_DQS_DP<7>")
	)
	(segment
		(start 387.219952 -269.32636)
		(end 387.92531 -270.031718)
		(width 0.088646)
		(layer "F.Cu")
		(net "M_E_CPU0_SA_DQS_DP<7>")
	)
	(segment
		(start 388.058152 -270.351504)
		(end 388.058152 -270.835882)
		(width 0.088646)
		(layer "F.Cu")
		(net "M_E_CPU0_SA_DQS_DP<7>")
	)
	(segment
		(start 401.951444 -295.000172)
		(end 402.514562 -294.767254)
		(width 0.20066)
		(layer "F.Cu")
		(net "M_E_CPU0_SA_DQS_DP<7>")
	)
	(segment
		(start 417.561014 -292.784784)
		(end 417.164012 -292.784784)
		(width 0.20066)
		(layer "F.Cu")
		(net "M_E_CPU0_SA_DQS_DP<7>")
	)
	(segment
		(start 407.740104 -292.091618)
		(end 407.761186 -292.070536)
		(width 0.1016)
		(layer "F.Cu")
		(net "M_E_CPU0_SA_DQS_DP<7>")
	)
	(segment
		(start 405.471884 -292.078156)
		(end 405.731726 -292.078156)
		(width 0.20066)
		(layer "F.Cu")
		(net "M_E_CPU0_SA_DQS_DP<7>")
	)
	(segment
		(start 416.856418 -292.657276)
		(end 416.53841 -292.339268)
		(width 0.20066)
		(layer "F.Cu")
		(net "M_E_CPU0_SA_DQS_DP<7>")
	)
	(segment
		(start 412.706058 -292.342824)
		(end 412.388558 -292.342824)
		(width 0.20066)
		(layer "F.Cu")
		(net "M_E_CPU0_SA_DQS_DP<7>")
	)
	(segment
		(start 408.868118 -292.35273)
		(end 409.868878 -292.767512)
		(width 0.20066)
		(layer "F.Cu")
		(net "M_E_CPU0_SA_DQS_DP<7>")
	)
	(segment
		(start 411.963616 -292.767766)
		(end 411.697932 -292.767766)
		(width 0.20066)
		(layer "F.Cu")
		(net "M_E_CPU0_SA_DQS_DP<7>")
	)
	(segment
		(start 385.439666 -269.668244)
		(end 385.439666 -269.662148)
		(width 0.088646)
		(layer "F.Cu")
		(net "M_E_CPU0_SA_DQS_DP<7>")
	)
	(segment
		(start 405.750268 -292.091618)
		(end 407.740104 -292.091618)
		(width 0.1016)
		(layer "F.Cu")
		(net "M_E_CPU0_SA_DQS_DP<7>")
	)
	(segment
		(start 386.422138 -269.188438)
		(end 386.886704 -269.188438)
		(width 0.088646)
		(layer "F.Cu")
		(net "M_E_CPU0_SA_DQS_DP<7>")
	)
	(segment
		(start 388.270496 -271.143222)
		(end 388.315708 -271.143222)
		(width 0.088646)
		(layer "F.Cu")
		(net "M_E_CPU0_SA_DQS_DP<7>")
	)
	(segment
		(start 407.761186 -292.070536)
		(end 407.763726 -292.070536)
		(width 0.101854)
		(layer "F.Cu")
		(net "M_E_CPU0_SA_DQS_DP<7>")
	)
	(segment
		(start 393.136628 -288.533332)
		(end 393.25423 -288.650934)
		(width 0.1524)
		(layer "F.Cu")
		(net "M_E_CPU0_SA_DQS_DP<7>")
	)
	(segment
		(start 416.53841 -292.339268)
		(end 415.88436 -292.339268)
		(width 0.20066)
		(layer "F.Cu")
		(net "M_E_CPU0_SA_DQS_DP<7>")
	)
	(segment
		(start 386.886704 -269.188438)
		(end 387.219952 -269.32636)
		(width 0.088646)
		(layer "F.Cu")
		(net "M_E_CPU0_SA_DQS_DP<7>")
	)
	(segment
		(start 393.136628 -280.24582)
		(end 393.136628 -288.533332)
		(width 0.1524)
		(layer "F.Cu")
		(net "M_E_CPU0_SA_DQS_DP<7>")
	)
	(segment
		(start 405.736806 -292.078156)
		(end 405.750268 -292.091618)
		(width 0.1016)
		(layer "F.Cu")
		(net "M_E_CPU0_SA_DQS_DP<7>")
	)
	(segment
		(start 403.012656 -294.43426)
		(end 404.167594 -293.279322)
		(width 0.20066)
		(layer "F.Cu")
		(net "M_E_CPU0_SA_DQS_DP<7>")
	)
	(segment
		(start 400.27733 -295.000172)
		(end 401.951444 -295.000172)
		(width 0.20066)
		(layer "F.Cu")
		(net "M_E_CPU0_SA_DQS_DP<7>")
	)
	(segment
		(start 404.167594 -293.279322)
		(end 404.5204 -292.75151)
		(width 0.20066)
		(layer "F.Cu")
		(net "M_E_CPU0_SA_DQS_DP<7>")
	)
	(segment
		(start 405.731726 -292.078156)
		(end 405.736806 -292.078156)
		(width 0.101854)
		(layer "F.Cu")
		(net "M_E_CPU0_SA_DQS_DP<7>")
	)
	(segment
		(start 413.287464 -292.091872)
		(end 413.280352 -292.08476)
		(width 0.1016)
		(layer "F.Cu")
		(net "M_E_CPU0_SA_DQS_DP<7>")
	)
	(segment
		(start 409.868878 -292.767512)
		(end 410.097732 -292.767512)
		(width 0.20066)
		(layer "F.Cu")
		(net "M_E_CPU0_SA_DQS_DP<7>")
	)
	(arc
		(start 385.439666 -269.65529)
		(mid 385.480537 -269.458461)
		(end 385.592574 -269.291562)
		(width 0.088646)
		(layer "F.Cu")
		(net "M_E_CPU0_SA_DQS_DP<7>")
	)
	(arc
		(start 386.263642 -269.148814)
		(mid 386.340455 -269.17836)
		(end 386.422138 -269.188438)
		(width 0.088646)
		(layer "F.Cu")
		(net "M_E_CPU0_SA_DQS_DP<7>")
	)
	(arc
		(start 385.439666 -269.662148)
		(mid 385.439656 -269.658719)
		(end 385.439666 -269.65529)
		(width 0.088646)
		(layer "F.Cu")
		(net "M_E_CPU0_SA_DQS_DP<7>")
	)
	(arc
		(start 385.614418 -269.269464)
		(mid 385.791891 -269.150907)
		(end 386.00126 -269.109444)
		(width 0.088646)
		(layer "F.Cu")
		(net "M_E_CPU0_SA_DQS_DP<7>")
	)
	(arc
		(start 386.1054 -269.109444)
		(mid 386.186928 -269.119445)
		(end 386.263642 -269.148814)
		(width 0.088646)
		(layer "F.Cu")
		(net "M_E_CPU0_SA_DQS_DP<7>")
	)
	(arc
		(start 385.301236 -269.952724)
		(mid 385.401956 -269.825806)
		(end 385.439666 -269.668244)
		(width 0.088646)
		(layer "F.Cu")
		(net "M_E_CPU0_SA_DQS_DP<7>")
	)
	(segment
		(start 413.279336 -301.436024)
		(end 413.275526 -301.436024)
		(width 0.101854)
		(layer "F.Cu")
		(net "M_E_CPU0_SA_DQS_DP<6>")
	)
	(segment
		(start 413.280098 -301.436786)
		(end 413.279336 -301.436024)
		(width 0.101854)
		(layer "F.Cu")
		(net "M_E_CPU0_SA_DQS_DP<6>")
	)
	(segment
		(start 412.962852 -301.436024)
		(end 412.706058 -301.692818)
		(width 0.20066)
		(layer "F.Cu")
		(net "M_E_CPU0_SA_DQS_DP<6>")
	)
	(segment
		(start 417.828984 -301.866808)
		(end 417.561014 -302.134778)
		(width 0.20066)
		(layer "F.Cu")
		(net "M_E_CPU0_SA_DQS_DP<6>")
	)
	(segment
		(start 415.302446 -301.441866)
		(end 413.285432 -301.441866)
		(width 0.1016)
		(layer "F.Cu")
		(net "M_E_CPU0_SA_DQS_DP<6>")
	)
	(segment
		(start 416.758882 -301.689262)
		(end 415.88436 -301.689262)
		(width 0.20066)
		(layer "F.Cu")
		(net "M_E_CPU0_SA_DQS_DP<6>")
	)
	(segment
		(start 412.706058 -301.692818)
		(end 412.427674 -301.692818)
		(width 0.20066)
		(layer "F.Cu")
		(net "M_E_CPU0_SA_DQS_DP<6>")
	)
	(segment
		(start 382.715516 -272.639028)
		(end 382.715262 -272.639282)
		(width 0.20066)
		(layer "F.Cu")
		(net "M_E_CPU0_SA_DQS_DP<6>")
	)
	(segment
		(start 418.397182 -301.866808)
		(end 417.828984 -301.866808)
		(width 0.20066)
		(layer "F.Cu")
		(net "M_E_CPU0_SA_DQS_DP<6>")
	)
	(segment
		(start 415.307526 -301.436786)
		(end 415.302446 -301.441866)
		(width 0.1016)
		(layer "F.Cu")
		(net "M_E_CPU0_SA_DQS_DP<6>")
	)
	(segment
		(start 413.285432 -301.441866)
		(end 413.280352 -301.436786)
		(width 0.1016)
		(layer "F.Cu")
		(net "M_E_CPU0_SA_DQS_DP<6>")
	)
	(segment
		(start 417.204398 -302.134778)
		(end 416.758882 -301.689262)
		(width 0.20066)
		(layer "F.Cu")
		(net "M_E_CPU0_SA_DQS_DP<6>")
	)
	(segment
		(start 409.723082 -301.866554)
		(end 410.853128 -301.866554)
		(width 0.20066)
		(layer "F.Cu")
		(net "M_E_CPU0_SA_DQS_DP<6>")
	)
	(segment
		(start 415.308288 -301.436024)
		(end 415.307526 -301.436786)
		(width 0.20066)
		(layer "F.Cu")
		(net "M_E_CPU0_SA_DQS_DP<6>")
	)
	(segment
		(start 415.631122 -301.436024)
		(end 415.308288 -301.436024)
		(width 0.20066)
		(layer "F.Cu")
		(net "M_E_CPU0_SA_DQS_DP<6>")
	)
	(segment
		(start 413.280352 -301.436786)
		(end 413.280098 -301.436786)
		(width 0.101854)
		(layer "F.Cu")
		(net "M_E_CPU0_SA_DQS_DP<6>")
	)
	(segment
		(start 412.427674 -301.692818)
		(end 412.002732 -302.11776)
		(width 0.20066)
		(layer "F.Cu")
		(net "M_E_CPU0_SA_DQS_DP<6>")
	)
	(segment
		(start 411.697932 -302.11776)
		(end 411.44698 -301.866808)
		(width 0.20066)
		(layer "F.Cu")
		(net "M_E_CPU0_SA_DQS_DP<6>")
	)
	(segment
		(start 415.88436 -301.689262)
		(end 415.631122 -301.436024)
		(width 0.20066)
		(layer "F.Cu")
		(net "M_E_CPU0_SA_DQS_DP<6>")
	)
	(segment
		(start 382.715516 -272.103342)
		(end 382.715516 -272.639028)
		(width 0.20066)
		(layer "F.Cu")
		(net "M_E_CPU0_SA_DQS_DP<6>")
	)
	(segment
		(start 410.853128 -301.866554)
		(end 410.853382 -301.866808)
		(width 0.20066)
		(layer "F.Cu")
		(net "M_E_CPU0_SA_DQS_DP<6>")
	)
	(segment
		(start 417.561014 -302.134778)
		(end 417.204398 -302.134778)
		(width 0.20066)
		(layer "F.Cu")
		(net "M_E_CPU0_SA_DQS_DP<6>")
	)
	(segment
		(start 413.275526 -301.436024)
		(end 412.962852 -301.436024)
		(width 0.20066)
		(layer "F.Cu")
		(net "M_E_CPU0_SA_DQS_DP<6>")
	)
	(segment
		(start 411.44698 -301.866808)
		(end 410.853382 -301.866808)
		(width 0.20066)
		(layer "F.Cu")
		(net "M_E_CPU0_SA_DQS_DP<6>")
	)
	(segment
		(start 412.002732 -302.11776)
		(end 411.697932 -302.11776)
		(width 0.20066)
		(layer "F.Cu")
		(net "M_E_CPU0_SA_DQS_DP<6>")
	)
	(segment
		(start 384.310636 -272.151094)
		(end 384.308858 -272.15211)
		(width 0.088646)
		(layer "In2.Cu")
		(net "M_E_CPU0_SA_DQS_DP<6>")
	)
	(segment
		(start 388.780782 -272.902934)
		(end 388.16788 -272.902934)
		(width 0.088646)
		(layer "In2.Cu")
		(net "M_E_CPU0_SA_DQS_DP<6>")
	)
	(segment
		(start 403.836378 -295.522396)
		(end 403.836124 -295.521888)
		(width 0.18288)
		(layer "In2.Cu")
		(net "M_E_CPU0_SA_DQS_DP<6>")
	)
	(segment
		(start 383.284984 -272.582132)
		(end 383.227834 -272.639282)
		(width 0.088646)
		(layer "In2.Cu")
		(net "M_E_CPU0_SA_DQS_DP<6>")
	)
	(segment
		(start 385.266946 -272.140934)
		(end 385.252214 -272.14957)
		(width 0.088646)
		(layer "In2.Cu")
		(net "M_E_CPU0_SA_DQS_DP<6>")
	)
	(segment
		(start 406.142444 -301.687992)
		(end 405.89962 -301.445168)
		(width 0.18288)
		(layer "In2.Cu")
		(net "M_E_CPU0_SA_DQS_DP<6>")
	)
	(segment
		(start 383.227834 -272.639282)
		(end 382.715262 -272.639282)
		(width 0.088646)
		(layer "In2.Cu")
		(net "M_E_CPU0_SA_DQS_DP<6>")
	)
	(segment
		(start 408.030172 -302.298608)
		(end 407.873454 -302.233584)
		(width 0.18288)
		(layer "In2.Cu")
		(net "M_E_CPU0_SA_DQS_DP<6>")
	)
	(segment
		(start 408.805888 -302.138842)
		(end 408.420316 -302.298608)
		(width 0.18288)
		(layer "In2.Cu")
		(net "M_E_CPU0_SA_DQS_DP<6>")
	)
	(segment
		(start 393.236704 -276.500844)
		(end 389.57885 -272.84299)
		(width 0.18288)
		(layer "In2.Cu")
		(net "M_E_CPU0_SA_DQS_DP<6>")
	)
	(segment
		(start 384.119374 -272.200624)
		(end 383.869692 -272.200624)
		(width 0.088646)
		(layer "In2.Cu")
		(net "M_E_CPU0_SA_DQS_DP<6>")
	)
	(segment
		(start 404.701248 -301.381668)
		(end 404.086568 -299.897546)
		(width 0.18288)
		(layer "In2.Cu")
		(net "M_E_CPU0_SA_DQS_DP<6>")
	)
	(segment
		(start 387.46557 -272.200624)
		(end 386.944616 -272.200624)
		(width 0.088646)
		(layer "In2.Cu")
		(net "M_E_CPU0_SA_DQS_DP<6>")
	)
	(segment
		(start 409.45054 -302.138842)
		(end 408.805888 -302.138842)
		(width 0.18288)
		(layer "In2.Cu")
		(net "M_E_CPU0_SA_DQS_DP<6>")
	)
	(segment
		(start 386.206746 -272.140934)
		(end 386.192014 -272.14957)
		(width 0.088646)
		(layer "In2.Cu")
		(net "M_E_CPU0_SA_DQS_DP<6>")
	)
	(segment
		(start 399.047462 -287.575244)
		(end 398.266412 -285.689294)
		(width 0.18288)
		(layer "In2.Cu")
		(net "M_E_CPU0_SA_DQS_DP<6>")
	)
	(segment
		(start 404.086568 -296.126662)
		(end 403.836378 -295.522396)
		(width 0.18288)
		(layer "In2.Cu")
		(net "M_E_CPU0_SA_DQS_DP<6>")
	)
	(segment
		(start 398.266412 -283.223208)
		(end 394.433552 -279.390094)
		(width 0.18288)
		(layer "In2.Cu")
		(net "M_E_CPU0_SA_DQS_DP<6>")
	)
	(segment
		(start 401.60321 -290.130738)
		(end 399.047462 -287.575244)
		(width 0.18288)
		(layer "In2.Cu")
		(net "M_E_CPU0_SA_DQS_DP<6>")
	)
	(segment
		(start 389.57885 -272.84299)
		(end 388.840726 -272.84299)
		(width 0.18288)
		(layer "In2.Cu")
		(net "M_E_CPU0_SA_DQS_DP<6>")
	)
	(segment
		(start 398.266412 -285.689294)
		(end 398.266412 -283.223208)
		(width 0.18288)
		(layer "In2.Cu")
		(net "M_E_CPU0_SA_DQS_DP<6>")
	)
	(segment
		(start 406.90927 -301.687992)
		(end 406.142444 -301.687992)
		(width 0.18288)
		(layer "In2.Cu")
		(net "M_E_CPU0_SA_DQS_DP<6>")
	)
	(segment
		(start 383.719832 -272.230342)
		(end 383.661158 -272.242026)
		(width 0.088646)
		(layer "In2.Cu")
		(net "M_E_CPU0_SA_DQS_DP<6>")
	)
	(segment
		(start 384.308858 -272.15211)
		(end 384.299968 -272.157444)
		(width 0.088646)
		(layer "In2.Cu")
		(net "M_E_CPU0_SA_DQS_DP<6>")
	)
	(segment
		(start 384.327146 -272.140934)
		(end 384.312414 -272.14957)
		(width 0.088646)
		(layer "In2.Cu")
		(net "M_E_CPU0_SA_DQS_DP<6>")
	)
	(segment
		(start 404.975822 -301.656496)
		(end 404.701248 -301.381668)
		(width 0.18288)
		(layer "In2.Cu")
		(net "M_E_CPU0_SA_DQS_DP<6>")
	)
	(segment
		(start 407.873454 -302.233584)
		(end 407.623264 -301.983394)
		(width 0.18288)
		(layer "In2.Cu")
		(net "M_E_CPU0_SA_DQS_DP<6>")
	)
	(segment
		(start 405.366982 -301.445168)
		(end 405.155654 -301.656496)
		(width 0.18288)
		(layer "In2.Cu")
		(net "M_E_CPU0_SA_DQS_DP<6>")
	)
	(segment
		(start 405.89962 -301.445168)
		(end 405.366982 -301.445168)
		(width 0.18288)
		(layer "In2.Cu")
		(net "M_E_CPU0_SA_DQS_DP<6>")
	)
	(segment
		(start 403.836124 -295.521888)
		(end 401.60321 -290.130738)
		(width 0.18288)
		(layer "In2.Cu")
		(net "M_E_CPU0_SA_DQS_DP<6>")
	)
	(segment
		(start 383.467864 -272.314924)
		(end 383.458974 -272.320004)
		(width 0.088646)
		(layer "In2.Cu")
		(net "M_E_CPU0_SA_DQS_DP<6>")
	)
	(segment
		(start 394.433552 -279.390094)
		(end 393.236704 -276.500844)
		(width 0.18288)
		(layer "In2.Cu")
		(net "M_E_CPU0_SA_DQS_DP<6>")
	)
	(segment
		(start 388.16788 -272.902934)
		(end 387.46557 -272.200624)
		(width 0.088646)
		(layer "In2.Cu")
		(net "M_E_CPU0_SA_DQS_DP<6>")
	)
	(segment
		(start 388.840726 -272.84299)
		(end 388.780782 -272.902934)
		(width 0.088646)
		(layer "In2.Cu")
		(net "M_E_CPU0_SA_DQS_DP<6>")
	)
	(segment
		(start 384.311652 -272.150586)
		(end 384.310636 -272.151094)
		(width 0.088646)
		(layer "In2.Cu")
		(net "M_E_CPU0_SA_DQS_DP<6>")
	)
	(segment
		(start 407.623264 -301.983394)
		(end 406.90927 -301.687992)
		(width 0.18288)
		(layer "In2.Cu")
		(net "M_E_CPU0_SA_DQS_DP<6>")
	)
	(segment
		(start 384.312414 -272.14957)
		(end 384.311652 -272.150586)
		(width 0.088646)
		(layer "In2.Cu")
		(net "M_E_CPU0_SA_DQS_DP<6>")
	)
	(segment
		(start 404.086568 -299.897546)
		(end 404.086568 -296.126662)
		(width 0.18288)
		(layer "In2.Cu")
		(net "M_E_CPU0_SA_DQS_DP<6>")
	)
	(segment
		(start 409.723082 -301.866554)
		(end 409.45054 -302.138842)
		(width 0.18288)
		(layer "In2.Cu")
		(net "M_E_CPU0_SA_DQS_DP<6>")
	)
	(segment
		(start 405.155654 -301.656496)
		(end 404.975822 -301.656496)
		(width 0.18288)
		(layer "In2.Cu")
		(net "M_E_CPU0_SA_DQS_DP<6>")
	)
	(segment
		(start 408.420316 -302.298608)
		(end 408.030172 -302.298608)
		(width 0.18288)
		(layer "In2.Cu")
		(net "M_E_CPU0_SA_DQS_DP<6>")
	)
	(segment
		(start 383.869692 -272.200624)
		(end 383.719832 -272.230342)
		(width 0.088646)
		(layer "In2.Cu")
		(net "M_E_CPU0_SA_DQS_DP<6>")
	)
	(arc
		(start 386.757418 -272.14957)
		(mid 386.483189 -272.073645)
		(end 386.206746 -272.140934)
		(width 0.088646)
		(layer "In2.Cu")
		(net "M_E_CPU0_SA_DQS_DP<6>")
	)
	(arc
		(start 386.192014 -272.14957)
		(mid 386.004816 -272.199713)
		(end 385.817618 -272.14957)
		(width 0.088646)
		(layer "In2.Cu")
		(net "M_E_CPU0_SA_DQS_DP<6>")
	)
	(arc
		(start 385.252214 -272.14957)
		(mid 385.065016 -272.199713)
		(end 384.877818 -272.14957)
		(width 0.088646)
		(layer "In2.Cu")
		(net "M_E_CPU0_SA_DQS_DP<6>")
	)
	(arc
		(start 384.877818 -272.14957)
		(mid 384.603589 -272.073645)
		(end 384.327146 -272.140934)
		(width 0.088646)
		(layer "In2.Cu")
		(net "M_E_CPU0_SA_DQS_DP<6>")
	)
	(arc
		(start 383.568194 -272.266918)
		(mid 383.543489 -272.279785)
		(end 383.517902 -272.290794)
		(width 0.088646)
		(layer "In2.Cu")
		(net "M_E_CPU0_SA_DQS_DP<6>")
	)
	(arc
		(start 385.817618 -272.14957)
		(mid 385.543389 -272.073645)
		(end 385.266946 -272.140934)
		(width 0.088646)
		(layer "In2.Cu")
		(net "M_E_CPU0_SA_DQS_DP<6>")
	)
	(arc
		(start 384.299968 -272.157444)
		(mid 384.212379 -272.190341)
		(end 384.119374 -272.200624)
		(width 0.088646)
		(layer "In2.Cu")
		(net "M_E_CPU0_SA_DQS_DP<6>")
	)
	(arc
		(start 383.517902 -272.290794)
		(mid 383.492433 -272.301927)
		(end 383.467864 -272.314924)
		(width 0.088646)
		(layer "In2.Cu")
		(net "M_E_CPU0_SA_DQS_DP<6>")
	)
	(arc
		(start 383.661158 -272.242026)
		(mid 383.613044 -272.248382)
		(end 383.568194 -272.266918)
		(width 0.088646)
		(layer "In2.Cu")
		(net "M_E_CPU0_SA_DQS_DP<6>")
	)
	(arc
		(start 383.458974 -272.320004)
		(mid 383.343165 -272.431933)
		(end 383.284984 -272.582132)
		(width 0.088646)
		(layer "In2.Cu")
		(net "M_E_CPU0_SA_DQS_DP<6>")
	)
	(arc
		(start 386.944616 -272.200624)
		(mid 386.847666 -272.187395)
		(end 386.757418 -272.14957)
		(width 0.088646)
		(layer "In2.Cu")
		(net "M_E_CPU0_SA_DQS_DP<6>")
	)
	(segment
		(start 390.048496 -295.888156)
		(end 390.13257 -295.972484)
		(width 0.1524)
		(layer "F.Cu")
		(net "M_E_CPU0_SA_DQS_DP<5>")
	)
	(segment
		(start 389.850884 -295.344596)
		(end 390.048496 -295.888156)
		(width 0.1524)
		(layer "F.Cu")
		(net "M_E_CPU0_SA_DQS_DP<5>")
	)
	(segment
		(start 390.607296 -296.395394)
		(end 393.205716 -299.55871)
		(width 0.20066)
		(layer "F.Cu")
		(net "M_E_CPU0_SA_DQS_DP<5>")
	)
	(segment
		(start 394.754608 -300.92904)
		(end 395.181074 -301.35449)
		(width 0.20066)
		(layer "F.Cu")
		(net "M_E_CPU0_SA_DQS_DP<5>")
	)
	(segment
		(start 397.663924 -304.009044)
		(end 397.839946 -304.00879)
		(width 0.20066)
		(layer "F.Cu")
		(net "M_E_CPU0_SA_DQS_DP<5>")
	)
	(segment
		(start 387.096254 -276.001226)
		(end 387.663436 -276.304502)
		(width 0.088646)
		(layer "F.Cu")
		(net "M_E_CPU0_SA_DQS_DP<5>")
	)
	(segment
		(start 397.237966 -303.583848)
		(end 397.663924 -304.009044)
		(width 0.20066)
		(layer "F.Cu")
		(net "M_E_CPU0_SA_DQS_DP<5>")
	)
	(segment
		(start 408.365706 -311.088532)
		(end 408.562302 -311.088532)
		(width 0.20066)
		(layer "F.Cu")
		(net "M_E_CPU0_SA_DQS_DP<5>")
	)
	(segment
		(start 387.893814 -276.53488)
		(end 387.939534 -276.53488)
		(width 0.088646)
		(layer "F.Cu")
		(net "M_E_CPU0_SA_DQS_DP<5>")
	)
	(segment
		(start 413.275526 -310.786526)
		(end 412.781496 -310.786526)
		(width 0.20066)
		(layer "F.Cu")
		(net "M_E_CPU0_SA_DQS_DP<5>")
	)
	(segment
		(start 416.294062 -311.039256)
		(end 416.04692 -311.039256)
		(width 0.20066)
		(layer "F.Cu")
		(net "M_E_CPU0_SA_DQS_DP<5>")
	)
	(segment
		(start 385.534662 -275.35886)
		(end 385.997196 -275.601176)
		(width 0.088646)
		(layer "F.Cu")
		(net "M_E_CPU0_SA_DQS_DP<5>")
	)
	(segment
		(start 403.490938 -309.785766)
		(end 404.524972 -310.63311)
		(width 0.20066)
		(layer "F.Cu")
		(net "M_E_CPU0_SA_DQS_DP<5>")
	)
	(segment
		(start 416.903916 -311.380378)
		(end 416.752786 -311.229248)
		(width 0.20066)
		(layer "F.Cu")
		(net "M_E_CPU0_SA_DQS_DP<5>")
	)
	(segment
		(start 396.20952 -302.55718)
		(end 396.635478 -302.982376)
		(width 0.20066)
		(layer "F.Cu")
		(net "M_E_CPU0_SA_DQS_DP<5>")
	)
	(segment
		(start 410.334714 -311.216802)
		(end 410.853382 -311.216802)
		(width 0.20066)
		(layer "F.Cu")
		(net "M_E_CPU0_SA_DQS_DP<5>")
	)
	(segment
		(start 396.8115 -302.982376)
		(end 397.237966 -303.407826)
		(width 0.20066)
		(layer "F.Cu")
		(net "M_E_CPU0_SA_DQS_DP<5>")
	)
	(segment
		(start 389.180324 -291.250624)
		(end 389.213598 -291.562536)
		(width 0.1524)
		(layer "F.Cu")
		(net "M_E_CPU0_SA_DQS_DP<5>")
	)
	(segment
		(start 404.524972 -310.63311)
		(end 405.074628 -311.040272)
		(width 0.20066)
		(layer "F.Cu")
		(net "M_E_CPU0_SA_DQS_DP<5>")
	)
	(segment
		(start 408.063446 -310.786272)
		(end 408.365706 -311.088532)
		(width 0.20066)
		(layer "F.Cu")
		(net "M_E_CPU0_SA_DQS_DP<5>")
	)
	(segment
		(start 413.3215 -310.79186)
		(end 413.310578 -310.780938)
		(width 0.1016)
		(layer "F.Cu")
		(net "M_E_CPU0_SA_DQS_DP<5>")
	)
	(segment
		(start 389.213598 -291.562536)
		(end 389.850884 -295.344596)
		(width 0.1524)
		(layer "F.Cu")
		(net "M_E_CPU0_SA_DQS_DP<5>")
	)
	(segment
		(start 407.754328 -310.791606)
		(end 407.759662 -310.786272)
		(width 0.1016)
		(layer "F.Cu")
		(net "M_E_CPU0_SA_DQS_DP<5>")
	)
	(segment
		(start 416.04692 -311.039256)
		(end 415.79292 -310.785256)
		(width 0.20066)
		(layer "F.Cu")
		(net "M_E_CPU0_SA_DQS_DP<5>")
	)
	(segment
		(start 408.562302 -311.088532)
		(end 409.925012 -311.502298)
		(width 0.20066)
		(layer "F.Cu")
		(net "M_E_CPU0_SA_DQS_DP<5>")
	)
	(segment
		(start 398.266158 -304.434494)
		(end 398.266412 -304.610516)
		(width 0.20066)
		(layer "F.Cu")
		(net "M_E_CPU0_SA_DQS_DP<5>")
	)
	(segment
		(start 386.705348 -275.839174)
		(end 386.705094 -275.83892)
		(width 0.088646)
		(layer "F.Cu")
		(net "M_E_CPU0_SA_DQS_DP<5>")
	)
	(segment
		(start 393.205716 -299.55871)
		(end 393.55014 -299.902626)
		(width 0.20066)
		(layer "F.Cu")
		(net "M_E_CPU0_SA_DQS_DP<5>")
	)
	(segment
		(start 397.237966 -303.407826)
		(end 397.237966 -303.583848)
		(width 0.20066)
		(layer "F.Cu")
		(net "M_E_CPU0_SA_DQS_DP<5>")
	)
	(segment
		(start 407.763726 -310.786272)
		(end 408.063446 -310.786272)
		(width 0.20066)
		(layer "F.Cu")
		(net "M_E_CPU0_SA_DQS_DP<5>")
	)
	(segment
		(start 405.465026 -310.786526)
		(end 405.731726 -310.786526)
		(width 0.20066)
		(layer "F.Cu")
		(net "M_E_CPU0_SA_DQS_DP<5>")
	)
	(segment
		(start 387.663436 -276.304502)
		(end 387.893814 -276.53488)
		(width 0.088646)
		(layer "F.Cu")
		(net "M_E_CPU0_SA_DQS_DP<5>")
	)
	(segment
		(start 407.759662 -310.786272)
		(end 407.763726 -310.786272)
		(width 0.1016)
		(layer "F.Cu")
		(net "M_E_CPU0_SA_DQS_DP<5>")
	)
	(segment
		(start 393.55014 -299.902626)
		(end 393.726162 -299.902626)
		(width 0.20066)
		(layer "F.Cu")
		(net "M_E_CPU0_SA_DQS_DP<5>")
	)
	(segment
		(start 395.181074 -301.35449)
		(end 395.181074 -301.530512)
		(width 0.20066)
		(layer "F.Cu")
		(net "M_E_CPU0_SA_DQS_DP<5>")
	)
	(segment
		(start 386.702808 -275.837904)
		(end 386.702808 -275.838158)
		(width 0.088646)
		(layer "F.Cu")
		(net "M_E_CPU0_SA_DQS_DP<5>")
	)
	(segment
		(start 386.17652 -275.639784)
		(end 386.702808 -275.837904)
		(width 0.088646)
		(layer "F.Cu")
		(net "M_E_CPU0_SA_DQS_DP<5>")
	)
	(segment
		(start 403.061678 -309.3974)
		(end 403.490938 -309.785766)
		(width 0.20066)
		(layer "F.Cu")
		(net "M_E_CPU0_SA_DQS_DP<5>")
	)
	(segment
		(start 418.397182 -311.216802)
		(end 417.898072 -311.216802)
		(width 0.20066)
		(layer "F.Cu")
		(net "M_E_CPU0_SA_DQS_DP<5>")
	)
	(segment
		(start 416.752786 -311.229248)
		(end 416.294062 -311.039256)
		(width 0.20066)
		(layer "F.Cu")
		(net "M_E_CPU0_SA_DQS_DP<5>")
	)
	(segment
		(start 405.741886 -310.791606)
		(end 407.065988 -310.791606)
		(width 0.1016)
		(layer "F.Cu")
		(net "M_E_CPU0_SA_DQS_DP<5>")
	)
	(segment
		(start 394.152628 -300.504098)
		(end 394.578586 -300.929294)
		(width 0.20066)
		(layer "F.Cu")
		(net "M_E_CPU0_SA_DQS_DP<5>")
	)
	(segment
		(start 405.736806 -310.786526)
		(end 405.741886 -310.791606)
		(width 0.1016)
		(layer "F.Cu")
		(net "M_E_CPU0_SA_DQS_DP<5>")
	)
	(segment
		(start 417.15563 -311.484772)
		(end 416.903916 -311.380378)
		(width 0.20066)
		(layer "F.Cu")
		(net "M_E_CPU0_SA_DQS_DP<5>")
	)
	(segment
		(start 415.300922 -310.79186)
		(end 413.3215 -310.79186)
		(width 0.1016)
		(layer "F.Cu")
		(net "M_E_CPU0_SA_DQS_DP<5>")
	)
	(segment
		(start 386.705094 -275.83892)
		(end 386.709158 -275.840698)
		(width 0.088646)
		(layer "F.Cu")
		(net "M_E_CPU0_SA_DQS_DP<5>")
	)
	(segment
		(start 398.266412 -304.610516)
		(end 403.061678 -309.3974)
		(width 0.20066)
		(layer "F.Cu")
		(net "M_E_CPU0_SA_DQS_DP<5>")
	)
	(segment
		(start 386.709158 -275.840698)
		(end 387.096254 -276.001226)
		(width 0.088646)
		(layer "F.Cu")
		(net "M_E_CPU0_SA_DQS_DP<5>")
	)
	(segment
		(start 390.184386 -295.972484)
		(end 390.211564 -295.999662)
		(width 0.1524)
		(layer "F.Cu")
		(net "M_E_CPU0_SA_DQS_DP<5>")
	)
	(segment
		(start 394.152628 -300.328076)
		(end 394.152628 -300.504098)
		(width 0.20066)
		(layer "F.Cu")
		(net "M_E_CPU0_SA_DQS_DP<5>")
	)
	(segment
		(start 396.635478 -302.982376)
		(end 396.8115 -302.982376)
		(width 0.20066)
		(layer "F.Cu")
		(net "M_E_CPU0_SA_DQS_DP<5>")
	)
	(segment
		(start 389.180324 -280.561034)
		(end 389.180324 -291.250624)
		(width 0.1524)
		(layer "F.Cu")
		(net "M_E_CPU0_SA_DQS_DP<5>")
	)
	(segment
		(start 386.702808 -275.838158)
		(end 386.705348 -275.839174)
		(width 0.088646)
		(layer "F.Cu")
		(net "M_E_CPU0_SA_DQS_DP<5>")
	)
	(segment
		(start 409.925012 -311.502298)
		(end 410.049218 -311.502298)
		(width 0.20066)
		(layer "F.Cu")
		(net "M_E_CPU0_SA_DQS_DP<5>")
	)
	(segment
		(start 413.29991 -310.786526)
		(end 413.275526 -310.786526)
		(width 0.101854)
		(layer "F.Cu")
		(net "M_E_CPU0_SA_DQS_DP<5>")
	)
	(segment
		(start 387.955028 -276.550374)
		(end 388.483348 -277.078694)
		(width 0.1524)
		(layer "F.Cu")
		(net "M_E_CPU0_SA_DQS_DP<5>")
	)
	(segment
		(start 396.20952 -302.381158)
		(end 396.20952 -302.55718)
		(width 0.20066)
		(layer "F.Cu")
		(net "M_E_CPU0_SA_DQS_DP<5>")
	)
	(segment
		(start 410.049218 -311.502298)
		(end 410.334714 -311.216802)
		(width 0.20066)
		(layer "F.Cu")
		(net "M_E_CPU0_SA_DQS_DP<5>")
	)
	(segment
		(start 413.305498 -310.780938)
		(end 413.29991 -310.786526)
		(width 0.101854)
		(layer "F.Cu")
		(net "M_E_CPU0_SA_DQS_DP<5>")
	)
	(segment
		(start 412.209488 -311.01665)
		(end 411.758384 -311.467754)
		(width 0.20066)
		(layer "F.Cu")
		(net "M_E_CPU0_SA_DQS_DP<5>")
	)
	(segment
		(start 412.551372 -311.01665)
		(end 412.209488 -311.01665)
		(width 0.20066)
		(layer "F.Cu")
		(net "M_E_CPU0_SA_DQS_DP<5>")
	)
	(segment
		(start 387.939534 -276.53488)
		(end 387.955028 -276.550374)
		(width 0.088646)
		(layer "F.Cu")
		(net "M_E_CPU0_SA_DQS_DP<5>")
	)
	(segment
		(start 411.622748 -311.467754)
		(end 411.371796 -311.216802)
		(width 0.20066)
		(layer "F.Cu")
		(net "M_E_CPU0_SA_DQS_DP<5>")
	)
	(segment
		(start 397.839946 -304.00879)
		(end 398.266158 -304.434494)
		(width 0.20066)
		(layer "F.Cu")
		(net "M_E_CPU0_SA_DQS_DP<5>")
	)
	(segment
		(start 395.181074 -301.530512)
		(end 395.607032 -301.955708)
		(width 0.20066)
		(layer "F.Cu")
		(net "M_E_CPU0_SA_DQS_DP<5>")
	)
	(segment
		(start 407.065988 -310.791606)
		(end 407.466038 -310.791606)
		(width 0.101854)
		(layer "F.Cu")
		(net "M_E_CPU0_SA_DQS_DP<5>")
	)
	(segment
		(start 411.758384 -311.467754)
		(end 411.622748 -311.467754)
		(width 0.20066)
		(layer "F.Cu")
		(net "M_E_CPU0_SA_DQS_DP<5>")
	)
	(segment
		(start 390.13257 -295.972484)
		(end 390.184386 -295.972484)
		(width 0.1524)
		(layer "F.Cu")
		(net "M_E_CPU0_SA_DQS_DP<5>")
	)
	(segment
		(start 405.074628 -311.040272)
		(end 405.21128 -311.040272)
		(width 0.20066)
		(layer "F.Cu")
		(net "M_E_CPU0_SA_DQS_DP<5>")
	)
	(segment
		(start 411.371796 -311.216802)
		(end 410.853382 -311.216802)
		(width 0.20066)
		(layer "F.Cu")
		(net "M_E_CPU0_SA_DQS_DP<5>")
	)
	(segment
		(start 417.630102 -311.484772)
		(end 417.15563 -311.484772)
		(width 0.20066)
		(layer "F.Cu")
		(net "M_E_CPU0_SA_DQS_DP<5>")
	)
	(segment
		(start 395.607032 -301.955708)
		(end 395.783054 -301.955708)
		(width 0.20066)
		(layer "F.Cu")
		(net "M_E_CPU0_SA_DQS_DP<5>")
	)
	(segment
		(start 417.898072 -311.216802)
		(end 417.630102 -311.484772)
		(width 0.20066)
		(layer "F.Cu")
		(net "M_E_CPU0_SA_DQS_DP<5>")
	)
	(segment
		(start 413.310578 -310.780938)
		(end 413.305498 -310.780938)
		(width 0.1016)
		(layer "F.Cu")
		(net "M_E_CPU0_SA_DQS_DP<5>")
	)
	(segment
		(start 394.578586 -300.929294)
		(end 394.754608 -300.92904)
		(width 0.20066)
		(layer "F.Cu")
		(net "M_E_CPU0_SA_DQS_DP<5>")
	)
	(segment
		(start 405.731726 -310.786526)
		(end 405.736806 -310.786526)
		(width 0.101854)
		(layer "F.Cu")
		(net "M_E_CPU0_SA_DQS_DP<5>")
	)
	(segment
		(start 405.21128 -311.040272)
		(end 405.465026 -310.786526)
		(width 0.20066)
		(layer "F.Cu")
		(net "M_E_CPU0_SA_DQS_DP<5>")
	)
	(segment
		(start 388.483348 -277.078694)
		(end 389.180324 -280.561034)
		(width 0.1524)
		(layer "F.Cu")
		(net "M_E_CPU0_SA_DQS_DP<5>")
	)
	(segment
		(start 393.726162 -299.902626)
		(end 394.152628 -300.328076)
		(width 0.20066)
		(layer "F.Cu")
		(net "M_E_CPU0_SA_DQS_DP<5>")
	)
	(segment
		(start 412.781496 -310.786526)
		(end 412.551372 -311.01665)
		(width 0.20066)
		(layer "F.Cu")
		(net "M_E_CPU0_SA_DQS_DP<5>")
	)
	(segment
		(start 385.997196 -275.601176)
		(end 386.02539 -275.608796)
		(width 0.088646)
		(layer "F.Cu")
		(net "M_E_CPU0_SA_DQS_DP<5>")
	)
	(segment
		(start 407.466038 -310.791606)
		(end 407.754328 -310.791606)
		(width 0.1016)
		(layer "F.Cu")
		(net "M_E_CPU0_SA_DQS_DP<5>")
	)
	(segment
		(start 390.211564 -295.999662)
		(end 390.607296 -296.395394)
		(width 0.20066)
		(layer "F.Cu")
		(net "M_E_CPU0_SA_DQS_DP<5>")
	)
	(segment
		(start 415.79292 -310.785256)
		(end 415.307526 -310.785256)
		(width 0.20066)
		(layer "F.Cu")
		(net "M_E_CPU0_SA_DQS_DP<5>")
	)
	(segment
		(start 395.783054 -301.955708)
		(end 396.20952 -302.381158)
		(width 0.20066)
		(layer "F.Cu")
		(net "M_E_CPU0_SA_DQS_DP<5>")
	)
	(segment
		(start 415.307526 -310.785256)
		(end 415.300922 -310.79186)
		(width 0.1016)
		(layer "F.Cu")
		(net "M_E_CPU0_SA_DQS_DP<5>")
	)
	(arc
		(start 386.02539 -275.608796)
		(mid 386.102176 -275.61834)
		(end 386.17652 -275.639784)
		(width 0.088646)
		(layer "F.Cu")
		(net "M_E_CPU0_SA_DQS_DP<5>")
	)
	(segment
		(start 407.583132 -275.276056)
		(end 407.342594 -275.516594)
		(width 0.20066)
		(layer "F.Cu")
		(net "M_E_CPU0_SA_DQS_DP<4>")
	)
	(segment
		(start 385.069334 -260.282436)
		(end 385.2799 -260.282436)
		(width 0.088646)
		(layer "F.Cu")
		(net "M_E_CPU0_SA_DQS_DP<4>")
	)
	(segment
		(start 404.986998 -275.516594)
		(end 406.753314 -275.516594)
		(width 0.20066)
		(layer "F.Cu")
		(net "M_E_CPU0_SA_DQS_DP<4>")
	)
	(segment
		(start 388.933436 -261.80796)
		(end 388.933436 -261.853172)
		(width 0.088646)
		(layer "F.Cu")
		(net "M_E_CPU0_SA_DQS_DP<4>")
	)
	(segment
		(start 399.166588 -274.440396)
		(end 399.265902 -274.794726)
		(width 0.1524)
		(layer "F.Cu")
		(net "M_E_CPU0_SA_DQS_DP<4>")
	)
	(segment
		(start 400.221196 -275.105114)
		(end 400.258026 -275.141944)
		(width 0.1524)
		(layer "F.Cu")
		(net "M_E_CPU0_SA_DQS_DP<4>")
	)
	(segment
		(start 408.08783 -275.276056)
		(end 407.583132 -275.276056)
		(width 0.20066)
		(layer "F.Cu")
		(net "M_E_CPU0_SA_DQS_DP<4>")
	)
	(segment
		(start 412.172658 -275.962364)
		(end 412.017464 -275.962364)
		(width 0.20066)
		(layer "F.Cu")
		(net "M_E_CPU0_SA_DQS_DP<4>")
	)
	(segment
		(start 404.328884 -275.141944)
		(end 404.502874 -275.315934)
		(width 0.20066)
		(layer "F.Cu")
		(net "M_E_CPU0_SA_DQS_DP<4>")
	)
	(segment
		(start 409.473908 -275.952966)
		(end 409.231846 -275.952966)
		(width 0.20066)
		(layer "F.Cu")
		(net "M_E_CPU0_SA_DQS_DP<4>")
	)
	(segment
		(start 413.73425 -275.516594)
		(end 413.459676 -275.24202)
		(width 0.20066)
		(layer "F.Cu")
		(net "M_E_CPU0_SA_DQS_DP<4>")
	)
	(segment
		(start 412.860236 -275.645372)
		(end 412.48965 -275.645372)
		(width 0.20066)
		(layer "F.Cu")
		(net "M_E_CPU0_SA_DQS_DP<4>")
	)
	(segment
		(start 384.124962 -259.894832)
		(end 384.982974 -260.264656)
		(width 0.088646)
		(layer "F.Cu")
		(net "M_E_CPU0_SA_DQS_DP<4>")
	)
	(segment
		(start 413.263588 -275.24202)
		(end 412.860236 -275.645372)
		(width 0.20066)
		(layer "F.Cu")
		(net "M_E_CPU0_SA_DQS_DP<4>")
	)
	(segment
		(start 411.99689 -275.94179)
		(end 411.804612 -275.94179)
		(width 0.101854)
		(layer "F.Cu")
		(net "M_E_CPU0_SA_DQS_DP<4>")
	)
	(segment
		(start 400.258026 -275.141944)
		(end 400.296126 -275.141944)
		(width 0.1524)
		(layer "F.Cu")
		(net "M_E_CPU0_SA_DQS_DP<4>")
	)
	(segment
		(start 399.57629 -275.105114)
		(end 400.221196 -275.105114)
		(width 0.1524)
		(layer "F.Cu")
		(net "M_E_CPU0_SA_DQS_DP<4>")
	)
	(segment
		(start 385.72186 -260.384544)
		(end 385.732274 -260.39064)
		(width 0.088646)
		(layer "F.Cu")
		(net "M_E_CPU0_SA_DQS_DP<4>")
	)
	(segment
		(start 404.803102 -275.440394)
		(end 404.986998 -275.516594)
		(width 0.20066)
		(layer "F.Cu")
		(net "M_E_CPU0_SA_DQS_DP<4>")
	)
	(segment
		(start 413.459676 -275.24202)
		(end 413.263588 -275.24202)
		(width 0.20066)
		(layer "F.Cu")
		(net "M_E_CPU0_SA_DQS_DP<4>")
	)
	(segment
		(start 388.933436 -261.853172)
		(end 398.577562 -271.497298)
		(width 0.1524)
		(layer "F.Cu")
		(net "M_E_CPU0_SA_DQS_DP<4>")
	)
	(segment
		(start 412.48965 -275.645372)
		(end 412.172658 -275.962364)
		(width 0.20066)
		(layer "F.Cu")
		(net "M_E_CPU0_SA_DQS_DP<4>")
	)
	(segment
		(start 385.579366 -260.301994)
		(end 385.722876 -260.384798)
		(width 0.088646)
		(layer "F.Cu")
		(net "M_E_CPU0_SA_DQS_DP<4>")
	)
	(segment
		(start 385.722876 -260.384798)
		(end 385.72186 -260.384544)
		(width 0.088646)
		(layer "F.Cu")
		(net "M_E_CPU0_SA_DQS_DP<4>")
	)
	(segment
		(start 398.577562 -271.497298)
		(end 399.166588 -274.440396)
		(width 0.1524)
		(layer "F.Cu")
		(net "M_E_CPU0_SA_DQS_DP<4>")
	)
	(segment
		(start 411.804612 -275.94179)
		(end 409.847796 -275.94179)
		(width 0.1016)
		(layer "F.Cu")
		(net "M_E_CPU0_SA_DQS_DP<4>")
	)
	(segment
		(start 408.48407 -275.672296)
		(end 408.08783 -275.276056)
		(width 0.20066)
		(layer "F.Cu")
		(net "M_E_CPU0_SA_DQS_DP<4>")
	)
	(segment
		(start 404.502874 -275.315934)
		(end 404.803102 -275.440394)
		(width 0.20066)
		(layer "F.Cu")
		(net "M_E_CPU0_SA_DQS_DP<4>")
	)
	(segment
		(start 400.296126 -275.141944)
		(end 404.328884 -275.141944)
		(width 0.20066)
		(layer "F.Cu")
		(net "M_E_CPU0_SA_DQS_DP<4>")
	)
	(segment
		(start 412.017464 -275.962364)
		(end 411.99689 -275.94179)
		(width 0.101854)
		(layer "F.Cu")
		(net "M_E_CPU0_SA_DQS_DP<4>")
	)
	(segment
		(start 414.297114 -275.516594)
		(end 413.73425 -275.516594)
		(width 0.20066)
		(layer "F.Cu")
		(net "M_E_CPU0_SA_DQS_DP<4>")
	)
	(segment
		(start 387.7183 -260.593078)
		(end 388.933436 -261.80796)
		(width 0.088646)
		(layer "F.Cu")
		(net "M_E_CPU0_SA_DQS_DP<4>")
	)
	(segment
		(start 408.951176 -275.672296)
		(end 408.48407 -275.672296)
		(width 0.20066)
		(layer "F.Cu")
		(net "M_E_CPU0_SA_DQS_DP<4>")
	)
	(segment
		(start 399.265902 -274.794726)
		(end 399.57629 -275.105114)
		(width 0.1524)
		(layer "F.Cu")
		(net "M_E_CPU0_SA_DQS_DP<4>")
	)
	(segment
		(start 409.231846 -275.952966)
		(end 408.951176 -275.672296)
		(width 0.20066)
		(layer "F.Cu")
		(net "M_E_CPU0_SA_DQS_DP<4>")
	)
	(segment
		(start 386.930138 -260.459982)
		(end 387.648196 -260.558534)
		(width 0.088646)
		(layer "F.Cu")
		(net "M_E_CPU0_SA_DQS_DP<4>")
	)
	(segment
		(start 407.342594 -275.516594)
		(end 406.753314 -275.516594)
		(width 0.20066)
		(layer "F.Cu")
		(net "M_E_CPU0_SA_DQS_DP<4>")
	)
	(segment
		(start 387.648196 -260.558534)
		(end 387.7183 -260.593078)
		(width 0.088646)
		(layer "F.Cu")
		(net "M_E_CPU0_SA_DQS_DP<4>")
	)
	(segment
		(start 409.847796 -275.94179)
		(end 409.485084 -275.94179)
		(width 0.101854)
		(layer "F.Cu")
		(net "M_E_CPU0_SA_DQS_DP<4>")
	)
	(segment
		(start 409.485084 -275.94179)
		(end 409.473908 -275.952966)
		(width 0.101854)
		(layer "F.Cu")
		(net "M_E_CPU0_SA_DQS_DP<4>")
	)
	(arc
		(start 384.982974 -260.264656)
		(mid 385.025248 -260.277937)
		(end 385.069334 -260.282436)
		(width 0.088646)
		(layer "F.Cu")
		(net "M_E_CPU0_SA_DQS_DP<4>")
	)
	(arc
		(start 385.377436 -260.27126)
		(mid 385.481299 -260.267558)
		(end 385.579366 -260.301994)
		(width 0.088646)
		(layer "F.Cu")
		(net "M_E_CPU0_SA_DQS_DP<4>")
	)
	(arc
		(start 386.661914 -260.384544)
		(mid 386.791306 -260.439046)
		(end 386.930138 -260.459982)
		(width 0.088646)
		(layer "F.Cu")
		(net "M_E_CPU0_SA_DQS_DP<4>")
	)
	(arc
		(start 385.732274 -260.39064)
		(mid 386.010706 -260.460454)
		(end 386.287518 -260.384544)
		(width 0.088646)
		(layer "F.Cu")
		(net "M_E_CPU0_SA_DQS_DP<4>")
	)
	(arc
		(start 386.287518 -260.384544)
		(mid 386.474716 -260.334401)
		(end 386.661914 -260.384544)
		(width 0.088646)
		(layer "F.Cu")
		(net "M_E_CPU0_SA_DQS_DP<4>")
	)
	(arc
		(start 385.2799 -260.282436)
		(mid 385.328982 -260.279582)
		(end 385.377436 -260.27126)
		(width 0.088646)
		(layer "F.Cu")
		(net "M_E_CPU0_SA_DQS_DP<4>")
	)
	(segment
		(start 409.848304 -285.291784)
		(end 409.83662 -285.303468)
		(width 0.1016)
		(layer "F.Cu")
		(net "M_E_CPU0_SA_DQS_DP<3>")
	)
	(segment
		(start 403.90318 -285.151576)
		(end 404.0759 -285.185866)
		(width 0.20066)
		(layer "F.Cu")
		(net "M_E_CPU0_SA_DQS_DP<3>")
	)
	(segment
		(start 398.482312 -283.518356)
		(end 398.482312 -283.6926)
		(width 0.20066)
		(layer "F.Cu")
		(net "M_E_CPU0_SA_DQS_DP<3>")
	)
	(segment
		(start 397.45666 -282.492704)
		(end 397.45666 -282.666948)
		(width 0.20066)
		(layer "F.Cu")
		(net "M_E_CPU0_SA_DQS_DP<3>")
	)
	(segment
		(start 407.342594 -284.866588)
		(end 406.753314 -284.866588)
		(width 0.20066)
		(layer "F.Cu")
		(net "M_E_CPU0_SA_DQS_DP<3>")
	)
	(segment
		(start 405.727662 -284.785054)
		(end 405.809196 -284.866588)
		(width 0.20066)
		(layer "F.Cu")
		(net "M_E_CPU0_SA_DQS_DP<3>")
	)
	(segment
		(start 401.04187 -285.327344)
		(end 403.640036 -285.327344)
		(width 0.20066)
		(layer "F.Cu")
		(net "M_E_CPU0_SA_DQS_DP<3>")
	)
	(segment
		(start 385.48945 -265.189462)
		(end 385.61645 -265.189462)
		(width 0.088646)
		(layer "F.Cu")
		(net "M_E_CPU0_SA_DQS_DP<3>")
	)
	(segment
		(start 409.83662 -285.303468)
		(end 409.831794 -285.303468)
		(width 0.101854)
		(layer "F.Cu")
		(net "M_E_CPU0_SA_DQS_DP<3>")
	)
	(segment
		(start 409.283916 -285.040578)
		(end 408.690318 -285.040578)
		(width 0.20066)
		(layer "F.Cu")
		(net "M_E_CPU0_SA_DQS_DP<3>")
	)
	(segment
		(start 387.209284 -265.624564)
		(end 387.209284 -265.696446)
		(width 0.088646)
		(layer "F.Cu")
		(net "M_E_CPU0_SA_DQS_DP<3>")
	)
	(segment
		(start 388.35584 -266.816078)
		(end 394.880084 -273.340322)
		(width 0.1524)
		(layer "F.Cu")
		(net "M_E_CPU0_SA_DQS_DP<3>")
	)
	(segment
		(start 387.637274 -266.052554)
		(end 387.637274 -266.124436)
		(width 0.088646)
		(layer "F.Cu")
		(net "M_E_CPU0_SA_DQS_DP<3>")
	)
	(segment
		(start 397.45666 -282.666948)
		(end 397.882618 -283.092906)
		(width 0.20066)
		(layer "F.Cu")
		(net "M_E_CPU0_SA_DQS_DP<3>")
	)
	(segment
		(start 409.546806 -285.303468)
		(end 409.283916 -285.040578)
		(width 0.20066)
		(layer "F.Cu")
		(net "M_E_CPU0_SA_DQS_DP<3>")
	)
	(segment
		(start 399.760694 -284.796738)
		(end 401.04187 -285.327344)
		(width 0.20066)
		(layer "F.Cu")
		(net "M_E_CPU0_SA_DQS_DP<3>")
	)
	(segment
		(start 385.35102 -264.855452)
		(end 385.35102 -265.051032)
		(width 0.088646)
		(layer "F.Cu")
		(net "M_E_CPU0_SA_DQS_DP<3>")
	)
	(segment
		(start 387.637274 -266.124436)
		(end 387.781292 -266.268454)
		(width 0.088646)
		(layer "F.Cu")
		(net "M_E_CPU0_SA_DQS_DP<3>")
	)
	(segment
		(start 404.611078 -284.678628)
		(end 405.06396 -284.376114)
		(width 0.20066)
		(layer "F.Cu")
		(net "M_E_CPU0_SA_DQS_DP<3>")
	)
	(segment
		(start 411.845252 -285.291784)
		(end 409.848304 -285.291784)
		(width 0.1016)
		(layer "F.Cu")
		(net "M_E_CPU0_SA_DQS_DP<3>")
	)
	(segment
		(start 388.340346 -266.755372)
		(end 388.340346 -266.800584)
		(width 0.088646)
		(layer "F.Cu")
		(net "M_E_CPU0_SA_DQS_DP<3>")
	)
	(segment
		(start 404.0759 -285.185866)
		(end 404.576534 -284.851348)
		(width 0.20066)
		(layer "F.Cu")
		(net "M_E_CPU0_SA_DQS_DP<3>")
	)
	(segment
		(start 405.06396 -284.376114)
		(end 405.661622 -284.376114)
		(width 0.20066)
		(layer "F.Cu")
		(net "M_E_CPU0_SA_DQS_DP<3>")
	)
	(segment
		(start 387.209284 -265.696446)
		(end 387.353302 -265.840464)
		(width 0.088646)
		(layer "F.Cu")
		(net "M_E_CPU0_SA_DQS_DP<3>")
	)
	(segment
		(start 385.70916 -265.25982)
		(end 385.709414 -265.260074)
		(width 0.088646)
		(layer "F.Cu")
		(net "M_E_CPU0_SA_DQS_DP<3>")
	)
	(segment
		(start 387.781292 -266.268454)
		(end 387.853428 -266.268454)
		(width 0.088646)
		(layer "F.Cu")
		(net "M_E_CPU0_SA_DQS_DP<3>")
	)
	(segment
		(start 398.482312 -283.6926)
		(end 398.90827 -284.118558)
		(width 0.20066)
		(layer "F.Cu")
		(net "M_E_CPU0_SA_DQS_DP<3>")
	)
	(segment
		(start 385.720844 -265.266678)
		(end 385.722368 -265.26744)
		(width 0.088646)
		(layer "F.Cu")
		(net "M_E_CPU0_SA_DQS_DP<3>")
	)
	(segment
		(start 397.004286 -281.988006)
		(end 397.004286 -282.04033)
		(width 0.1524)
		(layer "F.Cu")
		(net "M_E_CPU0_SA_DQS_DP<3>")
	)
	(segment
		(start 396.511526 -281.4955)
		(end 397.004286 -281.988006)
		(width 0.1524)
		(layer "F.Cu")
		(net "M_E_CPU0_SA_DQS_DP<3>")
	)
	(segment
		(start 385.064762 -264.778236)
		(end 385.229862 -264.734294)
		(width 0.088646)
		(layer "F.Cu")
		(net "M_E_CPU0_SA_DQS_DP<3>")
	)
	(segment
		(start 405.661622 -284.376114)
		(end 405.727662 -284.442154)
		(width 0.20066)
		(layer "F.Cu")
		(net "M_E_CPU0_SA_DQS_DP<3>")
	)
	(segment
		(start 387.065774 -265.481054)
		(end 387.209284 -265.624564)
		(width 0.088646)
		(layer "F.Cu")
		(net "M_E_CPU0_SA_DQS_DP<3>")
	)
	(segment
		(start 413.2707 -284.584902)
		(end 412.860236 -284.995366)
		(width 0.20066)
		(layer "F.Cu")
		(net "M_E_CPU0_SA_DQS_DP<3>")
	)
	(segment
		(start 411.863794 -285.310326)
		(end 411.845252 -285.291784)
		(width 0.1016)
		(layer "F.Cu")
		(net "M_E_CPU0_SA_DQS_DP<3>")
	)
	(segment
		(start 397.004286 -282.04033)
		(end 397.03121 -282.067254)
		(width 0.1524)
		(layer "F.Cu")
		(net "M_E_CPU0_SA_DQS_DP<3>")
	)
	(segment
		(start 413.748474 -284.866588)
		(end 413.466788 -284.584902)
		(width 0.20066)
		(layer "F.Cu")
		(net "M_E_CPU0_SA_DQS_DP<3>")
	)
	(segment
		(start 403.640036 -285.327344)
		(end 403.81301 -285.211774)
		(width 0.20066)
		(layer "F.Cu")
		(net "M_E_CPU0_SA_DQS_DP<3>")
	)
	(segment
		(start 394.880084 -273.340322)
		(end 396.511526 -281.4955)
		(width 0.1524)
		(layer "F.Cu")
		(net "M_E_CPU0_SA_DQS_DP<3>")
	)
	(segment
		(start 405.727662 -284.442154)
		(end 405.727662 -284.785054)
		(width 0.20066)
		(layer "F.Cu")
		(net "M_E_CPU0_SA_DQS_DP<3>")
	)
	(segment
		(start 405.809196 -284.866588)
		(end 406.753314 -284.866588)
		(width 0.20066)
		(layer "F.Cu")
		(net "M_E_CPU0_SA_DQS_DP<3>")
	)
	(segment
		(start 388.340346 -266.800584)
		(end 388.35584 -266.816078)
		(width 0.088646)
		(layer "F.Cu")
		(net "M_E_CPU0_SA_DQS_DP<3>")
	)
	(segment
		(start 412.860236 -284.995366)
		(end 412.48965 -284.995366)
		(width 0.20066)
		(layer "F.Cu")
		(net "M_E_CPU0_SA_DQS_DP<3>")
	)
	(segment
		(start 398.056862 -283.092906)
		(end 398.482312 -283.518356)
		(width 0.20066)
		(layer "F.Cu")
		(net "M_E_CPU0_SA_DQS_DP<3>")
	)
	(segment
		(start 404.576534 -284.851348)
		(end 404.611078 -284.678628)
		(width 0.20066)
		(layer "F.Cu")
		(net "M_E_CPU0_SA_DQS_DP<3>")
	)
	(segment
		(start 386.788406 -265.324844)
		(end 386.80644 -265.342116)
		(width 0.088646)
		(layer "F.Cu")
		(net "M_E_CPU0_SA_DQS_DP<3>")
	)
	(segment
		(start 397.03121 -282.067254)
		(end 397.45666 -282.492704)
		(width 0.20066)
		(layer "F.Cu")
		(net "M_E_CPU0_SA_DQS_DP<3>")
	)
	(segment
		(start 398.90827 -284.118558)
		(end 399.082514 -284.118558)
		(width 0.20066)
		(layer "F.Cu")
		(net "M_E_CPU0_SA_DQS_DP<3>")
	)
	(segment
		(start 414.297114 -284.866588)
		(end 413.748474 -284.866588)
		(width 0.20066)
		(layer "F.Cu")
		(net "M_E_CPU0_SA_DQS_DP<3>")
	)
	(segment
		(start 387.853428 -266.268454)
		(end 388.340346 -266.755372)
		(width 0.088646)
		(layer "F.Cu")
		(net "M_E_CPU0_SA_DQS_DP<3>")
	)
	(segment
		(start 399.082514 -284.118558)
		(end 399.760694 -284.796738)
		(width 0.20066)
		(layer "F.Cu")
		(net "M_E_CPU0_SA_DQS_DP<3>")
	)
	(segment
		(start 387.425184 -265.840464)
		(end 387.637274 -266.052554)
		(width 0.088646)
		(layer "F.Cu")
		(net "M_E_CPU0_SA_DQS_DP<3>")
	)
	(segment
		(start 408.27579 -284.62605)
		(end 407.583132 -284.62605)
		(width 0.20066)
		(layer "F.Cu")
		(net "M_E_CPU0_SA_DQS_DP<3>")
	)
	(segment
		(start 413.466788 -284.584902)
		(end 413.2707 -284.584902)
		(width 0.20066)
		(layer "F.Cu")
		(net "M_E_CPU0_SA_DQS_DP<3>")
	)
	(segment
		(start 408.690318 -285.040578)
		(end 408.27579 -284.62605)
		(width 0.20066)
		(layer "F.Cu")
		(net "M_E_CPU0_SA_DQS_DP<3>")
	)
	(segment
		(start 409.831794 -285.303468)
		(end 409.546806 -285.303468)
		(width 0.20066)
		(layer "F.Cu")
		(net "M_E_CPU0_SA_DQS_DP<3>")
	)
	(segment
		(start 407.583132 -284.62605)
		(end 407.342594 -284.866588)
		(width 0.20066)
		(layer "F.Cu")
		(net "M_E_CPU0_SA_DQS_DP<3>")
	)
	(segment
		(start 385.229862 -264.734294)
		(end 385.35102 -264.855452)
		(width 0.088646)
		(layer "F.Cu")
		(net "M_E_CPU0_SA_DQS_DP<3>")
	)
	(segment
		(start 386.80644 -265.342116)
		(end 387.065774 -265.481054)
		(width 0.088646)
		(layer "F.Cu")
		(net "M_E_CPU0_SA_DQS_DP<3>")
	)
	(segment
		(start 385.35102 -265.051032)
		(end 385.48945 -265.189462)
		(width 0.088646)
		(layer "F.Cu")
		(net "M_E_CPU0_SA_DQS_DP<3>")
	)
	(segment
		(start 403.81301 -285.211774)
		(end 403.90318 -285.151576)
		(width 0.20066)
		(layer "F.Cu")
		(net "M_E_CPU0_SA_DQS_DP<3>")
	)
	(segment
		(start 397.882618 -283.092906)
		(end 398.056862 -283.092906)
		(width 0.20066)
		(layer "F.Cu")
		(net "M_E_CPU0_SA_DQS_DP<3>")
	)
	(segment
		(start 387.353302 -265.840464)
		(end 387.425184 -265.840464)
		(width 0.088646)
		(layer "F.Cu")
		(net "M_E_CPU0_SA_DQS_DP<3>")
	)
	(segment
		(start 412.17469 -285.310326)
		(end 411.863794 -285.310326)
		(width 0.20066)
		(layer "F.Cu")
		(net "M_E_CPU0_SA_DQS_DP<3>")
	)
	(segment
		(start 385.709414 -265.260074)
		(end 385.720844 -265.266678)
		(width 0.088646)
		(layer "F.Cu")
		(net "M_E_CPU0_SA_DQS_DP<3>")
	)
	(segment
		(start 412.48965 -284.995366)
		(end 412.17469 -285.310326)
		(width 0.20066)
		(layer "F.Cu")
		(net "M_E_CPU0_SA_DQS_DP<3>")
	)
	(arc
		(start 386.28701 -265.26744)
		(mid 386.547215 -265.213274)
		(end 386.788406 -265.324844)
		(width 0.088646)
		(layer "F.Cu")
		(net "M_E_CPU0_SA_DQS_DP<3>")
	)
	(arc
		(start 385.61645 -265.189462)
		(mid 385.616958 -265.188954)
		(end 385.617466 -265.188446)
		(width 0.088646)
		(layer "F.Cu")
		(net "M_E_CPU0_SA_DQS_DP<3>")
	)
	(arc
		(start 385.617466 -265.188446)
		(mid 385.661247 -265.226788)
		(end 385.70916 -265.25982)
		(width 0.088646)
		(layer "F.Cu")
		(net "M_E_CPU0_SA_DQS_DP<3>")
	)
	(arc
		(start 385.722368 -265.26744)
		(mid 386.004706 -265.343123)
		(end 386.28701 -265.26744)
		(width 0.088646)
		(layer "F.Cu")
		(net "M_E_CPU0_SA_DQS_DP<3>")
	)
	(segment
		(start 384.595116 -270.475456)
		(end 384.439922 -270.20647)
		(width 0.088646)
		(layer "F.Cu")
		(net "M_E_CPU0_SA_DQS_DP<2>")
	)
	(segment
		(start 387.612128 -271.662144)
		(end 391.258044 -275.30806)
		(width 0.1524)
		(layer "F.Cu")
		(net "M_E_CPU0_SA_DQS_DP<2>")
	)
	(segment
		(start 399.130266 -296.309034)
		(end 403.115018 -296.309034)
		(width 0.20066)
		(layer "F.Cu")
		(net "M_E_CPU0_SA_DQS_DP<2>")
	)
	(segment
		(start 391.258044 -275.30806)
		(end 392.269218 -280.361898)
		(width 0.1524)
		(layer "F.Cu")
		(net "M_E_CPU0_SA_DQS_DP<2>")
	)
	(segment
		(start 409.848304 -294.641778)
		(end 409.83662 -294.653462)
		(width 0.1016)
		(layer "F.Cu")
		(net "M_E_CPU0_SA_DQS_DP<2>")
	)
	(segment
		(start 407.583132 -293.976044)
		(end 407.342594 -294.216582)
		(width 0.20066)
		(layer "F.Cu")
		(net "M_E_CPU0_SA_DQS_DP<2>")
	)
	(segment
		(start 387.000242 -270.74749)
		(end 387.000242 -270.747998)
		(width 0.088646)
		(layer "F.Cu")
		(net "M_E_CPU0_SA_DQS_DP<2>")
	)
	(segment
		(start 392.269218 -280.361898)
		(end 392.269218 -289.395662)
		(width 0.1524)
		(layer "F.Cu")
		(net "M_E_CPU0_SA_DQS_DP<2>")
	)
	(segment
		(start 386.07873 -270.623792)
		(end 386.07873 -270.623538)
		(width 0.088646)
		(layer "F.Cu")
		(net "M_E_CPU0_SA_DQS_DP<2>")
	)
	(segment
		(start 386.820156 -270.242792)
		(end 386.822442 -270.245078)
		(width 0.088646)
		(layer "F.Cu")
		(net "M_E_CPU0_SA_DQS_DP<2>")
	)
	(segment
		(start 413.2707 -293.934896)
		(end 412.860236 -294.34536)
		(width 0.20066)
		(layer "F.Cu")
		(net "M_E_CPU0_SA_DQS_DP<2>")
	)
	(segment
		(start 414.297114 -294.216582)
		(end 413.748474 -294.216582)
		(width 0.20066)
		(layer "F.Cu")
		(net "M_E_CPU0_SA_DQS_DP<2>")
	)
	(segment
		(start 387.334506 -271.26057)
		(end 387.504178 -271.49044)
		(width 0.088646)
		(layer "F.Cu")
		(net "M_E_CPU0_SA_DQS_DP<2>")
	)
	(segment
		(start 413.466788 -293.934896)
		(end 413.2707 -293.934896)
		(width 0.20066)
		(layer "F.Cu")
		(net "M_E_CPU0_SA_DQS_DP<2>")
	)
	(segment
		(start 409.83662 -294.653462)
		(end 409.831794 -294.653462)
		(width 0.101854)
		(layer "F.Cu")
		(net "M_E_CPU0_SA_DQS_DP<2>")
	)
	(segment
		(start 409.546806 -294.653462)
		(end 409.283916 -294.390572)
		(width 0.20066)
		(layer "F.Cu")
		(net "M_E_CPU0_SA_DQS_DP<2>")
	)
	(segment
		(start 408.27579 -293.976044)
		(end 407.583132 -293.976044)
		(width 0.20066)
		(layer "F.Cu")
		(net "M_E_CPU0_SA_DQS_DP<2>")
	)
	(segment
		(start 407.342594 -294.216582)
		(end 406.753314 -294.216582)
		(width 0.20066)
		(layer "F.Cu")
		(net "M_E_CPU0_SA_DQS_DP<2>")
	)
	(segment
		(start 392.269218 -289.395662)
		(end 392.533124 -289.659568)
		(width 0.1524)
		(layer "F.Cu")
		(net "M_E_CPU0_SA_DQS_DP<2>")
	)
	(segment
		(start 386.960364 -270.665702)
		(end 386.977636 -270.70685)
		(width 0.088646)
		(layer "F.Cu")
		(net "M_E_CPU0_SA_DQS_DP<2>")
	)
	(segment
		(start 412.860236 -294.34536)
		(end 412.48965 -294.34536)
		(width 0.20066)
		(layer "F.Cu")
		(net "M_E_CPU0_SA_DQS_DP<2>")
	)
	(segment
		(start 409.283916 -294.390572)
		(end 408.690318 -294.390572)
		(width 0.20066)
		(layer "F.Cu")
		(net "M_E_CPU0_SA_DQS_DP<2>")
	)
	(segment
		(start 405.969978 -294.026336)
		(end 406.156414 -294.214296)
		(width 0.20066)
		(layer "F.Cu")
		(net "M_E_CPU0_SA_DQS_DP<2>")
	)
	(segment
		(start 406.156414 -294.214296)
		(end 406.753314 -294.216582)
		(width 0.20066)
		(layer "F.Cu")
		(net "M_E_CPU0_SA_DQS_DP<2>")
	)
	(segment
		(start 387.00075 -270.748506)
		(end 387.014974 -270.782034)
		(width 0.088646)
		(layer "F.Cu")
		(net "M_E_CPU0_SA_DQS_DP<2>")
	)
	(segment
		(start 411.863794 -294.66032)
		(end 411.845252 -294.641778)
		(width 0.1016)
		(layer "F.Cu")
		(net "M_E_CPU0_SA_DQS_DP<2>")
	)
	(segment
		(start 411.845252 -294.641778)
		(end 409.848304 -294.641778)
		(width 0.1016)
		(layer "F.Cu")
		(net "M_E_CPU0_SA_DQS_DP<2>")
	)
	(segment
		(start 412.48965 -294.34536)
		(end 412.17469 -294.66032)
		(width 0.20066)
		(layer "F.Cu")
		(net "M_E_CPU0_SA_DQS_DP<2>")
	)
	(segment
		(start 392.533124 -289.659568)
		(end 392.533124 -289.711892)
		(width 0.1524)
		(layer "F.Cu")
		(net "M_E_CPU0_SA_DQS_DP<2>")
	)
	(segment
		(start 386.726176 -270.170656)
		(end 386.72897 -270.17218)
		(width 0.088646)
		(layer "F.Cu")
		(net "M_E_CPU0_SA_DQS_DP<2>")
	)
	(segment
		(start 387.504178 -271.49044)
		(end 387.585204 -271.571466)
		(width 0.088646)
		(layer "F.Cu")
		(net "M_E_CPU0_SA_DQS_DP<2>")
	)
	(segment
		(start 413.748474 -294.216582)
		(end 413.466788 -293.934896)
		(width 0.20066)
		(layer "F.Cu")
		(net "M_E_CPU0_SA_DQS_DP<2>")
	)
	(segment
		(start 403.115018 -296.309034)
		(end 405.397716 -294.026336)
		(width 0.20066)
		(layer "F.Cu")
		(net "M_E_CPU0_SA_DQS_DP<2>")
	)
	(segment
		(start 409.831794 -294.653462)
		(end 409.546806 -294.653462)
		(width 0.20066)
		(layer "F.Cu")
		(net "M_E_CPU0_SA_DQS_DP<2>")
	)
	(segment
		(start 387.000242 -270.747998)
		(end 387.00075 -270.748506)
		(width 0.088646)
		(layer "F.Cu")
		(net "M_E_CPU0_SA_DQS_DP<2>")
	)
	(segment
		(start 386.484622 -270.137636)
		(end 386.595112 -270.137636)
		(width 0.088646)
		(layer "F.Cu")
		(net "M_E_CPU0_SA_DQS_DP<2>")
	)
	(segment
		(start 408.690318 -294.390572)
		(end 408.27579 -293.976044)
		(width 0.20066)
		(layer "F.Cu")
		(net "M_E_CPU0_SA_DQS_DP<2>")
	)
	(segment
		(start 387.014974 -270.782034)
		(end 387.334506 -271.26057)
		(width 0.088646)
		(layer "F.Cu")
		(net "M_E_CPU0_SA_DQS_DP<2>")
	)
	(segment
		(start 392.560048 -289.738816)
		(end 399.130266 -296.309034)
		(width 0.20066)
		(layer "F.Cu")
		(net "M_E_CPU0_SA_DQS_DP<2>")
	)
	(segment
		(start 405.397716 -294.026336)
		(end 405.969978 -294.026336)
		(width 0.20066)
		(layer "F.Cu")
		(net "M_E_CPU0_SA_DQS_DP<2>")
	)
	(segment
		(start 384.439922 -270.20647)
		(end 384.461766 -270.125698)
		(width 0.088646)
		(layer "F.Cu")
		(net "M_E_CPU0_SA_DQS_DP<2>")
	)
	(segment
		(start 385.241292 -270.955008)
		(end 385.246118 -270.958056)
		(width 0.088646)
		(layer "F.Cu")
		(net "M_E_CPU0_SA_DQS_DP<2>")
	)
	(segment
		(start 386.977636 -270.70685)
		(end 387.000242 -270.74749)
		(width 0.088646)
		(layer "F.Cu")
		(net "M_E_CPU0_SA_DQS_DP<2>")
	)
	(segment
		(start 392.533124 -289.711892)
		(end 392.560048 -289.738816)
		(width 0.1524)
		(layer "F.Cu")
		(net "M_E_CPU0_SA_DQS_DP<2>")
	)
	(segment
		(start 412.17469 -294.66032)
		(end 411.863794 -294.66032)
		(width 0.20066)
		(layer "F.Cu")
		(net "M_E_CPU0_SA_DQS_DP<2>")
	)
	(segment
		(start 387.585204 -271.571466)
		(end 387.612128 -271.63649)
		(width 0.088646)
		(layer "F.Cu")
		(net "M_E_CPU0_SA_DQS_DP<2>")
	)
	(segment
		(start 386.07873 -270.623538)
		(end 386.09397 -270.575278)
		(width 0.088646)
		(layer "F.Cu")
		(net "M_E_CPU0_SA_DQS_DP<2>")
	)
	(segment
		(start 387.612128 -271.63649)
		(end 387.612128 -271.662144)
		(width 0.088646)
		(layer "F.Cu")
		(net "M_E_CPU0_SA_DQS_DP<2>")
	)
	(arc
		(start 384.725926 -270.124682)
		(mid 384.794999 -270.159614)
		(end 384.855212 -270.208248)
		(width 0.088646)
		(layer "F.Cu")
		(net "M_E_CPU0_SA_DQS_DP<2>")
	)
	(arc
		(start 386.824474 -270.24711)
		(mid 386.89179 -270.33996)
		(end 386.915914 -270.452088)
		(width 0.088646)
		(layer "F.Cu")
		(net "M_E_CPU0_SA_DQS_DP<2>")
	)
	(arc
		(start 384.981958 -270.493998)
		(mid 385.055156 -270.756273)
		(end 385.241292 -270.955008)
		(width 0.088646)
		(layer "F.Cu")
		(net "M_E_CPU0_SA_DQS_DP<2>")
	)
	(arc
		(start 385.246118 -270.958056)
		(mid 385.286528 -270.980929)
		(end 385.32943 -270.998696)
		(width 0.088646)
		(layer "F.Cu")
		(net "M_E_CPU0_SA_DQS_DP<2>")
	)
	(arc
		(start 386.595112 -270.137636)
		(mid 386.662688 -270.146025)
		(end 386.726176 -270.170656)
		(width 0.088646)
		(layer "F.Cu")
		(net "M_E_CPU0_SA_DQS_DP<2>")
	)
	(arc
		(start 384.969258 -270.406114)
		(mid 384.978111 -270.449694)
		(end 384.981958 -270.493998)
		(width 0.088646)
		(layer "F.Cu")
		(net "M_E_CPU0_SA_DQS_DP<2>")
	)
	(arc
		(start 386.72897 -270.17218)
		(mid 386.777076 -270.204242)
		(end 386.820156 -270.242792)
		(width 0.088646)
		(layer "F.Cu")
		(net "M_E_CPU0_SA_DQS_DP<2>")
	)
	(arc
		(start 384.588258 -270.10106)
		(mid 384.658229 -270.106255)
		(end 384.725926 -270.124682)
		(width 0.088646)
		(layer "F.Cu")
		(net "M_E_CPU0_SA_DQS_DP<2>")
	)
	(arc
		(start 384.461766 -270.125698)
		(mid 384.523943 -270.107882)
		(end 384.588258 -270.10106)
		(width 0.088646)
		(layer "F.Cu")
		(net "M_E_CPU0_SA_DQS_DP<2>")
	)
	(arc
		(start 386.09397 -270.575278)
		(mid 386.105297 -270.531094)
		(end 386.111242 -270.48587)
		(width 0.088646)
		(layer "F.Cu")
		(net "M_E_CPU0_SA_DQS_DP<2>")
	)
	(arc
		(start 386.915914 -270.452088)
		(mid 386.927924 -270.561022)
		(end 386.960364 -270.665702)
		(width 0.088646)
		(layer "F.Cu")
		(net "M_E_CPU0_SA_DQS_DP<2>")
	)
	(arc
		(start 385.32943 -270.998696)
		(mid 385.783007 -270.968992)
		(end 386.07873 -270.623792)
		(width 0.088646)
		(layer "F.Cu")
		(net "M_E_CPU0_SA_DQS_DP<2>")
	)
	(arc
		(start 386.111242 -270.48587)
		(mid 386.229372 -270.238272)
		(end 386.484622 -270.137636)
		(width 0.088646)
		(layer "F.Cu")
		(net "M_E_CPU0_SA_DQS_DP<2>")
	)
	(arc
		(start 384.855212 -270.208248)
		(mid 384.925323 -270.299633)
		(end 384.969258 -270.406114)
		(width 0.088646)
		(layer "F.Cu")
		(net "M_E_CPU0_SA_DQS_DP<2>")
	)
	(arc
		(start 386.822442 -270.245078)
		(mid 386.82346 -270.246092)
		(end 386.824474 -270.24711)
		(width 0.088646)
		(layer "F.Cu")
		(net "M_E_CPU0_SA_DQS_DP<2>")
	)
	(segment
		(start 409.83662 -303.991772)
		(end 409.633928 -303.991772)
		(width 0.101854)
		(layer "F.Cu")
		(net "M_E_CPU0_SA_DQS_DP<1>")
	)
	(segment
		(start 406.753314 -303.566576)
		(end 405.623014 -303.566576)
		(width 0.20066)
		(layer "F.Cu")
		(net "M_E_CPU0_SA_DQS_DP<1>")
	)
	(segment
		(start 412.890716 -303.695354)
		(end 412.438342 -303.695354)
		(width 0.20066)
		(layer "F.Cu")
		(net "M_E_CPU0_SA_DQS_DP<1>")
	)
	(segment
		(start 412.130494 -304.003202)
		(end 411.863794 -304.003202)
		(width 0.20066)
		(layer "F.Cu")
		(net "M_E_CPU0_SA_DQS_DP<1>")
	)
	(segment
		(start 411.863794 -304.003202)
		(end 411.851856 -304.003202)
		(width 0.101854)
		(layer "F.Cu")
		(net "M_E_CPU0_SA_DQS_DP<1>")
	)
	(segment
		(start 381.775716 -272.639028)
		(end 381.775462 -272.639282)
		(width 0.20066)
		(layer "F.Cu")
		(net "M_E_CPU0_SA_DQS_DP<1>")
	)
	(segment
		(start 413.47644 -303.294542)
		(end 413.291528 -303.294542)
		(width 0.20066)
		(layer "F.Cu")
		(net "M_E_CPU0_SA_DQS_DP<1>")
	)
	(segment
		(start 407.583132 -303.326038)
		(end 407.342594 -303.566576)
		(width 0.20066)
		(layer "F.Cu")
		(net "M_E_CPU0_SA_DQS_DP<1>")
	)
	(segment
		(start 409.283916 -303.740566)
		(end 408.6225 -303.740566)
		(width 0.20066)
		(layer "F.Cu")
		(net "M_E_CPU0_SA_DQS_DP<1>")
	)
	(segment
		(start 408.207972 -303.326038)
		(end 407.583132 -303.326038)
		(width 0.20066)
		(layer "F.Cu")
		(net "M_E_CPU0_SA_DQS_DP<1>")
	)
	(segment
		(start 411.840426 -303.991772)
		(end 409.83662 -303.991772)
		(width 0.1016)
		(layer "F.Cu")
		(net "M_E_CPU0_SA_DQS_DP<1>")
	)
	(segment
		(start 381.775716 -272.103342)
		(end 381.775716 -272.639028)
		(width 0.20066)
		(layer "F.Cu")
		(net "M_E_CPU0_SA_DQS_DP<1>")
	)
	(segment
		(start 413.748474 -303.566576)
		(end 413.47644 -303.294542)
		(width 0.20066)
		(layer "F.Cu")
		(net "M_E_CPU0_SA_DQS_DP<1>")
	)
	(segment
		(start 412.438342 -303.695354)
		(end 412.130494 -304.003202)
		(width 0.20066)
		(layer "F.Cu")
		(net "M_E_CPU0_SA_DQS_DP<1>")
	)
	(segment
		(start 407.342594 -303.566576)
		(end 406.753314 -303.566576)
		(width 0.20066)
		(layer "F.Cu")
		(net "M_E_CPU0_SA_DQS_DP<1>")
	)
	(segment
		(start 408.6225 -303.740566)
		(end 408.207972 -303.326038)
		(width 0.20066)
		(layer "F.Cu")
		(net "M_E_CPU0_SA_DQS_DP<1>")
	)
	(segment
		(start 409.633928 -303.991772)
		(end 409.535122 -303.991772)
		(width 0.20066)
		(layer "F.Cu")
		(net "M_E_CPU0_SA_DQS_DP<1>")
	)
	(segment
		(start 413.291528 -303.294542)
		(end 412.890716 -303.695354)
		(width 0.20066)
		(layer "F.Cu")
		(net "M_E_CPU0_SA_DQS_DP<1>")
	)
	(segment
		(start 411.851856 -304.003202)
		(end 411.840426 -303.991772)
		(width 0.1016)
		(layer "F.Cu")
		(net "M_E_CPU0_SA_DQS_DP<1>")
	)
	(segment
		(start 409.535122 -303.991772)
		(end 409.283916 -303.740566)
		(width 0.20066)
		(layer "F.Cu")
		(net "M_E_CPU0_SA_DQS_DP<1>")
	)
	(segment
		(start 414.297114 -303.566576)
		(end 413.748474 -303.566576)
		(width 0.20066)
		(layer "F.Cu")
		(net "M_E_CPU0_SA_DQS_DP<1>")
	)
	(segment
		(start 401.733512 -293.754048)
		(end 401.523962 -293.247064)
		(width 0.18288)
		(layer "In2.Cu")
		(net "M_E_CPU0_SA_DQS_DP<1>")
	)
	(segment
		(start 399.587466 -289.914584)
		(end 399.199608 -289.526726)
		(width 0.18288)
		(layer "In2.Cu")
		(net "M_E_CPU0_SA_DQS_DP<1>")
	)
	(segment
		(start 397.128492 -283.51607)
		(end 393.641072 -280.028904)
		(width 0.18288)
		(layer "In2.Cu")
		(net "M_E_CPU0_SA_DQS_DP<1>")
	)
	(segment
		(start 382.339342 -273.074638)
		(end 382.010666 -272.663158)
		(width 0.088646)
		(layer "In2.Cu")
		(net "M_E_CPU0_SA_DQS_DP<1>")
	)
	(segment
		(start 383.383028 -273.134836)
		(end 383.372614 -273.12874)
		(width 0.088646)
		(layer "In2.Cu")
		(net "M_E_CPU0_SA_DQS_DP<1>")
	)
	(segment
		(start 402.762212 -298.020486)
		(end 402.637752 -297.896026)
		(width 0.18288)
		(layer "In2.Cu")
		(net "M_E_CPU0_SA_DQS_DP<1>")
	)
	(segment
		(start 397.004032 -286.334962)
		(end 397.004032 -285.786322)
		(width 0.18288)
		(layer "In2.Cu")
		(net "M_E_CPU0_SA_DQS_DP<1>")
	)
	(segment
		(start 397.004032 -284.988762)
		(end 397.004032 -284.440122)
		(width 0.18288)
		(layer "In2.Cu")
		(net "M_E_CPU0_SA_DQS_DP<1>")
	)
	(segment
		(start 402.762212 -297.222926)
		(end 402.762212 -296.242232)
		(width 0.18288)
		(layer "In2.Cu")
		(net "M_E_CPU0_SA_DQS_DP<1>")
	)
	(segment
		(start 401.665948 -293.916608)
		(end 401.733512 -293.754048)
		(width 0.18288)
		(layer "In2.Cu")
		(net "M_E_CPU0_SA_DQS_DP<1>")
	)
	(segment
		(start 392.41222 -277.062946)
		(end 389.332724 -273.98345)
		(width 0.18288)
		(layer "In2.Cu")
		(net "M_E_CPU0_SA_DQS_DP<1>")
	)
	(segment
		(start 387.945122 -273.92376)
		(end 387.209538 -273.188176)
		(width 0.088646)
		(layer "In2.Cu")
		(net "M_E_CPU0_SA_DQS_DP<1>")
	)
	(segment
		(start 402.637752 -299.242226)
		(end 402.637752 -298.693586)
		(width 0.18288)
		(layer "In2.Cu")
		(net "M_E_CPU0_SA_DQS_DP<1>")
	)
	(segment
		(start 397.128492 -287.45561)
		(end 397.128492 -286.459422)
		(width 0.18288)
		(layer "In2.Cu")
		(net "M_E_CPU0_SA_DQS_DP<1>")
	)
	(segment
		(start 402.762212 -296.242232)
		(end 402.552662 -295.735248)
		(width 0.18288)
		(layer "In2.Cu")
		(net "M_E_CPU0_SA_DQS_DP<1>")
	)
	(segment
		(start 382.010666 -272.663158)
		(end 381.98679 -272.639282)
		(width 0.088646)
		(layer "In2.Cu")
		(net "M_E_CPU0_SA_DQS_DP<1>")
	)
	(segment
		(start 388.840726 -273.98345)
		(end 388.781036 -273.92376)
		(width 0.088646)
		(layer "In2.Cu")
		(net "M_E_CPU0_SA_DQS_DP<1>")
	)
	(segment
		(start 402.762212 -301.261526)
		(end 402.762212 -300.712886)
		(width 0.18288)
		(layer "In2.Cu")
		(net "M_E_CPU0_SA_DQS_DP<1>")
	)
	(segment
		(start 402.637752 -300.588426)
		(end 402.637752 -300.039786)
		(width 0.18288)
		(layer "In2.Cu")
		(net "M_E_CPU0_SA_DQS_DP<1>")
	)
	(segment
		(start 402.637752 -300.039786)
		(end 402.762212 -299.915326)
		(width 0.18288)
		(layer "In2.Cu")
		(net "M_E_CPU0_SA_DQS_DP<1>")
	)
	(segment
		(start 402.247862 -294.99814)
		(end 402.038312 -294.491156)
		(width 0.18288)
		(layer "In2.Cu")
		(net "M_E_CPU0_SA_DQS_DP<1>")
	)
	(segment
		(start 401.361148 -293.179754)
		(end 401.151598 -292.672516)
		(width 0.18288)
		(layer "In2.Cu")
		(net "M_E_CPU0_SA_DQS_DP<1>")
	)
	(segment
		(start 397.683482 -288.186622)
		(end 397.683482 -288.0106)
		(width 0.18288)
		(layer "In2.Cu")
		(net "M_E_CPU0_SA_DQS_DP<1>")
	)
	(segment
		(start 399.975578 -290.478718)
		(end 399.587466 -290.090606)
		(width 0.18288)
		(layer "In2.Cu")
		(net "M_E_CPU0_SA_DQS_DP<1>")
	)
	(segment
		(start 402.038312 -294.491156)
		(end 401.875498 -294.423846)
		(width 0.18288)
		(layer "In2.Cu")
		(net "M_E_CPU0_SA_DQS_DP<1>")
	)
	(segment
		(start 402.762212 -298.569126)
		(end 402.762212 -298.020486)
		(width 0.18288)
		(layer "In2.Cu")
		(net "M_E_CPU0_SA_DQS_DP<1>")
	)
	(segment
		(start 402.762212 -299.915326)
		(end 402.762212 -299.366686)
		(width 0.18288)
		(layer "In2.Cu")
		(net "M_E_CPU0_SA_DQS_DP<1>")
	)
	(segment
		(start 401.151598 -292.672516)
		(end 401.219162 -292.509956)
		(width 0.18288)
		(layer "In2.Cu")
		(net "M_E_CPU0_SA_DQS_DP<1>")
	)
	(segment
		(start 404.78075 -303.280064)
		(end 404.392892 -302.892206)
		(width 0.18288)
		(layer "In2.Cu")
		(net "M_E_CPU0_SA_DQS_DP<1>")
	)
	(segment
		(start 401.523962 -293.247064)
		(end 401.361148 -293.179754)
		(width 0.18288)
		(layer "In2.Cu")
		(net "M_E_CPU0_SA_DQS_DP<1>")
	)
	(segment
		(start 398.247616 -288.574734)
		(end 398.071594 -288.574734)
		(width 0.18288)
		(layer "In2.Cu")
		(net "M_E_CPU0_SA_DQS_DP<1>")
	)
	(segment
		(start 397.004032 -284.440122)
		(end 397.128492 -284.315662)
		(width 0.18288)
		(layer "In2.Cu")
		(net "M_E_CPU0_SA_DQS_DP<1>")
	)
	(segment
		(start 397.004032 -285.786322)
		(end 397.128492 -285.661862)
		(width 0.18288)
		(layer "In2.Cu")
		(net "M_E_CPU0_SA_DQS_DP<1>")
	)
	(segment
		(start 382.447546 -273.137376)
		(end 382.339342 -273.074638)
		(width 0.088646)
		(layer "In2.Cu")
		(net "M_E_CPU0_SA_DQS_DP<1>")
	)
	(segment
		(start 401.875498 -294.423846)
		(end 401.665948 -293.916608)
		(width 0.18288)
		(layer "In2.Cu")
		(net "M_E_CPU0_SA_DQS_DP<1>")
	)
	(segment
		(start 398.635474 -288.962592)
		(end 398.247616 -288.574734)
		(width 0.18288)
		(layer "In2.Cu")
		(net "M_E_CPU0_SA_DQS_DP<1>")
	)
	(segment
		(start 402.389848 -295.667938)
		(end 402.180298 -295.1607)
		(width 0.18288)
		(layer "In2.Cu")
		(net "M_E_CPU0_SA_DQS_DP<1>")
	)
	(segment
		(start 404.392892 -302.892206)
		(end 404.21687 -302.892206)
		(width 0.18288)
		(layer "In2.Cu")
		(net "M_E_CPU0_SA_DQS_DP<1>")
	)
	(segment
		(start 402.762212 -300.712886)
		(end 402.637752 -300.588426)
		(width 0.18288)
		(layer "In2.Cu")
		(net "M_E_CPU0_SA_DQS_DP<1>")
	)
	(segment
		(start 389.332724 -273.98345)
		(end 388.840726 -273.98345)
		(width 0.18288)
		(layer "In2.Cu")
		(net "M_E_CPU0_SA_DQS_DP<1>")
	)
	(segment
		(start 405.623014 -303.566576)
		(end 405.336502 -303.280064)
		(width 0.18288)
		(layer "In2.Cu")
		(net "M_E_CPU0_SA_DQS_DP<1>")
	)
	(segment
		(start 397.128492 -286.459422)
		(end 397.004032 -286.334962)
		(width 0.18288)
		(layer "In2.Cu")
		(net "M_E_CPU0_SA_DQS_DP<1>")
	)
	(segment
		(start 397.683482 -288.0106)
		(end 397.128492 -287.45561)
		(width 0.18288)
		(layer "In2.Cu")
		(net "M_E_CPU0_SA_DQS_DP<1>")
	)
	(segment
		(start 400.539966 -290.867084)
		(end 400.1516 -290.478718)
		(width 0.18288)
		(layer "In2.Cu")
		(net "M_E_CPU0_SA_DQS_DP<1>")
	)
	(segment
		(start 399.587466 -290.090606)
		(end 399.587466 -289.914584)
		(width 0.18288)
		(layer "In2.Cu")
		(net "M_E_CPU0_SA_DQS_DP<1>")
	)
	(segment
		(start 403.828758 -302.504094)
		(end 403.828758 -302.328072)
		(width 0.18288)
		(layer "In2.Cu")
		(net "M_E_CPU0_SA_DQS_DP<1>")
	)
	(segment
		(start 405.336502 -303.280064)
		(end 404.78075 -303.280064)
		(width 0.18288)
		(layer "In2.Cu")
		(net "M_E_CPU0_SA_DQS_DP<1>")
	)
	(segment
		(start 402.637752 -298.693586)
		(end 402.762212 -298.569126)
		(width 0.18288)
		(layer "In2.Cu")
		(net "M_E_CPU0_SA_DQS_DP<1>")
	)
	(segment
		(start 402.637752 -297.896026)
		(end 402.637752 -297.347386)
		(width 0.18288)
		(layer "In2.Cu")
		(net "M_E_CPU0_SA_DQS_DP<1>")
	)
	(segment
		(start 388.781036 -273.92376)
		(end 387.945122 -273.92376)
		(width 0.088646)
		(layer "In2.Cu")
		(net "M_E_CPU0_SA_DQS_DP<1>")
	)
	(segment
		(start 398.071594 -288.574734)
		(end 397.683482 -288.186622)
		(width 0.18288)
		(layer "In2.Cu")
		(net "M_E_CPU0_SA_DQS_DP<1>")
	)
	(segment
		(start 402.552662 -295.735248)
		(end 402.389848 -295.667938)
		(width 0.18288)
		(layer "In2.Cu")
		(net "M_E_CPU0_SA_DQS_DP<1>")
	)
	(segment
		(start 397.128492 -285.661862)
		(end 397.128492 -285.113222)
		(width 0.18288)
		(layer "In2.Cu")
		(net "M_E_CPU0_SA_DQS_DP<1>")
	)
	(segment
		(start 404.21687 -302.892206)
		(end 403.828758 -302.504094)
		(width 0.18288)
		(layer "In2.Cu")
		(net "M_E_CPU0_SA_DQS_DP<1>")
	)
	(segment
		(start 381.98679 -272.639282)
		(end 381.775462 -272.639282)
		(width 0.088646)
		(layer "In2.Cu")
		(net "M_E_CPU0_SA_DQS_DP<1>")
	)
	(segment
		(start 400.1516 -290.478718)
		(end 399.975578 -290.478718)
		(width 0.18288)
		(layer "In2.Cu")
		(net "M_E_CPU0_SA_DQS_DP<1>")
	)
	(segment
		(start 402.637752 -297.347386)
		(end 402.762212 -297.222926)
		(width 0.18288)
		(layer "In2.Cu")
		(net "M_E_CPU0_SA_DQS_DP<1>")
	)
	(segment
		(start 402.762212 -299.366686)
		(end 402.637752 -299.242226)
		(width 0.18288)
		(layer "In2.Cu")
		(net "M_E_CPU0_SA_DQS_DP<1>")
	)
	(segment
		(start 399.023586 -289.526726)
		(end 398.635474 -289.138614)
		(width 0.18288)
		(layer "In2.Cu")
		(net "M_E_CPU0_SA_DQS_DP<1>")
	)
	(segment
		(start 401.219162 -292.509956)
		(end 400.539966 -290.867084)
		(width 0.18288)
		(layer "In2.Cu")
		(net "M_E_CPU0_SA_DQS_DP<1>")
	)
	(segment
		(start 397.128492 -284.315662)
		(end 397.128492 -283.51607)
		(width 0.18288)
		(layer "In2.Cu")
		(net "M_E_CPU0_SA_DQS_DP<1>")
	)
	(segment
		(start 399.199608 -289.526726)
		(end 399.023586 -289.526726)
		(width 0.18288)
		(layer "In2.Cu")
		(net "M_E_CPU0_SA_DQS_DP<1>")
	)
	(segment
		(start 403.828758 -302.328072)
		(end 402.762212 -301.261526)
		(width 0.18288)
		(layer "In2.Cu")
		(net "M_E_CPU0_SA_DQS_DP<1>")
	)
	(segment
		(start 397.128492 -285.113222)
		(end 397.004032 -284.988762)
		(width 0.18288)
		(layer "In2.Cu")
		(net "M_E_CPU0_SA_DQS_DP<1>")
	)
	(segment
		(start 402.180298 -295.1607)
		(end 402.247862 -294.99814)
		(width 0.18288)
		(layer "In2.Cu")
		(net "M_E_CPU0_SA_DQS_DP<1>")
	)
	(segment
		(start 398.635474 -289.138614)
		(end 398.635474 -288.962592)
		(width 0.18288)
		(layer "In2.Cu")
		(net "M_E_CPU0_SA_DQS_DP<1>")
	)
	(segment
		(start 393.641072 -280.028904)
		(end 392.41222 -277.062946)
		(width 0.18288)
		(layer "In2.Cu")
		(net "M_E_CPU0_SA_DQS_DP<1>")
	)
	(arc
		(start 386.756656 -273.128486)
		(mid 386.474237 -273.204296)
		(end 386.19176 -273.12874)
		(width 0.088646)
		(layer "In2.Cu")
		(net "M_E_CPU0_SA_DQS_DP<1>")
	)
	(arc
		(start 382.998218 -273.12874)
		(mid 382.724019 -273.204575)
		(end 382.447546 -273.137376)
		(width 0.088646)
		(layer "In2.Cu")
		(net "M_E_CPU0_SA_DQS_DP<1>")
	)
	(arc
		(start 384.31216 -273.12874)
		(mid 384.124962 -273.078597)
		(end 383.937764 -273.12874)
		(width 0.088646)
		(layer "In2.Cu")
		(net "M_E_CPU0_SA_DQS_DP<1>")
	)
	(arc
		(start 384.877564 -273.12874)
		(mid 384.594862 -273.204516)
		(end 384.31216 -273.12874)
		(width 0.088646)
		(layer "In2.Cu")
		(net "M_E_CPU0_SA_DQS_DP<1>")
	)
	(arc
		(start 387.209538 -273.188176)
		(mid 387.172759 -273.155792)
		(end 387.132068 -273.128486)
		(width 0.088646)
		(layer "In2.Cu")
		(net "M_E_CPU0_SA_DQS_DP<1>")
	)
	(arc
		(start 383.372614 -273.12874)
		(mid 383.185416 -273.078597)
		(end 382.998218 -273.12874)
		(width 0.088646)
		(layer "In2.Cu")
		(net "M_E_CPU0_SA_DQS_DP<1>")
	)
	(arc
		(start 385.817364 -273.12874)
		(mid 385.534662 -273.204516)
		(end 385.25196 -273.12874)
		(width 0.088646)
		(layer "In2.Cu")
		(net "M_E_CPU0_SA_DQS_DP<1>")
	)
	(arc
		(start 386.19176 -273.12874)
		(mid 386.004562 -273.078597)
		(end 385.817364 -273.12874)
		(width 0.088646)
		(layer "In2.Cu")
		(net "M_E_CPU0_SA_DQS_DP<1>")
	)
	(arc
		(start 387.132068 -273.128486)
		(mid 386.944362 -273.078123)
		(end 386.756656 -273.128486)
		(width 0.088646)
		(layer "In2.Cu")
		(net "M_E_CPU0_SA_DQS_DP<1>")
	)
	(arc
		(start 385.25196 -273.12874)
		(mid 385.064762 -273.078597)
		(end 384.877564 -273.12874)
		(width 0.088646)
		(layer "In2.Cu")
		(net "M_E_CPU0_SA_DQS_DP<1>")
	)
	(arc
		(start 383.937764 -273.12874)
		(mid 383.661205 -273.204483)
		(end 383.383028 -273.134836)
		(width 0.088646)
		(layer "In2.Cu")
		(net "M_E_CPU0_SA_DQS_DP<1>")
	)
	(segment
		(start 386.652008 -276.611588)
		(end 386.888482 -276.709886)
		(width 0.088646)
		(layer "F.Cu")
		(net "M_E_CPU0_SA_DQS_DP<0>")
	)
	(segment
		(start 412.362904 -313.347354)
		(end 411.864556 -313.347354)
		(width 0.20066)
		(layer "F.Cu")
		(net "M_E_CPU0_SA_DQS_DP<0>")
	)
	(segment
		(start 388.311644 -293.588694)
		(end 388.844282 -296.264076)
		(width 0.1524)
		(layer "F.Cu")
		(net "M_E_CPU0_SA_DQS_DP<0>")
	)
	(segment
		(start 389.264906 -296.840402)
		(end 389.264906 -296.892218)
		(width 0.1524)
		(layer "F.Cu")
		(net "M_E_CPU0_SA_DQS_DP<0>")
	)
	(segment
		(start 411.858968 -313.341766)
		(end 409.83662 -313.341766)
		(width 0.1016)
		(layer "F.Cu")
		(net "M_E_CPU0_SA_DQS_DP<0>")
	)
	(segment
		(start 387.632194 -277.698454)
		(end 388.311644 -280.64587)
		(width 0.1524)
		(layer "F.Cu")
		(net "M_E_CPU0_SA_DQS_DP<0>")
	)
	(segment
		(start 387.00964 -276.831044)
		(end 387.00964 -277.030688)
		(width 0.088646)
		(layer "F.Cu")
		(net "M_E_CPU0_SA_DQS_DP<0>")
	)
	(segment
		(start 413.359092 -312.634884)
		(end 412.921196 -313.07278)
		(width 0.20066)
		(layer "F.Cu")
		(net "M_E_CPU0_SA_DQS_DP<0>")
	)
	(segment
		(start 387.00964 -277.030688)
		(end 387.253734 -277.274782)
		(width 0.088646)
		(layer "F.Cu")
		(net "M_E_CPU0_SA_DQS_DP<0>")
	)
	(segment
		(start 405.886412 -312.623962)
		(end 406.17902 -312.91657)
		(width 0.20066)
		(layer "F.Cu")
		(net "M_E_CPU0_SA_DQS_DP<0>")
	)
	(segment
		(start 412.921196 -313.07278)
		(end 412.637478 -313.07278)
		(width 0.20066)
		(layer "F.Cu")
		(net "M_E_CPU0_SA_DQS_DP<0>")
	)
	(segment
		(start 406.17902 -312.91657)
		(end 406.753314 -312.91657)
		(width 0.20066)
		(layer "F.Cu")
		(net "M_E_CPU0_SA_DQS_DP<0>")
	)
	(segment
		(start 411.864556 -313.347354)
		(end 411.863794 -313.346592)
		(width 0.20066)
		(layer "F.Cu")
		(net "M_E_CPU0_SA_DQS_DP<0>")
	)
	(segment
		(start 413.854646 -312.91657)
		(end 413.57296 -312.634884)
		(width 0.20066)
		(layer "F.Cu")
		(net "M_E_CPU0_SA_DQS_DP<0>")
	)
	(segment
		(start 387.253734 -277.274782)
		(end 387.253734 -277.319994)
		(width 0.088646)
		(layer "F.Cu")
		(net "M_E_CPU0_SA_DQS_DP<0>")
	)
	(segment
		(start 411.863794 -313.346592)
		(end 411.858968 -313.341766)
		(width 0.1016)
		(layer "F.Cu")
		(net "M_E_CPU0_SA_DQS_DP<0>")
	)
	(segment
		(start 385.594352 -276.742906)
		(end 385.782566 -276.692868)
		(width 0.088646)
		(layer "F.Cu")
		(net "M_E_CPU0_SA_DQS_DP<0>")
	)
	(segment
		(start 389.29183 -296.919142)
		(end 389.61568 -297.242992)
		(width 0.20066)
		(layer "F.Cu")
		(net "M_E_CPU0_SA_DQS_DP<0>")
	)
	(segment
		(start 407.873962 -312.676032)
		(end 407.583132 -312.676032)
		(width 0.20066)
		(layer "F.Cu")
		(net "M_E_CPU0_SA_DQS_DP<0>")
	)
	(segment
		(start 387.269228 -277.335488)
		(end 387.632194 -277.698454)
		(width 0.1524)
		(layer "F.Cu")
		(net "M_E_CPU0_SA_DQS_DP<0>")
	)
	(segment
		(start 407.583132 -312.676032)
		(end 407.342594 -312.91657)
		(width 0.20066)
		(layer "F.Cu")
		(net "M_E_CPU0_SA_DQS_DP<0>")
	)
	(segment
		(start 409.311602 -313.341766)
		(end 409.060396 -313.09056)
		(width 0.20066)
		(layer "F.Cu")
		(net "M_E_CPU0_SA_DQS_DP<0>")
	)
	(segment
		(start 414.297114 -312.91657)
		(end 413.854646 -312.91657)
		(width 0.20066)
		(layer "F.Cu")
		(net "M_E_CPU0_SA_DQS_DP<0>")
	)
	(segment
		(start 389.264906 -296.892218)
		(end 389.29183 -296.919142)
		(width 0.1524)
		(layer "F.Cu")
		(net "M_E_CPU0_SA_DQS_DP<0>")
	)
	(segment
		(start 404.375366 -312.323734)
		(end 405.039068 -312.623962)
		(width 0.20066)
		(layer "F.Cu")
		(net "M_E_CPU0_SA_DQS_DP<0>")
	)
	(segment
		(start 409.831794 -313.341766)
		(end 409.311602 -313.341766)
		(width 0.20066)
		(layer "F.Cu")
		(net "M_E_CPU0_SA_DQS_DP<0>")
	)
	(segment
		(start 389.023098 -296.598594)
		(end 389.264906 -296.840402)
		(width 0.1524)
		(layer "F.Cu")
		(net "M_E_CPU0_SA_DQS_DP<0>")
	)
	(segment
		(start 402.644864 -311.168034)
		(end 404.375366 -312.323734)
		(width 0.20066)
		(layer "F.Cu")
		(net "M_E_CPU0_SA_DQS_DP<0>")
	)
	(segment
		(start 388.311644 -280.64587)
		(end 388.311644 -293.588694)
		(width 0.1524)
		(layer "F.Cu")
		(net "M_E_CPU0_SA_DQS_DP<0>")
	)
	(segment
		(start 386.474716 -276.611588)
		(end 386.652008 -276.611588)
		(width 0.088646)
		(layer "F.Cu")
		(net "M_E_CPU0_SA_DQS_DP<0>")
	)
	(segment
		(start 407.342594 -312.91657)
		(end 406.753314 -312.91657)
		(width 0.20066)
		(layer "F.Cu")
		(net "M_E_CPU0_SA_DQS_DP<0>")
	)
	(segment
		(start 409.83662 -313.341766)
		(end 409.831794 -313.341766)
		(width 0.101854)
		(layer "F.Cu")
		(net "M_E_CPU0_SA_DQS_DP<0>")
	)
	(segment
		(start 412.637478 -313.07278)
		(end 412.362904 -313.347354)
		(width 0.20066)
		(layer "F.Cu")
		(net "M_E_CPU0_SA_DQS_DP<0>")
	)
	(segment
		(start 385.534662 -276.986492)
		(end 385.509008 -276.890734)
		(width 0.088646)
		(layer "F.Cu")
		(net "M_E_CPU0_SA_DQS_DP<0>")
	)
	(segment
		(start 409.060396 -313.09056)
		(end 408.28849 -313.09056)
		(width 0.20066)
		(layer "F.Cu")
		(net "M_E_CPU0_SA_DQS_DP<0>")
	)
	(segment
		(start 387.253734 -277.319994)
		(end 387.269228 -277.335488)
		(width 0.088646)
		(layer "F.Cu")
		(net "M_E_CPU0_SA_DQS_DP<0>")
	)
	(segment
		(start 405.039068 -312.623962)
		(end 405.886412 -312.623962)
		(width 0.20066)
		(layer "F.Cu")
		(net "M_E_CPU0_SA_DQS_DP<0>")
	)
	(segment
		(start 386.888482 -276.709886)
		(end 387.00964 -276.831044)
		(width 0.088646)
		(layer "F.Cu")
		(net "M_E_CPU0_SA_DQS_DP<0>")
	)
	(segment
		(start 385.509008 -276.890734)
		(end 385.594352 -276.742906)
		(width 0.088646)
		(layer "F.Cu")
		(net "M_E_CPU0_SA_DQS_DP<0>")
	)
	(segment
		(start 413.57296 -312.634884)
		(end 413.359092 -312.634884)
		(width 0.20066)
		(layer "F.Cu")
		(net "M_E_CPU0_SA_DQS_DP<0>")
	)
	(segment
		(start 393.718288 -302.241458)
		(end 402.644864 -311.168034)
		(width 0.20066)
		(layer "F.Cu")
		(net "M_E_CPU0_SA_DQS_DP<0>")
	)
	(segment
		(start 408.28849 -313.09056)
		(end 407.873962 -312.676032)
		(width 0.20066)
		(layer "F.Cu")
		(net "M_E_CPU0_SA_DQS_DP<0>")
	)
	(segment
		(start 388.844282 -296.264076)
		(end 389.023098 -296.598594)
		(width 0.1524)
		(layer "F.Cu")
		(net "M_E_CPU0_SA_DQS_DP<0>")
	)
	(segment
		(start 389.61568 -297.242992)
		(end 393.718288 -302.241458)
		(width 0.20066)
		(layer "F.Cu")
		(net "M_E_CPU0_SA_DQS_DP<0>")
	)
	(arc
		(start 386.452872 -276.61235)
		(mid 386.463789 -276.611813)
		(end 386.474716 -276.611588)
		(width 0.088646)
		(layer "F.Cu")
		(net "M_E_CPU0_SA_DQS_DP<0>")
	)
	(arc
		(start 385.782566 -276.692868)
		(mid 385.792812 -276.697158)
		(end 385.80314 -276.70125)
		(width 0.088646)
		(layer "F.Cu")
		(net "M_E_CPU0_SA_DQS_DP<0>")
	)
	(arc
		(start 385.80314 -276.70125)
		(mid 386.049755 -276.736424)
		(end 386.287518 -276.662134)
		(width 0.088646)
		(layer "F.Cu")
		(net "M_E_CPU0_SA_DQS_DP<0>")
	)
	(arc
		(start 386.287518 -276.662134)
		(mid 386.367288 -276.627592)
		(end 386.452872 -276.61235)
		(width 0.088646)
		(layer "F.Cu")
		(net "M_E_CPU0_SA_DQS_DP<0>")
	)
	(segment
		(start 412.91764 -274.241768)
		(end 412.792672 -274.241768)
		(width 0.20066)
		(layer "F.Cu")
		(net "M_E_CPU0_SA_DQS_DN<9>")
	)
	(segment
		(start 387.844284 -259.999988)
		(end 387.988048 -260.143752)
		(width 0.088646)
		(layer "F.Cu")
		(net "M_E_CPU0_SA_DQS_DN<9>")
	)
	(segment
		(start 388.706868 -260.862572)
		(end 388.850632 -261.006336)
		(width 0.088646)
		(layer "F.Cu")
		(net "M_E_CPU0_SA_DQS_DN<9>")
	)
	(segment
		(start 415.296604 -274.241768)
		(end 413.286448 -274.241768)
		(width 0.1016)
		(layer "F.Cu")
		(net "M_E_CPU0_SA_DQS_DN<9>")
	)
	(segment
		(start 418.397182 -274.66671)
		(end 417.8935 -274.66671)
		(width 0.20066)
		(layer "F.Cu")
		(net "M_E_CPU0_SA_DQS_DN<9>")
	)
	(segment
		(start 405.010366 -273.818604)
		(end 405.010366 -274.11553)
		(width 0.20066)
		(layer "F.Cu")
		(net "M_E_CPU0_SA_DQS_DN<9>")
	)
	(segment
		(start 410.347414 -274.66671)
		(end 410.853382 -274.66671)
		(width 0.20066)
		(layer "F.Cu")
		(net "M_E_CPU0_SA_DQS_DN<9>")
	)
	(segment
		(start 386.944362 -259.894832)
		(end 386.933694 -259.884164)
		(width 0.088646)
		(layer "F.Cu")
		(net "M_E_CPU0_SA_DQS_DN<9>")
	)
	(segment
		(start 389.96747 -262.024368)
		(end 389.982964 -262.039862)
		(width 0.088646)
		(layer "F.Cu")
		(net "M_E_CPU0_SA_DQS_DN<9>")
	)
	(segment
		(start 387.12775 -259.71246)
		(end 387.700774 -259.71246)
		(width 0.088646)
		(layer "F.Cu")
		(net "M_E_CPU0_SA_DQS_DN<9>")
	)
	(segment
		(start 412.11246 -274.127976)
		(end 411.844998 -274.395438)
		(width 0.20066)
		(layer "F.Cu")
		(net "M_E_CPU0_SA_DQS_DN<9>")
	)
	(segment
		(start 404.910798 -273.719036)
		(end 405.010366 -273.818604)
		(width 0.20066)
		(layer "F.Cu")
		(net "M_E_CPU0_SA_DQS_DN<9>")
	)
	(segment
		(start 412.792672 -274.241768)
		(end 412.534862 -273.983958)
		(width 0.20066)
		(layer "F.Cu")
		(net "M_E_CPU0_SA_DQS_DN<9>")
	)
	(segment
		(start 387.844284 -259.85597)
		(end 387.844284 -259.999988)
		(width 0.088646)
		(layer "F.Cu")
		(net "M_E_CPU0_SA_DQS_DN<9>")
	)
	(segment
		(start 417.632642 -274.405852)
		(end 417.011612 -274.405852)
		(width 0.20066)
		(layer "F.Cu")
		(net "M_E_CPU0_SA_DQS_DN<9>")
	)
	(segment
		(start 412.534862 -273.983958)
		(end 412.459932 -273.983958)
		(width 0.20066)
		(layer "F.Cu")
		(net "M_E_CPU0_SA_DQS_DN<9>")
	)
	(segment
		(start 405.736552 -274.241514)
		(end 407.742898 -274.241514)
		(width 0.1016)
		(layer "F.Cu")
		(net "M_E_CPU0_SA_DQS_DN<9>")
	)
	(segment
		(start 408.620722 -273.99615)
		(end 409.019756 -274.395184)
		(width 0.20066)
		(layer "F.Cu")
		(net "M_E_CPU0_SA_DQS_DN<9>")
	)
	(segment
		(start 386.933694 -259.884164)
		(end 386.933694 -259.813806)
		(width 0.088646)
		(layer "F.Cu")
		(net "M_E_CPU0_SA_DQS_DN<9>")
	)
	(segment
		(start 401.261072 -273.994118)
		(end 404.225506 -273.994118)
		(width 0.20066)
		(layer "F.Cu")
		(net "M_E_CPU0_SA_DQS_DN<9>")
	)
	(segment
		(start 389.982964 -262.039862)
		(end 399.156936 -271.213834)
		(width 0.1524)
		(layer "F.Cu")
		(net "M_E_CPU0_SA_DQS_DN<9>")
	)
	(segment
		(start 407.881074 -274.241514)
		(end 407.899362 -274.259802)
		(width 0.101854)
		(layer "F.Cu")
		(net "M_E_CPU0_SA_DQS_DN<9>")
	)
	(segment
		(start 388.275576 -260.287262)
		(end 388.275576 -260.43128)
		(width 0.088646)
		(layer "F.Cu")
		(net "M_E_CPU0_SA_DQS_DN<9>")
	)
	(segment
		(start 386.933694 -259.813806)
		(end 387.034786 -259.712714)
		(width 0.088646)
		(layer "F.Cu")
		(net "M_E_CPU0_SA_DQS_DN<9>")
	)
	(segment
		(start 408.355546 -273.99615)
		(end 408.620722 -273.99615)
		(width 0.20066)
		(layer "F.Cu")
		(net "M_E_CPU0_SA_DQS_DN<9>")
	)
	(segment
		(start 415.811462 -274.241768)
		(end 415.72688 -274.241768)
		(width 0.20066)
		(layer "F.Cu")
		(net "M_E_CPU0_SA_DQS_DN<9>")
	)
	(segment
		(start 388.132066 -260.143752)
		(end 388.275576 -260.287262)
		(width 0.088646)
		(layer "F.Cu")
		(net "M_E_CPU0_SA_DQS_DN<9>")
	)
	(segment
		(start 389.104378 -261.260082)
		(end 389.201152 -261.356856)
		(width 0.088646)
		(layer "F.Cu")
		(net "M_E_CPU0_SA_DQS_DN<9>")
	)
	(segment
		(start 408.091894 -274.259802)
		(end 408.355546 -273.99615)
		(width 0.20066)
		(layer "F.Cu")
		(net "M_E_CPU0_SA_DQS_DN<9>")
	)
	(segment
		(start 401.222972 -273.994118)
		(end 401.261072 -273.994118)
		(width 0.1524)
		(layer "F.Cu")
		(net "M_E_CPU0_SA_DQS_DN<9>")
	)
	(segment
		(start 400.483578 -273.957288)
		(end 401.186142 -273.957288)
		(width 0.1524)
		(layer "F.Cu")
		(net "M_E_CPU0_SA_DQS_DN<9>")
	)
	(segment
		(start 388.275576 -260.43128)
		(end 388.41934 -260.575044)
		(width 0.088646)
		(layer "F.Cu")
		(net "M_E_CPU0_SA_DQS_DN<9>")
	)
	(segment
		(start 411.531308 -274.395438)
		(end 411.260036 -274.66671)
		(width 0.20066)
		(layer "F.Cu")
		(net "M_E_CPU0_SA_DQS_DN<9>")
	)
	(segment
		(start 389.344408 -261.356856)
		(end 389.968232 -261.978902)
		(width 0.088646)
		(layer "F.Cu")
		(net "M_E_CPU0_SA_DQS_DN<9>")
	)
	(segment
		(start 389.104378 -261.116064)
		(end 389.104378 -261.260082)
		(width 0.088646)
		(layer "F.Cu")
		(net "M_E_CPU0_SA_DQS_DN<9>")
	)
	(segment
		(start 389.201152 -261.356856)
		(end 389.344408 -261.356856)
		(width 0.088646)
		(layer "F.Cu")
		(net "M_E_CPU0_SA_DQS_DN<9>")
	)
	(segment
		(start 416.5727 -273.96694)
		(end 416.08629 -273.96694)
		(width 0.20066)
		(layer "F.Cu")
		(net "M_E_CPU0_SA_DQS_DN<9>")
	)
	(segment
		(start 387.034786 -259.712714)
		(end 387.127496 -259.712714)
		(width 0.088646)
		(layer "F.Cu")
		(net "M_E_CPU0_SA_DQS_DN<9>")
	)
	(segment
		(start 417.8935 -274.66671)
		(end 417.632642 -274.405852)
		(width 0.20066)
		(layer "F.Cu")
		(net "M_E_CPU0_SA_DQS_DN<9>")
	)
	(segment
		(start 399.922238 -273.657314)
		(end 400.483578 -273.957288)
		(width 0.1524)
		(layer "F.Cu")
		(net "M_E_CPU0_SA_DQS_DN<9>")
	)
	(segment
		(start 407.899362 -274.259802)
		(end 408.091894 -274.259802)
		(width 0.20066)
		(layer "F.Cu")
		(net "M_E_CPU0_SA_DQS_DN<9>")
	)
	(segment
		(start 407.742898 -274.241514)
		(end 407.881074 -274.241514)
		(width 0.101854)
		(layer "F.Cu")
		(net "M_E_CPU0_SA_DQS_DN<9>")
	)
	(segment
		(start 399.156936 -271.213834)
		(end 399.527268 -273.067526)
		(width 0.1524)
		(layer "F.Cu")
		(net "M_E_CPU0_SA_DQS_DN<9>")
	)
	(segment
		(start 399.527268 -273.067526)
		(end 399.922238 -273.657314)
		(width 0.1524)
		(layer "F.Cu")
		(net "M_E_CPU0_SA_DQS_DN<9>")
	)
	(segment
		(start 409.019756 -274.395184)
		(end 410.075888 -274.395184)
		(width 0.20066)
		(layer "F.Cu")
		(net "M_E_CPU0_SA_DQS_DN<9>")
	)
	(segment
		(start 388.41934 -260.575044)
		(end 388.563358 -260.575044)
		(width 0.088646)
		(layer "F.Cu")
		(net "M_E_CPU0_SA_DQS_DN<9>")
	)
	(segment
		(start 405.13635 -274.241514)
		(end 405.45512 -274.241514)
		(width 0.20066)
		(layer "F.Cu")
		(net "M_E_CPU0_SA_DQS_DN<9>")
	)
	(segment
		(start 405.010366 -274.11553)
		(end 405.13635 -274.241514)
		(width 0.20066)
		(layer "F.Cu")
		(net "M_E_CPU0_SA_DQS_DN<9>")
	)
	(segment
		(start 388.563358 -260.575044)
		(end 388.706868 -260.718554)
		(width 0.088646)
		(layer "F.Cu")
		(net "M_E_CPU0_SA_DQS_DN<9>")
	)
	(segment
		(start 387.988048 -260.143752)
		(end 388.132066 -260.143752)
		(width 0.088646)
		(layer "F.Cu")
		(net "M_E_CPU0_SA_DQS_DN<9>")
	)
	(segment
		(start 387.127496 -259.712714)
		(end 387.12775 -259.71246)
		(width 0.088646)
		(layer "F.Cu")
		(net "M_E_CPU0_SA_DQS_DN<9>")
	)
	(segment
		(start 401.186142 -273.957288)
		(end 401.222972 -273.994118)
		(width 0.1524)
		(layer "F.Cu")
		(net "M_E_CPU0_SA_DQS_DN<9>")
	)
	(segment
		(start 389.968232 -261.978902)
		(end 389.96747 -262.024368)
		(width 0.088646)
		(layer "F.Cu")
		(net "M_E_CPU0_SA_DQS_DN<9>")
	)
	(segment
		(start 387.700774 -259.71246)
		(end 387.844284 -259.85597)
		(width 0.088646)
		(layer "F.Cu")
		(net "M_E_CPU0_SA_DQS_DN<9>")
	)
	(segment
		(start 404.225506 -273.994118)
		(end 404.500588 -273.719036)
		(width 0.20066)
		(layer "F.Cu")
		(net "M_E_CPU0_SA_DQS_DN<9>")
	)
	(segment
		(start 388.706868 -260.718554)
		(end 388.706868 -260.862572)
		(width 0.088646)
		(layer "F.Cu")
		(net "M_E_CPU0_SA_DQS_DN<9>")
	)
	(segment
		(start 411.844998 -274.395438)
		(end 411.531308 -274.395438)
		(width 0.20066)
		(layer "F.Cu")
		(net "M_E_CPU0_SA_DQS_DN<9>")
	)
	(segment
		(start 404.500588 -273.719036)
		(end 404.910798 -273.719036)
		(width 0.20066)
		(layer "F.Cu")
		(net "M_E_CPU0_SA_DQS_DN<9>")
	)
	(segment
		(start 412.459932 -273.983958)
		(end 412.11246 -274.127976)
		(width 0.20066)
		(layer "F.Cu")
		(net "M_E_CPU0_SA_DQS_DN<9>")
	)
	(segment
		(start 415.72688 -274.241768)
		(end 415.296604 -274.241768)
		(width 0.101854)
		(layer "F.Cu")
		(net "M_E_CPU0_SA_DQS_DN<9>")
	)
	(segment
		(start 410.075888 -274.395184)
		(end 410.347414 -274.66671)
		(width 0.20066)
		(layer "F.Cu")
		(net "M_E_CPU0_SA_DQS_DN<9>")
	)
	(segment
		(start 417.011612 -274.405852)
		(end 416.5727 -273.96694)
		(width 0.20066)
		(layer "F.Cu")
		(net "M_E_CPU0_SA_DQS_DN<9>")
	)
	(segment
		(start 388.99465 -261.006336)
		(end 389.104378 -261.116064)
		(width 0.088646)
		(layer "F.Cu")
		(net "M_E_CPU0_SA_DQS_DN<9>")
	)
	(segment
		(start 416.08629 -273.96694)
		(end 415.811462 -274.241768)
		(width 0.20066)
		(layer "F.Cu")
		(net "M_E_CPU0_SA_DQS_DN<9>")
	)
	(segment
		(start 388.850632 -261.006336)
		(end 388.99465 -261.006336)
		(width 0.088646)
		(layer "F.Cu")
		(net "M_E_CPU0_SA_DQS_DN<9>")
	)
	(segment
		(start 405.45512 -274.241514)
		(end 405.736552 -274.241514)
		(width 0.101854)
		(layer "F.Cu")
		(net "M_E_CPU0_SA_DQS_DN<9>")
	)
	(segment
		(start 413.286448 -274.241768)
		(end 412.91764 -274.241768)
		(width 0.101854)
		(layer "F.Cu")
		(net "M_E_CPU0_SA_DQS_DN<9>")
	)
	(segment
		(start 411.260036 -274.66671)
		(end 410.853382 -274.66671)
		(width 0.20066)
		(layer "F.Cu")
		(net "M_E_CPU0_SA_DQS_DN<9>")
	)
	(segment
		(start 387.382512 -265.038586)
		(end 387.522974 -265.038586)
		(width 0.088646)
		(layer "F.Cu")
		(net "M_E_CPU0_SA_DQS_DN<8>")
	)
	(segment
		(start 400.037046 -283.697426)
		(end 400.677126 -284.125416)
		(width 0.20066)
		(layer "F.Cu")
		(net "M_E_CPU0_SA_DQS_DN<8>")
	)
	(segment
		(start 387.878828 -265.39444)
		(end 387.985762 -265.501374)
		(width 0.088646)
		(layer "F.Cu")
		(net "M_E_CPU0_SA_DQS_DN<8>")
	)
	(segment
		(start 409.678632 -283.693362)
		(end 410.024072 -283.693362)
		(width 0.20066)
		(layer "F.Cu")
		(net "M_E_CPU0_SA_DQS_DN<8>")
	)
	(segment
		(start 411.65526 -283.745432)
		(end 411.383988 -284.016704)
		(width 0.20066)
		(layer "F.Cu")
		(net "M_E_CPU0_SA_DQS_DN<8>")
	)
	(segment
		(start 397.692626 -281.300936)
		(end 397.692626 -281.353006)
		(width 0.1524)
		(layer "F.Cu")
		(net "M_E_CPU0_SA_DQS_DN<8>")
	)
	(segment
		(start 413.286448 -283.591762)
		(end 413.280352 -283.597858)
		(width 0.1016)
		(layer "F.Cu")
		(net "M_E_CPU0_SA_DQS_DN<8>")
	)
	(segment
		(start 417.639246 -283.76245)
		(end 416.847528 -283.76245)
		(width 0.20066)
		(layer "F.Cu")
		(net "M_E_CPU0_SA_DQS_DN<8>")
	)
	(segment
		(start 405.004524 -283.418026)
		(end 405.205184 -283.618686)
		(width 0.20066)
		(layer "F.Cu")
		(net "M_E_CPU0_SA_DQS_DN<8>")
	)
	(segment
		(start 412.685992 -283.32049)
		(end 412.563564 -283.32049)
		(width 0.20066)
		(layer "F.Cu")
		(net "M_E_CPU0_SA_DQS_DN<8>")
	)
	(segment
		(start 397.270224 -280.78684)
		(end 397.534384 -281.142694)
		(width 0.1524)
		(layer "F.Cu")
		(net "M_E_CPU0_SA_DQS_DN<8>")
	)
	(segment
		(start 388.75208 -266.267438)
		(end 388.75208 -266.31265)
		(width 0.088646)
		(layer "F.Cu")
		(net "M_E_CPU0_SA_DQS_DN<8>")
	)
	(segment
		(start 404.834344 -283.06903)
		(end 405.004524 -283.23921)
		(width 0.20066)
		(layer "F.Cu")
		(net "M_E_CPU0_SA_DQS_DN<8>")
	)
	(segment
		(start 416.847528 -283.76245)
		(end 416.402012 -283.316934)
		(width 0.20066)
		(layer "F.Cu")
		(net "M_E_CPU0_SA_DQS_DN<8>")
	)
	(segment
		(start 400.677126 -284.125416)
		(end 400.943318 -284.235398)
		(width 0.20066)
		(layer "F.Cu")
		(net "M_E_CPU0_SA_DQS_DN<8>")
	)
	(segment
		(start 403.639274 -283.899356)
		(end 403.815296 -283.899356)
		(width 0.20066)
		(layer "F.Cu")
		(net "M_E_CPU0_SA_DQS_DN<8>")
	)
	(segment
		(start 416.402012 -283.316934)
		(end 415.912046 -283.316934)
		(width 0.20066)
		(layer "F.Cu")
		(net "M_E_CPU0_SA_DQS_DN<8>")
	)
	(segment
		(start 388.75208 -266.31265)
		(end 388.767574 -266.328144)
		(width 0.088646)
		(layer "F.Cu")
		(net "M_E_CPU0_SA_DQS_DN<8>")
	)
	(segment
		(start 387.274816 -264.790428)
		(end 387.274816 -264.930636)
		(width 0.088646)
		(layer "F.Cu")
		(net "M_E_CPU0_SA_DQS_DN<8>")
	)
	(segment
		(start 397.534384 -281.142694)
		(end 397.692626 -281.300936)
		(width 0.1524)
		(layer "F.Cu")
		(net "M_E_CPU0_SA_DQS_DN<8>")
	)
	(segment
		(start 415.296604 -283.591762)
		(end 413.286448 -283.591762)
		(width 0.1016)
		(layer "F.Cu")
		(net "M_E_CPU0_SA_DQS_DN<8>")
	)
	(segment
		(start 408.57551 -283.346144)
		(end 408.84094 -283.346144)
		(width 0.20066)
		(layer "F.Cu")
		(net "M_E_CPU0_SA_DQS_DN<8>")
	)
	(segment
		(start 408.312112 -283.609542)
		(end 408.57551 -283.346144)
		(width 0.20066)
		(layer "F.Cu")
		(net "M_E_CPU0_SA_DQS_DN<8>")
	)
	(segment
		(start 402.473414 -284.235398)
		(end 403.09419 -284.235398)
		(width 0.20066)
		(layer "F.Cu")
		(net "M_E_CPU0_SA_DQS_DN<8>")
	)
	(segment
		(start 415.912046 -283.316934)
		(end 415.626296 -283.602684)
		(width 0.20066)
		(layer "F.Cu")
		(net "M_E_CPU0_SA_DQS_DN<8>")
	)
	(segment
		(start 404.4696 -283.06903)
		(end 404.834344 -283.06903)
		(width 0.20066)
		(layer "F.Cu")
		(net "M_E_CPU0_SA_DQS_DN<8>")
	)
	(segment
		(start 412.563564 -283.32049)
		(end 412.138622 -283.745432)
		(width 0.20066)
		(layer "F.Cu")
		(net "M_E_CPU0_SA_DQS_DN<8>")
	)
	(segment
		(start 412.96336 -283.597858)
		(end 412.685992 -283.32049)
		(width 0.20066)
		(layer "F.Cu")
		(net "M_E_CPU0_SA_DQS_DN<8>")
	)
	(segment
		(start 387.985762 -265.642344)
		(end 388.09422 -265.750294)
		(width 0.088646)
		(layer "F.Cu")
		(net "M_E_CPU0_SA_DQS_DN<8>")
	)
	(segment
		(start 408.84094 -283.346144)
		(end 409.678632 -283.693362)
		(width 0.20066)
		(layer "F.Cu")
		(net "M_E_CPU0_SA_DQS_DN<8>")
	)
	(segment
		(start 387.274816 -264.930636)
		(end 387.382512 -265.038586)
		(width 0.088646)
		(layer "F.Cu")
		(net "M_E_CPU0_SA_DQS_DN<8>")
	)
	(segment
		(start 415.626296 -283.602684)
		(end 415.307526 -283.602684)
		(width 0.20066)
		(layer "F.Cu")
		(net "M_E_CPU0_SA_DQS_DN<8>")
	)
	(segment
		(start 411.383988 -284.016704)
		(end 410.853382 -284.016704)
		(width 0.20066)
		(layer "F.Cu")
		(net "M_E_CPU0_SA_DQS_DN<8>")
	)
	(segment
		(start 415.307526 -283.602684)
		(end 415.296604 -283.591762)
		(width 0.1016)
		(layer "F.Cu")
		(net "M_E_CPU0_SA_DQS_DN<8>")
	)
	(segment
		(start 388.09422 -265.750294)
		(end 388.234936 -265.750294)
		(width 0.088646)
		(layer "F.Cu")
		(net "M_E_CPU0_SA_DQS_DN<8>")
	)
	(segment
		(start 395.435582 -272.996152)
		(end 396.828518 -279.960832)
		(width 0.1524)
		(layer "F.Cu")
		(net "M_E_CPU0_SA_DQS_DN<8>")
	)
	(segment
		(start 403.815296 -283.899356)
		(end 404.241254 -283.473398)
		(width 0.20066)
		(layer "F.Cu")
		(net "M_E_CPU0_SA_DQS_DN<8>")
	)
	(segment
		(start 387.158992 -264.674604)
		(end 387.274816 -264.790428)
		(width 0.088646)
		(layer "F.Cu")
		(net "M_E_CPU0_SA_DQS_DN<8>")
	)
	(segment
		(start 396.828518 -279.960832)
		(end 397.270224 -280.78684)
		(width 0.1524)
		(layer "F.Cu")
		(net "M_E_CPU0_SA_DQS_DN<8>")
	)
	(segment
		(start 402.348954 -284.359858)
		(end 402.473414 -284.235398)
		(width 0.20066)
		(layer "F.Cu")
		(net "M_E_CPU0_SA_DQS_DN<8>")
	)
	(segment
		(start 407.745692 -283.591508)
		(end 407.763726 -283.609542)
		(width 0.1016)
		(layer "F.Cu")
		(net "M_E_CPU0_SA_DQS_DN<8>")
	)
	(segment
		(start 401.746974 -284.359858)
		(end 402.348954 -284.359858)
		(width 0.20066)
		(layer "F.Cu")
		(net "M_E_CPU0_SA_DQS_DN<8>")
	)
	(segment
		(start 413.275526 -283.597858)
		(end 412.96336 -283.597858)
		(width 0.20066)
		(layer "F.Cu")
		(net "M_E_CPU0_SA_DQS_DN<8>")
	)
	(segment
		(start 403.45106 -284.08757)
		(end 403.639274 -283.899356)
		(width 0.20066)
		(layer "F.Cu")
		(net "M_E_CPU0_SA_DQS_DN<8>")
	)
	(segment
		(start 403.09419 -284.235398)
		(end 403.45106 -284.08757)
		(width 0.20066)
		(layer "F.Cu")
		(net "M_E_CPU0_SA_DQS_DN<8>")
	)
	(segment
		(start 388.234936 -265.750294)
		(end 388.75208 -266.267438)
		(width 0.088646)
		(layer "F.Cu")
		(net "M_E_CPU0_SA_DQS_DN<8>")
	)
	(segment
		(start 407.763726 -283.609542)
		(end 408.312112 -283.609542)
		(width 0.20066)
		(layer "F.Cu")
		(net "M_E_CPU0_SA_DQS_DN<8>")
	)
	(segment
		(start 387.738366 -265.39444)
		(end 387.878828 -265.39444)
		(width 0.088646)
		(layer "F.Cu")
		(net "M_E_CPU0_SA_DQS_DN<8>")
	)
	(segment
		(start 410.347414 -284.016704)
		(end 410.853382 -284.016704)
		(width 0.20066)
		(layer "F.Cu")
		(net "M_E_CPU0_SA_DQS_DN<8>")
	)
	(segment
		(start 404.241254 -283.473398)
		(end 404.241254 -283.297376)
		(width 0.20066)
		(layer "F.Cu")
		(net "M_E_CPU0_SA_DQS_DN<8>")
	)
	(segment
		(start 405.758904 -283.591508)
		(end 407.745692 -283.591508)
		(width 0.1016)
		(layer "F.Cu")
		(net "M_E_CPU0_SA_DQS_DN<8>")
	)
	(segment
		(start 405.731726 -283.618686)
		(end 405.758904 -283.591508)
		(width 0.1016)
		(layer "F.Cu")
		(net "M_E_CPU0_SA_DQS_DN<8>")
	)
	(segment
		(start 386.944362 -264.763504)
		(end 387.033262 -264.674604)
		(width 0.088646)
		(layer "F.Cu")
		(net "M_E_CPU0_SA_DQS_DN<8>")
	)
	(segment
		(start 412.138622 -283.745432)
		(end 411.65526 -283.745432)
		(width 0.20066)
		(layer "F.Cu")
		(net "M_E_CPU0_SA_DQS_DN<8>")
	)
	(segment
		(start 400.943318 -284.235398)
		(end 401.622514 -284.235398)
		(width 0.20066)
		(layer "F.Cu")
		(net "M_E_CPU0_SA_DQS_DN<8>")
	)
	(segment
		(start 388.767574 -266.328144)
		(end 395.435582 -272.996152)
		(width 0.1524)
		(layer "F.Cu")
		(net "M_E_CPU0_SA_DQS_DN<8>")
	)
	(segment
		(start 404.241254 -283.297376)
		(end 404.4696 -283.06903)
		(width 0.20066)
		(layer "F.Cu")
		(net "M_E_CPU0_SA_DQS_DN<8>")
	)
	(segment
		(start 387.63067 -265.146282)
		(end 387.63067 -265.28649)
		(width 0.088646)
		(layer "F.Cu")
		(net "M_E_CPU0_SA_DQS_DN<8>")
	)
	(segment
		(start 413.280352 -283.597858)
		(end 413.275526 -283.597858)
		(width 0.101854)
		(layer "F.Cu")
		(net "M_E_CPU0_SA_DQS_DN<8>")
	)
	(segment
		(start 386.944362 -264.778236)
		(end 386.944362 -264.763504)
		(width 0.088646)
		(layer "F.Cu")
		(net "M_E_CPU0_SA_DQS_DN<8>")
	)
	(segment
		(start 417.8935 -284.016704)
		(end 417.639246 -283.76245)
		(width 0.20066)
		(layer "F.Cu")
		(net "M_E_CPU0_SA_DQS_DN<8>")
	)
	(segment
		(start 397.719042 -281.379422)
		(end 400.037046 -283.697426)
		(width 0.20066)
		(layer "F.Cu")
		(net "M_E_CPU0_SA_DQS_DN<8>")
	)
	(segment
		(start 401.622514 -284.235398)
		(end 401.746974 -284.359858)
		(width 0.20066)
		(layer "F.Cu")
		(net "M_E_CPU0_SA_DQS_DN<8>")
	)
	(segment
		(start 387.033262 -264.674604)
		(end 387.158992 -264.674604)
		(width 0.088646)
		(layer "F.Cu")
		(net "M_E_CPU0_SA_DQS_DN<8>")
	)
	(segment
		(start 387.985762 -265.501374)
		(end 387.985762 -265.642344)
		(width 0.088646)
		(layer "F.Cu")
		(net "M_E_CPU0_SA_DQS_DN<8>")
	)
	(segment
		(start 418.397182 -284.016704)
		(end 417.8935 -284.016704)
		(width 0.20066)
		(layer "F.Cu")
		(net "M_E_CPU0_SA_DQS_DN<8>")
	)
	(segment
		(start 405.004524 -283.23921)
		(end 405.004524 -283.418026)
		(width 0.20066)
		(layer "F.Cu")
		(net "M_E_CPU0_SA_DQS_DN<8>")
	)
	(segment
		(start 387.63067 -265.28649)
		(end 387.738366 -265.39444)
		(width 0.088646)
		(layer "F.Cu")
		(net "M_E_CPU0_SA_DQS_DN<8>")
	)
	(segment
		(start 410.024072 -283.693362)
		(end 410.347414 -284.016704)
		(width 0.20066)
		(layer "F.Cu")
		(net "M_E_CPU0_SA_DQS_DN<8>")
	)
	(segment
		(start 397.692626 -281.353006)
		(end 397.719042 -281.379422)
		(width 0.1524)
		(layer "F.Cu")
		(net "M_E_CPU0_SA_DQS_DN<8>")
	)
	(segment
		(start 387.522974 -265.038586)
		(end 387.63067 -265.146282)
		(width 0.088646)
		(layer "F.Cu")
		(net "M_E_CPU0_SA_DQS_DN<8>")
	)
	(segment
		(start 405.205184 -283.618686)
		(end 405.731726 -283.618686)
		(width 0.20066)
		(layer "F.Cu")
		(net "M_E_CPU0_SA_DQS_DN<8>")
	)
	(segment
		(start 417.098734 -293.112444)
		(end 416.670744 -292.935152)
		(width 0.20066)
		(layer "F.Cu")
		(net "M_E_CPU0_SA_DQS_DN<7>")
	)
	(segment
		(start 393.074652 -288.830766)
		(end 393.074652 -288.882836)
		(width 0.1524)
		(layer "F.Cu")
		(net "M_E_CPU0_SA_DQS_DN<7>")
	)
	(segment
		(start 387.867906 -270.389604)
		(end 387.867906 -270.873728)
		(width 0.088646)
		(layer "F.Cu")
		(net "M_E_CPU0_SA_DQS_DN<7>")
	)
	(segment
		(start 416.670744 -292.935152)
		(end 416.40252 -292.666928)
		(width 0.20066)
		(layer "F.Cu")
		(net "M_E_CPU0_SA_DQS_DN<7>")
	)
	(segment
		(start 404.810976 -292.90645)
		(end 404.868634 -292.767258)
		(width 0.20066)
		(layer "F.Cu")
		(net "M_E_CPU0_SA_DQS_DN<7>")
	)
	(segment
		(start 404.422356 -293.488364)
		(end 404.810976 -292.90645)
		(width 0.20066)
		(layer "F.Cu")
		(net "M_E_CPU0_SA_DQS_DN<7>")
	)
	(segment
		(start 407.763726 -292.948106)
		(end 408.082242 -292.948106)
		(width 0.20066)
		(layer "F.Cu")
		(net "M_E_CPU0_SA_DQS_DN<7>")
	)
	(segment
		(start 393.101576 -288.90976)
		(end 399.041112 -294.849296)
		(width 0.20066)
		(layer "F.Cu")
		(net "M_E_CPU0_SA_DQS_DN<7>")
	)
	(segment
		(start 409.8036 -293.095172)
		(end 410.075888 -293.095172)
		(width 0.20066)
		(layer "F.Cu")
		(net "M_E_CPU0_SA_DQS_DN<7>")
	)
	(segment
		(start 392.882628 -280.27122)
		(end 392.882628 -288.638742)
		(width 0.1524)
		(layer "F.Cu")
		(net "M_E_CPU0_SA_DQS_DN<7>")
	)
	(segment
		(start 387.76402 -270.139668)
		(end 387.867906 -270.389604)
		(width 0.088646)
		(layer "F.Cu")
		(net "M_E_CPU0_SA_DQS_DN<7>")
	)
	(segment
		(start 416.40252 -292.666928)
		(end 415.912046 -292.666928)
		(width 0.20066)
		(layer "F.Cu")
		(net "M_E_CPU0_SA_DQS_DN<7>")
	)
	(segment
		(start 386.001006 -269.29969)
		(end 386.105146 -269.29969)
		(width 0.088646)
		(layer "F.Cu")
		(net "M_E_CPU0_SA_DQS_DN<7>")
	)
	(segment
		(start 413.286448 -292.941756)
		(end 413.280352 -292.947852)
		(width 0.1016)
		(layer "F.Cu")
		(net "M_E_CPU0_SA_DQS_DN<7>")
	)
	(segment
		(start 399.859246 -295.251124)
		(end 400.244818 -295.327832)
		(width 0.20066)
		(layer "F.Cu")
		(net "M_E_CPU0_SA_DQS_DN<7>")
	)
	(segment
		(start 385.379468 -270.20647)
		(end 385.404614 -270.113506)
		(width 0.088646)
		(layer "F.Cu")
		(net "M_E_CPU0_SA_DQS_DN<7>")
	)
	(segment
		(start 402.946108 -294.873172)
		(end 403.221698 -294.689022)
		(width 0.20066)
		(layer "F.Cu")
		(net "M_E_CPU0_SA_DQS_DN<7>")
	)
	(segment
		(start 415.912046 -292.666928)
		(end 415.626296 -292.952678)
		(width 0.20066)
		(layer "F.Cu")
		(net "M_E_CPU0_SA_DQS_DN<7>")
	)
	(segment
		(start 412.96336 -292.947852)
		(end 412.685992 -292.670484)
		(width 0.20066)
		(layer "F.Cu")
		(net "M_E_CPU0_SA_DQS_DN<7>")
	)
	(segment
		(start 412.524448 -292.670484)
		(end 412.099506 -293.095426)
		(width 0.20066)
		(layer "F.Cu")
		(net "M_E_CPU0_SA_DQS_DN<7>")
	)
	(segment
		(start 392.882628 -288.638742)
		(end 393.074652 -288.830766)
		(width 0.1524)
		(layer "F.Cu")
		(net "M_E_CPU0_SA_DQS_DN<7>")
	)
	(segment
		(start 410.347414 -293.366698)
		(end 410.853382 -293.366698)
		(width 0.20066)
		(layer "F.Cu")
		(net "M_E_CPU0_SA_DQS_DN<7>")
	)
	(segment
		(start 405.750776 -292.941756)
		(end 407.710894 -292.941756)
		(width 0.1016)
		(layer "F.Cu")
		(net "M_E_CPU0_SA_DQS_DN<7>")
	)
	(segment
		(start 388.135876 -271.277842)
		(end 388.135876 -271.323054)
		(width 0.088646)
		(layer "F.Cu")
		(net "M_E_CPU0_SA_DQS_DN<7>")
	)
	(segment
		(start 402.016722 -295.327832)
		(end 402.669756 -295.05783)
		(width 0.20066)
		(layer "F.Cu")
		(net "M_E_CPU0_SA_DQS_DN<7>")
	)
	(segment
		(start 408.082242 -292.948106)
		(end 408.349958 -292.68039)
		(width 0.20066)
		(layer "F.Cu")
		(net "M_E_CPU0_SA_DQS_DN<7>")
	)
	(segment
		(start 418.397182 -293.366698)
		(end 417.8935 -293.366698)
		(width 0.20066)
		(layer "F.Cu")
		(net "M_E_CPU0_SA_DQS_DN<7>")
	)
	(segment
		(start 408.80284 -292.68039)
		(end 409.8036 -293.095172)
		(width 0.20066)
		(layer "F.Cu")
		(net "M_E_CPU0_SA_DQS_DN<7>")
	)
	(segment
		(start 385.727702 -269.425928)
		(end 385.749546 -269.40383)
		(width 0.088646)
		(layer "F.Cu")
		(net "M_E_CPU0_SA_DQS_DN<7>")
	)
	(segment
		(start 386.848604 -269.378684)
		(end 387.112002 -269.487904)
		(width 0.088646)
		(layer "F.Cu")
		(net "M_E_CPU0_SA_DQS_DN<7>")
	)
	(segment
		(start 407.717244 -292.948106)
		(end 407.763726 -292.948106)
		(width 0.101854)
		(layer "F.Cu")
		(net "M_E_CPU0_SA_DQS_DN<7>")
	)
	(segment
		(start 386.421884 -269.378684)
		(end 386.848604 -269.378684)
		(width 0.088646)
		(layer "F.Cu")
		(net "M_E_CPU0_SA_DQS_DN<7>")
	)
	(segment
		(start 411.65526 -293.095426)
		(end 411.383988 -293.366698)
		(width 0.20066)
		(layer "F.Cu")
		(net "M_E_CPU0_SA_DQS_DN<7>")
	)
	(segment
		(start 408.349958 -292.68039)
		(end 408.80284 -292.68039)
		(width 0.20066)
		(layer "F.Cu")
		(net "M_E_CPU0_SA_DQS_DN<7>")
	)
	(segment
		(start 387.963918 -271.106138)
		(end 388.033006 -271.174972)
		(width 0.088646)
		(layer "F.Cu")
		(net "M_E_CPU0_SA_DQS_DN<7>")
	)
	(segment
		(start 399.283682 -295.011856)
		(end 399.859246 -295.251124)
		(width 0.20066)
		(layer "F.Cu")
		(net "M_E_CPU0_SA_DQS_DN<7>")
	)
	(segment
		(start 387.112002 -269.487904)
		(end 387.76402 -270.139668)
		(width 0.088646)
		(layer "F.Cu")
		(net "M_E_CPU0_SA_DQS_DN<7>")
	)
	(segment
		(start 411.383988 -293.366698)
		(end 410.853382 -293.366698)
		(width 0.20066)
		(layer "F.Cu")
		(net "M_E_CPU0_SA_DQS_DN<7>")
	)
	(segment
		(start 412.685992 -292.670484)
		(end 412.524448 -292.670484)
		(width 0.20066)
		(layer "F.Cu")
		(net "M_E_CPU0_SA_DQS_DN<7>")
	)
	(segment
		(start 417.639246 -293.112444)
		(end 417.098734 -293.112444)
		(width 0.20066)
		(layer "F.Cu")
		(net "M_E_CPU0_SA_DQS_DN<7>")
	)
	(segment
		(start 393.074652 -288.882836)
		(end 393.101576 -288.90976)
		(width 0.1524)
		(layer "F.Cu")
		(net "M_E_CPU0_SA_DQS_DN<7>")
	)
	(segment
		(start 404.868634 -292.767258)
		(end 405.00046 -292.635432)
		(width 0.20066)
		(layer "F.Cu")
		(net "M_E_CPU0_SA_DQS_DN<7>")
	)
	(segment
		(start 417.8935 -293.366698)
		(end 417.639246 -293.112444)
		(width 0.20066)
		(layer "F.Cu")
		(net "M_E_CPU0_SA_DQS_DN<7>")
	)
	(segment
		(start 405.731726 -292.954456)
		(end 405.738076 -292.954456)
		(width 0.101854)
		(layer "F.Cu")
		(net "M_E_CPU0_SA_DQS_DN<7>")
	)
	(segment
		(start 415.296604 -292.941756)
		(end 413.286448 -292.941756)
		(width 0.1016)
		(layer "F.Cu")
		(net "M_E_CPU0_SA_DQS_DN<7>")
	)
	(segment
		(start 391.829544 -275.016722)
		(end 392.882628 -280.27122)
		(width 0.1524)
		(layer "F.Cu")
		(net "M_E_CPU0_SA_DQS_DN<7>")
	)
	(segment
		(start 413.280352 -292.947852)
		(end 413.275526 -292.947852)
		(width 0.101854)
		(layer "F.Cu")
		(net "M_E_CPU0_SA_DQS_DN<7>")
	)
	(segment
		(start 412.099506 -293.095426)
		(end 411.65526 -293.095426)
		(width 0.20066)
		(layer "F.Cu")
		(net "M_E_CPU0_SA_DQS_DN<7>")
	)
	(segment
		(start 405.477218 -292.954456)
		(end 405.731726 -292.954456)
		(width 0.20066)
		(layer "F.Cu")
		(net "M_E_CPU0_SA_DQS_DN<7>")
	)
	(segment
		(start 388.135876 -271.323054)
		(end 388.15137 -271.338548)
		(width 0.088646)
		(layer "F.Cu")
		(net "M_E_CPU0_SA_DQS_DN<7>")
	)
	(segment
		(start 388.15137 -271.338548)
		(end 391.829544 -275.016722)
		(width 0.1524)
		(layer "F.Cu")
		(net "M_E_CPU0_SA_DQS_DN<7>")
	)
	(segment
		(start 405.00046 -292.635432)
		(end 405.158194 -292.635432)
		(width 0.20066)
		(layer "F.Cu")
		(net "M_E_CPU0_SA_DQS_DN<7>")
	)
	(segment
		(start 415.626296 -292.952678)
		(end 415.307526 -292.952678)
		(width 0.20066)
		(layer "F.Cu")
		(net "M_E_CPU0_SA_DQS_DN<7>")
	)
	(segment
		(start 413.275526 -292.947852)
		(end 412.96336 -292.947852)
		(width 0.20066)
		(layer "F.Cu")
		(net "M_E_CPU0_SA_DQS_DN<7>")
	)
	(segment
		(start 385.629912 -269.671546)
		(end 385.629912 -269.66164)
		(width 0.088646)
		(layer "F.Cu")
		(net "M_E_CPU0_SA_DQS_DN<7>")
	)
	(segment
		(start 410.075888 -293.095172)
		(end 410.347414 -293.366698)
		(width 0.20066)
		(layer "F.Cu")
		(net "M_E_CPU0_SA_DQS_DN<7>")
	)
	(segment
		(start 399.041112 -294.849296)
		(end 399.283682 -295.011856)
		(width 0.20066)
		(layer "F.Cu")
		(net "M_E_CPU0_SA_DQS_DN<7>")
	)
	(segment
		(start 405.738076 -292.954456)
		(end 405.750776 -292.941756)
		(width 0.1016)
		(layer "F.Cu")
		(net "M_E_CPU0_SA_DQS_DN<7>")
	)
	(segment
		(start 385.534662 -270.475456)
		(end 385.379468 -270.20647)
		(width 0.088646)
		(layer "F.Cu")
		(net "M_E_CPU0_SA_DQS_DN<7>")
	)
	(segment
		(start 405.158194 -292.635432)
		(end 405.477218 -292.954456)
		(width 0.20066)
		(layer "F.Cu")
		(net "M_E_CPU0_SA_DQS_DN<7>")
	)
	(segment
		(start 407.710894 -292.941756)
		(end 407.717244 -292.948106)
		(width 0.101854)
		(layer "F.Cu")
		(net "M_E_CPU0_SA_DQS_DN<7>")
	)
	(segment
		(start 400.244818 -295.327832)
		(end 402.016722 -295.327832)
		(width 0.20066)
		(layer "F.Cu")
		(net "M_E_CPU0_SA_DQS_DN<7>")
	)
	(segment
		(start 402.669756 -295.05783)
		(end 402.946108 -294.873172)
		(width 0.20066)
		(layer "F.Cu")
		(net "M_E_CPU0_SA_DQS_DN<7>")
	)
	(segment
		(start 415.307526 -292.952678)
		(end 415.296604 -292.941756)
		(width 0.1016)
		(layer "F.Cu")
		(net "M_E_CPU0_SA_DQS_DN<7>")
	)
	(segment
		(start 388.033006 -271.174972)
		(end 388.135876 -271.277842)
		(width 0.088646)
		(layer "F.Cu")
		(net "M_E_CPU0_SA_DQS_DN<7>")
	)
	(segment
		(start 403.221698 -294.689022)
		(end 404.422356 -293.488364)
		(width 0.20066)
		(layer "F.Cu")
		(net "M_E_CPU0_SA_DQS_DN<7>")
	)
	(segment
		(start 387.867906 -270.873728)
		(end 387.963918 -271.106138)
		(width 0.088646)
		(layer "F.Cu")
		(net "M_E_CPU0_SA_DQS_DN<7>")
	)
	(arc
		(start 385.404614 -270.113506)
		(mid 385.413059 -270.106982)
		(end 385.421378 -270.100298)
		(width 0.088646)
		(layer "F.Cu")
		(net "M_E_CPU0_SA_DQS_DN<7>")
	)
	(arc
		(start 385.421378 -270.100298)
		(mid 385.573018 -269.908975)
		(end 385.629912 -269.671546)
		(width 0.088646)
		(layer "F.Cu")
		(net "M_E_CPU0_SA_DQS_DN<7>")
	)
	(arc
		(start 386.105146 -269.29969)
		(mid 386.140612 -269.303967)
		(end 386.17398 -269.316708)
		(width 0.088646)
		(layer "F.Cu")
		(net "M_E_CPU0_SA_DQS_DN<7>")
	)
	(arc
		(start 386.17398 -269.316708)
		(mid 386.294121 -269.362947)
		(end 386.421884 -269.378684)
		(width 0.088646)
		(layer "F.Cu")
		(net "M_E_CPU0_SA_DQS_DN<7>")
	)
	(arc
		(start 385.629912 -269.66164)
		(mid 385.655381 -269.534068)
		(end 385.727702 -269.425928)
		(width 0.088646)
		(layer "F.Cu")
		(net "M_E_CPU0_SA_DQS_DN<7>")
	)
	(arc
		(start 385.749546 -269.40383)
		(mid 385.864917 -269.326742)
		(end 386.001006 -269.29969)
		(width 0.088646)
		(layer "F.Cu")
		(net "M_E_CPU0_SA_DQS_DN<7>")
	)
	(segment
		(start 415.307526 -302.29683)
		(end 415.302446 -302.29175)
		(width 0.1016)
		(layer "F.Cu")
		(net "M_E_CPU0_SA_DQS_DN<6>")
	)
	(segment
		(start 413.285432 -302.29175)
		(end 413.280352 -302.29683)
		(width 0.1016)
		(layer "F.Cu")
		(net "M_E_CPU0_SA_DQS_DN<6>")
	)
	(segment
		(start 417.8935 -302.716692)
		(end 417.639246 -302.462438)
		(width 0.20066)
		(layer "F.Cu")
		(net "M_E_CPU0_SA_DQS_DN<6>")
	)
	(segment
		(start 413.280352 -302.29683)
		(end 413.275526 -302.29683)
		(width 0.101854)
		(layer "F.Cu")
		(net "M_E_CPU0_SA_DQS_DN<6>")
	)
	(segment
		(start 413.274764 -302.297592)
		(end 412.963106 -302.297592)
		(width 0.20066)
		(layer "F.Cu")
		(net "M_E_CPU0_SA_DQS_DN<6>")
	)
	(segment
		(start 413.275526 -302.29683)
		(end 413.274764 -302.297592)
		(width 0.20066)
		(layer "F.Cu")
		(net "M_E_CPU0_SA_DQS_DN<6>")
	)
	(segment
		(start 412.963106 -302.297592)
		(end 412.685992 -302.020478)
		(width 0.20066)
		(layer "F.Cu")
		(net "M_E_CPU0_SA_DQS_DN<6>")
	)
	(segment
		(start 417.068508 -302.462438)
		(end 416.622992 -302.016922)
		(width 0.20066)
		(layer "F.Cu")
		(net "M_E_CPU0_SA_DQS_DN<6>")
	)
	(segment
		(start 415.302446 -302.29175)
		(end 413.285432 -302.29175)
		(width 0.1016)
		(layer "F.Cu")
		(net "M_E_CPU0_SA_DQS_DN<6>")
	)
	(segment
		(start 415.631376 -302.297592)
		(end 415.308288 -302.297592)
		(width 0.20066)
		(layer "F.Cu")
		(net "M_E_CPU0_SA_DQS_DN<6>")
	)
	(segment
		(start 412.563564 -302.020478)
		(end 412.138622 -302.44542)
		(width 0.20066)
		(layer "F.Cu")
		(net "M_E_CPU0_SA_DQS_DN<6>")
	)
	(segment
		(start 415.912046 -302.016922)
		(end 415.631376 -302.297592)
		(width 0.20066)
		(layer "F.Cu")
		(net "M_E_CPU0_SA_DQS_DN<6>")
	)
	(segment
		(start 410.853382 -302.716692)
		(end 409.723082 -302.716692)
		(width 0.20066)
		(layer "F.Cu")
		(net "M_E_CPU0_SA_DQS_DN<6>")
	)
	(segment
		(start 412.685992 -302.020478)
		(end 412.563564 -302.020478)
		(width 0.20066)
		(layer "F.Cu")
		(net "M_E_CPU0_SA_DQS_DN<6>")
	)
	(segment
		(start 411.383988 -302.716692)
		(end 410.853382 -302.716692)
		(width 0.20066)
		(layer "F.Cu")
		(net "M_E_CPU0_SA_DQS_DN<6>")
	)
	(segment
		(start 415.308288 -302.297592)
		(end 415.307526 -302.29683)
		(width 0.20066)
		(layer "F.Cu")
		(net "M_E_CPU0_SA_DQS_DN<6>")
	)
	(segment
		(start 417.639246 -302.462438)
		(end 417.068508 -302.462438)
		(width 0.20066)
		(layer "F.Cu")
		(net "M_E_CPU0_SA_DQS_DN<6>")
	)
	(segment
		(start 383.655062 -272.103342)
		(end 383.655062 -272.639282)
		(width 0.20066)
		(layer "F.Cu")
		(net "M_E_CPU0_SA_DQS_DN<6>")
	)
	(segment
		(start 418.397182 -302.716692)
		(end 417.8935 -302.716692)
		(width 0.20066)
		(layer "F.Cu")
		(net "M_E_CPU0_SA_DQS_DN<6>")
	)
	(segment
		(start 416.622992 -302.016922)
		(end 415.912046 -302.016922)
		(width 0.20066)
		(layer "F.Cu")
		(net "M_E_CPU0_SA_DQS_DN<6>")
	)
	(segment
		(start 411.65526 -302.44542)
		(end 411.383988 -302.716692)
		(width 0.20066)
		(layer "F.Cu")
		(net "M_E_CPU0_SA_DQS_DN<6>")
	)
	(segment
		(start 412.138622 -302.44542)
		(end 411.65526 -302.44542)
		(width 0.20066)
		(layer "F.Cu")
		(net "M_E_CPU0_SA_DQS_DN<6>")
	)
	(segment
		(start 406.847548 -301.997872)
		(end 406.131268 -301.997872)
		(width 0.18288)
		(layer "In2.Cu")
		(net "M_E_CPU0_SA_DQS_DN<6>")
	)
	(segment
		(start 383.667 -272.48993)
		(end 383.655062 -272.639282)
		(width 0.088646)
		(layer "In2.Cu")
		(net "M_E_CPU0_SA_DQS_DN<6>")
	)
	(segment
		(start 403.776688 -297.596306)
		(end 403.652228 -297.471846)
		(width 0.18288)
		(layer "In2.Cu")
		(net "M_E_CPU0_SA_DQS_DN<6>")
	)
	(segment
		(start 401.34032 -290.306506)
		(end 401.340066 -290.305998)
		(width 0.18288)
		(layer "In2.Cu")
		(net "M_E_CPU0_SA_DQS_DN<6>")
	)
	(segment
		(start 405.467312 -302.293782)
		(end 405.139906 -301.966376)
		(width 0.18288)
		(layer "In2.Cu")
		(net "M_E_CPU0_SA_DQS_DN<6>")
	)
	(segment
		(start 407.147522 -302.122332)
		(end 406.847548 -301.997872)
		(width 0.18288)
		(layer "In2.Cu")
		(net "M_E_CPU0_SA_DQS_DN<6>")
	)
	(segment
		(start 403.549866 -295.64076)
		(end 403.387052 -295.57345)
		(width 0.18288)
		(layer "In2.Cu")
		(net "M_E_CPU0_SA_DQS_DN<6>")
	)
	(segment
		(start 402.02485 -292.283896)
		(end 402.09216 -292.121336)
		(width 0.18288)
		(layer "In2.Cu")
		(net "M_E_CPU0_SA_DQS_DN<6>")
	)
	(segment
		(start 407.967434 -302.608488)
		(end 407.698194 -302.496982)
		(width 0.18288)
		(layer "In2.Cu")
		(net "M_E_CPU0_SA_DQS_DN<6>")
	)
	(segment
		(start 403.776688 -298.942506)
		(end 403.652228 -298.818046)
		(width 0.18288)
		(layer "In2.Cu")
		(net "M_E_CPU0_SA_DQS_DN<6>")
	)
	(segment
		(start 383.888488 -272.39087)
		(end 383.775966 -272.413476)
		(width 0.088646)
		(layer "In2.Cu")
		(net "M_E_CPU0_SA_DQS_DN<6>")
	)
	(segment
		(start 402.234654 -292.791134)
		(end 402.02485 -292.283896)
		(width 0.18288)
		(layer "In2.Cu")
		(net "M_E_CPU0_SA_DQS_DN<6>")
	)
	(segment
		(start 398.784064 -287.750504)
		(end 397.956532 -285.752032)
		(width 0.18288)
		(layer "In2.Cu")
		(net "M_E_CPU0_SA_DQS_DN<6>")
	)
	(segment
		(start 401.482814 -290.975796)
		(end 401.550124 -290.813236)
		(width 0.18288)
		(layer "In2.Cu")
		(net "M_E_CPU0_SA_DQS_DN<6>")
	)
	(segment
		(start 401.340066 -290.305998)
		(end 401.339558 -290.305998)
		(width 0.18288)
		(layer "In2.Cu")
		(net "M_E_CPU0_SA_DQS_DN<6>")
	)
	(segment
		(start 407.448004 -302.246792)
		(end 407.147522 -302.122332)
		(width 0.18288)
		(layer "In2.Cu")
		(net "M_E_CPU0_SA_DQS_DN<6>")
	)
	(segment
		(start 403.652228 -296.923206)
		(end 403.776688 -296.798746)
		(width 0.18288)
		(layer "In2.Cu")
		(net "M_E_CPU0_SA_DQS_DN<6>")
	)
	(segment
		(start 401.692872 -291.483034)
		(end 401.482814 -290.975796)
		(width 0.18288)
		(layer "In2.Cu")
		(net "M_E_CPU0_SA_DQS_DN<6>")
	)
	(segment
		(start 403.776688 -299.959268)
		(end 403.776688 -298.942506)
		(width 0.18288)
		(layer "In2.Cu")
		(net "M_E_CPU0_SA_DQS_DN<6>")
	)
	(segment
		(start 384.11658 -272.39087)
		(end 383.888488 -272.39087)
		(width 0.088646)
		(layer "In2.Cu")
		(net "M_E_CPU0_SA_DQS_DN<6>")
	)
	(segment
		(start 392.973306 -276.676104)
		(end 389.747506 -273.45005)
		(width 0.18288)
		(layer "In2.Cu")
		(net "M_E_CPU0_SA_DQS_DN<6>")
	)
	(segment
		(start 399.435574 -288.578036)
		(end 399.435574 -288.402014)
		(width 0.18288)
		(layer "In2.Cu")
		(net "M_E_CPU0_SA_DQS_DN<6>")
	)
	(segment
		(start 402.09216 -292.121336)
		(end 401.855686 -291.550344)
		(width 0.18288)
		(layer "In2.Cu")
		(net "M_E_CPU0_SA_DQS_DN<6>")
	)
	(segment
		(start 408.868626 -302.448722)
		(end 408.483054 -302.608488)
		(width 0.18288)
		(layer "In2.Cu")
		(net "M_E_CPU0_SA_DQS_DN<6>")
	)
	(segment
		(start 401.855686 -291.550344)
		(end 401.692872 -291.483034)
		(width 0.18288)
		(layer "In2.Cu")
		(net "M_E_CPU0_SA_DQS_DN<6>")
	)
	(segment
		(start 389.747506 -273.45005)
		(end 389.450326 -273.15287)
		(width 0.18288)
		(layer "In2.Cu")
		(net "M_E_CPU0_SA_DQS_DN<6>")
	)
	(segment
		(start 384.405124 -272.316448)
		(end 384.40233 -272.318226)
		(width 0.088646)
		(layer "In2.Cu")
		(net "M_E_CPU0_SA_DQS_DN<6>")
	)
	(segment
		(start 406.131268 -301.997872)
		(end 405.835358 -302.293782)
		(width 0.18288)
		(layer "In2.Cu")
		(net "M_E_CPU0_SA_DQS_DN<6>")
	)
	(segment
		(start 403.776688 -296.798746)
		(end 403.776688 -296.188384)
		(width 0.18288)
		(layer "In2.Cu")
		(net "M_E_CPU0_SA_DQS_DN<6>")
	)
	(segment
		(start 402.397468 -292.858444)
		(end 402.234654 -292.791134)
		(width 0.18288)
		(layer "In2.Cu")
		(net "M_E_CPU0_SA_DQS_DN<6>")
	)
	(segment
		(start 403.387052 -295.57345)
		(end 403.177248 -295.066212)
		(width 0.18288)
		(layer "In2.Cu")
		(net "M_E_CPU0_SA_DQS_DN<6>")
	)
	(segment
		(start 403.652228 -298.269406)
		(end 403.776688 -298.144946)
		(width 0.18288)
		(layer "In2.Cu")
		(net "M_E_CPU0_SA_DQS_DN<6>")
	)
	(segment
		(start 385.347464 -272.314924)
		(end 385.332732 -272.32356)
		(width 0.088646)
		(layer "In2.Cu")
		(net "M_E_CPU0_SA_DQS_DN<6>")
	)
	(segment
		(start 384.406902 -272.315432)
		(end 384.405124 -272.316448)
		(width 0.088646)
		(layer "In2.Cu")
		(net "M_E_CPU0_SA_DQS_DN<6>")
	)
	(segment
		(start 394.170154 -279.565354)
		(end 392.973306 -276.676104)
		(width 0.18288)
		(layer "In2.Cu")
		(net "M_E_CPU0_SA_DQS_DN<6>")
	)
	(segment
		(start 400.775678 -289.91814)
		(end 400.387566 -289.530028)
		(width 0.18288)
		(layer "In2.Cu")
		(net "M_E_CPU0_SA_DQS_DN<6>")
	)
	(segment
		(start 401.339558 -290.305998)
		(end 400.9517 -289.91814)
		(width 0.18288)
		(layer "In2.Cu")
		(net "M_E_CPU0_SA_DQS_DN<6>")
	)
	(segment
		(start 388.840726 -273.15287)
		(end 388.781036 -273.09318)
		(width 0.088646)
		(layer "In2.Cu")
		(net "M_E_CPU0_SA_DQS_DN<6>")
	)
	(segment
		(start 383.775966 -272.413476)
		(end 383.775458 -272.413476)
		(width 0.088646)
		(layer "In2.Cu")
		(net "M_E_CPU0_SA_DQS_DN<6>")
	)
	(segment
		(start 386.287264 -272.314924)
		(end 386.272532 -272.32356)
		(width 0.088646)
		(layer "In2.Cu")
		(net "M_E_CPU0_SA_DQS_DN<6>")
	)
	(segment
		(start 388.088886 -273.09318)
		(end 387.386576 -272.39087)
		(width 0.088646)
		(layer "In2.Cu")
		(net "M_E_CPU0_SA_DQS_DN<6>")
	)
	(segment
		(start 403.776688 -296.188384)
		(end 403.549866 -295.64076)
		(width 0.18288)
		(layer "In2.Cu")
		(net "M_E_CPU0_SA_DQS_DN<6>")
	)
	(segment
		(start 408.483054 -302.608488)
		(end 407.967434 -302.608488)
		(width 0.18288)
		(layer "In2.Cu")
		(net "M_E_CPU0_SA_DQS_DN<6>")
	)
	(segment
		(start 400.387566 -289.354006)
		(end 399.999708 -288.966148)
		(width 0.18288)
		(layer "In2.Cu")
		(net "M_E_CPU0_SA_DQS_DN<6>")
	)
	(segment
		(start 405.835358 -302.293782)
		(end 405.467312 -302.293782)
		(width 0.18288)
		(layer "In2.Cu")
		(net "M_E_CPU0_SA_DQS_DN<6>")
	)
	(segment
		(start 402.727414 -293.654988)
		(end 402.397468 -292.858444)
		(width 0.18288)
		(layer "In2.Cu")
		(net "M_E_CPU0_SA_DQS_DN<6>")
	)
	(segment
		(start 403.177248 -295.066212)
		(end 403.244558 -294.903652)
		(width 0.18288)
		(layer "In2.Cu")
		(net "M_E_CPU0_SA_DQS_DN<6>")
	)
	(segment
		(start 397.956532 -285.752032)
		(end 397.956532 -283.351732)
		(width 0.18288)
		(layer "In2.Cu")
		(net "M_E_CPU0_SA_DQS_DN<6>")
	)
	(segment
		(start 383.775458 -272.413476)
		(end 383.773934 -272.41373)
		(width 0.088646)
		(layer "In2.Cu")
		(net "M_E_CPU0_SA_DQS_DN<6>")
	)
	(segment
		(start 404.438358 -301.557436)
		(end 403.776688 -299.959268)
		(width 0.18288)
		(layer "In2.Cu")
		(net "M_E_CPU0_SA_DQS_DN<6>")
	)
	(segment
		(start 384.40233 -272.318226)
		(end 384.388614 -272.325846)
		(width 0.088646)
		(layer "In2.Cu")
		(net "M_E_CPU0_SA_DQS_DN<6>")
	)
	(segment
		(start 402.869908 -294.324786)
		(end 402.660104 -293.817802)
		(width 0.18288)
		(layer "In2.Cu")
		(net "M_E_CPU0_SA_DQS_DN<6>")
	)
	(segment
		(start 403.244558 -294.903652)
		(end 403.032722 -294.392096)
		(width 0.18288)
		(layer "In2.Cu")
		(net "M_E_CPU0_SA_DQS_DN<6>")
	)
	(segment
		(start 399.823686 -288.966148)
		(end 399.435574 -288.578036)
		(width 0.18288)
		(layer "In2.Cu")
		(net "M_E_CPU0_SA_DQS_DN<6>")
	)
	(segment
		(start 403.032722 -294.392096)
		(end 402.869908 -294.324786)
		(width 0.18288)
		(layer "In2.Cu")
		(net "M_E_CPU0_SA_DQS_DN<6>")
	)
	(segment
		(start 399.435574 -288.402014)
		(end 398.784064 -287.750504)
		(width 0.18288)
		(layer "In2.Cu")
		(net "M_E_CPU0_SA_DQS_DN<6>")
	)
	(segment
		(start 403.652228 -298.818046)
		(end 403.652228 -298.269406)
		(width 0.18288)
		(layer "In2.Cu")
		(net "M_E_CPU0_SA_DQS_DN<6>")
	)
	(segment
		(start 404.847044 -301.966376)
		(end 404.438358 -301.557436)
		(width 0.18288)
		(layer "In2.Cu")
		(net "M_E_CPU0_SA_DQS_DN<6>")
	)
	(segment
		(start 401.550124 -290.813236)
		(end 401.34032 -290.306506)
		(width 0.18288)
		(layer "In2.Cu")
		(net "M_E_CPU0_SA_DQS_DN<6>")
	)
	(segment
		(start 402.660104 -293.817802)
		(end 402.727414 -293.654988)
		(width 0.18288)
		(layer "In2.Cu")
		(net "M_E_CPU0_SA_DQS_DN<6>")
	)
	(segment
		(start 384.407664 -272.314924)
		(end 384.406902 -272.315432)
		(width 0.088646)
		(layer "In2.Cu")
		(net "M_E_CPU0_SA_DQS_DN<6>")
	)
	(segment
		(start 397.956532 -283.351732)
		(end 394.170154 -279.565354)
		(width 0.18288)
		(layer "In2.Cu")
		(net "M_E_CPU0_SA_DQS_DN<6>")
	)
	(segment
		(start 383.773934 -272.41373)
		(end 383.729484 -272.432272)
		(width 0.088646)
		(layer "In2.Cu")
		(net "M_E_CPU0_SA_DQS_DN<6>")
	)
	(segment
		(start 407.698194 -302.496982)
		(end 407.448004 -302.246792)
		(width 0.18288)
		(layer "In2.Cu")
		(net "M_E_CPU0_SA_DQS_DN<6>")
	)
	(segment
		(start 403.776688 -298.144946)
		(end 403.776688 -297.596306)
		(width 0.18288)
		(layer "In2.Cu")
		(net "M_E_CPU0_SA_DQS_DN<6>")
	)
	(segment
		(start 400.9517 -289.91814)
		(end 400.775678 -289.91814)
		(width 0.18288)
		(layer "In2.Cu")
		(net "M_E_CPU0_SA_DQS_DN<6>")
	)
	(segment
		(start 409.455112 -302.448722)
		(end 408.868626 -302.448722)
		(width 0.18288)
		(layer "In2.Cu")
		(net "M_E_CPU0_SA_DQS_DN<6>")
	)
	(segment
		(start 400.387566 -289.530028)
		(end 400.387566 -289.354006)
		(width 0.18288)
		(layer "In2.Cu")
		(net "M_E_CPU0_SA_DQS_DN<6>")
	)
	(segment
		(start 389.450326 -273.15287)
		(end 388.840726 -273.15287)
		(width 0.18288)
		(layer "In2.Cu")
		(net "M_E_CPU0_SA_DQS_DN<6>")
	)
	(segment
		(start 399.999708 -288.966148)
		(end 399.823686 -288.966148)
		(width 0.18288)
		(layer "In2.Cu")
		(net "M_E_CPU0_SA_DQS_DN<6>")
	)
	(segment
		(start 405.139906 -301.966376)
		(end 404.847044 -301.966376)
		(width 0.18288)
		(layer "In2.Cu")
		(net "M_E_CPU0_SA_DQS_DN<6>")
	)
	(segment
		(start 409.723082 -302.716692)
		(end 409.455112 -302.448722)
		(width 0.18288)
		(layer "In2.Cu")
		(net "M_E_CPU0_SA_DQS_DN<6>")
	)
	(segment
		(start 387.386576 -272.39087)
		(end 386.944616 -272.39087)
		(width 0.088646)
		(layer "In2.Cu")
		(net "M_E_CPU0_SA_DQS_DN<6>")
	)
	(segment
		(start 403.652228 -297.471846)
		(end 403.652228 -296.923206)
		(width 0.18288)
		(layer "In2.Cu")
		(net "M_E_CPU0_SA_DQS_DN<6>")
	)
	(segment
		(start 388.781036 -273.09318)
		(end 388.088886 -273.09318)
		(width 0.088646)
		(layer "In2.Cu")
		(net "M_E_CPU0_SA_DQS_DN<6>")
	)
	(arc
		(start 384.78206 -272.314924)
		(mid 384.594862 -272.264781)
		(end 384.407664 -272.314924)
		(width 0.088646)
		(layer "In2.Cu")
		(net "M_E_CPU0_SA_DQS_DN<6>")
	)
	(arc
		(start 385.72186 -272.314924)
		(mid 385.534662 -272.264781)
		(end 385.347464 -272.314924)
		(width 0.088646)
		(layer "In2.Cu")
		(net "M_E_CPU0_SA_DQS_DN<6>")
	)
	(arc
		(start 384.388614 -272.325846)
		(mid 384.256677 -272.375422)
		(end 384.11658 -272.39087)
		(width 0.088646)
		(layer "In2.Cu")
		(net "M_E_CPU0_SA_DQS_DN<6>")
	)
	(arc
		(start 385.332732 -272.32356)
		(mid 385.056291 -272.390726)
		(end 384.78206 -272.314924)
		(width 0.088646)
		(layer "In2.Cu")
		(net "M_E_CPU0_SA_DQS_DN<6>")
	)
	(arc
		(start 386.944616 -272.39087)
		(mid 386.798146 -272.37151)
		(end 386.66166 -272.314924)
		(width 0.088646)
		(layer "In2.Cu")
		(net "M_E_CPU0_SA_DQS_DN<6>")
	)
	(arc
		(start 383.729484 -272.432272)
		(mid 383.686957 -272.448885)
		(end 383.667 -272.48993)
		(width 0.088646)
		(layer "In2.Cu")
		(net "M_E_CPU0_SA_DQS_DN<6>")
	)
	(arc
		(start 386.66166 -272.314924)
		(mid 386.474462 -272.264781)
		(end 386.287264 -272.314924)
		(width 0.088646)
		(layer "In2.Cu")
		(net "M_E_CPU0_SA_DQS_DN<6>")
	)
	(arc
		(start 386.272532 -272.32356)
		(mid 385.996091 -272.390726)
		(end 385.72186 -272.314924)
		(width 0.088646)
		(layer "In2.Cu")
		(net "M_E_CPU0_SA_DQS_DN<6>")
	)
	(segment
		(start 405.743156 -311.641744)
		(end 407.758646 -311.641744)
		(width 0.1016)
		(layer "F.Cu")
		(net "M_E_CPU0_SA_DQS_DN<5>")
	)
	(segment
		(start 407.764488 -311.647586)
		(end 408.07259 -311.647586)
		(width 0.20066)
		(layer "F.Cu")
		(net "M_E_CPU0_SA_DQS_DN<5>")
	)
	(segment
		(start 408.513534 -311.416192)
		(end 409.876244 -311.829958)
		(width 0.20066)
		(layer "F.Cu")
		(net "M_E_CPU0_SA_DQS_DN<5>")
	)
	(segment
		(start 405.186134 -311.367932)
		(end 405.46655 -311.648348)
		(width 0.20066)
		(layer "F.Cu")
		(net "M_E_CPU0_SA_DQS_DN<5>")
	)
	(segment
		(start 414.590992 -311.641744)
		(end 413.308546 -311.641744)
		(width 0.1016)
		(layer "F.Cu")
		(net "M_E_CPU0_SA_DQS_DN<5>")
	)
	(segment
		(start 403.27707 -310.034178)
		(end 404.32355 -310.891682)
		(width 0.20066)
		(layer "F.Cu")
		(net "M_E_CPU0_SA_DQS_DN<5>")
	)
	(segment
		(start 388.926324 -280.586688)
		(end 388.926324 -291.264086)
		(width 0.1524)
		(layer "F.Cu")
		(net "M_E_CPU0_SA_DQS_DN<5>")
	)
	(segment
		(start 412.530798 -311.34431)
		(end 412.345378 -311.34431)
		(width 0.20066)
		(layer "F.Cu")
		(net "M_E_CPU0_SA_DQS_DN<5>")
	)
	(segment
		(start 386.109464 -275.818092)
		(end 386.63626 -276.016466)
		(width 0.088646)
		(layer "F.Cu")
		(net "M_E_CPU0_SA_DQS_DN<5>")
	)
	(segment
		(start 412.835852 -311.649364)
		(end 412.530798 -311.34431)
		(width 0.20066)
		(layer "F.Cu")
		(net "M_E_CPU0_SA_DQS_DN<5>")
	)
	(segment
		(start 390.363964 -296.615866)
		(end 392.962638 -299.779436)
		(width 0.20066)
		(layer "F.Cu")
		(net "M_E_CPU0_SA_DQS_DN<5>")
	)
	(segment
		(start 387.775196 -276.730206)
		(end 388.249414 -277.204424)
		(width 0.1524)
		(layer "F.Cu")
		(net "M_E_CPU0_SA_DQS_DN<5>")
	)
	(segment
		(start 411.59938 -311.795414)
		(end 411.328108 -312.066686)
		(width 0.20066)
		(layer "F.Cu")
		(net "M_E_CPU0_SA_DQS_DN<5>")
	)
	(segment
		(start 387.759702 -276.714712)
		(end 387.775196 -276.730206)
		(width 0.088646)
		(layer "F.Cu")
		(net "M_E_CPU0_SA_DQS_DN<5>")
	)
	(segment
		(start 417.090352 -311.812432)
		(end 416.718242 -311.658254)
		(width 0.20066)
		(layer "F.Cu")
		(net "M_E_CPU0_SA_DQS_DN<5>")
	)
	(segment
		(start 415.29762 -311.641744)
		(end 414.99028 -311.641744)
		(width 0.1016)
		(layer "F.Cu")
		(net "M_E_CPU0_SA_DQS_DN<5>")
	)
	(segment
		(start 404.32355 -310.891682)
		(end 404.966424 -311.367932)
		(width 0.20066)
		(layer "F.Cu")
		(net "M_E_CPU0_SA_DQS_DN<5>")
	)
	(segment
		(start 407.763726 -311.646824)
		(end 407.764488 -311.647586)
		(width 0.20066)
		(layer "F.Cu")
		(net "M_E_CPU0_SA_DQS_DN<5>")
	)
	(segment
		(start 417.885372 -312.066686)
		(end 417.631118 -311.812432)
		(width 0.20066)
		(layer "F.Cu")
		(net "M_E_CPU0_SA_DQS_DN<5>")
	)
	(segment
		(start 408.07259 -311.647586)
		(end 408.303984 -311.416192)
		(width 0.20066)
		(layer "F.Cu")
		(net "M_E_CPU0_SA_DQS_DN<5>")
	)
	(segment
		(start 388.926324 -291.264086)
		(end 388.96163 -291.59708)
		(width 0.1524)
		(layer "F.Cu")
		(net "M_E_CPU0_SA_DQS_DN<5>")
	)
	(segment
		(start 409.876244 -311.829958)
		(end 410.110686 -311.829958)
		(width 0.20066)
		(layer "F.Cu")
		(net "M_E_CPU0_SA_DQS_DN<5>")
	)
	(segment
		(start 387.01472 -276.173438)
		(end 387.548628 -276.458934)
		(width 0.088646)
		(layer "F.Cu")
		(net "M_E_CPU0_SA_DQS_DN<5>")
	)
	(segment
		(start 410.347414 -312.066686)
		(end 410.853382 -312.066686)
		(width 0.20066)
		(layer "F.Cu")
		(net "M_E_CPU0_SA_DQS_DN<5>")
	)
	(segment
		(start 416.567112 -311.507124)
		(end 416.228784 -311.366916)
		(width 0.20066)
		(layer "F.Cu")
		(net "M_E_CPU0_SA_DQS_DN<5>")
	)
	(segment
		(start 417.631118 -311.812432)
		(end 417.090352 -311.812432)
		(width 0.20066)
		(layer "F.Cu")
		(net "M_E_CPU0_SA_DQS_DN<5>")
	)
	(segment
		(start 418.397182 -312.066686)
		(end 417.885372 -312.066686)
		(width 0.20066)
		(layer "F.Cu")
		(net "M_E_CPU0_SA_DQS_DN<5>")
	)
	(segment
		(start 389.979916 -296.231564)
		(end 390.363964 -296.615866)
		(width 0.20066)
		(layer "F.Cu")
		(net "M_E_CPU0_SA_DQS_DN<5>")
	)
	(segment
		(start 404.966424 -311.367932)
		(end 405.186134 -311.367932)
		(width 0.20066)
		(layer "F.Cu")
		(net "M_E_CPU0_SA_DQS_DN<5>")
	)
	(segment
		(start 386.63626 -276.016466)
		(end 387.01472 -276.173438)
		(width 0.088646)
		(layer "F.Cu")
		(net "M_E_CPU0_SA_DQS_DN<5>")
	)
	(segment
		(start 408.303984 -311.416192)
		(end 408.513534 -311.416192)
		(width 0.20066)
		(layer "F.Cu")
		(net "M_E_CPU0_SA_DQS_DN<5>")
	)
	(segment
		(start 412.345378 -311.34431)
		(end 411.894274 -311.795414)
		(width 0.20066)
		(layer "F.Cu")
		(net "M_E_CPU0_SA_DQS_DN<5>")
	)
	(segment
		(start 405.736552 -311.648348)
		(end 405.743156 -311.641744)
		(width 0.1016)
		(layer "F.Cu")
		(net "M_E_CPU0_SA_DQS_DN<5>")
	)
	(segment
		(start 413.300926 -311.649364)
		(end 413.275526 -311.649364)
		(width 0.101854)
		(layer "F.Cu")
		(net "M_E_CPU0_SA_DQS_DN<5>")
	)
	(segment
		(start 413.308546 -311.641744)
		(end 413.300926 -311.649364)
		(width 0.101854)
		(layer "F.Cu")
		(net "M_E_CPU0_SA_DQS_DN<5>")
	)
	(segment
		(start 416.228784 -311.366916)
		(end 416.072574 -311.366916)
		(width 0.20066)
		(layer "F.Cu")
		(net "M_E_CPU0_SA_DQS_DN<5>")
	)
	(segment
		(start 411.894274 -311.795414)
		(end 411.59938 -311.795414)
		(width 0.20066)
		(layer "F.Cu")
		(net "M_E_CPU0_SA_DQS_DN<5>")
	)
	(segment
		(start 415.78784 -311.65165)
		(end 415.307526 -311.65165)
		(width 0.20066)
		(layer "F.Cu")
		(net "M_E_CPU0_SA_DQS_DN<5>")
	)
	(segment
		(start 407.758646 -311.641744)
		(end 407.763726 -311.646824)
		(width 0.1016)
		(layer "F.Cu")
		(net "M_E_CPU0_SA_DQS_DN<5>")
	)
	(segment
		(start 388.249414 -277.204424)
		(end 388.926324 -280.586688)
		(width 0.1524)
		(layer "F.Cu")
		(net "M_E_CPU0_SA_DQS_DN<5>")
	)
	(segment
		(start 413.275526 -311.649364)
		(end 412.835852 -311.649364)
		(width 0.20066)
		(layer "F.Cu")
		(net "M_E_CPU0_SA_DQS_DN<5>")
	)
	(segment
		(start 385.064762 -276.172676)
		(end 385.88315 -275.823172)
		(width 0.088646)
		(layer "F.Cu")
		(net "M_E_CPU0_SA_DQS_DN<5>")
	)
	(segment
		(start 392.962638 -299.779436)
		(end 402.835618 -309.635144)
		(width 0.20066)
		(layer "F.Cu")
		(net "M_E_CPU0_SA_DQS_DN<5>")
	)
	(segment
		(start 414.99028 -311.641744)
		(end 414.590992 -311.641744)
		(width 0.101854)
		(layer "F.Cu")
		(net "M_E_CPU0_SA_DQS_DN<5>")
	)
	(segment
		(start 388.96163 -291.59708)
		(end 389.60425 -295.40962)
		(width 0.1524)
		(layer "F.Cu")
		(net "M_E_CPU0_SA_DQS_DN<5>")
	)
	(segment
		(start 416.718242 -311.658254)
		(end 416.567112 -311.507124)
		(width 0.20066)
		(layer "F.Cu")
		(net "M_E_CPU0_SA_DQS_DN<5>")
	)
	(segment
		(start 387.759702 -276.670008)
		(end 387.759702 -276.714712)
		(width 0.088646)
		(layer "F.Cu")
		(net "M_E_CPU0_SA_DQS_DN<5>")
	)
	(segment
		(start 389.952992 -296.20464)
		(end 389.979916 -296.231564)
		(width 0.1524)
		(layer "F.Cu")
		(net "M_E_CPU0_SA_DQS_DN<5>")
	)
	(segment
		(start 405.731726 -311.648348)
		(end 405.736552 -311.648348)
		(width 0.101854)
		(layer "F.Cu")
		(net "M_E_CPU0_SA_DQS_DN<5>")
	)
	(segment
		(start 415.307526 -311.65165)
		(end 415.29762 -311.641744)
		(width 0.1016)
		(layer "F.Cu")
		(net "M_E_CPU0_SA_DQS_DN<5>")
	)
	(segment
		(start 410.110686 -311.829958)
		(end 410.347414 -312.066686)
		(width 0.20066)
		(layer "F.Cu")
		(net "M_E_CPU0_SA_DQS_DN<5>")
	)
	(segment
		(start 387.548628 -276.458934)
		(end 387.759702 -276.670008)
		(width 0.088646)
		(layer "F.Cu")
		(net "M_E_CPU0_SA_DQS_DN<5>")
	)
	(segment
		(start 402.835618 -309.635144)
		(end 403.27707 -310.034178)
		(width 0.20066)
		(layer "F.Cu")
		(net "M_E_CPU0_SA_DQS_DN<5>")
	)
	(segment
		(start 411.328108 -312.066686)
		(end 410.853382 -312.066686)
		(width 0.20066)
		(layer "F.Cu")
		(net "M_E_CPU0_SA_DQS_DN<5>")
	)
	(segment
		(start 416.072574 -311.366916)
		(end 415.78784 -311.65165)
		(width 0.20066)
		(layer "F.Cu")
		(net "M_E_CPU0_SA_DQS_DN<5>")
	)
	(segment
		(start 389.828786 -296.02811)
		(end 389.952992 -296.152316)
		(width 0.1524)
		(layer "F.Cu")
		(net "M_E_CPU0_SA_DQS_DN<5>")
	)
	(segment
		(start 389.60425 -295.40962)
		(end 389.828786 -296.02811)
		(width 0.1524)
		(layer "F.Cu")
		(net "M_E_CPU0_SA_DQS_DN<5>")
	)
	(segment
		(start 405.46655 -311.648348)
		(end 405.731726 -311.648348)
		(width 0.20066)
		(layer "F.Cu")
		(net "M_E_CPU0_SA_DQS_DN<5>")
	)
	(segment
		(start 389.952992 -296.152316)
		(end 389.952992 -296.20464)
		(width 0.1524)
		(layer "F.Cu")
		(net "M_E_CPU0_SA_DQS_DN<5>")
	)
	(arc
		(start 385.88315 -275.823172)
		(mid 385.99581 -275.798811)
		(end 386.109464 -275.818092)
		(width 0.088646)
		(layer "F.Cu")
		(net "M_E_CPU0_SA_DQS_DN<5>")
	)
	(segment
		(start 409.468574 -275.075904)
		(end 409.217114 -275.075904)
		(width 0.20066)
		(layer "F.Cu")
		(net "M_E_CPU0_SA_DQS_DN<4>")
	)
	(segment
		(start 412.004764 -275.091652)
		(end 411.83179 -275.091652)
		(width 0.101854)
		(layer "F.Cu")
		(net "M_E_CPU0_SA_DQS_DN<4>")
	)
	(segment
		(start 411.83179 -275.091652)
		(end 409.852368 -275.091652)
		(width 0.1016)
		(layer "F.Cu")
		(net "M_E_CPU0_SA_DQS_DN<4>")
	)
	(segment
		(start 400.221196 -274.851114)
		(end 400.258026 -274.814284)
		(width 0.1524)
		(layer "F.Cu")
		(net "M_E_CPU0_SA_DQS_DN<4>")
	)
	(segment
		(start 404.803102 -275.085556)
		(end 405.052276 -275.188934)
		(width 0.20066)
		(layer "F.Cu")
		(net "M_E_CPU0_SA_DQS_DN<4>")
	)
	(segment
		(start 401.840446 -274.814284)
		(end 401.964906 -274.689824)
		(width 0.20066)
		(layer "F.Cu")
		(net "M_E_CPU0_SA_DQS_DN<4>")
	)
	(segment
		(start 389.068056 -261.67334)
		(end 389.113268 -261.67334)
		(width 0.088646)
		(layer "F.Cu")
		(net "M_E_CPU0_SA_DQS_DN<4>")
	)
	(segment
		(start 401.964906 -274.689824)
		(end 402.396706 -274.689824)
		(width 0.20066)
		(layer "F.Cu")
		(net "M_E_CPU0_SA_DQS_DN<4>")
	)
	(segment
		(start 388.496048 -260.957314)
		(end 388.496048 -261.101332)
		(width 0.088646)
		(layer "F.Cu")
		(net "M_E_CPU0_SA_DQS_DN<4>")
	)
	(segment
		(start 385.55422 -259.977382)
		(end 385.55422 -260.037326)
		(width 0.088646)
		(layer "F.Cu")
		(net "M_E_CPU0_SA_DQS_DN<4>")
	)
	(segment
		(start 405.73579 -274.752816)
		(end 405.821896 -274.66671)
		(width 0.20066)
		(layer "F.Cu")
		(net "M_E_CPU0_SA_DQS_DN<4>")
	)
	(segment
		(start 400.258026 -274.814284)
		(end 400.296126 -274.814284)
		(width 0.1524)
		(layer "F.Cu")
		(net "M_E_CPU0_SA_DQS_DN<4>")
	)
	(segment
		(start 387.704584 -260.37413)
		(end 387.830568 -260.435852)
		(width 0.088646)
		(layer "F.Cu")
		(net "M_E_CPU0_SA_DQS_DN<4>")
	)
	(segment
		(start 402.396706 -274.689824)
		(end 402.521166 -274.814284)
		(width 0.20066)
		(layer "F.Cu")
		(net "M_E_CPU0_SA_DQS_DN<4>")
	)
	(segment
		(start 385.55422 -260.037326)
		(end 385.624578 -260.107684)
		(width 0.088646)
		(layer "F.Cu")
		(net "M_E_CPU0_SA_DQS_DN<4>")
	)
	(segment
		(start 388.891018 -261.496302)
		(end 389.068056 -261.67334)
		(width 0.088646)
		(layer "F.Cu")
		(net "M_E_CPU0_SA_DQS_DN<4>")
	)
	(segment
		(start 388.496048 -261.101332)
		(end 388.621524 -261.226808)
		(width 0.088646)
		(layer "F.Cu")
		(net "M_E_CPU0_SA_DQS_DN<4>")
	)
	(segment
		(start 409.217114 -275.075904)
		(end 408.948382 -275.344636)
		(width 0.20066)
		(layer "F.Cu")
		(net "M_E_CPU0_SA_DQS_DN<4>")
	)
	(segment
		(start 388.2263 -260.831584)
		(end 388.370318 -260.831584)
		(width 0.088646)
		(layer "F.Cu")
		(net "M_E_CPU0_SA_DQS_DN<4>")
	)
	(segment
		(start 385.811268 -260.215126)
		(end 385.817364 -260.21919)
		(width 0.088646)
		(layer "F.Cu")
		(net "M_E_CPU0_SA_DQS_DN<4>")
	)
	(segment
		(start 408.22372 -274.948396)
		(end 407.58364 -274.948396)
		(width 0.20066)
		(layer "F.Cu")
		(net "M_E_CPU0_SA_DQS_DN<4>")
	)
	(segment
		(start 400.727926 -274.814284)
		(end 400.852386 -274.689824)
		(width 0.20066)
		(layer "F.Cu")
		(net "M_E_CPU0_SA_DQS_DN<4>")
	)
	(segment
		(start 409.852368 -275.091652)
		(end 409.484322 -275.091652)
		(width 0.101854)
		(layer "F.Cu")
		(net "M_E_CPU0_SA_DQS_DN<4>")
	)
	(segment
		(start 401.408646 -274.814284)
		(end 401.840446 -274.814284)
		(width 0.20066)
		(layer "F.Cu")
		(net "M_E_CPU0_SA_DQS_DN<4>")
	)
	(segment
		(start 405.052276 -275.188934)
		(end 405.648668 -275.188934)
		(width 0.20066)
		(layer "F.Cu")
		(net "M_E_CPU0_SA_DQS_DN<4>")
	)
	(segment
		(start 414.297114 -274.66671)
		(end 413.748474 -274.66671)
		(width 0.20066)
		(layer "F.Cu")
		(net "M_E_CPU0_SA_DQS_DN<4>")
	)
	(segment
		(start 399.412206 -274.37207)
		(end 399.492724 -274.662138)
		(width 0.1524)
		(layer "F.Cu")
		(net "M_E_CPU0_SA_DQS_DN<4>")
	)
	(segment
		(start 405.73579 -275.101812)
		(end 405.73579 -274.752816)
		(width 0.20066)
		(layer "F.Cu")
		(net "M_E_CPU0_SA_DQS_DN<4>")
	)
	(segment
		(start 388.891018 -261.352538)
		(end 388.891018 -261.496302)
		(width 0.088646)
		(layer "F.Cu")
		(net "M_E_CPU0_SA_DQS_DN<4>")
	)
	(segment
		(start 405.821896 -274.66671)
		(end 406.753314 -274.66671)
		(width 0.20066)
		(layer "F.Cu")
		(net "M_E_CPU0_SA_DQS_DN<4>")
	)
	(segment
		(start 407.301954 -274.66671)
		(end 406.753314 -274.66671)
		(width 0.20066)
		(layer "F.Cu")
		(net "M_E_CPU0_SA_DQS_DN<4>")
	)
	(segment
		(start 385.639564 -260.115812)
		(end 385.811268 -260.215126)
		(width 0.088646)
		(layer "F.Cu")
		(net "M_E_CPU0_SA_DQS_DN<4>")
	)
	(segment
		(start 412.724346 -275.317712)
		(end 412.419292 -275.317712)
		(width 0.20066)
		(layer "F.Cu")
		(net "M_E_CPU0_SA_DQS_DN<4>")
	)
	(segment
		(start 412.017464 -275.078952)
		(end 412.004764 -275.091652)
		(width 0.101854)
		(layer "F.Cu")
		(net "M_E_CPU0_SA_DQS_DN<4>")
	)
	(segment
		(start 403.633686 -274.814284)
		(end 404.464774 -274.814284)
		(width 0.20066)
		(layer "F.Cu")
		(net "M_E_CPU0_SA_DQS_DN<4>")
	)
	(segment
		(start 404.688548 -275.038058)
		(end 404.803102 -275.085556)
		(width 0.20066)
		(layer "F.Cu")
		(net "M_E_CPU0_SA_DQS_DN<4>")
	)
	(segment
		(start 409.484322 -275.091652)
		(end 409.468574 -275.075904)
		(width 0.101854)
		(layer "F.Cu")
		(net "M_E_CPU0_SA_DQS_DN<4>")
	)
	(segment
		(start 388.765288 -261.226808)
		(end 388.891018 -261.352538)
		(width 0.088646)
		(layer "F.Cu")
		(net "M_E_CPU0_SA_DQS_DN<4>")
	)
	(segment
		(start 412.180532 -275.078952)
		(end 412.017464 -275.078952)
		(width 0.20066)
		(layer "F.Cu")
		(net "M_E_CPU0_SA_DQS_DN<4>")
	)
	(segment
		(start 403.509226 -274.689824)
		(end 403.633686 -274.814284)
		(width 0.20066)
		(layer "F.Cu")
		(net "M_E_CPU0_SA_DQS_DN<4>")
	)
	(segment
		(start 399.492724 -274.662138)
		(end 399.6817 -274.851114)
		(width 0.1524)
		(layer "F.Cu")
		(net "M_E_CPU0_SA_DQS_DN<4>")
	)
	(segment
		(start 385.425442 -259.848604)
		(end 385.55422 -259.977382)
		(width 0.088646)
		(layer "F.Cu")
		(net "M_E_CPU0_SA_DQS_DN<4>")
	)
	(segment
		(start 399.6817 -274.851114)
		(end 400.221196 -274.851114)
		(width 0.1524)
		(layer "F.Cu")
		(net "M_E_CPU0_SA_DQS_DN<4>")
	)
	(segment
		(start 386.944362 -260.269736)
		(end 387.704584 -260.37413)
		(width 0.088646)
		(layer "F.Cu")
		(net "M_E_CPU0_SA_DQS_DN<4>")
	)
	(segment
		(start 389.113268 -261.67334)
		(end 398.81175 -271.371822)
		(width 0.1524)
		(layer "F.Cu")
		(net "M_E_CPU0_SA_DQS_DN<4>")
	)
	(segment
		(start 403.077426 -274.689824)
		(end 403.509226 -274.689824)
		(width 0.20066)
		(layer "F.Cu")
		(net "M_E_CPU0_SA_DQS_DN<4>")
	)
	(segment
		(start 413.13481 -274.907248)
		(end 412.724346 -275.317712)
		(width 0.20066)
		(layer "F.Cu")
		(net "M_E_CPU0_SA_DQS_DN<4>")
	)
	(segment
		(start 398.81175 -271.371822)
		(end 399.412206 -274.37207)
		(width 0.1524)
		(layer "F.Cu")
		(net "M_E_CPU0_SA_DQS_DN<4>")
	)
	(segment
		(start 400.852386 -274.689824)
		(end 401.284186 -274.689824)
		(width 0.20066)
		(layer "F.Cu")
		(net "M_E_CPU0_SA_DQS_DN<4>")
	)
	(segment
		(start 408.61996 -275.344636)
		(end 408.22372 -274.948396)
		(width 0.20066)
		(layer "F.Cu")
		(net "M_E_CPU0_SA_DQS_DN<4>")
	)
	(segment
		(start 388.621524 -261.226808)
		(end 388.765288 -261.226808)
		(width 0.088646)
		(layer "F.Cu")
		(net "M_E_CPU0_SA_DQS_DN<4>")
	)
	(segment
		(start 408.948382 -275.344636)
		(end 408.61996 -275.344636)
		(width 0.20066)
		(layer "F.Cu")
		(net "M_E_CPU0_SA_DQS_DN<4>")
	)
	(segment
		(start 400.296126 -274.814284)
		(end 400.727926 -274.814284)
		(width 0.20066)
		(layer "F.Cu")
		(net "M_E_CPU0_SA_DQS_DN<4>")
	)
	(segment
		(start 401.284186 -274.689824)
		(end 401.408646 -274.814284)
		(width 0.20066)
		(layer "F.Cu")
		(net "M_E_CPU0_SA_DQS_DN<4>")
	)
	(segment
		(start 387.830568 -260.435852)
		(end 388.2263 -260.831584)
		(width 0.088646)
		(layer "F.Cu")
		(net "M_E_CPU0_SA_DQS_DN<4>")
	)
	(segment
		(start 413.507936 -274.907248)
		(end 413.13481 -274.907248)
		(width 0.20066)
		(layer "F.Cu")
		(net "M_E_CPU0_SA_DQS_DN<4>")
	)
	(segment
		(start 405.648668 -275.188934)
		(end 405.73579 -275.101812)
		(width 0.20066)
		(layer "F.Cu")
		(net "M_E_CPU0_SA_DQS_DN<4>")
	)
	(segment
		(start 404.464774 -274.814284)
		(end 404.688548 -275.038058)
		(width 0.20066)
		(layer "F.Cu")
		(net "M_E_CPU0_SA_DQS_DN<4>")
	)
	(segment
		(start 412.419292 -275.317712)
		(end 412.180532 -275.078952)
		(width 0.20066)
		(layer "F.Cu")
		(net "M_E_CPU0_SA_DQS_DN<4>")
	)
	(segment
		(start 407.58364 -274.948396)
		(end 407.301954 -274.66671)
		(width 0.20066)
		(layer "F.Cu")
		(net "M_E_CPU0_SA_DQS_DN<4>")
	)
	(segment
		(start 385.176522 -259.848604)
		(end 385.425442 -259.848604)
		(width 0.088646)
		(layer "F.Cu")
		(net "M_E_CPU0_SA_DQS_DN<4>")
	)
	(segment
		(start 385.064762 -259.894832)
		(end 385.176522 -259.848604)
		(width 0.088646)
		(layer "F.Cu")
		(net "M_E_CPU0_SA_DQS_DN<4>")
	)
	(segment
		(start 402.521166 -274.814284)
		(end 402.952966 -274.814284)
		(width 0.20066)
		(layer "F.Cu")
		(net "M_E_CPU0_SA_DQS_DN<4>")
	)
	(segment
		(start 388.370318 -260.831584)
		(end 388.496048 -260.957314)
		(width 0.088646)
		(layer "F.Cu")
		(net "M_E_CPU0_SA_DQS_DN<4>")
	)
	(segment
		(start 402.952966 -274.814284)
		(end 403.077426 -274.689824)
		(width 0.20066)
		(layer "F.Cu")
		(net "M_E_CPU0_SA_DQS_DN<4>")
	)
	(segment
		(start 413.748474 -274.66671)
		(end 413.507936 -274.907248)
		(width 0.20066)
		(layer "F.Cu")
		(net "M_E_CPU0_SA_DQS_DN<4>")
	)
	(arc
		(start 385.624578 -260.107684)
		(mid 385.632145 -260.111612)
		(end 385.639564 -260.115812)
		(width 0.088646)
		(layer "F.Cu")
		(net "M_E_CPU0_SA_DQS_DN<4>")
	)
	(arc
		(start 386.756656 -260.219444)
		(mid 386.847189 -260.256998)
		(end 386.944362 -260.269736)
		(width 0.088646)
		(layer "F.Cu")
		(net "M_E_CPU0_SA_DQS_DN<4>")
	)
	(arc
		(start 386.192522 -260.219698)
		(mid 386.474543 -260.144142)
		(end 386.756656 -260.219444)
		(width 0.088646)
		(layer "F.Cu")
		(net "M_E_CPU0_SA_DQS_DN<4>")
	)
	(arc
		(start 385.817364 -260.21919)
		(mid 386.004562 -260.269333)
		(end 386.19176 -260.21919)
		(width 0.088646)
		(layer "F.Cu")
		(net "M_E_CPU0_SA_DQS_DN<4>")
	)
	(arc
		(start 386.19176 -260.21919)
		(mid 386.192141 -260.219444)
		(end 386.192522 -260.219698)
		(width 0.088646)
		(layer "F.Cu")
		(net "M_E_CPU0_SA_DQS_DN<4>")
	)
	(segment
		(start 401.107148 -284.999684)
		(end 403.540468 -284.999684)
		(width 0.20066)
		(layer "F.Cu")
		(net "M_E_CPU0_SA_DQS_DN<3>")
	)
	(segment
		(start 407.58364 -284.29839)
		(end 407.301954 -284.016704)
		(width 0.20066)
		(layer "F.Cu")
		(net "M_E_CPU0_SA_DQS_DN<3>")
	)
	(segment
		(start 412.186628 -284.435042)
		(end 411.863794 -284.435042)
		(width 0.20066)
		(layer "F.Cu")
		(net "M_E_CPU0_SA_DQS_DN<3>")
	)
	(segment
		(start 397.183864 -281.80792)
		(end 397.184626 -281.808682)
		(width 0.1524)
		(layer "F.Cu")
		(net "M_E_CPU0_SA_DQS_DN<3>")
	)
	(segment
		(start 404.316184 -284.48127)
		(end 404.964392 -284.048454)
		(width 0.20066)
		(layer "F.Cu")
		(net "M_E_CPU0_SA_DQS_DN<3>")
	)
	(segment
		(start 413.748474 -284.016704)
		(end 413.507936 -284.257242)
		(width 0.20066)
		(layer "F.Cu")
		(net "M_E_CPU0_SA_DQS_DN<3>")
	)
	(segment
		(start 397.183864 -281.808174)
		(end 397.183864 -281.80792)
		(width 0.1524)
		(layer "F.Cu")
		(net "M_E_CPU0_SA_DQS_DN<3>")
	)
	(segment
		(start 405.797512 -284.048454)
		(end 405.829262 -284.016704)
		(width 0.20066)
		(layer "F.Cu")
		(net "M_E_CPU0_SA_DQS_DN<3>")
	)
	(segment
		(start 412.419292 -284.667706)
		(end 412.186628 -284.435042)
		(width 0.20066)
		(layer "F.Cu")
		(net "M_E_CPU0_SA_DQS_DN<3>")
	)
	(segment
		(start 388.535672 -266.636246)
		(end 395.114272 -273.214846)
		(width 0.1524)
		(layer "F.Cu")
		(net "M_E_CPU0_SA_DQS_DN<3>")
	)
	(segment
		(start 403.540468 -284.999684)
		(end 404.31593 -284.481524)
		(width 0.20066)
		(layer "F.Cu")
		(net "M_E_CPU0_SA_DQS_DN<3>")
	)
	(segment
		(start 397.184626 -281.808682)
		(end 397.236188 -281.808682)
		(width 0.1524)
		(layer "F.Cu")
		(net "M_E_CPU0_SA_DQS_DN<3>")
	)
	(segment
		(start 395.114272 -273.214846)
		(end 396.745714 -281.370024)
		(width 0.1524)
		(layer "F.Cu")
		(net "M_E_CPU0_SA_DQS_DN<3>")
	)
	(segment
		(start 397.236188 -281.808682)
		(end 397.263112 -281.835606)
		(width 0.1524)
		(layer "F.Cu")
		(net "M_E_CPU0_SA_DQS_DN<3>")
	)
	(segment
		(start 412.724346 -284.667706)
		(end 412.419292 -284.667706)
		(width 0.20066)
		(layer "F.Cu")
		(net "M_E_CPU0_SA_DQS_DN<3>")
	)
	(segment
		(start 409.255722 -284.712918)
		(end 408.826208 -284.712918)
		(width 0.20066)
		(layer "F.Cu")
		(net "M_E_CPU0_SA_DQS_DN<3>")
	)
	(segment
		(start 407.301954 -284.016704)
		(end 406.753314 -284.016704)
		(width 0.20066)
		(layer "F.Cu")
		(net "M_E_CPU0_SA_DQS_DN<3>")
	)
	(segment
		(start 385.808474 -265.097514)
		(end 385.811014 -265.098784)
		(width 0.088646)
		(layer "F.Cu")
		(net "M_E_CPU0_SA_DQS_DN<3>")
	)
	(segment
		(start 388.474966 -266.620752)
		(end 388.520178 -266.620752)
		(width 0.088646)
		(layer "F.Cu")
		(net "M_E_CPU0_SA_DQS_DN<3>")
	)
	(segment
		(start 386.918454 -265.185906)
		(end 387.180582 -265.326368)
		(width 0.088646)
		(layer "F.Cu")
		(net "M_E_CPU0_SA_DQS_DN<3>")
	)
	(segment
		(start 384.734308 -264.536428)
		(end 384.92303 -264.443972)
		(width 0.088646)
		(layer "F.Cu")
		(net "M_E_CPU0_SA_DQS_DN<3>")
	)
	(segment
		(start 385.815332 -265.101324)
		(end 385.817364 -265.102594)
		(width 0.088646)
		(layer "F.Cu")
		(net "M_E_CPU0_SA_DQS_DN<3>")
	)
	(segment
		(start 411.85719 -284.441646)
		(end 409.852368 -284.441646)
		(width 0.1016)
		(layer "F.Cu")
		(net "M_E_CPU0_SA_DQS_DN<3>")
	)
	(segment
		(start 414.297114 -284.016704)
		(end 413.748474 -284.016704)
		(width 0.20066)
		(layer "F.Cu")
		(net "M_E_CPU0_SA_DQS_DN<3>")
	)
	(segment
		(start 404.31593 -284.481524)
		(end 404.316184 -284.48127)
		(width 0.20066)
		(layer "F.Cu")
		(net "M_E_CPU0_SA_DQS_DN<3>")
	)
	(segment
		(start 413.13481 -284.257242)
		(end 412.724346 -284.667706)
		(width 0.20066)
		(layer "F.Cu")
		(net "M_E_CPU0_SA_DQS_DN<3>")
	)
	(segment
		(start 413.507936 -284.257242)
		(end 413.13481 -284.257242)
		(width 0.20066)
		(layer "F.Cu")
		(net "M_E_CPU0_SA_DQS_DN<3>")
	)
	(segment
		(start 384.124962 -264.778236)
		(end 384.734308 -264.536428)
		(width 0.088646)
		(layer "F.Cu")
		(net "M_E_CPU0_SA_DQS_DN<3>")
	)
	(segment
		(start 396.745714 -281.370024)
		(end 397.183864 -281.808174)
		(width 0.1524)
		(layer "F.Cu")
		(net "M_E_CPU0_SA_DQS_DN<3>")
	)
	(segment
		(start 408.826208 -284.712918)
		(end 408.41168 -284.29839)
		(width 0.20066)
		(layer "F.Cu")
		(net "M_E_CPU0_SA_DQS_DN<3>")
	)
	(segment
		(start 385.811014 -265.098784)
		(end 385.8133 -265.100308)
		(width 0.088646)
		(layer "F.Cu")
		(net "M_E_CPU0_SA_DQS_DN<3>")
	)
	(segment
		(start 411.863794 -284.435042)
		(end 411.85719 -284.441646)
		(width 0.1016)
		(layer "F.Cu")
		(net "M_E_CPU0_SA_DQS_DN<3>")
	)
	(segment
		(start 405.829262 -284.016704)
		(end 406.753314 -284.016704)
		(width 0.20066)
		(layer "F.Cu")
		(net "M_E_CPU0_SA_DQS_DN<3>")
	)
	(segment
		(start 404.964392 -284.048454)
		(end 405.797512 -284.048454)
		(width 0.20066)
		(layer "F.Cu")
		(net "M_E_CPU0_SA_DQS_DN<3>")
	)
	(segment
		(start 408.41168 -284.29839)
		(end 407.58364 -284.29839)
		(width 0.20066)
		(layer "F.Cu")
		(net "M_E_CPU0_SA_DQS_DN<3>")
	)
	(segment
		(start 409.852368 -284.441646)
		(end 409.83662 -284.425898)
		(width 0.1016)
		(layer "F.Cu")
		(net "M_E_CPU0_SA_DQS_DN<3>")
	)
	(segment
		(start 388.520178 -266.620752)
		(end 388.535672 -266.636246)
		(width 0.088646)
		(layer "F.Cu")
		(net "M_E_CPU0_SA_DQS_DN<3>")
	)
	(segment
		(start 399.946368 -284.518862)
		(end 401.107148 -284.999684)
		(width 0.20066)
		(layer "F.Cu")
		(net "M_E_CPU0_SA_DQS_DN<3>")
	)
	(segment
		(start 397.263112 -281.835606)
		(end 399.946368 -284.518862)
		(width 0.20066)
		(layer "F.Cu")
		(net "M_E_CPU0_SA_DQS_DN<3>")
	)
	(segment
		(start 409.542742 -284.425898)
		(end 409.255722 -284.712918)
		(width 0.20066)
		(layer "F.Cu")
		(net "M_E_CPU0_SA_DQS_DN<3>")
	)
	(segment
		(start 385.32689 -264.50925)
		(end 385.724654 -265.022838)
		(width 0.088646)
		(layer "F.Cu")
		(net "M_E_CPU0_SA_DQS_DN<3>")
	)
	(segment
		(start 409.831794 -284.425898)
		(end 409.542742 -284.425898)
		(width 0.20066)
		(layer "F.Cu")
		(net "M_E_CPU0_SA_DQS_DN<3>")
	)
	(segment
		(start 409.83662 -284.425898)
		(end 409.831794 -284.425898)
		(width 0.101854)
		(layer "F.Cu")
		(net "M_E_CPU0_SA_DQS_DN<3>")
	)
	(segment
		(start 385.8133 -265.100308)
		(end 385.815332 -265.101324)
		(width 0.088646)
		(layer "F.Cu")
		(net "M_E_CPU0_SA_DQS_DN<3>")
	)
	(segment
		(start 387.180582 -265.326368)
		(end 388.474966 -266.620752)
		(width 0.088646)
		(layer "F.Cu")
		(net "M_E_CPU0_SA_DQS_DN<3>")
	)
	(arc
		(start 384.92303 -264.443972)
		(mid 385.134148 -264.419703)
		(end 385.32689 -264.50925)
		(width 0.088646)
		(layer "F.Cu")
		(net "M_E_CPU0_SA_DQS_DN<3>")
	)
	(arc
		(start 385.724654 -265.022838)
		(mid 385.763221 -265.063925)
		(end 385.808474 -265.097514)
		(width 0.088646)
		(layer "F.Cu")
		(net "M_E_CPU0_SA_DQS_DN<3>")
	)
	(arc
		(start 386.19176 -265.102594)
		(mid 386.568844 -265.024278)
		(end 386.918454 -265.185906)
		(width 0.088646)
		(layer "F.Cu")
		(net "M_E_CPU0_SA_DQS_DN<3>")
	)
	(arc
		(start 385.817364 -265.102594)
		(mid 386.004562 -265.152737)
		(end 386.19176 -265.102594)
		(width 0.088646)
		(layer "F.Cu")
		(net "M_E_CPU0_SA_DQS_DN<3>")
	)
	(segment
		(start 414.297114 -293.366698)
		(end 413.748474 -293.366698)
		(width 0.20066)
		(layer "F.Cu")
		(net "M_E_CPU0_SA_DQS_DN<2>")
	)
	(segment
		(start 392.523218 -289.290252)
		(end 392.722354 -289.489388)
		(width 0.1524)
		(layer "F.Cu")
		(net "M_E_CPU0_SA_DQS_DN<2>")
	)
	(segment
		(start 387.135878 -270.592296)
		(end 387.14934 -270.624046)
		(width 0.088646)
		(layer "F.Cu")
		(net "M_E_CPU0_SA_DQS_DN<2>")
	)
	(segment
		(start 386.955792 -270.108934)
		(end 386.9563 -270.109442)
		(width 0.088646)
		(layer "F.Cu")
		(net "M_E_CPU0_SA_DQS_DN<2>")
	)
	(segment
		(start 406.18029 -293.366698)
		(end 406.753314 -293.366698)
		(width 0.20066)
		(layer "F.Cu")
		(net "M_E_CPU0_SA_DQS_DN<2>")
	)
	(segment
		(start 387.17982 -270.68272)
		(end 387.183376 -270.691356)
		(width 0.088646)
		(layer "F.Cu")
		(net "M_E_CPU0_SA_DQS_DN<2>")
	)
	(segment
		(start 408.41168 -293.648384)
		(end 407.58364 -293.648384)
		(width 0.20066)
		(layer "F.Cu")
		(net "M_E_CPU0_SA_DQS_DN<2>")
	)
	(segment
		(start 413.507936 -293.607236)
		(end 413.13481 -293.607236)
		(width 0.20066)
		(layer "F.Cu")
		(net "M_E_CPU0_SA_DQS_DN<2>")
	)
	(segment
		(start 392.774424 -289.489388)
		(end 399.266156 -295.98112)
		(width 0.20066)
		(layer "F.Cu")
		(net "M_E_CPU0_SA_DQS_DN<2>")
	)
	(segment
		(start 385.345432 -270.79575)
		(end 385.348734 -270.797782)
		(width 0.088646)
		(layer "F.Cu")
		(net "M_E_CPU0_SA_DQS_DN<2>")
	)
	(segment
		(start 409.852368 -293.79164)
		(end 409.83662 -293.775892)
		(width 0.1016)
		(layer "F.Cu")
		(net "M_E_CPU0_SA_DQS_DN<2>")
	)
	(segment
		(start 387.648958 -271.365726)
		(end 387.760464 -271.477232)
		(width 0.088646)
		(layer "F.Cu")
		(net "M_E_CPU0_SA_DQS_DN<2>")
	)
	(segment
		(start 409.831794 -293.775892)
		(end 409.542742 -293.775892)
		(width 0.20066)
		(layer "F.Cu")
		(net "M_E_CPU0_SA_DQS_DN<2>")
	)
	(segment
		(start 385.348734 -270.797782)
		(end 385.350004 -270.79829)
		(width 0.088646)
		(layer "F.Cu")
		(net "M_E_CPU0_SA_DQS_DN<2>")
	)
	(segment
		(start 387.1722 -270.665194)
		(end 387.17982 -270.68272)
		(width 0.088646)
		(layer "F.Cu")
		(net "M_E_CPU0_SA_DQS_DN<2>")
	)
	(segment
		(start 407.301954 -293.366698)
		(end 406.753314 -293.366698)
		(width 0.20066)
		(layer "F.Cu")
		(net "M_E_CPU0_SA_DQS_DN<2>")
	)
	(segment
		(start 413.13481 -293.607236)
		(end 412.724346 -294.0177)
		(width 0.20066)
		(layer "F.Cu")
		(net "M_E_CPU0_SA_DQS_DN<2>")
	)
	(segment
		(start 411.863794 -293.785036)
		(end 411.85719 -293.79164)
		(width 0.1016)
		(layer "F.Cu")
		(net "M_E_CPU0_SA_DQS_DN<2>")
	)
	(segment
		(start 407.58364 -293.648384)
		(end 407.301954 -293.366698)
		(width 0.20066)
		(layer "F.Cu")
		(net "M_E_CPU0_SA_DQS_DN<2>")
	)
	(segment
		(start 409.255722 -294.062912)
		(end 408.826208 -294.062912)
		(width 0.20066)
		(layer "F.Cu")
		(net "M_E_CPU0_SA_DQS_DN<2>")
	)
	(segment
		(start 411.85719 -293.79164)
		(end 409.852368 -293.79164)
		(width 0.1016)
		(layer "F.Cu")
		(net "M_E_CPU0_SA_DQS_DN<2>")
	)
	(segment
		(start 387.760464 -271.477232)
		(end 387.78688 -271.477232)
		(width 0.088646)
		(layer "F.Cu")
		(net "M_E_CPU0_SA_DQS_DN<2>")
	)
	(segment
		(start 385.153154 -270.357346)
		(end 385.153408 -270.357346)
		(width 0.088646)
		(layer "F.Cu")
		(net "M_E_CPU0_SA_DQS_DN<2>")
	)
	(segment
		(start 412.186628 -293.785036)
		(end 411.863794 -293.785036)
		(width 0.20066)
		(layer "F.Cu")
		(net "M_E_CPU0_SA_DQS_DN<2>")
	)
	(segment
		(start 385.912614 -270.51762)
		(end 385.912614 -270.517112)
		(width 0.088646)
		(layer "F.Cu")
		(net "M_E_CPU0_SA_DQS_DN<2>")
	)
	(segment
		(start 384.79349 -269.945866)
		(end 384.793236 -269.946628)
		(width 0.088646)
		(layer "F.Cu")
		(net "M_E_CPU0_SA_DQS_DN<2>")
	)
	(segment
		(start 391.492232 -275.182584)
		(end 392.523218 -280.336498)
		(width 0.1524)
		(layer "F.Cu")
		(net "M_E_CPU0_SA_DQS_DN<2>")
	)
	(segment
		(start 387.14934 -270.624046)
		(end 387.1722 -270.665194)
		(width 0.088646)
		(layer "F.Cu")
		(net "M_E_CPU0_SA_DQS_DN<2>")
	)
	(segment
		(start 386.484622 -269.94739)
		(end 386.595112 -269.94739)
		(width 0.088646)
		(layer "F.Cu")
		(net "M_E_CPU0_SA_DQS_DN<2>")
	)
	(segment
		(start 408.826208 -294.062912)
		(end 408.41168 -293.648384)
		(width 0.20066)
		(layer "F.Cu")
		(net "M_E_CPU0_SA_DQS_DN<2>")
	)
	(segment
		(start 387.183376 -270.691356)
		(end 387.490208 -271.151096)
		(width 0.088646)
		(layer "F.Cu")
		(net "M_E_CPU0_SA_DQS_DN<2>")
	)
	(segment
		(start 385.897374 -270.56588)
		(end 385.912614 -270.51762)
		(width 0.088646)
		(layer "F.Cu")
		(net "M_E_CPU0_SA_DQS_DN<2>")
	)
	(segment
		(start 384.124962 -269.66164)
		(end 384.79349 -269.945866)
		(width 0.088646)
		(layer "F.Cu")
		(net "M_E_CPU0_SA_DQS_DN<2>")
	)
	(segment
		(start 412.419292 -294.0177)
		(end 412.186628 -293.785036)
		(width 0.20066)
		(layer "F.Cu")
		(net "M_E_CPU0_SA_DQS_DN<2>")
	)
	(segment
		(start 412.724346 -294.0177)
		(end 412.419292 -294.0177)
		(width 0.20066)
		(layer "F.Cu")
		(net "M_E_CPU0_SA_DQS_DN<2>")
	)
	(segment
		(start 405.848312 -293.698676)
		(end 406.18029 -293.366698)
		(width 0.20066)
		(layer "F.Cu")
		(net "M_E_CPU0_SA_DQS_DN<2>")
	)
	(segment
		(start 399.266156 -295.981374)
		(end 402.979128 -295.981374)
		(width 0.20066)
		(layer "F.Cu")
		(net "M_E_CPU0_SA_DQS_DN<2>")
	)
	(segment
		(start 386.9563 -270.109442)
		(end 386.956046 -270.109442)
		(width 0.088646)
		(layer "F.Cu")
		(net "M_E_CPU0_SA_DQS_DN<2>")
	)
	(segment
		(start 392.523218 -280.336498)
		(end 392.523218 -289.290252)
		(width 0.1524)
		(layer "F.Cu")
		(net "M_E_CPU0_SA_DQS_DN<2>")
	)
	(segment
		(start 387.78688 -271.477232)
		(end 391.492232 -275.182584)
		(width 0.1524)
		(layer "F.Cu")
		(net "M_E_CPU0_SA_DQS_DN<2>")
	)
	(segment
		(start 387.490208 -271.151096)
		(end 387.648958 -271.365726)
		(width 0.088646)
		(layer "F.Cu")
		(net "M_E_CPU0_SA_DQS_DN<2>")
	)
	(segment
		(start 392.722354 -289.489388)
		(end 392.774424 -289.489388)
		(width 0.1524)
		(layer "F.Cu")
		(net "M_E_CPU0_SA_DQS_DN<2>")
	)
	(segment
		(start 409.83662 -293.775892)
		(end 409.831794 -293.775892)
		(width 0.101854)
		(layer "F.Cu")
		(net "M_E_CPU0_SA_DQS_DN<2>")
	)
	(segment
		(start 409.542742 -293.775892)
		(end 409.255722 -294.062912)
		(width 0.20066)
		(layer "F.Cu")
		(net "M_E_CPU0_SA_DQS_DN<2>")
	)
	(segment
		(start 386.817108 -270.00327)
		(end 386.821426 -270.00581)
		(width 0.088646)
		(layer "F.Cu")
		(net "M_E_CPU0_SA_DQS_DN<2>")
	)
	(segment
		(start 402.979128 -295.981374)
		(end 405.261826 -293.698676)
		(width 0.20066)
		(layer "F.Cu")
		(net "M_E_CPU0_SA_DQS_DN<2>")
	)
	(segment
		(start 413.748474 -293.366698)
		(end 413.507936 -293.607236)
		(width 0.20066)
		(layer "F.Cu")
		(net "M_E_CPU0_SA_DQS_DN<2>")
	)
	(segment
		(start 399.266156 -295.98112)
		(end 399.266156 -295.981374)
		(width 0.20066)
		(layer "F.Cu")
		(net "M_E_CPU0_SA_DQS_DN<2>")
	)
	(segment
		(start 405.261826 -293.698676)
		(end 405.848312 -293.698676)
		(width 0.20066)
		(layer "F.Cu")
		(net "M_E_CPU0_SA_DQS_DN<2>")
	)
	(arc
		(start 385.92125 -270.472408)
		(mid 386.099618 -270.099067)
		(end 386.484622 -269.94739)
		(width 0.088646)
		(layer "F.Cu")
		(net "M_E_CPU0_SA_DQS_DN<2>")
	)
	(arc
		(start 384.793236 -269.946628)
		(mid 384.898236 -269.999603)
		(end 384.989832 -270.073374)
		(width 0.088646)
		(layer "F.Cu")
		(net "M_E_CPU0_SA_DQS_DN<2>")
	)
	(arc
		(start 386.956046 -270.109442)
		(mid 387.066369 -270.264196)
		(end 387.10616 -270.450056)
		(width 0.088646)
		(layer "F.Cu")
		(net "M_E_CPU0_SA_DQS_DN<2>")
	)
	(arc
		(start 387.10616 -270.450056)
		(mid 387.114257 -270.522589)
		(end 387.135878 -270.592296)
		(width 0.088646)
		(layer "F.Cu")
		(net "M_E_CPU0_SA_DQS_DN<2>")
	)
	(arc
		(start 385.391406 -270.81861)
		(mid 385.697582 -270.798773)
		(end 385.897374 -270.56588)
		(width 0.088646)
		(layer "F.Cu")
		(net "M_E_CPU0_SA_DQS_DN<2>")
	)
	(arc
		(start 386.595112 -269.94739)
		(mid 386.709587 -269.961514)
		(end 386.817108 -270.00327)
		(width 0.088646)
		(layer "F.Cu")
		(net "M_E_CPU0_SA_DQS_DN<2>")
	)
	(arc
		(start 384.989832 -270.073374)
		(mid 385.090295 -270.204543)
		(end 385.153154 -270.357346)
		(width 0.088646)
		(layer "F.Cu")
		(net "M_E_CPU0_SA_DQS_DN<2>")
	)
	(arc
		(start 385.153408 -270.357346)
		(mid 385.166531 -270.422215)
		(end 385.172204 -270.488156)
		(width 0.088646)
		(layer "F.Cu")
		(net "M_E_CPU0_SA_DQS_DN<2>")
	)
	(arc
		(start 385.350004 -270.79829)
		(mid 385.370078 -270.809727)
		(end 385.391406 -270.81861)
		(width 0.088646)
		(layer "F.Cu")
		(net "M_E_CPU0_SA_DQS_DN<2>")
	)
	(arc
		(start 385.172204 -270.488156)
		(mid 385.221159 -270.663158)
		(end 385.345432 -270.79575)
		(width 0.088646)
		(layer "F.Cu")
		(net "M_E_CPU0_SA_DQS_DN<2>")
	)
	(arc
		(start 386.821426 -270.00581)
		(mid 386.89227 -270.052601)
		(end 386.955792 -270.108934)
		(width 0.088646)
		(layer "F.Cu")
		(net "M_E_CPU0_SA_DQS_DN<2>")
	)
	(arc
		(start 385.912614 -270.517112)
		(mid 385.918289 -270.495021)
		(end 385.92125 -270.472408)
		(width 0.088646)
		(layer "F.Cu")
		(net "M_E_CPU0_SA_DQS_DN<2>")
	)
	(segment
		(start 412.176722 -303.125124)
		(end 411.863794 -303.125124)
		(width 0.20066)
		(layer "F.Cu")
		(net "M_E_CPU0_SA_DQS_DN<1>")
	)
	(segment
		(start 409.83662 -303.141634)
		(end 409.633928 -303.141634)
		(width 0.101854)
		(layer "F.Cu")
		(net "M_E_CPU0_SA_DQS_DN<1>")
	)
	(segment
		(start 409.255722 -303.412906)
		(end 408.75839 -303.412906)
		(width 0.20066)
		(layer "F.Cu")
		(net "M_E_CPU0_SA_DQS_DN<1>")
	)
	(segment
		(start 411.847284 -303.141634)
		(end 409.83662 -303.141634)
		(width 0.1016)
		(layer "F.Cu")
		(net "M_E_CPU0_SA_DQS_DN<1>")
	)
	(segment
		(start 407.301954 -302.716692)
		(end 406.753314 -302.716692)
		(width 0.20066)
		(layer "F.Cu")
		(net "M_E_CPU0_SA_DQS_DN<1>")
	)
	(segment
		(start 380.835916 -272.103342)
		(end 380.835916 -272.639028)
		(width 0.20066)
		(layer "F.Cu")
		(net "M_E_CPU0_SA_DQS_DN<1>")
	)
	(segment
		(start 380.835916 -272.639028)
		(end 380.835662 -272.639282)
		(width 0.20066)
		(layer "F.Cu")
		(net "M_E_CPU0_SA_DQS_DN<1>")
	)
	(segment
		(start 411.863794 -303.125124)
		(end 411.847284 -303.141634)
		(width 0.1016)
		(layer "F.Cu")
		(net "M_E_CPU0_SA_DQS_DN<1>")
	)
	(segment
		(start 413.707834 -302.716692)
		(end 413.457644 -302.966882)
		(width 0.20066)
		(layer "F.Cu")
		(net "M_E_CPU0_SA_DQS_DN<1>")
	)
	(segment
		(start 412.754826 -303.367694)
		(end 412.419292 -303.367694)
		(width 0.20066)
		(layer "F.Cu")
		(net "M_E_CPU0_SA_DQS_DN<1>")
	)
	(segment
		(start 409.526994 -303.141634)
		(end 409.255722 -303.412906)
		(width 0.20066)
		(layer "F.Cu")
		(net "M_E_CPU0_SA_DQS_DN<1>")
	)
	(segment
		(start 408.75839 -303.412906)
		(end 408.343862 -302.998378)
		(width 0.20066)
		(layer "F.Cu")
		(net "M_E_CPU0_SA_DQS_DN<1>")
	)
	(segment
		(start 412.419292 -303.367694)
		(end 412.176722 -303.125124)
		(width 0.20066)
		(layer "F.Cu")
		(net "M_E_CPU0_SA_DQS_DN<1>")
	)
	(segment
		(start 413.155638 -302.966882)
		(end 412.754826 -303.367694)
		(width 0.20066)
		(layer "F.Cu")
		(net "M_E_CPU0_SA_DQS_DN<1>")
	)
	(segment
		(start 407.58364 -302.998378)
		(end 407.301954 -302.716692)
		(width 0.20066)
		(layer "F.Cu")
		(net "M_E_CPU0_SA_DQS_DN<1>")
	)
	(segment
		(start 413.457644 -302.966882)
		(end 413.155638 -302.966882)
		(width 0.20066)
		(layer "F.Cu")
		(net "M_E_CPU0_SA_DQS_DN<1>")
	)
	(segment
		(start 408.343862 -302.998378)
		(end 407.58364 -302.998378)
		(width 0.20066)
		(layer "F.Cu")
		(net "M_E_CPU0_SA_DQS_DN<1>")
	)
	(segment
		(start 406.753314 -302.716692)
		(end 405.623014 -302.716692)
		(width 0.20066)
		(layer "F.Cu")
		(net "M_E_CPU0_SA_DQS_DN<1>")
	)
	(segment
		(start 409.633928 -303.141634)
		(end 409.526994 -303.141634)
		(width 0.20066)
		(layer "F.Cu")
		(net "M_E_CPU0_SA_DQS_DN<1>")
	)
	(segment
		(start 414.297114 -302.716692)
		(end 413.707834 -302.716692)
		(width 0.20066)
		(layer "F.Cu")
		(net "M_E_CPU0_SA_DQS_DN<1>")
	)
	(segment
		(start 382.902714 -272.963386)
		(end 382.902968 -272.963894)
		(width 0.088646)
		(layer "In2.Cu")
		(net "M_E_CPU0_SA_DQS_DN<1>")
	)
	(segment
		(start 393.90447 -279.853644)
		(end 392.675618 -276.887686)
		(width 0.18288)
		(layer "In2.Cu")
		(net "M_E_CPU0_SA_DQS_DN<1>")
	)
	(segment
		(start 388.780782 -273.733514)
		(end 388.02437 -273.733514)
		(width 0.088646)
		(layer "In2.Cu")
		(net "M_E_CPU0_SA_DQS_DN<1>")
	)
	(segment
		(start 405.623014 -302.716692)
		(end 405.369522 -302.970184)
		(width 0.18288)
		(layer "In2.Cu")
		(net "M_E_CPU0_SA_DQS_DN<1>")
	)
	(segment
		(start 382.540002 -272.971006)
		(end 382.463802 -272.925286)
		(width 0.088646)
		(layer "In2.Cu")
		(net "M_E_CPU0_SA_DQS_DN<1>")
	)
	(segment
		(start 403.072092 -296.18051)
		(end 400.802856 -290.69157)
		(width 0.18288)
		(layer "In2.Cu")
		(net "M_E_CPU0_SA_DQS_DN<1>")
	)
	(segment
		(start 392.675618 -276.887686)
		(end 389.461248 -273.67357)
		(width 0.18288)
		(layer "In2.Cu")
		(net "M_E_CPU0_SA_DQS_DN<1>")
	)
	(segment
		(start 383.456434 -272.957036)
		(end 383.453132 -272.955004)
		(width 0.088646)
		(layer "In2.Cu")
		(net "M_E_CPU0_SA_DQS_DN<1>")
	)
	(segment
		(start 397.438372 -283.387546)
		(end 393.90447 -279.853644)
		(width 0.18288)
		(layer "In2.Cu")
		(net "M_E_CPU0_SA_DQS_DN<1>")
	)
	(segment
		(start 381.348234 -272.639282)
		(end 380.835662 -272.639282)
		(width 0.088646)
		(layer "In2.Cu")
		(net "M_E_CPU0_SA_DQS_DN<1>")
	)
	(segment
		(start 404.909274 -302.970184)
		(end 403.072092 -301.133002)
		(width 0.18288)
		(layer "In2.Cu")
		(net "M_E_CPU0_SA_DQS_DN<1>")
	)
	(segment
		(start 383.467864 -272.96364)
		(end 383.465578 -272.96237)
		(width 0.088646)
		(layer "In2.Cu")
		(net "M_E_CPU0_SA_DQS_DN<1>")
	)
	(segment
		(start 382.463802 -272.925286)
		(end 382.136904 -272.515838)
		(width 0.088646)
		(layer "In2.Cu")
		(net "M_E_CPU0_SA_DQS_DN<1>")
	)
	(segment
		(start 405.369522 -302.970184)
		(end 404.909274 -302.970184)
		(width 0.18288)
		(layer "In2.Cu")
		(net "M_E_CPU0_SA_DQS_DN<1>")
	)
	(segment
		(start 388.840726 -273.67357)
		(end 388.780782 -273.733514)
		(width 0.088646)
		(layer "In2.Cu")
		(net "M_E_CPU0_SA_DQS_DN<1>")
	)
	(segment
		(start 400.802856 -290.69157)
		(end 397.438372 -287.327086)
		(width 0.18288)
		(layer "In2.Cu")
		(net "M_E_CPU0_SA_DQS_DN<1>")
	)
	(segment
		(start 403.072092 -301.133002)
		(end 403.072092 -296.18051)
		(width 0.18288)
		(layer "In2.Cu")
		(net "M_E_CPU0_SA_DQS_DN<1>")
	)
	(segment
		(start 397.438372 -287.327086)
		(end 397.438372 -283.387546)
		(width 0.18288)
		(layer "In2.Cu")
		(net "M_E_CPU0_SA_DQS_DN<1>")
	)
	(segment
		(start 382.136904 -272.515838)
		(end 382.099058 -272.450306)
		(width 0.088646)
		(layer "In2.Cu")
		(net "M_E_CPU0_SA_DQS_DN<1>")
	)
	(segment
		(start 383.465578 -272.96237)
		(end 383.456434 -272.957036)
		(width 0.088646)
		(layer "In2.Cu")
		(net "M_E_CPU0_SA_DQS_DN<1>")
	)
	(segment
		(start 389.461248 -273.67357)
		(end 388.840726 -273.67357)
		(width 0.18288)
		(layer "In2.Cu")
		(net "M_E_CPU0_SA_DQS_DN<1>")
	)
	(segment
		(start 381.405384 -272.582132)
		(end 381.348234 -272.639282)
		(width 0.088646)
		(layer "In2.Cu")
		(net "M_E_CPU0_SA_DQS_DN<1>")
	)
	(segment
		(start 388.02437 -273.733514)
		(end 387.344158 -273.053302)
		(width 0.088646)
		(layer "In2.Cu")
		(net "M_E_CPU0_SA_DQS_DN<1>")
	)
	(arc
		(start 384.407664 -272.96364)
		(mid 384.124962 -272.887864)
		(end 383.84226 -272.96364)
		(width 0.088646)
		(layer "In2.Cu")
		(net "M_E_CPU0_SA_DQS_DN<1>")
	)
	(arc
		(start 385.72186 -272.96364)
		(mid 385.534662 -273.013783)
		(end 385.347464 -272.96364)
		(width 0.088646)
		(layer "In2.Cu")
		(net "M_E_CPU0_SA_DQS_DN<1>")
	)
	(arc
		(start 383.453132 -272.955004)
		(mid 383.17683 -272.887682)
		(end 382.902714 -272.963386)
		(width 0.088646)
		(layer "In2.Cu")
		(net "M_E_CPU0_SA_DQS_DN<1>")
	)
	(arc
		(start 386.287264 -272.96364)
		(mid 386.004562 -272.887864)
		(end 385.72186 -272.96364)
		(width 0.088646)
		(layer "In2.Cu")
		(net "M_E_CPU0_SA_DQS_DN<1>")
	)
	(arc
		(start 387.227064 -272.96364)
		(mid 386.944362 -272.887864)
		(end 386.66166 -272.96364)
		(width 0.088646)
		(layer "In2.Cu")
		(net "M_E_CPU0_SA_DQS_DN<1>")
	)
	(arc
		(start 384.78206 -272.96364)
		(mid 384.594862 -273.013783)
		(end 384.407664 -272.96364)
		(width 0.088646)
		(layer "In2.Cu")
		(net "M_E_CPU0_SA_DQS_DN<1>")
	)
	(arc
		(start 385.347464 -272.96364)
		(mid 385.064762 -272.887864)
		(end 384.78206 -272.96364)
		(width 0.088646)
		(layer "In2.Cu")
		(net "M_E_CPU0_SA_DQS_DN<1>")
	)
	(arc
		(start 387.344158 -273.053302)
		(mid 387.288553 -273.004628)
		(end 387.227064 -272.96364)
		(width 0.088646)
		(layer "In2.Cu")
		(net "M_E_CPU0_SA_DQS_DN<1>")
	)
	(arc
		(start 386.66166 -272.96364)
		(mid 386.474462 -273.013783)
		(end 386.287264 -272.96364)
		(width 0.088646)
		(layer "In2.Cu")
		(net "M_E_CPU0_SA_DQS_DN<1>")
	)
	(arc
		(start 381.947166 -272.306034)
		(mid 381.605612 -272.305345)
		(end 381.405384 -272.582132)
		(width 0.088646)
		(layer "In2.Cu")
		(net "M_E_CPU0_SA_DQS_DN<1>")
	)
	(arc
		(start 382.099058 -272.450306)
		(mid 382.033463 -272.36727)
		(end 381.947166 -272.306034)
		(width 0.088646)
		(layer "In2.Cu")
		(net "M_E_CPU0_SA_DQS_DN<1>")
	)
	(arc
		(start 383.84226 -272.96364)
		(mid 383.655062 -273.013783)
		(end 383.467864 -272.96364)
		(width 0.088646)
		(layer "In2.Cu")
		(net "M_E_CPU0_SA_DQS_DN<1>")
	)
	(arc
		(start 382.902968 -272.963894)
		(mid 382.722397 -273.014312)
		(end 382.540002 -272.971006)
		(width 0.088646)
		(layer "In2.Cu")
		(net "M_E_CPU0_SA_DQS_DN<1>")
	)
	(segment
		(start 405.109934 -312.296302)
		(end 405.931116 -312.296302)
		(width 0.20066)
		(layer "F.Cu")
		(net "M_E_CPU0_SA_DQS_DN<0>")
	)
	(segment
		(start 414.297114 -312.066686)
		(end 413.784034 -312.066686)
		(width 0.20066)
		(layer "F.Cu")
		(net "M_E_CPU0_SA_DQS_DN<0>")
	)
	(segment
		(start 401.410424 -309.470044)
		(end 401.835874 -309.895494)
		(width 0.20066)
		(layer "F.Cu")
		(net "M_E_CPU0_SA_DQS_DN<0>")
	)
	(segment
		(start 386.996432 -276.548596)
		(end 387.199886 -276.75205)
		(width 0.088646)
		(layer "F.Cu")
		(net "M_E_CPU0_SA_DQS_DN<0>")
	)
	(segment
		(start 393.96162 -302.020986)
		(end 400.808698 -308.868064)
		(width 0.20066)
		(layer "F.Cu")
		(net "M_E_CPU0_SA_DQS_DN<0>")
	)
	(segment
		(start 407.301954 -312.066686)
		(end 406.753314 -312.066686)
		(width 0.20066)
		(layer "F.Cu")
		(net "M_E_CPU0_SA_DQS_DN<0>")
	)
	(segment
		(start 408.977338 -312.7629)
		(end 408.42438 -312.7629)
		(width 0.20066)
		(layer "F.Cu")
		(net "M_E_CPU0_SA_DQS_DN<0>")
	)
	(segment
		(start 412.346902 -312.485786)
		(end 411.863794 -312.485786)
		(width 0.20066)
		(layer "F.Cu")
		(net "M_E_CPU0_SA_DQS_DN<0>")
	)
	(segment
		(start 402.437854 -310.321452)
		(end 402.437854 -310.49722)
		(width 0.20066)
		(layer "F.Cu")
		(net "M_E_CPU0_SA_DQS_DN<0>")
	)
	(segment
		(start 389.523732 -296.68724)
		(end 389.859012 -297.02252)
		(width 0.20066)
		(layer "F.Cu")
		(net "M_E_CPU0_SA_DQS_DN<0>")
	)
	(segment
		(start 386.690108 -276.421342)
		(end 386.996432 -276.548342)
		(width 0.088646)
		(layer "F.Cu")
		(net "M_E_CPU0_SA_DQS_DN<0>")
	)
	(segment
		(start 388.565644 -293.563548)
		(end 389.08609 -296.177462)
		(width 0.1524)
		(layer "F.Cu")
		(net "M_E_CPU0_SA_DQS_DN<0>")
	)
	(segment
		(start 413.784034 -312.066686)
		(end 413.543496 -312.307224)
		(width 0.20066)
		(layer "F.Cu")
		(net "M_E_CPU0_SA_DQS_DN<0>")
	)
	(segment
		(start 386.474208 -276.421342)
		(end 386.690108 -276.421342)
		(width 0.088646)
		(layer "F.Cu")
		(net "M_E_CPU0_SA_DQS_DN<0>")
	)
	(segment
		(start 389.08609 -296.177462)
		(end 389.229092 -296.444924)
		(width 0.1524)
		(layer "F.Cu")
		(net "M_E_CPU0_SA_DQS_DN<0>")
	)
	(segment
		(start 412.606236 -312.74512)
		(end 412.346902 -312.485786)
		(width 0.20066)
		(layer "F.Cu")
		(net "M_E_CPU0_SA_DQS_DN<0>")
	)
	(segment
		(start 406.160732 -312.066686)
		(end 406.753314 -312.066686)
		(width 0.20066)
		(layer "F.Cu")
		(net "M_E_CPU0_SA_DQS_DN<0>")
	)
	(segment
		(start 409.86583 -312.491628)
		(end 409.83662 -312.462418)
		(width 0.1016)
		(layer "F.Cu")
		(net "M_E_CPU0_SA_DQS_DN<0>")
	)
	(segment
		(start 402.853906 -310.913272)
		(end 404.534878 -312.036206)
		(width 0.20066)
		(layer "F.Cu")
		(net "M_E_CPU0_SA_DQS_DN<0>")
	)
	(segment
		(start 411.863794 -312.485786)
		(end 411.857952 -312.491628)
		(width 0.1016)
		(layer "F.Cu")
		(net "M_E_CPU0_SA_DQS_DN<0>")
	)
	(segment
		(start 412.785306 -312.74512)
		(end 412.606236 -312.74512)
		(width 0.20066)
		(layer "F.Cu")
		(net "M_E_CPU0_SA_DQS_DN<0>")
	)
	(segment
		(start 400.984466 -308.868064)
		(end 401.410424 -309.294022)
		(width 0.20066)
		(layer "F.Cu")
		(net "M_E_CPU0_SA_DQS_DN<0>")
	)
	(segment
		(start 386.004562 -276.172676)
		(end 385.902454 -276.200108)
		(width 0.088646)
		(layer "F.Cu")
		(net "M_E_CPU0_SA_DQS_DN<0>")
	)
	(segment
		(start 387.388354 -277.140162)
		(end 387.433566 -277.140162)
		(width 0.088646)
		(layer "F.Cu")
		(net "M_E_CPU0_SA_DQS_DN<0>")
	)
	(segment
		(start 402.437854 -310.49722)
		(end 402.853906 -310.913272)
		(width 0.20066)
		(layer "F.Cu")
		(net "M_E_CPU0_SA_DQS_DN<0>")
	)
	(segment
		(start 387.199886 -276.75205)
		(end 387.199886 -276.951694)
		(width 0.088646)
		(layer "F.Cu")
		(net "M_E_CPU0_SA_DQS_DN<0>")
	)
	(segment
		(start 401.410424 -309.294022)
		(end 401.410424 -309.470044)
		(width 0.20066)
		(layer "F.Cu")
		(net "M_E_CPU0_SA_DQS_DN<0>")
	)
	(segment
		(start 387.433566 -277.140162)
		(end 387.44906 -277.155656)
		(width 0.088646)
		(layer "F.Cu")
		(net "M_E_CPU0_SA_DQS_DN<0>")
	)
	(segment
		(start 386.996432 -276.548342)
		(end 386.996432 -276.548596)
		(width 0.088646)
		(layer "F.Cu")
		(net "M_E_CPU0_SA_DQS_DN<0>")
	)
	(segment
		(start 413.223202 -312.307224)
		(end 412.785306 -312.74512)
		(width 0.20066)
		(layer "F.Cu")
		(net "M_E_CPU0_SA_DQS_DN<0>")
	)
	(segment
		(start 409.27782 -312.462418)
		(end 408.977338 -312.7629)
		(width 0.20066)
		(layer "F.Cu")
		(net "M_E_CPU0_SA_DQS_DN<0>")
	)
	(segment
		(start 389.496808 -296.660316)
		(end 389.523732 -296.68724)
		(width 0.1524)
		(layer "F.Cu")
		(net "M_E_CPU0_SA_DQS_DN<0>")
	)
	(segment
		(start 388.565644 -280.616914)
		(end 388.565644 -293.563548)
		(width 0.1524)
		(layer "F.Cu")
		(net "M_E_CPU0_SA_DQS_DN<0>")
	)
	(segment
		(start 408.009852 -312.348372)
		(end 407.58364 -312.348372)
		(width 0.20066)
		(layer "F.Cu")
		(net "M_E_CPU0_SA_DQS_DN<0>")
	)
	(segment
		(start 407.58364 -312.348372)
		(end 407.301954 -312.066686)
		(width 0.20066)
		(layer "F.Cu")
		(net "M_E_CPU0_SA_DQS_DN<0>")
	)
	(segment
		(start 404.534878 -312.036206)
		(end 405.109934 -312.296302)
		(width 0.20066)
		(layer "F.Cu")
		(net "M_E_CPU0_SA_DQS_DN<0>")
	)
	(segment
		(start 409.831794 -312.462418)
		(end 409.27782 -312.462418)
		(width 0.20066)
		(layer "F.Cu")
		(net "M_E_CPU0_SA_DQS_DN<0>")
	)
	(segment
		(start 385.821936 -276.339808)
		(end 385.871212 -276.522434)
		(width 0.088646)
		(layer "F.Cu")
		(net "M_E_CPU0_SA_DQS_DN<0>")
	)
	(segment
		(start 402.011896 -309.895494)
		(end 402.437854 -310.321452)
		(width 0.20066)
		(layer "F.Cu")
		(net "M_E_CPU0_SA_DQS_DN<0>")
	)
	(segment
		(start 389.229092 -296.444924)
		(end 389.444484 -296.660316)
		(width 0.1524)
		(layer "F.Cu")
		(net "M_E_CPU0_SA_DQS_DN<0>")
	)
	(segment
		(start 413.543496 -312.307224)
		(end 413.223202 -312.307224)
		(width 0.20066)
		(layer "F.Cu")
		(net "M_E_CPU0_SA_DQS_DN<0>")
	)
	(segment
		(start 385.902454 -276.200108)
		(end 385.821936 -276.339808)
		(width 0.088646)
		(layer "F.Cu")
		(net "M_E_CPU0_SA_DQS_DN<0>")
	)
	(segment
		(start 409.83662 -312.462418)
		(end 409.831794 -312.462418)
		(width 0.101854)
		(layer "F.Cu")
		(net "M_E_CPU0_SA_DQS_DN<0>")
	)
	(segment
		(start 387.44906 -277.155656)
		(end 387.863588 -277.570184)
		(width 0.1524)
		(layer "F.Cu")
		(net "M_E_CPU0_SA_DQS_DN<0>")
	)
	(segment
		(start 387.863588 -277.570184)
		(end 388.565644 -280.616914)
		(width 0.1524)
		(layer "F.Cu")
		(net "M_E_CPU0_SA_DQS_DN<0>")
	)
	(segment
		(start 411.857952 -312.491628)
		(end 409.86583 -312.491628)
		(width 0.1016)
		(layer "F.Cu")
		(net "M_E_CPU0_SA_DQS_DN<0>")
	)
	(segment
		(start 408.42438 -312.7629)
		(end 408.009852 -312.348372)
		(width 0.20066)
		(layer "F.Cu")
		(net "M_E_CPU0_SA_DQS_DN<0>")
	)
	(segment
		(start 389.859012 -297.02252)
		(end 393.96162 -302.020986)
		(width 0.20066)
		(layer "F.Cu")
		(net "M_E_CPU0_SA_DQS_DN<0>")
	)
	(segment
		(start 387.199886 -276.951694)
		(end 387.388354 -277.140162)
		(width 0.088646)
		(layer "F.Cu")
		(net "M_E_CPU0_SA_DQS_DN<0>")
	)
	(segment
		(start 389.444484 -296.660316)
		(end 389.496808 -296.660316)
		(width 0.1524)
		(layer "F.Cu")
		(net "M_E_CPU0_SA_DQS_DN<0>")
	)
	(segment
		(start 400.808698 -308.868064)
		(end 400.984466 -308.868064)
		(width 0.20066)
		(layer "F.Cu")
		(net "M_E_CPU0_SA_DQS_DN<0>")
	)
	(segment
		(start 405.931116 -312.296302)
		(end 406.160732 -312.066686)
		(width 0.20066)
		(layer "F.Cu")
		(net "M_E_CPU0_SA_DQS_DN<0>")
	)
	(segment
		(start 401.835874 -309.895494)
		(end 402.011896 -309.895494)
		(width 0.20066)
		(layer "F.Cu")
		(net "M_E_CPU0_SA_DQS_DN<0>")
	)
	(arc
		(start 385.871212 -276.522434)
		(mid 386.034357 -276.545916)
		(end 386.19176 -276.497034)
		(width 0.088646)
		(layer "F.Cu")
		(net "M_E_CPU0_SA_DQS_DN<0>")
	)
	(arc
		(start 386.19176 -276.497034)
		(mid 386.312224 -276.444985)
		(end 386.441442 -276.422104)
		(width 0.088646)
		(layer "F.Cu")
		(net "M_E_CPU0_SA_DQS_DN<0>")
	)
	(arc
		(start 386.441442 -276.422104)
		(mid 386.457566 -276.421493)
		(end 386.4737 -276.421342)
		(width 0.088646)
		(layer "F.Cu")
		(net "M_E_CPU0_SA_DQS_DN<0>")
	)
	(arc
		(start 386.4737 -276.421342)
		(mid 386.473954 -276.421342)
		(end 386.474208 -276.421342)
		(width 0.088646)
		(layer "F.Cu")
		(net "M_E_CPU0_SA_DQS_DN<0>")
	)
	(segment
		(start 411.863794 -304.832766)
		(end 411.854904 -304.841656)
		(width 0.1016)
		(layer "F.Cu")
		(net "M_E_CPU0_SA_DQ<9>")
	)
	(segment
		(start 409.185872 -305.493928)
		(end 408.974036 -305.705764)
		(width 0.20066)
		(layer "F.Cu")
		(net "M_E_CPU0_SA_DQ<9>")
	)
	(segment
		(start 406.753314 -305.266598)
		(end 405.623014 -305.266598)
		(width 0.20066)
		(layer "F.Cu")
		(net "M_E_CPU0_SA_DQ<9>")
	)
	(segment
		(start 412.218378 -304.832766)
		(end 411.863794 -304.832766)
		(width 0.20066)
		(layer "F.Cu")
		(net "M_E_CPU0_SA_DQ<9>")
	)
	(segment
		(start 409.83662 -304.841656)
		(end 409.650692 -304.841656)
		(width 0.101854)
		(layer "F.Cu")
		(net "M_E_CPU0_SA_DQ<9>")
	)
	(segment
		(start 409.339034 -304.841656)
		(end 409.185872 -304.994818)
		(width 0.20066)
		(layer "F.Cu")
		(net "M_E_CPU0_SA_DQ<9>")
	)
	(segment
		(start 409.650692 -304.841656)
		(end 409.339034 -304.841656)
		(width 0.20066)
		(layer "F.Cu")
		(net "M_E_CPU0_SA_DQ<9>")
	)
	(segment
		(start 381.305562 -272.917158)
		(end 381.305562 -273.452844)
		(width 0.20066)
		(layer "F.Cu")
		(net "M_E_CPU0_SA_DQ<9>")
	)
	(segment
		(start 408.974036 -305.705764)
		(end 408.553158 -305.705764)
		(width 0.20066)
		(layer "F.Cu")
		(net "M_E_CPU0_SA_DQ<9>")
	)
	(segment
		(start 411.854904 -304.841656)
		(end 409.83662 -304.841656)
		(width 0.1016)
		(layer "F.Cu")
		(net "M_E_CPU0_SA_DQ<9>")
	)
	(segment
		(start 408.553158 -305.705764)
		(end 408.113992 -305.266598)
		(width 0.20066)
		(layer "F.Cu")
		(net "M_E_CPU0_SA_DQ<9>")
	)
	(segment
		(start 414.297114 -305.266598)
		(end 412.65221 -305.266598)
		(width 0.20066)
		(layer "F.Cu")
		(net "M_E_CPU0_SA_DQ<9>")
	)
	(segment
		(start 412.65221 -305.266598)
		(end 412.218378 -304.832766)
		(width 0.20066)
		(layer "F.Cu")
		(net "M_E_CPU0_SA_DQ<9>")
	)
	(segment
		(start 409.185872 -304.994818)
		(end 409.185872 -305.493928)
		(width 0.20066)
		(layer "F.Cu")
		(net "M_E_CPU0_SA_DQ<9>")
	)
	(segment
		(start 381.305562 -273.452844)
		(end 381.305816 -273.453098)
		(width 0.20066)
		(layer "F.Cu")
		(net "M_E_CPU0_SA_DQ<9>")
	)
	(segment
		(start 408.113992 -305.266598)
		(end 406.753314 -305.266598)
		(width 0.20066)
		(layer "F.Cu")
		(net "M_E_CPU0_SA_DQ<9>")
	)
	(segment
		(start 396.353284 -288.319464)
		(end 396.111222 -288.319464)
		(width 0.18288)
		(layer "In2.Cu")
		(net "M_E_CPU0_SA_DQ<9>")
	)
	(segment
		(start 401.573746 -300.37024)
		(end 401.380706 -300.1772)
		(width 0.18288)
		(layer "In2.Cu")
		(net "M_E_CPU0_SA_DQ<9>")
	)
	(segment
		(start 401.573746 -297.553888)
		(end 401.380706 -297.360848)
		(width 0.18288)
		(layer "In2.Cu")
		(net "M_E_CPU0_SA_DQ<9>")
	)
	(segment
		(start 387.24332 -274.018502)
		(end 386.944362 -274.018502)
		(width 0.088646)
		(layer "In2.Cu")
		(net "M_E_CPU0_SA_DQ<9>")
	)
	(segment
		(start 395.984222 -288.192464)
		(end 395.984222 -283.421074)
		(width 0.18288)
		(layer "In2.Cu")
		(net "M_E_CPU0_SA_DQ<9>")
	)
	(segment
		(start 405.623014 -305.266598)
		(end 405.303228 -304.946812)
		(width 0.18288)
		(layer "In2.Cu")
		(net "M_E_CPU0_SA_DQ<9>")
	)
	(segment
		(start 401.932902 -301.898812)
		(end 401.766278 -301.898812)
		(width 0.18288)
		(layer "In2.Cu")
		(net "M_E_CPU0_SA_DQ<9>")
	)
	(segment
		(start 402.617686 -302.583596)
		(end 401.932902 -301.898812)
		(width 0.18288)
		(layer "In2.Cu")
		(net "M_E_CPU0_SA_DQ<9>")
	)
	(segment
		(start 401.245832 -296.347388)
		(end 401.403312 -295.967404)
		(width 0.18288)
		(layer "In2.Cu")
		(net "M_E_CPU0_SA_DQ<9>")
	)
	(segment
		(start 400.16684 -293.745412)
		(end 400.32432 -293.365428)
		(width 0.18288)
		(layer "In2.Cu")
		(net "M_E_CPU0_SA_DQ<9>")
	)
	(segment
		(start 399.627344 -292.444424)
		(end 399.784824 -292.06444)
		(width 0.18288)
		(layer "In2.Cu")
		(net "M_E_CPU0_SA_DQ<9>")
	)
	(segment
		(start 381.962914 -273.942556)
		(end 381.934212 -273.9263)
		(width 0.088646)
		(layer "In2.Cu")
		(net "M_E_CPU0_SA_DQ<9>")
	)
	(segment
		(start 401.380706 -299.666152)
		(end 401.573746 -299.473112)
		(width 0.18288)
		(layer "In2.Cu")
		(net "M_E_CPU0_SA_DQ<9>")
	)
	(segment
		(start 401.403312 -295.967404)
		(end 401.24507 -295.585896)
		(width 0.18288)
		(layer "In2.Cu")
		(net "M_E_CPU0_SA_DQ<9>")
	)
	(segment
		(start 405.303228 -304.810922)
		(end 404.818596 -304.32629)
		(width 0.18288)
		(layer "In2.Cu")
		(net "M_E_CPU0_SA_DQ<9>")
	)
	(segment
		(start 388.055104 -274.830286)
		(end 387.24332 -274.018502)
		(width 0.088646)
		(layer "In2.Cu")
		(net "M_E_CPU0_SA_DQ<9>")
	)
	(segment
		(start 404.193756 -304.32629)
		(end 402.617686 -302.75022)
		(width 0.18288)
		(layer "In2.Cu")
		(net "M_E_CPU0_SA_DQ<9>")
	)
	(segment
		(start 381.934212 -273.9263)
		(end 381.305816 -273.453098)
		(width 0.088646)
		(layer "In2.Cu")
		(net "M_E_CPU0_SA_DQ<9>")
	)
	(segment
		(start 401.380706 -297.360848)
		(end 401.380706 -296.672508)
		(width 0.18288)
		(layer "In2.Cu")
		(net "M_E_CPU0_SA_DQ<9>")
	)
	(segment
		(start 404.818596 -304.32629)
		(end 404.193756 -304.32629)
		(width 0.18288)
		(layer "In2.Cu")
		(net "M_E_CPU0_SA_DQ<9>")
	)
	(segment
		(start 401.766278 -301.898812)
		(end 401.380706 -301.51324)
		(width 0.18288)
		(layer "In2.Cu")
		(net "M_E_CPU0_SA_DQ<9>")
	)
	(segment
		(start 396.111222 -288.319464)
		(end 395.984222 -288.192464)
		(width 0.18288)
		(layer "In2.Cu")
		(net "M_E_CPU0_SA_DQ<9>")
	)
	(segment
		(start 401.573746 -299.473112)
		(end 401.573746 -298.962064)
		(width 0.18288)
		(layer "In2.Cu")
		(net "M_E_CPU0_SA_DQ<9>")
	)
	(segment
		(start 400.864832 -295.428416)
		(end 400.706336 -295.0464)
		(width 0.18288)
		(layer "In2.Cu")
		(net "M_E_CPU0_SA_DQ<9>")
	)
	(segment
		(start 389.179816 -274.830286)
		(end 388.840726 -274.830286)
		(width 0.18288)
		(layer "In2.Cu")
		(net "M_E_CPU0_SA_DQ<9>")
	)
	(segment
		(start 401.380706 -301.51324)
		(end 401.380706 -301.074328)
		(width 0.18288)
		(layer "In2.Cu")
		(net "M_E_CPU0_SA_DQ<9>")
	)
	(segment
		(start 399.246344 -291.525452)
		(end 399.024602 -290.990782)
		(width 0.18288)
		(layer "In2.Cu")
		(net "M_E_CPU0_SA_DQ<9>")
	)
	(segment
		(start 388.840726 -274.830286)
		(end 388.055104 -274.830286)
		(width 0.088646)
		(layer "In2.Cu")
		(net "M_E_CPU0_SA_DQ<9>")
	)
	(segment
		(start 391.8331 -277.48357)
		(end 389.179816 -274.830286)
		(width 0.18288)
		(layer "In2.Cu")
		(net "M_E_CPU0_SA_DQ<9>")
	)
	(segment
		(start 399.784824 -292.06444)
		(end 399.626582 -291.682932)
		(width 0.18288)
		(layer "In2.Cu")
		(net "M_E_CPU0_SA_DQ<9>")
	)
	(segment
		(start 399.024602 -290.990782)
		(end 396.353284 -288.319464)
		(width 0.18288)
		(layer "In2.Cu")
		(net "M_E_CPU0_SA_DQ<9>")
	)
	(segment
		(start 400.325336 -294.127428)
		(end 400.16684 -293.745412)
		(width 0.18288)
		(layer "In2.Cu")
		(net "M_E_CPU0_SA_DQ<9>")
	)
	(segment
		(start 400.32432 -293.365428)
		(end 400.166078 -292.98392)
		(width 0.18288)
		(layer "In2.Cu")
		(net "M_E_CPU0_SA_DQ<9>")
	)
	(segment
		(start 401.380706 -298.769024)
		(end 401.380706 -298.257976)
		(width 0.18288)
		(layer "In2.Cu")
		(net "M_E_CPU0_SA_DQ<9>")
	)
	(segment
		(start 401.380706 -296.672508)
		(end 401.245832 -296.347388)
		(width 0.18288)
		(layer "In2.Cu")
		(net "M_E_CPU0_SA_DQ<9>")
	)
	(segment
		(start 401.24507 -295.585896)
		(end 400.864832 -295.428416)
		(width 0.18288)
		(layer "In2.Cu")
		(net "M_E_CPU0_SA_DQ<9>")
	)
	(segment
		(start 405.303228 -304.946812)
		(end 405.303228 -304.810922)
		(width 0.18288)
		(layer "In2.Cu")
		(net "M_E_CPU0_SA_DQ<9>")
	)
	(segment
		(start 401.573746 -298.962064)
		(end 401.380706 -298.769024)
		(width 0.18288)
		(layer "In2.Cu")
		(net "M_E_CPU0_SA_DQ<9>")
	)
	(segment
		(start 400.863816 -294.666416)
		(end 400.705574 -294.284908)
		(width 0.18288)
		(layer "In2.Cu")
		(net "M_E_CPU0_SA_DQ<9>")
	)
	(segment
		(start 383.467864 -273.942556)
		(end 383.453132 -273.951192)
		(width 0.088646)
		(layer "In2.Cu")
		(net "M_E_CPU0_SA_DQ<9>")
	)
	(segment
		(start 400.705574 -294.284908)
		(end 400.325336 -294.127428)
		(width 0.18288)
		(layer "In2.Cu")
		(net "M_E_CPU0_SA_DQ<9>")
	)
	(segment
		(start 399.78584 -292.82644)
		(end 399.627344 -292.444424)
		(width 0.18288)
		(layer "In2.Cu")
		(net "M_E_CPU0_SA_DQ<9>")
	)
	(segment
		(start 401.380706 -301.074328)
		(end 401.573746 -300.881288)
		(width 0.18288)
		(layer "In2.Cu")
		(net "M_E_CPU0_SA_DQ<9>")
	)
	(segment
		(start 400.166078 -292.98392)
		(end 399.78584 -292.82644)
		(width 0.18288)
		(layer "In2.Cu")
		(net "M_E_CPU0_SA_DQ<9>")
	)
	(segment
		(start 395.984222 -283.421074)
		(end 393.096242 -280.533094)
		(width 0.18288)
		(layer "In2.Cu")
		(net "M_E_CPU0_SA_DQ<9>")
	)
	(segment
		(start 402.617686 -302.75022)
		(end 402.617686 -302.583596)
		(width 0.18288)
		(layer "In2.Cu")
		(net "M_E_CPU0_SA_DQ<9>")
	)
	(segment
		(start 401.573746 -300.881288)
		(end 401.573746 -300.37024)
		(width 0.18288)
		(layer "In2.Cu")
		(net "M_E_CPU0_SA_DQ<9>")
	)
	(segment
		(start 401.380706 -298.257976)
		(end 401.573746 -298.064936)
		(width 0.18288)
		(layer "In2.Cu")
		(net "M_E_CPU0_SA_DQ<9>")
	)
	(segment
		(start 382.528064 -273.942556)
		(end 382.52781 -273.942556)
		(width 0.088646)
		(layer "In2.Cu")
		(net "M_E_CPU0_SA_DQ<9>")
	)
	(segment
		(start 393.096242 -280.533094)
		(end 391.8331 -277.48357)
		(width 0.18288)
		(layer "In2.Cu")
		(net "M_E_CPU0_SA_DQ<9>")
	)
	(segment
		(start 401.380706 -300.1772)
		(end 401.380706 -299.666152)
		(width 0.18288)
		(layer "In2.Cu")
		(net "M_E_CPU0_SA_DQ<9>")
	)
	(segment
		(start 401.573746 -298.064936)
		(end 401.573746 -297.553888)
		(width 0.18288)
		(layer "In2.Cu")
		(net "M_E_CPU0_SA_DQ<9>")
	)
	(segment
		(start 399.626582 -291.682932)
		(end 399.246344 -291.525452)
		(width 0.18288)
		(layer "In2.Cu")
		(net "M_E_CPU0_SA_DQ<9>")
	)
	(segment
		(start 400.706336 -295.0464)
		(end 400.863816 -294.666416)
		(width 0.18288)
		(layer "In2.Cu")
		(net "M_E_CPU0_SA_DQ<9>")
	)
	(arc
		(start 383.84226 -273.942556)
		(mid 383.655062 -273.892413)
		(end 383.467864 -273.942556)
		(width 0.088646)
		(layer "In2.Cu")
		(net "M_E_CPU0_SA_DQ<9>")
	)
	(arc
		(start 384.78206 -273.942556)
		(mid 384.594862 -273.892413)
		(end 384.407664 -273.942556)
		(width 0.088646)
		(layer "In2.Cu")
		(net "M_E_CPU0_SA_DQ<9>")
	)
	(arc
		(start 386.89534 -274.01647)
		(mid 386.774436 -273.992351)
		(end 386.66166 -273.942556)
		(width 0.088646)
		(layer "In2.Cu")
		(net "M_E_CPU0_SA_DQ<9>")
	)
	(arc
		(start 383.453132 -273.951192)
		(mid 383.176657 -274.018512)
		(end 382.90246 -273.942556)
		(width 0.088646)
		(layer "In2.Cu")
		(net "M_E_CPU0_SA_DQ<9>")
	)
	(arc
		(start 386.66166 -273.942556)
		(mid 386.474462 -273.892413)
		(end 386.287264 -273.942556)
		(width 0.088646)
		(layer "In2.Cu")
		(net "M_E_CPU0_SA_DQ<9>")
	)
	(arc
		(start 382.52781 -273.942556)
		(mid 382.245362 -274.018239)
		(end 381.962914 -273.942556)
		(width 0.088646)
		(layer "In2.Cu")
		(net "M_E_CPU0_SA_DQ<9>")
	)
	(arc
		(start 386.287264 -273.942556)
		(mid 386.004562 -274.018332)
		(end 385.72186 -273.942556)
		(width 0.088646)
		(layer "In2.Cu")
		(net "M_E_CPU0_SA_DQ<9>")
	)
	(arc
		(start 385.72186 -273.942556)
		(mid 385.534662 -273.892413)
		(end 385.347464 -273.942556)
		(width 0.088646)
		(layer "In2.Cu")
		(net "M_E_CPU0_SA_DQ<9>")
	)
	(arc
		(start 386.944362 -274.018502)
		(mid 386.919829 -274.018014)
		(end 386.89534 -274.01647)
		(width 0.088646)
		(layer "In2.Cu")
		(net "M_E_CPU0_SA_DQ<9>")
	)
	(arc
		(start 385.347464 -273.942556)
		(mid 385.064762 -274.018332)
		(end 384.78206 -273.942556)
		(width 0.088646)
		(layer "In2.Cu")
		(net "M_E_CPU0_SA_DQ<9>")
	)
	(arc
		(start 384.407664 -273.942556)
		(mid 384.124962 -274.018332)
		(end 383.84226 -273.942556)
		(width 0.088646)
		(layer "In2.Cu")
		(net "M_E_CPU0_SA_DQ<9>")
	)
	(arc
		(start 382.90246 -273.942556)
		(mid 382.715262 -273.892413)
		(end 382.528064 -273.942556)
		(width 0.088646)
		(layer "In2.Cu")
		(net "M_E_CPU0_SA_DQ<9>")
	)
	(segment
		(start 381.775716 -274.26666)
		(end 381.775462 -274.266914)
		(width 0.20066)
		(layer "F.Cu")
		(net "M_E_CPU0_SA_DQ<8>")
	)
	(segment
		(start 409.036774 -306.23129)
		(end 408.566366 -306.23129)
		(width 0.20066)
		(layer "F.Cu")
		(net "M_E_CPU0_SA_DQ<8>")
	)
	(segment
		(start 407.966418 -306.96662)
		(end 406.753314 -306.96662)
		(width 0.20066)
		(layer "F.Cu")
		(net "M_E_CPU0_SA_DQ<8>")
	)
	(segment
		(start 412.209996 -306.532026)
		(end 411.863794 -306.532026)
		(width 0.20066)
		(layer "F.Cu")
		(net "M_E_CPU0_SA_DQ<8>")
	)
	(segment
		(start 409.582366 -306.541678)
		(end 409.347162 -306.541678)
		(width 0.20066)
		(layer "F.Cu")
		(net "M_E_CPU0_SA_DQ<8>")
	)
	(segment
		(start 413.258 -307.13807)
		(end 412.81604 -307.13807)
		(width 0.20066)
		(layer "F.Cu")
		(net "M_E_CPU0_SA_DQ<8>")
	)
	(segment
		(start 408.287982 -306.645056)
		(end 407.966418 -306.96662)
		(width 0.20066)
		(layer "F.Cu")
		(net "M_E_CPU0_SA_DQ<8>")
	)
	(segment
		(start 411.863794 -306.532026)
		(end 411.854142 -306.541678)
		(width 0.1016)
		(layer "F.Cu")
		(net "M_E_CPU0_SA_DQ<8>")
	)
	(segment
		(start 406.753314 -306.96662)
		(end 405.623014 -306.96662)
		(width 0.20066)
		(layer "F.Cu")
		(net "M_E_CPU0_SA_DQ<8>")
	)
	(segment
		(start 381.775716 -273.730974)
		(end 381.775716 -274.26666)
		(width 0.20066)
		(layer "F.Cu")
		(net "M_E_CPU0_SA_DQ<8>")
	)
	(segment
		(start 412.81604 -307.13807)
		(end 412.209996 -306.532026)
		(width 0.20066)
		(layer "F.Cu")
		(net "M_E_CPU0_SA_DQ<8>")
	)
	(segment
		(start 409.83662 -306.541678)
		(end 409.582366 -306.541678)
		(width 0.101854)
		(layer "F.Cu")
		(net "M_E_CPU0_SA_DQ<8>")
	)
	(segment
		(start 414.297114 -306.96662)
		(end 413.42945 -306.96662)
		(width 0.20066)
		(layer "F.Cu")
		(net "M_E_CPU0_SA_DQ<8>")
	)
	(segment
		(start 413.42945 -306.96662)
		(end 413.258 -307.13807)
		(width 0.20066)
		(layer "F.Cu")
		(net "M_E_CPU0_SA_DQ<8>")
	)
	(segment
		(start 408.287982 -306.509674)
		(end 408.287982 -306.645056)
		(width 0.20066)
		(layer "F.Cu")
		(net "M_E_CPU0_SA_DQ<8>")
	)
	(segment
		(start 411.854142 -306.541678)
		(end 409.83662 -306.541678)
		(width 0.1016)
		(layer "F.Cu")
		(net "M_E_CPU0_SA_DQ<8>")
	)
	(segment
		(start 409.347162 -306.541678)
		(end 409.036774 -306.23129)
		(width 0.20066)
		(layer "F.Cu")
		(net "M_E_CPU0_SA_DQ<8>")
	)
	(segment
		(start 408.566366 -306.23129)
		(end 408.287982 -306.509674)
		(width 0.20066)
		(layer "F.Cu")
		(net "M_E_CPU0_SA_DQ<8>")
	)
	(segment
		(start 395.409166 -289.404298)
		(end 394.968222 -288.963354)
		(width 0.18288)
		(layer "In2.Cu")
		(net "M_E_CPU0_SA_DQ<8>")
	)
	(segment
		(start 388.141718 -275.747226)
		(end 387.210046 -274.815554)
		(width 0.088646)
		(layer "In2.Cu")
		(net "M_E_CPU0_SA_DQ<8>")
	)
	(segment
		(start 392.51001 -280.924254)
		(end 391.27049 -277.93188)
		(width 0.18288)
		(layer "In2.Cu")
		(net "M_E_CPU0_SA_DQ<8>")
	)
	(segment
		(start 397.169894 -290.632134)
		(end 396.938246 -290.400486)
		(width 0.18288)
		(layer "In2.Cu")
		(net "M_E_CPU0_SA_DQ<8>")
	)
	(segment
		(start 404.263606 -305.4731)
		(end 403.778466 -305.4731)
		(width 0.18288)
		(layer "In2.Cu")
		(net "M_E_CPU0_SA_DQ<8>")
	)
	(segment
		(start 405.3332 -306.427632)
		(end 404.732998 -306.427632)
		(width 0.18288)
		(layer "In2.Cu")
		(net "M_E_CPU0_SA_DQ<8>")
	)
	(segment
		(start 389.085836 -275.747226)
		(end 388.840726 -275.747226)
		(width 0.18288)
		(layer "In2.Cu")
		(net "M_E_CPU0_SA_DQ<8>")
	)
	(segment
		(start 394.968222 -288.963354)
		(end 394.968222 -283.382466)
		(width 0.18288)
		(layer "In2.Cu")
		(net "M_E_CPU0_SA_DQ<8>")
	)
	(segment
		(start 397.169894 -291.165026)
		(end 397.169894 -290.632134)
		(width 0.18288)
		(layer "In2.Cu")
		(net "M_E_CPU0_SA_DQ<8>")
	)
	(segment
		(start 382.08839 -274.266914)
		(end 381.775462 -274.266914)
		(width 0.088646)
		(layer "In2.Cu")
		(net "M_E_CPU0_SA_DQ<8>")
	)
	(segment
		(start 404.732998 -306.427632)
		(end 404.51913 -306.213764)
		(width 0.18288)
		(layer "In2.Cu")
		(net "M_E_CPU0_SA_DQ<8>")
	)
	(segment
		(start 391.27049 -277.93188)
		(end 389.085836 -275.747226)
		(width 0.18288)
		(layer "In2.Cu")
		(net "M_E_CPU0_SA_DQ<8>")
	)
	(segment
		(start 396.173706 -289.635946)
		(end 395.942058 -289.404298)
		(width 0.18288)
		(layer "In2.Cu")
		(net "M_E_CPU0_SA_DQ<8>")
	)
	(segment
		(start 400.331432 -302.026066)
		(end 400.331432 -296.875708)
		(width 0.18288)
		(layer "In2.Cu")
		(net "M_E_CPU0_SA_DQ<8>")
	)
	(segment
		(start 382.45288 -274.768056)
		(end 382.432814 -274.756372)
		(width 0.088646)
		(layer "In2.Cu")
		(net "M_E_CPU0_SA_DQ<8>")
	)
	(segment
		(start 383.387346 -274.765262)
		(end 383.372614 -274.756626)
		(width 0.088646)
		(layer "In2.Cu")
		(net "M_E_CPU0_SA_DQ<8>")
	)
	(segment
		(start 394.968222 -283.382466)
		(end 392.51001 -280.924254)
		(width 0.18288)
		(layer "In2.Cu")
		(net "M_E_CPU0_SA_DQ<8>")
	)
	(segment
		(start 397.934434 -291.396674)
		(end 397.401542 -291.396674)
		(width 0.18288)
		(layer "In2.Cu")
		(net "M_E_CPU0_SA_DQ<8>")
	)
	(segment
		(start 385.266946 -274.765262)
		(end 385.252214 -274.756626)
		(width 0.088646)
		(layer "In2.Cu")
		(net "M_E_CPU0_SA_DQ<8>")
	)
	(segment
		(start 404.51913 -305.728624)
		(end 404.263606 -305.4731)
		(width 0.18288)
		(layer "In2.Cu")
		(net "M_E_CPU0_SA_DQ<8>")
	)
	(segment
		(start 396.173706 -290.168838)
		(end 396.173706 -289.635946)
		(width 0.18288)
		(layer "In2.Cu")
		(net "M_E_CPU0_SA_DQ<8>")
	)
	(segment
		(start 405.623014 -306.96662)
		(end 405.623014 -306.717446)
		(width 0.18288)
		(layer "In2.Cu")
		(net "M_E_CPU0_SA_DQ<8>")
	)
	(segment
		(start 382.432814 -274.756372)
		(end 382.427226 -274.75307)
		(width 0.088646)
		(layer "In2.Cu")
		(net "M_E_CPU0_SA_DQ<8>")
	)
	(segment
		(start 403.778466 -305.4731)
		(end 400.331432 -302.026066)
		(width 0.18288)
		(layer "In2.Cu")
		(net "M_E_CPU0_SA_DQ<8>")
	)
	(segment
		(start 404.51913 -306.213764)
		(end 404.51913 -305.728624)
		(width 0.18288)
		(layer "In2.Cu")
		(net "M_E_CPU0_SA_DQ<8>")
	)
	(segment
		(start 398.166082 -291.628322)
		(end 397.934434 -291.396674)
		(width 0.18288)
		(layer "In2.Cu")
		(net "M_E_CPU0_SA_DQ<8>")
	)
	(segment
		(start 388.840726 -275.747226)
		(end 388.141718 -275.747226)
		(width 0.088646)
		(layer "In2.Cu")
		(net "M_E_CPU0_SA_DQ<8>")
	)
	(segment
		(start 398.528032 -292.523164)
		(end 398.166082 -292.161214)
		(width 0.18288)
		(layer "In2.Cu")
		(net "M_E_CPU0_SA_DQ<8>")
	)
	(segment
		(start 395.942058 -289.404298)
		(end 395.409166 -289.404298)
		(width 0.18288)
		(layer "In2.Cu")
		(net "M_E_CPU0_SA_DQ<8>")
	)
	(segment
		(start 400.331432 -296.875708)
		(end 398.528032 -292.523164)
		(width 0.18288)
		(layer "In2.Cu")
		(net "M_E_CPU0_SA_DQ<8>")
	)
	(segment
		(start 397.401542 -291.396674)
		(end 397.169894 -291.165026)
		(width 0.18288)
		(layer "In2.Cu")
		(net "M_E_CPU0_SA_DQ<8>")
	)
	(segment
		(start 382.427226 -274.75307)
		(end 382.426718 -274.752816)
		(width 0.088646)
		(layer "In2.Cu")
		(net "M_E_CPU0_SA_DQ<8>")
	)
	(segment
		(start 398.166082 -292.161214)
		(end 398.166082 -291.628322)
		(width 0.18288)
		(layer "In2.Cu")
		(net "M_E_CPU0_SA_DQ<8>")
	)
	(segment
		(start 386.206746 -274.765262)
		(end 386.192014 -274.756626)
		(width 0.088646)
		(layer "In2.Cu")
		(net "M_E_CPU0_SA_DQ<8>")
	)
	(segment
		(start 384.327146 -274.765262)
		(end 384.312414 -274.756626)
		(width 0.088646)
		(layer "In2.Cu")
		(net "M_E_CPU0_SA_DQ<8>")
	)
	(segment
		(start 396.938246 -290.400486)
		(end 396.405354 -290.400486)
		(width 0.18288)
		(layer "In2.Cu")
		(net "M_E_CPU0_SA_DQ<8>")
	)
	(segment
		(start 396.405354 -290.400486)
		(end 396.173706 -290.168838)
		(width 0.18288)
		(layer "In2.Cu")
		(net "M_E_CPU0_SA_DQ<8>")
	)
	(segment
		(start 405.623014 -306.717446)
		(end 405.3332 -306.427632)
		(width 0.18288)
		(layer "In2.Cu")
		(net "M_E_CPU0_SA_DQ<8>")
	)
	(segment
		(start 382.153922 -274.332446)
		(end 382.08839 -274.266914)
		(width 0.088646)
		(layer "In2.Cu")
		(net "M_E_CPU0_SA_DQ<8>")
	)
	(arc
		(start 383.938018 -274.756626)
		(mid 383.663789 -274.832551)
		(end 383.387346 -274.765262)
		(width 0.088646)
		(layer "In2.Cu")
		(net "M_E_CPU0_SA_DQ<8>")
	)
	(arc
		(start 383.372614 -274.756626)
		(mid 383.185416 -274.706483)
		(end 382.998218 -274.756626)
		(width 0.088646)
		(layer "In2.Cu")
		(net "M_E_CPU0_SA_DQ<8>")
	)
	(arc
		(start 386.192014 -274.756626)
		(mid 386.004816 -274.706483)
		(end 385.817618 -274.756626)
		(width 0.088646)
		(layer "In2.Cu")
		(net "M_E_CPU0_SA_DQ<8>")
	)
	(arc
		(start 385.817618 -274.756626)
		(mid 385.543389 -274.832551)
		(end 385.266946 -274.765262)
		(width 0.088646)
		(layer "In2.Cu")
		(net "M_E_CPU0_SA_DQ<8>")
	)
	(arc
		(start 387.210046 -274.815554)
		(mid 387.172855 -274.783536)
		(end 387.131814 -274.756626)
		(width 0.088646)
		(layer "In2.Cu")
		(net "M_E_CPU0_SA_DQ<8>")
	)
	(arc
		(start 384.312414 -274.756626)
		(mid 384.125216 -274.706483)
		(end 383.938018 -274.756626)
		(width 0.088646)
		(layer "In2.Cu")
		(net "M_E_CPU0_SA_DQ<8>")
	)
	(arc
		(start 387.131814 -274.756626)
		(mid 386.944616 -274.706483)
		(end 386.757418 -274.756626)
		(width 0.088646)
		(layer "In2.Cu")
		(net "M_E_CPU0_SA_DQ<8>")
	)
	(arc
		(start 385.252214 -274.756626)
		(mid 385.065016 -274.706483)
		(end 384.877818 -274.756626)
		(width 0.088646)
		(layer "In2.Cu")
		(net "M_E_CPU0_SA_DQ<8>")
	)
	(arc
		(start 386.757418 -274.756626)
		(mid 386.483189 -274.832551)
		(end 386.206746 -274.765262)
		(width 0.088646)
		(layer "In2.Cu")
		(net "M_E_CPU0_SA_DQ<8>")
	)
	(arc
		(start 384.877818 -274.756626)
		(mid 384.603589 -274.832551)
		(end 384.327146 -274.765262)
		(width 0.088646)
		(layer "In2.Cu")
		(net "M_E_CPU0_SA_DQ<8>")
	)
	(arc
		(start 382.426718 -274.752816)
		(mid 382.241195 -274.574515)
		(end 382.153922 -274.332446)
		(width 0.088646)
		(layer "In2.Cu")
		(net "M_E_CPU0_SA_DQ<8>")
	)
	(arc
		(start 382.998218 -274.756626)
		(mid 382.727029 -274.832373)
		(end 382.45288 -274.768056)
		(width 0.088646)
		(layer "In2.Cu")
		(net "M_E_CPU0_SA_DQ<8>")
	)
	(segment
		(start 413.275018 -308.247288)
		(end 412.979108 -308.247288)
		(width 0.20066)
		(layer "F.Cu")
		(net "M_E_CPU0_SA_DQ<7>")
	)
	(segment
		(start 390.424924 -290.336986)
		(end 390.93521 -292.9001)
		(width 0.1016)
		(layer "F.Cu")
		(net "M_E_CPU0_SA_DQ<7>")
	)
	(segment
		(start 416.004756 -308.247034)
		(end 415.307526 -308.247034)
		(width 0.20066)
		(layer "F.Cu")
		(net "M_E_CPU0_SA_DQ<7>")
	)
	(segment
		(start 387.109716 -273.787108)
		(end 388.273036 -274.950428)
		(width 0.088646)
		(layer "F.Cu")
		(net "M_E_CPU0_SA_DQ<7>")
	)
	(segment
		(start 405.743156 -308.2417)
		(end 407.757122 -308.2417)
		(width 0.1016)
		(layer "F.Cu")
		(net "M_E_CPU0_SA_DQ<7>")
	)
	(segment
		(start 404.954232 -302.458374)
		(end 404.954232 -307.544216)
		(width 0.20066)
		(layer "F.Cu")
		(net "M_E_CPU0_SA_DQ<7>")
	)
	(segment
		(start 416.205416 -308.046374)
		(end 416.004756 -308.247034)
		(width 0.20066)
		(layer "F.Cu")
		(net "M_E_CPU0_SA_DQ<7>")
	)
	(segment
		(start 416.205416 -307.798978)
		(end 416.205416 -308.046374)
		(width 0.20066)
		(layer "F.Cu")
		(net "M_E_CPU0_SA_DQ<7>")
	)
	(segment
		(start 405.148542 -307.738526)
		(end 405.283162 -308.063646)
		(width 0.20066)
		(layer "F.Cu")
		(net "M_E_CPU0_SA_DQ<7>")
	)
	(segment
		(start 407.763726 -308.248304)
		(end 408.311096 -308.248304)
		(width 0.20066)
		(layer "F.Cu")
		(net "M_E_CPU0_SA_DQ<7>")
	)
	(segment
		(start 391.368534 -293.521384)
		(end 399.941034 -302.093884)
		(width 0.20066)
		(layer "F.Cu")
		(net "M_E_CPU0_SA_DQ<7>")
	)
	(segment
		(start 389.592566 -276.269958)
		(end 390.424924 -280.428446)
		(width 0.1016)
		(layer "F.Cu")
		(net "M_E_CPU0_SA_DQ<7>")
	)
	(segment
		(start 405.736552 -308.248304)
		(end 405.743156 -308.2417)
		(width 0.1016)
		(layer "F.Cu")
		(net "M_E_CPU0_SA_DQ<7>")
	)
	(segment
		(start 415.302192 -308.2417)
		(end 414.755584 -308.2417)
		(width 0.101854)
		(layer "F.Cu")
		(net "M_E_CPU0_SA_DQ<7>")
	)
	(segment
		(start 404.721568 -302.22571)
		(end 404.954232 -302.458374)
		(width 0.20066)
		(layer "F.Cu")
		(net "M_E_CPU0_SA_DQ<7>")
	)
	(segment
		(start 414.755584 -308.2417)
		(end 413.298132 -308.2417)
		(width 0.1016)
		(layer "F.Cu")
		(net "M_E_CPU0_SA_DQ<7>")
	)
	(segment
		(start 405.731726 -308.248304)
		(end 405.736552 -308.248304)
		(width 0.101854)
		(layer "F.Cu")
		(net "M_E_CPU0_SA_DQ<7>")
	)
	(segment
		(start 403.577298 -302.551846)
		(end 403.912578 -302.551846)
		(width 0.20066)
		(layer "F.Cu")
		(net "M_E_CPU0_SA_DQ<7>")
	)
	(segment
		(start 413.275526 -308.24678)
		(end 413.275018 -308.247288)
		(width 0.20066)
		(layer "F.Cu")
		(net "M_E_CPU0_SA_DQ<7>")
	)
	(segment
		(start 386.474716 -273.730974)
		(end 386.974334 -273.730974)
		(width 0.088646)
		(layer "F.Cu")
		(net "M_E_CPU0_SA_DQ<7>")
	)
	(segment
		(start 405.46782 -308.248304)
		(end 405.731726 -308.248304)
		(width 0.20066)
		(layer "F.Cu")
		(net "M_E_CPU0_SA_DQ<7>")
	)
	(segment
		(start 412.548578 -307.816758)
		(end 410.853382 -307.816758)
		(width 0.20066)
		(layer "F.Cu")
		(net "M_E_CPU0_SA_DQ<7>")
	)
	(segment
		(start 413.298132 -308.2417)
		(end 413.293052 -308.24678)
		(width 0.1016)
		(layer "F.Cu")
		(net "M_E_CPU0_SA_DQ<7>")
	)
	(segment
		(start 390.93521 -292.9001)
		(end 391.15111 -293.30396)
		(width 0.1016)
		(layer "F.Cu")
		(net "M_E_CPU0_SA_DQ<7>")
	)
	(segment
		(start 388.273036 -274.950428)
		(end 389.592566 -276.269958)
		(width 0.1016)
		(layer "F.Cu")
		(net "M_E_CPU0_SA_DQ<7>")
	)
	(segment
		(start 404.238714 -302.22571)
		(end 404.721568 -302.22571)
		(width 0.20066)
		(layer "F.Cu")
		(net "M_E_CPU0_SA_DQ<7>")
	)
	(segment
		(start 408.311096 -308.248304)
		(end 408.742642 -307.816758)
		(width 0.20066)
		(layer "F.Cu")
		(net "M_E_CPU0_SA_DQ<7>")
	)
	(segment
		(start 399.941034 -302.093884)
		(end 403.119336 -302.093884)
		(width 0.20066)
		(layer "F.Cu")
		(net "M_E_CPU0_SA_DQ<7>")
	)
	(segment
		(start 405.283162 -308.063646)
		(end 405.46782 -308.248304)
		(width 0.20066)
		(layer "F.Cu")
		(net "M_E_CPU0_SA_DQ<7>")
	)
	(segment
		(start 416.439604 -307.56479)
		(end 416.205416 -307.798978)
		(width 0.20066)
		(layer "F.Cu")
		(net "M_E_CPU0_SA_DQ<7>")
	)
	(segment
		(start 412.979108 -308.247288)
		(end 412.548578 -307.816758)
		(width 0.20066)
		(layer "F.Cu")
		(net "M_E_CPU0_SA_DQ<7>")
	)
	(segment
		(start 403.119336 -302.093884)
		(end 403.577298 -302.551846)
		(width 0.20066)
		(layer "F.Cu")
		(net "M_E_CPU0_SA_DQ<7>")
	)
	(segment
		(start 403.912578 -302.551846)
		(end 404.238714 -302.22571)
		(width 0.20066)
		(layer "F.Cu")
		(net "M_E_CPU0_SA_DQ<7>")
	)
	(segment
		(start 418.397182 -307.816758)
		(end 417.07562 -307.816758)
		(width 0.20066)
		(layer "F.Cu")
		(net "M_E_CPU0_SA_DQ<7>")
	)
	(segment
		(start 413.293052 -308.24678)
		(end 413.275526 -308.24678)
		(width 0.101854)
		(layer "F.Cu")
		(net "M_E_CPU0_SA_DQ<7>")
	)
	(segment
		(start 408.742642 -307.816758)
		(end 410.853382 -307.816758)
		(width 0.20066)
		(layer "F.Cu")
		(net "M_E_CPU0_SA_DQ<7>")
	)
	(segment
		(start 417.07562 -307.816758)
		(end 416.823652 -307.56479)
		(width 0.20066)
		(layer "F.Cu")
		(net "M_E_CPU0_SA_DQ<7>")
	)
	(segment
		(start 416.823652 -307.56479)
		(end 416.439604 -307.56479)
		(width 0.20066)
		(layer "F.Cu")
		(net "M_E_CPU0_SA_DQ<7>")
	)
	(segment
		(start 391.15111 -293.30396)
		(end 391.368534 -293.521384)
		(width 0.1016)
		(layer "F.Cu")
		(net "M_E_CPU0_SA_DQ<7>")
	)
	(segment
		(start 386.974334 -273.730974)
		(end 387.109716 -273.787108)
		(width 0.088646)
		(layer "F.Cu")
		(net "M_E_CPU0_SA_DQ<7>")
	)
	(segment
		(start 407.757122 -308.2417)
		(end 407.763726 -308.248304)
		(width 0.1016)
		(layer "F.Cu")
		(net "M_E_CPU0_SA_DQ<7>")
	)
	(segment
		(start 390.424924 -280.428446)
		(end 390.424924 -290.336986)
		(width 0.1016)
		(layer "F.Cu")
		(net "M_E_CPU0_SA_DQ<7>")
	)
	(segment
		(start 415.307526 -308.247034)
		(end 415.302192 -308.2417)
		(width 0.101854)
		(layer "F.Cu")
		(net "M_E_CPU0_SA_DQ<7>")
	)
	(segment
		(start 404.954232 -307.544216)
		(end 405.148542 -307.738526)
		(width 0.20066)
		(layer "F.Cu")
		(net "M_E_CPU0_SA_DQ<7>")
	)
	(segment
		(start 408.525218 -309.51678)
		(end 410.853382 -309.51678)
		(width 0.20066)
		(layer "F.Cu")
		(net "M_E_CPU0_SA_DQ<6>")
	)
	(segment
		(start 405.128476 -309.275988)
		(end 405.249634 -309.26405)
		(width 0.20066)
		(layer "F.Cu")
		(net "M_E_CPU0_SA_DQ<6>")
	)
	(segment
		(start 403.367748 -306.190396)
		(end 403.367748 -306.54117)
		(width 0.20066)
		(layer "F.Cu")
		(net "M_E_CPU0_SA_DQ<6>")
	)
	(segment
		(start 390.668002 -294.630602)
		(end 390.822688 -294.785288)
		(width 0.1016)
		(layer "F.Cu")
		(net "M_E_CPU0_SA_DQ<6>")
	)
	(segment
		(start 402.238464 -304.349912)
		(end 402.238464 -305.831748)
		(width 0.20066)
		(layer "F.Cu")
		(net "M_E_CPU0_SA_DQ<6>")
	)
	(segment
		(start 403.20976 -306.032408)
		(end 403.367748 -306.190396)
		(width 0.20066)
		(layer "F.Cu")
		(net "M_E_CPU0_SA_DQ<6>")
	)
	(segment
		(start 413.340296 -309.941722)
		(end 413.317182 -309.948326)
		(width 0.1016)
		(layer "F.Cu")
		(net "M_E_CPU0_SA_DQ<6>")
	)
	(segment
		(start 403.141942 -306.766976)
		(end 403.141942 -307.55971)
		(width 0.20066)
		(layer "F.Cu")
		(net "M_E_CPU0_SA_DQ<6>")
	)
	(segment
		(start 404.966932 -309.291736)
		(end 405.128476 -309.275988)
		(width 0.20066)
		(layer "F.Cu")
		(net "M_E_CPU0_SA_DQ<6>")
	)
	(segment
		(start 415.307526 -309.953406)
		(end 415.295842 -309.941722)
		(width 0.101854)
		(layer "F.Cu")
		(net "M_E_CPU0_SA_DQ<6>")
	)
	(segment
		(start 417.07562 -309.51678)
		(end 416.788092 -309.229252)
		(width 0.20066)
		(layer "F.Cu")
		(net "M_E_CPU0_SA_DQ<6>")
	)
	(segment
		(start 390.553194 -294.415972)
		(end 390.668002 -294.630602)
		(width 0.1016)
		(layer "F.Cu")
		(net "M_E_CPU0_SA_DQ<6>")
	)
	(segment
		(start 416.788092 -309.229252)
		(end 416.360356 -309.229252)
		(width 0.20066)
		(layer "F.Cu")
		(net "M_E_CPU0_SA_DQ<6>")
	)
	(segment
		(start 387.651244 -275.195284)
		(end 388.081266 -275.625306)
		(width 0.088646)
		(layer "F.Cu")
		(net "M_E_CPU0_SA_DQ<6>")
	)
	(segment
		(start 414.583626 -309.941722)
		(end 413.340296 -309.941722)
		(width 0.1016)
		(layer "F.Cu")
		(net "M_E_CPU0_SA_DQ<6>")
	)
	(segment
		(start 403.367748 -306.54117)
		(end 403.141942 -306.766976)
		(width 0.20066)
		(layer "F.Cu")
		(net "M_E_CPU0_SA_DQ<6>")
	)
	(segment
		(start 402.439124 -306.032408)
		(end 403.20976 -306.032408)
		(width 0.20066)
		(layer "F.Cu")
		(net "M_E_CPU0_SA_DQ<6>")
	)
	(segment
		(start 416.005772 -309.953406)
		(end 415.307526 -309.953406)
		(width 0.20066)
		(layer "F.Cu")
		(net "M_E_CPU0_SA_DQ<6>")
	)
	(segment
		(start 401.26158 -303.373028)
		(end 402.238464 -304.349912)
		(width 0.20066)
		(layer "F.Cu")
		(net "M_E_CPU0_SA_DQ<6>")
	)
	(segment
		(start 389.815324 -290.703)
		(end 390.553194 -294.415972)
		(width 0.1016)
		(layer "F.Cu")
		(net "M_E_CPU0_SA_DQ<6>")
	)
	(segment
		(start 389.815324 -280.494232)
		(end 389.815324 -290.703)
		(width 0.1016)
		(layer "F.Cu")
		(net "M_E_CPU0_SA_DQ<6>")
	)
	(segment
		(start 404.686008 -309.103776)
		(end 404.966932 -309.291736)
		(width 0.20066)
		(layer "F.Cu")
		(net "M_E_CPU0_SA_DQ<6>")
	)
	(segment
		(start 402.238464 -305.831748)
		(end 402.439124 -306.032408)
		(width 0.20066)
		(layer "F.Cu")
		(net "M_E_CPU0_SA_DQ<6>")
	)
	(segment
		(start 403.141942 -307.55971)
		(end 404.686008 -309.103776)
		(width 0.20066)
		(layer "F.Cu")
		(net "M_E_CPU0_SA_DQ<6>")
	)
	(segment
		(start 386.321808 -274.413472)
		(end 387.08457 -274.413472)
		(width 0.088646)
		(layer "F.Cu")
		(net "M_E_CPU0_SA_DQ<6>")
	)
	(segment
		(start 416.205416 -309.384192)
		(end 416.205416 -309.753762)
		(width 0.20066)
		(layer "F.Cu")
		(net "M_E_CPU0_SA_DQ<6>")
	)
	(segment
		(start 416.360356 -309.229252)
		(end 416.205416 -309.384192)
		(width 0.20066)
		(layer "F.Cu")
		(net "M_E_CPU0_SA_DQ<6>")
	)
	(segment
		(start 389.030972 -276.575012)
		(end 389.815324 -280.494232)
		(width 0.1016)
		(layer "F.Cu")
		(net "M_E_CPU0_SA_DQ<6>")
	)
	(segment
		(start 415.295842 -309.941722)
		(end 414.583626 -309.941722)
		(width 0.101854)
		(layer "F.Cu")
		(net "M_E_CPU0_SA_DQ<6>")
	)
	(segment
		(start 386.004562 -274.54479)
		(end 386.321808 -274.413472)
		(width 0.088646)
		(layer "F.Cu")
		(net "M_E_CPU0_SA_DQ<6>")
	)
	(segment
		(start 407.713942 -309.091584)
		(end 407.719022 -309.086504)
		(width 0.1016)
		(layer "F.Cu")
		(net "M_E_CPU0_SA_DQ<6>")
	)
	(segment
		(start 405.79929 -309.091584)
		(end 407.713942 -309.091584)
		(width 0.1016)
		(layer "F.Cu")
		(net "M_E_CPU0_SA_DQ<6>")
	)
	(segment
		(start 416.205416 -309.753762)
		(end 416.005772 -309.953406)
		(width 0.20066)
		(layer "F.Cu")
		(net "M_E_CPU0_SA_DQ<6>")
	)
	(segment
		(start 412.57347 -309.51678)
		(end 410.853382 -309.51678)
		(width 0.20066)
		(layer "F.Cu")
		(net "M_E_CPU0_SA_DQ<6>")
	)
	(segment
		(start 413.317182 -309.948326)
		(end 413.301688 -309.948326)
		(width 0.1016)
		(layer "F.Cu")
		(net "M_E_CPU0_SA_DQ<6>")
	)
	(segment
		(start 413.275526 -309.948326)
		(end 413.005016 -309.948326)
		(width 0.20066)
		(layer "F.Cu")
		(net "M_E_CPU0_SA_DQ<6>")
	)
	(segment
		(start 407.719022 -309.086504)
		(end 408.094942 -309.086504)
		(width 0.20066)
		(layer "F.Cu")
		(net "M_E_CPU0_SA_DQ<6>")
	)
	(segment
		(start 418.397182 -309.51678)
		(end 417.07562 -309.51678)
		(width 0.20066)
		(layer "F.Cu")
		(net "M_E_CPU0_SA_DQ<6>")
	)
	(segment
		(start 390.822688 -294.785288)
		(end 399.410428 -303.373028)
		(width 0.20066)
		(layer "F.Cu")
		(net "M_E_CPU0_SA_DQ<6>")
	)
	(segment
		(start 387.08457 -274.413472)
		(end 387.499098 -274.828)
		(width 0.088646)
		(layer "F.Cu")
		(net "M_E_CPU0_SA_DQ<6>")
	)
	(segment
		(start 388.081266 -275.625306)
		(end 389.030972 -276.575012)
		(width 0.1016)
		(layer "F.Cu")
		(net "M_E_CPU0_SA_DQ<6>")
	)
	(segment
		(start 399.410428 -303.373028)
		(end 401.26158 -303.373028)
		(width 0.20066)
		(layer "F.Cu")
		(net "M_E_CPU0_SA_DQ<6>")
	)
	(segment
		(start 405.793448 -309.085742)
		(end 405.79929 -309.091584)
		(width 0.1016)
		(layer "F.Cu")
		(net "M_E_CPU0_SA_DQ<6>")
	)
	(segment
		(start 405.427942 -309.085742)
		(end 405.788622 -309.085742)
		(width 0.20066)
		(layer "F.Cu")
		(net "M_E_CPU0_SA_DQ<6>")
	)
	(segment
		(start 413.005016 -309.948326)
		(end 412.57347 -309.51678)
		(width 0.20066)
		(layer "F.Cu")
		(net "M_E_CPU0_SA_DQ<6>")
	)
	(segment
		(start 387.499098 -274.828)
		(end 387.651244 -275.195284)
		(width 0.088646)
		(layer "F.Cu")
		(net "M_E_CPU0_SA_DQ<6>")
	)
	(segment
		(start 405.788622 -309.085742)
		(end 405.793448 -309.085742)
		(width 0.101854)
		(layer "F.Cu")
		(net "M_E_CPU0_SA_DQ<6>")
	)
	(segment
		(start 405.249634 -309.26405)
		(end 405.427942 -309.085742)
		(width 0.20066)
		(layer "F.Cu")
		(net "M_E_CPU0_SA_DQ<6>")
	)
	(segment
		(start 413.301688 -309.948326)
		(end 413.275526 -309.948326)
		(width 0.101854)
		(layer "F.Cu")
		(net "M_E_CPU0_SA_DQ<6>")
	)
	(segment
		(start 408.094942 -309.086504)
		(end 408.525218 -309.51678)
		(width 0.20066)
		(layer "F.Cu")
		(net "M_E_CPU0_SA_DQ<6>")
	)
	(segment
		(start 387.822186 -274.845018)
		(end 387.822186 -274.931886)
		(width 0.088646)
		(layer "F.Cu")
		(net "M_E_CPU0_SA_DQ<5>")
	)
	(segment
		(start 404.287736 -307.789072)
		(end 405.165306 -308.666642)
		(width 0.20066)
		(layer "F.Cu")
		(net "M_E_CPU0_SA_DQ<5>")
	)
	(segment
		(start 390.120124 -280.460958)
		(end 390.120124 -290.523422)
		(width 0.1016)
		(layer "F.Cu")
		(net "M_E_CPU0_SA_DQ<5>")
	)
	(segment
		(start 404.287736 -304.429414)
		(end 404.0505 -304.66665)
		(width 0.20066)
		(layer "F.Cu")
		(net "M_E_CPU0_SA_DQ<5>")
	)
	(segment
		(start 404.287736 -305.55311)
		(end 404.287736 -307.789072)
		(width 0.20066)
		(layer "F.Cu")
		(net "M_E_CPU0_SA_DQ<5>")
	)
	(segment
		(start 408.390852 -308.666642)
		(end 406.753314 -308.666642)
		(width 0.20066)
		(layer "F.Cu")
		(net "M_E_CPU0_SA_DQ<5>")
	)
	(segment
		(start 412.862522 -308.88305)
		(end 412.215584 -308.236112)
		(width 0.20066)
		(layer "F.Cu")
		(net "M_E_CPU0_SA_DQ<5>")
	)
	(segment
		(start 404.039578 -303.55794)
		(end 404.287736 -303.806098)
		(width 0.20066)
		(layer "F.Cu")
		(net "M_E_CPU0_SA_DQ<5>")
	)
	(segment
		(start 387.822186 -274.931886)
		(end 388.056882 -275.166582)
		(width 0.088646)
		(layer "F.Cu")
		(net "M_E_CPU0_SA_DQ<5>")
	)
	(segment
		(start 402.2344 -302.733456)
		(end 402.43506 -302.934116)
		(width 0.20066)
		(layer "F.Cu")
		(net "M_E_CPU0_SA_DQ<5>")
	)
	(segment
		(start 409.185872 -308.422548)
		(end 409.185872 -308.683152)
		(width 0.20066)
		(layer "F.Cu")
		(net "M_E_CPU0_SA_DQ<5>")
	)
	(segment
		(start 387.141212 -274.164044)
		(end 387.822186 -274.845018)
		(width 0.088646)
		(layer "F.Cu")
		(net "M_E_CPU0_SA_DQ<5>")
	)
	(segment
		(start 409.831794 -308.236112)
		(end 409.372308 -308.236112)
		(width 0.20066)
		(layer "F.Cu")
		(net "M_E_CPU0_SA_DQ<5>")
	)
	(segment
		(start 386.362194 -274.164044)
		(end 387.141212 -274.164044)
		(width 0.088646)
		(layer "F.Cu")
		(net "M_E_CPU0_SA_DQ<5>")
	)
	(segment
		(start 409.185872 -308.683152)
		(end 408.985212 -308.883812)
		(width 0.20066)
		(layer "F.Cu")
		(net "M_E_CPU0_SA_DQ<5>")
	)
	(segment
		(start 405.165306 -308.666642)
		(end 406.753314 -308.666642)
		(width 0.20066)
		(layer "F.Cu")
		(net "M_E_CPU0_SA_DQ<5>")
	)
	(segment
		(start 399.676112 -302.733456)
		(end 402.2344 -302.733456)
		(width 0.20066)
		(layer "F.Cu")
		(net "M_E_CPU0_SA_DQ<5>")
	)
	(segment
		(start 384.14198 -274.540218)
		(end 384.829812 -274.137882)
		(width 0.088646)
		(layer "F.Cu")
		(net "M_E_CPU0_SA_DQ<5>")
	)
	(segment
		(start 389.311388 -276.421088)
		(end 390.120124 -280.460958)
		(width 0.1016)
		(layer "F.Cu")
		(net "M_E_CPU0_SA_DQ<5>")
	)
	(segment
		(start 403.143212 -304.66665)
		(end 402.942552 -304.86731)
		(width 0.20066)
		(layer "F.Cu")
		(net "M_E_CPU0_SA_DQ<5>")
	)
	(segment
		(start 390.882378 -293.939722)
		(end 391.275316 -294.33266)
		(width 0.1016)
		(layer "F.Cu")
		(net "M_E_CPU0_SA_DQ<5>")
	)
	(segment
		(start 386.248656 -274.141438)
		(end 386.362194 -274.164044)
		(width 0.088646)
		(layer "F.Cu")
		(net "M_E_CPU0_SA_DQ<5>")
	)
	(segment
		(start 388.056882 -275.166582)
		(end 389.311388 -276.421088)
		(width 0.1016)
		(layer "F.Cu")
		(net "M_E_CPU0_SA_DQ<5>")
	)
	(segment
		(start 404.287736 -303.806098)
		(end 404.287736 -304.429414)
		(width 0.20066)
		(layer "F.Cu")
		(net "M_E_CPU0_SA_DQ<5>")
	)
	(segment
		(start 411.858206 -308.2417)
		(end 409.842208 -308.2417)
		(width 0.1016)
		(layer "F.Cu")
		(net "M_E_CPU0_SA_DQ<5>")
	)
	(segment
		(start 409.372308 -308.236112)
		(end 409.185872 -308.422548)
		(width 0.20066)
		(layer "F.Cu")
		(net "M_E_CPU0_SA_DQ<5>")
	)
	(segment
		(start 402.942552 -304.86731)
		(end 402.942552 -305.15179)
		(width 0.20066)
		(layer "F.Cu")
		(net "M_E_CPU0_SA_DQ<5>")
	)
	(segment
		(start 404.0505 -304.66665)
		(end 403.143212 -304.66665)
		(width 0.20066)
		(layer "F.Cu")
		(net "M_E_CPU0_SA_DQ<5>")
	)
	(segment
		(start 403.143212 -305.35245)
		(end 404.087076 -305.35245)
		(width 0.20066)
		(layer "F.Cu")
		(net "M_E_CPU0_SA_DQ<5>")
	)
	(segment
		(start 402.63572 -303.55794)
		(end 404.039578 -303.55794)
		(width 0.20066)
		(layer "F.Cu")
		(net "M_E_CPU0_SA_DQ<5>")
	)
	(segment
		(start 408.608022 -308.883812)
		(end 408.390852 -308.666642)
		(width 0.20066)
		(layer "F.Cu")
		(net "M_E_CPU0_SA_DQ<5>")
	)
	(segment
		(start 402.43506 -302.934116)
		(end 402.43506 -303.35728)
		(width 0.20066)
		(layer "F.Cu")
		(net "M_E_CPU0_SA_DQ<5>")
	)
	(segment
		(start 414.297114 -308.666642)
		(end 413.430974 -308.666642)
		(width 0.20066)
		(layer "F.Cu")
		(net "M_E_CPU0_SA_DQ<5>")
	)
	(segment
		(start 409.83662 -308.236112)
		(end 409.831794 -308.236112)
		(width 0.101854)
		(layer "F.Cu")
		(net "M_E_CPU0_SA_DQ<5>")
	)
	(segment
		(start 404.087076 -305.35245)
		(end 404.287736 -305.55311)
		(width 0.20066)
		(layer "F.Cu")
		(net "M_E_CPU0_SA_DQ<5>")
	)
	(segment
		(start 402.43506 -303.35728)
		(end 402.63572 -303.55794)
		(width 0.20066)
		(layer "F.Cu")
		(net "M_E_CPU0_SA_DQ<5>")
	)
	(segment
		(start 412.215584 -308.236112)
		(end 411.863794 -308.236112)
		(width 0.20066)
		(layer "F.Cu")
		(net "M_E_CPU0_SA_DQ<5>")
	)
	(segment
		(start 390.120124 -290.523422)
		(end 390.722866 -293.554658)
		(width 0.1016)
		(layer "F.Cu")
		(net "M_E_CPU0_SA_DQ<5>")
	)
	(segment
		(start 391.275316 -294.33266)
		(end 399.676112 -302.733456)
		(width 0.20066)
		(layer "F.Cu")
		(net "M_E_CPU0_SA_DQ<5>")
	)
	(segment
		(start 390.722866 -293.554658)
		(end 390.882378 -293.939722)
		(width 0.101854)
		(layer "F.Cu")
		(net "M_E_CPU0_SA_DQ<5>")
	)
	(segment
		(start 413.214566 -308.88305)
		(end 412.862522 -308.88305)
		(width 0.20066)
		(layer "F.Cu")
		(net "M_E_CPU0_SA_DQ<5>")
	)
	(segment
		(start 413.430974 -308.666642)
		(end 413.214566 -308.88305)
		(width 0.20066)
		(layer "F.Cu")
		(net "M_E_CPU0_SA_DQ<5>")
	)
	(segment
		(start 402.942552 -305.15179)
		(end 403.143212 -305.35245)
		(width 0.20066)
		(layer "F.Cu")
		(net "M_E_CPU0_SA_DQ<5>")
	)
	(segment
		(start 409.842208 -308.2417)
		(end 409.83662 -308.236112)
		(width 0.1016)
		(layer "F.Cu")
		(net "M_E_CPU0_SA_DQ<5>")
	)
	(segment
		(start 411.863794 -308.236112)
		(end 411.858206 -308.2417)
		(width 0.1016)
		(layer "F.Cu")
		(net "M_E_CPU0_SA_DQ<5>")
	)
	(segment
		(start 408.985212 -308.883812)
		(end 408.608022 -308.883812)
		(width 0.20066)
		(layer "F.Cu")
		(net "M_E_CPU0_SA_DQ<5>")
	)
	(arc
		(start 385.299712 -274.137882)
		(mid 385.534662 -274.200842)
		(end 385.769612 -274.137882)
		(width 0.088646)
		(layer "F.Cu")
		(net "M_E_CPU0_SA_DQ<5>")
	)
	(arc
		(start 385.769612 -274.137882)
		(mid 386.004562 -274.074922)
		(end 386.239512 -274.137882)
		(width 0.088646)
		(layer "F.Cu")
		(net "M_E_CPU0_SA_DQ<5>")
	)
	(arc
		(start 384.829812 -274.137882)
		(mid 385.064762 -274.074922)
		(end 385.299712 -274.137882)
		(width 0.088646)
		(layer "F.Cu")
		(net "M_E_CPU0_SA_DQ<5>")
	)
	(arc
		(start 386.239512 -274.137882)
		(mid 386.243942 -274.140021)
		(end 386.248656 -274.141438)
		(width 0.088646)
		(layer "F.Cu")
		(net "M_E_CPU0_SA_DQ<5>")
	)
	(arc
		(start 384.124962 -274.54479)
		(mid 384.13377 -274.543622)
		(end 384.14198 -274.540218)
		(width 0.088646)
		(layer "F.Cu")
		(net "M_E_CPU0_SA_DQ<5>")
	)
	(segment
		(start 400.133566 -304.0126)
		(end 400.810984 -304.0126)
		(width 0.20066)
		(layer "F.Cu")
		(net "M_E_CPU0_SA_DQ<4>")
	)
	(segment
		(start 399.247106 -304.129948)
		(end 399.247106 -304.616612)
		(width 0.20066)
		(layer "F.Cu")
		(net "M_E_CPU0_SA_DQ<4>")
	)
	(segment
		(start 400.332448 -305.392836)
		(end 400.332448 -305.676808)
		(width 0.20066)
		(layer "F.Cu")
		(net "M_E_CPU0_SA_DQ<4>")
	)
	(segment
		(start 407.5684 -310.366664)
		(end 406.753314 -310.366664)
		(width 0.20066)
		(layer "F.Cu")
		(net "M_E_CPU0_SA_DQ<4>")
	)
	(segment
		(start 399.932906 -304.21326)
		(end 400.133566 -304.0126)
		(width 0.20066)
		(layer "F.Cu")
		(net "M_E_CPU0_SA_DQ<4>")
	)
	(segment
		(start 401.592796 -306.08778)
		(end 401.310094 -306.370482)
		(width 0.20066)
		(layer "F.Cu")
		(net "M_E_CPU0_SA_DQ<4>")
	)
	(segment
		(start 389.510524 -291.019738)
		(end 389.533384 -291.284406)
		(width 0.1016)
		(layer "F.Cu")
		(net "M_E_CPU0_SA_DQ<4>")
	)
	(segment
		(start 401.310094 -306.370482)
		(end 401.310094 -306.654454)
		(width 0.20066)
		(layer "F.Cu")
		(net "M_E_CPU0_SA_DQ<4>")
	)
	(segment
		(start 386.114798 -275.00199)
		(end 386.8166 -274.705572)
		(width 0.088646)
		(layer "F.Cu")
		(net "M_E_CPU0_SA_DQ<4>")
	)
	(segment
		(start 400.810984 -304.0126)
		(end 401.080732 -304.282348)
		(width 0.20066)
		(layer "F.Cu")
		(net "M_E_CPU0_SA_DQ<4>")
	)
	(segment
		(start 401.092924 -305.60264)
		(end 401.391628 -305.60264)
		(width 0.20066)
		(layer "F.Cu")
		(net "M_E_CPU0_SA_DQ<4>")
	)
	(segment
		(start 411.854142 -309.941722)
		(end 409.847542 -309.941722)
		(width 0.1016)
		(layer "F.Cu")
		(net "M_E_CPU0_SA_DQ<4>")
	)
	(segment
		(start 407.683208 -310.251856)
		(end 407.5684 -310.366664)
		(width 0.20066)
		(layer "F.Cu")
		(net "M_E_CPU0_SA_DQ<4>")
	)
	(segment
		(start 401.592796 -305.803808)
		(end 401.592796 -306.08778)
		(width 0.20066)
		(layer "F.Cu")
		(net "M_E_CPU0_SA_DQ<4>")
	)
	(segment
		(start 387.263894 -274.865084)
		(end 387.495542 -275.423884)
		(width 0.088646)
		(layer "F.Cu")
		(net "M_E_CPU0_SA_DQ<4>")
	)
	(segment
		(start 401.080732 -304.282348)
		(end 401.080732 -304.644552)
		(width 0.20066)
		(layer "F.Cu")
		(net "M_E_CPU0_SA_DQ<4>")
	)
	(segment
		(start 400.332448 -305.676808)
		(end 400.533616 -305.877976)
		(width 0.20066)
		(layer "F.Cu")
		(net "M_E_CPU0_SA_DQ<4>")
	)
	(segment
		(start 408.2796 -310.251856)
		(end 407.683208 -310.251856)
		(width 0.20066)
		(layer "F.Cu")
		(net "M_E_CPU0_SA_DQ<4>")
	)
	(segment
		(start 399.732246 -304.817272)
		(end 399.932906 -304.616612)
		(width 0.20066)
		(layer "F.Cu")
		(net "M_E_CPU0_SA_DQ<4>")
	)
	(segment
		(start 408.992578 -310.073294)
		(end 408.992578 -310.418988)
		(width 0.20066)
		(layer "F.Cu")
		(net "M_E_CPU0_SA_DQ<4>")
	)
	(segment
		(start 409.831794 -309.9308)
		(end 409.135072 -309.9308)
		(width 0.20066)
		(layer "F.Cu")
		(net "M_E_CPU0_SA_DQ<4>")
	)
	(segment
		(start 387.495542 -275.423884)
		(end 387.59384 -275.571204)
		(width 0.088646)
		(layer "F.Cu")
		(net "M_E_CPU0_SA_DQ<4>")
	)
	(segment
		(start 390.677654 -295.560496)
		(end 399.247106 -304.129948)
		(width 0.20066)
		(layer "F.Cu")
		(net "M_E_CPU0_SA_DQ<4>")
	)
	(segment
		(start 387.104382 -274.705572)
		(end 387.263894 -274.865084)
		(width 0.088646)
		(layer "F.Cu")
		(net "M_E_CPU0_SA_DQ<4>")
	)
	(segment
		(start 405.592788 -310.366664)
		(end 406.753314 -310.366664)
		(width 0.20066)
		(layer "F.Cu")
		(net "M_E_CPU0_SA_DQ<4>")
	)
	(segment
		(start 408.992578 -310.418988)
		(end 408.829002 -310.582564)
		(width 0.20066)
		(layer "F.Cu")
		(net "M_E_CPU0_SA_DQ<4>")
	)
	(segment
		(start 386.8166 -274.705572)
		(end 387.104382 -274.705572)
		(width 0.088646)
		(layer "F.Cu")
		(net "M_E_CPU0_SA_DQ<4>")
	)
	(segment
		(start 404.140416 -309.484776)
		(end 404.335996 -309.645304)
		(width 0.20066)
		(layer "F.Cu")
		(net "M_E_CPU0_SA_DQ<4>")
	)
	(segment
		(start 414.297114 -310.366664)
		(end 412.806134 -310.366664)
		(width 0.20066)
		(layer "F.Cu")
		(net "M_E_CPU0_SA_DQ<4>")
	)
	(segment
		(start 400.533616 -305.877976)
		(end 400.817588 -305.877976)
		(width 0.20066)
		(layer "F.Cu")
		(net "M_E_CPU0_SA_DQ<4>")
	)
	(segment
		(start 389.533384 -291.284406)
		(end 390.019794 -294.072056)
		(width 0.1016)
		(layer "F.Cu")
		(net "M_E_CPU0_SA_DQ<4>")
	)
	(segment
		(start 405.128476 -310.17464)
		(end 405.592788 -310.366664)
		(width 0.20066)
		(layer "F.Cu")
		(net "M_E_CPU0_SA_DQ<4>")
	)
	(segment
		(start 390.514586 -295.397428)
		(end 390.677654 -295.560496)
		(width 0.1016)
		(layer "F.Cu")
		(net "M_E_CPU0_SA_DQ<4>")
	)
	(segment
		(start 411.863794 -309.93207)
		(end 411.854142 -309.941722)
		(width 0.1016)
		(layer "F.Cu")
		(net "M_E_CPU0_SA_DQ<4>")
	)
	(segment
		(start 399.247106 -304.616612)
		(end 399.447766 -304.817272)
		(width 0.20066)
		(layer "F.Cu")
		(net "M_E_CPU0_SA_DQ<4>")
	)
	(segment
		(start 400.817588 -305.877976)
		(end 401.092924 -305.60264)
		(width 0.20066)
		(layer "F.Cu")
		(net "M_E_CPU0_SA_DQ<4>")
	)
	(segment
		(start 401.310094 -306.654454)
		(end 404.140416 -309.484776)
		(width 0.20066)
		(layer "F.Cu")
		(net "M_E_CPU0_SA_DQ<4>")
	)
	(segment
		(start 409.847542 -309.941722)
		(end 409.83662 -309.9308)
		(width 0.1016)
		(layer "F.Cu")
		(net "M_E_CPU0_SA_DQ<4>")
	)
	(segment
		(start 388.750048 -276.727412)
		(end 389.510524 -280.526744)
		(width 0.1016)
		(layer "F.Cu")
		(net "M_E_CPU0_SA_DQ<4>")
	)
	(segment
		(start 408.610308 -310.582564)
		(end 408.2796 -310.251856)
		(width 0.20066)
		(layer "F.Cu")
		(net "M_E_CPU0_SA_DQ<4>")
	)
	(segment
		(start 390.019794 -294.072056)
		(end 390.379458 -295.137078)
		(width 0.1016)
		(layer "F.Cu")
		(net "M_E_CPU0_SA_DQ<4>")
	)
	(segment
		(start 387.59384 -275.571204)
		(end 387.864604 -275.841968)
		(width 0.088646)
		(layer "F.Cu")
		(net "M_E_CPU0_SA_DQ<4>")
	)
	(segment
		(start 390.379458 -295.137078)
		(end 390.514586 -295.397428)
		(width 0.1016)
		(layer "F.Cu")
		(net "M_E_CPU0_SA_DQ<4>")
	)
	(segment
		(start 409.83662 -309.9308)
		(end 409.831794 -309.9308)
		(width 0.101854)
		(layer "F.Cu")
		(net "M_E_CPU0_SA_DQ<4>")
	)
	(segment
		(start 412.806134 -310.366664)
		(end 412.37154 -309.93207)
		(width 0.20066)
		(layer "F.Cu")
		(net "M_E_CPU0_SA_DQ<4>")
	)
	(segment
		(start 399.447766 -304.817272)
		(end 399.732246 -304.817272)
		(width 0.20066)
		(layer "F.Cu")
		(net "M_E_CPU0_SA_DQ<4>")
	)
	(segment
		(start 385.137152 -275.007832)
		(end 385.36753 -274.919948)
		(width 0.088646)
		(layer "F.Cu")
		(net "M_E_CPU0_SA_DQ<4>")
	)
	(segment
		(start 401.391628 -305.60264)
		(end 401.592796 -305.803808)
		(width 0.20066)
		(layer "F.Cu")
		(net "M_E_CPU0_SA_DQ<4>")
	)
	(segment
		(start 389.510524 -280.526744)
		(end 389.510524 -291.019738)
		(width 0.1016)
		(layer "F.Cu")
		(net "M_E_CPU0_SA_DQ<4>")
	)
	(segment
		(start 408.829002 -310.582564)
		(end 408.610308 -310.582564)
		(width 0.20066)
		(layer "F.Cu")
		(net "M_E_CPU0_SA_DQ<4>")
	)
	(segment
		(start 387.864604 -275.841968)
		(end 388.750048 -276.727412)
		(width 0.1016)
		(layer "F.Cu")
		(net "M_E_CPU0_SA_DQ<4>")
	)
	(segment
		(start 412.37154 -309.93207)
		(end 411.863794 -309.93207)
		(width 0.20066)
		(layer "F.Cu")
		(net "M_E_CPU0_SA_DQ<4>")
	)
	(segment
		(start 404.335996 -309.645304)
		(end 405.128476 -310.17464)
		(width 0.20066)
		(layer "F.Cu")
		(net "M_E_CPU0_SA_DQ<4>")
	)
	(segment
		(start 401.080732 -304.644552)
		(end 400.332448 -305.392836)
		(width 0.20066)
		(layer "F.Cu")
		(net "M_E_CPU0_SA_DQ<4>")
	)
	(segment
		(start 409.135072 -309.9308)
		(end 408.992578 -310.073294)
		(width 0.20066)
		(layer "F.Cu")
		(net "M_E_CPU0_SA_DQ<4>")
	)
	(segment
		(start 399.932906 -304.616612)
		(end 399.932906 -304.21326)
		(width 0.20066)
		(layer "F.Cu")
		(net "M_E_CPU0_SA_DQ<4>")
	)
	(arc
		(start 385.36753 -274.919948)
		(mid 385.572182 -274.89061)
		(end 385.769612 -274.951952)
		(width 0.088646)
		(layer "F.Cu")
		(net "M_E_CPU0_SA_DQ<4>")
	)
	(arc
		(start 385.769612 -274.951952)
		(mid 385.937391 -275.010177)
		(end 386.114798 -275.00199)
		(width 0.088646)
		(layer "F.Cu")
		(net "M_E_CPU0_SA_DQ<4>")
	)
	(arc
		(start 384.595116 -275.35886)
		(mid 384.847587 -275.154708)
		(end 385.137152 -275.007832)
		(width 0.088646)
		(layer "F.Cu")
		(net "M_E_CPU0_SA_DQ<4>")
	)
	(segment
		(start 413.302958 -314.19165)
		(end 413.293052 -314.201556)
		(width 0.1016)
		(layer "F.Cu")
		(net "M_E_CPU0_SA_DQ<3>")
	)
	(segment
		(start 405.736552 -314.20816)
		(end 405.753062 -314.19165)
		(width 0.1016)
		(layer "F.Cu")
		(net "M_E_CPU0_SA_DQ<3>")
	)
	(segment
		(start 408.696414 -314.200794)
		(end 409.1305 -313.766708)
		(width 0.20066)
		(layer "F.Cu")
		(net "M_E_CPU0_SA_DQ<3>")
	)
	(segment
		(start 405.731726 -314.20816)
		(end 405.736552 -314.20816)
		(width 0.101854)
		(layer "F.Cu")
		(net "M_E_CPU0_SA_DQ<3>")
	)
	(segment
		(start 413.293052 -314.201556)
		(end 413.275526 -314.201556)
		(width 0.101854)
		(layer "F.Cu")
		(net "M_E_CPU0_SA_DQ<3>")
	)
	(segment
		(start 386.565394 -277.001986)
		(end 387.28904 -278.023828)
		(width 0.088646)
		(layer "F.Cu")
		(net "M_E_CPU0_SA_DQ<3>")
	)
	(segment
		(start 387.28904 -278.023828)
		(end 387.476238 -278.473408)
		(width 0.088646)
		(layer "F.Cu")
		(net "M_E_CPU0_SA_DQ<3>")
	)
	(segment
		(start 412.320486 -313.766708)
		(end 410.853382 -313.766708)
		(width 0.20066)
		(layer "F.Cu")
		(net "M_E_CPU0_SA_DQ<3>")
	)
	(segment
		(start 409.1305 -313.766708)
		(end 410.853382 -313.766708)
		(width 0.20066)
		(layer "F.Cu")
		(net "M_E_CPU0_SA_DQ<3>")
	)
	(segment
		(start 405.753062 -314.19165)
		(end 407.563574 -314.19165)
		(width 0.1016)
		(layer "F.Cu")
		(net "M_E_CPU0_SA_DQ<3>")
	)
	(segment
		(start 387.547104 -278.874982)
		(end 387.547104 -279.080468)
		(width 0.088646)
		(layer "F.Cu")
		(net "M_E_CPU0_SA_DQ<3>")
	)
	(segment
		(start 416.332416 -313.442096)
		(end 416.205416 -313.569096)
		(width 0.20066)
		(layer "F.Cu")
		(net "M_E_CPU0_SA_DQ<3>")
	)
	(segment
		(start 388.70509 -297.327828)
		(end 388.70509 -298.18711)
		(width 0.20066)
		(layer "F.Cu")
		(net "M_E_CPU0_SA_DQ<3>")
	)
	(segment
		(start 417.07562 -313.766708)
		(end 416.751008 -313.442096)
		(width 0.20066)
		(layer "F.Cu")
		(net "M_E_CPU0_SA_DQ<3>")
	)
	(segment
		(start 416.205416 -313.569096)
		(end 416.205416 -314.009024)
		(width 0.20066)
		(layer "F.Cu")
		(net "M_E_CPU0_SA_DQ<3>")
	)
	(segment
		(start 407.75382 -314.200794)
		(end 407.763726 -314.200794)
		(width 0.101854)
		(layer "F.Cu")
		(net "M_E_CPU0_SA_DQ<3>")
	)
	(segment
		(start 407.744676 -314.19165)
		(end 407.75382 -314.200794)
		(width 0.101854)
		(layer "F.Cu")
		(net "M_E_CPU0_SA_DQ<3>")
	)
	(segment
		(start 404.261828 -313.569096)
		(end 405.128476 -314.14847)
		(width 0.20066)
		(layer "F.Cu")
		(net "M_E_CPU0_SA_DQ<3>")
	)
	(segment
		(start 387.981444 -296.222928)
		(end 388.70509 -296.946574)
		(width 0.1016)
		(layer "F.Cu")
		(net "M_E_CPU0_SA_DQ<3>")
	)
	(segment
		(start 416.205416 -314.009024)
		(end 416.013138 -314.201302)
		(width 0.20066)
		(layer "F.Cu")
		(net "M_E_CPU0_SA_DQ<3>")
	)
	(segment
		(start 387.981444 -281.063446)
		(end 387.981444 -296.222928)
		(width 0.1016)
		(layer "F.Cu")
		(net "M_E_CPU0_SA_DQ<3>")
	)
	(segment
		(start 388.70509 -296.946574)
		(end 388.70509 -297.327828)
		(width 0.1016)
		(layer "F.Cu")
		(net "M_E_CPU0_SA_DQ<3>")
	)
	(segment
		(start 387.476238 -278.473408)
		(end 387.547104 -278.874982)
		(width 0.088646)
		(layer "F.Cu")
		(net "M_E_CPU0_SA_DQ<3>")
	)
	(segment
		(start 416.013138 -314.201302)
		(end 415.307526 -314.201302)
		(width 0.20066)
		(layer "F.Cu")
		(net "M_E_CPU0_SA_DQ<3>")
	)
	(segment
		(start 407.763726 -314.200794)
		(end 408.696414 -314.200794)
		(width 0.20066)
		(layer "F.Cu")
		(net "M_E_CPU0_SA_DQ<3>")
	)
	(segment
		(start 418.397182 -313.766708)
		(end 417.07562 -313.766708)
		(width 0.20066)
		(layer "F.Cu")
		(net "M_E_CPU0_SA_DQ<3>")
	)
	(segment
		(start 415.288222 -314.201302)
		(end 415.27857 -314.19165)
		(width 0.101854)
		(layer "F.Cu")
		(net "M_E_CPU0_SA_DQ<3>")
	)
	(segment
		(start 405.272494 -314.20816)
		(end 405.731726 -314.20816)
		(width 0.20066)
		(layer "F.Cu")
		(net "M_E_CPU0_SA_DQ<3>")
	)
	(segment
		(start 412.755334 -314.201556)
		(end 412.320486 -313.766708)
		(width 0.20066)
		(layer "F.Cu")
		(net "M_E_CPU0_SA_DQ<3>")
	)
	(segment
		(start 387.547104 -279.080468)
		(end 387.836664 -280.034746)
		(width 0.088646)
		(layer "F.Cu")
		(net "M_E_CPU0_SA_DQ<3>")
	)
	(segment
		(start 405.128476 -314.14847)
		(end 405.272494 -314.20816)
		(width 0.20066)
		(layer "F.Cu")
		(net "M_E_CPU0_SA_DQ<3>")
	)
	(segment
		(start 415.27857 -314.19165)
		(end 413.302958 -314.19165)
		(width 0.1016)
		(layer "F.Cu")
		(net "M_E_CPU0_SA_DQ<3>")
	)
	(segment
		(start 387.836664 -280.034746)
		(end 387.981444 -280.759154)
		(width 0.088646)
		(layer "F.Cu")
		(net "M_E_CPU0_SA_DQ<3>")
	)
	(segment
		(start 388.70509 -298.18711)
		(end 403.28723 -312.76925)
		(width 0.20066)
		(layer "F.Cu")
		(net "M_E_CPU0_SA_DQ<3>")
	)
	(segment
		(start 415.307526 -314.201302)
		(end 415.288222 -314.201302)
		(width 0.101854)
		(layer "F.Cu")
		(net "M_E_CPU0_SA_DQ<3>")
	)
	(segment
		(start 386.474716 -276.986492)
		(end 386.565394 -277.001986)
		(width 0.088646)
		(layer "F.Cu")
		(net "M_E_CPU0_SA_DQ<3>")
	)
	(segment
		(start 407.563574 -314.19165)
		(end 407.744676 -314.19165)
		(width 0.101854)
		(layer "F.Cu")
		(net "M_E_CPU0_SA_DQ<3>")
	)
	(segment
		(start 416.751008 -313.442096)
		(end 416.332416 -313.442096)
		(width 0.20066)
		(layer "F.Cu")
		(net "M_E_CPU0_SA_DQ<3>")
	)
	(segment
		(start 403.28723 -312.76925)
		(end 404.261828 -313.569096)
		(width 0.20066)
		(layer "F.Cu")
		(net "M_E_CPU0_SA_DQ<3>")
	)
	(segment
		(start 413.275526 -314.201556)
		(end 412.755334 -314.201556)
		(width 0.20066)
		(layer "F.Cu")
		(net "M_E_CPU0_SA_DQ<3>")
	)
	(segment
		(start 387.981444 -280.759154)
		(end 387.981444 -281.063446)
		(width 0.088646)
		(layer "F.Cu")
		(net "M_E_CPU0_SA_DQ<3>")
	)
	(segment
		(start 407.763726 -280.223976)
		(end 408.055572 -280.223976)
		(width 0.101854)
		(layer "F.Cu")
		(net "M_E_CPU0_SA_DQ<31>")
	)
	(segment
		(start 416.599878 -279.51049)
		(end 416.163252 -279.51049)
		(width 0.20066)
		(layer "F.Cu")
		(net "M_E_CPU0_SA_DQ<31>")
	)
	(segment
		(start 386.455666 -263.282684)
		(end 386.742432 -263.466326)
		(width 0.088646)
		(layer "F.Cu")
		(net "M_E_CPU0_SA_DQ<31>")
	)
	(segment
		(start 415.307526 -280.199846)
		(end 415.299398 -280.191718)
		(width 0.1016)
		(layer "F.Cu")
		(net "M_E_CPU0_SA_DQ<31>")
	)
	(segment
		(start 408.055572 -280.223976)
		(end 408.243278 -280.223976)
		(width 0.20066)
		(layer "F.Cu")
		(net "M_E_CPU0_SA_DQ<31>")
	)
	(segment
		(start 418.397182 -279.766776)
		(end 417.80206 -279.766776)
		(width 0.20066)
		(layer "F.Cu")
		(net "M_E_CPU0_SA_DQ<31>")
	)
	(segment
		(start 412.161228 -279.766776)
		(end 410.853382 -279.766776)
		(width 0.20066)
		(layer "F.Cu")
		(net "M_E_CPU0_SA_DQ<31>")
	)
	(segment
		(start 398.858994 -278.35606)
		(end 399.242026 -278.739092)
		(width 0.1016)
		(layer "F.Cu")
		(net "M_E_CPU0_SA_DQ<31>")
	)
	(segment
		(start 409.319222 -279.976834)
		(end 409.499562 -280.157174)
		(width 0.20066)
		(layer "F.Cu")
		(net "M_E_CPU0_SA_DQ<31>")
	)
	(segment
		(start 387.378448 -263.42848)
		(end 387.989064 -263.42848)
		(width 0.088646)
		(layer "F.Cu")
		(net "M_E_CPU0_SA_DQ<31>")
	)
	(segment
		(start 404.965916 -279.419304)
		(end 405.133302 -279.58669)
		(width 0.20066)
		(layer "F.Cu")
		(net "M_E_CPU0_SA_DQ<31>")
	)
	(segment
		(start 415.962592 -279.999186)
		(end 415.761932 -280.199846)
		(width 0.20066)
		(layer "F.Cu")
		(net "M_E_CPU0_SA_DQ<31>")
	)
	(segment
		(start 409.319222 -279.294082)
		(end 409.319222 -279.976834)
		(width 0.20066)
		(layer "F.Cu")
		(net "M_E_CPU0_SA_DQ<31>")
	)
	(segment
		(start 401.442936 -279.314402)
		(end 402.197316 -279.314402)
		(width 0.20066)
		(layer "F.Cu")
		(net "M_E_CPU0_SA_DQ<31>")
	)
	(segment
		(start 417.40836 -280.160476)
		(end 416.989514 -280.160476)
		(width 0.20066)
		(layer "F.Cu")
		(net "M_E_CPU0_SA_DQ<31>")
	)
	(segment
		(start 417.80206 -279.766776)
		(end 417.40836 -280.160476)
		(width 0.20066)
		(layer "F.Cu")
		(net "M_E_CPU0_SA_DQ<31>")
	)
	(segment
		(start 416.797744 -279.968706)
		(end 416.797744 -279.708356)
		(width 0.20066)
		(layer "F.Cu")
		(net "M_E_CPU0_SA_DQ<31>")
	)
	(segment
		(start 413.293052 -280.199846)
		(end 413.275526 -280.199846)
		(width 0.101854)
		(layer "F.Cu")
		(net "M_E_CPU0_SA_DQ<31>")
	)
	(segment
		(start 408.243278 -280.223976)
		(end 408.442414 -280.02484)
		(width 0.20066)
		(layer "F.Cu")
		(net "M_E_CPU0_SA_DQ<31>")
	)
	(segment
		(start 413.30118 -280.191718)
		(end 413.293052 -280.199846)
		(width 0.1016)
		(layer "F.Cu")
		(net "M_E_CPU0_SA_DQ<31>")
	)
	(segment
		(start 416.797744 -279.708356)
		(end 416.599878 -279.51049)
		(width 0.20066)
		(layer "F.Cu")
		(net "M_E_CPU0_SA_DQ<31>")
	)
	(segment
		(start 405.133302 -279.990804)
		(end 405.334216 -280.191718)
		(width 0.20066)
		(layer "F.Cu")
		(net "M_E_CPU0_SA_DQ<31>")
	)
	(segment
		(start 407.716228 -280.191718)
		(end 407.748486 -280.223976)
		(width 0.1016)
		(layer "F.Cu")
		(net "M_E_CPU0_SA_DQ<31>")
	)
	(segment
		(start 402.197316 -279.314402)
		(end 402.444204 -279.067514)
		(width 0.20066)
		(layer "F.Cu")
		(net "M_E_CPU0_SA_DQ<31>")
	)
	(segment
		(start 400.82978 -279.50414)
		(end 401.040854 -279.293066)
		(width 0.20066)
		(layer "F.Cu")
		(net "M_E_CPU0_SA_DQ<31>")
	)
	(segment
		(start 409.118562 -279.093422)
		(end 409.319222 -279.294082)
		(width 0.20066)
		(layer "F.Cu")
		(net "M_E_CPU0_SA_DQ<31>")
	)
	(segment
		(start 386.944362 -263.525508)
		(end 387.28142 -263.525508)
		(width 0.088646)
		(layer "F.Cu")
		(net "M_E_CPU0_SA_DQ<31>")
	)
	(segment
		(start 402.444204 -279.067514)
		(end 402.805646 -279.067514)
		(width 0.20066)
		(layer "F.Cu")
		(net "M_E_CPU0_SA_DQ<31>")
	)
	(segment
		(start 402.805646 -279.067514)
		(end 403.099778 -279.361646)
		(width 0.20066)
		(layer "F.Cu")
		(net "M_E_CPU0_SA_DQ<31>")
	)
	(segment
		(start 399.242026 -278.739092)
		(end 400.32559 -279.822656)
		(width 0.20066)
		(layer "F.Cu")
		(net "M_E_CPU0_SA_DQ<31>")
	)
	(segment
		(start 412.594298 -280.199846)
		(end 412.161228 -279.766776)
		(width 0.20066)
		(layer "F.Cu")
		(net "M_E_CPU0_SA_DQ<31>")
	)
	(segment
		(start 401.040854 -279.293066)
		(end 401.4216 -279.293066)
		(width 0.20066)
		(layer "F.Cu")
		(net "M_E_CPU0_SA_DQ<31>")
	)
	(segment
		(start 415.962592 -279.71115)
		(end 415.962592 -279.999186)
		(width 0.20066)
		(layer "F.Cu")
		(net "M_E_CPU0_SA_DQ<31>")
	)
	(segment
		(start 403.099778 -279.361646)
		(end 403.23897 -279.419304)
		(width 0.20066)
		(layer "F.Cu")
		(net "M_E_CPU0_SA_DQ<31>")
	)
	(segment
		(start 400.82978 -279.602692)
		(end 400.82978 -279.50414)
		(width 0.20066)
		(layer "F.Cu")
		(net "M_E_CPU0_SA_DQ<31>")
	)
	(segment
		(start 401.4216 -279.293066)
		(end 401.442936 -279.314402)
		(width 0.20066)
		(layer "F.Cu")
		(net "M_E_CPU0_SA_DQ<31>")
	)
	(segment
		(start 405.749506 -280.191718)
		(end 407.716228 -280.191718)
		(width 0.1016)
		(layer "F.Cu")
		(net "M_E_CPU0_SA_DQ<31>")
	)
	(segment
		(start 408.442414 -279.294082)
		(end 408.643074 -279.093422)
		(width 0.20066)
		(layer "F.Cu")
		(net "M_E_CPU0_SA_DQ<31>")
	)
	(segment
		(start 396.831312 -272.270728)
		(end 397.889476 -277.561548)
		(width 0.1016)
		(layer "F.Cu")
		(net "M_E_CPU0_SA_DQ<31>")
	)
	(segment
		(start 416.163252 -279.51049)
		(end 415.962592 -279.71115)
		(width 0.20066)
		(layer "F.Cu")
		(net "M_E_CPU0_SA_DQ<31>")
	)
	(segment
		(start 400.32559 -279.822656)
		(end 400.609816 -279.822656)
		(width 0.20066)
		(layer "F.Cu")
		(net "M_E_CPU0_SA_DQ<31>")
	)
	(segment
		(start 415.761932 -280.199846)
		(end 415.307526 -280.199846)
		(width 0.20066)
		(layer "F.Cu")
		(net "M_E_CPU0_SA_DQ<31>")
	)
	(segment
		(start 387.989064 -263.42848)
		(end 389.091424 -264.53084)
		(width 0.088646)
		(layer "F.Cu")
		(net "M_E_CPU0_SA_DQ<31>")
	)
	(segment
		(start 410.339032 -279.766776)
		(end 410.853382 -279.766776)
		(width 0.20066)
		(layer "F.Cu")
		(net "M_E_CPU0_SA_DQ<31>")
	)
	(segment
		(start 403.23897 -279.419304)
		(end 404.965916 -279.419304)
		(width 0.20066)
		(layer "F.Cu")
		(net "M_E_CPU0_SA_DQ<31>")
	)
	(segment
		(start 405.334216 -280.191718)
		(end 405.564086 -280.191718)
		(width 0.20066)
		(layer "F.Cu")
		(net "M_E_CPU0_SA_DQ<31>")
	)
	(segment
		(start 389.091424 -264.53084)
		(end 396.831312 -272.270728)
		(width 0.1016)
		(layer "F.Cu")
		(net "M_E_CPU0_SA_DQ<31>")
	)
	(segment
		(start 405.564086 -280.191718)
		(end 405.749506 -280.191718)
		(width 0.101854)
		(layer "F.Cu")
		(net "M_E_CPU0_SA_DQ<31>")
	)
	(segment
		(start 397.889476 -277.561548)
		(end 398.858994 -278.35606)
		(width 0.1016)
		(layer "F.Cu")
		(net "M_E_CPU0_SA_DQ<31>")
	)
	(segment
		(start 416.989514 -280.160476)
		(end 416.797744 -279.968706)
		(width 0.20066)
		(layer "F.Cu")
		(net "M_E_CPU0_SA_DQ<31>")
	)
	(segment
		(start 408.643074 -279.093422)
		(end 409.118562 -279.093422)
		(width 0.20066)
		(layer "F.Cu")
		(net "M_E_CPU0_SA_DQ<31>")
	)
	(segment
		(start 413.275526 -280.199846)
		(end 412.594298 -280.199846)
		(width 0.20066)
		(layer "F.Cu")
		(net "M_E_CPU0_SA_DQ<31>")
	)
	(segment
		(start 387.28142 -263.525508)
		(end 387.378448 -263.42848)
		(width 0.088646)
		(layer "F.Cu")
		(net "M_E_CPU0_SA_DQ<31>")
	)
	(segment
		(start 408.442414 -280.02484)
		(end 408.442414 -279.294082)
		(width 0.20066)
		(layer "F.Cu")
		(net "M_E_CPU0_SA_DQ<31>")
	)
	(segment
		(start 415.299398 -280.191718)
		(end 413.30118 -280.191718)
		(width 0.1016)
		(layer "F.Cu")
		(net "M_E_CPU0_SA_DQ<31>")
	)
	(segment
		(start 400.609816 -279.822656)
		(end 400.82978 -279.602692)
		(width 0.20066)
		(layer "F.Cu")
		(net "M_E_CPU0_SA_DQ<31>")
	)
	(segment
		(start 409.948634 -280.157174)
		(end 410.339032 -279.766776)
		(width 0.20066)
		(layer "F.Cu")
		(net "M_E_CPU0_SA_DQ<31>")
	)
	(segment
		(start 405.133302 -279.58669)
		(end 405.133302 -279.990804)
		(width 0.20066)
		(layer "F.Cu")
		(net "M_E_CPU0_SA_DQ<31>")
	)
	(segment
		(start 409.499562 -280.157174)
		(end 409.948634 -280.157174)
		(width 0.20066)
		(layer "F.Cu")
		(net "M_E_CPU0_SA_DQ<31>")
	)
	(segment
		(start 407.748486 -280.223976)
		(end 407.763726 -280.223976)
		(width 0.1016)
		(layer "F.Cu")
		(net "M_E_CPU0_SA_DQ<31>")
	)
	(arc
		(start 386.742432 -263.466326)
		(mid 386.839159 -263.510378)
		(end 386.944362 -263.525508)
		(width 0.088646)
		(layer "F.Cu")
		(net "M_E_CPU0_SA_DQ<31>")
	)
	(arc
		(start 386.004562 -263.150604)
		(mid 386.238521 -263.187936)
		(end 386.455666 -263.282684)
		(width 0.088646)
		(layer "F.Cu")
		(net "M_E_CPU0_SA_DQ<31>")
	)
	(segment
		(start 415.312606 -281.899106)
		(end 415.307526 -281.899106)
		(width 0.20066)
		(layer "F.Cu")
		(net "M_E_CPU0_SA_DQ<30>")
	)
	(segment
		(start 407.763726 -281.904186)
		(end 408.14498 -281.904186)
		(width 0.20066)
		(layer "F.Cu")
		(net "M_E_CPU0_SA_DQ<30>")
	)
	(segment
		(start 412.542482 -281.466798)
		(end 410.853382 -281.466798)
		(width 0.20066)
		(layer "F.Cu")
		(net "M_E_CPU0_SA_DQ<30>")
	)
	(segment
		(start 397.578834 -279.11679)
		(end 398.146778 -279.684734)
		(width 0.1016)
		(layer "F.Cu")
		(net "M_E_CPU0_SA_DQ<30>")
	)
	(segment
		(start 413.275526 -281.90063)
		(end 412.976314 -281.90063)
		(width 0.20066)
		(layer "F.Cu")
		(net "M_E_CPU0_SA_DQ<30>")
	)
	(segment
		(start 386.474716 -263.96442)
		(end 386.752338 -263.967214)
		(width 0.088646)
		(layer "F.Cu")
		(net "M_E_CPU0_SA_DQ<30>")
	)
	(segment
		(start 415.30016 -281.89174)
		(end 413.301942 -281.89174)
		(width 0.1016)
		(layer "F.Cu")
		(net "M_E_CPU0_SA_DQ<30>")
	)
	(segment
		(start 400.716242 -282.051506)
		(end 402.388324 -282.051506)
		(width 0.20066)
		(layer "F.Cu")
		(net "M_E_CPU0_SA_DQ<30>")
	)
	(segment
		(start 396.26921 -272.571718)
		(end 397.578834 -279.11679)
		(width 0.1016)
		(layer "F.Cu")
		(net "M_E_CPU0_SA_DQ<30>")
	)
	(segment
		(start 403.525482 -281.340052)
		(end 403.525482 -281.08402)
		(width 0.20066)
		(layer "F.Cu")
		(net "M_E_CPU0_SA_DQ<30>")
	)
	(segment
		(start 408.358086 -281.69108)
		(end 408.358086 -281.33421)
		(width 0.20066)
		(layer "F.Cu")
		(net "M_E_CPU0_SA_DQ<30>")
	)
	(segment
		(start 405.731726 -281.90063)
		(end 405.74468 -281.90063)
		(width 0.101854)
		(layer "F.Cu")
		(net "M_E_CPU0_SA_DQ<30>")
	)
	(segment
		(start 403.303232 -281.8765)
		(end 403.525482 -281.340052)
		(width 0.20066)
		(layer "F.Cu")
		(net "M_E_CPU0_SA_DQ<30>")
	)
	(segment
		(start 403.525482 -281.08402)
		(end 403.904196 -280.705306)
		(width 0.20066)
		(layer "F.Cu")
		(net "M_E_CPU0_SA_DQ<30>")
	)
	(segment
		(start 386.752338 -263.967214)
		(end 386.809742 -263.910826)
		(width 0.088646)
		(layer "F.Cu")
		(net "M_E_CPU0_SA_DQ<30>")
	)
	(segment
		(start 407.75128 -281.89174)
		(end 407.763726 -281.904186)
		(width 0.1016)
		(layer "F.Cu")
		(net "M_E_CPU0_SA_DQ<30>")
	)
	(segment
		(start 418.397182 -281.466798)
		(end 417.07562 -281.466798)
		(width 0.20066)
		(layer "F.Cu")
		(net "M_E_CPU0_SA_DQ<30>")
	)
	(segment
		(start 405.74468 -281.90063)
		(end 405.74976 -281.90063)
		(width 0.1016)
		(layer "F.Cu")
		(net "M_E_CPU0_SA_DQ<30>")
	)
	(segment
		(start 408.93365 -281.095196)
		(end 409.305252 -281.466798)
		(width 0.20066)
		(layer "F.Cu")
		(net "M_E_CPU0_SA_DQ<30>")
	)
	(segment
		(start 402.900388 -282.279344)
		(end 403.303232 -281.8765)
		(width 0.20066)
		(layer "F.Cu")
		(net "M_E_CPU0_SA_DQ<30>")
	)
	(segment
		(start 416.747452 -281.13863)
		(end 416.414204 -281.13863)
		(width 0.20066)
		(layer "F.Cu")
		(net "M_E_CPU0_SA_DQ<30>")
	)
	(segment
		(start 415.320988 -281.897836)
		(end 415.317432 -281.89682)
		(width 0.20066)
		(layer "F.Cu")
		(net "M_E_CPU0_SA_DQ<30>")
	)
	(segment
		(start 404.257002 -280.705306)
		(end 405.452326 -281.90063)
		(width 0.20066)
		(layer "F.Cu")
		(net "M_E_CPU0_SA_DQ<30>")
	)
	(segment
		(start 408.358086 -281.33421)
		(end 408.5971 -281.095196)
		(width 0.20066)
		(layer "F.Cu")
		(net "M_E_CPU0_SA_DQ<30>")
	)
	(segment
		(start 412.976314 -281.90063)
		(end 412.542482 -281.466798)
		(width 0.20066)
		(layer "F.Cu")
		(net "M_E_CPU0_SA_DQ<30>")
	)
	(segment
		(start 408.5971 -281.095196)
		(end 408.93365 -281.095196)
		(width 0.20066)
		(layer "F.Cu")
		(net "M_E_CPU0_SA_DQ<30>")
	)
	(segment
		(start 386.809742 -263.910826)
		(end 387.608318 -263.910826)
		(width 0.088646)
		(layer "F.Cu")
		(net "M_E_CPU0_SA_DQ<30>")
	)
	(segment
		(start 413.293052 -281.90063)
		(end 413.275526 -281.90063)
		(width 0.101854)
		(layer "F.Cu")
		(net "M_E_CPU0_SA_DQ<30>")
	)
	(segment
		(start 415.307526 -281.899106)
		(end 415.30016 -281.89174)
		(width 0.1016)
		(layer "F.Cu")
		(net "M_E_CPU0_SA_DQ<30>")
	)
	(segment
		(start 417.07562 -281.466798)
		(end 416.747452 -281.13863)
		(width 0.20066)
		(layer "F.Cu")
		(net "M_E_CPU0_SA_DQ<30>")
	)
	(segment
		(start 388.659878 -264.962386)
		(end 396.26921 -272.571718)
		(width 0.1016)
		(layer "F.Cu")
		(net "M_E_CPU0_SA_DQ<30>")
	)
	(segment
		(start 398.146778 -279.684734)
		(end 398.34947 -279.684734)
		(width 0.1016)
		(layer "F.Cu")
		(net "M_E_CPU0_SA_DQ<30>")
	)
	(segment
		(start 387.608318 -263.910826)
		(end 388.659878 -264.962386)
		(width 0.088646)
		(layer "F.Cu")
		(net "M_E_CPU0_SA_DQ<30>")
	)
	(segment
		(start 415.317432 -281.89682)
		(end 415.312606 -281.899106)
		(width 0.20066)
		(layer "F.Cu")
		(net "M_E_CPU0_SA_DQ<30>")
	)
	(segment
		(start 405.452326 -281.90063)
		(end 405.731726 -281.90063)
		(width 0.20066)
		(layer "F.Cu")
		(net "M_E_CPU0_SA_DQ<30>")
	)
	(segment
		(start 408.14498 -281.904186)
		(end 408.358086 -281.69108)
		(width 0.20066)
		(layer "F.Cu")
		(net "M_E_CPU0_SA_DQ<30>")
	)
	(segment
		(start 398.46758 -279.802844)
		(end 400.716242 -282.051506)
		(width 0.20066)
		(layer "F.Cu")
		(net "M_E_CPU0_SA_DQ<30>")
	)
	(segment
		(start 416.414204 -281.13863)
		(end 416.205416 -281.347418)
		(width 0.20066)
		(layer "F.Cu")
		(net "M_E_CPU0_SA_DQ<30>")
	)
	(segment
		(start 413.301942 -281.89174)
		(end 413.293052 -281.90063)
		(width 0.1016)
		(layer "F.Cu")
		(net "M_E_CPU0_SA_DQ<30>")
	)
	(segment
		(start 402.388324 -282.051506)
		(end 402.616162 -282.279344)
		(width 0.20066)
		(layer "F.Cu")
		(net "M_E_CPU0_SA_DQ<30>")
	)
	(segment
		(start 402.616162 -282.279344)
		(end 402.900388 -282.279344)
		(width 0.20066)
		(layer "F.Cu")
		(net "M_E_CPU0_SA_DQ<30>")
	)
	(segment
		(start 416.205416 -281.347418)
		(end 416.205416 -281.698192)
		(width 0.20066)
		(layer "F.Cu")
		(net "M_E_CPU0_SA_DQ<30>")
	)
	(segment
		(start 405.75865 -281.89174)
		(end 407.75128 -281.89174)
		(width 0.1016)
		(layer "F.Cu")
		(net "M_E_CPU0_SA_DQ<30>")
	)
	(segment
		(start 409.305252 -281.466798)
		(end 410.853382 -281.466798)
		(width 0.20066)
		(layer "F.Cu")
		(net "M_E_CPU0_SA_DQ<30>")
	)
	(segment
		(start 416.205416 -281.698192)
		(end 416.005772 -281.897836)
		(width 0.20066)
		(layer "F.Cu")
		(net "M_E_CPU0_SA_DQ<30>")
	)
	(segment
		(start 398.34947 -279.684734)
		(end 398.46758 -279.802844)
		(width 0.1016)
		(layer "F.Cu")
		(net "M_E_CPU0_SA_DQ<30>")
	)
	(segment
		(start 416.005772 -281.897836)
		(end 415.320988 -281.897836)
		(width 0.20066)
		(layer "F.Cu")
		(net "M_E_CPU0_SA_DQ<30>")
	)
	(segment
		(start 405.74976 -281.90063)
		(end 405.75865 -281.89174)
		(width 0.1016)
		(layer "F.Cu")
		(net "M_E_CPU0_SA_DQ<30>")
	)
	(segment
		(start 403.904196 -280.705306)
		(end 404.257002 -280.705306)
		(width 0.20066)
		(layer "F.Cu")
		(net "M_E_CPU0_SA_DQ<30>")
	)
	(segment
		(start 415.307526 -315.90361)
		(end 415.247328 -315.90361)
		(width 0.101854)
		(layer "F.Cu")
		(net "M_E_CPU0_SA_DQ<2>")
	)
	(segment
		(start 407.72715 -315.891672)
		(end 407.737056 -315.901578)
		(width 0.101854)
		(layer "F.Cu")
		(net "M_E_CPU0_SA_DQ<2>")
	)
	(segment
		(start 407.626566 -315.891672)
		(end 407.72715 -315.891672)
		(width 0.101854)
		(layer "F.Cu")
		(net "M_E_CPU0_SA_DQ<2>")
	)
	(segment
		(start 387.422898 -298.648882)
		(end 387.748272 -299.43425)
		(width 0.20066)
		(layer "F.Cu")
		(net "M_E_CPU0_SA_DQ<2>")
	)
	(segment
		(start 415.247328 -315.90361)
		(end 415.23539 -315.891672)
		(width 0.101854)
		(layer "F.Cu")
		(net "M_E_CPU0_SA_DQ<2>")
	)
	(segment
		(start 416.823652 -315.214762)
		(end 416.439604 -315.214762)
		(width 0.20066)
		(layer "F.Cu")
		(net "M_E_CPU0_SA_DQ<2>")
	)
	(segment
		(start 411.8483 -315.301884)
		(end 411.683454 -315.46673)
		(width 0.20066)
		(layer "F.Cu")
		(net "M_E_CPU0_SA_DQ<2>")
	)
	(segment
		(start 405.731726 -315.897514)
		(end 405.751538 -315.897514)
		(width 0.101854)
		(layer "F.Cu")
		(net "M_E_CPU0_SA_DQ<2>")
	)
	(segment
		(start 405.996902 -315.891672)
		(end 407.626566 -315.891672)
		(width 0.1016)
		(layer "F.Cu")
		(net "M_E_CPU0_SA_DQ<2>")
	)
	(segment
		(start 416.205416 -315.44895)
		(end 416.205416 -315.697616)
		(width 0.20066)
		(layer "F.Cu")
		(net "M_E_CPU0_SA_DQ<2>")
	)
	(segment
		(start 415.196274 -315.891672)
		(end 413.354774 -315.891672)
		(width 0.1016)
		(layer "F.Cu")
		(net "M_E_CPU0_SA_DQ<2>")
	)
	(segment
		(start 412.377128 -315.301884)
		(end 411.8483 -315.301884)
		(width 0.20066)
		(layer "F.Cu")
		(net "M_E_CPU0_SA_DQ<2>")
	)
	(segment
		(start 387.371844 -280.44648)
		(end 387.371844 -281.063446)
		(width 0.088646)
		(layer "F.Cu")
		(net "M_E_CPU0_SA_DQ<2>")
	)
	(segment
		(start 405.335486 -315.897514)
		(end 405.731726 -315.897514)
		(width 0.20066)
		(layer "F.Cu")
		(net "M_E_CPU0_SA_DQ<2>")
	)
	(segment
		(start 413.354774 -315.891672)
		(end 413.342582 -315.903864)
		(width 0.101854)
		(layer "F.Cu")
		(net "M_E_CPU0_SA_DQ<2>")
	)
	(segment
		(start 416.439604 -315.214762)
		(end 416.205416 -315.44895)
		(width 0.20066)
		(layer "F.Cu")
		(net "M_E_CPU0_SA_DQ<2>")
	)
	(segment
		(start 409.951682 -315.404246)
		(end 410.014166 -315.46673)
		(width 0.20066)
		(layer "F.Cu")
		(net "M_E_CPU0_SA_DQ<2>")
	)
	(segment
		(start 418.397182 -315.46673)
		(end 417.07562 -315.46673)
		(width 0.20066)
		(layer "F.Cu")
		(net "M_E_CPU0_SA_DQ<2>")
	)
	(segment
		(start 387.422898 -296.729658)
		(end 387.422898 -297.327828)
		(width 0.1016)
		(layer "F.Cu")
		(net "M_E_CPU0_SA_DQ<2>")
	)
	(segment
		(start 415.23539 -315.891672)
		(end 415.196274 -315.891672)
		(width 0.101854)
		(layer "F.Cu")
		(net "M_E_CPU0_SA_DQ<2>")
	)
	(segment
		(start 407.763726 -315.901578)
		(end 408.145234 -315.901578)
		(width 0.20066)
		(layer "F.Cu")
		(net "M_E_CPU0_SA_DQ<2>")
	)
	(segment
		(start 410.014166 -315.46673)
		(end 410.853382 -315.46673)
		(width 0.20066)
		(layer "F.Cu")
		(net "M_E_CPU0_SA_DQ<2>")
	)
	(segment
		(start 411.683454 -315.46673)
		(end 410.853382 -315.46673)
		(width 0.20066)
		(layer "F.Cu")
		(net "M_E_CPU0_SA_DQ<2>")
	)
	(segment
		(start 405.128476 -315.811916)
		(end 405.335486 -315.897514)
		(width 0.20066)
		(layer "F.Cu")
		(net "M_E_CPU0_SA_DQ<2>")
	)
	(segment
		(start 386.68833 -279.502362)
		(end 387.18744 -280.001472)
		(width 0.088646)
		(layer "F.Cu")
		(net "M_E_CPU0_SA_DQ<2>")
	)
	(segment
		(start 407.737056 -315.901578)
		(end 407.763726 -315.901578)
		(width 0.101854)
		(layer "F.Cu")
		(net "M_E_CPU0_SA_DQ<2>")
	)
	(segment
		(start 412.979108 -315.903864)
		(end 412.377128 -315.301884)
		(width 0.20066)
		(layer "F.Cu")
		(net "M_E_CPU0_SA_DQ<2>")
	)
	(segment
		(start 409.345892 -315.404246)
		(end 409.951682 -315.404246)
		(width 0.20066)
		(layer "F.Cu")
		(net "M_E_CPU0_SA_DQ<2>")
	)
	(segment
		(start 387.371844 -296.678604)
		(end 387.422898 -296.729658)
		(width 0.101854)
		(layer "F.Cu")
		(net "M_E_CPU0_SA_DQ<2>")
	)
	(segment
		(start 413.275526 -315.903864)
		(end 412.979108 -315.903864)
		(width 0.20066)
		(layer "F.Cu")
		(net "M_E_CPU0_SA_DQ<2>")
	)
	(segment
		(start 404.419054 -315.518038)
		(end 405.128476 -315.811916)
		(width 0.20066)
		(layer "F.Cu")
		(net "M_E_CPU0_SA_DQ<2>")
	)
	(segment
		(start 415.999422 -315.90361)
		(end 415.307526 -315.90361)
		(width 0.20066)
		(layer "F.Cu")
		(net "M_E_CPU0_SA_DQ<2>")
	)
	(segment
		(start 387.371844 -281.063446)
		(end 387.371844 -296.678604)
		(width 0.1016)
		(layer "F.Cu")
		(net "M_E_CPU0_SA_DQ<2>")
	)
	(segment
		(start 416.205416 -315.697616)
		(end 415.999422 -315.90361)
		(width 0.20066)
		(layer "F.Cu")
		(net "M_E_CPU0_SA_DQ<2>")
	)
	(segment
		(start 405.751538 -315.897514)
		(end 405.75738 -315.891672)
		(width 0.101854)
		(layer "F.Cu")
		(net "M_E_CPU0_SA_DQ<2>")
	)
	(segment
		(start 405.75738 -315.891672)
		(end 405.996902 -315.891672)
		(width 0.101854)
		(layer "F.Cu")
		(net "M_E_CPU0_SA_DQ<2>")
	)
	(segment
		(start 387.748272 -299.43425)
		(end 402.65223 -314.338208)
		(width 0.20066)
		(layer "F.Cu")
		(net "M_E_CPU0_SA_DQ<2>")
	)
	(segment
		(start 402.65223 -314.338208)
		(end 404.419054 -315.518038)
		(width 0.20066)
		(layer "F.Cu")
		(net "M_E_CPU0_SA_DQ<2>")
	)
	(segment
		(start 413.342582 -315.903864)
		(end 413.275526 -315.903864)
		(width 0.101854)
		(layer "F.Cu")
		(net "M_E_CPU0_SA_DQ<2>")
	)
	(segment
		(start 387.18744 -280.001472)
		(end 387.371844 -280.44648)
		(width 0.088646)
		(layer "F.Cu")
		(net "M_E_CPU0_SA_DQ<2>")
	)
	(segment
		(start 387.422898 -297.327828)
		(end 387.422898 -298.648882)
		(width 0.20066)
		(layer "F.Cu")
		(net "M_E_CPU0_SA_DQ<2>")
	)
	(segment
		(start 408.145234 -315.901578)
		(end 409.345892 -315.404246)
		(width 0.20066)
		(layer "F.Cu")
		(net "M_E_CPU0_SA_DQ<2>")
	)
	(segment
		(start 417.07562 -315.46673)
		(end 416.823652 -315.214762)
		(width 0.20066)
		(layer "F.Cu")
		(net "M_E_CPU0_SA_DQ<2>")
	)
	(segment
		(start 386.004562 -279.428194)
		(end 386.68833 -279.502362)
		(width 0.088646)
		(layer "F.Cu")
		(net "M_E_CPU0_SA_DQ<2>")
	)
	(segment
		(start 405.537416 -281.032712)
		(end 405.766016 -281.032712)
		(width 0.20066)
		(layer "F.Cu")
		(net "M_E_CPU0_SA_DQ<29>")
	)
	(segment
		(start 408.972512 -280.531316)
		(end 408.56662 -280.531316)
		(width 0.20066)
		(layer "F.Cu")
		(net "M_E_CPU0_SA_DQ<29>")
	)
	(segment
		(start 398.022318 -278.668988)
		(end 398.154398 -278.801068)
		(width 0.1016)
		(layer "F.Cu")
		(net "M_E_CPU0_SA_DQ<29>")
	)
	(segment
		(start 402.88591 -280.926794)
		(end 402.68525 -280.726134)
		(width 0.20066)
		(layer "F.Cu")
		(net "M_E_CPU0_SA_DQ<29>")
	)
	(segment
		(start 412.578296 -280.61666)
		(end 412.143448 -281.051508)
		(width 0.20066)
		(layer "F.Cu")
		(net "M_E_CPU0_SA_DQ<29>")
	)
	(segment
		(start 386.247894 -263.529826)
		(end 386.33019 -263.529826)
		(width 0.088646)
		(layer "F.Cu")
		(net "M_E_CPU0_SA_DQ<29>")
	)
	(segment
		(start 398.392142 -278.801068)
		(end 398.633696 -279.042622)
		(width 0.1016)
		(layer "F.Cu")
		(net "M_E_CPU0_SA_DQ<29>")
	)
	(segment
		(start 409.831794 -281.059636)
		(end 409.500832 -281.059636)
		(width 0.20066)
		(layer "F.Cu")
		(net "M_E_CPU0_SA_DQ<29>")
	)
	(segment
		(start 387.844792 -263.715754)
		(end 388.875778 -264.74674)
		(width 0.088646)
		(layer "F.Cu")
		(net "M_E_CPU0_SA_DQ<29>")
	)
	(segment
		(start 402.88591 -281.211274)
		(end 402.88591 -280.926794)
		(width 0.20066)
		(layer "F.Cu")
		(net "M_E_CPU0_SA_DQ<29>")
	)
	(segment
		(start 411.853888 -281.041602)
		(end 409.851352 -281.041602)
		(width 0.1016)
		(layer "F.Cu")
		(net "M_E_CPU0_SA_DQ<29>")
	)
	(segment
		(start 396.550134 -272.421096)
		(end 397.649192 -277.914862)
		(width 0.1016)
		(layer "F.Cu")
		(net "M_E_CPU0_SA_DQ<29>")
	)
	(segment
		(start 397.649192 -277.914862)
		(end 398.022318 -278.287988)
		(width 0.1016)
		(layer "F.Cu")
		(net "M_E_CPU0_SA_DQ<29>")
	)
	(segment
		(start 385.064762 -263.150604)
		(end 385.352798 -263.269984)
		(width 0.088646)
		(layer "F.Cu")
		(net "M_E_CPU0_SA_DQ<29>")
	)
	(segment
		(start 398.154398 -278.801068)
		(end 398.392142 -278.801068)
		(width 0.1016)
		(layer "F.Cu")
		(net "M_E_CPU0_SA_DQ<29>")
	)
	(segment
		(start 403.481794 -280.224738)
		(end 403.644862 -280.06167)
		(width 0.20066)
		(layer "F.Cu")
		(net "M_E_CPU0_SA_DQ<29>")
	)
	(segment
		(start 398.633696 -279.042622)
		(end 401.003008 -281.411934)
		(width 0.20066)
		(layer "F.Cu")
		(net "M_E_CPU0_SA_DQ<29>")
	)
	(segment
		(start 411.863794 -281.051508)
		(end 411.853888 -281.041602)
		(width 0.1016)
		(layer "F.Cu")
		(net "M_E_CPU0_SA_DQ<29>")
	)
	(segment
		(start 409.500832 -281.059636)
		(end 408.972512 -280.531316)
		(width 0.20066)
		(layer "F.Cu")
		(net "M_E_CPU0_SA_DQ<29>")
	)
	(segment
		(start 401.305014 -280.726134)
		(end 401.104354 -280.525474)
		(width 0.20066)
		(layer "F.Cu")
		(net "M_E_CPU0_SA_DQ<29>")
	)
	(segment
		(start 401.003008 -281.411934)
		(end 402.68525 -281.411934)
		(width 0.20066)
		(layer "F.Cu")
		(net "M_E_CPU0_SA_DQ<29>")
	)
	(segment
		(start 408.067002 -281.030934)
		(end 407.679398 -281.030934)
		(width 0.20066)
		(layer "F.Cu")
		(net "M_E_CPU0_SA_DQ<29>")
	)
	(segment
		(start 402.68525 -281.411934)
		(end 402.88591 -281.211274)
		(width 0.20066)
		(layer "F.Cu")
		(net "M_E_CPU0_SA_DQ<29>")
	)
	(segment
		(start 407.679398 -281.030934)
		(end 407.265124 -280.61666)
		(width 0.20066)
		(layer "F.Cu")
		(net "M_E_CPU0_SA_DQ<29>")
	)
	(segment
		(start 388.875778 -264.74674)
		(end 396.550134 -272.421096)
		(width 0.1016)
		(layer "F.Cu")
		(net "M_E_CPU0_SA_DQ<29>")
	)
	(segment
		(start 406.182068 -280.61666)
		(end 406.753314 -280.61666)
		(width 0.20066)
		(layer "F.Cu")
		(net "M_E_CPU0_SA_DQ<29>")
	)
	(segment
		(start 414.297114 -280.61666)
		(end 412.578296 -280.61666)
		(width 0.20066)
		(layer "F.Cu")
		(net "M_E_CPU0_SA_DQ<29>")
	)
	(segment
		(start 407.265124 -280.61666)
		(end 406.753314 -280.61666)
		(width 0.20066)
		(layer "F.Cu")
		(net "M_E_CPU0_SA_DQ<29>")
	)
	(segment
		(start 386.593588 -263.600692)
		(end 386.661914 -263.640062)
		(width 0.088646)
		(layer "F.Cu")
		(net "M_E_CPU0_SA_DQ<29>")
	)
	(segment
		(start 401.104354 -280.240994)
		(end 401.305014 -280.040334)
		(width 0.20066)
		(layer "F.Cu")
		(net "M_E_CPU0_SA_DQ<29>")
	)
	(segment
		(start 403.644862 -280.06167)
		(end 404.566374 -280.06167)
		(width 0.20066)
		(layer "F.Cu")
		(net "M_E_CPU0_SA_DQ<29>")
	)
	(segment
		(start 405.766016 -281.032712)
		(end 406.182068 -280.61666)
		(width 0.20066)
		(layer "F.Cu")
		(net "M_E_CPU0_SA_DQ<29>")
	)
	(segment
		(start 408.56662 -280.531316)
		(end 408.067002 -281.030934)
		(width 0.20066)
		(layer "F.Cu")
		(net "M_E_CPU0_SA_DQ<29>")
	)
	(segment
		(start 404.566374 -280.06167)
		(end 405.537416 -281.032712)
		(width 0.20066)
		(layer "F.Cu")
		(net "M_E_CPU0_SA_DQ<29>")
	)
	(segment
		(start 385.704842 -263.622028)
		(end 386.155692 -263.622028)
		(width 0.088646)
		(layer "F.Cu")
		(net "M_E_CPU0_SA_DQ<29>")
	)
	(segment
		(start 403.197568 -280.224738)
		(end 403.481794 -280.224738)
		(width 0.20066)
		(layer "F.Cu")
		(net "M_E_CPU0_SA_DQ<29>")
	)
	(segment
		(start 386.944362 -263.715754)
		(end 387.844792 -263.715754)
		(width 0.088646)
		(layer "F.Cu")
		(net "M_E_CPU0_SA_DQ<29>")
	)
	(segment
		(start 401.305014 -280.040334)
		(end 403.013164 -280.040334)
		(width 0.20066)
		(layer "F.Cu")
		(net "M_E_CPU0_SA_DQ<29>")
	)
	(segment
		(start 401.104354 -280.525474)
		(end 401.104354 -280.240994)
		(width 0.20066)
		(layer "F.Cu")
		(net "M_E_CPU0_SA_DQ<29>")
	)
	(segment
		(start 412.143448 -281.051508)
		(end 411.863794 -281.051508)
		(width 0.20066)
		(layer "F.Cu")
		(net "M_E_CPU0_SA_DQ<29>")
	)
	(segment
		(start 398.022318 -278.287988)
		(end 398.022318 -278.668988)
		(width 0.1016)
		(layer "F.Cu")
		(net "M_E_CPU0_SA_DQ<29>")
	)
	(segment
		(start 403.013164 -280.040334)
		(end 403.197568 -280.224738)
		(width 0.20066)
		(layer "F.Cu")
		(net "M_E_CPU0_SA_DQ<29>")
	)
	(segment
		(start 409.833318 -281.059636)
		(end 409.831794 -281.059636)
		(width 0.101854)
		(layer "F.Cu")
		(net "M_E_CPU0_SA_DQ<29>")
	)
	(segment
		(start 409.851352 -281.041602)
		(end 409.833318 -281.059636)
		(width 0.1016)
		(layer "F.Cu")
		(net "M_E_CPU0_SA_DQ<29>")
	)
	(segment
		(start 385.352798 -263.269984)
		(end 385.704842 -263.622028)
		(width 0.088646)
		(layer "F.Cu")
		(net "M_E_CPU0_SA_DQ<29>")
	)
	(segment
		(start 386.155692 -263.622028)
		(end 386.247894 -263.529826)
		(width 0.088646)
		(layer "F.Cu")
		(net "M_E_CPU0_SA_DQ<29>")
	)
	(segment
		(start 402.68525 -280.726134)
		(end 401.305014 -280.726134)
		(width 0.20066)
		(layer "F.Cu")
		(net "M_E_CPU0_SA_DQ<29>")
	)
	(arc
		(start 386.661914 -263.640062)
		(mid 386.798156 -263.696496)
		(end 386.944362 -263.715754)
		(width 0.088646)
		(layer "F.Cu")
		(net "M_E_CPU0_SA_DQ<29>")
	)
	(arc
		(start 386.33019 -263.529826)
		(mid 386.466562 -263.547888)
		(end 386.593588 -263.600692)
		(width 0.088646)
		(layer "F.Cu")
		(net "M_E_CPU0_SA_DQ<29>")
	)
	(segment
		(start 400.73453 -282.691078)
		(end 400.935444 -282.891992)
		(width 0.20066)
		(layer "F.Cu")
		(net "M_E_CPU0_SA_DQ<28>")
	)
	(segment
		(start 385.736338 -264.49401)
		(end 385.816094 -264.414254)
		(width 0.088646)
		(layer "F.Cu")
		(net "M_E_CPU0_SA_DQ<28>")
	)
	(segment
		(start 405.284178 -282.316682)
		(end 406.753314 -282.316682)
		(width 0.20066)
		(layer "F.Cu")
		(net "M_E_CPU0_SA_DQ<28>")
	)
	(segment
		(start 400.935444 -283.067506)
		(end 401.136104 -283.268166)
		(width 0.20066)
		(layer "F.Cu")
		(net "M_E_CPU0_SA_DQ<28>")
	)
	(segment
		(start 402.3233 -283.066744)
		(end 402.52396 -283.267404)
		(width 0.20066)
		(layer "F.Cu")
		(net "M_E_CPU0_SA_DQ<28>")
	)
	(segment
		(start 385.498086 -264.368026)
		(end 385.62407 -264.49401)
		(width 0.088646)
		(layer "F.Cu")
		(net "M_E_CPU0_SA_DQ<28>")
	)
	(segment
		(start 402.902928 -283.267404)
		(end 403.27453 -282.895802)
		(width 0.20066)
		(layer "F.Cu")
		(net "M_E_CPU0_SA_DQ<28>")
	)
	(segment
		(start 412.270448 -281.872436)
		(end 411.863794 -281.872436)
		(width 0.20066)
		(layer "F.Cu")
		(net "M_E_CPU0_SA_DQ<28>")
	)
	(segment
		(start 385.004564 -264.08888)
		(end 385.130548 -264.08888)
		(width 0.088646)
		(layer "F.Cu")
		(net "M_E_CPU0_SA_DQ<28>")
	)
	(segment
		(start 409.311856 -282.0924)
		(end 409.311856 -282.42387)
		(width 0.20066)
		(layer "F.Cu")
		(net "M_E_CPU0_SA_DQ<28>")
	)
	(segment
		(start 401.821904 -282.691078)
		(end 402.116798 -282.691078)
		(width 0.20066)
		(layer "F.Cu")
		(net "M_E_CPU0_SA_DQ<28>")
	)
	(segment
		(start 385.62407 -264.49401)
		(end 385.736338 -264.49401)
		(width 0.088646)
		(layer "F.Cu")
		(net "M_E_CPU0_SA_DQ<28>")
	)
	(segment
		(start 400.935444 -282.891992)
		(end 400.935444 -283.067506)
		(width 0.20066)
		(layer "F.Cu")
		(net "M_E_CPU0_SA_DQ<28>")
	)
	(segment
		(start 412.714694 -282.316682)
		(end 412.270448 -281.872436)
		(width 0.20066)
		(layer "F.Cu")
		(net "M_E_CPU0_SA_DQ<28>")
	)
	(segment
		(start 409.831794 -281.882342)
		(end 409.521914 -281.882342)
		(width 0.20066)
		(layer "F.Cu")
		(net "M_E_CPU0_SA_DQ<28>")
	)
	(segment
		(start 387.38429 -264.11809)
		(end 387.872986 -264.606786)
		(width 0.088646)
		(layer "F.Cu")
		(net "M_E_CPU0_SA_DQ<28>")
	)
	(segment
		(start 408.517598 -282.316682)
		(end 406.753314 -282.316682)
		(width 0.20066)
		(layer "F.Cu")
		(net "M_E_CPU0_SA_DQ<28>")
	)
	(segment
		(start 385.816094 -264.203434)
		(end 385.905248 -264.11428)
		(width 0.088646)
		(layer "F.Cu")
		(net "M_E_CPU0_SA_DQ<28>")
	)
	(segment
		(start 384.834384 -264.25906)
		(end 385.004564 -264.08888)
		(width 0.088646)
		(layer "F.Cu")
		(net "M_E_CPU0_SA_DQ<28>")
	)
	(segment
		(start 385.289806 -264.248138)
		(end 385.498086 -264.368026)
		(width 0.088646)
		(layer "F.Cu")
		(net "M_E_CPU0_SA_DQ<28>")
	)
	(segment
		(start 387.872986 -264.606786)
		(end 395.988032 -272.721832)
		(width 0.1016)
		(layer "F.Cu")
		(net "M_E_CPU0_SA_DQ<28>")
	)
	(segment
		(start 402.52396 -283.267404)
		(end 402.902928 -283.267404)
		(width 0.20066)
		(layer "F.Cu")
		(net "M_E_CPU0_SA_DQ<28>")
	)
	(segment
		(start 386.040884 -264.11428)
		(end 386.260848 -264.334244)
		(width 0.088646)
		(layer "F.Cu")
		(net "M_E_CPU0_SA_DQ<28>")
	)
	(segment
		(start 386.970524 -264.11809)
		(end 387.38429 -264.11809)
		(width 0.088646)
		(layer "F.Cu")
		(net "M_E_CPU0_SA_DQ<28>")
	)
	(segment
		(start 405.17191 -282.204414)
		(end 405.284178 -282.316682)
		(width 0.20066)
		(layer "F.Cu")
		(net "M_E_CPU0_SA_DQ<28>")
	)
	(segment
		(start 385.816094 -264.414254)
		(end 385.816094 -264.203434)
		(width 0.088646)
		(layer "F.Cu")
		(net "M_E_CPU0_SA_DQ<28>")
	)
	(segment
		(start 411.84449 -281.89174)
		(end 409.846018 -281.89174)
		(width 0.1016)
		(layer "F.Cu")
		(net "M_E_CPU0_SA_DQ<28>")
	)
	(segment
		(start 384.011932 -264.13968)
		(end 384.011932 -264.311384)
		(width 0.088646)
		(layer "F.Cu")
		(net "M_E_CPU0_SA_DQ<28>")
	)
	(segment
		(start 403.27453 -282.80995)
		(end 403.845522 -282.238958)
		(width 0.20066)
		(layer "F.Cu")
		(net "M_E_CPU0_SA_DQ<28>")
	)
	(segment
		(start 384.088132 -264.06348)
		(end 384.011932 -264.13968)
		(width 0.088646)
		(layer "F.Cu")
		(net "M_E_CPU0_SA_DQ<28>")
	)
	(segment
		(start 409.311856 -282.42387)
		(end 409.136342 -282.599384)
		(width 0.20066)
		(layer "F.Cu")
		(net "M_E_CPU0_SA_DQ<28>")
	)
	(segment
		(start 409.521914 -281.882342)
		(end 409.311856 -282.0924)
		(width 0.20066)
		(layer "F.Cu")
		(net "M_E_CPU0_SA_DQ<28>")
	)
	(segment
		(start 403.27453 -282.895802)
		(end 403.27453 -282.80995)
		(width 0.20066)
		(layer "F.Cu")
		(net "M_E_CPU0_SA_DQ<28>")
	)
	(segment
		(start 408.8003 -282.599384)
		(end 408.517598 -282.316682)
		(width 0.20066)
		(layer "F.Cu")
		(net "M_E_CPU0_SA_DQ<28>")
	)
	(segment
		(start 400.445732 -282.691078)
		(end 400.73453 -282.691078)
		(width 0.20066)
		(layer "F.Cu")
		(net "M_E_CPU0_SA_DQ<28>")
	)
	(segment
		(start 409.846018 -281.89174)
		(end 409.83662 -281.882342)
		(width 0.1016)
		(layer "F.Cu")
		(net "M_E_CPU0_SA_DQ<28>")
	)
	(segment
		(start 404.120604 -281.757628)
		(end 404.40483 -281.757628)
		(width 0.20066)
		(layer "F.Cu")
		(net "M_E_CPU0_SA_DQ<28>")
	)
	(segment
		(start 385.905248 -264.11428)
		(end 386.040884 -264.11428)
		(width 0.088646)
		(layer "F.Cu")
		(net "M_E_CPU0_SA_DQ<28>")
	)
	(segment
		(start 385.130548 -264.08888)
		(end 385.289806 -264.248138)
		(width 0.088646)
		(layer "F.Cu")
		(net "M_E_CPU0_SA_DQ<28>")
	)
	(segment
		(start 401.621244 -283.067506)
		(end 401.621244 -282.891738)
		(width 0.20066)
		(layer "F.Cu")
		(net "M_E_CPU0_SA_DQ<28>")
	)
	(segment
		(start 395.988032 -272.721832)
		(end 397.387572 -279.715722)
		(width 0.1016)
		(layer "F.Cu")
		(net "M_E_CPU0_SA_DQ<28>")
	)
	(segment
		(start 402.3233 -282.89758)
		(end 402.3233 -283.066744)
		(width 0.20066)
		(layer "F.Cu")
		(net "M_E_CPU0_SA_DQ<28>")
	)
	(segment
		(start 384.011932 -264.311384)
		(end 384.111754 -264.411206)
		(width 0.088646)
		(layer "F.Cu")
		(net "M_E_CPU0_SA_DQ<28>")
	)
	(segment
		(start 401.420584 -283.268166)
		(end 401.621244 -283.067506)
		(width 0.20066)
		(layer "F.Cu")
		(net "M_E_CPU0_SA_DQ<28>")
	)
	(segment
		(start 386.696458 -264.278618)
		(end 386.970524 -264.11809)
		(width 0.088646)
		(layer "F.Cu")
		(net "M_E_CPU0_SA_DQ<28>")
	)
	(segment
		(start 401.621244 -282.891738)
		(end 401.821904 -282.691078)
		(width 0.20066)
		(layer "F.Cu")
		(net "M_E_CPU0_SA_DQ<28>")
	)
	(segment
		(start 397.387572 -279.715722)
		(end 397.847058 -280.092404)
		(width 0.1016)
		(layer "F.Cu")
		(net "M_E_CPU0_SA_DQ<28>")
	)
	(segment
		(start 402.116798 -282.691078)
		(end 402.3233 -282.89758)
		(width 0.20066)
		(layer "F.Cu")
		(net "M_E_CPU0_SA_DQ<28>")
	)
	(segment
		(start 384.783584 -264.288778)
		(end 384.834384 -264.25906)
		(width 0.088646)
		(layer "F.Cu")
		(net "M_E_CPU0_SA_DQ<28>")
	)
	(segment
		(start 403.845522 -282.238958)
		(end 403.991572 -281.88666)
		(width 0.20066)
		(layer "F.Cu")
		(net "M_E_CPU0_SA_DQ<28>")
	)
	(segment
		(start 403.991572 -281.88666)
		(end 404.120604 -281.757628)
		(width 0.20066)
		(layer "F.Cu")
		(net "M_E_CPU0_SA_DQ<28>")
	)
	(segment
		(start 384.111754 -264.411206)
		(end 384.32613 -264.411206)
		(width 0.088646)
		(layer "F.Cu")
		(net "M_E_CPU0_SA_DQ<28>")
	)
	(segment
		(start 411.863794 -281.872436)
		(end 411.84449 -281.89174)
		(width 0.1016)
		(layer "F.Cu")
		(net "M_E_CPU0_SA_DQ<28>")
	)
	(segment
		(start 404.851616 -282.204414)
		(end 405.17191 -282.204414)
		(width 0.20066)
		(layer "F.Cu")
		(net "M_E_CPU0_SA_DQ<28>")
	)
	(segment
		(start 409.83662 -281.882342)
		(end 409.831794 -281.882342)
		(width 0.101854)
		(layer "F.Cu")
		(net "M_E_CPU0_SA_DQ<28>")
	)
	(segment
		(start 404.40483 -281.757628)
		(end 404.851616 -282.204414)
		(width 0.20066)
		(layer "F.Cu")
		(net "M_E_CPU0_SA_DQ<28>")
	)
	(segment
		(start 409.136342 -282.599384)
		(end 408.8003 -282.599384)
		(width 0.20066)
		(layer "F.Cu")
		(net "M_E_CPU0_SA_DQ<28>")
	)
	(segment
		(start 414.297114 -282.316682)
		(end 412.714694 -282.316682)
		(width 0.20066)
		(layer "F.Cu")
		(net "M_E_CPU0_SA_DQ<28>")
	)
	(segment
		(start 398.467326 -280.712672)
		(end 400.445732 -282.691078)
		(width 0.20066)
		(layer "F.Cu")
		(net "M_E_CPU0_SA_DQ<28>")
	)
	(segment
		(start 386.260848 -264.334244)
		(end 386.49148 -264.334244)
		(width 0.088646)
		(layer "F.Cu")
		(net "M_E_CPU0_SA_DQ<28>")
	)
	(segment
		(start 384.595116 -263.96442)
		(end 384.355848 -264.06348)
		(width 0.088646)
		(layer "F.Cu")
		(net "M_E_CPU0_SA_DQ<28>")
	)
	(segment
		(start 401.136104 -283.268166)
		(end 401.420584 -283.268166)
		(width 0.20066)
		(layer "F.Cu")
		(net "M_E_CPU0_SA_DQ<28>")
	)
	(segment
		(start 397.847058 -280.092404)
		(end 398.467326 -280.712672)
		(width 0.1016)
		(layer "F.Cu")
		(net "M_E_CPU0_SA_DQ<28>")
	)
	(segment
		(start 384.355848 -264.06348)
		(end 384.088132 -264.06348)
		(width 0.088646)
		(layer "F.Cu")
		(net "M_E_CPU0_SA_DQ<28>")
	)
	(arc
		(start 384.32613 -264.411206)
		(mid 384.562903 -264.380064)
		(end 384.783584 -264.288778)
		(width 0.088646)
		(layer "F.Cu")
		(net "M_E_CPU0_SA_DQ<28>")
	)
	(arc
		(start 386.49148 -264.334244)
		(mid 386.597674 -264.320088)
		(end 386.696458 -264.278618)
		(width 0.088646)
		(layer "F.Cu")
		(net "M_E_CPU0_SA_DQ<28>")
	)
	(segment
		(start 396.336012 -282.302966)
		(end 396.669768 -282.804362)
		(width 0.1016)
		(layer "F.Cu")
		(net "M_E_CPU0_SA_DQ<27>")
	)
	(segment
		(start 405.736552 -286.175704)
		(end 405.770588 -286.141668)
		(width 0.1016)
		(layer "F.Cu")
		(net "M_E_CPU0_SA_DQ<27>")
	)
	(segment
		(start 405.770588 -286.141668)
		(end 407.7462 -286.141668)
		(width 0.1016)
		(layer "F.Cu")
		(net "M_E_CPU0_SA_DQ<27>")
	)
	(segment
		(start 397.053562 -283.188156)
		(end 399.319496 -285.45409)
		(width 0.20066)
		(layer "F.Cu")
		(net "M_E_CPU0_SA_DQ<27>")
	)
	(segment
		(start 415.307526 -286.153098)
		(end 415.296096 -286.141668)
		(width 0.101854)
		(layer "F.Cu")
		(net "M_E_CPU0_SA_DQ<27>")
	)
	(segment
		(start 386.799582 -265.726926)
		(end 388.42696 -267.354304)
		(width 0.088646)
		(layer "F.Cu")
		(net "M_E_CPU0_SA_DQ<27>")
	)
	(segment
		(start 416.02279 -286.153098)
		(end 415.307526 -286.153098)
		(width 0.20066)
		(layer "F.Cu")
		(net "M_E_CPU0_SA_DQ<27>")
	)
	(segment
		(start 407.7462 -286.141668)
		(end 407.763726 -286.159194)
		(width 0.1016)
		(layer "F.Cu")
		(net "M_E_CPU0_SA_DQ<27>")
	)
	(segment
		(start 386.474716 -265.592306)
		(end 386.799582 -265.726926)
		(width 0.088646)
		(layer "F.Cu")
		(net "M_E_CPU0_SA_DQ<27>")
	)
	(segment
		(start 418.397182 -285.716726)
		(end 417.07562 -285.716726)
		(width 0.20066)
		(layer "F.Cu")
		(net "M_E_CPU0_SA_DQ<27>")
	)
	(segment
		(start 413.293052 -286.149034)
		(end 413.275526 -286.149034)
		(width 0.101854)
		(layer "F.Cu")
		(net "M_E_CPU0_SA_DQ<27>")
	)
	(segment
		(start 412.887414 -286.149034)
		(end 412.455106 -285.716726)
		(width 0.20066)
		(layer "F.Cu")
		(net "M_E_CPU0_SA_DQ<27>")
	)
	(segment
		(start 404.988522 -285.968694)
		(end 405.195532 -286.175704)
		(width 0.20066)
		(layer "F.Cu")
		(net "M_E_CPU0_SA_DQ<27>")
	)
	(segment
		(start 408.877008 -285.592266)
		(end 409.16098 -285.592266)
		(width 0.20066)
		(layer "F.Cu")
		(net "M_E_CPU0_SA_DQ<27>")
	)
	(segment
		(start 408.067256 -286.159194)
		(end 408.197812 -286.28975)
		(width 0.20066)
		(layer "F.Cu")
		(net "M_E_CPU0_SA_DQ<27>")
	)
	(segment
		(start 416.439604 -285.464758)
		(end 416.205416 -285.698946)
		(width 0.20066)
		(layer "F.Cu")
		(net "M_E_CPU0_SA_DQ<27>")
	)
	(segment
		(start 394.575284 -273.502628)
		(end 396.336012 -282.302966)
		(width 0.1016)
		(layer "F.Cu")
		(net "M_E_CPU0_SA_DQ<27>")
	)
	(segment
		(start 408.197812 -286.28975)
		(end 408.481784 -286.28975)
		(width 0.20066)
		(layer "F.Cu")
		(net "M_E_CPU0_SA_DQ<27>")
	)
	(segment
		(start 399.319496 -285.45409)
		(end 400.56181 -285.968694)
		(width 0.20066)
		(layer "F.Cu")
		(net "M_E_CPU0_SA_DQ<27>")
	)
	(segment
		(start 405.195532 -286.175704)
		(end 405.731726 -286.175704)
		(width 0.20066)
		(layer "F.Cu")
		(net "M_E_CPU0_SA_DQ<27>")
	)
	(segment
		(start 412.455106 -285.716726)
		(end 410.853382 -285.716726)
		(width 0.20066)
		(layer "F.Cu")
		(net "M_E_CPU0_SA_DQ<27>")
	)
	(segment
		(start 413.275526 -286.149034)
		(end 412.887414 -286.149034)
		(width 0.20066)
		(layer "F.Cu")
		(net "M_E_CPU0_SA_DQ<27>")
	)
	(segment
		(start 388.42696 -267.354304)
		(end 394.575284 -273.502628)
		(width 0.1016)
		(layer "F.Cu")
		(net "M_E_CPU0_SA_DQ<27>")
	)
	(segment
		(start 416.205416 -285.970472)
		(end 416.02279 -286.153098)
		(width 0.20066)
		(layer "F.Cu")
		(net "M_E_CPU0_SA_DQ<27>")
	)
	(segment
		(start 408.481784 -286.28975)
		(end 408.682444 -286.08909)
		(width 0.20066)
		(layer "F.Cu")
		(net "M_E_CPU0_SA_DQ<27>")
	)
	(segment
		(start 408.682444 -285.78683)
		(end 408.877008 -285.592266)
		(width 0.20066)
		(layer "F.Cu")
		(net "M_E_CPU0_SA_DQ<27>")
	)
	(segment
		(start 415.296096 -286.141668)
		(end 414.498282 -286.141668)
		(width 0.101854)
		(layer "F.Cu")
		(net "M_E_CPU0_SA_DQ<27>")
	)
	(segment
		(start 400.56181 -285.968694)
		(end 404.988522 -285.968694)
		(width 0.20066)
		(layer "F.Cu")
		(net "M_E_CPU0_SA_DQ<27>")
	)
	(segment
		(start 396.669768 -282.804362)
		(end 397.053562 -283.188156)
		(width 0.1016)
		(layer "F.Cu")
		(net "M_E_CPU0_SA_DQ<27>")
	)
	(segment
		(start 409.28544 -285.716726)
		(end 410.853382 -285.716726)
		(width 0.20066)
		(layer "F.Cu")
		(net "M_E_CPU0_SA_DQ<27>")
	)
	(segment
		(start 413.300418 -286.141668)
		(end 413.293052 -286.149034)
		(width 0.1016)
		(layer "F.Cu")
		(net "M_E_CPU0_SA_DQ<27>")
	)
	(segment
		(start 417.07562 -285.716726)
		(end 416.823652 -285.464758)
		(width 0.20066)
		(layer "F.Cu")
		(net "M_E_CPU0_SA_DQ<27>")
	)
	(segment
		(start 405.731726 -286.175704)
		(end 405.736552 -286.175704)
		(width 0.101854)
		(layer "F.Cu")
		(net "M_E_CPU0_SA_DQ<27>")
	)
	(segment
		(start 407.763726 -286.159194)
		(end 408.067256 -286.159194)
		(width 0.20066)
		(layer "F.Cu")
		(net "M_E_CPU0_SA_DQ<27>")
	)
	(segment
		(start 414.498282 -286.141668)
		(end 413.300418 -286.141668)
		(width 0.1016)
		(layer "F.Cu")
		(net "M_E_CPU0_SA_DQ<27>")
	)
	(segment
		(start 416.823652 -285.464758)
		(end 416.439604 -285.464758)
		(width 0.20066)
		(layer "F.Cu")
		(net "M_E_CPU0_SA_DQ<27>")
	)
	(segment
		(start 408.682444 -286.08909)
		(end 408.682444 -285.78683)
		(width 0.20066)
		(layer "F.Cu")
		(net "M_E_CPU0_SA_DQ<27>")
	)
	(segment
		(start 416.205416 -285.698946)
		(end 416.205416 -285.970472)
		(width 0.20066)
		(layer "F.Cu")
		(net "M_E_CPU0_SA_DQ<27>")
	)
	(segment
		(start 409.16098 -285.592266)
		(end 409.28544 -285.716726)
		(width 0.20066)
		(layer "F.Cu")
		(net "M_E_CPU0_SA_DQ<27>")
	)
	(segment
		(start 386.004562 -266.405868)
		(end 386.25399 -266.453366)
		(width 0.088646)
		(layer "F.Cu")
		(net "M_E_CPU0_SA_DQ<26>")
	)
	(segment
		(start 418.397182 -287.416748)
		(end 417.07562 -287.416748)
		(width 0.20066)
		(layer "F.Cu")
		(net "M_E_CPU0_SA_DQ<26>")
	)
	(segment
		(start 394.012928 -273.802856)
		(end 395.60881 -281.780996)
		(width 0.1016)
		(layer "F.Cu")
		(net "M_E_CPU0_SA_DQ<26>")
	)
	(segment
		(start 412.663894 -287.416748)
		(end 410.853382 -287.416748)
		(width 0.20066)
		(layer "F.Cu")
		(net "M_E_CPU0_SA_DQ<26>")
	)
	(segment
		(start 413.300418 -287.84169)
		(end 413.293052 -287.849056)
		(width 0.1016)
		(layer "F.Cu")
		(net "M_E_CPU0_SA_DQ<26>")
	)
	(segment
		(start 415.307526 -287.85312)
		(end 415.296096 -287.84169)
		(width 0.101854)
		(layer "F.Cu")
		(net "M_E_CPU0_SA_DQ<26>")
	)
	(segment
		(start 416.205416 -287.398968)
		(end 416.205416 -287.687004)
		(width 0.20066)
		(layer "F.Cu")
		(net "M_E_CPU0_SA_DQ<26>")
	)
	(segment
		(start 395.60881 -281.780996)
		(end 395.60881 -282.360878)
		(width 0.1016)
		(layer "F.Cu")
		(net "M_E_CPU0_SA_DQ<26>")
	)
	(segment
		(start 396.135352 -284.106366)
		(end 399.754344 -287.725358)
		(width 0.20066)
		(layer "F.Cu")
		(net "M_E_CPU0_SA_DQ<26>")
	)
	(segment
		(start 413.293052 -287.849056)
		(end 413.275526 -287.849056)
		(width 0.101854)
		(layer "F.Cu")
		(net "M_E_CPU0_SA_DQ<26>")
	)
	(segment
		(start 405.736552 -287.867344)
		(end 405.762206 -287.84169)
		(width 0.1016)
		(layer "F.Cu")
		(net "M_E_CPU0_SA_DQ<26>")
	)
	(segment
		(start 395.60881 -282.360878)
		(end 395.903958 -283.874972)
		(width 0.1016)
		(layer "F.Cu")
		(net "M_E_CPU0_SA_DQ<26>")
	)
	(segment
		(start 416.0393 -287.85312)
		(end 415.307526 -287.85312)
		(width 0.20066)
		(layer "F.Cu")
		(net "M_E_CPU0_SA_DQ<26>")
	)
	(segment
		(start 414.498282 -287.84169)
		(end 413.300418 -287.84169)
		(width 0.1016)
		(layer "F.Cu")
		(net "M_E_CPU0_SA_DQ<26>")
	)
	(segment
		(start 405.731726 -287.867344)
		(end 405.736552 -287.867344)
		(width 0.101854)
		(layer "F.Cu")
		(net "M_E_CPU0_SA_DQ<26>")
	)
	(segment
		(start 416.439604 -287.16478)
		(end 416.205416 -287.398968)
		(width 0.20066)
		(layer "F.Cu")
		(net "M_E_CPU0_SA_DQ<26>")
	)
	(segment
		(start 386.92836 -266.718288)
		(end 387.652768 -267.442696)
		(width 0.088646)
		(layer "F.Cu")
		(net "M_E_CPU0_SA_DQ<26>")
	)
	(segment
		(start 408.727402 -287.416748)
		(end 410.853382 -287.416748)
		(width 0.20066)
		(layer "F.Cu")
		(net "M_E_CPU0_SA_DQ<26>")
	)
	(segment
		(start 395.903958 -283.874972)
		(end 396.135352 -284.106366)
		(width 0.1016)
		(layer "F.Cu")
		(net "M_E_CPU0_SA_DQ<26>")
	)
	(segment
		(start 387.652768 -267.442696)
		(end 394.012928 -273.802856)
		(width 0.1016)
		(layer "F.Cu")
		(net "M_E_CPU0_SA_DQ<26>")
	)
	(segment
		(start 413.275526 -287.849056)
		(end 413.096202 -287.849056)
		(width 0.20066)
		(layer "F.Cu")
		(net "M_E_CPU0_SA_DQ<26>")
	)
	(segment
		(start 408.071066 -287.855152)
		(end 408.727402 -287.416748)
		(width 0.20066)
		(layer "F.Cu")
		(net "M_E_CPU0_SA_DQ<26>")
	)
	(segment
		(start 407.763726 -287.855152)
		(end 408.071066 -287.855152)
		(width 0.20066)
		(layer "F.Cu")
		(net "M_E_CPU0_SA_DQ<26>")
	)
	(segment
		(start 416.823652 -287.16478)
		(end 416.439604 -287.16478)
		(width 0.20066)
		(layer "F.Cu")
		(net "M_E_CPU0_SA_DQ<26>")
	)
	(segment
		(start 405.48052 -287.867344)
		(end 405.731726 -287.867344)
		(width 0.20066)
		(layer "F.Cu")
		(net "M_E_CPU0_SA_DQ<26>")
	)
	(segment
		(start 405.762206 -287.84169)
		(end 407.750264 -287.84169)
		(width 0.1016)
		(layer "F.Cu")
		(net "M_E_CPU0_SA_DQ<26>")
	)
	(segment
		(start 399.754344 -287.725358)
		(end 405.338534 -287.725358)
		(width 0.20066)
		(layer "F.Cu")
		(net "M_E_CPU0_SA_DQ<26>")
	)
	(segment
		(start 416.205416 -287.687004)
		(end 416.0393 -287.85312)
		(width 0.20066)
		(layer "F.Cu")
		(net "M_E_CPU0_SA_DQ<26>")
	)
	(segment
		(start 417.07562 -287.416748)
		(end 416.823652 -287.16478)
		(width 0.20066)
		(layer "F.Cu")
		(net "M_E_CPU0_SA_DQ<26>")
	)
	(segment
		(start 407.750264 -287.84169)
		(end 407.763726 -287.855152)
		(width 0.1016)
		(layer "F.Cu")
		(net "M_E_CPU0_SA_DQ<26>")
	)
	(segment
		(start 405.338534 -287.725358)
		(end 405.48052 -287.867344)
		(width 0.20066)
		(layer "F.Cu")
		(net "M_E_CPU0_SA_DQ<26>")
	)
	(segment
		(start 413.096202 -287.849056)
		(end 412.663894 -287.416748)
		(width 0.20066)
		(layer "F.Cu")
		(net "M_E_CPU0_SA_DQ<26>")
	)
	(segment
		(start 415.296096 -287.84169)
		(end 414.498282 -287.84169)
		(width 0.101854)
		(layer "F.Cu")
		(net "M_E_CPU0_SA_DQ<26>")
	)
	(segment
		(start 386.25399 -266.453366)
		(end 386.92836 -266.718288)
		(width 0.088646)
		(layer "F.Cu")
		(net "M_E_CPU0_SA_DQ<26>")
	)
	(segment
		(start 404.32736 -286.660082)
		(end 404.611332 -286.660082)
		(width 0.20066)
		(layer "F.Cu")
		(net "M_E_CPU0_SA_DQ<25>")
	)
	(segment
		(start 401.592288 -286.61233)
		(end 402.044662 -287.064704)
		(width 0.20066)
		(layer "F.Cu")
		(net "M_E_CPU0_SA_DQ<25>")
	)
	(segment
		(start 411.863794 -286.12465)
		(end 411.846776 -286.141668)
		(width 0.1016)
		(layer "F.Cu")
		(net "M_E_CPU0_SA_DQ<25>")
	)
	(segment
		(start 399.809716 -286.875982)
		(end 400.01952 -287.085786)
		(width 0.20066)
		(layer "F.Cu")
		(net "M_E_CPU0_SA_DQ<25>")
	)
	(segment
		(start 409.185872 -286.331152)
		(end 409.185872 -286.627316)
		(width 0.20066)
		(layer "F.Cu")
		(net "M_E_CPU0_SA_DQ<25>")
	)
	(segment
		(start 404.611332 -286.660082)
		(end 405.003254 -287.052004)
		(width 0.20066)
		(layer "F.Cu")
		(net "M_E_CPU0_SA_DQ<25>")
	)
	(segment
		(start 400.834352 -287.085786)
		(end 401.307808 -286.61233)
		(width 0.20066)
		(layer "F.Cu")
		(net "M_E_CPU0_SA_DQ<25>")
	)
	(segment
		(start 412.624778 -286.56661)
		(end 412.182818 -286.12465)
		(width 0.20066)
		(layer "F.Cu")
		(net "M_E_CPU0_SA_DQ<25>")
	)
	(segment
		(start 396.361158 -283.4005)
		(end 396.601188 -283.64053)
		(width 0.1016)
		(layer "F.Cu")
		(net "M_E_CPU0_SA_DQ<25>")
	)
	(segment
		(start 394.293852 -273.652488)
		(end 395.91361 -281.746198)
		(width 0.1016)
		(layer "F.Cu")
		(net "M_E_CPU0_SA_DQ<25>")
	)
	(segment
		(start 385.68503 -265.998706)
		(end 385.866132 -265.817604)
		(width 0.088646)
		(layer "F.Cu")
		(net "M_E_CPU0_SA_DQ<25>")
	)
	(segment
		(start 402.044662 -287.064704)
		(end 402.328634 -287.064704)
		(width 0.20066)
		(layer "F.Cu")
		(net "M_E_CPU0_SA_DQ<25>")
	)
	(segment
		(start 399.609056 -286.310832)
		(end 399.809716 -286.511492)
		(width 0.20066)
		(layer "F.Cu")
		(net "M_E_CPU0_SA_DQ<25>")
	)
	(segment
		(start 399.27149 -286.310832)
		(end 399.609056 -286.310832)
		(width 0.20066)
		(layer "F.Cu")
		(net "M_E_CPU0_SA_DQ<25>")
	)
	(segment
		(start 407.897838 -286.790892)
		(end 407.673556 -286.56661)
		(width 0.20066)
		(layer "F.Cu")
		(net "M_E_CPU0_SA_DQ<25>")
	)
	(segment
		(start 401.307808 -286.61233)
		(end 401.592288 -286.61233)
		(width 0.20066)
		(layer "F.Cu")
		(net "M_E_CPU0_SA_DQ<25>")
	)
	(segment
		(start 409.185872 -286.627316)
		(end 409.022296 -286.790892)
		(width 0.20066)
		(layer "F.Cu")
		(net "M_E_CPU0_SA_DQ<25>")
	)
	(segment
		(start 395.91361 -282.207716)
		(end 396.361158 -283.4005)
		(width 0.1016)
		(layer "F.Cu")
		(net "M_E_CPU0_SA_DQ<25>")
	)
	(segment
		(start 409.386532 -286.130492)
		(end 409.185872 -286.331152)
		(width 0.20066)
		(layer "F.Cu")
		(net "M_E_CPU0_SA_DQ<25>")
	)
	(segment
		(start 386.64007 -265.998706)
		(end 387.868414 -267.22705)
		(width 0.088646)
		(layer "F.Cu")
		(net "M_E_CPU0_SA_DQ<25>")
	)
	(segment
		(start 409.83662 -286.130492)
		(end 409.831794 -286.130492)
		(width 0.101854)
		(layer "F.Cu")
		(net "M_E_CPU0_SA_DQ<25>")
	)
	(segment
		(start 414.297114 -286.56661)
		(end 412.624778 -286.56661)
		(width 0.20066)
		(layer "F.Cu")
		(net "M_E_CPU0_SA_DQ<25>")
	)
	(segment
		(start 405.498046 -286.841184)
		(end 405.949404 -286.841184)
		(width 0.20066)
		(layer "F.Cu")
		(net "M_E_CPU0_SA_DQ<25>")
	)
	(segment
		(start 405.003254 -287.052004)
		(end 405.287226 -287.052004)
		(width 0.20066)
		(layer "F.Cu")
		(net "M_E_CPU0_SA_DQ<25>")
	)
	(segment
		(start 384.595116 -265.592306)
		(end 384.489706 -265.849608)
		(width 0.088646)
		(layer "F.Cu")
		(net "M_E_CPU0_SA_DQ<25>")
	)
	(segment
		(start 403.52726 -287.085786)
		(end 403.901656 -287.085786)
		(width 0.20066)
		(layer "F.Cu")
		(net "M_E_CPU0_SA_DQ<25>")
	)
	(segment
		(start 409.022296 -286.790892)
		(end 407.897838 -286.790892)
		(width 0.20066)
		(layer "F.Cu")
		(net "M_E_CPU0_SA_DQ<25>")
	)
	(segment
		(start 402.766784 -286.626554)
		(end 403.068028 -286.626554)
		(width 0.20066)
		(layer "F.Cu")
		(net "M_E_CPU0_SA_DQ<25>")
	)
	(segment
		(start 395.91361 -281.746198)
		(end 395.91361 -282.207716)
		(width 0.1016)
		(layer "F.Cu")
		(net "M_E_CPU0_SA_DQ<25>")
	)
	(segment
		(start 411.846776 -286.141668)
		(end 409.847796 -286.141668)
		(width 0.1016)
		(layer "F.Cu")
		(net "M_E_CPU0_SA_DQ<25>")
	)
	(segment
		(start 384.48996 -265.91006)
		(end 384.57886 -265.998706)
		(width 0.088646)
		(layer "F.Cu")
		(net "M_E_CPU0_SA_DQ<25>")
	)
	(segment
		(start 386.395722 -265.998706)
		(end 386.64007 -265.998706)
		(width 0.088646)
		(layer "F.Cu")
		(net "M_E_CPU0_SA_DQ<25>")
	)
	(segment
		(start 384.57886 -265.998706)
		(end 385.68503 -265.998706)
		(width 0.088646)
		(layer "F.Cu")
		(net "M_E_CPU0_SA_DQ<25>")
	)
	(segment
		(start 405.287226 -287.052004)
		(end 405.498046 -286.841184)
		(width 0.20066)
		(layer "F.Cu")
		(net "M_E_CPU0_SA_DQ<25>")
	)
	(segment
		(start 409.847796 -286.141668)
		(end 409.83662 -286.130492)
		(width 0.1016)
		(layer "F.Cu")
		(net "M_E_CPU0_SA_DQ<25>")
	)
	(segment
		(start 387.868414 -267.22705)
		(end 394.293852 -273.652488)
		(width 0.1016)
		(layer "F.Cu")
		(net "M_E_CPU0_SA_DQ<25>")
	)
	(segment
		(start 407.673556 -286.56661)
		(end 406.753314 -286.56661)
		(width 0.20066)
		(layer "F.Cu")
		(net "M_E_CPU0_SA_DQ<25>")
	)
	(segment
		(start 399.809716 -286.511492)
		(end 399.809716 -286.875982)
		(width 0.20066)
		(layer "F.Cu")
		(net "M_E_CPU0_SA_DQ<25>")
	)
	(segment
		(start 403.068028 -286.626554)
		(end 403.52726 -287.085786)
		(width 0.20066)
		(layer "F.Cu")
		(net "M_E_CPU0_SA_DQ<25>")
	)
	(segment
		(start 400.01952 -287.085786)
		(end 400.834352 -287.085786)
		(width 0.20066)
		(layer "F.Cu")
		(net "M_E_CPU0_SA_DQ<25>")
	)
	(segment
		(start 409.831794 -286.130492)
		(end 409.386532 -286.130492)
		(width 0.20066)
		(layer "F.Cu")
		(net "M_E_CPU0_SA_DQ<25>")
	)
	(segment
		(start 402.328634 -287.064704)
		(end 402.766784 -286.626554)
		(width 0.20066)
		(layer "F.Cu")
		(net "M_E_CPU0_SA_DQ<25>")
	)
	(segment
		(start 396.601188 -283.64053)
		(end 399.27149 -286.310832)
		(width 0.20066)
		(layer "F.Cu")
		(net "M_E_CPU0_SA_DQ<25>")
	)
	(segment
		(start 384.489706 -265.849608)
		(end 384.48996 -265.91006)
		(width 0.088646)
		(layer "F.Cu")
		(net "M_E_CPU0_SA_DQ<25>")
	)
	(segment
		(start 386.21462 -265.817604)
		(end 386.395722 -265.998706)
		(width 0.088646)
		(layer "F.Cu")
		(net "M_E_CPU0_SA_DQ<25>")
	)
	(segment
		(start 403.901656 -287.085786)
		(end 404.32736 -286.660082)
		(width 0.20066)
		(layer "F.Cu")
		(net "M_E_CPU0_SA_DQ<25>")
	)
	(segment
		(start 412.182818 -286.12465)
		(end 411.863794 -286.12465)
		(width 0.20066)
		(layer "F.Cu")
		(net "M_E_CPU0_SA_DQ<25>")
	)
	(segment
		(start 406.223978 -286.56661)
		(end 406.753314 -286.56661)
		(width 0.20066)
		(layer "F.Cu")
		(net "M_E_CPU0_SA_DQ<25>")
	)
	(segment
		(start 405.949404 -286.841184)
		(end 406.223978 -286.56661)
		(width 0.20066)
		(layer "F.Cu")
		(net "M_E_CPU0_SA_DQ<25>")
	)
	(segment
		(start 385.866132 -265.817604)
		(end 386.21462 -265.817604)
		(width 0.088646)
		(layer "F.Cu")
		(net "M_E_CPU0_SA_DQ<25>")
	)
	(segment
		(start 384.734054 -266.798044)
		(end 386.336286 -266.798044)
		(width 0.088646)
		(layer "F.Cu")
		(net "M_E_CPU0_SA_DQ<24>")
	)
	(segment
		(start 410.652214 -287.84169)
		(end 409.84043 -287.84169)
		(width 0.101854)
		(layer "F.Cu")
		(net "M_E_CPU0_SA_DQ<24>")
	)
	(segment
		(start 411.863794 -287.849056)
		(end 411.853888 -287.849056)
		(width 0.101854)
		(layer "F.Cu")
		(net "M_E_CPU0_SA_DQ<24>")
	)
	(segment
		(start 411.846522 -287.84169)
		(end 410.652214 -287.84169)
		(width 0.1016)
		(layer "F.Cu")
		(net "M_E_CPU0_SA_DQ<24>")
	)
	(segment
		(start 387.437122 -267.658342)
		(end 393.732004 -273.953224)
		(width 0.1016)
		(layer "F.Cu")
		(net "M_E_CPU0_SA_DQ<24>")
	)
	(segment
		(start 414.297114 -288.266632)
		(end 413.372808 -288.266632)
		(width 0.20066)
		(layer "F.Cu")
		(net "M_E_CPU0_SA_DQ<24>")
	)
	(segment
		(start 407.678128 -288.266632)
		(end 406.753314 -288.266632)
		(width 0.20066)
		(layer "F.Cu")
		(net "M_E_CPU0_SA_DQ<24>")
	)
	(segment
		(start 412.461202 -287.849056)
		(end 411.863794 -287.849056)
		(width 0.20066)
		(layer "F.Cu")
		(net "M_E_CPU0_SA_DQ<24>")
	)
	(segment
		(start 393.732004 -273.953224)
		(end 395.29258 -281.755088)
		(width 0.1016)
		(layer "F.Cu")
		(net "M_E_CPU0_SA_DQ<24>")
	)
	(segment
		(start 408.378152 -288.585656)
		(end 407.997152 -288.585656)
		(width 0.20066)
		(layer "F.Cu")
		(net "M_E_CPU0_SA_DQ<24>")
	)
	(segment
		(start 385.021582 -266.362688)
		(end 384.652266 -266.362688)
		(width 0.088646)
		(layer "F.Cu")
		(net "M_E_CPU0_SA_DQ<24>")
	)
	(segment
		(start 411.853888 -287.849056)
		(end 411.846522 -287.84169)
		(width 0.1016)
		(layer "F.Cu")
		(net "M_E_CPU0_SA_DQ<24>")
	)
	(segment
		(start 413.154368 -288.485072)
		(end 412.76651 -288.485072)
		(width 0.20066)
		(layer "F.Cu")
		(net "M_E_CPU0_SA_DQ<24>")
	)
	(segment
		(start 406.157176 -288.266632)
		(end 406.753314 -288.266632)
		(width 0.20066)
		(layer "F.Cu")
		(net "M_E_CPU0_SA_DQ<24>")
	)
	(segment
		(start 395.682978 -284.55874)
		(end 399.493486 -288.369248)
		(width 0.20066)
		(layer "F.Cu")
		(net "M_E_CPU0_SA_DQ<24>")
	)
	(segment
		(start 407.997152 -288.585656)
		(end 407.678128 -288.266632)
		(width 0.20066)
		(layer "F.Cu")
		(net "M_E_CPU0_SA_DQ<24>")
	)
	(segment
		(start 385.064762 -266.405868)
		(end 385.021582 -266.362688)
		(width 0.088646)
		(layer "F.Cu")
		(net "M_E_CPU0_SA_DQ<24>")
	)
	(segment
		(start 386.772404 -266.912598)
		(end 387.092698 -267.232892)
		(width 0.088646)
		(layer "F.Cu")
		(net "M_E_CPU0_SA_DQ<24>")
	)
	(segment
		(start 395.29258 -284.168342)
		(end 395.682978 -284.55874)
		(width 0.1016)
		(layer "F.Cu")
		(net "M_E_CPU0_SA_DQ<24>")
	)
	(segment
		(start 412.66237 -288.380932)
		(end 412.66237 -288.050224)
		(width 0.20066)
		(layer "F.Cu")
		(net "M_E_CPU0_SA_DQ<24>")
	)
	(segment
		(start 384.564128 -266.450826)
		(end 384.564128 -266.628118)
		(width 0.088646)
		(layer "F.Cu")
		(net "M_E_CPU0_SA_DQ<24>")
	)
	(segment
		(start 399.493486 -288.369248)
		(end 405.18207 -288.369248)
		(width 0.20066)
		(layer "F.Cu")
		(net "M_E_CPU0_SA_DQ<24>")
	)
	(segment
		(start 395.29258 -281.755088)
		(end 395.29258 -284.168342)
		(width 0.1016)
		(layer "F.Cu")
		(net "M_E_CPU0_SA_DQ<24>")
	)
	(segment
		(start 405.476202 -288.66338)
		(end 405.760428 -288.66338)
		(width 0.20066)
		(layer "F.Cu")
		(net "M_E_CPU0_SA_DQ<24>")
	)
	(segment
		(start 412.76651 -288.485072)
		(end 412.66237 -288.380932)
		(width 0.20066)
		(layer "F.Cu")
		(net "M_E_CPU0_SA_DQ<24>")
	)
	(segment
		(start 409.831794 -287.833054)
		(end 409.130754 -287.833054)
		(width 0.20066)
		(layer "F.Cu")
		(net "M_E_CPU0_SA_DQ<24>")
	)
	(segment
		(start 384.564128 -266.628118)
		(end 384.734054 -266.798044)
		(width 0.088646)
		(layer "F.Cu")
		(net "M_E_CPU0_SA_DQ<24>")
	)
	(segment
		(start 413.372808 -288.266632)
		(end 413.154368 -288.485072)
		(width 0.20066)
		(layer "F.Cu")
		(net "M_E_CPU0_SA_DQ<24>")
	)
	(segment
		(start 384.652266 -266.362688)
		(end 384.564128 -266.450826)
		(width 0.088646)
		(layer "F.Cu")
		(net "M_E_CPU0_SA_DQ<24>")
	)
	(segment
		(start 405.18207 -288.369248)
		(end 405.476202 -288.66338)
		(width 0.20066)
		(layer "F.Cu")
		(net "M_E_CPU0_SA_DQ<24>")
	)
	(segment
		(start 387.092698 -267.313918)
		(end 387.437122 -267.658342)
		(width 0.088646)
		(layer "F.Cu")
		(net "M_E_CPU0_SA_DQ<24>")
	)
	(segment
		(start 387.092698 -267.232892)
		(end 387.092698 -267.313918)
		(width 0.088646)
		(layer "F.Cu")
		(net "M_E_CPU0_SA_DQ<24>")
	)
	(segment
		(start 409.130754 -287.833054)
		(end 408.378152 -288.585656)
		(width 0.20066)
		(layer "F.Cu")
		(net "M_E_CPU0_SA_DQ<24>")
	)
	(segment
		(start 409.84043 -287.84169)
		(end 409.831794 -287.833054)
		(width 0.101854)
		(layer "F.Cu")
		(net "M_E_CPU0_SA_DQ<24>")
	)
	(segment
		(start 386.336286 -266.798044)
		(end 386.772404 -266.912598)
		(width 0.088646)
		(layer "F.Cu")
		(net "M_E_CPU0_SA_DQ<24>")
	)
	(segment
		(start 405.760428 -288.66338)
		(end 406.157176 -288.266632)
		(width 0.20066)
		(layer "F.Cu")
		(net "M_E_CPU0_SA_DQ<24>")
	)
	(segment
		(start 412.66237 -288.050224)
		(end 412.461202 -287.849056)
		(width 0.20066)
		(layer "F.Cu")
		(net "M_E_CPU0_SA_DQ<24>")
	)
	(segment
		(start 415.296096 -289.541712)
		(end 414.498282 -289.541712)
		(width 0.101854)
		(layer "F.Cu")
		(net "M_E_CPU0_SA_DQ<23>")
	)
	(segment
		(start 409.17114 -288.697162)
		(end 409.917138 -288.697162)
		(width 0.20066)
		(layer "F.Cu")
		(net "M_E_CPU0_SA_DQ<23>")
	)
	(segment
		(start 386.84962 -268.001242)
		(end 386.975096 -268.001242)
		(width 0.088646)
		(layer "F.Cu")
		(net "M_E_CPU0_SA_DQ<23>")
	)
	(segment
		(start 414.498282 -289.541712)
		(end 413.300418 -289.541712)
		(width 0.1016)
		(layer "F.Cu")
		(net "M_E_CPU0_SA_DQ<23>")
	)
	(segment
		(start 405.361648 -289.57905)
		(end 405.731726 -289.57905)
		(width 0.20066)
		(layer "F.Cu")
		(net "M_E_CPU0_SA_DQ<23>")
	)
	(segment
		(start 417.07562 -289.11677)
		(end 416.823652 -288.864802)
		(width 0.20066)
		(layer "F.Cu")
		(net "M_E_CPU0_SA_DQ<23>")
	)
	(segment
		(start 402.284438 -289.45205)
		(end 402.48078 -289.255708)
		(width 0.20066)
		(layer "F.Cu")
		(net "M_E_CPU0_SA_DQ<23>")
	)
	(segment
		(start 408.903424 -289.373564)
		(end 409.004262 -289.272726)
		(width 0.20066)
		(layer "F.Cu")
		(net "M_E_CPU0_SA_DQ<23>")
	)
	(segment
		(start 399.25498 -290.142168)
		(end 399.25498 -290.426648)
		(width 0.20066)
		(layer "F.Cu")
		(net "M_E_CPU0_SA_DQ<23>")
	)
	(segment
		(start 413.275526 -289.549078)
		(end 412.984442 -289.549078)
		(width 0.20066)
		(layer "F.Cu")
		(net "M_E_CPU0_SA_DQ<23>")
	)
	(segment
		(start 399.45564 -290.627308)
		(end 402.083778 -290.627308)
		(width 0.20066)
		(layer "F.Cu")
		(net "M_E_CPU0_SA_DQ<23>")
	)
	(segment
		(start 386.004562 -268.033754)
		(end 386.238242 -268.130528)
		(width 0.088646)
		(layer "F.Cu")
		(net "M_E_CPU0_SA_DQ<23>")
	)
	(segment
		(start 393.221718 -274.286472)
		(end 394.381228 -280.083514)
		(width 0.1016)
		(layer "F.Cu")
		(net "M_E_CPU0_SA_DQ<23>")
	)
	(segment
		(start 394.381228 -280.083514)
		(end 394.381228 -284.510988)
		(width 0.1016)
		(layer "F.Cu")
		(net "M_E_CPU0_SA_DQ<23>")
	)
	(segment
		(start 402.48078 -289.255708)
		(end 405.038306 -289.255708)
		(width 0.20066)
		(layer "F.Cu")
		(net "M_E_CPU0_SA_DQ<23>")
	)
	(segment
		(start 416.010852 -289.553142)
		(end 415.307526 -289.553142)
		(width 0.20066)
		(layer "F.Cu")
		(net "M_E_CPU0_SA_DQ<23>")
	)
	(segment
		(start 408.254708 -289.373564)
		(end 408.903424 -289.373564)
		(width 0.20066)
		(layer "F.Cu")
		(net "M_E_CPU0_SA_DQ<23>")
	)
	(segment
		(start 401.400518 -289.941508)
		(end 399.45564 -289.941508)
		(width 0.20066)
		(layer "F.Cu")
		(net "M_E_CPU0_SA_DQ<23>")
	)
	(segment
		(start 401.400518 -289.255708)
		(end 401.601178 -289.456368)
		(width 0.20066)
		(layer "F.Cu")
		(net "M_E_CPU0_SA_DQ<23>")
	)
	(segment
		(start 407.735786 -289.541712)
		(end 407.763726 -289.569652)
		(width 0.1016)
		(layer "F.Cu")
		(net "M_E_CPU0_SA_DQ<23>")
	)
	(segment
		(start 388.958582 -270.023336)
		(end 393.221718 -274.286472)
		(width 0.1016)
		(layer "F.Cu")
		(net "M_E_CPU0_SA_DQ<23>")
	)
	(segment
		(start 386.720334 -268.130528)
		(end 386.84962 -268.001242)
		(width 0.088646)
		(layer "F.Cu")
		(net "M_E_CPU0_SA_DQ<23>")
	)
	(segment
		(start 395.093952 -285.223712)
		(end 399.125948 -289.255708)
		(width 0.20066)
		(layer "F.Cu")
		(net "M_E_CPU0_SA_DQ<23>")
	)
	(segment
		(start 388.852664 -269.917418)
		(end 388.958582 -270.023336)
		(width 0.088646)
		(layer "F.Cu")
		(net "M_E_CPU0_SA_DQ<23>")
	)
	(segment
		(start 401.601178 -289.456368)
		(end 401.601178 -289.740848)
		(width 0.20066)
		(layer "F.Cu")
		(net "M_E_CPU0_SA_DQ<23>")
	)
	(segment
		(start 416.205416 -289.09899)
		(end 416.205416 -289.358578)
		(width 0.20066)
		(layer "F.Cu")
		(net "M_E_CPU0_SA_DQ<23>")
	)
	(segment
		(start 399.125948 -289.255708)
		(end 401.400518 -289.255708)
		(width 0.20066)
		(layer "F.Cu")
		(net "M_E_CPU0_SA_DQ<23>")
	)
	(segment
		(start 413.300418 -289.541712)
		(end 413.293052 -289.549078)
		(width 0.1016)
		(layer "F.Cu")
		(net "M_E_CPU0_SA_DQ<23>")
	)
	(segment
		(start 399.45564 -289.941508)
		(end 399.25498 -290.142168)
		(width 0.20066)
		(layer "F.Cu")
		(net "M_E_CPU0_SA_DQ<23>")
	)
	(segment
		(start 416.823652 -288.864802)
		(end 416.439604 -288.864802)
		(width 0.20066)
		(layer "F.Cu")
		(net "M_E_CPU0_SA_DQ<23>")
	)
	(segment
		(start 409.917138 -288.697162)
		(end 410.336746 -289.11677)
		(width 0.20066)
		(layer "F.Cu")
		(net "M_E_CPU0_SA_DQ<23>")
	)
	(segment
		(start 386.975096 -268.001242)
		(end 388.852664 -269.878302)
		(width 0.088646)
		(layer "F.Cu")
		(net "M_E_CPU0_SA_DQ<23>")
	)
	(segment
		(start 413.293052 -289.549078)
		(end 413.275526 -289.549078)
		(width 0.101854)
		(layer "F.Cu")
		(net "M_E_CPU0_SA_DQ<23>")
	)
	(segment
		(start 418.397182 -289.11677)
		(end 417.07562 -289.11677)
		(width 0.20066)
		(layer "F.Cu")
		(net "M_E_CPU0_SA_DQ<23>")
	)
	(segment
		(start 386.238242 -268.130528)
		(end 386.720334 -268.130528)
		(width 0.088646)
		(layer "F.Cu")
		(net "M_E_CPU0_SA_DQ<23>")
	)
	(segment
		(start 408.05862 -289.569652)
		(end 408.254708 -289.373564)
		(width 0.20066)
		(layer "F.Cu")
		(net "M_E_CPU0_SA_DQ<23>")
	)
	(segment
		(start 405.731726 -289.57905)
		(end 405.736552 -289.57905)
		(width 0.101854)
		(layer "F.Cu")
		(net "M_E_CPU0_SA_DQ<23>")
	)
	(segment
		(start 415.307526 -289.553142)
		(end 415.296096 -289.541712)
		(width 0.101854)
		(layer "F.Cu")
		(net "M_E_CPU0_SA_DQ<23>")
	)
	(segment
		(start 410.336746 -289.11677)
		(end 410.853382 -289.11677)
		(width 0.20066)
		(layer "F.Cu")
		(net "M_E_CPU0_SA_DQ<23>")
	)
	(segment
		(start 402.284438 -290.426648)
		(end 402.284438 -289.45205)
		(width 0.20066)
		(layer "F.Cu")
		(net "M_E_CPU0_SA_DQ<23>")
	)
	(segment
		(start 405.77389 -289.541712)
		(end 407.735786 -289.541712)
		(width 0.1016)
		(layer "F.Cu")
		(net "M_E_CPU0_SA_DQ<23>")
	)
	(segment
		(start 401.601178 -289.740848)
		(end 401.400518 -289.941508)
		(width 0.20066)
		(layer "F.Cu")
		(net "M_E_CPU0_SA_DQ<23>")
	)
	(segment
		(start 394.381228 -284.510988)
		(end 395.093952 -285.223712)
		(width 0.1016)
		(layer "F.Cu")
		(net "M_E_CPU0_SA_DQ<23>")
	)
	(segment
		(start 405.736552 -289.57905)
		(end 405.77389 -289.541712)
		(width 0.1016)
		(layer "F.Cu")
		(net "M_E_CPU0_SA_DQ<23>")
	)
	(segment
		(start 409.004262 -289.272726)
		(end 409.004262 -288.86404)
		(width 0.20066)
		(layer "F.Cu")
		(net "M_E_CPU0_SA_DQ<23>")
	)
	(segment
		(start 405.038306 -289.255708)
		(end 405.361648 -289.57905)
		(width 0.20066)
		(layer "F.Cu")
		(net "M_E_CPU0_SA_DQ<23>")
	)
	(segment
		(start 412.552134 -289.11677)
		(end 410.853382 -289.11677)
		(width 0.20066)
		(layer "F.Cu")
		(net "M_E_CPU0_SA_DQ<23>")
	)
	(segment
		(start 409.004262 -288.86404)
		(end 409.17114 -288.697162)
		(width 0.20066)
		(layer "F.Cu")
		(net "M_E_CPU0_SA_DQ<23>")
	)
	(segment
		(start 407.763726 -289.569652)
		(end 408.05862 -289.569652)
		(width 0.20066)
		(layer "F.Cu")
		(net "M_E_CPU0_SA_DQ<23>")
	)
	(segment
		(start 416.439604 -288.864802)
		(end 416.205416 -289.09899)
		(width 0.20066)
		(layer "F.Cu")
		(net "M_E_CPU0_SA_DQ<23>")
	)
	(segment
		(start 388.852664 -269.878302)
		(end 388.852664 -269.917418)
		(width 0.088646)
		(layer "F.Cu")
		(net "M_E_CPU0_SA_DQ<23>")
	)
	(segment
		(start 416.205416 -289.358578)
		(end 416.010852 -289.553142)
		(width 0.20066)
		(layer "F.Cu")
		(net "M_E_CPU0_SA_DQ<23>")
	)
	(segment
		(start 399.25498 -290.426648)
		(end 399.45564 -290.627308)
		(width 0.20066)
		(layer "F.Cu")
		(net "M_E_CPU0_SA_DQ<23>")
	)
	(segment
		(start 412.984442 -289.549078)
		(end 412.552134 -289.11677)
		(width 0.20066)
		(layer "F.Cu")
		(net "M_E_CPU0_SA_DQ<23>")
	)
	(segment
		(start 402.083778 -290.627308)
		(end 402.284438 -290.426648)
		(width 0.20066)
		(layer "F.Cu")
		(net "M_E_CPU0_SA_DQ<23>")
	)
	(segment
		(start 414.498282 -291.241734)
		(end 413.300418 -291.241734)
		(width 0.1016)
		(layer "F.Cu")
		(net "M_E_CPU0_SA_DQ<22>")
	)
	(segment
		(start 408.492452 -290.383722)
		(end 408.886152 -290.383722)
		(width 0.20066)
		(layer "F.Cu")
		(net "M_E_CPU0_SA_DQ<22>")
	)
	(segment
		(start 404.474426 -290.538408)
		(end 404.909528 -290.97351)
		(width 0.20066)
		(layer "F.Cu")
		(net "M_E_CPU0_SA_DQ<22>")
	)
	(segment
		(start 388.441184 -270.006064)
		(end 388.441184 -270.368776)
		(width 0.088646)
		(layer "F.Cu")
		(net "M_E_CPU0_SA_DQ<22>")
	)
	(segment
		(start 405.445976 -291.259006)
		(end 405.731726 -291.259006)
		(width 0.20066)
		(layer "F.Cu")
		(net "M_E_CPU0_SA_DQ<22>")
	)
	(segment
		(start 411.621732 -290.58489)
		(end 411.38983 -290.816792)
		(width 0.20066)
		(layer "F.Cu")
		(net "M_E_CPU0_SA_DQ<22>")
	)
	(segment
		(start 398.646396 -292.179502)
		(end 399.031714 -292.179502)
		(width 0.20066)
		(layer "F.Cu")
		(net "M_E_CPU0_SA_DQ<22>")
	)
	(segment
		(start 386.94614 -268.51102)
		(end 388.441184 -270.006064)
		(width 0.088646)
		(layer "F.Cu")
		(net "M_E_CPU0_SA_DQ<22>")
	)
	(segment
		(start 409.789122 -290.458144)
		(end 410.073094 -290.458144)
		(width 0.20066)
		(layer "F.Cu")
		(net "M_E_CPU0_SA_DQ<22>")
	)
	(segment
		(start 416.205416 -290.799012)
		(end 416.205416 -291.052504)
		(width 0.20066)
		(layer "F.Cu")
		(net "M_E_CPU0_SA_DQ<22>")
	)
	(segment
		(start 405.16048 -290.97351)
		(end 405.445976 -291.259006)
		(width 0.20066)
		(layer "F.Cu")
		(net "M_E_CPU0_SA_DQ<22>")
	)
	(segment
		(start 386.38099 -268.51102)
		(end 386.94614 -268.51102)
		(width 0.088646)
		(layer "F.Cu")
		(net "M_E_CPU0_SA_DQ<22>")
	)
	(segment
		(start 403.607016 -290.739068)
		(end 403.807676 -290.538408)
		(width 0.20066)
		(layer "F.Cu")
		(net "M_E_CPU0_SA_DQ<22>")
	)
	(segment
		(start 404.909528 -290.97351)
		(end 405.16048 -290.97351)
		(width 0.20066)
		(layer "F.Cu")
		(net "M_E_CPU0_SA_DQ<22>")
	)
	(segment
		(start 408.327098 -291.026088)
		(end 408.327098 -290.549076)
		(width 0.20066)
		(layer "F.Cu")
		(net "M_E_CPU0_SA_DQ<22>")
	)
	(segment
		(start 416.823652 -290.564824)
		(end 416.439604 -290.564824)
		(width 0.20066)
		(layer "F.Cu")
		(net "M_E_CPU0_SA_DQ<22>")
	)
	(segment
		(start 403.084792 -292.447726)
		(end 403.360382 -292.172136)
		(width 0.20066)
		(layer "F.Cu")
		(net "M_E_CPU0_SA_DQ<22>")
	)
	(segment
		(start 405.927052 -291.241734)
		(end 407.74366 -291.241734)
		(width 0.1016)
		(layer "F.Cu")
		(net "M_E_CPU0_SA_DQ<22>")
	)
	(segment
		(start 413.300418 -291.241734)
		(end 413.293052 -291.2491)
		(width 0.1016)
		(layer "F.Cu")
		(net "M_E_CPU0_SA_DQ<22>")
	)
	(segment
		(start 410.431742 -290.816792)
		(end 410.853382 -290.816792)
		(width 0.20066)
		(layer "F.Cu")
		(net "M_E_CPU0_SA_DQ<22>")
	)
	(segment
		(start 409.146502 -290.816792)
		(end 409.430474 -290.816792)
		(width 0.20066)
		(layer "F.Cu")
		(net "M_E_CPU0_SA_DQ<22>")
	)
	(segment
		(start 407.74366 -291.241734)
		(end 407.763726 -291.2618)
		(width 0.1016)
		(layer "F.Cu")
		(net "M_E_CPU0_SA_DQ<22>")
	)
	(segment
		(start 416.439604 -290.564824)
		(end 416.205416 -290.799012)
		(width 0.20066)
		(layer "F.Cu")
		(net "M_E_CPU0_SA_DQ<22>")
	)
	(segment
		(start 403.360382 -292.172136)
		(end 403.360382 -291.1602)
		(width 0.20066)
		(layer "F.Cu")
		(net "M_E_CPU0_SA_DQ<22>")
	)
	(segment
		(start 384.595116 -268.84757)
		(end 384.58521 -268.81074)
		(width 0.088646)
		(layer "F.Cu")
		(net "M_E_CPU0_SA_DQ<22>")
	)
	(segment
		(start 412.177992 -290.58489)
		(end 411.621732 -290.58489)
		(width 0.20066)
		(layer "F.Cu")
		(net "M_E_CPU0_SA_DQ<22>")
	)
	(segment
		(start 386.132578 -268.61389)
		(end 386.38099 -268.51102)
		(width 0.088646)
		(layer "F.Cu")
		(net "M_E_CPU0_SA_DQ<22>")
	)
	(segment
		(start 413.275526 -291.2491)
		(end 412.842202 -291.2491)
		(width 0.20066)
		(layer "F.Cu")
		(net "M_E_CPU0_SA_DQ<22>")
	)
	(segment
		(start 388.441184 -270.368776)
		(end 388.730236 -270.657828)
		(width 0.088646)
		(layer "F.Cu")
		(net "M_E_CPU0_SA_DQ<22>")
	)
	(segment
		(start 385.991354 -268.61389)
		(end 386.132578 -268.61389)
		(width 0.088646)
		(layer "F.Cu")
		(net "M_E_CPU0_SA_DQ<22>")
	)
	(segment
		(start 409.430474 -290.816792)
		(end 409.789122 -290.458144)
		(width 0.20066)
		(layer "F.Cu")
		(net "M_E_CPU0_SA_DQ<22>")
	)
	(segment
		(start 399.031714 -292.179502)
		(end 399.17878 -292.032436)
		(width 0.20066)
		(layer "F.Cu")
		(net "M_E_CPU0_SA_DQ<22>")
	)
	(segment
		(start 388.730236 -270.657828)
		(end 392.659362 -274.586954)
		(width 0.1016)
		(layer "F.Cu")
		(net "M_E_CPU0_SA_DQ<22>")
	)
	(segment
		(start 405.748998 -291.241734)
		(end 405.927052 -291.241734)
		(width 0.101854)
		(layer "F.Cu")
		(net "M_E_CPU0_SA_DQ<22>")
	)
	(segment
		(start 384.58521 -268.81074)
		(end 384.71348 -268.588236)
		(width 0.088646)
		(layer "F.Cu")
		(net "M_E_CPU0_SA_DQ<22>")
	)
	(segment
		(start 408.091386 -291.2618)
		(end 408.327098 -291.026088)
		(width 0.20066)
		(layer "F.Cu")
		(net "M_E_CPU0_SA_DQ<22>")
	)
	(segment
		(start 393.771628 -286.43199)
		(end 393.805156 -286.465518)
		(width 0.1016)
		(layer "F.Cu")
		(net "M_E_CPU0_SA_DQ<22>")
	)
	(segment
		(start 402.800566 -292.447726)
		(end 403.084792 -292.447726)
		(width 0.20066)
		(layer "F.Cu")
		(net "M_E_CPU0_SA_DQ<22>")
	)
	(segment
		(start 403.607016 -290.913566)
		(end 403.607016 -290.739068)
		(width 0.20066)
		(layer "F.Cu")
		(net "M_E_CPU0_SA_DQ<22>")
	)
	(segment
		(start 418.397182 -290.816792)
		(end 417.07562 -290.816792)
		(width 0.20066)
		(layer "F.Cu")
		(net "M_E_CPU0_SA_DQ<22>")
	)
	(segment
		(start 408.886152 -290.383722)
		(end 409.019502 -290.517072)
		(width 0.20066)
		(layer "F.Cu")
		(net "M_E_CPU0_SA_DQ<22>")
	)
	(segment
		(start 392.659362 -274.586954)
		(end 393.771628 -280.148538)
		(width 0.1016)
		(layer "F.Cu")
		(net "M_E_CPU0_SA_DQ<22>")
	)
	(segment
		(start 393.771628 -280.148538)
		(end 393.771628 -286.43199)
		(width 0.1016)
		(layer "F.Cu")
		(net "M_E_CPU0_SA_DQ<22>")
	)
	(segment
		(start 412.842202 -291.2491)
		(end 412.177992 -290.58489)
		(width 0.20066)
		(layer "F.Cu")
		(net "M_E_CPU0_SA_DQ<22>")
	)
	(segment
		(start 416.205416 -291.052504)
		(end 416.004756 -291.253164)
		(width 0.20066)
		(layer "F.Cu")
		(net "M_E_CPU0_SA_DQ<22>")
	)
	(segment
		(start 403.360382 -291.1602)
		(end 403.607016 -290.913566)
		(width 0.20066)
		(layer "F.Cu")
		(net "M_E_CPU0_SA_DQ<22>")
	)
	(segment
		(start 409.019502 -290.517072)
		(end 409.019502 -290.689792)
		(width 0.20066)
		(layer "F.Cu")
		(net "M_E_CPU0_SA_DQ<22>")
	)
	(segment
		(start 399.17878 -292.032436)
		(end 402.385276 -292.032436)
		(width 0.20066)
		(layer "F.Cu")
		(net "M_E_CPU0_SA_DQ<22>")
	)
	(segment
		(start 410.073094 -290.458144)
		(end 410.431742 -290.816792)
		(width 0.20066)
		(layer "F.Cu")
		(net "M_E_CPU0_SA_DQ<22>")
	)
	(segment
		(start 413.293052 -291.2491)
		(end 413.275526 -291.2491)
		(width 0.101854)
		(layer "F.Cu")
		(net "M_E_CPU0_SA_DQ<22>")
	)
	(segment
		(start 384.71348 -268.588236)
		(end 384.84302 -268.553946)
		(width 0.088646)
		(layer "F.Cu")
		(net "M_E_CPU0_SA_DQ<22>")
	)
	(segment
		(start 407.763726 -291.2618)
		(end 408.091386 -291.2618)
		(width 0.20066)
		(layer "F.Cu")
		(net "M_E_CPU0_SA_DQ<22>")
	)
	(segment
		(start 416.004756 -291.253164)
		(end 415.307526 -291.253164)
		(width 0.20066)
		(layer "F.Cu")
		(net "M_E_CPU0_SA_DQ<22>")
	)
	(segment
		(start 385.72186 -268.523212)
		(end 385.781804 -268.557756)
		(width 0.088646)
		(layer "F.Cu")
		(net "M_E_CPU0_SA_DQ<22>")
	)
	(segment
		(start 393.805156 -286.465518)
		(end 393.805156 -287.338262)
		(width 0.1016)
		(layer "F.Cu")
		(net "M_E_CPU0_SA_DQ<22>")
	)
	(segment
		(start 402.385276 -292.032436)
		(end 402.800566 -292.447726)
		(width 0.20066)
		(layer "F.Cu")
		(net "M_E_CPU0_SA_DQ<22>")
	)
	(segment
		(start 415.307526 -291.253164)
		(end 415.296096 -291.241734)
		(width 0.101854)
		(layer "F.Cu")
		(net "M_E_CPU0_SA_DQ<22>")
	)
	(segment
		(start 405.731726 -291.259006)
		(end 405.748998 -291.241734)
		(width 0.101854)
		(layer "F.Cu")
		(net "M_E_CPU0_SA_DQ<22>")
	)
	(segment
		(start 393.920726 -287.453832)
		(end 398.646396 -292.179502)
		(width 0.20066)
		(layer "F.Cu")
		(net "M_E_CPU0_SA_DQ<22>")
	)
	(segment
		(start 415.296096 -291.241734)
		(end 414.498282 -291.241734)
		(width 0.101854)
		(layer "F.Cu")
		(net "M_E_CPU0_SA_DQ<22>")
	)
	(segment
		(start 411.38983 -290.816792)
		(end 410.853382 -290.816792)
		(width 0.20066)
		(layer "F.Cu")
		(net "M_E_CPU0_SA_DQ<22>")
	)
	(segment
		(start 403.807676 -290.538408)
		(end 404.474426 -290.538408)
		(width 0.20066)
		(layer "F.Cu")
		(net "M_E_CPU0_SA_DQ<22>")
	)
	(segment
		(start 408.327098 -290.549076)
		(end 408.492452 -290.383722)
		(width 0.20066)
		(layer "F.Cu")
		(net "M_E_CPU0_SA_DQ<22>")
	)
	(segment
		(start 393.805156 -287.338262)
		(end 393.920726 -287.453832)
		(width 0.1016)
		(layer "F.Cu")
		(net "M_E_CPU0_SA_DQ<22>")
	)
	(segment
		(start 417.07562 -290.816792)
		(end 416.823652 -290.564824)
		(width 0.20066)
		(layer "F.Cu")
		(net "M_E_CPU0_SA_DQ<22>")
	)
	(segment
		(start 409.019502 -290.689792)
		(end 409.146502 -290.816792)
		(width 0.20066)
		(layer "F.Cu")
		(net "M_E_CPU0_SA_DQ<22>")
	)
	(arc
		(start 384.84302 -268.553946)
		(mid 385.09887 -268.598111)
		(end 385.347464 -268.523212)
		(width 0.088646)
		(layer "F.Cu")
		(net "M_E_CPU0_SA_DQ<22>")
	)
	(arc
		(start 385.781804 -268.557756)
		(mid 385.882883 -268.599623)
		(end 385.991354 -268.61389)
		(width 0.088646)
		(layer "F.Cu")
		(net "M_E_CPU0_SA_DQ<22>")
	)
	(arc
		(start 385.347464 -268.523212)
		(mid 385.534662 -268.473069)
		(end 385.72186 -268.523212)
		(width 0.088646)
		(layer "F.Cu")
		(net "M_E_CPU0_SA_DQ<22>")
	)
	(segment
		(start 386.232146 -268.336522)
		(end 386.247894 -268.320774)
		(width 0.088646)
		(layer "F.Cu")
		(net "M_E_CPU0_SA_DQ<21>")
	)
	(segment
		(start 412.291784 -289.532568)
		(end 411.864048 -289.532568)
		(width 0.20066)
		(layer "F.Cu")
		(net "M_E_CPU0_SA_DQ<21>")
	)
	(segment
		(start 396.299944 -288.61004)
		(end 396.299944 -288.894012)
		(width 0.20066)
		(layer "F.Cu")
		(net "M_E_CPU0_SA_DQ<21>")
	)
	(segment
		(start 402.231606 -291.384228)
		(end 402.92401 -290.691824)
		(width 0.20066)
		(layer "F.Cu")
		(net "M_E_CPU0_SA_DQ<21>")
	)
	(segment
		(start 405.135842 -290.248594)
		(end 405.902414 -290.248594)
		(width 0.20066)
		(layer "F.Cu")
		(net "M_E_CPU0_SA_DQ<21>")
	)
	(segment
		(start 402.92401 -290.691824)
		(end 402.92401 -290.103306)
		(width 0.20066)
		(layer "F.Cu")
		(net "M_E_CPU0_SA_DQ<21>")
	)
	(segment
		(start 388.742682 -270.238982)
		(end 392.94054 -274.43684)
		(width 0.1016)
		(layer "F.Cu")
		(net "M_E_CPU0_SA_DQ<21>")
	)
	(segment
		(start 398.240504 -290.834572)
		(end 398.79016 -291.384228)
		(width 0.20066)
		(layer "F.Cu")
		(net "M_E_CPU0_SA_DQ<21>")
	)
	(segment
		(start 394.843 -285.901638)
		(end 394.843 -286.185864)
		(width 0.20066)
		(layer "F.Cu")
		(net "M_E_CPU0_SA_DQ<21>")
	)
	(segment
		(start 405.902414 -290.248594)
		(end 406.184354 -289.966654)
		(width 0.20066)
		(layer "F.Cu")
		(net "M_E_CPU0_SA_DQ<21>")
	)
	(segment
		(start 411.863794 -289.532822)
		(end 411.854904 -289.541712)
		(width 0.101854)
		(layer "F.Cu")
		(net "M_E_CPU0_SA_DQ<21>")
	)
	(segment
		(start 394.560552 -287.15462)
		(end 394.844524 -287.15462)
		(width 0.20066)
		(layer "F.Cu")
		(net "M_E_CPU0_SA_DQ<21>")
	)
	(segment
		(start 409.857956 -289.535108)
		(end 409.831794 -289.535108)
		(width 0.101854)
		(layer "F.Cu")
		(net "M_E_CPU0_SA_DQ<21>")
	)
	(segment
		(start 414.297114 -289.966654)
		(end 413.385762 -289.966654)
		(width 0.20066)
		(layer "F.Cu")
		(net "M_E_CPU0_SA_DQ<21>")
	)
	(segment
		(start 388.646924 -270.143224)
		(end 388.742682 -270.238982)
		(width 0.088646)
		(layer "F.Cu")
		(net "M_E_CPU0_SA_DQ<21>")
	)
	(segment
		(start 397.56461 -288.599626)
		(end 397.765778 -288.800794)
		(width 0.20066)
		(layer "F.Cu")
		(net "M_E_CPU0_SA_DQ<21>")
	)
	(segment
		(start 395.825218 -287.144206)
		(end 395.329664 -287.63976)
		(width 0.20066)
		(layer "F.Cu")
		(net "M_E_CPU0_SA_DQ<21>")
	)
	(segment
		(start 388.646924 -269.988792)
		(end 388.646924 -270.143224)
		(width 0.088646)
		(layer "F.Cu")
		(net "M_E_CPU0_SA_DQ<21>")
	)
	(segment
		(start 408.162252 -289.966654)
		(end 407.88463 -290.244276)
		(width 0.20066)
		(layer "F.Cu")
		(net "M_E_CPU0_SA_DQ<21>")
	)
	(segment
		(start 409.831794 -289.535108)
		(end 409.44673 -289.535108)
		(width 0.20066)
		(layer "F.Cu")
		(net "M_E_CPU0_SA_DQ<21>")
	)
	(segment
		(start 394.076428 -285.135066)
		(end 394.62964 -285.688278)
		(width 0.1016)
		(layer "F.Cu")
		(net "M_E_CPU0_SA_DQ<21>")
	)
	(segment
		(start 396.795498 -287.830514)
		(end 396.795498 -288.114486)
		(width 0.20066)
		(layer "F.Cu")
		(net "M_E_CPU0_SA_DQ<21>")
	)
	(segment
		(start 402.92401 -290.103306)
		(end 403.132036 -289.89528)
		(width 0.20066)
		(layer "F.Cu")
		(net "M_E_CPU0_SA_DQ<21>")
	)
	(segment
		(start 385.064762 -268.033754)
		(end 385.019804 -268.045692)
		(width 0.088646)
		(layer "F.Cu")
		(net "M_E_CPU0_SA_DQ<21>")
	)
	(segment
		(start 397.755364 -290.06546)
		(end 398.130268 -289.690556)
		(width 0.20066)
		(layer "F.Cu")
		(net "M_E_CPU0_SA_DQ<21>")
	)
	(segment
		(start 397.280638 -288.599626)
		(end 397.56461 -288.599626)
		(width 0.20066)
		(layer "F.Cu")
		(net "M_E_CPU0_SA_DQ<21>")
	)
	(segment
		(start 398.615408 -289.891724)
		(end 398.615408 -290.175696)
		(width 0.20066)
		(layer "F.Cu")
		(net "M_E_CPU0_SA_DQ<21>")
	)
	(segment
		(start 396.59433 -287.629346)
		(end 396.795498 -287.830514)
		(width 0.20066)
		(layer "F.Cu")
		(net "M_E_CPU0_SA_DQ<21>")
	)
	(segment
		(start 411.864048 -289.532568)
		(end 411.863794 -289.532822)
		(width 0.20066)
		(layer "F.Cu")
		(net "M_E_CPU0_SA_DQ<21>")
	)
	(segment
		(start 394.076428 -280.114502)
		(end 394.076428 -285.135066)
		(width 0.1016)
		(layer "F.Cu")
		(net "M_E_CPU0_SA_DQ<21>")
	)
	(segment
		(start 409.313126 -289.668712)
		(end 409.313126 -289.839654)
		(width 0.20066)
		(layer "F.Cu")
		(net "M_E_CPU0_SA_DQ<21>")
	)
	(segment
		(start 397.765778 -289.084766)
		(end 397.270224 -289.58032)
		(width 0.20066)
		(layer "F.Cu")
		(net "M_E_CPU0_SA_DQ<21>")
	)
	(segment
		(start 407.88463 -290.244276)
		(end 407.517092 -290.244276)
		(width 0.20066)
		(layer "F.Cu")
		(net "M_E_CPU0_SA_DQ<21>")
	)
	(segment
		(start 395.814804 -288.1249)
		(end 396.310358 -287.629346)
		(width 0.20066)
		(layer "F.Cu")
		(net "M_E_CPU0_SA_DQ<21>")
	)
	(segment
		(start 396.299944 -288.894012)
		(end 396.501112 -289.09518)
		(width 0.20066)
		(layer "F.Cu")
		(net "M_E_CPU0_SA_DQ<21>")
	)
	(segment
		(start 395.329664 -287.923732)
		(end 395.530832 -288.1249)
		(width 0.20066)
		(layer "F.Cu")
		(net "M_E_CPU0_SA_DQ<21>")
	)
	(segment
		(start 413.385762 -289.966654)
		(end 413.257492 -290.094924)
		(width 0.20066)
		(layer "F.Cu")
		(net "M_E_CPU0_SA_DQ<21>")
	)
	(segment
		(start 404.782528 -289.89528)
		(end 405.135842 -290.248594)
		(width 0.20066)
		(layer "F.Cu")
		(net "M_E_CPU0_SA_DQ<21>")
	)
	(segment
		(start 410.652214 -289.541712)
		(end 409.86456 -289.541712)
		(width 0.101854)
		(layer "F.Cu")
		(net "M_E_CPU0_SA_DQ<21>")
	)
	(segment
		(start 397.270224 -289.58032)
		(end 397.270224 -289.864292)
		(width 0.20066)
		(layer "F.Cu")
		(net "M_E_CPU0_SA_DQ<21>")
	)
	(segment
		(start 403.132036 -289.89528)
		(end 404.782528 -289.89528)
		(width 0.20066)
		(layer "F.Cu")
		(net "M_E_CPU0_SA_DQ<21>")
	)
	(segment
		(start 398.130268 -289.690556)
		(end 398.41424 -289.690556)
		(width 0.20066)
		(layer "F.Cu")
		(net "M_E_CPU0_SA_DQ<21>")
	)
	(segment
		(start 394.62964 -285.688278)
		(end 394.843 -285.901638)
		(width 0.20066)
		(layer "F.Cu")
		(net "M_E_CPU0_SA_DQ<21>")
	)
	(segment
		(start 409.313126 -289.839654)
		(end 409.186126 -289.966654)
		(width 0.20066)
		(layer "F.Cu")
		(net "M_E_CPU0_SA_DQ<21>")
	)
	(segment
		(start 398.79016 -291.384228)
		(end 402.231606 -291.384228)
		(width 0.20066)
		(layer "F.Cu")
		(net "M_E_CPU0_SA_DQ<21>")
	)
	(segment
		(start 406.184354 -289.966654)
		(end 406.753314 -289.966654)
		(width 0.20066)
		(layer "F.Cu")
		(net "M_E_CPU0_SA_DQ<21>")
	)
	(segment
		(start 398.240504 -290.5506)
		(end 398.240504 -290.834572)
		(width 0.20066)
		(layer "F.Cu")
		(net "M_E_CPU0_SA_DQ<21>")
	)
	(segment
		(start 413.257492 -290.094924)
		(end 412.85414 -290.094924)
		(width 0.20066)
		(layer "F.Cu")
		(net "M_E_CPU0_SA_DQ<21>")
	)
	(segment
		(start 397.765778 -288.800794)
		(end 397.765778 -289.084766)
		(width 0.20066)
		(layer "F.Cu")
		(net "M_E_CPU0_SA_DQ<21>")
	)
	(segment
		(start 395.340078 -286.659066)
		(end 395.62405 -286.659066)
		(width 0.20066)
		(layer "F.Cu")
		(net "M_E_CPU0_SA_DQ<21>")
	)
	(segment
		(start 395.530832 -288.1249)
		(end 395.814804 -288.1249)
		(width 0.20066)
		(layer "F.Cu")
		(net "M_E_CPU0_SA_DQ<21>")
	)
	(segment
		(start 396.795498 -288.114486)
		(end 396.299944 -288.61004)
		(width 0.20066)
		(layer "F.Cu")
		(net "M_E_CPU0_SA_DQ<21>")
	)
	(segment
		(start 396.310358 -287.629346)
		(end 396.59433 -287.629346)
		(width 0.20066)
		(layer "F.Cu")
		(net "M_E_CPU0_SA_DQ<21>")
	)
	(segment
		(start 409.86456 -289.541712)
		(end 409.857956 -289.535108)
		(width 0.101854)
		(layer "F.Cu")
		(net "M_E_CPU0_SA_DQ<21>")
	)
	(segment
		(start 411.854904 -289.541712)
		(end 410.652214 -289.541712)
		(width 0.1016)
		(layer "F.Cu")
		(net "M_E_CPU0_SA_DQ<21>")
	)
	(segment
		(start 407.23947 -289.966654)
		(end 406.753314 -289.966654)
		(width 0.20066)
		(layer "F.Cu")
		(net "M_E_CPU0_SA_DQ<21>")
	)
	(segment
		(start 385.019804 -268.045692)
		(end 384.897376 -268.258036)
		(width 0.088646)
		(layer "F.Cu")
		(net "M_E_CPU0_SA_DQ<21>")
	)
	(segment
		(start 396.501112 -289.09518)
		(end 396.785084 -289.09518)
		(width 0.20066)
		(layer "F.Cu")
		(net "M_E_CPU0_SA_DQ<21>")
	)
	(segment
		(start 409.186126 -289.966654)
		(end 408.162252 -289.966654)
		(width 0.20066)
		(layer "F.Cu")
		(net "M_E_CPU0_SA_DQ<21>")
	)
	(segment
		(start 394.359384 -286.66948)
		(end 394.359384 -286.953452)
		(width 0.20066)
		(layer "F.Cu")
		(net "M_E_CPU0_SA_DQ<21>")
	)
	(segment
		(start 388.613904 -269.90929)
		(end 388.646924 -269.988792)
		(width 0.088646)
		(layer "F.Cu")
		(net "M_E_CPU0_SA_DQ<21>")
	)
	(segment
		(start 392.94054 -274.43684)
		(end 394.076428 -280.114502)
		(width 0.1016)
		(layer "F.Cu")
		(net "M_E_CPU0_SA_DQ<21>")
	)
	(segment
		(start 398.41424 -289.690556)
		(end 398.615408 -289.891724)
		(width 0.20066)
		(layer "F.Cu")
		(net "M_E_CPU0_SA_DQ<21>")
	)
	(segment
		(start 394.843 -286.185864)
		(end 394.359384 -286.66948)
		(width 0.20066)
		(layer "F.Cu")
		(net "M_E_CPU0_SA_DQ<21>")
	)
	(segment
		(start 398.615408 -290.175696)
		(end 398.240504 -290.5506)
		(width 0.20066)
		(layer "F.Cu")
		(net "M_E_CPU0_SA_DQ<21>")
	)
	(segment
		(start 397.270224 -289.864292)
		(end 397.471392 -290.06546)
		(width 0.20066)
		(layer "F.Cu")
		(net "M_E_CPU0_SA_DQ<21>")
	)
	(segment
		(start 387.025388 -268.320774)
		(end 388.613904 -269.90929)
		(width 0.088646)
		(layer "F.Cu")
		(net "M_E_CPU0_SA_DQ<21>")
	)
	(segment
		(start 409.44673 -289.535108)
		(end 409.313126 -289.668712)
		(width 0.20066)
		(layer "F.Cu")
		(net "M_E_CPU0_SA_DQ<21>")
	)
	(segment
		(start 397.471392 -290.06546)
		(end 397.755364 -290.06546)
		(width 0.20066)
		(layer "F.Cu")
		(net "M_E_CPU0_SA_DQ<21>")
	)
	(segment
		(start 412.85414 -290.094924)
		(end 412.291784 -289.532568)
		(width 0.20066)
		(layer "F.Cu")
		(net "M_E_CPU0_SA_DQ<21>")
	)
	(segment
		(start 386.247894 -268.320774)
		(end 387.025388 -268.320774)
		(width 0.088646)
		(layer "F.Cu")
		(net "M_E_CPU0_SA_DQ<21>")
	)
	(segment
		(start 395.825218 -286.860234)
		(end 395.825218 -287.144206)
		(width 0.20066)
		(layer "F.Cu")
		(net "M_E_CPU0_SA_DQ<21>")
	)
	(segment
		(start 396.785084 -289.09518)
		(end 397.280638 -288.599626)
		(width 0.20066)
		(layer "F.Cu")
		(net "M_E_CPU0_SA_DQ<21>")
	)
	(segment
		(start 384.897376 -268.258036)
		(end 384.931412 -268.383512)
		(width 0.088646)
		(layer "F.Cu")
		(net "M_E_CPU0_SA_DQ<21>")
	)
	(segment
		(start 407.517092 -290.244276)
		(end 407.23947 -289.966654)
		(width 0.20066)
		(layer "F.Cu")
		(net "M_E_CPU0_SA_DQ<21>")
	)
	(segment
		(start 395.62405 -286.659066)
		(end 395.825218 -286.860234)
		(width 0.20066)
		(layer "F.Cu")
		(net "M_E_CPU0_SA_DQ<21>")
	)
	(segment
		(start 395.329664 -287.63976)
		(end 395.329664 -287.923732)
		(width 0.20066)
		(layer "F.Cu")
		(net "M_E_CPU0_SA_DQ<21>")
	)
	(segment
		(start 394.844524 -287.15462)
		(end 395.340078 -286.659066)
		(width 0.20066)
		(layer "F.Cu")
		(net "M_E_CPU0_SA_DQ<21>")
	)
	(segment
		(start 394.359384 -286.953452)
		(end 394.560552 -287.15462)
		(width 0.20066)
		(layer "F.Cu")
		(net "M_E_CPU0_SA_DQ<21>")
	)
	(arc
		(start 384.931412 -268.383512)
		(mid 385.094557 -268.406994)
		(end 385.25196 -268.358112)
		(width 0.088646)
		(layer "F.Cu")
		(net "M_E_CPU0_SA_DQ<21>")
	)
	(arc
		(start 385.25196 -268.358112)
		(mid 385.534662 -268.282336)
		(end 385.817364 -268.358112)
		(width 0.088646)
		(layer "F.Cu")
		(net "M_E_CPU0_SA_DQ<21>")
	)
	(arc
		(start 385.817364 -268.358112)
		(mid 386.02795 -268.408735)
		(end 386.232146 -268.336522)
		(width 0.088646)
		(layer "F.Cu")
		(net "M_E_CPU0_SA_DQ<21>")
	)
	(segment
		(start 386.57022 -268.701266)
		(end 386.867146 -268.701266)
		(width 0.088646)
		(layer "F.Cu")
		(net "M_E_CPU0_SA_DQ<20>")
	)
	(segment
		(start 398.685766 -293.123366)
		(end 398.969738 -293.123366)
		(width 0.20066)
		(layer "F.Cu")
		(net "M_E_CPU0_SA_DQ<20>")
	)
	(segment
		(start 403.92731 -292.487858)
		(end 403.999954 -292.312344)
		(width 0.20066)
		(layer "F.Cu")
		(net "M_E_CPU0_SA_DQ<20>")
	)
	(segment
		(start 401.012914 -294.099996)
		(end 401.341082 -294.099996)
		(width 0.20066)
		(layer "F.Cu")
		(net "M_E_CPU0_SA_DQ<20>")
	)
	(segment
		(start 399.452084 -293.89197)
		(end 399.652744 -294.09263)
		(width 0.20066)
		(layer "F.Cu")
		(net "M_E_CPU0_SA_DQ<20>")
	)
	(segment
		(start 401.341082 -294.099996)
		(end 401.597114 -294.356028)
		(width 0.20066)
		(layer "F.Cu")
		(net "M_E_CPU0_SA_DQ<20>")
	)
	(segment
		(start 409.134056 -291.927026)
		(end 408.84983 -291.927026)
		(width 0.20066)
		(layer "F.Cu")
		(net "M_E_CPU0_SA_DQ<20>")
	)
	(segment
		(start 399.652744 -294.09263)
		(end 400.063716 -294.09263)
		(width 0.20066)
		(layer "F.Cu")
		(net "M_E_CPU0_SA_DQ<20>")
	)
	(segment
		(start 412.180532 -291.235638)
		(end 411.865826 -291.235638)
		(width 0.20066)
		(layer "F.Cu")
		(net "M_E_CPU0_SA_DQ<20>")
	)
	(segment
		(start 402.169122 -293.40683)
		(end 399.652744 -293.40683)
		(width 0.20066)
		(layer "F.Cu")
		(net "M_E_CPU0_SA_DQ<20>")
	)
	(segment
		(start 401.597114 -294.356028)
		(end 401.835112 -294.356028)
		(width 0.20066)
		(layer "F.Cu")
		(net "M_E_CPU0_SA_DQ<20>")
	)
	(segment
		(start 404.810722 -291.666676)
		(end 406.753314 -291.666676)
		(width 0.20066)
		(layer "F.Cu")
		(net "M_E_CPU0_SA_DQ<20>")
	)
	(segment
		(start 403.67077 -292.871652)
		(end 403.92731 -292.487858)
		(width 0.20066)
		(layer "F.Cu")
		(net "M_E_CPU0_SA_DQ<20>")
	)
	(segment
		(start 400.063716 -294.09263)
		(end 400.327114 -294.356028)
		(width 0.20066)
		(layer "F.Cu")
		(net "M_E_CPU0_SA_DQ<20>")
	)
	(segment
		(start 414.297114 -291.666676)
		(end 412.61157 -291.666676)
		(width 0.20066)
		(layer "F.Cu")
		(net "M_E_CPU0_SA_DQ<20>")
	)
	(segment
		(start 412.61157 -291.666676)
		(end 412.180532 -291.235638)
		(width 0.20066)
		(layer "F.Cu")
		(net "M_E_CPU0_SA_DQ<20>")
	)
	(segment
		(start 404.525988 -291.548566)
		(end 404.810722 -291.666676)
		(width 0.20066)
		(layer "F.Cu")
		(net "M_E_CPU0_SA_DQ<20>")
	)
	(segment
		(start 401.835112 -294.356028)
		(end 402.21154 -294.200326)
		(width 0.20066)
		(layer "F.Cu")
		(net "M_E_CPU0_SA_DQ<20>")
	)
	(segment
		(start 392.378438 -274.737322)
		(end 393.466828 -280.183844)
		(width 0.1016)
		(layer "F.Cu")
		(net "M_E_CPU0_SA_DQ<20>")
	)
	(segment
		(start 386.867146 -268.701266)
		(end 388.250684 -270.086074)
		(width 0.088646)
		(layer "F.Cu")
		(net "M_E_CPU0_SA_DQ<20>")
	)
	(segment
		(start 398.969738 -293.123366)
		(end 399.372074 -292.72103)
		(width 0.20066)
		(layer "F.Cu")
		(net "M_E_CPU0_SA_DQ<20>")
	)
	(segment
		(start 409.447492 -291.233606)
		(end 409.297124 -291.383974)
		(width 0.20066)
		(layer "F.Cu")
		(net "M_E_CPU0_SA_DQ<20>")
	)
	(segment
		(start 393.466828 -287.904428)
		(end 393.615926 -288.053526)
		(width 0.1016)
		(layer "F.Cu")
		(net "M_E_CPU0_SA_DQ<20>")
	)
	(segment
		(start 409.297124 -291.763958)
		(end 409.134056 -291.927026)
		(width 0.20066)
		(layer "F.Cu")
		(net "M_E_CPU0_SA_DQ<20>")
	)
	(segment
		(start 399.452084 -293.60749)
		(end 399.452084 -293.89197)
		(width 0.20066)
		(layer "F.Cu")
		(net "M_E_CPU0_SA_DQ<20>")
	)
	(segment
		(start 402.369782 -292.92169)
		(end 402.369782 -293.20617)
		(width 0.20066)
		(layer "F.Cu")
		(net "M_E_CPU0_SA_DQ<20>")
	)
	(segment
		(start 403.999954 -292.312344)
		(end 403.999954 -291.891212)
		(width 0.20066)
		(layer "F.Cu")
		(net "M_E_CPU0_SA_DQ<20>")
	)
	(segment
		(start 388.250684 -270.611092)
		(end 388.513828 -270.874236)
		(width 0.088646)
		(layer "F.Cu")
		(net "M_E_CPU0_SA_DQ<20>")
	)
	(segment
		(start 410.652214 -291.241734)
		(end 409.870656 -291.241734)
		(width 0.101854)
		(layer "F.Cu")
		(net "M_E_CPU0_SA_DQ<20>")
	)
	(segment
		(start 409.297124 -291.383974)
		(end 409.297124 -291.763958)
		(width 0.20066)
		(layer "F.Cu")
		(net "M_E_CPU0_SA_DQ<20>")
	)
	(segment
		(start 402.604986 -293.937436)
		(end 403.67077 -292.871652)
		(width 0.20066)
		(layer "F.Cu")
		(net "M_E_CPU0_SA_DQ<20>")
	)
	(segment
		(start 399.372074 -292.72103)
		(end 402.169122 -292.72103)
		(width 0.20066)
		(layer "F.Cu")
		(net "M_E_CPU0_SA_DQ<20>")
	)
	(segment
		(start 386.474716 -268.79677)
		(end 386.57022 -268.701266)
		(width 0.088646)
		(layer "F.Cu")
		(net "M_E_CPU0_SA_DQ<20>")
	)
	(segment
		(start 408.58948 -291.666676)
		(end 406.753314 -291.666676)
		(width 0.20066)
		(layer "F.Cu")
		(net "M_E_CPU0_SA_DQ<20>")
	)
	(segment
		(start 409.831794 -291.233606)
		(end 409.447492 -291.233606)
		(width 0.20066)
		(layer "F.Cu")
		(net "M_E_CPU0_SA_DQ<20>")
	)
	(segment
		(start 408.84983 -291.927026)
		(end 408.58948 -291.666676)
		(width 0.20066)
		(layer "F.Cu")
		(net "M_E_CPU0_SA_DQ<20>")
	)
	(segment
		(start 411.85973 -291.241734)
		(end 410.652214 -291.241734)
		(width 0.1016)
		(layer "F.Cu")
		(net "M_E_CPU0_SA_DQ<20>")
	)
	(segment
		(start 411.863794 -291.23767)
		(end 411.85973 -291.241734)
		(width 0.101854)
		(layer "F.Cu")
		(net "M_E_CPU0_SA_DQ<20>")
	)
	(segment
		(start 411.865826 -291.235638)
		(end 411.863794 -291.23767)
		(width 0.20066)
		(layer "F.Cu")
		(net "M_E_CPU0_SA_DQ<20>")
	)
	(segment
		(start 388.513828 -270.874236)
		(end 392.378438 -274.737322)
		(width 0.1016)
		(layer "F.Cu")
		(net "M_E_CPU0_SA_DQ<20>")
	)
	(segment
		(start 404.3426 -291.548566)
		(end 404.525988 -291.548566)
		(width 0.20066)
		(layer "F.Cu")
		(net "M_E_CPU0_SA_DQ<20>")
	)
	(segment
		(start 400.327114 -294.356028)
		(end 400.756882 -294.356028)
		(width 0.20066)
		(layer "F.Cu")
		(net "M_E_CPU0_SA_DQ<20>")
	)
	(segment
		(start 402.169122 -292.72103)
		(end 402.369782 -292.92169)
		(width 0.20066)
		(layer "F.Cu")
		(net "M_E_CPU0_SA_DQ<20>")
	)
	(segment
		(start 393.466828 -280.183844)
		(end 393.466828 -287.904428)
		(width 0.1016)
		(layer "F.Cu")
		(net "M_E_CPU0_SA_DQ<20>")
	)
	(segment
		(start 409.870656 -291.241734)
		(end 409.862528 -291.233606)
		(width 0.101854)
		(layer "F.Cu")
		(net "M_E_CPU0_SA_DQ<20>")
	)
	(segment
		(start 402.369782 -293.20617)
		(end 402.169122 -293.40683)
		(width 0.20066)
		(layer "F.Cu")
		(net "M_E_CPU0_SA_DQ<20>")
	)
	(segment
		(start 388.250684 -270.086074)
		(end 388.250684 -270.611092)
		(width 0.088646)
		(layer "F.Cu")
		(net "M_E_CPU0_SA_DQ<20>")
	)
	(segment
		(start 400.756882 -294.356028)
		(end 401.012914 -294.099996)
		(width 0.20066)
		(layer "F.Cu")
		(net "M_E_CPU0_SA_DQ<20>")
	)
	(segment
		(start 386.474716 -268.84757)
		(end 386.474716 -268.79677)
		(width 0.088646)
		(layer "F.Cu")
		(net "M_E_CPU0_SA_DQ<20>")
	)
	(segment
		(start 409.862528 -291.233606)
		(end 409.831794 -291.233606)
		(width 0.101854)
		(layer "F.Cu")
		(net "M_E_CPU0_SA_DQ<20>")
	)
	(segment
		(start 399.652744 -293.40683)
		(end 399.452084 -293.60749)
		(width 0.20066)
		(layer "F.Cu")
		(net "M_E_CPU0_SA_DQ<20>")
	)
	(segment
		(start 403.999954 -291.891212)
		(end 404.3426 -291.548566)
		(width 0.20066)
		(layer "F.Cu")
		(net "M_E_CPU0_SA_DQ<20>")
	)
	(segment
		(start 402.21154 -294.200326)
		(end 402.604986 -293.937436)
		(width 0.20066)
		(layer "F.Cu")
		(net "M_E_CPU0_SA_DQ<20>")
	)
	(segment
		(start 393.615926 -288.053526)
		(end 398.685766 -293.123366)
		(width 0.20066)
		(layer "F.Cu")
		(net "M_E_CPU0_SA_DQ<20>")
	)
	(segment
		(start 388.064502 -298.512992)
		(end 389.361172 -299.809662)
		(width 0.20066)
		(layer "F.Cu")
		(net "M_E_CPU0_SA_DQ<1>")
	)
	(segment
		(start 412.14929 -314.181744)
		(end 411.863794 -314.181744)
		(width 0.20066)
		(layer "F.Cu")
		(net "M_E_CPU0_SA_DQ<1>")
	)
	(segment
		(start 387.015736 -279.169368)
		(end 387.284722 -279.438354)
		(width 0.088646)
		(layer "F.Cu")
		(net "M_E_CPU0_SA_DQ<1>")
	)
	(segment
		(start 389.361172 -300.139354)
		(end 389.681466 -300.459648)
		(width 0.20066)
		(layer "F.Cu")
		(net "M_E_CPU0_SA_DQ<1>")
	)
	(segment
		(start 397.773398 -308.221888)
		(end 398.093692 -308.542182)
		(width 0.20066)
		(layer "F.Cu")
		(net "M_E_CPU0_SA_DQ<1>")
	)
	(segment
		(start 396.153132 -306.931314)
		(end 396.473426 -307.251608)
		(width 0.20066)
		(layer "F.Cu")
		(net "M_E_CPU0_SA_DQ<1>")
	)
	(segment
		(start 398.093692 -308.542182)
		(end 398.093692 -308.871874)
		(width 0.20066)
		(layer "F.Cu")
		(net "M_E_CPU0_SA_DQ<1>")
	)
	(segment
		(start 405.539448 -315.002164)
		(end 405.92502 -314.616592)
		(width 0.20066)
		(layer "F.Cu")
		(net "M_E_CPU0_SA_DQ<1>")
	)
	(segment
		(start 390.651746 -301.429928)
		(end 390.981438 -301.429928)
		(width 0.20066)
		(layer "F.Cu")
		(net "M_E_CPU0_SA_DQ<1>")
	)
	(segment
		(start 399.063972 -309.805578)
		(end 399.420842 -310.162448)
		(width 0.20066)
		(layer "F.Cu")
		(net "M_E_CPU0_SA_DQ<1>")
	)
	(segment
		(start 395.182852 -305.961034)
		(end 395.503146 -306.281328)
		(width 0.20066)
		(layer "F.Cu")
		(net "M_E_CPU0_SA_DQ<1>")
	)
	(segment
		(start 398.743678 -309.192168)
		(end 399.063972 -309.512462)
		(width 0.20066)
		(layer "F.Cu")
		(net "M_E_CPU0_SA_DQ<1>")
	)
	(segment
		(start 405.92502 -314.616592)
		(end 406.753314 -314.616592)
		(width 0.20066)
		(layer "F.Cu")
		(net "M_E_CPU0_SA_DQ<1>")
	)
	(segment
		(start 396.473426 -307.251608)
		(end 396.803118 -307.251608)
		(width 0.20066)
		(layer "F.Cu")
		(net "M_E_CPU0_SA_DQ<1>")
	)
	(segment
		(start 392.921998 -303.370488)
		(end 393.242292 -303.690782)
		(width 0.20066)
		(layer "F.Cu")
		(net "M_E_CPU0_SA_DQ<1>")
	)
	(segment
		(start 404.543768 -314.718954)
		(end 405.128476 -314.961016)
		(width 0.20066)
		(layer "F.Cu")
		(net "M_E_CPU0_SA_DQ<1>")
	)
	(segment
		(start 385.72186 -278.938736)
		(end 385.732274 -278.93264)
		(width 0.088646)
		(layer "F.Cu")
		(net "M_E_CPU0_SA_DQ<1>")
	)
	(segment
		(start 405.128476 -314.961016)
		(end 405.227536 -315.002164)
		(width 0.20066)
		(layer "F.Cu")
		(net "M_E_CPU0_SA_DQ<1>")
	)
	(segment
		(start 407.960576 -314.95238)
		(end 407.624788 -314.616592)
		(width 0.20066)
		(layer "F.Cu")
		(net "M_E_CPU0_SA_DQ<1>")
	)
	(segment
		(start 402.350478 -313.073288)
		(end 402.624798 -313.073288)
		(width 0.20066)
		(layer "F.Cu")
		(net "M_E_CPU0_SA_DQ<1>")
	)
	(segment
		(start 388.064502 -296.848022)
		(end 388.064502 -297.327828)
		(width 0.1016)
		(layer "F.Cu")
		(net "M_E_CPU0_SA_DQ<1>")
	)
	(segment
		(start 409.185872 -314.38342)
		(end 409.185872 -314.751466)
		(width 0.20066)
		(layer "F.Cu")
		(net "M_E_CPU0_SA_DQ<1>")
	)
	(segment
		(start 401.974812 -312.697622)
		(end 402.350478 -313.073288)
		(width 0.20066)
		(layer "F.Cu")
		(net "M_E_CPU0_SA_DQ<1>")
	)
	(segment
		(start 400.435318 -311.132728)
		(end 400.684238 -311.132728)
		(width 0.20066)
		(layer "F.Cu")
		(net "M_E_CPU0_SA_DQ<1>")
	)
	(segment
		(start 412.584138 -314.616592)
		(end 412.14929 -314.181744)
		(width 0.20066)
		(layer "F.Cu")
		(net "M_E_CPU0_SA_DQ<1>")
	)
	(segment
		(start 399.420842 -310.162448)
		(end 399.713958 -310.162448)
		(width 0.20066)
		(layer "F.Cu")
		(net "M_E_CPU0_SA_DQ<1>")
	)
	(segment
		(start 389.681466 -300.459648)
		(end 390.011158 -300.459648)
		(width 0.20066)
		(layer "F.Cu")
		(net "M_E_CPU0_SA_DQ<1>")
	)
	(segment
		(start 395.182852 -305.631342)
		(end 395.182852 -305.961034)
		(width 0.20066)
		(layer "F.Cu")
		(net "M_E_CPU0_SA_DQ<1>")
	)
	(segment
		(start 387.284722 -279.438354)
		(end 387.577584 -280.144982)
		(width 0.088646)
		(layer "F.Cu")
		(net "M_E_CPU0_SA_DQ<1>")
	)
	(segment
		(start 408.984958 -314.95238)
		(end 407.960576 -314.95238)
		(width 0.20066)
		(layer "F.Cu")
		(net "M_E_CPU0_SA_DQ<1>")
	)
	(segment
		(start 409.831794 -314.18276)
		(end 409.386532 -314.18276)
		(width 0.20066)
		(layer "F.Cu")
		(net "M_E_CPU0_SA_DQ<1>")
	)
	(segment
		(start 393.242292 -304.020474)
		(end 393.562586 -304.340768)
		(width 0.20066)
		(layer "F.Cu")
		(net "M_E_CPU0_SA_DQ<1>")
	)
	(segment
		(start 400.034252 -310.731662)
		(end 400.435318 -311.132728)
		(width 0.20066)
		(layer "F.Cu")
		(net "M_E_CPU0_SA_DQ<1>")
	)
	(segment
		(start 395.503146 -306.281328)
		(end 395.832838 -306.281328)
		(width 0.20066)
		(layer "F.Cu")
		(net "M_E_CPU0_SA_DQ<1>")
	)
	(segment
		(start 387.676644 -280.642568)
		(end 387.676644 -281.063446)
		(width 0.088646)
		(layer "F.Cu")
		(net "M_E_CPU0_SA_DQ<1>")
	)
	(segment
		(start 386.67563 -279.028398)
		(end 387.015736 -279.169368)
		(width 0.088646)
		(layer "F.Cu")
		(net "M_E_CPU0_SA_DQ<1>")
	)
	(segment
		(start 396.803118 -307.251608)
		(end 397.123412 -307.571902)
		(width 0.20066)
		(layer "F.Cu")
		(net "M_E_CPU0_SA_DQ<1>")
	)
	(segment
		(start 393.562586 -304.340768)
		(end 393.892278 -304.340768)
		(width 0.20066)
		(layer "F.Cu")
		(net "M_E_CPU0_SA_DQ<1>")
	)
	(segment
		(start 399.063972 -309.512462)
		(end 399.063972 -309.805578)
		(width 0.20066)
		(layer "F.Cu")
		(net "M_E_CPU0_SA_DQ<1>")
	)
	(segment
		(start 390.981438 -301.429928)
		(end 391.301732 -301.750222)
		(width 0.20066)
		(layer "F.Cu")
		(net "M_E_CPU0_SA_DQ<1>")
	)
	(segment
		(start 400.034252 -310.482742)
		(end 400.034252 -310.731662)
		(width 0.20066)
		(layer "F.Cu")
		(net "M_E_CPU0_SA_DQ<1>")
	)
	(segment
		(start 394.532866 -305.311048)
		(end 394.862558 -305.311048)
		(width 0.20066)
		(layer "F.Cu")
		(net "M_E_CPU0_SA_DQ<1>")
	)
	(segment
		(start 392.272012 -303.050194)
		(end 392.592306 -303.370488)
		(width 0.20066)
		(layer "F.Cu")
		(net "M_E_CPU0_SA_DQ<1>")
	)
	(segment
		(start 386.492242 -279.028398)
		(end 386.67563 -279.028398)
		(width 0.088646)
		(layer "F.Cu")
		(net "M_E_CPU0_SA_DQ<1>")
	)
	(segment
		(start 399.713958 -310.162448)
		(end 400.034252 -310.482742)
		(width 0.20066)
		(layer "F.Cu")
		(net "M_E_CPU0_SA_DQ<1>")
	)
	(segment
		(start 403.720046 -314.168536)
		(end 404.543768 -314.718954)
		(width 0.20066)
		(layer "F.Cu")
		(net "M_E_CPU0_SA_DQ<1>")
	)
	(segment
		(start 386.287518 -278.938736)
		(end 386.2959 -278.947118)
		(width 0.088646)
		(layer "F.Cu")
		(net "M_E_CPU0_SA_DQ<1>")
	)
	(segment
		(start 388.064502 -297.327828)
		(end 388.064502 -298.512992)
		(width 0.20066)
		(layer "F.Cu")
		(net "M_E_CPU0_SA_DQ<1>")
	)
	(segment
		(start 389.361172 -299.809662)
		(end 389.361172 -300.139354)
		(width 0.20066)
		(layer "F.Cu")
		(net "M_E_CPU0_SA_DQ<1>")
	)
	(segment
		(start 407.624788 -314.616592)
		(end 406.753314 -314.616592)
		(width 0.20066)
		(layer "F.Cu")
		(net "M_E_CPU0_SA_DQ<1>")
	)
	(segment
		(start 394.212572 -304.661062)
		(end 394.212572 -304.990754)
		(width 0.20066)
		(layer "F.Cu")
		(net "M_E_CPU0_SA_DQ<1>")
	)
	(segment
		(start 393.242292 -303.690782)
		(end 393.242292 -304.020474)
		(width 0.20066)
		(layer "F.Cu")
		(net "M_E_CPU0_SA_DQ<1>")
	)
	(segment
		(start 391.622026 -302.400208)
		(end 391.951718 -302.400208)
		(width 0.20066)
		(layer "F.Cu")
		(net "M_E_CPU0_SA_DQ<1>")
	)
	(segment
		(start 401.416774 -312.103008)
		(end 401.654518 -312.103008)
		(width 0.20066)
		(layer "F.Cu")
		(net "M_E_CPU0_SA_DQ<1>")
	)
	(segment
		(start 390.011158 -300.459648)
		(end 390.331452 -300.779942)
		(width 0.20066)
		(layer "F.Cu")
		(net "M_E_CPU0_SA_DQ<1>")
	)
	(segment
		(start 387.676644 -281.063446)
		(end 387.676644 -296.460164)
		(width 0.1016)
		(layer "F.Cu")
		(net "M_E_CPU0_SA_DQ<1>")
	)
	(segment
		(start 414.297114 -314.616592)
		(end 412.584138 -314.616592)
		(width 0.20066)
		(layer "F.Cu")
		(net "M_E_CPU0_SA_DQ<1>")
	)
	(segment
		(start 393.892278 -304.340768)
		(end 394.212572 -304.661062)
		(width 0.20066)
		(layer "F.Cu")
		(net "M_E_CPU0_SA_DQ<1>")
	)
	(segment
		(start 409.185872 -314.751466)
		(end 408.984958 -314.95238)
		(width 0.20066)
		(layer "F.Cu")
		(net "M_E_CPU0_SA_DQ<1>")
	)
	(segment
		(start 409.84551 -314.19165)
		(end 409.83662 -314.18276)
		(width 0.1016)
		(layer "F.Cu")
		(net "M_E_CPU0_SA_DQ<1>")
	)
	(segment
		(start 391.301732 -301.750222)
		(end 391.301732 -302.079914)
		(width 0.20066)
		(layer "F.Cu")
		(net "M_E_CPU0_SA_DQ<1>")
	)
	(segment
		(start 394.862558 -305.311048)
		(end 395.182852 -305.631342)
		(width 0.20066)
		(layer "F.Cu")
		(net "M_E_CPU0_SA_DQ<1>")
	)
	(segment
		(start 398.093692 -308.871874)
		(end 398.413986 -309.192168)
		(width 0.20066)
		(layer "F.Cu")
		(net "M_E_CPU0_SA_DQ<1>")
	)
	(segment
		(start 392.592306 -303.370488)
		(end 392.921998 -303.370488)
		(width 0.20066)
		(layer "F.Cu")
		(net "M_E_CPU0_SA_DQ<1>")
	)
	(segment
		(start 405.227536 -315.002164)
		(end 405.539448 -315.002164)
		(width 0.20066)
		(layer "F.Cu")
		(net "M_E_CPU0_SA_DQ<1>")
	)
	(segment
		(start 387.676644 -296.460164)
		(end 388.064502 -296.848022)
		(width 0.1016)
		(layer "F.Cu")
		(net "M_E_CPU0_SA_DQ<1>")
	)
	(segment
		(start 390.331452 -300.779942)
		(end 390.331452 -301.109634)
		(width 0.20066)
		(layer "F.Cu")
		(net "M_E_CPU0_SA_DQ<1>")
	)
	(segment
		(start 396.153132 -306.601622)
		(end 396.153132 -306.931314)
		(width 0.20066)
		(layer "F.Cu")
		(net "M_E_CPU0_SA_DQ<1>")
	)
	(segment
		(start 397.443706 -308.221888)
		(end 397.773398 -308.221888)
		(width 0.20066)
		(layer "F.Cu")
		(net "M_E_CPU0_SA_DQ<1>")
	)
	(segment
		(start 391.301732 -302.079914)
		(end 391.622026 -302.400208)
		(width 0.20066)
		(layer "F.Cu")
		(net "M_E_CPU0_SA_DQ<1>")
	)
	(segment
		(start 387.577584 -280.144982)
		(end 387.676644 -280.642568)
		(width 0.088646)
		(layer "F.Cu")
		(net "M_E_CPU0_SA_DQ<1>")
	)
	(segment
		(start 402.624798 -313.073288)
		(end 403.720046 -314.168536)
		(width 0.20066)
		(layer "F.Cu")
		(net "M_E_CPU0_SA_DQ<1>")
	)
	(segment
		(start 397.123412 -307.571902)
		(end 397.123412 -307.901594)
		(width 0.20066)
		(layer "F.Cu")
		(net "M_E_CPU0_SA_DQ<1>")
	)
	(segment
		(start 391.951718 -302.400208)
		(end 392.272012 -302.720502)
		(width 0.20066)
		(layer "F.Cu")
		(net "M_E_CPU0_SA_DQ<1>")
	)
	(segment
		(start 401.004532 -311.453022)
		(end 401.004532 -311.690766)
		(width 0.20066)
		(layer "F.Cu")
		(net "M_E_CPU0_SA_DQ<1>")
	)
	(segment
		(start 398.413986 -309.192168)
		(end 398.743678 -309.192168)
		(width 0.20066)
		(layer "F.Cu")
		(net "M_E_CPU0_SA_DQ<1>")
	)
	(segment
		(start 385.064762 -277.800562)
		(end 385.160266 -278.031194)
		(width 0.088646)
		(layer "F.Cu")
		(net "M_E_CPU0_SA_DQ<1>")
	)
	(segment
		(start 395.832838 -306.281328)
		(end 396.153132 -306.601622)
		(width 0.20066)
		(layer "F.Cu")
		(net "M_E_CPU0_SA_DQ<1>")
	)
	(segment
		(start 386.2959 -278.947118)
		(end 386.492242 -279.028398)
		(width 0.088646)
		(layer "F.Cu")
		(net "M_E_CPU0_SA_DQ<1>")
	)
	(segment
		(start 411.863794 -314.181744)
		(end 411.853888 -314.19165)
		(width 0.1016)
		(layer "F.Cu")
		(net "M_E_CPU0_SA_DQ<1>")
	)
	(segment
		(start 411.853888 -314.19165)
		(end 409.84551 -314.19165)
		(width 0.1016)
		(layer "F.Cu")
		(net "M_E_CPU0_SA_DQ<1>")
	)
	(segment
		(start 401.654518 -312.103008)
		(end 401.974812 -312.423302)
		(width 0.20066)
		(layer "F.Cu")
		(net "M_E_CPU0_SA_DQ<1>")
	)
	(segment
		(start 409.386532 -314.18276)
		(end 409.185872 -314.38342)
		(width 0.20066)
		(layer "F.Cu")
		(net "M_E_CPU0_SA_DQ<1>")
	)
	(segment
		(start 394.212572 -304.990754)
		(end 394.532866 -305.311048)
		(width 0.20066)
		(layer "F.Cu")
		(net "M_E_CPU0_SA_DQ<1>")
	)
	(segment
		(start 392.272012 -302.720502)
		(end 392.272012 -303.050194)
		(width 0.20066)
		(layer "F.Cu")
		(net "M_E_CPU0_SA_DQ<1>")
	)
	(segment
		(start 390.331452 -301.109634)
		(end 390.651746 -301.429928)
		(width 0.20066)
		(layer "F.Cu")
		(net "M_E_CPU0_SA_DQ<1>")
	)
	(segment
		(start 385.160266 -278.031194)
		(end 385.160266 -278.623014)
		(width 0.088646)
		(layer "F.Cu")
		(net "M_E_CPU0_SA_DQ<1>")
	)
	(segment
		(start 401.004532 -311.690766)
		(end 401.416774 -312.103008)
		(width 0.20066)
		(layer "F.Cu")
		(net "M_E_CPU0_SA_DQ<1>")
	)
	(segment
		(start 397.123412 -307.901594)
		(end 397.443706 -308.221888)
		(width 0.20066)
		(layer "F.Cu")
		(net "M_E_CPU0_SA_DQ<1>")
	)
	(segment
		(start 409.83662 -314.18276)
		(end 409.831794 -314.18276)
		(width 0.101854)
		(layer "F.Cu")
		(net "M_E_CPU0_SA_DQ<1>")
	)
	(segment
		(start 401.974812 -312.423302)
		(end 401.974812 -312.697622)
		(width 0.20066)
		(layer "F.Cu")
		(net "M_E_CPU0_SA_DQ<1>")
	)
	(segment
		(start 400.684238 -311.132728)
		(end 401.004532 -311.453022)
		(width 0.20066)
		(layer "F.Cu")
		(net "M_E_CPU0_SA_DQ<1>")
	)
	(arc
		(start 385.160266 -278.623014)
		(mid 385.212536 -278.805379)
		(end 385.347464 -278.938736)
		(width 0.088646)
		(layer "F.Cu")
		(net "M_E_CPU0_SA_DQ<1>")
	)
	(arc
		(start 385.347464 -278.938736)
		(mid 385.534662 -278.988879)
		(end 385.72186 -278.938736)
		(width 0.088646)
		(layer "F.Cu")
		(net "M_E_CPU0_SA_DQ<1>")
	)
	(arc
		(start 385.732274 -278.93264)
		(mid 386.010706 -278.862794)
		(end 386.287518 -278.938736)
		(width 0.088646)
		(layer "F.Cu")
		(net "M_E_CPU0_SA_DQ<1>")
	)
	(segment
		(start 416.420554 -294.75049)
		(end 416.205416 -294.965628)
		(width 0.20066)
		(layer "F.Cu")
		(net "M_E_CPU0_SA_DQ<19>")
	)
	(segment
		(start 413.293052 -295.499028)
		(end 413.275526 -295.499028)
		(width 0.101854)
		(layer "F.Cu")
		(net "M_E_CPU0_SA_DQ<19>")
	)
	(segment
		(start 391.939018 -289.491928)
		(end 392.327892 -290.430712)
		(width 0.1016)
		(layer "F.Cu")
		(net "M_E_CPU0_SA_DQ<19>")
	)
	(segment
		(start 405.66594 -295.59631)
		(end 405.731726 -295.530524)
		(width 0.20066)
		(layer "F.Cu")
		(net "M_E_CPU0_SA_DQ<19>")
	)
	(segment
		(start 400.223228 -298.326048)
		(end 401.049236 -298.326048)
		(width 0.20066)
		(layer "F.Cu")
		(net "M_E_CPU0_SA_DQ<19>")
	)
	(segment
		(start 386.474716 -270.475456)
		(end 386.526532 -270.475456)
		(width 0.088646)
		(layer "F.Cu")
		(net "M_E_CPU0_SA_DQ<19>")
	)
	(segment
		(start 401.249896 -298.125388)
		(end 401.249896 -297.840908)
		(width 0.20066)
		(layer "F.Cu")
		(net "M_E_CPU0_SA_DQ<19>")
	)
	(segment
		(start 412.842202 -295.499028)
		(end 412.409894 -295.06672)
		(width 0.20066)
		(layer "F.Cu")
		(net "M_E_CPU0_SA_DQ<19>")
	)
	(segment
		(start 400.557238 -297.640248)
		(end 400.356578 -297.439588)
		(width 0.20066)
		(layer "F.Cu")
		(net "M_E_CPU0_SA_DQ<19>")
	)
	(segment
		(start 413.300418 -295.491662)
		(end 413.293052 -295.499028)
		(width 0.1016)
		(layer "F.Cu")
		(net "M_E_CPU0_SA_DQ<19>")
	)
	(segment
		(start 390.955022 -275.477478)
		(end 391.939018 -280.403046)
		(width 0.1016)
		(layer "F.Cu")
		(net "M_E_CPU0_SA_DQ<19>")
	)
	(segment
		(start 392.327892 -290.430712)
		(end 393.050776 -291.153596)
		(width 0.1016)
		(layer "F.Cu")
		(net "M_E_CPU0_SA_DQ<19>")
	)
	(segment
		(start 386.956046 -271.307306)
		(end 387.266942 -271.618202)
		(width 0.088646)
		(layer "F.Cu")
		(net "M_E_CPU0_SA_DQ<19>")
	)
	(segment
		(start 408.610816 -295.06672)
		(end 410.853382 -295.06672)
		(width 0.20066)
		(layer "F.Cu")
		(net "M_E_CPU0_SA_DQ<19>")
	)
	(segment
		(start 417.07562 -295.06672)
		(end 416.75939 -294.75049)
		(width 0.20066)
		(layer "F.Cu")
		(net "M_E_CPU0_SA_DQ<19>")
	)
	(segment
		(start 386.880862 -271.014444)
		(end 386.857748 -271.070324)
		(width 0.088646)
		(layer "F.Cu")
		(net "M_E_CPU0_SA_DQ<19>")
	)
	(segment
		(start 387.319012 -271.841468)
		(end 389.261604 -273.78406)
		(width 0.088646)
		(layer "F.Cu")
		(net "M_E_CPU0_SA_DQ<19>")
	)
	(segment
		(start 415.307526 -295.503092)
		(end 415.296096 -295.491662)
		(width 0.101854)
		(layer "F.Cu")
		(net "M_E_CPU0_SA_DQ<19>")
	)
	(segment
		(start 412.409894 -295.06672)
		(end 410.853382 -295.06672)
		(width 0.20066)
		(layer "F.Cu")
		(net "M_E_CPU0_SA_DQ<19>")
	)
	(segment
		(start 387.302756 -271.704816)
		(end 387.319012 -271.78635)
		(width 0.088646)
		(layer "F.Cu")
		(net "M_E_CPU0_SA_DQ<19>")
	)
	(segment
		(start 401.049236 -298.326048)
		(end 401.249896 -298.125388)
		(width 0.20066)
		(layer "F.Cu")
		(net "M_E_CPU0_SA_DQ<19>")
	)
	(segment
		(start 393.050776 -291.153596)
		(end 400.223228 -298.326048)
		(width 0.20066)
		(layer "F.Cu")
		(net "M_E_CPU0_SA_DQ<19>")
	)
	(segment
		(start 400.557238 -296.954448)
		(end 403.374098 -296.954448)
		(width 0.20066)
		(layer "F.Cu")
		(net "M_E_CPU0_SA_DQ<19>")
	)
	(segment
		(start 386.857748 -271.070324)
		(end 386.956046 -271.307306)
		(width 0.088646)
		(layer "F.Cu")
		(net "M_E_CPU0_SA_DQ<19>")
	)
	(segment
		(start 415.975292 -295.503092)
		(end 415.307526 -295.503092)
		(width 0.20066)
		(layer "F.Cu")
		(net "M_E_CPU0_SA_DQ<19>")
	)
	(segment
		(start 416.205416 -295.272968)
		(end 415.975292 -295.503092)
		(width 0.20066)
		(layer "F.Cu")
		(net "M_E_CPU0_SA_DQ<19>")
	)
	(segment
		(start 400.356578 -297.439588)
		(end 400.356578 -297.155108)
		(width 0.20066)
		(layer "F.Cu")
		(net "M_E_CPU0_SA_DQ<19>")
	)
	(segment
		(start 416.75939 -294.75049)
		(end 416.420554 -294.75049)
		(width 0.20066)
		(layer "F.Cu")
		(net "M_E_CPU0_SA_DQ<19>")
	)
	(segment
		(start 389.261604 -273.78406)
		(end 390.955022 -275.477478)
		(width 0.1016)
		(layer "F.Cu")
		(net "M_E_CPU0_SA_DQ<19>")
	)
	(segment
		(start 405.731726 -295.530524)
		(end 405.770588 -295.491662)
		(width 0.101854)
		(layer "F.Cu")
		(net "M_E_CPU0_SA_DQ<19>")
	)
	(segment
		(start 407.763726 -295.491662)
		(end 408.185874 -295.491662)
		(width 0.20066)
		(layer "F.Cu")
		(net "M_E_CPU0_SA_DQ<19>")
	)
	(segment
		(start 401.249896 -297.840908)
		(end 401.049236 -297.640248)
		(width 0.20066)
		(layer "F.Cu")
		(net "M_E_CPU0_SA_DQ<19>")
	)
	(segment
		(start 386.750306 -270.69923)
		(end 386.880862 -271.014444)
		(width 0.088646)
		(layer "F.Cu")
		(net "M_E_CPU0_SA_DQ<19>")
	)
	(segment
		(start 386.526532 -270.475456)
		(end 386.750306 -270.69923)
		(width 0.088646)
		(layer "F.Cu")
		(net "M_E_CPU0_SA_DQ<19>")
	)
	(segment
		(start 416.205416 -294.965628)
		(end 416.205416 -295.272968)
		(width 0.20066)
		(layer "F.Cu")
		(net "M_E_CPU0_SA_DQ<19>")
	)
	(segment
		(start 418.397182 -295.06672)
		(end 417.07562 -295.06672)
		(width 0.20066)
		(layer "F.Cu")
		(net "M_E_CPU0_SA_DQ<19>")
	)
	(segment
		(start 401.049236 -297.640248)
		(end 400.557238 -297.640248)
		(width 0.20066)
		(layer "F.Cu")
		(net "M_E_CPU0_SA_DQ<19>")
	)
	(segment
		(start 413.275526 -295.499028)
		(end 412.842202 -295.499028)
		(width 0.20066)
		(layer "F.Cu")
		(net "M_E_CPU0_SA_DQ<19>")
	)
	(segment
		(start 387.319012 -271.78635)
		(end 387.319012 -271.841468)
		(width 0.088646)
		(layer "F.Cu")
		(net "M_E_CPU0_SA_DQ<19>")
	)
	(segment
		(start 414.498282 -295.491662)
		(end 413.300418 -295.491662)
		(width 0.1016)
		(layer "F.Cu")
		(net "M_E_CPU0_SA_DQ<19>")
	)
	(segment
		(start 404.732236 -295.59631)
		(end 405.66594 -295.59631)
		(width 0.20066)
		(layer "F.Cu")
		(net "M_E_CPU0_SA_DQ<19>")
	)
	(segment
		(start 408.185874 -295.491662)
		(end 408.610816 -295.06672)
		(width 0.20066)
		(layer "F.Cu")
		(net "M_E_CPU0_SA_DQ<19>")
	)
	(segment
		(start 387.266942 -271.618202)
		(end 387.302756 -271.704816)
		(width 0.088646)
		(layer "F.Cu")
		(net "M_E_CPU0_SA_DQ<19>")
	)
	(segment
		(start 400.356578 -297.155108)
		(end 400.557238 -296.954448)
		(width 0.20066)
		(layer "F.Cu")
		(net "M_E_CPU0_SA_DQ<19>")
	)
	(segment
		(start 403.374098 -296.954448)
		(end 404.732236 -295.59631)
		(width 0.20066)
		(layer "F.Cu")
		(net "M_E_CPU0_SA_DQ<19>")
	)
	(segment
		(start 391.939018 -280.403046)
		(end 391.939018 -289.491928)
		(width 0.1016)
		(layer "F.Cu")
		(net "M_E_CPU0_SA_DQ<19>")
	)
	(segment
		(start 415.296096 -295.491662)
		(end 414.498282 -295.491662)
		(width 0.101854)
		(layer "F.Cu")
		(net "M_E_CPU0_SA_DQ<19>")
	)
	(segment
		(start 405.770588 -295.491662)
		(end 407.763726 -295.491662)
		(width 0.1016)
		(layer "F.Cu")
		(net "M_E_CPU0_SA_DQ<19>")
	)
	(segment
		(start 391.937748 -291.91712)
		(end 392.1125 -292.091872)
		(width 0.1016)
		(layer "F.Cu")
		(net "M_E_CPU0_SA_DQ<18>")
	)
	(segment
		(start 399.754598 -299.73397)
		(end 403.803358 -299.73397)
		(width 0.20066)
		(layer "F.Cu")
		(net "M_E_CPU0_SA_DQ<18>")
	)
	(segment
		(start 388.830058 -274.215606)
		(end 390.39165 -275.777198)
		(width 0.1016)
		(layer "F.Cu")
		(net "M_E_CPU0_SA_DQ<18>")
	)
	(segment
		(start 408.68346 -297.228006)
		(end 409.144724 -296.766742)
		(width 0.20066)
		(layer "F.Cu")
		(net "M_E_CPU0_SA_DQ<18>")
	)
	(segment
		(start 417.07562 -296.766742)
		(end 416.823652 -296.514774)
		(width 0.20066)
		(layer "F.Cu")
		(net "M_E_CPU0_SA_DQ<18>")
	)
	(segment
		(start 391.395204 -290.12769)
		(end 391.937748 -291.91712)
		(width 0.1016)
		(layer "F.Cu")
		(net "M_E_CPU0_SA_DQ<18>")
	)
	(segment
		(start 387.0071 -273.138646)
		(end 388.280148 -273.665696)
		(width 0.088646)
		(layer "F.Cu")
		(net "M_E_CPU0_SA_DQ<18>")
	)
	(segment
		(start 407.603452 -297.191684)
		(end 407.708608 -297.228006)
		(width 0.1016)
		(layer "F.Cu")
		(net "M_E_CPU0_SA_DQ<18>")
	)
	(segment
		(start 404.78202 -297.355768)
		(end 405.572468 -297.355768)
		(width 0.20066)
		(layer "F.Cu")
		(net "M_E_CPU0_SA_DQ<18>")
	)
	(segment
		(start 391.329418 -289.79749)
		(end 391.395204 -290.12769)
		(width 0.1016)
		(layer "F.Cu")
		(net "M_E_CPU0_SA_DQ<18>")
	)
	(segment
		(start 409.144724 -296.766742)
		(end 410.853382 -296.766742)
		(width 0.20066)
		(layer "F.Cu")
		(net "M_E_CPU0_SA_DQ<18>")
	)
	(segment
		(start 414.498282 -297.191684)
		(end 413.300418 -297.191684)
		(width 0.1016)
		(layer "F.Cu")
		(net "M_E_CPU0_SA_DQ<18>")
	)
	(segment
		(start 388.280148 -273.665696)
		(end 388.830058 -274.215606)
		(width 0.088646)
		(layer "F.Cu")
		(net "M_E_CPU0_SA_DQ<18>")
	)
	(segment
		(start 392.1125 -292.091872)
		(end 399.754598 -299.73397)
		(width 0.20066)
		(layer "F.Cu")
		(net "M_E_CPU0_SA_DQ<18>")
	)
	(segment
		(start 415.307526 -297.203114)
		(end 415.296096 -297.191684)
		(width 0.101854)
		(layer "F.Cu")
		(net "M_E_CPU0_SA_DQ<18>")
	)
	(segment
		(start 416.823652 -296.514774)
		(end 416.439604 -296.514774)
		(width 0.20066)
		(layer "F.Cu")
		(net "M_E_CPU0_SA_DQ<18>")
	)
	(segment
		(start 416.205416 -296.748962)
		(end 416.205416 -297.002454)
		(width 0.20066)
		(layer "F.Cu")
		(net "M_E_CPU0_SA_DQ<18>")
	)
	(segment
		(start 416.004756 -297.203114)
		(end 415.307526 -297.203114)
		(width 0.20066)
		(layer "F.Cu")
		(net "M_E_CPU0_SA_DQ<18>")
	)
	(segment
		(start 412.44647 -296.766742)
		(end 410.853382 -296.766742)
		(width 0.20066)
		(layer "F.Cu")
		(net "M_E_CPU0_SA_DQ<18>")
	)
	(segment
		(start 404.20036 -299.336968)
		(end 404.20036 -297.937428)
		(width 0.20066)
		(layer "F.Cu")
		(net "M_E_CPU0_SA_DQ<18>")
	)
	(segment
		(start 385.534662 -272.103342)
		(end 385.805172 -272.341594)
		(width 0.088646)
		(layer "F.Cu")
		(net "M_E_CPU0_SA_DQ<18>")
	)
	(segment
		(start 405.572468 -297.355768)
		(end 405.731726 -297.19651)
		(width 0.20066)
		(layer "F.Cu")
		(net "M_E_CPU0_SA_DQ<18>")
	)
	(segment
		(start 416.205416 -297.002454)
		(end 416.004756 -297.203114)
		(width 0.20066)
		(layer "F.Cu")
		(net "M_E_CPU0_SA_DQ<18>")
	)
	(segment
		(start 404.20036 -297.937428)
		(end 404.78202 -297.355768)
		(width 0.20066)
		(layer "F.Cu")
		(net "M_E_CPU0_SA_DQ<18>")
	)
	(segment
		(start 407.708608 -297.228006)
		(end 407.763726 -297.228006)
		(width 0.1016)
		(layer "F.Cu")
		(net "M_E_CPU0_SA_DQ<18>")
	)
	(segment
		(start 407.763726 -297.228006)
		(end 408.68346 -297.228006)
		(width 0.20066)
		(layer "F.Cu")
		(net "M_E_CPU0_SA_DQ<18>")
	)
	(segment
		(start 405.731726 -297.19651)
		(end 405.736552 -297.191684)
		(width 0.101854)
		(layer "F.Cu")
		(net "M_E_CPU0_SA_DQ<18>")
	)
	(segment
		(start 412.878778 -297.19905)
		(end 412.44647 -296.766742)
		(width 0.20066)
		(layer "F.Cu")
		(net "M_E_CPU0_SA_DQ<18>")
	)
	(segment
		(start 403.803358 -299.73397)
		(end 404.20036 -299.336968)
		(width 0.20066)
		(layer "F.Cu")
		(net "M_E_CPU0_SA_DQ<18>")
	)
	(segment
		(start 418.397182 -296.766742)
		(end 417.07562 -296.766742)
		(width 0.20066)
		(layer "F.Cu")
		(net "M_E_CPU0_SA_DQ<18>")
	)
	(segment
		(start 390.39165 -275.777198)
		(end 391.329418 -280.465022)
		(width 0.1016)
		(layer "F.Cu")
		(net "M_E_CPU0_SA_DQ<18>")
	)
	(segment
		(start 416.439604 -296.514774)
		(end 416.205416 -296.748962)
		(width 0.20066)
		(layer "F.Cu")
		(net "M_E_CPU0_SA_DQ<18>")
	)
	(segment
		(start 413.275526 -297.19905)
		(end 412.878778 -297.19905)
		(width 0.20066)
		(layer "F.Cu")
		(net "M_E_CPU0_SA_DQ<18>")
	)
	(segment
		(start 391.329418 -280.465022)
		(end 391.329418 -289.79749)
		(width 0.1016)
		(layer "F.Cu")
		(net "M_E_CPU0_SA_DQ<18>")
	)
	(segment
		(start 413.293052 -297.19905)
		(end 413.275526 -297.19905)
		(width 0.101854)
		(layer "F.Cu")
		(net "M_E_CPU0_SA_DQ<18>")
	)
	(segment
		(start 413.300418 -297.191684)
		(end 413.293052 -297.19905)
		(width 0.1016)
		(layer "F.Cu")
		(net "M_E_CPU0_SA_DQ<18>")
	)
	(segment
		(start 385.805172 -272.341594)
		(end 387.0071 -273.138646)
		(width 0.088646)
		(layer "F.Cu")
		(net "M_E_CPU0_SA_DQ<18>")
	)
	(segment
		(start 415.296096 -297.191684)
		(end 414.498282 -297.191684)
		(width 0.101854)
		(layer "F.Cu")
		(net "M_E_CPU0_SA_DQ<18>")
	)
	(segment
		(start 405.736552 -297.191684)
		(end 407.603452 -297.191684)
		(width 0.1016)
		(layer "F.Cu")
		(net "M_E_CPU0_SA_DQ<18>")
	)
	(segment
		(start 409.229052 -296.157904)
		(end 409.1178 -296.269156)
		(width 0.20066)
		(layer "F.Cu")
		(net "M_E_CPU0_SA_DQ<17>")
	)
	(segment
		(start 412.627826 -295.916604)
		(end 412.191454 -295.480232)
		(width 0.20066)
		(layer "F.Cu")
		(net "M_E_CPU0_SA_DQ<17>")
	)
	(segment
		(start 384.683254 -271.516602)
		(end 384.683254 -271.642078)
		(width 0.088646)
		(layer "F.Cu")
		(net "M_E_CPU0_SA_DQ<17>")
	)
	(segment
		(start 409.435046 -295.484296)
		(end 409.229052 -295.69029)
		(width 0.20066)
		(layer "F.Cu")
		(net "M_E_CPU0_SA_DQ<17>")
	)
	(segment
		(start 384.962908 -271.921732)
		(end 385.10972 -271.921732)
		(width 0.088646)
		(layer "F.Cu")
		(net "M_E_CPU0_SA_DQ<17>")
	)
	(segment
		(start 388.069328 -273.023584)
		(end 388.144258 -273.098514)
		(width 0.088646)
		(layer "F.Cu")
		(net "M_E_CPU0_SA_DQ<17>")
	)
	(segment
		(start 400.047206 -299.094398)
		(end 401.878292 -299.094398)
		(width 0.20066)
		(layer "F.Cu")
		(net "M_E_CPU0_SA_DQ<17>")
	)
	(segment
		(start 405.399494 -296.237406)
		(end 405.592788 -296.237406)
		(width 0.20066)
		(layer "F.Cu")
		(net "M_E_CPU0_SA_DQ<17>")
	)
	(segment
		(start 407.6319 -295.916604)
		(end 406.753314 -295.916604)
		(width 0.20066)
		(layer "F.Cu")
		(net "M_E_CPU0_SA_DQ<17>")
	)
	(segment
		(start 408.36215 -296.646854)
		(end 407.6319 -295.916604)
		(width 0.20066)
		(layer "F.Cu")
		(net "M_E_CPU0_SA_DQ<17>")
	)
	(segment
		(start 405.18334 -296.45356)
		(end 405.399494 -296.237406)
		(width 0.20066)
		(layer "F.Cu")
		(net "M_E_CPU0_SA_DQ<17>")
	)
	(segment
		(start 387.378448 -272.737326)
		(end 388.069328 -273.023584)
		(width 0.088646)
		(layer "F.Cu")
		(net "M_E_CPU0_SA_DQ<17>")
	)
	(segment
		(start 402.078952 -298.893738)
		(end 402.078952 -297.806872)
		(width 0.20066)
		(layer "F.Cu")
		(net "M_E_CPU0_SA_DQ<17>")
	)
	(segment
		(start 391.634218 -280.434288)
		(end 391.634218 -289.699446)
		(width 0.1016)
		(layer "F.Cu")
		(net "M_E_CPU0_SA_DQ<17>")
	)
	(segment
		(start 412.191454 -295.480232)
		(end 411.863794 -295.480232)
		(width 0.20066)
		(layer "F.Cu")
		(net "M_E_CPU0_SA_DQ<17>")
	)
	(segment
		(start 403.560788 -298.893738)
		(end 403.560788 -297.672252)
		(width 0.20066)
		(layer "F.Cu")
		(net "M_E_CPU0_SA_DQ<17>")
	)
	(segment
		(start 403.560788 -297.672252)
		(end 404.77948 -296.45356)
		(width 0.20066)
		(layer "F.Cu")
		(net "M_E_CPU0_SA_DQ<17>")
	)
	(segment
		(start 402.078952 -297.806872)
		(end 402.279612 -297.606212)
		(width 0.20066)
		(layer "F.Cu")
		(net "M_E_CPU0_SA_DQ<17>")
	)
	(segment
		(start 402.764752 -297.806872)
		(end 402.764752 -298.893738)
		(width 0.20066)
		(layer "F.Cu")
		(net "M_E_CPU0_SA_DQ<17>")
	)
	(segment
		(start 385.10972 -271.921732)
		(end 385.360672 -271.67078)
		(width 0.088646)
		(layer "F.Cu")
		(net "M_E_CPU0_SA_DQ<17>")
	)
	(segment
		(start 409.84932 -295.484296)
		(end 409.831794 -295.484296)
		(width 0.101854)
		(layer "F.Cu")
		(net "M_E_CPU0_SA_DQ<17>")
	)
	(segment
		(start 386.541518 -272.566384)
		(end 386.95376 -272.737326)
		(width 0.088646)
		(layer "F.Cu")
		(net "M_E_CPU0_SA_DQ<17>")
	)
	(segment
		(start 403.360128 -299.094398)
		(end 403.560788 -298.893738)
		(width 0.20066)
		(layer "F.Cu")
		(net "M_E_CPU0_SA_DQ<17>")
	)
	(segment
		(start 409.1178 -296.269156)
		(end 408.966162 -296.269156)
		(width 0.20066)
		(layer "F.Cu")
		(net "M_E_CPU0_SA_DQ<17>")
	)
	(segment
		(start 401.878292 -299.094398)
		(end 402.078952 -298.893738)
		(width 0.20066)
		(layer "F.Cu")
		(net "M_E_CPU0_SA_DQ<17>")
	)
	(segment
		(start 405.592788 -296.237406)
		(end 405.91359 -295.916604)
		(width 0.20066)
		(layer "F.Cu")
		(net "M_E_CPU0_SA_DQ<17>")
	)
	(segment
		(start 392.57859 -291.625782)
		(end 400.047206 -299.094398)
		(width 0.20066)
		(layer "F.Cu")
		(net "M_E_CPU0_SA_DQ<17>")
	)
	(segment
		(start 411.852364 -295.491662)
		(end 411.05455 -295.491662)
		(width 0.101854)
		(layer "F.Cu")
		(net "M_E_CPU0_SA_DQ<17>")
	)
	(segment
		(start 386.95376 -272.737326)
		(end 387.378448 -272.737326)
		(width 0.088646)
		(layer "F.Cu")
		(net "M_E_CPU0_SA_DQ<17>")
	)
	(segment
		(start 402.564092 -297.606212)
		(end 402.764752 -297.806872)
		(width 0.20066)
		(layer "F.Cu")
		(net "M_E_CPU0_SA_DQ<17>")
	)
	(segment
		(start 411.863794 -295.480232)
		(end 411.852364 -295.491662)
		(width 0.101854)
		(layer "F.Cu")
		(net "M_E_CPU0_SA_DQ<17>")
	)
	(segment
		(start 384.801618 -271.398238)
		(end 384.683254 -271.516602)
		(width 0.088646)
		(layer "F.Cu")
		(net "M_E_CPU0_SA_DQ<17>")
	)
	(segment
		(start 385.064762 -271.289272)
		(end 384.801618 -271.398238)
		(width 0.088646)
		(layer "F.Cu")
		(net "M_E_CPU0_SA_DQ<17>")
	)
	(segment
		(start 404.77948 -296.45356)
		(end 405.18334 -296.45356)
		(width 0.20066)
		(layer "F.Cu")
		(net "M_E_CPU0_SA_DQ<17>")
	)
	(segment
		(start 386.05333 -272.19148)
		(end 386.173218 -272.311368)
		(width 0.088646)
		(layer "F.Cu")
		(net "M_E_CPU0_SA_DQ<17>")
	)
	(segment
		(start 414.297114 -295.916604)
		(end 412.627826 -295.916604)
		(width 0.20066)
		(layer "F.Cu")
		(net "M_E_CPU0_SA_DQ<17>")
	)
	(segment
		(start 390.673336 -275.627592)
		(end 391.634218 -280.434288)
		(width 0.1016)
		(layer "F.Cu")
		(net "M_E_CPU0_SA_DQ<17>")
	)
	(segment
		(start 402.279612 -297.606212)
		(end 402.564092 -297.606212)
		(width 0.20066)
		(layer "F.Cu")
		(net "M_E_CPU0_SA_DQ<17>")
	)
	(segment
		(start 386.05333 -271.807178)
		(end 386.05333 -272.19148)
		(width 0.088646)
		(layer "F.Cu")
		(net "M_E_CPU0_SA_DQ<17>")
	)
	(segment
		(start 408.966162 -296.269156)
		(end 408.588464 -296.646854)
		(width 0.20066)
		(layer "F.Cu")
		(net "M_E_CPU0_SA_DQ<17>")
	)
	(segment
		(start 409.856686 -295.491662)
		(end 409.84932 -295.484296)
		(width 0.1016)
		(layer "F.Cu")
		(net "M_E_CPU0_SA_DQ<17>")
	)
	(segment
		(start 385.916932 -271.67078)
		(end 386.05333 -271.807178)
		(width 0.088646)
		(layer "F.Cu")
		(net "M_E_CPU0_SA_DQ<17>")
	)
	(segment
		(start 411.05455 -295.491662)
		(end 409.856686 -295.491662)
		(width 0.1016)
		(layer "F.Cu")
		(net "M_E_CPU0_SA_DQ<17>")
	)
	(segment
		(start 405.91359 -295.916604)
		(end 406.753314 -295.916604)
		(width 0.20066)
		(layer "F.Cu")
		(net "M_E_CPU0_SA_DQ<17>")
	)
	(segment
		(start 385.360672 -271.67078)
		(end 385.916932 -271.67078)
		(width 0.088646)
		(layer "F.Cu")
		(net "M_E_CPU0_SA_DQ<17>")
	)
	(segment
		(start 409.831794 -295.484296)
		(end 409.435046 -295.484296)
		(width 0.20066)
		(layer "F.Cu")
		(net "M_E_CPU0_SA_DQ<17>")
	)
	(segment
		(start 388.144258 -273.098514)
		(end 390.673336 -275.627592)
		(width 0.1016)
		(layer "F.Cu")
		(net "M_E_CPU0_SA_DQ<17>")
	)
	(segment
		(start 384.683254 -271.642078)
		(end 384.962908 -271.921732)
		(width 0.088646)
		(layer "F.Cu")
		(net "M_E_CPU0_SA_DQ<17>")
	)
	(segment
		(start 391.634218 -289.699446)
		(end 392.328146 -291.375338)
		(width 0.1016)
		(layer "F.Cu")
		(net "M_E_CPU0_SA_DQ<17>")
	)
	(segment
		(start 386.375402 -272.461228)
		(end 386.541518 -272.566384)
		(width 0.088646)
		(layer "F.Cu")
		(net "M_E_CPU0_SA_DQ<17>")
	)
	(segment
		(start 408.588464 -296.646854)
		(end 408.36215 -296.646854)
		(width 0.20066)
		(layer "F.Cu")
		(net "M_E_CPU0_SA_DQ<17>")
	)
	(segment
		(start 386.173218 -272.311368)
		(end 386.375402 -272.461228)
		(width 0.088646)
		(layer "F.Cu")
		(net "M_E_CPU0_SA_DQ<17>")
	)
	(segment
		(start 402.965412 -299.094398)
		(end 403.360128 -299.094398)
		(width 0.20066)
		(layer "F.Cu")
		(net "M_E_CPU0_SA_DQ<17>")
	)
	(segment
		(start 402.764752 -298.893738)
		(end 402.965412 -299.094398)
		(width 0.20066)
		(layer "F.Cu")
		(net "M_E_CPU0_SA_DQ<17>")
	)
	(segment
		(start 392.328146 -291.375338)
		(end 392.57859 -291.625782)
		(width 0.1016)
		(layer "F.Cu")
		(net "M_E_CPU0_SA_DQ<17>")
	)
	(segment
		(start 409.229052 -295.69029)
		(end 409.229052 -296.157904)
		(width 0.20066)
		(layer "F.Cu")
		(net "M_E_CPU0_SA_DQ<17>")
	)
	(segment
		(start 403.473158 -301.186088)
		(end 403.757638 -301.186088)
		(width 0.20066)
		(layer "F.Cu")
		(net "M_E_CPU0_SA_DQ<16>")
	)
	(segment
		(start 399.479516 -300.373542)
		(end 400.328638 -300.373542)
		(width 0.20066)
		(layer "F.Cu")
		(net "M_E_CPU0_SA_DQ<16>")
	)
	(segment
		(start 390.110726 -275.927566)
		(end 391.024618 -280.504138)
		(width 0.1016)
		(layer "F.Cu")
		(net "M_E_CPU0_SA_DQ<16>")
	)
	(segment
		(start 407.837386 -297.865292)
		(end 407.58872 -297.616626)
		(width 0.20066)
		(layer "F.Cu")
		(net "M_E_CPU0_SA_DQ<16>")
	)
	(segment
		(start 411.863794 -297.180254)
		(end 411.852364 -297.191684)
		(width 0.101854)
		(layer "F.Cu")
		(net "M_E_CPU0_SA_DQ<16>")
	)
	(segment
		(start 403.272498 -300.985428)
		(end 403.473158 -301.186088)
		(width 0.20066)
		(layer "F.Cu")
		(net "M_E_CPU0_SA_DQ<16>")
	)
	(segment
		(start 385.930648 -273.496278)
		(end 386.041138 -273.496278)
		(width 0.088646)
		(layer "F.Cu")
		(net "M_E_CPU0_SA_DQ<16>")
	)
	(segment
		(start 409.856686 -297.191684)
		(end 409.84932 -297.184318)
		(width 0.1016)
		(layer "F.Cu")
		(net "M_E_CPU0_SA_DQ<16>")
	)
	(segment
		(start 402.101558 -301.186088)
		(end 402.386038 -301.186088)
		(width 0.20066)
		(layer "F.Cu")
		(net "M_E_CPU0_SA_DQ<16>")
	)
	(segment
		(start 385.430268 -273.280378)
		(end 385.714748 -273.280378)
		(width 0.088646)
		(layer "F.Cu")
		(net "M_E_CPU0_SA_DQ<16>")
	)
	(segment
		(start 386.549646 -273.285712)
		(end 386.695442 -273.285712)
		(width 0.088646)
		(layer "F.Cu")
		(net "M_E_CPU0_SA_DQ<16>")
	)
	(segment
		(start 403.071838 -300.373542)
		(end 403.272498 -300.574202)
		(width 0.20066)
		(layer "F.Cu")
		(net "M_E_CPU0_SA_DQ<16>")
	)
	(segment
		(start 403.757638 -301.186088)
		(end 403.958298 -300.985428)
		(width 0.20066)
		(layer "F.Cu")
		(net "M_E_CPU0_SA_DQ<16>")
	)
	(segment
		(start 385.067048 -272.917158)
		(end 385.430268 -273.280378)
		(width 0.088646)
		(layer "F.Cu")
		(net "M_E_CPU0_SA_DQ<16>")
	)
	(segment
		(start 386.041138 -273.496278)
		(end 386.549646 -273.285712)
		(width 0.088646)
		(layer "F.Cu")
		(net "M_E_CPU0_SA_DQ<16>")
	)
	(segment
		(start 404.158958 -300.373542)
		(end 404.503128 -300.373542)
		(width 0.20066)
		(layer "F.Cu")
		(net "M_E_CPU0_SA_DQ<16>")
	)
	(segment
		(start 405.167846 -298.017184)
		(end 405.53386 -298.017184)
		(width 0.20066)
		(layer "F.Cu")
		(net "M_E_CPU0_SA_DQ<16>")
	)
	(segment
		(start 391.408412 -292.30828)
		(end 391.627106 -292.526466)
		(width 0.1016)
		(layer "F.Cu")
		(net "M_E_CPU0_SA_DQ<16>")
	)
	(segment
		(start 408.997912 -297.865292)
		(end 407.837386 -297.865292)
		(width 0.20066)
		(layer "F.Cu")
		(net "M_E_CPU0_SA_DQ<16>")
	)
	(segment
		(start 411.852364 -297.191684)
		(end 411.05455 -297.191684)
		(width 0.101854)
		(layer "F.Cu")
		(net "M_E_CPU0_SA_DQ<16>")
	)
	(segment
		(start 391.024618 -290.379912)
		(end 391.408412 -292.30828)
		(width 0.1016)
		(layer "F.Cu")
		(net "M_E_CPU0_SA_DQ<16>")
	)
	(segment
		(start 409.396184 -297.184318)
		(end 409.185872 -297.39463)
		(width 0.20066)
		(layer "F.Cu")
		(net "M_E_CPU0_SA_DQ<16>")
	)
	(segment
		(start 391.024618 -280.504138)
		(end 391.024618 -290.379912)
		(width 0.1016)
		(layer "F.Cu")
		(net "M_E_CPU0_SA_DQ<16>")
	)
	(segment
		(start 401.900898 -300.574202)
		(end 401.900898 -300.985428)
		(width 0.20066)
		(layer "F.Cu")
		(net "M_E_CPU0_SA_DQ<16>")
	)
	(segment
		(start 391.627106 -292.526466)
		(end 399.479516 -300.373542)
		(width 0.20066)
		(layer "F.Cu")
		(net "M_E_CPU0_SA_DQ<16>")
	)
	(segment
		(start 402.787358 -300.373542)
		(end 403.071838 -300.373542)
		(width 0.20066)
		(layer "F.Cu")
		(net "M_E_CPU0_SA_DQ<16>")
	)
	(segment
		(start 402.586698 -300.985428)
		(end 402.586698 -300.574202)
		(width 0.20066)
		(layer "F.Cu")
		(net "M_E_CPU0_SA_DQ<16>")
	)
	(segment
		(start 414.297114 -297.616626)
		(end 412.667958 -297.616626)
		(width 0.20066)
		(layer "F.Cu")
		(net "M_E_CPU0_SA_DQ<16>")
	)
	(segment
		(start 401.215098 -300.574202)
		(end 401.415758 -300.373542)
		(width 0.20066)
		(layer "F.Cu")
		(net "M_E_CPU0_SA_DQ<16>")
	)
	(segment
		(start 401.215098 -300.985428)
		(end 401.215098 -300.574202)
		(width 0.20066)
		(layer "F.Cu")
		(net "M_E_CPU0_SA_DQ<16>")
	)
	(segment
		(start 402.586698 -300.574202)
		(end 402.787358 -300.373542)
		(width 0.20066)
		(layer "F.Cu")
		(net "M_E_CPU0_SA_DQ<16>")
	)
	(segment
		(start 388.015734 -273.832574)
		(end 388.614412 -274.431252)
		(width 0.088646)
		(layer "F.Cu")
		(net "M_E_CPU0_SA_DQ<16>")
	)
	(segment
		(start 403.958298 -300.574202)
		(end 404.158958 -300.373542)
		(width 0.20066)
		(layer "F.Cu")
		(net "M_E_CPU0_SA_DQ<16>")
	)
	(segment
		(start 401.014438 -301.186088)
		(end 401.215098 -300.985428)
		(width 0.20066)
		(layer "F.Cu")
		(net "M_E_CPU0_SA_DQ<16>")
	)
	(segment
		(start 409.185872 -297.677332)
		(end 408.997912 -297.865292)
		(width 0.20066)
		(layer "F.Cu")
		(net "M_E_CPU0_SA_DQ<16>")
	)
	(segment
		(start 405.53386 -298.017184)
		(end 405.934418 -297.616626)
		(width 0.20066)
		(layer "F.Cu")
		(net "M_E_CPU0_SA_DQ<16>")
	)
	(segment
		(start 402.386038 -301.186088)
		(end 402.586698 -300.985428)
		(width 0.20066)
		(layer "F.Cu")
		(net "M_E_CPU0_SA_DQ<16>")
	)
	(segment
		(start 412.667958 -297.616626)
		(end 412.231586 -297.180254)
		(width 0.20066)
		(layer "F.Cu")
		(net "M_E_CPU0_SA_DQ<16>")
	)
	(segment
		(start 404.839932 -300.036738)
		(end 404.839932 -298.345098)
		(width 0.20066)
		(layer "F.Cu")
		(net "M_E_CPU0_SA_DQ<16>")
	)
	(segment
		(start 401.700238 -300.373542)
		(end 401.900898 -300.574202)
		(width 0.20066)
		(layer "F.Cu")
		(net "M_E_CPU0_SA_DQ<16>")
	)
	(segment
		(start 400.328638 -300.373542)
		(end 400.529298 -300.574202)
		(width 0.20066)
		(layer "F.Cu")
		(net "M_E_CPU0_SA_DQ<16>")
	)
	(segment
		(start 409.185872 -297.39463)
		(end 409.185872 -297.677332)
		(width 0.20066)
		(layer "F.Cu")
		(net "M_E_CPU0_SA_DQ<16>")
	)
	(segment
		(start 386.695442 -273.285712)
		(end 388.015734 -273.832574)
		(width 0.088646)
		(layer "F.Cu")
		(net "M_E_CPU0_SA_DQ<16>")
	)
	(segment
		(start 403.272498 -300.574202)
		(end 403.272498 -300.985428)
		(width 0.20066)
		(layer "F.Cu")
		(net "M_E_CPU0_SA_DQ<16>")
	)
	(segment
		(start 407.58872 -297.616626)
		(end 406.753314 -297.616626)
		(width 0.20066)
		(layer "F.Cu")
		(net "M_E_CPU0_SA_DQ<16>")
	)
	(segment
		(start 409.84932 -297.184318)
		(end 409.831794 -297.184318)
		(width 0.101854)
		(layer "F.Cu")
		(net "M_E_CPU0_SA_DQ<16>")
	)
	(segment
		(start 403.958298 -300.985428)
		(end 403.958298 -300.574202)
		(width 0.20066)
		(layer "F.Cu")
		(net "M_E_CPU0_SA_DQ<16>")
	)
	(segment
		(start 412.231586 -297.180254)
		(end 411.863794 -297.180254)
		(width 0.20066)
		(layer "F.Cu")
		(net "M_E_CPU0_SA_DQ<16>")
	)
	(segment
		(start 388.614412 -274.431252)
		(end 390.110726 -275.927566)
		(width 0.1016)
		(layer "F.Cu")
		(net "M_E_CPU0_SA_DQ<16>")
	)
	(segment
		(start 385.714748 -273.280378)
		(end 385.930648 -273.496278)
		(width 0.088646)
		(layer "F.Cu")
		(net "M_E_CPU0_SA_DQ<16>")
	)
	(segment
		(start 404.839932 -298.345098)
		(end 405.167846 -298.017184)
		(width 0.20066)
		(layer "F.Cu")
		(net "M_E_CPU0_SA_DQ<16>")
	)
	(segment
		(start 400.529298 -300.985428)
		(end 400.729958 -301.186088)
		(width 0.20066)
		(layer "F.Cu")
		(net "M_E_CPU0_SA_DQ<16>")
	)
	(segment
		(start 411.05455 -297.191684)
		(end 409.856686 -297.191684)
		(width 0.1016)
		(layer "F.Cu")
		(net "M_E_CPU0_SA_DQ<16>")
	)
	(segment
		(start 405.934418 -297.616626)
		(end 406.753314 -297.616626)
		(width 0.20066)
		(layer "F.Cu")
		(net "M_E_CPU0_SA_DQ<16>")
	)
	(segment
		(start 404.503128 -300.373542)
		(end 404.839932 -300.036738)
		(width 0.20066)
		(layer "F.Cu")
		(net "M_E_CPU0_SA_DQ<16>")
	)
	(segment
		(start 400.729958 -301.186088)
		(end 401.014438 -301.186088)
		(width 0.20066)
		(layer "F.Cu")
		(net "M_E_CPU0_SA_DQ<16>")
	)
	(segment
		(start 409.831794 -297.184318)
		(end 409.396184 -297.184318)
		(width 0.20066)
		(layer "F.Cu")
		(net "M_E_CPU0_SA_DQ<16>")
	)
	(segment
		(start 401.900898 -300.985428)
		(end 402.101558 -301.186088)
		(width 0.20066)
		(layer "F.Cu")
		(net "M_E_CPU0_SA_DQ<16>")
	)
	(segment
		(start 400.529298 -300.574202)
		(end 400.529298 -300.985428)
		(width 0.20066)
		(layer "F.Cu")
		(net "M_E_CPU0_SA_DQ<16>")
	)
	(segment
		(start 401.415758 -300.373542)
		(end 401.700238 -300.373542)
		(width 0.20066)
		(layer "F.Cu")
		(net "M_E_CPU0_SA_DQ<16>")
	)
	(segment
		(start 385.064762 -272.917158)
		(end 385.067048 -272.917158)
		(width 0.088646)
		(layer "F.Cu")
		(net "M_E_CPU0_SA_DQ<16>")
	)
	(segment
		(start 413.01289 -298.899072)
		(end 412.580582 -298.466764)
		(width 0.20066)
		(layer "F.Cu")
		(net "M_E_CPU0_SA_DQ<15>")
	)
	(segment
		(start 418.397182 -298.466764)
		(end 417.07562 -298.466764)
		(width 0.20066)
		(layer "F.Cu")
		(net "M_E_CPU0_SA_DQ<15>")
	)
	(segment
		(start 414.498282 -298.891706)
		(end 413.300418 -298.891706)
		(width 0.1016)
		(layer "F.Cu")
		(net "M_E_CPU0_SA_DQ<15>")
	)
	(segment
		(start 416.823652 -298.214796)
		(end 416.439604 -298.214796)
		(width 0.20066)
		(layer "F.Cu")
		(net "M_E_CPU0_SA_DQ<15>")
	)
	(segment
		(start 415.296096 -298.891706)
		(end 414.498282 -298.891706)
		(width 0.101854)
		(layer "F.Cu")
		(net "M_E_CPU0_SA_DQ<15>")
	)
	(segment
		(start 413.275526 -298.899072)
		(end 413.01289 -298.899072)
		(width 0.20066)
		(layer "F.Cu")
		(net "M_E_CPU0_SA_DQ<15>")
	)
	(segment
		(start 382.715516 -271.011142)
		(end 382.715262 -271.011396)
		(width 0.20066)
		(layer "F.Cu")
		(net "M_E_CPU0_SA_DQ<15>")
	)
	(segment
		(start 416.205416 -298.727368)
		(end 416.029648 -298.903136)
		(width 0.20066)
		(layer "F.Cu")
		(net "M_E_CPU0_SA_DQ<15>")
	)
	(segment
		(start 382.715516 -270.475456)
		(end 382.715516 -271.011142)
		(width 0.20066)
		(layer "F.Cu")
		(net "M_E_CPU0_SA_DQ<15>")
	)
	(segment
		(start 413.300418 -298.891706)
		(end 413.293052 -298.899072)
		(width 0.1016)
		(layer "F.Cu")
		(net "M_E_CPU0_SA_DQ<15>")
	)
	(segment
		(start 417.07562 -298.466764)
		(end 416.823652 -298.214796)
		(width 0.20066)
		(layer "F.Cu")
		(net "M_E_CPU0_SA_DQ<15>")
	)
	(segment
		(start 413.293052 -298.899072)
		(end 413.275526 -298.899072)
		(width 0.101854)
		(layer "F.Cu")
		(net "M_E_CPU0_SA_DQ<15>")
	)
	(segment
		(start 412.580582 -298.466764)
		(end 410.853382 -298.466764)
		(width 0.20066)
		(layer "F.Cu")
		(net "M_E_CPU0_SA_DQ<15>")
	)
	(segment
		(start 416.439604 -298.214796)
		(end 416.205416 -298.448984)
		(width 0.20066)
		(layer "F.Cu")
		(net "M_E_CPU0_SA_DQ<15>")
	)
	(segment
		(start 416.029648 -298.903136)
		(end 415.307526 -298.903136)
		(width 0.20066)
		(layer "F.Cu")
		(net "M_E_CPU0_SA_DQ<15>")
	)
	(segment
		(start 410.853382 -298.466764)
		(end 409.723082 -298.466764)
		(width 0.20066)
		(layer "F.Cu")
		(net "M_E_CPU0_SA_DQ<15>")
	)
	(segment
		(start 415.307526 -298.903136)
		(end 415.296096 -298.891706)
		(width 0.101854)
		(layer "F.Cu")
		(net "M_E_CPU0_SA_DQ<15>")
	)
	(segment
		(start 416.205416 -298.448984)
		(end 416.205416 -298.727368)
		(width 0.20066)
		(layer "F.Cu")
		(net "M_E_CPU0_SA_DQ<15>")
	)
	(segment
		(start 382.528064 -271.335754)
		(end 382.519174 -271.330674)
		(width 0.088646)
		(layer "In2.Cu")
		(net "M_E_CPU0_SA_DQ<15>")
	)
	(segment
		(start 409.1051 -296.745914)
		(end 409.29814 -296.552874)
		(width 0.18288)
		(layer "In2.Cu")
		(net "M_E_CPU0_SA_DQ<15>")
	)
	(segment
		(start 388.840472 -271.045686)
		(end 388.161784 -271.045686)
		(width 0.088646)
		(layer "In2.Cu")
		(net "M_E_CPU0_SA_DQ<15>")
	)
	(segment
		(start 387.967474 -270.851376)
		(end 387.221476 -270.851376)
		(width 0.088646)
		(layer "In2.Cu")
		(net "M_E_CPU0_SA_DQ<15>")
	)
	(segment
		(start 400.303492 -283.251656)
		(end 395.6177 -278.565864)
		(width 0.18288)
		(layer "In2.Cu")
		(net "M_E_CPU0_SA_DQ<15>")
	)
	(segment
		(start 400.923506 -286.54375)
		(end 400.303492 -285.046166)
		(width 0.18288)
		(layer "In2.Cu")
		(net "M_E_CPU0_SA_DQ<15>")
	)
	(segment
		(start 408.812238 -294.201342)
		(end 408.204162 -294.201342)
		(width 0.18288)
		(layer "In2.Cu")
		(net "M_E_CPU0_SA_DQ<15>")
	)
	(segment
		(start 408.64409 -296.745914)
		(end 409.1051 -296.745914)
		(width 0.18288)
		(layer "In2.Cu")
		(net "M_E_CPU0_SA_DQ<15>")
	)
	(segment
		(start 408.48407 -297.365166)
		(end 408.48407 -296.905934)
		(width 0.18288)
		(layer "In2.Cu")
		(net "M_E_CPU0_SA_DQ<15>")
	)
	(segment
		(start 409.204668 -297.948096)
		(end 409.204668 -297.7515)
		(width 0.18288)
		(layer "In2.Cu")
		(net "M_E_CPU0_SA_DQ<15>")
	)
	(segment
		(start 405.349456 -291.253672)
		(end 404.906988 -290.957762)
		(width 0.18288)
		(layer "In2.Cu")
		(net "M_E_CPU0_SA_DQ<15>")
	)
	(segment
		(start 389.743442 -271.045686)
		(end 388.840472 -271.045686)
		(width 0.18288)
		(layer "In2.Cu")
		(net "M_E_CPU0_SA_DQ<15>")
	)
	(segment
		(start 406.877266 -292.26637)
		(end 406.009348 -292.26637)
		(width 0.18288)
		(layer "In2.Cu")
		(net "M_E_CPU0_SA_DQ<15>")
	)
	(segment
		(start 409.204922 -294.594026)
		(end 408.812238 -294.201342)
		(width 0.18288)
		(layer "In2.Cu")
		(net "M_E_CPU0_SA_DQ<15>")
	)
	(segment
		(start 388.161784 -271.045686)
		(end 387.967474 -270.851376)
		(width 0.088646)
		(layer "In2.Cu")
		(net "M_E_CPU0_SA_DQ<15>")
	)
	(segment
		(start 385.266946 -270.513302)
		(end 385.252214 -270.521938)
		(width 0.088646)
		(layer "In2.Cu")
		(net "M_E_CPU0_SA_DQ<15>")
	)
	(segment
		(start 404.906988 -290.957762)
		(end 404.603204 -290.223448)
		(width 0.18288)
		(layer "In2.Cu")
		(net "M_E_CPU0_SA_DQ<15>")
	)
	(segment
		(start 408.67711 -297.558206)
		(end 408.48407 -297.365166)
		(width 0.18288)
		(layer "In2.Cu")
		(net "M_E_CPU0_SA_DQ<15>")
	)
	(segment
		(start 408.010868 -294.008048)
		(end 408.010868 -293.399972)
		(width 0.18288)
		(layer "In2.Cu")
		(net "M_E_CPU0_SA_DQ<15>")
	)
	(segment
		(start 400.303492 -285.046166)
		(end 400.303492 -283.251656)
		(width 0.18288)
		(layer "In2.Cu")
		(net "M_E_CPU0_SA_DQ<15>")
	)
	(segment
		(start 386.206746 -270.513302)
		(end 386.192014 -270.521938)
		(width 0.088646)
		(layer "In2.Cu")
		(net "M_E_CPU0_SA_DQ<15>")
	)
	(segment
		(start 387.221476 -270.851376)
		(end 386.935472 -270.565372)
		(width 0.088646)
		(layer "In2.Cu")
		(net "M_E_CPU0_SA_DQ<15>")
	)
	(segment
		(start 409.011882 -295.19753)
		(end 409.204922 -295.00449)
		(width 0.18288)
		(layer "In2.Cu")
		(net "M_E_CPU0_SA_DQ<15>")
	)
	(segment
		(start 408.351228 -295.789604)
		(end 408.351228 -295.39057)
		(width 0.18288)
		(layer "In2.Cu")
		(net "M_E_CPU0_SA_DQ<15>")
	)
	(segment
		(start 409.723082 -298.466764)
		(end 409.204668 -297.948096)
		(width 0.18288)
		(layer "In2.Cu")
		(net "M_E_CPU0_SA_DQ<15>")
	)
	(segment
		(start 384.327146 -270.513302)
		(end 384.312414 -270.521938)
		(width 0.088646)
		(layer "In2.Cu")
		(net "M_E_CPU0_SA_DQ<15>")
	)
	(segment
		(start 409.204922 -295.00449)
		(end 409.204922 -294.594026)
		(width 0.18288)
		(layer "In2.Cu")
		(net "M_E_CPU0_SA_DQ<15>")
	)
	(segment
		(start 408.351228 -295.39057)
		(end 408.544268 -295.19753)
		(width 0.18288)
		(layer "In2.Cu")
		(net "M_E_CPU0_SA_DQ<15>")
	)
	(segment
		(start 382.345184 -271.068546)
		(end 382.402334 -271.011396)
		(width 0.088646)
		(layer "In2.Cu")
		(net "M_E_CPU0_SA_DQ<15>")
	)
	(segment
		(start 409.204668 -297.7515)
		(end 409.011882 -297.558206)
		(width 0.18288)
		(layer "In2.Cu")
		(net "M_E_CPU0_SA_DQ<15>")
	)
	(segment
		(start 408.48407 -296.905934)
		(end 408.64409 -296.745914)
		(width 0.18288)
		(layer "In2.Cu")
		(net "M_E_CPU0_SA_DQ<15>")
	)
	(segment
		(start 409.011882 -297.558206)
		(end 408.67711 -297.558206)
		(width 0.18288)
		(layer "In2.Cu")
		(net "M_E_CPU0_SA_DQ<15>")
	)
	(segment
		(start 382.91135 -271.330674)
		(end 382.90246 -271.335754)
		(width 0.088646)
		(layer "In2.Cu")
		(net "M_E_CPU0_SA_DQ<15>")
	)
	(segment
		(start 383.372614 -270.521938)
		(end 383.366518 -270.525494)
		(width 0.088646)
		(layer "In2.Cu")
		(net "M_E_CPU0_SA_DQ<15>")
	)
	(segment
		(start 408.544268 -295.982644)
		(end 408.351228 -295.789604)
		(width 0.18288)
		(layer "In2.Cu")
		(net "M_E_CPU0_SA_DQ<15>")
	)
	(segment
		(start 408.544268 -295.19753)
		(end 409.011882 -295.19753)
		(width 0.18288)
		(layer "In2.Cu")
		(net "M_E_CPU0_SA_DQ<15>")
	)
	(segment
		(start 409.098496 -295.982644)
		(end 408.544268 -295.982644)
		(width 0.18288)
		(layer "In2.Cu")
		(net "M_E_CPU0_SA_DQ<15>")
	)
	(segment
		(start 409.29814 -296.552874)
		(end 409.29814 -296.182288)
		(width 0.18288)
		(layer "In2.Cu")
		(net "M_E_CPU0_SA_DQ<15>")
	)
	(segment
		(start 408.204162 -294.201342)
		(end 408.010868 -294.008048)
		(width 0.18288)
		(layer "In2.Cu")
		(net "M_E_CPU0_SA_DQ<15>")
	)
	(segment
		(start 404.603204 -290.223448)
		(end 400.923506 -286.54375)
		(width 0.18288)
		(layer "In2.Cu")
		(net "M_E_CPU0_SA_DQ<15>")
	)
	(segment
		(start 408.010868 -293.399972)
		(end 406.877266 -292.26637)
		(width 0.18288)
		(layer "In2.Cu")
		(net "M_E_CPU0_SA_DQ<15>")
	)
	(segment
		(start 386.935472 -270.565372)
		(end 386.874004 -270.565372)
		(width 0.088646)
		(layer "In2.Cu")
		(net "M_E_CPU0_SA_DQ<15>")
	)
	(segment
		(start 383.387346 -270.513302)
		(end 383.372614 -270.521938)
		(width 0.088646)
		(layer "In2.Cu")
		(net "M_E_CPU0_SA_DQ<15>")
	)
	(segment
		(start 382.402334 -271.011396)
		(end 382.715262 -271.011396)
		(width 0.088646)
		(layer "In2.Cu")
		(net "M_E_CPU0_SA_DQ<15>")
	)
	(segment
		(start 406.009348 -292.26637)
		(end 405.599138 -291.85616)
		(width 0.18288)
		(layer "In2.Cu")
		(net "M_E_CPU0_SA_DQ<15>")
	)
	(segment
		(start 395.6177 -278.565864)
		(end 394.453618 -275.755862)
		(width 0.18288)
		(layer "In2.Cu")
		(net "M_E_CPU0_SA_DQ<15>")
	)
	(segment
		(start 405.599138 -291.85616)
		(end 405.349456 -291.253672)
		(width 0.18288)
		(layer "In2.Cu")
		(net "M_E_CPU0_SA_DQ<15>")
	)
	(segment
		(start 394.453618 -275.755862)
		(end 389.743442 -271.045686)
		(width 0.18288)
		(layer "In2.Cu")
		(net "M_E_CPU0_SA_DQ<15>")
	)
	(segment
		(start 409.29814 -296.182288)
		(end 409.098496 -295.982644)
		(width 0.18288)
		(layer "In2.Cu")
		(net "M_E_CPU0_SA_DQ<15>")
	)
	(arc
		(start 383.089912 -271.011396)
		(mid 383.042233 -271.194296)
		(end 382.91135 -271.330674)
		(width 0.088646)
		(layer "In2.Cu")
		(net "M_E_CPU0_SA_DQ<15>")
	)
	(arc
		(start 385.252214 -270.521938)
		(mid 385.065016 -270.572081)
		(end 384.877818 -270.521938)
		(width 0.088646)
		(layer "In2.Cu")
		(net "M_E_CPU0_SA_DQ<15>")
	)
	(arc
		(start 383.938018 -270.521938)
		(mid 383.663819 -270.446103)
		(end 383.387346 -270.513302)
		(width 0.088646)
		(layer "In2.Cu")
		(net "M_E_CPU0_SA_DQ<15>")
	)
	(arc
		(start 385.817618 -270.521938)
		(mid 385.543419 -270.446103)
		(end 385.266946 -270.513302)
		(width 0.088646)
		(layer "In2.Cu")
		(net "M_E_CPU0_SA_DQ<15>")
	)
	(arc
		(start 386.192014 -270.521938)
		(mid 386.004816 -270.572081)
		(end 385.817618 -270.521938)
		(width 0.088646)
		(layer "In2.Cu")
		(net "M_E_CPU0_SA_DQ<15>")
	)
	(arc
		(start 386.757418 -270.521938)
		(mid 386.483219 -270.446103)
		(end 386.206746 -270.513302)
		(width 0.088646)
		(layer "In2.Cu")
		(net "M_E_CPU0_SA_DQ<15>")
	)
	(arc
		(start 383.366518 -270.525494)
		(mid 383.163931 -270.731845)
		(end 383.089912 -271.011396)
		(width 0.088646)
		(layer "In2.Cu")
		(net "M_E_CPU0_SA_DQ<15>")
	)
	(arc
		(start 386.874004 -270.565372)
		(mid 386.813893 -270.548534)
		(end 386.757418 -270.521938)
		(width 0.088646)
		(layer "In2.Cu")
		(net "M_E_CPU0_SA_DQ<15>")
	)
	(arc
		(start 384.877818 -270.521938)
		(mid 384.603619 -270.446103)
		(end 384.327146 -270.513302)
		(width 0.088646)
		(layer "In2.Cu")
		(net "M_E_CPU0_SA_DQ<15>")
	)
	(arc
		(start 382.519174 -271.330674)
		(mid 382.403365 -271.218745)
		(end 382.345184 -271.068546)
		(width 0.088646)
		(layer "In2.Cu")
		(net "M_E_CPU0_SA_DQ<15>")
	)
	(arc
		(start 382.90246 -271.335754)
		(mid 382.715262 -271.385897)
		(end 382.528064 -271.335754)
		(width 0.088646)
		(layer "In2.Cu")
		(net "M_E_CPU0_SA_DQ<15>")
	)
	(arc
		(start 384.312414 -270.521938)
		(mid 384.125216 -270.572081)
		(end 383.938018 -270.521938)
		(width 0.088646)
		(layer "In2.Cu")
		(net "M_E_CPU0_SA_DQ<15>")
	)
	(segment
		(start 383.185162 -271.289272)
		(end 383.185416 -271.825212)
		(width 0.20066)
		(layer "F.Cu")
		(net "M_E_CPU0_SA_DQ<14>")
	)
	(segment
		(start 414.691068 -300.591728)
		(end 413.29864 -300.591728)
		(width 0.1016)
		(layer "F.Cu")
		(net "M_E_CPU0_SA_DQ<14>")
	)
	(segment
		(start 413.293052 -300.597316)
		(end 413.275526 -300.597316)
		(width 0.101854)
		(layer "F.Cu")
		(net "M_E_CPU0_SA_DQ<14>")
	)
	(segment
		(start 412.440374 -300.166786)
		(end 410.853382 -300.166786)
		(width 0.20066)
		(layer "F.Cu")
		(net "M_E_CPU0_SA_DQ<14>")
	)
	(segment
		(start 410.853382 -300.166786)
		(end 409.723082 -300.166786)
		(width 0.20066)
		(layer "F.Cu")
		(net "M_E_CPU0_SA_DQ<14>")
	)
	(segment
		(start 415.307526 -300.60138)
		(end 415.297874 -300.591728)
		(width 0.101854)
		(layer "F.Cu")
		(net "M_E_CPU0_SA_DQ<14>")
	)
	(segment
		(start 415.297874 -300.591728)
		(end 414.691068 -300.591728)
		(width 0.101854)
		(layer "F.Cu")
		(net "M_E_CPU0_SA_DQ<14>")
	)
	(segment
		(start 417.07562 -300.166786)
		(end 416.823652 -299.914818)
		(width 0.20066)
		(layer "F.Cu")
		(net "M_E_CPU0_SA_DQ<14>")
	)
	(segment
		(start 416.823652 -299.914818)
		(end 416.439604 -299.914818)
		(width 0.20066)
		(layer "F.Cu")
		(net "M_E_CPU0_SA_DQ<14>")
	)
	(segment
		(start 413.29864 -300.591728)
		(end 413.293052 -300.597316)
		(width 0.1016)
		(layer "F.Cu")
		(net "M_E_CPU0_SA_DQ<14>")
	)
	(segment
		(start 416.205416 -300.40072)
		(end 416.004756 -300.60138)
		(width 0.20066)
		(layer "F.Cu")
		(net "M_E_CPU0_SA_DQ<14>")
	)
	(segment
		(start 412.870904 -300.597316)
		(end 412.440374 -300.166786)
		(width 0.20066)
		(layer "F.Cu")
		(net "M_E_CPU0_SA_DQ<14>")
	)
	(segment
		(start 418.397182 -300.166786)
		(end 417.07562 -300.166786)
		(width 0.20066)
		(layer "F.Cu")
		(net "M_E_CPU0_SA_DQ<14>")
	)
	(segment
		(start 416.205416 -300.149006)
		(end 416.205416 -300.40072)
		(width 0.20066)
		(layer "F.Cu")
		(net "M_E_CPU0_SA_DQ<14>")
	)
	(segment
		(start 413.275526 -300.597316)
		(end 412.870904 -300.597316)
		(width 0.20066)
		(layer "F.Cu")
		(net "M_E_CPU0_SA_DQ<14>")
	)
	(segment
		(start 416.439604 -299.914818)
		(end 416.205416 -300.149006)
		(width 0.20066)
		(layer "F.Cu")
		(net "M_E_CPU0_SA_DQ<14>")
	)
	(segment
		(start 416.004756 -300.60138)
		(end 415.307526 -300.60138)
		(width 0.20066)
		(layer "F.Cu")
		(net "M_E_CPU0_SA_DQ<14>")
	)
	(segment
		(start 406.2984 -299.899578)
		(end 406.13838 -299.739558)
		(width 0.18288)
		(layer "In2.Cu")
		(net "M_E_CPU0_SA_DQ<14>")
	)
	(segment
		(start 387.737858 -271.34058)
		(end 387.235446 -271.34058)
		(width 0.088646)
		(layer "In2.Cu")
		(net "M_E_CPU0_SA_DQ<14>")
	)
	(segment
		(start 395.018006 -278.982678)
		(end 393.826746 -276.106382)
		(width 0.18288)
		(layer "In2.Cu")
		(net "M_E_CPU0_SA_DQ<14>")
	)
	(segment
		(start 387.227064 -271.335754)
		(end 387.212332 -271.327118)
		(width 0.088646)
		(layer "In2.Cu")
		(net "M_E_CPU0_SA_DQ<14>")
	)
	(segment
		(start 404.737316 -292.982904)
		(end 404.278338 -291.87521)
		(width 0.18288)
		(layer "In2.Cu")
		(net "M_E_CPU0_SA_DQ<14>")
	)
	(segment
		(start 388.840472 -271.883886)
		(end 388.281164 -271.883886)
		(width 0.088646)
		(layer "In2.Cu")
		(net "M_E_CPU0_SA_DQ<14>")
	)
	(segment
		(start 406.45842 -300.237652)
		(end 406.2984 -300.077632)
		(width 0.18288)
		(layer "In2.Cu")
		(net "M_E_CPU0_SA_DQ<14>")
	)
	(segment
		(start 399.957036 -287.028382)
		(end 399.287492 -285.411926)
		(width 0.18288)
		(layer "In2.Cu")
		(net "M_E_CPU0_SA_DQ<14>")
	)
	(segment
		(start 409.222194 -300.006766)
		(end 409.222194 -298.870116)
		(width 0.18288)
		(layer "In2.Cu")
		(net "M_E_CPU0_SA_DQ<14>")
	)
	(segment
		(start 405.36749 -294.554148)
		(end 405.36749 -293.613078)
		(width 0.18288)
		(layer "In2.Cu")
		(net "M_E_CPU0_SA_DQ<14>")
	)
	(segment
		(start 407.77414 -299.614844)
		(end 407.151332 -300.237652)
		(width 0.18288)
		(layer "In2.Cu")
		(net "M_E_CPU0_SA_DQ<14>")
	)
	(segment
		(start 409.062174 -298.710096)
		(end 408.225752 -298.710096)
		(width 0.18288)
		(layer "In2.Cu")
		(net "M_E_CPU0_SA_DQ<14>")
	)
	(segment
		(start 399.287492 -285.411926)
		(end 399.287492 -283.252164)
		(width 0.18288)
		(layer "In2.Cu")
		(net "M_E_CPU0_SA_DQ<14>")
	)
	(segment
		(start 408.225752 -298.710096)
		(end 407.77414 -299.161708)
		(width 0.18288)
		(layer "In2.Cu")
		(net "M_E_CPU0_SA_DQ<14>")
	)
	(segment
		(start 385.347464 -271.335754)
		(end 385.332732 -271.327118)
		(width 0.088646)
		(layer "In2.Cu")
		(net "M_E_CPU0_SA_DQ<14>")
	)
	(segment
		(start 387.235446 -271.34058)
		(end 387.227064 -271.335754)
		(width 0.088646)
		(layer "In2.Cu")
		(net "M_E_CPU0_SA_DQ<14>")
	)
	(segment
		(start 388.281164 -271.883886)
		(end 387.737858 -271.34058)
		(width 0.088646)
		(layer "In2.Cu")
		(net "M_E_CPU0_SA_DQ<14>")
	)
	(segment
		(start 405.09825 -299.543216)
		(end 405.09825 -294.823388)
		(width 0.18288)
		(layer "In2.Cu")
		(net "M_E_CPU0_SA_DQ<14>")
	)
	(segment
		(start 409.382214 -300.166786)
		(end 409.222194 -300.006766)
		(width 0.18288)
		(layer "In2.Cu")
		(net "M_E_CPU0_SA_DQ<14>")
	)
	(segment
		(start 404.060152 -291.657024)
		(end 403.68855 -290.759896)
		(width 0.18288)
		(layer "In2.Cu")
		(net "M_E_CPU0_SA_DQ<14>")
	)
	(segment
		(start 403.68855 -290.759896)
		(end 399.957036 -287.028382)
		(width 0.18288)
		(layer "In2.Cu")
		(net "M_E_CPU0_SA_DQ<14>")
	)
	(segment
		(start 405.36749 -293.613078)
		(end 404.737316 -292.982904)
		(width 0.18288)
		(layer "In2.Cu")
		(net "M_E_CPU0_SA_DQ<14>")
	)
	(segment
		(start 404.278338 -291.87521)
		(end 404.060152 -291.657024)
		(width 0.18288)
		(layer "In2.Cu")
		(net "M_E_CPU0_SA_DQ<14>")
	)
	(segment
		(start 407.151332 -300.237652)
		(end 406.45842 -300.237652)
		(width 0.18288)
		(layer "In2.Cu")
		(net "M_E_CPU0_SA_DQ<14>")
	)
	(segment
		(start 407.77414 -299.161708)
		(end 407.77414 -299.614844)
		(width 0.18288)
		(layer "In2.Cu")
		(net "M_E_CPU0_SA_DQ<14>")
	)
	(segment
		(start 409.222194 -298.870116)
		(end 409.062174 -298.710096)
		(width 0.18288)
		(layer "In2.Cu")
		(net "M_E_CPU0_SA_DQ<14>")
	)
	(segment
		(start 389.60425 -271.883886)
		(end 388.840472 -271.883886)
		(width 0.18288)
		(layer "In2.Cu")
		(net "M_E_CPU0_SA_DQ<14>")
	)
	(segment
		(start 383.813812 -271.35201)
		(end 383.185416 -271.825212)
		(width 0.088646)
		(layer "In2.Cu")
		(net "M_E_CPU0_SA_DQ<14>")
	)
	(segment
		(start 399.287492 -283.252164)
		(end 395.018006 -278.982678)
		(width 0.18288)
		(layer "In2.Cu")
		(net "M_E_CPU0_SA_DQ<14>")
	)
	(segment
		(start 383.842514 -271.335754)
		(end 383.813812 -271.35201)
		(width 0.088646)
		(layer "In2.Cu")
		(net "M_E_CPU0_SA_DQ<14>")
	)
	(segment
		(start 405.09825 -294.823388)
		(end 405.36749 -294.554148)
		(width 0.18288)
		(layer "In2.Cu")
		(net "M_E_CPU0_SA_DQ<14>")
	)
	(segment
		(start 406.2984 -300.077632)
		(end 406.2984 -299.899578)
		(width 0.18288)
		(layer "In2.Cu")
		(net "M_E_CPU0_SA_DQ<14>")
	)
	(segment
		(start 409.723082 -300.166786)
		(end 409.382214 -300.166786)
		(width 0.18288)
		(layer "In2.Cu")
		(net "M_E_CPU0_SA_DQ<14>")
	)
	(segment
		(start 393.826746 -276.106382)
		(end 389.60425 -271.883886)
		(width 0.18288)
		(layer "In2.Cu")
		(net "M_E_CPU0_SA_DQ<14>")
	)
	(segment
		(start 386.287264 -271.335754)
		(end 386.272532 -271.327118)
		(width 0.088646)
		(layer "In2.Cu")
		(net "M_E_CPU0_SA_DQ<14>")
	)
	(segment
		(start 406.13838 -299.739558)
		(end 405.294592 -299.739558)
		(width 0.18288)
		(layer "In2.Cu")
		(net "M_E_CPU0_SA_DQ<14>")
	)
	(segment
		(start 384.407664 -271.335754)
		(end 384.40741 -271.335754)
		(width 0.088646)
		(layer "In2.Cu")
		(net "M_E_CPU0_SA_DQ<14>")
	)
	(segment
		(start 405.294592 -299.739558)
		(end 405.09825 -299.543216)
		(width 0.18288)
		(layer "In2.Cu")
		(net "M_E_CPU0_SA_DQ<14>")
	)
	(arc
		(start 387.212332 -271.327118)
		(mid 386.935857 -271.259798)
		(end 386.66166 -271.335754)
		(width 0.088646)
		(layer "In2.Cu")
		(net "M_E_CPU0_SA_DQ<14>")
	)
	(arc
		(start 384.78206 -271.335754)
		(mid 384.594862 -271.385897)
		(end 384.407664 -271.335754)
		(width 0.088646)
		(layer "In2.Cu")
		(net "M_E_CPU0_SA_DQ<14>")
	)
	(arc
		(start 384.40741 -271.335754)
		(mid 384.124962 -271.260071)
		(end 383.842514 -271.335754)
		(width 0.088646)
		(layer "In2.Cu")
		(net "M_E_CPU0_SA_DQ<14>")
	)
	(arc
		(start 385.332732 -271.327118)
		(mid 385.056257 -271.259798)
		(end 384.78206 -271.335754)
		(width 0.088646)
		(layer "In2.Cu")
		(net "M_E_CPU0_SA_DQ<14>")
	)
	(arc
		(start 386.272532 -271.327118)
		(mid 385.996057 -271.259798)
		(end 385.72186 -271.335754)
		(width 0.088646)
		(layer "In2.Cu")
		(net "M_E_CPU0_SA_DQ<14>")
	)
	(arc
		(start 385.72186 -271.335754)
		(mid 385.534662 -271.385897)
		(end 385.347464 -271.335754)
		(width 0.088646)
		(layer "In2.Cu")
		(net "M_E_CPU0_SA_DQ<14>")
	)
	(arc
		(start 386.66166 -271.335754)
		(mid 386.474462 -271.385897)
		(end 386.287264 -271.335754)
		(width 0.088646)
		(layer "In2.Cu")
		(net "M_E_CPU0_SA_DQ<14>")
	)
	(segment
		(start 381.775716 -270.475456)
		(end 381.775716 -271.011142)
		(width 0.20066)
		(layer "F.Cu")
		(net "M_E_CPU0_SA_DQ<13>")
	)
	(segment
		(start 414.29686 -299.316902)
		(end 414.297114 -299.316648)
		(width 0.20066)
		(layer "F.Cu")
		(net "M_E_CPU0_SA_DQ<13>")
	)
	(segment
		(start 412.705296 -299.316902)
		(end 414.29686 -299.316902)
		(width 0.20066)
		(layer "F.Cu")
		(net "M_E_CPU0_SA_DQ<13>")
	)
	(segment
		(start 409.185872 -299.377354)
		(end 409.185872 -299.009816)
		(width 0.20066)
		(layer "F.Cu")
		(net "M_E_CPU0_SA_DQ<13>")
	)
	(segment
		(start 408.274012 -299.316648)
		(end 408.522678 -299.565314)
		(width 0.20066)
		(layer "F.Cu")
		(net "M_E_CPU0_SA_DQ<13>")
	)
	(segment
		(start 411.857444 -298.891706)
		(end 411.863794 -298.885356)
		(width 0.1016)
		(layer "F.Cu")
		(net "M_E_CPU0_SA_DQ<13>")
	)
	(segment
		(start 409.185872 -299.009816)
		(end 409.303982 -298.891706)
		(width 0.20066)
		(layer "F.Cu")
		(net "M_E_CPU0_SA_DQ<13>")
	)
	(segment
		(start 381.775716 -271.011142)
		(end 381.775462 -271.011396)
		(width 0.20066)
		(layer "F.Cu")
		(net "M_E_CPU0_SA_DQ<13>")
	)
	(segment
		(start 412.27375 -298.885356)
		(end 412.705296 -299.316902)
		(width 0.20066)
		(layer "F.Cu")
		(net "M_E_CPU0_SA_DQ<13>")
	)
	(segment
		(start 408.522678 -299.565314)
		(end 408.997912 -299.565314)
		(width 0.20066)
		(layer "F.Cu")
		(net "M_E_CPU0_SA_DQ<13>")
	)
	(segment
		(start 405.623014 -299.316648)
		(end 406.753314 -299.316648)
		(width 0.20066)
		(layer "F.Cu")
		(net "M_E_CPU0_SA_DQ<13>")
	)
	(segment
		(start 408.997912 -299.565314)
		(end 409.185872 -299.377354)
		(width 0.20066)
		(layer "F.Cu")
		(net "M_E_CPU0_SA_DQ<13>")
	)
	(segment
		(start 409.668726 -298.891706)
		(end 411.857444 -298.891706)
		(width 0.1016)
		(layer "F.Cu")
		(net "M_E_CPU0_SA_DQ<13>")
	)
	(segment
		(start 406.753314 -299.316648)
		(end 408.274012 -299.316648)
		(width 0.20066)
		(layer "F.Cu")
		(net "M_E_CPU0_SA_DQ<13>")
	)
	(segment
		(start 409.303982 -298.891706)
		(end 409.64866 -298.891706)
		(width 0.20066)
		(layer "F.Cu")
		(net "M_E_CPU0_SA_DQ<13>")
	)
	(segment
		(start 411.863794 -298.885356)
		(end 412.27375 -298.885356)
		(width 0.20066)
		(layer "F.Cu")
		(net "M_E_CPU0_SA_DQ<13>")
	)
	(segment
		(start 409.64866 -298.891706)
		(end 409.668726 -298.891706)
		(width 0.101854)
		(layer "F.Cu")
		(net "M_E_CPU0_SA_DQ<13>")
	)
	(segment
		(start 386.287264 -270.687038)
		(end 386.272532 -270.695674)
		(width 0.088646)
		(layer "In2.Cu")
		(net "M_E_CPU0_SA_DQ<13>")
	)
	(segment
		(start 406.681178 -298.846494)
		(end 407.03627 -298.846494)
		(width 0.18288)
		(layer "In2.Cu")
		(net "M_E_CPU0_SA_DQ<13>")
	)
	(segment
		(start 384.407664 -270.687038)
		(end 384.392932 -270.695674)
		(width 0.088646)
		(layer "In2.Cu")
		(net "M_E_CPU0_SA_DQ<13>")
	)
	(segment
		(start 405.742394 -299.028358)
		(end 406.166066 -298.604686)
		(width 0.18288)
		(layer "In2.Cu")
		(net "M_E_CPU0_SA_DQ<13>")
	)
	(segment
		(start 385.347464 -270.687038)
		(end 385.332732 -270.695674)
		(width 0.088646)
		(layer "In2.Cu")
		(net "M_E_CPU0_SA_DQ<13>")
	)
	(segment
		(start 404.472902 -291.290248)
		(end 404.140162 -290.486846)
		(width 0.18288)
		(layer "In2.Cu")
		(net "M_E_CPU0_SA_DQ<13>")
	)
	(segment
		(start 406.70734 -295.45153)
		(end 406.90038 -295.25849)
		(width 0.18288)
		(layer "In2.Cu")
		(net "M_E_CPU0_SA_DQ<13>")
	)
	(segment
		(start 405.876252 -293.397178)
		(end 405.181816 -292.702742)
		(width 0.18288)
		(layer "In2.Cu")
		(net "M_E_CPU0_SA_DQ<13>")
	)
	(segment
		(start 406.301956 -297.077638)
		(end 406.108916 -296.884598)
		(width 0.18288)
		(layer "In2.Cu")
		(net "M_E_CPU0_SA_DQ<13>")
	)
	(segment
		(start 405.623014 -299.316648)
		(end 405.742394 -299.028358)
		(width 0.18288)
		(layer "In2.Cu")
		(net "M_E_CPU0_SA_DQ<13>")
	)
	(segment
		(start 405.743156 -296.199814)
		(end 405.743156 -295.619424)
		(width 0.18288)
		(layer "In2.Cu")
		(net "M_E_CPU0_SA_DQ<13>")
	)
	(segment
		(start 382.432814 -271.500854)
		(end 382.426718 -271.497298)
		(width 0.088646)
		(layer "In2.Cu")
		(net "M_E_CPU0_SA_DQ<13>")
	)
	(segment
		(start 406.108916 -296.565574)
		(end 405.743156 -296.199814)
		(width 0.18288)
		(layer "In2.Cu")
		(net "M_E_CPU0_SA_DQ<13>")
	)
	(segment
		(start 383.467864 -270.687038)
		(end 383.458974 -270.692118)
		(width 0.088646)
		(layer "In2.Cu")
		(net "M_E_CPU0_SA_DQ<13>")
	)
	(segment
		(start 382.08839 -271.011396)
		(end 381.775462 -271.011396)
		(width 0.088646)
		(layer "In2.Cu")
		(net "M_E_CPU0_SA_DQ<13>")
	)
	(segment
		(start 399.795492 -283.259276)
		(end 395.30274 -278.766524)
		(width 0.18288)
		(layer "In2.Cu")
		(net "M_E_CPU0_SA_DQ<13>")
	)
	(segment
		(start 405.743156 -295.619424)
		(end 405.91105 -295.45153)
		(width 0.18288)
		(layer "In2.Cu")
		(net "M_E_CPU0_SA_DQ<13>")
	)
	(segment
		(start 394.120116 -275.911056)
		(end 389.650986 -271.441926)
		(width 0.18288)
		(layer "In2.Cu")
		(net "M_E_CPU0_SA_DQ<13>")
	)
	(segment
		(start 407.925778 -297.750992)
		(end 407.925778 -297.477942)
		(width 0.18288)
		(layer "In2.Cu")
		(net "M_E_CPU0_SA_DQ<13>")
	)
	(segment
		(start 406.108916 -296.884598)
		(end 406.108916 -296.565574)
		(width 0.18288)
		(layer "In2.Cu")
		(net "M_E_CPU0_SA_DQ<13>")
	)
	(segment
		(start 405.181816 -292.702742)
		(end 404.68423 -291.501576)
		(width 0.18288)
		(layer "In2.Cu")
		(net "M_E_CPU0_SA_DQ<13>")
	)
	(segment
		(start 389.650986 -271.441926)
		(end 388.840472 -271.441926)
		(width 0.18288)
		(layer "In2.Cu")
		(net "M_E_CPU0_SA_DQ<13>")
	)
	(segment
		(start 400.441414 -286.788098)
		(end 399.795492 -285.228538)
		(width 0.18288)
		(layer "In2.Cu")
		(net "M_E_CPU0_SA_DQ<13>")
	)
	(segment
		(start 404.68423 -291.501576)
		(end 404.472902 -291.290248)
		(width 0.18288)
		(layer "In2.Cu")
		(net "M_E_CPU0_SA_DQ<13>")
	)
	(segment
		(start 407.22931 -298.44746)
		(end 407.925778 -297.750992)
		(width 0.18288)
		(layer "In2.Cu")
		(net "M_E_CPU0_SA_DQ<13>")
	)
	(segment
		(start 406.166066 -298.604686)
		(end 406.43937 -298.604686)
		(width 0.18288)
		(layer "In2.Cu")
		(net "M_E_CPU0_SA_DQ<13>")
	)
	(segment
		(start 405.91105 -295.45153)
		(end 406.70734 -295.45153)
		(width 0.18288)
		(layer "In2.Cu")
		(net "M_E_CPU0_SA_DQ<13>")
	)
	(segment
		(start 387.86054 -271.041622)
		(end 387.126734 -271.041622)
		(width 0.088646)
		(layer "In2.Cu")
		(net "M_E_CPU0_SA_DQ<13>")
	)
	(segment
		(start 405.876252 -294.528494)
		(end 405.876252 -293.397178)
		(width 0.18288)
		(layer "In2.Cu")
		(net "M_E_CPU0_SA_DQ<13>")
	)
	(segment
		(start 404.140162 -290.486846)
		(end 400.441414 -286.788098)
		(width 0.18288)
		(layer "In2.Cu")
		(net "M_E_CPU0_SA_DQ<13>")
	)
	(segment
		(start 387.126734 -271.041622)
		(end 386.837936 -270.752824)
		(width 0.088646)
		(layer "In2.Cu")
		(net "M_E_CPU0_SA_DQ<13>")
	)
	(segment
		(start 407.03627 -298.846494)
		(end 407.22931 -298.653454)
		(width 0.18288)
		(layer "In2.Cu")
		(net "M_E_CPU0_SA_DQ<13>")
	)
	(segment
		(start 382.153922 -271.076928)
		(end 382.08839 -271.011396)
		(width 0.088646)
		(layer "In2.Cu")
		(net "M_E_CPU0_SA_DQ<13>")
	)
	(segment
		(start 383.280412 -271.011396)
		(end 383.280412 -271.02689)
		(width 0.088646)
		(layer "In2.Cu")
		(net "M_E_CPU0_SA_DQ<13>")
	)
	(segment
		(start 406.064466 -294.716708)
		(end 405.876252 -294.528494)
		(width 0.18288)
		(layer "In2.Cu")
		(net "M_E_CPU0_SA_DQ<13>")
	)
	(segment
		(start 407.525474 -297.077638)
		(end 406.301956 -297.077638)
		(width 0.18288)
		(layer "In2.Cu")
		(net "M_E_CPU0_SA_DQ<13>")
	)
	(segment
		(start 395.30274 -278.766524)
		(end 394.120116 -275.911056)
		(width 0.18288)
		(layer "In2.Cu")
		(net "M_E_CPU0_SA_DQ<13>")
	)
	(segment
		(start 399.795492 -285.228538)
		(end 399.795492 -283.259276)
		(width 0.18288)
		(layer "In2.Cu")
		(net "M_E_CPU0_SA_DQ<13>")
	)
	(segment
		(start 406.43937 -298.604686)
		(end 406.681178 -298.846494)
		(width 0.18288)
		(layer "In2.Cu")
		(net "M_E_CPU0_SA_DQ<13>")
	)
	(segment
		(start 388.840472 -271.441926)
		(end 388.260844 -271.441926)
		(width 0.088646)
		(layer "In2.Cu")
		(net "M_E_CPU0_SA_DQ<13>")
	)
	(segment
		(start 406.90038 -295.25849)
		(end 406.90038 -294.88511)
		(width 0.18288)
		(layer "In2.Cu")
		(net "M_E_CPU0_SA_DQ<13>")
	)
	(segment
		(start 407.22931 -298.653454)
		(end 407.22931 -298.44746)
		(width 0.18288)
		(layer "In2.Cu")
		(net "M_E_CPU0_SA_DQ<13>")
	)
	(segment
		(start 406.90038 -294.88511)
		(end 406.731978 -294.716708)
		(width 0.18288)
		(layer "In2.Cu")
		(net "M_E_CPU0_SA_DQ<13>")
	)
	(segment
		(start 382.447546 -271.50949)
		(end 382.432814 -271.500854)
		(width 0.088646)
		(layer "In2.Cu")
		(net "M_E_CPU0_SA_DQ<13>")
	)
	(segment
		(start 388.260844 -271.441926)
		(end 387.86054 -271.041622)
		(width 0.088646)
		(layer "In2.Cu")
		(net "M_E_CPU0_SA_DQ<13>")
	)
	(segment
		(start 407.925778 -297.477942)
		(end 407.525474 -297.077638)
		(width 0.18288)
		(layer "In2.Cu")
		(net "M_E_CPU0_SA_DQ<13>")
	)
	(segment
		(start 406.731978 -294.716708)
		(end 406.064466 -294.716708)
		(width 0.18288)
		(layer "In2.Cu")
		(net "M_E_CPU0_SA_DQ<13>")
	)
	(arc
		(start 385.332732 -270.695674)
		(mid 385.056257 -270.762994)
		(end 384.78206 -270.687038)
		(width 0.088646)
		(layer "In2.Cu")
		(net "M_E_CPU0_SA_DQ<13>")
	)
	(arc
		(start 382.426718 -271.497298)
		(mid 382.241195 -271.318997)
		(end 382.153922 -271.076928)
		(width 0.088646)
		(layer "In2.Cu")
		(net "M_E_CPU0_SA_DQ<13>")
	)
	(arc
		(start 386.837936 -270.752824)
		(mid 386.747034 -270.727333)
		(end 386.66166 -270.687038)
		(width 0.088646)
		(layer "In2.Cu")
		(net "M_E_CPU0_SA_DQ<13>")
	)
	(arc
		(start 385.72186 -270.687038)
		(mid 385.534662 -270.636895)
		(end 385.347464 -270.687038)
		(width 0.088646)
		(layer "In2.Cu")
		(net "M_E_CPU0_SA_DQ<13>")
	)
	(arc
		(start 384.78206 -270.687038)
		(mid 384.594862 -270.636895)
		(end 384.407664 -270.687038)
		(width 0.088646)
		(layer "In2.Cu")
		(net "M_E_CPU0_SA_DQ<13>")
	)
	(arc
		(start 383.458974 -270.692118)
		(mid 383.32806 -270.828478)
		(end 383.280412 -271.011396)
		(width 0.088646)
		(layer "In2.Cu")
		(net "M_E_CPU0_SA_DQ<13>")
	)
	(arc
		(start 382.998218 -271.500854)
		(mid 382.724019 -271.576689)
		(end 382.447546 -271.50949)
		(width 0.088646)
		(layer "In2.Cu")
		(net "M_E_CPU0_SA_DQ<13>")
	)
	(arc
		(start 383.280412 -271.02689)
		(mid 383.201042 -271.300624)
		(end 382.998218 -271.500854)
		(width 0.088646)
		(layer "In2.Cu")
		(net "M_E_CPU0_SA_DQ<13>")
	)
	(arc
		(start 383.84226 -270.687038)
		(mid 383.655062 -270.636895)
		(end 383.467864 -270.687038)
		(width 0.088646)
		(layer "In2.Cu")
		(net "M_E_CPU0_SA_DQ<13>")
	)
	(arc
		(start 386.272532 -270.695674)
		(mid 385.996057 -270.762994)
		(end 385.72186 -270.687038)
		(width 0.088646)
		(layer "In2.Cu")
		(net "M_E_CPU0_SA_DQ<13>")
	)
	(arc
		(start 384.392932 -270.695674)
		(mid 384.116457 -270.762994)
		(end 383.84226 -270.687038)
		(width 0.088646)
		(layer "In2.Cu")
		(net "M_E_CPU0_SA_DQ<13>")
	)
	(arc
		(start 386.66166 -270.687038)
		(mid 386.474462 -270.636895)
		(end 386.287264 -270.687038)
		(width 0.088646)
		(layer "In2.Cu")
		(net "M_E_CPU0_SA_DQ<13>")
	)
	(segment
		(start 408.522678 -301.265336)
		(end 408.997912 -301.265336)
		(width 0.20066)
		(layer "F.Cu")
		(net "M_E_CPU0_SA_DQ<12>")
	)
	(segment
		(start 406.753314 -301.01667)
		(end 408.274012 -301.01667)
		(width 0.20066)
		(layer "F.Cu")
		(net "M_E_CPU0_SA_DQ<12>")
	)
	(segment
		(start 409.69565 -300.591728)
		(end 411.857444 -300.591728)
		(width 0.1016)
		(layer "F.Cu")
		(net "M_E_CPU0_SA_DQ<12>")
	)
	(segment
		(start 414.29686 -301.016924)
		(end 414.297114 -301.01667)
		(width 0.20066)
		(layer "F.Cu")
		(net "M_E_CPU0_SA_DQ<12>")
	)
	(segment
		(start 409.64866 -300.591728)
		(end 409.69565 -300.591728)
		(width 0.101854)
		(layer "F.Cu")
		(net "M_E_CPU0_SA_DQ<12>")
	)
	(segment
		(start 409.185872 -300.709838)
		(end 409.303982 -300.591728)
		(width 0.20066)
		(layer "F.Cu")
		(net "M_E_CPU0_SA_DQ<12>")
	)
	(segment
		(start 408.997912 -301.265336)
		(end 409.185872 -301.077376)
		(width 0.20066)
		(layer "F.Cu")
		(net "M_E_CPU0_SA_DQ<12>")
	)
	(segment
		(start 409.303982 -300.591728)
		(end 409.64866 -300.591728)
		(width 0.20066)
		(layer "F.Cu")
		(net "M_E_CPU0_SA_DQ<12>")
	)
	(segment
		(start 412.705296 -301.016924)
		(end 414.29686 -301.016924)
		(width 0.20066)
		(layer "F.Cu")
		(net "M_E_CPU0_SA_DQ<12>")
	)
	(segment
		(start 409.185872 -301.077376)
		(end 409.185872 -300.709838)
		(width 0.20066)
		(layer "F.Cu")
		(net "M_E_CPU0_SA_DQ<12>")
	)
	(segment
		(start 381.305562 -271.289272)
		(end 381.305816 -271.825212)
		(width 0.20066)
		(layer "F.Cu")
		(net "M_E_CPU0_SA_DQ<12>")
	)
	(segment
		(start 405.623014 -301.01667)
		(end 406.753314 -301.01667)
		(width 0.20066)
		(layer "F.Cu")
		(net "M_E_CPU0_SA_DQ<12>")
	)
	(segment
		(start 408.274012 -301.01667)
		(end 408.522678 -301.265336)
		(width 0.20066)
		(layer "F.Cu")
		(net "M_E_CPU0_SA_DQ<12>")
	)
	(segment
		(start 411.863794 -300.585378)
		(end 412.27375 -300.585378)
		(width 0.20066)
		(layer "F.Cu")
		(net "M_E_CPU0_SA_DQ<12>")
	)
	(segment
		(start 411.857444 -300.591728)
		(end 411.863794 -300.585378)
		(width 0.1016)
		(layer "F.Cu")
		(net "M_E_CPU0_SA_DQ<12>")
	)
	(segment
		(start 412.27375 -300.585378)
		(end 412.705296 -301.016924)
		(width 0.20066)
		(layer "F.Cu")
		(net "M_E_CPU0_SA_DQ<12>")
	)
	(segment
		(start 383.768092 -271.690846)
		(end 383.501646 -272.057876)
		(width 0.088646)
		(layer "In2.Cu")
		(net "M_E_CPU0_SA_DQ<12>")
	)
	(segment
		(start 404.070312 -292.70706)
		(end 403.948392 -292.413182)
		(width 0.18288)
		(layer "In2.Cu")
		(net "M_E_CPU0_SA_DQ<12>")
	)
	(segment
		(start 404.788116 -293.933372)
		(end 404.66645 -293.639748)
		(width 0.18288)
		(layer "In2.Cu")
		(net "M_E_CPU0_SA_DQ<12>")
	)
	(segment
		(start 393.533884 -276.302216)
		(end 389.593074 -272.361406)
		(width 0.18288)
		(layer "In2.Cu")
		(net "M_E_CPU0_SA_DQ<12>")
	)
	(segment
		(start 403.948392 -292.413182)
		(end 403.69617 -292.308534)
		(width 0.18288)
		(layer "In2.Cu")
		(net "M_E_CPU0_SA_DQ<12>")
	)
	(segment
		(start 402.551138 -291.049964)
		(end 402.442934 -290.789106)
		(width 0.18288)
		(layer "In2.Cu")
		(net "M_E_CPU0_SA_DQ<12>")
	)
	(segment
		(start 387.20268 -271.541748)
		(end 387.131814 -271.500854)
		(width 0.088646)
		(layer "In2.Cu")
		(net "M_E_CPU0_SA_DQ<12>")
	)
	(segment
		(start 403.881082 -293.756588)
		(end 403.629114 -293.65194)
		(width 0.18288)
		(layer "In2.Cu")
		(net "M_E_CPU0_SA_DQ<12>")
	)
	(segment
		(start 382.028954 -272.132806)
		(end 381.305816 -271.825212)
		(width 0.088646)
		(layer "In2.Cu")
		(net "M_E_CPU0_SA_DQ<12>")
	)
	(segment
		(start 388.840726 -272.361406)
		(end 388.423404 -272.361406)
		(width 0.088646)
		(layer "In2.Cu")
		(net "M_E_CPU0_SA_DQ<12>")
	)
	(segment
		(start 399.491962 -287.288478)
		(end 398.779492 -285.568644)
		(width 0.18288)
		(layer "In2.Cu")
		(net "M_E_CPU0_SA_DQ<12>")
	)
	(segment
		(start 404.235158 -295.115488)
		(end 404.045928 -294.65905)
		(width 0.18288)
		(layer "In2.Cu")
		(net "M_E_CPU0_SA_DQ<12>")
	)
	(segment
		(start 382.058418 -272.14957)
		(end 382.058164 -272.149824)
		(width 0.088646)
		(layer "In2.Cu")
		(net "M_E_CPU0_SA_DQ<12>")
	)
	(segment
		(start 403.38375 -291.467286)
		(end 403.26183 -291.173408)
		(width 0.18288)
		(layer "In2.Cu")
		(net "M_E_CPU0_SA_DQ<12>")
	)
	(segment
		(start 403.965664 -292.959028)
		(end 404.070312 -292.70706)
		(width 0.18288)
		(layer "In2.Cu")
		(net "M_E_CPU0_SA_DQ<12>")
	)
	(segment
		(start 383.938018 -271.500854)
		(end 383.937764 -271.501108)
		(width 0.088646)
		(layer "In2.Cu")
		(net "M_E_CPU0_SA_DQ<12>")
	)
	(segment
		(start 404.150576 -294.407082)
		(end 404.683976 -294.186102)
		(width 0.18288)
		(layer "In2.Cu")
		(net "M_E_CPU0_SA_DQ<12>")
	)
	(segment
		(start 404.586186 -295.466516)
		(end 404.235158 -295.115488)
		(width 0.18288)
		(layer "In2.Cu")
		(net "M_E_CPU0_SA_DQ<12>")
	)
	(segment
		(start 403.279102 -291.719254)
		(end 403.38375 -291.467286)
		(width 0.18288)
		(layer "In2.Cu")
		(net "M_E_CPU0_SA_DQ<12>")
	)
	(segment
		(start 403.342094 -292.4556)
		(end 403.090126 -292.350952)
		(width 0.18288)
		(layer "In2.Cu")
		(net "M_E_CPU0_SA_DQ<12>")
	)
	(segment
		(start 403.629114 -293.65194)
		(end 403.507194 -293.357808)
		(width 0.18288)
		(layer "In2.Cu")
		(net "M_E_CPU0_SA_DQ<12>")
	)
	(segment
		(start 398.779492 -283.239972)
		(end 394.730224 -279.190704)
		(width 0.18288)
		(layer "In2.Cu")
		(net "M_E_CPU0_SA_DQ<12>")
	)
	(segment
		(start 403.072346 -291.805106)
		(end 403.279102 -291.719254)
		(width 0.18288)
		(layer "In2.Cu")
		(net "M_E_CPU0_SA_DQ<12>")
	)
	(segment
		(start 405.623014 -301.01667)
		(end 405.623014 -300.749462)
		(width 0.18288)
		(layer "In2.Cu")
		(net "M_E_CPU0_SA_DQ<12>")
	)
	(segment
		(start 403.26183 -291.173408)
		(end 403.009608 -291.06876)
		(width 0.18288)
		(layer "In2.Cu")
		(net "M_E_CPU0_SA_DQ<12>")
	)
	(segment
		(start 394.730224 -279.190704)
		(end 393.533884 -276.302216)
		(width 0.18288)
		(layer "In2.Cu")
		(net "M_E_CPU0_SA_DQ<12>")
	)
	(segment
		(start 386.206746 -271.50949)
		(end 386.192014 -271.500854)
		(width 0.088646)
		(layer "In2.Cu")
		(net "M_E_CPU0_SA_DQ<12>")
	)
	(segment
		(start 402.968206 -292.05682)
		(end 403.072346 -291.805106)
		(width 0.18288)
		(layer "In2.Cu")
		(net "M_E_CPU0_SA_DQ<12>")
	)
	(segment
		(start 403.611334 -293.106094)
		(end 403.965664 -292.959028)
		(width 0.18288)
		(layer "In2.Cu")
		(net "M_E_CPU0_SA_DQ<12>")
	)
	(segment
		(start 405.030686 -300.560994)
		(end 404.863046 -300.393354)
		(width 0.18288)
		(layer "In2.Cu")
		(net "M_E_CPU0_SA_DQ<12>")
	)
	(segment
		(start 404.683976 -294.186102)
		(end 404.788116 -293.933372)
		(width 0.18288)
		(layer "In2.Cu")
		(net "M_E_CPU0_SA_DQ<12>")
	)
	(segment
		(start 403.69617 -292.308534)
		(end 403.342094 -292.4556)
		(width 0.18288)
		(layer "In2.Cu")
		(net "M_E_CPU0_SA_DQ<12>")
	)
	(segment
		(start 403.090126 -292.350952)
		(end 402.968206 -292.05682)
		(width 0.18288)
		(layer "In2.Cu")
		(net "M_E_CPU0_SA_DQ<12>")
	)
	(segment
		(start 385.266946 -271.50949)
		(end 385.252214 -271.500854)
		(width 0.088646)
		(layer "In2.Cu")
		(net "M_E_CPU0_SA_DQ<12>")
	)
	(segment
		(start 402.442934 -290.23945)
		(end 399.491962 -287.288478)
		(width 0.18288)
		(layer "In2.Cu")
		(net "M_E_CPU0_SA_DQ<12>")
	)
	(segment
		(start 404.66645 -293.639748)
		(end 404.413974 -293.535354)
		(width 0.18288)
		(layer "In2.Cu")
		(net "M_E_CPU0_SA_DQ<12>")
	)
	(segment
		(start 382.433068 -272.14957)
		(end 382.432814 -272.14957)
		(width 0.088646)
		(layer "In2.Cu")
		(net "M_E_CPU0_SA_DQ<12>")
	)
	(segment
		(start 389.593074 -272.361406)
		(end 388.840726 -272.361406)
		(width 0.18288)
		(layer "In2.Cu")
		(net "M_E_CPU0_SA_DQ<12>")
	)
	(segment
		(start 382.058164 -272.149824)
		(end 382.028954 -272.132806)
		(width 0.088646)
		(layer "In2.Cu")
		(net "M_E_CPU0_SA_DQ<12>")
	)
	(segment
		(start 404.586186 -299.724826)
		(end 404.586186 -295.466516)
		(width 0.18288)
		(layer "In2.Cu")
		(net "M_E_CPU0_SA_DQ<12>")
	)
	(segment
		(start 402.803106 -291.154612)
		(end 402.551138 -291.049964)
		(width 0.18288)
		(layer "In2.Cu")
		(net "M_E_CPU0_SA_DQ<12>")
	)
	(segment
		(start 403.507194 -293.357808)
		(end 403.611334 -293.106094)
		(width 0.18288)
		(layer "In2.Cu")
		(net "M_E_CPU0_SA_DQ<12>")
	)
	(segment
		(start 383.372614 -272.149316)
		(end 383.372614 -272.14957)
		(width 0.088646)
		(layer "In2.Cu")
		(net "M_E_CPU0_SA_DQ<12>")
	)
	(segment
		(start 403.009608 -291.06876)
		(end 402.803106 -291.154612)
		(width 0.18288)
		(layer "In2.Cu")
		(net "M_E_CPU0_SA_DQ<12>")
	)
	(segment
		(start 405.434546 -300.560994)
		(end 405.030686 -300.560994)
		(width 0.18288)
		(layer "In2.Cu")
		(net "M_E_CPU0_SA_DQ<12>")
	)
	(segment
		(start 404.863046 -300.393354)
		(end 404.586186 -299.724826)
		(width 0.18288)
		(layer "In2.Cu")
		(net "M_E_CPU0_SA_DQ<12>")
	)
	(segment
		(start 398.779492 -285.568644)
		(end 398.779492 -283.239972)
		(width 0.18288)
		(layer "In2.Cu")
		(net "M_E_CPU0_SA_DQ<12>")
	)
	(segment
		(start 384.312668 -271.500854)
		(end 384.312414 -271.500854)
		(width 0.088646)
		(layer "In2.Cu")
		(net "M_E_CPU0_SA_DQ<12>")
	)
	(segment
		(start 388.423404 -272.361406)
		(end 387.602984 -271.540986)
		(width 0.088646)
		(layer "In2.Cu")
		(net "M_E_CPU0_SA_DQ<12>")
	)
	(segment
		(start 387.602984 -271.540986)
		(end 387.209284 -271.540986)
		(width 0.088646)
		(layer "In2.Cu")
		(net "M_E_CPU0_SA_DQ<12>")
	)
	(segment
		(start 385.252214 -271.500854)
		(end 385.25196 -271.500854)
		(width 0.088646)
		(layer "In2.Cu")
		(net "M_E_CPU0_SA_DQ<12>")
	)
	(segment
		(start 387.209284 -271.540986)
		(end 387.20268 -271.541748)
		(width 0.088646)
		(layer "In2.Cu")
		(net "M_E_CPU0_SA_DQ<12>")
	)
	(segment
		(start 402.442934 -290.789106)
		(end 402.442934 -290.23945)
		(width 0.18288)
		(layer "In2.Cu")
		(net "M_E_CPU0_SA_DQ<12>")
	)
	(segment
		(start 404.413974 -293.535354)
		(end 403.881082 -293.756588)
		(width 0.18288)
		(layer "In2.Cu")
		(net "M_E_CPU0_SA_DQ<12>")
	)
	(segment
		(start 405.623014 -300.749462)
		(end 405.434546 -300.560994)
		(width 0.18288)
		(layer "In2.Cu")
		(net "M_E_CPU0_SA_DQ<12>")
	)
	(segment
		(start 404.045928 -294.65905)
		(end 404.150576 -294.407082)
		(width 0.18288)
		(layer "In2.Cu")
		(net "M_E_CPU0_SA_DQ<12>")
	)
	(arc
		(start 383.484374 -272.07591)
		(mid 383.429615 -272.11432)
		(end 383.372614 -272.149316)
		(width 0.088646)
		(layer "In2.Cu")
		(net "M_E_CPU0_SA_DQ<12>")
	)
	(arc
		(start 385.25196 -271.500854)
		(mid 385.064906 -271.450804)
		(end 384.877818 -271.500854)
		(width 0.088646)
		(layer "In2.Cu")
		(net "M_E_CPU0_SA_DQ<12>")
	)
	(arc
		(start 385.817618 -271.500854)
		(mid 385.543419 -271.576689)
		(end 385.266946 -271.50949)
		(width 0.088646)
		(layer "In2.Cu")
		(net "M_E_CPU0_SA_DQ<12>")
	)
	(arc
		(start 387.131814 -271.500854)
		(mid 386.944616 -271.450711)
		(end 386.757418 -271.500854)
		(width 0.088646)
		(layer "In2.Cu")
		(net "M_E_CPU0_SA_DQ<12>")
	)
	(arc
		(start 383.794762 -271.64792)
		(mid 383.782148 -271.669831)
		(end 383.768092 -271.690846)
		(width 0.088646)
		(layer "In2.Cu")
		(net "M_E_CPU0_SA_DQ<12>")
	)
	(arc
		(start 386.757418 -271.500854)
		(mid 386.483219 -271.576689)
		(end 386.206746 -271.50949)
		(width 0.088646)
		(layer "In2.Cu")
		(net "M_E_CPU0_SA_DQ<12>")
	)
	(arc
		(start 384.312414 -271.500854)
		(mid 384.125216 -271.450711)
		(end 383.938018 -271.500854)
		(width 0.088646)
		(layer "In2.Cu")
		(net "M_E_CPU0_SA_DQ<12>")
	)
	(arc
		(start 383.372614 -272.14957)
		(mid 383.185416 -272.199713)
		(end 382.998218 -272.14957)
		(width 0.088646)
		(layer "In2.Cu")
		(net "M_E_CPU0_SA_DQ<12>")
	)
	(arc
		(start 382.432814 -272.14957)
		(mid 382.245616 -272.199713)
		(end 382.058418 -272.14957)
		(width 0.088646)
		(layer "In2.Cu")
		(net "M_E_CPU0_SA_DQ<12>")
	)
	(arc
		(start 383.937764 -271.501108)
		(mid 383.856026 -271.564542)
		(end 383.794762 -271.64792)
		(width 0.088646)
		(layer "In2.Cu")
		(net "M_E_CPU0_SA_DQ<12>")
	)
	(arc
		(start 386.192014 -271.500854)
		(mid 386.004816 -271.450711)
		(end 385.817618 -271.500854)
		(width 0.088646)
		(layer "In2.Cu")
		(net "M_E_CPU0_SA_DQ<12>")
	)
	(arc
		(start 382.998218 -272.14957)
		(mid 382.71566 -272.073921)
		(end 382.433068 -272.14957)
		(width 0.088646)
		(layer "In2.Cu")
		(net "M_E_CPU0_SA_DQ<12>")
	)
	(arc
		(start 383.501646 -272.057876)
		(mid 383.493686 -272.06754)
		(end 383.484374 -272.07591)
		(width 0.088646)
		(layer "In2.Cu")
		(net "M_E_CPU0_SA_DQ<12>")
	)
	(arc
		(start 384.877818 -271.500854)
		(mid 384.59526 -271.576503)
		(end 384.312668 -271.500854)
		(width 0.088646)
		(layer "In2.Cu")
		(net "M_E_CPU0_SA_DQ<12>")
	)
	(segment
		(start 410.853382 -304.416714)
		(end 409.723082 -304.416714)
		(width 0.20066)
		(layer "F.Cu")
		(net "M_E_CPU0_SA_DQ<11>")
	)
	(segment
		(start 416.205416 -304.398934)
		(end 416.205416 -304.649378)
		(width 0.20066)
		(layer "F.Cu")
		(net "M_E_CPU0_SA_DQ<11>")
	)
	(segment
		(start 416.439604 -304.164746)
		(end 416.205416 -304.398934)
		(width 0.20066)
		(layer "F.Cu")
		(net "M_E_CPU0_SA_DQ<11>")
	)
	(segment
		(start 383.185162 -273.452844)
		(end 383.185416 -273.453098)
		(width 0.20066)
		(layer "F.Cu")
		(net "M_E_CPU0_SA_DQ<11>")
	)
	(segment
		(start 383.185162 -272.917158)
		(end 383.185162 -273.452844)
		(width 0.20066)
		(layer "F.Cu")
		(net "M_E_CPU0_SA_DQ<11>")
	)
	(segment
		(start 418.397182 -304.416714)
		(end 417.07562 -304.416714)
		(width 0.20066)
		(layer "F.Cu")
		(net "M_E_CPU0_SA_DQ<11>")
	)
	(segment
		(start 415.296096 -304.841656)
		(end 414.495742 -304.841656)
		(width 0.101854)
		(layer "F.Cu")
		(net "M_E_CPU0_SA_DQ<11>")
	)
	(segment
		(start 412.96844 -304.852324)
		(end 412.53283 -304.416714)
		(width 0.20066)
		(layer "F.Cu")
		(net "M_E_CPU0_SA_DQ<11>")
	)
	(segment
		(start 413.30372 -304.841656)
		(end 413.293052 -304.852324)
		(width 0.1016)
		(layer "F.Cu")
		(net "M_E_CPU0_SA_DQ<11>")
	)
	(segment
		(start 416.823652 -304.164746)
		(end 416.439604 -304.164746)
		(width 0.20066)
		(layer "F.Cu")
		(net "M_E_CPU0_SA_DQ<11>")
	)
	(segment
		(start 415.307526 -304.853086)
		(end 415.296096 -304.841656)
		(width 0.101854)
		(layer "F.Cu")
		(net "M_E_CPU0_SA_DQ<11>")
	)
	(segment
		(start 416.205416 -304.649378)
		(end 416.001708 -304.853086)
		(width 0.20066)
		(layer "F.Cu")
		(net "M_E_CPU0_SA_DQ<11>")
	)
	(segment
		(start 417.07562 -304.416714)
		(end 416.823652 -304.164746)
		(width 0.20066)
		(layer "F.Cu")
		(net "M_E_CPU0_SA_DQ<11>")
	)
	(segment
		(start 413.293052 -304.852324)
		(end 413.275526 -304.852324)
		(width 0.101854)
		(layer "F.Cu")
		(net "M_E_CPU0_SA_DQ<11>")
	)
	(segment
		(start 416.001708 -304.853086)
		(end 415.307526 -304.853086)
		(width 0.20066)
		(layer "F.Cu")
		(net "M_E_CPU0_SA_DQ<11>")
	)
	(segment
		(start 413.275526 -304.852324)
		(end 412.96844 -304.852324)
		(width 0.20066)
		(layer "F.Cu")
		(net "M_E_CPU0_SA_DQ<11>")
	)
	(segment
		(start 412.53283 -304.416714)
		(end 410.853382 -304.416714)
		(width 0.20066)
		(layer "F.Cu")
		(net "M_E_CPU0_SA_DQ<11>")
	)
	(segment
		(start 414.495742 -304.841656)
		(end 413.30372 -304.841656)
		(width 0.1016)
		(layer "F.Cu")
		(net "M_E_CPU0_SA_DQ<11>")
	)
	(segment
		(start 408.497786 -303.928018)
		(end 407.70429 -303.928018)
		(width 0.18288)
		(layer "In2.Cu")
		(net "M_E_CPU0_SA_DQ<11>")
	)
	(segment
		(start 383.909824 -273.7612)
		(end 383.185416 -273.453098)
		(width 0.088646)
		(layer "In2.Cu")
		(net "M_E_CPU0_SA_DQ<11>")
	)
	(segment
		(start 408.986482 -304.416714)
		(end 408.497786 -303.928018)
		(width 0.18288)
		(layer "In2.Cu")
		(net "M_E_CPU0_SA_DQ<11>")
	)
	(segment
		(start 396.492222 -287.720278)
		(end 396.492222 -283.440378)
		(width 0.18288)
		(layer "In2.Cu")
		(net "M_E_CPU0_SA_DQ<11>")
	)
	(segment
		(start 406.325832 -304.450496)
		(end 405.86787 -303.992534)
		(width 0.18288)
		(layer "In2.Cu")
		(net "M_E_CPU0_SA_DQ<11>")
	)
	(segment
		(start 388.840726 -274.355306)
		(end 387.862064 -274.355306)
		(width 0.088646)
		(layer "In2.Cu")
		(net "M_E_CPU0_SA_DQ<11>")
	)
	(segment
		(start 402.105622 -301.340266)
		(end 402.105622 -296.314114)
		(width 0.18288)
		(layer "In2.Cu")
		(net "M_E_CPU0_SA_DQ<11>")
	)
	(segment
		(start 403.269196 -302.67656)
		(end 403.269196 -302.50384)
		(width 0.18288)
		(layer "In2.Cu")
		(net "M_E_CPU0_SA_DQ<11>")
	)
	(segment
		(start 387.862064 -274.355306)
		(end 387.335014 -273.828256)
		(width 0.088646)
		(layer "In2.Cu")
		(net "M_E_CPU0_SA_DQ<11>")
	)
	(segment
		(start 402.105622 -296.314114)
		(end 399.998438 -291.226494)
		(width 0.18288)
		(layer "In2.Cu")
		(net "M_E_CPU0_SA_DQ<11>")
	)
	(segment
		(start 389.202168 -274.355306)
		(end 388.840726 -274.355306)
		(width 0.18288)
		(layer "In2.Cu")
		(net "M_E_CPU0_SA_DQ<11>")
	)
	(segment
		(start 405.28621 -303.992534)
		(end 405.094694 -303.801018)
		(width 0.18288)
		(layer "In2.Cu")
		(net "M_E_CPU0_SA_DQ<11>")
	)
	(segment
		(start 403.269196 -302.50384)
		(end 402.105622 -301.340266)
		(width 0.18288)
		(layer "In2.Cu")
		(net "M_E_CPU0_SA_DQ<11>")
	)
	(segment
		(start 396.492222 -283.440378)
		(end 393.389358 -280.337514)
		(width 0.18288)
		(layer "In2.Cu")
		(net "M_E_CPU0_SA_DQ<11>")
	)
	(segment
		(start 392.119866 -277.273004)
		(end 389.202168 -274.355306)
		(width 0.18288)
		(layer "In2.Cu")
		(net "M_E_CPU0_SA_DQ<11>")
	)
	(segment
		(start 383.937764 -273.777456)
		(end 383.909824 -273.7612)
		(width 0.088646)
		(layer "In2.Cu")
		(net "M_E_CPU0_SA_DQ<11>")
	)
	(segment
		(start 405.094694 -303.801018)
		(end 404.393654 -303.801018)
		(width 0.18288)
		(layer "In2.Cu")
		(net "M_E_CPU0_SA_DQ<11>")
	)
	(segment
		(start 407.70429 -303.928018)
		(end 407.181812 -304.450496)
		(width 0.18288)
		(layer "In2.Cu")
		(net "M_E_CPU0_SA_DQ<11>")
	)
	(segment
		(start 409.723082 -304.416714)
		(end 408.986482 -304.416714)
		(width 0.18288)
		(layer "In2.Cu")
		(net "M_E_CPU0_SA_DQ<11>")
	)
	(segment
		(start 399.998438 -291.226494)
		(end 396.492222 -287.720278)
		(width 0.18288)
		(layer "In2.Cu")
		(net "M_E_CPU0_SA_DQ<11>")
	)
	(segment
		(start 405.86787 -303.992534)
		(end 405.28621 -303.992534)
		(width 0.18288)
		(layer "In2.Cu")
		(net "M_E_CPU0_SA_DQ<11>")
	)
	(segment
		(start 407.181812 -304.450496)
		(end 406.325832 -304.450496)
		(width 0.18288)
		(layer "In2.Cu")
		(net "M_E_CPU0_SA_DQ<11>")
	)
	(segment
		(start 393.389358 -280.337514)
		(end 392.119866 -277.273004)
		(width 0.18288)
		(layer "In2.Cu")
		(net "M_E_CPU0_SA_DQ<11>")
	)
	(segment
		(start 404.393654 -303.801018)
		(end 403.269196 -302.67656)
		(width 0.18288)
		(layer "In2.Cu")
		(net "M_E_CPU0_SA_DQ<11>")
	)
	(segment
		(start 387.335014 -273.828256)
		(end 386.944616 -273.828256)
		(width 0.088646)
		(layer "In2.Cu")
		(net "M_E_CPU0_SA_DQ<11>")
	)
	(arc
		(start 386.944616 -273.828256)
		(mid 386.847546 -273.815199)
		(end 386.757164 -273.777456)
		(width 0.088646)
		(layer "In2.Cu")
		(net "M_E_CPU0_SA_DQ<11>")
	)
	(arc
		(start 385.25196 -273.777456)
		(mid 385.064762 -273.827599)
		(end 384.877564 -273.777456)
		(width 0.088646)
		(layer "In2.Cu")
		(net "M_E_CPU0_SA_DQ<11>")
	)
	(arc
		(start 384.31216 -273.777456)
		(mid 384.124962 -273.827599)
		(end 383.937764 -273.777456)
		(width 0.088646)
		(layer "In2.Cu")
		(net "M_E_CPU0_SA_DQ<11>")
	)
	(arc
		(start 386.757164 -273.777456)
		(mid 386.474462 -273.70168)
		(end 386.19176 -273.777456)
		(width 0.088646)
		(layer "In2.Cu")
		(net "M_E_CPU0_SA_DQ<11>")
	)
	(arc
		(start 386.19176 -273.777456)
		(mid 386.004562 -273.827599)
		(end 385.817364 -273.777456)
		(width 0.088646)
		(layer "In2.Cu")
		(net "M_E_CPU0_SA_DQ<11>")
	)
	(arc
		(start 385.817364 -273.777456)
		(mid 385.534662 -273.70168)
		(end 385.25196 -273.777456)
		(width 0.088646)
		(layer "In2.Cu")
		(net "M_E_CPU0_SA_DQ<11>")
	)
	(arc
		(start 384.877564 -273.777456)
		(mid 384.594862 -273.70168)
		(end 384.31216 -273.777456)
		(width 0.088646)
		(layer "In2.Cu")
		(net "M_E_CPU0_SA_DQ<11>")
	)
	(segment
		(start 418.397182 -306.116736)
		(end 417.07562 -306.116736)
		(width 0.20066)
		(layer "F.Cu")
		(net "M_E_CPU0_SA_DQ<10>")
	)
	(segment
		(start 415.295842 -306.541678)
		(end 414.659572 -306.541678)
		(width 0.101854)
		(layer "F.Cu")
		(net "M_E_CPU0_SA_DQ<10>")
	)
	(segment
		(start 412.918148 -306.550822)
		(end 412.484062 -306.116736)
		(width 0.20066)
		(layer "F.Cu")
		(net "M_E_CPU0_SA_DQ<10>")
	)
	(segment
		(start 382.715516 -274.26666)
		(end 382.715262 -274.266914)
		(width 0.20066)
		(layer "F.Cu")
		(net "M_E_CPU0_SA_DQ<10>")
	)
	(segment
		(start 416.205416 -306.353718)
		(end 416.005772 -306.553362)
		(width 0.20066)
		(layer "F.Cu")
		(net "M_E_CPU0_SA_DQ<10>")
	)
	(segment
		(start 413.302196 -306.541678)
		(end 413.293052 -306.550822)
		(width 0.1016)
		(layer "F.Cu")
		(net "M_E_CPU0_SA_DQ<10>")
	)
	(segment
		(start 412.484062 -306.116736)
		(end 410.853382 -306.116736)
		(width 0.20066)
		(layer "F.Cu")
		(net "M_E_CPU0_SA_DQ<10>")
	)
	(segment
		(start 410.853382 -306.116736)
		(end 409.723082 -306.116736)
		(width 0.20066)
		(layer "F.Cu")
		(net "M_E_CPU0_SA_DQ<10>")
	)
	(segment
		(start 416.439604 -305.864768)
		(end 416.205416 -306.098956)
		(width 0.20066)
		(layer "F.Cu")
		(net "M_E_CPU0_SA_DQ<10>")
	)
	(segment
		(start 417.07562 -306.116736)
		(end 416.823652 -305.864768)
		(width 0.20066)
		(layer "F.Cu")
		(net "M_E_CPU0_SA_DQ<10>")
	)
	(segment
		(start 413.293052 -306.550822)
		(end 413.275526 -306.550822)
		(width 0.101854)
		(layer "F.Cu")
		(net "M_E_CPU0_SA_DQ<10>")
	)
	(segment
		(start 414.659572 -306.541678)
		(end 413.302196 -306.541678)
		(width 0.1016)
		(layer "F.Cu")
		(net "M_E_CPU0_SA_DQ<10>")
	)
	(segment
		(start 413.275526 -306.550822)
		(end 412.918148 -306.550822)
		(width 0.20066)
		(layer "F.Cu")
		(net "M_E_CPU0_SA_DQ<10>")
	)
	(segment
		(start 416.005772 -306.553362)
		(end 415.307526 -306.553362)
		(width 0.20066)
		(layer "F.Cu")
		(net "M_E_CPU0_SA_DQ<10>")
	)
	(segment
		(start 415.307526 -306.553362)
		(end 415.295842 -306.541678)
		(width 0.101854)
		(layer "F.Cu")
		(net "M_E_CPU0_SA_DQ<10>")
	)
	(segment
		(start 416.823652 -305.864768)
		(end 416.439604 -305.864768)
		(width 0.20066)
		(layer "F.Cu")
		(net "M_E_CPU0_SA_DQ<10>")
	)
	(segment
		(start 382.715516 -273.730974)
		(end 382.715516 -274.26666)
		(width 0.20066)
		(layer "F.Cu")
		(net "M_E_CPU0_SA_DQ<10>")
	)
	(segment
		(start 416.205416 -306.098956)
		(end 416.205416 -306.353718)
		(width 0.20066)
		(layer "F.Cu")
		(net "M_E_CPU0_SA_DQ<10>")
	)
	(segment
		(start 409.723082 -306.116736)
		(end 408.977338 -305.807872)
		(width 0.18288)
		(layer "In2.Cu")
		(net "M_E_CPU0_SA_DQ<10>")
	)
	(segment
		(start 395.828012 -288.838132)
		(end 395.476222 -288.486342)
		(width 0.18288)
		(layer "In2.Cu")
		(net "M_E_CPU0_SA_DQ<10>")
	)
	(segment
		(start 395.476222 -283.40177)
		(end 392.80338 -280.728928)
		(width 0.18288)
		(layer "In2.Cu")
		(net "M_E_CPU0_SA_DQ<10>")
	)
	(segment
		(start 396.133828 -288.838132)
		(end 395.828012 -288.838132)
		(width 0.18288)
		(layer "In2.Cu")
		(net "M_E_CPU0_SA_DQ<10>")
	)
	(segment
		(start 395.476222 -288.486342)
		(end 395.476222 -283.40177)
		(width 0.18288)
		(layer "In2.Cu")
		(net "M_E_CPU0_SA_DQ<10>")
	)
	(segment
		(start 405.321516 -305.693572)
		(end 404.466044 -304.8381)
		(width 0.18288)
		(layer "In2.Cu")
		(net "M_E_CPU0_SA_DQ<10>")
	)
	(segment
		(start 400.84883 -301.744634)
		(end 400.84883 -296.726864)
		(width 0.18288)
		(layer "In2.Cu")
		(net "M_E_CPU0_SA_DQ<10>")
	)
	(segment
		(start 392.80338 -280.728928)
		(end 391.55751 -277.721568)
		(width 0.18288)
		(layer "In2.Cu")
		(net "M_E_CPU0_SA_DQ<10>")
	)
	(segment
		(start 384.407664 -274.591272)
		(end 384.392932 -274.582636)
		(width 0.088646)
		(layer "In2.Cu")
		(net "M_E_CPU0_SA_DQ<10>")
	)
	(segment
		(start 389.144256 -275.308314)
		(end 388.840726 -275.308314)
		(width 0.18288)
		(layer "In2.Cu")
		(net "M_E_CPU0_SA_DQ<10>")
	)
	(segment
		(start 382.528064 -274.591272)
		(end 382.519174 -274.586192)
		(width 0.088646)
		(layer "In2.Cu")
		(net "M_E_CPU0_SA_DQ<10>")
	)
	(segment
		(start 408.977338 -305.807872)
		(end 408.640534 -305.471068)
		(width 0.18288)
		(layer "In2.Cu")
		(net "M_E_CPU0_SA_DQ<10>")
	)
	(segment
		(start 382.402334 -274.266914)
		(end 382.715262 -274.266914)
		(width 0.088646)
		(layer "In2.Cu")
		(net "M_E_CPU0_SA_DQ<10>")
	)
	(segment
		(start 383.467864 -274.591272)
		(end 383.453132 -274.582636)
		(width 0.088646)
		(layer "In2.Cu")
		(net "M_E_CPU0_SA_DQ<10>")
	)
	(segment
		(start 385.347464 -274.591272)
		(end 385.332732 -274.582636)
		(width 0.088646)
		(layer "In2.Cu")
		(net "M_E_CPU0_SA_DQ<10>")
	)
	(segment
		(start 403.942296 -304.8381)
		(end 400.84883 -301.744634)
		(width 0.18288)
		(layer "In2.Cu")
		(net "M_E_CPU0_SA_DQ<10>")
	)
	(segment
		(start 404.466044 -304.8381)
		(end 403.942296 -304.8381)
		(width 0.18288)
		(layer "In2.Cu")
		(net "M_E_CPU0_SA_DQ<10>")
	)
	(segment
		(start 407.836878 -305.471068)
		(end 407.614374 -305.693572)
		(width 0.18288)
		(layer "In2.Cu")
		(net "M_E_CPU0_SA_DQ<10>")
	)
	(segment
		(start 388.840726 -275.308314)
		(end 387.972046 -275.308314)
		(width 0.088646)
		(layer "In2.Cu")
		(net "M_E_CPU0_SA_DQ<10>")
	)
	(segment
		(start 398.604486 -291.30879)
		(end 396.133828 -288.838132)
		(width 0.18288)
		(layer "In2.Cu")
		(net "M_E_CPU0_SA_DQ<10>")
	)
	(segment
		(start 407.614374 -305.693572)
		(end 405.321516 -305.693572)
		(width 0.18288)
		(layer "In2.Cu")
		(net "M_E_CPU0_SA_DQ<10>")
	)
	(segment
		(start 391.55751 -277.721568)
		(end 389.144256 -275.308314)
		(width 0.18288)
		(layer "In2.Cu")
		(net "M_E_CPU0_SA_DQ<10>")
	)
	(segment
		(start 387.972046 -275.308314)
		(end 387.344666 -274.680934)
		(width 0.088646)
		(layer "In2.Cu")
		(net "M_E_CPU0_SA_DQ<10>")
	)
	(segment
		(start 408.640534 -305.471068)
		(end 407.836878 -305.471068)
		(width 0.18288)
		(layer "In2.Cu")
		(net "M_E_CPU0_SA_DQ<10>")
	)
	(segment
		(start 400.84883 -296.726864)
		(end 398.604486 -291.30879)
		(width 0.18288)
		(layer "In2.Cu")
		(net "M_E_CPU0_SA_DQ<10>")
	)
	(segment
		(start 386.287264 -274.591272)
		(end 386.272532 -274.582636)
		(width 0.088646)
		(layer "In2.Cu")
		(net "M_E_CPU0_SA_DQ<10>")
	)
	(segment
		(start 382.345184 -274.324064)
		(end 382.402334 -274.266914)
		(width 0.088646)
		(layer "In2.Cu")
		(net "M_E_CPU0_SA_DQ<10>")
	)
	(arc
		(start 386.272532 -274.582636)
		(mid 385.996091 -274.51547)
		(end 385.72186 -274.591272)
		(width 0.088646)
		(layer "In2.Cu")
		(net "M_E_CPU0_SA_DQ<10>")
	)
	(arc
		(start 386.66166 -274.591272)
		(mid 386.474462 -274.641415)
		(end 386.287264 -274.591272)
		(width 0.088646)
		(layer "In2.Cu")
		(net "M_E_CPU0_SA_DQ<10>")
	)
	(arc
		(start 384.392932 -274.582636)
		(mid 384.116491 -274.51547)
		(end 383.84226 -274.591272)
		(width 0.088646)
		(layer "In2.Cu")
		(net "M_E_CPU0_SA_DQ<10>")
	)
	(arc
		(start 387.344666 -274.680934)
		(mid 387.282097 -274.626941)
		(end 387.212332 -274.582636)
		(width 0.088646)
		(layer "In2.Cu")
		(net "M_E_CPU0_SA_DQ<10>")
	)
	(arc
		(start 383.84226 -274.591272)
		(mid 383.655062 -274.641415)
		(end 383.467864 -274.591272)
		(width 0.088646)
		(layer "In2.Cu")
		(net "M_E_CPU0_SA_DQ<10>")
	)
	(arc
		(start 384.78206 -274.591272)
		(mid 384.594862 -274.641415)
		(end 384.407664 -274.591272)
		(width 0.088646)
		(layer "In2.Cu")
		(net "M_E_CPU0_SA_DQ<10>")
	)
	(arc
		(start 387.212332 -274.582636)
		(mid 386.935891 -274.51547)
		(end 386.66166 -274.591272)
		(width 0.088646)
		(layer "In2.Cu")
		(net "M_E_CPU0_SA_DQ<10>")
	)
	(arc
		(start 382.519174 -274.586192)
		(mid 382.403365 -274.474263)
		(end 382.345184 -274.324064)
		(width 0.088646)
		(layer "In2.Cu")
		(net "M_E_CPU0_SA_DQ<10>")
	)
	(arc
		(start 383.453132 -274.582636)
		(mid 383.176691 -274.51547)
		(end 382.90246 -274.591272)
		(width 0.088646)
		(layer "In2.Cu")
		(net "M_E_CPU0_SA_DQ<10>")
	)
	(arc
		(start 385.72186 -274.591272)
		(mid 385.534662 -274.641415)
		(end 385.347464 -274.591272)
		(width 0.088646)
		(layer "In2.Cu")
		(net "M_E_CPU0_SA_DQ<10>")
	)
	(arc
		(start 382.90246 -274.591272)
		(mid 382.715262 -274.641415)
		(end 382.528064 -274.591272)
		(width 0.088646)
		(layer "In2.Cu")
		(net "M_E_CPU0_SA_DQ<10>")
	)
	(arc
		(start 385.332732 -274.582636)
		(mid 385.056291 -274.51547)
		(end 384.78206 -274.591272)
		(width 0.088646)
		(layer "In2.Cu")
		(net "M_E_CPU0_SA_DQ<10>")
	)
	(segment
		(start 403.680676 -315.990732)
		(end 404.82012 -316.462664)
		(width 0.20066)
		(layer "F.Cu")
		(net "M_E_CPU0_SA_DQ<0>")
	)
	(segment
		(start 387.067044 -296.258234)
		(end 386.974334 -296.350944)
		(width 0.1016)
		(layer "F.Cu")
		(net "M_E_CPU0_SA_DQ<0>")
	)
	(segment
		(start 387.067044 -280.359866)
		(end 387.067044 -281.063446)
		(width 0.088646)
		(layer "F.Cu")
		(net "M_E_CPU0_SA_DQ<0>")
	)
	(segment
		(start 386.7658 -297.025822)
		(end 386.649214 -297.142408)
		(width 0.20066)
		(layer "F.Cu")
		(net "M_E_CPU0_SA_DQ<0>")
	)
	(segment
		(start 403.06117 -316.438788)
		(end 403.323044 -316.33033)
		(width 0.20066)
		(layer "F.Cu")
		(net "M_E_CPU0_SA_DQ<0>")
	)
	(segment
		(start 386.974334 -296.350944)
		(end 386.974334 -296.817288)
		(width 0.1016)
		(layer "F.Cu")
		(net "M_E_CPU0_SA_DQ<0>")
	)
	(segment
		(start 386.50418 -279.87752)
		(end 386.711952 -279.87752)
		(width 0.088646)
		(layer "F.Cu")
		(net "M_E_CPU0_SA_DQ<0>")
	)
	(segment
		(start 409.204414 -316.343538)
		(end 408.949398 -316.598554)
		(width 0.20066)
		(layer "F.Cu")
		(net "M_E_CPU0_SA_DQ<0>")
	)
	(segment
		(start 409.204414 -316.05855)
		(end 409.204414 -316.343538)
		(width 0.20066)
		(layer "F.Cu")
		(net "M_E_CPU0_SA_DQ<0>")
	)
	(segment
		(start 403.323044 -316.33033)
		(end 403.418802 -316.09919)
		(width 0.20066)
		(layer "F.Cu")
		(net "M_E_CPU0_SA_DQ<0>")
	)
	(segment
		(start 405.843486 -316.316614)
		(end 406.753314 -316.316614)
		(width 0.20066)
		(layer "F.Cu")
		(net "M_E_CPU0_SA_DQ<0>")
	)
	(segment
		(start 402.797772 -316.329568)
		(end 403.06117 -316.438788)
		(width 0.20066)
		(layer "F.Cu")
		(net "M_E_CPU0_SA_DQ<0>")
	)
	(segment
		(start 409.831794 -315.854334)
		(end 409.40863 -315.854334)
		(width 0.20066)
		(layer "F.Cu")
		(net "M_E_CPU0_SA_DQ<0>")
	)
	(segment
		(start 386.943854 -280.062686)
		(end 387.067044 -280.359866)
		(width 0.088646)
		(layer "F.Cu")
		(net "M_E_CPU0_SA_DQ<0>")
	)
	(segment
		(start 404.82012 -316.462664)
		(end 405.697436 -316.462664)
		(width 0.20066)
		(layer "F.Cu")
		(net "M_E_CPU0_SA_DQ<0>")
	)
	(segment
		(start 402.689314 -316.067694)
		(end 402.797772 -316.329568)
		(width 0.20066)
		(layer "F.Cu")
		(net "M_E_CPU0_SA_DQ<0>")
	)
	(segment
		(start 402.022564 -315.303662)
		(end 402.676614 -315.57468)
		(width 0.20066)
		(layer "F.Cu")
		(net "M_E_CPU0_SA_DQ<0>")
	)
	(segment
		(start 411.842712 -315.891672)
		(end 411.602682 -315.891672)
		(width 0.101854)
		(layer "F.Cu")
		(net "M_E_CPU0_SA_DQ<0>")
	)
	(segment
		(start 412.255716 -315.88202)
		(end 411.863794 -315.88202)
		(width 0.20066)
		(layer "F.Cu")
		(net "M_E_CPU0_SA_DQ<0>")
	)
	(segment
		(start 385.439412 -279.428194)
		(end 385.439412 -279.446736)
		(width 0.088646)
		(layer "F.Cu")
		(net "M_E_CPU0_SA_DQ<0>")
	)
	(segment
		(start 386.791708 -279.91054)
		(end 386.943854 -280.062686)
		(width 0.088646)
		(layer "F.Cu")
		(net "M_E_CPU0_SA_DQ<0>")
	)
	(segment
		(start 411.852364 -315.88202)
		(end 411.842712 -315.891672)
		(width 0.101854)
		(layer "F.Cu")
		(net "M_E_CPU0_SA_DQ<0>")
	)
	(segment
		(start 386.649214 -297.142408)
		(end 386.649214 -299.930312)
		(width 0.20066)
		(layer "F.Cu")
		(net "M_E_CPU0_SA_DQ<0>")
	)
	(segment
		(start 411.863794 -315.88202)
		(end 411.852364 -315.88202)
		(width 0.101854)
		(layer "F.Cu")
		(net "M_E_CPU0_SA_DQ<0>")
	)
	(segment
		(start 407.615136 -316.598554)
		(end 407.333196 -316.316614)
		(width 0.20066)
		(layer "F.Cu")
		(net "M_E_CPU0_SA_DQ<0>")
	)
	(segment
		(start 386.649214 -299.930312)
		(end 402.022564 -315.303662)
		(width 0.20066)
		(layer "F.Cu")
		(net "M_E_CPU0_SA_DQ<0>")
	)
	(segment
		(start 385.72186 -279.917906)
		(end 385.732274 -279.924002)
		(width 0.088646)
		(layer "F.Cu")
		(net "M_E_CPU0_SA_DQ<0>")
	)
	(segment
		(start 405.697436 -316.462664)
		(end 405.843486 -316.316614)
		(width 0.20066)
		(layer "F.Cu")
		(net "M_E_CPU0_SA_DQ<0>")
	)
	(segment
		(start 402.785072 -315.836554)
		(end 402.689314 -316.067694)
		(width 0.20066)
		(layer "F.Cu")
		(net "M_E_CPU0_SA_DQ<0>")
	)
	(segment
		(start 409.40863 -315.854334)
		(end 409.204414 -316.05855)
		(width 0.20066)
		(layer "F.Cu")
		(net "M_E_CPU0_SA_DQ<0>")
	)
	(segment
		(start 407.333196 -316.316614)
		(end 406.753314 -316.316614)
		(width 0.20066)
		(layer "F.Cu")
		(net "M_E_CPU0_SA_DQ<0>")
	)
	(segment
		(start 409.83662 -315.854334)
		(end 409.831794 -315.854334)
		(width 0.101854)
		(layer "F.Cu")
		(net "M_E_CPU0_SA_DQ<0>")
	)
	(segment
		(start 412.69031 -316.316614)
		(end 412.255716 -315.88202)
		(width 0.20066)
		(layer "F.Cu")
		(net "M_E_CPU0_SA_DQ<0>")
	)
	(segment
		(start 409.924758 -315.891672)
		(end 409.88742 -315.854334)
		(width 0.1016)
		(layer "F.Cu")
		(net "M_E_CPU0_SA_DQ<0>")
	)
	(segment
		(start 411.602682 -315.891672)
		(end 409.924758 -315.891672)
		(width 0.1016)
		(layer "F.Cu")
		(net "M_E_CPU0_SA_DQ<0>")
	)
	(segment
		(start 387.067044 -281.063446)
		(end 387.067044 -296.258234)
		(width 0.1016)
		(layer "F.Cu")
		(net "M_E_CPU0_SA_DQ<0>")
	)
	(segment
		(start 403.418802 -316.09919)
		(end 403.680676 -315.990732)
		(width 0.20066)
		(layer "F.Cu")
		(net "M_E_CPU0_SA_DQ<0>")
	)
	(segment
		(start 409.88742 -315.854334)
		(end 409.83662 -315.854334)
		(width 0.1016)
		(layer "F.Cu")
		(net "M_E_CPU0_SA_DQ<0>")
	)
	(segment
		(start 386.974334 -296.817288)
		(end 386.7658 -297.025822)
		(width 0.1016)
		(layer "F.Cu")
		(net "M_E_CPU0_SA_DQ<0>")
	)
	(segment
		(start 408.949398 -316.598554)
		(end 407.615136 -316.598554)
		(width 0.20066)
		(layer "F.Cu")
		(net "M_E_CPU0_SA_DQ<0>")
	)
	(segment
		(start 414.297114 -316.316614)
		(end 412.69031 -316.316614)
		(width 0.20066)
		(layer "F.Cu")
		(net "M_E_CPU0_SA_DQ<0>")
	)
	(segment
		(start 385.18846 -279.067514)
		(end 385.26085 -279.108916)
		(width 0.088646)
		(layer "F.Cu")
		(net "M_E_CPU0_SA_DQ<0>")
	)
	(segment
		(start 402.676614 -315.57468)
		(end 402.785072 -315.836554)
		(width 0.20066)
		(layer "F.Cu")
		(net "M_E_CPU0_SA_DQ<0>")
	)
	(arc
		(start 386.711952 -279.87752)
		(mid 386.75511 -279.886105)
		(end 386.791708 -279.91054)
		(width 0.088646)
		(layer "F.Cu")
		(net "M_E_CPU0_SA_DQ<0>")
	)
	(arc
		(start 384.595116 -278.614378)
		(mid 384.876686 -278.86072)
		(end 385.18846 -279.067514)
		(width 0.088646)
		(layer "F.Cu")
		(net "M_E_CPU0_SA_DQ<0>")
	)
	(arc
		(start 385.732274 -279.924002)
		(mid 385.991952 -279.993709)
		(end 386.254498 -279.935686)
		(width 0.088646)
		(layer "F.Cu")
		(net "M_E_CPU0_SA_DQ<0>")
	)
	(arc
		(start 385.26085 -279.108916)
		(mid 385.391764 -279.245276)
		(end 385.439412 -279.428194)
		(width 0.088646)
		(layer "F.Cu")
		(net "M_E_CPU0_SA_DQ<0>")
	)
	(arc
		(start 385.439412 -279.446736)
		(mid 385.519574 -279.718925)
		(end 385.72186 -279.917906)
		(width 0.088646)
		(layer "F.Cu")
		(net "M_E_CPU0_SA_DQ<0>")
	)
	(arc
		(start 386.254498 -279.935686)
		(mid 386.375995 -279.892232)
		(end 386.50418 -279.87752)
		(width 0.088646)
		(layer "F.Cu")
		(net "M_E_CPU0_SA_DQ<0>")
	)
	(segment
		(start 409.194254 -267.016738)
		(end 410.853382 -267.016738)
		(width 0.20066)
		(layer "F.Cu")
		(net "M_E_CPU0_SA_CS_N<3>")
	)
	(segment
		(start 387.925818 -256.224786)
		(end 389.156702 -256.224786)
		(width 0.1016)
		(layer "F.Cu")
		(net "M_E_CPU0_SA_CS_N<3>")
	)
	(segment
		(start 386.566918 -256.224786)
		(end 387.925818 -256.224786)
		(width 0.088646)
		(layer "F.Cu")
		(net "M_E_CPU0_SA_CS_N<3>")
	)
	(segment
		(start 405.736552 -266.578588)
		(end 405.749506 -266.591542)
		(width 0.1016)
		(layer "F.Cu")
		(net "M_E_CPU0_SA_CS_N<3>")
	)
	(segment
		(start 384.207258 -256.112772)
		(end 384.357118 -256.262632)
		(width 0.088646)
		(layer "F.Cu")
		(net "M_E_CPU0_SA_CS_N<3>")
	)
	(segment
		(start 403.529292 -266.10818)
		(end 405.089106 -266.10818)
		(width 0.20066)
		(layer "F.Cu")
		(net "M_E_CPU0_SA_CS_N<3>")
	)
	(segment
		(start 384.357118 -256.262632)
		(end 384.910584 -256.262632)
		(width 0.088646)
		(layer "F.Cu")
		(net "M_E_CPU0_SA_CS_N<3>")
	)
	(segment
		(start 405.731726 -266.578588)
		(end 405.736552 -266.578588)
		(width 0.101854)
		(layer "F.Cu")
		(net "M_E_CPU0_SA_CS_N<3>")
	)
	(segment
		(start 409.098496 -266.92098)
		(end 409.194254 -267.016738)
		(width 0.20066)
		(layer "F.Cu")
		(net "M_E_CPU0_SA_CS_N<3>")
	)
	(segment
		(start 394.041122 -260.287008)
		(end 395.164564 -261.41045)
		(width 0.20066)
		(layer "F.Cu")
		(net "M_E_CPU0_SA_CS_N<3>")
	)
	(segment
		(start 395.164564 -261.41045)
		(end 401.424648 -264.003536)
		(width 0.20066)
		(layer "F.Cu")
		(net "M_E_CPU0_SA_CS_N<3>")
	)
	(segment
		(start 384.268726 -255.96088)
		(end 384.207258 -256.022348)
		(width 0.088646)
		(layer "F.Cu")
		(net "M_E_CPU0_SA_CS_N<3>")
	)
	(segment
		(start 385.72186 -256.149856)
		(end 385.722114 -256.149856)
		(width 0.088646)
		(layer "F.Cu")
		(net "M_E_CPU0_SA_CS_N<3>")
	)
	(segment
		(start 405.749506 -266.591542)
		(end 407.745438 -266.591542)
		(width 0.1016)
		(layer "F.Cu")
		(net "M_E_CPU0_SA_CS_N<3>")
	)
	(segment
		(start 408.555698 -266.743942)
		(end 408.732736 -266.92098)
		(width 0.20066)
		(layer "F.Cu")
		(net "M_E_CPU0_SA_CS_N<3>")
	)
	(segment
		(start 407.956766 -266.573254)
		(end 408.12212 -266.4079)
		(width 0.20066)
		(layer "F.Cu")
		(net "M_E_CPU0_SA_CS_N<3>")
	)
	(segment
		(start 405.559514 -266.578588)
		(end 405.731726 -266.578588)
		(width 0.20066)
		(layer "F.Cu")
		(net "M_E_CPU0_SA_CS_N<3>")
	)
	(segment
		(start 407.763726 -266.573254)
		(end 407.956766 -266.573254)
		(width 0.20066)
		(layer "F.Cu")
		(net "M_E_CPU0_SA_CS_N<3>")
	)
	(segment
		(start 384.207258 -256.022348)
		(end 384.207258 -256.112772)
		(width 0.088646)
		(layer "F.Cu")
		(net "M_E_CPU0_SA_CS_N<3>")
	)
	(segment
		(start 384.973576 -256.19964)
		(end 385.548886 -256.19964)
		(width 0.088646)
		(layer "F.Cu")
		(net "M_E_CPU0_SA_CS_N<3>")
	)
	(segment
		(start 393.834874 -260.08076)
		(end 393.9794 -260.225286)
		(width 0.1016)
		(layer "F.Cu")
		(net "M_E_CPU0_SA_CS_N<3>")
	)
	(segment
		(start 407.745438 -266.591542)
		(end 407.763726 -266.573254)
		(width 0.1016)
		(layer "F.Cu")
		(net "M_E_CPU0_SA_CS_N<3>")
	)
	(segment
		(start 401.424648 -264.003536)
		(end 403.529292 -266.10818)
		(width 0.20066)
		(layer "F.Cu")
		(net "M_E_CPU0_SA_CS_N<3>")
	)
	(segment
		(start 392.80846 -259.876544)
		(end 393.834874 -260.08076)
		(width 0.1016)
		(layer "F.Cu")
		(net "M_E_CPU0_SA_CS_N<3>")
	)
	(segment
		(start 408.555698 -266.493752)
		(end 408.555698 -266.743942)
		(width 0.20066)
		(layer "F.Cu")
		(net "M_E_CPU0_SA_CS_N<3>")
	)
	(segment
		(start 393.9794 -260.225286)
		(end 394.041122 -260.287008)
		(width 0.101854)
		(layer "F.Cu")
		(net "M_E_CPU0_SA_CS_N<3>")
	)
	(segment
		(start 405.089106 -266.10818)
		(end 405.559514 -266.578588)
		(width 0.20066)
		(layer "F.Cu")
		(net "M_E_CPU0_SA_CS_N<3>")
	)
	(segment
		(start 408.469846 -266.4079)
		(end 408.555698 -266.493752)
		(width 0.20066)
		(layer "F.Cu")
		(net "M_E_CPU0_SA_CS_N<3>")
	)
	(segment
		(start 389.156702 -256.224786)
		(end 392.80846 -259.876544)
		(width 0.1016)
		(layer "F.Cu")
		(net "M_E_CPU0_SA_CS_N<3>")
	)
	(segment
		(start 384.910584 -256.262632)
		(end 384.973576 -256.19964)
		(width 0.088646)
		(layer "F.Cu")
		(net "M_E_CPU0_SA_CS_N<3>")
	)
	(segment
		(start 408.12212 -266.4079)
		(end 408.469846 -266.4079)
		(width 0.20066)
		(layer "F.Cu")
		(net "M_E_CPU0_SA_CS_N<3>")
	)
	(segment
		(start 384.595116 -255.825498)
		(end 384.268726 -255.96088)
		(width 0.088646)
		(layer "F.Cu")
		(net "M_E_CPU0_SA_CS_N<3>")
	)
	(segment
		(start 408.732736 -266.92098)
		(end 409.098496 -266.92098)
		(width 0.20066)
		(layer "F.Cu")
		(net "M_E_CPU0_SA_CS_N<3>")
	)
	(arc
		(start 386.287518 -256.149856)
		(mid 386.422276 -256.205762)
		(end 386.566918 -256.224786)
		(width 0.088646)
		(layer "F.Cu")
		(net "M_E_CPU0_SA_CS_N<3>")
	)
	(arc
		(start 385.722114 -256.149856)
		(mid 386.004816 -256.07408)
		(end 386.287518 -256.149856)
		(width 0.088646)
		(layer "F.Cu")
		(net "M_E_CPU0_SA_CS_N<3>")
	)
	(arc
		(start 385.548886 -256.19964)
		(mid 385.638415 -256.185311)
		(end 385.72186 -256.149856)
		(width 0.088646)
		(layer "F.Cu")
		(net "M_E_CPU0_SA_CS_N<3>")
	)
	(segment
		(start 392.813286 -260.743954)
		(end 392.93673 -261.041642)
		(width 0.1016)
		(layer "F.Cu")
		(net "M_E_CPU0_SA_CS_N<2>")
	)
	(segment
		(start 386.544312 -256.639314)
		(end 386.544312 -256.735072)
		(width 0.088646)
		(layer "F.Cu")
		(net "M_E_CPU0_SA_CS_N<2>")
	)
	(segment
		(start 387.925818 -256.979166)
		(end 389.048498 -256.979166)
		(width 0.1016)
		(layer "F.Cu")
		(net "M_E_CPU0_SA_CS_N<2>")
	)
	(segment
		(start 387.065266 -256.979166)
		(end 387.925818 -256.979166)
		(width 0.088646)
		(layer "F.Cu")
		(net "M_E_CPU0_SA_CS_N<2>")
	)
	(segment
		(start 385.672584 -256.41046)
		(end 385.801362 -256.325116)
		(width 0.088646)
		(layer "F.Cu")
		(net "M_E_CPU0_SA_CS_N<2>")
	)
	(segment
		(start 385.564126 -256.853436)
		(end 385.564126 -256.529332)
		(width 0.088646)
		(layer "F.Cu")
		(net "M_E_CPU0_SA_CS_N<2>")
	)
	(segment
		(start 385.672584 -256.420874)
		(end 385.672584 -256.41046)
		(width 0.088646)
		(layer "F.Cu")
		(net "M_E_CPU0_SA_CS_N<2>")
	)
	(segment
		(start 384.633216 -256.918968)
		(end 384.826002 -257.111754)
		(width 0.088646)
		(layer "F.Cu")
		(net "M_E_CPU0_SA_CS_N<2>")
	)
	(segment
		(start 385.064762 -256.639314)
		(end 384.83413 -256.54381)
		(width 0.088646)
		(layer "F.Cu")
		(net "M_E_CPU0_SA_CS_N<2>")
	)
	(segment
		(start 384.633216 -256.63906)
		(end 384.633216 -256.918968)
		(width 0.088646)
		(layer "F.Cu")
		(net "M_E_CPU0_SA_CS_N<2>")
	)
	(segment
		(start 384.83413 -256.54381)
		(end 384.728466 -256.54381)
		(width 0.088646)
		(layer "F.Cu")
		(net "M_E_CPU0_SA_CS_N<2>")
	)
	(segment
		(start 385.305808 -257.111754)
		(end 385.564126 -256.853436)
		(width 0.088646)
		(layer "F.Cu")
		(net "M_E_CPU0_SA_CS_N<2>")
	)
	(segment
		(start 404.86457 -267.866622)
		(end 406.753314 -267.866622)
		(width 0.20066)
		(layer "F.Cu")
		(net "M_E_CPU0_SA_CS_N<2>")
	)
	(segment
		(start 393.221972 -261.326884)
		(end 394.548614 -262.653526)
		(width 0.20066)
		(layer "F.Cu")
		(net "M_E_CPU0_SA_CS_N<2>")
	)
	(segment
		(start 400.795236 -265.241024)
		(end 402.972524 -267.418312)
		(width 0.20066)
		(layer "F.Cu")
		(net "M_E_CPU0_SA_CS_N<2>")
	)
	(segment
		(start 402.972524 -267.418312)
		(end 404.41626 -267.418312)
		(width 0.20066)
		(layer "F.Cu")
		(net "M_E_CPU0_SA_CS_N<2>")
	)
	(segment
		(start 386.911596 -256.975864)
		(end 387.061964 -256.975864)
		(width 0.088646)
		(layer "F.Cu")
		(net "M_E_CPU0_SA_CS_N<2>")
	)
	(segment
		(start 387.061964 -256.975864)
		(end 387.065266 -256.979166)
		(width 0.088646)
		(layer "F.Cu")
		(net "M_E_CPU0_SA_CS_N<2>")
	)
	(segment
		(start 384.826002 -257.111754)
		(end 385.305808 -257.111754)
		(width 0.088646)
		(layer "F.Cu")
		(net "M_E_CPU0_SA_CS_N<2>")
	)
	(segment
		(start 394.548614 -262.653526)
		(end 400.795236 -265.241024)
		(width 0.20066)
		(layer "F.Cu")
		(net "M_E_CPU0_SA_CS_N<2>")
	)
	(segment
		(start 384.728466 -256.54381)
		(end 384.633216 -256.63906)
		(width 0.088646)
		(layer "F.Cu")
		(net "M_E_CPU0_SA_CS_N<2>")
	)
	(segment
		(start 386.715762 -256.946654)
		(end 386.77215 -256.975102)
		(width 0.088646)
		(layer "F.Cu")
		(net "M_E_CPU0_SA_CS_N<2>")
	)
	(segment
		(start 385.564126 -256.529332)
		(end 385.672584 -256.420874)
		(width 0.088646)
		(layer "F.Cu")
		(net "M_E_CPU0_SA_CS_N<2>")
	)
	(segment
		(start 392.93673 -261.041642)
		(end 393.221972 -261.326884)
		(width 0.1016)
		(layer "F.Cu")
		(net "M_E_CPU0_SA_CS_N<2>")
	)
	(segment
		(start 404.41626 -267.418312)
		(end 404.86457 -267.866622)
		(width 0.20066)
		(layer "F.Cu")
		(net "M_E_CPU0_SA_CS_N<2>")
	)
	(segment
		(start 389.048498 -256.979166)
		(end 392.813286 -260.743954)
		(width 0.1016)
		(layer "F.Cu")
		(net "M_E_CPU0_SA_CS_N<2>")
	)
	(arc
		(start 385.801362 -256.325116)
		(mid 385.840001 -256.30281)
		(end 385.881118 -256.285492)
		(width 0.088646)
		(layer "F.Cu")
		(net "M_E_CPU0_SA_CS_N<2>")
	)
	(arc
		(start 386.544312 -256.735072)
		(mid 386.607761 -256.858924)
		(end 386.715762 -256.946654)
		(width 0.088646)
		(layer "F.Cu")
		(net "M_E_CPU0_SA_CS_N<2>")
	)
	(arc
		(start 386.374894 -256.392426)
		(mid 386.504209 -256.485255)
		(end 386.544312 -256.639314)
		(width 0.088646)
		(layer "F.Cu")
		(net "M_E_CPU0_SA_CS_N<2>")
	)
	(arc
		(start 386.77215 -256.975102)
		(mid 386.84177 -256.991954)
		(end 386.911596 -256.975864)
		(width 0.088646)
		(layer "F.Cu")
		(net "M_E_CPU0_SA_CS_N<2>")
	)
	(arc
		(start 385.881118 -256.285492)
		(mid 386.039655 -256.266305)
		(end 386.19176 -256.314956)
		(width 0.088646)
		(layer "F.Cu")
		(net "M_E_CPU0_SA_CS_N<2>")
	)
	(arc
		(start 386.19176 -256.314956)
		(mid 386.280913 -256.359398)
		(end 386.374894 -256.392426)
		(width 0.088646)
		(layer "F.Cu")
		(net "M_E_CPU0_SA_CS_N<2>")
	)
	(segment
		(start 407.346658 -267.44168)
		(end 407.74874 -267.44168)
		(width 0.101854)
		(layer "F.Cu")
		(net "M_E_CPU0_SA_CS_N<1>")
	)
	(segment
		(start 409.92171 -267.44168)
		(end 411.734 -267.44168)
		(width 0.1016)
		(layer "F.Cu")
		(net "M_E_CPU0_SA_CS_N<1>")
	)
	(segment
		(start 409.908248 -267.428218)
		(end 409.92171 -267.44168)
		(width 0.1016)
		(layer "F.Cu")
		(net "M_E_CPU0_SA_CS_N<1>")
	)
	(segment
		(start 389.139938 -256.639314)
		(end 392.810492 -260.309868)
		(width 0.1016)
		(layer "F.Cu")
		(net "M_E_CPU0_SA_CS_N<1>")
	)
	(segment
		(start 409.903422 -267.428218)
		(end 409.908248 -267.428218)
		(width 0.101854)
		(layer "F.Cu")
		(net "M_E_CPU0_SA_CS_N<1>")
	)
	(segment
		(start 416.471354 -266.654026)
		(end 416.778694 -266.654026)
		(width 0.20066)
		(layer "F.Cu")
		(net "M_E_CPU0_SA_CS_N<1>")
	)
	(segment
		(start 416.296094 -267.12926)
		(end 416.296094 -266.829286)
		(width 0.20066)
		(layer "F.Cu")
		(net "M_E_CPU0_SA_CS_N<1>")
	)
	(segment
		(start 416.296094 -266.829286)
		(end 416.471354 -266.654026)
		(width 0.20066)
		(layer "F.Cu")
		(net "M_E_CPU0_SA_CS_N<1>")
	)
	(segment
		(start 407.74874 -267.44168)
		(end 407.763726 -267.456666)
		(width 0.101854)
		(layer "F.Cu")
		(net "M_E_CPU0_SA_CS_N<1>")
	)
	(segment
		(start 414.828736 -267.44168)
		(end 415.288984 -267.44168)
		(width 0.101854)
		(layer "F.Cu")
		(net "M_E_CPU0_SA_CS_N<1>")
	)
	(segment
		(start 405.731726 -267.456666)
		(end 405.736552 -267.456666)
		(width 0.101854)
		(layer "F.Cu")
		(net "M_E_CPU0_SA_CS_N<1>")
	)
	(segment
		(start 405.377396 -267.456666)
		(end 405.731726 -267.456666)
		(width 0.20066)
		(layer "F.Cu")
		(net "M_E_CPU0_SA_CS_N<1>")
	)
	(segment
		(start 394.82776 -262.012684)
		(end 401.087336 -264.605516)
		(width 0.20066)
		(layer "F.Cu")
		(net "M_E_CPU0_SA_CS_N<1>")
	)
	(segment
		(start 408.098498 -267.456666)
		(end 408.163776 -267.391388)
		(width 0.20066)
		(layer "F.Cu")
		(net "M_E_CPU0_SA_CS_N<1>")
	)
	(segment
		(start 413.311848 -267.448792)
		(end 413.31896 -267.44168)
		(width 0.1016)
		(layer "F.Cu")
		(net "M_E_CPU0_SA_CS_N<1>")
	)
	(segment
		(start 392.810492 -260.309868)
		(end 393.347448 -260.532372)
		(width 0.1016)
		(layer "F.Cu")
		(net "M_E_CPU0_SA_CS_N<1>")
	)
	(segment
		(start 405.736552 -267.456666)
		(end 405.751538 -267.44168)
		(width 0.1016)
		(layer "F.Cu")
		(net "M_E_CPU0_SA_CS_N<1>")
	)
	(segment
		(start 411.783022 -267.416534)
		(end 412.8008 -267.416534)
		(width 0.20066)
		(layer "F.Cu")
		(net "M_E_CPU0_SA_CS_N<1>")
	)
	(segment
		(start 416.778694 -266.654026)
		(end 417.141406 -267.016738)
		(width 0.20066)
		(layer "F.Cu")
		(net "M_E_CPU0_SA_CS_N<1>")
	)
	(segment
		(start 393.439904 -260.624828)
		(end 393.57173 -260.756654)
		(width 0.101854)
		(layer "F.Cu")
		(net "M_E_CPU0_SA_CS_N<1>")
	)
	(segment
		(start 401.087336 -264.605516)
		(end 403.239478 -266.757658)
		(width 0.20066)
		(layer "F.Cu")
		(net "M_E_CPU0_SA_CS_N<1>")
	)
	(segment
		(start 412.8008 -267.416534)
		(end 412.833058 -267.448792)
		(width 0.20066)
		(layer "F.Cu")
		(net "M_E_CPU0_SA_CS_N<1>")
	)
	(segment
		(start 413.31896 -267.44168)
		(end 414.828736 -267.44168)
		(width 0.1016)
		(layer "F.Cu")
		(net "M_E_CPU0_SA_CS_N<1>")
	)
	(segment
		(start 403.239478 -266.757658)
		(end 404.678388 -266.757658)
		(width 0.20066)
		(layer "F.Cu")
		(net "M_E_CPU0_SA_CS_N<1>")
	)
	(segment
		(start 411.734 -267.44168)
		(end 411.759146 -267.416534)
		(width 0.1016)
		(layer "F.Cu")
		(net "M_E_CPU0_SA_CS_N<1>")
	)
	(segment
		(start 415.288984 -267.44168)
		(end 415.307526 -267.460222)
		(width 0.101854)
		(layer "F.Cu")
		(net "M_E_CPU0_SA_CS_N<1>")
	)
	(segment
		(start 417.141406 -267.016738)
		(end 418.397182 -267.016738)
		(width 0.20066)
		(layer "F.Cu")
		(net "M_E_CPU0_SA_CS_N<1>")
	)
	(segment
		(start 386.944362 -256.639314)
		(end 387.925818 -256.639314)
		(width 0.088646)
		(layer "F.Cu")
		(net "M_E_CPU0_SA_CS_N<1>")
	)
	(segment
		(start 412.833058 -267.448792)
		(end 413.307022 -267.448792)
		(width 0.20066)
		(layer "F.Cu")
		(net "M_E_CPU0_SA_CS_N<1>")
	)
	(segment
		(start 408.163776 -267.391388)
		(end 408.956764 -267.391388)
		(width 0.20066)
		(layer "F.Cu")
		(net "M_E_CPU0_SA_CS_N<1>")
	)
	(segment
		(start 413.307022 -267.448792)
		(end 413.311848 -267.448792)
		(width 0.101854)
		(layer "F.Cu")
		(net "M_E_CPU0_SA_CS_N<1>")
	)
	(segment
		(start 411.759146 -267.416534)
		(end 411.783022 -267.416534)
		(width 0.101854)
		(layer "F.Cu")
		(net "M_E_CPU0_SA_CS_N<1>")
	)
	(segment
		(start 415.307526 -267.460222)
		(end 415.965132 -267.460222)
		(width 0.20066)
		(layer "F.Cu")
		(net "M_E_CPU0_SA_CS_N<1>")
	)
	(segment
		(start 415.965132 -267.460222)
		(end 416.296094 -267.12926)
		(width 0.20066)
		(layer "F.Cu")
		(net "M_E_CPU0_SA_CS_N<1>")
	)
	(segment
		(start 393.347448 -260.532372)
		(end 393.439904 -260.624828)
		(width 0.1016)
		(layer "F.Cu")
		(net "M_E_CPU0_SA_CS_N<1>")
	)
	(segment
		(start 407.763726 -267.456666)
		(end 408.098498 -267.456666)
		(width 0.20066)
		(layer "F.Cu")
		(net "M_E_CPU0_SA_CS_N<1>")
	)
	(segment
		(start 405.751538 -267.44168)
		(end 407.346658 -267.44168)
		(width 0.1016)
		(layer "F.Cu")
		(net "M_E_CPU0_SA_CS_N<1>")
	)
	(segment
		(start 393.57173 -260.756654)
		(end 394.82776 -262.012684)
		(width 0.20066)
		(layer "F.Cu")
		(net "M_E_CPU0_SA_CS_N<1>")
	)
	(segment
		(start 408.956764 -267.391388)
		(end 408.993594 -267.428218)
		(width 0.20066)
		(layer "F.Cu")
		(net "M_E_CPU0_SA_CS_N<1>")
	)
	(segment
		(start 404.678388 -266.757658)
		(end 405.377396 -267.456666)
		(width 0.20066)
		(layer "F.Cu")
		(net "M_E_CPU0_SA_CS_N<1>")
	)
	(segment
		(start 408.993594 -267.428218)
		(end 409.903422 -267.428218)
		(width 0.20066)
		(layer "F.Cu")
		(net "M_E_CPU0_SA_CS_N<1>")
	)
	(segment
		(start 387.925818 -256.639314)
		(end 389.139938 -256.639314)
		(width 0.1016)
		(layer "F.Cu")
		(net "M_E_CPU0_SA_CS_N<1>")
	)
	(segment
		(start 404.583138 -268.513052)
		(end 405.143462 -268.513052)
		(width 0.20066)
		(layer "F.Cu")
		(net "M_E_CPU0_SA_CS_N<0>")
	)
	(segment
		(start 402.50872 -267.882116)
		(end 402.50872 -267.881862)
		(width 0.20066)
		(layer "F.Cu")
		(net "M_E_CPU0_SA_CS_N<0>")
	)
	(segment
		(start 408.271726 -267.96365)
		(end 408.665426 -267.96365)
		(width 0.20066)
		(layer "F.Cu")
		(net "M_E_CPU0_SA_CS_N<0>")
	)
	(segment
		(start 411.796484 -268.291564)
		(end 411.808422 -268.303502)
		(width 0.1016)
		(layer "F.Cu")
		(net "M_E_CPU0_SA_CS_N<0>")
	)
	(segment
		(start 392.623802 -261.642352)
		(end 392.757152 -261.775702)
		(width 0.1016)
		(layer "F.Cu")
		(net "M_E_CPU0_SA_CS_N<0>")
	)
	(segment
		(start 407.763726 -268.273276)
		(end 407.9621 -268.273276)
		(width 0.20066)
		(layer "F.Cu")
		(net "M_E_CPU0_SA_CS_N<0>")
	)
	(segment
		(start 394.315442 -263.333992)
		(end 400.538188 -265.911584)
		(width 0.20066)
		(layer "F.Cu")
		(net "M_E_CPU0_SA_CS_N<0>")
	)
	(segment
		(start 405.731726 -268.281658)
		(end 405.736552 -268.281658)
		(width 0.101854)
		(layer "F.Cu")
		(net "M_E_CPU0_SA_CS_N<0>")
	)
	(segment
		(start 407.9621 -268.273276)
		(end 408.271726 -267.96365)
		(width 0.20066)
		(layer "F.Cu")
		(net "M_E_CPU0_SA_CS_N<0>")
	)
	(segment
		(start 392.757152 -261.775702)
		(end 394.315442 -263.333992)
		(width 0.20066)
		(layer "F.Cu")
		(net "M_E_CPU0_SA_CS_N<0>")
	)
	(segment
		(start 407.743914 -268.291564)
		(end 407.762202 -268.273276)
		(width 0.1016)
		(layer "F.Cu")
		(net "M_E_CPU0_SA_CS_N<0>")
	)
	(segment
		(start 409.231338 -268.098524)
		(end 409.434284 -268.30147)
		(width 0.20066)
		(layer "F.Cu")
		(net "M_E_CPU0_SA_CS_N<0>")
	)
	(segment
		(start 385.978654 -256.665222)
		(end 385.978654 -256.927096)
		(width 0.088646)
		(layer "F.Cu")
		(net "M_E_CPU0_SA_CS_N<0>")
	)
	(segment
		(start 400.538188 -265.911584)
		(end 402.50872 -267.882116)
		(width 0.20066)
		(layer "F.Cu")
		(net "M_E_CPU0_SA_CS_N<0>")
	)
	(segment
		(start 385.978654 -256.927096)
		(end 386.041646 -256.990088)
		(width 0.088646)
		(layer "F.Cu")
		(net "M_E_CPU0_SA_CS_N<0>")
	)
	(segment
		(start 392.159744 -260.521958)
		(end 392.623802 -261.642352)
		(width 0.1016)
		(layer "F.Cu")
		(net "M_E_CPU0_SA_CS_N<0>")
	)
	(segment
		(start 411.808422 -268.303502)
		(end 412.178246 -268.303502)
		(width 0.20066)
		(layer "F.Cu")
		(net "M_E_CPU0_SA_CS_N<0>")
	)
	(segment
		(start 409.882848 -268.30147)
		(end 409.892754 -268.291564)
		(width 0.1016)
		(layer "F.Cu")
		(net "M_E_CPU0_SA_CS_N<0>")
	)
	(segment
		(start 402.685758 -268.0589)
		(end 404.128986 -268.0589)
		(width 0.20066)
		(layer "F.Cu")
		(net "M_E_CPU0_SA_CS_N<0>")
	)
	(segment
		(start 408.665426 -267.96365)
		(end 408.8003 -268.098524)
		(width 0.20066)
		(layer "F.Cu")
		(net "M_E_CPU0_SA_CS_N<0>")
	)
	(segment
		(start 402.50872 -267.881862)
		(end 402.685758 -268.0589)
		(width 0.20066)
		(layer "F.Cu")
		(net "M_E_CPU0_SA_CS_N<0>")
	)
	(segment
		(start 405.374856 -268.281658)
		(end 405.731726 -268.281658)
		(width 0.20066)
		(layer "F.Cu")
		(net "M_E_CPU0_SA_CS_N<0>")
	)
	(segment
		(start 408.8003 -268.098524)
		(end 409.231338 -268.098524)
		(width 0.20066)
		(layer "F.Cu")
		(net "M_E_CPU0_SA_CS_N<0>")
	)
	(segment
		(start 404.128986 -268.0589)
		(end 404.583138 -268.513052)
		(width 0.20066)
		(layer "F.Cu")
		(net "M_E_CPU0_SA_CS_N<0>")
	)
	(segment
		(start 387.925818 -257.297682)
		(end 388.935468 -257.297682)
		(width 0.1016)
		(layer "F.Cu")
		(net "M_E_CPU0_SA_CS_N<0>")
	)
	(segment
		(start 405.736552 -268.281658)
		(end 405.746458 -268.291564)
		(width 0.1016)
		(layer "F.Cu")
		(net "M_E_CPU0_SA_CS_N<0>")
	)
	(segment
		(start 407.762202 -268.273276)
		(end 407.763726 -268.273276)
		(width 0.101854)
		(layer "F.Cu")
		(net "M_E_CPU0_SA_CS_N<0>")
	)
	(segment
		(start 405.746458 -268.291564)
		(end 407.743914 -268.291564)
		(width 0.1016)
		(layer "F.Cu")
		(net "M_E_CPU0_SA_CS_N<0>")
	)
	(segment
		(start 409.434284 -268.30147)
		(end 409.878022 -268.30147)
		(width 0.20066)
		(layer "F.Cu")
		(net "M_E_CPU0_SA_CS_N<0>")
	)
	(segment
		(start 386.041646 -256.990088)
		(end 386.466334 -256.990088)
		(width 0.088646)
		(layer "F.Cu")
		(net "M_E_CPU0_SA_CS_N<0>")
	)
	(segment
		(start 409.892754 -268.291564)
		(end 411.796484 -268.291564)
		(width 0.1016)
		(layer "F.Cu")
		(net "M_E_CPU0_SA_CS_N<0>")
	)
	(segment
		(start 405.143462 -268.513052)
		(end 405.374856 -268.281658)
		(width 0.20066)
		(layer "F.Cu")
		(net "M_E_CPU0_SA_CS_N<0>")
	)
	(segment
		(start 412.178246 -268.303502)
		(end 412.615126 -267.866622)
		(width 0.20066)
		(layer "F.Cu")
		(net "M_E_CPU0_SA_CS_N<0>")
	)
	(segment
		(start 387.10362 -257.297682)
		(end 387.925818 -257.297682)
		(width 0.088646)
		(layer "F.Cu")
		(net "M_E_CPU0_SA_CS_N<0>")
	)
	(segment
		(start 388.935468 -257.297682)
		(end 392.159744 -260.521958)
		(width 0.1016)
		(layer "F.Cu")
		(net "M_E_CPU0_SA_CS_N<0>")
	)
	(segment
		(start 412.615126 -267.866622)
		(end 414.297114 -267.866622)
		(width 0.20066)
		(layer "F.Cu")
		(net "M_E_CPU0_SA_CS_N<0>")
	)
	(segment
		(start 386.621528 -257.113786)
		(end 386.823458 -257.225546)
		(width 0.088646)
		(layer "F.Cu")
		(net "M_E_CPU0_SA_CS_N<0>")
	)
	(segment
		(start 386.004562 -256.639314)
		(end 385.978654 -256.665222)
		(width 0.088646)
		(layer "F.Cu")
		(net "M_E_CPU0_SA_CS_N<0>")
	)
	(segment
		(start 409.878022 -268.30147)
		(end 409.882848 -268.30147)
		(width 0.101854)
		(layer "F.Cu")
		(net "M_E_CPU0_SA_CS_N<0>")
	)
	(arc
		(start 386.823458 -257.225546)
		(mid 386.958958 -257.279414)
		(end 387.10362 -257.297682)
		(width 0.088646)
		(layer "F.Cu")
		(net "M_E_CPU0_SA_CS_N<0>")
	)
	(arc
		(start 386.466334 -256.990088)
		(mid 386.537807 -257.059618)
		(end 386.621528 -257.113786)
		(width 0.088646)
		(layer "F.Cu")
		(net "M_E_CPU0_SA_CS_N<0>")
	)
	(segment
		(start 398.160494 -268.096492)
		(end 399.013172 -268.096492)
		(width 0.1016)
		(layer "F.Cu")
		(net "M_E_CPU0_SA_CB<7>")
	)
	(segment
		(start 417.150804 -270.416782)
		(end 416.924236 -270.190214)
		(width 0.20066)
		(layer "F.Cu")
		(net "M_E_CPU0_SA_CB<7>")
	)
	(segment
		(start 408.173428 -270.841724)
		(end 408.374342 -270.64081)
		(width 0.20066)
		(layer "F.Cu")
		(net "M_E_CPU0_SA_CB<7>")
	)
	(segment
		(start 400.468592 -267.313918)
		(end 402.265896 -269.111222)
		(width 0.20066)
		(layer "F.Cu")
		(net "M_E_CPU0_SA_CB<7>")
	)
	(segment
		(start 403.714712 -269.111222)
		(end 404.189692 -269.586202)
		(width 0.20066)
		(layer "F.Cu")
		(net "M_E_CPU0_SA_CB<7>")
	)
	(segment
		(start 404.189692 -269.586202)
		(end 404.772368 -269.586202)
		(width 0.20066)
		(layer "F.Cu")
		(net "M_E_CPU0_SA_CB<7>")
	)
	(segment
		(start 415.599372 -270.841724)
		(end 415.231834 -270.841724)
		(width 0.101854)
		(layer "F.Cu")
		(net "M_E_CPU0_SA_CB<7>")
	)
	(segment
		(start 387.507734 -258.653026)
		(end 387.973824 -258.459986)
		(width 0.088646)
		(layer "F.Cu")
		(net "M_E_CPU0_SA_CB<7>")
	)
	(segment
		(start 410.853636 -270.417036)
		(end 410.853382 -270.416782)
		(width 0.20066)
		(layer "F.Cu")
		(net "M_E_CPU0_SA_CB<7>")
	)
	(segment
		(start 386.987034 -258.653026)
		(end 387.507734 -258.653026)
		(width 0.088646)
		(layer "F.Cu")
		(net "M_E_CPU0_SA_CB<7>")
	)
	(segment
		(start 416.235896 -270.641064)
		(end 416.035236 -270.841724)
		(width 0.20066)
		(layer "F.Cu")
		(net "M_E_CPU0_SA_CB<7>")
	)
	(segment
		(start 408.554682 -269.713202)
		(end 409.13304 -269.713202)
		(width 0.20066)
		(layer "F.Cu")
		(net "M_E_CPU0_SA_CB<7>")
	)
	(segment
		(start 405.082756 -269.89659)
		(end 405.082756 -270.472916)
		(width 0.20066)
		(layer "F.Cu")
		(net "M_E_CPU0_SA_CB<7>")
	)
	(segment
		(start 387.973824 -258.459986)
		(end 388.523988 -258.459986)
		(width 0.088646)
		(layer "F.Cu")
		(net "M_E_CPU0_SA_CB<7>")
	)
	(segment
		(start 386.32765 -258.399026)
		(end 386.532628 -258.399026)
		(width 0.088646)
		(layer "F.Cu")
		(net "M_E_CPU0_SA_CB<7>")
	)
	(segment
		(start 416.924236 -270.190214)
		(end 416.475418 -270.190214)
		(width 0.20066)
		(layer "F.Cu")
		(net "M_E_CPU0_SA_CB<7>")
	)
	(segment
		(start 386.004562 -258.2672)
		(end 386.32765 -258.399026)
		(width 0.088646)
		(layer "F.Cu")
		(net "M_E_CPU0_SA_CB<7>")
	)
	(segment
		(start 411.896306 -270.326612)
		(end 411.805882 -270.417036)
		(width 0.20066)
		(layer "F.Cu")
		(net "M_E_CPU0_SA_CB<7>")
	)
	(segment
		(start 407.958036 -270.841724)
		(end 408.173428 -270.841724)
		(width 0.20066)
		(layer "F.Cu")
		(net "M_E_CPU0_SA_CB<7>")
	)
	(segment
		(start 399.36166 -267.923518)
		(end 399.36166 -267.69441)
		(width 0.20066)
		(layer "F.Cu")
		(net "M_E_CPU0_SA_CB<7>")
	)
	(segment
		(start 411.805882 -270.417036)
		(end 410.853636 -270.417036)
		(width 0.20066)
		(layer "F.Cu")
		(net "M_E_CPU0_SA_CB<7>")
	)
	(segment
		(start 408.374342 -270.64081)
		(end 408.374342 -269.893542)
		(width 0.20066)
		(layer "F.Cu")
		(net "M_E_CPU0_SA_CB<7>")
	)
	(segment
		(start 415.231834 -270.841724)
		(end 413.322262 -270.841724)
		(width 0.1016)
		(layer "F.Cu")
		(net "M_E_CPU0_SA_CB<7>")
	)
	(segment
		(start 407.757884 -270.841724)
		(end 407.958036 -270.841724)
		(width 0.101854)
		(layer "F.Cu")
		(net "M_E_CPU0_SA_CB<7>")
	)
	(segment
		(start 409.13304 -269.713202)
		(end 409.83662 -270.416782)
		(width 0.20066)
		(layer "F.Cu")
		(net "M_E_CPU0_SA_CB<7>")
	)
	(segment
		(start 399.742152 -267.313918)
		(end 400.468592 -267.313918)
		(width 0.20066)
		(layer "F.Cu")
		(net "M_E_CPU0_SA_CB<7>")
	)
	(segment
		(start 412.905956 -270.841724)
		(end 412.390844 -270.326612)
		(width 0.20066)
		(layer "F.Cu")
		(net "M_E_CPU0_SA_CB<7>")
	)
	(segment
		(start 418.397182 -270.416782)
		(end 417.150804 -270.416782)
		(width 0.20066)
		(layer "F.Cu")
		(net "M_E_CPU0_SA_CB<7>")
	)
	(segment
		(start 408.374342 -269.893542)
		(end 408.554682 -269.713202)
		(width 0.20066)
		(layer "F.Cu")
		(net "M_E_CPU0_SA_CB<7>")
	)
	(segment
		(start 412.390844 -270.326612)
		(end 411.896306 -270.326612)
		(width 0.20066)
		(layer "F.Cu")
		(net "M_E_CPU0_SA_CB<7>")
	)
	(segment
		(start 416.235896 -270.429736)
		(end 416.235896 -270.641064)
		(width 0.20066)
		(layer "F.Cu")
		(net "M_E_CPU0_SA_CB<7>")
	)
	(segment
		(start 399.188686 -268.096492)
		(end 399.36166 -267.923518)
		(width 0.20066)
		(layer "F.Cu")
		(net "M_E_CPU0_SA_CB<7>")
	)
	(segment
		(start 399.36166 -267.69441)
		(end 399.742152 -267.313918)
		(width 0.20066)
		(layer "F.Cu")
		(net "M_E_CPU0_SA_CB<7>")
	)
	(segment
		(start 416.035236 -270.841724)
		(end 415.599372 -270.841724)
		(width 0.20066)
		(layer "F.Cu")
		(net "M_E_CPU0_SA_CB<7>")
	)
	(segment
		(start 405.729186 -270.841724)
		(end 407.757884 -270.841724)
		(width 0.1016)
		(layer "F.Cu")
		(net "M_E_CPU0_SA_CB<7>")
	)
	(segment
		(start 402.265896 -269.111222)
		(end 403.714712 -269.111222)
		(width 0.20066)
		(layer "F.Cu")
		(net "M_E_CPU0_SA_CB<7>")
	)
	(segment
		(start 413.107886 -270.841724)
		(end 412.905956 -270.841724)
		(width 0.20066)
		(layer "F.Cu")
		(net "M_E_CPU0_SA_CB<7>")
	)
	(segment
		(start 389.798306 -259.734304)
		(end 398.160494 -268.096492)
		(width 0.1016)
		(layer "F.Cu")
		(net "M_E_CPU0_SA_CB<7>")
	)
	(segment
		(start 388.523988 -258.459986)
		(end 389.798306 -259.734304)
		(width 0.088646)
		(layer "F.Cu")
		(net "M_E_CPU0_SA_CB<7>")
	)
	(segment
		(start 386.532628 -258.399026)
		(end 386.679694 -258.546092)
		(width 0.088646)
		(layer "F.Cu")
		(net "M_E_CPU0_SA_CB<7>")
	)
	(segment
		(start 413.322262 -270.841724)
		(end 413.107886 -270.841724)
		(width 0.101854)
		(layer "F.Cu")
		(net "M_E_CPU0_SA_CB<7>")
	)
	(segment
		(start 409.83662 -270.416782)
		(end 410.853382 -270.416782)
		(width 0.20066)
		(layer "F.Cu")
		(net "M_E_CPU0_SA_CB<7>")
	)
	(segment
		(start 405.451564 -270.841724)
		(end 405.564086 -270.841724)
		(width 0.20066)
		(layer "F.Cu")
		(net "M_E_CPU0_SA_CB<7>")
	)
	(segment
		(start 404.772368 -269.586202)
		(end 405.082756 -269.89659)
		(width 0.20066)
		(layer "F.Cu")
		(net "M_E_CPU0_SA_CB<7>")
	)
	(segment
		(start 399.013172 -268.096492)
		(end 399.188686 -268.096492)
		(width 0.20066)
		(layer "F.Cu")
		(net "M_E_CPU0_SA_CB<7>")
	)
	(segment
		(start 416.475418 -270.190214)
		(end 416.235896 -270.429736)
		(width 0.20066)
		(layer "F.Cu")
		(net "M_E_CPU0_SA_CB<7>")
	)
	(segment
		(start 405.564086 -270.841724)
		(end 405.729186 -270.841724)
		(width 0.101854)
		(layer "F.Cu")
		(net "M_E_CPU0_SA_CB<7>")
	)
	(segment
		(start 405.082756 -270.472916)
		(end 405.451564 -270.841724)
		(width 0.20066)
		(layer "F.Cu")
		(net "M_E_CPU0_SA_CB<7>")
	)
	(segment
		(start 386.679694 -258.546092)
		(end 386.758434 -258.591558)
		(width 0.088646)
		(layer "F.Cu")
		(net "M_E_CPU0_SA_CB<7>")
	)
	(arc
		(start 386.758434 -258.591558)
		(mid 386.868676 -258.63738)
		(end 386.987034 -258.653026)
		(width 0.088646)
		(layer "F.Cu")
		(net "M_E_CPU0_SA_CB<7>")
	)
	(segment
		(start 407.746454 -271.691608)
		(end 408.151076 -271.691608)
		(width 0.101854)
		(layer "F.Cu")
		(net "M_E_CPU0_SA_CB<6>")
	)
	(segment
		(start 388.864094 -259.886958)
		(end 389.088376 -259.886958)
		(width 0.088646)
		(layer "F.Cu")
		(net "M_E_CPU0_SA_CB<6>")
	)
	(segment
		(start 400.270472 -271.069054)
		(end 400.567144 -271.365726)
		(width 0.20066)
		(layer "F.Cu")
		(net "M_E_CPU0_SA_CB<6>")
	)
	(segment
		(start 405.178006 -271.691608)
		(end 405.32685 -271.691608)
		(width 0.20066)
		(layer "F.Cu")
		(net "M_E_CPU0_SA_CB<6>")
	)
	(segment
		(start 401.28571 -271.716754)
		(end 401.28571 -271.337278)
		(width 0.20066)
		(layer "F.Cu")
		(net "M_E_CPU0_SA_CB<6>")
	)
	(segment
		(start 415.985198 -272.541746)
		(end 415.599372 -272.541746)
		(width 0.20066)
		(layer "F.Cu")
		(net "M_E_CPU0_SA_CB<6>")
	)
	(segment
		(start 411.354778 -272.117058)
		(end 410.853636 -272.117058)
		(width 0.20066)
		(layer "F.Cu")
		(net "M_E_CPU0_SA_CB<6>")
	)
	(segment
		(start 386.734558 -259.078222)
		(end 386.797042 -259.139436)
		(width 0.088646)
		(layer "F.Cu")
		(net "M_E_CPU0_SA_CB<6>")
	)
	(segment
		(start 415.29508 -272.541746)
		(end 413.308292 -272.541746)
		(width 0.1016)
		(layer "F.Cu")
		(net "M_E_CPU0_SA_CB<6>")
	)
	(segment
		(start 404.34895 -272.083784)
		(end 404.78583 -272.083784)
		(width 0.20066)
		(layer "F.Cu")
		(net "M_E_CPU0_SA_CB<6>")
	)
	(segment
		(start 415.599372 -272.541746)
		(end 415.29508 -272.541746)
		(width 0.101854)
		(layer "F.Cu")
		(net "M_E_CPU0_SA_CB<6>")
	)
	(segment
		(start 413.107886 -272.541746)
		(end 413.008064 -272.541746)
		(width 0.20066)
		(layer "F.Cu")
		(net "M_E_CPU0_SA_CB<6>")
	)
	(segment
		(start 413.008064 -272.541746)
		(end 412.489904 -272.023586)
		(width 0.20066)
		(layer "F.Cu")
		(net "M_E_CPU0_SA_CB<6>")
	)
	(segment
		(start 410.046678 -272.116804)
		(end 410.853382 -272.116804)
		(width 0.20066)
		(layer "F.Cu")
		(net "M_E_CPU0_SA_CB<6>")
	)
	(segment
		(start 410.853636 -272.117058)
		(end 410.853382 -272.116804)
		(width 0.20066)
		(layer "F.Cu")
		(net "M_E_CPU0_SA_CB<6>")
	)
	(segment
		(start 389.088376 -259.886958)
		(end 389.379714 -260.178296)
		(width 0.088646)
		(layer "F.Cu")
		(net "M_E_CPU0_SA_CB<6>")
	)
	(segment
		(start 404.132034 -271.633188)
		(end 404.132034 -271.866868)
		(width 0.20066)
		(layer "F.Cu")
		(net "M_E_CPU0_SA_CB<6>")
	)
	(segment
		(start 408.972512 -272.209768)
		(end 409.183586 -271.998694)
		(width 0.20066)
		(layer "F.Cu")
		(net "M_E_CPU0_SA_CB<6>")
	)
	(segment
		(start 405.32685 -271.691608)
		(end 405.639524 -271.691608)
		(width 0.101854)
		(layer "F.Cu")
		(net "M_E_CPU0_SA_CB<6>")
	)
	(segment
		(start 416.291776 -271.638014)
		(end 416.206178 -271.723612)
		(width 0.20066)
		(layer "F.Cu")
		(net "M_E_CPU0_SA_CB<6>")
	)
	(segment
		(start 400.567144 -271.365726)
		(end 400.567144 -271.68221)
		(width 0.20066)
		(layer "F.Cu")
		(net "M_E_CPU0_SA_CB<6>")
	)
	(segment
		(start 416.206178 -271.723612)
		(end 416.206178 -272.320766)
		(width 0.20066)
		(layer "F.Cu")
		(net "M_E_CPU0_SA_CB<6>")
	)
	(segment
		(start 417.25723 -272.217642)
		(end 416.677602 -271.638014)
		(width 0.20066)
		(layer "F.Cu")
		(net "M_E_CPU0_SA_CB<6>")
	)
	(segment
		(start 412.489904 -272.023586)
		(end 411.44825 -272.023586)
		(width 0.20066)
		(layer "F.Cu")
		(net "M_E_CPU0_SA_CB<6>")
	)
	(segment
		(start 408.4828 -271.865598)
		(end 408.4828 -272.017998)
		(width 0.20066)
		(layer "F.Cu")
		(net "M_E_CPU0_SA_CB<6>")
	)
	(segment
		(start 404.78583 -272.083784)
		(end 405.178006 -271.691608)
		(width 0.20066)
		(layer "F.Cu")
		(net "M_E_CPU0_SA_CB<6>")
	)
	(segment
		(start 400.567144 -271.68221)
		(end 400.70913 -271.824196)
		(width 0.20066)
		(layer "F.Cu")
		(net "M_E_CPU0_SA_CB<6>")
	)
	(segment
		(start 388.547356 -259.366004)
		(end 388.547356 -259.57022)
		(width 0.088646)
		(layer "F.Cu")
		(net "M_E_CPU0_SA_CB<6>")
	)
	(segment
		(start 418.397182 -272.116804)
		(end 417.603686 -272.116804)
		(width 0.20066)
		(layer "F.Cu")
		(net "M_E_CPU0_SA_CB<6>")
	)
	(segment
		(start 402.189696 -270.433292)
		(end 402.932138 -270.433292)
		(width 0.20066)
		(layer "F.Cu")
		(net "M_E_CPU0_SA_CB<6>")
	)
	(segment
		(start 413.308292 -272.541746)
		(end 413.107886 -272.541746)
		(width 0.101854)
		(layer "F.Cu")
		(net "M_E_CPU0_SA_CB<6>")
	)
	(segment
		(start 408.151076 -271.691608)
		(end 408.30881 -271.691608)
		(width 0.20066)
		(layer "F.Cu")
		(net "M_E_CPU0_SA_CB<6>")
	)
	(segment
		(start 389.379714 -260.178296)
		(end 400.270472 -271.069054)
		(width 0.1016)
		(layer "F.Cu")
		(net "M_E_CPU0_SA_CB<6>")
	)
	(segment
		(start 409.183586 -271.998694)
		(end 409.928568 -271.998694)
		(width 0.20066)
		(layer "F.Cu")
		(net "M_E_CPU0_SA_CB<6>")
	)
	(segment
		(start 417.603686 -272.116804)
		(end 417.502848 -272.217642)
		(width 0.20066)
		(layer "F.Cu")
		(net "M_E_CPU0_SA_CB<6>")
	)
	(segment
		(start 416.677602 -271.638014)
		(end 416.291776 -271.638014)
		(width 0.20066)
		(layer "F.Cu")
		(net "M_E_CPU0_SA_CB<6>")
	)
	(segment
		(start 404.132034 -271.866868)
		(end 404.34895 -272.083784)
		(width 0.20066)
		(layer "F.Cu")
		(net "M_E_CPU0_SA_CB<6>")
	)
	(segment
		(start 416.206178 -272.320766)
		(end 415.985198 -272.541746)
		(width 0.20066)
		(layer "F.Cu")
		(net "M_E_CPU0_SA_CB<6>")
	)
	(segment
		(start 401.28571 -271.337278)
		(end 402.189696 -270.433292)
		(width 0.20066)
		(layer "F.Cu")
		(net "M_E_CPU0_SA_CB<6>")
	)
	(segment
		(start 388.320788 -259.139436)
		(end 388.547356 -259.366004)
		(width 0.088646)
		(layer "F.Cu")
		(net "M_E_CPU0_SA_CB<6>")
	)
	(segment
		(start 388.547356 -259.57022)
		(end 388.864094 -259.886958)
		(width 0.088646)
		(layer "F.Cu")
		(net "M_E_CPU0_SA_CB<6>")
	)
	(segment
		(start 408.30881 -271.691608)
		(end 408.4828 -271.865598)
		(width 0.20066)
		(layer "F.Cu")
		(net "M_E_CPU0_SA_CB<6>")
	)
	(segment
		(start 386.797042 -259.139436)
		(end 388.320788 -259.139436)
		(width 0.088646)
		(layer "F.Cu")
		(net "M_E_CPU0_SA_CB<6>")
	)
	(segment
		(start 411.44825 -272.023586)
		(end 411.354778 -272.117058)
		(width 0.20066)
		(layer "F.Cu")
		(net "M_E_CPU0_SA_CB<6>")
	)
	(segment
		(start 405.639524 -271.691608)
		(end 407.746454 -271.691608)
		(width 0.1016)
		(layer "F.Cu")
		(net "M_E_CPU0_SA_CB<6>")
	)
	(segment
		(start 401.178268 -271.824196)
		(end 401.28571 -271.716754)
		(width 0.20066)
		(layer "F.Cu")
		(net "M_E_CPU0_SA_CB<6>")
	)
	(segment
		(start 408.67457 -272.209768)
		(end 408.972512 -272.209768)
		(width 0.20066)
		(layer "F.Cu")
		(net "M_E_CPU0_SA_CB<6>")
	)
	(segment
		(start 409.928568 -271.998694)
		(end 410.046678 -272.116804)
		(width 0.20066)
		(layer "F.Cu")
		(net "M_E_CPU0_SA_CB<6>")
	)
	(segment
		(start 386.474716 -259.081016)
		(end 386.734558 -259.078222)
		(width 0.088646)
		(layer "F.Cu")
		(net "M_E_CPU0_SA_CB<6>")
	)
	(segment
		(start 402.932138 -270.433292)
		(end 404.132034 -271.633188)
		(width 0.20066)
		(layer "F.Cu")
		(net "M_E_CPU0_SA_CB<6>")
	)
	(segment
		(start 417.502848 -272.217642)
		(end 417.25723 -272.217642)
		(width 0.20066)
		(layer "F.Cu")
		(net "M_E_CPU0_SA_CB<6>")
	)
	(segment
		(start 408.4828 -272.017998)
		(end 408.67457 -272.209768)
		(width 0.20066)
		(layer "F.Cu")
		(net "M_E_CPU0_SA_CB<6>")
	)
	(segment
		(start 400.70913 -271.824196)
		(end 401.178268 -271.824196)
		(width 0.20066)
		(layer "F.Cu")
		(net "M_E_CPU0_SA_CB<6>")
	)
	(segment
		(start 403.847554 -270.25854)
		(end 404.146258 -270.25854)
		(width 0.20066)
		(layer "F.Cu")
		(net "M_E_CPU0_SA_CB<5>")
	)
	(segment
		(start 399.051272 -268.89329)
		(end 399.20291 -268.89329)
		(width 0.20066)
		(layer "F.Cu")
		(net "M_E_CPU0_SA_CB<5>")
	)
	(segment
		(start 400.115024 -268.148816)
		(end 400.398996 -268.148816)
		(width 0.20066)
		(layer "F.Cu")
		(net "M_E_CPU0_SA_CB<5>")
	)
	(segment
		(start 404.44801 -270.747236)
		(end 404.96744 -271.266666)
		(width 0.20066)
		(layer "F.Cu")
		(net "M_E_CPU0_SA_CB<5>")
	)
	(segment
		(start 385.376674 -258.396486)
		(end 385.668774 -258.688586)
		(width 0.088646)
		(layer "F.Cu")
		(net "M_E_CPU0_SA_CB<5>")
	)
	(segment
		(start 408.807158 -271.091406)
		(end 408.631898 -271.266666)
		(width 0.20066)
		(layer "F.Cu")
		(net "M_E_CPU0_SA_CB<5>")
	)
	(segment
		(start 403.378416 -269.789402)
		(end 403.847554 -270.25854)
		(width 0.20066)
		(layer "F.Cu")
		(net "M_E_CPU0_SA_CB<5>")
	)
	(segment
		(start 408.807158 -270.438626)
		(end 408.807158 -271.091406)
		(width 0.20066)
		(layer "F.Cu")
		(net "M_E_CPU0_SA_CB<5>")
	)
	(segment
		(start 408.631898 -271.266666)
		(end 406.753314 -271.266666)
		(width 0.20066)
		(layer "F.Cu")
		(net "M_E_CPU0_SA_CB<5>")
	)
	(segment
		(start 401.316952 -270.037052)
		(end 399.913856 -268.633956)
		(width 0.20066)
		(layer "F.Cu")
		(net "M_E_CPU0_SA_CB<5>")
	)
	(segment
		(start 401.316952 -270.321024)
		(end 401.316952 -270.037052)
		(width 0.20066)
		(layer "F.Cu")
		(net "M_E_CPU0_SA_CB<5>")
	)
	(segment
		(start 412.298134 -270.841724)
		(end 412.04261 -270.841724)
		(width 0.20066)
		(layer "F.Cu")
		(net "M_E_CPU0_SA_CB<5>")
	)
	(segment
		(start 387.354064 -258.932426)
		(end 387.430264 -258.856226)
		(width 0.088646)
		(layer "F.Cu")
		(net "M_E_CPU0_SA_CB<5>")
	)
	(segment
		(start 404.146258 -270.25854)
		(end 404.44801 -270.560292)
		(width 0.20066)
		(layer "F.Cu")
		(net "M_E_CPU0_SA_CB<5>")
	)
	(segment
		(start 404.96744 -271.266666)
		(end 406.753314 -271.266666)
		(width 0.20066)
		(layer "F.Cu")
		(net "M_E_CPU0_SA_CB<5>")
	)
	(segment
		(start 385.064762 -258.2672)
		(end 385.376674 -258.396486)
		(width 0.088646)
		(layer "F.Cu")
		(net "M_E_CPU0_SA_CB<5>")
	)
	(segment
		(start 409.915614 -270.841724)
		(end 409.631134 -270.841724)
		(width 0.101854)
		(layer "F.Cu")
		(net "M_E_CPU0_SA_CB<5>")
	)
	(segment
		(start 412.723076 -271.266666)
		(end 412.298134 -270.841724)
		(width 0.20066)
		(layer "F.Cu")
		(net "M_E_CPU0_SA_CB<5>")
	)
	(segment
		(start 386.658612 -258.753864)
		(end 386.820664 -258.881626)
		(width 0.088646)
		(layer "F.Cu")
		(net "M_E_CPU0_SA_CB<5>")
	)
	(segment
		(start 386.820664 -258.881626)
		(end 386.871464 -258.932426)
		(width 0.088646)
		(layer "F.Cu")
		(net "M_E_CPU0_SA_CB<5>")
	)
	(segment
		(start 389.59536 -259.96265)
		(end 398.526 -268.89329)
		(width 0.1016)
		(layer "F.Cu")
		(net "M_E_CPU0_SA_CB<5>")
	)
	(segment
		(start 409.122118 -270.332708)
		(end 408.913076 -270.332708)
		(width 0.20066)
		(layer "F.Cu")
		(net "M_E_CPU0_SA_CB<5>")
	)
	(segment
		(start 400.831812 -270.522192)
		(end 401.115784 -270.522192)
		(width 0.20066)
		(layer "F.Cu")
		(net "M_E_CPU0_SA_CB<5>")
	)
	(segment
		(start 402.039582 -269.789402)
		(end 403.378416 -269.789402)
		(width 0.20066)
		(layer "F.Cu")
		(net "M_E_CPU0_SA_CB<5>")
	)
	(segment
		(start 386.871464 -258.932426)
		(end 387.354064 -258.932426)
		(width 0.088646)
		(layer "F.Cu")
		(net "M_E_CPU0_SA_CB<5>")
	)
	(segment
		(start 414.297114 -271.266666)
		(end 412.723076 -271.266666)
		(width 0.20066)
		(layer "F.Cu")
		(net "M_E_CPU0_SA_CB<5>")
	)
	(segment
		(start 409.631134 -270.841724)
		(end 409.551124 -270.761714)
		(width 0.101854)
		(layer "F.Cu")
		(net "M_E_CPU0_SA_CB<5>")
	)
	(segment
		(start 388.488936 -258.856226)
		(end 389.59536 -259.96265)
		(width 0.088646)
		(layer "F.Cu")
		(net "M_E_CPU0_SA_CB<5>")
	)
	(segment
		(start 398.526 -268.89329)
		(end 399.051272 -268.89329)
		(width 0.1016)
		(layer "F.Cu")
		(net "M_E_CPU0_SA_CB<5>")
	)
	(segment
		(start 404.44801 -270.560292)
		(end 404.44801 -270.747236)
		(width 0.20066)
		(layer "F.Cu")
		(net "M_E_CPU0_SA_CB<5>")
	)
	(segment
		(start 408.913076 -270.332708)
		(end 408.807158 -270.438626)
		(width 0.20066)
		(layer "F.Cu")
		(net "M_E_CPU0_SA_CB<5>")
	)
	(segment
		(start 385.668774 -258.688586)
		(end 386.408168 -258.688586)
		(width 0.088646)
		(layer "F.Cu")
		(net "M_E_CPU0_SA_CB<5>")
	)
	(segment
		(start 401.115784 -270.522192)
		(end 401.316952 -270.321024)
		(width 0.20066)
		(layer "F.Cu")
		(net "M_E_CPU0_SA_CB<5>")
	)
	(segment
		(start 387.430264 -258.856226)
		(end 388.488936 -258.856226)
		(width 0.088646)
		(layer "F.Cu")
		(net "M_E_CPU0_SA_CB<5>")
	)
	(segment
		(start 411.843474 -270.841724)
		(end 409.915614 -270.841724)
		(width 0.1016)
		(layer "F.Cu")
		(net "M_E_CPU0_SA_CB<5>")
	)
	(segment
		(start 412.04261 -270.841724)
		(end 411.843474 -270.841724)
		(width 0.101854)
		(layer "F.Cu")
		(net "M_E_CPU0_SA_CB<5>")
	)
	(segment
		(start 399.20291 -268.89329)
		(end 400.831812 -270.522192)
		(width 0.20066)
		(layer "F.Cu")
		(net "M_E_CPU0_SA_CB<5>")
	)
	(segment
		(start 409.551124 -270.761714)
		(end 409.122118 -270.332708)
		(width 0.20066)
		(layer "F.Cu")
		(net "M_E_CPU0_SA_CB<5>")
	)
	(segment
		(start 399.913856 -268.633956)
		(end 399.913856 -268.349984)
		(width 0.20066)
		(layer "F.Cu")
		(net "M_E_CPU0_SA_CB<5>")
	)
	(segment
		(start 399.913856 -268.349984)
		(end 400.115024 -268.148816)
		(width 0.20066)
		(layer "F.Cu")
		(net "M_E_CPU0_SA_CB<5>")
	)
	(segment
		(start 400.398996 -268.148816)
		(end 402.039582 -269.789402)
		(width 0.20066)
		(layer "F.Cu")
		(net "M_E_CPU0_SA_CB<5>")
	)
	(arc
		(start 386.408168 -258.688586)
		(mid 386.537566 -258.705188)
		(end 386.658612 -258.753864)
		(width 0.088646)
		(layer "F.Cu")
		(net "M_E_CPU0_SA_CB<5>")
	)
	(segment
		(start 401.092162 -272.668238)
		(end 401.292822 -272.467578)
		(width 0.20066)
		(layer "F.Cu")
		(net "M_E_CPU0_SA_CB<4>")
	)
	(segment
		(start 412.858204 -272.966688)
		(end 412.433262 -272.541746)
		(width 0.20066)
		(layer "F.Cu")
		(net "M_E_CPU0_SA_CB<4>")
	)
	(segment
		(start 400.165062 -272.557748)
		(end 400.165062 -272.558002)
		(width 0.101854)
		(layer "F.Cu")
		(net "M_E_CPU0_SA_CB<4>")
	)
	(segment
		(start 408.566112 -273.175476)
		(end 408.236674 -272.846038)
		(width 0.20066)
		(layer "F.Cu")
		(net "M_E_CPU0_SA_CB<4>")
	)
	(segment
		(start 402.182076 -272.041112)
		(end 401.981416 -271.840452)
		(width 0.20066)
		(layer "F.Cu")
		(net "M_E_CPU0_SA_CB<4>")
	)
	(segment
		(start 404.090886 -272.726912)
		(end 404.915116 -272.726912)
		(width 0.20066)
		(layer "F.Cu")
		(net "M_E_CPU0_SA_CB<4>")
	)
	(segment
		(start 402.182076 -271.355312)
		(end 402.791676 -271.355312)
		(width 0.20066)
		(layer "F.Cu")
		(net "M_E_CPU0_SA_CB<4>")
	)
	(segment
		(start 386.757164 -259.329682)
		(end 387.973824 -259.329682)
		(width 0.088646)
		(layer "F.Cu")
		(net "M_E_CPU0_SA_CB<4>")
	)
	(segment
		(start 402.792946 -272.32864)
		(end 402.505418 -272.041112)
		(width 0.20066)
		(layer "F.Cu")
		(net "M_E_CPU0_SA_CB<4>")
	)
	(segment
		(start 402.099018 -272.989294)
		(end 402.416264 -272.989294)
		(width 0.20066)
		(layer "F.Cu")
		(net "M_E_CPU0_SA_CB<4>")
	)
	(segment
		(start 408.236674 -272.846038)
		(end 407.865834 -272.846038)
		(width 0.20066)
		(layer "F.Cu")
		(net "M_E_CPU0_SA_CB<4>")
	)
	(segment
		(start 412.251144 -272.541746)
		(end 411.689804 -272.541746)
		(width 0.101854)
		(layer "F.Cu")
		(net "M_E_CPU0_SA_CB<4>")
	)
	(segment
		(start 403.488398 -272.644108)
		(end 403.689058 -272.844768)
		(width 0.20066)
		(layer "F.Cu")
		(net "M_E_CPU0_SA_CB<4>")
	)
	(segment
		(start 400.891502 -273.00047)
		(end 401.092162 -272.79981)
		(width 0.20066)
		(layer "F.Cu")
		(net "M_E_CPU0_SA_CB<4>")
	)
	(segment
		(start 385.350766 -259.41782)
		(end 385.674108 -259.482082)
		(width 0.088646)
		(layer "F.Cu")
		(net "M_E_CPU0_SA_CB<4>")
	)
	(segment
		(start 403.689058 -272.844768)
		(end 403.97303 -272.844768)
		(width 0.20066)
		(layer "F.Cu")
		(net "M_E_CPU0_SA_CB<4>")
	)
	(segment
		(start 386.740908 -259.345938)
		(end 386.757164 -259.329682)
		(width 0.088646)
		(layer "F.Cu")
		(net "M_E_CPU0_SA_CB<4>")
	)
	(segment
		(start 384.595116 -259.081016)
		(end 384.607054 -259.109718)
		(width 0.088646)
		(layer "F.Cu")
		(net "M_E_CPU0_SA_CB<4>")
	)
	(segment
		(start 407.745184 -272.966688)
		(end 406.753314 -272.966688)
		(width 0.20066)
		(layer "F.Cu")
		(net "M_E_CPU0_SA_CB<4>")
	)
	(segment
		(start 388.934452 -260.164326)
		(end 389.156702 -260.386576)
		(width 0.088646)
		(layer "F.Cu")
		(net "M_E_CPU0_SA_CB<4>")
	)
	(segment
		(start 388.808468 -260.164326)
		(end 388.934452 -260.164326)
		(width 0.088646)
		(layer "F.Cu")
		(net "M_E_CPU0_SA_CB<4>")
	)
	(segment
		(start 405.154892 -272.966688)
		(end 406.753314 -272.966688)
		(width 0.20066)
		(layer "F.Cu")
		(net "M_E_CPU0_SA_CB<4>")
	)
	(segment
		(start 414.297114 -272.966688)
		(end 412.858204 -272.966688)
		(width 0.20066)
		(layer "F.Cu")
		(net "M_E_CPU0_SA_CB<4>")
	)
	(segment
		(start 407.865834 -272.846038)
		(end 407.745184 -272.966688)
		(width 0.20066)
		(layer "F.Cu")
		(net "M_E_CPU0_SA_CB<4>")
	)
	(segment
		(start 386.657342 -259.408676)
		(end 386.663184 -259.405374)
		(width 0.088646)
		(layer "F.Cu")
		(net "M_E_CPU0_SA_CB<4>")
	)
	(segment
		(start 400.60753 -273.00047)
		(end 400.891502 -273.00047)
		(width 0.20066)
		(layer "F.Cu")
		(net "M_E_CPU0_SA_CB<4>")
	)
	(segment
		(start 400.165062 -272.558002)
		(end 400.60753 -273.00047)
		(width 0.20066)
		(layer "F.Cu")
		(net "M_E_CPU0_SA_CB<4>")
	)
	(segment
		(start 401.981416 -271.840452)
		(end 401.981416 -271.555972)
		(width 0.20066)
		(layer "F.Cu")
		(net "M_E_CPU0_SA_CB<4>")
	)
	(segment
		(start 409.31973 -272.541746)
		(end 409.085542 -272.775934)
		(width 0.20066)
		(layer "F.Cu")
		(net "M_E_CPU0_SA_CB<4>")
	)
	(segment
		(start 408.884628 -273.175476)
		(end 408.566112 -273.175476)
		(width 0.20066)
		(layer "F.Cu")
		(net "M_E_CPU0_SA_CB<4>")
	)
	(segment
		(start 384.607054 -259.109718)
		(end 385.350766 -259.41782)
		(width 0.088646)
		(layer "F.Cu")
		(net "M_E_CPU0_SA_CB<4>")
	)
	(segment
		(start 404.915116 -272.726912)
		(end 405.154892 -272.966688)
		(width 0.20066)
		(layer "F.Cu")
		(net "M_E_CPU0_SA_CB<4>")
	)
	(segment
		(start 402.792946 -272.612612)
		(end 402.792946 -272.32864)
		(width 0.20066)
		(layer "F.Cu")
		(net "M_E_CPU0_SA_CB<4>")
	)
	(segment
		(start 399.994374 -272.38706)
		(end 400.165062 -272.557748)
		(width 0.1016)
		(layer "F.Cu")
		(net "M_E_CPU0_SA_CB<4>")
	)
	(segment
		(start 412.433262 -272.541746)
		(end 412.251144 -272.541746)
		(width 0.20066)
		(layer "F.Cu")
		(net "M_E_CPU0_SA_CB<4>")
	)
	(segment
		(start 409.845764 -272.541746)
		(end 409.426918 -272.541746)
		(width 0.101854)
		(layer "F.Cu")
		(net "M_E_CPU0_SA_CB<4>")
	)
	(segment
		(start 387.973824 -259.329682)
		(end 388.808468 -260.164326)
		(width 0.088646)
		(layer "F.Cu")
		(net "M_E_CPU0_SA_CB<4>")
	)
	(segment
		(start 409.085542 -272.775934)
		(end 409.085542 -272.974562)
		(width 0.20066)
		(layer "F.Cu")
		(net "M_E_CPU0_SA_CB<4>")
	)
	(segment
		(start 402.416264 -272.989294)
		(end 402.792946 -272.612612)
		(width 0.20066)
		(layer "F.Cu")
		(net "M_E_CPU0_SA_CB<4>")
	)
	(segment
		(start 401.981416 -271.555972)
		(end 402.182076 -271.355312)
		(width 0.20066)
		(layer "F.Cu")
		(net "M_E_CPU0_SA_CB<4>")
	)
	(segment
		(start 401.292822 -272.467578)
		(end 401.577302 -272.467578)
		(width 0.20066)
		(layer "F.Cu")
		(net "M_E_CPU0_SA_CB<4>")
	)
	(segment
		(start 402.505418 -272.041112)
		(end 402.182076 -272.041112)
		(width 0.20066)
		(layer "F.Cu")
		(net "M_E_CPU0_SA_CB<4>")
	)
	(segment
		(start 411.689804 -272.541746)
		(end 409.845764 -272.541746)
		(width 0.1016)
		(layer "F.Cu")
		(net "M_E_CPU0_SA_CB<4>")
	)
	(segment
		(start 385.674108 -259.482082)
		(end 386.424424 -259.482082)
		(width 0.088646)
		(layer "F.Cu")
		(net "M_E_CPU0_SA_CB<4>")
	)
	(segment
		(start 399.704306 -270.93418)
		(end 399.994374 -272.38706)
		(width 0.1016)
		(layer "F.Cu")
		(net "M_E_CPU0_SA_CB<4>")
	)
	(segment
		(start 401.577302 -272.467578)
		(end 402.099018 -272.989294)
		(width 0.20066)
		(layer "F.Cu")
		(net "M_E_CPU0_SA_CB<4>")
	)
	(segment
		(start 401.092162 -272.79981)
		(end 401.092162 -272.668238)
		(width 0.20066)
		(layer "F.Cu")
		(net "M_E_CPU0_SA_CB<4>")
	)
	(segment
		(start 409.085542 -272.974562)
		(end 408.884628 -273.175476)
		(width 0.20066)
		(layer "F.Cu")
		(net "M_E_CPU0_SA_CB<4>")
	)
	(segment
		(start 409.426918 -272.541746)
		(end 409.31973 -272.541746)
		(width 0.20066)
		(layer "F.Cu")
		(net "M_E_CPU0_SA_CB<4>")
	)
	(segment
		(start 402.791676 -271.355312)
		(end 403.488398 -272.052034)
		(width 0.20066)
		(layer "F.Cu")
		(net "M_E_CPU0_SA_CB<4>")
	)
	(segment
		(start 403.97303 -272.844768)
		(end 404.090886 -272.726912)
		(width 0.20066)
		(layer "F.Cu")
		(net "M_E_CPU0_SA_CB<4>")
	)
	(segment
		(start 403.488398 -272.052034)
		(end 403.488398 -272.644108)
		(width 0.20066)
		(layer "F.Cu")
		(net "M_E_CPU0_SA_CB<4>")
	)
	(segment
		(start 389.156702 -260.386576)
		(end 399.704306 -270.93418)
		(width 0.1016)
		(layer "F.Cu")
		(net "M_E_CPU0_SA_CB<4>")
	)
	(arc
		(start 386.512562 -259.469636)
		(mid 386.586731 -259.443379)
		(end 386.657342 -259.408676)
		(width 0.088646)
		(layer "F.Cu")
		(net "M_E_CPU0_SA_CB<4>")
	)
	(arc
		(start 386.424424 -259.482082)
		(mid 386.468933 -259.478973)
		(end 386.512562 -259.469636)
		(width 0.088646)
		(layer "F.Cu")
		(net "M_E_CPU0_SA_CB<4>")
	)
	(arc
		(start 386.663184 -259.405374)
		(mid 386.704005 -259.378216)
		(end 386.740908 -259.345938)
		(width 0.088646)
		(layer "F.Cu")
		(net "M_E_CPU0_SA_CB<4>")
	)
	(segment
		(start 416.642296 -276.090126)
		(end 416.358324 -276.090126)
		(width 0.20066)
		(layer "F.Cu")
		(net "M_E_CPU0_SA_CB<3>")
	)
	(segment
		(start 408.578304 -276.366732)
		(end 410.853382 -276.366732)
		(width 0.20066)
		(layer "F.Cu")
		(net "M_E_CPU0_SA_CB<3>")
	)
	(segment
		(start 415.202116 -276.791674)
		(end 413.310324 -276.791674)
		(width 0.1016)
		(layer "F.Cu")
		(net "M_E_CPU0_SA_CB<3>")
	)
	(segment
		(start 404.79599 -276.163024)
		(end 405.017478 -275.941536)
		(width 0.20066)
		(layer "F.Cu")
		(net "M_E_CPU0_SA_CB<3>")
	)
	(segment
		(start 388.536942 -261.924038)
		(end 388.834884 -262.22198)
		(width 0.088646)
		(layer "F.Cu")
		(net "M_E_CPU0_SA_CB<3>")
	)
	(segment
		(start 412.308548 -276.366732)
		(end 410.853382 -276.366732)
		(width 0.20066)
		(layer "F.Cu")
		(net "M_E_CPU0_SA_CB<3>")
	)
	(segment
		(start 415.957004 -276.791674)
		(end 415.846768 -276.791674)
		(width 0.20066)
		(layer "F.Cu")
		(net "M_E_CPU0_SA_CB<3>")
	)
	(segment
		(start 412.91764 -276.791674)
		(end 412.73349 -276.791674)
		(width 0.20066)
		(layer "F.Cu")
		(net "M_E_CPU0_SA_CB<3>")
	)
	(segment
		(start 416.157664 -276.591014)
		(end 415.957004 -276.791674)
		(width 0.20066)
		(layer "F.Cu")
		(net "M_E_CPU0_SA_CB<3>")
	)
	(segment
		(start 405.75865 -275.941536)
		(end 407.747216 -275.941536)
		(width 0.1016)
		(layer "F.Cu")
		(net "M_E_CPU0_SA_CB<3>")
	)
	(segment
		(start 387.58241 -260.862064)
		(end 388.536942 -261.816596)
		(width 0.088646)
		(layer "F.Cu")
		(net "M_E_CPU0_SA_CB<3>")
	)
	(segment
		(start 407.942542 -275.941536)
		(end 408.153108 -275.941536)
		(width 0.20066)
		(layer "F.Cu")
		(net "M_E_CPU0_SA_CB<3>")
	)
	(segment
		(start 398.244822 -271.631918)
		(end 398.281398 -271.700498)
		(width 0.1016)
		(layer "F.Cu")
		(net "M_E_CPU0_SA_CB<3>")
	)
	(segment
		(start 418.397182 -276.366732)
		(end 416.918902 -276.366732)
		(width 0.20066)
		(layer "F.Cu")
		(net "M_E_CPU0_SA_CB<3>")
	)
	(segment
		(start 407.747216 -275.941536)
		(end 407.942542 -275.941536)
		(width 0.101854)
		(layer "F.Cu")
		(net "M_E_CPU0_SA_CB<3>")
	)
	(segment
		(start 399.697956 -275.792184)
		(end 400.296126 -275.792184)
		(width 0.1016)
		(layer "F.Cu")
		(net "M_E_CPU0_SA_CB<3>")
	)
	(segment
		(start 405.017478 -275.941536)
		(end 405.451056 -275.941536)
		(width 0.20066)
		(layer "F.Cu")
		(net "M_E_CPU0_SA_CB<3>")
	)
	(segment
		(start 403.952202 -275.792184)
		(end 404.323042 -276.163024)
		(width 0.20066)
		(layer "F.Cu")
		(net "M_E_CPU0_SA_CB<3>")
	)
	(segment
		(start 416.358324 -276.090126)
		(end 416.157664 -276.290786)
		(width 0.20066)
		(layer "F.Cu")
		(net "M_E_CPU0_SA_CB<3>")
	)
	(segment
		(start 386.84454 -260.862064)
		(end 387.58241 -260.862064)
		(width 0.088646)
		(layer "F.Cu")
		(net "M_E_CPU0_SA_CB<3>")
	)
	(segment
		(start 412.73349 -276.791674)
		(end 412.308548 -276.366732)
		(width 0.20066)
		(layer "F.Cu")
		(net "M_E_CPU0_SA_CB<3>")
	)
	(segment
		(start 398.949926 -275.044154)
		(end 399.697956 -275.792184)
		(width 0.1016)
		(layer "F.Cu")
		(net "M_E_CPU0_SA_CB<3>")
	)
	(segment
		(start 408.153108 -275.941536)
		(end 408.578304 -276.366732)
		(width 0.20066)
		(layer "F.Cu")
		(net "M_E_CPU0_SA_CB<3>")
	)
	(segment
		(start 415.846768 -276.791674)
		(end 415.202116 -276.791674)
		(width 0.101854)
		(layer "F.Cu")
		(net "M_E_CPU0_SA_CB<3>")
	)
	(segment
		(start 416.918902 -276.366732)
		(end 416.642296 -276.090126)
		(width 0.20066)
		(layer "F.Cu")
		(net "M_E_CPU0_SA_CB<3>")
	)
	(segment
		(start 416.157664 -276.290786)
		(end 416.157664 -276.591014)
		(width 0.20066)
		(layer "F.Cu")
		(net "M_E_CPU0_SA_CB<3>")
	)
	(segment
		(start 386.474716 -260.708902)
		(end 386.84454 -260.862064)
		(width 0.088646)
		(layer "F.Cu")
		(net "M_E_CPU0_SA_CB<3>")
	)
	(segment
		(start 413.310324 -276.791674)
		(end 412.91764 -276.791674)
		(width 0.101854)
		(layer "F.Cu")
		(net "M_E_CPU0_SA_CB<3>")
	)
	(segment
		(start 388.536942 -261.816596)
		(end 388.536942 -261.924038)
		(width 0.088646)
		(layer "F.Cu")
		(net "M_E_CPU0_SA_CB<3>")
	)
	(segment
		(start 398.281398 -271.700498)
		(end 398.949926 -275.044154)
		(width 0.1016)
		(layer "F.Cu")
		(net "M_E_CPU0_SA_CB<3>")
	)
	(segment
		(start 405.451056 -275.941536)
		(end 405.75865 -275.941536)
		(width 0.101854)
		(layer "F.Cu")
		(net "M_E_CPU0_SA_CB<3>")
	)
	(segment
		(start 404.323042 -276.163024)
		(end 404.79599 -276.163024)
		(width 0.20066)
		(layer "F.Cu")
		(net "M_E_CPU0_SA_CB<3>")
	)
	(segment
		(start 388.834884 -262.22198)
		(end 398.244822 -271.631918)
		(width 0.1016)
		(layer "F.Cu")
		(net "M_E_CPU0_SA_CB<3>")
	)
	(segment
		(start 400.296126 -275.792184)
		(end 403.952202 -275.792184)
		(width 0.20066)
		(layer "F.Cu")
		(net "M_E_CPU0_SA_CB<3>")
	)
	(segment
		(start 416.588194 -277.803356)
		(end 416.588194 -277.523956)
		(width 0.20066)
		(layer "F.Cu")
		(net "M_E_CPU0_SA_CB<2>")
	)
	(segment
		(start 415.266378 -277.641812)
		(end 413.302196 -277.641812)
		(width 0.1016)
		(layer "F.Cu")
		(net "M_E_CPU0_SA_CB<2>")
	)
	(segment
		(start 405.063706 -277.864824)
		(end 405.286972 -277.641558)
		(width 0.20066)
		(layer "F.Cu")
		(net "M_E_CPU0_SA_CB<2>")
	)
	(segment
		(start 401.715224 -277.284688)
		(end 403.181566 -277.284688)
		(width 0.20066)
		(layer "F.Cu")
		(net "M_E_CPU0_SA_CB<2>")
	)
	(segment
		(start 416.423094 -277.358856)
		(end 415.549334 -277.358856)
		(width 0.20066)
		(layer "F.Cu")
		(net "M_E_CPU0_SA_CB<2>")
	)
	(segment
		(start 412.222188 -277.966678)
		(end 411.562042 -277.966678)
		(width 0.20066)
		(layer "F.Cu")
		(net "M_E_CPU0_SA_CB<2>")
	)
	(segment
		(start 415.549334 -277.358856)
		(end 415.379408 -277.528782)
		(width 0.20066)
		(layer "F.Cu")
		(net "M_E_CPU0_SA_CB<2>")
	)
	(segment
		(start 388.390638 -262.640318)
		(end 397.711168 -271.960848)
		(width 0.1016)
		(layer "F.Cu")
		(net "M_E_CPU0_SA_CB<2>")
	)
	(segment
		(start 403.181566 -277.284688)
		(end 403.761702 -277.864824)
		(width 0.20066)
		(layer "F.Cu")
		(net "M_E_CPU0_SA_CB<2>")
	)
	(segment
		(start 387.807454 -262.466328)
		(end 388.216648 -262.466328)
		(width 0.088646)
		(layer "F.Cu")
		(net "M_E_CPU0_SA_CB<2>")
	)
	(segment
		(start 386.356352 -261.616698)
		(end 386.757164 -261.847076)
		(width 0.088646)
		(layer "F.Cu")
		(net "M_E_CPU0_SA_CB<2>")
	)
	(segment
		(start 401.543774 -277.113238)
		(end 401.715224 -277.284688)
		(width 0.20066)
		(layer "F.Cu")
		(net "M_E_CPU0_SA_CB<2>")
	)
	(segment
		(start 408.4828 -277.984966)
		(end 409.337002 -277.984966)
		(width 0.20066)
		(layer "F.Cu")
		(net "M_E_CPU0_SA_CB<2>")
	)
	(segment
		(start 400.29638 -277.113238)
		(end 401.543774 -277.113238)
		(width 0.20066)
		(layer "F.Cu")
		(net "M_E_CPU0_SA_CB<2>")
	)
	(segment
		(start 418.397182 -278.066754)
		(end 416.851592 -278.066754)
		(width 0.20066)
		(layer "F.Cu")
		(net "M_E_CPU0_SA_CB<2>")
	)
	(segment
		(start 407.730706 -277.641558)
		(end 407.942542 -277.641558)
		(width 0.101854)
		(layer "F.Cu")
		(net "M_E_CPU0_SA_CB<2>")
	)
	(segment
		(start 388.216648 -262.466328)
		(end 388.390638 -262.640318)
		(width 0.088646)
		(layer "F.Cu")
		(net "M_E_CPU0_SA_CB<2>")
	)
	(segment
		(start 398.903698 -276.763734)
		(end 399.475452 -277.113238)
		(width 0.1016)
		(layer "F.Cu")
		(net "M_E_CPU0_SA_CB<2>")
	)
	(segment
		(start 411.562042 -277.966678)
		(end 411.461966 -278.066754)
		(width 0.20066)
		(layer "F.Cu")
		(net "M_E_CPU0_SA_CB<2>")
	)
	(segment
		(start 416.588194 -277.523956)
		(end 416.423094 -277.358856)
		(width 0.20066)
		(layer "F.Cu")
		(net "M_E_CPU0_SA_CB<2>")
	)
	(segment
		(start 412.547054 -277.641812)
		(end 412.222188 -277.966678)
		(width 0.20066)
		(layer "F.Cu")
		(net "M_E_CPU0_SA_CB<2>")
	)
	(segment
		(start 386.888482 -261.95147)
		(end 387.332728 -262.251952)
		(width 0.088646)
		(layer "F.Cu")
		(net "M_E_CPU0_SA_CB<2>")
	)
	(segment
		(start 387.332728 -262.251952)
		(end 387.526022 -262.3185)
		(width 0.088646)
		(layer "F.Cu")
		(net "M_E_CPU0_SA_CB<2>")
	)
	(segment
		(start 399.475452 -277.113238)
		(end 400.29638 -277.113238)
		(width 0.1016)
		(layer "F.Cu")
		(net "M_E_CPU0_SA_CB<2>")
	)
	(segment
		(start 405.451056 -277.641558)
		(end 405.764746 -277.641558)
		(width 0.101854)
		(layer "F.Cu")
		(net "M_E_CPU0_SA_CB<2>")
	)
	(segment
		(start 413.302196 -277.641812)
		(end 412.994856 -277.641812)
		(width 0.101854)
		(layer "F.Cu")
		(net "M_E_CPU0_SA_CB<2>")
	)
	(segment
		(start 405.764746 -277.641558)
		(end 407.730706 -277.641558)
		(width 0.1016)
		(layer "F.Cu")
		(net "M_E_CPU0_SA_CB<2>")
	)
	(segment
		(start 409.337002 -277.984966)
		(end 409.928822 -278.066754)
		(width 0.20066)
		(layer "F.Cu")
		(net "M_E_CPU0_SA_CB<2>")
	)
	(segment
		(start 416.851592 -278.066754)
		(end 416.588194 -277.803356)
		(width 0.20066)
		(layer "F.Cu")
		(net "M_E_CPU0_SA_CB<2>")
	)
	(segment
		(start 397.711168 -271.960848)
		(end 398.571974 -276.266402)
		(width 0.1016)
		(layer "F.Cu")
		(net "M_E_CPU0_SA_CB<2>")
	)
	(segment
		(start 403.761702 -277.864824)
		(end 405.063706 -277.864824)
		(width 0.20066)
		(layer "F.Cu")
		(net "M_E_CPU0_SA_CB<2>")
	)
	(segment
		(start 407.942542 -277.641558)
		(end 408.139392 -277.641558)
		(width 0.20066)
		(layer "F.Cu")
		(net "M_E_CPU0_SA_CB<2>")
	)
	(segment
		(start 398.571974 -276.266402)
		(end 398.903698 -276.763734)
		(width 0.1016)
		(layer "F.Cu")
		(net "M_E_CPU0_SA_CB<2>")
	)
	(segment
		(start 415.379408 -277.528782)
		(end 415.266378 -277.641812)
		(width 0.101854)
		(layer "F.Cu")
		(net "M_E_CPU0_SA_CB<2>")
	)
	(segment
		(start 408.139392 -277.641558)
		(end 408.4828 -277.984966)
		(width 0.20066)
		(layer "F.Cu")
		(net "M_E_CPU0_SA_CB<2>")
	)
	(segment
		(start 412.994856 -277.641812)
		(end 412.547054 -277.641812)
		(width 0.20066)
		(layer "F.Cu")
		(net "M_E_CPU0_SA_CB<2>")
	)
	(segment
		(start 405.286972 -277.641558)
		(end 405.451056 -277.641558)
		(width 0.20066)
		(layer "F.Cu")
		(net "M_E_CPU0_SA_CB<2>")
	)
	(segment
		(start 409.928822 -278.066754)
		(end 410.853382 -278.066754)
		(width 0.20066)
		(layer "F.Cu")
		(net "M_E_CPU0_SA_CB<2>")
	)
	(segment
		(start 411.461966 -278.066754)
		(end 410.853382 -278.066754)
		(width 0.20066)
		(layer "F.Cu")
		(net "M_E_CPU0_SA_CB<2>")
	)
	(arc
		(start 386.85851 -261.921498)
		(mid 386.873777 -261.936203)
		(end 386.888482 -261.95147)
		(width 0.088646)
		(layer "F.Cu")
		(net "M_E_CPU0_SA_CB<2>")
	)
	(arc
		(start 386.004562 -261.522718)
		(mid 386.186633 -261.546604)
		(end 386.356352 -261.616698)
		(width 0.088646)
		(layer "F.Cu")
		(net "M_E_CPU0_SA_CB<2>")
	)
	(arc
		(start 386.757164 -261.847076)
		(mid 386.80992 -261.881452)
		(end 386.85851 -261.921498)
		(width 0.088646)
		(layer "F.Cu")
		(net "M_E_CPU0_SA_CB<2>")
	)
	(arc
		(start 387.526022 -262.3185)
		(mid 387.617423 -262.345044)
		(end 387.70306 -262.386572)
		(width 0.088646)
		(layer "F.Cu")
		(net "M_E_CPU0_SA_CB<2>")
	)
	(arc
		(start 387.70306 -262.386572)
		(mid 387.757584 -262.423405)
		(end 387.807454 -262.466328)
		(width 0.088646)
		(layer "F.Cu")
		(net "M_E_CPU0_SA_CB<2>")
	)
	(segment
		(start 397.9926 -271.810988)
		(end 398.759426 -275.647404)
		(width 0.1016)
		(layer "F.Cu")
		(net "M_E_CPU0_SA_CB<1>")
	)
	(segment
		(start 403.090888 -276.628098)
		(end 403.271228 -276.447758)
		(width 0.20066)
		(layer "F.Cu")
		(net "M_E_CPU0_SA_CB<1>")
	)
	(segment
		(start 405.466804 -277.216616)
		(end 406.753314 -277.216616)
		(width 0.20066)
		(layer "F.Cu")
		(net "M_E_CPU0_SA_CB<1>")
	)
	(segment
		(start 398.759426 -275.647404)
		(end 399.172176 -275.922232)
		(width 0.1016)
		(layer "F.Cu")
		(net "M_E_CPU0_SA_CB<1>")
	)
	(segment
		(start 400.29638 -276.447758)
		(end 402.11375 -276.447758)
		(width 0.20066)
		(layer "F.Cu")
		(net "M_E_CPU0_SA_CB<1>")
	)
	(segment
		(start 411.851348 -276.791674)
		(end 409.843986 -276.791674)
		(width 0.1016)
		(layer "F.Cu")
		(net "M_E_CPU0_SA_CB<1>")
	)
	(segment
		(start 399.9611 -276.447758)
		(end 400.29638 -276.447758)
		(width 0.1016)
		(layer "F.Cu")
		(net "M_E_CPU0_SA_CB<1>")
	)
	(segment
		(start 387.515354 -261.113524)
		(end 388.304786 -261.902956)
		(width 0.088646)
		(layer "F.Cu")
		(net "M_E_CPU0_SA_CB<1>")
	)
	(segment
		(start 403.637242 -276.447758)
		(end 403.837902 -276.648418)
		(width 0.20066)
		(layer "F.Cu")
		(net "M_E_CPU0_SA_CB<1>")
	)
	(segment
		(start 408.361642 -277.07082)
		(end 408.077416 -277.07082)
		(width 0.20066)
		(layer "F.Cu")
		(net "M_E_CPU0_SA_CB<1>")
	)
	(segment
		(start 414.297114 -277.216616)
		(end 412.575248 -277.216616)
		(width 0.20066)
		(layer "F.Cu")
		(net "M_E_CPU0_SA_CB<1>")
	)
	(segment
		(start 407.931366 -277.21687)
		(end 406.753568 -277.21687)
		(width 0.20066)
		(layer "F.Cu")
		(net "M_E_CPU0_SA_CB<1>")
	)
	(segment
		(start 385.952492 -260.86943)
		(end 386.08508 -260.86943)
		(width 0.088646)
		(layer "F.Cu")
		(net "M_E_CPU0_SA_CB<1>")
	)
	(segment
		(start 409.297124 -276.933152)
		(end 409.297124 -277.279608)
		(width 0.20066)
		(layer "F.Cu")
		(net "M_E_CPU0_SA_CB<1>")
	)
	(segment
		(start 384.595116 -260.708902)
		(end 384.4925 -260.811518)
		(width 0.088646)
		(layer "F.Cu")
		(net "M_E_CPU0_SA_CB<1>")
	)
	(segment
		(start 385.274566 -261.113524)
		(end 385.708398 -261.113524)
		(width 0.088646)
		(layer "F.Cu")
		(net "M_E_CPU0_SA_CB<1>")
	)
	(segment
		(start 403.837902 -277.0251)
		(end 404.022306 -277.209504)
		(width 0.20066)
		(layer "F.Cu")
		(net "M_E_CPU0_SA_CB<1>")
	)
	(segment
		(start 399.516346 -276.536912)
		(end 399.9611 -276.447758)
		(width 0.1016)
		(layer "F.Cu")
		(net "M_E_CPU0_SA_CB<1>")
	)
	(segment
		(start 412.575248 -277.216616)
		(end 412.150306 -276.791674)
		(width 0.20066)
		(layer "F.Cu")
		(net "M_E_CPU0_SA_CB<1>")
	)
	(segment
		(start 402.29409 -276.628098)
		(end 403.090888 -276.628098)
		(width 0.20066)
		(layer "F.Cu")
		(net "M_E_CPU0_SA_CB<1>")
	)
	(segment
		(start 386.329174 -261.113524)
		(end 387.515354 -261.113524)
		(width 0.088646)
		(layer "F.Cu")
		(net "M_E_CPU0_SA_CB<1>")
	)
	(segment
		(start 386.08508 -260.86943)
		(end 386.329174 -261.113524)
		(width 0.088646)
		(layer "F.Cu")
		(net "M_E_CPU0_SA_CB<1>")
	)
	(segment
		(start 385.708398 -261.113524)
		(end 385.952492 -260.86943)
		(width 0.088646)
		(layer "F.Cu")
		(net "M_E_CPU0_SA_CB<1>")
	)
	(segment
		(start 404.022306 -277.209504)
		(end 404.53437 -277.209504)
		(width 0.20066)
		(layer "F.Cu")
		(net "M_E_CPU0_SA_CB<1>")
	)
	(segment
		(start 399.172176 -275.922232)
		(end 399.26133 -276.366986)
		(width 0.1016)
		(layer "F.Cu")
		(net "M_E_CPU0_SA_CB<1>")
	)
	(segment
		(start 384.815334 -261.206488)
		(end 384.989832 -261.03199)
		(width 0.088646)
		(layer "F.Cu")
		(net "M_E_CPU0_SA_CB<1>")
	)
	(segment
		(start 384.989832 -261.03199)
		(end 385.193032 -261.03199)
		(width 0.088646)
		(layer "F.Cu")
		(net "M_E_CPU0_SA_CB<1>")
	)
	(segment
		(start 403.271228 -276.447758)
		(end 403.637242 -276.447758)
		(width 0.20066)
		(layer "F.Cu")
		(net "M_E_CPU0_SA_CB<1>")
	)
	(segment
		(start 408.077416 -277.07082)
		(end 407.931366 -277.21687)
		(width 0.20066)
		(layer "F.Cu")
		(net "M_E_CPU0_SA_CB<1>")
	)
	(segment
		(start 406.753568 -277.21687)
		(end 406.753314 -277.216616)
		(width 0.20066)
		(layer "F.Cu")
		(net "M_E_CPU0_SA_CB<1>")
	)
	(segment
		(start 409.843986 -276.791674)
		(end 409.551124 -276.791674)
		(width 0.101854)
		(layer "F.Cu")
		(net "M_E_CPU0_SA_CB<1>")
	)
	(segment
		(start 384.4925 -260.811518)
		(end 384.4925 -261.104126)
		(width 0.088646)
		(layer "F.Cu")
		(net "M_E_CPU0_SA_CB<1>")
	)
	(segment
		(start 388.304786 -261.902956)
		(end 388.304786 -262.123174)
		(width 0.088646)
		(layer "F.Cu")
		(net "M_E_CPU0_SA_CB<1>")
	)
	(segment
		(start 409.438602 -276.791674)
		(end 409.297124 -276.933152)
		(width 0.20066)
		(layer "F.Cu")
		(net "M_E_CPU0_SA_CB<1>")
	)
	(segment
		(start 408.77109 -277.480268)
		(end 408.361642 -277.07082)
		(width 0.20066)
		(layer "F.Cu")
		(net "M_E_CPU0_SA_CB<1>")
	)
	(segment
		(start 409.297124 -277.279608)
		(end 409.096464 -277.480268)
		(width 0.20066)
		(layer "F.Cu")
		(net "M_E_CPU0_SA_CB<1>")
	)
	(segment
		(start 412.04261 -276.791674)
		(end 411.851348 -276.791674)
		(width 0.101854)
		(layer "F.Cu")
		(net "M_E_CPU0_SA_CB<1>")
	)
	(segment
		(start 409.551124 -276.791674)
		(end 409.438602 -276.791674)
		(width 0.20066)
		(layer "F.Cu")
		(net "M_E_CPU0_SA_CB<1>")
	)
	(segment
		(start 388.610094 -262.428482)
		(end 397.9926 -271.810988)
		(width 0.1016)
		(layer "F.Cu")
		(net "M_E_CPU0_SA_CB<1>")
	)
	(segment
		(start 399.26133 -276.366986)
		(end 399.516346 -276.536912)
		(width 0.1016)
		(layer "F.Cu")
		(net "M_E_CPU0_SA_CB<1>")
	)
	(segment
		(start 404.810468 -276.933406)
		(end 405.183594 -276.933406)
		(width 0.20066)
		(layer "F.Cu")
		(net "M_E_CPU0_SA_CB<1>")
	)
	(segment
		(start 405.183594 -276.933406)
		(end 405.466804 -277.216616)
		(width 0.20066)
		(layer "F.Cu")
		(net "M_E_CPU0_SA_CB<1>")
	)
	(segment
		(start 384.594862 -261.206488)
		(end 384.815334 -261.206488)
		(width 0.088646)
		(layer "F.Cu")
		(net "M_E_CPU0_SA_CB<1>")
	)
	(segment
		(start 384.4925 -261.104126)
		(end 384.594862 -261.206488)
		(width 0.088646)
		(layer "F.Cu")
		(net "M_E_CPU0_SA_CB<1>")
	)
	(segment
		(start 388.304786 -262.123174)
		(end 388.610094 -262.428482)
		(width 0.088646)
		(layer "F.Cu")
		(net "M_E_CPU0_SA_CB<1>")
	)
	(segment
		(start 404.53437 -277.209504)
		(end 404.810468 -276.933406)
		(width 0.20066)
		(layer "F.Cu")
		(net "M_E_CPU0_SA_CB<1>")
	)
	(segment
		(start 402.11375 -276.447758)
		(end 402.29409 -276.628098)
		(width 0.20066)
		(layer "F.Cu")
		(net "M_E_CPU0_SA_CB<1>")
	)
	(segment
		(start 403.837902 -276.648418)
		(end 403.837902 -277.0251)
		(width 0.20066)
		(layer "F.Cu")
		(net "M_E_CPU0_SA_CB<1>")
	)
	(segment
		(start 409.096464 -277.480268)
		(end 408.77109 -277.480268)
		(width 0.20066)
		(layer "F.Cu")
		(net "M_E_CPU0_SA_CB<1>")
	)
	(segment
		(start 385.193032 -261.03199)
		(end 385.274566 -261.113524)
		(width 0.088646)
		(layer "F.Cu")
		(net "M_E_CPU0_SA_CB<1>")
	)
	(segment
		(start 412.150306 -276.791674)
		(end 412.04261 -276.791674)
		(width 0.20066)
		(layer "F.Cu")
		(net "M_E_CPU0_SA_CB<1>")
	)
	(segment
		(start 411.787594 -278.389588)
		(end 411.685486 -278.491696)
		(width 0.1016)
		(layer "F.Cu")
		(net "M_E_CPU0_SA_CB<0>")
	)
	(segment
		(start 388.175754 -262.856726)
		(end 397.429482 -272.110454)
		(width 0.1016)
		(layer "F.Cu")
		(net "M_E_CPU0_SA_CB<0>")
	)
	(segment
		(start 412.915862 -279.0952)
		(end 412.60395 -279.0952)
		(width 0.20066)
		(layer "F.Cu")
		(net "M_E_CPU0_SA_CB<0>")
	)
	(segment
		(start 409.313888 -278.491696)
		(end 409.249118 -278.426926)
		(width 0.20066)
		(layer "F.Cu")
		(net "M_E_CPU0_SA_CB<0>")
	)
	(segment
		(start 387.188456 -262.41502)
		(end 387.414516 -262.497824)
		(width 0.088646)
		(layer "F.Cu")
		(net "M_E_CPU0_SA_CB<0>")
	)
	(segment
		(start 387.70433 -262.635238)
		(end 387.762242 -262.69315)
		(width 0.088646)
		(layer "F.Cu")
		(net "M_E_CPU0_SA_CB<0>")
	)
	(segment
		(start 385.064762 -261.522718)
		(end 385.066032 -261.522718)
		(width 0.088646)
		(layer "F.Cu")
		(net "M_E_CPU0_SA_CB<0>")
	)
	(segment
		(start 401.55749 -278.41702)
		(end 401.84197 -278.41702)
		(width 0.20066)
		(layer "F.Cu")
		(net "M_E_CPU0_SA_CB<0>")
	)
	(segment
		(start 400.67103 -278.21636)
		(end 400.67103 -277.96109)
		(width 0.20066)
		(layer "F.Cu")
		(net "M_E_CPU0_SA_CB<0>")
	)
	(segment
		(start 400.47037 -278.41702)
		(end 400.67103 -278.21636)
		(width 0.20066)
		(layer "F.Cu")
		(net "M_E_CPU0_SA_CB<0>")
	)
	(segment
		(start 386.786374 -262.128762)
		(end 387.188456 -262.41502)
		(width 0.088646)
		(layer "F.Cu")
		(net "M_E_CPU0_SA_CB<0>")
	)
	(segment
		(start 412.403036 -278.894286)
		(end 412.403036 -278.590248)
		(width 0.20066)
		(layer "F.Cu")
		(net "M_E_CPU0_SA_CB<0>")
	)
	(segment
		(start 400.87169 -277.76043)
		(end 401.15617 -277.76043)
		(width 0.20066)
		(layer "F.Cu")
		(net "M_E_CPU0_SA_CB<0>")
	)
	(segment
		(start 400.67103 -277.96109)
		(end 400.87169 -277.76043)
		(width 0.20066)
		(layer "F.Cu")
		(net "M_E_CPU0_SA_CB<0>")
	)
	(segment
		(start 386.739638 -262.071612)
		(end 386.786374 -262.128762)
		(width 0.088646)
		(layer "F.Cu")
		(net "M_E_CPU0_SA_CB<0>")
	)
	(segment
		(start 412.202376 -278.389588)
		(end 412.04261 -278.389588)
		(width 0.20066)
		(layer "F.Cu")
		(net "M_E_CPU0_SA_CB<0>")
	)
	(segment
		(start 385.066032 -261.522718)
		(end 385.350258 -261.806944)
		(width 0.088646)
		(layer "F.Cu")
		(net "M_E_CPU0_SA_CB<0>")
	)
	(segment
		(start 397.429482 -272.110454)
		(end 398.437608 -277.150068)
		(width 0.1016)
		(layer "F.Cu")
		(net "M_E_CPU0_SA_CB<0>")
	)
	(segment
		(start 402.932392 -277.940262)
		(end 403.517608 -278.525478)
		(width 0.20066)
		(layer "F.Cu")
		(net "M_E_CPU0_SA_CB<0>")
	)
	(segment
		(start 405.952706 -278.916638)
		(end 406.753314 -278.916638)
		(width 0.20066)
		(layer "F.Cu")
		(net "M_E_CPU0_SA_CB<0>")
	)
	(segment
		(start 412.60395 -279.0952)
		(end 412.403036 -278.894286)
		(width 0.20066)
		(layer "F.Cu")
		(net "M_E_CPU0_SA_CB<0>")
	)
	(segment
		(start 414.297114 -278.916638)
		(end 413.094424 -278.916638)
		(width 0.20066)
		(layer "F.Cu")
		(net "M_E_CPU0_SA_CB<0>")
	)
	(segment
		(start 412.403036 -278.590248)
		(end 412.202376 -278.389588)
		(width 0.20066)
		(layer "F.Cu")
		(net "M_E_CPU0_SA_CB<0>")
	)
	(segment
		(start 411.685486 -278.491696)
		(end 409.84805 -278.491696)
		(width 0.1016)
		(layer "F.Cu")
		(net "M_E_CPU0_SA_CB<0>")
	)
	(segment
		(start 386.279644 -261.916926)
		(end 386.379974 -261.916926)
		(width 0.088646)
		(layer "F.Cu")
		(net "M_E_CPU0_SA_CB<0>")
	)
	(segment
		(start 401.35683 -277.96109)
		(end 401.35683 -278.21636)
		(width 0.20066)
		(layer "F.Cu")
		(net "M_E_CPU0_SA_CB<0>")
	)
	(segment
		(start 402.318728 -277.940262)
		(end 402.932392 -277.940262)
		(width 0.20066)
		(layer "F.Cu")
		(net "M_E_CPU0_SA_CB<0>")
	)
	(segment
		(start 408.41041 -278.426926)
		(end 407.920444 -278.916892)
		(width 0.20066)
		(layer "F.Cu")
		(net "M_E_CPU0_SA_CB<0>")
	)
	(segment
		(start 398.437608 -277.150068)
		(end 399.029936 -277.742396)
		(width 0.1016)
		(layer "F.Cu")
		(net "M_E_CPU0_SA_CB<0>")
	)
	(segment
		(start 401.35683 -278.21636)
		(end 401.55749 -278.41702)
		(width 0.20066)
		(layer "F.Cu")
		(net "M_E_CPU0_SA_CB<0>")
	)
	(segment
		(start 409.551124 -278.491696)
		(end 409.313888 -278.491696)
		(width 0.20066)
		(layer "F.Cu")
		(net "M_E_CPU0_SA_CB<0>")
	)
	(segment
		(start 386.597144 -261.974838)
		(end 386.661914 -262.012176)
		(width 0.088646)
		(layer "F.Cu")
		(net "M_E_CPU0_SA_CB<0>")
	)
	(segment
		(start 387.762242 -262.69315)
		(end 388.012178 -262.69315)
		(width 0.088646)
		(layer "F.Cu")
		(net "M_E_CPU0_SA_CB<0>")
	)
	(segment
		(start 405.068532 -278.525478)
		(end 405.564086 -279.021032)
		(width 0.20066)
		(layer "F.Cu")
		(net "M_E_CPU0_SA_CB<0>")
	)
	(segment
		(start 407.920444 -278.916892)
		(end 406.753568 -278.916892)
		(width 0.20066)
		(layer "F.Cu")
		(net "M_E_CPU0_SA_CB<0>")
	)
	(segment
		(start 412.04261 -278.389588)
		(end 411.787594 -278.389588)
		(width 0.101854)
		(layer "F.Cu")
		(net "M_E_CPU0_SA_CB<0>")
	)
	(segment
		(start 399.511774 -277.742396)
		(end 400.186398 -278.41702)
		(width 0.20066)
		(layer "F.Cu")
		(net "M_E_CPU0_SA_CB<0>")
	)
	(segment
		(start 401.84197 -278.41702)
		(end 402.318728 -277.940262)
		(width 0.20066)
		(layer "F.Cu")
		(net "M_E_CPU0_SA_CB<0>")
	)
	(segment
		(start 388.012178 -262.69315)
		(end 388.175754 -262.856726)
		(width 0.088646)
		(layer "F.Cu")
		(net "M_E_CPU0_SA_CB<0>")
	)
	(segment
		(start 401.15617 -277.76043)
		(end 401.35683 -277.96109)
		(width 0.20066)
		(layer "F.Cu")
		(net "M_E_CPU0_SA_CB<0>")
	)
	(segment
		(start 406.753568 -278.916892)
		(end 406.753314 -278.916638)
		(width 0.20066)
		(layer "F.Cu")
		(net "M_E_CPU0_SA_CB<0>")
	)
	(segment
		(start 403.517608 -278.525478)
		(end 405.068532 -278.525478)
		(width 0.20066)
		(layer "F.Cu")
		(net "M_E_CPU0_SA_CB<0>")
	)
	(segment
		(start 409.249118 -278.426926)
		(end 408.41041 -278.426926)
		(width 0.20066)
		(layer "F.Cu")
		(net "M_E_CPU0_SA_CB<0>")
	)
	(segment
		(start 413.094424 -278.916638)
		(end 412.915862 -279.0952)
		(width 0.20066)
		(layer "F.Cu")
		(net "M_E_CPU0_SA_CB<0>")
	)
	(segment
		(start 399.25498 -277.742396)
		(end 399.511774 -277.742396)
		(width 0.20066)
		(layer "F.Cu")
		(net "M_E_CPU0_SA_CB<0>")
	)
	(segment
		(start 405.564086 -279.021032)
		(end 405.848312 -279.021032)
		(width 0.20066)
		(layer "F.Cu")
		(net "M_E_CPU0_SA_CB<0>")
	)
	(segment
		(start 409.84805 -278.491696)
		(end 409.551124 -278.491696)
		(width 0.101854)
		(layer "F.Cu")
		(net "M_E_CPU0_SA_CB<0>")
	)
	(segment
		(start 399.029936 -277.742396)
		(end 399.25498 -277.742396)
		(width 0.1016)
		(layer "F.Cu")
		(net "M_E_CPU0_SA_CB<0>")
	)
	(segment
		(start 405.848312 -279.021032)
		(end 405.952706 -278.916638)
		(width 0.20066)
		(layer "F.Cu")
		(net "M_E_CPU0_SA_CB<0>")
	)
	(segment
		(start 400.186398 -278.41702)
		(end 400.47037 -278.41702)
		(width 0.20066)
		(layer "F.Cu")
		(net "M_E_CPU0_SA_CB<0>")
	)
	(arc
		(start 385.350258 -261.806944)
		(mid 385.382963 -261.837311)
		(end 385.418076 -261.864856)
		(width 0.088646)
		(layer "F.Cu")
		(net "M_E_CPU0_SA_CB<0>")
	)
	(arc
		(start 386.661914 -262.012176)
		(mid 386.702723 -262.039348)
		(end 386.739638 -262.071612)
		(width 0.088646)
		(layer "F.Cu")
		(net "M_E_CPU0_SA_CB<0>")
	)
	(arc
		(start 386.171694 -261.96163)
		(mid 386.221222 -261.928537)
		(end 386.279644 -261.916926)
		(width 0.088646)
		(layer "F.Cu")
		(net "M_E_CPU0_SA_CB<0>")
	)
	(arc
		(start 387.414516 -262.497824)
		(mid 387.516394 -262.511932)
		(end 387.610604 -262.553196)
		(width 0.088646)
		(layer "F.Cu")
		(net "M_E_CPU0_SA_CB<0>")
	)
	(arc
		(start 385.418076 -261.864856)
		(mid 385.782732 -262.007972)
		(end 386.171694 -261.96163)
		(width 0.088646)
		(layer "F.Cu")
		(net "M_E_CPU0_SA_CB<0>")
	)
	(arc
		(start 387.610604 -262.553196)
		(mid 387.660889 -262.590305)
		(end 387.70433 -262.635238)
		(width 0.088646)
		(layer "F.Cu")
		(net "M_E_CPU0_SA_CB<0>")
	)
	(arc
		(start 386.379974 -261.916926)
		(mid 386.492369 -261.931608)
		(end 386.597144 -261.974838)
		(width 0.088646)
		(layer "F.Cu")
		(net "M_E_CPU0_SA_CB<0>")
	)
	(segment
		(start 385.202684 -252.84049)
		(end 386.099558 -252.973586)
		(width 0.1016)
		(layer "F.Cu")
		(net "M_E_CPU0_SA_CA<6>")
	)
	(segment
		(start 405.848058 -260.712458)
		(end 406.202388 -261.066788)
		(width 0.20066)
		(layer "F.Cu")
		(net "M_E_CPU0_SA_CA<6>")
	)
	(segment
		(start 390.109964 -254.159004)
		(end 392.778742 -256.827782)
		(width 0.1016)
		(layer "F.Cu")
		(net "M_E_CPU0_SA_CA<6>")
	)
	(segment
		(start 412.518606 -261.50824)
		(end 411.863794 -261.50824)
		(width 0.20066)
		(layer "F.Cu")
		(net "M_E_CPU0_SA_CA<6>")
	)
	(segment
		(start 393.181586 -256.827782)
		(end 393.277344 -256.827782)
		(width 0.101854)
		(layer "F.Cu")
		(net "M_E_CPU0_SA_CA<6>")
	)
	(segment
		(start 409.247086 -261.237476)
		(end 409.247086 -260.73735)
		(width 0.20066)
		(layer "F.Cu")
		(net "M_E_CPU0_SA_CA<6>")
	)
	(segment
		(start 383.282698 -252.321314)
		(end 383.409444 -252.38075)
		(width 0.088646)
		(layer "F.Cu")
		(net "M_E_CPU0_SA_CA<6>")
	)
	(segment
		(start 380.176024 -250.304808)
		(end 380.211584 -250.41606)
		(width 0.088646)
		(layer "F.Cu")
		(net "M_E_CPU0_SA_CA<6>")
	)
	(segment
		(start 383.902204 -252.612652)
		(end 384.287522 -252.727206)
		(width 0.088646)
		(layer "F.Cu")
		(net "M_E_CPU0_SA_CA<6>")
	)
	(segment
		(start 381.655574 -251.472446)
		(end 383.282698 -252.321314)
		(width 0.088646)
		(layer "F.Cu")
		(net "M_E_CPU0_SA_CA<6>")
	)
	(segment
		(start 414.297114 -261.066788)
		(end 412.960058 -261.066788)
		(width 0.20066)
		(layer "F.Cu")
		(net "M_E_CPU0_SA_CA<6>")
	)
	(segment
		(start 380.650242 -250.866148)
		(end 381.655574 -251.472446)
		(width 0.088646)
		(layer "F.Cu")
		(net "M_E_CPU0_SA_CA<6>")
	)
	(segment
		(start 409.540202 -261.530592)
		(end 409.247086 -261.237476)
		(width 0.20066)
		(layer "F.Cu")
		(net "M_E_CPU0_SA_CA<6>")
	)
	(segment
		(start 380.160784 -250.231656)
		(end 380.176024 -250.304808)
		(width 0.088646)
		(layer "F.Cu")
		(net "M_E_CPU0_SA_CA<6>")
	)
	(segment
		(start 392.778742 -256.827782)
		(end 393.181586 -256.827782)
		(width 0.1016)
		(layer "F.Cu")
		(net "M_E_CPU0_SA_CA<6>")
	)
	(segment
		(start 408.161744 -260.646926)
		(end 407.68524 -260.646926)
		(width 0.20066)
		(layer "F.Cu")
		(net "M_E_CPU0_SA_CA<6>")
	)
	(segment
		(start 412.960058 -261.066788)
		(end 412.518606 -261.50824)
		(width 0.20066)
		(layer "F.Cu")
		(net "M_E_CPU0_SA_CA<6>")
	)
	(segment
		(start 380.564644 -249.596148)
		(end 380.442978 -249.666506)
		(width 0.088646)
		(layer "F.Cu")
		(net "M_E_CPU0_SA_CA<6>")
	)
	(segment
		(start 380.160784 -250.14047)
		(end 380.160784 -250.231656)
		(width 0.088646)
		(layer "F.Cu")
		(net "M_E_CPU0_SA_CA<6>")
	)
	(segment
		(start 408.368754 -260.439916)
		(end 408.161744 -260.646926)
		(width 0.20066)
		(layer "F.Cu")
		(net "M_E_CPU0_SA_CA<6>")
	)
	(segment
		(start 408.949652 -260.439916)
		(end 408.368754 -260.439916)
		(width 0.20066)
		(layer "F.Cu")
		(net "M_E_CPU0_SA_CA<6>")
	)
	(segment
		(start 388.393432 -253.447804)
		(end 390.109964 -254.159004)
		(width 0.1016)
		(layer "F.Cu")
		(net "M_E_CPU0_SA_CA<6>")
	)
	(segment
		(start 388.057644 -253.363476)
		(end 388.393432 -253.447804)
		(width 0.1016)
		(layer "F.Cu")
		(net "M_E_CPU0_SA_CA<6>")
	)
	(segment
		(start 409.83662 -261.530592)
		(end 409.831794 -261.530592)
		(width 0.101854)
		(layer "F.Cu")
		(net "M_E_CPU0_SA_CA<6>")
	)
	(segment
		(start 384.554984 -252.769878)
		(end 384.672586 -252.78842)
		(width 0.1016)
		(layer "F.Cu")
		(net "M_E_CPU0_SA_CA<6>")
	)
	(segment
		(start 407.265378 -261.066788)
		(end 406.753314 -261.066788)
		(width 0.20066)
		(layer "F.Cu")
		(net "M_E_CPU0_SA_CA<6>")
	)
	(segment
		(start 384.456432 -252.75413)
		(end 384.554984 -252.769878)
		(width 0.1016)
		(layer "F.Cu")
		(net "M_E_CPU0_SA_CA<6>")
	)
	(segment
		(start 407.68524 -260.646926)
		(end 407.265378 -261.066788)
		(width 0.20066)
		(layer "F.Cu")
		(net "M_E_CPU0_SA_CA<6>")
	)
	(segment
		(start 384.287522 -252.727206)
		(end 384.456432 -252.75413)
		(width 0.088646)
		(layer "F.Cu")
		(net "M_E_CPU0_SA_CA<6>")
	)
	(segment
		(start 386.099558 -252.973586)
		(end 388.057644 -253.363476)
		(width 0.1016)
		(layer "F.Cu")
		(net "M_E_CPU0_SA_CA<6>")
	)
	(segment
		(start 409.903676 -261.49173)
		(end 409.864814 -261.530592)
		(width 0.1016)
		(layer "F.Cu")
		(net "M_E_CPU0_SA_CA<6>")
	)
	(segment
		(start 409.831794 -261.530592)
		(end 409.540202 -261.530592)
		(width 0.20066)
		(layer "F.Cu")
		(net "M_E_CPU0_SA_CA<6>")
	)
	(segment
		(start 381.19558 -249.342148)
		(end 380.722124 -249.521472)
		(width 0.088646)
		(layer "F.Cu")
		(net "M_E_CPU0_SA_CA<6>")
	)
	(segment
		(start 380.46279 -250.71578)
		(end 380.565406 -250.807474)
		(width 0.088646)
		(layer "F.Cu")
		(net "M_E_CPU0_SA_CA<6>")
	)
	(segment
		(start 393.277344 -256.827782)
		(end 397.03629 -256.827782)
		(width 0.20066)
		(layer "F.Cu")
		(net "M_E_CPU0_SA_CA<6>")
	)
	(segment
		(start 406.202388 -261.066788)
		(end 406.753314 -261.066788)
		(width 0.20066)
		(layer "F.Cu")
		(net "M_E_CPU0_SA_CA<6>")
	)
	(segment
		(start 380.211584 -250.41606)
		(end 380.291086 -250.525788)
		(width 0.088646)
		(layer "F.Cu")
		(net "M_E_CPU0_SA_CA<6>")
	)
	(segment
		(start 411.863794 -261.50824)
		(end 411.847284 -261.49173)
		(width 0.1016)
		(layer "F.Cu")
		(net "M_E_CPU0_SA_CA<6>")
	)
	(segment
		(start 380.565406 -250.807474)
		(end 380.650242 -250.866148)
		(width 0.088646)
		(layer "F.Cu")
		(net "M_E_CPU0_SA_CA<6>")
	)
	(segment
		(start 380.722124 -249.521472)
		(end 380.564644 -249.596148)
		(width 0.088646)
		(layer "F.Cu")
		(net "M_E_CPU0_SA_CA<6>")
	)
	(segment
		(start 404.080726 -259.745734)
		(end 405.04745 -260.712458)
		(width 0.20066)
		(layer "F.Cu")
		(net "M_E_CPU0_SA_CA<6>")
	)
	(segment
		(start 380.291086 -250.525788)
		(end 380.46279 -250.71578)
		(width 0.088646)
		(layer "F.Cu")
		(net "M_E_CPU0_SA_CA<6>")
	)
	(segment
		(start 409.864814 -261.530592)
		(end 409.83662 -261.530592)
		(width 0.1016)
		(layer "F.Cu")
		(net "M_E_CPU0_SA_CA<6>")
	)
	(segment
		(start 384.672586 -252.78842)
		(end 385.202684 -252.84049)
		(width 0.1016)
		(layer "F.Cu")
		(net "M_E_CPU0_SA_CA<6>")
	)
	(segment
		(start 409.247086 -260.73735)
		(end 408.949652 -260.439916)
		(width 0.20066)
		(layer "F.Cu")
		(net "M_E_CPU0_SA_CA<6>")
	)
	(segment
		(start 383.409444 -252.38075)
		(end 383.902204 -252.612652)
		(width 0.088646)
		(layer "F.Cu")
		(net "M_E_CPU0_SA_CA<6>")
	)
	(segment
		(start 397.03629 -256.827782)
		(end 404.080726 -259.745734)
		(width 0.20066)
		(layer "F.Cu")
		(net "M_E_CPU0_SA_CA<6>")
	)
	(segment
		(start 405.04745 -260.712458)
		(end 405.848058 -260.712458)
		(width 0.20066)
		(layer "F.Cu")
		(net "M_E_CPU0_SA_CA<6>")
	)
	(segment
		(start 411.847284 -261.49173)
		(end 409.903676 -261.49173)
		(width 0.1016)
		(layer "F.Cu")
		(net "M_E_CPU0_SA_CA<6>")
	)
	(arc
		(start 380.442978 -249.666506)
		(mid 380.240155 -249.866737)
		(end 380.160784 -250.14047)
		(width 0.088646)
		(layer "F.Cu")
		(net "M_E_CPU0_SA_CA<6>")
	)
	(segment
		(start 410.02839 -261.916672)
		(end 410.853382 -261.916672)
		(width 0.20066)
		(layer "F.Cu")
		(net "M_E_CPU0_SA_CA<5>")
	)
	(segment
		(start 389.96493 -254.445262)
		(end 392.987022 -257.467354)
		(width 0.1016)
		(layer "F.Cu")
		(net "M_E_CPU0_SA_CA<5>")
	)
	(segment
		(start 408.809698 -261.187946)
		(end 408.809698 -261.38251)
		(width 0.20066)
		(layer "F.Cu")
		(net "M_E_CPU0_SA_CA<5>")
	)
	(segment
		(start 416.855148 -261.489952)
		(end 416.438588 -261.489952)
		(width 0.20066)
		(layer "F.Cu")
		(net "M_E_CPU0_SA_CA<5>")
	)
	(segment
		(start 408.396694 -261.795514)
		(end 408.396694 -262.043926)
		(width 0.20066)
		(layer "F.Cu")
		(net "M_E_CPU0_SA_CA<5>")
	)
	(segment
		(start 408.064462 -261.085838)
		(end 408.70759 -261.085838)
		(width 0.20066)
		(layer "F.Cu")
		(net "M_E_CPU0_SA_CA<5>")
	)
	(segment
		(start 388.162546 -253.698248)
		(end 388.318756 -253.763272)
		(width 0.088646)
		(layer "F.Cu")
		(net "M_E_CPU0_SA_CA<5>")
	)
	(segment
		(start 392.987022 -257.467354)
		(end 393.181586 -257.467354)
		(width 0.1016)
		(layer "F.Cu")
		(net "M_E_CPU0_SA_CA<5>")
	)
	(segment
		(start 405.748998 -261.481316)
		(end 405.759412 -261.49173)
		(width 0.1016)
		(layer "F.Cu")
		(net "M_E_CPU0_SA_CA<5>")
	)
	(segment
		(start 404.765256 -261.481316)
		(end 405.731726 -261.481316)
		(width 0.20066)
		(layer "F.Cu")
		(net "M_E_CPU0_SA_CA<5>")
	)
	(segment
		(start 387.576314 -253.605284)
		(end 387.8834 -253.698248)
		(width 0.088646)
		(layer "F.Cu")
		(net "M_E_CPU0_SA_CA<5>")
	)
	(segment
		(start 405.731726 -261.481316)
		(end 405.748998 -261.481316)
		(width 0.101854)
		(layer "F.Cu")
		(net "M_E_CPU0_SA_CA<5>")
	)
	(segment
		(start 412.674054 -262.357362)
		(end 412.233364 -261.916672)
		(width 0.20066)
		(layer "F.Cu")
		(net "M_E_CPU0_SA_CA<5>")
	)
	(segment
		(start 388.357618 -253.779274)
		(end 389.96493 -254.445262)
		(width 0.1016)
		(layer "F.Cu")
		(net "M_E_CPU0_SA_CA<5>")
	)
	(segment
		(start 393.277344 -257.467354)
		(end 396.831312 -257.467354)
		(width 0.20066)
		(layer "F.Cu")
		(net "M_E_CPU0_SA_CA<5>")
	)
	(segment
		(start 388.318756 -253.763272)
		(end 388.357618 -253.779274)
		(width 0.088646)
		(layer "F.Cu")
		(net "M_E_CPU0_SA_CA<5>")
	)
	(segment
		(start 412.233364 -261.916672)
		(end 410.853382 -261.916672)
		(width 0.20066)
		(layer "F.Cu")
		(net "M_E_CPU0_SA_CA<5>")
	)
	(segment
		(start 396.831312 -257.467354)
		(end 403.523196 -260.239256)
		(width 0.20066)
		(layer "F.Cu")
		(net "M_E_CPU0_SA_CA<5>")
	)
	(segment
		(start 417.281868 -261.916672)
		(end 416.855148 -261.489952)
		(width 0.20066)
		(layer "F.Cu")
		(net "M_E_CPU0_SA_CA<5>")
	)
	(segment
		(start 408.809698 -261.38251)
		(end 408.396694 -261.795514)
		(width 0.20066)
		(layer "F.Cu")
		(net "M_E_CPU0_SA_CA<5>")
	)
	(segment
		(start 407.763726 -261.386574)
		(end 408.064462 -261.085838)
		(width 0.20066)
		(layer "F.Cu")
		(net "M_E_CPU0_SA_CA<5>")
	)
	(segment
		(start 393.181586 -257.467354)
		(end 393.277344 -257.467354)
		(width 0.101854)
		(layer "F.Cu")
		(net "M_E_CPU0_SA_CA<5>")
	)
	(segment
		(start 413.296354 -262.341614)
		(end 413.280606 -262.357362)
		(width 0.1016)
		(layer "F.Cu")
		(net "M_E_CPU0_SA_CA<5>")
	)
	(segment
		(start 407.65857 -261.49173)
		(end 407.763726 -261.386574)
		(width 0.1016)
		(layer "F.Cu")
		(net "M_E_CPU0_SA_CA<5>")
	)
	(segment
		(start 415.307526 -262.35787)
		(end 415.29127 -262.341614)
		(width 0.1016)
		(layer "F.Cu")
		(net "M_E_CPU0_SA_CA<5>")
	)
	(segment
		(start 408.70759 -261.085838)
		(end 408.809698 -261.187946)
		(width 0.20066)
		(layer "F.Cu")
		(net "M_E_CPU0_SA_CA<5>")
	)
	(segment
		(start 415.57067 -262.35787)
		(end 415.307526 -262.35787)
		(width 0.20066)
		(layer "F.Cu")
		(net "M_E_CPU0_SA_CA<5>")
	)
	(segment
		(start 415.29127 -262.341614)
		(end 413.296354 -262.341614)
		(width 0.1016)
		(layer "F.Cu")
		(net "M_E_CPU0_SA_CA<5>")
	)
	(segment
		(start 416.438588 -261.489952)
		(end 415.57067 -262.35787)
		(width 0.20066)
		(layer "F.Cu")
		(net "M_E_CPU0_SA_CA<5>")
	)
	(segment
		(start 418.397182 -261.916672)
		(end 417.281868 -261.916672)
		(width 0.20066)
		(layer "F.Cu")
		(net "M_E_CPU0_SA_CA<5>")
	)
	(segment
		(start 408.396694 -262.043926)
		(end 408.559 -262.206232)
		(width 0.20066)
		(layer "F.Cu")
		(net "M_E_CPU0_SA_CA<5>")
	)
	(segment
		(start 413.275526 -262.357362)
		(end 412.674054 -262.357362)
		(width 0.20066)
		(layer "F.Cu")
		(net "M_E_CPU0_SA_CA<5>")
	)
	(segment
		(start 408.559 -262.206232)
		(end 409.73883 -262.206232)
		(width 0.20066)
		(layer "F.Cu")
		(net "M_E_CPU0_SA_CA<5>")
	)
	(segment
		(start 409.73883 -262.206232)
		(end 410.02839 -261.916672)
		(width 0.20066)
		(layer "F.Cu")
		(net "M_E_CPU0_SA_CA<5>")
	)
	(segment
		(start 386.463286 -253.38405)
		(end 387.576314 -253.605284)
		(width 0.088646)
		(layer "F.Cu")
		(net "M_E_CPU0_SA_CA<5>")
	)
	(segment
		(start 387.8834 -253.698248)
		(end 388.162546 -253.698248)
		(width 0.088646)
		(layer "F.Cu")
		(net "M_E_CPU0_SA_CA<5>")
	)
	(segment
		(start 413.280606 -262.357362)
		(end 413.275526 -262.357362)
		(width 0.101854)
		(layer "F.Cu")
		(net "M_E_CPU0_SA_CA<5>")
	)
	(segment
		(start 403.523196 -260.239256)
		(end 404.765256 -261.481316)
		(width 0.20066)
		(layer "F.Cu")
		(net "M_E_CPU0_SA_CA<5>")
	)
	(segment
		(start 386.004562 -253.383796)
		(end 386.463286 -253.38405)
		(width 0.088646)
		(layer "F.Cu")
		(net "M_E_CPU0_SA_CA<5>")
	)
	(segment
		(start 405.759412 -261.49173)
		(end 407.65857 -261.49173)
		(width 0.1016)
		(layer "F.Cu")
		(net "M_E_CPU0_SA_CA<5>")
	)
	(segment
		(start 404.417276 -262.298434)
		(end 405.098504 -262.298434)
		(width 0.20066)
		(layer "F.Cu")
		(net "M_E_CPU0_SA_CA<4>")
	)
	(segment
		(start 411.863794 -263.221216)
		(end 412.767526 -263.221216)
		(width 0.20066)
		(layer "F.Cu")
		(net "M_E_CPU0_SA_CA<4>")
	)
	(segment
		(start 406.178258 -262.76681)
		(end 406.753314 -262.76681)
		(width 0.20066)
		(layer "F.Cu")
		(net "M_E_CPU0_SA_CA<4>")
	)
	(segment
		(start 396.755112 -258.234942)
		(end 402.90496 -260.782562)
		(width 0.20066)
		(layer "F.Cu")
		(net "M_E_CPU0_SA_CA<4>")
	)
	(segment
		(start 393.146026 -258.05765)
		(end 396.473426 -258.05765)
		(width 0.1016)
		(layer "F.Cu")
		(net "M_E_CPU0_SA_CA<4>")
	)
	(segment
		(start 411.83433 -263.191752)
		(end 411.863794 -263.221216)
		(width 0.1016)
		(layer "F.Cu")
		(net "M_E_CPU0_SA_CA<4>")
	)
	(segment
		(start 385.34086 -253.383796)
		(end 385.45008 -253.493016)
		(width 0.088646)
		(layer "F.Cu")
		(net "M_E_CPU0_SA_CA<4>")
	)
	(segment
		(start 388.188708 -254.347726)
		(end 388.814818 -254.347726)
		(width 0.088646)
		(layer "F.Cu")
		(net "M_E_CPU0_SA_CA<4>")
	)
	(segment
		(start 408.338528 -262.667496)
		(end 409.013914 -262.667496)
		(width 0.20066)
		(layer "F.Cu")
		(net "M_E_CPU0_SA_CA<4>")
	)
	(segment
		(start 396.577058 -258.161282)
		(end 396.755112 -258.234942)
		(width 0.101854)
		(layer "F.Cu")
		(net "M_E_CPU0_SA_CA<4>")
	)
	(segment
		(start 386.376164 -253.701042)
		(end 386.489194 -253.644654)
		(width 0.088646)
		(layer "F.Cu")
		(net "M_E_CPU0_SA_CA<4>")
	)
	(segment
		(start 385.064762 -253.383796)
		(end 385.34086 -253.383796)
		(width 0.088646)
		(layer "F.Cu")
		(net "M_E_CPU0_SA_CA<4>")
	)
	(segment
		(start 412.767526 -263.221216)
		(end 413.100266 -262.888476)
		(width 0.20066)
		(layer "F.Cu")
		(net "M_E_CPU0_SA_CA<4>")
	)
	(segment
		(start 385.45008 -253.493016)
		(end 385.722114 -253.873)
		(width 0.088646)
		(layer "F.Cu")
		(net "M_E_CPU0_SA_CA<4>")
	)
	(segment
		(start 414.175448 -262.888476)
		(end 414.297114 -262.76681)
		(width 0.20066)
		(layer "F.Cu")
		(net "M_E_CPU0_SA_CA<4>")
	)
	(segment
		(start 386.578602 -253.630938)
		(end 387.473698 -253.781306)
		(width 0.088646)
		(layer "F.Cu")
		(net "M_E_CPU0_SA_CA<4>")
	)
	(segment
		(start 406.753314 -262.76681)
		(end 407.299922 -262.76681)
		(width 0.20066)
		(layer "F.Cu")
		(net "M_E_CPU0_SA_CA<4>")
	)
	(segment
		(start 405.28113 -262.48106)
		(end 405.892508 -262.48106)
		(width 0.20066)
		(layer "F.Cu")
		(net "M_E_CPU0_SA_CA<4>")
	)
	(segment
		(start 409.013914 -262.667496)
		(end 409.560268 -263.21385)
		(width 0.20066)
		(layer "F.Cu")
		(net "M_E_CPU0_SA_CA<4>")
	)
	(segment
		(start 409.831794 -263.21385)
		(end 409.853892 -263.191752)
		(width 0.1016)
		(layer "F.Cu")
		(net "M_E_CPU0_SA_CA<4>")
	)
	(segment
		(start 409.560268 -263.21385)
		(end 409.831794 -263.21385)
		(width 0.20066)
		(layer "F.Cu")
		(net "M_E_CPU0_SA_CA<4>")
	)
	(segment
		(start 396.473426 -258.05765)
		(end 396.577058 -258.161282)
		(width 0.1016)
		(layer "F.Cu")
		(net "M_E_CPU0_SA_CA<4>")
	)
	(segment
		(start 407.299922 -262.76681)
		(end 407.698448 -262.368284)
		(width 0.20066)
		(layer "F.Cu")
		(net "M_E_CPU0_SA_CA<4>")
	)
	(segment
		(start 407.698448 -262.368284)
		(end 408.039316 -262.368284)
		(width 0.20066)
		(layer "F.Cu")
		(net "M_E_CPU0_SA_CA<4>")
	)
	(segment
		(start 388.900162 -254.347726)
		(end 389.815324 -254.726948)
		(width 0.1016)
		(layer "F.Cu")
		(net "M_E_CPU0_SA_CA<4>")
	)
	(segment
		(start 408.039316 -262.368284)
		(end 408.338528 -262.667496)
		(width 0.20066)
		(layer "F.Cu")
		(net "M_E_CPU0_SA_CA<4>")
	)
	(segment
		(start 388.814818 -254.347726)
		(end 388.900162 -254.347726)
		(width 0.1016)
		(layer "F.Cu")
		(net "M_E_CPU0_SA_CA<4>")
	)
	(segment
		(start 387.723634 -253.882652)
		(end 388.188708 -254.347726)
		(width 0.088646)
		(layer "F.Cu")
		(net "M_E_CPU0_SA_CA<4>")
	)
	(segment
		(start 386.287518 -253.873254)
		(end 386.376164 -253.701042)
		(width 0.088646)
		(layer "F.Cu")
		(net "M_E_CPU0_SA_CA<4>")
	)
	(segment
		(start 402.90496 -260.782562)
		(end 404.417276 -262.298434)
		(width 0.20066)
		(layer "F.Cu")
		(net "M_E_CPU0_SA_CA<4>")
	)
	(segment
		(start 389.815324 -254.726948)
		(end 393.146026 -258.05765)
		(width 0.1016)
		(layer "F.Cu")
		(net "M_E_CPU0_SA_CA<4>")
	)
	(segment
		(start 385.722114 -253.873)
		(end 385.722114 -253.873254)
		(width 0.088646)
		(layer "F.Cu")
		(net "M_E_CPU0_SA_CA<4>")
	)
	(segment
		(start 405.892508 -262.48106)
		(end 406.178258 -262.76681)
		(width 0.20066)
		(layer "F.Cu")
		(net "M_E_CPU0_SA_CA<4>")
	)
	(segment
		(start 413.100266 -262.888476)
		(end 414.175448 -262.888476)
		(width 0.20066)
		(layer "F.Cu")
		(net "M_E_CPU0_SA_CA<4>")
	)
	(segment
		(start 387.623558 -253.831344)
		(end 387.723634 -253.882652)
		(width 0.088646)
		(layer "F.Cu")
		(net "M_E_CPU0_SA_CA<4>")
	)
	(segment
		(start 405.098504 -262.298434)
		(end 405.28113 -262.48106)
		(width 0.20066)
		(layer "F.Cu")
		(net "M_E_CPU0_SA_CA<4>")
	)
	(segment
		(start 409.853892 -263.191752)
		(end 411.83433 -263.191752)
		(width 0.1016)
		(layer "F.Cu")
		(net "M_E_CPU0_SA_CA<4>")
	)
	(arc
		(start 387.473698 -253.781306)
		(mid 387.550578 -253.800488)
		(end 387.623558 -253.831344)
		(width 0.088646)
		(layer "F.Cu")
		(net "M_E_CPU0_SA_CA<4>")
	)
	(arc
		(start 386.489194 -253.644654)
		(mid 386.532793 -253.630563)
		(end 386.578602 -253.630938)
		(width 0.088646)
		(layer "F.Cu")
		(net "M_E_CPU0_SA_CA<4>")
	)
	(arc
		(start 385.722114 -253.873254)
		(mid 386.004816 -253.94903)
		(end 386.287518 -253.873254)
		(width 0.088646)
		(layer "F.Cu")
		(net "M_E_CPU0_SA_CA<4>")
	)
	(segment
		(start 408.997912 -263.371076)
		(end 408.997912 -263.771126)
		(width 0.20066)
		(layer "F.Cu")
		(net "M_E_CPU0_SA_CA<3>")
	)
	(segment
		(start 410.239718 -263.616694)
		(end 410.853382 -263.616694)
		(width 0.20066)
		(layer "F.Cu")
		(net "M_E_CPU0_SA_CA<3>")
	)
	(segment
		(start 416.359848 -263.184132)
		(end 416.189668 -263.354312)
		(width 0.20066)
		(layer "F.Cu")
		(net "M_E_CPU0_SA_CA<3>")
	)
	(segment
		(start 407.74239 -263.191752)
		(end 407.763726 -263.170416)
		(width 0.1016)
		(layer "F.Cu")
		(net "M_E_CPU0_SA_CA<3>")
	)
	(segment
		(start 404.325328 -263.175496)
		(end 405.731726 -263.175496)
		(width 0.20066)
		(layer "F.Cu")
		(net "M_E_CPU0_SA_CA<3>")
	)
	(segment
		(start 395.951964 -258.440682)
		(end 396.168372 -258.65709)
		(width 0.1016)
		(layer "F.Cu")
		(net "M_E_CPU0_SA_CA<3>")
	)
	(segment
		(start 409.958286 -263.898126)
		(end 410.239718 -263.616694)
		(width 0.20066)
		(layer "F.Cu")
		(net "M_E_CPU0_SA_CA<3>")
	)
	(segment
		(start 408.997912 -263.771126)
		(end 409.124912 -263.898126)
		(width 0.20066)
		(layer "F.Cu")
		(net "M_E_CPU0_SA_CA<3>")
	)
	(segment
		(start 413.293052 -264.055606)
		(end 413.275526 -264.055606)
		(width 0.101854)
		(layer "F.Cu")
		(net "M_E_CPU0_SA_CA<3>")
	)
	(segment
		(start 386.153914 -254.466344)
		(end 386.258054 -254.519938)
		(width 0.088646)
		(layer "F.Cu")
		(net "M_E_CPU0_SA_CA<3>")
	)
	(segment
		(start 415.989008 -264.061194)
		(end 415.307526 -264.061194)
		(width 0.20066)
		(layer "F.Cu")
		(net "M_E_CPU0_SA_CA<3>")
	)
	(segment
		(start 407.763726 -263.170416)
		(end 408.797252 -263.170416)
		(width 0.20066)
		(layer "F.Cu")
		(net "M_E_CPU0_SA_CA<3>")
	)
	(segment
		(start 413.275526 -264.055606)
		(end 412.143702 -264.055606)
		(width 0.20066)
		(layer "F.Cu")
		(net "M_E_CPU0_SA_CA<3>")
	)
	(segment
		(start 417.114228 -263.616694)
		(end 416.681666 -263.184132)
		(width 0.20066)
		(layer "F.Cu")
		(net "M_E_CPU0_SA_CA<3>")
	)
	(segment
		(start 405.747982 -263.191752)
		(end 407.74239 -263.191752)
		(width 0.1016)
		(layer "F.Cu")
		(net "M_E_CPU0_SA_CA<3>")
	)
	(segment
		(start 388.230618 -254.667258)
		(end 388.846314 -254.667258)
		(width 0.1016)
		(layer "F.Cu")
		(net "M_E_CPU0_SA_CA<3>")
	)
	(segment
		(start 415.307526 -264.061194)
		(end 415.287968 -264.041636)
		(width 0.1016)
		(layer "F.Cu")
		(net "M_E_CPU0_SA_CA<3>")
	)
	(segment
		(start 396.250668 -258.739386)
		(end 396.385796 -258.874514)
		(width 0.20066)
		(layer "F.Cu")
		(net "M_E_CPU0_SA_CA<3>")
	)
	(segment
		(start 408.797252 -263.170416)
		(end 408.997912 -263.371076)
		(width 0.20066)
		(layer "F.Cu")
		(net "M_E_CPU0_SA_CA<3>")
	)
	(segment
		(start 388.846314 -254.667258)
		(end 389.66267 -255.005586)
		(width 0.1016)
		(layer "F.Cu")
		(net "M_E_CPU0_SA_CA<3>")
	)
	(segment
		(start 393.097766 -258.440682)
		(end 395.951964 -258.440682)
		(width 0.1016)
		(layer "F.Cu")
		(net "M_E_CPU0_SA_CA<3>")
	)
	(segment
		(start 384.843782 -254.446278)
		(end 385.07162 -254.446278)
		(width 0.088646)
		(layer "F.Cu")
		(net "M_E_CPU0_SA_CA<3>")
	)
	(segment
		(start 386.654548 -254.531876)
		(end 386.666486 -254.525018)
		(width 0.088646)
		(layer "F.Cu")
		(net "M_E_CPU0_SA_CA<3>")
	)
	(segment
		(start 416.681666 -263.184132)
		(end 416.359848 -263.184132)
		(width 0.20066)
		(layer "F.Cu")
		(net "M_E_CPU0_SA_CA<3>")
	)
	(segment
		(start 402.597366 -261.447534)
		(end 404.325328 -263.175496)
		(width 0.20066)
		(layer "F.Cu")
		(net "M_E_CPU0_SA_CA<3>")
	)
	(segment
		(start 396.168372 -258.65709)
		(end 396.250668 -258.739386)
		(width 0.101854)
		(layer "F.Cu")
		(net "M_E_CPU0_SA_CA<3>")
	)
	(segment
		(start 409.124912 -263.898126)
		(end 409.958286 -263.898126)
		(width 0.20066)
		(layer "F.Cu")
		(net "M_E_CPU0_SA_CA<3>")
	)
	(segment
		(start 418.397182 -263.616694)
		(end 417.114228 -263.616694)
		(width 0.20066)
		(layer "F.Cu")
		(net "M_E_CPU0_SA_CA<3>")
	)
	(segment
		(start 387.149848 -254.474218)
		(end 387.391402 -254.578866)
		(width 0.088646)
		(layer "F.Cu")
		(net "M_E_CPU0_SA_CA<3>")
	)
	(segment
		(start 396.385796 -258.874514)
		(end 402.597366 -261.447534)
		(width 0.20066)
		(layer "F.Cu")
		(net "M_E_CPU0_SA_CA<3>")
	)
	(segment
		(start 384.595116 -254.197612)
		(end 384.843782 -254.446278)
		(width 0.088646)
		(layer "F.Cu")
		(net "M_E_CPU0_SA_CA<3>")
	)
	(segment
		(start 386.258054 -254.519938)
		(end 386.385308 -254.57277)
		(width 0.088646)
		(layer "F.Cu")
		(net "M_E_CPU0_SA_CA<3>")
	)
	(segment
		(start 386.857494 -254.474218)
		(end 387.149848 -254.474218)
		(width 0.088646)
		(layer "F.Cu")
		(net "M_E_CPU0_SA_CA<3>")
	)
	(segment
		(start 413.307022 -264.041636)
		(end 413.293052 -264.055606)
		(width 0.1016)
		(layer "F.Cu")
		(net "M_E_CPU0_SA_CA<3>")
	)
	(segment
		(start 412.143702 -264.055606)
		(end 411.70479 -263.616694)
		(width 0.20066)
		(layer "F.Cu")
		(net "M_E_CPU0_SA_CA<3>")
	)
	(segment
		(start 411.70479 -263.616694)
		(end 410.853382 -263.616694)
		(width 0.20066)
		(layer "F.Cu")
		(net "M_E_CPU0_SA_CA<3>")
	)
	(segment
		(start 389.66267 -255.005586)
		(end 393.097766 -258.440682)
		(width 0.1016)
		(layer "F.Cu")
		(net "M_E_CPU0_SA_CA<3>")
	)
	(segment
		(start 387.610604 -254.578866)
		(end 387.698996 -254.667258)
		(width 0.088646)
		(layer "F.Cu")
		(net "M_E_CPU0_SA_CA<3>")
	)
	(segment
		(start 416.189668 -263.354312)
		(end 416.189668 -263.860534)
		(width 0.20066)
		(layer "F.Cu")
		(net "M_E_CPU0_SA_CA<3>")
	)
	(segment
		(start 415.287968 -264.041636)
		(end 413.307022 -264.041636)
		(width 0.1016)
		(layer "F.Cu")
		(net "M_E_CPU0_SA_CA<3>")
	)
	(segment
		(start 387.391402 -254.578866)
		(end 387.610604 -254.578866)
		(width 0.088646)
		(layer "F.Cu")
		(net "M_E_CPU0_SA_CA<3>")
	)
	(segment
		(start 387.698996 -254.667258)
		(end 388.230618 -254.667258)
		(width 0.088646)
		(layer "F.Cu")
		(net "M_E_CPU0_SA_CA<3>")
	)
	(segment
		(start 386.666486 -254.525018)
		(end 386.857494 -254.474218)
		(width 0.088646)
		(layer "F.Cu")
		(net "M_E_CPU0_SA_CA<3>")
	)
	(segment
		(start 405.731726 -263.175496)
		(end 405.747982 -263.191752)
		(width 0.1016)
		(layer "F.Cu")
		(net "M_E_CPU0_SA_CA<3>")
	)
	(segment
		(start 416.189668 -263.860534)
		(end 415.989008 -264.061194)
		(width 0.20066)
		(layer "F.Cu")
		(net "M_E_CPU0_SA_CA<3>")
	)
	(arc
		(start 385.72186 -254.52197)
		(mid 385.932316 -254.450862)
		(end 386.153914 -254.466344)
		(width 0.088646)
		(layer "F.Cu")
		(net "M_E_CPU0_SA_CA<3>")
	)
	(arc
		(start 386.385308 -254.57277)
		(mid 386.523784 -254.577688)
		(end 386.654548 -254.531876)
		(width 0.088646)
		(layer "F.Cu")
		(net "M_E_CPU0_SA_CA<3>")
	)
	(arc
		(start 385.347464 -254.52197)
		(mid 385.534662 -254.572113)
		(end 385.72186 -254.52197)
		(width 0.088646)
		(layer "F.Cu")
		(net "M_E_CPU0_SA_CA<3>")
	)
	(arc
		(start 385.07162 -254.446278)
		(mid 385.214406 -254.466397)
		(end 385.347464 -254.52197)
		(width 0.088646)
		(layer "F.Cu")
		(net "M_E_CPU0_SA_CA<3>")
	)
	(segment
		(start 392.971274 -258.745482)
		(end 395.352016 -258.745482)
		(width 0.1016)
		(layer "F.Cu")
		(net "M_E_CPU0_SA_CA<2>")
	)
	(segment
		(start 409.530042 -264.908538)
		(end 408.668982 -264.047478)
		(width 0.20066)
		(layer "F.Cu")
		(net "M_E_CPU0_SA_CA<2>")
	)
	(segment
		(start 412.739078 -264.901426)
		(end 411.863794 -264.901426)
		(width 0.20066)
		(layer "F.Cu")
		(net "M_E_CPU0_SA_CA<2>")
	)
	(segment
		(start 386.646674 -254.74422)
		(end 386.882894 -254.664464)
		(width 0.088646)
		(layer "F.Cu")
		(net "M_E_CPU0_SA_CA<2>")
	)
	(segment
		(start 403.831044 -263.669526)
		(end 404.095204 -263.933686)
		(width 0.20066)
		(layer "F.Cu")
		(net "M_E_CPU0_SA_CA<2>")
	)
	(segment
		(start 384.358134 -254.77851)
		(end 384.782568 -254.77851)
		(width 0.088646)
		(layer "F.Cu")
		(net "M_E_CPU0_SA_CA<2>")
	)
	(segment
		(start 388.784846 -254.972058)
		(end 389.48995 -255.264158)
		(width 0.1016)
		(layer "F.Cu")
		(net "M_E_CPU0_SA_CA<2>")
	)
	(segment
		(start 409.831794 -264.908538)
		(end 409.530042 -264.908538)
		(width 0.20066)
		(layer "F.Cu")
		(net "M_E_CPU0_SA_CA<2>")
	)
	(segment
		(start 406.202134 -264.466578)
		(end 406.753314 -264.466578)
		(width 0.20066)
		(layer "F.Cu")
		(net "M_E_CPU0_SA_CA<2>")
	)
	(segment
		(start 396.129764 -259.52323)
		(end 402.198078 -262.036814)
		(width 0.20066)
		(layer "F.Cu")
		(net "M_E_CPU0_SA_CA<2>")
	)
	(segment
		(start 384.124962 -255.011682)
		(end 384.358134 -254.77851)
		(width 0.088646)
		(layer "F.Cu")
		(net "M_E_CPU0_SA_CA<2>")
	)
	(segment
		(start 389.48995 -255.264158)
		(end 392.971274 -258.745482)
		(width 0.1016)
		(layer "F.Cu")
		(net "M_E_CPU0_SA_CA<2>")
	)
	(segment
		(start 387.094222 -254.664464)
		(end 387.336538 -254.769366)
		(width 0.088646)
		(layer "F.Cu")
		(net "M_E_CPU0_SA_CA<2>")
	)
	(segment
		(start 395.74216 -259.135626)
		(end 395.798294 -259.19176)
		(width 0.101854)
		(layer "F.Cu")
		(net "M_E_CPU0_SA_CA<2>")
	)
	(segment
		(start 404.095204 -263.933686)
		(end 405.323548 -263.933686)
		(width 0.20066)
		(layer "F.Cu")
		(net "M_E_CPU0_SA_CA<2>")
	)
	(segment
		(start 403.831044 -263.66978)
		(end 403.831044 -263.669526)
		(width 0.20066)
		(layer "F.Cu")
		(net "M_E_CPU0_SA_CA<2>")
	)
	(segment
		(start 409.848812 -264.89152)
		(end 409.831794 -264.908538)
		(width 0.1016)
		(layer "F.Cu")
		(net "M_E_CPU0_SA_CA<2>")
	)
	(segment
		(start 384.868674 -254.692404)
		(end 384.877564 -254.687324)
		(width 0.088646)
		(layer "F.Cu")
		(net "M_E_CPU0_SA_CA<2>")
	)
	(segment
		(start 387.521704 -254.769366)
		(end 387.724396 -254.972058)
		(width 0.088646)
		(layer "F.Cu")
		(net "M_E_CPU0_SA_CA<2>")
	)
	(segment
		(start 386.086858 -254.64643)
		(end 386.170424 -254.689356)
		(width 0.088646)
		(layer "F.Cu")
		(net "M_E_CPU0_SA_CA<2>")
	)
	(segment
		(start 395.352016 -258.745482)
		(end 395.74216 -259.135626)
		(width 0.1016)
		(layer "F.Cu")
		(net "M_E_CPU0_SA_CA<2>")
	)
	(segment
		(start 405.594058 -264.204196)
		(end 405.939752 -264.204196)
		(width 0.20066)
		(layer "F.Cu")
		(net "M_E_CPU0_SA_CA<2>")
	)
	(segment
		(start 413.173926 -264.466578)
		(end 412.739078 -264.901426)
		(width 0.20066)
		(layer "F.Cu")
		(net "M_E_CPU0_SA_CA<2>")
	)
	(segment
		(start 411.863794 -264.901426)
		(end 411.853888 -264.89152)
		(width 0.1016)
		(layer "F.Cu")
		(net "M_E_CPU0_SA_CA<2>")
	)
	(segment
		(start 387.336538 -254.769366)
		(end 387.521704 -254.769366)
		(width 0.088646)
		(layer "F.Cu")
		(net "M_E_CPU0_SA_CA<2>")
	)
	(segment
		(start 414.297114 -264.466578)
		(end 413.173926 -264.466578)
		(width 0.20066)
		(layer "F.Cu")
		(net "M_E_CPU0_SA_CA<2>")
	)
	(segment
		(start 408.668982 -264.047478)
		(end 407.755598 -264.047478)
		(width 0.20066)
		(layer "F.Cu")
		(net "M_E_CPU0_SA_CA<2>")
	)
	(segment
		(start 402.198078 -262.036814)
		(end 403.831044 -263.66978)
		(width 0.20066)
		(layer "F.Cu")
		(net "M_E_CPU0_SA_CA<2>")
	)
	(segment
		(start 387.724396 -254.972058)
		(end 388.230618 -254.972058)
		(width 0.088646)
		(layer "F.Cu")
		(net "M_E_CPU0_SA_CA<2>")
	)
	(segment
		(start 386.170424 -254.689356)
		(end 386.31495 -254.754126)
		(width 0.088646)
		(layer "F.Cu")
		(net "M_E_CPU0_SA_CA<2>")
	)
	(segment
		(start 405.939752 -264.204196)
		(end 406.202134 -264.466578)
		(width 0.20066)
		(layer "F.Cu")
		(net "M_E_CPU0_SA_CA<2>")
	)
	(segment
		(start 405.323548 -263.933686)
		(end 405.594058 -264.204196)
		(width 0.20066)
		(layer "F.Cu")
		(net "M_E_CPU0_SA_CA<2>")
	)
	(segment
		(start 407.336498 -264.466578)
		(end 406.753314 -264.466578)
		(width 0.20066)
		(layer "F.Cu")
		(net "M_E_CPU0_SA_CA<2>")
	)
	(segment
		(start 388.230618 -254.972058)
		(end 388.784846 -254.972058)
		(width 0.1016)
		(layer "F.Cu")
		(net "M_E_CPU0_SA_CA<2>")
	)
	(segment
		(start 395.798294 -259.19176)
		(end 396.129764 -259.52323)
		(width 0.20066)
		(layer "F.Cu")
		(net "M_E_CPU0_SA_CA<2>")
	)
	(segment
		(start 384.782568 -254.77851)
		(end 384.868674 -254.692404)
		(width 0.088646)
		(layer "F.Cu")
		(net "M_E_CPU0_SA_CA<2>")
	)
	(segment
		(start 407.755598 -264.047478)
		(end 407.336498 -264.466578)
		(width 0.20066)
		(layer "F.Cu")
		(net "M_E_CPU0_SA_CA<2>")
	)
	(segment
		(start 386.882894 -254.664464)
		(end 387.094222 -254.664464)
		(width 0.088646)
		(layer "F.Cu")
		(net "M_E_CPU0_SA_CA<2>")
	)
	(segment
		(start 411.853888 -264.89152)
		(end 409.848812 -264.89152)
		(width 0.1016)
		(layer "F.Cu")
		(net "M_E_CPU0_SA_CA<2>")
	)
	(arc
		(start 385.25196 -254.687324)
		(mid 385.534662 -254.763066)
		(end 385.817364 -254.687324)
		(width 0.088646)
		(layer "F.Cu")
		(net "M_E_CPU0_SA_CA<2>")
	)
	(arc
		(start 386.31495 -254.754126)
		(mid 386.481549 -254.774029)
		(end 386.646674 -254.74422)
		(width 0.088646)
		(layer "F.Cu")
		(net "M_E_CPU0_SA_CA<2>")
	)
	(arc
		(start 385.817364 -254.687324)
		(mid 385.94826 -254.641437)
		(end 386.086858 -254.64643)
		(width 0.088646)
		(layer "F.Cu")
		(net "M_E_CPU0_SA_CA<2>")
	)
	(arc
		(start 384.877564 -254.687324)
		(mid 385.064762 -254.637181)
		(end 385.25196 -254.687324)
		(width 0.088646)
		(layer "F.Cu")
		(net "M_E_CPU0_SA_CA<2>")
	)
	(segment
		(start 407.698448 -264.89152)
		(end 407.712926 -264.877042)
		(width 0.1016)
		(layer "F.Cu")
		(net "M_E_CPU0_SA_CA<1>")
	)
	(segment
		(start 387.584696 -255.276858)
		(end 388.230618 -255.276858)
		(width 0.088646)
		(layer "F.Cu")
		(net "M_E_CPU0_SA_CA<1>")
	)
	(segment
		(start 417.152328 -265.515852)
		(end 416.913568 -265.515852)
		(width 0.20066)
		(layer "F.Cu")
		(net "M_E_CPU0_SA_CA<1>")
	)
	(segment
		(start 403.860254 -264.606786)
		(end 405.061928 -264.606786)
		(width 0.20066)
		(layer "F.Cu")
		(net "M_E_CPU0_SA_CA<1>")
	)
	(segment
		(start 415.958528 -265.368532)
		(end 415.958528 -265.582908)
		(width 0.20066)
		(layer "F.Cu")
		(net "M_E_CPU0_SA_CA<1>")
	)
	(segment
		(start 386.944362 -255.011682)
		(end 387.584696 -255.276858)
		(width 0.088646)
		(layer "F.Cu")
		(net "M_E_CPU0_SA_CA<1>")
	)
	(segment
		(start 409.194508 -265.513312)
		(end 409.391104 -265.316716)
		(width 0.20066)
		(layer "F.Cu")
		(net "M_E_CPU0_SA_CA<1>")
	)
	(segment
		(start 416.644328 -265.246612)
		(end 416.080448 -265.246612)
		(width 0.20066)
		(layer "F.Cu")
		(net "M_E_CPU0_SA_CA<1>")
	)
	(segment
		(start 395.090904 -259.388864)
		(end 395.15542 -259.45338)
		(width 0.101854)
		(layer "F.Cu")
		(net "M_E_CPU0_SA_CA<1>")
	)
	(segment
		(start 401.986242 -262.732774)
		(end 403.860254 -264.606786)
		(width 0.20066)
		(layer "F.Cu")
		(net "M_E_CPU0_SA_CA<1>")
	)
	(segment
		(start 395.15542 -259.45338)
		(end 395.923516 -260.221476)
		(width 0.20066)
		(layer "F.Cu")
		(net "M_E_CPU0_SA_CA<1>")
	)
	(segment
		(start 408.472894 -265.075416)
		(end 408.472894 -265.37158)
		(width 0.20066)
		(layer "F.Cu")
		(net "M_E_CPU0_SA_CA<1>")
	)
	(segment
		(start 407.763726 -264.877042)
		(end 408.27452 -264.877042)
		(width 0.20066)
		(layer "F.Cu")
		(net "M_E_CPU0_SA_CA<1>")
	)
	(segment
		(start 394.752322 -259.050282)
		(end 395.090904 -259.388864)
		(width 0.1016)
		(layer "F.Cu")
		(net "M_E_CPU0_SA_CA<1>")
	)
	(segment
		(start 392.844782 -259.050282)
		(end 394.752322 -259.050282)
		(width 0.1016)
		(layer "F.Cu")
		(net "M_E_CPU0_SA_CA<1>")
	)
	(segment
		(start 416.913568 -265.515852)
		(end 416.644328 -265.246612)
		(width 0.20066)
		(layer "F.Cu")
		(net "M_E_CPU0_SA_CA<1>")
	)
	(segment
		(start 418.397182 -265.316716)
		(end 417.351464 -265.316716)
		(width 0.20066)
		(layer "F.Cu")
		(net "M_E_CPU0_SA_CA<1>")
	)
	(segment
		(start 405.329644 -264.874502)
		(end 405.731726 -264.874502)
		(width 0.20066)
		(layer "F.Cu")
		(net "M_E_CPU0_SA_CA<1>")
	)
	(segment
		(start 408.27452 -264.877042)
		(end 408.472894 -265.075416)
		(width 0.20066)
		(layer "F.Cu")
		(net "M_E_CPU0_SA_CA<1>")
	)
	(segment
		(start 408.472894 -265.37158)
		(end 408.614626 -265.513312)
		(width 0.20066)
		(layer "F.Cu")
		(net "M_E_CPU0_SA_CA<1>")
	)
	(segment
		(start 405.731726 -264.874502)
		(end 405.736552 -264.874502)
		(width 0.101854)
		(layer "F.Cu")
		(net "M_E_CPU0_SA_CA<1>")
	)
	(segment
		(start 395.923516 -260.221476)
		(end 401.986242 -262.732774)
		(width 0.20066)
		(layer "F.Cu")
		(net "M_E_CPU0_SA_CA<1>")
	)
	(segment
		(start 408.614626 -265.513312)
		(end 409.194508 -265.513312)
		(width 0.20066)
		(layer "F.Cu")
		(net "M_E_CPU0_SA_CA<1>")
	)
	(segment
		(start 415.958528 -265.582908)
		(end 415.778188 -265.763248)
		(width 0.20066)
		(layer "F.Cu")
		(net "M_E_CPU0_SA_CA<1>")
	)
	(segment
		(start 388.662164 -255.276858)
		(end 389.360918 -255.566418)
		(width 0.1016)
		(layer "F.Cu")
		(net "M_E_CPU0_SA_CA<1>")
	)
	(segment
		(start 409.391104 -265.316716)
		(end 410.853382 -265.316716)
		(width 0.20066)
		(layer "F.Cu")
		(net "M_E_CPU0_SA_CA<1>")
	)
	(segment
		(start 415.307526 -265.763248)
		(end 415.285936 -265.741658)
		(width 0.1016)
		(layer "F.Cu")
		(net "M_E_CPU0_SA_CA<1>")
	)
	(segment
		(start 416.080448 -265.246612)
		(end 415.958528 -265.368532)
		(width 0.20066)
		(layer "F.Cu")
		(net "M_E_CPU0_SA_CA<1>")
	)
	(segment
		(start 415.285936 -265.741658)
		(end 413.428688 -265.741658)
		(width 0.1016)
		(layer "F.Cu")
		(net "M_E_CPU0_SA_CA<1>")
	)
	(segment
		(start 417.351464 -265.316716)
		(end 417.152328 -265.515852)
		(width 0.20066)
		(layer "F.Cu")
		(net "M_E_CPU0_SA_CA<1>")
	)
	(segment
		(start 413.283908 -265.741658)
		(end 413.275526 -265.75004)
		(width 0.101854)
		(layer "F.Cu")
		(net "M_E_CPU0_SA_CA<1>")
	)
	(segment
		(start 412.097728 -265.316716)
		(end 410.853382 -265.316716)
		(width 0.20066)
		(layer "F.Cu")
		(net "M_E_CPU0_SA_CA<1>")
	)
	(segment
		(start 405.061928 -264.606786)
		(end 405.329644 -264.874502)
		(width 0.20066)
		(layer "F.Cu")
		(net "M_E_CPU0_SA_CA<1>")
	)
	(segment
		(start 412.531052 -265.75004)
		(end 412.097728 -265.316716)
		(width 0.20066)
		(layer "F.Cu")
		(net "M_E_CPU0_SA_CA<1>")
	)
	(segment
		(start 413.428688 -265.741658)
		(end 413.283908 -265.741658)
		(width 0.101854)
		(layer "F.Cu")
		(net "M_E_CPU0_SA_CA<1>")
	)
	(segment
		(start 413.275526 -265.75004)
		(end 412.531052 -265.75004)
		(width 0.20066)
		(layer "F.Cu")
		(net "M_E_CPU0_SA_CA<1>")
	)
	(segment
		(start 405.75357 -264.89152)
		(end 407.698448 -264.89152)
		(width 0.1016)
		(layer "F.Cu")
		(net "M_E_CPU0_SA_CA<1>")
	)
	(segment
		(start 407.712926 -264.877042)
		(end 407.763726 -264.877042)
		(width 0.101854)
		(layer "F.Cu")
		(net "M_E_CPU0_SA_CA<1>")
	)
	(segment
		(start 389.360918 -255.566418)
		(end 392.844782 -259.050282)
		(width 0.1016)
		(layer "F.Cu")
		(net "M_E_CPU0_SA_CA<1>")
	)
	(segment
		(start 405.736552 -264.874502)
		(end 405.75357 -264.89152)
		(width 0.1016)
		(layer "F.Cu")
		(net "M_E_CPU0_SA_CA<1>")
	)
	(segment
		(start 415.778188 -265.763248)
		(end 415.307526 -265.763248)
		(width 0.20066)
		(layer "F.Cu")
		(net "M_E_CPU0_SA_CA<1>")
	)
	(segment
		(start 388.230618 -255.276858)
		(end 388.662164 -255.276858)
		(width 0.1016)
		(layer "F.Cu")
		(net "M_E_CPU0_SA_CA<1>")
	)
	(segment
		(start 412.89986 -266.411964)
		(end 412.723076 -266.23518)
		(width 0.20066)
		(layer "F.Cu")
		(net "M_E_CPU0_SA_CA<0>")
	)
	(segment
		(start 387.192012 -255.668526)
		(end 387.350254 -255.668526)
		(width 0.088646)
		(layer "F.Cu")
		(net "M_E_CPU0_SA_CA<0>")
	)
	(segment
		(start 388.821676 -255.792732)
		(end 388.960868 -255.792732)
		(width 0.1016)
		(layer "F.Cu")
		(net "M_E_CPU0_SA_CA<0>")
	)
	(segment
		(start 409.421838 -266.482576)
		(end 409.069032 -266.482576)
		(width 0.20066)
		(layer "F.Cu")
		(net "M_E_CPU0_SA_CA<0>")
	)
	(segment
		(start 412.130494 -266.603226)
		(end 411.863794 -266.603226)
		(width 0.20066)
		(layer "F.Cu")
		(net "M_E_CPU0_SA_CA<0>")
	)
	(segment
		(start 388.378954 -255.78689)
		(end 388.525512 -255.640332)
		(width 0.1016)
		(layer "F.Cu")
		(net "M_E_CPU0_SA_CA<0>")
	)
	(segment
		(start 408.981148 -266.077446)
		(end 408.871928 -265.968226)
		(width 0.20066)
		(layer "F.Cu")
		(net "M_E_CPU0_SA_CA<0>")
	)
	(segment
		(start 392.785092 -259.421884)
		(end 393.408916 -259.421884)
		(width 0.1016)
		(layer "F.Cu")
		(net "M_E_CPU0_SA_CA<0>")
	)
	(segment
		(start 408.871928 -265.968226)
		(end 407.498042 -265.968226)
		(width 0.20066)
		(layer "F.Cu")
		(net "M_E_CPU0_SA_CA<0>")
	)
	(segment
		(start 409.546806 -266.607544)
		(end 409.421838 -266.482576)
		(width 0.20066)
		(layer "F.Cu")
		(net "M_E_CPU0_SA_CA<0>")
	)
	(segment
		(start 413.400748 -266.1666)
		(end 413.155384 -266.411964)
		(width 0.20066)
		(layer "F.Cu")
		(net "M_E_CPU0_SA_CA<0>")
	)
	(segment
		(start 409.852622 -266.591542)
		(end 409.83662 -266.607544)
		(width 0.1016)
		(layer "F.Cu")
		(net "M_E_CPU0_SA_CA<0>")
	)
	(segment
		(start 388.669276 -255.640332)
		(end 388.821676 -255.792732)
		(width 0.1016)
		(layer "F.Cu")
		(net "M_E_CPU0_SA_CA<0>")
	)
	(segment
		(start 408.981148 -266.394692)
		(end 408.981148 -266.077446)
		(width 0.20066)
		(layer "F.Cu")
		(net "M_E_CPU0_SA_CA<0>")
	)
	(segment
		(start 407.299668 -266.1666)
		(end 406.753314 -266.1666)
		(width 0.20066)
		(layer "F.Cu")
		(net "M_E_CPU0_SA_CA<0>")
	)
	(segment
		(start 405.000968 -265.320018)
		(end 405.654764 -265.973814)
		(width 0.20066)
		(layer "F.Cu")
		(net "M_E_CPU0_SA_CA<0>")
	)
	(segment
		(start 406.03043 -265.973814)
		(end 406.223216 -266.1666)
		(width 0.20066)
		(layer "F.Cu")
		(net "M_E_CPU0_SA_CA<0>")
	)
	(segment
		(start 387.350254 -255.668526)
		(end 387.436868 -255.581912)
		(width 0.088646)
		(layer "F.Cu")
		(net "M_E_CPU0_SA_CA<0>")
	)
	(segment
		(start 394.282422 -259.59562)
		(end 394.36929 -259.682488)
		(width 0.1016)
		(layer "F.Cu")
		(net "M_E_CPU0_SA_CA<0>")
	)
	(segment
		(start 413.155384 -266.411964)
		(end 412.89986 -266.411964)
		(width 0.20066)
		(layer "F.Cu")
		(net "M_E_CPU0_SA_CA<0>")
	)
	(segment
		(start 414.297114 -266.1666)
		(end 413.400748 -266.1666)
		(width 0.20066)
		(layer "F.Cu")
		(net "M_E_CPU0_SA_CA<0>")
	)
	(segment
		(start 411.863794 -266.603226)
		(end 411.863032 -266.603226)
		(width 0.101854)
		(layer "F.Cu")
		(net "M_E_CPU0_SA_CA<0>")
	)
	(segment
		(start 406.223216 -266.1666)
		(end 406.753314 -266.1666)
		(width 0.20066)
		(layer "F.Cu")
		(net "M_E_CPU0_SA_CA<0>")
	)
	(segment
		(start 412.49854 -266.23518)
		(end 412.130494 -266.603226)
		(width 0.20066)
		(layer "F.Cu")
		(net "M_E_CPU0_SA_CA<0>")
	)
	(segment
		(start 403.668738 -265.320018)
		(end 405.000968 -265.320018)
		(width 0.20066)
		(layer "F.Cu")
		(net "M_E_CPU0_SA_CA<0>")
	)
	(segment
		(start 388.161784 -255.78689)
		(end 388.378954 -255.78689)
		(width 0.1016)
		(layer "F.Cu")
		(net "M_E_CPU0_SA_CA<0>")
	)
	(segment
		(start 405.654764 -265.973814)
		(end 406.03043 -265.973814)
		(width 0.20066)
		(layer "F.Cu")
		(net "M_E_CPU0_SA_CA<0>")
	)
	(segment
		(start 407.498042 -265.968226)
		(end 407.299668 -266.1666)
		(width 0.20066)
		(layer "F.Cu")
		(net "M_E_CPU0_SA_CA<0>")
	)
	(segment
		(start 411.863032 -266.603226)
		(end 411.851348 -266.591542)
		(width 0.1016)
		(layer "F.Cu")
		(net "M_E_CPU0_SA_CA<0>")
	)
	(segment
		(start 401.7137 -263.36498)
		(end 403.668738 -265.320018)
		(width 0.20066)
		(layer "F.Cu")
		(net "M_E_CPU0_SA_CA<0>")
	)
	(segment
		(start 387.849618 -255.581912)
		(end 387.956806 -255.581912)
		(width 0.1016)
		(layer "F.Cu")
		(net "M_E_CPU0_SA_CA<0>")
	)
	(segment
		(start 411.851348 -266.591542)
		(end 409.852622 -266.591542)
		(width 0.1016)
		(layer "F.Cu")
		(net "M_E_CPU0_SA_CA<0>")
	)
	(segment
		(start 394.44295 -259.756148)
		(end 395.462252 -260.77545)
		(width 0.20066)
		(layer "F.Cu")
		(net "M_E_CPU0_SA_CA<0>")
	)
	(segment
		(start 409.069032 -266.482576)
		(end 408.981148 -266.394692)
		(width 0.20066)
		(layer "F.Cu")
		(net "M_E_CPU0_SA_CA<0>")
	)
	(segment
		(start 393.408916 -259.421884)
		(end 394.282422 -259.59562)
		(width 0.1016)
		(layer "F.Cu")
		(net "M_E_CPU0_SA_CA<0>")
	)
	(segment
		(start 409.83662 -266.607544)
		(end 409.831794 -266.607544)
		(width 0.101854)
		(layer "F.Cu")
		(net "M_E_CPU0_SA_CA<0>")
	)
	(segment
		(start 387.436868 -255.581912)
		(end 387.849618 -255.581912)
		(width 0.088646)
		(layer "F.Cu")
		(net "M_E_CPU0_SA_CA<0>")
	)
	(segment
		(start 388.960868 -255.792732)
		(end 389.293862 -255.930654)
		(width 0.1016)
		(layer "F.Cu")
		(net "M_E_CPU0_SA_CA<0>")
	)
	(segment
		(start 387.956806 -255.581912)
		(end 388.161784 -255.78689)
		(width 0.1016)
		(layer "F.Cu")
		(net "M_E_CPU0_SA_CA<0>")
	)
	(segment
		(start 386.004562 -255.011682)
		(end 387.192012 -255.668526)
		(width 0.088646)
		(layer "F.Cu")
		(net "M_E_CPU0_SA_CA<0>")
	)
	(segment
		(start 412.723076 -266.23518)
		(end 412.49854 -266.23518)
		(width 0.20066)
		(layer "F.Cu")
		(net "M_E_CPU0_SA_CA<0>")
	)
	(segment
		(start 409.831794 -266.607544)
		(end 409.546806 -266.607544)
		(width 0.20066)
		(layer "F.Cu")
		(net "M_E_CPU0_SA_CA<0>")
	)
	(segment
		(start 394.36929 -259.682488)
		(end 394.44295 -259.756148)
		(width 0.101854)
		(layer "F.Cu")
		(net "M_E_CPU0_SA_CA<0>")
	)
	(segment
		(start 388.525512 -255.640332)
		(end 388.669276 -255.640332)
		(width 0.1016)
		(layer "F.Cu")
		(net "M_E_CPU0_SA_CA<0>")
	)
	(segment
		(start 389.293862 -255.930654)
		(end 392.785092 -259.421884)
		(width 0.1016)
		(layer "F.Cu")
		(net "M_E_CPU0_SA_CA<0>")
	)
	(segment
		(start 395.462252 -260.77545)
		(end 401.7137 -263.36498)
		(width 0.20066)
		(layer "F.Cu")
		(net "M_E_CPU0_SA_CA<0>")
	)
	(segment
		(start 384.082544 -251.908056)
		(end 384.92049 -252.121162)
		(width 0.1524)
		(layer "F.Cu")
		(net "M_E_CPU0_CLK_DP<1>")
	)
	(segment
		(start 410.313632 -260.21665)
		(end 410.853382 -260.21665)
		(width 0.20066)
		(layer "F.Cu")
		(net "M_E_CPU0_CLK_DP<1>")
	)
	(segment
		(start 390.331452 -253.463806)
		(end 391.500868 -254.423926)
		(width 0.1524)
		(layer "F.Cu")
		(net "M_E_CPU0_CLK_DP<1>")
	)
	(segment
		(start 381.512826 -250.617736)
		(end 381.52959 -250.630436)
		(width 0.1524)
		(layer "F.Cu")
		(net "M_E_CPU0_CLK_DP<1>")
	)
	(segment
		(start 392.011154 -254.934212)
		(end 392.011154 -254.986282)
		(width 0.1524)
		(layer "F.Cu")
		(net "M_E_CPU0_CLK_DP<1>")
	)
	(segment
		(start 410.031184 -259.934202)
		(end 410.313632 -260.21665)
		(width 0.20066)
		(layer "F.Cu")
		(net "M_E_CPU0_CLK_DP<1>")
	)
	(segment
		(start 409.680918 -259.934202)
		(end 410.031184 -259.934202)
		(width 0.20066)
		(layer "F.Cu")
		(net "M_E_CPU0_CLK_DP<1>")
	)
	(segment
		(start 384.92049 -252.121162)
		(end 385.78155 -252.205998)
		(width 0.1524)
		(layer "F.Cu")
		(net "M_E_CPU0_CLK_DP<1>")
	)
	(segment
		(start 388.690866 -252.784356)
		(end 390.331452 -253.463806)
		(width 0.1524)
		(layer "F.Cu")
		(net "M_E_CPU0_CLK_DP<1>")
	)
	(segment
		(start 409.27909 -259.532374)
		(end 409.680918 -259.934202)
		(width 0.20066)
		(layer "F.Cu")
		(net "M_E_CPU0_CLK_DP<1>")
	)
	(segment
		(start 399.940526 -255.855724)
		(end 399.940526 -255.855978)
		(width 0.20066)
		(layer "F.Cu")
		(net "M_E_CPU0_CLK_DP<1>")
	)
	(segment
		(start 382.113028 -250.989592)
		(end 383.724658 -251.776484)
		(width 0.1524)
		(layer "F.Cu")
		(net "M_E_CPU0_CLK_DP<1>")
	)
	(segment
		(start 408.207718 -258.208018)
		(end 409.113736 -259.114036)
		(width 0.20066)
		(layer "F.Cu")
		(net "M_E_CPU0_CLK_DP<1>")
	)
	(segment
		(start 399.940526 -255.855978)
		(end 407.78049 -257.961384)
		(width 0.20066)
		(layer "F.Cu")
		(net "M_E_CPU0_CLK_DP<1>")
	)
	(segment
		(start 407.78049 -257.961384)
		(end 408.207718 -258.208018)
		(width 0.20066)
		(layer "F.Cu")
		(net "M_E_CPU0_CLK_DP<1>")
	)
	(segment
		(start 383.724658 -251.776484)
		(end 384.082544 -251.908056)
		(width 0.1524)
		(layer "F.Cu")
		(net "M_E_CPU0_CLK_DP<1>")
	)
	(segment
		(start 409.113736 -259.114036)
		(end 409.27909 -259.532374)
		(width 0.20066)
		(layer "F.Cu")
		(net "M_E_CPU0_CLK_DP<1>")
	)
	(segment
		(start 398.775936 -255.54305)
		(end 399.940526 -255.855724)
		(width 0.20066)
		(layer "F.Cu")
		(net "M_E_CPU0_CLK_DP<1>")
	)
	(segment
		(start 380.725934 -250.155964)
		(end 381.2032 -250.411488)
		(width 0.1524)
		(layer "F.Cu")
		(net "M_E_CPU0_CLK_DP<1>")
	)
	(segment
		(start 392.011154 -254.986282)
		(end 392.567922 -255.54305)
		(width 0.20066)
		(layer "F.Cu")
		(net "M_E_CPU0_CLK_DP<1>")
	)
	(segment
		(start 391.500868 -254.423926)
		(end 392.011154 -254.934212)
		(width 0.1524)
		(layer "F.Cu")
		(net "M_E_CPU0_CLK_DP<1>")
	)
	(segment
		(start 392.567922 -255.54305)
		(end 398.775936 -255.54305)
		(width 0.20066)
		(layer "F.Cu")
		(net "M_E_CPU0_CLK_DP<1>")
	)
	(segment
		(start 385.78155 -252.205998)
		(end 388.690866 -252.784356)
		(width 0.1524)
		(layer "F.Cu")
		(net "M_E_CPU0_CLK_DP<1>")
	)
	(segment
		(start 381.52959 -250.630436)
		(end 382.113028 -250.989592)
		(width 0.1524)
		(layer "F.Cu")
		(net "M_E_CPU0_CLK_DP<1>")
	)
	(segment
		(start 381.2032 -250.411488)
		(end 381.512826 -250.617736)
		(width 0.1524)
		(layer "F.Cu")
		(net "M_E_CPU0_CLK_DP<1>")
	)
	(segment
		(start 383.394204 -250.760992)
		(end 383.394712 -250.761246)
		(width 0.1524)
		(layer "F.Cu")
		(net "M_E_CPU0_CLK_DP<0>")
	)
	(segment
		(start 382.605534 -250.155964)
		(end 382.862836 -250.367038)
		(width 0.1524)
		(layer "F.Cu")
		(net "M_E_CPU0_CLK_DP<0>")
	)
	(segment
		(start 405.976582 -255.87579)
		(end 405.976328 -255.876044)
		(width 0.20066)
		(layer "F.Cu")
		(net "M_E_CPU0_CLK_DP<0>")
	)
	(segment
		(start 390.759696 -252.980952)
		(end 391.064242 -253.184152)
		(width 0.1524)
		(layer "F.Cu")
		(net "M_E_CPU0_CLK_DP<0>")
	)
	(segment
		(start 417.934648 -260.21665)
		(end 418.397182 -260.21665)
		(width 0.20066)
		(layer "F.Cu")
		(net "M_E_CPU0_CLK_DP<0>")
	)
	(segment
		(start 417.648136 -259.930138)
		(end 417.934648 -260.21665)
		(width 0.20066)
		(layer "F.Cu")
		(net "M_E_CPU0_CLK_DP<0>")
	)
	(segment
		(start 417.449 -259.930138)
		(end 417.648136 -259.930138)
		(width 0.20066)
		(layer "F.Cu")
		(net "M_E_CPU0_CLK_DP<0>")
	)
	(segment
		(start 417.208716 -259.830316)
		(end 417.449 -259.930138)
		(width 0.20066)
		(layer "F.Cu")
		(net "M_E_CPU0_CLK_DP<0>")
	)
	(segment
		(start 392.750294 -254.236474)
		(end 393.4968 -254.450342)
		(width 0.1524)
		(layer "F.Cu")
		(net "M_E_CPU0_CLK_DP<0>")
	)
	(segment
		(start 383.394712 -250.761246)
		(end 383.394966 -250.761754)
		(width 0.1524)
		(layer "F.Cu")
		(net "M_E_CPU0_CLK_DP<0>")
	)
	(segment
		(start 415.696146 -258.200906)
		(end 417.208716 -259.830316)
		(width 0.20066)
		(layer "F.Cu")
		(net "M_E_CPU0_CLK_DP<0>")
	)
	(segment
		(start 415.474912 -258.049268)
		(end 415.680144 -258.183634)
		(width 0.20066)
		(layer "F.Cu")
		(net "M_E_CPU0_CLK_DP<0>")
	)
	(segment
		(start 405.976328 -255.876044)
		(end 415.444432 -258.038092)
		(width 0.20066)
		(layer "F.Cu")
		(net "M_E_CPU0_CLK_DP<0>")
	)
	(segment
		(start 388.74192 -252.14453)
		(end 390.759696 -252.980952)
		(width 0.1524)
		(layer "F.Cu")
		(net "M_E_CPU0_CLK_DP<0>")
	)
	(segment
		(start 394.608812 -254.452628)
		(end 398.19326 -254.452628)
		(width 0.20066)
		(layer "F.Cu")
		(net "M_E_CPU0_CLK_DP<0>")
	)
	(segment
		(start 394.4493 -254.415798)
		(end 394.533882 -254.415798)
		(width 0.152654)
		(layer "F.Cu")
		(net "M_E_CPU0_CLK_DP<0>")
	)
	(segment
		(start 393.4968 -254.450342)
		(end 394.414756 -254.450342)
		(width 0.152654)
		(layer "F.Cu")
		(net "M_E_CPU0_CLK_DP<0>")
	)
	(segment
		(start 383.394966 -250.761754)
		(end 383.783332 -251.049282)
		(width 0.1524)
		(layer "F.Cu")
		(net "M_E_CPU0_CLK_DP<0>")
	)
	(segment
		(start 394.533882 -254.415798)
		(end 394.570712 -254.452628)
		(width 0.152654)
		(layer "F.Cu")
		(net "M_E_CPU0_CLK_DP<0>")
	)
	(segment
		(start 415.444432 -258.038092)
		(end 415.474912 -258.049268)
		(width 0.20066)
		(layer "F.Cu")
		(net "M_E_CPU0_CLK_DP<0>")
	)
	(segment
		(start 415.680144 -258.183634)
		(end 415.696146 -258.200906)
		(width 0.20066)
		(layer "F.Cu")
		(net "M_E_CPU0_CLK_DP<0>")
	)
	(segment
		(start 383.783332 -251.049282)
		(end 383.985516 -251.184664)
		(width 0.1524)
		(layer "F.Cu")
		(net "M_E_CPU0_CLK_DP<0>")
	)
	(segment
		(start 405.182324 -255.694434)
		(end 405.57958 -255.785366)
		(width 0.20066)
		(layer "F.Cu")
		(net "M_E_CPU0_CLK_DP<0>")
	)
	(segment
		(start 398.609312 -254.490474)
		(end 405.182324 -255.694434)
		(width 0.20066)
		(layer "F.Cu")
		(net "M_E_CPU0_CLK_DP<0>")
	)
	(segment
		(start 398.19326 -254.452628)
		(end 398.609312 -254.490474)
		(width 0.20066)
		(layer "F.Cu")
		(net "M_E_CPU0_CLK_DP<0>")
	)
	(segment
		(start 385.819396 -251.563632)
		(end 388.74192 -252.14453)
		(width 0.1524)
		(layer "F.Cu")
		(net "M_E_CPU0_CLK_DP<0>")
	)
	(segment
		(start 405.57958 -255.785366)
		(end 405.57958 -255.785112)
		(width 0.20066)
		(layer "F.Cu")
		(net "M_E_CPU0_CLK_DP<0>")
	)
	(segment
		(start 383.985516 -251.184664)
		(end 384.208528 -251.276104)
		(width 0.1524)
		(layer "F.Cu")
		(net "M_E_CPU0_CLK_DP<0>")
	)
	(segment
		(start 384.208528 -251.276104)
		(end 385.493514 -251.531374)
		(width 0.1524)
		(layer "F.Cu")
		(net "M_E_CPU0_CLK_DP<0>")
	)
	(segment
		(start 382.862836 -250.367038)
		(end 383.394204 -250.760992)
		(width 0.1524)
		(layer "F.Cu")
		(net "M_E_CPU0_CLK_DP<0>")
	)
	(segment
		(start 385.493514 -251.531374)
		(end 385.819396 -251.563632)
		(width 0.1524)
		(layer "F.Cu")
		(net "M_E_CPU0_CLK_DP<0>")
	)
	(segment
		(start 394.570712 -254.452628)
		(end 394.608812 -254.452628)
		(width 0.152654)
		(layer "F.Cu")
		(net "M_E_CPU0_CLK_DP<0>")
	)
	(segment
		(start 391.064242 -253.184152)
		(end 392.750294 -254.236474)
		(width 0.1524)
		(layer "F.Cu")
		(net "M_E_CPU0_CLK_DP<0>")
	)
	(segment
		(start 394.414756 -254.450342)
		(end 394.4493 -254.415798)
		(width 0.152654)
		(layer "F.Cu")
		(net "M_E_CPU0_CLK_DP<0>")
	)
	(segment
		(start 405.57958 -255.785112)
		(end 405.976582 -255.87579)
		(width 0.20066)
		(layer "F.Cu")
		(net "M_E_CPU0_CLK_DP<0>")
	)
	(segment
		(start 403.566376 -256.36093)
		(end 403.65426 -256.513838)
		(width 0.20066)
		(layer "F.Cu")
		(net "M_E_CPU0_CLK_DN<1>")
	)
	(segment
		(start 394.039344 -255.0922)
		(end 394.162534 -255.21539)
		(width 0.20066)
		(layer "F.Cu")
		(net "M_E_CPU0_CLK_DN<1>")
	)
	(segment
		(start 410.279088 -259.366766)
		(end 410.853382 -259.366766)
		(width 0.20066)
		(layer "F.Cu")
		(net "M_E_CPU0_CLK_DN<1>")
	)
	(segment
		(start 392.19124 -254.754634)
		(end 392.243056 -254.754634)
		(width 0.1524)
		(layer "F.Cu")
		(net "M_E_CPU0_CLK_DN<1>")
	)
	(segment
		(start 396.338044 -255.0922)
		(end 396.940024 -255.0922)
		(width 0.20066)
		(layer "F.Cu")
		(net "M_E_CPU0_CLK_DN<1>")
	)
	(segment
		(start 407.906474 -257.655314)
		(end 408.409648 -257.946144)
		(width 0.20066)
		(layer "F.Cu")
		(net "M_E_CPU0_CLK_DN<1>")
	)
	(segment
		(start 406.373076 -257.114802)
		(end 406.460706 -257.266948)
		(width 0.20066)
		(layer "F.Cu")
		(net "M_E_CPU0_CLK_DN<1>")
	)
	(segment
		(start 384.964432 -251.87021)
		(end 385.818888 -251.954284)
		(width 0.1524)
		(layer "F.Cu")
		(net "M_E_CPU0_CLK_DN<1>")
	)
	(segment
		(start 381.665734 -250.155964)
		(end 381.665734 -250.41479)
		(width 0.1524)
		(layer "F.Cu")
		(net "M_E_CPU0_CLK_DN<1>")
	)
	(segment
		(start 405.638762 -257.04673)
		(end 405.791416 -256.958846)
		(width 0.20066)
		(layer "F.Cu")
		(net "M_E_CPU0_CLK_DN<1>")
	)
	(segment
		(start 402.163026 -255.984248)
		(end 402.25091 -256.136902)
		(width 0.20066)
		(layer "F.Cu")
		(net "M_E_CPU0_CLK_DN<1>")
	)
	(segment
		(start 402.984716 -256.204974)
		(end 403.566376 -256.36093)
		(width 0.20066)
		(layer "F.Cu")
		(net "M_E_CPU0_CLK_DN<1>")
	)
	(segment
		(start 409.817062 -259.606542)
		(end 410.039312 -259.606542)
		(width 0.20066)
		(layer "F.Cu")
		(net "M_E_CPU0_CLK_DN<1>")
	)
	(segment
		(start 400.84756 -255.759966)
		(end 401.428712 -255.915922)
		(width 0.20066)
		(layer "F.Cu")
		(net "M_E_CPU0_CLK_DN<1>")
	)
	(segment
		(start 402.25091 -256.136902)
		(end 402.832062 -256.292858)
		(width 0.20066)
		(layer "F.Cu")
		(net "M_E_CPU0_CLK_DN<1>")
	)
	(segment
		(start 391.67181 -254.235204)
		(end 392.19124 -254.754634)
		(width 0.1524)
		(layer "F.Cu")
		(net "M_E_CPU0_CLK_DN<1>")
	)
	(segment
		(start 394.162534 -255.21539)
		(end 394.764514 -255.21539)
		(width 0.20066)
		(layer "F.Cu")
		(net "M_E_CPU0_CLK_DN<1>")
	)
	(segment
		(start 381.669544 -250.417584)
		(end 381.673354 -250.420632)
		(width 0.1524)
		(layer "F.Cu")
		(net "M_E_CPU0_CLK_DN<1>")
	)
	(segment
		(start 393.314174 -255.21539)
		(end 393.437364 -255.0922)
		(width 0.20066)
		(layer "F.Cu")
		(net "M_E_CPU0_CLK_DN<1>")
	)
	(segment
		(start 400.025616 -255.53924)
		(end 400.178016 -255.451356)
		(width 0.20066)
		(layer "F.Cu")
		(net "M_E_CPU0_CLK_DN<1>")
	)
	(segment
		(start 400.759676 -255.607312)
		(end 400.84756 -255.759966)
		(width 0.20066)
		(layer "F.Cu")
		(net "M_E_CPU0_CLK_DN<1>")
	)
	(segment
		(start 402.832062 -256.292858)
		(end 402.984716 -256.204974)
		(width 0.20066)
		(layer "F.Cu")
		(net "M_E_CPU0_CLK_DN<1>")
	)
	(segment
		(start 381.673354 -250.420632)
		(end 382.23571 -250.76658)
		(width 0.1524)
		(layer "F.Cu")
		(net "M_E_CPU0_CLK_DN<1>")
	)
	(segment
		(start 408.409648 -257.946144)
		(end 409.393136 -258.929632)
		(width 0.20066)
		(layer "F.Cu")
		(net "M_E_CPU0_CLK_DN<1>")
	)
	(segment
		(start 398.81937 -255.21539)
		(end 400.025616 -255.53924)
		(width 0.20066)
		(layer "F.Cu")
		(net "M_E_CPU0_CLK_DN<1>")
	)
	(segment
		(start 405.791416 -256.958846)
		(end 406.373076 -257.114802)
		(width 0.20066)
		(layer "F.Cu")
		(net "M_E_CPU0_CLK_DN<1>")
	)
	(segment
		(start 409.393136 -258.929632)
		(end 409.558998 -259.348478)
		(width 0.20066)
		(layer "F.Cu")
		(net "M_E_CPU0_CLK_DN<1>")
	)
	(segment
		(start 401.428712 -255.915922)
		(end 401.581366 -255.828038)
		(width 0.20066)
		(layer "F.Cu")
		(net "M_E_CPU0_CLK_DN<1>")
	)
	(segment
		(start 393.437364 -255.0922)
		(end 394.039344 -255.0922)
		(width 0.20066)
		(layer "F.Cu")
		(net "M_E_CPU0_CLK_DN<1>")
	)
	(segment
		(start 404.969726 -256.737866)
		(end 405.05761 -256.890774)
		(width 0.20066)
		(layer "F.Cu")
		(net "M_E_CPU0_CLK_DN<1>")
	)
	(segment
		(start 396.940024 -255.0922)
		(end 397.063214 -255.21539)
		(width 0.20066)
		(layer "F.Cu")
		(net "M_E_CPU0_CLK_DN<1>")
	)
	(segment
		(start 397.063214 -255.21539)
		(end 398.81937 -255.21539)
		(width 0.20066)
		(layer "F.Cu")
		(net "M_E_CPU0_CLK_DN<1>")
	)
	(segment
		(start 395.489684 -255.0922)
		(end 395.612874 -255.21539)
		(width 0.20066)
		(layer "F.Cu")
		(net "M_E_CPU0_CLK_DN<1>")
	)
	(segment
		(start 384.157982 -251.664978)
		(end 384.964432 -251.87021)
		(width 0.1524)
		(layer "F.Cu")
		(net "M_E_CPU0_CLK_DN<1>")
	)
	(segment
		(start 404.388066 -256.58191)
		(end 404.969726 -256.737866)
		(width 0.20066)
		(layer "F.Cu")
		(net "M_E_CPU0_CLK_DN<1>")
	)
	(segment
		(start 395.612874 -255.21539)
		(end 396.214854 -255.21539)
		(width 0.20066)
		(layer "F.Cu")
		(net "M_E_CPU0_CLK_DN<1>")
	)
	(segment
		(start 381.665734 -250.41479)
		(end 381.669544 -250.417584)
		(width 0.1524)
		(layer "F.Cu")
		(net "M_E_CPU0_CLK_DN<1>")
	)
	(segment
		(start 396.214854 -255.21539)
		(end 396.338044 -255.0922)
		(width 0.20066)
		(layer "F.Cu")
		(net "M_E_CPU0_CLK_DN<1>")
	)
	(segment
		(start 392.243056 -254.754634)
		(end 392.703812 -255.21539)
		(width 0.20066)
		(layer "F.Cu")
		(net "M_E_CPU0_CLK_DN<1>")
	)
	(segment
		(start 410.039312 -259.606542)
		(end 410.279088 -259.366766)
		(width 0.20066)
		(layer "F.Cu")
		(net "M_E_CPU0_CLK_DN<1>")
	)
	(segment
		(start 382.23571 -250.76658)
		(end 383.82448 -251.54255)
		(width 0.1524)
		(layer "F.Cu")
		(net "M_E_CPU0_CLK_DN<1>")
	)
	(segment
		(start 401.581366 -255.828038)
		(end 402.163026 -255.984248)
		(width 0.20066)
		(layer "F.Cu")
		(net "M_E_CPU0_CLK_DN<1>")
	)
	(segment
		(start 404.235412 -256.669794)
		(end 404.388066 -256.58191)
		(width 0.20066)
		(layer "F.Cu")
		(net "M_E_CPU0_CLK_DN<1>")
	)
	(segment
		(start 406.460706 -257.266948)
		(end 407.906474 -257.655314)
		(width 0.20066)
		(layer "F.Cu")
		(net "M_E_CPU0_CLK_DN<1>")
	)
	(segment
		(start 383.82448 -251.54255)
		(end 384.157982 -251.664978)
		(width 0.1524)
		(layer "F.Cu")
		(net "M_E_CPU0_CLK_DN<1>")
	)
	(segment
		(start 390.463532 -253.243334)
		(end 391.67181 -254.235204)
		(width 0.1524)
		(layer "F.Cu")
		(net "M_E_CPU0_CLK_DN<1>")
	)
	(segment
		(start 403.65426 -256.513838)
		(end 404.235412 -256.669794)
		(width 0.20066)
		(layer "F.Cu")
		(net "M_E_CPU0_CLK_DN<1>")
	)
	(segment
		(start 394.887704 -255.0922)
		(end 395.489684 -255.0922)
		(width 0.20066)
		(layer "F.Cu")
		(net "M_E_CPU0_CLK_DN<1>")
	)
	(segment
		(start 409.558998 -259.348478)
		(end 409.817062 -259.606542)
		(width 0.20066)
		(layer "F.Cu")
		(net "M_E_CPU0_CLK_DN<1>")
	)
	(segment
		(start 388.765034 -252.540008)
		(end 390.463532 -253.243334)
		(width 0.1524)
		(layer "F.Cu")
		(net "M_E_CPU0_CLK_DN<1>")
	)
	(segment
		(start 385.818888 -251.954284)
		(end 388.765034 -252.540008)
		(width 0.1524)
		(layer "F.Cu")
		(net "M_E_CPU0_CLK_DN<1>")
	)
	(segment
		(start 400.178016 -255.451356)
		(end 400.759676 -255.607312)
		(width 0.20066)
		(layer "F.Cu")
		(net "M_E_CPU0_CLK_DN<1>")
	)
	(segment
		(start 392.703812 -255.21539)
		(end 393.314174 -255.21539)
		(width 0.20066)
		(layer "F.Cu")
		(net "M_E_CPU0_CLK_DN<1>")
	)
	(segment
		(start 405.05761 -256.890774)
		(end 405.638762 -257.04673)
		(width 0.20066)
		(layer "F.Cu")
		(net "M_E_CPU0_CLK_DN<1>")
	)
	(segment
		(start 394.764514 -255.21539)
		(end 394.887704 -255.0922)
		(width 0.20066)
		(layer "F.Cu")
		(net "M_E_CPU0_CLK_DN<1>")
	)
	(segment
		(start 397.511778 -254.001778)
		(end 397.634968 -254.124968)
		(width 0.20066)
		(layer "F.Cu")
		(net "M_E_CPU0_CLK_DN<0>")
	)
	(segment
		(start 384.105658 -250.959366)
		(end 384.281426 -251.031756)
		(width 0.1524)
		(layer "F.Cu")
		(net "M_E_CPU0_CLK_DN<0>")
	)
	(segment
		(start 398.653762 -254.165354)
		(end 405.248364 -255.373378)
		(width 0.20066)
		(layer "F.Cu")
		(net "M_E_CPU0_CLK_DN<0>")
	)
	(segment
		(start 412.521146 -257.03403)
		(end 413.107886 -257.167888)
		(width 0.20066)
		(layer "F.Cu")
		(net "M_E_CPU0_CLK_DN<0>")
	)
	(segment
		(start 413.253936 -257.076194)
		(end 413.84093 -257.210306)
		(width 0.20066)
		(layer "F.Cu")
		(net "M_E_CPU0_CLK_DN<0>")
	)
	(segment
		(start 409.018994 -256.109216)
		(end 409.606242 -256.243074)
		(width 0.20066)
		(layer "F.Cu")
		(net "M_E_CPU0_CLK_DN<0>")
	)
	(segment
		(start 417.514532 -259.602478)
		(end 417.653724 -259.602478)
		(width 0.20066)
		(layer "F.Cu")
		(net "M_E_CPU0_CLK_DN<0>")
	)
	(segment
		(start 411.696408 -256.845562)
		(end 411.842204 -256.753868)
		(width 0.20066)
		(layer "F.Cu")
		(net "M_E_CPU0_CLK_DN<0>")
	)
	(segment
		(start 383.545334 -250.155964)
		(end 383.545334 -250.495054)
		(width 0.1524)
		(layer "F.Cu")
		(net "M_E_CPU0_CLK_DN<0>")
	)
	(segment
		(start 407.607262 -255.78689)
		(end 408.19451 -255.920748)
		(width 0.20066)
		(layer "F.Cu")
		(net "M_E_CPU0_CLK_DN<0>")
	)
	(segment
		(start 411.842204 -256.753868)
		(end 412.429452 -256.887726)
		(width 0.20066)
		(layer "F.Cu")
		(net "M_E_CPU0_CLK_DN<0>")
	)
	(segment
		(start 383.545334 -250.495054)
		(end 383.594864 -250.593606)
		(width 0.1524)
		(layer "F.Cu")
		(net "M_E_CPU0_CLK_DN<0>")
	)
	(segment
		(start 390.880092 -252.755654)
		(end 391.044176 -252.865128)
		(width 0.1524)
		(layer "F.Cu")
		(net "M_E_CPU0_CLK_DN<0>")
	)
	(segment
		(start 385.530598 -251.27966)
		(end 385.858512 -251.312172)
		(width 0.1524)
		(layer "F.Cu")
		(net "M_E_CPU0_CLK_DN<0>")
	)
	(segment
		(start 384.281426 -251.031756)
		(end 385.530598 -251.27966)
		(width 0.1524)
		(layer "F.Cu")
		(net "M_E_CPU0_CLK_DN<0>")
	)
	(segment
		(start 413.932624 -257.35661)
		(end 415.53638 -257.722624)
		(width 0.20066)
		(layer "F.Cu")
		(net "M_E_CPU0_CLK_DN<0>")
	)
	(segment
		(start 392.855958 -254.00254)
		(end 393.532106 -254.196088)
		(width 0.1524)
		(layer "F.Cu")
		(net "M_E_CPU0_CLK_DN<0>")
	)
	(segment
		(start 408.286204 -256.067052)
		(end 408.872944 -256.20091)
		(width 0.20066)
		(layer "F.Cu")
		(net "M_E_CPU0_CLK_DN<0>")
	)
	(segment
		(start 398.208246 -254.124968)
		(end 398.653762 -254.165354)
		(width 0.20066)
		(layer "F.Cu")
		(net "M_E_CPU0_CLK_DN<0>")
	)
	(segment
		(start 394.608812 -254.124968)
		(end 396.804388 -254.124968)
		(width 0.20066)
		(layer "F.Cu")
		(net "M_E_CPU0_CLK_DN<0>")
	)
	(segment
		(start 415.893504 -257.931412)
		(end 416.143694 -258.200906)
		(width 0.20066)
		(layer "F.Cu")
		(net "M_E_CPU0_CLK_DN<0>")
	)
	(segment
		(start 383.929636 -250.84151)
		(end 384.105658 -250.959366)
		(width 0.1524)
		(layer "F.Cu")
		(net "M_E_CPU0_CLK_DN<0>")
	)
	(segment
		(start 408.19451 -255.920748)
		(end 408.286204 -256.067052)
		(width 0.20066)
		(layer "F.Cu")
		(net "M_E_CPU0_CLK_DN<0>")
	)
	(segment
		(start 417.889436 -259.366766)
		(end 418.397182 -259.366766)
		(width 0.20066)
		(layer "F.Cu")
		(net "M_E_CPU0_CLK_DN<0>")
	)
	(segment
		(start 406.874472 -255.744726)
		(end 407.461212 -255.878584)
		(width 0.20066)
		(layer "F.Cu")
		(net "M_E_CPU0_CLK_DN<0>")
	)
	(segment
		(start 394.534136 -254.161544)
		(end 394.570712 -254.124968)
		(width 0.1524)
		(layer "F.Cu")
		(net "M_E_CPU0_CLK_DN<0>")
	)
	(segment
		(start 388.816088 -251.900182)
		(end 390.880092 -252.755654)
		(width 0.1524)
		(layer "F.Cu")
		(net "M_E_CPU0_CLK_DN<0>")
	)
	(segment
		(start 396.804388 -254.124968)
		(end 396.927578 -254.001778)
		(width 0.20066)
		(layer "F.Cu")
		(net "M_E_CPU0_CLK_DN<0>")
	)
	(segment
		(start 406.19553 -255.464564)
		(end 406.782778 -255.598422)
		(width 0.20066)
		(layer "F.Cu")
		(net "M_E_CPU0_CLK_DN<0>")
	)
	(segment
		(start 409.697936 -256.389378)
		(end 410.284676 -256.523236)
		(width 0.20066)
		(layer "F.Cu")
		(net "M_E_CPU0_CLK_DN<0>")
	)
	(segment
		(start 411.017974 -256.5654)
		(end 411.109668 -256.711704)
		(width 0.20066)
		(layer "F.Cu")
		(net "M_E_CPU0_CLK_DN<0>")
	)
	(segment
		(start 416.143694 -258.200906)
		(end 417.400232 -259.55498)
		(width 0.20066)
		(layer "F.Cu")
		(net "M_E_CPU0_CLK_DN<0>")
	)
	(segment
		(start 417.653724 -259.602478)
		(end 417.889436 -259.366766)
		(width 0.20066)
		(layer "F.Cu")
		(net "M_E_CPU0_CLK_DN<0>")
	)
	(segment
		(start 397.634968 -254.124968)
		(end 398.208246 -254.124968)
		(width 0.20066)
		(layer "F.Cu")
		(net "M_E_CPU0_CLK_DN<0>")
	)
	(segment
		(start 393.532106 -254.196088)
		(end 394.321284 -254.196088)
		(width 0.1524)
		(layer "F.Cu")
		(net "M_E_CPU0_CLK_DN<0>")
	)
	(segment
		(start 408.872944 -256.20091)
		(end 409.018994 -256.109216)
		(width 0.20066)
		(layer "F.Cu")
		(net "M_E_CPU0_CLK_DN<0>")
	)
	(segment
		(start 410.430726 -256.431542)
		(end 411.017974 -256.5654)
		(width 0.20066)
		(layer "F.Cu")
		(net "M_E_CPU0_CLK_DN<0>")
	)
	(segment
		(start 407.461212 -255.878584)
		(end 407.607262 -255.78689)
		(width 0.20066)
		(layer "F.Cu")
		(net "M_E_CPU0_CLK_DN<0>")
	)
	(segment
		(start 417.400232 -259.55498)
		(end 417.514532 -259.602478)
		(width 0.20066)
		(layer "F.Cu")
		(net "M_E_CPU0_CLK_DN<0>")
	)
	(segment
		(start 413.84093 -257.210306)
		(end 413.932624 -257.35661)
		(width 0.20066)
		(layer "F.Cu")
		(net "M_E_CPU0_CLK_DN<0>")
	)
	(segment
		(start 394.355828 -254.161544)
		(end 394.534136 -254.161544)
		(width 0.1524)
		(layer "F.Cu")
		(net "M_E_CPU0_CLK_DN<0>")
	)
	(segment
		(start 410.284676 -256.523236)
		(end 410.430726 -256.431542)
		(width 0.20066)
		(layer "F.Cu")
		(net "M_E_CPU0_CLK_DN<0>")
	)
	(segment
		(start 406.04948 -255.556258)
		(end 406.19553 -255.464564)
		(width 0.20066)
		(layer "F.Cu")
		(net "M_E_CPU0_CLK_DN<0>")
	)
	(segment
		(start 394.570712 -254.124968)
		(end 394.608812 -254.124968)
		(width 0.152654)
		(layer "F.Cu")
		(net "M_E_CPU0_CLK_DN<0>")
	)
	(segment
		(start 413.107886 -257.167888)
		(end 413.253936 -257.076194)
		(width 0.20066)
		(layer "F.Cu")
		(net "M_E_CPU0_CLK_DN<0>")
	)
	(segment
		(start 383.594864 -250.593606)
		(end 383.929636 -250.84151)
		(width 0.1524)
		(layer "F.Cu")
		(net "M_E_CPU0_CLK_DN<0>")
	)
	(segment
		(start 394.321284 -254.196088)
		(end 394.355828 -254.161544)
		(width 0.1524)
		(layer "F.Cu")
		(net "M_E_CPU0_CLK_DN<0>")
	)
	(segment
		(start 412.429452 -256.887726)
		(end 412.521146 -257.03403)
		(width 0.20066)
		(layer "F.Cu")
		(net "M_E_CPU0_CLK_DN<0>")
	)
	(segment
		(start 396.927578 -254.001778)
		(end 397.511778 -254.001778)
		(width 0.20066)
		(layer "F.Cu")
		(net "M_E_CPU0_CLK_DN<0>")
	)
	(segment
		(start 391.044176 -252.865128)
		(end 392.855958 -254.00254)
		(width 0.1524)
		(layer "F.Cu")
		(net "M_E_CPU0_CLK_DN<0>")
	)
	(segment
		(start 415.53638 -257.722624)
		(end 415.623502 -257.754628)
		(width 0.20066)
		(layer "F.Cu")
		(net "M_E_CPU0_CLK_DN<0>")
	)
	(segment
		(start 411.109668 -256.711704)
		(end 411.696408 -256.845562)
		(width 0.20066)
		(layer "F.Cu")
		(net "M_E_CPU0_CLK_DN<0>")
	)
	(segment
		(start 405.248364 -255.373378)
		(end 406.04948 -255.556258)
		(width 0.20066)
		(layer "F.Cu")
		(net "M_E_CPU0_CLK_DN<0>")
	)
	(segment
		(start 415.623502 -257.754628)
		(end 415.893504 -257.931412)
		(width 0.20066)
		(layer "F.Cu")
		(net "M_E_CPU0_CLK_DN<0>")
	)
	(segment
		(start 385.858512 -251.312172)
		(end 388.816088 -251.900182)
		(width 0.1524)
		(layer "F.Cu")
		(net "M_E_CPU0_CLK_DN<0>")
	)
	(segment
		(start 406.782778 -255.598422)
		(end 406.874472 -255.744726)
		(width 0.20066)
		(layer "F.Cu")
		(net "M_E_CPU0_CLK_DN<0>")
	)
	(segment
		(start 409.606242 -256.243074)
		(end 409.697936 -256.389378)
		(width 0.20066)
		(layer "F.Cu")
		(net "M_E_CPU0_CLK_DN<0>")
	)
	(segment
		(start 409.64866 -269.141702)
		(end 409.465526 -269.141702)
		(width 0.20066)
		(layer "F.Cu")
		(net "M_E_CPU0_ALERT_N")
	)
	(segment
		(start 412.04261 -269.141702)
		(end 411.68193 -269.141702)
		(width 0.101854)
		(layer "F.Cu")
		(net "M_E_CPU0_ALERT_N")
	)
	(segment
		(start 408.453082 -268.81455)
		(end 407.700988 -269.566644)
		(width 0.20066)
		(layer "F.Cu")
		(net "M_E_CPU0_ALERT_N")
	)
	(segment
		(start 411.68193 -269.141702)
		(end 409.863036 -269.141702)
		(width 0.1016)
		(layer "F.Cu")
		(net "M_E_CPU0_ALERT_N")
	)
	(segment
		(start 407.700988 -269.566644)
		(end 406.753314 -269.566644)
		(width 0.20066)
		(layer "F.Cu")
		(net "M_E_CPU0_ALERT_N")
	)
	(segment
		(start 413.30118 -269.972028)
		(end 412.955232 -269.972028)
		(width 0.20066)
		(layer "F.Cu")
		(net "M_E_CPU0_ALERT_N")
	)
	(segment
		(start 412.510732 -269.362428)
		(end 412.290006 -269.141702)
		(width 0.20066)
		(layer "F.Cu")
		(net "M_E_CPU0_ALERT_N")
	)
	(segment
		(start 412.510732 -269.527528)
		(end 412.510732 -269.362428)
		(width 0.20066)
		(layer "F.Cu")
		(net "M_E_CPU0_ALERT_N")
	)
	(segment
		(start 413.706564 -269.566644)
		(end 413.30118 -269.972028)
		(width 0.20066)
		(layer "F.Cu")
		(net "M_E_CPU0_ALERT_N")
	)
	(segment
		(start 406.753314 -269.566644)
		(end 405.648414 -269.566644)
		(width 0.20066)
		(layer "F.Cu")
		(net "M_E_CPU0_ALERT_N")
	)
	(segment
		(start 409.465526 -269.141702)
		(end 409.138374 -268.81455)
		(width 0.20066)
		(layer "F.Cu")
		(net "M_E_CPU0_ALERT_N")
	)
	(segment
		(start 414.297114 -269.566644)
		(end 413.706564 -269.566644)
		(width 0.20066)
		(layer "F.Cu")
		(net "M_E_CPU0_ALERT_N")
	)
	(segment
		(start 412.290006 -269.141702)
		(end 412.04261 -269.141702)
		(width 0.20066)
		(layer "F.Cu")
		(net "M_E_CPU0_ALERT_N")
	)
	(segment
		(start 370.027962 -253.383796)
		(end 370.027962 -253.919482)
		(width 0.20066)
		(layer "F.Cu")
		(net "M_E_CPU0_ALERT_N")
	)
	(segment
		(start 370.027962 -253.919482)
		(end 370.028216 -253.919736)
		(width 0.20066)
		(layer "F.Cu")
		(net "M_E_CPU0_ALERT_N")
	)
	(segment
		(start 409.138374 -268.81455)
		(end 408.453082 -268.81455)
		(width 0.20066)
		(layer "F.Cu")
		(net "M_E_CPU0_ALERT_N")
	)
	(segment
		(start 412.955232 -269.972028)
		(end 412.510732 -269.527528)
		(width 0.20066)
		(layer "F.Cu")
		(net "M_E_CPU0_ALERT_N")
	)
	(segment
		(start 409.863036 -269.141702)
		(end 409.64866 -269.141702)
		(width 0.101854)
		(layer "F.Cu")
		(net "M_E_CPU0_ALERT_N")
	)
	(via
		(at 405.648414 -269.566644)
		(size 0.4572)
		(drill 0.2032)
		(layers "F.Cu" "B.Cu")
		(net "M_E_CPU0_ALERT_N")
	)
	(via
		(at 370.028216 -253.919736)
		(size 0.4572)
		(drill 0.2032)
		(layers "F.Cu" "B.Cu")
		(net "M_E_CPU0_ALERT_N")
	)
	(segment
		(start 372.190264 -257.664712)
		(end 372.175532 -257.673348)
		(width 0.088646)
		(layer "In11.Cu")
		(net "M_E_CPU0_ALERT_N")
	)
	(segment
		(start 388.763764 -258.427728)
		(end 387.113018 -258.427728)
		(width 0.18288)
		(layer "In11.Cu")
		(net "M_E_CPU0_ALERT_N")
	)
	(segment
		(start 405.648414 -269.566644)
		(end 405.648414 -269.291562)
		(width 0.18288)
		(layer "In11.Cu")
		(net "M_E_CPU0_ALERT_N")
	)
	(segment
		(start 381.588518 -257.664712)
		(end 381.578104 -257.670808)
		(width 0.088646)
		(layer "In11.Cu")
		(net "M_E_CPU0_ALERT_N")
	)
	(segment
		(start 383.852674 -257.670808)
		(end 383.84226 -257.664712)
		(width 0.088646)
		(layer "In11.Cu")
		(net "M_E_CPU0_ALERT_N")
	)
	(segment
		(start 375.009918 -257.664712)
		(end 374.999504 -257.670808)
		(width 0.088646)
		(layer "In11.Cu")
		(net "M_E_CPU0_ALERT_N")
	)
	(segment
		(start 373.515128 -257.670808)
		(end 373.504714 -257.664712)
		(width 0.088646)
		(layer "In11.Cu")
		(net "M_E_CPU0_ALERT_N")
	)
	(segment
		(start 386.849366 -258.297426)
		(end 386.849366 -257.98907)
		(width 0.088646)
		(layer "In11.Cu")
		(net "M_E_CPU0_ALERT_N")
	)
	(segment
		(start 371.250464 -257.664712)
		(end 371.235732 -257.673348)
		(width 0.088646)
		(layer "In11.Cu")
		(net "M_E_CPU0_ALERT_N")
	)
	(segment
		(start 381.973328 -257.670808)
		(end 381.962914 -257.664712)
		(width 0.088646)
		(layer "In11.Cu")
		(net "M_E_CPU0_ALERT_N")
	)
	(segment
		(start 383.46761 -257.664458)
		(end 383.467864 -257.664712)
		(width 0.088646)
		(layer "In11.Cu")
		(net "M_E_CPU0_ALERT_N")
	)
	(segment
		(start 405.373586 -269.045944)
		(end 405.17953 -268.884654)
		(width 0.18288)
		(layer "In11.Cu")
		(net "M_E_CPU0_ALERT_N")
	)
	(segment
		(start 370.028216 -256.325878)
		(end 370.028216 -253.919736)
		(width 0.088646)
		(layer "In11.Cu")
		(net "M_E_CPU0_ALERT_N")
	)
	(segment
		(start 369.56746 -257.22961)
		(end 369.70843 -256.88925)
		(width 0.088646)
		(layer "In11.Cu")
		(net "M_E_CPU0_ALERT_N")
	)
	(segment
		(start 405.545544 -269.188692)
		(end 405.373586 -269.045944)
		(width 0.18288)
		(layer "In11.Cu")
		(net "M_E_CPU0_ALERT_N")
	)
	(segment
		(start 373.130318 -257.664712)
		(end 373.119904 -257.670808)
		(width 0.088646)
		(layer "In11.Cu")
		(net "M_E_CPU0_ALERT_N")
	)
	(segment
		(start 375.394728 -257.670808)
		(end 375.384314 -257.664712)
		(width 0.088646)
		(layer "In11.Cu")
		(net "M_E_CPU0_ALERT_N")
	)
	(segment
		(start 376.889264 -257.664712)
		(end 376.874532 -257.673348)
		(width 0.088646)
		(layer "In11.Cu")
		(net "M_E_CPU0_ALERT_N")
	)
	(segment
		(start 386.670804 -257.669792)
		(end 386.661914 -257.664712)
		(width 0.088646)
		(layer "In11.Cu")
		(net "M_E_CPU0_ALERT_N")
	)
	(segment
		(start 377.829064 -257.664712)
		(end 377.814332 -257.673348)
		(width 0.088646)
		(layer "In11.Cu")
		(net "M_E_CPU0_ALERT_N")
	)
	(segment
		(start 379.708918 -257.664712)
		(end 379.698504 -257.670808)
		(width 0.088646)
		(layer "In11.Cu")
		(net "M_E_CPU0_ALERT_N")
	)
	(segment
		(start 370.310664 -257.664712)
		(end 370.295932 -257.673348)
		(width 0.088646)
		(layer "In11.Cu")
		(net "M_E_CPU0_ALERT_N")
	)
	(segment
		(start 369.70843 -256.88925)
		(end 369.856004 -256.741676)
		(width 0.088646)
		(layer "In11.Cu")
		(net "M_E_CPU0_ALERT_N")
	)
	(segment
		(start 387.113018 -258.427728)
		(end 386.979668 -258.427728)
		(width 0.088646)
		(layer "In11.Cu")
		(net "M_E_CPU0_ALERT_N")
	)
	(segment
		(start 384.797046 -257.673348)
		(end 384.782314 -257.664712)
		(width 0.088646)
		(layer "In11.Cu")
		(net "M_E_CPU0_ALERT_N")
	)
	(segment
		(start 396.356586 -260.06171)
		(end 390.397746 -260.06171)
		(width 0.18288)
		(layer "In11.Cu")
		(net "M_E_CPU0_ALERT_N")
	)
	(segment
		(start 369.56746 -257.332988)
		(end 369.56746 -257.22961)
		(width 0.088646)
		(layer "In11.Cu")
		(net "M_E_CPU0_ALERT_N")
	)
	(segment
		(start 405.648414 -269.291562)
		(end 405.545544 -269.188692)
		(width 0.18288)
		(layer "In11.Cu")
		(net "M_E_CPU0_ALERT_N")
	)
	(segment
		(start 369.856004 -256.741676)
		(end 370.028216 -256.325878)
		(width 0.088646)
		(layer "In11.Cu")
		(net "M_E_CPU0_ALERT_N")
	)
	(segment
		(start 378.768864 -257.664712)
		(end 378.754132 -257.673348)
		(width 0.088646)
		(layer "In11.Cu")
		(net "M_E_CPU0_ALERT_N")
	)
	(segment
		(start 390.397746 -260.06171)
		(end 388.763764 -258.427728)
		(width 0.18288)
		(layer "In11.Cu")
		(net "M_E_CPU0_ALERT_N")
	)
	(segment
		(start 385.736846 -257.673348)
		(end 385.722114 -257.664712)
		(width 0.088646)
		(layer "In11.Cu")
		(net "M_E_CPU0_ALERT_N")
	)
	(segment
		(start 386.979668 -258.427728)
		(end 386.849366 -258.297426)
		(width 0.088646)
		(layer "In11.Cu")
		(net "M_E_CPU0_ALERT_N")
	)
	(segment
		(start 405.17953 -268.884654)
		(end 396.356586 -260.06171)
		(width 0.18288)
		(layer "In11.Cu")
		(net "M_E_CPU0_ALERT_N")
	)
	(segment
		(start 380.093728 -257.670808)
		(end 380.083314 -257.664712)
		(width 0.088646)
		(layer "In11.Cu")
		(net "M_E_CPU0_ALERT_N")
	)
	(segment
		(start 383.84226 -257.664712)
		(end 383.842514 -257.664458)
		(width 0.088646)
		(layer "In11.Cu")
		(net "M_E_CPU0_ALERT_N")
	)
	(segment
		(start 369.886484 -257.698748)
		(end 369.60048 -257.412744)
		(width 0.088646)
		(layer "In11.Cu")
		(net "M_E_CPU0_ALERT_N")
	)
	(arc
		(start 382.90246 -257.664712)
		(mid 382.715262 -257.614569)
		(end 382.528064 -257.664712)
		(width 0.088646)
		(layer "In11.Cu")
		(net "M_E_CPU0_ALERT_N")
	)
	(arc
		(start 369.966494 -257.737356)
		(mid 369.923178 -257.724907)
		(end 369.886484 -257.698748)
		(width 0.088646)
		(layer "In11.Cu")
		(net "M_E_CPU0_ALERT_N")
	)
	(arc
		(start 371.62486 -257.664712)
		(mid 371.437662 -257.614569)
		(end 371.250464 -257.664712)
		(width 0.088646)
		(layer "In11.Cu")
		(net "M_E_CPU0_ALERT_N")
	)
	(arc
		(start 384.782314 -257.664712)
		(mid 384.595116 -257.614569)
		(end 384.407918 -257.664712)
		(width 0.088646)
		(layer "In11.Cu")
		(net "M_E_CPU0_ALERT_N")
	)
	(arc
		(start 380.083314 -257.664712)
		(mid 379.896116 -257.614569)
		(end 379.708918 -257.664712)
		(width 0.088646)
		(layer "In11.Cu")
		(net "M_E_CPU0_ALERT_N")
	)
	(arc
		(start 370.295932 -257.673348)
		(mid 370.136071 -257.730355)
		(end 369.966494 -257.737356)
		(width 0.088646)
		(layer "In11.Cu")
		(net "M_E_CPU0_ALERT_N")
	)
	(arc
		(start 377.26366 -257.664712)
		(mid 377.076462 -257.614569)
		(end 376.889264 -257.664712)
		(width 0.088646)
		(layer "In11.Cu")
		(net "M_E_CPU0_ALERT_N")
	)
	(arc
		(start 382.528064 -257.664712)
		(mid 382.251505 -257.740455)
		(end 381.973328 -257.670808)
		(width 0.088646)
		(layer "In11.Cu")
		(net "M_E_CPU0_ALERT_N")
	)
	(arc
		(start 372.175532 -257.673348)
		(mid 371.899057 -257.740668)
		(end 371.62486 -257.664712)
		(width 0.088646)
		(layer "In11.Cu")
		(net "M_E_CPU0_ALERT_N")
	)
	(arc
		(start 372.56466 -257.664712)
		(mid 372.377462 -257.614569)
		(end 372.190264 -257.664712)
		(width 0.088646)
		(layer "In11.Cu")
		(net "M_E_CPU0_ALERT_N")
	)
	(arc
		(start 380.648464 -257.664712)
		(mid 380.371905 -257.740455)
		(end 380.093728 -257.670808)
		(width 0.088646)
		(layer "In11.Cu")
		(net "M_E_CPU0_ALERT_N")
	)
	(arc
		(start 378.20346 -257.664712)
		(mid 378.016262 -257.614569)
		(end 377.829064 -257.664712)
		(width 0.088646)
		(layer "In11.Cu")
		(net "M_E_CPU0_ALERT_N")
	)
	(arc
		(start 385.347718 -257.664712)
		(mid 385.073519 -257.740547)
		(end 384.797046 -257.673348)
		(width 0.088646)
		(layer "In11.Cu")
		(net "M_E_CPU0_ALERT_N")
	)
	(arc
		(start 379.14326 -257.664712)
		(mid 378.956062 -257.614569)
		(end 378.768864 -257.664712)
		(width 0.088646)
		(layer "In11.Cu")
		(net "M_E_CPU0_ALERT_N")
	)
	(arc
		(start 381.02286 -257.664712)
		(mid 380.835662 -257.614569)
		(end 380.648464 -257.664712)
		(width 0.088646)
		(layer "In11.Cu")
		(net "M_E_CPU0_ALERT_N")
	)
	(arc
		(start 386.661914 -257.664712)
		(mid 386.474716 -257.614569)
		(end 386.287518 -257.664712)
		(width 0.088646)
		(layer "In11.Cu")
		(net "M_E_CPU0_ALERT_N")
	)
	(arc
		(start 378.754132 -257.673348)
		(mid 378.477657 -257.740668)
		(end 378.20346 -257.664712)
		(width 0.088646)
		(layer "In11.Cu")
		(net "M_E_CPU0_ALERT_N")
	)
	(arc
		(start 373.119904 -257.670808)
		(mid 372.841472 -257.740654)
		(end 372.56466 -257.664712)
		(width 0.088646)
		(layer "In11.Cu")
		(net "M_E_CPU0_ALERT_N")
	)
	(arc
		(start 386.849366 -257.98907)
		(mid 386.801687 -257.80617)
		(end 386.670804 -257.669792)
		(width 0.088646)
		(layer "In11.Cu")
		(net "M_E_CPU0_ALERT_N")
	)
	(arc
		(start 377.814332 -257.673348)
		(mid 377.537857 -257.740668)
		(end 377.26366 -257.664712)
		(width 0.088646)
		(layer "In11.Cu")
		(net "M_E_CPU0_ALERT_N")
	)
	(arc
		(start 370.68506 -257.664712)
		(mid 370.497862 -257.614569)
		(end 370.310664 -257.664712)
		(width 0.088646)
		(layer "In11.Cu")
		(net "M_E_CPU0_ALERT_N")
	)
	(arc
		(start 371.235732 -257.673348)
		(mid 370.959257 -257.740668)
		(end 370.68506 -257.664712)
		(width 0.088646)
		(layer "In11.Cu")
		(net "M_E_CPU0_ALERT_N")
	)
	(arc
		(start 375.949464 -257.664712)
		(mid 375.672905 -257.740455)
		(end 375.394728 -257.670808)
		(width 0.088646)
		(layer "In11.Cu")
		(net "M_E_CPU0_ALERT_N")
	)
	(arc
		(start 385.722114 -257.664712)
		(mid 385.534916 -257.614569)
		(end 385.347718 -257.664712)
		(width 0.088646)
		(layer "In11.Cu")
		(net "M_E_CPU0_ALERT_N")
	)
	(arc
		(start 376.874532 -257.673348)
		(mid 376.598057 -257.740668)
		(end 376.32386 -257.664712)
		(width 0.088646)
		(layer "In11.Cu")
		(net "M_E_CPU0_ALERT_N")
	)
	(arc
		(start 386.287518 -257.664712)
		(mid 386.013319 -257.740547)
		(end 385.736846 -257.673348)
		(width 0.088646)
		(layer "In11.Cu")
		(net "M_E_CPU0_ALERT_N")
	)
	(arc
		(start 374.999504 -257.670808)
		(mid 374.721072 -257.740654)
		(end 374.44426 -257.664712)
		(width 0.088646)
		(layer "In11.Cu")
		(net "M_E_CPU0_ALERT_N")
	)
	(arc
		(start 381.578104 -257.670808)
		(mid 381.299672 -257.740654)
		(end 381.02286 -257.664712)
		(width 0.088646)
		(layer "In11.Cu")
		(net "M_E_CPU0_ALERT_N")
	)
	(arc
		(start 373.504714 -257.664712)
		(mid 373.317516 -257.614569)
		(end 373.130318 -257.664712)
		(width 0.088646)
		(layer "In11.Cu")
		(net "M_E_CPU0_ALERT_N")
	)
	(arc
		(start 384.407918 -257.664712)
		(mid 384.131105 -257.740582)
		(end 383.852674 -257.670808)
		(width 0.088646)
		(layer "In11.Cu")
		(net "M_E_CPU0_ALERT_N")
	)
	(arc
		(start 369.60048 -257.412744)
		(mid 369.57603 -257.376152)
		(end 369.56746 -257.332988)
		(width 0.088646)
		(layer "In11.Cu")
		(net "M_E_CPU0_ALERT_N")
	)
	(arc
		(start 375.384314 -257.664712)
		(mid 375.197116 -257.614569)
		(end 375.009918 -257.664712)
		(width 0.088646)
		(layer "In11.Cu")
		(net "M_E_CPU0_ALERT_N")
	)
	(arc
		(start 376.32386 -257.664712)
		(mid 376.136662 -257.614569)
		(end 375.949464 -257.664712)
		(width 0.088646)
		(layer "In11.Cu")
		(net "M_E_CPU0_ALERT_N")
	)
	(arc
		(start 374.069864 -257.664712)
		(mid 373.793305 -257.740455)
		(end 373.515128 -257.670808)
		(width 0.088646)
		(layer "In11.Cu")
		(net "M_E_CPU0_ALERT_N")
	)
	(arc
		(start 379.698504 -257.670808)
		(mid 379.420072 -257.740654)
		(end 379.14326 -257.664712)
		(width 0.088646)
		(layer "In11.Cu")
		(net "M_E_CPU0_ALERT_N")
	)
	(arc
		(start 383.842514 -257.664458)
		(mid 383.655062 -257.614222)
		(end 383.46761 -257.664458)
		(width 0.088646)
		(layer "In11.Cu")
		(net "M_E_CPU0_ALERT_N")
	)
	(arc
		(start 381.962914 -257.664712)
		(mid 381.775716 -257.614569)
		(end 381.588518 -257.664712)
		(width 0.088646)
		(layer "In11.Cu")
		(net "M_E_CPU0_ALERT_N")
	)
	(arc
		(start 374.44426 -257.664712)
		(mid 374.257062 -257.614569)
		(end 374.069864 -257.664712)
		(width 0.088646)
		(layer "In11.Cu")
		(net "M_E_CPU0_ALERT_N")
	)
	(arc
		(start 383.467864 -257.664712)
		(mid 383.185162 -257.740488)
		(end 382.90246 -257.664712)
		(width 0.088646)
		(layer "In11.Cu")
		(net "M_E_CPU0_ALERT_N")
	)
	(segment
		(start 97.183448 -255.825498)
		(end 97.183448 -256.361184)
		(width 0.20066)
		(layer "F.Cu")
		(net "M_D_CPU1_SB_RSP<1>")
	)
	(segment
		(start 15.684246 -243.216684)
		(end 16.789146 -243.216684)
		(width 0.20066)
		(layer "F.Cu")
		(net "M_D_CPU1_SB_RSP<1>")
	)
	(segment
		(start 97.183448 -256.361184)
		(end 97.183194 -256.361438)
		(width 0.20066)
		(layer "F.Cu")
		(net "M_D_CPU1_SB_RSP<1>")
	)
	(segment
		(start 23.563326 -255.559306)
		(end 23.380446 -255.742186)
		(width 0.18288)
		(layer "In6.Cu")
		(net "M_D_CPU1_SB_RSP<1>")
	)
	(segment
		(start 24.762206 -255.742186)
		(end 24.762206 -256.075942)
		(width 0.18288)
		(layer "In6.Cu")
		(net "M_D_CPU1_SB_RSP<1>")
	)
	(segment
		(start 81.132934 -255.343406)
		(end 81.11998 -255.338072)
		(width 0.18288)
		(layer "In6.Cu")
		(net "M_D_CPU1_SB_RSP<1>")
	)
	(segment
		(start 71.129398 -256.258822)
		(end 71.129144 -256.258568)
		(width 0.18288)
		(layer "In6.Cu")
		(net "M_D_CPU1_SB_RSP<1>")
	)
	(segment
		(start 92.211906 -255.865884)
		(end 92.201492 -255.87198)
		(width 0.088646)
		(layer "In6.Cu")
		(net "M_D_CPU1_SB_RSP<1>")
	)
	(segment
		(start 81.158842 -255.332738)
		(end 81.132934 -255.343406)
		(width 0.18288)
		(layer "In6.Cu")
		(net "M_D_CPU1_SB_RSP<1>")
	)
	(segment
		(start 66.475356 -256.258568)
		(end 66.475102 -256.258822)
		(width 0.18288)
		(layer "In6.Cu")
		(net "M_D_CPU1_SB_RSP<1>")
	)
	(segment
		(start 81.11998 -255.338072)
		(end 79.026004 -256.205228)
		(width 0.18288)
		(layer "In6.Cu")
		(net "M_D_CPU1_SB_RSP<1>")
	)
	(segment
		(start 21.815806 -256.258822)
		(end 21.01342 -256.258822)
		(width 0.18288)
		(layer "In6.Cu")
		(net "M_D_CPU1_SB_RSP<1>")
	)
	(segment
		(start 16.5989 -255.451102)
		(end 15.980664 -254.832866)
		(width 0.18288)
		(layer "In6.Cu")
		(net "M_D_CPU1_SB_RSP<1>")
	)
	(segment
		(start 89.39276 -255.865884)
		(end 89.382346 -255.87198)
		(width 0.088646)
		(layer "In6.Cu")
		(net "M_D_CPU1_SB_RSP<1>")
	)
	(segment
		(start 15.980664 -254.832866)
		(end 15.980664 -245.124986)
		(width 0.18288)
		(layer "In6.Cu")
		(net "M_D_CPU1_SB_RSP<1>")
	)
	(segment
		(start 79.026004 -256.205228)
		(end 78.929484 -256.24536)
		(width 0.18288)
		(layer "In6.Cu")
		(net "M_D_CPU1_SB_RSP<1>")
	)
	(segment
		(start 25.270206 -255.559306)
		(end 24.945086 -255.559306)
		(width 0.18288)
		(layer "In6.Cu")
		(net "M_D_CPU1_SB_RSP<1>")
	)
	(segment
		(start 24.945086 -255.559306)
		(end 24.762206 -255.742186)
		(width 0.18288)
		(layer "In6.Cu")
		(net "M_D_CPU1_SB_RSP<1>")
	)
	(segment
		(start 88.452706 -255.865884)
		(end 88.442292 -255.87198)
		(width 0.088646)
		(layer "In6.Cu")
		(net "M_D_CPU1_SB_RSP<1>")
	)
	(segment
		(start 23.888446 -255.559306)
		(end 23.563326 -255.559306)
		(width 0.18288)
		(layer "In6.Cu")
		(net "M_D_CPU1_SB_RSP<1>")
	)
	(segment
		(start 21.998686 -256.075942)
		(end 21.815806 -256.258822)
		(width 0.18288)
		(layer "In6.Cu")
		(net "M_D_CPU1_SB_RSP<1>")
	)
	(segment
		(start 97.183194 -256.361438)
		(end 96.551242 -255.890522)
		(width 0.088646)
		(layer "In6.Cu")
		(net "M_D_CPU1_SB_RSP<1>")
	)
	(segment
		(start 22.181566 -255.559306)
		(end 21.998686 -255.742186)
		(width 0.18288)
		(layer "In6.Cu")
		(net "M_D_CPU1_SB_RSP<1>")
	)
	(segment
		(start 78.896718 -256.258822)
		(end 71.129398 -256.258822)
		(width 0.18288)
		(layer "In6.Cu")
		(net "M_D_CPU1_SB_RSP<1>")
	)
	(segment
		(start 21.998686 -255.742186)
		(end 21.998686 -256.075942)
		(width 0.18288)
		(layer "In6.Cu")
		(net "M_D_CPU1_SB_RSP<1>")
	)
	(segment
		(start 24.071326 -256.075942)
		(end 24.071326 -255.742186)
		(width 0.18288)
		(layer "In6.Cu")
		(net "M_D_CPU1_SB_RSP<1>")
	)
	(segment
		(start 16.614902 -244.490748)
		(end 17.155668 -244.490748)
		(width 0.18288)
		(layer "In6.Cu")
		(net "M_D_CPU1_SB_RSP<1>")
	)
	(segment
		(start 84.025994 -255.796288)
		(end 83.88858 -255.796288)
		(width 0.088646)
		(layer "In6.Cu")
		(net "M_D_CPU1_SB_RSP<1>")
	)
	(segment
		(start 24.762206 -256.075942)
		(end 24.579326 -256.258822)
		(width 0.18288)
		(layer "In6.Cu")
		(net "M_D_CPU1_SB_RSP<1>")
	)
	(segment
		(start 25.453086 -256.075942)
		(end 25.453086 -255.742186)
		(width 0.18288)
		(layer "In6.Cu")
		(net "M_D_CPU1_SB_RSP<1>")
	)
	(segment
		(start 23.197566 -256.258822)
		(end 22.872446 -256.258822)
		(width 0.18288)
		(layer "In6.Cu")
		(net "M_D_CPU1_SB_RSP<1>")
	)
	(segment
		(start 71.129144 -256.258568)
		(end 66.475356 -256.258568)
		(width 0.18288)
		(layer "In6.Cu")
		(net "M_D_CPU1_SB_RSP<1>")
	)
	(segment
		(start 20.2057 -255.451102)
		(end 16.5989 -255.451102)
		(width 0.18288)
		(layer "In6.Cu")
		(net "M_D_CPU1_SB_RSP<1>")
	)
	(segment
		(start 25.453086 -255.742186)
		(end 25.270206 -255.559306)
		(width 0.18288)
		(layer "In6.Cu")
		(net "M_D_CPU1_SB_RSP<1>")
	)
	(segment
		(start 15.980664 -245.124986)
		(end 16.614902 -244.490748)
		(width 0.18288)
		(layer "In6.Cu")
		(net "M_D_CPU1_SB_RSP<1>")
	)
	(segment
		(start 24.579326 -256.258822)
		(end 24.254206 -256.258822)
		(width 0.18288)
		(layer "In6.Cu")
		(net "M_D_CPU1_SB_RSP<1>")
	)
	(segment
		(start 17.34439 -244.302026)
		(end 17.34439 -243.771928)
		(width 0.18288)
		(layer "In6.Cu")
		(net "M_D_CPU1_SB_RSP<1>")
	)
	(segment
		(start 23.380446 -256.075942)
		(end 23.197566 -256.258822)
		(width 0.18288)
		(layer "In6.Cu")
		(net "M_D_CPU1_SB_RSP<1>")
	)
	(segment
		(start 21.01342 -256.258822)
		(end 20.2057 -255.451102)
		(width 0.18288)
		(layer "In6.Cu")
		(net "M_D_CPU1_SB_RSP<1>")
	)
	(segment
		(start 17.34439 -243.771928)
		(end 16.789146 -243.216684)
		(width 0.18288)
		(layer "In6.Cu")
		(net "M_D_CPU1_SB_RSP<1>")
	)
	(segment
		(start 66.475102 -256.258822)
		(end 25.635966 -256.258822)
		(width 0.18288)
		(layer "In6.Cu")
		(net "M_D_CPU1_SB_RSP<1>")
	)
	(segment
		(start 22.506686 -255.559306)
		(end 22.181566 -255.559306)
		(width 0.18288)
		(layer "In6.Cu")
		(net "M_D_CPU1_SB_RSP<1>")
	)
	(segment
		(start 93.156278 -255.863344)
		(end 93.141546 -255.87198)
		(width 0.088646)
		(layer "In6.Cu")
		(net "M_D_CPU1_SB_RSP<1>")
	)
	(segment
		(start 25.635966 -256.258822)
		(end 25.453086 -256.075942)
		(width 0.18288)
		(layer "In6.Cu")
		(net "M_D_CPU1_SB_RSP<1>")
	)
	(segment
		(start 17.155668 -244.490748)
		(end 17.34439 -244.302026)
		(width 0.18288)
		(layer "In6.Cu")
		(net "M_D_CPU1_SB_RSP<1>")
	)
	(segment
		(start 95.035878 -255.863344)
		(end 95.021146 -255.87198)
		(width 0.088646)
		(layer "In6.Cu")
		(net "M_D_CPU1_SB_RSP<1>")
	)
	(segment
		(start 22.689566 -255.742186)
		(end 22.506686 -255.559306)
		(width 0.18288)
		(layer "In6.Cu")
		(net "M_D_CPU1_SB_RSP<1>")
	)
	(segment
		(start 22.872446 -256.258822)
		(end 22.689566 -256.075942)
		(width 0.18288)
		(layer "In6.Cu")
		(net "M_D_CPU1_SB_RSP<1>")
	)
	(segment
		(start 90.332306 -255.865884)
		(end 90.321892 -255.87198)
		(width 0.088646)
		(layer "In6.Cu")
		(net "M_D_CPU1_SB_RSP<1>")
	)
	(segment
		(start 22.689566 -256.075942)
		(end 22.689566 -255.742186)
		(width 0.18288)
		(layer "In6.Cu")
		(net "M_D_CPU1_SB_RSP<1>")
	)
	(segment
		(start 24.254206 -256.258822)
		(end 24.071326 -256.075942)
		(width 0.18288)
		(layer "In6.Cu")
		(net "M_D_CPU1_SB_RSP<1>")
	)
	(segment
		(start 23.380446 -255.742186)
		(end 23.380446 -256.075942)
		(width 0.18288)
		(layer "In6.Cu")
		(net "M_D_CPU1_SB_RSP<1>")
	)
	(segment
		(start 83.42503 -255.332738)
		(end 83.088734 -255.332738)
		(width 0.088646)
		(layer "In6.Cu")
		(net "M_D_CPU1_SB_RSP<1>")
	)
	(segment
		(start 91.27236 -255.865884)
		(end 91.261946 -255.87198)
		(width 0.088646)
		(layer "In6.Cu")
		(net "M_D_CPU1_SB_RSP<1>")
	)
	(segment
		(start 83.88858 -255.796288)
		(end 83.42503 -255.332738)
		(width 0.088646)
		(layer "In6.Cu")
		(net "M_D_CPU1_SB_RSP<1>")
	)
	(segment
		(start 24.071326 -255.742186)
		(end 23.888446 -255.559306)
		(width 0.18288)
		(layer "In6.Cu")
		(net "M_D_CPU1_SB_RSP<1>")
	)
	(segment
		(start 83.088734 -255.332738)
		(end 81.158842 -255.332738)
		(width 0.18288)
		(layer "In6.Cu")
		(net "M_D_CPU1_SB_RSP<1>")
	)
	(segment
		(start 95.975678 -255.863344)
		(end 95.960946 -255.87198)
		(width 0.088646)
		(layer "In6.Cu")
		(net "M_D_CPU1_SB_RSP<1>")
	)
	(segment
		(start 78.929484 -256.24536)
		(end 78.896718 -256.258822)
		(width 0.18288)
		(layer "In6.Cu")
		(net "M_D_CPU1_SB_RSP<1>")
	)
	(arc
		(start 89.00795 -255.87198)
		(mid 88.731137 -255.79611)
		(end 88.452706 -255.865884)
		(width 0.088646)
		(layer "In6.Cu")
		(net "M_D_CPU1_SB_RSP<1>")
	)
	(arc
		(start 93.141546 -255.87198)
		(mid 92.954348 -255.922123)
		(end 92.76715 -255.87198)
		(width 0.088646)
		(layer "In6.Cu")
		(net "M_D_CPU1_SB_RSP<1>")
	)
	(arc
		(start 91.827096 -255.87198)
		(mid 91.550537 -255.796237)
		(end 91.27236 -255.865884)
		(width 0.088646)
		(layer "In6.Cu")
		(net "M_D_CPU1_SB_RSP<1>")
	)
	(arc
		(start 92.76715 -255.87198)
		(mid 92.490337 -255.79611)
		(end 92.211906 -255.865884)
		(width 0.088646)
		(layer "In6.Cu")
		(net "M_D_CPU1_SB_RSP<1>")
	)
	(arc
		(start 90.88755 -255.87198)
		(mid 90.610737 -255.79611)
		(end 90.332306 -255.865884)
		(width 0.088646)
		(layer "In6.Cu")
		(net "M_D_CPU1_SB_RSP<1>")
	)
	(arc
		(start 84.683092 -255.87198)
		(mid 84.495894 -255.922123)
		(end 84.308696 -255.87198)
		(width 0.088646)
		(layer "In6.Cu")
		(net "M_D_CPU1_SB_RSP<1>")
	)
	(arc
		(start 85.622892 -255.87198)
		(mid 85.435694 -255.922123)
		(end 85.248496 -255.87198)
		(width 0.088646)
		(layer "In6.Cu")
		(net "M_D_CPU1_SB_RSP<1>")
	)
	(arc
		(start 96.551242 -255.890522)
		(mid 96.514128 -255.865812)
		(end 96.474534 -255.84531)
		(width 0.088646)
		(layer "In6.Cu")
		(net "M_D_CPU1_SB_RSP<1>")
	)
	(arc
		(start 88.442292 -255.87198)
		(mid 88.255094 -255.922123)
		(end 88.067896 -255.87198)
		(width 0.088646)
		(layer "In6.Cu")
		(net "M_D_CPU1_SB_RSP<1>")
	)
	(arc
		(start 87.502492 -255.87198)
		(mid 87.315294 -255.922123)
		(end 87.128096 -255.87198)
		(width 0.088646)
		(layer "In6.Cu")
		(net "M_D_CPU1_SB_RSP<1>")
	)
	(arc
		(start 95.960946 -255.87198)
		(mid 95.773748 -255.922123)
		(end 95.58655 -255.87198)
		(width 0.088646)
		(layer "In6.Cu")
		(net "M_D_CPU1_SB_RSP<1>")
	)
	(arc
		(start 86.562692 -255.87198)
		(mid 86.375494 -255.922123)
		(end 86.188296 -255.87198)
		(width 0.088646)
		(layer "In6.Cu")
		(net "M_D_CPU1_SB_RSP<1>")
	)
	(arc
		(start 89.382346 -255.87198)
		(mid 89.195148 -255.922123)
		(end 89.00795 -255.87198)
		(width 0.088646)
		(layer "In6.Cu")
		(net "M_D_CPU1_SB_RSP<1>")
	)
	(arc
		(start 89.947496 -255.87198)
		(mid 89.670937 -255.796237)
		(end 89.39276 -255.865884)
		(width 0.088646)
		(layer "In6.Cu")
		(net "M_D_CPU1_SB_RSP<1>")
	)
	(arc
		(start 91.261946 -255.87198)
		(mid 91.074748 -255.922123)
		(end 90.88755 -255.87198)
		(width 0.088646)
		(layer "In6.Cu")
		(net "M_D_CPU1_SB_RSP<1>")
	)
	(arc
		(start 88.067896 -255.87198)
		(mid 87.785194 -255.796204)
		(end 87.502492 -255.87198)
		(width 0.088646)
		(layer "In6.Cu")
		(net "M_D_CPU1_SB_RSP<1>")
	)
	(arc
		(start 93.70695 -255.87198)
		(mid 93.432751 -255.796145)
		(end 93.156278 -255.863344)
		(width 0.088646)
		(layer "In6.Cu")
		(net "M_D_CPU1_SB_RSP<1>")
	)
	(arc
		(start 92.201492 -255.87198)
		(mid 92.014294 -255.922123)
		(end 91.827096 -255.87198)
		(width 0.088646)
		(layer "In6.Cu")
		(net "M_D_CPU1_SB_RSP<1>")
	)
	(arc
		(start 94.081346 -255.87198)
		(mid 93.894148 -255.922123)
		(end 93.70695 -255.87198)
		(width 0.088646)
		(layer "In6.Cu")
		(net "M_D_CPU1_SB_RSP<1>")
	)
	(arc
		(start 87.128096 -255.87198)
		(mid 86.845394 -255.796204)
		(end 86.562692 -255.87198)
		(width 0.088646)
		(layer "In6.Cu")
		(net "M_D_CPU1_SB_RSP<1>")
	)
	(arc
		(start 84.308696 -255.87198)
		(mid 84.172327 -255.815538)
		(end 84.025994 -255.796288)
		(width 0.088646)
		(layer "In6.Cu")
		(net "M_D_CPU1_SB_RSP<1>")
	)
	(arc
		(start 95.021146 -255.87198)
		(mid 94.833948 -255.922123)
		(end 94.64675 -255.87198)
		(width 0.088646)
		(layer "In6.Cu")
		(net "M_D_CPU1_SB_RSP<1>")
	)
	(arc
		(start 95.58655 -255.87198)
		(mid 95.312351 -255.796145)
		(end 95.035878 -255.863344)
		(width 0.088646)
		(layer "In6.Cu")
		(net "M_D_CPU1_SB_RSP<1>")
	)
	(arc
		(start 85.248496 -255.87198)
		(mid 84.965794 -255.796204)
		(end 84.683092 -255.87198)
		(width 0.088646)
		(layer "In6.Cu")
		(net "M_D_CPU1_SB_RSP<1>")
	)
	(arc
		(start 96.474534 -255.84531)
		(mid 96.223003 -255.796285)
		(end 95.975678 -255.863344)
		(width 0.088646)
		(layer "In6.Cu")
		(net "M_D_CPU1_SB_RSP<1>")
	)
	(arc
		(start 90.321892 -255.87198)
		(mid 90.134694 -255.922123)
		(end 89.947496 -255.87198)
		(width 0.088646)
		(layer "In6.Cu")
		(net "M_D_CPU1_SB_RSP<1>")
	)
	(arc
		(start 94.64675 -255.87198)
		(mid 94.364048 -255.796204)
		(end 94.081346 -255.87198)
		(width 0.088646)
		(layer "In6.Cu")
		(net "M_D_CPU1_SB_RSP<1>")
	)
	(arc
		(start 86.188296 -255.87198)
		(mid 85.905594 -255.796204)
		(end 85.622892 -255.87198)
		(width 0.088646)
		(layer "In6.Cu")
		(net "M_D_CPU1_SB_RSP<1>")
	)
	(segment
		(start 96.713294 -256.639314)
		(end 96.713294 -257.175)
		(width 0.20066)
		(layer "F.Cu")
		(net "M_D_CPU1_SB_RSP<0>")
	)
	(segment
		(start 8.140446 -243.216684)
		(end 9.245346 -243.216684)
		(width 0.20066)
		(layer "F.Cu")
		(net "M_D_CPU1_SB_RSP<0>")
	)
	(segment
		(start 96.713294 -257.175)
		(end 96.713548 -257.175254)
		(width 0.20066)
		(layer "F.Cu")
		(net "M_D_CPU1_SB_RSP<0>")
	)
	(segment
		(start 80.952594 -256.33934)
		(end 78.575154 -257.324098)
		(width 0.18288)
		(layer "In6.Cu")
		(net "M_D_CPU1_SB_RSP<0>")
	)
	(segment
		(start 96.062292 -256.689352)
		(end 96.056196 -256.685796)
		(width 0.088646)
		(layer "In6.Cu")
		(net "M_D_CPU1_SB_RSP<0>")
	)
	(segment
		(start 94.17685 -256.685796)
		(end 94.166436 -256.6797)
		(width 0.088646)
		(layer "In6.Cu")
		(net "M_D_CPU1_SB_RSP<0>")
	)
	(segment
		(start 9.08558 -249.30608)
		(end 8.57758 -248.79808)
		(width 0.18288)
		(layer "In6.Cu")
		(net "M_D_CPU1_SB_RSP<0>")
	)
	(segment
		(start 9.417812 -245.340886)
		(end 10.089134 -244.669564)
		(width 0.18288)
		(layer "In6.Cu")
		(net "M_D_CPU1_SB_RSP<0>")
	)
	(segment
		(start 66.475102 -257.324098)
		(end 15.225776 -257.324098)
		(width 0.18288)
		(layer "In6.Cu")
		(net "M_D_CPU1_SB_RSP<0>")
	)
	(segment
		(start 96.713548 -257.175254)
		(end 96.400874 -257.175254)
		(width 0.088646)
		(layer "In6.Cu")
		(net "M_D_CPU1_SB_RSP<0>")
	)
	(segment
		(start 8.57758 -248.79808)
		(end 8.57758 -245.59768)
		(width 0.18288)
		(layer "In6.Cu")
		(net "M_D_CPU1_SB_RSP<0>")
	)
	(segment
		(start 10.089134 -244.060472)
		(end 9.245346 -243.216684)
		(width 0.18288)
		(layer "In6.Cu")
		(net "M_D_CPU1_SB_RSP<0>")
	)
	(segment
		(start 92.296996 -256.685796)
		(end 92.282264 -256.67716)
		(width 0.088646)
		(layer "In6.Cu")
		(net "M_D_CPU1_SB_RSP<0>")
	)
	(segment
		(start 71.129144 -257.323844)
		(end 66.475356 -257.323844)
		(width 0.18288)
		(layer "In6.Cu")
		(net "M_D_CPU1_SB_RSP<0>")
	)
	(segment
		(start 12.877038 -254.97536)
		(end 12.877038 -251.827538)
		(width 0.18288)
		(layer "In6.Cu")
		(net "M_D_CPU1_SB_RSP<0>")
	)
	(segment
		(start 83.088734 -256.33934)
		(end 80.952594 -256.33934)
		(width 0.18288)
		(layer "In6.Cu")
		(net "M_D_CPU1_SB_RSP<0>")
	)
	(segment
		(start 10.089134 -244.669564)
		(end 10.089134 -244.060472)
		(width 0.18288)
		(layer "In6.Cu")
		(net "M_D_CPU1_SB_RSP<0>")
	)
	(segment
		(start 78.575154 -257.324098)
		(end 71.129398 -257.324098)
		(width 0.18288)
		(layer "In6.Cu")
		(net "M_D_CPU1_SB_RSP<0>")
	)
	(segment
		(start 83.825842 -256.736342)
		(end 83.42884 -256.33934)
		(width 0.088646)
		(layer "In6.Cu")
		(net "M_D_CPU1_SB_RSP<0>")
	)
	(segment
		(start 8.834374 -245.340886)
		(end 9.417812 -245.340886)
		(width 0.18288)
		(layer "In6.Cu")
		(net "M_D_CPU1_SB_RSP<0>")
	)
	(segment
		(start 84.025994 -256.736342)
		(end 83.825842 -256.736342)
		(width 0.088646)
		(layer "In6.Cu")
		(net "M_D_CPU1_SB_RSP<0>")
	)
	(segment
		(start 71.129398 -257.324098)
		(end 71.129144 -257.323844)
		(width 0.18288)
		(layer "In6.Cu")
		(net "M_D_CPU1_SB_RSP<0>")
	)
	(segment
		(start 10.35558 -249.30608)
		(end 9.08558 -249.30608)
		(width 0.18288)
		(layer "In6.Cu")
		(net "M_D_CPU1_SB_RSP<0>")
	)
	(segment
		(start 96.056196 -256.685796)
		(end 96.041464 -256.67716)
		(width 0.088646)
		(layer "In6.Cu")
		(net "M_D_CPU1_SB_RSP<0>")
	)
	(segment
		(start 8.57758 -245.59768)
		(end 8.834374 -245.340886)
		(width 0.18288)
		(layer "In6.Cu")
		(net "M_D_CPU1_SB_RSP<0>")
	)
	(segment
		(start 96.400874 -257.175254)
		(end 96.335088 -257.109468)
		(width 0.088646)
		(layer "In6.Cu")
		(net "M_D_CPU1_SB_RSP<0>")
	)
	(segment
		(start 15.225776 -257.324098)
		(end 12.877038 -254.97536)
		(width 0.18288)
		(layer "In6.Cu")
		(net "M_D_CPU1_SB_RSP<0>")
	)
	(segment
		(start 95.116396 -256.685796)
		(end 95.105982 -256.6797)
		(width 0.088646)
		(layer "In6.Cu")
		(net "M_D_CPU1_SB_RSP<0>")
	)
	(segment
		(start 83.42884 -256.33934)
		(end 83.088734 -256.33934)
		(width 0.088646)
		(layer "In6.Cu")
		(net "M_D_CPU1_SB_RSP<0>")
	)
	(segment
		(start 12.877038 -251.827538)
		(end 10.35558 -249.30608)
		(width 0.18288)
		(layer "In6.Cu")
		(net "M_D_CPU1_SB_RSP<0>")
	)
	(segment
		(start 66.475356 -257.323844)
		(end 66.475102 -257.324098)
		(width 0.18288)
		(layer "In6.Cu")
		(net "M_D_CPU1_SB_RSP<0>")
	)
	(arc
		(start 92.671392 -256.685796)
		(mid 92.484194 -256.735939)
		(end 92.296996 -256.685796)
		(width 0.088646)
		(layer "In6.Cu")
		(net "M_D_CPU1_SB_RSP<0>")
	)
	(arc
		(start 91.731592 -256.685796)
		(mid 91.544394 -256.735939)
		(end 91.357196 -256.685796)
		(width 0.088646)
		(layer "In6.Cu")
		(net "M_D_CPU1_SB_RSP<0>")
	)
	(arc
		(start 88.537796 -256.685796)
		(mid 88.255094 -256.61002)
		(end 87.972392 -256.685796)
		(width 0.088646)
		(layer "In6.Cu")
		(net "M_D_CPU1_SB_RSP<0>")
	)
	(arc
		(start 89.851992 -256.685796)
		(mid 89.664794 -256.735939)
		(end 89.477596 -256.685796)
		(width 0.088646)
		(layer "In6.Cu")
		(net "M_D_CPU1_SB_RSP<0>")
	)
	(arc
		(start 95.490792 -256.685796)
		(mid 95.303594 -256.735939)
		(end 95.116396 -256.685796)
		(width 0.088646)
		(layer "In6.Cu")
		(net "M_D_CPU1_SB_RSP<0>")
	)
	(arc
		(start 87.032592 -256.685796)
		(mid 86.845394 -256.735939)
		(end 86.658196 -256.685796)
		(width 0.088646)
		(layer "In6.Cu")
		(net "M_D_CPU1_SB_RSP<0>")
	)
	(arc
		(start 89.477596 -256.685796)
		(mid 89.194894 -256.61002)
		(end 88.912192 -256.685796)
		(width 0.088646)
		(layer "In6.Cu")
		(net "M_D_CPU1_SB_RSP<0>")
	)
	(arc
		(start 88.912192 -256.685796)
		(mid 88.724994 -256.735939)
		(end 88.537796 -256.685796)
		(width 0.088646)
		(layer "In6.Cu")
		(net "M_D_CPU1_SB_RSP<0>")
	)
	(arc
		(start 96.335088 -257.109468)
		(mid 96.2478 -256.867512)
		(end 96.062292 -256.689352)
		(width 0.088646)
		(layer "In6.Cu")
		(net "M_D_CPU1_SB_RSP<0>")
	)
	(arc
		(start 87.597996 -256.685796)
		(mid 87.315294 -256.61002)
		(end 87.032592 -256.685796)
		(width 0.088646)
		(layer "In6.Cu")
		(net "M_D_CPU1_SB_RSP<0>")
	)
	(arc
		(start 91.357196 -256.685796)
		(mid 91.074494 -256.61002)
		(end 90.791792 -256.685796)
		(width 0.088646)
		(layer "In6.Cu")
		(net "M_D_CPU1_SB_RSP<0>")
	)
	(arc
		(start 92.282264 -256.67716)
		(mid 92.005789 -256.60984)
		(end 91.731592 -256.685796)
		(width 0.088646)
		(layer "In6.Cu")
		(net "M_D_CPU1_SB_RSP<0>")
	)
	(arc
		(start 95.105982 -256.6797)
		(mid 94.827804 -256.609977)
		(end 94.551246 -256.685796)
		(width 0.088646)
		(layer "In6.Cu")
		(net "M_D_CPU1_SB_RSP<0>")
	)
	(arc
		(start 87.972392 -256.685796)
		(mid 87.785194 -256.735939)
		(end 87.597996 -256.685796)
		(width 0.088646)
		(layer "In6.Cu")
		(net "M_D_CPU1_SB_RSP<0>")
	)
	(arc
		(start 96.041464 -256.67716)
		(mid 95.764989 -256.60984)
		(end 95.490792 -256.685796)
		(width 0.088646)
		(layer "In6.Cu")
		(net "M_D_CPU1_SB_RSP<0>")
	)
	(arc
		(start 86.092792 -256.685796)
		(mid 85.905594 -256.735939)
		(end 85.718396 -256.685796)
		(width 0.088646)
		(layer "In6.Cu")
		(net "M_D_CPU1_SB_RSP<0>")
	)
	(arc
		(start 90.791792 -256.685796)
		(mid 90.604594 -256.735939)
		(end 90.417396 -256.685796)
		(width 0.088646)
		(layer "In6.Cu")
		(net "M_D_CPU1_SB_RSP<0>")
	)
	(arc
		(start 93.611192 -256.685796)
		(mid 93.423994 -256.735939)
		(end 93.236796 -256.685796)
		(width 0.088646)
		(layer "In6.Cu")
		(net "M_D_CPU1_SB_RSP<0>")
	)
	(arc
		(start 84.778596 -256.685796)
		(mid 84.495894 -256.61002)
		(end 84.213192 -256.685796)
		(width 0.088646)
		(layer "In6.Cu")
		(net "M_D_CPU1_SB_RSP<0>")
	)
	(arc
		(start 85.718396 -256.685796)
		(mid 85.435694 -256.61002)
		(end 85.152992 -256.685796)
		(width 0.088646)
		(layer "In6.Cu")
		(net "M_D_CPU1_SB_RSP<0>")
	)
	(arc
		(start 90.417396 -256.685796)
		(mid 90.134694 -256.61002)
		(end 89.851992 -256.685796)
		(width 0.088646)
		(layer "In6.Cu")
		(net "M_D_CPU1_SB_RSP<0>")
	)
	(arc
		(start 84.213192 -256.685796)
		(mid 84.12292 -256.723395)
		(end 84.025994 -256.736342)
		(width 0.088646)
		(layer "In6.Cu")
		(net "M_D_CPU1_SB_RSP<0>")
	)
	(arc
		(start 94.551246 -256.685796)
		(mid 94.364048 -256.735939)
		(end 94.17685 -256.685796)
		(width 0.088646)
		(layer "In6.Cu")
		(net "M_D_CPU1_SB_RSP<0>")
	)
	(arc
		(start 85.152992 -256.685796)
		(mid 84.965794 -256.735939)
		(end 84.778596 -256.685796)
		(width 0.088646)
		(layer "In6.Cu")
		(net "M_D_CPU1_SB_RSP<0>")
	)
	(arc
		(start 86.658196 -256.685796)
		(mid 86.375494 -256.61002)
		(end 86.092792 -256.685796)
		(width 0.088646)
		(layer "In6.Cu")
		(net "M_D_CPU1_SB_RSP<0>")
	)
	(arc
		(start 93.236796 -256.685796)
		(mid 92.954094 -256.61002)
		(end 92.671392 -256.685796)
		(width 0.088646)
		(layer "In6.Cu")
		(net "M_D_CPU1_SB_RSP<0>")
	)
	(arc
		(start 94.166436 -256.6797)
		(mid 93.888004 -256.609854)
		(end 93.611192 -256.685796)
		(width 0.088646)
		(layer "In6.Cu")
		(net "M_D_CPU1_SB_RSP<0>")
	)
	(segment
		(start 18.102326 -246.61241)
		(end 18.314162 -246.824246)
		(width 0.20066)
		(layer "F.Cu")
		(net "M_D_CPU1_SB_PAR")
	)
	(segment
		(start 97.543112 -247.714262)
		(end 97.543112 -247.178576)
		(width 0.20066)
		(layer "F.Cu")
		(net "M_D_CPU1_SB_PAR")
	)
	(segment
		(start 14.812264 -247.04167)
		(end 16.885158 -247.04167)
		(width 0.1016)
		(layer "F.Cu")
		(net "M_D_CPU1_SB_PAR")
	)
	(segment
		(start 20.889214 -246.616728)
		(end 19.784314 -246.616728)
		(width 0.20066)
		(layer "F.Cu")
		(net "M_D_CPU1_SB_PAR")
	)
	(segment
		(start 12.240514 -246.616728)
		(end 13.937742 -246.616728)
		(width 0.20066)
		(layer "F.Cu")
		(net "M_D_CPU1_SB_PAR")
	)
	(segment
		(start 16.885158 -247.04167)
		(end 17.42948 -247.04167)
		(width 0.20066)
		(layer "F.Cu")
		(net "M_D_CPU1_SB_PAR")
	)
	(segment
		(start 14.574266 -247.04167)
		(end 14.812264 -247.04167)
		(width 0.101854)
		(layer "F.Cu")
		(net "M_D_CPU1_SB_PAR")
	)
	(segment
		(start 18.968212 -246.616728)
		(end 19.784314 -246.616728)
		(width 0.20066)
		(layer "F.Cu")
		(net "M_D_CPU1_SB_PAR")
	)
	(segment
		(start 13.937742 -246.616728)
		(end 14.063726 -246.742712)
		(width 0.20066)
		(layer "F.Cu")
		(net "M_D_CPU1_SB_PAR")
	)
	(segment
		(start 17.707102 -246.61241)
		(end 18.102326 -246.61241)
		(width 0.20066)
		(layer "F.Cu")
		(net "M_D_CPU1_SB_PAR")
	)
	(segment
		(start 14.20622 -247.055894)
		(end 14.560042 -247.055894)
		(width 0.20066)
		(layer "F.Cu")
		(net "M_D_CPU1_SB_PAR")
	)
	(segment
		(start 18.314162 -246.824246)
		(end 18.760694 -246.824246)
		(width 0.20066)
		(layer "F.Cu")
		(net "M_D_CPU1_SB_PAR")
	)
	(segment
		(start 17.578578 -246.892572)
		(end 17.578578 -246.740934)
		(width 0.20066)
		(layer "F.Cu")
		(net "M_D_CPU1_SB_PAR")
	)
	(segment
		(start 14.063726 -246.9134)
		(end 14.20622 -247.055894)
		(width 0.20066)
		(layer "F.Cu")
		(net "M_D_CPU1_SB_PAR")
	)
	(segment
		(start 17.578578 -246.740934)
		(end 17.707102 -246.61241)
		(width 0.20066)
		(layer "F.Cu")
		(net "M_D_CPU1_SB_PAR")
	)
	(segment
		(start 18.760694 -246.824246)
		(end 18.968212 -246.616728)
		(width 0.20066)
		(layer "F.Cu")
		(net "M_D_CPU1_SB_PAR")
	)
	(segment
		(start 14.560042 -247.055894)
		(end 14.574266 -247.04167)
		(width 0.101854)
		(layer "F.Cu")
		(net "M_D_CPU1_SB_PAR")
	)
	(segment
		(start 97.543112 -247.178576)
		(end 97.543366 -247.178322)
		(width 0.20066)
		(layer "F.Cu")
		(net "M_D_CPU1_SB_PAR")
	)
	(segment
		(start 14.063726 -246.742712)
		(end 14.063726 -246.9134)
		(width 0.20066)
		(layer "F.Cu")
		(net "M_D_CPU1_SB_PAR")
	)
	(segment
		(start 17.42948 -247.04167)
		(end 17.578578 -246.892572)
		(width 0.20066)
		(layer "F.Cu")
		(net "M_D_CPU1_SB_PAR")
	)
	(segment
		(start 94.925896 -247.494044)
		(end 94.718378 -247.61571)
		(width 0.088646)
		(layer "In11.Cu")
		(net "M_D_CPU1_SB_PAR")
	)
	(segment
		(start 54.85384 -247.888252)
		(end 50.553112 -247.888252)
		(width 0.18288)
		(layer "In11.Cu")
		(net "M_D_CPU1_SB_PAR")
	)
	(segment
		(start 94.718378 -247.61571)
		(end 94.30258 -247.61571)
		(width 0.088646)
		(layer "In11.Cu")
		(net "M_D_CPU1_SB_PAR")
	)
	(segment
		(start 27.493468 -247.401842)
		(end 27.178508 -247.401842)
		(width 0.18288)
		(layer "In11.Cu")
		(net "M_D_CPU1_SB_PAR")
	)
	(segment
		(start 64.496188 -245.20779)
		(end 64.355726 -245.20779)
		(width 0.18288)
		(layer "In11.Cu")
		(net "M_D_CPU1_SB_PAR")
	)
	(segment
		(start 83.912964 -247.517158)
		(end 83.673696 -247.517158)
		(width 0.088646)
		(layer "In11.Cu")
		(net "M_D_CPU1_SB_PAR")
	)
	(segment
		(start 26.985468 -247.842786)
		(end 26.792428 -248.035826)
		(width 0.18288)
		(layer "In11.Cu")
		(net "M_D_CPU1_SB_PAR")
	)
	(segment
		(start 65.390268 -245.40083)
		(end 65.390268 -245.730014)
		(width 0.18288)
		(layer "In11.Cu")
		(net "M_D_CPU1_SB_PAR")
	)
	(segment
		(start 27.879548 -248.035826)
		(end 27.686508 -247.842786)
		(width 0.18288)
		(layer "In11.Cu")
		(net "M_D_CPU1_SB_PAR")
	)
	(segment
		(start 60.136786 -247.078246)
		(end 59.034426 -247.078246)
		(width 0.18288)
		(layer "In11.Cu")
		(net "M_D_CPU1_SB_PAR")
	)
	(segment
		(start 26.792428 -248.035826)
		(end 24.694642 -248.035826)
		(width 0.18288)
		(layer "In11.Cu")
		(net "M_D_CPU1_SB_PAR")
	)
	(segment
		(start 74.448924 -246.963946)
		(end 74.102214 -247.310656)
		(width 0.18288)
		(layer "In11.Cu")
		(net "M_D_CPU1_SB_PAR")
	)
	(segment
		(start 91.632278 -247.673876)
		(end 91.621864 -247.66778)
		(width 0.088646)
		(layer "In11.Cu")
		(net "M_D_CPU1_SB_PAR")
	)
	(segment
		(start 37.435282 -247.888252)
		(end 35.58032 -247.888252)
		(width 0.18288)
		(layer "In11.Cu")
		(net "M_D_CPU1_SB_PAR")
	)
	(segment
		(start 22.81174 -247.588786)
		(end 22.6187 -247.781826)
		(width 0.18288)
		(layer "In11.Cu")
		(net "M_D_CPU1_SB_PAR")
	)
	(segment
		(start 40.505126 -247.63603)
		(end 39.085012 -247.63603)
		(width 0.18288)
		(layer "In11.Cu")
		(net "M_D_CPU1_SB_PAR")
	)
	(segment
		(start 63.520066 -245.203726)
		(end 62.605666 -246.118126)
		(width 0.18288)
		(layer "In11.Cu")
		(net "M_D_CPU1_SB_PAR")
	)
	(segment
		(start 96.416114 -247.50268)
		(end 96.4057 -247.496584)
		(width 0.088646)
		(layer "In11.Cu")
		(net "M_D_CPU1_SB_PAR")
	)
	(segment
		(start 40.988488 -248.119392)
		(end 40.505126 -247.63603)
		(width 0.18288)
		(layer "In11.Cu")
		(net "M_D_CPU1_SB_PAR")
	)
	(segment
		(start 60.36945 -246.845582)
		(end 60.136786 -247.078246)
		(width 0.18288)
		(layer "In11.Cu")
		(net "M_D_CPU1_SB_PAR")
	)
	(segment
		(start 37.90315 -248.35612)
		(end 37.435282 -247.888252)
		(width 0.18288)
		(layer "In11.Cu")
		(net "M_D_CPU1_SB_PAR")
	)
	(segment
		(start 42.626534 -247.926352)
		(end 42.626534 -247.551448)
		(width 0.18288)
		(layer "In11.Cu")
		(net "M_D_CPU1_SB_PAR")
	)
	(segment
		(start 29.151326 -248.035826)
		(end 27.879548 -248.035826)
		(width 0.18288)
		(layer "In11.Cu")
		(net "M_D_CPU1_SB_PAR")
	)
	(segment
		(start 38.705282 -248.35612)
		(end 37.90315 -248.35612)
		(width 0.18288)
		(layer "In11.Cu")
		(net "M_D_CPU1_SB_PAR")
	)
	(segment
		(start 38.891718 -247.829324)
		(end 38.891718 -248.169684)
		(width 0.18288)
		(layer "In11.Cu")
		(net "M_D_CPU1_SB_PAR")
	)
	(segment
		(start 84.386166 -247.743472)
		(end 84.139278 -247.743472)
		(width 0.088646)
		(layer "In11.Cu")
		(net "M_D_CPU1_SB_PAR")
	)
	(segment
		(start 80.35798 -246.963946)
		(end 74.448924 -246.963946)
		(width 0.18288)
		(layer "In11.Cu")
		(net "M_D_CPU1_SB_PAR")
	)
	(segment
		(start 94.066614 -247.66778)
		(end 94.051882 -247.676416)
		(width 0.088646)
		(layer "In11.Cu")
		(net "M_D_CPU1_SB_PAR")
	)
	(segment
		(start 41.925494 -247.551448)
		(end 41.925494 -247.926352)
		(width 0.18288)
		(layer "In11.Cu")
		(net "M_D_CPU1_SB_PAR")
	)
	(segment
		(start 49.293526 -248.010426)
		(end 48.231806 -248.010426)
		(width 0.18288)
		(layer "In11.Cu")
		(net "M_D_CPU1_SB_PAR")
	)
	(segment
		(start 31.437326 -247.756426)
		(end 29.430726 -247.756426)
		(width 0.18288)
		(layer "In11.Cu")
		(net "M_D_CPU1_SB_PAR")
	)
	(segment
		(start 39.085012 -247.63603)
		(end 38.891718 -247.829324)
		(width 0.18288)
		(layer "In11.Cu")
		(net "M_D_CPU1_SB_PAR")
	)
	(segment
		(start 97.543366 -247.178322)
		(end 96.94164 -247.442482)
		(width 0.088646)
		(layer "In11.Cu")
		(net "M_D_CPU1_SB_PAR")
	)
	(segment
		(start 61.242702 -246.10695)
		(end 60.916058 -246.242586)
		(width 0.18288)
		(layer "In11.Cu")
		(net "M_D_CPU1_SB_PAR")
	)
	(segment
		(start 33.95091 -248.036842)
		(end 33.476946 -248.036842)
		(width 0.18288)
		(layer "In11.Cu")
		(net "M_D_CPU1_SB_PAR")
	)
	(segment
		(start 93.126814 -247.66778)
		(end 93.112082 -247.676416)
		(width 0.088646)
		(layer "In11.Cu")
		(net "M_D_CPU1_SB_PAR")
	)
	(segment
		(start 24.440642 -247.781826)
		(end 23.70582 -247.781826)
		(width 0.18288)
		(layer "In11.Cu")
		(net "M_D_CPU1_SB_PAR")
	)
	(segment
		(start 64.882268 -245.923054)
		(end 64.689228 -245.730014)
		(width 0.18288)
		(layer "In11.Cu")
		(net "M_D_CPU1_SB_PAR")
	)
	(segment
		(start 23.51278 -247.195848)
		(end 23.31974 -247.002808)
		(width 0.18288)
		(layer "In11.Cu")
		(net "M_D_CPU1_SB_PAR")
	)
	(segment
		(start 23.51278 -247.588786)
		(end 23.51278 -247.195848)
		(width 0.18288)
		(layer "In11.Cu")
		(net "M_D_CPU1_SB_PAR")
	)
	(segment
		(start 80.911192 -247.517158)
		(end 80.35798 -246.963946)
		(width 0.18288)
		(layer "In11.Cu")
		(net "M_D_CPU1_SB_PAR")
	)
	(segment
		(start 74.102214 -247.310656)
		(end 68.318634 -247.310656)
		(width 0.18288)
		(layer "In11.Cu")
		(net "M_D_CPU1_SB_PAR")
	)
	(segment
		(start 64.689228 -245.730014)
		(end 64.689228 -245.40083)
		(width 0.18288)
		(layer "In11.Cu")
		(net "M_D_CPU1_SB_PAR")
	)
	(segment
		(start 49.7459 -247.558052)
		(end 49.293526 -248.010426)
		(width 0.18288)
		(layer "In11.Cu")
		(net "M_D_CPU1_SB_PAR")
	)
	(segment
		(start 58.920126 -246.963946)
		(end 55.778146 -246.963946)
		(width 0.18288)
		(layer "In11.Cu")
		(net "M_D_CPU1_SB_PAR")
	)
	(segment
		(start 89.367868 -247.66778)
		(end 89.357454 -247.673876)
		(width 0.088646)
		(layer "In11.Cu")
		(net "M_D_CPU1_SB_PAR")
	)
	(segment
		(start 91.247468 -247.66778)
		(end 91.237054 -247.673876)
		(width 0.088646)
		(layer "In11.Cu")
		(net "M_D_CPU1_SB_PAR")
	)
	(segment
		(start 22.81174 -247.195848)
		(end 22.81174 -247.588786)
		(width 0.18288)
		(layer "In11.Cu")
		(net "M_D_CPU1_SB_PAR")
	)
	(segment
		(start 84.139278 -247.743472)
		(end 83.912964 -247.517158)
		(width 0.088646)
		(layer "In11.Cu")
		(net "M_D_CPU1_SB_PAR")
	)
	(segment
		(start 55.778146 -246.963946)
		(end 54.85384 -247.888252)
		(width 0.18288)
		(layer "In11.Cu")
		(net "M_D_CPU1_SB_PAR")
	)
	(segment
		(start 35.270694 -247.578626)
		(end 34.409126 -247.578626)
		(width 0.18288)
		(layer "In11.Cu")
		(net "M_D_CPU1_SB_PAR")
	)
	(segment
		(start 33.476946 -248.036842)
		(end 33.33115 -247.891046)
		(width 0.18288)
		(layer "In11.Cu")
		(net "M_D_CPU1_SB_PAR")
	)
	(segment
		(start 60.916058 -246.242586)
		(end 60.728098 -246.696738)
		(width 0.18288)
		(layer "In11.Cu")
		(net "M_D_CPU1_SB_PAR")
	)
	(segment
		(start 61.697108 -246.295672)
		(end 61.242702 -246.10695)
		(width 0.18288)
		(layer "In11.Cu")
		(net "M_D_CPU1_SB_PAR")
	)
	(segment
		(start 31.571946 -247.891046)
		(end 31.437326 -247.756426)
		(width 0.18288)
		(layer "In11.Cu")
		(net "M_D_CPU1_SB_PAR")
	)
	(segment
		(start 62.125606 -246.118126)
		(end 61.697108 -246.295672)
		(width 0.18288)
		(layer "In11.Cu")
		(net "M_D_CPU1_SB_PAR")
	)
	(segment
		(start 48.231806 -248.010426)
		(end 48.112426 -247.891046)
		(width 0.18288)
		(layer "In11.Cu")
		(net "M_D_CPU1_SB_PAR")
	)
	(segment
		(start 88.427814 -247.66778)
		(end 88.4174 -247.673876)
		(width 0.088646)
		(layer "In11.Cu")
		(net "M_D_CPU1_SB_PAR")
	)
	(segment
		(start 38.891718 -248.169684)
		(end 38.705282 -248.35612)
		(width 0.18288)
		(layer "In11.Cu")
		(net "M_D_CPU1_SB_PAR")
	)
	(segment
		(start 46.684946 -247.891046)
		(end 46.474126 -247.680226)
		(width 0.18288)
		(layer "In11.Cu")
		(net "M_D_CPU1_SB_PAR")
	)
	(segment
		(start 44.616878 -247.680226)
		(end 44.177712 -248.119392)
		(width 0.18288)
		(layer "In11.Cu")
		(net "M_D_CPU1_SB_PAR")
	)
	(segment
		(start 48.112426 -247.891046)
		(end 46.684946 -247.891046)
		(width 0.18288)
		(layer "In11.Cu")
		(net "M_D_CPU1_SB_PAR")
	)
	(segment
		(start 64.351662 -245.203726)
		(end 63.520066 -245.203726)
		(width 0.18288)
		(layer "In11.Cu")
		(net "M_D_CPU1_SB_PAR")
	)
	(segment
		(start 65.197228 -245.923054)
		(end 64.882268 -245.923054)
		(width 0.18288)
		(layer "In11.Cu")
		(net "M_D_CPU1_SB_PAR")
	)
	(segment
		(start 64.689228 -245.40083)
		(end 64.496188 -245.20779)
		(width 0.18288)
		(layer "In11.Cu")
		(net "M_D_CPU1_SB_PAR")
	)
	(segment
		(start 33.33115 -247.891046)
		(end 31.571946 -247.891046)
		(width 0.18288)
		(layer "In11.Cu")
		(net "M_D_CPU1_SB_PAR")
	)
	(segment
		(start 64.355726 -245.20779)
		(end 64.351662 -245.203726)
		(width 0.18288)
		(layer "In11.Cu")
		(net "M_D_CPU1_SB_PAR")
	)
	(segment
		(start 34.409126 -247.578626)
		(end 33.95091 -248.036842)
		(width 0.18288)
		(layer "In11.Cu")
		(net "M_D_CPU1_SB_PAR")
	)
	(segment
		(start 42.819574 -248.119392)
		(end 42.626534 -247.926352)
		(width 0.18288)
		(layer "In11.Cu")
		(net "M_D_CPU1_SB_PAR")
	)
	(segment
		(start 22.6187 -247.781826)
		(end 22.054312 -247.781826)
		(width 0.18288)
		(layer "In11.Cu")
		(net "M_D_CPU1_SB_PAR")
	)
	(segment
		(start 44.177712 -248.119392)
		(end 42.819574 -248.119392)
		(width 0.18288)
		(layer "In11.Cu")
		(net "M_D_CPU1_SB_PAR")
	)
	(segment
		(start 89.752678 -247.673876)
		(end 89.742264 -247.66778)
		(width 0.088646)
		(layer "In11.Cu")
		(net "M_D_CPU1_SB_PAR")
	)
	(segment
		(start 35.58032 -247.888252)
		(end 35.270694 -247.578626)
		(width 0.18288)
		(layer "In11.Cu")
		(net "M_D_CPU1_SB_PAR")
	)
	(segment
		(start 65.583308 -245.20779)
		(end 65.390268 -245.40083)
		(width 0.18288)
		(layer "In11.Cu")
		(net "M_D_CPU1_SB_PAR")
	)
	(segment
		(start 23.70582 -247.781826)
		(end 23.51278 -247.588786)
		(width 0.18288)
		(layer "In11.Cu")
		(net "M_D_CPU1_SB_PAR")
	)
	(segment
		(start 23.00478 -247.002808)
		(end 22.81174 -247.195848)
		(width 0.18288)
		(layer "In11.Cu")
		(net "M_D_CPU1_SB_PAR")
	)
	(segment
		(start 41.732454 -248.119392)
		(end 40.988488 -248.119392)
		(width 0.18288)
		(layer "In11.Cu")
		(net "M_D_CPU1_SB_PAR")
	)
	(segment
		(start 94.30258 -247.61571)
		(end 94.239334 -247.617996)
		(width 0.088646)
		(layer "In11.Cu")
		(net "M_D_CPU1_SB_PAR")
	)
	(segment
		(start 26.985468 -247.594882)
		(end 26.985468 -247.842786)
		(width 0.18288)
		(layer "In11.Cu")
		(net "M_D_CPU1_SB_PAR")
	)
	(segment
		(start 59.034426 -247.078246)
		(end 58.920126 -246.963946)
		(width 0.18288)
		(layer "In11.Cu")
		(net "M_D_CPU1_SB_PAR")
	)
	(segment
		(start 41.925494 -247.926352)
		(end 41.732454 -248.119392)
		(width 0.18288)
		(layer "In11.Cu")
		(net "M_D_CPU1_SB_PAR")
	)
	(segment
		(start 27.686508 -247.842786)
		(end 27.686508 -247.594882)
		(width 0.18288)
		(layer "In11.Cu")
		(net "M_D_CPU1_SB_PAR")
	)
	(segment
		(start 65.390268 -245.730014)
		(end 65.197228 -245.923054)
		(width 0.18288)
		(layer "In11.Cu")
		(net "M_D_CPU1_SB_PAR")
	)
	(segment
		(start 62.605666 -246.118126)
		(end 62.125606 -246.118126)
		(width 0.18288)
		(layer "In11.Cu")
		(net "M_D_CPU1_SB_PAR")
	)
	(segment
		(start 27.686508 -247.594882)
		(end 27.493468 -247.401842)
		(width 0.18288)
		(layer "In11.Cu")
		(net "M_D_CPU1_SB_PAR")
	)
	(segment
		(start 24.694642 -248.035826)
		(end 24.440642 -247.781826)
		(width 0.18288)
		(layer "In11.Cu")
		(net "M_D_CPU1_SB_PAR")
	)
	(segment
		(start 42.626534 -247.551448)
		(end 42.433494 -247.358408)
		(width 0.18288)
		(layer "In11.Cu")
		(net "M_D_CPU1_SB_PAR")
	)
	(segment
		(start 27.178508 -247.401842)
		(end 26.985468 -247.594882)
		(width 0.18288)
		(layer "In11.Cu")
		(net "M_D_CPU1_SB_PAR")
	)
	(segment
		(start 60.728098 -246.696738)
		(end 60.36945 -246.845582)
		(width 0.18288)
		(layer "In11.Cu")
		(net "M_D_CPU1_SB_PAR")
	)
	(segment
		(start 66.215768 -245.20779)
		(end 65.583308 -245.20779)
		(width 0.18288)
		(layer "In11.Cu")
		(net "M_D_CPU1_SB_PAR")
	)
	(segment
		(start 42.118534 -247.358408)
		(end 41.925494 -247.551448)
		(width 0.18288)
		(layer "In11.Cu")
		(net "M_D_CPU1_SB_PAR")
	)
	(segment
		(start 42.433494 -247.358408)
		(end 42.118534 -247.358408)
		(width 0.18288)
		(layer "In11.Cu")
		(net "M_D_CPU1_SB_PAR")
	)
	(segment
		(start 83.673696 -247.517158)
		(end 80.911192 -247.517158)
		(width 0.18288)
		(layer "In11.Cu")
		(net "M_D_CPU1_SB_PAR")
	)
	(segment
		(start 23.31974 -247.002808)
		(end 23.00478 -247.002808)
		(width 0.18288)
		(layer "In11.Cu")
		(net "M_D_CPU1_SB_PAR")
	)
	(segment
		(start 29.430726 -247.756426)
		(end 29.151326 -248.035826)
		(width 0.18288)
		(layer "In11.Cu")
		(net "M_D_CPU1_SB_PAR")
	)
	(segment
		(start 50.553112 -247.888252)
		(end 50.222912 -247.558052)
		(width 0.18288)
		(layer "In11.Cu")
		(net "M_D_CPU1_SB_PAR")
	)
	(segment
		(start 50.222912 -247.558052)
		(end 49.7459 -247.558052)
		(width 0.18288)
		(layer "In11.Cu")
		(net "M_D_CPU1_SB_PAR")
	)
	(segment
		(start 96.790764 -247.50268)
		(end 96.79051 -247.50268)
		(width 0.088646)
		(layer "In11.Cu")
		(net "M_D_CPU1_SB_PAR")
	)
	(segment
		(start 46.474126 -247.680226)
		(end 44.616878 -247.680226)
		(width 0.18288)
		(layer "In11.Cu")
		(net "M_D_CPU1_SB_PAR")
	)
	(segment
		(start 68.318634 -247.310656)
		(end 66.215768 -245.20779)
		(width 0.18288)
		(layer "In11.Cu")
		(net "M_D_CPU1_SB_PAR")
	)
	(segment
		(start 22.054312 -247.781826)
		(end 20.889214 -246.616728)
		(width 0.18288)
		(layer "In11.Cu")
		(net "M_D_CPU1_SB_PAR")
	)
	(arc
		(start 92.56141 -247.66778)
		(mid 92.374212 -247.617637)
		(end 92.187014 -247.66778)
		(width 0.088646)
		(layer "In11.Cu")
		(net "M_D_CPU1_SB_PAR")
	)
	(arc
		(start 85.043264 -247.66778)
		(mid 84.856066 -247.617637)
		(end 84.668868 -247.66778)
		(width 0.088646)
		(layer "In11.Cu")
		(net "M_D_CPU1_SB_PAR")
	)
	(arc
		(start 86.548468 -247.66778)
		(mid 86.265766 -247.743556)
		(end 85.983064 -247.66778)
		(width 0.088646)
		(layer "In11.Cu")
		(net "M_D_CPU1_SB_PAR")
	)
	(arc
		(start 93.50121 -247.66778)
		(mid 93.314012 -247.617637)
		(end 93.126814 -247.66778)
		(width 0.088646)
		(layer "In11.Cu")
		(net "M_D_CPU1_SB_PAR")
	)
	(arc
		(start 89.357454 -247.673876)
		(mid 89.079022 -247.743722)
		(end 88.80221 -247.66778)
		(width 0.088646)
		(layer "In11.Cu")
		(net "M_D_CPU1_SB_PAR")
	)
	(arc
		(start 91.237054 -247.673876)
		(mid 90.958622 -247.743722)
		(end 90.68181 -247.66778)
		(width 0.088646)
		(layer "In11.Cu")
		(net "M_D_CPU1_SB_PAR")
	)
	(arc
		(start 90.68181 -247.66778)
		(mid 90.494612 -247.617637)
		(end 90.307414 -247.66778)
		(width 0.088646)
		(layer "In11.Cu")
		(net "M_D_CPU1_SB_PAR")
	)
	(arc
		(start 96.94164 -247.442482)
		(mid 96.864026 -247.467129)
		(end 96.790764 -247.50268)
		(width 0.088646)
		(layer "In11.Cu")
		(net "M_D_CPU1_SB_PAR")
	)
	(arc
		(start 86.922864 -247.66778)
		(mid 86.735666 -247.617637)
		(end 86.548468 -247.66778)
		(width 0.088646)
		(layer "In11.Cu")
		(net "M_D_CPU1_SB_PAR")
	)
	(arc
		(start 88.4174 -247.673876)
		(mid 88.139222 -247.743599)
		(end 87.862664 -247.66778)
		(width 0.088646)
		(layer "In11.Cu")
		(net "M_D_CPU1_SB_PAR")
	)
	(arc
		(start 96.79051 -247.50268)
		(mid 96.603312 -247.552823)
		(end 96.416114 -247.50268)
		(width 0.088646)
		(layer "In11.Cu")
		(net "M_D_CPU1_SB_PAR")
	)
	(arc
		(start 87.862664 -247.66778)
		(mid 87.675466 -247.617637)
		(end 87.488268 -247.66778)
		(width 0.088646)
		(layer "In11.Cu")
		(net "M_D_CPU1_SB_PAR")
	)
	(arc
		(start 88.80221 -247.66778)
		(mid 88.615012 -247.617637)
		(end 88.427814 -247.66778)
		(width 0.088646)
		(layer "In11.Cu")
		(net "M_D_CPU1_SB_PAR")
	)
	(arc
		(start 89.742264 -247.66778)
		(mid 89.555066 -247.617637)
		(end 89.367868 -247.66778)
		(width 0.088646)
		(layer "In11.Cu")
		(net "M_D_CPU1_SB_PAR")
	)
	(arc
		(start 85.983064 -247.66778)
		(mid 85.795866 -247.617637)
		(end 85.608668 -247.66778)
		(width 0.088646)
		(layer "In11.Cu")
		(net "M_D_CPU1_SB_PAR")
	)
	(arc
		(start 87.488268 -247.66778)
		(mid 87.205566 -247.743556)
		(end 86.922864 -247.66778)
		(width 0.088646)
		(layer "In11.Cu")
		(net "M_D_CPU1_SB_PAR")
	)
	(arc
		(start 90.307414 -247.66778)
		(mid 90.030855 -247.743523)
		(end 89.752678 -247.673876)
		(width 0.088646)
		(layer "In11.Cu")
		(net "M_D_CPU1_SB_PAR")
	)
	(arc
		(start 85.608668 -247.66778)
		(mid 85.325966 -247.743556)
		(end 85.043264 -247.66778)
		(width 0.088646)
		(layer "In11.Cu")
		(net "M_D_CPU1_SB_PAR")
	)
	(arc
		(start 94.051882 -247.676416)
		(mid 93.775407 -247.743736)
		(end 93.50121 -247.66778)
		(width 0.088646)
		(layer "In11.Cu")
		(net "M_D_CPU1_SB_PAR")
	)
	(arc
		(start 95.476568 -247.50268)
		(mid 95.202369 -247.426845)
		(end 94.925896 -247.494044)
		(width 0.088646)
		(layer "In11.Cu")
		(net "M_D_CPU1_SB_PAR")
	)
	(arc
		(start 92.187014 -247.66778)
		(mid 91.910455 -247.743523)
		(end 91.632278 -247.673876)
		(width 0.088646)
		(layer "In11.Cu")
		(net "M_D_CPU1_SB_PAR")
	)
	(arc
		(start 84.668868 -247.66778)
		(mid 84.532499 -247.724222)
		(end 84.386166 -247.743472)
		(width 0.088646)
		(layer "In11.Cu")
		(net "M_D_CPU1_SB_PAR")
	)
	(arc
		(start 93.112082 -247.676416)
		(mid 92.835607 -247.743736)
		(end 92.56141 -247.66778)
		(width 0.088646)
		(layer "In11.Cu")
		(net "M_D_CPU1_SB_PAR")
	)
	(arc
		(start 96.4057 -247.496584)
		(mid 96.127522 -247.426861)
		(end 95.850964 -247.50268)
		(width 0.088646)
		(layer "In11.Cu")
		(net "M_D_CPU1_SB_PAR")
	)
	(arc
		(start 94.239334 -247.617996)
		(mid 94.149934 -247.632351)
		(end 94.066614 -247.66778)
		(width 0.088646)
		(layer "In11.Cu")
		(net "M_D_CPU1_SB_PAR")
	)
	(arc
		(start 95.850964 -247.50268)
		(mid 95.663766 -247.552823)
		(end 95.476568 -247.50268)
		(width 0.088646)
		(layer "In11.Cu")
		(net "M_D_CPU1_SB_PAR")
	)
	(arc
		(start 91.621864 -247.66778)
		(mid 91.434666 -247.617637)
		(end 91.247468 -247.66778)
		(width 0.088646)
		(layer "In11.Cu")
		(net "M_D_CPU1_SB_PAR")
	)
	(segment
		(start 14.874494 -237.855506)
		(end 14.605762 -237.855506)
		(width 0.20066)
		(layer "F.Cu")
		(net "M_D_CPU1_SB_DQS_DP<9>")
	)
	(segment
		(start 11.11631 -238.551212)
		(end 10.898124 -238.551212)
		(width 0.20066)
		(layer "F.Cu")
		(net "M_D_CPU1_SB_DQS_DP<9>")
	)
	(segment
		(start 13.854684 -238.280702)
		(end 13.593572 -238.541814)
		(width 0.20066)
		(layer "F.Cu")
		(net "M_D_CPU1_SB_DQS_DP<9>")
	)
	(segment
		(start 16.789146 -238.116618)
		(end 15.684246 -238.116618)
		(width 0.20066)
		(layer "F.Cu")
		(net "M_D_CPU1_SB_DQS_DP<9>")
	)
	(segment
		(start 14.605762 -237.855506)
		(end 14.180566 -238.280702)
		(width 0.20066)
		(layer "F.Cu")
		(net "M_D_CPU1_SB_DQS_DP<9>")
	)
	(segment
		(start 15.135606 -238.116618)
		(end 14.874494 -237.855506)
		(width 0.20066)
		(layer "F.Cu")
		(net "M_D_CPU1_SB_DQS_DP<9>")
	)
	(segment
		(start 11.36269 -238.541814)
		(end 11.125708 -238.541814)
		(width 0.101854)
		(layer "F.Cu")
		(net "M_D_CPU1_SB_DQS_DP<9>")
	)
	(segment
		(start 10.898124 -238.551212)
		(end 10.627614 -238.280702)
		(width 0.20066)
		(layer "F.Cu")
		(net "M_D_CPU1_SB_DQS_DP<9>")
	)
	(segment
		(start 14.180566 -238.280702)
		(end 13.854684 -238.280702)
		(width 0.20066)
		(layer "F.Cu")
		(net "M_D_CPU1_SB_DQS_DP<9>")
	)
	(segment
		(start 13.118084 -238.541814)
		(end 11.36269 -238.541814)
		(width 0.1016)
		(layer "F.Cu")
		(net "M_D_CPU1_SB_DQS_DP<9>")
	)
	(segment
		(start 15.684246 -238.116618)
		(end 15.135606 -238.116618)
		(width 0.20066)
		(layer "F.Cu")
		(net "M_D_CPU1_SB_DQS_DP<9>")
	)
	(segment
		(start 9.364472 -237.855506)
		(end 8.93953 -237.855506)
		(width 0.20066)
		(layer "F.Cu")
		(net "M_D_CPU1_SB_DQS_DP<9>")
	)
	(segment
		(start 8.678418 -238.116618)
		(end 8.140446 -238.116618)
		(width 0.20066)
		(layer "F.Cu")
		(net "M_D_CPU1_SB_DQS_DP<9>")
	)
	(segment
		(start 98.952812 -245.272306)
		(end 98.952812 -244.73662)
		(width 0.20066)
		(layer "F.Cu")
		(net "M_D_CPU1_SB_DQS_DP<9>")
	)
	(segment
		(start 10.627614 -238.280702)
		(end 10.000488 -238.280702)
		(width 0.20066)
		(layer "F.Cu")
		(net "M_D_CPU1_SB_DQS_DP<9>")
	)
	(segment
		(start 10.000488 -238.280702)
		(end 9.364472 -237.855506)
		(width 0.20066)
		(layer "F.Cu")
		(net "M_D_CPU1_SB_DQS_DP<9>")
	)
	(segment
		(start 11.125708 -238.541814)
		(end 11.11631 -238.551212)
		(width 0.101854)
		(layer "F.Cu")
		(net "M_D_CPU1_SB_DQS_DP<9>")
	)
	(segment
		(start 13.593572 -238.541814)
		(end 13.441426 -238.541814)
		(width 0.20066)
		(layer "F.Cu")
		(net "M_D_CPU1_SB_DQS_DP<9>")
	)
	(segment
		(start 98.953066 -245.27256)
		(end 98.952812 -245.272306)
		(width 0.20066)
		(layer "F.Cu")
		(net "M_D_CPU1_SB_DQS_DP<9>")
	)
	(segment
		(start 8.93953 -237.855506)
		(end 8.678418 -238.116618)
		(width 0.20066)
		(layer "F.Cu")
		(net "M_D_CPU1_SB_DQS_DP<9>")
	)
	(segment
		(start 13.441426 -238.541814)
		(end 13.118084 -238.541814)
		(width 0.101854)
		(layer "F.Cu")
		(net "M_D_CPU1_SB_DQS_DP<9>")
	)
	(segment
		(start 33.415224 -239.114076)
		(end 32.406844 -239.114076)
		(width 0.18288)
		(layer "In11.Cu")
		(net "M_D_CPU1_SB_DQS_DP<9>")
	)
	(segment
		(start 87.407496 -245.234968)
		(end 87.392764 -245.226332)
		(width 0.088646)
		(layer "In11.Cu")
		(net "M_D_CPU1_SB_DQS_DP<9>")
	)
	(segment
		(start 97.982786 -245.11)
		(end 97.925636 -245.103142)
		(width 0.088646)
		(layer "In11.Cu")
		(net "M_D_CPU1_SB_DQS_DP<9>")
	)
	(segment
		(start 32.406844 -239.114076)
		(end 32.127952 -239.392968)
		(width 0.18288)
		(layer "In11.Cu")
		(net "M_D_CPU1_SB_DQS_DP<9>")
	)
	(segment
		(start 86.467696 -245.234968)
		(end 86.452964 -245.226332)
		(width 0.088646)
		(layer "In11.Cu")
		(net "M_D_CPU1_SB_DQS_DP<9>")
	)
	(segment
		(start 51.266344 -238.542068)
		(end 50.87239 -238.542068)
		(width 0.18288)
		(layer "In11.Cu")
		(net "M_D_CPU1_SB_DQS_DP<9>")
	)
	(segment
		(start 66.40322 -238.874554)
		(end 65.602866 -238.874554)
		(width 0.18288)
		(layer "In11.Cu")
		(net "M_D_CPU1_SB_DQS_DP<9>")
	)
	(segment
		(start 97.925636 -245.103142)
		(end 97.92081 -245.105682)
		(width 0.088646)
		(layer "In11.Cu")
		(net "M_D_CPU1_SB_DQS_DP<9>")
	)
	(segment
		(start 31.674054 -239.392968)
		(end 31.414212 -239.133126)
		(width 0.18288)
		(layer "In11.Cu")
		(net "M_D_CPU1_SB_DQS_DP<9>")
	)
	(segment
		(start 64.817498 -238.089186)
		(end 63.679832 -237.616746)
		(width 0.18288)
		(layer "In11.Cu")
		(net "M_D_CPU1_SB_DQS_DP<9>")
	)
	(segment
		(start 52.230274 -238.267748)
		(end 51.540664 -238.267748)
		(width 0.18288)
		(layer "In11.Cu")
		(net "M_D_CPU1_SB_DQS_DP<9>")
	)
	(segment
		(start 17.906746 -237.6297)
		(end 17.422114 -237.83036)
		(width 0.18288)
		(layer "In11.Cu")
		(net "M_D_CPU1_SB_DQS_DP<9>")
	)
	(segment
		(start 31.37281 -239.10798)
		(end 31.038292 -239.10798)
		(width 0.18288)
		(layer "In11.Cu")
		(net "M_D_CPU1_SB_DQS_DP<9>")
	)
	(segment
		(start 45.931074 -239.106202)
		(end 44.92371 -238.098838)
		(width 0.18288)
		(layer "In11.Cu")
		(net "M_D_CPU1_SB_DQS_DP<9>")
	)
	(segment
		(start 50.56251 -238.232188)
		(end 50.240692 -238.232188)
		(width 0.18288)
		(layer "In11.Cu")
		(net "M_D_CPU1_SB_DQS_DP<9>")
	)
	(segment
		(start 24.40432 -238.262668)
		(end 21.410422 -238.262668)
		(width 0.18288)
		(layer "In11.Cu")
		(net "M_D_CPU1_SB_DQS_DP<9>")
	)
	(segment
		(start 85.527896 -245.234968)
		(end 85.513164 -245.226332)
		(width 0.088646)
		(layer "In11.Cu")
		(net "M_D_CPU1_SB_DQS_DP<9>")
	)
	(segment
		(start 96.79051 -245.226078)
		(end 96.790764 -245.226332)
		(width 0.088646)
		(layer "In11.Cu")
		(net "M_D_CPU1_SB_DQS_DP<9>")
	)
	(segment
		(start 20.4216 -238.267748)
		(end 19.914616 -238.267748)
		(width 0.18288)
		(layer "In11.Cu")
		(net "M_D_CPU1_SB_DQS_DP<9>")
	)
	(segment
		(start 63.679832 -237.616746)
		(end 53.802026 -237.616746)
		(width 0.18288)
		(layer "In11.Cu")
		(net "M_D_CPU1_SB_DQS_DP<9>")
	)
	(segment
		(start 93.986096 -245.234968)
		(end 93.971364 -245.226332)
		(width 0.088646)
		(layer "In11.Cu")
		(net "M_D_CPU1_SB_DQS_DP<9>")
	)
	(segment
		(start 35.176206 -238.279178)
		(end 34.995866 -238.459772)
		(width 0.18288)
		(layer "In11.Cu")
		(net "M_D_CPU1_SB_DQS_DP<9>")
	)
	(segment
		(start 51.540664 -238.267748)
		(end 51.266344 -238.542068)
		(width 0.18288)
		(layer "In11.Cu")
		(net "M_D_CPU1_SB_DQS_DP<9>")
	)
	(segment
		(start 85.230462 -244.750844)
		(end 85.230462 -244.73662)
		(width 0.088646)
		(layer "In11.Cu")
		(net "M_D_CPU1_SB_DQS_DP<9>")
	)
	(segment
		(start 67.017392 -239.128554)
		(end 66.40322 -238.874554)
		(width 0.18288)
		(layer "In11.Cu")
		(net "M_D_CPU1_SB_DQS_DP<9>")
	)
	(segment
		(start 50.240692 -238.232188)
		(end 49.683924 -238.463074)
		(width 0.18288)
		(layer "In11.Cu")
		(net "M_D_CPU1_SB_DQS_DP<9>")
	)
	(segment
		(start 21.410422 -238.262668)
		(end 21.131784 -238.541306)
		(width 0.18288)
		(layer "In11.Cu")
		(net "M_D_CPU1_SB_DQS_DP<9>")
	)
	(segment
		(start 49.421288 -238.725456)
		(end 48.484536 -239.113822)
		(width 0.18288)
		(layer "In11.Cu")
		(net "M_D_CPU1_SB_DQS_DP<9>")
	)
	(segment
		(start 94.925896 -245.234968)
		(end 94.911164 -245.226332)
		(width 0.088646)
		(layer "In11.Cu")
		(net "M_D_CPU1_SB_DQS_DP<9>")
	)
	(segment
		(start 31.038292 -239.10798)
		(end 30.84449 -238.914178)
		(width 0.18288)
		(layer "In11.Cu")
		(net "M_D_CPU1_SB_DQS_DP<9>")
	)
	(segment
		(start 53.802026 -237.616746)
		(end 52.230274 -238.267748)
		(width 0.18288)
		(layer "In11.Cu")
		(net "M_D_CPU1_SB_DQS_DP<9>")
	)
	(segment
		(start 21.131784 -238.541306)
		(end 20.695158 -238.541306)
		(width 0.18288)
		(layer "In11.Cu")
		(net "M_D_CPU1_SB_DQS_DP<9>")
	)
	(segment
		(start 95.865696 -245.234968)
		(end 95.850964 -245.226332)
		(width 0.088646)
		(layer "In11.Cu")
		(net "M_D_CPU1_SB_DQS_DP<9>")
	)
	(segment
		(start 17.422114 -237.83036)
		(end 17.075404 -237.83036)
		(width 0.18288)
		(layer "In11.Cu")
		(net "M_D_CPU1_SB_DQS_DP<9>")
	)
	(segment
		(start 65.602866 -238.874554)
		(end 64.817498 -238.089186)
		(width 0.18288)
		(layer "In11.Cu")
		(net "M_D_CPU1_SB_DQS_DP<9>")
	)
	(segment
		(start 98.612452 -244.826536)
		(end 98.187256 -245.068344)
		(width 0.088646)
		(layer "In11.Cu")
		(net "M_D_CPU1_SB_DQS_DP<9>")
	)
	(segment
		(start 46.774354 -239.392968)
		(end 46.487588 -239.106202)
		(width 0.18288)
		(layer "In11.Cu")
		(net "M_D_CPU1_SB_DQS_DP<9>")
	)
	(segment
		(start 83.733386 -244.043454)
		(end 83.673696 -244.103144)
		(width 0.088646)
		(layer "In11.Cu")
		(net "M_D_CPU1_SB_DQS_DP<9>")
	)
	(segment
		(start 49.683924 -238.463074)
		(end 49.421288 -238.725456)
		(width 0.18288)
		(layer "In11.Cu")
		(net "M_D_CPU1_SB_DQS_DP<9>")
	)
	(segment
		(start 47.444406 -239.113822)
		(end 47.16526 -239.392968)
		(width 0.18288)
		(layer "In11.Cu")
		(net "M_D_CPU1_SB_DQS_DP<9>")
	)
	(segment
		(start 31.397956 -239.133126)
		(end 31.37281 -239.10798)
		(width 0.18288)
		(layer "In11.Cu")
		(net "M_D_CPU1_SB_DQS_DP<9>")
	)
	(segment
		(start 28.583636 -238.861346)
		(end 25.84958 -238.861346)
		(width 0.18288)
		(layer "In11.Cu")
		(net "M_D_CPU1_SB_DQS_DP<9>")
	)
	(segment
		(start 81.931256 -243.525802)
		(end 71.41464 -243.525802)
		(width 0.18288)
		(layer "In11.Cu")
		(net "M_D_CPU1_SB_DQS_DP<9>")
	)
	(segment
		(start 35.474148 -238.279178)
		(end 35.176206 -238.279178)
		(width 0.18288)
		(layer "In11.Cu")
		(net "M_D_CPU1_SB_DQS_DP<9>")
	)
	(segment
		(start 89.287096 -245.234968)
		(end 89.272364 -245.226332)
		(width 0.088646)
		(layer "In11.Cu")
		(net "M_D_CPU1_SB_DQS_DP<9>")
	)
	(segment
		(start 84.855812 -244.361716)
		(end 84.430108 -244.361716)
		(width 0.088646)
		(layer "In11.Cu")
		(net "M_D_CPU1_SB_DQS_DP<9>")
	)
	(segment
		(start 90.777314 -245.226332)
		(end 90.7669 -245.232428)
		(width 0.088646)
		(layer "In11.Cu")
		(net "M_D_CPU1_SB_DQS_DP<9>")
	)
	(segment
		(start 36.223448 -238.544608)
		(end 35.739578 -238.544608)
		(width 0.18288)
		(layer "In11.Cu")
		(net "M_D_CPU1_SB_DQS_DP<9>")
	)
	(segment
		(start 30.84449 -238.914178)
		(end 29.869638 -238.510064)
		(width 0.18288)
		(layer "In11.Cu")
		(net "M_D_CPU1_SB_DQS_DP<9>")
	)
	(segment
		(start 43.875198 -237.664244)
		(end 41.024302 -237.664244)
		(width 0.18288)
		(layer "In11.Cu")
		(net "M_D_CPU1_SB_DQS_DP<9>")
	)
	(segment
		(start 82.508598 -244.103144)
		(end 81.931256 -243.525802)
		(width 0.18288)
		(layer "In11.Cu")
		(net "M_D_CPU1_SB_DQS_DP<9>")
	)
	(segment
		(start 29.43225 -238.510064)
		(end 28.583636 -238.861346)
		(width 0.18288)
		(layer "In11.Cu")
		(net "M_D_CPU1_SB_DQS_DP<9>")
	)
	(segment
		(start 34.995866 -238.459772)
		(end 33.415224 -239.114076)
		(width 0.18288)
		(layer "In11.Cu")
		(net "M_D_CPU1_SB_DQS_DP<9>")
	)
	(segment
		(start 83.673696 -244.103144)
		(end 82.508598 -244.103144)
		(width 0.18288)
		(layer "In11.Cu")
		(net "M_D_CPU1_SB_DQS_DP<9>")
	)
	(segment
		(start 88.347296 -245.234968)
		(end 88.332564 -245.226332)
		(width 0.088646)
		(layer "In11.Cu")
		(net "M_D_CPU1_SB_DQS_DP<9>")
	)
	(segment
		(start 35.739578 -238.544608)
		(end 35.474148 -238.279178)
		(width 0.18288)
		(layer "In11.Cu")
		(net "M_D_CPU1_SB_DQS_DP<9>")
	)
	(segment
		(start 84.111846 -244.043454)
		(end 83.733386 -244.043454)
		(width 0.088646)
		(layer "In11.Cu")
		(net "M_D_CPU1_SB_DQS_DP<9>")
	)
	(segment
		(start 19.914616 -238.267748)
		(end 19.276568 -237.6297)
		(width 0.18288)
		(layer "In11.Cu")
		(net "M_D_CPU1_SB_DQS_DP<9>")
	)
	(segment
		(start 25.84958 -238.861346)
		(end 24.40432 -238.262668)
		(width 0.18288)
		(layer "In11.Cu")
		(net "M_D_CPU1_SB_DQS_DP<9>")
	)
	(segment
		(start 50.87239 -238.542068)
		(end 50.56251 -238.232188)
		(width 0.18288)
		(layer "In11.Cu")
		(net "M_D_CPU1_SB_DQS_DP<9>")
	)
	(segment
		(start 32.127952 -239.392968)
		(end 31.674054 -239.392968)
		(width 0.18288)
		(layer "In11.Cu")
		(net "M_D_CPU1_SB_DQS_DP<9>")
	)
	(segment
		(start 44.92371 -238.098838)
		(end 43.875198 -237.664244)
		(width 0.18288)
		(layer "In11.Cu")
		(net "M_D_CPU1_SB_DQS_DP<9>")
	)
	(segment
		(start 20.695158 -238.541306)
		(end 20.4216 -238.267748)
		(width 0.18288)
		(layer "In11.Cu")
		(net "M_D_CPU1_SB_DQS_DP<9>")
	)
	(segment
		(start 41.024302 -237.664244)
		(end 39.443406 -238.319056)
		(width 0.18288)
		(layer "In11.Cu")
		(net "M_D_CPU1_SB_DQS_DP<9>")
	)
	(segment
		(start 71.41464 -243.525802)
		(end 67.017392 -239.128554)
		(width 0.18288)
		(layer "In11.Cu")
		(net "M_D_CPU1_SB_DQS_DP<9>")
	)
	(segment
		(start 97.56521 -245.105682)
		(end 97.34169 -245.23446)
		(width 0.088646)
		(layer "In11.Cu")
		(net "M_D_CPU1_SB_DQS_DP<9>")
	)
	(segment
		(start 97.92081 -245.105682)
		(end 97.56521 -245.105682)
		(width 0.088646)
		(layer "In11.Cu")
		(net "M_D_CPU1_SB_DQS_DP<9>")
	)
	(segment
		(start 92.656914 -245.226332)
		(end 92.6465 -245.232428)
		(width 0.088646)
		(layer "In11.Cu")
		(net "M_D_CPU1_SB_DQS_DP<9>")
	)
	(segment
		(start 47.16526 -239.392968)
		(end 46.774354 -239.392968)
		(width 0.18288)
		(layer "In11.Cu")
		(net "M_D_CPU1_SB_DQS_DP<9>")
	)
	(segment
		(start 84.430108 -244.361716)
		(end 84.111846 -244.043454)
		(width 0.088646)
		(layer "In11.Cu")
		(net "M_D_CPU1_SB_DQS_DP<9>")
	)
	(segment
		(start 17.075404 -237.83036)
		(end 16.789146 -238.116618)
		(width 0.18288)
		(layer "In11.Cu")
		(net "M_D_CPU1_SB_DQS_DP<9>")
	)
	(segment
		(start 31.414212 -239.133126)
		(end 31.397956 -239.133126)
		(width 0.18288)
		(layer "In11.Cu")
		(net "M_D_CPU1_SB_DQS_DP<9>")
	)
	(segment
		(start 93.041724 -245.232428)
		(end 93.03131 -245.226332)
		(width 0.088646)
		(layer "In11.Cu")
		(net "M_D_CPU1_SB_DQS_DP<9>")
	)
	(segment
		(start 19.276568 -237.6297)
		(end 17.906746 -237.6297)
		(width 0.18288)
		(layer "In11.Cu")
		(net "M_D_CPU1_SB_DQS_DP<9>")
	)
	(segment
		(start 48.484536 -239.113822)
		(end 47.444406 -239.113822)
		(width 0.18288)
		(layer "In11.Cu")
		(net "M_D_CPU1_SB_DQS_DP<9>")
	)
	(segment
		(start 36.449 -238.319056)
		(end 36.223448 -238.544608)
		(width 0.18288)
		(layer "In11.Cu")
		(net "M_D_CPU1_SB_DQS_DP<9>")
	)
	(segment
		(start 29.869638 -238.510064)
		(end 29.43225 -238.510064)
		(width 0.18288)
		(layer "In11.Cu")
		(net "M_D_CPU1_SB_DQS_DP<9>")
	)
	(segment
		(start 91.162124 -245.232428)
		(end 91.15171 -245.226332)
		(width 0.088646)
		(layer "In11.Cu")
		(net "M_D_CPU1_SB_DQS_DP<9>")
	)
	(segment
		(start 39.443406 -238.319056)
		(end 36.449 -238.319056)
		(width 0.18288)
		(layer "In11.Cu")
		(net "M_D_CPU1_SB_DQS_DP<9>")
	)
	(segment
		(start 46.487588 -239.106202)
		(end 45.931074 -239.106202)
		(width 0.18288)
		(layer "In11.Cu")
		(net "M_D_CPU1_SB_DQS_DP<9>")
	)
	(arc
		(start 93.03131 -245.226332)
		(mid 92.844112 -245.176189)
		(end 92.656914 -245.226332)
		(width 0.088646)
		(layer "In11.Cu")
		(net "M_D_CPU1_SB_DQS_DP<9>")
	)
	(arc
		(start 86.078568 -245.226332)
		(mid 85.804339 -245.302257)
		(end 85.527896 -245.234968)
		(width 0.088646)
		(layer "In11.Cu")
		(net "M_D_CPU1_SB_DQS_DP<9>")
	)
	(arc
		(start 87.958168 -245.226332)
		(mid 87.683939 -245.302257)
		(end 87.407496 -245.234968)
		(width 0.088646)
		(layer "In11.Cu")
		(net "M_D_CPU1_SB_DQS_DP<9>")
	)
	(arc
		(start 98.187256 -245.068344)
		(mid 98.088414 -245.105854)
		(end 97.982786 -245.11)
		(width 0.088646)
		(layer "In11.Cu")
		(net "M_D_CPU1_SB_DQS_DP<9>")
	)
	(arc
		(start 89.272364 -245.226332)
		(mid 89.085166 -245.176189)
		(end 88.897968 -245.226332)
		(width 0.088646)
		(layer "In11.Cu")
		(net "M_D_CPU1_SB_DQS_DP<9>")
	)
	(arc
		(start 92.091764 -245.226332)
		(mid 91.904566 -245.176189)
		(end 91.717368 -245.226332)
		(width 0.088646)
		(layer "In11.Cu")
		(net "M_D_CPU1_SB_DQS_DP<9>")
	)
	(arc
		(start 94.536768 -245.226332)
		(mid 94.262539 -245.302257)
		(end 93.986096 -245.234968)
		(width 0.088646)
		(layer "In11.Cu")
		(net "M_D_CPU1_SB_DQS_DP<9>")
	)
	(arc
		(start 91.15171 -245.226332)
		(mid 90.964512 -245.176189)
		(end 90.777314 -245.226332)
		(width 0.088646)
		(layer "In11.Cu")
		(net "M_D_CPU1_SB_DQS_DP<9>")
	)
	(arc
		(start 97.34169 -245.23446)
		(mid 97.065025 -245.301931)
		(end 96.79051 -245.226078)
		(width 0.088646)
		(layer "In11.Cu")
		(net "M_D_CPU1_SB_DQS_DP<9>")
	)
	(arc
		(start 98.952812 -244.73662)
		(mid 98.776791 -244.759457)
		(end 98.612452 -244.826536)
		(width 0.088646)
		(layer "In11.Cu")
		(net "M_D_CPU1_SB_DQS_DP<9>")
	)
	(arc
		(start 88.332564 -245.226332)
		(mid 88.145366 -245.176189)
		(end 87.958168 -245.226332)
		(width 0.088646)
		(layer "In11.Cu")
		(net "M_D_CPU1_SB_DQS_DP<9>")
	)
	(arc
		(start 90.7669 -245.232428)
		(mid 90.488722 -245.30212)
		(end 90.212164 -245.226332)
		(width 0.088646)
		(layer "In11.Cu")
		(net "M_D_CPU1_SB_DQS_DP<9>")
	)
	(arc
		(start 93.596968 -245.226332)
		(mid 93.320155 -245.302168)
		(end 93.041724 -245.232428)
		(width 0.088646)
		(layer "In11.Cu")
		(net "M_D_CPU1_SB_DQS_DP<9>")
	)
	(arc
		(start 91.717368 -245.226332)
		(mid 91.440555 -245.302168)
		(end 91.162124 -245.232428)
		(width 0.088646)
		(layer "In11.Cu")
		(net "M_D_CPU1_SB_DQS_DP<9>")
	)
	(arc
		(start 95.850964 -245.226332)
		(mid 95.663766 -245.176189)
		(end 95.476568 -245.226332)
		(width 0.088646)
		(layer "In11.Cu")
		(net "M_D_CPU1_SB_DQS_DP<9>")
	)
	(arc
		(start 92.6465 -245.232428)
		(mid 92.368322 -245.30212)
		(end 92.091764 -245.226332)
		(width 0.088646)
		(layer "In11.Cu")
		(net "M_D_CPU1_SB_DQS_DP<9>")
	)
	(arc
		(start 93.971364 -245.226332)
		(mid 93.784166 -245.176189)
		(end 93.596968 -245.226332)
		(width 0.088646)
		(layer "In11.Cu")
		(net "M_D_CPU1_SB_DQS_DP<9>")
	)
	(arc
		(start 88.897968 -245.226332)
		(mid 88.623739 -245.302257)
		(end 88.347296 -245.234968)
		(width 0.088646)
		(layer "In11.Cu")
		(net "M_D_CPU1_SB_DQS_DP<9>")
	)
	(arc
		(start 85.513164 -245.226332)
		(mid 85.309683 -245.025528)
		(end 85.230462 -244.750844)
		(width 0.088646)
		(layer "In11.Cu")
		(net "M_D_CPU1_SB_DQS_DP<9>")
	)
	(arc
		(start 96.416368 -245.226332)
		(mid 96.142139 -245.302257)
		(end 95.865696 -245.234968)
		(width 0.088646)
		(layer "In11.Cu")
		(net "M_D_CPU1_SB_DQS_DP<9>")
	)
	(arc
		(start 87.392764 -245.226332)
		(mid 87.205566 -245.176189)
		(end 87.018368 -245.226332)
		(width 0.088646)
		(layer "In11.Cu")
		(net "M_D_CPU1_SB_DQS_DP<9>")
	)
	(arc
		(start 96.790764 -245.226332)
		(mid 96.603566 -245.176189)
		(end 96.416368 -245.226332)
		(width 0.088646)
		(layer "In11.Cu")
		(net "M_D_CPU1_SB_DQS_DP<9>")
	)
	(arc
		(start 89.837768 -245.226332)
		(mid 89.563539 -245.302257)
		(end 89.287096 -245.234968)
		(width 0.088646)
		(layer "In11.Cu")
		(net "M_D_CPU1_SB_DQS_DP<9>")
	)
	(arc
		(start 94.911164 -245.226332)
		(mid 94.723966 -245.176189)
		(end 94.536768 -245.226332)
		(width 0.088646)
		(layer "In11.Cu")
		(net "M_D_CPU1_SB_DQS_DP<9>")
	)
	(arc
		(start 95.476568 -245.226332)
		(mid 95.202339 -245.302257)
		(end 94.925896 -245.234968)
		(width 0.088646)
		(layer "In11.Cu")
		(net "M_D_CPU1_SB_DQS_DP<9>")
	)
	(arc
		(start 90.212164 -245.226332)
		(mid 90.024966 -245.176189)
		(end 89.837768 -245.226332)
		(width 0.088646)
		(layer "In11.Cu")
		(net "M_D_CPU1_SB_DQS_DP<9>")
	)
	(arc
		(start 87.018368 -245.226332)
		(mid 86.744139 -245.302257)
		(end 86.467696 -245.234968)
		(width 0.088646)
		(layer "In11.Cu")
		(net "M_D_CPU1_SB_DQS_DP<9>")
	)
	(arc
		(start 86.452964 -245.226332)
		(mid 86.265766 -245.176189)
		(end 86.078568 -245.226332)
		(width 0.088646)
		(layer "In11.Cu")
		(net "M_D_CPU1_SB_DQS_DP<9>")
	)
	(arc
		(start 85.230462 -244.73662)
		(mid 85.120745 -244.471613)
		(end 84.855812 -244.361716)
		(width 0.088646)
		(layer "In11.Cu")
		(net "M_D_CPU1_SB_DQS_DP<9>")
	)
	(segment
		(start 13.310616 -199.277986)
		(end 12.976352 -199.277986)
		(width 0.20066)
		(layer "F.Cu")
		(net "M_D_CPU1_SB_DQS_DP<8>")
	)
	(segment
		(start 16.885158 -198.591932)
		(end 16.884904 -198.591678)
		(width 0.1016)
		(layer "F.Cu")
		(net "M_D_CPU1_SB_DQS_DP<8>")
	)
	(segment
		(start 20.889214 -199.01662)
		(end 19.784314 -199.01662)
		(width 0.20066)
		(layer "F.Cu")
		(net "M_D_CPU1_SB_DQS_DP<8>")
	)
	(segment
		(start 13.733018 -198.855584)
		(end 13.310616 -199.277986)
		(width 0.20066)
		(layer "F.Cu")
		(net "M_D_CPU1_SB_DQS_DP<8>")
	)
	(segment
		(start 14.56563 -198.591678)
		(end 14.560042 -198.58609)
		(width 0.101854)
		(layer "F.Cu")
		(net "M_D_CPU1_SB_DQS_DP<8>")
	)
	(segment
		(start 14.80693 -198.591678)
		(end 14.56563 -198.591678)
		(width 0.101854)
		(layer "F.Cu")
		(net "M_D_CPU1_SB_DQS_DP<8>")
	)
	(segment
		(start 14.09319 -198.855584)
		(end 13.733018 -198.855584)
		(width 0.20066)
		(layer "F.Cu")
		(net "M_D_CPU1_SB_DQS_DP<8>")
	)
	(segment
		(start 12.714986 -199.01662)
		(end 12.240514 -199.01662)
		(width 0.20066)
		(layer "F.Cu")
		(net "M_D_CPU1_SB_DQS_DP<8>")
	)
	(segment
		(start 100.832412 -230.622348)
		(end 100.832412 -230.086662)
		(width 0.20066)
		(layer "F.Cu")
		(net "M_D_CPU1_SB_DQS_DP<8>")
	)
	(segment
		(start 18.428716 -199.277986)
		(end 17.7927 -198.853044)
		(width 0.20066)
		(layer "F.Cu")
		(net "M_D_CPU1_SB_DQS_DP<8>")
	)
	(segment
		(start 19.294602 -199.01662)
		(end 19.033236 -199.277986)
		(width 0.20066)
		(layer "F.Cu")
		(net "M_D_CPU1_SB_DQS_DP<8>")
	)
	(segment
		(start 12.976352 -199.277986)
		(end 12.714986 -199.01662)
		(width 0.20066)
		(layer "F.Cu")
		(net "M_D_CPU1_SB_DQS_DP<8>")
	)
	(segment
		(start 14.560042 -198.58609)
		(end 14.362684 -198.58609)
		(width 0.20066)
		(layer "F.Cu")
		(net "M_D_CPU1_SB_DQS_DP<8>")
	)
	(segment
		(start 19.784314 -199.01662)
		(end 19.294602 -199.01662)
		(width 0.20066)
		(layer "F.Cu")
		(net "M_D_CPU1_SB_DQS_DP<8>")
	)
	(segment
		(start 17.287748 -198.853044)
		(end 17.026636 -198.591932)
		(width 0.20066)
		(layer "F.Cu")
		(net "M_D_CPU1_SB_DQS_DP<8>")
	)
	(segment
		(start 17.7927 -198.853044)
		(end 17.287748 -198.853044)
		(width 0.20066)
		(layer "F.Cu")
		(net "M_D_CPU1_SB_DQS_DP<8>")
	)
	(segment
		(start 100.832666 -230.622602)
		(end 100.832412 -230.622348)
		(width 0.20066)
		(layer "F.Cu")
		(net "M_D_CPU1_SB_DQS_DP<8>")
	)
	(segment
		(start 16.884904 -198.591678)
		(end 14.80693 -198.591678)
		(width 0.1016)
		(layer "F.Cu")
		(net "M_D_CPU1_SB_DQS_DP<8>")
	)
	(segment
		(start 14.362684 -198.58609)
		(end 14.09319 -198.855584)
		(width 0.20066)
		(layer "F.Cu")
		(net "M_D_CPU1_SB_DQS_DP<8>")
	)
	(segment
		(start 17.026636 -198.591932)
		(end 16.885158 -198.591932)
		(width 0.20066)
		(layer "F.Cu")
		(net "M_D_CPU1_SB_DQS_DP<8>")
	)
	(segment
		(start 19.033236 -199.277986)
		(end 18.428716 -199.277986)
		(width 0.20066)
		(layer "F.Cu")
		(net "M_D_CPU1_SB_DQS_DP<8>")
	)
	(segment
		(start 91.621102 -227.155756)
		(end 91.612974 -227.160582)
		(width 0.088646)
		(layer "In11.Cu")
		(net "M_D_CPU1_SB_DQS_DP<8>")
	)
	(segment
		(start 59.22645 -197.37324)
		(end 55.475124 -197.37324)
		(width 0.18288)
		(layer "In11.Cu")
		(net "M_D_CPU1_SB_DQS_DP<8>")
	)
	(segment
		(start 98.108516 -227.663502)
		(end 98.108516 -227.64496)
		(width 0.088646)
		(layer "In11.Cu")
		(net "M_D_CPU1_SB_DQS_DP<8>")
	)
	(segment
		(start 55.475124 -197.37324)
		(end 54.842156 -198.006208)
		(width 0.18288)
		(layer "In11.Cu")
		(net "M_D_CPU1_SB_DQS_DP<8>")
	)
	(segment
		(start 21.741892 -199.298814)
		(end 21.171408 -199.298814)
		(width 0.18288)
		(layer "In11.Cu")
		(net "M_D_CPU1_SB_DQS_DP<8>")
	)
	(segment
		(start 43.897042 -197.294754)
		(end 41.076118 -197.294754)
		(width 0.18288)
		(layer "In11.Cu")
		(net "M_D_CPU1_SB_DQS_DP<8>")
	)
	(segment
		(start 87.770716 -226.017328)
		(end 87.770716 -226.003104)
		(width 0.088646)
		(layer "In11.Cu")
		(net "M_D_CPU1_SB_DQS_DP<8>")
	)
	(segment
		(start 36.47694 -198.005954)
		(end 36.212018 -197.741032)
		(width 0.18288)
		(layer "In11.Cu")
		(net "M_D_CPU1_SB_DQS_DP<8>")
	)
	(segment
		(start 24.601932 -198.243444)
		(end 23.864062 -198.243444)
		(width 0.18288)
		(layer "In11.Cu")
		(net "M_D_CPU1_SB_DQS_DP<8>")
	)
	(segment
		(start 97.817178 -228.139752)
		(end 97.825306 -228.13518)
		(width 0.088646)
		(layer "In11.Cu")
		(net "M_D_CPU1_SB_DQS_DP<8>")
	)
	(segment
		(start 31.373572 -197.20052)
		(end 30.633162 -197.20052)
		(width 0.18288)
		(layer "In11.Cu")
		(net "M_D_CPU1_SB_DQS_DP<8>")
	)
	(segment
		(start 54.842156 -198.006208)
		(end 51.582574 -198.006208)
		(width 0.18288)
		(layer "In11.Cu")
		(net "M_D_CPU1_SB_DQS_DP<8>")
	)
	(segment
		(start 27.801062 -197.620382)
		(end 27.405584 -197.88378)
		(width 0.18288)
		(layer "In11.Cu")
		(net "M_D_CPU1_SB_DQS_DP<8>")
	)
	(segment
		(start 100.519484 -230.086662)
		(end 100.454206 -230.021384)
		(width 0.088646)
		(layer "In11.Cu")
		(net "M_D_CPU1_SB_DQS_DP<8>")
	)
	(segment
		(start 64.814958 -200.220072)
		(end 62.670436 -198.07555)
		(width 0.18288)
		(layer "In11.Cu")
		(net "M_D_CPU1_SB_DQS_DP<8>")
	)
	(segment
		(start 93.13926 -227.162868)
		(end 93.127576 -227.155756)
		(width 0.088646)
		(layer "In11.Cu")
		(net "M_D_CPU1_SB_DQS_DP<8>")
	)
	(segment
		(start 49.967896 -198.061326)
		(end 49.059084 -197.152514)
		(width 0.18288)
		(layer "In11.Cu")
		(net "M_D_CPU1_SB_DQS_DP<8>")
	)
	(segment
		(start 95.01886 -227.162868)
		(end 95.007176 -227.155756)
		(width 0.088646)
		(layer "In11.Cu")
		(net "M_D_CPU1_SB_DQS_DP<8>")
	)
	(segment
		(start 41.076118 -197.294754)
		(end 40.364918 -198.005954)
		(width 0.18288)
		(layer "In11.Cu")
		(net "M_D_CPU1_SB_DQS_DP<8>")
	)
	(segment
		(start 26.646632 -198.642732)
		(end 25.715214 -198.642732)
		(width 0.18288)
		(layer "In11.Cu")
		(net "M_D_CPU1_SB_DQS_DP<8>")
	)
	(segment
		(start 35.084766 -198.03745)
		(end 34.680906 -197.633336)
		(width 0.18288)
		(layer "In11.Cu")
		(net "M_D_CPU1_SB_DQS_DP<8>")
	)
	(segment
		(start 47.207424 -196.891148)
		(end 46.760892 -196.891148)
		(width 0.18288)
		(layer "In11.Cu")
		(net "M_D_CPU1_SB_DQS_DP<8>")
	)
	(segment
		(start 96.886014 -227.155502)
		(end 96.8756 -227.149406)
		(width 0.088646)
		(layer "In11.Cu")
		(net "M_D_CPU1_SB_DQS_DP<8>")
	)
	(segment
		(start 84.441284 -225.578416)
		(end 84.123784 -225.260916)
		(width 0.088646)
		(layer "In11.Cu")
		(net "M_D_CPU1_SB_DQS_DP<8>")
	)
	(segment
		(start 51.318414 -197.742048)
		(end 50.870358 -197.742048)
		(width 0.18288)
		(layer "In11.Cu")
		(net "M_D_CPU1_SB_DQS_DP<8>")
	)
	(segment
		(start 27.405584 -197.88378)
		(end 26.646632 -198.642732)
		(width 0.18288)
		(layer "In11.Cu")
		(net "M_D_CPU1_SB_DQS_DP<8>")
	)
	(segment
		(start 50.870358 -197.742048)
		(end 50.55108 -198.061326)
		(width 0.18288)
		(layer "In11.Cu")
		(net "M_D_CPU1_SB_DQS_DP<8>")
	)
	(segment
		(start 28.142438 -197.404228)
		(end 27.801062 -197.620382)
		(width 0.18288)
		(layer "In11.Cu")
		(net "M_D_CPU1_SB_DQS_DP<8>")
	)
	(segment
		(start 82.64652 -223.374966)
		(end 75.546712 -216.275158)
		(width 0.18288)
		(layer "In11.Cu")
		(net "M_D_CPU1_SB_DQS_DP<8>")
	)
	(segment
		(start 97.825306 -228.78288)
		(end 97.822766 -228.781356)
		(width 0.088646)
		(layer "In11.Cu")
		(net "M_D_CPU1_SB_DQS_DP<8>")
	)
	(segment
		(start 35.489896 -198.03745)
		(end 35.084766 -198.03745)
		(width 0.18288)
		(layer "In11.Cu")
		(net "M_D_CPU1_SB_DQS_DP<8>")
	)
	(segment
		(start 29.020262 -197.404228)
		(end 28.142438 -197.404228)
		(width 0.18288)
		(layer "In11.Cu")
		(net "M_D_CPU1_SB_DQS_DP<8>")
	)
	(segment
		(start 31.683198 -196.890894)
		(end 31.373572 -197.20052)
		(width 0.18288)
		(layer "In11.Cu")
		(net "M_D_CPU1_SB_DQS_DP<8>")
	)
	(segment
		(start 98.669602 -229.597458)
		(end 98.657918 -229.60457)
		(width 0.088646)
		(layer "In11.Cu")
		(net "M_D_CPU1_SB_DQS_DP<8>")
	)
	(segment
		(start 22.051264 -199.608186)
		(end 21.741892 -199.298814)
		(width 0.18288)
		(layer "In11.Cu")
		(net "M_D_CPU1_SB_DQS_DP<8>")
	)
	(segment
		(start 89.38006 -227.162868)
		(end 89.367614 -227.155502)
		(width 0.088646)
		(layer "In11.Cu")
		(net "M_D_CPU1_SB_DQS_DP<8>")
	)
	(segment
		(start 30.633162 -197.20052)
		(end 30.016196 -197.817486)
		(width 0.18288)
		(layer "In11.Cu")
		(net "M_D_CPU1_SB_DQS_DP<8>")
	)
	(segment
		(start 85.057996 -225.51898)
		(end 85.043264 -225.527616)
		(width 0.088646)
		(layer "In11.Cu")
		(net "M_D_CPU1_SB_DQS_DP<8>")
	)
	(segment
		(start 97.826068 -228.783388)
		(end 97.825306 -228.78288)
		(width 0.088646)
		(layer "In11.Cu")
		(net "M_D_CPU1_SB_DQS_DP<8>")
	)
	(segment
		(start 50.55108 -198.061326)
		(end 49.967896 -198.061326)
		(width 0.18288)
		(layer "In11.Cu")
		(net "M_D_CPU1_SB_DQS_DP<8>")
	)
	(segment
		(start 33.50006 -197.144132)
		(end 32.364172 -197.144132)
		(width 0.18288)
		(layer "In11.Cu")
		(net "M_D_CPU1_SB_DQS_DP<8>")
	)
	(segment
		(start 90.31986 -227.162868)
		(end 90.308176 -227.155756)
		(width 0.088646)
		(layer "In11.Cu")
		(net "M_D_CPU1_SB_DQS_DP<8>")
	)
	(segment
		(start 32.364172 -197.144132)
		(end 32.110934 -196.890894)
		(width 0.18288)
		(layer "In11.Cu")
		(net "M_D_CPU1_SB_DQS_DP<8>")
	)
	(segment
		(start 89.367614 -227.155502)
		(end 89.352882 -227.146866)
		(width 0.088646)
		(layer "In11.Cu")
		(net "M_D_CPU1_SB_DQS_DP<8>")
	)
	(segment
		(start 86.937596 -225.51898)
		(end 86.922864 -225.527616)
		(width 0.088646)
		(layer "In11.Cu")
		(net "M_D_CPU1_SB_DQS_DP<8>")
	)
	(segment
		(start 97.825814 -227.155502)
		(end 97.811082 -227.146866)
		(width 0.088646)
		(layer "In11.Cu")
		(net "M_D_CPU1_SB_DQS_DP<8>")
	)
	(segment
		(start 44.419774 -197.817486)
		(end 43.897042 -197.294754)
		(width 0.18288)
		(layer "In11.Cu")
		(net "M_D_CPU1_SB_DQS_DP<8>")
	)
	(segment
		(start 62.670436 -198.07555)
		(end 59.92876 -198.07555)
		(width 0.18288)
		(layer "In11.Cu")
		(net "M_D_CPU1_SB_DQS_DP<8>")
	)
	(segment
		(start 49.059084 -197.152514)
		(end 47.46879 -197.152514)
		(width 0.18288)
		(layer "In11.Cu")
		(net "M_D_CPU1_SB_DQS_DP<8>")
	)
	(segment
		(start 92.195904 -227.160582)
		(end 92.187268 -227.155756)
		(width 0.088646)
		(layer "In11.Cu")
		(net "M_D_CPU1_SB_DQS_DP<8>")
	)
	(segment
		(start 59.92876 -198.07555)
		(end 59.22645 -197.37324)
		(width 0.18288)
		(layer "In11.Cu")
		(net "M_D_CPU1_SB_DQS_DP<8>")
	)
	(segment
		(start 97.825306 -228.13518)
		(end 97.826068 -228.134672)
		(width 0.088646)
		(layer "In11.Cu")
		(net "M_D_CPU1_SB_DQS_DP<8>")
	)
	(segment
		(start 46.486318 -197.165722)
		(end 45.80636 -197.165722)
		(width 0.18288)
		(layer "In11.Cu")
		(net "M_D_CPU1_SB_DQS_DP<8>")
	)
	(segment
		(start 84.856066 -225.578416)
		(end 84.441284 -225.578416)
		(width 0.088646)
		(layer "In11.Cu")
		(net "M_D_CPU1_SB_DQS_DP<8>")
	)
	(segment
		(start 46.760892 -196.891148)
		(end 46.486318 -197.165722)
		(width 0.18288)
		(layer "In11.Cu")
		(net "M_D_CPU1_SB_DQS_DP<8>")
	)
	(segment
		(start 21.171408 -199.298814)
		(end 20.889214 -199.01662)
		(width 0.18288)
		(layer "In11.Cu")
		(net "M_D_CPU1_SB_DQS_DP<8>")
	)
	(segment
		(start 47.46879 -197.152514)
		(end 47.207424 -196.891148)
		(width 0.18288)
		(layer "In11.Cu")
		(net "M_D_CPU1_SB_DQS_DP<8>")
	)
	(segment
		(start 82.64652 -223.459294)
		(end 82.64652 -223.374966)
		(width 0.088646)
		(layer "In11.Cu")
		(net "M_D_CPU1_SB_DQS_DP<8>")
	)
	(segment
		(start 30.016196 -197.817486)
		(end 29.43352 -197.817486)
		(width 0.18288)
		(layer "In11.Cu")
		(net "M_D_CPU1_SB_DQS_DP<8>")
	)
	(segment
		(start 97.8281 -227.156772)
		(end 97.825814 -227.155502)
		(width 0.088646)
		(layer "In11.Cu")
		(net "M_D_CPU1_SB_DQS_DP<8>")
	)
	(segment
		(start 23.864062 -198.243444)
		(end 22.49932 -199.608186)
		(width 0.18288)
		(layer "In11.Cu")
		(net "M_D_CPU1_SB_DQS_DP<8>")
	)
	(segment
		(start 32.110934 -196.890894)
		(end 31.683198 -196.890894)
		(width 0.18288)
		(layer "In11.Cu")
		(net "M_D_CPU1_SB_DQS_DP<8>")
	)
	(segment
		(start 22.49932 -199.608186)
		(end 22.051264 -199.608186)
		(width 0.18288)
		(layer "In11.Cu")
		(net "M_D_CPU1_SB_DQS_DP<8>")
	)
	(segment
		(start 75.546712 -212.441536)
		(end 65.722246 -202.616816)
		(width 0.18288)
		(layer "In11.Cu")
		(net "M_D_CPU1_SB_DQS_DP<8>")
	)
	(segment
		(start 97.83191 -227.159058)
		(end 97.830132 -227.158042)
		(width 0.088646)
		(layer "In11.Cu")
		(net "M_D_CPU1_SB_DQS_DP<8>")
	)
	(segment
		(start 51.582574 -198.006208)
		(end 51.318414 -197.742048)
		(width 0.18288)
		(layer "In11.Cu")
		(net "M_D_CPU1_SB_DQS_DP<8>")
	)
	(segment
		(start 75.546712 -216.275158)
		(end 75.546712 -212.441536)
		(width 0.18288)
		(layer "In11.Cu")
		(net "M_D_CPU1_SB_DQS_DP<8>")
	)
	(segment
		(start 45.154596 -197.817486)
		(end 44.419774 -197.817486)
		(width 0.18288)
		(layer "In11.Cu")
		(net "M_D_CPU1_SB_DQS_DP<8>")
	)
	(segment
		(start 84.123784 -224.936558)
		(end 82.64652 -223.459294)
		(width 0.088646)
		(layer "In11.Cu")
		(net "M_D_CPU1_SB_DQS_DP<8>")
	)
	(segment
		(start 84.123784 -225.260916)
		(end 84.123784 -224.936558)
		(width 0.088646)
		(layer "In11.Cu")
		(net "M_D_CPU1_SB_DQS_DP<8>")
	)
	(segment
		(start 97.822766 -228.781356)
		(end 97.817178 -228.778308)
		(width 0.088646)
		(layer "In11.Cu")
		(net "M_D_CPU1_SB_DQS_DP<8>")
	)
	(segment
		(start 94.07906 -227.162868)
		(end 94.067376 -227.155756)
		(width 0.088646)
		(layer "In11.Cu")
		(net "M_D_CPU1_SB_DQS_DP<8>")
	)
	(segment
		(start 65.722246 -202.616816)
		(end 64.814958 -200.220072)
		(width 0.18288)
		(layer "In11.Cu")
		(net "M_D_CPU1_SB_DQS_DP<8>")
	)
	(segment
		(start 36.212018 -197.741032)
		(end 35.786314 -197.741032)
		(width 0.18288)
		(layer "In11.Cu")
		(net "M_D_CPU1_SB_DQS_DP<8>")
	)
	(segment
		(start 98.108516 -229.285292)
		(end 98.108516 -229.26294)
		(width 0.088646)
		(layer "In11.Cu")
		(net "M_D_CPU1_SB_DQS_DP<8>")
	)
	(segment
		(start 87.958168 -226.341686)
		(end 87.949278 -226.336606)
		(width 0.088646)
		(layer "In11.Cu")
		(net "M_D_CPU1_SB_DQS_DP<8>")
	)
	(segment
		(start 34.680906 -197.633336)
		(end 33.50006 -197.144132)
		(width 0.18288)
		(layer "In11.Cu")
		(net "M_D_CPU1_SB_DQS_DP<8>")
	)
	(segment
		(start 45.80636 -197.165722)
		(end 45.154596 -197.817486)
		(width 0.18288)
		(layer "In11.Cu")
		(net "M_D_CPU1_SB_DQS_DP<8>")
	)
	(segment
		(start 29.43352 -197.817486)
		(end 29.020262 -197.404228)
		(width 0.18288)
		(layer "In11.Cu")
		(net "M_D_CPU1_SB_DQS_DP<8>")
	)
	(segment
		(start 100.832412 -230.086662)
		(end 100.519484 -230.086662)
		(width 0.088646)
		(layer "In11.Cu")
		(net "M_D_CPU1_SB_DQS_DP<8>")
	)
	(segment
		(start 99.235768 -229.597204)
		(end 99.235514 -229.597204)
		(width 0.088646)
		(layer "In11.Cu")
		(net "M_D_CPU1_SB_DQS_DP<8>")
	)
	(segment
		(start 40.364918 -198.005954)
		(end 36.47694 -198.005954)
		(width 0.18288)
		(layer "In11.Cu")
		(net "M_D_CPU1_SB_DQS_DP<8>")
	)
	(segment
		(start 88.240616 -226.83978)
		(end 88.240616 -226.821238)
		(width 0.088646)
		(layer "In11.Cu")
		(net "M_D_CPU1_SB_DQS_DP<8>")
	)
	(segment
		(start 35.786314 -197.741032)
		(end 35.489896 -198.03745)
		(width 0.18288)
		(layer "In11.Cu")
		(net "M_D_CPU1_SB_DQS_DP<8>")
	)
	(segment
		(start 97.830132 -227.158042)
		(end 97.8281 -227.156772)
		(width 0.088646)
		(layer "In11.Cu")
		(net "M_D_CPU1_SB_DQS_DP<8>")
	)
	(segment
		(start 25.715214 -198.642732)
		(end 24.601932 -198.243444)
		(width 0.18288)
		(layer "In11.Cu")
		(net "M_D_CPU1_SB_DQS_DP<8>")
	)
	(segment
		(start 99.624896 -229.588568)
		(end 99.610164 -229.597204)
		(width 0.088646)
		(layer "In11.Cu")
		(net "M_D_CPU1_SB_DQS_DP<8>")
	)
	(arc
		(start 86.548468 -225.527616)
		(mid 86.265766 -225.451874)
		(end 85.983064 -225.527616)
		(width 0.088646)
		(layer "In11.Cu")
		(net "M_D_CPU1_SB_DQS_DP<8>")
	)
	(arc
		(start 91.247214 -227.155502)
		(mid 90.964656 -227.079853)
		(end 90.682064 -227.155502)
		(width 0.088646)
		(layer "In11.Cu")
		(net "M_D_CPU1_SB_DQS_DP<8>")
	)
	(arc
		(start 92.561918 -227.155502)
		(mid 92.379585 -227.205737)
		(end 92.195904 -227.160582)
		(width 0.088646)
		(layer "In11.Cu")
		(net "M_D_CPU1_SB_DQS_DP<8>")
	)
	(arc
		(start 100.175568 -229.597204)
		(mid 99.901369 -229.521369)
		(end 99.624896 -229.588568)
		(width 0.088646)
		(layer "In11.Cu")
		(net "M_D_CPU1_SB_DQS_DP<8>")
	)
	(arc
		(start 99.235514 -229.597204)
		(mid 98.952529 -229.521428)
		(end 98.669602 -229.597458)
		(width 0.088646)
		(layer "In11.Cu")
		(net "M_D_CPU1_SB_DQS_DP<8>")
	)
	(arc
		(start 85.043264 -225.527616)
		(mid 84.953008 -225.565338)
		(end 84.856066 -225.578416)
		(width 0.088646)
		(layer "In11.Cu")
		(net "M_D_CPU1_SB_DQS_DP<8>")
	)
	(arc
		(start 98.295714 -229.597204)
		(mid 98.161752 -229.465475)
		(end 98.108516 -229.285292)
		(width 0.088646)
		(layer "In11.Cu")
		(net "M_D_CPU1_SB_DQS_DP<8>")
	)
	(arc
		(start 98.108516 -227.64496)
		(mid 98.034525 -227.365394)
		(end 97.83191 -227.159058)
		(width 0.088646)
		(layer "In11.Cu")
		(net "M_D_CPU1_SB_DQS_DP<8>")
	)
	(arc
		(start 97.811082 -227.146866)
		(mid 97.534607 -227.079546)
		(end 97.26041 -227.155502)
		(width 0.088646)
		(layer "In11.Cu")
		(net "M_D_CPU1_SB_DQS_DP<8>")
	)
	(arc
		(start 93.127576 -227.155756)
		(mid 92.844793 -227.079819)
		(end 92.561918 -227.155502)
		(width 0.088646)
		(layer "In11.Cu")
		(net "M_D_CPU1_SB_DQS_DP<8>")
	)
	(arc
		(start 92.187268 -227.155756)
		(mid 91.904168 -227.079692)
		(end 91.621102 -227.155756)
		(width 0.088646)
		(layer "In11.Cu")
		(net "M_D_CPU1_SB_DQS_DP<8>")
	)
	(arc
		(start 86.922864 -225.527616)
		(mid 86.735666 -225.577759)
		(end 86.548468 -225.527616)
		(width 0.088646)
		(layer "In11.Cu")
		(net "M_D_CPU1_SB_DQS_DP<8>")
	)
	(arc
		(start 89.742264 -227.155502)
		(mid 89.562119 -227.205823)
		(end 89.38006 -227.162868)
		(width 0.088646)
		(layer "In11.Cu")
		(net "M_D_CPU1_SB_DQS_DP<8>")
	)
	(arc
		(start 100.454206 -230.021384)
		(mid 100.452908 -230.01083)
		(end 100.451412 -230.000302)
		(width 0.088646)
		(layer "In11.Cu")
		(net "M_D_CPU1_SB_DQS_DP<8>")
	)
	(arc
		(start 93.501464 -227.155502)
		(mid 93.321319 -227.205823)
		(end 93.13926 -227.162868)
		(width 0.088646)
		(layer "In11.Cu")
		(net "M_D_CPU1_SB_DQS_DP<8>")
	)
	(arc
		(start 88.80221 -227.155502)
		(mid 88.615012 -227.205645)
		(end 88.427814 -227.155502)
		(width 0.088646)
		(layer "In11.Cu")
		(net "M_D_CPU1_SB_DQS_DP<8>")
	)
	(arc
		(start 97.826068 -228.134672)
		(mid 98.028354 -227.935691)
		(end 98.108516 -227.663502)
		(width 0.088646)
		(layer "In11.Cu")
		(net "M_D_CPU1_SB_DQS_DP<8>")
	)
	(arc
		(start 95.007176 -227.155756)
		(mid 94.724249 -227.079692)
		(end 94.441264 -227.155502)
		(width 0.088646)
		(layer "In11.Cu")
		(net "M_D_CPU1_SB_DQS_DP<8>")
	)
	(arc
		(start 85.983064 -225.527616)
		(mid 85.795866 -225.577759)
		(end 85.608668 -225.527616)
		(width 0.088646)
		(layer "In11.Cu")
		(net "M_D_CPU1_SB_DQS_DP<8>")
	)
	(arc
		(start 97.26041 -227.155502)
		(mid 97.073212 -227.205645)
		(end 96.886014 -227.155502)
		(width 0.088646)
		(layer "In11.Cu")
		(net "M_D_CPU1_SB_DQS_DP<8>")
	)
	(arc
		(start 100.451412 -230.000302)
		(mid 100.35929 -229.767402)
		(end 100.175568 -229.597204)
		(width 0.088646)
		(layer "In11.Cu")
		(net "M_D_CPU1_SB_DQS_DP<8>")
	)
	(arc
		(start 91.612974 -227.160582)
		(mid 91.429436 -227.205705)
		(end 91.247214 -227.155502)
		(width 0.088646)
		(layer "In11.Cu")
		(net "M_D_CPU1_SB_DQS_DP<8>")
	)
	(arc
		(start 99.610164 -229.597204)
		(mid 99.422966 -229.647347)
		(end 99.235768 -229.597204)
		(width 0.088646)
		(layer "In11.Cu")
		(net "M_D_CPU1_SB_DQS_DP<8>")
	)
	(arc
		(start 98.108516 -229.26294)
		(mid 98.030405 -228.985991)
		(end 97.826068 -228.783388)
		(width 0.088646)
		(layer "In11.Cu")
		(net "M_D_CPU1_SB_DQS_DP<8>")
	)
	(arc
		(start 94.441264 -227.155502)
		(mid 94.261119 -227.205823)
		(end 94.07906 -227.162868)
		(width 0.088646)
		(layer "In11.Cu")
		(net "M_D_CPU1_SB_DQS_DP<8>")
	)
	(arc
		(start 87.770716 -226.003104)
		(mid 87.691575 -225.728481)
		(end 87.488268 -225.527616)
		(width 0.088646)
		(layer "In11.Cu")
		(net "M_D_CPU1_SB_DQS_DP<8>")
	)
	(arc
		(start 88.240616 -226.821238)
		(mid 88.162505 -226.544289)
		(end 87.958168 -226.341686)
		(width 0.088646)
		(layer "In11.Cu")
		(net "M_D_CPU1_SB_DQS_DP<8>")
	)
	(arc
		(start 97.817178 -228.778308)
		(mid 97.638581 -228.45903)
		(end 97.817178 -228.139752)
		(width 0.088646)
		(layer "In11.Cu")
		(net "M_D_CPU1_SB_DQS_DP<8>")
	)
	(arc
		(start 85.608668 -225.527616)
		(mid 85.334439 -225.451691)
		(end 85.057996 -225.51898)
		(width 0.088646)
		(layer "In11.Cu")
		(net "M_D_CPU1_SB_DQS_DP<8>")
	)
	(arc
		(start 89.352882 -227.146866)
		(mid 89.076407 -227.079546)
		(end 88.80221 -227.155502)
		(width 0.088646)
		(layer "In11.Cu")
		(net "M_D_CPU1_SB_DQS_DP<8>")
	)
	(arc
		(start 87.949278 -226.336606)
		(mid 87.818364 -226.200246)
		(end 87.770716 -226.017328)
		(width 0.088646)
		(layer "In11.Cu")
		(net "M_D_CPU1_SB_DQS_DP<8>")
	)
	(arc
		(start 88.427814 -227.155502)
		(mid 88.292881 -227.022148)
		(end 88.240616 -226.83978)
		(width 0.088646)
		(layer "In11.Cu")
		(net "M_D_CPU1_SB_DQS_DP<8>")
	)
	(arc
		(start 96.320864 -227.155502)
		(mid 96.133556 -227.205645)
		(end 95.946214 -227.155502)
		(width 0.088646)
		(layer "In11.Cu")
		(net "M_D_CPU1_SB_DQS_DP<8>")
	)
	(arc
		(start 95.381064 -227.155502)
		(mid 95.200919 -227.205823)
		(end 95.01886 -227.162868)
		(width 0.088646)
		(layer "In11.Cu")
		(net "M_D_CPU1_SB_DQS_DP<8>")
	)
	(arc
		(start 95.946214 -227.155502)
		(mid 95.663656 -227.079853)
		(end 95.381064 -227.155502)
		(width 0.088646)
		(layer "In11.Cu")
		(net "M_D_CPU1_SB_DQS_DP<8>")
	)
	(arc
		(start 90.682064 -227.155502)
		(mid 90.501919 -227.205823)
		(end 90.31986 -227.162868)
		(width 0.088646)
		(layer "In11.Cu")
		(net "M_D_CPU1_SB_DQS_DP<8>")
	)
	(arc
		(start 94.067376 -227.155756)
		(mid 93.784449 -227.079692)
		(end 93.501464 -227.155502)
		(width 0.088646)
		(layer "In11.Cu")
		(net "M_D_CPU1_SB_DQS_DP<8>")
	)
	(arc
		(start 87.488268 -225.527616)
		(mid 87.214039 -225.451691)
		(end 86.937596 -225.51898)
		(width 0.088646)
		(layer "In11.Cu")
		(net "M_D_CPU1_SB_DQS_DP<8>")
	)
	(arc
		(start 96.8756 -227.149406)
		(mid 96.597422 -227.079683)
		(end 96.320864 -227.155502)
		(width 0.088646)
		(layer "In11.Cu")
		(net "M_D_CPU1_SB_DQS_DP<8>")
	)
	(arc
		(start 90.308176 -227.155756)
		(mid 90.025249 -227.079692)
		(end 89.742264 -227.155502)
		(width 0.088646)
		(layer "In11.Cu")
		(net "M_D_CPU1_SB_DQS_DP<8>")
	)
	(arc
		(start 98.657918 -229.60457)
		(mid 98.475858 -229.64759)
		(end 98.295714 -229.597204)
		(width 0.088646)
		(layer "In11.Cu")
		(net "M_D_CPU1_SB_DQS_DP<8>")
	)
	(segment
		(start 19.784314 -208.366614)
		(end 19.294602 -208.366614)
		(width 0.20066)
		(layer "F.Cu")
		(net "M_D_CPU1_SB_DQS_DP<7>")
	)
	(segment
		(start 17.026636 -207.941926)
		(end 16.885158 -207.941926)
		(width 0.20066)
		(layer "F.Cu")
		(net "M_D_CPU1_SB_DQS_DP<7>")
	)
	(segment
		(start 16.885158 -207.941926)
		(end 16.884904 -207.941672)
		(width 0.1016)
		(layer "F.Cu")
		(net "M_D_CPU1_SB_DQS_DP<7>")
	)
	(segment
		(start 20.889214 -208.366614)
		(end 19.784314 -208.366614)
		(width 0.20066)
		(layer "F.Cu")
		(net "M_D_CPU1_SB_DQS_DP<7>")
	)
	(segment
		(start 14.362684 -207.936084)
		(end 14.09319 -208.205578)
		(width 0.20066)
		(layer "F.Cu")
		(net "M_D_CPU1_SB_DQS_DP<7>")
	)
	(segment
		(start 16.884904 -207.941672)
		(end 14.80693 -207.941672)
		(width 0.1016)
		(layer "F.Cu")
		(net "M_D_CPU1_SB_DQS_DP<7>")
	)
	(segment
		(start 19.294602 -208.366614)
		(end 19.033236 -208.62798)
		(width 0.20066)
		(layer "F.Cu")
		(net "M_D_CPU1_SB_DQS_DP<7>")
	)
	(segment
		(start 97.543112 -233.064304)
		(end 97.543366 -233.06405)
		(width 0.20066)
		(layer "F.Cu")
		(net "M_D_CPU1_SB_DQS_DP<7>")
	)
	(segment
		(start 97.543366 -233.06405)
		(end 97.543366 -232.528364)
		(width 0.20066)
		(layer "F.Cu")
		(net "M_D_CPU1_SB_DQS_DP<7>")
	)
	(segment
		(start 12.714986 -208.366614)
		(end 12.240514 -208.366614)
		(width 0.20066)
		(layer "F.Cu")
		(net "M_D_CPU1_SB_DQS_DP<7>")
	)
	(segment
		(start 14.56563 -207.941672)
		(end 14.560042 -207.936084)
		(width 0.101854)
		(layer "F.Cu")
		(net "M_D_CPU1_SB_DQS_DP<7>")
	)
	(segment
		(start 13.733018 -208.205578)
		(end 13.310616 -208.62798)
		(width 0.20066)
		(layer "F.Cu")
		(net "M_D_CPU1_SB_DQS_DP<7>")
	)
	(segment
		(start 14.560042 -207.936084)
		(end 14.362684 -207.936084)
		(width 0.20066)
		(layer "F.Cu")
		(net "M_D_CPU1_SB_DQS_DP<7>")
	)
	(segment
		(start 18.428716 -208.62798)
		(end 17.7927 -208.203038)
		(width 0.20066)
		(layer "F.Cu")
		(net "M_D_CPU1_SB_DQS_DP<7>")
	)
	(segment
		(start 13.310616 -208.62798)
		(end 12.976352 -208.62798)
		(width 0.20066)
		(layer "F.Cu")
		(net "M_D_CPU1_SB_DQS_DP<7>")
	)
	(segment
		(start 14.09319 -208.205578)
		(end 13.733018 -208.205578)
		(width 0.20066)
		(layer "F.Cu")
		(net "M_D_CPU1_SB_DQS_DP<7>")
	)
	(segment
		(start 19.033236 -208.62798)
		(end 18.428716 -208.62798)
		(width 0.20066)
		(layer "F.Cu")
		(net "M_D_CPU1_SB_DQS_DP<7>")
	)
	(segment
		(start 14.80693 -207.941672)
		(end 14.56563 -207.941672)
		(width 0.101854)
		(layer "F.Cu")
		(net "M_D_CPU1_SB_DQS_DP<7>")
	)
	(segment
		(start 12.976352 -208.62798)
		(end 12.714986 -208.366614)
		(width 0.20066)
		(layer "F.Cu")
		(net "M_D_CPU1_SB_DQS_DP<7>")
	)
	(segment
		(start 17.287748 -208.203038)
		(end 17.026636 -207.941926)
		(width 0.20066)
		(layer "F.Cu")
		(net "M_D_CPU1_SB_DQS_DP<7>")
	)
	(segment
		(start 17.7927 -208.203038)
		(end 17.287748 -208.203038)
		(width 0.20066)
		(layer "F.Cu")
		(net "M_D_CPU1_SB_DQS_DP<7>")
	)
	(segment
		(start 78.05928 -228.347524)
		(end 74.931016 -225.21926)
		(width 0.18288)
		(layer "In6.Cu")
		(net "M_D_CPU1_SB_DQS_DP<7>")
	)
	(segment
		(start 91.247214 -232.038906)
		(end 91.232482 -232.03027)
		(width 0.088646)
		(layer "In6.Cu")
		(net "M_D_CPU1_SB_DQS_DP<7>")
	)
	(segment
		(start 74.931016 -222.435166)
		(end 66.702686 -214.206836)
		(width 0.18288)
		(layer "In6.Cu")
		(net "M_D_CPU1_SB_DQS_DP<7>")
	)
	(segment
		(start 40.681148 -208.048352)
		(end 39.983156 -207.35036)
		(width 0.18288)
		(layer "In6.Cu")
		(net "M_D_CPU1_SB_DQS_DP<7>")
	)
	(segment
		(start 31.40329 -208.192116)
		(end 30.828996 -208.192116)
		(width 0.18288)
		(layer "In6.Cu")
		(net "M_D_CPU1_SB_DQS_DP<7>")
	)
	(segment
		(start 29.756354 -208.906364)
		(end 29.018992 -208.60131)
		(width 0.18288)
		(layer "In6.Cu")
		(net "M_D_CPU1_SB_DQS_DP<7>")
	)
	(segment
		(start 88.347296 -231.2162)
		(end 88.332564 -231.224836)
		(width 0.088646)
		(layer "In6.Cu")
		(net "M_D_CPU1_SB_DQS_DP<7>")
	)
	(segment
		(start 83.594194 -228.98227)
		(end 83.019392 -228.407468)
		(width 0.088646)
		(layer "In6.Cu")
		(net "M_D_CPU1_SB_DQS_DP<7>")
	)
	(segment
		(start 89.287096 -231.2162)
		(end 89.272364 -231.224836)
		(width 0.088646)
		(layer "In6.Cu")
		(net "M_D_CPU1_SB_DQS_DP<7>")
	)
	(segment
		(start 50.141632 -207.354424)
		(end 49.294796 -208.20126)
		(width 0.18288)
		(layer "In6.Cu")
		(net "M_D_CPU1_SB_DQS_DP<7>")
	)
	(segment
		(start 46.741334 -207.941672)
		(end 46.49089 -208.192116)
		(width 0.18288)
		(layer "In6.Cu")
		(net "M_D_CPU1_SB_DQS_DP<7>")
	)
	(segment
		(start 65.768982 -213.681818)
		(end 64.898016 -211.579968)
		(width 0.18288)
		(layer "In6.Cu")
		(net "M_D_CPU1_SB_DQS_DP<7>")
	)
	(segment
		(start 90.30589 -232.038144)
		(end 90.298524 -232.033826)
		(width 0.088646)
		(layer "In6.Cu")
		(net "M_D_CPU1_SB_DQS_DP<7>")
	)
	(segment
		(start 54.64302 -209.326226)
		(end 52.668932 -207.352138)
		(width 0.18288)
		(layer "In6.Cu")
		(net "M_D_CPU1_SB_DQS_DP<7>")
	)
	(segment
		(start 62.85357 -210.033616)
		(end 59.944762 -210.033616)
		(width 0.18288)
		(layer "In6.Cu")
		(net "M_D_CPU1_SB_DQS_DP<7>")
	)
	(segment
		(start 29.018992 -208.60131)
		(end 28.460192 -208.04251)
		(width 0.18288)
		(layer "In6.Cu")
		(net "M_D_CPU1_SB_DQS_DP<7>")
	)
	(segment
		(start 24.662384 -208.817464)
		(end 21.933154 -208.817464)
		(width 0.18288)
		(layer "In6.Cu")
		(net "M_D_CPU1_SB_DQS_DP<7>")
	)
	(segment
		(start 32.36214 -208.18856)
		(end 32.115252 -207.941672)
		(width 0.18288)
		(layer "In6.Cu")
		(net "M_D_CPU1_SB_DQS_DP<7>")
	)
	(segment
		(start 59.944762 -210.033616)
		(end 59.237372 -209.326226)
		(width 0.18288)
		(layer "In6.Cu")
		(net "M_D_CPU1_SB_DQS_DP<7>")
	)
	(segment
		(start 84.385912 -230.335328)
		(end 84.313776 -230.335328)
		(width 0.088646)
		(layer "In6.Cu")
		(net "M_D_CPU1_SB_DQS_DP<7>")
	)
	(segment
		(start 47.46244 -208.20126)
		(end 47.202852 -207.941672)
		(width 0.18288)
		(layer "In6.Cu")
		(net "M_D_CPU1_SB_DQS_DP<7>")
	)
	(segment
		(start 32.115252 -207.941672)
		(end 31.653734 -207.941672)
		(width 0.18288)
		(layer "In6.Cu")
		(net "M_D_CPU1_SB_DQS_DP<7>")
	)
	(segment
		(start 39.983156 -207.35036)
		(end 36.473892 -207.35036)
		(width 0.18288)
		(layer "In6.Cu")
		(net "M_D_CPU1_SB_DQS_DP<7>")
	)
	(segment
		(start 50.578766 -207.354424)
		(end 50.141632 -207.354424)
		(width 0.18288)
		(layer "In6.Cu")
		(net "M_D_CPU1_SB_DQS_DP<7>")
	)
	(segment
		(start 96.886776 -232.039414)
		(end 96.886014 -232.038906)
		(width 0.088646)
		(layer "In6.Cu")
		(net "M_D_CPU1_SB_DQS_DP<7>")
	)
	(segment
		(start 82.65541 -228.347524)
		(end 82.632042 -228.347524)
		(width 0.088646)
		(layer "In6.Cu")
		(net "M_D_CPU1_SB_DQS_DP<7>")
	)
	(segment
		(start 90.307414 -232.038906)
		(end 90.30589 -232.038144)
		(width 0.088646)
		(layer "In6.Cu")
		(net "M_D_CPU1_SB_DQS_DP<7>")
	)
	(segment
		(start 46.49089 -208.192116)
		(end 45.984414 -208.192116)
		(width 0.18288)
		(layer "In6.Cu")
		(net "M_D_CPU1_SB_DQS_DP<7>")
	)
	(segment
		(start 74.931016 -225.21926)
		(end 74.931016 -222.435166)
		(width 0.18288)
		(layer "In6.Cu")
		(net "M_D_CPU1_SB_DQS_DP<7>")
	)
	(segment
		(start 84.313776 -230.335328)
		(end 83.594194 -229.615746)
		(width 0.088646)
		(layer "In6.Cu")
		(net "M_D_CPU1_SB_DQS_DP<7>")
	)
	(segment
		(start 97.543366 -232.528364)
		(end 97.230438 -232.528364)
		(width 0.088646)
		(layer "In6.Cu")
		(net "M_D_CPU1_SB_DQS_DP<7>")
	)
	(segment
		(start 97.230438 -232.528364)
		(end 97.164906 -232.462832)
		(width 0.088646)
		(layer "In6.Cu")
		(net "M_D_CPU1_SB_DQS_DP<7>")
	)
	(segment
		(start 36.473892 -207.35036)
		(end 36.21532 -207.091788)
		(width 0.18288)
		(layer "In6.Cu")
		(net "M_D_CPU1_SB_DQS_DP<7>")
	)
	(segment
		(start 82.632042 -228.347524)
		(end 78.05928 -228.347524)
		(width 0.18288)
		(layer "In6.Cu")
		(net "M_D_CPU1_SB_DQS_DP<7>")
	)
	(segment
		(start 45.984414 -208.192116)
		(end 45.420788 -207.62849)
		(width 0.18288)
		(layer "In6.Cu")
		(net "M_D_CPU1_SB_DQS_DP<7>")
	)
	(segment
		(start 28.460192 -208.04251)
		(end 25.437338 -208.04251)
		(width 0.18288)
		(layer "In6.Cu")
		(net "M_D_CPU1_SB_DQS_DP<7>")
	)
	(segment
		(start 35.503358 -207.342232)
		(end 34.638996 -207.342232)
		(width 0.18288)
		(layer "In6.Cu")
		(net "M_D_CPU1_SB_DQS_DP<7>")
	)
	(segment
		(start 51.56327 -207.352138)
		(end 51.30292 -207.091788)
		(width 0.18288)
		(layer "In6.Cu")
		(net "M_D_CPU1_SB_DQS_DP<7>")
	)
	(segment
		(start 85.891116 -230.900732)
		(end 85.891116 -230.890826)
		(width 0.088646)
		(layer "In6.Cu")
		(net "M_D_CPU1_SB_DQS_DP<7>")
	)
	(segment
		(start 64.898016 -211.579968)
		(end 64.055498 -210.73745)
		(width 0.18288)
		(layer "In6.Cu")
		(net "M_D_CPU1_SB_DQS_DP<7>")
	)
	(segment
		(start 30.114748 -208.906364)
		(end 29.756354 -208.906364)
		(width 0.18288)
		(layer "In6.Cu")
		(net "M_D_CPU1_SB_DQS_DP<7>")
	)
	(segment
		(start 64.055498 -210.73745)
		(end 63.557404 -210.73745)
		(width 0.18288)
		(layer "In6.Cu")
		(net "M_D_CPU1_SB_DQS_DP<7>")
	)
	(segment
		(start 95.006414 -232.038906)
		(end 94.996 -232.03281)
		(width 0.088646)
		(layer "In6.Cu")
		(net "M_D_CPU1_SB_DQS_DP<7>")
	)
	(segment
		(start 94.066868 -232.038906)
		(end 94.056454 -232.03281)
		(width 0.088646)
		(layer "In6.Cu")
		(net "M_D_CPU1_SB_DQS_DP<7>")
	)
	(segment
		(start 21.155406 -208.632806)
		(end 20.889214 -208.366614)
		(width 0.18288)
		(layer "In6.Cu")
		(net "M_D_CPU1_SB_DQS_DP<7>")
	)
	(segment
		(start 52.668932 -207.352138)
		(end 51.56327 -207.352138)
		(width 0.18288)
		(layer "In6.Cu")
		(net "M_D_CPU1_SB_DQS_DP<7>")
	)
	(segment
		(start 96.886014 -232.038906)
		(end 96.871282 -232.03027)
		(width 0.088646)
		(layer "In6.Cu")
		(net "M_D_CPU1_SB_DQS_DP<7>")
	)
	(segment
		(start 35.753802 -207.091788)
		(end 35.503358 -207.342232)
		(width 0.18288)
		(layer "In6.Cu")
		(net "M_D_CPU1_SB_DQS_DP<7>")
	)
	(segment
		(start 87.40648 -231.216962)
		(end 87.392764 -231.22509)
		(width 0.088646)
		(layer "In6.Cu")
		(net "M_D_CPU1_SB_DQS_DP<7>")
	)
	(segment
		(start 51.30292 -207.091788)
		(end 50.841402 -207.091788)
		(width 0.18288)
		(layer "In6.Cu")
		(net "M_D_CPU1_SB_DQS_DP<7>")
	)
	(segment
		(start 34.638996 -207.342232)
		(end 33.792668 -208.18856)
		(width 0.18288)
		(layer "In6.Cu")
		(net "M_D_CPU1_SB_DQS_DP<7>")
	)
	(segment
		(start 30.828996 -208.192116)
		(end 30.114748 -208.906364)
		(width 0.18288)
		(layer "In6.Cu")
		(net "M_D_CPU1_SB_DQS_DP<7>")
	)
	(segment
		(start 44.32427 -207.62849)
		(end 43.904408 -208.048352)
		(width 0.18288)
		(layer "In6.Cu")
		(net "M_D_CPU1_SB_DQS_DP<7>")
	)
	(segment
		(start 31.653734 -207.941672)
		(end 31.40329 -208.192116)
		(width 0.18288)
		(layer "In6.Cu")
		(net "M_D_CPU1_SB_DQS_DP<7>")
	)
	(segment
		(start 66.294 -214.206836)
		(end 65.768982 -213.681818)
		(width 0.18288)
		(layer "In6.Cu")
		(net "M_D_CPU1_SB_DQS_DP<7>")
	)
	(segment
		(start 63.557404 -210.73745)
		(end 62.85357 -210.033616)
		(width 0.18288)
		(layer "In6.Cu")
		(net "M_D_CPU1_SB_DQS_DP<7>")
	)
	(segment
		(start 50.841402 -207.091788)
		(end 50.578766 -207.354424)
		(width 0.18288)
		(layer "In6.Cu")
		(net "M_D_CPU1_SB_DQS_DP<7>")
	)
	(segment
		(start 90.119962 -231.714548)
		(end 90.119962 -231.69245)
		(width 0.088646)
		(layer "In6.Cu")
		(net "M_D_CPU1_SB_DQS_DP<7>")
	)
	(segment
		(start 82.715354 -228.407468)
		(end 82.65541 -228.347524)
		(width 0.088646)
		(layer "In6.Cu")
		(net "M_D_CPU1_SB_DQS_DP<7>")
	)
	(segment
		(start 49.294796 -208.20126)
		(end 47.46244 -208.20126)
		(width 0.18288)
		(layer "In6.Cu")
		(net "M_D_CPU1_SB_DQS_DP<7>")
	)
	(segment
		(start 93.126814 -232.038906)
		(end 93.112082 -232.03027)
		(width 0.088646)
		(layer "In6.Cu")
		(net "M_D_CPU1_SB_DQS_DP<7>")
	)
	(segment
		(start 33.792668 -208.18856)
		(end 32.36214 -208.18856)
		(width 0.18288)
		(layer "In6.Cu")
		(net "M_D_CPU1_SB_DQS_DP<7>")
	)
	(segment
		(start 36.21532 -207.091788)
		(end 35.753802 -207.091788)
		(width 0.18288)
		(layer "In6.Cu")
		(net "M_D_CPU1_SB_DQS_DP<7>")
	)
	(segment
		(start 59.237372 -209.326226)
		(end 54.64302 -209.326226)
		(width 0.18288)
		(layer "In6.Cu")
		(net "M_D_CPU1_SB_DQS_DP<7>")
	)
	(segment
		(start 21.933154 -208.817464)
		(end 21.748496 -208.632806)
		(width 0.18288)
		(layer "In6.Cu")
		(net "M_D_CPU1_SB_DQS_DP<7>")
	)
	(segment
		(start 45.420788 -207.62849)
		(end 44.32427 -207.62849)
		(width 0.18288)
		(layer "In6.Cu")
		(net "M_D_CPU1_SB_DQS_DP<7>")
	)
	(segment
		(start 95.946214 -232.038906)
		(end 95.931482 -232.03027)
		(width 0.088646)
		(layer "In6.Cu")
		(net "M_D_CPU1_SB_DQS_DP<7>")
	)
	(segment
		(start 96.89211 -232.042462)
		(end 96.886776 -232.039414)
		(width 0.088646)
		(layer "In6.Cu")
		(net "M_D_CPU1_SB_DQS_DP<7>")
	)
	(segment
		(start 66.702686 -214.206836)
		(end 66.294 -214.206836)
		(width 0.18288)
		(layer "In6.Cu")
		(net "M_D_CPU1_SB_DQS_DP<7>")
	)
	(segment
		(start 83.019392 -228.407468)
		(end 82.715354 -228.407468)
		(width 0.088646)
		(layer "In6.Cu")
		(net "M_D_CPU1_SB_DQS_DP<7>")
	)
	(segment
		(start 83.594194 -229.615746)
		(end 83.594194 -228.98227)
		(width 0.088646)
		(layer "In6.Cu")
		(net "M_D_CPU1_SB_DQS_DP<7>")
	)
	(segment
		(start 43.904408 -208.048352)
		(end 40.681148 -208.048352)
		(width 0.18288)
		(layer "In6.Cu")
		(net "M_D_CPU1_SB_DQS_DP<7>")
	)
	(segment
		(start 25.437338 -208.04251)
		(end 24.662384 -208.817464)
		(width 0.18288)
		(layer "In6.Cu")
		(net "M_D_CPU1_SB_DQS_DP<7>")
	)
	(segment
		(start 21.748496 -208.632806)
		(end 21.155406 -208.632806)
		(width 0.18288)
		(layer "In6.Cu")
		(net "M_D_CPU1_SB_DQS_DP<7>")
	)
	(segment
		(start 47.202852 -207.941672)
		(end 46.741334 -207.941672)
		(width 0.18288)
		(layer "In6.Cu")
		(net "M_D_CPU1_SB_DQS_DP<7>")
	)
	(arc
		(start 94.441264 -232.038906)
		(mid 94.254066 -232.089049)
		(end 94.066868 -232.038906)
		(width 0.088646)
		(layer "In6.Cu")
		(net "M_D_CPU1_SB_DQS_DP<7>")
	)
	(arc
		(start 94.056454 -232.03281)
		(mid 93.778022 -231.962964)
		(end 93.50121 -232.038906)
		(width 0.088646)
		(layer "In6.Cu")
		(net "M_D_CPU1_SB_DQS_DP<7>")
	)
	(arc
		(start 91.62161 -232.038906)
		(mid 91.434412 -232.089049)
		(end 91.247214 -232.038906)
		(width 0.088646)
		(layer "In6.Cu")
		(net "M_D_CPU1_SB_DQS_DP<7>")
	)
	(arc
		(start 87.392764 -231.22509)
		(mid 87.205566 -231.275233)
		(end 87.018368 -231.22509)
		(width 0.088646)
		(layer "In6.Cu")
		(net "M_D_CPU1_SB_DQS_DP<7>")
	)
	(arc
		(start 90.298524 -232.033826)
		(mid 90.16761 -231.897466)
		(end 90.119962 -231.714548)
		(width 0.088646)
		(layer "In6.Cu")
		(net "M_D_CPU1_SB_DQS_DP<7>")
	)
	(arc
		(start 87.018368 -231.22509)
		(mid 86.735666 -231.149314)
		(end 86.452964 -231.22509)
		(width 0.088646)
		(layer "In6.Cu")
		(net "M_D_CPU1_SB_DQS_DP<7>")
	)
	(arc
		(start 86.452964 -231.22509)
		(mid 86.078489 -231.225044)
		(end 85.891116 -230.900732)
		(width 0.088646)
		(layer "In6.Cu")
		(net "M_D_CPU1_SB_DQS_DP<7>")
	)
	(arc
		(start 96.32061 -232.038906)
		(mid 96.133412 -232.089049)
		(end 95.946214 -232.038906)
		(width 0.088646)
		(layer "In6.Cu")
		(net "M_D_CPU1_SB_DQS_DP<7>")
	)
	(arc
		(start 87.958168 -231.224836)
		(mid 87.683341 -231.149025)
		(end 87.40648 -231.216962)
		(width 0.088646)
		(layer "In6.Cu")
		(net "M_D_CPU1_SB_DQS_DP<7>")
	)
	(arc
		(start 97.164906 -232.462832)
		(mid 97.077662 -232.220744)
		(end 96.89211 -232.042462)
		(width 0.088646)
		(layer "In6.Cu")
		(net "M_D_CPU1_SB_DQS_DP<7>")
	)
	(arc
		(start 89.272364 -231.224836)
		(mid 89.085166 -231.274979)
		(end 88.897968 -231.224836)
		(width 0.088646)
		(layer "In6.Cu")
		(net "M_D_CPU1_SB_DQS_DP<7>")
	)
	(arc
		(start 93.50121 -232.038906)
		(mid 93.314012 -232.089049)
		(end 93.126814 -232.038906)
		(width 0.088646)
		(layer "In6.Cu")
		(net "M_D_CPU1_SB_DQS_DP<7>")
	)
	(arc
		(start 95.931482 -232.03027)
		(mid 95.655007 -231.96295)
		(end 95.38081 -232.038906)
		(width 0.088646)
		(layer "In6.Cu")
		(net "M_D_CPU1_SB_DQS_DP<7>")
	)
	(arc
		(start 91.232482 -232.03027)
		(mid 90.956007 -231.96295)
		(end 90.68181 -232.038906)
		(width 0.088646)
		(layer "In6.Cu")
		(net "M_D_CPU1_SB_DQS_DP<7>")
	)
	(arc
		(start 85.891116 -230.890826)
		(mid 85.604241 -230.408741)
		(end 85.043264 -230.411274)
		(width 0.088646)
		(layer "In6.Cu")
		(net "M_D_CPU1_SB_DQS_DP<7>")
	)
	(arc
		(start 96.871282 -232.03027)
		(mid 96.594807 -231.96295)
		(end 96.32061 -232.038906)
		(width 0.088646)
		(layer "In6.Cu")
		(net "M_D_CPU1_SB_DQS_DP<7>")
	)
	(arc
		(start 88.897968 -231.224836)
		(mid 88.623739 -231.148911)
		(end 88.347296 -231.2162)
		(width 0.088646)
		(layer "In6.Cu")
		(net "M_D_CPU1_SB_DQS_DP<7>")
	)
	(arc
		(start 93.112082 -232.03027)
		(mid 92.835607 -231.96295)
		(end 92.56141 -232.038906)
		(width 0.088646)
		(layer "In6.Cu")
		(net "M_D_CPU1_SB_DQS_DP<7>")
	)
	(arc
		(start 90.119962 -231.69245)
		(mid 89.835531 -231.223549)
		(end 89.287096 -231.2162)
		(width 0.088646)
		(layer "In6.Cu")
		(net "M_D_CPU1_SB_DQS_DP<7>")
	)
	(arc
		(start 90.68181 -232.038906)
		(mid 90.494612 -232.089049)
		(end 90.307414 -232.038906)
		(width 0.088646)
		(layer "In6.Cu")
		(net "M_D_CPU1_SB_DQS_DP<7>")
	)
	(arc
		(start 94.996 -232.03281)
		(mid 94.717822 -231.963087)
		(end 94.441264 -232.038906)
		(width 0.088646)
		(layer "In6.Cu")
		(net "M_D_CPU1_SB_DQS_DP<7>")
	)
	(arc
		(start 85.043264 -230.411274)
		(mid 84.856066 -230.461417)
		(end 84.668868 -230.411274)
		(width 0.088646)
		(layer "In6.Cu")
		(net "M_D_CPU1_SB_DQS_DP<7>")
	)
	(arc
		(start 95.38081 -232.038906)
		(mid 95.193612 -232.089049)
		(end 95.006414 -232.038906)
		(width 0.088646)
		(layer "In6.Cu")
		(net "M_D_CPU1_SB_DQS_DP<7>")
	)
	(arc
		(start 84.668868 -230.411274)
		(mid 84.532396 -230.354651)
		(end 84.385912 -230.335328)
		(width 0.088646)
		(layer "In6.Cu")
		(net "M_D_CPU1_SB_DQS_DP<7>")
	)
	(arc
		(start 92.56141 -232.038906)
		(mid 92.374212 -232.089049)
		(end 92.187014 -232.038906)
		(width 0.088646)
		(layer "In6.Cu")
		(net "M_D_CPU1_SB_DQS_DP<7>")
	)
	(arc
		(start 92.187014 -232.038906)
		(mid 91.904312 -231.96313)
		(end 91.62161 -232.038906)
		(width 0.088646)
		(layer "In6.Cu")
		(net "M_D_CPU1_SB_DQS_DP<7>")
	)
	(arc
		(start 88.332564 -231.224836)
		(mid 88.145366 -231.274979)
		(end 87.958168 -231.224836)
		(width 0.088646)
		(layer "In6.Cu")
		(net "M_D_CPU1_SB_DQS_DP<7>")
	)
	(segment
		(start 16.884904 -217.291666)
		(end 14.80693 -217.291666)
		(width 0.1016)
		(layer "F.Cu")
		(net "M_D_CPU1_SB_DQS_DP<6>")
	)
	(segment
		(start 17.287748 -217.553032)
		(end 17.026636 -217.29192)
		(width 0.20066)
		(layer "F.Cu")
		(net "M_D_CPU1_SB_DQS_DP<6>")
	)
	(segment
		(start 12.714986 -217.716608)
		(end 12.240514 -217.716608)
		(width 0.20066)
		(layer "F.Cu")
		(net "M_D_CPU1_SB_DQS_DP<6>")
	)
	(segment
		(start 16.885158 -217.29192)
		(end 16.884904 -217.291666)
		(width 0.1016)
		(layer "F.Cu")
		(net "M_D_CPU1_SB_DQS_DP<6>")
	)
	(segment
		(start 14.560042 -217.286078)
		(end 14.362684 -217.286078)
		(width 0.20066)
		(layer "F.Cu")
		(net "M_D_CPU1_SB_DQS_DP<6>")
	)
	(segment
		(start 100.832666 -235.506006)
		(end 100.832666 -234.97032)
		(width 0.20066)
		(layer "F.Cu")
		(net "M_D_CPU1_SB_DQS_DP<6>")
	)
	(segment
		(start 20.889214 -217.716608)
		(end 19.784314 -217.716608)
		(width 0.20066)
		(layer "F.Cu")
		(net "M_D_CPU1_SB_DQS_DP<6>")
	)
	(segment
		(start 14.56563 -217.291666)
		(end 14.560042 -217.286078)
		(width 0.101854)
		(layer "F.Cu")
		(net "M_D_CPU1_SB_DQS_DP<6>")
	)
	(segment
		(start 14.80693 -217.291666)
		(end 14.56563 -217.291666)
		(width 0.101854)
		(layer "F.Cu")
		(net "M_D_CPU1_SB_DQS_DP<6>")
	)
	(segment
		(start 17.7927 -217.553032)
		(end 17.287748 -217.553032)
		(width 0.20066)
		(layer "F.Cu")
		(net "M_D_CPU1_SB_DQS_DP<6>")
	)
	(segment
		(start 19.033236 -217.977974)
		(end 18.428716 -217.977974)
		(width 0.20066)
		(layer "F.Cu")
		(net "M_D_CPU1_SB_DQS_DP<6>")
	)
	(segment
		(start 13.733018 -217.555572)
		(end 13.310616 -217.977974)
		(width 0.20066)
		(layer "F.Cu")
		(net "M_D_CPU1_SB_DQS_DP<6>")
	)
	(segment
		(start 18.428716 -217.977974)
		(end 17.7927 -217.553032)
		(width 0.20066)
		(layer "F.Cu")
		(net "M_D_CPU1_SB_DQS_DP<6>")
	)
	(segment
		(start 19.784314 -217.716608)
		(end 19.294602 -217.716608)
		(width 0.20066)
		(layer "F.Cu")
		(net "M_D_CPU1_SB_DQS_DP<6>")
	)
	(segment
		(start 19.294602 -217.716608)
		(end 19.033236 -217.977974)
		(width 0.20066)
		(layer "F.Cu")
		(net "M_D_CPU1_SB_DQS_DP<6>")
	)
	(segment
		(start 17.026636 -217.29192)
		(end 16.885158 -217.29192)
		(width 0.20066)
		(layer "F.Cu")
		(net "M_D_CPU1_SB_DQS_DP<6>")
	)
	(segment
		(start 12.976352 -217.977974)
		(end 12.714986 -217.716608)
		(width 0.20066)
		(layer "F.Cu")
		(net "M_D_CPU1_SB_DQS_DP<6>")
	)
	(segment
		(start 13.310616 -217.977974)
		(end 12.976352 -217.977974)
		(width 0.20066)
		(layer "F.Cu")
		(net "M_D_CPU1_SB_DQS_DP<6>")
	)
	(segment
		(start 100.832666 -234.97032)
		(end 100.832412 -234.970066)
		(width 0.20066)
		(layer "F.Cu")
		(net "M_D_CPU1_SB_DQS_DP<6>")
	)
	(segment
		(start 14.09319 -217.555572)
		(end 13.733018 -217.555572)
		(width 0.20066)
		(layer "F.Cu")
		(net "M_D_CPU1_SB_DQS_DP<6>")
	)
	(segment
		(start 14.362684 -217.286078)
		(end 14.09319 -217.555572)
		(width 0.20066)
		(layer "F.Cu")
		(net "M_D_CPU1_SB_DQS_DP<6>")
	)
	(segment
		(start 49.900332 -209.961226)
		(end 49.08677 -210.774788)
		(width 0.18288)
		(layer "In11.Cu")
		(net "M_D_CPU1_SB_DQS_DP<6>")
	)
	(segment
		(start 62.102746 -213.485984)
		(end 60.228226 -211.611464)
		(width 0.18288)
		(layer "In11.Cu")
		(net "M_D_CPU1_SB_DQS_DP<6>")
	)
	(segment
		(start 66.594736 -214.473536)
		(end 66.122042 -214.277702)
		(width 0.18288)
		(layer "In11.Cu")
		(net "M_D_CPU1_SB_DQS_DP<6>")
	)
	(segment
		(start 44.302172 -211.390992)
		(end 43.738292 -210.827112)
		(width 0.18288)
		(layer "In11.Cu")
		(net "M_D_CPU1_SB_DQS_DP<6>")
	)
	(segment
		(start 68.08724 -215.965532)
		(end 66.594736 -214.473536)
		(width 0.18288)
		(layer "In11.Cu")
		(net "M_D_CPU1_SB_DQS_DP<6>")
	)
	(segment
		(start 94.921324 -234.474512)
		(end 94.91091 -234.480608)
		(width 0.088646)
		(layer "In11.Cu")
		(net "M_D_CPU1_SB_DQS_DP<6>")
	)
	(segment
		(start 93.131132 -232.041446)
		(end 93.1291 -232.040176)
		(width 0.088646)
		(layer "In11.Cu")
		(net "M_D_CPU1_SB_DQS_DP<6>")
	)
	(segment
		(start 94.349316 -234.15625)
		(end 94.349316 -234.155996)
		(width 0.088646)
		(layer "In11.Cu")
		(net "M_D_CPU1_SB_DQS_DP<6>")
	)
	(segment
		(start 36.4744 -209.933794)
		(end 36.182554 -209.641948)
		(width 0.18288)
		(layer "In11.Cu")
		(net "M_D_CPU1_SB_DQS_DP<6>")
	)
	(segment
		(start 30.969966 -210.787996)
		(end 30.341824 -210.159854)
		(width 0.18288)
		(layer "In11.Cu")
		(net "M_D_CPU1_SB_DQS_DP<6>")
	)
	(segment
		(start 34.694368 -209.939128)
		(end 33.867344 -210.766152)
		(width 0.18288)
		(layer "In11.Cu")
		(net "M_D_CPU1_SB_DQS_DP<6>")
	)
	(segment
		(start 93.1291 -232.040176)
		(end 93.126814 -232.038906)
		(width 0.088646)
		(layer "In11.Cu")
		(net "M_D_CPU1_SB_DQS_DP<6>")
	)
	(segment
		(start 21.886418 -218.209876)
		(end 21.661374 -217.984832)
		(width 0.18288)
		(layer "In11.Cu")
		(net "M_D_CPU1_SB_DQS_DP<6>")
	)
	(segment
		(start 82.43316 -230.30307)
		(end 82.37347 -230.24338)
		(width 0.088646)
		(layer "In11.Cu")
		(net "M_D_CPU1_SB_DQS_DP<6>")
	)
	(segment
		(start 93.596968 -232.852722)
		(end 93.588078 -232.847642)
		(width 0.088646)
		(layer "In11.Cu")
		(net "M_D_CPU1_SB_DQS_DP<6>")
	)
	(segment
		(start 58.79211 -211.016596)
		(end 57.112662 -211.016596)
		(width 0.18288)
		(layer "In11.Cu")
		(net "M_D_CPU1_SB_DQS_DP<6>")
	)
	(segment
		(start 82.775298 -230.30307)
		(end 82.43316 -230.30307)
		(width 0.088646)
		(layer "In11.Cu")
		(net "M_D_CPU1_SB_DQS_DP<6>")
	)
	(segment
		(start 69.301868 -218.899486)
		(end 68.08724 -215.965532)
		(width 0.18288)
		(layer "In11.Cu")
		(net "M_D_CPU1_SB_DQS_DP<6>")
	)
	(segment
		(start 57.112662 -211.016596)
		(end 54.385972 -209.886804)
		(width 0.18288)
		(layer "In11.Cu")
		(net "M_D_CPU1_SB_DQS_DP<6>")
	)
	(segment
		(start 85.057996 -232.03027)
		(end 85.043264 -232.038906)
		(width 0.088646)
		(layer "In11.Cu")
		(net "M_D_CPU1_SB_DQS_DP<6>")
	)
	(segment
		(start 33.867344 -210.766152)
		(end 32.366966 -210.766152)
		(width 0.18288)
		(layer "In11.Cu")
		(net "M_D_CPU1_SB_DQS_DP<6>")
	)
	(segment
		(start 41.214802 -210.827112)
		(end 39.05885 -209.933794)
		(width 0.18288)
		(layer "In11.Cu")
		(net "M_D_CPU1_SB_DQS_DP<6>")
	)
	(segment
		(start 28.01493 -210.814412)
		(end 26.594308 -212.23478)
		(width 0.18288)
		(layer "In11.Cu")
		(net "M_D_CPU1_SB_DQS_DP<6>")
	)
	(segment
		(start 45.0596 -211.390992)
		(end 44.302172 -211.390992)
		(width 0.18288)
		(layer "In11.Cu")
		(net "M_D_CPU1_SB_DQS_DP<6>")
	)
	(segment
		(start 82.37347 -230.24338)
		(end 80.645762 -230.24338)
		(width 0.18288)
		(layer "In11.Cu")
		(net "M_D_CPU1_SB_DQS_DP<6>")
	)
	(segment
		(start 26.035254 -212.466682)
		(end 25.427686 -213.07425)
		(width 0.18288)
		(layer "In11.Cu")
		(net "M_D_CPU1_SB_DQS_DP<6>")
	)
	(segment
		(start 47.465742 -210.774788)
		(end 47.18177 -210.490816)
		(width 0.18288)
		(layer "In11.Cu")
		(net "M_D_CPU1_SB_DQS_DP<6>")
	)
	(segment
		(start 89.38006 -232.046272)
		(end 89.368376 -232.03916)
		(width 0.088646)
		(layer "In11.Cu")
		(net "M_D_CPU1_SB_DQS_DP<6>")
	)
	(segment
		(start 22.742398 -218.037664)
		(end 22.326092 -218.209876)
		(width 0.18288)
		(layer "In11.Cu")
		(net "M_D_CPU1_SB_DQS_DP<6>")
	)
	(segment
		(start 25.427686 -215.661748)
		(end 25.19934 -216.212674)
		(width 0.18288)
		(layer "In11.Cu")
		(net "M_D_CPU1_SB_DQS_DP<6>")
	)
	(segment
		(start 51.53533 -209.886804)
		(end 51.290474 -209.641948)
		(width 0.18288)
		(layer "In11.Cu")
		(net "M_D_CPU1_SB_DQS_DP<6>")
	)
	(segment
		(start 51.290474 -209.641948)
		(end 50.842418 -209.641948)
		(width 0.18288)
		(layer "In11.Cu")
		(net "M_D_CPU1_SB_DQS_DP<6>")
	)
	(segment
		(start 90.31986 -232.046272)
		(end 90.308176 -232.03916)
		(width 0.088646)
		(layer "In11.Cu")
		(net "M_D_CPU1_SB_DQS_DP<6>")
	)
	(segment
		(start 39.05885 -209.933794)
		(end 36.4744 -209.933794)
		(width 0.18288)
		(layer "In11.Cu")
		(net "M_D_CPU1_SB_DQS_DP<6>")
	)
	(segment
		(start 54.385972 -209.886804)
		(end 51.53533 -209.886804)
		(width 0.18288)
		(layer "In11.Cu")
		(net "M_D_CPU1_SB_DQS_DP<6>")
	)
	(segment
		(start 25.19934 -216.212674)
		(end 24.922226 -216.489534)
		(width 0.18288)
		(layer "In11.Cu")
		(net "M_D_CPU1_SB_DQS_DP<6>")
	)
	(segment
		(start 60.228226 -211.611464)
		(end 58.79211 -211.016596)
		(width 0.18288)
		(layer "In11.Cu")
		(net "M_D_CPU1_SB_DQS_DP<6>")
	)
	(segment
		(start 93.13291 -232.042462)
		(end 93.131132 -232.041446)
		(width 0.088646)
		(layer "In11.Cu")
		(net "M_D_CPU1_SB_DQS_DP<6>")
	)
	(segment
		(start 97.745296 -234.471972)
		(end 97.730564 -234.480608)
		(width 0.088646)
		(layer "In11.Cu")
		(net "M_D_CPU1_SB_DQS_DP<6>")
	)
	(segment
		(start 22.326092 -218.209876)
		(end 21.886418 -218.209876)
		(width 0.18288)
		(layer "In11.Cu")
		(net "M_D_CPU1_SB_DQS_DP<6>")
	)
	(segment
		(start 94.066614 -233.666538)
		(end 94.057724 -233.661458)
		(width 0.088646)
		(layer "In11.Cu")
		(net "M_D_CPU1_SB_DQS_DP<6>")
	)
	(segment
		(start 83.633564 -231.161336)
		(end 82.775298 -230.30307)
		(width 0.088646)
		(layer "In11.Cu")
		(net "M_D_CPU1_SB_DQS_DP<6>")
	)
	(segment
		(start 32.366966 -210.766152)
		(end 32.09163 -210.490816)
		(width 0.18288)
		(layer "In11.Cu")
		(net "M_D_CPU1_SB_DQS_DP<6>")
	)
	(segment
		(start 43.738292 -210.827112)
		(end 41.214802 -210.827112)
		(width 0.18288)
		(layer "In11.Cu")
		(net "M_D_CPU1_SB_DQS_DP<6>")
	)
	(segment
		(start 46.756066 -210.490816)
		(end 46.462188 -210.784694)
		(width 0.18288)
		(layer "In11.Cu")
		(net "M_D_CPU1_SB_DQS_DP<6>")
	)
	(segment
		(start 24.922226 -216.489534)
		(end 23.843488 -216.936574)
		(width 0.18288)
		(layer "In11.Cu")
		(net "M_D_CPU1_SB_DQS_DP<6>")
	)
	(segment
		(start 46.462188 -210.784694)
		(end 45.665898 -210.784694)
		(width 0.18288)
		(layer "In11.Cu")
		(net "M_D_CPU1_SB_DQS_DP<6>")
	)
	(segment
		(start 29.129228 -210.159854)
		(end 28.47467 -210.814412)
		(width 0.18288)
		(layer "In11.Cu")
		(net "M_D_CPU1_SB_DQS_DP<6>")
	)
	(segment
		(start 21.661374 -217.984832)
		(end 21.157438 -217.984832)
		(width 0.18288)
		(layer "In11.Cu")
		(net "M_D_CPU1_SB_DQS_DP<6>")
	)
	(segment
		(start 88.44026 -232.046272)
		(end 88.428576 -232.03916)
		(width 0.088646)
		(layer "In11.Cu")
		(net "M_D_CPU1_SB_DQS_DP<6>")
	)
	(segment
		(start 100.832412 -234.970066)
		(end 100.519484 -234.970066)
		(width 0.088646)
		(layer "In11.Cu")
		(net "M_D_CPU1_SB_DQS_DP<6>")
	)
	(segment
		(start 30.341824 -210.159854)
		(end 29.129228 -210.159854)
		(width 0.18288)
		(layer "In11.Cu")
		(net "M_D_CPU1_SB_DQS_DP<6>")
	)
	(segment
		(start 93.879162 -233.34218)
		(end 93.879162 -233.326686)
		(width 0.088646)
		(layer "In11.Cu")
		(net "M_D_CPU1_SB_DQS_DP<6>")
	)
	(segment
		(start 47.18177 -210.490816)
		(end 46.756066 -210.490816)
		(width 0.18288)
		(layer "In11.Cu")
		(net "M_D_CPU1_SB_DQS_DP<6>")
	)
	(segment
		(start 36.182554 -209.641948)
		(end 35.775138 -209.641948)
		(width 0.18288)
		(layer "In11.Cu")
		(net "M_D_CPU1_SB_DQS_DP<6>")
	)
	(segment
		(start 88.428576 -232.03916)
		(end 88.427814 -232.038906)
		(width 0.088646)
		(layer "In11.Cu")
		(net "M_D_CPU1_SB_DQS_DP<6>")
	)
	(segment
		(start 25.427686 -213.07425)
		(end 25.427686 -215.661748)
		(width 0.18288)
		(layer "In11.Cu")
		(net "M_D_CPU1_SB_DQS_DP<6>")
	)
	(segment
		(start 35.775138 -209.641948)
		(end 35.477958 -209.939128)
		(width 0.18288)
		(layer "In11.Cu")
		(net "M_D_CPU1_SB_DQS_DP<6>")
	)
	(segment
		(start 45.665898 -210.784694)
		(end 45.0596 -211.390992)
		(width 0.18288)
		(layer "In11.Cu")
		(net "M_D_CPU1_SB_DQS_DP<6>")
	)
	(segment
		(start 83.936332 -231.96296)
		(end 83.633564 -231.660192)
		(width 0.088646)
		(layer "In11.Cu")
		(net "M_D_CPU1_SB_DQS_DP<6>")
	)
	(segment
		(start 99.624896 -234.471972)
		(end 99.610164 -234.480608)
		(width 0.088646)
		(layer "In11.Cu")
		(net "M_D_CPU1_SB_DQS_DP<6>")
	)
	(segment
		(start 32.09163 -210.490816)
		(end 31.665926 -210.490816)
		(width 0.18288)
		(layer "In11.Cu")
		(net "M_D_CPU1_SB_DQS_DP<6>")
	)
	(segment
		(start 50.842418 -209.641948)
		(end 50.52314 -209.961226)
		(width 0.18288)
		(layer "In11.Cu")
		(net "M_D_CPU1_SB_DQS_DP<6>")
	)
	(segment
		(start 95.865696 -234.471972)
		(end 95.850964 -234.480608)
		(width 0.088646)
		(layer "In11.Cu")
		(net "M_D_CPU1_SB_DQS_DP<6>")
	)
	(segment
		(start 64.013334 -214.277702)
		(end 62.102746 -213.485984)
		(width 0.18288)
		(layer "In11.Cu")
		(net "M_D_CPU1_SB_DQS_DP<6>")
	)
	(segment
		(start 26.594308 -212.23478)
		(end 26.035254 -212.466682)
		(width 0.18288)
		(layer "In11.Cu")
		(net "M_D_CPU1_SB_DQS_DP<6>")
	)
	(segment
		(start 28.47467 -210.814412)
		(end 28.01493 -210.814412)
		(width 0.18288)
		(layer "In11.Cu")
		(net "M_D_CPU1_SB_DQS_DP<6>")
	)
	(segment
		(start 100.519484 -234.970066)
		(end 100.454206 -234.904788)
		(width 0.088646)
		(layer "In11.Cu")
		(net "M_D_CPU1_SB_DQS_DP<6>")
	)
	(segment
		(start 80.645762 -230.24338)
		(end 69.301868 -218.899486)
		(width 0.18288)
		(layer "In11.Cu")
		(net "M_D_CPU1_SB_DQS_DP<6>")
	)
	(segment
		(start 31.368746 -210.787996)
		(end 30.969966 -210.787996)
		(width 0.18288)
		(layer "In11.Cu")
		(net "M_D_CPU1_SB_DQS_DP<6>")
	)
	(segment
		(start 50.52314 -209.961226)
		(end 49.900332 -209.961226)
		(width 0.18288)
		(layer "In11.Cu")
		(net "M_D_CPU1_SB_DQS_DP<6>")
	)
	(segment
		(start 23.843488 -216.936574)
		(end 22.742398 -218.037664)
		(width 0.18288)
		(layer "In11.Cu")
		(net "M_D_CPU1_SB_DQS_DP<6>")
	)
	(segment
		(start 93.126814 -232.038906)
		(end 93.112082 -232.03027)
		(width 0.088646)
		(layer "In11.Cu")
		(net "M_D_CPU1_SB_DQS_DP<6>")
	)
	(segment
		(start 21.157438 -217.984832)
		(end 20.889214 -217.716608)
		(width 0.18288)
		(layer "In11.Cu")
		(net "M_D_CPU1_SB_DQS_DP<6>")
	)
	(segment
		(start 84.385912 -231.96296)
		(end 83.936332 -231.96296)
		(width 0.088646)
		(layer "In11.Cu")
		(net "M_D_CPU1_SB_DQS_DP<6>")
	)
	(segment
		(start 66.122042 -214.277702)
		(end 64.013334 -214.277702)
		(width 0.18288)
		(layer "In11.Cu")
		(net "M_D_CPU1_SB_DQS_DP<6>")
	)
	(segment
		(start 88.427814 -232.038906)
		(end 88.4174 -232.03281)
		(width 0.088646)
		(layer "In11.Cu")
		(net "M_D_CPU1_SB_DQS_DP<6>")
	)
	(segment
		(start 83.633564 -231.660192)
		(end 83.633564 -231.161336)
		(width 0.088646)
		(layer "In11.Cu")
		(net "M_D_CPU1_SB_DQS_DP<6>")
	)
	(segment
		(start 31.665926 -210.490816)
		(end 31.368746 -210.787996)
		(width 0.18288)
		(layer "In11.Cu")
		(net "M_D_CPU1_SB_DQS_DP<6>")
	)
	(segment
		(start 35.477958 -209.939128)
		(end 34.694368 -209.939128)
		(width 0.18288)
		(layer "In11.Cu")
		(net "M_D_CPU1_SB_DQS_DP<6>")
	)
	(segment
		(start 91.247468 -232.038906)
		(end 91.24696 -232.038906)
		(width 0.088646)
		(layer "In11.Cu")
		(net "M_D_CPU1_SB_DQS_DP<6>")
	)
	(segment
		(start 98.685096 -234.471972)
		(end 98.670364 -234.480608)
		(width 0.088646)
		(layer "In11.Cu")
		(net "M_D_CPU1_SB_DQS_DP<6>")
	)
	(segment
		(start 49.08677 -210.774788)
		(end 47.465742 -210.774788)
		(width 0.18288)
		(layer "In11.Cu")
		(net "M_D_CPU1_SB_DQS_DP<6>")
	)
	(arc
		(start 94.91091 -234.480608)
		(mid 94.723712 -234.530785)
		(end 94.536514 -234.480608)
		(width 0.088646)
		(layer "In11.Cu")
		(net "M_D_CPU1_SB_DQS_DP<6>")
	)
	(arc
		(start 84.668868 -232.038906)
		(mid 84.532396 -231.982283)
		(end 84.385912 -231.96296)
		(width 0.088646)
		(layer "In11.Cu")
		(net "M_D_CPU1_SB_DQS_DP<6>")
	)
	(arc
		(start 86.922864 -232.038906)
		(mid 86.735666 -232.089049)
		(end 86.548468 -232.038906)
		(width 0.088646)
		(layer "In11.Cu")
		(net "M_D_CPU1_SB_DQS_DP<6>")
	)
	(arc
		(start 94.536514 -234.480608)
		(mid 94.399489 -234.343495)
		(end 94.349316 -234.15625)
		(width 0.088646)
		(layer "In11.Cu")
		(net "M_D_CPU1_SB_DQS_DP<6>")
	)
	(arc
		(start 90.682064 -232.038906)
		(mid 90.501919 -232.089227)
		(end 90.31986 -232.046272)
		(width 0.088646)
		(layer "In11.Cu")
		(net "M_D_CPU1_SB_DQS_DP<6>")
	)
	(arc
		(start 93.409516 -232.528364)
		(mid 93.335525 -232.248798)
		(end 93.13291 -232.042462)
		(width 0.088646)
		(layer "In11.Cu")
		(net "M_D_CPU1_SB_DQS_DP<6>")
	)
	(arc
		(start 94.349316 -234.155996)
		(mid 94.27357 -233.873368)
		(end 94.066614 -233.666538)
		(width 0.088646)
		(layer "In11.Cu")
		(net "M_D_CPU1_SB_DQS_DP<6>")
	)
	(arc
		(start 100.175568 -234.480608)
		(mid 99.901369 -234.404773)
		(end 99.624896 -234.471972)
		(width 0.088646)
		(layer "In11.Cu")
		(net "M_D_CPU1_SB_DQS_DP<6>")
	)
	(arc
		(start 87.862664 -232.038906)
		(mid 87.675466 -232.089049)
		(end 87.488268 -232.038906)
		(width 0.088646)
		(layer "In11.Cu")
		(net "M_D_CPU1_SB_DQS_DP<6>")
	)
	(arc
		(start 96.790764 -234.480608)
		(mid 96.603566 -234.530751)
		(end 96.416368 -234.480608)
		(width 0.088646)
		(layer "In11.Cu")
		(net "M_D_CPU1_SB_DQS_DP<6>")
	)
	(arc
		(start 91.24696 -232.038906)
		(mid 90.964512 -231.963223)
		(end 90.682064 -232.038906)
		(width 0.088646)
		(layer "In11.Cu")
		(net "M_D_CPU1_SB_DQS_DP<6>")
	)
	(arc
		(start 89.368376 -232.03916)
		(mid 89.085449 -231.963096)
		(end 88.802464 -232.038906)
		(width 0.088646)
		(layer "In11.Cu")
		(net "M_D_CPU1_SB_DQS_DP<6>")
	)
	(arc
		(start 100.454206 -234.904788)
		(mid 100.452908 -234.894234)
		(end 100.451412 -234.883706)
		(width 0.088646)
		(layer "In11.Cu")
		(net "M_D_CPU1_SB_DQS_DP<6>")
	)
	(arc
		(start 93.112082 -232.03027)
		(mid 92.835607 -231.96295)
		(end 92.56141 -232.038906)
		(width 0.088646)
		(layer "In11.Cu")
		(net "M_D_CPU1_SB_DQS_DP<6>")
	)
	(arc
		(start 85.608668 -232.038906)
		(mid 85.334469 -231.963071)
		(end 85.057996 -232.03027)
		(width 0.088646)
		(layer "In11.Cu")
		(net "M_D_CPU1_SB_DQS_DP<6>")
	)
	(arc
		(start 95.850964 -234.480608)
		(mid 95.663766 -234.530751)
		(end 95.476568 -234.480608)
		(width 0.088646)
		(layer "In11.Cu")
		(net "M_D_CPU1_SB_DQS_DP<6>")
	)
	(arc
		(start 90.308176 -232.03916)
		(mid 90.025249 -231.963096)
		(end 89.742264 -232.038906)
		(width 0.088646)
		(layer "In11.Cu")
		(net "M_D_CPU1_SB_DQS_DP<6>")
	)
	(arc
		(start 99.610164 -234.480608)
		(mid 99.422966 -234.530751)
		(end 99.235768 -234.480608)
		(width 0.088646)
		(layer "In11.Cu")
		(net "M_D_CPU1_SB_DQS_DP<6>")
	)
	(arc
		(start 85.043264 -232.038906)
		(mid 84.856066 -232.089049)
		(end 84.668868 -232.038906)
		(width 0.088646)
		(layer "In11.Cu")
		(net "M_D_CPU1_SB_DQS_DP<6>")
	)
	(arc
		(start 100.451412 -234.883706)
		(mid 100.35929 -234.650806)
		(end 100.175568 -234.480608)
		(width 0.088646)
		(layer "In11.Cu")
		(net "M_D_CPU1_SB_DQS_DP<6>")
	)
	(arc
		(start 85.983064 -232.038906)
		(mid 85.795866 -232.089049)
		(end 85.608668 -232.038906)
		(width 0.088646)
		(layer "In11.Cu")
		(net "M_D_CPU1_SB_DQS_DP<6>")
	)
	(arc
		(start 88.802464 -232.038906)
		(mid 88.622319 -232.089227)
		(end 88.44026 -232.046272)
		(width 0.088646)
		(layer "In11.Cu")
		(net "M_D_CPU1_SB_DQS_DP<6>")
	)
	(arc
		(start 93.588078 -232.847642)
		(mid 93.457164 -232.711282)
		(end 93.409516 -232.528364)
		(width 0.088646)
		(layer "In11.Cu")
		(net "M_D_CPU1_SB_DQS_DP<6>")
	)
	(arc
		(start 87.488268 -232.038906)
		(mid 87.205566 -231.96313)
		(end 86.922864 -232.038906)
		(width 0.088646)
		(layer "In11.Cu")
		(net "M_D_CPU1_SB_DQS_DP<6>")
	)
	(arc
		(start 92.187014 -232.038906)
		(mid 91.904312 -231.96313)
		(end 91.62161 -232.038906)
		(width 0.088646)
		(layer "In11.Cu")
		(net "M_D_CPU1_SB_DQS_DP<6>")
	)
	(arc
		(start 93.879162 -233.326686)
		(mid 93.799792 -233.052952)
		(end 93.596968 -232.852722)
		(width 0.088646)
		(layer "In11.Cu")
		(net "M_D_CPU1_SB_DQS_DP<6>")
	)
	(arc
		(start 97.730564 -234.480608)
		(mid 97.543366 -234.530751)
		(end 97.356168 -234.480608)
		(width 0.088646)
		(layer "In11.Cu")
		(net "M_D_CPU1_SB_DQS_DP<6>")
	)
	(arc
		(start 89.742264 -232.038906)
		(mid 89.562119 -232.089227)
		(end 89.38006 -232.046272)
		(width 0.088646)
		(layer "In11.Cu")
		(net "M_D_CPU1_SB_DQS_DP<6>")
	)
	(arc
		(start 95.476568 -234.480608)
		(mid 95.199755 -234.404738)
		(end 94.921324 -234.474512)
		(width 0.088646)
		(layer "In11.Cu")
		(net "M_D_CPU1_SB_DQS_DP<6>")
	)
	(arc
		(start 86.548468 -232.038906)
		(mid 86.265766 -231.96313)
		(end 85.983064 -232.038906)
		(width 0.088646)
		(layer "In11.Cu")
		(net "M_D_CPU1_SB_DQS_DP<6>")
	)
	(arc
		(start 88.4174 -232.03281)
		(mid 88.139222 -231.963087)
		(end 87.862664 -232.038906)
		(width 0.088646)
		(layer "In11.Cu")
		(net "M_D_CPU1_SB_DQS_DP<6>")
	)
	(arc
		(start 98.295968 -234.480608)
		(mid 98.021769 -234.404773)
		(end 97.745296 -234.471972)
		(width 0.088646)
		(layer "In11.Cu")
		(net "M_D_CPU1_SB_DQS_DP<6>")
	)
	(arc
		(start 92.56141 -232.038906)
		(mid 92.374212 -232.089049)
		(end 92.187014 -232.038906)
		(width 0.088646)
		(layer "In11.Cu")
		(net "M_D_CPU1_SB_DQS_DP<6>")
	)
	(arc
		(start 99.235768 -234.480608)
		(mid 98.961569 -234.404773)
		(end 98.685096 -234.471972)
		(width 0.088646)
		(layer "In11.Cu")
		(net "M_D_CPU1_SB_DQS_DP<6>")
	)
	(arc
		(start 91.62161 -232.038906)
		(mid 91.434556 -232.088956)
		(end 91.247468 -232.038906)
		(width 0.088646)
		(layer "In11.Cu")
		(net "M_D_CPU1_SB_DQS_DP<6>")
	)
	(arc
		(start 96.416368 -234.480608)
		(mid 96.142169 -234.404773)
		(end 95.865696 -234.471972)
		(width 0.088646)
		(layer "In11.Cu")
		(net "M_D_CPU1_SB_DQS_DP<6>")
	)
	(arc
		(start 97.356168 -234.480608)
		(mid 97.073466 -234.404832)
		(end 96.790764 -234.480608)
		(width 0.088646)
		(layer "In11.Cu")
		(net "M_D_CPU1_SB_DQS_DP<6>")
	)
	(arc
		(start 98.670364 -234.480608)
		(mid 98.483166 -234.530751)
		(end 98.295968 -234.480608)
		(width 0.088646)
		(layer "In11.Cu")
		(net "M_D_CPU1_SB_DQS_DP<6>")
	)
	(arc
		(start 94.057724 -233.661458)
		(mid 93.92681 -233.525098)
		(end 93.879162 -233.34218)
		(width 0.088646)
		(layer "In11.Cu")
		(net "M_D_CPU1_SB_DQS_DP<6>")
	)
	(segment
		(start 13.310616 -227.327968)
		(end 12.976352 -227.327968)
		(width 0.20066)
		(layer "F.Cu")
		(net "M_D_CPU1_SB_DQS_DP<5>")
	)
	(segment
		(start 12.714986 -227.066602)
		(end 12.240514 -227.066602)
		(width 0.20066)
		(layer "F.Cu")
		(net "M_D_CPU1_SB_DQS_DP<5>")
	)
	(segment
		(start 13.733018 -226.905566)
		(end 13.310616 -227.327968)
		(width 0.20066)
		(layer "F.Cu")
		(net "M_D_CPU1_SB_DQS_DP<5>")
	)
	(segment
		(start 17.7927 -226.903026)
		(end 17.287748 -226.903026)
		(width 0.20066)
		(layer "F.Cu")
		(net "M_D_CPU1_SB_DQS_DP<5>")
	)
	(segment
		(start 14.560042 -226.636072)
		(end 14.362684 -226.636072)
		(width 0.20066)
		(layer "F.Cu")
		(net "M_D_CPU1_SB_DQS_DP<5>")
	)
	(segment
		(start 14.56563 -226.64166)
		(end 14.560042 -226.636072)
		(width 0.101854)
		(layer "F.Cu")
		(net "M_D_CPU1_SB_DQS_DP<5>")
	)
	(segment
		(start 14.362684 -226.636072)
		(end 14.09319 -226.905566)
		(width 0.20066)
		(layer "F.Cu")
		(net "M_D_CPU1_SB_DQS_DP<5>")
	)
	(segment
		(start 16.884904 -226.64166)
		(end 14.80693 -226.64166)
		(width 0.1016)
		(layer "F.Cu")
		(net "M_D_CPU1_SB_DQS_DP<5>")
	)
	(segment
		(start 18.428716 -227.327968)
		(end 17.7927 -226.903026)
		(width 0.20066)
		(layer "F.Cu")
		(net "M_D_CPU1_SB_DQS_DP<5>")
	)
	(segment
		(start 100.832666 -240.389156)
		(end 100.832412 -240.388902)
		(width 0.20066)
		(layer "F.Cu")
		(net "M_D_CPU1_SB_DQS_DP<5>")
	)
	(segment
		(start 19.033236 -227.327968)
		(end 18.428716 -227.327968)
		(width 0.20066)
		(layer "F.Cu")
		(net "M_D_CPU1_SB_DQS_DP<5>")
	)
	(segment
		(start 19.294602 -227.066602)
		(end 19.033236 -227.327968)
		(width 0.20066)
		(layer "F.Cu")
		(net "M_D_CPU1_SB_DQS_DP<5>")
	)
	(segment
		(start 14.80693 -226.64166)
		(end 14.56563 -226.64166)
		(width 0.101854)
		(layer "F.Cu")
		(net "M_D_CPU1_SB_DQS_DP<5>")
	)
	(segment
		(start 16.885158 -226.641914)
		(end 16.884904 -226.64166)
		(width 0.1016)
		(layer "F.Cu")
		(net "M_D_CPU1_SB_DQS_DP<5>")
	)
	(segment
		(start 12.976352 -227.327968)
		(end 12.714986 -227.066602)
		(width 0.20066)
		(layer "F.Cu")
		(net "M_D_CPU1_SB_DQS_DP<5>")
	)
	(segment
		(start 19.784314 -227.066602)
		(end 19.294602 -227.066602)
		(width 0.20066)
		(layer "F.Cu")
		(net "M_D_CPU1_SB_DQS_DP<5>")
	)
	(segment
		(start 17.287748 -226.903026)
		(end 17.026636 -226.641914)
		(width 0.20066)
		(layer "F.Cu")
		(net "M_D_CPU1_SB_DQS_DP<5>")
	)
	(segment
		(start 14.09319 -226.905566)
		(end 13.733018 -226.905566)
		(width 0.20066)
		(layer "F.Cu")
		(net "M_D_CPU1_SB_DQS_DP<5>")
	)
	(segment
		(start 20.889214 -227.066602)
		(end 19.784314 -227.066602)
		(width 0.20066)
		(layer "F.Cu")
		(net "M_D_CPU1_SB_DQS_DP<5>")
	)
	(segment
		(start 100.832412 -240.388902)
		(end 100.832412 -239.853216)
		(width 0.20066)
		(layer "F.Cu")
		(net "M_D_CPU1_SB_DQS_DP<5>")
	)
	(segment
		(start 17.026636 -226.641914)
		(end 16.885158 -226.641914)
		(width 0.20066)
		(layer "F.Cu")
		(net "M_D_CPU1_SB_DQS_DP<5>")
	)
	(segment
		(start 87.488268 -238.549942)
		(end 87.479378 -238.544862)
		(width 0.088646)
		(layer "In11.Cu")
		(net "M_D_CPU1_SB_DQS_DP<5>")
	)
	(segment
		(start 87.022432 -237.738666)
		(end 87.0204 -237.737396)
		(width 0.088646)
		(layer "In11.Cu")
		(net "M_D_CPU1_SB_DQS_DP<5>")
	)
	(segment
		(start 87.0204 -237.737396)
		(end 87.018114 -237.736126)
		(width 0.088646)
		(layer "In11.Cu")
		(net "M_D_CPU1_SB_DQS_DP<5>")
	)
	(segment
		(start 32.146494 -223.241108)
		(end 31.684214 -223.241108)
		(width 0.18288)
		(layer "In11.Cu")
		(net "M_D_CPU1_SB_DQS_DP<5>")
	)
	(segment
		(start 88.43391 -238.553498)
		(end 88.432132 -238.552482)
		(width 0.088646)
		(layer "In11.Cu")
		(net "M_D_CPU1_SB_DQS_DP<5>")
	)
	(segment
		(start 87.02421 -237.739682)
		(end 87.022432 -237.738666)
		(width 0.088646)
		(layer "In11.Cu")
		(net "M_D_CPU1_SB_DQS_DP<5>")
	)
	(segment
		(start 98.685096 -239.355122)
		(end 98.670364 -239.363758)
		(width 0.088646)
		(layer "In11.Cu")
		(net "M_D_CPU1_SB_DQS_DP<5>")
	)
	(segment
		(start 77.168756 -236.285024)
		(end 67.011804 -226.128072)
		(width 0.18288)
		(layer "In11.Cu")
		(net "M_D_CPU1_SB_DQS_DP<5>")
	)
	(segment
		(start 43.862244 -223.578674)
		(end 41.187116 -223.578674)
		(width 0.18288)
		(layer "In11.Cu")
		(net "M_D_CPU1_SB_DQS_DP<5>")
	)
	(segment
		(start 29.427932 -224.4852)
		(end 28.769564 -225.143568)
		(width 0.18288)
		(layer "In11.Cu")
		(net "M_D_CPU1_SB_DQS_DP<5>")
	)
	(segment
		(start 66.242438 -225.799142)
		(end 66.059558 -225.799142)
		(width 0.16002)
		(layer "In11.Cu")
		(net "M_D_CPU1_SB_DQS_DP<5>")
	)
	(segment
		(start 50.848768 -222.392748)
		(end 50.573178 -222.668338)
		(width 0.18288)
		(layer "In11.Cu")
		(net "M_D_CPU1_SB_DQS_DP<5>")
	)
	(segment
		(start 46.475904 -223.529906)
		(end 45.683424 -223.529906)
		(width 0.18288)
		(layer "In11.Cu")
		(net "M_D_CPU1_SB_DQS_DP<5>")
	)
	(segment
		(start 31.684214 -223.241108)
		(end 31.390336 -223.534986)
		(width 0.18288)
		(layer "In11.Cu")
		(net "M_D_CPU1_SB_DQS_DP<5>")
	)
	(segment
		(start 28.108656 -225.41738)
		(end 27.073352 -226.452684)
		(width 0.18288)
		(layer "In11.Cu")
		(net "M_D_CPU1_SB_DQS_DP<5>")
	)
	(segment
		(start 84.385912 -237.786926)
		(end 84.089494 -237.786926)
		(width 0.088646)
		(layer "In11.Cu")
		(net "M_D_CPU1_SB_DQS_DP<5>")
	)
	(segment
		(start 100.832412 -239.853216)
		(end 100.519484 -239.853216)
		(width 0.088646)
		(layer "In11.Cu")
		(net "M_D_CPU1_SB_DQS_DP<5>")
	)
	(segment
		(start 51.553364 -222.645732)
		(end 51.30038 -222.392748)
		(width 0.18288)
		(layer "In11.Cu")
		(net "M_D_CPU1_SB_DQS_DP<5>")
	)
	(segment
		(start 46.764702 -223.241108)
		(end 46.475904 -223.529906)
		(width 0.18288)
		(layer "In11.Cu")
		(net "M_D_CPU1_SB_DQS_DP<5>")
	)
	(segment
		(start 21.746464 -227.339906)
		(end 21.162518 -227.339906)
		(width 0.18288)
		(layer "In11.Cu")
		(net "M_D_CPU1_SB_DQS_DP<5>")
	)
	(segment
		(start 88.897968 -239.363758)
		(end 88.889078 -239.358678)
		(width 0.088646)
		(layer "In11.Cu")
		(net "M_D_CPU1_SB_DQS_DP<5>")
	)
	(segment
		(start 34.866072 -222.681546)
		(end 34.029904 -223.517714)
		(width 0.18288)
		(layer "In11.Cu")
		(net "M_D_CPU1_SB_DQS_DP<5>")
	)
	(segment
		(start 27.073352 -226.452684)
		(end 24.220678 -227.634546)
		(width 0.18288)
		(layer "In11.Cu")
		(net "M_D_CPU1_SB_DQS_DP<5>")
	)
	(segment
		(start 28.769564 -225.143568)
		(end 28.108656 -225.41738)
		(width 0.18288)
		(layer "In11.Cu")
		(net "M_D_CPU1_SB_DQS_DP<5>")
	)
	(segment
		(start 87.018114 -237.736126)
		(end 87.0077 -237.73003)
		(width 0.088646)
		(layer "In11.Cu")
		(net "M_D_CPU1_SB_DQS_DP<5>")
	)
	(segment
		(start 60.048394 -224.571306)
		(end 59.020456 -223.543368)
		(width 0.18288)
		(layer "In11.Cu")
		(net "M_D_CPU1_SB_DQS_DP<5>")
	)
	(segment
		(start 93.981778 -239.357662)
		(end 93.971364 -239.363758)
		(width 0.088646)
		(layer "In11.Cu")
		(net "M_D_CPU1_SB_DQS_DP<5>")
	)
	(segment
		(start 88.432132 -238.552482)
		(end 88.4301 -238.551212)
		(width 0.088646)
		(layer "In11.Cu")
		(net "M_D_CPU1_SB_DQS_DP<5>")
	)
	(segment
		(start 35.48253 -222.681546)
		(end 34.866072 -222.681546)
		(width 0.18288)
		(layer "In11.Cu")
		(net "M_D_CPU1_SB_DQS_DP<5>")
	)
	(segment
		(start 44.383706 -224.100136)
		(end 43.862244 -223.578674)
		(width 0.18288)
		(layer "In11.Cu")
		(net "M_D_CPU1_SB_DQS_DP<5>")
	)
	(segment
		(start 54.296818 -222.645732)
		(end 51.553364 -222.645732)
		(width 0.18288)
		(layer "In11.Cu")
		(net "M_D_CPU1_SB_DQS_DP<5>")
	)
	(segment
		(start 39.014654 -222.678498)
		(end 36.457382 -222.678498)
		(width 0.18288)
		(layer "In11.Cu")
		(net "M_D_CPU1_SB_DQS_DP<5>")
	)
	(segment
		(start 22.041104 -227.634546)
		(end 21.746464 -227.339906)
		(width 0.18288)
		(layer "In11.Cu")
		(net "M_D_CPU1_SB_DQS_DP<5>")
	)
	(segment
		(start 47.153068 -223.241108)
		(end 46.764702 -223.241108)
		(width 0.18288)
		(layer "In11.Cu")
		(net "M_D_CPU1_SB_DQS_DP<5>")
	)
	(segment
		(start 59.020456 -223.543368)
		(end 56.4642 -223.543368)
		(width 0.18288)
		(layer "In11.Cu")
		(net "M_D_CPU1_SB_DQS_DP<5>")
	)
	(segment
		(start 62.147958 -224.94113)
		(end 62.003178 -224.94113)
		(width 0.16002)
		(layer "In11.Cu")
		(net "M_D_CPU1_SB_DQS_DP<5>")
	)
	(segment
		(start 89.287096 -239.355122)
		(end 89.272364 -239.363758)
		(width 0.088646)
		(layer "In11.Cu")
		(net "M_D_CPU1_SB_DQS_DP<5>")
	)
	(segment
		(start 21.162518 -227.339906)
		(end 20.889214 -227.066602)
		(width 0.18288)
		(layer "In11.Cu")
		(net "M_D_CPU1_SB_DQS_DP<5>")
	)
	(segment
		(start 51.30038 -222.392748)
		(end 50.848768 -222.392748)
		(width 0.18288)
		(layer "In11.Cu")
		(net "M_D_CPU1_SB_DQS_DP<5>")
	)
	(segment
		(start 65.883282 -225.799142)
		(end 65.640712 -226.041712)
		(width 0.18288)
		(layer "In11.Cu")
		(net "M_D_CPU1_SB_DQS_DP<5>")
	)
	(segment
		(start 66.41973 -225.799142)
		(end 66.242438 -225.799142)
		(width 0.18288)
		(layer "In11.Cu")
		(net "M_D_CPU1_SB_DQS_DP<5>")
	)
	(segment
		(start 94.921324 -239.357662)
		(end 94.91091 -239.363758)
		(width 0.088646)
		(layer "In11.Cu")
		(net "M_D_CPU1_SB_DQS_DP<5>")
	)
	(segment
		(start 50.573178 -222.668338)
		(end 49.894744 -222.668338)
		(width 0.18288)
		(layer "In11.Cu")
		(net "M_D_CPU1_SB_DQS_DP<5>")
	)
	(segment
		(start 61.572394 -225.222054)
		(end 61.149992 -225.222054)
		(width 0.18288)
		(layer "In11.Cu")
		(net "M_D_CPU1_SB_DQS_DP<5>")
	)
	(segment
		(start 85.138514 -237.736126)
		(end 85.123782 -237.72749)
		(width 0.088646)
		(layer "In11.Cu")
		(net "M_D_CPU1_SB_DQS_DP<5>")
	)
	(segment
		(start 84.089494 -237.786926)
		(end 82.647282 -236.344714)
		(width 0.088646)
		(layer "In11.Cu")
		(net "M_D_CPU1_SB_DQS_DP<5>")
	)
	(segment
		(start 82.37347 -236.285024)
		(end 77.168756 -236.285024)
		(width 0.18288)
		(layer "In11.Cu")
		(net "M_D_CPU1_SB_DQS_DP<5>")
	)
	(segment
		(start 36.457382 -222.678498)
		(end 36.169854 -222.39097)
		(width 0.18288)
		(layer "In11.Cu")
		(net "M_D_CPU1_SB_DQS_DP<5>")
	)
	(segment
		(start 34.029904 -223.517714)
		(end 32.4231 -223.517714)
		(width 0.18288)
		(layer "In11.Cu")
		(net "M_D_CPU1_SB_DQS_DP<5>")
	)
	(segment
		(start 32.4231 -223.517714)
		(end 32.146494 -223.241108)
		(width 0.18288)
		(layer "In11.Cu")
		(net "M_D_CPU1_SB_DQS_DP<5>")
	)
	(segment
		(start 66.059558 -225.799142)
		(end 65.883282 -225.799142)
		(width 0.18288)
		(layer "In11.Cu")
		(net "M_D_CPU1_SB_DQS_DP<5>")
	)
	(segment
		(start 24.220678 -227.634546)
		(end 22.041104 -227.634546)
		(width 0.18288)
		(layer "In11.Cu")
		(net "M_D_CPU1_SB_DQS_DP<5>")
	)
	(segment
		(start 65.040002 -226.041712)
		(end 64.201548 -225.203258)
		(width 0.18288)
		(layer "In11.Cu")
		(net "M_D_CPU1_SB_DQS_DP<5>")
	)
	(segment
		(start 30.493208 -223.773238)
		(end 29.427932 -224.4852)
		(width 0.18288)
		(layer "In11.Cu")
		(net "M_D_CPU1_SB_DQS_DP<5>")
	)
	(segment
		(start 62.003178 -224.94113)
		(end 61.853318 -224.94113)
		(width 0.18288)
		(layer "In11.Cu")
		(net "M_D_CPU1_SB_DQS_DP<5>")
	)
	(segment
		(start 45.683424 -223.529906)
		(end 45.113194 -224.100136)
		(width 0.18288)
		(layer "In11.Cu")
		(net "M_D_CPU1_SB_DQS_DP<5>")
	)
	(segment
		(start 93.046296 -239.355122)
		(end 93.031564 -239.363758)
		(width 0.088646)
		(layer "In11.Cu")
		(net "M_D_CPU1_SB_DQS_DP<5>")
	)
	(segment
		(start 31.068518 -223.534986)
		(end 30.493208 -223.773238)
		(width 0.18288)
		(layer "In11.Cu")
		(net "M_D_CPU1_SB_DQS_DP<5>")
	)
	(segment
		(start 41.187116 -223.578674)
		(end 39.014654 -222.678498)
		(width 0.18288)
		(layer "In11.Cu")
		(net "M_D_CPU1_SB_DQS_DP<5>")
	)
	(segment
		(start 66.74866 -226.128072)
		(end 66.41973 -225.799142)
		(width 0.18288)
		(layer "In11.Cu")
		(net "M_D_CPU1_SB_DQS_DP<5>")
	)
	(segment
		(start 67.011804 -226.128072)
		(end 66.74866 -226.128072)
		(width 0.18288)
		(layer "In11.Cu")
		(net "M_D_CPU1_SB_DQS_DP<5>")
	)
	(segment
		(start 88.4301 -238.551212)
		(end 88.427814 -238.549942)
		(width 0.088646)
		(layer "In11.Cu")
		(net "M_D_CPU1_SB_DQS_DP<5>")
	)
	(segment
		(start 100.519484 -239.853216)
		(end 100.454206 -239.787938)
		(width 0.088646)
		(layer "In11.Cu")
		(net "M_D_CPU1_SB_DQS_DP<5>")
	)
	(segment
		(start 95.865696 -239.355122)
		(end 95.850964 -239.363758)
		(width 0.088646)
		(layer "In11.Cu")
		(net "M_D_CPU1_SB_DQS_DP<5>")
	)
	(segment
		(start 97.745296 -239.355122)
		(end 97.730564 -239.363758)
		(width 0.088646)
		(layer "In11.Cu")
		(net "M_D_CPU1_SB_DQS_DP<5>")
	)
	(segment
		(start 91.166696 -239.355122)
		(end 91.151964 -239.363758)
		(width 0.088646)
		(layer "In11.Cu")
		(net "M_D_CPU1_SB_DQS_DP<5>")
	)
	(segment
		(start 82.43316 -236.344714)
		(end 82.37347 -236.285024)
		(width 0.088646)
		(layer "In11.Cu")
		(net "M_D_CPU1_SB_DQS_DP<5>")
	)
	(segment
		(start 49.010824 -223.552258)
		(end 47.464218 -223.552258)
		(width 0.18288)
		(layer "In11.Cu")
		(net "M_D_CPU1_SB_DQS_DP<5>")
	)
	(segment
		(start 82.647282 -236.344714)
		(end 82.43316 -236.344714)
		(width 0.088646)
		(layer "In11.Cu")
		(net "M_D_CPU1_SB_DQS_DP<5>")
	)
	(segment
		(start 86.078568 -237.736126)
		(end 86.068154 -237.73003)
		(width 0.088646)
		(layer "In11.Cu")
		(net "M_D_CPU1_SB_DQS_DP<5>")
	)
	(segment
		(start 62.59068 -225.203258)
		(end 62.328552 -224.94113)
		(width 0.18288)
		(layer "In11.Cu")
		(net "M_D_CPU1_SB_DQS_DP<5>")
	)
	(segment
		(start 45.113194 -224.100136)
		(end 44.383706 -224.100136)
		(width 0.18288)
		(layer "In11.Cu")
		(net "M_D_CPU1_SB_DQS_DP<5>")
	)
	(segment
		(start 65.640712 -226.041712)
		(end 65.040002 -226.041712)
		(width 0.18288)
		(layer "In11.Cu")
		(net "M_D_CPU1_SB_DQS_DP<5>")
	)
	(segment
		(start 47.464218 -223.552258)
		(end 47.153068 -223.241108)
		(width 0.18288)
		(layer "In11.Cu")
		(net "M_D_CPU1_SB_DQS_DP<5>")
	)
	(segment
		(start 88.427814 -238.549942)
		(end 88.4174 -238.543846)
		(width 0.088646)
		(layer "In11.Cu")
		(net "M_D_CPU1_SB_DQS_DP<5>")
	)
	(segment
		(start 99.624896 -239.355122)
		(end 99.610164 -239.363758)
		(width 0.088646)
		(layer "In11.Cu")
		(net "M_D_CPU1_SB_DQS_DP<5>")
	)
	(segment
		(start 61.149992 -225.222054)
		(end 60.499244 -224.571306)
		(width 0.18288)
		(layer "In11.Cu")
		(net "M_D_CPU1_SB_DQS_DP<5>")
	)
	(segment
		(start 36.169854 -222.39097)
		(end 35.773106 -222.39097)
		(width 0.18288)
		(layer "In11.Cu")
		(net "M_D_CPU1_SB_DQS_DP<5>")
	)
	(segment
		(start 56.4642 -223.543368)
		(end 54.296818 -222.645732)
		(width 0.18288)
		(layer "In11.Cu")
		(net "M_D_CPU1_SB_DQS_DP<5>")
	)
	(segment
		(start 60.499244 -224.571306)
		(end 60.048394 -224.571306)
		(width 0.18288)
		(layer "In11.Cu")
		(net "M_D_CPU1_SB_DQS_DP<5>")
	)
	(segment
		(start 61.853318 -224.94113)
		(end 61.572394 -225.222054)
		(width 0.18288)
		(layer "In11.Cu")
		(net "M_D_CPU1_SB_DQS_DP<5>")
	)
	(segment
		(start 49.894744 -222.668338)
		(end 49.010824 -223.552258)
		(width 0.18288)
		(layer "In11.Cu")
		(net "M_D_CPU1_SB_DQS_DP<5>")
	)
	(segment
		(start 62.328552 -224.94113)
		(end 62.147958 -224.94113)
		(width 0.18288)
		(layer "In11.Cu")
		(net "M_D_CPU1_SB_DQS_DP<5>")
	)
	(segment
		(start 35.773106 -222.39097)
		(end 35.48253 -222.681546)
		(width 0.18288)
		(layer "In11.Cu")
		(net "M_D_CPU1_SB_DQS_DP<5>")
	)
	(segment
		(start 64.201548 -225.203258)
		(end 62.59068 -225.203258)
		(width 0.18288)
		(layer "In11.Cu")
		(net "M_D_CPU1_SB_DQS_DP<5>")
	)
	(segment
		(start 31.390336 -223.534986)
		(end 31.068518 -223.534986)
		(width 0.18288)
		(layer "In11.Cu")
		(net "M_D_CPU1_SB_DQS_DP<5>")
	)
	(segment
		(start 92.106496 -239.355122)
		(end 92.091764 -239.363758)
		(width 0.088646)
		(layer "In11.Cu")
		(net "M_D_CPU1_SB_DQS_DP<5>")
	)
	(arc
		(start 93.596968 -239.363758)
		(mid 93.322769 -239.287923)
		(end 93.046296 -239.355122)
		(width 0.088646)
		(layer "In11.Cu")
		(net "M_D_CPU1_SB_DQS_DP<5>")
	)
	(arc
		(start 98.670364 -239.363758)
		(mid 98.483166 -239.413901)
		(end 98.295968 -239.363758)
		(width 0.088646)
		(layer "In11.Cu")
		(net "M_D_CPU1_SB_DQS_DP<5>")
	)
	(arc
		(start 90.212164 -239.363758)
		(mid 90.024966 -239.413901)
		(end 89.837768 -239.363758)
		(width 0.088646)
		(layer "In11.Cu")
		(net "M_D_CPU1_SB_DQS_DP<5>")
	)
	(arc
		(start 88.4174 -238.543846)
		(mid 88.139222 -238.474123)
		(end 87.862664 -238.549942)
		(width 0.088646)
		(layer "In11.Cu")
		(net "M_D_CPU1_SB_DQS_DP<5>")
	)
	(arc
		(start 87.862664 -238.549942)
		(mid 87.675466 -238.600085)
		(end 87.488268 -238.549942)
		(width 0.088646)
		(layer "In11.Cu")
		(net "M_D_CPU1_SB_DQS_DP<5>")
	)
	(arc
		(start 100.175568 -239.363758)
		(mid 99.901369 -239.287923)
		(end 99.624896 -239.355122)
		(width 0.088646)
		(layer "In11.Cu")
		(net "M_D_CPU1_SB_DQS_DP<5>")
	)
	(arc
		(start 88.889078 -239.358678)
		(mid 88.758164 -239.222318)
		(end 88.710516 -239.0394)
		(width 0.088646)
		(layer "In11.Cu")
		(net "M_D_CPU1_SB_DQS_DP<5>")
	)
	(arc
		(start 87.479378 -238.544862)
		(mid 87.348464 -238.408502)
		(end 87.300816 -238.225584)
		(width 0.088646)
		(layer "In11.Cu")
		(net "M_D_CPU1_SB_DQS_DP<5>")
	)
	(arc
		(start 97.356168 -239.363758)
		(mid 97.073466 -239.287982)
		(end 96.790764 -239.363758)
		(width 0.088646)
		(layer "In11.Cu")
		(net "M_D_CPU1_SB_DQS_DP<5>")
	)
	(arc
		(start 88.710516 -239.0394)
		(mid 88.636525 -238.759834)
		(end 88.43391 -238.553498)
		(width 0.088646)
		(layer "In11.Cu")
		(net "M_D_CPU1_SB_DQS_DP<5>")
	)
	(arc
		(start 93.971364 -239.363758)
		(mid 93.784166 -239.413901)
		(end 93.596968 -239.363758)
		(width 0.088646)
		(layer "In11.Cu")
		(net "M_D_CPU1_SB_DQS_DP<5>")
	)
	(arc
		(start 86.068154 -237.73003)
		(mid 85.789722 -237.660184)
		(end 85.51291 -237.736126)
		(width 0.088646)
		(layer "In11.Cu")
		(net "M_D_CPU1_SB_DQS_DP<5>")
	)
	(arc
		(start 99.235768 -239.363758)
		(mid 98.961569 -239.287923)
		(end 98.685096 -239.355122)
		(width 0.088646)
		(layer "In11.Cu")
		(net "M_D_CPU1_SB_DQS_DP<5>")
	)
	(arc
		(start 94.91091 -239.363758)
		(mid 94.723712 -239.413901)
		(end 94.536514 -239.363758)
		(width 0.088646)
		(layer "In11.Cu")
		(net "M_D_CPU1_SB_DQS_DP<5>")
	)
	(arc
		(start 90.777568 -239.363758)
		(mid 90.494866 -239.287982)
		(end 90.212164 -239.363758)
		(width 0.088646)
		(layer "In11.Cu")
		(net "M_D_CPU1_SB_DQS_DP<5>")
	)
	(arc
		(start 96.416368 -239.363758)
		(mid 96.142169 -239.287923)
		(end 95.865696 -239.355122)
		(width 0.088646)
		(layer "In11.Cu")
		(net "M_D_CPU1_SB_DQS_DP<5>")
	)
	(arc
		(start 92.657168 -239.363758)
		(mid 92.382969 -239.287923)
		(end 92.106496 -239.355122)
		(width 0.088646)
		(layer "In11.Cu")
		(net "M_D_CPU1_SB_DQS_DP<5>")
	)
	(arc
		(start 95.476568 -239.363758)
		(mid 95.199755 -239.287888)
		(end 94.921324 -239.357662)
		(width 0.088646)
		(layer "In11.Cu")
		(net "M_D_CPU1_SB_DQS_DP<5>")
	)
	(arc
		(start 100.454206 -239.787938)
		(mid 100.452908 -239.777384)
		(end 100.451412 -239.766856)
		(width 0.088646)
		(layer "In11.Cu")
		(net "M_D_CPU1_SB_DQS_DP<5>")
	)
	(arc
		(start 95.850964 -239.363758)
		(mid 95.663766 -239.413901)
		(end 95.476568 -239.363758)
		(width 0.088646)
		(layer "In11.Cu")
		(net "M_D_CPU1_SB_DQS_DP<5>")
	)
	(arc
		(start 85.51291 -237.736126)
		(mid 85.325712 -237.786269)
		(end 85.138514 -237.736126)
		(width 0.088646)
		(layer "In11.Cu")
		(net "M_D_CPU1_SB_DQS_DP<5>")
	)
	(arc
		(start 89.272364 -239.363758)
		(mid 89.085166 -239.413901)
		(end 88.897968 -239.363758)
		(width 0.088646)
		(layer "In11.Cu")
		(net "M_D_CPU1_SB_DQS_DP<5>")
	)
	(arc
		(start 86.452964 -237.736126)
		(mid 86.265766 -237.786269)
		(end 86.078568 -237.736126)
		(width 0.088646)
		(layer "In11.Cu")
		(net "M_D_CPU1_SB_DQS_DP<5>")
	)
	(arc
		(start 96.790764 -239.363758)
		(mid 96.603566 -239.413901)
		(end 96.416368 -239.363758)
		(width 0.088646)
		(layer "In11.Cu")
		(net "M_D_CPU1_SB_DQS_DP<5>")
	)
	(arc
		(start 89.837768 -239.363758)
		(mid 89.563569 -239.287923)
		(end 89.287096 -239.355122)
		(width 0.088646)
		(layer "In11.Cu")
		(net "M_D_CPU1_SB_DQS_DP<5>")
	)
	(arc
		(start 92.091764 -239.363758)
		(mid 91.904566 -239.413901)
		(end 91.717368 -239.363758)
		(width 0.088646)
		(layer "In11.Cu")
		(net "M_D_CPU1_SB_DQS_DP<5>")
	)
	(arc
		(start 85.123782 -237.72749)
		(mid 84.847307 -237.66017)
		(end 84.57311 -237.736126)
		(width 0.088646)
		(layer "In11.Cu")
		(net "M_D_CPU1_SB_DQS_DP<5>")
	)
	(arc
		(start 91.717368 -239.363758)
		(mid 91.443169 -239.287923)
		(end 91.166696 -239.355122)
		(width 0.088646)
		(layer "In11.Cu")
		(net "M_D_CPU1_SB_DQS_DP<5>")
	)
	(arc
		(start 91.151964 -239.363758)
		(mid 90.964766 -239.413901)
		(end 90.777568 -239.363758)
		(width 0.088646)
		(layer "In11.Cu")
		(net "M_D_CPU1_SB_DQS_DP<5>")
	)
	(arc
		(start 93.031564 -239.363758)
		(mid 92.844366 -239.413901)
		(end 92.657168 -239.363758)
		(width 0.088646)
		(layer "In11.Cu")
		(net "M_D_CPU1_SB_DQS_DP<5>")
	)
	(arc
		(start 87.300816 -238.225584)
		(mid 87.226825 -237.946018)
		(end 87.02421 -237.739682)
		(width 0.088646)
		(layer "In11.Cu")
		(net "M_D_CPU1_SB_DQS_DP<5>")
	)
	(arc
		(start 97.730564 -239.363758)
		(mid 97.543366 -239.413901)
		(end 97.356168 -239.363758)
		(width 0.088646)
		(layer "In11.Cu")
		(net "M_D_CPU1_SB_DQS_DP<5>")
	)
	(arc
		(start 94.536514 -239.363758)
		(mid 94.259955 -239.288015)
		(end 93.981778 -239.357662)
		(width 0.088646)
		(layer "In11.Cu")
		(net "M_D_CPU1_SB_DQS_DP<5>")
	)
	(arc
		(start 84.57311 -237.736126)
		(mid 84.482854 -237.773848)
		(end 84.385912 -237.786926)
		(width 0.088646)
		(layer "In11.Cu")
		(net "M_D_CPU1_SB_DQS_DP<5>")
	)
	(arc
		(start 100.451412 -239.766856)
		(mid 100.35929 -239.533956)
		(end 100.175568 -239.363758)
		(width 0.088646)
		(layer "In11.Cu")
		(net "M_D_CPU1_SB_DQS_DP<5>")
	)
	(arc
		(start 87.0077 -237.73003)
		(mid 86.729522 -237.660307)
		(end 86.452964 -237.736126)
		(width 0.088646)
		(layer "In11.Cu")
		(net "M_D_CPU1_SB_DQS_DP<5>")
	)
	(arc
		(start 98.295968 -239.363758)
		(mid 98.021769 -239.287923)
		(end 97.745296 -239.355122)
		(width 0.088646)
		(layer "In11.Cu")
		(net "M_D_CPU1_SB_DQS_DP<5>")
	)
	(arc
		(start 99.610164 -239.363758)
		(mid 99.422966 -239.413901)
		(end 99.235768 -239.363758)
		(width 0.088646)
		(layer "In11.Cu")
		(net "M_D_CPU1_SB_DQS_DP<5>")
	)
	(segment
		(start 12.976352 -236.677962)
		(end 12.714986 -236.416596)
		(width 0.20066)
		(layer "F.Cu")
		(net "M_D_CPU1_SB_DQS_DP<4>")
	)
	(segment
		(start 16.884904 -235.991654)
		(end 14.80693 -235.991654)
		(width 0.1016)
		(layer "F.Cu")
		(net "M_D_CPU1_SB_DQS_DP<4>")
	)
	(segment
		(start 19.033236 -236.677962)
		(end 18.428716 -236.677962)
		(width 0.20066)
		(layer "F.Cu")
		(net "M_D_CPU1_SB_DQS_DP<4>")
	)
	(segment
		(start 17.7927 -236.25302)
		(end 17.287748 -236.25302)
		(width 0.20066)
		(layer "F.Cu")
		(net "M_D_CPU1_SB_DQS_DP<4>")
	)
	(segment
		(start 14.560042 -235.986066)
		(end 14.362684 -235.986066)
		(width 0.20066)
		(layer "F.Cu")
		(net "M_D_CPU1_SB_DQS_DP<4>")
	)
	(segment
		(start 13.310616 -236.677962)
		(end 12.976352 -236.677962)
		(width 0.20066)
		(layer "F.Cu")
		(net "M_D_CPU1_SB_DQS_DP<4>")
	)
	(segment
		(start 16.885158 -235.991908)
		(end 16.884904 -235.991654)
		(width 0.1016)
		(layer "F.Cu")
		(net "M_D_CPU1_SB_DQS_DP<4>")
	)
	(segment
		(start 14.362684 -235.986066)
		(end 14.09319 -236.25556)
		(width 0.20066)
		(layer "F.Cu")
		(net "M_D_CPU1_SB_DQS_DP<4>")
	)
	(segment
		(start 18.428716 -236.677962)
		(end 17.7927 -236.25302)
		(width 0.20066)
		(layer "F.Cu")
		(net "M_D_CPU1_SB_DQS_DP<4>")
	)
	(segment
		(start 99.892866 -245.27256)
		(end 99.892612 -245.272306)
		(width 0.20066)
		(layer "F.Cu")
		(net "M_D_CPU1_SB_DQS_DP<4>")
	)
	(segment
		(start 14.09319 -236.25556)
		(end 13.733018 -236.25556)
		(width 0.20066)
		(layer "F.Cu")
		(net "M_D_CPU1_SB_DQS_DP<4>")
	)
	(segment
		(start 19.294602 -236.416596)
		(end 19.033236 -236.677962)
		(width 0.20066)
		(layer "F.Cu")
		(net "M_D_CPU1_SB_DQS_DP<4>")
	)
	(segment
		(start 13.733018 -236.25556)
		(end 13.310616 -236.677962)
		(width 0.20066)
		(layer "F.Cu")
		(net "M_D_CPU1_SB_DQS_DP<4>")
	)
	(segment
		(start 17.287748 -236.25302)
		(end 17.026636 -235.991908)
		(width 0.20066)
		(layer "F.Cu")
		(net "M_D_CPU1_SB_DQS_DP<4>")
	)
	(segment
		(start 17.026636 -235.991908)
		(end 16.885158 -235.991908)
		(width 0.20066)
		(layer "F.Cu")
		(net "M_D_CPU1_SB_DQS_DP<4>")
	)
	(segment
		(start 14.56563 -235.991654)
		(end 14.560042 -235.986066)
		(width 0.101854)
		(layer "F.Cu")
		(net "M_D_CPU1_SB_DQS_DP<4>")
	)
	(segment
		(start 14.80693 -235.991654)
		(end 14.56563 -235.991654)
		(width 0.101854)
		(layer "F.Cu")
		(net "M_D_CPU1_SB_DQS_DP<4>")
	)
	(segment
		(start 20.889214 -236.416596)
		(end 19.784314 -236.416596)
		(width 0.20066)
		(layer "F.Cu")
		(net "M_D_CPU1_SB_DQS_DP<4>")
	)
	(segment
		(start 99.892612 -245.272306)
		(end 99.892612 -244.73662)
		(width 0.20066)
		(layer "F.Cu")
		(net "M_D_CPU1_SB_DQS_DP<4>")
	)
	(segment
		(start 12.714986 -236.416596)
		(end 12.240514 -236.416596)
		(width 0.20066)
		(layer "F.Cu")
		(net "M_D_CPU1_SB_DQS_DP<4>")
	)
	(segment
		(start 19.784314 -236.416596)
		(end 19.294602 -236.416596)
		(width 0.20066)
		(layer "F.Cu")
		(net "M_D_CPU1_SB_DQS_DP<4>")
	)
	(segment
		(start 55.296308 -235.393738)
		(end 51.523646 -235.393738)
		(width 0.18288)
		(layer "In11.Cu")
		(net "M_D_CPU1_SB_DQS_DP<4>")
	)
	(segment
		(start 84.469732 -243.483892)
		(end 84.005928 -243.020088)
		(width 0.088646)
		(layer "In11.Cu")
		(net "M_D_CPU1_SB_DQS_DP<4>")
	)
	(segment
		(start 84.005928 -243.020088)
		(end 83.733386 -243.020088)
		(width 0.088646)
		(layer "In11.Cu")
		(net "M_D_CPU1_SB_DQS_DP<4>")
	)
	(segment
		(start 47.428404 -236.247686)
		(end 47.170086 -235.989368)
		(width 0.18288)
		(layer "In11.Cu")
		(net "M_D_CPU1_SB_DQS_DP<4>")
	)
	(segment
		(start 31.66745 -235.989368)
		(end 31.369508 -236.28731)
		(width 0.18288)
		(layer "In11.Cu")
		(net "M_D_CPU1_SB_DQS_DP<4>")
	)
	(segment
		(start 32.105854 -235.989368)
		(end 31.66745 -235.989368)
		(width 0.18288)
		(layer "In11.Cu")
		(net "M_D_CPU1_SB_DQS_DP<4>")
	)
	(segment
		(start 67.46113 -237.675928)
		(end 66.605658 -237.320582)
		(width 0.18288)
		(layer "In11.Cu")
		(net "M_D_CPU1_SB_DQS_DP<4>")
	)
	(segment
		(start 70.445122 -240.483898)
		(end 70.2691 -240.483898)
		(width 0.18288)
		(layer "In11.Cu")
		(net "M_D_CPU1_SB_DQS_DP<4>")
	)
	(segment
		(start 49.799494 -235.406946)
		(end 48.958754 -236.247686)
		(width 0.18288)
		(layer "In11.Cu")
		(net "M_D_CPU1_SB_DQS_DP<4>")
	)
	(segment
		(start 29.644594 -237.254542)
		(end 25.425654 -237.254542)
		(width 0.18288)
		(layer "In11.Cu")
		(net "M_D_CPU1_SB_DQS_DP<4>")
	)
	(segment
		(start 100.0887 -245.055898)
		(end 100.07981 -245.060978)
		(width 0.088646)
		(layer "In11.Cu")
		(net "M_D_CPU1_SB_DQS_DP<4>")
	)
	(segment
		(start 50.602896 -235.399326)
		(end 50.595276 -235.406946)
		(width 0.18288)
		(layer "In11.Cu")
		(net "M_D_CPU1_SB_DQS_DP<4>")
	)
	(segment
		(start 72.173084 -242.387882)
		(end 71.785226 -242.000024)
		(width 0.18288)
		(layer "In11.Cu")
		(net "M_D_CPU1_SB_DQS_DP<4>")
	)
	(segment
		(start 71.221092 -241.43589)
		(end 70.833234 -241.048032)
		(width 0.18288)
		(layer "In11.Cu")
		(net "M_D_CPU1_SB_DQS_DP<4>")
	)
	(segment
		(start 60.474098 -235.4072)
		(end 59.26836 -235.4072)
		(width 0.18288)
		(layer "In11.Cu")
		(net "M_D_CPU1_SB_DQS_DP<4>")
	)
	(segment
		(start 91.166696 -244.238526)
		(end 91.151964 -244.247162)
		(width 0.088646)
		(layer "In11.Cu")
		(net "M_D_CPU1_SB_DQS_DP<4>")
	)
	(segment
		(start 83.733386 -243.020088)
		(end 83.673696 -242.960398)
		(width 0.088646)
		(layer "In11.Cu")
		(net "M_D_CPU1_SB_DQS_DP<4>")
	)
	(segment
		(start 88.347296 -244.238526)
		(end 88.332564 -244.247162)
		(width 0.088646)
		(layer "In11.Cu")
		(net "M_D_CPU1_SB_DQS_DP<4>")
	)
	(segment
		(start 50.871374 -235.143548)
		(end 50.615596 -235.399326)
		(width 0.18288)
		(layer "In11.Cu")
		(net "M_D_CPU1_SB_DQS_DP<4>")
	)
	(segment
		(start 70.833234 -241.048032)
		(end 70.833234 -240.87201)
		(width 0.18288)
		(layer "In11.Cu")
		(net "M_D_CPU1_SB_DQS_DP<4>")
	)
	(segment
		(start 94.921324 -244.241066)
		(end 94.91091 -244.247162)
		(width 0.088646)
		(layer "In11.Cu")
		(net "M_D_CPU1_SB_DQS_DP<4>")
	)
	(segment
		(start 33.745424 -236.252512)
		(end 32.368998 -236.252512)
		(width 0.18288)
		(layer "In11.Cu")
		(net "M_D_CPU1_SB_DQS_DP<4>")
	)
	(segment
		(start 46.77537 -235.989368)
		(end 46.499018 -236.26572)
		(width 0.18288)
		(layer "In11.Cu")
		(net "M_D_CPU1_SB_DQS_DP<4>")
	)
	(segment
		(start 32.368998 -236.252512)
		(end 32.105854 -235.989368)
		(width 0.18288)
		(layer "In11.Cu")
		(net "M_D_CPU1_SB_DQS_DP<4>")
	)
	(segment
		(start 68.92925 -239.144048)
		(end 68.92925 -238.968026)
		(width 0.18288)
		(layer "In11.Cu")
		(net "M_D_CPU1_SB_DQS_DP<4>")
	)
	(segment
		(start 70.833234 -240.87201)
		(end 70.445122 -240.483898)
		(width 0.18288)
		(layer "In11.Cu")
		(net "M_D_CPU1_SB_DQS_DP<4>")
	)
	(segment
		(start 71.785226 -242.000024)
		(end 71.785226 -241.824002)
		(width 0.18288)
		(layer "In11.Cu")
		(net "M_D_CPU1_SB_DQS_DP<4>")
	)
	(segment
		(start 51.273456 -235.143548)
		(end 50.871374 -235.143548)
		(width 0.18288)
		(layer "In11.Cu")
		(net "M_D_CPU1_SB_DQS_DP<4>")
	)
	(segment
		(start 51.523646 -235.393738)
		(end 51.273456 -235.143548)
		(width 0.18288)
		(layer "In11.Cu")
		(net "M_D_CPU1_SB_DQS_DP<4>")
	)
	(segment
		(start 50.595276 -235.406946)
		(end 49.799494 -235.406946)
		(width 0.18288)
		(layer "In11.Cu")
		(net "M_D_CPU1_SB_DQS_DP<4>")
	)
	(segment
		(start 86.078314 -244.247162)
		(end 86.069424 -244.242082)
		(width 0.088646)
		(layer "In11.Cu")
		(net "M_D_CPU1_SB_DQS_DP<4>")
	)
	(segment
		(start 48.958754 -236.247686)
		(end 47.428404 -236.247686)
		(width 0.18288)
		(layer "In11.Cu")
		(net "M_D_CPU1_SB_DQS_DP<4>")
	)
	(segment
		(start 84.856066 -243.483892)
		(end 84.469732 -243.483892)
		(width 0.088646)
		(layer "In11.Cu")
		(net "M_D_CPU1_SB_DQS_DP<4>")
	)
	(segment
		(start 46.499018 -236.26572)
		(end 45.219874 -236.26572)
		(width 0.18288)
		(layer "In11.Cu")
		(net "M_D_CPU1_SB_DQS_DP<4>")
	)
	(segment
		(start 40.401494 -235.406692)
		(end 36.428426 -235.406692)
		(width 0.18288)
		(layer "In11.Cu")
		(net "M_D_CPU1_SB_DQS_DP<4>")
	)
	(segment
		(start 44.31538 -236.239558)
		(end 41.23436 -236.239558)
		(width 0.18288)
		(layer "In11.Cu")
		(net "M_D_CPU1_SB_DQS_DP<4>")
	)
	(segment
		(start 99.517962 -244.73662)
		(end 99.517962 -244.721126)
		(width 0.088646)
		(layer "In11.Cu")
		(net "M_D_CPU1_SB_DQS_DP<4>")
	)
	(segment
		(start 60.732924 -235.666026)
		(end 60.474098 -235.4072)
		(width 0.18288)
		(layer "In11.Cu")
		(net "M_D_CPU1_SB_DQS_DP<4>")
	)
	(segment
		(start 24.765762 -236.981238)
		(end 22.041104 -236.981238)
		(width 0.18288)
		(layer "In11.Cu")
		(net "M_D_CPU1_SB_DQS_DP<4>")
	)
	(segment
		(start 50.615596 -235.399326)
		(end 50.602896 -235.399326)
		(width 0.18288)
		(layer "In11.Cu")
		(net "M_D_CPU1_SB_DQS_DP<4>")
	)
	(segment
		(start 89.287096 -244.238526)
		(end 89.272364 -244.247162)
		(width 0.088646)
		(layer "In11.Cu")
		(net "M_D_CPU1_SB_DQS_DP<4>")
	)
	(segment
		(start 68.365116 -238.579914)
		(end 67.461638 -237.676182)
		(width 0.18288)
		(layer "In11.Cu")
		(net "M_D_CPU1_SB_DQS_DP<4>")
	)
	(segment
		(start 69.881242 -240.09604)
		(end 69.881242 -239.920018)
		(width 0.18288)
		(layer "In11.Cu")
		(net "M_D_CPU1_SB_DQS_DP<4>")
	)
	(segment
		(start 93.046296 -244.238526)
		(end 93.031564 -244.247162)
		(width 0.088646)
		(layer "In11.Cu")
		(net "M_D_CPU1_SB_DQS_DP<4>")
	)
	(segment
		(start 67.461638 -237.676182)
		(end 67.46113 -237.675928)
		(width 0.18288)
		(layer "In11.Cu")
		(net "M_D_CPU1_SB_DQS_DP<4>")
	)
	(segment
		(start 44.933616 -235.979462)
		(end 44.575476 -235.979462)
		(width 0.18288)
		(layer "In11.Cu")
		(net "M_D_CPU1_SB_DQS_DP<4>")
	)
	(segment
		(start 58.35904 -235.402882)
		(end 57.1754 -235.402882)
		(width 0.18288)
		(layer "In11.Cu")
		(net "M_D_CPU1_SB_DQS_DP<4>")
	)
	(segment
		(start 47.170086 -235.989368)
		(end 46.77537 -235.989368)
		(width 0.18288)
		(layer "In11.Cu")
		(net "M_D_CPU1_SB_DQS_DP<4>")
	)
	(segment
		(start 31.369508 -236.28731)
		(end 30.611826 -236.28731)
		(width 0.18288)
		(layer "In11.Cu")
		(net "M_D_CPU1_SB_DQS_DP<4>")
	)
	(segment
		(start 58.654696 -235.107226)
		(end 58.35904 -235.402882)
		(width 0.18288)
		(layer "In11.Cu")
		(net "M_D_CPU1_SB_DQS_DP<4>")
	)
	(segment
		(start 55.934356 -236.031786)
		(end 55.296308 -235.393738)
		(width 0.18288)
		(layer "In11.Cu")
		(net "M_D_CPU1_SB_DQS_DP<4>")
	)
	(segment
		(start 100.20554 -244.73662)
		(end 100.26269 -244.79377)
		(width 0.088646)
		(layer "In11.Cu")
		(net "M_D_CPU1_SB_DQS_DP<4>")
	)
	(segment
		(start 97.745296 -244.238526)
		(end 97.730564 -244.247162)
		(width 0.088646)
		(layer "In11.Cu")
		(net "M_D_CPU1_SB_DQS_DP<4>")
	)
	(segment
		(start 30.611826 -236.28731)
		(end 29.644594 -237.254542)
		(width 0.18288)
		(layer "In11.Cu")
		(net "M_D_CPU1_SB_DQS_DP<4>")
	)
	(segment
		(start 85.890862 -243.922804)
		(end 85.890862 -243.90731)
		(width 0.088646)
		(layer "In11.Cu")
		(net "M_D_CPU1_SB_DQS_DP<4>")
	)
	(segment
		(start 35.700462 -235.141008)
		(end 35.456368 -235.385102)
		(width 0.18288)
		(layer "In11.Cu")
		(net "M_D_CPU1_SB_DQS_DP<4>")
	)
	(segment
		(start 83.673696 -242.960398)
		(end 83.032854 -242.960398)
		(width 0.18288)
		(layer "In11.Cu")
		(net "M_D_CPU1_SB_DQS_DP<4>")
	)
	(segment
		(start 25.425654 -237.254542)
		(end 24.765762 -236.981238)
		(width 0.18288)
		(layer "In11.Cu")
		(net "M_D_CPU1_SB_DQS_DP<4>")
	)
	(segment
		(start 59.26836 -235.4072)
		(end 58.968386 -235.107226)
		(width 0.18288)
		(layer "In11.Cu")
		(net "M_D_CPU1_SB_DQS_DP<4>")
	)
	(segment
		(start 93.981778 -244.241066)
		(end 93.971364 -244.247162)
		(width 0.088646)
		(layer "In11.Cu")
		(net "M_D_CPU1_SB_DQS_DP<4>")
	)
	(segment
		(start 34.612834 -235.385102)
		(end 33.745424 -236.252512)
		(width 0.18288)
		(layer "In11.Cu")
		(net "M_D_CPU1_SB_DQS_DP<4>")
	)
	(segment
		(start 44.575476 -235.979462)
		(end 44.31538 -236.239558)
		(width 0.18288)
		(layer "In11.Cu")
		(net "M_D_CPU1_SB_DQS_DP<4>")
	)
	(segment
		(start 68.92925 -238.968026)
		(end 68.541138 -238.579914)
		(width 0.18288)
		(layer "In11.Cu")
		(net "M_D_CPU1_SB_DQS_DP<4>")
	)
	(segment
		(start 83.032854 -242.960398)
		(end 82.460338 -242.387882)
		(width 0.18288)
		(layer "In11.Cu")
		(net "M_D_CPU1_SB_DQS_DP<4>")
	)
	(segment
		(start 41.23436 -236.239558)
		(end 40.401494 -235.406692)
		(width 0.18288)
		(layer "In11.Cu")
		(net "M_D_CPU1_SB_DQS_DP<4>")
	)
	(segment
		(start 64.721486 -236.561884)
		(end 62.566042 -235.666026)
		(width 0.18288)
		(layer "In11.Cu")
		(net "M_D_CPU1_SB_DQS_DP<4>")
	)
	(segment
		(start 71.785226 -241.824002)
		(end 71.397114 -241.43589)
		(width 0.18288)
		(layer "In11.Cu")
		(net "M_D_CPU1_SB_DQS_DP<4>")
	)
	(segment
		(start 65.855342 -237.320582)
		(end 64.721486 -236.561884)
		(width 0.18288)
		(layer "In11.Cu")
		(net "M_D_CPU1_SB_DQS_DP<4>")
	)
	(segment
		(start 62.566042 -235.666026)
		(end 60.732924 -235.666026)
		(width 0.18288)
		(layer "In11.Cu")
		(net "M_D_CPU1_SB_DQS_DP<4>")
	)
	(segment
		(start 69.317108 -239.531906)
		(end 68.92925 -239.144048)
		(width 0.18288)
		(layer "In11.Cu")
		(net "M_D_CPU1_SB_DQS_DP<4>")
	)
	(segment
		(start 22.041104 -236.981238)
		(end 21.745956 -236.68609)
		(width 0.18288)
		(layer "In11.Cu")
		(net "M_D_CPU1_SB_DQS_DP<4>")
	)
	(segment
		(start 58.968386 -235.107226)
		(end 58.654696 -235.107226)
		(width 0.18288)
		(layer "In11.Cu")
		(net "M_D_CPU1_SB_DQS_DP<4>")
	)
	(segment
		(start 35.456368 -235.385102)
		(end 34.612834 -235.385102)
		(width 0.18288)
		(layer "In11.Cu")
		(net "M_D_CPU1_SB_DQS_DP<4>")
	)
	(segment
		(start 69.49313 -239.531906)
		(end 69.317108 -239.531906)
		(width 0.18288)
		(layer "In11.Cu")
		(net "M_D_CPU1_SB_DQS_DP<4>")
	)
	(segment
		(start 56.546496 -236.031786)
		(end 55.934356 -236.031786)
		(width 0.18288)
		(layer "In11.Cu")
		(net "M_D_CPU1_SB_DQS_DP<4>")
	)
	(segment
		(start 69.881242 -239.920018)
		(end 69.49313 -239.531906)
		(width 0.18288)
		(layer "In11.Cu")
		(net "M_D_CPU1_SB_DQS_DP<4>")
	)
	(segment
		(start 87.402924 -244.241066)
		(end 87.39251 -244.247162)
		(width 0.088646)
		(layer "In11.Cu")
		(net "M_D_CPU1_SB_DQS_DP<4>")
	)
	(segment
		(start 66.605658 -237.320582)
		(end 65.855342 -237.320582)
		(width 0.18288)
		(layer "In11.Cu")
		(net "M_D_CPU1_SB_DQS_DP<4>")
	)
	(segment
		(start 36.428426 -235.406692)
		(end 36.162742 -235.141008)
		(width 0.18288)
		(layer "In11.Cu")
		(net "M_D_CPU1_SB_DQS_DP<4>")
	)
	(segment
		(start 21.158708 -236.68609)
		(end 20.889214 -236.416596)
		(width 0.18288)
		(layer "In11.Cu")
		(net "M_D_CPU1_SB_DQS_DP<4>")
	)
	(segment
		(start 45.219874 -236.26572)
		(end 44.933616 -235.979462)
		(width 0.18288)
		(layer "In11.Cu")
		(net "M_D_CPU1_SB_DQS_DP<4>")
	)
	(segment
		(start 70.2691 -240.483898)
		(end 69.881242 -240.09604)
		(width 0.18288)
		(layer "In11.Cu")
		(net "M_D_CPU1_SB_DQS_DP<4>")
	)
	(segment
		(start 95.865696 -244.238526)
		(end 95.850964 -244.247162)
		(width 0.088646)
		(layer "In11.Cu")
		(net "M_D_CPU1_SB_DQS_DP<4>")
	)
	(segment
		(start 98.685096 -244.238526)
		(end 98.670364 -244.247162)
		(width 0.088646)
		(layer "In11.Cu")
		(net "M_D_CPU1_SB_DQS_DP<4>")
	)
	(segment
		(start 99.705414 -245.060978)
		(end 99.696524 -245.055898)
		(width 0.088646)
		(layer "In11.Cu")
		(net "M_D_CPU1_SB_DQS_DP<4>")
	)
	(segment
		(start 36.162742 -235.141008)
		(end 35.700462 -235.141008)
		(width 0.18288)
		(layer "In11.Cu")
		(net "M_D_CPU1_SB_DQS_DP<4>")
	)
	(segment
		(start 68.541138 -238.579914)
		(end 68.365116 -238.579914)
		(width 0.18288)
		(layer "In11.Cu")
		(net "M_D_CPU1_SB_DQS_DP<4>")
	)
	(segment
		(start 71.397114 -241.43589)
		(end 71.221092 -241.43589)
		(width 0.18288)
		(layer "In11.Cu")
		(net "M_D_CPU1_SB_DQS_DP<4>")
	)
	(segment
		(start 21.745956 -236.68609)
		(end 21.158708 -236.68609)
		(width 0.18288)
		(layer "In11.Cu")
		(net "M_D_CPU1_SB_DQS_DP<4>")
	)
	(segment
		(start 57.1754 -235.402882)
		(end 56.546496 -236.031786)
		(width 0.18288)
		(layer "In11.Cu")
		(net "M_D_CPU1_SB_DQS_DP<4>")
	)
	(segment
		(start 99.892612 -244.73662)
		(end 100.20554 -244.73662)
		(width 0.088646)
		(layer "In11.Cu")
		(net "M_D_CPU1_SB_DQS_DP<4>")
	)
	(segment
		(start 82.460338 -242.387882)
		(end 72.173084 -242.387882)
		(width 0.18288)
		(layer "In11.Cu")
		(net "M_D_CPU1_SB_DQS_DP<4>")
	)
	(arc
		(start 95.850964 -244.247162)
		(mid 95.663766 -244.297305)
		(end 95.476568 -244.247162)
		(width 0.088646)
		(layer "In11.Cu")
		(net "M_D_CPU1_SB_DQS_DP<4>")
	)
	(arc
		(start 99.696524 -245.055898)
		(mid 99.56561 -244.919538)
		(end 99.517962 -244.73662)
		(width 0.088646)
		(layer "In11.Cu")
		(net "M_D_CPU1_SB_DQS_DP<4>")
	)
	(arc
		(start 98.670364 -244.247162)
		(mid 98.483166 -244.297305)
		(end 98.295968 -244.247162)
		(width 0.088646)
		(layer "In11.Cu")
		(net "M_D_CPU1_SB_DQS_DP<4>")
	)
	(arc
		(start 87.018114 -244.247162)
		(mid 86.735412 -244.171386)
		(end 86.45271 -244.247162)
		(width 0.088646)
		(layer "In11.Cu")
		(net "M_D_CPU1_SB_DQS_DP<4>")
	)
	(arc
		(start 89.272364 -244.247162)
		(mid 89.085166 -244.297305)
		(end 88.897968 -244.247162)
		(width 0.088646)
		(layer "In11.Cu")
		(net "M_D_CPU1_SB_DQS_DP<4>")
	)
	(arc
		(start 87.39251 -244.247162)
		(mid 87.205312 -244.297305)
		(end 87.018114 -244.247162)
		(width 0.088646)
		(layer "In11.Cu")
		(net "M_D_CPU1_SB_DQS_DP<4>")
	)
	(arc
		(start 99.235768 -244.247162)
		(mid 98.961569 -244.171327)
		(end 98.685096 -244.238526)
		(width 0.088646)
		(layer "In11.Cu")
		(net "M_D_CPU1_SB_DQS_DP<4>")
	)
	(arc
		(start 97.356168 -244.247162)
		(mid 97.073466 -244.171386)
		(end 96.790764 -244.247162)
		(width 0.088646)
		(layer "In11.Cu")
		(net "M_D_CPU1_SB_DQS_DP<4>")
	)
	(arc
		(start 85.608668 -243.433346)
		(mid 85.334469 -243.357511)
		(end 85.057996 -243.42471)
		(width 0.088646)
		(layer "In11.Cu")
		(net "M_D_CPU1_SB_DQS_DP<4>")
	)
	(arc
		(start 85.057996 -243.42471)
		(mid 85.050808 -243.429238)
		(end 85.043518 -243.4336)
		(width 0.088646)
		(layer "In11.Cu")
		(net "M_D_CPU1_SB_DQS_DP<4>")
	)
	(arc
		(start 93.596968 -244.247162)
		(mid 93.322769 -244.171327)
		(end 93.046296 -244.238526)
		(width 0.088646)
		(layer "In11.Cu")
		(net "M_D_CPU1_SB_DQS_DP<4>")
	)
	(arc
		(start 90.212164 -244.247162)
		(mid 90.024966 -244.297305)
		(end 89.837768 -244.247162)
		(width 0.088646)
		(layer "In11.Cu")
		(net "M_D_CPU1_SB_DQS_DP<4>")
	)
	(arc
		(start 93.971364 -244.247162)
		(mid 93.784166 -244.297305)
		(end 93.596968 -244.247162)
		(width 0.088646)
		(layer "In11.Cu")
		(net "M_D_CPU1_SB_DQS_DP<4>")
	)
	(arc
		(start 92.091764 -244.247162)
		(mid 91.904566 -244.297305)
		(end 91.717368 -244.247162)
		(width 0.088646)
		(layer "In11.Cu")
		(net "M_D_CPU1_SB_DQS_DP<4>")
	)
	(arc
		(start 85.043518 -243.4336)
		(mid 84.953108 -243.47111)
		(end 84.856066 -243.483892)
		(width 0.088646)
		(layer "In11.Cu")
		(net "M_D_CPU1_SB_DQS_DP<4>")
	)
	(arc
		(start 95.476568 -244.247162)
		(mid 95.199755 -244.171292)
		(end 94.921324 -244.241066)
		(width 0.088646)
		(layer "In11.Cu")
		(net "M_D_CPU1_SB_DQS_DP<4>")
	)
	(arc
		(start 96.790764 -244.247162)
		(mid 96.603566 -244.297305)
		(end 96.416368 -244.247162)
		(width 0.088646)
		(layer "In11.Cu")
		(net "M_D_CPU1_SB_DQS_DP<4>")
	)
	(arc
		(start 94.536514 -244.247162)
		(mid 94.259955 -244.171419)
		(end 93.981778 -244.241066)
		(width 0.088646)
		(layer "In11.Cu")
		(net "M_D_CPU1_SB_DQS_DP<4>")
	)
	(arc
		(start 100.07981 -245.060978)
		(mid 99.892612 -245.111121)
		(end 99.705414 -245.060978)
		(width 0.088646)
		(layer "In11.Cu")
		(net "M_D_CPU1_SB_DQS_DP<4>")
	)
	(arc
		(start 88.897968 -244.247162)
		(mid 88.623769 -244.171327)
		(end 88.347296 -244.238526)
		(width 0.088646)
		(layer "In11.Cu")
		(net "M_D_CPU1_SB_DQS_DP<4>")
	)
	(arc
		(start 88.332564 -244.247162)
		(mid 88.145366 -244.297305)
		(end 87.958168 -244.247162)
		(width 0.088646)
		(layer "In11.Cu")
		(net "M_D_CPU1_SB_DQS_DP<4>")
	)
	(arc
		(start 87.958168 -244.247162)
		(mid 87.681355 -244.171292)
		(end 87.402924 -244.241066)
		(width 0.088646)
		(layer "In11.Cu")
		(net "M_D_CPU1_SB_DQS_DP<4>")
	)
	(arc
		(start 92.657168 -244.247162)
		(mid 92.374466 -244.171386)
		(end 92.091764 -244.247162)
		(width 0.088646)
		(layer "In11.Cu")
		(net "M_D_CPU1_SB_DQS_DP<4>")
	)
	(arc
		(start 98.295968 -244.247162)
		(mid 98.021769 -244.171327)
		(end 97.745296 -244.238526)
		(width 0.088646)
		(layer "In11.Cu")
		(net "M_D_CPU1_SB_DQS_DP<4>")
	)
	(arc
		(start 90.777568 -244.247162)
		(mid 90.494866 -244.171386)
		(end 90.212164 -244.247162)
		(width 0.088646)
		(layer "In11.Cu")
		(net "M_D_CPU1_SB_DQS_DP<4>")
	)
	(arc
		(start 85.890862 -243.90731)
		(mid 85.811492 -243.633576)
		(end 85.608668 -243.433346)
		(width 0.088646)
		(layer "In11.Cu")
		(net "M_D_CPU1_SB_DQS_DP<4>")
	)
	(arc
		(start 91.717368 -244.247162)
		(mid 91.443169 -244.171327)
		(end 91.166696 -244.238526)
		(width 0.088646)
		(layer "In11.Cu")
		(net "M_D_CPU1_SB_DQS_DP<4>")
	)
	(arc
		(start 91.151964 -244.247162)
		(mid 90.964766 -244.297305)
		(end 90.777568 -244.247162)
		(width 0.088646)
		(layer "In11.Cu")
		(net "M_D_CPU1_SB_DQS_DP<4>")
	)
	(arc
		(start 93.031564 -244.247162)
		(mid 92.844366 -244.297305)
		(end 92.657168 -244.247162)
		(width 0.088646)
		(layer "In11.Cu")
		(net "M_D_CPU1_SB_DQS_DP<4>")
	)
	(arc
		(start 96.416368 -244.247162)
		(mid 96.142169 -244.171327)
		(end 95.865696 -244.238526)
		(width 0.088646)
		(layer "In11.Cu")
		(net "M_D_CPU1_SB_DQS_DP<4>")
	)
	(arc
		(start 100.26269 -244.79377)
		(mid 100.204571 -244.944011)
		(end 100.0887 -245.055898)
		(width 0.088646)
		(layer "In11.Cu")
		(net "M_D_CPU1_SB_DQS_DP<4>")
	)
	(arc
		(start 97.730564 -244.247162)
		(mid 97.543366 -244.297305)
		(end 97.356168 -244.247162)
		(width 0.088646)
		(layer "In11.Cu")
		(net "M_D_CPU1_SB_DQS_DP<4>")
	)
	(arc
		(start 89.837768 -244.247162)
		(mid 89.563569 -244.171327)
		(end 89.287096 -244.238526)
		(width 0.088646)
		(layer "In11.Cu")
		(net "M_D_CPU1_SB_DQS_DP<4>")
	)
	(arc
		(start 86.069424 -244.242082)
		(mid 85.93851 -244.105722)
		(end 85.890862 -243.922804)
		(width 0.088646)
		(layer "In11.Cu")
		(net "M_D_CPU1_SB_DQS_DP<4>")
	)
	(arc
		(start 94.91091 -244.247162)
		(mid 94.723712 -244.297305)
		(end 94.536514 -244.247162)
		(width 0.088646)
		(layer "In11.Cu")
		(net "M_D_CPU1_SB_DQS_DP<4>")
	)
	(arc
		(start 99.517962 -244.721126)
		(mid 99.438592 -244.447392)
		(end 99.235768 -244.247162)
		(width 0.088646)
		(layer "In11.Cu")
		(net "M_D_CPU1_SB_DQS_DP<4>")
	)
	(arc
		(start 86.45271 -244.247162)
		(mid 86.265512 -244.297305)
		(end 86.078314 -244.247162)
		(width 0.088646)
		(layer "In11.Cu")
		(net "M_D_CPU1_SB_DQS_DP<4>")
	)
	(segment
		(start 13.854684 -200.880726)
		(end 13.593572 -201.141838)
		(width 0.20066)
		(layer "F.Cu")
		(net "M_D_CPU1_SB_DQS_DP<3>")
	)
	(segment
		(start 13.441426 -201.141838)
		(end 13.118084 -201.141838)
		(width 0.101854)
		(layer "F.Cu")
		(net "M_D_CPU1_SB_DQS_DP<3>")
	)
	(segment
		(start 14.605762 -200.45553)
		(end 14.180566 -200.880726)
		(width 0.20066)
		(layer "F.Cu")
		(net "M_D_CPU1_SB_DQS_DP<3>")
	)
	(segment
		(start 16.789146 -200.716642)
		(end 15.684246 -200.716642)
		(width 0.20066)
		(layer "F.Cu")
		(net "M_D_CPU1_SB_DQS_DP<3>")
	)
	(segment
		(start 11.36269 -201.141838)
		(end 11.125708 -201.141838)
		(width 0.101854)
		(layer "F.Cu")
		(net "M_D_CPU1_SB_DQS_DP<3>")
	)
	(segment
		(start 13.593572 -201.141838)
		(end 13.441426 -201.141838)
		(width 0.20066)
		(layer "F.Cu")
		(net "M_D_CPU1_SB_DQS_DP<3>")
	)
	(segment
		(start 14.180566 -200.880726)
		(end 13.854684 -200.880726)
		(width 0.20066)
		(layer "F.Cu")
		(net "M_D_CPU1_SB_DQS_DP<3>")
	)
	(segment
		(start 8.678418 -200.716642)
		(end 8.140446 -200.716642)
		(width 0.20066)
		(layer "F.Cu")
		(net "M_D_CPU1_SB_DQS_DP<3>")
	)
	(segment
		(start 10.000488 -200.880726)
		(end 9.364472 -200.45553)
		(width 0.20066)
		(layer "F.Cu")
		(net "M_D_CPU1_SB_DQS_DP<3>")
	)
	(segment
		(start 10.898124 -201.151236)
		(end 10.627614 -200.880726)
		(width 0.20066)
		(layer "F.Cu")
		(net "M_D_CPU1_SB_DQS_DP<3>")
	)
	(segment
		(start 10.627614 -200.880726)
		(end 10.000488 -200.880726)
		(width 0.20066)
		(layer "F.Cu")
		(net "M_D_CPU1_SB_DQS_DP<3>")
	)
	(segment
		(start 9.364472 -200.45553)
		(end 8.93953 -200.45553)
		(width 0.20066)
		(layer "F.Cu")
		(net "M_D_CPU1_SB_DQS_DP<3>")
	)
	(segment
		(start 15.684246 -200.716642)
		(end 15.135606 -200.716642)
		(width 0.20066)
		(layer "F.Cu")
		(net "M_D_CPU1_SB_DQS_DP<3>")
	)
	(segment
		(start 11.125708 -201.141838)
		(end 11.11631 -201.151236)
		(width 0.101854)
		(layer "F.Cu")
		(net "M_D_CPU1_SB_DQS_DP<3>")
	)
	(segment
		(start 11.11631 -201.151236)
		(end 10.898124 -201.151236)
		(width 0.20066)
		(layer "F.Cu")
		(net "M_D_CPU1_SB_DQS_DP<3>")
	)
	(segment
		(start 8.93953 -200.45553)
		(end 8.678418 -200.716642)
		(width 0.20066)
		(layer "F.Cu")
		(net "M_D_CPU1_SB_DQS_DP<3>")
	)
	(segment
		(start 14.874494 -200.45553)
		(end 14.605762 -200.45553)
		(width 0.20066)
		(layer "F.Cu")
		(net "M_D_CPU1_SB_DQS_DP<3>")
	)
	(segment
		(start 98.953066 -230.622602)
		(end 98.952812 -230.622348)
		(width 0.20066)
		(layer "F.Cu")
		(net "M_D_CPU1_SB_DQS_DP<3>")
	)
	(segment
		(start 13.118084 -201.141838)
		(end 11.36269 -201.141838)
		(width 0.1016)
		(layer "F.Cu")
		(net "M_D_CPU1_SB_DQS_DP<3>")
	)
	(segment
		(start 98.952812 -230.622348)
		(end 98.952812 -230.086662)
		(width 0.20066)
		(layer "F.Cu")
		(net "M_D_CPU1_SB_DQS_DP<3>")
	)
	(segment
		(start 15.135606 -200.716642)
		(end 14.874494 -200.45553)
		(width 0.20066)
		(layer "F.Cu")
		(net "M_D_CPU1_SB_DQS_DP<3>")
	)
	(segment
		(start 26.573734 -199.96531)
		(end 22.634702 -200.861168)
		(width 0.18288)
		(layer "In11.Cu")
		(net "M_D_CPU1_SB_DQS_DP<3>")
	)
	(segment
		(start 95.006414 -228.134672)
		(end 94.991682 -228.143308)
		(width 0.088646)
		(layer "In11.Cu")
		(net "M_D_CPU1_SB_DQS_DP<3>")
	)
	(segment
		(start 50.580036 -200.928732)
		(end 50.002186 -200.928732)
		(width 0.18288)
		(layer "In11.Cu")
		(net "M_D_CPU1_SB_DQS_DP<3>")
	)
	(segment
		(start 32.766254 -199.211438)
		(end 32.360616 -199.211438)
		(width 0.18288)
		(layer "In11.Cu")
		(net "M_D_CPU1_SB_DQS_DP<3>")
	)
	(segment
		(start 96.978216 -229.2731)
		(end 96.978216 -229.272846)
		(width 0.088646)
		(layer "In11.Cu")
		(net "M_D_CPU1_SB_DQS_DP<3>")
	)
	(segment
		(start 91.632278 -228.140768)
		(end 91.621864 -228.134672)
		(width 0.088646)
		(layer "In11.Cu")
		(net "M_D_CPU1_SB_DQS_DP<3>")
	)
	(segment
		(start 18.099532 -200.214738)
		(end 17.571466 -200.433432)
		(width 0.18288)
		(layer "In11.Cu")
		(net "M_D_CPU1_SB_DQS_DP<3>")
	)
	(segment
		(start 50.789586 -201.138282)
		(end 50.580036 -200.928732)
		(width 0.18288)
		(layer "In11.Cu")
		(net "M_D_CPU1_SB_DQS_DP<3>")
	)
	(segment
		(start 95.946214 -228.134672)
		(end 95.931482 -228.143308)
		(width 0.088646)
		(layer "In11.Cu")
		(net "M_D_CPU1_SB_DQS_DP<3>")
	)
	(segment
		(start 37.911278 -200.554082)
		(end 37.150548 -200.869804)
		(width 0.18288)
		(layer "In11.Cu")
		(net "M_D_CPU1_SB_DQS_DP<3>")
	)
	(segment
		(start 48.208946 -199.135492)
		(end 47.470822 -199.135492)
		(width 0.18288)
		(layer "In11.Cu")
		(net "M_D_CPU1_SB_DQS_DP<3>")
	)
	(segment
		(start 83.059778 -225.61677)
		(end 83.059778 -225.343974)
		(width 0.088646)
		(layer "In11.Cu")
		(net "M_D_CPU1_SB_DQS_DP<3>")
	)
	(segment
		(start 17.571466 -200.433432)
		(end 17.072356 -200.433432)
		(width 0.18288)
		(layer "In11.Cu")
		(net "M_D_CPU1_SB_DQS_DP<3>")
	)
	(segment
		(start 97.54616 -229.926642)
		(end 97.26041 -229.762304)
		(width 0.088646)
		(layer "In11.Cu")
		(net "M_D_CPU1_SB_DQS_DP<3>")
	)
	(segment
		(start 97.638362 -230.086662)
		(end 97.638362 -230.013256)
		(width 0.088646)
		(layer "In11.Cu")
		(net "M_D_CPU1_SB_DQS_DP<3>")
	)
	(segment
		(start 63.241174 -202.90409)
		(end 62.597538 -201.351388)
		(width 0.18288)
		(layer "In11.Cu")
		(net "M_D_CPU1_SB_DQS_DP<3>")
	)
	(segment
		(start 62.597538 -201.351388)
		(end 61.639704 -200.3933)
		(width 0.18288)
		(layer "In11.Cu")
		(net "M_D_CPU1_SB_DQS_DP<3>")
	)
	(segment
		(start 32.128206 -199.443848)
		(end 31.625286 -199.443848)
		(width 0.18288)
		(layer "In11.Cu")
		(net "M_D_CPU1_SB_DQS_DP<3>")
	)
	(segment
		(start 20.204684 -200.83907)
		(end 18.697702 -200.214738)
		(width 0.18288)
		(layer "In11.Cu")
		(net "M_D_CPU1_SB_DQS_DP<3>")
	)
	(segment
		(start 31.21279 -199.229726)
		(end 29.299662 -199.96531)
		(width 0.18288)
		(layer "In11.Cu")
		(net "M_D_CPU1_SB_DQS_DP<3>")
	)
	(segment
		(start 37.150548 -200.869804)
		(end 36.46932 -200.869804)
		(width 0.18288)
		(layer "In11.Cu")
		(net "M_D_CPU1_SB_DQS_DP<3>")
	)
	(segment
		(start 35.735768 -201.140568)
		(end 35.478212 -200.883012)
		(width 0.18288)
		(layer "In11.Cu")
		(net "M_D_CPU1_SB_DQS_DP<3>")
	)
	(segment
		(start 20.710144 -201.1426)
		(end 20.406614 -200.83907)
		(width 0.18288)
		(layer "In11.Cu")
		(net "M_D_CPU1_SB_DQS_DP<3>")
	)
	(segment
		(start 64.827404 -203.873862)
		(end 63.775844 -203.43876)
		(width 0.18288)
		(layer "In11.Cu")
		(net "M_D_CPU1_SB_DQS_DP<3>")
	)
	(segment
		(start 20.406614 -200.83907)
		(end 20.204684 -200.83907)
		(width 0.18288)
		(layer "In11.Cu")
		(net "M_D_CPU1_SB_DQS_DP<3>")
	)
	(segment
		(start 44.569888 -199.921876)
		(end 38.543484 -199.921876)
		(width 0.18288)
		(layer "In11.Cu")
		(net "M_D_CPU1_SB_DQS_DP<3>")
	)
	(segment
		(start 32.360616 -199.211438)
		(end 32.128206 -199.443848)
		(width 0.18288)
		(layer "In11.Cu")
		(net "M_D_CPU1_SB_DQS_DP<3>")
	)
	(segment
		(start 47.165006 -199.441308)
		(end 46.697646 -199.441308)
		(width 0.18288)
		(layer "In11.Cu")
		(net "M_D_CPU1_SB_DQS_DP<3>")
	)
	(segment
		(start 82.551778 -224.835974)
		(end 82.466942 -224.835974)
		(width 0.088646)
		(layer "In11.Cu")
		(net "M_D_CPU1_SB_DQS_DP<3>")
	)
	(segment
		(start 61.639704 -200.3933)
		(end 61.046106 -200.147174)
		(width 0.18288)
		(layer "In11.Cu")
		(net "M_D_CPU1_SB_DQS_DP<3>")
	)
	(segment
		(start 97.826068 -230.41102)
		(end 97.825814 -230.41102)
		(width 0.088646)
		(layer "In11.Cu")
		(net "M_D_CPU1_SB_DQS_DP<3>")
	)
	(segment
		(start 86.548214 -226.506786)
		(end 86.5378 -226.512882)
		(width 0.088646)
		(layer "In11.Cu")
		(net "M_D_CPU1_SB_DQS_DP<3>")
	)
	(segment
		(start 47.470822 -199.135492)
		(end 47.165006 -199.441308)
		(width 0.18288)
		(layer "In11.Cu")
		(net "M_D_CPU1_SB_DQS_DP<3>")
	)
	(segment
		(start 89.367614 -228.134672)
		(end 89.352882 -228.143308)
		(width 0.088646)
		(layer "In11.Cu")
		(net "M_D_CPU1_SB_DQS_DP<3>")
	)
	(segment
		(start 31.411164 -199.229726)
		(end 31.21279 -199.229726)
		(width 0.18288)
		(layer "In11.Cu")
		(net "M_D_CPU1_SB_DQS_DP<3>")
	)
	(segment
		(start 18.697702 -200.214738)
		(end 18.099532 -200.214738)
		(width 0.18288)
		(layer "In11.Cu")
		(net "M_D_CPU1_SB_DQS_DP<3>")
	)
	(segment
		(start 57.782206 -199.618092)
		(end 55.602632 -199.618092)
		(width 0.18288)
		(layer "In11.Cu")
		(net "M_D_CPU1_SB_DQS_DP<3>")
	)
	(segment
		(start 94.066614 -228.134672)
		(end 94.051882 -228.143308)
		(width 0.088646)
		(layer "In11.Cu")
		(net "M_D_CPU1_SB_DQS_DP<3>")
	)
	(segment
		(start 87.39251 -227.320602)
		(end 87.386414 -227.317046)
		(width 0.088646)
		(layer "In11.Cu")
		(net "M_D_CPU1_SB_DQS_DP<3>")
	)
	(segment
		(start 51.278282 -201.138282)
		(end 50.789586 -201.138282)
		(width 0.18288)
		(layer "In11.Cu")
		(net "M_D_CPU1_SB_DQS_DP<3>")
	)
	(segment
		(start 50.002186 -200.928732)
		(end 48.208946 -199.135492)
		(width 0.18288)
		(layer "In11.Cu")
		(net "M_D_CPU1_SB_DQS_DP<3>")
	)
	(segment
		(start 74.218292 -216.587324)
		(end 74.218292 -213.26475)
		(width 0.18288)
		(layer "In11.Cu")
		(net "M_D_CPU1_SB_DQS_DP<3>")
	)
	(segment
		(start 96.3295 -228.139752)
		(end 96.32061 -228.134672)
		(width 0.088646)
		(layer "In11.Cu")
		(net "M_D_CPU1_SB_DQS_DP<3>")
	)
	(segment
		(start 82.466942 -224.835974)
		(end 74.218292 -216.587324)
		(width 0.18288)
		(layer "In11.Cu")
		(net "M_D_CPU1_SB_DQS_DP<3>")
	)
	(segment
		(start 46.43755 -199.181212)
		(end 46.356524 -199.181212)
		(width 0.18288)
		(layer "In11.Cu")
		(net "M_D_CPU1_SB_DQS_DP<3>")
	)
	(segment
		(start 83.059778 -225.343974)
		(end 82.551778 -224.835974)
		(width 0.088646)
		(layer "In11.Cu")
		(net "M_D_CPU1_SB_DQS_DP<3>")
	)
	(segment
		(start 31.625286 -199.443848)
		(end 31.411164 -199.229726)
		(width 0.18288)
		(layer "In11.Cu")
		(net "M_D_CPU1_SB_DQS_DP<3>")
	)
	(segment
		(start 97.26041 -229.762304)
		(end 97.260664 -229.762304)
		(width 0.088646)
		(layer "In11.Cu")
		(net "M_D_CPU1_SB_DQS_DP<3>")
	)
	(segment
		(start 97.825814 -230.41102)
		(end 97.816924 -230.40594)
		(width 0.088646)
		(layer "In11.Cu")
		(net "M_D_CPU1_SB_DQS_DP<3>")
	)
	(segment
		(start 88.427814 -228.134672)
		(end 88.4174 -228.140768)
		(width 0.088646)
		(layer "In11.Cu")
		(net "M_D_CPU1_SB_DQS_DP<3>")
	)
	(segment
		(start 21.166074 -201.1426)
		(end 20.710144 -201.1426)
		(width 0.18288)
		(layer "In11.Cu")
		(net "M_D_CPU1_SB_DQS_DP<3>")
	)
	(segment
		(start 38.543484 -199.921876)
		(end 37.911278 -200.554082)
		(width 0.18288)
		(layer "In11.Cu")
		(net "M_D_CPU1_SB_DQS_DP<3>")
	)
	(segment
		(start 83.849464 -226.406456)
		(end 83.059778 -225.61677)
		(width 0.088646)
		(layer "In11.Cu")
		(net "M_D_CPU1_SB_DQS_DP<3>")
	)
	(segment
		(start 87.4014 -227.325682)
		(end 87.39251 -227.320602)
		(width 0.088646)
		(layer "In11.Cu")
		(net "M_D_CPU1_SB_DQS_DP<3>")
	)
	(segment
		(start 96.792288 -228.94925)
		(end 96.790764 -228.948488)
		(width 0.088646)
		(layer "In11.Cu")
		(net "M_D_CPU1_SB_DQS_DP<3>")
	)
	(segment
		(start 98.228912 -230.39451)
		(end 98.200464 -230.41102)
		(width 0.088646)
		(layer "In11.Cu")
		(net "M_D_CPU1_SB_DQS_DP<3>")
	)
	(segment
		(start 98.952812 -230.086662)
		(end 98.228912 -230.39451)
		(width 0.088646)
		(layer "In11.Cu")
		(net "M_D_CPU1_SB_DQS_DP<3>")
	)
	(segment
		(start 46.697646 -199.441308)
		(end 46.43755 -199.181212)
		(width 0.18288)
		(layer "In11.Cu")
		(net "M_D_CPU1_SB_DQS_DP<3>")
	)
	(segment
		(start 35.028378 -200.883012)
		(end 34.068258 -199.922892)
		(width 0.18288)
		(layer "In11.Cu")
		(net "M_D_CPU1_SB_DQS_DP<3>")
	)
	(segment
		(start 90.307414 -228.134672)
		(end 90.292682 -228.143308)
		(width 0.088646)
		(layer "In11.Cu")
		(net "M_D_CPU1_SB_DQS_DP<3>")
	)
	(segment
		(start 59.059572 -200.147174)
		(end 57.782206 -199.618092)
		(width 0.18288)
		(layer "In11.Cu")
		(net "M_D_CPU1_SB_DQS_DP<3>")
	)
	(segment
		(start 74.218292 -213.26475)
		(end 64.827404 -203.873862)
		(width 0.18288)
		(layer "In11.Cu")
		(net "M_D_CPU1_SB_DQS_DP<3>")
	)
	(segment
		(start 17.072356 -200.433432)
		(end 16.789146 -200.716642)
		(width 0.18288)
		(layer "In11.Cu")
		(net "M_D_CPU1_SB_DQS_DP<3>")
	)
	(segment
		(start 93.126814 -228.134672)
		(end 93.112082 -228.143308)
		(width 0.088646)
		(layer "In11.Cu")
		(net "M_D_CPU1_SB_DQS_DP<3>")
	)
	(segment
		(start 51.575208 -200.841356)
		(end 51.278282 -201.138282)
		(width 0.18288)
		(layer "In11.Cu")
		(net "M_D_CPU1_SB_DQS_DP<3>")
	)
	(segment
		(start 21.447506 -200.861168)
		(end 21.166074 -201.1426)
		(width 0.18288)
		(layer "In11.Cu")
		(net "M_D_CPU1_SB_DQS_DP<3>")
	)
	(segment
		(start 36.46932 -200.869804)
		(end 36.198556 -201.140568)
		(width 0.18288)
		(layer "In11.Cu")
		(net "M_D_CPU1_SB_DQS_DP<3>")
	)
	(segment
		(start 97.638362 -230.013256)
		(end 97.54616 -229.926642)
		(width 0.088646)
		(layer "In11.Cu")
		(net "M_D_CPU1_SB_DQS_DP<3>")
	)
	(segment
		(start 22.634702 -200.861168)
		(end 21.447506 -200.861168)
		(width 0.18288)
		(layer "In11.Cu")
		(net "M_D_CPU1_SB_DQS_DP<3>")
	)
	(segment
		(start 46.356524 -199.181212)
		(end 44.569888 -199.921876)
		(width 0.18288)
		(layer "In11.Cu")
		(net "M_D_CPU1_SB_DQS_DP<3>")
	)
	(segment
		(start 29.299662 -199.96531)
		(end 26.573734 -199.96531)
		(width 0.18288)
		(layer "In11.Cu")
		(net "M_D_CPU1_SB_DQS_DP<3>")
	)
	(segment
		(start 52.71389 -200.841356)
		(end 51.575208 -200.841356)
		(width 0.18288)
		(layer "In11.Cu")
		(net "M_D_CPU1_SB_DQS_DP<3>")
	)
	(segment
		(start 96.799654 -228.953568)
		(end 96.792288 -228.94925)
		(width 0.088646)
		(layer "In11.Cu")
		(net "M_D_CPU1_SB_DQS_DP<3>")
	)
	(segment
		(start 36.198556 -201.140568)
		(end 35.735768 -201.140568)
		(width 0.18288)
		(layer "In11.Cu")
		(net "M_D_CPU1_SB_DQS_DP<3>")
	)
	(segment
		(start 34.068258 -199.922892)
		(end 32.766254 -199.211438)
		(width 0.18288)
		(layer "In11.Cu")
		(net "M_D_CPU1_SB_DQS_DP<3>")
	)
	(segment
		(start 87.579962 -227.65258)
		(end 87.579962 -227.64496)
		(width 0.088646)
		(layer "In11.Cu")
		(net "M_D_CPU1_SB_DQS_DP<3>")
	)
	(segment
		(start 96.78797 -228.946964)
		(end 96.784668 -228.944932)
		(width 0.088646)
		(layer "In11.Cu")
		(net "M_D_CPU1_SB_DQS_DP<3>")
	)
	(segment
		(start 35.478212 -200.883012)
		(end 35.028378 -200.883012)
		(width 0.18288)
		(layer "In11.Cu")
		(net "M_D_CPU1_SB_DQS_DP<3>")
	)
	(segment
		(start 84.681822 -226.406456)
		(end 83.849464 -226.406456)
		(width 0.088646)
		(layer "In11.Cu")
		(net "M_D_CPU1_SB_DQS_DP<3>")
	)
	(segment
		(start 96.790764 -228.948488)
		(end 96.78797 -228.946964)
		(width 0.088646)
		(layer "In11.Cu")
		(net "M_D_CPU1_SB_DQS_DP<3>")
	)
	(segment
		(start 55.602632 -199.618092)
		(end 52.71389 -200.841356)
		(width 0.18288)
		(layer "In11.Cu")
		(net "M_D_CPU1_SB_DQS_DP<3>")
	)
	(segment
		(start 91.247468 -228.134672)
		(end 91.237054 -228.140768)
		(width 0.088646)
		(layer "In11.Cu")
		(net "M_D_CPU1_SB_DQS_DP<3>")
	)
	(segment
		(start 63.775844 -203.43876)
		(end 63.241174 -202.90409)
		(width 0.18288)
		(layer "In11.Cu")
		(net "M_D_CPU1_SB_DQS_DP<3>")
	)
	(segment
		(start 86.9315 -226.511866)
		(end 86.92261 -226.506786)
		(width 0.088646)
		(layer "In11.Cu")
		(net "M_D_CPU1_SB_DQS_DP<3>")
	)
	(segment
		(start 61.046106 -200.147174)
		(end 59.059572 -200.147174)
		(width 0.18288)
		(layer "In11.Cu")
		(net "M_D_CPU1_SB_DQS_DP<3>")
	)
	(arc
		(start 96.784668 -228.944932)
		(mid 96.582081 -228.738581)
		(end 96.508062 -228.45903)
		(width 0.088646)
		(layer "In11.Cu")
		(net "M_D_CPU1_SB_DQS_DP<3>")
	)
	(arc
		(start 85.053424 -226.512882)
		(mid 85.047347 -226.509042)
		(end 85.041232 -226.505262)
		(width 0.088646)
		(layer "In11.Cu")
		(net "M_D_CPU1_SB_DQS_DP<3>")
	)
	(arc
		(start 85.608668 -226.506786)
		(mid 85.331855 -226.582656)
		(end 85.053424 -226.512882)
		(width 0.088646)
		(layer "In11.Cu")
		(net "M_D_CPU1_SB_DQS_DP<3>")
	)
	(arc
		(start 92.187014 -228.134672)
		(mid 91.910455 -228.210381)
		(end 91.632278 -228.140768)
		(width 0.088646)
		(layer "In11.Cu")
		(net "M_D_CPU1_SB_DQS_DP<3>")
	)
	(arc
		(start 96.978216 -229.272846)
		(mid 96.930537 -229.089946)
		(end 96.799654 -228.953568)
		(width 0.088646)
		(layer "In11.Cu")
		(net "M_D_CPU1_SB_DQS_DP<3>")
	)
	(arc
		(start 86.5378 -226.512882)
		(mid 86.259622 -226.582605)
		(end 85.983064 -226.506786)
		(width 0.088646)
		(layer "In11.Cu")
		(net "M_D_CPU1_SB_DQS_DP<3>")
	)
	(arc
		(start 87.579962 -227.64496)
		(mid 87.532283 -227.46206)
		(end 87.4014 -227.325682)
		(width 0.088646)
		(layer "In11.Cu")
		(net "M_D_CPU1_SB_DQS_DP<3>")
	)
	(arc
		(start 85.041232 -226.505262)
		(mid 84.868184 -226.431648)
		(end 84.681822 -226.406456)
		(width 0.088646)
		(layer "In11.Cu")
		(net "M_D_CPU1_SB_DQS_DP<3>")
	)
	(arc
		(start 97.260664 -229.762304)
		(mid 97.053904 -229.555541)
		(end 96.978216 -229.2731)
		(width 0.088646)
		(layer "In11.Cu")
		(net "M_D_CPU1_SB_DQS_DP<3>")
	)
	(arc
		(start 89.352882 -228.143308)
		(mid 89.076441 -228.210474)
		(end 88.80221 -228.134672)
		(width 0.088646)
		(layer "In11.Cu")
		(net "M_D_CPU1_SB_DQS_DP<3>")
	)
	(arc
		(start 94.991682 -228.143308)
		(mid 94.715241 -228.210474)
		(end 94.44101 -228.134672)
		(width 0.088646)
		(layer "In11.Cu")
		(net "M_D_CPU1_SB_DQS_DP<3>")
	)
	(arc
		(start 87.386414 -227.317046)
		(mid 87.184001 -227.110633)
		(end 87.110062 -226.831144)
		(width 0.088646)
		(layer "In11.Cu")
		(net "M_D_CPU1_SB_DQS_DP<3>")
	)
	(arc
		(start 94.051882 -228.143308)
		(mid 93.775441 -228.210474)
		(end 93.50121 -228.134672)
		(width 0.088646)
		(layer "In11.Cu")
		(net "M_D_CPU1_SB_DQS_DP<3>")
	)
	(arc
		(start 96.32061 -228.134672)
		(mid 96.133412 -228.084529)
		(end 95.946214 -228.134672)
		(width 0.088646)
		(layer "In11.Cu")
		(net "M_D_CPU1_SB_DQS_DP<3>")
	)
	(arc
		(start 86.92261 -226.506786)
		(mid 86.735412 -226.456643)
		(end 86.548214 -226.506786)
		(width 0.088646)
		(layer "In11.Cu")
		(net "M_D_CPU1_SB_DQS_DP<3>")
	)
	(arc
		(start 85.983064 -226.506786)
		(mid 85.795866 -226.456643)
		(end 85.608668 -226.506786)
		(width 0.088646)
		(layer "In11.Cu")
		(net "M_D_CPU1_SB_DQS_DP<3>")
	)
	(arc
		(start 89.74201 -228.134672)
		(mid 89.554812 -228.084529)
		(end 89.367614 -228.134672)
		(width 0.088646)
		(layer "In11.Cu")
		(net "M_D_CPU1_SB_DQS_DP<3>")
	)
	(arc
		(start 95.38081 -228.134672)
		(mid 95.193612 -228.084529)
		(end 95.006414 -228.134672)
		(width 0.088646)
		(layer "In11.Cu")
		(net "M_D_CPU1_SB_DQS_DP<3>")
	)
	(arc
		(start 88.80221 -228.134672)
		(mid 88.615012 -228.084529)
		(end 88.427814 -228.134672)
		(width 0.088646)
		(layer "In11.Cu")
		(net "M_D_CPU1_SB_DQS_DP<3>")
	)
	(arc
		(start 95.931482 -228.143308)
		(mid 95.655041 -228.210474)
		(end 95.38081 -228.134672)
		(width 0.088646)
		(layer "In11.Cu")
		(net "M_D_CPU1_SB_DQS_DP<3>")
	)
	(arc
		(start 93.50121 -228.134672)
		(mid 93.314012 -228.084529)
		(end 93.126814 -228.134672)
		(width 0.088646)
		(layer "In11.Cu")
		(net "M_D_CPU1_SB_DQS_DP<3>")
	)
	(arc
		(start 90.68181 -228.134672)
		(mid 90.494612 -228.084529)
		(end 90.307414 -228.134672)
		(width 0.088646)
		(layer "In11.Cu")
		(net "M_D_CPU1_SB_DQS_DP<3>")
	)
	(arc
		(start 92.56141 -228.134672)
		(mid 92.374212 -228.084529)
		(end 92.187014 -228.134672)
		(width 0.088646)
		(layer "In11.Cu")
		(net "M_D_CPU1_SB_DQS_DP<3>")
	)
	(arc
		(start 97.816924 -230.40594)
		(mid 97.68601 -230.26958)
		(end 97.638362 -230.086662)
		(width 0.088646)
		(layer "In11.Cu")
		(net "M_D_CPU1_SB_DQS_DP<3>")
	)
	(arc
		(start 96.508062 -228.45903)
		(mid 96.50801 -228.451663)
		(end 96.507808 -228.444298)
		(width 0.088646)
		(layer "In11.Cu")
		(net "M_D_CPU1_SB_DQS_DP<3>")
	)
	(arc
		(start 88.4174 -228.140768)
		(mid 88.139222 -228.21046)
		(end 87.862664 -228.134672)
		(width 0.088646)
		(layer "In11.Cu")
		(net "M_D_CPU1_SB_DQS_DP<3>")
	)
	(arc
		(start 90.292682 -228.143308)
		(mid 90.016241 -228.210474)
		(end 89.74201 -228.134672)
		(width 0.088646)
		(layer "In11.Cu")
		(net "M_D_CPU1_SB_DQS_DP<3>")
	)
	(arc
		(start 96.507808 -228.444298)
		(mid 96.456754 -228.269718)
		(end 96.3295 -228.139752)
		(width 0.088646)
		(layer "In11.Cu")
		(net "M_D_CPU1_SB_DQS_DP<3>")
	)
	(arc
		(start 91.237054 -228.140768)
		(mid 90.958622 -228.210582)
		(end 90.68181 -228.134672)
		(width 0.088646)
		(layer "In11.Cu")
		(net "M_D_CPU1_SB_DQS_DP<3>")
	)
	(arc
		(start 93.112082 -228.143308)
		(mid 92.835641 -228.210474)
		(end 92.56141 -228.134672)
		(width 0.088646)
		(layer "In11.Cu")
		(net "M_D_CPU1_SB_DQS_DP<3>")
	)
	(arc
		(start 91.621864 -228.134672)
		(mid 91.434666 -228.084529)
		(end 91.247468 -228.134672)
		(width 0.088646)
		(layer "In11.Cu")
		(net "M_D_CPU1_SB_DQS_DP<3>")
	)
	(arc
		(start 94.44101 -228.134672)
		(mid 94.253812 -228.084529)
		(end 94.066614 -228.134672)
		(width 0.088646)
		(layer "In11.Cu")
		(net "M_D_CPU1_SB_DQS_DP<3>")
	)
	(arc
		(start 87.862664 -228.134672)
		(mid 87.657592 -227.930993)
		(end 87.579962 -227.65258)
		(width 0.088646)
		(layer "In11.Cu")
		(net "M_D_CPU1_SB_DQS_DP<3>")
	)
	(arc
		(start 98.200464 -230.41102)
		(mid 98.013266 -230.461197)
		(end 97.826068 -230.41102)
		(width 0.088646)
		(layer "In11.Cu")
		(net "M_D_CPU1_SB_DQS_DP<3>")
	)
	(arc
		(start 87.110062 -226.831144)
		(mid 87.062383 -226.648244)
		(end 86.9315 -226.511866)
		(width 0.088646)
		(layer "In11.Cu")
		(net "M_D_CPU1_SB_DQS_DP<3>")
	)
	(segment
		(start 13.854684 -210.23072)
		(end 13.593572 -210.491832)
		(width 0.20066)
		(layer "F.Cu")
		(net "M_D_CPU1_SB_DQS_DP<2>")
	)
	(segment
		(start 11.11631 -210.50123)
		(end 10.898124 -210.50123)
		(width 0.20066)
		(layer "F.Cu")
		(net "M_D_CPU1_SB_DQS_DP<2>")
	)
	(segment
		(start 10.898124 -210.50123)
		(end 10.627614 -210.23072)
		(width 0.20066)
		(layer "F.Cu")
		(net "M_D_CPU1_SB_DQS_DP<2>")
	)
	(segment
		(start 14.605762 -209.805524)
		(end 14.180566 -210.23072)
		(width 0.20066)
		(layer "F.Cu")
		(net "M_D_CPU1_SB_DQS_DP<2>")
	)
	(segment
		(start 8.678418 -210.066636)
		(end 8.140446 -210.066636)
		(width 0.20066)
		(layer "F.Cu")
		(net "M_D_CPU1_SB_DQS_DP<2>")
	)
	(segment
		(start 95.663766 -233.06405)
		(end 95.663766 -232.528364)
		(width 0.20066)
		(layer "F.Cu")
		(net "M_D_CPU1_SB_DQS_DP<2>")
	)
	(segment
		(start 13.118084 -210.491832)
		(end 11.36269 -210.491832)
		(width 0.1016)
		(layer "F.Cu")
		(net "M_D_CPU1_SB_DQS_DP<2>")
	)
	(segment
		(start 14.180566 -210.23072)
		(end 13.854684 -210.23072)
		(width 0.20066)
		(layer "F.Cu")
		(net "M_D_CPU1_SB_DQS_DP<2>")
	)
	(segment
		(start 11.36269 -210.491832)
		(end 11.125708 -210.491832)
		(width 0.101854)
		(layer "F.Cu")
		(net "M_D_CPU1_SB_DQS_DP<2>")
	)
	(segment
		(start 16.789146 -210.066636)
		(end 15.684246 -210.066636)
		(width 0.20066)
		(layer "F.Cu")
		(net "M_D_CPU1_SB_DQS_DP<2>")
	)
	(segment
		(start 13.593572 -210.491832)
		(end 13.441426 -210.491832)
		(width 0.20066)
		(layer "F.Cu")
		(net "M_D_CPU1_SB_DQS_DP<2>")
	)
	(segment
		(start 14.874494 -209.805524)
		(end 14.605762 -209.805524)
		(width 0.20066)
		(layer "F.Cu")
		(net "M_D_CPU1_SB_DQS_DP<2>")
	)
	(segment
		(start 10.000488 -210.23072)
		(end 9.364472 -209.805524)
		(width 0.20066)
		(layer "F.Cu")
		(net "M_D_CPU1_SB_DQS_DP<2>")
	)
	(segment
		(start 8.93953 -209.805524)
		(end 8.678418 -210.066636)
		(width 0.20066)
		(layer "F.Cu")
		(net "M_D_CPU1_SB_DQS_DP<2>")
	)
	(segment
		(start 10.627614 -210.23072)
		(end 10.000488 -210.23072)
		(width 0.20066)
		(layer "F.Cu")
		(net "M_D_CPU1_SB_DQS_DP<2>")
	)
	(segment
		(start 13.441426 -210.491832)
		(end 13.118084 -210.491832)
		(width 0.101854)
		(layer "F.Cu")
		(net "M_D_CPU1_SB_DQS_DP<2>")
	)
	(segment
		(start 9.364472 -209.805524)
		(end 8.93953 -209.805524)
		(width 0.20066)
		(layer "F.Cu")
		(net "M_D_CPU1_SB_DQS_DP<2>")
	)
	(segment
		(start 11.125708 -210.491832)
		(end 11.11631 -210.50123)
		(width 0.101854)
		(layer "F.Cu")
		(net "M_D_CPU1_SB_DQS_DP<2>")
	)
	(segment
		(start 95.663512 -233.064304)
		(end 95.663766 -233.06405)
		(width 0.20066)
		(layer "F.Cu")
		(net "M_D_CPU1_SB_DQS_DP<2>")
	)
	(segment
		(start 15.135606 -210.066636)
		(end 14.874494 -209.805524)
		(width 0.20066)
		(layer "F.Cu")
		(net "M_D_CPU1_SB_DQS_DP<2>")
	)
	(segment
		(start 15.684246 -210.066636)
		(end 15.135606 -210.066636)
		(width 0.20066)
		(layer "F.Cu")
		(net "M_D_CPU1_SB_DQS_DP<2>")
	)
	(segment
		(start 82.632042 -229.465124)
		(end 77.453998 -229.465124)
		(width 0.18288)
		(layer "In6.Cu")
		(net "M_D_CPU1_SB_DQS_DP<2>")
	)
	(segment
		(start 66.162174 -216.238074)
		(end 65.206118 -215.282018)
		(width 0.18288)
		(layer "In6.Cu")
		(net "M_D_CPU1_SB_DQS_DP<2>")
	)
	(segment
		(start 83.731862 -230.578152)
		(end 83.009232 -229.855522)
		(width 0.088646)
		(layer "In6.Cu")
		(net "M_D_CPU1_SB_DQS_DP<2>")
	)
	(segment
		(start 46.748954 -211.340954)
		(end 46.485302 -211.077302)
		(width 0.18288)
		(layer "In6.Cu")
		(net "M_D_CPU1_SB_DQS_DP<2>")
	)
	(segment
		(start 40.985948 -209.589624)
		(end 39.501572 -210.204304)
		(width 0.18288)
		(layer "In6.Cu")
		(net "M_D_CPU1_SB_DQS_DP<2>")
	)
	(segment
		(start 73.737978 -225.749104)
		(end 73.737978 -222.842328)
		(width 0.18288)
		(layer "In6.Cu")
		(net "M_D_CPU1_SB_DQS_DP<2>")
	)
	(segment
		(start 24.449532 -210.208876)
		(end 21.388832 -210.208876)
		(width 0.18288)
		(layer "In6.Cu")
		(net "M_D_CPU1_SB_DQS_DP<2>")
	)
	(segment
		(start 33.06826 -210.821016)
		(end 32.836358 -211.052918)
		(width 0.18288)
		(layer "In6.Cu")
		(net "M_D_CPU1_SB_DQS_DP<2>")
	)
	(segment
		(start 18.665698 -209.55635)
		(end 18.394172 -209.55635)
		(width 0.18288)
		(layer "In6.Cu")
		(net "M_D_CPU1_SB_DQS_DP<2>")
	)
	(segment
		(start 32.093662 -211.341716)
		(end 31.678626 -211.341716)
		(width 0.18288)
		(layer "In6.Cu")
		(net "M_D_CPU1_SB_DQS_DP<2>")
	)
	(segment
		(start 45.67936 -211.077302)
		(end 44.191682 -209.589624)
		(width 0.18288)
		(layer "In6.Cu")
		(net "M_D_CPU1_SB_DQS_DP<2>")
	)
	(segment
		(start 35.489134 -210.202018)
		(end 34.853626 -210.202018)
		(width 0.18288)
		(layer "In6.Cu")
		(net "M_D_CPU1_SB_DQS_DP<2>")
	)
	(segment
		(start 34.853626 -210.202018)
		(end 34.444178 -210.611466)
		(width 0.18288)
		(layer "In6.Cu")
		(net "M_D_CPU1_SB_DQS_DP<2>")
	)
	(segment
		(start 55.765446 -210.756754)
		(end 55.050182 -210.46059)
		(width 0.18288)
		(layer "In6.Cu")
		(net "M_D_CPU1_SB_DQS_DP<2>")
	)
	(segment
		(start 50.854864 -210.491324)
		(end 50.573432 -210.209892)
		(width 0.18288)
		(layer "In6.Cu")
		(net "M_D_CPU1_SB_DQS_DP<2>")
	)
	(segment
		(start 64.345566 -213.205568)
		(end 63.884556 -212.744304)
		(width 0.18288)
		(layer "In6.Cu")
		(net "M_D_CPU1_SB_DQS_DP<2>")
	)
	(segment
		(start 91.632278 -233.023918)
		(end 91.621864 -233.017822)
		(width 0.088646)
		(layer "In6.Cu")
		(net "M_D_CPU1_SB_DQS_DP<2>")
	)
	(segment
		(start 32.371538 -211.06384)
		(end 32.093662 -211.341716)
		(width 0.18288)
		(layer "In6.Cu")
		(net "M_D_CPU1_SB_DQS_DP<2>")
	)
	(segment
		(start 34.444178 -210.611466)
		(end 33.939226 -210.821016)
		(width 0.18288)
		(layer "In6.Cu")
		(net "M_D_CPU1_SB_DQS_DP<2>")
	)
	(segment
		(start 19.182842 -209.770726)
		(end 18.665698 -209.55635)
		(width 0.18288)
		(layer "In6.Cu")
		(net "M_D_CPU1_SB_DQS_DP<2>")
	)
	(segment
		(start 31.411926 -211.075016)
		(end 30.971744 -211.075016)
		(width 0.18288)
		(layer "In6.Cu")
		(net "M_D_CPU1_SB_DQS_DP<2>")
	)
	(segment
		(start 95.323406 -232.61828)
		(end 94.89821 -232.860088)
		(width 0.088646)
		(layer "In6.Cu")
		(net "M_D_CPU1_SB_DQS_DP<2>")
	)
	(segment
		(start 82.715354 -229.40518)
		(end 82.65541 -229.465124)
		(width 0.088646)
		(layer "In6.Cu")
		(net "M_D_CPU1_SB_DQS_DP<2>")
	)
	(segment
		(start 82.902044 -229.40518)
		(end 82.715354 -229.40518)
		(width 0.088646)
		(layer "In6.Cu")
		(net "M_D_CPU1_SB_DQS_DP<2>")
	)
	(segment
		(start 48.641 -211.081874)
		(end 47.428404 -211.081874)
		(width 0.18288)
		(layer "In6.Cu")
		(net "M_D_CPU1_SB_DQS_DP<2>")
	)
	(segment
		(start 55.050182 -210.46059)
		(end 52.500784 -210.46059)
		(width 0.18288)
		(layer "In6.Cu")
		(net "M_D_CPU1_SB_DQS_DP<2>")
	)
	(segment
		(start 47.169324 -211.340954)
		(end 46.748954 -211.340954)
		(width 0.18288)
		(layer "In6.Cu")
		(net "M_D_CPU1_SB_DQS_DP<2>")
	)
	(segment
		(start 86.078568 -232.204006)
		(end 86.068154 -232.210102)
		(width 0.088646)
		(layer "In6.Cu")
		(net "M_D_CPU1_SB_DQS_DP<2>")
	)
	(segment
		(start 18.394172 -209.55635)
		(end 17.841722 -209.785204)
		(width 0.18288)
		(layer "In6.Cu")
		(net "M_D_CPU1_SB_DQS_DP<2>")
	)
	(segment
		(start 29.065728 -209.842354)
		(end 28.368244 -209.553302)
		(width 0.18288)
		(layer "In6.Cu")
		(net "M_D_CPU1_SB_DQS_DP<2>")
	)
	(segment
		(start 83.009232 -229.855522)
		(end 83.009232 -229.512368)
		(width 0.088646)
		(layer "In6.Cu")
		(net "M_D_CPU1_SB_DQS_DP<2>")
	)
	(segment
		(start 63.884556 -212.744304)
		(end 61.306456 -211.676234)
		(width 0.18288)
		(layer "In6.Cu")
		(net "M_D_CPU1_SB_DQS_DP<2>")
	)
	(segment
		(start 39.501572 -210.204304)
		(end 36.481004 -210.204304)
		(width 0.18288)
		(layer "In6.Cu")
		(net "M_D_CPU1_SB_DQS_DP<2>")
	)
	(segment
		(start 47.428404 -211.081874)
		(end 47.169324 -211.340954)
		(width 0.18288)
		(layer "In6.Cu")
		(net "M_D_CPU1_SB_DQS_DP<2>")
	)
	(segment
		(start 94.275402 -232.897426)
		(end 94.051882 -233.026458)
		(width 0.088646)
		(layer "In6.Cu")
		(net "M_D_CPU1_SB_DQS_DP<2>")
	)
	(segment
		(start 30.971744 -211.075016)
		(end 30.519878 -210.887818)
		(width 0.18288)
		(layer "In6.Cu")
		(net "M_D_CPU1_SB_DQS_DP<2>")
	)
	(segment
		(start 59.574938 -211.676234)
		(end 58.823098 -211.36483)
		(width 0.18288)
		(layer "In6.Cu")
		(net "M_D_CPU1_SB_DQS_DP<2>")
	)
	(segment
		(start 30.519878 -210.887818)
		(end 29.763466 -210.13166)
		(width 0.18288)
		(layer "In6.Cu")
		(net "M_D_CPU1_SB_DQS_DP<2>")
	)
	(segment
		(start 44.191682 -209.589624)
		(end 40.985948 -209.589624)
		(width 0.18288)
		(layer "In6.Cu")
		(net "M_D_CPU1_SB_DQS_DP<2>")
	)
	(segment
		(start 21.10613 -210.491578)
		(end 20.691094 -210.491578)
		(width 0.18288)
		(layer "In6.Cu")
		(net "M_D_CPU1_SB_DQS_DP<2>")
	)
	(segment
		(start 91.247468 -233.017822)
		(end 91.237054 -233.023918)
		(width 0.088646)
		(layer "In6.Cu")
		(net "M_D_CPU1_SB_DQS_DP<2>")
	)
	(segment
		(start 90.307414 -233.017822)
		(end 90.292682 -233.026458)
		(width 0.088646)
		(layer "In6.Cu")
		(net "M_D_CPU1_SB_DQS_DP<2>")
	)
	(segment
		(start 49.497234 -210.72729)
		(end 48.641 -211.081874)
		(width 0.18288)
		(layer "In6.Cu")
		(net "M_D_CPU1_SB_DQS_DP<2>")
	)
	(segment
		(start 46.485302 -211.077302)
		(end 45.67936 -211.077302)
		(width 0.18288)
		(layer "In6.Cu")
		(net "M_D_CPU1_SB_DQS_DP<2>")
	)
	(segment
		(start 21.388832 -210.208876)
		(end 21.10613 -210.491578)
		(width 0.18288)
		(layer "In6.Cu")
		(net "M_D_CPU1_SB_DQS_DP<2>")
	)
	(segment
		(start 77.453998 -229.465124)
		(end 73.737978 -225.749104)
		(width 0.18288)
		(layer "In6.Cu")
		(net "M_D_CPU1_SB_DQS_DP<2>")
	)
	(segment
		(start 58.823098 -211.36483)
		(end 55.765446 -210.756754)
		(width 0.18288)
		(layer "In6.Cu")
		(net "M_D_CPU1_SB_DQS_DP<2>")
	)
	(segment
		(start 73.737978 -222.842328)
		(end 67.133724 -216.238074)
		(width 0.18288)
		(layer "In6.Cu")
		(net "M_D_CPU1_SB_DQS_DP<2>")
	)
	(segment
		(start 20.401534 -210.202018)
		(end 19.614642 -210.202018)
		(width 0.18288)
		(layer "In6.Cu")
		(net "M_D_CPU1_SB_DQS_DP<2>")
	)
	(segment
		(start 29.763466 -210.13166)
		(end 29.065728 -209.842354)
		(width 0.18288)
		(layer "In6.Cu")
		(net "M_D_CPU1_SB_DQS_DP<2>")
	)
	(segment
		(start 89.273888 -232.204768)
		(end 89.272364 -232.204006)
		(width 0.088646)
		(layer "In6.Cu")
		(net "M_D_CPU1_SB_DQS_DP<2>")
	)
	(segment
		(start 17.070578 -209.785204)
		(end 16.789146 -210.066636)
		(width 0.18288)
		(layer "In6.Cu")
		(net "M_D_CPU1_SB_DQS_DP<2>")
	)
	(segment
		(start 88.347296 -232.212642)
		(end 88.332564 -232.204006)
		(width 0.088646)
		(layer "In6.Cu")
		(net "M_D_CPU1_SB_DQS_DP<2>")
	)
	(segment
		(start 35.778694 -210.491578)
		(end 35.489134 -210.202018)
		(width 0.18288)
		(layer "In6.Cu")
		(net "M_D_CPU1_SB_DQS_DP<2>")
	)
	(segment
		(start 50.014632 -210.209892)
		(end 49.497234 -210.72729)
		(width 0.18288)
		(layer "In6.Cu")
		(net "M_D_CPU1_SB_DQS_DP<2>")
	)
	(segment
		(start 33.939226 -210.821016)
		(end 33.06826 -210.821016)
		(width 0.18288)
		(layer "In6.Cu")
		(net "M_D_CPU1_SB_DQS_DP<2>")
	)
	(segment
		(start 36.19373 -210.491578)
		(end 35.778694 -210.491578)
		(width 0.18288)
		(layer "In6.Cu")
		(net "M_D_CPU1_SB_DQS_DP<2>")
	)
	(segment
		(start 83.98637 -231.300274)
		(end 83.731862 -231.045766)
		(width 0.088646)
		(layer "In6.Cu")
		(net "M_D_CPU1_SB_DQS_DP<2>")
	)
	(segment
		(start 52.247546 -210.207352)
		(end 51.549046 -210.207352)
		(width 0.18288)
		(layer "In6.Cu")
		(net "M_D_CPU1_SB_DQS_DP<2>")
	)
	(segment
		(start 50.573432 -210.209892)
		(end 50.014632 -210.209892)
		(width 0.18288)
		(layer "In6.Cu")
		(net "M_D_CPU1_SB_DQS_DP<2>")
	)
	(segment
		(start 32.836358 -211.052918)
		(end 32.39135 -211.052918)
		(width 0.18288)
		(layer "In6.Cu")
		(net "M_D_CPU1_SB_DQS_DP<2>")
	)
	(segment
		(start 20.691094 -210.491578)
		(end 20.401534 -210.202018)
		(width 0.18288)
		(layer "In6.Cu")
		(net "M_D_CPU1_SB_DQS_DP<2>")
	)
	(segment
		(start 83.731862 -231.045766)
		(end 83.731862 -230.578152)
		(width 0.088646)
		(layer "In6.Cu")
		(net "M_D_CPU1_SB_DQS_DP<2>")
	)
	(segment
		(start 26.030682 -209.553302)
		(end 24.449532 -210.208876)
		(width 0.18288)
		(layer "In6.Cu")
		(net "M_D_CPU1_SB_DQS_DP<2>")
	)
	(segment
		(start 82.65541 -229.465124)
		(end 82.632042 -229.465124)
		(width 0.088646)
		(layer "In6.Cu")
		(net "M_D_CPU1_SB_DQS_DP<2>")
	)
	(segment
		(start 94.69374 -232.901744)
		(end 94.63659 -232.894886)
		(width 0.088646)
		(layer "In6.Cu")
		(net "M_D_CPU1_SB_DQS_DP<2>")
	)
	(segment
		(start 94.631764 -232.897426)
		(end 94.275402 -232.897426)
		(width 0.088646)
		(layer "In6.Cu")
		(net "M_D_CPU1_SB_DQS_DP<2>")
	)
	(segment
		(start 51.265074 -210.491324)
		(end 50.854864 -210.491324)
		(width 0.18288)
		(layer "In6.Cu")
		(net "M_D_CPU1_SB_DQS_DP<2>")
	)
	(segment
		(start 94.63659 -232.894886)
		(end 94.631764 -232.897426)
		(width 0.088646)
		(layer "In6.Cu")
		(net "M_D_CPU1_SB_DQS_DP<2>")
	)
	(segment
		(start 19.614642 -210.202018)
		(end 19.182842 -209.770726)
		(width 0.18288)
		(layer "In6.Cu")
		(net "M_D_CPU1_SB_DQS_DP<2>")
	)
	(segment
		(start 28.368244 -209.553302)
		(end 26.030682 -209.553302)
		(width 0.18288)
		(layer "In6.Cu")
		(net "M_D_CPU1_SB_DQS_DP<2>")
	)
	(segment
		(start 32.39135 -211.052918)
		(end 32.380428 -211.06384)
		(width 0.18288)
		(layer "In6.Cu")
		(net "M_D_CPU1_SB_DQS_DP<2>")
	)
	(segment
		(start 83.009232 -229.512368)
		(end 82.902044 -229.40518)
		(width 0.088646)
		(layer "In6.Cu")
		(net "M_D_CPU1_SB_DQS_DP<2>")
	)
	(segment
		(start 89.281254 -232.209086)
		(end 89.273888 -232.204768)
		(width 0.088646)
		(layer "In6.Cu")
		(net "M_D_CPU1_SB_DQS_DP<2>")
	)
	(segment
		(start 36.481004 -210.204304)
		(end 36.19373 -210.491578)
		(width 0.18288)
		(layer "In6.Cu")
		(net "M_D_CPU1_SB_DQS_DP<2>")
	)
	(segment
		(start 67.133724 -216.238074)
		(end 66.162174 -216.238074)
		(width 0.18288)
		(layer "In6.Cu")
		(net "M_D_CPU1_SB_DQS_DP<2>")
	)
	(segment
		(start 32.380428 -211.06384)
		(end 32.371538 -211.06384)
		(width 0.18288)
		(layer "In6.Cu")
		(net "M_D_CPU1_SB_DQS_DP<2>")
	)
	(segment
		(start 31.678626 -211.341716)
		(end 31.411926 -211.075016)
		(width 0.18288)
		(layer "In6.Cu")
		(net "M_D_CPU1_SB_DQS_DP<2>")
	)
	(segment
		(start 51.549046 -210.207352)
		(end 51.265074 -210.491324)
		(width 0.18288)
		(layer "In6.Cu")
		(net "M_D_CPU1_SB_DQS_DP<2>")
	)
	(segment
		(start 52.500784 -210.46059)
		(end 52.247546 -210.207352)
		(width 0.18288)
		(layer "In6.Cu")
		(net "M_D_CPU1_SB_DQS_DP<2>")
	)
	(segment
		(start 17.841722 -209.785204)
		(end 17.070578 -209.785204)
		(width 0.18288)
		(layer "In6.Cu")
		(net "M_D_CPU1_SB_DQS_DP<2>")
	)
	(segment
		(start 93.126814 -233.017822)
		(end 93.112082 -233.026458)
		(width 0.088646)
		(layer "In6.Cu")
		(net "M_D_CPU1_SB_DQS_DP<2>")
	)
	(segment
		(start 85.230716 -231.730042)
		(end 85.230716 -231.714548)
		(width 0.088646)
		(layer "In6.Cu")
		(net "M_D_CPU1_SB_DQS_DP<2>")
	)
	(segment
		(start 61.306456 -211.676234)
		(end 59.574938 -211.676234)
		(width 0.18288)
		(layer "In6.Cu")
		(net "M_D_CPU1_SB_DQS_DP<2>")
	)
	(segment
		(start 65.206118 -215.282018)
		(end 64.345566 -213.205568)
		(width 0.18288)
		(layer "In6.Cu")
		(net "M_D_CPU1_SB_DQS_DP<2>")
	)
	(segment
		(start 89.459816 -232.543858)
		(end 89.459816 -232.528364)
		(width 0.088646)
		(layer "In6.Cu")
		(net "M_D_CPU1_SB_DQS_DP<2>")
	)
	(arc
		(start 92.56141 -233.017822)
		(mid 92.374212 -232.967679)
		(end 92.187014 -233.017822)
		(width 0.088646)
		(layer "In6.Cu")
		(net "M_D_CPU1_SB_DQS_DP<2>")
	)
	(arc
		(start 91.237054 -233.023918)
		(mid 90.958622 -233.093764)
		(end 90.68181 -233.017822)
		(width 0.088646)
		(layer "In6.Cu")
		(net "M_D_CPU1_SB_DQS_DP<2>")
	)
	(arc
		(start 90.292682 -233.026458)
		(mid 89.741489 -233.01766)
		(end 89.459816 -232.543858)
		(width 0.088646)
		(layer "In6.Cu")
		(net "M_D_CPU1_SB_DQS_DP<2>")
	)
	(arc
		(start 94.89821 -232.860088)
		(mid 94.799368 -232.897598)
		(end 94.69374 -232.901744)
		(width 0.088646)
		(layer "In6.Cu")
		(net "M_D_CPU1_SB_DQS_DP<2>")
	)
	(arc
		(start 86.452964 -232.204006)
		(mid 86.265766 -232.153863)
		(end 86.078568 -232.204006)
		(width 0.088646)
		(layer "In6.Cu")
		(net "M_D_CPU1_SB_DQS_DP<2>")
	)
	(arc
		(start 89.459816 -232.528364)
		(mid 89.412137 -232.345464)
		(end 89.281254 -232.209086)
		(width 0.088646)
		(layer "In6.Cu")
		(net "M_D_CPU1_SB_DQS_DP<2>")
	)
	(arc
		(start 87.392764 -232.204006)
		(mid 87.205566 -232.153863)
		(end 87.018368 -232.204006)
		(width 0.088646)
		(layer "In6.Cu")
		(net "M_D_CPU1_SB_DQS_DP<2>")
	)
	(arc
		(start 92.187014 -233.017822)
		(mid 91.910455 -233.093565)
		(end 91.632278 -233.023918)
		(width 0.088646)
		(layer "In6.Cu")
		(net "M_D_CPU1_SB_DQS_DP<2>")
	)
	(arc
		(start 89.272364 -232.204006)
		(mid 89.085166 -232.153863)
		(end 88.897968 -232.204006)
		(width 0.088646)
		(layer "In6.Cu")
		(net "M_D_CPU1_SB_DQS_DP<2>")
	)
	(arc
		(start 88.897968 -232.204006)
		(mid 88.623769 -232.279841)
		(end 88.347296 -232.212642)
		(width 0.088646)
		(layer "In6.Cu")
		(net "M_D_CPU1_SB_DQS_DP<2>")
	)
	(arc
		(start 91.621864 -233.017822)
		(mid 91.434666 -232.967679)
		(end 91.247468 -233.017822)
		(width 0.088646)
		(layer "In6.Cu")
		(net "M_D_CPU1_SB_DQS_DP<2>")
	)
	(arc
		(start 84.668868 -231.39019)
		(mid 84.312345 -231.461093)
		(end 83.98637 -231.300274)
		(width 0.088646)
		(layer "In6.Cu")
		(net "M_D_CPU1_SB_DQS_DP<2>")
	)
	(arc
		(start 94.051882 -233.026458)
		(mid 93.775407 -233.093778)
		(end 93.50121 -233.017822)
		(width 0.088646)
		(layer "In6.Cu")
		(net "M_D_CPU1_SB_DQS_DP<2>")
	)
	(arc
		(start 87.018368 -232.204006)
		(mid 86.735666 -232.279782)
		(end 86.452964 -232.204006)
		(width 0.088646)
		(layer "In6.Cu")
		(net "M_D_CPU1_SB_DQS_DP<2>")
	)
	(arc
		(start 90.68181 -233.017822)
		(mid 90.494612 -232.967679)
		(end 90.307414 -233.017822)
		(width 0.088646)
		(layer "In6.Cu")
		(net "M_D_CPU1_SB_DQS_DP<2>")
	)
	(arc
		(start 95.663766 -232.528364)
		(mid 95.487745 -232.551201)
		(end 95.323406 -232.61828)
		(width 0.088646)
		(layer "In6.Cu")
		(net "M_D_CPU1_SB_DQS_DP<2>")
	)
	(arc
		(start 85.230716 -231.714548)
		(mid 85.043417 -231.390107)
		(end 84.668868 -231.39019)
		(width 0.088646)
		(layer "In6.Cu")
		(net "M_D_CPU1_SB_DQS_DP<2>")
	)
	(arc
		(start 87.958168 -232.204006)
		(mid 87.675466 -232.279782)
		(end 87.392764 -232.204006)
		(width 0.088646)
		(layer "In6.Cu")
		(net "M_D_CPU1_SB_DQS_DP<2>")
	)
	(arc
		(start 93.50121 -233.017822)
		(mid 93.314012 -232.967679)
		(end 93.126814 -233.017822)
		(width 0.088646)
		(layer "In6.Cu")
		(net "M_D_CPU1_SB_DQS_DP<2>")
	)
	(arc
		(start 93.112082 -233.026458)
		(mid 92.835607 -233.093778)
		(end 92.56141 -233.017822)
		(width 0.088646)
		(layer "In6.Cu")
		(net "M_D_CPU1_SB_DQS_DP<2>")
	)
	(arc
		(start 88.332564 -232.204006)
		(mid 88.145366 -232.153863)
		(end 87.958168 -232.204006)
		(width 0.088646)
		(layer "In6.Cu")
		(net "M_D_CPU1_SB_DQS_DP<2>")
	)
	(arc
		(start 86.068154 -232.210102)
		(mid 85.514679 -232.205107)
		(end 85.230716 -231.730042)
		(width 0.088646)
		(layer "In6.Cu")
		(net "M_D_CPU1_SB_DQS_DP<2>")
	)
	(segment
		(start 16.789146 -219.41663)
		(end 15.684246 -219.41663)
		(width 0.20066)
		(layer "F.Cu")
		(net "M_D_CPU1_SB_DQS_DP<1>")
	)
	(segment
		(start 14.605762 -219.155518)
		(end 14.180566 -219.580714)
		(width 0.20066)
		(layer "F.Cu")
		(net "M_D_CPU1_SB_DQS_DP<1>")
	)
	(segment
		(start 9.364472 -219.155518)
		(end 8.93953 -219.155518)
		(width 0.20066)
		(layer "F.Cu")
		(net "M_D_CPU1_SB_DQS_DP<1>")
	)
	(segment
		(start 11.11631 -219.851224)
		(end 10.898124 -219.851224)
		(width 0.20066)
		(layer "F.Cu")
		(net "M_D_CPU1_SB_DQS_DP<1>")
	)
	(segment
		(start 11.125708 -219.841826)
		(end 11.11631 -219.851224)
		(width 0.101854)
		(layer "F.Cu")
		(net "M_D_CPU1_SB_DQS_DP<1>")
	)
	(segment
		(start 8.93953 -219.155518)
		(end 8.678418 -219.41663)
		(width 0.20066)
		(layer "F.Cu")
		(net "M_D_CPU1_SB_DQS_DP<1>")
	)
	(segment
		(start 13.441426 -219.841826)
		(end 13.118084 -219.841826)
		(width 0.101854)
		(layer "F.Cu")
		(net "M_D_CPU1_SB_DQS_DP<1>")
	)
	(segment
		(start 10.627614 -219.580714)
		(end 10.000488 -219.580714)
		(width 0.20066)
		(layer "F.Cu")
		(net "M_D_CPU1_SB_DQS_DP<1>")
	)
	(segment
		(start 14.180566 -219.580714)
		(end 13.854684 -219.580714)
		(width 0.20066)
		(layer "F.Cu")
		(net "M_D_CPU1_SB_DQS_DP<1>")
	)
	(segment
		(start 13.118084 -219.841826)
		(end 11.36269 -219.841826)
		(width 0.1016)
		(layer "F.Cu")
		(net "M_D_CPU1_SB_DQS_DP<1>")
	)
	(segment
		(start 10.898124 -219.851224)
		(end 10.627614 -219.580714)
		(width 0.20066)
		(layer "F.Cu")
		(net "M_D_CPU1_SB_DQS_DP<1>")
	)
	(segment
		(start 11.36269 -219.841826)
		(end 11.125708 -219.841826)
		(width 0.101854)
		(layer "F.Cu")
		(net "M_D_CPU1_SB_DQS_DP<1>")
	)
	(segment
		(start 13.593572 -219.841826)
		(end 13.441426 -219.841826)
		(width 0.20066)
		(layer "F.Cu")
		(net "M_D_CPU1_SB_DQS_DP<1>")
	)
	(segment
		(start 8.678418 -219.41663)
		(end 8.140446 -219.41663)
		(width 0.20066)
		(layer "F.Cu")
		(net "M_D_CPU1_SB_DQS_DP<1>")
	)
	(segment
		(start 98.952812 -235.505752)
		(end 98.952812 -234.970066)
		(width 0.20066)
		(layer "F.Cu")
		(net "M_D_CPU1_SB_DQS_DP<1>")
	)
	(segment
		(start 14.874494 -219.155518)
		(end 14.605762 -219.155518)
		(width 0.20066)
		(layer "F.Cu")
		(net "M_D_CPU1_SB_DQS_DP<1>")
	)
	(segment
		(start 13.854684 -219.580714)
		(end 13.593572 -219.841826)
		(width 0.20066)
		(layer "F.Cu")
		(net "M_D_CPU1_SB_DQS_DP<1>")
	)
	(segment
		(start 98.953066 -235.506006)
		(end 98.952812 -235.505752)
		(width 0.20066)
		(layer "F.Cu")
		(net "M_D_CPU1_SB_DQS_DP<1>")
	)
	(segment
		(start 15.135606 -219.41663)
		(end 14.874494 -219.155518)
		(width 0.20066)
		(layer "F.Cu")
		(net "M_D_CPU1_SB_DQS_DP<1>")
	)
	(segment
		(start 15.684246 -219.41663)
		(end 15.135606 -219.41663)
		(width 0.20066)
		(layer "F.Cu")
		(net "M_D_CPU1_SB_DQS_DP<1>")
	)
	(segment
		(start 10.000488 -219.580714)
		(end 9.364472 -219.155518)
		(width 0.20066)
		(layer "F.Cu")
		(net "M_D_CPU1_SB_DQS_DP<1>")
	)
	(segment
		(start 82.779108 -231.322372)
		(end 82.433414 -231.322372)
		(width 0.088646)
		(layer "In11.Cu")
		(net "M_D_CPU1_SB_DQS_DP<1>")
	)
	(segment
		(start 92.5703 -234.650788)
		(end 92.56141 -234.645708)
		(width 0.088646)
		(layer "In11.Cu")
		(net "M_D_CPU1_SB_DQS_DP<1>")
	)
	(segment
		(start 92.100654 -233.836972)
		(end 92.091764 -233.831892)
		(width 0.088646)
		(layer "In11.Cu")
		(net "M_D_CPU1_SB_DQS_DP<1>")
	)
	(segment
		(start 92.279216 -234.171744)
		(end 92.279216 -234.15625)
		(width 0.088646)
		(layer "In11.Cu")
		(net "M_D_CPU1_SB_DQS_DP<1>")
	)
	(segment
		(start 29.973778 -212.160612)
		(end 29.339794 -212.160612)
		(width 0.18288)
		(layer "In11.Cu")
		(net "M_D_CPU1_SB_DQS_DP<1>")
	)
	(segment
		(start 36.197032 -212.194648)
		(end 35.736276 -212.194648)
		(width 0.18288)
		(layer "In11.Cu")
		(net "M_D_CPU1_SB_DQS_DP<1>")
	)
	(segment
		(start 82.945478 -231.969564)
		(end 82.945478 -231.488742)
		(width 0.088646)
		(layer "In11.Cu")
		(net "M_D_CPU1_SB_DQS_DP<1>")
	)
	(segment
		(start 27.145996 -216.734898)
		(end 26.921968 -217.275918)
		(width 0.18288)
		(layer "In11.Cu")
		(net "M_D_CPU1_SB_DQS_DP<1>")
	)
	(segment
		(start 32.090614 -213.040722)
		(end 31.601918 -213.040722)
		(width 0.18288)
		(layer "In11.Cu")
		(net "M_D_CPU1_SB_DQS_DP<1>")
	)
	(segment
		(start 48.663606 -212.76437)
		(end 47.483522 -212.76437)
		(width 0.18288)
		(layer "In11.Cu")
		(net "M_D_CPU1_SB_DQS_DP<1>")
	)
	(segment
		(start 22.95779 -219.569284)
		(end 21.422614 -219.569284)
		(width 0.18288)
		(layer "In11.Cu")
		(net "M_D_CPU1_SB_DQS_DP<1>")
	)
	(segment
		(start 51.578256 -211.901024)
		(end 51.288442 -212.190838)
		(width 0.18288)
		(layer "In11.Cu")
		(net "M_D_CPU1_SB_DQS_DP<1>")
	)
	(segment
		(start 59.77509 -213.47049)
		(end 58.440828 -212.917786)
		(width 0.18288)
		(layer "In11.Cu")
		(net "M_D_CPU1_SB_DQS_DP<1>")
	)
	(segment
		(start 68.318126 -219.552266)
		(end 67.259708 -216.997026)
		(width 0.18288)
		(layer "In11.Cu")
		(net "M_D_CPU1_SB_DQS_DP<1>")
	)
	(segment
		(start 26.921968 -217.275918)
		(end 26.183336 -218.01455)
		(width 0.18288)
		(layer "In11.Cu")
		(net "M_D_CPU1_SB_DQS_DP<1>")
	)
	(segment
		(start 89.287096 -233.840528)
		(end 89.272364 -233.831892)
		(width 0.088646)
		(layer "In11.Cu")
		(net "M_D_CPU1_SB_DQS_DP<1>")
	)
	(segment
		(start 88.427814 -233.017822)
		(end 88.4174 -233.023918)
		(width 0.088646)
		(layer "In11.Cu")
		(net "M_D_CPU1_SB_DQS_DP<1>")
	)
	(segment
		(start 51.288442 -212.190838)
		(end 50.799746 -212.190838)
		(width 0.18288)
		(layer "In11.Cu")
		(net "M_D_CPU1_SB_DQS_DP<1>")
	)
	(segment
		(start 90.226896 -233.840528)
		(end 90.212164 -233.831892)
		(width 0.088646)
		(layer "In11.Cu")
		(net "M_D_CPU1_SB_DQS_DP<1>")
	)
	(segment
		(start 27.85618 -213.042754)
		(end 27.145996 -213.752684)
		(width 0.18288)
		(layer "In11.Cu")
		(net "M_D_CPU1_SB_DQS_DP<1>")
	)
	(segment
		(start 23.330916 -219.196158)
		(end 22.95779 -219.569284)
		(width 0.18288)
		(layer "In11.Cu")
		(net "M_D_CPU1_SB_DQS_DP<1>")
	)
	(segment
		(start 93.046804 -235.46816)
		(end 93.025468 -235.455968)
		(width 0.088646)
		(layer "In11.Cu")
		(net "M_D_CPU1_SB_DQS_DP<1>")
	)
	(segment
		(start 97.56521 -235.339128)
		(end 97.34169 -235.467906)
		(width 0.088646)
		(layer "In11.Cu")
		(net "M_D_CPU1_SB_DQS_DP<1>")
	)
	(segment
		(start 31.347156 -212.78596)
		(end 30.599126 -212.78596)
		(width 0.18288)
		(layer "In11.Cu")
		(net "M_D_CPU1_SB_DQS_DP<1>")
	)
	(segment
		(start 58.440828 -212.917786)
		(end 56.591962 -212.917786)
		(width 0.18288)
		(layer "In11.Cu")
		(net "M_D_CPU1_SB_DQS_DP<1>")
	)
	(segment
		(start 21.422614 -219.569284)
		(end 21.151088 -219.84081)
		(width 0.18288)
		(layer "In11.Cu")
		(net "M_D_CPU1_SB_DQS_DP<1>")
	)
	(segment
		(start 17.087596 -219.11818)
		(end 16.789146 -219.41663)
		(width 0.18288)
		(layer "In11.Cu")
		(net "M_D_CPU1_SB_DQS_DP<1>")
	)
	(segment
		(start 20.6629 -219.84081)
		(end 20.36953 -219.54744)
		(width 0.18288)
		(layer "In11.Cu")
		(net "M_D_CPU1_SB_DQS_DP<1>")
	)
	(segment
		(start 26.183336 -218.01455)
		(end 23.330916 -219.196158)
		(width 0.18288)
		(layer "In11.Cu")
		(net "M_D_CPU1_SB_DQS_DP<1>")
	)
	(segment
		(start 88.989662 -233.356404)
		(end 88.989662 -233.34218)
		(width 0.088646)
		(layer "In11.Cu")
		(net "M_D_CPU1_SB_DQS_DP<1>")
	)
	(segment
		(start 82.433414 -231.322372)
		(end 82.37347 -231.382316)
		(width 0.088646)
		(layer "In11.Cu")
		(net "M_D_CPU1_SB_DQS_DP<1>")
	)
	(segment
		(start 88.8111 -233.022902)
		(end 88.80221 -233.017822)
		(width 0.088646)
		(layer "In11.Cu")
		(net "M_D_CPU1_SB_DQS_DP<1>")
	)
	(segment
		(start 32.36722 -212.764116)
		(end 32.090614 -213.040722)
		(width 0.18288)
		(layer "In11.Cu")
		(net "M_D_CPU1_SB_DQS_DP<1>")
	)
	(segment
		(start 94.925896 -235.46816)
		(end 94.911164 -235.459524)
		(width 0.088646)
		(layer "In11.Cu")
		(net "M_D_CPU1_SB_DQS_DP<1>")
	)
	(segment
		(start 28.883864 -212.61705)
		(end 27.85618 -213.042754)
		(width 0.18288)
		(layer "In11.Cu")
		(net "M_D_CPU1_SB_DQS_DP<1>")
	)
	(segment
		(start 44.48556 -213.396322)
		(end 42.890948 -212.735922)
		(width 0.18288)
		(layer "In11.Cu")
		(net "M_D_CPU1_SB_DQS_DP<1>")
	)
	(segment
		(start 31.601918 -213.040722)
		(end 31.347156 -212.78596)
		(width 0.18288)
		(layer "In11.Cu")
		(net "M_D_CPU1_SB_DQS_DP<1>")
	)
	(segment
		(start 17.923764 -218.927172)
		(end 17.4625 -219.11818)
		(width 0.18288)
		(layer "In11.Cu")
		(net "M_D_CPU1_SB_DQS_DP<1>")
	)
	(segment
		(start 39.392098 -211.896706)
		(end 36.494974 -211.896706)
		(width 0.18288)
		(layer "In11.Cu")
		(net "M_D_CPU1_SB_DQS_DP<1>")
	)
	(segment
		(start 66.670936 -216.408508)
		(end 66.158872 -216.195148)
		(width 0.18288)
		(layer "In11.Cu")
		(net "M_D_CPU1_SB_DQS_DP<1>")
	)
	(segment
		(start 98.612452 -235.059982)
		(end 98.187256 -235.30179)
		(width 0.088646)
		(layer "In11.Cu")
		(net "M_D_CPU1_SB_DQS_DP<1>")
	)
	(segment
		(start 82.37347 -231.382316)
		(end 80.14843 -231.382316)
		(width 0.18288)
		(layer "In11.Cu")
		(net "M_D_CPU1_SB_DQS_DP<1>")
	)
	(segment
		(start 18.720054 -218.927172)
		(end 17.923764 -218.927172)
		(width 0.18288)
		(layer "In11.Cu")
		(net "M_D_CPU1_SB_DQS_DP<1>")
	)
	(segment
		(start 95.865696 -235.46816)
		(end 95.850964 -235.459524)
		(width 0.088646)
		(layer "In11.Cu")
		(net "M_D_CPU1_SB_DQS_DP<1>")
	)
	(segment
		(start 84.069682 -233.093768)
		(end 82.945478 -231.969564)
		(width 0.088646)
		(layer "In11.Cu")
		(net "M_D_CPU1_SB_DQS_DP<1>")
	)
	(segment
		(start 20.36953 -219.54744)
		(end 19.587972 -219.54744)
		(width 0.18288)
		(layer "In11.Cu")
		(net "M_D_CPU1_SB_DQS_DP<1>")
	)
	(segment
		(start 67.259708 -216.997026)
		(end 66.670936 -216.408508)
		(width 0.18288)
		(layer "In11.Cu")
		(net "M_D_CPU1_SB_DQS_DP<1>")
	)
	(segment
		(start 93.046296 -235.46816)
		(end 93.046804 -235.46816)
		(width 0.088646)
		(layer "In11.Cu")
		(net "M_D_CPU1_SB_DQS_DP<1>")
	)
	(segment
		(start 97.92081 -235.339128)
		(end 97.56521 -235.339128)
		(width 0.088646)
		(layer "In11.Cu")
		(net "M_D_CPU1_SB_DQS_DP<1>")
	)
	(segment
		(start 50.025046 -211.981288)
		(end 49.651412 -212.354922)
		(width 0.18288)
		(layer "In11.Cu")
		(net "M_D_CPU1_SB_DQS_DP<1>")
	)
	(segment
		(start 45.143674 -213.396322)
		(end 44.48556 -213.396322)
		(width 0.18288)
		(layer "In11.Cu")
		(net "M_D_CPU1_SB_DQS_DP<1>")
	)
	(segment
		(start 61.568076 -215.263476)
		(end 59.77509 -213.47049)
		(width 0.18288)
		(layer "In11.Cu")
		(net "M_D_CPU1_SB_DQS_DP<1>")
	)
	(segment
		(start 46.719744 -213.043008)
		(end 46.458378 -212.781642)
		(width 0.18288)
		(layer "In11.Cu")
		(net "M_D_CPU1_SB_DQS_DP<1>")
	)
	(segment
		(start 35.736276 -212.194648)
		(end 35.512756 -211.971128)
		(width 0.18288)
		(layer "In11.Cu")
		(net "M_D_CPU1_SB_DQS_DP<1>")
	)
	(segment
		(start 27.145996 -213.752684)
		(end 27.145996 -216.734898)
		(width 0.18288)
		(layer "In11.Cu")
		(net "M_D_CPU1_SB_DQS_DP<1>")
	)
	(segment
		(start 35.512756 -211.971128)
		(end 34.973514 -211.971128)
		(width 0.18288)
		(layer "In11.Cu")
		(net "M_D_CPU1_SB_DQS_DP<1>")
	)
	(segment
		(start 46.011592 -212.781642)
		(end 45.575982 -213.217252)
		(width 0.18288)
		(layer "In11.Cu")
		(net "M_D_CPU1_SB_DQS_DP<1>")
	)
	(segment
		(start 96.79051 -235.459524)
		(end 96.790764 -235.459524)
		(width 0.088646)
		(layer "In11.Cu")
		(net "M_D_CPU1_SB_DQS_DP<1>")
	)
	(segment
		(start 30.599126 -212.78596)
		(end 29.973778 -212.160612)
		(width 0.18288)
		(layer "In11.Cu")
		(net "M_D_CPU1_SB_DQS_DP<1>")
	)
	(segment
		(start 29.339794 -212.160612)
		(end 28.883864 -212.61705)
		(width 0.18288)
		(layer "In11.Cu")
		(net "M_D_CPU1_SB_DQS_DP<1>")
	)
	(segment
		(start 49.651412 -212.354922)
		(end 48.663606 -212.76437)
		(width 0.18288)
		(layer "In11.Cu")
		(net "M_D_CPU1_SB_DQS_DP<1>")
	)
	(segment
		(start 19.14271 -219.102178)
		(end 18.720054 -218.927172)
		(width 0.18288)
		(layer "In11.Cu")
		(net "M_D_CPU1_SB_DQS_DP<1>")
	)
	(segment
		(start 41.418256 -212.735922)
		(end 39.392098 -211.896706)
		(width 0.18288)
		(layer "In11.Cu")
		(net "M_D_CPU1_SB_DQS_DP<1>")
	)
	(segment
		(start 50.590196 -211.981288)
		(end 50.025046 -211.981288)
		(width 0.18288)
		(layer "In11.Cu")
		(net "M_D_CPU1_SB_DQS_DP<1>")
	)
	(segment
		(start 34.973514 -211.971128)
		(end 34.180526 -212.764116)
		(width 0.18288)
		(layer "In11.Cu")
		(net "M_D_CPU1_SB_DQS_DP<1>")
	)
	(segment
		(start 21.151088 -219.84081)
		(end 20.6629 -219.84081)
		(width 0.18288)
		(layer "In11.Cu")
		(net "M_D_CPU1_SB_DQS_DP<1>")
	)
	(segment
		(start 36.494974 -211.896706)
		(end 36.197032 -212.194648)
		(width 0.18288)
		(layer "In11.Cu")
		(net "M_D_CPU1_SB_DQS_DP<1>")
	)
	(segment
		(start 45.575982 -213.217252)
		(end 45.143674 -213.396322)
		(width 0.18288)
		(layer "In11.Cu")
		(net "M_D_CPU1_SB_DQS_DP<1>")
	)
	(segment
		(start 47.204884 -213.043008)
		(end 46.719744 -213.043008)
		(width 0.18288)
		(layer "In11.Cu")
		(net "M_D_CPU1_SB_DQS_DP<1>")
	)
	(segment
		(start 85.057996 -233.026458)
		(end 85.043264 -233.017822)
		(width 0.088646)
		(layer "In11.Cu")
		(net "M_D_CPU1_SB_DQS_DP<1>")
	)
	(segment
		(start 46.458378 -212.781642)
		(end 46.011592 -212.781642)
		(width 0.18288)
		(layer "In11.Cu")
		(net "M_D_CPU1_SB_DQS_DP<1>")
	)
	(segment
		(start 56.591962 -212.917786)
		(end 54.136544 -211.901024)
		(width 0.18288)
		(layer "In11.Cu")
		(net "M_D_CPU1_SB_DQS_DP<1>")
	)
	(segment
		(start 66.158872 -216.195148)
		(end 63.818516 -216.195148)
		(width 0.18288)
		(layer "In11.Cu")
		(net "M_D_CPU1_SB_DQS_DP<1>")
	)
	(segment
		(start 50.799746 -212.190838)
		(end 50.590196 -211.981288)
		(width 0.18288)
		(layer "In11.Cu")
		(net "M_D_CPU1_SB_DQS_DP<1>")
	)
	(segment
		(start 97.982786 -235.343446)
		(end 97.925636 -235.336588)
		(width 0.088646)
		(layer "In11.Cu")
		(net "M_D_CPU1_SB_DQS_DP<1>")
	)
	(segment
		(start 80.14843 -231.382316)
		(end 68.318126 -219.552266)
		(width 0.18288)
		(layer "In11.Cu")
		(net "M_D_CPU1_SB_DQS_DP<1>")
	)
	(segment
		(start 93.986096 -235.46816)
		(end 93.971364 -235.459524)
		(width 0.088646)
		(layer "In11.Cu")
		(net "M_D_CPU1_SB_DQS_DP<1>")
	)
	(segment
		(start 19.587972 -219.54744)
		(end 19.14271 -219.102178)
		(width 0.18288)
		(layer "In11.Cu")
		(net "M_D_CPU1_SB_DQS_DP<1>")
	)
	(segment
		(start 17.4625 -219.11818)
		(end 17.087596 -219.11818)
		(width 0.18288)
		(layer "In11.Cu")
		(net "M_D_CPU1_SB_DQS_DP<1>")
	)
	(segment
		(start 63.818516 -216.195148)
		(end 61.568076 -215.263476)
		(width 0.18288)
		(layer "In11.Cu")
		(net "M_D_CPU1_SB_DQS_DP<1>")
	)
	(segment
		(start 97.925636 -235.336588)
		(end 97.92081 -235.339128)
		(width 0.088646)
		(layer "In11.Cu")
		(net "M_D_CPU1_SB_DQS_DP<1>")
	)
	(segment
		(start 54.136544 -211.901024)
		(end 51.578256 -211.901024)
		(width 0.18288)
		(layer "In11.Cu")
		(net "M_D_CPU1_SB_DQS_DP<1>")
	)
	(segment
		(start 47.483522 -212.76437)
		(end 47.204884 -213.043008)
		(width 0.18288)
		(layer "In11.Cu")
		(net "M_D_CPU1_SB_DQS_DP<1>")
	)
	(segment
		(start 84.38642 -233.093768)
		(end 84.069682 -233.093768)
		(width 0.088646)
		(layer "In11.Cu")
		(net "M_D_CPU1_SB_DQS_DP<1>")
	)
	(segment
		(start 82.945478 -231.488742)
		(end 82.779108 -231.322372)
		(width 0.088646)
		(layer "In11.Cu")
		(net "M_D_CPU1_SB_DQS_DP<1>")
	)
	(segment
		(start 42.890948 -212.735922)
		(end 41.418256 -212.735922)
		(width 0.18288)
		(layer "In11.Cu")
		(net "M_D_CPU1_SB_DQS_DP<1>")
	)
	(segment
		(start 34.180526 -212.764116)
		(end 32.36722 -212.764116)
		(width 0.18288)
		(layer "In11.Cu")
		(net "M_D_CPU1_SB_DQS_DP<1>")
	)
	(arc
		(start 92.748862 -234.970066)
		(mid 92.701183 -234.787166)
		(end 92.5703 -234.650788)
		(width 0.088646)
		(layer "In11.Cu")
		(net "M_D_CPU1_SB_DQS_DP<1>")
	)
	(arc
		(start 95.476568 -235.459524)
		(mid 95.202369 -235.535359)
		(end 94.925896 -235.46816)
		(width 0.088646)
		(layer "In11.Cu")
		(net "M_D_CPU1_SB_DQS_DP<1>")
	)
	(arc
		(start 90.777568 -233.831892)
		(mid 90.503339 -233.907817)
		(end 90.226896 -233.840528)
		(width 0.088646)
		(layer "In11.Cu")
		(net "M_D_CPU1_SB_DQS_DP<1>")
	)
	(arc
		(start 88.80221 -233.017822)
		(mid 88.615012 -232.967679)
		(end 88.427814 -233.017822)
		(width 0.088646)
		(layer "In11.Cu")
		(net "M_D_CPU1_SB_DQS_DP<1>")
	)
	(arc
		(start 87.488268 -233.017822)
		(mid 87.205566 -233.093598)
		(end 86.922864 -233.017822)
		(width 0.088646)
		(layer "In11.Cu")
		(net "M_D_CPU1_SB_DQS_DP<1>")
	)
	(arc
		(start 93.596968 -235.459524)
		(mid 93.322769 -235.535359)
		(end 93.046296 -235.46816)
		(width 0.088646)
		(layer "In11.Cu")
		(net "M_D_CPU1_SB_DQS_DP<1>")
	)
	(arc
		(start 86.548468 -233.017822)
		(mid 86.265766 -233.093598)
		(end 85.983064 -233.017822)
		(width 0.088646)
		(layer "In11.Cu")
		(net "M_D_CPU1_SB_DQS_DP<1>")
	)
	(arc
		(start 85.608668 -233.017822)
		(mid 85.334469 -233.093657)
		(end 85.057996 -233.026458)
		(width 0.088646)
		(layer "In11.Cu")
		(net "M_D_CPU1_SB_DQS_DP<1>")
	)
	(arc
		(start 85.043264 -233.017822)
		(mid 84.856066 -232.967679)
		(end 84.668868 -233.017822)
		(width 0.088646)
		(layer "In11.Cu")
		(net "M_D_CPU1_SB_DQS_DP<1>")
	)
	(arc
		(start 93.025468 -235.455968)
		(mid 92.822881 -235.249617)
		(end 92.748862 -234.970066)
		(width 0.088646)
		(layer "In11.Cu")
		(net "M_D_CPU1_SB_DQS_DP<1>")
	)
	(arc
		(start 90.212164 -233.831892)
		(mid 90.024966 -233.781749)
		(end 89.837768 -233.831892)
		(width 0.088646)
		(layer "In11.Cu")
		(net "M_D_CPU1_SB_DQS_DP<1>")
	)
	(arc
		(start 92.56141 -234.645708)
		(mid 92.358587 -234.445477)
		(end 92.279216 -234.171744)
		(width 0.088646)
		(layer "In11.Cu")
		(net "M_D_CPU1_SB_DQS_DP<1>")
	)
	(arc
		(start 95.850964 -235.459524)
		(mid 95.663766 -235.409381)
		(end 95.476568 -235.459524)
		(width 0.088646)
		(layer "In11.Cu")
		(net "M_D_CPU1_SB_DQS_DP<1>")
	)
	(arc
		(start 93.971364 -235.459524)
		(mid 93.784166 -235.409381)
		(end 93.596968 -235.459524)
		(width 0.088646)
		(layer "In11.Cu")
		(net "M_D_CPU1_SB_DQS_DP<1>")
	)
	(arc
		(start 98.952812 -234.970066)
		(mid 98.776791 -234.992903)
		(end 98.612452 -235.059982)
		(width 0.088646)
		(layer "In11.Cu")
		(net "M_D_CPU1_SB_DQS_DP<1>")
	)
	(arc
		(start 85.983064 -233.017822)
		(mid 85.795866 -232.967679)
		(end 85.608668 -233.017822)
		(width 0.088646)
		(layer "In11.Cu")
		(net "M_D_CPU1_SB_DQS_DP<1>")
	)
	(arc
		(start 96.416368 -235.459524)
		(mid 96.142169 -235.535359)
		(end 95.865696 -235.46816)
		(width 0.088646)
		(layer "In11.Cu")
		(net "M_D_CPU1_SB_DQS_DP<1>")
	)
	(arc
		(start 87.862664 -233.017822)
		(mid 87.675466 -232.967679)
		(end 87.488268 -233.017822)
		(width 0.088646)
		(layer "In11.Cu")
		(net "M_D_CPU1_SB_DQS_DP<1>")
	)
	(arc
		(start 86.922864 -233.017822)
		(mid 86.735666 -232.967679)
		(end 86.548468 -233.017822)
		(width 0.088646)
		(layer "In11.Cu")
		(net "M_D_CPU1_SB_DQS_DP<1>")
	)
	(arc
		(start 97.34169 -235.467906)
		(mid 97.065025 -235.535377)
		(end 96.79051 -235.459524)
		(width 0.088646)
		(layer "In11.Cu")
		(net "M_D_CPU1_SB_DQS_DP<1>")
	)
	(arc
		(start 92.091764 -233.831892)
		(mid 91.904566 -233.781749)
		(end 91.717368 -233.831892)
		(width 0.088646)
		(layer "In11.Cu")
		(net "M_D_CPU1_SB_DQS_DP<1>")
	)
	(arc
		(start 89.272364 -233.831892)
		(mid 89.068883 -233.631088)
		(end 88.989662 -233.356404)
		(width 0.088646)
		(layer "In11.Cu")
		(net "M_D_CPU1_SB_DQS_DP<1>")
	)
	(arc
		(start 84.668868 -233.017822)
		(mid 84.532642 -233.074379)
		(end 84.38642 -233.093768)
		(width 0.088646)
		(layer "In11.Cu")
		(net "M_D_CPU1_SB_DQS_DP<1>")
	)
	(arc
		(start 91.717368 -233.831892)
		(mid 91.434666 -233.907634)
		(end 91.151964 -233.831892)
		(width 0.088646)
		(layer "In11.Cu")
		(net "M_D_CPU1_SB_DQS_DP<1>")
	)
	(arc
		(start 89.837768 -233.831892)
		(mid 89.563539 -233.907817)
		(end 89.287096 -233.840528)
		(width 0.088646)
		(layer "In11.Cu")
		(net "M_D_CPU1_SB_DQS_DP<1>")
	)
	(arc
		(start 96.790764 -235.459524)
		(mid 96.603566 -235.409381)
		(end 96.416368 -235.459524)
		(width 0.088646)
		(layer "In11.Cu")
		(net "M_D_CPU1_SB_DQS_DP<1>")
	)
	(arc
		(start 92.279216 -234.15625)
		(mid 92.231537 -233.97335)
		(end 92.100654 -233.836972)
		(width 0.088646)
		(layer "In11.Cu")
		(net "M_D_CPU1_SB_DQS_DP<1>")
	)
	(arc
		(start 88.4174 -233.023918)
		(mid 88.139222 -233.093641)
		(end 87.862664 -233.017822)
		(width 0.088646)
		(layer "In11.Cu")
		(net "M_D_CPU1_SB_DQS_DP<1>")
	)
	(arc
		(start 88.989662 -233.34218)
		(mid 88.941983 -233.15928)
		(end 88.8111 -233.022902)
		(width 0.088646)
		(layer "In11.Cu")
		(net "M_D_CPU1_SB_DQS_DP<1>")
	)
	(arc
		(start 98.187256 -235.30179)
		(mid 98.088414 -235.3393)
		(end 97.982786 -235.343446)
		(width 0.088646)
		(layer "In11.Cu")
		(net "M_D_CPU1_SB_DQS_DP<1>")
	)
	(arc
		(start 91.151964 -233.831892)
		(mid 90.964766 -233.781749)
		(end 90.777568 -233.831892)
		(width 0.088646)
		(layer "In11.Cu")
		(net "M_D_CPU1_SB_DQS_DP<1>")
	)
	(arc
		(start 94.536768 -235.459524)
		(mid 94.262569 -235.535359)
		(end 93.986096 -235.46816)
		(width 0.088646)
		(layer "In11.Cu")
		(net "M_D_CPU1_SB_DQS_DP<1>")
	)
	(arc
		(start 94.911164 -235.459524)
		(mid 94.723966 -235.409381)
		(end 94.536768 -235.459524)
		(width 0.088646)
		(layer "In11.Cu")
		(net "M_D_CPU1_SB_DQS_DP<1>")
	)
	(segment
		(start 16.789146 -228.766624)
		(end 15.684246 -228.766624)
		(width 0.20066)
		(layer "F.Cu")
		(net "M_D_CPU1_SB_DQS_DP<0>")
	)
	(segment
		(start 14.605762 -228.505512)
		(end 14.180566 -228.930708)
		(width 0.20066)
		(layer "F.Cu")
		(net "M_D_CPU1_SB_DQS_DP<0>")
	)
	(segment
		(start 13.854684 -228.930708)
		(end 13.593572 -229.19182)
		(width 0.20066)
		(layer "F.Cu")
		(net "M_D_CPU1_SB_DQS_DP<0>")
	)
	(segment
		(start 98.953066 -240.389156)
		(end 98.952812 -240.388902)
		(width 0.20066)
		(layer "F.Cu")
		(net "M_D_CPU1_SB_DQS_DP<0>")
	)
	(segment
		(start 10.898124 -229.201218)
		(end 10.627614 -228.930708)
		(width 0.20066)
		(layer "F.Cu")
		(net "M_D_CPU1_SB_DQS_DP<0>")
	)
	(segment
		(start 9.364472 -228.505512)
		(end 8.93953 -228.505512)
		(width 0.20066)
		(layer "F.Cu")
		(net "M_D_CPU1_SB_DQS_DP<0>")
	)
	(segment
		(start 14.180566 -228.930708)
		(end 13.854684 -228.930708)
		(width 0.20066)
		(layer "F.Cu")
		(net "M_D_CPU1_SB_DQS_DP<0>")
	)
	(segment
		(start 13.118084 -229.19182)
		(end 11.36269 -229.19182)
		(width 0.1016)
		(layer "F.Cu")
		(net "M_D_CPU1_SB_DQS_DP<0>")
	)
	(segment
		(start 8.678418 -228.766624)
		(end 8.140446 -228.766624)
		(width 0.20066)
		(layer "F.Cu")
		(net "M_D_CPU1_SB_DQS_DP<0>")
	)
	(segment
		(start 10.627614 -228.930708)
		(end 10.000488 -228.930708)
		(width 0.20066)
		(layer "F.Cu")
		(net "M_D_CPU1_SB_DQS_DP<0>")
	)
	(segment
		(start 8.93953 -228.505512)
		(end 8.678418 -228.766624)
		(width 0.20066)
		(layer "F.Cu")
		(net "M_D_CPU1_SB_DQS_DP<0>")
	)
	(segment
		(start 11.125708 -229.19182)
		(end 11.11631 -229.201218)
		(width 0.101854)
		(layer "F.Cu")
		(net "M_D_CPU1_SB_DQS_DP<0>")
	)
	(segment
		(start 15.135606 -228.766624)
		(end 14.874494 -228.505512)
		(width 0.20066)
		(layer "F.Cu")
		(net "M_D_CPU1_SB_DQS_DP<0>")
	)
	(segment
		(start 13.593572 -229.19182)
		(end 13.441426 -229.19182)
		(width 0.20066)
		(layer "F.Cu")
		(net "M_D_CPU1_SB_DQS_DP<0>")
	)
	(segment
		(start 15.684246 -228.766624)
		(end 15.135606 -228.766624)
		(width 0.20066)
		(layer "F.Cu")
		(net "M_D_CPU1_SB_DQS_DP<0>")
	)
	(segment
		(start 10.000488 -228.930708)
		(end 9.364472 -228.505512)
		(width 0.20066)
		(layer "F.Cu")
		(net "M_D_CPU1_SB_DQS_DP<0>")
	)
	(segment
		(start 14.874494 -228.505512)
		(end 14.605762 -228.505512)
		(width 0.20066)
		(layer "F.Cu")
		(net "M_D_CPU1_SB_DQS_DP<0>")
	)
	(segment
		(start 11.11631 -229.201218)
		(end 10.898124 -229.201218)
		(width 0.20066)
		(layer "F.Cu")
		(net "M_D_CPU1_SB_DQS_DP<0>")
	)
	(segment
		(start 98.952812 -240.388902)
		(end 98.952812 -239.853216)
		(width 0.20066)
		(layer "F.Cu")
		(net "M_D_CPU1_SB_DQS_DP<0>")
	)
	(segment
		(start 11.36269 -229.19182)
		(end 11.125708 -229.19182)
		(width 0.101854)
		(layer "F.Cu")
		(net "M_D_CPU1_SB_DQS_DP<0>")
	)
	(segment
		(start 13.441426 -229.19182)
		(end 13.118084 -229.19182)
		(width 0.101854)
		(layer "F.Cu")
		(net "M_D_CPU1_SB_DQS_DP<0>")
	)
	(segment
		(start 48.632872 -225.505772)
		(end 47.511716 -225.505772)
		(width 0.18288)
		(layer "In11.Cu")
		(net "M_D_CPU1_SB_DQS_DP<0>")
	)
	(segment
		(start 60.269882 -226.515676)
		(end 59.592972 -226.23526)
		(width 0.18288)
		(layer "In11.Cu")
		(net "M_D_CPU1_SB_DQS_DP<0>")
	)
	(segment
		(start 44.471082 -226.1108)
		(end 43.067478 -225.528886)
		(width 0.18288)
		(layer "In11.Cu")
		(net "M_D_CPU1_SB_DQS_DP<0>")
	)
	(segment
		(start 87.8713 -239.533938)
		(end 87.86241 -239.528858)
		(width 0.088646)
		(layer "In11.Cu")
		(net "M_D_CPU1_SB_DQS_DP<0>")
	)
	(segment
		(start 91.162124 -240.349024)
		(end 91.15171 -240.342928)
		(width 0.088646)
		(layer "In11.Cu")
		(net "M_D_CPU1_SB_DQS_DP<0>")
	)
	(segment
		(start 21.437854 -228.886512)
		(end 21.132038 -229.192328)
		(width 0.18288)
		(layer "In11.Cu")
		(net "M_D_CPU1_SB_DQS_DP<0>")
	)
	(segment
		(start 61.832236 -227.491036)
		(end 61.53531 -227.19411)
		(width 0.18288)
		(layer "In11.Cu")
		(net "M_D_CPU1_SB_DQS_DP<0>")
	)
	(segment
		(start 35.172904 -224.700592)
		(end 34.506154 -224.977198)
		(width 0.18288)
		(layer "In11.Cu")
		(net "M_D_CPU1_SB_DQS_DP<0>")
	)
	(segment
		(start 21.132038 -229.192328)
		(end 20.669758 -229.192328)
		(width 0.18288)
		(layer "In11.Cu")
		(net "M_D_CPU1_SB_DQS_DP<0>")
	)
	(segment
		(start 18.763488 -228.256846)
		(end 18.03019 -228.256846)
		(width 0.18288)
		(layer "In11.Cu")
		(net "M_D_CPU1_SB_DQS_DP<0>")
	)
	(segment
		(start 24.472392 -228.886512)
		(end 21.437854 -228.886512)
		(width 0.18288)
		(layer "In11.Cu")
		(net "M_D_CPU1_SB_DQS_DP<0>")
	)
	(segment
		(start 36.200842 -224.940876)
		(end 35.712146 -224.940876)
		(width 0.18288)
		(layer "In11.Cu")
		(net "M_D_CPU1_SB_DQS_DP<0>")
	)
	(segment
		(start 82.433414 -237.363762)
		(end 82.37347 -237.423706)
		(width 0.088646)
		(layer "In11.Cu")
		(net "M_D_CPU1_SB_DQS_DP<0>")
	)
	(segment
		(start 93.046296 -240.351564)
		(end 93.031564 -240.342928)
		(width 0.088646)
		(layer "In11.Cu")
		(net "M_D_CPU1_SB_DQS_DP<0>")
	)
	(segment
		(start 86.461854 -238.720122)
		(end 86.452964 -238.715042)
		(width 0.088646)
		(layer "In11.Cu")
		(net "M_D_CPU1_SB_DQS_DP<0>")
	)
	(segment
		(start 62.595506 -227.202746)
		(end 62.307216 -227.491036)
		(width 0.18288)
		(layer "In11.Cu")
		(net "M_D_CPU1_SB_DQS_DP<0>")
	)
	(segment
		(start 96.79051 -240.342674)
		(end 96.790764 -240.342928)
		(width 0.088646)
		(layer "In11.Cu")
		(net "M_D_CPU1_SB_DQS_DP<0>")
	)
	(segment
		(start 94.925896 -240.351564)
		(end 94.911164 -240.342928)
		(width 0.088646)
		(layer "In11.Cu")
		(net "M_D_CPU1_SB_DQS_DP<0>")
	)
	(segment
		(start 32.138874 -225.791014)
		(end 31.650178 -225.791014)
		(width 0.18288)
		(layer "In11.Cu")
		(net "M_D_CPU1_SB_DQS_DP<0>")
	)
	(segment
		(start 50.115724 -224.690432)
		(end 49.77257 -225.033586)
		(width 0.18288)
		(layer "In11.Cu")
		(net "M_D_CPU1_SB_DQS_DP<0>")
	)
	(segment
		(start 84.573618 -238.715296)
		(end 84.573872 -238.714788)
		(width 0.088646)
		(layer "In11.Cu")
		(net "M_D_CPU1_SB_DQS_DP<0>")
	)
	(segment
		(start 97.982786 -240.226596)
		(end 97.925636 -240.219738)
		(width 0.088646)
		(layer "In11.Cu")
		(net "M_D_CPU1_SB_DQS_DP<0>")
	)
	(segment
		(start 98.612452 -239.943132)
		(end 98.187256 -240.18494)
		(width 0.088646)
		(layer "In11.Cu")
		(net "M_D_CPU1_SB_DQS_DP<0>")
	)
	(segment
		(start 65.02527 -228.929184)
		(end 63.555372 -227.459286)
		(width 0.18288)
		(layer "In11.Cu")
		(net "M_D_CPU1_SB_DQS_DP<0>")
	)
	(segment
		(start 97.925636 -240.219738)
		(end 97.92081 -240.222278)
		(width 0.088646)
		(layer "In11.Cu")
		(net "M_D_CPU1_SB_DQS_DP<0>")
	)
	(segment
		(start 59.592972 -226.23526)
		(end 59.263534 -225.905822)
		(width 0.18288)
		(layer "In11.Cu")
		(net "M_D_CPU1_SB_DQS_DP<0>")
	)
	(segment
		(start 95.865696 -240.351564)
		(end 95.850964 -240.342928)
		(width 0.088646)
		(layer "In11.Cu")
		(net "M_D_CPU1_SB_DQS_DP<0>")
	)
	(segment
		(start 20.669758 -229.192328)
		(end 20.387564 -228.910134)
		(width 0.18288)
		(layer "In11.Cu")
		(net "M_D_CPU1_SB_DQS_DP<0>")
	)
	(segment
		(start 29.13634 -226.954842)
		(end 24.472392 -228.886512)
		(width 0.18288)
		(layer "In11.Cu")
		(net "M_D_CPU1_SB_DQS_DP<0>")
	)
	(segment
		(start 51.28133 -224.940368)
		(end 50.811938 -224.940368)
		(width 0.18288)
		(layer "In11.Cu")
		(net "M_D_CPU1_SB_DQS_DP<0>")
	)
	(segment
		(start 31.650178 -225.791014)
		(end 31.382716 -225.523552)
		(width 0.18288)
		(layer "In11.Cu")
		(net "M_D_CPU1_SB_DQS_DP<0>")
	)
	(segment
		(start 66.227198 -229.190296)
		(end 66.049398 -229.190296)
		(width 0.16002)
		(layer "In11.Cu")
		(net "M_D_CPU1_SB_DQS_DP<0>")
	)
	(segment
		(start 92.106496 -240.351564)
		(end 92.091764 -240.342928)
		(width 0.088646)
		(layer "In11.Cu")
		(net "M_D_CPU1_SB_DQS_DP<0>")
	)
	(segment
		(start 34.506154 -224.977198)
		(end 33.982406 -225.500946)
		(width 0.18288)
		(layer "In11.Cu")
		(net "M_D_CPU1_SB_DQS_DP<0>")
	)
	(segment
		(start 19.782282 -228.67874)
		(end 18.763488 -228.256846)
		(width 0.18288)
		(layer "In11.Cu")
		(net "M_D_CPU1_SB_DQS_DP<0>")
	)
	(segment
		(start 46.737778 -225.791014)
		(end 46.485556 -225.538792)
		(width 0.18288)
		(layer "In11.Cu")
		(net "M_D_CPU1_SB_DQS_DP<0>")
	)
	(segment
		(start 93.986096 -240.351564)
		(end 93.971364 -240.342928)
		(width 0.088646)
		(layer "In11.Cu")
		(net "M_D_CPU1_SB_DQS_DP<0>")
	)
	(segment
		(start 39.064692 -224.641918)
		(end 36.4998 -224.641918)
		(width 0.18288)
		(layer "In11.Cu")
		(net "M_D_CPU1_SB_DQS_DP<0>")
	)
	(segment
		(start 43.067478 -225.528886)
		(end 41.204134 -225.528886)
		(width 0.18288)
		(layer "In11.Cu")
		(net "M_D_CPU1_SB_DQS_DP<0>")
	)
	(segment
		(start 49.77257 -225.033586)
		(end 48.632872 -225.505772)
		(width 0.18288)
		(layer "In11.Cu")
		(net "M_D_CPU1_SB_DQS_DP<0>")
	)
	(segment
		(start 62.93612 -227.202746)
		(end 62.595506 -227.202746)
		(width 0.18288)
		(layer "In11.Cu")
		(net "M_D_CPU1_SB_DQS_DP<0>")
	)
	(segment
		(start 75.808078 -237.423706)
		(end 67.332098 -228.947726)
		(width 0.18288)
		(layer "In11.Cu")
		(net "M_D_CPU1_SB_DQS_DP<0>")
	)
	(segment
		(start 62.307216 -227.491036)
		(end 62.135258 -227.491036)
		(width 0.18288)
		(layer "In11.Cu")
		(net "M_D_CPU1_SB_DQS_DP<0>")
	)
	(segment
		(start 56.6928 -225.56343)
		(end 54.504082 -224.656904)
		(width 0.18288)
		(layer "In11.Cu")
		(net "M_D_CPU1_SB_DQS_DP<0>")
	)
	(segment
		(start 82.69605 -237.363762)
		(end 82.433414 -237.363762)
		(width 0.088646)
		(layer "In11.Cu")
		(net "M_D_CPU1_SB_DQS_DP<0>")
	)
	(segment
		(start 66.6877 -228.947726)
		(end 66.44513 -229.190296)
		(width 0.18288)
		(layer "In11.Cu")
		(net "M_D_CPU1_SB_DQS_DP<0>")
	)
	(segment
		(start 47.511716 -225.505772)
		(end 47.226474 -225.791014)
		(width 0.18288)
		(layer "In11.Cu")
		(net "M_D_CPU1_SB_DQS_DP<0>")
	)
	(segment
		(start 20.01393 -228.910134)
		(end 19.782282 -228.67874)
		(width 0.18288)
		(layer "In11.Cu")
		(net "M_D_CPU1_SB_DQS_DP<0>")
	)
	(segment
		(start 83.996784 -238.664496)
		(end 82.69605 -237.363762)
		(width 0.088646)
		(layer "In11.Cu")
		(net "M_D_CPU1_SB_DQS_DP<0>")
	)
	(segment
		(start 88.347296 -240.351564)
		(end 88.332564 -240.342928)
		(width 0.088646)
		(layer "In11.Cu")
		(net "M_D_CPU1_SB_DQS_DP<0>")
	)
	(segment
		(start 18.03019 -228.256846)
		(end 17.491202 -228.480112)
		(width 0.18288)
		(layer "In11.Cu")
		(net "M_D_CPU1_SB_DQS_DP<0>")
	)
	(segment
		(start 41.204134 -225.528886)
		(end 39.064692 -224.641918)
		(width 0.18288)
		(layer "In11.Cu")
		(net "M_D_CPU1_SB_DQS_DP<0>")
	)
	(segment
		(start 84.386166 -238.664496)
		(end 83.996784 -238.664496)
		(width 0.088646)
		(layer "In11.Cu")
		(net "M_D_CPU1_SB_DQS_DP<0>")
	)
	(segment
		(start 35.712146 -224.940876)
		(end 35.471862 -224.700592)
		(width 0.18288)
		(layer "In11.Cu")
		(net "M_D_CPU1_SB_DQS_DP<0>")
	)
	(segment
		(start 97.92081 -240.222278)
		(end 97.56521 -240.222278)
		(width 0.088646)
		(layer "In11.Cu")
		(net "M_D_CPU1_SB_DQS_DP<0>")
	)
	(segment
		(start 45.91939 -225.538792)
		(end 45.347382 -226.1108)
		(width 0.18288)
		(layer "In11.Cu")
		(net "M_D_CPU1_SB_DQS_DP<0>")
	)
	(segment
		(start 20.387564 -228.910134)
		(end 20.01393 -228.910134)
		(width 0.18288)
		(layer "In11.Cu")
		(net "M_D_CPU1_SB_DQS_DP<0>")
	)
	(segment
		(start 65.853818 -229.190296)
		(end 65.592706 -228.929184)
		(width 0.18288)
		(layer "In11.Cu")
		(net "M_D_CPU1_SB_DQS_DP<0>")
	)
	(segment
		(start 61.980318 -227.491036)
		(end 61.832236 -227.491036)
		(width 0.18288)
		(layer "In11.Cu")
		(net "M_D_CPU1_SB_DQS_DP<0>")
	)
	(segment
		(start 30.325568 -225.765614)
		(end 29.13634 -226.954842)
		(width 0.18288)
		(layer "In11.Cu")
		(net "M_D_CPU1_SB_DQS_DP<0>")
	)
	(segment
		(start 59.263534 -225.905822)
		(end 58.43778 -225.56343)
		(width 0.18288)
		(layer "In11.Cu")
		(net "M_D_CPU1_SB_DQS_DP<0>")
	)
	(segment
		(start 60.948316 -227.19411)
		(end 60.269882 -226.515676)
		(width 0.18288)
		(layer "In11.Cu")
		(net "M_D_CPU1_SB_DQS_DP<0>")
	)
	(segment
		(start 17.075658 -228.480112)
		(end 16.789146 -228.766624)
		(width 0.18288)
		(layer "In11.Cu")
		(net "M_D_CPU1_SB_DQS_DP<0>")
	)
	(segment
		(start 89.287096 -240.351564)
		(end 89.272364 -240.342928)
		(width 0.088646)
		(layer "In11.Cu")
		(net "M_D_CPU1_SB_DQS_DP<0>")
	)
	(segment
		(start 17.491202 -228.480112)
		(end 17.075658 -228.480112)
		(width 0.18288)
		(layer "In11.Cu")
		(net "M_D_CPU1_SB_DQS_DP<0>")
	)
	(segment
		(start 51.564794 -224.656904)
		(end 51.28133 -224.940368)
		(width 0.18288)
		(layer "In11.Cu")
		(net "M_D_CPU1_SB_DQS_DP<0>")
	)
	(segment
		(start 47.226474 -225.791014)
		(end 46.737778 -225.791014)
		(width 0.18288)
		(layer "In11.Cu")
		(net "M_D_CPU1_SB_DQS_DP<0>")
	)
	(segment
		(start 54.504082 -224.656904)
		(end 51.564794 -224.656904)
		(width 0.18288)
		(layer "In11.Cu")
		(net "M_D_CPU1_SB_DQS_DP<0>")
	)
	(segment
		(start 50.562002 -224.690432)
		(end 50.115724 -224.690432)
		(width 0.18288)
		(layer "In11.Cu")
		(net "M_D_CPU1_SB_DQS_DP<0>")
	)
	(segment
		(start 33.982406 -225.500946)
		(end 32.428942 -225.500946)
		(width 0.18288)
		(layer "In11.Cu")
		(net "M_D_CPU1_SB_DQS_DP<0>")
	)
	(segment
		(start 35.471862 -224.700592)
		(end 35.172904 -224.700592)
		(width 0.18288)
		(layer "In11.Cu")
		(net "M_D_CPU1_SB_DQS_DP<0>")
	)
	(segment
		(start 32.428942 -225.500946)
		(end 32.138874 -225.791014)
		(width 0.18288)
		(layer "In11.Cu")
		(net "M_D_CPU1_SB_DQS_DP<0>")
	)
	(segment
		(start 90.777314 -240.342928)
		(end 90.7669 -240.349024)
		(width 0.088646)
		(layer "In11.Cu")
		(net "M_D_CPU1_SB_DQS_DP<0>")
	)
	(segment
		(start 66.049398 -229.190296)
		(end 65.853818 -229.190296)
		(width 0.18288)
		(layer "In11.Cu")
		(net "M_D_CPU1_SB_DQS_DP<0>")
	)
	(segment
		(start 45.347382 -226.1108)
		(end 44.471082 -226.1108)
		(width 0.18288)
		(layer "In11.Cu")
		(net "M_D_CPU1_SB_DQS_DP<0>")
	)
	(segment
		(start 31.382716 -225.523552)
		(end 30.91053 -225.523552)
		(width 0.18288)
		(layer "In11.Cu")
		(net "M_D_CPU1_SB_DQS_DP<0>")
	)
	(segment
		(start 82.37347 -237.423706)
		(end 75.808078 -237.423706)
		(width 0.18288)
		(layer "In11.Cu")
		(net "M_D_CPU1_SB_DQS_DP<0>")
	)
	(segment
		(start 86.640416 -239.054894)
		(end 86.640416 -239.0394)
		(width 0.088646)
		(layer "In11.Cu")
		(net "M_D_CPU1_SB_DQS_DP<0>")
	)
	(segment
		(start 50.811938 -224.940368)
		(end 50.562002 -224.690432)
		(width 0.18288)
		(layer "In11.Cu")
		(net "M_D_CPU1_SB_DQS_DP<0>")
	)
	(segment
		(start 65.592706 -228.929184)
		(end 65.02527 -228.929184)
		(width 0.18288)
		(layer "In11.Cu")
		(net "M_D_CPU1_SB_DQS_DP<0>")
	)
	(segment
		(start 46.485556 -225.538792)
		(end 45.91939 -225.538792)
		(width 0.18288)
		(layer "In11.Cu")
		(net "M_D_CPU1_SB_DQS_DP<0>")
	)
	(segment
		(start 61.53531 -227.19411)
		(end 60.948316 -227.19411)
		(width 0.18288)
		(layer "In11.Cu")
		(net "M_D_CPU1_SB_DQS_DP<0>")
	)
	(segment
		(start 30.91053 -225.523552)
		(end 30.325568 -225.765614)
		(width 0.18288)
		(layer "In11.Cu")
		(net "M_D_CPU1_SB_DQS_DP<0>")
	)
	(segment
		(start 58.43778 -225.56343)
		(end 56.6928 -225.56343)
		(width 0.18288)
		(layer "In11.Cu")
		(net "M_D_CPU1_SB_DQS_DP<0>")
	)
	(segment
		(start 67.332098 -228.947726)
		(end 66.6877 -228.947726)
		(width 0.18288)
		(layer "In11.Cu")
		(net "M_D_CPU1_SB_DQS_DP<0>")
	)
	(segment
		(start 87.488014 -239.528858)
		(end 87.473282 -239.537494)
		(width 0.088646)
		(layer "In11.Cu")
		(net "M_D_CPU1_SB_DQS_DP<0>")
	)
	(segment
		(start 97.56521 -240.222278)
		(end 97.34169 -240.351056)
		(width 0.088646)
		(layer "In11.Cu")
		(net "M_D_CPU1_SB_DQS_DP<0>")
	)
	(segment
		(start 62.135258 -227.491036)
		(end 61.980318 -227.491036)
		(width 0.16002)
		(layer "In11.Cu")
		(net "M_D_CPU1_SB_DQS_DP<0>")
	)
	(segment
		(start 66.44513 -229.190296)
		(end 66.227198 -229.190296)
		(width 0.18288)
		(layer "In11.Cu")
		(net "M_D_CPU1_SB_DQS_DP<0>")
	)
	(segment
		(start 88.049862 -239.86744)
		(end 88.049862 -239.853216)
		(width 0.088646)
		(layer "In11.Cu")
		(net "M_D_CPU1_SB_DQS_DP<0>")
	)
	(segment
		(start 63.555372 -227.459286)
		(end 62.93612 -227.202746)
		(width 0.18288)
		(layer "In11.Cu")
		(net "M_D_CPU1_SB_DQS_DP<0>")
	)
	(segment
		(start 36.4998 -224.641918)
		(end 36.200842 -224.940876)
		(width 0.18288)
		(layer "In11.Cu")
		(net "M_D_CPU1_SB_DQS_DP<0>")
	)
	(arc
		(start 88.332564 -240.342928)
		(mid 88.129083 -240.142124)
		(end 88.049862 -239.86744)
		(width 0.088646)
		(layer "In11.Cu")
		(net "M_D_CPU1_SB_DQS_DP<0>")
	)
	(arc
		(start 87.86241 -239.528858)
		(mid 87.675212 -239.478715)
		(end 87.488014 -239.528858)
		(width 0.088646)
		(layer "In11.Cu")
		(net "M_D_CPU1_SB_DQS_DP<0>")
	)
	(arc
		(start 97.34169 -240.351056)
		(mid 97.065025 -240.418527)
		(end 96.79051 -240.342674)
		(width 0.088646)
		(layer "In11.Cu")
		(net "M_D_CPU1_SB_DQS_DP<0>")
	)
	(arc
		(start 93.031564 -240.342928)
		(mid 92.844366 -240.292785)
		(end 92.657168 -240.342928)
		(width 0.088646)
		(layer "In11.Cu")
		(net "M_D_CPU1_SB_DQS_DP<0>")
	)
	(arc
		(start 85.513164 -238.715042)
		(mid 85.325966 -238.664899)
		(end 85.138768 -238.715042)
		(width 0.088646)
		(layer "In11.Cu")
		(net "M_D_CPU1_SB_DQS_DP<0>")
	)
	(arc
		(start 96.416368 -240.342928)
		(mid 96.142139 -240.418853)
		(end 95.865696 -240.351564)
		(width 0.088646)
		(layer "In11.Cu")
		(net "M_D_CPU1_SB_DQS_DP<0>")
	)
	(arc
		(start 89.837768 -240.342928)
		(mid 89.563539 -240.418853)
		(end 89.287096 -240.351564)
		(width 0.088646)
		(layer "In11.Cu")
		(net "M_D_CPU1_SB_DQS_DP<0>")
	)
	(arc
		(start 86.640416 -239.0394)
		(mid 86.592737 -238.8565)
		(end 86.461854 -238.720122)
		(width 0.088646)
		(layer "In11.Cu")
		(net "M_D_CPU1_SB_DQS_DP<0>")
	)
	(arc
		(start 98.952812 -239.853216)
		(mid 98.776791 -239.876053)
		(end 98.612452 -239.943132)
		(width 0.088646)
		(layer "In11.Cu")
		(net "M_D_CPU1_SB_DQS_DP<0>")
	)
	(arc
		(start 84.573872 -238.714788)
		(mid 84.483331 -238.677296)
		(end 84.386166 -238.664496)
		(width 0.088646)
		(layer "In11.Cu")
		(net "M_D_CPU1_SB_DQS_DP<0>")
	)
	(arc
		(start 93.596968 -240.342928)
		(mid 93.322739 -240.418853)
		(end 93.046296 -240.351564)
		(width 0.088646)
		(layer "In11.Cu")
		(net "M_D_CPU1_SB_DQS_DP<0>")
	)
	(arc
		(start 93.971364 -240.342928)
		(mid 93.784166 -240.292785)
		(end 93.596968 -240.342928)
		(width 0.088646)
		(layer "In11.Cu")
		(net "M_D_CPU1_SB_DQS_DP<0>")
	)
	(arc
		(start 86.452964 -238.715042)
		(mid 86.265766 -238.664899)
		(end 86.078568 -238.715042)
		(width 0.088646)
		(layer "In11.Cu")
		(net "M_D_CPU1_SB_DQS_DP<0>")
	)
	(arc
		(start 89.272364 -240.342928)
		(mid 89.085166 -240.292785)
		(end 88.897968 -240.342928)
		(width 0.088646)
		(layer "In11.Cu")
		(net "M_D_CPU1_SB_DQS_DP<0>")
	)
	(arc
		(start 90.212164 -240.342928)
		(mid 90.024966 -240.292785)
		(end 89.837768 -240.342928)
		(width 0.088646)
		(layer "In11.Cu")
		(net "M_D_CPU1_SB_DQS_DP<0>")
	)
	(arc
		(start 92.091764 -240.342928)
		(mid 91.904566 -240.292785)
		(end 91.717368 -240.342928)
		(width 0.088646)
		(layer "In11.Cu")
		(net "M_D_CPU1_SB_DQS_DP<0>")
	)
	(arc
		(start 88.049862 -239.853216)
		(mid 88.002183 -239.670316)
		(end 87.8713 -239.533938)
		(width 0.088646)
		(layer "In11.Cu")
		(net "M_D_CPU1_SB_DQS_DP<0>")
	)
	(arc
		(start 94.911164 -240.342928)
		(mid 94.723966 -240.292785)
		(end 94.536768 -240.342928)
		(width 0.088646)
		(layer "In11.Cu")
		(net "M_D_CPU1_SB_DQS_DP<0>")
	)
	(arc
		(start 95.850964 -240.342928)
		(mid 95.663766 -240.292785)
		(end 95.476568 -240.342928)
		(width 0.088646)
		(layer "In11.Cu")
		(net "M_D_CPU1_SB_DQS_DP<0>")
	)
	(arc
		(start 87.473282 -239.537494)
		(mid 87.196807 -239.604814)
		(end 86.92261 -239.528858)
		(width 0.088646)
		(layer "In11.Cu")
		(net "M_D_CPU1_SB_DQS_DP<0>")
	)
	(arc
		(start 92.657168 -240.342928)
		(mid 92.382939 -240.418853)
		(end 92.106496 -240.351564)
		(width 0.088646)
		(layer "In11.Cu")
		(net "M_D_CPU1_SB_DQS_DP<0>")
	)
	(arc
		(start 98.187256 -240.18494)
		(mid 98.088414 -240.22245)
		(end 97.982786 -240.226596)
		(width 0.088646)
		(layer "In11.Cu")
		(net "M_D_CPU1_SB_DQS_DP<0>")
	)
	(arc
		(start 85.138768 -238.715042)
		(mid 84.856239 -238.790818)
		(end 84.573618 -238.715296)
		(width 0.088646)
		(layer "In11.Cu")
		(net "M_D_CPU1_SB_DQS_DP<0>")
	)
	(arc
		(start 91.717368 -240.342928)
		(mid 91.440555 -240.418764)
		(end 91.162124 -240.349024)
		(width 0.088646)
		(layer "In11.Cu")
		(net "M_D_CPU1_SB_DQS_DP<0>")
	)
	(arc
		(start 86.92261 -239.528858)
		(mid 86.719787 -239.328627)
		(end 86.640416 -239.054894)
		(width 0.088646)
		(layer "In11.Cu")
		(net "M_D_CPU1_SB_DQS_DP<0>")
	)
	(arc
		(start 96.790764 -240.342928)
		(mid 96.603566 -240.292785)
		(end 96.416368 -240.342928)
		(width 0.088646)
		(layer "In11.Cu")
		(net "M_D_CPU1_SB_DQS_DP<0>")
	)
	(arc
		(start 95.476568 -240.342928)
		(mid 95.202339 -240.418853)
		(end 94.925896 -240.351564)
		(width 0.088646)
		(layer "In11.Cu")
		(net "M_D_CPU1_SB_DQS_DP<0>")
	)
	(arc
		(start 88.897968 -240.342928)
		(mid 88.623739 -240.418853)
		(end 88.347296 -240.351564)
		(width 0.088646)
		(layer "In11.Cu")
		(net "M_D_CPU1_SB_DQS_DP<0>")
	)
	(arc
		(start 91.15171 -240.342928)
		(mid 90.964512 -240.292785)
		(end 90.777314 -240.342928)
		(width 0.088646)
		(layer "In11.Cu")
		(net "M_D_CPU1_SB_DQS_DP<0>")
	)
	(arc
		(start 94.536768 -240.342928)
		(mid 94.262539 -240.418853)
		(end 93.986096 -240.351564)
		(width 0.088646)
		(layer "In11.Cu")
		(net "M_D_CPU1_SB_DQS_DP<0>")
	)
	(arc
		(start 86.078568 -238.715042)
		(mid 85.795866 -238.790818)
		(end 85.513164 -238.715042)
		(width 0.088646)
		(layer "In11.Cu")
		(net "M_D_CPU1_SB_DQS_DP<0>")
	)
	(arc
		(start 90.7669 -240.349024)
		(mid 90.488722 -240.418716)
		(end 90.212164 -240.342928)
		(width 0.088646)
		(layer "In11.Cu")
		(net "M_D_CPU1_SB_DQS_DP<0>")
	)
	(segment
		(start 98.013266 -245.27256)
		(end 98.013012 -245.272306)
		(width 0.20066)
		(layer "F.Cu")
		(net "M_D_CPU1_SB_DQS_DN<9>")
	)
	(segment
		(start 9.46404 -237.527846)
		(end 8.950198 -237.527846)
		(width 0.20066)
		(layer "F.Cu")
		(net "M_D_CPU1_SB_DQS_DN<9>")
	)
	(segment
		(start 10.912094 -237.681008)
		(end 10.64006 -237.953042)
		(width 0.20066)
		(layer "F.Cu")
		(net "M_D_CPU1_SB_DQS_DN<9>")
	)
	(segment
		(start 13.59662 -237.691676)
		(end 13.441426 -237.691676)
		(width 0.20066)
		(layer "F.Cu")
		(net "M_D_CPU1_SB_DQS_DN<9>")
	)
	(segment
		(start 13.857986 -237.953042)
		(end 13.59662 -237.691676)
		(width 0.20066)
		(layer "F.Cu")
		(net "M_D_CPU1_SB_DQS_DN<9>")
	)
	(segment
		(start 15.684246 -237.266734)
		(end 15.137638 -237.266734)
		(width 0.20066)
		(layer "F.Cu")
		(net "M_D_CPU1_SB_DQS_DN<9>")
	)
	(segment
		(start 98.013012 -245.272306)
		(end 98.013012 -244.73662)
		(width 0.20066)
		(layer "F.Cu")
		(net "M_D_CPU1_SB_DQS_DN<9>")
	)
	(segment
		(start 8.689086 -237.266734)
		(end 8.140446 -237.266734)
		(width 0.20066)
		(layer "F.Cu")
		(net "M_D_CPU1_SB_DQS_DN<9>")
	)
	(segment
		(start 11.11631 -237.681008)
		(end 10.912094 -237.681008)
		(width 0.20066)
		(layer "F.Cu")
		(net "M_D_CPU1_SB_DQS_DN<9>")
	)
	(segment
		(start 16.789146 -237.266734)
		(end 15.684246 -237.266734)
		(width 0.20066)
		(layer "F.Cu")
		(net "M_D_CPU1_SB_DQS_DN<9>")
	)
	(segment
		(start 10.64006 -237.953042)
		(end 10.100056 -237.953042)
		(width 0.20066)
		(layer "F.Cu")
		(net "M_D_CPU1_SB_DQS_DN<9>")
	)
	(segment
		(start 8.950198 -237.527846)
		(end 8.689086 -237.266734)
		(width 0.20066)
		(layer "F.Cu")
		(net "M_D_CPU1_SB_DQS_DN<9>")
	)
	(segment
		(start 11.12774 -237.691676)
		(end 11.117072 -237.681008)
		(width 0.101854)
		(layer "F.Cu")
		(net "M_D_CPU1_SB_DQS_DN<9>")
	)
	(segment
		(start 10.100056 -237.953042)
		(end 9.46404 -237.527846)
		(width 0.20066)
		(layer "F.Cu")
		(net "M_D_CPU1_SB_DQS_DN<9>")
	)
	(segment
		(start 15.137638 -237.266734)
		(end 14.876526 -237.527846)
		(width 0.20066)
		(layer "F.Cu")
		(net "M_D_CPU1_SB_DQS_DN<9>")
	)
	(segment
		(start 14.469872 -237.527846)
		(end 14.044676 -237.953042)
		(width 0.20066)
		(layer "F.Cu")
		(net "M_D_CPU1_SB_DQS_DN<9>")
	)
	(segment
		(start 14.876526 -237.527846)
		(end 14.469872 -237.527846)
		(width 0.20066)
		(layer "F.Cu")
		(net "M_D_CPU1_SB_DQS_DN<9>")
	)
	(segment
		(start 13.441426 -237.691676)
		(end 11.12774 -237.691676)
		(width 0.1016)
		(layer "F.Cu")
		(net "M_D_CPU1_SB_DQS_DN<9>")
	)
	(segment
		(start 11.117072 -237.681008)
		(end 11.11631 -237.681008)
		(width 0.101854)
		(layer "F.Cu")
		(net "M_D_CPU1_SB_DQS_DN<9>")
	)
	(segment
		(start 14.044676 -237.953042)
		(end 13.857986 -237.953042)
		(width 0.20066)
		(layer "F.Cu")
		(net "M_D_CPU1_SB_DQS_DN<9>")
	)
	(segment
		(start 20.402296 -237.957868)
		(end 20.04314 -237.957868)
		(width 0.18288)
		(layer "In11.Cu")
		(net "M_D_CPU1_SB_DQS_DN<9>")
	)
	(segment
		(start 71.155306 -242.652042)
		(end 70.767194 -242.26393)
		(width 0.18288)
		(layer "In11.Cu")
		(net "M_D_CPU1_SB_DQS_DN<9>")
	)
	(segment
		(start 61.174884 -237.182406)
		(end 61.050424 -237.306866)
		(width 0.18288)
		(layer "In11.Cu")
		(net "M_D_CPU1_SB_DQS_DN<9>")
	)
	(segment
		(start 84.19084 -243.853208)
		(end 83.73364 -243.853208)
		(width 0.088646)
		(layer "In11.Cu")
		(net "M_D_CPU1_SB_DQS_DN<9>")
	)
	(segment
		(start 51.307746 -237.691676)
		(end 50.828448 -237.691676)
		(width 0.18288)
		(layer "In11.Cu")
		(net "M_D_CPU1_SB_DQS_DN<9>")
	)
	(segment
		(start 50.828448 -237.691676)
		(end 50.597816 -237.922308)
		(width 0.18288)
		(layer "In11.Cu")
		(net "M_D_CPU1_SB_DQS_DN<9>")
	)
	(segment
		(start 57.136284 -237.182406)
		(end 57.011824 -237.306866)
		(width 0.18288)
		(layer "In11.Cu")
		(net "M_D_CPU1_SB_DQS_DN<9>")
	)
	(segment
		(start 82.637122 -243.793264)
		(end 82.05978 -243.215922)
		(width 0.18288)
		(layer "In11.Cu")
		(net "M_D_CPU1_SB_DQS_DN<9>")
	)
	(segment
		(start 36.486084 -238.009176)
		(end 36.168076 -237.691168)
		(width 0.18288)
		(layer "In11.Cu")
		(net "M_D_CPU1_SB_DQS_DN<9>")
	)
	(segment
		(start 62.521084 -237.182406)
		(end 62.396624 -237.306866)
		(width 0.18288)
		(layer "In11.Cu")
		(net "M_D_CPU1_SB_DQS_DN<9>")
	)
	(segment
		(start 90.692478 -245.054882)
		(end 90.682064 -245.060978)
		(width 0.088646)
		(layer "In11.Cu")
		(net "M_D_CPU1_SB_DQS_DN<9>")
	)
	(segment
		(start 70.203314 -241.70005)
		(end 69.815202 -241.311938)
		(width 0.18288)
		(layer "In11.Cu")
		(net "M_D_CPU1_SB_DQS_DN<9>")
	)
	(segment
		(start 31.01975 -238.651034)
		(end 29.932376 -238.200184)
		(width 0.18288)
		(layer "In11.Cu")
		(net "M_D_CPU1_SB_DQS_DN<9>")
	)
	(segment
		(start 46.518576 -238.796322)
		(end 46.059598 -238.796322)
		(width 0.18288)
		(layer "In11.Cu")
		(net "M_D_CPU1_SB_DQS_DN<9>")
	)
	(segment
		(start 63.069724 -237.182406)
		(end 62.521084 -237.182406)
		(width 0.18288)
		(layer "In11.Cu")
		(net "M_D_CPU1_SB_DQS_DN<9>")
	)
	(segment
		(start 95.006414 -245.060978)
		(end 94.991682 -245.052342)
		(width 0.088646)
		(layer "In11.Cu")
		(net "M_D_CPU1_SB_DQS_DN<9>")
	)
	(segment
		(start 87.488014 -245.060978)
		(end 87.473282 -245.052342)
		(width 0.088646)
		(layer "In11.Cu")
		(net "M_D_CPU1_SB_DQS_DN<9>")
	)
	(segment
		(start 40.961564 -237.354364)
		(end 39.380668 -238.009176)
		(width 0.18288)
		(layer "In11.Cu")
		(net "M_D_CPU1_SB_DQS_DN<9>")
	)
	(segment
		(start 97.981262 -244.852444)
		(end 97.9424 -244.874542)
		(width 0.088646)
		(layer "In11.Cu")
		(net "M_D_CPU1_SB_DQS_DN<9>")
	)
	(segment
		(start 32.38754 -238.804196)
		(end 32.125412 -238.542068)
		(width 0.18288)
		(layer "In11.Cu")
		(net "M_D_CPU1_SB_DQS_DN<9>")
	)
	(segment
		(start 92.572078 -245.054882)
		(end 92.561664 -245.060978)
		(width 0.088646)
		(layer "In11.Cu")
		(net "M_D_CPU1_SB_DQS_DN<9>")
	)
	(segment
		(start 31.665926 -238.542068)
		(end 31.409894 -238.7981)
		(width 0.18288)
		(layer "In11.Cu")
		(net "M_D_CPU1_SB_DQS_DN<9>")
	)
	(segment
		(start 62.396624 -237.306866)
		(end 61.847984 -237.306866)
		(width 0.18288)
		(layer "In11.Cu")
		(net "M_D_CPU1_SB_DQS_DN<9>")
	)
	(segment
		(start 89.367614 -245.060978)
		(end 89.352882 -245.052342)
		(width 0.088646)
		(layer "In11.Cu")
		(net "M_D_CPU1_SB_DQS_DN<9>")
	)
	(segment
		(start 70.591172 -242.26393)
		(end 70.203314 -241.876072)
		(width 0.18288)
		(layer "In11.Cu")
		(net "M_D_CPU1_SB_DQS_DN<9>")
	)
	(segment
		(start 86.548214 -245.060978)
		(end 86.533482 -245.052342)
		(width 0.088646)
		(layer "In11.Cu")
		(net "M_D_CPU1_SB_DQS_DN<9>")
	)
	(segment
		(start 47.166784 -238.544608)
		(end 46.77029 -238.544608)
		(width 0.18288)
		(layer "In11.Cu")
		(net "M_D_CPU1_SB_DQS_DN<9>")
	)
	(segment
		(start 58.482484 -237.182406)
		(end 58.358024 -237.306866)
		(width 0.18288)
		(layer "In11.Cu")
		(net "M_D_CPU1_SB_DQS_DN<9>")
	)
	(segment
		(start 49.24552 -238.462312)
		(end 48.42256 -238.803942)
		(width 0.18288)
		(layer "In11.Cu")
		(net "M_D_CPU1_SB_DQS_DN<9>")
	)
	(segment
		(start 51.573938 -237.957868)
		(end 51.307746 -237.691676)
		(width 0.18288)
		(layer "In11.Cu")
		(net "M_D_CPU1_SB_DQS_DN<9>")
	)
	(segment
		(start 96.886268 -245.060978)
		(end 96.875854 -245.054882)
		(width 0.088646)
		(layer "In11.Cu")
		(net "M_D_CPU1_SB_DQS_DN<9>")
	)
	(segment
		(start 84.509102 -244.17147)
		(end 84.19084 -243.853208)
		(width 0.088646)
		(layer "In11.Cu")
		(net "M_D_CPU1_SB_DQS_DN<9>")
	)
	(segment
		(start 20.66925 -237.690914)
		(end 20.402296 -237.957868)
		(width 0.18288)
		(layer "In11.Cu")
		(net "M_D_CPU1_SB_DQS_DN<9>")
	)
	(segment
		(start 48.42256 -238.803942)
		(end 47.426118 -238.803942)
		(width 0.18288)
		(layer "In11.Cu")
		(net "M_D_CPU1_SB_DQS_DN<9>")
	)
	(segment
		(start 61.050424 -237.306866)
		(end 60.501784 -237.306866)
		(width 0.18288)
		(layer "In11.Cu")
		(net "M_D_CPU1_SB_DQS_DN<9>")
	)
	(segment
		(start 94.066614 -245.060978)
		(end 94.051882 -245.052342)
		(width 0.088646)
		(layer "In11.Cu")
		(net "M_D_CPU1_SB_DQS_DN<9>")
	)
	(segment
		(start 52.167536 -237.957868)
		(end 51.573938 -237.957868)
		(width 0.18288)
		(layer "In11.Cu")
		(net "M_D_CPU1_SB_DQS_DN<9>")
	)
	(segment
		(start 31.166816 -238.7981)
		(end 31.01975 -238.651034)
		(width 0.18288)
		(layer "In11.Cu")
		(net "M_D_CPU1_SB_DQS_DN<9>")
	)
	(segment
		(start 43.937936 -237.354364)
		(end 40.961564 -237.354364)
		(width 0.18288)
		(layer "In11.Cu")
		(net "M_D_CPU1_SB_DQS_DN<9>")
	)
	(segment
		(start 69.251322 -240.748058)
		(end 68.86321 -240.359946)
		(width 0.18288)
		(layer "In11.Cu")
		(net "M_D_CPU1_SB_DQS_DN<9>")
	)
	(segment
		(start 49.508664 -238.199676)
		(end 49.24552 -238.462312)
		(width 0.18288)
		(layer "In11.Cu")
		(net "M_D_CPU1_SB_DQS_DN<9>")
	)
	(segment
		(start 20.04314 -237.957868)
		(end 19.405092 -237.31982)
		(width 0.18288)
		(layer "In11.Cu")
		(net "M_D_CPU1_SB_DQS_DN<9>")
	)
	(segment
		(start 83.673696 -243.793264)
		(end 82.637122 -243.793264)
		(width 0.18288)
		(layer "In11.Cu")
		(net "M_D_CPU1_SB_DQS_DN<9>")
	)
	(segment
		(start 60.377324 -237.182406)
		(end 59.828684 -237.182406)
		(width 0.18288)
		(layer "In11.Cu")
		(net "M_D_CPU1_SB_DQS_DN<9>")
	)
	(segment
		(start 29.932376 -238.200184)
		(end 29.369512 -238.200184)
		(width 0.18288)
		(layer "In11.Cu")
		(net "M_D_CPU1_SB_DQS_DN<9>")
	)
	(segment
		(start 98.013012 -244.73662)
		(end 97.981262 -244.852444)
		(width 0.088646)
		(layer "In11.Cu")
		(net "M_D_CPU1_SB_DQS_DN<9>")
	)
	(segment
		(start 32.125412 -238.542068)
		(end 31.665926 -238.542068)
		(width 0.18288)
		(layer "In11.Cu")
		(net "M_D_CPU1_SB_DQS_DN<9>")
	)
	(segment
		(start 61.847984 -237.306866)
		(end 61.723524 -237.182406)
		(width 0.18288)
		(layer "In11.Cu")
		(net "M_D_CPU1_SB_DQS_DN<9>")
	)
	(segment
		(start 29.369512 -238.200184)
		(end 28.520898 -238.551466)
		(width 0.18288)
		(layer "In11.Cu")
		(net "M_D_CPU1_SB_DQS_DN<9>")
	)
	(segment
		(start 70.203314 -241.876072)
		(end 70.203314 -241.70005)
		(width 0.18288)
		(layer "In11.Cu")
		(net "M_D_CPU1_SB_DQS_DN<9>")
	)
	(segment
		(start 63.742824 -237.306866)
		(end 63.194184 -237.306866)
		(width 0.18288)
		(layer "In11.Cu")
		(net "M_D_CPU1_SB_DQS_DN<9>")
	)
	(segment
		(start 35.486086 -237.969298)
		(end 35.047682 -237.969298)
		(width 0.18288)
		(layer "In11.Cu")
		(net "M_D_CPU1_SB_DQS_DN<9>")
	)
	(segment
		(start 83.73364 -243.853208)
		(end 83.673696 -243.793264)
		(width 0.088646)
		(layer "In11.Cu")
		(net "M_D_CPU1_SB_DQS_DN<9>")
	)
	(segment
		(start 63.194184 -237.306866)
		(end 63.069724 -237.182406)
		(width 0.18288)
		(layer "In11.Cu")
		(net "M_D_CPU1_SB_DQS_DN<9>")
	)
	(segment
		(start 46.059598 -238.796322)
		(end 45.09897 -237.835694)
		(width 0.18288)
		(layer "In11.Cu")
		(net "M_D_CPU1_SB_DQS_DN<9>")
	)
	(segment
		(start 85.420962 -244.73662)
		(end 85.420962 -244.726714)
		(width 0.088646)
		(layer "In11.Cu")
		(net "M_D_CPU1_SB_DQS_DN<9>")
	)
	(segment
		(start 57.809384 -237.306866)
		(end 57.684924 -237.182406)
		(width 0.18288)
		(layer "In11.Cu")
		(net "M_D_CPU1_SB_DQS_DN<9>")
	)
	(segment
		(start 56.463184 -237.306866)
		(end 56.338724 -237.182406)
		(width 0.18288)
		(layer "In11.Cu")
		(net "M_D_CPU1_SB_DQS_DN<9>")
	)
	(segment
		(start 53.739288 -237.306866)
		(end 52.167536 -237.957868)
		(width 0.18288)
		(layer "In11.Cu")
		(net "M_D_CPU1_SB_DQS_DN<9>")
	)
	(segment
		(start 82.05978 -243.215922)
		(end 71.543164 -243.215922)
		(width 0.18288)
		(layer "In11.Cu")
		(net "M_D_CPU1_SB_DQS_DN<9>")
	)
	(segment
		(start 39.380668 -238.009176)
		(end 36.486084 -238.009176)
		(width 0.18288)
		(layer "In11.Cu")
		(net "M_D_CPU1_SB_DQS_DN<9>")
	)
	(segment
		(start 56.338724 -237.182406)
		(end 55.790084 -237.182406)
		(width 0.18288)
		(layer "In11.Cu")
		(net "M_D_CPU1_SB_DQS_DN<9>")
	)
	(segment
		(start 59.155584 -237.306866)
		(end 59.031124 -237.182406)
		(width 0.18288)
		(layer "In11.Cu")
		(net "M_D_CPU1_SB_DQS_DN<9>")
	)
	(segment
		(start 64.992758 -237.826042)
		(end 63.742824 -237.306866)
		(width 0.18288)
		(layer "In11.Cu")
		(net "M_D_CPU1_SB_DQS_DN<9>")
	)
	(segment
		(start 17.042892 -237.52048)
		(end 16.789146 -237.266734)
		(width 0.18288)
		(layer "In11.Cu")
		(net "M_D_CPU1_SB_DQS_DN<9>")
	)
	(segment
		(start 57.684924 -237.182406)
		(end 57.136284 -237.182406)
		(width 0.18288)
		(layer "In11.Cu")
		(net "M_D_CPU1_SB_DQS_DN<9>")
	)
	(segment
		(start 34.820606 -238.196374)
		(end 33.352486 -238.804196)
		(width 0.18288)
		(layer "In11.Cu")
		(net "M_D_CPU1_SB_DQS_DN<9>")
	)
	(segment
		(start 55.665624 -237.306866)
		(end 53.739288 -237.306866)
		(width 0.18288)
		(layer "In11.Cu")
		(net "M_D_CPU1_SB_DQS_DN<9>")
	)
	(segment
		(start 84.856066 -244.17147)
		(end 84.509102 -244.17147)
		(width 0.088646)
		(layer "In11.Cu")
		(net "M_D_CPU1_SB_DQS_DN<9>")
	)
	(segment
		(start 59.031124 -237.182406)
		(end 58.482484 -237.182406)
		(width 0.18288)
		(layer "In11.Cu")
		(net "M_D_CPU1_SB_DQS_DN<9>")
	)
	(segment
		(start 97.514156 -244.915436)
		(end 97.260918 -245.061232)
		(width 0.088646)
		(layer "In11.Cu")
		(net "M_D_CPU1_SB_DQS_DN<9>")
	)
	(segment
		(start 59.828684 -237.182406)
		(end 59.704224 -237.306866)
		(width 0.18288)
		(layer "In11.Cu")
		(net "M_D_CPU1_SB_DQS_DN<9>")
	)
	(segment
		(start 70.767194 -242.26393)
		(end 70.591172 -242.26393)
		(width 0.18288)
		(layer "In11.Cu")
		(net "M_D_CPU1_SB_DQS_DN<9>")
	)
	(segment
		(start 59.704224 -237.306866)
		(end 59.155584 -237.306866)
		(width 0.18288)
		(layer "In11.Cu")
		(net "M_D_CPU1_SB_DQS_DN<9>")
	)
	(segment
		(start 17.359376 -237.52048)
		(end 17.042892 -237.52048)
		(width 0.18288)
		(layer "In11.Cu")
		(net "M_D_CPU1_SB_DQS_DN<9>")
	)
	(segment
		(start 19.405092 -237.31982)
		(end 17.844008 -237.31982)
		(width 0.18288)
		(layer "In11.Cu")
		(net "M_D_CPU1_SB_DQS_DN<9>")
	)
	(segment
		(start 31.409894 -238.7981)
		(end 31.166816 -238.7981)
		(width 0.18288)
		(layer "In11.Cu")
		(net "M_D_CPU1_SB_DQS_DN<9>")
	)
	(segment
		(start 35.047682 -237.969298)
		(end 34.820606 -238.196374)
		(width 0.18288)
		(layer "In11.Cu")
		(net "M_D_CPU1_SB_DQS_DN<9>")
	)
	(segment
		(start 45.09897 -237.835694)
		(end 43.937936 -237.354364)
		(width 0.18288)
		(layer "In11.Cu")
		(net "M_D_CPU1_SB_DQS_DN<9>")
	)
	(segment
		(start 47.426118 -238.803942)
		(end 47.166784 -238.544608)
		(width 0.18288)
		(layer "In11.Cu")
		(net "M_D_CPU1_SB_DQS_DN<9>")
	)
	(segment
		(start 92.187268 -245.060978)
		(end 92.176854 -245.054882)
		(width 0.088646)
		(layer "In11.Cu")
		(net "M_D_CPU1_SB_DQS_DN<9>")
	)
	(segment
		(start 97.260918 -245.061232)
		(end 97.260664 -245.060978)
		(width 0.088646)
		(layer "In11.Cu")
		(net "M_D_CPU1_SB_DQS_DN<9>")
	)
	(segment
		(start 58.358024 -237.306866)
		(end 57.809384 -237.306866)
		(width 0.18288)
		(layer "In11.Cu")
		(net "M_D_CPU1_SB_DQS_DN<9>")
	)
	(segment
		(start 57.011824 -237.306866)
		(end 56.463184 -237.306866)
		(width 0.18288)
		(layer "In11.Cu")
		(net "M_D_CPU1_SB_DQS_DN<9>")
	)
	(segment
		(start 88.427814 -245.060978)
		(end 88.413082 -245.052342)
		(width 0.088646)
		(layer "In11.Cu")
		(net "M_D_CPU1_SB_DQS_DN<9>")
	)
	(segment
		(start 71.155306 -242.828064)
		(end 71.155306 -242.652042)
		(width 0.18288)
		(layer "In11.Cu")
		(net "M_D_CPU1_SB_DQS_DN<9>")
	)
	(segment
		(start 85.608414 -245.060978)
		(end 85.599524 -245.055898)
		(width 0.088646)
		(layer "In11.Cu")
		(net "M_D_CPU1_SB_DQS_DN<9>")
	)
	(segment
		(start 28.520898 -238.551466)
		(end 25.912318 -238.551466)
		(width 0.18288)
		(layer "In11.Cu")
		(net "M_D_CPU1_SB_DQS_DN<9>")
	)
	(segment
		(start 68.687188 -240.359946)
		(end 67.19316 -238.865918)
		(width 0.18288)
		(layer "In11.Cu")
		(net "M_D_CPU1_SB_DQS_DN<9>")
	)
	(segment
		(start 21.147024 -237.690914)
		(end 20.66925 -237.690914)
		(width 0.18288)
		(layer "In11.Cu")
		(net "M_D_CPU1_SB_DQS_DN<9>")
	)
	(segment
		(start 97.787714 -244.915436)
		(end 97.514156 -244.915436)
		(width 0.088646)
		(layer "In11.Cu")
		(net "M_D_CPU1_SB_DQS_DN<9>")
	)
	(segment
		(start 21.408898 -237.952788)
		(end 21.147024 -237.690914)
		(width 0.18288)
		(layer "In11.Cu")
		(net "M_D_CPU1_SB_DQS_DN<9>")
	)
	(segment
		(start 67.19316 -238.865918)
		(end 67.193668 -238.865664)
		(width 0.18288)
		(layer "In11.Cu")
		(net "M_D_CPU1_SB_DQS_DN<9>")
	)
	(segment
		(start 66.46545 -238.564674)
		(end 65.73139 -238.564674)
		(width 0.18288)
		(layer "In11.Cu")
		(net "M_D_CPU1_SB_DQS_DN<9>")
	)
	(segment
		(start 60.501784 -237.306866)
		(end 60.377324 -237.182406)
		(width 0.18288)
		(layer "In11.Cu")
		(net "M_D_CPU1_SB_DQS_DN<9>")
	)
	(segment
		(start 50.597816 -237.922308)
		(end 50.177954 -237.922308)
		(width 0.18288)
		(layer "In11.Cu")
		(net "M_D_CPU1_SB_DQS_DN<9>")
	)
	(segment
		(start 55.790084 -237.182406)
		(end 55.665624 -237.306866)
		(width 0.18288)
		(layer "In11.Cu")
		(net "M_D_CPU1_SB_DQS_DN<9>")
	)
	(segment
		(start 24.467058 -237.952788)
		(end 21.408898 -237.952788)
		(width 0.18288)
		(layer "In11.Cu")
		(net "M_D_CPU1_SB_DQS_DN<9>")
	)
	(segment
		(start 69.251322 -240.92408)
		(end 69.251322 -240.748058)
		(width 0.18288)
		(layer "In11.Cu")
		(net "M_D_CPU1_SB_DQS_DN<9>")
	)
	(segment
		(start 69.815202 -241.311938)
		(end 69.63918 -241.311938)
		(width 0.18288)
		(layer "In11.Cu")
		(net "M_D_CPU1_SB_DQS_DN<9>")
	)
	(segment
		(start 17.844008 -237.31982)
		(end 17.359376 -237.52048)
		(width 0.18288)
		(layer "In11.Cu")
		(net "M_D_CPU1_SB_DQS_DN<9>")
	)
	(segment
		(start 50.177954 -237.922308)
		(end 49.508664 -238.199676)
		(width 0.18288)
		(layer "In11.Cu")
		(net "M_D_CPU1_SB_DQS_DN<9>")
	)
	(segment
		(start 46.77029 -238.544608)
		(end 46.518576 -238.796322)
		(width 0.18288)
		(layer "In11.Cu")
		(net "M_D_CPU1_SB_DQS_DN<9>")
	)
	(segment
		(start 35.764216 -237.691168)
		(end 35.486086 -237.969298)
		(width 0.18288)
		(layer "In11.Cu")
		(net "M_D_CPU1_SB_DQS_DN<9>")
	)
	(segment
		(start 25.912318 -238.551466)
		(end 24.467058 -237.952788)
		(width 0.18288)
		(layer "In11.Cu")
		(net "M_D_CPU1_SB_DQS_DN<9>")
	)
	(segment
		(start 90.307668 -245.060978)
		(end 90.297254 -245.054882)
		(width 0.088646)
		(layer "In11.Cu")
		(net "M_D_CPU1_SB_DQS_DN<9>")
	)
	(segment
		(start 33.352486 -238.804196)
		(end 32.38754 -238.804196)
		(width 0.18288)
		(layer "In11.Cu")
		(net "M_D_CPU1_SB_DQS_DN<9>")
	)
	(segment
		(start 71.543164 -243.215922)
		(end 71.155306 -242.828064)
		(width 0.18288)
		(layer "In11.Cu")
		(net "M_D_CPU1_SB_DQS_DN<9>")
	)
	(segment
		(start 61.723524 -237.182406)
		(end 61.174884 -237.182406)
		(width 0.18288)
		(layer "In11.Cu")
		(net "M_D_CPU1_SB_DQS_DN<9>")
	)
	(segment
		(start 95.946214 -245.060978)
		(end 95.931482 -245.052342)
		(width 0.088646)
		(layer "In11.Cu")
		(net "M_D_CPU1_SB_DQS_DN<9>")
	)
	(segment
		(start 65.73139 -238.564674)
		(end 64.992758 -237.826042)
		(width 0.18288)
		(layer "In11.Cu")
		(net "M_D_CPU1_SB_DQS_DN<9>")
	)
	(segment
		(start 68.86321 -240.359946)
		(end 68.687188 -240.359946)
		(width 0.18288)
		(layer "In11.Cu")
		(net "M_D_CPU1_SB_DQS_DN<9>")
	)
	(segment
		(start 36.168076 -237.691168)
		(end 35.764216 -237.691168)
		(width 0.18288)
		(layer "In11.Cu")
		(net "M_D_CPU1_SB_DQS_DN<9>")
	)
	(segment
		(start 67.193668 -238.865664)
		(end 66.46545 -238.564674)
		(width 0.18288)
		(layer "In11.Cu")
		(net "M_D_CPU1_SB_DQS_DN<9>")
	)
	(segment
		(start 69.63918 -241.311938)
		(end 69.251322 -240.92408)
		(width 0.18288)
		(layer "In11.Cu")
		(net "M_D_CPU1_SB_DQS_DN<9>")
	)
	(arc
		(start 93.50121 -245.060978)
		(mid 93.314012 -245.111121)
		(end 93.126814 -245.060978)
		(width 0.088646)
		(layer "In11.Cu")
		(net "M_D_CPU1_SB_DQS_DN<9>")
	)
	(arc
		(start 97.9424 -244.874542)
		(mid 97.867715 -244.905047)
		(end 97.787714 -244.915436)
		(width 0.088646)
		(layer "In11.Cu")
		(net "M_D_CPU1_SB_DQS_DN<9>")
	)
	(arc
		(start 95.38081 -245.060978)
		(mid 95.193612 -245.111121)
		(end 95.006414 -245.060978)
		(width 0.088646)
		(layer "In11.Cu")
		(net "M_D_CPU1_SB_DQS_DN<9>")
	)
	(arc
		(start 87.86241 -245.060978)
		(mid 87.675212 -245.111121)
		(end 87.488014 -245.060978)
		(width 0.088646)
		(layer "In11.Cu")
		(net "M_D_CPU1_SB_DQS_DN<9>")
	)
	(arc
		(start 88.80221 -245.060978)
		(mid 88.615012 -245.111121)
		(end 88.427814 -245.060978)
		(width 0.088646)
		(layer "In11.Cu")
		(net "M_D_CPU1_SB_DQS_DN<9>")
	)
	(arc
		(start 96.875854 -245.054882)
		(mid 96.597422 -244.985068)
		(end 96.32061 -245.060978)
		(width 0.088646)
		(layer "In11.Cu")
		(net "M_D_CPU1_SB_DQS_DN<9>")
	)
	(arc
		(start 86.92261 -245.060978)
		(mid 86.735412 -245.111121)
		(end 86.548214 -245.060978)
		(width 0.088646)
		(layer "In11.Cu")
		(net "M_D_CPU1_SB_DQS_DN<9>")
	)
	(arc
		(start 89.352882 -245.052342)
		(mid 89.076441 -244.985176)
		(end 88.80221 -245.060978)
		(width 0.088646)
		(layer "In11.Cu")
		(net "M_D_CPU1_SB_DQS_DN<9>")
	)
	(arc
		(start 89.74201 -245.060978)
		(mid 89.554812 -245.111121)
		(end 89.367614 -245.060978)
		(width 0.088646)
		(layer "In11.Cu")
		(net "M_D_CPU1_SB_DQS_DN<9>")
	)
	(arc
		(start 85.599524 -245.055898)
		(mid 85.46861 -244.919538)
		(end 85.420962 -244.73662)
		(width 0.088646)
		(layer "In11.Cu")
		(net "M_D_CPU1_SB_DQS_DN<9>")
	)
	(arc
		(start 94.991682 -245.052342)
		(mid 94.715241 -244.985176)
		(end 94.44101 -245.060978)
		(width 0.088646)
		(layer "In11.Cu")
		(net "M_D_CPU1_SB_DQS_DN<9>")
	)
	(arc
		(start 92.561664 -245.060978)
		(mid 92.374466 -245.111121)
		(end 92.187268 -245.060978)
		(width 0.088646)
		(layer "In11.Cu")
		(net "M_D_CPU1_SB_DQS_DN<9>")
	)
	(arc
		(start 97.260664 -245.060978)
		(mid 97.073466 -245.111121)
		(end 96.886268 -245.060978)
		(width 0.088646)
		(layer "In11.Cu")
		(net "M_D_CPU1_SB_DQS_DN<9>")
	)
	(arc
		(start 90.682064 -245.060978)
		(mid 90.494866 -245.111121)
		(end 90.307668 -245.060978)
		(width 0.088646)
		(layer "In11.Cu")
		(net "M_D_CPU1_SB_DQS_DN<9>")
	)
	(arc
		(start 91.247214 -245.060978)
		(mid 90.970655 -244.985269)
		(end 90.692478 -245.054882)
		(width 0.088646)
		(layer "In11.Cu")
		(net "M_D_CPU1_SB_DQS_DN<9>")
	)
	(arc
		(start 92.176854 -245.054882)
		(mid 91.898422 -244.985068)
		(end 91.62161 -245.060978)
		(width 0.088646)
		(layer "In11.Cu")
		(net "M_D_CPU1_SB_DQS_DN<9>")
	)
	(arc
		(start 90.297254 -245.054882)
		(mid 90.018822 -244.985068)
		(end 89.74201 -245.060978)
		(width 0.088646)
		(layer "In11.Cu")
		(net "M_D_CPU1_SB_DQS_DN<9>")
	)
	(arc
		(start 85.98281 -245.060978)
		(mid 85.795612 -245.111121)
		(end 85.608414 -245.060978)
		(width 0.088646)
		(layer "In11.Cu")
		(net "M_D_CPU1_SB_DQS_DN<9>")
	)
	(arc
		(start 88.413082 -245.052342)
		(mid 88.136641 -244.985176)
		(end 87.86241 -245.060978)
		(width 0.088646)
		(layer "In11.Cu")
		(net "M_D_CPU1_SB_DQS_DN<9>")
	)
	(arc
		(start 95.931482 -245.052342)
		(mid 95.655041 -244.985176)
		(end 95.38081 -245.060978)
		(width 0.088646)
		(layer "In11.Cu")
		(net "M_D_CPU1_SB_DQS_DN<9>")
	)
	(arc
		(start 86.533482 -245.052342)
		(mid 86.257041 -244.985176)
		(end 85.98281 -245.060978)
		(width 0.088646)
		(layer "In11.Cu")
		(net "M_D_CPU1_SB_DQS_DN<9>")
	)
	(arc
		(start 85.420962 -244.726714)
		(mid 85.252068 -244.333539)
		(end 84.856066 -244.17147)
		(width 0.088646)
		(layer "In11.Cu")
		(net "M_D_CPU1_SB_DQS_DN<9>")
	)
	(arc
		(start 94.44101 -245.060978)
		(mid 94.253812 -245.111121)
		(end 94.066614 -245.060978)
		(width 0.088646)
		(layer "In11.Cu")
		(net "M_D_CPU1_SB_DQS_DN<9>")
	)
	(arc
		(start 96.32061 -245.060978)
		(mid 96.133412 -245.111121)
		(end 95.946214 -245.060978)
		(width 0.088646)
		(layer "In11.Cu")
		(net "M_D_CPU1_SB_DQS_DN<9>")
	)
	(arc
		(start 93.126814 -245.060978)
		(mid 92.850255 -244.985269)
		(end 92.572078 -245.054882)
		(width 0.088646)
		(layer "In11.Cu")
		(net "M_D_CPU1_SB_DQS_DN<9>")
	)
	(arc
		(start 94.051882 -245.052342)
		(mid 93.775441 -244.985176)
		(end 93.50121 -245.060978)
		(width 0.088646)
		(layer "In11.Cu")
		(net "M_D_CPU1_SB_DQS_DN<9>")
	)
	(arc
		(start 91.62161 -245.060978)
		(mid 91.434412 -245.111121)
		(end 91.247214 -245.060978)
		(width 0.088646)
		(layer "In11.Cu")
		(net "M_D_CPU1_SB_DQS_DN<9>")
	)
	(arc
		(start 87.473282 -245.052342)
		(mid 87.196841 -244.985176)
		(end 86.92261 -245.060978)
		(width 0.088646)
		(layer "In11.Cu")
		(net "M_D_CPU1_SB_DQS_DN<9>")
	)
	(segment
		(start 19.032728 -199.605646)
		(end 18.329148 -199.605646)
		(width 0.20066)
		(layer "F.Cu")
		(net "M_D_CPU1_SB_DQS_DN<8>")
	)
	(segment
		(start 14.560042 -199.44969)
		(end 14.37513 -199.44969)
		(width 0.20066)
		(layer "F.Cu")
		(net "M_D_CPU1_SB_DQS_DN<8>")
	)
	(segment
		(start 17.693132 -199.180704)
		(end 17.28851 -199.180704)
		(width 0.20066)
		(layer "F.Cu")
		(net "M_D_CPU1_SB_DQS_DN<8>")
	)
	(segment
		(start 20.889214 -199.866758)
		(end 19.784314 -199.866758)
		(width 0.20066)
		(layer "F.Cu")
		(net "M_D_CPU1_SB_DQS_DN<8>")
	)
	(segment
		(start 19.29384 -199.866758)
		(end 19.032728 -199.605646)
		(width 0.20066)
		(layer "F.Cu")
		(net "M_D_CPU1_SB_DQS_DN<8>")
	)
	(segment
		(start 12.973304 -199.605646)
		(end 12.712192 -199.866758)
		(width 0.20066)
		(layer "F.Cu")
		(net "M_D_CPU1_SB_DQS_DN<8>")
	)
	(segment
		(start 19.784314 -199.866758)
		(end 19.29384 -199.866758)
		(width 0.20066)
		(layer "F.Cu")
		(net "M_D_CPU1_SB_DQS_DN<8>")
	)
	(segment
		(start 14.807692 -199.441816)
		(end 14.567916 -199.441816)
		(width 0.101854)
		(layer "F.Cu")
		(net "M_D_CPU1_SB_DQS_DN<8>")
	)
	(segment
		(start 17.28851 -199.180704)
		(end 17.027398 -199.441816)
		(width 0.20066)
		(layer "F.Cu")
		(net "M_D_CPU1_SB_DQS_DN<8>")
	)
	(segment
		(start 16.885158 -199.441816)
		(end 14.807692 -199.441816)
		(width 0.1016)
		(layer "F.Cu")
		(net "M_D_CPU1_SB_DQS_DN<8>")
	)
	(segment
		(start 13.868908 -199.183244)
		(end 13.446506 -199.605646)
		(width 0.20066)
		(layer "F.Cu")
		(net "M_D_CPU1_SB_DQS_DN<8>")
	)
	(segment
		(start 13.446506 -199.605646)
		(end 12.973304 -199.605646)
		(width 0.20066)
		(layer "F.Cu")
		(net "M_D_CPU1_SB_DQS_DN<8>")
	)
	(segment
		(start 14.108684 -199.183244)
		(end 13.868908 -199.183244)
		(width 0.20066)
		(layer "F.Cu")
		(net "M_D_CPU1_SB_DQS_DN<8>")
	)
	(segment
		(start 99.892866 -230.622602)
		(end 99.892612 -230.622348)
		(width 0.20066)
		(layer "F.Cu")
		(net "M_D_CPU1_SB_DQS_DN<8>")
	)
	(segment
		(start 18.329148 -199.605646)
		(end 17.693132 -199.180704)
		(width 0.20066)
		(layer "F.Cu")
		(net "M_D_CPU1_SB_DQS_DN<8>")
	)
	(segment
		(start 99.892612 -230.622348)
		(end 99.892612 -230.086662)
		(width 0.20066)
		(layer "F.Cu")
		(net "M_D_CPU1_SB_DQS_DN<8>")
	)
	(segment
		(start 17.027398 -199.441816)
		(end 16.885158 -199.441816)
		(width 0.20066)
		(layer "F.Cu")
		(net "M_D_CPU1_SB_DQS_DN<8>")
	)
	(segment
		(start 12.712192 -199.866758)
		(end 12.240514 -199.866758)
		(width 0.20066)
		(layer "F.Cu")
		(net "M_D_CPU1_SB_DQS_DN<8>")
	)
	(segment
		(start 14.567916 -199.441816)
		(end 14.560042 -199.44969)
		(width 0.101854)
		(layer "F.Cu")
		(net "M_D_CPU1_SB_DQS_DN<8>")
	)
	(segment
		(start 14.37513 -199.44969)
		(end 14.108684 -199.183244)
		(width 0.20066)
		(layer "F.Cu")
		(net "M_D_CPU1_SB_DQS_DN<8>")
	)
	(segment
		(start 21.147278 -199.608694)
		(end 20.889214 -199.866758)
		(width 0.18288)
		(layer "In11.Cu")
		(net "M_D_CPU1_SB_DQS_DN<8>")
	)
	(segment
		(start 74.28484 -211.618068)
		(end 73.896982 -211.23021)
		(width 0.18288)
		(layer "In11.Cu")
		(net "M_D_CPU1_SB_DQS_DN<8>")
	)
	(segment
		(start 31.618428 -197.744588)
		(end 31.38424 -197.5104)
		(width 0.18288)
		(layer "In11.Cu")
		(net "M_D_CPU1_SB_DQS_DN<8>")
	)
	(segment
		(start 73.896982 -211.23021)
		(end 73.72096 -211.23021)
		(width 0.18288)
		(layer "In11.Cu")
		(net "M_D_CPU1_SB_DQS_DN<8>")
	)
	(segment
		(start 97.447862 -228.45903)
		(end 97.447862 -228.45141)
		(width 0.088646)
		(layer "In11.Cu")
		(net "M_D_CPU1_SB_DQS_DN<8>")
	)
	(segment
		(start 35.771582 -198.590916)
		(end 35.527996 -198.34733)
		(width 0.18288)
		(layer "In11.Cu")
		(net "M_D_CPU1_SB_DQS_DN<8>")
	)
	(segment
		(start 45.28312 -198.127366)
		(end 44.29125 -198.127366)
		(width 0.18288)
		(layer "In11.Cu")
		(net "M_D_CPU1_SB_DQS_DN<8>")
	)
	(segment
		(start 83.933538 -225.015552)
		(end 82.512154 -223.594168)
		(width 0.088646)
		(layer "In11.Cu")
		(net "M_D_CPU1_SB_DQS_DN<8>")
	)
	(segment
		(start 97.726754 -228.946202)
		(end 97.718372 -228.941376)
		(width 0.088646)
		(layer "In11.Cu")
		(net "M_D_CPU1_SB_DQS_DN<8>")
	)
	(segment
		(start 71.428864 -208.938114)
		(end 71.428864 -208.762092)
		(width 0.18288)
		(layer "In11.Cu")
		(net "M_D_CPU1_SB_DQS_DN<8>")
	)
	(segment
		(start 82.512154 -223.594168)
		(end 82.427318 -223.594168)
		(width 0.088646)
		(layer "In11.Cu")
		(net "M_D_CPU1_SB_DQS_DN<8>")
	)
	(segment
		(start 62.541912 -198.38543)
		(end 59.800236 -198.38543)
		(width 0.18288)
		(layer "In11.Cu")
		(net "M_D_CPU1_SB_DQS_DN<8>")
	)
	(segment
		(start 48.93056 -197.462394)
		(end 47.456598 -197.462394)
		(width 0.18288)
		(layer "In11.Cu")
		(net "M_D_CPU1_SB_DQS_DN<8>")
	)
	(segment
		(start 54.97068 -198.316088)
		(end 51.56327 -198.316088)
		(width 0.18288)
		(layer "In11.Cu")
		(net "M_D_CPU1_SB_DQS_DN<8>")
	)
	(segment
		(start 99.892612 -230.086662)
		(end 100.20554 -230.086662)
		(width 0.088646)
		(layer "In11.Cu")
		(net "M_D_CPU1_SB_DQS_DN<8>")
	)
	(segment
		(start 93.986096 -227.329238)
		(end 93.971364 -227.320602)
		(width 0.088646)
		(layer "In11.Cu")
		(net "M_D_CPU1_SB_DQS_DN<8>")
	)
	(segment
		(start 71.428864 -208.762092)
		(end 65.4558 -202.789028)
		(width 0.18288)
		(layer "In11.Cu")
		(net "M_D_CPU1_SB_DQS_DN<8>")
	)
	(segment
		(start 75.236832 -212.57006)
		(end 74.848974 -212.182202)
		(width 0.18288)
		(layer "In11.Cu")
		(net "M_D_CPU1_SB_DQS_DN<8>")
	)
	(segment
		(start 71.816976 -209.326226)
		(end 71.428864 -208.938114)
		(width 0.18288)
		(layer "In11.Cu")
		(net "M_D_CPU1_SB_DQS_DN<8>")
	)
	(segment
		(start 47.174404 -197.744588)
		(end 46.713648 -197.744588)
		(width 0.18288)
		(layer "In11.Cu")
		(net "M_D_CPU1_SB_DQS_DN<8>")
	)
	(segment
		(start 28.232354 -197.714108)
		(end 27.969972 -197.880478)
		(width 0.18288)
		(layer "In11.Cu")
		(net "M_D_CPU1_SB_DQS_DN<8>")
	)
	(segment
		(start 40.493442 -198.315834)
		(end 36.478464 -198.315834)
		(width 0.18288)
		(layer "In11.Cu")
		(net "M_D_CPU1_SB_DQS_DN<8>")
	)
	(segment
		(start 23.992586 -198.553324)
		(end 22.627844 -199.918066)
		(width 0.18288)
		(layer "In11.Cu")
		(net "M_D_CPU1_SB_DQS_DN<8>")
	)
	(segment
		(start 28.891738 -197.714108)
		(end 28.232354 -197.714108)
		(width 0.18288)
		(layer "In11.Cu")
		(net "M_D_CPU1_SB_DQS_DN<8>")
	)
	(segment
		(start 97.918016 -229.28834)
		(end 97.918016 -229.272846)
		(width 0.088646)
		(layer "In11.Cu")
		(net "M_D_CPU1_SB_DQS_DN<8>")
	)
	(segment
		(start 24.546052 -198.553324)
		(end 23.992586 -198.553324)
		(width 0.18288)
		(layer "In11.Cu")
		(net "M_D_CPU1_SB_DQS_DN<8>")
	)
	(segment
		(start 29.304996 -198.127366)
		(end 28.891738 -197.714108)
		(width 0.18288)
		(layer "In11.Cu")
		(net "M_D_CPU1_SB_DQS_DN<8>")
	)
	(segment
		(start 34.956242 -198.34733)
		(end 34.505646 -197.896734)
		(width 0.18288)
		(layer "In11.Cu")
		(net "M_D_CPU1_SB_DQS_DN<8>")
	)
	(segment
		(start 50.822098 -198.592948)
		(end 50.600356 -198.371206)
		(width 0.18288)
		(layer "In11.Cu")
		(net "M_D_CPU1_SB_DQS_DN<8>")
	)
	(segment
		(start 88.347296 -227.329238)
		(end 88.332564 -227.320602)
		(width 0.088646)
		(layer "In11.Cu")
		(net "M_D_CPU1_SB_DQS_DN<8>")
	)
	(segment
		(start 21.613368 -199.608694)
		(end 21.147278 -199.608694)
		(width 0.18288)
		(layer "In11.Cu")
		(net "M_D_CPU1_SB_DQS_DN<8>")
	)
	(segment
		(start 21.92274 -199.918066)
		(end 21.613368 -199.608694)
		(width 0.18288)
		(layer "In11.Cu")
		(net "M_D_CPU1_SB_DQS_DN<8>")
	)
	(segment
		(start 32.39008 -197.454012)
		(end 32.099504 -197.744588)
		(width 0.18288)
		(layer "In11.Cu")
		(net "M_D_CPU1_SB_DQS_DN<8>")
	)
	(segment
		(start 100.20554 -230.086662)
		(end 100.26269 -230.029512)
		(width 0.088646)
		(layer "In11.Cu")
		(net "M_D_CPU1_SB_DQS_DN<8>")
	)
	(segment
		(start 97.739454 -228.953568)
		(end 97.731326 -228.948996)
		(width 0.088646)
		(layer "In11.Cu")
		(net "M_D_CPU1_SB_DQS_DN<8>")
	)
	(segment
		(start 99.705414 -229.762304)
		(end 99.690682 -229.77094)
		(width 0.088646)
		(layer "In11.Cu")
		(net "M_D_CPU1_SB_DQS_DN<8>")
	)
	(segment
		(start 75.236832 -216.403682)
		(end 75.236832 -212.57006)
		(width 0.18288)
		(layer "In11.Cu")
		(net "M_D_CPU1_SB_DQS_DN<8>")
	)
	(segment
		(start 97.731326 -228.948996)
		(end 97.730564 -228.948488)
		(width 0.088646)
		(layer "In11.Cu")
		(net "M_D_CPU1_SB_DQS_DN<8>")
	)
	(segment
		(start 59.097926 -197.68312)
		(end 55.603648 -197.68312)
		(width 0.18288)
		(layer "In11.Cu")
		(net "M_D_CPU1_SB_DQS_DN<8>")
	)
	(segment
		(start 47.456598 -197.462394)
		(end 47.174404 -197.744588)
		(width 0.18288)
		(layer "In11.Cu")
		(net "M_D_CPU1_SB_DQS_DN<8>")
	)
	(segment
		(start 96.805496 -227.329238)
		(end 96.790764 -227.320602)
		(width 0.088646)
		(layer "In11.Cu")
		(net "M_D_CPU1_SB_DQS_DN<8>")
	)
	(segment
		(start 59.800236 -198.38543)
		(end 59.097926 -197.68312)
		(width 0.18288)
		(layer "In11.Cu")
		(net "M_D_CPU1_SB_DQS_DN<8>")
	)
	(segment
		(start 33.437322 -197.454012)
		(end 32.39008 -197.454012)
		(width 0.18288)
		(layer "In11.Cu")
		(net "M_D_CPU1_SB_DQS_DN<8>")
	)
	(segment
		(start 25.661112 -198.952612)
		(end 25.053798 -198.734934)
		(width 0.18288)
		(layer "In11.Cu")
		(net "M_D_CPU1_SB_DQS_DN<8>")
	)
	(segment
		(start 89.287096 -227.329238)
		(end 89.272364 -227.320602)
		(width 0.088646)
		(layer "In11.Cu")
		(net "M_D_CPU1_SB_DQS_DN<8>")
	)
	(segment
		(start 45.934884 -197.475602)
		(end 45.28312 -198.127366)
		(width 0.18288)
		(layer "In11.Cu")
		(net "M_D_CPU1_SB_DQS_DN<8>")
	)
	(segment
		(start 87.018114 -225.69297)
		(end 87.0077 -225.699066)
		(width 0.088646)
		(layer "In11.Cu")
		(net "M_D_CPU1_SB_DQS_DN<8>")
	)
	(segment
		(start 36.478464 -198.315834)
		(end 36.203382 -198.590916)
		(width 0.18288)
		(layer "In11.Cu")
		(net "M_D_CPU1_SB_DQS_DN<8>")
	)
	(segment
		(start 97.739454 -227.325682)
		(end 97.735644 -227.323396)
		(width 0.088646)
		(layer "In11.Cu")
		(net "M_D_CPU1_SB_DQS_DN<8>")
	)
	(segment
		(start 46.713648 -197.744588)
		(end 46.444662 -197.475602)
		(width 0.18288)
		(layer "In11.Cu")
		(net "M_D_CPU1_SB_DQS_DN<8>")
	)
	(segment
		(start 98.765614 -229.762304)
		(end 98.750882 -229.77094)
		(width 0.088646)
		(layer "In11.Cu")
		(net "M_D_CPU1_SB_DQS_DN<8>")
	)
	(segment
		(start 32.099504 -197.744588)
		(end 31.618428 -197.744588)
		(width 0.18288)
		(layer "In11.Cu")
		(net "M_D_CPU1_SB_DQS_DN<8>")
	)
	(segment
		(start 87.862664 -226.506786)
		(end 87.850472 -226.499674)
		(width 0.088646)
		(layer "In11.Cu")
		(net "M_D_CPU1_SB_DQS_DN<8>")
	)
	(segment
		(start 22.627844 -199.918066)
		(end 21.92274 -199.918066)
		(width 0.18288)
		(layer "In11.Cu")
		(net "M_D_CPU1_SB_DQS_DN<8>")
	)
	(segment
		(start 51.28641 -198.592948)
		(end 50.822098 -198.592948)
		(width 0.18288)
		(layer "In11.Cu")
		(net "M_D_CPU1_SB_DQS_DN<8>")
	)
	(segment
		(start 65.4558 -202.789028)
		(end 65.455292 -202.788266)
		(width 0.18288)
		(layer "In11.Cu")
		(net "M_D_CPU1_SB_DQS_DN<8>")
	)
	(segment
		(start 72.768968 -210.278218)
		(end 72.380856 -209.890106)
		(width 0.18288)
		(layer "In11.Cu")
		(net "M_D_CPU1_SB_DQS_DN<8>")
	)
	(segment
		(start 72.94499 -210.278218)
		(end 72.768968 -210.278218)
		(width 0.18288)
		(layer "In11.Cu")
		(net "M_D_CPU1_SB_DQS_DN<8>")
	)
	(segment
		(start 55.603648 -197.68312)
		(end 54.97068 -198.316088)
		(width 0.18288)
		(layer "In11.Cu")
		(net "M_D_CPU1_SB_DQS_DN<8>")
	)
	(segment
		(start 71.992998 -209.326226)
		(end 71.816976 -209.326226)
		(width 0.18288)
		(layer "In11.Cu")
		(net "M_D_CPU1_SB_DQS_DN<8>")
	)
	(segment
		(start 35.527996 -198.34733)
		(end 34.956242 -198.34733)
		(width 0.18288)
		(layer "In11.Cu")
		(net "M_D_CPU1_SB_DQS_DN<8>")
	)
	(segment
		(start 100.0887 -229.767384)
		(end 100.07981 -229.762304)
		(width 0.088646)
		(layer "In11.Cu")
		(net "M_D_CPU1_SB_DQS_DN<8>")
	)
	(segment
		(start 88.332564 -227.320602)
		(end 88.326468 -227.317046)
		(width 0.088646)
		(layer "In11.Cu")
		(net "M_D_CPU1_SB_DQS_DN<8>")
	)
	(segment
		(start 90.226896 -227.329238)
		(end 90.212164 -227.320602)
		(width 0.088646)
		(layer "In11.Cu")
		(net "M_D_CPU1_SB_DQS_DN<8>")
	)
	(segment
		(start 49.839372 -198.371206)
		(end 48.93056 -197.462394)
		(width 0.18288)
		(layer "In11.Cu")
		(net "M_D_CPU1_SB_DQS_DN<8>")
	)
	(segment
		(start 26.775156 -198.952612)
		(end 25.661112 -198.952612)
		(width 0.18288)
		(layer "In11.Cu")
		(net "M_D_CPU1_SB_DQS_DN<8>")
	)
	(segment
		(start 84.856066 -225.768662)
		(end 84.36229 -225.768662)
		(width 0.088646)
		(layer "In11.Cu")
		(net "M_D_CPU1_SB_DQS_DN<8>")
	)
	(segment
		(start 50.600356 -198.371206)
		(end 49.839372 -198.371206)
		(width 0.18288)
		(layer "In11.Cu")
		(net "M_D_CPU1_SB_DQS_DN<8>")
	)
	(segment
		(start 74.672952 -212.182202)
		(end 74.28484 -211.79409)
		(width 0.18288)
		(layer "In11.Cu")
		(net "M_D_CPU1_SB_DQS_DN<8>")
	)
	(segment
		(start 73.72096 -211.23021)
		(end 73.332848 -210.842098)
		(width 0.18288)
		(layer "In11.Cu")
		(net "M_D_CPU1_SB_DQS_DN<8>")
	)
	(segment
		(start 64.548004 -200.391776)
		(end 62.541912 -198.38543)
		(width 0.18288)
		(layer "In11.Cu")
		(net "M_D_CPU1_SB_DQS_DN<8>")
	)
	(segment
		(start 43.768518 -197.604634)
		(end 41.204642 -197.604634)
		(width 0.18288)
		(layer "In11.Cu")
		(net "M_D_CPU1_SB_DQS_DN<8>")
	)
	(segment
		(start 87.4014 -225.69805)
		(end 87.39251 -225.69297)
		(width 0.088646)
		(layer "In11.Cu")
		(net "M_D_CPU1_SB_DQS_DN<8>")
	)
	(segment
		(start 97.735644 -227.323396)
		(end 97.733612 -227.322126)
		(width 0.088646)
		(layer "In11.Cu")
		(net "M_D_CPU1_SB_DQS_DN<8>")
	)
	(segment
		(start 94.925896 -227.329238)
		(end 94.911164 -227.320602)
		(width 0.088646)
		(layer "In11.Cu")
		(net "M_D_CPU1_SB_DQS_DN<8>")
	)
	(segment
		(start 27.603196 -198.124826)
		(end 26.775156 -198.952612)
		(width 0.18288)
		(layer "In11.Cu")
		(net "M_D_CPU1_SB_DQS_DN<8>")
	)
	(segment
		(start 31.38424 -197.5104)
		(end 30.761686 -197.5104)
		(width 0.18288)
		(layer "In11.Cu")
		(net "M_D_CPU1_SB_DQS_DN<8>")
	)
	(segment
		(start 74.28484 -211.79409)
		(end 74.28484 -211.618068)
		(width 0.18288)
		(layer "In11.Cu")
		(net "M_D_CPU1_SB_DQS_DN<8>")
	)
	(segment
		(start 30.761686 -197.5104)
		(end 30.14472 -198.127366)
		(width 0.18288)
		(layer "In11.Cu")
		(net "M_D_CPU1_SB_DQS_DN<8>")
	)
	(segment
		(start 25.053544 -198.735188)
		(end 24.546052 -198.553324)
		(width 0.18288)
		(layer "In11.Cu")
		(net "M_D_CPU1_SB_DQS_DN<8>")
	)
	(segment
		(start 34.505646 -197.896734)
		(end 33.437322 -197.454012)
		(width 0.18288)
		(layer "In11.Cu")
		(net "M_D_CPU1_SB_DQS_DN<8>")
	)
	(segment
		(start 97.733612 -227.322126)
		(end 97.730564 -227.320602)
		(width 0.088646)
		(layer "In11.Cu")
		(net "M_D_CPU1_SB_DQS_DN<8>")
	)
	(segment
		(start 97.730564 -228.948488)
		(end 97.726754 -228.946202)
		(width 0.088646)
		(layer "In11.Cu")
		(net "M_D_CPU1_SB_DQS_DN<8>")
	)
	(segment
		(start 44.29125 -198.127366)
		(end 43.768518 -197.604634)
		(width 0.18288)
		(layer "In11.Cu")
		(net "M_D_CPU1_SB_DQS_DN<8>")
	)
	(segment
		(start 82.427318 -223.594168)
		(end 75.236832 -216.403682)
		(width 0.18288)
		(layer "In11.Cu")
		(net "M_D_CPU1_SB_DQS_DN<8>")
	)
	(segment
		(start 30.14472 -198.127366)
		(end 29.304996 -198.127366)
		(width 0.18288)
		(layer "In11.Cu")
		(net "M_D_CPU1_SB_DQS_DN<8>")
	)
	(segment
		(start 88.049862 -226.831144)
		(end 88.049862 -226.822508)
		(width 0.088646)
		(layer "In11.Cu")
		(net "M_D_CPU1_SB_DQS_DN<8>")
	)
	(segment
		(start 97.730564 -227.969318)
		(end 97.739454 -227.964238)
		(width 0.088646)
		(layer "In11.Cu")
		(net "M_D_CPU1_SB_DQS_DN<8>")
	)
	(segment
		(start 91.717114 -227.320602)
		(end 91.7067 -227.326698)
		(width 0.088646)
		(layer "In11.Cu")
		(net "M_D_CPU1_SB_DQS_DN<8>")
	)
	(segment
		(start 92.101924 -227.326698)
		(end 92.09151 -227.320602)
		(width 0.088646)
		(layer "In11.Cu")
		(net "M_D_CPU1_SB_DQS_DN<8>")
	)
	(segment
		(start 25.053798 -198.734934)
		(end 25.053544 -198.735188)
		(width 0.18288)
		(layer "In11.Cu")
		(net "M_D_CPU1_SB_DQS_DN<8>")
	)
	(segment
		(start 73.332848 -210.842098)
		(end 73.332848 -210.666076)
		(width 0.18288)
		(layer "In11.Cu")
		(net "M_D_CPU1_SB_DQS_DN<8>")
	)
	(segment
		(start 74.848974 -212.182202)
		(end 74.672952 -212.182202)
		(width 0.18288)
		(layer "In11.Cu")
		(net "M_D_CPU1_SB_DQS_DN<8>")
	)
	(segment
		(start 65.455292 -202.788266)
		(end 64.548004 -200.391776)
		(width 0.18288)
		(layer "In11.Cu")
		(net "M_D_CPU1_SB_DQS_DN<8>")
	)
	(segment
		(start 46.444662 -197.475602)
		(end 45.934884 -197.475602)
		(width 0.18288)
		(layer "In11.Cu")
		(net "M_D_CPU1_SB_DQS_DN<8>")
	)
	(segment
		(start 86.078568 -225.69297)
		(end 86.068154 -225.699066)
		(width 0.088646)
		(layer "In11.Cu")
		(net "M_D_CPU1_SB_DQS_DN<8>")
	)
	(segment
		(start 27.969972 -197.880478)
		(end 27.603196 -198.124826)
		(width 0.18288)
		(layer "In11.Cu")
		(net "M_D_CPU1_SB_DQS_DN<8>")
	)
	(segment
		(start 41.204642 -197.604634)
		(end 40.493442 -198.315834)
		(width 0.18288)
		(layer "In11.Cu")
		(net "M_D_CPU1_SB_DQS_DN<8>")
	)
	(segment
		(start 72.380856 -209.714084)
		(end 71.992998 -209.326226)
		(width 0.18288)
		(layer "In11.Cu")
		(net "M_D_CPU1_SB_DQS_DN<8>")
	)
	(segment
		(start 84.36229 -225.768662)
		(end 83.933538 -225.33991)
		(width 0.088646)
		(layer "In11.Cu")
		(net "M_D_CPU1_SB_DQS_DN<8>")
	)
	(segment
		(start 73.332848 -210.666076)
		(end 72.94499 -210.278218)
		(width 0.18288)
		(layer "In11.Cu")
		(net "M_D_CPU1_SB_DQS_DN<8>")
	)
	(segment
		(start 93.046296 -227.329238)
		(end 93.031564 -227.320602)
		(width 0.088646)
		(layer "In11.Cu")
		(net "M_D_CPU1_SB_DQS_DN<8>")
	)
	(segment
		(start 51.56327 -198.316088)
		(end 51.28641 -198.592948)
		(width 0.18288)
		(layer "In11.Cu")
		(net "M_D_CPU1_SB_DQS_DN<8>")
	)
	(segment
		(start 83.933538 -225.33991)
		(end 83.933538 -225.015552)
		(width 0.088646)
		(layer "In11.Cu")
		(net "M_D_CPU1_SB_DQS_DN<8>")
	)
	(segment
		(start 36.203382 -198.590916)
		(end 35.771582 -198.590916)
		(width 0.18288)
		(layer "In11.Cu")
		(net "M_D_CPU1_SB_DQS_DN<8>")
	)
	(segment
		(start 72.380856 -209.890106)
		(end 72.380856 -209.714084)
		(width 0.18288)
		(layer "In11.Cu")
		(net "M_D_CPU1_SB_DQS_DN<8>")
	)
	(arc
		(start 88.049862 -226.822508)
		(mid 87.997592 -226.640143)
		(end 87.862664 -226.506786)
		(width 0.088646)
		(layer "In11.Cu")
		(net "M_D_CPU1_SB_DQS_DN<8>")
	)
	(arc
		(start 89.272364 -227.320602)
		(mid 89.085166 -227.270459)
		(end 88.897968 -227.320602)
		(width 0.088646)
		(layer "In11.Cu")
		(net "M_D_CPU1_SB_DQS_DN<8>")
	)
	(arc
		(start 93.596968 -227.320602)
		(mid 93.322769 -227.396437)
		(end 93.046296 -227.329238)
		(width 0.088646)
		(layer "In11.Cu")
		(net "M_D_CPU1_SB_DQS_DN<8>")
	)
	(arc
		(start 94.536768 -227.320602)
		(mid 94.262569 -227.396437)
		(end 93.986096 -227.329238)
		(width 0.088646)
		(layer "In11.Cu")
		(net "M_D_CPU1_SB_DQS_DN<8>")
	)
	(arc
		(start 97.918016 -229.272846)
		(mid 97.870337 -229.089946)
		(end 97.739454 -228.953568)
		(width 0.088646)
		(layer "In11.Cu")
		(net "M_D_CPU1_SB_DQS_DN<8>")
	)
	(arc
		(start 91.151964 -227.320602)
		(mid 90.964766 -227.270459)
		(end 90.777568 -227.320602)
		(width 0.088646)
		(layer "In11.Cu")
		(net "M_D_CPU1_SB_DQS_DN<8>")
	)
	(arc
		(start 85.138514 -225.69297)
		(mid 85.002271 -225.749416)
		(end 84.856066 -225.768662)
		(width 0.088646)
		(layer "In11.Cu")
		(net "M_D_CPU1_SB_DQS_DN<8>")
	)
	(arc
		(start 92.657168 -227.320602)
		(mid 92.380355 -227.396472)
		(end 92.101924 -227.326698)
		(width 0.088646)
		(layer "In11.Cu")
		(net "M_D_CPU1_SB_DQS_DN<8>")
	)
	(arc
		(start 100.07981 -229.762304)
		(mid 99.892612 -229.712161)
		(end 99.705414 -229.762304)
		(width 0.088646)
		(layer "In11.Cu")
		(net "M_D_CPU1_SB_DQS_DN<8>")
	)
	(arc
		(start 96.790764 -227.320602)
		(mid 96.603566 -227.270459)
		(end 96.416368 -227.320602)
		(width 0.088646)
		(layer "In11.Cu")
		(net "M_D_CPU1_SB_DQS_DN<8>")
	)
	(arc
		(start 97.356168 -227.320602)
		(mid 97.081969 -227.396437)
		(end 96.805496 -227.329238)
		(width 0.088646)
		(layer "In11.Cu")
		(net "M_D_CPU1_SB_DQS_DN<8>")
	)
	(arc
		(start 95.476568 -227.320602)
		(mid 95.202369 -227.396437)
		(end 94.925896 -227.329238)
		(width 0.088646)
		(layer "In11.Cu")
		(net "M_D_CPU1_SB_DQS_DN<8>")
	)
	(arc
		(start 95.850964 -227.320602)
		(mid 95.663766 -227.270459)
		(end 95.476568 -227.320602)
		(width 0.088646)
		(layer "In11.Cu")
		(net "M_D_CPU1_SB_DQS_DN<8>")
	)
	(arc
		(start 87.579962 -226.017328)
		(mid 87.532283 -225.834428)
		(end 87.4014 -225.69805)
		(width 0.088646)
		(layer "In11.Cu")
		(net "M_D_CPU1_SB_DQS_DN<8>")
	)
	(arc
		(start 90.777568 -227.320602)
		(mid 90.503369 -227.396437)
		(end 90.226896 -227.329238)
		(width 0.088646)
		(layer "In11.Cu")
		(net "M_D_CPU1_SB_DQS_DN<8>")
	)
	(arc
		(start 93.971364 -227.320602)
		(mid 93.784166 -227.270459)
		(end 93.596968 -227.320602)
		(width 0.088646)
		(layer "In11.Cu")
		(net "M_D_CPU1_SB_DQS_DN<8>")
	)
	(arc
		(start 92.09151 -227.320602)
		(mid 91.904312 -227.270459)
		(end 91.717114 -227.320602)
		(width 0.088646)
		(layer "In11.Cu")
		(net "M_D_CPU1_SB_DQS_DN<8>")
	)
	(arc
		(start 96.416368 -227.320602)
		(mid 96.133666 -227.396378)
		(end 95.850964 -227.320602)
		(width 0.088646)
		(layer "In11.Cu")
		(net "M_D_CPU1_SB_DQS_DN<8>")
	)
	(arc
		(start 97.718372 -228.941376)
		(mid 97.520144 -228.735528)
		(end 97.447862 -228.45903)
		(width 0.088646)
		(layer "In11.Cu")
		(net "M_D_CPU1_SB_DQS_DN<8>")
	)
	(arc
		(start 93.031564 -227.320602)
		(mid 92.844366 -227.270459)
		(end 92.657168 -227.320602)
		(width 0.088646)
		(layer "In11.Cu")
		(net "M_D_CPU1_SB_DQS_DN<8>")
	)
	(arc
		(start 94.911164 -227.320602)
		(mid 94.723966 -227.270459)
		(end 94.536768 -227.320602)
		(width 0.088646)
		(layer "In11.Cu")
		(net "M_D_CPU1_SB_DQS_DN<8>")
	)
	(arc
		(start 86.068154 -225.699066)
		(mid 85.789722 -225.76888)
		(end 85.51291 -225.69297)
		(width 0.088646)
		(layer "In11.Cu")
		(net "M_D_CPU1_SB_DQS_DN<8>")
	)
	(arc
		(start 98.20021 -229.762304)
		(mid 97.997387 -229.562073)
		(end 97.918016 -229.28834)
		(width 0.088646)
		(layer "In11.Cu")
		(net "M_D_CPU1_SB_DQS_DN<8>")
	)
	(arc
		(start 87.850472 -226.499674)
		(mid 87.652244 -226.293826)
		(end 87.579962 -226.017328)
		(width 0.088646)
		(layer "In11.Cu")
		(net "M_D_CPU1_SB_DQS_DN<8>")
	)
	(arc
		(start 97.730564 -227.320602)
		(mid 97.543366 -227.270459)
		(end 97.356168 -227.320602)
		(width 0.088646)
		(layer "In11.Cu")
		(net "M_D_CPU1_SB_DQS_DN<8>")
	)
	(arc
		(start 86.452964 -225.69297)
		(mid 86.265766 -225.642827)
		(end 86.078568 -225.69297)
		(width 0.088646)
		(layer "In11.Cu")
		(net "M_D_CPU1_SB_DQS_DN<8>")
	)
	(arc
		(start 87.39251 -225.69297)
		(mid 87.205312 -225.642827)
		(end 87.018114 -225.69297)
		(width 0.088646)
		(layer "In11.Cu")
		(net "M_D_CPU1_SB_DQS_DN<8>")
	)
	(arc
		(start 97.447862 -228.45141)
		(mid 97.525491 -228.172997)
		(end 97.730564 -227.969318)
		(width 0.088646)
		(layer "In11.Cu")
		(net "M_D_CPU1_SB_DQS_DN<8>")
	)
	(arc
		(start 99.14001 -229.762304)
		(mid 98.952812 -229.712161)
		(end 98.765614 -229.762304)
		(width 0.088646)
		(layer "In11.Cu")
		(net "M_D_CPU1_SB_DQS_DN<8>")
	)
	(arc
		(start 99.690682 -229.77094)
		(mid 99.414207 -229.83826)
		(end 99.14001 -229.762304)
		(width 0.088646)
		(layer "In11.Cu")
		(net "M_D_CPU1_SB_DQS_DN<8>")
	)
	(arc
		(start 89.837768 -227.320602)
		(mid 89.563569 -227.396437)
		(end 89.287096 -227.329238)
		(width 0.088646)
		(layer "In11.Cu")
		(net "M_D_CPU1_SB_DQS_DN<8>")
	)
	(arc
		(start 90.212164 -227.320602)
		(mid 90.024966 -227.270459)
		(end 89.837768 -227.320602)
		(width 0.088646)
		(layer "In11.Cu")
		(net "M_D_CPU1_SB_DQS_DN<8>")
	)
	(arc
		(start 85.51291 -225.69297)
		(mid 85.325712 -225.642827)
		(end 85.138514 -225.69297)
		(width 0.088646)
		(layer "In11.Cu")
		(net "M_D_CPU1_SB_DQS_DN<8>")
	)
	(arc
		(start 100.26269 -230.029512)
		(mid 100.204571 -229.879271)
		(end 100.0887 -229.767384)
		(width 0.088646)
		(layer "In11.Cu")
		(net "M_D_CPU1_SB_DQS_DN<8>")
	)
	(arc
		(start 88.326468 -227.317046)
		(mid 88.123881 -227.110695)
		(end 88.049862 -226.831144)
		(width 0.088646)
		(layer "In11.Cu")
		(net "M_D_CPU1_SB_DQS_DN<8>")
	)
	(arc
		(start 88.897968 -227.320602)
		(mid 88.623769 -227.396437)
		(end 88.347296 -227.329238)
		(width 0.088646)
		(layer "In11.Cu")
		(net "M_D_CPU1_SB_DQS_DN<8>")
	)
	(arc
		(start 97.739454 -227.964238)
		(mid 97.91793 -227.64496)
		(end 97.739454 -227.325682)
		(width 0.088646)
		(layer "In11.Cu")
		(net "M_D_CPU1_SB_DQS_DN<8>")
	)
	(arc
		(start 98.750882 -229.77094)
		(mid 98.474407 -229.83826)
		(end 98.20021 -229.762304)
		(width 0.088646)
		(layer "In11.Cu")
		(net "M_D_CPU1_SB_DQS_DN<8>")
	)
	(arc
		(start 91.7067 -227.326698)
		(mid 91.428522 -227.396421)
		(end 91.151964 -227.320602)
		(width 0.088646)
		(layer "In11.Cu")
		(net "M_D_CPU1_SB_DQS_DN<8>")
	)
	(arc
		(start 87.0077 -225.699066)
		(mid 86.729522 -225.768758)
		(end 86.452964 -225.69297)
		(width 0.088646)
		(layer "In11.Cu")
		(net "M_D_CPU1_SB_DQS_DN<8>")
	)
	(segment
		(start 14.108684 -208.533238)
		(end 13.868908 -208.533238)
		(width 0.20066)
		(layer "F.Cu")
		(net "M_D_CPU1_SB_DQS_DN<7>")
	)
	(segment
		(start 12.712192 -209.216752)
		(end 12.240514 -209.216752)
		(width 0.20066)
		(layer "F.Cu")
		(net "M_D_CPU1_SB_DQS_DN<7>")
	)
	(segment
		(start 96.603566 -233.06405)
		(end 96.603566 -232.528364)
		(width 0.20066)
		(layer "F.Cu")
		(net "M_D_CPU1_SB_DQS_DN<7>")
	)
	(segment
		(start 19.784314 -209.216752)
		(end 19.29384 -209.216752)
		(width 0.20066)
		(layer "F.Cu")
		(net "M_D_CPU1_SB_DQS_DN<7>")
	)
	(segment
		(start 17.027398 -208.79181)
		(end 16.885158 -208.79181)
		(width 0.20066)
		(layer "F.Cu")
		(net "M_D_CPU1_SB_DQS_DN<7>")
	)
	(segment
		(start 19.29384 -209.216752)
		(end 19.032728 -208.95564)
		(width 0.20066)
		(layer "F.Cu")
		(net "M_D_CPU1_SB_DQS_DN<7>")
	)
	(segment
		(start 16.885158 -208.79181)
		(end 14.807692 -208.79181)
		(width 0.1016)
		(layer "F.Cu")
		(net "M_D_CPU1_SB_DQS_DN<7>")
	)
	(segment
		(start 12.973304 -208.95564)
		(end 12.712192 -209.216752)
		(width 0.20066)
		(layer "F.Cu")
		(net "M_D_CPU1_SB_DQS_DN<7>")
	)
	(segment
		(start 19.032728 -208.95564)
		(end 18.329148 -208.95564)
		(width 0.20066)
		(layer "F.Cu")
		(net "M_D_CPU1_SB_DQS_DN<7>")
	)
	(segment
		(start 18.329148 -208.95564)
		(end 17.693132 -208.530698)
		(width 0.20066)
		(layer "F.Cu")
		(net "M_D_CPU1_SB_DQS_DN<7>")
	)
	(segment
		(start 17.28851 -208.530698)
		(end 17.027398 -208.79181)
		(width 0.20066)
		(layer "F.Cu")
		(net "M_D_CPU1_SB_DQS_DN<7>")
	)
	(segment
		(start 20.889214 -209.216752)
		(end 19.784314 -209.216752)
		(width 0.20066)
		(layer "F.Cu")
		(net "M_D_CPU1_SB_DQS_DN<7>")
	)
	(segment
		(start 14.567916 -208.79181)
		(end 14.560042 -208.799684)
		(width 0.101854)
		(layer "F.Cu")
		(net "M_D_CPU1_SB_DQS_DN<7>")
	)
	(segment
		(start 96.603312 -233.064304)
		(end 96.603566 -233.06405)
		(width 0.20066)
		(layer "F.Cu")
		(net "M_D_CPU1_SB_DQS_DN<7>")
	)
	(segment
		(start 14.37513 -208.799684)
		(end 14.108684 -208.533238)
		(width 0.20066)
		(layer "F.Cu")
		(net "M_D_CPU1_SB_DQS_DN<7>")
	)
	(segment
		(start 13.446506 -208.95564)
		(end 12.973304 -208.95564)
		(width 0.20066)
		(layer "F.Cu")
		(net "M_D_CPU1_SB_DQS_DN<7>")
	)
	(segment
		(start 13.868908 -208.533238)
		(end 13.446506 -208.95564)
		(width 0.20066)
		(layer "F.Cu")
		(net "M_D_CPU1_SB_DQS_DN<7>")
	)
	(segment
		(start 14.560042 -208.799684)
		(end 14.37513 -208.799684)
		(width 0.20066)
		(layer "F.Cu")
		(net "M_D_CPU1_SB_DQS_DN<7>")
	)
	(segment
		(start 17.693132 -208.530698)
		(end 17.28851 -208.530698)
		(width 0.20066)
		(layer "F.Cu")
		(net "M_D_CPU1_SB_DQS_DN<7>")
	)
	(segment
		(start 14.807692 -208.79181)
		(end 14.567916 -208.79181)
		(width 0.101854)
		(layer "F.Cu")
		(net "M_D_CPU1_SB_DQS_DN<7>")
	)
	(segment
		(start 85.700616 -230.910638)
		(end 85.700616 -230.900732)
		(width 0.088646)
		(layer "In6.Cu")
		(net "M_D_CPU1_SB_DQS_DN<7>")
	)
	(segment
		(start 84.234782 -230.525574)
		(end 83.403948 -229.69474)
		(width 0.088646)
		(layer "In6.Cu")
		(net "M_D_CPU1_SB_DQS_DN<7>")
	)
	(segment
		(start 51.560984 -207.662018)
		(end 51.28133 -207.941672)
		(width 0.18288)
		(layer "In6.Cu")
		(net "M_D_CPU1_SB_DQS_DN<7>")
	)
	(segment
		(start 45.292264 -207.93837)
		(end 44.452794 -207.93837)
		(width 0.18288)
		(layer "In6.Cu")
		(net "M_D_CPU1_SB_DQS_DN<7>")
	)
	(segment
		(start 30.95752 -208.501996)
		(end 30.243272 -209.216244)
		(width 0.18288)
		(layer "In6.Cu")
		(net "M_D_CPU1_SB_DQS_DN<7>")
	)
	(segment
		(start 45.85589 -208.501996)
		(end 45.292264 -207.93837)
		(width 0.18288)
		(layer "In6.Cu")
		(net "M_D_CPU1_SB_DQS_DN<7>")
	)
	(segment
		(start 44.452794 -207.93837)
		(end 44.032932 -208.358232)
		(width 0.18288)
		(layer "In6.Cu")
		(net "M_D_CPU1_SB_DQS_DN<7>")
	)
	(segment
		(start 84.385912 -230.525574)
		(end 84.234782 -230.525574)
		(width 0.088646)
		(layer "In6.Cu")
		(net "M_D_CPU1_SB_DQS_DN<7>")
	)
	(segment
		(start 88.427814 -231.39019)
		(end 88.4174 -231.396286)
		(width 0.088646)
		(layer "In6.Cu")
		(net "M_D_CPU1_SB_DQS_DN<7>")
	)
	(segment
		(start 82.7151 -228.597714)
		(end 82.65541 -228.657404)
		(width 0.088646)
		(layer "In6.Cu")
		(net "M_D_CPU1_SB_DQS_DN<7>")
	)
	(segment
		(start 85.138768 -230.576374)
		(end 85.128354 -230.58247)
		(width 0.088646)
		(layer "In6.Cu")
		(net "M_D_CPU1_SB_DQS_DN<7>")
	)
	(segment
		(start 36.475162 -207.66024)
		(end 36.19373 -207.941672)
		(width 0.18288)
		(layer "In6.Cu")
		(net "M_D_CPU1_SB_DQS_DN<7>")
	)
	(segment
		(start 77.930756 -228.657404)
		(end 74.621136 -225.347784)
		(width 0.18288)
		(layer "In6.Cu")
		(net "M_D_CPU1_SB_DQS_DN<7>")
	)
	(segment
		(start 21.16328 -208.942686)
		(end 20.889214 -209.216752)
		(width 0.18288)
		(layer "In6.Cu")
		(net "M_D_CPU1_SB_DQS_DN<7>")
	)
	(segment
		(start 93.046296 -232.212642)
		(end 93.031564 -232.204006)
		(width 0.088646)
		(layer "In6.Cu")
		(net "M_D_CPU1_SB_DQS_DN<7>")
	)
	(segment
		(start 35.778694 -207.941672)
		(end 35.489134 -207.652112)
		(width 0.18288)
		(layer "In6.Cu")
		(net "M_D_CPU1_SB_DQS_DN<7>")
	)
	(segment
		(start 25.565862 -208.35239)
		(end 24.790908 -209.127344)
		(width 0.18288)
		(layer "In6.Cu")
		(net "M_D_CPU1_SB_DQS_DN<7>")
	)
	(segment
		(start 94.925896 -232.212642)
		(end 94.911164 -232.204006)
		(width 0.088646)
		(layer "In6.Cu")
		(net "M_D_CPU1_SB_DQS_DN<7>")
	)
	(segment
		(start 74.621136 -225.347784)
		(end 74.621136 -222.56369)
		(width 0.18288)
		(layer "In6.Cu")
		(net "M_D_CPU1_SB_DQS_DN<7>")
	)
	(segment
		(start 57.982104 -209.636106)
		(end 57.857644 -209.760566)
		(width 0.18288)
		(layer "In6.Cu")
		(net "M_D_CPU1_SB_DQS_DN<7>")
	)
	(segment
		(start 96.603566 -232.528364)
		(end 96.916494 -232.528364)
		(width 0.088646)
		(layer "In6.Cu")
		(net "M_D_CPU1_SB_DQS_DN<7>")
	)
	(segment
		(start 29.694632 -209.216244)
		(end 28.843478 -208.8642)
		(width 0.18288)
		(layer "In6.Cu")
		(net "M_D_CPU1_SB_DQS_DN<7>")
	)
	(segment
		(start 95.865696 -232.212642)
		(end 95.850964 -232.204006)
		(width 0.088646)
		(layer "In6.Cu")
		(net "M_D_CPU1_SB_DQS_DN<7>")
	)
	(segment
		(start 63.42888 -211.04733)
		(end 62.725046 -210.343496)
		(width 0.18288)
		(layer "In6.Cu")
		(net "M_D_CPU1_SB_DQS_DN<7>")
	)
	(segment
		(start 40.552624 -208.358232)
		(end 39.854632 -207.66024)
		(width 0.18288)
		(layer "In6.Cu")
		(net "M_D_CPU1_SB_DQS_DN<7>")
	)
	(segment
		(start 35.489134 -207.652112)
		(end 34.76752 -207.652112)
		(width 0.18288)
		(layer "In6.Cu")
		(net "M_D_CPU1_SB_DQS_DN<7>")
	)
	(segment
		(start 60.73013 -210.467956)
		(end 60.60567 -210.343496)
		(width 0.18288)
		(layer "In6.Cu")
		(net "M_D_CPU1_SB_DQS_DN<7>")
	)
	(segment
		(start 62.725046 -210.343496)
		(end 61.40323 -210.343496)
		(width 0.18288)
		(layer "In6.Cu")
		(net "M_D_CPU1_SB_DQS_DN<7>")
	)
	(segment
		(start 50.270156 -207.664304)
		(end 49.42332 -208.51114)
		(width 0.18288)
		(layer "In6.Cu")
		(net "M_D_CPU1_SB_DQS_DN<7>")
	)
	(segment
		(start 52.540408 -207.662018)
		(end 51.560984 -207.662018)
		(width 0.18288)
		(layer "In6.Cu")
		(net "M_D_CPU1_SB_DQS_DN<7>")
	)
	(segment
		(start 28.331668 -208.35239)
		(end 25.565862 -208.35239)
		(width 0.18288)
		(layer "In6.Cu")
		(net "M_D_CPU1_SB_DQS_DN<7>")
	)
	(segment
		(start 34.76752 -207.652112)
		(end 33.921192 -208.49844)
		(width 0.18288)
		(layer "In6.Cu")
		(net "M_D_CPU1_SB_DQS_DN<7>")
	)
	(segment
		(start 61.40323 -210.343496)
		(end 61.27877 -210.467956)
		(width 0.18288)
		(layer "In6.Cu")
		(net "M_D_CPU1_SB_DQS_DN<7>")
	)
	(segment
		(start 28.843478 -208.8642)
		(end 28.331668 -208.35239)
		(width 0.18288)
		(layer "In6.Cu")
		(net "M_D_CPU1_SB_DQS_DN<7>")
	)
	(segment
		(start 32.093662 -208.791556)
		(end 31.678626 -208.791556)
		(width 0.18288)
		(layer "In6.Cu")
		(net "M_D_CPU1_SB_DQS_DN<7>")
	)
	(segment
		(start 46.476666 -208.501996)
		(end 45.85589 -208.501996)
		(width 0.18288)
		(layer "In6.Cu")
		(net "M_D_CPU1_SB_DQS_DN<7>")
	)
	(segment
		(start 82.65541 -228.657404)
		(end 82.632042 -228.657404)
		(width 0.088646)
		(layer "In6.Cu")
		(net "M_D_CPU1_SB_DQS_DN<7>")
	)
	(segment
		(start 59.108848 -209.636106)
		(end 57.982104 -209.636106)
		(width 0.18288)
		(layer "In6.Cu")
		(net "M_D_CPU1_SB_DQS_DN<7>")
	)
	(segment
		(start 54.514496 -209.636106)
		(end 52.540408 -207.662018)
		(width 0.18288)
		(layer "In6.Cu")
		(net "M_D_CPU1_SB_DQS_DN<7>")
	)
	(segment
		(start 57.309004 -209.760566)
		(end 57.184544 -209.636106)
		(width 0.18288)
		(layer "In6.Cu")
		(net "M_D_CPU1_SB_DQS_DN<7>")
	)
	(segment
		(start 31.389066 -208.501996)
		(end 30.95752 -208.501996)
		(width 0.18288)
		(layer "In6.Cu")
		(net "M_D_CPU1_SB_DQS_DN<7>")
	)
	(segment
		(start 74.621136 -222.56369)
		(end 66.574162 -214.516716)
		(width 0.18288)
		(layer "In6.Cu")
		(net "M_D_CPU1_SB_DQS_DN<7>")
	)
	(segment
		(start 39.854632 -207.66024)
		(end 36.475162 -207.66024)
		(width 0.18288)
		(layer "In6.Cu")
		(net "M_D_CPU1_SB_DQS_DN<7>")
	)
	(segment
		(start 49.42332 -208.51114)
		(end 47.461678 -208.51114)
		(width 0.18288)
		(layer "In6.Cu")
		(net "M_D_CPU1_SB_DQS_DN<7>")
	)
	(segment
		(start 47.461678 -208.51114)
		(end 47.181262 -208.791556)
		(width 0.18288)
		(layer "In6.Cu")
		(net "M_D_CPU1_SB_DQS_DN<7>")
	)
	(segment
		(start 60.60567 -210.343496)
		(end 59.816238 -210.343496)
		(width 0.18288)
		(layer "In6.Cu")
		(net "M_D_CPU1_SB_DQS_DN<7>")
	)
	(segment
		(start 21.619972 -208.942686)
		(end 21.16328 -208.942686)
		(width 0.18288)
		(layer "In6.Cu")
		(net "M_D_CPU1_SB_DQS_DN<7>")
	)
	(segment
		(start 92.101924 -232.210102)
		(end 92.09151 -232.204006)
		(width 0.088646)
		(layer "In6.Cu")
		(net "M_D_CPU1_SB_DQS_DN<7>")
	)
	(segment
		(start 83.403948 -229.69474)
		(end 83.403948 -229.061264)
		(width 0.088646)
		(layer "In6.Cu")
		(net "M_D_CPU1_SB_DQS_DN<7>")
	)
	(segment
		(start 82.940398 -228.597714)
		(end 82.7151 -228.597714)
		(width 0.088646)
		(layer "In6.Cu")
		(net "M_D_CPU1_SB_DQS_DN<7>")
	)
	(segment
		(start 82.632042 -228.657404)
		(end 77.930756 -228.657404)
		(width 0.18288)
		(layer "In6.Cu")
		(net "M_D_CPU1_SB_DQS_DN<7>")
	)
	(segment
		(start 57.857644 -209.760566)
		(end 57.309004 -209.760566)
		(width 0.18288)
		(layer "In6.Cu")
		(net "M_D_CPU1_SB_DQS_DN<7>")
	)
	(segment
		(start 30.243272 -209.216244)
		(end 29.694632 -209.216244)
		(width 0.18288)
		(layer "In6.Cu")
		(net "M_D_CPU1_SB_DQS_DN<7>")
	)
	(segment
		(start 66.165476 -214.516716)
		(end 65.506092 -213.857586)
		(width 0.18288)
		(layer "In6.Cu")
		(net "M_D_CPU1_SB_DQS_DN<7>")
	)
	(segment
		(start 44.032932 -208.358232)
		(end 40.552624 -208.358232)
		(width 0.18288)
		(layer "In6.Cu")
		(net "M_D_CPU1_SB_DQS_DN<7>")
	)
	(segment
		(start 66.574162 -214.516716)
		(end 66.165476 -214.516716)
		(width 0.18288)
		(layer "In6.Cu")
		(net "M_D_CPU1_SB_DQS_DN<7>")
	)
	(segment
		(start 96.916494 -232.528364)
		(end 96.973644 -232.471214)
		(width 0.088646)
		(layer "In6.Cu")
		(net "M_D_CPU1_SB_DQS_DN<7>")
	)
	(segment
		(start 21.80463 -209.127344)
		(end 21.619972 -208.942686)
		(width 0.18288)
		(layer "In6.Cu")
		(net "M_D_CPU1_SB_DQS_DN<7>")
	)
	(segment
		(start 31.678626 -208.791556)
		(end 31.389066 -208.501996)
		(width 0.18288)
		(layer "In6.Cu")
		(net "M_D_CPU1_SB_DQS_DN<7>")
	)
	(segment
		(start 63.926974 -211.04733)
		(end 63.42888 -211.04733)
		(width 0.18288)
		(layer "In6.Cu")
		(net "M_D_CPU1_SB_DQS_DN<7>")
	)
	(segment
		(start 24.790908 -209.127344)
		(end 21.80463 -209.127344)
		(width 0.18288)
		(layer "In6.Cu")
		(net "M_D_CPU1_SB_DQS_DN<7>")
	)
	(segment
		(start 32.386778 -208.49844)
		(end 32.093662 -208.791556)
		(width 0.18288)
		(layer "In6.Cu")
		(net "M_D_CPU1_SB_DQS_DN<7>")
	)
	(segment
		(start 50.580036 -207.664304)
		(end 50.270156 -207.664304)
		(width 0.18288)
		(layer "In6.Cu")
		(net "M_D_CPU1_SB_DQS_DN<7>")
	)
	(segment
		(start 57.184544 -209.636106)
		(end 54.514496 -209.636106)
		(width 0.18288)
		(layer "In6.Cu")
		(net "M_D_CPU1_SB_DQS_DN<7>")
	)
	(segment
		(start 89.367614 -231.39019)
		(end 89.352882 -231.398826)
		(width 0.088646)
		(layer "In6.Cu")
		(net "M_D_CPU1_SB_DQS_DN<7>")
	)
	(segment
		(start 83.403948 -229.061264)
		(end 82.940398 -228.597714)
		(width 0.088646)
		(layer "In6.Cu")
		(net "M_D_CPU1_SB_DQS_DN<7>")
	)
	(segment
		(start 50.857404 -207.941672)
		(end 50.580036 -207.664304)
		(width 0.18288)
		(layer "In6.Cu")
		(net "M_D_CPU1_SB_DQS_DN<7>")
	)
	(segment
		(start 64.635126 -211.755736)
		(end 63.926974 -211.04733)
		(width 0.18288)
		(layer "In6.Cu")
		(net "M_D_CPU1_SB_DQS_DN<7>")
	)
	(segment
		(start 33.921192 -208.49844)
		(end 32.386778 -208.49844)
		(width 0.18288)
		(layer "In6.Cu")
		(net "M_D_CPU1_SB_DQS_DN<7>")
	)
	(segment
		(start 59.816238 -210.343496)
		(end 59.108848 -209.636106)
		(width 0.18288)
		(layer "In6.Cu")
		(net "M_D_CPU1_SB_DQS_DN<7>")
	)
	(segment
		(start 46.766226 -208.791556)
		(end 46.476666 -208.501996)
		(width 0.18288)
		(layer "In6.Cu")
		(net "M_D_CPU1_SB_DQS_DN<7>")
	)
	(segment
		(start 61.27877 -210.467956)
		(end 60.73013 -210.467956)
		(width 0.18288)
		(layer "In6.Cu")
		(net "M_D_CPU1_SB_DQS_DN<7>")
	)
	(segment
		(start 91.162378 -232.210102)
		(end 91.151964 -232.204006)
		(width 0.088646)
		(layer "In6.Cu")
		(net "M_D_CPU1_SB_DQS_DN<7>")
	)
	(segment
		(start 36.19373 -207.941672)
		(end 35.778694 -207.941672)
		(width 0.18288)
		(layer "In6.Cu")
		(net "M_D_CPU1_SB_DQS_DN<7>")
	)
	(segment
		(start 47.181262 -208.791556)
		(end 46.766226 -208.791556)
		(width 0.18288)
		(layer "In6.Cu")
		(net "M_D_CPU1_SB_DQS_DN<7>")
	)
	(segment
		(start 51.28133 -207.941672)
		(end 50.857404 -207.941672)
		(width 0.18288)
		(layer "In6.Cu")
		(net "M_D_CPU1_SB_DQS_DN<7>")
	)
	(segment
		(start 65.506092 -213.857586)
		(end 64.635126 -211.755736)
		(width 0.18288)
		(layer "In6.Cu")
		(net "M_D_CPU1_SB_DQS_DN<7>")
	)
	(arc
		(start 86.548468 -231.39019)
		(mid 85.987492 -231.392721)
		(end 85.700616 -230.910638)
		(width 0.088646)
		(layer "In6.Cu")
		(net "M_D_CPU1_SB_DQS_DN<7>")
	)
	(arc
		(start 93.971364 -232.204006)
		(mid 93.784166 -232.153863)
		(end 93.596968 -232.204006)
		(width 0.088646)
		(layer "In6.Cu")
		(net "M_D_CPU1_SB_DQS_DN<7>")
	)
	(arc
		(start 85.128354 -230.58247)
		(mid 84.849922 -230.652316)
		(end 84.57311 -230.576374)
		(width 0.088646)
		(layer "In6.Cu")
		(net "M_D_CPU1_SB_DQS_DN<7>")
	)
	(arc
		(start 88.80221 -231.39019)
		(mid 88.615012 -231.340047)
		(end 88.427814 -231.39019)
		(width 0.088646)
		(layer "In6.Cu")
		(net "M_D_CPU1_SB_DQS_DN<7>")
	)
	(arc
		(start 92.657168 -232.204006)
		(mid 92.380355 -232.279876)
		(end 92.101924 -232.210102)
		(width 0.088646)
		(layer "In6.Cu")
		(net "M_D_CPU1_SB_DQS_DN<7>")
	)
	(arc
		(start 89.929462 -231.714548)
		(mid 89.92941 -231.707181)
		(end 89.929208 -231.699816)
		(width 0.088646)
		(layer "In6.Cu")
		(net "M_D_CPU1_SB_DQS_DN<7>")
	)
	(arc
		(start 93.031564 -232.204006)
		(mid 92.844366 -232.153863)
		(end 92.657168 -232.204006)
		(width 0.088646)
		(layer "In6.Cu")
		(net "M_D_CPU1_SB_DQS_DN<7>")
	)
	(arc
		(start 86.922864 -231.39019)
		(mid 86.735666 -231.340047)
		(end 86.548468 -231.39019)
		(width 0.088646)
		(layer "In6.Cu")
		(net "M_D_CPU1_SB_DQS_DN<7>")
	)
	(arc
		(start 84.57311 -230.576374)
		(mid 84.482854 -230.538652)
		(end 84.385912 -230.525574)
		(width 0.088646)
		(layer "In6.Cu")
		(net "M_D_CPU1_SB_DQS_DN<7>")
	)
	(arc
		(start 87.488268 -231.39019)
		(mid 87.205566 -231.465966)
		(end 86.922864 -231.39019)
		(width 0.088646)
		(layer "In6.Cu")
		(net "M_D_CPU1_SB_DQS_DN<7>")
	)
	(arc
		(start 92.09151 -232.204006)
		(mid 91.904312 -232.153863)
		(end 91.717114 -232.204006)
		(width 0.088646)
		(layer "In6.Cu")
		(net "M_D_CPU1_SB_DQS_DN<7>")
	)
	(arc
		(start 94.911164 -232.204006)
		(mid 94.723966 -232.153863)
		(end 94.536768 -232.204006)
		(width 0.088646)
		(layer "In6.Cu")
		(net "M_D_CPU1_SB_DQS_DN<7>")
	)
	(arc
		(start 96.973644 -232.471214)
		(mid 96.765496 -232.19051)
		(end 96.416368 -232.204006)
		(width 0.088646)
		(layer "In6.Cu")
		(net "M_D_CPU1_SB_DQS_DN<7>")
	)
	(arc
		(start 85.700616 -230.900732)
		(mid 85.513317 -230.576291)
		(end 85.138768 -230.576374)
		(width 0.088646)
		(layer "In6.Cu")
		(net "M_D_CPU1_SB_DQS_DN<7>")
	)
	(arc
		(start 87.862664 -231.39019)
		(mid 87.675466 -231.340047)
		(end 87.488268 -231.39019)
		(width 0.088646)
		(layer "In6.Cu")
		(net "M_D_CPU1_SB_DQS_DN<7>")
	)
	(arc
		(start 91.151964 -232.204006)
		(mid 90.964766 -232.153863)
		(end 90.777568 -232.204006)
		(width 0.088646)
		(layer "In6.Cu")
		(net "M_D_CPU1_SB_DQS_DN<7>")
	)
	(arc
		(start 90.777568 -232.204006)
		(mid 90.212069 -232.204245)
		(end 89.929462 -231.714548)
		(width 0.088646)
		(layer "In6.Cu")
		(net "M_D_CPU1_SB_DQS_DN<7>")
	)
	(arc
		(start 88.4174 -231.396286)
		(mid 88.139222 -231.465978)
		(end 87.862664 -231.39019)
		(width 0.088646)
		(layer "In6.Cu")
		(net "M_D_CPU1_SB_DQS_DN<7>")
	)
	(arc
		(start 91.717114 -232.204006)
		(mid 91.440555 -232.279749)
		(end 91.162378 -232.210102)
		(width 0.088646)
		(layer "In6.Cu")
		(net "M_D_CPU1_SB_DQS_DN<7>")
	)
	(arc
		(start 96.416368 -232.204006)
		(mid 96.142169 -232.279841)
		(end 95.865696 -232.212642)
		(width 0.088646)
		(layer "In6.Cu")
		(net "M_D_CPU1_SB_DQS_DN<7>")
	)
	(arc
		(start 95.850964 -232.204006)
		(mid 95.663766 -232.153863)
		(end 95.476568 -232.204006)
		(width 0.088646)
		(layer "In6.Cu")
		(net "M_D_CPU1_SB_DQS_DN<7>")
	)
	(arc
		(start 93.596968 -232.204006)
		(mid 93.322769 -232.279841)
		(end 93.046296 -232.212642)
		(width 0.088646)
		(layer "In6.Cu")
		(net "M_D_CPU1_SB_DQS_DN<7>")
	)
	(arc
		(start 89.352882 -231.398826)
		(mid 89.076441 -231.465992)
		(end 88.80221 -231.39019)
		(width 0.088646)
		(layer "In6.Cu")
		(net "M_D_CPU1_SB_DQS_DN<7>")
	)
	(arc
		(start 95.476568 -232.204006)
		(mid 95.202369 -232.279841)
		(end 94.925896 -232.212642)
		(width 0.088646)
		(layer "In6.Cu")
		(net "M_D_CPU1_SB_DQS_DN<7>")
	)
	(arc
		(start 94.536768 -232.204006)
		(mid 94.254066 -232.279782)
		(end 93.971364 -232.204006)
		(width 0.088646)
		(layer "In6.Cu")
		(net "M_D_CPU1_SB_DQS_DN<7>")
	)
	(arc
		(start 89.929208 -231.699816)
		(mid 89.735714 -231.386669)
		(end 89.367614 -231.39019)
		(width 0.088646)
		(layer "In6.Cu")
		(net "M_D_CPU1_SB_DQS_DN<7>")
	)
	(segment
		(start 13.446506 -218.305634)
		(end 12.973304 -218.305634)
		(width 0.20066)
		(layer "F.Cu")
		(net "M_D_CPU1_SB_DQS_DN<6>")
	)
	(segment
		(start 99.892866 -235.506006)
		(end 99.892866 -234.97032)
		(width 0.20066)
		(layer "F.Cu")
		(net "M_D_CPU1_SB_DQS_DN<6>")
	)
	(segment
		(start 13.868908 -217.883232)
		(end 13.446506 -218.305634)
		(width 0.20066)
		(layer "F.Cu")
		(net "M_D_CPU1_SB_DQS_DN<6>")
	)
	(segment
		(start 12.973304 -218.305634)
		(end 12.712192 -218.566746)
		(width 0.20066)
		(layer "F.Cu")
		(net "M_D_CPU1_SB_DQS_DN<6>")
	)
	(segment
		(start 14.108684 -217.883232)
		(end 13.868908 -217.883232)
		(width 0.20066)
		(layer "F.Cu")
		(net "M_D_CPU1_SB_DQS_DN<6>")
	)
	(segment
		(start 18.329148 -218.305634)
		(end 17.693132 -217.880692)
		(width 0.20066)
		(layer "F.Cu")
		(net "M_D_CPU1_SB_DQS_DN<6>")
	)
	(segment
		(start 20.889214 -218.566746)
		(end 19.784314 -218.566746)
		(width 0.20066)
		(layer "F.Cu")
		(net "M_D_CPU1_SB_DQS_DN<6>")
	)
	(segment
		(start 17.027398 -218.141804)
		(end 16.885158 -218.141804)
		(width 0.20066)
		(layer "F.Cu")
		(net "M_D_CPU1_SB_DQS_DN<6>")
	)
	(segment
		(start 14.807692 -218.141804)
		(end 14.567916 -218.141804)
		(width 0.101854)
		(layer "F.Cu")
		(net "M_D_CPU1_SB_DQS_DN<6>")
	)
	(segment
		(start 19.784314 -218.566746)
		(end 19.29384 -218.566746)
		(width 0.20066)
		(layer "F.Cu")
		(net "M_D_CPU1_SB_DQS_DN<6>")
	)
	(segment
		(start 14.560042 -218.149678)
		(end 14.37513 -218.149678)
		(width 0.20066)
		(layer "F.Cu")
		(net "M_D_CPU1_SB_DQS_DN<6>")
	)
	(segment
		(start 14.567916 -218.141804)
		(end 14.560042 -218.149678)
		(width 0.101854)
		(layer "F.Cu")
		(net "M_D_CPU1_SB_DQS_DN<6>")
	)
	(segment
		(start 19.29384 -218.566746)
		(end 19.032728 -218.305634)
		(width 0.20066)
		(layer "F.Cu")
		(net "M_D_CPU1_SB_DQS_DN<6>")
	)
	(segment
		(start 17.28851 -217.880692)
		(end 17.027398 -218.141804)
		(width 0.20066)
		(layer "F.Cu")
		(net "M_D_CPU1_SB_DQS_DN<6>")
	)
	(segment
		(start 16.885158 -218.141804)
		(end 14.807692 -218.141804)
		(width 0.1016)
		(layer "F.Cu")
		(net "M_D_CPU1_SB_DQS_DN<6>")
	)
	(segment
		(start 12.712192 -218.566746)
		(end 12.240514 -218.566746)
		(width 0.20066)
		(layer "F.Cu")
		(net "M_D_CPU1_SB_DQS_DN<6>")
	)
	(segment
		(start 17.693132 -217.880692)
		(end 17.28851 -217.880692)
		(width 0.20066)
		(layer "F.Cu")
		(net "M_D_CPU1_SB_DQS_DN<6>")
	)
	(segment
		(start 19.032728 -218.305634)
		(end 18.329148 -218.305634)
		(width 0.20066)
		(layer "F.Cu")
		(net "M_D_CPU1_SB_DQS_DN<6>")
	)
	(segment
		(start 99.892866 -234.97032)
		(end 99.892612 -234.970066)
		(width 0.20066)
		(layer "F.Cu")
		(net "M_D_CPU1_SB_DQS_DN<6>")
	)
	(segment
		(start 14.37513 -218.149678)
		(end 14.108684 -217.883232)
		(width 0.20066)
		(layer "F.Cu")
		(net "M_D_CPU1_SB_DQS_DN<6>")
	)
	(segment
		(start 35.686238 -210.492848)
		(end 35.442398 -210.249008)
		(width 0.18288)
		(layer "In11.Cu")
		(net "M_D_CPU1_SB_DQS_DN<6>")
	)
	(segment
		(start 69.03847 -219.074746)
		(end 67.823842 -216.140792)
		(width 0.18288)
		(layer "In11.Cu")
		(net "M_D_CPU1_SB_DQS_DN<6>")
	)
	(segment
		(start 99.892612 -234.970066)
		(end 100.20554 -234.970066)
		(width 0.088646)
		(layer "In11.Cu")
		(net "M_D_CPU1_SB_DQS_DN<6>")
	)
	(segment
		(start 22.917912 -218.300808)
		(end 22.388576 -218.519756)
		(width 0.18288)
		(layer "In11.Cu")
		(net "M_D_CPU1_SB_DQS_DN<6>")
	)
	(segment
		(start 54.323234 -210.196684)
		(end 53.774594 -210.196684)
		(width 0.18288)
		(layer "In11.Cu")
		(net "M_D_CPU1_SB_DQS_DN<6>")
	)
	(segment
		(start 83.443318 -231.24033)
		(end 82.696304 -230.493316)
		(width 0.088646)
		(layer "In11.Cu")
		(net "M_D_CPU1_SB_DQS_DN<6>")
	)
	(segment
		(start 21.53285 -218.294712)
		(end 21.161248 -218.294712)
		(width 0.18288)
		(layer "In11.Cu")
		(net "M_D_CPU1_SB_DQS_DN<6>")
	)
	(segment
		(start 53.774594 -210.196684)
		(end 53.650134 -210.321144)
		(width 0.18288)
		(layer "In11.Cu")
		(net "M_D_CPU1_SB_DQS_DN<6>")
	)
	(segment
		(start 46.684692 -211.340954)
		(end 46.438312 -211.094574)
		(width 0.18288)
		(layer "In11.Cu")
		(net "M_D_CPU1_SB_DQS_DN<6>")
	)
	(segment
		(start 51.554634 -210.196684)
		(end 51.25847 -210.492848)
		(width 0.18288)
		(layer "In11.Cu")
		(net "M_D_CPU1_SB_DQS_DN<6>")
	)
	(segment
		(start 50.794158 -210.492848)
		(end 50.572416 -210.271106)
		(width 0.18288)
		(layer "In11.Cu")
		(net "M_D_CPU1_SB_DQS_DN<6>")
	)
	(segment
		(start 50.028856 -210.271106)
		(end 49.215294 -211.084668)
		(width 0.18288)
		(layer "In11.Cu")
		(net "M_D_CPU1_SB_DQS_DN<6>")
	)
	(segment
		(start 26.769568 -212.498178)
		(end 26.210514 -212.729826)
		(width 0.18288)
		(layer "In11.Cu")
		(net "M_D_CPU1_SB_DQS_DN<6>")
	)
	(segment
		(start 38.996112 -210.243674)
		(end 36.440364 -210.243674)
		(width 0.18288)
		(layer "In11.Cu")
		(net "M_D_CPU1_SB_DQS_DN<6>")
	)
	(segment
		(start 99.705414 -234.645708)
		(end 99.690682 -234.654344)
		(width 0.088646)
		(layer "In11.Cu")
		(net "M_D_CPU1_SB_DQS_DN<6>")
	)
	(segment
		(start 98.765614 -234.645708)
		(end 98.750882 -234.654344)
		(width 0.088646)
		(layer "In11.Cu")
		(net "M_D_CPU1_SB_DQS_DN<6>")
	)
	(segment
		(start 58.729372 -211.326476)
		(end 57.049924 -211.326476)
		(width 0.18288)
		(layer "In11.Cu")
		(net "M_D_CPU1_SB_DQS_DN<6>")
	)
	(segment
		(start 47.429166 -211.084668)
		(end 47.17288 -211.340954)
		(width 0.18288)
		(layer "In11.Cu")
		(net "M_D_CPU1_SB_DQS_DN<6>")
	)
	(segment
		(start 88.335104 -232.20553)
		(end 88.33358 -232.204514)
		(width 0.088646)
		(layer "In11.Cu")
		(net "M_D_CPU1_SB_DQS_DN<6>")
	)
	(segment
		(start 57.049924 -211.326476)
		(end 54.323234 -210.196684)
		(width 0.18288)
		(layer "In11.Cu")
		(net "M_D_CPU1_SB_DQS_DN<6>")
	)
	(segment
		(start 46.438312 -211.094574)
		(end 45.794422 -211.094574)
		(width 0.18288)
		(layer "In11.Cu")
		(net "M_D_CPU1_SB_DQS_DN<6>")
	)
	(segment
		(start 25.462738 -216.38768)
		(end 25.097486 -216.752932)
		(width 0.18288)
		(layer "In11.Cu")
		(net "M_D_CPU1_SB_DQS_DN<6>")
	)
	(segment
		(start 88.347296 -232.212642)
		(end 88.339422 -232.20807)
		(width 0.088646)
		(layer "In11.Cu")
		(net "M_D_CPU1_SB_DQS_DN<6>")
	)
	(segment
		(start 93.040454 -232.209086)
		(end 93.033088 -232.204768)
		(width 0.088646)
		(layer "In11.Cu")
		(net "M_D_CPU1_SB_DQS_DN<6>")
	)
	(segment
		(start 88.33358 -232.204514)
		(end 88.332564 -232.204006)
		(width 0.088646)
		(layer "In11.Cu")
		(net "M_D_CPU1_SB_DQS_DN<6>")
	)
	(segment
		(start 32.082994 -211.3407)
		(end 31.594298 -211.3407)
		(width 0.18288)
		(layer "In11.Cu")
		(net "M_D_CPU1_SB_DQS_DN<6>")
	)
	(segment
		(start 26.210514 -212.729826)
		(end 25.737566 -213.202774)
		(width 0.18288)
		(layer "In11.Cu")
		(net "M_D_CPU1_SB_DQS_DN<6>")
	)
	(segment
		(start 31.594298 -211.3407)
		(end 31.351474 -211.097876)
		(width 0.18288)
		(layer "In11.Cu")
		(net "M_D_CPU1_SB_DQS_DN<6>")
	)
	(segment
		(start 43.609768 -211.136992)
		(end 41.152064 -211.136992)
		(width 0.18288)
		(layer "In11.Cu")
		(net "M_D_CPU1_SB_DQS_DN<6>")
	)
	(segment
		(start 24.018748 -217.199972)
		(end 22.917912 -218.300808)
		(width 0.18288)
		(layer "In11.Cu")
		(net "M_D_CPU1_SB_DQS_DN<6>")
	)
	(segment
		(start 61.926978 -213.748874)
		(end 61.333634 -213.15553)
		(width 0.18288)
		(layer "In11.Cu")
		(net "M_D_CPU1_SB_DQS_DN<6>")
	)
	(segment
		(start 25.737566 -213.202774)
		(end 25.737566 -215.72474)
		(width 0.18288)
		(layer "In11.Cu")
		(net "M_D_CPU1_SB_DQS_DN<6>")
	)
	(segment
		(start 88.339422 -232.20807)
		(end 88.337136 -232.206546)
		(width 0.088646)
		(layer "In11.Cu")
		(net "M_D_CPU1_SB_DQS_DN<6>")
	)
	(segment
		(start 21.161248 -218.294712)
		(end 20.889214 -218.566746)
		(width 0.18288)
		(layer "In11.Cu")
		(net "M_D_CPU1_SB_DQS_DN<6>")
	)
	(segment
		(start 100.0887 -234.650788)
		(end 100.07981 -234.645708)
		(width 0.088646)
		(layer "In11.Cu")
		(net "M_D_CPU1_SB_DQS_DN<6>")
	)
	(segment
		(start 66.059304 -214.587582)
		(end 65.510664 -214.587582)
		(width 0.18288)
		(layer "In11.Cu")
		(net "M_D_CPU1_SB_DQS_DN<6>")
	)
	(segment
		(start 86.078568 -232.204006)
		(end 86.068154 -232.210102)
		(width 0.088646)
		(layer "In11.Cu")
		(net "M_D_CPU1_SB_DQS_DN<6>")
	)
	(segment
		(start 82.696304 -230.493316)
		(end 82.433414 -230.493316)
		(width 0.088646)
		(layer "In11.Cu")
		(net "M_D_CPU1_SB_DQS_DN<6>")
	)
	(segment
		(start 65.386204 -214.712042)
		(end 64.837564 -214.712042)
		(width 0.18288)
		(layer "In11.Cu")
		(net "M_D_CPU1_SB_DQS_DN<6>")
	)
	(segment
		(start 93.5101 -233.022902)
		(end 93.50121 -233.017822)
		(width 0.088646)
		(layer "In11.Cu")
		(net "M_D_CPU1_SB_DQS_DN<6>")
	)
	(segment
		(start 30.841442 -211.097876)
		(end 30.2133 -210.469734)
		(width 0.18288)
		(layer "In11.Cu")
		(net "M_D_CPU1_SB_DQS_DN<6>")
	)
	(segment
		(start 31.351474 -211.097876)
		(end 30.841442 -211.097876)
		(width 0.18288)
		(layer "In11.Cu")
		(net "M_D_CPU1_SB_DQS_DN<6>")
	)
	(segment
		(start 64.837564 -214.712042)
		(end 64.713104 -214.587582)
		(width 0.18288)
		(layer "In11.Cu")
		(net "M_D_CPU1_SB_DQS_DN<6>")
	)
	(segment
		(start 28.603194 -211.124292)
		(end 28.143454 -211.124292)
		(width 0.18288)
		(layer "In11.Cu")
		(net "M_D_CPU1_SB_DQS_DN<6>")
	)
	(segment
		(start 84.385912 -232.153206)
		(end 83.857084 -232.153206)
		(width 0.088646)
		(layer "In11.Cu")
		(net "M_D_CPU1_SB_DQS_DN<6>")
	)
	(segment
		(start 65.510664 -214.587582)
		(end 65.386204 -214.712042)
		(width 0.18288)
		(layer "In11.Cu")
		(net "M_D_CPU1_SB_DQS_DN<6>")
	)
	(segment
		(start 63.40856 -214.362792)
		(end 63.245746 -214.430102)
		(width 0.18288)
		(layer "In11.Cu")
		(net "M_D_CPU1_SB_DQS_DN<6>")
	)
	(segment
		(start 93.688662 -233.356404)
		(end 93.688662 -233.34218)
		(width 0.088646)
		(layer "In11.Cu")
		(net "M_D_CPU1_SB_DQS_DN<6>")
	)
	(segment
		(start 53.650134 -210.321144)
		(end 53.101494 -210.321144)
		(width 0.18288)
		(layer "In11.Cu")
		(net "M_D_CPU1_SB_DQS_DN<6>")
	)
	(segment
		(start 100.20554 -234.970066)
		(end 100.26269 -234.912916)
		(width 0.088646)
		(layer "In11.Cu")
		(net "M_D_CPU1_SB_DQS_DN<6>")
	)
	(segment
		(start 82.433414 -230.493316)
		(end 82.37347 -230.55326)
		(width 0.088646)
		(layer "In11.Cu")
		(net "M_D_CPU1_SB_DQS_DN<6>")
	)
	(segment
		(start 47.17288 -211.340954)
		(end 46.684692 -211.340954)
		(width 0.18288)
		(layer "In11.Cu")
		(net "M_D_CPU1_SB_DQS_DN<6>")
	)
	(segment
		(start 61.157612 -213.15553)
		(end 60.769246 -212.767164)
		(width 0.18288)
		(layer "In11.Cu")
		(net "M_D_CPU1_SB_DQS_DN<6>")
	)
	(segment
		(start 32.347662 -211.076032)
		(end 32.082994 -211.3407)
		(width 0.18288)
		(layer "In11.Cu")
		(net "M_D_CPU1_SB_DQS_DN<6>")
	)
	(segment
		(start 53.101494 -210.321144)
		(end 52.977034 -210.196684)
		(width 0.18288)
		(layer "In11.Cu")
		(net "M_D_CPU1_SB_DQS_DN<6>")
	)
	(segment
		(start 35.442398 -210.249008)
		(end 34.822892 -210.249008)
		(width 0.18288)
		(layer "In11.Cu")
		(net "M_D_CPU1_SB_DQS_DN<6>")
	)
	(segment
		(start 61.333634 -213.15553)
		(end 61.157612 -213.15553)
		(width 0.18288)
		(layer "In11.Cu")
		(net "M_D_CPU1_SB_DQS_DN<6>")
	)
	(segment
		(start 83.443318 -231.73944)
		(end 83.443318 -231.24033)
		(width 0.088646)
		(layer "In11.Cu")
		(net "M_D_CPU1_SB_DQS_DN<6>")
	)
	(segment
		(start 44.173648 -211.700872)
		(end 43.609768 -211.136992)
		(width 0.18288)
		(layer "In11.Cu")
		(net "M_D_CPU1_SB_DQS_DN<6>")
	)
	(segment
		(start 91.162378 -232.210102)
		(end 91.151964 -232.204006)
		(width 0.088646)
		(layer "In11.Cu")
		(net "M_D_CPU1_SB_DQS_DN<6>")
	)
	(segment
		(start 93.219016 -232.543858)
		(end 93.219016 -232.528364)
		(width 0.088646)
		(layer "In11.Cu")
		(net "M_D_CPU1_SB_DQS_DN<6>")
	)
	(segment
		(start 36.19119 -210.492848)
		(end 35.686238 -210.492848)
		(width 0.18288)
		(layer "In11.Cu")
		(net "M_D_CPU1_SB_DQS_DN<6>")
	)
	(segment
		(start 34.822892 -210.249008)
		(end 33.995868 -211.076032)
		(width 0.18288)
		(layer "In11.Cu")
		(net "M_D_CPU1_SB_DQS_DN<6>")
	)
	(segment
		(start 93.033088 -232.204768)
		(end 93.031564 -232.204006)
		(width 0.088646)
		(layer "In11.Cu")
		(net "M_D_CPU1_SB_DQS_DN<6>")
	)
	(segment
		(start 33.995868 -211.076032)
		(end 32.347662 -211.076032)
		(width 0.18288)
		(layer "In11.Cu")
		(net "M_D_CPU1_SB_DQS_DN<6>")
	)
	(segment
		(start 52.977034 -210.196684)
		(end 51.554634 -210.196684)
		(width 0.18288)
		(layer "In11.Cu")
		(net "M_D_CPU1_SB_DQS_DN<6>")
	)
	(segment
		(start 66.419222 -214.73668)
		(end 66.059304 -214.587582)
		(width 0.18288)
		(layer "In11.Cu")
		(net "M_D_CPU1_SB_DQS_DN<6>")
	)
	(segment
		(start 62.738762 -214.220044)
		(end 62.671452 -214.05723)
		(width 0.18288)
		(layer "In11.Cu")
		(net "M_D_CPU1_SB_DQS_DN<6>")
	)
	(segment
		(start 94.158562 -234.166156)
		(end 94.158562 -234.147614)
		(width 0.088646)
		(layer "In11.Cu")
		(net "M_D_CPU1_SB_DQS_DN<6>")
	)
	(segment
		(start 21.757894 -218.519756)
		(end 21.53285 -218.294712)
		(width 0.18288)
		(layer "In11.Cu")
		(net "M_D_CPU1_SB_DQS_DN<6>")
	)
	(segment
		(start 64.713104 -214.587582)
		(end 63.951104 -214.587582)
		(width 0.18288)
		(layer "In11.Cu")
		(net "M_D_CPU1_SB_DQS_DN<6>")
	)
	(segment
		(start 29.257752 -210.469734)
		(end 28.603194 -211.124292)
		(width 0.18288)
		(layer "In11.Cu")
		(net "M_D_CPU1_SB_DQS_DN<6>")
	)
	(segment
		(start 60.769246 -212.767164)
		(end 60.769246 -212.591142)
		(width 0.18288)
		(layer "In11.Cu")
		(net "M_D_CPU1_SB_DQS_DN<6>")
	)
	(segment
		(start 60.052966 -211.874862)
		(end 58.729372 -211.326476)
		(width 0.18288)
		(layer "In11.Cu")
		(net "M_D_CPU1_SB_DQS_DN<6>")
	)
	(segment
		(start 89.287096 -232.212642)
		(end 89.272364 -232.204006)
		(width 0.088646)
		(layer "In11.Cu")
		(net "M_D_CPU1_SB_DQS_DN<6>")
	)
	(segment
		(start 45.794422 -211.094574)
		(end 45.188124 -211.700872)
		(width 0.18288)
		(layer "In11.Cu")
		(net "M_D_CPU1_SB_DQS_DN<6>")
	)
	(segment
		(start 45.188124 -211.700872)
		(end 44.173648 -211.700872)
		(width 0.18288)
		(layer "In11.Cu")
		(net "M_D_CPU1_SB_DQS_DN<6>")
	)
	(segment
		(start 92.101924 -232.210102)
		(end 92.09151 -232.204006)
		(width 0.088646)
		(layer "In11.Cu")
		(net "M_D_CPU1_SB_DQS_DN<6>")
	)
	(segment
		(start 97.825814 -234.645708)
		(end 97.8154 -234.651804)
		(width 0.088646)
		(layer "In11.Cu")
		(net "M_D_CPU1_SB_DQS_DN<6>")
	)
	(segment
		(start 50.572416 -210.271106)
		(end 50.028856 -210.271106)
		(width 0.18288)
		(layer "In11.Cu")
		(net "M_D_CPU1_SB_DQS_DN<6>")
	)
	(segment
		(start 67.823842 -216.140792)
		(end 66.419222 -214.73668)
		(width 0.18288)
		(layer "In11.Cu")
		(net "M_D_CPU1_SB_DQS_DN<6>")
	)
	(segment
		(start 88.337136 -232.206546)
		(end 88.335104 -232.20553)
		(width 0.088646)
		(layer "In11.Cu")
		(net "M_D_CPU1_SB_DQS_DN<6>")
	)
	(segment
		(start 60.769246 -212.591142)
		(end 60.052966 -211.874862)
		(width 0.18288)
		(layer "In11.Cu")
		(net "M_D_CPU1_SB_DQS_DN<6>")
	)
	(segment
		(start 83.857084 -232.153206)
		(end 83.443318 -231.73944)
		(width 0.088646)
		(layer "In11.Cu")
		(net "M_D_CPU1_SB_DQS_DN<6>")
	)
	(segment
		(start 41.152064 -211.136992)
		(end 38.996112 -210.243674)
		(width 0.18288)
		(layer "In11.Cu")
		(net "M_D_CPU1_SB_DQS_DN<6>")
	)
	(segment
		(start 95.946214 -234.645708)
		(end 95.931482 -234.654344)
		(width 0.088646)
		(layer "In11.Cu")
		(net "M_D_CPU1_SB_DQS_DN<6>")
	)
	(segment
		(start 25.097486 -216.752932)
		(end 24.018748 -217.199972)
		(width 0.18288)
		(layer "In11.Cu")
		(net "M_D_CPU1_SB_DQS_DN<6>")
	)
	(segment
		(start 28.143454 -211.124292)
		(end 26.769568 -212.498178)
		(width 0.18288)
		(layer "In11.Cu")
		(net "M_D_CPU1_SB_DQS_DN<6>")
	)
	(segment
		(start 30.2133 -210.469734)
		(end 29.257752 -210.469734)
		(width 0.18288)
		(layer "In11.Cu")
		(net "M_D_CPU1_SB_DQS_DN<6>")
	)
	(segment
		(start 63.951104 -214.587582)
		(end 63.40856 -214.362792)
		(width 0.18288)
		(layer "In11.Cu")
		(net "M_D_CPU1_SB_DQS_DN<6>")
	)
	(segment
		(start 82.37347 -230.55326)
		(end 80.517238 -230.55326)
		(width 0.18288)
		(layer "In11.Cu")
		(net "M_D_CPU1_SB_DQS_DN<6>")
	)
	(segment
		(start 85.138514 -232.204006)
		(end 85.123782 -232.212642)
		(width 0.088646)
		(layer "In11.Cu")
		(net "M_D_CPU1_SB_DQS_DN<6>")
	)
	(segment
		(start 96.886268 -234.645708)
		(end 96.875854 -234.651804)
		(width 0.088646)
		(layer "In11.Cu")
		(net "M_D_CPU1_SB_DQS_DN<6>")
	)
	(segment
		(start 62.671452 -214.05723)
		(end 61.926978 -213.748874)
		(width 0.18288)
		(layer "In11.Cu")
		(net "M_D_CPU1_SB_DQS_DN<6>")
	)
	(segment
		(start 49.215294 -211.084668)
		(end 47.429166 -211.084668)
		(width 0.18288)
		(layer "In11.Cu")
		(net "M_D_CPU1_SB_DQS_DN<6>")
	)
	(segment
		(start 63.245746 -214.430102)
		(end 62.738762 -214.220044)
		(width 0.18288)
		(layer "In11.Cu")
		(net "M_D_CPU1_SB_DQS_DN<6>")
	)
	(segment
		(start 25.737566 -215.72474)
		(end 25.462738 -216.38768)
		(width 0.18288)
		(layer "In11.Cu")
		(net "M_D_CPU1_SB_DQS_DN<6>")
	)
	(segment
		(start 22.388576 -218.519756)
		(end 21.757894 -218.519756)
		(width 0.18288)
		(layer "In11.Cu")
		(net "M_D_CPU1_SB_DQS_DN<6>")
	)
	(segment
		(start 80.517238 -230.55326)
		(end 69.03847 -219.074746)
		(width 0.18288)
		(layer "In11.Cu")
		(net "M_D_CPU1_SB_DQS_DN<6>")
	)
	(segment
		(start 51.25847 -210.492848)
		(end 50.794158 -210.492848)
		(width 0.18288)
		(layer "In11.Cu")
		(net "M_D_CPU1_SB_DQS_DN<6>")
	)
	(segment
		(start 90.226896 -232.212642)
		(end 90.212164 -232.204006)
		(width 0.088646)
		(layer "In11.Cu")
		(net "M_D_CPU1_SB_DQS_DN<6>")
	)
	(segment
		(start 36.440364 -210.243674)
		(end 36.19119 -210.492848)
		(width 0.18288)
		(layer "In11.Cu")
		(net "M_D_CPU1_SB_DQS_DN<6>")
	)
	(arc
		(start 98.750882 -234.654344)
		(mid 98.474407 -234.721664)
		(end 98.20021 -234.645708)
		(width 0.088646)
		(layer "In11.Cu")
		(net "M_D_CPU1_SB_DQS_DN<6>")
	)
	(arc
		(start 87.958168 -232.204006)
		(mid 87.675466 -232.279782)
		(end 87.392764 -232.204006)
		(width 0.088646)
		(layer "In11.Cu")
		(net "M_D_CPU1_SB_DQS_DN<6>")
	)
	(arc
		(start 92.657168 -232.204006)
		(mid 92.380355 -232.279876)
		(end 92.101924 -232.210102)
		(width 0.088646)
		(layer "In11.Cu")
		(net "M_D_CPU1_SB_DQS_DN<6>")
	)
	(arc
		(start 91.717114 -232.204006)
		(mid 91.440555 -232.279749)
		(end 91.162378 -232.210102)
		(width 0.088646)
		(layer "In11.Cu")
		(net "M_D_CPU1_SB_DQS_DN<6>")
	)
	(arc
		(start 86.452964 -232.204006)
		(mid 86.265766 -232.153863)
		(end 86.078568 -232.204006)
		(width 0.088646)
		(layer "In11.Cu")
		(net "M_D_CPU1_SB_DQS_DN<6>")
	)
	(arc
		(start 90.777568 -232.204006)
		(mid 90.503369 -232.279841)
		(end 90.226896 -232.212642)
		(width 0.088646)
		(layer "In11.Cu")
		(net "M_D_CPU1_SB_DQS_DN<6>")
	)
	(arc
		(start 97.8154 -234.651804)
		(mid 97.537222 -234.721527)
		(end 97.260664 -234.645708)
		(width 0.088646)
		(layer "In11.Cu")
		(net "M_D_CPU1_SB_DQS_DN<6>")
	)
	(arc
		(start 93.031564 -232.204006)
		(mid 92.844366 -232.153863)
		(end 92.657168 -232.204006)
		(width 0.088646)
		(layer "In11.Cu")
		(net "M_D_CPU1_SB_DQS_DN<6>")
	)
	(arc
		(start 99.14001 -234.645708)
		(mid 98.952812 -234.595565)
		(end 98.765614 -234.645708)
		(width 0.088646)
		(layer "In11.Cu")
		(net "M_D_CPU1_SB_DQS_DN<6>")
	)
	(arc
		(start 87.392764 -232.204006)
		(mid 87.205566 -232.153863)
		(end 87.018368 -232.204006)
		(width 0.088646)
		(layer "In11.Cu")
		(net "M_D_CPU1_SB_DQS_DN<6>")
	)
	(arc
		(start 95.931482 -234.654344)
		(mid 95.655007 -234.721664)
		(end 95.38081 -234.645708)
		(width 0.088646)
		(layer "In11.Cu")
		(net "M_D_CPU1_SB_DQS_DN<6>")
	)
	(arc
		(start 84.57311 -232.204006)
		(mid 84.482854 -232.166284)
		(end 84.385912 -232.153206)
		(width 0.088646)
		(layer "In11.Cu")
		(net "M_D_CPU1_SB_DQS_DN<6>")
	)
	(arc
		(start 85.51291 -232.204006)
		(mid 85.325712 -232.153863)
		(end 85.138514 -232.204006)
		(width 0.088646)
		(layer "In11.Cu")
		(net "M_D_CPU1_SB_DQS_DN<6>")
	)
	(arc
		(start 89.837768 -232.204006)
		(mid 89.563569 -232.279841)
		(end 89.287096 -232.212642)
		(width 0.088646)
		(layer "In11.Cu")
		(net "M_D_CPU1_SB_DQS_DN<6>")
	)
	(arc
		(start 98.20021 -234.645708)
		(mid 98.013012 -234.595565)
		(end 97.825814 -234.645708)
		(width 0.088646)
		(layer "In11.Cu")
		(net "M_D_CPU1_SB_DQS_DN<6>")
	)
	(arc
		(start 97.260664 -234.645708)
		(mid 97.073466 -234.595565)
		(end 96.886268 -234.645708)
		(width 0.088646)
		(layer "In11.Cu")
		(net "M_D_CPU1_SB_DQS_DN<6>")
	)
	(arc
		(start 100.07981 -234.645708)
		(mid 99.892612 -234.595565)
		(end 99.705414 -234.645708)
		(width 0.088646)
		(layer "In11.Cu")
		(net "M_D_CPU1_SB_DQS_DN<6>")
	)
	(arc
		(start 96.32061 -234.645708)
		(mid 96.133412 -234.595565)
		(end 95.946214 -234.645708)
		(width 0.088646)
		(layer "In11.Cu")
		(net "M_D_CPU1_SB_DQS_DN<6>")
	)
	(arc
		(start 86.068154 -232.210102)
		(mid 85.789722 -232.279948)
		(end 85.51291 -232.204006)
		(width 0.088646)
		(layer "In11.Cu")
		(net "M_D_CPU1_SB_DQS_DN<6>")
	)
	(arc
		(start 93.688662 -233.34218)
		(mid 93.640983 -233.15928)
		(end 93.5101 -233.022902)
		(width 0.088646)
		(layer "In11.Cu")
		(net "M_D_CPU1_SB_DQS_DN<6>")
	)
	(arc
		(start 93.50121 -233.017822)
		(mid 93.298387 -232.817591)
		(end 93.219016 -232.543858)
		(width 0.088646)
		(layer "In11.Cu")
		(net "M_D_CPU1_SB_DQS_DN<6>")
	)
	(arc
		(start 88.332564 -232.204006)
		(mid 88.145366 -232.153863)
		(end 87.958168 -232.204006)
		(width 0.088646)
		(layer "In11.Cu")
		(net "M_D_CPU1_SB_DQS_DN<6>")
	)
	(arc
		(start 93.219016 -232.528364)
		(mid 93.171337 -232.345464)
		(end 93.040454 -232.209086)
		(width 0.088646)
		(layer "In11.Cu")
		(net "M_D_CPU1_SB_DQS_DN<6>")
	)
	(arc
		(start 96.875854 -234.651804)
		(mid 96.597422 -234.72165)
		(end 96.32061 -234.645708)
		(width 0.088646)
		(layer "In11.Cu")
		(net "M_D_CPU1_SB_DQS_DN<6>")
	)
	(arc
		(start 95.006414 -234.645708)
		(mid 94.723712 -234.721484)
		(end 94.44101 -234.645708)
		(width 0.088646)
		(layer "In11.Cu")
		(net "M_D_CPU1_SB_DQS_DN<6>")
	)
	(arc
		(start 94.44101 -234.645708)
		(mid 94.236675 -234.443103)
		(end 94.158562 -234.166156)
		(width 0.088646)
		(layer "In11.Cu")
		(net "M_D_CPU1_SB_DQS_DN<6>")
	)
	(arc
		(start 88.897968 -232.204006)
		(mid 88.623769 -232.279841)
		(end 88.347296 -232.212642)
		(width 0.088646)
		(layer "In11.Cu")
		(net "M_D_CPU1_SB_DQS_DN<6>")
	)
	(arc
		(start 94.158562 -234.147614)
		(mid 94.106292 -233.965249)
		(end 93.971364 -233.831892)
		(width 0.088646)
		(layer "In11.Cu")
		(net "M_D_CPU1_SB_DQS_DN<6>")
	)
	(arc
		(start 90.212164 -232.204006)
		(mid 90.024966 -232.153863)
		(end 89.837768 -232.204006)
		(width 0.088646)
		(layer "In11.Cu")
		(net "M_D_CPU1_SB_DQS_DN<6>")
	)
	(arc
		(start 100.26269 -234.912916)
		(mid 100.204571 -234.762675)
		(end 100.0887 -234.650788)
		(width 0.088646)
		(layer "In11.Cu")
		(net "M_D_CPU1_SB_DQS_DN<6>")
	)
	(arc
		(start 92.09151 -232.204006)
		(mid 91.904312 -232.153863)
		(end 91.717114 -232.204006)
		(width 0.088646)
		(layer "In11.Cu")
		(net "M_D_CPU1_SB_DQS_DN<6>")
	)
	(arc
		(start 99.690682 -234.654344)
		(mid 99.414207 -234.721664)
		(end 99.14001 -234.645708)
		(width 0.088646)
		(layer "In11.Cu")
		(net "M_D_CPU1_SB_DQS_DN<6>")
	)
	(arc
		(start 91.151964 -232.204006)
		(mid 90.964766 -232.153863)
		(end 90.777568 -232.204006)
		(width 0.088646)
		(layer "In11.Cu")
		(net "M_D_CPU1_SB_DQS_DN<6>")
	)
	(arc
		(start 95.38081 -234.645708)
		(mid 95.193612 -234.595565)
		(end 95.006414 -234.645708)
		(width 0.088646)
		(layer "In11.Cu")
		(net "M_D_CPU1_SB_DQS_DN<6>")
	)
	(arc
		(start 93.971364 -233.831892)
		(mid 93.767883 -233.631088)
		(end 93.688662 -233.356404)
		(width 0.088646)
		(layer "In11.Cu")
		(net "M_D_CPU1_SB_DQS_DN<6>")
	)
	(arc
		(start 89.272364 -232.204006)
		(mid 89.085166 -232.153863)
		(end 88.897968 -232.204006)
		(width 0.088646)
		(layer "In11.Cu")
		(net "M_D_CPU1_SB_DQS_DN<6>")
	)
	(arc
		(start 85.123782 -232.212642)
		(mid 84.847307 -232.279962)
		(end 84.57311 -232.204006)
		(width 0.088646)
		(layer "In11.Cu")
		(net "M_D_CPU1_SB_DQS_DN<6>")
	)
	(arc
		(start 87.018368 -232.204006)
		(mid 86.735666 -232.279782)
		(end 86.452964 -232.204006)
		(width 0.088646)
		(layer "In11.Cu")
		(net "M_D_CPU1_SB_DQS_DN<6>")
	)
	(segment
		(start 99.892612 -240.388902)
		(end 99.892612 -239.853216)
		(width 0.20066)
		(layer "F.Cu")
		(net "M_D_CPU1_SB_DQS_DN<5>")
	)
	(segment
		(start 16.885158 -227.491798)
		(end 14.807692 -227.491798)
		(width 0.1016)
		(layer "F.Cu")
		(net "M_D_CPU1_SB_DQS_DN<5>")
	)
	(segment
		(start 14.37513 -227.499672)
		(end 14.108684 -227.233226)
		(width 0.20066)
		(layer "F.Cu")
		(net "M_D_CPU1_SB_DQS_DN<5>")
	)
	(segment
		(start 17.693132 -227.230686)
		(end 17.28851 -227.230686)
		(width 0.20066)
		(layer "F.Cu")
		(net "M_D_CPU1_SB_DQS_DN<5>")
	)
	(segment
		(start 19.784314 -227.91674)
		(end 19.29384 -227.91674)
		(width 0.20066)
		(layer "F.Cu")
		(net "M_D_CPU1_SB_DQS_DN<5>")
	)
	(segment
		(start 13.446506 -227.655628)
		(end 12.973304 -227.655628)
		(width 0.20066)
		(layer "F.Cu")
		(net "M_D_CPU1_SB_DQS_DN<5>")
	)
	(segment
		(start 99.892866 -240.389156)
		(end 99.892612 -240.388902)
		(width 0.20066)
		(layer "F.Cu")
		(net "M_D_CPU1_SB_DQS_DN<5>")
	)
	(segment
		(start 12.712192 -227.91674)
		(end 12.240514 -227.91674)
		(width 0.20066)
		(layer "F.Cu")
		(net "M_D_CPU1_SB_DQS_DN<5>")
	)
	(segment
		(start 17.027398 -227.491798)
		(end 16.885158 -227.491798)
		(width 0.20066)
		(layer "F.Cu")
		(net "M_D_CPU1_SB_DQS_DN<5>")
	)
	(segment
		(start 14.560042 -227.499672)
		(end 14.37513 -227.499672)
		(width 0.20066)
		(layer "F.Cu")
		(net "M_D_CPU1_SB_DQS_DN<5>")
	)
	(segment
		(start 14.108684 -227.233226)
		(end 13.868908 -227.233226)
		(width 0.20066)
		(layer "F.Cu")
		(net "M_D_CPU1_SB_DQS_DN<5>")
	)
	(segment
		(start 17.28851 -227.230686)
		(end 17.027398 -227.491798)
		(width 0.20066)
		(layer "F.Cu")
		(net "M_D_CPU1_SB_DQS_DN<5>")
	)
	(segment
		(start 19.29384 -227.91674)
		(end 19.032728 -227.655628)
		(width 0.20066)
		(layer "F.Cu")
		(net "M_D_CPU1_SB_DQS_DN<5>")
	)
	(segment
		(start 20.889214 -227.91674)
		(end 19.784314 -227.91674)
		(width 0.20066)
		(layer "F.Cu")
		(net "M_D_CPU1_SB_DQS_DN<5>")
	)
	(segment
		(start 14.567916 -227.491798)
		(end 14.560042 -227.499672)
		(width 0.101854)
		(layer "F.Cu")
		(net "M_D_CPU1_SB_DQS_DN<5>")
	)
	(segment
		(start 13.868908 -227.233226)
		(end 13.446506 -227.655628)
		(width 0.20066)
		(layer "F.Cu")
		(net "M_D_CPU1_SB_DQS_DN<5>")
	)
	(segment
		(start 14.807692 -227.491798)
		(end 14.567916 -227.491798)
		(width 0.101854)
		(layer "F.Cu")
		(net "M_D_CPU1_SB_DQS_DN<5>")
	)
	(segment
		(start 19.032728 -227.655628)
		(end 18.329148 -227.655628)
		(width 0.20066)
		(layer "F.Cu")
		(net "M_D_CPU1_SB_DQS_DN<5>")
	)
	(segment
		(start 18.329148 -227.655628)
		(end 17.693132 -227.230686)
		(width 0.20066)
		(layer "F.Cu")
		(net "M_D_CPU1_SB_DQS_DN<5>")
	)
	(segment
		(start 12.973304 -227.655628)
		(end 12.712192 -227.91674)
		(width 0.20066)
		(layer "F.Cu")
		(net "M_D_CPU1_SB_DQS_DN<5>")
	)
	(segment
		(start 51.555904 -222.955612)
		(end 51.270408 -223.241108)
		(width 0.18288)
		(layer "In11.Cu")
		(net "M_D_CPU1_SB_DQS_DN<5>")
	)
	(segment
		(start 75.136248 -234.69092)
		(end 74.74839 -234.303062)
		(width 0.18288)
		(layer "In11.Cu")
		(net "M_D_CPU1_SB_DQS_DN<5>")
	)
	(segment
		(start 88.334088 -238.715804)
		(end 88.332564 -238.715042)
		(width 0.088646)
		(layer "In11.Cu")
		(net "M_D_CPU1_SB_DQS_DN<5>")
	)
	(segment
		(start 31.131256 -223.844866)
		(end 30.639766 -224.04832)
		(width 0.18288)
		(layer "In11.Cu")
		(net "M_D_CPU1_SB_DQS_DN<5>")
	)
	(segment
		(start 94.066614 -239.528858)
		(end 94.051882 -239.537494)
		(width 0.088646)
		(layer "In11.Cu")
		(net "M_D_CPU1_SB_DQS_DN<5>")
	)
	(segment
		(start 47.226474 -224.090992)
		(end 46.737778 -224.090992)
		(width 0.18288)
		(layer "In11.Cu")
		(net "M_D_CPU1_SB_DQS_DN<5>")
	)
	(segment
		(start 31.650178 -224.090992)
		(end 31.404052 -223.844866)
		(width 0.18288)
		(layer "In11.Cu")
		(net "M_D_CPU1_SB_DQS_DN<5>")
	)
	(segment
		(start 27.248612 -226.716082)
		(end 24.283416 -227.944426)
		(width 0.18288)
		(layer "In11.Cu")
		(net "M_D_CPU1_SB_DQS_DN<5>")
	)
	(segment
		(start 62.585092 -225.513138)
		(end 62.307216 -225.791014)
		(width 0.18288)
		(layer "In11.Cu")
		(net "M_D_CPU1_SB_DQS_DN<5>")
	)
	(segment
		(start 88.341454 -238.720122)
		(end 88.334088 -238.715804)
		(width 0.088646)
		(layer "In11.Cu")
		(net "M_D_CPU1_SB_DQS_DN<5>")
	)
	(segment
		(start 59.91987 -224.881186)
		(end 58.891932 -223.853248)
		(width 0.18288)
		(layer "In11.Cu")
		(net "M_D_CPU1_SB_DQS_DN<5>")
	)
	(segment
		(start 32.402272 -223.827594)
		(end 32.138874 -224.090992)
		(width 0.18288)
		(layer "In11.Cu")
		(net "M_D_CPU1_SB_DQS_DN<5>")
	)
	(segment
		(start 75.136248 -234.866942)
		(end 75.136248 -234.69092)
		(width 0.18288)
		(layer "In11.Cu")
		(net "M_D_CPU1_SB_DQS_DN<5>")
	)
	(segment
		(start 76.08824 -235.642912)
		(end 75.700382 -235.255054)
		(width 0.18288)
		(layer "In11.Cu")
		(net "M_D_CPU1_SB_DQS_DN<5>")
	)
	(segment
		(start 75.52436 -235.255054)
		(end 75.136248 -234.866942)
		(width 0.18288)
		(layer "In11.Cu")
		(net "M_D_CPU1_SB_DQS_DN<5>")
	)
	(segment
		(start 98.765614 -239.528858)
		(end 98.750882 -239.537494)
		(width 0.088646)
		(layer "In11.Cu")
		(net "M_D_CPU1_SB_DQS_DN<5>")
	)
	(segment
		(start 61.84646 -225.791014)
		(end 61.58738 -225.531934)
		(width 0.18288)
		(layer "In11.Cu")
		(net "M_D_CPU1_SB_DQS_DN<5>")
	)
	(segment
		(start 31.404052 -223.844866)
		(end 31.131256 -223.844866)
		(width 0.18288)
		(layer "In11.Cu")
		(net "M_D_CPU1_SB_DQS_DN<5>")
	)
	(segment
		(start 97.825814 -239.528858)
		(end 97.8154 -239.534954)
		(width 0.088646)
		(layer "In11.Cu")
		(net "M_D_CPU1_SB_DQS_DN<5>")
	)
	(segment
		(start 84.38642 -237.977172)
		(end 84.0105 -237.977172)
		(width 0.088646)
		(layer "In11.Cu")
		(net "M_D_CPU1_SB_DQS_DN<5>")
	)
	(segment
		(start 74.184256 -233.91495)
		(end 74.184256 -233.738928)
		(width 0.18288)
		(layer "In11.Cu")
		(net "M_D_CPU1_SB_DQS_DN<5>")
	)
	(segment
		(start 82.433414 -236.53496)
		(end 82.37347 -236.594904)
		(width 0.088646)
		(layer "In11.Cu")
		(net "M_D_CPU1_SB_DQS_DN<5>")
	)
	(segment
		(start 50.80254 -223.241108)
		(end 50.53965 -222.978218)
		(width 0.18288)
		(layer "In11.Cu")
		(net "M_D_CPU1_SB_DQS_DN<5>")
	)
	(segment
		(start 43.73372 -223.888554)
		(end 41.124378 -223.888554)
		(width 0.18288)
		(layer "In11.Cu")
		(net "M_D_CPU1_SB_DQS_DN<5>")
	)
	(segment
		(start 34.158428 -223.827594)
		(end 32.402272 -223.827594)
		(width 0.18288)
		(layer "In11.Cu")
		(net "M_D_CPU1_SB_DQS_DN<5>")
	)
	(segment
		(start 45.241718 -224.410016)
		(end 44.255182 -224.410016)
		(width 0.18288)
		(layer "In11.Cu")
		(net "M_D_CPU1_SB_DQS_DN<5>")
	)
	(segment
		(start 30.639766 -224.04832)
		(end 29.624782 -224.726754)
		(width 0.18288)
		(layer "In11.Cu")
		(net "M_D_CPU1_SB_DQS_DN<5>")
	)
	(segment
		(start 90.307668 -239.528858)
		(end 90.297254 -239.534954)
		(width 0.088646)
		(layer "In11.Cu")
		(net "M_D_CPU1_SB_DQS_DN<5>")
	)
	(segment
		(start 28.283916 -225.680778)
		(end 27.248612 -226.716082)
		(width 0.18288)
		(layer "In11.Cu")
		(net "M_D_CPU1_SB_DQS_DN<5>")
	)
	(segment
		(start 47.455328 -223.862138)
		(end 47.226474 -224.090992)
		(width 0.18288)
		(layer "In11.Cu")
		(net "M_D_CPU1_SB_DQS_DN<5>")
	)
	(segment
		(start 38.951916 -222.988378)
		(end 36.441634 -222.988378)
		(width 0.18288)
		(layer "In11.Cu")
		(net "M_D_CPU1_SB_DQS_DN<5>")
	)
	(segment
		(start 61.58738 -225.531934)
		(end 61.021468 -225.531934)
		(width 0.18288)
		(layer "In11.Cu")
		(net "M_D_CPU1_SB_DQS_DN<5>")
	)
	(segment
		(start 62.137798 -225.791014)
		(end 61.980318 -225.791014)
		(width 0.16002)
		(layer "In11.Cu")
		(net "M_D_CPU1_SB_DQS_DN<5>")
	)
	(segment
		(start 100.0887 -239.533938)
		(end 100.07981 -239.528858)
		(width 0.088646)
		(layer "In11.Cu")
		(net "M_D_CPU1_SB_DQS_DN<5>")
	)
	(segment
		(start 93.126814 -239.528858)
		(end 93.112082 -239.537494)
		(width 0.088646)
		(layer "In11.Cu")
		(net "M_D_CPU1_SB_DQS_DN<5>")
	)
	(segment
		(start 86.931754 -237.906306)
		(end 86.924388 -237.901988)
		(width 0.088646)
		(layer "In11.Cu")
		(net "M_D_CPU1_SB_DQS_DN<5>")
	)
	(segment
		(start 60.37072 -224.881186)
		(end 59.91987 -224.881186)
		(width 0.18288)
		(layer "In11.Cu")
		(net "M_D_CPU1_SB_DQS_DN<5>")
	)
	(segment
		(start 32.138874 -224.090992)
		(end 31.650178 -224.090992)
		(width 0.18288)
		(layer "In11.Cu")
		(net "M_D_CPU1_SB_DQS_DN<5>")
	)
	(segment
		(start 82.37347 -236.594904)
		(end 77.040232 -236.594904)
		(width 0.18288)
		(layer "In11.Cu")
		(net "M_D_CPU1_SB_DQS_DN<5>")
	)
	(segment
		(start 91.247214 -239.528858)
		(end 91.2368 -239.534954)
		(width 0.088646)
		(layer "In11.Cu")
		(net "M_D_CPU1_SB_DQS_DN<5>")
	)
	(segment
		(start 74.572368 -234.303062)
		(end 74.184256 -233.91495)
		(width 0.18288)
		(layer "In11.Cu")
		(net "M_D_CPU1_SB_DQS_DN<5>")
	)
	(segment
		(start 99.705414 -239.528858)
		(end 99.690682 -239.537494)
		(width 0.088646)
		(layer "In11.Cu")
		(net "M_D_CPU1_SB_DQS_DN<5>")
	)
	(segment
		(start 41.124378 -223.888554)
		(end 38.951916 -222.988378)
		(width 0.18288)
		(layer "In11.Cu")
		(net "M_D_CPU1_SB_DQS_DN<5>")
	)
	(segment
		(start 21.91258 -227.944426)
		(end 21.61794 -227.649786)
		(width 0.18288)
		(layer "In11.Cu")
		(net "M_D_CPU1_SB_DQS_DN<5>")
	)
	(segment
		(start 92.187014 -239.528858)
		(end 92.172282 -239.537494)
		(width 0.088646)
		(layer "In11.Cu")
		(net "M_D_CPU1_SB_DQS_DN<5>")
	)
	(segment
		(start 65.917064 -226.652074)
		(end 65.616582 -226.351592)
		(width 0.18288)
		(layer "In11.Cu")
		(net "M_D_CPU1_SB_DQS_DN<5>")
	)
	(segment
		(start 95.946214 -239.528858)
		(end 95.931482 -239.537494)
		(width 0.088646)
		(layer "In11.Cu")
		(net "M_D_CPU1_SB_DQS_DN<5>")
	)
	(segment
		(start 56.401462 -223.853248)
		(end 54.23408 -222.955612)
		(width 0.18288)
		(layer "In11.Cu")
		(net "M_D_CPU1_SB_DQS_DN<5>")
	)
	(segment
		(start 100.20554 -239.853216)
		(end 100.26269 -239.796066)
		(width 0.088646)
		(layer "In11.Cu")
		(net "M_D_CPU1_SB_DQS_DN<5>")
	)
	(segment
		(start 87.110316 -238.23549)
		(end 87.110316 -238.225584)
		(width 0.088646)
		(layer "In11.Cu")
		(net "M_D_CPU1_SB_DQS_DN<5>")
	)
	(segment
		(start 65.616582 -226.351592)
		(end 64.911478 -226.351592)
		(width 0.18288)
		(layer "In11.Cu")
		(net "M_D_CPU1_SB_DQS_DN<5>")
	)
	(segment
		(start 34.994596 -222.991426)
		(end 34.158428 -223.827594)
		(width 0.18288)
		(layer "In11.Cu")
		(net "M_D_CPU1_SB_DQS_DN<5>")
	)
	(segment
		(start 36.19119 -223.238822)
		(end 35.702494 -223.238822)
		(width 0.18288)
		(layer "In11.Cu")
		(net "M_D_CPU1_SB_DQS_DN<5>")
	)
	(segment
		(start 66.398648 -226.652074)
		(end 66.255138 -226.652074)
		(width 0.18288)
		(layer "In11.Cu")
		(net "M_D_CPU1_SB_DQS_DN<5>")
	)
	(segment
		(start 54.23408 -222.955612)
		(end 51.555904 -222.955612)
		(width 0.18288)
		(layer "In11.Cu")
		(net "M_D_CPU1_SB_DQS_DN<5>")
	)
	(segment
		(start 77.040232 -236.594904)
		(end 76.652374 -236.207046)
		(width 0.18288)
		(layer "In11.Cu")
		(net "M_D_CPU1_SB_DQS_DN<5>")
	)
	(segment
		(start 75.700382 -235.255054)
		(end 75.52436 -235.255054)
		(width 0.18288)
		(layer "In11.Cu")
		(net "M_D_CPU1_SB_DQS_DN<5>")
	)
	(segment
		(start 28.944824 -225.406966)
		(end 28.283916 -225.680778)
		(width 0.18288)
		(layer "In11.Cu")
		(net "M_D_CPU1_SB_DQS_DN<5>")
	)
	(segment
		(start 46.737778 -224.090992)
		(end 46.486572 -223.839786)
		(width 0.18288)
		(layer "In11.Cu")
		(net "M_D_CPU1_SB_DQS_DN<5>")
	)
	(segment
		(start 50.53965 -222.978218)
		(end 50.023268 -222.978218)
		(width 0.18288)
		(layer "In11.Cu")
		(net "M_D_CPU1_SB_DQS_DN<5>")
	)
	(segment
		(start 29.624782 -224.726754)
		(end 28.944824 -225.406966)
		(width 0.18288)
		(layer "In11.Cu")
		(net "M_D_CPU1_SB_DQS_DN<5>")
	)
	(segment
		(start 64.911478 -226.351592)
		(end 64.073024 -225.513138)
		(width 0.18288)
		(layer "In11.Cu")
		(net "M_D_CPU1_SB_DQS_DN<5>")
	)
	(segment
		(start 66.039238 -226.652074)
		(end 65.917064 -226.652074)
		(width 0.18288)
		(layer "In11.Cu")
		(net "M_D_CPU1_SB_DQS_DN<5>")
	)
	(segment
		(start 35.455098 -222.991426)
		(end 34.994596 -222.991426)
		(width 0.18288)
		(layer "In11.Cu")
		(net "M_D_CPU1_SB_DQS_DN<5>")
	)
	(segment
		(start 74.184256 -233.738928)
		(end 73.796398 -233.35107)
		(width 0.18288)
		(layer "In11.Cu")
		(net "M_D_CPU1_SB_DQS_DN<5>")
	)
	(segment
		(start 61.021468 -225.531934)
		(end 60.37072 -224.881186)
		(width 0.18288)
		(layer "In11.Cu")
		(net "M_D_CPU1_SB_DQS_DN<5>")
	)
	(segment
		(start 45.811948 -223.839786)
		(end 45.241718 -224.410016)
		(width 0.18288)
		(layer "In11.Cu")
		(net "M_D_CPU1_SB_DQS_DN<5>")
	)
	(segment
		(start 35.702494 -223.238822)
		(end 35.455098 -222.991426)
		(width 0.18288)
		(layer "In11.Cu")
		(net "M_D_CPU1_SB_DQS_DN<5>")
	)
	(segment
		(start 66.88328 -226.437952)
		(end 66.61277 -226.437952)
		(width 0.18288)
		(layer "In11.Cu")
		(net "M_D_CPU1_SB_DQS_DN<5>")
	)
	(segment
		(start 84.0105 -237.977172)
		(end 82.568288 -236.53496)
		(width 0.088646)
		(layer "In11.Cu")
		(net "M_D_CPU1_SB_DQS_DN<5>")
	)
	(segment
		(start 64.073024 -225.513138)
		(end 62.585092 -225.513138)
		(width 0.18288)
		(layer "In11.Cu")
		(net "M_D_CPU1_SB_DQS_DN<5>")
	)
	(segment
		(start 99.892612 -239.853216)
		(end 100.20554 -239.853216)
		(width 0.088646)
		(layer "In11.Cu")
		(net "M_D_CPU1_SB_DQS_DN<5>")
	)
	(segment
		(start 49.139348 -223.862138)
		(end 47.455328 -223.862138)
		(width 0.18288)
		(layer "In11.Cu")
		(net "M_D_CPU1_SB_DQS_DN<5>")
	)
	(segment
		(start 62.307216 -225.791014)
		(end 62.137798 -225.791014)
		(width 0.18288)
		(layer "In11.Cu")
		(net "M_D_CPU1_SB_DQS_DN<5>")
	)
	(segment
		(start 76.476352 -236.207046)
		(end 76.08824 -235.818934)
		(width 0.18288)
		(layer "In11.Cu")
		(net "M_D_CPU1_SB_DQS_DN<5>")
	)
	(segment
		(start 88.520016 -239.054894)
		(end 88.520016 -239.0394)
		(width 0.088646)
		(layer "In11.Cu")
		(net "M_D_CPU1_SB_DQS_DN<5>")
	)
	(segment
		(start 73.620376 -233.35107)
		(end 73.232264 -232.962958)
		(width 0.18288)
		(layer "In11.Cu")
		(net "M_D_CPU1_SB_DQS_DN<5>")
	)
	(segment
		(start 73.232264 -232.962958)
		(end 73.232264 -232.786936)
		(width 0.18288)
		(layer "In11.Cu")
		(net "M_D_CPU1_SB_DQS_DN<5>")
	)
	(segment
		(start 73.796398 -233.35107)
		(end 73.620376 -233.35107)
		(width 0.18288)
		(layer "In11.Cu")
		(net "M_D_CPU1_SB_DQS_DN<5>")
	)
	(segment
		(start 21.61794 -227.649786)
		(end 21.156168 -227.649786)
		(width 0.18288)
		(layer "In11.Cu")
		(net "M_D_CPU1_SB_DQS_DN<5>")
	)
	(segment
		(start 86.924388 -237.901988)
		(end 86.922864 -237.901226)
		(width 0.088646)
		(layer "In11.Cu")
		(net "M_D_CPU1_SB_DQS_DN<5>")
	)
	(segment
		(start 61.980318 -225.791014)
		(end 61.84646 -225.791014)
		(width 0.18288)
		(layer "In11.Cu")
		(net "M_D_CPU1_SB_DQS_DN<5>")
	)
	(segment
		(start 51.270408 -223.241108)
		(end 50.80254 -223.241108)
		(width 0.18288)
		(layer "In11.Cu")
		(net "M_D_CPU1_SB_DQS_DN<5>")
	)
	(segment
		(start 82.568288 -236.53496)
		(end 82.433414 -236.53496)
		(width 0.088646)
		(layer "In11.Cu")
		(net "M_D_CPU1_SB_DQS_DN<5>")
	)
	(segment
		(start 76.08824 -235.818934)
		(end 76.08824 -235.642912)
		(width 0.18288)
		(layer "In11.Cu")
		(net "M_D_CPU1_SB_DQS_DN<5>")
	)
	(segment
		(start 85.057996 -237.909862)
		(end 85.043264 -237.901226)
		(width 0.088646)
		(layer "In11.Cu")
		(net "M_D_CPU1_SB_DQS_DN<5>")
	)
	(segment
		(start 24.283416 -227.944426)
		(end 21.91258 -227.944426)
		(width 0.18288)
		(layer "In11.Cu")
		(net "M_D_CPU1_SB_DQS_DN<5>")
	)
	(segment
		(start 66.255138 -226.652074)
		(end 66.039238 -226.652074)
		(width 0.16002)
		(layer "In11.Cu")
		(net "M_D_CPU1_SB_DQS_DN<5>")
	)
	(segment
		(start 66.61277 -226.437952)
		(end 66.398648 -226.652074)
		(width 0.18288)
		(layer "In11.Cu")
		(net "M_D_CPU1_SB_DQS_DN<5>")
	)
	(segment
		(start 58.891932 -223.853248)
		(end 56.401462 -223.853248)
		(width 0.18288)
		(layer "In11.Cu")
		(net "M_D_CPU1_SB_DQS_DN<5>")
	)
	(segment
		(start 46.486572 -223.839786)
		(end 45.811948 -223.839786)
		(width 0.18288)
		(layer "In11.Cu")
		(net "M_D_CPU1_SB_DQS_DN<5>")
	)
	(segment
		(start 44.255182 -224.410016)
		(end 43.73372 -223.888554)
		(width 0.18288)
		(layer "In11.Cu")
		(net "M_D_CPU1_SB_DQS_DN<5>")
	)
	(segment
		(start 21.156168 -227.649786)
		(end 20.889214 -227.91674)
		(width 0.18288)
		(layer "In11.Cu")
		(net "M_D_CPU1_SB_DQS_DN<5>")
	)
	(segment
		(start 74.74839 -234.303062)
		(end 74.572368 -234.303062)
		(width 0.18288)
		(layer "In11.Cu")
		(net "M_D_CPU1_SB_DQS_DN<5>")
	)
	(segment
		(start 36.441634 -222.988378)
		(end 36.19119 -223.238822)
		(width 0.18288)
		(layer "In11.Cu")
		(net "M_D_CPU1_SB_DQS_DN<5>")
	)
	(segment
		(start 89.367614 -239.528858)
		(end 89.352882 -239.537494)
		(width 0.088646)
		(layer "In11.Cu")
		(net "M_D_CPU1_SB_DQS_DN<5>")
	)
	(segment
		(start 50.023268 -222.978218)
		(end 49.139348 -223.862138)
		(width 0.18288)
		(layer "In11.Cu")
		(net "M_D_CPU1_SB_DQS_DN<5>")
	)
	(segment
		(start 96.886268 -239.528858)
		(end 96.875854 -239.534954)
		(width 0.088646)
		(layer "In11.Cu")
		(net "M_D_CPU1_SB_DQS_DN<5>")
	)
	(segment
		(start 73.232264 -232.786936)
		(end 66.88328 -226.437952)
		(width 0.18288)
		(layer "In11.Cu")
		(net "M_D_CPU1_SB_DQS_DN<5>")
	)
	(segment
		(start 76.652374 -236.207046)
		(end 76.476352 -236.207046)
		(width 0.18288)
		(layer "In11.Cu")
		(net "M_D_CPU1_SB_DQS_DN<5>")
	)
	(arc
		(start 90.297254 -239.534954)
		(mid 90.018822 -239.6048)
		(end 89.74201 -239.528858)
		(width 0.088646)
		(layer "In11.Cu")
		(net "M_D_CPU1_SB_DQS_DN<5>")
	)
	(arc
		(start 99.690682 -239.537494)
		(mid 99.414207 -239.604814)
		(end 99.14001 -239.528858)
		(width 0.088646)
		(layer "In11.Cu")
		(net "M_D_CPU1_SB_DQS_DN<5>")
	)
	(arc
		(start 99.14001 -239.528858)
		(mid 98.952812 -239.478715)
		(end 98.765614 -239.528858)
		(width 0.088646)
		(layer "In11.Cu")
		(net "M_D_CPU1_SB_DQS_DN<5>")
	)
	(arc
		(start 85.983064 -237.901226)
		(mid 85.795866 -237.851083)
		(end 85.608668 -237.901226)
		(width 0.088646)
		(layer "In11.Cu")
		(net "M_D_CPU1_SB_DQS_DN<5>")
	)
	(arc
		(start 100.26269 -239.796066)
		(mid 100.204571 -239.645825)
		(end 100.0887 -239.533938)
		(width 0.088646)
		(layer "In11.Cu")
		(net "M_D_CPU1_SB_DQS_DN<5>")
	)
	(arc
		(start 91.2368 -239.534954)
		(mid 90.958622 -239.604677)
		(end 90.682064 -239.528858)
		(width 0.088646)
		(layer "In11.Cu")
		(net "M_D_CPU1_SB_DQS_DN<5>")
	)
	(arc
		(start 98.750882 -239.537494)
		(mid 98.474407 -239.604814)
		(end 98.20021 -239.528858)
		(width 0.088646)
		(layer "In11.Cu")
		(net "M_D_CPU1_SB_DQS_DN<5>")
	)
	(arc
		(start 96.32061 -239.528858)
		(mid 96.133412 -239.478715)
		(end 95.946214 -239.528858)
		(width 0.088646)
		(layer "In11.Cu")
		(net "M_D_CPU1_SB_DQS_DN<5>")
	)
	(arc
		(start 86.922864 -237.901226)
		(mid 86.735666 -237.851083)
		(end 86.548468 -237.901226)
		(width 0.088646)
		(layer "In11.Cu")
		(net "M_D_CPU1_SB_DQS_DN<5>")
	)
	(arc
		(start 87.958168 -238.715042)
		(mid 87.675466 -238.790818)
		(end 87.392764 -238.715042)
		(width 0.088646)
		(layer "In11.Cu")
		(net "M_D_CPU1_SB_DQS_DN<5>")
	)
	(arc
		(start 92.172282 -239.537494)
		(mid 91.895807 -239.604814)
		(end 91.62161 -239.528858)
		(width 0.088646)
		(layer "In11.Cu")
		(net "M_D_CPU1_SB_DQS_DN<5>")
	)
	(arc
		(start 88.332564 -238.715042)
		(mid 88.145366 -238.664899)
		(end 87.958168 -238.715042)
		(width 0.088646)
		(layer "In11.Cu")
		(net "M_D_CPU1_SB_DQS_DN<5>")
	)
	(arc
		(start 90.682064 -239.528858)
		(mid 90.494866 -239.478715)
		(end 90.307668 -239.528858)
		(width 0.088646)
		(layer "In11.Cu")
		(net "M_D_CPU1_SB_DQS_DN<5>")
	)
	(arc
		(start 92.56141 -239.528858)
		(mid 92.374212 -239.478715)
		(end 92.187014 -239.528858)
		(width 0.088646)
		(layer "In11.Cu")
		(net "M_D_CPU1_SB_DQS_DN<5>")
	)
	(arc
		(start 84.668868 -237.901226)
		(mid 84.532642 -237.957783)
		(end 84.38642 -237.977172)
		(width 0.088646)
		(layer "In11.Cu")
		(net "M_D_CPU1_SB_DQS_DN<5>")
	)
	(arc
		(start 95.38081 -239.528858)
		(mid 95.193612 -239.478715)
		(end 95.006414 -239.528858)
		(width 0.088646)
		(layer "In11.Cu")
		(net "M_D_CPU1_SB_DQS_DN<5>")
	)
	(arc
		(start 85.043264 -237.901226)
		(mid 84.856066 -237.851083)
		(end 84.668868 -237.901226)
		(width 0.088646)
		(layer "In11.Cu")
		(net "M_D_CPU1_SB_DQS_DN<5>")
	)
	(arc
		(start 97.8154 -239.534954)
		(mid 97.537222 -239.604677)
		(end 97.260664 -239.528858)
		(width 0.088646)
		(layer "In11.Cu")
		(net "M_D_CPU1_SB_DQS_DN<5>")
	)
	(arc
		(start 88.520016 -239.0394)
		(mid 88.472337 -238.8565)
		(end 88.341454 -238.720122)
		(width 0.088646)
		(layer "In11.Cu")
		(net "M_D_CPU1_SB_DQS_DN<5>")
	)
	(arc
		(start 85.608668 -237.901226)
		(mid 85.334469 -237.977061)
		(end 85.057996 -237.909862)
		(width 0.088646)
		(layer "In11.Cu")
		(net "M_D_CPU1_SB_DQS_DN<5>")
	)
	(arc
		(start 95.931482 -239.537494)
		(mid 95.655007 -239.604814)
		(end 95.38081 -239.528858)
		(width 0.088646)
		(layer "In11.Cu")
		(net "M_D_CPU1_SB_DQS_DN<5>")
	)
	(arc
		(start 87.392764 -238.715042)
		(mid 87.188429 -238.512437)
		(end 87.110316 -238.23549)
		(width 0.088646)
		(layer "In11.Cu")
		(net "M_D_CPU1_SB_DQS_DN<5>")
	)
	(arc
		(start 89.74201 -239.528858)
		(mid 89.554812 -239.478715)
		(end 89.367614 -239.528858)
		(width 0.088646)
		(layer "In11.Cu")
		(net "M_D_CPU1_SB_DQS_DN<5>")
	)
	(arc
		(start 91.62161 -239.528858)
		(mid 91.434412 -239.478715)
		(end 91.247214 -239.528858)
		(width 0.088646)
		(layer "In11.Cu")
		(net "M_D_CPU1_SB_DQS_DN<5>")
	)
	(arc
		(start 86.548468 -237.901226)
		(mid 86.265766 -237.977002)
		(end 85.983064 -237.901226)
		(width 0.088646)
		(layer "In11.Cu")
		(net "M_D_CPU1_SB_DQS_DN<5>")
	)
	(arc
		(start 98.20021 -239.528858)
		(mid 98.013012 -239.478715)
		(end 97.825814 -239.528858)
		(width 0.088646)
		(layer "In11.Cu")
		(net "M_D_CPU1_SB_DQS_DN<5>")
	)
	(arc
		(start 97.260664 -239.528858)
		(mid 97.073466 -239.478715)
		(end 96.886268 -239.528858)
		(width 0.088646)
		(layer "In11.Cu")
		(net "M_D_CPU1_SB_DQS_DN<5>")
	)
	(arc
		(start 88.80221 -239.528858)
		(mid 88.599387 -239.328627)
		(end 88.520016 -239.054894)
		(width 0.088646)
		(layer "In11.Cu")
		(net "M_D_CPU1_SB_DQS_DN<5>")
	)
	(arc
		(start 94.44101 -239.528858)
		(mid 94.253812 -239.478715)
		(end 94.066614 -239.528858)
		(width 0.088646)
		(layer "In11.Cu")
		(net "M_D_CPU1_SB_DQS_DN<5>")
	)
	(arc
		(start 96.875854 -239.534954)
		(mid 96.597422 -239.6048)
		(end 96.32061 -239.528858)
		(width 0.088646)
		(layer "In11.Cu")
		(net "M_D_CPU1_SB_DQS_DN<5>")
	)
	(arc
		(start 95.006414 -239.528858)
		(mid 94.723712 -239.604634)
		(end 94.44101 -239.528858)
		(width 0.088646)
		(layer "In11.Cu")
		(net "M_D_CPU1_SB_DQS_DN<5>")
	)
	(arc
		(start 93.50121 -239.528858)
		(mid 93.314012 -239.478715)
		(end 93.126814 -239.528858)
		(width 0.088646)
		(layer "In11.Cu")
		(net "M_D_CPU1_SB_DQS_DN<5>")
	)
	(arc
		(start 94.051882 -239.537494)
		(mid 93.775407 -239.604814)
		(end 93.50121 -239.528858)
		(width 0.088646)
		(layer "In11.Cu")
		(net "M_D_CPU1_SB_DQS_DN<5>")
	)
	(arc
		(start 93.112082 -239.537494)
		(mid 92.835607 -239.604814)
		(end 92.56141 -239.528858)
		(width 0.088646)
		(layer "In11.Cu")
		(net "M_D_CPU1_SB_DQS_DN<5>")
	)
	(arc
		(start 87.110316 -238.225584)
		(mid 87.062637 -238.042684)
		(end 86.931754 -237.906306)
		(width 0.088646)
		(layer "In11.Cu")
		(net "M_D_CPU1_SB_DQS_DN<5>")
	)
	(arc
		(start 100.07981 -239.528858)
		(mid 99.892612 -239.478715)
		(end 99.705414 -239.528858)
		(width 0.088646)
		(layer "In11.Cu")
		(net "M_D_CPU1_SB_DQS_DN<5>")
	)
	(arc
		(start 89.352882 -239.537494)
		(mid 89.076407 -239.604814)
		(end 88.80221 -239.528858)
		(width 0.088646)
		(layer "In11.Cu")
		(net "M_D_CPU1_SB_DQS_DN<5>")
	)
	(segment
		(start 13.868908 -236.58322)
		(end 13.446506 -237.005622)
		(width 0.20066)
		(layer "F.Cu")
		(net "M_D_CPU1_SB_DQS_DN<4>")
	)
	(segment
		(start 12.973304 -237.005622)
		(end 12.712192 -237.266734)
		(width 0.20066)
		(layer "F.Cu")
		(net "M_D_CPU1_SB_DQS_DN<4>")
	)
	(segment
		(start 100.832412 -245.272306)
		(end 100.832412 -244.73662)
		(width 0.20066)
		(layer "F.Cu")
		(net "M_D_CPU1_SB_DQS_DN<4>")
	)
	(segment
		(start 17.693132 -236.58068)
		(end 17.28851 -236.58068)
		(width 0.20066)
		(layer "F.Cu")
		(net "M_D_CPU1_SB_DQS_DN<4>")
	)
	(segment
		(start 17.027398 -236.841792)
		(end 16.885158 -236.841792)
		(width 0.20066)
		(layer "F.Cu")
		(net "M_D_CPU1_SB_DQS_DN<4>")
	)
	(segment
		(start 13.446506 -237.005622)
		(end 12.973304 -237.005622)
		(width 0.20066)
		(layer "F.Cu")
		(net "M_D_CPU1_SB_DQS_DN<4>")
	)
	(segment
		(start 12.712192 -237.266734)
		(end 12.240514 -237.266734)
		(width 0.20066)
		(layer "F.Cu")
		(net "M_D_CPU1_SB_DQS_DN<4>")
	)
	(segment
		(start 14.37513 -236.849666)
		(end 14.108684 -236.58322)
		(width 0.20066)
		(layer "F.Cu")
		(net "M_D_CPU1_SB_DQS_DN<4>")
	)
	(segment
		(start 100.832666 -245.27256)
		(end 100.832412 -245.272306)
		(width 0.20066)
		(layer "F.Cu")
		(net "M_D_CPU1_SB_DQS_DN<4>")
	)
	(segment
		(start 16.885158 -236.841792)
		(end 14.807692 -236.841792)
		(width 0.1016)
		(layer "F.Cu")
		(net "M_D_CPU1_SB_DQS_DN<4>")
	)
	(segment
		(start 14.108684 -236.58322)
		(end 13.868908 -236.58322)
		(width 0.20066)
		(layer "F.Cu")
		(net "M_D_CPU1_SB_DQS_DN<4>")
	)
	(segment
		(start 14.807692 -236.841792)
		(end 14.567916 -236.841792)
		(width 0.101854)
		(layer "F.Cu")
		(net "M_D_CPU1_SB_DQS_DN<4>")
	)
	(segment
		(start 19.29384 -237.266734)
		(end 19.032728 -237.005622)
		(width 0.20066)
		(layer "F.Cu")
		(net "M_D_CPU1_SB_DQS_DN<4>")
	)
	(segment
		(start 18.329148 -237.005622)
		(end 17.693132 -236.58068)
		(width 0.20066)
		(layer "F.Cu")
		(net "M_D_CPU1_SB_DQS_DN<4>")
	)
	(segment
		(start 14.567916 -236.841792)
		(end 14.560042 -236.849666)
		(width 0.101854)
		(layer "F.Cu")
		(net "M_D_CPU1_SB_DQS_DN<4>")
	)
	(segment
		(start 20.889214 -237.266734)
		(end 19.784314 -237.266734)
		(width 0.20066)
		(layer "F.Cu")
		(net "M_D_CPU1_SB_DQS_DN<4>")
	)
	(segment
		(start 19.784314 -237.266734)
		(end 19.29384 -237.266734)
		(width 0.20066)
		(layer "F.Cu")
		(net "M_D_CPU1_SB_DQS_DN<4>")
	)
	(segment
		(start 14.560042 -236.849666)
		(end 14.37513 -236.849666)
		(width 0.20066)
		(layer "F.Cu")
		(net "M_D_CPU1_SB_DQS_DN<4>")
	)
	(segment
		(start 19.032728 -237.005622)
		(end 18.329148 -237.005622)
		(width 0.20066)
		(layer "F.Cu")
		(net "M_D_CPU1_SB_DQS_DN<4>")
	)
	(segment
		(start 17.28851 -236.58068)
		(end 17.027398 -236.841792)
		(width 0.20066)
		(layer "F.Cu")
		(net "M_D_CPU1_SB_DQS_DN<4>")
	)
	(segment
		(start 31.38551 -236.59719)
		(end 30.74035 -236.59719)
		(width 0.18288)
		(layer "In11.Cu")
		(net "M_D_CPU1_SB_DQS_DN<4>")
	)
	(segment
		(start 46.507146 -236.5756)
		(end 45.212 -236.5756)
		(width 0.18288)
		(layer "In11.Cu")
		(net "M_D_CPU1_SB_DQS_DN<4>")
	)
	(segment
		(start 35.451288 -235.694982)
		(end 34.741358 -235.694982)
		(width 0.18288)
		(layer "In11.Cu")
		(net "M_D_CPU1_SB_DQS_DN<4>")
	)
	(segment
		(start 72.04456 -242.697762)
		(end 67.28587 -237.939072)
		(width 0.18288)
		(layer "In11.Cu")
		(net "M_D_CPU1_SB_DQS_DN<4>")
	)
	(segment
		(start 91.247214 -244.412262)
		(end 91.2368 -244.418358)
		(width 0.088646)
		(layer "In11.Cu")
		(net "M_D_CPU1_SB_DQS_DN<4>")
	)
	(segment
		(start 82.331814 -242.697762)
		(end 72.04456 -242.697762)
		(width 0.18288)
		(layer "In11.Cu")
		(net "M_D_CPU1_SB_DQS_DN<4>")
	)
	(segment
		(start 65.7606 -237.630462)
		(end 64.57442 -236.836712)
		(width 0.18288)
		(layer "In11.Cu")
		(net "M_D_CPU1_SB_DQS_DN<4>")
	)
	(segment
		(start 21.159978 -236.99597)
		(end 20.889214 -237.266734)
		(width 0.18288)
		(layer "In11.Cu")
		(net "M_D_CPU1_SB_DQS_DN<4>")
	)
	(segment
		(start 44.93387 -236.85373)
		(end 44.575476 -236.85373)
		(width 0.18288)
		(layer "In11.Cu")
		(net "M_D_CPU1_SB_DQS_DN<4>")
	)
	(segment
		(start 95.946214 -244.412262)
		(end 95.931482 -244.420898)
		(width 0.088646)
		(layer "In11.Cu")
		(net "M_D_CPU1_SB_DQS_DN<4>")
	)
	(segment
		(start 89.367614 -244.412262)
		(end 89.352882 -244.420898)
		(width 0.088646)
		(layer "In11.Cu")
		(net "M_D_CPU1_SB_DQS_DN<4>")
	)
	(segment
		(start 60.6044 -235.975906)
		(end 60.345574 -235.71708)
		(width 0.18288)
		(layer "In11.Cu")
		(net "M_D_CPU1_SB_DQS_DN<4>")
	)
	(segment
		(start 60.345574 -235.71708)
		(end 59.27725 -235.71708)
		(width 0.18288)
		(layer "In11.Cu")
		(net "M_D_CPU1_SB_DQS_DN<4>")
	)
	(segment
		(start 25.362916 -237.564422)
		(end 24.703024 -237.291118)
		(width 0.18288)
		(layer "In11.Cu")
		(net "M_D_CPU1_SB_DQS_DN<4>")
	)
	(segment
		(start 49.087278 -236.557566)
		(end 47.432976 -236.557566)
		(width 0.18288)
		(layer "In11.Cu")
		(net "M_D_CPU1_SB_DQS_DN<4>")
	)
	(segment
		(start 50.59807 -235.716826)
		(end 49.928018 -235.716826)
		(width 0.18288)
		(layer "In11.Cu")
		(net "M_D_CPU1_SB_DQS_DN<4>")
	)
	(segment
		(start 41.105836 -236.549438)
		(end 40.27297 -235.716572)
		(width 0.18288)
		(layer "In11.Cu")
		(net "M_D_CPU1_SB_DQS_DN<4>")
	)
	(segment
		(start 32.418274 -236.562392)
		(end 32.137858 -236.842808)
		(width 0.18288)
		(layer "In11.Cu")
		(net "M_D_CPU1_SB_DQS_DN<4>")
	)
	(segment
		(start 99.327462 -244.750844)
		(end 99.327462 -244.73662)
		(width 0.088646)
		(layer "In11.Cu")
		(net "M_D_CPU1_SB_DQS_DN<4>")
	)
	(segment
		(start 67.28587 -237.939072)
		(end 66.542666 -237.630462)
		(width 0.18288)
		(layer "In11.Cu")
		(net "M_D_CPU1_SB_DQS_DN<4>")
	)
	(segment
		(start 98.765614 -244.412262)
		(end 98.750882 -244.420898)
		(width 0.088646)
		(layer "In11.Cu")
		(net "M_D_CPU1_SB_DQS_DN<4>")
	)
	(segment
		(start 35.747452 -235.991146)
		(end 35.451288 -235.694982)
		(width 0.18288)
		(layer "In11.Cu")
		(net "M_D_CPU1_SB_DQS_DN<4>")
	)
	(segment
		(start 44.271184 -236.549438)
		(end 41.105836 -236.549438)
		(width 0.18288)
		(layer "In11.Cu")
		(net "M_D_CPU1_SB_DQS_DN<4>")
	)
	(segment
		(start 44.575476 -236.85373)
		(end 44.271184 -236.549438)
		(width 0.18288)
		(layer "In11.Cu")
		(net "M_D_CPU1_SB_DQS_DN<4>")
	)
	(segment
		(start 58.972704 -236.021626)
		(end 58.64987 -236.021626)
		(width 0.18288)
		(layer "In11.Cu")
		(net "M_D_CPU1_SB_DQS_DN<4>")
	)
	(segment
		(start 92.187268 -244.412262)
		(end 92.176854 -244.418358)
		(width 0.088646)
		(layer "In11.Cu")
		(net "M_D_CPU1_SB_DQS_DN<4>")
	)
	(segment
		(start 56.67502 -236.341666)
		(end 55.805832 -236.341666)
		(width 0.18288)
		(layer "In11.Cu")
		(net "M_D_CPU1_SB_DQS_DN<4>")
	)
	(segment
		(start 58.64987 -236.021626)
		(end 58.341006 -235.712762)
		(width 0.18288)
		(layer "In11.Cu")
		(net "M_D_CPU1_SB_DQS_DN<4>")
	)
	(segment
		(start 57.303924 -235.712762)
		(end 56.67502 -236.341666)
		(width 0.18288)
		(layer "In11.Cu")
		(net "M_D_CPU1_SB_DQS_DN<4>")
	)
	(segment
		(start 58.341006 -235.712762)
		(end 57.303924 -235.712762)
		(width 0.18288)
		(layer "In11.Cu")
		(net "M_D_CPU1_SB_DQS_DN<4>")
	)
	(segment
		(start 29.773118 -237.564422)
		(end 25.362916 -237.564422)
		(width 0.18288)
		(layer "In11.Cu")
		(net "M_D_CPU1_SB_DQS_DN<4>")
	)
	(segment
		(start 24.703024 -237.291118)
		(end 21.91258 -237.291118)
		(width 0.18288)
		(layer "In11.Cu")
		(net "M_D_CPU1_SB_DQS_DN<4>")
	)
	(segment
		(start 99.624896 -245.234968)
		(end 99.610164 -245.226332)
		(width 0.088646)
		(layer "In11.Cu")
		(net "M_D_CPU1_SB_DQS_DN<4>")
	)
	(segment
		(start 66.542666 -237.630462)
		(end 65.7606 -237.630462)
		(width 0.18288)
		(layer "In11.Cu")
		(net "M_D_CPU1_SB_DQS_DN<4>")
	)
	(segment
		(start 90.307668 -244.412262)
		(end 90.297254 -244.418358)
		(width 0.088646)
		(layer "In11.Cu")
		(net "M_D_CPU1_SB_DQS_DN<4>")
	)
	(segment
		(start 30.74035 -236.59719)
		(end 29.773118 -237.564422)
		(width 0.18288)
		(layer "In11.Cu")
		(net "M_D_CPU1_SB_DQS_DN<4>")
	)
	(segment
		(start 88.427814 -244.412262)
		(end 88.413082 -244.420898)
		(width 0.088646)
		(layer "In11.Cu")
		(net "M_D_CPU1_SB_DQS_DN<4>")
	)
	(segment
		(start 59.27725 -235.71708)
		(end 58.972704 -236.021626)
		(width 0.18288)
		(layer "In11.Cu")
		(net "M_D_CPU1_SB_DQS_DN<4>")
	)
	(segment
		(start 84.390738 -243.674138)
		(end 83.926934 -243.210334)
		(width 0.088646)
		(layer "In11.Cu")
		(net "M_D_CPU1_SB_DQS_DN<4>")
	)
	(segment
		(start 21.617432 -236.99597)
		(end 21.159978 -236.99597)
		(width 0.18288)
		(layer "In11.Cu")
		(net "M_D_CPU1_SB_DQS_DN<4>")
	)
	(segment
		(start 97.825814 -244.412262)
		(end 97.8154 -244.418358)
		(width 0.088646)
		(layer "In11.Cu")
		(net "M_D_CPU1_SB_DQS_DN<4>")
	)
	(segment
		(start 51.264312 -235.991908)
		(end 50.873152 -235.991908)
		(width 0.18288)
		(layer "In11.Cu")
		(net "M_D_CPU1_SB_DQS_DN<4>")
	)
	(segment
		(start 83.73364 -243.210334)
		(end 83.673696 -243.270278)
		(width 0.088646)
		(layer "In11.Cu")
		(net "M_D_CPU1_SB_DQS_DN<4>")
	)
	(segment
		(start 50.873152 -235.991908)
		(end 50.59807 -235.716826)
		(width 0.18288)
		(layer "In11.Cu")
		(net "M_D_CPU1_SB_DQS_DN<4>")
	)
	(segment
		(start 64.57442 -236.836712)
		(end 62.50305 -235.975906)
		(width 0.18288)
		(layer "In11.Cu")
		(net "M_D_CPU1_SB_DQS_DN<4>")
	)
	(segment
		(start 84.856066 -243.674138)
		(end 84.390738 -243.674138)
		(width 0.088646)
		(layer "In11.Cu")
		(net "M_D_CPU1_SB_DQS_DN<4>")
	)
	(segment
		(start 55.805832 -236.341666)
		(end 55.167784 -235.703618)
		(width 0.18288)
		(layer "In11.Cu")
		(net "M_D_CPU1_SB_DQS_DN<4>")
	)
	(segment
		(start 34.741358 -235.694982)
		(end 33.873948 -236.562392)
		(width 0.18288)
		(layer "In11.Cu")
		(net "M_D_CPU1_SB_DQS_DN<4>")
	)
	(segment
		(start 100.832412 -244.73662)
		(end 100.519484 -244.73662)
		(width 0.088646)
		(layer "In11.Cu")
		(net "M_D_CPU1_SB_DQS_DN<4>")
	)
	(segment
		(start 85.700362 -243.93271)
		(end 85.700362 -243.922804)
		(width 0.088646)
		(layer "In11.Cu")
		(net "M_D_CPU1_SB_DQS_DN<4>")
	)
	(segment
		(start 40.27297 -235.716572)
		(end 36.438586 -235.716572)
		(width 0.18288)
		(layer "In11.Cu")
		(net "M_D_CPU1_SB_DQS_DN<4>")
	)
	(segment
		(start 47.432976 -236.557566)
		(end 47.147734 -236.842808)
		(width 0.18288)
		(layer "In11.Cu")
		(net "M_D_CPU1_SB_DQS_DN<4>")
	)
	(segment
		(start 47.147734 -236.842808)
		(end 46.774354 -236.842808)
		(width 0.18288)
		(layer "In11.Cu")
		(net "M_D_CPU1_SB_DQS_DN<4>")
	)
	(segment
		(start 100.519484 -244.73662)
		(end 100.45446 -244.801644)
		(width 0.088646)
		(layer "In11.Cu")
		(net "M_D_CPU1_SB_DQS_DN<4>")
	)
	(segment
		(start 96.886268 -244.412262)
		(end 96.875854 -244.418358)
		(width 0.088646)
		(layer "In11.Cu")
		(net "M_D_CPU1_SB_DQS_DN<4>")
	)
	(segment
		(start 46.774354 -236.842808)
		(end 46.507146 -236.5756)
		(width 0.18288)
		(layer "In11.Cu")
		(net "M_D_CPU1_SB_DQS_DN<4>")
	)
	(segment
		(start 33.873948 -236.562392)
		(end 32.418274 -236.562392)
		(width 0.18288)
		(layer "In11.Cu")
		(net "M_D_CPU1_SB_DQS_DN<4>")
	)
	(segment
		(start 49.928018 -235.716826)
		(end 49.087278 -236.557566)
		(width 0.18288)
		(layer "In11.Cu")
		(net "M_D_CPU1_SB_DQS_DN<4>")
	)
	(segment
		(start 62.50305 -235.975906)
		(end 60.6044 -235.975906)
		(width 0.18288)
		(layer "In11.Cu")
		(net "M_D_CPU1_SB_DQS_DN<4>")
	)
	(segment
		(start 82.90433 -243.270278)
		(end 82.331814 -242.697762)
		(width 0.18288)
		(layer "In11.Cu")
		(net "M_D_CPU1_SB_DQS_DN<4>")
	)
	(segment
		(start 99.1489 -244.417342)
		(end 99.14001 -244.412262)
		(width 0.088646)
		(layer "In11.Cu")
		(net "M_D_CPU1_SB_DQS_DN<4>")
	)
	(segment
		(start 94.066614 -244.412262)
		(end 94.051882 -244.420898)
		(width 0.088646)
		(layer "In11.Cu")
		(net "M_D_CPU1_SB_DQS_DN<4>")
	)
	(segment
		(start 93.126814 -244.412262)
		(end 93.1164 -244.418358)
		(width 0.088646)
		(layer "In11.Cu")
		(net "M_D_CPU1_SB_DQS_DN<4>")
	)
	(segment
		(start 36.164012 -235.991146)
		(end 35.747452 -235.991146)
		(width 0.18288)
		(layer "In11.Cu")
		(net "M_D_CPU1_SB_DQS_DN<4>")
	)
	(segment
		(start 32.137858 -236.842808)
		(end 31.631128 -236.842808)
		(width 0.18288)
		(layer "In11.Cu")
		(net "M_D_CPU1_SB_DQS_DN<4>")
	)
	(segment
		(start 36.438586 -235.716572)
		(end 36.164012 -235.991146)
		(width 0.18288)
		(layer "In11.Cu")
		(net "M_D_CPU1_SB_DQS_DN<4>")
	)
	(segment
		(start 55.167784 -235.703618)
		(end 51.552602 -235.703618)
		(width 0.18288)
		(layer "In11.Cu")
		(net "M_D_CPU1_SB_DQS_DN<4>")
	)
	(segment
		(start 83.673696 -243.270278)
		(end 82.90433 -243.270278)
		(width 0.18288)
		(layer "In11.Cu")
		(net "M_D_CPU1_SB_DQS_DN<4>")
	)
	(segment
		(start 51.552602 -235.703618)
		(end 51.264312 -235.991908)
		(width 0.18288)
		(layer "In11.Cu")
		(net "M_D_CPU1_SB_DQS_DN<4>")
	)
	(segment
		(start 83.926934 -243.210334)
		(end 83.73364 -243.210334)
		(width 0.088646)
		(layer "In11.Cu")
		(net "M_D_CPU1_SB_DQS_DN<4>")
	)
	(segment
		(start 45.212 -236.5756)
		(end 44.93387 -236.85373)
		(width 0.18288)
		(layer "In11.Cu")
		(net "M_D_CPU1_SB_DQS_DN<4>")
	)
	(segment
		(start 21.91258 -237.291118)
		(end 21.617432 -236.99597)
		(width 0.18288)
		(layer "In11.Cu")
		(net "M_D_CPU1_SB_DQS_DN<4>")
	)
	(segment
		(start 31.631128 -236.842808)
		(end 31.38551 -236.59719)
		(width 0.18288)
		(layer "In11.Cu")
		(net "M_D_CPU1_SB_DQS_DN<4>")
	)
	(arc
		(start 94.44101 -244.412262)
		(mid 94.253812 -244.362119)
		(end 94.066614 -244.412262)
		(width 0.088646)
		(layer "In11.Cu")
		(net "M_D_CPU1_SB_DQS_DN<4>")
	)
	(arc
		(start 97.260664 -244.412262)
		(mid 97.073466 -244.362119)
		(end 96.886268 -244.412262)
		(width 0.088646)
		(layer "In11.Cu")
		(net "M_D_CPU1_SB_DQS_DN<4>")
	)
	(arc
		(start 95.006414 -244.412262)
		(mid 94.723712 -244.488038)
		(end 94.44101 -244.412262)
		(width 0.088646)
		(layer "In11.Cu")
		(net "M_D_CPU1_SB_DQS_DN<4>")
	)
	(arc
		(start 94.051882 -244.420898)
		(mid 93.775407 -244.488218)
		(end 93.50121 -244.412262)
		(width 0.088646)
		(layer "In11.Cu")
		(net "M_D_CPU1_SB_DQS_DN<4>")
	)
	(arc
		(start 93.1164 -244.418358)
		(mid 92.838222 -244.488081)
		(end 92.561664 -244.412262)
		(width 0.088646)
		(layer "In11.Cu")
		(net "M_D_CPU1_SB_DQS_DN<4>")
	)
	(arc
		(start 90.682064 -244.412262)
		(mid 90.494866 -244.362119)
		(end 90.307668 -244.412262)
		(width 0.088646)
		(layer "In11.Cu")
		(net "M_D_CPU1_SB_DQS_DN<4>")
	)
	(arc
		(start 88.413082 -244.420898)
		(mid 88.136607 -244.488218)
		(end 87.86241 -244.412262)
		(width 0.088646)
		(layer "In11.Cu")
		(net "M_D_CPU1_SB_DQS_DN<4>")
	)
	(arc
		(start 86.548214 -244.412262)
		(mid 86.265512 -244.488038)
		(end 85.98281 -244.412262)
		(width 0.088646)
		(layer "In11.Cu")
		(net "M_D_CPU1_SB_DQS_DN<4>")
	)
	(arc
		(start 99.14001 -244.412262)
		(mid 98.952812 -244.362119)
		(end 98.765614 -244.412262)
		(width 0.088646)
		(layer "In11.Cu")
		(net "M_D_CPU1_SB_DQS_DN<4>")
	)
	(arc
		(start 97.8154 -244.418358)
		(mid 97.537222 -244.488081)
		(end 97.260664 -244.412262)
		(width 0.088646)
		(layer "In11.Cu")
		(net "M_D_CPU1_SB_DQS_DN<4>")
	)
	(arc
		(start 87.86241 -244.412262)
		(mid 87.675212 -244.362119)
		(end 87.488014 -244.412262)
		(width 0.088646)
		(layer "In11.Cu")
		(net "M_D_CPU1_SB_DQS_DN<4>")
	)
	(arc
		(start 85.700362 -243.922804)
		(mid 85.513063 -243.598363)
		(end 85.138514 -243.598446)
		(width 0.088646)
		(layer "In11.Cu")
		(net "M_D_CPU1_SB_DQS_DN<4>")
	)
	(arc
		(start 91.2368 -244.418358)
		(mid 90.958622 -244.488081)
		(end 90.682064 -244.412262)
		(width 0.088646)
		(layer "In11.Cu")
		(net "M_D_CPU1_SB_DQS_DN<4>")
	)
	(arc
		(start 96.32061 -244.412262)
		(mid 96.133412 -244.362119)
		(end 95.946214 -244.412262)
		(width 0.088646)
		(layer "In11.Cu")
		(net "M_D_CPU1_SB_DQS_DN<4>")
	)
	(arc
		(start 98.20021 -244.412262)
		(mid 98.013012 -244.362119)
		(end 97.825814 -244.412262)
		(width 0.088646)
		(layer "In11.Cu")
		(net "M_D_CPU1_SB_DQS_DN<4>")
	)
	(arc
		(start 99.327462 -244.73662)
		(mid 99.279783 -244.55372)
		(end 99.1489 -244.417342)
		(width 0.088646)
		(layer "In11.Cu")
		(net "M_D_CPU1_SB_DQS_DN<4>")
	)
	(arc
		(start 98.750882 -244.420898)
		(mid 98.474407 -244.488218)
		(end 98.20021 -244.412262)
		(width 0.088646)
		(layer "In11.Cu")
		(net "M_D_CPU1_SB_DQS_DN<4>")
	)
	(arc
		(start 95.931482 -244.420898)
		(mid 95.655007 -244.488218)
		(end 95.38081 -244.412262)
		(width 0.088646)
		(layer "In11.Cu")
		(net "M_D_CPU1_SB_DQS_DN<4>")
	)
	(arc
		(start 91.62161 -244.412262)
		(mid 91.434412 -244.362119)
		(end 91.247214 -244.412262)
		(width 0.088646)
		(layer "In11.Cu")
		(net "M_D_CPU1_SB_DQS_DN<4>")
	)
	(arc
		(start 92.561664 -244.412262)
		(mid 92.374466 -244.362119)
		(end 92.187268 -244.412262)
		(width 0.088646)
		(layer "In11.Cu")
		(net "M_D_CPU1_SB_DQS_DN<4>")
	)
	(arc
		(start 86.92261 -244.412262)
		(mid 86.735412 -244.362119)
		(end 86.548214 -244.412262)
		(width 0.088646)
		(layer "In11.Cu")
		(net "M_D_CPU1_SB_DQS_DN<4>")
	)
	(arc
		(start 85.138514 -243.598446)
		(mid 85.002272 -243.65488)
		(end 84.856066 -243.674138)
		(width 0.088646)
		(layer "In11.Cu")
		(net "M_D_CPU1_SB_DQS_DN<4>")
	)
	(arc
		(start 96.875854 -244.418358)
		(mid 96.597422 -244.488204)
		(end 96.32061 -244.412262)
		(width 0.088646)
		(layer "In11.Cu")
		(net "M_D_CPU1_SB_DQS_DN<4>")
	)
	(arc
		(start 88.80221 -244.412262)
		(mid 88.615012 -244.362119)
		(end 88.427814 -244.412262)
		(width 0.088646)
		(layer "In11.Cu")
		(net "M_D_CPU1_SB_DQS_DN<4>")
	)
	(arc
		(start 99.610164 -245.226332)
		(mid 99.406683 -245.025528)
		(end 99.327462 -244.750844)
		(width 0.088646)
		(layer "In11.Cu")
		(net "M_D_CPU1_SB_DQS_DN<4>")
	)
	(arc
		(start 89.352882 -244.420898)
		(mid 89.076407 -244.488218)
		(end 88.80221 -244.412262)
		(width 0.088646)
		(layer "In11.Cu")
		(net "M_D_CPU1_SB_DQS_DN<4>")
	)
	(arc
		(start 89.74201 -244.412262)
		(mid 89.554812 -244.362119)
		(end 89.367614 -244.412262)
		(width 0.088646)
		(layer "In11.Cu")
		(net "M_D_CPU1_SB_DQS_DN<4>")
	)
	(arc
		(start 100.45446 -244.801644)
		(mid 100.453165 -244.812325)
		(end 100.451666 -244.82298)
		(width 0.088646)
		(layer "In11.Cu")
		(net "M_D_CPU1_SB_DQS_DN<4>")
	)
	(arc
		(start 92.176854 -244.418358)
		(mid 91.898422 -244.488204)
		(end 91.62161 -244.412262)
		(width 0.088646)
		(layer "In11.Cu")
		(net "M_D_CPU1_SB_DQS_DN<4>")
	)
	(arc
		(start 85.98281 -244.412262)
		(mid 85.778475 -244.209657)
		(end 85.700362 -243.93271)
		(width 0.088646)
		(layer "In11.Cu")
		(net "M_D_CPU1_SB_DQS_DN<4>")
	)
	(arc
		(start 90.297254 -244.418358)
		(mid 90.018822 -244.488204)
		(end 89.74201 -244.412262)
		(width 0.088646)
		(layer "In11.Cu")
		(net "M_D_CPU1_SB_DQS_DN<4>")
	)
	(arc
		(start 95.38081 -244.412262)
		(mid 95.193612 -244.362119)
		(end 95.006414 -244.412262)
		(width 0.088646)
		(layer "In11.Cu")
		(net "M_D_CPU1_SB_DQS_DN<4>")
	)
	(arc
		(start 100.175568 -245.226332)
		(mid 99.901339 -245.302257)
		(end 99.624896 -245.234968)
		(width 0.088646)
		(layer "In11.Cu")
		(net "M_D_CPU1_SB_DQS_DN<4>")
	)
	(arc
		(start 100.451666 -244.82298)
		(mid 100.359472 -245.056059)
		(end 100.175568 -245.226332)
		(width 0.088646)
		(layer "In11.Cu")
		(net "M_D_CPU1_SB_DQS_DN<4>")
	)
	(arc
		(start 87.488014 -244.412262)
		(mid 87.205312 -244.488038)
		(end 86.92261 -244.412262)
		(width 0.088646)
		(layer "In11.Cu")
		(net "M_D_CPU1_SB_DQS_DN<4>")
	)
	(arc
		(start 93.50121 -244.412262)
		(mid 93.314012 -244.362119)
		(end 93.126814 -244.412262)
		(width 0.088646)
		(layer "In11.Cu")
		(net "M_D_CPU1_SB_DQS_DN<4>")
	)
	(segment
		(start 98.013266 -230.622602)
		(end 98.013012 -230.622348)
		(width 0.20066)
		(layer "F.Cu")
		(net "M_D_CPU1_SB_DQS_DN<3>")
	)
	(segment
		(start 10.912094 -200.281032)
		(end 10.64006 -200.553066)
		(width 0.20066)
		(layer "F.Cu")
		(net "M_D_CPU1_SB_DQS_DN<3>")
	)
	(segment
		(start 14.876526 -200.12787)
		(end 14.469872 -200.12787)
		(width 0.20066)
		(layer "F.Cu")
		(net "M_D_CPU1_SB_DQS_DN<3>")
	)
	(segment
		(start 8.950198 -200.12787)
		(end 8.689086 -199.866758)
		(width 0.20066)
		(layer "F.Cu")
		(net "M_D_CPU1_SB_DQS_DN<3>")
	)
	(segment
		(start 15.137638 -199.866758)
		(end 14.876526 -200.12787)
		(width 0.20066)
		(layer "F.Cu")
		(net "M_D_CPU1_SB_DQS_DN<3>")
	)
	(segment
		(start 9.46404 -200.12787)
		(end 8.950198 -200.12787)
		(width 0.20066)
		(layer "F.Cu")
		(net "M_D_CPU1_SB_DQS_DN<3>")
	)
	(segment
		(start 14.469872 -200.12787)
		(end 14.044676 -200.553066)
		(width 0.20066)
		(layer "F.Cu")
		(net "M_D_CPU1_SB_DQS_DN<3>")
	)
	(segment
		(start 13.59662 -200.2917)
		(end 13.441426 -200.2917)
		(width 0.20066)
		(layer "F.Cu")
		(net "M_D_CPU1_SB_DQS_DN<3>")
	)
	(segment
		(start 13.441426 -200.2917)
		(end 11.12774 -200.2917)
		(width 0.1016)
		(layer "F.Cu")
		(net "M_D_CPU1_SB_DQS_DN<3>")
	)
	(segment
		(start 11.117072 -200.281032)
		(end 11.11631 -200.281032)
		(width 0.101854)
		(layer "F.Cu")
		(net "M_D_CPU1_SB_DQS_DN<3>")
	)
	(segment
		(start 13.857986 -200.553066)
		(end 13.59662 -200.2917)
		(width 0.20066)
		(layer "F.Cu")
		(net "M_D_CPU1_SB_DQS_DN<3>")
	)
	(segment
		(start 98.013012 -230.622348)
		(end 98.013012 -230.086662)
		(width 0.20066)
		(layer "F.Cu")
		(net "M_D_CPU1_SB_DQS_DN<3>")
	)
	(segment
		(start 16.789146 -199.866758)
		(end 15.684246 -199.866758)
		(width 0.20066)
		(layer "F.Cu")
		(net "M_D_CPU1_SB_DQS_DN<3>")
	)
	(segment
		(start 11.11631 -200.281032)
		(end 10.912094 -200.281032)
		(width 0.20066)
		(layer "F.Cu")
		(net "M_D_CPU1_SB_DQS_DN<3>")
	)
	(segment
		(start 10.100056 -200.553066)
		(end 9.46404 -200.12787)
		(width 0.20066)
		(layer "F.Cu")
		(net "M_D_CPU1_SB_DQS_DN<3>")
	)
	(segment
		(start 11.12774 -200.2917)
		(end 11.117072 -200.281032)
		(width 0.101854)
		(layer "F.Cu")
		(net "M_D_CPU1_SB_DQS_DN<3>")
	)
	(segment
		(start 10.64006 -200.553066)
		(end 10.100056 -200.553066)
		(width 0.20066)
		(layer "F.Cu")
		(net "M_D_CPU1_SB_DQS_DN<3>")
	)
	(segment
		(start 14.044676 -200.553066)
		(end 13.857986 -200.553066)
		(width 0.20066)
		(layer "F.Cu")
		(net "M_D_CPU1_SB_DQS_DN<3>")
	)
	(segment
		(start 15.684246 -199.866758)
		(end 15.137638 -199.866758)
		(width 0.20066)
		(layer "F.Cu")
		(net "M_D_CPU1_SB_DQS_DN<3>")
	)
	(segment
		(start 8.689086 -199.866758)
		(end 8.140446 -199.866758)
		(width 0.20066)
		(layer "F.Cu")
		(net "M_D_CPU1_SB_DQS_DN<3>")
	)
	(segment
		(start 53.72735 -199.940418)
		(end 53.22189 -200.154286)
		(width 0.18288)
		(layer "In11.Cu")
		(net "M_D_CPU1_SB_DQS_DN<3>")
	)
	(segment
		(start 88.347296 -227.960682)
		(end 88.332564 -227.969318)
		(width 0.088646)
		(layer "In11.Cu")
		(net "M_D_CPU1_SB_DQS_DN<3>")
	)
	(segment
		(start 22.598634 -200.551288)
		(end 21.430996 -200.551288)
		(width 0.18288)
		(layer "In11.Cu")
		(net "M_D_CPU1_SB_DQS_DN<3>")
	)
	(segment
		(start 67.47637 -206.084424)
		(end 67.47637 -205.908402)
		(width 0.18288)
		(layer "In11.Cu")
		(net "M_D_CPU1_SB_DQS_DN<3>")
	)
	(segment
		(start 90.226896 -227.960682)
		(end 90.212164 -227.969318)
		(width 0.088646)
		(layer "In11.Cu")
		(net "M_D_CPU1_SB_DQS_DN<3>")
	)
	(segment
		(start 53.155596 -200.317608)
		(end 52.650644 -200.531476)
		(width 0.18288)
		(layer "In11.Cu")
		(net "M_D_CPU1_SB_DQS_DN<3>")
	)
	(segment
		(start 50.53076 -200.618852)
		(end 50.13071 -200.618852)
		(width 0.18288)
		(layer "In11.Cu")
		(net "M_D_CPU1_SB_DQS_DN<3>")
	)
	(segment
		(start 68.428362 -206.860394)
		(end 68.04025 -206.472282)
		(width 0.18288)
		(layer "In11.Cu")
		(net "M_D_CPU1_SB_DQS_DN<3>")
	)
	(segment
		(start 46.46803 -198.871332)
		(end 46.293786 -198.871332)
		(width 0.18288)
		(layer "In11.Cu")
		(net "M_D_CPU1_SB_DQS_DN<3>")
	)
	(segment
		(start 36.465764 -200.559924)
		(end 36.198048 -200.292208)
		(width 0.18288)
		(layer "In11.Cu")
		(net "M_D_CPU1_SB_DQS_DN<3>")
	)
	(segment
		(start 73.57618 -212.184234)
		(end 73.188322 -211.796376)
		(width 0.18288)
		(layer "In11.Cu")
		(net "M_D_CPU1_SB_DQS_DN<3>")
	)
	(segment
		(start 57.098692 -199.183752)
		(end 56.550052 -199.183752)
		(width 0.18288)
		(layer "In11.Cu")
		(net "M_D_CPU1_SB_DQS_DN<3>")
	)
	(segment
		(start 83.928458 -226.21621)
		(end 83.250024 -225.537776)
		(width 0.088646)
		(layer "In11.Cu")
		(net "M_D_CPU1_SB_DQS_DN<3>")
	)
	(segment
		(start 70.896226 -209.328258)
		(end 70.720204 -209.328258)
		(width 0.18288)
		(layer "In11.Cu")
		(net "M_D_CPU1_SB_DQS_DN<3>")
	)
	(segment
		(start 72.624188 -211.232242)
		(end 72.23633 -210.844384)
		(width 0.18288)
		(layer "In11.Cu")
		(net "M_D_CPU1_SB_DQS_DN<3>")
	)
	(segment
		(start 69.380354 -207.988408)
		(end 69.380354 -207.812386)
		(width 0.18288)
		(layer "In11.Cu")
		(net "M_D_CPU1_SB_DQS_DN<3>")
	)
	(segment
		(start 92.101924 -227.963222)
		(end 92.09151 -227.969318)
		(width 0.088646)
		(layer "In11.Cu")
		(net "M_D_CPU1_SB_DQS_DN<3>")
	)
	(segment
		(start 66.912236 -205.52029)
		(end 65.002156 -203.61021)
		(width 0.18288)
		(layer "In11.Cu")
		(net "M_D_CPU1_SB_DQS_DN<3>")
	)
	(segment
		(start 31.33344 -198.919846)
		(end 31.15437 -198.919846)
		(width 0.18288)
		(layer "In11.Cu")
		(net "M_D_CPU1_SB_DQS_DN<3>")
	)
	(segment
		(start 52.650644 -200.531476)
		(end 51.529996 -200.531476)
		(width 0.18288)
		(layer "In11.Cu")
		(net "M_D_CPU1_SB_DQS_DN<3>")
	)
	(segment
		(start 67.864228 -206.472282)
		(end 67.47637 -206.084424)
		(width 0.18288)
		(layer "In11.Cu")
		(net "M_D_CPU1_SB_DQS_DN<3>")
	)
	(segment
		(start 84.681568 -226.21621)
		(end 83.928458 -226.21621)
		(width 0.088646)
		(layer "In11.Cu")
		(net "M_D_CPU1_SB_DQS_DN<3>")
	)
	(segment
		(start 46.293786 -198.871332)
		(end 44.50715 -199.611996)
		(width 0.18288)
		(layer "In11.Cu")
		(net "M_D_CPU1_SB_DQS_DN<3>")
	)
	(segment
		(start 57.844944 -199.308212)
		(end 57.223152 -199.308212)
		(width 0.18288)
		(layer "In11.Cu")
		(net "M_D_CPU1_SB_DQS_DN<3>")
	)
	(segment
		(start 55.539132 -199.308212)
		(end 53.890418 -200.006458)
		(width 0.18288)
		(layer "In11.Cu")
		(net "M_D_CPU1_SB_DQS_DN<3>")
	)
	(segment
		(start 96.886776 -228.783896)
		(end 96.886014 -228.783388)
		(width 0.088646)
		(layer "In11.Cu")
		(net "M_D_CPU1_SB_DQS_DN<3>")
	)
	(segment
		(start 63.504318 -202.72883)
		(end 62.860936 -201.176128)
		(width 0.18288)
		(layer "In11.Cu")
		(net "M_D_CPU1_SB_DQS_DN<3>")
	)
	(segment
		(start 93.986096 -227.960682)
		(end 93.971364 -227.969318)
		(width 0.088646)
		(layer "In11.Cu")
		(net "M_D_CPU1_SB_DQS_DN<3>")
	)
	(segment
		(start 51.529996 -200.531476)
		(end 51.286918 -200.288398)
		(width 0.18288)
		(layer "In11.Cu")
		(net "M_D_CPU1_SB_DQS_DN<3>")
	)
	(segment
		(start 50.13071 -200.618852)
		(end 48.33747 -198.825612)
		(width 0.18288)
		(layer "In11.Cu")
		(net "M_D_CPU1_SB_DQS_DN<3>")
	)
	(segment
		(start 71.672196 -210.28025)
		(end 71.284338 -209.892392)
		(width 0.18288)
		(layer "In11.Cu")
		(net "M_D_CPU1_SB_DQS_DN<3>")
	)
	(segment
		(start 37.087556 -200.559924)
		(end 36.465764 -200.559924)
		(width 0.18288)
		(layer "In11.Cu")
		(net "M_D_CPU1_SB_DQS_DN<3>")
	)
	(segment
		(start 35.156902 -200.573132)
		(end 34.254948 -199.671178)
		(width 0.18288)
		(layer "In11.Cu")
		(net "M_D_CPU1_SB_DQS_DN<3>")
	)
	(segment
		(start 82.686398 -224.701354)
		(end 82.686398 -224.616772)
		(width 0.088646)
		(layer "In11.Cu")
		(net "M_D_CPU1_SB_DQS_DN<3>")
	)
	(segment
		(start 57.223152 -199.308212)
		(end 57.098692 -199.183752)
		(width 0.18288)
		(layer "In11.Cu")
		(net "M_D_CPU1_SB_DQS_DN<3>")
	)
	(segment
		(start 47.429166 -198.825612)
		(end 47.196502 -198.592948)
		(width 0.18288)
		(layer "In11.Cu")
		(net "M_D_CPU1_SB_DQS_DN<3>")
	)
	(segment
		(start 17.04594 -200.123552)
		(end 16.789146 -199.866758)
		(width 0.18288)
		(layer "In11.Cu")
		(net "M_D_CPU1_SB_DQS_DN<3>")
	)
	(segment
		(start 71.284338 -209.892392)
		(end 71.284338 -209.71637)
		(width 0.18288)
		(layer "In11.Cu")
		(net "M_D_CPU1_SB_DQS_DN<3>")
	)
	(segment
		(start 73.752202 -212.184234)
		(end 73.57618 -212.184234)
		(width 0.18288)
		(layer "In11.Cu")
		(net "M_D_CPU1_SB_DQS_DN<3>")
	)
	(segment
		(start 82.686398 -224.616772)
		(end 74.528172 -216.458546)
		(width 0.18288)
		(layer "In11.Cu")
		(net "M_D_CPU1_SB_DQS_DN<3>")
	)
	(segment
		(start 37.736018 -200.290938)
		(end 37.087556 -200.559924)
		(width 0.18288)
		(layer "In11.Cu")
		(net "M_D_CPU1_SB_DQS_DN<3>")
	)
	(segment
		(start 74.528172 -216.458546)
		(end 74.528172 -213.136226)
		(width 0.18288)
		(layer "In11.Cu")
		(net "M_D_CPU1_SB_DQS_DN<3>")
	)
	(segment
		(start 83.250024 -225.26498)
		(end 82.686398 -224.701354)
		(width 0.088646)
		(layer "In11.Cu")
		(net "M_D_CPU1_SB_DQS_DN<3>")
	)
	(segment
		(start 31.660338 -198.592948)
		(end 31.33344 -198.919846)
		(width 0.18288)
		(layer "In11.Cu")
		(net "M_D_CPU1_SB_DQS_DN<3>")
	)
	(segment
		(start 20.441158 -200.52919)
		(end 20.267422 -200.52919)
		(width 0.18288)
		(layer "In11.Cu")
		(net "M_D_CPU1_SB_DQS_DN<3>")
	)
	(segment
		(start 62.860936 -201.176128)
		(end 61.814964 -200.130156)
		(width 0.18288)
		(layer "In11.Cu")
		(net "M_D_CPU1_SB_DQS_DN<3>")
	)
	(segment
		(start 68.428362 -207.036416)
		(end 68.428362 -206.860394)
		(width 0.18288)
		(layer "In11.Cu")
		(net "M_D_CPU1_SB_DQS_DN<3>")
	)
	(segment
		(start 35.49904 -200.573132)
		(end 35.156902 -200.573132)
		(width 0.18288)
		(layer "In11.Cu")
		(net "M_D_CPU1_SB_DQS_DN<3>")
	)
	(segment
		(start 71.284338 -209.71637)
		(end 70.896226 -209.328258)
		(width 0.18288)
		(layer "In11.Cu")
		(net "M_D_CPU1_SB_DQS_DN<3>")
	)
	(segment
		(start 32.121602 -198.592948)
		(end 31.660338 -198.592948)
		(width 0.18288)
		(layer "In11.Cu")
		(net "M_D_CPU1_SB_DQS_DN<3>")
	)
	(segment
		(start 70.332346 -208.9404)
		(end 70.332346 -208.764378)
		(width 0.18288)
		(layer "In11.Cu")
		(net "M_D_CPU1_SB_DQS_DN<3>")
	)
	(segment
		(start 96.89211 -228.786944)
		(end 96.886776 -228.783896)
		(width 0.088646)
		(layer "In11.Cu")
		(net "M_D_CPU1_SB_DQS_DN<3>")
	)
	(segment
		(start 74.140314 -212.748368)
		(end 74.140314 -212.572346)
		(width 0.18288)
		(layer "In11.Cu")
		(net "M_D_CPU1_SB_DQS_DN<3>")
	)
	(segment
		(start 87.494364 -227.159058)
		(end 87.488268 -227.155502)
		(width 0.088646)
		(layer "In11.Cu")
		(net "M_D_CPU1_SB_DQS_DN<3>")
	)
	(segment
		(start 46.746414 -198.592948)
		(end 46.46803 -198.871332)
		(width 0.18288)
		(layer "In11.Cu")
		(net "M_D_CPU1_SB_DQS_DN<3>")
	)
	(segment
		(start 17.508728 -200.123552)
		(end 17.04594 -200.123552)
		(width 0.18288)
		(layer "In11.Cu")
		(net "M_D_CPU1_SB_DQS_DN<3>")
	)
	(segment
		(start 50.861214 -200.288398)
		(end 50.53076 -200.618852)
		(width 0.18288)
		(layer "In11.Cu")
		(net "M_D_CPU1_SB_DQS_DN<3>")
	)
	(segment
		(start 18.037048 -199.904858)
		(end 17.715484 -200.0377)
		(width 0.18288)
		(layer "In11.Cu")
		(net "M_D_CPU1_SB_DQS_DN<3>")
	)
	(segment
		(start 93.046296 -227.960682)
		(end 93.031564 -227.969318)
		(width 0.088646)
		(layer "In11.Cu")
		(net "M_D_CPU1_SB_DQS_DN<3>")
	)
	(segment
		(start 69.380354 -207.812386)
		(end 68.992242 -207.424274)
		(width 0.18288)
		(layer "In11.Cu")
		(net "M_D_CPU1_SB_DQS_DN<3>")
	)
	(segment
		(start 83.250024 -225.537776)
		(end 83.250024 -225.26498)
		(width 0.088646)
		(layer "In11.Cu")
		(net "M_D_CPU1_SB_DQS_DN<3>")
	)
	(segment
		(start 63.94958 -203.174092)
		(end 63.504318 -202.72883)
		(width 0.18288)
		(layer "In11.Cu")
		(net "M_D_CPU1_SB_DQS_DN<3>")
	)
	(segment
		(start 71.848218 -210.28025)
		(end 71.672196 -210.28025)
		(width 0.18288)
		(layer "In11.Cu")
		(net "M_D_CPU1_SB_DQS_DN<3>")
	)
	(segment
		(start 68.81622 -207.424274)
		(end 68.428362 -207.036416)
		(width 0.18288)
		(layer "In11.Cu")
		(net "M_D_CPU1_SB_DQS_DN<3>")
	)
	(segment
		(start 44.50715 -199.611996)
		(end 38.41496 -199.611996)
		(width 0.18288)
		(layer "In11.Cu")
		(net "M_D_CPU1_SB_DQS_DN<3>")
	)
	(segment
		(start 69.944234 -208.376266)
		(end 69.768212 -208.376266)
		(width 0.18288)
		(layer "In11.Cu")
		(net "M_D_CPU1_SB_DQS_DN<3>")
	)
	(segment
		(start 61.814964 -200.130156)
		(end 61.108844 -199.837294)
		(width 0.18288)
		(layer "In11.Cu")
		(net "M_D_CPU1_SB_DQS_DN<3>")
	)
	(segment
		(start 97.659698 -229.77221)
		(end 97.355914 -229.597458)
		(width 0.088646)
		(layer "In11.Cu")
		(net "M_D_CPU1_SB_DQS_DN<3>")
	)
	(segment
		(start 53.22189 -200.154286)
		(end 53.155596 -200.317608)
		(width 0.18288)
		(layer "In11.Cu")
		(net "M_D_CPU1_SB_DQS_DN<3>")
	)
	(segment
		(start 96.88449 -228.782626)
		(end 96.877124 -228.778308)
		(width 0.088646)
		(layer "In11.Cu")
		(net "M_D_CPU1_SB_DQS_DN<3>")
	)
	(segment
		(start 87.488268 -227.155502)
		(end 87.479378 -227.150422)
		(width 0.088646)
		(layer "In11.Cu")
		(net "M_D_CPU1_SB_DQS_DN<3>")
	)
	(segment
		(start 56.550052 -199.183752)
		(end 56.425592 -199.308212)
		(width 0.18288)
		(layer "In11.Cu")
		(net "M_D_CPU1_SB_DQS_DN<3>")
	)
	(segment
		(start 18.76044 -199.904858)
		(end 18.037048 -199.904858)
		(width 0.18288)
		(layer "In11.Cu")
		(net "M_D_CPU1_SB_DQS_DN<3>")
	)
	(segment
		(start 72.23633 -210.668362)
		(end 71.848218 -210.28025)
		(width 0.18288)
		(layer "In11.Cu")
		(net "M_D_CPU1_SB_DQS_DN<3>")
	)
	(segment
		(start 96.698562 -228.45903)
		(end 96.698562 -228.436932)
		(width 0.088646)
		(layer "In11.Cu")
		(net "M_D_CPU1_SB_DQS_DN<3>")
	)
	(segment
		(start 97.994978 -230.086662)
		(end 97.659698 -229.77221)
		(width 0.088646)
		(layer "In11.Cu")
		(net "M_D_CPU1_SB_DQS_DN<3>")
	)
	(segment
		(start 95.865696 -227.960682)
		(end 95.850964 -227.969318)
		(width 0.088646)
		(layer "In11.Cu")
		(net "M_D_CPU1_SB_DQS_DN<3>")
	)
	(segment
		(start 74.528172 -213.136226)
		(end 74.140314 -212.748368)
		(width 0.18288)
		(layer "In11.Cu")
		(net "M_D_CPU1_SB_DQS_DN<3>")
	)
	(segment
		(start 91.717114 -227.969318)
		(end 91.7067 -227.963222)
		(width 0.088646)
		(layer "In11.Cu")
		(net "M_D_CPU1_SB_DQS_DN<3>")
	)
	(segment
		(start 20.267422 -200.52919)
		(end 18.76044 -199.904858)
		(width 0.18288)
		(layer "In11.Cu")
		(net "M_D_CPU1_SB_DQS_DN<3>")
	)
	(segment
		(start 20.677886 -200.292462)
		(end 20.441158 -200.52919)
		(width 0.18288)
		(layer "In11.Cu")
		(net "M_D_CPU1_SB_DQS_DN<3>")
	)
	(segment
		(start 67.088258 -205.52029)
		(end 66.912236 -205.52029)
		(width 0.18288)
		(layer "In11.Cu")
		(net "M_D_CPU1_SB_DQS_DN<3>")
	)
	(segment
		(start 70.332346 -208.764378)
		(end 69.944234 -208.376266)
		(width 0.18288)
		(layer "In11.Cu")
		(net "M_D_CPU1_SB_DQS_DN<3>")
	)
	(segment
		(start 86.463378 -226.33559)
		(end 86.452964 -226.341686)
		(width 0.088646)
		(layer "In11.Cu")
		(net "M_D_CPU1_SB_DQS_DN<3>")
	)
	(segment
		(start 70.720204 -209.328258)
		(end 70.332346 -208.9404)
		(width 0.18288)
		(layer "In11.Cu")
		(net "M_D_CPU1_SB_DQS_DN<3>")
	)
	(segment
		(start 87.958168 -227.969318)
		(end 87.949278 -227.964238)
		(width 0.088646)
		(layer "In11.Cu")
		(net "M_D_CPU1_SB_DQS_DN<3>")
	)
	(segment
		(start 29.241242 -199.65543)
		(end 26.537666 -199.65543)
		(width 0.18288)
		(layer "In11.Cu")
		(net "M_D_CPU1_SB_DQS_DN<3>")
	)
	(segment
		(start 35.779964 -200.292208)
		(end 35.49904 -200.573132)
		(width 0.18288)
		(layer "In11.Cu")
		(net "M_D_CPU1_SB_DQS_DN<3>")
	)
	(segment
		(start 34.254948 -199.671178)
		(end 32.846518 -198.901558)
		(width 0.18288)
		(layer "In11.Cu")
		(net "M_D_CPU1_SB_DQS_DN<3>")
	)
	(segment
		(start 51.286918 -200.288398)
		(end 50.861214 -200.288398)
		(width 0.18288)
		(layer "In11.Cu")
		(net "M_D_CPU1_SB_DQS_DN<3>")
	)
	(segment
		(start 89.287096 -227.960682)
		(end 89.272364 -227.969318)
		(width 0.088646)
		(layer "In11.Cu")
		(net "M_D_CPU1_SB_DQS_DN<3>")
	)
	(segment
		(start 53.890418 -200.006458)
		(end 53.72735 -199.940418)
		(width 0.18288)
		(layer "In11.Cu")
		(net "M_D_CPU1_SB_DQS_DN<3>")
	)
	(segment
		(start 59.12231 -199.837294)
		(end 57.844944 -199.308212)
		(width 0.18288)
		(layer "In11.Cu")
		(net "M_D_CPU1_SB_DQS_DN<3>")
	)
	(segment
		(start 65.002156 -203.61021)
		(end 63.94958 -203.174092)
		(width 0.18288)
		(layer "In11.Cu")
		(net "M_D_CPU1_SB_DQS_DN<3>")
	)
	(segment
		(start 21.430996 -200.551288)
		(end 21.17217 -200.292462)
		(width 0.18288)
		(layer "In11.Cu")
		(net "M_D_CPU1_SB_DQS_DN<3>")
	)
	(segment
		(start 69.768212 -208.376266)
		(end 69.380354 -207.988408)
		(width 0.18288)
		(layer "In11.Cu")
		(net "M_D_CPU1_SB_DQS_DN<3>")
	)
	(segment
		(start 38.41496 -199.611996)
		(end 37.736018 -200.290938)
		(width 0.18288)
		(layer "In11.Cu")
		(net "M_D_CPU1_SB_DQS_DN<3>")
	)
	(segment
		(start 72.80021 -211.232242)
		(end 72.624188 -211.232242)
		(width 0.18288)
		(layer "In11.Cu")
		(net "M_D_CPU1_SB_DQS_DN<3>")
	)
	(segment
		(start 31.15437 -198.919846)
		(end 29.241242 -199.65543)
		(width 0.18288)
		(layer "In11.Cu")
		(net "M_D_CPU1_SB_DQS_DN<3>")
	)
	(segment
		(start 68.04025 -206.472282)
		(end 67.864228 -206.472282)
		(width 0.18288)
		(layer "In11.Cu")
		(net "M_D_CPU1_SB_DQS_DN<3>")
	)
	(segment
		(start 72.23633 -210.844384)
		(end 72.23633 -210.668362)
		(width 0.18288)
		(layer "In11.Cu")
		(net "M_D_CPU1_SB_DQS_DN<3>")
	)
	(segment
		(start 73.188322 -211.620354)
		(end 72.80021 -211.232242)
		(width 0.18288)
		(layer "In11.Cu")
		(net "M_D_CPU1_SB_DQS_DN<3>")
	)
	(segment
		(start 73.188322 -211.796376)
		(end 73.188322 -211.620354)
		(width 0.18288)
		(layer "In11.Cu")
		(net "M_D_CPU1_SB_DQS_DN<3>")
	)
	(segment
		(start 67.47637 -205.908402)
		(end 67.088258 -205.52029)
		(width 0.18288)
		(layer "In11.Cu")
		(net "M_D_CPU1_SB_DQS_DN<3>")
	)
	(segment
		(start 17.715484 -200.0377)
		(end 17.508728 -200.123552)
		(width 0.18288)
		(layer "In11.Cu")
		(net "M_D_CPU1_SB_DQS_DN<3>")
	)
	(segment
		(start 26.537666 -199.65543)
		(end 22.598634 -200.551288)
		(width 0.18288)
		(layer "In11.Cu")
		(net "M_D_CPU1_SB_DQS_DN<3>")
	)
	(segment
		(start 36.198048 -200.292208)
		(end 35.779964 -200.292208)
		(width 0.18288)
		(layer "In11.Cu")
		(net "M_D_CPU1_SB_DQS_DN<3>")
	)
	(segment
		(start 98.013012 -230.086662)
		(end 97.994978 -230.086662)
		(width 0.088646)
		(layer "In11.Cu")
		(net "M_D_CPU1_SB_DQS_DN<3>")
	)
	(segment
		(start 94.925896 -227.960682)
		(end 94.911164 -227.969318)
		(width 0.088646)
		(layer "In11.Cu")
		(net "M_D_CPU1_SB_DQS_DN<3>")
	)
	(segment
		(start 96.886014 -228.783388)
		(end 96.88449 -228.782626)
		(width 0.088646)
		(layer "In11.Cu")
		(net "M_D_CPU1_SB_DQS_DN<3>")
	)
	(segment
		(start 21.17217 -200.292462)
		(end 20.677886 -200.292462)
		(width 0.18288)
		(layer "In11.Cu")
		(net "M_D_CPU1_SB_DQS_DN<3>")
	)
	(segment
		(start 47.196502 -198.592948)
		(end 46.746414 -198.592948)
		(width 0.18288)
		(layer "In11.Cu")
		(net "M_D_CPU1_SB_DQS_DN<3>")
	)
	(segment
		(start 56.425592 -199.308212)
		(end 55.539132 -199.308212)
		(width 0.18288)
		(layer "In11.Cu")
		(net "M_D_CPU1_SB_DQS_DN<3>")
	)
	(segment
		(start 32.430212 -198.901558)
		(end 32.121602 -198.592948)
		(width 0.18288)
		(layer "In11.Cu")
		(net "M_D_CPU1_SB_DQS_DN<3>")
	)
	(segment
		(start 32.846518 -198.901558)
		(end 32.430212 -198.901558)
		(width 0.18288)
		(layer "In11.Cu")
		(net "M_D_CPU1_SB_DQS_DN<3>")
	)
	(segment
		(start 74.140314 -212.572346)
		(end 73.752202 -212.184234)
		(width 0.18288)
		(layer "In11.Cu")
		(net "M_D_CPU1_SB_DQS_DN<3>")
	)
	(segment
		(start 61.108844 -199.837294)
		(end 59.12231 -199.837294)
		(width 0.18288)
		(layer "In11.Cu")
		(net "M_D_CPU1_SB_DQS_DN<3>")
	)
	(segment
		(start 48.33747 -198.825612)
		(end 47.429166 -198.825612)
		(width 0.18288)
		(layer "In11.Cu")
		(net "M_D_CPU1_SB_DQS_DN<3>")
	)
	(segment
		(start 87.030306 -226.348798)
		(end 87.018114 -226.341686)
		(width 0.088646)
		(layer "In11.Cu")
		(net "M_D_CPU1_SB_DQS_DN<3>")
	)
	(segment
		(start 86.078568 -226.341686)
		(end 86.068154 -226.33559)
		(width 0.088646)
		(layer "In11.Cu")
		(net "M_D_CPU1_SB_DQS_DN<3>")
	)
	(segment
		(start 97.168716 -229.2731)
		(end 97.168716 -229.272846)
		(width 0.088646)
		(layer "In11.Cu")
		(net "M_D_CPU1_SB_DQS_DN<3>")
	)
	(segment
		(start 68.992242 -207.424274)
		(end 68.81622 -207.424274)
		(width 0.18288)
		(layer "In11.Cu")
		(net "M_D_CPU1_SB_DQS_DN<3>")
	)
	(arc
		(start 87.770716 -227.64496)
		(mid 87.6968 -227.365458)
		(end 87.494364 -227.159058)
		(width 0.088646)
		(layer "In11.Cu")
		(net "M_D_CPU1_SB_DQS_DN<3>")
	)
	(arc
		(start 87.300816 -226.831144)
		(mid 87.228581 -226.55462)
		(end 87.030306 -226.348798)
		(width 0.088646)
		(layer "In11.Cu")
		(net "M_D_CPU1_SB_DQS_DN<3>")
	)
	(arc
		(start 89.272364 -227.969318)
		(mid 89.085166 -228.019461)
		(end 88.897968 -227.969318)
		(width 0.088646)
		(layer "In11.Cu")
		(net "M_D_CPU1_SB_DQS_DN<3>")
	)
	(arc
		(start 87.949278 -227.964238)
		(mid 87.818364 -227.827878)
		(end 87.770716 -227.64496)
		(width 0.088646)
		(layer "In11.Cu")
		(net "M_D_CPU1_SB_DQS_DN<3>")
	)
	(arc
		(start 88.897968 -227.969318)
		(mid 88.623739 -227.893393)
		(end 88.347296 -227.960682)
		(width 0.088646)
		(layer "In11.Cu")
		(net "M_D_CPU1_SB_DQS_DN<3>")
	)
	(arc
		(start 93.031564 -227.969318)
		(mid 92.844366 -228.019461)
		(end 92.657168 -227.969318)
		(width 0.088646)
		(layer "In11.Cu")
		(net "M_D_CPU1_SB_DQS_DN<3>")
	)
	(arc
		(start 90.777568 -227.969318)
		(mid 90.503339 -227.893393)
		(end 90.226896 -227.960682)
		(width 0.088646)
		(layer "In11.Cu")
		(net "M_D_CPU1_SB_DQS_DN<3>")
	)
	(arc
		(start 85.138514 -226.341686)
		(mid 84.918502 -226.24813)
		(end 84.681568 -226.21621)
		(width 0.088646)
		(layer "In11.Cu")
		(net "M_D_CPU1_SB_DQS_DN<3>")
	)
	(arc
		(start 93.596968 -227.969318)
		(mid 93.322739 -227.893393)
		(end 93.046296 -227.960682)
		(width 0.088646)
		(layer "In11.Cu")
		(net "M_D_CPU1_SB_DQS_DN<3>")
	)
	(arc
		(start 86.452964 -226.341686)
		(mid 86.265766 -226.391829)
		(end 86.078568 -226.341686)
		(width 0.088646)
		(layer "In11.Cu")
		(net "M_D_CPU1_SB_DQS_DN<3>")
	)
	(arc
		(start 94.911164 -227.969318)
		(mid 94.723966 -228.019461)
		(end 94.536768 -227.969318)
		(width 0.088646)
		(layer "In11.Cu")
		(net "M_D_CPU1_SB_DQS_DN<3>")
	)
	(arc
		(start 97.168716 -229.272846)
		(mid 97.094725 -228.99328)
		(end 96.89211 -228.786944)
		(width 0.088646)
		(layer "In11.Cu")
		(net "M_D_CPU1_SB_DQS_DN<3>")
	)
	(arc
		(start 91.151964 -227.969318)
		(mid 90.964766 -228.019461)
		(end 90.777568 -227.969318)
		(width 0.088646)
		(layer "In11.Cu")
		(net "M_D_CPU1_SB_DQS_DN<3>")
	)
	(arc
		(start 96.877124 -228.778308)
		(mid 96.74621 -228.641948)
		(end 96.698562 -228.45903)
		(width 0.088646)
		(layer "In11.Cu")
		(net "M_D_CPU1_SB_DQS_DN<3>")
	)
	(arc
		(start 85.51291 -226.341686)
		(mid 85.325712 -226.391829)
		(end 85.138514 -226.341686)
		(width 0.088646)
		(layer "In11.Cu")
		(net "M_D_CPU1_SB_DQS_DN<3>")
	)
	(arc
		(start 94.536768 -227.969318)
		(mid 94.262539 -227.893393)
		(end 93.986096 -227.960682)
		(width 0.088646)
		(layer "In11.Cu")
		(net "M_D_CPU1_SB_DQS_DN<3>")
	)
	(arc
		(start 91.7067 -227.963222)
		(mid 91.428522 -227.89353)
		(end 91.151964 -227.969318)
		(width 0.088646)
		(layer "In11.Cu")
		(net "M_D_CPU1_SB_DQS_DN<3>")
	)
	(arc
		(start 89.837768 -227.969318)
		(mid 89.563539 -227.893393)
		(end 89.287096 -227.960682)
		(width 0.088646)
		(layer "In11.Cu")
		(net "M_D_CPU1_SB_DQS_DN<3>")
	)
	(arc
		(start 96.698562 -228.436932)
		(mid 96.617651 -228.166804)
		(end 96.416368 -227.969318)
		(width 0.088646)
		(layer "In11.Cu")
		(net "M_D_CPU1_SB_DQS_DN<3>")
	)
	(arc
		(start 90.212164 -227.969318)
		(mid 90.024966 -228.019461)
		(end 89.837768 -227.969318)
		(width 0.088646)
		(layer "In11.Cu")
		(net "M_D_CPU1_SB_DQS_DN<3>")
	)
	(arc
		(start 88.332564 -227.969318)
		(mid 88.145366 -228.019461)
		(end 87.958168 -227.969318)
		(width 0.088646)
		(layer "In11.Cu")
		(net "M_D_CPU1_SB_DQS_DN<3>")
	)
	(arc
		(start 97.355914 -229.597458)
		(mid 97.218889 -229.460345)
		(end 97.168716 -229.2731)
		(width 0.088646)
		(layer "In11.Cu")
		(net "M_D_CPU1_SB_DQS_DN<3>")
	)
	(arc
		(start 87.479378 -227.150422)
		(mid 87.348464 -227.014062)
		(end 87.300816 -226.831144)
		(width 0.088646)
		(layer "In11.Cu")
		(net "M_D_CPU1_SB_DQS_DN<3>")
	)
	(arc
		(start 95.850964 -227.969318)
		(mid 95.663766 -228.019461)
		(end 95.476568 -227.969318)
		(width 0.088646)
		(layer "In11.Cu")
		(net "M_D_CPU1_SB_DQS_DN<3>")
	)
	(arc
		(start 92.657168 -227.969318)
		(mid 92.380355 -227.893482)
		(end 92.101924 -227.963222)
		(width 0.088646)
		(layer "In11.Cu")
		(net "M_D_CPU1_SB_DQS_DN<3>")
	)
	(arc
		(start 86.068154 -226.33559)
		(mid 85.789722 -226.265744)
		(end 85.51291 -226.341686)
		(width 0.088646)
		(layer "In11.Cu")
		(net "M_D_CPU1_SB_DQS_DN<3>")
	)
	(arc
		(start 87.018114 -226.341686)
		(mid 86.741555 -226.265943)
		(end 86.463378 -226.33559)
		(width 0.088646)
		(layer "In11.Cu")
		(net "M_D_CPU1_SB_DQS_DN<3>")
	)
	(arc
		(start 96.416368 -227.969318)
		(mid 96.142139 -227.893393)
		(end 95.865696 -227.960682)
		(width 0.088646)
		(layer "In11.Cu")
		(net "M_D_CPU1_SB_DQS_DN<3>")
	)
	(arc
		(start 92.09151 -227.969318)
		(mid 91.904312 -228.019461)
		(end 91.717114 -227.969318)
		(width 0.088646)
		(layer "In11.Cu")
		(net "M_D_CPU1_SB_DQS_DN<3>")
	)
	(arc
		(start 95.476568 -227.969318)
		(mid 95.202339 -227.893393)
		(end 94.925896 -227.960682)
		(width 0.088646)
		(layer "In11.Cu")
		(net "M_D_CPU1_SB_DQS_DN<3>")
	)
	(arc
		(start 93.971364 -227.969318)
		(mid 93.784166 -228.019461)
		(end 93.596968 -227.969318)
		(width 0.088646)
		(layer "In11.Cu")
		(net "M_D_CPU1_SB_DQS_DN<3>")
	)
	(segment
		(start 11.11631 -209.631026)
		(end 10.912094 -209.631026)
		(width 0.20066)
		(layer "F.Cu")
		(net "M_D_CPU1_SB_DQS_DN<2>")
	)
	(segment
		(start 15.137638 -209.216752)
		(end 14.876526 -209.477864)
		(width 0.20066)
		(layer "F.Cu")
		(net "M_D_CPU1_SB_DQS_DN<2>")
	)
	(segment
		(start 94.723966 -233.06405)
		(end 94.723966 -232.528364)
		(width 0.20066)
		(layer "F.Cu")
		(net "M_D_CPU1_SB_DQS_DN<2>")
	)
	(segment
		(start 14.876526 -209.477864)
		(end 14.469872 -209.477864)
		(width 0.20066)
		(layer "F.Cu")
		(net "M_D_CPU1_SB_DQS_DN<2>")
	)
	(segment
		(start 10.912094 -209.631026)
		(end 10.64006 -209.90306)
		(width 0.20066)
		(layer "F.Cu")
		(net "M_D_CPU1_SB_DQS_DN<2>")
	)
	(segment
		(start 8.950198 -209.477864)
		(end 8.689086 -209.216752)
		(width 0.20066)
		(layer "F.Cu")
		(net "M_D_CPU1_SB_DQS_DN<2>")
	)
	(segment
		(start 13.59662 -209.641694)
		(end 13.441426 -209.641694)
		(width 0.20066)
		(layer "F.Cu")
		(net "M_D_CPU1_SB_DQS_DN<2>")
	)
	(segment
		(start 10.64006 -209.90306)
		(end 10.100056 -209.90306)
		(width 0.20066)
		(layer "F.Cu")
		(net "M_D_CPU1_SB_DQS_DN<2>")
	)
	(segment
		(start 11.12774 -209.641694)
		(end 11.117072 -209.631026)
		(width 0.101854)
		(layer "F.Cu")
		(net "M_D_CPU1_SB_DQS_DN<2>")
	)
	(segment
		(start 14.469872 -209.477864)
		(end 14.044676 -209.90306)
		(width 0.20066)
		(layer "F.Cu")
		(net "M_D_CPU1_SB_DQS_DN<2>")
	)
	(segment
		(start 13.857986 -209.90306)
		(end 13.59662 -209.641694)
		(width 0.20066)
		(layer "F.Cu")
		(net "M_D_CPU1_SB_DQS_DN<2>")
	)
	(segment
		(start 16.789146 -209.216752)
		(end 15.684246 -209.216752)
		(width 0.20066)
		(layer "F.Cu")
		(net "M_D_CPU1_SB_DQS_DN<2>")
	)
	(segment
		(start 11.117072 -209.631026)
		(end 11.11631 -209.631026)
		(width 0.101854)
		(layer "F.Cu")
		(net "M_D_CPU1_SB_DQS_DN<2>")
	)
	(segment
		(start 15.684246 -209.216752)
		(end 15.137638 -209.216752)
		(width 0.20066)
		(layer "F.Cu")
		(net "M_D_CPU1_SB_DQS_DN<2>")
	)
	(segment
		(start 14.044676 -209.90306)
		(end 13.857986 -209.90306)
		(width 0.20066)
		(layer "F.Cu")
		(net "M_D_CPU1_SB_DQS_DN<2>")
	)
	(segment
		(start 13.441426 -209.641694)
		(end 11.12774 -209.641694)
		(width 0.1016)
		(layer "F.Cu")
		(net "M_D_CPU1_SB_DQS_DN<2>")
	)
	(segment
		(start 10.100056 -209.90306)
		(end 9.46404 -209.477864)
		(width 0.20066)
		(layer "F.Cu")
		(net "M_D_CPU1_SB_DQS_DN<2>")
	)
	(segment
		(start 9.46404 -209.477864)
		(end 8.950198 -209.477864)
		(width 0.20066)
		(layer "F.Cu")
		(net "M_D_CPU1_SB_DQS_DN<2>")
	)
	(segment
		(start 94.723712 -233.064304)
		(end 94.723966 -233.06405)
		(width 0.20066)
		(layer "F.Cu")
		(net "M_D_CPU1_SB_DQS_DN<2>")
	)
	(segment
		(start 8.689086 -209.216752)
		(end 8.140446 -209.216752)
		(width 0.20066)
		(layer "F.Cu")
		(net "M_D_CPU1_SB_DQS_DN<2>")
	)
	(segment
		(start 31.653734 -210.491832)
		(end 31.38043 -210.765136)
		(width 0.18288)
		(layer "In6.Cu")
		(net "M_D_CPU1_SB_DQS_DN<2>")
	)
	(segment
		(start 34.725102 -209.892138)
		(end 34.26841 -210.348576)
		(width 0.18288)
		(layer "In6.Cu")
		(net "M_D_CPU1_SB_DQS_DN<2>")
	)
	(segment
		(start 51.274218 -209.640932)
		(end 50.855372 -209.640932)
		(width 0.18288)
		(layer "In6.Cu")
		(net "M_D_CPU1_SB_DQS_DN<2>")
	)
	(segment
		(start 90.226896 -232.844086)
		(end 90.212164 -232.852722)
		(width 0.088646)
		(layer "In6.Cu")
		(net "M_D_CPU1_SB_DQS_DN<2>")
	)
	(segment
		(start 63.249302 -212.145626)
		(end 63.181738 -211.982558)
		(width 0.18288)
		(layer "In6.Cu")
		(net "M_D_CPU1_SB_DQS_DN<2>")
	)
	(segment
		(start 82.65541 -229.155244)
		(end 82.632042 -229.155244)
		(width 0.088646)
		(layer "In6.Cu")
		(net "M_D_CPU1_SB_DQS_DN<2>")
	)
	(segment
		(start 82.7151 -229.214934)
		(end 82.65541 -229.155244)
		(width 0.088646)
		(layer "In6.Cu")
		(net "M_D_CPU1_SB_DQS_DN<2>")
	)
	(segment
		(start 93.971618 -232.852722)
		(end 93.971364 -232.852722)
		(width 0.088646)
		(layer "In6.Cu")
		(net "M_D_CPU1_SB_DQS_DN<2>")
	)
	(segment
		(start 29.939234 -209.86877)
		(end 28.429966 -209.243422)
		(width 0.18288)
		(layer "In6.Cu")
		(net "M_D_CPU1_SB_DQS_DN<2>")
	)
	(segment
		(start 52.629308 -210.15071)
		(end 52.37607 -209.897472)
		(width 0.18288)
		(layer "In6.Cu")
		(net "M_D_CPU1_SB_DQS_DN<2>")
	)
	(segment
		(start 64.608456 -213.0298)
		(end 64.060324 -212.481414)
		(width 0.18288)
		(layer "In6.Cu")
		(net "M_D_CPU1_SB_DQS_DN<2>")
	)
	(segment
		(start 49.321466 -210.4644)
		(end 48.579278 -210.771994)
		(width 0.18288)
		(layer "In6.Cu")
		(net "M_D_CPU1_SB_DQS_DN<2>")
	)
	(segment
		(start 64.060324 -212.481414)
		(end 63.249302 -212.145626)
		(width 0.18288)
		(layer "In6.Cu")
		(net "M_D_CPU1_SB_DQS_DN<2>")
	)
	(segment
		(start 46.762416 -210.492848)
		(end 46.487842 -210.767422)
		(width 0.18288)
		(layer "In6.Cu")
		(net "M_D_CPU1_SB_DQS_DN<2>")
	)
	(segment
		(start 42.300906 -209.155284)
		(end 41.752266 -209.155284)
		(width 0.18288)
		(layer "In6.Cu")
		(net "M_D_CPU1_SB_DQS_DN<2>")
	)
	(segment
		(start 51.530758 -209.897472)
		(end 51.274218 -209.640932)
		(width 0.18288)
		(layer "In6.Cu")
		(net "M_D_CPU1_SB_DQS_DN<2>")
	)
	(segment
		(start 19.358356 -209.507836)
		(end 18.727674 -209.24647)
		(width 0.18288)
		(layer "In6.Cu")
		(net "M_D_CPU1_SB_DQS_DN<2>")
	)
	(segment
		(start 34.26841 -210.348576)
		(end 33.87725 -210.511136)
		(width 0.18288)
		(layer "In6.Cu")
		(net "M_D_CPU1_SB_DQS_DN<2>")
	)
	(segment
		(start 26.672286 -209.243422)
		(end 25.96896 -209.243422)
		(width 0.18288)
		(layer "In6.Cu")
		(net "M_D_CPU1_SB_DQS_DN<2>")
	)
	(segment
		(start 42.974006 -209.279744)
		(end 42.425366 -209.279744)
		(width 0.18288)
		(layer "In6.Cu")
		(net "M_D_CPU1_SB_DQS_DN<2>")
	)
	(segment
		(start 38.890956 -209.894424)
		(end 38.766496 -209.769964)
		(width 0.18288)
		(layer "In6.Cu")
		(net "M_D_CPU1_SB_DQS_DN<2>")
	)
	(segment
		(start 44.320206 -209.279744)
		(end 43.771566 -209.279744)
		(width 0.18288)
		(layer "In6.Cu")
		(net "M_D_CPU1_SB_DQS_DN<2>")
	)
	(segment
		(start 94.498668 -232.70718)
		(end 94.224348 -232.70718)
		(width 0.088646)
		(layer "In6.Cu")
		(net "M_D_CPU1_SB_DQS_DN<2>")
	)
	(segment
		(start 33.87725 -210.511136)
		(end 32.939736 -210.511136)
		(width 0.18288)
		(layer "In6.Cu")
		(net "M_D_CPU1_SB_DQS_DN<2>")
	)
	(segment
		(start 22.747732 -209.898996)
		(end 21.385022 -209.898996)
		(width 0.18288)
		(layer "In6.Cu")
		(net "M_D_CPU1_SB_DQS_DN<2>")
	)
	(segment
		(start 21.385022 -209.898996)
		(end 21.12772 -209.641694)
		(width 0.18288)
		(layer "In6.Cu")
		(net "M_D_CPU1_SB_DQS_DN<2>")
	)
	(segment
		(start 82.632042 -229.155244)
		(end 77.582522 -229.155244)
		(width 0.18288)
		(layer "In6.Cu")
		(net "M_D_CPU1_SB_DQS_DN<2>")
	)
	(segment
		(start 39.439596 -209.894424)
		(end 38.890956 -209.894424)
		(width 0.18288)
		(layer "In6.Cu")
		(net "M_D_CPU1_SB_DQS_DN<2>")
	)
	(segment
		(start 45.342302 -210.125818)
		(end 44.95419 -209.737706)
		(width 0.18288)
		(layer "In6.Cu")
		(net "M_D_CPU1_SB_DQS_DN<2>")
	)
	(segment
		(start 53.851048 -210.02625)
		(end 53.302408 -210.02625)
		(width 0.18288)
		(layer "In6.Cu")
		(net "M_D_CPU1_SB_DQS_DN<2>")
	)
	(segment
		(start 50.596292 -209.900012)
		(end 49.886108 -209.900012)
		(width 0.18288)
		(layer "In6.Cu")
		(net "M_D_CPU1_SB_DQS_DN<2>")
	)
	(segment
		(start 57.73928 -210.706208)
		(end 57.592976 -210.803998)
		(width 0.18288)
		(layer "In6.Cu")
		(net "M_D_CPU1_SB_DQS_DN<2>")
	)
	(segment
		(start 82.981038 -229.214934)
		(end 82.7151 -229.214934)
		(width 0.088646)
		(layer "In6.Cu")
		(net "M_D_CPU1_SB_DQS_DN<2>")
	)
	(segment
		(start 59.63666 -211.366354)
		(end 58.913522 -211.066634)
		(width 0.18288)
		(layer "In6.Cu")
		(net "M_D_CPU1_SB_DQS_DN<2>")
	)
	(segment
		(start 83.199478 -229.433374)
		(end 82.981038 -229.214934)
		(width 0.088646)
		(layer "In6.Cu")
		(net "M_D_CPU1_SB_DQS_DN<2>")
	)
	(segment
		(start 43.771566 -209.279744)
		(end 43.647106 -209.155284)
		(width 0.18288)
		(layer "In6.Cu")
		(net "M_D_CPU1_SB_DQS_DN<2>")
	)
	(segment
		(start 30.695646 -210.624928)
		(end 29.939234 -209.86877)
		(width 0.18288)
		(layer "In6.Cu")
		(net "M_D_CPU1_SB_DQS_DN<2>")
	)
	(segment
		(start 93.046296 -232.844086)
		(end 93.031564 -232.852722)
		(width 0.088646)
		(layer "In6.Cu")
		(net "M_D_CPU1_SB_DQS_DN<2>")
	)
	(segment
		(start 83.922108 -230.499158)
		(end 83.199478 -229.776528)
		(width 0.088646)
		(layer "In6.Cu")
		(net "M_D_CPU1_SB_DQS_DN<2>")
	)
	(segment
		(start 61.368178 -211.366354)
		(end 59.63666 -211.366354)
		(width 0.18288)
		(layer "In6.Cu")
		(net "M_D_CPU1_SB_DQS_DN<2>")
	)
	(segment
		(start 42.425366 -209.279744)
		(end 42.300906 -209.155284)
		(width 0.18288)
		(layer "In6.Cu")
		(net "M_D_CPU1_SB_DQS_DN<2>")
	)
	(segment
		(start 19.743166 -209.892138)
		(end 19.358356 -209.507836)
		(width 0.18288)
		(layer "In6.Cu")
		(net "M_D_CPU1_SB_DQS_DN<2>")
	)
	(segment
		(start 35.753802 -209.641694)
		(end 35.503358 -209.892138)
		(width 0.18288)
		(layer "In6.Cu")
		(net "M_D_CPU1_SB_DQS_DN<2>")
	)
	(segment
		(start 35.503358 -209.892138)
		(end 34.725102 -209.892138)
		(width 0.18288)
		(layer "In6.Cu")
		(net "M_D_CPU1_SB_DQS_DN<2>")
	)
	(segment
		(start 38.217856 -209.769964)
		(end 38.093396 -209.894424)
		(width 0.18288)
		(layer "In6.Cu")
		(net "M_D_CPU1_SB_DQS_DN<2>")
	)
	(segment
		(start 23.545292 -209.898996)
		(end 23.420832 -209.774536)
		(width 0.18288)
		(layer "In6.Cu")
		(net "M_D_CPU1_SB_DQS_DN<2>")
	)
	(segment
		(start 63.181738 -211.982558)
		(end 62.674754 -211.772754)
		(width 0.18288)
		(layer "In6.Cu")
		(net "M_D_CPU1_SB_DQS_DN<2>")
	)
	(segment
		(start 28.429966 -209.243422)
		(end 27.469846 -209.243422)
		(width 0.18288)
		(layer "In6.Cu")
		(net "M_D_CPU1_SB_DQS_DN<2>")
	)
	(segment
		(start 36.46805 -209.894424)
		(end 36.21532 -209.641694)
		(width 0.18288)
		(layer "In6.Cu")
		(net "M_D_CPU1_SB_DQS_DN<2>")
	)
	(segment
		(start 84.12099 -231.165654)
		(end 83.922108 -230.966772)
		(width 0.088646)
		(layer "In6.Cu")
		(net "M_D_CPU1_SB_DQS_DN<2>")
	)
	(segment
		(start 38.766496 -209.769964)
		(end 38.217856 -209.769964)
		(width 0.18288)
		(layer "In6.Cu")
		(net "M_D_CPU1_SB_DQS_DN<2>")
	)
	(segment
		(start 74.047858 -225.62058)
		(end 74.047858 -222.713804)
		(width 0.18288)
		(layer "In6.Cu")
		(net "M_D_CPU1_SB_DQS_DN<2>")
	)
	(segment
		(start 77.582522 -229.155244)
		(end 74.047858 -225.62058)
		(width 0.18288)
		(layer "In6.Cu")
		(net "M_D_CPU1_SB_DQS_DN<2>")
	)
	(segment
		(start 38.093396 -209.894424)
		(end 36.46805 -209.894424)
		(width 0.18288)
		(layer "In6.Cu")
		(net "M_D_CPU1_SB_DQS_DN<2>")
	)
	(segment
		(start 92.101924 -232.846626)
		(end 92.09151 -232.852722)
		(width 0.088646)
		(layer "In6.Cu")
		(net "M_D_CPU1_SB_DQS_DN<2>")
	)
	(segment
		(start 31.033466 -210.765136)
		(end 30.695646 -210.624928)
		(width 0.18288)
		(layer "In6.Cu")
		(net "M_D_CPU1_SB_DQS_DN<2>")
	)
	(segment
		(start 49.886108 -209.900012)
		(end 49.321466 -210.4644)
		(width 0.18288)
		(layer "In6.Cu")
		(net "M_D_CPU1_SB_DQS_DN<2>")
	)
	(segment
		(start 47.449994 -210.771994)
		(end 47.170848 -210.492848)
		(width 0.18288)
		(layer "In6.Cu")
		(net "M_D_CPU1_SB_DQS_DN<2>")
	)
	(segment
		(start 94.723966 -232.528364)
		(end 94.692216 -232.644188)
		(width 0.088646)
		(layer "In6.Cu")
		(net "M_D_CPU1_SB_DQS_DN<2>")
	)
	(segment
		(start 62.674754 -211.772754)
		(end 62.512194 -211.840064)
		(width 0.18288)
		(layer "In6.Cu")
		(net "M_D_CPU1_SB_DQS_DN<2>")
	)
	(segment
		(start 26.796746 -209.118962)
		(end 26.672286 -209.243422)
		(width 0.18288)
		(layer "In6.Cu")
		(net "M_D_CPU1_SB_DQS_DN<2>")
	)
	(segment
		(start 22.872192 -209.774536)
		(end 22.747732 -209.898996)
		(width 0.18288)
		(layer "In6.Cu")
		(net "M_D_CPU1_SB_DQS_DN<2>")
	)
	(segment
		(start 46.487842 -210.767422)
		(end 45.807884 -210.767422)
		(width 0.18288)
		(layer "In6.Cu")
		(net "M_D_CPU1_SB_DQS_DN<2>")
	)
	(segment
		(start 65.469008 -215.10625)
		(end 64.608456 -213.0298)
		(width 0.18288)
		(layer "In6.Cu")
		(net "M_D_CPU1_SB_DQS_DN<2>")
	)
	(segment
		(start 48.579278 -210.771994)
		(end 47.449994 -210.771994)
		(width 0.18288)
		(layer "In6.Cu")
		(net "M_D_CPU1_SB_DQS_DN<2>")
	)
	(segment
		(start 43.098466 -209.155284)
		(end 42.974006 -209.279744)
		(width 0.18288)
		(layer "In6.Cu")
		(net "M_D_CPU1_SB_DQS_DN<2>")
	)
	(segment
		(start 58.37555 -210.9597)
		(end 58.27776 -210.813142)
		(width 0.18288)
		(layer "In6.Cu")
		(net "M_D_CPU1_SB_DQS_DN<2>")
	)
	(segment
		(start 57.592976 -210.803998)
		(end 55.85587 -210.458558)
		(width 0.18288)
		(layer "In6.Cu")
		(net "M_D_CPU1_SB_DQS_DN<2>")
	)
	(segment
		(start 17.047718 -209.475324)
		(end 16.789146 -209.216752)
		(width 0.18288)
		(layer "In6.Cu")
		(net "M_D_CPU1_SB_DQS_DN<2>")
	)
	(segment
		(start 44.778168 -209.737706)
		(end 44.320206 -209.279744)
		(width 0.18288)
		(layer "In6.Cu")
		(net "M_D_CPU1_SB_DQS_DN<2>")
	)
	(segment
		(start 27.345386 -209.118962)
		(end 26.796746 -209.118962)
		(width 0.18288)
		(layer "In6.Cu")
		(net "M_D_CPU1_SB_DQS_DN<2>")
	)
	(segment
		(start 52.37607 -209.897472)
		(end 51.530758 -209.897472)
		(width 0.18288)
		(layer "In6.Cu")
		(net "M_D_CPU1_SB_DQS_DN<2>")
	)
	(segment
		(start 20.666202 -209.641694)
		(end 20.415758 -209.892138)
		(width 0.18288)
		(layer "In6.Cu")
		(net "M_D_CPU1_SB_DQS_DN<2>")
	)
	(segment
		(start 58.27776 -210.813142)
		(end 57.73928 -210.706208)
		(width 0.18288)
		(layer "In6.Cu")
		(net "M_D_CPU1_SB_DQS_DN<2>")
	)
	(segment
		(start 55.111904 -210.15071)
		(end 53.975508 -210.15071)
		(width 0.18288)
		(layer "In6.Cu")
		(net "M_D_CPU1_SB_DQS_DN<2>")
	)
	(segment
		(start 24.387556 -209.898996)
		(end 23.545292 -209.898996)
		(width 0.18288)
		(layer "In6.Cu")
		(net "M_D_CPU1_SB_DQS_DN<2>")
	)
	(segment
		(start 32.939736 -210.511136)
		(end 32.707834 -210.743038)
		(width 0.18288)
		(layer "In6.Cu")
		(net "M_D_CPU1_SB_DQS_DN<2>")
	)
	(segment
		(start 47.170848 -210.492848)
		(end 46.762416 -210.492848)
		(width 0.18288)
		(layer "In6.Cu")
		(net "M_D_CPU1_SB_DQS_DN<2>")
	)
	(segment
		(start 32.707834 -210.743038)
		(end 32.366458 -210.743038)
		(width 0.18288)
		(layer "In6.Cu")
		(net "M_D_CPU1_SB_DQS_DN<2>")
	)
	(segment
		(start 25.96896 -209.243422)
		(end 24.387556 -209.898996)
		(width 0.18288)
		(layer "In6.Cu")
		(net "M_D_CPU1_SB_DQS_DN<2>")
	)
	(segment
		(start 27.469846 -209.243422)
		(end 27.345386 -209.118962)
		(width 0.18288)
		(layer "In6.Cu")
		(net "M_D_CPU1_SB_DQS_DN<2>")
	)
	(segment
		(start 41.752266 -209.155284)
		(end 41.627806 -209.279744)
		(width 0.18288)
		(layer "In6.Cu")
		(net "M_D_CPU1_SB_DQS_DN<2>")
	)
	(segment
		(start 31.38043 -210.765136)
		(end 31.033466 -210.765136)
		(width 0.18288)
		(layer "In6.Cu")
		(net "M_D_CPU1_SB_DQS_DN<2>")
	)
	(segment
		(start 23.420832 -209.774536)
		(end 22.872192 -209.774536)
		(width 0.18288)
		(layer "In6.Cu")
		(net "M_D_CPU1_SB_DQS_DN<2>")
	)
	(segment
		(start 58.913522 -211.066634)
		(end 58.37555 -210.9597)
		(width 0.18288)
		(layer "In6.Cu")
		(net "M_D_CPU1_SB_DQS_DN<2>")
	)
	(segment
		(start 21.12772 -209.641694)
		(end 20.666202 -209.641694)
		(width 0.18288)
		(layer "In6.Cu")
		(net "M_D_CPU1_SB_DQS_DN<2>")
	)
	(segment
		(start 45.342302 -210.30184)
		(end 45.342302 -210.125818)
		(width 0.18288)
		(layer "In6.Cu")
		(net "M_D_CPU1_SB_DQS_DN<2>")
	)
	(segment
		(start 18.33245 -209.24647)
		(end 17.779746 -209.475324)
		(width 0.18288)
		(layer "In6.Cu")
		(net "M_D_CPU1_SB_DQS_DN<2>")
	)
	(segment
		(start 18.727674 -209.24647)
		(end 18.33245 -209.24647)
		(width 0.18288)
		(layer "In6.Cu")
		(net "M_D_CPU1_SB_DQS_DN<2>")
	)
	(segment
		(start 36.21532 -209.641694)
		(end 35.753802 -209.641694)
		(width 0.18288)
		(layer "In6.Cu")
		(net "M_D_CPU1_SB_DQS_DN<2>")
	)
	(segment
		(start 66.290698 -215.928194)
		(end 65.469008 -215.10625)
		(width 0.18288)
		(layer "In6.Cu")
		(net "M_D_CPU1_SB_DQS_DN<2>")
	)
	(segment
		(start 43.647106 -209.155284)
		(end 43.098466 -209.155284)
		(width 0.18288)
		(layer "In6.Cu")
		(net "M_D_CPU1_SB_DQS_DN<2>")
	)
	(segment
		(start 53.975508 -210.15071)
		(end 53.851048 -210.02625)
		(width 0.18288)
		(layer "In6.Cu")
		(net "M_D_CPU1_SB_DQS_DN<2>")
	)
	(segment
		(start 85.421216 -231.714548)
		(end 85.421216 -231.696006)
		(width 0.088646)
		(layer "In6.Cu")
		(net "M_D_CPU1_SB_DQS_DN<2>")
	)
	(segment
		(start 17.779746 -209.475324)
		(end 17.047718 -209.475324)
		(width 0.18288)
		(layer "In6.Cu")
		(net "M_D_CPU1_SB_DQS_DN<2>")
	)
	(segment
		(start 53.177948 -210.15071)
		(end 52.629308 -210.15071)
		(width 0.18288)
		(layer "In6.Cu")
		(net "M_D_CPU1_SB_DQS_DN<2>")
	)
	(segment
		(start 32.115252 -210.491832)
		(end 31.653734 -210.491832)
		(width 0.18288)
		(layer "In6.Cu")
		(net "M_D_CPU1_SB_DQS_DN<2>")
	)
	(segment
		(start 89.371932 -232.041446)
		(end 89.352882 -232.03027)
		(width 0.088646)
		(layer "In6.Cu")
		(net "M_D_CPU1_SB_DQS_DN<2>")
	)
	(segment
		(start 45.807884 -210.767422)
		(end 45.342302 -210.30184)
		(width 0.18288)
		(layer "In6.Cu")
		(net "M_D_CPU1_SB_DQS_DN<2>")
	)
	(segment
		(start 53.302408 -210.02625)
		(end 53.177948 -210.15071)
		(width 0.18288)
		(layer "In6.Cu")
		(net "M_D_CPU1_SB_DQS_DN<2>")
	)
	(segment
		(start 55.85587 -210.458558)
		(end 55.111904 -210.15071)
		(width 0.18288)
		(layer "In6.Cu")
		(net "M_D_CPU1_SB_DQS_DN<2>")
	)
	(segment
		(start 94.692216 -232.644188)
		(end 94.653354 -232.666286)
		(width 0.088646)
		(layer "In6.Cu")
		(net "M_D_CPU1_SB_DQS_DN<2>")
	)
	(segment
		(start 40.924226 -209.279744)
		(end 39.439596 -209.894424)
		(width 0.18288)
		(layer "In6.Cu")
		(net "M_D_CPU1_SB_DQS_DN<2>")
	)
	(segment
		(start 41.627806 -209.279744)
		(end 40.924226 -209.279744)
		(width 0.18288)
		(layer "In6.Cu")
		(net "M_D_CPU1_SB_DQS_DN<2>")
	)
	(segment
		(start 62.512194 -211.840064)
		(end 61.368178 -211.366354)
		(width 0.18288)
		(layer "In6.Cu")
		(net "M_D_CPU1_SB_DQS_DN<2>")
	)
	(segment
		(start 67.262248 -215.928194)
		(end 66.290698 -215.928194)
		(width 0.18288)
		(layer "In6.Cu")
		(net "M_D_CPU1_SB_DQS_DN<2>")
	)
	(segment
		(start 32.366458 -210.743038)
		(end 32.115252 -210.491832)
		(width 0.18288)
		(layer "In6.Cu")
		(net "M_D_CPU1_SB_DQS_DN<2>")
	)
	(segment
		(start 88.427814 -232.038906)
		(end 88.4174 -232.03281)
		(width 0.088646)
		(layer "In6.Cu")
		(net "M_D_CPU1_SB_DQS_DN<2>")
	)
	(segment
		(start 50.855372 -209.640932)
		(end 50.596292 -209.900012)
		(width 0.18288)
		(layer "In6.Cu")
		(net "M_D_CPU1_SB_DQS_DN<2>")
	)
	(segment
		(start 44.95419 -209.737706)
		(end 44.778168 -209.737706)
		(width 0.18288)
		(layer "In6.Cu")
		(net "M_D_CPU1_SB_DQS_DN<2>")
	)
	(segment
		(start 94.224348 -232.70718)
		(end 93.971618 -232.852722)
		(width 0.088646)
		(layer "In6.Cu")
		(net "M_D_CPU1_SB_DQS_DN<2>")
	)
	(segment
		(start 20.415758 -209.892138)
		(end 19.743166 -209.892138)
		(width 0.18288)
		(layer "In6.Cu")
		(net "M_D_CPU1_SB_DQS_DN<2>")
	)
	(segment
		(start 83.199478 -229.776528)
		(end 83.199478 -229.433374)
		(width 0.088646)
		(layer "In6.Cu")
		(net "M_D_CPU1_SB_DQS_DN<2>")
	)
	(segment
		(start 91.717114 -232.852722)
		(end 91.7067 -232.846626)
		(width 0.088646)
		(layer "In6.Cu")
		(net "M_D_CPU1_SB_DQS_DN<2>")
	)
	(segment
		(start 74.047858 -222.713804)
		(end 67.262248 -215.928194)
		(width 0.18288)
		(layer "In6.Cu")
		(net "M_D_CPU1_SB_DQS_DN<2>")
	)
	(segment
		(start 83.922108 -230.966772)
		(end 83.922108 -230.499158)
		(width 0.088646)
		(layer "In6.Cu")
		(net "M_D_CPU1_SB_DQS_DN<2>")
	)
	(arc
		(start 88.4174 -232.03281)
		(mid 88.139222 -231.963087)
		(end 87.862664 -232.038906)
		(width 0.088646)
		(layer "In6.Cu")
		(net "M_D_CPU1_SB_DQS_DN<2>")
	)
	(arc
		(start 92.657168 -232.852722)
		(mid 92.380355 -232.776852)
		(end 92.101924 -232.846626)
		(width 0.088646)
		(layer "In6.Cu")
		(net "M_D_CPU1_SB_DQS_DN<2>")
	)
	(arc
		(start 93.031564 -232.852722)
		(mid 92.844366 -232.902865)
		(end 92.657168 -232.852722)
		(width 0.088646)
		(layer "In6.Cu")
		(net "M_D_CPU1_SB_DQS_DN<2>")
	)
	(arc
		(start 94.653354 -232.666286)
		(mid 94.578669 -232.696791)
		(end 94.498668 -232.70718)
		(width 0.088646)
		(layer "In6.Cu")
		(net "M_D_CPU1_SB_DQS_DN<2>")
	)
	(arc
		(start 91.7067 -232.846626)
		(mid 91.428522 -232.776903)
		(end 91.151964 -232.852722)
		(width 0.088646)
		(layer "In6.Cu")
		(net "M_D_CPU1_SB_DQS_DN<2>")
	)
	(arc
		(start 93.971364 -232.852722)
		(mid 93.784166 -232.902865)
		(end 93.596968 -232.852722)
		(width 0.088646)
		(layer "In6.Cu")
		(net "M_D_CPU1_SB_DQS_DN<2>")
	)
	(arc
		(start 89.352882 -232.03027)
		(mid 89.076407 -231.96295)
		(end 88.80221 -232.038906)
		(width 0.088646)
		(layer "In6.Cu")
		(net "M_D_CPU1_SB_DQS_DN<2>")
	)
	(arc
		(start 91.151964 -232.852722)
		(mid 90.964766 -232.902865)
		(end 90.777568 -232.852722)
		(width 0.088646)
		(layer "In6.Cu")
		(net "M_D_CPU1_SB_DQS_DN<2>")
	)
	(arc
		(start 90.777568 -232.852722)
		(mid 90.503369 -232.776887)
		(end 90.226896 -232.844086)
		(width 0.088646)
		(layer "In6.Cu")
		(net "M_D_CPU1_SB_DQS_DN<2>")
	)
	(arc
		(start 93.596968 -232.852722)
		(mid 93.322769 -232.776887)
		(end 93.046296 -232.844086)
		(width 0.088646)
		(layer "In6.Cu")
		(net "M_D_CPU1_SB_DQS_DN<2>")
	)
	(arc
		(start 86.548468 -232.038906)
		(mid 86.265766 -231.96313)
		(end 85.983064 -232.038906)
		(width 0.088646)
		(layer "In6.Cu")
		(net "M_D_CPU1_SB_DQS_DN<2>")
	)
	(arc
		(start 87.862664 -232.038906)
		(mid 87.675466 -232.089049)
		(end 87.488268 -232.038906)
		(width 0.088646)
		(layer "In6.Cu")
		(net "M_D_CPU1_SB_DQS_DN<2>")
	)
	(arc
		(start 92.09151 -232.852722)
		(mid 91.904312 -232.902865)
		(end 91.717114 -232.852722)
		(width 0.088646)
		(layer "In6.Cu")
		(net "M_D_CPU1_SB_DQS_DN<2>")
	)
	(arc
		(start 84.573364 -231.224836)
		(mid 84.386166 -231.274979)
		(end 84.198968 -231.224836)
		(width 0.088646)
		(layer "In6.Cu")
		(net "M_D_CPU1_SB_DQS_DN<2>")
	)
	(arc
		(start 84.198968 -231.224836)
		(mid 84.158038 -231.197803)
		(end 84.12099 -231.165654)
		(width 0.088646)
		(layer "In6.Cu")
		(net "M_D_CPU1_SB_DQS_DN<2>")
	)
	(arc
		(start 86.922864 -232.038906)
		(mid 86.735666 -232.089049)
		(end 86.548468 -232.038906)
		(width 0.088646)
		(layer "In6.Cu")
		(net "M_D_CPU1_SB_DQS_DN<2>")
	)
	(arc
		(start 89.650316 -232.528364)
		(mid 89.575818 -232.247908)
		(end 89.371932 -232.041446)
		(width 0.088646)
		(layer "In6.Cu")
		(net "M_D_CPU1_SB_DQS_DN<2>")
	)
	(arc
		(start 85.983064 -232.038906)
		(mid 85.608589 -232.03886)
		(end 85.421216 -231.714548)
		(width 0.088646)
		(layer "In6.Cu")
		(net "M_D_CPU1_SB_DQS_DN<2>")
	)
	(arc
		(start 88.80221 -232.038906)
		(mid 88.615012 -232.089049)
		(end 88.427814 -232.038906)
		(width 0.088646)
		(layer "In6.Cu")
		(net "M_D_CPU1_SB_DQS_DN<2>")
	)
	(arc
		(start 85.421216 -231.696006)
		(mid 85.130738 -231.220287)
		(end 84.573364 -231.224836)
		(width 0.088646)
		(layer "In6.Cu")
		(net "M_D_CPU1_SB_DQS_DN<2>")
	)
	(arc
		(start 90.212164 -232.852722)
		(mid 89.837689 -232.852676)
		(end 89.650316 -232.528364)
		(width 0.088646)
		(layer "In6.Cu")
		(net "M_D_CPU1_SB_DQS_DN<2>")
	)
	(arc
		(start 87.488268 -232.038906)
		(mid 87.205566 -231.96313)
		(end 86.922864 -232.038906)
		(width 0.088646)
		(layer "In6.Cu")
		(net "M_D_CPU1_SB_DQS_DN<2>")
	)
	(segment
		(start 15.137638 -218.566746)
		(end 14.876526 -218.827858)
		(width 0.20066)
		(layer "F.Cu")
		(net "M_D_CPU1_SB_DQS_DN<1>")
	)
	(segment
		(start 10.912094 -218.98102)
		(end 10.64006 -219.253054)
		(width 0.20066)
		(layer "F.Cu")
		(net "M_D_CPU1_SB_DQS_DN<1>")
	)
	(segment
		(start 16.789146 -218.566746)
		(end 15.684246 -218.566746)
		(width 0.20066)
		(layer "F.Cu")
		(net "M_D_CPU1_SB_DQS_DN<1>")
	)
	(segment
		(start 98.013266 -234.97032)
		(end 98.013012 -234.970066)
		(width 0.20066)
		(layer "F.Cu")
		(net "M_D_CPU1_SB_DQS_DN<1>")
	)
	(segment
		(start 98.013266 -235.506006)
		(end 98.013266 -234.97032)
		(width 0.20066)
		(layer "F.Cu")
		(net "M_D_CPU1_SB_DQS_DN<1>")
	)
	(segment
		(start 13.59662 -218.991688)
		(end 13.441426 -218.991688)
		(width 0.20066)
		(layer "F.Cu")
		(net "M_D_CPU1_SB_DQS_DN<1>")
	)
	(segment
		(start 14.044676 -219.253054)
		(end 13.857986 -219.253054)
		(width 0.20066)
		(layer "F.Cu")
		(net "M_D_CPU1_SB_DQS_DN<1>")
	)
	(segment
		(start 11.117072 -218.98102)
		(end 11.11631 -218.98102)
		(width 0.101854)
		(layer "F.Cu")
		(net "M_D_CPU1_SB_DQS_DN<1>")
	)
	(segment
		(start 8.950198 -218.827858)
		(end 8.689086 -218.566746)
		(width 0.20066)
		(layer "F.Cu")
		(net "M_D_CPU1_SB_DQS_DN<1>")
	)
	(segment
		(start 13.441426 -218.991688)
		(end 11.12774 -218.991688)
		(width 0.1016)
		(layer "F.Cu")
		(net "M_D_CPU1_SB_DQS_DN<1>")
	)
	(segment
		(start 11.11631 -218.98102)
		(end 10.912094 -218.98102)
		(width 0.20066)
		(layer "F.Cu")
		(net "M_D_CPU1_SB_DQS_DN<1>")
	)
	(segment
		(start 14.876526 -218.827858)
		(end 14.469872 -218.827858)
		(width 0.20066)
		(layer "F.Cu")
		(net "M_D_CPU1_SB_DQS_DN<1>")
	)
	(segment
		(start 13.857986 -219.253054)
		(end 13.59662 -218.991688)
		(width 0.20066)
		(layer "F.Cu")
		(net "M_D_CPU1_SB_DQS_DN<1>")
	)
	(segment
		(start 10.64006 -219.253054)
		(end 10.100056 -219.253054)
		(width 0.20066)
		(layer "F.Cu")
		(net "M_D_CPU1_SB_DQS_DN<1>")
	)
	(segment
		(start 11.12774 -218.991688)
		(end 11.117072 -218.98102)
		(width 0.101854)
		(layer "F.Cu")
		(net "M_D_CPU1_SB_DQS_DN<1>")
	)
	(segment
		(start 10.100056 -219.253054)
		(end 9.46404 -218.827858)
		(width 0.20066)
		(layer "F.Cu")
		(net "M_D_CPU1_SB_DQS_DN<1>")
	)
	(segment
		(start 8.689086 -218.566746)
		(end 8.140446 -218.566746)
		(width 0.20066)
		(layer "F.Cu")
		(net "M_D_CPU1_SB_DQS_DN<1>")
	)
	(segment
		(start 14.469872 -218.827858)
		(end 14.044676 -219.253054)
		(width 0.20066)
		(layer "F.Cu")
		(net "M_D_CPU1_SB_DQS_DN<1>")
	)
	(segment
		(start 9.46404 -218.827858)
		(end 8.950198 -218.827858)
		(width 0.20066)
		(layer "F.Cu")
		(net "M_D_CPU1_SB_DQS_DN<1>")
	)
	(segment
		(start 15.684246 -218.566746)
		(end 15.137638 -218.566746)
		(width 0.20066)
		(layer "F.Cu")
		(net "M_D_CPU1_SB_DQS_DN<1>")
	)
	(segment
		(start 90.307414 -233.666538)
		(end 90.292682 -233.657902)
		(width 0.088646)
		(layer "In11.Cu")
		(net "M_D_CPU1_SB_DQS_DN<1>")
	)
	(segment
		(start 84.385912 -232.903522)
		(end 84.148676 -232.903522)
		(width 0.088646)
		(layer "In11.Cu")
		(net "M_D_CPU1_SB_DQS_DN<1>")
	)
	(segment
		(start 89.180162 -233.34218)
		(end 89.180162 -233.326686)
		(width 0.088646)
		(layer "In11.Cu")
		(net "M_D_CPU1_SB_DQS_DN<1>")
	)
	(segment
		(start 82.43316 -231.132126)
		(end 82.37347 -231.072436)
		(width 0.088646)
		(layer "In11.Cu")
		(net "M_D_CPU1_SB_DQS_DN<1>")
	)
	(segment
		(start 35.46348 -211.661248)
		(end 34.84499 -211.661248)
		(width 0.18288)
		(layer "In11.Cu")
		(net "M_D_CPU1_SB_DQS_DN<1>")
	)
	(segment
		(start 89.367614 -233.666538)
		(end 89.358724 -233.661458)
		(width 0.088646)
		(layer "In11.Cu")
		(net "M_D_CPU1_SB_DQS_DN<1>")
	)
	(segment
		(start 47.478442 -212.45449)
		(end 47.21352 -212.189568)
		(width 0.18288)
		(layer "In11.Cu")
		(net "M_D_CPU1_SB_DQS_DN<1>")
	)
	(segment
		(start 26.836116 -215.32596)
		(end 26.711656 -215.45042)
		(width 0.18288)
		(layer "In11.Cu")
		(net "M_D_CPU1_SB_DQS_DN<1>")
	)
	(segment
		(start 46.492922 -212.471762)
		(end 45.883068 -212.471762)
		(width 0.18288)
		(layer "In11.Cu")
		(net "M_D_CPU1_SB_DQS_DN<1>")
	)
	(segment
		(start 52.794916 -211.591144)
		(end 51.547268 -211.591144)
		(width 0.18288)
		(layer "In11.Cu")
		(net "M_D_CPU1_SB_DQS_DN<1>")
	)
	(segment
		(start 95.006414 -235.294424)
		(end 94.991682 -235.285788)
		(width 0.088646)
		(layer "In11.Cu")
		(net "M_D_CPU1_SB_DQS_DN<1>")
	)
	(segment
		(start 92.939362 -234.970066)
		(end 92.939362 -234.954572)
		(width 0.088646)
		(layer "In11.Cu")
		(net "M_D_CPU1_SB_DQS_DN<1>")
	)
	(segment
		(start 19.716496 -219.23756)
		(end 19.31797 -218.83878)
		(width 0.18288)
		(layer "In11.Cu")
		(net "M_D_CPU1_SB_DQS_DN<1>")
	)
	(segment
		(start 83.135724 -231.409748)
		(end 82.858102 -231.132126)
		(width 0.088646)
		(layer "In11.Cu")
		(net "M_D_CPU1_SB_DQS_DN<1>")
	)
	(segment
		(start 32.362648 -212.454236)
		(end 32.09925 -212.190838)
		(width 0.18288)
		(layer "In11.Cu")
		(net "M_D_CPU1_SB_DQS_DN<1>")
	)
	(segment
		(start 38.78072 -211.462366)
		(end 38.23208 -211.462366)
		(width 0.18288)
		(layer "In11.Cu")
		(net "M_D_CPU1_SB_DQS_DN<1>")
	)
	(segment
		(start 92.469716 -234.15625)
		(end 92.469716 -234.142026)
		(width 0.088646)
		(layer "In11.Cu")
		(net "M_D_CPU1_SB_DQS_DN<1>")
	)
	(segment
		(start 39.45382 -211.586826)
		(end 38.90518 -211.586826)
		(width 0.18288)
		(layer "In11.Cu")
		(net "M_D_CPU1_SB_DQS_DN<1>")
	)
	(segment
		(start 92.187014 -233.666538)
		(end 92.1766 -233.660442)
		(width 0.088646)
		(layer "In11.Cu")
		(net "M_D_CPU1_SB_DQS_DN<1>")
	)
	(segment
		(start 18.782538 -218.617292)
		(end 17.861026 -218.617292)
		(width 0.18288)
		(layer "In11.Cu")
		(net "M_D_CPU1_SB_DQS_DN<1>")
	)
	(segment
		(start 80.276954 -231.072436)
		(end 68.581524 -219.377006)
		(width 0.18288)
		(layer "In11.Cu")
		(net "M_D_CPU1_SB_DQS_DN<1>")
	)
	(segment
		(start 51.547268 -211.591144)
		(end 51.297078 -211.340954)
		(width 0.18288)
		(layer "In11.Cu")
		(net "M_D_CPU1_SB_DQS_DN<1>")
	)
	(segment
		(start 17.861026 -218.617292)
		(end 17.399762 -218.8083)
		(width 0.18288)
		(layer "In11.Cu")
		(net "M_D_CPU1_SB_DQS_DN<1>")
	)
	(segment
		(start 45.883068 -212.471762)
		(end 45.400976 -212.953854)
		(width 0.18288)
		(layer "In11.Cu")
		(net "M_D_CPU1_SB_DQS_DN<1>")
	)
	(segment
		(start 40.278304 -211.793582)
		(end 40.11549 -211.860892)
		(width 0.18288)
		(layer "In11.Cu")
		(net "M_D_CPU1_SB_DQS_DN<1>")
	)
	(segment
		(start 93.12529 -235.293662)
		(end 93.117924 -235.289344)
		(width 0.088646)
		(layer "In11.Cu")
		(net "M_D_CPU1_SB_DQS_DN<1>")
	)
	(segment
		(start 30.102302 -211.850732)
		(end 29.21127 -211.850732)
		(width 0.18288)
		(layer "In11.Cu")
		(net "M_D_CPU1_SB_DQS_DN<1>")
	)
	(segment
		(start 52.919376 -211.466684)
		(end 52.794916 -211.591144)
		(width 0.18288)
		(layer "In11.Cu")
		(net "M_D_CPU1_SB_DQS_DN<1>")
	)
	(segment
		(start 63.880238 -215.885268)
		(end 63.151512 -215.583516)
		(width 0.18288)
		(layer "In11.Cu")
		(net "M_D_CPU1_SB_DQS_DN<1>")
	)
	(segment
		(start 97.514156 -235.148882)
		(end 97.260918 -235.294678)
		(width 0.088646)
		(layer "In11.Cu")
		(net "M_D_CPU1_SB_DQS_DN<1>")
	)
	(segment
		(start 66.84645 -216.145364)
		(end 66.222118 -215.885268)
		(width 0.18288)
		(layer "In11.Cu")
		(net "M_D_CPU1_SB_DQS_DN<1>")
	)
	(segment
		(start 20.688554 -218.990926)
		(end 20.44192 -219.23756)
		(width 0.18288)
		(layer "In11.Cu")
		(net "M_D_CPU1_SB_DQS_DN<1>")
	)
	(segment
		(start 38.90518 -211.586826)
		(end 38.78072 -211.462366)
		(width 0.18288)
		(layer "In11.Cu")
		(net "M_D_CPU1_SB_DQS_DN<1>")
	)
	(segment
		(start 62.414404 -215.278208)
		(end 61.743844 -215.000586)
		(width 0.18288)
		(layer "In11.Cu")
		(net "M_D_CPU1_SB_DQS_DN<1>")
	)
	(segment
		(start 34.84499 -211.661248)
		(end 34.052002 -212.454236)
		(width 0.18288)
		(layer "In11.Cu")
		(net "M_D_CPU1_SB_DQS_DN<1>")
	)
	(segment
		(start 26.008076 -217.751152)
		(end 23.155656 -218.93276)
		(width 0.18288)
		(layer "In11.Cu")
		(net "M_D_CPU1_SB_DQS_DN<1>")
	)
	(segment
		(start 26.836116 -213.62416)
		(end 26.836116 -215.32596)
		(width 0.18288)
		(layer "In11.Cu")
		(net "M_D_CPU1_SB_DQS_DN<1>")
	)
	(segment
		(start 23.155656 -218.93276)
		(end 22.829266 -219.259404)
		(width 0.18288)
		(layer "In11.Cu")
		(net "M_D_CPU1_SB_DQS_DN<1>")
	)
	(segment
		(start 50.54092 -211.671408)
		(end 49.896522 -211.671408)
		(width 0.18288)
		(layer "In11.Cu")
		(net "M_D_CPU1_SB_DQS_DN<1>")
	)
	(segment
		(start 49.896522 -211.671408)
		(end 49.476152 -212.091524)
		(width 0.18288)
		(layer "In11.Cu")
		(net "M_D_CPU1_SB_DQS_DN<1>")
	)
	(segment
		(start 38.10762 -211.586826)
		(end 36.47567 -211.586826)
		(width 0.18288)
		(layer "In11.Cu")
		(net "M_D_CPU1_SB_DQS_DN<1>")
	)
	(segment
		(start 30.72765 -212.47608)
		(end 30.102302 -211.850732)
		(width 0.18288)
		(layer "In11.Cu")
		(net "M_D_CPU1_SB_DQS_DN<1>")
	)
	(segment
		(start 54.198266 -211.591144)
		(end 53.592476 -211.591144)
		(width 0.18288)
		(layer "In11.Cu")
		(net "M_D_CPU1_SB_DQS_DN<1>")
	)
	(segment
		(start 83.135724 -231.89057)
		(end 83.135724 -231.409748)
		(width 0.088646)
		(layer "In11.Cu")
		(net "M_D_CPU1_SB_DQS_DN<1>")
	)
	(segment
		(start 53.468016 -211.466684)
		(end 52.919376 -211.466684)
		(width 0.18288)
		(layer "In11.Cu")
		(net "M_D_CPU1_SB_DQS_DN<1>")
	)
	(segment
		(start 64.852804 -215.760808)
		(end 64.728344 -215.885268)
		(width 0.18288)
		(layer "In11.Cu")
		(net "M_D_CPU1_SB_DQS_DN<1>")
	)
	(segment
		(start 63.084202 -215.420702)
		(end 62.576964 -215.210898)
		(width 0.18288)
		(layer "In11.Cu")
		(net "M_D_CPU1_SB_DQS_DN<1>")
	)
	(segment
		(start 56.653684 -212.607906)
		(end 55.766716 -212.240622)
		(width 0.18288)
		(layer "In11.Cu")
		(net "M_D_CPU1_SB_DQS_DN<1>")
	)
	(segment
		(start 95.946214 -235.294424)
		(end 95.931482 -235.285788)
		(width 0.088646)
		(layer "In11.Cu")
		(net "M_D_CPU1_SB_DQS_DN<1>")
	)
	(segment
		(start 21.428456 -219.259404)
		(end 21.159978 -218.990926)
		(width 0.18288)
		(layer "In11.Cu")
		(net "M_D_CPU1_SB_DQS_DN<1>")
	)
	(segment
		(start 45.080936 -213.086442)
		(end 44.547282 -213.086442)
		(width 0.18288)
		(layer "In11.Cu")
		(net "M_D_CPU1_SB_DQS_DN<1>")
	)
	(segment
		(start 50.871374 -211.340954)
		(end 50.54092 -211.671408)
		(width 0.18288)
		(layer "In11.Cu")
		(net "M_D_CPU1_SB_DQS_DN<1>")
	)
	(segment
		(start 66.222118 -215.885268)
		(end 65.525904 -215.885268)
		(width 0.18288)
		(layer "In11.Cu")
		(net "M_D_CPU1_SB_DQS_DN<1>")
	)
	(segment
		(start 84.148676 -232.903522)
		(end 83.135724 -231.89057)
		(width 0.088646)
		(layer "In11.Cu")
		(net "M_D_CPU1_SB_DQS_DN<1>")
	)
	(segment
		(start 82.37347 -231.072436)
		(end 80.276954 -231.072436)
		(width 0.18288)
		(layer "In11.Cu")
		(net "M_D_CPU1_SB_DQS_DN<1>")
	)
	(segment
		(start 55.192168 -211.868004)
		(end 55.029608 -211.935314)
		(width 0.18288)
		(layer "In11.Cu")
		(net "M_D_CPU1_SB_DQS_DN<1>")
	)
	(segment
		(start 97.260918 -235.294678)
		(end 97.260664 -235.294424)
		(width 0.088646)
		(layer "In11.Cu")
		(net "M_D_CPU1_SB_DQS_DN<1>")
	)
	(segment
		(start 67.523106 -216.821766)
		(end 66.84645 -216.145364)
		(width 0.18288)
		(layer "In11.Cu")
		(net "M_D_CPU1_SB_DQS_DN<1>")
	)
	(segment
		(start 59.950858 -213.2076)
		(end 58.50255 -212.607906)
		(width 0.18288)
		(layer "In11.Cu")
		(net "M_D_CPU1_SB_DQS_DN<1>")
	)
	(segment
		(start 27.680412 -212.779864)
		(end 26.836116 -213.62416)
		(width 0.18288)
		(layer "In11.Cu")
		(net "M_D_CPU1_SB_DQS_DN<1>")
	)
	(segment
		(start 55.766716 -212.240622)
		(end 55.699152 -212.077808)
		(width 0.18288)
		(layer "In11.Cu")
		(net "M_D_CPU1_SB_DQS_DN<1>")
	)
	(segment
		(start 34.052002 -212.454236)
		(end 32.362648 -212.454236)
		(width 0.18288)
		(layer "In11.Cu")
		(net "M_D_CPU1_SB_DQS_DN<1>")
	)
	(segment
		(start 82.858102 -231.132126)
		(end 82.43316 -231.132126)
		(width 0.088646)
		(layer "In11.Cu")
		(net "M_D_CPU1_SB_DQS_DN<1>")
	)
	(segment
		(start 60.748418 -213.829138)
		(end 60.572396 -213.829138)
		(width 0.18288)
		(layer "In11.Cu")
		(net "M_D_CPU1_SB_DQS_DN<1>")
	)
	(segment
		(start 26.711656 -215.99906)
		(end 26.836116 -216.12352)
		(width 0.18288)
		(layer "In11.Cu")
		(net "M_D_CPU1_SB_DQS_DN<1>")
	)
	(segment
		(start 65.525904 -215.885268)
		(end 65.401444 -215.760808)
		(width 0.18288)
		(layer "In11.Cu")
		(net "M_D_CPU1_SB_DQS_DN<1>")
	)
	(segment
		(start 21.159978 -218.990926)
		(end 20.688554 -218.990926)
		(width 0.18288)
		(layer "In11.Cu")
		(net "M_D_CPU1_SB_DQS_DN<1>")
	)
	(segment
		(start 53.592476 -211.591144)
		(end 53.468016 -211.466684)
		(width 0.18288)
		(layer "In11.Cu")
		(net "M_D_CPU1_SB_DQS_DN<1>")
	)
	(segment
		(start 92.657168 -234.480608)
		(end 92.648278 -234.475528)
		(width 0.088646)
		(layer "In11.Cu")
		(net "M_D_CPU1_SB_DQS_DN<1>")
	)
	(segment
		(start 55.699152 -212.077808)
		(end 55.192168 -211.868004)
		(width 0.18288)
		(layer "In11.Cu")
		(net "M_D_CPU1_SB_DQS_DN<1>")
	)
	(segment
		(start 26.65857 -217.100658)
		(end 26.008076 -217.751152)
		(width 0.18288)
		(layer "In11.Cu")
		(net "M_D_CPU1_SB_DQS_DN<1>")
	)
	(segment
		(start 64.728344 -215.885268)
		(end 63.880238 -215.885268)
		(width 0.18288)
		(layer "In11.Cu")
		(net "M_D_CPU1_SB_DQS_DN<1>")
	)
	(segment
		(start 40.785288 -212.003386)
		(end 40.278304 -211.793582)
		(width 0.18288)
		(layer "In11.Cu")
		(net "M_D_CPU1_SB_DQS_DN<1>")
	)
	(segment
		(start 32.09925 -212.190838)
		(end 31.673546 -212.190838)
		(width 0.18288)
		(layer "In11.Cu")
		(net "M_D_CPU1_SB_DQS_DN<1>")
	)
	(segment
		(start 97.787714 -235.148882)
		(end 97.514156 -235.148882)
		(width 0.088646)
		(layer "In11.Cu")
		(net "M_D_CPU1_SB_DQS_DN<1>")
	)
	(segment
		(start 51.297078 -211.340954)
		(end 50.871374 -211.340954)
		(width 0.18288)
		(layer "In11.Cu")
		(net "M_D_CPU1_SB_DQS_DN<1>")
	)
	(segment
		(start 40.852598 -212.1662)
		(end 40.785288 -212.003386)
		(width 0.18288)
		(layer "In11.Cu")
		(net "M_D_CPU1_SB_DQS_DN<1>")
	)
	(segment
		(start 93.126814 -235.294424)
		(end 93.12529 -235.293662)
		(width 0.088646)
		(layer "In11.Cu")
		(net "M_D_CPU1_SB_DQS_DN<1>")
	)
	(segment
		(start 42.95267 -212.426042)
		(end 41.479978 -212.426042)
		(width 0.18288)
		(layer "In11.Cu")
		(net "M_D_CPU1_SB_DQS_DN<1>")
	)
	(segment
		(start 49.476152 -212.091524)
		(end 48.600868 -212.45449)
		(width 0.18288)
		(layer "In11.Cu")
		(net "M_D_CPU1_SB_DQS_DN<1>")
	)
	(segment
		(start 86.078568 -232.852722)
		(end 86.068154 -232.846626)
		(width 0.088646)
		(layer "In11.Cu")
		(net "M_D_CPU1_SB_DQS_DN<1>")
	)
	(segment
		(start 38.23208 -211.462366)
		(end 38.10762 -211.586826)
		(width 0.18288)
		(layer "In11.Cu")
		(net "M_D_CPU1_SB_DQS_DN<1>")
	)
	(segment
		(start 96.886268 -235.294424)
		(end 96.875854 -235.288328)
		(width 0.088646)
		(layer "In11.Cu")
		(net "M_D_CPU1_SB_DQS_DN<1>")
	)
	(segment
		(start 61.13653 -214.21725)
		(end 60.748418 -213.829138)
		(width 0.18288)
		(layer "In11.Cu")
		(net "M_D_CPU1_SB_DQS_DN<1>")
	)
	(segment
		(start 40.11549 -211.860892)
		(end 39.45382 -211.586826)
		(width 0.18288)
		(layer "In11.Cu")
		(net "M_D_CPU1_SB_DQS_DN<1>")
	)
	(segment
		(start 85.138514 -232.852722)
		(end 85.123782 -232.844086)
		(width 0.088646)
		(layer "In11.Cu")
		(net "M_D_CPU1_SB_DQS_DN<1>")
	)
	(segment
		(start 29.21127 -211.850732)
		(end 28.708096 -212.35416)
		(width 0.18288)
		(layer "In11.Cu")
		(net "M_D_CPU1_SB_DQS_DN<1>")
	)
	(segment
		(start 62.576964 -215.210898)
		(end 62.414404 -215.278208)
		(width 0.18288)
		(layer "In11.Cu")
		(net "M_D_CPU1_SB_DQS_DN<1>")
	)
	(segment
		(start 63.151512 -215.583516)
		(end 63.084202 -215.420702)
		(width 0.18288)
		(layer "In11.Cu")
		(net "M_D_CPU1_SB_DQS_DN<1>")
	)
	(segment
		(start 58.50255 -212.607906)
		(end 56.653684 -212.607906)
		(width 0.18288)
		(layer "In11.Cu")
		(net "M_D_CPU1_SB_DQS_DN<1>")
	)
	(segment
		(start 68.581524 -219.377006)
		(end 67.523106 -216.821766)
		(width 0.18288)
		(layer "In11.Cu")
		(net "M_D_CPU1_SB_DQS_DN<1>")
	)
	(segment
		(start 17.0307 -218.8083)
		(end 16.789146 -218.566746)
		(width 0.18288)
		(layer "In11.Cu")
		(net "M_D_CPU1_SB_DQS_DN<1>")
	)
	(segment
		(start 35.78098 -211.343748)
		(end 35.46348 -211.661248)
		(width 0.18288)
		(layer "In11.Cu")
		(net "M_D_CPU1_SB_DQS_DN<1>")
	)
	(segment
		(start 94.066614 -235.294424)
		(end 94.051882 -235.285788)
		(width 0.088646)
		(layer "In11.Cu")
		(net "M_D_CPU1_SB_DQS_DN<1>")
	)
	(segment
		(start 36.47567 -211.586826)
		(end 36.232592 -211.343748)
		(width 0.18288)
		(layer "In11.Cu")
		(net "M_D_CPU1_SB_DQS_DN<1>")
	)
	(segment
		(start 28.708096 -212.35416)
		(end 27.680412 -212.779864)
		(width 0.18288)
		(layer "In11.Cu")
		(net "M_D_CPU1_SB_DQS_DN<1>")
	)
	(segment
		(start 41.479978 -212.426042)
		(end 40.852598 -212.1662)
		(width 0.18288)
		(layer "In11.Cu")
		(net "M_D_CPU1_SB_DQS_DN<1>")
	)
	(segment
		(start 47.21352 -212.189568)
		(end 46.775116 -212.189568)
		(width 0.18288)
		(layer "In11.Cu")
		(net "M_D_CPU1_SB_DQS_DN<1>")
	)
	(segment
		(start 20.44192 -219.23756)
		(end 19.716496 -219.23756)
		(width 0.18288)
		(layer "In11.Cu")
		(net "M_D_CPU1_SB_DQS_DN<1>")
	)
	(segment
		(start 91.247468 -233.666538)
		(end 91.237054 -233.660442)
		(width 0.088646)
		(layer "In11.Cu")
		(net "M_D_CPU1_SB_DQS_DN<1>")
	)
	(segment
		(start 26.836116 -216.12352)
		(end 26.836116 -216.67216)
		(width 0.18288)
		(layer "In11.Cu")
		(net "M_D_CPU1_SB_DQS_DN<1>")
	)
	(segment
		(start 61.743844 -215.000586)
		(end 61.13653 -214.393272)
		(width 0.18288)
		(layer "In11.Cu")
		(net "M_D_CPU1_SB_DQS_DN<1>")
	)
	(segment
		(start 48.600868 -212.45449)
		(end 47.478442 -212.45449)
		(width 0.18288)
		(layer "In11.Cu")
		(net "M_D_CPU1_SB_DQS_DN<1>")
	)
	(segment
		(start 17.399762 -218.8083)
		(end 17.0307 -218.8083)
		(width 0.18288)
		(layer "In11.Cu")
		(net "M_D_CPU1_SB_DQS_DN<1>")
	)
	(segment
		(start 61.13653 -214.393272)
		(end 61.13653 -214.21725)
		(width 0.18288)
		(layer "In11.Cu")
		(net "M_D_CPU1_SB_DQS_DN<1>")
	)
	(segment
		(start 65.401444 -215.760808)
		(end 64.852804 -215.760808)
		(width 0.18288)
		(layer "In11.Cu")
		(net "M_D_CPU1_SB_DQS_DN<1>")
	)
	(segment
		(start 97.981262 -235.08589)
		(end 97.9424 -235.107988)
		(width 0.088646)
		(layer "In11.Cu")
		(net "M_D_CPU1_SB_DQS_DN<1>")
	)
	(segment
		(start 26.836116 -216.67216)
		(end 26.65857 -217.100658)
		(width 0.18288)
		(layer "In11.Cu")
		(net "M_D_CPU1_SB_DQS_DN<1>")
	)
	(segment
		(start 98.013012 -234.970066)
		(end 97.981262 -235.08589)
		(width 0.088646)
		(layer "In11.Cu")
		(net "M_D_CPU1_SB_DQS_DN<1>")
	)
	(segment
		(start 55.029608 -211.935314)
		(end 54.198266 -211.591144)
		(width 0.18288)
		(layer "In11.Cu")
		(net "M_D_CPU1_SB_DQS_DN<1>")
	)
	(segment
		(start 44.547282 -213.086442)
		(end 42.95267 -212.426042)
		(width 0.18288)
		(layer "In11.Cu")
		(net "M_D_CPU1_SB_DQS_DN<1>")
	)
	(segment
		(start 88.347296 -232.844086)
		(end 88.332564 -232.852722)
		(width 0.088646)
		(layer "In11.Cu")
		(net "M_D_CPU1_SB_DQS_DN<1>")
	)
	(segment
		(start 45.400976 -212.953854)
		(end 45.080936 -213.086442)
		(width 0.18288)
		(layer "In11.Cu")
		(net "M_D_CPU1_SB_DQS_DN<1>")
	)
	(segment
		(start 31.388304 -212.47608)
		(end 30.72765 -212.47608)
		(width 0.18288)
		(layer "In11.Cu")
		(net "M_D_CPU1_SB_DQS_DN<1>")
	)
	(segment
		(start 46.775116 -212.189568)
		(end 46.492922 -212.471762)
		(width 0.18288)
		(layer "In11.Cu")
		(net "M_D_CPU1_SB_DQS_DN<1>")
	)
	(segment
		(start 26.711656 -215.45042)
		(end 26.711656 -215.99906)
		(width 0.18288)
		(layer "In11.Cu")
		(net "M_D_CPU1_SB_DQS_DN<1>")
	)
	(segment
		(start 22.829266 -219.259404)
		(end 21.428456 -219.259404)
		(width 0.18288)
		(layer "In11.Cu")
		(net "M_D_CPU1_SB_DQS_DN<1>")
	)
	(segment
		(start 36.232592 -211.343748)
		(end 35.78098 -211.343748)
		(width 0.18288)
		(layer "In11.Cu")
		(net "M_D_CPU1_SB_DQS_DN<1>")
	)
	(segment
		(start 31.673546 -212.190838)
		(end 31.388304 -212.47608)
		(width 0.18288)
		(layer "In11.Cu")
		(net "M_D_CPU1_SB_DQS_DN<1>")
	)
	(segment
		(start 60.572396 -213.829138)
		(end 59.950858 -213.2076)
		(width 0.18288)
		(layer "In11.Cu")
		(net "M_D_CPU1_SB_DQS_DN<1>")
	)
	(segment
		(start 19.31797 -218.83878)
		(end 18.782538 -218.617292)
		(width 0.18288)
		(layer "In11.Cu")
		(net "M_D_CPU1_SB_DQS_DN<1>")
	)
	(arc
		(start 94.051882 -235.285788)
		(mid 93.775407 -235.218468)
		(end 93.50121 -235.294424)
		(width 0.088646)
		(layer "In11.Cu")
		(net "M_D_CPU1_SB_DQS_DN<1>")
	)
	(arc
		(start 94.991682 -235.285788)
		(mid 94.715207 -235.218468)
		(end 94.44101 -235.294424)
		(width 0.088646)
		(layer "In11.Cu")
		(net "M_D_CPU1_SB_DQS_DN<1>")
	)
	(arc
		(start 89.358724 -233.661458)
		(mid 89.22781 -233.525098)
		(end 89.180162 -233.34218)
		(width 0.088646)
		(layer "In11.Cu")
		(net "M_D_CPU1_SB_DQS_DN<1>")
	)
	(arc
		(start 86.068154 -232.846626)
		(mid 85.789722 -232.77678)
		(end 85.51291 -232.852722)
		(width 0.088646)
		(layer "In11.Cu")
		(net "M_D_CPU1_SB_DQS_DN<1>")
	)
	(arc
		(start 91.237054 -233.660442)
		(mid 90.958622 -233.590628)
		(end 90.68181 -233.666538)
		(width 0.088646)
		(layer "In11.Cu")
		(net "M_D_CPU1_SB_DQS_DN<1>")
	)
	(arc
		(start 97.9424 -235.107988)
		(mid 97.867715 -235.138493)
		(end 97.787714 -235.148882)
		(width 0.088646)
		(layer "In11.Cu")
		(net "M_D_CPU1_SB_DQS_DN<1>")
	)
	(arc
		(start 85.123782 -232.844086)
		(mid 84.847307 -232.776766)
		(end 84.57311 -232.852722)
		(width 0.088646)
		(layer "In11.Cu")
		(net "M_D_CPU1_SB_DQS_DN<1>")
	)
	(arc
		(start 95.931482 -235.285788)
		(mid 95.655007 -235.218468)
		(end 95.38081 -235.294424)
		(width 0.088646)
		(layer "In11.Cu")
		(net "M_D_CPU1_SB_DQS_DN<1>")
	)
	(arc
		(start 94.44101 -235.294424)
		(mid 94.253812 -235.344567)
		(end 94.066614 -235.294424)
		(width 0.088646)
		(layer "In11.Cu")
		(net "M_D_CPU1_SB_DQS_DN<1>")
	)
	(arc
		(start 87.958168 -232.852722)
		(mid 87.675466 -232.776946)
		(end 87.392764 -232.852722)
		(width 0.088646)
		(layer "In11.Cu")
		(net "M_D_CPU1_SB_DQS_DN<1>")
	)
	(arc
		(start 92.648278 -234.475528)
		(mid 92.517364 -234.339168)
		(end 92.469716 -234.15625)
		(width 0.088646)
		(layer "In11.Cu")
		(net "M_D_CPU1_SB_DQS_DN<1>")
	)
	(arc
		(start 91.621864 -233.666538)
		(mid 91.434666 -233.716681)
		(end 91.247468 -233.666538)
		(width 0.088646)
		(layer "In11.Cu")
		(net "M_D_CPU1_SB_DQS_DN<1>")
	)
	(arc
		(start 93.50121 -235.294424)
		(mid 93.314012 -235.344567)
		(end 93.126814 -235.294424)
		(width 0.088646)
		(layer "In11.Cu")
		(net "M_D_CPU1_SB_DQS_DN<1>")
	)
	(arc
		(start 96.875854 -235.288328)
		(mid 96.597422 -235.218482)
		(end 96.32061 -235.294424)
		(width 0.088646)
		(layer "In11.Cu")
		(net "M_D_CPU1_SB_DQS_DN<1>")
	)
	(arc
		(start 95.38081 -235.294424)
		(mid 95.193612 -235.344567)
		(end 95.006414 -235.294424)
		(width 0.088646)
		(layer "In11.Cu")
		(net "M_D_CPU1_SB_DQS_DN<1>")
	)
	(arc
		(start 88.897968 -232.852722)
		(mid 88.623769 -232.776887)
		(end 88.347296 -232.844086)
		(width 0.088646)
		(layer "In11.Cu")
		(net "M_D_CPU1_SB_DQS_DN<1>")
	)
	(arc
		(start 92.939362 -234.954572)
		(mid 92.859992 -234.680838)
		(end 92.657168 -234.480608)
		(width 0.088646)
		(layer "In11.Cu")
		(net "M_D_CPU1_SB_DQS_DN<1>")
	)
	(arc
		(start 84.57311 -232.852722)
		(mid 84.482854 -232.890444)
		(end 84.385912 -232.903522)
		(width 0.088646)
		(layer "In11.Cu")
		(net "M_D_CPU1_SB_DQS_DN<1>")
	)
	(arc
		(start 92.469716 -234.142026)
		(mid 92.390497 -233.867341)
		(end 92.187014 -233.666538)
		(width 0.088646)
		(layer "In11.Cu")
		(net "M_D_CPU1_SB_DQS_DN<1>")
	)
	(arc
		(start 88.332564 -232.852722)
		(mid 88.145366 -232.902865)
		(end 87.958168 -232.852722)
		(width 0.088646)
		(layer "In11.Cu")
		(net "M_D_CPU1_SB_DQS_DN<1>")
	)
	(arc
		(start 97.260664 -235.294424)
		(mid 97.073466 -235.344567)
		(end 96.886268 -235.294424)
		(width 0.088646)
		(layer "In11.Cu")
		(net "M_D_CPU1_SB_DQS_DN<1>")
	)
	(arc
		(start 89.180162 -233.326686)
		(mid 89.100792 -233.052952)
		(end 88.897968 -232.852722)
		(width 0.088646)
		(layer "In11.Cu")
		(net "M_D_CPU1_SB_DQS_DN<1>")
	)
	(arc
		(start 90.68181 -233.666538)
		(mid 90.494612 -233.716681)
		(end 90.307414 -233.666538)
		(width 0.088646)
		(layer "In11.Cu")
		(net "M_D_CPU1_SB_DQS_DN<1>")
	)
	(arc
		(start 90.292682 -233.657902)
		(mid 90.016241 -233.590736)
		(end 89.74201 -233.666538)
		(width 0.088646)
		(layer "In11.Cu")
		(net "M_D_CPU1_SB_DQS_DN<1>")
	)
	(arc
		(start 93.117924 -235.289344)
		(mid 92.98701 -235.152984)
		(end 92.939362 -234.970066)
		(width 0.088646)
		(layer "In11.Cu")
		(net "M_D_CPU1_SB_DQS_DN<1>")
	)
	(arc
		(start 87.018368 -232.852722)
		(mid 86.735666 -232.776946)
		(end 86.452964 -232.852722)
		(width 0.088646)
		(layer "In11.Cu")
		(net "M_D_CPU1_SB_DQS_DN<1>")
	)
	(arc
		(start 87.392764 -232.852722)
		(mid 87.205566 -232.902865)
		(end 87.018368 -232.852722)
		(width 0.088646)
		(layer "In11.Cu")
		(net "M_D_CPU1_SB_DQS_DN<1>")
	)
	(arc
		(start 86.452964 -232.852722)
		(mid 86.265766 -232.902865)
		(end 86.078568 -232.852722)
		(width 0.088646)
		(layer "In11.Cu")
		(net "M_D_CPU1_SB_DQS_DN<1>")
	)
	(arc
		(start 89.74201 -233.666538)
		(mid 89.554812 -233.716681)
		(end 89.367614 -233.666538)
		(width 0.088646)
		(layer "In11.Cu")
		(net "M_D_CPU1_SB_DQS_DN<1>")
	)
	(arc
		(start 96.32061 -235.294424)
		(mid 96.133412 -235.344567)
		(end 95.946214 -235.294424)
		(width 0.088646)
		(layer "In11.Cu")
		(net "M_D_CPU1_SB_DQS_DN<1>")
	)
	(arc
		(start 85.51291 -232.852722)
		(mid 85.325712 -232.902865)
		(end 85.138514 -232.852722)
		(width 0.088646)
		(layer "In11.Cu")
		(net "M_D_CPU1_SB_DQS_DN<1>")
	)
	(arc
		(start 92.1766 -233.660442)
		(mid 91.898422 -233.59075)
		(end 91.621864 -233.666538)
		(width 0.088646)
		(layer "In11.Cu")
		(net "M_D_CPU1_SB_DQS_DN<1>")
	)
	(segment
		(start 10.912094 -228.331014)
		(end 10.64006 -228.603048)
		(width 0.20066)
		(layer "F.Cu")
		(net "M_D_CPU1_SB_DQS_DN<0>")
	)
	(segment
		(start 14.044676 -228.603048)
		(end 13.857986 -228.603048)
		(width 0.20066)
		(layer "F.Cu")
		(net "M_D_CPU1_SB_DQS_DN<0>")
	)
	(segment
		(start 8.689086 -227.91674)
		(end 8.140446 -227.91674)
		(width 0.20066)
		(layer "F.Cu")
		(net "M_D_CPU1_SB_DQS_DN<0>")
	)
	(segment
		(start 13.59662 -228.341682)
		(end 13.441426 -228.341682)
		(width 0.20066)
		(layer "F.Cu")
		(net "M_D_CPU1_SB_DQS_DN<0>")
	)
	(segment
		(start 10.100056 -228.603048)
		(end 9.46404 -228.177852)
		(width 0.20066)
		(layer "F.Cu")
		(net "M_D_CPU1_SB_DQS_DN<0>")
	)
	(segment
		(start 14.876526 -228.177852)
		(end 14.469872 -228.177852)
		(width 0.20066)
		(layer "F.Cu")
		(net "M_D_CPU1_SB_DQS_DN<0>")
	)
	(segment
		(start 13.857986 -228.603048)
		(end 13.59662 -228.341682)
		(width 0.20066)
		(layer "F.Cu")
		(net "M_D_CPU1_SB_DQS_DN<0>")
	)
	(segment
		(start 8.950198 -228.177852)
		(end 8.689086 -227.91674)
		(width 0.20066)
		(layer "F.Cu")
		(net "M_D_CPU1_SB_DQS_DN<0>")
	)
	(segment
		(start 10.64006 -228.603048)
		(end 10.100056 -228.603048)
		(width 0.20066)
		(layer "F.Cu")
		(net "M_D_CPU1_SB_DQS_DN<0>")
	)
	(segment
		(start 98.013012 -240.388902)
		(end 98.013012 -239.853216)
		(width 0.20066)
		(layer "F.Cu")
		(net "M_D_CPU1_SB_DQS_DN<0>")
	)
	(segment
		(start 11.12774 -228.341682)
		(end 11.117072 -228.331014)
		(width 0.101854)
		(layer "F.Cu")
		(net "M_D_CPU1_SB_DQS_DN<0>")
	)
	(segment
		(start 11.117072 -228.331014)
		(end 11.11631 -228.331014)
		(width 0.101854)
		(layer "F.Cu")
		(net "M_D_CPU1_SB_DQS_DN<0>")
	)
	(segment
		(start 15.137638 -227.91674)
		(end 14.876526 -228.177852)
		(width 0.20066)
		(layer "F.Cu")
		(net "M_D_CPU1_SB_DQS_DN<0>")
	)
	(segment
		(start 13.441426 -228.341682)
		(end 11.12774 -228.341682)
		(width 0.1016)
		(layer "F.Cu")
		(net "M_D_CPU1_SB_DQS_DN<0>")
	)
	(segment
		(start 98.013266 -240.389156)
		(end 98.013012 -240.388902)
		(width 0.20066)
		(layer "F.Cu")
		(net "M_D_CPU1_SB_DQS_DN<0>")
	)
	(segment
		(start 11.11631 -228.331014)
		(end 10.912094 -228.331014)
		(width 0.20066)
		(layer "F.Cu")
		(net "M_D_CPU1_SB_DQS_DN<0>")
	)
	(segment
		(start 14.469872 -228.177852)
		(end 14.044676 -228.603048)
		(width 0.20066)
		(layer "F.Cu")
		(net "M_D_CPU1_SB_DQS_DN<0>")
	)
	(segment
		(start 16.789146 -227.91674)
		(end 15.684246 -227.91674)
		(width 0.20066)
		(layer "F.Cu")
		(net "M_D_CPU1_SB_DQS_DN<0>")
	)
	(segment
		(start 15.684246 -227.91674)
		(end 15.137638 -227.91674)
		(width 0.20066)
		(layer "F.Cu")
		(net "M_D_CPU1_SB_DQS_DN<0>")
	)
	(segment
		(start 9.46404 -228.177852)
		(end 8.950198 -228.177852)
		(width 0.20066)
		(layer "F.Cu")
		(net "M_D_CPU1_SB_DQS_DN<0>")
	)
	(segment
		(start 75.936602 -237.113826)
		(end 75.548744 -236.725968)
		(width 0.18288)
		(layer "In11.Cu")
		(net "M_D_CPU1_SB_DQS_DN<0>")
	)
	(segment
		(start 36.450524 -224.332038)
		(end 36.209478 -224.090992)
		(width 0.18288)
		(layer "In11.Cu")
		(net "M_D_CPU1_SB_DQS_DN<0>")
	)
	(segment
		(start 51.56581 -224.347024)
		(end 51.310794 -224.092008)
		(width 0.18288)
		(layer "In11.Cu")
		(net "M_D_CPU1_SB_DQS_DN<0>")
	)
	(segment
		(start 73.256648 -234.25785)
		(end 73.080626 -234.25785)
		(width 0.18288)
		(layer "In11.Cu")
		(net "M_D_CPU1_SB_DQS_DN<0>")
	)
	(segment
		(start 70.400672 -231.401874)
		(end 70.22465 -231.401874)
		(width 0.18288)
		(layer "In11.Cu")
		(net "M_D_CPU1_SB_DQS_DN<0>")
	)
	(segment
		(start 30.848046 -225.213672)
		(end 30.150308 -225.502216)
		(width 0.18288)
		(layer "In11.Cu")
		(net "M_D_CPU1_SB_DQS_DN<0>")
	)
	(segment
		(start 96.886268 -240.177574)
		(end 96.875854 -240.171478)
		(width 0.088646)
		(layer "In11.Cu")
		(net "M_D_CPU1_SB_DQS_DN<0>")
	)
	(segment
		(start 62.580266 -226.892866)
		(end 62.328552 -226.641152)
		(width 0.18288)
		(layer "In11.Cu")
		(net "M_D_CPU1_SB_DQS_DN<0>")
	)
	(segment
		(start 69.44868 -230.449882)
		(end 69.272658 -230.449882)
		(width 0.18288)
		(layer "In11.Cu")
		(net "M_D_CPU1_SB_DQS_DN<0>")
	)
	(segment
		(start 64.765936 -228.231446)
		(end 64.765936 -228.055424)
		(width 0.18288)
		(layer "In11.Cu")
		(net "M_D_CPU1_SB_DQS_DN<0>")
	)
	(segment
		(start 47.489872 -225.195892)
		(end 47.23511 -224.94113)
		(width 0.18288)
		(layer "In11.Cu")
		(net "M_D_CPU1_SB_DQS_DN<0>")
	)
	(segment
		(start 17.428464 -228.170232)
		(end 17.042638 -228.170232)
		(width 0.18288)
		(layer "In11.Cu")
		(net "M_D_CPU1_SB_DQS_DN<0>")
	)
	(segment
		(start 55.782718 -224.716086)
		(end 55.27548 -224.506282)
		(width 0.18288)
		(layer "In11.Cu")
		(net "M_D_CPU1_SB_DQS_DN<0>")
	)
	(segment
		(start 75.548744 -236.549946)
		(end 75.160632 -236.161834)
		(width 0.18288)
		(layer "In11.Cu")
		(net "M_D_CPU1_SB_DQS_DN<0>")
	)
	(segment
		(start 63.730632 -227.195888)
		(end 62.998858 -226.892866)
		(width 0.18288)
		(layer "In11.Cu")
		(net "M_D_CPU1_SB_DQS_DN<0>")
	)
	(segment
		(start 17.042638 -228.170232)
		(end 16.789146 -227.91674)
		(width 0.18288)
		(layer "In11.Cu")
		(net "M_D_CPU1_SB_DQS_DN<0>")
	)
	(segment
		(start 74.032618 -235.209842)
		(end 73.64476 -234.821984)
		(width 0.18288)
		(layer "In11.Cu")
		(net "M_D_CPU1_SB_DQS_DN<0>")
	)
	(segment
		(start 65.62217 -228.619304)
		(end 65.153794 -228.619304)
		(width 0.18288)
		(layer "In11.Cu")
		(net "M_D_CPU1_SB_DQS_DN<0>")
	)
	(segment
		(start 55.11292 -224.573592)
		(end 54.565804 -224.347024)
		(width 0.18288)
		(layer "In11.Cu")
		(net "M_D_CPU1_SB_DQS_DN<0>")
	)
	(segment
		(start 44.53382 -225.80092)
		(end 43.130216 -225.219006)
		(width 0.18288)
		(layer "In11.Cu")
		(net "M_D_CPU1_SB_DQS_DN<0>")
	)
	(segment
		(start 34.330894 -224.714054)
		(end 33.853882 -225.191066)
		(width 0.18288)
		(layer "In11.Cu")
		(net "M_D_CPU1_SB_DQS_DN<0>")
	)
	(segment
		(start 50.862738 -224.092008)
		(end 50.574194 -224.380552)
		(width 0.18288)
		(layer "In11.Cu")
		(net "M_D_CPU1_SB_DQS_DN<0>")
	)
	(segment
		(start 72.128634 -233.305858)
		(end 71.740776 -232.918)
		(width 0.18288)
		(layer "In11.Cu")
		(net "M_D_CPU1_SB_DQS_DN<0>")
	)
	(segment
		(start 59.767724 -225.971354)
		(end 59.439302 -225.642932)
		(width 0.18288)
		(layer "In11.Cu")
		(net "M_D_CPU1_SB_DQS_DN<0>")
	)
	(segment
		(start 70.788784 -231.789986)
		(end 70.400672 -231.401874)
		(width 0.18288)
		(layer "In11.Cu")
		(net "M_D_CPU1_SB_DQS_DN<0>")
	)
	(segment
		(start 71.740776 -232.741978)
		(end 71.352664 -232.353866)
		(width 0.18288)
		(layer "In11.Cu")
		(net "M_D_CPU1_SB_DQS_DN<0>")
	)
	(segment
		(start 68.320666 -229.49789)
		(end 67.460622 -228.637846)
		(width 0.18288)
		(layer "In11.Cu")
		(net "M_D_CPU1_SB_DQS_DN<0>")
	)
	(segment
		(start 28.96108 -226.691444)
		(end 24.409654 -228.576632)
		(width 0.18288)
		(layer "In11.Cu")
		(net "M_D_CPU1_SB_DQS_DN<0>")
	)
	(segment
		(start 64.201802 -227.667058)
		(end 63.730632 -227.195888)
		(width 0.18288)
		(layer "In11.Cu")
		(net "M_D_CPU1_SB_DQS_DN<0>")
	)
	(segment
		(start 20.670266 -228.342444)
		(end 20.412456 -228.600254)
		(width 0.18288)
		(layer "In11.Cu")
		(net "M_D_CPU1_SB_DQS_DN<0>")
	)
	(segment
		(start 97.514156 -240.032032)
		(end 97.260918 -240.177828)
		(width 0.088646)
		(layer "In11.Cu")
		(net "M_D_CPU1_SB_DQS_DN<0>")
	)
	(segment
		(start 66.054478 -228.345746)
		(end 65.895728 -228.345746)
		(width 0.18288)
		(layer "In11.Cu")
		(net "M_D_CPU1_SB_DQS_DN<0>")
	)
	(segment
		(start 70.22465 -231.401874)
		(end 69.836792 -231.014016)
		(width 0.18288)
		(layer "In11.Cu")
		(net "M_D_CPU1_SB_DQS_DN<0>")
	)
	(segment
		(start 18.826226 -227.946966)
		(end 17.967452 -227.946966)
		(width 0.18288)
		(layer "In11.Cu")
		(net "M_D_CPU1_SB_DQS_DN<0>")
	)
	(segment
		(start 97.787714 -240.032032)
		(end 97.514156 -240.032032)
		(width 0.088646)
		(layer "In11.Cu")
		(net "M_D_CPU1_SB_DQS_DN<0>")
	)
	(segment
		(start 88.427814 -240.177574)
		(end 88.418924 -240.172494)
		(width 0.088646)
		(layer "In11.Cu")
		(net "M_D_CPU1_SB_DQS_DN<0>")
	)
	(segment
		(start 35.109912 -224.390712)
		(end 34.330894 -224.714054)
		(width 0.18288)
		(layer "In11.Cu")
		(net "M_D_CPU1_SB_DQS_DN<0>")
	)
	(segment
		(start 93.126814 -240.177574)
		(end 93.112082 -240.168938)
		(width 0.088646)
		(layer "In11.Cu")
		(net "M_D_CPU1_SB_DQS_DN<0>")
	)
	(segment
		(start 82.43316 -237.173516)
		(end 82.37347 -237.113826)
		(width 0.088646)
		(layer "In11.Cu")
		(net "M_D_CPU1_SB_DQS_DN<0>")
	)
	(segment
		(start 82.37347 -237.113826)
		(end 75.936602 -237.113826)
		(width 0.18288)
		(layer "In11.Cu")
		(net "M_D_CPU1_SB_DQS_DN<0>")
	)
	(segment
		(start 97.260918 -240.177828)
		(end 97.260664 -240.177574)
		(width 0.088646)
		(layer "In11.Cu")
		(net "M_D_CPU1_SB_DQS_DN<0>")
	)
	(segment
		(start 73.080626 -234.25785)
		(end 72.692768 -233.869992)
		(width 0.18288)
		(layer "In11.Cu")
		(net "M_D_CPU1_SB_DQS_DN<0>")
	)
	(segment
		(start 60.445142 -226.252278)
		(end 59.767724 -225.971354)
		(width 0.18288)
		(layer "In11.Cu")
		(net "M_D_CPU1_SB_DQS_DN<0>")
	)
	(segment
		(start 41.266872 -225.219006)
		(end 39.12743 -224.332038)
		(width 0.18288)
		(layer "In11.Cu")
		(net "M_D_CPU1_SB_DQS_DN<0>")
	)
	(segment
		(start 74.98461 -236.161834)
		(end 74.596752 -235.773976)
		(width 0.18288)
		(layer "In11.Cu")
		(net "M_D_CPU1_SB_DQS_DN<0>")
	)
	(segment
		(start 88.240362 -239.853216)
		(end 88.240362 -239.837722)
		(width 0.088646)
		(layer "In11.Cu")
		(net "M_D_CPU1_SB_DQS_DN<0>")
	)
	(segment
		(start 45.218858 -225.80092)
		(end 44.53382 -225.80092)
		(width 0.18288)
		(layer "In11.Cu")
		(net "M_D_CPU1_SB_DQS_DN<0>")
	)
	(segment
		(start 32.397446 -225.191066)
		(end 32.14751 -224.94113)
		(width 0.18288)
		(layer "In11.Cu")
		(net "M_D_CPU1_SB_DQS_DN<0>")
	)
	(segment
		(start 71.740776 -232.918)
		(end 71.740776 -232.741978)
		(width 0.18288)
		(layer "In11.Cu")
		(net "M_D_CPU1_SB_DQS_DN<0>")
	)
	(segment
		(start 55.27548 -224.506282)
		(end 55.11292 -224.573592)
		(width 0.18288)
		(layer "In11.Cu")
		(net "M_D_CPU1_SB_DQS_DN<0>")
	)
	(segment
		(start 74.20864 -235.209842)
		(end 74.032618 -235.209842)
		(width 0.18288)
		(layer "In11.Cu")
		(net "M_D_CPU1_SB_DQS_DN<0>")
	)
	(segment
		(start 69.836792 -230.837994)
		(end 69.44868 -230.449882)
		(width 0.18288)
		(layer "In11.Cu")
		(net "M_D_CPU1_SB_DQS_DN<0>")
	)
	(segment
		(start 97.981262 -239.96904)
		(end 97.9424 -239.991138)
		(width 0.088646)
		(layer "In11.Cu")
		(net "M_D_CPU1_SB_DQS_DN<0>")
	)
	(segment
		(start 35.484054 -224.390712)
		(end 35.109912 -224.390712)
		(width 0.18288)
		(layer "In11.Cu")
		(net "M_D_CPU1_SB_DQS_DN<0>")
	)
	(segment
		(start 55.850028 -224.8789)
		(end 55.782718 -224.716086)
		(width 0.18288)
		(layer "In11.Cu")
		(net "M_D_CPU1_SB_DQS_DN<0>")
	)
	(segment
		(start 90.307668 -240.177574)
		(end 90.297254 -240.171478)
		(width 0.088646)
		(layer "In11.Cu")
		(net "M_D_CPU1_SB_DQS_DN<0>")
	)
	(segment
		(start 90.692478 -240.171478)
		(end 90.682064 -240.177574)
		(width 0.088646)
		(layer "In11.Cu")
		(net "M_D_CPU1_SB_DQS_DN<0>")
	)
	(segment
		(start 84.385912 -238.47425)
		(end 84.075778 -238.47425)
		(width 0.088646)
		(layer "In11.Cu")
		(net "M_D_CPU1_SB_DQS_DN<0>")
	)
	(segment
		(start 66.255138 -228.345746)
		(end 66.054478 -228.345746)
		(width 0.16002)
		(layer "In11.Cu")
		(net "M_D_CPU1_SB_DQS_DN<0>")
	)
	(segment
		(start 95.946214 -240.177574)
		(end 95.931482 -240.168938)
		(width 0.088646)
		(layer "In11.Cu")
		(net "M_D_CPU1_SB_DQS_DN<0>")
	)
	(segment
		(start 36.209478 -224.090992)
		(end 35.783774 -224.090992)
		(width 0.18288)
		(layer "In11.Cu")
		(net "M_D_CPU1_SB_DQS_DN<0>")
	)
	(segment
		(start 95.006414 -240.177574)
		(end 94.991682 -240.168938)
		(width 0.088646)
		(layer "In11.Cu")
		(net "M_D_CPU1_SB_DQS_DN<0>")
	)
	(segment
		(start 31.671514 -224.94113)
		(end 31.398972 -225.213672)
		(width 0.18288)
		(layer "In11.Cu")
		(net "M_D_CPU1_SB_DQS_DN<0>")
	)
	(segment
		(start 71.352664 -232.353866)
		(end 71.176642 -232.353866)
		(width 0.18288)
		(layer "In11.Cu")
		(net "M_D_CPU1_SB_DQS_DN<0>")
	)
	(segment
		(start 66.399156 -228.345746)
		(end 66.255138 -228.345746)
		(width 0.18288)
		(layer "In11.Cu")
		(net "M_D_CPU1_SB_DQS_DN<0>")
	)
	(segment
		(start 20.412456 -228.600254)
		(end 20.142454 -228.600254)
		(width 0.18288)
		(layer "In11.Cu")
		(net "M_D_CPU1_SB_DQS_DN<0>")
	)
	(segment
		(start 20.142454 -228.600254)
		(end 19.957542 -228.415342)
		(width 0.18288)
		(layer "In11.Cu")
		(net "M_D_CPU1_SB_DQS_DN<0>")
	)
	(segment
		(start 73.64476 -234.645962)
		(end 73.256648 -234.25785)
		(width 0.18288)
		(layer "In11.Cu")
		(net "M_D_CPU1_SB_DQS_DN<0>")
	)
	(segment
		(start 39.12743 -224.332038)
		(end 36.450524 -224.332038)
		(width 0.18288)
		(layer "In11.Cu")
		(net "M_D_CPU1_SB_DQS_DN<0>")
	)
	(segment
		(start 51.310794 -224.092008)
		(end 50.862738 -224.092008)
		(width 0.18288)
		(layer "In11.Cu")
		(net "M_D_CPU1_SB_DQS_DN<0>")
	)
	(segment
		(start 87.018368 -239.363758)
		(end 87.009478 -239.358678)
		(width 0.088646)
		(layer "In11.Cu")
		(net "M_D_CPU1_SB_DQS_DN<0>")
	)
	(segment
		(start 24.409654 -228.576632)
		(end 21.368004 -228.576632)
		(width 0.18288)
		(layer "In11.Cu")
		(net "M_D_CPU1_SB_DQS_DN<0>")
	)
	(segment
		(start 31.398972 -225.213672)
		(end 30.848046 -225.213672)
		(width 0.18288)
		(layer "In11.Cu")
		(net "M_D_CPU1_SB_DQS_DN<0>")
	)
	(segment
		(start 62.328552 -226.641152)
		(end 62.114938 -226.641152)
		(width 0.18288)
		(layer "In11.Cu")
		(net "M_D_CPU1_SB_DQS_DN<0>")
	)
	(segment
		(start 61.967618 -226.641152)
		(end 61.827918 -226.641152)
		(width 0.18288)
		(layer "In11.Cu")
		(net "M_D_CPU1_SB_DQS_DN<0>")
	)
	(segment
		(start 66.691256 -228.637846)
		(end 66.399156 -228.345746)
		(width 0.18288)
		(layer "In11.Cu")
		(net "M_D_CPU1_SB_DQS_DN<0>")
	)
	(segment
		(start 69.836792 -231.014016)
		(end 69.836792 -230.837994)
		(width 0.18288)
		(layer "In11.Cu")
		(net "M_D_CPU1_SB_DQS_DN<0>")
	)
	(segment
		(start 92.187014 -240.177574)
		(end 92.172282 -240.168938)
		(width 0.088646)
		(layer "In11.Cu")
		(net "M_D_CPU1_SB_DQS_DN<0>")
	)
	(segment
		(start 73.64476 -234.821984)
		(end 73.64476 -234.645962)
		(width 0.18288)
		(layer "In11.Cu")
		(net "M_D_CPU1_SB_DQS_DN<0>")
	)
	(segment
		(start 33.853882 -225.191066)
		(end 32.397446 -225.191066)
		(width 0.18288)
		(layer "In11.Cu")
		(net "M_D_CPU1_SB_DQS_DN<0>")
	)
	(segment
		(start 21.133816 -228.342444)
		(end 20.670266 -228.342444)
		(width 0.18288)
		(layer "In11.Cu")
		(net "M_D_CPU1_SB_DQS_DN<0>")
	)
	(segment
		(start 72.304656 -233.305858)
		(end 72.128634 -233.305858)
		(width 0.18288)
		(layer "In11.Cu")
		(net "M_D_CPU1_SB_DQS_DN<0>")
	)
	(segment
		(start 64.765936 -228.055424)
		(end 64.377824 -227.667312)
		(width 0.18288)
		(layer "In11.Cu")
		(net "M_D_CPU1_SB_DQS_DN<0>")
	)
	(segment
		(start 19.957542 -228.415342)
		(end 18.826226 -227.946966)
		(width 0.18288)
		(layer "In11.Cu")
		(net "M_D_CPU1_SB_DQS_DN<0>")
	)
	(segment
		(start 89.367614 -240.177574)
		(end 89.352882 -240.168938)
		(width 0.088646)
		(layer "In11.Cu")
		(net "M_D_CPU1_SB_DQS_DN<0>")
	)
	(segment
		(start 94.066614 -240.177574)
		(end 94.051882 -240.168938)
		(width 0.088646)
		(layer "In11.Cu")
		(net "M_D_CPU1_SB_DQS_DN<0>")
	)
	(segment
		(start 35.783774 -224.090992)
		(end 35.484054 -224.390712)
		(width 0.18288)
		(layer "In11.Cu")
		(net "M_D_CPU1_SB_DQS_DN<0>")
	)
	(segment
		(start 47.23511 -224.94113)
		(end 46.766734 -224.94113)
		(width 0.18288)
		(layer "In11.Cu")
		(net "M_D_CPU1_SB_DQS_DN<0>")
	)
	(segment
		(start 75.160632 -236.161834)
		(end 74.98461 -236.161834)
		(width 0.18288)
		(layer "In11.Cu")
		(net "M_D_CPU1_SB_DQS_DN<0>")
	)
	(segment
		(start 61.827918 -226.641152)
		(end 61.58484 -226.88423)
		(width 0.18288)
		(layer "In11.Cu")
		(net "M_D_CPU1_SB_DQS_DN<0>")
	)
	(segment
		(start 68.8848 -230.062024)
		(end 68.8848 -229.886002)
		(width 0.18288)
		(layer "In11.Cu")
		(net "M_D_CPU1_SB_DQS_DN<0>")
	)
	(segment
		(start 65.153794 -228.619304)
		(end 64.765936 -228.231446)
		(width 0.18288)
		(layer "In11.Cu")
		(net "M_D_CPU1_SB_DQS_DN<0>")
	)
	(segment
		(start 61.07684 -226.88423)
		(end 60.445142 -226.252278)
		(width 0.18288)
		(layer "In11.Cu")
		(net "M_D_CPU1_SB_DQS_DN<0>")
	)
	(segment
		(start 69.272658 -230.449882)
		(end 68.8848 -230.062024)
		(width 0.18288)
		(layer "In11.Cu")
		(net "M_D_CPU1_SB_DQS_DN<0>")
	)
	(segment
		(start 84.075778 -238.47425)
		(end 82.775044 -237.173516)
		(width 0.088646)
		(layer "In11.Cu")
		(net "M_D_CPU1_SB_DQS_DN<0>")
	)
	(segment
		(start 67.460622 -228.637846)
		(end 66.691256 -228.637846)
		(width 0.18288)
		(layer "In11.Cu")
		(net "M_D_CPU1_SB_DQS_DN<0>")
	)
	(segment
		(start 49.59731 -224.770188)
		(end 48.570134 -225.195892)
		(width 0.18288)
		(layer "In11.Cu")
		(net "M_D_CPU1_SB_DQS_DN<0>")
	)
	(segment
		(start 61.58484 -226.88423)
		(end 61.07684 -226.88423)
		(width 0.18288)
		(layer "In11.Cu")
		(net "M_D_CPU1_SB_DQS_DN<0>")
	)
	(segment
		(start 68.8848 -229.886002)
		(end 68.496688 -229.49789)
		(width 0.18288)
		(layer "In11.Cu")
		(net "M_D_CPU1_SB_DQS_DN<0>")
	)
	(segment
		(start 70.788784 -231.966008)
		(end 70.788784 -231.789986)
		(width 0.18288)
		(layer "In11.Cu")
		(net "M_D_CPU1_SB_DQS_DN<0>")
	)
	(segment
		(start 17.967452 -227.946966)
		(end 17.428464 -228.170232)
		(width 0.18288)
		(layer "In11.Cu")
		(net "M_D_CPU1_SB_DQS_DN<0>")
	)
	(segment
		(start 87.407496 -239.355122)
		(end 87.392764 -239.363758)
		(width 0.088646)
		(layer "In11.Cu")
		(net "M_D_CPU1_SB_DQS_DN<0>")
	)
	(segment
		(start 21.368004 -228.576632)
		(end 21.133816 -228.342444)
		(width 0.18288)
		(layer "In11.Cu")
		(net "M_D_CPU1_SB_DQS_DN<0>")
	)
	(segment
		(start 62.114938 -226.641152)
		(end 61.967618 -226.641152)
		(width 0.16002)
		(layer "In11.Cu")
		(net "M_D_CPU1_SB_DQS_DN<0>")
	)
	(segment
		(start 46.766734 -224.94113)
		(end 46.478952 -225.228912)
		(width 0.18288)
		(layer "In11.Cu")
		(net "M_D_CPU1_SB_DQS_DN<0>")
	)
	(segment
		(start 71.176642 -232.353866)
		(end 70.788784 -231.966008)
		(width 0.18288)
		(layer "In11.Cu")
		(net "M_D_CPU1_SB_DQS_DN<0>")
	)
	(segment
		(start 58.499502 -225.25355)
		(end 56.754522 -225.25355)
		(width 0.18288)
		(layer "In11.Cu")
		(net "M_D_CPU1_SB_DQS_DN<0>")
	)
	(segment
		(start 68.496688 -229.49789)
		(end 68.320666 -229.49789)
		(width 0.18288)
		(layer "In11.Cu")
		(net "M_D_CPU1_SB_DQS_DN<0>")
	)
	(segment
		(start 74.596752 -235.773976)
		(end 74.596752 -235.597954)
		(width 0.18288)
		(layer "In11.Cu")
		(net "M_D_CPU1_SB_DQS_DN<0>")
	)
	(segment
		(start 50.574194 -224.380552)
		(end 49.9872 -224.380552)
		(width 0.18288)
		(layer "In11.Cu")
		(net "M_D_CPU1_SB_DQS_DN<0>")
	)
	(segment
		(start 43.130216 -225.219006)
		(end 41.266872 -225.219006)
		(width 0.18288)
		(layer "In11.Cu")
		(net "M_D_CPU1_SB_DQS_DN<0>")
	)
	(segment
		(start 46.478952 -225.228912)
		(end 45.790866 -225.228912)
		(width 0.18288)
		(layer "In11.Cu")
		(net "M_D_CPU1_SB_DQS_DN<0>")
	)
	(segment
		(start 48.570134 -225.195892)
		(end 47.489872 -225.195892)
		(width 0.18288)
		(layer "In11.Cu")
		(net "M_D_CPU1_SB_DQS_DN<0>")
	)
	(segment
		(start 86.830916 -239.0394)
		(end 86.830916 -239.029494)
		(width 0.088646)
		(layer "In11.Cu")
		(net "M_D_CPU1_SB_DQS_DN<0>")
	)
	(segment
		(start 64.377824 -227.667312)
		(end 64.201802 -227.667058)
		(width 0.18288)
		(layer "In11.Cu")
		(net "M_D_CPU1_SB_DQS_DN<0>")
	)
	(segment
		(start 56.754522 -225.25355)
		(end 55.850028 -224.8789)
		(width 0.18288)
		(layer "In11.Cu")
		(net "M_D_CPU1_SB_DQS_DN<0>")
	)
	(segment
		(start 59.439302 -225.642932)
		(end 58.499502 -225.25355)
		(width 0.18288)
		(layer "In11.Cu")
		(net "M_D_CPU1_SB_DQS_DN<0>")
	)
	(segment
		(start 98.013012 -239.853216)
		(end 97.981262 -239.96904)
		(width 0.088646)
		(layer "In11.Cu")
		(net "M_D_CPU1_SB_DQS_DN<0>")
	)
	(segment
		(start 54.565804 -224.347024)
		(end 51.56581 -224.347024)
		(width 0.18288)
		(layer "In11.Cu")
		(net "M_D_CPU1_SB_DQS_DN<0>")
	)
	(segment
		(start 75.548744 -236.725968)
		(end 75.548744 -236.549946)
		(width 0.18288)
		(layer "In11.Cu")
		(net "M_D_CPU1_SB_DQS_DN<0>")
	)
	(segment
		(start 45.790866 -225.228912)
		(end 45.218858 -225.80092)
		(width 0.18288)
		(layer "In11.Cu")
		(net "M_D_CPU1_SB_DQS_DN<0>")
	)
	(segment
		(start 32.14751 -224.94113)
		(end 31.671514 -224.94113)
		(width 0.18288)
		(layer "In11.Cu")
		(net "M_D_CPU1_SB_DQS_DN<0>")
	)
	(segment
		(start 82.775044 -237.173516)
		(end 82.43316 -237.173516)
		(width 0.088646)
		(layer "In11.Cu")
		(net "M_D_CPU1_SB_DQS_DN<0>")
	)
	(segment
		(start 72.692768 -233.869992)
		(end 72.692768 -233.69397)
		(width 0.18288)
		(layer "In11.Cu")
		(net "M_D_CPU1_SB_DQS_DN<0>")
	)
	(segment
		(start 65.895728 -228.345746)
		(end 65.62217 -228.619304)
		(width 0.18288)
		(layer "In11.Cu")
		(net "M_D_CPU1_SB_DQS_DN<0>")
	)
	(segment
		(start 74.596752 -235.597954)
		(end 74.20864 -235.209842)
		(width 0.18288)
		(layer "In11.Cu")
		(net "M_D_CPU1_SB_DQS_DN<0>")
	)
	(segment
		(start 62.998858 -226.892866)
		(end 62.580266 -226.892866)
		(width 0.18288)
		(layer "In11.Cu")
		(net "M_D_CPU1_SB_DQS_DN<0>")
	)
	(segment
		(start 30.150308 -225.502216)
		(end 28.96108 -226.691444)
		(width 0.18288)
		(layer "In11.Cu")
		(net "M_D_CPU1_SB_DQS_DN<0>")
	)
	(segment
		(start 49.9872 -224.380552)
		(end 49.59731 -224.770188)
		(width 0.18288)
		(layer "In11.Cu")
		(net "M_D_CPU1_SB_DQS_DN<0>")
	)
	(segment
		(start 72.692768 -233.69397)
		(end 72.304656 -233.305858)
		(width 0.18288)
		(layer "In11.Cu")
		(net "M_D_CPU1_SB_DQS_DN<0>")
	)
	(arc
		(start 85.043264 -238.549942)
		(mid 84.856066 -238.600085)
		(end 84.668868 -238.549942)
		(width 0.088646)
		(layer "In11.Cu")
		(net "M_D_CPU1_SB_DQS_DN<0>")
	)
	(arc
		(start 88.80221 -240.177574)
		(mid 88.615012 -240.227717)
		(end 88.427814 -240.177574)
		(width 0.088646)
		(layer "In11.Cu")
		(net "M_D_CPU1_SB_DQS_DN<0>")
	)
	(arc
		(start 96.32061 -240.177574)
		(mid 96.133412 -240.227717)
		(end 95.946214 -240.177574)
		(width 0.088646)
		(layer "In11.Cu")
		(net "M_D_CPU1_SB_DQS_DN<0>")
	)
	(arc
		(start 86.548468 -238.549942)
		(mid 86.265766 -238.474166)
		(end 85.983064 -238.549942)
		(width 0.088646)
		(layer "In11.Cu")
		(net "M_D_CPU1_SB_DQS_DN<0>")
	)
	(arc
		(start 90.297254 -240.171478)
		(mid 90.018822 -240.101664)
		(end 89.74201 -240.177574)
		(width 0.088646)
		(layer "In11.Cu")
		(net "M_D_CPU1_SB_DQS_DN<0>")
	)
	(arc
		(start 88.418924 -240.172494)
		(mid 88.28801 -240.036134)
		(end 88.240362 -239.853216)
		(width 0.088646)
		(layer "In11.Cu")
		(net "M_D_CPU1_SB_DQS_DN<0>")
	)
	(arc
		(start 92.56141 -240.177574)
		(mid 92.374212 -240.227717)
		(end 92.187014 -240.177574)
		(width 0.088646)
		(layer "In11.Cu")
		(net "M_D_CPU1_SB_DQS_DN<0>")
	)
	(arc
		(start 87.009478 -239.358678)
		(mid 86.878564 -239.222318)
		(end 86.830916 -239.0394)
		(width 0.088646)
		(layer "In11.Cu")
		(net "M_D_CPU1_SB_DQS_DN<0>")
	)
	(arc
		(start 97.260664 -240.177574)
		(mid 97.073466 -240.227717)
		(end 96.886268 -240.177574)
		(width 0.088646)
		(layer "In11.Cu")
		(net "M_D_CPU1_SB_DQS_DN<0>")
	)
	(arc
		(start 87.958168 -239.363758)
		(mid 87.683969 -239.287923)
		(end 87.407496 -239.355122)
		(width 0.088646)
		(layer "In11.Cu")
		(net "M_D_CPU1_SB_DQS_DN<0>")
	)
	(arc
		(start 92.172282 -240.168938)
		(mid 91.895841 -240.101772)
		(end 91.62161 -240.177574)
		(width 0.088646)
		(layer "In11.Cu")
		(net "M_D_CPU1_SB_DQS_DN<0>")
	)
	(arc
		(start 97.9424 -239.991138)
		(mid 97.867715 -240.021643)
		(end 97.787714 -240.032032)
		(width 0.088646)
		(layer "In11.Cu")
		(net "M_D_CPU1_SB_DQS_DN<0>")
	)
	(arc
		(start 85.608668 -238.549942)
		(mid 85.325966 -238.474166)
		(end 85.043264 -238.549942)
		(width 0.088646)
		(layer "In11.Cu")
		(net "M_D_CPU1_SB_DQS_DN<0>")
	)
	(arc
		(start 84.668868 -238.549942)
		(mid 84.532376 -238.493467)
		(end 84.385912 -238.47425)
		(width 0.088646)
		(layer "In11.Cu")
		(net "M_D_CPU1_SB_DQS_DN<0>")
	)
	(arc
		(start 96.875854 -240.171478)
		(mid 96.597422 -240.101664)
		(end 96.32061 -240.177574)
		(width 0.088646)
		(layer "In11.Cu")
		(net "M_D_CPU1_SB_DQS_DN<0>")
	)
	(arc
		(start 90.682064 -240.177574)
		(mid 90.494866 -240.227717)
		(end 90.307668 -240.177574)
		(width 0.088646)
		(layer "In11.Cu")
		(net "M_D_CPU1_SB_DQS_DN<0>")
	)
	(arc
		(start 94.991682 -240.168938)
		(mid 94.715241 -240.101772)
		(end 94.44101 -240.177574)
		(width 0.088646)
		(layer "In11.Cu")
		(net "M_D_CPU1_SB_DQS_DN<0>")
	)
	(arc
		(start 94.44101 -240.177574)
		(mid 94.253812 -240.227717)
		(end 94.066614 -240.177574)
		(width 0.088646)
		(layer "In11.Cu")
		(net "M_D_CPU1_SB_DQS_DN<0>")
	)
	(arc
		(start 95.931482 -240.168938)
		(mid 95.655041 -240.101772)
		(end 95.38081 -240.177574)
		(width 0.088646)
		(layer "In11.Cu")
		(net "M_D_CPU1_SB_DQS_DN<0>")
	)
	(arc
		(start 91.62161 -240.177574)
		(mid 91.434412 -240.227717)
		(end 91.247214 -240.177574)
		(width 0.088646)
		(layer "In11.Cu")
		(net "M_D_CPU1_SB_DQS_DN<0>")
	)
	(arc
		(start 94.051882 -240.168938)
		(mid 93.775441 -240.101772)
		(end 93.50121 -240.177574)
		(width 0.088646)
		(layer "In11.Cu")
		(net "M_D_CPU1_SB_DQS_DN<0>")
	)
	(arc
		(start 85.983064 -238.549942)
		(mid 85.795866 -238.600085)
		(end 85.608668 -238.549942)
		(width 0.088646)
		(layer "In11.Cu")
		(net "M_D_CPU1_SB_DQS_DN<0>")
	)
	(arc
		(start 86.830916 -239.029494)
		(mid 86.752805 -238.752545)
		(end 86.548468 -238.549942)
		(width 0.088646)
		(layer "In11.Cu")
		(net "M_D_CPU1_SB_DQS_DN<0>")
	)
	(arc
		(start 95.38081 -240.177574)
		(mid 95.193612 -240.227717)
		(end 95.006414 -240.177574)
		(width 0.088646)
		(layer "In11.Cu")
		(net "M_D_CPU1_SB_DQS_DN<0>")
	)
	(arc
		(start 93.50121 -240.177574)
		(mid 93.314012 -240.227717)
		(end 93.126814 -240.177574)
		(width 0.088646)
		(layer "In11.Cu")
		(net "M_D_CPU1_SB_DQS_DN<0>")
	)
	(arc
		(start 89.352882 -240.168938)
		(mid 89.076441 -240.101772)
		(end 88.80221 -240.177574)
		(width 0.088646)
		(layer "In11.Cu")
		(net "M_D_CPU1_SB_DQS_DN<0>")
	)
	(arc
		(start 89.74201 -240.177574)
		(mid 89.554812 -240.227717)
		(end 89.367614 -240.177574)
		(width 0.088646)
		(layer "In11.Cu")
		(net "M_D_CPU1_SB_DQS_DN<0>")
	)
	(arc
		(start 91.247214 -240.177574)
		(mid 90.970655 -240.101865)
		(end 90.692478 -240.171478)
		(width 0.088646)
		(layer "In11.Cu")
		(net "M_D_CPU1_SB_DQS_DN<0>")
	)
	(arc
		(start 88.240362 -239.837722)
		(mid 88.160992 -239.563988)
		(end 87.958168 -239.363758)
		(width 0.088646)
		(layer "In11.Cu")
		(net "M_D_CPU1_SB_DQS_DN<0>")
	)
	(arc
		(start 87.392764 -239.363758)
		(mid 87.205566 -239.413901)
		(end 87.018368 -239.363758)
		(width 0.088646)
		(layer "In11.Cu")
		(net "M_D_CPU1_SB_DQS_DN<0>")
	)
	(arc
		(start 93.112082 -240.168938)
		(mid 92.835641 -240.101772)
		(end 92.56141 -240.177574)
		(width 0.088646)
		(layer "In11.Cu")
		(net "M_D_CPU1_SB_DQS_DN<0>")
	)
	(segment
		(start 11.11631 -220.68282)
		(end 11.1252 -220.69171)
		(width 0.1016)
		(layer "F.Cu")
		(net "M_D_CPU1_SB_DQ<9>")
	)
	(segment
		(start 13.110718 -220.69171)
		(end 13.441426 -220.69171)
		(width 0.101854)
		(layer "F.Cu")
		(net "M_D_CPU1_SB_DQ<9>")
	)
	(segment
		(start 98.483166 -236.319568)
		(end 98.483166 -235.783882)
		(width 0.20066)
		(layer "F.Cu")
		(net "M_D_CPU1_SB_DQ<9>")
	)
	(segment
		(start 10.344912 -221.173548)
		(end 10.344912 -220.84538)
		(width 0.20066)
		(layer "F.Cu")
		(net "M_D_CPU1_SB_DQ<9>")
	)
	(segment
		(start 16.789146 -221.116652)
		(end 15.684246 -221.116652)
		(width 0.20066)
		(layer "F.Cu")
		(net "M_D_CPU1_SB_DQ<9>")
	)
	(segment
		(start 10.19048 -221.32798)
		(end 10.344912 -221.173548)
		(width 0.20066)
		(layer "F.Cu")
		(net "M_D_CPU1_SB_DQ<9>")
	)
	(segment
		(start 9.474708 -221.116652)
		(end 9.686036 -221.32798)
		(width 0.20066)
		(layer "F.Cu")
		(net "M_D_CPU1_SB_DQ<9>")
	)
	(segment
		(start 14.04493 -221.116652)
		(end 15.684246 -221.116652)
		(width 0.20066)
		(layer "F.Cu")
		(net "M_D_CPU1_SB_DQ<9>")
	)
	(segment
		(start 13.441426 -220.69171)
		(end 13.619988 -220.69171)
		(width 0.20066)
		(layer "F.Cu")
		(net "M_D_CPU1_SB_DQ<9>")
	)
	(segment
		(start 13.619988 -220.69171)
		(end 14.04493 -221.116652)
		(width 0.20066)
		(layer "F.Cu")
		(net "M_D_CPU1_SB_DQ<9>")
	)
	(segment
		(start 8.140446 -221.116652)
		(end 9.474708 -221.116652)
		(width 0.20066)
		(layer "F.Cu")
		(net "M_D_CPU1_SB_DQ<9>")
	)
	(segment
		(start 11.1252 -220.69171)
		(end 13.110718 -220.69171)
		(width 0.1016)
		(layer "F.Cu")
		(net "M_D_CPU1_SB_DQ<9>")
	)
	(segment
		(start 98.482912 -236.319822)
		(end 98.483166 -236.319568)
		(width 0.20066)
		(layer "F.Cu")
		(net "M_D_CPU1_SB_DQ<9>")
	)
	(segment
		(start 9.686036 -221.32798)
		(end 10.19048 -221.32798)
		(width 0.20066)
		(layer "F.Cu")
		(net "M_D_CPU1_SB_DQ<9>")
	)
	(segment
		(start 10.507472 -220.68282)
		(end 11.11631 -220.68282)
		(width 0.20066)
		(layer "F.Cu")
		(net "M_D_CPU1_SB_DQ<9>")
	)
	(segment
		(start 10.344912 -220.84538)
		(end 10.507472 -220.68282)
		(width 0.20066)
		(layer "F.Cu")
		(net "M_D_CPU1_SB_DQ<9>")
	)
	(segment
		(start 42.06367 -214.507826)
		(end 40.46347 -214.507826)
		(width 0.18288)
		(layer "In11.Cu")
		(net "M_D_CPU1_SB_DQ<9>")
	)
	(segment
		(start 89.7509 -234.650788)
		(end 89.74201 -234.645708)
		(width 0.088646)
		(layer "In11.Cu")
		(net "M_D_CPU1_SB_DQ<9>")
	)
	(segment
		(start 17.378172 -220.527626)
		(end 16.789146 -221.116652)
		(width 0.18288)
		(layer "In11.Cu")
		(net "M_D_CPU1_SB_DQ<9>")
	)
	(segment
		(start 30.282388 -214.742268)
		(end 29.843984 -214.742268)
		(width 0.18288)
		(layer "In11.Cu")
		(net "M_D_CPU1_SB_DQ<9>")
	)
	(segment
		(start 49.773078 -214.517478)
		(end 48.235616 -214.517478)
		(width 0.18288)
		(layer "In11.Cu")
		(net "M_D_CPU1_SB_DQ<9>")
	)
	(segment
		(start 55.075582 -213.723982)
		(end 52.315872 -213.723982)
		(width 0.18288)
		(layer "In11.Cu")
		(net "M_D_CPU1_SB_DQ<9>")
	)
	(segment
		(start 58.74893 -214.609426)
		(end 55.961026 -214.609426)
		(width 0.18288)
		(layer "In11.Cu")
		(net "M_D_CPU1_SB_DQ<9>")
	)
	(segment
		(start 29.037026 -215.549226)
		(end 29.037026 -217.759026)
		(width 0.18288)
		(layer "In11.Cu")
		(net "M_D_CPU1_SB_DQ<9>")
	)
	(segment
		(start 48.235616 -214.517478)
		(end 48.010826 -214.742268)
		(width 0.18288)
		(layer "In11.Cu")
		(net "M_D_CPU1_SB_DQ<9>")
	)
	(segment
		(start 43.25747 -215.701626)
		(end 42.06367 -214.507826)
		(width 0.18288)
		(layer "In11.Cu")
		(net "M_D_CPU1_SB_DQ<9>")
	)
	(segment
		(start 66.140076 -218.471242)
		(end 65.90411 -218.471242)
		(width 0.18288)
		(layer "In11.Cu")
		(net "M_D_CPU1_SB_DQ<9>")
	)
	(segment
		(start 34.396426 -214.562182)
		(end 32.796226 -214.562182)
		(width 0.18288)
		(layer "In11.Cu")
		(net "M_D_CPU1_SB_DQ<9>")
	)
	(segment
		(start 83.594702 -233.781092)
		(end 83.116166 -233.302556)
		(width 0.088646)
		(layer "In11.Cu")
		(net "M_D_CPU1_SB_DQ<9>")
	)
	(segment
		(start 67.34048 -220.16339)
		(end 66.9925 -219.323666)
		(width 0.18288)
		(layer "In11.Cu")
		(net "M_D_CPU1_SB_DQ<9>")
	)
	(segment
		(start 32.61614 -214.742268)
		(end 31.369508 -214.742268)
		(width 0.18288)
		(layer "In11.Cu")
		(net "M_D_CPU1_SB_DQ<9>")
	)
	(segment
		(start 31.369508 -214.742268)
		(end 31.176468 -214.935308)
		(width 0.18288)
		(layer "In11.Cu")
		(net "M_D_CPU1_SB_DQ<9>")
	)
	(segment
		(start 45.922438 -214.742268)
		(end 45.264324 -215.400382)
		(width 0.18288)
		(layer "In11.Cu")
		(net "M_D_CPU1_SB_DQ<9>")
	)
	(segment
		(start 83.116166 -233.302556)
		(end 83.116166 -232.907332)
		(width 0.088646)
		(layer "In11.Cu")
		(net "M_D_CPU1_SB_DQ<9>")
	)
	(segment
		(start 96.886014 -236.273594)
		(end 96.871282 -236.28223)
		(width 0.088646)
		(layer "In11.Cu")
		(net "M_D_CPU1_SB_DQ<9>")
	)
	(segment
		(start 64.412114 -218.471242)
		(end 63.822326 -217.881454)
		(width 0.18288)
		(layer "In11.Cu")
		(net "M_D_CPU1_SB_DQ<9>")
	)
	(segment
		(start 52.147724 -213.89213)
		(end 50.398426 -213.89213)
		(width 0.18288)
		(layer "In11.Cu")
		(net "M_D_CPU1_SB_DQ<9>")
	)
	(segment
		(start 65.90411 -218.471242)
		(end 65.607692 -218.76766)
		(width 0.18288)
		(layer "In11.Cu")
		(net "M_D_CPU1_SB_DQ<9>")
	)
	(segment
		(start 95.006414 -236.273594)
		(end 94.996 -236.27969)
		(width 0.088646)
		(layer "In11.Cu")
		(net "M_D_CPU1_SB_DQ<9>")
	)
	(segment
		(start 82.633312 -232.424478)
		(end 82.37347 -232.424478)
		(width 0.088646)
		(layer "In11.Cu")
		(net "M_D_CPU1_SB_DQ<9>")
	)
	(segment
		(start 18.245074 -220.194886)
		(end 18.245074 -220.367606)
		(width 0.18288)
		(layer "In11.Cu")
		(net "M_D_CPU1_SB_DQ<9>")
	)
	(segment
		(start 32.796226 -214.562182)
		(end 32.61614 -214.742268)
		(width 0.18288)
		(layer "In11.Cu")
		(net "M_D_CPU1_SB_DQ<9>")
	)
	(segment
		(start 40.46347 -214.507826)
		(end 39.734236 -213.778592)
		(width 0.18288)
		(layer "In11.Cu")
		(net "M_D_CPU1_SB_DQ<9>")
	)
	(segment
		(start 45.264324 -215.400382)
		(end 44.24807 -215.400382)
		(width 0.18288)
		(layer "In11.Cu")
		(net "M_D_CPU1_SB_DQ<9>")
	)
	(segment
		(start 28.744926 -218.051126)
		(end 27.906726 -218.051126)
		(width 0.18288)
		(layer "In11.Cu")
		(net "M_D_CPU1_SB_DQ<9>")
	)
	(segment
		(start 29.037026 -217.759026)
		(end 28.744926 -218.051126)
		(width 0.18288)
		(layer "In11.Cu")
		(net "M_D_CPU1_SB_DQ<9>")
	)
	(segment
		(start 30.983428 -215.514682)
		(end 30.668468 -215.514682)
		(width 0.18288)
		(layer "In11.Cu")
		(net "M_D_CPU1_SB_DQ<9>")
	)
	(segment
		(start 25.458166 -219.867226)
		(end 24.416766 -220.908626)
		(width 0.18288)
		(layer "In11.Cu")
		(net "M_D_CPU1_SB_DQ<9>")
	)
	(segment
		(start 39.734236 -213.778592)
		(end 36.881816 -213.778592)
		(width 0.18288)
		(layer "In11.Cu")
		(net "M_D_CPU1_SB_DQ<9>")
	)
	(segment
		(start 90.212164 -235.459524)
		(end 90.199972 -235.452412)
		(width 0.088646)
		(layer "In11.Cu")
		(net "M_D_CPU1_SB_DQ<9>")
	)
	(segment
		(start 64.906652 -218.471242)
		(end 64.412114 -218.471242)
		(width 0.18288)
		(layer "In11.Cu")
		(net "M_D_CPU1_SB_DQ<9>")
	)
	(segment
		(start 26.725626 -219.232226)
		(end 26.725626 -219.562426)
		(width 0.18288)
		(layer "In11.Cu")
		(net "M_D_CPU1_SB_DQ<9>")
	)
	(segment
		(start 88.341454 -233.836972)
		(end 88.332564 -233.831892)
		(width 0.088646)
		(layer "In11.Cu")
		(net "M_D_CPU1_SB_DQ<9>")
	)
	(segment
		(start 18.085054 -220.527626)
		(end 17.378172 -220.527626)
		(width 0.18288)
		(layer "In11.Cu")
		(net "M_D_CPU1_SB_DQ<9>")
	)
	(segment
		(start 21.21916 -221.54134)
		(end 20.447 -221.54134)
		(width 0.18288)
		(layer "In11.Cu")
		(net "M_D_CPU1_SB_DQ<9>")
	)
	(segment
		(start 20.447 -221.54134)
		(end 20.11553 -221.20987)
		(width 0.18288)
		(layer "In11.Cu")
		(net "M_D_CPU1_SB_DQ<9>")
	)
	(segment
		(start 93.126814 -236.273594)
		(end 93.112082 -236.28223)
		(width 0.088646)
		(layer "In11.Cu")
		(net "M_D_CPU1_SB_DQ<9>")
	)
	(segment
		(start 23.358094 -220.908626)
		(end 22.88794 -221.37878)
		(width 0.18288)
		(layer "In11.Cu")
		(net "M_D_CPU1_SB_DQ<9>")
	)
	(segment
		(start 43.946826 -215.701626)
		(end 43.25747 -215.701626)
		(width 0.18288)
		(layer "In11.Cu")
		(net "M_D_CPU1_SB_DQ<9>")
	)
	(segment
		(start 60.177426 -215.523826)
		(end 59.66333 -215.523826)
		(width 0.18288)
		(layer "In11.Cu")
		(net "M_D_CPU1_SB_DQ<9>")
	)
	(segment
		(start 98.483166 -235.783882)
		(end 98.104706 -236.162342)
		(width 0.088646)
		(layer "In11.Cu")
		(net "M_D_CPU1_SB_DQ<9>")
	)
	(segment
		(start 36.881816 -213.778592)
		(end 36.768278 -213.89213)
		(width 0.18288)
		(layer "In11.Cu")
		(net "M_D_CPU1_SB_DQ<9>")
	)
	(segment
		(start 48.010826 -214.742268)
		(end 45.922438 -214.742268)
		(width 0.18288)
		(layer "In11.Cu")
		(net "M_D_CPU1_SB_DQ<9>")
	)
	(segment
		(start 26.725626 -219.562426)
		(end 26.420826 -219.867226)
		(width 0.18288)
		(layer "In11.Cu")
		(net "M_D_CPU1_SB_DQ<9>")
	)
	(segment
		(start 65.20307 -218.76766)
		(end 64.906652 -218.471242)
		(width 0.18288)
		(layer "In11.Cu")
		(net "M_D_CPU1_SB_DQ<9>")
	)
	(segment
		(start 79.601568 -232.424478)
		(end 67.34048 -220.16339)
		(width 0.18288)
		(layer "In11.Cu")
		(net "M_D_CPU1_SB_DQ<9>")
	)
	(segment
		(start 24.416766 -220.908626)
		(end 23.358094 -220.908626)
		(width 0.18288)
		(layer "In11.Cu")
		(net "M_D_CPU1_SB_DQ<9>")
	)
	(segment
		(start 31.176468 -215.321642)
		(end 30.983428 -215.514682)
		(width 0.18288)
		(layer "In11.Cu")
		(net "M_D_CPU1_SB_DQ<9>")
	)
	(segment
		(start 88.520016 -234.171744)
		(end 88.520016 -234.15625)
		(width 0.088646)
		(layer "In11.Cu")
		(net "M_D_CPU1_SB_DQ<9>")
	)
	(segment
		(start 63.23965 -217.881454)
		(end 62.558422 -217.200226)
		(width 0.18288)
		(layer "In11.Cu")
		(net "M_D_CPU1_SB_DQ<9>")
	)
	(segment
		(start 20.11553 -220.777054)
		(end 19.373342 -220.034866)
		(width 0.18288)
		(layer "In11.Cu")
		(net "M_D_CPU1_SB_DQ<9>")
	)
	(segment
		(start 94.066868 -236.273594)
		(end 94.056454 -236.27969)
		(width 0.088646)
		(layer "In11.Cu")
		(net "M_D_CPU1_SB_DQ<9>")
	)
	(segment
		(start 35.066478 -213.89213)
		(end 34.396426 -214.562182)
		(width 0.18288)
		(layer "In11.Cu")
		(net "M_D_CPU1_SB_DQ<9>")
	)
	(segment
		(start 59.66333 -215.523826)
		(end 58.74893 -214.609426)
		(width 0.18288)
		(layer "In11.Cu")
		(net "M_D_CPU1_SB_DQ<9>")
	)
	(segment
		(start 62.558422 -217.200226)
		(end 61.853826 -217.200226)
		(width 0.18288)
		(layer "In11.Cu")
		(net "M_D_CPU1_SB_DQ<9>")
	)
	(segment
		(start 95.946214 -236.273594)
		(end 95.931482 -236.28223)
		(width 0.088646)
		(layer "In11.Cu")
		(net "M_D_CPU1_SB_DQ<9>")
	)
	(segment
		(start 90.399362 -235.802424)
		(end 90.399362 -235.775246)
		(width 0.088646)
		(layer "In11.Cu")
		(net "M_D_CPU1_SB_DQ<9>")
	)
	(segment
		(start 30.475428 -214.935308)
		(end 30.282388 -214.742268)
		(width 0.18288)
		(layer "In11.Cu")
		(net "M_D_CPU1_SB_DQ<9>")
	)
	(segment
		(start 61.853826 -217.200226)
		(end 60.177426 -215.523826)
		(width 0.18288)
		(layer "In11.Cu")
		(net "M_D_CPU1_SB_DQ<9>")
	)
	(segment
		(start 84.386166 -233.781092)
		(end 83.594702 -233.781092)
		(width 0.088646)
		(layer "In11.Cu")
		(net "M_D_CPU1_SB_DQ<9>")
	)
	(segment
		(start 26.420826 -219.867226)
		(end 25.458166 -219.867226)
		(width 0.18288)
		(layer "In11.Cu")
		(net "M_D_CPU1_SB_DQ<9>")
	)
	(segment
		(start 63.822326 -217.881454)
		(end 63.23965 -217.881454)
		(width 0.18288)
		(layer "In11.Cu")
		(net "M_D_CPU1_SB_DQ<9>")
	)
	(segment
		(start 20.11553 -221.20987)
		(end 20.11553 -220.777054)
		(width 0.18288)
		(layer "In11.Cu")
		(net "M_D_CPU1_SB_DQ<9>")
	)
	(segment
		(start 66.9925 -219.323666)
		(end 66.140076 -218.471242)
		(width 0.18288)
		(layer "In11.Cu")
		(net "M_D_CPU1_SB_DQ<9>")
	)
	(segment
		(start 29.843984 -214.742268)
		(end 29.037026 -215.549226)
		(width 0.18288)
		(layer "In11.Cu")
		(net "M_D_CPU1_SB_DQ<9>")
	)
	(segment
		(start 36.768278 -213.89213)
		(end 35.066478 -213.89213)
		(width 0.18288)
		(layer "In11.Cu")
		(net "M_D_CPU1_SB_DQ<9>")
	)
	(segment
		(start 89.367614 -234.645708)
		(end 89.352882 -234.654344)
		(width 0.088646)
		(layer "In11.Cu")
		(net "M_D_CPU1_SB_DQ<9>")
	)
	(segment
		(start 92.187014 -236.273594)
		(end 92.172282 -236.28223)
		(width 0.088646)
		(layer "In11.Cu")
		(net "M_D_CPU1_SB_DQ<9>")
	)
	(segment
		(start 55.961026 -214.609426)
		(end 55.075582 -213.723982)
		(width 0.18288)
		(layer "In11.Cu")
		(net "M_D_CPU1_SB_DQ<9>")
	)
	(segment
		(start 65.607692 -218.76766)
		(end 65.20307 -218.76766)
		(width 0.18288)
		(layer "In11.Cu")
		(net "M_D_CPU1_SB_DQ<9>")
	)
	(segment
		(start 30.668468 -215.514682)
		(end 30.475428 -215.321642)
		(width 0.18288)
		(layer "In11.Cu")
		(net "M_D_CPU1_SB_DQ<9>")
	)
	(segment
		(start 18.245074 -220.367606)
		(end 18.085054 -220.527626)
		(width 0.18288)
		(layer "In11.Cu")
		(net "M_D_CPU1_SB_DQ<9>")
	)
	(segment
		(start 27.906726 -218.051126)
		(end 26.725626 -219.232226)
		(width 0.18288)
		(layer "In11.Cu")
		(net "M_D_CPU1_SB_DQ<9>")
	)
	(segment
		(start 52.315872 -213.723982)
		(end 52.147724 -213.89213)
		(width 0.18288)
		(layer "In11.Cu")
		(net "M_D_CPU1_SB_DQ<9>")
	)
	(segment
		(start 19.373342 -220.034866)
		(end 18.405094 -220.034866)
		(width 0.18288)
		(layer "In11.Cu")
		(net "M_D_CPU1_SB_DQ<9>")
	)
	(segment
		(start 82.37347 -232.424478)
		(end 79.601568 -232.424478)
		(width 0.18288)
		(layer "In11.Cu")
		(net "M_D_CPU1_SB_DQ<9>")
	)
	(segment
		(start 44.24807 -215.400382)
		(end 43.946826 -215.701626)
		(width 0.18288)
		(layer "In11.Cu")
		(net "M_D_CPU1_SB_DQ<9>")
	)
	(segment
		(start 30.475428 -215.321642)
		(end 30.475428 -214.935308)
		(width 0.18288)
		(layer "In11.Cu")
		(net "M_D_CPU1_SB_DQ<9>")
	)
	(segment
		(start 50.398426 -213.89213)
		(end 49.773078 -214.517478)
		(width 0.18288)
		(layer "In11.Cu")
		(net "M_D_CPU1_SB_DQ<9>")
	)
	(segment
		(start 18.405094 -220.034866)
		(end 18.245074 -220.194886)
		(width 0.18288)
		(layer "In11.Cu")
		(net "M_D_CPU1_SB_DQ<9>")
	)
	(segment
		(start 83.116166 -232.907332)
		(end 82.633312 -232.424478)
		(width 0.088646)
		(layer "In11.Cu")
		(net "M_D_CPU1_SB_DQ<9>")
	)
	(segment
		(start 22.88794 -221.37878)
		(end 21.38172 -221.37878)
		(width 0.18288)
		(layer "In11.Cu")
		(net "M_D_CPU1_SB_DQ<9>")
	)
	(segment
		(start 21.38172 -221.37878)
		(end 21.21916 -221.54134)
		(width 0.18288)
		(layer "In11.Cu")
		(net "M_D_CPU1_SB_DQ<9>")
	)
	(segment
		(start 31.176468 -214.935308)
		(end 31.176468 -215.321642)
		(width 0.18288)
		(layer "In11.Cu")
		(net "M_D_CPU1_SB_DQ<9>")
	)
	(arc
		(start 86.078568 -233.831892)
		(mid 85.795866 -233.907634)
		(end 85.513164 -233.831892)
		(width 0.088646)
		(layer "In11.Cu")
		(net "M_D_CPU1_SB_DQ<9>")
	)
	(arc
		(start 96.871282 -236.28223)
		(mid 96.594841 -236.349396)
		(end 96.32061 -236.273594)
		(width 0.088646)
		(layer "In11.Cu")
		(net "M_D_CPU1_SB_DQ<9>")
	)
	(arc
		(start 97.825814 -236.273594)
		(mid 97.543112 -236.349336)
		(end 97.26041 -236.273594)
		(width 0.088646)
		(layer "In11.Cu")
		(net "M_D_CPU1_SB_DQ<9>")
	)
	(arc
		(start 95.38081 -236.273594)
		(mid 95.193612 -236.223451)
		(end 95.006414 -236.273594)
		(width 0.088646)
		(layer "In11.Cu")
		(net "M_D_CPU1_SB_DQ<9>")
	)
	(arc
		(start 87.392764 -233.831892)
		(mid 87.205566 -233.781749)
		(end 87.018368 -233.831892)
		(width 0.088646)
		(layer "In11.Cu")
		(net "M_D_CPU1_SB_DQ<9>")
	)
	(arc
		(start 91.247214 -236.273594)
		(mid 90.964512 -236.349336)
		(end 90.68181 -236.273594)
		(width 0.088646)
		(layer "In11.Cu")
		(net "M_D_CPU1_SB_DQ<9>")
	)
	(arc
		(start 96.32061 -236.273594)
		(mid 96.133412 -236.223451)
		(end 95.946214 -236.273594)
		(width 0.088646)
		(layer "In11.Cu")
		(net "M_D_CPU1_SB_DQ<9>")
	)
	(arc
		(start 97.26041 -236.273594)
		(mid 97.073212 -236.223451)
		(end 96.886014 -236.273594)
		(width 0.088646)
		(layer "In11.Cu")
		(net "M_D_CPU1_SB_DQ<9>")
	)
	(arc
		(start 95.931482 -236.28223)
		(mid 95.655041 -236.349396)
		(end 95.38081 -236.273594)
		(width 0.088646)
		(layer "In11.Cu")
		(net "M_D_CPU1_SB_DQ<9>")
	)
	(arc
		(start 84.573364 -233.831892)
		(mid 84.483108 -233.79417)
		(end 84.386166 -233.781092)
		(width 0.088646)
		(layer "In11.Cu")
		(net "M_D_CPU1_SB_DQ<9>")
	)
	(arc
		(start 89.352882 -234.654344)
		(mid 89.076407 -234.721664)
		(end 88.80221 -234.645708)
		(width 0.088646)
		(layer "In11.Cu")
		(net "M_D_CPU1_SB_DQ<9>")
	)
	(arc
		(start 86.452964 -233.831892)
		(mid 86.265766 -233.781749)
		(end 86.078568 -233.831892)
		(width 0.088646)
		(layer "In11.Cu")
		(net "M_D_CPU1_SB_DQ<9>")
	)
	(arc
		(start 90.68181 -236.273594)
		(mid 90.479524 -236.074613)
		(end 90.399362 -235.802424)
		(width 0.088646)
		(layer "In11.Cu")
		(net "M_D_CPU1_SB_DQ<9>")
	)
	(arc
		(start 88.80221 -234.645708)
		(mid 88.599387 -234.445477)
		(end 88.520016 -234.171744)
		(width 0.088646)
		(layer "In11.Cu")
		(net "M_D_CPU1_SB_DQ<9>")
	)
	(arc
		(start 92.172282 -236.28223)
		(mid 91.895841 -236.349396)
		(end 91.62161 -236.273594)
		(width 0.088646)
		(layer "In11.Cu")
		(net "M_D_CPU1_SB_DQ<9>")
	)
	(arc
		(start 89.929462 -234.970066)
		(mid 89.881783 -234.787166)
		(end 89.7509 -234.650788)
		(width 0.088646)
		(layer "In11.Cu")
		(net "M_D_CPU1_SB_DQ<9>")
	)
	(arc
		(start 88.520016 -234.15625)
		(mid 88.472337 -233.97335)
		(end 88.341454 -233.836972)
		(width 0.088646)
		(layer "In11.Cu")
		(net "M_D_CPU1_SB_DQ<9>")
	)
	(arc
		(start 90.399362 -235.775246)
		(mid 90.347092 -235.592881)
		(end 90.212164 -235.459524)
		(width 0.088646)
		(layer "In11.Cu")
		(net "M_D_CPU1_SB_DQ<9>")
	)
	(arc
		(start 93.112082 -236.28223)
		(mid 92.835641 -236.349396)
		(end 92.56141 -236.273594)
		(width 0.088646)
		(layer "In11.Cu")
		(net "M_D_CPU1_SB_DQ<9>")
	)
	(arc
		(start 87.958168 -233.831892)
		(mid 87.675466 -233.907634)
		(end 87.392764 -233.831892)
		(width 0.088646)
		(layer "In11.Cu")
		(net "M_D_CPU1_SB_DQ<9>")
	)
	(arc
		(start 90.199972 -235.452412)
		(mid 90.001744 -235.246564)
		(end 89.929462 -234.970066)
		(width 0.088646)
		(layer "In11.Cu")
		(net "M_D_CPU1_SB_DQ<9>")
	)
	(arc
		(start 94.056454 -236.27969)
		(mid 93.778022 -236.349504)
		(end 93.50121 -236.273594)
		(width 0.088646)
		(layer "In11.Cu")
		(net "M_D_CPU1_SB_DQ<9>")
	)
	(arc
		(start 87.018368 -233.831892)
		(mid 86.735666 -233.907634)
		(end 86.452964 -233.831892)
		(width 0.088646)
		(layer "In11.Cu")
		(net "M_D_CPU1_SB_DQ<9>")
	)
	(arc
		(start 88.332564 -233.831892)
		(mid 88.145366 -233.781749)
		(end 87.958168 -233.831892)
		(width 0.088646)
		(layer "In11.Cu")
		(net "M_D_CPU1_SB_DQ<9>")
	)
	(arc
		(start 93.50121 -236.273594)
		(mid 93.314012 -236.223451)
		(end 93.126814 -236.273594)
		(width 0.088646)
		(layer "In11.Cu")
		(net "M_D_CPU1_SB_DQ<9>")
	)
	(arc
		(start 92.56141 -236.273594)
		(mid 92.374212 -236.223451)
		(end 92.187014 -236.273594)
		(width 0.088646)
		(layer "In11.Cu")
		(net "M_D_CPU1_SB_DQ<9>")
	)
	(arc
		(start 97.972626 -236.225588)
		(mid 97.896709 -236.241919)
		(end 97.825814 -236.273594)
		(width 0.088646)
		(layer "In11.Cu")
		(net "M_D_CPU1_SB_DQ<9>")
	)
	(arc
		(start 85.513164 -233.831892)
		(mid 85.325966 -233.781749)
		(end 85.138768 -233.831892)
		(width 0.088646)
		(layer "In11.Cu")
		(net "M_D_CPU1_SB_DQ<9>")
	)
	(arc
		(start 89.74201 -234.645708)
		(mid 89.554812 -234.595565)
		(end 89.367614 -234.645708)
		(width 0.088646)
		(layer "In11.Cu")
		(net "M_D_CPU1_SB_DQ<9>")
	)
	(arc
		(start 94.441264 -236.273594)
		(mid 94.254066 -236.223451)
		(end 94.066868 -236.273594)
		(width 0.088646)
		(layer "In11.Cu")
		(net "M_D_CPU1_SB_DQ<9>")
	)
	(arc
		(start 94.996 -236.27969)
		(mid 94.717822 -236.349382)
		(end 94.441264 -236.273594)
		(width 0.088646)
		(layer "In11.Cu")
		(net "M_D_CPU1_SB_DQ<9>")
	)
	(arc
		(start 85.138768 -233.831892)
		(mid 84.856066 -233.907634)
		(end 84.573364 -233.831892)
		(width 0.088646)
		(layer "In11.Cu")
		(net "M_D_CPU1_SB_DQ<9>")
	)
	(arc
		(start 98.104706 -236.162342)
		(mid 98.044077 -236.205276)
		(end 97.972626 -236.225588)
		(width 0.088646)
		(layer "In11.Cu")
		(net "M_D_CPU1_SB_DQ<9>")
	)
	(arc
		(start 91.62161 -236.273594)
		(mid 91.434412 -236.223451)
		(end 91.247214 -236.273594)
		(width 0.088646)
		(layer "In11.Cu")
		(net "M_D_CPU1_SB_DQ<9>")
	)
	(segment
		(start 8.140446 -222.816674)
		(end 9.474708 -222.816674)
		(width 0.20066)
		(layer "F.Cu")
		(net "M_D_CPU1_SB_DQ<8>")
	)
	(segment
		(start 16.789146 -222.816674)
		(end 15.684246 -222.816674)
		(width 0.20066)
		(layer "F.Cu")
		(net "M_D_CPU1_SB_DQ<8>")
	)
	(segment
		(start 13.890244 -222.391732)
		(end 14.315186 -222.816674)
		(width 0.20066)
		(layer "F.Cu")
		(net "M_D_CPU1_SB_DQ<8>")
	)
	(segment
		(start 10.344912 -222.593154)
		(end 10.554462 -222.383604)
		(width 0.20066)
		(layer "F.Cu")
		(net "M_D_CPU1_SB_DQ<8>")
	)
	(segment
		(start 11.124438 -222.391732)
		(end 11.372342 -222.391732)
		(width 0.101854)
		(layer "F.Cu")
		(net "M_D_CPU1_SB_DQ<8>")
	)
	(segment
		(start 9.713468 -223.055434)
		(end 10.172192 -223.055434)
		(width 0.20066)
		(layer "F.Cu")
		(net "M_D_CPU1_SB_DQ<8>")
	)
	(segment
		(start 10.344912 -222.882714)
		(end 10.344912 -222.593154)
		(width 0.20066)
		(layer "F.Cu")
		(net "M_D_CPU1_SB_DQ<8>")
	)
	(segment
		(start 13.441426 -222.391732)
		(end 13.890244 -222.391732)
		(width 0.20066)
		(layer "F.Cu")
		(net "M_D_CPU1_SB_DQ<8>")
	)
	(segment
		(start 9.474708 -222.816674)
		(end 9.713468 -223.055434)
		(width 0.20066)
		(layer "F.Cu")
		(net "M_D_CPU1_SB_DQ<8>")
	)
	(segment
		(start 11.11631 -222.383604)
		(end 11.124438 -222.391732)
		(width 0.101854)
		(layer "F.Cu")
		(net "M_D_CPU1_SB_DQ<8>")
	)
	(segment
		(start 98.953066 -237.133892)
		(end 98.952812 -237.133638)
		(width 0.20066)
		(layer "F.Cu")
		(net "M_D_CPU1_SB_DQ<8>")
	)
	(segment
		(start 11.372342 -222.391732)
		(end 13.441426 -222.391732)
		(width 0.1016)
		(layer "F.Cu")
		(net "M_D_CPU1_SB_DQ<8>")
	)
	(segment
		(start 14.315186 -222.816674)
		(end 15.684246 -222.816674)
		(width 0.20066)
		(layer "F.Cu")
		(net "M_D_CPU1_SB_DQ<8>")
	)
	(segment
		(start 98.952812 -237.133638)
		(end 98.952812 -236.597952)
		(width 0.20066)
		(layer "F.Cu")
		(net "M_D_CPU1_SB_DQ<8>")
	)
	(segment
		(start 10.554462 -222.383604)
		(end 11.11631 -222.383604)
		(width 0.20066)
		(layer "F.Cu")
		(net "M_D_CPU1_SB_DQ<8>")
	)
	(segment
		(start 10.172192 -223.055434)
		(end 10.344912 -222.882714)
		(width 0.20066)
		(layer "F.Cu")
		(net "M_D_CPU1_SB_DQ<8>")
	)
	(segment
		(start 29.494226 -219.194126)
		(end 28.783026 -219.905326)
		(width 0.18288)
		(layer "In11.Cu")
		(net "M_D_CPU1_SB_DQ<8>")
	)
	(segment
		(start 35.53206 -216.311226)
		(end 35.175698 -216.311226)
		(width 0.18288)
		(layer "In11.Cu")
		(net "M_D_CPU1_SB_DQ<8>")
	)
	(segment
		(start 59.592972 -217.149426)
		(end 58.703972 -216.260426)
		(width 0.18288)
		(layer "In11.Cu")
		(net "M_D_CPU1_SB_DQ<8>")
	)
	(segment
		(start 42.168826 -216.387426)
		(end 40.340026 -216.387426)
		(width 0.18288)
		(layer "In11.Cu")
		(net "M_D_CPU1_SB_DQ<8>")
	)
	(segment
		(start 49.478438 -216.402666)
		(end 48.544734 -216.402666)
		(width 0.18288)
		(layer "In11.Cu")
		(net "M_D_CPU1_SB_DQ<8>")
	)
	(segment
		(start 34.281618 -216.504266)
		(end 34.088578 -216.311226)
		(width 0.18288)
		(layer "In11.Cu")
		(net "M_D_CPU1_SB_DQ<8>")
	)
	(segment
		(start 57.956704 -216.453466)
		(end 57.956704 -216.94394)
		(width 0.18288)
		(layer "In11.Cu")
		(net "M_D_CPU1_SB_DQ<8>")
	)
	(segment
		(start 89.459816 -235.80598)
		(end 89.459816 -235.783882)
		(width 0.088646)
		(layer "In11.Cu")
		(net "M_D_CPU1_SB_DQ<8>")
	)
	(segment
		(start 50.411888 -217.21191)
		(end 50.218848 -217.40495)
		(width 0.18288)
		(layer "In11.Cu")
		(net "M_D_CPU1_SB_DQ<8>")
	)
	(segment
		(start 89.7509 -236.278674)
		(end 89.74201 -236.273594)
		(width 0.088646)
		(layer "In11.Cu")
		(net "M_D_CPU1_SB_DQ<8>")
	)
	(segment
		(start 82.37347 -233.440478)
		(end 79.088996 -233.440478)
		(width 0.18288)
		(layer "In11.Cu")
		(net "M_D_CPU1_SB_DQ<8>")
	)
	(segment
		(start 30.116526 -219.194126)
		(end 29.494226 -219.194126)
		(width 0.18288)
		(layer "In11.Cu")
		(net "M_D_CPU1_SB_DQ<8>")
	)
	(segment
		(start 97.740978 -237.093506)
		(end 97.730564 -237.08741)
		(width 0.088646)
		(layer "In11.Cu")
		(net "M_D_CPU1_SB_DQ<8>")
	)
	(segment
		(start 37.034216 -216.666826)
		(end 36.809426 -216.442036)
		(width 0.18288)
		(layer "In11.Cu")
		(net "M_D_CPU1_SB_DQ<8>")
	)
	(segment
		(start 21.87956 -223.078548)
		(end 21.194268 -222.393256)
		(width 0.18288)
		(layer "In11.Cu")
		(net "M_D_CPU1_SB_DQ<8>")
	)
	(segment
		(start 57.255664 -216.453466)
		(end 57.062624 -216.260426)
		(width 0.18288)
		(layer "In11.Cu")
		(net "M_D_CPU1_SB_DQ<8>")
	)
	(segment
		(start 63.822326 -220.527626)
		(end 62.942216 -219.647516)
		(width 0.18288)
		(layer "In11.Cu")
		(net "M_D_CPU1_SB_DQ<8>")
	)
	(segment
		(start 83.988402 -234.7214)
		(end 82.70748 -233.440478)
		(width 0.088646)
		(layer "In11.Cu")
		(net "M_D_CPU1_SB_DQ<8>")
	)
	(segment
		(start 51.897026 -216.442036)
		(end 50.604928 -216.442036)
		(width 0.18288)
		(layer "In11.Cu")
		(net "M_D_CPU1_SB_DQ<8>")
	)
	(segment
		(start 49.903888 -217.40495)
		(end 49.710848 -217.21191)
		(width 0.18288)
		(layer "In11.Cu")
		(net "M_D_CPU1_SB_DQ<8>")
	)
	(segment
		(start 45.674026 -217.098626)
		(end 44.229782 -217.098626)
		(width 0.18288)
		(layer "In11.Cu")
		(net "M_D_CPU1_SB_DQ<8>")
	)
	(segment
		(start 79.088996 -233.440478)
		(end 66.176144 -220.527626)
		(width 0.18288)
		(layer "In11.Cu")
		(net "M_D_CPU1_SB_DQ<8>")
	)
	(segment
		(start 87.488014 -234.645708)
		(end 87.473282 -234.654344)
		(width 0.088646)
		(layer "In11.Cu")
		(net "M_D_CPU1_SB_DQ<8>")
	)
	(segment
		(start 84.38642 -234.7214)
		(end 83.988402 -234.7214)
		(width 0.088646)
		(layer "In11.Cu")
		(net "M_D_CPU1_SB_DQ<8>")
	)
	(segment
		(start 91.162378 -237.093506)
		(end 91.151964 -237.08741)
		(width 0.088646)
		(layer "In11.Cu")
		(net "M_D_CPU1_SB_DQ<8>")
	)
	(segment
		(start 19.456146 -222.204026)
		(end 17.401794 -222.204026)
		(width 0.18288)
		(layer "In11.Cu")
		(net "M_D_CPU1_SB_DQ<8>")
	)
	(segment
		(start 50.218848 -217.40495)
		(end 49.903888 -217.40495)
		(width 0.18288)
		(layer "In11.Cu")
		(net "M_D_CPU1_SB_DQ<8>")
	)
	(segment
		(start 25.752806 -221.569026)
		(end 24.663146 -222.658686)
		(width 0.18288)
		(layer "In11.Cu")
		(net "M_D_CPU1_SB_DQ<8>")
	)
	(segment
		(start 34.474658 -217.240104)
		(end 34.281618 -217.047064)
		(width 0.18288)
		(layer "In11.Cu")
		(net "M_D_CPU1_SB_DQ<8>")
	)
	(segment
		(start 87.8713 -234.650788)
		(end 87.86241 -234.645708)
		(width 0.088646)
		(layer "In11.Cu")
		(net "M_D_CPU1_SB_DQ<8>")
	)
	(segment
		(start 33.558226 -216.311226)
		(end 32.577278 -217.292174)
		(width 0.18288)
		(layer "In11.Cu")
		(net "M_D_CPU1_SB_DQ<8>")
	)
	(segment
		(start 43.134026 -217.352626)
		(end 42.168826 -216.387426)
		(width 0.18288)
		(layer "In11.Cu")
		(net "M_D_CPU1_SB_DQ<8>")
	)
	(segment
		(start 52.020216 -216.565226)
		(end 51.897026 -216.442036)
		(width 0.18288)
		(layer "In11.Cu")
		(net "M_D_CPU1_SB_DQ<8>")
	)
	(segment
		(start 40.340026 -216.387426)
		(end 40.060626 -216.666826)
		(width 0.18288)
		(layer "In11.Cu")
		(net "M_D_CPU1_SB_DQ<8>")
	)
	(segment
		(start 35.175698 -216.311226)
		(end 34.982658 -216.504266)
		(width 0.18288)
		(layer "In11.Cu")
		(net "M_D_CPU1_SB_DQ<8>")
	)
	(segment
		(start 96.805496 -237.096046)
		(end 96.790764 -237.08741)
		(width 0.088646)
		(layer "In11.Cu")
		(net "M_D_CPU1_SB_DQ<8>")
	)
	(segment
		(start 50.411888 -216.635076)
		(end 50.411888 -217.21191)
		(width 0.18288)
		(layer "In11.Cu")
		(net "M_D_CPU1_SB_DQ<8>")
	)
	(segment
		(start 95.865696 -237.096046)
		(end 95.850964 -237.08741)
		(width 0.088646)
		(layer "In11.Cu")
		(net "M_D_CPU1_SB_DQ<8>")
	)
	(segment
		(start 93.046296 -237.096046)
		(end 93.031564 -237.08741)
		(width 0.088646)
		(layer "In11.Cu")
		(net "M_D_CPU1_SB_DQ<8>")
	)
	(segment
		(start 26.979626 -221.213426)
		(end 26.624026 -221.569026)
		(width 0.18288)
		(layer "In11.Cu")
		(net "M_D_CPU1_SB_DQ<8>")
	)
	(segment
		(start 92.101924 -237.093506)
		(end 92.09151 -237.08741)
		(width 0.088646)
		(layer "In11.Cu")
		(net "M_D_CPU1_SB_DQ<8>")
	)
	(segment
		(start 23.298404 -223.078548)
		(end 21.87956 -223.078548)
		(width 0.18288)
		(layer "In11.Cu")
		(net "M_D_CPU1_SB_DQ<8>")
	)
	(segment
		(start 26.979626 -220.832426)
		(end 26.979626 -221.213426)
		(width 0.18288)
		(layer "In11.Cu")
		(net "M_D_CPU1_SB_DQ<8>")
	)
	(segment
		(start 44.229782 -217.098626)
		(end 43.975782 -217.352626)
		(width 0.18288)
		(layer "In11.Cu")
		(net "M_D_CPU1_SB_DQ<8>")
	)
	(segment
		(start 48.544734 -216.402666)
		(end 47.655226 -217.292174)
		(width 0.18288)
		(layer "In11.Cu")
		(net "M_D_CPU1_SB_DQ<8>")
	)
	(segment
		(start 90.226896 -237.096046)
		(end 90.212164 -237.08741)
		(width 0.088646)
		(layer "In11.Cu")
		(net "M_D_CPU1_SB_DQ<8>")
	)
	(segment
		(start 34.088578 -216.311226)
		(end 33.558226 -216.311226)
		(width 0.18288)
		(layer "In11.Cu")
		(net "M_D_CPU1_SB_DQ<8>")
	)
	(segment
		(start 62.942216 -219.647516)
		(end 62.373002 -219.647516)
		(width 0.18288)
		(layer "In11.Cu")
		(net "M_D_CPU1_SB_DQ<8>")
	)
	(segment
		(start 32.577278 -217.292174)
		(end 31.297626 -217.292174)
		(width 0.18288)
		(layer "In11.Cu")
		(net "M_D_CPU1_SB_DQ<8>")
	)
	(segment
		(start 59.874912 -217.149426)
		(end 59.592972 -217.149426)
		(width 0.18288)
		(layer "In11.Cu")
		(net "M_D_CPU1_SB_DQ<8>")
	)
	(segment
		(start 94.925896 -237.096046)
		(end 94.911164 -237.08741)
		(width 0.088646)
		(layer "In11.Cu")
		(net "M_D_CPU1_SB_DQ<8>")
	)
	(segment
		(start 66.176144 -220.527626)
		(end 63.822326 -220.527626)
		(width 0.18288)
		(layer "In11.Cu")
		(net "M_D_CPU1_SB_DQ<8>")
	)
	(segment
		(start 34.281618 -217.047064)
		(end 34.281618 -216.504266)
		(width 0.18288)
		(layer "In11.Cu")
		(net "M_D_CPU1_SB_DQ<8>")
	)
	(segment
		(start 88.347296 -235.46816)
		(end 88.332564 -235.459524)
		(width 0.088646)
		(layer "In11.Cu")
		(net "M_D_CPU1_SB_DQ<8>")
	)
	(segment
		(start 57.956704 -216.94394)
		(end 57.763664 -217.13698)
		(width 0.18288)
		(layer "In11.Cu")
		(net "M_D_CPU1_SB_DQ<8>")
	)
	(segment
		(start 89.281254 -235.464604)
		(end 89.272364 -235.459524)
		(width 0.088646)
		(layer "In11.Cu")
		(net "M_D_CPU1_SB_DQ<8>")
	)
	(segment
		(start 49.710848 -216.635076)
		(end 49.478438 -216.402666)
		(width 0.18288)
		(layer "In11.Cu")
		(net "M_D_CPU1_SB_DQ<8>")
	)
	(segment
		(start 62.373002 -219.647516)
		(end 59.874912 -217.149426)
		(width 0.18288)
		(layer "In11.Cu")
		(net "M_D_CPU1_SB_DQ<8>")
	)
	(segment
		(start 90.212164 -237.08741)
		(end 90.206068 -237.083854)
		(width 0.088646)
		(layer "In11.Cu")
		(net "M_D_CPU1_SB_DQ<8>")
	)
	(segment
		(start 55.789322 -216.260426)
		(end 55.484522 -216.565226)
		(width 0.18288)
		(layer "In11.Cu")
		(net "M_D_CPU1_SB_DQ<8>")
	)
	(segment
		(start 86.548214 -234.645708)
		(end 86.533482 -234.654344)
		(width 0.088646)
		(layer "In11.Cu")
		(net "M_D_CPU1_SB_DQ<8>")
	)
	(segment
		(start 21.194268 -222.393256)
		(end 19.645376 -222.393256)
		(width 0.18288)
		(layer "In11.Cu")
		(net "M_D_CPU1_SB_DQ<8>")
	)
	(segment
		(start 30.815026 -217.774774)
		(end 30.815026 -218.495626)
		(width 0.18288)
		(layer "In11.Cu")
		(net "M_D_CPU1_SB_DQ<8>")
	)
	(segment
		(start 34.789618 -217.240104)
		(end 34.474658 -217.240104)
		(width 0.18288)
		(layer "In11.Cu")
		(net "M_D_CPU1_SB_DQ<8>")
	)
	(segment
		(start 57.763664 -217.13698)
		(end 57.448704 -217.13698)
		(width 0.18288)
		(layer "In11.Cu")
		(net "M_D_CPU1_SB_DQ<8>")
	)
	(segment
		(start 82.70748 -233.440478)
		(end 82.37347 -233.440478)
		(width 0.088646)
		(layer "In11.Cu")
		(net "M_D_CPU1_SB_DQ<8>")
	)
	(segment
		(start 23.718266 -222.658686)
		(end 23.298404 -223.078548)
		(width 0.18288)
		(layer "In11.Cu")
		(net "M_D_CPU1_SB_DQ<8>")
	)
	(segment
		(start 43.975782 -217.352626)
		(end 43.134026 -217.352626)
		(width 0.18288)
		(layer "In11.Cu")
		(net "M_D_CPU1_SB_DQ<8>")
	)
	(segment
		(start 57.255664 -216.94394)
		(end 57.255664 -216.453466)
		(width 0.18288)
		(layer "In11.Cu")
		(net "M_D_CPU1_SB_DQ<8>")
	)
	(segment
		(start 50.604928 -216.442036)
		(end 50.411888 -216.635076)
		(width 0.18288)
		(layer "In11.Cu")
		(net "M_D_CPU1_SB_DQ<8>")
	)
	(segment
		(start 57.062624 -216.260426)
		(end 55.789322 -216.260426)
		(width 0.18288)
		(layer "In11.Cu")
		(net "M_D_CPU1_SB_DQ<8>")
	)
	(segment
		(start 45.867574 -217.292174)
		(end 45.674026 -217.098626)
		(width 0.18288)
		(layer "In11.Cu")
		(net "M_D_CPU1_SB_DQ<8>")
	)
	(segment
		(start 34.982658 -216.504266)
		(end 34.982658 -217.047064)
		(width 0.18288)
		(layer "In11.Cu")
		(net "M_D_CPU1_SB_DQ<8>")
	)
	(segment
		(start 58.703972 -216.260426)
		(end 58.149744 -216.260426)
		(width 0.18288)
		(layer "In11.Cu")
		(net "M_D_CPU1_SB_DQ<8>")
	)
	(segment
		(start 85.608414 -234.645708)
		(end 85.593682 -234.654344)
		(width 0.088646)
		(layer "In11.Cu")
		(net "M_D_CPU1_SB_DQ<8>")
	)
	(segment
		(start 34.982658 -217.047064)
		(end 34.789618 -217.240104)
		(width 0.18288)
		(layer "In11.Cu")
		(net "M_D_CPU1_SB_DQ<8>")
	)
	(segment
		(start 47.655226 -217.292174)
		(end 45.867574 -217.292174)
		(width 0.18288)
		(layer "In11.Cu")
		(net "M_D_CPU1_SB_DQ<8>")
	)
	(segment
		(start 57.448704 -217.13698)
		(end 57.255664 -216.94394)
		(width 0.18288)
		(layer "In11.Cu")
		(net "M_D_CPU1_SB_DQ<8>")
	)
	(segment
		(start 55.484522 -216.565226)
		(end 52.020216 -216.565226)
		(width 0.18288)
		(layer "In11.Cu")
		(net "M_D_CPU1_SB_DQ<8>")
	)
	(segment
		(start 30.815026 -218.495626)
		(end 30.116526 -219.194126)
		(width 0.18288)
		(layer "In11.Cu")
		(net "M_D_CPU1_SB_DQ<8>")
	)
	(segment
		(start 58.149744 -216.260426)
		(end 57.956704 -216.453466)
		(width 0.18288)
		(layer "In11.Cu")
		(net "M_D_CPU1_SB_DQ<8>")
	)
	(segment
		(start 26.624026 -221.569026)
		(end 25.752806 -221.569026)
		(width 0.18288)
		(layer "In11.Cu")
		(net "M_D_CPU1_SB_DQ<8>")
	)
	(segment
		(start 24.663146 -222.658686)
		(end 23.718266 -222.658686)
		(width 0.18288)
		(layer "In11.Cu")
		(net "M_D_CPU1_SB_DQ<8>")
	)
	(segment
		(start 40.060626 -216.666826)
		(end 37.034216 -216.666826)
		(width 0.18288)
		(layer "In11.Cu")
		(net "M_D_CPU1_SB_DQ<8>")
	)
	(segment
		(start 27.906726 -219.905326)
		(end 26.979626 -220.832426)
		(width 0.18288)
		(layer "In11.Cu")
		(net "M_D_CPU1_SB_DQ<8>")
	)
	(segment
		(start 35.66287 -216.442036)
		(end 35.53206 -216.311226)
		(width 0.18288)
		(layer "In11.Cu")
		(net "M_D_CPU1_SB_DQ<8>")
	)
	(segment
		(start 28.783026 -219.905326)
		(end 27.906726 -219.905326)
		(width 0.18288)
		(layer "In11.Cu")
		(net "M_D_CPU1_SB_DQ<8>")
	)
	(segment
		(start 17.401794 -222.204026)
		(end 16.789146 -222.816674)
		(width 0.18288)
		(layer "In11.Cu")
		(net "M_D_CPU1_SB_DQ<8>")
	)
	(segment
		(start 88.332564 -235.459524)
		(end 88.326468 -235.455968)
		(width 0.088646)
		(layer "In11.Cu")
		(net "M_D_CPU1_SB_DQ<8>")
	)
	(segment
		(start 49.710848 -217.21191)
		(end 49.710848 -216.635076)
		(width 0.18288)
		(layer "In11.Cu")
		(net "M_D_CPU1_SB_DQ<8>")
	)
	(segment
		(start 31.297626 -217.292174)
		(end 30.815026 -217.774774)
		(width 0.18288)
		(layer "In11.Cu")
		(net "M_D_CPU1_SB_DQ<8>")
	)
	(segment
		(start 36.809426 -216.442036)
		(end 35.66287 -216.442036)
		(width 0.18288)
		(layer "In11.Cu")
		(net "M_D_CPU1_SB_DQ<8>")
	)
	(segment
		(start 19.645376 -222.393256)
		(end 19.456146 -222.204026)
		(width 0.18288)
		(layer "In11.Cu")
		(net "M_D_CPU1_SB_DQ<8>")
	)
	(segment
		(start 98.373946 -237.042198)
		(end 98.295714 -237.08741)
		(width 0.088646)
		(layer "In11.Cu")
		(net "M_D_CPU1_SB_DQ<8>")
	)
	(arc
		(start 98.295714 -237.08741)
		(mid 98.019155 -237.163153)
		(end 97.740978 -237.093506)
		(width 0.088646)
		(layer "In11.Cu")
		(net "M_D_CPU1_SB_DQ<8>")
	)
	(arc
		(start 89.459816 -235.783882)
		(mid 89.412137 -235.600982)
		(end 89.281254 -235.464604)
		(width 0.088646)
		(layer "In11.Cu")
		(net "M_D_CPU1_SB_DQ<8>")
	)
	(arc
		(start 95.476568 -237.08741)
		(mid 95.202369 -237.163245)
		(end 94.925896 -237.096046)
		(width 0.088646)
		(layer "In11.Cu")
		(net "M_D_CPU1_SB_DQ<8>")
	)
	(arc
		(start 86.92261 -234.645708)
		(mid 86.735412 -234.595565)
		(end 86.548214 -234.645708)
		(width 0.088646)
		(layer "In11.Cu")
		(net "M_D_CPU1_SB_DQ<8>")
	)
	(arc
		(start 88.897968 -235.459524)
		(mid 88.623769 -235.535359)
		(end 88.347296 -235.46816)
		(width 0.088646)
		(layer "In11.Cu")
		(net "M_D_CPU1_SB_DQ<8>")
	)
	(arc
		(start 95.850964 -237.08741)
		(mid 95.663766 -237.037233)
		(end 95.476568 -237.08741)
		(width 0.088646)
		(layer "In11.Cu")
		(net "M_D_CPU1_SB_DQ<8>")
	)
	(arc
		(start 92.09151 -237.08741)
		(mid 91.904312 -237.037233)
		(end 91.717114 -237.08741)
		(width 0.088646)
		(layer "In11.Cu")
		(net "M_D_CPU1_SB_DQ<8>")
	)
	(arc
		(start 90.777568 -237.08741)
		(mid 90.503369 -237.163245)
		(end 90.226896 -237.096046)
		(width 0.088646)
		(layer "In11.Cu")
		(net "M_D_CPU1_SB_DQ<8>")
	)
	(arc
		(start 96.790764 -237.08741)
		(mid 96.603566 -237.037233)
		(end 96.416368 -237.08741)
		(width 0.088646)
		(layer "In11.Cu")
		(net "M_D_CPU1_SB_DQ<8>")
	)
	(arc
		(start 91.151964 -237.08741)
		(mid 90.964766 -237.037233)
		(end 90.777568 -237.08741)
		(width 0.088646)
		(layer "In11.Cu")
		(net "M_D_CPU1_SB_DQ<8>")
	)
	(arc
		(start 91.717114 -237.08741)
		(mid 91.440555 -237.163153)
		(end 91.162378 -237.093506)
		(width 0.088646)
		(layer "In11.Cu")
		(net "M_D_CPU1_SB_DQ<8>")
	)
	(arc
		(start 89.272364 -235.459524)
		(mid 89.085166 -235.409381)
		(end 88.897968 -235.459524)
		(width 0.088646)
		(layer "In11.Cu")
		(net "M_D_CPU1_SB_DQ<8>")
	)
	(arc
		(start 97.356168 -237.08741)
		(mid 97.081969 -237.163245)
		(end 96.805496 -237.096046)
		(width 0.088646)
		(layer "In11.Cu")
		(net "M_D_CPU1_SB_DQ<8>")
	)
	(arc
		(start 87.473282 -234.654344)
		(mid 87.196807 -234.721664)
		(end 86.92261 -234.645708)
		(width 0.088646)
		(layer "In11.Cu")
		(net "M_D_CPU1_SB_DQ<8>")
	)
	(arc
		(start 97.730564 -237.08741)
		(mid 97.543366 -237.037233)
		(end 97.356168 -237.08741)
		(width 0.088646)
		(layer "In11.Cu")
		(net "M_D_CPU1_SB_DQ<8>")
	)
	(arc
		(start 85.593682 -234.654344)
		(mid 85.317207 -234.721664)
		(end 85.04301 -234.645708)
		(width 0.088646)
		(layer "In11.Cu")
		(net "M_D_CPU1_SB_DQ<8>")
	)
	(arc
		(start 86.533482 -234.654344)
		(mid 86.257007 -234.721664)
		(end 85.98281 -234.645708)
		(width 0.088646)
		(layer "In11.Cu")
		(net "M_D_CPU1_SB_DQ<8>")
	)
	(arc
		(start 84.668614 -234.645708)
		(mid 84.549983 -234.697228)
		(end 84.422742 -234.720384)
		(width 0.088646)
		(layer "In11.Cu")
		(net "M_D_CPU1_SB_DQ<8>")
	)
	(arc
		(start 93.031564 -237.08741)
		(mid 92.844366 -237.037233)
		(end 92.657168 -237.08741)
		(width 0.088646)
		(layer "In11.Cu")
		(net "M_D_CPU1_SB_DQ<8>")
	)
	(arc
		(start 85.04301 -234.645708)
		(mid 84.855812 -234.595565)
		(end 84.668614 -234.645708)
		(width 0.088646)
		(layer "In11.Cu")
		(net "M_D_CPU1_SB_DQ<8>")
	)
	(arc
		(start 93.971364 -237.08741)
		(mid 93.784166 -237.037233)
		(end 93.596968 -237.08741)
		(width 0.088646)
		(layer "In11.Cu")
		(net "M_D_CPU1_SB_DQ<8>")
	)
	(arc
		(start 96.416368 -237.08741)
		(mid 96.142169 -237.163245)
		(end 95.865696 -237.096046)
		(width 0.088646)
		(layer "In11.Cu")
		(net "M_D_CPU1_SB_DQ<8>")
	)
	(arc
		(start 88.326468 -235.455968)
		(mid 88.123881 -235.249617)
		(end 88.049862 -234.970066)
		(width 0.088646)
		(layer "In11.Cu")
		(net "M_D_CPU1_SB_DQ<8>")
	)
	(arc
		(start 94.911164 -237.08741)
		(mid 94.723966 -237.037233)
		(end 94.536768 -237.08741)
		(width 0.088646)
		(layer "In11.Cu")
		(net "M_D_CPU1_SB_DQ<8>")
	)
	(arc
		(start 90.206068 -237.083854)
		(mid 90.003481 -236.877503)
		(end 89.929462 -236.597952)
		(width 0.088646)
		(layer "In11.Cu")
		(net "M_D_CPU1_SB_DQ<8>")
	)
	(arc
		(start 84.422742 -234.720384)
		(mid 84.404589 -234.721187)
		(end 84.38642 -234.7214)
		(width 0.088646)
		(layer "In11.Cu")
		(net "M_D_CPU1_SB_DQ<8>")
	)
	(arc
		(start 98.952812 -236.597952)
		(mid 98.677919 -236.83902)
		(end 98.373946 -237.042198)
		(width 0.088646)
		(layer "In11.Cu")
		(net "M_D_CPU1_SB_DQ<8>")
	)
	(arc
		(start 89.929462 -236.597952)
		(mid 89.881783 -236.415052)
		(end 89.7509 -236.278674)
		(width 0.088646)
		(layer "In11.Cu")
		(net "M_D_CPU1_SB_DQ<8>")
	)
	(arc
		(start 85.98281 -234.645708)
		(mid 85.795612 -234.595565)
		(end 85.608414 -234.645708)
		(width 0.088646)
		(layer "In11.Cu")
		(net "M_D_CPU1_SB_DQ<8>")
	)
	(arc
		(start 89.74201 -236.273594)
		(mid 89.540728 -236.076107)
		(end 89.459816 -235.80598)
		(width 0.088646)
		(layer "In11.Cu")
		(net "M_D_CPU1_SB_DQ<8>")
	)
	(arc
		(start 93.596968 -237.08741)
		(mid 93.322769 -237.163245)
		(end 93.046296 -237.096046)
		(width 0.088646)
		(layer "In11.Cu")
		(net "M_D_CPU1_SB_DQ<8>")
	)
	(arc
		(start 92.657168 -237.08741)
		(mid 92.380355 -237.16328)
		(end 92.101924 -237.093506)
		(width 0.088646)
		(layer "In11.Cu")
		(net "M_D_CPU1_SB_DQ<8>")
	)
	(arc
		(start 94.536768 -237.08741)
		(mid 94.254066 -237.163186)
		(end 93.971364 -237.08741)
		(width 0.088646)
		(layer "In11.Cu")
		(net "M_D_CPU1_SB_DQ<8>")
	)
	(arc
		(start 87.86241 -234.645708)
		(mid 87.675212 -234.595565)
		(end 87.488014 -234.645708)
		(width 0.088646)
		(layer "In11.Cu")
		(net "M_D_CPU1_SB_DQ<8>")
	)
	(arc
		(start 88.049862 -234.970066)
		(mid 88.002183 -234.787166)
		(end 87.8713 -234.650788)
		(width 0.088646)
		(layer "In11.Cu")
		(net "M_D_CPU1_SB_DQ<8>")
	)
	(segment
		(start 18.760694 -223.874076)
		(end 18.968212 -223.666558)
		(width 0.20066)
		(layer "F.Cu")
		(net "M_D_CPU1_SB_DQ<7>")
	)
	(segment
		(start 18.102326 -223.66224)
		(end 18.314162 -223.874076)
		(width 0.20066)
		(layer "F.Cu")
		(net "M_D_CPU1_SB_DQ<7>")
	)
	(segment
		(start 18.968212 -223.666558)
		(end 19.784314 -223.666558)
		(width 0.20066)
		(layer "F.Cu")
		(net "M_D_CPU1_SB_DQ<7>")
	)
	(segment
		(start 17.707102 -223.66224)
		(end 18.102326 -223.66224)
		(width 0.20066)
		(layer "F.Cu")
		(net "M_D_CPU1_SB_DQ<7>")
	)
	(segment
		(start 14.812264 -224.0915)
		(end 16.885158 -224.0915)
		(width 0.1016)
		(layer "F.Cu")
		(net "M_D_CPU1_SB_DQ<7>")
	)
	(segment
		(start 14.560042 -224.105724)
		(end 14.574266 -224.0915)
		(width 0.101854)
		(layer "F.Cu")
		(net "M_D_CPU1_SB_DQ<7>")
	)
	(segment
		(start 16.885158 -224.0915)
		(end 17.42948 -224.0915)
		(width 0.20066)
		(layer "F.Cu")
		(net "M_D_CPU1_SB_DQ<7>")
	)
	(segment
		(start 14.063726 -223.792542)
		(end 14.063726 -223.96323)
		(width 0.20066)
		(layer "F.Cu")
		(net "M_D_CPU1_SB_DQ<7>")
	)
	(segment
		(start 14.574266 -224.0915)
		(end 14.812264 -224.0915)
		(width 0.101854)
		(layer "F.Cu")
		(net "M_D_CPU1_SB_DQ<7>")
	)
	(segment
		(start 18.314162 -223.874076)
		(end 18.760694 -223.874076)
		(width 0.20066)
		(layer "F.Cu")
		(net "M_D_CPU1_SB_DQ<7>")
	)
	(segment
		(start 99.892612 -238.76127)
		(end 99.892612 -238.225584)
		(width 0.20066)
		(layer "F.Cu")
		(net "M_D_CPU1_SB_DQ<7>")
	)
	(segment
		(start 20.889214 -223.666558)
		(end 19.784314 -223.666558)
		(width 0.20066)
		(layer "F.Cu")
		(net "M_D_CPU1_SB_DQ<7>")
	)
	(segment
		(start 17.578578 -223.790764)
		(end 17.707102 -223.66224)
		(width 0.20066)
		(layer "F.Cu")
		(net "M_D_CPU1_SB_DQ<7>")
	)
	(segment
		(start 14.063726 -223.96323)
		(end 14.20622 -224.105724)
		(width 0.20066)
		(layer "F.Cu")
		(net "M_D_CPU1_SB_DQ<7>")
	)
	(segment
		(start 17.42948 -224.0915)
		(end 17.578578 -223.942402)
		(width 0.20066)
		(layer "F.Cu")
		(net "M_D_CPU1_SB_DQ<7>")
	)
	(segment
		(start 17.578578 -223.942402)
		(end 17.578578 -223.790764)
		(width 0.20066)
		(layer "F.Cu")
		(net "M_D_CPU1_SB_DQ<7>")
	)
	(segment
		(start 14.20622 -224.105724)
		(end 14.560042 -224.105724)
		(width 0.20066)
		(layer "F.Cu")
		(net "M_D_CPU1_SB_DQ<7>")
	)
	(segment
		(start 99.892866 -238.761524)
		(end 99.892612 -238.76127)
		(width 0.20066)
		(layer "F.Cu")
		(net "M_D_CPU1_SB_DQ<7>")
	)
	(segment
		(start 13.937742 -223.666558)
		(end 14.063726 -223.792542)
		(width 0.20066)
		(layer "F.Cu")
		(net "M_D_CPU1_SB_DQ<7>")
	)
	(segment
		(start 12.240514 -223.666558)
		(end 13.937742 -223.666558)
		(width 0.20066)
		(layer "F.Cu")
		(net "M_D_CPU1_SB_DQ<7>")
	)
	(segment
		(start 95.865696 -237.72749)
		(end 95.850964 -237.736126)
		(width 0.088646)
		(layer "In11.Cu")
		(net "M_D_CPU1_SB_DQ<7>")
	)
	(segment
		(start 44.985686 -219.842588)
		(end 44.720256 -219.577158)
		(width 0.18288)
		(layer "In11.Cu")
		(net "M_D_CPU1_SB_DQ<7>")
	)
	(segment
		(start 53.406802 -218.99245)
		(end 50.254408 -218.99245)
		(width 0.18288)
		(layer "In11.Cu")
		(net "M_D_CPU1_SB_DQ<7>")
	)
	(segment
		(start 34.864294 -218.689936)
		(end 33.465516 -218.689936)
		(width 0.18288)
		(layer "In11.Cu")
		(net "M_D_CPU1_SB_DQ<7>")
	)
	(segment
		(start 65.68313 -221.721426)
		(end 63.682626 -221.721426)
		(width 0.18288)
		(layer "In11.Cu")
		(net "M_D_CPU1_SB_DQ<7>")
	)
	(segment
		(start 47.546006 -219.842588)
		(end 44.985686 -219.842588)
		(width 0.18288)
		(layer "In11.Cu")
		(net "M_D_CPU1_SB_DQ<7>")
	)
	(segment
		(start 90.226896 -237.727236)
		(end 90.212164 -237.735872)
		(width 0.088646)
		(layer "In11.Cu")
		(net "M_D_CPU1_SB_DQ<7>")
	)
	(segment
		(start 98.295714 -237.736126)
		(end 98.2853 -237.73003)
		(width 0.088646)
		(layer "In11.Cu")
		(net "M_D_CPU1_SB_DQ<7>")
	)
	(segment
		(start 99.892612 -238.225584)
		(end 99.579938 -238.225584)
		(width 0.088646)
		(layer "In11.Cu")
		(net "M_D_CPU1_SB_DQ<7>")
	)
	(segment
		(start 59.156346 -219.966286)
		(end 57.718706 -219.966286)
		(width 0.18288)
		(layer "In11.Cu")
		(net "M_D_CPU1_SB_DQ<7>")
	)
	(segment
		(start 28.496514 -221.721426)
		(end 27.970226 -221.721426)
		(width 0.18288)
		(layer "In11.Cu")
		(net "M_D_CPU1_SB_DQ<7>")
	)
	(segment
		(start 32.821626 -219.333826)
		(end 32.821626 -219.479368)
		(width 0.18288)
		(layer "In11.Cu")
		(net "M_D_CPU1_SB_DQ<7>")
	)
	(segment
		(start 33.465516 -218.689936)
		(end 32.821626 -219.333826)
		(width 0.18288)
		(layer "In11.Cu")
		(net "M_D_CPU1_SB_DQ<7>")
	)
	(segment
		(start 99.579938 -238.225584)
		(end 99.514406 -238.160052)
		(width 0.088646)
		(layer "In11.Cu")
		(net "M_D_CPU1_SB_DQ<7>")
	)
	(segment
		(start 35.166808 -218.99245)
		(end 34.864294 -218.689936)
		(width 0.18288)
		(layer "In11.Cu")
		(net "M_D_CPU1_SB_DQ<7>")
	)
	(segment
		(start 91.717114 -237.735872)
		(end 91.7067 -237.729776)
		(width 0.088646)
		(layer "In11.Cu")
		(net "M_D_CPU1_SB_DQ<7>")
	)
	(segment
		(start 49.662842 -218.400884)
		(end 48.98771 -218.400884)
		(width 0.18288)
		(layer "In11.Cu")
		(net "M_D_CPU1_SB_DQ<7>")
	)
	(segment
		(start 26.439368 -223.252284)
		(end 25.557226 -223.252284)
		(width 0.18288)
		(layer "In11.Cu")
		(net "M_D_CPU1_SB_DQ<7>")
	)
	(segment
		(start 94.925896 -237.72749)
		(end 94.911164 -237.736126)
		(width 0.088646)
		(layer "In11.Cu")
		(net "M_D_CPU1_SB_DQ<7>")
	)
	(segment
		(start 25.557226 -223.252284)
		(end 24.581104 -224.228406)
		(width 0.18288)
		(layer "In11.Cu")
		(net "M_D_CPU1_SB_DQ<7>")
	)
	(segment
		(start 89.37244 -236.92485)
		(end 89.367614 -236.922056)
		(width 0.088646)
		(layer "In11.Cu")
		(net "M_D_CPU1_SB_DQ<7>")
	)
	(segment
		(start 82.99831 -235.458762)
		(end 82.99831 -234.63377)
		(width 0.088646)
		(layer "In11.Cu")
		(net "M_D_CPU1_SB_DQ<7>")
	)
	(segment
		(start 40.213026 -218.648026)
		(end 39.868602 -218.99245)
		(width 0.18288)
		(layer "In11.Cu")
		(net "M_D_CPU1_SB_DQ<7>")
	)
	(segment
		(start 50.254408 -218.99245)
		(end 49.662842 -218.400884)
		(width 0.18288)
		(layer "In11.Cu")
		(net "M_D_CPU1_SB_DQ<7>")
	)
	(segment
		(start 89.367614 -236.922056)
		(end 89.35974 -236.917484)
		(width 0.088646)
		(layer "In11.Cu")
		(net "M_D_CPU1_SB_DQ<7>")
	)
	(segment
		(start 44.456604 -218.648026)
		(end 40.213026 -218.648026)
		(width 0.18288)
		(layer "In11.Cu")
		(net "M_D_CPU1_SB_DQ<7>")
	)
	(segment
		(start 21.477224 -224.254568)
		(end 20.889214 -223.666558)
		(width 0.18288)
		(layer "In11.Cu")
		(net "M_D_CPU1_SB_DQ<7>")
	)
	(segment
		(start 60.720986 -219.750386)
		(end 59.372246 -219.750386)
		(width 0.18288)
		(layer "In11.Cu")
		(net "M_D_CPU1_SB_DQ<7>")
	)
	(segment
		(start 78.204822 -234.243118)
		(end 65.68313 -221.721426)
		(width 0.18288)
		(layer "In11.Cu")
		(net "M_D_CPU1_SB_DQ<7>")
	)
	(segment
		(start 89.37371 -236.925612)
		(end 89.37244 -236.92485)
		(width 0.088646)
		(layer "In11.Cu")
		(net "M_D_CPU1_SB_DQ<7>")
	)
	(segment
		(start 53.624226 -218.775026)
		(end 53.406802 -218.99245)
		(width 0.18288)
		(layer "In11.Cu")
		(net "M_D_CPU1_SB_DQ<7>")
	)
	(segment
		(start 93.596968 -237.736126)
		(end 93.596968 -237.735872)
		(width 0.088646)
		(layer "In11.Cu")
		(net "M_D_CPU1_SB_DQ<7>")
	)
	(segment
		(start 93.046296 -237.727236)
		(end 93.031564 -237.735872)
		(width 0.088646)
		(layer "In11.Cu")
		(net "M_D_CPU1_SB_DQ<7>")
	)
	(segment
		(start 44.720256 -219.577158)
		(end 44.720256 -218.911678)
		(width 0.18288)
		(layer "In11.Cu")
		(net "M_D_CPU1_SB_DQ<7>")
	)
	(segment
		(start 62.793626 -220.832426)
		(end 61.803026 -220.832426)
		(width 0.18288)
		(layer "In11.Cu")
		(net "M_D_CPU1_SB_DQ<7>")
	)
	(segment
		(start 93.986096 -237.72749)
		(end 93.971364 -237.736126)
		(width 0.088646)
		(layer "In11.Cu")
		(net "M_D_CPU1_SB_DQ<7>")
	)
	(segment
		(start 32.458406 -219.842588)
		(end 30.839664 -219.842588)
		(width 0.18288)
		(layer "In11.Cu")
		(net "M_D_CPU1_SB_DQ<7>")
	)
	(segment
		(start 98.680524 -237.73003)
		(end 98.67011 -237.736126)
		(width 0.088646)
		(layer "In11.Cu")
		(net "M_D_CPU1_SB_DQ<7>")
	)
	(segment
		(start 82.99831 -234.63377)
		(end 82.607658 -234.243118)
		(width 0.088646)
		(layer "In11.Cu")
		(net "M_D_CPU1_SB_DQ<7>")
	)
	(segment
		(start 89.837768 -237.735872)
		(end 89.828878 -237.730792)
		(width 0.088646)
		(layer "In11.Cu")
		(net "M_D_CPU1_SB_DQ<7>")
	)
	(segment
		(start 48.98771 -218.400884)
		(end 47.546006 -219.842588)
		(width 0.18288)
		(layer "In11.Cu")
		(net "M_D_CPU1_SB_DQ<7>")
	)
	(segment
		(start 24.581104 -224.228406)
		(end 24.572722 -224.228406)
		(width 0.18288)
		(layer "In11.Cu")
		(net "M_D_CPU1_SB_DQ<7>")
	)
	(segment
		(start 44.720256 -218.911678)
		(end 44.456604 -218.648026)
		(width 0.18288)
		(layer "In11.Cu")
		(net "M_D_CPU1_SB_DQ<7>")
	)
	(segment
		(start 59.372246 -219.750386)
		(end 59.156346 -219.966286)
		(width 0.18288)
		(layer "In11.Cu")
		(net "M_D_CPU1_SB_DQ<7>")
	)
	(segment
		(start 56.527446 -218.775026)
		(end 53.624226 -218.775026)
		(width 0.18288)
		(layer "In11.Cu")
		(net "M_D_CPU1_SB_DQ<7>")
	)
	(segment
		(start 57.718706 -219.966286)
		(end 56.527446 -218.775026)
		(width 0.18288)
		(layer "In11.Cu")
		(net "M_D_CPU1_SB_DQ<7>")
	)
	(segment
		(start 30.839664 -219.842588)
		(end 29.900626 -220.781626)
		(width 0.18288)
		(layer "In11.Cu")
		(net "M_D_CPU1_SB_DQ<7>")
	)
	(segment
		(start 82.37347 -234.243118)
		(end 78.204822 -234.243118)
		(width 0.18288)
		(layer "In11.Cu")
		(net "M_D_CPU1_SB_DQ<7>")
	)
	(segment
		(start 29.900626 -220.781626)
		(end 29.436314 -220.781626)
		(width 0.18288)
		(layer "In11.Cu")
		(net "M_D_CPU1_SB_DQ<7>")
	)
	(segment
		(start 32.821626 -219.479368)
		(end 32.458406 -219.842588)
		(width 0.18288)
		(layer "In11.Cu")
		(net "M_D_CPU1_SB_DQ<7>")
	)
	(segment
		(start 84.386166 -236.15904)
		(end 83.698588 -236.15904)
		(width 0.088646)
		(layer "In11.Cu")
		(net "M_D_CPU1_SB_DQ<7>")
	)
	(segment
		(start 27.970226 -221.721426)
		(end 26.439368 -223.252284)
		(width 0.18288)
		(layer "In11.Cu")
		(net "M_D_CPU1_SB_DQ<7>")
	)
	(segment
		(start 39.868602 -218.99245)
		(end 35.166808 -218.99245)
		(width 0.18288)
		(layer "In11.Cu")
		(net "M_D_CPU1_SB_DQ<7>")
	)
	(segment
		(start 82.607658 -234.243118)
		(end 82.37347 -234.243118)
		(width 0.088646)
		(layer "In11.Cu")
		(net "M_D_CPU1_SB_DQ<7>")
	)
	(segment
		(start 24.572722 -224.228406)
		(end 24.54656 -224.254568)
		(width 0.18288)
		(layer "In11.Cu")
		(net "M_D_CPU1_SB_DQ<7>")
	)
	(segment
		(start 61.803026 -220.832426)
		(end 60.720986 -219.750386)
		(width 0.18288)
		(layer "In11.Cu")
		(net "M_D_CPU1_SB_DQ<7>")
	)
	(segment
		(start 63.682626 -221.721426)
		(end 62.793626 -220.832426)
		(width 0.18288)
		(layer "In11.Cu")
		(net "M_D_CPU1_SB_DQ<7>")
	)
	(segment
		(start 96.805496 -237.72749)
		(end 96.790764 -237.736126)
		(width 0.088646)
		(layer "In11.Cu")
		(net "M_D_CPU1_SB_DQ<7>")
	)
	(segment
		(start 29.436314 -220.781626)
		(end 28.496514 -221.721426)
		(width 0.18288)
		(layer "In11.Cu")
		(net "M_D_CPU1_SB_DQ<7>")
	)
	(segment
		(start 89.180416 -236.597952)
		(end 89.180416 -236.57941)
		(width 0.088646)
		(layer "In11.Cu")
		(net "M_D_CPU1_SB_DQ<7>")
	)
	(segment
		(start 92.101924 -237.729776)
		(end 92.09151 -237.735872)
		(width 0.088646)
		(layer "In11.Cu")
		(net "M_D_CPU1_SB_DQ<7>")
	)
	(segment
		(start 24.54656 -224.254568)
		(end 21.477224 -224.254568)
		(width 0.18288)
		(layer "In11.Cu")
		(net "M_D_CPU1_SB_DQ<7>")
	)
	(segment
		(start 83.698588 -236.15904)
		(end 82.99831 -235.458762)
		(width 0.088646)
		(layer "In11.Cu")
		(net "M_D_CPU1_SB_DQ<7>")
	)
	(arc
		(start 93.031564 -237.735872)
		(mid 92.844366 -237.786015)
		(end 92.657168 -237.735872)
		(width 0.088646)
		(layer "In11.Cu")
		(net "M_D_CPU1_SB_DQ<7>")
	)
	(arc
		(start 89.35974 -236.917484)
		(mid 89.228328 -236.781152)
		(end 89.180416 -236.597952)
		(width 0.088646)
		(layer "In11.Cu")
		(net "M_D_CPU1_SB_DQ<7>")
	)
	(arc
		(start 86.452964 -236.10824)
		(mid 86.265766 -236.158383)
		(end 86.078568 -236.10824)
		(width 0.088646)
		(layer "In11.Cu")
		(net "M_D_CPU1_SB_DQ<7>")
	)
	(arc
		(start 94.536768 -237.736126)
		(mid 94.262569 -237.660291)
		(end 93.986096 -237.72749)
		(width 0.088646)
		(layer "In11.Cu")
		(net "M_D_CPU1_SB_DQ<7>")
	)
	(arc
		(start 97.730564 -237.736126)
		(mid 97.543366 -237.786269)
		(end 97.356168 -237.736126)
		(width 0.088646)
		(layer "In11.Cu")
		(net "M_D_CPU1_SB_DQ<7>")
	)
	(arc
		(start 92.09151 -237.735872)
		(mid 91.904312 -237.786015)
		(end 91.717114 -237.735872)
		(width 0.088646)
		(layer "In11.Cu")
		(net "M_D_CPU1_SB_DQ<7>")
	)
	(arc
		(start 91.151964 -237.735872)
		(mid 90.964766 -237.786015)
		(end 90.777568 -237.735872)
		(width 0.088646)
		(layer "In11.Cu")
		(net "M_D_CPU1_SB_DQ<7>")
	)
	(arc
		(start 90.777568 -237.735872)
		(mid 90.503339 -237.659947)
		(end 90.226896 -237.727236)
		(width 0.088646)
		(layer "In11.Cu")
		(net "M_D_CPU1_SB_DQ<7>")
	)
	(arc
		(start 98.67011 -237.736126)
		(mid 98.482912 -237.786269)
		(end 98.295714 -237.736126)
		(width 0.088646)
		(layer "In11.Cu")
		(net "M_D_CPU1_SB_DQ<7>")
	)
	(arc
		(start 99.514406 -238.160052)
		(mid 99.425318 -237.915067)
		(end 99.235768 -237.736126)
		(width 0.088646)
		(layer "In11.Cu")
		(net "M_D_CPU1_SB_DQ<7>")
	)
	(arc
		(start 87.018368 -236.10824)
		(mid 86.735666 -236.032498)
		(end 86.452964 -236.10824)
		(width 0.088646)
		(layer "In11.Cu")
		(net "M_D_CPU1_SB_DQ<7>")
	)
	(arc
		(start 90.212164 -237.735872)
		(mid 90.024966 -237.786015)
		(end 89.837768 -237.735872)
		(width 0.088646)
		(layer "In11.Cu")
		(net "M_D_CPU1_SB_DQ<7>")
	)
	(arc
		(start 88.332564 -236.10824)
		(mid 88.145366 -236.158383)
		(end 87.958168 -236.10824)
		(width 0.088646)
		(layer "In11.Cu")
		(net "M_D_CPU1_SB_DQ<7>")
	)
	(arc
		(start 87.958168 -236.10824)
		(mid 87.675466 -236.032498)
		(end 87.392764 -236.10824)
		(width 0.088646)
		(layer "In11.Cu")
		(net "M_D_CPU1_SB_DQ<7>")
	)
	(arc
		(start 84.573364 -236.10824)
		(mid 84.483108 -236.145962)
		(end 84.386166 -236.15904)
		(width 0.088646)
		(layer "In11.Cu")
		(net "M_D_CPU1_SB_DQ<7>")
	)
	(arc
		(start 98.2853 -237.73003)
		(mid 98.007122 -237.660307)
		(end 97.730564 -237.736126)
		(width 0.088646)
		(layer "In11.Cu")
		(net "M_D_CPU1_SB_DQ<7>")
	)
	(arc
		(start 85.513164 -236.10824)
		(mid 85.325966 -236.158383)
		(end 85.138768 -236.10824)
		(width 0.088646)
		(layer "In11.Cu")
		(net "M_D_CPU1_SB_DQ<7>")
	)
	(arc
		(start 97.356168 -237.736126)
		(mid 97.081969 -237.660291)
		(end 96.805496 -237.72749)
		(width 0.088646)
		(layer "In11.Cu")
		(net "M_D_CPU1_SB_DQ<7>")
	)
	(arc
		(start 88.897968 -236.10824)
		(mid 88.615266 -236.032498)
		(end 88.332564 -236.10824)
		(width 0.088646)
		(layer "In11.Cu")
		(net "M_D_CPU1_SB_DQ<7>")
	)
	(arc
		(start 94.911164 -237.736126)
		(mid 94.723966 -237.786269)
		(end 94.536768 -237.736126)
		(width 0.088646)
		(layer "In11.Cu")
		(net "M_D_CPU1_SB_DQ<7>")
	)
	(arc
		(start 99.235768 -237.736126)
		(mid 98.958955 -237.660256)
		(end 98.680524 -237.73003)
		(width 0.088646)
		(layer "In11.Cu")
		(net "M_D_CPU1_SB_DQ<7>")
	)
	(arc
		(start 95.476568 -237.736126)
		(mid 95.202369 -237.660291)
		(end 94.925896 -237.72749)
		(width 0.088646)
		(layer "In11.Cu")
		(net "M_D_CPU1_SB_DQ<7>")
	)
	(arc
		(start 95.850964 -237.736126)
		(mid 95.663766 -237.786269)
		(end 95.476568 -237.736126)
		(width 0.088646)
		(layer "In11.Cu")
		(net "M_D_CPU1_SB_DQ<7>")
	)
	(arc
		(start 89.828878 -237.730792)
		(mid 89.697964 -237.594432)
		(end 89.650316 -237.411514)
		(width 0.088646)
		(layer "In11.Cu")
		(net "M_D_CPU1_SB_DQ<7>")
	)
	(arc
		(start 85.138768 -236.10824)
		(mid 84.856066 -236.032498)
		(end 84.573364 -236.10824)
		(width 0.088646)
		(layer "In11.Cu")
		(net "M_D_CPU1_SB_DQ<7>")
	)
	(arc
		(start 89.180416 -236.57941)
		(mid 89.100254 -236.307221)
		(end 88.897968 -236.10824)
		(width 0.088646)
		(layer "In11.Cu")
		(net "M_D_CPU1_SB_DQ<7>")
	)
	(arc
		(start 89.650316 -237.411514)
		(mid 89.576325 -237.131948)
		(end 89.37371 -236.925612)
		(width 0.088646)
		(layer "In11.Cu")
		(net "M_D_CPU1_SB_DQ<7>")
	)
	(arc
		(start 96.416368 -237.736126)
		(mid 96.142169 -237.660291)
		(end 95.865696 -237.72749)
		(width 0.088646)
		(layer "In11.Cu")
		(net "M_D_CPU1_SB_DQ<7>")
	)
	(arc
		(start 93.971364 -237.736126)
		(mid 93.784166 -237.786269)
		(end 93.596968 -237.736126)
		(width 0.088646)
		(layer "In11.Cu")
		(net "M_D_CPU1_SB_DQ<7>")
	)
	(arc
		(start 91.7067 -237.729776)
		(mid 91.428522 -237.660084)
		(end 91.151964 -237.735872)
		(width 0.088646)
		(layer "In11.Cu")
		(net "M_D_CPU1_SB_DQ<7>")
	)
	(arc
		(start 86.078568 -236.10824)
		(mid 85.795866 -236.032498)
		(end 85.513164 -236.10824)
		(width 0.088646)
		(layer "In11.Cu")
		(net "M_D_CPU1_SB_DQ<7>")
	)
	(arc
		(start 92.657168 -237.735872)
		(mid 92.380355 -237.660036)
		(end 92.101924 -237.729776)
		(width 0.088646)
		(layer "In11.Cu")
		(net "M_D_CPU1_SB_DQ<7>")
	)
	(arc
		(start 96.790764 -237.736126)
		(mid 96.603566 -237.786269)
		(end 96.416368 -237.736126)
		(width 0.088646)
		(layer "In11.Cu")
		(net "M_D_CPU1_SB_DQ<7>")
	)
	(arc
		(start 87.392764 -236.10824)
		(mid 87.205566 -236.158383)
		(end 87.018368 -236.10824)
		(width 0.088646)
		(layer "In11.Cu")
		(net "M_D_CPU1_SB_DQ<7>")
	)
	(arc
		(start 93.596968 -237.735872)
		(mid 93.322739 -237.659947)
		(end 93.046296 -237.727236)
		(width 0.088646)
		(layer "In11.Cu")
		(net "M_D_CPU1_SB_DQ<7>")
	)
	(segment
		(start 13.82268 -224.931478)
		(end 14.560042 -224.931478)
		(width 0.20066)
		(layer "F.Cu")
		(net "M_D_CPU1_SB_DQ<6>")
	)
	(segment
		(start 17.66189 -225.41103)
		(end 17.829276 -225.578416)
		(width 0.20066)
		(layer "F.Cu")
		(net "M_D_CPU1_SB_DQ<6>")
	)
	(segment
		(start 17.829276 -225.578416)
		(end 18.257774 -225.578416)
		(width 0.20066)
		(layer "F.Cu")
		(net "M_D_CPU1_SB_DQ<6>")
	)
	(segment
		(start 17.518126 -224.941638)
		(end 17.66189 -225.085402)
		(width 0.20066)
		(layer "F.Cu")
		(net "M_D_CPU1_SB_DQ<6>")
	)
	(segment
		(start 13.387578 -225.36658)
		(end 13.82268 -224.931478)
		(width 0.20066)
		(layer "F.Cu")
		(net "M_D_CPU1_SB_DQ<6>")
	)
	(segment
		(start 12.240514 -225.36658)
		(end 13.387578 -225.36658)
		(width 0.20066)
		(layer "F.Cu")
		(net "M_D_CPU1_SB_DQ<6>")
	)
	(segment
		(start 18.46961 -225.36658)
		(end 19.784314 -225.36658)
		(width 0.20066)
		(layer "F.Cu")
		(net "M_D_CPU1_SB_DQ<6>")
	)
	(segment
		(start 100.362512 -239.57534)
		(end 100.362766 -239.575086)
		(width 0.20066)
		(layer "F.Cu")
		(net "M_D_CPU1_SB_DQ<6>")
	)
	(segment
		(start 18.257774 -225.578416)
		(end 18.46961 -225.36658)
		(width 0.20066)
		(layer "F.Cu")
		(net "M_D_CPU1_SB_DQ<6>")
	)
	(segment
		(start 14.560042 -224.931478)
		(end 14.570202 -224.941638)
		(width 0.101854)
		(layer "F.Cu")
		(net "M_D_CPU1_SB_DQ<6>")
	)
	(segment
		(start 16.885158 -224.941638)
		(end 17.518126 -224.941638)
		(width 0.20066)
		(layer "F.Cu")
		(net "M_D_CPU1_SB_DQ<6>")
	)
	(segment
		(start 17.66189 -225.085402)
		(end 17.66189 -225.41103)
		(width 0.20066)
		(layer "F.Cu")
		(net "M_D_CPU1_SB_DQ<6>")
	)
	(segment
		(start 14.825218 -224.941638)
		(end 16.885158 -224.941638)
		(width 0.1016)
		(layer "F.Cu")
		(net "M_D_CPU1_SB_DQ<6>")
	)
	(segment
		(start 100.362766 -239.575086)
		(end 100.362766 -239.0394)
		(width 0.20066)
		(layer "F.Cu")
		(net "M_D_CPU1_SB_DQ<6>")
	)
	(segment
		(start 20.889214 -225.36658)
		(end 19.784314 -225.36658)
		(width 0.20066)
		(layer "F.Cu")
		(net "M_D_CPU1_SB_DQ<6>")
	)
	(segment
		(start 14.570202 -224.941638)
		(end 14.825218 -224.941638)
		(width 0.101854)
		(layer "F.Cu")
		(net "M_D_CPU1_SB_DQ<6>")
	)
	(segment
		(start 49.433988 -220.579188)
		(end 48.543464 -220.579188)
		(width 0.18288)
		(layer "In11.Cu")
		(net "M_D_CPU1_SB_DQ<6>")
	)
	(segment
		(start 29.875226 -222.585026)
		(end 29.340302 -222.585026)
		(width 0.18288)
		(layer "In11.Cu")
		(net "M_D_CPU1_SB_DQ<6>")
	)
	(segment
		(start 93.126814 -238.549942)
		(end 93.112082 -238.541306)
		(width 0.088646)
		(layer "In11.Cu")
		(net "M_D_CPU1_SB_DQ<6>")
	)
	(segment
		(start 42.804334 -221.569026)
		(end 41.864534 -220.629226)
		(width 0.18288)
		(layer "In11.Cu")
		(net "M_D_CPU1_SB_DQ<6>")
	)
	(segment
		(start 77.600556 -235.263944)
		(end 66.42735 -224.090738)
		(width 0.18288)
		(layer "In11.Cu")
		(net "M_D_CPU1_SB_DQ<6>")
	)
	(segment
		(start 47.580042 -221.54261)
		(end 45.851826 -221.54261)
		(width 0.18288)
		(layer "In11.Cu")
		(net "M_D_CPU1_SB_DQ<6>")
	)
	(segment
		(start 60.059316 -221.450916)
		(end 59.426348 -221.450916)
		(width 0.18288)
		(layer "In11.Cu")
		(net "M_D_CPU1_SB_DQ<6>")
	)
	(segment
		(start 54.10581 -220.883226)
		(end 53.91277 -220.690186)
		(width 0.18288)
		(layer "In11.Cu")
		(net "M_D_CPU1_SB_DQ<6>")
	)
	(segment
		(start 34.498788 -220.579188)
		(end 33.421828 -220.579188)
		(width 0.18288)
		(layer "In11.Cu")
		(net "M_D_CPU1_SB_DQ<6>")
	)
	(segment
		(start 53.40477 -220.277436)
		(end 53.21173 -220.470476)
		(width 0.18288)
		(layer "In11.Cu")
		(net "M_D_CPU1_SB_DQ<6>")
	)
	(segment
		(start 87.492586 -236.92485)
		(end 87.488268 -236.92231)
		(width 0.088646)
		(layer "In11.Cu")
		(net "M_D_CPU1_SB_DQ<6>")
	)
	(segment
		(start 82.60334 -235.61929)
		(end 82.60334 -235.35259)
		(width 0.088646)
		(layer "In11.Cu")
		(net "M_D_CPU1_SB_DQ<6>")
	)
	(segment
		(start 23.423626 -225.312732)
		(end 23.108666 -225.312732)
		(width 0.18288)
		(layer "In11.Cu")
		(net "M_D_CPU1_SB_DQ<6>")
	)
	(segment
		(start 53.91277 -220.470476)
		(end 53.71973 -220.277436)
		(width 0.18288)
		(layer "In11.Cu")
		(net "M_D_CPU1_SB_DQ<6>")
	)
	(segment
		(start 28.138882 -223.448626)
		(end 26.462482 -225.125026)
		(width 0.18288)
		(layer "In11.Cu")
		(net "M_D_CPU1_SB_DQ<6>")
	)
	(segment
		(start 88.347296 -237.727236)
		(end 88.332564 -237.735872)
		(width 0.088646)
		(layer "In11.Cu")
		(net "M_D_CPU1_SB_DQ<6>")
	)
	(segment
		(start 82.37347 -235.263944)
		(end 77.600556 -235.263944)
		(width 0.18288)
		(layer "In11.Cu")
		(net "M_D_CPU1_SB_DQ<6>")
	)
	(segment
		(start 64.851026 -223.296226)
		(end 63.606426 -223.296226)
		(width 0.18288)
		(layer "In11.Cu")
		(net "M_D_CPU1_SB_DQ<6>")
	)
	(segment
		(start 61.091826 -222.483426)
		(end 60.059316 -221.450916)
		(width 0.18288)
		(layer "In11.Cu")
		(net "M_D_CPU1_SB_DQ<6>")
	)
	(segment
		(start 40.496236 -220.694758)
		(end 34.614358 -220.694758)
		(width 0.18288)
		(layer "In11.Cu")
		(net "M_D_CPU1_SB_DQ<6>")
	)
	(segment
		(start 22.722586 -225.981006)
		(end 21.50364 -225.981006)
		(width 0.18288)
		(layer "In11.Cu")
		(net "M_D_CPU1_SB_DQ<6>")
	)
	(segment
		(start 63.606426 -223.296226)
		(end 62.793626 -222.483426)
		(width 0.18288)
		(layer "In11.Cu")
		(net "M_D_CPU1_SB_DQ<6>")
	)
	(segment
		(start 59.426348 -221.450916)
		(end 59.105038 -221.772226)
		(width 0.18288)
		(layer "In11.Cu")
		(net "M_D_CPU1_SB_DQ<6>")
	)
	(segment
		(start 23.616666 -225.787966)
		(end 23.616666 -225.505772)
		(width 0.18288)
		(layer "In11.Cu")
		(net "M_D_CPU1_SB_DQ<6>")
	)
	(segment
		(start 55.166006 -220.883226)
		(end 54.10581 -220.883226)
		(width 0.18288)
		(layer "In11.Cu")
		(net "M_D_CPU1_SB_DQ<6>")
	)
	(segment
		(start 53.71973 -220.277436)
		(end 53.40477 -220.277436)
		(width 0.18288)
		(layer "In11.Cu")
		(net "M_D_CPU1_SB_DQ<6>")
	)
	(segment
		(start 30.764226 -221.696026)
		(end 29.875226 -222.585026)
		(width 0.18288)
		(layer "In11.Cu")
		(net "M_D_CPU1_SB_DQ<6>")
	)
	(segment
		(start 99.393248 -238.637826)
		(end 98.98634 -238.637826)
		(width 0.088646)
		(layer "In11.Cu")
		(net "M_D_CPU1_SB_DQ<6>")
	)
	(segment
		(start 45.267626 -221.391226)
		(end 44.581826 -221.391226)
		(width 0.18288)
		(layer "In11.Cu")
		(net "M_D_CPU1_SB_DQ<6>")
	)
	(segment
		(start 48.543464 -220.579188)
		(end 47.580042 -221.54261)
		(width 0.18288)
		(layer "In11.Cu")
		(net "M_D_CPU1_SB_DQ<6>")
	)
	(segment
		(start 28.476702 -223.448626)
		(end 28.138882 -223.448626)
		(width 0.18288)
		(layer "In11.Cu")
		(net "M_D_CPU1_SB_DQ<6>")
	)
	(segment
		(start 21.50364 -225.981006)
		(end 20.889214 -225.36658)
		(width 0.18288)
		(layer "In11.Cu")
		(net "M_D_CPU1_SB_DQ<6>")
	)
	(segment
		(start 91.247468 -238.549942)
		(end 91.237054 -238.543846)
		(width 0.088646)
		(layer "In11.Cu")
		(net "M_D_CPU1_SB_DQ<6>")
	)
	(segment
		(start 82.514694 -235.263944)
		(end 82.37347 -235.263944)
		(width 0.088646)
		(layer "In11.Cu")
		(net "M_D_CPU1_SB_DQ<6>")
	)
	(segment
		(start 92.187014 -238.549942)
		(end 92.1766 -238.543846)
		(width 0.088646)
		(layer "In11.Cu")
		(net "M_D_CPU1_SB_DQ<6>")
	)
	(segment
		(start 96.886014 -238.549942)
		(end 96.871282 -238.541306)
		(width 0.088646)
		(layer "In11.Cu")
		(net "M_D_CPU1_SB_DQ<6>")
	)
	(segment
		(start 49.547272 -220.692472)
		(end 49.433988 -220.579188)
		(width 0.18288)
		(layer "In11.Cu")
		(net "M_D_CPU1_SB_DQ<6>")
	)
	(segment
		(start 25.785826 -225.125026)
		(end 24.929846 -225.981006)
		(width 0.18288)
		(layer "In11.Cu")
		(net "M_D_CPU1_SB_DQ<6>")
	)
	(segment
		(start 33.421828 -220.579188)
		(end 32.458406 -221.54261)
		(width 0.18288)
		(layer "In11.Cu")
		(net "M_D_CPU1_SB_DQ<6>")
	)
	(segment
		(start 62.793626 -222.483426)
		(end 61.091826 -222.483426)
		(width 0.18288)
		(layer "In11.Cu")
		(net "M_D_CPU1_SB_DQ<6>")
	)
	(segment
		(start 53.91277 -220.690186)
		(end 53.91277 -220.470476)
		(width 0.18288)
		(layer "In11.Cu")
		(net "M_D_CPU1_SB_DQ<6>")
	)
	(segment
		(start 22.915626 -225.505772)
		(end 22.915626 -225.787966)
		(width 0.18288)
		(layer "In11.Cu")
		(net "M_D_CPU1_SB_DQ<6>")
	)
	(segment
		(start 29.340302 -222.585026)
		(end 28.476702 -223.448626)
		(width 0.18288)
		(layer "In11.Cu")
		(net "M_D_CPU1_SB_DQ<6>")
	)
	(segment
		(start 89.367614 -238.549942)
		(end 89.358724 -238.544862)
		(width 0.088646)
		(layer "In11.Cu")
		(net "M_D_CPU1_SB_DQ<6>")
	)
	(segment
		(start 23.108666 -225.312732)
		(end 22.915626 -225.505772)
		(width 0.18288)
		(layer "In11.Cu")
		(net "M_D_CPU1_SB_DQ<6>")
	)
	(segment
		(start 23.616666 -225.505772)
		(end 23.423626 -225.312732)
		(width 0.18288)
		(layer "In11.Cu")
		(net "M_D_CPU1_SB_DQ<6>")
	)
	(segment
		(start 41.864534 -220.629226)
		(end 40.721026 -220.629226)
		(width 0.18288)
		(layer "In11.Cu")
		(net "M_D_CPU1_SB_DQ<6>")
	)
	(segment
		(start 34.614358 -220.694758)
		(end 34.498788 -220.579188)
		(width 0.18288)
		(layer "In11.Cu")
		(net "M_D_CPU1_SB_DQ<6>")
	)
	(segment
		(start 44.581826 -221.391226)
		(end 43.870626 -221.569026)
		(width 0.18288)
		(layer "In11.Cu")
		(net "M_D_CPU1_SB_DQ<6>")
	)
	(segment
		(start 43.870626 -221.569026)
		(end 42.804334 -221.569026)
		(width 0.18288)
		(layer "In11.Cu")
		(net "M_D_CPU1_SB_DQ<6>")
	)
	(segment
		(start 40.721026 -220.629226)
		(end 40.496236 -220.694758)
		(width 0.18288)
		(layer "In11.Cu")
		(net "M_D_CPU1_SB_DQ<6>")
	)
	(segment
		(start 31.125922 -221.54261)
		(end 31.124144 -221.544388)
		(width 0.18288)
		(layer "In11.Cu")
		(net "M_D_CPU1_SB_DQ<6>")
	)
	(segment
		(start 97.826068 -238.549942)
		(end 97.815654 -238.543846)
		(width 0.088646)
		(layer "In11.Cu")
		(net "M_D_CPU1_SB_DQ<6>")
	)
	(segment
		(start 83.830414 -236.846364)
		(end 82.60334 -235.61929)
		(width 0.088646)
		(layer "In11.Cu")
		(net "M_D_CPU1_SB_DQ<6>")
	)
	(segment
		(start 94.066614 -238.549942)
		(end 94.051882 -238.541306)
		(width 0.088646)
		(layer "In11.Cu")
		(net "M_D_CPU1_SB_DQ<6>")
	)
	(segment
		(start 45.851826 -221.54261)
		(end 45.267626 -221.391226)
		(width 0.18288)
		(layer "In11.Cu")
		(net "M_D_CPU1_SB_DQ<6>")
	)
	(segment
		(start 31.124144 -221.544388)
		(end 30.764226 -221.696026)
		(width 0.18288)
		(layer "In11.Cu")
		(net "M_D_CPU1_SB_DQ<6>")
	)
	(segment
		(start 85.057996 -236.913674)
		(end 85.043264 -236.92231)
		(width 0.088646)
		(layer "In11.Cu")
		(net "M_D_CPU1_SB_DQ<6>")
	)
	(segment
		(start 52.049426 -220.883226)
		(end 51.858672 -220.692472)
		(width 0.18288)
		(layer "In11.Cu")
		(net "M_D_CPU1_SB_DQ<6>")
	)
	(segment
		(start 23.809706 -225.981006)
		(end 23.616666 -225.787966)
		(width 0.18288)
		(layer "In11.Cu")
		(net "M_D_CPU1_SB_DQ<6>")
	)
	(segment
		(start 22.915626 -225.787966)
		(end 22.722586 -225.981006)
		(width 0.18288)
		(layer "In11.Cu")
		(net "M_D_CPU1_SB_DQ<6>")
	)
	(segment
		(start 65.645538 -224.090738)
		(end 64.851026 -223.296226)
		(width 0.18288)
		(layer "In11.Cu")
		(net "M_D_CPU1_SB_DQ<6>")
	)
	(segment
		(start 53.21173 -220.690186)
		(end 53.01869 -220.883226)
		(width 0.18288)
		(layer "In11.Cu")
		(net "M_D_CPU1_SB_DQ<6>")
	)
	(segment
		(start 59.105038 -221.772226)
		(end 56.055006 -221.772226)
		(width 0.18288)
		(layer "In11.Cu")
		(net "M_D_CPU1_SB_DQ<6>")
	)
	(segment
		(start 95.946214 -238.549942)
		(end 95.931482 -238.541306)
		(width 0.088646)
		(layer "In11.Cu")
		(net "M_D_CPU1_SB_DQ<6>")
	)
	(segment
		(start 87.958168 -237.735872)
		(end 87.949278 -237.730792)
		(width 0.088646)
		(layer "In11.Cu")
		(net "M_D_CPU1_SB_DQ<6>")
	)
	(segment
		(start 82.60334 -235.35259)
		(end 82.514694 -235.263944)
		(width 0.088646)
		(layer "In11.Cu")
		(net "M_D_CPU1_SB_DQ<6>")
	)
	(segment
		(start 56.055006 -221.772226)
		(end 55.166006 -220.883226)
		(width 0.18288)
		(layer "In11.Cu")
		(net "M_D_CPU1_SB_DQ<6>")
	)
	(segment
		(start 24.929846 -225.981006)
		(end 23.809706 -225.981006)
		(width 0.18288)
		(layer "In11.Cu")
		(net "M_D_CPU1_SB_DQ<6>")
	)
	(segment
		(start 90.307414 -238.549942)
		(end 90.292682 -238.541306)
		(width 0.088646)
		(layer "In11.Cu")
		(net "M_D_CPU1_SB_DQ<6>")
	)
	(segment
		(start 32.458406 -221.54261)
		(end 31.125922 -221.54261)
		(width 0.18288)
		(layer "In11.Cu")
		(net "M_D_CPU1_SB_DQ<6>")
	)
	(segment
		(start 89.180162 -238.225584)
		(end 89.180162 -238.203486)
		(width 0.088646)
		(layer "In11.Cu")
		(net "M_D_CPU1_SB_DQ<6>")
	)
	(segment
		(start 53.21173 -220.470476)
		(end 53.21173 -220.690186)
		(width 0.18288)
		(layer "In11.Cu")
		(net "M_D_CPU1_SB_DQ<6>")
	)
	(segment
		(start 26.462482 -225.125026)
		(end 25.785826 -225.125026)
		(width 0.18288)
		(layer "In11.Cu")
		(net "M_D_CPU1_SB_DQ<6>")
	)
	(segment
		(start 66.42735 -224.090738)
		(end 65.645538 -224.090738)
		(width 0.18288)
		(layer "In11.Cu")
		(net "M_D_CPU1_SB_DQ<6>")
	)
	(segment
		(start 87.494364 -236.925866)
		(end 87.492586 -236.92485)
		(width 0.088646)
		(layer "In11.Cu")
		(net "M_D_CPU1_SB_DQ<6>")
	)
	(segment
		(start 84.385912 -236.846364)
		(end 83.830414 -236.846364)
		(width 0.088646)
		(layer "In11.Cu")
		(net "M_D_CPU1_SB_DQ<6>")
	)
	(segment
		(start 53.01869 -220.883226)
		(end 52.049426 -220.883226)
		(width 0.18288)
		(layer "In11.Cu")
		(net "M_D_CPU1_SB_DQ<6>")
	)
	(segment
		(start 51.858672 -220.692472)
		(end 49.547272 -220.692472)
		(width 0.18288)
		(layer "In11.Cu")
		(net "M_D_CPU1_SB_DQ<6>")
	)
	(segment
		(start 86.937596 -236.913674)
		(end 86.922864 -236.92231)
		(width 0.088646)
		(layer "In11.Cu")
		(net "M_D_CPU1_SB_DQ<6>")
	)
	(arc
		(start 97.26041 -238.549942)
		(mid 97.073212 -238.600085)
		(end 96.886014 -238.549942)
		(width 0.088646)
		(layer "In11.Cu")
		(net "M_D_CPU1_SB_DQ<6>")
	)
	(arc
		(start 89.74201 -238.549942)
		(mid 89.554812 -238.600085)
		(end 89.367614 -238.549942)
		(width 0.088646)
		(layer "In11.Cu")
		(net "M_D_CPU1_SB_DQ<6>")
	)
	(arc
		(start 86.548468 -236.92231)
		(mid 86.265766 -236.846534)
		(end 85.983064 -236.92231)
		(width 0.088646)
		(layer "In11.Cu")
		(net "M_D_CPU1_SB_DQ<6>")
	)
	(arc
		(start 93.50121 -238.549942)
		(mid 93.314012 -238.600085)
		(end 93.126814 -238.549942)
		(width 0.088646)
		(layer "In11.Cu")
		(net "M_D_CPU1_SB_DQ<6>")
	)
	(arc
		(start 95.38081 -238.549942)
		(mid 95.193612 -238.600085)
		(end 95.006414 -238.549942)
		(width 0.088646)
		(layer "In11.Cu")
		(net "M_D_CPU1_SB_DQ<6>")
	)
	(arc
		(start 85.983064 -236.92231)
		(mid 85.795866 -236.972453)
		(end 85.608668 -236.92231)
		(width 0.088646)
		(layer "In11.Cu")
		(net "M_D_CPU1_SB_DQ<6>")
	)
	(arc
		(start 87.770716 -237.411514)
		(mid 87.696737 -237.132155)
		(end 87.494364 -236.925866)
		(width 0.088646)
		(layer "In11.Cu")
		(net "M_D_CPU1_SB_DQ<6>")
	)
	(arc
		(start 84.668868 -236.92231)
		(mid 84.532396 -236.865687)
		(end 84.385912 -236.846364)
		(width 0.088646)
		(layer "In11.Cu")
		(net "M_D_CPU1_SB_DQ<6>")
	)
	(arc
		(start 89.358724 -238.544862)
		(mid 89.22781 -238.408502)
		(end 89.180162 -238.225584)
		(width 0.088646)
		(layer "In11.Cu")
		(net "M_D_CPU1_SB_DQ<6>")
	)
	(arc
		(start 87.488268 -236.92231)
		(mid 87.214069 -236.846475)
		(end 86.937596 -236.913674)
		(width 0.088646)
		(layer "In11.Cu")
		(net "M_D_CPU1_SB_DQ<6>")
	)
	(arc
		(start 86.922864 -236.92231)
		(mid 86.735666 -236.972453)
		(end 86.548468 -236.92231)
		(width 0.088646)
		(layer "In11.Cu")
		(net "M_D_CPU1_SB_DQ<6>")
	)
	(arc
		(start 94.44101 -238.549942)
		(mid 94.253812 -238.600085)
		(end 94.066614 -238.549942)
		(width 0.088646)
		(layer "In11.Cu")
		(net "M_D_CPU1_SB_DQ<6>")
	)
	(arc
		(start 97.815654 -238.543846)
		(mid 97.537222 -238.474)
		(end 97.26041 -238.549942)
		(width 0.088646)
		(layer "In11.Cu")
		(net "M_D_CPU1_SB_DQ<6>")
	)
	(arc
		(start 98.98634 -238.637826)
		(mid 98.837038 -238.608128)
		(end 98.710496 -238.523526)
		(width 0.088646)
		(layer "In11.Cu")
		(net "M_D_CPU1_SB_DQ<6>")
	)
	(arc
		(start 100.362766 -239.0394)
		(mid 99.917947 -238.742182)
		(end 99.393248 -238.637826)
		(width 0.088646)
		(layer "In11.Cu")
		(net "M_D_CPU1_SB_DQ<6>")
	)
	(arc
		(start 91.237054 -238.543846)
		(mid 90.958622 -238.474)
		(end 90.68181 -238.549942)
		(width 0.088646)
		(layer "In11.Cu")
		(net "M_D_CPU1_SB_DQ<6>")
	)
	(arc
		(start 96.32061 -238.549942)
		(mid 96.133412 -238.600085)
		(end 95.946214 -238.549942)
		(width 0.088646)
		(layer "In11.Cu")
		(net "M_D_CPU1_SB_DQ<6>")
	)
	(arc
		(start 89.180162 -238.203486)
		(mid 89.099251 -237.933358)
		(end 88.897968 -237.735872)
		(width 0.088646)
		(layer "In11.Cu")
		(net "M_D_CPU1_SB_DQ<6>")
	)
	(arc
		(start 85.043264 -236.92231)
		(mid 84.856066 -236.972453)
		(end 84.668868 -236.92231)
		(width 0.088646)
		(layer "In11.Cu")
		(net "M_D_CPU1_SB_DQ<6>")
	)
	(arc
		(start 98.710496 -238.523526)
		(mid 98.708968 -238.522006)
		(end 98.707448 -238.520478)
		(width 0.088646)
		(layer "In11.Cu")
		(net "M_D_CPU1_SB_DQ<6>")
	)
	(arc
		(start 85.608668 -236.92231)
		(mid 85.334469 -236.846475)
		(end 85.057996 -236.913674)
		(width 0.088646)
		(layer "In11.Cu")
		(net "M_D_CPU1_SB_DQ<6>")
	)
	(arc
		(start 88.897968 -237.735872)
		(mid 88.623739 -237.659947)
		(end 88.347296 -237.727236)
		(width 0.088646)
		(layer "In11.Cu")
		(net "M_D_CPU1_SB_DQ<6>")
	)
	(arc
		(start 95.006414 -238.549942)
		(mid 94.723712 -238.474166)
		(end 94.44101 -238.549942)
		(width 0.088646)
		(layer "In11.Cu")
		(net "M_D_CPU1_SB_DQ<6>")
	)
	(arc
		(start 98.200464 -238.549942)
		(mid 98.013266 -238.600085)
		(end 97.826068 -238.549942)
		(width 0.088646)
		(layer "In11.Cu")
		(net "M_D_CPU1_SB_DQ<6>")
	)
	(arc
		(start 88.332564 -237.735872)
		(mid 88.145366 -237.786015)
		(end 87.958168 -237.735872)
		(width 0.088646)
		(layer "In11.Cu")
		(net "M_D_CPU1_SB_DQ<6>")
	)
	(arc
		(start 92.1766 -238.543846)
		(mid 91.898422 -238.474123)
		(end 91.621864 -238.549942)
		(width 0.088646)
		(layer "In11.Cu")
		(net "M_D_CPU1_SB_DQ<6>")
	)
	(arc
		(start 93.112082 -238.541306)
		(mid 92.835607 -238.473986)
		(end 92.56141 -238.549942)
		(width 0.088646)
		(layer "In11.Cu")
		(net "M_D_CPU1_SB_DQ<6>")
	)
	(arc
		(start 94.051882 -238.541306)
		(mid 93.775407 -238.473986)
		(end 93.50121 -238.549942)
		(width 0.088646)
		(layer "In11.Cu")
		(net "M_D_CPU1_SB_DQ<6>")
	)
	(arc
		(start 87.949278 -237.730792)
		(mid 87.818364 -237.594432)
		(end 87.770716 -237.411514)
		(width 0.088646)
		(layer "In11.Cu")
		(net "M_D_CPU1_SB_DQ<6>")
	)
	(arc
		(start 92.56141 -238.549942)
		(mid 92.374212 -238.600085)
		(end 92.187014 -238.549942)
		(width 0.088646)
		(layer "In11.Cu")
		(net "M_D_CPU1_SB_DQ<6>")
	)
	(arc
		(start 90.68181 -238.549942)
		(mid 90.494612 -238.600085)
		(end 90.307414 -238.549942)
		(width 0.088646)
		(layer "In11.Cu")
		(net "M_D_CPU1_SB_DQ<6>")
	)
	(arc
		(start 98.707448 -238.520478)
		(mid 98.450449 -238.475031)
		(end 98.200464 -238.549942)
		(width 0.088646)
		(layer "In11.Cu")
		(net "M_D_CPU1_SB_DQ<6>")
	)
	(arc
		(start 90.292682 -238.541306)
		(mid 90.016207 -238.473986)
		(end 89.74201 -238.549942)
		(width 0.088646)
		(layer "In11.Cu")
		(net "M_D_CPU1_SB_DQ<6>")
	)
	(arc
		(start 95.931482 -238.541306)
		(mid 95.655007 -238.473986)
		(end 95.38081 -238.549942)
		(width 0.088646)
		(layer "In11.Cu")
		(net "M_D_CPU1_SB_DQ<6>")
	)
	(arc
		(start 91.621864 -238.549942)
		(mid 91.434666 -238.600085)
		(end 91.247468 -238.549942)
		(width 0.088646)
		(layer "In11.Cu")
		(net "M_D_CPU1_SB_DQ<6>")
	)
	(arc
		(start 96.871282 -238.541306)
		(mid 96.594807 -238.473986)
		(end 96.32061 -238.549942)
		(width 0.088646)
		(layer "In11.Cu")
		(net "M_D_CPU1_SB_DQ<6>")
	)
	(segment
		(start 9.686036 -224.728024)
		(end 10.19048 -224.728024)
		(width 0.20066)
		(layer "F.Cu")
		(net "M_D_CPU1_SB_DQ<5>")
	)
	(segment
		(start 10.507472 -224.082864)
		(end 11.11631 -224.082864)
		(width 0.20066)
		(layer "F.Cu")
		(net "M_D_CPU1_SB_DQ<5>")
	)
	(segment
		(start 16.789146 -224.516696)
		(end 15.684246 -224.516696)
		(width 0.20066)
		(layer "F.Cu")
		(net "M_D_CPU1_SB_DQ<5>")
	)
	(segment
		(start 14.04493 -224.516696)
		(end 15.684246 -224.516696)
		(width 0.20066)
		(layer "F.Cu")
		(net "M_D_CPU1_SB_DQ<5>")
	)
	(segment
		(start 10.344912 -224.573592)
		(end 10.344912 -224.245424)
		(width 0.20066)
		(layer "F.Cu")
		(net "M_D_CPU1_SB_DQ<5>")
	)
	(segment
		(start 11.11631 -224.082864)
		(end 11.1252 -224.091754)
		(width 0.1016)
		(layer "F.Cu")
		(net "M_D_CPU1_SB_DQ<5>")
	)
	(segment
		(start 10.344912 -224.245424)
		(end 10.507472 -224.082864)
		(width 0.20066)
		(layer "F.Cu")
		(net "M_D_CPU1_SB_DQ<5>")
	)
	(segment
		(start 9.474708 -224.516696)
		(end 9.686036 -224.728024)
		(width 0.20066)
		(layer "F.Cu")
		(net "M_D_CPU1_SB_DQ<5>")
	)
	(segment
		(start 98.952812 -238.76127)
		(end 98.952812 -238.225584)
		(width 0.20066)
		(layer "F.Cu")
		(net "M_D_CPU1_SB_DQ<5>")
	)
	(segment
		(start 10.19048 -224.728024)
		(end 10.344912 -224.573592)
		(width 0.20066)
		(layer "F.Cu")
		(net "M_D_CPU1_SB_DQ<5>")
	)
	(segment
		(start 13.619988 -224.091754)
		(end 14.04493 -224.516696)
		(width 0.20066)
		(layer "F.Cu")
		(net "M_D_CPU1_SB_DQ<5>")
	)
	(segment
		(start 13.441426 -224.091754)
		(end 13.619988 -224.091754)
		(width 0.20066)
		(layer "F.Cu")
		(net "M_D_CPU1_SB_DQ<5>")
	)
	(segment
		(start 11.1252 -224.091754)
		(end 13.110718 -224.091754)
		(width 0.1016)
		(layer "F.Cu")
		(net "M_D_CPU1_SB_DQ<5>")
	)
	(segment
		(start 8.140446 -224.516696)
		(end 9.474708 -224.516696)
		(width 0.20066)
		(layer "F.Cu")
		(net "M_D_CPU1_SB_DQ<5>")
	)
	(segment
		(start 98.953066 -238.761524)
		(end 98.952812 -238.76127)
		(width 0.20066)
		(layer "F.Cu")
		(net "M_D_CPU1_SB_DQ<5>")
	)
	(segment
		(start 13.110718 -224.091754)
		(end 13.441426 -224.091754)
		(width 0.101854)
		(layer "F.Cu")
		(net "M_D_CPU1_SB_DQ<5>")
	)
	(segment
		(start 30.056328 -221.391226)
		(end 29.60243 -221.391226)
		(width 0.18288)
		(layer "In11.Cu")
		(net "M_D_CPU1_SB_DQ<5>")
	)
	(segment
		(start 55.239666 -219.765626)
		(end 51.739038 -219.765626)
		(width 0.18288)
		(layer "In11.Cu")
		(net "M_D_CPU1_SB_DQ<5>")
	)
	(segment
		(start 42.930826 -220.121226)
		(end 41.305226 -220.121226)
		(width 0.18288)
		(layer "In11.Cu")
		(net "M_D_CPU1_SB_DQ<5>")
	)
	(segment
		(start 44.1706 -220.693488)
		(end 42.930826 -220.121226)
		(width 0.18288)
		(layer "In11.Cu")
		(net "M_D_CPU1_SB_DQ<5>")
	)
	(segment
		(start 26.553414 -223.880426)
		(end 25.785826 -223.880426)
		(width 0.18288)
		(layer "In11.Cu")
		(net "M_D_CPU1_SB_DQ<5>")
	)
	(segment
		(start 95.006414 -237.901226)
		(end 94.991682 -237.909862)
		(width 0.088646)
		(layer "In11.Cu")
		(net "M_D_CPU1_SB_DQ<5>")
	)
	(segment
		(start 64.370458 -222.356426)
		(end 63.504826 -222.356426)
		(width 0.18288)
		(layer "In11.Cu")
		(net "M_D_CPU1_SB_DQ<5>")
	)
	(segment
		(start 93.126814 -237.901226)
		(end 93.112082 -237.909862)
		(width 0.088646)
		(layer "In11.Cu")
		(net "M_D_CPU1_SB_DQ<5>")
	)
	(segment
		(start 62.615826 -221.467426)
		(end 60.888626 -221.467426)
		(width 0.18288)
		(layer "In11.Cu")
		(net "M_D_CPU1_SB_DQ<5>")
	)
	(segment
		(start 49.508664 -219.842334)
		(end 49.331372 -220.019626)
		(width 0.18288)
		(layer "In11.Cu")
		(net "M_D_CPU1_SB_DQ<5>")
	)
	(segment
		(start 82.808064 -235.537756)
		(end 82.808064 -234.955842)
		(width 0.088646)
		(layer "In11.Cu")
		(net "M_D_CPU1_SB_DQ<5>")
	)
	(segment
		(start 90.307414 -237.901226)
		(end 90.292682 -237.909862)
		(width 0.088646)
		(layer "In11.Cu")
		(net "M_D_CPU1_SB_DQ<5>")
	)
	(segment
		(start 82.37347 -234.755944)
		(end 77.898752 -234.755944)
		(width 0.18288)
		(layer "In11.Cu")
		(net "M_D_CPU1_SB_DQ<5>")
	)
	(segment
		(start 82.608166 -234.755944)
		(end 82.37347 -234.755944)
		(width 0.088646)
		(layer "In11.Cu")
		(net "M_D_CPU1_SB_DQ<5>")
	)
	(segment
		(start 98.210878 -237.907322)
		(end 98.200464 -237.901226)
		(width 0.088646)
		(layer "In11.Cu")
		(net "M_D_CPU1_SB_DQ<5>")
	)
	(segment
		(start 66.383916 -223.241108)
		(end 65.684908 -223.241108)
		(width 0.18288)
		(layer "In11.Cu")
		(net "M_D_CPU1_SB_DQ<5>")
	)
	(segment
		(start 19.524472 -225.463354)
		(end 17.735804 -225.463354)
		(width 0.18288)
		(layer "In11.Cu")
		(net "M_D_CPU1_SB_DQ<5>")
	)
	(segment
		(start 63.504826 -222.356426)
		(end 62.615826 -221.467426)
		(width 0.18288)
		(layer "In11.Cu")
		(net "M_D_CPU1_SB_DQ<5>")
	)
	(segment
		(start 51.739038 -219.765626)
		(end 51.592226 -219.842334)
		(width 0.18288)
		(layer "In11.Cu")
		(net "M_D_CPU1_SB_DQ<5>")
	)
	(segment
		(start 99.265486 -238.225584)
		(end 99.32289 -238.16818)
		(width 0.088646)
		(layer "In11.Cu")
		(net "M_D_CPU1_SB_DQ<5>")
	)
	(segment
		(start 65.054226 -222.610426)
		(end 64.370458 -222.356426)
		(width 0.18288)
		(layer "In11.Cu")
		(net "M_D_CPU1_SB_DQ<5>")
	)
	(segment
		(start 91.247468 -237.901226)
		(end 91.237054 -237.907322)
		(width 0.088646)
		(layer "In11.Cu")
		(net "M_D_CPU1_SB_DQ<5>")
	)
	(segment
		(start 94.066614 -237.901226)
		(end 94.051882 -237.909862)
		(width 0.088646)
		(layer "In11.Cu")
		(net "M_D_CPU1_SB_DQ<5>")
	)
	(segment
		(start 88.989662 -236.597952)
		(end 88.989662 -236.589316)
		(width 0.088646)
		(layer "In11.Cu")
		(net "M_D_CPU1_SB_DQ<5>")
	)
	(segment
		(start 55.976266 -220.502226)
		(end 55.239666 -219.765626)
		(width 0.18288)
		(layer "In11.Cu")
		(net "M_D_CPU1_SB_DQ<5>")
	)
	(segment
		(start 36.377626 -219.842334)
		(end 34.570924 -219.842334)
		(width 0.18288)
		(layer "In11.Cu")
		(net "M_D_CPU1_SB_DQ<5>")
	)
	(segment
		(start 48.353472 -220.019626)
		(end 47.67961 -220.693488)
		(width 0.18288)
		(layer "In11.Cu")
		(net "M_D_CPU1_SB_DQ<5>")
	)
	(segment
		(start 89.286588 -237.095538)
		(end 89.272364 -237.08741)
		(width 0.088646)
		(layer "In11.Cu")
		(net "M_D_CPU1_SB_DQ<5>")
	)
	(segment
		(start 32.46755 -220.690948)
		(end 31.593536 -220.690948)
		(width 0.18288)
		(layer "In11.Cu")
		(net "M_D_CPU1_SB_DQ<5>")
	)
	(segment
		(start 17.735804 -225.463354)
		(end 16.789146 -224.516696)
		(width 0.18288)
		(layer "In11.Cu")
		(net "M_D_CPU1_SB_DQ<5>")
	)
	(segment
		(start 31.593536 -220.690948)
		(end 30.056328 -221.391226)
		(width 0.18288)
		(layer "In11.Cu")
		(net "M_D_CPU1_SB_DQ<5>")
	)
	(segment
		(start 47.67961 -220.693488)
		(end 44.1706 -220.693488)
		(width 0.18288)
		(layer "In11.Cu")
		(net "M_D_CPU1_SB_DQ<5>")
	)
	(segment
		(start 58.455814 -220.502226)
		(end 55.976266 -220.502226)
		(width 0.18288)
		(layer "In11.Cu")
		(net "M_D_CPU1_SB_DQ<5>")
	)
	(segment
		(start 49.331372 -220.019626)
		(end 48.353472 -220.019626)
		(width 0.18288)
		(layer "In11.Cu")
		(net "M_D_CPU1_SB_DQ<5>")
	)
	(segment
		(start 99.1489 -237.906306)
		(end 99.14001 -237.901226)
		(width 0.088646)
		(layer "In11.Cu")
		(net "M_D_CPU1_SB_DQ<5>")
	)
	(segment
		(start 41.305226 -220.121226)
		(end 39.755826 -219.740226)
		(width 0.18288)
		(layer "In11.Cu")
		(net "M_D_CPU1_SB_DQ<5>")
	)
	(segment
		(start 84.386166 -236.349286)
		(end 83.619594 -236.349286)
		(width 0.088646)
		(layer "In11.Cu")
		(net "M_D_CPU1_SB_DQ<5>")
	)
	(segment
		(start 21.281644 -224.9424)
		(end 20.045426 -224.9424)
		(width 0.18288)
		(layer "In11.Cu")
		(net "M_D_CPU1_SB_DQ<5>")
	)
	(segment
		(start 89.272364 -237.08741)
		(end 89.266268 -237.083854)
		(width 0.088646)
		(layer "In11.Cu")
		(net "M_D_CPU1_SB_DQ<5>")
	)
	(segment
		(start 33.215072 -219.943426)
		(end 32.46755 -220.690948)
		(width 0.18288)
		(layer "In11.Cu")
		(net "M_D_CPU1_SB_DQ<5>")
	)
	(segment
		(start 82.808064 -234.955842)
		(end 82.608166 -234.755944)
		(width 0.088646)
		(layer "In11.Cu")
		(net "M_D_CPU1_SB_DQ<5>")
	)
	(segment
		(start 28.68803 -222.305626)
		(end 28.128214 -222.305626)
		(width 0.18288)
		(layer "In11.Cu")
		(net "M_D_CPU1_SB_DQ<5>")
	)
	(segment
		(start 28.128214 -222.305626)
		(end 26.553414 -223.880426)
		(width 0.18288)
		(layer "In11.Cu")
		(net "M_D_CPU1_SB_DQ<5>")
	)
	(segment
		(start 97.826068 -237.901226)
		(end 97.815654 -237.907322)
		(width 0.088646)
		(layer "In11.Cu")
		(net "M_D_CPU1_SB_DQ<5>")
	)
	(segment
		(start 37.063426 -219.740226)
		(end 36.377626 -219.842334)
		(width 0.18288)
		(layer "In11.Cu")
		(net "M_D_CPU1_SB_DQ<5>")
	)
	(segment
		(start 29.60243 -221.391226)
		(end 28.68803 -222.305626)
		(width 0.18288)
		(layer "In11.Cu")
		(net "M_D_CPU1_SB_DQ<5>")
	)
	(segment
		(start 98.952812 -238.225584)
		(end 99.265486 -238.225584)
		(width 0.088646)
		(layer "In11.Cu")
		(net "M_D_CPU1_SB_DQ<5>")
	)
	(segment
		(start 77.898752 -234.755944)
		(end 66.383916 -223.241108)
		(width 0.18288)
		(layer "In11.Cu")
		(net "M_D_CPU1_SB_DQ<5>")
	)
	(segment
		(start 60.439046 -221.017846)
		(end 58.455814 -220.502226)
		(width 0.18288)
		(layer "In11.Cu")
		(net "M_D_CPU1_SB_DQ<5>")
	)
	(segment
		(start 51.592226 -219.842334)
		(end 49.508664 -219.842334)
		(width 0.18288)
		(layer "In11.Cu")
		(net "M_D_CPU1_SB_DQ<5>")
	)
	(segment
		(start 89.459816 -237.433612)
		(end 89.459816 -237.411514)
		(width 0.088646)
		(layer "In11.Cu")
		(net "M_D_CPU1_SB_DQ<5>")
	)
	(segment
		(start 83.619594 -236.349286)
		(end 82.808064 -235.537756)
		(width 0.088646)
		(layer "In11.Cu")
		(net "M_D_CPU1_SB_DQ<5>")
	)
	(segment
		(start 20.045426 -224.9424)
		(end 19.524472 -225.463354)
		(width 0.18288)
		(layer "In11.Cu")
		(net "M_D_CPU1_SB_DQ<5>")
	)
	(segment
		(start 65.684908 -223.241108)
		(end 65.054226 -222.610426)
		(width 0.18288)
		(layer "In11.Cu")
		(net "M_D_CPU1_SB_DQ<5>")
	)
	(segment
		(start 34.570924 -219.842334)
		(end 34.14268 -219.943426)
		(width 0.18288)
		(layer "In11.Cu")
		(net "M_D_CPU1_SB_DQ<5>")
	)
	(segment
		(start 25.785826 -223.880426)
		(end 24.896826 -224.769426)
		(width 0.18288)
		(layer "In11.Cu")
		(net "M_D_CPU1_SB_DQ<5>")
	)
	(segment
		(start 24.896826 -224.769426)
		(end 21.88718 -224.769426)
		(width 0.18288)
		(layer "In11.Cu")
		(net "M_D_CPU1_SB_DQ<5>")
	)
	(segment
		(start 21.88718 -224.769426)
		(end 21.281644 -224.9424)
		(width 0.18288)
		(layer "In11.Cu")
		(net "M_D_CPU1_SB_DQ<5>")
	)
	(segment
		(start 91.632278 -237.907322)
		(end 91.621864 -237.901226)
		(width 0.088646)
		(layer "In11.Cu")
		(net "M_D_CPU1_SB_DQ<5>")
	)
	(segment
		(start 39.755826 -219.740226)
		(end 37.063426 -219.740226)
		(width 0.18288)
		(layer "In11.Cu")
		(net "M_D_CPU1_SB_DQ<5>")
	)
	(segment
		(start 60.888626 -221.467426)
		(end 60.439046 -221.017846)
		(width 0.18288)
		(layer "In11.Cu")
		(net "M_D_CPU1_SB_DQ<5>")
	)
	(segment
		(start 95.946214 -237.901226)
		(end 95.931482 -237.909862)
		(width 0.088646)
		(layer "In11.Cu")
		(net "M_D_CPU1_SB_DQ<5>")
	)
	(segment
		(start 96.886014 -237.901226)
		(end 96.871282 -237.909862)
		(width 0.088646)
		(layer "In11.Cu")
		(net "M_D_CPU1_SB_DQ<5>")
	)
	(segment
		(start 34.14268 -219.943426)
		(end 33.215072 -219.943426)
		(width 0.18288)
		(layer "In11.Cu")
		(net "M_D_CPU1_SB_DQ<5>")
	)
	(arc
		(start 93.112082 -237.909862)
		(mid 92.835641 -237.977028)
		(end 92.56141 -237.901226)
		(width 0.088646)
		(layer "In11.Cu")
		(net "M_D_CPU1_SB_DQ<5>")
	)
	(arc
		(start 94.051882 -237.909862)
		(mid 93.775407 -237.977182)
		(end 93.50121 -237.901226)
		(width 0.088646)
		(layer "In11.Cu")
		(net "M_D_CPU1_SB_DQ<5>")
	)
	(arc
		(start 85.608668 -236.273594)
		(mid 85.325966 -236.349336)
		(end 85.043264 -236.273594)
		(width 0.088646)
		(layer "In11.Cu")
		(net "M_D_CPU1_SB_DQ<5>")
	)
	(arc
		(start 94.44101 -237.901226)
		(mid 94.253812 -237.851083)
		(end 94.066614 -237.901226)
		(width 0.088646)
		(layer "In11.Cu")
		(net "M_D_CPU1_SB_DQ<5>")
	)
	(arc
		(start 98.765614 -237.901226)
		(mid 98.489055 -237.976969)
		(end 98.210878 -237.907322)
		(width 0.088646)
		(layer "In11.Cu")
		(net "M_D_CPU1_SB_DQ<5>")
	)
	(arc
		(start 88.989662 -236.589316)
		(mid 88.937392 -236.406951)
		(end 88.802464 -236.273594)
		(width 0.088646)
		(layer "In11.Cu")
		(net "M_D_CPU1_SB_DQ<5>")
	)
	(arc
		(start 87.488268 -236.273594)
		(mid 87.205566 -236.349336)
		(end 86.922864 -236.273594)
		(width 0.088646)
		(layer "In11.Cu")
		(net "M_D_CPU1_SB_DQ<5>")
	)
	(arc
		(start 86.548468 -236.273594)
		(mid 86.265766 -236.349336)
		(end 85.983064 -236.273594)
		(width 0.088646)
		(layer "In11.Cu")
		(net "M_D_CPU1_SB_DQ<5>")
	)
	(arc
		(start 90.68181 -237.901226)
		(mid 90.494612 -237.851083)
		(end 90.307414 -237.901226)
		(width 0.088646)
		(layer "In11.Cu")
		(net "M_D_CPU1_SB_DQ<5>")
	)
	(arc
		(start 93.50121 -237.901226)
		(mid 93.314012 -237.851083)
		(end 93.126814 -237.901226)
		(width 0.088646)
		(layer "In11.Cu")
		(net "M_D_CPU1_SB_DQ<5>")
	)
	(arc
		(start 88.802464 -236.273594)
		(mid 88.615266 -236.223451)
		(end 88.428068 -236.273594)
		(width 0.088646)
		(layer "In11.Cu")
		(net "M_D_CPU1_SB_DQ<5>")
	)
	(arc
		(start 95.931482 -237.909862)
		(mid 95.655007 -237.977182)
		(end 95.38081 -237.901226)
		(width 0.088646)
		(layer "In11.Cu")
		(net "M_D_CPU1_SB_DQ<5>")
	)
	(arc
		(start 95.38081 -237.901226)
		(mid 95.193612 -237.851083)
		(end 95.006414 -237.901226)
		(width 0.088646)
		(layer "In11.Cu")
		(net "M_D_CPU1_SB_DQ<5>")
	)
	(arc
		(start 89.459816 -237.411514)
		(mid 89.413677 -237.231329)
		(end 89.286588 -237.095538)
		(width 0.088646)
		(layer "In11.Cu")
		(net "M_D_CPU1_SB_DQ<5>")
	)
	(arc
		(start 98.200464 -237.901226)
		(mid 98.013266 -237.851083)
		(end 97.826068 -237.901226)
		(width 0.088646)
		(layer "In11.Cu")
		(net "M_D_CPU1_SB_DQ<5>")
	)
	(arc
		(start 90.292682 -237.909862)
		(mid 90.016241 -237.977028)
		(end 89.74201 -237.901226)
		(width 0.088646)
		(layer "In11.Cu")
		(net "M_D_CPU1_SB_DQ<5>")
	)
	(arc
		(start 92.187014 -237.901226)
		(mid 91.910455 -237.976935)
		(end 91.632278 -237.907322)
		(width 0.088646)
		(layer "In11.Cu")
		(net "M_D_CPU1_SB_DQ<5>")
	)
	(arc
		(start 99.14001 -237.901226)
		(mid 98.952812 -237.851083)
		(end 98.765614 -237.901226)
		(width 0.088646)
		(layer "In11.Cu")
		(net "M_D_CPU1_SB_DQ<5>")
	)
	(arc
		(start 91.621864 -237.901226)
		(mid 91.434666 -237.851083)
		(end 91.247468 -237.901226)
		(width 0.088646)
		(layer "In11.Cu")
		(net "M_D_CPU1_SB_DQ<5>")
	)
	(arc
		(start 84.668868 -236.273594)
		(mid 84.532502 -236.330072)
		(end 84.386166 -236.349286)
		(width 0.088646)
		(layer "In11.Cu")
		(net "M_D_CPU1_SB_DQ<5>")
	)
	(arc
		(start 99.32289 -238.16818)
		(mid 99.264734 -238.018067)
		(end 99.1489 -237.906306)
		(width 0.088646)
		(layer "In11.Cu")
		(net "M_D_CPU1_SB_DQ<5>")
	)
	(arc
		(start 89.74201 -237.901226)
		(mid 89.540728 -237.703739)
		(end 89.459816 -237.433612)
		(width 0.088646)
		(layer "In11.Cu")
		(net "M_D_CPU1_SB_DQ<5>")
	)
	(arc
		(start 96.32061 -237.901226)
		(mid 96.133412 -237.851083)
		(end 95.946214 -237.901226)
		(width 0.088646)
		(layer "In11.Cu")
		(net "M_D_CPU1_SB_DQ<5>")
	)
	(arc
		(start 97.815654 -237.907322)
		(mid 97.537222 -237.977168)
		(end 97.26041 -237.901226)
		(width 0.088646)
		(layer "In11.Cu")
		(net "M_D_CPU1_SB_DQ<5>")
	)
	(arc
		(start 88.428068 -236.273594)
		(mid 88.145366 -236.349336)
		(end 87.862664 -236.273594)
		(width 0.088646)
		(layer "In11.Cu")
		(net "M_D_CPU1_SB_DQ<5>")
	)
	(arc
		(start 97.26041 -237.901226)
		(mid 97.073212 -237.851083)
		(end 96.886014 -237.901226)
		(width 0.088646)
		(layer "In11.Cu")
		(net "M_D_CPU1_SB_DQ<5>")
	)
	(arc
		(start 86.922864 -236.273594)
		(mid 86.735666 -236.223451)
		(end 86.548468 -236.273594)
		(width 0.088646)
		(layer "In11.Cu")
		(net "M_D_CPU1_SB_DQ<5>")
	)
	(arc
		(start 91.237054 -237.907322)
		(mid 90.958622 -237.977136)
		(end 90.68181 -237.901226)
		(width 0.088646)
		(layer "In11.Cu")
		(net "M_D_CPU1_SB_DQ<5>")
	)
	(arc
		(start 87.862664 -236.273594)
		(mid 87.675466 -236.223451)
		(end 87.488268 -236.273594)
		(width 0.088646)
		(layer "In11.Cu")
		(net "M_D_CPU1_SB_DQ<5>")
	)
	(arc
		(start 89.266268 -237.083854)
		(mid 89.063681 -236.877503)
		(end 88.989662 -236.597952)
		(width 0.088646)
		(layer "In11.Cu")
		(net "M_D_CPU1_SB_DQ<5>")
	)
	(arc
		(start 96.871282 -237.909862)
		(mid 96.594807 -237.977182)
		(end 96.32061 -237.901226)
		(width 0.088646)
		(layer "In11.Cu")
		(net "M_D_CPU1_SB_DQ<5>")
	)
	(arc
		(start 92.56141 -237.901226)
		(mid 92.374212 -237.851083)
		(end 92.187014 -237.901226)
		(width 0.088646)
		(layer "In11.Cu")
		(net "M_D_CPU1_SB_DQ<5>")
	)
	(arc
		(start 85.043264 -236.273594)
		(mid 84.856066 -236.223451)
		(end 84.668868 -236.273594)
		(width 0.088646)
		(layer "In11.Cu")
		(net "M_D_CPU1_SB_DQ<5>")
	)
	(arc
		(start 94.991682 -237.909862)
		(mid 94.715207 -237.977182)
		(end 94.44101 -237.901226)
		(width 0.088646)
		(layer "In11.Cu")
		(net "M_D_CPU1_SB_DQ<5>")
	)
	(arc
		(start 85.983064 -236.273594)
		(mid 85.795866 -236.223451)
		(end 85.608668 -236.273594)
		(width 0.088646)
		(layer "In11.Cu")
		(net "M_D_CPU1_SB_DQ<5>")
	)
	(segment
		(start 98.482912 -239.57534)
		(end 98.483166 -239.575086)
		(width 0.20066)
		(layer "F.Cu")
		(net "M_D_CPU1_SB_DQ<4>")
	)
	(segment
		(start 9.474708 -226.216718)
		(end 9.713468 -226.455478)
		(width 0.20066)
		(layer "F.Cu")
		(net "M_D_CPU1_SB_DQ<4>")
	)
	(segment
		(start 10.344912 -226.282758)
		(end 10.344912 -225.993198)
		(width 0.20066)
		(layer "F.Cu")
		(net "M_D_CPU1_SB_DQ<4>")
	)
	(segment
		(start 8.140446 -226.216718)
		(end 9.474708 -226.216718)
		(width 0.20066)
		(layer "F.Cu")
		(net "M_D_CPU1_SB_DQ<4>")
	)
	(segment
		(start 16.789146 -226.216718)
		(end 15.684246 -226.216718)
		(width 0.20066)
		(layer "F.Cu")
		(net "M_D_CPU1_SB_DQ<4>")
	)
	(segment
		(start 11.124438 -225.791776)
		(end 11.372342 -225.791776)
		(width 0.101854)
		(layer "F.Cu")
		(net "M_D_CPU1_SB_DQ<4>")
	)
	(segment
		(start 11.372342 -225.791776)
		(end 13.441426 -225.791776)
		(width 0.1016)
		(layer "F.Cu")
		(net "M_D_CPU1_SB_DQ<4>")
	)
	(segment
		(start 10.344912 -225.993198)
		(end 10.554462 -225.783648)
		(width 0.20066)
		(layer "F.Cu")
		(net "M_D_CPU1_SB_DQ<4>")
	)
	(segment
		(start 13.890244 -225.791776)
		(end 14.315186 -226.216718)
		(width 0.20066)
		(layer "F.Cu")
		(net "M_D_CPU1_SB_DQ<4>")
	)
	(segment
		(start 14.315186 -226.216718)
		(end 15.684246 -226.216718)
		(width 0.20066)
		(layer "F.Cu")
		(net "M_D_CPU1_SB_DQ<4>")
	)
	(segment
		(start 11.11631 -225.783648)
		(end 11.124438 -225.791776)
		(width 0.101854)
		(layer "F.Cu")
		(net "M_D_CPU1_SB_DQ<4>")
	)
	(segment
		(start 10.554462 -225.783648)
		(end 11.11631 -225.783648)
		(width 0.20066)
		(layer "F.Cu")
		(net "M_D_CPU1_SB_DQ<4>")
	)
	(segment
		(start 9.713468 -226.455478)
		(end 10.172192 -226.455478)
		(width 0.20066)
		(layer "F.Cu")
		(net "M_D_CPU1_SB_DQ<4>")
	)
	(segment
		(start 13.441426 -225.791776)
		(end 13.890244 -225.791776)
		(width 0.20066)
		(layer "F.Cu")
		(net "M_D_CPU1_SB_DQ<4>")
	)
	(segment
		(start 98.483166 -239.575086)
		(end 98.483166 -239.0394)
		(width 0.20066)
		(layer "F.Cu")
		(net "M_D_CPU1_SB_DQ<4>")
	)
	(segment
		(start 10.172192 -226.455478)
		(end 10.344912 -226.282758)
		(width 0.20066)
		(layer "F.Cu")
		(net "M_D_CPU1_SB_DQ<4>")
	)
	(segment
		(start 62.565026 -223.118426)
		(end 59.745626 -223.118426)
		(width 0.18288)
		(layer "In11.Cu")
		(net "M_D_CPU1_SB_DQ<4>")
	)
	(segment
		(start 44.607226 -222.635826)
		(end 44.175426 -222.204026)
		(width 0.18288)
		(layer "In11.Cu")
		(net "M_D_CPU1_SB_DQ<4>")
	)
	(segment
		(start 20.070826 -226.642422)
		(end 19.90852 -226.804728)
		(width 0.18288)
		(layer "In11.Cu")
		(net "M_D_CPU1_SB_DQ<4>")
	)
	(segment
		(start 26.065226 -225.633026)
		(end 25.19299 -226.505262)
		(width 0.18288)
		(layer "In11.Cu")
		(net "M_D_CPU1_SB_DQ<4>")
	)
	(segment
		(start 21.48459 -226.505262)
		(end 21.34743 -226.642422)
		(width 0.18288)
		(layer "In11.Cu")
		(net "M_D_CPU1_SB_DQ<4>")
	)
	(segment
		(start 55.801006 -222.305626)
		(end 54.912006 -221.416626)
		(width 0.18288)
		(layer "In11.Cu")
		(net "M_D_CPU1_SB_DQ<4>")
	)
	(segment
		(start 84.385912 -237.03661)
		(end 83.75142 -237.03661)
		(width 0.088646)
		(layer "In11.Cu")
		(net "M_D_CPU1_SB_DQ<4>")
	)
	(segment
		(start 53.089556 -221.922848)
		(end 53.089556 -221.609666)
		(width 0.18288)
		(layer "In11.Cu")
		(net "M_D_CPU1_SB_DQ<4>")
	)
	(segment
		(start 88.8111 -237.906306)
		(end 88.80221 -237.901226)
		(width 0.088646)
		(layer "In11.Cu")
		(net "M_D_CPU1_SB_DQ<4>")
	)
	(segment
		(start 53.790596 -221.609666)
		(end 53.790596 -221.922848)
		(width 0.18288)
		(layer "In11.Cu")
		(net "M_D_CPU1_SB_DQ<4>")
	)
	(segment
		(start 25.19299 -226.505262)
		(end 21.48459 -226.505262)
		(width 0.18288)
		(layer "In11.Cu")
		(net "M_D_CPU1_SB_DQ<4>")
	)
	(segment
		(start 49.357026 -221.950026)
		(end 48.326294 -221.950026)
		(width 0.18288)
		(layer "In11.Cu")
		(net "M_D_CPU1_SB_DQ<4>")
	)
	(segment
		(start 86.078568 -237.08741)
		(end 86.068154 -237.093506)
		(width 0.088646)
		(layer "In11.Cu")
		(net "M_D_CPU1_SB_DQ<4>")
	)
	(segment
		(start 65.584578 -224.944178)
		(end 64.546226 -223.905826)
		(width 0.18288)
		(layer "In11.Cu")
		(net "M_D_CPU1_SB_DQ<4>")
	)
	(segment
		(start 82.486754 -235.771944)
		(end 82.37347 -235.771944)
		(width 0.088646)
		(layer "In11.Cu")
		(net "M_D_CPU1_SB_DQ<4>")
	)
	(segment
		(start 26.700226 -225.633026)
		(end 26.065226 -225.633026)
		(width 0.18288)
		(layer "In11.Cu")
		(net "M_D_CPU1_SB_DQ<4>")
	)
	(segment
		(start 58.932826 -222.305626)
		(end 55.801006 -222.305626)
		(width 0.18288)
		(layer "In11.Cu")
		(net "M_D_CPU1_SB_DQ<4>")
	)
	(segment
		(start 53.790596 -221.922848)
		(end 53.597556 -222.115888)
		(width 0.18288)
		(layer "In11.Cu")
		(net "M_D_CPU1_SB_DQ<4>")
	)
	(segment
		(start 92.106496 -238.723678)
		(end 92.091764 -238.715042)
		(width 0.088646)
		(layer "In11.Cu")
		(net "M_D_CPU1_SB_DQ<4>")
	)
	(segment
		(start 29.519626 -223.143826)
		(end 28.663646 -223.999806)
		(width 0.18288)
		(layer "In11.Cu")
		(net "M_D_CPU1_SB_DQ<4>")
	)
	(segment
		(start 82.37347 -235.771944)
		(end 77.386688 -235.771944)
		(width 0.18288)
		(layer "In11.Cu")
		(net "M_D_CPU1_SB_DQ<4>")
	)
	(segment
		(start 53.597556 -222.115888)
		(end 53.282596 -222.115888)
		(width 0.18288)
		(layer "In11.Cu")
		(net "M_D_CPU1_SB_DQ<4>")
	)
	(segment
		(start 66.559938 -224.944178)
		(end 65.584578 -224.944178)
		(width 0.18288)
		(layer "In11.Cu")
		(net "M_D_CPU1_SB_DQ<4>")
	)
	(segment
		(start 53.282596 -222.115888)
		(end 53.089556 -221.922848)
		(width 0.18288)
		(layer "In11.Cu")
		(net "M_D_CPU1_SB_DQ<4>")
	)
	(segment
		(start 28.663646 -223.999806)
		(end 28.333446 -223.999806)
		(width 0.18288)
		(layer "In11.Cu")
		(net "M_D_CPU1_SB_DQ<4>")
	)
	(segment
		(start 85.138514 -237.08741)
		(end 85.123782 -237.096046)
		(width 0.088646)
		(layer "In11.Cu")
		(net "M_D_CPU1_SB_DQ<4>")
	)
	(segment
		(start 93.981778 -238.721138)
		(end 93.971364 -238.715042)
		(width 0.088646)
		(layer "In11.Cu")
		(net "M_D_CPU1_SB_DQ<4>")
	)
	(segment
		(start 34.066226 -222.000826)
		(end 33.187894 -222.000826)
		(width 0.18288)
		(layer "In11.Cu")
		(net "M_D_CPU1_SB_DQ<4>")
	)
	(segment
		(start 77.386688 -235.771944)
		(end 66.559938 -224.944178)
		(width 0.18288)
		(layer "In11.Cu")
		(net "M_D_CPU1_SB_DQ<4>")
	)
	(segment
		(start 48.326294 -221.950026)
		(end 47.883826 -222.392494)
		(width 0.18288)
		(layer "In11.Cu")
		(net "M_D_CPU1_SB_DQ<4>")
	)
	(segment
		(start 98.483166 -239.0394)
		(end 98.449384 -239.005618)
		(width 0.088646)
		(layer "In11.Cu")
		(net "M_D_CPU1_SB_DQ<4>")
	)
	(segment
		(start 19.90852 -226.804728)
		(end 17.377156 -226.804728)
		(width 0.18288)
		(layer "In11.Cu")
		(net "M_D_CPU1_SB_DQ<4>")
	)
	(segment
		(start 95.865696 -238.723678)
		(end 95.850964 -238.715042)
		(width 0.088646)
		(layer "In11.Cu")
		(net "M_D_CPU1_SB_DQ<4>")
	)
	(segment
		(start 89.287096 -238.723678)
		(end 89.272364 -238.715042)
		(width 0.088646)
		(layer "In11.Cu")
		(net "M_D_CPU1_SB_DQ<4>")
	)
	(segment
		(start 89.272364 -238.715042)
		(end 89.266268 -238.711486)
		(width 0.088646)
		(layer "In11.Cu")
		(net "M_D_CPU1_SB_DQ<4>")
	)
	(segment
		(start 34.527744 -221.539308)
		(end 34.066226 -222.000826)
		(width 0.18288)
		(layer "In11.Cu")
		(net "M_D_CPU1_SB_DQ<4>")
	)
	(segment
		(start 53.983636 -221.416626)
		(end 53.790596 -221.609666)
		(width 0.18288)
		(layer "In11.Cu")
		(net "M_D_CPU1_SB_DQ<4>")
	)
	(segment
		(start 30.942026 -222.392494)
		(end 30.190694 -223.143826)
		(width 0.18288)
		(layer "In11.Cu")
		(net "M_D_CPU1_SB_DQ<4>")
	)
	(segment
		(start 21.34743 -226.642422)
		(end 20.070826 -226.642422)
		(width 0.18288)
		(layer "In11.Cu")
		(net "M_D_CPU1_SB_DQ<4>")
	)
	(segment
		(start 83.75142 -237.03661)
		(end 82.486754 -235.771944)
		(width 0.088646)
		(layer "In11.Cu")
		(net "M_D_CPU1_SB_DQ<4>")
	)
	(segment
		(start 51.983894 -221.542356)
		(end 49.764696 -221.542356)
		(width 0.18288)
		(layer "In11.Cu")
		(net "M_D_CPU1_SB_DQ<4>")
	)
	(segment
		(start 63.352426 -223.905826)
		(end 62.565026 -223.118426)
		(width 0.18288)
		(layer "In11.Cu")
		(net "M_D_CPU1_SB_DQ<4>")
	)
	(segment
		(start 90.226896 -238.723678)
		(end 90.212164 -238.715042)
		(width 0.088646)
		(layer "In11.Cu")
		(net "M_D_CPU1_SB_DQ<4>")
	)
	(segment
		(start 47.883826 -222.392494)
		(end 45.739558 -222.392494)
		(width 0.18288)
		(layer "In11.Cu")
		(net "M_D_CPU1_SB_DQ<4>")
	)
	(segment
		(start 59.745626 -223.118426)
		(end 58.932826 -222.305626)
		(width 0.18288)
		(layer "In11.Cu")
		(net "M_D_CPU1_SB_DQ<4>")
	)
	(segment
		(start 30.190694 -223.143826)
		(end 29.519626 -223.143826)
		(width 0.18288)
		(layer "In11.Cu")
		(net "M_D_CPU1_SB_DQ<4>")
	)
	(segment
		(start 88.427814 -237.901226)
		(end 88.4174 -237.907322)
		(width 0.088646)
		(layer "In11.Cu")
		(net "M_D_CPU1_SB_DQ<4>")
	)
	(segment
		(start 33.187894 -222.000826)
		(end 32.796226 -222.392494)
		(width 0.18288)
		(layer "In11.Cu")
		(net "M_D_CPU1_SB_DQ<4>")
	)
	(segment
		(start 41.254426 -222.204026)
		(end 40.589708 -221.539308)
		(width 0.18288)
		(layer "In11.Cu")
		(net "M_D_CPU1_SB_DQ<4>")
	)
	(segment
		(start 93.046296 -238.723678)
		(end 93.031564 -238.715042)
		(width 0.088646)
		(layer "In11.Cu")
		(net "M_D_CPU1_SB_DQ<4>")
	)
	(segment
		(start 64.546226 -223.905826)
		(end 63.352426 -223.905826)
		(width 0.18288)
		(layer "In11.Cu")
		(net "M_D_CPU1_SB_DQ<4>")
	)
	(segment
		(start 28.333446 -223.999806)
		(end 26.700226 -225.633026)
		(width 0.18288)
		(layer "In11.Cu")
		(net "M_D_CPU1_SB_DQ<4>")
	)
	(segment
		(start 94.921324 -238.721138)
		(end 94.91091 -238.715042)
		(width 0.088646)
		(layer "In11.Cu")
		(net "M_D_CPU1_SB_DQ<4>")
	)
	(segment
		(start 87.4014 -237.09249)
		(end 87.39251 -237.08741)
		(width 0.088646)
		(layer "In11.Cu")
		(net "M_D_CPU1_SB_DQ<4>")
	)
	(segment
		(start 96.805496 -238.723678)
		(end 96.790764 -238.715042)
		(width 0.088646)
		(layer "In11.Cu")
		(net "M_D_CPU1_SB_DQ<4>")
	)
	(segment
		(start 87.580216 -237.419388)
		(end 87.579962 -237.411768)
		(width 0.088646)
		(layer "In11.Cu")
		(net "M_D_CPU1_SB_DQ<4>")
	)
	(segment
		(start 52.109624 -221.416626)
		(end 51.983894 -221.542356)
		(width 0.18288)
		(layer "In11.Cu")
		(net "M_D_CPU1_SB_DQ<4>")
	)
	(segment
		(start 54.912006 -221.416626)
		(end 53.983636 -221.416626)
		(width 0.18288)
		(layer "In11.Cu")
		(net "M_D_CPU1_SB_DQ<4>")
	)
	(segment
		(start 52.896516 -221.416626)
		(end 52.109624 -221.416626)
		(width 0.18288)
		(layer "In11.Cu")
		(net "M_D_CPU1_SB_DQ<4>")
	)
	(segment
		(start 49.764696 -221.542356)
		(end 49.357026 -221.950026)
		(width 0.18288)
		(layer "In11.Cu")
		(net "M_D_CPU1_SB_DQ<4>")
	)
	(segment
		(start 87.018114 -237.08741)
		(end 87.0077 -237.093506)
		(width 0.088646)
		(layer "In11.Cu")
		(net "M_D_CPU1_SB_DQ<4>")
	)
	(segment
		(start 45.739558 -222.392494)
		(end 45.496226 -222.635826)
		(width 0.18288)
		(layer "In11.Cu")
		(net "M_D_CPU1_SB_DQ<4>")
	)
	(segment
		(start 40.589708 -221.539308)
		(end 34.527744 -221.539308)
		(width 0.18288)
		(layer "In11.Cu")
		(net "M_D_CPU1_SB_DQ<4>")
	)
	(segment
		(start 32.796226 -222.392494)
		(end 30.942026 -222.392494)
		(width 0.18288)
		(layer "In11.Cu")
		(net "M_D_CPU1_SB_DQ<4>")
	)
	(segment
		(start 53.089556 -221.609666)
		(end 52.896516 -221.416626)
		(width 0.18288)
		(layer "In11.Cu")
		(net "M_D_CPU1_SB_DQ<4>")
	)
	(segment
		(start 44.175426 -222.204026)
		(end 41.254426 -222.204026)
		(width 0.18288)
		(layer "In11.Cu")
		(net "M_D_CPU1_SB_DQ<4>")
	)
	(segment
		(start 45.496226 -222.635826)
		(end 44.607226 -222.635826)
		(width 0.18288)
		(layer "In11.Cu")
		(net "M_D_CPU1_SB_DQ<4>")
	)
	(segment
		(start 17.377156 -226.804728)
		(end 16.789146 -226.216718)
		(width 0.18288)
		(layer "In11.Cu")
		(net "M_D_CPU1_SB_DQ<4>")
	)
	(arc
		(start 92.091764 -238.715042)
		(mid 91.904566 -238.664899)
		(end 91.717368 -238.715042)
		(width 0.088646)
		(layer "In11.Cu")
		(net "M_D_CPU1_SB_DQ<4>")
	)
	(arc
		(start 96.416368 -238.715042)
		(mid 96.142169 -238.790877)
		(end 95.865696 -238.723678)
		(width 0.088646)
		(layer "In11.Cu")
		(net "M_D_CPU1_SB_DQ<4>")
	)
	(arc
		(start 86.452964 -237.08741)
		(mid 86.265766 -237.037267)
		(end 86.078568 -237.08741)
		(width 0.088646)
		(layer "In11.Cu")
		(net "M_D_CPU1_SB_DQ<4>")
	)
	(arc
		(start 95.850964 -238.715042)
		(mid 95.663766 -238.664899)
		(end 95.476568 -238.715042)
		(width 0.088646)
		(layer "In11.Cu")
		(net "M_D_CPU1_SB_DQ<4>")
	)
	(arc
		(start 84.57311 -237.08741)
		(mid 84.482854 -237.049688)
		(end 84.385912 -237.03661)
		(width 0.088646)
		(layer "In11.Cu")
		(net "M_D_CPU1_SB_DQ<4>")
	)
	(arc
		(start 90.777568 -238.715042)
		(mid 90.503369 -238.790877)
		(end 90.226896 -238.723678)
		(width 0.088646)
		(layer "In11.Cu")
		(net "M_D_CPU1_SB_DQ<4>")
	)
	(arc
		(start 97.974404 -238.789464)
		(mid 97.848237 -238.766173)
		(end 97.730564 -238.715042)
		(width 0.088646)
		(layer "In11.Cu")
		(net "M_D_CPU1_SB_DQ<4>")
	)
	(arc
		(start 88.80221 -237.901226)
		(mid 88.615012 -237.851083)
		(end 88.427814 -237.901226)
		(width 0.088646)
		(layer "In11.Cu")
		(net "M_D_CPU1_SB_DQ<4>")
	)
	(arc
		(start 87.862664 -237.901226)
		(mid 87.657838 -237.697604)
		(end 87.580216 -237.419388)
		(width 0.088646)
		(layer "In11.Cu")
		(net "M_D_CPU1_SB_DQ<4>")
	)
	(arc
		(start 96.790764 -238.715042)
		(mid 96.603566 -238.664899)
		(end 96.416368 -238.715042)
		(width 0.088646)
		(layer "In11.Cu")
		(net "M_D_CPU1_SB_DQ<4>")
	)
	(arc
		(start 87.0077 -237.093506)
		(mid 86.729522 -237.163229)
		(end 86.452964 -237.08741)
		(width 0.088646)
		(layer "In11.Cu")
		(net "M_D_CPU1_SB_DQ<4>")
	)
	(arc
		(start 97.356168 -238.715042)
		(mid 97.081969 -238.790877)
		(end 96.805496 -238.723678)
		(width 0.088646)
		(layer "In11.Cu")
		(net "M_D_CPU1_SB_DQ<4>")
	)
	(arc
		(start 94.91091 -238.715042)
		(mid 94.723712 -238.664899)
		(end 94.536514 -238.715042)
		(width 0.088646)
		(layer "In11.Cu")
		(net "M_D_CPU1_SB_DQ<4>")
	)
	(arc
		(start 89.837768 -238.715042)
		(mid 89.563569 -238.790877)
		(end 89.287096 -238.723678)
		(width 0.088646)
		(layer "In11.Cu")
		(net "M_D_CPU1_SB_DQ<4>")
	)
	(arc
		(start 93.971364 -238.715042)
		(mid 93.784166 -238.664899)
		(end 93.596968 -238.715042)
		(width 0.088646)
		(layer "In11.Cu")
		(net "M_D_CPU1_SB_DQ<4>")
	)
	(arc
		(start 91.151964 -238.715042)
		(mid 90.964766 -238.664899)
		(end 90.777568 -238.715042)
		(width 0.088646)
		(layer "In11.Cu")
		(net "M_D_CPU1_SB_DQ<4>")
	)
	(arc
		(start 87.39251 -237.08741)
		(mid 87.205312 -237.037267)
		(end 87.018114 -237.08741)
		(width 0.088646)
		(layer "In11.Cu")
		(net "M_D_CPU1_SB_DQ<4>")
	)
	(arc
		(start 93.596968 -238.715042)
		(mid 93.322769 -238.790877)
		(end 93.046296 -238.723678)
		(width 0.088646)
		(layer "In11.Cu")
		(net "M_D_CPU1_SB_DQ<4>")
	)
	(arc
		(start 95.476568 -238.715042)
		(mid 95.199755 -238.790912)
		(end 94.921324 -238.721138)
		(width 0.088646)
		(layer "In11.Cu")
		(net "M_D_CPU1_SB_DQ<4>")
	)
	(arc
		(start 85.123782 -237.096046)
		(mid 84.847307 -237.163366)
		(end 84.57311 -237.08741)
		(width 0.088646)
		(layer "In11.Cu")
		(net "M_D_CPU1_SB_DQ<4>")
	)
	(arc
		(start 92.657168 -238.715042)
		(mid 92.382969 -238.790877)
		(end 92.106496 -238.723678)
		(width 0.088646)
		(layer "In11.Cu")
		(net "M_D_CPU1_SB_DQ<4>")
	)
	(arc
		(start 88.4174 -237.907322)
		(mid 88.139222 -237.977014)
		(end 87.862664 -237.901226)
		(width 0.088646)
		(layer "In11.Cu")
		(net "M_D_CPU1_SB_DQ<4>")
	)
	(arc
		(start 91.717368 -238.715042)
		(mid 91.434666 -238.790818)
		(end 91.151964 -238.715042)
		(width 0.088646)
		(layer "In11.Cu")
		(net "M_D_CPU1_SB_DQ<4>")
	)
	(arc
		(start 87.579962 -237.411768)
		(mid 87.532283 -237.228868)
		(end 87.4014 -237.09249)
		(width 0.088646)
		(layer "In11.Cu")
		(net "M_D_CPU1_SB_DQ<4>")
	)
	(arc
		(start 90.212164 -238.715042)
		(mid 90.024966 -238.664899)
		(end 89.837768 -238.715042)
		(width 0.088646)
		(layer "In11.Cu")
		(net "M_D_CPU1_SB_DQ<4>")
	)
	(arc
		(start 94.536514 -238.715042)
		(mid 94.259955 -238.790785)
		(end 93.981778 -238.721138)
		(width 0.088646)
		(layer "In11.Cu")
		(net "M_D_CPU1_SB_DQ<4>")
	)
	(arc
		(start 89.266268 -238.711486)
		(mid 89.063681 -238.505135)
		(end 88.989662 -238.225584)
		(width 0.088646)
		(layer "In11.Cu")
		(net "M_D_CPU1_SB_DQ<4>")
	)
	(arc
		(start 88.989662 -238.225584)
		(mid 88.941983 -238.042684)
		(end 88.8111 -237.906306)
		(width 0.088646)
		(layer "In11.Cu")
		(net "M_D_CPU1_SB_DQ<4>")
	)
	(arc
		(start 85.51291 -237.08741)
		(mid 85.325712 -237.037267)
		(end 85.138514 -237.08741)
		(width 0.088646)
		(layer "In11.Cu")
		(net "M_D_CPU1_SB_DQ<4>")
	)
	(arc
		(start 93.031564 -238.715042)
		(mid 92.844366 -238.664899)
		(end 92.657168 -238.715042)
		(width 0.088646)
		(layer "In11.Cu")
		(net "M_D_CPU1_SB_DQ<4>")
	)
	(arc
		(start 86.068154 -237.093506)
		(mid 85.789722 -237.163352)
		(end 85.51291 -237.08741)
		(width 0.088646)
		(layer "In11.Cu")
		(net "M_D_CPU1_SB_DQ<4>")
	)
	(arc
		(start 97.730564 -238.715042)
		(mid 97.543366 -238.664899)
		(end 97.356168 -238.715042)
		(width 0.088646)
		(layer "In11.Cu")
		(net "M_D_CPU1_SB_DQ<4>")
	)
	(arc
		(start 98.449384 -239.005618)
		(mid 98.231469 -238.854511)
		(end 97.974404 -238.789464)
		(width 0.088646)
		(layer "In11.Cu")
		(net "M_D_CPU1_SB_DQ<4>")
	)
	(segment
		(start 14.574266 -230.041704)
		(end 14.812264 -230.041704)
		(width 0.101854)
		(layer "F.Cu")
		(net "M_D_CPU1_SB_DQ<3>")
	)
	(segment
		(start 14.063726 -229.913434)
		(end 14.20622 -230.055928)
		(width 0.20066)
		(layer "F.Cu")
		(net "M_D_CPU1_SB_DQ<3>")
	)
	(segment
		(start 17.42948 -230.041704)
		(end 17.578578 -229.892606)
		(width 0.20066)
		(layer "F.Cu")
		(net "M_D_CPU1_SB_DQ<3>")
	)
	(segment
		(start 18.760694 -229.82428)
		(end 18.968212 -229.616762)
		(width 0.20066)
		(layer "F.Cu")
		(net "M_D_CPU1_SB_DQ<3>")
	)
	(segment
		(start 100.362512 -241.203226)
		(end 100.362766 -241.202972)
		(width 0.20066)
		(layer "F.Cu")
		(net "M_D_CPU1_SB_DQ<3>")
	)
	(segment
		(start 16.885158 -230.041704)
		(end 17.42948 -230.041704)
		(width 0.20066)
		(layer "F.Cu")
		(net "M_D_CPU1_SB_DQ<3>")
	)
	(segment
		(start 14.063726 -229.742746)
		(end 14.063726 -229.913434)
		(width 0.20066)
		(layer "F.Cu")
		(net "M_D_CPU1_SB_DQ<3>")
	)
	(segment
		(start 17.578578 -229.892606)
		(end 17.578578 -229.740968)
		(width 0.20066)
		(layer "F.Cu")
		(net "M_D_CPU1_SB_DQ<3>")
	)
	(segment
		(start 13.937742 -229.616762)
		(end 14.063726 -229.742746)
		(width 0.20066)
		(layer "F.Cu")
		(net "M_D_CPU1_SB_DQ<3>")
	)
	(segment
		(start 18.968212 -229.616762)
		(end 19.784314 -229.616762)
		(width 0.20066)
		(layer "F.Cu")
		(net "M_D_CPU1_SB_DQ<3>")
	)
	(segment
		(start 17.707102 -229.612444)
		(end 18.102326 -229.612444)
		(width 0.20066)
		(layer "F.Cu")
		(net "M_D_CPU1_SB_DQ<3>")
	)
	(segment
		(start 20.889214 -229.616762)
		(end 19.784314 -229.616762)
		(width 0.20066)
		(layer "F.Cu")
		(net "M_D_CPU1_SB_DQ<3>")
	)
	(segment
		(start 14.560042 -230.055928)
		(end 14.574266 -230.041704)
		(width 0.101854)
		(layer "F.Cu")
		(net "M_D_CPU1_SB_DQ<3>")
	)
	(segment
		(start 18.314162 -229.82428)
		(end 18.760694 -229.82428)
		(width 0.20066)
		(layer "F.Cu")
		(net "M_D_CPU1_SB_DQ<3>")
	)
	(segment
		(start 14.20622 -230.055928)
		(end 14.560042 -230.055928)
		(width 0.20066)
		(layer "F.Cu")
		(net "M_D_CPU1_SB_DQ<3>")
	)
	(segment
		(start 12.240514 -229.616762)
		(end 13.937742 -229.616762)
		(width 0.20066)
		(layer "F.Cu")
		(net "M_D_CPU1_SB_DQ<3>")
	)
	(segment
		(start 17.578578 -229.740968)
		(end 17.707102 -229.612444)
		(width 0.20066)
		(layer "F.Cu")
		(net "M_D_CPU1_SB_DQ<3>")
	)
	(segment
		(start 18.102326 -229.612444)
		(end 18.314162 -229.82428)
		(width 0.20066)
		(layer "F.Cu")
		(net "M_D_CPU1_SB_DQ<3>")
	)
	(segment
		(start 14.812264 -230.041704)
		(end 16.885158 -230.041704)
		(width 0.1016)
		(layer "F.Cu")
		(net "M_D_CPU1_SB_DQ<3>")
	)
	(segment
		(start 100.362766 -241.202972)
		(end 100.362766 -240.667286)
		(width 0.20066)
		(layer "F.Cu")
		(net "M_D_CPU1_SB_DQ<3>")
	)
	(segment
		(start 31.756604 -226.640898)
		(end 31.754826 -226.642676)
		(width 0.18288)
		(layer "In11.Cu")
		(net "M_D_CPU1_SB_DQ<3>")
	)
	(segment
		(start 85.527896 -239.355122)
		(end 85.513164 -239.363758)
		(width 0.088646)
		(layer "In11.Cu")
		(net "M_D_CPU1_SB_DQ<3>")
	)
	(segment
		(start 24.82342 -230.204772)
		(end 23.725632 -230.204772)
		(width 0.18288)
		(layer "In11.Cu")
		(net "M_D_CPU1_SB_DQ<3>")
	)
	(segment
		(start 23.024592 -229.436422)
		(end 22.831552 -229.629462)
		(width 0.18288)
		(layer "In11.Cu")
		(net "M_D_CPU1_SB_DQ<3>")
	)
	(segment
		(start 31.754826 -226.642676)
		(end 30.815788 -226.642676)
		(width 0.18288)
		(layer "In11.Cu")
		(net "M_D_CPU1_SB_DQ<3>")
	)
	(segment
		(start 23.532592 -230.011732)
		(end 23.532592 -229.629462)
		(width 0.18288)
		(layer "In11.Cu")
		(net "M_D_CPU1_SB_DQ<3>")
	)
	(segment
		(start 29.470096 -227.666296)
		(end 28.846526 -228.289866)
		(width 0.18288)
		(layer "In11.Cu")
		(net "M_D_CPU1_SB_DQ<3>")
	)
	(segment
		(start 25.825958 -229.202234)
		(end 24.82342 -230.204772)
		(width 0.18288)
		(layer "In11.Cu")
		(net "M_D_CPU1_SB_DQ<3>")
	)
	(segment
		(start 33.90138 -226.852226)
		(end 33.335976 -226.852226)
		(width 0.18288)
		(layer "In11.Cu")
		(net "M_D_CPU1_SB_DQ<3>")
	)
	(segment
		(start 54.02453 -225.988626)
		(end 53.83149 -225.795586)
		(width 0.18288)
		(layer "In11.Cu")
		(net "M_D_CPU1_SB_DQ<3>")
	)
	(segment
		(start 22.831552 -229.629462)
		(end 22.831552 -230.011732)
		(width 0.18288)
		(layer "In11.Cu")
		(net "M_D_CPU1_SB_DQ<3>")
	)
	(segment
		(start 56.037226 -226.801426)
		(end 55.224426 -225.988626)
		(width 0.18288)
		(layer "In11.Cu")
		(net "M_D_CPU1_SB_DQ<3>")
	)
	(segment
		(start 22.831552 -230.011732)
		(end 22.638512 -230.204772)
		(width 0.18288)
		(layer "In11.Cu")
		(net "M_D_CPU1_SB_DQ<3>")
	)
	(segment
		(start 39.002716 -225.912426)
		(end 38.809676 -225.719386)
		(width 0.18288)
		(layer "In11.Cu")
		(net "M_D_CPU1_SB_DQ<3>")
	)
	(segment
		(start 53.13045 -225.795586)
		(end 52.93741 -225.988626)
		(width 0.18288)
		(layer "In11.Cu")
		(net "M_D_CPU1_SB_DQ<3>")
	)
	(segment
		(start 53.32349 -225.239072)
		(end 53.13045 -225.432112)
		(width 0.18288)
		(layer "In11.Cu")
		(net "M_D_CPU1_SB_DQ<3>")
	)
	(segment
		(start 49.12487 -226.716336)
		(end 48.150018 -226.716336)
		(width 0.18288)
		(layer "In11.Cu")
		(net "M_D_CPU1_SB_DQ<3>")
	)
	(segment
		(start 27.370786 -228.289866)
		(end 26.458418 -229.202234)
		(width 0.18288)
		(layer "In11.Cu")
		(net "M_D_CPU1_SB_DQ<3>")
	)
	(segment
		(start 50.048668 -225.792538)
		(end 49.12487 -226.716336)
		(width 0.18288)
		(layer "In11.Cu")
		(net "M_D_CPU1_SB_DQ<3>")
	)
	(segment
		(start 92.106496 -240.983008)
		(end 92.091764 -240.991644)
		(width 0.088646)
		(layer "In11.Cu")
		(net "M_D_CPU1_SB_DQ<3>")
	)
	(segment
		(start 34.961068 -225.792538)
		(end 33.90138 -226.852226)
		(width 0.18288)
		(layer "In11.Cu")
		(net "M_D_CPU1_SB_DQ<3>")
	)
	(segment
		(start 32.057848 -226.640898)
		(end 31.756604 -226.640898)
		(width 0.18288)
		(layer "In11.Cu")
		(net "M_D_CPU1_SB_DQ<3>")
	)
	(segment
		(start 42.778426 -227.563426)
		(end 42.067226 -226.852226)
		(width 0.18288)
		(layer "In11.Cu")
		(net "M_D_CPU1_SB_DQ<3>")
	)
	(segment
		(start 88.347296 -240.983008)
		(end 88.332564 -240.991644)
		(width 0.088646)
		(layer "In11.Cu")
		(net "M_D_CPU1_SB_DQ<3>")
	)
	(segment
		(start 84.21878 -239.414304)
		(end 82.741262 -237.936786)
		(width 0.088646)
		(layer "In11.Cu")
		(net "M_D_CPU1_SB_DQ<3>")
	)
	(segment
		(start 45.9486 -226.642676)
		(end 45.02785 -227.563426)
		(width 0.18288)
		(layer "In11.Cu")
		(net "M_D_CPU1_SB_DQ<3>")
	)
	(segment
		(start 87.770716 -240.667286)
		(end 87.770716 -240.653062)
		(width 0.088646)
		(layer "In11.Cu")
		(net "M_D_CPU1_SB_DQ<3>")
	)
	(segment
		(start 93.046296 -240.983008)
		(end 93.031564 -240.991644)
		(width 0.088646)
		(layer "In11.Cu")
		(net "M_D_CPU1_SB_DQ<3>")
	)
	(segment
		(start 56.875426 -226.801426)
		(end 56.037226 -226.801426)
		(width 0.18288)
		(layer "In11.Cu")
		(net "M_D_CPU1_SB_DQ<3>")
	)
	(segment
		(start 38.809676 -225.5012)
		(end 38.616636 -225.30816)
		(width 0.18288)
		(layer "In11.Cu")
		(net "M_D_CPU1_SB_DQ<3>")
	)
	(segment
		(start 57.637426 -227.563426)
		(end 56.875426 -226.801426)
		(width 0.18288)
		(layer "In11.Cu")
		(net "M_D_CPU1_SB_DQ<3>")
	)
	(segment
		(start 61.619892 -229.191312)
		(end 59.992006 -227.563426)
		(width 0.18288)
		(layer "In11.Cu")
		(net "M_D_CPU1_SB_DQ<3>")
	)
	(segment
		(start 52.93741 -225.988626)
		(end 51.922426 -225.988626)
		(width 0.18288)
		(layer "In11.Cu")
		(net "M_D_CPU1_SB_DQ<3>")
	)
	(segment
		(start 84.588096 -239.355122)
		(end 84.573364 -239.363758)
		(width 0.088646)
		(layer "In11.Cu")
		(net "M_D_CPU1_SB_DQ<3>")
	)
	(segment
		(start 53.83149 -225.795586)
		(end 53.83149 -225.432112)
		(width 0.18288)
		(layer "In11.Cu")
		(net "M_D_CPU1_SB_DQ<3>")
	)
	(segment
		(start 42.067226 -226.852226)
		(end 40.804338 -226.852226)
		(width 0.18288)
		(layer "In11.Cu")
		(net "M_D_CPU1_SB_DQ<3>")
	)
	(segment
		(start 40.804338 -226.852226)
		(end 39.864538 -225.912426)
		(width 0.18288)
		(layer "In11.Cu")
		(net "M_D_CPU1_SB_DQ<3>")
	)
	(segment
		(start 39.864538 -225.912426)
		(end 39.002716 -225.912426)
		(width 0.18288)
		(layer "In11.Cu")
		(net "M_D_CPU1_SB_DQ<3>")
	)
	(segment
		(start 94.925896 -240.983008)
		(end 94.911164 -240.991644)
		(width 0.088646)
		(layer "In11.Cu")
		(net "M_D_CPU1_SB_DQ<3>")
	)
	(segment
		(start 59.992006 -227.563426)
		(end 57.637426 -227.563426)
		(width 0.18288)
		(layer "In11.Cu")
		(net "M_D_CPU1_SB_DQ<3>")
	)
	(segment
		(start 30.815788 -226.642676)
		(end 29.792168 -227.666296)
		(width 0.18288)
		(layer "In11.Cu")
		(net "M_D_CPU1_SB_DQ<3>")
	)
	(segment
		(start 51.922426 -225.988626)
		(end 51.726338 -225.792538)
		(width 0.18288)
		(layer "In11.Cu")
		(net "M_D_CPU1_SB_DQ<3>")
	)
	(segment
		(start 63.517272 -229.191312)
		(end 61.619892 -229.191312)
		(width 0.18288)
		(layer "In11.Cu")
		(net "M_D_CPU1_SB_DQ<3>")
	)
	(segment
		(start 90.222578 -240.985548)
		(end 90.212164 -240.991644)
		(width 0.088646)
		(layer "In11.Cu")
		(net "M_D_CPU1_SB_DQ<3>")
	)
	(segment
		(start 96.801178 -240.985548)
		(end 96.790764 -240.991644)
		(width 0.088646)
		(layer "In11.Cu")
		(net "M_D_CPU1_SB_DQ<3>")
	)
	(segment
		(start 36.841938 -225.792538)
		(end 34.961068 -225.792538)
		(width 0.18288)
		(layer "In11.Cu")
		(net "M_D_CPU1_SB_DQ<3>")
	)
	(segment
		(start 38.616636 -225.30816)
		(end 38.301676 -225.30816)
		(width 0.18288)
		(layer "In11.Cu")
		(net "M_D_CPU1_SB_DQ<3>")
	)
	(segment
		(start 26.458418 -229.202234)
		(end 25.825958 -229.202234)
		(width 0.18288)
		(layer "In11.Cu")
		(net "M_D_CPU1_SB_DQ<3>")
	)
	(segment
		(start 51.726338 -225.792538)
		(end 50.048668 -225.792538)
		(width 0.18288)
		(layer "In11.Cu")
		(net "M_D_CPU1_SB_DQ<3>")
	)
	(segment
		(start 33.126426 -226.642676)
		(end 32.059626 -226.642676)
		(width 0.18288)
		(layer "In11.Cu")
		(net "M_D_CPU1_SB_DQ<3>")
	)
	(segment
		(start 65.047368 -229.442772)
		(end 63.768732 -229.442772)
		(width 0.18288)
		(layer "In11.Cu")
		(net "M_D_CPU1_SB_DQ<3>")
	)
	(segment
		(start 21.477224 -230.204772)
		(end 20.889214 -229.616762)
		(width 0.18288)
		(layer "In11.Cu")
		(net "M_D_CPU1_SB_DQ<3>")
	)
	(segment
		(start 48.150018 -226.716336)
		(end 48.076358 -226.642676)
		(width 0.18288)
		(layer "In11.Cu")
		(net "M_D_CPU1_SB_DQ<3>")
	)
	(segment
		(start 89.287096 -240.983008)
		(end 89.272364 -240.991644)
		(width 0.088646)
		(layer "In11.Cu")
		(net "M_D_CPU1_SB_DQ<3>")
	)
	(segment
		(start 45.02785 -227.563426)
		(end 42.778426 -227.563426)
		(width 0.18288)
		(layer "In11.Cu")
		(net "M_D_CPU1_SB_DQ<3>")
	)
	(segment
		(start 23.532592 -229.629462)
		(end 23.339552 -229.436422)
		(width 0.18288)
		(layer "In11.Cu")
		(net "M_D_CPU1_SB_DQ<3>")
	)
	(segment
		(start 23.339552 -229.436422)
		(end 23.024592 -229.436422)
		(width 0.18288)
		(layer "In11.Cu")
		(net "M_D_CPU1_SB_DQ<3>")
	)
	(segment
		(start 29.792168 -227.666296)
		(end 29.470096 -227.666296)
		(width 0.18288)
		(layer "In11.Cu")
		(net "M_D_CPU1_SB_DQ<3>")
	)
	(segment
		(start 66.895472 -230.201978)
		(end 66.516758 -230.045006)
		(width 0.18288)
		(layer "In11.Cu")
		(net "M_D_CPU1_SB_DQ<3>")
	)
	(segment
		(start 28.846526 -228.289866)
		(end 27.370786 -228.289866)
		(width 0.18288)
		(layer "In11.Cu")
		(net "M_D_CPU1_SB_DQ<3>")
	)
	(segment
		(start 84.386166 -239.414304)
		(end 84.21878 -239.414304)
		(width 0.088646)
		(layer "In11.Cu")
		(net "M_D_CPU1_SB_DQ<3>")
	)
	(segment
		(start 66.516758 -230.045006)
		(end 65.649602 -230.045006)
		(width 0.18288)
		(layer "In11.Cu")
		(net "M_D_CPU1_SB_DQ<3>")
	)
	(segment
		(start 53.13045 -225.432112)
		(end 53.13045 -225.795586)
		(width 0.18288)
		(layer "In11.Cu")
		(net "M_D_CPU1_SB_DQ<3>")
	)
	(segment
		(start 82.37347 -237.936786)
		(end 74.633328 -237.936786)
		(width 0.18288)
		(layer "In11.Cu")
		(net "M_D_CPU1_SB_DQ<3>")
	)
	(segment
		(start 82.741262 -237.936786)
		(end 82.37347 -237.936786)
		(width 0.088646)
		(layer "In11.Cu")
		(net "M_D_CPU1_SB_DQ<3>")
	)
	(segment
		(start 53.83149 -225.432112)
		(end 53.63845 -225.239072)
		(width 0.18288)
		(layer "In11.Cu")
		(net "M_D_CPU1_SB_DQ<3>")
	)
	(segment
		(start 87.488014 -240.177574)
		(end 87.473282 -240.168938)
		(width 0.088646)
		(layer "In11.Cu")
		(net "M_D_CPU1_SB_DQ<3>")
	)
	(segment
		(start 38.108636 -225.5012)
		(end 38.108636 -225.719386)
		(width 0.18288)
		(layer "In11.Cu")
		(net "M_D_CPU1_SB_DQ<3>")
	)
	(segment
		(start 74.633328 -237.936786)
		(end 66.895472 -230.201978)
		(width 0.18288)
		(layer "In11.Cu")
		(net "M_D_CPU1_SB_DQ<3>")
	)
	(segment
		(start 65.649602 -230.045006)
		(end 65.047368 -229.442772)
		(width 0.18288)
		(layer "In11.Cu")
		(net "M_D_CPU1_SB_DQ<3>")
	)
	(segment
		(start 91.162124 -240.985548)
		(end 91.15171 -240.991644)
		(width 0.088646)
		(layer "In11.Cu")
		(net "M_D_CPU1_SB_DQ<3>")
	)
	(segment
		(start 87.958168 -240.991644)
		(end 87.949278 -240.986564)
		(width 0.088646)
		(layer "In11.Cu")
		(net "M_D_CPU1_SB_DQ<3>")
	)
	(segment
		(start 22.638512 -230.204772)
		(end 21.477224 -230.204772)
		(width 0.18288)
		(layer "In11.Cu")
		(net "M_D_CPU1_SB_DQ<3>")
	)
	(segment
		(start 98.008694 -240.624106)
		(end 97.97034 -240.7158)
		(width 0.088646)
		(layer "In11.Cu")
		(net "M_D_CPU1_SB_DQ<3>")
	)
	(segment
		(start 38.301676 -225.30816)
		(end 38.108636 -225.5012)
		(width 0.18288)
		(layer "In11.Cu")
		(net "M_D_CPU1_SB_DQ<3>")
	)
	(segment
		(start 37.915596 -225.912426)
		(end 36.961826 -225.912426)
		(width 0.18288)
		(layer "In11.Cu")
		(net "M_D_CPU1_SB_DQ<3>")
	)
	(segment
		(start 38.108636 -225.719386)
		(end 37.915596 -225.912426)
		(width 0.18288)
		(layer "In11.Cu")
		(net "M_D_CPU1_SB_DQ<3>")
	)
	(segment
		(start 95.865696 -240.983008)
		(end 95.850964 -240.991644)
		(width 0.088646)
		(layer "In11.Cu")
		(net "M_D_CPU1_SB_DQ<3>")
	)
	(segment
		(start 86.548214 -240.177574)
		(end 86.539324 -240.172494)
		(width 0.088646)
		(layer "In11.Cu")
		(net "M_D_CPU1_SB_DQ<3>")
	)
	(segment
		(start 38.809676 -225.719386)
		(end 38.809676 -225.5012)
		(width 0.18288)
		(layer "In11.Cu")
		(net "M_D_CPU1_SB_DQ<3>")
	)
	(segment
		(start 48.076358 -226.642676)
		(end 45.9486 -226.642676)
		(width 0.18288)
		(layer "In11.Cu")
		(net "M_D_CPU1_SB_DQ<3>")
	)
	(segment
		(start 32.059626 -226.642676)
		(end 32.057848 -226.640898)
		(width 0.18288)
		(layer "In11.Cu")
		(net "M_D_CPU1_SB_DQ<3>")
	)
	(segment
		(start 53.63845 -225.239072)
		(end 53.32349 -225.239072)
		(width 0.18288)
		(layer "In11.Cu")
		(net "M_D_CPU1_SB_DQ<3>")
	)
	(segment
		(start 36.961826 -225.912426)
		(end 36.841938 -225.792538)
		(width 0.18288)
		(layer "In11.Cu")
		(net "M_D_CPU1_SB_DQ<3>")
	)
	(segment
		(start 98.685096 -240.351564)
		(end 98.670364 -240.342928)
		(width 0.088646)
		(layer "In11.Cu")
		(net "M_D_CPU1_SB_DQ<3>")
	)
	(segment
		(start 63.768732 -229.442772)
		(end 63.517272 -229.191312)
		(width 0.18288)
		(layer "In11.Cu")
		(net "M_D_CPU1_SB_DQ<3>")
	)
	(segment
		(start 86.360762 -239.853216)
		(end 86.360762 -239.837722)
		(width 0.088646)
		(layer "In11.Cu")
		(net "M_D_CPU1_SB_DQ<3>")
	)
	(segment
		(start 33.335976 -226.852226)
		(end 33.126426 -226.642676)
		(width 0.18288)
		(layer "In11.Cu")
		(net "M_D_CPU1_SB_DQ<3>")
	)
	(segment
		(start 100.007166 -240.572036)
		(end 99.610164 -240.342928)
		(width 0.088646)
		(layer "In11.Cu")
		(net "M_D_CPU1_SB_DQ<3>")
	)
	(segment
		(start 23.725632 -230.204772)
		(end 23.532592 -230.011732)
		(width 0.18288)
		(layer "In11.Cu")
		(net "M_D_CPU1_SB_DQ<3>")
	)
	(segment
		(start 55.224426 -225.988626)
		(end 54.02453 -225.988626)
		(width 0.18288)
		(layer "In11.Cu")
		(net "M_D_CPU1_SB_DQ<3>")
	)
	(arc
		(start 84.573364 -239.363758)
		(mid 84.483092 -239.401357)
		(end 84.386166 -239.414304)
		(width 0.088646)
		(layer "In11.Cu")
		(net "M_D_CPU1_SB_DQ<3>")
	)
	(arc
		(start 95.476568 -240.991644)
		(mid 95.202369 -240.915809)
		(end 94.925896 -240.983008)
		(width 0.088646)
		(layer "In11.Cu")
		(net "M_D_CPU1_SB_DQ<3>")
	)
	(arc
		(start 98.093022 -240.49863)
		(mid 98.044764 -240.557269)
		(end 98.008694 -240.624106)
		(width 0.088646)
		(layer "In11.Cu")
		(net "M_D_CPU1_SB_DQ<3>")
	)
	(arc
		(start 100.362766 -240.667286)
		(mid 100.178697 -240.643062)
		(end 100.007166 -240.572036)
		(width 0.088646)
		(layer "In11.Cu")
		(net "M_D_CPU1_SB_DQ<3>")
	)
	(arc
		(start 87.473282 -240.168938)
		(mid 87.196841 -240.101772)
		(end 86.92261 -240.177574)
		(width 0.088646)
		(layer "In11.Cu")
		(net "M_D_CPU1_SB_DQ<3>")
	)
	(arc
		(start 95.850964 -240.991644)
		(mid 95.663766 -241.041787)
		(end 95.476568 -240.991644)
		(width 0.088646)
		(layer "In11.Cu")
		(net "M_D_CPU1_SB_DQ<3>")
	)
	(arc
		(start 91.717368 -240.991644)
		(mid 91.440555 -240.915774)
		(end 91.162124 -240.985548)
		(width 0.088646)
		(layer "In11.Cu")
		(net "M_D_CPU1_SB_DQ<3>")
	)
	(arc
		(start 90.777314 -240.991644)
		(mid 90.500755 -240.915901)
		(end 90.222578 -240.985548)
		(width 0.088646)
		(layer "In11.Cu")
		(net "M_D_CPU1_SB_DQ<3>")
	)
	(arc
		(start 99.235768 -240.342928)
		(mid 98.961539 -240.418853)
		(end 98.685096 -240.351564)
		(width 0.088646)
		(layer "In11.Cu")
		(net "M_D_CPU1_SB_DQ<3>")
	)
	(arc
		(start 92.091764 -240.991644)
		(mid 91.904566 -241.041787)
		(end 91.717368 -240.991644)
		(width 0.088646)
		(layer "In11.Cu")
		(net "M_D_CPU1_SB_DQ<3>")
	)
	(arc
		(start 90.212164 -240.991644)
		(mid 90.024966 -241.041787)
		(end 89.837768 -240.991644)
		(width 0.088646)
		(layer "In11.Cu")
		(net "M_D_CPU1_SB_DQ<3>")
	)
	(arc
		(start 86.539324 -240.172494)
		(mid 86.40841 -240.036134)
		(end 86.360762 -239.853216)
		(width 0.088646)
		(layer "In11.Cu")
		(net "M_D_CPU1_SB_DQ<3>")
	)
	(arc
		(start 96.790764 -240.991644)
		(mid 96.603566 -241.041787)
		(end 96.416368 -240.991644)
		(width 0.088646)
		(layer "In11.Cu")
		(net "M_D_CPU1_SB_DQ<3>")
	)
	(arc
		(start 91.15171 -240.991644)
		(mid 90.964512 -241.041787)
		(end 90.777314 -240.991644)
		(width 0.088646)
		(layer "In11.Cu")
		(net "M_D_CPU1_SB_DQ<3>")
	)
	(arc
		(start 93.971364 -240.991644)
		(mid 93.784166 -241.041787)
		(end 93.596968 -240.991644)
		(width 0.088646)
		(layer "In11.Cu")
		(net "M_D_CPU1_SB_DQ<3>")
	)
	(arc
		(start 85.513164 -239.363758)
		(mid 85.325966 -239.413901)
		(end 85.138768 -239.363758)
		(width 0.088646)
		(layer "In11.Cu")
		(net "M_D_CPU1_SB_DQ<3>")
	)
	(arc
		(start 93.031564 -240.991644)
		(mid 92.844366 -241.041787)
		(end 92.657168 -240.991644)
		(width 0.088646)
		(layer "In11.Cu")
		(net "M_D_CPU1_SB_DQ<3>")
	)
	(arc
		(start 86.078568 -239.363758)
		(mid 85.804369 -239.287923)
		(end 85.527896 -239.355122)
		(width 0.088646)
		(layer "In11.Cu")
		(net "M_D_CPU1_SB_DQ<3>")
	)
	(arc
		(start 97.739962 -240.985802)
		(mid 97.735172 -240.988782)
		(end 97.73031 -240.991644)
		(width 0.088646)
		(layer "In11.Cu")
		(net "M_D_CPU1_SB_DQ<3>")
	)
	(arc
		(start 89.837768 -240.991644)
		(mid 89.563569 -240.915809)
		(end 89.287096 -240.983008)
		(width 0.088646)
		(layer "In11.Cu")
		(net "M_D_CPU1_SB_DQ<3>")
	)
	(arc
		(start 88.332564 -240.991644)
		(mid 88.145366 -241.041787)
		(end 87.958168 -240.991644)
		(width 0.088646)
		(layer "In11.Cu")
		(net "M_D_CPU1_SB_DQ<3>")
	)
	(arc
		(start 93.596968 -240.991644)
		(mid 93.322769 -240.915809)
		(end 93.046296 -240.983008)
		(width 0.088646)
		(layer "In11.Cu")
		(net "M_D_CPU1_SB_DQ<3>")
	)
	(arc
		(start 94.536768 -240.991644)
		(mid 94.254066 -240.915868)
		(end 93.971364 -240.991644)
		(width 0.088646)
		(layer "In11.Cu")
		(net "M_D_CPU1_SB_DQ<3>")
	)
	(arc
		(start 94.911164 -240.991644)
		(mid 94.723966 -241.041787)
		(end 94.536768 -240.991644)
		(width 0.088646)
		(layer "In11.Cu")
		(net "M_D_CPU1_SB_DQ<3>")
	)
	(arc
		(start 86.360762 -239.837722)
		(mid 86.281392 -239.563988)
		(end 86.078568 -239.363758)
		(width 0.088646)
		(layer "In11.Cu")
		(net "M_D_CPU1_SB_DQ<3>")
	)
	(arc
		(start 99.610164 -240.342928)
		(mid 99.422966 -240.292785)
		(end 99.235768 -240.342928)
		(width 0.088646)
		(layer "In11.Cu")
		(net "M_D_CPU1_SB_DQ<3>")
	)
	(arc
		(start 87.770716 -240.653062)
		(mid 87.691497 -240.378377)
		(end 87.488014 -240.177574)
		(width 0.088646)
		(layer "In11.Cu")
		(net "M_D_CPU1_SB_DQ<3>")
	)
	(arc
		(start 88.897968 -240.991644)
		(mid 88.623769 -240.915809)
		(end 88.347296 -240.983008)
		(width 0.088646)
		(layer "In11.Cu")
		(net "M_D_CPU1_SB_DQ<3>")
	)
	(arc
		(start 92.657168 -240.991644)
		(mid 92.382969 -240.915809)
		(end 92.106496 -240.983008)
		(width 0.088646)
		(layer "In11.Cu")
		(net "M_D_CPU1_SB_DQ<3>")
	)
	(arc
		(start 98.295968 -240.342928)
		(mid 98.189388 -240.414122)
		(end 98.093022 -240.49863)
		(width 0.088646)
		(layer "In11.Cu")
		(net "M_D_CPU1_SB_DQ<3>")
	)
	(arc
		(start 98.670364 -240.342928)
		(mid 98.483166 -240.292785)
		(end 98.295968 -240.342928)
		(width 0.088646)
		(layer "In11.Cu")
		(net "M_D_CPU1_SB_DQ<3>")
	)
	(arc
		(start 86.92261 -240.177574)
		(mid 86.735412 -240.227717)
		(end 86.548214 -240.177574)
		(width 0.088646)
		(layer "In11.Cu")
		(net "M_D_CPU1_SB_DQ<3>")
	)
	(arc
		(start 97.355914 -240.991644)
		(mid 97.079355 -240.915901)
		(end 96.801178 -240.985548)
		(width 0.088646)
		(layer "In11.Cu")
		(net "M_D_CPU1_SB_DQ<3>")
	)
	(arc
		(start 87.949278 -240.986564)
		(mid 87.818364 -240.850204)
		(end 87.770716 -240.667286)
		(width 0.088646)
		(layer "In11.Cu")
		(net "M_D_CPU1_SB_DQ<3>")
	)
	(arc
		(start 85.138768 -239.363758)
		(mid 84.864569 -239.287923)
		(end 84.588096 -239.355122)
		(width 0.088646)
		(layer "In11.Cu")
		(net "M_D_CPU1_SB_DQ<3>")
	)
	(arc
		(start 97.97034 -240.7158)
		(mid 97.876285 -240.868826)
		(end 97.739962 -240.985802)
		(width 0.088646)
		(layer "In11.Cu")
		(net "M_D_CPU1_SB_DQ<3>")
	)
	(arc
		(start 97.73031 -240.991644)
		(mid 97.543112 -241.041787)
		(end 97.355914 -240.991644)
		(width 0.088646)
		(layer "In11.Cu")
		(net "M_D_CPU1_SB_DQ<3>")
	)
	(arc
		(start 89.272364 -240.991644)
		(mid 89.085166 -241.041787)
		(end 88.897968 -240.991644)
		(width 0.088646)
		(layer "In11.Cu")
		(net "M_D_CPU1_SB_DQ<3>")
	)
	(arc
		(start 96.416368 -240.991644)
		(mid 96.142169 -240.915809)
		(end 95.865696 -240.983008)
		(width 0.088646)
		(layer "In11.Cu")
		(net "M_D_CPU1_SB_DQ<3>")
	)
	(segment
		(start 18.968212 -195.616576)
		(end 19.784314 -195.616576)
		(width 0.20066)
		(layer "F.Cu")
		(net "M_D_CPU1_SB_DQ<31>")
	)
	(segment
		(start 14.574266 -196.041518)
		(end 14.812264 -196.041518)
		(width 0.101854)
		(layer "F.Cu")
		(net "M_D_CPU1_SB_DQ<31>")
	)
	(segment
		(start 14.20622 -196.055742)
		(end 14.560042 -196.055742)
		(width 0.20066)
		(layer "F.Cu")
		(net "M_D_CPU1_SB_DQ<31>")
	)
	(segment
		(start 99.892866 -228.99497)
		(end 99.892612 -228.994716)
		(width 0.20066)
		(layer "F.Cu")
		(net "M_D_CPU1_SB_DQ<31>")
	)
	(segment
		(start 17.578578 -195.89242)
		(end 17.578578 -195.740782)
		(width 0.20066)
		(layer "F.Cu")
		(net "M_D_CPU1_SB_DQ<31>")
	)
	(segment
		(start 14.812264 -196.041518)
		(end 16.885158 -196.041518)
		(width 0.1016)
		(layer "F.Cu")
		(net "M_D_CPU1_SB_DQ<31>")
	)
	(segment
		(start 18.760694 -195.824094)
		(end 18.968212 -195.616576)
		(width 0.20066)
		(layer "F.Cu")
		(net "M_D_CPU1_SB_DQ<31>")
	)
	(segment
		(start 14.063726 -195.74256)
		(end 14.063726 -195.913248)
		(width 0.20066)
		(layer "F.Cu")
		(net "M_D_CPU1_SB_DQ<31>")
	)
	(segment
		(start 12.240514 -195.616576)
		(end 13.937742 -195.616576)
		(width 0.20066)
		(layer "F.Cu")
		(net "M_D_CPU1_SB_DQ<31>")
	)
	(segment
		(start 99.892612 -228.994716)
		(end 99.892612 -228.45903)
		(width 0.20066)
		(layer "F.Cu")
		(net "M_D_CPU1_SB_DQ<31>")
	)
	(segment
		(start 14.560042 -196.055742)
		(end 14.574266 -196.041518)
		(width 0.101854)
		(layer "F.Cu")
		(net "M_D_CPU1_SB_DQ<31>")
	)
	(segment
		(start 17.42948 -196.041518)
		(end 17.578578 -195.89242)
		(width 0.20066)
		(layer "F.Cu")
		(net "M_D_CPU1_SB_DQ<31>")
	)
	(segment
		(start 17.707102 -195.612258)
		(end 18.102326 -195.612258)
		(width 0.20066)
		(layer "F.Cu")
		(net "M_D_CPU1_SB_DQ<31>")
	)
	(segment
		(start 18.314162 -195.824094)
		(end 18.760694 -195.824094)
		(width 0.20066)
		(layer "F.Cu")
		(net "M_D_CPU1_SB_DQ<31>")
	)
	(segment
		(start 14.063726 -195.913248)
		(end 14.20622 -196.055742)
		(width 0.20066)
		(layer "F.Cu")
		(net "M_D_CPU1_SB_DQ<31>")
	)
	(segment
		(start 13.937742 -195.616576)
		(end 14.063726 -195.74256)
		(width 0.20066)
		(layer "F.Cu")
		(net "M_D_CPU1_SB_DQ<31>")
	)
	(segment
		(start 18.102326 -195.612258)
		(end 18.314162 -195.824094)
		(width 0.20066)
		(layer "F.Cu")
		(net "M_D_CPU1_SB_DQ<31>")
	)
	(segment
		(start 20.889214 -195.616576)
		(end 19.784314 -195.616576)
		(width 0.20066)
		(layer "F.Cu")
		(net "M_D_CPU1_SB_DQ<31>")
	)
	(segment
		(start 16.885158 -196.041518)
		(end 17.42948 -196.041518)
		(width 0.20066)
		(layer "F.Cu")
		(net "M_D_CPU1_SB_DQ<31>")
	)
	(segment
		(start 17.578578 -195.740782)
		(end 17.707102 -195.612258)
		(width 0.20066)
		(layer "F.Cu")
		(net "M_D_CPU1_SB_DQ<31>")
	)
	(segment
		(start 64.970406 -193.16954)
		(end 64.655446 -193.16954)
		(width 0.18288)
		(layer "In11.Cu")
		(net "M_D_CPU1_SB_DQ<31>")
	)
	(segment
		(start 64.655446 -193.16954)
		(end 64.462406 -193.36258)
		(width 0.18288)
		(layer "In11.Cu")
		(net "M_D_CPU1_SB_DQ<31>")
	)
	(segment
		(start 83.874864 -222.5675)
		(end 83.874864 -221.595442)
		(width 0.088646)
		(layer "In11.Cu")
		(net "M_D_CPU1_SB_DQ<31>")
	)
	(segment
		(start 85.057996 -223.891348)
		(end 85.043264 -223.899984)
		(width 0.088646)
		(layer "In11.Cu")
		(net "M_D_CPU1_SB_DQ<31>")
	)
	(segment
		(start 66.550286 -194.173856)
		(end 65.89395 -193.768472)
		(width 0.18288)
		(layer "In11.Cu")
		(net "M_D_CPU1_SB_DQ<31>")
	)
	(segment
		(start 63.253366 -193.16954)
		(end 63.060326 -193.36258)
		(width 0.18288)
		(layer "In11.Cu")
		(net "M_D_CPU1_SB_DQ<31>")
	)
	(segment
		(start 99.892612 -228.45903)
		(end 99.579684 -228.45903)
		(width 0.088646)
		(layer "In11.Cu")
		(net "M_D_CPU1_SB_DQ<31>")
	)
	(segment
		(start 99.518216 -226.831144)
		(end 99.518216 -226.821238)
		(width 0.088646)
		(layer "In11.Cu")
		(net "M_D_CPU1_SB_DQ<31>")
	)
	(segment
		(start 93.126814 -225.527616)
		(end 93.112082 -225.51898)
		(width 0.088646)
		(layer "In11.Cu")
		(net "M_D_CPU1_SB_DQ<31>")
	)
	(segment
		(start 61.658246 -193.575432)
		(end 61.465206 -193.768472)
		(width 0.18288)
		(layer "In11.Cu")
		(net "M_D_CPU1_SB_DQ<31>")
	)
	(segment
		(start 62.552326 -193.768472)
		(end 62.359286 -193.575432)
		(width 0.18288)
		(layer "In11.Cu")
		(net "M_D_CPU1_SB_DQ<31>")
	)
	(segment
		(start 65.163446 -193.36258)
		(end 64.970406 -193.16954)
		(width 0.18288)
		(layer "In11.Cu")
		(net "M_D_CPU1_SB_DQ<31>")
	)
	(segment
		(start 61.465206 -193.768472)
		(end 26.058876 -193.768472)
		(width 0.18288)
		(layer "In11.Cu")
		(net "M_D_CPU1_SB_DQ<31>")
	)
	(segment
		(start 99.048316 -226.017328)
		(end 99.048316 -226.003104)
		(width 0.088646)
		(layer "In11.Cu")
		(net "M_D_CPU1_SB_DQ<31>")
	)
	(segment
		(start 26.058876 -193.768472)
		(end 23.17369 -194.740022)
		(width 0.18288)
		(layer "In11.Cu")
		(net "M_D_CPU1_SB_DQ<31>")
	)
	(segment
		(start 78.416404 -215.464644)
		(end 78.416404 -211.23529)
		(width 0.18288)
		(layer "In11.Cu")
		(net "M_D_CPU1_SB_DQ<31>")
	)
	(segment
		(start 63.761366 -193.575432)
		(end 63.761366 -193.36258)
		(width 0.18288)
		(layer "In11.Cu")
		(net "M_D_CPU1_SB_DQ<31>")
	)
	(segment
		(start 62.166246 -193.16954)
		(end 61.851286 -193.16954)
		(width 0.18288)
		(layer "In11.Cu")
		(net "M_D_CPU1_SB_DQ<31>")
	)
	(segment
		(start 95.946214 -225.527616)
		(end 95.931482 -225.51898)
		(width 0.088646)
		(layer "In11.Cu")
		(net "M_D_CPU1_SB_DQ<31>")
	)
	(segment
		(start 84.2899 -223.56953)
		(end 83.874864 -222.5675)
		(width 0.088646)
		(layer "In11.Cu")
		(net "M_D_CPU1_SB_DQ<31>")
	)
	(segment
		(start 92.187014 -225.527616)
		(end 92.172282 -225.51898)
		(width 0.088646)
		(layer "In11.Cu")
		(net "M_D_CPU1_SB_DQ<31>")
	)
	(segment
		(start 90.307414 -225.527616)
		(end 90.292682 -225.51898)
		(width 0.088646)
		(layer "In11.Cu")
		(net "M_D_CPU1_SB_DQ<31>")
	)
	(segment
		(start 62.867286 -193.768472)
		(end 62.552326 -193.768472)
		(width 0.18288)
		(layer "In11.Cu")
		(net "M_D_CPU1_SB_DQ<31>")
	)
	(segment
		(start 88.897968 -224.7138)
		(end 88.889078 -224.70872)
		(width 0.088646)
		(layer "In11.Cu")
		(net "M_D_CPU1_SB_DQ<31>")
	)
	(segment
		(start 84.856066 -223.95053)
		(end 84.6709 -223.95053)
		(width 0.088646)
		(layer "In11.Cu")
		(net "M_D_CPU1_SB_DQ<31>")
	)
	(segment
		(start 99.579684 -228.45903)
		(end 99.522534 -228.40188)
		(width 0.088646)
		(layer "In11.Cu")
		(net "M_D_CPU1_SB_DQ<31>")
	)
	(segment
		(start 83.399376 -220.447616)
		(end 83.304634 -220.352874)
		(width 0.088646)
		(layer "In11.Cu")
		(net "M_D_CPU1_SB_DQ<31>")
	)
	(segment
		(start 99.235768 -226.341686)
		(end 99.226878 -226.336606)
		(width 0.088646)
		(layer "In11.Cu")
		(net "M_D_CPU1_SB_DQ<31>")
	)
	(segment
		(start 95.006414 -225.527616)
		(end 94.991682 -225.51898)
		(width 0.088646)
		(layer "In11.Cu")
		(net "M_D_CPU1_SB_DQ<31>")
	)
	(segment
		(start 64.462406 -193.36258)
		(end 64.462406 -193.575432)
		(width 0.18288)
		(layer "In11.Cu")
		(net "M_D_CPU1_SB_DQ<31>")
	)
	(segment
		(start 22.721316 -195.192396)
		(end 21.313394 -195.192396)
		(width 0.18288)
		(layer "In11.Cu")
		(net "M_D_CPU1_SB_DQ<31>")
	)
	(segment
		(start 65.356486 -193.768472)
		(end 65.163446 -193.575432)
		(width 0.18288)
		(layer "In11.Cu")
		(net "M_D_CPU1_SB_DQ<31>")
	)
	(segment
		(start 64.462406 -193.575432)
		(end 64.269366 -193.768472)
		(width 0.18288)
		(layer "In11.Cu")
		(net "M_D_CPU1_SB_DQ<31>")
	)
	(segment
		(start 64.269366 -193.768472)
		(end 63.954406 -193.768472)
		(width 0.18288)
		(layer "In11.Cu")
		(net "M_D_CPU1_SB_DQ<31>")
	)
	(segment
		(start 71.768716 -204.587602)
		(end 66.550286 -194.173856)
		(width 0.18288)
		(layer "In11.Cu")
		(net "M_D_CPU1_SB_DQ<31>")
	)
	(segment
		(start 61.658246 -193.36258)
		(end 61.658246 -193.575432)
		(width 0.18288)
		(layer "In11.Cu")
		(net "M_D_CPU1_SB_DQ<31>")
	)
	(segment
		(start 99.711764 -227.159058)
		(end 99.696778 -227.150422)
		(width 0.088646)
		(layer "In11.Cu")
		(net "M_D_CPU1_SB_DQ<31>")
	)
	(segment
		(start 97.825814 -225.527616)
		(end 97.811082 -225.51898)
		(width 0.088646)
		(layer "In11.Cu")
		(net "M_D_CPU1_SB_DQ<31>")
	)
	(segment
		(start 84.6709 -223.95053)
		(end 84.2899 -223.56953)
		(width 0.088646)
		(layer "In11.Cu")
		(net "M_D_CPU1_SB_DQ<31>")
	)
	(segment
		(start 21.313394 -195.192396)
		(end 20.889214 -195.616576)
		(width 0.18288)
		(layer "In11.Cu")
		(net "M_D_CPU1_SB_DQ<31>")
	)
	(segment
		(start 63.761366 -193.36258)
		(end 63.568326 -193.16954)
		(width 0.18288)
		(layer "In11.Cu")
		(net "M_D_CPU1_SB_DQ<31>")
	)
	(segment
		(start 62.359286 -193.36258)
		(end 62.166246 -193.16954)
		(width 0.18288)
		(layer "In11.Cu")
		(net "M_D_CPU1_SB_DQ<31>")
	)
	(segment
		(start 61.851286 -193.16954)
		(end 61.658246 -193.36258)
		(width 0.18288)
		(layer "In11.Cu")
		(net "M_D_CPU1_SB_DQ<31>")
	)
	(segment
		(start 83.304634 -220.352874)
		(end 78.416404 -215.464644)
		(width 0.18288)
		(layer "In11.Cu")
		(net "M_D_CPU1_SB_DQ<31>")
	)
	(segment
		(start 65.89395 -193.768472)
		(end 65.356486 -193.768472)
		(width 0.18288)
		(layer "In11.Cu")
		(net "M_D_CPU1_SB_DQ<31>")
	)
	(segment
		(start 65.163446 -193.575432)
		(end 65.163446 -193.36258)
		(width 0.18288)
		(layer "In11.Cu")
		(net "M_D_CPU1_SB_DQ<31>")
	)
	(segment
		(start 23.17369 -194.740022)
		(end 22.721316 -195.192396)
		(width 0.18288)
		(layer "In11.Cu")
		(net "M_D_CPU1_SB_DQ<31>")
	)
	(segment
		(start 83.874864 -221.595442)
		(end 83.399376 -220.447616)
		(width 0.088646)
		(layer "In11.Cu")
		(net "M_D_CPU1_SB_DQ<31>")
	)
	(segment
		(start 63.568326 -193.16954)
		(end 63.253366 -193.16954)
		(width 0.18288)
		(layer "In11.Cu")
		(net "M_D_CPU1_SB_DQ<31>")
	)
	(segment
		(start 94.066614 -225.527616)
		(end 94.051882 -225.51898)
		(width 0.088646)
		(layer "In11.Cu")
		(net "M_D_CPU1_SB_DQ<31>")
	)
	(segment
		(start 78.416404 -211.23529)
		(end 71.768716 -204.587602)
		(width 0.18288)
		(layer "In11.Cu")
		(net "M_D_CPU1_SB_DQ<31>")
	)
	(segment
		(start 62.359286 -193.575432)
		(end 62.359286 -193.36258)
		(width 0.18288)
		(layer "In11.Cu")
		(net "M_D_CPU1_SB_DQ<31>")
	)
	(segment
		(start 96.886014 -225.527616)
		(end 96.871282 -225.51898)
		(width 0.088646)
		(layer "In11.Cu")
		(net "M_D_CPU1_SB_DQ<31>")
	)
	(segment
		(start 63.060326 -193.36258)
		(end 63.060326 -193.575432)
		(width 0.18288)
		(layer "In11.Cu")
		(net "M_D_CPU1_SB_DQ<31>")
	)
	(segment
		(start 63.954406 -193.768472)
		(end 63.761366 -193.575432)
		(width 0.18288)
		(layer "In11.Cu")
		(net "M_D_CPU1_SB_DQ<31>")
	)
	(segment
		(start 99.696524 -228.139752)
		(end 99.705414 -228.134672)
		(width 0.088646)
		(layer "In11.Cu")
		(net "M_D_CPU1_SB_DQ<31>")
	)
	(segment
		(start 89.180416 -225.211894)
		(end 89.180416 -225.193352)
		(width 0.088646)
		(layer "In11.Cu")
		(net "M_D_CPU1_SB_DQ<31>")
	)
	(segment
		(start 63.060326 -193.575432)
		(end 62.867286 -193.768472)
		(width 0.18288)
		(layer "In11.Cu")
		(net "M_D_CPU1_SB_DQ<31>")
	)
	(arc
		(start 85.043264 -223.899984)
		(mid 84.952992 -223.937583)
		(end 84.856066 -223.95053)
		(width 0.088646)
		(layer "In11.Cu")
		(net "M_D_CPU1_SB_DQ<31>")
	)
	(arc
		(start 96.871282 -225.51898)
		(mid 96.594841 -225.451814)
		(end 96.32061 -225.527616)
		(width 0.088646)
		(layer "In11.Cu")
		(net "M_D_CPU1_SB_DQ<31>")
	)
	(arc
		(start 92.56141 -225.527616)
		(mid 92.374212 -225.577759)
		(end 92.187014 -225.527616)
		(width 0.088646)
		(layer "In11.Cu")
		(net "M_D_CPU1_SB_DQ<31>")
	)
	(arc
		(start 94.991682 -225.51898)
		(mid 94.715241 -225.451814)
		(end 94.44101 -225.527616)
		(width 0.088646)
		(layer "In11.Cu")
		(net "M_D_CPU1_SB_DQ<31>")
	)
	(arc
		(start 99.705414 -228.134672)
		(mid 99.988154 -227.648663)
		(end 99.711764 -227.159058)
		(width 0.088646)
		(layer "In11.Cu")
		(net "M_D_CPU1_SB_DQ<31>")
	)
	(arc
		(start 88.889078 -224.70872)
		(mid 88.758164 -224.57236)
		(end 88.710516 -224.389442)
		(width 0.088646)
		(layer "In11.Cu")
		(net "M_D_CPU1_SB_DQ<31>")
	)
	(arc
		(start 94.051882 -225.51898)
		(mid 93.775441 -225.451814)
		(end 93.50121 -225.527616)
		(width 0.088646)
		(layer "In11.Cu")
		(net "M_D_CPU1_SB_DQ<31>")
	)
	(arc
		(start 91.62161 -225.527616)
		(mid 91.434412 -225.577759)
		(end 91.247214 -225.527616)
		(width 0.088646)
		(layer "In11.Cu")
		(net "M_D_CPU1_SB_DQ<31>")
	)
	(arc
		(start 94.44101 -225.527616)
		(mid 94.253812 -225.577759)
		(end 94.066614 -225.527616)
		(width 0.088646)
		(layer "In11.Cu")
		(net "M_D_CPU1_SB_DQ<31>")
	)
	(arc
		(start 90.68181 -225.527616)
		(mid 90.494612 -225.577759)
		(end 90.307414 -225.527616)
		(width 0.088646)
		(layer "In11.Cu")
		(net "M_D_CPU1_SB_DQ<31>")
	)
	(arc
		(start 93.50121 -225.527616)
		(mid 93.314012 -225.577759)
		(end 93.126814 -225.527616)
		(width 0.088646)
		(layer "In11.Cu")
		(net "M_D_CPU1_SB_DQ<31>")
	)
	(arc
		(start 89.74201 -225.527616)
		(mid 89.371287 -225.529708)
		(end 89.180416 -225.211894)
		(width 0.088646)
		(layer "In11.Cu")
		(net "M_D_CPU1_SB_DQ<31>")
	)
	(arc
		(start 85.608668 -223.899984)
		(mid 85.334469 -223.824149)
		(end 85.057996 -223.891348)
		(width 0.088646)
		(layer "In11.Cu")
		(net "M_D_CPU1_SB_DQ<31>")
	)
	(arc
		(start 86.548468 -223.899984)
		(mid 86.265766 -223.824208)
		(end 85.983064 -223.899984)
		(width 0.088646)
		(layer "In11.Cu")
		(net "M_D_CPU1_SB_DQ<31>")
	)
	(arc
		(start 97.811082 -225.51898)
		(mid 97.534641 -225.451814)
		(end 97.26041 -225.527616)
		(width 0.088646)
		(layer "In11.Cu")
		(net "M_D_CPU1_SB_DQ<31>")
	)
	(arc
		(start 93.112082 -225.51898)
		(mid 92.835641 -225.451814)
		(end 92.56141 -225.527616)
		(width 0.088646)
		(layer "In11.Cu")
		(net "M_D_CPU1_SB_DQ<31>")
	)
	(arc
		(start 91.247214 -225.527616)
		(mid 90.964512 -225.451874)
		(end 90.68181 -225.527616)
		(width 0.088646)
		(layer "In11.Cu")
		(net "M_D_CPU1_SB_DQ<31>")
	)
	(arc
		(start 98.20021 -225.527616)
		(mid 98.013012 -225.577759)
		(end 97.825814 -225.527616)
		(width 0.088646)
		(layer "In11.Cu")
		(net "M_D_CPU1_SB_DQ<31>")
	)
	(arc
		(start 89.180416 -225.193352)
		(mid 89.102305 -224.916403)
		(end 88.897968 -224.7138)
		(width 0.088646)
		(layer "In11.Cu")
		(net "M_D_CPU1_SB_DQ<31>")
	)
	(arc
		(start 92.172282 -225.51898)
		(mid 91.895841 -225.451814)
		(end 91.62161 -225.527616)
		(width 0.088646)
		(layer "In11.Cu")
		(net "M_D_CPU1_SB_DQ<31>")
	)
	(arc
		(start 99.522534 -228.40188)
		(mid 99.580653 -228.251639)
		(end 99.696524 -228.139752)
		(width 0.088646)
		(layer "In11.Cu")
		(net "M_D_CPU1_SB_DQ<31>")
	)
	(arc
		(start 99.048316 -226.003104)
		(mid 98.759617 -225.523957)
		(end 98.20021 -225.527616)
		(width 0.088646)
		(layer "In11.Cu")
		(net "M_D_CPU1_SB_DQ<31>")
	)
	(arc
		(start 87.862664 -223.899984)
		(mid 87.675466 -223.950127)
		(end 87.488268 -223.899984)
		(width 0.088646)
		(layer "In11.Cu")
		(net "M_D_CPU1_SB_DQ<31>")
	)
	(arc
		(start 97.26041 -225.527616)
		(mid 97.073212 -225.577759)
		(end 96.886014 -225.527616)
		(width 0.088646)
		(layer "In11.Cu")
		(net "M_D_CPU1_SB_DQ<31>")
	)
	(arc
		(start 90.292682 -225.51898)
		(mid 90.016241 -225.451814)
		(end 89.74201 -225.527616)
		(width 0.088646)
		(layer "In11.Cu")
		(net "M_D_CPU1_SB_DQ<31>")
	)
	(arc
		(start 99.696778 -227.150422)
		(mid 99.565864 -227.014062)
		(end 99.518216 -226.831144)
		(width 0.088646)
		(layer "In11.Cu")
		(net "M_D_CPU1_SB_DQ<31>")
	)
	(arc
		(start 96.32061 -225.527616)
		(mid 96.133412 -225.577759)
		(end 95.946214 -225.527616)
		(width 0.088646)
		(layer "In11.Cu")
		(net "M_D_CPU1_SB_DQ<31>")
	)
	(arc
		(start 86.922864 -223.899984)
		(mid 86.735666 -223.950127)
		(end 86.548468 -223.899984)
		(width 0.088646)
		(layer "In11.Cu")
		(net "M_D_CPU1_SB_DQ<31>")
	)
	(arc
		(start 88.710516 -224.389442)
		(mid 88.427899 -223.899983)
		(end 87.862664 -223.899984)
		(width 0.088646)
		(layer "In11.Cu")
		(net "M_D_CPU1_SB_DQ<31>")
	)
	(arc
		(start 99.226878 -226.336606)
		(mid 99.095964 -226.200246)
		(end 99.048316 -226.017328)
		(width 0.088646)
		(layer "In11.Cu")
		(net "M_D_CPU1_SB_DQ<31>")
	)
	(arc
		(start 95.931482 -225.51898)
		(mid 95.655041 -225.451814)
		(end 95.38081 -225.527616)
		(width 0.088646)
		(layer "In11.Cu")
		(net "M_D_CPU1_SB_DQ<31>")
	)
	(arc
		(start 95.38081 -225.527616)
		(mid 95.193612 -225.577759)
		(end 95.006414 -225.527616)
		(width 0.088646)
		(layer "In11.Cu")
		(net "M_D_CPU1_SB_DQ<31>")
	)
	(arc
		(start 87.488268 -223.899984)
		(mid 87.205566 -223.824208)
		(end 86.922864 -223.899984)
		(width 0.088646)
		(layer "In11.Cu")
		(net "M_D_CPU1_SB_DQ<31>")
	)
	(arc
		(start 99.518216 -226.821238)
		(mid 99.440105 -226.544289)
		(end 99.235768 -226.341686)
		(width 0.088646)
		(layer "In11.Cu")
		(net "M_D_CPU1_SB_DQ<31>")
	)
	(arc
		(start 85.983064 -223.899984)
		(mid 85.795866 -223.950127)
		(end 85.608668 -223.899984)
		(width 0.088646)
		(layer "In11.Cu")
		(net "M_D_CPU1_SB_DQ<31>")
	)
	(segment
		(start 13.387578 -197.316598)
		(end 13.82268 -196.881496)
		(width 0.20066)
		(layer "F.Cu")
		(net "M_D_CPU1_SB_DQ<30>")
	)
	(segment
		(start 17.518126 -196.891656)
		(end 17.66189 -197.03542)
		(width 0.20066)
		(layer "F.Cu")
		(net "M_D_CPU1_SB_DQ<30>")
	)
	(segment
		(start 18.46961 -197.316598)
		(end 19.784314 -197.316598)
		(width 0.20066)
		(layer "F.Cu")
		(net "M_D_CPU1_SB_DQ<30>")
	)
	(segment
		(start 17.829276 -197.528434)
		(end 18.257774 -197.528434)
		(width 0.20066)
		(layer "F.Cu")
		(net "M_D_CPU1_SB_DQ<30>")
	)
	(segment
		(start 16.885158 -196.891656)
		(end 17.518126 -196.891656)
		(width 0.20066)
		(layer "F.Cu")
		(net "M_D_CPU1_SB_DQ<30>")
	)
	(segment
		(start 14.570202 -196.891656)
		(end 14.825218 -196.891656)
		(width 0.101854)
		(layer "F.Cu")
		(net "M_D_CPU1_SB_DQ<30>")
	)
	(segment
		(start 17.66189 -197.03542)
		(end 17.66189 -197.361048)
		(width 0.20066)
		(layer "F.Cu")
		(net "M_D_CPU1_SB_DQ<30>")
	)
	(segment
		(start 18.257774 -197.528434)
		(end 18.46961 -197.316598)
		(width 0.20066)
		(layer "F.Cu")
		(net "M_D_CPU1_SB_DQ<30>")
	)
	(segment
		(start 13.82268 -196.881496)
		(end 14.560042 -196.881496)
		(width 0.20066)
		(layer "F.Cu")
		(net "M_D_CPU1_SB_DQ<30>")
	)
	(segment
		(start 100.362512 -229.808786)
		(end 100.362766 -229.808532)
		(width 0.20066)
		(layer "F.Cu")
		(net "M_D_CPU1_SB_DQ<30>")
	)
	(segment
		(start 14.825218 -196.891656)
		(end 16.885158 -196.891656)
		(width 0.1016)
		(layer "F.Cu")
		(net "M_D_CPU1_SB_DQ<30>")
	)
	(segment
		(start 17.66189 -197.361048)
		(end 17.829276 -197.528434)
		(width 0.20066)
		(layer "F.Cu")
		(net "M_D_CPU1_SB_DQ<30>")
	)
	(segment
		(start 100.362766 -229.808532)
		(end 100.362766 -229.272846)
		(width 0.20066)
		(layer "F.Cu")
		(net "M_D_CPU1_SB_DQ<30>")
	)
	(segment
		(start 20.889214 -197.316598)
		(end 19.784314 -197.316598)
		(width 0.20066)
		(layer "F.Cu")
		(net "M_D_CPU1_SB_DQ<30>")
	)
	(segment
		(start 12.240514 -197.316598)
		(end 13.387578 -197.316598)
		(width 0.20066)
		(layer "F.Cu")
		(net "M_D_CPU1_SB_DQ<30>")
	)
	(segment
		(start 14.560042 -196.881496)
		(end 14.570202 -196.891656)
		(width 0.101854)
		(layer "F.Cu")
		(net "M_D_CPU1_SB_DQ<30>")
	)
	(segment
		(start 93.046296 -226.33305)
		(end 93.031564 -226.341686)
		(width 0.088646)
		(layer "In11.Cu")
		(net "M_D_CPU1_SB_DQ<30>")
	)
	(segment
		(start 31.190184 -194.968114)
		(end 30.963362 -195.194936)
		(width 0.18288)
		(layer "In11.Cu")
		(net "M_D_CPU1_SB_DQ<30>")
	)
	(segment
		(start 37.776404 -196.189092)
		(end 37.016182 -196.189092)
		(width 0.18288)
		(layer "In11.Cu")
		(net "M_D_CPU1_SB_DQ<30>")
	)
	(segment
		(start 84.856066 -224.638108)
		(end 84.577936 -224.638108)
		(width 0.088646)
		(layer "In11.Cu")
		(net "M_D_CPU1_SB_DQ<30>")
	)
	(segment
		(start 88.897968 -226.341686)
		(end 88.889078 -226.336606)
		(width 0.088646)
		(layer "In11.Cu")
		(net "M_D_CPU1_SB_DQ<30>")
	)
	(segment
		(start 97.745296 -226.33305)
		(end 97.730564 -226.341686)
		(width 0.088646)
		(layer "In11.Cu")
		(net "M_D_CPU1_SB_DQ<30>")
	)
	(segment
		(start 82.458052 -221.432882)
		(end 77.053948 -216.028778)
		(width 0.18288)
		(layer "In11.Cu")
		(net "M_D_CPU1_SB_DQ<30>")
	)
	(segment
		(start 86.078568 -224.7138)
		(end 86.068154 -224.707704)
		(width 0.088646)
		(layer "In11.Cu")
		(net "M_D_CPU1_SB_DQ<30>")
	)
	(segment
		(start 36.867846 -196.040756)
		(end 35.461956 -196.040756)
		(width 0.18288)
		(layer "In11.Cu")
		(net "M_D_CPU1_SB_DQ<30>")
	)
	(segment
		(start 55.229506 -195.052696)
		(end 54.07152 -195.052696)
		(width 0.18288)
		(layer "In11.Cu")
		(net "M_D_CPU1_SB_DQ<30>")
	)
	(segment
		(start 92.106496 -226.33305)
		(end 92.091764 -226.341686)
		(width 0.088646)
		(layer "In11.Cu")
		(net "M_D_CPU1_SB_DQ<30>")
	)
	(segment
		(start 46.46041 -195.194428)
		(end 40.947848 -195.194428)
		(width 0.18288)
		(layer "In11.Cu")
		(net "M_D_CPU1_SB_DQ<30>")
	)
	(segment
		(start 39.953184 -196.189092)
		(end 38.863524 -196.189092)
		(width 0.18288)
		(layer "In11.Cu")
		(net "M_D_CPU1_SB_DQ<30>")
	)
	(segment
		(start 25.70734 -195.194936)
		(end 24.713184 -196.189092)
		(width 0.18288)
		(layer "In11.Cu")
		(net "M_D_CPU1_SB_DQ<30>")
	)
	(segment
		(start 38.162484 -195.13042)
		(end 37.969444 -195.32346)
		(width 0.18288)
		(layer "In11.Cu")
		(net "M_D_CPU1_SB_DQ<30>")
	)
	(segment
		(start 22.98065 -196.702426)
		(end 21.503386 -196.702426)
		(width 0.18288)
		(layer "In11.Cu")
		(net "M_D_CPU1_SB_DQ<30>")
	)
	(segment
		(start 88.240616 -225.203258)
		(end 88.240616 -225.193352)
		(width 0.088646)
		(layer "In11.Cu")
		(net "M_D_CPU1_SB_DQ<30>")
	)
	(segment
		(start 38.863524 -196.189092)
		(end 38.670484 -195.996052)
		(width 0.18288)
		(layer "In11.Cu")
		(net "M_D_CPU1_SB_DQ<30>")
	)
	(segment
		(start 91.717368 -226.341686)
		(end 91.706954 -226.33559)
		(width 0.088646)
		(layer "In11.Cu")
		(net "M_D_CPU1_SB_DQ<30>")
	)
	(segment
		(start 63.51905 -195.842128)
		(end 63.23076 -196.130418)
		(width 0.18288)
		(layer "In11.Cu")
		(net "M_D_CPU1_SB_DQ<30>")
	)
	(segment
		(start 24.713184 -196.189092)
		(end 23.493984 -196.189092)
		(width 0.18288)
		(layer "In11.Cu")
		(net "M_D_CPU1_SB_DQ<30>")
	)
	(segment
		(start 21.503386 -196.702426)
		(end 20.889214 -197.316598)
		(width 0.18288)
		(layer "In11.Cu")
		(net "M_D_CPU1_SB_DQ<30>")
	)
	(segment
		(start 33.431226 -195.305426)
		(end 33.093914 -194.968114)
		(width 0.18288)
		(layer "In11.Cu")
		(net "M_D_CPU1_SB_DQ<30>")
	)
	(segment
		(start 59.63285 -196.130418)
		(end 58.706766 -195.204334)
		(width 0.18288)
		(layer "In11.Cu")
		(net "M_D_CPU1_SB_DQ<30>")
	)
	(segment
		(start 88.710516 -226.017328)
		(end 88.710516 -225.998786)
		(width 0.088646)
		(layer "In11.Cu")
		(net "M_D_CPU1_SB_DQ<30>")
	)
	(segment
		(start 63.23076 -196.130418)
		(end 59.63285 -196.130418)
		(width 0.18288)
		(layer "In11.Cu")
		(net "M_D_CPU1_SB_DQ<30>")
	)
	(segment
		(start 47.439834 -195.34251)
		(end 47.101506 -195.004182)
		(width 0.18288)
		(layer "In11.Cu")
		(net "M_D_CPU1_SB_DQ<30>")
	)
	(segment
		(start 88.428068 -225.527616)
		(end 88.419178 -225.522536)
		(width 0.088646)
		(layer "In11.Cu")
		(net "M_D_CPU1_SB_DQ<30>")
	)
	(segment
		(start 64.523366 -195.842128)
		(end 63.51905 -195.842128)
		(width 0.18288)
		(layer "In11.Cu")
		(net "M_D_CPU1_SB_DQ<30>")
	)
	(segment
		(start 46.650656 -195.004182)
		(end 46.46041 -195.194428)
		(width 0.18288)
		(layer "In11.Cu")
		(net "M_D_CPU1_SB_DQ<30>")
	)
	(segment
		(start 84.577936 -224.638108)
		(end 83.427824 -223.487996)
		(width 0.088646)
		(layer "In11.Cu")
		(net "M_D_CPU1_SB_DQ<30>")
	)
	(segment
		(start 40.947848 -195.194428)
		(end 39.953184 -196.189092)
		(width 0.18288)
		(layer "In11.Cu")
		(net "M_D_CPU1_SB_DQ<30>")
	)
	(segment
		(start 83.427824 -223.487996)
		(end 83.427824 -222.12681)
		(width 0.088646)
		(layer "In11.Cu")
		(net "M_D_CPU1_SB_DQ<30>")
	)
	(segment
		(start 66.512186 -197.830948)
		(end 64.523366 -195.842128)
		(width 0.18288)
		(layer "In11.Cu")
		(net "M_D_CPU1_SB_DQ<30>")
	)
	(segment
		(start 99.048316 -227.659184)
		(end 99.048316 -227.635054)
		(width 0.088646)
		(layer "In11.Cu")
		(net "M_D_CPU1_SB_DQ<30>")
	)
	(segment
		(start 83.427824 -222.12681)
		(end 82.733896 -221.432882)
		(width 0.088646)
		(layer "In11.Cu")
		(net "M_D_CPU1_SB_DQ<30>")
	)
	(segment
		(start 53.932328 -195.191888)
		(end 49.933098 -195.191888)
		(width 0.18288)
		(layer "In11.Cu")
		(net "M_D_CPU1_SB_DQ<30>")
	)
	(segment
		(start 23.493984 -196.189092)
		(end 22.98065 -196.702426)
		(width 0.18288)
		(layer "In11.Cu")
		(net "M_D_CPU1_SB_DQ<30>")
	)
	(segment
		(start 37.969444 -195.32346)
		(end 37.969444 -195.996052)
		(width 0.18288)
		(layer "In11.Cu")
		(net "M_D_CPU1_SB_DQ<30>")
	)
	(segment
		(start 82.733896 -221.432882)
		(end 82.597498 -221.432882)
		(width 0.088646)
		(layer "In11.Cu")
		(net "M_D_CPU1_SB_DQ<30>")
	)
	(segment
		(start 99.61753 -228.912674)
		(end 98.909886 -228.83114)
		(width 0.088646)
		(layer "In11.Cu")
		(net "M_D_CPU1_SB_DQ<30>")
	)
	(segment
		(start 98.765868 -227.155502)
		(end 98.756978 -227.150422)
		(width 0.088646)
		(layer "In11.Cu")
		(net "M_D_CPU1_SB_DQ<30>")
	)
	(segment
		(start 96.805496 -226.33305)
		(end 96.790764 -226.341686)
		(width 0.088646)
		(layer "In11.Cu")
		(net "M_D_CPU1_SB_DQ<30>")
	)
	(segment
		(start 47.101506 -195.004182)
		(end 46.650656 -195.004182)
		(width 0.18288)
		(layer "In11.Cu")
		(net "M_D_CPU1_SB_DQ<30>")
	)
	(segment
		(start 82.597498 -221.432882)
		(end 82.458052 -221.432882)
		(width 0.18288)
		(layer "In11.Cu")
		(net "M_D_CPU1_SB_DQ<30>")
	)
	(segment
		(start 93.986096 -226.33305)
		(end 93.971364 -226.341686)
		(width 0.088646)
		(layer "In11.Cu")
		(net "M_D_CPU1_SB_DQ<30>")
	)
	(segment
		(start 38.670484 -195.996052)
		(end 38.670484 -195.32346)
		(width 0.18288)
		(layer "In11.Cu")
		(net "M_D_CPU1_SB_DQ<30>")
	)
	(segment
		(start 94.925896 -226.33305)
		(end 94.911164 -226.341686)
		(width 0.088646)
		(layer "In11.Cu")
		(net "M_D_CPU1_SB_DQ<30>")
	)
	(segment
		(start 54.07152 -195.052696)
		(end 53.932328 -195.191888)
		(width 0.18288)
		(layer "In11.Cu")
		(net "M_D_CPU1_SB_DQ<30>")
	)
	(segment
		(start 49.782476 -195.34251)
		(end 47.439834 -195.34251)
		(width 0.18288)
		(layer "In11.Cu")
		(net "M_D_CPU1_SB_DQ<30>")
	)
	(segment
		(start 77.053948 -211.800186)
		(end 69.600318 -204.346556)
		(width 0.18288)
		(layer "In11.Cu")
		(net "M_D_CPU1_SB_DQ<30>")
	)
	(segment
		(start 49.933098 -195.191888)
		(end 49.782476 -195.34251)
		(width 0.18288)
		(layer "In11.Cu")
		(net "M_D_CPU1_SB_DQ<30>")
	)
	(segment
		(start 34.726626 -195.305426)
		(end 33.431226 -195.305426)
		(width 0.18288)
		(layer "In11.Cu")
		(net "M_D_CPU1_SB_DQ<30>")
	)
	(segment
		(start 98.302064 -226.345242)
		(end 98.295968 -226.341686)
		(width 0.088646)
		(layer "In11.Cu")
		(net "M_D_CPU1_SB_DQ<30>")
	)
	(segment
		(start 37.969444 -195.996052)
		(end 37.776404 -196.189092)
		(width 0.18288)
		(layer "In11.Cu")
		(net "M_D_CPU1_SB_DQ<30>")
	)
	(segment
		(start 69.600318 -204.346556)
		(end 66.512186 -197.830948)
		(width 0.18288)
		(layer "In11.Cu")
		(net "M_D_CPU1_SB_DQ<30>")
	)
	(segment
		(start 37.016182 -196.189092)
		(end 36.867846 -196.040756)
		(width 0.18288)
		(layer "In11.Cu")
		(net "M_D_CPU1_SB_DQ<30>")
	)
	(segment
		(start 58.706766 -195.204334)
		(end 55.381144 -195.204334)
		(width 0.18288)
		(layer "In11.Cu")
		(net "M_D_CPU1_SB_DQ<30>")
	)
	(segment
		(start 90.222578 -226.33559)
		(end 90.212164 -226.341686)
		(width 0.088646)
		(layer "In11.Cu")
		(net "M_D_CPU1_SB_DQ<30>")
	)
	(segment
		(start 55.381144 -195.204334)
		(end 55.229506 -195.052696)
		(width 0.18288)
		(layer "In11.Cu")
		(net "M_D_CPU1_SB_DQ<30>")
	)
	(segment
		(start 77.053948 -216.028778)
		(end 77.053948 -211.800186)
		(width 0.18288)
		(layer "In11.Cu")
		(net "M_D_CPU1_SB_DQ<30>")
	)
	(segment
		(start 33.093914 -194.968114)
		(end 31.190184 -194.968114)
		(width 0.18288)
		(layer "In11.Cu")
		(net "M_D_CPU1_SB_DQ<30>")
	)
	(segment
		(start 98.578416 -228.467666)
		(end 98.578416 -228.450394)
		(width 0.088646)
		(layer "In11.Cu")
		(net "M_D_CPU1_SB_DQ<30>")
	)
	(segment
		(start 38.477444 -195.13042)
		(end 38.162484 -195.13042)
		(width 0.18288)
		(layer "In11.Cu")
		(net "M_D_CPU1_SB_DQ<30>")
	)
	(segment
		(start 38.670484 -195.32346)
		(end 38.477444 -195.13042)
		(width 0.18288)
		(layer "In11.Cu")
		(net "M_D_CPU1_SB_DQ<30>")
	)
	(segment
		(start 30.963362 -195.194936)
		(end 25.70734 -195.194936)
		(width 0.18288)
		(layer "In11.Cu")
		(net "M_D_CPU1_SB_DQ<30>")
	)
	(segment
		(start 35.461956 -196.040756)
		(end 34.726626 -195.305426)
		(width 0.18288)
		(layer "In11.Cu")
		(net "M_D_CPU1_SB_DQ<30>")
	)
	(segment
		(start 89.287096 -226.33305)
		(end 89.272364 -226.341686)
		(width 0.088646)
		(layer "In11.Cu")
		(net "M_D_CPU1_SB_DQ<30>")
	)
	(arc
		(start 95.850964 -226.341686)
		(mid 95.663766 -226.391829)
		(end 95.476568 -226.341686)
		(width 0.088646)
		(layer "In11.Cu")
		(net "M_D_CPU1_SB_DQ<30>")
	)
	(arc
		(start 88.889078 -226.336606)
		(mid 88.758164 -226.200246)
		(end 88.710516 -226.017328)
		(width 0.088646)
		(layer "In11.Cu")
		(net "M_D_CPU1_SB_DQ<30>")
	)
	(arc
		(start 98.756978 -227.150422)
		(mid 98.626064 -227.014062)
		(end 98.578416 -226.831144)
		(width 0.088646)
		(layer "In11.Cu")
		(net "M_D_CPU1_SB_DQ<30>")
	)
	(arc
		(start 98.773234 -228.787706)
		(mid 98.769399 -228.785591)
		(end 98.765614 -228.783388)
		(width 0.088646)
		(layer "In11.Cu")
		(net "M_D_CPU1_SB_DQ<30>")
	)
	(arc
		(start 87.392764 -224.7138)
		(mid 87.205566 -224.763943)
		(end 87.018368 -224.7138)
		(width 0.088646)
		(layer "In11.Cu")
		(net "M_D_CPU1_SB_DQ<30>")
	)
	(arc
		(start 91.706954 -226.33559)
		(mid 91.428522 -226.265744)
		(end 91.15171 -226.341686)
		(width 0.088646)
		(layer "In11.Cu")
		(net "M_D_CPU1_SB_DQ<30>")
	)
	(arc
		(start 85.138514 -224.7138)
		(mid 85.002272 -224.657366)
		(end 84.856066 -224.638108)
		(width 0.088646)
		(layer "In11.Cu")
		(net "M_D_CPU1_SB_DQ<30>")
	)
	(arc
		(start 93.031564 -226.341686)
		(mid 92.844366 -226.391829)
		(end 92.657168 -226.341686)
		(width 0.088646)
		(layer "In11.Cu")
		(net "M_D_CPU1_SB_DQ<30>")
	)
	(arc
		(start 93.596968 -226.341686)
		(mid 93.322769 -226.265851)
		(end 93.046296 -226.33305)
		(width 0.088646)
		(layer "In11.Cu")
		(net "M_D_CPU1_SB_DQ<30>")
	)
	(arc
		(start 94.536768 -226.341686)
		(mid 94.262569 -226.265851)
		(end 93.986096 -226.33305)
		(width 0.088646)
		(layer "In11.Cu")
		(net "M_D_CPU1_SB_DQ<30>")
	)
	(arc
		(start 92.091764 -226.341686)
		(mid 91.904566 -226.391829)
		(end 91.717368 -226.341686)
		(width 0.088646)
		(layer "In11.Cu")
		(net "M_D_CPU1_SB_DQ<30>")
	)
	(arc
		(start 100.362766 -229.272846)
		(mid 100.020628 -229.029699)
		(end 99.61753 -228.912674)
		(width 0.088646)
		(layer "In11.Cu")
		(net "M_D_CPU1_SB_DQ<30>")
	)
	(arc
		(start 86.452964 -224.7138)
		(mid 86.265766 -224.763943)
		(end 86.078568 -224.7138)
		(width 0.088646)
		(layer "In11.Cu")
		(net "M_D_CPU1_SB_DQ<30>")
	)
	(arc
		(start 97.356168 -226.341686)
		(mid 97.081969 -226.265851)
		(end 96.805496 -226.33305)
		(width 0.088646)
		(layer "In11.Cu")
		(net "M_D_CPU1_SB_DQ<30>")
	)
	(arc
		(start 85.51291 -224.7138)
		(mid 85.325712 -224.763943)
		(end 85.138514 -224.7138)
		(width 0.088646)
		(layer "In11.Cu")
		(net "M_D_CPU1_SB_DQ<30>")
	)
	(arc
		(start 98.765614 -228.783388)
		(mid 98.630681 -228.650034)
		(end 98.578416 -228.467666)
		(width 0.088646)
		(layer "In11.Cu")
		(net "M_D_CPU1_SB_DQ<30>")
	)
	(arc
		(start 87.958168 -224.7138)
		(mid 87.675466 -224.638024)
		(end 87.392764 -224.7138)
		(width 0.088646)
		(layer "In11.Cu")
		(net "M_D_CPU1_SB_DQ<30>")
	)
	(arc
		(start 98.765614 -228.134672)
		(mid 98.969095 -227.933868)
		(end 99.048316 -227.659184)
		(width 0.088646)
		(layer "In11.Cu")
		(net "M_D_CPU1_SB_DQ<30>")
	)
	(arc
		(start 88.240616 -225.193352)
		(mid 88.162505 -224.916403)
		(end 87.958168 -224.7138)
		(width 0.088646)
		(layer "In11.Cu")
		(net "M_D_CPU1_SB_DQ<30>")
	)
	(arc
		(start 91.15171 -226.341686)
		(mid 90.964512 -226.391829)
		(end 90.777314 -226.341686)
		(width 0.088646)
		(layer "In11.Cu")
		(net "M_D_CPU1_SB_DQ<30>")
	)
	(arc
		(start 86.068154 -224.707704)
		(mid 85.789722 -224.637858)
		(end 85.51291 -224.7138)
		(width 0.088646)
		(layer "In11.Cu")
		(net "M_D_CPU1_SB_DQ<30>")
	)
	(arc
		(start 92.657168 -226.341686)
		(mid 92.382969 -226.265851)
		(end 92.106496 -226.33305)
		(width 0.088646)
		(layer "In11.Cu")
		(net "M_D_CPU1_SB_DQ<30>")
	)
	(arc
		(start 97.730564 -226.341686)
		(mid 97.543366 -226.391829)
		(end 97.356168 -226.341686)
		(width 0.088646)
		(layer "In11.Cu")
		(net "M_D_CPU1_SB_DQ<30>")
	)
	(arc
		(start 98.909886 -228.83114)
		(mid 98.839454 -228.816043)
		(end 98.773234 -228.787706)
		(width 0.088646)
		(layer "In11.Cu")
		(net "M_D_CPU1_SB_DQ<30>")
	)
	(arc
		(start 88.419178 -225.522536)
		(mid 88.288264 -225.386176)
		(end 88.240616 -225.203258)
		(width 0.088646)
		(layer "In11.Cu")
		(net "M_D_CPU1_SB_DQ<30>")
	)
	(arc
		(start 88.710516 -225.998786)
		(mid 88.630354 -225.726597)
		(end 88.428068 -225.527616)
		(width 0.088646)
		(layer "In11.Cu")
		(net "M_D_CPU1_SB_DQ<30>")
	)
	(arc
		(start 89.272364 -226.341686)
		(mid 89.085166 -226.391829)
		(end 88.897968 -226.341686)
		(width 0.088646)
		(layer "In11.Cu")
		(net "M_D_CPU1_SB_DQ<30>")
	)
	(arc
		(start 90.777314 -226.341686)
		(mid 90.500755 -226.265943)
		(end 90.222578 -226.33559)
		(width 0.088646)
		(layer "In11.Cu")
		(net "M_D_CPU1_SB_DQ<30>")
	)
	(arc
		(start 93.971364 -226.341686)
		(mid 93.784166 -226.391829)
		(end 93.596968 -226.341686)
		(width 0.088646)
		(layer "In11.Cu")
		(net "M_D_CPU1_SB_DQ<30>")
	)
	(arc
		(start 87.018368 -224.7138)
		(mid 86.735666 -224.638024)
		(end 86.452964 -224.7138)
		(width 0.088646)
		(layer "In11.Cu")
		(net "M_D_CPU1_SB_DQ<30>")
	)
	(arc
		(start 96.416368 -226.341686)
		(mid 96.133666 -226.26591)
		(end 95.850964 -226.341686)
		(width 0.088646)
		(layer "In11.Cu")
		(net "M_D_CPU1_SB_DQ<30>")
	)
	(arc
		(start 89.837768 -226.341686)
		(mid 89.563569 -226.265851)
		(end 89.287096 -226.33305)
		(width 0.088646)
		(layer "In11.Cu")
		(net "M_D_CPU1_SB_DQ<30>")
	)
	(arc
		(start 95.476568 -226.341686)
		(mid 95.202369 -226.265851)
		(end 94.925896 -226.33305)
		(width 0.088646)
		(layer "In11.Cu")
		(net "M_D_CPU1_SB_DQ<30>")
	)
	(arc
		(start 98.578416 -226.831144)
		(mid 98.5045 -226.551642)
		(end 98.302064 -226.345242)
		(width 0.088646)
		(layer "In11.Cu")
		(net "M_D_CPU1_SB_DQ<30>")
	)
	(arc
		(start 99.048316 -227.635054)
		(mid 98.970205 -227.358105)
		(end 98.765868 -227.155502)
		(width 0.088646)
		(layer "In11.Cu")
		(net "M_D_CPU1_SB_DQ<30>")
	)
	(arc
		(start 94.911164 -226.341686)
		(mid 94.723966 -226.391829)
		(end 94.536768 -226.341686)
		(width 0.088646)
		(layer "In11.Cu")
		(net "M_D_CPU1_SB_DQ<30>")
	)
	(arc
		(start 90.212164 -226.341686)
		(mid 90.024966 -226.391829)
		(end 89.837768 -226.341686)
		(width 0.088646)
		(layer "In11.Cu")
		(net "M_D_CPU1_SB_DQ<30>")
	)
	(arc
		(start 98.295968 -226.341686)
		(mid 98.021769 -226.265851)
		(end 97.745296 -226.33305)
		(width 0.088646)
		(layer "In11.Cu")
		(net "M_D_CPU1_SB_DQ<30>")
	)
	(arc
		(start 96.790764 -226.341686)
		(mid 96.603566 -226.391829)
		(end 96.416368 -226.341686)
		(width 0.088646)
		(layer "In11.Cu")
		(net "M_D_CPU1_SB_DQ<30>")
	)
	(arc
		(start 98.578416 -228.450394)
		(mid 98.630686 -228.268029)
		(end 98.765614 -228.134672)
		(width 0.088646)
		(layer "In11.Cu")
		(net "M_D_CPU1_SB_DQ<30>")
	)
	(segment
		(start 14.570202 -230.891842)
		(end 14.825218 -230.891842)
		(width 0.101854)
		(layer "F.Cu")
		(net "M_D_CPU1_SB_DQ<2>")
	)
	(segment
		(start 18.257774 -231.52862)
		(end 18.46961 -231.316784)
		(width 0.20066)
		(layer "F.Cu")
		(net "M_D_CPU1_SB_DQ<2>")
	)
	(segment
		(start 18.46961 -231.316784)
		(end 19.784314 -231.316784)
		(width 0.20066)
		(layer "F.Cu")
		(net "M_D_CPU1_SB_DQ<2>")
	)
	(segment
		(start 14.560042 -230.881682)
		(end 14.570202 -230.891842)
		(width 0.101854)
		(layer "F.Cu")
		(net "M_D_CPU1_SB_DQ<2>")
	)
	(segment
		(start 99.892612 -242.016788)
		(end 99.892612 -241.481102)
		(width 0.20066)
		(layer "F.Cu")
		(net "M_D_CPU1_SB_DQ<2>")
	)
	(segment
		(start 16.885158 -230.891842)
		(end 17.518126 -230.891842)
		(width 0.20066)
		(layer "F.Cu")
		(net "M_D_CPU1_SB_DQ<2>")
	)
	(segment
		(start 17.518126 -230.891842)
		(end 17.66189 -231.035606)
		(width 0.20066)
		(layer "F.Cu")
		(net "M_D_CPU1_SB_DQ<2>")
	)
	(segment
		(start 99.892866 -242.017042)
		(end 99.892612 -242.016788)
		(width 0.20066)
		(layer "F.Cu")
		(net "M_D_CPU1_SB_DQ<2>")
	)
	(segment
		(start 13.82268 -230.881682)
		(end 14.560042 -230.881682)
		(width 0.20066)
		(layer "F.Cu")
		(net "M_D_CPU1_SB_DQ<2>")
	)
	(segment
		(start 13.387578 -231.316784)
		(end 13.82268 -230.881682)
		(width 0.20066)
		(layer "F.Cu")
		(net "M_D_CPU1_SB_DQ<2>")
	)
	(segment
		(start 20.889214 -231.316784)
		(end 19.784314 -231.316784)
		(width 0.20066)
		(layer "F.Cu")
		(net "M_D_CPU1_SB_DQ<2>")
	)
	(segment
		(start 17.829276 -231.52862)
		(end 18.257774 -231.52862)
		(width 0.20066)
		(layer "F.Cu")
		(net "M_D_CPU1_SB_DQ<2>")
	)
	(segment
		(start 17.66189 -231.361234)
		(end 17.829276 -231.52862)
		(width 0.20066)
		(layer "F.Cu")
		(net "M_D_CPU1_SB_DQ<2>")
	)
	(segment
		(start 14.825218 -230.891842)
		(end 16.885158 -230.891842)
		(width 0.1016)
		(layer "F.Cu")
		(net "M_D_CPU1_SB_DQ<2>")
	)
	(segment
		(start 12.240514 -231.316784)
		(end 13.387578 -231.316784)
		(width 0.20066)
		(layer "F.Cu")
		(net "M_D_CPU1_SB_DQ<2>")
	)
	(segment
		(start 17.66189 -231.035606)
		(end 17.66189 -231.361234)
		(width 0.20066)
		(layer "F.Cu")
		(net "M_D_CPU1_SB_DQ<2>")
	)
	(segment
		(start 95.946214 -241.80546)
		(end 95.931482 -241.796824)
		(width 0.088646)
		(layer "In11.Cu")
		(net "M_D_CPU1_SB_DQ<2>")
	)
	(segment
		(start 44.327826 -228.808026)
		(end 43.819826 -229.316026)
		(width 0.18288)
		(layer "In11.Cu")
		(net "M_D_CPU1_SB_DQ<2>")
	)
	(segment
		(start 41.330626 -227.995226)
		(end 38.864032 -227.995226)
		(width 0.18288)
		(layer "In11.Cu")
		(net "M_D_CPU1_SB_DQ<2>")
	)
	(segment
		(start 82.996024 -238.952786)
		(end 82.37347 -238.952786)
		(width 0.088646)
		(layer "In11.Cu")
		(net "M_D_CPU1_SB_DQ<2>")
	)
	(segment
		(start 28.681426 -229.951026)
		(end 27.538426 -229.951026)
		(width 0.18288)
		(layer "In11.Cu")
		(net "M_D_CPU1_SB_DQ<2>")
	)
	(segment
		(start 37.969952 -227.24491)
		(end 37.969952 -227.802186)
		(width 0.18288)
		(layer "In11.Cu")
		(net "M_D_CPU1_SB_DQ<2>")
	)
	(segment
		(start 84.129118 -240.08588)
		(end 82.996024 -238.952786)
		(width 0.088646)
		(layer "In11.Cu")
		(net "M_D_CPU1_SB_DQ<2>")
	)
	(segment
		(start 23.40229 -231.259126)
		(end 23.08733 -231.259126)
		(width 0.18288)
		(layer "In11.Cu")
		(net "M_D_CPU1_SB_DQ<2>")
	)
	(segment
		(start 64.9478 -231.043226)
		(end 62.879986 -231.043226)
		(width 0.18288)
		(layer "In11.Cu")
		(net "M_D_CPU1_SB_DQ<2>")
	)
	(segment
		(start 58.755026 -229.417626)
		(end 57.891426 -229.417626)
		(width 0.18288)
		(layer "In11.Cu")
		(net "M_D_CPU1_SB_DQ<2>")
	)
	(segment
		(start 43.819826 -229.316026)
		(end 42.651426 -229.316026)
		(width 0.18288)
		(layer "In11.Cu")
		(net "M_D_CPU1_SB_DQ<2>")
	)
	(segment
		(start 38.864032 -227.995226)
		(end 38.670992 -227.802186)
		(width 0.18288)
		(layer "In11.Cu")
		(net "M_D_CPU1_SB_DQ<2>")
	)
	(segment
		(start 22.70125 -231.919526)
		(end 22.087332 -231.919526)
		(width 0.18288)
		(layer "In11.Cu")
		(net "M_D_CPU1_SB_DQ<2>")
	)
	(segment
		(start 38.162992 -227.05187)
		(end 37.969952 -227.24491)
		(width 0.18288)
		(layer "In11.Cu")
		(net "M_D_CPU1_SB_DQ<2>")
	)
	(segment
		(start 66.602102 -231.780842)
		(end 66.51371 -231.744266)
		(width 0.18288)
		(layer "In11.Cu")
		(net "M_D_CPU1_SB_DQ<2>")
	)
	(segment
		(start 66.51371 -231.744266)
		(end 65.64884 -231.744266)
		(width 0.18288)
		(layer "In11.Cu")
		(net "M_D_CPU1_SB_DQ<2>")
	)
	(segment
		(start 97.825814 -241.80546)
		(end 97.811082 -241.796824)
		(width 0.088646)
		(layer "In11.Cu")
		(net "M_D_CPU1_SB_DQ<2>")
	)
	(segment
		(start 54.525926 -227.944426)
		(end 53.789326 -227.207826)
		(width 0.18288)
		(layer "In11.Cu")
		(net "M_D_CPU1_SB_DQ<2>")
	)
	(segment
		(start 23.59533 -231.452166)
		(end 23.40229 -231.259126)
		(width 0.18288)
		(layer "In11.Cu")
		(net "M_D_CPU1_SB_DQ<2>")
	)
	(segment
		(start 73.766426 -238.952786)
		(end 66.602102 -231.780842)
		(width 0.18288)
		(layer "In11.Cu")
		(net "M_D_CPU1_SB_DQ<2>")
	)
	(segment
		(start 59.728354 -228.884226)
		(end 59.288426 -228.884226)
		(width 0.18288)
		(layer "In11.Cu")
		(net "M_D_CPU1_SB_DQ<2>")
	)
	(segment
		(start 50.308002 -228.342444)
		(end 49.977294 -228.011736)
		(width 0.18288)
		(layer "In11.Cu")
		(net "M_D_CPU1_SB_DQ<2>")
	)
	(segment
		(start 82.37347 -238.952786)
		(end 73.766426 -238.952786)
		(width 0.18288)
		(layer "In11.Cu")
		(net "M_D_CPU1_SB_DQ<2>")
	)
	(segment
		(start 23.78837 -231.919526)
		(end 23.59533 -231.726486)
		(width 0.18288)
		(layer "In11.Cu")
		(net "M_D_CPU1_SB_DQ<2>")
	)
	(segment
		(start 95.006414 -241.80546)
		(end 94.996 -241.799364)
		(width 0.088646)
		(layer "In11.Cu")
		(net "M_D_CPU1_SB_DQ<2>")
	)
	(segment
		(start 92.187014 -241.80546)
		(end 92.172282 -241.796824)
		(width 0.088646)
		(layer "In11.Cu")
		(net "M_D_CPU1_SB_DQ<2>")
	)
	(segment
		(start 27.538426 -229.951026)
		(end 26.586942 -230.90251)
		(width 0.18288)
		(layer "In11.Cu")
		(net "M_D_CPU1_SB_DQ<2>")
	)
	(segment
		(start 30.916626 -228.935026)
		(end 29.697426 -228.935026)
		(width 0.18288)
		(layer "In11.Cu")
		(net "M_D_CPU1_SB_DQ<2>")
	)
	(segment
		(start 98.422206 -241.677444)
		(end 98.20021 -241.80546)
		(width 0.088646)
		(layer "In11.Cu")
		(net "M_D_CPU1_SB_DQ<2>")
	)
	(segment
		(start 31.174182 -229.192582)
		(end 30.916626 -228.935026)
		(width 0.18288)
		(layer "In11.Cu")
		(net "M_D_CPU1_SB_DQ<2>")
	)
	(segment
		(start 37.969952 -227.802186)
		(end 37.776912 -227.995226)
		(width 0.18288)
		(layer "In11.Cu")
		(net "M_D_CPU1_SB_DQ<2>")
	)
	(segment
		(start 48.581564 -228.011736)
		(end 47.400718 -229.192582)
		(width 0.18288)
		(layer "In11.Cu")
		(net "M_D_CPU1_SB_DQ<2>")
	)
	(segment
		(start 91.247214 -241.80546)
		(end 91.232482 -241.796824)
		(width 0.088646)
		(layer "In11.Cu")
		(net "M_D_CPU1_SB_DQ<2>")
	)
	(segment
		(start 88.428068 -241.80546)
		(end 88.413336 -241.796824)
		(width 0.088646)
		(layer "In11.Cu")
		(net "M_D_CPU1_SB_DQ<2>")
	)
	(segment
		(start 87.300816 -241.481102)
		(end 87.300816 -241.471196)
		(width 0.088646)
		(layer "In11.Cu")
		(net "M_D_CPU1_SB_DQ<2>")
	)
	(segment
		(start 23.08733 -231.259126)
		(end 22.89429 -231.452166)
		(width 0.18288)
		(layer "In11.Cu")
		(net "M_D_CPU1_SB_DQ<2>")
	)
	(segment
		(start 49.977294 -228.011736)
		(end 48.581564 -228.011736)
		(width 0.18288)
		(layer "In11.Cu")
		(net "M_D_CPU1_SB_DQ<2>")
	)
	(segment
		(start 89.367614 -241.80546)
		(end 89.352882 -241.796824)
		(width 0.088646)
		(layer "In11.Cu")
		(net "M_D_CPU1_SB_DQ<2>")
	)
	(segment
		(start 46.207934 -229.192582)
		(end 45.823378 -228.808026)
		(width 0.18288)
		(layer "In11.Cu")
		(net "M_D_CPU1_SB_DQ<2>")
	)
	(segment
		(start 65.64884 -231.744266)
		(end 64.9478 -231.043226)
		(width 0.18288)
		(layer "In11.Cu")
		(net "M_D_CPU1_SB_DQ<2>")
	)
	(segment
		(start 87.488268 -241.80546)
		(end 87.479378 -241.80038)
		(width 0.088646)
		(layer "In11.Cu")
		(net "M_D_CPU1_SB_DQ<2>")
	)
	(segment
		(start 38.477952 -227.05187)
		(end 38.162992 -227.05187)
		(width 0.18288)
		(layer "In11.Cu")
		(net "M_D_CPU1_SB_DQ<2>")
	)
	(segment
		(start 36.413186 -228.342444)
		(end 35.220402 -228.342444)
		(width 0.18288)
		(layer "In11.Cu")
		(net "M_D_CPU1_SB_DQ<2>")
	)
	(segment
		(start 38.670992 -227.24491)
		(end 38.477952 -227.05187)
		(width 0.18288)
		(layer "In11.Cu")
		(net "M_D_CPU1_SB_DQ<2>")
	)
	(segment
		(start 51.959002 -228.342444)
		(end 50.308002 -228.342444)
		(width 0.18288)
		(layer "In11.Cu")
		(net "M_D_CPU1_SB_DQ<2>")
	)
	(segment
		(start 85.891116 -240.667286)
		(end 85.891116 -240.653062)
		(width 0.088646)
		(layer "In11.Cu")
		(net "M_D_CPU1_SB_DQ<2>")
	)
	(segment
		(start 94.066868 -241.80546)
		(end 94.056454 -241.799364)
		(width 0.088646)
		(layer "In11.Cu")
		(net "M_D_CPU1_SB_DQ<2>")
	)
	(segment
		(start 86.078568 -240.991644)
		(end 86.069678 -240.986564)
		(width 0.088646)
		(layer "In11.Cu")
		(net "M_D_CPU1_SB_DQ<2>")
	)
	(segment
		(start 22.89429 -231.452166)
		(end 22.89429 -231.726486)
		(width 0.18288)
		(layer "In11.Cu")
		(net "M_D_CPU1_SB_DQ<2>")
	)
	(segment
		(start 33.342326 -228.163374)
		(end 32.313118 -229.192582)
		(width 0.18288)
		(layer "In11.Cu")
		(net "M_D_CPU1_SB_DQ<2>")
	)
	(segment
		(start 57.891426 -229.417626)
		(end 56.418226 -227.944426)
		(width 0.18288)
		(layer "In11.Cu")
		(net "M_D_CPU1_SB_DQ<2>")
	)
	(segment
		(start 61.73724 -230.893112)
		(end 59.728354 -228.884226)
		(width 0.18288)
		(layer "In11.Cu")
		(net "M_D_CPU1_SB_DQ<2>")
	)
	(segment
		(start 45.823378 -228.808026)
		(end 44.327826 -228.808026)
		(width 0.18288)
		(layer "In11.Cu")
		(net "M_D_CPU1_SB_DQ<2>")
	)
	(segment
		(start 22.087332 -231.919526)
		(end 21.48459 -231.316784)
		(width 0.18288)
		(layer "In11.Cu")
		(net "M_D_CPU1_SB_DQ<2>")
	)
	(segment
		(start 21.48459 -231.316784)
		(end 20.889214 -231.316784)
		(width 0.18288)
		(layer "In11.Cu")
		(net "M_D_CPU1_SB_DQ<2>")
	)
	(segment
		(start 35.041332 -228.163374)
		(end 33.342326 -228.163374)
		(width 0.18288)
		(layer "In11.Cu")
		(net "M_D_CPU1_SB_DQ<2>")
	)
	(segment
		(start 35.220402 -228.342444)
		(end 35.041332 -228.163374)
		(width 0.18288)
		(layer "In11.Cu")
		(net "M_D_CPU1_SB_DQ<2>")
	)
	(segment
		(start 85.608414 -240.177574)
		(end 85.593682 -240.168938)
		(width 0.088646)
		(layer "In11.Cu")
		(net "M_D_CPU1_SB_DQ<2>")
	)
	(segment
		(start 29.697426 -228.935026)
		(end 28.681426 -229.951026)
		(width 0.18288)
		(layer "In11.Cu")
		(net "M_D_CPU1_SB_DQ<2>")
	)
	(segment
		(start 47.400718 -229.192582)
		(end 46.207934 -229.192582)
		(width 0.18288)
		(layer "In11.Cu")
		(net "M_D_CPU1_SB_DQ<2>")
	)
	(segment
		(start 26.055574 -230.90251)
		(end 25.038558 -231.919526)
		(width 0.18288)
		(layer "In11.Cu")
		(net "M_D_CPU1_SB_DQ<2>")
	)
	(segment
		(start 23.59533 -231.726486)
		(end 23.59533 -231.452166)
		(width 0.18288)
		(layer "In11.Cu")
		(net "M_D_CPU1_SB_DQ<2>")
	)
	(segment
		(start 90.307414 -241.80546)
		(end 90.292682 -241.796824)
		(width 0.088646)
		(layer "In11.Cu")
		(net "M_D_CPU1_SB_DQ<2>")
	)
	(segment
		(start 62.879986 -231.043226)
		(end 62.729872 -230.893112)
		(width 0.18288)
		(layer "In11.Cu")
		(net "M_D_CPU1_SB_DQ<2>")
	)
	(segment
		(start 38.670992 -227.802186)
		(end 38.670992 -227.24491)
		(width 0.18288)
		(layer "In11.Cu")
		(net "M_D_CPU1_SB_DQ<2>")
	)
	(segment
		(start 84.326222 -240.08588)
		(end 84.129118 -240.08588)
		(width 0.088646)
		(layer "In11.Cu")
		(net "M_D_CPU1_SB_DQ<2>")
	)
	(segment
		(start 22.89429 -231.726486)
		(end 22.70125 -231.919526)
		(width 0.18288)
		(layer "In11.Cu")
		(net "M_D_CPU1_SB_DQ<2>")
	)
	(segment
		(start 93.126814 -241.80546)
		(end 93.112082 -241.796824)
		(width 0.088646)
		(layer "In11.Cu")
		(net "M_D_CPU1_SB_DQ<2>")
	)
	(segment
		(start 56.418226 -227.944426)
		(end 54.525926 -227.944426)
		(width 0.18288)
		(layer "In11.Cu")
		(net "M_D_CPU1_SB_DQ<2>")
	)
	(segment
		(start 62.729872 -230.893112)
		(end 61.73724 -230.893112)
		(width 0.18288)
		(layer "In11.Cu")
		(net "M_D_CPU1_SB_DQ<2>")
	)
	(segment
		(start 99.892612 -241.481102)
		(end 99.601528 -241.481102)
		(width 0.088646)
		(layer "In11.Cu")
		(net "M_D_CPU1_SB_DQ<2>")
	)
	(segment
		(start 42.651426 -229.316026)
		(end 41.330626 -227.995226)
		(width 0.18288)
		(layer "In11.Cu")
		(net "M_D_CPU1_SB_DQ<2>")
	)
	(segment
		(start 25.038558 -231.919526)
		(end 23.78837 -231.919526)
		(width 0.18288)
		(layer "In11.Cu")
		(net "M_D_CPU1_SB_DQ<2>")
	)
	(segment
		(start 26.586942 -230.90251)
		(end 26.055574 -230.90251)
		(width 0.18288)
		(layer "In11.Cu")
		(net "M_D_CPU1_SB_DQ<2>")
	)
	(segment
		(start 53.09362 -227.207826)
		(end 51.959002 -228.342444)
		(width 0.18288)
		(layer "In11.Cu")
		(net "M_D_CPU1_SB_DQ<2>")
	)
	(segment
		(start 53.789326 -227.207826)
		(end 53.09362 -227.207826)
		(width 0.18288)
		(layer "In11.Cu")
		(net "M_D_CPU1_SB_DQ<2>")
	)
	(segment
		(start 32.313118 -229.192582)
		(end 31.174182 -229.192582)
		(width 0.18288)
		(layer "In11.Cu")
		(net "M_D_CPU1_SB_DQ<2>")
	)
	(segment
		(start 88.43645 -241.810286)
		(end 88.428068 -241.80546)
		(width 0.088646)
		(layer "In11.Cu")
		(net "M_D_CPU1_SB_DQ<2>")
	)
	(segment
		(start 36.760404 -227.995226)
		(end 36.413186 -228.342444)
		(width 0.18288)
		(layer "In11.Cu")
		(net "M_D_CPU1_SB_DQ<2>")
	)
	(segment
		(start 37.776912 -227.995226)
		(end 36.760404 -227.995226)
		(width 0.18288)
		(layer "In11.Cu")
		(net "M_D_CPU1_SB_DQ<2>")
	)
	(segment
		(start 59.288426 -228.884226)
		(end 58.755026 -229.417626)
		(width 0.18288)
		(layer "In11.Cu")
		(net "M_D_CPU1_SB_DQ<2>")
	)
	(segment
		(start 96.886014 -241.80546)
		(end 96.871282 -241.796824)
		(width 0.088646)
		(layer "In11.Cu")
		(net "M_D_CPU1_SB_DQ<2>")
	)
	(arc
		(start 90.68181 -241.80546)
		(mid 90.494612 -241.855603)
		(end 90.307414 -241.80546)
		(width 0.088646)
		(layer "In11.Cu")
		(net "M_D_CPU1_SB_DQ<2>")
	)
	(arc
		(start 88.80221 -241.80546)
		(mid 88.619959 -241.855571)
		(end 88.43645 -241.810286)
		(width 0.088646)
		(layer "In11.Cu")
		(net "M_D_CPU1_SB_DQ<2>")
	)
	(arc
		(start 92.56141 -241.80546)
		(mid 92.374212 -241.855603)
		(end 92.187014 -241.80546)
		(width 0.088646)
		(layer "In11.Cu")
		(net "M_D_CPU1_SB_DQ<2>")
	)
	(arc
		(start 87.479378 -241.80038)
		(mid 87.348464 -241.66402)
		(end 87.300816 -241.481102)
		(width 0.088646)
		(layer "In11.Cu")
		(net "M_D_CPU1_SB_DQ<2>")
	)
	(arc
		(start 87.862664 -241.80546)
		(mid 87.675466 -241.855603)
		(end 87.488268 -241.80546)
		(width 0.088646)
		(layer "In11.Cu")
		(net "M_D_CPU1_SB_DQ<2>")
	)
	(arc
		(start 94.441264 -241.80546)
		(mid 94.254066 -241.855603)
		(end 94.066868 -241.80546)
		(width 0.088646)
		(layer "In11.Cu")
		(net "M_D_CPU1_SB_DQ<2>")
	)
	(arc
		(start 89.352882 -241.796824)
		(mid 89.076407 -241.729504)
		(end 88.80221 -241.80546)
		(width 0.088646)
		(layer "In11.Cu")
		(net "M_D_CPU1_SB_DQ<2>")
	)
	(arc
		(start 97.26041 -241.80546)
		(mid 97.073212 -241.855603)
		(end 96.886014 -241.80546)
		(width 0.088646)
		(layer "In11.Cu")
		(net "M_D_CPU1_SB_DQ<2>")
	)
	(arc
		(start 88.413336 -241.796824)
		(mid 88.136861 -241.729504)
		(end 87.862664 -241.80546)
		(width 0.088646)
		(layer "In11.Cu")
		(net "M_D_CPU1_SB_DQ<2>")
	)
	(arc
		(start 92.172282 -241.796824)
		(mid 91.895807 -241.729504)
		(end 91.62161 -241.80546)
		(width 0.088646)
		(layer "In11.Cu")
		(net "M_D_CPU1_SB_DQ<2>")
	)
	(arc
		(start 98.20021 -241.80546)
		(mid 98.013012 -241.855603)
		(end 97.825814 -241.80546)
		(width 0.088646)
		(layer "In11.Cu")
		(net "M_D_CPU1_SB_DQ<2>")
	)
	(arc
		(start 95.931482 -241.796824)
		(mid 95.655007 -241.729504)
		(end 95.38081 -241.80546)
		(width 0.088646)
		(layer "In11.Cu")
		(net "M_D_CPU1_SB_DQ<2>")
	)
	(arc
		(start 99.27717 -241.29365)
		(mid 98.861075 -241.117756)
		(end 98.578416 -241.47018)
		(width 0.088646)
		(layer "In11.Cu")
		(net "M_D_CPU1_SB_DQ<2>")
	)
	(arc
		(start 96.32061 -241.80546)
		(mid 96.133412 -241.855603)
		(end 95.946214 -241.80546)
		(width 0.088646)
		(layer "In11.Cu")
		(net "M_D_CPU1_SB_DQ<2>")
	)
	(arc
		(start 94.056454 -241.799364)
		(mid 93.778022 -241.729518)
		(end 93.50121 -241.80546)
		(width 0.088646)
		(layer "In11.Cu")
		(net "M_D_CPU1_SB_DQ<2>")
	)
	(arc
		(start 87.018368 -240.991644)
		(mid 86.735666 -240.915868)
		(end 86.452964 -240.991644)
		(width 0.088646)
		(layer "In11.Cu")
		(net "M_D_CPU1_SB_DQ<2>")
	)
	(arc
		(start 93.50121 -241.80546)
		(mid 93.314012 -241.855603)
		(end 93.126814 -241.80546)
		(width 0.088646)
		(layer "In11.Cu")
		(net "M_D_CPU1_SB_DQ<2>")
	)
	(arc
		(start 99.601528 -241.481102)
		(mid 99.414208 -241.430872)
		(end 99.27717 -241.29365)
		(width 0.088646)
		(layer "In11.Cu")
		(net "M_D_CPU1_SB_DQ<2>")
	)
	(arc
		(start 95.38081 -241.80546)
		(mid 95.193612 -241.855603)
		(end 95.006414 -241.80546)
		(width 0.088646)
		(layer "In11.Cu")
		(net "M_D_CPU1_SB_DQ<2>")
	)
	(arc
		(start 94.996 -241.799364)
		(mid 94.717822 -241.729641)
		(end 94.441264 -241.80546)
		(width 0.088646)
		(layer "In11.Cu")
		(net "M_D_CPU1_SB_DQ<2>")
	)
	(arc
		(start 93.112082 -241.796824)
		(mid 92.835607 -241.729504)
		(end 92.56141 -241.80546)
		(width 0.088646)
		(layer "In11.Cu")
		(net "M_D_CPU1_SB_DQ<2>")
	)
	(arc
		(start 98.578416 -241.47018)
		(mid 98.55687 -241.552441)
		(end 98.5012 -241.616738)
		(width 0.088646)
		(layer "In11.Cu")
		(net "M_D_CPU1_SB_DQ<2>")
	)
	(arc
		(start 91.62161 -241.80546)
		(mid 91.434412 -241.855603)
		(end 91.247214 -241.80546)
		(width 0.088646)
		(layer "In11.Cu")
		(net "M_D_CPU1_SB_DQ<2>")
	)
	(arc
		(start 84.668614 -240.177574)
		(mid 84.503456 -240.109169)
		(end 84.326222 -240.08588)
		(width 0.088646)
		(layer "In11.Cu")
		(net "M_D_CPU1_SB_DQ<2>")
	)
	(arc
		(start 87.300816 -241.471196)
		(mid 87.222705 -241.194247)
		(end 87.018368 -240.991644)
		(width 0.088646)
		(layer "In11.Cu")
		(net "M_D_CPU1_SB_DQ<2>")
	)
	(arc
		(start 90.292682 -241.796824)
		(mid 90.016207 -241.729504)
		(end 89.74201 -241.80546)
		(width 0.088646)
		(layer "In11.Cu")
		(net "M_D_CPU1_SB_DQ<2>")
	)
	(arc
		(start 98.5012 -241.616738)
		(mid 98.463696 -241.649685)
		(end 98.422206 -241.677444)
		(width 0.088646)
		(layer "In11.Cu")
		(net "M_D_CPU1_SB_DQ<2>")
	)
	(arc
		(start 85.891116 -240.653062)
		(mid 85.811897 -240.378377)
		(end 85.608414 -240.177574)
		(width 0.088646)
		(layer "In11.Cu")
		(net "M_D_CPU1_SB_DQ<2>")
	)
	(arc
		(start 89.74201 -241.80546)
		(mid 89.554812 -241.855603)
		(end 89.367614 -241.80546)
		(width 0.088646)
		(layer "In11.Cu")
		(net "M_D_CPU1_SB_DQ<2>")
	)
	(arc
		(start 97.811082 -241.796824)
		(mid 97.534607 -241.729504)
		(end 97.26041 -241.80546)
		(width 0.088646)
		(layer "In11.Cu")
		(net "M_D_CPU1_SB_DQ<2>")
	)
	(arc
		(start 86.069678 -240.986564)
		(mid 85.938764 -240.850204)
		(end 85.891116 -240.667286)
		(width 0.088646)
		(layer "In11.Cu")
		(net "M_D_CPU1_SB_DQ<2>")
	)
	(arc
		(start 91.232482 -241.796824)
		(mid 90.956007 -241.729504)
		(end 90.68181 -241.80546)
		(width 0.088646)
		(layer "In11.Cu")
		(net "M_D_CPU1_SB_DQ<2>")
	)
	(arc
		(start 96.871282 -241.796824)
		(mid 96.594807 -241.729504)
		(end 96.32061 -241.80546)
		(width 0.088646)
		(layer "In11.Cu")
		(net "M_D_CPU1_SB_DQ<2>")
	)
	(arc
		(start 85.593682 -240.168938)
		(mid 85.317241 -240.101772)
		(end 85.04301 -240.177574)
		(width 0.088646)
		(layer "In11.Cu")
		(net "M_D_CPU1_SB_DQ<2>")
	)
	(arc
		(start 85.04301 -240.177574)
		(mid 84.855812 -240.227717)
		(end 84.668614 -240.177574)
		(width 0.088646)
		(layer "In11.Cu")
		(net "M_D_CPU1_SB_DQ<2>")
	)
	(arc
		(start 86.452964 -240.991644)
		(mid 86.265766 -241.041787)
		(end 86.078568 -240.991644)
		(width 0.088646)
		(layer "In11.Cu")
		(net "M_D_CPU1_SB_DQ<2>")
	)
	(segment
		(start 98.953066 -228.99497)
		(end 98.952812 -228.994716)
		(width 0.20066)
		(layer "F.Cu")
		(net "M_D_CPU1_SB_DQ<29>")
	)
	(segment
		(start 9.474708 -196.466714)
		(end 9.686036 -196.678042)
		(width 0.20066)
		(layer "F.Cu")
		(net "M_D_CPU1_SB_DQ<29>")
	)
	(segment
		(start 13.110718 -196.041772)
		(end 13.441426 -196.041772)
		(width 0.101854)
		(layer "F.Cu")
		(net "M_D_CPU1_SB_DQ<29>")
	)
	(segment
		(start 10.344912 -196.195442)
		(end 10.507472 -196.032882)
		(width 0.20066)
		(layer "F.Cu")
		(net "M_D_CPU1_SB_DQ<29>")
	)
	(segment
		(start 98.952812 -228.994716)
		(end 98.952812 -228.45903)
		(width 0.20066)
		(layer "F.Cu")
		(net "M_D_CPU1_SB_DQ<29>")
	)
	(segment
		(start 10.507472 -196.032882)
		(end 11.11631 -196.032882)
		(width 0.20066)
		(layer "F.Cu")
		(net "M_D_CPU1_SB_DQ<29>")
	)
	(segment
		(start 11.11631 -196.032882)
		(end 11.1252 -196.041772)
		(width 0.1016)
		(layer "F.Cu")
		(net "M_D_CPU1_SB_DQ<29>")
	)
	(segment
		(start 10.19048 -196.678042)
		(end 10.344912 -196.52361)
		(width 0.20066)
		(layer "F.Cu")
		(net "M_D_CPU1_SB_DQ<29>")
	)
	(segment
		(start 14.04493 -196.466714)
		(end 15.684246 -196.466714)
		(width 0.20066)
		(layer "F.Cu")
		(net "M_D_CPU1_SB_DQ<29>")
	)
	(segment
		(start 13.619988 -196.041772)
		(end 14.04493 -196.466714)
		(width 0.20066)
		(layer "F.Cu")
		(net "M_D_CPU1_SB_DQ<29>")
	)
	(segment
		(start 10.344912 -196.52361)
		(end 10.344912 -196.195442)
		(width 0.20066)
		(layer "F.Cu")
		(net "M_D_CPU1_SB_DQ<29>")
	)
	(segment
		(start 11.1252 -196.041772)
		(end 13.110718 -196.041772)
		(width 0.1016)
		(layer "F.Cu")
		(net "M_D_CPU1_SB_DQ<29>")
	)
	(segment
		(start 9.686036 -196.678042)
		(end 10.19048 -196.678042)
		(width 0.20066)
		(layer "F.Cu")
		(net "M_D_CPU1_SB_DQ<29>")
	)
	(segment
		(start 8.140446 -196.466714)
		(end 9.474708 -196.466714)
		(width 0.20066)
		(layer "F.Cu")
		(net "M_D_CPU1_SB_DQ<29>")
	)
	(segment
		(start 16.789146 -196.466714)
		(end 15.684246 -196.466714)
		(width 0.20066)
		(layer "F.Cu")
		(net "M_D_CPU1_SB_DQ<29>")
	)
	(segment
		(start 13.441426 -196.041772)
		(end 13.619988 -196.041772)
		(width 0.20066)
		(layer "F.Cu")
		(net "M_D_CPU1_SB_DQ<29>")
	)
	(segment
		(start 83.66887 -221.653608)
		(end 82.880962 -220.8657)
		(width 0.088646)
		(layer "In11.Cu")
		(net "M_D_CPU1_SB_DQ<29>")
	)
	(segment
		(start 98.679254 -225.69805)
		(end 98.670364 -225.69297)
		(width 0.088646)
		(layer "In11.Cu")
		(net "M_D_CPU1_SB_DQ<29>")
	)
	(segment
		(start 98.952812 -228.45903)
		(end 99.26574 -228.45903)
		(width 0.088646)
		(layer "In11.Cu")
		(net "M_D_CPU1_SB_DQ<29>")
	)
	(segment
		(start 19.969226 -196.04228)
		(end 19.776694 -195.962524)
		(width 0.18288)
		(layer "In11.Cu")
		(net "M_D_CPU1_SB_DQ<29>")
	)
	(segment
		(start 77.754226 -211.509864)
		(end 70.717664 -204.473302)
		(width 0.18288)
		(layer "In11.Cu")
		(net "M_D_CPU1_SB_DQ<29>")
	)
	(segment
		(start 92.106496 -225.701606)
		(end 92.091764 -225.69297)
		(width 0.088646)
		(layer "In11.Cu")
		(net "M_D_CPU1_SB_DQ<29>")
	)
	(segment
		(start 66.813938 -196.424296)
		(end 65.378584 -194.988942)
		(width 0.18288)
		(layer "In11.Cu")
		(net "M_D_CPU1_SB_DQ<29>")
	)
	(segment
		(start 21.627592 -196.101716)
		(end 21.484082 -196.04228)
		(width 0.18288)
		(layer "In11.Cu")
		(net "M_D_CPU1_SB_DQ<29>")
	)
	(segment
		(start 86.078568 -224.065084)
		(end 86.068154 -224.07118)
		(width 0.088646)
		(layer "In11.Cu")
		(net "M_D_CPU1_SB_DQ<29>")
	)
	(segment
		(start 83.66887 -223.239838)
		(end 83.66887 -221.653608)
		(width 0.088646)
		(layer "In11.Cu")
		(net "M_D_CPU1_SB_DQ<29>")
	)
	(segment
		(start 64.101218 -194.292982)
		(end 26.200354 -194.292982)
		(width 0.18288)
		(layer "In11.Cu")
		(net "M_D_CPU1_SB_DQ<29>")
	)
	(segment
		(start 84.85632 -224.140776)
		(end 84.569554 -224.140776)
		(width 0.088646)
		(layer "In11.Cu")
		(net "M_D_CPU1_SB_DQ<29>")
	)
	(segment
		(start 19.776694 -195.962524)
		(end 18.032984 -195.962524)
		(width 0.18288)
		(layer "In11.Cu")
		(net "M_D_CPU1_SB_DQ<29>")
	)
	(segment
		(start 88.341454 -224.070164)
		(end 88.332564 -224.065084)
		(width 0.088646)
		(layer "In11.Cu")
		(net "M_D_CPU1_SB_DQ<29>")
	)
	(segment
		(start 93.046296 -225.701606)
		(end 93.031564 -225.69297)
		(width 0.088646)
		(layer "In11.Cu")
		(net "M_D_CPU1_SB_DQ<29>")
	)
	(segment
		(start 88.520016 -224.399348)
		(end 88.520016 -224.389442)
		(width 0.088646)
		(layer "In11.Cu")
		(net "M_D_CPU1_SB_DQ<29>")
	)
	(segment
		(start 77.754226 -215.738964)
		(end 77.754226 -211.509864)
		(width 0.18288)
		(layer "In11.Cu")
		(net "M_D_CPU1_SB_DQ<29>")
	)
	(segment
		(start 95.865696 -225.701606)
		(end 95.850964 -225.69297)
		(width 0.088646)
		(layer "In11.Cu")
		(net "M_D_CPU1_SB_DQ<29>")
	)
	(segment
		(start 99.60991 -227.969318)
		(end 99.6188 -227.964238)
		(width 0.088646)
		(layer "In11.Cu")
		(net "M_D_CPU1_SB_DQ<29>")
	)
	(segment
		(start 18.032984 -195.962524)
		(end 16.789146 -196.466714)
		(width 0.18288)
		(layer "In11.Cu")
		(net "M_D_CPU1_SB_DQ<29>")
	)
	(segment
		(start 98.857816 -226.027234)
		(end 98.857816 -226.017328)
		(width 0.088646)
		(layer "In11.Cu")
		(net "M_D_CPU1_SB_DQ<29>")
	)
	(segment
		(start 22.319234 -196.101716)
		(end 21.627592 -196.101716)
		(width 0.18288)
		(layer "In11.Cu")
		(net "M_D_CPU1_SB_DQ<29>")
	)
	(segment
		(start 99.6188 -227.325682)
		(end 99.60991 -227.320602)
		(width 0.088646)
		(layer "In11.Cu")
		(net "M_D_CPU1_SB_DQ<29>")
	)
	(segment
		(start 93.986096 -225.701606)
		(end 93.971364 -225.69297)
		(width 0.088646)
		(layer "In11.Cu")
		(net "M_D_CPU1_SB_DQ<29>")
	)
	(segment
		(start 89.287096 -225.701606)
		(end 89.272364 -225.69297)
		(width 0.088646)
		(layer "In11.Cu")
		(net "M_D_CPU1_SB_DQ<29>")
	)
	(segment
		(start 70.717664 -204.473302)
		(end 66.813938 -196.424296)
		(width 0.18288)
		(layer "In11.Cu")
		(net "M_D_CPU1_SB_DQ<29>")
	)
	(segment
		(start 99.149154 -226.511866)
		(end 99.140264 -226.506786)
		(width 0.088646)
		(layer "In11.Cu")
		(net "M_D_CPU1_SB_DQ<29>")
	)
	(segment
		(start 23.149306 -195.7578)
		(end 22.319234 -196.101716)
		(width 0.18288)
		(layer "In11.Cu")
		(net "M_D_CPU1_SB_DQ<29>")
	)
	(segment
		(start 84.346034 -223.917256)
		(end 84.346034 -223.917002)
		(width 0.088646)
		(layer "In11.Cu")
		(net "M_D_CPU1_SB_DQ<29>")
	)
	(segment
		(start 97.745296 -225.701606)
		(end 97.730564 -225.69297)
		(width 0.088646)
		(layer "In11.Cu")
		(net "M_D_CPU1_SB_DQ<29>")
	)
	(segment
		(start 23.7363 -195.170806)
		(end 23.149306 -195.7578)
		(width 0.18288)
		(layer "In11.Cu")
		(net "M_D_CPU1_SB_DQ<29>")
	)
	(segment
		(start 82.880962 -220.8657)
		(end 77.754226 -215.738964)
		(width 0.18288)
		(layer "In11.Cu")
		(net "M_D_CPU1_SB_DQ<29>")
	)
	(segment
		(start 26.200354 -194.292982)
		(end 23.7363 -195.170806)
		(width 0.18288)
		(layer "In11.Cu")
		(net "M_D_CPU1_SB_DQ<29>")
	)
	(segment
		(start 65.378584 -194.988942)
		(end 64.101218 -194.292982)
		(width 0.18288)
		(layer "In11.Cu")
		(net "M_D_CPU1_SB_DQ<29>")
	)
	(segment
		(start 88.989662 -225.217482)
		(end 88.989662 -225.194622)
		(width 0.088646)
		(layer "In11.Cu")
		(net "M_D_CPU1_SB_DQ<29>")
	)
	(segment
		(start 96.805496 -225.701606)
		(end 96.790764 -225.69297)
		(width 0.088646)
		(layer "In11.Cu")
		(net "M_D_CPU1_SB_DQ<29>")
	)
	(segment
		(start 90.222578 -225.699066)
		(end 90.212164 -225.69297)
		(width 0.088646)
		(layer "In11.Cu")
		(net "M_D_CPU1_SB_DQ<29>")
	)
	(segment
		(start 94.925896 -225.701606)
		(end 94.911164 -225.69297)
		(width 0.088646)
		(layer "In11.Cu")
		(net "M_D_CPU1_SB_DQ<29>")
	)
	(segment
		(start 84.346034 -223.917002)
		(end 83.66887 -223.239838)
		(width 0.088646)
		(layer "In11.Cu")
		(net "M_D_CPU1_SB_DQ<29>")
	)
	(segment
		(start 84.569554 -224.140776)
		(end 84.346034 -223.917256)
		(width 0.088646)
		(layer "In11.Cu")
		(net "M_D_CPU1_SB_DQ<29>")
	)
	(segment
		(start 21.484082 -196.04228)
		(end 19.969226 -196.04228)
		(width 0.18288)
		(layer "In11.Cu")
		(net "M_D_CPU1_SB_DQ<29>")
	)
	(segment
		(start 91.162124 -225.699066)
		(end 91.15171 -225.69297)
		(width 0.088646)
		(layer "In11.Cu")
		(net "M_D_CPU1_SB_DQ<29>")
	)
	(segment
		(start 99.327716 -226.846638)
		(end 99.327716 -226.831144)
		(width 0.088646)
		(layer "In11.Cu")
		(net "M_D_CPU1_SB_DQ<29>")
	)
	(segment
		(start 99.26574 -228.45903)
		(end 99.330764 -228.394006)
		(width 0.088646)
		(layer "In11.Cu")
		(net "M_D_CPU1_SB_DQ<29>")
	)
	(arc
		(start 87.018368 -224.065084)
		(mid 86.735666 -224.14086)
		(end 86.452964 -224.065084)
		(width 0.088646)
		(layer "In11.Cu")
		(net "M_D_CPU1_SB_DQ<29>")
	)
	(arc
		(start 92.657168 -225.69297)
		(mid 92.382939 -225.768895)
		(end 92.106496 -225.701606)
		(width 0.088646)
		(layer "In11.Cu")
		(net "M_D_CPU1_SB_DQ<29>")
	)
	(arc
		(start 97.356168 -225.69297)
		(mid 97.081939 -225.768895)
		(end 96.805496 -225.701606)
		(width 0.088646)
		(layer "In11.Cu")
		(net "M_D_CPU1_SB_DQ<29>")
	)
	(arc
		(start 98.295968 -225.69297)
		(mid 98.021739 -225.768895)
		(end 97.745296 -225.701606)
		(width 0.088646)
		(layer "In11.Cu")
		(net "M_D_CPU1_SB_DQ<29>")
	)
	(arc
		(start 99.6188 -227.964238)
		(mid 99.797397 -227.64496)
		(end 99.6188 -227.325682)
		(width 0.088646)
		(layer "In11.Cu")
		(net "M_D_CPU1_SB_DQ<29>")
	)
	(arc
		(start 92.091764 -225.69297)
		(mid 91.904566 -225.642827)
		(end 91.717368 -225.69297)
		(width 0.088646)
		(layer "In11.Cu")
		(net "M_D_CPU1_SB_DQ<29>")
	)
	(arc
		(start 85.138514 -224.065084)
		(mid 85.019883 -224.116604)
		(end 84.892642 -224.13976)
		(width 0.088646)
		(layer "In11.Cu")
		(net "M_D_CPU1_SB_DQ<29>")
	)
	(arc
		(start 95.476568 -225.69297)
		(mid 95.202339 -225.768895)
		(end 94.925896 -225.701606)
		(width 0.088646)
		(layer "In11.Cu")
		(net "M_D_CPU1_SB_DQ<29>")
	)
	(arc
		(start 89.837768 -225.69297)
		(mid 89.563539 -225.768895)
		(end 89.287096 -225.701606)
		(width 0.088646)
		(layer "In11.Cu")
		(net "M_D_CPU1_SB_DQ<29>")
	)
	(arc
		(start 95.850964 -225.69297)
		(mid 95.663766 -225.642827)
		(end 95.476568 -225.69297)
		(width 0.088646)
		(layer "In11.Cu")
		(net "M_D_CPU1_SB_DQ<29>")
	)
	(arc
		(start 98.857816 -226.017328)
		(mid 98.810137 -225.834428)
		(end 98.679254 -225.69805)
		(width 0.088646)
		(layer "In11.Cu")
		(net "M_D_CPU1_SB_DQ<29>")
	)
	(arc
		(start 91.15171 -225.69297)
		(mid 90.964512 -225.642827)
		(end 90.777314 -225.69297)
		(width 0.088646)
		(layer "In11.Cu")
		(net "M_D_CPU1_SB_DQ<29>")
	)
	(arc
		(start 94.536768 -225.69297)
		(mid 94.262539 -225.768895)
		(end 93.986096 -225.701606)
		(width 0.088646)
		(layer "In11.Cu")
		(net "M_D_CPU1_SB_DQ<29>")
	)
	(arc
		(start 89.272364 -225.69297)
		(mid 89.068883 -225.492166)
		(end 88.989662 -225.217482)
		(width 0.088646)
		(layer "In11.Cu")
		(net "M_D_CPU1_SB_DQ<29>")
	)
	(arc
		(start 97.730564 -225.69297)
		(mid 97.543366 -225.642827)
		(end 97.356168 -225.69297)
		(width 0.088646)
		(layer "In11.Cu")
		(net "M_D_CPU1_SB_DQ<29>")
	)
	(arc
		(start 96.790764 -225.69297)
		(mid 96.603566 -225.642827)
		(end 96.416368 -225.69297)
		(width 0.088646)
		(layer "In11.Cu")
		(net "M_D_CPU1_SB_DQ<29>")
	)
	(arc
		(start 87.958168 -224.065084)
		(mid 87.675466 -224.14086)
		(end 87.392764 -224.065084)
		(width 0.088646)
		(layer "In11.Cu")
		(net "M_D_CPU1_SB_DQ<29>")
	)
	(arc
		(start 99.330764 -228.394006)
		(mid 99.419918 -228.148519)
		(end 99.60991 -227.969318)
		(width 0.088646)
		(layer "In11.Cu")
		(net "M_D_CPU1_SB_DQ<29>")
	)
	(arc
		(start 88.520016 -224.389442)
		(mid 88.472337 -224.206542)
		(end 88.341454 -224.070164)
		(width 0.088646)
		(layer "In11.Cu")
		(net "M_D_CPU1_SB_DQ<29>")
	)
	(arc
		(start 88.332564 -224.065084)
		(mid 88.145366 -224.014941)
		(end 87.958168 -224.065084)
		(width 0.088646)
		(layer "In11.Cu")
		(net "M_D_CPU1_SB_DQ<29>")
	)
	(arc
		(start 86.068154 -224.07118)
		(mid 85.789722 -224.141026)
		(end 85.51291 -224.065084)
		(width 0.088646)
		(layer "In11.Cu")
		(net "M_D_CPU1_SB_DQ<29>")
	)
	(arc
		(start 87.392764 -224.065084)
		(mid 87.205566 -224.014941)
		(end 87.018368 -224.065084)
		(width 0.088646)
		(layer "In11.Cu")
		(net "M_D_CPU1_SB_DQ<29>")
	)
	(arc
		(start 85.51291 -224.065084)
		(mid 85.325712 -224.014941)
		(end 85.138514 -224.065084)
		(width 0.088646)
		(layer "In11.Cu")
		(net "M_D_CPU1_SB_DQ<29>")
	)
	(arc
		(start 93.031564 -225.69297)
		(mid 92.844366 -225.642827)
		(end 92.657168 -225.69297)
		(width 0.088646)
		(layer "In11.Cu")
		(net "M_D_CPU1_SB_DQ<29>")
	)
	(arc
		(start 93.596968 -225.69297)
		(mid 93.322739 -225.768895)
		(end 93.046296 -225.701606)
		(width 0.088646)
		(layer "In11.Cu")
		(net "M_D_CPU1_SB_DQ<29>")
	)
	(arc
		(start 99.327716 -226.831144)
		(mid 99.280037 -226.648244)
		(end 99.149154 -226.511866)
		(width 0.088646)
		(layer "In11.Cu")
		(net "M_D_CPU1_SB_DQ<29>")
	)
	(arc
		(start 99.60991 -227.320602)
		(mid 99.407087 -227.120371)
		(end 99.327716 -226.846638)
		(width 0.088646)
		(layer "In11.Cu")
		(net "M_D_CPU1_SB_DQ<29>")
	)
	(arc
		(start 90.212164 -225.69297)
		(mid 90.024966 -225.642827)
		(end 89.837768 -225.69297)
		(width 0.088646)
		(layer "In11.Cu")
		(net "M_D_CPU1_SB_DQ<29>")
	)
	(arc
		(start 93.971364 -225.69297)
		(mid 93.784166 -225.642827)
		(end 93.596968 -225.69297)
		(width 0.088646)
		(layer "In11.Cu")
		(net "M_D_CPU1_SB_DQ<29>")
	)
	(arc
		(start 84.892642 -224.13976)
		(mid 84.874489 -224.140563)
		(end 84.85632 -224.140776)
		(width 0.088646)
		(layer "In11.Cu")
		(net "M_D_CPU1_SB_DQ<29>")
	)
	(arc
		(start 99.140264 -226.506786)
		(mid 98.935929 -226.304181)
		(end 98.857816 -226.027234)
		(width 0.088646)
		(layer "In11.Cu")
		(net "M_D_CPU1_SB_DQ<29>")
	)
	(arc
		(start 96.416368 -225.69297)
		(mid 96.142139 -225.768895)
		(end 95.865696 -225.701606)
		(width 0.088646)
		(layer "In11.Cu")
		(net "M_D_CPU1_SB_DQ<29>")
	)
	(arc
		(start 88.989662 -225.194622)
		(mid 88.937392 -225.012257)
		(end 88.802464 -224.8789)
		(width 0.088646)
		(layer "In11.Cu")
		(net "M_D_CPU1_SB_DQ<29>")
	)
	(arc
		(start 86.452964 -224.065084)
		(mid 86.265766 -224.014941)
		(end 86.078568 -224.065084)
		(width 0.088646)
		(layer "In11.Cu")
		(net "M_D_CPU1_SB_DQ<29>")
	)
	(arc
		(start 98.670364 -225.69297)
		(mid 98.483166 -225.642827)
		(end 98.295968 -225.69297)
		(width 0.088646)
		(layer "In11.Cu")
		(net "M_D_CPU1_SB_DQ<29>")
	)
	(arc
		(start 90.777314 -225.69297)
		(mid 90.500755 -225.768679)
		(end 90.222578 -225.699066)
		(width 0.088646)
		(layer "In11.Cu")
		(net "M_D_CPU1_SB_DQ<29>")
	)
	(arc
		(start 94.911164 -225.69297)
		(mid 94.723966 -225.642827)
		(end 94.536768 -225.69297)
		(width 0.088646)
		(layer "In11.Cu")
		(net "M_D_CPU1_SB_DQ<29>")
	)
	(arc
		(start 88.802464 -224.8789)
		(mid 88.598129 -224.676295)
		(end 88.520016 -224.399348)
		(width 0.088646)
		(layer "In11.Cu")
		(net "M_D_CPU1_SB_DQ<29>")
	)
	(arc
		(start 91.717368 -225.69297)
		(mid 91.440555 -225.768806)
		(end 91.162124 -225.699066)
		(width 0.088646)
		(layer "In11.Cu")
		(net "M_D_CPU1_SB_DQ<29>")
	)
	(segment
		(start 16.789146 -198.166736)
		(end 15.684246 -198.166736)
		(width 0.20066)
		(layer "F.Cu")
		(net "M_D_CPU1_SB_DQ<28>")
	)
	(segment
		(start 13.890244 -197.741794)
		(end 14.315186 -198.166736)
		(width 0.20066)
		(layer "F.Cu")
		(net "M_D_CPU1_SB_DQ<28>")
	)
	(segment
		(start 11.372342 -197.741794)
		(end 13.441426 -197.741794)
		(width 0.1016)
		(layer "F.Cu")
		(net "M_D_CPU1_SB_DQ<28>")
	)
	(segment
		(start 98.483166 -229.808532)
		(end 98.483166 -229.272846)
		(width 0.20066)
		(layer "F.Cu")
		(net "M_D_CPU1_SB_DQ<28>")
	)
	(segment
		(start 98.482912 -229.808786)
		(end 98.483166 -229.808532)
		(width 0.20066)
		(layer "F.Cu")
		(net "M_D_CPU1_SB_DQ<28>")
	)
	(segment
		(start 9.474708 -198.166736)
		(end 9.713468 -198.405496)
		(width 0.20066)
		(layer "F.Cu")
		(net "M_D_CPU1_SB_DQ<28>")
	)
	(segment
		(start 10.344912 -198.232776)
		(end 10.344912 -197.943216)
		(width 0.20066)
		(layer "F.Cu")
		(net "M_D_CPU1_SB_DQ<28>")
	)
	(segment
		(start 9.713468 -198.405496)
		(end 10.172192 -198.405496)
		(width 0.20066)
		(layer "F.Cu")
		(net "M_D_CPU1_SB_DQ<28>")
	)
	(segment
		(start 11.124438 -197.741794)
		(end 11.372342 -197.741794)
		(width 0.101854)
		(layer "F.Cu")
		(net "M_D_CPU1_SB_DQ<28>")
	)
	(segment
		(start 10.172192 -198.405496)
		(end 10.344912 -198.232776)
		(width 0.20066)
		(layer "F.Cu")
		(net "M_D_CPU1_SB_DQ<28>")
	)
	(segment
		(start 11.11631 -197.733666)
		(end 11.124438 -197.741794)
		(width 0.101854)
		(layer "F.Cu")
		(net "M_D_CPU1_SB_DQ<28>")
	)
	(segment
		(start 10.554462 -197.733666)
		(end 11.11631 -197.733666)
		(width 0.20066)
		(layer "F.Cu")
		(net "M_D_CPU1_SB_DQ<28>")
	)
	(segment
		(start 14.315186 -198.166736)
		(end 15.684246 -198.166736)
		(width 0.20066)
		(layer "F.Cu")
		(net "M_D_CPU1_SB_DQ<28>")
	)
	(segment
		(start 8.140446 -198.166736)
		(end 9.474708 -198.166736)
		(width 0.20066)
		(layer "F.Cu")
		(net "M_D_CPU1_SB_DQ<28>")
	)
	(segment
		(start 13.441426 -197.741794)
		(end 13.890244 -197.741794)
		(width 0.20066)
		(layer "F.Cu")
		(net "M_D_CPU1_SB_DQ<28>")
	)
	(segment
		(start 10.344912 -197.943216)
		(end 10.554462 -197.733666)
		(width 0.20066)
		(layer "F.Cu")
		(net "M_D_CPU1_SB_DQ<28>")
	)
	(segment
		(start 22.737826 -197.997826)
		(end 21.672296 -197.997826)
		(width 0.18288)
		(layer "In11.Cu")
		(net "M_D_CPU1_SB_DQ<28>")
	)
	(segment
		(start 21.672296 -197.997826)
		(end 21.417026 -197.742556)
		(width 0.18288)
		(layer "In11.Cu")
		(net "M_D_CPU1_SB_DQ<28>")
	)
	(segment
		(start 34.47034 -196.03974)
		(end 30.241748 -196.03974)
		(width 0.18288)
		(layer "In11.Cu")
		(net "M_D_CPU1_SB_DQ<28>")
	)
	(segment
		(start 51.86553 -196.039486)
		(end 45.449998 -196.039486)
		(width 0.18288)
		(layer "In11.Cu")
		(net "M_D_CPU1_SB_DQ<28>")
	)
	(segment
		(start 35.321494 -196.890894)
		(end 34.47034 -196.03974)
		(width 0.18288)
		(layer "In11.Cu")
		(net "M_D_CPU1_SB_DQ<28>")
	)
	(segment
		(start 98.670364 -227.320602)
		(end 98.670364 -227.320348)
		(width 0.088646)
		(layer "In11.Cu")
		(net "M_D_CPU1_SB_DQ<28>")
	)
	(segment
		(start 58.705496 -195.939156)
		(end 56.10352 -195.939156)
		(width 0.18288)
		(layer "In11.Cu")
		(net "M_D_CPU1_SB_DQ<28>")
	)
	(segment
		(start 29.0195 -196.02958)
		(end 25.685496 -196.02958)
		(width 0.18288)
		(layer "In11.Cu")
		(net "M_D_CPU1_SB_DQ<28>")
	)
	(segment
		(start 66.109342 -199.429878)
		(end 64.252602 -197.573138)
		(width 0.18288)
		(layer "In11.Cu")
		(net "M_D_CPU1_SB_DQ<28>")
	)
	(segment
		(start 36.985448 -196.773292)
		(end 36.867846 -196.890894)
		(width 0.18288)
		(layer "In11.Cu")
		(net "M_D_CPU1_SB_DQ<28>")
	)
	(segment
		(start 55.78729 -196.255386)
		(end 53.961538 -196.255386)
		(width 0.18288)
		(layer "In11.Cu")
		(net "M_D_CPU1_SB_DQ<28>")
	)
	(segment
		(start 92.187014 -226.506786)
		(end 92.1766 -226.512882)
		(width 0.088646)
		(layer "In11.Cu")
		(net "M_D_CPU1_SB_DQ<28>")
	)
	(segment
		(start 87.871554 -224.88398)
		(end 87.862664 -224.8789)
		(width 0.088646)
		(layer "In11.Cu")
		(net "M_D_CPU1_SB_DQ<28>")
	)
	(segment
		(start 98.483166 -229.272846)
		(end 98.670364 -229.085648)
		(width 0.088646)
		(layer "In11.Cu")
		(net "M_D_CPU1_SB_DQ<28>")
	)
	(segment
		(start 40.181784 -196.773292)
		(end 36.985448 -196.773292)
		(width 0.18288)
		(layer "In11.Cu")
		(net "M_D_CPU1_SB_DQ<28>")
	)
	(segment
		(start 30.055058 -196.22643)
		(end 29.21635 -196.22643)
		(width 0.18288)
		(layer "In11.Cu")
		(net "M_D_CPU1_SB_DQ<28>")
	)
	(segment
		(start 98.387662 -228.45903)
		(end 98.387662 -228.444806)
		(width 0.088646)
		(layer "In11.Cu")
		(net "M_D_CPU1_SB_DQ<28>")
	)
	(segment
		(start 68.633848 -204.370178)
		(end 66.109342 -199.429878)
		(width 0.18288)
		(layer "In11.Cu")
		(net "M_D_CPU1_SB_DQ<28>")
	)
	(segment
		(start 19.537426 -197.413626)
		(end 17.542256 -197.413626)
		(width 0.18288)
		(layer "In11.Cu")
		(net "M_D_CPU1_SB_DQ<28>")
	)
	(segment
		(start 24.967184 -196.747892)
		(end 23.98776 -196.747892)
		(width 0.18288)
		(layer "In11.Cu")
		(net "M_D_CPU1_SB_DQ<28>")
	)
	(segment
		(start 36.867846 -196.890894)
		(end 35.321494 -196.890894)
		(width 0.18288)
		(layer "In11.Cu")
		(net "M_D_CPU1_SB_DQ<28>")
	)
	(segment
		(start 98.200464 -226.50704)
		(end 98.20021 -226.506786)
		(width 0.088646)
		(layer "In11.Cu")
		(net "M_D_CPU1_SB_DQ<28>")
	)
	(segment
		(start 56.10352 -195.939156)
		(end 55.78729 -196.255386)
		(width 0.18288)
		(layer "In11.Cu")
		(net "M_D_CPU1_SB_DQ<28>")
	)
	(segment
		(start 17.542256 -197.413626)
		(end 16.789146 -198.166736)
		(width 0.18288)
		(layer "In11.Cu")
		(net "M_D_CPU1_SB_DQ<28>")
	)
	(segment
		(start 84.498942 -224.828354)
		(end 83.237578 -223.56699)
		(width 0.088646)
		(layer "In11.Cu")
		(net "M_D_CPU1_SB_DQ<28>")
	)
	(segment
		(start 85.057996 -224.887536)
		(end 85.043264 -224.8789)
		(width 0.088646)
		(layer "In11.Cu")
		(net "M_D_CPU1_SB_DQ<28>")
	)
	(segment
		(start 90.307414 -226.506786)
		(end 90.292682 -226.515422)
		(width 0.088646)
		(layer "In11.Cu")
		(net "M_D_CPU1_SB_DQ<28>")
	)
	(segment
		(start 45.449998 -196.039486)
		(end 45.310806 -196.178678)
		(width 0.18288)
		(layer "In11.Cu")
		(net "M_D_CPU1_SB_DQ<28>")
	)
	(segment
		(start 53.874162 -196.16801)
		(end 51.994054 -196.16801)
		(width 0.18288)
		(layer "In11.Cu")
		(net "M_D_CPU1_SB_DQ<28>")
	)
	(segment
		(start 29.21635 -196.22643)
		(end 29.0195 -196.02958)
		(width 0.18288)
		(layer "In11.Cu")
		(net "M_D_CPU1_SB_DQ<28>")
	)
	(segment
		(start 82.597498 -221.993714)
		(end 82.028792 -221.993714)
		(width 0.18288)
		(layer "In11.Cu")
		(net "M_D_CPU1_SB_DQ<28>")
	)
	(segment
		(start 76.353924 -212.090254)
		(end 68.633848 -204.370178)
		(width 0.18288)
		(layer "In11.Cu")
		(net "M_D_CPU1_SB_DQ<28>")
	)
	(segment
		(start 64.252602 -197.573138)
		(end 62.69101 -196.824346)
		(width 0.18288)
		(layer "In11.Cu")
		(net "M_D_CPU1_SB_DQ<28>")
	)
	(segment
		(start 25.685496 -196.02958)
		(end 24.967184 -196.747892)
		(width 0.18288)
		(layer "In11.Cu")
		(net "M_D_CPU1_SB_DQ<28>")
	)
	(segment
		(start 82.028792 -221.993714)
		(end 76.353924 -216.318846)
		(width 0.18288)
		(layer "In11.Cu")
		(net "M_D_CPU1_SB_DQ<28>")
	)
	(segment
		(start 82.714338 -221.993714)
		(end 82.597498 -221.993714)
		(width 0.088646)
		(layer "In11.Cu")
		(net "M_D_CPU1_SB_DQ<28>")
	)
	(segment
		(start 84.856066 -224.828354)
		(end 84.498942 -224.828354)
		(width 0.088646)
		(layer "In11.Cu")
		(net "M_D_CPU1_SB_DQ<28>")
	)
	(segment
		(start 19.866356 -197.742556)
		(end 19.537426 -197.413626)
		(width 0.18288)
		(layer "In11.Cu")
		(net "M_D_CPU1_SB_DQ<28>")
	)
	(segment
		(start 53.961538 -196.255386)
		(end 53.874162 -196.16801)
		(width 0.18288)
		(layer "In11.Cu")
		(net "M_D_CPU1_SB_DQ<28>")
	)
	(segment
		(start 90.692224 -226.512882)
		(end 90.68181 -226.506786)
		(width 0.088646)
		(layer "In11.Cu")
		(net "M_D_CPU1_SB_DQ<28>")
	)
	(segment
		(start 83.237578 -223.56699)
		(end 83.237578 -222.516954)
		(width 0.088646)
		(layer "In11.Cu")
		(net "M_D_CPU1_SB_DQ<28>")
	)
	(segment
		(start 93.126814 -226.506786)
		(end 93.112082 -226.515422)
		(width 0.088646)
		(layer "In11.Cu")
		(net "M_D_CPU1_SB_DQ<28>")
	)
	(segment
		(start 44.286678 -196.178678)
		(end 43.946826 -195.838826)
		(width 0.18288)
		(layer "In11.Cu")
		(net "M_D_CPU1_SB_DQ<28>")
	)
	(segment
		(start 88.520016 -226.032822)
		(end 88.520016 -226.017328)
		(width 0.088646)
		(layer "In11.Cu")
		(net "M_D_CPU1_SB_DQ<28>")
	)
	(segment
		(start 59.590686 -196.824346)
		(end 58.705496 -195.939156)
		(width 0.18288)
		(layer "In11.Cu")
		(net "M_D_CPU1_SB_DQ<28>")
	)
	(segment
		(start 98.857562 -227.645214)
		(end 98.857562 -227.64496)
		(width 0.088646)
		(layer "In11.Cu")
		(net "M_D_CPU1_SB_DQ<28>")
	)
	(segment
		(start 98.670364 -229.085648)
		(end 98.670364 -228.948234)
		(width 0.088646)
		(layer "In11.Cu")
		(net "M_D_CPU1_SB_DQ<28>")
	)
	(segment
		(start 23.98776 -196.747892)
		(end 22.737826 -197.997826)
		(width 0.18288)
		(layer "In11.Cu")
		(net "M_D_CPU1_SB_DQ<28>")
	)
	(segment
		(start 96.886014 -226.506786)
		(end 96.8756 -226.512882)
		(width 0.088646)
		(layer "In11.Cu")
		(net "M_D_CPU1_SB_DQ<28>")
	)
	(segment
		(start 43.946826 -195.838826)
		(end 41.11625 -195.838826)
		(width 0.18288)
		(layer "In11.Cu")
		(net "M_D_CPU1_SB_DQ<28>")
	)
	(segment
		(start 89.367614 -226.506786)
		(end 89.352882 -226.515422)
		(width 0.088646)
		(layer "In11.Cu")
		(net "M_D_CPU1_SB_DQ<28>")
	)
	(segment
		(start 51.994054 -196.16801)
		(end 51.86553 -196.039486)
		(width 0.18288)
		(layer "In11.Cu")
		(net "M_D_CPU1_SB_DQ<28>")
	)
	(segment
		(start 45.310806 -196.178678)
		(end 44.286678 -196.178678)
		(width 0.18288)
		(layer "In11.Cu")
		(net "M_D_CPU1_SB_DQ<28>")
	)
	(segment
		(start 95.006414 -226.506786)
		(end 94.991682 -226.515422)
		(width 0.088646)
		(layer "In11.Cu")
		(net "M_D_CPU1_SB_DQ<28>")
	)
	(segment
		(start 95.946468 -226.506786)
		(end 95.936054 -226.512882)
		(width 0.088646)
		(layer "In11.Cu")
		(net "M_D_CPU1_SB_DQ<28>")
	)
	(segment
		(start 21.417026 -197.742556)
		(end 19.866356 -197.742556)
		(width 0.18288)
		(layer "In11.Cu")
		(net "M_D_CPU1_SB_DQ<28>")
	)
	(segment
		(start 97.826068 -226.506786)
		(end 97.82556 -226.506786)
		(width 0.088646)
		(layer "In11.Cu")
		(net "M_D_CPU1_SB_DQ<28>")
	)
	(segment
		(start 94.066614 -226.506786)
		(end 94.051882 -226.515422)
		(width 0.088646)
		(layer "In11.Cu")
		(net "M_D_CPU1_SB_DQ<28>")
	)
	(segment
		(start 88.050116 -225.2218)
		(end 88.050116 -225.203258)
		(width 0.088646)
		(layer "In11.Cu")
		(net "M_D_CPU1_SB_DQ<28>")
	)
	(segment
		(start 76.353924 -216.318846)
		(end 76.353924 -212.090254)
		(width 0.18288)
		(layer "In11.Cu")
		(net "M_D_CPU1_SB_DQ<28>")
	)
	(segment
		(start 41.11625 -195.838826)
		(end 40.181784 -196.773292)
		(width 0.18288)
		(layer "In11.Cu")
		(net "M_D_CPU1_SB_DQ<28>")
	)
	(segment
		(start 88.341454 -225.69805)
		(end 88.332564 -225.69297)
		(width 0.088646)
		(layer "In11.Cu")
		(net "M_D_CPU1_SB_DQ<28>")
	)
	(segment
		(start 83.237578 -222.516954)
		(end 82.714338 -221.993714)
		(width 0.088646)
		(layer "In11.Cu")
		(net "M_D_CPU1_SB_DQ<28>")
	)
	(segment
		(start 30.241748 -196.03974)
		(end 30.055058 -196.22643)
		(width 0.18288)
		(layer "In11.Cu")
		(net "M_D_CPU1_SB_DQ<28>")
	)
	(segment
		(start 62.69101 -196.824346)
		(end 59.590686 -196.824346)
		(width 0.18288)
		(layer "In11.Cu")
		(net "M_D_CPU1_SB_DQ<28>")
	)
	(arc
		(start 93.112082 -226.515422)
		(mid 92.835607 -226.582742)
		(end 92.56141 -226.506786)
		(width 0.088646)
		(layer "In11.Cu")
		(net "M_D_CPU1_SB_DQ<28>")
	)
	(arc
		(start 96.8756 -226.512882)
		(mid 96.597422 -226.582605)
		(end 96.320864 -226.506786)
		(width 0.088646)
		(layer "In11.Cu")
		(net "M_D_CPU1_SB_DQ<28>")
	)
	(arc
		(start 88.332564 -225.69297)
		(mid 88.130278 -225.493989)
		(end 88.050116 -225.2218)
		(width 0.088646)
		(layer "In11.Cu")
		(net "M_D_CPU1_SB_DQ<28>")
	)
	(arc
		(start 88.80221 -226.506786)
		(mid 88.599387 -226.306555)
		(end 88.520016 -226.032822)
		(width 0.088646)
		(layer "In11.Cu")
		(net "M_D_CPU1_SB_DQ<28>")
	)
	(arc
		(start 87.488268 -224.8789)
		(mid 87.205566 -224.954676)
		(end 86.922864 -224.8789)
		(width 0.088646)
		(layer "In11.Cu")
		(net "M_D_CPU1_SB_DQ<28>")
	)
	(arc
		(start 94.991682 -226.515422)
		(mid 94.715207 -226.582742)
		(end 94.44101 -226.506786)
		(width 0.088646)
		(layer "In11.Cu")
		(net "M_D_CPU1_SB_DQ<28>")
	)
	(arc
		(start 91.621864 -226.506786)
		(mid 91.434666 -226.456643)
		(end 91.247468 -226.506786)
		(width 0.088646)
		(layer "In11.Cu")
		(net "M_D_CPU1_SB_DQ<28>")
	)
	(arc
		(start 89.74201 -226.506786)
		(mid 89.554812 -226.456643)
		(end 89.367614 -226.506786)
		(width 0.088646)
		(layer "In11.Cu")
		(net "M_D_CPU1_SB_DQ<28>")
	)
	(arc
		(start 92.56141 -226.506786)
		(mid 92.374212 -226.456643)
		(end 92.187014 -226.506786)
		(width 0.088646)
		(layer "In11.Cu")
		(net "M_D_CPU1_SB_DQ<28>")
	)
	(arc
		(start 97.26041 -226.506786)
		(mid 97.073212 -226.456643)
		(end 96.886014 -226.506786)
		(width 0.088646)
		(layer "In11.Cu")
		(net "M_D_CPU1_SB_DQ<28>")
	)
	(arc
		(start 88.050116 -225.203258)
		(mid 88.002437 -225.020358)
		(end 87.871554 -224.88398)
		(width 0.088646)
		(layer "In11.Cu")
		(net "M_D_CPU1_SB_DQ<28>")
	)
	(arc
		(start 98.857562 -227.64496)
		(mid 98.807408 -227.457704)
		(end 98.670364 -227.320602)
		(width 0.088646)
		(layer "In11.Cu")
		(net "M_D_CPU1_SB_DQ<28>")
	)
	(arc
		(start 85.608668 -224.8789)
		(mid 85.334469 -224.954735)
		(end 85.057996 -224.887536)
		(width 0.088646)
		(layer "In11.Cu")
		(net "M_D_CPU1_SB_DQ<28>")
	)
	(arc
		(start 87.862664 -224.8789)
		(mid 87.675466 -224.828757)
		(end 87.488268 -224.8789)
		(width 0.088646)
		(layer "In11.Cu")
		(net "M_D_CPU1_SB_DQ<28>")
	)
	(arc
		(start 89.352882 -226.515422)
		(mid 89.076407 -226.582742)
		(end 88.80221 -226.506786)
		(width 0.088646)
		(layer "In11.Cu")
		(net "M_D_CPU1_SB_DQ<28>")
	)
	(arc
		(start 90.68181 -226.506786)
		(mid 90.494612 -226.456643)
		(end 90.307414 -226.506786)
		(width 0.088646)
		(layer "In11.Cu")
		(net "M_D_CPU1_SB_DQ<28>")
	)
	(arc
		(start 85.983064 -224.8789)
		(mid 85.795866 -224.828757)
		(end 85.608668 -224.8789)
		(width 0.088646)
		(layer "In11.Cu")
		(net "M_D_CPU1_SB_DQ<28>")
	)
	(arc
		(start 94.051882 -226.515422)
		(mid 93.775407 -226.582742)
		(end 93.50121 -226.506786)
		(width 0.088646)
		(layer "In11.Cu")
		(net "M_D_CPU1_SB_DQ<28>")
	)
	(arc
		(start 92.1766 -226.512882)
		(mid 91.898422 -226.582605)
		(end 91.621864 -226.506786)
		(width 0.088646)
		(layer "In11.Cu")
		(net "M_D_CPU1_SB_DQ<28>")
	)
	(arc
		(start 98.387662 -228.444806)
		(mid 98.466881 -228.170121)
		(end 98.670364 -227.969318)
		(width 0.088646)
		(layer "In11.Cu")
		(net "M_D_CPU1_SB_DQ<28>")
	)
	(arc
		(start 93.50121 -226.506786)
		(mid 93.314012 -226.456643)
		(end 93.126814 -226.506786)
		(width 0.088646)
		(layer "In11.Cu")
		(net "M_D_CPU1_SB_DQ<28>")
	)
	(arc
		(start 91.247468 -226.506786)
		(mid 90.970655 -226.582656)
		(end 90.692224 -226.512882)
		(width 0.088646)
		(layer "In11.Cu")
		(net "M_D_CPU1_SB_DQ<28>")
	)
	(arc
		(start 98.670364 -227.969318)
		(mid 98.807409 -227.832358)
		(end 98.857562 -227.645214)
		(width 0.088646)
		(layer "In11.Cu")
		(net "M_D_CPU1_SB_DQ<28>")
	)
	(arc
		(start 98.670364 -228.948234)
		(mid 98.46342 -228.741524)
		(end 98.387662 -228.45903)
		(width 0.088646)
		(layer "In11.Cu")
		(net "M_D_CPU1_SB_DQ<28>")
	)
	(arc
		(start 85.043264 -224.8789)
		(mid 84.952992 -224.841301)
		(end 84.856066 -224.828354)
		(width 0.088646)
		(layer "In11.Cu")
		(net "M_D_CPU1_SB_DQ<28>")
	)
	(arc
		(start 86.548468 -224.8789)
		(mid 86.265766 -224.954676)
		(end 85.983064 -224.8789)
		(width 0.088646)
		(layer "In11.Cu")
		(net "M_D_CPU1_SB_DQ<28>")
	)
	(arc
		(start 95.936054 -226.512882)
		(mid 95.657622 -226.582728)
		(end 95.38081 -226.506786)
		(width 0.088646)
		(layer "In11.Cu")
		(net "M_D_CPU1_SB_DQ<28>")
	)
	(arc
		(start 98.20021 -226.506786)
		(mid 98.013156 -226.456736)
		(end 97.826068 -226.506786)
		(width 0.088646)
		(layer "In11.Cu")
		(net "M_D_CPU1_SB_DQ<28>")
	)
	(arc
		(start 97.82556 -226.506786)
		(mid 97.542968 -226.582562)
		(end 97.26041 -226.506786)
		(width 0.088646)
		(layer "In11.Cu")
		(net "M_D_CPU1_SB_DQ<28>")
	)
	(arc
		(start 98.670364 -227.320348)
		(mid 98.463509 -227.113606)
		(end 98.387662 -226.831144)
		(width 0.088646)
		(layer "In11.Cu")
		(net "M_D_CPU1_SB_DQ<28>")
	)
	(arc
		(start 86.922864 -224.8789)
		(mid 86.735666 -224.828757)
		(end 86.548468 -224.8789)
		(width 0.088646)
		(layer "In11.Cu")
		(net "M_D_CPU1_SB_DQ<28>")
	)
	(arc
		(start 94.44101 -226.506786)
		(mid 94.253812 -226.456643)
		(end 94.066614 -226.506786)
		(width 0.088646)
		(layer "In11.Cu")
		(net "M_D_CPU1_SB_DQ<28>")
	)
	(arc
		(start 90.292682 -226.515422)
		(mid 90.016207 -226.582742)
		(end 89.74201 -226.506786)
		(width 0.088646)
		(layer "In11.Cu")
		(net "M_D_CPU1_SB_DQ<28>")
	)
	(arc
		(start 98.387662 -226.831144)
		(mid 98.337498 -226.644006)
		(end 98.200464 -226.50704)
		(width 0.088646)
		(layer "In11.Cu")
		(net "M_D_CPU1_SB_DQ<28>")
	)
	(arc
		(start 96.320864 -226.506786)
		(mid 96.133666 -226.456643)
		(end 95.946468 -226.506786)
		(width 0.088646)
		(layer "In11.Cu")
		(net "M_D_CPU1_SB_DQ<28>")
	)
	(arc
		(start 88.520016 -226.017328)
		(mid 88.472337 -225.834428)
		(end 88.341454 -225.69805)
		(width 0.088646)
		(layer "In11.Cu")
		(net "M_D_CPU1_SB_DQ<28>")
	)
	(arc
		(start 95.38081 -226.506786)
		(mid 95.193612 -226.456643)
		(end 95.006414 -226.506786)
		(width 0.088646)
		(layer "In11.Cu")
		(net "M_D_CPU1_SB_DQ<28>")
	)
	(segment
		(start 17.707102 -201.562462)
		(end 18.102326 -201.562462)
		(width 0.20066)
		(layer "F.Cu")
		(net "M_D_CPU1_SB_DQ<27>")
	)
	(segment
		(start 18.314162 -201.774298)
		(end 18.760694 -201.774298)
		(width 0.20066)
		(layer "F.Cu")
		(net "M_D_CPU1_SB_DQ<27>")
	)
	(segment
		(start 18.102326 -201.562462)
		(end 18.314162 -201.774298)
		(width 0.20066)
		(layer "F.Cu")
		(net "M_D_CPU1_SB_DQ<27>")
	)
	(segment
		(start 100.362766 -231.436164)
		(end 100.362766 -230.900478)
		(width 0.20066)
		(layer "F.Cu")
		(net "M_D_CPU1_SB_DQ<27>")
	)
	(segment
		(start 18.760694 -201.774298)
		(end 18.968212 -201.56678)
		(width 0.20066)
		(layer "F.Cu")
		(net "M_D_CPU1_SB_DQ<27>")
	)
	(segment
		(start 17.578578 -201.842624)
		(end 17.578578 -201.690986)
		(width 0.20066)
		(layer "F.Cu")
		(net "M_D_CPU1_SB_DQ<27>")
	)
	(segment
		(start 14.20622 -202.005946)
		(end 14.560042 -202.005946)
		(width 0.20066)
		(layer "F.Cu")
		(net "M_D_CPU1_SB_DQ<27>")
	)
	(segment
		(start 100.362512 -231.436418)
		(end 100.362766 -231.436164)
		(width 0.20066)
		(layer "F.Cu")
		(net "M_D_CPU1_SB_DQ<27>")
	)
	(segment
		(start 20.889214 -201.56678)
		(end 19.784314 -201.56678)
		(width 0.20066)
		(layer "F.Cu")
		(net "M_D_CPU1_SB_DQ<27>")
	)
	(segment
		(start 12.240514 -201.56678)
		(end 13.937742 -201.56678)
		(width 0.20066)
		(layer "F.Cu")
		(net "M_D_CPU1_SB_DQ<27>")
	)
	(segment
		(start 14.560042 -202.005946)
		(end 14.574266 -201.991722)
		(width 0.101854)
		(layer "F.Cu")
		(net "M_D_CPU1_SB_DQ<27>")
	)
	(segment
		(start 18.968212 -201.56678)
		(end 19.784314 -201.56678)
		(width 0.20066)
		(layer "F.Cu")
		(net "M_D_CPU1_SB_DQ<27>")
	)
	(segment
		(start 16.885158 -201.991722)
		(end 17.42948 -201.991722)
		(width 0.20066)
		(layer "F.Cu")
		(net "M_D_CPU1_SB_DQ<27>")
	)
	(segment
		(start 13.937742 -201.56678)
		(end 14.063726 -201.692764)
		(width 0.20066)
		(layer "F.Cu")
		(net "M_D_CPU1_SB_DQ<27>")
	)
	(segment
		(start 14.812264 -201.991722)
		(end 16.885158 -201.991722)
		(width 0.1016)
		(layer "F.Cu")
		(net "M_D_CPU1_SB_DQ<27>")
	)
	(segment
		(start 14.574266 -201.991722)
		(end 14.812264 -201.991722)
		(width 0.101854)
		(layer "F.Cu")
		(net "M_D_CPU1_SB_DQ<27>")
	)
	(segment
		(start 14.063726 -201.863452)
		(end 14.20622 -202.005946)
		(width 0.20066)
		(layer "F.Cu")
		(net "M_D_CPU1_SB_DQ<27>")
	)
	(segment
		(start 17.42948 -201.991722)
		(end 17.578578 -201.842624)
		(width 0.20066)
		(layer "F.Cu")
		(net "M_D_CPU1_SB_DQ<27>")
	)
	(segment
		(start 14.063726 -201.692764)
		(end 14.063726 -201.863452)
		(width 0.20066)
		(layer "F.Cu")
		(net "M_D_CPU1_SB_DQ<27>")
	)
	(segment
		(start 17.578578 -201.690986)
		(end 17.707102 -201.562462)
		(width 0.20066)
		(layer "F.Cu")
		(net "M_D_CPU1_SB_DQ<27>")
	)
	(segment
		(start 90.307414 -228.783388)
		(end 90.292682 -228.774752)
		(width 0.088646)
		(layer "In11.Cu")
		(net "M_D_CPU1_SB_DQ<27>")
	)
	(segment
		(start 55.400448 -200.791826)
		(end 54.582314 -200.791826)
		(width 0.18288)
		(layer "In11.Cu")
		(net "M_D_CPU1_SB_DQ<27>")
	)
	(segment
		(start 98.670618 -230.57612)
		(end 98.67011 -230.57612)
		(width 0.088646)
		(layer "In11.Cu")
		(net "M_D_CPU1_SB_DQ<27>")
	)
	(segment
		(start 60.482226 -200.944226)
		(end 59.415426 -200.944226)
		(width 0.18288)
		(layer "In11.Cu")
		(net "M_D_CPU1_SB_DQ<27>")
	)
	(segment
		(start 39.46144 -200.447148)
		(end 39.2684 -200.640188)
		(width 0.18288)
		(layer "In11.Cu")
		(net "M_D_CPU1_SB_DQ<27>")
	)
	(segment
		(start 45.555408 -200.853294)
		(end 44.139358 -200.853294)
		(width 0.18288)
		(layer "In11.Cu")
		(net "M_D_CPU1_SB_DQ<27>")
	)
	(segment
		(start 87.488268 -228.783388)
		(end 87.479378 -228.778308)
		(width 0.088646)
		(layer "In11.Cu")
		(net "M_D_CPU1_SB_DQ<27>")
	)
	(segment
		(start 42.863008 -201.350626)
		(end 42.669968 -201.157586)
		(width 0.18288)
		(layer "In11.Cu")
		(net "M_D_CPU1_SB_DQ<27>")
	)
	(segment
		(start 34.485834 -201.338434)
		(end 32.965644 -201.338434)
		(width 0.18288)
		(layer "In11.Cu")
		(net "M_D_CPU1_SB_DQ<27>")
	)
	(segment
		(start 57.963054 -200.36282)
		(end 57.770014 -200.16978)
		(width 0.18288)
		(layer "In11.Cu")
		(net "M_D_CPU1_SB_DQ<27>")
	)
	(segment
		(start 57.262014 -200.36282)
		(end 57.262014 -201.076052)
		(width 0.18288)
		(layer "In11.Cu")
		(net "M_D_CPU1_SB_DQ<27>")
	)
	(segment
		(start 37.578284 -202.105768)
		(end 36.954968 -202.105768)
		(width 0.18288)
		(layer "In11.Cu")
		(net "M_D_CPU1_SB_DQ<27>")
	)
	(segment
		(start 36.841684 -201.992484)
		(end 35.139884 -201.992484)
		(width 0.18288)
		(layer "In11.Cu")
		(net "M_D_CPU1_SB_DQ<27>")
	)
	(segment
		(start 59.09056 -201.269092)
		(end 58.156094 -201.269092)
		(width 0.18288)
		(layer "In11.Cu")
		(net "M_D_CPU1_SB_DQ<27>")
	)
	(segment
		(start 57.455054 -200.16978)
		(end 57.262014 -200.36282)
		(width 0.18288)
		(layer "In11.Cu")
		(net "M_D_CPU1_SB_DQ<27>")
	)
	(segment
		(start 41.968928 -200.674986)
		(end 41.968928 -201.157586)
		(width 0.18288)
		(layer "In11.Cu")
		(net "M_D_CPU1_SB_DQ<27>")
	)
	(segment
		(start 86.548214 -227.155502)
		(end 86.5378 -227.149406)
		(width 0.088646)
		(layer "In11.Cu")
		(net "M_D_CPU1_SB_DQ<27>")
	)
	(segment
		(start 29.746956 -200.536556)
		(end 29.746956 -200.849992)
		(width 0.18288)
		(layer "In11.Cu")
		(net "M_D_CPU1_SB_DQ<27>")
	)
	(segment
		(start 62.920626 -204.068426)
		(end 62.920626 -203.382626)
		(width 0.18288)
		(layer "In11.Cu")
		(net "M_D_CPU1_SB_DQ<27>")
	)
	(segment
		(start 29.553916 -201.043032)
		(end 28.88742 -201.043032)
		(width 0.18288)
		(layer "In11.Cu")
		(net "M_D_CPU1_SB_DQ<27>")
	)
	(segment
		(start 57.262014 -201.076052)
		(end 57.068974 -201.269092)
		(width 0.18288)
		(layer "In11.Cu")
		(net "M_D_CPU1_SB_DQ<27>")
	)
	(segment
		(start 53.947314 -201.426826)
		(end 53.522626 -201.426826)
		(width 0.18288)
		(layer "In11.Cu")
		(net "M_D_CPU1_SB_DQ<27>")
	)
	(segment
		(start 89.367614 -228.783388)
		(end 89.352882 -228.774752)
		(width 0.088646)
		(layer "In11.Cu")
		(net "M_D_CPU1_SB_DQ<27>")
	)
	(segment
		(start 38.562026 -201.122026)
		(end 37.578284 -202.105768)
		(width 0.18288)
		(layer "In11.Cu")
		(net "M_D_CPU1_SB_DQ<27>")
	)
	(segment
		(start 26.716736 -201.350626)
		(end 25.785826 -201.350626)
		(width 0.18288)
		(layer "In11.Cu")
		(net "M_D_CPU1_SB_DQ<27>")
	)
	(segment
		(start 27.610816 -201.157586)
		(end 27.610816 -200.744582)
		(width 0.18288)
		(layer "In11.Cu")
		(net "M_D_CPU1_SB_DQ<27>")
	)
	(segment
		(start 93.126814 -228.783388)
		(end 93.112082 -228.774752)
		(width 0.088646)
		(layer "In11.Cu")
		(net "M_D_CPU1_SB_DQ<27>")
	)
	(segment
		(start 39.7764 -200.447148)
		(end 39.46144 -200.447148)
		(width 0.18288)
		(layer "In11.Cu")
		(net "M_D_CPU1_SB_DQ<27>")
	)
	(segment
		(start 26.909776 -201.157586)
		(end 26.716736 -201.350626)
		(width 0.18288)
		(layer "In11.Cu")
		(net "M_D_CPU1_SB_DQ<27>")
	)
	(segment
		(start 84.385912 -227.07981)
		(end 83.640422 -227.07981)
		(width 0.088646)
		(layer "In11.Cu")
		(net "M_D_CPU1_SB_DQ<27>")
	)
	(segment
		(start 42.669968 -200.674986)
		(end 42.476928 -200.481946)
		(width 0.18288)
		(layer "In11.Cu")
		(net "M_D_CPU1_SB_DQ<27>")
	)
	(segment
		(start 49.404524 -201.144124)
		(end 45.846238 -201.144124)
		(width 0.18288)
		(layer "In11.Cu")
		(net "M_D_CPU1_SB_DQ<27>")
	)
	(segment
		(start 94.066614 -228.783388)
		(end 94.051882 -228.774752)
		(width 0.088646)
		(layer "In11.Cu")
		(net "M_D_CPU1_SB_DQ<27>")
	)
	(segment
		(start 57.770014 -200.16978)
		(end 57.455054 -200.16978)
		(width 0.18288)
		(layer "In11.Cu")
		(net "M_D_CPU1_SB_DQ<27>")
	)
	(segment
		(start 42.669968 -201.157586)
		(end 42.669968 -200.674986)
		(width 0.18288)
		(layer "In11.Cu")
		(net "M_D_CPU1_SB_DQ<27>")
	)
	(segment
		(start 96.422464 -229.60076)
		(end 96.416368 -229.597204)
		(width 0.088646)
		(layer "In11.Cu")
		(net "M_D_CPU1_SB_DQ<27>")
	)
	(segment
		(start 73.570846 -216.776554)
		(end 73.570846 -213.89848)
		(width 0.18288)
		(layer "In11.Cu")
		(net "M_D_CPU1_SB_DQ<27>")
	)
	(segment
		(start 41.042336 -201.350626)
		(end 40.813736 -201.122026)
		(width 0.18288)
		(layer "In11.Cu")
		(net "M_D_CPU1_SB_DQ<27>")
	)
	(segment
		(start 87.030306 -227.97643)
		(end 87.018114 -227.969318)
		(width 0.088646)
		(layer "In11.Cu")
		(net "M_D_CPU1_SB_DQ<27>")
	)
	(segment
		(start 55.877714 -201.269092)
		(end 55.400448 -200.791826)
		(width 0.18288)
		(layer "In11.Cu")
		(net "M_D_CPU1_SB_DQ<27>")
	)
	(segment
		(start 27.417776 -200.551542)
		(end 27.102816 -200.551542)
		(width 0.18288)
		(layer "In11.Cu")
		(net "M_D_CPU1_SB_DQ<27>")
	)
	(segment
		(start 88.427814 -228.783388)
		(end 88.4174 -228.777292)
		(width 0.088646)
		(layer "In11.Cu")
		(net "M_D_CPU1_SB_DQ<27>")
	)
	(segment
		(start 57.963054 -201.076052)
		(end 57.963054 -200.36282)
		(width 0.18288)
		(layer "In11.Cu")
		(net "M_D_CPU1_SB_DQ<27>")
	)
	(segment
		(start 30.254956 -200.343516)
		(end 29.939996 -200.343516)
		(width 0.18288)
		(layer "In11.Cu")
		(net "M_D_CPU1_SB_DQ<27>")
	)
	(segment
		(start 28.88742 -201.043032)
		(end 28.579826 -201.350626)
		(width 0.18288)
		(layer "In11.Cu")
		(net "M_D_CPU1_SB_DQ<27>")
	)
	(segment
		(start 92.187014 -228.783388)
		(end 92.1766 -228.777292)
		(width 0.088646)
		(layer "In11.Cu")
		(net "M_D_CPU1_SB_DQ<27>")
	)
	(segment
		(start 99.624896 -230.584756)
		(end 99.610164 -230.57612)
		(width 0.088646)
		(layer "In11.Cu")
		(net "M_D_CPU1_SB_DQ<27>")
	)
	(segment
		(start 95.95231 -228.786944)
		(end 95.946214 -228.783388)
		(width 0.088646)
		(layer "In11.Cu")
		(net "M_D_CPU1_SB_DQ<27>")
	)
	(segment
		(start 25.785826 -201.350626)
		(end 25.557226 -201.122026)
		(width 0.18288)
		(layer "In11.Cu")
		(net "M_D_CPU1_SB_DQ<27>")
	)
	(segment
		(start 29.746956 -200.849992)
		(end 29.553916 -201.043032)
		(width 0.18288)
		(layer "In11.Cu")
		(net "M_D_CPU1_SB_DQ<27>")
	)
	(segment
		(start 86.830916 -227.653596)
		(end 86.830916 -227.64496)
		(width 0.088646)
		(layer "In11.Cu")
		(net "M_D_CPU1_SB_DQ<27>")
	)
	(segment
		(start 36.954968 -202.105768)
		(end 36.841684 -201.992484)
		(width 0.18288)
		(layer "In11.Cu")
		(net "M_D_CPU1_SB_DQ<27>")
	)
	(segment
		(start 26.909776 -200.744582)
		(end 26.909776 -201.157586)
		(width 0.18288)
		(layer "In11.Cu")
		(net "M_D_CPU1_SB_DQ<27>")
	)
	(segment
		(start 43.642026 -201.350626)
		(end 42.863008 -201.350626)
		(width 0.18288)
		(layer "In11.Cu")
		(net "M_D_CPU1_SB_DQ<27>")
	)
	(segment
		(start 42.476928 -200.481946)
		(end 42.161968 -200.481946)
		(width 0.18288)
		(layer "In11.Cu")
		(net "M_D_CPU1_SB_DQ<27>")
	)
	(segment
		(start 39.2684 -200.640188)
		(end 39.2684 -200.928986)
		(width 0.18288)
		(layer "In11.Cu")
		(net "M_D_CPU1_SB_DQ<27>")
	)
	(segment
		(start 31.436056 -201.043032)
		(end 30.641036 -201.043032)
		(width 0.18288)
		(layer "In11.Cu")
		(net "M_D_CPU1_SB_DQ<27>")
	)
	(segment
		(start 40.813736 -201.122026)
		(end 40.16248 -201.122026)
		(width 0.18288)
		(layer "In11.Cu")
		(net "M_D_CPU1_SB_DQ<27>")
	)
	(segment
		(start 23.18131 -202.034902)
		(end 21.357336 -202.034902)
		(width 0.18288)
		(layer "In11.Cu")
		(net "M_D_CPU1_SB_DQ<27>")
	)
	(segment
		(start 27.610816 -200.744582)
		(end 27.417776 -200.551542)
		(width 0.18288)
		(layer "In11.Cu")
		(net "M_D_CPU1_SB_DQ<27>")
	)
	(segment
		(start 32.965644 -201.338434)
		(end 32.770318 -201.143108)
		(width 0.18288)
		(layer "In11.Cu")
		(net "M_D_CPU1_SB_DQ<27>")
	)
	(segment
		(start 58.156094 -201.269092)
		(end 57.963054 -201.076052)
		(width 0.18288)
		(layer "In11.Cu")
		(net "M_D_CPU1_SB_DQ<27>")
	)
	(segment
		(start 25.557226 -201.122026)
		(end 24.094186 -201.122026)
		(width 0.18288)
		(layer "In11.Cu")
		(net "M_D_CPU1_SB_DQ<27>")
	)
	(segment
		(start 97.730564 -230.57612)
		(end 97.44456 -230.411274)
		(width 0.088646)
		(layer "In11.Cu")
		(net "M_D_CPU1_SB_DQ<27>")
	)
	(segment
		(start 63.48857 -204.63637)
		(end 62.920626 -204.068426)
		(width 0.18288)
		(layer "In11.Cu")
		(net "M_D_CPU1_SB_DQ<27>")
	)
	(segment
		(start 31.536132 -201.143108)
		(end 31.436056 -201.043032)
		(width 0.18288)
		(layer "In11.Cu")
		(net "M_D_CPU1_SB_DQ<27>")
	)
	(segment
		(start 39.96944 -200.928986)
		(end 39.96944 -200.640188)
		(width 0.18288)
		(layer "In11.Cu")
		(net "M_D_CPU1_SB_DQ<27>")
	)
	(segment
		(start 29.939996 -200.343516)
		(end 29.746956 -200.536556)
		(width 0.18288)
		(layer "In11.Cu")
		(net "M_D_CPU1_SB_DQ<27>")
	)
	(segment
		(start 83.039966 -226.245674)
		(end 82.494374 -225.700082)
		(width 0.088646)
		(layer "In11.Cu")
		(net "M_D_CPU1_SB_DQ<27>")
	)
	(segment
		(start 83.039966 -226.479354)
		(end 83.039966 -226.245674)
		(width 0.088646)
		(layer "In11.Cu")
		(net "M_D_CPU1_SB_DQ<27>")
	)
	(segment
		(start 73.570846 -213.89848)
		(end 64.308736 -204.63637)
		(width 0.18288)
		(layer "In11.Cu")
		(net "M_D_CPU1_SB_DQ<27>")
	)
	(segment
		(start 44.139358 -200.853294)
		(end 43.642026 -201.350626)
		(width 0.18288)
		(layer "In11.Cu")
		(net "M_D_CPU1_SB_DQ<27>")
	)
	(segment
		(start 21.357336 -202.034902)
		(end 20.889214 -201.56678)
		(width 0.18288)
		(layer "In11.Cu")
		(net "M_D_CPU1_SB_DQ<27>")
	)
	(segment
		(start 83.640422 -227.07981)
		(end 83.039966 -226.479354)
		(width 0.088646)
		(layer "In11.Cu")
		(net "M_D_CPU1_SB_DQ<27>")
	)
	(segment
		(start 95.946214 -228.783388)
		(end 95.931482 -228.774752)
		(width 0.088646)
		(layer "In11.Cu")
		(net "M_D_CPU1_SB_DQ<27>")
	)
	(segment
		(start 32.770318 -201.143108)
		(end 31.536132 -201.143108)
		(width 0.18288)
		(layer "In11.Cu")
		(net "M_D_CPU1_SB_DQ<27>")
	)
	(segment
		(start 30.447996 -200.536556)
		(end 30.254956 -200.343516)
		(width 0.18288)
		(layer "In11.Cu")
		(net "M_D_CPU1_SB_DQ<27>")
	)
	(segment
		(start 50.254662 -201.994262)
		(end 49.404524 -201.144124)
		(width 0.18288)
		(layer "In11.Cu")
		(net "M_D_CPU1_SB_DQ<27>")
	)
	(segment
		(start 41.775888 -201.350626)
		(end 41.042336 -201.350626)
		(width 0.18288)
		(layer "In11.Cu")
		(net "M_D_CPU1_SB_DQ<27>")
	)
	(segment
		(start 24.094186 -201.122026)
		(end 23.18131 -202.034902)
		(width 0.18288)
		(layer "In11.Cu")
		(net "M_D_CPU1_SB_DQ<27>")
	)
	(segment
		(start 64.308736 -204.63637)
		(end 63.48857 -204.63637)
		(width 0.18288)
		(layer "In11.Cu")
		(net "M_D_CPU1_SB_DQ<27>")
	)
	(segment
		(start 99.844606 -230.650288)
		(end 99.82835 -230.64851)
		(width 0.088646)
		(layer "In11.Cu")
		(net "M_D_CPU1_SB_DQ<27>")
	)
	(segment
		(start 86.55431 -227.159058)
		(end 86.548214 -227.155502)
		(width 0.088646)
		(layer "In11.Cu")
		(net "M_D_CPU1_SB_DQ<27>")
	)
	(segment
		(start 40.16248 -201.122026)
		(end 39.96944 -200.928986)
		(width 0.18288)
		(layer "In11.Cu")
		(net "M_D_CPU1_SB_DQ<27>")
	)
	(segment
		(start 96.416368 -229.597204)
		(end 96.407478 -229.592124)
		(width 0.088646)
		(layer "In11.Cu")
		(net "M_D_CPU1_SB_DQ<27>")
	)
	(segment
		(start 62.920626 -203.382626)
		(end 60.482226 -200.944226)
		(width 0.18288)
		(layer "In11.Cu")
		(net "M_D_CPU1_SB_DQ<27>")
	)
	(segment
		(start 42.161968 -200.481946)
		(end 41.968928 -200.674986)
		(width 0.18288)
		(layer "In11.Cu")
		(net "M_D_CPU1_SB_DQ<27>")
	)
	(segment
		(start 91.247468 -228.783388)
		(end 91.237054 -228.777292)
		(width 0.088646)
		(layer "In11.Cu")
		(net "M_D_CPU1_SB_DQ<27>")
	)
	(segment
		(start 39.07536 -201.122026)
		(end 38.562026 -201.122026)
		(width 0.18288)
		(layer "In11.Cu")
		(net "M_D_CPU1_SB_DQ<27>")
	)
	(segment
		(start 52.95519 -201.994262)
		(end 50.254662 -201.994262)
		(width 0.18288)
		(layer "In11.Cu")
		(net "M_D_CPU1_SB_DQ<27>")
	)
	(segment
		(start 39.2684 -200.928986)
		(end 39.07536 -201.122026)
		(width 0.18288)
		(layer "In11.Cu")
		(net "M_D_CPU1_SB_DQ<27>")
	)
	(segment
		(start 27.102816 -200.551542)
		(end 26.909776 -200.744582)
		(width 0.18288)
		(layer "In11.Cu")
		(net "M_D_CPU1_SB_DQ<27>")
	)
	(segment
		(start 35.139884 -201.992484)
		(end 34.485834 -201.338434)
		(width 0.18288)
		(layer "In11.Cu")
		(net "M_D_CPU1_SB_DQ<27>")
	)
	(segment
		(start 30.447996 -200.849992)
		(end 30.447996 -200.536556)
		(width 0.18288)
		(layer "In11.Cu")
		(net "M_D_CPU1_SB_DQ<27>")
	)
	(segment
		(start 59.415426 -200.944226)
		(end 59.09056 -201.269092)
		(width 0.18288)
		(layer "In11.Cu")
		(net "M_D_CPU1_SB_DQ<27>")
	)
	(segment
		(start 57.068974 -201.269092)
		(end 55.877714 -201.269092)
		(width 0.18288)
		(layer "In11.Cu")
		(net "M_D_CPU1_SB_DQ<27>")
	)
	(segment
		(start 41.968928 -201.157586)
		(end 41.775888 -201.350626)
		(width 0.18288)
		(layer "In11.Cu")
		(net "M_D_CPU1_SB_DQ<27>")
	)
	(segment
		(start 54.582314 -200.791826)
		(end 53.947314 -201.426826)
		(width 0.18288)
		(layer "In11.Cu")
		(net "M_D_CPU1_SB_DQ<27>")
	)
	(segment
		(start 53.522626 -201.426826)
		(end 52.95519 -201.994262)
		(width 0.18288)
		(layer "In11.Cu")
		(net "M_D_CPU1_SB_DQ<27>")
	)
	(segment
		(start 82.494374 -225.700082)
		(end 73.570846 -216.776554)
		(width 0.18288)
		(layer "In11.Cu")
		(net "M_D_CPU1_SB_DQ<27>")
	)
	(segment
		(start 96.886268 -230.41102)
		(end 96.877378 -230.40594)
		(width 0.088646)
		(layer "In11.Cu")
		(net "M_D_CPU1_SB_DQ<27>")
	)
	(segment
		(start 27.803856 -201.350626)
		(end 27.610816 -201.157586)
		(width 0.18288)
		(layer "In11.Cu")
		(net "M_D_CPU1_SB_DQ<27>")
	)
	(segment
		(start 39.96944 -200.640188)
		(end 39.7764 -200.447148)
		(width 0.18288)
		(layer "In11.Cu")
		(net "M_D_CPU1_SB_DQ<27>")
	)
	(segment
		(start 85.053424 -227.149406)
		(end 85.04301 -227.155502)
		(width 0.088646)
		(layer "In11.Cu")
		(net "M_D_CPU1_SB_DQ<27>")
	)
	(segment
		(start 30.641036 -201.043032)
		(end 30.447996 -200.849992)
		(width 0.18288)
		(layer "In11.Cu")
		(net "M_D_CPU1_SB_DQ<27>")
	)
	(segment
		(start 28.579826 -201.350626)
		(end 27.803856 -201.350626)
		(width 0.18288)
		(layer "In11.Cu")
		(net "M_D_CPU1_SB_DQ<27>")
	)
	(segment
		(start 45.846238 -201.144124)
		(end 45.555408 -200.853294)
		(width 0.18288)
		(layer "In11.Cu")
		(net "M_D_CPU1_SB_DQ<27>")
	)
	(arc
		(start 87.018114 -227.969318)
		(mid 86.883181 -227.835964)
		(end 86.830916 -227.653596)
		(width 0.088646)
		(layer "In11.Cu")
		(net "M_D_CPU1_SB_DQ<27>")
	)
	(arc
		(start 100.362766 -230.900478)
		(mid 100.124871 -230.731525)
		(end 99.844606 -230.650288)
		(width 0.088646)
		(layer "In11.Cu")
		(net "M_D_CPU1_SB_DQ<27>")
	)
	(arc
		(start 91.237054 -228.777292)
		(mid 90.958622 -228.707446)
		(end 90.68181 -228.783388)
		(width 0.088646)
		(layer "In11.Cu")
		(net "M_D_CPU1_SB_DQ<27>")
	)
	(arc
		(start 88.80221 -228.783388)
		(mid 88.615012 -228.833531)
		(end 88.427814 -228.783388)
		(width 0.088646)
		(layer "In11.Cu")
		(net "M_D_CPU1_SB_DQ<27>")
	)
	(arc
		(start 85.983064 -227.155502)
		(mid 85.795866 -227.205645)
		(end 85.608668 -227.155502)
		(width 0.088646)
		(layer "In11.Cu")
		(net "M_D_CPU1_SB_DQ<27>")
	)
	(arc
		(start 97.44456 -230.411274)
		(mid 97.352642 -230.38651)
		(end 97.260664 -230.41102)
		(width 0.088646)
		(layer "In11.Cu")
		(net "M_D_CPU1_SB_DQ<27>")
	)
	(arc
		(start 99.610164 -230.57612)
		(mid 99.422966 -230.525977)
		(end 99.235768 -230.57612)
		(width 0.088646)
		(layer "In11.Cu")
		(net "M_D_CPU1_SB_DQ<27>")
	)
	(arc
		(start 94.051882 -228.774752)
		(mid 93.775407 -228.707432)
		(end 93.50121 -228.783388)
		(width 0.088646)
		(layer "In11.Cu")
		(net "M_D_CPU1_SB_DQ<27>")
	)
	(arc
		(start 96.698816 -230.086662)
		(mid 96.6249 -229.80716)
		(end 96.422464 -229.60076)
		(width 0.088646)
		(layer "In11.Cu")
		(net "M_D_CPU1_SB_DQ<27>")
	)
	(arc
		(start 88.4174 -228.777292)
		(mid 88.139222 -228.707569)
		(end 87.862664 -228.783388)
		(width 0.088646)
		(layer "In11.Cu")
		(net "M_D_CPU1_SB_DQ<27>")
	)
	(arc
		(start 96.407478 -229.592124)
		(mid 96.276564 -229.455764)
		(end 96.228916 -229.272846)
		(width 0.088646)
		(layer "In11.Cu")
		(net "M_D_CPU1_SB_DQ<27>")
	)
	(arc
		(start 93.112082 -228.774752)
		(mid 92.835607 -228.707432)
		(end 92.56141 -228.783388)
		(width 0.088646)
		(layer "In11.Cu")
		(net "M_D_CPU1_SB_DQ<27>")
	)
	(arc
		(start 95.38081 -228.783388)
		(mid 95.193612 -228.833531)
		(end 95.006414 -228.783388)
		(width 0.088646)
		(layer "In11.Cu")
		(net "M_D_CPU1_SB_DQ<27>")
	)
	(arc
		(start 96.877378 -230.40594)
		(mid 96.746464 -230.26958)
		(end 96.698816 -230.086662)
		(width 0.088646)
		(layer "In11.Cu")
		(net "M_D_CPU1_SB_DQ<27>")
	)
	(arc
		(start 87.300816 -228.45903)
		(mid 87.228643 -228.182362)
		(end 87.030306 -227.97643)
		(width 0.088646)
		(layer "In11.Cu")
		(net "M_D_CPU1_SB_DQ<27>")
	)
	(arc
		(start 85.04301 -227.155502)
		(mid 84.855812 -227.205645)
		(end 84.668614 -227.155502)
		(width 0.088646)
		(layer "In11.Cu")
		(net "M_D_CPU1_SB_DQ<27>")
	)
	(arc
		(start 91.621864 -228.783388)
		(mid 91.434666 -228.833531)
		(end 91.247468 -228.783388)
		(width 0.088646)
		(layer "In11.Cu")
		(net "M_D_CPU1_SB_DQ<27>")
	)
	(arc
		(start 92.56141 -228.783388)
		(mid 92.374212 -228.833531)
		(end 92.187014 -228.783388)
		(width 0.088646)
		(layer "In11.Cu")
		(net "M_D_CPU1_SB_DQ<27>")
	)
	(arc
		(start 95.006414 -228.783388)
		(mid 94.723712 -228.707612)
		(end 94.44101 -228.783388)
		(width 0.088646)
		(layer "In11.Cu")
		(net "M_D_CPU1_SB_DQ<27>")
	)
	(arc
		(start 97.260664 -230.41102)
		(mid 97.073466 -230.461163)
		(end 96.886268 -230.41102)
		(width 0.088646)
		(layer "In11.Cu")
		(net "M_D_CPU1_SB_DQ<27>")
	)
	(arc
		(start 87.479378 -228.778308)
		(mid 87.348464 -228.641948)
		(end 87.300816 -228.45903)
		(width 0.088646)
		(layer "In11.Cu")
		(net "M_D_CPU1_SB_DQ<27>")
	)
	(arc
		(start 98.295968 -230.57612)
		(mid 98.013266 -230.651896)
		(end 97.730564 -230.57612)
		(width 0.088646)
		(layer "In11.Cu")
		(net "M_D_CPU1_SB_DQ<27>")
	)
	(arc
		(start 96.228916 -229.272846)
		(mid 96.154925 -228.99328)
		(end 95.95231 -228.786944)
		(width 0.088646)
		(layer "In11.Cu")
		(net "M_D_CPU1_SB_DQ<27>")
	)
	(arc
		(start 90.68181 -228.783388)
		(mid 90.494612 -228.833531)
		(end 90.307414 -228.783388)
		(width 0.088646)
		(layer "In11.Cu")
		(net "M_D_CPU1_SB_DQ<27>")
	)
	(arc
		(start 92.1766 -228.777292)
		(mid 91.898422 -228.707569)
		(end 91.621864 -228.783388)
		(width 0.088646)
		(layer "In11.Cu")
		(net "M_D_CPU1_SB_DQ<27>")
	)
	(arc
		(start 90.292682 -228.774752)
		(mid 90.016207 -228.707432)
		(end 89.74201 -228.783388)
		(width 0.088646)
		(layer "In11.Cu")
		(net "M_D_CPU1_SB_DQ<27>")
	)
	(arc
		(start 85.608668 -227.155502)
		(mid 85.331855 -227.079632)
		(end 85.053424 -227.149406)
		(width 0.088646)
		(layer "In11.Cu")
		(net "M_D_CPU1_SB_DQ<27>")
	)
	(arc
		(start 84.668614 -227.155502)
		(mid 84.532245 -227.09906)
		(end 84.385912 -227.07981)
		(width 0.088646)
		(layer "In11.Cu")
		(net "M_D_CPU1_SB_DQ<27>")
	)
	(arc
		(start 89.74201 -228.783388)
		(mid 89.554812 -228.833531)
		(end 89.367614 -228.783388)
		(width 0.088646)
		(layer "In11.Cu")
		(net "M_D_CPU1_SB_DQ<27>")
	)
	(arc
		(start 93.50121 -228.783388)
		(mid 93.314012 -228.833531)
		(end 93.126814 -228.783388)
		(width 0.088646)
		(layer "In11.Cu")
		(net "M_D_CPU1_SB_DQ<27>")
	)
	(arc
		(start 98.67011 -230.57612)
		(mid 98.483056 -230.52607)
		(end 98.295968 -230.57612)
		(width 0.088646)
		(layer "In11.Cu")
		(net "M_D_CPU1_SB_DQ<27>")
	)
	(arc
		(start 99.235768 -230.57612)
		(mid 98.953176 -230.651896)
		(end 98.670618 -230.57612)
		(width 0.088646)
		(layer "In11.Cu")
		(net "M_D_CPU1_SB_DQ<27>")
	)
	(arc
		(start 87.862664 -228.783388)
		(mid 87.675466 -228.833531)
		(end 87.488268 -228.783388)
		(width 0.088646)
		(layer "In11.Cu")
		(net "M_D_CPU1_SB_DQ<27>")
	)
	(arc
		(start 99.82835 -230.64851)
		(mid 99.72359 -230.626313)
		(end 99.624896 -230.584756)
		(width 0.088646)
		(layer "In11.Cu")
		(net "M_D_CPU1_SB_DQ<27>")
	)
	(arc
		(start 86.830916 -227.64496)
		(mid 86.756925 -227.365394)
		(end 86.55431 -227.159058)
		(width 0.088646)
		(layer "In11.Cu")
		(net "M_D_CPU1_SB_DQ<27>")
	)
	(arc
		(start 86.5378 -227.149406)
		(mid 86.259622 -227.079683)
		(end 85.983064 -227.155502)
		(width 0.088646)
		(layer "In11.Cu")
		(net "M_D_CPU1_SB_DQ<27>")
	)
	(arc
		(start 89.352882 -228.774752)
		(mid 89.076407 -228.707432)
		(end 88.80221 -228.783388)
		(width 0.088646)
		(layer "In11.Cu")
		(net "M_D_CPU1_SB_DQ<27>")
	)
	(arc
		(start 94.44101 -228.783388)
		(mid 94.253812 -228.833531)
		(end 94.066614 -228.783388)
		(width 0.088646)
		(layer "In11.Cu")
		(net "M_D_CPU1_SB_DQ<27>")
	)
	(arc
		(start 95.931482 -228.774752)
		(mid 95.655007 -228.707432)
		(end 95.38081 -228.783388)
		(width 0.088646)
		(layer "In11.Cu")
		(net "M_D_CPU1_SB_DQ<27>")
	)
	(segment
		(start 14.570202 -202.84186)
		(end 14.825218 -202.84186)
		(width 0.101854)
		(layer "F.Cu")
		(net "M_D_CPU1_SB_DQ<26>")
	)
	(segment
		(start 16.885158 -202.84186)
		(end 17.518126 -202.84186)
		(width 0.20066)
		(layer "F.Cu")
		(net "M_D_CPU1_SB_DQ<26>")
	)
	(segment
		(start 13.387578 -203.266802)
		(end 13.82268 -202.8317)
		(width 0.20066)
		(layer "F.Cu")
		(net "M_D_CPU1_SB_DQ<26>")
	)
	(segment
		(start 13.82268 -202.8317)
		(end 14.560042 -202.8317)
		(width 0.20066)
		(layer "F.Cu")
		(net "M_D_CPU1_SB_DQ<26>")
	)
	(segment
		(start 18.257774 -203.478638)
		(end 18.46961 -203.266802)
		(width 0.20066)
		(layer "F.Cu")
		(net "M_D_CPU1_SB_DQ<26>")
	)
	(segment
		(start 17.518126 -202.84186)
		(end 17.66189 -202.985624)
		(width 0.20066)
		(layer "F.Cu")
		(net "M_D_CPU1_SB_DQ<26>")
	)
	(segment
		(start 20.889214 -203.266802)
		(end 19.784314 -203.266802)
		(width 0.20066)
		(layer "F.Cu")
		(net "M_D_CPU1_SB_DQ<26>")
	)
	(segment
		(start 17.829276 -203.478638)
		(end 18.257774 -203.478638)
		(width 0.20066)
		(layer "F.Cu")
		(net "M_D_CPU1_SB_DQ<26>")
	)
	(segment
		(start 14.825218 -202.84186)
		(end 16.885158 -202.84186)
		(width 0.1016)
		(layer "F.Cu")
		(net "M_D_CPU1_SB_DQ<26>")
	)
	(segment
		(start 18.46961 -203.266802)
		(end 19.784314 -203.266802)
		(width 0.20066)
		(layer "F.Cu")
		(net "M_D_CPU1_SB_DQ<26>")
	)
	(segment
		(start 14.560042 -202.8317)
		(end 14.570202 -202.84186)
		(width 0.101854)
		(layer "F.Cu")
		(net "M_D_CPU1_SB_DQ<26>")
	)
	(segment
		(start 12.240514 -203.266802)
		(end 13.387578 -203.266802)
		(width 0.20066)
		(layer "F.Cu")
		(net "M_D_CPU1_SB_DQ<26>")
	)
	(segment
		(start 17.66189 -203.311252)
		(end 17.829276 -203.478638)
		(width 0.20066)
		(layer "F.Cu")
		(net "M_D_CPU1_SB_DQ<26>")
	)
	(segment
		(start 99.892866 -232.250488)
		(end 99.892612 -232.250234)
		(width 0.20066)
		(layer "F.Cu")
		(net "M_D_CPU1_SB_DQ<26>")
	)
	(segment
		(start 99.892612 -232.250234)
		(end 99.892612 -231.714548)
		(width 0.20066)
		(layer "F.Cu")
		(net "M_D_CPU1_SB_DQ<26>")
	)
	(segment
		(start 17.66189 -202.985624)
		(end 17.66189 -203.311252)
		(width 0.20066)
		(layer "F.Cu")
		(net "M_D_CPU1_SB_DQ<26>")
	)
	(segment
		(start 60.668916 -205.577948)
		(end 60.510166 -205.419198)
		(width 0.18288)
		(layer "In11.Cu")
		(net "M_D_CPU1_SB_DQ<26>")
	)
	(segment
		(start 23.069804 -203.222098)
		(end 22.876764 -203.415138)
		(width 0.18288)
		(layer "In11.Cu")
		(net "M_D_CPU1_SB_DQ<26>")
	)
	(segment
		(start 87.958168 -229.597204)
		(end 87.947754 -229.591108)
		(width 0.088646)
		(layer "In11.Cu")
		(net "M_D_CPU1_SB_DQ<26>")
	)
	(segment
		(start 30.89402 -202.882246)
		(end 30.89402 -203.289154)
		(width 0.18288)
		(layer "In11.Cu")
		(net "M_D_CPU1_SB_DQ<26>")
	)
	(segment
		(start 93.046296 -229.588568)
		(end 93.031564 -229.597204)
		(width 0.088646)
		(layer "In11.Cu")
		(net "M_D_CPU1_SB_DQ<26>")
	)
	(segment
		(start 61.059568 -204.040486)
		(end 59.751214 -204.040486)
		(width 0.18288)
		(layer "In11.Cu")
		(net "M_D_CPU1_SB_DQ<26>")
	)
	(segment
		(start 82.036158 -226.776026)
		(end 72.486266 -217.226134)
		(width 0.18288)
		(layer "In11.Cu")
		(net "M_D_CPU1_SB_DQ<26>")
	)
	(segment
		(start 28.732226 -203.103226)
		(end 25.531826 -203.103226)
		(width 0.18288)
		(layer "In11.Cu")
		(net "M_D_CPU1_SB_DQ<26>")
	)
	(segment
		(start 97.825814 -232.038906)
		(end 97.811082 -232.03027)
		(width 0.088646)
		(layer "In11.Cu")
		(net "M_D_CPU1_SB_DQ<26>")
	)
	(segment
		(start 83.86699 -228.020372)
		(end 82.620866 -226.774248)
		(width 0.088646)
		(layer "In11.Cu")
		(net "M_D_CPU1_SB_DQ<26>")
	)
	(segment
		(start 60.64758 -204.859636)
		(end 61.059568 -204.859636)
		(width 0.18288)
		(layer "In11.Cu")
		(net "M_D_CPU1_SB_DQ<26>")
	)
	(segment
		(start 30.89402 -203.289154)
		(end 30.734 -203.449174)
		(width 0.18288)
		(layer "In11.Cu")
		(net "M_D_CPU1_SB_DQ<26>")
	)
	(segment
		(start 41.707562 -203.455016)
		(end 41.514522 -203.648056)
		(width 0.18288)
		(layer "In11.Cu")
		(net "M_D_CPU1_SB_DQ<26>")
	)
	(segment
		(start 86.548468 -228.783388)
		(end 86.539578 -228.778308)
		(width 0.088646)
		(layer "In11.Cu")
		(net "M_D_CPU1_SB_DQ<26>")
	)
	(segment
		(start 23.577804 -203.415138)
		(end 23.384764 -203.222098)
		(width 0.18288)
		(layer "In11.Cu")
		(net "M_D_CPU1_SB_DQ<26>")
	)
	(segment
		(start 60.510166 -204.99705)
		(end 60.64758 -204.859636)
		(width 0.18288)
		(layer "In11.Cu")
		(net "M_D_CPU1_SB_DQ<26>")
	)
	(segment
		(start 22.876764 -203.566776)
		(end 22.683724 -203.759816)
		(width 0.18288)
		(layer "In11.Cu")
		(net "M_D_CPU1_SB_DQ<26>")
	)
	(segment
		(start 98.214434 -232.030778)
		(end 98.20021 -232.038906)
		(width 0.088646)
		(layer "In11.Cu")
		(net "M_D_CPU1_SB_DQ<26>")
	)
	(segment
		(start 35.214306 -203.692506)
		(end 34.37636 -202.85456)
		(width 0.18288)
		(layer "In11.Cu")
		(net "M_D_CPU1_SB_DQ<26>")
	)
	(segment
		(start 44.240958 -202.707494)
		(end 44.023026 -202.925426)
		(width 0.18288)
		(layer "In11.Cu")
		(net "M_D_CPU1_SB_DQ<26>")
	)
	(segment
		(start 72.486266 -217.226134)
		(end 72.486266 -214.34806)
		(width 0.18288)
		(layer "In11.Cu")
		(net "M_D_CPU1_SB_DQ<26>")
	)
	(segment
		(start 22.876764 -203.415138)
		(end 22.876764 -203.566776)
		(width 0.18288)
		(layer "In11.Cu")
		(net "M_D_CPU1_SB_DQ<26>")
	)
	(segment
		(start 45.852588 -202.842368)
		(end 45.717714 -202.707494)
		(width 0.18288)
		(layer "In11.Cu")
		(net "M_D_CPU1_SB_DQ<26>")
	)
	(segment
		(start 86.078568 -227.969318)
		(end 86.068154 -227.963222)
		(width 0.088646)
		(layer "In11.Cu")
		(net "M_D_CPU1_SB_DQ<26>")
	)
	(segment
		(start 66.444876 -208.916524)
		(end 64.980058 -207.451706)
		(width 0.18288)
		(layer "In11.Cu")
		(net "M_D_CPU1_SB_DQ<26>")
	)
	(segment
		(start 52.95773 -203.693522)
		(end 50.175922 -203.693522)
		(width 0.18288)
		(layer "In11.Cu")
		(net "M_D_CPU1_SB_DQ<26>")
	)
	(segment
		(start 96.416368 -231.224836)
		(end 96.407478 -231.219756)
		(width 0.088646)
		(layer "In11.Cu")
		(net "M_D_CPU1_SB_DQ<26>")
	)
	(segment
		(start 41.514522 -203.648056)
		(end 41.199562 -203.648056)
		(width 0.18288)
		(layer "In11.Cu")
		(net "M_D_CPU1_SB_DQ<26>")
	)
	(segment
		(start 31.557214 -202.8444)
		(end 31.43504 -202.722226)
		(width 0.18288)
		(layer "In11.Cu")
		(net "M_D_CPU1_SB_DQ<26>")
	)
	(segment
		(start 34.37636 -202.85456)
		(end 33.493964 -202.85456)
		(width 0.18288)
		(layer "In11.Cu")
		(net "M_D_CPU1_SB_DQ<26>")
	)
	(segment
		(start 23.770844 -203.759816)
		(end 23.577804 -203.566776)
		(width 0.18288)
		(layer "In11.Cu")
		(net "M_D_CPU1_SB_DQ<26>")
	)
	(segment
		(start 33.493964 -202.85456)
		(end 33.176718 -203.171806)
		(width 0.18288)
		(layer "In11.Cu")
		(net "M_D_CPU1_SB_DQ<26>")
	)
	(segment
		(start 59.751214 -204.040486)
		(end 58.73242 -203.021692)
		(width 0.18288)
		(layer "In11.Cu")
		(net "M_D_CPU1_SB_DQ<26>")
	)
	(segment
		(start 31.43504 -202.722226)
		(end 31.05404 -202.722226)
		(width 0.18288)
		(layer "In11.Cu")
		(net "M_D_CPU1_SB_DQ<26>")
	)
	(segment
		(start 37.74567 -203.843382)
		(end 36.909502 -203.843382)
		(width 0.18288)
		(layer "In11.Cu")
		(net "M_D_CPU1_SB_DQ<26>")
	)
	(segment
		(start 82.620866 -226.774248)
		(end 82.37347 -226.774248)
		(width 0.088646)
		(layer "In11.Cu")
		(net "M_D_CPU1_SB_DQ<26>")
	)
	(segment
		(start 21.382228 -203.759816)
		(end 20.889214 -203.266802)
		(width 0.18288)
		(layer "In11.Cu")
		(net "M_D_CPU1_SB_DQ<26>")
	)
	(segment
		(start 57.203594 -202.433682)
		(end 57.010554 -202.626722)
		(width 0.18288)
		(layer "In11.Cu")
		(net "M_D_CPU1_SB_DQ<26>")
	)
	(segment
		(start 38.943026 -202.646026)
		(end 37.74567 -203.843382)
		(width 0.18288)
		(layer "In11.Cu")
		(net "M_D_CPU1_SB_DQ<26>")
	)
	(segment
		(start 30.38602 -203.449174)
		(end 30.19298 -203.256134)
		(width 0.18288)
		(layer "In11.Cu")
		(net "M_D_CPU1_SB_DQ<26>")
	)
	(segment
		(start 88.347296 -229.588568)
		(end 88.332564 -229.597204)
		(width 0.088646)
		(layer "In11.Cu")
		(net "M_D_CPU1_SB_DQ<26>")
	)
	(segment
		(start 42.408602 -203.455016)
		(end 42.408602 -203.118466)
		(width 0.18288)
		(layer "In11.Cu")
		(net "M_D_CPU1_SB_DQ<26>")
	)
	(segment
		(start 23.384764 -203.222098)
		(end 23.069804 -203.222098)
		(width 0.18288)
		(layer "In11.Cu")
		(net "M_D_CPU1_SB_DQ<26>")
	)
	(segment
		(start 85.138514 -227.969318)
		(end 85.123782 -227.960682)
		(width 0.088646)
		(layer "In11.Cu")
		(net "M_D_CPU1_SB_DQ<26>")
	)
	(segment
		(start 42.215562 -202.925426)
		(end 41.900602 -202.925426)
		(width 0.18288)
		(layer "In11.Cu")
		(net "M_D_CPU1_SB_DQ<26>")
	)
	(segment
		(start 93.981778 -229.591108)
		(end 93.971364 -229.597204)
		(width 0.088646)
		(layer "In11.Cu")
		(net "M_D_CPU1_SB_DQ<26>")
	)
	(segment
		(start 32.792924 -203.171806)
		(end 32.465518 -202.8444)
		(width 0.18288)
		(layer "In11.Cu")
		(net "M_D_CPU1_SB_DQ<26>")
	)
	(segment
		(start 48.286416 -203.052426)
		(end 48.076358 -202.842368)
		(width 0.18288)
		(layer "In11.Cu")
		(net "M_D_CPU1_SB_DQ<26>")
	)
	(segment
		(start 60.510166 -205.419198)
		(end 60.510166 -204.99705)
		(width 0.18288)
		(layer "In11.Cu")
		(net "M_D_CPU1_SB_DQ<26>")
	)
	(segment
		(start 63.555626 -206.456026)
		(end 62.677548 -205.577948)
		(width 0.18288)
		(layer "In11.Cu")
		(net "M_D_CPU1_SB_DQ<26>")
	)
	(segment
		(start 64.335406 -206.456026)
		(end 63.555626 -206.456026)
		(width 0.18288)
		(layer "In11.Cu")
		(net "M_D_CPU1_SB_DQ<26>")
	)
	(segment
		(start 57.010554 -202.626722)
		(end 57.010554 -202.828652)
		(width 0.18288)
		(layer "In11.Cu")
		(net "M_D_CPU1_SB_DQ<26>")
	)
	(segment
		(start 30.734 -203.449174)
		(end 30.38602 -203.449174)
		(width 0.18288)
		(layer "In11.Cu")
		(net "M_D_CPU1_SB_DQ<26>")
	)
	(segment
		(start 41.006522 -203.118466)
		(end 40.813482 -202.925426)
		(width 0.18288)
		(layer "In11.Cu")
		(net "M_D_CPU1_SB_DQ<26>")
	)
	(segment
		(start 40.813482 -202.925426)
		(end 40.633396 -202.925426)
		(width 0.18288)
		(layer "In11.Cu")
		(net "M_D_CPU1_SB_DQ<26>")
	)
	(segment
		(start 43.109642 -203.455016)
		(end 42.916602 -203.648056)
		(width 0.18288)
		(layer "In11.Cu")
		(net "M_D_CPU1_SB_DQ<26>")
	)
	(segment
		(start 45.717714 -202.707494)
		(end 44.240958 -202.707494)
		(width 0.18288)
		(layer "In11.Cu")
		(net "M_D_CPU1_SB_DQ<26>")
	)
	(segment
		(start 62.677548 -205.577948)
		(end 60.668916 -205.577948)
		(width 0.18288)
		(layer "In11.Cu")
		(net "M_D_CPU1_SB_DQ<26>")
	)
	(segment
		(start 22.683724 -203.759816)
		(end 21.382228 -203.759816)
		(width 0.18288)
		(layer "In11.Cu")
		(net "M_D_CPU1_SB_DQ<26>")
	)
	(segment
		(start 57.904634 -203.021692)
		(end 57.711594 -202.828652)
		(width 0.18288)
		(layer "In11.Cu")
		(net "M_D_CPU1_SB_DQ<26>")
	)
	(segment
		(start 24.875236 -203.759816)
		(end 23.770844 -203.759816)
		(width 0.18288)
		(layer "In11.Cu")
		(net "M_D_CPU1_SB_DQ<26>")
	)
	(segment
		(start 48.076358 -202.842368)
		(end 45.852588 -202.842368)
		(width 0.18288)
		(layer "In11.Cu")
		(net "M_D_CPU1_SB_DQ<26>")
	)
	(segment
		(start 72.486266 -214.34806)
		(end 67.05473 -208.916524)
		(width 0.18288)
		(layer "In11.Cu")
		(net "M_D_CPU1_SB_DQ<26>")
	)
	(segment
		(start 30.19298 -203.256134)
		(end 30.19298 -202.882246)
		(width 0.18288)
		(layer "In11.Cu")
		(net "M_D_CPU1_SB_DQ<26>")
	)
	(segment
		(start 44.023026 -202.925426)
		(end 43.302682 -202.925426)
		(width 0.18288)
		(layer "In11.Cu")
		(net "M_D_CPU1_SB_DQ<26>")
	)
	(segment
		(start 95.95231 -230.414576)
		(end 95.946214 -230.41102)
		(width 0.088646)
		(layer "In11.Cu")
		(net "M_D_CPU1_SB_DQ<26>")
	)
	(segment
		(start 82.037936 -226.774248)
		(end 82.036158 -226.776026)
		(width 0.18288)
		(layer "In11.Cu")
		(net "M_D_CPU1_SB_DQ<26>")
	)
	(segment
		(start 36.909502 -203.843382)
		(end 36.758626 -203.692506)
		(width 0.18288)
		(layer "In11.Cu")
		(net "M_D_CPU1_SB_DQ<26>")
	)
	(segment
		(start 58.73242 -203.021692)
		(end 57.904634 -203.021692)
		(width 0.18288)
		(layer "In11.Cu")
		(net "M_D_CPU1_SB_DQ<26>")
	)
	(segment
		(start 91.166696 -229.588568)
		(end 91.151964 -229.597204)
		(width 0.088646)
		(layer "In11.Cu")
		(net "M_D_CPU1_SB_DQ<26>")
	)
	(segment
		(start 41.199562 -203.648056)
		(end 41.006522 -203.455016)
		(width 0.18288)
		(layer "In11.Cu")
		(net "M_D_CPU1_SB_DQ<26>")
	)
	(segment
		(start 33.176718 -203.171806)
		(end 32.792924 -203.171806)
		(width 0.18288)
		(layer "In11.Cu")
		(net "M_D_CPU1_SB_DQ<26>")
	)
	(segment
		(start 95.946214 -230.41102)
		(end 95.937324 -230.40594)
		(width 0.088646)
		(layer "In11.Cu")
		(net "M_D_CPU1_SB_DQ<26>")
	)
	(segment
		(start 41.900602 -202.925426)
		(end 41.707562 -203.118466)
		(width 0.18288)
		(layer "In11.Cu")
		(net "M_D_CPU1_SB_DQ<26>")
	)
	(segment
		(start 94.921324 -229.591108)
		(end 94.91091 -229.597204)
		(width 0.088646)
		(layer "In11.Cu")
		(net "M_D_CPU1_SB_DQ<26>")
	)
	(segment
		(start 61.219588 -204.200506)
		(end 61.059568 -204.040486)
		(width 0.18288)
		(layer "In11.Cu")
		(net "M_D_CPU1_SB_DQ<26>")
	)
	(segment
		(start 61.059568 -204.859636)
		(end 61.219588 -204.699616)
		(width 0.18288)
		(layer "In11.Cu")
		(net "M_D_CPU1_SB_DQ<26>")
	)
	(segment
		(start 40.633396 -202.925426)
		(end 40.353996 -202.646026)
		(width 0.18288)
		(layer "In11.Cu")
		(net "M_D_CPU1_SB_DQ<26>")
	)
	(segment
		(start 40.353996 -202.646026)
		(end 38.943026 -202.646026)
		(width 0.18288)
		(layer "In11.Cu")
		(net "M_D_CPU1_SB_DQ<26>")
	)
	(segment
		(start 82.37347 -226.774248)
		(end 82.037936 -226.774248)
		(width 0.18288)
		(layer "In11.Cu")
		(net "M_D_CPU1_SB_DQ<26>")
	)
	(segment
		(start 32.465518 -202.8444)
		(end 31.557214 -202.8444)
		(width 0.18288)
		(layer "In11.Cu")
		(net "M_D_CPU1_SB_DQ<26>")
	)
	(segment
		(start 42.916602 -203.648056)
		(end 42.601642 -203.648056)
		(width 0.18288)
		(layer "In11.Cu")
		(net "M_D_CPU1_SB_DQ<26>")
	)
	(segment
		(start 61.219588 -204.699616)
		(end 61.219588 -204.200506)
		(width 0.18288)
		(layer "In11.Cu")
		(net "M_D_CPU1_SB_DQ<26>")
	)
	(segment
		(start 57.518554 -202.433682)
		(end 57.203594 -202.433682)
		(width 0.18288)
		(layer "In11.Cu")
		(net "M_D_CPU1_SB_DQ<26>")
	)
	(segment
		(start 29.113226 -202.722226)
		(end 28.732226 -203.103226)
		(width 0.18288)
		(layer "In11.Cu")
		(net "M_D_CPU1_SB_DQ<26>")
	)
	(segment
		(start 96.698562 -231.714548)
		(end 96.698562 -231.69245)
		(width 0.088646)
		(layer "In11.Cu")
		(net "M_D_CPU1_SB_DQ<26>")
	)
	(segment
		(start 57.711594 -202.626722)
		(end 57.518554 -202.433682)
		(width 0.18288)
		(layer "In11.Cu")
		(net "M_D_CPU1_SB_DQ<26>")
	)
	(segment
		(start 86.361016 -228.45903)
		(end 86.361016 -228.440488)
		(width 0.088646)
		(layer "In11.Cu")
		(net "M_D_CPU1_SB_DQ<26>")
	)
	(segment
		(start 49.534826 -203.052426)
		(end 48.286416 -203.052426)
		(width 0.18288)
		(layer "In11.Cu")
		(net "M_D_CPU1_SB_DQ<26>")
	)
	(segment
		(start 43.302682 -202.925426)
		(end 43.109642 -203.118466)
		(width 0.18288)
		(layer "In11.Cu")
		(net "M_D_CPU1_SB_DQ<26>")
	)
	(segment
		(start 92.106496 -229.588568)
		(end 92.091764 -229.597204)
		(width 0.088646)
		(layer "In11.Cu")
		(net "M_D_CPU1_SB_DQ<26>")
	)
	(segment
		(start 96.886014 -232.038906)
		(end 96.877124 -232.033826)
		(width 0.088646)
		(layer "In11.Cu")
		(net "M_D_CPU1_SB_DQ<26>")
	)
	(segment
		(start 23.577804 -203.566776)
		(end 23.577804 -203.415138)
		(width 0.18288)
		(layer "In11.Cu")
		(net "M_D_CPU1_SB_DQ<26>")
	)
	(segment
		(start 53.90896 -202.742292)
		(end 52.95773 -203.693522)
		(width 0.18288)
		(layer "In11.Cu")
		(net "M_D_CPU1_SB_DQ<26>")
	)
	(segment
		(start 95.758762 -230.086662)
		(end 95.758762 -230.071168)
		(width 0.088646)
		(layer "In11.Cu")
		(net "M_D_CPU1_SB_DQ<26>")
	)
	(segment
		(start 42.601642 -203.648056)
		(end 42.408602 -203.455016)
		(width 0.18288)
		(layer "In11.Cu")
		(net "M_D_CPU1_SB_DQ<26>")
	)
	(segment
		(start 41.707562 -203.118466)
		(end 41.707562 -203.455016)
		(width 0.18288)
		(layer "In11.Cu")
		(net "M_D_CPU1_SB_DQ<26>")
	)
	(segment
		(start 31.05404 -202.722226)
		(end 30.89402 -202.882246)
		(width 0.18288)
		(layer "In11.Cu")
		(net "M_D_CPU1_SB_DQ<26>")
	)
	(segment
		(start 55.699914 -203.021692)
		(end 55.420514 -202.742292)
		(width 0.18288)
		(layer "In11.Cu")
		(net "M_D_CPU1_SB_DQ<26>")
	)
	(segment
		(start 50.175922 -203.693522)
		(end 49.534826 -203.052426)
		(width 0.18288)
		(layer "In11.Cu")
		(net "M_D_CPU1_SB_DQ<26>")
	)
	(segment
		(start 86.830916 -229.281482)
		(end 86.830916 -229.26294)
		(width 0.088646)
		(layer "In11.Cu")
		(net "M_D_CPU1_SB_DQ<26>")
	)
	(segment
		(start 57.711594 -202.828652)
		(end 57.711594 -202.626722)
		(width 0.18288)
		(layer "In11.Cu")
		(net "M_D_CPU1_SB_DQ<26>")
	)
	(segment
		(start 36.758626 -203.692506)
		(end 35.214306 -203.692506)
		(width 0.18288)
		(layer "In11.Cu")
		(net "M_D_CPU1_SB_DQ<26>")
	)
	(segment
		(start 64.980058 -207.451706)
		(end 64.980058 -207.100678)
		(width 0.18288)
		(layer "In11.Cu")
		(net "M_D_CPU1_SB_DQ<26>")
	)
	(segment
		(start 55.420514 -202.742292)
		(end 53.90896 -202.742292)
		(width 0.18288)
		(layer "In11.Cu")
		(net "M_D_CPU1_SB_DQ<26>")
	)
	(segment
		(start 43.109642 -203.118466)
		(end 43.109642 -203.455016)
		(width 0.18288)
		(layer "In11.Cu")
		(net "M_D_CPU1_SB_DQ<26>")
	)
	(segment
		(start 64.980058 -207.100678)
		(end 64.335406 -206.456026)
		(width 0.18288)
		(layer "In11.Cu")
		(net "M_D_CPU1_SB_DQ<26>")
	)
	(segment
		(start 30.19298 -202.882246)
		(end 30.03296 -202.722226)
		(width 0.18288)
		(layer "In11.Cu")
		(net "M_D_CPU1_SB_DQ<26>")
	)
	(segment
		(start 84.385912 -228.020372)
		(end 83.86699 -228.020372)
		(width 0.088646)
		(layer "In11.Cu")
		(net "M_D_CPU1_SB_DQ<26>")
	)
	(segment
		(start 56.817514 -203.021692)
		(end 55.699914 -203.021692)
		(width 0.18288)
		(layer "In11.Cu")
		(net "M_D_CPU1_SB_DQ<26>")
	)
	(segment
		(start 57.010554 -202.828652)
		(end 56.817514 -203.021692)
		(width 0.18288)
		(layer "In11.Cu")
		(net "M_D_CPU1_SB_DQ<26>")
	)
	(segment
		(start 41.006522 -203.455016)
		(end 41.006522 -203.118466)
		(width 0.18288)
		(layer "In11.Cu")
		(net "M_D_CPU1_SB_DQ<26>")
	)
	(segment
		(start 89.287096 -229.588568)
		(end 89.272364 -229.597204)
		(width 0.088646)
		(layer "In11.Cu")
		(net "M_D_CPU1_SB_DQ<26>")
	)
	(segment
		(start 67.05473 -208.916524)
		(end 66.444876 -208.916524)
		(width 0.18288)
		(layer "In11.Cu")
		(net "M_D_CPU1_SB_DQ<26>")
	)
	(segment
		(start 25.531826 -203.103226)
		(end 24.875236 -203.759816)
		(width 0.18288)
		(layer "In11.Cu")
		(net "M_D_CPU1_SB_DQ<26>")
	)
	(segment
		(start 30.03296 -202.722226)
		(end 29.113226 -202.722226)
		(width 0.18288)
		(layer "In11.Cu")
		(net "M_D_CPU1_SB_DQ<26>")
	)
	(segment
		(start 42.408602 -203.118466)
		(end 42.215562 -202.925426)
		(width 0.18288)
		(layer "In11.Cu")
		(net "M_D_CPU1_SB_DQ<26>")
	)
	(arc
		(start 87.39251 -229.597204)
		(mid 87.205312 -229.647347)
		(end 87.018114 -229.597204)
		(width 0.088646)
		(layer "In11.Cu")
		(net "M_D_CPU1_SB_DQ<26>")
	)
	(arc
		(start 98.37928 -231.85628)
		(mid 98.309618 -231.955579)
		(end 98.214434 -232.030778)
		(width 0.088646)
		(layer "In11.Cu")
		(net "M_D_CPU1_SB_DQ<26>")
	)
	(arc
		(start 97.26041 -232.038906)
		(mid 97.073212 -232.089049)
		(end 96.886014 -232.038906)
		(width 0.088646)
		(layer "In11.Cu")
		(net "M_D_CPU1_SB_DQ<26>")
	)
	(arc
		(start 95.758762 -230.071168)
		(mid 95.679392 -229.797434)
		(end 95.476568 -229.597204)
		(width 0.088646)
		(layer "In11.Cu")
		(net "M_D_CPU1_SB_DQ<26>")
	)
	(arc
		(start 96.407478 -231.219756)
		(mid 96.276564 -231.083396)
		(end 96.228916 -230.900478)
		(width 0.088646)
		(layer "In11.Cu")
		(net "M_D_CPU1_SB_DQ<26>")
	)
	(arc
		(start 96.228916 -230.900478)
		(mid 96.154925 -230.620912)
		(end 95.95231 -230.414576)
		(width 0.088646)
		(layer "In11.Cu")
		(net "M_D_CPU1_SB_DQ<26>")
	)
	(arc
		(start 98.683826 -231.424226)
		(mid 98.51558 -231.628994)
		(end 98.37928 -231.85628)
		(width 0.088646)
		(layer "In11.Cu")
		(net "M_D_CPU1_SB_DQ<26>")
	)
	(arc
		(start 86.068154 -227.963222)
		(mid 85.789722 -227.893408)
		(end 85.51291 -227.969318)
		(width 0.088646)
		(layer "In11.Cu")
		(net "M_D_CPU1_SB_DQ<26>")
	)
	(arc
		(start 96.877124 -232.033826)
		(mid 96.74621 -231.897466)
		(end 96.698562 -231.714548)
		(width 0.088646)
		(layer "In11.Cu")
		(net "M_D_CPU1_SB_DQ<26>")
	)
	(arc
		(start 92.657168 -229.597204)
		(mid 92.382969 -229.521369)
		(end 92.106496 -229.588568)
		(width 0.088646)
		(layer "In11.Cu")
		(net "M_D_CPU1_SB_DQ<26>")
	)
	(arc
		(start 95.937324 -230.40594)
		(mid 95.80641 -230.26958)
		(end 95.758762 -230.086662)
		(width 0.088646)
		(layer "In11.Cu")
		(net "M_D_CPU1_SB_DQ<26>")
	)
	(arc
		(start 93.031564 -229.597204)
		(mid 92.844366 -229.647347)
		(end 92.657168 -229.597204)
		(width 0.088646)
		(layer "In11.Cu")
		(net "M_D_CPU1_SB_DQ<26>")
	)
	(arc
		(start 89.837768 -229.597204)
		(mid 89.563569 -229.521369)
		(end 89.287096 -229.588568)
		(width 0.088646)
		(layer "In11.Cu")
		(net "M_D_CPU1_SB_DQ<26>")
	)
	(arc
		(start 87.947754 -229.591108)
		(mid 87.669322 -229.521262)
		(end 87.39251 -229.597204)
		(width 0.088646)
		(layer "In11.Cu")
		(net "M_D_CPU1_SB_DQ<26>")
	)
	(arc
		(start 86.539578 -228.778308)
		(mid 86.408664 -228.641948)
		(end 86.361016 -228.45903)
		(width 0.088646)
		(layer "In11.Cu")
		(net "M_D_CPU1_SB_DQ<26>")
	)
	(arc
		(start 93.596968 -229.597204)
		(mid 93.322769 -229.521369)
		(end 93.046296 -229.588568)
		(width 0.088646)
		(layer "In11.Cu")
		(net "M_D_CPU1_SB_DQ<26>")
	)
	(arc
		(start 94.536514 -229.597204)
		(mid 94.259955 -229.521461)
		(end 93.981778 -229.591108)
		(width 0.088646)
		(layer "In11.Cu")
		(net "M_D_CPU1_SB_DQ<26>")
	)
	(arc
		(start 84.57311 -227.969318)
		(mid 84.482874 -228.007188)
		(end 84.385912 -228.020372)
		(width 0.088646)
		(layer "In11.Cu")
		(net "M_D_CPU1_SB_DQ<26>")
	)
	(arc
		(start 98.20021 -232.038906)
		(mid 98.013012 -232.089049)
		(end 97.825814 -232.038906)
		(width 0.088646)
		(layer "In11.Cu")
		(net "M_D_CPU1_SB_DQ<26>")
	)
	(arc
		(start 94.91091 -229.597204)
		(mid 94.723712 -229.647347)
		(end 94.536514 -229.597204)
		(width 0.088646)
		(layer "In11.Cu")
		(net "M_D_CPU1_SB_DQ<26>")
	)
	(arc
		(start 95.476568 -229.597204)
		(mid 95.199755 -229.521334)
		(end 94.921324 -229.591108)
		(width 0.088646)
		(layer "In11.Cu")
		(net "M_D_CPU1_SB_DQ<26>")
	)
	(arc
		(start 89.272364 -229.597204)
		(mid 89.085166 -229.647347)
		(end 88.897968 -229.597204)
		(width 0.088646)
		(layer "In11.Cu")
		(net "M_D_CPU1_SB_DQ<26>")
	)
	(arc
		(start 99.892612 -231.714548)
		(mid 99.527476 -231.498151)
		(end 99.141026 -231.322626)
		(width 0.088646)
		(layer "In11.Cu")
		(net "M_D_CPU1_SB_DQ<26>")
	)
	(arc
		(start 93.971364 -229.597204)
		(mid 93.784166 -229.647347)
		(end 93.596968 -229.597204)
		(width 0.088646)
		(layer "In11.Cu")
		(net "M_D_CPU1_SB_DQ<26>")
	)
	(arc
		(start 92.091764 -229.597204)
		(mid 91.904566 -229.647347)
		(end 91.717368 -229.597204)
		(width 0.088646)
		(layer "In11.Cu")
		(net "M_D_CPU1_SB_DQ<26>")
	)
	(arc
		(start 91.151964 -229.597204)
		(mid 90.964766 -229.647347)
		(end 90.777568 -229.597204)
		(width 0.088646)
		(layer "In11.Cu")
		(net "M_D_CPU1_SB_DQ<26>")
	)
	(arc
		(start 97.811082 -232.03027)
		(mid 97.534607 -231.96295)
		(end 97.26041 -232.038906)
		(width 0.088646)
		(layer "In11.Cu")
		(net "M_D_CPU1_SB_DQ<26>")
	)
	(arc
		(start 90.212164 -229.597204)
		(mid 90.024966 -229.647347)
		(end 89.837768 -229.597204)
		(width 0.088646)
		(layer "In11.Cu")
		(net "M_D_CPU1_SB_DQ<26>")
	)
	(arc
		(start 85.51291 -227.969318)
		(mid 85.325712 -228.019461)
		(end 85.138514 -227.969318)
		(width 0.088646)
		(layer "In11.Cu")
		(net "M_D_CPU1_SB_DQ<26>")
	)
	(arc
		(start 88.332564 -229.597204)
		(mid 88.145366 -229.647347)
		(end 87.958168 -229.597204)
		(width 0.088646)
		(layer "In11.Cu")
		(net "M_D_CPU1_SB_DQ<26>")
	)
	(arc
		(start 87.018114 -229.597204)
		(mid 86.883181 -229.46385)
		(end 86.830916 -229.281482)
		(width 0.088646)
		(layer "In11.Cu")
		(net "M_D_CPU1_SB_DQ<26>")
	)
	(arc
		(start 85.123782 -227.960682)
		(mid 84.847341 -227.893516)
		(end 84.57311 -227.969318)
		(width 0.088646)
		(layer "In11.Cu")
		(net "M_D_CPU1_SB_DQ<26>")
	)
	(arc
		(start 96.698562 -231.69245)
		(mid 96.617651 -231.422322)
		(end 96.416368 -231.224836)
		(width 0.088646)
		(layer "In11.Cu")
		(net "M_D_CPU1_SB_DQ<26>")
	)
	(arc
		(start 86.830916 -229.26294)
		(mid 86.752805 -228.985991)
		(end 86.548468 -228.783388)
		(width 0.088646)
		(layer "In11.Cu")
		(net "M_D_CPU1_SB_DQ<26>")
	)
	(arc
		(start 88.897968 -229.597204)
		(mid 88.623769 -229.521369)
		(end 88.347296 -229.588568)
		(width 0.088646)
		(layer "In11.Cu")
		(net "M_D_CPU1_SB_DQ<26>")
	)
	(arc
		(start 86.361016 -228.440488)
		(mid 86.280854 -228.168299)
		(end 86.078568 -227.969318)
		(width 0.088646)
		(layer "In11.Cu")
		(net "M_D_CPU1_SB_DQ<26>")
	)
	(arc
		(start 91.717368 -229.597204)
		(mid 91.443169 -229.521369)
		(end 91.166696 -229.588568)
		(width 0.088646)
		(layer "In11.Cu")
		(net "M_D_CPU1_SB_DQ<26>")
	)
	(arc
		(start 90.777568 -229.597204)
		(mid 90.494866 -229.521428)
		(end 90.212164 -229.597204)
		(width 0.088646)
		(layer "In11.Cu")
		(net "M_D_CPU1_SB_DQ<26>")
	)
	(arc
		(start 99.141026 -231.322626)
		(mid 98.896946 -231.303852)
		(end 98.683826 -231.424226)
		(width 0.088646)
		(layer "In11.Cu")
		(net "M_D_CPU1_SB_DQ<26>")
	)
	(segment
		(start 98.483166 -231.436164)
		(end 98.483166 -230.900478)
		(width 0.20066)
		(layer "F.Cu")
		(net "M_D_CPU1_SB_DQ<25>")
	)
	(segment
		(start 9.474708 -202.416664)
		(end 9.686036 -202.627992)
		(width 0.20066)
		(layer "F.Cu")
		(net "M_D_CPU1_SB_DQ<25>")
	)
	(segment
		(start 16.789146 -202.416664)
		(end 15.684246 -202.416664)
		(width 0.20066)
		(layer "F.Cu")
		(net "M_D_CPU1_SB_DQ<25>")
	)
	(segment
		(start 14.04493 -202.416664)
		(end 15.684246 -202.416664)
		(width 0.20066)
		(layer "F.Cu")
		(net "M_D_CPU1_SB_DQ<25>")
	)
	(segment
		(start 8.140446 -202.416664)
		(end 9.474708 -202.416664)
		(width 0.20066)
		(layer "F.Cu")
		(net "M_D_CPU1_SB_DQ<25>")
	)
	(segment
		(start 9.686036 -202.627992)
		(end 10.19048 -202.627992)
		(width 0.20066)
		(layer "F.Cu")
		(net "M_D_CPU1_SB_DQ<25>")
	)
	(segment
		(start 11.11631 -201.982832)
		(end 11.1252 -201.991722)
		(width 0.1016)
		(layer "F.Cu")
		(net "M_D_CPU1_SB_DQ<25>")
	)
	(segment
		(start 10.507472 -201.982832)
		(end 11.11631 -201.982832)
		(width 0.20066)
		(layer "F.Cu")
		(net "M_D_CPU1_SB_DQ<25>")
	)
	(segment
		(start 98.482912 -231.436418)
		(end 98.483166 -231.436164)
		(width 0.20066)
		(layer "F.Cu")
		(net "M_D_CPU1_SB_DQ<25>")
	)
	(segment
		(start 13.619988 -201.991722)
		(end 14.04493 -202.416664)
		(width 0.20066)
		(layer "F.Cu")
		(net "M_D_CPU1_SB_DQ<25>")
	)
	(segment
		(start 13.110718 -201.991722)
		(end 13.441426 -201.991722)
		(width 0.101854)
		(layer "F.Cu")
		(net "M_D_CPU1_SB_DQ<25>")
	)
	(segment
		(start 10.344912 -202.47356)
		(end 10.344912 -202.145392)
		(width 0.20066)
		(layer "F.Cu")
		(net "M_D_CPU1_SB_DQ<25>")
	)
	(segment
		(start 10.19048 -202.627992)
		(end 10.344912 -202.47356)
		(width 0.20066)
		(layer "F.Cu")
		(net "M_D_CPU1_SB_DQ<25>")
	)
	(segment
		(start 10.344912 -202.145392)
		(end 10.507472 -201.982832)
		(width 0.20066)
		(layer "F.Cu")
		(net "M_D_CPU1_SB_DQ<25>")
	)
	(segment
		(start 11.1252 -201.991722)
		(end 13.110718 -201.991722)
		(width 0.1016)
		(layer "F.Cu")
		(net "M_D_CPU1_SB_DQ<25>")
	)
	(segment
		(start 13.441426 -201.991722)
		(end 13.619988 -201.991722)
		(width 0.20066)
		(layer "F.Cu")
		(net "M_D_CPU1_SB_DQ<25>")
	)
	(segment
		(start 73.002648 -214.133938)
		(end 67.078606 -208.209896)
		(width 0.18288)
		(layer "In11.Cu")
		(net "M_D_CPU1_SB_DQ<25>")
	)
	(segment
		(start 44.414694 -202.148694)
		(end 44.124626 -201.858626)
		(width 0.18288)
		(layer "In11.Cu")
		(net "M_D_CPU1_SB_DQ<25>")
	)
	(segment
		(start 27.611324 -202.051666)
		(end 27.611324 -202.336146)
		(width 0.18288)
		(layer "In11.Cu")
		(net "M_D_CPU1_SB_DQ<25>")
	)
	(segment
		(start 42.230802 -202.399138)
		(end 42.037762 -202.206098)
		(width 0.18288)
		(layer "In11.Cu")
		(net "M_D_CPU1_SB_DQ<25>")
	)
	(segment
		(start 27.418284 -202.529186)
		(end 27.103324 -202.529186)
		(width 0.18288)
		(layer "In11.Cu")
		(net "M_D_CPU1_SB_DQ<25>")
	)
	(segment
		(start 88.347296 -228.957124)
		(end 88.332564 -228.948488)
		(width 0.088646)
		(layer "In11.Cu")
		(net "M_D_CPU1_SB_DQ<25>")
	)
	(segment
		(start 37.922454 -202.650598)
		(end 37.251894 -202.650598)
		(width 0.18288)
		(layer "In11.Cu")
		(net "M_D_CPU1_SB_DQ<25>")
	)
	(segment
		(start 41.844722 -201.858626)
		(end 40.416226 -201.858626)
		(width 0.18288)
		(layer "In11.Cu")
		(net "M_D_CPU1_SB_DQ<25>")
	)
	(segment
		(start 42.738802 -202.051666)
		(end 42.738802 -202.206098)
		(width 0.18288)
		(layer "In11.Cu")
		(net "M_D_CPU1_SB_DQ<25>")
	)
	(segment
		(start 97.356422 -231.22509)
		(end 97.355914 -231.224836)
		(width 0.088646)
		(layer "In11.Cu")
		(net "M_D_CPU1_SB_DQ<25>")
	)
	(segment
		(start 25.150826 -201.858626)
		(end 24.338026 -202.671426)
		(width 0.18288)
		(layer "In11.Cu")
		(net "M_D_CPU1_SB_DQ<25>")
	)
	(segment
		(start 52.93233 -202.840082)
		(end 50.160682 -202.840082)
		(width 0.18288)
		(layer "In11.Cu")
		(net "M_D_CPU1_SB_DQ<25>")
	)
	(segment
		(start 19.334734 -203.640436)
		(end 19.334734 -203.035408)
		(width 0.18288)
		(layer "In11.Cu")
		(net "M_D_CPU1_SB_DQ<25>")
	)
	(segment
		(start 47.987458 -201.993246)
		(end 45.85335 -201.993246)
		(width 0.18288)
		(layer "In11.Cu")
		(net "M_D_CPU1_SB_DQ<25>")
	)
	(segment
		(start 87.110316 -228.459284)
		(end 87.110062 -228.458776)
		(width 0.088646)
		(layer "In11.Cu")
		(net "M_D_CPU1_SB_DQ<25>")
	)
	(segment
		(start 40.238426 -202.036426)
		(end 38.536626 -202.036426)
		(width 0.18288)
		(layer "In11.Cu")
		(net "M_D_CPU1_SB_DQ<25>")
	)
	(segment
		(start 18.826734 -202.842368)
		(end 18.633694 -203.035408)
		(width 0.18288)
		(layer "In11.Cu")
		(net "M_D_CPU1_SB_DQ<25>")
	)
	(segment
		(start 53.61432 -202.158092)
		(end 52.93233 -202.840082)
		(width 0.18288)
		(layer "In11.Cu")
		(net "M_D_CPU1_SB_DQ<25>")
	)
	(segment
		(start 20.035774 -203.623164)
		(end 19.825462 -203.833476)
		(width 0.18288)
		(layer "In11.Cu")
		(net "M_D_CPU1_SB_DQ<25>")
	)
	(segment
		(start 21.525484 -202.842368)
		(end 20.228814 -202.842368)
		(width 0.18288)
		(layer "In11.Cu")
		(net "M_D_CPU1_SB_DQ<25>")
	)
	(segment
		(start 19.527774 -203.833476)
		(end 19.334734 -203.640436)
		(width 0.18288)
		(layer "In11.Cu")
		(net "M_D_CPU1_SB_DQ<25>")
	)
	(segment
		(start 63.910972 -205.160626)
		(end 63.022226 -205.160626)
		(width 0.18288)
		(layer "In11.Cu")
		(net "M_D_CPU1_SB_DQ<25>")
	)
	(segment
		(start 82.727292 -226.51212)
		(end 82.727292 -226.317302)
		(width 0.088646)
		(layer "In11.Cu")
		(net "M_D_CPU1_SB_DQ<25>")
	)
	(segment
		(start 19.825462 -203.833476)
		(end 19.527774 -203.833476)
		(width 0.18288)
		(layer "In11.Cu")
		(net "M_D_CPU1_SB_DQ<25>")
	)
	(segment
		(start 18.125694 -203.707746)
		(end 17.932654 -203.514706)
		(width 0.18288)
		(layer "In11.Cu")
		(net "M_D_CPU1_SB_DQ<25>")
	)
	(segment
		(start 27.804364 -201.858626)
		(end 27.611324 -202.051666)
		(width 0.18288)
		(layer "In11.Cu")
		(net "M_D_CPU1_SB_DQ<25>")
	)
	(segment
		(start 65.639188 -206.888842)
		(end 63.910972 -205.160626)
		(width 0.18288)
		(layer "In11.Cu")
		(net "M_D_CPU1_SB_DQ<25>")
	)
	(segment
		(start 27.611324 -202.336146)
		(end 27.418284 -202.529186)
		(width 0.18288)
		(layer "In11.Cu")
		(net "M_D_CPU1_SB_DQ<25>")
	)
	(segment
		(start 42.931842 -201.858626)
		(end 42.738802 -202.051666)
		(width 0.18288)
		(layer "In11.Cu")
		(net "M_D_CPU1_SB_DQ<25>")
	)
	(segment
		(start 55.801514 -202.158092)
		(end 53.61432 -202.158092)
		(width 0.18288)
		(layer "In11.Cu")
		(net "M_D_CPU1_SB_DQ<25>")
	)
	(segment
		(start 42.738802 -202.206098)
		(end 42.545762 -202.399138)
		(width 0.18288)
		(layer "In11.Cu")
		(net "M_D_CPU1_SB_DQ<25>")
	)
	(segment
		(start 82.65922 -226.24923)
		(end 82.37347 -226.24923)
		(width 0.088646)
		(layer "In11.Cu")
		(net "M_D_CPU1_SB_DQ<25>")
	)
	(segment
		(start 94.921324 -228.954584)
		(end 94.91091 -228.948488)
		(width 0.088646)
		(layer "In11.Cu")
		(net "M_D_CPU1_SB_DQ<25>")
	)
	(segment
		(start 96.3295 -229.767384)
		(end 96.32061 -229.762304)
		(width 0.088646)
		(layer "In11.Cu")
		(net "M_D_CPU1_SB_DQ<25>")
	)
	(segment
		(start 20.035774 -203.035408)
		(end 20.035774 -203.623164)
		(width 0.18288)
		(layer "In11.Cu")
		(net "M_D_CPU1_SB_DQ<25>")
	)
	(segment
		(start 96.790764 -230.57612)
		(end 96.778572 -230.569008)
		(width 0.088646)
		(layer "In11.Cu")
		(net "M_D_CPU1_SB_DQ<25>")
	)
	(segment
		(start 17.932654 -203.514706)
		(end 17.932654 -203.035408)
		(width 0.18288)
		(layer "In11.Cu")
		(net "M_D_CPU1_SB_DQ<25>")
	)
	(segment
		(start 63.022226 -205.160626)
		(end 60.888626 -203.027026)
		(width 0.18288)
		(layer "In11.Cu")
		(net "M_D_CPU1_SB_DQ<25>")
	)
	(segment
		(start 18.440654 -203.707746)
		(end 18.125694 -203.707746)
		(width 0.18288)
		(layer "In11.Cu")
		(net "M_D_CPU1_SB_DQ<25>")
	)
	(segment
		(start 26.717244 -201.858626)
		(end 25.150826 -201.858626)
		(width 0.18288)
		(layer "In11.Cu")
		(net "M_D_CPU1_SB_DQ<25>")
	)
	(segment
		(start 29.367226 -202.214226)
		(end 29.011626 -201.858626)
		(width 0.18288)
		(layer "In11.Cu")
		(net "M_D_CPU1_SB_DQ<25>")
	)
	(segment
		(start 86.078568 -227.320602)
		(end 86.068154 -227.326698)
		(width 0.088646)
		(layer "In11.Cu")
		(net "M_D_CPU1_SB_DQ<25>")
	)
	(segment
		(start 67.078606 -208.209896)
		(end 66.457322 -208.209896)
		(width 0.18288)
		(layer "In11.Cu")
		(net "M_D_CPU1_SB_DQ<25>")
	)
	(segment
		(start 42.037762 -202.206098)
		(end 42.037762 -202.051666)
		(width 0.18288)
		(layer "In11.Cu")
		(net "M_D_CPU1_SB_DQ<25>")
	)
	(segment
		(start 45.697902 -202.148694)
		(end 44.414694 -202.148694)
		(width 0.18288)
		(layer "In11.Cu")
		(net "M_D_CPU1_SB_DQ<25>")
	)
	(segment
		(start 27.103324 -202.529186)
		(end 26.910284 -202.336146)
		(width 0.18288)
		(layer "In11.Cu")
		(net "M_D_CPU1_SB_DQ<25>")
	)
	(segment
		(start 35.202368 -202.842368)
		(end 34.24555 -201.88555)
		(width 0.18288)
		(layer "In11.Cu")
		(net "M_D_CPU1_SB_DQ<25>")
	)
	(segment
		(start 56.055514 -201.904092)
		(end 55.801514 -202.158092)
		(width 0.18288)
		(layer "In11.Cu")
		(net "M_D_CPU1_SB_DQ<25>")
	)
	(segment
		(start 65.639188 -207.391762)
		(end 65.639188 -206.888842)
		(width 0.18288)
		(layer "In11.Cu")
		(net "M_D_CPU1_SB_DQ<25>")
	)
	(segment
		(start 50.160682 -202.840082)
		(end 49.19853 -201.87793)
		(width 0.18288)
		(layer "In11.Cu")
		(net "M_D_CPU1_SB_DQ<25>")
	)
	(segment
		(start 19.334734 -203.035408)
		(end 19.141694 -202.842368)
		(width 0.18288)
		(layer "In11.Cu")
		(net "M_D_CPU1_SB_DQ<25>")
	)
	(segment
		(start 24.338026 -202.671426)
		(end 21.696426 -202.671426)
		(width 0.18288)
		(layer "In11.Cu")
		(net "M_D_CPU1_SB_DQ<25>")
	)
	(segment
		(start 60.406026 -203.027026)
		(end 59.283092 -201.904092)
		(width 0.18288)
		(layer "In11.Cu")
		(net "M_D_CPU1_SB_DQ<25>")
	)
	(segment
		(start 40.416226 -201.858626)
		(end 40.238426 -202.036426)
		(width 0.18288)
		(layer "In11.Cu")
		(net "M_D_CPU1_SB_DQ<25>")
	)
	(segment
		(start 59.283092 -201.904092)
		(end 56.055514 -201.904092)
		(width 0.18288)
		(layer "In11.Cu")
		(net "M_D_CPU1_SB_DQ<25>")
	)
	(segment
		(start 17.739614 -202.842368)
		(end 17.21485 -202.842368)
		(width 0.18288)
		(layer "In11.Cu")
		(net "M_D_CPU1_SB_DQ<25>")
	)
	(segment
		(start 90.226896 -228.957124)
		(end 90.212164 -228.948488)
		(width 0.088646)
		(layer "In11.Cu")
		(net "M_D_CPU1_SB_DQ<25>")
	)
	(segment
		(start 21.696426 -202.671426)
		(end 21.525484 -202.842368)
		(width 0.18288)
		(layer "In11.Cu")
		(net "M_D_CPU1_SB_DQ<25>")
	)
	(segment
		(start 30.561026 -202.214226)
		(end 29.367226 -202.214226)
		(width 0.18288)
		(layer "In11.Cu")
		(net "M_D_CPU1_SB_DQ<25>")
	)
	(segment
		(start 26.910284 -202.336146)
		(end 26.910284 -202.051666)
		(width 0.18288)
		(layer "In11.Cu")
		(net "M_D_CPU1_SB_DQ<25>")
	)
	(segment
		(start 86.9315 -228.139498)
		(end 86.92261 -228.134418)
		(width 0.088646)
		(layer "In11.Cu")
		(net "M_D_CPU1_SB_DQ<25>")
	)
	(segment
		(start 42.545762 -202.399138)
		(end 42.230802 -202.399138)
		(width 0.18288)
		(layer "In11.Cu")
		(net "M_D_CPU1_SB_DQ<25>")
	)
	(segment
		(start 45.85335 -201.993246)
		(end 45.697902 -202.148694)
		(width 0.18288)
		(layer "In11.Cu")
		(net "M_D_CPU1_SB_DQ<25>")
	)
	(segment
		(start 73.002648 -217.012012)
		(end 73.002648 -214.133938)
		(width 0.18288)
		(layer "In11.Cu")
		(net "M_D_CPU1_SB_DQ<25>")
	)
	(segment
		(start 92.106496 -228.957124)
		(end 92.091764 -228.948488)
		(width 0.088646)
		(layer "In11.Cu")
		(net "M_D_CPU1_SB_DQ<25>")
	)
	(segment
		(start 83.485228 -227.270056)
		(end 82.727292 -226.51212)
		(width 0.088646)
		(layer "In11.Cu")
		(net "M_D_CPU1_SB_DQ<25>")
	)
	(segment
		(start 32.979106 -201.88555)
		(end 32.874458 -201.990198)
		(width 0.18288)
		(layer "In11.Cu")
		(net "M_D_CPU1_SB_DQ<25>")
	)
	(segment
		(start 20.228814 -202.842368)
		(end 20.035774 -203.035408)
		(width 0.18288)
		(layer "In11.Cu")
		(net "M_D_CPU1_SB_DQ<25>")
	)
	(segment
		(start 95.859854 -228.953568)
		(end 95.850964 -228.948488)
		(width 0.088646)
		(layer "In11.Cu")
		(net "M_D_CPU1_SB_DQ<25>")
	)
	(segment
		(start 18.633694 -203.035408)
		(end 18.633694 -203.514706)
		(width 0.18288)
		(layer "In11.Cu")
		(net "M_D_CPU1_SB_DQ<25>")
	)
	(segment
		(start 89.287096 -228.957124)
		(end 89.272364 -228.948488)
		(width 0.088646)
		(layer "In11.Cu")
		(net "M_D_CPU1_SB_DQ<25>")
	)
	(segment
		(start 38.536626 -202.036426)
		(end 37.922454 -202.650598)
		(width 0.18288)
		(layer "In11.Cu")
		(net "M_D_CPU1_SB_DQ<25>")
	)
	(segment
		(start 30.785054 -201.990198)
		(end 30.561026 -202.214226)
		(width 0.18288)
		(layer "In11.Cu")
		(net "M_D_CPU1_SB_DQ<25>")
	)
	(segment
		(start 93.046296 -228.957124)
		(end 93.031564 -228.948488)
		(width 0.088646)
		(layer "In11.Cu")
		(net "M_D_CPU1_SB_DQ<25>")
	)
	(segment
		(start 82.239866 -226.24923)
		(end 73.002648 -217.012012)
		(width 0.18288)
		(layer "In11.Cu")
		(net "M_D_CPU1_SB_DQ<25>")
	)
	(segment
		(start 42.037762 -202.051666)
		(end 41.844722 -201.858626)
		(width 0.18288)
		(layer "In11.Cu")
		(net "M_D_CPU1_SB_DQ<25>")
	)
	(segment
		(start 87.11057 -228.477826)
		(end 87.110316 -228.459284)
		(width 0.088646)
		(layer "In11.Cu")
		(net "M_D_CPU1_SB_DQ<25>")
	)
	(segment
		(start 26.910284 -202.051666)
		(end 26.717244 -201.858626)
		(width 0.18288)
		(layer "In11.Cu")
		(net "M_D_CPU1_SB_DQ<25>")
	)
	(segment
		(start 82.37347 -226.24923)
		(end 82.239866 -226.24923)
		(width 0.18288)
		(layer "In11.Cu")
		(net "M_D_CPU1_SB_DQ<25>")
	)
	(segment
		(start 18.633694 -203.514706)
		(end 18.440654 -203.707746)
		(width 0.18288)
		(layer "In11.Cu")
		(net "M_D_CPU1_SB_DQ<25>")
	)
	(segment
		(start 66.457322 -208.209896)
		(end 65.639188 -207.391762)
		(width 0.18288)
		(layer "In11.Cu")
		(net "M_D_CPU1_SB_DQ<25>")
	)
	(segment
		(start 17.932654 -203.035408)
		(end 17.739614 -202.842368)
		(width 0.18288)
		(layer "In11.Cu")
		(net "M_D_CPU1_SB_DQ<25>")
	)
	(segment
		(start 19.141694 -202.842368)
		(end 18.826734 -202.842368)
		(width 0.18288)
		(layer "In11.Cu")
		(net "M_D_CPU1_SB_DQ<25>")
	)
	(segment
		(start 48.102774 -201.87793)
		(end 47.987458 -201.993246)
		(width 0.18288)
		(layer "In11.Cu")
		(net "M_D_CPU1_SB_DQ<25>")
	)
	(segment
		(start 87.392764 -228.948488)
		(end 87.392764 -228.948742)
		(width 0.088646)
		(layer "In11.Cu")
		(net "M_D_CPU1_SB_DQ<25>")
	)
	(segment
		(start 93.981778 -228.954584)
		(end 93.971364 -228.948488)
		(width 0.088646)
		(layer "In11.Cu")
		(net "M_D_CPU1_SB_DQ<25>")
	)
	(segment
		(start 97.75952 -231.208072)
		(end 97.73031 -231.22509)
		(width 0.088646)
		(layer "In11.Cu")
		(net "M_D_CPU1_SB_DQ<25>")
	)
	(segment
		(start 60.888626 -203.027026)
		(end 60.406026 -203.027026)
		(width 0.18288)
		(layer "In11.Cu")
		(net "M_D_CPU1_SB_DQ<25>")
	)
	(segment
		(start 34.24555 -201.88555)
		(end 32.979106 -201.88555)
		(width 0.18288)
		(layer "In11.Cu")
		(net "M_D_CPU1_SB_DQ<25>")
	)
	(segment
		(start 86.640162 -227.654866)
		(end 86.640162 -227.636324)
		(width 0.088646)
		(layer "In11.Cu")
		(net "M_D_CPU1_SB_DQ<25>")
	)
	(segment
		(start 37.060124 -202.842368)
		(end 35.202368 -202.842368)
		(width 0.18288)
		(layer "In11.Cu")
		(net "M_D_CPU1_SB_DQ<25>")
	)
	(segment
		(start 29.011626 -201.858626)
		(end 27.804364 -201.858626)
		(width 0.18288)
		(layer "In11.Cu")
		(net "M_D_CPU1_SB_DQ<25>")
	)
	(segment
		(start 49.19853 -201.87793)
		(end 48.102774 -201.87793)
		(width 0.18288)
		(layer "In11.Cu")
		(net "M_D_CPU1_SB_DQ<25>")
	)
	(segment
		(start 32.874458 -201.990198)
		(end 30.785054 -201.990198)
		(width 0.18288)
		(layer "In11.Cu")
		(net "M_D_CPU1_SB_DQ<25>")
	)
	(segment
		(start 82.727292 -226.317302)
		(end 82.65922 -226.24923)
		(width 0.088646)
		(layer "In11.Cu")
		(net "M_D_CPU1_SB_DQ<25>")
	)
	(segment
		(start 96.038416 -229.28834)
		(end 96.038416 -229.272846)
		(width 0.088646)
		(layer "In11.Cu")
		(net "M_D_CPU1_SB_DQ<25>")
	)
	(segment
		(start 98.483166 -230.900478)
		(end 97.75952 -231.208072)
		(width 0.088646)
		(layer "In11.Cu")
		(net "M_D_CPU1_SB_DQ<25>")
	)
	(segment
		(start 44.124626 -201.858626)
		(end 42.931842 -201.858626)
		(width 0.18288)
		(layer "In11.Cu")
		(net "M_D_CPU1_SB_DQ<25>")
	)
	(segment
		(start 84.385912 -227.270056)
		(end 83.485228 -227.270056)
		(width 0.088646)
		(layer "In11.Cu")
		(net "M_D_CPU1_SB_DQ<25>")
	)
	(segment
		(start 37.251894 -202.650598)
		(end 37.060124 -202.842368)
		(width 0.18288)
		(layer "In11.Cu")
		(net "M_D_CPU1_SB_DQ<25>")
	)
	(segment
		(start 17.21485 -202.842368)
		(end 16.789146 -202.416664)
		(width 0.18288)
		(layer "In11.Cu")
		(net "M_D_CPU1_SB_DQ<25>")
	)
	(arc
		(start 85.51291 -227.320602)
		(mid 85.325712 -227.270459)
		(end 85.138514 -227.320602)
		(width 0.088646)
		(layer "In11.Cu")
		(net "M_D_CPU1_SB_DQ<25>")
	)
	(arc
		(start 97.177098 -230.979726)
		(mid 97.140196 -230.880538)
		(end 97.076768 -230.79583)
		(width 0.088646)
		(layer "In11.Cu")
		(net "M_D_CPU1_SB_DQ<25>")
	)
	(arc
		(start 96.038416 -229.272846)
		(mid 95.990737 -229.089946)
		(end 95.859854 -228.953568)
		(width 0.088646)
		(layer "In11.Cu")
		(net "M_D_CPU1_SB_DQ<25>")
	)
	(arc
		(start 87.958168 -228.948488)
		(mid 87.675466 -229.024264)
		(end 87.392764 -228.948488)
		(width 0.088646)
		(layer "In11.Cu")
		(net "M_D_CPU1_SB_DQ<25>")
	)
	(arc
		(start 87.110062 -228.458776)
		(mid 87.062383 -228.275876)
		(end 86.9315 -228.139498)
		(width 0.088646)
		(layer "In11.Cu")
		(net "M_D_CPU1_SB_DQ<25>")
	)
	(arc
		(start 94.91091 -228.948488)
		(mid 94.723712 -228.898345)
		(end 94.536514 -228.948488)
		(width 0.088646)
		(layer "In11.Cu")
		(net "M_D_CPU1_SB_DQ<25>")
	)
	(arc
		(start 91.717368 -228.948488)
		(mid 91.434666 -229.024264)
		(end 91.151964 -228.948488)
		(width 0.088646)
		(layer "In11.Cu")
		(net "M_D_CPU1_SB_DQ<25>")
	)
	(arc
		(start 93.596968 -228.948488)
		(mid 93.322769 -229.024323)
		(end 93.046296 -228.957124)
		(width 0.088646)
		(layer "In11.Cu")
		(net "M_D_CPU1_SB_DQ<25>")
	)
	(arc
		(start 87.392764 -228.948742)
		(mid 87.190722 -228.749819)
		(end 87.11057 -228.477826)
		(width 0.088646)
		(layer "In11.Cu")
		(net "M_D_CPU1_SB_DQ<25>")
	)
	(arc
		(start 93.031564 -228.948488)
		(mid 92.844366 -228.898345)
		(end 92.657168 -228.948488)
		(width 0.088646)
		(layer "In11.Cu")
		(net "M_D_CPU1_SB_DQ<25>")
	)
	(arc
		(start 90.212164 -228.948488)
		(mid 90.024966 -228.898345)
		(end 89.837768 -228.948488)
		(width 0.088646)
		(layer "In11.Cu")
		(net "M_D_CPU1_SB_DQ<25>")
	)
	(arc
		(start 84.57311 -227.320602)
		(mid 84.482838 -227.283003)
		(end 84.385912 -227.270056)
		(width 0.088646)
		(layer "In11.Cu")
		(net "M_D_CPU1_SB_DQ<25>")
	)
	(arc
		(start 88.332564 -228.948488)
		(mid 88.145366 -228.898345)
		(end 87.958168 -228.948488)
		(width 0.088646)
		(layer "In11.Cu")
		(net "M_D_CPU1_SB_DQ<25>")
	)
	(arc
		(start 97.345754 -231.21874)
		(mid 97.237127 -231.11638)
		(end 97.177098 -230.979726)
		(width 0.088646)
		(layer "In11.Cu")
		(net "M_D_CPU1_SB_DQ<25>")
	)
	(arc
		(start 88.897968 -228.948488)
		(mid 88.623769 -229.024323)
		(end 88.347296 -228.957124)
		(width 0.088646)
		(layer "In11.Cu")
		(net "M_D_CPU1_SB_DQ<25>")
	)
	(arc
		(start 89.837768 -228.948488)
		(mid 89.563569 -229.024323)
		(end 89.287096 -228.957124)
		(width 0.088646)
		(layer "In11.Cu")
		(net "M_D_CPU1_SB_DQ<25>")
	)
	(arc
		(start 92.657168 -228.948488)
		(mid 92.382969 -229.024323)
		(end 92.106496 -228.957124)
		(width 0.088646)
		(layer "In11.Cu")
		(net "M_D_CPU1_SB_DQ<25>")
	)
	(arc
		(start 93.971364 -228.948488)
		(mid 93.784166 -228.898345)
		(end 93.596968 -228.948488)
		(width 0.088646)
		(layer "In11.Cu")
		(net "M_D_CPU1_SB_DQ<25>")
	)
	(arc
		(start 86.452964 -227.320602)
		(mid 86.265766 -227.270459)
		(end 86.078568 -227.320602)
		(width 0.088646)
		(layer "In11.Cu")
		(net "M_D_CPU1_SB_DQ<25>")
	)
	(arc
		(start 86.92261 -228.134418)
		(mid 86.718275 -227.931813)
		(end 86.640162 -227.654866)
		(width 0.088646)
		(layer "In11.Cu")
		(net "M_D_CPU1_SB_DQ<25>")
	)
	(arc
		(start 97.73031 -231.22509)
		(mid 97.543366 -231.275174)
		(end 97.356422 -231.22509)
		(width 0.088646)
		(layer "In11.Cu")
		(net "M_D_CPU1_SB_DQ<25>")
	)
	(arc
		(start 96.778572 -230.569008)
		(mid 96.580344 -230.36316)
		(end 96.508062 -230.086662)
		(width 0.088646)
		(layer "In11.Cu")
		(net "M_D_CPU1_SB_DQ<25>")
	)
	(arc
		(start 97.355914 -231.224836)
		(mid 97.350798 -231.221848)
		(end 97.345754 -231.21874)
		(width 0.088646)
		(layer "In11.Cu")
		(net "M_D_CPU1_SB_DQ<25>")
	)
	(arc
		(start 95.850964 -228.948488)
		(mid 95.663766 -228.898345)
		(end 95.476568 -228.948488)
		(width 0.088646)
		(layer "In11.Cu")
		(net "M_D_CPU1_SB_DQ<25>")
	)
	(arc
		(start 90.777568 -228.948488)
		(mid 90.503369 -229.024323)
		(end 90.226896 -228.957124)
		(width 0.088646)
		(layer "In11.Cu")
		(net "M_D_CPU1_SB_DQ<25>")
	)
	(arc
		(start 95.476568 -228.948488)
		(mid 95.199755 -229.024358)
		(end 94.921324 -228.954584)
		(width 0.088646)
		(layer "In11.Cu")
		(net "M_D_CPU1_SB_DQ<25>")
	)
	(arc
		(start 96.508062 -230.086662)
		(mid 96.460383 -229.903762)
		(end 96.3295 -229.767384)
		(width 0.088646)
		(layer "In11.Cu")
		(net "M_D_CPU1_SB_DQ<25>")
	)
	(arc
		(start 85.138514 -227.320602)
		(mid 84.855812 -227.396378)
		(end 84.57311 -227.320602)
		(width 0.088646)
		(layer "In11.Cu")
		(net "M_D_CPU1_SB_DQ<25>")
	)
	(arc
		(start 89.272364 -228.948488)
		(mid 89.085166 -228.898345)
		(end 88.897968 -228.948488)
		(width 0.088646)
		(layer "In11.Cu")
		(net "M_D_CPU1_SB_DQ<25>")
	)
	(arc
		(start 92.091764 -228.948488)
		(mid 91.904566 -228.898345)
		(end 91.717368 -228.948488)
		(width 0.088646)
		(layer "In11.Cu")
		(net "M_D_CPU1_SB_DQ<25>")
	)
	(arc
		(start 96.32061 -229.762304)
		(mid 96.117787 -229.562073)
		(end 96.038416 -229.28834)
		(width 0.088646)
		(layer "In11.Cu")
		(net "M_D_CPU1_SB_DQ<25>")
	)
	(arc
		(start 94.536514 -228.948488)
		(mid 94.259955 -229.024231)
		(end 93.981778 -228.954584)
		(width 0.088646)
		(layer "In11.Cu")
		(net "M_D_CPU1_SB_DQ<25>")
	)
	(arc
		(start 86.068154 -227.326698)
		(mid 85.789722 -227.396544)
		(end 85.51291 -227.320602)
		(width 0.088646)
		(layer "In11.Cu")
		(net "M_D_CPU1_SB_DQ<25>")
	)
	(arc
		(start 91.151964 -228.948488)
		(mid 90.964766 -228.898345)
		(end 90.777568 -228.948488)
		(width 0.088646)
		(layer "In11.Cu")
		(net "M_D_CPU1_SB_DQ<25>")
	)
	(arc
		(start 86.640162 -227.636324)
		(mid 86.587892 -227.453959)
		(end 86.452964 -227.320602)
		(width 0.088646)
		(layer "In11.Cu")
		(net "M_D_CPU1_SB_DQ<25>")
	)
	(arc
		(start 97.076768 -230.79583)
		(mid 96.940969 -230.6766)
		(end 96.790764 -230.57612)
		(width 0.088646)
		(layer "In11.Cu")
		(net "M_D_CPU1_SB_DQ<25>")
	)
	(segment
		(start 11.124438 -203.691744)
		(end 11.372342 -203.691744)
		(width 0.101854)
		(layer "F.Cu")
		(net "M_D_CPU1_SB_DQ<24>")
	)
	(segment
		(start 10.344912 -204.182726)
		(end 10.344912 -203.893166)
		(width 0.20066)
		(layer "F.Cu")
		(net "M_D_CPU1_SB_DQ<24>")
	)
	(segment
		(start 98.953066 -232.250488)
		(end 98.952812 -232.250234)
		(width 0.20066)
		(layer "F.Cu")
		(net "M_D_CPU1_SB_DQ<24>")
	)
	(segment
		(start 11.11631 -203.683616)
		(end 11.124438 -203.691744)
		(width 0.101854)
		(layer "F.Cu")
		(net "M_D_CPU1_SB_DQ<24>")
	)
	(segment
		(start 10.344912 -203.893166)
		(end 10.554462 -203.683616)
		(width 0.20066)
		(layer "F.Cu")
		(net "M_D_CPU1_SB_DQ<24>")
	)
	(segment
		(start 9.474708 -204.116686)
		(end 9.713468 -204.355446)
		(width 0.20066)
		(layer "F.Cu")
		(net "M_D_CPU1_SB_DQ<24>")
	)
	(segment
		(start 98.952812 -232.250234)
		(end 98.952812 -231.714548)
		(width 0.20066)
		(layer "F.Cu")
		(net "M_D_CPU1_SB_DQ<24>")
	)
	(segment
		(start 8.140446 -204.116686)
		(end 9.474708 -204.116686)
		(width 0.20066)
		(layer "F.Cu")
		(net "M_D_CPU1_SB_DQ<24>")
	)
	(segment
		(start 9.713468 -204.355446)
		(end 10.172192 -204.355446)
		(width 0.20066)
		(layer "F.Cu")
		(net "M_D_CPU1_SB_DQ<24>")
	)
	(segment
		(start 16.789146 -204.116686)
		(end 15.684246 -204.116686)
		(width 0.20066)
		(layer "F.Cu")
		(net "M_D_CPU1_SB_DQ<24>")
	)
	(segment
		(start 10.172192 -204.355446)
		(end 10.344912 -204.182726)
		(width 0.20066)
		(layer "F.Cu")
		(net "M_D_CPU1_SB_DQ<24>")
	)
	(segment
		(start 13.441426 -203.691744)
		(end 13.890244 -203.691744)
		(width 0.20066)
		(layer "F.Cu")
		(net "M_D_CPU1_SB_DQ<24>")
	)
	(segment
		(start 14.315186 -204.116686)
		(end 15.684246 -204.116686)
		(width 0.20066)
		(layer "F.Cu")
		(net "M_D_CPU1_SB_DQ<24>")
	)
	(segment
		(start 10.554462 -203.683616)
		(end 11.11631 -203.683616)
		(width 0.20066)
		(layer "F.Cu")
		(net "M_D_CPU1_SB_DQ<24>")
	)
	(segment
		(start 13.890244 -203.691744)
		(end 14.315186 -204.116686)
		(width 0.20066)
		(layer "F.Cu")
		(net "M_D_CPU1_SB_DQ<24>")
	)
	(segment
		(start 11.372342 -203.691744)
		(end 13.441426 -203.691744)
		(width 0.1016)
		(layer "F.Cu")
		(net "M_D_CPU1_SB_DQ<24>")
	)
	(segment
		(start 86.170516 -228.468936)
		(end 86.170516 -228.45903)
		(width 0.088646)
		(layer "In11.Cu")
		(net "M_D_CPU1_SB_DQ<24>")
	)
	(segment
		(start 43.630596 -204.867256)
		(end 41.240456 -204.867256)
		(width 0.18288)
		(layer "In11.Cu")
		(net "M_D_CPU1_SB_DQ<24>")
	)
	(segment
		(start 89.367614 -229.762304)
		(end 89.352882 -229.77094)
		(width 0.088646)
		(layer "In11.Cu")
		(net "M_D_CPU1_SB_DQ<24>")
	)
	(segment
		(start 66.822828 -209.452718)
		(end 66.256662 -209.452718)
		(width 0.18288)
		(layer "In11.Cu")
		(net "M_D_CPU1_SB_DQ<24>")
	)
	(segment
		(start 22.710648 -204.540866)
		(end 22.517608 -204.347826)
		(width 0.18288)
		(layer "In11.Cu")
		(net "M_D_CPU1_SB_DQ<24>")
	)
	(segment
		(start 25.100026 -204.347826)
		(end 23.604728 -204.347826)
		(width 0.18288)
		(layer "In11.Cu")
		(net "M_D_CPU1_SB_DQ<24>")
	)
	(segment
		(start 31.231586 -203.992226)
		(end 29.494226 -203.992226)
		(width 0.18288)
		(layer "In11.Cu")
		(net "M_D_CPU1_SB_DQ<24>")
	)
	(segment
		(start 44.099226 -204.398626)
		(end 43.630596 -204.867256)
		(width 0.18288)
		(layer "In11.Cu")
		(net "M_D_CPU1_SB_DQ<24>")
	)
	(segment
		(start 18.59915 -204.735176)
		(end 18.59915 -205.24978)
		(width 0.18288)
		(layer "In11.Cu")
		(net "M_D_CPU1_SB_DQ<24>")
	)
	(segment
		(start 82.905092 -227.327714)
		(end 82.37347 -227.327714)
		(width 0.088646)
		(layer "In11.Cu")
		(net "M_D_CPU1_SB_DQ<24>")
	)
	(segment
		(start 18.09115 -205.44282)
		(end 17.89811 -205.24978)
		(width 0.18288)
		(layer "In11.Cu")
		(net "M_D_CPU1_SB_DQ<24>")
	)
	(segment
		(start 19.10715 -204.542136)
		(end 18.79219 -204.542136)
		(width 0.18288)
		(layer "In11.Cu")
		(net "M_D_CPU1_SB_DQ<24>")
	)
	(segment
		(start 64.080136 -206.964026)
		(end 63.327026 -206.964026)
		(width 0.18288)
		(layer "In11.Cu")
		(net "M_D_CPU1_SB_DQ<24>")
	)
	(segment
		(start 86.640162 -229.282752)
		(end 86.640162 -229.26421)
		(width 0.088646)
		(layer "In11.Cu")
		(net "M_D_CPU1_SB_DQ<24>")
	)
	(segment
		(start 86.922356 -229.762304)
		(end 86.92261 -229.762304)
		(width 0.088646)
		(layer "In11.Cu")
		(net "M_D_CPU1_SB_DQ<24>")
	)
	(segment
		(start 88.427814 -229.762304)
		(end 88.413082 -229.77094)
		(width 0.088646)
		(layer "In11.Cu")
		(net "M_D_CPU1_SB_DQ<24>")
	)
	(segment
		(start 17.89811 -204.735176)
		(end 17.70507 -204.542136)
		(width 0.18288)
		(layer "In11.Cu")
		(net "M_D_CPU1_SB_DQ<24>")
	)
	(segment
		(start 20.00123 -205.24978)
		(end 19.80819 -205.44282)
		(width 0.18288)
		(layer "In11.Cu")
		(net "M_D_CPU1_SB_DQ<24>")
	)
	(segment
		(start 21.578316 -204.542136)
		(end 20.19427 -204.542136)
		(width 0.18288)
		(layer "In11.Cu")
		(net "M_D_CPU1_SB_DQ<24>")
	)
	(segment
		(start 92.187014 -229.762304)
		(end 92.172282 -229.77094)
		(width 0.088646)
		(layer "In11.Cu")
		(net "M_D_CPU1_SB_DQ<24>")
	)
	(segment
		(start 19.30019 -204.735176)
		(end 19.10715 -204.542136)
		(width 0.18288)
		(layer "In11.Cu")
		(net "M_D_CPU1_SB_DQ<24>")
	)
	(segment
		(start 62.488826 -206.125826)
		(end 59.69508 -206.125826)
		(width 0.18288)
		(layer "In11.Cu")
		(net "M_D_CPU1_SB_DQ<24>")
	)
	(segment
		(start 25.785826 -203.662026)
		(end 25.100026 -204.347826)
		(width 0.18288)
		(layer "In11.Cu")
		(net "M_D_CPU1_SB_DQ<24>")
	)
	(segment
		(start 19.80819 -205.44282)
		(end 19.49323 -205.44282)
		(width 0.18288)
		(layer "In11.Cu")
		(net "M_D_CPU1_SB_DQ<24>")
	)
	(segment
		(start 37.178488 -204.424026)
		(end 37.060124 -204.54239)
		(width 0.18288)
		(layer "In11.Cu")
		(net "M_D_CPU1_SB_DQ<24>")
	)
	(segment
		(start 71.943214 -217.463878)
		(end 71.943214 -214.573104)
		(width 0.18288)
		(layer "In11.Cu")
		(net "M_D_CPU1_SB_DQ<24>")
	)
	(segment
		(start 57.149746 -203.580492)
		(end 55.12816 -203.580492)
		(width 0.18288)
		(layer "In11.Cu")
		(net "M_D_CPU1_SB_DQ<24>")
	)
	(segment
		(start 66.256662 -209.452718)
		(end 64.44234 -207.638396)
		(width 0.18288)
		(layer "In11.Cu")
		(net "M_D_CPU1_SB_DQ<24>")
	)
	(segment
		(start 87.86241 -229.762304)
		(end 87.862664 -229.762304)
		(width 0.088646)
		(layer "In11.Cu")
		(net "M_D_CPU1_SB_DQ<24>")
	)
	(segment
		(start 22.903688 -205.28661)
		(end 22.710648 -205.09357)
		(width 0.18288)
		(layer "In11.Cu")
		(net "M_D_CPU1_SB_DQ<24>")
	)
	(segment
		(start 31.533592 -203.69022)
		(end 31.231586 -203.992226)
		(width 0.18288)
		(layer "In11.Cu")
		(net "M_D_CPU1_SB_DQ<24>")
	)
	(segment
		(start 17.89811 -205.24978)
		(end 17.89811 -204.735176)
		(width 0.18288)
		(layer "In11.Cu")
		(net "M_D_CPU1_SB_DQ<24>")
	)
	(segment
		(start 63.327026 -206.964026)
		(end 62.488826 -206.125826)
		(width 0.18288)
		(layer "In11.Cu")
		(net "M_D_CPU1_SB_DQ<24>")
	)
	(segment
		(start 59.69508 -206.125826)
		(end 57.149746 -203.580492)
		(width 0.18288)
		(layer "In11.Cu")
		(net "M_D_CPU1_SB_DQ<24>")
	)
	(segment
		(start 83.787996 -228.210618)
		(end 82.905092 -227.327714)
		(width 0.088646)
		(layer "In11.Cu")
		(net "M_D_CPU1_SB_DQ<24>")
	)
	(segment
		(start 90.307668 -229.762304)
		(end 90.297254 -229.7684)
		(width 0.088646)
		(layer "In11.Cu")
		(net "M_D_CPU1_SB_DQ<24>")
	)
	(segment
		(start 96.3295 -231.39527)
		(end 96.32061 -231.39019)
		(width 0.088646)
		(layer "In11.Cu")
		(net "M_D_CPU1_SB_DQ<24>")
	)
	(segment
		(start 17.214596 -204.542136)
		(end 16.789146 -204.116686)
		(width 0.18288)
		(layer "In11.Cu")
		(net "M_D_CPU1_SB_DQ<24>")
	)
	(segment
		(start 22.517608 -204.347826)
		(end 21.772626 -204.347826)
		(width 0.18288)
		(layer "In11.Cu")
		(net "M_D_CPU1_SB_DQ<24>")
	)
	(segment
		(start 96.790764 -232.204006)
		(end 96.784668 -232.20045)
		(width 0.088646)
		(layer "In11.Cu")
		(net "M_D_CPU1_SB_DQ<24>")
	)
	(segment
		(start 54.430422 -204.27823)
		(end 52.122832 -204.27823)
		(width 0.18288)
		(layer "In11.Cu")
		(net "M_D_CPU1_SB_DQ<24>")
	)
	(segment
		(start 34.22015 -203.56195)
		(end 33.602168 -203.56195)
		(width 0.18288)
		(layer "In11.Cu")
		(net "M_D_CPU1_SB_DQ<24>")
	)
	(segment
		(start 64.44234 -207.638396)
		(end 64.44234 -207.32623)
		(width 0.18288)
		(layer "In11.Cu")
		(net "M_D_CPU1_SB_DQ<24>")
	)
	(segment
		(start 96.805496 -232.212642)
		(end 96.790764 -232.204006)
		(width 0.088646)
		(layer "In11.Cu")
		(net "M_D_CPU1_SB_DQ<24>")
	)
	(segment
		(start 97.740978 -232.210102)
		(end 97.730564 -232.204006)
		(width 0.088646)
		(layer "In11.Cu")
		(net "M_D_CPU1_SB_DQ<24>")
	)
	(segment
		(start 21.772626 -204.347826)
		(end 21.578316 -204.542136)
		(width 0.18288)
		(layer "In11.Cu")
		(net "M_D_CPU1_SB_DQ<24>")
	)
	(segment
		(start 55.12816 -203.580492)
		(end 54.430422 -204.27823)
		(width 0.18288)
		(layer "In11.Cu")
		(net "M_D_CPU1_SB_DQ<24>")
	)
	(segment
		(start 40.797226 -204.424026)
		(end 37.178488 -204.424026)
		(width 0.18288)
		(layer "In11.Cu")
		(net "M_D_CPU1_SB_DQ<24>")
	)
	(segment
		(start 23.411688 -204.540866)
		(end 23.411688 -205.09357)
		(width 0.18288)
		(layer "In11.Cu")
		(net "M_D_CPU1_SB_DQ<24>")
	)
	(segment
		(start 37.060124 -204.54239)
		(end 35.20059 -204.54239)
		(width 0.18288)
		(layer "In11.Cu")
		(net "M_D_CPU1_SB_DQ<24>")
	)
	(segment
		(start 64.44234 -207.32623)
		(end 64.080136 -206.964026)
		(width 0.18288)
		(layer "In11.Cu")
		(net "M_D_CPU1_SB_DQ<24>")
	)
	(segment
		(start 95.850964 -230.57612)
		(end 95.844868 -230.572564)
		(width 0.088646)
		(layer "In11.Cu")
		(net "M_D_CPU1_SB_DQ<24>")
	)
	(segment
		(start 20.19427 -204.542136)
		(end 20.00123 -204.735176)
		(width 0.18288)
		(layer "In11.Cu")
		(net "M_D_CPU1_SB_DQ<24>")
	)
	(segment
		(start 50.06848 -204.542644)
		(end 49.21504 -203.689204)
		(width 0.18288)
		(layer "In11.Cu")
		(net "M_D_CPU1_SB_DQ<24>")
	)
	(segment
		(start 84.385912 -228.210618)
		(end 83.787996 -228.210618)
		(width 0.088646)
		(layer "In11.Cu")
		(net "M_D_CPU1_SB_DQ<24>")
	)
	(segment
		(start 95.3897 -229.767384)
		(end 95.38081 -229.762304)
		(width 0.088646)
		(layer "In11.Cu")
		(net "M_D_CPU1_SB_DQ<24>")
	)
	(segment
		(start 19.30019 -205.24978)
		(end 19.30019 -204.735176)
		(width 0.18288)
		(layer "In11.Cu")
		(net "M_D_CPU1_SB_DQ<24>")
	)
	(segment
		(start 49.21504 -203.689204)
		(end 45.809916 -203.689204)
		(width 0.18288)
		(layer "In11.Cu")
		(net "M_D_CPU1_SB_DQ<24>")
	)
	(segment
		(start 93.126814 -229.762304)
		(end 93.112082 -229.77094)
		(width 0.088646)
		(layer "In11.Cu")
		(net "M_D_CPU1_SB_DQ<24>")
	)
	(segment
		(start 19.49323 -205.44282)
		(end 19.30019 -205.24978)
		(width 0.18288)
		(layer "In11.Cu")
		(net "M_D_CPU1_SB_DQ<24>")
	)
	(segment
		(start 45.100494 -204.398626)
		(end 44.099226 -204.398626)
		(width 0.18288)
		(layer "In11.Cu")
		(net "M_D_CPU1_SB_DQ<24>")
	)
	(segment
		(start 33.473898 -203.69022)
		(end 31.533592 -203.69022)
		(width 0.18288)
		(layer "In11.Cu")
		(net "M_D_CPU1_SB_DQ<24>")
	)
	(segment
		(start 33.602168 -203.56195)
		(end 33.473898 -203.69022)
		(width 0.18288)
		(layer "In11.Cu")
		(net "M_D_CPU1_SB_DQ<24>")
	)
	(segment
		(start 20.00123 -204.735176)
		(end 20.00123 -205.24978)
		(width 0.18288)
		(layer "In11.Cu")
		(net "M_D_CPU1_SB_DQ<24>")
	)
	(segment
		(start 18.59915 -205.24978)
		(end 18.40611 -205.44282)
		(width 0.18288)
		(layer "In11.Cu")
		(net "M_D_CPU1_SB_DQ<24>")
	)
	(segment
		(start 85.057996 -228.143308)
		(end 85.043264 -228.134672)
		(width 0.088646)
		(layer "In11.Cu")
		(net "M_D_CPU1_SB_DQ<24>")
	)
	(segment
		(start 52.122832 -204.27823)
		(end 51.858418 -204.542644)
		(width 0.18288)
		(layer "In11.Cu")
		(net "M_D_CPU1_SB_DQ<24>")
	)
	(segment
		(start 22.710648 -205.09357)
		(end 22.710648 -204.540866)
		(width 0.18288)
		(layer "In11.Cu")
		(net "M_D_CPU1_SB_DQ<24>")
	)
	(segment
		(start 95.859854 -230.5812)
		(end 95.850964 -230.57612)
		(width 0.088646)
		(layer "In11.Cu")
		(net "M_D_CPU1_SB_DQ<24>")
	)
	(segment
		(start 29.494226 -203.992226)
		(end 29.164026 -203.662026)
		(width 0.18288)
		(layer "In11.Cu")
		(net "M_D_CPU1_SB_DQ<24>")
	)
	(segment
		(start 81.80705 -227.327714)
		(end 71.943214 -217.463878)
		(width 0.18288)
		(layer "In11.Cu")
		(net "M_D_CPU1_SB_DQ<24>")
	)
	(segment
		(start 29.164026 -203.662026)
		(end 25.785826 -203.662026)
		(width 0.18288)
		(layer "In11.Cu")
		(net "M_D_CPU1_SB_DQ<24>")
	)
	(segment
		(start 71.943214 -214.573104)
		(end 66.822828 -209.452718)
		(width 0.18288)
		(layer "In11.Cu")
		(net "M_D_CPU1_SB_DQ<24>")
	)
	(segment
		(start 23.411688 -205.09357)
		(end 23.218648 -205.28661)
		(width 0.18288)
		(layer "In11.Cu")
		(net "M_D_CPU1_SB_DQ<24>")
	)
	(segment
		(start 17.70507 -204.542136)
		(end 17.214596 -204.542136)
		(width 0.18288)
		(layer "In11.Cu")
		(net "M_D_CPU1_SB_DQ<24>")
	)
	(segment
		(start 45.809916 -203.689204)
		(end 45.100494 -204.398626)
		(width 0.18288)
		(layer "In11.Cu")
		(net "M_D_CPU1_SB_DQ<24>")
	)
	(segment
		(start 85.991954 -228.139752)
		(end 85.983064 -228.134672)
		(width 0.088646)
		(layer "In11.Cu")
		(net "M_D_CPU1_SB_DQ<24>")
	)
	(segment
		(start 82.37347 -227.327714)
		(end 81.80705 -227.327714)
		(width 0.18288)
		(layer "In11.Cu")
		(net "M_D_CPU1_SB_DQ<24>")
	)
	(segment
		(start 35.20059 -204.54239)
		(end 34.22015 -203.56195)
		(width 0.18288)
		(layer "In11.Cu")
		(net "M_D_CPU1_SB_DQ<24>")
	)
	(segment
		(start 94.066614 -229.762304)
		(end 94.051882 -229.77094)
		(width 0.088646)
		(layer "In11.Cu")
		(net "M_D_CPU1_SB_DQ<24>")
	)
	(segment
		(start 96.038416 -230.922576)
		(end 96.038416 -230.900478)
		(width 0.088646)
		(layer "In11.Cu")
		(net "M_D_CPU1_SB_DQ<24>")
	)
	(segment
		(start 18.79219 -204.542136)
		(end 18.59915 -204.735176)
		(width 0.18288)
		(layer "In11.Cu")
		(net "M_D_CPU1_SB_DQ<24>")
	)
	(segment
		(start 18.40611 -205.44282)
		(end 18.09115 -205.44282)
		(width 0.18288)
		(layer "In11.Cu")
		(net "M_D_CPU1_SB_DQ<24>")
	)
	(segment
		(start 23.218648 -205.28661)
		(end 22.903688 -205.28661)
		(width 0.18288)
		(layer "In11.Cu")
		(net "M_D_CPU1_SB_DQ<24>")
	)
	(segment
		(start 41.240456 -204.867256)
		(end 40.797226 -204.424026)
		(width 0.18288)
		(layer "In11.Cu")
		(net "M_D_CPU1_SB_DQ<24>")
	)
	(segment
		(start 51.858418 -204.542644)
		(end 50.06848 -204.542644)
		(width 0.18288)
		(layer "In11.Cu")
		(net "M_D_CPU1_SB_DQ<24>")
	)
	(segment
		(start 91.247214 -229.762304)
		(end 91.2368 -229.7684)
		(width 0.088646)
		(layer "In11.Cu")
		(net "M_D_CPU1_SB_DQ<24>")
	)
	(segment
		(start 23.604728 -204.347826)
		(end 23.411688 -204.540866)
		(width 0.18288)
		(layer "In11.Cu")
		(net "M_D_CPU1_SB_DQ<24>")
	)
	(arc
		(start 87.488268 -229.762304)
		(mid 87.205312 -229.838207)
		(end 86.922356 -229.762304)
		(width 0.088646)
		(layer "In11.Cu")
		(net "M_D_CPU1_SB_DQ<24>")
	)
	(arc
		(start 95.006414 -229.762304)
		(mid 94.723712 -229.83808)
		(end 94.44101 -229.762304)
		(width 0.088646)
		(layer "In11.Cu")
		(net "M_D_CPU1_SB_DQ<24>")
	)
	(arc
		(start 97.356168 -232.204006)
		(mid 97.081969 -232.279841)
		(end 96.805496 -232.212642)
		(width 0.088646)
		(layer "In11.Cu")
		(net "M_D_CPU1_SB_DQ<24>")
	)
	(arc
		(start 96.784668 -232.20045)
		(mid 96.582081 -231.994099)
		(end 96.508062 -231.714548)
		(width 0.088646)
		(layer "In11.Cu")
		(net "M_D_CPU1_SB_DQ<24>")
	)
	(arc
		(start 85.043264 -228.134672)
		(mid 84.856066 -228.084529)
		(end 84.668868 -228.134672)
		(width 0.088646)
		(layer "In11.Cu")
		(net "M_D_CPU1_SB_DQ<24>")
	)
	(arc
		(start 84.668868 -228.134672)
		(mid 84.532395 -228.191306)
		(end 84.385912 -228.210618)
		(width 0.088646)
		(layer "In11.Cu")
		(net "M_D_CPU1_SB_DQ<24>")
	)
	(arc
		(start 86.452964 -228.948488)
		(mid 86.248629 -228.745883)
		(end 86.170516 -228.468936)
		(width 0.088646)
		(layer "In11.Cu")
		(net "M_D_CPU1_SB_DQ<24>")
	)
	(arc
		(start 94.44101 -229.762304)
		(mid 94.253812 -229.712161)
		(end 94.066614 -229.762304)
		(width 0.088646)
		(layer "In11.Cu")
		(net "M_D_CPU1_SB_DQ<24>")
	)
	(arc
		(start 98.952812 -231.714548)
		(mid 98.63853 -231.978432)
		(end 98.295714 -232.204006)
		(width 0.088646)
		(layer "In11.Cu")
		(net "M_D_CPU1_SB_DQ<24>")
	)
	(arc
		(start 96.508062 -231.714548)
		(mid 96.460383 -231.531648)
		(end 96.3295 -231.39527)
		(width 0.088646)
		(layer "In11.Cu")
		(net "M_D_CPU1_SB_DQ<24>")
	)
	(arc
		(start 97.730564 -232.204006)
		(mid 97.543366 -232.153863)
		(end 97.356168 -232.204006)
		(width 0.088646)
		(layer "In11.Cu")
		(net "M_D_CPU1_SB_DQ<24>")
	)
	(arc
		(start 90.682064 -229.762304)
		(mid 90.494866 -229.712161)
		(end 90.307668 -229.762304)
		(width 0.088646)
		(layer "In11.Cu")
		(net "M_D_CPU1_SB_DQ<24>")
	)
	(arc
		(start 92.172282 -229.77094)
		(mid 91.895807 -229.83826)
		(end 91.62161 -229.762304)
		(width 0.088646)
		(layer "In11.Cu")
		(net "M_D_CPU1_SB_DQ<24>")
	)
	(arc
		(start 89.352882 -229.77094)
		(mid 89.076407 -229.83826)
		(end 88.80221 -229.762304)
		(width 0.088646)
		(layer "In11.Cu")
		(net "M_D_CPU1_SB_DQ<24>")
	)
	(arc
		(start 88.413082 -229.77094)
		(mid 88.136607 -229.83826)
		(end 87.86241 -229.762304)
		(width 0.088646)
		(layer "In11.Cu")
		(net "M_D_CPU1_SB_DQ<24>")
	)
	(arc
		(start 91.2368 -229.7684)
		(mid 90.958622 -229.838123)
		(end 90.682064 -229.762304)
		(width 0.088646)
		(layer "In11.Cu")
		(net "M_D_CPU1_SB_DQ<24>")
	)
	(arc
		(start 94.051882 -229.77094)
		(mid 93.775407 -229.83826)
		(end 93.50121 -229.762304)
		(width 0.088646)
		(layer "In11.Cu")
		(net "M_D_CPU1_SB_DQ<24>")
	)
	(arc
		(start 96.038416 -230.900478)
		(mid 95.990737 -230.717578)
		(end 95.859854 -230.5812)
		(width 0.088646)
		(layer "In11.Cu")
		(net "M_D_CPU1_SB_DQ<24>")
	)
	(arc
		(start 89.74201 -229.762304)
		(mid 89.554812 -229.712161)
		(end 89.367614 -229.762304)
		(width 0.088646)
		(layer "In11.Cu")
		(net "M_D_CPU1_SB_DQ<24>")
	)
	(arc
		(start 95.844868 -230.572564)
		(mid 95.642281 -230.366213)
		(end 95.568262 -230.086662)
		(width 0.088646)
		(layer "In11.Cu")
		(net "M_D_CPU1_SB_DQ<24>")
	)
	(arc
		(start 90.297254 -229.7684)
		(mid 90.018822 -229.838246)
		(end 89.74201 -229.762304)
		(width 0.088646)
		(layer "In11.Cu")
		(net "M_D_CPU1_SB_DQ<24>")
	)
	(arc
		(start 95.568262 -230.086662)
		(mid 95.520583 -229.903762)
		(end 95.3897 -229.767384)
		(width 0.088646)
		(layer "In11.Cu")
		(net "M_D_CPU1_SB_DQ<24>")
	)
	(arc
		(start 92.56141 -229.762304)
		(mid 92.374212 -229.712161)
		(end 92.187014 -229.762304)
		(width 0.088646)
		(layer "In11.Cu")
		(net "M_D_CPU1_SB_DQ<24>")
	)
	(arc
		(start 86.170516 -228.45903)
		(mid 86.122837 -228.27613)
		(end 85.991954 -228.139752)
		(width 0.088646)
		(layer "In11.Cu")
		(net "M_D_CPU1_SB_DQ<24>")
	)
	(arc
		(start 85.608668 -228.134672)
		(mid 85.334439 -228.210597)
		(end 85.057996 -228.143308)
		(width 0.088646)
		(layer "In11.Cu")
		(net "M_D_CPU1_SB_DQ<24>")
	)
	(arc
		(start 93.112082 -229.77094)
		(mid 92.835607 -229.83826)
		(end 92.56141 -229.762304)
		(width 0.088646)
		(layer "In11.Cu")
		(net "M_D_CPU1_SB_DQ<24>")
	)
	(arc
		(start 88.80221 -229.762304)
		(mid 88.615012 -229.712161)
		(end 88.427814 -229.762304)
		(width 0.088646)
		(layer "In11.Cu")
		(net "M_D_CPU1_SB_DQ<24>")
	)
	(arc
		(start 85.983064 -228.134672)
		(mid 85.795866 -228.084529)
		(end 85.608668 -228.134672)
		(width 0.088646)
		(layer "In11.Cu")
		(net "M_D_CPU1_SB_DQ<24>")
	)
	(arc
		(start 86.640162 -229.26421)
		(mid 86.587892 -229.081845)
		(end 86.452964 -228.948488)
		(width 0.088646)
		(layer "In11.Cu")
		(net "M_D_CPU1_SB_DQ<24>")
	)
	(arc
		(start 91.62161 -229.762304)
		(mid 91.434412 -229.712161)
		(end 91.247214 -229.762304)
		(width 0.088646)
		(layer "In11.Cu")
		(net "M_D_CPU1_SB_DQ<24>")
	)
	(arc
		(start 86.92261 -229.762304)
		(mid 86.718275 -229.559699)
		(end 86.640162 -229.282752)
		(width 0.088646)
		(layer "In11.Cu")
		(net "M_D_CPU1_SB_DQ<24>")
	)
	(arc
		(start 96.32061 -231.39019)
		(mid 96.119328 -231.192703)
		(end 96.038416 -230.922576)
		(width 0.088646)
		(layer "In11.Cu")
		(net "M_D_CPU1_SB_DQ<24>")
	)
	(arc
		(start 95.38081 -229.762304)
		(mid 95.193612 -229.712161)
		(end 95.006414 -229.762304)
		(width 0.088646)
		(layer "In11.Cu")
		(net "M_D_CPU1_SB_DQ<24>")
	)
	(arc
		(start 87.862664 -229.762304)
		(mid 87.675466 -229.712161)
		(end 87.488268 -229.762304)
		(width 0.088646)
		(layer "In11.Cu")
		(net "M_D_CPU1_SB_DQ<24>")
	)
	(arc
		(start 98.295714 -232.204006)
		(mid 98.019155 -232.279749)
		(end 97.740978 -232.210102)
		(width 0.088646)
		(layer "In11.Cu")
		(net "M_D_CPU1_SB_DQ<24>")
	)
	(arc
		(start 93.50121 -229.762304)
		(mid 93.314012 -229.712161)
		(end 93.126814 -229.762304)
		(width 0.088646)
		(layer "In11.Cu")
		(net "M_D_CPU1_SB_DQ<24>")
	)
	(segment
		(start 14.063726 -205.092554)
		(end 14.063726 -205.263242)
		(width 0.20066)
		(layer "F.Cu")
		(net "M_D_CPU1_SB_DQ<23>")
	)
	(segment
		(start 18.314162 -205.174088)
		(end 18.760694 -205.174088)
		(width 0.20066)
		(layer "F.Cu")
		(net "M_D_CPU1_SB_DQ<23>")
	)
	(segment
		(start 14.560042 -205.405736)
		(end 14.574266 -205.391512)
		(width 0.101854)
		(layer "F.Cu")
		(net "M_D_CPU1_SB_DQ<23>")
	)
	(segment
		(start 18.968212 -204.96657)
		(end 19.784314 -204.96657)
		(width 0.20066)
		(layer "F.Cu")
		(net "M_D_CPU1_SB_DQ<23>")
	)
	(segment
		(start 18.760694 -205.174088)
		(end 18.968212 -204.96657)
		(width 0.20066)
		(layer "F.Cu")
		(net "M_D_CPU1_SB_DQ<23>")
	)
	(segment
		(start 20.889214 -204.96657)
		(end 19.784314 -204.96657)
		(width 0.20066)
		(layer "F.Cu")
		(net "M_D_CPU1_SB_DQ<23>")
	)
	(segment
		(start 17.42948 -205.391512)
		(end 17.578578 -205.242414)
		(width 0.20066)
		(layer "F.Cu")
		(net "M_D_CPU1_SB_DQ<23>")
	)
	(segment
		(start 17.578578 -205.242414)
		(end 17.578578 -205.090776)
		(width 0.20066)
		(layer "F.Cu")
		(net "M_D_CPU1_SB_DQ<23>")
	)
	(segment
		(start 17.707102 -204.962252)
		(end 18.102326 -204.962252)
		(width 0.20066)
		(layer "F.Cu")
		(net "M_D_CPU1_SB_DQ<23>")
	)
	(segment
		(start 14.20622 -205.405736)
		(end 14.560042 -205.405736)
		(width 0.20066)
		(layer "F.Cu")
		(net "M_D_CPU1_SB_DQ<23>")
	)
	(segment
		(start 14.812264 -205.391512)
		(end 16.885158 -205.391512)
		(width 0.1016)
		(layer "F.Cu")
		(net "M_D_CPU1_SB_DQ<23>")
	)
	(segment
		(start 17.578578 -205.090776)
		(end 17.707102 -204.962252)
		(width 0.20066)
		(layer "F.Cu")
		(net "M_D_CPU1_SB_DQ<23>")
	)
	(segment
		(start 16.885158 -205.391512)
		(end 17.42948 -205.391512)
		(width 0.20066)
		(layer "F.Cu")
		(net "M_D_CPU1_SB_DQ<23>")
	)
	(segment
		(start 13.937742 -204.96657)
		(end 14.063726 -205.092554)
		(width 0.20066)
		(layer "F.Cu")
		(net "M_D_CPU1_SB_DQ<23>")
	)
	(segment
		(start 18.102326 -204.962252)
		(end 18.314162 -205.174088)
		(width 0.20066)
		(layer "F.Cu")
		(net "M_D_CPU1_SB_DQ<23>")
	)
	(segment
		(start 96.603312 -231.436418)
		(end 96.603566 -231.436164)
		(width 0.20066)
		(layer "F.Cu")
		(net "M_D_CPU1_SB_DQ<23>")
	)
	(segment
		(start 12.240514 -204.96657)
		(end 13.937742 -204.96657)
		(width 0.20066)
		(layer "F.Cu")
		(net "M_D_CPU1_SB_DQ<23>")
	)
	(segment
		(start 14.574266 -205.391512)
		(end 14.812264 -205.391512)
		(width 0.101854)
		(layer "F.Cu")
		(net "M_D_CPU1_SB_DQ<23>")
	)
	(segment
		(start 14.063726 -205.263242)
		(end 14.20622 -205.405736)
		(width 0.20066)
		(layer "F.Cu")
		(net "M_D_CPU1_SB_DQ<23>")
	)
	(segment
		(start 96.603566 -231.436164)
		(end 96.603566 -230.900478)
		(width 0.20066)
		(layer "F.Cu")
		(net "M_D_CPU1_SB_DQ<23>")
	)
	(segment
		(start 93.126814 -230.41102)
		(end 93.112082 -230.402384)
		(width 0.088646)
		(layer "In6.Cu")
		(net "M_D_CPU1_SB_DQ<23>")
	)
	(segment
		(start 36.602162 -204.026516)
		(end 36.267898 -203.692252)
		(width 0.18288)
		(layer "In6.Cu")
		(net "M_D_CPU1_SB_DQ<23>")
	)
	(segment
		(start 66.40322 -209.57032)
		(end 63.778892 -206.945992)
		(width 0.18288)
		(layer "In6.Cu")
		(net "M_D_CPU1_SB_DQ<23>")
	)
	(segment
		(start 51.246278 -203.695046)
		(end 50.888646 -203.695046)
		(width 0.18288)
		(layer "In6.Cu")
		(net "M_D_CPU1_SB_DQ<23>")
	)
	(segment
		(start 33.260792 -204.860652)
		(end 32.941006 -204.540866)
		(width 0.18288)
		(layer "In6.Cu")
		(net "M_D_CPU1_SB_DQ<23>")
	)
	(segment
		(start 94.066614 -230.41102)
		(end 94.051882 -230.402384)
		(width 0.088646)
		(layer "In6.Cu")
		(net "M_D_CPU1_SB_DQ<23>")
	)
	(segment
		(start 27.152092 -204.012038)
		(end 26.992072 -204.172058)
		(width 0.18288)
		(layer "In6.Cu")
		(net "M_D_CPU1_SB_DQ<23>")
	)
	(segment
		(start 60.261754 -206.176626)
		(end 59.085226 -206.176626)
		(width 0.18288)
		(layer "In6.Cu")
		(net "M_D_CPU1_SB_DQ<23>")
	)
	(segment
		(start 35.297872 -204.126592)
		(end 34.543238 -204.126592)
		(width 0.18288)
		(layer "In6.Cu")
		(net "M_D_CPU1_SB_DQ<23>")
	)
	(segment
		(start 43.469052 -204.825092)
		(end 41.274492 -204.825092)
		(width 0.18288)
		(layer "In6.Cu")
		(net "M_D_CPU1_SB_DQ<23>")
	)
	(segment
		(start 57.254394 -205.55458)
		(end 57.071514 -205.73746)
		(width 0.18288)
		(layer "In6.Cu")
		(net "M_D_CPU1_SB_DQ<23>")
	)
	(segment
		(start 57.579514 -205.55458)
		(end 57.254394 -205.55458)
		(width 0.18288)
		(layer "In6.Cu")
		(net "M_D_CPU1_SB_DQ<23>")
	)
	(segment
		(start 56.888634 -206.379826)
		(end 56.164226 -206.379826)
		(width 0.18288)
		(layer "In6.Cu")
		(net "M_D_CPU1_SB_DQ<23>")
	)
	(segment
		(start 27.685492 -204.172058)
		(end 27.525472 -204.012038)
		(width 0.18288)
		(layer "In6.Cu")
		(net "M_D_CPU1_SB_DQ<23>")
	)
	(segment
		(start 95.006414 -230.41102)
		(end 94.991682 -230.402384)
		(width 0.088646)
		(layer "In6.Cu")
		(net "M_D_CPU1_SB_DQ<23>")
	)
	(segment
		(start 85.608668 -228.783388)
		(end 85.598254 -228.777292)
		(width 0.088646)
		(layer "In6.Cu")
		(net "M_D_CPU1_SB_DQ<23>")
	)
	(segment
		(start 92.187014 -230.41102)
		(end 92.172282 -230.402384)
		(width 0.088646)
		(layer "In6.Cu")
		(net "M_D_CPU1_SB_DQ<23>")
	)
	(segment
		(start 43.75531 -204.538834)
		(end 43.469052 -204.825092)
		(width 0.18288)
		(layer "In6.Cu")
		(net "M_D_CPU1_SB_DQ<23>")
	)
	(segment
		(start 57.071514 -205.73746)
		(end 57.071514 -206.196946)
		(width 0.18288)
		(layer "In6.Cu")
		(net "M_D_CPU1_SB_DQ<23>")
	)
	(segment
		(start 84.481416 -228.45903)
		(end 84.481162 -228.459284)
		(width 0.088646)
		(layer "In6.Cu")
		(net "M_D_CPU1_SB_DQ<23>")
	)
	(segment
		(start 86.830916 -229.272846)
		(end 86.830662 -229.26294)
		(width 0.088646)
		(layer "In6.Cu")
		(net "M_D_CPU1_SB_DQ<23>")
	)
	(segment
		(start 24.846026 -204.343)
		(end 23.412704 -204.343)
		(width 0.18288)
		(layer "In6.Cu")
		(net "M_D_CPU1_SB_DQ<23>")
	)
	(segment
		(start 76.962762 -224.197164)
		(end 76.962762 -221.519496)
		(width 0.18288)
		(layer "In6.Cu")
		(net "M_D_CPU1_SB_DQ<23>")
	)
	(segment
		(start 61.33846 -207.253332)
		(end 60.261754 -206.176626)
		(width 0.18288)
		(layer "In6.Cu")
		(net "M_D_CPU1_SB_DQ<23>")
	)
	(segment
		(start 79.121762 -226.356164)
		(end 76.962762 -224.197164)
		(width 0.18288)
		(layer "In6.Cu")
		(net "M_D_CPU1_SB_DQ<23>")
	)
	(segment
		(start 88.347296 -229.588568)
		(end 88.332564 -229.597204)
		(width 0.088646)
		(layer "In6.Cu")
		(net "M_D_CPU1_SB_DQ<23>")
	)
	(segment
		(start 91.060016 -230.095298)
		(end 91.060016 -230.076756)
		(width 0.088646)
		(layer "In6.Cu")
		(net "M_D_CPU1_SB_DQ<23>")
	)
	(segment
		(start 57.762394 -206.196946)
		(end 57.762394 -205.73746)
		(width 0.18288)
		(layer "In6.Cu")
		(net "M_D_CPU1_SB_DQ<23>")
	)
	(segment
		(start 27.845512 -204.540866)
		(end 27.685492 -204.380846)
		(width 0.18288)
		(layer "In6.Cu")
		(net "M_D_CPU1_SB_DQ<23>")
	)
	(segment
		(start 40.475916 -204.026516)
		(end 36.602162 -204.026516)
		(width 0.18288)
		(layer "In6.Cu")
		(net "M_D_CPU1_SB_DQ<23>")
	)
	(segment
		(start 52.786534 -203.86548)
		(end 51.416712 -203.86548)
		(width 0.18288)
		(layer "In6.Cu")
		(net "M_D_CPU1_SB_DQ<23>")
	)
	(segment
		(start 84.481162 -228.070156)
		(end 82.76717 -226.356164)
		(width 0.088646)
		(layer "In6.Cu")
		(net "M_D_CPU1_SB_DQ<23>")
	)
	(segment
		(start 21.512784 -204.343)
		(end 20.889214 -204.96657)
		(width 0.18288)
		(layer "In6.Cu")
		(net "M_D_CPU1_SB_DQ<23>")
	)
	(segment
		(start 22.356064 -204.343)
		(end 21.512784 -204.343)
		(width 0.18288)
		(layer "In6.Cu")
		(net "M_D_CPU1_SB_DQ<23>")
	)
	(segment
		(start 23.229824 -203.783946)
		(end 23.046944 -203.601066)
		(width 0.18288)
		(layer "In6.Cu")
		(net "M_D_CPU1_SB_DQ<23>")
	)
	(segment
		(start 27.525472 -204.012038)
		(end 27.152092 -204.012038)
		(width 0.18288)
		(layer "In6.Cu")
		(net "M_D_CPU1_SB_DQ<23>")
	)
	(segment
		(start 82.76717 -226.356164)
		(end 82.479642 -226.356164)
		(width 0.088646)
		(layer "In6.Cu")
		(net "M_D_CPU1_SB_DQ<23>")
	)
	(segment
		(start 22.538944 -203.783946)
		(end 22.538944 -204.16012)
		(width 0.18288)
		(layer "In6.Cu")
		(net "M_D_CPU1_SB_DQ<23>")
	)
	(segment
		(start 57.762394 -205.73746)
		(end 57.579514 -205.55458)
		(width 0.18288)
		(layer "In6.Cu")
		(net "M_D_CPU1_SB_DQ<23>")
	)
	(segment
		(start 89.287096 -229.588568)
		(end 89.272364 -229.597204)
		(width 0.088646)
		(layer "In6.Cu")
		(net "M_D_CPU1_SB_DQ<23>")
	)
	(segment
		(start 41.274492 -204.825092)
		(end 40.475916 -204.026516)
		(width 0.18288)
		(layer "In6.Cu")
		(net "M_D_CPU1_SB_DQ<23>")
	)
	(segment
		(start 55.231792 -205.447392)
		(end 54.368446 -205.447392)
		(width 0.18288)
		(layer "In6.Cu")
		(net "M_D_CPU1_SB_DQ<23>")
	)
	(segment
		(start 22.538944 -204.16012)
		(end 22.356064 -204.343)
		(width 0.18288)
		(layer "In6.Cu")
		(net "M_D_CPU1_SB_DQ<23>")
	)
	(segment
		(start 67.71132 -210.702652)
		(end 66.578988 -209.57032)
		(width 0.18288)
		(layer "In6.Cu")
		(net "M_D_CPU1_SB_DQ<23>")
	)
	(segment
		(start 22.721824 -203.601066)
		(end 22.538944 -203.783946)
		(width 0.18288)
		(layer "In6.Cu")
		(net "M_D_CPU1_SB_DQ<23>")
	)
	(segment
		(start 86.830916 -229.281482)
		(end 86.830916 -229.272846)
		(width 0.088646)
		(layer "In6.Cu")
		(net "M_D_CPU1_SB_DQ<23>")
	)
	(segment
		(start 68.81876 -213.375494)
		(end 67.71132 -210.702652)
		(width 0.18288)
		(layer "In6.Cu")
		(net "M_D_CPU1_SB_DQ<23>")
	)
	(segment
		(start 66.578988 -209.57032)
		(end 66.40322 -209.57032)
		(width 0.18288)
		(layer "In6.Cu")
		(net "M_D_CPU1_SB_DQ<23>")
	)
	(segment
		(start 23.046944 -203.601066)
		(end 22.721824 -203.601066)
		(width 0.18288)
		(layer "In6.Cu")
		(net "M_D_CPU1_SB_DQ<23>")
	)
	(segment
		(start 50.16373 -203.92898)
		(end 49.553876 -204.538834)
		(width 0.18288)
		(layer "In6.Cu")
		(net "M_D_CPU1_SB_DQ<23>")
	)
	(segment
		(start 32.941006 -204.540866)
		(end 27.845512 -204.540866)
		(width 0.18288)
		(layer "In6.Cu")
		(net "M_D_CPU1_SB_DQ<23>")
	)
	(segment
		(start 85.608668 -228.783642)
		(end 85.608668 -228.783388)
		(width 0.088646)
		(layer "In6.Cu")
		(net "M_D_CPU1_SB_DQ<23>")
	)
	(segment
		(start 76.962762 -221.519496)
		(end 68.81876 -213.375494)
		(width 0.18288)
		(layer "In6.Cu")
		(net "M_D_CPU1_SB_DQ<23>")
	)
	(segment
		(start 56.164226 -206.379826)
		(end 55.231792 -205.447392)
		(width 0.18288)
		(layer "In6.Cu")
		(net "M_D_CPU1_SB_DQ<23>")
	)
	(segment
		(start 62.722252 -207.253332)
		(end 61.33846 -207.253332)
		(width 0.18288)
		(layer "In6.Cu")
		(net "M_D_CPU1_SB_DQ<23>")
	)
	(segment
		(start 36.267898 -203.692252)
		(end 35.732212 -203.692252)
		(width 0.18288)
		(layer "In6.Cu")
		(net "M_D_CPU1_SB_DQ<23>")
	)
	(segment
		(start 23.229824 -204.16012)
		(end 23.229824 -203.783946)
		(width 0.18288)
		(layer "In6.Cu")
		(net "M_D_CPU1_SB_DQ<23>")
	)
	(segment
		(start 27.685492 -204.380846)
		(end 27.685492 -204.172058)
		(width 0.18288)
		(layer "In6.Cu")
		(net "M_D_CPU1_SB_DQ<23>")
	)
	(segment
		(start 25.043892 -204.540866)
		(end 24.846026 -204.343)
		(width 0.18288)
		(layer "In6.Cu")
		(net "M_D_CPU1_SB_DQ<23>")
	)
	(segment
		(start 50.888646 -203.695046)
		(end 50.654712 -203.92898)
		(width 0.18288)
		(layer "In6.Cu")
		(net "M_D_CPU1_SB_DQ<23>")
	)
	(segment
		(start 58.882026 -206.379826)
		(end 57.945274 -206.379826)
		(width 0.18288)
		(layer "In6.Cu")
		(net "M_D_CPU1_SB_DQ<23>")
	)
	(segment
		(start 59.085226 -206.176626)
		(end 58.882026 -206.379826)
		(width 0.18288)
		(layer "In6.Cu")
		(net "M_D_CPU1_SB_DQ<23>")
	)
	(segment
		(start 84.481162 -228.459284)
		(end 84.481162 -228.070156)
		(width 0.088646)
		(layer "In6.Cu")
		(net "M_D_CPU1_SB_DQ<23>")
	)
	(segment
		(start 51.416712 -203.86548)
		(end 51.246278 -203.695046)
		(width 0.18288)
		(layer "In6.Cu")
		(net "M_D_CPU1_SB_DQ<23>")
	)
	(segment
		(start 87.958168 -229.597204)
		(end 87.947754 -229.591108)
		(width 0.088646)
		(layer "In6.Cu")
		(net "M_D_CPU1_SB_DQ<23>")
	)
	(segment
		(start 26.832052 -204.540866)
		(end 25.043892 -204.540866)
		(width 0.18288)
		(layer "In6.Cu")
		(net "M_D_CPU1_SB_DQ<23>")
	)
	(segment
		(start 82.479642 -226.356164)
		(end 79.121762 -226.356164)
		(width 0.18288)
		(layer "In6.Cu")
		(net "M_D_CPU1_SB_DQ<23>")
	)
	(segment
		(start 35.732212 -203.692252)
		(end 35.297872 -204.126592)
		(width 0.18288)
		(layer "In6.Cu")
		(net "M_D_CPU1_SB_DQ<23>")
	)
	(segment
		(start 50.654712 -203.92898)
		(end 50.16373 -203.92898)
		(width 0.18288)
		(layer "In6.Cu")
		(net "M_D_CPU1_SB_DQ<23>")
	)
	(segment
		(start 63.778892 -206.945992)
		(end 63.029592 -206.945992)
		(width 0.18288)
		(layer "In6.Cu")
		(net "M_D_CPU1_SB_DQ<23>")
	)
	(segment
		(start 57.945274 -206.379826)
		(end 57.762394 -206.196946)
		(width 0.18288)
		(layer "In6.Cu")
		(net "M_D_CPU1_SB_DQ<23>")
	)
	(segment
		(start 57.071514 -206.196946)
		(end 56.888634 -206.379826)
		(width 0.18288)
		(layer "In6.Cu")
		(net "M_D_CPU1_SB_DQ<23>")
	)
	(segment
		(start 26.992072 -204.172058)
		(end 26.992072 -204.380846)
		(width 0.18288)
		(layer "In6.Cu")
		(net "M_D_CPU1_SB_DQ<23>")
	)
	(segment
		(start 49.553876 -204.538834)
		(end 43.75531 -204.538834)
		(width 0.18288)
		(layer "In6.Cu")
		(net "M_D_CPU1_SB_DQ<23>")
	)
	(segment
		(start 54.368446 -205.447392)
		(end 52.786534 -203.86548)
		(width 0.18288)
		(layer "In6.Cu")
		(net "M_D_CPU1_SB_DQ<23>")
	)
	(segment
		(start 33.809178 -204.860652)
		(end 33.260792 -204.860652)
		(width 0.18288)
		(layer "In6.Cu")
		(net "M_D_CPU1_SB_DQ<23>")
	)
	(segment
		(start 23.412704 -204.343)
		(end 23.229824 -204.16012)
		(width 0.18288)
		(layer "In6.Cu")
		(net "M_D_CPU1_SB_DQ<23>")
	)
	(segment
		(start 63.029592 -206.945992)
		(end 62.722252 -207.253332)
		(width 0.18288)
		(layer "In6.Cu")
		(net "M_D_CPU1_SB_DQ<23>")
	)
	(segment
		(start 34.543238 -204.126592)
		(end 33.809178 -204.860652)
		(width 0.18288)
		(layer "In6.Cu")
		(net "M_D_CPU1_SB_DQ<23>")
	)
	(segment
		(start 26.992072 -204.380846)
		(end 26.832052 -204.540866)
		(width 0.18288)
		(layer "In6.Cu")
		(net "M_D_CPU1_SB_DQ<23>")
	)
	(arc
		(start 92.172282 -230.402384)
		(mid 91.895807 -230.335064)
		(end 91.62161 -230.41102)
		(width 0.088646)
		(layer "In6.Cu")
		(net "M_D_CPU1_SB_DQ<23>")
	)
	(arc
		(start 92.56141 -230.41102)
		(mid 92.374212 -230.461163)
		(end 92.187014 -230.41102)
		(width 0.088646)
		(layer "In6.Cu")
		(net "M_D_CPU1_SB_DQ<23>")
	)
	(arc
		(start 95.762826 -230.484426)
		(mid 95.448756 -230.487795)
		(end 95.136208 -230.45674)
		(width 0.088646)
		(layer "In6.Cu")
		(net "M_D_CPU1_SB_DQ<23>")
	)
	(arc
		(start 89.272364 -229.597204)
		(mid 89.085166 -229.647347)
		(end 88.897968 -229.597204)
		(width 0.088646)
		(layer "In6.Cu")
		(net "M_D_CPU1_SB_DQ<23>")
	)
	(arc
		(start 85.043518 -228.783388)
		(mid 84.668821 -228.783507)
		(end 84.481416 -228.45903)
		(width 0.088646)
		(layer "In6.Cu")
		(net "M_D_CPU1_SB_DQ<23>")
	)
	(arc
		(start 90.212164 -229.597204)
		(mid 90.024966 -229.647347)
		(end 89.837768 -229.597204)
		(width 0.088646)
		(layer "In6.Cu")
		(net "M_D_CPU1_SB_DQ<23>")
	)
	(arc
		(start 87.947754 -229.591108)
		(mid 87.669322 -229.521294)
		(end 87.39251 -229.597204)
		(width 0.088646)
		(layer "In6.Cu")
		(net "M_D_CPU1_SB_DQ<23>")
	)
	(arc
		(start 95.136208 -230.45674)
		(mid 95.069193 -230.439894)
		(end 95.006414 -230.41102)
		(width 0.088646)
		(layer "In6.Cu")
		(net "M_D_CPU1_SB_DQ<23>")
	)
	(arc
		(start 91.62161 -230.41102)
		(mid 91.250887 -230.413112)
		(end 91.060016 -230.095298)
		(width 0.088646)
		(layer "In6.Cu")
		(net "M_D_CPU1_SB_DQ<23>")
	)
	(arc
		(start 94.44101 -230.41102)
		(mid 94.253812 -230.461163)
		(end 94.066614 -230.41102)
		(width 0.088646)
		(layer "In6.Cu")
		(net "M_D_CPU1_SB_DQ<23>")
	)
	(arc
		(start 87.39251 -229.597204)
		(mid 87.021787 -229.599296)
		(end 86.830916 -229.281482)
		(width 0.088646)
		(layer "In6.Cu")
		(net "M_D_CPU1_SB_DQ<23>")
	)
	(arc
		(start 88.897968 -229.597204)
		(mid 88.623769 -229.521369)
		(end 88.347296 -229.588568)
		(width 0.088646)
		(layer "In6.Cu")
		(net "M_D_CPU1_SB_DQ<23>")
	)
	(arc
		(start 85.598254 -228.777292)
		(mid 85.320076 -228.707569)
		(end 85.043518 -228.783388)
		(width 0.088646)
		(layer "In6.Cu")
		(net "M_D_CPU1_SB_DQ<23>")
	)
	(arc
		(start 94.991682 -230.402384)
		(mid 94.715207 -230.335064)
		(end 94.44101 -230.41102)
		(width 0.088646)
		(layer "In6.Cu")
		(net "M_D_CPU1_SB_DQ<23>")
	)
	(arc
		(start 85.983064 -228.783642)
		(mid 85.795866 -228.833785)
		(end 85.608668 -228.783642)
		(width 0.088646)
		(layer "In6.Cu")
		(net "M_D_CPU1_SB_DQ<23>")
	)
	(arc
		(start 86.830662 -229.26294)
		(mid 86.543806 -228.781262)
		(end 85.983064 -228.783642)
		(width 0.088646)
		(layer "In6.Cu")
		(net "M_D_CPU1_SB_DQ<23>")
	)
	(arc
		(start 93.112082 -230.402384)
		(mid 92.835607 -230.335064)
		(end 92.56141 -230.41102)
		(width 0.088646)
		(layer "In6.Cu")
		(net "M_D_CPU1_SB_DQ<23>")
	)
	(arc
		(start 94.051882 -230.402384)
		(mid 93.775407 -230.335064)
		(end 93.50121 -230.41102)
		(width 0.088646)
		(layer "In6.Cu")
		(net "M_D_CPU1_SB_DQ<23>")
	)
	(arc
		(start 89.837768 -229.597204)
		(mid 89.563569 -229.521369)
		(end 89.287096 -229.588568)
		(width 0.088646)
		(layer "In6.Cu")
		(net "M_D_CPU1_SB_DQ<23>")
	)
	(arc
		(start 96.603566 -230.900478)
		(mid 96.239125 -230.579386)
		(end 95.762826 -230.484426)
		(width 0.088646)
		(layer "In6.Cu")
		(net "M_D_CPU1_SB_DQ<23>")
	)
	(arc
		(start 91.060016 -230.076756)
		(mid 90.773141 -229.594671)
		(end 90.212164 -229.597204)
		(width 0.088646)
		(layer "In6.Cu")
		(net "M_D_CPU1_SB_DQ<23>")
	)
	(arc
		(start 93.50121 -230.41102)
		(mid 93.314012 -230.461163)
		(end 93.126814 -230.41102)
		(width 0.088646)
		(layer "In6.Cu")
		(net "M_D_CPU1_SB_DQ<23>")
	)
	(arc
		(start 88.332564 -229.597204)
		(mid 88.145366 -229.647347)
		(end 87.958168 -229.597204)
		(width 0.088646)
		(layer "In6.Cu")
		(net "M_D_CPU1_SB_DQ<23>")
	)
	(segment
		(start 14.825218 -206.24165)
		(end 16.885158 -206.24165)
		(width 0.1016)
		(layer "F.Cu")
		(net "M_D_CPU1_SB_DQ<22>")
	)
	(segment
		(start 13.387578 -206.666592)
		(end 13.82268 -206.23149)
		(width 0.20066)
		(layer "F.Cu")
		(net "M_D_CPU1_SB_DQ<22>")
	)
	(segment
		(start 12.240514 -206.666592)
		(end 13.387578 -206.666592)
		(width 0.20066)
		(layer "F.Cu")
		(net "M_D_CPU1_SB_DQ<22>")
	)
	(segment
		(start 14.560042 -206.23149)
		(end 14.570202 -206.24165)
		(width 0.101854)
		(layer "F.Cu")
		(net "M_D_CPU1_SB_DQ<22>")
	)
	(segment
		(start 13.82268 -206.23149)
		(end 14.560042 -206.23149)
		(width 0.20066)
		(layer "F.Cu")
		(net "M_D_CPU1_SB_DQ<22>")
	)
	(segment
		(start 18.46961 -206.666592)
		(end 19.784314 -206.666592)
		(width 0.20066)
		(layer "F.Cu")
		(net "M_D_CPU1_SB_DQ<22>")
	)
	(segment
		(start 17.66189 -206.711042)
		(end 17.829276 -206.878428)
		(width 0.20066)
		(layer "F.Cu")
		(net "M_D_CPU1_SB_DQ<22>")
	)
	(segment
		(start 20.889214 -206.666592)
		(end 19.784314 -206.666592)
		(width 0.20066)
		(layer "F.Cu")
		(net "M_D_CPU1_SB_DQ<22>")
	)
	(segment
		(start 97.073466 -232.250488)
		(end 97.073212 -232.250234)
		(width 0.20066)
		(layer "F.Cu")
		(net "M_D_CPU1_SB_DQ<22>")
	)
	(segment
		(start 14.570202 -206.24165)
		(end 14.825218 -206.24165)
		(width 0.101854)
		(layer "F.Cu")
		(net "M_D_CPU1_SB_DQ<22>")
	)
	(segment
		(start 18.257774 -206.878428)
		(end 18.46961 -206.666592)
		(width 0.20066)
		(layer "F.Cu")
		(net "M_D_CPU1_SB_DQ<22>")
	)
	(segment
		(start 17.66189 -206.385414)
		(end 17.66189 -206.711042)
		(width 0.20066)
		(layer "F.Cu")
		(net "M_D_CPU1_SB_DQ<22>")
	)
	(segment
		(start 16.885158 -206.24165)
		(end 17.518126 -206.24165)
		(width 0.20066)
		(layer "F.Cu")
		(net "M_D_CPU1_SB_DQ<22>")
	)
	(segment
		(start 97.073212 -232.250234)
		(end 97.073212 -231.714548)
		(width 0.20066)
		(layer "F.Cu")
		(net "M_D_CPU1_SB_DQ<22>")
	)
	(segment
		(start 17.518126 -206.24165)
		(end 17.66189 -206.385414)
		(width 0.20066)
		(layer "F.Cu")
		(net "M_D_CPU1_SB_DQ<22>")
	)
	(segment
		(start 17.829276 -206.878428)
		(end 18.257774 -206.878428)
		(width 0.20066)
		(layer "F.Cu")
		(net "M_D_CPU1_SB_DQ<22>")
	)
	(segment
		(start 39.94023 -205.39075)
		(end 39.188898 -205.39075)
		(width 0.18288)
		(layer "In6.Cu")
		(net "M_D_CPU1_SB_DQ<22>")
	)
	(segment
		(start 78.659228 -227.351844)
		(end 75.926696 -224.619312)
		(width 0.18288)
		(layer "In6.Cu")
		(net "M_D_CPU1_SB_DQ<22>")
	)
	(segment
		(start 57.784746 -208.183226)
		(end 57.601866 -208.000346)
		(width 0.18288)
		(layer "In6.Cu")
		(net "M_D_CPU1_SB_DQ<22>")
	)
	(segment
		(start 23.713694 -206.460852)
		(end 23.553674 -206.620872)
		(width 0.18288)
		(layer "In6.Cu")
		(net "M_D_CPU1_SB_DQ<22>")
	)
	(segment
		(start 27.282394 -205.918308)
		(end 26.957274 -205.918308)
		(width 0.18288)
		(layer "In6.Cu")
		(net "M_D_CPU1_SB_DQ<22>")
	)
	(segment
		(start 92.106496 -231.2162)
		(end 92.091764 -231.224836)
		(width 0.088646)
		(layer "In6.Cu")
		(net "M_D_CPU1_SB_DQ<22>")
	)
	(segment
		(start 96.23933 -231.297226)
		(end 94.803214 -231.297226)
		(width 0.088646)
		(layer "In6.Cu")
		(net "M_D_CPU1_SB_DQ<22>")
	)
	(segment
		(start 23.020274 -206.217012)
		(end 22.860254 -206.056992)
		(width 0.18288)
		(layer "In6.Cu")
		(net "M_D_CPU1_SB_DQ<22>")
	)
	(segment
		(start 23.020274 -206.460852)
		(end 23.020274 -206.217012)
		(width 0.18288)
		(layer "In6.Cu")
		(net "M_D_CPU1_SB_DQ<22>")
	)
	(segment
		(start 85.138768 -229.597458)
		(end 85.125052 -229.58933)
		(width 0.088646)
		(layer "In6.Cu")
		(net "M_D_CPU1_SB_DQ<22>")
	)
	(segment
		(start 29.083762 -206.240888)
		(end 28.921964 -206.402686)
		(width 0.18288)
		(layer "In6.Cu")
		(net "M_D_CPU1_SB_DQ<22>")
	)
	(segment
		(start 57.601866 -207.691228)
		(end 57.418986 -207.508348)
		(width 0.18288)
		(layer "In6.Cu")
		(net "M_D_CPU1_SB_DQ<22>")
	)
	(segment
		(start 87.862664 -230.41102)
		(end 87.851742 -230.41737)
		(width 0.088646)
		(layer "In6.Cu")
		(net "M_D_CPU1_SB_DQ<22>")
	)
	(segment
		(start 97.073212 -231.714548)
		(end 97.072958 -231.714294)
		(width 0.088646)
		(layer "In6.Cu")
		(net "M_D_CPU1_SB_DQ<22>")
	)
	(segment
		(start 87.488268 -230.411274)
		(end 87.470996 -230.401114)
		(width 0.088646)
		(layer "In6.Cu")
		(net "M_D_CPU1_SB_DQ<22>")
	)
	(segment
		(start 34.2011 -206.240888)
		(end 30.672024 -206.240888)
		(width 0.18288)
		(layer "In6.Cu")
		(net "M_D_CPU1_SB_DQ<22>")
	)
	(segment
		(start 23.713694 -206.217012)
		(end 23.713694 -206.460852)
		(width 0.18288)
		(layer "In6.Cu")
		(net "M_D_CPU1_SB_DQ<22>")
	)
	(segment
		(start 66.876168 -211.694268)
		(end 66.292476 -211.110576)
		(width 0.18288)
		(layer "In6.Cu")
		(net "M_D_CPU1_SB_DQ<22>")
	)
	(segment
		(start 27.465274 -206.219806)
		(end 27.465274 -206.101188)
		(width 0.18288)
		(layer "In6.Cu")
		(net "M_D_CPU1_SB_DQ<22>")
	)
	(segment
		(start 84.386166 -229.648004)
		(end 84.22132 -229.648004)
		(width 0.088646)
		(layer "In6.Cu")
		(net "M_D_CPU1_SB_DQ<22>")
	)
	(segment
		(start 27.648154 -206.402686)
		(end 27.465274 -206.219806)
		(width 0.18288)
		(layer "In6.Cu")
		(net "M_D_CPU1_SB_DQ<22>")
	)
	(segment
		(start 50.458624 -205.391766)
		(end 49.607978 -206.242412)
		(width 0.18288)
		(layer "In6.Cu")
		(net "M_D_CPU1_SB_DQ<22>")
	)
	(segment
		(start 86.361016 -230.086662)
		(end 86.360762 -230.076756)
		(width 0.088646)
		(layer "In6.Cu")
		(net "M_D_CPU1_SB_DQ<22>")
	)
	(segment
		(start 84.22132 -229.648004)
		(end 84.008976 -229.43566)
		(width 0.088646)
		(layer "In6.Cu")
		(net "M_D_CPU1_SB_DQ<22>")
	)
	(segment
		(start 26.774394 -206.101188)
		(end 26.774394 -206.219806)
		(width 0.18288)
		(layer "In6.Cu")
		(net "M_D_CPU1_SB_DQ<22>")
	)
	(segment
		(start 93.046296 -231.2162)
		(end 93.031564 -231.224836)
		(width 0.088646)
		(layer "In6.Cu")
		(net "M_D_CPU1_SB_DQ<22>")
	)
	(segment
		(start 86.361016 -230.095298)
		(end 86.361016 -230.086662)
		(width 0.088646)
		(layer "In6.Cu")
		(net "M_D_CPU1_SB_DQ<22>")
	)
	(segment
		(start 38.160452 -205.39075)
		(end 37.807138 -205.39075)
		(width 0.18288)
		(layer "In6.Cu")
		(net "M_D_CPU1_SB_DQ<22>")
	)
	(segment
		(start 56.910986 -207.691228)
		(end 56.910986 -208.000346)
		(width 0.18288)
		(layer "In6.Cu")
		(net "M_D_CPU1_SB_DQ<22>")
	)
	(segment
		(start 36.778692 -205.39075)
		(end 35.051238 -205.39075)
		(width 0.18288)
		(layer "In6.Cu")
		(net "M_D_CPU1_SB_DQ<22>")
	)
	(segment
		(start 28.921964 -206.402686)
		(end 27.648154 -206.402686)
		(width 0.18288)
		(layer "In6.Cu")
		(net "M_D_CPU1_SB_DQ<22>")
	)
	(segment
		(start 66.292476 -211.110576)
		(end 66.082672 -211.110576)
		(width 0.18288)
		(layer "In6.Cu")
		(net "M_D_CPU1_SB_DQ<22>")
	)
	(segment
		(start 23.553674 -206.620872)
		(end 23.180294 -206.620872)
		(width 0.18288)
		(layer "In6.Cu")
		(net "M_D_CPU1_SB_DQ<22>")
	)
	(segment
		(start 82.74177 -227.351844)
		(end 82.479642 -227.351844)
		(width 0.088646)
		(layer "In6.Cu")
		(net "M_D_CPU1_SB_DQ<22>")
	)
	(segment
		(start 35.051238 -205.39075)
		(end 34.2011 -206.240888)
		(width 0.18288)
		(layer "In6.Cu")
		(net "M_D_CPU1_SB_DQ<22>")
	)
	(segment
		(start 29.67609 -206.240888)
		(end 29.083762 -206.240888)
		(width 0.18288)
		(layer "In6.Cu")
		(net "M_D_CPU1_SB_DQ<22>")
	)
	(segment
		(start 90.307668 -230.41102)
		(end 90.297254 -230.404924)
		(width 0.088646)
		(layer "In6.Cu")
		(net "M_D_CPU1_SB_DQ<22>")
	)
	(segment
		(start 23.180294 -206.620872)
		(end 23.020274 -206.460852)
		(width 0.18288)
		(layer "In6.Cu")
		(net "M_D_CPU1_SB_DQ<22>")
	)
	(segment
		(start 56.037226 -208.183226)
		(end 55.097426 -207.243426)
		(width 0.18288)
		(layer "In6.Cu")
		(net "M_D_CPU1_SB_DQ<22>")
	)
	(segment
		(start 88.427814 -230.41102)
		(end 88.4174 -230.404924)
		(width 0.088646)
		(layer "In6.Cu")
		(net "M_D_CPU1_SB_DQ<22>")
	)
	(segment
		(start 21.498814 -206.056992)
		(end 20.889214 -206.666592)
		(width 0.18288)
		(layer "In6.Cu")
		(net "M_D_CPU1_SB_DQ<22>")
	)
	(segment
		(start 55.097426 -207.243426)
		(end 54.284626 -207.243426)
		(width 0.18288)
		(layer "In6.Cu")
		(net "M_D_CPU1_SB_DQ<22>")
	)
	(segment
		(start 30.672024 -206.240888)
		(end 30.36697 -205.935834)
		(width 0.18288)
		(layer "In6.Cu")
		(net "M_D_CPU1_SB_DQ<22>")
	)
	(segment
		(start 49.607978 -206.242412)
		(end 40.791892 -206.242412)
		(width 0.18288)
		(layer "In6.Cu")
		(net "M_D_CPU1_SB_DQ<22>")
	)
	(segment
		(start 37.807138 -205.39075)
		(end 37.469572 -205.728316)
		(width 0.18288)
		(layer "In6.Cu")
		(net "M_D_CPU1_SB_DQ<22>")
	)
	(segment
		(start 84.008976 -229.43566)
		(end 84.008976 -228.61905)
		(width 0.088646)
		(layer "In6.Cu")
		(net "M_D_CPU1_SB_DQ<22>")
	)
	(segment
		(start 38.498018 -205.728316)
		(end 38.160452 -205.39075)
		(width 0.18288)
		(layer "In6.Cu")
		(net "M_D_CPU1_SB_DQ<22>")
	)
	(segment
		(start 26.774394 -206.219806)
		(end 26.591514 -206.402686)
		(width 0.18288)
		(layer "In6.Cu")
		(net "M_D_CPU1_SB_DQ<22>")
	)
	(segment
		(start 64.304926 -208.996026)
		(end 61.035946 -208.996026)
		(width 0.18288)
		(layer "In6.Cu")
		(net "M_D_CPU1_SB_DQ<22>")
	)
	(segment
		(start 40.791892 -206.242412)
		(end 39.94023 -205.39075)
		(width 0.18288)
		(layer "In6.Cu")
		(net "M_D_CPU1_SB_DQ<22>")
	)
	(segment
		(start 56.728106 -208.183226)
		(end 56.037226 -208.183226)
		(width 0.18288)
		(layer "In6.Cu")
		(net "M_D_CPU1_SB_DQ<22>")
	)
	(segment
		(start 26.002996 -206.402686)
		(end 25.657302 -206.056992)
		(width 0.18288)
		(layer "In6.Cu")
		(net "M_D_CPU1_SB_DQ<22>")
	)
	(segment
		(start 37.116258 -205.728316)
		(end 36.778692 -205.39075)
		(width 0.18288)
		(layer "In6.Cu")
		(net "M_D_CPU1_SB_DQ<22>")
	)
	(segment
		(start 52.432966 -205.391766)
		(end 50.458624 -205.391766)
		(width 0.18288)
		(layer "In6.Cu")
		(net "M_D_CPU1_SB_DQ<22>")
	)
	(segment
		(start 57.601866 -208.000346)
		(end 57.601866 -207.691228)
		(width 0.18288)
		(layer "In6.Cu")
		(net "M_D_CPU1_SB_DQ<22>")
	)
	(segment
		(start 59.943746 -207.903826)
		(end 59.339226 -207.903826)
		(width 0.18288)
		(layer "In6.Cu")
		(net "M_D_CPU1_SB_DQ<22>")
	)
	(segment
		(start 23.873714 -206.056992)
		(end 23.713694 -206.217012)
		(width 0.18288)
		(layer "In6.Cu")
		(net "M_D_CPU1_SB_DQ<22>")
	)
	(segment
		(start 29.981144 -205.935834)
		(end 29.67609 -206.240888)
		(width 0.18288)
		(layer "In6.Cu")
		(net "M_D_CPU1_SB_DQ<22>")
	)
	(segment
		(start 89.367614 -230.41102)
		(end 89.352882 -230.402384)
		(width 0.088646)
		(layer "In6.Cu")
		(net "M_D_CPU1_SB_DQ<22>")
	)
	(segment
		(start 75.926696 -221.988634)
		(end 67.75577 -213.817708)
		(width 0.18288)
		(layer "In6.Cu")
		(net "M_D_CPU1_SB_DQ<22>")
	)
	(segment
		(start 66.082672 -211.110576)
		(end 65.350644 -210.378548)
		(width 0.18288)
		(layer "In6.Cu")
		(net "M_D_CPU1_SB_DQ<22>")
	)
	(segment
		(start 61.035946 -208.996026)
		(end 59.943746 -207.903826)
		(width 0.18288)
		(layer "In6.Cu")
		(net "M_D_CPU1_SB_DQ<22>")
	)
	(segment
		(start 30.36697 -205.935834)
		(end 29.981144 -205.935834)
		(width 0.18288)
		(layer "In6.Cu")
		(net "M_D_CPU1_SB_DQ<22>")
	)
	(segment
		(start 65.350644 -210.041744)
		(end 64.304926 -208.996026)
		(width 0.18288)
		(layer "In6.Cu")
		(net "M_D_CPU1_SB_DQ<22>")
	)
	(segment
		(start 22.860254 -206.056992)
		(end 21.498814 -206.056992)
		(width 0.18288)
		(layer "In6.Cu")
		(net "M_D_CPU1_SB_DQ<22>")
	)
	(segment
		(start 84.008976 -228.61905)
		(end 82.74177 -227.351844)
		(width 0.088646)
		(layer "In6.Cu")
		(net "M_D_CPU1_SB_DQ<22>")
	)
	(segment
		(start 37.469572 -205.728316)
		(end 37.116258 -205.728316)
		(width 0.18288)
		(layer "In6.Cu")
		(net "M_D_CPU1_SB_DQ<22>")
	)
	(segment
		(start 59.339226 -207.903826)
		(end 59.059826 -208.183226)
		(width 0.18288)
		(layer "In6.Cu")
		(net "M_D_CPU1_SB_DQ<22>")
	)
	(segment
		(start 59.059826 -208.183226)
		(end 57.784746 -208.183226)
		(width 0.18288)
		(layer "In6.Cu")
		(net "M_D_CPU1_SB_DQ<22>")
	)
	(segment
		(start 91.162124 -231.21874)
		(end 91.15171 -231.224836)
		(width 0.088646)
		(layer "In6.Cu")
		(net "M_D_CPU1_SB_DQ<22>")
	)
	(segment
		(start 26.591514 -206.402686)
		(end 26.002996 -206.402686)
		(width 0.18288)
		(layer "In6.Cu")
		(net "M_D_CPU1_SB_DQ<22>")
	)
	(segment
		(start 57.093866 -207.508348)
		(end 56.910986 -207.691228)
		(width 0.18288)
		(layer "In6.Cu")
		(net "M_D_CPU1_SB_DQ<22>")
	)
	(segment
		(start 82.479642 -227.351844)
		(end 78.659228 -227.351844)
		(width 0.18288)
		(layer "In6.Cu")
		(net "M_D_CPU1_SB_DQ<22>")
	)
	(segment
		(start 26.957274 -205.918308)
		(end 26.774394 -206.101188)
		(width 0.18288)
		(layer "In6.Cu")
		(net "M_D_CPU1_SB_DQ<22>")
	)
	(segment
		(start 56.910986 -208.000346)
		(end 56.728106 -208.183226)
		(width 0.18288)
		(layer "In6.Cu")
		(net "M_D_CPU1_SB_DQ<22>")
	)
	(segment
		(start 67.75577 -213.817708)
		(end 66.876168 -211.694268)
		(width 0.18288)
		(layer "In6.Cu")
		(net "M_D_CPU1_SB_DQ<22>")
	)
	(segment
		(start 25.657302 -206.056992)
		(end 23.873714 -206.056992)
		(width 0.18288)
		(layer "In6.Cu")
		(net "M_D_CPU1_SB_DQ<22>")
	)
	(segment
		(start 75.926696 -224.619312)
		(end 75.926696 -221.988634)
		(width 0.18288)
		(layer "In6.Cu")
		(net "M_D_CPU1_SB_DQ<22>")
	)
	(segment
		(start 38.851332 -205.728316)
		(end 38.498018 -205.728316)
		(width 0.18288)
		(layer "In6.Cu")
		(net "M_D_CPU1_SB_DQ<22>")
	)
	(segment
		(start 65.350644 -210.378548)
		(end 65.350644 -210.041744)
		(width 0.18288)
		(layer "In6.Cu")
		(net "M_D_CPU1_SB_DQ<22>")
	)
	(segment
		(start 57.418986 -207.508348)
		(end 57.093866 -207.508348)
		(width 0.18288)
		(layer "In6.Cu")
		(net "M_D_CPU1_SB_DQ<22>")
	)
	(segment
		(start 54.284626 -207.243426)
		(end 52.432966 -205.391766)
		(width 0.18288)
		(layer "In6.Cu")
		(net "M_D_CPU1_SB_DQ<22>")
	)
	(segment
		(start 27.465274 -206.101188)
		(end 27.282394 -205.918308)
		(width 0.18288)
		(layer "In6.Cu")
		(net "M_D_CPU1_SB_DQ<22>")
	)
	(segment
		(start 39.188898 -205.39075)
		(end 38.851332 -205.728316)
		(width 0.18288)
		(layer "In6.Cu")
		(net "M_D_CPU1_SB_DQ<22>")
	)
	(segment
		(start 90.590116 -230.909114)
		(end 90.590116 -230.890572)
		(width 0.088646)
		(layer "In6.Cu")
		(net "M_D_CPU1_SB_DQ<22>")
	)
	(arc
		(start 90.297254 -230.404924)
		(mid 90.018822 -230.335078)
		(end 89.74201 -230.41102)
		(width 0.088646)
		(layer "In6.Cu")
		(net "M_D_CPU1_SB_DQ<22>")
	)
	(arc
		(start 94.536768 -231.224836)
		(mid 94.254066 -231.149094)
		(end 93.971364 -231.224836)
		(width 0.088646)
		(layer "In6.Cu")
		(net "M_D_CPU1_SB_DQ<22>")
	)
	(arc
		(start 88.80221 -230.41102)
		(mid 88.615012 -230.461163)
		(end 88.427814 -230.41102)
		(width 0.088646)
		(layer "In6.Cu")
		(net "M_D_CPU1_SB_DQ<22>")
	)
	(arc
		(start 85.125052 -229.58933)
		(mid 84.848192 -229.521458)
		(end 84.573364 -229.597204)
		(width 0.088646)
		(layer "In6.Cu")
		(net "M_D_CPU1_SB_DQ<22>")
	)
	(arc
		(start 88.4174 -230.404924)
		(mid 88.139222 -230.335201)
		(end 87.862664 -230.41102)
		(width 0.088646)
		(layer "In6.Cu")
		(net "M_D_CPU1_SB_DQ<22>")
	)
	(arc
		(start 96.327976 -231.306624)
		(mid 96.283907 -231.299533)
		(end 96.23933 -231.297226)
		(width 0.088646)
		(layer "In6.Cu")
		(net "M_D_CPU1_SB_DQ<22>")
	)
	(arc
		(start 92.091764 -231.224836)
		(mid 91.904566 -231.274979)
		(end 91.717368 -231.224836)
		(width 0.088646)
		(layer "In6.Cu")
		(net "M_D_CPU1_SB_DQ<22>")
	)
	(arc
		(start 93.031564 -231.224836)
		(mid 92.844366 -231.274979)
		(end 92.657168 -231.224836)
		(width 0.088646)
		(layer "In6.Cu")
		(net "M_D_CPU1_SB_DQ<22>")
	)
	(arc
		(start 86.360762 -230.076756)
		(mid 86.282739 -229.799957)
		(end 86.078568 -229.597458)
		(width 0.088646)
		(layer "In6.Cu")
		(net "M_D_CPU1_SB_DQ<22>")
	)
	(arc
		(start 89.74201 -230.41102)
		(mid 89.554812 -230.461163)
		(end 89.367614 -230.41102)
		(width 0.088646)
		(layer "In6.Cu")
		(net "M_D_CPU1_SB_DQ<22>")
	)
	(arc
		(start 89.352882 -230.402384)
		(mid 89.076407 -230.335064)
		(end 88.80221 -230.41102)
		(width 0.088646)
		(layer "In6.Cu")
		(net "M_D_CPU1_SB_DQ<22>")
	)
	(arc
		(start 93.596968 -231.224836)
		(mid 93.322739 -231.148911)
		(end 93.046296 -231.2162)
		(width 0.088646)
		(layer "In6.Cu")
		(net "M_D_CPU1_SB_DQ<22>")
	)
	(arc
		(start 84.573364 -229.597204)
		(mid 84.483108 -229.634926)
		(end 84.386166 -229.648004)
		(width 0.088646)
		(layer "In6.Cu")
		(net "M_D_CPU1_SB_DQ<22>")
	)
	(arc
		(start 92.657168 -231.224836)
		(mid 92.382939 -231.148911)
		(end 92.106496 -231.2162)
		(width 0.088646)
		(layer "In6.Cu")
		(net "M_D_CPU1_SB_DQ<22>")
	)
	(arc
		(start 87.470996 -230.401114)
		(mid 87.195533 -230.335196)
		(end 86.92261 -230.41102)
		(width 0.088646)
		(layer "In6.Cu")
		(net "M_D_CPU1_SB_DQ<22>")
	)
	(arc
		(start 86.548214 -230.41102)
		(mid 86.413281 -230.277666)
		(end 86.361016 -230.095298)
		(width 0.088646)
		(layer "In6.Cu")
		(net "M_D_CPU1_SB_DQ<22>")
	)
	(arc
		(start 93.971364 -231.224836)
		(mid 93.784166 -231.274979)
		(end 93.596968 -231.224836)
		(width 0.088646)
		(layer "In6.Cu")
		(net "M_D_CPU1_SB_DQ<22>")
	)
	(arc
		(start 87.851742 -230.41737)
		(mid 87.669212 -230.461394)
		(end 87.488268 -230.411274)
		(width 0.088646)
		(layer "In6.Cu")
		(net "M_D_CPU1_SB_DQ<22>")
	)
	(arc
		(start 86.92261 -230.41102)
		(mid 86.735412 -230.461163)
		(end 86.548214 -230.41102)
		(width 0.088646)
		(layer "In6.Cu")
		(net "M_D_CPU1_SB_DQ<22>")
	)
	(arc
		(start 97.072958 -231.714294)
		(mid 96.729703 -231.457036)
		(end 96.327976 -231.306624)
		(width 0.088646)
		(layer "In6.Cu")
		(net "M_D_CPU1_SB_DQ<22>")
	)
	(arc
		(start 90.590116 -230.890572)
		(mid 90.512005 -230.613623)
		(end 90.307668 -230.41102)
		(width 0.088646)
		(layer "In6.Cu")
		(net "M_D_CPU1_SB_DQ<22>")
	)
	(arc
		(start 90.777314 -231.224836)
		(mid 90.642381 -231.091482)
		(end 90.590116 -230.909114)
		(width 0.088646)
		(layer "In6.Cu")
		(net "M_D_CPU1_SB_DQ<22>")
	)
	(arc
		(start 94.803214 -231.297226)
		(mid 94.665292 -231.278327)
		(end 94.536768 -231.224836)
		(width 0.088646)
		(layer "In6.Cu")
		(net "M_D_CPU1_SB_DQ<22>")
	)
	(arc
		(start 91.717368 -231.224836)
		(mid 91.440555 -231.149)
		(end 91.162124 -231.21874)
		(width 0.088646)
		(layer "In6.Cu")
		(net "M_D_CPU1_SB_DQ<22>")
	)
	(arc
		(start 85.513164 -229.597458)
		(mid 85.325966 -229.647601)
		(end 85.138768 -229.597458)
		(width 0.088646)
		(layer "In6.Cu")
		(net "M_D_CPU1_SB_DQ<22>")
	)
	(arc
		(start 91.15171 -231.224836)
		(mid 90.964512 -231.274979)
		(end 90.777314 -231.224836)
		(width 0.088646)
		(layer "In6.Cu")
		(net "M_D_CPU1_SB_DQ<22>")
	)
	(arc
		(start 86.078568 -229.597458)
		(mid 85.795866 -229.521682)
		(end 85.513164 -229.597458)
		(width 0.088646)
		(layer "In6.Cu")
		(net "M_D_CPU1_SB_DQ<22>")
	)
	(segment
		(start 10.344912 -205.873604)
		(end 10.344912 -205.545436)
		(width 0.20066)
		(layer "F.Cu")
		(net "M_D_CPU1_SB_DQ<21>")
	)
	(segment
		(start 95.663766 -231.436164)
		(end 95.663766 -230.900478)
		(width 0.20066)
		(layer "F.Cu")
		(net "M_D_CPU1_SB_DQ<21>")
	)
	(segment
		(start 13.110718 -205.391766)
		(end 13.441426 -205.391766)
		(width 0.101854)
		(layer "F.Cu")
		(net "M_D_CPU1_SB_DQ<21>")
	)
	(segment
		(start 11.1252 -205.391766)
		(end 13.110718 -205.391766)
		(width 0.1016)
		(layer "F.Cu")
		(net "M_D_CPU1_SB_DQ<21>")
	)
	(segment
		(start 10.19048 -206.028036)
		(end 10.344912 -205.873604)
		(width 0.20066)
		(layer "F.Cu")
		(net "M_D_CPU1_SB_DQ<21>")
	)
	(segment
		(start 8.140446 -205.816708)
		(end 9.474708 -205.816708)
		(width 0.20066)
		(layer "F.Cu")
		(net "M_D_CPU1_SB_DQ<21>")
	)
	(segment
		(start 13.441426 -205.391766)
		(end 13.619988 -205.391766)
		(width 0.20066)
		(layer "F.Cu")
		(net "M_D_CPU1_SB_DQ<21>")
	)
	(segment
		(start 11.11631 -205.382876)
		(end 11.1252 -205.391766)
		(width 0.1016)
		(layer "F.Cu")
		(net "M_D_CPU1_SB_DQ<21>")
	)
	(segment
		(start 16.789146 -205.816708)
		(end 15.684246 -205.816708)
		(width 0.20066)
		(layer "F.Cu")
		(net "M_D_CPU1_SB_DQ<21>")
	)
	(segment
		(start 10.344912 -205.545436)
		(end 10.507472 -205.382876)
		(width 0.20066)
		(layer "F.Cu")
		(net "M_D_CPU1_SB_DQ<21>")
	)
	(segment
		(start 10.507472 -205.382876)
		(end 11.11631 -205.382876)
		(width 0.20066)
		(layer "F.Cu")
		(net "M_D_CPU1_SB_DQ<21>")
	)
	(segment
		(start 13.619988 -205.391766)
		(end 14.04493 -205.816708)
		(width 0.20066)
		(layer "F.Cu")
		(net "M_D_CPU1_SB_DQ<21>")
	)
	(segment
		(start 9.474708 -205.816708)
		(end 9.686036 -206.028036)
		(width 0.20066)
		(layer "F.Cu")
		(net "M_D_CPU1_SB_DQ<21>")
	)
	(segment
		(start 95.663512 -231.436418)
		(end 95.663766 -231.436164)
		(width 0.20066)
		(layer "F.Cu")
		(net "M_D_CPU1_SB_DQ<21>")
	)
	(segment
		(start 14.04493 -205.816708)
		(end 15.684246 -205.816708)
		(width 0.20066)
		(layer "F.Cu")
		(net "M_D_CPU1_SB_DQ<21>")
	)
	(segment
		(start 9.686036 -206.028036)
		(end 10.19048 -206.028036)
		(width 0.20066)
		(layer "F.Cu")
		(net "M_D_CPU1_SB_DQ<21>")
	)
	(segment
		(start 40.256968 -204.542136)
		(end 35.618928 -204.542136)
		(width 0.18288)
		(layer "In6.Cu")
		(net "M_D_CPU1_SB_DQ<21>")
	)
	(segment
		(start 54.995826 -206.125826)
		(end 54.192424 -206.125826)
		(width 0.18288)
		(layer "In6.Cu")
		(net "M_D_CPU1_SB_DQ<21>")
	)
	(segment
		(start 17.384268 -205.221586)
		(end 16.789146 -205.816708)
		(width 0.18288)
		(layer "In6.Cu")
		(net "M_D_CPU1_SB_DQ<21>")
	)
	(segment
		(start 84.290916 -228.36251)
		(end 82.78241 -226.854004)
		(width 0.088646)
		(layer "In6.Cu")
		(net "M_D_CPU1_SB_DQ<21>")
	)
	(segment
		(start 34.735008 -204.741272)
		(end 34.084006 -205.392274)
		(width 0.18288)
		(layer "In6.Cu")
		(net "M_D_CPU1_SB_DQ<21>")
	)
	(segment
		(start 65.877948 -210.193382)
		(end 65.877948 -209.782918)
		(width 0.18288)
		(layer "In6.Cu")
		(net "M_D_CPU1_SB_DQ<21>")
	)
	(segment
		(start 60.171584 -207.210152)
		(end 59.293252 -207.210152)
		(width 0.18288)
		(layer "In6.Cu")
		(net "M_D_CPU1_SB_DQ<21>")
	)
	(segment
		(start 35.618928 -204.542136)
		(end 35.419792 -204.741272)
		(width 0.18288)
		(layer "In6.Cu")
		(net "M_D_CPU1_SB_DQ<21>")
	)
	(segment
		(start 76.464922 -221.759526)
		(end 68.267326 -213.56193)
		(width 0.18288)
		(layer "In6.Cu")
		(net "M_D_CPU1_SB_DQ<21>")
	)
	(segment
		(start 19.70532 -205.392274)
		(end 19.534632 -205.221586)
		(width 0.18288)
		(layer "In6.Cu")
		(net "M_D_CPU1_SB_DQ<21>")
	)
	(segment
		(start 18.07591 -205.038706)
		(end 17.89303 -205.221586)
		(width 0.18288)
		(layer "In6.Cu")
		(net "M_D_CPU1_SB_DQ<21>")
	)
	(segment
		(start 41.107106 -205.392274)
		(end 40.256968 -204.542136)
		(width 0.18288)
		(layer "In6.Cu")
		(net "M_D_CPU1_SB_DQ<21>")
	)
	(segment
		(start 46.264322 -205.744572)
		(end 44.12361 -205.744572)
		(width 0.18288)
		(layer "In6.Cu")
		(net "M_D_CPU1_SB_DQ<21>")
	)
	(segment
		(start 89.367614 -229.762304)
		(end 89.352882 -229.77094)
		(width 0.088646)
		(layer "In6.Cu")
		(net "M_D_CPU1_SB_DQ<21>")
	)
	(segment
		(start 76.464922 -224.403412)
		(end 76.464922 -221.759526)
		(width 0.18288)
		(layer "In6.Cu")
		(net "M_D_CPU1_SB_DQ<21>")
	)
	(segment
		(start 82.78241 -226.854004)
		(end 82.479642 -226.854004)
		(width 0.088646)
		(layer "In6.Cu")
		(net "M_D_CPU1_SB_DQ<21>")
	)
	(segment
		(start 90.869262 -230.096568)
		(end 90.869262 -230.078026)
		(width 0.088646)
		(layer "In6.Cu")
		(net "M_D_CPU1_SB_DQ<21>")
	)
	(segment
		(start 65.877948 -209.782918)
		(end 64.274192 -208.179162)
		(width 0.18288)
		(layer "In6.Cu")
		(net "M_D_CPU1_SB_DQ<21>")
	)
	(segment
		(start 54.192424 -206.125826)
		(end 52.608226 -204.541628)
		(width 0.18288)
		(layer "In6.Cu")
		(net "M_D_CPU1_SB_DQ<21>")
	)
	(segment
		(start 52.608226 -204.541628)
		(end 50.400966 -204.541628)
		(width 0.18288)
		(layer "In6.Cu")
		(net "M_D_CPU1_SB_DQ<21>")
	)
	(segment
		(start 68.267326 -213.56193)
		(end 67.3608 -211.373212)
		(width 0.18288)
		(layer "In6.Cu")
		(net "M_D_CPU1_SB_DQ<21>")
	)
	(segment
		(start 43.771312 -205.392274)
		(end 41.107106 -205.392274)
		(width 0.18288)
		(layer "In6.Cu")
		(net "M_D_CPU1_SB_DQ<21>")
	)
	(segment
		(start 85.513164 -228.948742)
		(end 85.513418 -228.948488)
		(width 0.088646)
		(layer "In6.Cu")
		(net "M_D_CPU1_SB_DQ<21>")
	)
	(segment
		(start 84.290916 -228.45903)
		(end 84.290916 -228.36251)
		(width 0.088646)
		(layer "In6.Cu")
		(net "M_D_CPU1_SB_DQ<21>")
	)
	(segment
		(start 85.139022 -228.948488)
		(end 85.128608 -228.954584)
		(width 0.088646)
		(layer "In6.Cu")
		(net "M_D_CPU1_SB_DQ<21>")
	)
	(segment
		(start 35.419792 -204.741272)
		(end 34.735008 -204.741272)
		(width 0.18288)
		(layer "In6.Cu")
		(net "M_D_CPU1_SB_DQ<21>")
	)
	(segment
		(start 82.479642 -226.854004)
		(end 78.915514 -226.854004)
		(width 0.18288)
		(layer "In6.Cu")
		(net "M_D_CPU1_SB_DQ<21>")
	)
	(segment
		(start 78.915514 -226.854004)
		(end 76.464922 -224.403412)
		(width 0.18288)
		(layer "In6.Cu")
		(net "M_D_CPU1_SB_DQ<21>")
	)
	(segment
		(start 63.05296 -207.878426)
		(end 60.839858 -207.878426)
		(width 0.18288)
		(layer "In6.Cu")
		(net "M_D_CPU1_SB_DQ<21>")
	)
	(segment
		(start 93.986096 -230.584756)
		(end 93.971364 -230.57612)
		(width 0.088646)
		(layer "In6.Cu")
		(net "M_D_CPU1_SB_DQ<21>")
	)
	(segment
		(start 59.293252 -207.210152)
		(end 58.996326 -206.913226)
		(width 0.18288)
		(layer "In6.Cu")
		(net "M_D_CPU1_SB_DQ<21>")
	)
	(segment
		(start 50.400966 -204.541628)
		(end 49.55032 -205.392274)
		(width 0.18288)
		(layer "In6.Cu")
		(net "M_D_CPU1_SB_DQ<21>")
	)
	(segment
		(start 18.94967 -205.221586)
		(end 18.76679 -205.038706)
		(width 0.18288)
		(layer "In6.Cu")
		(net "M_D_CPU1_SB_DQ<21>")
	)
	(segment
		(start 67.3608 -211.373212)
		(end 66.539618 -210.55203)
		(width 0.18288)
		(layer "In6.Cu")
		(net "M_D_CPU1_SB_DQ<21>")
	)
	(segment
		(start 18.76679 -204.765148)
		(end 18.58391 -204.582268)
		(width 0.18288)
		(layer "In6.Cu")
		(net "M_D_CPU1_SB_DQ<21>")
	)
	(segment
		(start 19.534632 -205.221586)
		(end 18.94967 -205.221586)
		(width 0.18288)
		(layer "In6.Cu")
		(net "M_D_CPU1_SB_DQ<21>")
	)
	(segment
		(start 86.640162 -229.2731)
		(end 86.640162 -229.264464)
		(width 0.088646)
		(layer "In6.Cu")
		(net "M_D_CPU1_SB_DQ<21>")
	)
	(segment
		(start 18.25879 -204.582268)
		(end 18.07591 -204.765148)
		(width 0.18288)
		(layer "In6.Cu")
		(net "M_D_CPU1_SB_DQ<21>")
	)
	(segment
		(start 18.07591 -204.765148)
		(end 18.07591 -205.038706)
		(width 0.18288)
		(layer "In6.Cu")
		(net "M_D_CPU1_SB_DQ<21>")
	)
	(segment
		(start 93.046296 -230.584756)
		(end 93.031564 -230.57612)
		(width 0.088646)
		(layer "In6.Cu")
		(net "M_D_CPU1_SB_DQ<21>")
	)
	(segment
		(start 17.89303 -205.221586)
		(end 17.384268 -205.221586)
		(width 0.18288)
		(layer "In6.Cu")
		(net "M_D_CPU1_SB_DQ<21>")
	)
	(segment
		(start 63.353696 -208.179162)
		(end 63.05296 -207.878426)
		(width 0.18288)
		(layer "In6.Cu")
		(net "M_D_CPU1_SB_DQ<21>")
	)
	(segment
		(start 44.12361 -205.744572)
		(end 43.771312 -205.392274)
		(width 0.18288)
		(layer "In6.Cu")
		(net "M_D_CPU1_SB_DQ<21>")
	)
	(segment
		(start 66.236596 -210.55203)
		(end 65.877948 -210.193382)
		(width 0.18288)
		(layer "In6.Cu")
		(net "M_D_CPU1_SB_DQ<21>")
	)
	(segment
		(start 88.427814 -229.762304)
		(end 88.410542 -229.77221)
		(width 0.088646)
		(layer "In6.Cu")
		(net "M_D_CPU1_SB_DQ<21>")
	)
	(segment
		(start 94.925896 -230.584756)
		(end 94.911164 -230.57612)
		(width 0.088646)
		(layer "In6.Cu")
		(net "M_D_CPU1_SB_DQ<21>")
	)
	(segment
		(start 18.58391 -204.582268)
		(end 18.25879 -204.582268)
		(width 0.18288)
		(layer "In6.Cu")
		(net "M_D_CPU1_SB_DQ<21>")
	)
	(segment
		(start 60.839858 -207.878426)
		(end 60.171584 -207.210152)
		(width 0.18288)
		(layer "In6.Cu")
		(net "M_D_CPU1_SB_DQ<21>")
	)
	(segment
		(start 49.55032 -205.392274)
		(end 46.61662 -205.392274)
		(width 0.18288)
		(layer "In6.Cu")
		(net "M_D_CPU1_SB_DQ<21>")
	)
	(segment
		(start 92.106496 -230.584756)
		(end 92.091764 -230.57612)
		(width 0.088646)
		(layer "In6.Cu")
		(net "M_D_CPU1_SB_DQ<21>")
	)
	(segment
		(start 64.274192 -208.179162)
		(end 63.353696 -208.179162)
		(width 0.18288)
		(layer "In6.Cu")
		(net "M_D_CPU1_SB_DQ<21>")
	)
	(segment
		(start 18.76679 -205.038706)
		(end 18.76679 -204.765148)
		(width 0.18288)
		(layer "In6.Cu")
		(net "M_D_CPU1_SB_DQ<21>")
	)
	(segment
		(start 66.539618 -210.55203)
		(end 66.236596 -210.55203)
		(width 0.18288)
		(layer "In6.Cu")
		(net "M_D_CPU1_SB_DQ<21>")
	)
	(segment
		(start 90.307668 -229.762304)
		(end 90.297254 -229.7684)
		(width 0.088646)
		(layer "In6.Cu")
		(net "M_D_CPU1_SB_DQ<21>")
	)
	(segment
		(start 34.084006 -205.392274)
		(end 19.70532 -205.392274)
		(width 0.18288)
		(layer "In6.Cu")
		(net "M_D_CPU1_SB_DQ<21>")
	)
	(segment
		(start 58.996326 -206.913226)
		(end 55.783226 -206.913226)
		(width 0.18288)
		(layer "In6.Cu")
		(net "M_D_CPU1_SB_DQ<21>")
	)
	(segment
		(start 86.939882 -229.772464)
		(end 86.92261 -229.762304)
		(width 0.088646)
		(layer "In6.Cu")
		(net "M_D_CPU1_SB_DQ<21>")
	)
	(segment
		(start 86.640416 -229.283006)
		(end 86.640162 -229.2731)
		(width 0.088646)
		(layer "In6.Cu")
		(net "M_D_CPU1_SB_DQ<21>")
	)
	(segment
		(start 55.783226 -206.913226)
		(end 54.995826 -206.125826)
		(width 0.18288)
		(layer "In6.Cu")
		(net "M_D_CPU1_SB_DQ<21>")
	)
	(segment
		(start 46.61662 -205.392274)
		(end 46.264322 -205.744572)
		(width 0.18288)
		(layer "In6.Cu")
		(net "M_D_CPU1_SB_DQ<21>")
	)
	(arc
		(start 92.091764 -230.57612)
		(mid 91.904566 -230.525977)
		(end 91.717368 -230.57612)
		(width 0.088646)
		(layer "In6.Cu")
		(net "M_D_CPU1_SB_DQ<21>")
	)
	(arc
		(start 92.657168 -230.57612)
		(mid 92.382969 -230.651955)
		(end 92.106496 -230.584756)
		(width 0.088646)
		(layer "In6.Cu")
		(net "M_D_CPU1_SB_DQ<21>")
	)
	(arc
		(start 89.74201 -229.762304)
		(mid 89.554812 -229.712161)
		(end 89.367614 -229.762304)
		(width 0.088646)
		(layer "In6.Cu")
		(net "M_D_CPU1_SB_DQ<21>")
	)
	(arc
		(start 89.352882 -229.77094)
		(mid 89.076407 -229.83826)
		(end 88.80221 -229.762304)
		(width 0.088646)
		(layer "In6.Cu")
		(net "M_D_CPU1_SB_DQ<21>")
	)
	(arc
		(start 86.640162 -229.264464)
		(mid 86.449288 -228.946655)
		(end 86.078568 -228.948742)
		(width 0.088646)
		(layer "In6.Cu")
		(net "M_D_CPU1_SB_DQ<21>")
	)
	(arc
		(start 94.911164 -230.57612)
		(mid 94.723966 -230.525977)
		(end 94.536768 -230.57612)
		(width 0.088646)
		(layer "In6.Cu")
		(net "M_D_CPU1_SB_DQ<21>")
	)
	(arc
		(start 87.862664 -229.762558)
		(mid 87.675466 -229.712415)
		(end 87.488268 -229.762558)
		(width 0.088646)
		(layer "In6.Cu")
		(net "M_D_CPU1_SB_DQ<21>")
	)
	(arc
		(start 86.92261 -229.762304)
		(mid 86.718521 -229.559757)
		(end 86.640416 -229.283006)
		(width 0.088646)
		(layer "In6.Cu")
		(net "M_D_CPU1_SB_DQ<21>")
	)
	(arc
		(start 88.80221 -229.762304)
		(mid 88.615012 -229.712161)
		(end 88.427814 -229.762304)
		(width 0.088646)
		(layer "In6.Cu")
		(net "M_D_CPU1_SB_DQ<21>")
	)
	(arc
		(start 90.869262 -230.078026)
		(mid 90.678388 -229.760217)
		(end 90.307668 -229.762304)
		(width 0.088646)
		(layer "In6.Cu")
		(net "M_D_CPU1_SB_DQ<21>")
	)
	(arc
		(start 93.031564 -230.57612)
		(mid 92.844366 -230.525977)
		(end 92.657168 -230.57612)
		(width 0.088646)
		(layer "In6.Cu")
		(net "M_D_CPU1_SB_DQ<21>")
	)
	(arc
		(start 93.596968 -230.57612)
		(mid 93.322769 -230.651955)
		(end 93.046296 -230.584756)
		(width 0.088646)
		(layer "In6.Cu")
		(net "M_D_CPU1_SB_DQ<21>")
	)
	(arc
		(start 88.410542 -229.77221)
		(mid 88.135362 -229.838162)
		(end 87.862664 -229.762558)
		(width 0.088646)
		(layer "In6.Cu")
		(net "M_D_CPU1_SB_DQ<21>")
	)
	(arc
		(start 86.078568 -228.948742)
		(mid 85.795866 -229.024518)
		(end 85.513164 -228.948742)
		(width 0.088646)
		(layer "In6.Cu")
		(net "M_D_CPU1_SB_DQ<21>")
	)
	(arc
		(start 93.971364 -230.57612)
		(mid 93.784166 -230.525977)
		(end 93.596968 -230.57612)
		(width 0.088646)
		(layer "In6.Cu")
		(net "M_D_CPU1_SB_DQ<21>")
	)
	(arc
		(start 94.536768 -230.57612)
		(mid 94.262569 -230.651955)
		(end 93.986096 -230.584756)
		(width 0.088646)
		(layer "In6.Cu")
		(net "M_D_CPU1_SB_DQ<21>")
	)
	(arc
		(start 85.513418 -228.948488)
		(mid 85.32622 -228.898345)
		(end 85.139022 -228.948488)
		(width 0.088646)
		(layer "In6.Cu")
		(net "M_D_CPU1_SB_DQ<21>")
	)
	(arc
		(start 95.663766 -230.900478)
		(mid 95.340122 -230.749615)
		(end 95.007176 -230.62057)
		(width 0.088646)
		(layer "In6.Cu")
		(net "M_D_CPU1_SB_DQ<21>")
	)
	(arc
		(start 85.128608 -228.954584)
		(mid 84.568436 -228.94569)
		(end 84.290916 -228.45903)
		(width 0.088646)
		(layer "In6.Cu")
		(net "M_D_CPU1_SB_DQ<21>")
	)
	(arc
		(start 87.488268 -229.762558)
		(mid 87.215346 -229.838461)
		(end 86.939882 -229.772464)
		(width 0.088646)
		(layer "In6.Cu")
		(net "M_D_CPU1_SB_DQ<21>")
	)
	(arc
		(start 91.717368 -230.57612)
		(mid 91.156171 -230.578816)
		(end 90.869262 -230.096568)
		(width 0.088646)
		(layer "In6.Cu")
		(net "M_D_CPU1_SB_DQ<21>")
	)
	(arc
		(start 95.007176 -230.62057)
		(mid 94.965834 -230.604257)
		(end 94.925896 -230.584756)
		(width 0.088646)
		(layer "In6.Cu")
		(net "M_D_CPU1_SB_DQ<21>")
	)
	(arc
		(start 90.297254 -229.7684)
		(mid 90.018822 -229.838246)
		(end 89.74201 -229.762304)
		(width 0.088646)
		(layer "In6.Cu")
		(net "M_D_CPU1_SB_DQ<21>")
	)
	(segment
		(start 13.441426 -207.091788)
		(end 13.890244 -207.091788)
		(width 0.20066)
		(layer "F.Cu")
		(net "M_D_CPU1_SB_DQ<20>")
	)
	(segment
		(start 16.789146 -207.51673)
		(end 15.684246 -207.51673)
		(width 0.20066)
		(layer "F.Cu")
		(net "M_D_CPU1_SB_DQ<20>")
	)
	(segment
		(start 9.474708 -207.51673)
		(end 9.713468 -207.75549)
		(width 0.20066)
		(layer "F.Cu")
		(net "M_D_CPU1_SB_DQ<20>")
	)
	(segment
		(start 10.554462 -207.08366)
		(end 11.11631 -207.08366)
		(width 0.20066)
		(layer "F.Cu")
		(net "M_D_CPU1_SB_DQ<20>")
	)
	(segment
		(start 11.11631 -207.08366)
		(end 11.124438 -207.091788)
		(width 0.101854)
		(layer "F.Cu")
		(net "M_D_CPU1_SB_DQ<20>")
	)
	(segment
		(start 11.372342 -207.091788)
		(end 13.441426 -207.091788)
		(width 0.1016)
		(layer "F.Cu")
		(net "M_D_CPU1_SB_DQ<20>")
	)
	(segment
		(start 11.124438 -207.091788)
		(end 11.372342 -207.091788)
		(width 0.101854)
		(layer "F.Cu")
		(net "M_D_CPU1_SB_DQ<20>")
	)
	(segment
		(start 8.140446 -207.51673)
		(end 9.474708 -207.51673)
		(width 0.20066)
		(layer "F.Cu")
		(net "M_D_CPU1_SB_DQ<20>")
	)
	(segment
		(start 10.344912 -207.29321)
		(end 10.554462 -207.08366)
		(width 0.20066)
		(layer "F.Cu")
		(net "M_D_CPU1_SB_DQ<20>")
	)
	(segment
		(start 10.172192 -207.75549)
		(end 10.344912 -207.58277)
		(width 0.20066)
		(layer "F.Cu")
		(net "M_D_CPU1_SB_DQ<20>")
	)
	(segment
		(start 14.315186 -207.51673)
		(end 15.684246 -207.51673)
		(width 0.20066)
		(layer "F.Cu")
		(net "M_D_CPU1_SB_DQ<20>")
	)
	(segment
		(start 9.713468 -207.75549)
		(end 10.172192 -207.75549)
		(width 0.20066)
		(layer "F.Cu")
		(net "M_D_CPU1_SB_DQ<20>")
	)
	(segment
		(start 10.344912 -207.58277)
		(end 10.344912 -207.29321)
		(width 0.20066)
		(layer "F.Cu")
		(net "M_D_CPU1_SB_DQ<20>")
	)
	(segment
		(start 95.193612 -232.250234)
		(end 95.193612 -231.714548)
		(width 0.20066)
		(layer "F.Cu")
		(net "M_D_CPU1_SB_DQ<20>")
	)
	(segment
		(start 13.890244 -207.091788)
		(end 14.315186 -207.51673)
		(width 0.20066)
		(layer "F.Cu")
		(net "M_D_CPU1_SB_DQ<20>")
	)
	(segment
		(start 95.193866 -232.250488)
		(end 95.193612 -232.250234)
		(width 0.20066)
		(layer "F.Cu")
		(net "M_D_CPU1_SB_DQ<20>")
	)
	(segment
		(start 42.743374 -206.854552)
		(end 42.512488 -207.085438)
		(width 0.18288)
		(layer "In6.Cu")
		(net "M_D_CPU1_SB_DQ<20>")
	)
	(segment
		(start 17.823688 -206.903574)
		(end 17.402302 -206.903574)
		(width 0.18288)
		(layer "In6.Cu")
		(net "M_D_CPU1_SB_DQ<20>")
	)
	(segment
		(start 92.187014 -231.39019)
		(end 92.172282 -231.398826)
		(width 0.088646)
		(layer "In6.Cu")
		(net "M_D_CPU1_SB_DQ<20>")
	)
	(segment
		(start 18.697448 -206.720694)
		(end 18.697448 -206.458312)
		(width 0.18288)
		(layer "In6.Cu")
		(net "M_D_CPU1_SB_DQ<20>")
	)
	(segment
		(start 75.428856 -222.194882)
		(end 67.025266 -213.791292)
		(width 0.18288)
		(layer "In6.Cu")
		(net "M_D_CPU1_SB_DQ<20>")
	)
	(segment
		(start 20.151598 -207.093312)
		(end 19.96186 -206.903574)
		(width 0.18288)
		(layer "In6.Cu")
		(net "M_D_CPU1_SB_DQ<20>")
	)
	(segment
		(start 22.87143 -207.253332)
		(end 22.71141 -207.093312)
		(width 0.18288)
		(layer "In6.Cu")
		(net "M_D_CPU1_SB_DQ<20>")
	)
	(segment
		(start 82.955384 -227.849684)
		(end 82.479642 -227.849684)
		(width 0.088646)
		(layer "In6.Cu")
		(net "M_D_CPU1_SB_DQ<20>")
	)
	(segment
		(start 66.657728 -212.90407)
		(end 65.558924 -211.805266)
		(width 0.18288)
		(layer "In6.Cu")
		(net "M_D_CPU1_SB_DQ<20>")
	)
	(segment
		(start 78.407514 -227.849684)
		(end 75.428856 -224.871026)
		(width 0.18288)
		(layer "In6.Cu")
		(net "M_D_CPU1_SB_DQ<20>")
	)
	(segment
		(start 49.494186 -207.092296)
		(end 43.987212 -207.092296)
		(width 0.18288)
		(layer "In6.Cu")
		(net "M_D_CPU1_SB_DQ<20>")
	)
	(segment
		(start 86.170262 -230.086916)
		(end 86.170262 -230.07828)
		(width 0.088646)
		(layer "In6.Cu")
		(net "M_D_CPU1_SB_DQ<20>")
	)
	(segment
		(start 18.006568 -206.458312)
		(end 18.006568 -206.720694)
		(width 0.18288)
		(layer "In6.Cu")
		(net "M_D_CPU1_SB_DQ<20>")
	)
	(segment
		(start 88.347296 -230.584756)
		(end 88.332564 -230.57612)
		(width 0.088646)
		(layer "In6.Cu")
		(net "M_D_CPU1_SB_DQ<20>")
	)
	(segment
		(start 18.514568 -206.275432)
		(end 18.189448 -206.275432)
		(width 0.18288)
		(layer "In6.Cu")
		(net "M_D_CPU1_SB_DQ<20>")
	)
	(segment
		(start 83.808062 -228.702362)
		(end 82.955384 -227.849684)
		(width 0.088646)
		(layer "In6.Cu")
		(net "M_D_CPU1_SB_DQ<20>")
	)
	(segment
		(start 42.512488 -207.085438)
		(end 42.075354 -207.085438)
		(width 0.18288)
		(layer "In6.Cu")
		(net "M_D_CPU1_SB_DQ<20>")
	)
	(segment
		(start 43.749468 -206.854552)
		(end 42.743374 -206.854552)
		(width 0.18288)
		(layer "In6.Cu")
		(net "M_D_CPU1_SB_DQ<20>")
	)
	(segment
		(start 17.402302 -206.903574)
		(end 16.789146 -207.51673)
		(width 0.18288)
		(layer "In6.Cu")
		(net "M_D_CPU1_SB_DQ<20>")
	)
	(segment
		(start 64.047116 -209.504026)
		(end 60.12688 -209.504026)
		(width 0.18288)
		(layer "In6.Cu")
		(net "M_D_CPU1_SB_DQ<20>")
	)
	(segment
		(start 22.87143 -207.586072)
		(end 22.87143 -207.253332)
		(width 0.18288)
		(layer "In6.Cu")
		(net "M_D_CPU1_SB_DQ<20>")
	)
	(segment
		(start 31.7881 -207.093312)
		(end 23.72487 -207.093312)
		(width 0.18288)
		(layer "In6.Cu")
		(net "M_D_CPU1_SB_DQ<20>")
	)
	(segment
		(start 84.138008 -229.848918)
		(end 83.808062 -229.518972)
		(width 0.088646)
		(layer "In6.Cu")
		(net "M_D_CPU1_SB_DQ<20>")
	)
	(segment
		(start 19.96186 -206.903574)
		(end 18.880328 -206.903574)
		(width 0.18288)
		(layer "In6.Cu")
		(net "M_D_CPU1_SB_DQ<20>")
	)
	(segment
		(start 94.066868 -231.39019)
		(end 94.056454 -231.396286)
		(width 0.088646)
		(layer "In6.Cu")
		(net "M_D_CPU1_SB_DQ<20>")
	)
	(segment
		(start 35.409886 -206.240888)
		(end 34.845752 -206.805022)
		(width 0.18288)
		(layer "In6.Cu")
		(net "M_D_CPU1_SB_DQ<20>")
	)
	(segment
		(start 87.96909 -230.570024)
		(end 87.958168 -230.576374)
		(width 0.088646)
		(layer "In6.Cu")
		(net "M_D_CPU1_SB_DQ<20>")
	)
	(segment
		(start 18.880328 -206.903574)
		(end 18.697448 -206.720694)
		(width 0.18288)
		(layer "In6.Cu")
		(net "M_D_CPU1_SB_DQ<20>")
	)
	(segment
		(start 18.006568 -206.720694)
		(end 17.823688 -206.903574)
		(width 0.18288)
		(layer "In6.Cu")
		(net "M_D_CPU1_SB_DQ<20>")
	)
	(segment
		(start 18.697448 -206.458312)
		(end 18.514568 -206.275432)
		(width 0.18288)
		(layer "In6.Cu")
		(net "M_D_CPU1_SB_DQ<20>")
	)
	(segment
		(start 82.479642 -227.849684)
		(end 78.407514 -227.849684)
		(width 0.18288)
		(layer "In6.Cu")
		(net "M_D_CPU1_SB_DQ<20>")
	)
	(segment
		(start 54.112668 -207.827626)
		(end 52.526692 -206.24165)
		(width 0.18288)
		(layer "In6.Cu")
		(net "M_D_CPU1_SB_DQ<20>")
	)
	(segment
		(start 34.845752 -206.805022)
		(end 33.673034 -206.805022)
		(width 0.18288)
		(layer "In6.Cu")
		(net "M_D_CPU1_SB_DQ<20>")
	)
	(segment
		(start 86.170516 -230.10114)
		(end 86.170262 -230.086916)
		(width 0.088646)
		(layer "In6.Cu")
		(net "M_D_CPU1_SB_DQ<20>")
	)
	(segment
		(start 23.03145 -207.746092)
		(end 22.87143 -207.586072)
		(width 0.18288)
		(layer "In6.Cu")
		(net "M_D_CPU1_SB_DQ<20>")
	)
	(segment
		(start 23.40483 -207.746092)
		(end 23.03145 -207.746092)
		(width 0.18288)
		(layer "In6.Cu")
		(net "M_D_CPU1_SB_DQ<20>")
	)
	(segment
		(start 22.71141 -207.093312)
		(end 20.151598 -207.093312)
		(width 0.18288)
		(layer "In6.Cu")
		(net "M_D_CPU1_SB_DQ<20>")
	)
	(segment
		(start 84.352638 -229.848918)
		(end 84.138008 -229.848918)
		(width 0.088646)
		(layer "In6.Cu")
		(net "M_D_CPU1_SB_DQ<20>")
	)
	(segment
		(start 31.789116 -207.092296)
		(end 31.7881 -207.093312)
		(width 0.18288)
		(layer "In6.Cu")
		(net "M_D_CPU1_SB_DQ<20>")
	)
	(segment
		(start 83.808062 -229.518972)
		(end 83.808062 -228.702362)
		(width 0.088646)
		(layer "In6.Cu")
		(net "M_D_CPU1_SB_DQ<20>")
	)
	(segment
		(start 41.844468 -206.854552)
		(end 40.545512 -206.854552)
		(width 0.18288)
		(layer "In6.Cu")
		(net "M_D_CPU1_SB_DQ<20>")
	)
	(segment
		(start 40.545512 -206.854552)
		(end 39.931848 -206.240888)
		(width 0.18288)
		(layer "In6.Cu")
		(net "M_D_CPU1_SB_DQ<20>")
	)
	(segment
		(start 60.12688 -209.504026)
		(end 59.383168 -208.760314)
		(width 0.18288)
		(layer "In6.Cu")
		(net "M_D_CPU1_SB_DQ<20>")
	)
	(segment
		(start 65.332356 -211.258404)
		(end 64.387222 -209.844132)
		(width 0.18288)
		(layer "In6.Cu")
		(net "M_D_CPU1_SB_DQ<20>")
	)
	(segment
		(start 52.526692 -206.24165)
		(end 50.344832 -206.24165)
		(width 0.18288)
		(layer "In6.Cu")
		(net "M_D_CPU1_SB_DQ<20>")
	)
	(segment
		(start 23.56485 -207.586072)
		(end 23.40483 -207.746092)
		(width 0.18288)
		(layer "In6.Cu")
		(net "M_D_CPU1_SB_DQ<20>")
	)
	(segment
		(start 33.673034 -206.805022)
		(end 33.38576 -207.092296)
		(width 0.18288)
		(layer "In6.Cu")
		(net "M_D_CPU1_SB_DQ<20>")
	)
	(segment
		(start 65.558924 -211.805266)
		(end 65.332356 -211.258404)
		(width 0.18288)
		(layer "In6.Cu")
		(net "M_D_CPU1_SB_DQ<20>")
	)
	(segment
		(start 23.56485 -207.253332)
		(end 23.56485 -207.586072)
		(width 0.18288)
		(layer "In6.Cu")
		(net "M_D_CPU1_SB_DQ<20>")
	)
	(segment
		(start 18.189448 -206.275432)
		(end 18.006568 -206.458312)
		(width 0.18288)
		(layer "In6.Cu")
		(net "M_D_CPU1_SB_DQ<20>")
	)
	(segment
		(start 93.126814 -231.39019)
		(end 93.112082 -231.398826)
		(width 0.088646)
		(layer "In6.Cu")
		(net "M_D_CPU1_SB_DQ<20>")
	)
	(segment
		(start 55.82666 -208.760314)
		(end 54.893972 -207.827626)
		(width 0.18288)
		(layer "In6.Cu")
		(net "M_D_CPU1_SB_DQ<20>")
	)
	(segment
		(start 39.931848 -206.240888)
		(end 35.409886 -206.240888)
		(width 0.18288)
		(layer "In6.Cu")
		(net "M_D_CPU1_SB_DQ<20>")
	)
	(segment
		(start 75.428856 -224.871026)
		(end 75.428856 -222.194882)
		(width 0.18288)
		(layer "In6.Cu")
		(net "M_D_CPU1_SB_DQ<20>")
	)
	(segment
		(start 67.025266 -213.791292)
		(end 66.657728 -212.90407)
		(width 0.18288)
		(layer "In6.Cu")
		(net "M_D_CPU1_SB_DQ<20>")
	)
	(segment
		(start 23.72487 -207.093312)
		(end 23.56485 -207.253332)
		(width 0.18288)
		(layer "In6.Cu")
		(net "M_D_CPU1_SB_DQ<20>")
	)
	(segment
		(start 90.399362 -230.91902)
		(end 90.399362 -230.891842)
		(width 0.088646)
		(layer "In6.Cu")
		(net "M_D_CPU1_SB_DQ<20>")
	)
	(segment
		(start 84.354924 -229.846632)
		(end 84.352638 -229.848918)
		(width 0.088646)
		(layer "In6.Cu")
		(net "M_D_CPU1_SB_DQ<20>")
	)
	(segment
		(start 89.287096 -230.584756)
		(end 89.272364 -230.57612)
		(width 0.088646)
		(layer "In6.Cu")
		(net "M_D_CPU1_SB_DQ<20>")
	)
	(segment
		(start 86.467696 -230.58501)
		(end 86.452964 -230.576374)
		(width 0.088646)
		(layer "In6.Cu")
		(net "M_D_CPU1_SB_DQ<20>")
	)
	(segment
		(start 94.838012 -231.619298)
		(end 94.441264 -231.39019)
		(width 0.088646)
		(layer "In6.Cu")
		(net "M_D_CPU1_SB_DQ<20>")
	)
	(segment
		(start 64.387222 -209.844132)
		(end 64.047116 -209.504026)
		(width 0.18288)
		(layer "In6.Cu")
		(net "M_D_CPU1_SB_DQ<20>")
	)
	(segment
		(start 54.893972 -207.827626)
		(end 54.112668 -207.827626)
		(width 0.18288)
		(layer "In6.Cu")
		(net "M_D_CPU1_SB_DQ<20>")
	)
	(segment
		(start 43.987212 -207.092296)
		(end 43.749468 -206.854552)
		(width 0.18288)
		(layer "In6.Cu")
		(net "M_D_CPU1_SB_DQ<20>")
	)
	(segment
		(start 59.383168 -208.760314)
		(end 55.82666 -208.760314)
		(width 0.18288)
		(layer "In6.Cu")
		(net "M_D_CPU1_SB_DQ<20>")
	)
	(segment
		(start 42.075354 -207.085438)
		(end 41.844468 -206.854552)
		(width 0.18288)
		(layer "In6.Cu")
		(net "M_D_CPU1_SB_DQ<20>")
	)
	(segment
		(start 33.38576 -207.092296)
		(end 31.789116 -207.092296)
		(width 0.18288)
		(layer "In6.Cu")
		(net "M_D_CPU1_SB_DQ<20>")
	)
	(segment
		(start 50.344832 -206.24165)
		(end 49.494186 -207.092296)
		(width 0.18288)
		(layer "In6.Cu")
		(net "M_D_CPU1_SB_DQ<20>")
	)
	(arc
		(start 91.247214 -231.39019)
		(mid 90.964512 -231.465932)
		(end 90.68181 -231.39019)
		(width 0.088646)
		(layer "In6.Cu")
		(net "M_D_CPU1_SB_DQ<20>")
	)
	(arc
		(start 86.170262 -230.07828)
		(mid 86.117992 -229.895915)
		(end 85.983064 -229.762558)
		(width 0.088646)
		(layer "In6.Cu")
		(net "M_D_CPU1_SB_DQ<20>")
	)
	(arc
		(start 90.68181 -231.39019)
		(mid 90.479524 -231.191209)
		(end 90.399362 -230.91902)
		(width 0.088646)
		(layer "In6.Cu")
		(net "M_D_CPU1_SB_DQ<20>")
	)
	(arc
		(start 93.50121 -231.39019)
		(mid 93.314012 -231.340047)
		(end 93.126814 -231.39019)
		(width 0.088646)
		(layer "In6.Cu")
		(net "M_D_CPU1_SB_DQ<20>")
	)
	(arc
		(start 94.056454 -231.396286)
		(mid 93.778022 -231.4661)
		(end 93.50121 -231.39019)
		(width 0.088646)
		(layer "In6.Cu")
		(net "M_D_CPU1_SB_DQ<20>")
	)
	(arc
		(start 94.441264 -231.39019)
		(mid 94.254066 -231.340047)
		(end 94.066868 -231.39019)
		(width 0.088646)
		(layer "In6.Cu")
		(net "M_D_CPU1_SB_DQ<20>")
	)
	(arc
		(start 87.018368 -230.576374)
		(mid 86.744139 -230.652299)
		(end 86.467696 -230.58501)
		(width 0.088646)
		(layer "In6.Cu")
		(net "M_D_CPU1_SB_DQ<20>")
	)
	(arc
		(start 91.62161 -231.39019)
		(mid 91.434412 -231.340047)
		(end 91.247214 -231.39019)
		(width 0.088646)
		(layer "In6.Cu")
		(net "M_D_CPU1_SB_DQ<20>")
	)
	(arc
		(start 92.172282 -231.398826)
		(mid 91.895841 -231.465992)
		(end 91.62161 -231.39019)
		(width 0.088646)
		(layer "In6.Cu")
		(net "M_D_CPU1_SB_DQ<20>")
	)
	(arc
		(start 89.837768 -230.57612)
		(mid 89.563569 -230.651955)
		(end 89.287096 -230.584756)
		(width 0.088646)
		(layer "In6.Cu")
		(net "M_D_CPU1_SB_DQ<20>")
	)
	(arc
		(start 93.112082 -231.398826)
		(mid 92.835641 -231.465992)
		(end 92.56141 -231.39019)
		(width 0.088646)
		(layer "In6.Cu")
		(net "M_D_CPU1_SB_DQ<20>")
	)
	(arc
		(start 90.399362 -230.891842)
		(mid 90.347092 -230.709477)
		(end 90.212164 -230.57612)
		(width 0.088646)
		(layer "In6.Cu")
		(net "M_D_CPU1_SB_DQ<20>")
	)
	(arc
		(start 92.56141 -231.39019)
		(mid 92.374212 -231.340047)
		(end 92.187014 -231.39019)
		(width 0.088646)
		(layer "In6.Cu")
		(net "M_D_CPU1_SB_DQ<20>")
	)
	(arc
		(start 85.043264 -229.762558)
		(mid 84.856066 -229.712415)
		(end 84.668868 -229.762558)
		(width 0.088646)
		(layer "In6.Cu")
		(net "M_D_CPU1_SB_DQ<20>")
	)
	(arc
		(start 95.193612 -231.714548)
		(mid 95.00956 -231.690279)
		(end 94.838012 -231.619298)
		(width 0.088646)
		(layer "In6.Cu")
		(net "M_D_CPU1_SB_DQ<20>")
	)
	(arc
		(start 88.332564 -230.57612)
		(mid 88.15162 -230.526029)
		(end 87.96909 -230.570024)
		(width 0.088646)
		(layer "In6.Cu")
		(net "M_D_CPU1_SB_DQ<20>")
	)
	(arc
		(start 89.272364 -230.57612)
		(mid 89.085166 -230.525977)
		(end 88.897968 -230.57612)
		(width 0.088646)
		(layer "In6.Cu")
		(net "M_D_CPU1_SB_DQ<20>")
	)
	(arc
		(start 85.983064 -229.762558)
		(mid 85.795866 -229.712415)
		(end 85.608668 -229.762558)
		(width 0.088646)
		(layer "In6.Cu")
		(net "M_D_CPU1_SB_DQ<20>")
	)
	(arc
		(start 90.212164 -230.57612)
		(mid 90.024966 -230.525977)
		(end 89.837768 -230.57612)
		(width 0.088646)
		(layer "In6.Cu")
		(net "M_D_CPU1_SB_DQ<20>")
	)
	(arc
		(start 85.608668 -229.762558)
		(mid 85.325966 -229.838334)
		(end 85.043264 -229.762558)
		(width 0.088646)
		(layer "In6.Cu")
		(net "M_D_CPU1_SB_DQ<20>")
	)
	(arc
		(start 86.452964 -230.576374)
		(mid 86.249728 -230.375627)
		(end 86.170516 -230.10114)
		(width 0.088646)
		(layer "In6.Cu")
		(net "M_D_CPU1_SB_DQ<20>")
	)
	(arc
		(start 88.897968 -230.57612)
		(mid 88.623769 -230.651955)
		(end 88.347296 -230.584756)
		(width 0.088646)
		(layer "In6.Cu")
		(net "M_D_CPU1_SB_DQ<20>")
	)
	(arc
		(start 84.668868 -229.762558)
		(mid 84.517428 -229.825255)
		(end 84.354924 -229.846632)
		(width 0.088646)
		(layer "In6.Cu")
		(net "M_D_CPU1_SB_DQ<20>")
	)
	(arc
		(start 87.958168 -230.576374)
		(mid 87.675466 -230.65215)
		(end 87.392764 -230.576374)
		(width 0.088646)
		(layer "In6.Cu")
		(net "M_D_CPU1_SB_DQ<20>")
	)
	(arc
		(start 87.392764 -230.576374)
		(mid 87.205566 -230.526231)
		(end 87.018368 -230.576374)
		(width 0.088646)
		(layer "In6.Cu")
		(net "M_D_CPU1_SB_DQ<20>")
	)
	(segment
		(start 16.789146 -230.466646)
		(end 15.684246 -230.466646)
		(width 0.20066)
		(layer "F.Cu")
		(net "M_D_CPU1_SB_DQ<1>")
	)
	(segment
		(start 10.344912 -230.195374)
		(end 10.507472 -230.032814)
		(width 0.20066)
		(layer "F.Cu")
		(net "M_D_CPU1_SB_DQ<1>")
	)
	(segment
		(start 11.1252 -230.041704)
		(end 13.110718 -230.041704)
		(width 0.1016)
		(layer "F.Cu")
		(net "M_D_CPU1_SB_DQ<1>")
	)
	(segment
		(start 9.474708 -230.466646)
		(end 9.686036 -230.677974)
		(width 0.20066)
		(layer "F.Cu")
		(net "M_D_CPU1_SB_DQ<1>")
	)
	(segment
		(start 13.619988 -230.041704)
		(end 14.04493 -230.466646)
		(width 0.20066)
		(layer "F.Cu")
		(net "M_D_CPU1_SB_DQ<1>")
	)
	(segment
		(start 98.482912 -241.203226)
		(end 98.483166 -241.202972)
		(width 0.20066)
		(layer "F.Cu")
		(net "M_D_CPU1_SB_DQ<1>")
	)
	(segment
		(start 10.19048 -230.677974)
		(end 10.344912 -230.523542)
		(width 0.20066)
		(layer "F.Cu")
		(net "M_D_CPU1_SB_DQ<1>")
	)
	(segment
		(start 11.11631 -230.032814)
		(end 11.1252 -230.041704)
		(width 0.1016)
		(layer "F.Cu")
		(net "M_D_CPU1_SB_DQ<1>")
	)
	(segment
		(start 98.483166 -241.202972)
		(end 98.483166 -240.667286)
		(width 0.20066)
		(layer "F.Cu")
		(net "M_D_CPU1_SB_DQ<1>")
	)
	(segment
		(start 10.344912 -230.523542)
		(end 10.344912 -230.195374)
		(width 0.20066)
		(layer "F.Cu")
		(net "M_D_CPU1_SB_DQ<1>")
	)
	(segment
		(start 13.441426 -230.041704)
		(end 13.619988 -230.041704)
		(width 0.20066)
		(layer "F.Cu")
		(net "M_D_CPU1_SB_DQ<1>")
	)
	(segment
		(start 10.507472 -230.032814)
		(end 11.11631 -230.032814)
		(width 0.20066)
		(layer "F.Cu")
		(net "M_D_CPU1_SB_DQ<1>")
	)
	(segment
		(start 13.110718 -230.041704)
		(end 13.441426 -230.041704)
		(width 0.101854)
		(layer "F.Cu")
		(net "M_D_CPU1_SB_DQ<1>")
	)
	(segment
		(start 9.686036 -230.677974)
		(end 10.19048 -230.677974)
		(width 0.20066)
		(layer "F.Cu")
		(net "M_D_CPU1_SB_DQ<1>")
	)
	(segment
		(start 8.140446 -230.466646)
		(end 9.474708 -230.466646)
		(width 0.20066)
		(layer "F.Cu")
		(net "M_D_CPU1_SB_DQ<1>")
	)
	(segment
		(start 14.04493 -230.466646)
		(end 15.684246 -230.466646)
		(width 0.20066)
		(layer "F.Cu")
		(net "M_D_CPU1_SB_DQ<1>")
	)
	(segment
		(start 64.736726 -230.039926)
		(end 61.696854 -230.039926)
		(width 0.18288)
		(layer "In11.Cu")
		(net "M_D_CPU1_SB_DQ<1>")
	)
	(segment
		(start 40.543226 -227.461826)
		(end 39.610284 -226.528884)
		(width 0.18288)
		(layer "In11.Cu")
		(net "M_D_CPU1_SB_DQ<1>")
	)
	(segment
		(start 20.030948 -229.780338)
		(end 19.703796 -229.453186)
		(width 0.18288)
		(layer "In11.Cu")
		(net "M_D_CPU1_SB_DQ<1>")
	)
	(segment
		(start 54.894226 -226.522026)
		(end 51.871626 -226.522026)
		(width 0.18288)
		(layer "In11.Cu")
		(net "M_D_CPU1_SB_DQ<1>")
	)
	(segment
		(start 90.307414 -241.156744)
		(end 90.292682 -241.16538)
		(width 0.088646)
		(layer "In11.Cu")
		(net "M_D_CPU1_SB_DQ<1>")
	)
	(segment
		(start 97.905062 -241.111024)
		(end 97.825814 -241.156744)
		(width 0.088646)
		(layer "In11.Cu")
		(net "M_D_CPU1_SB_DQ<1>")
	)
	(segment
		(start 66.926968 -231.070912)
		(end 66.49466 -230.892096)
		(width 0.18288)
		(layer "In11.Cu")
		(net "M_D_CPU1_SB_DQ<1>")
	)
	(segment
		(start 36.73983 -226.642422)
		(end 35.370008 -226.642422)
		(width 0.18288)
		(layer "In11.Cu")
		(net "M_D_CPU1_SB_DQ<1>")
	)
	(segment
		(start 84.38642 -239.60455)
		(end 84.139786 -239.60455)
		(width 0.088646)
		(layer "In11.Cu")
		(net "M_D_CPU1_SB_DQ<1>")
	)
	(segment
		(start 18.743168 -229.824026)
		(end 17.431766 -229.824026)
		(width 0.18288)
		(layer "In11.Cu")
		(net "M_D_CPU1_SB_DQ<1>")
	)
	(segment
		(start 30.564074 -228.198426)
		(end 29.697426 -228.198426)
		(width 0.18288)
		(layer "In11.Cu")
		(net "M_D_CPU1_SB_DQ<1>")
	)
	(segment
		(start 46.35754 -227.49256)
		(end 45.72635 -228.12375)
		(width 0.18288)
		(layer "In11.Cu")
		(net "M_D_CPU1_SB_DQ<1>")
	)
	(segment
		(start 21.399246 -230.728774)
		(end 21.237194 -230.890826)
		(width 0.18288)
		(layer "In11.Cu")
		(net "M_D_CPU1_SB_DQ<1>")
	)
	(segment
		(start 51.75123 -226.642422)
		(end 50.457608 -226.642422)
		(width 0.18288)
		(layer "In11.Cu")
		(net "M_D_CPU1_SB_DQ<1>")
	)
	(segment
		(start 87.401654 -240.348008)
		(end 87.392764 -240.342928)
		(width 0.088646)
		(layer "In11.Cu")
		(net "M_D_CPU1_SB_DQ<1>")
	)
	(segment
		(start 31.26994 -227.49256)
		(end 30.564074 -228.198426)
		(width 0.18288)
		(layer "In11.Cu")
		(net "M_D_CPU1_SB_DQ<1>")
	)
	(segment
		(start 25.874726 -230.065326)
		(end 25.211278 -230.728774)
		(width 0.18288)
		(layer "In11.Cu")
		(net "M_D_CPU1_SB_DQ<1>")
	)
	(segment
		(start 35.370008 -226.642422)
		(end 34.51987 -227.49256)
		(width 0.18288)
		(layer "In11.Cu")
		(net "M_D_CPU1_SB_DQ<1>")
	)
	(segment
		(start 51.871626 -226.522026)
		(end 51.75123 -226.642422)
		(width 0.18288)
		(layer "In11.Cu")
		(net "M_D_CPU1_SB_DQ<1>")
	)
	(segment
		(start 28.554426 -229.341426)
		(end 27.055826 -229.341426)
		(width 0.18288)
		(layer "In11.Cu")
		(net "M_D_CPU1_SB_DQ<1>")
	)
	(segment
		(start 82.980022 -238.444786)
		(end 82.37347 -238.444786)
		(width 0.088646)
		(layer "In11.Cu")
		(net "M_D_CPU1_SB_DQ<1>")
	)
	(segment
		(start 39.610284 -226.528884)
		(end 36.853368 -226.528884)
		(width 0.18288)
		(layer "In11.Cu")
		(net "M_D_CPU1_SB_DQ<1>")
	)
	(segment
		(start 29.697426 -228.198426)
		(end 28.554426 -229.341426)
		(width 0.18288)
		(layer "In11.Cu")
		(net "M_D_CPU1_SB_DQ<1>")
	)
	(segment
		(start 26.166826 -229.722426)
		(end 25.874726 -230.014526)
		(width 0.18288)
		(layer "In11.Cu")
		(net "M_D_CPU1_SB_DQ<1>")
	)
	(segment
		(start 86.467696 -240.351564)
		(end 86.452964 -240.342928)
		(width 0.088646)
		(layer "In11.Cu")
		(net "M_D_CPU1_SB_DQ<1>")
	)
	(segment
		(start 26.674826 -229.722426)
		(end 26.166826 -229.722426)
		(width 0.18288)
		(layer "In11.Cu")
		(net "M_D_CPU1_SB_DQ<1>")
	)
	(segment
		(start 27.055826 -229.341426)
		(end 26.674826 -229.722426)
		(width 0.18288)
		(layer "In11.Cu")
		(net "M_D_CPU1_SB_DQ<1>")
	)
	(segment
		(start 74.316082 -238.444786)
		(end 66.926968 -231.070912)
		(width 0.18288)
		(layer "In11.Cu")
		(net "M_D_CPU1_SB_DQ<1>")
	)
	(segment
		(start 92.187014 -241.156744)
		(end 92.172282 -241.16538)
		(width 0.088646)
		(layer "In11.Cu")
		(net "M_D_CPU1_SB_DQ<1>")
	)
	(segment
		(start 88.427814 -241.156744)
		(end 88.4174 -241.16284)
		(width 0.088646)
		(layer "In11.Cu")
		(net "M_D_CPU1_SB_DQ<1>")
	)
	(segment
		(start 89.367614 -241.156744)
		(end 89.352882 -241.16538)
		(width 0.088646)
		(layer "In11.Cu")
		(net "M_D_CPU1_SB_DQ<1>")
	)
	(segment
		(start 87.580216 -240.677192)
		(end 87.580216 -240.667286)
		(width 0.088646)
		(layer "In11.Cu")
		(net "M_D_CPU1_SB_DQ<1>")
	)
	(segment
		(start 82.37347 -238.444786)
		(end 74.316082 -238.444786)
		(width 0.18288)
		(layer "In11.Cu")
		(net "M_D_CPU1_SB_DQ<1>")
	)
	(segment
		(start 95.006414 -241.156744)
		(end 94.996 -241.16284)
		(width 0.088646)
		(layer "In11.Cu")
		(net "M_D_CPU1_SB_DQ<1>")
	)
	(segment
		(start 34.51987 -227.49256)
		(end 31.26994 -227.49256)
		(width 0.18288)
		(layer "In11.Cu")
		(net "M_D_CPU1_SB_DQ<1>")
	)
	(segment
		(start 95.946214 -241.156744)
		(end 95.931482 -241.16538)
		(width 0.088646)
		(layer "In11.Cu")
		(net "M_D_CPU1_SB_DQ<1>")
	)
	(segment
		(start 61.696854 -230.039926)
		(end 59.829954 -228.173026)
		(width 0.18288)
		(layer "In11.Cu")
		(net "M_D_CPU1_SB_DQ<1>")
	)
	(segment
		(start 86.170262 -239.86744)
		(end 86.170262 -239.853216)
		(width 0.088646)
		(layer "In11.Cu")
		(net "M_D_CPU1_SB_DQ<1>")
	)
	(segment
		(start 50.457608 -226.642422)
		(end 49.60747 -227.49256)
		(width 0.18288)
		(layer "In11.Cu")
		(net "M_D_CPU1_SB_DQ<1>")
	)
	(segment
		(start 85.9917 -239.533938)
		(end 85.98281 -239.528858)
		(width 0.088646)
		(layer "In11.Cu")
		(net "M_D_CPU1_SB_DQ<1>")
	)
	(segment
		(start 66.49466 -230.892096)
		(end 65.588896 -230.892096)
		(width 0.18288)
		(layer "In11.Cu")
		(net "M_D_CPU1_SB_DQ<1>")
	)
	(segment
		(start 41.947846 -227.461826)
		(end 40.543226 -227.461826)
		(width 0.18288)
		(layer "In11.Cu")
		(net "M_D_CPU1_SB_DQ<1>")
	)
	(segment
		(start 84.139786 -239.60455)
		(end 82.980022 -238.444786)
		(width 0.088646)
		(layer "In11.Cu")
		(net "M_D_CPU1_SB_DQ<1>")
	)
	(segment
		(start 94.066868 -241.156744)
		(end 94.056454 -241.16284)
		(width 0.088646)
		(layer "In11.Cu")
		(net "M_D_CPU1_SB_DQ<1>")
	)
	(segment
		(start 49.60747 -227.49256)
		(end 46.35754 -227.49256)
		(width 0.18288)
		(layer "In11.Cu")
		(net "M_D_CPU1_SB_DQ<1>")
	)
	(segment
		(start 36.853368 -226.528884)
		(end 36.73983 -226.642422)
		(width 0.18288)
		(layer "In11.Cu")
		(net "M_D_CPU1_SB_DQ<1>")
	)
	(segment
		(start 65.588896 -230.892096)
		(end 64.736726 -230.039926)
		(width 0.18288)
		(layer "In11.Cu")
		(net "M_D_CPU1_SB_DQ<1>")
	)
	(segment
		(start 55.718964 -227.346764)
		(end 54.894226 -226.522026)
		(width 0.18288)
		(layer "In11.Cu")
		(net "M_D_CPU1_SB_DQ<1>")
	)
	(segment
		(start 96.886014 -241.156744)
		(end 96.871282 -241.16538)
		(width 0.088646)
		(layer "In11.Cu")
		(net "M_D_CPU1_SB_DQ<1>")
	)
	(segment
		(start 57.383426 -228.173026)
		(end 56.557164 -227.346764)
		(width 0.18288)
		(layer "In11.Cu")
		(net "M_D_CPU1_SB_DQ<1>")
	)
	(segment
		(start 42.60977 -228.12375)
		(end 41.947846 -227.461826)
		(width 0.18288)
		(layer "In11.Cu")
		(net "M_D_CPU1_SB_DQ<1>")
	)
	(segment
		(start 25.874726 -230.014526)
		(end 25.874726 -230.065326)
		(width 0.18288)
		(layer "In11.Cu")
		(net "M_D_CPU1_SB_DQ<1>")
	)
	(segment
		(start 20.030948 -230.540306)
		(end 20.030948 -229.780338)
		(width 0.18288)
		(layer "In11.Cu")
		(net "M_D_CPU1_SB_DQ<1>")
	)
	(segment
		(start 19.703796 -229.453186)
		(end 19.114008 -229.453186)
		(width 0.18288)
		(layer "In11.Cu")
		(net "M_D_CPU1_SB_DQ<1>")
	)
	(segment
		(start 45.72635 -228.12375)
		(end 42.60977 -228.12375)
		(width 0.18288)
		(layer "In11.Cu")
		(net "M_D_CPU1_SB_DQ<1>")
	)
	(segment
		(start 17.431766 -229.824026)
		(end 16.789146 -230.466646)
		(width 0.18288)
		(layer "In11.Cu")
		(net "M_D_CPU1_SB_DQ<1>")
	)
	(segment
		(start 59.829954 -228.173026)
		(end 57.383426 -228.173026)
		(width 0.18288)
		(layer "In11.Cu")
		(net "M_D_CPU1_SB_DQ<1>")
	)
	(segment
		(start 56.557164 -227.346764)
		(end 55.718964 -227.346764)
		(width 0.18288)
		(layer "In11.Cu")
		(net "M_D_CPU1_SB_DQ<1>")
	)
	(segment
		(start 25.211278 -230.728774)
		(end 21.399246 -230.728774)
		(width 0.18288)
		(layer "In11.Cu")
		(net "M_D_CPU1_SB_DQ<1>")
	)
	(segment
		(start 85.608414 -239.528858)
		(end 85.593682 -239.537494)
		(width 0.088646)
		(layer "In11.Cu")
		(net "M_D_CPU1_SB_DQ<1>")
	)
	(segment
		(start 19.114008 -229.453186)
		(end 18.743168 -229.824026)
		(width 0.18288)
		(layer "In11.Cu")
		(net "M_D_CPU1_SB_DQ<1>")
	)
	(segment
		(start 93.126814 -241.156744)
		(end 93.112082 -241.16538)
		(width 0.088646)
		(layer "In11.Cu")
		(net "M_D_CPU1_SB_DQ<1>")
	)
	(segment
		(start 20.381468 -230.890826)
		(end 20.030948 -230.540306)
		(width 0.18288)
		(layer "In11.Cu")
		(net "M_D_CPU1_SB_DQ<1>")
	)
	(segment
		(start 21.237194 -230.890826)
		(end 20.381468 -230.890826)
		(width 0.18288)
		(layer "In11.Cu")
		(net "M_D_CPU1_SB_DQ<1>")
	)
	(arc
		(start 86.452964 -240.342928)
		(mid 86.249483 -240.142124)
		(end 86.170262 -239.86744)
		(width 0.088646)
		(layer "In11.Cu")
		(net "M_D_CPU1_SB_DQ<1>")
	)
	(arc
		(start 87.580216 -240.667286)
		(mid 87.532537 -240.484386)
		(end 87.401654 -240.348008)
		(width 0.088646)
		(layer "In11.Cu")
		(net "M_D_CPU1_SB_DQ<1>")
	)
	(arc
		(start 92.172282 -241.16538)
		(mid 91.895807 -241.2327)
		(end 91.62161 -241.156744)
		(width 0.088646)
		(layer "In11.Cu")
		(net "M_D_CPU1_SB_DQ<1>")
	)
	(arc
		(start 88.80221 -241.156744)
		(mid 88.615012 -241.106601)
		(end 88.427814 -241.156744)
		(width 0.088646)
		(layer "In11.Cu")
		(net "M_D_CPU1_SB_DQ<1>")
	)
	(arc
		(start 96.871282 -241.16538)
		(mid 96.594807 -241.2327)
		(end 96.32061 -241.156744)
		(width 0.088646)
		(layer "In11.Cu")
		(net "M_D_CPU1_SB_DQ<1>")
	)
	(arc
		(start 94.441264 -241.156744)
		(mid 94.254066 -241.106601)
		(end 94.066868 -241.156744)
		(width 0.088646)
		(layer "In11.Cu")
		(net "M_D_CPU1_SB_DQ<1>")
	)
	(arc
		(start 91.62161 -241.156744)
		(mid 91.434412 -241.106601)
		(end 91.247214 -241.156744)
		(width 0.088646)
		(layer "In11.Cu")
		(net "M_D_CPU1_SB_DQ<1>")
	)
	(arc
		(start 87.018368 -240.342928)
		(mid 86.744139 -240.418853)
		(end 86.467696 -240.351564)
		(width 0.088646)
		(layer "In11.Cu")
		(net "M_D_CPU1_SB_DQ<1>")
	)
	(arc
		(start 89.352882 -241.16538)
		(mid 89.076407 -241.2327)
		(end 88.80221 -241.156744)
		(width 0.088646)
		(layer "In11.Cu")
		(net "M_D_CPU1_SB_DQ<1>")
	)
	(arc
		(start 90.292682 -241.16538)
		(mid 90.016207 -241.2327)
		(end 89.74201 -241.156744)
		(width 0.088646)
		(layer "In11.Cu")
		(net "M_D_CPU1_SB_DQ<1>")
	)
	(arc
		(start 90.68181 -241.156744)
		(mid 90.494612 -241.106601)
		(end 90.307414 -241.156744)
		(width 0.088646)
		(layer "In11.Cu")
		(net "M_D_CPU1_SB_DQ<1>")
	)
	(arc
		(start 85.593682 -239.537494)
		(mid 85.317207 -239.604814)
		(end 85.04301 -239.528858)
		(width 0.088646)
		(layer "In11.Cu")
		(net "M_D_CPU1_SB_DQ<1>")
	)
	(arc
		(start 96.32061 -241.156744)
		(mid 96.133412 -241.106601)
		(end 95.946214 -241.156744)
		(width 0.088646)
		(layer "In11.Cu")
		(net "M_D_CPU1_SB_DQ<1>")
	)
	(arc
		(start 88.4174 -241.16284)
		(mid 88.139222 -241.232563)
		(end 87.862664 -241.156744)
		(width 0.088646)
		(layer "In11.Cu")
		(net "M_D_CPU1_SB_DQ<1>")
	)
	(arc
		(start 86.170262 -239.853216)
		(mid 86.122583 -239.670316)
		(end 85.9917 -239.533938)
		(width 0.088646)
		(layer "In11.Cu")
		(net "M_D_CPU1_SB_DQ<1>")
	)
	(arc
		(start 95.931482 -241.16538)
		(mid 95.655007 -241.2327)
		(end 95.38081 -241.156744)
		(width 0.088646)
		(layer "In11.Cu")
		(net "M_D_CPU1_SB_DQ<1>")
	)
	(arc
		(start 84.668614 -239.528858)
		(mid 84.549983 -239.580378)
		(end 84.422742 -239.603534)
		(width 0.088646)
		(layer "In11.Cu")
		(net "M_D_CPU1_SB_DQ<1>")
	)
	(arc
		(start 85.04301 -239.528858)
		(mid 84.855812 -239.478715)
		(end 84.668614 -239.528858)
		(width 0.088646)
		(layer "In11.Cu")
		(net "M_D_CPU1_SB_DQ<1>")
	)
	(arc
		(start 85.98281 -239.528858)
		(mid 85.795612 -239.478715)
		(end 85.608414 -239.528858)
		(width 0.088646)
		(layer "In11.Cu")
		(net "M_D_CPU1_SB_DQ<1>")
	)
	(arc
		(start 91.247214 -241.156744)
		(mid 90.964512 -241.23252)
		(end 90.68181 -241.156744)
		(width 0.088646)
		(layer "In11.Cu")
		(net "M_D_CPU1_SB_DQ<1>")
	)
	(arc
		(start 97.26041 -241.156744)
		(mid 97.073212 -241.106601)
		(end 96.886014 -241.156744)
		(width 0.088646)
		(layer "In11.Cu")
		(net "M_D_CPU1_SB_DQ<1>")
	)
	(arc
		(start 89.74201 -241.156744)
		(mid 89.554812 -241.106601)
		(end 89.367614 -241.156744)
		(width 0.088646)
		(layer "In11.Cu")
		(net "M_D_CPU1_SB_DQ<1>")
	)
	(arc
		(start 94.056454 -241.16284)
		(mid 93.778022 -241.232686)
		(end 93.50121 -241.156744)
		(width 0.088646)
		(layer "In11.Cu")
		(net "M_D_CPU1_SB_DQ<1>")
	)
	(arc
		(start 92.56141 -241.156744)
		(mid 92.374212 -241.106601)
		(end 92.187014 -241.156744)
		(width 0.088646)
		(layer "In11.Cu")
		(net "M_D_CPU1_SB_DQ<1>")
	)
	(arc
		(start 94.996 -241.16284)
		(mid 94.717822 -241.232563)
		(end 94.441264 -241.156744)
		(width 0.088646)
		(layer "In11.Cu")
		(net "M_D_CPU1_SB_DQ<1>")
	)
	(arc
		(start 93.112082 -241.16538)
		(mid 92.835607 -241.2327)
		(end 92.56141 -241.156744)
		(width 0.088646)
		(layer "In11.Cu")
		(net "M_D_CPU1_SB_DQ<1>")
	)
	(arc
		(start 87.862664 -241.156744)
		(mid 87.658329 -240.954139)
		(end 87.580216 -240.677192)
		(width 0.088646)
		(layer "In11.Cu")
		(net "M_D_CPU1_SB_DQ<1>")
	)
	(arc
		(start 97.825814 -241.156744)
		(mid 97.543112 -241.23252)
		(end 97.26041 -241.156744)
		(width 0.088646)
		(layer "In11.Cu")
		(net "M_D_CPU1_SB_DQ<1>")
	)
	(arc
		(start 93.50121 -241.156744)
		(mid 93.314012 -241.106601)
		(end 93.126814 -241.156744)
		(width 0.088646)
		(layer "In11.Cu")
		(net "M_D_CPU1_SB_DQ<1>")
	)
	(arc
		(start 87.392764 -240.342928)
		(mid 87.205566 -240.292785)
		(end 87.018368 -240.342928)
		(width 0.088646)
		(layer "In11.Cu")
		(net "M_D_CPU1_SB_DQ<1>")
	)
	(arc
		(start 95.38081 -241.156744)
		(mid 95.193612 -241.106601)
		(end 95.006414 -241.156744)
		(width 0.088646)
		(layer "In11.Cu")
		(net "M_D_CPU1_SB_DQ<1>")
	)
	(arc
		(start 84.422742 -239.603534)
		(mid 84.404589 -239.604337)
		(end 84.38642 -239.60455)
		(width 0.088646)
		(layer "In11.Cu")
		(net "M_D_CPU1_SB_DQ<1>")
	)
	(arc
		(start 98.483166 -240.667286)
		(mid 98.208646 -240.908088)
		(end 97.905062 -241.111024)
		(width 0.088646)
		(layer "In11.Cu")
		(net "M_D_CPU1_SB_DQ<1>")
	)
	(segment
		(start 14.063726 -211.042758)
		(end 14.063726 -211.213446)
		(width 0.20066)
		(layer "F.Cu")
		(net "M_D_CPU1_SB_DQ<19>")
	)
	(segment
		(start 20.889214 -210.916774)
		(end 19.784314 -210.916774)
		(width 0.20066)
		(layer "F.Cu")
		(net "M_D_CPU1_SB_DQ<19>")
	)
	(segment
		(start 18.760694 -211.124292)
		(end 18.968212 -210.916774)
		(width 0.20066)
		(layer "F.Cu")
		(net "M_D_CPU1_SB_DQ<19>")
	)
	(segment
		(start 14.063726 -211.213446)
		(end 14.20622 -211.35594)
		(width 0.20066)
		(layer "F.Cu")
		(net "M_D_CPU1_SB_DQ<19>")
	)
	(segment
		(start 12.240514 -210.916774)
		(end 13.937742 -210.916774)
		(width 0.20066)
		(layer "F.Cu")
		(net "M_D_CPU1_SB_DQ<19>")
	)
	(segment
		(start 97.073466 -233.87812)
		(end 97.073212 -233.877866)
		(width 0.20066)
		(layer "F.Cu")
		(net "M_D_CPU1_SB_DQ<19>")
	)
	(segment
		(start 17.578578 -211.04098)
		(end 17.707102 -210.912456)
		(width 0.20066)
		(layer "F.Cu")
		(net "M_D_CPU1_SB_DQ<19>")
	)
	(segment
		(start 18.968212 -210.916774)
		(end 19.784314 -210.916774)
		(width 0.20066)
		(layer "F.Cu")
		(net "M_D_CPU1_SB_DQ<19>")
	)
	(segment
		(start 14.20622 -211.35594)
		(end 14.560042 -211.35594)
		(width 0.20066)
		(layer "F.Cu")
		(net "M_D_CPU1_SB_DQ<19>")
	)
	(segment
		(start 17.42948 -211.341716)
		(end 17.578578 -211.192618)
		(width 0.20066)
		(layer "F.Cu")
		(net "M_D_CPU1_SB_DQ<19>")
	)
	(segment
		(start 97.073212 -233.877866)
		(end 97.073212 -233.34218)
		(width 0.20066)
		(layer "F.Cu")
		(net "M_D_CPU1_SB_DQ<19>")
	)
	(segment
		(start 14.560042 -211.35594)
		(end 14.574266 -211.341716)
		(width 0.101854)
		(layer "F.Cu")
		(net "M_D_CPU1_SB_DQ<19>")
	)
	(segment
		(start 16.885158 -211.341716)
		(end 17.42948 -211.341716)
		(width 0.20066)
		(layer "F.Cu")
		(net "M_D_CPU1_SB_DQ<19>")
	)
	(segment
		(start 14.574266 -211.341716)
		(end 14.812264 -211.341716)
		(width 0.101854)
		(layer "F.Cu")
		(net "M_D_CPU1_SB_DQ<19>")
	)
	(segment
		(start 13.937742 -210.916774)
		(end 14.063726 -211.042758)
		(width 0.20066)
		(layer "F.Cu")
		(net "M_D_CPU1_SB_DQ<19>")
	)
	(segment
		(start 18.102326 -210.912456)
		(end 18.314162 -211.124292)
		(width 0.20066)
		(layer "F.Cu")
		(net "M_D_CPU1_SB_DQ<19>")
	)
	(segment
		(start 14.812264 -211.341716)
		(end 16.885158 -211.341716)
		(width 0.1016)
		(layer "F.Cu")
		(net "M_D_CPU1_SB_DQ<19>")
	)
	(segment
		(start 18.314162 -211.124292)
		(end 18.760694 -211.124292)
		(width 0.20066)
		(layer "F.Cu")
		(net "M_D_CPU1_SB_DQ<19>")
	)
	(segment
		(start 17.578578 -211.192618)
		(end 17.578578 -211.04098)
		(width 0.20066)
		(layer "F.Cu")
		(net "M_D_CPU1_SB_DQ<19>")
	)
	(segment
		(start 17.707102 -210.912456)
		(end 18.102326 -210.912456)
		(width 0.20066)
		(layer "F.Cu")
		(net "M_D_CPU1_SB_DQ<19>")
	)
	(segment
		(start 92.187014 -233.666538)
		(end 92.1766 -233.660442)
		(width 0.088646)
		(layer "In6.Cu")
		(net "M_D_CPU1_SB_DQ<19>")
	)
	(segment
		(start 65.889378 -217.069924)
		(end 65.889378 -216.670382)
		(width 0.18288)
		(layer "In6.Cu")
		(net "M_D_CPU1_SB_DQ<19>")
	)
	(segment
		(start 94.4499 -233.661458)
		(end 94.44101 -233.666538)
		(width 0.088646)
		(layer "In6.Cu")
		(net "M_D_CPU1_SB_DQ<19>")
	)
	(segment
		(start 63.278512 -213.499192)
		(end 63.080646 -213.301326)
		(width 0.18288)
		(layer "In6.Cu")
		(net "M_D_CPU1_SB_DQ<19>")
	)
	(segment
		(start 83.73364 -231.963214)
		(end 83.527138 -231.756712)
		(width 0.088646)
		(layer "In6.Cu")
		(net "M_D_CPU1_SB_DQ<19>")
	)
	(segment
		(start 62.842902 -214.386668)
		(end 62.842902 -214.160608)
		(width 0.18288)
		(layer "In6.Cu")
		(net "M_D_CPU1_SB_DQ<19>")
	)
	(segment
		(start 85.51291 -232.852722)
		(end 85.505798 -232.856786)
		(width 0.088646)
		(layer "In6.Cu")
		(net "M_D_CPU1_SB_DQ<19>")
	)
	(segment
		(start 43.76801 -210.839304)
		(end 41.354248 -210.839304)
		(width 0.18288)
		(layer "In6.Cu")
		(net "M_D_CPU1_SB_DQ<19>")
	)
	(segment
		(start 45.119544 -212.190838)
		(end 43.76801 -210.839304)
		(width 0.18288)
		(layer "In6.Cu")
		(net "M_D_CPU1_SB_DQ<19>")
	)
	(segment
		(start 62.842902 -214.160608)
		(end 63.278512 -213.725252)
		(width 0.18288)
		(layer "In6.Cu")
		(net "M_D_CPU1_SB_DQ<19>")
	)
	(segment
		(start 27.31135 -210.208622)
		(end 26.98623 -210.208622)
		(width 0.18288)
		(layer "In6.Cu")
		(net "M_D_CPU1_SB_DQ<19>")
	)
	(segment
		(start 31.480252 -212.1916)
		(end 30.86989 -211.581238)
		(width 0.18288)
		(layer "In6.Cu")
		(net "M_D_CPU1_SB_DQ<19>")
	)
	(segment
		(start 63.080646 -213.301326)
		(end 62.854586 -213.301326)
		(width 0.18288)
		(layer "In6.Cu")
		(net "M_D_CPU1_SB_DQ<19>")
	)
	(segment
		(start 63.099442 -214.643208)
		(end 62.842902 -214.386668)
		(width 0.18288)
		(layer "In6.Cu")
		(net "M_D_CPU1_SB_DQ<19>")
	)
	(segment
		(start 57.018936 -212.414104)
		(end 56.127904 -212.414104)
		(width 0.18288)
		(layer "In6.Cu")
		(net "M_D_CPU1_SB_DQ<19>")
	)
	(segment
		(start 94.066614 -233.666538)
		(end 94.051882 -233.657902)
		(width 0.088646)
		(layer "In6.Cu")
		(net "M_D_CPU1_SB_DQ<19>")
	)
	(segment
		(start 82.632042 -229.962964)
		(end 77.130656 -229.962964)
		(width 0.18288)
		(layer "In6.Cu")
		(net "M_D_CPU1_SB_DQ<19>")
	)
	(segment
		(start 66.176906 -217.357452)
		(end 65.889378 -217.069924)
		(width 0.18288)
		(layer "In6.Cu")
		(net "M_D_CPU1_SB_DQ<19>")
	)
	(segment
		(start 40.85209 -211.341462)
		(end 33.338262 -211.341462)
		(width 0.18288)
		(layer "In6.Cu")
		(net "M_D_CPU1_SB_DQ<19>")
	)
	(segment
		(start 58.97245 -212.414104)
		(end 58.075576 -212.414104)
		(width 0.18288)
		(layer "In6.Cu")
		(net "M_D_CPU1_SB_DQ<19>")
	)
	(segment
		(start 82.817716 -229.962964)
		(end 82.632042 -229.962964)
		(width 0.088646)
		(layer "In6.Cu")
		(net "M_D_CPU1_SB_DQ<19>")
	)
	(segment
		(start 65.889378 -216.670382)
		(end 64.386206 -215.16721)
		(width 0.18288)
		(layer "In6.Cu")
		(net "M_D_CPU1_SB_DQ<19>")
	)
	(segment
		(start 30.86989 -211.581238)
		(end 29.155136 -211.581238)
		(width 0.18288)
		(layer "In6.Cu")
		(net "M_D_CPU1_SB_DQ<19>")
	)
	(segment
		(start 83.527138 -231.756712)
		(end 83.527138 -230.672386)
		(width 0.088646)
		(layer "In6.Cu")
		(net "M_D_CPU1_SB_DQ<19>")
	)
	(segment
		(start 64.386206 -214.932514)
		(end 64.0969 -214.643208)
		(width 0.18288)
		(layer "In6.Cu")
		(net "M_D_CPU1_SB_DQ<19>")
	)
	(segment
		(start 62.854586 -213.301326)
		(end 62.418976 -213.736682)
		(width 0.18288)
		(layer "In6.Cu")
		(net "M_D_CPU1_SB_DQ<19>")
	)
	(segment
		(start 50.001678 -211.340954)
		(end 49.151794 -212.190838)
		(width 0.18288)
		(layer "In6.Cu")
		(net "M_D_CPU1_SB_DQ<19>")
	)
	(segment
		(start 62.192916 -213.736682)
		(end 61.556392 -213.100158)
		(width 0.18288)
		(layer "In6.Cu")
		(net "M_D_CPU1_SB_DQ<19>")
	)
	(segment
		(start 85.523324 -232.846626)
		(end 85.51291 -232.852722)
		(width 0.088646)
		(layer "In6.Cu")
		(net "M_D_CPU1_SB_DQ<19>")
	)
	(segment
		(start 96.718882 -233.247438)
		(end 96.315022 -233.01452)
		(width 0.088646)
		(layer "In6.Cu")
		(net "M_D_CPU1_SB_DQ<19>")
	)
	(segment
		(start 26.80335 -211.139278)
		(end 26.62047 -211.322158)
		(width 0.18288)
		(layer "In6.Cu")
		(net "M_D_CPU1_SB_DQ<19>")
	)
	(segment
		(start 77.130656 -229.962964)
		(end 73.165462 -225.99777)
		(width 0.18288)
		(layer "In6.Cu")
		(net "M_D_CPU1_SB_DQ<19>")
	)
	(segment
		(start 29.155136 -211.581238)
		(end 28.896056 -211.322158)
		(width 0.18288)
		(layer "In6.Cu")
		(net "M_D_CPU1_SB_DQ<19>")
	)
	(segment
		(start 95.386906 -233.021124)
		(end 95.375222 -233.01452)
		(width 0.088646)
		(layer "In6.Cu")
		(net "M_D_CPU1_SB_DQ<19>")
	)
	(segment
		(start 91.247468 -233.666538)
		(end 91.237054 -233.660442)
		(width 0.088646)
		(layer "In6.Cu")
		(net "M_D_CPU1_SB_DQ<19>")
	)
	(segment
		(start 57.384696 -211.754212)
		(end 57.201816 -211.937092)
		(width 0.18288)
		(layer "In6.Cu")
		(net "M_D_CPU1_SB_DQ<19>")
	)
	(segment
		(start 84.385912 -231.963214)
		(end 83.73364 -231.963214)
		(width 0.088646)
		(layer "In6.Cu")
		(net "M_D_CPU1_SB_DQ<19>")
	)
	(segment
		(start 57.892696 -212.231224)
		(end 57.892696 -211.937092)
		(width 0.18288)
		(layer "In6.Cu")
		(net "M_D_CPU1_SB_DQ<19>")
	)
	(segment
		(start 57.892696 -211.937092)
		(end 57.709816 -211.754212)
		(width 0.18288)
		(layer "In6.Cu")
		(net "M_D_CPU1_SB_DQ<19>")
	)
	(segment
		(start 83.527138 -230.672386)
		(end 82.817716 -229.962964)
		(width 0.088646)
		(layer "In6.Cu")
		(net "M_D_CPU1_SB_DQ<19>")
	)
	(segment
		(start 26.80335 -210.391502)
		(end 26.80335 -211.139278)
		(width 0.18288)
		(layer "In6.Cu")
		(net "M_D_CPU1_SB_DQ<19>")
	)
	(segment
		(start 26.62047 -211.322158)
		(end 25.540208 -211.322158)
		(width 0.18288)
		(layer "In6.Cu")
		(net "M_D_CPU1_SB_DQ<19>")
	)
	(segment
		(start 58.075576 -212.414104)
		(end 57.892696 -212.231224)
		(width 0.18288)
		(layer "In6.Cu")
		(net "M_D_CPU1_SB_DQ<19>")
	)
	(segment
		(start 63.278512 -213.725252)
		(end 63.278512 -213.499192)
		(width 0.18288)
		(layer "In6.Cu")
		(net "M_D_CPU1_SB_DQ<19>")
	)
	(segment
		(start 41.354248 -210.839304)
		(end 40.85209 -211.341462)
		(width 0.18288)
		(layer "In6.Cu")
		(net "M_D_CPU1_SB_DQ<19>")
	)
	(segment
		(start 59.658504 -213.100158)
		(end 58.97245 -212.414104)
		(width 0.18288)
		(layer "In6.Cu")
		(net "M_D_CPU1_SB_DQ<19>")
	)
	(segment
		(start 21.466302 -211.493862)
		(end 20.889214 -210.916774)
		(width 0.18288)
		(layer "In6.Cu")
		(net "M_D_CPU1_SB_DQ<19>")
	)
	(segment
		(start 87.392764 -232.852722)
		(end 87.381842 -232.859072)
		(width 0.088646)
		(layer "In6.Cu")
		(net "M_D_CPU1_SB_DQ<19>")
	)
	(segment
		(start 84.951062 -232.528364)
		(end 84.951062 -232.518458)
		(width 0.088646)
		(layer "In6.Cu")
		(net "M_D_CPU1_SB_DQ<19>")
	)
	(segment
		(start 93.126814 -233.666538)
		(end 93.112082 -233.657902)
		(width 0.088646)
		(layer "In6.Cu")
		(net "M_D_CPU1_SB_DQ<19>")
	)
	(segment
		(start 85.138768 -232.852976)
		(end 85.13318 -232.849928)
		(width 0.088646)
		(layer "In6.Cu")
		(net "M_D_CPU1_SB_DQ<19>")
	)
	(segment
		(start 25.540208 -211.322158)
		(end 25.368504 -211.493862)
		(width 0.18288)
		(layer "In6.Cu")
		(net "M_D_CPU1_SB_DQ<19>")
	)
	(segment
		(start 73.165462 -225.99777)
		(end 73.165462 -222.986092)
		(width 0.18288)
		(layer "In6.Cu")
		(net "M_D_CPU1_SB_DQ<19>")
	)
	(segment
		(start 49.151794 -212.190838)
		(end 45.119544 -212.190838)
		(width 0.18288)
		(layer "In6.Cu")
		(net "M_D_CPU1_SB_DQ<19>")
	)
	(segment
		(start 28.896056 -211.322158)
		(end 27.67711 -211.322158)
		(width 0.18288)
		(layer "In6.Cu")
		(net "M_D_CPU1_SB_DQ<19>")
	)
	(segment
		(start 86.08949 -232.859072)
		(end 86.078568 -232.852722)
		(width 0.088646)
		(layer "In6.Cu")
		(net "M_D_CPU1_SB_DQ<19>")
	)
	(segment
		(start 32.488124 -212.1916)
		(end 31.480252 -212.1916)
		(width 0.18288)
		(layer "In6.Cu")
		(net "M_D_CPU1_SB_DQ<19>")
	)
	(segment
		(start 67.536822 -217.357452)
		(end 66.176906 -217.357452)
		(width 0.18288)
		(layer "In6.Cu")
		(net "M_D_CPU1_SB_DQ<19>")
	)
	(segment
		(start 55.054754 -211.340954)
		(end 50.001678 -211.340954)
		(width 0.18288)
		(layer "In6.Cu")
		(net "M_D_CPU1_SB_DQ<19>")
	)
	(segment
		(start 90.307414 -233.666538)
		(end 90.292682 -233.657902)
		(width 0.088646)
		(layer "In6.Cu")
		(net "M_D_CPU1_SB_DQ<19>")
	)
	(segment
		(start 61.556392 -213.100158)
		(end 59.658504 -213.100158)
		(width 0.18288)
		(layer "In6.Cu")
		(net "M_D_CPU1_SB_DQ<19>")
	)
	(segment
		(start 56.127904 -212.414104)
		(end 55.054754 -211.340954)
		(width 0.18288)
		(layer "In6.Cu")
		(net "M_D_CPU1_SB_DQ<19>")
	)
	(segment
		(start 27.49423 -211.139278)
		(end 27.49423 -210.391502)
		(width 0.18288)
		(layer "In6.Cu")
		(net "M_D_CPU1_SB_DQ<19>")
	)
	(segment
		(start 57.709816 -211.754212)
		(end 57.384696 -211.754212)
		(width 0.18288)
		(layer "In6.Cu")
		(net "M_D_CPU1_SB_DQ<19>")
	)
	(segment
		(start 88.240616 -233.350816)
		(end 88.240616 -233.332274)
		(width 0.088646)
		(layer "In6.Cu")
		(net "M_D_CPU1_SB_DQ<19>")
	)
	(segment
		(start 25.368504 -211.493862)
		(end 21.466302 -211.493862)
		(width 0.18288)
		(layer "In6.Cu")
		(net "M_D_CPU1_SB_DQ<19>")
	)
	(segment
		(start 27.49423 -210.391502)
		(end 27.31135 -210.208622)
		(width 0.18288)
		(layer "In6.Cu")
		(net "M_D_CPU1_SB_DQ<19>")
	)
	(segment
		(start 89.367614 -233.666538)
		(end 89.352882 -233.657902)
		(width 0.088646)
		(layer "In6.Cu")
		(net "M_D_CPU1_SB_DQ<19>")
	)
	(segment
		(start 27.67711 -211.322158)
		(end 27.49423 -211.139278)
		(width 0.18288)
		(layer "In6.Cu")
		(net "M_D_CPU1_SB_DQ<19>")
	)
	(segment
		(start 57.201816 -212.231224)
		(end 57.018936 -212.414104)
		(width 0.18288)
		(layer "In6.Cu")
		(net "M_D_CPU1_SB_DQ<19>")
	)
	(segment
		(start 62.418976 -213.736682)
		(end 62.192916 -213.736682)
		(width 0.18288)
		(layer "In6.Cu")
		(net "M_D_CPU1_SB_DQ<19>")
	)
	(segment
		(start 33.338262 -211.341462)
		(end 32.488124 -212.1916)
		(width 0.18288)
		(layer "In6.Cu")
		(net "M_D_CPU1_SB_DQ<19>")
	)
	(segment
		(start 73.165462 -222.986092)
		(end 67.536822 -217.357452)
		(width 0.18288)
		(layer "In6.Cu")
		(net "M_D_CPU1_SB_DQ<19>")
	)
	(segment
		(start 26.98623 -210.208622)
		(end 26.80335 -210.391502)
		(width 0.18288)
		(layer "In6.Cu")
		(net "M_D_CPU1_SB_DQ<19>")
	)
	(segment
		(start 64.0969 -214.643208)
		(end 63.099442 -214.643208)
		(width 0.18288)
		(layer "In6.Cu")
		(net "M_D_CPU1_SB_DQ<19>")
	)
	(segment
		(start 64.386206 -215.16721)
		(end 64.386206 -214.932514)
		(width 0.18288)
		(layer "In6.Cu")
		(net "M_D_CPU1_SB_DQ<19>")
	)
	(segment
		(start 57.201816 -211.937092)
		(end 57.201816 -212.231224)
		(width 0.18288)
		(layer "In6.Cu")
		(net "M_D_CPU1_SB_DQ<19>")
	)
	(arc
		(start 96.315022 -233.01452)
		(mid 96.130167 -232.96757)
		(end 95.946214 -233.017822)
		(width 0.088646)
		(layer "In6.Cu")
		(net "M_D_CPU1_SB_DQ<19>")
	)
	(arc
		(start 95.946214 -233.017822)
		(mid 95.667011 -233.093462)
		(end 95.386906 -233.021124)
		(width 0.088646)
		(layer "In6.Cu")
		(net "M_D_CPU1_SB_DQ<19>")
	)
	(arc
		(start 94.051882 -233.657902)
		(mid 93.775441 -233.590736)
		(end 93.50121 -233.666538)
		(width 0.088646)
		(layer "In6.Cu")
		(net "M_D_CPU1_SB_DQ<19>")
	)
	(arc
		(start 95.375222 -233.01452)
		(mid 95.190367 -232.96757)
		(end 95.006414 -233.017822)
		(width 0.088646)
		(layer "In6.Cu")
		(net "M_D_CPU1_SB_DQ<19>")
	)
	(arc
		(start 89.352882 -233.657902)
		(mid 89.076441 -233.590736)
		(end 88.80221 -233.666538)
		(width 0.088646)
		(layer "In6.Cu")
		(net "M_D_CPU1_SB_DQ<19>")
	)
	(arc
		(start 92.1766 -233.660442)
		(mid 91.898422 -233.59075)
		(end 91.621864 -233.666538)
		(width 0.088646)
		(layer "In6.Cu")
		(net "M_D_CPU1_SB_DQ<19>")
	)
	(arc
		(start 87.958168 -232.852722)
		(mid 87.675466 -232.776946)
		(end 87.392764 -232.852722)
		(width 0.088646)
		(layer "In6.Cu")
		(net "M_D_CPU1_SB_DQ<19>")
	)
	(arc
		(start 88.80221 -233.666538)
		(mid 88.615012 -233.716681)
		(end 88.427814 -233.666538)
		(width 0.088646)
		(layer "In6.Cu")
		(net "M_D_CPU1_SB_DQ<19>")
	)
	(arc
		(start 88.427814 -233.666538)
		(mid 88.292881 -233.533184)
		(end 88.240616 -233.350816)
		(width 0.088646)
		(layer "In6.Cu")
		(net "M_D_CPU1_SB_DQ<19>")
	)
	(arc
		(start 87.381842 -232.859072)
		(mid 87.199312 -232.903066)
		(end 87.018368 -232.852976)
		(width 0.088646)
		(layer "In6.Cu")
		(net "M_D_CPU1_SB_DQ<19>")
	)
	(arc
		(start 91.621864 -233.666538)
		(mid 91.434666 -233.716681)
		(end 91.247468 -233.666538)
		(width 0.088646)
		(layer "In6.Cu")
		(net "M_D_CPU1_SB_DQ<19>")
	)
	(arc
		(start 94.62389 -233.399584)
		(mid 94.565734 -233.549697)
		(end 94.4499 -233.661458)
		(width 0.088646)
		(layer "In6.Cu")
		(net "M_D_CPU1_SB_DQ<19>")
	)
	(arc
		(start 85.13318 -232.849928)
		(mid 84.999737 -232.713147)
		(end 84.951062 -232.528364)
		(width 0.088646)
		(layer "In6.Cu")
		(net "M_D_CPU1_SB_DQ<19>")
	)
	(arc
		(start 86.078568 -232.852722)
		(mid 85.801755 -232.776886)
		(end 85.523324 -232.846626)
		(width 0.088646)
		(layer "In6.Cu")
		(net "M_D_CPU1_SB_DQ<19>")
	)
	(arc
		(start 84.951062 -232.518458)
		(mid 84.782077 -232.125194)
		(end 84.385912 -231.963214)
		(width 0.088646)
		(layer "In6.Cu")
		(net "M_D_CPU1_SB_DQ<19>")
	)
	(arc
		(start 87.018368 -232.852976)
		(mid 86.735666 -232.777234)
		(end 86.452964 -232.852976)
		(width 0.088646)
		(layer "In6.Cu")
		(net "M_D_CPU1_SB_DQ<19>")
	)
	(arc
		(start 93.50121 -233.666538)
		(mid 93.314012 -233.716681)
		(end 93.126814 -233.666538)
		(width 0.088646)
		(layer "In6.Cu")
		(net "M_D_CPU1_SB_DQ<19>")
	)
	(arc
		(start 90.68181 -233.666538)
		(mid 90.494612 -233.716681)
		(end 90.307414 -233.666538)
		(width 0.088646)
		(layer "In6.Cu")
		(net "M_D_CPU1_SB_DQ<19>")
	)
	(arc
		(start 86.452964 -232.852976)
		(mid 86.27202 -232.903033)
		(end 86.08949 -232.859072)
		(width 0.088646)
		(layer "In6.Cu")
		(net "M_D_CPU1_SB_DQ<19>")
	)
	(arc
		(start 93.112082 -233.657902)
		(mid 92.835641 -233.590736)
		(end 92.56141 -233.666538)
		(width 0.088646)
		(layer "In6.Cu")
		(net "M_D_CPU1_SB_DQ<19>")
	)
	(arc
		(start 97.073212 -233.34218)
		(mid 96.889824 -233.318085)
		(end 96.718882 -233.247438)
		(width 0.088646)
		(layer "In6.Cu")
		(net "M_D_CPU1_SB_DQ<19>")
	)
	(arc
		(start 91.237054 -233.660442)
		(mid 90.958622 -233.590628)
		(end 90.68181 -233.666538)
		(width 0.088646)
		(layer "In6.Cu")
		(net "M_D_CPU1_SB_DQ<19>")
	)
	(arc
		(start 95.006414 -233.017822)
		(mid 94.790107 -233.183607)
		(end 94.62389 -233.399584)
		(width 0.088646)
		(layer "In6.Cu")
		(net "M_D_CPU1_SB_DQ<19>")
	)
	(arc
		(start 89.74201 -233.666538)
		(mid 89.554812 -233.716681)
		(end 89.367614 -233.666538)
		(width 0.088646)
		(layer "In6.Cu")
		(net "M_D_CPU1_SB_DQ<19>")
	)
	(arc
		(start 85.505798 -232.856786)
		(mid 85.32179 -232.902899)
		(end 85.138768 -232.852976)
		(width 0.088646)
		(layer "In6.Cu")
		(net "M_D_CPU1_SB_DQ<19>")
	)
	(arc
		(start 94.44101 -233.666538)
		(mid 94.253812 -233.716681)
		(end 94.066614 -233.666538)
		(width 0.088646)
		(layer "In6.Cu")
		(net "M_D_CPU1_SB_DQ<19>")
	)
	(arc
		(start 90.292682 -233.657902)
		(mid 90.016241 -233.590736)
		(end 89.74201 -233.666538)
		(width 0.088646)
		(layer "In6.Cu")
		(net "M_D_CPU1_SB_DQ<19>")
	)
	(arc
		(start 88.240616 -233.332274)
		(mid 88.162505 -233.055325)
		(end 87.958168 -232.852722)
		(width 0.088646)
		(layer "In6.Cu")
		(net "M_D_CPU1_SB_DQ<19>")
	)
	(arc
		(start 92.56141 -233.666538)
		(mid 92.374212 -233.716681)
		(end 92.187014 -233.666538)
		(width 0.088646)
		(layer "In6.Cu")
		(net "M_D_CPU1_SB_DQ<19>")
	)
	(segment
		(start 20.889214 -212.616796)
		(end 19.784314 -212.616796)
		(width 0.20066)
		(layer "F.Cu")
		(net "M_D_CPU1_SB_DQ<18>")
	)
	(segment
		(start 12.240514 -212.616796)
		(end 13.387578 -212.616796)
		(width 0.20066)
		(layer "F.Cu")
		(net "M_D_CPU1_SB_DQ<18>")
	)
	(segment
		(start 13.82268 -212.181694)
		(end 14.560042 -212.181694)
		(width 0.20066)
		(layer "F.Cu")
		(net "M_D_CPU1_SB_DQ<18>")
	)
	(segment
		(start 17.66189 -212.335618)
		(end 17.66189 -212.661246)
		(width 0.20066)
		(layer "F.Cu")
		(net "M_D_CPU1_SB_DQ<18>")
	)
	(segment
		(start 17.66189 -212.661246)
		(end 17.829276 -212.828632)
		(width 0.20066)
		(layer "F.Cu")
		(net "M_D_CPU1_SB_DQ<18>")
	)
	(segment
		(start 96.603312 -234.69219)
		(end 96.603566 -234.691936)
		(width 0.20066)
		(layer "F.Cu")
		(net "M_D_CPU1_SB_DQ<18>")
	)
	(segment
		(start 13.387578 -212.616796)
		(end 13.82268 -212.181694)
		(width 0.20066)
		(layer "F.Cu")
		(net "M_D_CPU1_SB_DQ<18>")
	)
	(segment
		(start 18.257774 -212.828632)
		(end 18.46961 -212.616796)
		(width 0.20066)
		(layer "F.Cu")
		(net "M_D_CPU1_SB_DQ<18>")
	)
	(segment
		(start 14.825218 -212.191854)
		(end 16.885158 -212.191854)
		(width 0.1016)
		(layer "F.Cu")
		(net "M_D_CPU1_SB_DQ<18>")
	)
	(segment
		(start 14.570202 -212.191854)
		(end 14.825218 -212.191854)
		(width 0.101854)
		(layer "F.Cu")
		(net "M_D_CPU1_SB_DQ<18>")
	)
	(segment
		(start 17.829276 -212.828632)
		(end 18.257774 -212.828632)
		(width 0.20066)
		(layer "F.Cu")
		(net "M_D_CPU1_SB_DQ<18>")
	)
	(segment
		(start 17.518126 -212.191854)
		(end 17.66189 -212.335618)
		(width 0.20066)
		(layer "F.Cu")
		(net "M_D_CPU1_SB_DQ<18>")
	)
	(segment
		(start 14.560042 -212.181694)
		(end 14.570202 -212.191854)
		(width 0.101854)
		(layer "F.Cu")
		(net "M_D_CPU1_SB_DQ<18>")
	)
	(segment
		(start 16.885158 -212.191854)
		(end 17.518126 -212.191854)
		(width 0.20066)
		(layer "F.Cu")
		(net "M_D_CPU1_SB_DQ<18>")
	)
	(segment
		(start 18.46961 -212.616796)
		(end 19.784314 -212.616796)
		(width 0.20066)
		(layer "F.Cu")
		(net "M_D_CPU1_SB_DQ<18>")
	)
	(segment
		(start 96.603566 -234.691936)
		(end 96.603566 -234.15625)
		(width 0.20066)
		(layer "F.Cu")
		(net "M_D_CPU1_SB_DQ<18>")
	)
	(segment
		(start 86.93658 -233.658918)
		(end 86.922864 -233.667046)
		(width 0.088646)
		(layer "In6.Cu")
		(net "M_D_CPU1_SB_DQ<18>")
	)
	(segment
		(start 65.499234 -218.38539)
		(end 64.450722 -217.336878)
		(width 0.18288)
		(layer "In6.Cu")
		(net "M_D_CPU1_SB_DQ<18>")
	)
	(segment
		(start 85.61705 -233.671618)
		(end 85.608668 -233.666792)
		(width 0.088646)
		(layer "In6.Cu")
		(net "M_D_CPU1_SB_DQ<18>")
	)
	(segment
		(start 83.125818 -231.986582)
		(end 83.125818 -231.180894)
		(width 0.088646)
		(layer "In6.Cu")
		(net "M_D_CPU1_SB_DQ<18>")
	)
	(segment
		(start 41.643808 -212.720174)
		(end 40.11422 -212.720174)
		(width 0.18288)
		(layer "In6.Cu")
		(net "M_D_CPU1_SB_DQ<18>")
	)
	(segment
		(start 26.827734 -213.189566)
		(end 26.644854 -213.006686)
		(width 0.18288)
		(layer "In6.Cu")
		(net "M_D_CPU1_SB_DQ<18>")
	)
	(segment
		(start 85.052408 -233.661712)
		(end 85.043518 -233.667046)
		(width 0.088646)
		(layer "In6.Cu")
		(net "M_D_CPU1_SB_DQ<18>")
	)
	(segment
		(start 72.159368 -223.501458)
		(end 67.0433 -218.38539)
		(width 0.18288)
		(layer "In6.Cu")
		(net "M_D_CPU1_SB_DQ<18>")
	)
	(segment
		(start 52.719986 -213.237318)
		(end 51.99888 -213.237318)
		(width 0.18288)
		(layer "In6.Cu")
		(net "M_D_CPU1_SB_DQ<18>")
	)
	(segment
		(start 39.571168 -213.263226)
		(end 36.73475 -213.263226)
		(width 0.18288)
		(layer "In6.Cu")
		(net "M_D_CPU1_SB_DQ<18>")
	)
	(segment
		(start 89.287096 -234.471972)
		(end 89.272364 -234.480608)
		(width 0.088646)
		(layer "In6.Cu")
		(net "M_D_CPU1_SB_DQ<18>")
	)
	(segment
		(start 64.450722 -217.336878)
		(end 64.450722 -216.685622)
		(width 0.18288)
		(layer "In6.Cu")
		(net "M_D_CPU1_SB_DQ<18>")
	)
	(segment
		(start 64.450722 -216.685622)
		(end 64.042036 -216.276936)
		(width 0.18288)
		(layer "In6.Cu")
		(net "M_D_CPU1_SB_DQ<18>")
	)
	(segment
		(start 22.727666 -212.718904)
		(end 22.727666 -213.030816)
		(width 0.18288)
		(layer "In6.Cu")
		(net "M_D_CPU1_SB_DQ<18>")
	)
	(segment
		(start 76.675234 -230.958644)
		(end 72.159368 -226.442778)
		(width 0.18288)
		(layer "In6.Cu")
		(net "M_D_CPU1_SB_DQ<18>")
	)
	(segment
		(start 83.916266 -232.77703)
		(end 83.125818 -231.986582)
		(width 0.088646)
		(layer "In6.Cu")
		(net "M_D_CPU1_SB_DQ<18>")
	)
	(segment
		(start 23.601426 -213.213696)
		(end 23.418546 -213.030816)
		(width 0.18288)
		(layer "In6.Cu")
		(net "M_D_CPU1_SB_DQ<18>")
	)
	(segment
		(start 21.486114 -213.213696)
		(end 20.889214 -212.616796)
		(width 0.18288)
		(layer "In6.Cu")
		(net "M_D_CPU1_SB_DQ<18>")
	)
	(segment
		(start 33.39846 -213.041484)
		(end 32.548576 -213.891368)
		(width 0.18288)
		(layer "In6.Cu")
		(net "M_D_CPU1_SB_DQ<18>")
	)
	(segment
		(start 32.548576 -213.891368)
		(end 31.480252 -213.891368)
		(width 0.18288)
		(layer "In6.Cu")
		(net "M_D_CPU1_SB_DQ<18>")
	)
	(segment
		(start 62.181486 -215.438736)
		(end 61.614812 -215.438736)
		(width 0.18288)
		(layer "In6.Cu")
		(net "M_D_CPU1_SB_DQ<18>")
	)
	(segment
		(start 63.019686 -216.276936)
		(end 62.181486 -215.438736)
		(width 0.18288)
		(layer "In6.Cu")
		(net "M_D_CPU1_SB_DQ<18>")
	)
	(segment
		(start 82.632042 -230.958644)
		(end 76.675234 -230.958644)
		(width 0.18288)
		(layer "In6.Cu")
		(net "M_D_CPU1_SB_DQ<18>")
	)
	(segment
		(start 41.826688 -213.207346)
		(end 41.826688 -212.903054)
		(width 0.18288)
		(layer "In6.Cu")
		(net "M_D_CPU1_SB_DQ<18>")
	)
	(segment
		(start 29.429964 -213.280752)
		(end 29.155898 -213.006686)
		(width 0.18288)
		(layer "In6.Cu")
		(net "M_D_CPU1_SB_DQ<18>")
	)
	(segment
		(start 42.700448 -212.720174)
		(end 42.517568 -212.903054)
		(width 0.18288)
		(layer "In6.Cu")
		(net "M_D_CPU1_SB_DQ<18>")
	)
	(segment
		(start 23.418546 -212.718904)
		(end 23.235666 -212.536024)
		(width 0.18288)
		(layer "In6.Cu")
		(net "M_D_CPU1_SB_DQ<18>")
	)
	(segment
		(start 27.518614 -213.189566)
		(end 27.518614 -213.716362)
		(width 0.18288)
		(layer "In6.Cu")
		(net "M_D_CPU1_SB_DQ<18>")
	)
	(segment
		(start 31.480252 -213.891368)
		(end 30.869636 -213.280752)
		(width 0.18288)
		(layer "In6.Cu")
		(net "M_D_CPU1_SB_DQ<18>")
	)
	(segment
		(start 84.680044 -233.673142)
		(end 84.669122 -233.666792)
		(width 0.088646)
		(layer "In6.Cu")
		(net "M_D_CPU1_SB_DQ<18>")
	)
	(segment
		(start 26.827734 -213.724998)
		(end 26.827734 -213.189566)
		(width 0.18288)
		(layer "In6.Cu")
		(net "M_D_CPU1_SB_DQ<18>")
	)
	(segment
		(start 92.106496 -234.471972)
		(end 92.091764 -234.480608)
		(width 0.088646)
		(layer "In6.Cu")
		(net "M_D_CPU1_SB_DQ<18>")
	)
	(segment
		(start 61.006482 -214.830406)
		(end 59.722258 -214.830406)
		(width 0.18288)
		(layer "In6.Cu")
		(net "M_D_CPU1_SB_DQ<18>")
	)
	(segment
		(start 43.4086 -212.720174)
		(end 42.700448 -212.720174)
		(width 0.18288)
		(layer "In6.Cu")
		(net "M_D_CPU1_SB_DQ<18>")
	)
	(segment
		(start 93.981778 -234.474512)
		(end 93.971364 -234.480608)
		(width 0.088646)
		(layer "In6.Cu")
		(net "M_D_CPU1_SB_DQ<18>")
	)
	(segment
		(start 85.993224 -233.660696)
		(end 85.98281 -233.666792)
		(width 0.088646)
		(layer "In6.Cu")
		(net "M_D_CPU1_SB_DQ<18>")
	)
	(segment
		(start 23.418546 -213.030816)
		(end 23.418546 -212.718904)
		(width 0.18288)
		(layer "In6.Cu")
		(net "M_D_CPU1_SB_DQ<18>")
	)
	(segment
		(start 42.517568 -212.903054)
		(end 42.517568 -213.203028)
		(width 0.18288)
		(layer "In6.Cu")
		(net "M_D_CPU1_SB_DQ<18>")
	)
	(segment
		(start 52.902866 -212.601556)
		(end 52.902866 -213.054438)
		(width 0.18288)
		(layer "In6.Cu")
		(net "M_D_CPU1_SB_DQ<18>")
	)
	(segment
		(start 53.410866 -212.418676)
		(end 53.085746 -212.418676)
		(width 0.18288)
		(layer "In6.Cu")
		(net "M_D_CPU1_SB_DQ<18>")
	)
	(segment
		(start 50.419 -213.040976)
		(end 49.567592 -213.892384)
		(width 0.18288)
		(layer "In6.Cu")
		(net "M_D_CPU1_SB_DQ<18>")
	)
	(segment
		(start 27.518614 -213.716362)
		(end 27.327098 -213.907878)
		(width 0.18288)
		(layer "In6.Cu")
		(net "M_D_CPU1_SB_DQ<18>")
	)
	(segment
		(start 27.010614 -213.907878)
		(end 26.827734 -213.724998)
		(width 0.18288)
		(layer "In6.Cu")
		(net "M_D_CPU1_SB_DQ<18>")
	)
	(segment
		(start 53.776626 -213.237318)
		(end 53.593746 -213.054438)
		(width 0.18288)
		(layer "In6.Cu")
		(net "M_D_CPU1_SB_DQ<18>")
	)
	(segment
		(start 25.36952 -213.006686)
		(end 25.16251 -213.213696)
		(width 0.18288)
		(layer "In6.Cu")
		(net "M_D_CPU1_SB_DQ<18>")
	)
	(segment
		(start 55.147718 -213.237318)
		(end 53.776626 -213.237318)
		(width 0.18288)
		(layer "In6.Cu")
		(net "M_D_CPU1_SB_DQ<18>")
	)
	(segment
		(start 88.347296 -234.471972)
		(end 88.332564 -234.480608)
		(width 0.088646)
		(layer "In6.Cu")
		(net "M_D_CPU1_SB_DQ<18>")
	)
	(segment
		(start 22.727666 -213.030816)
		(end 22.544786 -213.213696)
		(width 0.18288)
		(layer "In6.Cu")
		(net "M_D_CPU1_SB_DQ<18>")
	)
	(segment
		(start 42.33037 -213.390226)
		(end 42.009568 -213.390226)
		(width 0.18288)
		(layer "In6.Cu")
		(net "M_D_CPU1_SB_DQ<18>")
	)
	(segment
		(start 41.826688 -212.903054)
		(end 41.643808 -212.720174)
		(width 0.18288)
		(layer "In6.Cu")
		(net "M_D_CPU1_SB_DQ<18>")
	)
	(segment
		(start 94.9198 -234.475528)
		(end 94.91091 -234.480608)
		(width 0.088646)
		(layer "In6.Cu")
		(net "M_D_CPU1_SB_DQ<18>")
	)
	(segment
		(start 42.009568 -213.390226)
		(end 41.826688 -213.207346)
		(width 0.18288)
		(layer "In6.Cu")
		(net "M_D_CPU1_SB_DQ<18>")
	)
	(segment
		(start 67.0433 -218.38539)
		(end 65.499234 -218.38539)
		(width 0.18288)
		(layer "In6.Cu")
		(net "M_D_CPU1_SB_DQ<18>")
	)
	(segment
		(start 72.159368 -226.442778)
		(end 72.159368 -223.501458)
		(width 0.18288)
		(layer "In6.Cu")
		(net "M_D_CPU1_SB_DQ<18>")
	)
	(segment
		(start 58.831988 -213.940136)
		(end 55.850536 -213.940136)
		(width 0.18288)
		(layer "In6.Cu")
		(net "M_D_CPU1_SB_DQ<18>")
	)
	(segment
		(start 84.669122 -233.666792)
		(end 84.654898 -233.658664)
		(width 0.088646)
		(layer "In6.Cu")
		(net "M_D_CPU1_SB_DQ<18>")
	)
	(segment
		(start 22.544786 -213.213696)
		(end 21.486114 -213.213696)
		(width 0.18288)
		(layer "In6.Cu")
		(net "M_D_CPU1_SB_DQ<18>")
	)
	(segment
		(start 30.869636 -213.280752)
		(end 29.429964 -213.280752)
		(width 0.18288)
		(layer "In6.Cu")
		(net "M_D_CPU1_SB_DQ<18>")
	)
	(segment
		(start 55.850536 -213.940136)
		(end 55.147718 -213.237318)
		(width 0.18288)
		(layer "In6.Cu")
		(net "M_D_CPU1_SB_DQ<18>")
	)
	(segment
		(start 83.125818 -231.180894)
		(end 82.903568 -230.958644)
		(width 0.088646)
		(layer "In6.Cu")
		(net "M_D_CPU1_SB_DQ<18>")
	)
	(segment
		(start 40.11422 -212.720174)
		(end 39.571168 -213.263226)
		(width 0.18288)
		(layer "In6.Cu")
		(net "M_D_CPU1_SB_DQ<18>")
	)
	(segment
		(start 27.327098 -213.907878)
		(end 27.010614 -213.907878)
		(width 0.18288)
		(layer "In6.Cu")
		(net "M_D_CPU1_SB_DQ<18>")
	)
	(segment
		(start 82.903568 -230.958644)
		(end 82.632042 -230.958644)
		(width 0.088646)
		(layer "In6.Cu")
		(net "M_D_CPU1_SB_DQ<18>")
	)
	(segment
		(start 44.58081 -213.892384)
		(end 43.4086 -212.720174)
		(width 0.18288)
		(layer "In6.Cu")
		(net "M_D_CPU1_SB_DQ<18>")
	)
	(segment
		(start 22.910546 -212.536024)
		(end 22.727666 -212.718904)
		(width 0.18288)
		(layer "In6.Cu")
		(net "M_D_CPU1_SB_DQ<18>")
	)
	(segment
		(start 87.770716 -234.15625)
		(end 87.770462 -234.137708)
		(width 0.088646)
		(layer "In6.Cu")
		(net "M_D_CPU1_SB_DQ<18>")
	)
	(segment
		(start 53.593746 -213.054438)
		(end 53.593746 -212.601556)
		(width 0.18288)
		(layer "In6.Cu")
		(net "M_D_CPU1_SB_DQ<18>")
	)
	(segment
		(start 51.99888 -213.237318)
		(end 51.802538 -213.040976)
		(width 0.18288)
		(layer "In6.Cu")
		(net "M_D_CPU1_SB_DQ<18>")
	)
	(segment
		(start 52.902866 -213.054438)
		(end 52.719986 -213.237318)
		(width 0.18288)
		(layer "In6.Cu")
		(net "M_D_CPU1_SB_DQ<18>")
	)
	(segment
		(start 61.614812 -215.438736)
		(end 61.006482 -214.830406)
		(width 0.18288)
		(layer "In6.Cu")
		(net "M_D_CPU1_SB_DQ<18>")
	)
	(segment
		(start 87.958168 -234.480608)
		(end 87.949278 -234.475528)
		(width 0.088646)
		(layer "In6.Cu")
		(net "M_D_CPU1_SB_DQ<18>")
	)
	(segment
		(start 42.517568 -213.203028)
		(end 42.33037 -213.390226)
		(width 0.18288)
		(layer "In6.Cu")
		(net "M_D_CPU1_SB_DQ<18>")
	)
	(segment
		(start 36.73475 -213.263226)
		(end 36.513008 -213.041484)
		(width 0.18288)
		(layer "In6.Cu")
		(net "M_D_CPU1_SB_DQ<18>")
	)
	(segment
		(start 23.235666 -212.536024)
		(end 22.910546 -212.536024)
		(width 0.18288)
		(layer "In6.Cu")
		(net "M_D_CPU1_SB_DQ<18>")
	)
	(segment
		(start 59.722258 -214.830406)
		(end 58.831988 -213.940136)
		(width 0.18288)
		(layer "In6.Cu")
		(net "M_D_CPU1_SB_DQ<18>")
	)
	(segment
		(start 64.042036 -216.276936)
		(end 63.019686 -216.276936)
		(width 0.18288)
		(layer "In6.Cu")
		(net "M_D_CPU1_SB_DQ<18>")
	)
	(segment
		(start 91.166696 -234.471972)
		(end 91.151964 -234.480608)
		(width 0.088646)
		(layer "In6.Cu")
		(net "M_D_CPU1_SB_DQ<18>")
	)
	(segment
		(start 93.046296 -234.471972)
		(end 93.031564 -234.480608)
		(width 0.088646)
		(layer "In6.Cu")
		(net "M_D_CPU1_SB_DQ<18>")
	)
	(segment
		(start 27.701494 -213.006686)
		(end 27.518614 -213.189566)
		(width 0.18288)
		(layer "In6.Cu")
		(net "M_D_CPU1_SB_DQ<18>")
	)
	(segment
		(start 53.593746 -212.601556)
		(end 53.410866 -212.418676)
		(width 0.18288)
		(layer "In6.Cu")
		(net "M_D_CPU1_SB_DQ<18>")
	)
	(segment
		(start 25.16251 -213.213696)
		(end 23.601426 -213.213696)
		(width 0.18288)
		(layer "In6.Cu")
		(net "M_D_CPU1_SB_DQ<18>")
	)
	(segment
		(start 26.644854 -213.006686)
		(end 25.36952 -213.006686)
		(width 0.18288)
		(layer "In6.Cu")
		(net "M_D_CPU1_SB_DQ<18>")
	)
	(segment
		(start 29.155898 -213.006686)
		(end 27.701494 -213.006686)
		(width 0.18288)
		(layer "In6.Cu")
		(net "M_D_CPU1_SB_DQ<18>")
	)
	(segment
		(start 36.513008 -213.041484)
		(end 33.39846 -213.041484)
		(width 0.18288)
		(layer "In6.Cu")
		(net "M_D_CPU1_SB_DQ<18>")
	)
	(segment
		(start 53.085746 -212.418676)
		(end 52.902866 -212.601556)
		(width 0.18288)
		(layer "In6.Cu")
		(net "M_D_CPU1_SB_DQ<18>")
	)
	(segment
		(start 86.55939 -233.673142)
		(end 86.548468 -233.666792)
		(width 0.088646)
		(layer "In6.Cu")
		(net "M_D_CPU1_SB_DQ<18>")
	)
	(segment
		(start 51.802538 -213.040976)
		(end 50.419 -213.040976)
		(width 0.18288)
		(layer "In6.Cu")
		(net "M_D_CPU1_SB_DQ<18>")
	)
	(segment
		(start 49.567592 -213.892384)
		(end 44.58081 -213.892384)
		(width 0.18288)
		(layer "In6.Cu")
		(net "M_D_CPU1_SB_DQ<18>")
	)
	(arc
		(start 87.488268 -233.666792)
		(mid 87.213441 -233.590981)
		(end 86.93658 -233.658918)
		(width 0.088646)
		(layer "In6.Cu")
		(net "M_D_CPU1_SB_DQ<18>")
	)
	(arc
		(start 93.971364 -234.480608)
		(mid 93.784166 -234.530751)
		(end 93.596968 -234.480608)
		(width 0.088646)
		(layer "In6.Cu")
		(net "M_D_CPU1_SB_DQ<18>")
	)
	(arc
		(start 87.770462 -234.137708)
		(mid 87.690389 -233.865667)
		(end 87.488268 -233.666792)
		(width 0.088646)
		(layer "In6.Cu")
		(net "M_D_CPU1_SB_DQ<18>")
	)
	(arc
		(start 94.536514 -234.480608)
		(mid 94.259955 -234.404865)
		(end 93.981778 -234.474512)
		(width 0.088646)
		(layer "In6.Cu")
		(net "M_D_CPU1_SB_DQ<18>")
	)
	(arc
		(start 95.762826 -233.786426)
		(mid 95.582924 -233.769731)
		(end 95.407226 -233.811826)
		(width 0.088646)
		(layer "In6.Cu")
		(net "M_D_CPU1_SB_DQ<18>")
	)
	(arc
		(start 92.657168 -234.480608)
		(mid 92.382969 -234.404773)
		(end 92.106496 -234.471972)
		(width 0.088646)
		(layer "In6.Cu")
		(net "M_D_CPU1_SB_DQ<18>")
	)
	(arc
		(start 86.922864 -233.667046)
		(mid 86.74192 -233.717137)
		(end 86.55939 -233.673142)
		(width 0.088646)
		(layer "In6.Cu")
		(net "M_D_CPU1_SB_DQ<18>")
	)
	(arc
		(start 89.837768 -234.480608)
		(mid 89.563569 -234.404773)
		(end 89.287096 -234.471972)
		(width 0.088646)
		(layer "In6.Cu")
		(net "M_D_CPU1_SB_DQ<18>")
	)
	(arc
		(start 93.596968 -234.480608)
		(mid 93.322769 -234.404773)
		(end 93.046296 -234.471972)
		(width 0.088646)
		(layer "In6.Cu")
		(net "M_D_CPU1_SB_DQ<18>")
	)
	(arc
		(start 89.272364 -234.480608)
		(mid 89.085166 -234.530751)
		(end 88.897968 -234.480608)
		(width 0.088646)
		(layer "In6.Cu")
		(net "M_D_CPU1_SB_DQ<18>")
	)
	(arc
		(start 91.717368 -234.480608)
		(mid 91.443169 -234.404773)
		(end 91.166696 -234.471972)
		(width 0.088646)
		(layer "In6.Cu")
		(net "M_D_CPU1_SB_DQ<18>")
	)
	(arc
		(start 94.91091 -234.480608)
		(mid 94.723712 -234.530751)
		(end 94.536514 -234.480608)
		(width 0.088646)
		(layer "In6.Cu")
		(net "M_D_CPU1_SB_DQ<18>")
	)
	(arc
		(start 84.654898 -233.658664)
		(mid 84.527855 -233.522848)
		(end 84.48167 -233.342688)
		(width 0.088646)
		(layer "In6.Cu")
		(net "M_D_CPU1_SB_DQ<18>")
	)
	(arc
		(start 95.407226 -233.811826)
		(mid 95.198158 -233.971921)
		(end 95.09379 -234.213654)
		(width 0.088646)
		(layer "In6.Cu")
		(net "M_D_CPU1_SB_DQ<18>")
	)
	(arc
		(start 86.548468 -233.666792)
		(mid 86.271655 -233.590922)
		(end 85.993224 -233.660696)
		(width 0.088646)
		(layer "In6.Cu")
		(net "M_D_CPU1_SB_DQ<18>")
	)
	(arc
		(start 87.949278 -234.475528)
		(mid 87.818364 -234.339168)
		(end 87.770716 -234.15625)
		(width 0.088646)
		(layer "In6.Cu")
		(net "M_D_CPU1_SB_DQ<18>")
	)
	(arc
		(start 91.151964 -234.480608)
		(mid 90.964766 -234.530751)
		(end 90.777568 -234.480608)
		(width 0.088646)
		(layer "In6.Cu")
		(net "M_D_CPU1_SB_DQ<18>")
	)
	(arc
		(start 96.603566 -234.15625)
		(mid 96.197844 -233.938037)
		(end 95.762826 -233.786426)
		(width 0.088646)
		(layer "In6.Cu")
		(net "M_D_CPU1_SB_DQ<18>")
	)
	(arc
		(start 85.608668 -233.666792)
		(mid 85.331196 -233.591074)
		(end 85.052408 -233.661712)
		(width 0.088646)
		(layer "In6.Cu")
		(net "M_D_CPU1_SB_DQ<18>")
	)
	(arc
		(start 85.043518 -233.667046)
		(mid 84.862574 -233.717137)
		(end 84.680044 -233.673142)
		(width 0.088646)
		(layer "In6.Cu")
		(net "M_D_CPU1_SB_DQ<18>")
	)
	(arc
		(start 90.212164 -234.480608)
		(mid 90.024966 -234.530751)
		(end 89.837768 -234.480608)
		(width 0.088646)
		(layer "In6.Cu")
		(net "M_D_CPU1_SB_DQ<18>")
	)
	(arc
		(start 88.897968 -234.480608)
		(mid 88.623769 -234.404773)
		(end 88.347296 -234.471972)
		(width 0.088646)
		(layer "In6.Cu")
		(net "M_D_CPU1_SB_DQ<18>")
	)
	(arc
		(start 85.98281 -233.666792)
		(mid 85.800559 -233.716903)
		(end 85.61705 -233.671618)
		(width 0.088646)
		(layer "In6.Cu")
		(net "M_D_CPU1_SB_DQ<18>")
	)
	(arc
		(start 88.332564 -234.480608)
		(mid 88.145366 -234.530751)
		(end 87.958168 -234.480608)
		(width 0.088646)
		(layer "In6.Cu")
		(net "M_D_CPU1_SB_DQ<18>")
	)
	(arc
		(start 93.031564 -234.480608)
		(mid 92.844366 -234.530751)
		(end 92.657168 -234.480608)
		(width 0.088646)
		(layer "In6.Cu")
		(net "M_D_CPU1_SB_DQ<18>")
	)
	(arc
		(start 92.091764 -234.480608)
		(mid 91.904566 -234.530751)
		(end 91.717368 -234.480608)
		(width 0.088646)
		(layer "In6.Cu")
		(net "M_D_CPU1_SB_DQ<18>")
	)
	(arc
		(start 84.48167 -233.342688)
		(mid 84.316157 -232.942723)
		(end 83.916266 -232.77703)
		(width 0.088646)
		(layer "In6.Cu")
		(net "M_D_CPU1_SB_DQ<18>")
	)
	(arc
		(start 95.09379 -234.213654)
		(mid 95.035634 -234.363767)
		(end 94.9198 -234.475528)
		(width 0.088646)
		(layer "In6.Cu")
		(net "M_D_CPU1_SB_DQ<18>")
	)
	(arc
		(start 90.777568 -234.480608)
		(mid 90.494866 -234.404832)
		(end 90.212164 -234.480608)
		(width 0.088646)
		(layer "In6.Cu")
		(net "M_D_CPU1_SB_DQ<18>")
	)
	(segment
		(start 11.11631 -211.332826)
		(end 11.1252 -211.341716)
		(width 0.1016)
		(layer "F.Cu")
		(net "M_D_CPU1_SB_DQ<17>")
	)
	(segment
		(start 8.140446 -211.766658)
		(end 9.474708 -211.766658)
		(width 0.20066)
		(layer "F.Cu")
		(net "M_D_CPU1_SB_DQ<17>")
	)
	(segment
		(start 10.19048 -211.977986)
		(end 10.344912 -211.823554)
		(width 0.20066)
		(layer "F.Cu")
		(net "M_D_CPU1_SB_DQ<17>")
	)
	(segment
		(start 9.474708 -211.766658)
		(end 9.686036 -211.977986)
		(width 0.20066)
		(layer "F.Cu")
		(net "M_D_CPU1_SB_DQ<17>")
	)
	(segment
		(start 11.1252 -211.341716)
		(end 13.110718 -211.341716)
		(width 0.1016)
		(layer "F.Cu")
		(net "M_D_CPU1_SB_DQ<17>")
	)
	(segment
		(start 14.04493 -211.766658)
		(end 15.684246 -211.766658)
		(width 0.20066)
		(layer "F.Cu")
		(net "M_D_CPU1_SB_DQ<17>")
	)
	(segment
		(start 95.193612 -233.877866)
		(end 95.193612 -233.34218)
		(width 0.20066)
		(layer "F.Cu")
		(net "M_D_CPU1_SB_DQ<17>")
	)
	(segment
		(start 13.441426 -211.341716)
		(end 13.619988 -211.341716)
		(width 0.20066)
		(layer "F.Cu")
		(net "M_D_CPU1_SB_DQ<17>")
	)
	(segment
		(start 10.507472 -211.332826)
		(end 11.11631 -211.332826)
		(width 0.20066)
		(layer "F.Cu")
		(net "M_D_CPU1_SB_DQ<17>")
	)
	(segment
		(start 13.110718 -211.341716)
		(end 13.441426 -211.341716)
		(width 0.101854)
		(layer "F.Cu")
		(net "M_D_CPU1_SB_DQ<17>")
	)
	(segment
		(start 9.686036 -211.977986)
		(end 10.19048 -211.977986)
		(width 0.20066)
		(layer "F.Cu")
		(net "M_D_CPU1_SB_DQ<17>")
	)
	(segment
		(start 10.344912 -211.495386)
		(end 10.507472 -211.332826)
		(width 0.20066)
		(layer "F.Cu")
		(net "M_D_CPU1_SB_DQ<17>")
	)
	(segment
		(start 10.344912 -211.823554)
		(end 10.344912 -211.495386)
		(width 0.20066)
		(layer "F.Cu")
		(net "M_D_CPU1_SB_DQ<17>")
	)
	(segment
		(start 95.193866 -233.87812)
		(end 95.193612 -233.877866)
		(width 0.20066)
		(layer "F.Cu")
		(net "M_D_CPU1_SB_DQ<17>")
	)
	(segment
		(start 13.619988 -211.341716)
		(end 14.04493 -211.766658)
		(width 0.20066)
		(layer "F.Cu")
		(net "M_D_CPU1_SB_DQ<17>")
	)
	(segment
		(start 16.789146 -211.766658)
		(end 15.684246 -211.766658)
		(width 0.20066)
		(layer "F.Cu")
		(net "M_D_CPU1_SB_DQ<17>")
	)
	(segment
		(start 67.337178 -217.861896)
		(end 65.900808 -217.861896)
		(width 0.18288)
		(layer "In6.Cu")
		(net "M_D_CPU1_SB_DQ<17>")
	)
	(segment
		(start 18.777712 -212.682836)
		(end 18.594832 -212.865716)
		(width 0.18288)
		(layer "In6.Cu")
		(net "M_D_CPU1_SB_DQ<17>")
	)
	(segment
		(start 49.35982 -213.042246)
		(end 44.5389 -213.042246)
		(width 0.18288)
		(layer "In6.Cu")
		(net "M_D_CPU1_SB_DQ<17>")
	)
	(segment
		(start 83.654646 -232.15346)
		(end 83.336892 -231.835706)
		(width 0.088646)
		(layer "In6.Cu")
		(net "M_D_CPU1_SB_DQ<17>")
	)
	(segment
		(start 26.811224 -212.188806)
		(end 26.628344 -212.371686)
		(width 0.18288)
		(layer "In6.Cu")
		(net "M_D_CPU1_SB_DQ<17>")
	)
	(segment
		(start 90.226896 -233.840528)
		(end 90.212164 -233.831892)
		(width 0.088646)
		(layer "In6.Cu")
		(net "M_D_CPU1_SB_DQ<17>")
	)
	(segment
		(start 32.548576 -213.041484)
		(end 31.480252 -213.041484)
		(width 0.18288)
		(layer "In6.Cu")
		(net "M_D_CPU1_SB_DQ<17>")
	)
	(segment
		(start 84.760562 -232.542588)
		(end 84.760562 -232.528364)
		(width 0.088646)
		(layer "In6.Cu")
		(net "M_D_CPU1_SB_DQ<17>")
	)
	(segment
		(start 55.884826 -212.983826)
		(end 54.810152 -211.909152)
		(width 0.18288)
		(layer "In6.Cu")
		(net "M_D_CPU1_SB_DQ<17>")
	)
	(segment
		(start 52.167282 -211.909152)
		(end 51.885596 -212.190838)
		(width 0.18288)
		(layer "In6.Cu")
		(net "M_D_CPU1_SB_DQ<17>")
	)
	(segment
		(start 82.632042 -230.460804)
		(end 76.924408 -230.460804)
		(width 0.18288)
		(layer "In6.Cu")
		(net "M_D_CPU1_SB_DQ<17>")
	)
	(segment
		(start 17.903952 -212.190838)
		(end 17.213072 -212.190838)
		(width 0.18288)
		(layer "In6.Cu")
		(net "M_D_CPU1_SB_DQ<17>")
	)
	(segment
		(start 27.319224 -211.883498)
		(end 26.994104 -211.883498)
		(width 0.18288)
		(layer "In6.Cu")
		(net "M_D_CPU1_SB_DQ<17>")
	)
	(segment
		(start 27.684984 -212.371686)
		(end 27.502104 -212.188806)
		(width 0.18288)
		(layer "In6.Cu")
		(net "M_D_CPU1_SB_DQ<17>")
	)
	(segment
		(start 17.213072 -212.190838)
		(end 16.789146 -211.766658)
		(width 0.18288)
		(layer "In6.Cu")
		(net "M_D_CPU1_SB_DQ<17>")
	)
	(segment
		(start 21.160232 -212.190838)
		(end 18.960592 -212.190838)
		(width 0.18288)
		(layer "In6.Cu")
		(net "M_D_CPU1_SB_DQ<17>")
	)
	(segment
		(start 42.93108 -212.1916)
		(end 42.7482 -212.00872)
		(width 0.18288)
		(layer "In6.Cu")
		(net "M_D_CPU1_SB_DQ<17>")
	)
	(segment
		(start 28.995116 -212.371686)
		(end 27.684984 -212.371686)
		(width 0.18288)
		(layer "In6.Cu")
		(net "M_D_CPU1_SB_DQ<17>")
	)
	(segment
		(start 18.086832 -212.373718)
		(end 17.903952 -212.190838)
		(width 0.18288)
		(layer "In6.Cu")
		(net "M_D_CPU1_SB_DQ<17>")
	)
	(segment
		(start 42.7482 -211.681314)
		(end 42.56532 -211.498434)
		(width 0.18288)
		(layer "In6.Cu")
		(net "M_D_CPU1_SB_DQ<17>")
	)
	(segment
		(start 27.502104 -212.066378)
		(end 27.319224 -211.883498)
		(width 0.18288)
		(layer "In6.Cu")
		(net "M_D_CPU1_SB_DQ<17>")
	)
	(segment
		(start 59.584082 -213.781386)
		(end 58.786522 -212.983826)
		(width 0.18288)
		(layer "In6.Cu")
		(net "M_D_CPU1_SB_DQ<17>")
	)
	(segment
		(start 65.299336 -216.805256)
		(end 64.227202 -215.733122)
		(width 0.18288)
		(layer "In6.Cu")
		(net "M_D_CPU1_SB_DQ<17>")
	)
	(segment
		(start 42.7482 -212.00872)
		(end 42.7482 -211.681314)
		(width 0.18288)
		(layer "In6.Cu")
		(net "M_D_CPU1_SB_DQ<17>")
	)
	(segment
		(start 58.786522 -212.983826)
		(end 55.884826 -212.983826)
		(width 0.18288)
		(layer "In6.Cu")
		(net "M_D_CPU1_SB_DQ<17>")
	)
	(segment
		(start 64.227202 -215.733122)
		(end 63.24092 -215.733122)
		(width 0.18288)
		(layer "In6.Cu")
		(net "M_D_CPU1_SB_DQ<17>")
	)
	(segment
		(start 42.05732 -212.00872)
		(end 41.87444 -212.1916)
		(width 0.18288)
		(layer "In6.Cu")
		(net "M_D_CPU1_SB_DQ<17>")
	)
	(segment
		(start 83.336892 -231.835706)
		(end 83.336892 -230.883968)
		(width 0.088646)
		(layer "In6.Cu")
		(net "M_D_CPU1_SB_DQ<17>")
	)
	(segment
		(start 61.978032 -214.893906)
		(end 60.865512 -213.781386)
		(width 0.18288)
		(layer "In6.Cu")
		(net "M_D_CPU1_SB_DQ<17>")
	)
	(segment
		(start 26.811224 -212.066378)
		(end 26.811224 -212.188806)
		(width 0.18288)
		(layer "In6.Cu")
		(net "M_D_CPU1_SB_DQ<17>")
	)
	(segment
		(start 25.388824 -212.371686)
		(end 25.040844 -212.023706)
		(width 0.18288)
		(layer "In6.Cu")
		(net "M_D_CPU1_SB_DQ<17>")
	)
	(segment
		(start 65.299336 -217.260424)
		(end 65.299336 -216.805256)
		(width 0.18288)
		(layer "In6.Cu")
		(net "M_D_CPU1_SB_DQ<17>")
	)
	(segment
		(start 21.327364 -212.023706)
		(end 21.160232 -212.190838)
		(width 0.18288)
		(layer "In6.Cu")
		(net "M_D_CPU1_SB_DQ<17>")
	)
	(segment
		(start 54.810152 -211.909152)
		(end 52.167282 -211.909152)
		(width 0.18288)
		(layer "In6.Cu")
		(net "M_D_CPU1_SB_DQ<17>")
	)
	(segment
		(start 87.488268 -233.017822)
		(end 87.474552 -233.02595)
		(width 0.088646)
		(layer "In6.Cu")
		(net "M_D_CPU1_SB_DQ<17>")
	)
	(segment
		(start 33.39846 -212.1916)
		(end 32.548576 -213.041484)
		(width 0.18288)
		(layer "In6.Cu")
		(net "M_D_CPU1_SB_DQ<17>")
	)
	(segment
		(start 26.994104 -211.883498)
		(end 26.811224 -212.066378)
		(width 0.18288)
		(layer "In6.Cu")
		(net "M_D_CPU1_SB_DQ<17>")
	)
	(segment
		(start 25.040844 -212.023706)
		(end 21.327364 -212.023706)
		(width 0.18288)
		(layer "In6.Cu")
		(net "M_D_CPU1_SB_DQ<17>")
	)
	(segment
		(start 60.865512 -213.781386)
		(end 59.584082 -213.781386)
		(width 0.18288)
		(layer "In6.Cu")
		(net "M_D_CPU1_SB_DQ<17>")
	)
	(segment
		(start 93.981778 -233.837988)
		(end 93.971364 -233.831892)
		(width 0.088646)
		(layer "In6.Cu")
		(net "M_D_CPU1_SB_DQ<17>")
	)
	(segment
		(start 65.900808 -217.861896)
		(end 65.299336 -217.260424)
		(width 0.18288)
		(layer "In6.Cu")
		(net "M_D_CPU1_SB_DQ<17>")
	)
	(segment
		(start 89.287096 -233.840528)
		(end 89.272364 -233.831892)
		(width 0.088646)
		(layer "In6.Cu")
		(net "M_D_CPU1_SB_DQ<17>")
	)
	(segment
		(start 18.086832 -212.682836)
		(end 18.086832 -212.373718)
		(width 0.18288)
		(layer "In6.Cu")
		(net "M_D_CPU1_SB_DQ<17>")
	)
	(segment
		(start 72.667622 -223.19234)
		(end 67.337178 -217.861896)
		(width 0.18288)
		(layer "In6.Cu")
		(net "M_D_CPU1_SB_DQ<17>")
	)
	(segment
		(start 42.56532 -211.498434)
		(end 42.2402 -211.498434)
		(width 0.18288)
		(layer "In6.Cu")
		(net "M_D_CPU1_SB_DQ<17>")
	)
	(segment
		(start 72.667622 -226.204018)
		(end 72.667622 -223.19234)
		(width 0.18288)
		(layer "In6.Cu")
		(net "M_D_CPU1_SB_DQ<17>")
	)
	(segment
		(start 31.480252 -213.041484)
		(end 30.590744 -212.151976)
		(width 0.18288)
		(layer "In6.Cu")
		(net "M_D_CPU1_SB_DQ<17>")
	)
	(segment
		(start 18.269712 -212.865716)
		(end 18.086832 -212.682836)
		(width 0.18288)
		(layer "In6.Cu")
		(net "M_D_CPU1_SB_DQ<17>")
	)
	(segment
		(start 92.106496 -233.840528)
		(end 92.091764 -233.831892)
		(width 0.088646)
		(layer "In6.Cu")
		(net "M_D_CPU1_SB_DQ<17>")
	)
	(segment
		(start 18.594832 -212.865716)
		(end 18.269712 -212.865716)
		(width 0.18288)
		(layer "In6.Cu")
		(net "M_D_CPU1_SB_DQ<17>")
	)
	(segment
		(start 41.87444 -212.1916)
		(end 33.39846 -212.1916)
		(width 0.18288)
		(layer "In6.Cu")
		(net "M_D_CPU1_SB_DQ<17>")
	)
	(segment
		(start 26.628344 -212.371686)
		(end 25.388824 -212.371686)
		(width 0.18288)
		(layer "In6.Cu")
		(net "M_D_CPU1_SB_DQ<17>")
	)
	(segment
		(start 42.2402 -211.498434)
		(end 42.05732 -211.681314)
		(width 0.18288)
		(layer "In6.Cu")
		(net "M_D_CPU1_SB_DQ<17>")
	)
	(segment
		(start 82.913728 -230.460804)
		(end 82.632042 -230.460804)
		(width 0.088646)
		(layer "In6.Cu")
		(net "M_D_CPU1_SB_DQ<17>")
	)
	(segment
		(start 93.046296 -233.840528)
		(end 93.031564 -233.831892)
		(width 0.088646)
		(layer "In6.Cu")
		(net "M_D_CPU1_SB_DQ<17>")
	)
	(segment
		(start 84.385912 -232.15346)
		(end 83.654646 -232.15346)
		(width 0.088646)
		(layer "In6.Cu")
		(net "M_D_CPU1_SB_DQ<17>")
	)
	(segment
		(start 18.960592 -212.190838)
		(end 18.777712 -212.373718)
		(width 0.18288)
		(layer "In6.Cu")
		(net "M_D_CPU1_SB_DQ<17>")
	)
	(segment
		(start 86.548468 -233.018076)
		(end 86.538054 -233.024172)
		(width 0.088646)
		(layer "In6.Cu")
		(net "M_D_CPU1_SB_DQ<17>")
	)
	(segment
		(start 51.885596 -212.190838)
		(end 50.211228 -212.190838)
		(width 0.18288)
		(layer "In6.Cu")
		(net "M_D_CPU1_SB_DQ<17>")
	)
	(segment
		(start 76.924408 -230.460804)
		(end 72.667622 -226.204018)
		(width 0.18288)
		(layer "In6.Cu")
		(net "M_D_CPU1_SB_DQ<17>")
	)
	(segment
		(start 27.502104 -212.188806)
		(end 27.502104 -212.066378)
		(width 0.18288)
		(layer "In6.Cu")
		(net "M_D_CPU1_SB_DQ<17>")
	)
	(segment
		(start 43.688254 -212.1916)
		(end 42.93108 -212.1916)
		(width 0.18288)
		(layer "In6.Cu")
		(net "M_D_CPU1_SB_DQ<17>")
	)
	(segment
		(start 83.336892 -230.883968)
		(end 82.913728 -230.460804)
		(width 0.088646)
		(layer "In6.Cu")
		(net "M_D_CPU1_SB_DQ<17>")
	)
	(segment
		(start 18.777712 -212.373718)
		(end 18.777712 -212.682836)
		(width 0.18288)
		(layer "In6.Cu")
		(net "M_D_CPU1_SB_DQ<17>")
	)
	(segment
		(start 29.214826 -212.151976)
		(end 28.995116 -212.371686)
		(width 0.18288)
		(layer "In6.Cu")
		(net "M_D_CPU1_SB_DQ<17>")
	)
	(segment
		(start 50.211228 -212.190838)
		(end 49.35982 -213.042246)
		(width 0.18288)
		(layer "In6.Cu")
		(net "M_D_CPU1_SB_DQ<17>")
	)
	(segment
		(start 30.590744 -212.151976)
		(end 29.214826 -212.151976)
		(width 0.18288)
		(layer "In6.Cu")
		(net "M_D_CPU1_SB_DQ<17>")
	)
	(segment
		(start 44.5389 -213.042246)
		(end 43.688254 -212.1916)
		(width 0.18288)
		(layer "In6.Cu")
		(net "M_D_CPU1_SB_DQ<17>")
	)
	(segment
		(start 88.049862 -233.356404)
		(end 88.049862 -233.333544)
		(width 0.088646)
		(layer "In6.Cu")
		(net "M_D_CPU1_SB_DQ<17>")
	)
	(segment
		(start 63.24092 -215.733122)
		(end 62.401704 -214.893906)
		(width 0.18288)
		(layer "In6.Cu")
		(net "M_D_CPU1_SB_DQ<17>")
	)
	(segment
		(start 62.401704 -214.893906)
		(end 61.978032 -214.893906)
		(width 0.18288)
		(layer "In6.Cu")
		(net "M_D_CPU1_SB_DQ<17>")
	)
	(segment
		(start 42.05732 -211.681314)
		(end 42.05732 -212.00872)
		(width 0.18288)
		(layer "In6.Cu")
		(net "M_D_CPU1_SB_DQ<17>")
	)
	(arc
		(start 94.536514 -233.831892)
		(mid 94.259955 -233.907601)
		(end 93.981778 -233.837988)
		(width 0.088646)
		(layer "In6.Cu")
		(net "M_D_CPU1_SB_DQ<17>")
	)
	(arc
		(start 85.98281 -233.018076)
		(mid 85.795612 -232.967933)
		(end 85.608414 -233.018076)
		(width 0.088646)
		(layer "In6.Cu")
		(net "M_D_CPU1_SB_DQ<17>")
	)
	(arc
		(start 95.193612 -233.34218)
		(mid 94.879392 -233.606262)
		(end 94.536514 -233.831892)
		(width 0.088646)
		(layer "In6.Cu")
		(net "M_D_CPU1_SB_DQ<17>")
	)
	(arc
		(start 93.031564 -233.831892)
		(mid 92.844366 -233.781749)
		(end 92.657168 -233.831892)
		(width 0.088646)
		(layer "In6.Cu")
		(net "M_D_CPU1_SB_DQ<17>")
	)
	(arc
		(start 86.538054 -233.024172)
		(mid 86.259622 -233.093986)
		(end 85.98281 -233.018076)
		(width 0.088646)
		(layer "In6.Cu")
		(net "M_D_CPU1_SB_DQ<17>")
	)
	(arc
		(start 84.760562 -232.528364)
		(mid 84.650845 -232.263357)
		(end 84.385912 -232.15346)
		(width 0.088646)
		(layer "In6.Cu")
		(net "M_D_CPU1_SB_DQ<17>")
	)
	(arc
		(start 88.049862 -233.333544)
		(mid 87.858988 -233.015735)
		(end 87.488268 -233.017822)
		(width 0.088646)
		(layer "In6.Cu")
		(net "M_D_CPU1_SB_DQ<17>")
	)
	(arc
		(start 93.596968 -233.831892)
		(mid 93.322739 -233.907817)
		(end 93.046296 -233.840528)
		(width 0.088646)
		(layer "In6.Cu")
		(net "M_D_CPU1_SB_DQ<17>")
	)
	(arc
		(start 89.837768 -233.831892)
		(mid 89.563539 -233.907817)
		(end 89.287096 -233.840528)
		(width 0.088646)
		(layer "In6.Cu")
		(net "M_D_CPU1_SB_DQ<17>")
	)
	(arc
		(start 91.151964 -233.831892)
		(mid 90.964766 -233.781749)
		(end 90.777568 -233.831892)
		(width 0.088646)
		(layer "In6.Cu")
		(net "M_D_CPU1_SB_DQ<17>")
	)
	(arc
		(start 93.971364 -233.831892)
		(mid 93.784166 -233.781749)
		(end 93.596968 -233.831892)
		(width 0.088646)
		(layer "In6.Cu")
		(net "M_D_CPU1_SB_DQ<17>")
	)
	(arc
		(start 86.922864 -233.018076)
		(mid 86.735666 -232.967967)
		(end 86.548468 -233.018076)
		(width 0.088646)
		(layer "In6.Cu")
		(net "M_D_CPU1_SB_DQ<17>")
	)
	(arc
		(start 85.608414 -233.018076)
		(mid 85.049156 -233.021573)
		(end 84.760562 -232.542588)
		(width 0.088646)
		(layer "In6.Cu")
		(net "M_D_CPU1_SB_DQ<17>")
	)
	(arc
		(start 88.897968 -233.831892)
		(mid 88.338707 -233.835387)
		(end 88.049862 -233.356404)
		(width 0.088646)
		(layer "In6.Cu")
		(net "M_D_CPU1_SB_DQ<17>")
	)
	(arc
		(start 90.212164 -233.831892)
		(mid 90.024966 -233.781749)
		(end 89.837768 -233.831892)
		(width 0.088646)
		(layer "In6.Cu")
		(net "M_D_CPU1_SB_DQ<17>")
	)
	(arc
		(start 89.272364 -233.831892)
		(mid 89.085166 -233.781749)
		(end 88.897968 -233.831892)
		(width 0.088646)
		(layer "In6.Cu")
		(net "M_D_CPU1_SB_DQ<17>")
	)
	(arc
		(start 87.474552 -233.02595)
		(mid 87.197692 -233.093822)
		(end 86.922864 -233.018076)
		(width 0.088646)
		(layer "In6.Cu")
		(net "M_D_CPU1_SB_DQ<17>")
	)
	(arc
		(start 90.777568 -233.831892)
		(mid 90.503339 -233.907817)
		(end 90.226896 -233.840528)
		(width 0.088646)
		(layer "In6.Cu")
		(net "M_D_CPU1_SB_DQ<17>")
	)
	(arc
		(start 91.717368 -233.831892)
		(mid 91.434666 -233.907634)
		(end 91.151964 -233.831892)
		(width 0.088646)
		(layer "In6.Cu")
		(net "M_D_CPU1_SB_DQ<17>")
	)
	(arc
		(start 92.091764 -233.831892)
		(mid 91.904566 -233.781749)
		(end 91.717368 -233.831892)
		(width 0.088646)
		(layer "In6.Cu")
		(net "M_D_CPU1_SB_DQ<17>")
	)
	(arc
		(start 92.657168 -233.831892)
		(mid 92.382939 -233.907817)
		(end 92.106496 -233.840528)
		(width 0.088646)
		(layer "In6.Cu")
		(net "M_D_CPU1_SB_DQ<17>")
	)
	(segment
		(start 10.344912 -213.24316)
		(end 10.554462 -213.03361)
		(width 0.20066)
		(layer "F.Cu")
		(net "M_D_CPU1_SB_DQ<16>")
	)
	(segment
		(start 8.140446 -213.46668)
		(end 9.474708 -213.46668)
		(width 0.20066)
		(layer "F.Cu")
		(net "M_D_CPU1_SB_DQ<16>")
	)
	(segment
		(start 16.789146 -213.46668)
		(end 15.684246 -213.46668)
		(width 0.20066)
		(layer "F.Cu")
		(net "M_D_CPU1_SB_DQ<16>")
	)
	(segment
		(start 95.663512 -234.69219)
		(end 95.663766 -234.691936)
		(width 0.20066)
		(layer "F.Cu")
		(net "M_D_CPU1_SB_DQ<16>")
	)
	(segment
		(start 11.372342 -213.041738)
		(end 13.441426 -213.041738)
		(width 0.1016)
		(layer "F.Cu")
		(net "M_D_CPU1_SB_DQ<16>")
	)
	(segment
		(start 9.713468 -213.70544)
		(end 10.172192 -213.70544)
		(width 0.20066)
		(layer "F.Cu")
		(net "M_D_CPU1_SB_DQ<16>")
	)
	(segment
		(start 9.474708 -213.46668)
		(end 9.713468 -213.70544)
		(width 0.20066)
		(layer "F.Cu")
		(net "M_D_CPU1_SB_DQ<16>")
	)
	(segment
		(start 13.890244 -213.041738)
		(end 14.315186 -213.46668)
		(width 0.20066)
		(layer "F.Cu")
		(net "M_D_CPU1_SB_DQ<16>")
	)
	(segment
		(start 13.441426 -213.041738)
		(end 13.890244 -213.041738)
		(width 0.20066)
		(layer "F.Cu")
		(net "M_D_CPU1_SB_DQ<16>")
	)
	(segment
		(start 95.663766 -234.691936)
		(end 95.663766 -234.15625)
		(width 0.20066)
		(layer "F.Cu")
		(net "M_D_CPU1_SB_DQ<16>")
	)
	(segment
		(start 14.315186 -213.46668)
		(end 15.684246 -213.46668)
		(width 0.20066)
		(layer "F.Cu")
		(net "M_D_CPU1_SB_DQ<16>")
	)
	(segment
		(start 10.344912 -213.53272)
		(end 10.344912 -213.24316)
		(width 0.20066)
		(layer "F.Cu")
		(net "M_D_CPU1_SB_DQ<16>")
	)
	(segment
		(start 11.124438 -213.041738)
		(end 11.372342 -213.041738)
		(width 0.101854)
		(layer "F.Cu")
		(net "M_D_CPU1_SB_DQ<16>")
	)
	(segment
		(start 10.172192 -213.70544)
		(end 10.344912 -213.53272)
		(width 0.20066)
		(layer "F.Cu")
		(net "M_D_CPU1_SB_DQ<16>")
	)
	(segment
		(start 11.11631 -213.03361)
		(end 11.124438 -213.041738)
		(width 0.101854)
		(layer "F.Cu")
		(net "M_D_CPU1_SB_DQ<16>")
	)
	(segment
		(start 10.554462 -213.03361)
		(end 11.11631 -213.03361)
		(width 0.20066)
		(layer "F.Cu")
		(net "M_D_CPU1_SB_DQ<16>")
	)
	(segment
		(start 19.468846 -214.07374)
		(end 19.285966 -213.89086)
		(width 0.18288)
		(layer "In6.Cu")
		(net "M_D_CPU1_SB_DQ<16>")
	)
	(segment
		(start 82.632296 -231.456484)
		(end 76.468986 -231.456484)
		(width 0.18288)
		(layer "In6.Cu")
		(net "M_D_CPU1_SB_DQ<16>")
	)
	(segment
		(start 47.13859 -214.742268)
		(end 46.792642 -214.742268)
		(width 0.18288)
		(layer "In6.Cu")
		(net "M_D_CPU1_SB_DQ<16>")
	)
	(segment
		(start 52.719986 -213.740492)
		(end 51.94808 -213.740492)
		(width 0.18288)
		(layer "In6.Cu")
		(net "M_D_CPU1_SB_DQ<16>")
	)
	(segment
		(start 93.126814 -234.645708)
		(end 93.112082 -234.654344)
		(width 0.088646)
		(layer "In6.Cu")
		(net "M_D_CPU1_SB_DQ<16>")
	)
	(segment
		(start 21.459698 -213.89086)
		(end 20.342606 -213.89086)
		(width 0.18288)
		(layer "In6.Cu")
		(net "M_D_CPU1_SB_DQ<16>")
	)
	(segment
		(start 53.410866 -214.645748)
		(end 53.085746 -214.645748)
		(width 0.18288)
		(layer "In6.Cu")
		(net "M_D_CPU1_SB_DQ<16>")
	)
	(segment
		(start 95.018606 -234.638596)
		(end 95.006414 -234.645708)
		(width 0.088646)
		(layer "In6.Cu")
		(net "M_D_CPU1_SB_DQ<16>")
	)
	(segment
		(start 53.776626 -213.740492)
		(end 53.593746 -213.923372)
		(width 0.18288)
		(layer "In6.Cu")
		(net "M_D_CPU1_SB_DQ<16>")
	)
	(segment
		(start 46.792642 -214.742268)
		(end 46.591982 -214.541608)
		(width 0.18288)
		(layer "In6.Cu")
		(net "M_D_CPU1_SB_DQ<16>")
	)
	(segment
		(start 66.768726 -218.951556)
		(end 65.325498 -218.951556)
		(width 0.18288)
		(layer "In6.Cu")
		(net "M_D_CPU1_SB_DQ<16>")
	)
	(segment
		(start 18.595086 -214.593678)
		(end 18.269966 -214.593678)
		(width 0.18288)
		(layer "In6.Cu")
		(net "M_D_CPU1_SB_DQ<16>")
	)
	(segment
		(start 86.078314 -233.831892)
		(end 86.069424 -233.837226)
		(width 0.088646)
		(layer "In6.Cu")
		(net "M_D_CPU1_SB_DQ<16>")
	)
	(segment
		(start 17.213326 -213.89086)
		(end 16.789146 -213.46668)
		(width 0.18288)
		(layer "In6.Cu")
		(net "M_D_CPU1_SB_DQ<16>")
	)
	(segment
		(start 86.45271 -233.832146)
		(end 86.441788 -233.825796)
		(width 0.088646)
		(layer "In6.Cu")
		(net "M_D_CPU1_SB_DQ<16>")
	)
	(segment
		(start 33.398714 -213.891368)
		(end 32.897826 -214.392256)
		(width 0.18288)
		(layer "In6.Cu")
		(net "M_D_CPU1_SB_DQ<16>")
	)
	(segment
		(start 65.325498 -218.951556)
		(end 63.720218 -217.346276)
		(width 0.18288)
		(layer "In6.Cu")
		(net "M_D_CPU1_SB_DQ<16>")
	)
	(segment
		(start 51.797712 -213.89086)
		(end 50.522886 -213.89086)
		(width 0.18288)
		(layer "In6.Cu")
		(net "M_D_CPU1_SB_DQ<16>")
	)
	(segment
		(start 20.159726 -214.410798)
		(end 19.976846 -214.593678)
		(width 0.18288)
		(layer "In6.Cu")
		(net "M_D_CPU1_SB_DQ<16>")
	)
	(segment
		(start 82.925158 -232.055162)
		(end 82.925158 -231.54513)
		(width 0.088646)
		(layer "In6.Cu")
		(net "M_D_CPU1_SB_DQ<16>")
	)
	(segment
		(start 82.925158 -231.54513)
		(end 82.836512 -231.456484)
		(width 0.088646)
		(layer "In6.Cu")
		(net "M_D_CPU1_SB_DQ<16>")
	)
	(segment
		(start 45.131228 -214.742268)
		(end 44.554394 -214.742268)
		(width 0.18288)
		(layer "In6.Cu")
		(net "M_D_CPU1_SB_DQ<16>")
	)
	(segment
		(start 25.676606 -214.446104)
		(end 24.948388 -213.717886)
		(width 0.18288)
		(layer "In6.Cu")
		(net "M_D_CPU1_SB_DQ<16>")
	)
	(segment
		(start 19.285966 -213.89086)
		(end 18.960846 -213.89086)
		(width 0.18288)
		(layer "In6.Cu")
		(net "M_D_CPU1_SB_DQ<16>")
	)
	(segment
		(start 51.94808 -213.740492)
		(end 51.797712 -213.89086)
		(width 0.18288)
		(layer "In6.Cu")
		(net "M_D_CPU1_SB_DQ<16>")
	)
	(segment
		(start 88.427814 -234.645708)
		(end 88.410542 -234.655614)
		(width 0.088646)
		(layer "In6.Cu")
		(net "M_D_CPU1_SB_DQ<16>")
	)
	(segment
		(start 28.703524 -214.446104)
		(end 25.676606 -214.446104)
		(width 0.18288)
		(layer "In6.Cu")
		(net "M_D_CPU1_SB_DQ<16>")
	)
	(segment
		(start 71.570596 -226.558094)
		(end 71.570596 -223.753426)
		(width 0.18288)
		(layer "In6.Cu")
		(net "M_D_CPU1_SB_DQ<16>")
	)
	(segment
		(start 20.159726 -214.07374)
		(end 20.159726 -214.410798)
		(width 0.18288)
		(layer "In6.Cu")
		(net "M_D_CPU1_SB_DQ<16>")
	)
	(segment
		(start 53.593746 -213.923372)
		(end 53.593746 -214.462868)
		(width 0.18288)
		(layer "In6.Cu")
		(net "M_D_CPU1_SB_DQ<16>")
	)
	(segment
		(start 18.960846 -213.89086)
		(end 18.777966 -214.07374)
		(width 0.18288)
		(layer "In6.Cu")
		(net "M_D_CPU1_SB_DQ<16>")
	)
	(segment
		(start 24.948388 -213.717886)
		(end 21.632672 -213.717886)
		(width 0.18288)
		(layer "In6.Cu")
		(net "M_D_CPU1_SB_DQ<16>")
	)
	(segment
		(start 87.018368 -233.832146)
		(end 87.007954 -233.838242)
		(width 0.088646)
		(layer "In6.Cu")
		(net "M_D_CPU1_SB_DQ<16>")
	)
	(segment
		(start 32.070548 -214.741506)
		(end 31.480252 -214.741506)
		(width 0.18288)
		(layer "In6.Cu")
		(net "M_D_CPU1_SB_DQ<16>")
	)
	(segment
		(start 31.480252 -214.741506)
		(end 30.555438 -213.816692)
		(width 0.18288)
		(layer "In6.Cu")
		(net "M_D_CPU1_SB_DQ<16>")
	)
	(segment
		(start 63.299086 -217.346276)
		(end 62.863222 -216.910412)
		(width 0.18288)
		(layer "In6.Cu")
		(net "M_D_CPU1_SB_DQ<16>")
	)
	(segment
		(start 44.554394 -214.742268)
		(end 43.703494 -213.891368)
		(width 0.18288)
		(layer "In6.Cu")
		(net "M_D_CPU1_SB_DQ<16>")
	)
	(segment
		(start 32.897826 -214.392256)
		(end 32.419798 -214.392256)
		(width 0.18288)
		(layer "In6.Cu")
		(net "M_D_CPU1_SB_DQ<16>")
	)
	(segment
		(start 87.58047 -234.175046)
		(end 87.580216 -234.156504)
		(width 0.088646)
		(layer "In6.Cu")
		(net "M_D_CPU1_SB_DQ<16>")
	)
	(segment
		(start 63.720218 -217.346276)
		(end 63.299086 -217.346276)
		(width 0.18288)
		(layer "In6.Cu")
		(net "M_D_CPU1_SB_DQ<16>")
	)
	(segment
		(start 43.703494 -213.891368)
		(end 33.398714 -213.891368)
		(width 0.18288)
		(layer "In6.Cu")
		(net "M_D_CPU1_SB_DQ<16>")
	)
	(segment
		(start 55.569358 -214.541354)
		(end 54.768496 -213.740492)
		(width 0.18288)
		(layer "In6.Cu")
		(net "M_D_CPU1_SB_DQ<16>")
	)
	(segment
		(start 62.863222 -216.910412)
		(end 62.215014 -216.910412)
		(width 0.18288)
		(layer "In6.Cu")
		(net "M_D_CPU1_SB_DQ<16>")
	)
	(segment
		(start 18.087086 -214.07374)
		(end 17.904206 -213.89086)
		(width 0.18288)
		(layer "In6.Cu")
		(net "M_D_CPU1_SB_DQ<16>")
	)
	(segment
		(start 21.632672 -213.717886)
		(end 21.459698 -213.89086)
		(width 0.18288)
		(layer "In6.Cu")
		(net "M_D_CPU1_SB_DQ<16>")
	)
	(segment
		(start 83.837272 -232.967276)
		(end 82.925158 -232.055162)
		(width 0.088646)
		(layer "In6.Cu")
		(net "M_D_CPU1_SB_DQ<16>")
	)
	(segment
		(start 91.247214 -234.645708)
		(end 91.2368 -234.651804)
		(width 0.088646)
		(layer "In6.Cu")
		(net "M_D_CPU1_SB_DQ<16>")
	)
	(segment
		(start 83.916266 -232.967276)
		(end 83.837272 -232.967276)
		(width 0.088646)
		(layer "In6.Cu")
		(net "M_D_CPU1_SB_DQ<16>")
	)
	(segment
		(start 92.187014 -234.645708)
		(end 92.172282 -234.654344)
		(width 0.088646)
		(layer "In6.Cu")
		(net "M_D_CPU1_SB_DQ<16>")
	)
	(segment
		(start 18.269966 -214.593678)
		(end 18.087086 -214.410798)
		(width 0.18288)
		(layer "In6.Cu")
		(net "M_D_CPU1_SB_DQ<16>")
	)
	(segment
		(start 87.02929 -233.825796)
		(end 87.018368 -233.832146)
		(width 0.088646)
		(layer "In6.Cu")
		(net "M_D_CPU1_SB_DQ<16>")
	)
	(segment
		(start 89.367614 -234.645708)
		(end 89.352882 -234.654344)
		(width 0.088646)
		(layer "In6.Cu")
		(net "M_D_CPU1_SB_DQ<16>")
	)
	(segment
		(start 19.468846 -214.410798)
		(end 19.468846 -214.07374)
		(width 0.18288)
		(layer "In6.Cu")
		(net "M_D_CPU1_SB_DQ<16>")
	)
	(segment
		(start 50.522886 -213.89086)
		(end 49.887886 -214.52586)
		(width 0.18288)
		(layer "In6.Cu")
		(net "M_D_CPU1_SB_DQ<16>")
	)
	(segment
		(start 49.887886 -214.52586)
		(end 47.354998 -214.52586)
		(width 0.18288)
		(layer "In6.Cu")
		(net "M_D_CPU1_SB_DQ<16>")
	)
	(segment
		(start 45.331888 -214.541608)
		(end 45.131228 -214.742268)
		(width 0.18288)
		(layer "In6.Cu")
		(net "M_D_CPU1_SB_DQ<16>")
	)
	(segment
		(start 53.593746 -214.462868)
		(end 53.410866 -214.645748)
		(width 0.18288)
		(layer "In6.Cu")
		(net "M_D_CPU1_SB_DQ<16>")
	)
	(segment
		(start 52.902866 -214.462868)
		(end 52.902866 -213.923372)
		(width 0.18288)
		(layer "In6.Cu")
		(net "M_D_CPU1_SB_DQ<16>")
	)
	(segment
		(start 18.087086 -214.410798)
		(end 18.087086 -214.07374)
		(width 0.18288)
		(layer "In6.Cu")
		(net "M_D_CPU1_SB_DQ<16>")
	)
	(segment
		(start 84.112354 -233.023156)
		(end 84.103464 -233.018076)
		(width 0.088646)
		(layer "In6.Cu")
		(net "M_D_CPU1_SB_DQ<16>")
	)
	(segment
		(start 29.332936 -213.816692)
		(end 28.703524 -214.446104)
		(width 0.18288)
		(layer "In6.Cu")
		(net "M_D_CPU1_SB_DQ<16>")
	)
	(segment
		(start 19.651726 -214.593678)
		(end 19.468846 -214.410798)
		(width 0.18288)
		(layer "In6.Cu")
		(net "M_D_CPU1_SB_DQ<16>")
	)
	(segment
		(start 85.513164 -233.832146)
		(end 85.504782 -233.82732)
		(width 0.088646)
		(layer "In6.Cu")
		(net "M_D_CPU1_SB_DQ<16>")
	)
	(segment
		(start 82.836512 -231.456484)
		(end 82.632296 -231.456484)
		(width 0.088646)
		(layer "In6.Cu")
		(net "M_D_CPU1_SB_DQ<16>")
	)
	(segment
		(start 60.712096 -215.407494)
		(end 59.58967 -215.407494)
		(width 0.18288)
		(layer "In6.Cu")
		(net "M_D_CPU1_SB_DQ<16>")
	)
	(segment
		(start 52.902866 -213.923372)
		(end 52.719986 -213.740492)
		(width 0.18288)
		(layer "In6.Cu")
		(net "M_D_CPU1_SB_DQ<16>")
	)
	(segment
		(start 53.085746 -214.645748)
		(end 52.902866 -214.462868)
		(width 0.18288)
		(layer "In6.Cu")
		(net "M_D_CPU1_SB_DQ<16>")
	)
	(segment
		(start 94.066614 -234.645708)
		(end 94.051882 -234.654344)
		(width 0.088646)
		(layer "In6.Cu")
		(net "M_D_CPU1_SB_DQ<16>")
	)
	(segment
		(start 62.215014 -216.910412)
		(end 60.712096 -215.407494)
		(width 0.18288)
		(layer "In6.Cu")
		(net "M_D_CPU1_SB_DQ<16>")
	)
	(segment
		(start 85.139022 -233.832146)
		(end 85.128608 -233.838242)
		(width 0.088646)
		(layer "In6.Cu")
		(net "M_D_CPU1_SB_DQ<16>")
	)
	(segment
		(start 17.904206 -213.89086)
		(end 17.213326 -213.89086)
		(width 0.18288)
		(layer "In6.Cu")
		(net "M_D_CPU1_SB_DQ<16>")
	)
	(segment
		(start 76.468986 -231.456484)
		(end 71.570596 -226.558094)
		(width 0.18288)
		(layer "In6.Cu")
		(net "M_D_CPU1_SB_DQ<16>")
	)
	(segment
		(start 84.573364 -233.832146)
		(end 84.567268 -233.82859)
		(width 0.088646)
		(layer "In6.Cu")
		(net "M_D_CPU1_SB_DQ<16>")
	)
	(segment
		(start 54.768496 -213.740492)
		(end 53.776626 -213.740492)
		(width 0.18288)
		(layer "In6.Cu")
		(net "M_D_CPU1_SB_DQ<16>")
	)
	(segment
		(start 46.591982 -214.541608)
		(end 45.331888 -214.541608)
		(width 0.18288)
		(layer "In6.Cu")
		(net "M_D_CPU1_SB_DQ<16>")
	)
	(segment
		(start 18.777966 -214.07374)
		(end 18.777966 -214.410798)
		(width 0.18288)
		(layer "In6.Cu")
		(net "M_D_CPU1_SB_DQ<16>")
	)
	(segment
		(start 32.419798 -214.392256)
		(end 32.070548 -214.741506)
		(width 0.18288)
		(layer "In6.Cu")
		(net "M_D_CPU1_SB_DQ<16>")
	)
	(segment
		(start 47.354998 -214.52586)
		(end 47.13859 -214.742268)
		(width 0.18288)
		(layer "In6.Cu")
		(net "M_D_CPU1_SB_DQ<16>")
	)
	(segment
		(start 18.777966 -214.410798)
		(end 18.595086 -214.593678)
		(width 0.18288)
		(layer "In6.Cu")
		(net "M_D_CPU1_SB_DQ<16>")
	)
	(segment
		(start 90.307668 -234.645708)
		(end 90.297254 -234.651804)
		(width 0.088646)
		(layer "In6.Cu")
		(net "M_D_CPU1_SB_DQ<16>")
	)
	(segment
		(start 87.580216 -234.156504)
		(end 87.580216 -234.149392)
		(width 0.088646)
		(layer "In6.Cu")
		(net "M_D_CPU1_SB_DQ<16>")
	)
	(segment
		(start 59.58967 -215.407494)
		(end 58.72353 -214.541354)
		(width 0.18288)
		(layer "In6.Cu")
		(net "M_D_CPU1_SB_DQ<16>")
	)
	(segment
		(start 71.570596 -223.753426)
		(end 66.768726 -218.951556)
		(width 0.18288)
		(layer "In6.Cu")
		(net "M_D_CPU1_SB_DQ<16>")
	)
	(segment
		(start 30.555438 -213.816692)
		(end 29.332936 -213.816692)
		(width 0.18288)
		(layer "In6.Cu")
		(net "M_D_CPU1_SB_DQ<16>")
	)
	(segment
		(start 20.342606 -213.89086)
		(end 20.159726 -214.07374)
		(width 0.18288)
		(layer "In6.Cu")
		(net "M_D_CPU1_SB_DQ<16>")
	)
	(segment
		(start 58.72353 -214.541354)
		(end 55.569358 -214.541354)
		(width 0.18288)
		(layer "In6.Cu")
		(net "M_D_CPU1_SB_DQ<16>")
	)
	(segment
		(start 19.976846 -214.593678)
		(end 19.651726 -214.593678)
		(width 0.18288)
		(layer "In6.Cu")
		(net "M_D_CPU1_SB_DQ<16>")
	)
	(arc
		(start 94.44101 -234.645708)
		(mid 94.253812 -234.595565)
		(end 94.066614 -234.645708)
		(width 0.088646)
		(layer "In6.Cu")
		(net "M_D_CPU1_SB_DQ<16>")
	)
	(arc
		(start 88.80221 -234.645708)
		(mid 88.615012 -234.595565)
		(end 88.427814 -234.645708)
		(width 0.088646)
		(layer "In6.Cu")
		(net "M_D_CPU1_SB_DQ<16>")
	)
	(arc
		(start 84.567268 -233.82859)
		(mid 84.364792 -233.622067)
		(end 84.290916 -233.342434)
		(width 0.088646)
		(layer "In6.Cu")
		(net "M_D_CPU1_SB_DQ<16>")
	)
	(arc
		(start 95.006414 -234.645708)
		(mid 94.723712 -234.721484)
		(end 94.44101 -234.645708)
		(width 0.088646)
		(layer "In6.Cu")
		(net "M_D_CPU1_SB_DQ<16>")
	)
	(arc
		(start 87.392764 -233.831892)
		(mid 87.21182 -233.781835)
		(end 87.02929 -233.825796)
		(width 0.088646)
		(layer "In6.Cu")
		(net "M_D_CPU1_SB_DQ<16>")
	)
	(arc
		(start 90.297254 -234.651804)
		(mid 90.018822 -234.72165)
		(end 89.74201 -234.645708)
		(width 0.088646)
		(layer "In6.Cu")
		(net "M_D_CPU1_SB_DQ<16>")
	)
	(arc
		(start 87.580216 -234.149392)
		(mid 87.52824 -233.965993)
		(end 87.392764 -233.831892)
		(width 0.088646)
		(layer "In6.Cu")
		(net "M_D_CPU1_SB_DQ<16>")
	)
	(arc
		(start 92.172282 -234.654344)
		(mid 91.895807 -234.721664)
		(end 91.62161 -234.645708)
		(width 0.088646)
		(layer "In6.Cu")
		(net "M_D_CPU1_SB_DQ<16>")
	)
	(arc
		(start 87.862664 -234.645962)
		(mid 87.660622 -234.447039)
		(end 87.58047 -234.175046)
		(width 0.088646)
		(layer "In6.Cu")
		(net "M_D_CPU1_SB_DQ<16>")
	)
	(arc
		(start 85.504782 -233.82732)
		(mid 85.321274 -233.782042)
		(end 85.139022 -233.832146)
		(width 0.088646)
		(layer "In6.Cu")
		(net "M_D_CPU1_SB_DQ<16>")
	)
	(arc
		(start 89.74201 -234.645708)
		(mid 89.554812 -234.595565)
		(end 89.367614 -234.645708)
		(width 0.088646)
		(layer "In6.Cu")
		(net "M_D_CPU1_SB_DQ<16>")
	)
	(arc
		(start 91.62161 -234.645708)
		(mid 91.434412 -234.595565)
		(end 91.247214 -234.645708)
		(width 0.088646)
		(layer "In6.Cu")
		(net "M_D_CPU1_SB_DQ<16>")
	)
	(arc
		(start 87.007954 -233.838242)
		(mid 86.729522 -233.908088)
		(end 86.45271 -233.832146)
		(width 0.088646)
		(layer "In6.Cu")
		(net "M_D_CPU1_SB_DQ<16>")
	)
	(arc
		(start 84.290916 -233.342434)
		(mid 84.243237 -233.159534)
		(end 84.112354 -233.023156)
		(width 0.088646)
		(layer "In6.Cu")
		(net "M_D_CPU1_SB_DQ<16>")
	)
	(arc
		(start 93.50121 -234.645708)
		(mid 93.314012 -234.595565)
		(end 93.126814 -234.645708)
		(width 0.088646)
		(layer "In6.Cu")
		(net "M_D_CPU1_SB_DQ<16>")
	)
	(arc
		(start 86.441788 -233.825796)
		(mid 86.259258 -233.781772)
		(end 86.078314 -233.831892)
		(width 0.088646)
		(layer "In6.Cu")
		(net "M_D_CPU1_SB_DQ<16>")
	)
	(arc
		(start 84.103464 -233.018076)
		(mid 84.013208 -232.980354)
		(end 83.916266 -232.967276)
		(width 0.088646)
		(layer "In6.Cu")
		(net "M_D_CPU1_SB_DQ<16>")
	)
	(arc
		(start 93.112082 -234.654344)
		(mid 92.835607 -234.721664)
		(end 92.56141 -234.645708)
		(width 0.088646)
		(layer "In6.Cu")
		(net "M_D_CPU1_SB_DQ<16>")
	)
	(arc
		(start 89.352882 -234.654344)
		(mid 89.076407 -234.721664)
		(end 88.80221 -234.645708)
		(width 0.088646)
		(layer "In6.Cu")
		(net "M_D_CPU1_SB_DQ<16>")
	)
	(arc
		(start 95.663766 -234.15625)
		(mid 95.354935 -234.415813)
		(end 95.018606 -234.638596)
		(width 0.088646)
		(layer "In6.Cu")
		(net "M_D_CPU1_SB_DQ<16>")
	)
	(arc
		(start 86.069424 -233.837226)
		(mid 85.790636 -233.907789)
		(end 85.513164 -233.832146)
		(width 0.088646)
		(layer "In6.Cu")
		(net "M_D_CPU1_SB_DQ<16>")
	)
	(arc
		(start 94.051882 -234.654344)
		(mid 93.775407 -234.721664)
		(end 93.50121 -234.645708)
		(width 0.088646)
		(layer "In6.Cu")
		(net "M_D_CPU1_SB_DQ<16>")
	)
	(arc
		(start 85.128608 -233.838242)
		(mid 84.850176 -233.908088)
		(end 84.573364 -233.832146)
		(width 0.088646)
		(layer "In6.Cu")
		(net "M_D_CPU1_SB_DQ<16>")
	)
	(arc
		(start 88.410542 -234.655614)
		(mid 88.135362 -234.721566)
		(end 87.862664 -234.645962)
		(width 0.088646)
		(layer "In6.Cu")
		(net "M_D_CPU1_SB_DQ<16>")
	)
	(arc
		(start 91.2368 -234.651804)
		(mid 90.958622 -234.721527)
		(end 90.682064 -234.645708)
		(width 0.088646)
		(layer "In6.Cu")
		(net "M_D_CPU1_SB_DQ<16>")
	)
	(arc
		(start 90.682064 -234.645708)
		(mid 90.494866 -234.595565)
		(end 90.307668 -234.645708)
		(width 0.088646)
		(layer "In6.Cu")
		(net "M_D_CPU1_SB_DQ<16>")
	)
	(arc
		(start 92.56141 -234.645708)
		(mid 92.374212 -234.595565)
		(end 92.187014 -234.645708)
		(width 0.088646)
		(layer "In6.Cu")
		(net "M_D_CPU1_SB_DQ<16>")
	)
	(segment
		(start 99.892612 -233.877866)
		(end 99.892612 -233.34218)
		(width 0.20066)
		(layer "F.Cu")
		(net "M_D_CPU1_SB_DQ<15>")
	)
	(segment
		(start 17.578578 -214.592408)
		(end 17.578578 -214.44077)
		(width 0.20066)
		(layer "F.Cu")
		(net "M_D_CPU1_SB_DQ<15>")
	)
	(segment
		(start 12.240514 -214.316564)
		(end 13.937742 -214.316564)
		(width 0.20066)
		(layer "F.Cu")
		(net "M_D_CPU1_SB_DQ<15>")
	)
	(segment
		(start 18.314162 -214.524082)
		(end 18.760694 -214.524082)
		(width 0.20066)
		(layer "F.Cu")
		(net "M_D_CPU1_SB_DQ<15>")
	)
	(segment
		(start 17.707102 -214.312246)
		(end 18.102326 -214.312246)
		(width 0.20066)
		(layer "F.Cu")
		(net "M_D_CPU1_SB_DQ<15>")
	)
	(segment
		(start 18.968212 -214.316564)
		(end 19.784314 -214.316564)
		(width 0.20066)
		(layer "F.Cu")
		(net "M_D_CPU1_SB_DQ<15>")
	)
	(segment
		(start 18.760694 -214.524082)
		(end 18.968212 -214.316564)
		(width 0.20066)
		(layer "F.Cu")
		(net "M_D_CPU1_SB_DQ<15>")
	)
	(segment
		(start 14.063726 -214.442548)
		(end 14.063726 -214.613236)
		(width 0.20066)
		(layer "F.Cu")
		(net "M_D_CPU1_SB_DQ<15>")
	)
	(segment
		(start 17.42948 -214.741506)
		(end 17.578578 -214.592408)
		(width 0.20066)
		(layer "F.Cu")
		(net "M_D_CPU1_SB_DQ<15>")
	)
	(segment
		(start 13.937742 -214.316564)
		(end 14.063726 -214.442548)
		(width 0.20066)
		(layer "F.Cu")
		(net "M_D_CPU1_SB_DQ<15>")
	)
	(segment
		(start 99.892866 -233.87812)
		(end 99.892612 -233.877866)
		(width 0.20066)
		(layer "F.Cu")
		(net "M_D_CPU1_SB_DQ<15>")
	)
	(segment
		(start 14.560042 -214.75573)
		(end 14.574266 -214.741506)
		(width 0.101854)
		(layer "F.Cu")
		(net "M_D_CPU1_SB_DQ<15>")
	)
	(segment
		(start 14.063726 -214.613236)
		(end 14.20622 -214.75573)
		(width 0.20066)
		(layer "F.Cu")
		(net "M_D_CPU1_SB_DQ<15>")
	)
	(segment
		(start 14.20622 -214.75573)
		(end 14.560042 -214.75573)
		(width 0.20066)
		(layer "F.Cu")
		(net "M_D_CPU1_SB_DQ<15>")
	)
	(segment
		(start 14.812264 -214.741506)
		(end 16.885158 -214.741506)
		(width 0.1016)
		(layer "F.Cu")
		(net "M_D_CPU1_SB_DQ<15>")
	)
	(segment
		(start 20.889214 -214.316564)
		(end 19.784314 -214.316564)
		(width 0.20066)
		(layer "F.Cu")
		(net "M_D_CPU1_SB_DQ<15>")
	)
	(segment
		(start 17.578578 -214.44077)
		(end 17.707102 -214.312246)
		(width 0.20066)
		(layer "F.Cu")
		(net "M_D_CPU1_SB_DQ<15>")
	)
	(segment
		(start 14.574266 -214.741506)
		(end 14.812264 -214.741506)
		(width 0.101854)
		(layer "F.Cu")
		(net "M_D_CPU1_SB_DQ<15>")
	)
	(segment
		(start 16.885158 -214.741506)
		(end 17.42948 -214.741506)
		(width 0.20066)
		(layer "F.Cu")
		(net "M_D_CPU1_SB_DQ<15>")
	)
	(segment
		(start 18.102326 -214.312246)
		(end 18.314162 -214.524082)
		(width 0.20066)
		(layer "F.Cu")
		(net "M_D_CPU1_SB_DQ<15>")
	)
	(segment
		(start 39.826438 -205.394814)
		(end 35.171888 -205.394814)
		(width 0.18288)
		(layer "In11.Cu")
		(net "M_D_CPU1_SB_DQ<15>")
	)
	(segment
		(start 28.935426 -206.938626)
		(end 27.811222 -206.938626)
		(width 0.18288)
		(layer "In11.Cu")
		(net "M_D_CPU1_SB_DQ<15>")
	)
	(segment
		(start 87.488014 -230.41102)
		(end 87.473282 -230.402384)
		(width 0.088646)
		(layer "In11.Cu")
		(net "M_D_CPU1_SB_DQ<15>")
	)
	(segment
		(start 90.692478 -230.404924)
		(end 90.682064 -230.41102)
		(width 0.088646)
		(layer "In11.Cu")
		(net "M_D_CPU1_SB_DQ<15>")
	)
	(segment
		(start 26.917142 -207.531208)
		(end 26.917142 -207.131666)
		(width 0.18288)
		(layer "In11.Cu")
		(net "M_D_CPU1_SB_DQ<15>")
	)
	(segment
		(start 33.031938 -206.244698)
		(end 31.026354 -206.244698)
		(width 0.18288)
		(layer "In11.Cu")
		(net "M_D_CPU1_SB_DQ<15>")
	)
	(segment
		(start 59.887358 -207.878426)
		(end 59.0169 -207.007968)
		(width 0.18288)
		(layer "In11.Cu")
		(net "M_D_CPU1_SB_DQ<15>")
	)
	(segment
		(start 23.00859 -209.852006)
		(end 22.785578 -210.075018)
		(width 0.18288)
		(layer "In11.Cu")
		(net "M_D_CPU1_SB_DQ<15>")
	)
	(segment
		(start 98.295714 -232.852722)
		(end 98.2853 -232.846626)
		(width 0.088646)
		(layer "In11.Cu")
		(net "M_D_CPU1_SB_DQ<15>")
	)
	(segment
		(start 40.685212 -206.253588)
		(end 39.826438 -205.394814)
		(width 0.18288)
		(layer "In11.Cu")
		(net "M_D_CPU1_SB_DQ<15>")
	)
	(segment
		(start 86.548214 -230.41102)
		(end 86.533482 -230.402384)
		(width 0.088646)
		(layer "In11.Cu")
		(net "M_D_CPU1_SB_DQ<15>")
	)
	(segment
		(start 45.41266 -206.018384)
		(end 44.253912 -206.018384)
		(width 0.18288)
		(layer "In11.Cu")
		(net "M_D_CPU1_SB_DQ<15>")
	)
	(segment
		(start 92.187014 -230.41102)
		(end 92.172282 -230.402384)
		(width 0.088646)
		(layer "In11.Cu")
		(net "M_D_CPU1_SB_DQ<15>")
	)
	(segment
		(start 85.608414 -230.41102)
		(end 85.593682 -230.402384)
		(width 0.088646)
		(layer "In11.Cu")
		(net "M_D_CPU1_SB_DQ<15>")
	)
	(segment
		(start 26.917142 -207.131666)
		(end 26.724102 -206.938626)
		(width 0.18288)
		(layer "In11.Cu")
		(net "M_D_CPU1_SB_DQ<15>")
	)
	(segment
		(start 83.3628 -228.939598)
		(end 82.629502 -228.2063)
		(width 0.088646)
		(layer "In11.Cu")
		(net "M_D_CPU1_SB_DQ<15>")
	)
	(segment
		(start 88.427814 -230.41102)
		(end 88.413082 -230.402384)
		(width 0.088646)
		(layer "In11.Cu")
		(net "M_D_CPU1_SB_DQ<15>")
	)
	(segment
		(start 50.21453 -205.395068)
		(end 49.36617 -206.243428)
		(width 0.18288)
		(layer "In11.Cu")
		(net "M_D_CPU1_SB_DQ<15>")
	)
	(segment
		(start 44.253912 -206.018384)
		(end 44.018708 -206.253588)
		(width 0.18288)
		(layer "In11.Cu")
		(net "M_D_CPU1_SB_DQ<15>")
	)
	(segment
		(start 33.16351 -206.37627)
		(end 33.031938 -206.244698)
		(width 0.18288)
		(layer "In11.Cu")
		(net "M_D_CPU1_SB_DQ<15>")
	)
	(segment
		(start 25.074626 -206.938626)
		(end 22.857714 -209.155538)
		(width 0.18288)
		(layer "In11.Cu")
		(net "M_D_CPU1_SB_DQ<15>")
	)
	(segment
		(start 81.548224 -228.2063)
		(end 71.12508 -217.783156)
		(width 0.18288)
		(layer "In11.Cu")
		(net "M_D_CPU1_SB_DQ<15>")
	)
	(segment
		(start 29.138626 -207.141826)
		(end 28.935426 -206.938626)
		(width 0.18288)
		(layer "In11.Cu")
		(net "M_D_CPU1_SB_DQ<15>")
	)
	(segment
		(start 84.386166 -230.335328)
		(end 84.26069 -230.335328)
		(width 0.088646)
		(layer "In11.Cu")
		(net "M_D_CPU1_SB_DQ<15>")
	)
	(segment
		(start 21.480526 -213.725252)
		(end 20.889214 -214.316564)
		(width 0.18288)
		(layer "In11.Cu")
		(net "M_D_CPU1_SB_DQ<15>")
	)
	(segment
		(start 22.512782 -210.075018)
		(end 22.361906 -209.924142)
		(width 0.18288)
		(layer "In11.Cu")
		(net "M_D_CPU1_SB_DQ<15>")
	)
	(segment
		(start 95.95231 -232.042462)
		(end 95.946214 -232.038906)
		(width 0.088646)
		(layer "In11.Cu")
		(net "M_D_CPU1_SB_DQ<15>")
	)
	(segment
		(start 35.171888 -205.394814)
		(end 34.190432 -206.37627)
		(width 0.18288)
		(layer "In11.Cu")
		(net "M_D_CPU1_SB_DQ<15>")
	)
	(segment
		(start 54.872128 -205.395068)
		(end 50.21453 -205.395068)
		(width 0.18288)
		(layer "In11.Cu")
		(net "M_D_CPU1_SB_DQ<15>")
	)
	(segment
		(start 26.724102 -206.938626)
		(end 25.074626 -206.938626)
		(width 0.18288)
		(layer "In11.Cu")
		(net "M_D_CPU1_SB_DQ<15>")
	)
	(segment
		(start 69.24929 -213.254844)
		(end 66.713862 -210.719416)
		(width 0.18288)
		(layer "In11.Cu")
		(net "M_D_CPU1_SB_DQ<15>")
	)
	(segment
		(start 56.485028 -207.007968)
		(end 54.872128 -205.395068)
		(width 0.18288)
		(layer "In11.Cu")
		(net "M_D_CPU1_SB_DQ<15>")
	)
	(segment
		(start 90.307668 -230.41102)
		(end 90.297254 -230.404924)
		(width 0.088646)
		(layer "In11.Cu")
		(net "M_D_CPU1_SB_DQ<15>")
	)
	(segment
		(start 22.08911 -209.924142)
		(end 21.480526 -210.532726)
		(width 0.18288)
		(layer "In11.Cu")
		(net "M_D_CPU1_SB_DQ<15>")
	)
	(segment
		(start 95.758762 -231.714548)
		(end 95.758762 -231.69245)
		(width 0.088646)
		(layer "In11.Cu")
		(net "M_D_CPU1_SB_DQ<15>")
	)
	(segment
		(start 93.126814 -230.41102)
		(end 93.112082 -230.402384)
		(width 0.088646)
		(layer "In11.Cu")
		(net "M_D_CPU1_SB_DQ<15>")
	)
	(segment
		(start 30.129226 -207.141826)
		(end 29.138626 -207.141826)
		(width 0.18288)
		(layer "In11.Cu")
		(net "M_D_CPU1_SB_DQ<15>")
	)
	(segment
		(start 34.190432 -206.37627)
		(end 33.16351 -206.37627)
		(width 0.18288)
		(layer "In11.Cu")
		(net "M_D_CPU1_SB_DQ<15>")
	)
	(segment
		(start 95.946214 -232.038906)
		(end 95.937324 -232.033826)
		(width 0.088646)
		(layer "In11.Cu")
		(net "M_D_CPU1_SB_DQ<15>")
	)
	(segment
		(start 22.785578 -210.075018)
		(end 22.512782 -210.075018)
		(width 0.18288)
		(layer "In11.Cu")
		(net "M_D_CPU1_SB_DQ<15>")
	)
	(segment
		(start 96.805496 -232.844086)
		(end 96.790764 -232.852722)
		(width 0.088646)
		(layer "In11.Cu")
		(net "M_D_CPU1_SB_DQ<15>")
	)
	(segment
		(start 83.3628 -229.437438)
		(end 83.3628 -228.939598)
		(width 0.088646)
		(layer "In11.Cu")
		(net "M_D_CPU1_SB_DQ<15>")
	)
	(segment
		(start 23.00859 -209.57921)
		(end 23.00859 -209.852006)
		(width 0.18288)
		(layer "In11.Cu")
		(net "M_D_CPU1_SB_DQ<15>")
	)
	(segment
		(start 99.579938 -233.34218)
		(end 99.514406 -233.276648)
		(width 0.088646)
		(layer "In11.Cu")
		(net "M_D_CPU1_SB_DQ<15>")
	)
	(segment
		(start 71.12508 -217.783156)
		(end 69.24929 -213.254844)
		(width 0.18288)
		(layer "In11.Cu")
		(net "M_D_CPU1_SB_DQ<15>")
	)
	(segment
		(start 63.103506 -207.878426)
		(end 59.887358 -207.878426)
		(width 0.18288)
		(layer "In11.Cu")
		(net "M_D_CPU1_SB_DQ<15>")
	)
	(segment
		(start 27.110182 -207.724248)
		(end 26.917142 -207.531208)
		(width 0.18288)
		(layer "In11.Cu")
		(net "M_D_CPU1_SB_DQ<15>")
	)
	(segment
		(start 22.857714 -209.428334)
		(end 23.00859 -209.57921)
		(width 0.18288)
		(layer "In11.Cu")
		(net "M_D_CPU1_SB_DQ<15>")
	)
	(segment
		(start 94.066614 -230.41102)
		(end 94.051882 -230.402384)
		(width 0.088646)
		(layer "In11.Cu")
		(net "M_D_CPU1_SB_DQ<15>")
	)
	(segment
		(start 21.480526 -210.532726)
		(end 21.480526 -213.725252)
		(width 0.18288)
		(layer "In11.Cu")
		(net "M_D_CPU1_SB_DQ<15>")
	)
	(segment
		(start 98.680524 -232.846626)
		(end 98.67011 -232.852722)
		(width 0.088646)
		(layer "In11.Cu")
		(net "M_D_CPU1_SB_DQ<15>")
	)
	(segment
		(start 27.425142 -207.724248)
		(end 27.110182 -207.724248)
		(width 0.18288)
		(layer "In11.Cu")
		(net "M_D_CPU1_SB_DQ<15>")
	)
	(segment
		(start 49.36617 -206.243428)
		(end 45.637704 -206.243428)
		(width 0.18288)
		(layer "In11.Cu")
		(net "M_D_CPU1_SB_DQ<15>")
	)
	(segment
		(start 95.006414 -230.41102)
		(end 94.991682 -230.402384)
		(width 0.088646)
		(layer "In11.Cu")
		(net "M_D_CPU1_SB_DQ<15>")
	)
	(segment
		(start 22.857714 -209.155538)
		(end 22.857714 -209.428334)
		(width 0.18288)
		(layer "In11.Cu")
		(net "M_D_CPU1_SB_DQ<15>")
	)
	(segment
		(start 82.37347 -228.2063)
		(end 81.548224 -228.2063)
		(width 0.18288)
		(layer "In11.Cu")
		(net "M_D_CPU1_SB_DQ<15>")
	)
	(segment
		(start 66.713862 -210.719416)
		(end 65.944496 -210.719416)
		(width 0.18288)
		(layer "In11.Cu")
		(net "M_D_CPU1_SB_DQ<15>")
	)
	(segment
		(start 22.361906 -209.924142)
		(end 22.08911 -209.924142)
		(width 0.18288)
		(layer "In11.Cu")
		(net "M_D_CPU1_SB_DQ<15>")
	)
	(segment
		(start 99.892612 -233.34218)
		(end 99.579938 -233.34218)
		(width 0.088646)
		(layer "In11.Cu")
		(net "M_D_CPU1_SB_DQ<15>")
	)
	(segment
		(start 96.416368 -232.852722)
		(end 96.407478 -232.847642)
		(width 0.088646)
		(layer "In11.Cu")
		(net "M_D_CPU1_SB_DQ<15>")
	)
	(segment
		(start 95.01251 -230.414576)
		(end 95.006414 -230.41102)
		(width 0.088646)
		(layer "In11.Cu")
		(net "M_D_CPU1_SB_DQ<15>")
	)
	(segment
		(start 65.944496 -210.719416)
		(end 63.103506 -207.878426)
		(width 0.18288)
		(layer "In11.Cu")
		(net "M_D_CPU1_SB_DQ<15>")
	)
	(segment
		(start 27.618182 -207.131666)
		(end 27.618182 -207.531208)
		(width 0.18288)
		(layer "In11.Cu")
		(net "M_D_CPU1_SB_DQ<15>")
	)
	(segment
		(start 45.637704 -206.243428)
		(end 45.41266 -206.018384)
		(width 0.18288)
		(layer "In11.Cu")
		(net "M_D_CPU1_SB_DQ<15>")
	)
	(segment
		(start 89.367614 -230.41102)
		(end 89.352882 -230.402384)
		(width 0.088646)
		(layer "In11.Cu")
		(net "M_D_CPU1_SB_DQ<15>")
	)
	(segment
		(start 44.018708 -206.253588)
		(end 40.685212 -206.253588)
		(width 0.18288)
		(layer "In11.Cu")
		(net "M_D_CPU1_SB_DQ<15>")
	)
	(segment
		(start 82.629502 -228.2063)
		(end 82.37347 -228.2063)
		(width 0.088646)
		(layer "In11.Cu")
		(net "M_D_CPU1_SB_DQ<15>")
	)
	(segment
		(start 59.0169 -207.007968)
		(end 56.485028 -207.007968)
		(width 0.18288)
		(layer "In11.Cu")
		(net "M_D_CPU1_SB_DQ<15>")
	)
	(segment
		(start 27.811222 -206.938626)
		(end 27.618182 -207.131666)
		(width 0.18288)
		(layer "In11.Cu")
		(net "M_D_CPU1_SB_DQ<15>")
	)
	(segment
		(start 95.476568 -231.224836)
		(end 95.467678 -231.219756)
		(width 0.088646)
		(layer "In11.Cu")
		(net "M_D_CPU1_SB_DQ<15>")
	)
	(segment
		(start 31.026354 -206.244698)
		(end 30.129226 -207.141826)
		(width 0.18288)
		(layer "In11.Cu")
		(net "M_D_CPU1_SB_DQ<15>")
	)
	(segment
		(start 27.618182 -207.531208)
		(end 27.425142 -207.724248)
		(width 0.18288)
		(layer "In11.Cu")
		(net "M_D_CPU1_SB_DQ<15>")
	)
	(segment
		(start 84.26069 -230.335328)
		(end 83.3628 -229.437438)
		(width 0.088646)
		(layer "In11.Cu")
		(net "M_D_CPU1_SB_DQ<15>")
	)
	(arc
		(start 99.235768 -232.852722)
		(mid 98.958955 -232.776852)
		(end 98.680524 -232.846626)
		(width 0.088646)
		(layer "In11.Cu")
		(net "M_D_CPU1_SB_DQ<15>")
	)
	(arc
		(start 86.533482 -230.402384)
		(mid 86.257007 -230.335064)
		(end 85.98281 -230.41102)
		(width 0.088646)
		(layer "In11.Cu")
		(net "M_D_CPU1_SB_DQ<15>")
	)
	(arc
		(start 90.682064 -230.41102)
		(mid 90.494866 -230.461163)
		(end 90.307668 -230.41102)
		(width 0.088646)
		(layer "In11.Cu")
		(net "M_D_CPU1_SB_DQ<15>")
	)
	(arc
		(start 87.473282 -230.402384)
		(mid 87.196807 -230.335064)
		(end 86.92261 -230.41102)
		(width 0.088646)
		(layer "In11.Cu")
		(net "M_D_CPU1_SB_DQ<15>")
	)
	(arc
		(start 95.937324 -232.033826)
		(mid 95.80641 -231.897466)
		(end 95.758762 -231.714548)
		(width 0.088646)
		(layer "In11.Cu")
		(net "M_D_CPU1_SB_DQ<15>")
	)
	(arc
		(start 89.352882 -230.402384)
		(mid 89.076407 -230.335064)
		(end 88.80221 -230.41102)
		(width 0.088646)
		(layer "In11.Cu")
		(net "M_D_CPU1_SB_DQ<15>")
	)
	(arc
		(start 88.413082 -230.402384)
		(mid 88.136607 -230.335064)
		(end 87.86241 -230.41102)
		(width 0.088646)
		(layer "In11.Cu")
		(net "M_D_CPU1_SB_DQ<15>")
	)
	(arc
		(start 98.67011 -232.852722)
		(mid 98.482912 -232.902865)
		(end 98.295714 -232.852722)
		(width 0.088646)
		(layer "In11.Cu")
		(net "M_D_CPU1_SB_DQ<15>")
	)
	(arc
		(start 89.74201 -230.41102)
		(mid 89.554812 -230.461163)
		(end 89.367614 -230.41102)
		(width 0.088646)
		(layer "In11.Cu")
		(net "M_D_CPU1_SB_DQ<15>")
	)
	(arc
		(start 95.467678 -231.219756)
		(mid 95.336764 -231.083396)
		(end 95.289116 -230.900478)
		(width 0.088646)
		(layer "In11.Cu")
		(net "M_D_CPU1_SB_DQ<15>")
	)
	(arc
		(start 99.514406 -233.276648)
		(mid 99.425318 -233.031663)
		(end 99.235768 -232.852722)
		(width 0.088646)
		(layer "In11.Cu")
		(net "M_D_CPU1_SB_DQ<15>")
	)
	(arc
		(start 96.407478 -232.847642)
		(mid 96.276564 -232.711282)
		(end 96.228916 -232.528364)
		(width 0.088646)
		(layer "In11.Cu")
		(net "M_D_CPU1_SB_DQ<15>")
	)
	(arc
		(start 87.86241 -230.41102)
		(mid 87.675212 -230.461163)
		(end 87.488014 -230.41102)
		(width 0.088646)
		(layer "In11.Cu")
		(net "M_D_CPU1_SB_DQ<15>")
	)
	(arc
		(start 91.62161 -230.41102)
		(mid 91.434412 -230.461163)
		(end 91.247214 -230.41102)
		(width 0.088646)
		(layer "In11.Cu")
		(net "M_D_CPU1_SB_DQ<15>")
	)
	(arc
		(start 84.668614 -230.41102)
		(mid 84.532372 -230.354586)
		(end 84.386166 -230.335328)
		(width 0.088646)
		(layer "In11.Cu")
		(net "M_D_CPU1_SB_DQ<15>")
	)
	(arc
		(start 95.289116 -230.900478)
		(mid 95.215125 -230.620912)
		(end 95.01251 -230.414576)
		(width 0.088646)
		(layer "In11.Cu")
		(net "M_D_CPU1_SB_DQ<15>")
	)
	(arc
		(start 95.758762 -231.69245)
		(mid 95.677851 -231.422322)
		(end 95.476568 -231.224836)
		(width 0.088646)
		(layer "In11.Cu")
		(net "M_D_CPU1_SB_DQ<15>")
	)
	(arc
		(start 86.92261 -230.41102)
		(mid 86.735412 -230.461163)
		(end 86.548214 -230.41102)
		(width 0.088646)
		(layer "In11.Cu")
		(net "M_D_CPU1_SB_DQ<15>")
	)
	(arc
		(start 91.247214 -230.41102)
		(mid 90.970655 -230.335277)
		(end 90.692478 -230.404924)
		(width 0.088646)
		(layer "In11.Cu")
		(net "M_D_CPU1_SB_DQ<15>")
	)
	(arc
		(start 96.790764 -232.852722)
		(mid 96.603566 -232.902865)
		(end 96.416368 -232.852722)
		(width 0.088646)
		(layer "In11.Cu")
		(net "M_D_CPU1_SB_DQ<15>")
	)
	(arc
		(start 90.297254 -230.404924)
		(mid 90.018822 -230.335078)
		(end 89.74201 -230.41102)
		(width 0.088646)
		(layer "In11.Cu")
		(net "M_D_CPU1_SB_DQ<15>")
	)
	(arc
		(start 92.56141 -230.41102)
		(mid 92.374212 -230.461163)
		(end 92.187014 -230.41102)
		(width 0.088646)
		(layer "In11.Cu")
		(net "M_D_CPU1_SB_DQ<15>")
	)
	(arc
		(start 92.172282 -230.402384)
		(mid 91.895807 -230.335064)
		(end 91.62161 -230.41102)
		(width 0.088646)
		(layer "In11.Cu")
		(net "M_D_CPU1_SB_DQ<15>")
	)
	(arc
		(start 85.593682 -230.402384)
		(mid 85.317207 -230.335064)
		(end 85.04301 -230.41102)
		(width 0.088646)
		(layer "In11.Cu")
		(net "M_D_CPU1_SB_DQ<15>")
	)
	(arc
		(start 97.730564 -232.852722)
		(mid 97.543366 -232.902865)
		(end 97.356168 -232.852722)
		(width 0.088646)
		(layer "In11.Cu")
		(net "M_D_CPU1_SB_DQ<15>")
	)
	(arc
		(start 85.04301 -230.41102)
		(mid 84.855812 -230.461163)
		(end 84.668614 -230.41102)
		(width 0.088646)
		(layer "In11.Cu")
		(net "M_D_CPU1_SB_DQ<15>")
	)
	(arc
		(start 98.2853 -232.846626)
		(mid 98.007122 -232.776903)
		(end 97.730564 -232.852722)
		(width 0.088646)
		(layer "In11.Cu")
		(net "M_D_CPU1_SB_DQ<15>")
	)
	(arc
		(start 97.356168 -232.852722)
		(mid 97.081969 -232.776887)
		(end 96.805496 -232.844086)
		(width 0.088646)
		(layer "In11.Cu")
		(net "M_D_CPU1_SB_DQ<15>")
	)
	(arc
		(start 85.98281 -230.41102)
		(mid 85.795612 -230.461163)
		(end 85.608414 -230.41102)
		(width 0.088646)
		(layer "In11.Cu")
		(net "M_D_CPU1_SB_DQ<15>")
	)
	(arc
		(start 94.051882 -230.402384)
		(mid 93.775407 -230.335064)
		(end 93.50121 -230.41102)
		(width 0.088646)
		(layer "In11.Cu")
		(net "M_D_CPU1_SB_DQ<15>")
	)
	(arc
		(start 93.50121 -230.41102)
		(mid 93.314012 -230.461163)
		(end 93.126814 -230.41102)
		(width 0.088646)
		(layer "In11.Cu")
		(net "M_D_CPU1_SB_DQ<15>")
	)
	(arc
		(start 96.228916 -232.528364)
		(mid 96.154925 -232.248798)
		(end 95.95231 -232.042462)
		(width 0.088646)
		(layer "In11.Cu")
		(net "M_D_CPU1_SB_DQ<15>")
	)
	(arc
		(start 94.991682 -230.402384)
		(mid 94.715207 -230.335064)
		(end 94.44101 -230.41102)
		(width 0.088646)
		(layer "In11.Cu")
		(net "M_D_CPU1_SB_DQ<15>")
	)
	(arc
		(start 88.80221 -230.41102)
		(mid 88.615012 -230.461163)
		(end 88.427814 -230.41102)
		(width 0.088646)
		(layer "In11.Cu")
		(net "M_D_CPU1_SB_DQ<15>")
	)
	(arc
		(start 93.112082 -230.402384)
		(mid 92.835607 -230.335064)
		(end 92.56141 -230.41102)
		(width 0.088646)
		(layer "In11.Cu")
		(net "M_D_CPU1_SB_DQ<15>")
	)
	(arc
		(start 94.44101 -230.41102)
		(mid 94.253812 -230.461163)
		(end 94.066614 -230.41102)
		(width 0.088646)
		(layer "In11.Cu")
		(net "M_D_CPU1_SB_DQ<15>")
	)
	(segment
		(start 17.518126 -215.591644)
		(end 17.66189 -215.735408)
		(width 0.20066)
		(layer "F.Cu")
		(net "M_D_CPU1_SB_DQ<14>")
	)
	(segment
		(start 100.362766 -234.691936)
		(end 100.362766 -234.15625)
		(width 0.20066)
		(layer "F.Cu")
		(net "M_D_CPU1_SB_DQ<14>")
	)
	(segment
		(start 13.387578 -216.016586)
		(end 13.82268 -215.581484)
		(width 0.20066)
		(layer "F.Cu")
		(net "M_D_CPU1_SB_DQ<14>")
	)
	(segment
		(start 14.570202 -215.591644)
		(end 14.825218 -215.591644)
		(width 0.101854)
		(layer "F.Cu")
		(net "M_D_CPU1_SB_DQ<14>")
	)
	(segment
		(start 18.46961 -216.016586)
		(end 19.784314 -216.016586)
		(width 0.20066)
		(layer "F.Cu")
		(net "M_D_CPU1_SB_DQ<14>")
	)
	(segment
		(start 14.560042 -215.581484)
		(end 14.570202 -215.591644)
		(width 0.101854)
		(layer "F.Cu")
		(net "M_D_CPU1_SB_DQ<14>")
	)
	(segment
		(start 20.889214 -216.016586)
		(end 19.784314 -216.016586)
		(width 0.20066)
		(layer "F.Cu")
		(net "M_D_CPU1_SB_DQ<14>")
	)
	(segment
		(start 16.885158 -215.591644)
		(end 17.518126 -215.591644)
		(width 0.20066)
		(layer "F.Cu")
		(net "M_D_CPU1_SB_DQ<14>")
	)
	(segment
		(start 100.362512 -234.69219)
		(end 100.362766 -234.691936)
		(width 0.20066)
		(layer "F.Cu")
		(net "M_D_CPU1_SB_DQ<14>")
	)
	(segment
		(start 13.82268 -215.581484)
		(end 14.560042 -215.581484)
		(width 0.20066)
		(layer "F.Cu")
		(net "M_D_CPU1_SB_DQ<14>")
	)
	(segment
		(start 17.66189 -215.735408)
		(end 17.66189 -216.061036)
		(width 0.20066)
		(layer "F.Cu")
		(net "M_D_CPU1_SB_DQ<14>")
	)
	(segment
		(start 17.829276 -216.228422)
		(end 18.257774 -216.228422)
		(width 0.20066)
		(layer "F.Cu")
		(net "M_D_CPU1_SB_DQ<14>")
	)
	(segment
		(start 14.825218 -215.591644)
		(end 16.885158 -215.591644)
		(width 0.1016)
		(layer "F.Cu")
		(net "M_D_CPU1_SB_DQ<14>")
	)
	(segment
		(start 12.240514 -216.016586)
		(end 13.387578 -216.016586)
		(width 0.20066)
		(layer "F.Cu")
		(net "M_D_CPU1_SB_DQ<14>")
	)
	(segment
		(start 17.66189 -216.061036)
		(end 17.829276 -216.228422)
		(width 0.20066)
		(layer "F.Cu")
		(net "M_D_CPU1_SB_DQ<14>")
	)
	(segment
		(start 18.257774 -216.228422)
		(end 18.46961 -216.016586)
		(width 0.20066)
		(layer "F.Cu")
		(net "M_D_CPU1_SB_DQ<14>")
	)
	(segment
		(start 91.162124 -231.21874)
		(end 91.15171 -231.224836)
		(width 0.088646)
		(layer "In11.Cu")
		(net "M_D_CPU1_SB_DQ<14>")
	)
	(segment
		(start 62.211458 -209.683858)
		(end 59.183778 -209.683858)
		(width 0.18288)
		(layer "In11.Cu")
		(net "M_D_CPU1_SB_DQ<14>")
	)
	(segment
		(start 98.765614 -233.666538)
		(end 98.7552 -233.660442)
		(width 0.088646)
		(layer "In11.Cu")
		(net "M_D_CPU1_SB_DQ<14>")
	)
	(segment
		(start 96.886014 -233.666538)
		(end 96.871282 -233.657902)
		(width 0.088646)
		(layer "In11.Cu")
		(net "M_D_CPU1_SB_DQ<14>")
	)
	(segment
		(start 23.703026 -211.906104)
		(end 23.509986 -212.099144)
		(width 0.18288)
		(layer "In11.Cu")
		(net "M_D_CPU1_SB_DQ<14>")
	)
	(segment
		(start 21.447252 -215.458548)
		(end 20.889214 -216.016586)
		(width 0.18288)
		(layer "In11.Cu")
		(net "M_D_CPU1_SB_DQ<14>")
	)
	(segment
		(start 23.703026 -214.878158)
		(end 23.122636 -215.458548)
		(width 0.18288)
		(layer "In11.Cu")
		(net "M_D_CPU1_SB_DQ<14>")
	)
	(segment
		(start 90.222578 -231.21874)
		(end 90.212164 -231.224836)
		(width 0.088646)
		(layer "In11.Cu")
		(net "M_D_CPU1_SB_DQ<14>")
	)
	(segment
		(start 31.26994 -207.94218)
		(end 30.354778 -208.857342)
		(width 0.18288)
		(layer "In11.Cu")
		(net "M_D_CPU1_SB_DQ<14>")
	)
	(segment
		(start 55.944262 -208.793842)
		(end 54.245256 -207.094836)
		(width 0.18288)
		(layer "In11.Cu")
		(net "M_D_CPU1_SB_DQ<14>")
	)
	(segment
		(start 88.347296 -231.2162)
		(end 88.332564 -231.224836)
		(width 0.088646)
		(layer "In11.Cu")
		(net "M_D_CPU1_SB_DQ<14>")
	)
	(segment
		(start 23.362412 -214.202264)
		(end 23.509986 -214.202264)
		(width 0.18288)
		(layer "In11.Cu")
		(net "M_D_CPU1_SB_DQ<14>")
	)
	(segment
		(start 23.169372 -212.292184)
		(end 23.169372 -212.607144)
		(width 0.18288)
		(layer "In11.Cu")
		(net "M_D_CPU1_SB_DQ<14>")
	)
	(segment
		(start 23.169372 -212.607144)
		(end 23.362412 -212.800184)
		(width 0.18288)
		(layer "In11.Cu")
		(net "M_D_CPU1_SB_DQ<14>")
	)
	(segment
		(start 34.587942 -207.94218)
		(end 34.069274 -207.94218)
		(width 0.18288)
		(layer "In11.Cu")
		(net "M_D_CPU1_SB_DQ<14>")
	)
	(segment
		(start 23.362412 -213.501224)
		(end 23.169372 -213.694264)
		(width 0.18288)
		(layer "In11.Cu")
		(net "M_D_CPU1_SB_DQ<14>")
	)
	(segment
		(start 30.354778 -208.857342)
		(end 25.69591 -208.857342)
		(width 0.18288)
		(layer "In11.Cu")
		(net "M_D_CPU1_SB_DQ<14>")
	)
	(segment
		(start 39.25062 -207.09382)
		(end 35.436302 -207.09382)
		(width 0.18288)
		(layer "In11.Cu")
		(net "M_D_CPU1_SB_DQ<14>")
	)
	(segment
		(start 92.106496 -231.2162)
		(end 92.091764 -231.224836)
		(width 0.088646)
		(layer "In11.Cu")
		(net "M_D_CPU1_SB_DQ<14>")
	)
	(segment
		(start 23.509986 -213.501224)
		(end 23.362412 -213.501224)
		(width 0.18288)
		(layer "In11.Cu")
		(net "M_D_CPU1_SB_DQ<14>")
	)
	(segment
		(start 84.26069 -231.275636)
		(end 84.099908 -231.114854)
		(width 0.088646)
		(layer "In11.Cu")
		(net "M_D_CPU1_SB_DQ<14>")
	)
	(segment
		(start 23.703026 -210.850226)
		(end 23.703026 -211.906104)
		(width 0.18288)
		(layer "In11.Cu")
		(net "M_D_CPU1_SB_DQ<14>")
	)
	(segment
		(start 48.372268 -208.04759)
		(end 48.266858 -207.94218)
		(width 0.18288)
		(layer "In11.Cu")
		(net "M_D_CPU1_SB_DQ<14>")
	)
	(segment
		(start 82.94624 -229.7557)
		(end 82.94624 -229.478586)
		(width 0.088646)
		(layer "In11.Cu")
		(net "M_D_CPU1_SB_DQ<14>")
	)
	(segment
		(start 64.698626 -211.180426)
		(end 63.708026 -211.180426)
		(width 0.18288)
		(layer "In11.Cu")
		(net "M_D_CPU1_SB_DQ<14>")
	)
	(segment
		(start 23.362412 -212.800184)
		(end 23.509986 -212.800184)
		(width 0.18288)
		(layer "In11.Cu")
		(net "M_D_CPU1_SB_DQ<14>")
	)
	(segment
		(start 89.287096 -231.2162)
		(end 89.272364 -231.224836)
		(width 0.088646)
		(layer "In11.Cu")
		(net "M_D_CPU1_SB_DQ<14>")
	)
	(segment
		(start 94.349316 -232.528364)
		(end 94.349316 -232.518458)
		(width 0.088646)
		(layer "In11.Cu")
		(net "M_D_CPU1_SB_DQ<14>")
	)
	(segment
		(start 94.066868 -232.038906)
		(end 94.057978 -232.033826)
		(width 0.088646)
		(layer "In11.Cu")
		(net "M_D_CPU1_SB_DQ<14>")
	)
	(segment
		(start 23.509986 -212.800184)
		(end 23.703026 -212.993224)
		(width 0.18288)
		(layer "In11.Cu")
		(net "M_D_CPU1_SB_DQ<14>")
	)
	(segment
		(start 81.09077 -229.2223)
		(end 70.230238 -218.361768)
		(width 0.18288)
		(layer "In11.Cu")
		(net "M_D_CPU1_SB_DQ<14>")
	)
	(segment
		(start 45.193966 -207.798924)
		(end 44.305982 -207.798924)
		(width 0.18288)
		(layer "In11.Cu")
		(net "M_D_CPU1_SB_DQ<14>")
	)
	(segment
		(start 23.362412 -212.099144)
		(end 23.169372 -212.292184)
		(width 0.18288)
		(layer "In11.Cu")
		(net "M_D_CPU1_SB_DQ<14>")
	)
	(segment
		(start 84.099908 -231.114854)
		(end 84.099908 -230.909368)
		(width 0.088646)
		(layer "In11.Cu")
		(net "M_D_CPU1_SB_DQ<14>")
	)
	(segment
		(start 93.046296 -231.2162)
		(end 93.031564 -231.224836)
		(width 0.088646)
		(layer "In11.Cu")
		(net "M_D_CPU1_SB_DQ<14>")
	)
	(segment
		(start 25.69591 -208.857342)
		(end 23.703026 -210.850226)
		(width 0.18288)
		(layer "In11.Cu")
		(net "M_D_CPU1_SB_DQ<14>")
	)
	(segment
		(start 45.337222 -207.94218)
		(end 45.193966 -207.798924)
		(width 0.18288)
		(layer "In11.Cu")
		(net "M_D_CPU1_SB_DQ<14>")
	)
	(segment
		(start 49.478184 -208.04759)
		(end 48.372268 -208.04759)
		(width 0.18288)
		(layer "In11.Cu")
		(net "M_D_CPU1_SB_DQ<14>")
	)
	(segment
		(start 84.099908 -230.909368)
		(end 82.94624 -229.7557)
		(width 0.088646)
		(layer "In11.Cu")
		(net "M_D_CPU1_SB_DQ<14>")
	)
	(segment
		(start 65.816988 -212.298788)
		(end 64.698626 -211.180426)
		(width 0.18288)
		(layer "In11.Cu")
		(net "M_D_CPU1_SB_DQ<14>")
	)
	(segment
		(start 63.708026 -211.180426)
		(end 62.211458 -209.683858)
		(width 0.18288)
		(layer "In11.Cu")
		(net "M_D_CPU1_SB_DQ<14>")
	)
	(segment
		(start 66.538094 -212.298788)
		(end 65.816988 -212.298788)
		(width 0.18288)
		(layer "In11.Cu")
		(net "M_D_CPU1_SB_DQ<14>")
	)
	(segment
		(start 58.293762 -208.793842)
		(end 55.944262 -208.793842)
		(width 0.18288)
		(layer "In11.Cu")
		(net "M_D_CPU1_SB_DQ<14>")
	)
	(segment
		(start 23.703026 -214.395304)
		(end 23.703026 -214.878158)
		(width 0.18288)
		(layer "In11.Cu")
		(net "M_D_CPU1_SB_DQ<14>")
	)
	(segment
		(start 95.946214 -233.666538)
		(end 95.931482 -233.657902)
		(width 0.088646)
		(layer "In11.Cu")
		(net "M_D_CPU1_SB_DQ<14>")
	)
	(segment
		(start 23.169372 -214.009224)
		(end 23.362412 -214.202264)
		(width 0.18288)
		(layer "In11.Cu")
		(net "M_D_CPU1_SB_DQ<14>")
	)
	(segment
		(start 93.879416 -231.714548)
		(end 93.879416 -231.700324)
		(width 0.088646)
		(layer "In11.Cu")
		(net "M_D_CPU1_SB_DQ<14>")
	)
	(segment
		(start 48.266858 -207.94218)
		(end 45.337222 -207.94218)
		(width 0.18288)
		(layer "In11.Cu")
		(net "M_D_CPU1_SB_DQ<14>")
	)
	(segment
		(start 94.536768 -232.852722)
		(end 94.527878 -232.847642)
		(width 0.088646)
		(layer "In11.Cu")
		(net "M_D_CPU1_SB_DQ<14>")
	)
	(segment
		(start 59.183778 -209.683858)
		(end 58.293762 -208.793842)
		(width 0.18288)
		(layer "In11.Cu")
		(net "M_D_CPU1_SB_DQ<14>")
	)
	(segment
		(start 23.703026 -213.308184)
		(end 23.509986 -213.501224)
		(width 0.18288)
		(layer "In11.Cu")
		(net "M_D_CPU1_SB_DQ<14>")
	)
	(segment
		(start 95.006414 -233.666538)
		(end 94.997524 -233.661458)
		(width 0.088646)
		(layer "In11.Cu")
		(net "M_D_CPU1_SB_DQ<14>")
	)
	(segment
		(start 40.119046 -207.962246)
		(end 39.25062 -207.09382)
		(width 0.18288)
		(layer "In11.Cu")
		(net "M_D_CPU1_SB_DQ<14>")
	)
	(segment
		(start 44.14266 -207.962246)
		(end 40.119046 -207.962246)
		(width 0.18288)
		(layer "In11.Cu")
		(net "M_D_CPU1_SB_DQ<14>")
	)
	(segment
		(start 97.826068 -233.666538)
		(end 97.815654 -233.660442)
		(width 0.088646)
		(layer "In11.Cu")
		(net "M_D_CPU1_SB_DQ<14>")
	)
	(segment
		(start 34.069274 -207.94218)
		(end 33.790128 -208.221326)
		(width 0.18288)
		(layer "In11.Cu")
		(net "M_D_CPU1_SB_DQ<14>")
	)
	(segment
		(start 82.94624 -229.478586)
		(end 82.689954 -229.2223)
		(width 0.088646)
		(layer "In11.Cu")
		(net "M_D_CPU1_SB_DQ<14>")
	)
	(segment
		(start 33.790128 -208.221326)
		(end 33.398714 -208.221326)
		(width 0.18288)
		(layer "In11.Cu")
		(net "M_D_CPU1_SB_DQ<14>")
	)
	(segment
		(start 84.386166 -231.275636)
		(end 84.26069 -231.275636)
		(width 0.088646)
		(layer "In11.Cu")
		(net "M_D_CPU1_SB_DQ<14>")
	)
	(segment
		(start 94.818962 -233.34218)
		(end 94.818962 -233.326686)
		(width 0.088646)
		(layer "In11.Cu")
		(net "M_D_CPU1_SB_DQ<14>")
	)
	(segment
		(start 99.705414 -233.666538)
		(end 99.690682 -233.657902)
		(width 0.088646)
		(layer "In11.Cu")
		(net "M_D_CPU1_SB_DQ<14>")
	)
	(segment
		(start 23.703026 -212.993224)
		(end 23.703026 -213.308184)
		(width 0.18288)
		(layer "In11.Cu")
		(net "M_D_CPU1_SB_DQ<14>")
	)
	(segment
		(start 54.245256 -207.094836)
		(end 50.430938 -207.094836)
		(width 0.18288)
		(layer "In11.Cu")
		(net "M_D_CPU1_SB_DQ<14>")
	)
	(segment
		(start 68.55333 -214.314024)
		(end 66.538094 -212.298788)
		(width 0.18288)
		(layer "In11.Cu")
		(net "M_D_CPU1_SB_DQ<14>")
	)
	(segment
		(start 23.509986 -212.099144)
		(end 23.362412 -212.099144)
		(width 0.18288)
		(layer "In11.Cu")
		(net "M_D_CPU1_SB_DQ<14>")
	)
	(segment
		(start 82.37347 -229.2223)
		(end 81.09077 -229.2223)
		(width 0.18288)
		(layer "In11.Cu")
		(net "M_D_CPU1_SB_DQ<14>")
	)
	(segment
		(start 50.430938 -207.094836)
		(end 49.478184 -208.04759)
		(width 0.18288)
		(layer "In11.Cu")
		(net "M_D_CPU1_SB_DQ<14>")
	)
	(segment
		(start 35.436302 -207.09382)
		(end 34.587942 -207.94218)
		(width 0.18288)
		(layer "In11.Cu")
		(net "M_D_CPU1_SB_DQ<14>")
	)
	(segment
		(start 23.169372 -213.694264)
		(end 23.169372 -214.009224)
		(width 0.18288)
		(layer "In11.Cu")
		(net "M_D_CPU1_SB_DQ<14>")
	)
	(segment
		(start 70.230238 -218.361768)
		(end 68.55333 -214.314024)
		(width 0.18288)
		(layer "In11.Cu")
		(net "M_D_CPU1_SB_DQ<14>")
	)
	(segment
		(start 33.119568 -207.94218)
		(end 31.26994 -207.94218)
		(width 0.18288)
		(layer "In11.Cu")
		(net "M_D_CPU1_SB_DQ<14>")
	)
	(segment
		(start 23.122636 -215.458548)
		(end 21.447252 -215.458548)
		(width 0.18288)
		(layer "In11.Cu")
		(net "M_D_CPU1_SB_DQ<14>")
	)
	(segment
		(start 33.398714 -208.221326)
		(end 33.119568 -207.94218)
		(width 0.18288)
		(layer "In11.Cu")
		(net "M_D_CPU1_SB_DQ<14>")
	)
	(segment
		(start 82.689954 -229.2223)
		(end 82.37347 -229.2223)
		(width 0.088646)
		(layer "In11.Cu")
		(net "M_D_CPU1_SB_DQ<14>")
	)
	(segment
		(start 44.305982 -207.798924)
		(end 44.14266 -207.962246)
		(width 0.18288)
		(layer "In11.Cu")
		(net "M_D_CPU1_SB_DQ<14>")
	)
	(segment
		(start 23.509986 -214.202264)
		(end 23.703026 -214.395304)
		(width 0.18288)
		(layer "In11.Cu")
		(net "M_D_CPU1_SB_DQ<14>")
	)
	(arc
		(start 92.091764 -231.224836)
		(mid 91.904566 -231.274979)
		(end 91.717368 -231.224836)
		(width 0.088646)
		(layer "In11.Cu")
		(net "M_D_CPU1_SB_DQ<14>")
	)
	(arc
		(start 90.212164 -231.224836)
		(mid 90.024966 -231.274979)
		(end 89.837768 -231.224836)
		(width 0.088646)
		(layer "In11.Cu")
		(net "M_D_CPU1_SB_DQ<14>")
	)
	(arc
		(start 89.837768 -231.224836)
		(mid 89.563539 -231.148911)
		(end 89.287096 -231.2162)
		(width 0.088646)
		(layer "In11.Cu")
		(net "M_D_CPU1_SB_DQ<14>")
	)
	(arc
		(start 86.452964 -231.224836)
		(mid 86.265766 -231.274979)
		(end 86.078568 -231.224836)
		(width 0.088646)
		(layer "In11.Cu")
		(net "M_D_CPU1_SB_DQ<14>")
	)
	(arc
		(start 100.362766 -234.15625)
		(mid 100.04758 -233.893286)
		(end 99.705414 -233.666538)
		(width 0.088646)
		(layer "In11.Cu")
		(net "M_D_CPU1_SB_DQ<14>")
	)
	(arc
		(start 99.690682 -233.657902)
		(mid 99.414241 -233.590736)
		(end 99.14001 -233.666538)
		(width 0.088646)
		(layer "In11.Cu")
		(net "M_D_CPU1_SB_DQ<14>")
	)
	(arc
		(start 95.931482 -233.657902)
		(mid 95.655041 -233.590736)
		(end 95.38081 -233.666538)
		(width 0.088646)
		(layer "In11.Cu")
		(net "M_D_CPU1_SB_DQ<14>")
	)
	(arc
		(start 85.138768 -231.224836)
		(mid 84.856066 -231.149094)
		(end 84.573364 -231.224836)
		(width 0.088646)
		(layer "In11.Cu")
		(net "M_D_CPU1_SB_DQ<14>")
	)
	(arc
		(start 93.879416 -231.700324)
		(mid 93.800275 -231.425701)
		(end 93.596968 -231.224836)
		(width 0.088646)
		(layer "In11.Cu")
		(net "M_D_CPU1_SB_DQ<14>")
	)
	(arc
		(start 91.717368 -231.224836)
		(mid 91.440555 -231.149)
		(end 91.162124 -231.21874)
		(width 0.088646)
		(layer "In11.Cu")
		(net "M_D_CPU1_SB_DQ<14>")
	)
	(arc
		(start 84.573364 -231.224836)
		(mid 84.483108 -231.262558)
		(end 84.386166 -231.275636)
		(width 0.088646)
		(layer "In11.Cu")
		(net "M_D_CPU1_SB_DQ<14>")
	)
	(arc
		(start 94.057978 -232.033826)
		(mid 93.927064 -231.897466)
		(end 93.879416 -231.714548)
		(width 0.088646)
		(layer "In11.Cu")
		(net "M_D_CPU1_SB_DQ<14>")
	)
	(arc
		(start 90.777314 -231.224836)
		(mid 90.500755 -231.149127)
		(end 90.222578 -231.21874)
		(width 0.088646)
		(layer "In11.Cu")
		(net "M_D_CPU1_SB_DQ<14>")
	)
	(arc
		(start 92.657168 -231.224836)
		(mid 92.382939 -231.148911)
		(end 92.106496 -231.2162)
		(width 0.088646)
		(layer "In11.Cu")
		(net "M_D_CPU1_SB_DQ<14>")
	)
	(arc
		(start 99.14001 -233.666538)
		(mid 98.952812 -233.716681)
		(end 98.765614 -233.666538)
		(width 0.088646)
		(layer "In11.Cu")
		(net "M_D_CPU1_SB_DQ<14>")
	)
	(arc
		(start 86.078568 -231.224836)
		(mid 85.795866 -231.149094)
		(end 85.513164 -231.224836)
		(width 0.088646)
		(layer "In11.Cu")
		(net "M_D_CPU1_SB_DQ<14>")
	)
	(arc
		(start 95.38081 -233.666538)
		(mid 95.193612 -233.716681)
		(end 95.006414 -233.666538)
		(width 0.088646)
		(layer "In11.Cu")
		(net "M_D_CPU1_SB_DQ<14>")
	)
	(arc
		(start 94.527878 -232.847642)
		(mid 94.396964 -232.711282)
		(end 94.349316 -232.528364)
		(width 0.088646)
		(layer "In11.Cu")
		(net "M_D_CPU1_SB_DQ<14>")
	)
	(arc
		(start 88.897968 -231.224836)
		(mid 88.623739 -231.148911)
		(end 88.347296 -231.2162)
		(width 0.088646)
		(layer "In11.Cu")
		(net "M_D_CPU1_SB_DQ<14>")
	)
	(arc
		(start 93.031564 -231.224836)
		(mid 92.844366 -231.274979)
		(end 92.657168 -231.224836)
		(width 0.088646)
		(layer "In11.Cu")
		(net "M_D_CPU1_SB_DQ<14>")
	)
	(arc
		(start 88.332564 -231.224836)
		(mid 88.145366 -231.274979)
		(end 87.958168 -231.224836)
		(width 0.088646)
		(layer "In11.Cu")
		(net "M_D_CPU1_SB_DQ<14>")
	)
	(arc
		(start 94.997524 -233.661458)
		(mid 94.86661 -233.525098)
		(end 94.818962 -233.34218)
		(width 0.088646)
		(layer "In11.Cu")
		(net "M_D_CPU1_SB_DQ<14>")
	)
	(arc
		(start 91.15171 -231.224836)
		(mid 90.964512 -231.274979)
		(end 90.777314 -231.224836)
		(width 0.088646)
		(layer "In11.Cu")
		(net "M_D_CPU1_SB_DQ<14>")
	)
	(arc
		(start 94.818962 -233.326686)
		(mid 94.739592 -233.052952)
		(end 94.536768 -232.852722)
		(width 0.088646)
		(layer "In11.Cu")
		(net "M_D_CPU1_SB_DQ<14>")
	)
	(arc
		(start 97.815654 -233.660442)
		(mid 97.537222 -233.590628)
		(end 97.26041 -233.666538)
		(width 0.088646)
		(layer "In11.Cu")
		(net "M_D_CPU1_SB_DQ<14>")
	)
	(arc
		(start 87.018368 -231.224836)
		(mid 86.735666 -231.149094)
		(end 86.452964 -231.224836)
		(width 0.088646)
		(layer "In11.Cu")
		(net "M_D_CPU1_SB_DQ<14>")
	)
	(arc
		(start 96.871282 -233.657902)
		(mid 96.594841 -233.590736)
		(end 96.32061 -233.666538)
		(width 0.088646)
		(layer "In11.Cu")
		(net "M_D_CPU1_SB_DQ<14>")
	)
	(arc
		(start 89.272364 -231.224836)
		(mid 89.085166 -231.274979)
		(end 88.897968 -231.224836)
		(width 0.088646)
		(layer "In11.Cu")
		(net "M_D_CPU1_SB_DQ<14>")
	)
	(arc
		(start 97.26041 -233.666538)
		(mid 97.073212 -233.716681)
		(end 96.886014 -233.666538)
		(width 0.088646)
		(layer "In11.Cu")
		(net "M_D_CPU1_SB_DQ<14>")
	)
	(arc
		(start 87.958168 -231.224836)
		(mid 87.675466 -231.149094)
		(end 87.392764 -231.224836)
		(width 0.088646)
		(layer "In11.Cu")
		(net "M_D_CPU1_SB_DQ<14>")
	)
	(arc
		(start 98.200464 -233.666538)
		(mid 98.013266 -233.716681)
		(end 97.826068 -233.666538)
		(width 0.088646)
		(layer "In11.Cu")
		(net "M_D_CPU1_SB_DQ<14>")
	)
	(arc
		(start 93.596968 -231.224836)
		(mid 93.322739 -231.148911)
		(end 93.046296 -231.2162)
		(width 0.088646)
		(layer "In11.Cu")
		(net "M_D_CPU1_SB_DQ<14>")
	)
	(arc
		(start 85.513164 -231.224836)
		(mid 85.325966 -231.274979)
		(end 85.138768 -231.224836)
		(width 0.088646)
		(layer "In11.Cu")
		(net "M_D_CPU1_SB_DQ<14>")
	)
	(arc
		(start 98.7552 -233.660442)
		(mid 98.477022 -233.59075)
		(end 98.200464 -233.666538)
		(width 0.088646)
		(layer "In11.Cu")
		(net "M_D_CPU1_SB_DQ<14>")
	)
	(arc
		(start 96.32061 -233.666538)
		(mid 96.133412 -233.716681)
		(end 95.946214 -233.666538)
		(width 0.088646)
		(layer "In11.Cu")
		(net "M_D_CPU1_SB_DQ<14>")
	)
	(arc
		(start 94.349316 -232.518458)
		(mid 94.271205 -232.241509)
		(end 94.066868 -232.038906)
		(width 0.088646)
		(layer "In11.Cu")
		(net "M_D_CPU1_SB_DQ<14>")
	)
	(arc
		(start 87.392764 -231.224836)
		(mid 87.205566 -231.274979)
		(end 87.018368 -231.224836)
		(width 0.088646)
		(layer "In11.Cu")
		(net "M_D_CPU1_SB_DQ<14>")
	)
	(segment
		(start 10.507472 -214.73287)
		(end 11.11631 -214.73287)
		(width 0.20066)
		(layer "F.Cu")
		(net "M_D_CPU1_SB_DQ<13>")
	)
	(segment
		(start 9.474708 -215.166702)
		(end 9.686036 -215.37803)
		(width 0.20066)
		(layer "F.Cu")
		(net "M_D_CPU1_SB_DQ<13>")
	)
	(segment
		(start 10.19048 -215.37803)
		(end 10.344912 -215.223598)
		(width 0.20066)
		(layer "F.Cu")
		(net "M_D_CPU1_SB_DQ<13>")
	)
	(segment
		(start 8.140446 -215.166702)
		(end 9.474708 -215.166702)
		(width 0.20066)
		(layer "F.Cu")
		(net "M_D_CPU1_SB_DQ<13>")
	)
	(segment
		(start 11.1252 -214.74176)
		(end 13.110718 -214.74176)
		(width 0.1016)
		(layer "F.Cu")
		(net "M_D_CPU1_SB_DQ<13>")
	)
	(segment
		(start 98.953066 -233.87812)
		(end 98.952812 -233.877866)
		(width 0.20066)
		(layer "F.Cu")
		(net "M_D_CPU1_SB_DQ<13>")
	)
	(segment
		(start 98.952812 -233.877866)
		(end 98.952812 -233.34218)
		(width 0.20066)
		(layer "F.Cu")
		(net "M_D_CPU1_SB_DQ<13>")
	)
	(segment
		(start 10.344912 -214.89543)
		(end 10.507472 -214.73287)
		(width 0.20066)
		(layer "F.Cu")
		(net "M_D_CPU1_SB_DQ<13>")
	)
	(segment
		(start 11.11631 -214.73287)
		(end 11.1252 -214.74176)
		(width 0.1016)
		(layer "F.Cu")
		(net "M_D_CPU1_SB_DQ<13>")
	)
	(segment
		(start 14.04493 -215.166702)
		(end 15.684246 -215.166702)
		(width 0.20066)
		(layer "F.Cu")
		(net "M_D_CPU1_SB_DQ<13>")
	)
	(segment
		(start 9.686036 -215.37803)
		(end 10.19048 -215.37803)
		(width 0.20066)
		(layer "F.Cu")
		(net "M_D_CPU1_SB_DQ<13>")
	)
	(segment
		(start 16.789146 -215.166702)
		(end 15.684246 -215.166702)
		(width 0.20066)
		(layer "F.Cu")
		(net "M_D_CPU1_SB_DQ<13>")
	)
	(segment
		(start 13.619988 -214.74176)
		(end 14.04493 -215.166702)
		(width 0.20066)
		(layer "F.Cu")
		(net "M_D_CPU1_SB_DQ<13>")
	)
	(segment
		(start 10.344912 -215.223598)
		(end 10.344912 -214.89543)
		(width 0.20066)
		(layer "F.Cu")
		(net "M_D_CPU1_SB_DQ<13>")
	)
	(segment
		(start 13.110718 -214.74176)
		(end 13.441426 -214.74176)
		(width 0.101854)
		(layer "F.Cu")
		(net "M_D_CPU1_SB_DQ<13>")
	)
	(segment
		(start 13.441426 -214.74176)
		(end 13.619988 -214.74176)
		(width 0.20066)
		(layer "F.Cu")
		(net "M_D_CPU1_SB_DQ<13>")
	)
	(segment
		(start 92.106496 -230.584756)
		(end 92.091764 -230.57612)
		(width 0.088646)
		(layer "In11.Cu")
		(net "M_D_CPU1_SB_DQ<13>")
	)
	(segment
		(start 99.1489 -233.022902)
		(end 99.14001 -233.017822)
		(width 0.088646)
		(layer "In11.Cu")
		(net "M_D_CPU1_SB_DQ<13>")
	)
	(segment
		(start 89.287096 -230.584756)
		(end 89.272364 -230.57612)
		(width 0.088646)
		(layer "In11.Cu")
		(net "M_D_CPU1_SB_DQ<13>")
	)
	(segment
		(start 96.038416 -232.543858)
		(end 96.038416 -232.528364)
		(width 0.088646)
		(layer "In11.Cu")
		(net "M_D_CPU1_SB_DQ<13>")
	)
	(segment
		(start 48.440848 -206.956152)
		(end 48.304196 -207.092804)
		(width 0.18288)
		(layer "In11.Cu")
		(net "M_D_CPU1_SB_DQ<13>")
	)
	(segment
		(start 68.845684 -213.608158)
		(end 66.489072 -211.251546)
		(width 0.18288)
		(layer "In11.Cu")
		(net "M_D_CPU1_SB_DQ<13>")
	)
	(segment
		(start 46.138592 -207.16113)
		(end 44.34713 -207.16113)
		(width 0.18288)
		(layer "In11.Cu")
		(net "M_D_CPU1_SB_DQ<13>")
	)
	(segment
		(start 55.386986 -207.489806)
		(end 55.386986 -206.798164)
		(width 0.18288)
		(layer "In11.Cu")
		(net "M_D_CPU1_SB_DQ<13>")
	)
	(segment
		(start 22.645624 -211.069428)
		(end 22.645624 -214.569802)
		(width 0.18288)
		(layer "In11.Cu")
		(net "M_D_CPU1_SB_DQ<13>")
	)
	(segment
		(start 46.206918 -207.092804)
		(end 46.138592 -207.16113)
		(width 0.18288)
		(layer "In11.Cu")
		(net "M_D_CPU1_SB_DQ<13>")
	)
	(segment
		(start 65.746122 -211.251546)
		(end 63.909194 -209.414618)
		(width 0.18288)
		(layer "In11.Cu")
		(net "M_D_CPU1_SB_DQ<13>")
	)
	(segment
		(start 31.035244 -207.093312)
		(end 30.22473 -207.903826)
		(width 0.18288)
		(layer "In11.Cu")
		(net "M_D_CPU1_SB_DQ<13>")
	)
	(segment
		(start 25.430226 -208.284826)
		(end 22.645624 -211.069428)
		(width 0.18288)
		(layer "In11.Cu")
		(net "M_D_CPU1_SB_DQ<13>")
	)
	(segment
		(start 85.527896 -230.584756)
		(end 85.513164 -230.57612)
		(width 0.088646)
		(layer "In11.Cu")
		(net "M_D_CPU1_SB_DQ<13>")
	)
	(segment
		(start 96.886014 -233.017822)
		(end 96.871282 -233.026458)
		(width 0.088646)
		(layer "In11.Cu")
		(net "M_D_CPU1_SB_DQ<13>")
	)
	(segment
		(start 61.863986 -208.840832)
		(end 59.107832 -208.840832)
		(width 0.18288)
		(layer "In11.Cu")
		(net "M_D_CPU1_SB_DQ<13>")
	)
	(segment
		(start 82.715862 -228.7143)
		(end 82.37347 -228.7143)
		(width 0.088646)
		(layer "In11.Cu")
		(net "M_D_CPU1_SB_DQ<13>")
	)
	(segment
		(start 63.909194 -209.414618)
		(end 61.863986 -208.840832)
		(width 0.18288)
		(layer "In11.Cu")
		(net "M_D_CPU1_SB_DQ<13>")
	)
	(segment
		(start 88.347296 -230.584756)
		(end 88.332564 -230.57612)
		(width 0.088646)
		(layer "In11.Cu")
		(net "M_D_CPU1_SB_DQ<13>")
	)
	(segment
		(start 54.827932 -206.23911)
		(end 50.43678 -206.23911)
		(width 0.18288)
		(layer "In11.Cu")
		(net "M_D_CPU1_SB_DQ<13>")
	)
	(segment
		(start 59.107832 -208.840832)
		(end 58.26506 -207.99806)
		(width 0.18288)
		(layer "In11.Cu")
		(net "M_D_CPU1_SB_DQ<13>")
	)
	(segment
		(start 98.210878 -233.023918)
		(end 98.200464 -233.017822)
		(width 0.088646)
		(layer "In11.Cu")
		(net "M_D_CPU1_SB_DQ<13>")
	)
	(segment
		(start 21.605494 -214.739474)
		(end 17.216374 -214.739474)
		(width 0.18288)
		(layer "In11.Cu")
		(net "M_D_CPU1_SB_DQ<13>")
	)
	(segment
		(start 91.162124 -230.582216)
		(end 91.15171 -230.57612)
		(width 0.088646)
		(layer "In11.Cu")
		(net "M_D_CPU1_SB_DQ<13>")
	)
	(segment
		(start 95.098616 -230.922576)
		(end 95.098616 -230.900478)
		(width 0.088646)
		(layer "In11.Cu")
		(net "M_D_CPU1_SB_DQ<13>")
	)
	(segment
		(start 55.89524 -207.99806)
		(end 55.386986 -207.489806)
		(width 0.18288)
		(layer "In11.Cu")
		(net "M_D_CPU1_SB_DQ<13>")
	)
	(segment
		(start 82.37347 -228.7143)
		(end 81.301336 -228.7143)
		(width 0.18288)
		(layer "In11.Cu")
		(net "M_D_CPU1_SB_DQ<13>")
	)
	(segment
		(start 22.645624 -214.569802)
		(end 22.3012 -214.914226)
		(width 0.18288)
		(layer "In11.Cu")
		(net "M_D_CPU1_SB_DQ<13>")
	)
	(segment
		(start 93.986096 -230.584756)
		(end 93.971364 -230.57612)
		(width 0.088646)
		(layer "In11.Cu")
		(net "M_D_CPU1_SB_DQ<13>")
	)
	(segment
		(start 58.26506 -207.99806)
		(end 55.89524 -207.99806)
		(width 0.18288)
		(layer "In11.Cu")
		(net "M_D_CPU1_SB_DQ<13>")
	)
	(segment
		(start 29.351478 -207.903826)
		(end 28.325826 -208.284826)
		(width 0.18288)
		(layer "In11.Cu")
		(net "M_D_CPU1_SB_DQ<13>")
	)
	(segment
		(start 98.952812 -233.34218)
		(end 99.265486 -233.34218)
		(width 0.088646)
		(layer "In11.Cu")
		(net "M_D_CPU1_SB_DQ<13>")
	)
	(segment
		(start 66.489072 -211.251546)
		(end 65.746122 -211.251546)
		(width 0.18288)
		(layer "In11.Cu")
		(net "M_D_CPU1_SB_DQ<13>")
	)
	(segment
		(start 70.720204 -218.133168)
		(end 68.845684 -213.608158)
		(width 0.18288)
		(layer "In11.Cu")
		(net "M_D_CPU1_SB_DQ<13>")
	)
	(segment
		(start 50.43678 -206.23911)
		(end 49.719738 -206.956152)
		(width 0.18288)
		(layer "In11.Cu")
		(net "M_D_CPU1_SB_DQ<13>")
	)
	(segment
		(start 84.386166 -230.525574)
		(end 84.181696 -230.525574)
		(width 0.088646)
		(layer "In11.Cu")
		(net "M_D_CPU1_SB_DQ<13>")
	)
	(segment
		(start 83.172554 -229.170992)
		(end 82.715862 -228.7143)
		(width 0.088646)
		(layer "In11.Cu")
		(net "M_D_CPU1_SB_DQ<13>")
	)
	(segment
		(start 90.777314 -230.57612)
		(end 90.7669 -230.582216)
		(width 0.088646)
		(layer "In11.Cu")
		(net "M_D_CPU1_SB_DQ<13>")
	)
	(segment
		(start 22.3012 -214.914226)
		(end 21.780246 -214.914226)
		(width 0.18288)
		(layer "In11.Cu")
		(net "M_D_CPU1_SB_DQ<13>")
	)
	(segment
		(start 86.467696 -230.584756)
		(end 86.452964 -230.57612)
		(width 0.088646)
		(layer "In11.Cu")
		(net "M_D_CPU1_SB_DQ<13>")
	)
	(segment
		(start 28.325826 -208.284826)
		(end 25.430226 -208.284826)
		(width 0.18288)
		(layer "In11.Cu")
		(net "M_D_CPU1_SB_DQ<13>")
	)
	(segment
		(start 48.304196 -207.092804)
		(end 46.206918 -207.092804)
		(width 0.18288)
		(layer "In11.Cu")
		(net "M_D_CPU1_SB_DQ<13>")
	)
	(segment
		(start 97.826068 -233.017822)
		(end 97.815654 -233.023918)
		(width 0.088646)
		(layer "In11.Cu")
		(net "M_D_CPU1_SB_DQ<13>")
	)
	(segment
		(start 34.685478 -206.93507)
		(end 32.79394 -206.93507)
		(width 0.18288)
		(layer "In11.Cu")
		(net "M_D_CPU1_SB_DQ<13>")
	)
	(segment
		(start 95.859854 -232.209086)
		(end 95.850964 -232.204006)
		(width 0.088646)
		(layer "In11.Cu")
		(net "M_D_CPU1_SB_DQ<13>")
	)
	(segment
		(start 36.806378 -206.240126)
		(end 35.380422 -206.240126)
		(width 0.18288)
		(layer "In11.Cu")
		(net "M_D_CPU1_SB_DQ<13>")
	)
	(segment
		(start 44.34713 -207.16113)
		(end 44.11472 -206.92872)
		(width 0.18288)
		(layer "In11.Cu")
		(net "M_D_CPU1_SB_DQ<13>")
	)
	(segment
		(start 32.79394 -206.93507)
		(end 32.635698 -207.093312)
		(width 0.18288)
		(layer "In11.Cu")
		(net "M_D_CPU1_SB_DQ<13>")
	)
	(segment
		(start 40.451278 -206.92872)
		(end 39.624508 -206.10195)
		(width 0.18288)
		(layer "In11.Cu")
		(net "M_D_CPU1_SB_DQ<13>")
	)
	(segment
		(start 39.624508 -206.10195)
		(end 36.944554 -206.10195)
		(width 0.18288)
		(layer "In11.Cu")
		(net "M_D_CPU1_SB_DQ<13>")
	)
	(segment
		(start 49.719738 -206.956152)
		(end 48.440848 -206.956152)
		(width 0.18288)
		(layer "In11.Cu")
		(net "M_D_CPU1_SB_DQ<13>")
	)
	(segment
		(start 84.588096 -230.584756)
		(end 84.573364 -230.57612)
		(width 0.088646)
		(layer "In11.Cu")
		(net "M_D_CPU1_SB_DQ<13>")
	)
	(segment
		(start 32.635698 -207.093312)
		(end 31.035244 -207.093312)
		(width 0.18288)
		(layer "In11.Cu")
		(net "M_D_CPU1_SB_DQ<13>")
	)
	(segment
		(start 95.3897 -231.39527)
		(end 95.38081 -231.39019)
		(width 0.088646)
		(layer "In11.Cu")
		(net "M_D_CPU1_SB_DQ<13>")
	)
	(segment
		(start 30.22473 -207.903826)
		(end 29.351478 -207.903826)
		(width 0.18288)
		(layer "In11.Cu")
		(net "M_D_CPU1_SB_DQ<13>")
	)
	(segment
		(start 55.386986 -206.798164)
		(end 54.827932 -206.23911)
		(width 0.18288)
		(layer "In11.Cu")
		(net "M_D_CPU1_SB_DQ<13>")
	)
	(segment
		(start 93.046296 -230.584756)
		(end 93.031564 -230.57612)
		(width 0.088646)
		(layer "In11.Cu")
		(net "M_D_CPU1_SB_DQ<13>")
	)
	(segment
		(start 36.944554 -206.10195)
		(end 36.806378 -206.240126)
		(width 0.18288)
		(layer "In11.Cu")
		(net "M_D_CPU1_SB_DQ<13>")
	)
	(segment
		(start 87.407496 -230.584756)
		(end 87.392764 -230.57612)
		(width 0.088646)
		(layer "In11.Cu")
		(net "M_D_CPU1_SB_DQ<13>")
	)
	(segment
		(start 21.780246 -214.914226)
		(end 21.605494 -214.739474)
		(width 0.18288)
		(layer "In11.Cu")
		(net "M_D_CPU1_SB_DQ<13>")
	)
	(segment
		(start 83.172554 -229.516432)
		(end 83.172554 -229.170992)
		(width 0.088646)
		(layer "In11.Cu")
		(net "M_D_CPU1_SB_DQ<13>")
	)
	(segment
		(start 17.216374 -214.739474)
		(end 16.789146 -215.166702)
		(width 0.18288)
		(layer "In11.Cu")
		(net "M_D_CPU1_SB_DQ<13>")
	)
	(segment
		(start 95.850964 -232.204006)
		(end 95.844868 -232.20045)
		(width 0.088646)
		(layer "In11.Cu")
		(net "M_D_CPU1_SB_DQ<13>")
	)
	(segment
		(start 44.11472 -206.92872)
		(end 40.451278 -206.92872)
		(width 0.18288)
		(layer "In11.Cu")
		(net "M_D_CPU1_SB_DQ<13>")
	)
	(segment
		(start 84.181696 -230.525574)
		(end 83.172554 -229.516432)
		(width 0.088646)
		(layer "In11.Cu")
		(net "M_D_CPU1_SB_DQ<13>")
	)
	(segment
		(start 99.265486 -233.34218)
		(end 99.32289 -233.284776)
		(width 0.088646)
		(layer "In11.Cu")
		(net "M_D_CPU1_SB_DQ<13>")
	)
	(segment
		(start 81.301336 -228.7143)
		(end 70.720204 -218.133168)
		(width 0.18288)
		(layer "In11.Cu")
		(net "M_D_CPU1_SB_DQ<13>")
	)
	(segment
		(start 35.380422 -206.240126)
		(end 34.685478 -206.93507)
		(width 0.18288)
		(layer "In11.Cu")
		(net "M_D_CPU1_SB_DQ<13>")
	)
	(segment
		(start 94.920054 -230.5812)
		(end 94.911164 -230.57612)
		(width 0.088646)
		(layer "In11.Cu")
		(net "M_D_CPU1_SB_DQ<13>")
	)
	(arc
		(start 95.844868 -232.20045)
		(mid 95.642281 -231.994099)
		(end 95.568262 -231.714548)
		(width 0.088646)
		(layer "In11.Cu")
		(net "M_D_CPU1_SB_DQ<13>")
	)
	(arc
		(start 98.200464 -233.017822)
		(mid 98.013266 -232.967679)
		(end 97.826068 -233.017822)
		(width 0.088646)
		(layer "In11.Cu")
		(net "M_D_CPU1_SB_DQ<13>")
	)
	(arc
		(start 97.815654 -233.023918)
		(mid 97.537222 -233.093764)
		(end 97.26041 -233.017822)
		(width 0.088646)
		(layer "In11.Cu")
		(net "M_D_CPU1_SB_DQ<13>")
	)
	(arc
		(start 96.038416 -232.528364)
		(mid 95.990737 -232.345464)
		(end 95.859854 -232.209086)
		(width 0.088646)
		(layer "In11.Cu")
		(net "M_D_CPU1_SB_DQ<13>")
	)
	(arc
		(start 93.031564 -230.57612)
		(mid 92.844366 -230.525977)
		(end 92.657168 -230.57612)
		(width 0.088646)
		(layer "In11.Cu")
		(net "M_D_CPU1_SB_DQ<13>")
	)
	(arc
		(start 90.212164 -230.57612)
		(mid 90.024966 -230.525977)
		(end 89.837768 -230.57612)
		(width 0.088646)
		(layer "In11.Cu")
		(net "M_D_CPU1_SB_DQ<13>")
	)
	(arc
		(start 96.871282 -233.026458)
		(mid 96.594807 -233.093778)
		(end 96.32061 -233.017822)
		(width 0.088646)
		(layer "In11.Cu")
		(net "M_D_CPU1_SB_DQ<13>")
	)
	(arc
		(start 96.32061 -233.017822)
		(mid 96.117787 -232.817591)
		(end 96.038416 -232.543858)
		(width 0.088646)
		(layer "In11.Cu")
		(net "M_D_CPU1_SB_DQ<13>")
	)
	(arc
		(start 88.897968 -230.57612)
		(mid 88.623769 -230.651955)
		(end 88.347296 -230.584756)
		(width 0.088646)
		(layer "In11.Cu")
		(net "M_D_CPU1_SB_DQ<13>")
	)
	(arc
		(start 94.911164 -230.57612)
		(mid 94.723966 -230.525977)
		(end 94.536768 -230.57612)
		(width 0.088646)
		(layer "In11.Cu")
		(net "M_D_CPU1_SB_DQ<13>")
	)
	(arc
		(start 91.717368 -230.57612)
		(mid 91.440555 -230.65199)
		(end 91.162124 -230.582216)
		(width 0.088646)
		(layer "In11.Cu")
		(net "M_D_CPU1_SB_DQ<13>")
	)
	(arc
		(start 87.018368 -230.57612)
		(mid 86.744169 -230.651955)
		(end 86.467696 -230.584756)
		(width 0.088646)
		(layer "In11.Cu")
		(net "M_D_CPU1_SB_DQ<13>")
	)
	(arc
		(start 99.32289 -233.284776)
		(mid 99.264734 -233.134663)
		(end 99.1489 -233.022902)
		(width 0.088646)
		(layer "In11.Cu")
		(net "M_D_CPU1_SB_DQ<13>")
	)
	(arc
		(start 92.657168 -230.57612)
		(mid 92.382969 -230.651955)
		(end 92.106496 -230.584756)
		(width 0.088646)
		(layer "In11.Cu")
		(net "M_D_CPU1_SB_DQ<13>")
	)
	(arc
		(start 85.138768 -230.57612)
		(mid 84.864569 -230.651955)
		(end 84.588096 -230.584756)
		(width 0.088646)
		(layer "In11.Cu")
		(net "M_D_CPU1_SB_DQ<13>")
	)
	(arc
		(start 87.392764 -230.57612)
		(mid 87.205566 -230.525977)
		(end 87.018368 -230.57612)
		(width 0.088646)
		(layer "In11.Cu")
		(net "M_D_CPU1_SB_DQ<13>")
	)
	(arc
		(start 93.596968 -230.57612)
		(mid 93.322769 -230.651955)
		(end 93.046296 -230.584756)
		(width 0.088646)
		(layer "In11.Cu")
		(net "M_D_CPU1_SB_DQ<13>")
	)
	(arc
		(start 97.26041 -233.017822)
		(mid 97.073212 -232.967679)
		(end 96.886014 -233.017822)
		(width 0.088646)
		(layer "In11.Cu")
		(net "M_D_CPU1_SB_DQ<13>")
	)
	(arc
		(start 90.7669 -230.582216)
		(mid 90.488722 -230.651939)
		(end 90.212164 -230.57612)
		(width 0.088646)
		(layer "In11.Cu")
		(net "M_D_CPU1_SB_DQ<13>")
	)
	(arc
		(start 93.971364 -230.57612)
		(mid 93.784166 -230.525977)
		(end 93.596968 -230.57612)
		(width 0.088646)
		(layer "In11.Cu")
		(net "M_D_CPU1_SB_DQ<13>")
	)
	(arc
		(start 95.38081 -231.39019)
		(mid 95.179528 -231.192703)
		(end 95.098616 -230.922576)
		(width 0.088646)
		(layer "In11.Cu")
		(net "M_D_CPU1_SB_DQ<13>")
	)
	(arc
		(start 95.098616 -230.900478)
		(mid 95.050937 -230.717578)
		(end 94.920054 -230.5812)
		(width 0.088646)
		(layer "In11.Cu")
		(net "M_D_CPU1_SB_DQ<13>")
	)
	(arc
		(start 94.536768 -230.57612)
		(mid 94.262569 -230.651955)
		(end 93.986096 -230.584756)
		(width 0.088646)
		(layer "In11.Cu")
		(net "M_D_CPU1_SB_DQ<13>")
	)
	(arc
		(start 91.15171 -230.57612)
		(mid 90.964512 -230.525977)
		(end 90.777314 -230.57612)
		(width 0.088646)
		(layer "In11.Cu")
		(net "M_D_CPU1_SB_DQ<13>")
	)
	(arc
		(start 92.091764 -230.57612)
		(mid 91.904566 -230.525977)
		(end 91.717368 -230.57612)
		(width 0.088646)
		(layer "In11.Cu")
		(net "M_D_CPU1_SB_DQ<13>")
	)
	(arc
		(start 86.452964 -230.57612)
		(mid 86.265766 -230.525977)
		(end 86.078568 -230.57612)
		(width 0.088646)
		(layer "In11.Cu")
		(net "M_D_CPU1_SB_DQ<13>")
	)
	(arc
		(start 86.078568 -230.57612)
		(mid 85.804369 -230.651955)
		(end 85.527896 -230.584756)
		(width 0.088646)
		(layer "In11.Cu")
		(net "M_D_CPU1_SB_DQ<13>")
	)
	(arc
		(start 89.272364 -230.57612)
		(mid 89.085166 -230.525977)
		(end 88.897968 -230.57612)
		(width 0.088646)
		(layer "In11.Cu")
		(net "M_D_CPU1_SB_DQ<13>")
	)
	(arc
		(start 85.513164 -230.57612)
		(mid 85.325966 -230.525977)
		(end 85.138768 -230.57612)
		(width 0.088646)
		(layer "In11.Cu")
		(net "M_D_CPU1_SB_DQ<13>")
	)
	(arc
		(start 84.573364 -230.57612)
		(mid 84.483092 -230.538521)
		(end 84.386166 -230.525574)
		(width 0.088646)
		(layer "In11.Cu")
		(net "M_D_CPU1_SB_DQ<13>")
	)
	(arc
		(start 98.765614 -233.017822)
		(mid 98.489055 -233.093565)
		(end 98.210878 -233.023918)
		(width 0.088646)
		(layer "In11.Cu")
		(net "M_D_CPU1_SB_DQ<13>")
	)
	(arc
		(start 88.332564 -230.57612)
		(mid 88.145366 -230.525977)
		(end 87.958168 -230.57612)
		(width 0.088646)
		(layer "In11.Cu")
		(net "M_D_CPU1_SB_DQ<13>")
	)
	(arc
		(start 87.958168 -230.57612)
		(mid 87.683969 -230.651955)
		(end 87.407496 -230.584756)
		(width 0.088646)
		(layer "In11.Cu")
		(net "M_D_CPU1_SB_DQ<13>")
	)
	(arc
		(start 95.568262 -231.714548)
		(mid 95.520583 -231.531648)
		(end 95.3897 -231.39527)
		(width 0.088646)
		(layer "In11.Cu")
		(net "M_D_CPU1_SB_DQ<13>")
	)
	(arc
		(start 99.14001 -233.017822)
		(mid 98.952812 -232.967679)
		(end 98.765614 -233.017822)
		(width 0.088646)
		(layer "In11.Cu")
		(net "M_D_CPU1_SB_DQ<13>")
	)
	(arc
		(start 89.837768 -230.57612)
		(mid 89.563569 -230.651955)
		(end 89.287096 -230.584756)
		(width 0.088646)
		(layer "In11.Cu")
		(net "M_D_CPU1_SB_DQ<13>")
	)
	(segment
		(start 9.713468 -217.105484)
		(end 10.172192 -217.105484)
		(width 0.20066)
		(layer "F.Cu")
		(net "M_D_CPU1_SB_DQ<12>")
	)
	(segment
		(start 10.344912 -216.643204)
		(end 10.554462 -216.433654)
		(width 0.20066)
		(layer "F.Cu")
		(net "M_D_CPU1_SB_DQ<12>")
	)
	(segment
		(start 98.483166 -234.691936)
		(end 98.483166 -234.15625)
		(width 0.20066)
		(layer "F.Cu")
		(net "M_D_CPU1_SB_DQ<12>")
	)
	(segment
		(start 11.372342 -216.441782)
		(end 13.441426 -216.441782)
		(width 0.1016)
		(layer "F.Cu")
		(net "M_D_CPU1_SB_DQ<12>")
	)
	(segment
		(start 10.554462 -216.433654)
		(end 11.11631 -216.433654)
		(width 0.20066)
		(layer "F.Cu")
		(net "M_D_CPU1_SB_DQ<12>")
	)
	(segment
		(start 13.441426 -216.441782)
		(end 13.890244 -216.441782)
		(width 0.20066)
		(layer "F.Cu")
		(net "M_D_CPU1_SB_DQ<12>")
	)
	(segment
		(start 13.890244 -216.441782)
		(end 14.315186 -216.866724)
		(width 0.20066)
		(layer "F.Cu")
		(net "M_D_CPU1_SB_DQ<12>")
	)
	(segment
		(start 16.789146 -216.866724)
		(end 15.684246 -216.866724)
		(width 0.20066)
		(layer "F.Cu")
		(net "M_D_CPU1_SB_DQ<12>")
	)
	(segment
		(start 11.11631 -216.433654)
		(end 11.124438 -216.441782)
		(width 0.101854)
		(layer "F.Cu")
		(net "M_D_CPU1_SB_DQ<12>")
	)
	(segment
		(start 9.474708 -216.866724)
		(end 9.713468 -217.105484)
		(width 0.20066)
		(layer "F.Cu")
		(net "M_D_CPU1_SB_DQ<12>")
	)
	(segment
		(start 10.344912 -216.932764)
		(end 10.344912 -216.643204)
		(width 0.20066)
		(layer "F.Cu")
		(net "M_D_CPU1_SB_DQ<12>")
	)
	(segment
		(start 11.124438 -216.441782)
		(end 11.372342 -216.441782)
		(width 0.101854)
		(layer "F.Cu")
		(net "M_D_CPU1_SB_DQ<12>")
	)
	(segment
		(start 8.140446 -216.866724)
		(end 9.474708 -216.866724)
		(width 0.20066)
		(layer "F.Cu")
		(net "M_D_CPU1_SB_DQ<12>")
	)
	(segment
		(start 98.482912 -234.69219)
		(end 98.483166 -234.691936)
		(width 0.20066)
		(layer "F.Cu")
		(net "M_D_CPU1_SB_DQ<12>")
	)
	(segment
		(start 14.315186 -216.866724)
		(end 15.684246 -216.866724)
		(width 0.20066)
		(layer "F.Cu")
		(net "M_D_CPU1_SB_DQ<12>")
	)
	(segment
		(start 10.172192 -217.105484)
		(end 10.344912 -216.932764)
		(width 0.20066)
		(layer "F.Cu")
		(net "M_D_CPU1_SB_DQ<12>")
	)
	(segment
		(start 31.279592 -208.792318)
		(end 30.429708 -209.642202)
		(width 0.18288)
		(layer "In11.Cu")
		(net "M_D_CPU1_SB_DQ<12>")
	)
	(segment
		(start 88.427814 -231.39019)
		(end 88.4174 -231.396286)
		(width 0.088646)
		(layer "In11.Cu")
		(net "M_D_CPU1_SB_DQ<12>")
	)
	(segment
		(start 39.122096 -208.83753)
		(end 38.224206 -207.93964)
		(width 0.18288)
		(layer "In11.Cu")
		(net "M_D_CPU1_SB_DQ<12>")
	)
	(segment
		(start 83.909662 -230.988362)
		(end 82.6516 -229.7303)
		(width 0.088646)
		(layer "In11.Cu")
		(net "M_D_CPU1_SB_DQ<12>")
	)
	(segment
		(start 50.436272 -207.93964)
		(end 49.582832 -208.79308)
		(width 0.18288)
		(layer "In11.Cu")
		(net "M_D_CPU1_SB_DQ<12>")
	)
	(segment
		(start 93.980254 -232.209086)
		(end 93.971364 -232.204006)
		(width 0.088646)
		(layer "In11.Cu")
		(net "M_D_CPU1_SB_DQ<12>")
	)
	(segment
		(start 45.237908 -208.83753)
		(end 39.122096 -208.83753)
		(width 0.18288)
		(layer "In11.Cu")
		(net "M_D_CPU1_SB_DQ<12>")
	)
	(segment
		(start 24.866092 -210.75396)
		(end 24.866092 -214.787226)
		(width 0.18288)
		(layer "In11.Cu")
		(net "M_D_CPU1_SB_DQ<12>")
	)
	(segment
		(start 17.420844 -216.235026)
		(end 16.789146 -216.866724)
		(width 0.18288)
		(layer "In11.Cu")
		(net "M_D_CPU1_SB_DQ<12>")
	)
	(segment
		(start 20.513548 -216.441528)
		(end 20.307046 -216.235026)
		(width 0.18288)
		(layer "In11.Cu")
		(net "M_D_CPU1_SB_DQ<12>")
	)
	(segment
		(start 35.330384 -207.93964)
		(end 34.477706 -208.792318)
		(width 0.18288)
		(layer "In11.Cu")
		(net "M_D_CPU1_SB_DQ<12>")
	)
	(segment
		(start 64.673226 -212.247226)
		(end 62.742826 -212.247226)
		(width 0.18288)
		(layer "In11.Cu")
		(net "M_D_CPU1_SB_DQ<12>")
	)
	(segment
		(start 59.263026 -210.367626)
		(end 59.133994 -210.496658)
		(width 0.18288)
		(layer "In11.Cu")
		(net "M_D_CPU1_SB_DQ<12>")
	)
	(segment
		(start 62.742826 -212.247226)
		(end 60.863226 -210.367626)
		(width 0.18288)
		(layer "In11.Cu")
		(net "M_D_CPU1_SB_DQ<12>")
	)
	(segment
		(start 96.805496 -233.840528)
		(end 96.790764 -233.831892)
		(width 0.088646)
		(layer "In11.Cu")
		(net "M_D_CPU1_SB_DQ<12>")
	)
	(segment
		(start 93.971364 -232.204006)
		(end 93.959172 -232.196894)
		(width 0.088646)
		(layer "In11.Cu")
		(net "M_D_CPU1_SB_DQ<12>")
	)
	(segment
		(start 95.865696 -233.840528)
		(end 95.850964 -233.831892)
		(width 0.088646)
		(layer "In11.Cu")
		(net "M_D_CPU1_SB_DQ<12>")
	)
	(segment
		(start 84.181696 -231.465882)
		(end 83.909662 -231.193848)
		(width 0.088646)
		(layer "In11.Cu")
		(net "M_D_CPU1_SB_DQ<12>")
	)
	(segment
		(start 34.477706 -208.792318)
		(end 31.279592 -208.792318)
		(width 0.18288)
		(layer "In11.Cu")
		(net "M_D_CPU1_SB_DQ<12>")
	)
	(segment
		(start 53.279294 -207.93964)
		(end 50.436272 -207.93964)
		(width 0.18288)
		(layer "In11.Cu")
		(net "M_D_CPU1_SB_DQ<12>")
	)
	(segment
		(start 69.724016 -218.574112)
		(end 68.059554 -214.555832)
		(width 0.18288)
		(layer "In11.Cu")
		(net "M_D_CPU1_SB_DQ<12>")
	)
	(segment
		(start 68.059554 -214.555832)
		(end 66.411348 -212.907626)
		(width 0.18288)
		(layer "In11.Cu")
		(net "M_D_CPU1_SB_DQ<12>")
	)
	(segment
		(start 24.866092 -214.787226)
		(end 23.004272 -216.649046)
		(width 0.18288)
		(layer "In11.Cu")
		(net "M_D_CPU1_SB_DQ<12>")
	)
	(segment
		(start 21.904706 -216.649046)
		(end 21.697188 -216.441528)
		(width 0.18288)
		(layer "In11.Cu")
		(net "M_D_CPU1_SB_DQ<12>")
	)
	(segment
		(start 82.6516 -229.7303)
		(end 82.37347 -229.7303)
		(width 0.088646)
		(layer "In11.Cu")
		(net "M_D_CPU1_SB_DQ<12>")
	)
	(segment
		(start 26.096976 -209.523076)
		(end 24.866092 -210.75396)
		(width 0.18288)
		(layer "In11.Cu")
		(net "M_D_CPU1_SB_DQ<12>")
	)
	(segment
		(start 29.022802 -209.642202)
		(end 28.903676 -209.523076)
		(width 0.18288)
		(layer "In11.Cu")
		(net "M_D_CPU1_SB_DQ<12>")
	)
	(segment
		(start 93.126814 -231.39019)
		(end 93.112082 -231.398826)
		(width 0.088646)
		(layer "In11.Cu")
		(net "M_D_CPU1_SB_DQ<12>")
	)
	(segment
		(start 83.909662 -231.193848)
		(end 83.909662 -230.988362)
		(width 0.088646)
		(layer "In11.Cu")
		(net "M_D_CPU1_SB_DQ<12>")
	)
	(segment
		(start 20.307046 -216.235026)
		(end 17.420844 -216.235026)
		(width 0.18288)
		(layer "In11.Cu")
		(net "M_D_CPU1_SB_DQ<12>")
	)
	(segment
		(start 94.158816 -232.543858)
		(end 94.158816 -232.528364)
		(width 0.088646)
		(layer "In11.Cu")
		(net "M_D_CPU1_SB_DQ<12>")
	)
	(segment
		(start 82.37347 -229.7303)
		(end 80.880204 -229.7303)
		(width 0.18288)
		(layer "In11.Cu")
		(net "M_D_CPU1_SB_DQ<12>")
	)
	(segment
		(start 23.004272 -216.649046)
		(end 21.904706 -216.649046)
		(width 0.18288)
		(layer "In11.Cu")
		(net "M_D_CPU1_SB_DQ<12>")
	)
	(segment
		(start 92.187014 -231.39019)
		(end 92.172282 -231.398826)
		(width 0.088646)
		(layer "In11.Cu")
		(net "M_D_CPU1_SB_DQ<12>")
	)
	(segment
		(start 57.467754 -210.496658)
		(end 56.39054 -209.419444)
		(width 0.18288)
		(layer "In11.Cu")
		(net "M_D_CPU1_SB_DQ<12>")
	)
	(segment
		(start 30.429708 -209.642202)
		(end 29.022802 -209.642202)
		(width 0.18288)
		(layer "In11.Cu")
		(net "M_D_CPU1_SB_DQ<12>")
	)
	(segment
		(start 84.386166 -231.465882)
		(end 84.181696 -231.465882)
		(width 0.088646)
		(layer "In11.Cu")
		(net "M_D_CPU1_SB_DQ<12>")
	)
	(segment
		(start 66.411348 -212.907626)
		(end 65.333626 -212.907626)
		(width 0.18288)
		(layer "In11.Cu")
		(net "M_D_CPU1_SB_DQ<12>")
	)
	(segment
		(start 49.582832 -208.79308)
		(end 45.282358 -208.79308)
		(width 0.18288)
		(layer "In11.Cu")
		(net "M_D_CPU1_SB_DQ<12>")
	)
	(segment
		(start 54.759098 -209.419444)
		(end 53.279294 -207.93964)
		(width 0.18288)
		(layer "In11.Cu")
		(net "M_D_CPU1_SB_DQ<12>")
	)
	(segment
		(start 21.697188 -216.441528)
		(end 20.513548 -216.441528)
		(width 0.18288)
		(layer "In11.Cu")
		(net "M_D_CPU1_SB_DQ<12>")
	)
	(segment
		(start 80.880204 -229.7303)
		(end 69.724016 -218.574112)
		(width 0.18288)
		(layer "In11.Cu")
		(net "M_D_CPU1_SB_DQ<12>")
	)
	(segment
		(start 94.921324 -233.837988)
		(end 94.91091 -233.831892)
		(width 0.088646)
		(layer "In11.Cu")
		(net "M_D_CPU1_SB_DQ<12>")
	)
	(segment
		(start 94.628462 -233.360722)
		(end 94.628462 -233.34218)
		(width 0.088646)
		(layer "In11.Cu")
		(net "M_D_CPU1_SB_DQ<12>")
	)
	(segment
		(start 90.307414 -231.39019)
		(end 90.292682 -231.398826)
		(width 0.088646)
		(layer "In11.Cu")
		(net "M_D_CPU1_SB_DQ<12>")
	)
	(segment
		(start 89.367614 -231.39019)
		(end 89.352882 -231.398826)
		(width 0.088646)
		(layer "In11.Cu")
		(net "M_D_CPU1_SB_DQ<12>")
	)
	(segment
		(start 65.333626 -212.907626)
		(end 64.673226 -212.247226)
		(width 0.18288)
		(layer "In11.Cu")
		(net "M_D_CPU1_SB_DQ<12>")
	)
	(segment
		(start 94.4499 -233.022902)
		(end 94.44101 -233.017822)
		(width 0.088646)
		(layer "In11.Cu")
		(net "M_D_CPU1_SB_DQ<12>")
	)
	(segment
		(start 60.863226 -210.367626)
		(end 59.263026 -210.367626)
		(width 0.18288)
		(layer "In11.Cu")
		(net "M_D_CPU1_SB_DQ<12>")
	)
	(segment
		(start 45.282358 -208.79308)
		(end 45.237908 -208.83753)
		(width 0.18288)
		(layer "In11.Cu")
		(net "M_D_CPU1_SB_DQ<12>")
	)
	(segment
		(start 28.903676 -209.523076)
		(end 26.096976 -209.523076)
		(width 0.18288)
		(layer "In11.Cu")
		(net "M_D_CPU1_SB_DQ<12>")
	)
	(segment
		(start 59.133994 -210.496658)
		(end 57.467754 -210.496658)
		(width 0.18288)
		(layer "In11.Cu")
		(net "M_D_CPU1_SB_DQ<12>")
	)
	(segment
		(start 93.5101 -231.39527)
		(end 93.50121 -231.39019)
		(width 0.088646)
		(layer "In11.Cu")
		(net "M_D_CPU1_SB_DQ<12>")
	)
	(segment
		(start 38.224206 -207.93964)
		(end 35.330384 -207.93964)
		(width 0.18288)
		(layer "In11.Cu")
		(net "M_D_CPU1_SB_DQ<12>")
	)
	(segment
		(start 56.39054 -209.419444)
		(end 54.759098 -209.419444)
		(width 0.18288)
		(layer "In11.Cu")
		(net "M_D_CPU1_SB_DQ<12>")
	)
	(arc
		(start 96.790764 -233.831892)
		(mid 96.603566 -233.781749)
		(end 96.416368 -233.831892)
		(width 0.088646)
		(layer "In11.Cu")
		(net "M_D_CPU1_SB_DQ<12>")
	)
	(arc
		(start 88.4174 -231.396286)
		(mid 88.139222 -231.465978)
		(end 87.862664 -231.39019)
		(width 0.088646)
		(layer "In11.Cu")
		(net "M_D_CPU1_SB_DQ<12>")
	)
	(arc
		(start 93.959172 -232.196894)
		(mid 93.760944 -231.991046)
		(end 93.688662 -231.714548)
		(width 0.088646)
		(layer "In11.Cu")
		(net "M_D_CPU1_SB_DQ<12>")
	)
	(arc
		(start 89.74201 -231.39019)
		(mid 89.554812 -231.340047)
		(end 89.367614 -231.39019)
		(width 0.088646)
		(layer "In11.Cu")
		(net "M_D_CPU1_SB_DQ<12>")
	)
	(arc
		(start 98.483166 -234.15625)
		(mid 98.223242 -233.989927)
		(end 97.927668 -233.901234)
		(width 0.088646)
		(layer "In11.Cu")
		(net "M_D_CPU1_SB_DQ<12>")
	)
	(arc
		(start 87.488268 -231.39019)
		(mid 87.205566 -231.465932)
		(end 86.922864 -231.39019)
		(width 0.088646)
		(layer "In11.Cu")
		(net "M_D_CPU1_SB_DQ<12>")
	)
	(arc
		(start 95.850964 -233.831892)
		(mid 95.663766 -233.781749)
		(end 95.476568 -233.831892)
		(width 0.088646)
		(layer "In11.Cu")
		(net "M_D_CPU1_SB_DQ<12>")
	)
	(arc
		(start 93.688662 -231.714548)
		(mid 93.640983 -231.531648)
		(end 93.5101 -231.39527)
		(width 0.088646)
		(layer "In11.Cu")
		(net "M_D_CPU1_SB_DQ<12>")
	)
	(arc
		(start 89.352882 -231.398826)
		(mid 89.076441 -231.465992)
		(end 88.80221 -231.39019)
		(width 0.088646)
		(layer "In11.Cu")
		(net "M_D_CPU1_SB_DQ<12>")
	)
	(arc
		(start 95.476568 -233.831892)
		(mid 95.199755 -233.907728)
		(end 94.921324 -233.837988)
		(width 0.088646)
		(layer "In11.Cu")
		(net "M_D_CPU1_SB_DQ<12>")
	)
	(arc
		(start 97.730564 -233.831892)
		(mid 97.543366 -233.781749)
		(end 97.356168 -233.831892)
		(width 0.088646)
		(layer "In11.Cu")
		(net "M_D_CPU1_SB_DQ<12>")
	)
	(arc
		(start 91.62161 -231.39019)
		(mid 91.434412 -231.340047)
		(end 91.247214 -231.39019)
		(width 0.088646)
		(layer "In11.Cu")
		(net "M_D_CPU1_SB_DQ<12>")
	)
	(arc
		(start 93.50121 -231.39019)
		(mid 93.314012 -231.340047)
		(end 93.126814 -231.39019)
		(width 0.088646)
		(layer "In11.Cu")
		(net "M_D_CPU1_SB_DQ<12>")
	)
	(arc
		(start 90.68181 -231.39019)
		(mid 90.494612 -231.340047)
		(end 90.307414 -231.39019)
		(width 0.088646)
		(layer "In11.Cu")
		(net "M_D_CPU1_SB_DQ<12>")
	)
	(arc
		(start 94.91091 -233.831892)
		(mid 94.708624 -233.632911)
		(end 94.628462 -233.360722)
		(width 0.088646)
		(layer "In11.Cu")
		(net "M_D_CPU1_SB_DQ<12>")
	)
	(arc
		(start 85.983064 -231.39019)
		(mid 85.795866 -231.340047)
		(end 85.608668 -231.39019)
		(width 0.088646)
		(layer "In11.Cu")
		(net "M_D_CPU1_SB_DQ<12>")
	)
	(arc
		(start 87.862664 -231.39019)
		(mid 87.675466 -231.340047)
		(end 87.488268 -231.39019)
		(width 0.088646)
		(layer "In11.Cu")
		(net "M_D_CPU1_SB_DQ<12>")
	)
	(arc
		(start 85.608668 -231.39019)
		(mid 85.325966 -231.465932)
		(end 85.043264 -231.39019)
		(width 0.088646)
		(layer "In11.Cu")
		(net "M_D_CPU1_SB_DQ<12>")
	)
	(arc
		(start 96.416368 -233.831892)
		(mid 96.142139 -233.907817)
		(end 95.865696 -233.840528)
		(width 0.088646)
		(layer "In11.Cu")
		(net "M_D_CPU1_SB_DQ<12>")
	)
	(arc
		(start 86.548468 -231.39019)
		(mid 86.265766 -231.465932)
		(end 85.983064 -231.39019)
		(width 0.088646)
		(layer "In11.Cu")
		(net "M_D_CPU1_SB_DQ<12>")
	)
	(arc
		(start 94.628462 -233.34218)
		(mid 94.580783 -233.15928)
		(end 94.4499 -233.022902)
		(width 0.088646)
		(layer "In11.Cu")
		(net "M_D_CPU1_SB_DQ<12>")
	)
	(arc
		(start 94.44101 -233.017822)
		(mid 94.238187 -232.817591)
		(end 94.158816 -232.543858)
		(width 0.088646)
		(layer "In11.Cu")
		(net "M_D_CPU1_SB_DQ<12>")
	)
	(arc
		(start 94.158816 -232.528364)
		(mid 94.111137 -232.345464)
		(end 93.980254 -232.209086)
		(width 0.088646)
		(layer "In11.Cu")
		(net "M_D_CPU1_SB_DQ<12>")
	)
	(arc
		(start 85.043264 -231.39019)
		(mid 84.856066 -231.340047)
		(end 84.668868 -231.39019)
		(width 0.088646)
		(layer "In11.Cu")
		(net "M_D_CPU1_SB_DQ<12>")
	)
	(arc
		(start 90.292682 -231.398826)
		(mid 90.016241 -231.465992)
		(end 89.74201 -231.39019)
		(width 0.088646)
		(layer "In11.Cu")
		(net "M_D_CPU1_SB_DQ<12>")
	)
	(arc
		(start 93.112082 -231.398826)
		(mid 92.835641 -231.465992)
		(end 92.56141 -231.39019)
		(width 0.088646)
		(layer "In11.Cu")
		(net "M_D_CPU1_SB_DQ<12>")
	)
	(arc
		(start 92.56141 -231.39019)
		(mid 92.374212 -231.340047)
		(end 92.187014 -231.39019)
		(width 0.088646)
		(layer "In11.Cu")
		(net "M_D_CPU1_SB_DQ<12>")
	)
	(arc
		(start 86.922864 -231.39019)
		(mid 86.735666 -231.340047)
		(end 86.548468 -231.39019)
		(width 0.088646)
		(layer "In11.Cu")
		(net "M_D_CPU1_SB_DQ<12>")
	)
	(arc
		(start 97.356168 -233.831892)
		(mid 97.081939 -233.907817)
		(end 96.805496 -233.840528)
		(width 0.088646)
		(layer "In11.Cu")
		(net "M_D_CPU1_SB_DQ<12>")
	)
	(arc
		(start 91.247214 -231.39019)
		(mid 90.964512 -231.465932)
		(end 90.68181 -231.39019)
		(width 0.088646)
		(layer "In11.Cu")
		(net "M_D_CPU1_SB_DQ<12>")
	)
	(arc
		(start 92.172282 -231.398826)
		(mid 91.895841 -231.465992)
		(end 91.62161 -231.39019)
		(width 0.088646)
		(layer "In11.Cu")
		(net "M_D_CPU1_SB_DQ<12>")
	)
	(arc
		(start 88.80221 -231.39019)
		(mid 88.615012 -231.340047)
		(end 88.427814 -231.39019)
		(width 0.088646)
		(layer "In11.Cu")
		(net "M_D_CPU1_SB_DQ<12>")
	)
	(arc
		(start 84.668868 -231.39019)
		(mid 84.532502 -231.446668)
		(end 84.386166 -231.465882)
		(width 0.088646)
		(layer "In11.Cu")
		(net "M_D_CPU1_SB_DQ<12>")
	)
	(arc
		(start 97.927668 -233.901234)
		(mid 97.825881 -233.875756)
		(end 97.730564 -233.831892)
		(width 0.088646)
		(layer "In11.Cu")
		(net "M_D_CPU1_SB_DQ<12>")
	)
	(segment
		(start 14.812264 -220.69171)
		(end 16.885158 -220.69171)
		(width 0.1016)
		(layer "F.Cu")
		(net "M_D_CPU1_SB_DQ<11>")
	)
	(segment
		(start 12.240514 -220.266768)
		(end 13.937742 -220.266768)
		(width 0.20066)
		(layer "F.Cu")
		(net "M_D_CPU1_SB_DQ<11>")
	)
	(segment
		(start 14.560042 -220.705934)
		(end 14.574266 -220.69171)
		(width 0.101854)
		(layer "F.Cu")
		(net "M_D_CPU1_SB_DQ<11>")
	)
	(segment
		(start 17.578578 -220.390974)
		(end 17.707102 -220.26245)
		(width 0.20066)
		(layer "F.Cu")
		(net "M_D_CPU1_SB_DQ<11>")
	)
	(segment
		(start 18.102326 -220.26245)
		(end 18.314162 -220.474286)
		(width 0.20066)
		(layer "F.Cu")
		(net "M_D_CPU1_SB_DQ<11>")
	)
	(segment
		(start 14.063726 -220.392752)
		(end 14.063726 -220.56344)
		(width 0.20066)
		(layer "F.Cu")
		(net "M_D_CPU1_SB_DQ<11>")
	)
	(segment
		(start 14.063726 -220.56344)
		(end 14.20622 -220.705934)
		(width 0.20066)
		(layer "F.Cu")
		(net "M_D_CPU1_SB_DQ<11>")
	)
	(segment
		(start 17.42948 -220.69171)
		(end 17.578578 -220.542612)
		(width 0.20066)
		(layer "F.Cu")
		(net "M_D_CPU1_SB_DQ<11>")
	)
	(segment
		(start 20.889214 -220.266768)
		(end 19.784314 -220.266768)
		(width 0.20066)
		(layer "F.Cu")
		(net "M_D_CPU1_SB_DQ<11>")
	)
	(segment
		(start 16.885158 -220.69171)
		(end 17.42948 -220.69171)
		(width 0.20066)
		(layer "F.Cu")
		(net "M_D_CPU1_SB_DQ<11>")
	)
	(segment
		(start 18.968212 -220.266768)
		(end 19.784314 -220.266768)
		(width 0.20066)
		(layer "F.Cu")
		(net "M_D_CPU1_SB_DQ<11>")
	)
	(segment
		(start 100.362512 -236.319822)
		(end 100.362766 -236.319568)
		(width 0.20066)
		(layer "F.Cu")
		(net "M_D_CPU1_SB_DQ<11>")
	)
	(segment
		(start 13.937742 -220.266768)
		(end 14.063726 -220.392752)
		(width 0.20066)
		(layer "F.Cu")
		(net "M_D_CPU1_SB_DQ<11>")
	)
	(segment
		(start 18.314162 -220.474286)
		(end 18.760694 -220.474286)
		(width 0.20066)
		(layer "F.Cu")
		(net "M_D_CPU1_SB_DQ<11>")
	)
	(segment
		(start 14.20622 -220.705934)
		(end 14.560042 -220.705934)
		(width 0.20066)
		(layer "F.Cu")
		(net "M_D_CPU1_SB_DQ<11>")
	)
	(segment
		(start 100.362766 -236.319568)
		(end 100.362766 -235.783882)
		(width 0.20066)
		(layer "F.Cu")
		(net "M_D_CPU1_SB_DQ<11>")
	)
	(segment
		(start 17.578578 -220.542612)
		(end 17.578578 -220.390974)
		(width 0.20066)
		(layer "F.Cu")
		(net "M_D_CPU1_SB_DQ<11>")
	)
	(segment
		(start 14.574266 -220.69171)
		(end 14.812264 -220.69171)
		(width 0.101854)
		(layer "F.Cu")
		(net "M_D_CPU1_SB_DQ<11>")
	)
	(segment
		(start 18.760694 -220.474286)
		(end 18.968212 -220.266768)
		(width 0.20066)
		(layer "F.Cu")
		(net "M_D_CPU1_SB_DQ<11>")
	)
	(segment
		(start 17.707102 -220.26245)
		(end 18.102326 -220.26245)
		(width 0.20066)
		(layer "F.Cu")
		(net "M_D_CPU1_SB_DQ<11>")
	)
	(segment
		(start 48.076358 -213.892384)
		(end 46.007528 -213.892384)
		(width 0.18288)
		(layer "In11.Cu")
		(net "M_D_CPU1_SB_DQ<11>")
	)
	(segment
		(start 83.673696 -233.590846)
		(end 83.306412 -233.223562)
		(width 0.088646)
		(layer "In11.Cu")
		(net "M_D_CPU1_SB_DQ<11>")
	)
	(segment
		(start 94.925896 -236.099604)
		(end 94.911164 -236.10824)
		(width 0.088646)
		(layer "In11.Cu")
		(net "M_D_CPU1_SB_DQ<11>")
	)
	(segment
		(start 37.945822 -212.715094)
		(end 37.945822 -212.972142)
		(width 0.18288)
		(layer "In11.Cu")
		(net "M_D_CPU1_SB_DQ<11>")
	)
	(segment
		(start 51.875182 -213.190582)
		(end 51.726846 -213.042246)
		(width 0.18288)
		(layer "In11.Cu")
		(net "M_D_CPU1_SB_DQ<11>")
	)
	(segment
		(start 66.140584 -217.687398)
		(end 64.70523 -217.687398)
		(width 0.18288)
		(layer "In11.Cu")
		(net "M_D_CPU1_SB_DQ<11>")
	)
	(segment
		(start 64.70523 -217.687398)
		(end 64.370458 -217.352626)
		(width 0.18288)
		(layer "In11.Cu")
		(net "M_D_CPU1_SB_DQ<11>")
	)
	(segment
		(start 53.048408 -212.444076)
		(end 52.855368 -212.637116)
		(width 0.18288)
		(layer "In11.Cu")
		(net "M_D_CPU1_SB_DQ<11>")
	)
	(segment
		(start 93.046296 -236.099604)
		(end 93.031564 -236.10824)
		(width 0.088646)
		(layer "In11.Cu")
		(net "M_D_CPU1_SB_DQ<11>")
	)
	(segment
		(start 59.898026 -215.015826)
		(end 58.932826 -214.050626)
		(width 0.18288)
		(layer "In11.Cu")
		(net "M_D_CPU1_SB_DQ<11>")
	)
	(segment
		(start 38.839902 -213.165182)
		(end 38.646862 -212.972142)
		(width 0.18288)
		(layer "In11.Cu")
		(net "M_D_CPU1_SB_DQ<11>")
	)
	(segment
		(start 57.867804 -213.686644)
		(end 57.674764 -213.493604)
		(width 0.18288)
		(layer "In11.Cu")
		(net "M_D_CPU1_SB_DQ<11>")
	)
	(segment
		(start 22.588474 -220.854778)
		(end 21.477224 -220.854778)
		(width 0.18288)
		(layer "In11.Cu")
		(net "M_D_CPU1_SB_DQ<11>")
	)
	(segment
		(start 53.749448 -213.190582)
		(end 53.556408 -212.997542)
		(width 0.18288)
		(layer "In11.Cu")
		(net "M_D_CPU1_SB_DQ<11>")
	)
	(segment
		(start 57.166764 -213.686644)
		(end 57.166764 -213.857586)
		(width 0.18288)
		(layer "In11.Cu")
		(net "M_D_CPU1_SB_DQ<11>")
	)
	(segment
		(start 57.166764 -213.857586)
		(end 56.973724 -214.050626)
		(width 0.18288)
		(layer "In11.Cu")
		(net "M_D_CPU1_SB_DQ<11>")
	)
	(segment
		(start 31.348172 -213.796626)
		(end 29.164026 -213.796626)
		(width 0.18288)
		(layer "In11.Cu")
		(net "M_D_CPU1_SB_DQ<11>")
	)
	(segment
		(start 88.710516 -234.15625)
		(end 88.710516 -234.142026)
		(width 0.088646)
		(layer "In11.Cu")
		(net "M_D_CPU1_SB_DQ<11>")
	)
	(segment
		(start 98.464878 -235.40974)
		(end 98.457004 -235.410248)
		(width 0.088646)
		(layer "In11.Cu")
		(net "M_D_CPU1_SB_DQ<11>")
	)
	(segment
		(start 44.198286 -214.556086)
		(end 43.502834 -214.556086)
		(width 0.18288)
		(layer "In11.Cu")
		(net "M_D_CPU1_SB_DQ<11>")
	)
	(segment
		(start 45.03293 -214.866982)
		(end 44.509182 -214.866982)
		(width 0.18288)
		(layer "In11.Cu")
		(net "M_D_CPU1_SB_DQ<11>")
	)
	(segment
		(start 37.752782 -213.165182)
		(end 36.834826 -213.165182)
		(width 0.18288)
		(layer "In11.Cu")
		(net "M_D_CPU1_SB_DQ<11>")
	)
	(segment
		(start 38.646862 -212.972142)
		(end 38.646862 -212.715094)
		(width 0.18288)
		(layer "In11.Cu")
		(net "M_D_CPU1_SB_DQ<11>")
	)
	(segment
		(start 34.142426 -213.952582)
		(end 33.048956 -213.952582)
		(width 0.18288)
		(layer "In11.Cu")
		(net "M_D_CPU1_SB_DQ<11>")
	)
	(segment
		(start 35.052762 -213.042246)
		(end 34.142426 -213.952582)
		(width 0.18288)
		(layer "In11.Cu")
		(net "M_D_CPU1_SB_DQ<11>")
	)
	(segment
		(start 84.386166 -233.590846)
		(end 83.673696 -233.590846)
		(width 0.088646)
		(layer "In11.Cu")
		(net "M_D_CPU1_SB_DQ<11>")
	)
	(segment
		(start 53.556408 -212.637116)
		(end 53.363368 -212.444076)
		(width 0.18288)
		(layer "In11.Cu")
		(net "M_D_CPU1_SB_DQ<11>")
	)
	(segment
		(start 57.359804 -213.493604)
		(end 57.166764 -213.686644)
		(width 0.18288)
		(layer "In11.Cu")
		(net "M_D_CPU1_SB_DQ<11>")
	)
	(segment
		(start 42.789602 -213.974426)
		(end 42.596562 -213.781386)
		(width 0.18288)
		(layer "In11.Cu")
		(net "M_D_CPU1_SB_DQ<11>")
	)
	(segment
		(start 27.741626 -217.327734)
		(end 26.43124 -218.63812)
		(width 0.18288)
		(layer "In11.Cu")
		(net "M_D_CPU1_SB_DQ<11>")
	)
	(segment
		(start 52.855368 -212.997542)
		(end 52.662328 -213.190582)
		(width 0.18288)
		(layer "In11.Cu")
		(net "M_D_CPU1_SB_DQ<11>")
	)
	(segment
		(start 89.287096 -234.471972)
		(end 89.272364 -234.480608)
		(width 0.088646)
		(layer "In11.Cu")
		(net "M_D_CPU1_SB_DQ<11>")
	)
	(segment
		(start 38.138862 -212.522054)
		(end 37.945822 -212.715094)
		(width 0.18288)
		(layer "In11.Cu")
		(net "M_D_CPU1_SB_DQ<11>")
	)
	(segment
		(start 42.596562 -213.456774)
		(end 42.403522 -213.263734)
		(width 0.18288)
		(layer "In11.Cu")
		(net "M_D_CPU1_SB_DQ<11>")
	)
	(segment
		(start 43.150028 -213.974426)
		(end 42.789602 -213.974426)
		(width 0.18288)
		(layer "In11.Cu")
		(net "M_D_CPU1_SB_DQ<11>")
	)
	(segment
		(start 40.114982 -213.165182)
		(end 38.839902 -213.165182)
		(width 0.18288)
		(layer "In11.Cu")
		(net "M_D_CPU1_SB_DQ<11>")
	)
	(segment
		(start 52.662328 -213.190582)
		(end 51.875182 -213.190582)
		(width 0.18288)
		(layer "In11.Cu")
		(net "M_D_CPU1_SB_DQ<11>")
	)
	(segment
		(start 50.267362 -213.042246)
		(end 49.382426 -213.927182)
		(width 0.18288)
		(layer "In11.Cu")
		(net "M_D_CPU1_SB_DQ<11>")
	)
	(segment
		(start 32.988758 -213.892384)
		(end 31.44393 -213.892384)
		(width 0.18288)
		(layer "In11.Cu")
		(net "M_D_CPU1_SB_DQ<11>")
	)
	(segment
		(start 33.048956 -213.952582)
		(end 32.988758 -213.892384)
		(width 0.18288)
		(layer "In11.Cu")
		(net "M_D_CPU1_SB_DQ<11>")
	)
	(segment
		(start 23.65502 -219.788232)
		(end 22.588474 -220.854778)
		(width 0.18288)
		(layer "In11.Cu")
		(net "M_D_CPU1_SB_DQ<11>")
	)
	(segment
		(start 56.973724 -214.050626)
		(end 56.215026 -214.050626)
		(width 0.18288)
		(layer "In11.Cu")
		(net "M_D_CPU1_SB_DQ<11>")
	)
	(segment
		(start 43.502834 -214.556086)
		(end 43.277028 -214.33028)
		(width 0.18288)
		(layer "In11.Cu")
		(net "M_D_CPU1_SB_DQ<11>")
	)
	(segment
		(start 43.277028 -214.101426)
		(end 43.150028 -213.974426)
		(width 0.18288)
		(layer "In11.Cu")
		(net "M_D_CPU1_SB_DQ<11>")
	)
	(segment
		(start 27.741626 -215.219026)
		(end 27.741626 -217.327734)
		(width 0.18288)
		(layer "In11.Cu")
		(net "M_D_CPU1_SB_DQ<11>")
	)
	(segment
		(start 62.082426 -216.692226)
		(end 60.406026 -215.015826)
		(width 0.18288)
		(layer "In11.Cu")
		(net "M_D_CPU1_SB_DQ<11>")
	)
	(segment
		(start 37.945822 -212.972142)
		(end 37.752782 -213.165182)
		(width 0.18288)
		(layer "In11.Cu")
		(net "M_D_CPU1_SB_DQ<11>")
	)
	(segment
		(start 36.71189 -213.042246)
		(end 35.052762 -213.042246)
		(width 0.18288)
		(layer "In11.Cu")
		(net "M_D_CPU1_SB_DQ<11>")
	)
	(segment
		(start 90.307668 -235.294424)
		(end 90.298778 -235.289344)
		(width 0.088646)
		(layer "In11.Cu")
		(net "M_D_CPU1_SB_DQ<11>")
	)
	(segment
		(start 51.726846 -213.042246)
		(end 50.267362 -213.042246)
		(width 0.18288)
		(layer "In11.Cu")
		(net "M_D_CPU1_SB_DQ<11>")
	)
	(segment
		(start 38.646862 -212.715094)
		(end 38.453822 -212.522054)
		(width 0.18288)
		(layer "In11.Cu")
		(net "M_D_CPU1_SB_DQ<11>")
	)
	(segment
		(start 42.596562 -213.781386)
		(end 42.596562 -213.456774)
		(width 0.18288)
		(layer "In11.Cu")
		(net "M_D_CPU1_SB_DQ<11>")
	)
	(segment
		(start 92.106496 -236.099604)
		(end 92.091764 -236.10824)
		(width 0.088646)
		(layer "In11.Cu")
		(net "M_D_CPU1_SB_DQ<11>")
	)
	(segment
		(start 99.952556 -235.613956)
		(end 99.750626 -235.412026)
		(width 0.088646)
		(layer "In11.Cu")
		(net "M_D_CPU1_SB_DQ<11>")
	)
	(segment
		(start 41.702482 -213.974426)
		(end 40.924226 -213.974426)
		(width 0.18288)
		(layer "In11.Cu")
		(net "M_D_CPU1_SB_DQ<11>")
	)
	(segment
		(start 99.242626 -235.412026)
		(end 99.115626 -235.539026)
		(width 0.088646)
		(layer "In11.Cu")
		(net "M_D_CPU1_SB_DQ<11>")
	)
	(segment
		(start 67.868038 -219.945966)
		(end 67.492372 -219.039186)
		(width 0.18288)
		(layer "In11.Cu")
		(net "M_D_CPU1_SB_DQ<11>")
	)
	(segment
		(start 41.895522 -213.781386)
		(end 41.702482 -213.974426)
		(width 0.18288)
		(layer "In11.Cu")
		(net "M_D_CPU1_SB_DQ<11>")
	)
	(segment
		(start 43.277028 -214.33028)
		(end 43.277028 -214.101426)
		(width 0.18288)
		(layer "In11.Cu")
		(net "M_D_CPU1_SB_DQ<11>")
	)
	(segment
		(start 53.556408 -212.997542)
		(end 53.556408 -212.637116)
		(width 0.18288)
		(layer "In11.Cu")
		(net "M_D_CPU1_SB_DQ<11>")
	)
	(segment
		(start 52.855368 -212.637116)
		(end 52.855368 -212.997542)
		(width 0.18288)
		(layer "In11.Cu")
		(net "M_D_CPU1_SB_DQ<11>")
	)
	(segment
		(start 64.370458 -217.352626)
		(end 63.504826 -217.352626)
		(width 0.18288)
		(layer "In11.Cu")
		(net "M_D_CPU1_SB_DQ<11>")
	)
	(segment
		(start 53.363368 -212.444076)
		(end 53.048408 -212.444076)
		(width 0.18288)
		(layer "In11.Cu")
		(net "M_D_CPU1_SB_DQ<11>")
	)
	(segment
		(start 36.834826 -213.165182)
		(end 36.71189 -213.042246)
		(width 0.18288)
		(layer "In11.Cu")
		(net "M_D_CPU1_SB_DQ<11>")
	)
	(segment
		(start 44.509182 -214.866982)
		(end 44.198286 -214.556086)
		(width 0.18288)
		(layer "In11.Cu")
		(net "M_D_CPU1_SB_DQ<11>")
	)
	(segment
		(start 91.162124 -236.102144)
		(end 91.15171 -236.10824)
		(width 0.088646)
		(layer "In11.Cu")
		(net "M_D_CPU1_SB_DQ<11>")
	)
	(segment
		(start 57.674764 -213.493604)
		(end 57.359804 -213.493604)
		(width 0.18288)
		(layer "In11.Cu")
		(net "M_D_CPU1_SB_DQ<11>")
	)
	(segment
		(start 31.44393 -213.892384)
		(end 31.348172 -213.796626)
		(width 0.18288)
		(layer "In11.Cu")
		(net "M_D_CPU1_SB_DQ<11>")
	)
	(segment
		(start 49.382426 -213.927182)
		(end 48.111156 -213.927182)
		(width 0.18288)
		(layer "In11.Cu")
		(net "M_D_CPU1_SB_DQ<11>")
	)
	(segment
		(start 62.844426 -216.692226)
		(end 62.082426 -216.692226)
		(width 0.18288)
		(layer "In11.Cu")
		(net "M_D_CPU1_SB_DQ<11>")
	)
	(segment
		(start 88.427814 -233.666538)
		(end 88.4174 -233.660442)
		(width 0.088646)
		(layer "In11.Cu")
		(net "M_D_CPU1_SB_DQ<11>")
	)
	(segment
		(start 58.932826 -214.050626)
		(end 58.060844 -214.050626)
		(width 0.18288)
		(layer "In11.Cu")
		(net "M_D_CPU1_SB_DQ<11>")
	)
	(segment
		(start 42.403522 -213.263734)
		(end 42.088562 -213.263734)
		(width 0.18288)
		(layer "In11.Cu")
		(net "M_D_CPU1_SB_DQ<11>")
	)
	(segment
		(start 63.504826 -217.352626)
		(end 62.844426 -216.692226)
		(width 0.18288)
		(layer "In11.Cu")
		(net "M_D_CPU1_SB_DQ<11>")
	)
	(segment
		(start 60.406026 -215.015826)
		(end 59.898026 -215.015826)
		(width 0.18288)
		(layer "In11.Cu")
		(net "M_D_CPU1_SB_DQ<11>")
	)
	(segment
		(start 83.306412 -233.223562)
		(end 83.306412 -232.615994)
		(width 0.088646)
		(layer "In11.Cu")
		(net "M_D_CPU1_SB_DQ<11>")
	)
	(segment
		(start 56.215026 -214.050626)
		(end 55.354982 -213.190582)
		(width 0.18288)
		(layer "In11.Cu")
		(net "M_D_CPU1_SB_DQ<11>")
	)
	(segment
		(start 21.477224 -220.854778)
		(end 20.889214 -220.266768)
		(width 0.18288)
		(layer "In11.Cu")
		(net "M_D_CPU1_SB_DQ<11>")
	)
	(segment
		(start 89.843864 -234.484164)
		(end 89.837768 -234.480608)
		(width 0.088646)
		(layer "In11.Cu")
		(net "M_D_CPU1_SB_DQ<11>")
	)
	(segment
		(start 46.007528 -213.892384)
		(end 45.03293 -214.866982)
		(width 0.18288)
		(layer "In11.Cu")
		(net "M_D_CPU1_SB_DQ<11>")
	)
	(segment
		(start 26.43124 -218.63812)
		(end 23.65502 -219.788232)
		(width 0.18288)
		(layer "In11.Cu")
		(net "M_D_CPU1_SB_DQ<11>")
	)
	(segment
		(start 82.37347 -231.914446)
		(end 79.836518 -231.914446)
		(width 0.18288)
		(layer "In11.Cu")
		(net "M_D_CPU1_SB_DQ<11>")
	)
	(segment
		(start 83.306412 -232.615994)
		(end 82.604864 -231.914446)
		(width 0.088646)
		(layer "In11.Cu")
		(net "M_D_CPU1_SB_DQ<11>")
	)
	(segment
		(start 48.111156 -213.927182)
		(end 48.076358 -213.892384)
		(width 0.18288)
		(layer "In11.Cu")
		(net "M_D_CPU1_SB_DQ<11>")
	)
	(segment
		(start 40.924226 -213.974426)
		(end 40.114982 -213.165182)
		(width 0.18288)
		(layer "In11.Cu")
		(net "M_D_CPU1_SB_DQ<11>")
	)
	(segment
		(start 95.865696 -236.099604)
		(end 95.850964 -236.10824)
		(width 0.088646)
		(layer "In11.Cu")
		(net "M_D_CPU1_SB_DQ<11>")
	)
	(segment
		(start 96.801178 -236.102144)
		(end 96.790764 -236.10824)
		(width 0.088646)
		(layer "In11.Cu")
		(net "M_D_CPU1_SB_DQ<11>")
	)
	(segment
		(start 58.060844 -214.050626)
		(end 57.867804 -213.857586)
		(width 0.18288)
		(layer "In11.Cu")
		(net "M_D_CPU1_SB_DQ<11>")
	)
	(segment
		(start 38.453822 -212.522054)
		(end 38.138862 -212.522054)
		(width 0.18288)
		(layer "In11.Cu")
		(net "M_D_CPU1_SB_DQ<11>")
	)
	(segment
		(start 67.492372 -219.039186)
		(end 66.140584 -217.687398)
		(width 0.18288)
		(layer "In11.Cu")
		(net "M_D_CPU1_SB_DQ<11>")
	)
	(segment
		(start 42.088562 -213.263734)
		(end 41.895522 -213.456774)
		(width 0.18288)
		(layer "In11.Cu")
		(net "M_D_CPU1_SB_DQ<11>")
	)
	(segment
		(start 55.354982 -213.190582)
		(end 53.749448 -213.190582)
		(width 0.18288)
		(layer "In11.Cu")
		(net "M_D_CPU1_SB_DQ<11>")
	)
	(segment
		(start 90.590116 -235.792518)
		(end 90.590116 -235.773976)
		(width 0.088646)
		(layer "In11.Cu")
		(net "M_D_CPU1_SB_DQ<11>")
	)
	(segment
		(start 41.895522 -213.456774)
		(end 41.895522 -213.781386)
		(width 0.18288)
		(layer "In11.Cu")
		(net "M_D_CPU1_SB_DQ<11>")
	)
	(segment
		(start 29.164026 -213.796626)
		(end 27.741626 -215.219026)
		(width 0.18288)
		(layer "In11.Cu")
		(net "M_D_CPU1_SB_DQ<11>")
	)
	(segment
		(start 79.836518 -231.914446)
		(end 67.868038 -219.945966)
		(width 0.18288)
		(layer "In11.Cu")
		(net "M_D_CPU1_SB_DQ<11>")
	)
	(segment
		(start 88.897968 -234.480608)
		(end 88.889078 -234.475528)
		(width 0.088646)
		(layer "In11.Cu")
		(net "M_D_CPU1_SB_DQ<11>")
	)
	(segment
		(start 82.604864 -231.914446)
		(end 82.37347 -231.914446)
		(width 0.088646)
		(layer "In11.Cu")
		(net "M_D_CPU1_SB_DQ<11>")
	)
	(segment
		(start 57.867804 -213.857586)
		(end 57.867804 -213.686644)
		(width 0.18288)
		(layer "In11.Cu")
		(net "M_D_CPU1_SB_DQ<11>")
	)
	(arc
		(start 86.922864 -233.666538)
		(mid 86.735666 -233.716681)
		(end 86.548468 -233.666538)
		(width 0.088646)
		(layer "In11.Cu")
		(net "M_D_CPU1_SB_DQ<11>")
	)
	(arc
		(start 87.488268 -233.666538)
		(mid 87.205566 -233.590796)
		(end 86.922864 -233.666538)
		(width 0.088646)
		(layer "In11.Cu")
		(net "M_D_CPU1_SB_DQ<11>")
	)
	(arc
		(start 88.889078 -234.475528)
		(mid 88.758164 -234.339168)
		(end 88.710516 -234.15625)
		(width 0.088646)
		(layer "In11.Cu")
		(net "M_D_CPU1_SB_DQ<11>")
	)
	(arc
		(start 96.790764 -236.10824)
		(mid 96.603566 -236.158383)
		(end 96.416368 -236.10824)
		(width 0.088646)
		(layer "In11.Cu")
		(net "M_D_CPU1_SB_DQ<11>")
	)
	(arc
		(start 93.031564 -236.10824)
		(mid 92.844366 -236.158383)
		(end 92.657168 -236.10824)
		(width 0.088646)
		(layer "In11.Cu")
		(net "M_D_CPU1_SB_DQ<11>")
	)
	(arc
		(start 86.548468 -233.666538)
		(mid 86.265766 -233.590796)
		(end 85.983064 -233.666538)
		(width 0.088646)
		(layer "In11.Cu")
		(net "M_D_CPU1_SB_DQ<11>")
	)
	(arc
		(start 92.091764 -236.10824)
		(mid 91.904566 -236.158383)
		(end 91.717368 -236.10824)
		(width 0.088646)
		(layer "In11.Cu")
		(net "M_D_CPU1_SB_DQ<11>")
	)
	(arc
		(start 99.750626 -235.412026)
		(mid 99.496626 -235.306816)
		(end 99.242626 -235.412026)
		(width 0.088646)
		(layer "In11.Cu")
		(net "M_D_CPU1_SB_DQ<11>")
	)
	(arc
		(start 92.657168 -236.10824)
		(mid 92.382939 -236.032315)
		(end 92.106496 -236.099604)
		(width 0.088646)
		(layer "In11.Cu")
		(net "M_D_CPU1_SB_DQ<11>")
	)
	(arc
		(start 93.971364 -236.10824)
		(mid 93.784166 -236.158383)
		(end 93.596968 -236.10824)
		(width 0.088646)
		(layer "In11.Cu")
		(net "M_D_CPU1_SB_DQ<11>")
	)
	(arc
		(start 90.298778 -235.289344)
		(mid 90.167864 -235.152984)
		(end 90.120216 -234.970066)
		(width 0.088646)
		(layer "In11.Cu")
		(net "M_D_CPU1_SB_DQ<11>")
	)
	(arc
		(start 100.362766 -235.783882)
		(mid 100.140758 -235.739722)
		(end 99.952556 -235.613956)
		(width 0.088646)
		(layer "In11.Cu")
		(net "M_D_CPU1_SB_DQ<11>")
	)
	(arc
		(start 90.590116 -235.773976)
		(mid 90.512005 -235.497027)
		(end 90.307668 -235.294424)
		(width 0.088646)
		(layer "In11.Cu")
		(net "M_D_CPU1_SB_DQ<11>")
	)
	(arc
		(start 95.850964 -236.10824)
		(mid 95.663766 -236.158383)
		(end 95.476568 -236.10824)
		(width 0.088646)
		(layer "In11.Cu")
		(net "M_D_CPU1_SB_DQ<11>")
	)
	(arc
		(start 88.710516 -234.142026)
		(mid 88.631297 -233.867341)
		(end 88.427814 -233.666538)
		(width 0.088646)
		(layer "In11.Cu")
		(net "M_D_CPU1_SB_DQ<11>")
	)
	(arc
		(start 97.355914 -236.10824)
		(mid 97.079355 -236.032531)
		(end 96.801178 -236.102144)
		(width 0.088646)
		(layer "In11.Cu")
		(net "M_D_CPU1_SB_DQ<11>")
	)
	(arc
		(start 91.717368 -236.10824)
		(mid 91.440555 -236.032404)
		(end 91.162124 -236.102144)
		(width 0.088646)
		(layer "In11.Cu")
		(net "M_D_CPU1_SB_DQ<11>")
	)
	(arc
		(start 85.608668 -233.666538)
		(mid 85.325966 -233.590796)
		(end 85.043264 -233.666538)
		(width 0.088646)
		(layer "In11.Cu")
		(net "M_D_CPU1_SB_DQ<11>")
	)
	(arc
		(start 98.457004 -235.410248)
		(mid 98.373671 -235.425695)
		(end 98.295968 -235.459524)
		(width 0.088646)
		(layer "In11.Cu")
		(net "M_D_CPU1_SB_DQ<11>")
	)
	(arc
		(start 99.115626 -235.539026)
		(mid 98.963226 -235.602152)
		(end 98.810826 -235.539026)
		(width 0.088646)
		(layer "In11.Cu")
		(net "M_D_CPU1_SB_DQ<11>")
	)
	(arc
		(start 94.536768 -236.10824)
		(mid 94.254066 -236.032498)
		(end 93.971364 -236.10824)
		(width 0.088646)
		(layer "In11.Cu")
		(net "M_D_CPU1_SB_DQ<11>")
	)
	(arc
		(start 85.983064 -233.666538)
		(mid 85.795866 -233.716681)
		(end 85.608668 -233.666538)
		(width 0.088646)
		(layer "In11.Cu")
		(net "M_D_CPU1_SB_DQ<11>")
	)
	(arc
		(start 97.73031 -236.10824)
		(mid 97.543112 -236.158383)
		(end 97.355914 -236.10824)
		(width 0.088646)
		(layer "In11.Cu")
		(net "M_D_CPU1_SB_DQ<11>")
	)
	(arc
		(start 84.668868 -233.666538)
		(mid 84.532502 -233.61006)
		(end 84.386166 -233.590846)
		(width 0.088646)
		(layer "In11.Cu")
		(net "M_D_CPU1_SB_DQ<11>")
	)
	(arc
		(start 98.810826 -235.539026)
		(mid 98.65188 -235.436879)
		(end 98.464878 -235.40974)
		(width 0.088646)
		(layer "In11.Cu")
		(net "M_D_CPU1_SB_DQ<11>")
	)
	(arc
		(start 93.596968 -236.10824)
		(mid 93.322739 -236.032315)
		(end 93.046296 -236.099604)
		(width 0.088646)
		(layer "In11.Cu")
		(net "M_D_CPU1_SB_DQ<11>")
	)
	(arc
		(start 98.12274 -235.639356)
		(mid 97.968032 -235.908535)
		(end 97.73031 -236.10824)
		(width 0.088646)
		(layer "In11.Cu")
		(net "M_D_CPU1_SB_DQ<11>")
	)
	(arc
		(start 89.837768 -234.480608)
		(mid 89.563569 -234.404773)
		(end 89.287096 -234.471972)
		(width 0.088646)
		(layer "In11.Cu")
		(net "M_D_CPU1_SB_DQ<11>")
	)
	(arc
		(start 94.911164 -236.10824)
		(mid 94.723966 -236.158383)
		(end 94.536768 -236.10824)
		(width 0.088646)
		(layer "In11.Cu")
		(net "M_D_CPU1_SB_DQ<11>")
	)
	(arc
		(start 91.15171 -236.10824)
		(mid 90.964512 -236.158383)
		(end 90.777314 -236.10824)
		(width 0.088646)
		(layer "In11.Cu")
		(net "M_D_CPU1_SB_DQ<11>")
	)
	(arc
		(start 90.777314 -236.10824)
		(mid 90.642381 -235.974886)
		(end 90.590116 -235.792518)
		(width 0.088646)
		(layer "In11.Cu")
		(net "M_D_CPU1_SB_DQ<11>")
	)
	(arc
		(start 96.416368 -236.10824)
		(mid 96.142139 -236.032315)
		(end 95.865696 -236.099604)
		(width 0.088646)
		(layer "In11.Cu")
		(net "M_D_CPU1_SB_DQ<11>")
	)
	(arc
		(start 87.862664 -233.666538)
		(mid 87.675466 -233.716681)
		(end 87.488268 -233.666538)
		(width 0.088646)
		(layer "In11.Cu")
		(net "M_D_CPU1_SB_DQ<11>")
	)
	(arc
		(start 95.476568 -236.10824)
		(mid 95.202339 -236.032315)
		(end 94.925896 -236.099604)
		(width 0.088646)
		(layer "In11.Cu")
		(net "M_D_CPU1_SB_DQ<11>")
	)
	(arc
		(start 90.120216 -234.970066)
		(mid 90.0463 -234.690564)
		(end 89.843864 -234.484164)
		(width 0.088646)
		(layer "In11.Cu")
		(net "M_D_CPU1_SB_DQ<11>")
	)
	(arc
		(start 89.272364 -234.480608)
		(mid 89.085166 -234.530751)
		(end 88.897968 -234.480608)
		(width 0.088646)
		(layer "In11.Cu")
		(net "M_D_CPU1_SB_DQ<11>")
	)
	(arc
		(start 88.4174 -233.660442)
		(mid 88.139222 -233.59075)
		(end 87.862664 -233.666538)
		(width 0.088646)
		(layer "In11.Cu")
		(net "M_D_CPU1_SB_DQ<11>")
	)
	(arc
		(start 85.043264 -233.666538)
		(mid 84.856066 -233.716681)
		(end 84.668868 -233.666538)
		(width 0.088646)
		(layer "In11.Cu")
		(net "M_D_CPU1_SB_DQ<11>")
	)
	(arc
		(start 98.295968 -235.459524)
		(mid 98.19664 -235.537194)
		(end 98.12274 -235.639356)
		(width 0.088646)
		(layer "In11.Cu")
		(net "M_D_CPU1_SB_DQ<11>")
	)
	(segment
		(start 14.560042 -221.531688)
		(end 14.570202 -221.541848)
		(width 0.101854)
		(layer "F.Cu")
		(net "M_D_CPU1_SB_DQ<10>")
	)
	(segment
		(start 14.570202 -221.541848)
		(end 14.825218 -221.541848)
		(width 0.101854)
		(layer "F.Cu")
		(net "M_D_CPU1_SB_DQ<10>")
	)
	(segment
		(start 16.885158 -221.541848)
		(end 17.518126 -221.541848)
		(width 0.20066)
		(layer "F.Cu")
		(net "M_D_CPU1_SB_DQ<10>")
	)
	(segment
		(start 18.257774 -222.178626)
		(end 18.46961 -221.96679)
		(width 0.20066)
		(layer "F.Cu")
		(net "M_D_CPU1_SB_DQ<10>")
	)
	(segment
		(start 18.46961 -221.96679)
		(end 19.784314 -221.96679)
		(width 0.20066)
		(layer "F.Cu")
		(net "M_D_CPU1_SB_DQ<10>")
	)
	(segment
		(start 17.66189 -222.01124)
		(end 17.829276 -222.178626)
		(width 0.20066)
		(layer "F.Cu")
		(net "M_D_CPU1_SB_DQ<10>")
	)
	(segment
		(start 17.66189 -221.685612)
		(end 17.66189 -222.01124)
		(width 0.20066)
		(layer "F.Cu")
		(net "M_D_CPU1_SB_DQ<10>")
	)
	(segment
		(start 13.387578 -221.96679)
		(end 13.82268 -221.531688)
		(width 0.20066)
		(layer "F.Cu")
		(net "M_D_CPU1_SB_DQ<10>")
	)
	(segment
		(start 99.892866 -237.133892)
		(end 99.892612 -237.133638)
		(width 0.20066)
		(layer "F.Cu")
		(net "M_D_CPU1_SB_DQ<10>")
	)
	(segment
		(start 14.825218 -221.541848)
		(end 16.885158 -221.541848)
		(width 0.1016)
		(layer "F.Cu")
		(net "M_D_CPU1_SB_DQ<10>")
	)
	(segment
		(start 12.240514 -221.96679)
		(end 13.387578 -221.96679)
		(width 0.20066)
		(layer "F.Cu")
		(net "M_D_CPU1_SB_DQ<10>")
	)
	(segment
		(start 17.518126 -221.541848)
		(end 17.66189 -221.685612)
		(width 0.20066)
		(layer "F.Cu")
		(net "M_D_CPU1_SB_DQ<10>")
	)
	(segment
		(start 13.82268 -221.531688)
		(end 14.560042 -221.531688)
		(width 0.20066)
		(layer "F.Cu")
		(net "M_D_CPU1_SB_DQ<10>")
	)
	(segment
		(start 20.889214 -221.96679)
		(end 19.784314 -221.96679)
		(width 0.20066)
		(layer "F.Cu")
		(net "M_D_CPU1_SB_DQ<10>")
	)
	(segment
		(start 99.892612 -237.133638)
		(end 99.892612 -236.597952)
		(width 0.20066)
		(layer "F.Cu")
		(net "M_D_CPU1_SB_DQ<10>")
	)
	(segment
		(start 17.829276 -222.178626)
		(end 18.257774 -222.178626)
		(width 0.20066)
		(layer "F.Cu")
		(net "M_D_CPU1_SB_DQ<10>")
	)
	(segment
		(start 48.799496 -215.879426)
		(end 48.598074 -215.678004)
		(width 0.18288)
		(layer "In11.Cu")
		(net "M_D_CPU1_SB_DQ<10>")
	)
	(segment
		(start 97.825814 -236.922056)
		(end 97.811082 -236.91342)
		(width 0.088646)
		(layer "In11.Cu")
		(net "M_D_CPU1_SB_DQ<10>")
	)
	(segment
		(start 46.441614 -215.777064)
		(end 46.248574 -215.584024)
		(width 0.18288)
		(layer "In11.Cu")
		(net "M_D_CPU1_SB_DQ<10>")
	)
	(segment
		(start 51.8287 -215.592152)
		(end 50.344578 -215.592152)
		(width 0.18288)
		(layer "In11.Cu")
		(net "M_D_CPU1_SB_DQ<10>")
	)
	(segment
		(start 52.967636 -214.441278)
		(end 52.967636 -215.13419)
		(width 0.18288)
		(layer "In11.Cu")
		(net "M_D_CPU1_SB_DQ<10>")
	)
	(segment
		(start 25.539446 -220.603826)
		(end 24.677624 -221.465648)
		(width 0.18288)
		(layer "In11.Cu")
		(net "M_D_CPU1_SB_DQ<10>")
	)
	(segment
		(start 38.62324 -215.181942)
		(end 38.62324 -214.509858)
		(width 0.18288)
		(layer "In11.Cu")
		(net "M_D_CPU1_SB_DQ<10>")
	)
	(segment
		(start 62.483238 -218.972638)
		(end 59.999626 -216.489026)
		(width 0.18288)
		(layer "In11.Cu")
		(net "M_D_CPU1_SB_DQ<10>")
	)
	(segment
		(start 50.151538 -215.256872)
		(end 49.958498 -215.063832)
		(width 0.18288)
		(layer "In11.Cu")
		(net "M_D_CPU1_SB_DQ<10>")
	)
	(segment
		(start 95.946214 -236.922056)
		(end 95.931482 -236.91342)
		(width 0.088646)
		(layer "In11.Cu")
		(net "M_D_CPU1_SB_DQ<10>")
	)
	(segment
		(start 87.407496 -234.471972)
		(end 87.392764 -234.480608)
		(width 0.088646)
		(layer "In11.Cu")
		(net "M_D_CPU1_SB_DQ<10>")
	)
	(segment
		(start 47.260002 -216.441274)
		(end 46.634654 -216.441274)
		(width 0.18288)
		(layer "In11.Cu")
		(net "M_D_CPU1_SB_DQ<10>")
	)
	(segment
		(start 86.467696 -234.471972)
		(end 86.452964 -234.480608)
		(width 0.088646)
		(layer "In11.Cu")
		(net "M_D_CPU1_SB_DQ<10>")
	)
	(segment
		(start 43.909742 -216.248742)
		(end 42.940986 -216.248742)
		(width 0.18288)
		(layer "In11.Cu")
		(net "M_D_CPU1_SB_DQ<10>")
	)
	(segment
		(start 52.967636 -215.13419)
		(end 52.774596 -215.32723)
		(width 0.18288)
		(layer "In11.Cu")
		(net "M_D_CPU1_SB_DQ<10>")
	)
	(segment
		(start 63.7794 -218.779598)
		(end 63.7794 -218.6051)
		(width 0.18288)
		(layer "In11.Cu")
		(net "M_D_CPU1_SB_DQ<10>")
	)
	(segment
		(start 58.92165 -215.701626)
		(end 56.21147 -215.701626)
		(width 0.18288)
		(layer "In11.Cu")
		(net "M_D_CPU1_SB_DQ<10>")
	)
	(segment
		(start 48.598074 -215.678004)
		(end 48.023272 -215.678004)
		(width 0.18288)
		(layer "In11.Cu")
		(net "M_D_CPU1_SB_DQ<10>")
	)
	(segment
		(start 35.34918 -215.676226)
		(end 33.079182 -215.676226)
		(width 0.18288)
		(layer "In11.Cu")
		(net "M_D_CPU1_SB_DQ<10>")
	)
	(segment
		(start 91.247214 -236.922056)
		(end 91.232482 -236.91342)
		(width 0.088646)
		(layer "In11.Cu")
		(net "M_D_CPU1_SB_DQ<10>")
	)
	(segment
		(start 45.740574 -216.295986)
		(end 45.547534 -216.489026)
		(width 0.18288)
		(layer "In11.Cu")
		(net "M_D_CPU1_SB_DQ<10>")
	)
	(segment
		(start 37.9222 -215.181942)
		(end 37.72916 -215.374982)
		(width 0.18288)
		(layer "In11.Cu")
		(net "M_D_CPU1_SB_DQ<10>")
	)
	(segment
		(start 49.450498 -215.686386)
		(end 49.257458 -215.879426)
		(width 0.18288)
		(layer "In11.Cu")
		(net "M_D_CPU1_SB_DQ<10>")
	)
	(segment
		(start 59.70905 -216.489026)
		(end 58.92165 -215.701626)
		(width 0.18288)
		(layer "In11.Cu")
		(net "M_D_CPU1_SB_DQ<10>")
	)
	(segment
		(start 95.006414 -236.922056)
		(end 94.996 -236.91596)
		(width 0.088646)
		(layer "In11.Cu")
		(net "M_D_CPU1_SB_DQ<10>")
	)
	(segment
		(start 29.913326 -218.609926)
		(end 28.262326 -218.609926)
		(width 0.18288)
		(layer "In11.Cu")
		(net "M_D_CPU1_SB_DQ<10>")
	)
	(segment
		(start 82.37347 -232.932478)
		(end 79.299562 -232.932478)
		(width 0.18288)
		(layer "In11.Cu")
		(net "M_D_CPU1_SB_DQ<10>")
	)
	(segment
		(start 52.774596 -215.32723)
		(end 52.093622 -215.32723)
		(width 0.18288)
		(layer "In11.Cu")
		(net "M_D_CPU1_SB_DQ<10>")
	)
	(segment
		(start 56.21147 -215.701626)
		(end 55.984394 -215.47455)
		(width 0.18288)
		(layer "In11.Cu")
		(net "M_D_CPU1_SB_DQ<10>")
	)
	(segment
		(start 30.180026 -216.831418)
		(end 30.180026 -218.343226)
		(width 0.18288)
		(layer "In11.Cu")
		(net "M_D_CPU1_SB_DQ<10>")
	)
	(segment
		(start 90.307414 -236.922056)
		(end 90.29319 -236.913928)
		(width 0.088646)
		(layer "In11.Cu")
		(net "M_D_CPU1_SB_DQ<10>")
	)
	(segment
		(start 38.11524 -214.316818)
		(end 37.9222 -214.509858)
		(width 0.18288)
		(layer "In11.Cu")
		(net "M_D_CPU1_SB_DQ<10>")
	)
	(segment
		(start 33.079182 -215.676226)
		(end 32.313118 -216.44229)
		(width 0.18288)
		(layer "In11.Cu")
		(net "M_D_CPU1_SB_DQ<10>")
	)
	(segment
		(start 94.066868 -236.922056)
		(end 94.056454 -236.91596)
		(width 0.088646)
		(layer "In11.Cu")
		(net "M_D_CPU1_SB_DQ<10>")
	)
	(segment
		(start 40.617648 -215.830404)
		(end 40.162226 -215.374982)
		(width 0.18288)
		(layer "In11.Cu")
		(net "M_D_CPU1_SB_DQ<10>")
	)
	(segment
		(start 27.386026 -219.638626)
		(end 26.420826 -220.603826)
		(width 0.18288)
		(layer "In11.Cu")
		(net "M_D_CPU1_SB_DQ<10>")
	)
	(segment
		(start 89.37371 -235.29798)
		(end 89.367614 -235.294424)
		(width 0.088646)
		(layer "In11.Cu")
		(net "M_D_CPU1_SB_DQ<10>")
	)
	(segment
		(start 53.668676 -214.441278)
		(end 53.475636 -214.248238)
		(width 0.18288)
		(layer "In11.Cu")
		(net "M_D_CPU1_SB_DQ<10>")
	)
	(segment
		(start 21.496782 -221.96679)
		(end 20.889214 -221.96679)
		(width 0.18288)
		(layer "In11.Cu")
		(net "M_D_CPU1_SB_DQ<10>")
	)
	(segment
		(start 98.387662 -236.583728)
		(end 98.387662 -236.597952)
		(width 0.088646)
		(layer "In11.Cu")
		(net "M_D_CPU1_SB_DQ<10>")
	)
	(segment
		(start 53.475636 -214.248238)
		(end 53.160676 -214.248238)
		(width 0.18288)
		(layer "In11.Cu")
		(net "M_D_CPU1_SB_DQ<10>")
	)
	(segment
		(start 32.313118 -216.44229)
		(end 30.569154 -216.44229)
		(width 0.18288)
		(layer "In11.Cu")
		(net "M_D_CPU1_SB_DQ<10>")
	)
	(segment
		(start 38.4302 -214.316818)
		(end 38.11524 -214.316818)
		(width 0.18288)
		(layer "In11.Cu")
		(net "M_D_CPU1_SB_DQ<10>")
	)
	(segment
		(start 84.588096 -234.471972)
		(end 84.573364 -234.480608)
		(width 0.088646)
		(layer "In11.Cu")
		(net "M_D_CPU1_SB_DQ<10>")
	)
	(segment
		(start 46.634654 -216.441274)
		(end 46.441614 -216.248234)
		(width 0.18288)
		(layer "In11.Cu")
		(net "M_D_CPU1_SB_DQ<10>")
	)
	(segment
		(start 36.897056 -215.592152)
		(end 35.433254 -215.592152)
		(width 0.18288)
		(layer "In11.Cu")
		(net "M_D_CPU1_SB_DQ<10>")
	)
	(segment
		(start 82.820256 -233.063288)
		(end 82.689446 -232.932478)
		(width 0.088646)
		(layer "In11.Cu")
		(net "M_D_CPU1_SB_DQ<10>")
	)
	(segment
		(start 82.820256 -233.284014)
		(end 82.820256 -233.063288)
		(width 0.088646)
		(layer "In11.Cu")
		(net "M_D_CPU1_SB_DQ<10>")
	)
	(segment
		(start 63.7794 -218.6051)
		(end 63.58636 -218.41206)
		(width 0.18288)
		(layer "In11.Cu")
		(net "M_D_CPU1_SB_DQ<10>")
	)
	(segment
		(start 30.569154 -216.44229)
		(end 30.180026 -216.831418)
		(width 0.18288)
		(layer "In11.Cu")
		(net "M_D_CPU1_SB_DQ<10>")
	)
	(segment
		(start 64.222122 -218.972638)
		(end 63.97244 -218.972638)
		(width 0.18288)
		(layer "In11.Cu")
		(net "M_D_CPU1_SB_DQ<10>")
	)
	(segment
		(start 53.668676 -215.28151)
		(end 53.668676 -214.441278)
		(width 0.18288)
		(layer "In11.Cu")
		(net "M_D_CPU1_SB_DQ<10>")
	)
	(segment
		(start 96.886014 -236.922056)
		(end 96.871282 -236.91342)
		(width 0.088646)
		(layer "In11.Cu")
		(net "M_D_CPU1_SB_DQ<10>")
	)
	(segment
		(start 52.093622 -215.32723)
		(end 51.8287 -215.592152)
		(width 0.18288)
		(layer "In11.Cu")
		(net "M_D_CPU1_SB_DQ<10>")
	)
	(segment
		(start 49.643538 -215.063832)
		(end 49.450498 -215.256872)
		(width 0.18288)
		(layer "In11.Cu")
		(net "M_D_CPU1_SB_DQ<10>")
	)
	(segment
		(start 35.433254 -215.592152)
		(end 35.34918 -215.676226)
		(width 0.18288)
		(layer "In11.Cu")
		(net "M_D_CPU1_SB_DQ<10>")
	)
	(segment
		(start 50.151538 -215.399112)
		(end 50.151538 -215.256872)
		(width 0.18288)
		(layer "In11.Cu")
		(net "M_D_CPU1_SB_DQ<10>")
	)
	(segment
		(start 66.36131 -219.994226)
		(end 65.24371 -219.994226)
		(width 0.18288)
		(layer "In11.Cu")
		(net "M_D_CPU1_SB_DQ<10>")
	)
	(segment
		(start 27.386026 -219.486226)
		(end 27.386026 -219.638626)
		(width 0.18288)
		(layer "In11.Cu")
		(net "M_D_CPU1_SB_DQ<10>")
	)
	(segment
		(start 88.427814 -235.294424)
		(end 88.418924 -235.289344)
		(width 0.088646)
		(layer "In11.Cu")
		(net "M_D_CPU1_SB_DQ<10>")
	)
	(segment
		(start 45.740574 -215.777064)
		(end 45.740574 -216.295986)
		(width 0.18288)
		(layer "In11.Cu")
		(net "M_D_CPU1_SB_DQ<10>")
	)
	(segment
		(start 99.313238 -236.152944)
		(end 99.235768 -236.10824)
		(width 0.088646)
		(layer "In11.Cu")
		(net "M_D_CPU1_SB_DQ<10>")
	)
	(segment
		(start 37.114226 -215.374982)
		(end 36.897056 -215.592152)
		(width 0.18288)
		(layer "In11.Cu")
		(net "M_D_CPU1_SB_DQ<10>")
	)
	(segment
		(start 98.685096 -236.099604)
		(end 98.670364 -236.10824)
		(width 0.088646)
		(layer "In11.Cu")
		(net "M_D_CPU1_SB_DQ<10>")
	)
	(segment
		(start 62.88532 -218.972638)
		(end 62.483238 -218.972638)
		(width 0.18288)
		(layer "In11.Cu")
		(net "M_D_CPU1_SB_DQ<10>")
	)
	(segment
		(start 85.527896 -234.471972)
		(end 85.513164 -234.480608)
		(width 0.088646)
		(layer "In11.Cu")
		(net "M_D_CPU1_SB_DQ<10>")
	)
	(segment
		(start 30.180026 -218.343226)
		(end 29.913326 -218.609926)
		(width 0.18288)
		(layer "In11.Cu")
		(net "M_D_CPU1_SB_DQ<10>")
	)
	(segment
		(start 49.257458 -215.879426)
		(end 48.799496 -215.879426)
		(width 0.18288)
		(layer "In11.Cu")
		(net "M_D_CPU1_SB_DQ<10>")
	)
	(segment
		(start 46.248574 -215.584024)
		(end 45.933614 -215.584024)
		(width 0.18288)
		(layer "In11.Cu")
		(net "M_D_CPU1_SB_DQ<10>")
	)
	(segment
		(start 26.420826 -220.603826)
		(end 25.539446 -220.603826)
		(width 0.18288)
		(layer "In11.Cu")
		(net "M_D_CPU1_SB_DQ<10>")
	)
	(segment
		(start 37.9222 -214.509858)
		(end 37.9222 -215.181942)
		(width 0.18288)
		(layer "In11.Cu")
		(net "M_D_CPU1_SB_DQ<10>")
	)
	(segment
		(start 22.778212 -222.5548)
		(end 22.084792 -222.5548)
		(width 0.18288)
		(layer "In11.Cu")
		(net "M_D_CPU1_SB_DQ<10>")
	)
	(segment
		(start 23.867364 -221.465648)
		(end 22.778212 -222.5548)
		(width 0.18288)
		(layer "In11.Cu")
		(net "M_D_CPU1_SB_DQ<10>")
	)
	(segment
		(start 49.958498 -215.063832)
		(end 49.643538 -215.063832)
		(width 0.18288)
		(layer "In11.Cu")
		(net "M_D_CPU1_SB_DQ<10>")
	)
	(segment
		(start 24.677624 -221.465648)
		(end 23.867364 -221.465648)
		(width 0.18288)
		(layer "In11.Cu")
		(net "M_D_CPU1_SB_DQ<10>")
	)
	(segment
		(start 42.940986 -216.248742)
		(end 42.522648 -215.830404)
		(width 0.18288)
		(layer "In11.Cu")
		(net "M_D_CPU1_SB_DQ<10>")
	)
	(segment
		(start 63.07836 -218.6051)
		(end 63.07836 -218.779598)
		(width 0.18288)
		(layer "In11.Cu")
		(net "M_D_CPU1_SB_DQ<10>")
	)
	(segment
		(start 84.067396 -234.531154)
		(end 82.820256 -233.284014)
		(width 0.088646)
		(layer "In11.Cu")
		(net "M_D_CPU1_SB_DQ<10>")
	)
	(segment
		(start 88.240362 -234.970066)
		(end 88.240362 -234.954572)
		(width 0.088646)
		(layer "In11.Cu")
		(net "M_D_CPU1_SB_DQ<10>")
	)
	(segment
		(start 38.81628 -215.374982)
		(end 38.62324 -215.181942)
		(width 0.18288)
		(layer "In11.Cu")
		(net "M_D_CPU1_SB_DQ<10>")
	)
	(segment
		(start 44.150026 -216.489026)
		(end 43.909742 -216.248742)
		(width 0.18288)
		(layer "In11.Cu")
		(net "M_D_CPU1_SB_DQ<10>")
	)
	(segment
		(start 50.344578 -215.592152)
		(end 50.151538 -215.399112)
		(width 0.18288)
		(layer "In11.Cu")
		(net "M_D_CPU1_SB_DQ<10>")
	)
	(segment
		(start 82.689446 -232.932478)
		(end 82.37347 -232.932478)
		(width 0.088646)
		(layer "In11.Cu")
		(net "M_D_CPU1_SB_DQ<10>")
	)
	(segment
		(start 79.299562 -232.932478)
		(end 66.36131 -219.994226)
		(width 0.18288)
		(layer "In11.Cu")
		(net "M_D_CPU1_SB_DQ<10>")
	)
	(segment
		(start 89.367614 -235.294424)
		(end 89.352882 -235.285788)
		(width 0.088646)
		(layer "In11.Cu")
		(net "M_D_CPU1_SB_DQ<10>")
	)
	(segment
		(start 38.62324 -214.509858)
		(end 38.4302 -214.316818)
		(width 0.18288)
		(layer "In11.Cu")
		(net "M_D_CPU1_SB_DQ<10>")
	)
	(segment
		(start 63.2714 -218.41206)
		(end 63.07836 -218.6051)
		(width 0.18288)
		(layer "In11.Cu")
		(net "M_D_CPU1_SB_DQ<10>")
	)
	(segment
		(start 90.119962 -236.597952)
		(end 90.119962 -236.575854)
		(width 0.088646)
		(layer "In11.Cu")
		(net "M_D_CPU1_SB_DQ<10>")
	)
	(segment
		(start 98.2091 -236.91723)
		(end 98.20021 -236.92231)
		(width 0.088646)
		(layer "In11.Cu")
		(net "M_D_CPU1_SB_DQ<10>")
	)
	(segment
		(start 22.084792 -222.5548)
		(end 21.496782 -221.96679)
		(width 0.18288)
		(layer "In11.Cu")
		(net "M_D_CPU1_SB_DQ<10>")
	)
	(segment
		(start 89.837768 -236.10824)
		(end 89.828878 -236.10316)
		(width 0.088646)
		(layer "In11.Cu")
		(net "M_D_CPU1_SB_DQ<10>")
	)
	(segment
		(start 48.023272 -215.678004)
		(end 47.260002 -216.441274)
		(width 0.18288)
		(layer "In11.Cu")
		(net "M_D_CPU1_SB_DQ<10>")
	)
	(segment
		(start 37.72916 -215.374982)
		(end 37.114226 -215.374982)
		(width 0.18288)
		(layer "In11.Cu")
		(net "M_D_CPU1_SB_DQ<10>")
	)
	(segment
		(start 93.126814 -236.922056)
		(end 93.112082 -236.91342)
		(width 0.088646)
		(layer "In11.Cu")
		(net "M_D_CPU1_SB_DQ<10>")
	)
	(segment
		(start 63.07836 -218.779598)
		(end 62.88532 -218.972638)
		(width 0.18288)
		(layer "In11.Cu")
		(net "M_D_CPU1_SB_DQ<10>")
	)
	(segment
		(start 49.450498 -215.256872)
		(end 49.450498 -215.686386)
		(width 0.18288)
		(layer "In11.Cu")
		(net "M_D_CPU1_SB_DQ<10>")
	)
	(segment
		(start 42.522648 -215.830404)
		(end 40.617648 -215.830404)
		(width 0.18288)
		(layer "In11.Cu")
		(net "M_D_CPU1_SB_DQ<10>")
	)
	(segment
		(start 84.386166 -234.531154)
		(end 84.067396 -234.531154)
		(width 0.088646)
		(layer "In11.Cu")
		(net "M_D_CPU1_SB_DQ<10>")
	)
	(segment
		(start 59.999626 -216.489026)
		(end 59.70905 -216.489026)
		(width 0.18288)
		(layer "In11.Cu")
		(net "M_D_CPU1_SB_DQ<10>")
	)
	(segment
		(start 97.825814 -236.92231)
		(end 97.825814 -236.922056)
		(width 0.088646)
		(layer "In11.Cu")
		(net "M_D_CPU1_SB_DQ<10>")
	)
	(segment
		(start 45.933614 -215.584024)
		(end 45.740574 -215.777064)
		(width 0.18288)
		(layer "In11.Cu")
		(net "M_D_CPU1_SB_DQ<10>")
	)
	(segment
		(start 63.58636 -218.41206)
		(end 63.2714 -218.41206)
		(width 0.18288)
		(layer "In11.Cu")
		(net "M_D_CPU1_SB_DQ<10>")
	)
	(segment
		(start 65.24371 -219.994226)
		(end 64.222122 -218.972638)
		(width 0.18288)
		(layer "In11.Cu")
		(net "M_D_CPU1_SB_DQ<10>")
	)
	(segment
		(start 28.262326 -218.609926)
		(end 27.386026 -219.486226)
		(width 0.18288)
		(layer "In11.Cu")
		(net "M_D_CPU1_SB_DQ<10>")
	)
	(segment
		(start 40.162226 -215.374982)
		(end 38.81628 -215.374982)
		(width 0.18288)
		(layer "In11.Cu")
		(net "M_D_CPU1_SB_DQ<10>")
	)
	(segment
		(start 55.984394 -215.47455)
		(end 53.861716 -215.47455)
		(width 0.18288)
		(layer "In11.Cu")
		(net "M_D_CPU1_SB_DQ<10>")
	)
	(segment
		(start 45.547534 -216.489026)
		(end 44.150026 -216.489026)
		(width 0.18288)
		(layer "In11.Cu")
		(net "M_D_CPU1_SB_DQ<10>")
	)
	(segment
		(start 53.160676 -214.248238)
		(end 52.967636 -214.441278)
		(width 0.18288)
		(layer "In11.Cu")
		(net "M_D_CPU1_SB_DQ<10>")
	)
	(segment
		(start 53.861716 -215.47455)
		(end 53.668676 -215.28151)
		(width 0.18288)
		(layer "In11.Cu")
		(net "M_D_CPU1_SB_DQ<10>")
	)
	(segment
		(start 46.441614 -216.248234)
		(end 46.441614 -215.777064)
		(width 0.18288)
		(layer "In11.Cu")
		(net "M_D_CPU1_SB_DQ<10>")
	)
	(segment
		(start 63.97244 -218.972638)
		(end 63.7794 -218.779598)
		(width 0.18288)
		(layer "In11.Cu")
		(net "M_D_CPU1_SB_DQ<10>")
	)
	(arc
		(start 89.352882 -235.285788)
		(mid 89.076407 -235.218468)
		(end 88.80221 -235.294424)
		(width 0.088646)
		(layer "In11.Cu")
		(net "M_D_CPU1_SB_DQ<10>")
	)
	(arc
		(start 92.187014 -236.922056)
		(mid 91.904312 -236.84628)
		(end 91.62161 -236.922056)
		(width 0.088646)
		(layer "In11.Cu")
		(net "M_D_CPU1_SB_DQ<10>")
	)
	(arc
		(start 97.811082 -236.91342)
		(mid 97.534607 -236.8461)
		(end 97.26041 -236.922056)
		(width 0.088646)
		(layer "In11.Cu")
		(net "M_D_CPU1_SB_DQ<10>")
	)
	(arc
		(start 86.452964 -234.480608)
		(mid 86.265766 -234.530751)
		(end 86.078568 -234.480608)
		(width 0.088646)
		(layer "In11.Cu")
		(net "M_D_CPU1_SB_DQ<10>")
	)
	(arc
		(start 93.50121 -236.922056)
		(mid 93.314012 -236.972233)
		(end 93.126814 -236.922056)
		(width 0.088646)
		(layer "In11.Cu")
		(net "M_D_CPU1_SB_DQ<10>")
	)
	(arc
		(start 85.138768 -234.480608)
		(mid 84.864569 -234.404773)
		(end 84.588096 -234.471972)
		(width 0.088646)
		(layer "In11.Cu")
		(net "M_D_CPU1_SB_DQ<10>")
	)
	(arc
		(start 86.078568 -234.480608)
		(mid 85.804369 -234.404773)
		(end 85.527896 -234.471972)
		(width 0.088646)
		(layer "In11.Cu")
		(net "M_D_CPU1_SB_DQ<10>")
	)
	(arc
		(start 98.387662 -236.597952)
		(mid 98.339983 -236.780852)
		(end 98.2091 -236.91723)
		(width 0.088646)
		(layer "In11.Cu")
		(net "M_D_CPU1_SB_DQ<10>")
	)
	(arc
		(start 98.20021 -236.92231)
		(mid 98.013012 -236.972453)
		(end 97.825814 -236.92231)
		(width 0.088646)
		(layer "In11.Cu")
		(net "M_D_CPU1_SB_DQ<10>")
	)
	(arc
		(start 87.958168 -234.480608)
		(mid 87.683969 -234.404773)
		(end 87.407496 -234.471972)
		(width 0.088646)
		(layer "In11.Cu")
		(net "M_D_CPU1_SB_DQ<10>")
	)
	(arc
		(start 94.056454 -236.91596)
		(mid 93.778022 -236.846114)
		(end 93.50121 -236.922056)
		(width 0.088646)
		(layer "In11.Cu")
		(net "M_D_CPU1_SB_DQ<10>")
	)
	(arc
		(start 85.513164 -234.480608)
		(mid 85.325966 -234.530751)
		(end 85.138768 -234.480608)
		(width 0.088646)
		(layer "In11.Cu")
		(net "M_D_CPU1_SB_DQ<10>")
	)
	(arc
		(start 89.828878 -236.10316)
		(mid 89.697964 -235.9668)
		(end 89.650316 -235.783882)
		(width 0.088646)
		(layer "In11.Cu")
		(net "M_D_CPU1_SB_DQ<10>")
	)
	(arc
		(start 94.441264 -236.922056)
		(mid 94.254066 -236.972233)
		(end 94.066868 -236.922056)
		(width 0.088646)
		(layer "In11.Cu")
		(net "M_D_CPU1_SB_DQ<10>")
	)
	(arc
		(start 97.26041 -236.922056)
		(mid 97.073212 -236.972233)
		(end 96.886014 -236.922056)
		(width 0.088646)
		(layer "In11.Cu")
		(net "M_D_CPU1_SB_DQ<10>")
	)
	(arc
		(start 89.650316 -235.783882)
		(mid 89.576325 -235.504316)
		(end 89.37371 -235.29798)
		(width 0.088646)
		(layer "In11.Cu")
		(net "M_D_CPU1_SB_DQ<10>")
	)
	(arc
		(start 95.38081 -236.922056)
		(mid 95.193612 -236.972233)
		(end 95.006414 -236.922056)
		(width 0.088646)
		(layer "In11.Cu")
		(net "M_D_CPU1_SB_DQ<10>")
	)
	(arc
		(start 96.871282 -236.91342)
		(mid 96.594807 -236.8461)
		(end 96.32061 -236.922056)
		(width 0.088646)
		(layer "In11.Cu")
		(net "M_D_CPU1_SB_DQ<10>")
	)
	(arc
		(start 90.68181 -236.922056)
		(mid 90.494612 -236.972233)
		(end 90.307414 -236.922056)
		(width 0.088646)
		(layer "In11.Cu")
		(net "M_D_CPU1_SB_DQ<10>")
	)
	(arc
		(start 88.80221 -235.294424)
		(mid 88.615012 -235.344567)
		(end 88.427814 -235.294424)
		(width 0.088646)
		(layer "In11.Cu")
		(net "M_D_CPU1_SB_DQ<10>")
	)
	(arc
		(start 84.573364 -234.480608)
		(mid 84.483092 -234.518207)
		(end 84.386166 -234.531154)
		(width 0.088646)
		(layer "In11.Cu")
		(net "M_D_CPU1_SB_DQ<10>")
	)
	(arc
		(start 88.240362 -234.954572)
		(mid 88.160992 -234.680838)
		(end 87.958168 -234.480608)
		(width 0.088646)
		(layer "In11.Cu")
		(net "M_D_CPU1_SB_DQ<10>")
	)
	(arc
		(start 99.892612 -236.597952)
		(mid 99.617471 -236.35651)
		(end 99.313238 -236.152944)
		(width 0.088646)
		(layer "In11.Cu")
		(net "M_D_CPU1_SB_DQ<10>")
	)
	(arc
		(start 96.32061 -236.922056)
		(mid 96.133412 -236.972233)
		(end 95.946214 -236.922056)
		(width 0.088646)
		(layer "In11.Cu")
		(net "M_D_CPU1_SB_DQ<10>")
	)
	(arc
		(start 91.232482 -236.91342)
		(mid 90.956007 -236.8461)
		(end 90.68181 -236.922056)
		(width 0.088646)
		(layer "In11.Cu")
		(net "M_D_CPU1_SB_DQ<10>")
	)
	(arc
		(start 91.62161 -236.922056)
		(mid 91.434412 -236.972233)
		(end 91.247214 -236.922056)
		(width 0.088646)
		(layer "In11.Cu")
		(net "M_D_CPU1_SB_DQ<10>")
	)
	(arc
		(start 99.235768 -236.10824)
		(mid 98.961539 -236.032315)
		(end 98.685096 -236.099604)
		(width 0.088646)
		(layer "In11.Cu")
		(net "M_D_CPU1_SB_DQ<10>")
	)
	(arc
		(start 90.119962 -236.575854)
		(mid 90.039051 -236.305726)
		(end 89.837768 -236.10824)
		(width 0.088646)
		(layer "In11.Cu")
		(net "M_D_CPU1_SB_DQ<10>")
	)
	(arc
		(start 90.29319 -236.913928)
		(mid 90.166147 -236.778112)
		(end 90.119962 -236.597952)
		(width 0.088646)
		(layer "In11.Cu")
		(net "M_D_CPU1_SB_DQ<10>")
	)
	(arc
		(start 95.931482 -236.91342)
		(mid 95.655007 -236.8461)
		(end 95.38081 -236.922056)
		(width 0.088646)
		(layer "In11.Cu")
		(net "M_D_CPU1_SB_DQ<10>")
	)
	(arc
		(start 92.56141 -236.922056)
		(mid 92.374212 -236.972233)
		(end 92.187014 -236.922056)
		(width 0.088646)
		(layer "In11.Cu")
		(net "M_D_CPU1_SB_DQ<10>")
	)
	(arc
		(start 93.112082 -236.91342)
		(mid 92.835607 -236.8461)
		(end 92.56141 -236.922056)
		(width 0.088646)
		(layer "In11.Cu")
		(net "M_D_CPU1_SB_DQ<10>")
	)
	(arc
		(start 98.670364 -236.10824)
		(mid 98.466883 -236.309044)
		(end 98.387662 -236.583728)
		(width 0.088646)
		(layer "In11.Cu")
		(net "M_D_CPU1_SB_DQ<10>")
	)
	(arc
		(start 94.996 -236.91596)
		(mid 94.717822 -236.846237)
		(end 94.441264 -236.922056)
		(width 0.088646)
		(layer "In11.Cu")
		(net "M_D_CPU1_SB_DQ<10>")
	)
	(arc
		(start 87.018368 -234.480608)
		(mid 86.744169 -234.404773)
		(end 86.467696 -234.471972)
		(width 0.088646)
		(layer "In11.Cu")
		(net "M_D_CPU1_SB_DQ<10>")
	)
	(arc
		(start 87.392764 -234.480608)
		(mid 87.205566 -234.530751)
		(end 87.018368 -234.480608)
		(width 0.088646)
		(layer "In11.Cu")
		(net "M_D_CPU1_SB_DQ<10>")
	)
	(arc
		(start 88.418924 -235.289344)
		(mid 88.28801 -235.152984)
		(end 88.240362 -234.970066)
		(width 0.088646)
		(layer "In11.Cu")
		(net "M_D_CPU1_SB_DQ<10>")
	)
	(segment
		(start 98.953066 -242.017042)
		(end 98.952812 -242.016788)
		(width 0.20066)
		(layer "F.Cu")
		(net "M_D_CPU1_SB_DQ<0>")
	)
	(segment
		(start 8.140446 -232.166668)
		(end 9.474708 -232.166668)
		(width 0.20066)
		(layer "F.Cu")
		(net "M_D_CPU1_SB_DQ<0>")
	)
	(segment
		(start 10.344912 -231.943148)
		(end 10.554462 -231.733598)
		(width 0.20066)
		(layer "F.Cu")
		(net "M_D_CPU1_SB_DQ<0>")
	)
	(segment
		(start 11.372342 -231.741726)
		(end 13.441426 -231.741726)
		(width 0.1016)
		(layer "F.Cu")
		(net "M_D_CPU1_SB_DQ<0>")
	)
	(segment
		(start 13.890244 -231.741726)
		(end 14.315186 -232.166668)
		(width 0.20066)
		(layer "F.Cu")
		(net "M_D_CPU1_SB_DQ<0>")
	)
	(segment
		(start 10.172192 -232.405428)
		(end 10.344912 -232.232708)
		(width 0.20066)
		(layer "F.Cu")
		(net "M_D_CPU1_SB_DQ<0>")
	)
	(segment
		(start 13.441426 -231.741726)
		(end 13.890244 -231.741726)
		(width 0.20066)
		(layer "F.Cu")
		(net "M_D_CPU1_SB_DQ<0>")
	)
	(segment
		(start 9.713468 -232.405428)
		(end 10.172192 -232.405428)
		(width 0.20066)
		(layer "F.Cu")
		(net "M_D_CPU1_SB_DQ<0>")
	)
	(segment
		(start 11.124438 -231.741726)
		(end 11.372342 -231.741726)
		(width 0.101854)
		(layer "F.Cu")
		(net "M_D_CPU1_SB_DQ<0>")
	)
	(segment
		(start 16.789146 -232.166668)
		(end 15.684246 -232.166668)
		(width 0.20066)
		(layer "F.Cu")
		(net "M_D_CPU1_SB_DQ<0>")
	)
	(segment
		(start 14.315186 -232.166668)
		(end 15.684246 -232.166668)
		(width 0.20066)
		(layer "F.Cu")
		(net "M_D_CPU1_SB_DQ<0>")
	)
	(segment
		(start 98.952812 -242.016788)
		(end 98.952812 -241.481102)
		(width 0.20066)
		(layer "F.Cu")
		(net "M_D_CPU1_SB_DQ<0>")
	)
	(segment
		(start 11.11631 -231.733598)
		(end 11.124438 -231.741726)
		(width 0.101854)
		(layer "F.Cu")
		(net "M_D_CPU1_SB_DQ<0>")
	)
	(segment
		(start 10.344912 -232.232708)
		(end 10.344912 -231.943148)
		(width 0.20066)
		(layer "F.Cu")
		(net "M_D_CPU1_SB_DQ<0>")
	)
	(segment
		(start 10.554462 -231.733598)
		(end 11.11631 -231.733598)
		(width 0.20066)
		(layer "F.Cu")
		(net "M_D_CPU1_SB_DQ<0>")
	)
	(segment
		(start 9.474708 -232.166668)
		(end 9.713468 -232.405428)
		(width 0.20066)
		(layer "F.Cu")
		(net "M_D_CPU1_SB_DQ<0>")
	)
	(segment
		(start 59.512962 -230.738426)
		(end 58.801762 -230.027226)
		(width 0.18288)
		(layer "In11.Cu")
		(net "M_D_CPU1_SB_DQ<0>")
	)
	(segment
		(start 89.287096 -241.979196)
		(end 89.272364 -241.97056)
		(width 0.088646)
		(layer "In11.Cu")
		(net "M_D_CPU1_SB_DQ<0>")
	)
	(segment
		(start 51.831494 -229.192582)
		(end 49.53127 -229.192582)
		(width 0.18288)
		(layer "In11.Cu")
		(net "M_D_CPU1_SB_DQ<0>")
	)
	(segment
		(start 21.164804 -231.745028)
		(end 19.334988 -231.745028)
		(width 0.18288)
		(layer "In11.Cu")
		(net "M_D_CPU1_SB_DQ<0>")
	)
	(segment
		(start 41.457626 -229.874826)
		(end 40.187626 -228.604826)
		(width 0.18288)
		(layer "In11.Cu")
		(net "M_D_CPU1_SB_DQ<0>")
	)
	(segment
		(start 19.334988 -231.745028)
		(end 19.115786 -231.525826)
		(width 0.18288)
		(layer "In11.Cu")
		(net "M_D_CPU1_SB_DQ<0>")
	)
	(segment
		(start 84.385912 -240.292128)
		(end 84.062316 -240.292128)
		(width 0.088646)
		(layer "In11.Cu")
		(net "M_D_CPU1_SB_DQ<0>")
	)
	(segment
		(start 30.357826 -230.509826)
		(end 29.341826 -230.509826)
		(width 0.18288)
		(layer "In11.Cu")
		(net "M_D_CPU1_SB_DQ<0>")
	)
	(segment
		(start 97.745296 -241.979196)
		(end 97.730564 -241.97056)
		(width 0.088646)
		(layer "In11.Cu")
		(net "M_D_CPU1_SB_DQ<0>")
	)
	(segment
		(start 47.022258 -230.040942)
		(end 46.04131 -230.040942)
		(width 0.18288)
		(layer "In11.Cu")
		(net "M_D_CPU1_SB_DQ<0>")
	)
	(segment
		(start 30.824932 -230.04272)
		(end 30.357826 -230.509826)
		(width 0.18288)
		(layer "In11.Cu")
		(net "M_D_CPU1_SB_DQ<0>")
	)
	(segment
		(start 95.865696 -241.979196)
		(end 95.850964 -241.97056)
		(width 0.088646)
		(layer "In11.Cu")
		(net "M_D_CPU1_SB_DQ<0>")
	)
	(segment
		(start 67.31 -233.214926)
		(end 66.031618 -233.214926)
		(width 0.18288)
		(layer "In11.Cu")
		(net "M_D_CPU1_SB_DQ<0>")
	)
	(segment
		(start 61.736732 -231.744012)
		(end 60.731146 -230.738426)
		(width 0.18288)
		(layer "In11.Cu")
		(net "M_D_CPU1_SB_DQ<0>")
	)
	(segment
		(start 31.932118 -230.042466)
		(end 31.822898 -230.042466)
		(width 0.18288)
		(layer "In11.Cu")
		(net "M_D_CPU1_SB_DQ<0>")
	)
	(segment
		(start 19.115786 -231.525826)
		(end 17.429988 -231.525826)
		(width 0.18288)
		(layer "In11.Cu")
		(net "M_D_CPU1_SB_DQ<0>")
	)
	(segment
		(start 91.166696 -241.979196)
		(end 91.151964 -241.97056)
		(width 0.088646)
		(layer "In11.Cu")
		(net "M_D_CPU1_SB_DQ<0>")
	)
	(segment
		(start 25.93975 -232.499408)
		(end 21.919184 -232.499408)
		(width 0.18288)
		(layer "In11.Cu")
		(net "M_D_CPU1_SB_DQ<0>")
	)
	(segment
		(start 86.931754 -241.161824)
		(end 86.922864 -241.156744)
		(width 0.088646)
		(layer "In11.Cu")
		(net "M_D_CPU1_SB_DQ<0>")
	)
	(segment
		(start 85.522054 -240.348008)
		(end 85.513164 -240.342928)
		(width 0.088646)
		(layer "In11.Cu")
		(net "M_D_CPU1_SB_DQ<0>")
	)
	(segment
		(start 53.046376 -229.287324)
		(end 53.046376 -228.823266)
		(width 0.18288)
		(layer "In11.Cu")
		(net "M_D_CPU1_SB_DQ<0>")
	)
	(segment
		(start 31.932372 -230.04272)
		(end 31.932118 -230.042466)
		(width 0.18288)
		(layer "In11.Cu")
		(net "M_D_CPU1_SB_DQ<0>")
	)
	(segment
		(start 96.805496 -241.979196)
		(end 96.790764 -241.97056)
		(width 0.088646)
		(layer "In11.Cu")
		(net "M_D_CPU1_SB_DQ<0>")
	)
	(segment
		(start 53.940456 -228.630226)
		(end 53.747416 -228.823266)
		(width 0.18288)
		(layer "In11.Cu")
		(net "M_D_CPU1_SB_DQ<0>")
	)
	(segment
		(start 32.557212 -229.798626)
		(end 32.313118 -230.04272)
		(width 0.18288)
		(layer "In11.Cu")
		(net "M_D_CPU1_SB_DQ<0>")
	)
	(segment
		(start 46.04131 -230.040942)
		(end 45.801026 -230.281226)
		(width 0.18288)
		(layer "In11.Cu")
		(net "M_D_CPU1_SB_DQ<0>")
	)
	(segment
		(start 84.062316 -240.292128)
		(end 83.230974 -239.460786)
		(width 0.088646)
		(layer "In11.Cu")
		(net "M_D_CPU1_SB_DQ<0>")
	)
	(segment
		(start 92.106496 -241.979196)
		(end 92.091764 -241.97056)
		(width 0.088646)
		(layer "In11.Cu")
		(net "M_D_CPU1_SB_DQ<0>")
	)
	(segment
		(start 47.695612 -229.747826)
		(end 47.400718 -230.04272)
		(width 0.18288)
		(layer "In11.Cu")
		(net "M_D_CPU1_SB_DQ<0>")
	)
	(segment
		(start 66.031618 -233.214926)
		(end 64.367918 -231.551226)
		(width 0.18288)
		(layer "In11.Cu")
		(net "M_D_CPU1_SB_DQ<0>")
	)
	(segment
		(start 73.55586 -239.460786)
		(end 67.31 -233.214926)
		(width 0.18288)
		(layer "In11.Cu")
		(net "M_D_CPU1_SB_DQ<0>")
	)
	(segment
		(start 55.453026 -228.630226)
		(end 53.940456 -228.630226)
		(width 0.18288)
		(layer "In11.Cu")
		(net "M_D_CPU1_SB_DQ<0>")
	)
	(segment
		(start 47.400718 -230.04272)
		(end 47.024036 -230.04272)
		(width 0.18288)
		(layer "In11.Cu")
		(net "M_D_CPU1_SB_DQ<0>")
	)
	(segment
		(start 83.230974 -239.460786)
		(end 82.411316 -239.460786)
		(width 0.088646)
		(layer "In11.Cu")
		(net "M_D_CPU1_SB_DQ<0>")
	)
	(segment
		(start 45.801026 -230.281226)
		(end 44.480226 -230.281226)
		(width 0.18288)
		(layer "In11.Cu")
		(net "M_D_CPU1_SB_DQ<0>")
	)
	(segment
		(start 34.67354 -229.191312)
		(end 34.066226 -229.798626)
		(width 0.18288)
		(layer "In11.Cu")
		(net "M_D_CPU1_SB_DQ<0>")
	)
	(segment
		(start 31.822644 -230.04272)
		(end 30.824932 -230.04272)
		(width 0.18288)
		(layer "In11.Cu")
		(net "M_D_CPU1_SB_DQ<0>")
	)
	(segment
		(start 32.313118 -230.04272)
		(end 31.932372 -230.04272)
		(width 0.18288)
		(layer "In11.Cu")
		(net "M_D_CPU1_SB_DQ<0>")
	)
	(segment
		(start 28.005786 -231.271826)
		(end 26.675334 -232.602278)
		(width 0.18288)
		(layer "In11.Cu")
		(net "M_D_CPU1_SB_DQ<0>")
	)
	(segment
		(start 53.046376 -228.823266)
		(end 52.853336 -228.630226)
		(width 0.18288)
		(layer "In11.Cu")
		(net "M_D_CPU1_SB_DQ<0>")
	)
	(segment
		(start 53.554376 -229.480364)
		(end 53.239416 -229.480364)
		(width 0.18288)
		(layer "In11.Cu")
		(net "M_D_CPU1_SB_DQ<0>")
	)
	(segment
		(start 98.952812 -241.481102)
		(end 98.952812 -241.51209)
		(width 0.088646)
		(layer "In11.Cu")
		(net "M_D_CPU1_SB_DQ<0>")
	)
	(segment
		(start 52.853336 -228.630226)
		(end 52.39385 -228.630226)
		(width 0.18288)
		(layer "In11.Cu")
		(net "M_D_CPU1_SB_DQ<0>")
	)
	(segment
		(start 85.700616 -240.677192)
		(end 85.700616 -240.667286)
		(width 0.088646)
		(layer "In11.Cu")
		(net "M_D_CPU1_SB_DQ<0>")
	)
	(segment
		(start 53.747416 -228.823266)
		(end 53.747416 -229.287324)
		(width 0.18288)
		(layer "In11.Cu")
		(net "M_D_CPU1_SB_DQ<0>")
	)
	(segment
		(start 36.414456 -229.191312)
		(end 34.67354 -229.191312)
		(width 0.18288)
		(layer "In11.Cu")
		(net "M_D_CPU1_SB_DQ<0>")
	)
	(segment
		(start 48.976026 -229.747826)
		(end 47.695612 -229.747826)
		(width 0.18288)
		(layer "In11.Cu")
		(net "M_D_CPU1_SB_DQ<0>")
	)
	(segment
		(start 87.110316 -241.496596)
		(end 87.110316 -241.481102)
		(width 0.088646)
		(layer "In11.Cu")
		(net "M_D_CPU1_SB_DQ<0>")
	)
	(segment
		(start 64.367918 -231.551226)
		(end 62.526418 -231.551226)
		(width 0.18288)
		(layer "In11.Cu")
		(net "M_D_CPU1_SB_DQ<0>")
	)
	(segment
		(start 17.429988 -231.525826)
		(end 16.789146 -232.166668)
		(width 0.18288)
		(layer "In11.Cu")
		(net "M_D_CPU1_SB_DQ<0>")
	)
	(segment
		(start 31.822898 -230.042466)
		(end 31.822644 -230.04272)
		(width 0.18288)
		(layer "In11.Cu")
		(net "M_D_CPU1_SB_DQ<0>")
	)
	(segment
		(start 47.024036 -230.04272)
		(end 47.022258 -230.040942)
		(width 0.18288)
		(layer "In11.Cu")
		(net "M_D_CPU1_SB_DQ<0>")
	)
	(segment
		(start 60.731146 -230.738426)
		(end 59.512962 -230.738426)
		(width 0.18288)
		(layer "In11.Cu")
		(net "M_D_CPU1_SB_DQ<0>")
	)
	(segment
		(start 34.066226 -229.798626)
		(end 32.557212 -229.798626)
		(width 0.18288)
		(layer "In11.Cu")
		(net "M_D_CPU1_SB_DQ<0>")
	)
	(segment
		(start 37.000942 -228.604826)
		(end 36.414456 -229.191312)
		(width 0.18288)
		(layer "In11.Cu")
		(net "M_D_CPU1_SB_DQ<0>")
	)
	(segment
		(start 26.04262 -232.602278)
		(end 25.93975 -232.499408)
		(width 0.18288)
		(layer "In11.Cu")
		(net "M_D_CPU1_SB_DQ<0>")
	)
	(segment
		(start 28.579826 -231.271826)
		(end 28.005786 -231.271826)
		(width 0.18288)
		(layer "In11.Cu")
		(net "M_D_CPU1_SB_DQ<0>")
	)
	(segment
		(start 40.187626 -228.604826)
		(end 37.000942 -228.604826)
		(width 0.18288)
		(layer "In11.Cu")
		(net "M_D_CPU1_SB_DQ<0>")
	)
	(segment
		(start 52.39385 -228.630226)
		(end 51.831494 -229.192582)
		(width 0.18288)
		(layer "In11.Cu")
		(net "M_D_CPU1_SB_DQ<0>")
	)
	(segment
		(start 94.925896 -241.979196)
		(end 94.911164 -241.97056)
		(width 0.088646)
		(layer "In11.Cu")
		(net "M_D_CPU1_SB_DQ<0>")
	)
	(segment
		(start 21.919184 -232.499408)
		(end 21.164804 -231.745028)
		(width 0.18288)
		(layer "In11.Cu")
		(net "M_D_CPU1_SB_DQ<0>")
	)
	(segment
		(start 58.801762 -230.027226)
		(end 56.850026 -230.027226)
		(width 0.18288)
		(layer "In11.Cu")
		(net "M_D_CPU1_SB_DQ<0>")
	)
	(segment
		(start 62.526418 -231.551226)
		(end 62.333632 -231.744012)
		(width 0.18288)
		(layer "In11.Cu")
		(net "M_D_CPU1_SB_DQ<0>")
	)
	(segment
		(start 98.29927 -241.968528)
		(end 98.295968 -241.97056)
		(width 0.088646)
		(layer "In11.Cu")
		(net "M_D_CPU1_SB_DQ<0>")
	)
	(segment
		(start 62.333632 -231.744012)
		(end 61.736732 -231.744012)
		(width 0.18288)
		(layer "In11.Cu")
		(net "M_D_CPU1_SB_DQ<0>")
	)
	(segment
		(start 56.850026 -230.027226)
		(end 55.453026 -228.630226)
		(width 0.18288)
		(layer "In11.Cu")
		(net "M_D_CPU1_SB_DQ<0>")
	)
	(segment
		(start 44.480226 -230.281226)
		(end 44.073826 -229.874826)
		(width 0.18288)
		(layer "In11.Cu")
		(net "M_D_CPU1_SB_DQ<0>")
	)
	(segment
		(start 88.332564 -241.97056)
		(end 88.324182 -241.965734)
		(width 0.088646)
		(layer "In11.Cu")
		(net "M_D_CPU1_SB_DQ<0>")
	)
	(segment
		(start 26.675334 -232.602278)
		(end 26.04262 -232.602278)
		(width 0.18288)
		(layer "In11.Cu")
		(net "M_D_CPU1_SB_DQ<0>")
	)
	(segment
		(start 29.341826 -230.509826)
		(end 28.579826 -231.271826)
		(width 0.18288)
		(layer "In11.Cu")
		(net "M_D_CPU1_SB_DQ<0>")
	)
	(segment
		(start 53.747416 -229.287324)
		(end 53.554376 -229.480364)
		(width 0.18288)
		(layer "In11.Cu")
		(net "M_D_CPU1_SB_DQ<0>")
	)
	(segment
		(start 90.226896 -241.979196)
		(end 90.212164 -241.97056)
		(width 0.088646)
		(layer "In11.Cu")
		(net "M_D_CPU1_SB_DQ<0>")
	)
	(segment
		(start 88.347296 -241.979196)
		(end 88.332564 -241.97056)
		(width 0.088646)
		(layer "In11.Cu")
		(net "M_D_CPU1_SB_DQ<0>")
	)
	(segment
		(start 49.53127 -229.192582)
		(end 48.976026 -229.747826)
		(width 0.18288)
		(layer "In11.Cu")
		(net "M_D_CPU1_SB_DQ<0>")
	)
	(segment
		(start 82.411316 -239.460786)
		(end 73.55586 -239.460786)
		(width 0.18288)
		(layer "In11.Cu")
		(net "M_D_CPU1_SB_DQ<0>")
	)
	(segment
		(start 84.588096 -240.351564)
		(end 84.573364 -240.342928)
		(width 0.088646)
		(layer "In11.Cu")
		(net "M_D_CPU1_SB_DQ<0>")
	)
	(segment
		(start 53.239416 -229.480364)
		(end 53.046376 -229.287324)
		(width 0.18288)
		(layer "In11.Cu")
		(net "M_D_CPU1_SB_DQ<0>")
	)
	(segment
		(start 93.046296 -241.979196)
		(end 93.031564 -241.97056)
		(width 0.088646)
		(layer "In11.Cu")
		(net "M_D_CPU1_SB_DQ<0>")
	)
	(segment
		(start 44.073826 -229.874826)
		(end 41.457626 -229.874826)
		(width 0.18288)
		(layer "In11.Cu")
		(net "M_D_CPU1_SB_DQ<0>")
	)
	(arc
		(start 93.596968 -241.97056)
		(mid 93.322769 -242.046395)
		(end 93.046296 -241.979196)
		(width 0.088646)
		(layer "In11.Cu")
		(net "M_D_CPU1_SB_DQ<0>")
	)
	(arc
		(start 93.971364 -241.97056)
		(mid 93.784166 -241.920417)
		(end 93.596968 -241.97056)
		(width 0.088646)
		(layer "In11.Cu")
		(net "M_D_CPU1_SB_DQ<0>")
	)
	(arc
		(start 96.790764 -241.97056)
		(mid 96.603566 -241.920417)
		(end 96.416368 -241.97056)
		(width 0.088646)
		(layer "In11.Cu")
		(net "M_D_CPU1_SB_DQ<0>")
	)
	(arc
		(start 90.212164 -241.97056)
		(mid 90.024966 -241.920417)
		(end 89.837768 -241.97056)
		(width 0.088646)
		(layer "In11.Cu")
		(net "M_D_CPU1_SB_DQ<0>")
	)
	(arc
		(start 94.536768 -241.97056)
		(mid 94.254066 -242.046336)
		(end 93.971364 -241.97056)
		(width 0.088646)
		(layer "In11.Cu")
		(net "M_D_CPU1_SB_DQ<0>")
	)
	(arc
		(start 97.730564 -241.97056)
		(mid 97.543366 -241.920417)
		(end 97.356168 -241.97056)
		(width 0.088646)
		(layer "In11.Cu")
		(net "M_D_CPU1_SB_DQ<0>")
	)
	(arc
		(start 91.151964 -241.97056)
		(mid 90.964766 -241.920417)
		(end 90.777568 -241.97056)
		(width 0.088646)
		(layer "In11.Cu")
		(net "M_D_CPU1_SB_DQ<0>")
	)
	(arc
		(start 90.777568 -241.97056)
		(mid 90.503369 -242.046395)
		(end 90.226896 -241.979196)
		(width 0.088646)
		(layer "In11.Cu")
		(net "M_D_CPU1_SB_DQ<0>")
	)
	(arc
		(start 98.952812 -241.51209)
		(mid 98.840253 -241.783833)
		(end 98.56851 -241.896392)
		(width 0.088646)
		(layer "In11.Cu")
		(net "M_D_CPU1_SB_DQ<0>")
	)
	(arc
		(start 86.548468 -241.156744)
		(mid 86.265766 -241.23252)
		(end 85.983064 -241.156744)
		(width 0.088646)
		(layer "In11.Cu")
		(net "M_D_CPU1_SB_DQ<0>")
	)
	(arc
		(start 86.922864 -241.156744)
		(mid 86.735666 -241.106601)
		(end 86.548468 -241.156744)
		(width 0.088646)
		(layer "In11.Cu")
		(net "M_D_CPU1_SB_DQ<0>")
	)
	(arc
		(start 85.983064 -241.156744)
		(mid 85.778729 -240.954139)
		(end 85.700616 -240.677192)
		(width 0.088646)
		(layer "In11.Cu")
		(net "M_D_CPU1_SB_DQ<0>")
	)
	(arc
		(start 93.031564 -241.97056)
		(mid 92.844366 -241.920417)
		(end 92.657168 -241.97056)
		(width 0.088646)
		(layer "In11.Cu")
		(net "M_D_CPU1_SB_DQ<0>")
	)
	(arc
		(start 98.56851 -241.896392)
		(mid 98.429131 -241.914702)
		(end 98.29927 -241.968528)
		(width 0.088646)
		(layer "In11.Cu")
		(net "M_D_CPU1_SB_DQ<0>")
	)
	(arc
		(start 94.911164 -241.97056)
		(mid 94.723966 -241.920417)
		(end 94.536768 -241.97056)
		(width 0.088646)
		(layer "In11.Cu")
		(net "M_D_CPU1_SB_DQ<0>")
	)
	(arc
		(start 96.416368 -241.97056)
		(mid 96.142169 -242.046395)
		(end 95.865696 -241.979196)
		(width 0.088646)
		(layer "In11.Cu")
		(net "M_D_CPU1_SB_DQ<0>")
	)
	(arc
		(start 85.138768 -240.342928)
		(mid 84.864539 -240.418853)
		(end 84.588096 -240.351564)
		(width 0.088646)
		(layer "In11.Cu")
		(net "M_D_CPU1_SB_DQ<0>")
	)
	(arc
		(start 88.897968 -241.97056)
		(mid 88.623769 -242.046395)
		(end 88.347296 -241.979196)
		(width 0.088646)
		(layer "In11.Cu")
		(net "M_D_CPU1_SB_DQ<0>")
	)
	(arc
		(start 98.295968 -241.97056)
		(mid 98.021769 -242.046395)
		(end 97.745296 -241.979196)
		(width 0.088646)
		(layer "In11.Cu")
		(net "M_D_CPU1_SB_DQ<0>")
	)
	(arc
		(start 87.958422 -241.97056)
		(mid 87.675466 -242.046463)
		(end 87.39251 -241.97056)
		(width 0.088646)
		(layer "In11.Cu")
		(net "M_D_CPU1_SB_DQ<0>")
	)
	(arc
		(start 95.850964 -241.97056)
		(mid 95.663766 -241.920417)
		(end 95.476568 -241.97056)
		(width 0.088646)
		(layer "In11.Cu")
		(net "M_D_CPU1_SB_DQ<0>")
	)
	(arc
		(start 91.717368 -241.97056)
		(mid 91.443169 -242.046395)
		(end 91.166696 -241.979196)
		(width 0.088646)
		(layer "In11.Cu")
		(net "M_D_CPU1_SB_DQ<0>")
	)
	(arc
		(start 87.110316 -241.481102)
		(mid 87.062637 -241.298202)
		(end 86.931754 -241.161824)
		(width 0.088646)
		(layer "In11.Cu")
		(net "M_D_CPU1_SB_DQ<0>")
	)
	(arc
		(start 89.272364 -241.97056)
		(mid 89.085166 -241.920417)
		(end 88.897968 -241.97056)
		(width 0.088646)
		(layer "In11.Cu")
		(net "M_D_CPU1_SB_DQ<0>")
	)
	(arc
		(start 85.700616 -240.667286)
		(mid 85.652937 -240.484386)
		(end 85.522054 -240.348008)
		(width 0.088646)
		(layer "In11.Cu")
		(net "M_D_CPU1_SB_DQ<0>")
	)
	(arc
		(start 87.39251 -241.97056)
		(mid 87.189687 -241.770329)
		(end 87.110316 -241.496596)
		(width 0.088646)
		(layer "In11.Cu")
		(net "M_D_CPU1_SB_DQ<0>")
	)
	(arc
		(start 88.324182 -241.965734)
		(mid 88.140674 -241.920456)
		(end 87.958422 -241.97056)
		(width 0.088646)
		(layer "In11.Cu")
		(net "M_D_CPU1_SB_DQ<0>")
	)
	(arc
		(start 85.513164 -240.342928)
		(mid 85.325966 -240.292785)
		(end 85.138768 -240.342928)
		(width 0.088646)
		(layer "In11.Cu")
		(net "M_D_CPU1_SB_DQ<0>")
	)
	(arc
		(start 89.837768 -241.97056)
		(mid 89.563569 -242.046395)
		(end 89.287096 -241.979196)
		(width 0.088646)
		(layer "In11.Cu")
		(net "M_D_CPU1_SB_DQ<0>")
	)
	(arc
		(start 97.356168 -241.97056)
		(mid 97.081969 -242.046395)
		(end 96.805496 -241.979196)
		(width 0.088646)
		(layer "In11.Cu")
		(net "M_D_CPU1_SB_DQ<0>")
	)
	(arc
		(start 92.091764 -241.97056)
		(mid 91.904566 -241.920417)
		(end 91.717368 -241.97056)
		(width 0.088646)
		(layer "In11.Cu")
		(net "M_D_CPU1_SB_DQ<0>")
	)
	(arc
		(start 92.657168 -241.97056)
		(mid 92.382969 -242.046395)
		(end 92.106496 -241.979196)
		(width 0.088646)
		(layer "In11.Cu")
		(net "M_D_CPU1_SB_DQ<0>")
	)
	(arc
		(start 84.573364 -240.342928)
		(mid 84.482985 -240.305173)
		(end 84.385912 -240.292128)
		(width 0.088646)
		(layer "In11.Cu")
		(net "M_D_CPU1_SB_DQ<0>")
	)
	(arc
		(start 95.476568 -241.97056)
		(mid 95.202369 -242.046395)
		(end 94.925896 -241.979196)
		(width 0.088646)
		(layer "In11.Cu")
		(net "M_D_CPU1_SB_DQ<0>")
	)
	(segment
		(start 95.663766 -246.086376)
		(end 95.663766 -245.55069)
		(width 0.20066)
		(layer "F.Cu")
		(net "M_D_CPU1_SB_CS_N<3>")
	)
	(segment
		(start 19.784314 -244.916706)
		(end 20.889214 -244.916706)
		(width 0.20066)
		(layer "F.Cu")
		(net "M_D_CPU1_SB_CS_N<3>")
	)
	(segment
		(start 95.663512 -246.08663)
		(end 95.663766 -246.086376)
		(width 0.20066)
		(layer "F.Cu")
		(net "M_D_CPU1_SB_CS_N<3>")
	)
	(segment
		(start 38.506146 -242.191794)
		(end 38.323266 -242.374674)
		(width 0.18288)
		(layer "In6.Cu")
		(net "M_D_CPU1_SB_CS_N<3>")
	)
	(segment
		(start 36.801806 -241.941096)
		(end 34.681414 -241.941096)
		(width 0.18288)
		(layer "In6.Cu")
		(net "M_D_CPU1_SB_CS_N<3>")
	)
	(segment
		(start 72.685656 -245.531132)
		(end 69.503798 -245.531132)
		(width 0.18288)
		(layer "In6.Cu")
		(net "M_D_CPU1_SB_CS_N<3>")
	)
	(segment
		(start 27.41676 -241.751612)
		(end 27.25674 -241.591592)
		(width 0.18288)
		(layer "In6.Cu")
		(net "M_D_CPU1_SB_CS_N<3>")
	)
	(segment
		(start 27.57678 -242.228624)
		(end 27.41676 -242.068604)
		(width 0.18288)
		(layer "In6.Cu")
		(net "M_D_CPU1_SB_CS_N<3>")
	)
	(segment
		(start 89.287096 -245.866412)
		(end 89.272364 -245.875048)
		(width 0.088646)
		(layer "In6.Cu")
		(net "M_D_CPU1_SB_CS_N<3>")
	)
	(segment
		(start 49.850802 -241.940842)
		(end 49.694338 -242.097306)
		(width 0.18288)
		(layer "In6.Cu")
		(net "M_D_CPU1_SB_CS_N<3>")
	)
	(segment
		(start 47.09414 -241.940842)
		(end 47.093886 -241.941096)
		(width 0.18288)
		(layer "In6.Cu")
		(net "M_D_CPU1_SB_CS_N<3>")
	)
	(segment
		(start 22.360636 -243.445284)
		(end 22.102064 -243.445284)
		(width 0.18288)
		(layer "In6.Cu")
		(net "M_D_CPU1_SB_CS_N<3>")
	)
	(segment
		(start 95.3897 -246.683784)
		(end 95.38081 -246.688864)
		(width 0.088646)
		(layer "In6.Cu")
		(net "M_D_CPU1_SB_CS_N<3>")
	)
	(segment
		(start 55.942738 -241.940842)
		(end 55.376572 -241.374676)
		(width 0.18288)
		(layer "In6.Cu")
		(net "M_D_CPU1_SB_CS_N<3>")
	)
	(segment
		(start 31.115254 -241.608356)
		(end 29.307028 -241.608356)
		(width 0.18288)
		(layer "In6.Cu")
		(net "M_D_CPU1_SB_CS_N<3>")
	)
	(segment
		(start 21.321522 -243.383562)
		(end 21.321522 -243.642134)
		(width 0.18288)
		(layer "In6.Cu")
		(net "M_D_CPU1_SB_CS_N<3>")
	)
	(segment
		(start 28.974542 -241.940842)
		(end 28.209494 -241.940842)
		(width 0.18288)
		(layer "In6.Cu")
		(net "M_D_CPU1_SB_CS_N<3>")
	)
	(segment
		(start 95.850964 -245.875048)
		(end 95.844868 -245.878604)
		(width 0.088646)
		(layer "In6.Cu")
		(net "M_D_CPU1_SB_CS_N<3>")
	)
	(segment
		(start 32.918908 -242.089686)
		(end 32.770318 -241.941096)
		(width 0.18288)
		(layer "In6.Cu")
		(net "M_D_CPU1_SB_CS_N<3>")
	)
	(segment
		(start 37.815266 -242.191794)
		(end 37.815266 -241.99977)
		(width 0.18288)
		(layer "In6.Cu")
		(net "M_D_CPU1_SB_CS_N<3>")
	)
	(segment
		(start 37.815266 -241.99977)
		(end 37.632386 -241.81689)
		(width 0.18288)
		(layer "In6.Cu")
		(net "M_D_CPU1_SB_CS_N<3>")
	)
	(segment
		(start 84.164678 -245.840758)
		(end 83.92287 -245.840758)
		(width 0.088646)
		(layer "In6.Cu")
		(net "M_D_CPU1_SB_CS_N<3>")
	)
	(segment
		(start 93.041724 -245.868952)
		(end 93.03131 -245.875048)
		(width 0.088646)
		(layer "In6.Cu")
		(net "M_D_CPU1_SB_CS_N<3>")
	)
	(segment
		(start 21.551646 -243.153438)
		(end 21.321522 -243.383562)
		(width 0.18288)
		(layer "In6.Cu")
		(net "M_D_CPU1_SB_CS_N<3>")
	)
	(segment
		(start 69.503798 -245.531132)
		(end 66.974466 -243.0018)
		(width 0.18288)
		(layer "In6.Cu")
		(net "M_D_CPU1_SB_CS_N<3>")
	)
	(segment
		(start 25.98166 -242.228624)
		(end 25.07996 -241.326924)
		(width 0.18288)
		(layer "In6.Cu")
		(net "M_D_CPU1_SB_CS_N<3>")
	)
	(segment
		(start 41.081452 -242.485926)
		(end 40.412416 -241.81689)
		(width 0.18288)
		(layer "In6.Cu")
		(net "M_D_CPU1_SB_CS_N<3>")
	)
	(segment
		(start 36.926012 -241.81689)
		(end 36.801806 -241.941096)
		(width 0.18288)
		(layer "In6.Cu")
		(net "M_D_CPU1_SB_CS_N<3>")
	)
	(segment
		(start 95.663766 -245.55069)
		(end 95.97644 -245.55069)
		(width 0.088646)
		(layer "In6.Cu")
		(net "M_D_CPU1_SB_CS_N<3>")
	)
	(segment
		(start 80.768444 -245.068344)
		(end 73.148444 -245.068344)
		(width 0.18288)
		(layer "In6.Cu")
		(net "M_D_CPU1_SB_CS_N<3>")
	)
	(segment
		(start 47.093886 -241.941096)
		(end 42.708576 -241.941096)
		(width 0.18288)
		(layer "In6.Cu")
		(net "M_D_CPU1_SB_CS_N<3>")
	)
	(segment
		(start 22.925532 -242.880388)
		(end 22.360636 -243.445284)
		(width 0.18288)
		(layer "In6.Cu")
		(net "M_D_CPU1_SB_CS_N<3>")
	)
	(segment
		(start 73.148444 -245.068344)
		(end 72.685656 -245.531132)
		(width 0.18288)
		(layer "In6.Cu")
		(net "M_D_CPU1_SB_CS_N<3>")
	)
	(segment
		(start 21.613368 -244.192552)
		(end 20.889214 -244.916706)
		(width 0.18288)
		(layer "In6.Cu")
		(net "M_D_CPU1_SB_CS_N<3>")
	)
	(segment
		(start 22.102064 -243.445284)
		(end 21.810218 -243.153438)
		(width 0.18288)
		(layer "In6.Cu")
		(net "M_D_CPU1_SB_CS_N<3>")
	)
	(segment
		(start 58.163714 -242.092734)
		(end 58.011822 -241.940842)
		(width 0.18288)
		(layer "In6.Cu")
		(net "M_D_CPU1_SB_CS_N<3>")
	)
	(segment
		(start 37.632386 -241.81689)
		(end 36.926012 -241.81689)
		(width 0.18288)
		(layer "In6.Cu")
		(net "M_D_CPU1_SB_CS_N<3>")
	)
	(segment
		(start 95.97644 -245.55069)
		(end 96.033844 -245.608094)
		(width 0.088646)
		(layer "In6.Cu")
		(net "M_D_CPU1_SB_CS_N<3>")
	)
	(segment
		(start 90.222578 -245.868952)
		(end 90.212164 -245.875048)
		(width 0.088646)
		(layer "In6.Cu")
		(net "M_D_CPU1_SB_CS_N<3>")
	)
	(segment
		(start 26.72334 -241.751612)
		(end 26.72334 -242.068604)
		(width 0.18288)
		(layer "In6.Cu")
		(net "M_D_CPU1_SB_CS_N<3>")
	)
	(segment
		(start 83.612736 -246.48287)
		(end 83.440778 -246.654828)
		(width 0.088646)
		(layer "In6.Cu")
		(net "M_D_CPU1_SB_CS_N<3>")
	)
	(segment
		(start 37.998146 -242.374674)
		(end 37.815266 -242.191794)
		(width 0.18288)
		(layer "In6.Cu")
		(net "M_D_CPU1_SB_CS_N<3>")
	)
	(segment
		(start 53.23713 -241.72164)
		(end 51.98618 -241.72164)
		(width 0.18288)
		(layer "In6.Cu")
		(net "M_D_CPU1_SB_CS_N<3>")
	)
	(segment
		(start 26.72334 -242.068604)
		(end 26.56332 -242.228624)
		(width 0.18288)
		(layer "In6.Cu")
		(net "M_D_CPU1_SB_CS_N<3>")
	)
	(segment
		(start 27.25674 -241.591592)
		(end 26.88336 -241.591592)
		(width 0.18288)
		(layer "In6.Cu")
		(net "M_D_CPU1_SB_CS_N<3>")
	)
	(segment
		(start 92.102178 -245.868952)
		(end 92.091764 -245.875048)
		(width 0.088646)
		(layer "In6.Cu")
		(net "M_D_CPU1_SB_CS_N<3>")
	)
	(segment
		(start 26.56332 -242.228624)
		(end 25.98166 -242.228624)
		(width 0.18288)
		(layer "In6.Cu")
		(net "M_D_CPU1_SB_CS_N<3>")
	)
	(segment
		(start 40.412416 -241.81689)
		(end 38.689026 -241.81689)
		(width 0.18288)
		(layer "In6.Cu")
		(net "M_D_CPU1_SB_CS_N<3>")
	)
	(segment
		(start 91.162124 -245.868952)
		(end 91.15171 -245.875048)
		(width 0.088646)
		(layer "In6.Cu")
		(net "M_D_CPU1_SB_CS_N<3>")
	)
	(segment
		(start 59.605926 -241.838226)
		(end 59.351418 -242.092734)
		(width 0.18288)
		(layer "In6.Cu")
		(net "M_D_CPU1_SB_CS_N<3>")
	)
	(segment
		(start 83.92287 -245.840758)
		(end 83.753198 -246.01043)
		(width 0.088646)
		(layer "In6.Cu")
		(net "M_D_CPU1_SB_CS_N<3>")
	)
	(segment
		(start 49.694338 -242.097306)
		(end 47.977298 -242.097306)
		(width 0.18288)
		(layer "In6.Cu")
		(net "M_D_CPU1_SB_CS_N<3>")
	)
	(segment
		(start 59.351418 -242.092734)
		(end 58.163714 -242.092734)
		(width 0.18288)
		(layer "In6.Cu")
		(net "M_D_CPU1_SB_CS_N<3>")
	)
	(segment
		(start 32.770318 -241.941096)
		(end 31.447994 -241.941096)
		(width 0.18288)
		(layer "In6.Cu")
		(net "M_D_CPU1_SB_CS_N<3>")
	)
	(segment
		(start 83.753198 -246.01043)
		(end 83.612736 -246.34952)
		(width 0.088646)
		(layer "In6.Cu")
		(net "M_D_CPU1_SB_CS_N<3>")
	)
	(segment
		(start 94.819216 -246.373142)
		(end 94.819216 -246.3546)
		(width 0.088646)
		(layer "In6.Cu")
		(net "M_D_CPU1_SB_CS_N<3>")
	)
	(segment
		(start 34.532824 -242.089686)
		(end 32.918908 -242.089686)
		(width 0.18288)
		(layer "In6.Cu")
		(net "M_D_CPU1_SB_CS_N<3>")
	)
	(segment
		(start 21.613368 -243.93398)
		(end 21.613368 -244.192552)
		(width 0.18288)
		(layer "In6.Cu")
		(net "M_D_CPU1_SB_CS_N<3>")
	)
	(segment
		(start 58.011822 -241.940842)
		(end 55.942738 -241.940842)
		(width 0.18288)
		(layer "In6.Cu")
		(net "M_D_CPU1_SB_CS_N<3>")
	)
	(segment
		(start 29.307028 -241.608356)
		(end 28.974542 -241.940842)
		(width 0.18288)
		(layer "In6.Cu")
		(net "M_D_CPU1_SB_CS_N<3>")
	)
	(segment
		(start 28.209494 -241.940842)
		(end 27.921712 -242.228624)
		(width 0.18288)
		(layer "In6.Cu")
		(net "M_D_CPU1_SB_CS_N<3>")
	)
	(segment
		(start 26.88336 -241.591592)
		(end 26.72334 -241.751612)
		(width 0.18288)
		(layer "In6.Cu")
		(net "M_D_CPU1_SB_CS_N<3>")
	)
	(segment
		(start 38.506146 -241.99977)
		(end 38.506146 -242.191794)
		(width 0.18288)
		(layer "In6.Cu")
		(net "M_D_CPU1_SB_CS_N<3>")
	)
	(segment
		(start 62.71514 -241.838226)
		(end 59.605926 -241.838226)
		(width 0.18288)
		(layer "In6.Cu")
		(net "M_D_CPU1_SB_CS_N<3>")
	)
	(segment
		(start 66.974466 -243.0018)
		(end 65.314576 -243.0018)
		(width 0.18288)
		(layer "In6.Cu")
		(net "M_D_CPU1_SB_CS_N<3>")
	)
	(segment
		(start 88.347296 -245.866412)
		(end 88.332564 -245.875048)
		(width 0.088646)
		(layer "In6.Cu")
		(net "M_D_CPU1_SB_CS_N<3>")
	)
	(segment
		(start 27.921712 -242.228624)
		(end 27.57678 -242.228624)
		(width 0.18288)
		(layer "In6.Cu")
		(net "M_D_CPU1_SB_CS_N<3>")
	)
	(segment
		(start 25.07996 -241.326924)
		(end 23.939246 -241.326924)
		(width 0.18288)
		(layer "In6.Cu")
		(net "M_D_CPU1_SB_CS_N<3>")
	)
	(segment
		(start 95.859854 -245.869968)
		(end 95.850964 -245.875048)
		(width 0.088646)
		(layer "In6.Cu")
		(net "M_D_CPU1_SB_CS_N<3>")
	)
	(segment
		(start 34.681414 -241.941096)
		(end 34.532824 -242.089686)
		(width 0.18288)
		(layer "In6.Cu")
		(net "M_D_CPU1_SB_CS_N<3>")
	)
	(segment
		(start 55.376572 -241.374676)
		(end 53.584094 -241.374676)
		(width 0.18288)
		(layer "In6.Cu")
		(net "M_D_CPU1_SB_CS_N<3>")
	)
	(segment
		(start 64.254888 -241.942112)
		(end 62.819026 -241.942112)
		(width 0.18288)
		(layer "In6.Cu")
		(net "M_D_CPU1_SB_CS_N<3>")
	)
	(segment
		(start 22.925532 -242.340638)
		(end 22.925532 -242.880388)
		(width 0.18288)
		(layer "In6.Cu")
		(net "M_D_CPU1_SB_CS_N<3>")
	)
	(segment
		(start 65.314576 -243.0018)
		(end 64.254888 -241.942112)
		(width 0.18288)
		(layer "In6.Cu")
		(net "M_D_CPU1_SB_CS_N<3>")
	)
	(segment
		(start 38.323266 -242.374674)
		(end 37.998146 -242.374674)
		(width 0.18288)
		(layer "In6.Cu")
		(net "M_D_CPU1_SB_CS_N<3>")
	)
	(segment
		(start 84.198968 -245.875048)
		(end 84.164678 -245.840758)
		(width 0.088646)
		(layer "In6.Cu")
		(net "M_D_CPU1_SB_CS_N<3>")
	)
	(segment
		(start 53.584094 -241.374676)
		(end 53.23713 -241.72164)
		(width 0.18288)
		(layer "In6.Cu")
		(net "M_D_CPU1_SB_CS_N<3>")
	)
	(segment
		(start 51.766978 -241.940842)
		(end 49.850802 -241.940842)
		(width 0.18288)
		(layer "In6.Cu")
		(net "M_D_CPU1_SB_CS_N<3>")
	)
	(segment
		(start 42.163746 -242.485926)
		(end 41.081452 -242.485926)
		(width 0.18288)
		(layer "In6.Cu")
		(net "M_D_CPU1_SB_CS_N<3>")
	)
	(segment
		(start 51.98618 -241.72164)
		(end 51.766978 -241.940842)
		(width 0.18288)
		(layer "In6.Cu")
		(net "M_D_CPU1_SB_CS_N<3>")
	)
	(segment
		(start 21.810218 -243.153438)
		(end 21.551646 -243.153438)
		(width 0.18288)
		(layer "In6.Cu")
		(net "M_D_CPU1_SB_CS_N<3>")
	)
	(segment
		(start 83.612736 -246.34952)
		(end 83.612736 -246.48287)
		(width 0.088646)
		(layer "In6.Cu")
		(net "M_D_CPU1_SB_CS_N<3>")
	)
	(segment
		(start 27.41676 -242.068604)
		(end 27.41676 -241.751612)
		(width 0.18288)
		(layer "In6.Cu")
		(net "M_D_CPU1_SB_CS_N<3>")
	)
	(segment
		(start 38.689026 -241.81689)
		(end 38.506146 -241.99977)
		(width 0.18288)
		(layer "In6.Cu")
		(net "M_D_CPU1_SB_CS_N<3>")
	)
	(segment
		(start 21.321522 -243.642134)
		(end 21.613368 -243.93398)
		(width 0.18288)
		(layer "In6.Cu")
		(net "M_D_CPU1_SB_CS_N<3>")
	)
	(segment
		(start 47.977298 -242.097306)
		(end 47.820834 -241.940842)
		(width 0.18288)
		(layer "In6.Cu")
		(net "M_D_CPU1_SB_CS_N<3>")
	)
	(segment
		(start 23.939246 -241.326924)
		(end 22.925532 -242.340638)
		(width 0.18288)
		(layer "In6.Cu")
		(net "M_D_CPU1_SB_CS_N<3>")
	)
	(segment
		(start 62.819026 -241.942112)
		(end 62.71514 -241.838226)
		(width 0.18288)
		(layer "In6.Cu")
		(net "M_D_CPU1_SB_CS_N<3>")
	)
	(segment
		(start 83.440778 -246.654828)
		(end 83.19135 -246.654828)
		(width 0.088646)
		(layer "In6.Cu")
		(net "M_D_CPU1_SB_CS_N<3>")
	)
	(segment
		(start 42.708576 -241.941096)
		(end 42.163746 -242.485926)
		(width 0.18288)
		(layer "In6.Cu")
		(net "M_D_CPU1_SB_CS_N<3>")
	)
	(segment
		(start 31.447994 -241.941096)
		(end 31.115254 -241.608356)
		(width 0.18288)
		(layer "In6.Cu")
		(net "M_D_CPU1_SB_CS_N<3>")
	)
	(segment
		(start 83.19135 -246.654828)
		(end 82.354928 -246.654828)
		(width 0.18288)
		(layer "In6.Cu")
		(net "M_D_CPU1_SB_CS_N<3>")
	)
	(segment
		(start 82.354928 -246.654828)
		(end 80.768444 -245.068344)
		(width 0.18288)
		(layer "In6.Cu")
		(net "M_D_CPU1_SB_CS_N<3>")
	)
	(segment
		(start 47.820834 -241.940842)
		(end 47.09414 -241.940842)
		(width 0.18288)
		(layer "In6.Cu")
		(net "M_D_CPU1_SB_CS_N<3>")
	)
	(arc
		(start 84.573364 -245.875048)
		(mid 84.386166 -245.925191)
		(end 84.198968 -245.875048)
		(width 0.088646)
		(layer "In6.Cu")
		(net "M_D_CPU1_SB_CS_N<3>")
	)
	(arc
		(start 85.513164 -245.875048)
		(mid 85.325966 -245.925191)
		(end 85.138768 -245.875048)
		(width 0.088646)
		(layer "In6.Cu")
		(net "M_D_CPU1_SB_CS_N<3>")
	)
	(arc
		(start 94.819216 -246.3546)
		(mid 94.741105 -246.077651)
		(end 94.536768 -245.875048)
		(width 0.088646)
		(layer "In6.Cu")
		(net "M_D_CPU1_SB_CS_N<3>")
	)
	(arc
		(start 95.006414 -246.688864)
		(mid 94.871481 -246.55551)
		(end 94.819216 -246.373142)
		(width 0.088646)
		(layer "In6.Cu")
		(net "M_D_CPU1_SB_CS_N<3>")
	)
	(arc
		(start 86.452964 -245.875048)
		(mid 86.265766 -245.925191)
		(end 86.078568 -245.875048)
		(width 0.088646)
		(layer "In6.Cu")
		(net "M_D_CPU1_SB_CS_N<3>")
	)
	(arc
		(start 93.596968 -245.875048)
		(mid 93.320155 -245.799178)
		(end 93.041724 -245.868952)
		(width 0.088646)
		(layer "In6.Cu")
		(net "M_D_CPU1_SB_CS_N<3>")
	)
	(arc
		(start 90.777314 -245.875048)
		(mid 90.500755 -245.799305)
		(end 90.222578 -245.868952)
		(width 0.088646)
		(layer "In6.Cu")
		(net "M_D_CPU1_SB_CS_N<3>")
	)
	(arc
		(start 92.091764 -245.875048)
		(mid 91.904566 -245.925191)
		(end 91.717368 -245.875048)
		(width 0.088646)
		(layer "In6.Cu")
		(net "M_D_CPU1_SB_CS_N<3>")
	)
	(arc
		(start 89.272364 -245.875048)
		(mid 89.085166 -245.925191)
		(end 88.897968 -245.875048)
		(width 0.088646)
		(layer "In6.Cu")
		(net "M_D_CPU1_SB_CS_N<3>")
	)
	(arc
		(start 85.138768 -245.875048)
		(mid 84.856066 -245.799272)
		(end 84.573364 -245.875048)
		(width 0.088646)
		(layer "In6.Cu")
		(net "M_D_CPU1_SB_CS_N<3>")
	)
	(arc
		(start 96.033844 -245.608094)
		(mid 95.975688 -245.758207)
		(end 95.859854 -245.869968)
		(width 0.088646)
		(layer "In6.Cu")
		(net "M_D_CPU1_SB_CS_N<3>")
	)
	(arc
		(start 87.958168 -245.875048)
		(mid 87.675466 -245.799272)
		(end 87.392764 -245.875048)
		(width 0.088646)
		(layer "In6.Cu")
		(net "M_D_CPU1_SB_CS_N<3>")
	)
	(arc
		(start 95.844868 -245.878604)
		(mid 95.642281 -246.084955)
		(end 95.568262 -246.364506)
		(width 0.088646)
		(layer "In6.Cu")
		(net "M_D_CPU1_SB_CS_N<3>")
	)
	(arc
		(start 91.15171 -245.875048)
		(mid 90.964512 -245.925191)
		(end 90.777314 -245.875048)
		(width 0.088646)
		(layer "In6.Cu")
		(net "M_D_CPU1_SB_CS_N<3>")
	)
	(arc
		(start 93.03131 -245.875048)
		(mid 92.844112 -245.925191)
		(end 92.656914 -245.875048)
		(width 0.088646)
		(layer "In6.Cu")
		(net "M_D_CPU1_SB_CS_N<3>")
	)
	(arc
		(start 86.078568 -245.875048)
		(mid 85.795866 -245.799272)
		(end 85.513164 -245.875048)
		(width 0.088646)
		(layer "In6.Cu")
		(net "M_D_CPU1_SB_CS_N<3>")
	)
	(arc
		(start 87.018368 -245.875048)
		(mid 86.735666 -245.799272)
		(end 86.452964 -245.875048)
		(width 0.088646)
		(layer "In6.Cu")
		(net "M_D_CPU1_SB_CS_N<3>")
	)
	(arc
		(start 95.568262 -246.364506)
		(mid 95.520583 -246.547406)
		(end 95.3897 -246.683784)
		(width 0.088646)
		(layer "In6.Cu")
		(net "M_D_CPU1_SB_CS_N<3>")
	)
	(arc
		(start 95.38081 -246.688864)
		(mid 95.193612 -246.739007)
		(end 95.006414 -246.688864)
		(width 0.088646)
		(layer "In6.Cu")
		(net "M_D_CPU1_SB_CS_N<3>")
	)
	(arc
		(start 91.717368 -245.875048)
		(mid 91.440555 -245.799178)
		(end 91.162124 -245.868952)
		(width 0.088646)
		(layer "In6.Cu")
		(net "M_D_CPU1_SB_CS_N<3>")
	)
	(arc
		(start 93.971364 -245.875048)
		(mid 93.784166 -245.925191)
		(end 93.596968 -245.875048)
		(width 0.088646)
		(layer "In6.Cu")
		(net "M_D_CPU1_SB_CS_N<3>")
	)
	(arc
		(start 90.212164 -245.875048)
		(mid 90.024966 -245.925191)
		(end 89.837768 -245.875048)
		(width 0.088646)
		(layer "In6.Cu")
		(net "M_D_CPU1_SB_CS_N<3>")
	)
	(arc
		(start 87.392764 -245.875048)
		(mid 87.205566 -245.925191)
		(end 87.018368 -245.875048)
		(width 0.088646)
		(layer "In6.Cu")
		(net "M_D_CPU1_SB_CS_N<3>")
	)
	(arc
		(start 88.897968 -245.875048)
		(mid 88.623769 -245.799213)
		(end 88.347296 -245.866412)
		(width 0.088646)
		(layer "In6.Cu")
		(net "M_D_CPU1_SB_CS_N<3>")
	)
	(arc
		(start 89.837768 -245.875048)
		(mid 89.563569 -245.799213)
		(end 89.287096 -245.866412)
		(width 0.088646)
		(layer "In6.Cu")
		(net "M_D_CPU1_SB_CS_N<3>")
	)
	(arc
		(start 94.536768 -245.875048)
		(mid 94.254066 -245.799272)
		(end 93.971364 -245.875048)
		(width 0.088646)
		(layer "In6.Cu")
		(net "M_D_CPU1_SB_CS_N<3>")
	)
	(arc
		(start 92.656914 -245.875048)
		(mid 92.380355 -245.799305)
		(end 92.102178 -245.868952)
		(width 0.088646)
		(layer "In6.Cu")
		(net "M_D_CPU1_SB_CS_N<3>")
	)
	(arc
		(start 88.332564 -245.875048)
		(mid 88.145366 -245.925191)
		(end 87.958168 -245.875048)
		(width 0.088646)
		(layer "In6.Cu")
		(net "M_D_CPU1_SB_CS_N<3>")
	)
	(segment
		(start 96.603312 -246.08663)
		(end 96.603566 -246.086376)
		(width 0.20066)
		(layer "F.Cu")
		(net "M_D_CPU1_SB_CS_N<2>")
	)
	(segment
		(start 96.603566 -246.086376)
		(end 96.603566 -245.55069)
		(width 0.20066)
		(layer "F.Cu")
		(net "M_D_CPU1_SB_CS_N<2>")
	)
	(segment
		(start 15.684246 -245.76659)
		(end 16.789146 -245.76659)
		(width 0.20066)
		(layer "F.Cu")
		(net "M_D_CPU1_SB_CS_N<2>")
	)
	(segment
		(start 42.189146 -243.255546)
		(end 41.071546 -243.255546)
		(width 0.18288)
		(layer "In6.Cu")
		(net "M_D_CPU1_SB_CS_N<2>")
	)
	(segment
		(start 39.887398 -242.611148)
		(end 39.707566 -242.79098)
		(width 0.18288)
		(layer "In6.Cu")
		(net "M_D_CPU1_SB_CS_N<2>")
	)
	(segment
		(start 54.221126 -241.892836)
		(end 53.227224 -242.886738)
		(width 0.18288)
		(layer "In6.Cu")
		(net "M_D_CPU1_SB_CS_N<2>")
	)
	(segment
		(start 20.260818 -245.340886)
		(end 19.633692 -245.968012)
		(width 0.18288)
		(layer "In6.Cu")
		(net "M_D_CPU1_SB_CS_N<2>")
	)
	(segment
		(start 55.980838 -242.79098)
		(end 55.082694 -241.892836)
		(width 0.18288)
		(layer "In6.Cu")
		(net "M_D_CPU1_SB_CS_N<2>")
	)
	(segment
		(start 23.487126 -242.516152)
		(end 23.487126 -242.925092)
		(width 0.18288)
		(layer "In6.Cu")
		(net "M_D_CPU1_SB_CS_N<2>")
	)
	(segment
		(start 95.95231 -246.036592)
		(end 95.946214 -246.040148)
		(width 0.088646)
		(layer "In6.Cu")
		(net "M_D_CPU1_SB_CS_N<2>")
	)
	(segment
		(start 96.603566 -245.55069)
		(end 96.290892 -245.55069)
		(width 0.088646)
		(layer "In6.Cu")
		(net "M_D_CPU1_SB_CS_N<2>")
	)
	(segment
		(start 36.716716 -242.920266)
		(end 36.58743 -242.79098)
		(width 0.18288)
		(layer "In6.Cu")
		(net "M_D_CPU1_SB_CS_N<2>")
	)
	(segment
		(start 94.628462 -246.364506)
		(end 94.628462 -246.35587)
		(width 0.088646)
		(layer "In6.Cu")
		(net "M_D_CPU1_SB_CS_N<2>")
	)
	(segment
		(start 65.026794 -243.574824)
		(end 64.240918 -242.788948)
		(width 0.18288)
		(layer "In6.Cu")
		(net "M_D_CPU1_SB_CS_N<2>")
	)
	(segment
		(start 72.70877 -246.105426)
		(end 69.355462 -246.105426)
		(width 0.18288)
		(layer "In6.Cu")
		(net "M_D_CPU1_SB_CS_N<2>")
	)
	(segment
		(start 39.707566 -242.79098)
		(end 38.975538 -242.79098)
		(width 0.18288)
		(layer "In6.Cu")
		(net "M_D_CPU1_SB_CS_N<2>")
	)
	(segment
		(start 94.066868 -246.040148)
		(end 94.056454 -246.046244)
		(width 0.088646)
		(layer "In6.Cu")
		(net "M_D_CPU1_SB_CS_N<2>")
	)
	(segment
		(start 24.6761 -241.89309)
		(end 24.110188 -241.89309)
		(width 0.18288)
		(layer "In6.Cu")
		(net "M_D_CPU1_SB_CS_N<2>")
	)
	(segment
		(start 18.220436 -246.359426)
		(end 17.133316 -245.909084)
		(width 0.18288)
		(layer "In6.Cu")
		(net "M_D_CPU1_SB_CS_N<2>")
	)
	(segment
		(start 83.920838 -246.128794)
		(end 83.920838 -246.802148)
		(width 0.088646)
		(layer "In6.Cu")
		(net "M_D_CPU1_SB_CS_N<2>")
	)
	(segment
		(start 53.227224 -242.886738)
		(end 51.853084 -242.886738)
		(width 0.18288)
		(layer "In6.Cu")
		(net "M_D_CPU1_SB_CS_N<2>")
	)
	(segment
		(start 90.307414 -246.040148)
		(end 90.292682 -246.048784)
		(width 0.088646)
		(layer "In6.Cu")
		(net "M_D_CPU1_SB_CS_N<2>")
	)
	(segment
		(start 92.187014 -246.040148)
		(end 92.172282 -246.048784)
		(width 0.088646)
		(layer "In6.Cu")
		(net "M_D_CPU1_SB_CS_N<2>")
	)
	(segment
		(start 38.846252 -242.920266)
		(end 36.716716 -242.920266)
		(width 0.18288)
		(layer "In6.Cu")
		(net "M_D_CPU1_SB_CS_N<2>")
	)
	(segment
		(start 18.688812 -246.359426)
		(end 18.220436 -246.359426)
		(width 0.18288)
		(layer "In6.Cu")
		(net "M_D_CPU1_SB_CS_N<2>")
	)
	(segment
		(start 19.633692 -245.968012)
		(end 18.688812 -246.359426)
		(width 0.18288)
		(layer "In6.Cu")
		(net "M_D_CPU1_SB_CS_N<2>")
	)
	(segment
		(start 51.853084 -242.886738)
		(end 51.757326 -242.79098)
		(width 0.18288)
		(layer "In6.Cu")
		(net "M_D_CPU1_SB_CS_N<2>")
	)
	(segment
		(start 49.894236 -242.677442)
		(end 47.30877 -242.677442)
		(width 0.18288)
		(layer "In6.Cu")
		(net "M_D_CPU1_SB_CS_N<2>")
	)
	(segment
		(start 35.70732 -242.79098)
		(end 35.541966 -242.625626)
		(width 0.18288)
		(layer "In6.Cu")
		(net "M_D_CPU1_SB_CS_N<2>")
	)
	(segment
		(start 83.72348 -246.999506)
		(end 83.520534 -246.999506)
		(width 0.088646)
		(layer "In6.Cu")
		(net "M_D_CPU1_SB_CS_N<2>")
	)
	(segment
		(start 51.757326 -242.79098)
		(end 50.007774 -242.79098)
		(width 0.18288)
		(layer "In6.Cu")
		(net "M_D_CPU1_SB_CS_N<2>")
	)
	(segment
		(start 60.197238 -242.955826)
		(end 58.923682 -242.955826)
		(width 0.18288)
		(layer "In6.Cu")
		(net "M_D_CPU1_SB_CS_N<2>")
	)
	(segment
		(start 23.487126 -242.925092)
		(end 22.54377 -245.203218)
		(width 0.18288)
		(layer "In6.Cu")
		(net "M_D_CPU1_SB_CS_N<2>")
	)
	(segment
		(start 58.923682 -242.955826)
		(end 58.758836 -242.79098)
		(width 0.18288)
		(layer "In6.Cu")
		(net "M_D_CPU1_SB_CS_N<2>")
	)
	(segment
		(start 40.427148 -242.611148)
		(end 39.887398 -242.611148)
		(width 0.18288)
		(layer "In6.Cu")
		(net "M_D_CPU1_SB_CS_N<2>")
	)
	(segment
		(start 64.240918 -242.788948)
		(end 60.364116 -242.788948)
		(width 0.18288)
		(layer "In6.Cu")
		(net "M_D_CPU1_SB_CS_N<2>")
	)
	(segment
		(start 38.975538 -242.79098)
		(end 38.846252 -242.920266)
		(width 0.18288)
		(layer "In6.Cu")
		(net "M_D_CPU1_SB_CS_N<2>")
	)
	(segment
		(start 25.57399 -242.79098)
		(end 24.6761 -241.89309)
		(width 0.18288)
		(layer "In6.Cu")
		(net "M_D_CPU1_SB_CS_N<2>")
	)
	(segment
		(start 60.364116 -242.788948)
		(end 60.197238 -242.955826)
		(width 0.18288)
		(layer "In6.Cu")
		(net "M_D_CPU1_SB_CS_N<2>")
	)
	(segment
		(start 33.49879 -242.79098)
		(end 25.57399 -242.79098)
		(width 0.18288)
		(layer "In6.Cu")
		(net "M_D_CPU1_SB_CS_N<2>")
	)
	(segment
		(start 80.629252 -245.403878)
		(end 73.410318 -245.403878)
		(width 0.18288)
		(layer "In6.Cu")
		(net "M_D_CPU1_SB_CS_N<2>")
	)
	(segment
		(start 66.82486 -243.574824)
		(end 65.026794 -243.574824)
		(width 0.18288)
		(layer "In6.Cu")
		(net "M_D_CPU1_SB_CS_N<2>")
	)
	(segment
		(start 42.653712 -242.79098)
		(end 42.189146 -243.255546)
		(width 0.18288)
		(layer "In6.Cu")
		(net "M_D_CPU1_SB_CS_N<2>")
	)
	(segment
		(start 95.758762 -246.364506)
		(end 95.758762 -246.38)
		(width 0.088646)
		(layer "In6.Cu")
		(net "M_D_CPU1_SB_CS_N<2>")
	)
	(segment
		(start 22.54377 -245.203218)
		(end 22.406102 -245.340886)
		(width 0.18288)
		(layer "In6.Cu")
		(net "M_D_CPU1_SB_CS_N<2>")
	)
	(segment
		(start 95.946214 -246.040148)
		(end 95.937324 -246.045228)
		(width 0.088646)
		(layer "In6.Cu")
		(net "M_D_CPU1_SB_CS_N<2>")
	)
	(segment
		(start 22.406102 -245.340886)
		(end 20.260818 -245.340886)
		(width 0.18288)
		(layer "In6.Cu")
		(net "M_D_CPU1_SB_CS_N<2>")
	)
	(segment
		(start 50.007774 -242.79098)
		(end 49.894236 -242.677442)
		(width 0.18288)
		(layer "In6.Cu")
		(net "M_D_CPU1_SB_CS_N<2>")
	)
	(segment
		(start 58.758836 -242.79098)
		(end 55.980838 -242.79098)
		(width 0.18288)
		(layer "In6.Cu")
		(net "M_D_CPU1_SB_CS_N<2>")
	)
	(segment
		(start 89.367614 -246.040148)
		(end 89.352882 -246.048784)
		(width 0.088646)
		(layer "In6.Cu")
		(net "M_D_CPU1_SB_CS_N<2>")
	)
	(segment
		(start 36.58743 -242.79098)
		(end 35.70732 -242.79098)
		(width 0.18288)
		(layer "In6.Cu")
		(net "M_D_CPU1_SB_CS_N<2>")
	)
	(segment
		(start 69.355462 -246.105426)
		(end 66.82486 -243.574824)
		(width 0.18288)
		(layer "In6.Cu")
		(net "M_D_CPU1_SB_CS_N<2>")
	)
	(segment
		(start 83.520534 -246.999506)
		(end 82.22488 -246.999506)
		(width 0.18288)
		(layer "In6.Cu")
		(net "M_D_CPU1_SB_CS_N<2>")
	)
	(segment
		(start 47.195232 -242.79098)
		(end 42.653712 -242.79098)
		(width 0.18288)
		(layer "In6.Cu")
		(net "M_D_CPU1_SB_CS_N<2>")
	)
	(segment
		(start 88.427814 -246.040148)
		(end 88.4174 -246.046244)
		(width 0.088646)
		(layer "In6.Cu")
		(net "M_D_CPU1_SB_CS_N<2>")
	)
	(segment
		(start 83.920838 -246.802148)
		(end 83.72348 -246.999506)
		(width 0.088646)
		(layer "In6.Cu")
		(net "M_D_CPU1_SB_CS_N<2>")
	)
	(segment
		(start 24.110188 -241.89309)
		(end 23.487126 -242.516152)
		(width 0.18288)
		(layer "In6.Cu")
		(net "M_D_CPU1_SB_CS_N<2>")
	)
	(segment
		(start 35.541966 -242.625626)
		(end 33.664144 -242.625626)
		(width 0.18288)
		(layer "In6.Cu")
		(net "M_D_CPU1_SB_CS_N<2>")
	)
	(segment
		(start 17.133316 -245.909084)
		(end 16.789146 -245.76659)
		(width 0.18288)
		(layer "In6.Cu")
		(net "M_D_CPU1_SB_CS_N<2>")
	)
	(segment
		(start 94.911164 -246.853964)
		(end 94.905068 -246.850408)
		(width 0.088646)
		(layer "In6.Cu")
		(net "M_D_CPU1_SB_CS_N<2>")
	)
	(segment
		(start 94.925896 -246.8626)
		(end 94.911164 -246.853964)
		(width 0.088646)
		(layer "In6.Cu")
		(net "M_D_CPU1_SB_CS_N<2>")
	)
	(segment
		(start 47.30877 -242.677442)
		(end 47.195232 -242.79098)
		(width 0.18288)
		(layer "In6.Cu")
		(net "M_D_CPU1_SB_CS_N<2>")
	)
	(segment
		(start 96.290892 -245.55069)
		(end 96.225106 -245.616476)
		(width 0.088646)
		(layer "In6.Cu")
		(net "M_D_CPU1_SB_CS_N<2>")
	)
	(segment
		(start 41.071546 -243.255546)
		(end 40.427148 -242.611148)
		(width 0.18288)
		(layer "In6.Cu")
		(net "M_D_CPU1_SB_CS_N<2>")
	)
	(segment
		(start 55.082694 -241.892836)
		(end 54.221126 -241.892836)
		(width 0.18288)
		(layer "In6.Cu")
		(net "M_D_CPU1_SB_CS_N<2>")
	)
	(segment
		(start 73.410318 -245.403878)
		(end 72.70877 -246.105426)
		(width 0.18288)
		(layer "In6.Cu")
		(net "M_D_CPU1_SB_CS_N<2>")
	)
	(segment
		(start 84.103464 -246.040148)
		(end 84.009484 -246.040148)
		(width 0.088646)
		(layer "In6.Cu")
		(net "M_D_CPU1_SB_CS_N<2>")
	)
	(segment
		(start 84.009484 -246.040148)
		(end 83.920838 -246.128794)
		(width 0.088646)
		(layer "In6.Cu")
		(net "M_D_CPU1_SB_CS_N<2>")
	)
	(segment
		(start 82.22488 -246.999506)
		(end 80.629252 -245.403878)
		(width 0.18288)
		(layer "In6.Cu")
		(net "M_D_CPU1_SB_CS_N<2>")
	)
	(segment
		(start 33.664144 -242.625626)
		(end 33.49879 -242.79098)
		(width 0.18288)
		(layer "In6.Cu")
		(net "M_D_CPU1_SB_CS_N<2>")
	)
	(arc
		(start 87.862664 -246.040148)
		(mid 87.675466 -245.990005)
		(end 87.488268 -246.040148)
		(width 0.088646)
		(layer "In6.Cu")
		(net "M_D_CPU1_SB_CS_N<2>")
	)
	(arc
		(start 89.352882 -246.048784)
		(mid 89.076407 -246.116104)
		(end 88.80221 -246.040148)
		(width 0.088646)
		(layer "In6.Cu")
		(net "M_D_CPU1_SB_CS_N<2>")
	)
	(arc
		(start 84.668868 -246.040148)
		(mid 84.386166 -246.115924)
		(end 84.103464 -246.040148)
		(width 0.088646)
		(layer "In6.Cu")
		(net "M_D_CPU1_SB_CS_N<2>")
	)
	(arc
		(start 88.4174 -246.046244)
		(mid 88.139222 -246.115967)
		(end 87.862664 -246.040148)
		(width 0.088646)
		(layer "In6.Cu")
		(net "M_D_CPU1_SB_CS_N<2>")
	)
	(arc
		(start 89.74201 -246.040148)
		(mid 89.554812 -245.990005)
		(end 89.367614 -246.040148)
		(width 0.088646)
		(layer "In6.Cu")
		(net "M_D_CPU1_SB_CS_N<2>")
	)
	(arc
		(start 90.68181 -246.040148)
		(mid 90.494612 -245.990005)
		(end 90.307414 -246.040148)
		(width 0.088646)
		(layer "In6.Cu")
		(net "M_D_CPU1_SB_CS_N<2>")
	)
	(arc
		(start 91.247214 -246.040148)
		(mid 90.964512 -246.115924)
		(end 90.68181 -246.040148)
		(width 0.088646)
		(layer "In6.Cu")
		(net "M_D_CPU1_SB_CS_N<2>")
	)
	(arc
		(start 93.126814 -246.040148)
		(mid 92.844112 -246.115924)
		(end 92.56141 -246.040148)
		(width 0.088646)
		(layer "In6.Cu")
		(net "M_D_CPU1_SB_CS_N<2>")
	)
	(arc
		(start 93.50121 -246.040148)
		(mid 93.314012 -245.990005)
		(end 93.126814 -246.040148)
		(width 0.088646)
		(layer "In6.Cu")
		(net "M_D_CPU1_SB_CS_N<2>")
	)
	(arc
		(start 94.628462 -246.35587)
		(mid 94.576192 -246.173505)
		(end 94.441264 -246.040148)
		(width 0.088646)
		(layer "In6.Cu")
		(net "M_D_CPU1_SB_CS_N<2>")
	)
	(arc
		(start 86.922864 -246.040148)
		(mid 86.735666 -245.990005)
		(end 86.548468 -246.040148)
		(width 0.088646)
		(layer "In6.Cu")
		(net "M_D_CPU1_SB_CS_N<2>")
	)
	(arc
		(start 87.488268 -246.040148)
		(mid 87.205566 -246.115924)
		(end 86.922864 -246.040148)
		(width 0.088646)
		(layer "In6.Cu")
		(net "M_D_CPU1_SB_CS_N<2>")
	)
	(arc
		(start 95.937324 -246.045228)
		(mid 95.80641 -246.181588)
		(end 95.758762 -246.364506)
		(width 0.088646)
		(layer "In6.Cu")
		(net "M_D_CPU1_SB_CS_N<2>")
	)
	(arc
		(start 94.905068 -246.850408)
		(mid 94.702481 -246.644057)
		(end 94.628462 -246.364506)
		(width 0.088646)
		(layer "In6.Cu")
		(net "M_D_CPU1_SB_CS_N<2>")
	)
	(arc
		(start 85.608668 -246.040148)
		(mid 85.325966 -246.115924)
		(end 85.043264 -246.040148)
		(width 0.088646)
		(layer "In6.Cu")
		(net "M_D_CPU1_SB_CS_N<2>")
	)
	(arc
		(start 85.043264 -246.040148)
		(mid 84.856066 -245.990005)
		(end 84.668868 -246.040148)
		(width 0.088646)
		(layer "In6.Cu")
		(net "M_D_CPU1_SB_CS_N<2>")
	)
	(arc
		(start 86.548468 -246.040148)
		(mid 86.265766 -246.115924)
		(end 85.983064 -246.040148)
		(width 0.088646)
		(layer "In6.Cu")
		(net "M_D_CPU1_SB_CS_N<2>")
	)
	(arc
		(start 92.172282 -246.048784)
		(mid 91.895807 -246.116104)
		(end 91.62161 -246.040148)
		(width 0.088646)
		(layer "In6.Cu")
		(net "M_D_CPU1_SB_CS_N<2>")
	)
	(arc
		(start 90.292682 -246.048784)
		(mid 90.016207 -246.116104)
		(end 89.74201 -246.040148)
		(width 0.088646)
		(layer "In6.Cu")
		(net "M_D_CPU1_SB_CS_N<2>")
	)
	(arc
		(start 96.225106 -245.616476)
		(mid 96.137818 -245.858432)
		(end 95.95231 -246.036592)
		(width 0.088646)
		(layer "In6.Cu")
		(net "M_D_CPU1_SB_CS_N<2>")
	)
	(arc
		(start 95.758762 -246.38)
		(mid 95.679392 -246.653734)
		(end 95.476568 -246.853964)
		(width 0.088646)
		(layer "In6.Cu")
		(net "M_D_CPU1_SB_CS_N<2>")
	)
	(arc
		(start 92.56141 -246.040148)
		(mid 92.374212 -245.990005)
		(end 92.187014 -246.040148)
		(width 0.088646)
		(layer "In6.Cu")
		(net "M_D_CPU1_SB_CS_N<2>")
	)
	(arc
		(start 94.056454 -246.046244)
		(mid 93.778022 -246.11609)
		(end 93.50121 -246.040148)
		(width 0.088646)
		(layer "In6.Cu")
		(net "M_D_CPU1_SB_CS_N<2>")
	)
	(arc
		(start 94.441264 -246.040148)
		(mid 94.254066 -245.990005)
		(end 94.066868 -246.040148)
		(width 0.088646)
		(layer "In6.Cu")
		(net "M_D_CPU1_SB_CS_N<2>")
	)
	(arc
		(start 88.80221 -246.040148)
		(mid 88.615012 -245.990005)
		(end 88.427814 -246.040148)
		(width 0.088646)
		(layer "In6.Cu")
		(net "M_D_CPU1_SB_CS_N<2>")
	)
	(arc
		(start 95.476568 -246.853964)
		(mid 95.202369 -246.929799)
		(end 94.925896 -246.8626)
		(width 0.088646)
		(layer "In6.Cu")
		(net "M_D_CPU1_SB_CS_N<2>")
	)
	(arc
		(start 85.983064 -246.040148)
		(mid 85.795866 -245.990005)
		(end 85.608668 -246.040148)
		(width 0.088646)
		(layer "In6.Cu")
		(net "M_D_CPU1_SB_CS_N<2>")
	)
	(arc
		(start 91.62161 -246.040148)
		(mid 91.434412 -245.990005)
		(end 91.247214 -246.040148)
		(width 0.088646)
		(layer "In6.Cu")
		(net "M_D_CPU1_SB_CS_N<2>")
	)
	(segment
		(start 97.073466 -246.900446)
		(end 97.073212 -246.900192)
		(width 0.20066)
		(layer "F.Cu")
		(net "M_D_CPU1_SB_CS_N<1>")
	)
	(segment
		(start 97.073212 -246.900192)
		(end 97.073212 -246.364506)
		(width 0.20066)
		(layer "F.Cu")
		(net "M_D_CPU1_SB_CS_N<1>")
	)
	(segment
		(start 12.240514 -244.916706)
		(end 13.345414 -244.916706)
		(width 0.20066)
		(layer "F.Cu")
		(net "M_D_CPU1_SB_CS_N<1>")
	)
	(segment
		(start 85.608414 -245.060978)
		(end 85.593682 -245.052342)
		(width 0.088646)
		(layer "In6.Cu")
		(net "M_D_CPU1_SB_CS_N<1>")
	)
	(segment
		(start 63.267336 -240.244376)
		(end 59.396376 -240.244376)
		(width 0.18288)
		(layer "In6.Cu")
		(net "M_D_CPU1_SB_CS_N<1>")
	)
	(segment
		(start 26.827734 -240.134394)
		(end 26.827734 -239.390428)
		(width 0.18288)
		(layer "In6.Cu")
		(net "M_D_CPU1_SB_CS_N<1>")
	)
	(segment
		(start 36.48456 -240.241074)
		(end 30.169358 -240.241074)
		(width 0.18288)
		(layer "In6.Cu")
		(net "M_D_CPU1_SB_CS_N<1>")
	)
	(segment
		(start 50.98669 -240.24082)
		(end 50.985928 -240.241582)
		(width 0.18288)
		(layer "In6.Cu")
		(net "M_D_CPU1_SB_CS_N<1>")
	)
	(segment
		(start 89.367614 -245.060978)
		(end 89.352882 -245.052342)
		(width 0.088646)
		(layer "In6.Cu")
		(net "M_D_CPU1_SB_CS_N<1>")
	)
	(segment
		(start 92.187268 -245.060978)
		(end 92.176854 -245.054882)
		(width 0.088646)
		(layer "In6.Cu")
		(net "M_D_CPU1_SB_CS_N<1>")
	)
	(segment
		(start 65.898776 -241.968274)
		(end 64.384174 -240.453672)
		(width 0.18288)
		(layer "In6.Cu")
		(net "M_D_CPU1_SB_CS_N<1>")
	)
	(segment
		(start 30.169358 -240.241074)
		(end 29.135832 -239.207548)
		(width 0.18288)
		(layer "In6.Cu")
		(net "M_D_CPU1_SB_CS_N<1>")
	)
	(segment
		(start 95.006414 -245.060978)
		(end 94.991682 -245.052342)
		(width 0.088646)
		(layer "In6.Cu")
		(net "M_D_CPU1_SB_CS_N<1>")
	)
	(segment
		(start 27.518614 -239.390428)
		(end 27.518614 -240.134394)
		(width 0.18288)
		(layer "In6.Cu")
		(net "M_D_CPU1_SB_CS_N<1>")
	)
	(segment
		(start 47.989998 -240.241074)
		(end 37.5412 -240.241074)
		(width 0.18288)
		(layer "In6.Cu")
		(net "M_D_CPU1_SB_CS_N<1>")
	)
	(segment
		(start 37.5412 -240.241074)
		(end 37.35832 -240.058194)
		(width 0.18288)
		(layer "In6.Cu")
		(net "M_D_CPU1_SB_CS_N<1>")
	)
	(segment
		(start 26.827734 -239.390428)
		(end 26.644854 -239.207548)
		(width 0.18288)
		(layer "In6.Cu")
		(net "M_D_CPU1_SB_CS_N<1>")
	)
	(segment
		(start 92.572078 -245.054882)
		(end 92.561664 -245.060978)
		(width 0.088646)
		(layer "In6.Cu")
		(net "M_D_CPU1_SB_CS_N<1>")
	)
	(segment
		(start 27.518614 -240.134394)
		(end 27.335734 -240.317274)
		(width 0.18288)
		(layer "In6.Cu")
		(net "M_D_CPU1_SB_CS_N<1>")
	)
	(segment
		(start 83.4136 -245.783608)
		(end 83.324954 -245.872254)
		(width 0.088646)
		(layer "In6.Cu")
		(net "M_D_CPU1_SB_CS_N<1>")
	)
	(segment
		(start 27.010614 -240.317274)
		(end 26.827734 -240.134394)
		(width 0.18288)
		(layer "In6.Cu")
		(net "M_D_CPU1_SB_CS_N<1>")
	)
	(segment
		(start 37.35832 -240.058194)
		(end 37.35832 -239.58931)
		(width 0.18288)
		(layer "In6.Cu")
		(net "M_D_CPU1_SB_CS_N<1>")
	)
	(segment
		(start 27.335734 -240.317274)
		(end 27.010614 -240.317274)
		(width 0.18288)
		(layer "In6.Cu")
		(net "M_D_CPU1_SB_CS_N<1>")
	)
	(segment
		(start 83.324954 -245.872254)
		(end 83.191096 -245.872254)
		(width 0.088646)
		(layer "In6.Cu")
		(net "M_D_CPU1_SB_CS_N<1>")
	)
	(segment
		(start 86.548214 -245.060978)
		(end 86.533482 -245.052342)
		(width 0.088646)
		(layer "In6.Cu")
		(net "M_D_CPU1_SB_CS_N<1>")
	)
	(segment
		(start 82.528664 -245.872254)
		(end 81.043526 -244.387116)
		(width 0.18288)
		(layer "In6.Cu")
		(net "M_D_CPU1_SB_CS_N<1>")
	)
	(segment
		(start 17.32788 -241.090704)
		(end 15.192756 -241.090704)
		(width 0.18288)
		(layer "In6.Cu")
		(net "M_D_CPU1_SB_CS_N<1>")
	)
	(segment
		(start 23.999952 -239.63122)
		(end 22.540214 -241.090958)
		(width 0.18288)
		(layer "In6.Cu")
		(net "M_D_CPU1_SB_CS_N<1>")
	)
	(segment
		(start 50.985928 -240.241582)
		(end 47.990506 -240.241582)
		(width 0.18288)
		(layer "In6.Cu")
		(net "M_D_CPU1_SB_CS_N<1>")
	)
	(segment
		(start 55.806086 -240.382044)
		(end 55.067454 -239.643412)
		(width 0.18288)
		(layer "In6.Cu")
		(net "M_D_CPU1_SB_CS_N<1>")
	)
	(segment
		(start 81.043526 -244.387116)
		(end 69.85 -244.387116)
		(width 0.18288)
		(layer "In6.Cu")
		(net "M_D_CPU1_SB_CS_N<1>")
	)
	(segment
		(start 90.307668 -245.060978)
		(end 90.297254 -245.054882)
		(width 0.088646)
		(layer "In6.Cu")
		(net "M_D_CPU1_SB_CS_N<1>")
	)
	(segment
		(start 90.692478 -245.054882)
		(end 90.682064 -245.060978)
		(width 0.088646)
		(layer "In6.Cu")
		(net "M_D_CPU1_SB_CS_N<1>")
	)
	(segment
		(start 84.10321 -245.060978)
		(end 84.008976 -245.060978)
		(width 0.088646)
		(layer "In6.Cu")
		(net "M_D_CPU1_SB_CS_N<1>")
	)
	(segment
		(start 64.384174 -240.453672)
		(end 63.476632 -240.453672)
		(width 0.18288)
		(layer "In6.Cu")
		(net "M_D_CPU1_SB_CS_N<1>")
	)
	(segment
		(start 13.65758 -244.60454)
		(end 13.345414 -244.916706)
		(width 0.18288)
		(layer "In6.Cu")
		(net "M_D_CPU1_SB_CS_N<1>")
	)
	(segment
		(start 59.258708 -240.382044)
		(end 55.806086 -240.382044)
		(width 0.18288)
		(layer "In6.Cu")
		(net "M_D_CPU1_SB_CS_N<1>")
	)
	(segment
		(start 22.540214 -241.090958)
		(end 17.328134 -241.090958)
		(width 0.18288)
		(layer "In6.Cu")
		(net "M_D_CPU1_SB_CS_N<1>")
	)
	(segment
		(start 13.86078 -242.42268)
		(end 13.86078 -244.114066)
		(width 0.18288)
		(layer "In6.Cu")
		(net "M_D_CPU1_SB_CS_N<1>")
	)
	(segment
		(start 84.008976 -245.060978)
		(end 83.4136 -245.656354)
		(width 0.088646)
		(layer "In6.Cu")
		(net "M_D_CPU1_SB_CS_N<1>")
	)
	(segment
		(start 15.192756 -241.090704)
		(end 13.86078 -242.42268)
		(width 0.18288)
		(layer "In6.Cu")
		(net "M_D_CPU1_SB_CS_N<1>")
	)
	(segment
		(start 83.4136 -245.656354)
		(end 83.4136 -245.783608)
		(width 0.088646)
		(layer "In6.Cu")
		(net "M_D_CPU1_SB_CS_N<1>")
	)
	(segment
		(start 47.990506 -240.241582)
		(end 47.989998 -240.241074)
		(width 0.18288)
		(layer "In6.Cu")
		(net "M_D_CPU1_SB_CS_N<1>")
	)
	(segment
		(start 25.53843 -239.207548)
		(end 25.114758 -239.63122)
		(width 0.18288)
		(layer "In6.Cu")
		(net "M_D_CPU1_SB_CS_N<1>")
	)
	(segment
		(start 25.114758 -239.63122)
		(end 23.999952 -239.63122)
		(width 0.18288)
		(layer "In6.Cu")
		(net "M_D_CPU1_SB_CS_N<1>")
	)
	(segment
		(start 37.17544 -239.40643)
		(end 36.85032 -239.40643)
		(width 0.18288)
		(layer "In6.Cu")
		(net "M_D_CPU1_SB_CS_N<1>")
	)
	(segment
		(start 63.476632 -240.453672)
		(end 63.267336 -240.244376)
		(width 0.18288)
		(layer "In6.Cu")
		(net "M_D_CPU1_SB_CS_N<1>")
	)
	(segment
		(start 55.067454 -239.643412)
		(end 52.405026 -239.643412)
		(width 0.18288)
		(layer "In6.Cu")
		(net "M_D_CPU1_SB_CS_N<1>")
	)
	(segment
		(start 87.488014 -245.060978)
		(end 87.473282 -245.052342)
		(width 0.088646)
		(layer "In6.Cu")
		(net "M_D_CPU1_SB_CS_N<1>")
	)
	(segment
		(start 37.35832 -239.58931)
		(end 37.17544 -239.40643)
		(width 0.18288)
		(layer "In6.Cu")
		(net "M_D_CPU1_SB_CS_N<1>")
	)
	(segment
		(start 59.396376 -240.244376)
		(end 59.258708 -240.382044)
		(width 0.18288)
		(layer "In6.Cu")
		(net "M_D_CPU1_SB_CS_N<1>")
	)
	(segment
		(start 88.427814 -245.060978)
		(end 88.413082 -245.052342)
		(width 0.088646)
		(layer "In6.Cu")
		(net "M_D_CPU1_SB_CS_N<1>")
	)
	(segment
		(start 13.86078 -244.114066)
		(end 13.65758 -244.60454)
		(width 0.18288)
		(layer "In6.Cu")
		(net "M_D_CPU1_SB_CS_N<1>")
	)
	(segment
		(start 27.701494 -239.207548)
		(end 27.518614 -239.390428)
		(width 0.18288)
		(layer "In6.Cu")
		(net "M_D_CPU1_SB_CS_N<1>")
	)
	(segment
		(start 29.135832 -239.207548)
		(end 27.701494 -239.207548)
		(width 0.18288)
		(layer "In6.Cu")
		(net "M_D_CPU1_SB_CS_N<1>")
	)
	(segment
		(start 67.431158 -241.968274)
		(end 65.898776 -241.968274)
		(width 0.18288)
		(layer "In6.Cu")
		(net "M_D_CPU1_SB_CS_N<1>")
	)
	(segment
		(start 26.644854 -239.207548)
		(end 25.53843 -239.207548)
		(width 0.18288)
		(layer "In6.Cu")
		(net "M_D_CPU1_SB_CS_N<1>")
	)
	(segment
		(start 69.85 -244.387116)
		(end 67.431158 -241.968274)
		(width 0.18288)
		(layer "In6.Cu")
		(net "M_D_CPU1_SB_CS_N<1>")
	)
	(segment
		(start 52.405026 -239.643412)
		(end 51.807618 -240.24082)
		(width 0.18288)
		(layer "In6.Cu")
		(net "M_D_CPU1_SB_CS_N<1>")
	)
	(segment
		(start 84.668614 -245.060978)
		(end 84.653882 -245.052342)
		(width 0.088646)
		(layer "In6.Cu")
		(net "M_D_CPU1_SB_CS_N<1>")
	)
	(segment
		(start 36.85032 -239.40643)
		(end 36.66744 -239.58931)
		(width 0.18288)
		(layer "In6.Cu")
		(net "M_D_CPU1_SB_CS_N<1>")
	)
	(segment
		(start 83.191096 -245.872254)
		(end 82.528664 -245.872254)
		(width 0.18288)
		(layer "In6.Cu")
		(net "M_D_CPU1_SB_CS_N<1>")
	)
	(segment
		(start 36.66744 -239.58931)
		(end 36.66744 -240.058194)
		(width 0.18288)
		(layer "In6.Cu")
		(net "M_D_CPU1_SB_CS_N<1>")
	)
	(segment
		(start 51.807618 -240.24082)
		(end 50.98669 -240.24082)
		(width 0.18288)
		(layer "In6.Cu")
		(net "M_D_CPU1_SB_CS_N<1>")
	)
	(segment
		(start 36.66744 -240.058194)
		(end 36.48456 -240.241074)
		(width 0.18288)
		(layer "In6.Cu")
		(net "M_D_CPU1_SB_CS_N<1>")
	)
	(segment
		(start 94.066614 -245.060978)
		(end 94.051882 -245.052342)
		(width 0.088646)
		(layer "In6.Cu")
		(net "M_D_CPU1_SB_CS_N<1>")
	)
	(segment
		(start 17.328134 -241.090958)
		(end 17.32788 -241.090704)
		(width 0.18288)
		(layer "In6.Cu")
		(net "M_D_CPU1_SB_CS_N<1>")
	)
	(arc
		(start 89.352882 -245.052342)
		(mid 89.076441 -244.985176)
		(end 88.80221 -245.060978)
		(width 0.088646)
		(layer "In6.Cu")
		(net "M_D_CPU1_SB_CS_N<1>")
	)
	(arc
		(start 95.94469 -245.060216)
		(mid 95.905485 -245.039254)
		(end 95.86468 -245.021608)
		(width 0.088646)
		(layer "In6.Cu")
		(net "M_D_CPU1_SB_CS_N<1>")
	)
	(arc
		(start 96.383856 -245.122954)
		(mid 96.286521 -245.122941)
		(end 96.189546 -245.114572)
		(width 0.088646)
		(layer "In6.Cu")
		(net "M_D_CPU1_SB_CS_N<1>")
	)
	(arc
		(start 90.682064 -245.060978)
		(mid 90.494866 -245.111121)
		(end 90.307668 -245.060978)
		(width 0.088646)
		(layer "In6.Cu")
		(net "M_D_CPU1_SB_CS_N<1>")
	)
	(arc
		(start 86.533482 -245.052342)
		(mid 86.257041 -244.985176)
		(end 85.98281 -245.060978)
		(width 0.088646)
		(layer "In6.Cu")
		(net "M_D_CPU1_SB_CS_N<1>")
	)
	(arc
		(start 97.073212 -246.364506)
		(mid 97.064165 -245.97856)
		(end 97.026222 -245.594378)
		(width 0.088646)
		(layer "In6.Cu")
		(net "M_D_CPU1_SB_CS_N<1>")
	)
	(arc
		(start 87.86241 -245.060978)
		(mid 87.675212 -245.111121)
		(end 87.488014 -245.060978)
		(width 0.088646)
		(layer "In6.Cu")
		(net "M_D_CPU1_SB_CS_N<1>")
	)
	(arc
		(start 88.413082 -245.052342)
		(mid 88.136641 -244.985176)
		(end 87.86241 -245.060978)
		(width 0.088646)
		(layer "In6.Cu")
		(net "M_D_CPU1_SB_CS_N<1>")
	)
	(arc
		(start 85.593682 -245.052342)
		(mid 85.317241 -244.985176)
		(end 85.04301 -245.060978)
		(width 0.088646)
		(layer "In6.Cu")
		(net "M_D_CPU1_SB_CS_N<1>")
	)
	(arc
		(start 94.051882 -245.052342)
		(mid 93.775441 -244.985176)
		(end 93.50121 -245.060978)
		(width 0.088646)
		(layer "In6.Cu")
		(net "M_D_CPU1_SB_CS_N<1>")
	)
	(arc
		(start 86.92261 -245.060978)
		(mid 86.735412 -245.111121)
		(end 86.548214 -245.060978)
		(width 0.088646)
		(layer "In6.Cu")
		(net "M_D_CPU1_SB_CS_N<1>")
	)
	(arc
		(start 93.126814 -245.060978)
		(mid 92.850255 -244.985269)
		(end 92.572078 -245.054882)
		(width 0.088646)
		(layer "In6.Cu")
		(net "M_D_CPU1_SB_CS_N<1>")
	)
	(arc
		(start 91.247214 -245.060978)
		(mid 90.970655 -244.985269)
		(end 90.692478 -245.054882)
		(width 0.088646)
		(layer "In6.Cu")
		(net "M_D_CPU1_SB_CS_N<1>")
	)
	(arc
		(start 85.04301 -245.060978)
		(mid 84.855812 -245.111121)
		(end 84.668614 -245.060978)
		(width 0.088646)
		(layer "In6.Cu")
		(net "M_D_CPU1_SB_CS_N<1>")
	)
	(arc
		(start 94.44101 -245.060978)
		(mid 94.253812 -245.111121)
		(end 94.066614 -245.060978)
		(width 0.088646)
		(layer "In6.Cu")
		(net "M_D_CPU1_SB_CS_N<1>")
	)
	(arc
		(start 90.297254 -245.054882)
		(mid 90.018822 -244.985068)
		(end 89.74201 -245.060978)
		(width 0.088646)
		(layer "In6.Cu")
		(net "M_D_CPU1_SB_CS_N<1>")
	)
	(arc
		(start 85.98281 -245.060978)
		(mid 85.795612 -245.111121)
		(end 85.608414 -245.060978)
		(width 0.088646)
		(layer "In6.Cu")
		(net "M_D_CPU1_SB_CS_N<1>")
	)
	(arc
		(start 97.026222 -245.594378)
		(mid 96.871197 -245.283389)
		(end 96.559116 -245.130574)
		(width 0.088646)
		(layer "In6.Cu")
		(net "M_D_CPU1_SB_CS_N<1>")
	)
	(arc
		(start 96.559116 -245.130574)
		(mid 96.471649 -245.123015)
		(end 96.383856 -245.122954)
		(width 0.088646)
		(layer "In6.Cu")
		(net "M_D_CPU1_SB_CS_N<1>")
	)
	(arc
		(start 96.189546 -245.114572)
		(mid 96.163569 -245.112005)
		(end 96.137476 -245.11127)
		(width 0.088646)
		(layer "In6.Cu")
		(net "M_D_CPU1_SB_CS_N<1>")
	)
	(arc
		(start 88.80221 -245.060978)
		(mid 88.615012 -245.111121)
		(end 88.427814 -245.060978)
		(width 0.088646)
		(layer "In6.Cu")
		(net "M_D_CPU1_SB_CS_N<1>")
	)
	(arc
		(start 92.176854 -245.054882)
		(mid 91.898422 -244.985068)
		(end 91.62161 -245.060978)
		(width 0.088646)
		(layer "In6.Cu")
		(net "M_D_CPU1_SB_CS_N<1>")
	)
	(arc
		(start 89.74201 -245.060978)
		(mid 89.554812 -245.111121)
		(end 89.367614 -245.060978)
		(width 0.088646)
		(layer "In6.Cu")
		(net "M_D_CPU1_SB_CS_N<1>")
	)
	(arc
		(start 96.137476 -245.11127)
		(mid 96.037611 -245.098837)
		(end 95.94469 -245.060216)
		(width 0.088646)
		(layer "In6.Cu")
		(net "M_D_CPU1_SB_CS_N<1>")
	)
	(arc
		(start 93.50121 -245.060978)
		(mid 93.314012 -245.111121)
		(end 93.126814 -245.060978)
		(width 0.088646)
		(layer "In6.Cu")
		(net "M_D_CPU1_SB_CS_N<1>")
	)
	(arc
		(start 95.86468 -245.021608)
		(mid 95.618319 -244.986778)
		(end 95.38081 -245.060978)
		(width 0.088646)
		(layer "In6.Cu")
		(net "M_D_CPU1_SB_CS_N<1>")
	)
	(arc
		(start 91.62161 -245.060978)
		(mid 91.434412 -245.111121)
		(end 91.247214 -245.060978)
		(width 0.088646)
		(layer "In6.Cu")
		(net "M_D_CPU1_SB_CS_N<1>")
	)
	(arc
		(start 95.38081 -245.060978)
		(mid 95.193612 -245.111121)
		(end 95.006414 -245.060978)
		(width 0.088646)
		(layer "In6.Cu")
		(net "M_D_CPU1_SB_CS_N<1>")
	)
	(arc
		(start 94.991682 -245.052342)
		(mid 94.715241 -244.985176)
		(end 94.44101 -245.060978)
		(width 0.088646)
		(layer "In6.Cu")
		(net "M_D_CPU1_SB_CS_N<1>")
	)
	(arc
		(start 92.561664 -245.060978)
		(mid 92.374466 -245.111121)
		(end 92.187268 -245.060978)
		(width 0.088646)
		(layer "In6.Cu")
		(net "M_D_CPU1_SB_CS_N<1>")
	)
	(arc
		(start 87.473282 -245.052342)
		(mid 87.196841 -244.985176)
		(end 86.92261 -245.060978)
		(width 0.088646)
		(layer "In6.Cu")
		(net "M_D_CPU1_SB_CS_N<1>")
	)
	(arc
		(start 84.653882 -245.052342)
		(mid 84.377441 -244.985176)
		(end 84.10321 -245.060978)
		(width 0.088646)
		(layer "In6.Cu")
		(net "M_D_CPU1_SB_CS_N<1>")
	)
	(segment
		(start 8.140446 -245.76659)
		(end 9.245346 -245.76659)
		(width 0.20066)
		(layer "F.Cu")
		(net "M_D_CPU1_SB_CS_N<0>")
	)
	(segment
		(start 95.193612 -246.900192)
		(end 95.193612 -246.364506)
		(width 0.20066)
		(layer "F.Cu")
		(net "M_D_CPU1_SB_CS_N<0>")
	)
	(segment
		(start 95.193866 -246.900446)
		(end 95.193612 -246.900192)
		(width 0.20066)
		(layer "F.Cu")
		(net "M_D_CPU1_SB_CS_N<0>")
	)
	(segment
		(start 11.759438 -246.03075)
		(end 11.759438 -245.52783)
		(width 0.18288)
		(layer "In6.Cu")
		(net "M_D_CPU1_SB_CS_N<0>")
	)
	(segment
		(start 10.459212 -245.76659)
		(end 9.245346 -245.76659)
		(width 0.18288)
		(layer "In6.Cu")
		(net "M_D_CPU1_SB_CS_N<0>")
	)
	(segment
		(start 55.710836 -241.000026)
		(end 54.858412 -240.147602)
		(width 0.18288)
		(layer "In6.Cu")
		(net "M_D_CPU1_SB_CS_N<0>")
	)
	(segment
		(start 92.656914 -245.226332)
		(end 92.6465 -245.232428)
		(width 0.088646)
		(layer "In6.Cu")
		(net "M_D_CPU1_SB_CS_N<0>")
	)
	(segment
		(start 67.234562 -242.499134)
		(end 65.696592 -242.499134)
		(width 0.18288)
		(layer "In6.Cu")
		(net "M_D_CPU1_SB_CS_N<0>")
	)
	(segment
		(start 86.467696 -245.234968)
		(end 86.452964 -245.226332)
		(width 0.088646)
		(layer "In6.Cu")
		(net "M_D_CPU1_SB_CS_N<0>")
	)
	(segment
		(start 91.162124 -245.232428)
		(end 91.15171 -245.226332)
		(width 0.088646)
		(layer "In6.Cu")
		(net "M_D_CPU1_SB_CS_N<0>")
	)
	(segment
		(start 83.608926 -245.740174)
		(end 83.608926 -245.83136)
		(width 0.088646)
		(layer "In6.Cu")
		(net "M_D_CPU1_SB_CS_N<0>")
	)
	(segment
		(start 12.478258 -245.52783)
		(end 12.478258 -246.03075)
		(width 0.18288)
		(layer "In6.Cu")
		(net "M_D_CPU1_SB_CS_N<0>")
	)
	(segment
		(start 69.751448 -245.01602)
		(end 67.234562 -242.499134)
		(width 0.18288)
		(layer "In6.Cu")
		(net "M_D_CPU1_SB_CS_N<0>")
	)
	(segment
		(start 80.900524 -244.725698)
		(end 72.869552 -244.725698)
		(width 0.18288)
		(layer "In6.Cu")
		(net "M_D_CPU1_SB_CS_N<0>")
	)
	(segment
		(start 24.833834 -240.16208)
		(end 24.182832 -240.16208)
		(width 0.18288)
		(layer "In6.Cu")
		(net "M_D_CPU1_SB_CS_N<0>")
	)
	(segment
		(start 88.347296 -245.234968)
		(end 88.332564 -245.226332)
		(width 0.088646)
		(layer "In6.Cu")
		(net "M_D_CPU1_SB_CS_N<0>")
	)
	(segment
		(start 11.576558 -245.34495)
		(end 10.880852 -245.34495)
		(width 0.18288)
		(layer "In6.Cu")
		(net "M_D_CPU1_SB_CS_N<0>")
	)
	(segment
		(start 24.182832 -240.16208)
		(end 22.40407 -241.940842)
		(width 0.18288)
		(layer "In6.Cu")
		(net "M_D_CPU1_SB_CS_N<0>")
	)
	(segment
		(start 59.133486 -241.203226)
		(end 58.930286 -241.000026)
		(width 0.18288)
		(layer "In6.Cu")
		(net "M_D_CPU1_SB_CS_N<0>")
	)
	(segment
		(start 93.041724 -245.232428)
		(end 93.03131 -245.226332)
		(width 0.088646)
		(layer "In6.Cu")
		(net "M_D_CPU1_SB_CS_N<0>")
	)
	(segment
		(start 83.479132 -246.144542)
		(end 83.403694 -246.21998)
		(width 0.088646)
		(layer "In6.Cu")
		(net "M_D_CPU1_SB_CS_N<0>")
	)
	(segment
		(start 84.095844 -245.253256)
		(end 83.608926 -245.740174)
		(width 0.088646)
		(layer "In6.Cu")
		(net "M_D_CPU1_SB_CS_N<0>")
	)
	(segment
		(start 84.172044 -245.253256)
		(end 84.095844 -245.253256)
		(width 0.088646)
		(layer "In6.Cu")
		(net "M_D_CPU1_SB_CS_N<0>")
	)
	(segment
		(start 28.886912 -240.858548)
		(end 25.530302 -240.858548)
		(width 0.18288)
		(layer "In6.Cu")
		(net "M_D_CPU1_SB_CS_N<0>")
	)
	(segment
		(start 89.287096 -245.234968)
		(end 89.272364 -245.226332)
		(width 0.088646)
		(layer "In6.Cu")
		(net "M_D_CPU1_SB_CS_N<0>")
	)
	(segment
		(start 83.19135 -246.21998)
		(end 82.394806 -246.21998)
		(width 0.18288)
		(layer "In6.Cu")
		(net "M_D_CPU1_SB_CS_N<0>")
	)
	(segment
		(start 93.986096 -245.234968)
		(end 93.971364 -245.226332)
		(width 0.088646)
		(layer "In6.Cu")
		(net "M_D_CPU1_SB_CS_N<0>")
	)
	(segment
		(start 25.530302 -240.858548)
		(end 24.833834 -240.16208)
		(width 0.18288)
		(layer "In6.Cu")
		(net "M_D_CPU1_SB_CS_N<0>")
	)
	(segment
		(start 85.527896 -245.234968)
		(end 85.513164 -245.226332)
		(width 0.088646)
		(layer "In6.Cu")
		(net "M_D_CPU1_SB_CS_N<0>")
	)
	(segment
		(start 54.858412 -240.147602)
		(end 53.879242 -240.147602)
		(width 0.18288)
		(layer "In6.Cu")
		(net "M_D_CPU1_SB_CS_N<0>")
	)
	(segment
		(start 16.069818 -241.940842)
		(end 14.97838 -243.03228)
		(width 0.18288)
		(layer "In6.Cu")
		(net "M_D_CPU1_SB_CS_N<0>")
	)
	(segment
		(start 62.87897 -241.09045)
		(end 62.766194 -241.203226)
		(width 0.18288)
		(layer "In6.Cu")
		(net "M_D_CPU1_SB_CS_N<0>")
	)
	(segment
		(start 13.718032 -245.34495)
		(end 12.661138 -245.34495)
		(width 0.18288)
		(layer "In6.Cu")
		(net "M_D_CPU1_SB_CS_N<0>")
	)
	(segment
		(start 82.394806 -246.21998)
		(end 80.900524 -244.725698)
		(width 0.18288)
		(layer "In6.Cu")
		(net "M_D_CPU1_SB_CS_N<0>")
	)
	(segment
		(start 12.295378 -246.21363)
		(end 11.942318 -246.21363)
		(width 0.18288)
		(layer "In6.Cu")
		(net "M_D_CPU1_SB_CS_N<0>")
	)
	(segment
		(start 87.407496 -245.234968)
		(end 87.392764 -245.226332)
		(width 0.088646)
		(layer "In6.Cu")
		(net "M_D_CPU1_SB_CS_N<0>")
	)
	(segment
		(start 10.880852 -245.34495)
		(end 10.459212 -245.76659)
		(width 0.18288)
		(layer "In6.Cu")
		(net "M_D_CPU1_SB_CS_N<0>")
	)
	(segment
		(start 29.119322 -241.090958)
		(end 28.886912 -240.858548)
		(width 0.18288)
		(layer "In6.Cu")
		(net "M_D_CPU1_SB_CS_N<0>")
	)
	(segment
		(start 64.287908 -241.09045)
		(end 62.87897 -241.09045)
		(width 0.18288)
		(layer "In6.Cu")
		(net "M_D_CPU1_SB_CS_N<0>")
	)
	(segment
		(start 90.777314 -245.226332)
		(end 90.7669 -245.232428)
		(width 0.088646)
		(layer "In6.Cu")
		(net "M_D_CPU1_SB_CS_N<0>")
	)
	(segment
		(start 72.57923 -245.01602)
		(end 69.751448 -245.01602)
		(width 0.18288)
		(layer "In6.Cu")
		(net "M_D_CPU1_SB_CS_N<0>")
	)
	(segment
		(start 22.40407 -241.940842)
		(end 16.069818 -241.940842)
		(width 0.18288)
		(layer "In6.Cu")
		(net "M_D_CPU1_SB_CS_N<0>")
	)
	(segment
		(start 12.478258 -246.03075)
		(end 12.295378 -246.21363)
		(width 0.18288)
		(layer "In6.Cu")
		(net "M_D_CPU1_SB_CS_N<0>")
	)
	(segment
		(start 65.696592 -242.499134)
		(end 64.287908 -241.09045)
		(width 0.18288)
		(layer "In6.Cu")
		(net "M_D_CPU1_SB_CS_N<0>")
	)
	(segment
		(start 14.97838 -243.03228)
		(end 14.97838 -243.870226)
		(width 0.18288)
		(layer "In6.Cu")
		(net "M_D_CPU1_SB_CS_N<0>")
	)
	(segment
		(start 14.045946 -245.017036)
		(end 13.718032 -245.34495)
		(width 0.18288)
		(layer "In6.Cu")
		(net "M_D_CPU1_SB_CS_N<0>")
	)
	(segment
		(start 83.403694 -246.21998)
		(end 83.19135 -246.21998)
		(width 0.088646)
		(layer "In6.Cu")
		(net "M_D_CPU1_SB_CS_N<0>")
	)
	(segment
		(start 14.97838 -243.870226)
		(end 14.197584 -244.651022)
		(width 0.18288)
		(layer "In6.Cu")
		(net "M_D_CPU1_SB_CS_N<0>")
	)
	(segment
		(start 11.942318 -246.21363)
		(end 11.759438 -246.03075)
		(width 0.18288)
		(layer "In6.Cu")
		(net "M_D_CPU1_SB_CS_N<0>")
	)
	(segment
		(start 84.588096 -245.234968)
		(end 84.573364 -245.226332)
		(width 0.088646)
		(layer "In6.Cu")
		(net "M_D_CPU1_SB_CS_N<0>")
	)
	(segment
		(start 14.197584 -244.651022)
		(end 14.045946 -245.017036)
		(width 0.18288)
		(layer "In6.Cu")
		(net "M_D_CPU1_SB_CS_N<0>")
	)
	(segment
		(start 58.930286 -241.000026)
		(end 55.710836 -241.000026)
		(width 0.18288)
		(layer "In6.Cu")
		(net "M_D_CPU1_SB_CS_N<0>")
	)
	(segment
		(start 12.661138 -245.34495)
		(end 12.478258 -245.52783)
		(width 0.18288)
		(layer "In6.Cu")
		(net "M_D_CPU1_SB_CS_N<0>")
	)
	(segment
		(start 83.608926 -245.83136)
		(end 83.479132 -246.144542)
		(width 0.088646)
		(layer "In6.Cu")
		(net "M_D_CPU1_SB_CS_N<0>")
	)
	(segment
		(start 11.759438 -245.52783)
		(end 11.576558 -245.34495)
		(width 0.18288)
		(layer "In6.Cu")
		(net "M_D_CPU1_SB_CS_N<0>")
	)
	(segment
		(start 62.766194 -241.203226)
		(end 59.133486 -241.203226)
		(width 0.18288)
		(layer "In6.Cu")
		(net "M_D_CPU1_SB_CS_N<0>")
	)
	(segment
		(start 84.198968 -245.226332)
		(end 84.172044 -245.253256)
		(width 0.088646)
		(layer "In6.Cu")
		(net "M_D_CPU1_SB_CS_N<0>")
	)
	(segment
		(start 52.935886 -241.090958)
		(end 29.119322 -241.090958)
		(width 0.18288)
		(layer "In6.Cu")
		(net "M_D_CPU1_SB_CS_N<0>")
	)
	(segment
		(start 53.879242 -240.147602)
		(end 52.935886 -241.090958)
		(width 0.18288)
		(layer "In6.Cu")
		(net "M_D_CPU1_SB_CS_N<0>")
	)
	(segment
		(start 94.925896 -245.234968)
		(end 94.911164 -245.226332)
		(width 0.088646)
		(layer "In6.Cu")
		(net "M_D_CPU1_SB_CS_N<0>")
	)
	(segment
		(start 72.869552 -244.725698)
		(end 72.57923 -245.01602)
		(width 0.18288)
		(layer "In6.Cu")
		(net "M_D_CPU1_SB_CS_N<0>")
	)
	(arc
		(start 85.513164 -245.226332)
		(mid 85.325966 -245.176189)
		(end 85.138768 -245.226332)
		(width 0.088646)
		(layer "In6.Cu")
		(net "M_D_CPU1_SB_CS_N<0>")
	)
	(arc
		(start 92.6465 -245.232428)
		(mid 92.368322 -245.30212)
		(end 92.091764 -245.226332)
		(width 0.088646)
		(layer "In6.Cu")
		(net "M_D_CPU1_SB_CS_N<0>")
	)
	(arc
		(start 94.911164 -245.226332)
		(mid 94.723966 -245.176189)
		(end 94.536768 -245.226332)
		(width 0.088646)
		(layer "In6.Cu")
		(net "M_D_CPU1_SB_CS_N<0>")
	)
	(arc
		(start 95.014796 -245.273322)
		(mid 94.969524 -245.256051)
		(end 94.925896 -245.234968)
		(width 0.088646)
		(layer "In6.Cu")
		(net "M_D_CPU1_SB_CS_N<0>")
	)
	(arc
		(start 91.15171 -245.226332)
		(mid 90.964512 -245.176189)
		(end 90.777314 -245.226332)
		(width 0.088646)
		(layer "In6.Cu")
		(net "M_D_CPU1_SB_CS_N<0>")
	)
	(arc
		(start 84.573364 -245.226332)
		(mid 84.386166 -245.176189)
		(end 84.198968 -245.226332)
		(width 0.088646)
		(layer "In6.Cu")
		(net "M_D_CPU1_SB_CS_N<0>")
	)
	(arc
		(start 94.536768 -245.226332)
		(mid 94.262539 -245.302257)
		(end 93.986096 -245.234968)
		(width 0.088646)
		(layer "In6.Cu")
		(net "M_D_CPU1_SB_CS_N<0>")
	)
	(arc
		(start 87.392764 -245.226332)
		(mid 87.205566 -245.176189)
		(end 87.018368 -245.226332)
		(width 0.088646)
		(layer "In6.Cu")
		(net "M_D_CPU1_SB_CS_N<0>")
	)
	(arc
		(start 93.971364 -245.226332)
		(mid 93.784166 -245.176189)
		(end 93.596968 -245.226332)
		(width 0.088646)
		(layer "In6.Cu")
		(net "M_D_CPU1_SB_CS_N<0>")
	)
	(arc
		(start 90.7669 -245.232428)
		(mid 90.488722 -245.30212)
		(end 90.212164 -245.226332)
		(width 0.088646)
		(layer "In6.Cu")
		(net "M_D_CPU1_SB_CS_N<0>")
	)
	(arc
		(start 88.897968 -245.226332)
		(mid 88.623739 -245.302257)
		(end 88.347296 -245.234968)
		(width 0.088646)
		(layer "In6.Cu")
		(net "M_D_CPU1_SB_CS_N<0>")
	)
	(arc
		(start 87.958168 -245.226332)
		(mid 87.683939 -245.302257)
		(end 87.407496 -245.234968)
		(width 0.088646)
		(layer "In6.Cu")
		(net "M_D_CPU1_SB_CS_N<0>")
	)
	(arc
		(start 87.018368 -245.226332)
		(mid 86.744139 -245.302257)
		(end 86.467696 -245.234968)
		(width 0.088646)
		(layer "In6.Cu")
		(net "M_D_CPU1_SB_CS_N<0>")
	)
	(arc
		(start 95.193612 -246.364506)
		(mid 95.231183 -245.859238)
		(end 95.11411 -245.366286)
		(width 0.088646)
		(layer "In6.Cu")
		(net "M_D_CPU1_SB_CS_N<0>")
	)
	(arc
		(start 86.078568 -245.226332)
		(mid 85.804339 -245.302257)
		(end 85.527896 -245.234968)
		(width 0.088646)
		(layer "In6.Cu")
		(net "M_D_CPU1_SB_CS_N<0>")
	)
	(arc
		(start 88.332564 -245.226332)
		(mid 88.145366 -245.176189)
		(end 87.958168 -245.226332)
		(width 0.088646)
		(layer "In6.Cu")
		(net "M_D_CPU1_SB_CS_N<0>")
	)
	(arc
		(start 85.138768 -245.226332)
		(mid 84.864539 -245.302257)
		(end 84.588096 -245.234968)
		(width 0.088646)
		(layer "In6.Cu")
		(net "M_D_CPU1_SB_CS_N<0>")
	)
	(arc
		(start 92.091764 -245.226332)
		(mid 91.904566 -245.176189)
		(end 91.717368 -245.226332)
		(width 0.088646)
		(layer "In6.Cu")
		(net "M_D_CPU1_SB_CS_N<0>")
	)
	(arc
		(start 89.837768 -245.226332)
		(mid 89.563539 -245.302257)
		(end 89.287096 -245.234968)
		(width 0.088646)
		(layer "In6.Cu")
		(net "M_D_CPU1_SB_CS_N<0>")
	)
	(arc
		(start 93.596968 -245.226332)
		(mid 93.320155 -245.302168)
		(end 93.041724 -245.232428)
		(width 0.088646)
		(layer "In6.Cu")
		(net "M_D_CPU1_SB_CS_N<0>")
	)
	(arc
		(start 95.11411 -245.366286)
		(mid 95.074651 -245.308892)
		(end 95.014796 -245.273322)
		(width 0.088646)
		(layer "In6.Cu")
		(net "M_D_CPU1_SB_CS_N<0>")
	)
	(arc
		(start 90.212164 -245.226332)
		(mid 90.024966 -245.176189)
		(end 89.837768 -245.226332)
		(width 0.088646)
		(layer "In6.Cu")
		(net "M_D_CPU1_SB_CS_N<0>")
	)
	(arc
		(start 93.03131 -245.226332)
		(mid 92.844112 -245.176189)
		(end 92.656914 -245.226332)
		(width 0.088646)
		(layer "In6.Cu")
		(net "M_D_CPU1_SB_CS_N<0>")
	)
	(arc
		(start 86.452964 -245.226332)
		(mid 86.265766 -245.176189)
		(end 86.078568 -245.226332)
		(width 0.088646)
		(layer "In6.Cu")
		(net "M_D_CPU1_SB_CS_N<0>")
	)
	(arc
		(start 89.272364 -245.226332)
		(mid 89.085166 -245.176189)
		(end 88.897968 -245.226332)
		(width 0.088646)
		(layer "In6.Cu")
		(net "M_D_CPU1_SB_CS_N<0>")
	)
	(arc
		(start 91.717368 -245.226332)
		(mid 91.440555 -245.302168)
		(end 91.162124 -245.232428)
		(width 0.088646)
		(layer "In6.Cu")
		(net "M_D_CPU1_SB_CS_N<0>")
	)
	(segment
		(start 17.578578 -239.090962)
		(end 17.707102 -238.962438)
		(width 0.20066)
		(layer "F.Cu")
		(net "M_D_CPU1_SB_CB<7>")
	)
	(segment
		(start 18.760694 -239.174274)
		(end 18.968212 -238.966756)
		(width 0.20066)
		(layer "F.Cu")
		(net "M_D_CPU1_SB_CB<7>")
	)
	(segment
		(start 100.362766 -246.086376)
		(end 100.362766 -245.55069)
		(width 0.20066)
		(layer "F.Cu")
		(net "M_D_CPU1_SB_CB<7>")
	)
	(segment
		(start 17.42948 -239.391698)
		(end 17.578578 -239.2426)
		(width 0.20066)
		(layer "F.Cu")
		(net "M_D_CPU1_SB_CB<7>")
	)
	(segment
		(start 18.102326 -238.962438)
		(end 18.314162 -239.174274)
		(width 0.20066)
		(layer "F.Cu")
		(net "M_D_CPU1_SB_CB<7>")
	)
	(segment
		(start 100.362512 -246.08663)
		(end 100.362766 -246.086376)
		(width 0.20066)
		(layer "F.Cu")
		(net "M_D_CPU1_SB_CB<7>")
	)
	(segment
		(start 17.707102 -238.962438)
		(end 18.102326 -238.962438)
		(width 0.20066)
		(layer "F.Cu")
		(net "M_D_CPU1_SB_CB<7>")
	)
	(segment
		(start 13.937742 -238.966756)
		(end 14.063726 -239.09274)
		(width 0.20066)
		(layer "F.Cu")
		(net "M_D_CPU1_SB_CB<7>")
	)
	(segment
		(start 14.560042 -239.405922)
		(end 14.574266 -239.391698)
		(width 0.101854)
		(layer "F.Cu")
		(net "M_D_CPU1_SB_CB<7>")
	)
	(segment
		(start 14.20622 -239.405922)
		(end 14.560042 -239.405922)
		(width 0.20066)
		(layer "F.Cu")
		(net "M_D_CPU1_SB_CB<7>")
	)
	(segment
		(start 20.889214 -238.966756)
		(end 19.784314 -238.966756)
		(width 0.20066)
		(layer "F.Cu")
		(net "M_D_CPU1_SB_CB<7>")
	)
	(segment
		(start 14.063726 -239.09274)
		(end 14.063726 -239.263428)
		(width 0.20066)
		(layer "F.Cu")
		(net "M_D_CPU1_SB_CB<7>")
	)
	(segment
		(start 14.063726 -239.263428)
		(end 14.20622 -239.405922)
		(width 0.20066)
		(layer "F.Cu")
		(net "M_D_CPU1_SB_CB<7>")
	)
	(segment
		(start 16.885158 -239.391698)
		(end 17.42948 -239.391698)
		(width 0.20066)
		(layer "F.Cu")
		(net "M_D_CPU1_SB_CB<7>")
	)
	(segment
		(start 14.574266 -239.391698)
		(end 14.812264 -239.391698)
		(width 0.101854)
		(layer "F.Cu")
		(net "M_D_CPU1_SB_CB<7>")
	)
	(segment
		(start 12.240514 -238.966756)
		(end 13.937742 -238.966756)
		(width 0.20066)
		(layer "F.Cu")
		(net "M_D_CPU1_SB_CB<7>")
	)
	(segment
		(start 14.812264 -239.391698)
		(end 16.885158 -239.391698)
		(width 0.1016)
		(layer "F.Cu")
		(net "M_D_CPU1_SB_CB<7>")
	)
	(segment
		(start 17.578578 -239.2426)
		(end 17.578578 -239.090962)
		(width 0.20066)
		(layer "F.Cu")
		(net "M_D_CPU1_SB_CB<7>")
	)
	(segment
		(start 18.968212 -238.966756)
		(end 19.784314 -238.966756)
		(width 0.20066)
		(layer "F.Cu")
		(net "M_D_CPU1_SB_CB<7>")
	)
	(segment
		(start 18.314162 -239.174274)
		(end 18.760694 -239.174274)
		(width 0.20066)
		(layer "F.Cu")
		(net "M_D_CPU1_SB_CB<7>")
	)
	(segment
		(start 26.849578 -239.579912)
		(end 26.656538 -239.386872)
		(width 0.18288)
		(layer "In11.Cu")
		(net "M_D_CPU1_SB_CB<7>")
	)
	(segment
		(start 66.593974 -239.526826)
		(end 66.261996 -239.389412)
		(width 0.18288)
		(layer "In11.Cu")
		(net "M_D_CPU1_SB_CB<7>")
	)
	(segment
		(start 47.375826 -240.241074)
		(end 46.65472 -240.241074)
		(width 0.18288)
		(layer "In11.Cu")
		(net "M_D_CPU1_SB_CB<7>")
	)
	(segment
		(start 50.06213 -239.39119)
		(end 49.034192 -240.419128)
		(width 0.18288)
		(layer "In11.Cu")
		(net "M_D_CPU1_SB_CB<7>")
	)
	(segment
		(start 65.323212 -239.389412)
		(end 64.661288 -238.727488)
		(width 0.18288)
		(layer "In11.Cu")
		(net "M_D_CPU1_SB_CB<7>")
	)
	(segment
		(start 22.871938 -239.364266)
		(end 22.678898 -239.557306)
		(width 0.18288)
		(layer "In11.Cu")
		(net "M_D_CPU1_SB_CB<7>")
	)
	(segment
		(start 40.975026 -238.612426)
		(end 40.009826 -239.577626)
		(width 0.18288)
		(layer "In11.Cu")
		(net "M_D_CPU1_SB_CB<7>")
	)
	(segment
		(start 96.801178 -245.868952)
		(end 96.790764 -245.875048)
		(width 0.088646)
		(layer "In11.Cu")
		(net "M_D_CPU1_SB_CB<7>")
	)
	(segment
		(start 23.766018 -239.557306)
		(end 23.572978 -239.364266)
		(width 0.18288)
		(layer "In11.Cu")
		(net "M_D_CPU1_SB_CB<7>")
	)
	(segment
		(start 98.670364 -245.226586)
		(end 98.670364 -245.226332)
		(width 0.088646)
		(layer "In11.Cu")
		(net "M_D_CPU1_SB_CB<7>")
	)
	(segment
		(start 23.572978 -239.364266)
		(end 23.572978 -239.032288)
		(width 0.18288)
		(layer "In11.Cu")
		(net "M_D_CPU1_SB_CB<7>")
	)
	(segment
		(start 22.678898 -239.557306)
		(end 21.479764 -239.557306)
		(width 0.18288)
		(layer "In11.Cu")
		(net "M_D_CPU1_SB_CB<7>")
	)
	(segment
		(start 88.347296 -245.866412)
		(end 88.332564 -245.875048)
		(width 0.088646)
		(layer "In11.Cu")
		(net "M_D_CPU1_SB_CB<7>")
	)
	(segment
		(start 23.572978 -239.032288)
		(end 23.379938 -238.839248)
		(width 0.18288)
		(layer "In11.Cu")
		(net "M_D_CPU1_SB_CB<7>")
	)
	(segment
		(start 100.362766 -245.55069)
		(end 99.639374 -245.85803)
		(width 0.088646)
		(layer "In11.Cu")
		(net "M_D_CPU1_SB_CB<7>")
	)
	(segment
		(start 99.235768 -245.875048)
		(end 98.949764 -245.709694)
		(width 0.088646)
		(layer "In11.Cu")
		(net "M_D_CPU1_SB_CB<7>")
	)
	(segment
		(start 51.998626 -239.39119)
		(end 50.06213 -239.39119)
		(width 0.18288)
		(layer "In11.Cu")
		(net "M_D_CPU1_SB_CB<7>")
	)
	(segment
		(start 36.580826 -239.577626)
		(end 36.39439 -239.39119)
		(width 0.18288)
		(layer "In11.Cu")
		(net "M_D_CPU1_SB_CB<7>")
	)
	(segment
		(start 52.12207 -239.514634)
		(end 51.998626 -239.39119)
		(width 0.18288)
		(layer "In11.Cu")
		(net "M_D_CPU1_SB_CB<7>")
	)
	(segment
		(start 43.769026 -238.612426)
		(end 40.975026 -238.612426)
		(width 0.18288)
		(layer "In11.Cu")
		(net "M_D_CPU1_SB_CB<7>")
	)
	(segment
		(start 33.109916 -240.241074)
		(end 31.49092 -240.241074)
		(width 0.18288)
		(layer "In11.Cu")
		(net "M_D_CPU1_SB_CB<7>")
	)
	(segment
		(start 27.357578 -239.881156)
		(end 27.042618 -239.881156)
		(width 0.18288)
		(layer "In11.Cu")
		(net "M_D_CPU1_SB_CB<7>")
	)
	(segment
		(start 85.138768 -245.875048)
		(end 85.129878 -245.869968)
		(width 0.088646)
		(layer "In11.Cu")
		(net "M_D_CPU1_SB_CB<7>")
	)
	(segment
		(start 84.951316 -245.55069)
		(end 84.951316 -245.536466)
		(width 0.088646)
		(layer "In11.Cu")
		(net "M_D_CPU1_SB_CB<7>")
	)
	(segment
		(start 66.261996 -239.389412)
		(end 65.323212 -239.389412)
		(width 0.18288)
		(layer "In11.Cu")
		(net "M_D_CPU1_SB_CB<7>")
	)
	(segment
		(start 26.849578 -239.688116)
		(end 26.849578 -239.579912)
		(width 0.18288)
		(layer "In11.Cu")
		(net "M_D_CPU1_SB_CB<7>")
	)
	(segment
		(start 89.287096 -245.866412)
		(end 89.272364 -245.875048)
		(width 0.088646)
		(layer "In11.Cu")
		(net "M_D_CPU1_SB_CB<7>")
	)
	(segment
		(start 83.855052 -244.624352)
		(end 83.673696 -244.624352)
		(width 0.088646)
		(layer "In11.Cu")
		(net "M_D_CPU1_SB_CB<7>")
	)
	(segment
		(start 25.44318 -239.386872)
		(end 25.272746 -239.557306)
		(width 0.18288)
		(layer "In11.Cu")
		(net "M_D_CPU1_SB_CB<7>")
	)
	(segment
		(start 40.009826 -239.577626)
		(end 36.580826 -239.577626)
		(width 0.18288)
		(layer "In11.Cu")
		(net "M_D_CPU1_SB_CB<7>")
	)
	(segment
		(start 92.102178 -245.868952)
		(end 92.091764 -245.875048)
		(width 0.088646)
		(layer "In11.Cu")
		(net "M_D_CPU1_SB_CB<7>")
	)
	(segment
		(start 84.386166 -244.985286)
		(end 84.215986 -244.985286)
		(width 0.088646)
		(layer "In11.Cu")
		(net "M_D_CPU1_SB_CB<7>")
	)
	(segment
		(start 29.240226 -239.603026)
		(end 29.024072 -239.386872)
		(width 0.18288)
		(layer "In11.Cu")
		(net "M_D_CPU1_SB_CB<7>")
	)
	(segment
		(start 27.550618 -239.579912)
		(end 27.550618 -239.688116)
		(width 0.18288)
		(layer "In11.Cu")
		(net "M_D_CPU1_SB_CB<7>")
	)
	(segment
		(start 64.661288 -238.727488)
		(end 63.354712 -238.727488)
		(width 0.18288)
		(layer "In11.Cu")
		(net "M_D_CPU1_SB_CB<7>")
	)
	(segment
		(start 95.865696 -245.866412)
		(end 95.850964 -245.875048)
		(width 0.088646)
		(layer "In11.Cu")
		(net "M_D_CPU1_SB_CB<7>")
	)
	(segment
		(start 35.48761 -239.39119)
		(end 34.470594 -240.408206)
		(width 0.18288)
		(layer "In11.Cu")
		(net "M_D_CPU1_SB_CB<7>")
	)
	(segment
		(start 25.272746 -239.557306)
		(end 23.766018 -239.557306)
		(width 0.18288)
		(layer "In11.Cu")
		(net "M_D_CPU1_SB_CB<7>")
	)
	(segment
		(start 83.673696 -244.624352)
		(end 82.19948 -244.624352)
		(width 0.18288)
		(layer "In11.Cu")
		(net "M_D_CPU1_SB_CB<7>")
	)
	(segment
		(start 58.75401 -238.691674)
		(end 56.02986 -238.691674)
		(width 0.18288)
		(layer "In11.Cu")
		(net "M_D_CPU1_SB_CB<7>")
	)
	(segment
		(start 82.19948 -244.624352)
		(end 81.642458 -244.06733)
		(width 0.18288)
		(layer "In11.Cu")
		(net "M_D_CPU1_SB_CB<7>")
	)
	(segment
		(start 34.470594 -240.408206)
		(end 33.277048 -240.408206)
		(width 0.18288)
		(layer "In11.Cu")
		(net "M_D_CPU1_SB_CB<7>")
	)
	(segment
		(start 97.730564 -245.874794)
		(end 97.73031 -245.875048)
		(width 0.088646)
		(layer "In11.Cu")
		(net "M_D_CPU1_SB_CB<7>")
	)
	(segment
		(start 99.639374 -245.85803)
		(end 99.610164 -245.875048)
		(width 0.088646)
		(layer "In11.Cu")
		(net "M_D_CPU1_SB_CB<7>")
	)
	(segment
		(start 99.610164 -245.875048)
		(end 99.60991 -245.875048)
		(width 0.088646)
		(layer "In11.Cu")
		(net "M_D_CPU1_SB_CB<7>")
	)
	(segment
		(start 46.65472 -240.241074)
		(end 46.08068 -239.667034)
		(width 0.18288)
		(layer "In11.Cu")
		(net "M_D_CPU1_SB_CB<7>")
	)
	(segment
		(start 44.823634 -239.667034)
		(end 43.769026 -238.612426)
		(width 0.18288)
		(layer "In11.Cu")
		(net "M_D_CPU1_SB_CB<7>")
	)
	(segment
		(start 55.2069 -239.514634)
		(end 52.12207 -239.514634)
		(width 0.18288)
		(layer "In11.Cu")
		(net "M_D_CPU1_SB_CB<7>")
	)
	(segment
		(start 30.852872 -239.603026)
		(end 29.240226 -239.603026)
		(width 0.18288)
		(layer "In11.Cu")
		(net "M_D_CPU1_SB_CB<7>")
	)
	(segment
		(start 31.49092 -240.241074)
		(end 30.852872 -239.603026)
		(width 0.18288)
		(layer "In11.Cu")
		(net "M_D_CPU1_SB_CB<7>")
	)
	(segment
		(start 46.08068 -239.667034)
		(end 44.823634 -239.667034)
		(width 0.18288)
		(layer "In11.Cu")
		(net "M_D_CPU1_SB_CB<7>")
	)
	(segment
		(start 27.042618 -239.881156)
		(end 26.849578 -239.688116)
		(width 0.18288)
		(layer "In11.Cu")
		(net "M_D_CPU1_SB_CB<7>")
	)
	(segment
		(start 21.479764 -239.557306)
		(end 20.889214 -238.966756)
		(width 0.18288)
		(layer "In11.Cu")
		(net "M_D_CPU1_SB_CB<7>")
	)
	(segment
		(start 23.379938 -238.839248)
		(end 23.064978 -238.839248)
		(width 0.18288)
		(layer "In11.Cu")
		(net "M_D_CPU1_SB_CB<7>")
	)
	(segment
		(start 63.354712 -238.727488)
		(end 62.451488 -239.630712)
		(width 0.18288)
		(layer "In11.Cu")
		(net "M_D_CPU1_SB_CB<7>")
	)
	(segment
		(start 26.656538 -239.386872)
		(end 25.44318 -239.386872)
		(width 0.18288)
		(layer "In11.Cu")
		(net "M_D_CPU1_SB_CB<7>")
	)
	(segment
		(start 62.451488 -239.630712)
		(end 59.693048 -239.630712)
		(width 0.18288)
		(layer "In11.Cu")
		(net "M_D_CPU1_SB_CB<7>")
	)
	(segment
		(start 56.02986 -238.691674)
		(end 55.2069 -239.514634)
		(width 0.18288)
		(layer "In11.Cu")
		(net "M_D_CPU1_SB_CB<7>")
	)
	(segment
		(start 49.034192 -240.419128)
		(end 47.55388 -240.419128)
		(width 0.18288)
		(layer "In11.Cu")
		(net "M_D_CPU1_SB_CB<7>")
	)
	(segment
		(start 98.670364 -245.226332)
		(end 98.67011 -245.226332)
		(width 0.088646)
		(layer "In11.Cu")
		(net "M_D_CPU1_SB_CB<7>")
	)
	(segment
		(start 84.215986 -244.985286)
		(end 83.855052 -244.624352)
		(width 0.088646)
		(layer "In11.Cu")
		(net "M_D_CPU1_SB_CB<7>")
	)
	(segment
		(start 23.064978 -238.839248)
		(end 22.871938 -239.032288)
		(width 0.18288)
		(layer "In11.Cu")
		(net "M_D_CPU1_SB_CB<7>")
	)
	(segment
		(start 91.162124 -245.868952)
		(end 91.15171 -245.875048)
		(width 0.088646)
		(layer "In11.Cu")
		(net "M_D_CPU1_SB_CB<7>")
	)
	(segment
		(start 29.024072 -239.386872)
		(end 27.743658 -239.386872)
		(width 0.18288)
		(layer "In11.Cu")
		(net "M_D_CPU1_SB_CB<7>")
	)
	(segment
		(start 94.925896 -245.866412)
		(end 94.911164 -245.875048)
		(width 0.088646)
		(layer "In11.Cu")
		(net "M_D_CPU1_SB_CB<7>")
	)
	(segment
		(start 59.693048 -239.630712)
		(end 58.75401 -238.691674)
		(width 0.18288)
		(layer "In11.Cu")
		(net "M_D_CPU1_SB_CB<7>")
	)
	(segment
		(start 98.295968 -245.226332)
		(end 98.00971 -245.39194)
		(width 0.088646)
		(layer "In11.Cu")
		(net "M_D_CPU1_SB_CB<7>")
	)
	(segment
		(start 81.642458 -244.06733)
		(end 71.134478 -244.06733)
		(width 0.18288)
		(layer "In11.Cu")
		(net "M_D_CPU1_SB_CB<7>")
	)
	(segment
		(start 33.277048 -240.408206)
		(end 33.109916 -240.241074)
		(width 0.18288)
		(layer "In11.Cu")
		(net "M_D_CPU1_SB_CB<7>")
	)
	(segment
		(start 36.39439 -239.39119)
		(end 35.48761 -239.39119)
		(width 0.18288)
		(layer "In11.Cu")
		(net "M_D_CPU1_SB_CB<7>")
	)
	(segment
		(start 90.222578 -245.868952)
		(end 90.212164 -245.875048)
		(width 0.088646)
		(layer "In11.Cu")
		(net "M_D_CPU1_SB_CB<7>")
	)
	(segment
		(start 93.041724 -245.868952)
		(end 93.03131 -245.875048)
		(width 0.088646)
		(layer "In11.Cu")
		(net "M_D_CPU1_SB_CB<7>")
	)
	(segment
		(start 27.743658 -239.386872)
		(end 27.550618 -239.579912)
		(width 0.18288)
		(layer "In11.Cu")
		(net "M_D_CPU1_SB_CB<7>")
	)
	(segment
		(start 22.871938 -239.032288)
		(end 22.871938 -239.364266)
		(width 0.18288)
		(layer "In11.Cu")
		(net "M_D_CPU1_SB_CB<7>")
	)
	(segment
		(start 47.55388 -240.419128)
		(end 47.375826 -240.241074)
		(width 0.18288)
		(layer "In11.Cu")
		(net "M_D_CPU1_SB_CB<7>")
	)
	(segment
		(start 27.550618 -239.688116)
		(end 27.357578 -239.881156)
		(width 0.18288)
		(layer "In11.Cu")
		(net "M_D_CPU1_SB_CB<7>")
	)
	(segment
		(start 71.134478 -244.06733)
		(end 66.593974 -239.526826)
		(width 0.18288)
		(layer "In11.Cu")
		(net "M_D_CPU1_SB_CB<7>")
	)
	(arc
		(start 88.332564 -245.875048)
		(mid 88.145366 -245.925191)
		(end 87.958168 -245.875048)
		(width 0.088646)
		(layer "In11.Cu")
		(net "M_D_CPU1_SB_CB<7>")
	)
	(arc
		(start 92.091764 -245.875048)
		(mid 91.904566 -245.925191)
		(end 91.717368 -245.875048)
		(width 0.088646)
		(layer "In11.Cu")
		(net "M_D_CPU1_SB_CB<7>")
	)
	(arc
		(start 93.596968 -245.875048)
		(mid 93.320155 -245.799178)
		(end 93.041724 -245.868952)
		(width 0.088646)
		(layer "In11.Cu")
		(net "M_D_CPU1_SB_CB<7>")
	)
	(arc
		(start 95.476568 -245.875048)
		(mid 95.202369 -245.799213)
		(end 94.925896 -245.866412)
		(width 0.088646)
		(layer "In11.Cu")
		(net "M_D_CPU1_SB_CB<7>")
	)
	(arc
		(start 94.536768 -245.875048)
		(mid 94.254066 -245.799272)
		(end 93.971364 -245.875048)
		(width 0.088646)
		(layer "In11.Cu")
		(net "M_D_CPU1_SB_CB<7>")
	)
	(arc
		(start 90.212164 -245.875048)
		(mid 90.024966 -245.925191)
		(end 89.837768 -245.875048)
		(width 0.088646)
		(layer "In11.Cu")
		(net "M_D_CPU1_SB_CB<7>")
	)
	(arc
		(start 84.951316 -245.536466)
		(mid 84.872097 -245.261781)
		(end 84.668614 -245.060978)
		(width 0.088646)
		(layer "In11.Cu")
		(net "M_D_CPU1_SB_CB<7>")
	)
	(arc
		(start 98.00971 -245.39194)
		(mid 97.942444 -245.458988)
		(end 97.917762 -245.55069)
		(width 0.088646)
		(layer "In11.Cu")
		(net "M_D_CPU1_SB_CB<7>")
	)
	(arc
		(start 97.73031 -245.875048)
		(mid 97.543112 -245.925225)
		(end 97.355914 -245.875048)
		(width 0.088646)
		(layer "In11.Cu")
		(net "M_D_CPU1_SB_CB<7>")
	)
	(arc
		(start 93.03131 -245.875048)
		(mid 92.844112 -245.925191)
		(end 92.656914 -245.875048)
		(width 0.088646)
		(layer "In11.Cu")
		(net "M_D_CPU1_SB_CB<7>")
	)
	(arc
		(start 91.15171 -245.875048)
		(mid 90.964512 -245.925191)
		(end 90.777314 -245.875048)
		(width 0.088646)
		(layer "In11.Cu")
		(net "M_D_CPU1_SB_CB<7>")
	)
	(arc
		(start 87.958168 -245.875048)
		(mid 87.675466 -245.799272)
		(end 87.392764 -245.875048)
		(width 0.088646)
		(layer "In11.Cu")
		(net "M_D_CPU1_SB_CB<7>")
	)
	(arc
		(start 98.857816 -245.55069)
		(mid 98.807523 -245.363514)
		(end 98.670364 -245.226586)
		(width 0.088646)
		(layer "In11.Cu")
		(net "M_D_CPU1_SB_CB<7>")
	)
	(arc
		(start 89.837768 -245.875048)
		(mid 89.563569 -245.799213)
		(end 89.287096 -245.866412)
		(width 0.088646)
		(layer "In11.Cu")
		(net "M_D_CPU1_SB_CB<7>")
	)
	(arc
		(start 96.790764 -245.875048)
		(mid 96.603566 -245.925191)
		(end 96.416368 -245.875048)
		(width 0.088646)
		(layer "In11.Cu")
		(net "M_D_CPU1_SB_CB<7>")
	)
	(arc
		(start 90.777314 -245.875048)
		(mid 90.500755 -245.799305)
		(end 90.222578 -245.868952)
		(width 0.088646)
		(layer "In11.Cu")
		(net "M_D_CPU1_SB_CB<7>")
	)
	(arc
		(start 98.949764 -245.709694)
		(mid 98.882434 -245.642536)
		(end 98.857816 -245.55069)
		(width 0.088646)
		(layer "In11.Cu")
		(net "M_D_CPU1_SB_CB<7>")
	)
	(arc
		(start 98.67011 -245.226332)
		(mid 98.483056 -245.176282)
		(end 98.295968 -245.226332)
		(width 0.088646)
		(layer "In11.Cu")
		(net "M_D_CPU1_SB_CB<7>")
	)
	(arc
		(start 92.656914 -245.875048)
		(mid 92.380355 -245.799305)
		(end 92.102178 -245.868952)
		(width 0.088646)
		(layer "In11.Cu")
		(net "M_D_CPU1_SB_CB<7>")
	)
	(arc
		(start 86.452964 -245.875048)
		(mid 86.265766 -245.925191)
		(end 86.078568 -245.875048)
		(width 0.088646)
		(layer "In11.Cu")
		(net "M_D_CPU1_SB_CB<7>")
	)
	(arc
		(start 87.392764 -245.875048)
		(mid 87.205566 -245.925191)
		(end 87.018368 -245.875048)
		(width 0.088646)
		(layer "In11.Cu")
		(net "M_D_CPU1_SB_CB<7>")
	)
	(arc
		(start 93.971364 -245.875048)
		(mid 93.784166 -245.925191)
		(end 93.596968 -245.875048)
		(width 0.088646)
		(layer "In11.Cu")
		(net "M_D_CPU1_SB_CB<7>")
	)
	(arc
		(start 96.416368 -245.875048)
		(mid 96.142169 -245.799213)
		(end 95.865696 -245.866412)
		(width 0.088646)
		(layer "In11.Cu")
		(net "M_D_CPU1_SB_CB<7>")
	)
	(arc
		(start 86.078568 -245.875048)
		(mid 85.795866 -245.799272)
		(end 85.513164 -245.875048)
		(width 0.088646)
		(layer "In11.Cu")
		(net "M_D_CPU1_SB_CB<7>")
	)
	(arc
		(start 97.917762 -245.55069)
		(mid 97.867598 -245.737828)
		(end 97.730564 -245.874794)
		(width 0.088646)
		(layer "In11.Cu")
		(net "M_D_CPU1_SB_CB<7>")
	)
	(arc
		(start 87.018368 -245.875048)
		(mid 86.735666 -245.799272)
		(end 86.452964 -245.875048)
		(width 0.088646)
		(layer "In11.Cu")
		(net "M_D_CPU1_SB_CB<7>")
	)
	(arc
		(start 84.668614 -245.060978)
		(mid 84.532371 -245.004532)
		(end 84.386166 -244.985286)
		(width 0.088646)
		(layer "In11.Cu")
		(net "M_D_CPU1_SB_CB<7>")
	)
	(arc
		(start 85.513164 -245.875048)
		(mid 85.325966 -245.925191)
		(end 85.138768 -245.875048)
		(width 0.088646)
		(layer "In11.Cu")
		(net "M_D_CPU1_SB_CB<7>")
	)
	(arc
		(start 95.850964 -245.875048)
		(mid 95.663766 -245.925191)
		(end 95.476568 -245.875048)
		(width 0.088646)
		(layer "In11.Cu")
		(net "M_D_CPU1_SB_CB<7>")
	)
	(arc
		(start 88.897968 -245.875048)
		(mid 88.623769 -245.799213)
		(end 88.347296 -245.866412)
		(width 0.088646)
		(layer "In11.Cu")
		(net "M_D_CPU1_SB_CB<7>")
	)
	(arc
		(start 91.717368 -245.875048)
		(mid 91.440555 -245.799178)
		(end 91.162124 -245.868952)
		(width 0.088646)
		(layer "In11.Cu")
		(net "M_D_CPU1_SB_CB<7>")
	)
	(arc
		(start 94.911164 -245.875048)
		(mid 94.723966 -245.925191)
		(end 94.536768 -245.875048)
		(width 0.088646)
		(layer "In11.Cu")
		(net "M_D_CPU1_SB_CB<7>")
	)
	(arc
		(start 85.129878 -245.869968)
		(mid 84.998964 -245.733608)
		(end 84.951316 -245.55069)
		(width 0.088646)
		(layer "In11.Cu")
		(net "M_D_CPU1_SB_CB<7>")
	)
	(arc
		(start 99.60991 -245.875048)
		(mid 99.422856 -245.925098)
		(end 99.235768 -245.875048)
		(width 0.088646)
		(layer "In11.Cu")
		(net "M_D_CPU1_SB_CB<7>")
	)
	(arc
		(start 89.272364 -245.875048)
		(mid 89.085166 -245.925191)
		(end 88.897968 -245.875048)
		(width 0.088646)
		(layer "In11.Cu")
		(net "M_D_CPU1_SB_CB<7>")
	)
	(arc
		(start 97.355914 -245.875048)
		(mid 97.079355 -245.799305)
		(end 96.801178 -245.868952)
		(width 0.088646)
		(layer "In11.Cu")
		(net "M_D_CPU1_SB_CB<7>")
	)
	(segment
		(start 17.66189 -240.3856)
		(end 17.66189 -240.711228)
		(width 0.20066)
		(layer "F.Cu")
		(net "M_D_CPU1_SB_CB<6>")
	)
	(segment
		(start 20.889214 -240.666778)
		(end 19.784314 -240.666778)
		(width 0.20066)
		(layer "F.Cu")
		(net "M_D_CPU1_SB_CB<6>")
	)
	(segment
		(start 16.885158 -240.241836)
		(end 17.518126 -240.241836)
		(width 0.20066)
		(layer "F.Cu")
		(net "M_D_CPU1_SB_CB<6>")
	)
	(segment
		(start 12.240514 -240.666778)
		(end 13.387578 -240.666778)
		(width 0.20066)
		(layer "F.Cu")
		(net "M_D_CPU1_SB_CB<6>")
	)
	(segment
		(start 18.257774 -240.878614)
		(end 18.46961 -240.666778)
		(width 0.20066)
		(layer "F.Cu")
		(net "M_D_CPU1_SB_CB<6>")
	)
	(segment
		(start 17.66189 -240.711228)
		(end 17.829276 -240.878614)
		(width 0.20066)
		(layer "F.Cu")
		(net "M_D_CPU1_SB_CB<6>")
	)
	(segment
		(start 99.892866 -246.900446)
		(end 99.892612 -246.900192)
		(width 0.20066)
		(layer "F.Cu")
		(net "M_D_CPU1_SB_CB<6>")
	)
	(segment
		(start 14.570202 -240.241836)
		(end 14.825218 -240.241836)
		(width 0.101854)
		(layer "F.Cu")
		(net "M_D_CPU1_SB_CB<6>")
	)
	(segment
		(start 17.518126 -240.241836)
		(end 17.66189 -240.3856)
		(width 0.20066)
		(layer "F.Cu")
		(net "M_D_CPU1_SB_CB<6>")
	)
	(segment
		(start 13.387578 -240.666778)
		(end 13.82268 -240.231676)
		(width 0.20066)
		(layer "F.Cu")
		(net "M_D_CPU1_SB_CB<6>")
	)
	(segment
		(start 99.892612 -246.900192)
		(end 99.892612 -246.364506)
		(width 0.20066)
		(layer "F.Cu")
		(net "M_D_CPU1_SB_CB<6>")
	)
	(segment
		(start 14.560042 -240.231676)
		(end 14.570202 -240.241836)
		(width 0.101854)
		(layer "F.Cu")
		(net "M_D_CPU1_SB_CB<6>")
	)
	(segment
		(start 18.46961 -240.666778)
		(end 19.784314 -240.666778)
		(width 0.20066)
		(layer "F.Cu")
		(net "M_D_CPU1_SB_CB<6>")
	)
	(segment
		(start 14.825218 -240.241836)
		(end 16.885158 -240.241836)
		(width 0.1016)
		(layer "F.Cu")
		(net "M_D_CPU1_SB_CB<6>")
	)
	(segment
		(start 13.82268 -240.231676)
		(end 14.560042 -240.231676)
		(width 0.20066)
		(layer "F.Cu")
		(net "M_D_CPU1_SB_CB<6>")
	)
	(segment
		(start 17.829276 -240.878614)
		(end 18.257774 -240.878614)
		(width 0.20066)
		(layer "F.Cu")
		(net "M_D_CPU1_SB_CB<6>")
	)
	(segment
		(start 42.327068 -239.672876)
		(end 42.134028 -239.865916)
		(width 0.18288)
		(layer "In11.Cu")
		(net "M_D_CPU1_SB_CB<6>")
	)
	(segment
		(start 70.450456 -245.08333)
		(end 66.189352 -240.822226)
		(width 0.18288)
		(layer "In11.Cu")
		(net "M_D_CPU1_SB_CB<6>")
	)
	(segment
		(start 94.066868 -246.688864)
		(end 94.056454 -246.682768)
		(width 0.088646)
		(layer "In11.Cu")
		(net "M_D_CPU1_SB_CB<6>")
	)
	(segment
		(start 89.367614 -246.688864)
		(end 89.352882 -246.680228)
		(width 0.088646)
		(layer "In11.Cu")
		(net "M_D_CPU1_SB_CB<6>")
	)
	(segment
		(start 59.814968 -241.27841)
		(end 58.921142 -240.384584)
		(width 0.18288)
		(layer "In11.Cu")
		(net "M_D_CPU1_SB_CB<6>")
	)
	(segment
		(start 55.007256 -241.313716)
		(end 53.940456 -241.313716)
		(width 0.18288)
		(layer "In11.Cu")
		(net "M_D_CPU1_SB_CB<6>")
	)
	(segment
		(start 41.940988 -240.427256)
		(end 41.451276 -240.427256)
		(width 0.18288)
		(layer "In11.Cu")
		(net "M_D_CPU1_SB_CB<6>")
	)
	(segment
		(start 38.751002 -240.989866)
		(end 38.751002 -240.83772)
		(width 0.18288)
		(layer "In11.Cu")
		(net "M_D_CPU1_SB_CB<6>")
	)
	(segment
		(start 66.189352 -240.822226)
		(end 64.793622 -240.822226)
		(width 0.18288)
		(layer "In11.Cu")
		(net "M_D_CPU1_SB_CB<6>")
	)
	(segment
		(start 23.521416 -241.031776)
		(end 23.521416 -240.775998)
		(width 0.18288)
		(layer "In11.Cu")
		(net "M_D_CPU1_SB_CB<6>")
	)
	(segment
		(start 99.544378 -246.165878)
		(end 99.282758 -246.098568)
		(width 0.088646)
		(layer "In11.Cu")
		(net "M_D_CPU1_SB_CB<6>")
	)
	(segment
		(start 42.642028 -239.672876)
		(end 42.327068 -239.672876)
		(width 0.18288)
		(layer "In11.Cu")
		(net "M_D_CPU1_SB_CB<6>")
	)
	(segment
		(start 25.557226 -241.000026)
		(end 25.332436 -241.224816)
		(width 0.18288)
		(layer "In11.Cu")
		(net "M_D_CPU1_SB_CB<6>")
	)
	(segment
		(start 43.028108 -240.427256)
		(end 42.835068 -240.234216)
		(width 0.18288)
		(layer "In11.Cu")
		(net "M_D_CPU1_SB_CB<6>")
	)
	(segment
		(start 95.946214 -246.688864)
		(end 95.931482 -246.680228)
		(width 0.088646)
		(layer "In11.Cu")
		(net "M_D_CPU1_SB_CB<6>")
	)
	(segment
		(start 30.952694 -241.254026)
		(end 29.418026 -241.254026)
		(width 0.18288)
		(layer "In11.Cu")
		(net "M_D_CPU1_SB_CB<6>")
	)
	(segment
		(start 63.440818 -240.254282)
		(end 62.41669 -241.27841)
		(width 0.18288)
		(layer "In11.Cu")
		(net "M_D_CPU1_SB_CB<6>")
	)
	(segment
		(start 22.820376 -240.775998)
		(end 22.820376 -241.031776)
		(width 0.18288)
		(layer "In11.Cu")
		(net "M_D_CPU1_SB_CB<6>")
	)
	(segment
		(start 88.427814 -246.688864)
		(end 88.4174 -246.682768)
		(width 0.088646)
		(layer "In11.Cu")
		(net "M_D_CPU1_SB_CB<6>")
	)
	(segment
		(start 38.049962 -240.989866)
		(end 37.856922 -241.182906)
		(width 0.18288)
		(layer "In11.Cu")
		(net "M_D_CPU1_SB_CB<6>")
	)
	(segment
		(start 81.080356 -245.08333)
		(end 70.450456 -245.08333)
		(width 0.18288)
		(layer "In11.Cu")
		(net "M_D_CPU1_SB_CB<6>")
	)
	(segment
		(start 38.243002 -240.64468)
		(end 38.049962 -240.83772)
		(width 0.18288)
		(layer "In11.Cu")
		(net "M_D_CPU1_SB_CB<6>")
	)
	(segment
		(start 53.239416 -240.643664)
		(end 53.046376 -240.836704)
		(width 0.18288)
		(layer "In11.Cu")
		(net "M_D_CPU1_SB_CB<6>")
	)
	(segment
		(start 23.714456 -241.224816)
		(end 23.521416 -241.031776)
		(width 0.18288)
		(layer "In11.Cu")
		(net "M_D_CPU1_SB_CB<6>")
	)
	(segment
		(start 23.328376 -240.582958)
		(end 23.013416 -240.582958)
		(width 0.18288)
		(layer "In11.Cu")
		(net "M_D_CPU1_SB_CB<6>")
	)
	(segment
		(start 62.41669 -241.27841)
		(end 59.814968 -241.27841)
		(width 0.18288)
		(layer "In11.Cu")
		(net "M_D_CPU1_SB_CB<6>")
	)
	(segment
		(start 29.164026 -241.000026)
		(end 25.557226 -241.000026)
		(width 0.18288)
		(layer "In11.Cu")
		(net "M_D_CPU1_SB_CB<6>")
	)
	(segment
		(start 29.418026 -241.254026)
		(end 29.164026 -241.000026)
		(width 0.18288)
		(layer "In11.Cu")
		(net "M_D_CPU1_SB_CB<6>")
	)
	(segment
		(start 53.554376 -240.643664)
		(end 53.239416 -240.643664)
		(width 0.18288)
		(layer "In11.Cu")
		(net "M_D_CPU1_SB_CB<6>")
	)
	(segment
		(start 51.85537 -241.313716)
		(end 51.632866 -241.091212)
		(width 0.18288)
		(layer "In11.Cu")
		(net "M_D_CPU1_SB_CB<6>")
	)
	(segment
		(start 22.627336 -241.224816)
		(end 21.447252 -241.224816)
		(width 0.18288)
		(layer "In11.Cu")
		(net "M_D_CPU1_SB_CB<6>")
	)
	(segment
		(start 46.703996 -241.941096)
		(end 46.005242 -241.242342)
		(width 0.18288)
		(layer "In11.Cu")
		(net "M_D_CPU1_SB_CB<6>")
	)
	(segment
		(start 35.431984 -241.091212)
		(end 34.442146 -242.08105)
		(width 0.18288)
		(layer "In11.Cu")
		(net "M_D_CPU1_SB_CB<6>")
	)
	(segment
		(start 53.046376 -241.120676)
		(end 52.853336 -241.313716)
		(width 0.18288)
		(layer "In11.Cu")
		(net "M_D_CPU1_SB_CB<6>")
	)
	(segment
		(start 46.005242 -241.242342)
		(end 44.671488 -241.242342)
		(width 0.18288)
		(layer "In11.Cu")
		(net "M_D_CPU1_SB_CB<6>")
	)
	(segment
		(start 38.944042 -241.182906)
		(end 38.751002 -240.989866)
		(width 0.18288)
		(layer "In11.Cu")
		(net "M_D_CPU1_SB_CB<6>")
	)
	(segment
		(start 36.69792 -241.182906)
		(end 36.606226 -241.091212)
		(width 0.18288)
		(layer "In11.Cu")
		(net "M_D_CPU1_SB_CB<6>")
	)
	(segment
		(start 40.695626 -241.182906)
		(end 38.944042 -241.182906)
		(width 0.18288)
		(layer "In11.Cu")
		(net "M_D_CPU1_SB_CB<6>")
	)
	(segment
		(start 32.848042 -242.08105)
		(end 32.708342 -241.94135)
		(width 0.18288)
		(layer "In11.Cu")
		(net "M_D_CPU1_SB_CB<6>")
	)
	(segment
		(start 36.606226 -241.091212)
		(end 35.431984 -241.091212)
		(width 0.18288)
		(layer "In11.Cu")
		(net "M_D_CPU1_SB_CB<6>")
	)
	(segment
		(start 53.747416 -241.120676)
		(end 53.747416 -240.836704)
		(width 0.18288)
		(layer "In11.Cu")
		(net "M_D_CPU1_SB_CB<6>")
	)
	(segment
		(start 93.126814 -246.688864)
		(end 93.112082 -246.680228)
		(width 0.088646)
		(layer "In11.Cu")
		(net "M_D_CPU1_SB_CB<6>")
	)
	(segment
		(start 38.557962 -240.64468)
		(end 38.243002 -240.64468)
		(width 0.18288)
		(layer "In11.Cu")
		(net "M_D_CPU1_SB_CB<6>")
	)
	(segment
		(start 37.856922 -241.182906)
		(end 36.69792 -241.182906)
		(width 0.18288)
		(layer "In11.Cu")
		(net "M_D_CPU1_SB_CB<6>")
	)
	(segment
		(start 53.046376 -240.836704)
		(end 53.046376 -241.120676)
		(width 0.18288)
		(layer "In11.Cu")
		(net "M_D_CPU1_SB_CB<6>")
	)
	(segment
		(start 85.325966 -246.613172)
		(end 85.072728 -246.613172)
		(width 0.088646)
		(layer "In11.Cu")
		(net "M_D_CPU1_SB_CB<6>")
	)
	(segment
		(start 22.820376 -241.031776)
		(end 22.627336 -241.224816)
		(width 0.18288)
		(layer "In11.Cu")
		(net "M_D_CPU1_SB_CB<6>")
	)
	(segment
		(start 25.332436 -241.224816)
		(end 23.714456 -241.224816)
		(width 0.18288)
		(layer "In11.Cu")
		(net "M_D_CPU1_SB_CB<6>")
	)
	(segment
		(start 95.006414 -246.688864)
		(end 94.996 -246.682768)
		(width 0.088646)
		(layer "In11.Cu")
		(net "M_D_CPU1_SB_CB<6>")
	)
	(segment
		(start 91.247214 -246.688864)
		(end 91.232482 -246.680228)
		(width 0.088646)
		(layer "In11.Cu")
		(net "M_D_CPU1_SB_CB<6>")
	)
	(segment
		(start 53.747416 -240.836704)
		(end 53.554376 -240.643664)
		(width 0.18288)
		(layer "In11.Cu")
		(net "M_D_CPU1_SB_CB<6>")
	)
	(segment
		(start 23.013416 -240.582958)
		(end 22.820376 -240.775998)
		(width 0.18288)
		(layer "In11.Cu")
		(net "M_D_CPU1_SB_CB<6>")
	)
	(segment
		(start 42.134028 -239.865916)
		(end 42.134028 -240.234216)
		(width 0.18288)
		(layer "In11.Cu")
		(net "M_D_CPU1_SB_CB<6>")
	)
	(segment
		(start 85.072728 -246.613172)
		(end 84.104734 -245.645178)
		(width 0.088646)
		(layer "In11.Cu")
		(net "M_D_CPU1_SB_CB<6>")
	)
	(segment
		(start 84.104734 -245.645178)
		(end 83.67395 -245.645178)
		(width 0.088646)
		(layer "In11.Cu")
		(net "M_D_CPU1_SB_CB<6>")
	)
	(segment
		(start 44.671488 -241.242342)
		(end 43.856402 -240.427256)
		(width 0.18288)
		(layer "In11.Cu")
		(net "M_D_CPU1_SB_CB<6>")
	)
	(segment
		(start 97.825814 -246.688864)
		(end 97.811082 -246.680228)
		(width 0.088646)
		(layer "In11.Cu")
		(net "M_D_CPU1_SB_CB<6>")
	)
	(segment
		(start 98.765614 -246.040148)
		(end 98.64852 -246.107204)
		(width 0.088646)
		(layer "In11.Cu")
		(net "M_D_CPU1_SB_CB<6>")
	)
	(segment
		(start 53.940456 -241.313716)
		(end 53.747416 -241.120676)
		(width 0.18288)
		(layer "In11.Cu")
		(net "M_D_CPU1_SB_CB<6>")
	)
	(segment
		(start 58.921142 -240.384584)
		(end 55.936388 -240.384584)
		(width 0.18288)
		(layer "In11.Cu")
		(net "M_D_CPU1_SB_CB<6>")
	)
	(segment
		(start 98.477578 -246.438674)
		(end 98.31705 -246.599202)
		(width 0.088646)
		(layer "In11.Cu")
		(net "M_D_CPU1_SB_CB<6>")
	)
	(segment
		(start 83.67395 -245.645178)
		(end 81.642204 -245.645178)
		(width 0.18288)
		(layer "In11.Cu")
		(net "M_D_CPU1_SB_CB<6>")
	)
	(segment
		(start 38.049962 -240.83772)
		(end 38.049962 -240.989866)
		(width 0.18288)
		(layer "In11.Cu")
		(net "M_D_CPU1_SB_CB<6>")
	)
	(segment
		(start 23.521416 -240.775998)
		(end 23.328376 -240.582958)
		(width 0.18288)
		(layer "In11.Cu")
		(net "M_D_CPU1_SB_CB<6>")
	)
	(segment
		(start 42.835068 -239.865916)
		(end 42.642028 -239.672876)
		(width 0.18288)
		(layer "In11.Cu")
		(net "M_D_CPU1_SB_CB<6>")
	)
	(segment
		(start 42.835068 -240.234216)
		(end 42.835068 -239.865916)
		(width 0.18288)
		(layer "In11.Cu")
		(net "M_D_CPU1_SB_CB<6>")
	)
	(segment
		(start 47.285402 -241.941096)
		(end 46.703996 -241.941096)
		(width 0.18288)
		(layer "In11.Cu")
		(net "M_D_CPU1_SB_CB<6>")
	)
	(segment
		(start 52.853336 -241.313716)
		(end 51.85537 -241.313716)
		(width 0.18288)
		(layer "In11.Cu")
		(net "M_D_CPU1_SB_CB<6>")
	)
	(segment
		(start 38.751002 -240.83772)
		(end 38.557962 -240.64468)
		(width 0.18288)
		(layer "In11.Cu")
		(net "M_D_CPU1_SB_CB<6>")
	)
	(segment
		(start 81.642204 -245.645178)
		(end 81.080356 -245.08333)
		(width 0.18288)
		(layer "In11.Cu")
		(net "M_D_CPU1_SB_CB<6>")
	)
	(segment
		(start 64.225678 -240.254282)
		(end 63.440818 -240.254282)
		(width 0.18288)
		(layer "In11.Cu")
		(net "M_D_CPU1_SB_CB<6>")
	)
	(segment
		(start 64.793622 -240.822226)
		(end 64.225678 -240.254282)
		(width 0.18288)
		(layer "In11.Cu")
		(net "M_D_CPU1_SB_CB<6>")
	)
	(segment
		(start 49.311052 -242.168172)
		(end 47.512478 -242.168172)
		(width 0.18288)
		(layer "In11.Cu")
		(net "M_D_CPU1_SB_CB<6>")
	)
	(segment
		(start 43.856402 -240.427256)
		(end 43.028108 -240.427256)
		(width 0.18288)
		(layer "In11.Cu")
		(net "M_D_CPU1_SB_CB<6>")
	)
	(segment
		(start 51.632866 -241.091212)
		(end 50.388012 -241.091212)
		(width 0.18288)
		(layer "In11.Cu")
		(net "M_D_CPU1_SB_CB<6>")
	)
	(segment
		(start 47.512478 -242.168172)
		(end 47.285402 -241.941096)
		(width 0.18288)
		(layer "In11.Cu")
		(net "M_D_CPU1_SB_CB<6>")
	)
	(segment
		(start 42.134028 -240.234216)
		(end 41.940988 -240.427256)
		(width 0.18288)
		(layer "In11.Cu")
		(net "M_D_CPU1_SB_CB<6>")
	)
	(segment
		(start 31.640018 -241.94135)
		(end 30.952694 -241.254026)
		(width 0.18288)
		(layer "In11.Cu")
		(net "M_D_CPU1_SB_CB<6>")
	)
	(segment
		(start 21.447252 -241.224816)
		(end 20.889214 -240.666778)
		(width 0.18288)
		(layer "In11.Cu")
		(net "M_D_CPU1_SB_CB<6>")
	)
	(segment
		(start 50.388012 -241.091212)
		(end 49.311052 -242.168172)
		(width 0.18288)
		(layer "In11.Cu")
		(net "M_D_CPU1_SB_CB<6>")
	)
	(segment
		(start 32.708342 -241.94135)
		(end 31.640018 -241.94135)
		(width 0.18288)
		(layer "In11.Cu")
		(net "M_D_CPU1_SB_CB<6>")
	)
	(segment
		(start 34.442146 -242.08105)
		(end 32.848042 -242.08105)
		(width 0.18288)
		(layer "In11.Cu")
		(net "M_D_CPU1_SB_CB<6>")
	)
	(segment
		(start 55.936388 -240.384584)
		(end 55.007256 -241.313716)
		(width 0.18288)
		(layer "In11.Cu")
		(net "M_D_CPU1_SB_CB<6>")
	)
	(segment
		(start 41.451276 -240.427256)
		(end 40.695626 -241.182906)
		(width 0.18288)
		(layer "In11.Cu")
		(net "M_D_CPU1_SB_CB<6>")
	)
	(arc
		(start 86.548468 -246.688864)
		(mid 86.265766 -246.613088)
		(end 85.983064 -246.688864)
		(width 0.088646)
		(layer "In11.Cu")
		(net "M_D_CPU1_SB_CB<6>")
	)
	(arc
		(start 96.886014 -246.688864)
		(mid 96.603312 -246.613088)
		(end 96.32061 -246.688864)
		(width 0.088646)
		(layer "In11.Cu")
		(net "M_D_CPU1_SB_CB<6>")
	)
	(arc
		(start 91.232482 -246.680228)
		(mid 90.956007 -246.612908)
		(end 90.68181 -246.688864)
		(width 0.088646)
		(layer "In11.Cu")
		(net "M_D_CPU1_SB_CB<6>")
	)
	(arc
		(start 93.112082 -246.680228)
		(mid 92.835607 -246.612908)
		(end 92.56141 -246.688864)
		(width 0.088646)
		(layer "In11.Cu")
		(net "M_D_CPU1_SB_CB<6>")
	)
	(arc
		(start 99.14001 -246.040148)
		(mid 98.952812 -245.990005)
		(end 98.765614 -246.040148)
		(width 0.088646)
		(layer "In11.Cu")
		(net "M_D_CPU1_SB_CB<6>")
	)
	(arc
		(start 85.608668 -246.688864)
		(mid 85.472299 -246.632422)
		(end 85.325966 -246.613172)
		(width 0.088646)
		(layer "In11.Cu")
		(net "M_D_CPU1_SB_CB<6>")
	)
	(arc
		(start 87.862664 -246.688864)
		(mid 87.675466 -246.739007)
		(end 87.488268 -246.688864)
		(width 0.088646)
		(layer "In11.Cu")
		(net "M_D_CPU1_SB_CB<6>")
	)
	(arc
		(start 88.80221 -246.688864)
		(mid 88.615012 -246.739007)
		(end 88.427814 -246.688864)
		(width 0.088646)
		(layer "In11.Cu")
		(net "M_D_CPU1_SB_CB<6>")
	)
	(arc
		(start 90.68181 -246.688864)
		(mid 90.494612 -246.739007)
		(end 90.307414 -246.688864)
		(width 0.088646)
		(layer "In11.Cu")
		(net "M_D_CPU1_SB_CB<6>")
	)
	(arc
		(start 96.32061 -246.688864)
		(mid 96.133412 -246.739007)
		(end 95.946214 -246.688864)
		(width 0.088646)
		(layer "In11.Cu")
		(net "M_D_CPU1_SB_CB<6>")
	)
	(arc
		(start 92.187014 -246.688864)
		(mid 91.904312 -246.613088)
		(end 91.62161 -246.688864)
		(width 0.088646)
		(layer "In11.Cu")
		(net "M_D_CPU1_SB_CB<6>")
	)
	(arc
		(start 93.50121 -246.688864)
		(mid 93.314012 -246.739007)
		(end 93.126814 -246.688864)
		(width 0.088646)
		(layer "In11.Cu")
		(net "M_D_CPU1_SB_CB<6>")
	)
	(arc
		(start 87.488268 -246.688864)
		(mid 87.205566 -246.613088)
		(end 86.922864 -246.688864)
		(width 0.088646)
		(layer "In11.Cu")
		(net "M_D_CPU1_SB_CB<6>")
	)
	(arc
		(start 90.307414 -246.688864)
		(mid 90.024712 -246.613088)
		(end 89.74201 -246.688864)
		(width 0.088646)
		(layer "In11.Cu")
		(net "M_D_CPU1_SB_CB<6>")
	)
	(arc
		(start 85.983064 -246.688864)
		(mid 85.795866 -246.739007)
		(end 85.608668 -246.688864)
		(width 0.088646)
		(layer "In11.Cu")
		(net "M_D_CPU1_SB_CB<6>")
	)
	(arc
		(start 97.811082 -246.680228)
		(mid 97.534607 -246.612908)
		(end 97.26041 -246.688864)
		(width 0.088646)
		(layer "In11.Cu")
		(net "M_D_CPU1_SB_CB<6>")
	)
	(arc
		(start 92.56141 -246.688864)
		(mid 92.374212 -246.739007)
		(end 92.187014 -246.688864)
		(width 0.088646)
		(layer "In11.Cu")
		(net "M_D_CPU1_SB_CB<6>")
	)
	(arc
		(start 98.64852 -246.107204)
		(mid 98.562861 -246.192159)
		(end 98.531426 -246.308626)
		(width 0.088646)
		(layer "In11.Cu")
		(net "M_D_CPU1_SB_CB<6>")
	)
	(arc
		(start 94.996 -246.682768)
		(mid 94.717822 -246.613045)
		(end 94.441264 -246.688864)
		(width 0.088646)
		(layer "In11.Cu")
		(net "M_D_CPU1_SB_CB<6>")
	)
	(arc
		(start 89.74201 -246.688864)
		(mid 89.554812 -246.739007)
		(end 89.367614 -246.688864)
		(width 0.088646)
		(layer "In11.Cu")
		(net "M_D_CPU1_SB_CB<6>")
	)
	(arc
		(start 94.441264 -246.688864)
		(mid 94.254066 -246.739007)
		(end 94.066868 -246.688864)
		(width 0.088646)
		(layer "In11.Cu")
		(net "M_D_CPU1_SB_CB<6>")
	)
	(arc
		(start 95.931482 -246.680228)
		(mid 95.655007 -246.612908)
		(end 95.38081 -246.688864)
		(width 0.088646)
		(layer "In11.Cu")
		(net "M_D_CPU1_SB_CB<6>")
	)
	(arc
		(start 97.26041 -246.688864)
		(mid 97.073212 -246.739007)
		(end 96.886014 -246.688864)
		(width 0.088646)
		(layer "In11.Cu")
		(net "M_D_CPU1_SB_CB<6>")
	)
	(arc
		(start 98.20021 -246.688864)
		(mid 98.013012 -246.739007)
		(end 97.825814 -246.688864)
		(width 0.088646)
		(layer "In11.Cu")
		(net "M_D_CPU1_SB_CB<6>")
	)
	(arc
		(start 88.4174 -246.682768)
		(mid 88.139222 -246.613045)
		(end 87.862664 -246.688864)
		(width 0.088646)
		(layer "In11.Cu")
		(net "M_D_CPU1_SB_CB<6>")
	)
	(arc
		(start 89.352882 -246.680228)
		(mid 89.076407 -246.612908)
		(end 88.80221 -246.688864)
		(width 0.088646)
		(layer "In11.Cu")
		(net "M_D_CPU1_SB_CB<6>")
	)
	(arc
		(start 94.056454 -246.682768)
		(mid 93.778022 -246.612922)
		(end 93.50121 -246.688864)
		(width 0.088646)
		(layer "In11.Cu")
		(net "M_D_CPU1_SB_CB<6>")
	)
	(arc
		(start 98.531426 -246.308626)
		(mid 98.517428 -246.379)
		(end 98.477578 -246.438674)
		(width 0.088646)
		(layer "In11.Cu")
		(net "M_D_CPU1_SB_CB<6>")
	)
	(arc
		(start 95.38081 -246.688864)
		(mid 95.193612 -246.739007)
		(end 95.006414 -246.688864)
		(width 0.088646)
		(layer "In11.Cu")
		(net "M_D_CPU1_SB_CB<6>")
	)
	(arc
		(start 91.62161 -246.688864)
		(mid 91.434412 -246.739007)
		(end 91.247214 -246.688864)
		(width 0.088646)
		(layer "In11.Cu")
		(net "M_D_CPU1_SB_CB<6>")
	)
	(arc
		(start 98.31705 -246.599202)
		(mid 98.261577 -246.647874)
		(end 98.20021 -246.688864)
		(width 0.088646)
		(layer "In11.Cu")
		(net "M_D_CPU1_SB_CB<6>")
	)
	(arc
		(start 86.922864 -246.688864)
		(mid 86.735666 -246.739007)
		(end 86.548468 -246.688864)
		(width 0.088646)
		(layer "In11.Cu")
		(net "M_D_CPU1_SB_CB<6>")
	)
	(arc
		(start 99.282758 -246.098568)
		(mid 99.209379 -246.074257)
		(end 99.14001 -246.040148)
		(width 0.088646)
		(layer "In11.Cu")
		(net "M_D_CPU1_SB_CB<6>")
	)
	(arc
		(start 99.892612 -246.364506)
		(mid 99.731822 -246.241827)
		(end 99.544378 -246.165878)
		(width 0.088646)
		(layer "In11.Cu")
		(net "M_D_CPU1_SB_CB<6>")
	)
	(segment
		(start 10.344912 -239.545368)
		(end 10.507472 -239.382808)
		(width 0.20066)
		(layer "F.Cu")
		(net "M_D_CPU1_SB_CB<5>")
	)
	(segment
		(start 10.19048 -240.027968)
		(end 10.344912 -239.873536)
		(width 0.20066)
		(layer "F.Cu")
		(net "M_D_CPU1_SB_CB<5>")
	)
	(segment
		(start 11.11631 -239.382808)
		(end 11.1252 -239.391698)
		(width 0.1016)
		(layer "F.Cu")
		(net "M_D_CPU1_SB_CB<5>")
	)
	(segment
		(start 11.1252 -239.391698)
		(end 13.110718 -239.391698)
		(width 0.1016)
		(layer "F.Cu")
		(net "M_D_CPU1_SB_CB<5>")
	)
	(segment
		(start 98.482912 -246.08663)
		(end 98.483166 -246.086376)
		(width 0.20066)
		(layer "F.Cu")
		(net "M_D_CPU1_SB_CB<5>")
	)
	(segment
		(start 13.110718 -239.391698)
		(end 13.441426 -239.391698)
		(width 0.101854)
		(layer "F.Cu")
		(net "M_D_CPU1_SB_CB<5>")
	)
	(segment
		(start 10.344912 -239.873536)
		(end 10.344912 -239.545368)
		(width 0.20066)
		(layer "F.Cu")
		(net "M_D_CPU1_SB_CB<5>")
	)
	(segment
		(start 13.619988 -239.391698)
		(end 14.04493 -239.81664)
		(width 0.20066)
		(layer "F.Cu")
		(net "M_D_CPU1_SB_CB<5>")
	)
	(segment
		(start 9.474708 -239.81664)
		(end 9.686036 -240.027968)
		(width 0.20066)
		(layer "F.Cu")
		(net "M_D_CPU1_SB_CB<5>")
	)
	(segment
		(start 8.140446 -239.81664)
		(end 9.474708 -239.81664)
		(width 0.20066)
		(layer "F.Cu")
		(net "M_D_CPU1_SB_CB<5>")
	)
	(segment
		(start 98.483166 -246.086376)
		(end 98.483166 -245.55069)
		(width 0.20066)
		(layer "F.Cu")
		(net "M_D_CPU1_SB_CB<5>")
	)
	(segment
		(start 16.789146 -239.81664)
		(end 15.684246 -239.81664)
		(width 0.20066)
		(layer "F.Cu")
		(net "M_D_CPU1_SB_CB<5>")
	)
	(segment
		(start 10.507472 -239.382808)
		(end 11.11631 -239.382808)
		(width 0.20066)
		(layer "F.Cu")
		(net "M_D_CPU1_SB_CB<5>")
	)
	(segment
		(start 13.441426 -239.391698)
		(end 13.619988 -239.391698)
		(width 0.20066)
		(layer "F.Cu")
		(net "M_D_CPU1_SB_CB<5>")
	)
	(segment
		(start 14.04493 -239.81664)
		(end 15.684246 -239.81664)
		(width 0.20066)
		(layer "F.Cu")
		(net "M_D_CPU1_SB_CB<5>")
	)
	(segment
		(start 9.686036 -240.027968)
		(end 10.19048 -240.027968)
		(width 0.20066)
		(layer "F.Cu")
		(net "M_D_CPU1_SB_CB<5>")
	)
	(segment
		(start 36.323778 -240.241074)
		(end 35.458146 -240.241074)
		(width 0.18288)
		(layer "In11.Cu")
		(net "M_D_CPU1_SB_CB<5>")
	)
	(segment
		(start 32.624776 -241.091212)
		(end 31.528766 -241.091212)
		(width 0.18288)
		(layer "In11.Cu")
		(net "M_D_CPU1_SB_CB<5>")
	)
	(segment
		(start 34.71037 -240.98885)
		(end 32.727138 -240.98885)
		(width 0.18288)
		(layer "In11.Cu")
		(net "M_D_CPU1_SB_CB<5>")
	)
	(segment
		(start 46.743112 -241.091212)
		(end 45.864526 -240.212626)
		(width 0.18288)
		(layer "In11.Cu")
		(net "M_D_CPU1_SB_CB<5>")
	)
	(segment
		(start 89.367614 -246.040148)
		(end 89.352882 -246.048784)
		(width 0.088646)
		(layer "In11.Cu")
		(net "M_D_CPU1_SB_CB<5>")
	)
	(segment
		(start 17.3863 -239.219486)
		(end 16.789146 -239.81664)
		(width 0.18288)
		(layer "In11.Cu")
		(net "M_D_CPU1_SB_CB<5>")
	)
	(segment
		(start 70.74027 -244.57533)
		(end 66.444622 -240.279682)
		(width 0.18288)
		(layer "In11.Cu")
		(net "M_D_CPU1_SB_CB<5>")
	)
	(segment
		(start 51.998626 -240.241074)
		(end 50.017426 -240.241074)
		(width 0.18288)
		(layer "In11.Cu")
		(net "M_D_CPU1_SB_CB<5>")
	)
	(segment
		(start 84.385912 -245.175532)
		(end 84.08924 -245.175532)
		(width 0.088646)
		(layer "In11.Cu")
		(net "M_D_CPU1_SB_CB<5>")
	)
	(segment
		(start 96.886014 -246.040148)
		(end 96.871282 -246.048784)
		(width 0.088646)
		(layer "In11.Cu")
		(net "M_D_CPU1_SB_CB<5>")
	)
	(segment
		(start 47.41799 -240.996216)
		(end 47.322994 -241.091212)
		(width 0.18288)
		(layer "In11.Cu")
		(net "M_D_CPU1_SB_CB<5>")
	)
	(segment
		(start 40.314626 -240.114836)
		(end 36.450016 -240.114836)
		(width 0.18288)
		(layer "In11.Cu")
		(net "M_D_CPU1_SB_CB<5>")
	)
	(segment
		(start 31.528766 -241.091212)
		(end 30.601412 -240.163858)
		(width 0.18288)
		(layer "In11.Cu")
		(net "M_D_CPU1_SB_CB<5>")
	)
	(segment
		(start 97.905062 -245.994428)
		(end 97.825814 -246.040148)
		(width 0.088646)
		(layer "In11.Cu")
		(net "M_D_CPU1_SB_CB<5>")
	)
	(segment
		(start 84.582254 -245.231412)
		(end 84.573364 -245.226332)
		(width 0.088646)
		(layer "In11.Cu")
		(net "M_D_CPU1_SB_CB<5>")
	)
	(segment
		(start 59.53887 -240.199418)
		(end 58.604912 -239.26546)
		(width 0.18288)
		(layer "In11.Cu")
		(net "M_D_CPU1_SB_CB<5>")
	)
	(segment
		(start 45.864526 -240.212626)
		(end 44.63288 -240.212626)
		(width 0.18288)
		(layer "In11.Cu")
		(net "M_D_CPU1_SB_CB<5>")
	)
	(segment
		(start 29.21254 -240.163858)
		(end 28.96489 -240.411508)
		(width 0.18288)
		(layer "In11.Cu")
		(net "M_D_CPU1_SB_CB<5>")
	)
	(segment
		(start 35.458146 -240.241074)
		(end 34.71037 -240.98885)
		(width 0.18288)
		(layer "In11.Cu")
		(net "M_D_CPU1_SB_CB<5>")
	)
	(segment
		(start 49.262284 -240.996216)
		(end 47.41799 -240.996216)
		(width 0.18288)
		(layer "In11.Cu")
		(net "M_D_CPU1_SB_CB<5>")
	)
	(segment
		(start 50.017426 -240.241074)
		(end 49.262284 -240.996216)
		(width 0.18288)
		(layer "In11.Cu")
		(net "M_D_CPU1_SB_CB<5>")
	)
	(segment
		(start 88.427814 -246.040148)
		(end 88.4174 -246.046244)
		(width 0.088646)
		(layer "In11.Cu")
		(net "M_D_CPU1_SB_CB<5>")
	)
	(segment
		(start 25.527508 -240.411508)
		(end 25.188164 -240.072164)
		(width 0.18288)
		(layer "In11.Cu")
		(net "M_D_CPU1_SB_CB<5>")
	)
	(segment
		(start 52.154074 -240.085626)
		(end 51.998626 -240.241074)
		(width 0.18288)
		(layer "In11.Cu")
		(net "M_D_CPU1_SB_CB<5>")
	)
	(segment
		(start 20.307554 -240.241074)
		(end 19.285966 -239.219486)
		(width 0.18288)
		(layer "In11.Cu")
		(net "M_D_CPU1_SB_CB<5>")
	)
	(segment
		(start 63.581026 -239.349026)
		(end 62.730634 -240.199418)
		(width 0.18288)
		(layer "In11.Cu")
		(net "M_D_CPU1_SB_CB<5>")
	)
	(segment
		(start 44.63288 -240.212626)
		(end 43.56608 -239.145826)
		(width 0.18288)
		(layer "In11.Cu")
		(net "M_D_CPU1_SB_CB<5>")
	)
	(segment
		(start 92.187014 -246.040148)
		(end 92.172282 -246.048784)
		(width 0.088646)
		(layer "In11.Cu")
		(net "M_D_CPU1_SB_CB<5>")
	)
	(segment
		(start 58.604912 -239.26546)
		(end 56.232044 -239.26546)
		(width 0.18288)
		(layer "In11.Cu")
		(net "M_D_CPU1_SB_CB<5>")
	)
	(segment
		(start 30.601412 -240.163858)
		(end 29.21254 -240.163858)
		(width 0.18288)
		(layer "In11.Cu")
		(net "M_D_CPU1_SB_CB<5>")
	)
	(segment
		(start 41.283636 -239.145826)
		(end 40.314626 -240.114836)
		(width 0.18288)
		(layer "In11.Cu")
		(net "M_D_CPU1_SB_CB<5>")
	)
	(segment
		(start 21.441918 -240.241074)
		(end 20.307554 -240.241074)
		(width 0.18288)
		(layer "In11.Cu")
		(net "M_D_CPU1_SB_CB<5>")
	)
	(segment
		(start 21.610828 -240.072164)
		(end 21.441918 -240.241074)
		(width 0.18288)
		(layer "In11.Cu")
		(net "M_D_CPU1_SB_CB<5>")
	)
	(segment
		(start 90.307414 -246.040148)
		(end 90.292682 -246.048784)
		(width 0.088646)
		(layer "In11.Cu")
		(net "M_D_CPU1_SB_CB<5>")
	)
	(segment
		(start 95.946214 -246.040148)
		(end 95.931482 -246.048784)
		(width 0.088646)
		(layer "In11.Cu")
		(net "M_D_CPU1_SB_CB<5>")
	)
	(segment
		(start 55.411878 -240.085626)
		(end 52.154074 -240.085626)
		(width 0.18288)
		(layer "In11.Cu")
		(net "M_D_CPU1_SB_CB<5>")
	)
	(segment
		(start 32.727138 -240.98885)
		(end 32.624776 -241.091212)
		(width 0.18288)
		(layer "In11.Cu")
		(net "M_D_CPU1_SB_CB<5>")
	)
	(segment
		(start 84.760816 -245.560596)
		(end 84.760816 -245.55069)
		(width 0.088646)
		(layer "In11.Cu")
		(net "M_D_CPU1_SB_CB<5>")
	)
	(segment
		(start 66.444622 -240.279682)
		(end 65.161922 -240.279682)
		(width 0.18288)
		(layer "In11.Cu")
		(net "M_D_CPU1_SB_CB<5>")
	)
	(segment
		(start 84.08924 -245.175532)
		(end 84.046314 -245.132606)
		(width 0.088646)
		(layer "In11.Cu")
		(net "M_D_CPU1_SB_CB<5>")
	)
	(segment
		(start 84.046314 -245.132606)
		(end 83.67395 -245.132606)
		(width 0.088646)
		(layer "In11.Cu")
		(net "M_D_CPU1_SB_CB<5>")
	)
	(segment
		(start 94.066868 -246.040148)
		(end 94.056454 -246.046244)
		(width 0.088646)
		(layer "In11.Cu")
		(net "M_D_CPU1_SB_CB<5>")
	)
	(segment
		(start 83.67395 -245.132606)
		(end 81.989168 -245.132606)
		(width 0.18288)
		(layer "In11.Cu")
		(net "M_D_CPU1_SB_CB<5>")
	)
	(segment
		(start 19.285966 -239.219486)
		(end 17.3863 -239.219486)
		(width 0.18288)
		(layer "In11.Cu")
		(net "M_D_CPU1_SB_CB<5>")
	)
	(segment
		(start 36.450016 -240.114836)
		(end 36.323778 -240.241074)
		(width 0.18288)
		(layer "In11.Cu")
		(net "M_D_CPU1_SB_CB<5>")
	)
	(segment
		(start 81.431892 -244.57533)
		(end 70.74027 -244.57533)
		(width 0.18288)
		(layer "In11.Cu")
		(net "M_D_CPU1_SB_CB<5>")
	)
	(segment
		(start 81.989168 -245.132606)
		(end 81.431892 -244.57533)
		(width 0.18288)
		(layer "In11.Cu")
		(net "M_D_CPU1_SB_CB<5>")
	)
	(segment
		(start 43.56608 -239.145826)
		(end 41.283636 -239.145826)
		(width 0.18288)
		(layer "In11.Cu")
		(net "M_D_CPU1_SB_CB<5>")
	)
	(segment
		(start 47.322994 -241.091212)
		(end 46.743112 -241.091212)
		(width 0.18288)
		(layer "In11.Cu")
		(net "M_D_CPU1_SB_CB<5>")
	)
	(segment
		(start 65.161922 -240.279682)
		(end 64.231266 -239.349026)
		(width 0.18288)
		(layer "In11.Cu")
		(net "M_D_CPU1_SB_CB<5>")
	)
	(segment
		(start 25.188164 -240.072164)
		(end 21.610828 -240.072164)
		(width 0.18288)
		(layer "In11.Cu")
		(net "M_D_CPU1_SB_CB<5>")
	)
	(segment
		(start 95.006414 -246.040148)
		(end 94.996 -246.046244)
		(width 0.088646)
		(layer "In11.Cu")
		(net "M_D_CPU1_SB_CB<5>")
	)
	(segment
		(start 64.231266 -239.349026)
		(end 63.581026 -239.349026)
		(width 0.18288)
		(layer "In11.Cu")
		(net "M_D_CPU1_SB_CB<5>")
	)
	(segment
		(start 28.96489 -240.411508)
		(end 25.527508 -240.411508)
		(width 0.18288)
		(layer "In11.Cu")
		(net "M_D_CPU1_SB_CB<5>")
	)
	(segment
		(start 62.730634 -240.199418)
		(end 59.53887 -240.199418)
		(width 0.18288)
		(layer "In11.Cu")
		(net "M_D_CPU1_SB_CB<5>")
	)
	(segment
		(start 56.232044 -239.26546)
		(end 55.411878 -240.085626)
		(width 0.18288)
		(layer "In11.Cu")
		(net "M_D_CPU1_SB_CB<5>")
	)
	(arc
		(start 89.352882 -246.048784)
		(mid 89.076407 -246.116104)
		(end 88.80221 -246.040148)
		(width 0.088646)
		(layer "In11.Cu")
		(net "M_D_CPU1_SB_CB<5>")
	)
	(arc
		(start 88.80221 -246.040148)
		(mid 88.615012 -245.990005)
		(end 88.427814 -246.040148)
		(width 0.088646)
		(layer "In11.Cu")
		(net "M_D_CPU1_SB_CB<5>")
	)
	(arc
		(start 93.50121 -246.040148)
		(mid 93.314012 -245.990005)
		(end 93.126814 -246.040148)
		(width 0.088646)
		(layer "In11.Cu")
		(net "M_D_CPU1_SB_CB<5>")
	)
	(arc
		(start 85.608668 -246.040148)
		(mid 85.325966 -246.115924)
		(end 85.043264 -246.040148)
		(width 0.088646)
		(layer "In11.Cu")
		(net "M_D_CPU1_SB_CB<5>")
	)
	(arc
		(start 84.573364 -245.226332)
		(mid 84.482985 -245.188577)
		(end 84.385912 -245.175532)
		(width 0.088646)
		(layer "In11.Cu")
		(net "M_D_CPU1_SB_CB<5>")
	)
	(arc
		(start 95.931482 -246.048784)
		(mid 95.655007 -246.116104)
		(end 95.38081 -246.040148)
		(width 0.088646)
		(layer "In11.Cu")
		(net "M_D_CPU1_SB_CB<5>")
	)
	(arc
		(start 91.247214 -246.040148)
		(mid 90.964512 -246.115924)
		(end 90.68181 -246.040148)
		(width 0.088646)
		(layer "In11.Cu")
		(net "M_D_CPU1_SB_CB<5>")
	)
	(arc
		(start 96.32061 -246.040148)
		(mid 96.133412 -245.990005)
		(end 95.946214 -246.040148)
		(width 0.088646)
		(layer "In11.Cu")
		(net "M_D_CPU1_SB_CB<5>")
	)
	(arc
		(start 90.292682 -246.048784)
		(mid 90.016207 -246.116104)
		(end 89.74201 -246.040148)
		(width 0.088646)
		(layer "In11.Cu")
		(net "M_D_CPU1_SB_CB<5>")
	)
	(arc
		(start 94.441264 -246.040148)
		(mid 94.254066 -245.990005)
		(end 94.066868 -246.040148)
		(width 0.088646)
		(layer "In11.Cu")
		(net "M_D_CPU1_SB_CB<5>")
	)
	(arc
		(start 86.548468 -246.040148)
		(mid 86.265766 -246.115924)
		(end 85.983064 -246.040148)
		(width 0.088646)
		(layer "In11.Cu")
		(net "M_D_CPU1_SB_CB<5>")
	)
	(arc
		(start 90.68181 -246.040148)
		(mid 90.494612 -245.990005)
		(end 90.307414 -246.040148)
		(width 0.088646)
		(layer "In11.Cu")
		(net "M_D_CPU1_SB_CB<5>")
	)
	(arc
		(start 96.871282 -246.048784)
		(mid 96.594807 -246.116104)
		(end 96.32061 -246.040148)
		(width 0.088646)
		(layer "In11.Cu")
		(net "M_D_CPU1_SB_CB<5>")
	)
	(arc
		(start 87.862664 -246.040148)
		(mid 87.675466 -245.990005)
		(end 87.488268 -246.040148)
		(width 0.088646)
		(layer "In11.Cu")
		(net "M_D_CPU1_SB_CB<5>")
	)
	(arc
		(start 94.056454 -246.046244)
		(mid 93.778022 -246.11609)
		(end 93.50121 -246.040148)
		(width 0.088646)
		(layer "In11.Cu")
		(net "M_D_CPU1_SB_CB<5>")
	)
	(arc
		(start 86.922864 -246.040148)
		(mid 86.735666 -245.990005)
		(end 86.548468 -246.040148)
		(width 0.088646)
		(layer "In11.Cu")
		(net "M_D_CPU1_SB_CB<5>")
	)
	(arc
		(start 91.62161 -246.040148)
		(mid 91.434412 -245.990005)
		(end 91.247214 -246.040148)
		(width 0.088646)
		(layer "In11.Cu")
		(net "M_D_CPU1_SB_CB<5>")
	)
	(arc
		(start 89.74201 -246.040148)
		(mid 89.554812 -245.990005)
		(end 89.367614 -246.040148)
		(width 0.088646)
		(layer "In11.Cu")
		(net "M_D_CPU1_SB_CB<5>")
	)
	(arc
		(start 84.760816 -245.55069)
		(mid 84.713137 -245.36779)
		(end 84.582254 -245.231412)
		(width 0.088646)
		(layer "In11.Cu")
		(net "M_D_CPU1_SB_CB<5>")
	)
	(arc
		(start 93.126814 -246.040148)
		(mid 92.844112 -246.115924)
		(end 92.56141 -246.040148)
		(width 0.088646)
		(layer "In11.Cu")
		(net "M_D_CPU1_SB_CB<5>")
	)
	(arc
		(start 85.043264 -246.040148)
		(mid 84.838929 -245.837543)
		(end 84.760816 -245.560596)
		(width 0.088646)
		(layer "In11.Cu")
		(net "M_D_CPU1_SB_CB<5>")
	)
	(arc
		(start 94.996 -246.046244)
		(mid 94.717822 -246.115967)
		(end 94.441264 -246.040148)
		(width 0.088646)
		(layer "In11.Cu")
		(net "M_D_CPU1_SB_CB<5>")
	)
	(arc
		(start 92.172282 -246.048784)
		(mid 91.895807 -246.116104)
		(end 91.62161 -246.040148)
		(width 0.088646)
		(layer "In11.Cu")
		(net "M_D_CPU1_SB_CB<5>")
	)
	(arc
		(start 98.483166 -245.55069)
		(mid 98.208646 -245.791492)
		(end 97.905062 -245.994428)
		(width 0.088646)
		(layer "In11.Cu")
		(net "M_D_CPU1_SB_CB<5>")
	)
	(arc
		(start 95.38081 -246.040148)
		(mid 95.193612 -245.990005)
		(end 95.006414 -246.040148)
		(width 0.088646)
		(layer "In11.Cu")
		(net "M_D_CPU1_SB_CB<5>")
	)
	(arc
		(start 97.26041 -246.040148)
		(mid 97.073212 -245.990005)
		(end 96.886014 -246.040148)
		(width 0.088646)
		(layer "In11.Cu")
		(net "M_D_CPU1_SB_CB<5>")
	)
	(arc
		(start 92.56141 -246.040148)
		(mid 92.374212 -245.990005)
		(end 92.187014 -246.040148)
		(width 0.088646)
		(layer "In11.Cu")
		(net "M_D_CPU1_SB_CB<5>")
	)
	(arc
		(start 97.825814 -246.040148)
		(mid 97.543112 -246.115924)
		(end 97.26041 -246.040148)
		(width 0.088646)
		(layer "In11.Cu")
		(net "M_D_CPU1_SB_CB<5>")
	)
	(arc
		(start 88.4174 -246.046244)
		(mid 88.139222 -246.115967)
		(end 87.862664 -246.040148)
		(width 0.088646)
		(layer "In11.Cu")
		(net "M_D_CPU1_SB_CB<5>")
	)
	(arc
		(start 87.488268 -246.040148)
		(mid 87.205566 -246.115924)
		(end 86.922864 -246.040148)
		(width 0.088646)
		(layer "In11.Cu")
		(net "M_D_CPU1_SB_CB<5>")
	)
	(arc
		(start 85.983064 -246.040148)
		(mid 85.795866 -245.990005)
		(end 85.608668 -246.040148)
		(width 0.088646)
		(layer "In11.Cu")
		(net "M_D_CPU1_SB_CB<5>")
	)
	(segment
		(start 13.890244 -241.09172)
		(end 14.315186 -241.516662)
		(width 0.20066)
		(layer "F.Cu")
		(net "M_D_CPU1_SB_CB<4>")
	)
	(segment
		(start 11.372342 -241.09172)
		(end 13.441426 -241.09172)
		(width 0.1016)
		(layer "F.Cu")
		(net "M_D_CPU1_SB_CB<4>")
	)
	(segment
		(start 10.344912 -241.582702)
		(end 10.344912 -241.293142)
		(width 0.20066)
		(layer "F.Cu")
		(net "M_D_CPU1_SB_CB<4>")
	)
	(segment
		(start 11.124438 -241.09172)
		(end 11.372342 -241.09172)
		(width 0.101854)
		(layer "F.Cu")
		(net "M_D_CPU1_SB_CB<4>")
	)
	(segment
		(start 10.344912 -241.293142)
		(end 10.554462 -241.083592)
		(width 0.20066)
		(layer "F.Cu")
		(net "M_D_CPU1_SB_CB<4>")
	)
	(segment
		(start 10.554462 -241.083592)
		(end 11.11631 -241.083592)
		(width 0.20066)
		(layer "F.Cu")
		(net "M_D_CPU1_SB_CB<4>")
	)
	(segment
		(start 98.953066 -246.900446)
		(end 98.952812 -246.900192)
		(width 0.20066)
		(layer "F.Cu")
		(net "M_D_CPU1_SB_CB<4>")
	)
	(segment
		(start 11.11631 -241.083592)
		(end 11.124438 -241.09172)
		(width 0.101854)
		(layer "F.Cu")
		(net "M_D_CPU1_SB_CB<4>")
	)
	(segment
		(start 16.789146 -241.516662)
		(end 15.684246 -241.516662)
		(width 0.20066)
		(layer "F.Cu")
		(net "M_D_CPU1_SB_CB<4>")
	)
	(segment
		(start 9.474708 -241.516662)
		(end 9.713468 -241.755422)
		(width 0.20066)
		(layer "F.Cu")
		(net "M_D_CPU1_SB_CB<4>")
	)
	(segment
		(start 8.140446 -241.516662)
		(end 9.474708 -241.516662)
		(width 0.20066)
		(layer "F.Cu")
		(net "M_D_CPU1_SB_CB<4>")
	)
	(segment
		(start 9.713468 -241.755422)
		(end 10.172192 -241.755422)
		(width 0.20066)
		(layer "F.Cu")
		(net "M_D_CPU1_SB_CB<4>")
	)
	(segment
		(start 13.441426 -241.09172)
		(end 13.890244 -241.09172)
		(width 0.20066)
		(layer "F.Cu")
		(net "M_D_CPU1_SB_CB<4>")
	)
	(segment
		(start 98.952812 -246.900192)
		(end 98.952812 -246.364506)
		(width 0.20066)
		(layer "F.Cu")
		(net "M_D_CPU1_SB_CB<4>")
	)
	(segment
		(start 10.172192 -241.755422)
		(end 10.344912 -241.582702)
		(width 0.20066)
		(layer "F.Cu")
		(net "M_D_CPU1_SB_CB<4>")
	)
	(segment
		(start 14.315186 -241.516662)
		(end 15.684246 -241.516662)
		(width 0.20066)
		(layer "F.Cu")
		(net "M_D_CPU1_SB_CB<4>")
	)
	(segment
		(start 64.146938 -241.000026)
		(end 63.61557 -241.000026)
		(width 0.18288)
		(layer "In11.Cu")
		(net "M_D_CPU1_SB_CB<4>")
	)
	(segment
		(start 84.345526 -246.15521)
		(end 83.67395 -246.15521)
		(width 0.088646)
		(layer "In11.Cu")
		(net "M_D_CPU1_SB_CB<4>")
	)
	(segment
		(start 44.150026 -241.941096)
		(end 42.650156 -241.941096)
		(width 0.18288)
		(layer "In11.Cu")
		(net "M_D_CPU1_SB_CB<4>")
	)
	(segment
		(start 36.606226 -241.941096)
		(end 35.588956 -241.941096)
		(width 0.18288)
		(layer "In11.Cu")
		(net "M_D_CPU1_SB_CB<4>")
	)
	(segment
		(start 51.977798 -241.859054)
		(end 51.895756 -241.941096)
		(width 0.18288)
		(layer "In11.Cu")
		(net "M_D_CPU1_SB_CB<4>")
	)
	(segment
		(start 31.653988 -242.791488)
		(end 30.675326 -241.812826)
		(width 0.18288)
		(layer "In11.Cu")
		(net "M_D_CPU1_SB_CB<4>")
	)
	(segment
		(start 32.7533 -242.645184)
		(end 32.606996 -242.791488)
		(width 0.18288)
		(layer "In11.Cu")
		(net "M_D_CPU1_SB_CB<4>")
	)
	(segment
		(start 88.347296 -246.8626)
		(end 88.332564 -246.853964)
		(width 0.088646)
		(layer "In11.Cu")
		(net "M_D_CPU1_SB_CB<4>")
	)
	(segment
		(start 62.813438 -241.802158)
		(end 59.544966 -241.802158)
		(width 0.18288)
		(layer "In11.Cu")
		(net "M_D_CPU1_SB_CB<4>")
	)
	(segment
		(start 89.282778 -246.86006)
		(end 89.272364 -246.853964)
		(width 0.088646)
		(layer "In11.Cu")
		(net "M_D_CPU1_SB_CB<4>")
	)
	(segment
		(start 22.91588 -242.419632)
		(end 22.91588 -241.965226)
		(width 0.18288)
		(layer "In11.Cu")
		(net "M_D_CPU1_SB_CB<4>")
	)
	(segment
		(start 65.966848 -242.217956)
		(end 65.364868 -242.217956)
		(width 0.18288)
		(layer "In11.Cu")
		(net "M_D_CPU1_SB_CB<4>")
	)
	(segment
		(start 80.869536 -245.59133)
		(end 69.340222 -245.59133)
		(width 0.18288)
		(layer "In11.Cu")
		(net "M_D_CPU1_SB_CB<4>")
	)
	(segment
		(start 42.448226 -242.143026)
		(end 40.670226 -242.143026)
		(width 0.18288)
		(layer "In11.Cu")
		(net "M_D_CPU1_SB_CB<4>")
	)
	(segment
		(start 44.176696 -241.914426)
		(end 44.150026 -241.941096)
		(width 0.18288)
		(layer "In11.Cu")
		(net "M_D_CPU1_SB_CB<4>")
	)
	(segment
		(start 59.544966 -241.802158)
		(end 58.750708 -241.0079)
		(width 0.18288)
		(layer "In11.Cu")
		(net "M_D_CPU1_SB_CB<4>")
	)
	(segment
		(start 29.213302 -241.94135)
		(end 27.308302 -241.94135)
		(width 0.18288)
		(layer "In11.Cu")
		(net "M_D_CPU1_SB_CB<4>")
	)
	(segment
		(start 23.80996 -241.772186)
		(end 23.61692 -241.965226)
		(width 0.18288)
		(layer "In11.Cu")
		(net "M_D_CPU1_SB_CB<4>")
	)
	(segment
		(start 81.433416 -246.15521)
		(end 80.869536 -245.59133)
		(width 0.18288)
		(layer "In11.Cu")
		(net "M_D_CPU1_SB_CB<4>")
	)
	(segment
		(start 21.404326 -241.941096)
		(end 19.777456 -241.941096)
		(width 0.18288)
		(layer "In11.Cu")
		(net "M_D_CPU1_SB_CB<4>")
	)
	(segment
		(start 40.263826 -241.736626)
		(end 36.810696 -241.736626)
		(width 0.18288)
		(layer "In11.Cu")
		(net "M_D_CPU1_SB_CB<4>")
	)
	(segment
		(start 27.132026 -242.117626)
		(end 25.658826 -242.117626)
		(width 0.18288)
		(layer "In11.Cu")
		(net "M_D_CPU1_SB_CB<4>")
	)
	(segment
		(start 65.364868 -242.217956)
		(end 64.146938 -241.000026)
		(width 0.18288)
		(layer "In11.Cu")
		(net "M_D_CPU1_SB_CB<4>")
	)
	(segment
		(start 93.046296 -246.8626)
		(end 93.031564 -246.853964)
		(width 0.088646)
		(layer "In11.Cu")
		(net "M_D_CPU1_SB_CB<4>")
	)
	(segment
		(start 90.222324 -246.86006)
		(end 90.21191 -246.853964)
		(width 0.088646)
		(layer "In11.Cu")
		(net "M_D_CPU1_SB_CB<4>")
	)
	(segment
		(start 30.675326 -241.812826)
		(end 29.341826 -241.812826)
		(width 0.18288)
		(layer "In11.Cu")
		(net "M_D_CPU1_SB_CB<4>")
	)
	(segment
		(start 34.884868 -242.645184)
		(end 32.7533 -242.645184)
		(width 0.18288)
		(layer "In11.Cu")
		(net "M_D_CPU1_SB_CB<4>")
	)
	(segment
		(start 23.10892 -242.612672)
		(end 22.91588 -242.419632)
		(width 0.18288)
		(layer "In11.Cu")
		(net "M_D_CPU1_SB_CB<4>")
	)
	(segment
		(start 45.889926 -241.914426)
		(end 44.176696 -241.914426)
		(width 0.18288)
		(layer "In11.Cu")
		(net "M_D_CPU1_SB_CB<4>")
	)
	(segment
		(start 25.658826 -242.117626)
		(end 25.313386 -241.772186)
		(width 0.18288)
		(layer "In11.Cu")
		(net "M_D_CPU1_SB_CB<4>")
	)
	(segment
		(start 21.573236 -241.772186)
		(end 21.404326 -241.941096)
		(width 0.18288)
		(layer "In11.Cu")
		(net "M_D_CPU1_SB_CB<4>")
	)
	(segment
		(start 23.61692 -242.419632)
		(end 23.42388 -242.612672)
		(width 0.18288)
		(layer "In11.Cu")
		(net "M_D_CPU1_SB_CB<4>")
	)
	(segment
		(start 95.861378 -246.86006)
		(end 95.850964 -246.853964)
		(width 0.088646)
		(layer "In11.Cu")
		(net "M_D_CPU1_SB_CB<4>")
	)
	(segment
		(start 35.588956 -241.941096)
		(end 34.884868 -242.645184)
		(width 0.18288)
		(layer "In11.Cu")
		(net "M_D_CPU1_SB_CB<4>")
	)
	(segment
		(start 69.340222 -245.59133)
		(end 65.966848 -242.217956)
		(width 0.18288)
		(layer "In11.Cu")
		(net "M_D_CPU1_SB_CB<4>")
	)
	(segment
		(start 85.325966 -246.803418)
		(end 84.993734 -246.803418)
		(width 0.088646)
		(layer "In11.Cu")
		(net "M_D_CPU1_SB_CB<4>")
	)
	(segment
		(start 91.162378 -246.86006)
		(end 91.151964 -246.853964)
		(width 0.088646)
		(layer "In11.Cu")
		(net "M_D_CPU1_SB_CB<4>")
	)
	(segment
		(start 19.777456 -241.941096)
		(end 19.550126 -242.168426)
		(width 0.18288)
		(layer "In11.Cu")
		(net "M_D_CPU1_SB_CB<4>")
	)
	(segment
		(start 27.308302 -241.94135)
		(end 27.132026 -242.117626)
		(width 0.18288)
		(layer "In11.Cu")
		(net "M_D_CPU1_SB_CB<4>")
	)
	(segment
		(start 22.72284 -241.772186)
		(end 21.573236 -241.772186)
		(width 0.18288)
		(layer "In11.Cu")
		(net "M_D_CPU1_SB_CB<4>")
	)
	(segment
		(start 23.42388 -242.612672)
		(end 23.10892 -242.612672)
		(width 0.18288)
		(layer "In11.Cu")
		(net "M_D_CPU1_SB_CB<4>")
	)
	(segment
		(start 96.800924 -246.86006)
		(end 96.79051 -246.853964)
		(width 0.088646)
		(layer "In11.Cu")
		(net "M_D_CPU1_SB_CB<4>")
	)
	(segment
		(start 98.373946 -246.808752)
		(end 98.295714 -246.853964)
		(width 0.088646)
		(layer "In11.Cu")
		(net "M_D_CPU1_SB_CB<4>")
	)
	(segment
		(start 92.101924 -246.86006)
		(end 92.09151 -246.853964)
		(width 0.088646)
		(layer "In11.Cu")
		(net "M_D_CPU1_SB_CB<4>")
	)
	(segment
		(start 19.550126 -242.168426)
		(end 17.44091 -242.168426)
		(width 0.18288)
		(layer "In11.Cu")
		(net "M_D_CPU1_SB_CB<4>")
	)
	(segment
		(start 97.740978 -246.86006)
		(end 97.730564 -246.853964)
		(width 0.088646)
		(layer "In11.Cu")
		(net "M_D_CPU1_SB_CB<4>")
	)
	(segment
		(start 63.61557 -241.000026)
		(end 62.813438 -241.802158)
		(width 0.18288)
		(layer "In11.Cu")
		(net "M_D_CPU1_SB_CB<4>")
	)
	(segment
		(start 94.925896 -246.8626)
		(end 94.911164 -246.853964)
		(width 0.088646)
		(layer "In11.Cu")
		(net "M_D_CPU1_SB_CB<4>")
	)
	(segment
		(start 29.341826 -241.812826)
		(end 29.213302 -241.94135)
		(width 0.18288)
		(layer "In11.Cu")
		(net "M_D_CPU1_SB_CB<4>")
	)
	(segment
		(start 51.895756 -241.941096)
		(end 50.663856 -241.941096)
		(width 0.18288)
		(layer "In11.Cu")
		(net "M_D_CPU1_SB_CB<4>")
	)
	(segment
		(start 84.993734 -246.803418)
		(end 84.345526 -246.15521)
		(width 0.088646)
		(layer "In11.Cu")
		(net "M_D_CPU1_SB_CB<4>")
	)
	(segment
		(start 50.663856 -241.941096)
		(end 49.813718 -242.791234)
		(width 0.18288)
		(layer "In11.Cu")
		(net "M_D_CPU1_SB_CB<4>")
	)
	(segment
		(start 17.44091 -242.168426)
		(end 16.789146 -241.516662)
		(width 0.18288)
		(layer "In11.Cu")
		(net "M_D_CPU1_SB_CB<4>")
	)
	(segment
		(start 56.136032 -241.0079)
		(end 55.284878 -241.859054)
		(width 0.18288)
		(layer "In11.Cu")
		(net "M_D_CPU1_SB_CB<4>")
	)
	(segment
		(start 23.61692 -241.965226)
		(end 23.61692 -242.419632)
		(width 0.18288)
		(layer "In11.Cu")
		(net "M_D_CPU1_SB_CB<4>")
	)
	(segment
		(start 55.284878 -241.859054)
		(end 51.977798 -241.859054)
		(width 0.18288)
		(layer "In11.Cu")
		(net "M_D_CPU1_SB_CB<4>")
	)
	(segment
		(start 22.91588 -241.965226)
		(end 22.72284 -241.772186)
		(width 0.18288)
		(layer "In11.Cu")
		(net "M_D_CPU1_SB_CB<4>")
	)
	(segment
		(start 42.650156 -241.941096)
		(end 42.448226 -242.143026)
		(width 0.18288)
		(layer "In11.Cu")
		(net "M_D_CPU1_SB_CB<4>")
	)
	(segment
		(start 49.813718 -242.791234)
		(end 46.766734 -242.791234)
		(width 0.18288)
		(layer "In11.Cu")
		(net "M_D_CPU1_SB_CB<4>")
	)
	(segment
		(start 32.606996 -242.791488)
		(end 31.653988 -242.791488)
		(width 0.18288)
		(layer "In11.Cu")
		(net "M_D_CPU1_SB_CB<4>")
	)
	(segment
		(start 58.750708 -241.0079)
		(end 56.136032 -241.0079)
		(width 0.18288)
		(layer "In11.Cu")
		(net "M_D_CPU1_SB_CB<4>")
	)
	(segment
		(start 40.670226 -242.143026)
		(end 40.263826 -241.736626)
		(width 0.18288)
		(layer "In11.Cu")
		(net "M_D_CPU1_SB_CB<4>")
	)
	(segment
		(start 46.766734 -242.791234)
		(end 45.889926 -241.914426)
		(width 0.18288)
		(layer "In11.Cu")
		(net "M_D_CPU1_SB_CB<4>")
	)
	(segment
		(start 25.313386 -241.772186)
		(end 23.80996 -241.772186)
		(width 0.18288)
		(layer "In11.Cu")
		(net "M_D_CPU1_SB_CB<4>")
	)
	(segment
		(start 83.67395 -246.15521)
		(end 81.433416 -246.15521)
		(width 0.18288)
		(layer "In11.Cu")
		(net "M_D_CPU1_SB_CB<4>")
	)
	(segment
		(start 36.810696 -241.736626)
		(end 36.606226 -241.941096)
		(width 0.18288)
		(layer "In11.Cu")
		(net "M_D_CPU1_SB_CB<4>")
	)
	(arc
		(start 98.952812 -246.364506)
		(mid 98.677919 -246.605574)
		(end 98.373946 -246.808752)
		(width 0.088646)
		(layer "In11.Cu")
		(net "M_D_CPU1_SB_CB<4>")
	)
	(arc
		(start 89.272364 -246.853964)
		(mid 89.085166 -246.803821)
		(end 88.897968 -246.853964)
		(width 0.088646)
		(layer "In11.Cu")
		(net "M_D_CPU1_SB_CB<4>")
	)
	(arc
		(start 87.392764 -246.853964)
		(mid 87.205566 -246.803821)
		(end 87.018368 -246.853964)
		(width 0.088646)
		(layer "In11.Cu")
		(net "M_D_CPU1_SB_CB<4>")
	)
	(arc
		(start 97.730564 -246.853964)
		(mid 97.543366 -246.803821)
		(end 97.356168 -246.853964)
		(width 0.088646)
		(layer "In11.Cu")
		(net "M_D_CPU1_SB_CB<4>")
	)
	(arc
		(start 90.777568 -246.853964)
		(mid 90.500755 -246.929834)
		(end 90.222324 -246.86006)
		(width 0.088646)
		(layer "In11.Cu")
		(net "M_D_CPU1_SB_CB<4>")
	)
	(arc
		(start 92.09151 -246.853964)
		(mid 91.904312 -246.803821)
		(end 91.717114 -246.853964)
		(width 0.088646)
		(layer "In11.Cu")
		(net "M_D_CPU1_SB_CB<4>")
	)
	(arc
		(start 85.513164 -246.853964)
		(mid 85.422892 -246.816365)
		(end 85.325966 -246.803418)
		(width 0.088646)
		(layer "In11.Cu")
		(net "M_D_CPU1_SB_CB<4>")
	)
	(arc
		(start 86.452964 -246.853964)
		(mid 86.265766 -246.803821)
		(end 86.078568 -246.853964)
		(width 0.088646)
		(layer "In11.Cu")
		(net "M_D_CPU1_SB_CB<4>")
	)
	(arc
		(start 86.078568 -246.853964)
		(mid 85.795866 -246.92974)
		(end 85.513164 -246.853964)
		(width 0.088646)
		(layer "In11.Cu")
		(net "M_D_CPU1_SB_CB<4>")
	)
	(arc
		(start 94.536768 -246.853964)
		(mid 94.254066 -246.92974)
		(end 93.971364 -246.853964)
		(width 0.088646)
		(layer "In11.Cu")
		(net "M_D_CPU1_SB_CB<4>")
	)
	(arc
		(start 96.416114 -246.853964)
		(mid 96.139555 -246.929707)
		(end 95.861378 -246.86006)
		(width 0.088646)
		(layer "In11.Cu")
		(net "M_D_CPU1_SB_CB<4>")
	)
	(arc
		(start 92.657168 -246.853964)
		(mid 92.380355 -246.929834)
		(end 92.101924 -246.86006)
		(width 0.088646)
		(layer "In11.Cu")
		(net "M_D_CPU1_SB_CB<4>")
	)
	(arc
		(start 91.717114 -246.853964)
		(mid 91.440555 -246.929707)
		(end 91.162378 -246.86006)
		(width 0.088646)
		(layer "In11.Cu")
		(net "M_D_CPU1_SB_CB<4>")
	)
	(arc
		(start 89.837514 -246.853964)
		(mid 89.560955 -246.929707)
		(end 89.282778 -246.86006)
		(width 0.088646)
		(layer "In11.Cu")
		(net "M_D_CPU1_SB_CB<4>")
	)
	(arc
		(start 88.332564 -246.853964)
		(mid 88.145366 -246.803821)
		(end 87.958168 -246.853964)
		(width 0.088646)
		(layer "In11.Cu")
		(net "M_D_CPU1_SB_CB<4>")
	)
	(arc
		(start 87.018368 -246.853964)
		(mid 86.735666 -246.92974)
		(end 86.452964 -246.853964)
		(width 0.088646)
		(layer "In11.Cu")
		(net "M_D_CPU1_SB_CB<4>")
	)
	(arc
		(start 95.476568 -246.853964)
		(mid 95.202369 -246.929799)
		(end 94.925896 -246.8626)
		(width 0.088646)
		(layer "In11.Cu")
		(net "M_D_CPU1_SB_CB<4>")
	)
	(arc
		(start 93.596968 -246.853964)
		(mid 93.322769 -246.929799)
		(end 93.046296 -246.8626)
		(width 0.088646)
		(layer "In11.Cu")
		(net "M_D_CPU1_SB_CB<4>")
	)
	(arc
		(start 87.958168 -246.853964)
		(mid 87.675466 -246.92974)
		(end 87.392764 -246.853964)
		(width 0.088646)
		(layer "In11.Cu")
		(net "M_D_CPU1_SB_CB<4>")
	)
	(arc
		(start 96.79051 -246.853964)
		(mid 96.603312 -246.803821)
		(end 96.416114 -246.853964)
		(width 0.088646)
		(layer "In11.Cu")
		(net "M_D_CPU1_SB_CB<4>")
	)
	(arc
		(start 90.21191 -246.853964)
		(mid 90.024712 -246.803821)
		(end 89.837514 -246.853964)
		(width 0.088646)
		(layer "In11.Cu")
		(net "M_D_CPU1_SB_CB<4>")
	)
	(arc
		(start 97.356168 -246.853964)
		(mid 97.079355 -246.929834)
		(end 96.800924 -246.86006)
		(width 0.088646)
		(layer "In11.Cu")
		(net "M_D_CPU1_SB_CB<4>")
	)
	(arc
		(start 93.031564 -246.853964)
		(mid 92.844366 -246.803821)
		(end 92.657168 -246.853964)
		(width 0.088646)
		(layer "In11.Cu")
		(net "M_D_CPU1_SB_CB<4>")
	)
	(arc
		(start 95.850964 -246.853964)
		(mid 95.663766 -246.803821)
		(end 95.476568 -246.853964)
		(width 0.088646)
		(layer "In11.Cu")
		(net "M_D_CPU1_SB_CB<4>")
	)
	(arc
		(start 88.897968 -246.853964)
		(mid 88.623769 -246.929799)
		(end 88.347296 -246.8626)
		(width 0.088646)
		(layer "In11.Cu")
		(net "M_D_CPU1_SB_CB<4>")
	)
	(arc
		(start 98.295714 -246.853964)
		(mid 98.019155 -246.929707)
		(end 97.740978 -246.86006)
		(width 0.088646)
		(layer "In11.Cu")
		(net "M_D_CPU1_SB_CB<4>")
	)
	(arc
		(start 93.971364 -246.853964)
		(mid 93.784166 -246.803821)
		(end 93.596968 -246.853964)
		(width 0.088646)
		(layer "In11.Cu")
		(net "M_D_CPU1_SB_CB<4>")
	)
	(arc
		(start 91.151964 -246.853964)
		(mid 90.964766 -246.803821)
		(end 90.777568 -246.853964)
		(width 0.088646)
		(layer "In11.Cu")
		(net "M_D_CPU1_SB_CB<4>")
	)
	(arc
		(start 94.911164 -246.853964)
		(mid 94.723966 -246.803821)
		(end 94.536768 -246.853964)
		(width 0.088646)
		(layer "In11.Cu")
		(net "M_D_CPU1_SB_CB<4>")
	)
	(segment
		(start 18.760694 -233.224324)
		(end 18.968212 -233.016806)
		(width 0.20066)
		(layer "F.Cu")
		(net "M_D_CPU1_SB_CB<3>")
	)
	(segment
		(start 13.937742 -233.016806)
		(end 14.063726 -233.14279)
		(width 0.20066)
		(layer "F.Cu")
		(net "M_D_CPU1_SB_CB<3>")
	)
	(segment
		(start 16.885158 -233.441748)
		(end 17.42948 -233.441748)
		(width 0.20066)
		(layer "F.Cu")
		(net "M_D_CPU1_SB_CB<3>")
	)
	(segment
		(start 17.42948 -233.441748)
		(end 17.578578 -233.29265)
		(width 0.20066)
		(layer "F.Cu")
		(net "M_D_CPU1_SB_CB<3>")
	)
	(segment
		(start 17.707102 -233.012488)
		(end 18.102326 -233.012488)
		(width 0.20066)
		(layer "F.Cu")
		(net "M_D_CPU1_SB_CB<3>")
	)
	(segment
		(start 18.102326 -233.012488)
		(end 18.314162 -233.224324)
		(width 0.20066)
		(layer "F.Cu")
		(net "M_D_CPU1_SB_CB<3>")
	)
	(segment
		(start 17.578578 -233.29265)
		(end 17.578578 -233.141012)
		(width 0.20066)
		(layer "F.Cu")
		(net "M_D_CPU1_SB_CB<3>")
	)
	(segment
		(start 14.063726 -233.14279)
		(end 14.063726 -233.313478)
		(width 0.20066)
		(layer "F.Cu")
		(net "M_D_CPU1_SB_CB<3>")
	)
	(segment
		(start 18.314162 -233.224324)
		(end 18.760694 -233.224324)
		(width 0.20066)
		(layer "F.Cu")
		(net "M_D_CPU1_SB_CB<3>")
	)
	(segment
		(start 14.20622 -233.455972)
		(end 14.560042 -233.455972)
		(width 0.20066)
		(layer "F.Cu")
		(net "M_D_CPU1_SB_CB<3>")
	)
	(segment
		(start 14.063726 -233.313478)
		(end 14.20622 -233.455972)
		(width 0.20066)
		(layer "F.Cu")
		(net "M_D_CPU1_SB_CB<3>")
	)
	(segment
		(start 14.812264 -233.441748)
		(end 16.885158 -233.441748)
		(width 0.1016)
		(layer "F.Cu")
		(net "M_D_CPU1_SB_CB<3>")
	)
	(segment
		(start 18.968212 -233.016806)
		(end 19.784314 -233.016806)
		(width 0.20066)
		(layer "F.Cu")
		(net "M_D_CPU1_SB_CB<3>")
	)
	(segment
		(start 99.892866 -243.644928)
		(end 99.892612 -243.644674)
		(width 0.20066)
		(layer "F.Cu")
		(net "M_D_CPU1_SB_CB<3>")
	)
	(segment
		(start 17.578578 -233.141012)
		(end 17.707102 -233.012488)
		(width 0.20066)
		(layer "F.Cu")
		(net "M_D_CPU1_SB_CB<3>")
	)
	(segment
		(start 12.240514 -233.016806)
		(end 13.937742 -233.016806)
		(width 0.20066)
		(layer "F.Cu")
		(net "M_D_CPU1_SB_CB<3>")
	)
	(segment
		(start 14.574266 -233.441748)
		(end 14.812264 -233.441748)
		(width 0.101854)
		(layer "F.Cu")
		(net "M_D_CPU1_SB_CB<3>")
	)
	(segment
		(start 14.560042 -233.455972)
		(end 14.574266 -233.441748)
		(width 0.101854)
		(layer "F.Cu")
		(net "M_D_CPU1_SB_CB<3>")
	)
	(segment
		(start 20.889214 -233.016806)
		(end 19.784314 -233.016806)
		(width 0.20066)
		(layer "F.Cu")
		(net "M_D_CPU1_SB_CB<3>")
	)
	(segment
		(start 99.892612 -243.644674)
		(end 99.892612 -243.108988)
		(width 0.20066)
		(layer "F.Cu")
		(net "M_D_CPU1_SB_CB<3>")
	)
	(segment
		(start 37.952934 -231.339136)
		(end 37.952934 -231.789986)
		(width 0.18288)
		(layer "In11.Cu")
		(net "M_D_CPU1_SB_CB<3>")
	)
	(segment
		(start 98.685096 -242.61064)
		(end 98.670364 -242.619276)
		(width 0.088646)
		(layer "In11.Cu")
		(net "M_D_CPU1_SB_CB<3>")
	)
	(segment
		(start 37.012626 -231.983026)
		(end 36.771072 -231.741472)
		(width 0.18288)
		(layer "In11.Cu")
		(net "M_D_CPU1_SB_CB<3>")
	)
	(segment
		(start 40.543226 -231.983026)
		(end 38.847014 -231.983026)
		(width 0.18288)
		(layer "In11.Cu")
		(net "M_D_CPU1_SB_CB<3>")
	)
	(segment
		(start 94.925896 -242.61064)
		(end 94.911164 -242.619276)
		(width 0.088646)
		(layer "In11.Cu")
		(net "M_D_CPU1_SB_CB<3>")
	)
	(segment
		(start 32.543496 -232.591356)
		(end 31.029656 -232.591356)
		(width 0.18288)
		(layer "In11.Cu")
		(net "M_D_CPU1_SB_CB<3>")
	)
	(segment
		(start 57.804304 -231.896666)
		(end 57.804304 -231.941624)
		(width 0.18288)
		(layer "In11.Cu")
		(net "M_D_CPU1_SB_CB<3>")
	)
	(segment
		(start 83.368896 -240.263426)
		(end 73.22312 -240.263426)
		(width 0.18288)
		(layer "In11.Cu")
		(net "M_D_CPU1_SB_CB<3>")
	)
	(segment
		(start 73.22312 -240.263426)
		(end 67.920616 -234.960922)
		(width 0.18288)
		(layer "In11.Cu")
		(net "M_D_CPU1_SB_CB<3>")
	)
	(segment
		(start 57.804304 -231.941624)
		(end 57.611264 -232.134664)
		(width 0.18288)
		(layer "In11.Cu")
		(net "M_D_CPU1_SB_CB<3>")
	)
	(segment
		(start 49.712626 -231.424226)
		(end 48.644556 -231.424226)
		(width 0.18288)
		(layer "In11.Cu")
		(net "M_D_CPU1_SB_CB<3>")
	)
	(segment
		(start 57.103264 -231.941624)
		(end 57.103264 -231.896666)
		(width 0.18288)
		(layer "In11.Cu")
		(net "M_D_CPU1_SB_CB<3>")
	)
	(segment
		(start 85.057996 -241.796824)
		(end 85.043264 -241.80546)
		(width 0.088646)
		(layer "In11.Cu")
		(net "M_D_CPU1_SB_CB<3>")
	)
	(segment
		(start 43.235626 -232.618026)
		(end 42.245026 -231.627426)
		(width 0.18288)
		(layer "In11.Cu")
		(net "M_D_CPU1_SB_CB<3>")
	)
	(segment
		(start 51.80838 -231.74198)
		(end 50.03038 -231.74198)
		(width 0.18288)
		(layer "In11.Cu")
		(net "M_D_CPU1_SB_CB<3>")
	)
	(segment
		(start 38.145974 -231.146096)
		(end 37.952934 -231.339136)
		(width 0.18288)
		(layer "In11.Cu")
		(net "M_D_CPU1_SB_CB<3>")
	)
	(segment
		(start 25.49398 -234.3023)
		(end 24.820626 -233.628946)
		(width 0.18288)
		(layer "In11.Cu")
		(net "M_D_CPU1_SB_CB<3>")
	)
	(segment
		(start 24.820626 -233.628946)
		(end 21.501354 -233.628946)
		(width 0.18288)
		(layer "In11.Cu")
		(net "M_D_CPU1_SB_CB<3>")
	)
	(segment
		(start 57.103264 -231.896666)
		(end 56.910224 -231.703626)
		(width 0.18288)
		(layer "In11.Cu")
		(net "M_D_CPU1_SB_CB<3>")
	)
	(segment
		(start 40.898826 -231.627426)
		(end 40.543226 -231.983026)
		(width 0.18288)
		(layer "In11.Cu")
		(net "M_D_CPU1_SB_CB<3>")
	)
	(segment
		(start 57.296304 -232.134664)
		(end 57.103264 -231.941624)
		(width 0.18288)
		(layer "In11.Cu")
		(net "M_D_CPU1_SB_CB<3>")
	)
	(segment
		(start 36.771072 -231.741472)
		(end 35.158426 -231.741472)
		(width 0.18288)
		(layer "In11.Cu")
		(net "M_D_CPU1_SB_CB<3>")
	)
	(segment
		(start 29.337254 -233.629454)
		(end 28.664408 -234.3023)
		(width 0.18288)
		(layer "In11.Cu")
		(net "M_D_CPU1_SB_CB<3>")
	)
	(segment
		(start 83.6168 -240.263426)
		(end 83.368896 -240.263426)
		(width 0.088646)
		(layer "In11.Cu")
		(net "M_D_CPU1_SB_CB<3>")
	)
	(segment
		(start 33.558226 -231.576626)
		(end 32.543496 -232.591356)
		(width 0.18288)
		(layer "In11.Cu")
		(net "M_D_CPU1_SB_CB<3>")
	)
	(segment
		(start 60.685426 -231.983026)
		(end 59.720226 -231.983026)
		(width 0.18288)
		(layer "In11.Cu")
		(net "M_D_CPU1_SB_CB<3>")
	)
	(segment
		(start 88.347296 -242.61064)
		(end 88.332564 -242.619276)
		(width 0.088646)
		(layer "In11.Cu")
		(net "M_D_CPU1_SB_CB<3>")
	)
	(segment
		(start 38.460934 -231.146096)
		(end 38.145974 -231.146096)
		(width 0.18288)
		(layer "In11.Cu")
		(net "M_D_CPU1_SB_CB<3>")
	)
	(segment
		(start 86.830916 -242.303554)
		(end 86.830916 -242.285012)
		(width 0.088646)
		(layer "In11.Cu")
		(net "M_D_CPU1_SB_CB<3>")
	)
	(segment
		(start 62.868302 -232.591864)
		(end 61.294264 -232.591864)
		(width 0.18288)
		(layer "In11.Cu")
		(net "M_D_CPU1_SB_CB<3>")
	)
	(segment
		(start 93.046296 -242.61064)
		(end 93.031564 -242.619276)
		(width 0.088646)
		(layer "In11.Cu")
		(net "M_D_CPU1_SB_CB<3>")
	)
	(segment
		(start 37.952934 -231.789986)
		(end 37.759894 -231.983026)
		(width 0.18288)
		(layer "In11.Cu")
		(net "M_D_CPU1_SB_CB<3>")
	)
	(segment
		(start 43.870626 -232.618026)
		(end 43.235626 -232.618026)
		(width 0.18288)
		(layer "In11.Cu")
		(net "M_D_CPU1_SB_CB<3>")
	)
	(segment
		(start 38.653974 -231.789986)
		(end 38.653974 -231.339136)
		(width 0.18288)
		(layer "In11.Cu")
		(net "M_D_CPU1_SB_CB<3>")
	)
	(segment
		(start 95.865696 -242.61064)
		(end 95.850964 -242.619276)
		(width 0.088646)
		(layer "In11.Cu")
		(net "M_D_CPU1_SB_CB<3>")
	)
	(segment
		(start 96.805496 -242.61064)
		(end 96.790764 -242.619276)
		(width 0.088646)
		(layer "In11.Cu")
		(net "M_D_CPU1_SB_CB<3>")
	)
	(segment
		(start 21.501354 -233.628946)
		(end 20.889214 -233.016806)
		(width 0.18288)
		(layer "In11.Cu")
		(net "M_D_CPU1_SB_CB<3>")
	)
	(segment
		(start 57.997344 -231.703626)
		(end 57.804304 -231.896666)
		(width 0.18288)
		(layer "In11.Cu")
		(net "M_D_CPU1_SB_CB<3>")
	)
	(segment
		(start 46.156626 -232.262426)
		(end 44.226226 -232.262426)
		(width 0.18288)
		(layer "In11.Cu")
		(net "M_D_CPU1_SB_CB<3>")
	)
	(segment
		(start 50.03038 -231.74198)
		(end 49.712626 -231.424226)
		(width 0.18288)
		(layer "In11.Cu")
		(net "M_D_CPU1_SB_CB<3>")
	)
	(segment
		(start 44.226226 -232.262426)
		(end 43.870626 -232.618026)
		(width 0.18288)
		(layer "In11.Cu")
		(net "M_D_CPU1_SB_CB<3>")
	)
	(segment
		(start 93.986096 -242.61064)
		(end 93.971364 -242.619276)
		(width 0.088646)
		(layer "In11.Cu")
		(net "M_D_CPU1_SB_CB<3>")
	)
	(segment
		(start 57.611264 -232.134664)
		(end 57.296304 -232.134664)
		(width 0.18288)
		(layer "In11.Cu")
		(net "M_D_CPU1_SB_CB<3>")
	)
	(segment
		(start 99.579938 -243.108988)
		(end 99.51466 -243.04371)
		(width 0.088646)
		(layer "In11.Cu")
		(net "M_D_CPU1_SB_CB<3>")
	)
	(segment
		(start 29.991558 -233.629454)
		(end 29.337254 -233.629454)
		(width 0.18288)
		(layer "In11.Cu")
		(net "M_D_CPU1_SB_CB<3>")
	)
	(segment
		(start 55.605426 -231.906826)
		(end 51.973226 -231.906826)
		(width 0.18288)
		(layer "In11.Cu")
		(net "M_D_CPU1_SB_CB<3>")
	)
	(segment
		(start 59.720226 -231.983026)
		(end 59.440826 -231.703626)
		(width 0.18288)
		(layer "In11.Cu")
		(net "M_D_CPU1_SB_CB<3>")
	)
	(segment
		(start 48.644556 -231.424226)
		(end 47.476156 -232.592626)
		(width 0.18288)
		(layer "In11.Cu")
		(net "M_D_CPU1_SB_CB<3>")
	)
	(segment
		(start 38.653974 -231.339136)
		(end 38.460934 -231.146096)
		(width 0.18288)
		(layer "In11.Cu")
		(net "M_D_CPU1_SB_CB<3>")
	)
	(segment
		(start 66.814446 -234.502706)
		(end 66.07048 -234.502706)
		(width 0.18288)
		(layer "In11.Cu")
		(net "M_D_CPU1_SB_CB<3>")
	)
	(segment
		(start 31.029656 -232.591356)
		(end 29.991558 -233.629454)
		(width 0.18288)
		(layer "In11.Cu")
		(net "M_D_CPU1_SB_CB<3>")
	)
	(segment
		(start 61.294264 -232.591864)
		(end 60.685426 -231.983026)
		(width 0.18288)
		(layer "In11.Cu")
		(net "M_D_CPU1_SB_CB<3>")
	)
	(segment
		(start 47.476156 -232.592626)
		(end 46.486826 -232.592626)
		(width 0.18288)
		(layer "In11.Cu")
		(net "M_D_CPU1_SB_CB<3>")
	)
	(segment
		(start 37.759894 -231.983026)
		(end 37.012626 -231.983026)
		(width 0.18288)
		(layer "In11.Cu")
		(net "M_D_CPU1_SB_CB<3>")
	)
	(segment
		(start 63.14313 -232.866692)
		(end 62.868302 -232.591864)
		(width 0.18288)
		(layer "In11.Cu")
		(net "M_D_CPU1_SB_CB<3>")
	)
	(segment
		(start 66.07048 -234.502706)
		(end 64.434466 -232.866692)
		(width 0.18288)
		(layer "In11.Cu")
		(net "M_D_CPU1_SB_CB<3>")
	)
	(segment
		(start 46.486826 -232.592626)
		(end 46.156626 -232.262426)
		(width 0.18288)
		(layer "In11.Cu")
		(net "M_D_CPU1_SB_CB<3>")
	)
	(segment
		(start 64.434466 -232.866692)
		(end 63.14313 -232.866692)
		(width 0.18288)
		(layer "In11.Cu")
		(net "M_D_CPU1_SB_CB<3>")
	)
	(segment
		(start 89.287096 -242.61064)
		(end 89.272364 -242.619276)
		(width 0.088646)
		(layer "In11.Cu")
		(net "M_D_CPU1_SB_CB<3>")
	)
	(segment
		(start 83.777582 -240.93297)
		(end 83.777582 -240.424208)
		(width 0.088646)
		(layer "In11.Cu")
		(net "M_D_CPU1_SB_CB<3>")
	)
	(segment
		(start 88.332564 -242.619276)
		(end 88.324182 -242.624102)
		(width 0.088646)
		(layer "In11.Cu")
		(net "M_D_CPU1_SB_CB<3>")
	)
	(segment
		(start 59.440826 -231.703626)
		(end 57.997344 -231.703626)
		(width 0.18288)
		(layer "In11.Cu")
		(net "M_D_CPU1_SB_CB<3>")
	)
	(segment
		(start 28.664408 -234.3023)
		(end 25.49398 -234.3023)
		(width 0.18288)
		(layer "In11.Cu")
		(net "M_D_CPU1_SB_CB<3>")
	)
	(segment
		(start 84.59089 -241.746278)
		(end 83.777582 -240.93297)
		(width 0.088646)
		(layer "In11.Cu")
		(net "M_D_CPU1_SB_CB<3>")
	)
	(segment
		(start 90.226896 -242.61064)
		(end 90.212164 -242.619276)
		(width 0.088646)
		(layer "In11.Cu")
		(net "M_D_CPU1_SB_CB<3>")
	)
	(segment
		(start 92.106496 -242.61064)
		(end 92.091764 -242.619276)
		(width 0.088646)
		(layer "In11.Cu")
		(net "M_D_CPU1_SB_CB<3>")
	)
	(segment
		(start 34.99358 -231.576626)
		(end 33.558226 -231.576626)
		(width 0.18288)
		(layer "In11.Cu")
		(net "M_D_CPU1_SB_CB<3>")
	)
	(segment
		(start 56.910224 -231.703626)
		(end 55.808626 -231.703626)
		(width 0.18288)
		(layer "In11.Cu")
		(net "M_D_CPU1_SB_CB<3>")
	)
	(segment
		(start 55.808626 -231.703626)
		(end 55.605426 -231.906826)
		(width 0.18288)
		(layer "In11.Cu")
		(net "M_D_CPU1_SB_CB<3>")
	)
	(segment
		(start 35.158426 -231.741472)
		(end 34.99358 -231.576626)
		(width 0.18288)
		(layer "In11.Cu")
		(net "M_D_CPU1_SB_CB<3>")
	)
	(segment
		(start 42.245026 -231.627426)
		(end 40.898826 -231.627426)
		(width 0.18288)
		(layer "In11.Cu")
		(net "M_D_CPU1_SB_CB<3>")
	)
	(segment
		(start 51.973226 -231.906826)
		(end 51.80838 -231.74198)
		(width 0.18288)
		(layer "In11.Cu")
		(net "M_D_CPU1_SB_CB<3>")
	)
	(segment
		(start 99.892612 -243.108988)
		(end 99.579938 -243.108988)
		(width 0.088646)
		(layer "In11.Cu")
		(net "M_D_CPU1_SB_CB<3>")
	)
	(segment
		(start 83.777582 -240.424208)
		(end 83.6168 -240.263426)
		(width 0.088646)
		(layer "In11.Cu")
		(net "M_D_CPU1_SB_CB<3>")
	)
	(segment
		(start 38.847014 -231.983026)
		(end 38.653974 -231.789986)
		(width 0.18288)
		(layer "In11.Cu")
		(net "M_D_CPU1_SB_CB<3>")
	)
	(segment
		(start 67.920616 -234.960922)
		(end 66.814446 -234.502706)
		(width 0.18288)
		(layer "In11.Cu")
		(net "M_D_CPU1_SB_CB<3>")
	)
	(arc
		(start 97.356168 -242.619276)
		(mid 97.081939 -242.543351)
		(end 96.805496 -242.61064)
		(width 0.088646)
		(layer "In11.Cu")
		(net "M_D_CPU1_SB_CB<3>")
	)
	(arc
		(start 92.091764 -242.619276)
		(mid 91.904566 -242.669419)
		(end 91.717368 -242.619276)
		(width 0.088646)
		(layer "In11.Cu")
		(net "M_D_CPU1_SB_CB<3>")
	)
	(arc
		(start 91.151964 -242.619276)
		(mid 90.964766 -242.669419)
		(end 90.777568 -242.619276)
		(width 0.088646)
		(layer "In11.Cu")
		(net "M_D_CPU1_SB_CB<3>")
	)
	(arc
		(start 86.830916 -242.285012)
		(mid 86.752805 -242.008063)
		(end 86.548468 -241.80546)
		(width 0.088646)
		(layer "In11.Cu")
		(net "M_D_CPU1_SB_CB<3>")
	)
	(arc
		(start 88.897968 -242.619276)
		(mid 88.623739 -242.543351)
		(end 88.347296 -242.61064)
		(width 0.088646)
		(layer "In11.Cu")
		(net "M_D_CPU1_SB_CB<3>")
	)
	(arc
		(start 87.39251 -242.619276)
		(mid 87.205312 -242.669419)
		(end 87.018114 -242.619276)
		(width 0.088646)
		(layer "In11.Cu")
		(net "M_D_CPU1_SB_CB<3>")
	)
	(arc
		(start 95.850964 -242.619276)
		(mid 95.663766 -242.669419)
		(end 95.476568 -242.619276)
		(width 0.088646)
		(layer "In11.Cu")
		(net "M_D_CPU1_SB_CB<3>")
	)
	(arc
		(start 90.212164 -242.619276)
		(mid 90.024966 -242.669419)
		(end 89.837768 -242.619276)
		(width 0.088646)
		(layer "In11.Cu")
		(net "M_D_CPU1_SB_CB<3>")
	)
	(arc
		(start 93.031564 -242.619276)
		(mid 92.844366 -242.669419)
		(end 92.657168 -242.619276)
		(width 0.088646)
		(layer "In11.Cu")
		(net "M_D_CPU1_SB_CB<3>")
	)
	(arc
		(start 93.596968 -242.619276)
		(mid 93.322739 -242.543351)
		(end 93.046296 -242.61064)
		(width 0.088646)
		(layer "In11.Cu")
		(net "M_D_CPU1_SB_CB<3>")
	)
	(arc
		(start 89.837768 -242.619276)
		(mid 89.563539 -242.543351)
		(end 89.287096 -242.61064)
		(width 0.088646)
		(layer "In11.Cu")
		(net "M_D_CPU1_SB_CB<3>")
	)
	(arc
		(start 92.657168 -242.619276)
		(mid 92.382939 -242.543351)
		(end 92.106496 -242.61064)
		(width 0.088646)
		(layer "In11.Cu")
		(net "M_D_CPU1_SB_CB<3>")
	)
	(arc
		(start 87.958422 -242.619276)
		(mid 87.675466 -242.543407)
		(end 87.39251 -242.619276)
		(width 0.088646)
		(layer "In11.Cu")
		(net "M_D_CPU1_SB_CB<3>")
	)
	(arc
		(start 93.971364 -242.619276)
		(mid 93.784166 -242.669419)
		(end 93.596968 -242.619276)
		(width 0.088646)
		(layer "In11.Cu")
		(net "M_D_CPU1_SB_CB<3>")
	)
	(arc
		(start 86.548468 -241.80546)
		(mid 86.265766 -241.729684)
		(end 85.983064 -241.80546)
		(width 0.088646)
		(layer "In11.Cu")
		(net "M_D_CPU1_SB_CB<3>")
	)
	(arc
		(start 99.51466 -243.04371)
		(mid 99.425546 -242.798413)
		(end 99.235768 -242.619276)
		(width 0.088646)
		(layer "In11.Cu")
		(net "M_D_CPU1_SB_CB<3>")
	)
	(arc
		(start 98.295968 -242.619276)
		(mid 98.013266 -242.543534)
		(end 97.730564 -242.619276)
		(width 0.088646)
		(layer "In11.Cu")
		(net "M_D_CPU1_SB_CB<3>")
	)
	(arc
		(start 91.717368 -242.619276)
		(mid 91.434666 -242.543534)
		(end 91.151964 -242.619276)
		(width 0.088646)
		(layer "In11.Cu")
		(net "M_D_CPU1_SB_CB<3>")
	)
	(arc
		(start 96.416368 -242.619276)
		(mid 96.142139 -242.543351)
		(end 95.865696 -242.61064)
		(width 0.088646)
		(layer "In11.Cu")
		(net "M_D_CPU1_SB_CB<3>")
	)
	(arc
		(start 94.536768 -242.619276)
		(mid 94.262539 -242.543351)
		(end 93.986096 -242.61064)
		(width 0.088646)
		(layer "In11.Cu")
		(net "M_D_CPU1_SB_CB<3>")
	)
	(arc
		(start 84.668868 -241.80546)
		(mid 84.627938 -241.778427)
		(end 84.59089 -241.746278)
		(width 0.088646)
		(layer "In11.Cu")
		(net "M_D_CPU1_SB_CB<3>")
	)
	(arc
		(start 85.983064 -241.80546)
		(mid 85.795866 -241.855603)
		(end 85.608668 -241.80546)
		(width 0.088646)
		(layer "In11.Cu")
		(net "M_D_CPU1_SB_CB<3>")
	)
	(arc
		(start 85.043264 -241.80546)
		(mid 84.856066 -241.855603)
		(end 84.668868 -241.80546)
		(width 0.088646)
		(layer "In11.Cu")
		(net "M_D_CPU1_SB_CB<3>")
	)
	(arc
		(start 87.018114 -242.619276)
		(mid 86.883181 -242.485922)
		(end 86.830916 -242.303554)
		(width 0.088646)
		(layer "In11.Cu")
		(net "M_D_CPU1_SB_CB<3>")
	)
	(arc
		(start 94.911164 -242.619276)
		(mid 94.723966 -242.669419)
		(end 94.536768 -242.619276)
		(width 0.088646)
		(layer "In11.Cu")
		(net "M_D_CPU1_SB_CB<3>")
	)
	(arc
		(start 96.790764 -242.619276)
		(mid 96.603566 -242.669419)
		(end 96.416368 -242.619276)
		(width 0.088646)
		(layer "In11.Cu")
		(net "M_D_CPU1_SB_CB<3>")
	)
	(arc
		(start 90.777568 -242.619276)
		(mid 90.503339 -242.543351)
		(end 90.226896 -242.61064)
		(width 0.088646)
		(layer "In11.Cu")
		(net "M_D_CPU1_SB_CB<3>")
	)
	(arc
		(start 95.476568 -242.619276)
		(mid 95.202339 -242.543351)
		(end 94.925896 -242.61064)
		(width 0.088646)
		(layer "In11.Cu")
		(net "M_D_CPU1_SB_CB<3>")
	)
	(arc
		(start 99.235768 -242.619276)
		(mid 98.961539 -242.543351)
		(end 98.685096 -242.61064)
		(width 0.088646)
		(layer "In11.Cu")
		(net "M_D_CPU1_SB_CB<3>")
	)
	(arc
		(start 85.608668 -241.80546)
		(mid 85.334469 -241.729625)
		(end 85.057996 -241.796824)
		(width 0.088646)
		(layer "In11.Cu")
		(net "M_D_CPU1_SB_CB<3>")
	)
	(arc
		(start 88.324182 -242.624102)
		(mid 88.140674 -242.66938)
		(end 87.958422 -242.619276)
		(width 0.088646)
		(layer "In11.Cu")
		(net "M_D_CPU1_SB_CB<3>")
	)
	(arc
		(start 98.670364 -242.619276)
		(mid 98.483166 -242.669419)
		(end 98.295968 -242.619276)
		(width 0.088646)
		(layer "In11.Cu")
		(net "M_D_CPU1_SB_CB<3>")
	)
	(arc
		(start 89.272364 -242.619276)
		(mid 89.085166 -242.669419)
		(end 88.897968 -242.619276)
		(width 0.088646)
		(layer "In11.Cu")
		(net "M_D_CPU1_SB_CB<3>")
	)
	(arc
		(start 97.730564 -242.619276)
		(mid 97.543366 -242.669419)
		(end 97.356168 -242.619276)
		(width 0.088646)
		(layer "In11.Cu")
		(net "M_D_CPU1_SB_CB<3>")
	)
	(segment
		(start 18.46961 -234.716574)
		(end 19.784314 -234.716574)
		(width 0.20066)
		(layer "F.Cu")
		(net "M_D_CPU1_SB_CB<2>")
	)
	(segment
		(start 17.829276 -234.92841)
		(end 18.257774 -234.92841)
		(width 0.20066)
		(layer "F.Cu")
		(net "M_D_CPU1_SB_CB<2>")
	)
	(segment
		(start 18.257774 -234.92841)
		(end 18.46961 -234.716574)
		(width 0.20066)
		(layer "F.Cu")
		(net "M_D_CPU1_SB_CB<2>")
	)
	(segment
		(start 14.570202 -234.291632)
		(end 14.825218 -234.291632)
		(width 0.101854)
		(layer "F.Cu")
		(net "M_D_CPU1_SB_CB<2>")
	)
	(segment
		(start 20.889214 -234.716574)
		(end 19.784314 -234.716574)
		(width 0.20066)
		(layer "F.Cu")
		(net "M_D_CPU1_SB_CB<2>")
	)
	(segment
		(start 17.66189 -234.761024)
		(end 17.829276 -234.92841)
		(width 0.20066)
		(layer "F.Cu")
		(net "M_D_CPU1_SB_CB<2>")
	)
	(segment
		(start 13.82268 -234.281472)
		(end 14.560042 -234.281472)
		(width 0.20066)
		(layer "F.Cu")
		(net "M_D_CPU1_SB_CB<2>")
	)
	(segment
		(start 13.387578 -234.716574)
		(end 13.82268 -234.281472)
		(width 0.20066)
		(layer "F.Cu")
		(net "M_D_CPU1_SB_CB<2>")
	)
	(segment
		(start 100.362766 -244.45849)
		(end 100.362766 -243.922804)
		(width 0.20066)
		(layer "F.Cu")
		(net "M_D_CPU1_SB_CB<2>")
	)
	(segment
		(start 17.518126 -234.291632)
		(end 17.66189 -234.435396)
		(width 0.20066)
		(layer "F.Cu")
		(net "M_D_CPU1_SB_CB<2>")
	)
	(segment
		(start 17.66189 -234.435396)
		(end 17.66189 -234.761024)
		(width 0.20066)
		(layer "F.Cu")
		(net "M_D_CPU1_SB_CB<2>")
	)
	(segment
		(start 12.240514 -234.716574)
		(end 13.387578 -234.716574)
		(width 0.20066)
		(layer "F.Cu")
		(net "M_D_CPU1_SB_CB<2>")
	)
	(segment
		(start 100.362512 -244.458744)
		(end 100.362766 -244.45849)
		(width 0.20066)
		(layer "F.Cu")
		(net "M_D_CPU1_SB_CB<2>")
	)
	(segment
		(start 16.885158 -234.291632)
		(end 17.518126 -234.291632)
		(width 0.20066)
		(layer "F.Cu")
		(net "M_D_CPU1_SB_CB<2>")
	)
	(segment
		(start 14.560042 -234.281472)
		(end 14.570202 -234.291632)
		(width 0.101854)
		(layer "F.Cu")
		(net "M_D_CPU1_SB_CB<2>")
	)
	(segment
		(start 14.825218 -234.291632)
		(end 16.885158 -234.291632)
		(width 0.1016)
		(layer "F.Cu")
		(net "M_D_CPU1_SB_CB<2>")
	)
	(segment
		(start 43.819826 -234.416092)
		(end 42.712386 -234.416092)
		(width 0.18288)
		(layer "In11.Cu")
		(net "M_D_CPU1_SB_CB<2>")
	)
	(segment
		(start 62.89675 -234.042712)
		(end 61.091826 -234.042712)
		(width 0.18288)
		(layer "In11.Cu")
		(net "M_D_CPU1_SB_CB<2>")
	)
	(segment
		(start 61.091826 -234.042712)
		(end 60.658502 -233.609388)
		(width 0.18288)
		(layer "In11.Cu")
		(net "M_D_CPU1_SB_CB<2>")
	)
	(segment
		(start 95.946214 -243.433346)
		(end 95.931482 -243.42471)
		(width 0.088646)
		(layer "In11.Cu")
		(net "M_D_CPU1_SB_CB<2>")
	)
	(segment
		(start 88.427814 -243.433346)
		(end 88.4174 -243.42725)
		(width 0.088646)
		(layer "In11.Cu")
		(net "M_D_CPU1_SB_CB<2>")
	)
	(segment
		(start 29.421074 -235.234226)
		(end 28.64739 -236.00791)
		(width 0.18288)
		(layer "In11.Cu")
		(net "M_D_CPU1_SB_CB<2>")
	)
	(segment
		(start 82.796634 -241.279426)
		(end 72.80148 -241.279426)
		(width 0.18288)
		(layer "In11.Cu")
		(net "M_D_CPU1_SB_CB<2>")
	)
	(segment
		(start 38.67785 -233.364786)
		(end 38.67785 -233.211878)
		(width 0.18288)
		(layer "In11.Cu")
		(net "M_D_CPU1_SB_CB<2>")
	)
	(segment
		(start 98.765614 -243.433346)
		(end 98.7552 -243.42725)
		(width 0.088646)
		(layer "In11.Cu")
		(net "M_D_CPU1_SB_CB<2>")
	)
	(segment
		(start 37.97681 -233.211878)
		(end 37.97681 -233.364786)
		(width 0.18288)
		(layer "In11.Cu")
		(net "M_D_CPU1_SB_CB<2>")
	)
	(segment
		(start 100.05949 -243.786914)
		(end 99.84486 -243.54663)
		(width 0.088646)
		(layer "In11.Cu")
		(net "M_D_CPU1_SB_CB<2>")
	)
	(segment
		(start 57.86501 -233.74604)
		(end 57.67197 -233.93908)
		(width 0.18288)
		(layer "In11.Cu")
		(net "M_D_CPU1_SB_CB<2>")
	)
	(segment
		(start 36.646104 -233.557826)
		(end 36.526978 -233.4387)
		(width 0.18288)
		(layer "In11.Cu")
		(net "M_D_CPU1_SB_CB<2>")
	)
	(segment
		(start 40.746426 -233.253026)
		(end 40.441626 -233.557826)
		(width 0.18288)
		(layer "In11.Cu")
		(net "M_D_CPU1_SB_CB<2>")
	)
	(segment
		(start 90.307414 -243.433346)
		(end 90.292682 -243.42471)
		(width 0.088646)
		(layer "In11.Cu")
		(net "M_D_CPU1_SB_CB<2>")
	)
	(segment
		(start 86.361016 -243.108988)
		(end 86.361016 -243.090446)
		(width 0.088646)
		(layer "In11.Cu")
		(net "M_D_CPU1_SB_CB<2>")
	)
	(segment
		(start 66.014092 -236.082078)
		(end 64.246506 -234.314492)
		(width 0.18288)
		(layer "In11.Cu")
		(net "M_D_CPU1_SB_CB<2>")
	)
	(segment
		(start 40.441626 -233.557826)
		(end 38.87089 -233.557826)
		(width 0.18288)
		(layer "In11.Cu")
		(net "M_D_CPU1_SB_CB<2>")
	)
	(segment
		(start 38.67785 -233.211878)
		(end 38.48481 -233.018838)
		(width 0.18288)
		(layer "In11.Cu")
		(net "M_D_CPU1_SB_CB<2>")
	)
	(segment
		(start 38.48481 -233.018838)
		(end 38.16985 -233.018838)
		(width 0.18288)
		(layer "In11.Cu")
		(net "M_D_CPU1_SB_CB<2>")
	)
	(segment
		(start 59.390026 -233.354626)
		(end 58.05805 -233.354626)
		(width 0.18288)
		(layer "In11.Cu")
		(net "M_D_CPU1_SB_CB<2>")
	)
	(segment
		(start 49.494694 -233.441494)
		(end 49.357026 -233.303826)
		(width 0.18288)
		(layer "In11.Cu")
		(net "M_D_CPU1_SB_CB<2>")
	)
	(segment
		(start 48.635666 -233.412792)
		(end 47.756826 -234.291632)
		(width 0.18288)
		(layer "In11.Cu")
		(net "M_D_CPU1_SB_CB<2>")
	)
	(segment
		(start 51.794918 -233.441494)
		(end 49.494694 -233.441494)
		(width 0.18288)
		(layer "In11.Cu")
		(net "M_D_CPU1_SB_CB<2>")
	)
	(segment
		(start 24.744426 -235.310426)
		(end 21.483066 -235.310426)
		(width 0.18288)
		(layer "In11.Cu")
		(net "M_D_CPU1_SB_CB<2>")
	)
	(segment
		(start 86.937596 -243.42471)
		(end 86.922864 -243.433346)
		(width 0.088646)
		(layer "In11.Cu")
		(net "M_D_CPU1_SB_CB<2>")
	)
	(segment
		(start 44.093892 -234.142026)
		(end 43.819826 -234.416092)
		(width 0.18288)
		(layer "In11.Cu")
		(net "M_D_CPU1_SB_CB<2>")
	)
	(segment
		(start 41.54932 -233.253026)
		(end 40.746426 -233.253026)
		(width 0.18288)
		(layer "In11.Cu")
		(net "M_D_CPU1_SB_CB<2>")
	)
	(segment
		(start 52.832254 -233.49077)
		(end 51.844194 -233.49077)
		(width 0.18288)
		(layer "In11.Cu")
		(net "M_D_CPU1_SB_CB<2>")
	)
	(segment
		(start 93.126814 -243.433346)
		(end 93.112082 -243.42471)
		(width 0.088646)
		(layer "In11.Cu")
		(net "M_D_CPU1_SB_CB<2>")
	)
	(segment
		(start 57.16397 -233.547666)
		(end 56.97093 -233.354626)
		(width 0.18288)
		(layer "In11.Cu")
		(net "M_D_CPU1_SB_CB<2>")
	)
	(segment
		(start 28.64739 -236.00791)
		(end 25.44191 -236.00791)
		(width 0.18288)
		(layer "In11.Cu")
		(net "M_D_CPU1_SB_CB<2>")
	)
	(segment
		(start 72.80148 -241.279426)
		(end 68.230496 -236.708442)
		(width 0.18288)
		(layer "In11.Cu")
		(net "M_D_CPU1_SB_CB<2>")
	)
	(segment
		(start 36.526978 -233.4387)
		(end 33.398206 -233.4387)
		(width 0.18288)
		(layer "In11.Cu")
		(net "M_D_CPU1_SB_CB<2>")
	)
	(segment
		(start 83.447128 -241.92992)
		(end 82.796634 -241.279426)
		(width 0.18288)
		(layer "In11.Cu")
		(net "M_D_CPU1_SB_CB<2>")
	)
	(segment
		(start 49.357026 -233.303826)
		(end 48.89881 -233.303826)
		(width 0.18288)
		(layer "In11.Cu")
		(net "M_D_CPU1_SB_CB<2>")
	)
	(segment
		(start 37.97681 -233.364786)
		(end 37.78377 -233.557826)
		(width 0.18288)
		(layer "In11.Cu")
		(net "M_D_CPU1_SB_CB<2>")
	)
	(segment
		(start 42.712386 -234.416092)
		(end 41.54932 -233.253026)
		(width 0.18288)
		(layer "In11.Cu")
		(net "M_D_CPU1_SB_CB<2>")
	)
	(segment
		(start 38.87089 -233.557826)
		(end 38.67785 -233.364786)
		(width 0.18288)
		(layer "In11.Cu")
		(net "M_D_CPU1_SB_CB<2>")
	)
	(segment
		(start 66.718434 -236.082078)
		(end 66.014092 -236.082078)
		(width 0.18288)
		(layer "In11.Cu")
		(net "M_D_CPU1_SB_CB<2>")
	)
	(segment
		(start 63.16853 -234.314492)
		(end 62.89675 -234.042712)
		(width 0.18288)
		(layer "In11.Cu")
		(net "M_D_CPU1_SB_CB<2>")
	)
	(segment
		(start 57.35701 -233.93908)
		(end 57.16397 -233.74604)
		(width 0.18288)
		(layer "In11.Cu")
		(net "M_D_CPU1_SB_CB<2>")
	)
	(segment
		(start 30.459426 -235.234226)
		(end 29.421074 -235.234226)
		(width 0.18288)
		(layer "In11.Cu")
		(net "M_D_CPU1_SB_CB<2>")
	)
	(segment
		(start 57.67197 -233.93908)
		(end 57.35701 -233.93908)
		(width 0.18288)
		(layer "In11.Cu")
		(net "M_D_CPU1_SB_CB<2>")
	)
	(segment
		(start 83.673696 -241.92992)
		(end 83.447128 -241.92992)
		(width 0.18288)
		(layer "In11.Cu")
		(net "M_D_CPU1_SB_CB<2>")
	)
	(segment
		(start 86.078568 -242.619276)
		(end 86.068154 -242.61318)
		(width 0.088646)
		(layer "In11.Cu")
		(net "M_D_CPU1_SB_CB<2>")
	)
	(segment
		(start 83.953096 -242.398804)
		(end 83.953096 -242.018566)
		(width 0.088646)
		(layer "In11.Cu")
		(net "M_D_CPU1_SB_CB<2>")
	)
	(segment
		(start 84.224622 -242.67033)
		(end 83.953096 -242.398804)
		(width 0.088646)
		(layer "In11.Cu")
		(net "M_D_CPU1_SB_CB<2>")
	)
	(segment
		(start 57.16397 -233.74604)
		(end 57.16397 -233.547666)
		(width 0.18288)
		(layer "In11.Cu")
		(net "M_D_CPU1_SB_CB<2>")
	)
	(segment
		(start 86.548468 -243.433346)
		(end 86.539578 -243.428266)
		(width 0.088646)
		(layer "In11.Cu")
		(net "M_D_CPU1_SB_CB<2>")
	)
	(segment
		(start 57.86501 -233.547666)
		(end 57.86501 -233.74604)
		(width 0.18288)
		(layer "In11.Cu")
		(net "M_D_CPU1_SB_CB<2>")
	)
	(segment
		(start 97.826068 -243.433346)
		(end 97.815654 -243.42725)
		(width 0.088646)
		(layer "In11.Cu")
		(net "M_D_CPU1_SB_CB<2>")
	)
	(segment
		(start 33.398206 -233.4387)
		(end 32.545274 -234.291632)
		(width 0.18288)
		(layer "In11.Cu")
		(net "M_D_CPU1_SB_CB<2>")
	)
	(segment
		(start 58.05805 -233.354626)
		(end 57.86501 -233.547666)
		(width 0.18288)
		(layer "In11.Cu")
		(net "M_D_CPU1_SB_CB<2>")
	)
	(segment
		(start 53.95214 -233.452416)
		(end 53.571648 -233.071924)
		(width 0.18288)
		(layer "In11.Cu")
		(net "M_D_CPU1_SB_CB<2>")
	)
	(segment
		(start 48.89881 -233.303826)
		(end 48.635666 -233.412792)
		(width 0.18288)
		(layer "In11.Cu")
		(net "M_D_CPU1_SB_CB<2>")
	)
	(segment
		(start 37.78377 -233.557826)
		(end 36.646104 -233.557826)
		(width 0.18288)
		(layer "In11.Cu")
		(net "M_D_CPU1_SB_CB<2>")
	)
	(segment
		(start 55.681626 -233.452416)
		(end 53.95214 -233.452416)
		(width 0.18288)
		(layer "In11.Cu")
		(net "M_D_CPU1_SB_CB<2>")
	)
	(segment
		(start 47.756826 -234.291632)
		(end 46.026832 -234.291632)
		(width 0.18288)
		(layer "In11.Cu")
		(net "M_D_CPU1_SB_CB<2>")
	)
	(segment
		(start 92.187014 -243.433346)
		(end 92.1766 -243.42725)
		(width 0.088646)
		(layer "In11.Cu")
		(net "M_D_CPU1_SB_CB<2>")
	)
	(segment
		(start 89.367614 -243.433346)
		(end 89.352882 -243.42471)
		(width 0.088646)
		(layer "In11.Cu")
		(net "M_D_CPU1_SB_CB<2>")
	)
	(segment
		(start 64.246506 -234.314492)
		(end 63.16853 -234.314492)
		(width 0.18288)
		(layer "In11.Cu")
		(net "M_D_CPU1_SB_CB<2>")
	)
	(segment
		(start 85.138514 -242.619276)
		(end 85.123782 -242.61064)
		(width 0.088646)
		(layer "In11.Cu")
		(net "M_D_CPU1_SB_CB<2>")
	)
	(segment
		(start 46.026832 -234.291632)
		(end 45.877226 -234.142026)
		(width 0.18288)
		(layer "In11.Cu")
		(net "M_D_CPU1_SB_CB<2>")
	)
	(segment
		(start 94.066614 -243.433346)
		(end 94.051882 -243.42471)
		(width 0.088646)
		(layer "In11.Cu")
		(net "M_D_CPU1_SB_CB<2>")
	)
	(segment
		(start 31.40202 -234.291632)
		(end 30.459426 -235.234226)
		(width 0.18288)
		(layer "In11.Cu")
		(net "M_D_CPU1_SB_CB<2>")
	)
	(segment
		(start 53.2511 -233.071924)
		(end 52.832254 -233.49077)
		(width 0.18288)
		(layer "In11.Cu")
		(net "M_D_CPU1_SB_CB<2>")
	)
	(segment
		(start 38.16985 -233.018838)
		(end 37.97681 -233.211878)
		(width 0.18288)
		(layer "In11.Cu")
		(net "M_D_CPU1_SB_CB<2>")
	)
	(segment
		(start 83.86445 -241.92992)
		(end 83.673696 -241.92992)
		(width 0.088646)
		(layer "In11.Cu")
		(net "M_D_CPU1_SB_CB<2>")
	)
	(segment
		(start 55.779416 -233.354626)
		(end 55.681626 -233.452416)
		(width 0.18288)
		(layer "In11.Cu")
		(net "M_D_CPU1_SB_CB<2>")
	)
	(segment
		(start 25.44191 -236.00791)
		(end 24.744426 -235.310426)
		(width 0.18288)
		(layer "In11.Cu")
		(net "M_D_CPU1_SB_CB<2>")
	)
	(segment
		(start 84.385912 -242.67033)
		(end 84.224622 -242.67033)
		(width 0.088646)
		(layer "In11.Cu")
		(net "M_D_CPU1_SB_CB<2>")
	)
	(segment
		(start 21.483066 -235.310426)
		(end 20.889214 -234.716574)
		(width 0.18288)
		(layer "In11.Cu")
		(net "M_D_CPU1_SB_CB<2>")
	)
	(segment
		(start 83.953096 -242.018566)
		(end 83.86445 -241.92992)
		(width 0.088646)
		(layer "In11.Cu")
		(net "M_D_CPU1_SB_CB<2>")
	)
	(segment
		(start 59.644788 -233.609388)
		(end 59.390026 -233.354626)
		(width 0.18288)
		(layer "In11.Cu")
		(net "M_D_CPU1_SB_CB<2>")
	)
	(segment
		(start 45.877226 -234.142026)
		(end 44.093892 -234.142026)
		(width 0.18288)
		(layer "In11.Cu")
		(net "M_D_CPU1_SB_CB<2>")
	)
	(segment
		(start 96.886014 -243.433346)
		(end 96.871282 -243.42471)
		(width 0.088646)
		(layer "In11.Cu")
		(net "M_D_CPU1_SB_CB<2>")
	)
	(segment
		(start 68.230496 -236.708442)
		(end 66.718434 -236.082078)
		(width 0.18288)
		(layer "In11.Cu")
		(net "M_D_CPU1_SB_CB<2>")
	)
	(segment
		(start 60.658502 -233.609388)
		(end 59.644788 -233.609388)
		(width 0.18288)
		(layer "In11.Cu")
		(net "M_D_CPU1_SB_CB<2>")
	)
	(segment
		(start 56.97093 -233.354626)
		(end 55.779416 -233.354626)
		(width 0.18288)
		(layer "In11.Cu")
		(net "M_D_CPU1_SB_CB<2>")
	)
	(segment
		(start 51.844194 -233.49077)
		(end 51.794918 -233.441494)
		(width 0.18288)
		(layer "In11.Cu")
		(net "M_D_CPU1_SB_CB<2>")
	)
	(segment
		(start 91.247468 -243.433346)
		(end 91.237054 -243.42725)
		(width 0.088646)
		(layer "In11.Cu")
		(net "M_D_CPU1_SB_CB<2>")
	)
	(segment
		(start 32.545274 -234.291632)
		(end 31.40202 -234.291632)
		(width 0.18288)
		(layer "In11.Cu")
		(net "M_D_CPU1_SB_CB<2>")
	)
	(segment
		(start 53.571648 -233.071924)
		(end 53.2511 -233.071924)
		(width 0.18288)
		(layer "In11.Cu")
		(net "M_D_CPU1_SB_CB<2>")
	)
	(arc
		(start 85.51291 -242.619276)
		(mid 85.325712 -242.669419)
		(end 85.138514 -242.619276)
		(width 0.088646)
		(layer "In11.Cu")
		(net "M_D_CPU1_SB_CB<2>")
	)
	(arc
		(start 98.7552 -243.42725)
		(mid 98.477022 -243.357527)
		(end 98.200464 -243.433346)
		(width 0.088646)
		(layer "In11.Cu")
		(net "M_D_CPU1_SB_CB<2>")
	)
	(arc
		(start 86.068154 -242.61318)
		(mid 85.789722 -242.543366)
		(end 85.51291 -242.619276)
		(width 0.088646)
		(layer "In11.Cu")
		(net "M_D_CPU1_SB_CB<2>")
	)
	(arc
		(start 97.26041 -243.433346)
		(mid 97.073212 -243.483489)
		(end 96.886014 -243.433346)
		(width 0.088646)
		(layer "In11.Cu")
		(net "M_D_CPU1_SB_CB<2>")
	)
	(arc
		(start 97.815654 -243.42725)
		(mid 97.537222 -243.357404)
		(end 97.26041 -243.433346)
		(width 0.088646)
		(layer "In11.Cu")
		(net "M_D_CPU1_SB_CB<2>")
	)
	(arc
		(start 86.361016 -243.090446)
		(mid 86.280854 -242.818257)
		(end 86.078568 -242.619276)
		(width 0.088646)
		(layer "In11.Cu")
		(net "M_D_CPU1_SB_CB<2>")
	)
	(arc
		(start 96.871282 -243.42471)
		(mid 96.594807 -243.35739)
		(end 96.32061 -243.433346)
		(width 0.088646)
		(layer "In11.Cu")
		(net "M_D_CPU1_SB_CB<2>")
	)
	(arc
		(start 92.56141 -243.433346)
		(mid 92.374212 -243.483489)
		(end 92.187014 -243.433346)
		(width 0.088646)
		(layer "In11.Cu")
		(net "M_D_CPU1_SB_CB<2>")
	)
	(arc
		(start 93.50121 -243.433346)
		(mid 93.314012 -243.483489)
		(end 93.126814 -243.433346)
		(width 0.088646)
		(layer "In11.Cu")
		(net "M_D_CPU1_SB_CB<2>")
	)
	(arc
		(start 91.237054 -243.42725)
		(mid 90.958622 -243.357404)
		(end 90.68181 -243.433346)
		(width 0.088646)
		(layer "In11.Cu")
		(net "M_D_CPU1_SB_CB<2>")
	)
	(arc
		(start 90.68181 -243.433346)
		(mid 90.494612 -243.483489)
		(end 90.307414 -243.433346)
		(width 0.088646)
		(layer "In11.Cu")
		(net "M_D_CPU1_SB_CB<2>")
	)
	(arc
		(start 88.4174 -243.42725)
		(mid 88.139222 -243.357527)
		(end 87.862664 -243.433346)
		(width 0.088646)
		(layer "In11.Cu")
		(net "M_D_CPU1_SB_CB<2>")
	)
	(arc
		(start 91.621864 -243.433346)
		(mid 91.434666 -243.483489)
		(end 91.247468 -243.433346)
		(width 0.088646)
		(layer "In11.Cu")
		(net "M_D_CPU1_SB_CB<2>")
	)
	(arc
		(start 89.74201 -243.433346)
		(mid 89.554812 -243.483489)
		(end 89.367614 -243.433346)
		(width 0.088646)
		(layer "In11.Cu")
		(net "M_D_CPU1_SB_CB<2>")
	)
	(arc
		(start 93.112082 -243.42471)
		(mid 92.835607 -243.35739)
		(end 92.56141 -243.433346)
		(width 0.088646)
		(layer "In11.Cu")
		(net "M_D_CPU1_SB_CB<2>")
	)
	(arc
		(start 92.1766 -243.42725)
		(mid 91.898422 -243.357527)
		(end 91.621864 -243.433346)
		(width 0.088646)
		(layer "In11.Cu")
		(net "M_D_CPU1_SB_CB<2>")
	)
	(arc
		(start 85.123782 -242.61064)
		(mid 84.847341 -242.543474)
		(end 84.57311 -242.619276)
		(width 0.088646)
		(layer "In11.Cu")
		(net "M_D_CPU1_SB_CB<2>")
	)
	(arc
		(start 90.292682 -243.42471)
		(mid 90.016207 -243.35739)
		(end 89.74201 -243.433346)
		(width 0.088646)
		(layer "In11.Cu")
		(net "M_D_CPU1_SB_CB<2>")
	)
	(arc
		(start 99.14001 -243.433346)
		(mid 98.952812 -243.483489)
		(end 98.765614 -243.433346)
		(width 0.088646)
		(layer "In11.Cu")
		(net "M_D_CPU1_SB_CB<2>")
	)
	(arc
		(start 88.80221 -243.433346)
		(mid 88.615012 -243.483489)
		(end 88.427814 -243.433346)
		(width 0.088646)
		(layer "In11.Cu")
		(net "M_D_CPU1_SB_CB<2>")
	)
	(arc
		(start 84.57311 -242.619276)
		(mid 84.482874 -242.657146)
		(end 84.385912 -242.67033)
		(width 0.088646)
		(layer "In11.Cu")
		(net "M_D_CPU1_SB_CB<2>")
	)
	(arc
		(start 86.922864 -243.433346)
		(mid 86.735666 -243.483489)
		(end 86.548468 -243.433346)
		(width 0.088646)
		(layer "In11.Cu")
		(net "M_D_CPU1_SB_CB<2>")
	)
	(arc
		(start 94.44101 -243.433346)
		(mid 94.253812 -243.483489)
		(end 94.066614 -243.433346)
		(width 0.088646)
		(layer "In11.Cu")
		(net "M_D_CPU1_SB_CB<2>")
	)
	(arc
		(start 96.32061 -243.433346)
		(mid 96.133412 -243.483489)
		(end 95.946214 -243.433346)
		(width 0.088646)
		(layer "In11.Cu")
		(net "M_D_CPU1_SB_CB<2>")
	)
	(arc
		(start 95.38081 -243.433346)
		(mid 95.193612 -243.483489)
		(end 95.006414 -243.433346)
		(width 0.088646)
		(layer "In11.Cu")
		(net "M_D_CPU1_SB_CB<2>")
	)
	(arc
		(start 89.352882 -243.42471)
		(mid 89.076407 -243.35739)
		(end 88.80221 -243.433346)
		(width 0.088646)
		(layer "In11.Cu")
		(net "M_D_CPU1_SB_CB<2>")
	)
	(arc
		(start 99.71151 -243.436902)
		(mid 99.426241 -243.357567)
		(end 99.14001 -243.433346)
		(width 0.088646)
		(layer "In11.Cu")
		(net "M_D_CPU1_SB_CB<2>")
	)
	(arc
		(start 87.488268 -243.433346)
		(mid 87.214069 -243.357511)
		(end 86.937596 -243.42471)
		(width 0.088646)
		(layer "In11.Cu")
		(net "M_D_CPU1_SB_CB<2>")
	)
	(arc
		(start 99.84486 -243.54663)
		(mid 99.782405 -243.486636)
		(end 99.71151 -243.436902)
		(width 0.088646)
		(layer "In11.Cu")
		(net "M_D_CPU1_SB_CB<2>")
	)
	(arc
		(start 95.006414 -243.433346)
		(mid 94.723712 -243.35757)
		(end 94.44101 -243.433346)
		(width 0.088646)
		(layer "In11.Cu")
		(net "M_D_CPU1_SB_CB<2>")
	)
	(arc
		(start 98.200464 -243.433346)
		(mid 98.013266 -243.483489)
		(end 97.826068 -243.433346)
		(width 0.088646)
		(layer "In11.Cu")
		(net "M_D_CPU1_SB_CB<2>")
	)
	(arc
		(start 87.862664 -243.433346)
		(mid 87.675466 -243.483489)
		(end 87.488268 -243.433346)
		(width 0.088646)
		(layer "In11.Cu")
		(net "M_D_CPU1_SB_CB<2>")
	)
	(arc
		(start 86.539578 -243.428266)
		(mid 86.408664 -243.291906)
		(end 86.361016 -243.108988)
		(width 0.088646)
		(layer "In11.Cu")
		(net "M_D_CPU1_SB_CB<2>")
	)
	(arc
		(start 100.362766 -243.922804)
		(mid 100.196582 -243.887297)
		(end 100.05949 -243.786914)
		(width 0.088646)
		(layer "In11.Cu")
		(net "M_D_CPU1_SB_CB<2>")
	)
	(arc
		(start 95.931482 -243.42471)
		(mid 95.655007 -243.35739)
		(end 95.38081 -243.433346)
		(width 0.088646)
		(layer "In11.Cu")
		(net "M_D_CPU1_SB_CB<2>")
	)
	(arc
		(start 94.051882 -243.42471)
		(mid 93.775407 -243.35739)
		(end 93.50121 -243.433346)
		(width 0.088646)
		(layer "In11.Cu")
		(net "M_D_CPU1_SB_CB<2>")
	)
	(segment
		(start 13.441426 -233.441748)
		(end 13.619988 -233.441748)
		(width 0.20066)
		(layer "F.Cu")
		(net "M_D_CPU1_SB_CB<1>")
	)
	(segment
		(start 13.619988 -233.441748)
		(end 14.04493 -233.86669)
		(width 0.20066)
		(layer "F.Cu")
		(net "M_D_CPU1_SB_CB<1>")
	)
	(segment
		(start 10.344912 -233.923586)
		(end 10.344912 -233.595418)
		(width 0.20066)
		(layer "F.Cu")
		(net "M_D_CPU1_SB_CB<1>")
	)
	(segment
		(start 10.344912 -233.595418)
		(end 10.507472 -233.432858)
		(width 0.20066)
		(layer "F.Cu")
		(net "M_D_CPU1_SB_CB<1>")
	)
	(segment
		(start 98.952812 -243.644674)
		(end 98.952812 -243.108988)
		(width 0.20066)
		(layer "F.Cu")
		(net "M_D_CPU1_SB_CB<1>")
	)
	(segment
		(start 9.686036 -234.078018)
		(end 10.19048 -234.078018)
		(width 0.20066)
		(layer "F.Cu")
		(net "M_D_CPU1_SB_CB<1>")
	)
	(segment
		(start 10.19048 -234.078018)
		(end 10.344912 -233.923586)
		(width 0.20066)
		(layer "F.Cu")
		(net "M_D_CPU1_SB_CB<1>")
	)
	(segment
		(start 13.110718 -233.441748)
		(end 13.441426 -233.441748)
		(width 0.101854)
		(layer "F.Cu")
		(net "M_D_CPU1_SB_CB<1>")
	)
	(segment
		(start 14.04493 -233.86669)
		(end 15.684246 -233.86669)
		(width 0.20066)
		(layer "F.Cu")
		(net "M_D_CPU1_SB_CB<1>")
	)
	(segment
		(start 11.1252 -233.441748)
		(end 13.110718 -233.441748)
		(width 0.1016)
		(layer "F.Cu")
		(net "M_D_CPU1_SB_CB<1>")
	)
	(segment
		(start 98.953066 -243.644928)
		(end 98.952812 -243.644674)
		(width 0.20066)
		(layer "F.Cu")
		(net "M_D_CPU1_SB_CB<1>")
	)
	(segment
		(start 8.140446 -233.86669)
		(end 9.474708 -233.86669)
		(width 0.20066)
		(layer "F.Cu")
		(net "M_D_CPU1_SB_CB<1>")
	)
	(segment
		(start 9.474708 -233.86669)
		(end 9.686036 -234.078018)
		(width 0.20066)
		(layer "F.Cu")
		(net "M_D_CPU1_SB_CB<1>")
	)
	(segment
		(start 16.789146 -233.86669)
		(end 15.684246 -233.86669)
		(width 0.20066)
		(layer "F.Cu")
		(net "M_D_CPU1_SB_CB<1>")
	)
	(segment
		(start 10.507472 -233.432858)
		(end 11.11631 -233.432858)
		(width 0.20066)
		(layer "F.Cu")
		(net "M_D_CPU1_SB_CB<1>")
	)
	(segment
		(start 11.11631 -233.432858)
		(end 11.1252 -233.441748)
		(width 0.1016)
		(layer "F.Cu")
		(net "M_D_CPU1_SB_CB<1>")
	)
	(segment
		(start 45.597826 -233.507026)
		(end 44.267374 -233.507026)
		(width 0.18288)
		(layer "In11.Cu")
		(net "M_D_CPU1_SB_CB<1>")
	)
	(segment
		(start 36.41471 -232.492042)
		(end 36.315142 -232.59161)
		(width 0.18288)
		(layer "In11.Cu")
		(net "M_D_CPU1_SB_CB<1>")
	)
	(segment
		(start 95.946214 -242.78463)
		(end 95.931482 -242.793266)
		(width 0.088646)
		(layer "In11.Cu")
		(net "M_D_CPU1_SB_CB<1>")
	)
	(segment
		(start 28.805886 -234.937046)
		(end 25.225502 -234.937046)
		(width 0.18288)
		(layer "In11.Cu")
		(net "M_D_CPU1_SB_CB<1>")
	)
	(segment
		(start 21.395182 -234.29087)
		(end 20.04187 -234.29087)
		(width 0.18288)
		(layer "In11.Cu")
		(net "M_D_CPU1_SB_CB<1>")
	)
	(segment
		(start 25.225502 -234.937046)
		(end 24.521922 -234.233466)
		(width 0.18288)
		(layer "In11.Cu")
		(net "M_D_CPU1_SB_CB<1>")
	)
	(segment
		(start 21.452586 -234.233466)
		(end 21.395182 -234.29087)
		(width 0.18288)
		(layer "In11.Cu")
		(net "M_D_CPU1_SB_CB<1>")
	)
	(segment
		(start 18.451576 -233.253026)
		(end 16.789146 -233.86669)
		(width 0.18288)
		(layer "In11.Cu")
		(net "M_D_CPU1_SB_CB<1>")
	)
	(segment
		(start 41.343326 -232.706926)
		(end 40.073326 -232.492042)
		(width 0.18288)
		(layer "In11.Cu")
		(net "M_D_CPU1_SB_CB<1>")
	)
	(segment
		(start 29.552646 -234.190286)
		(end 28.805886 -234.937046)
		(width 0.18288)
		(layer "In11.Cu")
		(net "M_D_CPU1_SB_CB<1>")
	)
	(segment
		(start 49.155096 -232.591864)
		(end 47.401226 -233.441494)
		(width 0.18288)
		(layer "In11.Cu")
		(net "M_D_CPU1_SB_CB<1>")
	)
	(segment
		(start 63.086996 -233.430826)
		(end 63.01613 -233.501692)
		(width 0.18288)
		(layer "In11.Cu")
		(net "M_D_CPU1_SB_CB<1>")
	)
	(segment
		(start 20.04187 -234.29087)
		(end 19.004026 -233.253026)
		(width 0.18288)
		(layer "In11.Cu")
		(net "M_D_CPU1_SB_CB<1>")
	)
	(segment
		(start 93.126814 -242.78463)
		(end 93.112082 -242.793266)
		(width 0.088646)
		(layer "In11.Cu")
		(net "M_D_CPU1_SB_CB<1>")
	)
	(segment
		(start 32.250126 -233.441494)
		(end 31.403798 -233.441494)
		(width 0.18288)
		(layer "In11.Cu")
		(net "M_D_CPU1_SB_CB<1>")
	)
	(segment
		(start 30.655006 -234.190286)
		(end 29.552646 -234.190286)
		(width 0.18288)
		(layer "In11.Cu")
		(net "M_D_CPU1_SB_CB<1>")
	)
	(segment
		(start 91.247468 -242.78463)
		(end 91.237054 -242.790726)
		(width 0.088646)
		(layer "In11.Cu")
		(net "M_D_CPU1_SB_CB<1>")
	)
	(segment
		(start 99.1489 -242.78971)
		(end 99.14001 -242.78463)
		(width 0.088646)
		(layer "In11.Cu")
		(net "M_D_CPU1_SB_CB<1>")
	)
	(segment
		(start 83.50885 -241.272822)
		(end 83.007454 -240.771426)
		(width 0.18288)
		(layer "In11.Cu")
		(net "M_D_CPU1_SB_CB<1>")
	)
	(segment
		(start 98.952812 -243.108988)
		(end 99.265486 -243.108988)
		(width 0.088646)
		(layer "In11.Cu")
		(net "M_D_CPU1_SB_CB<1>")
	)
	(segment
		(start 89.367614 -242.78463)
		(end 89.352882 -242.793266)
		(width 0.088646)
		(layer "In11.Cu")
		(net "M_D_CPU1_SB_CB<1>")
	)
	(segment
		(start 88.428068 -242.78463)
		(end 88.413336 -242.793266)
		(width 0.088646)
		(layer "In11.Cu")
		(net "M_D_CPU1_SB_CB<1>")
	)
	(segment
		(start 65.901062 -235.065062)
		(end 64.266826 -233.430826)
		(width 0.18288)
		(layer "In11.Cu")
		(net "M_D_CPU1_SB_CB<1>")
	)
	(segment
		(start 59.110626 -232.668826)
		(end 56.189626 -232.668826)
		(width 0.18288)
		(layer "In11.Cu")
		(net "M_D_CPU1_SB_CB<1>")
	)
	(segment
		(start 36.315142 -232.59161)
		(end 34.084768 -232.59161)
		(width 0.18288)
		(layer "In11.Cu")
		(net "M_D_CPU1_SB_CB<1>")
	)
	(segment
		(start 59.288426 -232.491026)
		(end 59.110626 -232.668826)
		(width 0.18288)
		(layer "In11.Cu")
		(net "M_D_CPU1_SB_CB<1>")
	)
	(segment
		(start 98.765614 -242.78463)
		(end 98.7552 -242.790726)
		(width 0.088646)
		(layer "In11.Cu")
		(net "M_D_CPU1_SB_CB<1>")
	)
	(segment
		(start 83.673696 -241.272822)
		(end 83.50885 -241.272822)
		(width 0.18288)
		(layer "In11.Cu")
		(net "M_D_CPU1_SB_CB<1>")
	)
	(segment
		(start 60.190126 -232.491026)
		(end 59.288426 -232.491026)
		(width 0.18288)
		(layer "In11.Cu")
		(net "M_D_CPU1_SB_CB<1>")
	)
	(segment
		(start 31.403798 -233.441494)
		(end 30.655006 -234.190286)
		(width 0.18288)
		(layer "In11.Cu")
		(net "M_D_CPU1_SB_CB<1>")
	)
	(segment
		(start 24.521922 -234.233466)
		(end 21.452586 -234.233466)
		(width 0.18288)
		(layer "In11.Cu")
		(net "M_D_CPU1_SB_CB<1>")
	)
	(segment
		(start 88.43645 -242.779804)
		(end 88.428068 -242.78463)
		(width 0.088646)
		(layer "In11.Cu")
		(net "M_D_CPU1_SB_CB<1>")
	)
	(segment
		(start 83.848194 -241.272822)
		(end 83.673696 -241.272822)
		(width 0.088646)
		(layer "In11.Cu")
		(net "M_D_CPU1_SB_CB<1>")
	)
	(segment
		(start 44.267374 -233.507026)
		(end 41.71569 -232.706926)
		(width 0.18288)
		(layer "In11.Cu")
		(net "M_D_CPU1_SB_CB<1>")
	)
	(segment
		(start 63.01613 -233.501692)
		(end 61.688726 -233.501692)
		(width 0.18288)
		(layer "In11.Cu")
		(net "M_D_CPU1_SB_CB<1>")
	)
	(segment
		(start 85.138514 -241.97056)
		(end 85.123782 -241.979196)
		(width 0.088646)
		(layer "In11.Cu")
		(net "M_D_CPU1_SB_CB<1>")
	)
	(segment
		(start 33.34258 -232.66654)
		(end 32.82061 -233.18851)
		(width 0.18288)
		(layer "In11.Cu")
		(net "M_D_CPU1_SB_CB<1>")
	)
	(segment
		(start 92.187014 -242.78463)
		(end 92.1766 -242.790726)
		(width 0.088646)
		(layer "In11.Cu")
		(net "M_D_CPU1_SB_CB<1>")
	)
	(segment
		(start 84.45627 -241.880898)
		(end 83.848194 -241.272822)
		(width 0.088646)
		(layer "In11.Cu")
		(net "M_D_CPU1_SB_CB<1>")
	)
	(segment
		(start 47.401226 -233.441494)
		(end 45.663358 -233.441494)
		(width 0.18288)
		(layer "In11.Cu")
		(net "M_D_CPU1_SB_CB<1>")
	)
	(segment
		(start 94.066614 -242.78463)
		(end 94.051882 -242.793266)
		(width 0.088646)
		(layer "In11.Cu")
		(net "M_D_CPU1_SB_CB<1>")
	)
	(segment
		(start 83.007454 -240.771426)
		(end 73.0123 -240.771426)
		(width 0.18288)
		(layer "In11.Cu")
		(net "M_D_CPU1_SB_CB<1>")
	)
	(segment
		(start 61.666374 -233.486706)
		(end 60.190126 -232.491026)
		(width 0.18288)
		(layer "In11.Cu")
		(net "M_D_CPU1_SB_CB<1>")
	)
	(segment
		(start 41.71569 -232.706926)
		(end 41.343326 -232.706926)
		(width 0.18288)
		(layer "In11.Cu")
		(net "M_D_CPU1_SB_CB<1>")
	)
	(segment
		(start 73.0123 -240.771426)
		(end 67.76085 -235.519976)
		(width 0.18288)
		(layer "In11.Cu")
		(net "M_D_CPU1_SB_CB<1>")
	)
	(segment
		(start 86.937596 -242.793266)
		(end 86.922864 -242.78463)
		(width 0.088646)
		(layer "In11.Cu")
		(net "M_D_CPU1_SB_CB<1>")
	)
	(segment
		(start 95.006414 -242.78463)
		(end 94.991682 -242.793266)
		(width 0.088646)
		(layer "In11.Cu")
		(net "M_D_CPU1_SB_CB<1>")
	)
	(segment
		(start 86.640162 -242.309142)
		(end 86.640162 -242.286282)
		(width 0.088646)
		(layer "In11.Cu")
		(net "M_D_CPU1_SB_CB<1>")
	)
	(segment
		(start 86.078568 -241.97056)
		(end 86.068154 -241.976656)
		(width 0.088646)
		(layer "In11.Cu")
		(net "M_D_CPU1_SB_CB<1>")
	)
	(segment
		(start 99.265486 -243.108988)
		(end 99.32289 -243.051584)
		(width 0.088646)
		(layer "In11.Cu")
		(net "M_D_CPU1_SB_CB<1>")
	)
	(segment
		(start 51.557428 -232.488486)
		(end 51.454304 -232.591864)
		(width 0.18288)
		(layer "In11.Cu")
		(net "M_D_CPU1_SB_CB<1>")
	)
	(segment
		(start 97.826068 -242.78463)
		(end 97.815654 -242.790726)
		(width 0.088646)
		(layer "In11.Cu")
		(net "M_D_CPU1_SB_CB<1>")
	)
	(segment
		(start 90.307414 -242.78463)
		(end 90.292682 -242.793266)
		(width 0.088646)
		(layer "In11.Cu")
		(net "M_D_CPU1_SB_CB<1>")
	)
	(segment
		(start 56.002174 -232.63606)
		(end 55.160926 -232.488486)
		(width 0.18288)
		(layer "In11.Cu")
		(net "M_D_CPU1_SB_CB<1>")
	)
	(segment
		(start 19.004026 -233.253026)
		(end 18.451576 -233.253026)
		(width 0.18288)
		(layer "In11.Cu")
		(net "M_D_CPU1_SB_CB<1>")
	)
	(segment
		(start 45.663358 -233.441494)
		(end 45.597826 -233.507026)
		(width 0.18288)
		(layer "In11.Cu")
		(net "M_D_CPU1_SB_CB<1>")
	)
	(segment
		(start 66.662554 -235.065062)
		(end 65.901062 -235.065062)
		(width 0.18288)
		(layer "In11.Cu")
		(net "M_D_CPU1_SB_CB<1>")
	)
	(segment
		(start 40.073326 -232.492042)
		(end 36.41471 -232.492042)
		(width 0.18288)
		(layer "In11.Cu")
		(net "M_D_CPU1_SB_CB<1>")
	)
	(segment
		(start 96.886014 -242.78463)
		(end 96.871282 -242.793266)
		(width 0.088646)
		(layer "In11.Cu")
		(net "M_D_CPU1_SB_CB<1>")
	)
	(segment
		(start 32.82061 -233.18851)
		(end 32.250126 -233.441494)
		(width 0.18288)
		(layer "In11.Cu")
		(net "M_D_CPU1_SB_CB<1>")
	)
	(segment
		(start 51.454304 -232.591864)
		(end 49.155096 -232.591864)
		(width 0.18288)
		(layer "In11.Cu")
		(net "M_D_CPU1_SB_CB<1>")
	)
	(segment
		(start 64.266826 -233.430826)
		(end 63.086996 -233.430826)
		(width 0.18288)
		(layer "In11.Cu")
		(net "M_D_CPU1_SB_CB<1>")
	)
	(segment
		(start 55.160926 -232.488486)
		(end 51.557428 -232.488486)
		(width 0.18288)
		(layer "In11.Cu")
		(net "M_D_CPU1_SB_CB<1>")
	)
	(segment
		(start 61.688726 -233.501692)
		(end 61.666374 -233.486706)
		(width 0.18288)
		(layer "In11.Cu")
		(net "M_D_CPU1_SB_CB<1>")
	)
	(segment
		(start 34.084768 -232.59161)
		(end 33.34258 -232.66654)
		(width 0.18288)
		(layer "In11.Cu")
		(net "M_D_CPU1_SB_CB<1>")
	)
	(segment
		(start 56.189626 -232.668826)
		(end 56.002174 -232.63606)
		(width 0.18288)
		(layer "In11.Cu")
		(net "M_D_CPU1_SB_CB<1>")
	)
	(segment
		(start 67.76085 -235.519976)
		(end 66.662554 -235.065062)
		(width 0.18288)
		(layer "In11.Cu")
		(net "M_D_CPU1_SB_CB<1>")
	)
	(arc
		(start 87.488268 -242.78463)
		(mid 87.214039 -242.860555)
		(end 86.937596 -242.793266)
		(width 0.088646)
		(layer "In11.Cu")
		(net "M_D_CPU1_SB_CB<1>")
	)
	(arc
		(start 98.200464 -242.78463)
		(mid 98.013266 -242.734487)
		(end 97.826068 -242.78463)
		(width 0.088646)
		(layer "In11.Cu")
		(net "M_D_CPU1_SB_CB<1>")
	)
	(arc
		(start 91.237054 -242.790726)
		(mid 90.958622 -242.86054)
		(end 90.68181 -242.78463)
		(width 0.088646)
		(layer "In11.Cu")
		(net "M_D_CPU1_SB_CB<1>")
	)
	(arc
		(start 94.44101 -242.78463)
		(mid 94.253812 -242.734487)
		(end 94.066614 -242.78463)
		(width 0.088646)
		(layer "In11.Cu")
		(net "M_D_CPU1_SB_CB<1>")
	)
	(arc
		(start 89.74201 -242.78463)
		(mid 89.554812 -242.734487)
		(end 89.367614 -242.78463)
		(width 0.088646)
		(layer "In11.Cu")
		(net "M_D_CPU1_SB_CB<1>")
	)
	(arc
		(start 92.56141 -242.78463)
		(mid 92.374212 -242.734487)
		(end 92.187014 -242.78463)
		(width 0.088646)
		(layer "In11.Cu")
		(net "M_D_CPU1_SB_CB<1>")
	)
	(arc
		(start 94.991682 -242.793266)
		(mid 94.715241 -242.860432)
		(end 94.44101 -242.78463)
		(width 0.088646)
		(layer "In11.Cu")
		(net "M_D_CPU1_SB_CB<1>")
	)
	(arc
		(start 93.112082 -242.793266)
		(mid 92.835641 -242.860432)
		(end 92.56141 -242.78463)
		(width 0.088646)
		(layer "In11.Cu")
		(net "M_D_CPU1_SB_CB<1>")
	)
	(arc
		(start 86.922864 -242.78463)
		(mid 86.719383 -242.583826)
		(end 86.640162 -242.309142)
		(width 0.088646)
		(layer "In11.Cu")
		(net "M_D_CPU1_SB_CB<1>")
	)
	(arc
		(start 89.352882 -242.793266)
		(mid 89.076441 -242.860432)
		(end 88.80221 -242.78463)
		(width 0.088646)
		(layer "In11.Cu")
		(net "M_D_CPU1_SB_CB<1>")
	)
	(arc
		(start 87.862664 -242.78463)
		(mid 87.675466 -242.734487)
		(end 87.488268 -242.78463)
		(width 0.088646)
		(layer "In11.Cu")
		(net "M_D_CPU1_SB_CB<1>")
	)
	(arc
		(start 95.931482 -242.793266)
		(mid 95.655041 -242.860432)
		(end 95.38081 -242.78463)
		(width 0.088646)
		(layer "In11.Cu")
		(net "M_D_CPU1_SB_CB<1>")
	)
	(arc
		(start 90.292682 -242.793266)
		(mid 90.016241 -242.860432)
		(end 89.74201 -242.78463)
		(width 0.088646)
		(layer "In11.Cu")
		(net "M_D_CPU1_SB_CB<1>")
	)
	(arc
		(start 86.452964 -241.97056)
		(mid 86.265766 -241.920417)
		(end 86.078568 -241.97056)
		(width 0.088646)
		(layer "In11.Cu")
		(net "M_D_CPU1_SB_CB<1>")
	)
	(arc
		(start 85.123782 -241.979196)
		(mid 84.773738 -242.040558)
		(end 84.45627 -241.880898)
		(width 0.088646)
		(layer "In11.Cu")
		(net "M_D_CPU1_SB_CB<1>")
	)
	(arc
		(start 97.26041 -242.78463)
		(mid 97.073212 -242.734487)
		(end 96.886014 -242.78463)
		(width 0.088646)
		(layer "In11.Cu")
		(net "M_D_CPU1_SB_CB<1>")
	)
	(arc
		(start 88.80221 -242.78463)
		(mid 88.619959 -242.734519)
		(end 88.43645 -242.779804)
		(width 0.088646)
		(layer "In11.Cu")
		(net "M_D_CPU1_SB_CB<1>")
	)
	(arc
		(start 86.640162 -242.286282)
		(mid 86.587892 -242.103917)
		(end 86.452964 -241.97056)
		(width 0.088646)
		(layer "In11.Cu")
		(net "M_D_CPU1_SB_CB<1>")
	)
	(arc
		(start 95.38081 -242.78463)
		(mid 95.193612 -242.734487)
		(end 95.006414 -242.78463)
		(width 0.088646)
		(layer "In11.Cu")
		(net "M_D_CPU1_SB_CB<1>")
	)
	(arc
		(start 92.1766 -242.790726)
		(mid 91.898422 -242.860418)
		(end 91.621864 -242.78463)
		(width 0.088646)
		(layer "In11.Cu")
		(net "M_D_CPU1_SB_CB<1>")
	)
	(arc
		(start 85.51291 -241.97056)
		(mid 85.325712 -241.920417)
		(end 85.138514 -241.97056)
		(width 0.088646)
		(layer "In11.Cu")
		(net "M_D_CPU1_SB_CB<1>")
	)
	(arc
		(start 99.32289 -243.051584)
		(mid 99.264734 -242.901471)
		(end 99.1489 -242.78971)
		(width 0.088646)
		(layer "In11.Cu")
		(net "M_D_CPU1_SB_CB<1>")
	)
	(arc
		(start 88.413336 -242.793266)
		(mid 88.136895 -242.860432)
		(end 87.862664 -242.78463)
		(width 0.088646)
		(layer "In11.Cu")
		(net "M_D_CPU1_SB_CB<1>")
	)
	(arc
		(start 91.621864 -242.78463)
		(mid 91.434666 -242.734487)
		(end 91.247468 -242.78463)
		(width 0.088646)
		(layer "In11.Cu")
		(net "M_D_CPU1_SB_CB<1>")
	)
	(arc
		(start 98.7552 -242.790726)
		(mid 98.477022 -242.860418)
		(end 98.200464 -242.78463)
		(width 0.088646)
		(layer "In11.Cu")
		(net "M_D_CPU1_SB_CB<1>")
	)
	(arc
		(start 86.068154 -241.976656)
		(mid 85.789722 -242.046502)
		(end 85.51291 -241.97056)
		(width 0.088646)
		(layer "In11.Cu")
		(net "M_D_CPU1_SB_CB<1>")
	)
	(arc
		(start 96.871282 -242.793266)
		(mid 96.594841 -242.860432)
		(end 96.32061 -242.78463)
		(width 0.088646)
		(layer "In11.Cu")
		(net "M_D_CPU1_SB_CB<1>")
	)
	(arc
		(start 90.68181 -242.78463)
		(mid 90.494612 -242.734487)
		(end 90.307414 -242.78463)
		(width 0.088646)
		(layer "In11.Cu")
		(net "M_D_CPU1_SB_CB<1>")
	)
	(arc
		(start 93.50121 -242.78463)
		(mid 93.314012 -242.734487)
		(end 93.126814 -242.78463)
		(width 0.088646)
		(layer "In11.Cu")
		(net "M_D_CPU1_SB_CB<1>")
	)
	(arc
		(start 94.051882 -242.793266)
		(mid 93.775441 -242.860432)
		(end 93.50121 -242.78463)
		(width 0.088646)
		(layer "In11.Cu")
		(net "M_D_CPU1_SB_CB<1>")
	)
	(arc
		(start 96.32061 -242.78463)
		(mid 96.133412 -242.734487)
		(end 95.946214 -242.78463)
		(width 0.088646)
		(layer "In11.Cu")
		(net "M_D_CPU1_SB_CB<1>")
	)
	(arc
		(start 99.14001 -242.78463)
		(mid 98.952812 -242.734487)
		(end 98.765614 -242.78463)
		(width 0.088646)
		(layer "In11.Cu")
		(net "M_D_CPU1_SB_CB<1>")
	)
	(arc
		(start 97.815654 -242.790726)
		(mid 97.537222 -242.86054)
		(end 97.26041 -242.78463)
		(width 0.088646)
		(layer "In11.Cu")
		(net "M_D_CPU1_SB_CB<1>")
	)
	(segment
		(start 8.140446 -235.566712)
		(end 9.474708 -235.566712)
		(width 0.20066)
		(layer "F.Cu")
		(net "M_D_CPU1_SB_CB<0>")
	)
	(segment
		(start 11.11631 -235.133642)
		(end 11.124438 -235.14177)
		(width 0.101854)
		(layer "F.Cu")
		(net "M_D_CPU1_SB_CB<0>")
	)
	(segment
		(start 9.474708 -235.566712)
		(end 9.713468 -235.805472)
		(width 0.20066)
		(layer "F.Cu")
		(net "M_D_CPU1_SB_CB<0>")
	)
	(segment
		(start 10.344912 -235.343192)
		(end 10.554462 -235.133642)
		(width 0.20066)
		(layer "F.Cu")
		(net "M_D_CPU1_SB_CB<0>")
	)
	(segment
		(start 10.344912 -235.632752)
		(end 10.344912 -235.343192)
		(width 0.20066)
		(layer "F.Cu")
		(net "M_D_CPU1_SB_CB<0>")
	)
	(segment
		(start 14.315186 -235.566712)
		(end 15.684246 -235.566712)
		(width 0.20066)
		(layer "F.Cu")
		(net "M_D_CPU1_SB_CB<0>")
	)
	(segment
		(start 13.441426 -235.14177)
		(end 13.890244 -235.14177)
		(width 0.20066)
		(layer "F.Cu")
		(net "M_D_CPU1_SB_CB<0>")
	)
	(segment
		(start 11.372342 -235.14177)
		(end 13.441426 -235.14177)
		(width 0.1016)
		(layer "F.Cu")
		(net "M_D_CPU1_SB_CB<0>")
	)
	(segment
		(start 11.124438 -235.14177)
		(end 11.372342 -235.14177)
		(width 0.101854)
		(layer "F.Cu")
		(net "M_D_CPU1_SB_CB<0>")
	)
	(segment
		(start 10.172192 -235.805472)
		(end 10.344912 -235.632752)
		(width 0.20066)
		(layer "F.Cu")
		(net "M_D_CPU1_SB_CB<0>")
	)
	(segment
		(start 98.483166 -244.45849)
		(end 98.483166 -243.922804)
		(width 0.20066)
		(layer "F.Cu")
		(net "M_D_CPU1_SB_CB<0>")
	)
	(segment
		(start 13.890244 -235.14177)
		(end 14.315186 -235.566712)
		(width 0.20066)
		(layer "F.Cu")
		(net "M_D_CPU1_SB_CB<0>")
	)
	(segment
		(start 16.789146 -235.566712)
		(end 15.684246 -235.566712)
		(width 0.20066)
		(layer "F.Cu")
		(net "M_D_CPU1_SB_CB<0>")
	)
	(segment
		(start 98.482912 -244.458744)
		(end 98.483166 -244.45849)
		(width 0.20066)
		(layer "F.Cu")
		(net "M_D_CPU1_SB_CB<0>")
	)
	(segment
		(start 10.554462 -235.133642)
		(end 11.11631 -235.133642)
		(width 0.20066)
		(layer "F.Cu")
		(net "M_D_CPU1_SB_CB<0>")
	)
	(segment
		(start 9.713468 -235.805472)
		(end 10.172192 -235.805472)
		(width 0.20066)
		(layer "F.Cu")
		(net "M_D_CPU1_SB_CB<0>")
	)
	(segment
		(start 40.333168 -234.155234)
		(end 36.793424 -234.155234)
		(width 0.18288)
		(layer "In11.Cu")
		(net "M_D_CPU1_SB_CB<0>")
	)
	(segment
		(start 48.304958 -234.669584)
		(end 47.833026 -235.141516)
		(width 0.18288)
		(layer "In11.Cu")
		(net "M_D_CPU1_SB_CB<0>")
	)
	(segment
		(start 42.31513 -235.000292)
		(end 41.711372 -234.396534)
		(width 0.18288)
		(layer "In11.Cu")
		(net "M_D_CPU1_SB_CB<0>")
	)
	(segment
		(start 72.601582 -241.798094)
		(end 67.96278 -237.159292)
		(width 0.18288)
		(layer "In11.Cu")
		(net "M_D_CPU1_SB_CB<0>")
	)
	(segment
		(start 36.793424 -234.155234)
		(end 36.657026 -234.291632)
		(width 0.18288)
		(layer "In11.Cu")
		(net "M_D_CPU1_SB_CB<0>")
	)
	(segment
		(start 93.046296 -243.607082)
		(end 93.031564 -243.598446)
		(width 0.088646)
		(layer "In11.Cu")
		(net "M_D_CPU1_SB_CB<0>")
	)
	(segment
		(start 64.06261 -234.91571)
		(end 62.999112 -234.91571)
		(width 0.18288)
		(layer "In11.Cu")
		(net "M_D_CPU1_SB_CB<0>")
	)
	(segment
		(start 85.057996 -242.793266)
		(end 85.043264 -242.78463)
		(width 0.088646)
		(layer "In11.Cu")
		(net "M_D_CPU1_SB_CB<0>")
	)
	(segment
		(start 98.483166 -243.922804)
		(end 98.450146 -243.890038)
		(width 0.088646)
		(layer "In11.Cu")
		(net "M_D_CPU1_SB_CB<0>")
	)
	(segment
		(start 24.525986 -235.828586)
		(end 21.554186 -235.828586)
		(width 0.18288)
		(layer "In11.Cu")
		(net "M_D_CPU1_SB_CB<0>")
	)
	(segment
		(start 44.40428 -235.285026)
		(end 44.119546 -235.000292)
		(width 0.18288)
		(layer "In11.Cu")
		(net "M_D_CPU1_SB_CB<0>")
	)
	(segment
		(start 30.82417 -235.742226)
		(end 29.722826 -235.742226)
		(width 0.18288)
		(layer "In11.Cu")
		(net "M_D_CPU1_SB_CB<0>")
	)
	(segment
		(start 51.97729 -234.011216)
		(end 51.69662 -234.291886)
		(width 0.18288)
		(layer "In11.Cu")
		(net "M_D_CPU1_SB_CB<0>")
	)
	(segment
		(start 25.238964 -236.541564)
		(end 24.525986 -235.828586)
		(width 0.18288)
		(layer "In11.Cu")
		(net "M_D_CPU1_SB_CB<0>")
	)
	(segment
		(start 66.640202 -236.611414)
		(end 65.758314 -236.611414)
		(width 0.18288)
		(layer "In11.Cu")
		(net "M_D_CPU1_SB_CB<0>")
	)
	(segment
		(start 58.856626 -234.472226)
		(end 55.986172 -234.472226)
		(width 0.18288)
		(layer "In11.Cu")
		(net "M_D_CPU1_SB_CB<0>")
	)
	(segment
		(start 62.999112 -234.91571)
		(end 62.761876 -235.152946)
		(width 0.18288)
		(layer "In11.Cu")
		(net "M_D_CPU1_SB_CB<0>")
	)
	(segment
		(start 19.128486 -234.700826)
		(end 17.655032 -234.700826)
		(width 0.18288)
		(layer "In11.Cu")
		(net "M_D_CPU1_SB_CB<0>")
	)
	(segment
		(start 28.923488 -236.541564)
		(end 25.238964 -236.541564)
		(width 0.18288)
		(layer "In11.Cu")
		(net "M_D_CPU1_SB_CB<0>")
	)
	(segment
		(start 47.833026 -235.141516)
		(end 46.096936 -235.141516)
		(width 0.18288)
		(layer "In11.Cu")
		(net "M_D_CPU1_SB_CB<0>")
	)
	(segment
		(start 49.39919 -234.291632)
		(end 49.021238 -234.669584)
		(width 0.18288)
		(layer "In11.Cu")
		(net "M_D_CPU1_SB_CB<0>")
	)
	(segment
		(start 82.596482 -241.798094)
		(end 72.601582 -241.798094)
		(width 0.18288)
		(layer "In11.Cu")
		(net "M_D_CPU1_SB_CB<0>")
	)
	(segment
		(start 21.554186 -235.828586)
		(end 21.39188 -235.990892)
		(width 0.18288)
		(layer "In11.Cu")
		(net "M_D_CPU1_SB_CB<0>")
	)
	(segment
		(start 90.226896 -243.607082)
		(end 90.212164 -243.598446)
		(width 0.088646)
		(layer "In11.Cu")
		(net "M_D_CPU1_SB_CB<0>")
	)
	(segment
		(start 60.279026 -234.192826)
		(end 59.136026 -234.192826)
		(width 0.18288)
		(layer "In11.Cu")
		(net "M_D_CPU1_SB_CB<0>")
	)
	(segment
		(start 67.96278 -237.159292)
		(end 66.640202 -236.611414)
		(width 0.18288)
		(layer "In11.Cu")
		(net "M_D_CPU1_SB_CB<0>")
	)
	(segment
		(start 59.136026 -234.192826)
		(end 58.856626 -234.472226)
		(width 0.18288)
		(layer "In11.Cu")
		(net "M_D_CPU1_SB_CB<0>")
	)
	(segment
		(start 83.238594 -242.440206)
		(end 82.596482 -241.798094)
		(width 0.18288)
		(layer "In11.Cu")
		(net "M_D_CPU1_SB_CB<0>")
	)
	(segment
		(start 83.717384 -242.440206)
		(end 83.673696 -242.440206)
		(width 0.088646)
		(layer "In11.Cu")
		(net "M_D_CPU1_SB_CB<0>")
	)
	(segment
		(start 36.657026 -234.291632)
		(end 34.235136 -234.291632)
		(width 0.18288)
		(layer "In11.Cu")
		(net "M_D_CPU1_SB_CB<0>")
	)
	(segment
		(start 88.347296 -243.607082)
		(end 88.332564 -243.598446)
		(width 0.088646)
		(layer "In11.Cu")
		(net "M_D_CPU1_SB_CB<0>")
	)
	(segment
		(start 86.170516 -243.124482)
		(end 86.170516 -243.108988)
		(width 0.088646)
		(layer "In11.Cu")
		(net "M_D_CPU1_SB_CB<0>")
	)
	(segment
		(start 41.711372 -234.396534)
		(end 40.574468 -234.396534)
		(width 0.18288)
		(layer "In11.Cu")
		(net "M_D_CPU1_SB_CB<0>")
	)
	(segment
		(start 93.981778 -243.604542)
		(end 93.971364 -243.598446)
		(width 0.088646)
		(layer "In11.Cu")
		(net "M_D_CPU1_SB_CB<0>")
	)
	(segment
		(start 55.986172 -234.472226)
		(end 55.525162 -234.011216)
		(width 0.18288)
		(layer "In11.Cu")
		(net "M_D_CPU1_SB_CB<0>")
	)
	(segment
		(start 51.010058 -234.291886)
		(end 51.009804 -234.291632)
		(width 0.18288)
		(layer "In11.Cu")
		(net "M_D_CPU1_SB_CB<0>")
	)
	(segment
		(start 45.953426 -235.285026)
		(end 44.40428 -235.285026)
		(width 0.18288)
		(layer "In11.Cu")
		(net "M_D_CPU1_SB_CB<0>")
	)
	(segment
		(start 84.385912 -242.860576)
		(end 84.137754 -242.860576)
		(width 0.088646)
		(layer "In11.Cu")
		(net "M_D_CPU1_SB_CB<0>")
	)
	(segment
		(start 21.39188 -235.990892)
		(end 20.418552 -235.990892)
		(width 0.18288)
		(layer "In11.Cu")
		(net "M_D_CPU1_SB_CB<0>")
	)
	(segment
		(start 29.722826 -235.742226)
		(end 28.923488 -236.541564)
		(width 0.18288)
		(layer "In11.Cu")
		(net "M_D_CPU1_SB_CB<0>")
	)
	(segment
		(start 44.119546 -235.000292)
		(end 42.31513 -235.000292)
		(width 0.18288)
		(layer "In11.Cu")
		(net "M_D_CPU1_SB_CB<0>")
	)
	(segment
		(start 87.958168 -243.598446)
		(end 87.947754 -243.604542)
		(width 0.088646)
		(layer "In11.Cu")
		(net "M_D_CPU1_SB_CB<0>")
	)
	(segment
		(start 51.69662 -234.291886)
		(end 51.010058 -234.291886)
		(width 0.18288)
		(layer "In11.Cu")
		(net "M_D_CPU1_SB_CB<0>")
	)
	(segment
		(start 31.424626 -235.14177)
		(end 30.82417 -235.742226)
		(width 0.18288)
		(layer "In11.Cu")
		(net "M_D_CPU1_SB_CB<0>")
	)
	(segment
		(start 95.865696 -243.607082)
		(end 95.850964 -243.598446)
		(width 0.088646)
		(layer "In11.Cu")
		(net "M_D_CPU1_SB_CB<0>")
	)
	(segment
		(start 46.096936 -235.141516)
		(end 45.953426 -235.285026)
		(width 0.18288)
		(layer "In11.Cu")
		(net "M_D_CPU1_SB_CB<0>")
	)
	(segment
		(start 17.655032 -234.700826)
		(end 16.789146 -235.566712)
		(width 0.18288)
		(layer "In11.Cu")
		(net "M_D_CPU1_SB_CB<0>")
	)
	(segment
		(start 85.991954 -242.78971)
		(end 85.983064 -242.78463)
		(width 0.088646)
		(layer "In11.Cu")
		(net "M_D_CPU1_SB_CB<0>")
	)
	(segment
		(start 94.921324 -243.604542)
		(end 94.91091 -243.598446)
		(width 0.088646)
		(layer "In11.Cu")
		(net "M_D_CPU1_SB_CB<0>")
	)
	(segment
		(start 51.009804 -234.291632)
		(end 49.39919 -234.291632)
		(width 0.18288)
		(layer "In11.Cu")
		(net "M_D_CPU1_SB_CB<0>")
	)
	(segment
		(start 61.239146 -235.152946)
		(end 60.279026 -234.192826)
		(width 0.18288)
		(layer "In11.Cu")
		(net "M_D_CPU1_SB_CB<0>")
	)
	(segment
		(start 89.287096 -243.607082)
		(end 89.272364 -243.598446)
		(width 0.088646)
		(layer "In11.Cu")
		(net "M_D_CPU1_SB_CB<0>")
	)
	(segment
		(start 62.761876 -235.152946)
		(end 61.239146 -235.152946)
		(width 0.18288)
		(layer "In11.Cu")
		(net "M_D_CPU1_SB_CB<0>")
	)
	(segment
		(start 34.235136 -234.291632)
		(end 33.385252 -235.14177)
		(width 0.18288)
		(layer "In11.Cu")
		(net "M_D_CPU1_SB_CB<0>")
	)
	(segment
		(start 20.418552 -235.990892)
		(end 19.128486 -234.700826)
		(width 0.18288)
		(layer "In11.Cu")
		(net "M_D_CPU1_SB_CB<0>")
	)
	(segment
		(start 49.021238 -234.669584)
		(end 48.304958 -234.669584)
		(width 0.18288)
		(layer "In11.Cu")
		(net "M_D_CPU1_SB_CB<0>")
	)
	(segment
		(start 83.673696 -242.440206)
		(end 83.238594 -242.440206)
		(width 0.18288)
		(layer "In11.Cu")
		(net "M_D_CPU1_SB_CB<0>")
	)
	(segment
		(start 84.137754 -242.860576)
		(end 83.717384 -242.440206)
		(width 0.088646)
		(layer "In11.Cu")
		(net "M_D_CPU1_SB_CB<0>")
	)
	(segment
		(start 33.385252 -235.14177)
		(end 31.424626 -235.14177)
		(width 0.18288)
		(layer "In11.Cu")
		(net "M_D_CPU1_SB_CB<0>")
	)
	(segment
		(start 55.525162 -234.011216)
		(end 51.97729 -234.011216)
		(width 0.18288)
		(layer "In11.Cu")
		(net "M_D_CPU1_SB_CB<0>")
	)
	(segment
		(start 65.758314 -236.611414)
		(end 64.06261 -234.91571)
		(width 0.18288)
		(layer "In11.Cu")
		(net "M_D_CPU1_SB_CB<0>")
	)
	(segment
		(start 92.106496 -243.607082)
		(end 92.091764 -243.598446)
		(width 0.088646)
		(layer "In11.Cu")
		(net "M_D_CPU1_SB_CB<0>")
	)
	(segment
		(start 40.574468 -234.396534)
		(end 40.333168 -234.155234)
		(width 0.18288)
		(layer "In11.Cu")
		(net "M_D_CPU1_SB_CB<0>")
	)
	(segment
		(start 87.018114 -243.598446)
		(end 87.003382 -243.607082)
		(width 0.088646)
		(layer "In11.Cu")
		(net "M_D_CPU1_SB_CB<0>")
	)
	(segment
		(start 96.805496 -243.607082)
		(end 96.790764 -243.598446)
		(width 0.088646)
		(layer "In11.Cu")
		(net "M_D_CPU1_SB_CB<0>")
	)
	(arc
		(start 92.091764 -243.598446)
		(mid 91.904566 -243.548303)
		(end 91.717368 -243.598446)
		(width 0.088646)
		(layer "In11.Cu")
		(net "M_D_CPU1_SB_CB<0>")
	)
	(arc
		(start 92.657168 -243.598446)
		(mid 92.382969 -243.674281)
		(end 92.106496 -243.607082)
		(width 0.088646)
		(layer "In11.Cu")
		(net "M_D_CPU1_SB_CB<0>")
	)
	(arc
		(start 93.031564 -243.598446)
		(mid 92.844366 -243.548303)
		(end 92.657168 -243.598446)
		(width 0.088646)
		(layer "In11.Cu")
		(net "M_D_CPU1_SB_CB<0>")
	)
	(arc
		(start 87.947754 -243.604542)
		(mid 87.669322 -243.674388)
		(end 87.39251 -243.598446)
		(width 0.088646)
		(layer "In11.Cu")
		(net "M_D_CPU1_SB_CB<0>")
	)
	(arc
		(start 89.272364 -243.598446)
		(mid 89.085166 -243.548303)
		(end 88.897968 -243.598446)
		(width 0.088646)
		(layer "In11.Cu")
		(net "M_D_CPU1_SB_CB<0>")
	)
	(arc
		(start 90.777568 -243.598446)
		(mid 90.503369 -243.674281)
		(end 90.226896 -243.607082)
		(width 0.088646)
		(layer "In11.Cu")
		(net "M_D_CPU1_SB_CB<0>")
	)
	(arc
		(start 89.837768 -243.598446)
		(mid 89.563569 -243.674281)
		(end 89.287096 -243.607082)
		(width 0.088646)
		(layer "In11.Cu")
		(net "M_D_CPU1_SB_CB<0>")
	)
	(arc
		(start 97.730564 -243.598446)
		(mid 97.543366 -243.548303)
		(end 97.356168 -243.598446)
		(width 0.088646)
		(layer "In11.Cu")
		(net "M_D_CPU1_SB_CB<0>")
	)
	(arc
		(start 93.971364 -243.598446)
		(mid 93.784166 -243.548303)
		(end 93.596968 -243.598446)
		(width 0.088646)
		(layer "In11.Cu")
		(net "M_D_CPU1_SB_CB<0>")
	)
	(arc
		(start 88.332564 -243.598446)
		(mid 88.145366 -243.548303)
		(end 87.958168 -243.598446)
		(width 0.088646)
		(layer "In11.Cu")
		(net "M_D_CPU1_SB_CB<0>")
	)
	(arc
		(start 86.170516 -243.108988)
		(mid 86.122837 -242.926088)
		(end 85.991954 -242.78971)
		(width 0.088646)
		(layer "In11.Cu")
		(net "M_D_CPU1_SB_CB<0>")
	)
	(arc
		(start 85.608668 -242.78463)
		(mid 85.334439 -242.860555)
		(end 85.057996 -242.793266)
		(width 0.088646)
		(layer "In11.Cu")
		(net "M_D_CPU1_SB_CB<0>")
	)
	(arc
		(start 96.790764 -243.598446)
		(mid 96.603566 -243.548303)
		(end 96.416368 -243.598446)
		(width 0.088646)
		(layer "In11.Cu")
		(net "M_D_CPU1_SB_CB<0>")
	)
	(arc
		(start 87.003382 -243.607082)
		(mid 86.726907 -243.674402)
		(end 86.45271 -243.598446)
		(width 0.088646)
		(layer "In11.Cu")
		(net "M_D_CPU1_SB_CB<0>")
	)
	(arc
		(start 94.91091 -243.598446)
		(mid 94.723712 -243.548303)
		(end 94.536514 -243.598446)
		(width 0.088646)
		(layer "In11.Cu")
		(net "M_D_CPU1_SB_CB<0>")
	)
	(arc
		(start 97.973896 -243.672868)
		(mid 97.847984 -243.649536)
		(end 97.730564 -243.598446)
		(width 0.088646)
		(layer "In11.Cu")
		(net "M_D_CPU1_SB_CB<0>")
	)
	(arc
		(start 85.983064 -242.78463)
		(mid 85.795866 -242.734487)
		(end 85.608668 -242.78463)
		(width 0.088646)
		(layer "In11.Cu")
		(net "M_D_CPU1_SB_CB<0>")
	)
	(arc
		(start 95.850964 -243.598446)
		(mid 95.663766 -243.548303)
		(end 95.476568 -243.598446)
		(width 0.088646)
		(layer "In11.Cu")
		(net "M_D_CPU1_SB_CB<0>")
	)
	(arc
		(start 98.450146 -243.890038)
		(mid 98.231657 -243.738388)
		(end 97.973896 -243.672868)
		(width 0.088646)
		(layer "In11.Cu")
		(net "M_D_CPU1_SB_CB<0>")
	)
	(arc
		(start 93.596968 -243.598446)
		(mid 93.322769 -243.674281)
		(end 93.046296 -243.607082)
		(width 0.088646)
		(layer "In11.Cu")
		(net "M_D_CPU1_SB_CB<0>")
	)
	(arc
		(start 84.668868 -242.78463)
		(mid 84.532395 -242.841264)
		(end 84.385912 -242.860576)
		(width 0.088646)
		(layer "In11.Cu")
		(net "M_D_CPU1_SB_CB<0>")
	)
	(arc
		(start 97.356168 -243.598446)
		(mid 97.081969 -243.674281)
		(end 96.805496 -243.607082)
		(width 0.088646)
		(layer "In11.Cu")
		(net "M_D_CPU1_SB_CB<0>")
	)
	(arc
		(start 96.416368 -243.598446)
		(mid 96.142169 -243.674281)
		(end 95.865696 -243.607082)
		(width 0.088646)
		(layer "In11.Cu")
		(net "M_D_CPU1_SB_CB<0>")
	)
	(arc
		(start 85.043264 -242.78463)
		(mid 84.856066 -242.734487)
		(end 84.668868 -242.78463)
		(width 0.088646)
		(layer "In11.Cu")
		(net "M_D_CPU1_SB_CB<0>")
	)
	(arc
		(start 90.212164 -243.598446)
		(mid 90.024966 -243.548303)
		(end 89.837768 -243.598446)
		(width 0.088646)
		(layer "In11.Cu")
		(net "M_D_CPU1_SB_CB<0>")
	)
	(arc
		(start 88.897968 -243.598446)
		(mid 88.623769 -243.674281)
		(end 88.347296 -243.607082)
		(width 0.088646)
		(layer "In11.Cu")
		(net "M_D_CPU1_SB_CB<0>")
	)
	(arc
		(start 91.151964 -243.598446)
		(mid 90.964766 -243.548303)
		(end 90.777568 -243.598446)
		(width 0.088646)
		(layer "In11.Cu")
		(net "M_D_CPU1_SB_CB<0>")
	)
	(arc
		(start 87.39251 -243.598446)
		(mid 87.205312 -243.548303)
		(end 87.018114 -243.598446)
		(width 0.088646)
		(layer "In11.Cu")
		(net "M_D_CPU1_SB_CB<0>")
	)
	(arc
		(start 94.536514 -243.598446)
		(mid 94.259955 -243.674189)
		(end 93.981778 -243.604542)
		(width 0.088646)
		(layer "In11.Cu")
		(net "M_D_CPU1_SB_CB<0>")
	)
	(arc
		(start 91.717368 -243.598446)
		(mid 91.434666 -243.674222)
		(end 91.151964 -243.598446)
		(width 0.088646)
		(layer "In11.Cu")
		(net "M_D_CPU1_SB_CB<0>")
	)
	(arc
		(start 95.476568 -243.598446)
		(mid 95.199755 -243.674316)
		(end 94.921324 -243.604542)
		(width 0.088646)
		(layer "In11.Cu")
		(net "M_D_CPU1_SB_CB<0>")
	)
	(arc
		(start 86.45271 -243.598446)
		(mid 86.249887 -243.398215)
		(end 86.170516 -243.124482)
		(width 0.088646)
		(layer "In11.Cu")
		(net "M_D_CPU1_SB_CB<0>")
	)
	(segment
		(start 14.04493 -247.466612)
		(end 15.684246 -247.466612)
		(width 0.20066)
		(layer "F.Cu")
		(net "M_D_CPU1_SB_CA<6>")
	)
	(segment
		(start 13.110718 -247.04167)
		(end 13.441426 -247.04167)
		(width 0.101854)
		(layer "F.Cu")
		(net "M_D_CPU1_SB_CA<6>")
	)
	(segment
		(start 9.686036 -247.67794)
		(end 10.19048 -247.67794)
		(width 0.20066)
		(layer "F.Cu")
		(net "M_D_CPU1_SB_CA<6>")
	)
	(segment
		(start 8.140446 -247.466612)
		(end 9.474708 -247.466612)
		(width 0.20066)
		(layer "F.Cu")
		(net "M_D_CPU1_SB_CA<6>")
	)
	(segment
		(start 11.1252 -247.04167)
		(end 13.110718 -247.04167)
		(width 0.1016)
		(layer "F.Cu")
		(net "M_D_CPU1_SB_CA<6>")
	)
	(segment
		(start 94.723712 -247.714262)
		(end 94.723712 -247.178576)
		(width 0.20066)
		(layer "F.Cu")
		(net "M_D_CPU1_SB_CA<6>")
	)
	(segment
		(start 13.441426 -247.04167)
		(end 13.619988 -247.04167)
		(width 0.20066)
		(layer "F.Cu")
		(net "M_D_CPU1_SB_CA<6>")
	)
	(segment
		(start 16.789146 -247.466612)
		(end 15.684246 -247.466612)
		(width 0.20066)
		(layer "F.Cu")
		(net "M_D_CPU1_SB_CA<6>")
	)
	(segment
		(start 10.344912 -247.19534)
		(end 10.507472 -247.03278)
		(width 0.20066)
		(layer "F.Cu")
		(net "M_D_CPU1_SB_CA<6>")
	)
	(segment
		(start 94.723712 -247.178576)
		(end 94.723966 -247.178322)
		(width 0.20066)
		(layer "F.Cu")
		(net "M_D_CPU1_SB_CA<6>")
	)
	(segment
		(start 10.344912 -247.523508)
		(end 10.344912 -247.19534)
		(width 0.20066)
		(layer "F.Cu")
		(net "M_D_CPU1_SB_CA<6>")
	)
	(segment
		(start 13.619988 -247.04167)
		(end 14.04493 -247.466612)
		(width 0.20066)
		(layer "F.Cu")
		(net "M_D_CPU1_SB_CA<6>")
	)
	(segment
		(start 11.11631 -247.03278)
		(end 11.1252 -247.04167)
		(width 0.1016)
		(layer "F.Cu")
		(net "M_D_CPU1_SB_CA<6>")
	)
	(segment
		(start 10.507472 -247.03278)
		(end 11.11631 -247.03278)
		(width 0.20066)
		(layer "F.Cu")
		(net "M_D_CPU1_SB_CA<6>")
	)
	(segment
		(start 10.19048 -247.67794)
		(end 10.344912 -247.523508)
		(width 0.20066)
		(layer "F.Cu")
		(net "M_D_CPU1_SB_CA<6>")
	)
	(segment
		(start 9.474708 -247.466612)
		(end 9.686036 -247.67794)
		(width 0.20066)
		(layer "F.Cu")
		(net "M_D_CPU1_SB_CA<6>")
	)
	(segment
		(start 17.956276 -246.179086)
		(end 17.642332 -246.179086)
		(width 0.18288)
		(layer "In11.Cu")
		(net "M_D_CPU1_SB_CA<6>")
	)
	(segment
		(start 18.850356 -246.372126)
		(end 18.850356 -246.83593)
		(width 0.18288)
		(layer "In11.Cu")
		(net "M_D_CPU1_SB_CA<6>")
	)
	(segment
		(start 80.483202 -246.600472)
		(end 68.412106 -246.600472)
		(width 0.18288)
		(layer "In11.Cu")
		(net "M_D_CPU1_SB_CA<6>")
	)
	(segment
		(start 53.023008 -246.788432)
		(end 53.023008 -247.156986)
		(width 0.18288)
		(layer "In11.Cu")
		(net "M_D_CPU1_SB_CA<6>")
	)
	(segment
		(start 18.149316 -246.83593)
		(end 18.149316 -246.372126)
		(width 0.18288)
		(layer "In11.Cu")
		(net "M_D_CPU1_SB_CA<6>")
	)
	(segment
		(start 90.222324 -247.496584)
		(end 90.21191 -247.50268)
		(width 0.088646)
		(layer "In11.Cu")
		(net "M_D_CPU1_SB_CA<6>")
	)
	(segment
		(start 36.935664 -247.041162)
		(end 34.494978 -247.041162)
		(width 0.18288)
		(layer "In11.Cu")
		(net "M_D_CPU1_SB_CA<6>")
	)
	(segment
		(start 53.023008 -247.156986)
		(end 52.829968 -247.350026)
		(width 0.18288)
		(layer "In11.Cu")
		(net "M_D_CPU1_SB_CA<6>")
	)
	(segment
		(start 89.837514 -247.50268)
		(end 89.8271 -247.496584)
		(width 0.088646)
		(layer "In11.Cu")
		(net "M_D_CPU1_SB_CA<6>")
	)
	(segment
		(start 94.25178 -247.419622)
		(end 94.163896 -247.433846)
		(width 0.088646)
		(layer "In11.Cu")
		(net "M_D_CPU1_SB_CA<6>")
	)
	(segment
		(start 44.191682 -247.159018)
		(end 43.866308 -246.833644)
		(width 0.18288)
		(layer "In11.Cu")
		(net "M_D_CPU1_SB_CA<6>")
	)
	(segment
		(start 17.642332 -246.179086)
		(end 17.630648 -246.19077)
		(width 0.18288)
		(layer "In11.Cu")
		(net "M_D_CPU1_SB_CA<6>")
	)
	(segment
		(start 18.850356 -246.83593)
		(end 18.657316 -247.02897)
		(width 0.18288)
		(layer "In11.Cu")
		(net "M_D_CPU1_SB_CA<6>")
	)
	(segment
		(start 83.979004 -247.307862)
		(end 83.979004 -247.211596)
		(width 0.088646)
		(layer "In11.Cu")
		(net "M_D_CPU1_SB_CA<6>")
	)
	(segment
		(start 18.342356 -247.02897)
		(end 18.149316 -246.83593)
		(width 0.18288)
		(layer "In11.Cu")
		(net "M_D_CPU1_SB_CA<6>")
	)
	(segment
		(start 29.608526 -247.223026)
		(end 29.252926 -246.867426)
		(width 0.18288)
		(layer "In11.Cu")
		(net "M_D_CPU1_SB_CA<6>")
	)
	(segment
		(start 34.291524 -246.837708)
		(end 33.355534 -246.837708)
		(width 0.18288)
		(layer "In11.Cu")
		(net "M_D_CPU1_SB_CA<6>")
	)
	(segment
		(start 17.312894 -246.942864)
		(end 16.789146 -247.466612)
		(width 0.18288)
		(layer "In11.Cu")
		(net "M_D_CPU1_SB_CA<6>")
	)
	(segment
		(start 40.754808 -246.833644)
		(end 40.473376 -247.115076)
		(width 0.18288)
		(layer "In11.Cu")
		(net "M_D_CPU1_SB_CA<6>")
	)
	(segment
		(start 33.15208 -247.041162)
		(end 30.71749 -247.041162)
		(width 0.18288)
		(layer "In11.Cu")
		(net "M_D_CPU1_SB_CA<6>")
	)
	(segment
		(start 45.622464 -247.159018)
		(end 44.191682 -247.159018)
		(width 0.18288)
		(layer "In11.Cu")
		(net "M_D_CPU1_SB_CA<6>")
	)
	(segment
		(start 83.979004 -247.211596)
		(end 83.88096 -247.113552)
		(width 0.088646)
		(layer "In11.Cu")
		(net "M_D_CPU1_SB_CA<6>")
	)
	(segment
		(start 66.44386 -244.632226)
		(end 63.154306 -244.632226)
		(width 0.18288)
		(layer "In11.Cu")
		(net "M_D_CPU1_SB_CA<6>")
	)
	(segment
		(start 93.986096 -247.494044)
		(end 93.971364 -247.50268)
		(width 0.088646)
		(layer "In11.Cu")
		(net "M_D_CPU1_SB_CA<6>")
	)
	(segment
		(start 53.216048 -246.595392)
		(end 53.023008 -246.788432)
		(width 0.18288)
		(layer "In11.Cu")
		(net "M_D_CPU1_SB_CA<6>")
	)
	(segment
		(start 63.154306 -244.632226)
		(end 62.283086 -245.503446)
		(width 0.18288)
		(layer "In11.Cu")
		(net "M_D_CPU1_SB_CA<6>")
	)
	(segment
		(start 43.866308 -246.833644)
		(end 40.754808 -246.833644)
		(width 0.18288)
		(layer "In11.Cu")
		(net "M_D_CPU1_SB_CA<6>")
	)
	(segment
		(start 17.571974 -246.19077)
		(end 17.312894 -246.44985)
		(width 0.18288)
		(layer "In11.Cu")
		(net "M_D_CPU1_SB_CA<6>")
	)
	(segment
		(start 58.876946 -246.433086)
		(end 55.518558 -246.433086)
		(width 0.18288)
		(layer "In11.Cu")
		(net "M_D_CPU1_SB_CA<6>")
	)
	(segment
		(start 24.858726 -246.867426)
		(end 24.604726 -247.121426)
		(width 0.18288)
		(layer "In11.Cu")
		(net "M_D_CPU1_SB_CA<6>")
	)
	(segment
		(start 20.445476 -246.189246)
		(end 20.252436 -246.382286)
		(width 0.18288)
		(layer "In11.Cu")
		(net "M_D_CPU1_SB_CA<6>")
	)
	(segment
		(start 30.71749 -247.041162)
		(end 30.535626 -247.223026)
		(width 0.18288)
		(layer "In11.Cu")
		(net "M_D_CPU1_SB_CA<6>")
	)
	(segment
		(start 53.724048 -247.156986)
		(end 53.724048 -246.788432)
		(width 0.18288)
		(layer "In11.Cu")
		(net "M_D_CPU1_SB_CA<6>")
	)
	(segment
		(start 83.88096 -247.113552)
		(end 83.673696 -247.113552)
		(width 0.088646)
		(layer "In11.Cu")
		(net "M_D_CPU1_SB_CA<6>")
	)
	(segment
		(start 18.657316 -247.02897)
		(end 18.342356 -247.02897)
		(width 0.18288)
		(layer "In11.Cu")
		(net "M_D_CPU1_SB_CA<6>")
	)
	(segment
		(start 40.473376 -247.115076)
		(end 37.009578 -247.115076)
		(width 0.18288)
		(layer "In11.Cu")
		(net "M_D_CPU1_SB_CA<6>")
	)
	(segment
		(start 68.412106 -246.600472)
		(end 66.44386 -244.632226)
		(width 0.18288)
		(layer "In11.Cu")
		(net "M_D_CPU1_SB_CA<6>")
	)
	(segment
		(start 88.347296 -247.494044)
		(end 88.332564 -247.50268)
		(width 0.088646)
		(layer "In11.Cu")
		(net "M_D_CPU1_SB_CA<6>")
	)
	(segment
		(start 23.240746 -246.189246)
		(end 20.445476 -246.189246)
		(width 0.18288)
		(layer "In11.Cu")
		(net "M_D_CPU1_SB_CA<6>")
	)
	(segment
		(start 80.996282 -247.113552)
		(end 80.483202 -246.600472)
		(width 0.18288)
		(layer "In11.Cu")
		(net "M_D_CPU1_SB_CA<6>")
	)
	(segment
		(start 24.604726 -247.121426)
		(end 24.172926 -247.121426)
		(width 0.18288)
		(layer "In11.Cu")
		(net "M_D_CPU1_SB_CA<6>")
	)
	(segment
		(start 59.806586 -245.503446)
		(end 58.876946 -246.433086)
		(width 0.18288)
		(layer "In11.Cu")
		(net "M_D_CPU1_SB_CA<6>")
	)
	(segment
		(start 92.101924 -247.496584)
		(end 92.09151 -247.50268)
		(width 0.088646)
		(layer "In11.Cu")
		(net "M_D_CPU1_SB_CA<6>")
	)
	(segment
		(start 93.046296 -247.494044)
		(end 93.031564 -247.50268)
		(width 0.088646)
		(layer "In11.Cu")
		(net "M_D_CPU1_SB_CA<6>")
	)
	(segment
		(start 91.717114 -247.50268)
		(end 91.7067 -247.496584)
		(width 0.088646)
		(layer "In11.Cu")
		(net "M_D_CPU1_SB_CA<6>")
	)
	(segment
		(start 55.518558 -246.433086)
		(end 54.601618 -247.350026)
		(width 0.18288)
		(layer "In11.Cu")
		(net "M_D_CPU1_SB_CA<6>")
	)
	(segment
		(start 19.551396 -247.178576)
		(end 19.551396 -246.372126)
		(width 0.18288)
		(layer "In11.Cu")
		(net "M_D_CPU1_SB_CA<6>")
	)
	(segment
		(start 18.149316 -246.372126)
		(end 17.956276 -246.179086)
		(width 0.18288)
		(layer "In11.Cu")
		(net "M_D_CPU1_SB_CA<6>")
	)
	(segment
		(start 20.05076 -247.371616)
		(end 19.744436 -247.371616)
		(width 0.18288)
		(layer "In11.Cu")
		(net "M_D_CPU1_SB_CA<6>")
	)
	(segment
		(start 84.224368 -247.553226)
		(end 83.979004 -247.307862)
		(width 0.088646)
		(layer "In11.Cu")
		(net "M_D_CPU1_SB_CA<6>")
	)
	(segment
		(start 17.312894 -246.44985)
		(end 17.312894 -246.942864)
		(width 0.18288)
		(layer "In11.Cu")
		(net "M_D_CPU1_SB_CA<6>")
	)
	(segment
		(start 62.283086 -245.503446)
		(end 59.806586 -245.503446)
		(width 0.18288)
		(layer "In11.Cu")
		(net "M_D_CPU1_SB_CA<6>")
	)
	(segment
		(start 83.673696 -247.113552)
		(end 80.996282 -247.113552)
		(width 0.18288)
		(layer "In11.Cu")
		(net "M_D_CPU1_SB_CA<6>")
	)
	(segment
		(start 54.601618 -247.350026)
		(end 53.917088 -247.350026)
		(width 0.18288)
		(layer "In11.Cu")
		(net "M_D_CPU1_SB_CA<6>")
	)
	(segment
		(start 52.079144 -247.350026)
		(end 51.767486 -247.038368)
		(width 0.18288)
		(layer "In11.Cu")
		(net "M_D_CPU1_SB_CA<6>")
	)
	(segment
		(start 19.358356 -246.179086)
		(end 19.043396 -246.179086)
		(width 0.18288)
		(layer "In11.Cu")
		(net "M_D_CPU1_SB_CA<6>")
	)
	(segment
		(start 84.386166 -247.553226)
		(end 84.224368 -247.553226)
		(width 0.088646)
		(layer "In11.Cu")
		(net "M_D_CPU1_SB_CA<6>")
	)
	(segment
		(start 20.252436 -246.382286)
		(end 20.252436 -247.16994)
		(width 0.18288)
		(layer "In11.Cu")
		(net "M_D_CPU1_SB_CA<6>")
	)
	(segment
		(start 34.494978 -247.041162)
		(end 34.291524 -246.837708)
		(width 0.18288)
		(layer "In11.Cu")
		(net "M_D_CPU1_SB_CA<6>")
	)
	(segment
		(start 19.043396 -246.179086)
		(end 18.850356 -246.372126)
		(width 0.18288)
		(layer "In11.Cu")
		(net "M_D_CPU1_SB_CA<6>")
	)
	(segment
		(start 29.252926 -246.867426)
		(end 24.858726 -246.867426)
		(width 0.18288)
		(layer "In11.Cu")
		(net "M_D_CPU1_SB_CA<6>")
	)
	(segment
		(start 24.172926 -247.121426)
		(end 23.240746 -246.189246)
		(width 0.18288)
		(layer "In11.Cu")
		(net "M_D_CPU1_SB_CA<6>")
	)
	(segment
		(start 52.829968 -247.350026)
		(end 52.079144 -247.350026)
		(width 0.18288)
		(layer "In11.Cu")
		(net "M_D_CPU1_SB_CA<6>")
	)
	(segment
		(start 33.355534 -246.837708)
		(end 33.15208 -247.041162)
		(width 0.18288)
		(layer "In11.Cu")
		(net "M_D_CPU1_SB_CA<6>")
	)
	(segment
		(start 53.531008 -246.595392)
		(end 53.216048 -246.595392)
		(width 0.18288)
		(layer "In11.Cu")
		(net "M_D_CPU1_SB_CA<6>")
	)
	(segment
		(start 53.724048 -246.788432)
		(end 53.531008 -246.595392)
		(width 0.18288)
		(layer "In11.Cu")
		(net "M_D_CPU1_SB_CA<6>")
	)
	(segment
		(start 30.535626 -247.223026)
		(end 29.608526 -247.223026)
		(width 0.18288)
		(layer "In11.Cu")
		(net "M_D_CPU1_SB_CA<6>")
	)
	(segment
		(start 45.743114 -247.038368)
		(end 45.622464 -247.159018)
		(width 0.18288)
		(layer "In11.Cu")
		(net "M_D_CPU1_SB_CA<6>")
	)
	(segment
		(start 19.551396 -246.372126)
		(end 19.358356 -246.179086)
		(width 0.18288)
		(layer "In11.Cu")
		(net "M_D_CPU1_SB_CA<6>")
	)
	(segment
		(start 37.009578 -247.115076)
		(end 36.935664 -247.041162)
		(width 0.18288)
		(layer "In11.Cu")
		(net "M_D_CPU1_SB_CA<6>")
	)
	(segment
		(start 20.252436 -247.16994)
		(end 20.05076 -247.371616)
		(width 0.18288)
		(layer "In11.Cu")
		(net "M_D_CPU1_SB_CA<6>")
	)
	(segment
		(start 51.767486 -247.038368)
		(end 45.743114 -247.038368)
		(width 0.18288)
		(layer "In11.Cu")
		(net "M_D_CPU1_SB_CA<6>")
	)
	(segment
		(start 17.630648 -246.19077)
		(end 17.571974 -246.19077)
		(width 0.18288)
		(layer "In11.Cu")
		(net "M_D_CPU1_SB_CA<6>")
	)
	(segment
		(start 53.917088 -247.350026)
		(end 53.724048 -247.156986)
		(width 0.18288)
		(layer "In11.Cu")
		(net "M_D_CPU1_SB_CA<6>")
	)
	(segment
		(start 19.744436 -247.371616)
		(end 19.551396 -247.178576)
		(width 0.18288)
		(layer "In11.Cu")
		(net "M_D_CPU1_SB_CA<6>")
	)
	(arc
		(start 93.596968 -247.50268)
		(mid 93.322769 -247.426845)
		(end 93.046296 -247.494044)
		(width 0.088646)
		(layer "In11.Cu")
		(net "M_D_CPU1_SB_CA<6>")
	)
	(arc
		(start 85.513164 -247.50268)
		(mid 85.325966 -247.552823)
		(end 85.138768 -247.50268)
		(width 0.088646)
		(layer "In11.Cu")
		(net "M_D_CPU1_SB_CA<6>")
	)
	(arc
		(start 93.971364 -247.50268)
		(mid 93.784166 -247.552823)
		(end 93.596968 -247.50268)
		(width 0.088646)
		(layer "In11.Cu")
		(net "M_D_CPU1_SB_CA<6>")
	)
	(arc
		(start 93.031564 -247.50268)
		(mid 92.844366 -247.552823)
		(end 92.657168 -247.50268)
		(width 0.088646)
		(layer "In11.Cu")
		(net "M_D_CPU1_SB_CA<6>")
	)
	(arc
		(start 85.138768 -247.50268)
		(mid 84.856066 -247.426904)
		(end 84.573364 -247.50268)
		(width 0.088646)
		(layer "In11.Cu")
		(net "M_D_CPU1_SB_CA<6>")
	)
	(arc
		(start 91.151964 -247.50268)
		(mid 90.964766 -247.552823)
		(end 90.777568 -247.50268)
		(width 0.088646)
		(layer "In11.Cu")
		(net "M_D_CPU1_SB_CA<6>")
	)
	(arc
		(start 86.452964 -247.50268)
		(mid 86.265766 -247.552823)
		(end 86.078568 -247.50268)
		(width 0.088646)
		(layer "In11.Cu")
		(net "M_D_CPU1_SB_CA<6>")
	)
	(arc
		(start 84.573364 -247.50268)
		(mid 84.483092 -247.540279)
		(end 84.386166 -247.553226)
		(width 0.088646)
		(layer "In11.Cu")
		(net "M_D_CPU1_SB_CA<6>")
	)
	(arc
		(start 94.723966 -247.178322)
		(mid 94.506894 -247.336189)
		(end 94.25178 -247.419622)
		(width 0.088646)
		(layer "In11.Cu")
		(net "M_D_CPU1_SB_CA<6>")
	)
	(arc
		(start 91.7067 -247.496584)
		(mid 91.428522 -247.426861)
		(end 91.151964 -247.50268)
		(width 0.088646)
		(layer "In11.Cu")
		(net "M_D_CPU1_SB_CA<6>")
	)
	(arc
		(start 88.897968 -247.50268)
		(mid 88.623769 -247.426845)
		(end 88.347296 -247.494044)
		(width 0.088646)
		(layer "In11.Cu")
		(net "M_D_CPU1_SB_CA<6>")
	)
	(arc
		(start 87.018368 -247.50268)
		(mid 86.735666 -247.426904)
		(end 86.452964 -247.50268)
		(width 0.088646)
		(layer "In11.Cu")
		(net "M_D_CPU1_SB_CA<6>")
	)
	(arc
		(start 86.078568 -247.50268)
		(mid 85.795866 -247.426904)
		(end 85.513164 -247.50268)
		(width 0.088646)
		(layer "In11.Cu")
		(net "M_D_CPU1_SB_CA<6>")
	)
	(arc
		(start 92.09151 -247.50268)
		(mid 91.904312 -247.552823)
		(end 91.717114 -247.50268)
		(width 0.088646)
		(layer "In11.Cu")
		(net "M_D_CPU1_SB_CA<6>")
	)
	(arc
		(start 89.272364 -247.50268)
		(mid 89.085166 -247.552823)
		(end 88.897968 -247.50268)
		(width 0.088646)
		(layer "In11.Cu")
		(net "M_D_CPU1_SB_CA<6>")
	)
	(arc
		(start 92.657168 -247.50268)
		(mid 92.380355 -247.42681)
		(end 92.101924 -247.496584)
		(width 0.088646)
		(layer "In11.Cu")
		(net "M_D_CPU1_SB_CA<6>")
	)
	(arc
		(start 90.777568 -247.50268)
		(mid 90.500755 -247.42681)
		(end 90.222324 -247.496584)
		(width 0.088646)
		(layer "In11.Cu")
		(net "M_D_CPU1_SB_CA<6>")
	)
	(arc
		(start 89.8271 -247.496584)
		(mid 89.548922 -247.426861)
		(end 89.272364 -247.50268)
		(width 0.088646)
		(layer "In11.Cu")
		(net "M_D_CPU1_SB_CA<6>")
	)
	(arc
		(start 87.958168 -247.50268)
		(mid 87.675466 -247.426904)
		(end 87.392764 -247.50268)
		(width 0.088646)
		(layer "In11.Cu")
		(net "M_D_CPU1_SB_CA<6>")
	)
	(arc
		(start 87.392764 -247.50268)
		(mid 87.205566 -247.552823)
		(end 87.018368 -247.50268)
		(width 0.088646)
		(layer "In11.Cu")
		(net "M_D_CPU1_SB_CA<6>")
	)
	(arc
		(start 88.332564 -247.50268)
		(mid 88.145366 -247.552823)
		(end 87.958168 -247.50268)
		(width 0.088646)
		(layer "In11.Cu")
		(net "M_D_CPU1_SB_CA<6>")
	)
	(arc
		(start 90.21191 -247.50268)
		(mid 90.024712 -247.552823)
		(end 89.837514 -247.50268)
		(width 0.088646)
		(layer "In11.Cu")
		(net "M_D_CPU1_SB_CA<6>")
	)
	(arc
		(start 94.163896 -247.433846)
		(mid 94.07248 -247.456514)
		(end 93.986096 -247.494044)
		(width 0.088646)
		(layer "In11.Cu")
		(net "M_D_CPU1_SB_CA<6>")
	)
	(segment
		(start 18.968212 -248.31675)
		(end 19.784314 -248.31675)
		(width 0.20066)
		(layer "F.Cu")
		(net "M_D_CPU1_SB_CA<5>")
	)
	(segment
		(start 12.240514 -248.31675)
		(end 13.937742 -248.31675)
		(width 0.20066)
		(layer "F.Cu")
		(net "M_D_CPU1_SB_CA<5>")
	)
	(segment
		(start 14.560042 -248.755916)
		(end 14.574266 -248.741692)
		(width 0.101854)
		(layer "F.Cu")
		(net "M_D_CPU1_SB_CA<5>")
	)
	(segment
		(start 17.42948 -248.741692)
		(end 17.578578 -248.592594)
		(width 0.20066)
		(layer "F.Cu")
		(net "M_D_CPU1_SB_CA<5>")
	)
	(segment
		(start 18.102326 -248.312432)
		(end 18.314162 -248.524268)
		(width 0.20066)
		(layer "F.Cu")
		(net "M_D_CPU1_SB_CA<5>")
	)
	(segment
		(start 14.574266 -248.741692)
		(end 14.812264 -248.741692)
		(width 0.101854)
		(layer "F.Cu")
		(net "M_D_CPU1_SB_CA<5>")
	)
	(segment
		(start 20.889214 -248.31675)
		(end 19.784314 -248.31675)
		(width 0.20066)
		(layer "F.Cu")
		(net "M_D_CPU1_SB_CA<5>")
	)
	(segment
		(start 18.314162 -248.524268)
		(end 18.760694 -248.524268)
		(width 0.20066)
		(layer "F.Cu")
		(net "M_D_CPU1_SB_CA<5>")
	)
	(segment
		(start 14.063726 -248.613422)
		(end 14.20622 -248.755916)
		(width 0.20066)
		(layer "F.Cu")
		(net "M_D_CPU1_SB_CA<5>")
	)
	(segment
		(start 17.578578 -248.440956)
		(end 17.707102 -248.312432)
		(width 0.20066)
		(layer "F.Cu")
		(net "M_D_CPU1_SB_CA<5>")
	)
	(segment
		(start 14.20622 -248.755916)
		(end 14.560042 -248.755916)
		(width 0.20066)
		(layer "F.Cu")
		(net "M_D_CPU1_SB_CA<5>")
	)
	(segment
		(start 14.063726 -248.442734)
		(end 14.063726 -248.613422)
		(width 0.20066)
		(layer "F.Cu")
		(net "M_D_CPU1_SB_CA<5>")
	)
	(segment
		(start 14.812264 -248.741692)
		(end 16.885158 -248.741692)
		(width 0.1016)
		(layer "F.Cu")
		(net "M_D_CPU1_SB_CA<5>")
	)
	(segment
		(start 18.760694 -248.524268)
		(end 18.968212 -248.31675)
		(width 0.20066)
		(layer "F.Cu")
		(net "M_D_CPU1_SB_CA<5>")
	)
	(segment
		(start 17.578578 -248.592594)
		(end 17.578578 -248.440956)
		(width 0.20066)
		(layer "F.Cu")
		(net "M_D_CPU1_SB_CA<5>")
	)
	(segment
		(start 97.073466 -248.528078)
		(end 97.073212 -248.527824)
		(width 0.20066)
		(layer "F.Cu")
		(net "M_D_CPU1_SB_CA<5>")
	)
	(segment
		(start 97.073212 -248.527824)
		(end 97.073212 -247.992138)
		(width 0.20066)
		(layer "F.Cu")
		(net "M_D_CPU1_SB_CA<5>")
	)
	(segment
		(start 17.707102 -248.312432)
		(end 18.102326 -248.312432)
		(width 0.20066)
		(layer "F.Cu")
		(net "M_D_CPU1_SB_CA<5>")
	)
	(segment
		(start 16.885158 -248.741692)
		(end 17.42948 -248.741692)
		(width 0.20066)
		(layer "F.Cu")
		(net "M_D_CPU1_SB_CA<5>")
	)
	(segment
		(start 13.937742 -248.31675)
		(end 14.063726 -248.442734)
		(width 0.20066)
		(layer "F.Cu")
		(net "M_D_CPU1_SB_CA<5>")
	)
	(segment
		(start 30.263084 -248.706386)
		(end 30.070044 -248.899426)
		(width 0.18288)
		(layer "In11.Cu")
		(net "M_D_CPU1_SB_CA<5>")
	)
	(segment
		(start 94.777306 -247.843548)
		(end 94.736412 -247.884442)
		(width 0.088646)
		(layer "In11.Cu")
		(net "M_D_CPU1_SB_CA<5>")
	)
	(segment
		(start 30.771084 -248.290842)
		(end 30.456124 -248.290842)
		(width 0.18288)
		(layer "In11.Cu")
		(net "M_D_CPU1_SB_CA<5>")
	)
	(segment
		(start 34.338006 -248.707656)
		(end 33.334198 -248.707656)
		(width 0.18288)
		(layer "In11.Cu")
		(net "M_D_CPU1_SB_CA<5>")
	)
	(segment
		(start 30.070044 -248.899426)
		(end 29.220668 -248.899426)
		(width 0.18288)
		(layer "In11.Cu")
		(net "M_D_CPU1_SB_CA<5>")
	)
	(segment
		(start 83.87207 -247.86717)
		(end 83.67395 -247.86717)
		(width 0.088646)
		(layer "In11.Cu")
		(net "M_D_CPU1_SB_CA<5>")
	)
	(segment
		(start 30.456124 -248.290842)
		(end 30.263084 -248.483882)
		(width 0.18288)
		(layer "In11.Cu")
		(net "M_D_CPU1_SB_CA<5>")
	)
	(segment
		(start 90.307414 -248.316496)
		(end 90.297 -248.3104)
		(width 0.088646)
		(layer "In11.Cu")
		(net "M_D_CPU1_SB_CA<5>")
	)
	(segment
		(start 63.11392 -246.460772)
		(end 62.308486 -247.266206)
		(width 0.18288)
		(layer "In11.Cu")
		(net "M_D_CPU1_SB_CA<5>")
	)
	(segment
		(start 49.60493 -248.74093)
		(end 49.382426 -248.518426)
		(width 0.18288)
		(layer "In11.Cu")
		(net "M_D_CPU1_SB_CA<5>")
	)
	(segment
		(start 58.018934 -248.011696)
		(end 57.825894 -247.818656)
		(width 0.18288)
		(layer "In11.Cu")
		(net "M_D_CPU1_SB_CA<5>")
	)
	(segment
		(start 30.964124 -248.483882)
		(end 30.771084 -248.290842)
		(width 0.18288)
		(layer "In11.Cu")
		(net "M_D_CPU1_SB_CA<5>")
	)
	(segment
		(start 22.930612 -248.782586)
		(end 22.737572 -248.975626)
		(width 0.18288)
		(layer "In11.Cu")
		(net "M_D_CPU1_SB_CA<5>")
	)
	(segment
		(start 49.382426 -248.518426)
		(end 48.182784 -248.518426)
		(width 0.18288)
		(layer "In11.Cu")
		(net "M_D_CPU1_SB_CA<5>")
	)
	(segment
		(start 53.360828 -248.403872)
		(end 53.167788 -248.596912)
		(width 0.18288)
		(layer "In11.Cu")
		(net "M_D_CPU1_SB_CA<5>")
	)
	(segment
		(start 52.317142 -248.907046)
		(end 52.151026 -248.74093)
		(width 0.18288)
		(layer "In11.Cu")
		(net "M_D_CPU1_SB_CA<5>")
	)
	(segment
		(start 23.631652 -248.462546)
		(end 23.438612 -248.269506)
		(width 0.18288)
		(layer "In11.Cu")
		(net "M_D_CPU1_SB_CA<5>")
	)
	(segment
		(start 32.30372 -248.741184)
		(end 31.570168 -248.741184)
		(width 0.18288)
		(layer "In11.Cu")
		(net "M_D_CPU1_SB_CA<5>")
	)
	(segment
		(start 21.54809 -248.975626)
		(end 20.889214 -248.31675)
		(width 0.18288)
		(layer "In11.Cu")
		(net "M_D_CPU1_SB_CA<5>")
	)
	(segment
		(start 22.737572 -248.975626)
		(end 21.54809 -248.975626)
		(width 0.18288)
		(layer "In11.Cu")
		(net "M_D_CPU1_SB_CA<5>")
	)
	(segment
		(start 89.367868 -248.316496)
		(end 89.357454 -248.3104)
		(width 0.088646)
		(layer "In11.Cu")
		(net "M_D_CPU1_SB_CA<5>")
	)
	(segment
		(start 41.94302 -248.943876)
		(end 41.94302 -248.849388)
		(width 0.18288)
		(layer "In11.Cu")
		(net "M_D_CPU1_SB_CA<5>")
	)
	(segment
		(start 74.82205 -247.309386)
		(end 74.051414 -248.080022)
		(width 0.18288)
		(layer "In11.Cu")
		(net "M_D_CPU1_SB_CA<5>")
	)
	(segment
		(start 30.964124 -248.706386)
		(end 30.964124 -248.483882)
		(width 0.18288)
		(layer "In11.Cu")
		(net "M_D_CPU1_SB_CA<5>")
	)
	(segment
		(start 53.868828 -248.714006)
		(end 53.868828 -248.596912)
		(width 0.18288)
		(layer "In11.Cu")
		(net "M_D_CPU1_SB_CA<5>")
	)
	(segment
		(start 53.675788 -248.403872)
		(end 53.360828 -248.403872)
		(width 0.18288)
		(layer "In11.Cu")
		(net "M_D_CPU1_SB_CA<5>")
	)
	(segment
		(start 45.742098 -248.221754)
		(end 45.549058 -248.414794)
		(width 0.18288)
		(layer "In11.Cu")
		(net "M_D_CPU1_SB_CA<5>")
	)
	(segment
		(start 42.45102 -249.136916)
		(end 42.13606 -249.136916)
		(width 0.18288)
		(layer "In11.Cu")
		(net "M_D_CPU1_SB_CA<5>")
	)
	(segment
		(start 55.578756 -248.011696)
		(end 54.683406 -248.907046)
		(width 0.18288)
		(layer "In11.Cu")
		(net "M_D_CPU1_SB_CA<5>")
	)
	(segment
		(start 35.232086 -248.548144)
		(end 35.232086 -248.314972)
		(width 0.18288)
		(layer "In11.Cu")
		(net "M_D_CPU1_SB_CA<5>")
	)
	(segment
		(start 33.334198 -248.707656)
		(end 33.00476 -249.037094)
		(width 0.18288)
		(layer "In11.Cu")
		(net "M_D_CPU1_SB_CA<5>")
	)
	(segment
		(start 48.182784 -248.518426)
		(end 47.960026 -248.741184)
		(width 0.18288)
		(layer "In11.Cu")
		(net "M_D_CPU1_SB_CA<5>")
	)
	(segment
		(start 84.023708 -248.018808)
		(end 83.87207 -247.86717)
		(width 0.088646)
		(layer "In11.Cu")
		(net "M_D_CPU1_SB_CA<5>")
	)
	(segment
		(start 60.734194 -247.776746)
		(end 59.674506 -247.776746)
		(width 0.18288)
		(layer "In11.Cu")
		(net "M_D_CPU1_SB_CA<5>")
	)
	(segment
		(start 74.051414 -248.080022)
		(end 68.13931 -248.080022)
		(width 0.18288)
		(layer "In11.Cu")
		(net "M_D_CPU1_SB_CA<5>")
	)
	(segment
		(start 94.450154 -248.311416)
		(end 94.441264 -248.316496)
		(width 0.088646)
		(layer "In11.Cu")
		(net "M_D_CPU1_SB_CA<5>")
	)
	(segment
		(start 23.824692 -248.975626)
		(end 23.631652 -248.782586)
		(width 0.18288)
		(layer "In11.Cu")
		(net "M_D_CPU1_SB_CA<5>")
	)
	(segment
		(start 83.67395 -247.86717)
		(end 80.772508 -247.86717)
		(width 0.18288)
		(layer "In11.Cu")
		(net "M_D_CPU1_SB_CA<5>")
	)
	(segment
		(start 44.97705 -248.874026)
		(end 44.257468 -248.874026)
		(width 0.18288)
		(layer "In11.Cu")
		(net "M_D_CPU1_SB_CA<5>")
	)
	(segment
		(start 80.772508 -247.86717)
		(end 80.214724 -247.309386)
		(width 0.18288)
		(layer "In11.Cu")
		(net "M_D_CPU1_SB_CA<5>")
	)
	(segment
		(start 28.997148 -248.675906)
		(end 28.14193 -248.675906)
		(width 0.18288)
		(layer "In11.Cu")
		(net "M_D_CPU1_SB_CA<5>")
	)
	(segment
		(start 22.930612 -248.462546)
		(end 22.930612 -248.782586)
		(width 0.18288)
		(layer "In11.Cu")
		(net "M_D_CPU1_SB_CA<5>")
	)
	(segment
		(start 26.344118 -248.594626)
		(end 25.390094 -248.594626)
		(width 0.18288)
		(layer "In11.Cu")
		(net "M_D_CPU1_SB_CA<5>")
	)
	(segment
		(start 35.039046 -248.121932)
		(end 34.724086 -248.121932)
		(width 0.18288)
		(layer "In11.Cu")
		(net "M_D_CPU1_SB_CA<5>")
	)
	(segment
		(start 54.061868 -248.907046)
		(end 53.868828 -248.714006)
		(width 0.18288)
		(layer "In11.Cu")
		(net "M_D_CPU1_SB_CA<5>")
	)
	(segment
		(start 95.946468 -247.66778)
		(end 95.936054 -247.673876)
		(width 0.088646)
		(layer "In11.Cu")
		(net "M_D_CPU1_SB_CA<5>")
	)
	(segment
		(start 56.931814 -248.011696)
		(end 55.578756 -248.011696)
		(width 0.18288)
		(layer "In11.Cu")
		(net "M_D_CPU1_SB_CA<5>")
	)
	(segment
		(start 92.187014 -248.316496)
		(end 92.1766 -248.3104)
		(width 0.088646)
		(layer "In11.Cu")
		(net "M_D_CPU1_SB_CA<5>")
	)
	(segment
		(start 53.167788 -248.714006)
		(end 52.974748 -248.907046)
		(width 0.18288)
		(layer "In11.Cu")
		(net "M_D_CPU1_SB_CA<5>")
	)
	(segment
		(start 42.8371 -248.656348)
		(end 42.64406 -248.849388)
		(width 0.18288)
		(layer "In11.Cu")
		(net "M_D_CPU1_SB_CA<5>")
	)
	(segment
		(start 66.52006 -246.460772)
		(end 63.11392 -246.460772)
		(width 0.18288)
		(layer "In11.Cu")
		(net "M_D_CPU1_SB_CA<5>")
	)
	(segment
		(start 88.427814 -248.316496)
		(end 88.4174 -248.3104)
		(width 0.088646)
		(layer "In11.Cu")
		(net "M_D_CPU1_SB_CA<5>")
	)
	(segment
		(start 45.356018 -248.741184)
		(end 45.109892 -248.741184)
		(width 0.18288)
		(layer "In11.Cu")
		(net "M_D_CPU1_SB_CA<5>")
	)
	(segment
		(start 41.94302 -248.849388)
		(end 41.74998 -248.656348)
		(width 0.18288)
		(layer "In11.Cu")
		(net "M_D_CPU1_SB_CA<5>")
	)
	(segment
		(start 31.411926 -248.899426)
		(end 31.157164 -248.899426)
		(width 0.18288)
		(layer "In11.Cu")
		(net "M_D_CPU1_SB_CA<5>")
	)
	(segment
		(start 39.679626 -248.874026)
		(end 36.637468 -248.874026)
		(width 0.18288)
		(layer "In11.Cu")
		(net "M_D_CPU1_SB_CA<5>")
	)
	(segment
		(start 23.123652 -248.269506)
		(end 22.930612 -248.462546)
		(width 0.18288)
		(layer "In11.Cu")
		(net "M_D_CPU1_SB_CA<5>")
	)
	(segment
		(start 80.214724 -247.309386)
		(end 74.82205 -247.309386)
		(width 0.18288)
		(layer "In11.Cu")
		(net "M_D_CPU1_SB_CA<5>")
	)
	(segment
		(start 42.64406 -248.849388)
		(end 42.64406 -248.943876)
		(width 0.18288)
		(layer "In11.Cu")
		(net "M_D_CPU1_SB_CA<5>")
	)
	(segment
		(start 59.674506 -247.776746)
		(end 59.439556 -248.011696)
		(width 0.18288)
		(layer "In11.Cu")
		(net "M_D_CPU1_SB_CA<5>")
	)
	(segment
		(start 31.157164 -248.899426)
		(end 30.964124 -248.706386)
		(width 0.18288)
		(layer "In11.Cu")
		(net "M_D_CPU1_SB_CA<5>")
	)
	(segment
		(start 39.897304 -248.656348)
		(end 39.679626 -248.874026)
		(width 0.18288)
		(layer "In11.Cu")
		(net "M_D_CPU1_SB_CA<5>")
	)
	(segment
		(start 42.64406 -248.943876)
		(end 42.45102 -249.136916)
		(width 0.18288)
		(layer "In11.Cu")
		(net "M_D_CPU1_SB_CA<5>")
	)
	(segment
		(start 97.073212 -247.992138)
		(end 97.229676 -247.72112)
		(width 0.088646)
		(layer "In11.Cu")
		(net "M_D_CPU1_SB_CA<5>")
	)
	(segment
		(start 47.960026 -248.741184)
		(end 46.443138 -248.741184)
		(width 0.18288)
		(layer "In11.Cu")
		(net "M_D_CPU1_SB_CA<5>")
	)
	(segment
		(start 45.109892 -248.741184)
		(end 44.97705 -248.874026)
		(width 0.18288)
		(layer "In11.Cu")
		(net "M_D_CPU1_SB_CA<5>")
	)
	(segment
		(start 25.009094 -248.975626)
		(end 23.824692 -248.975626)
		(width 0.18288)
		(layer "In11.Cu")
		(net "M_D_CPU1_SB_CA<5>")
	)
	(segment
		(start 42.13606 -249.136916)
		(end 41.94302 -248.943876)
		(width 0.18288)
		(layer "In11.Cu")
		(net "M_D_CPU1_SB_CA<5>")
	)
	(segment
		(start 41.74998 -248.656348)
		(end 39.897304 -248.656348)
		(width 0.18288)
		(layer "In11.Cu")
		(net "M_D_CPU1_SB_CA<5>")
	)
	(segment
		(start 33.00476 -249.037094)
		(end 32.59963 -249.037094)
		(width 0.18288)
		(layer "In11.Cu")
		(net "M_D_CPU1_SB_CA<5>")
	)
	(segment
		(start 94.441264 -248.316496)
		(end 94.44101 -248.316496)
		(width 0.088646)
		(layer "In11.Cu")
		(net "M_D_CPU1_SB_CA<5>")
	)
	(segment
		(start 59.439556 -248.011696)
		(end 58.018934 -248.011696)
		(width 0.18288)
		(layer "In11.Cu")
		(net "M_D_CPU1_SB_CA<5>")
	)
	(segment
		(start 23.631652 -248.782586)
		(end 23.631652 -248.462546)
		(width 0.18288)
		(layer "In11.Cu")
		(net "M_D_CPU1_SB_CA<5>")
	)
	(segment
		(start 30.263084 -248.483882)
		(end 30.263084 -248.706386)
		(width 0.18288)
		(layer "In11.Cu")
		(net "M_D_CPU1_SB_CA<5>")
	)
	(segment
		(start 57.825894 -247.694704)
		(end 57.632854 -247.501664)
		(width 0.18288)
		(layer "In11.Cu")
		(net "M_D_CPU1_SB_CA<5>")
	)
	(segment
		(start 25.390094 -248.594626)
		(end 25.009094 -248.975626)
		(width 0.18288)
		(layer "In11.Cu")
		(net "M_D_CPU1_SB_CA<5>")
	)
	(segment
		(start 53.868828 -248.596912)
		(end 53.675788 -248.403872)
		(width 0.18288)
		(layer "In11.Cu")
		(net "M_D_CPU1_SB_CA<5>")
	)
	(segment
		(start 28.14193 -248.675906)
		(end 27.51836 -249.299476)
		(width 0.18288)
		(layer "In11.Cu")
		(net "M_D_CPU1_SB_CA<5>")
	)
	(segment
		(start 46.250098 -248.414794)
		(end 46.057058 -248.221754)
		(width 0.18288)
		(layer "In11.Cu")
		(net "M_D_CPU1_SB_CA<5>")
	)
	(segment
		(start 96.331278 -247.673876)
		(end 96.320864 -247.66778)
		(width 0.088646)
		(layer "In11.Cu")
		(net "M_D_CPU1_SB_CA<5>")
	)
	(segment
		(start 34.531046 -248.314972)
		(end 34.531046 -248.514616)
		(width 0.18288)
		(layer "In11.Cu")
		(net "M_D_CPU1_SB_CA<5>")
	)
	(segment
		(start 31.570168 -248.741184)
		(end 31.411926 -248.899426)
		(width 0.18288)
		(layer "In11.Cu")
		(net "M_D_CPU1_SB_CA<5>")
	)
	(segment
		(start 36.637468 -248.874026)
		(end 36.504626 -248.741184)
		(width 0.18288)
		(layer "In11.Cu")
		(net "M_D_CPU1_SB_CA<5>")
	)
	(segment
		(start 45.549058 -248.414794)
		(end 45.549058 -248.548144)
		(width 0.18288)
		(layer "In11.Cu")
		(net "M_D_CPU1_SB_CA<5>")
	)
	(segment
		(start 57.124854 -247.694704)
		(end 57.124854 -247.818656)
		(width 0.18288)
		(layer "In11.Cu")
		(net "M_D_CPU1_SB_CA<5>")
	)
	(segment
		(start 46.250098 -248.548144)
		(end 46.250098 -248.414794)
		(width 0.18288)
		(layer "In11.Cu")
		(net "M_D_CPU1_SB_CA<5>")
	)
	(segment
		(start 52.974748 -248.907046)
		(end 52.317142 -248.907046)
		(width 0.18288)
		(layer "In11.Cu")
		(net "M_D_CPU1_SB_CA<5>")
	)
	(segment
		(start 46.057058 -248.221754)
		(end 45.742098 -248.221754)
		(width 0.18288)
		(layer "In11.Cu")
		(net "M_D_CPU1_SB_CA<5>")
	)
	(segment
		(start 68.13931 -248.080022)
		(end 66.52006 -246.460772)
		(width 0.18288)
		(layer "In11.Cu")
		(net "M_D_CPU1_SB_CA<5>")
	)
	(segment
		(start 61.244734 -247.266206)
		(end 60.734194 -247.776746)
		(width 0.18288)
		(layer "In11.Cu")
		(net "M_D_CPU1_SB_CA<5>")
	)
	(segment
		(start 57.124854 -247.818656)
		(end 56.931814 -248.011696)
		(width 0.18288)
		(layer "In11.Cu")
		(net "M_D_CPU1_SB_CA<5>")
	)
	(segment
		(start 35.425126 -248.741184)
		(end 35.232086 -248.548144)
		(width 0.18288)
		(layer "In11.Cu")
		(net "M_D_CPU1_SB_CA<5>")
	)
	(segment
		(start 29.220668 -248.899426)
		(end 28.997148 -248.675906)
		(width 0.18288)
		(layer "In11.Cu")
		(net "M_D_CPU1_SB_CA<5>")
	)
	(segment
		(start 54.683406 -248.907046)
		(end 54.061868 -248.907046)
		(width 0.18288)
		(layer "In11.Cu")
		(net "M_D_CPU1_SB_CA<5>")
	)
	(segment
		(start 35.232086 -248.314972)
		(end 35.039046 -248.121932)
		(width 0.18288)
		(layer "In11.Cu")
		(net "M_D_CPU1_SB_CA<5>")
	)
	(segment
		(start 44.03979 -248.656348)
		(end 42.8371 -248.656348)
		(width 0.18288)
		(layer "In11.Cu")
		(net "M_D_CPU1_SB_CA<5>")
	)
	(segment
		(start 84.352384 -248.018808)
		(end 84.023708 -248.018808)
		(width 0.088646)
		(layer "In11.Cu")
		(net "M_D_CPU1_SB_CA<5>")
	)
	(segment
		(start 53.167788 -248.596912)
		(end 53.167788 -248.714006)
		(width 0.18288)
		(layer "In11.Cu")
		(net "M_D_CPU1_SB_CA<5>")
	)
	(segment
		(start 52.151026 -248.74093)
		(end 49.60493 -248.74093)
		(width 0.18288)
		(layer "In11.Cu")
		(net "M_D_CPU1_SB_CA<5>")
	)
	(segment
		(start 36.504626 -248.741184)
		(end 35.425126 -248.741184)
		(width 0.18288)
		(layer "In11.Cu")
		(net "M_D_CPU1_SB_CA<5>")
	)
	(segment
		(start 27.51836 -249.299476)
		(end 27.048968 -249.299476)
		(width 0.18288)
		(layer "In11.Cu")
		(net "M_D_CPU1_SB_CA<5>")
	)
	(segment
		(start 27.048968 -249.299476)
		(end 26.344118 -248.594626)
		(width 0.18288)
		(layer "In11.Cu")
		(net "M_D_CPU1_SB_CA<5>")
	)
	(segment
		(start 57.317894 -247.501664)
		(end 57.124854 -247.694704)
		(width 0.18288)
		(layer "In11.Cu")
		(net "M_D_CPU1_SB_CA<5>")
	)
	(segment
		(start 94.066614 -248.316496)
		(end 94.051882 -248.30786)
		(width 0.088646)
		(layer "In11.Cu")
		(net "M_D_CPU1_SB_CA<5>")
	)
	(segment
		(start 34.724086 -248.121932)
		(end 34.531046 -248.314972)
		(width 0.18288)
		(layer "In11.Cu")
		(net "M_D_CPU1_SB_CA<5>")
	)
	(segment
		(start 45.549058 -248.548144)
		(end 45.356018 -248.741184)
		(width 0.18288)
		(layer "In11.Cu")
		(net "M_D_CPU1_SB_CA<5>")
	)
	(segment
		(start 57.632854 -247.501664)
		(end 57.317894 -247.501664)
		(width 0.18288)
		(layer "In11.Cu")
		(net "M_D_CPU1_SB_CA<5>")
	)
	(segment
		(start 46.443138 -248.741184)
		(end 46.250098 -248.548144)
		(width 0.18288)
		(layer "In11.Cu")
		(net "M_D_CPU1_SB_CA<5>")
	)
	(segment
		(start 97.229676 -247.72112)
		(end 97.208594 -247.643142)
		(width 0.088646)
		(layer "In11.Cu")
		(net "M_D_CPU1_SB_CA<5>")
	)
	(segment
		(start 62.308486 -247.266206)
		(end 61.244734 -247.266206)
		(width 0.18288)
		(layer "In11.Cu")
		(net "M_D_CPU1_SB_CA<5>")
	)
	(segment
		(start 44.257468 -248.874026)
		(end 44.03979 -248.656348)
		(width 0.18288)
		(layer "In11.Cu")
		(net "M_D_CPU1_SB_CA<5>")
	)
	(segment
		(start 57.825894 -247.818656)
		(end 57.825894 -247.694704)
		(width 0.18288)
		(layer "In11.Cu")
		(net "M_D_CPU1_SB_CA<5>")
	)
	(segment
		(start 23.438612 -248.269506)
		(end 23.123652 -248.269506)
		(width 0.18288)
		(layer "In11.Cu")
		(net "M_D_CPU1_SB_CA<5>")
	)
	(segment
		(start 34.531046 -248.514616)
		(end 34.338006 -248.707656)
		(width 0.18288)
		(layer "In11.Cu")
		(net "M_D_CPU1_SB_CA<5>")
	)
	(segment
		(start 93.126814 -248.316496)
		(end 93.112082 -248.30786)
		(width 0.088646)
		(layer "In11.Cu")
		(net "M_D_CPU1_SB_CA<5>")
	)
	(segment
		(start 91.247468 -248.316496)
		(end 91.237054 -248.3104)
		(width 0.088646)
		(layer "In11.Cu")
		(net "M_D_CPU1_SB_CA<5>")
	)
	(segment
		(start 32.59963 -249.037094)
		(end 32.30372 -248.741184)
		(width 0.18288)
		(layer "In11.Cu")
		(net "M_D_CPU1_SB_CA<5>")
	)
	(segment
		(start 84.59089 -248.257314)
		(end 84.352384 -248.018808)
		(width 0.088646)
		(layer "In11.Cu")
		(net "M_D_CPU1_SB_CA<5>")
	)
	(arc
		(start 88.80221 -248.316496)
		(mid 88.615012 -248.366639)
		(end 88.427814 -248.316496)
		(width 0.088646)
		(layer "In11.Cu")
		(net "M_D_CPU1_SB_CA<5>")
	)
	(arc
		(start 94.615 -248.092468)
		(mid 94.553294 -248.217532)
		(end 94.450154 -248.311416)
		(width 0.088646)
		(layer "In11.Cu")
		(net "M_D_CPU1_SB_CA<5>")
	)
	(arc
		(start 89.357454 -248.3104)
		(mid 89.079022 -248.240586)
		(end 88.80221 -248.316496)
		(width 0.088646)
		(layer "In11.Cu")
		(net "M_D_CPU1_SB_CA<5>")
	)
	(arc
		(start 85.608668 -248.316496)
		(mid 85.325966 -248.240754)
		(end 85.043264 -248.316496)
		(width 0.088646)
		(layer "In11.Cu")
		(net "M_D_CPU1_SB_CA<5>")
	)
	(arc
		(start 88.4174 -248.3104)
		(mid 88.139222 -248.240708)
		(end 87.862664 -248.316496)
		(width 0.088646)
		(layer "In11.Cu")
		(net "M_D_CPU1_SB_CA<5>")
	)
	(arc
		(start 93.112082 -248.30786)
		(mid 92.835641 -248.240694)
		(end 92.56141 -248.316496)
		(width 0.088646)
		(layer "In11.Cu")
		(net "M_D_CPU1_SB_CA<5>")
	)
	(arc
		(start 96.320864 -247.66778)
		(mid 96.133666 -247.617637)
		(end 95.946468 -247.66778)
		(width 0.088646)
		(layer "In11.Cu")
		(net "M_D_CPU1_SB_CA<5>")
	)
	(arc
		(start 92.56141 -248.316496)
		(mid 92.374212 -248.366639)
		(end 92.187014 -248.316496)
		(width 0.088646)
		(layer "In11.Cu")
		(net "M_D_CPU1_SB_CA<5>")
	)
	(arc
		(start 89.742264 -248.316496)
		(mid 89.555066 -248.366639)
		(end 89.367868 -248.316496)
		(width 0.088646)
		(layer "In11.Cu")
		(net "M_D_CPU1_SB_CA<5>")
	)
	(arc
		(start 90.68181 -248.316496)
		(mid 90.494612 -248.366639)
		(end 90.307414 -248.316496)
		(width 0.088646)
		(layer "In11.Cu")
		(net "M_D_CPU1_SB_CA<5>")
	)
	(arc
		(start 90.297 -248.3104)
		(mid 90.018822 -248.240708)
		(end 89.742264 -248.316496)
		(width 0.088646)
		(layer "In11.Cu")
		(net "M_D_CPU1_SB_CA<5>")
	)
	(arc
		(start 87.862664 -248.316496)
		(mid 87.675466 -248.366639)
		(end 87.488268 -248.316496)
		(width 0.088646)
		(layer "In11.Cu")
		(net "M_D_CPU1_SB_CA<5>")
	)
	(arc
		(start 95.006414 -247.66778)
		(mid 94.8861 -247.748155)
		(end 94.777306 -247.843548)
		(width 0.088646)
		(layer "In11.Cu")
		(net "M_D_CPU1_SB_CA<5>")
	)
	(arc
		(start 95.38081 -247.66778)
		(mid 95.193612 -247.617637)
		(end 95.006414 -247.66778)
		(width 0.088646)
		(layer "In11.Cu")
		(net "M_D_CPU1_SB_CA<5>")
	)
	(arc
		(start 86.922864 -248.316496)
		(mid 86.735666 -248.366639)
		(end 86.548468 -248.316496)
		(width 0.088646)
		(layer "In11.Cu")
		(net "M_D_CPU1_SB_CA<5>")
	)
	(arc
		(start 85.043264 -248.316496)
		(mid 84.856066 -248.366639)
		(end 84.668868 -248.316496)
		(width 0.088646)
		(layer "In11.Cu")
		(net "M_D_CPU1_SB_CA<5>")
	)
	(arc
		(start 85.983064 -248.316496)
		(mid 85.795866 -248.366639)
		(end 85.608668 -248.316496)
		(width 0.088646)
		(layer "In11.Cu")
		(net "M_D_CPU1_SB_CA<5>")
	)
	(arc
		(start 86.548468 -248.316496)
		(mid 86.265766 -248.240754)
		(end 85.983064 -248.316496)
		(width 0.088646)
		(layer "In11.Cu")
		(net "M_D_CPU1_SB_CA<5>")
	)
	(arc
		(start 87.488268 -248.316496)
		(mid 87.205566 -248.240754)
		(end 86.922864 -248.316496)
		(width 0.088646)
		(layer "In11.Cu")
		(net "M_D_CPU1_SB_CA<5>")
	)
	(arc
		(start 96.886014 -247.66778)
		(mid 96.609455 -247.743523)
		(end 96.331278 -247.673876)
		(width 0.088646)
		(layer "In11.Cu")
		(net "M_D_CPU1_SB_CA<5>")
	)
	(arc
		(start 84.668868 -248.316496)
		(mid 84.627938 -248.289463)
		(end 84.59089 -248.257314)
		(width 0.088646)
		(layer "In11.Cu")
		(net "M_D_CPU1_SB_CA<5>")
	)
	(arc
		(start 93.50121 -248.316496)
		(mid 93.314012 -248.366639)
		(end 93.126814 -248.316496)
		(width 0.088646)
		(layer "In11.Cu")
		(net "M_D_CPU1_SB_CA<5>")
	)
	(arc
		(start 97.208594 -247.643142)
		(mid 97.044498 -247.618795)
		(end 96.886014 -247.66778)
		(width 0.088646)
		(layer "In11.Cu")
		(net "M_D_CPU1_SB_CA<5>")
	)
	(arc
		(start 92.1766 -248.3104)
		(mid 91.898422 -248.240708)
		(end 91.621864 -248.316496)
		(width 0.088646)
		(layer "In11.Cu")
		(net "M_D_CPU1_SB_CA<5>")
	)
	(arc
		(start 94.051882 -248.30786)
		(mid 93.775441 -248.240694)
		(end 93.50121 -248.316496)
		(width 0.088646)
		(layer "In11.Cu")
		(net "M_D_CPU1_SB_CA<5>")
	)
	(arc
		(start 94.736412 -247.884442)
		(mid 94.662268 -247.98061)
		(end 94.615 -248.092468)
		(width 0.088646)
		(layer "In11.Cu")
		(net "M_D_CPU1_SB_CA<5>")
	)
	(arc
		(start 95.936054 -247.673876)
		(mid 95.657622 -247.743722)
		(end 95.38081 -247.66778)
		(width 0.088646)
		(layer "In11.Cu")
		(net "M_D_CPU1_SB_CA<5>")
	)
	(arc
		(start 94.44101 -248.316496)
		(mid 94.253812 -248.366639)
		(end 94.066614 -248.316496)
		(width 0.088646)
		(layer "In11.Cu")
		(net "M_D_CPU1_SB_CA<5>")
	)
	(arc
		(start 91.237054 -248.3104)
		(mid 90.958622 -248.240586)
		(end 90.68181 -248.316496)
		(width 0.088646)
		(layer "In11.Cu")
		(net "M_D_CPU1_SB_CA<5>")
	)
	(arc
		(start 91.621864 -248.316496)
		(mid 91.434666 -248.366639)
		(end 91.247468 -248.316496)
		(width 0.088646)
		(layer "In11.Cu")
		(net "M_D_CPU1_SB_CA<5>")
	)
	(segment
		(start 14.04493 -249.166634)
		(end 15.684246 -249.166634)
		(width 0.20066)
		(layer "F.Cu")
		(net "M_D_CPU1_SB_CA<4>")
	)
	(segment
		(start 10.344912 -248.895362)
		(end 10.507472 -248.732802)
		(width 0.20066)
		(layer "F.Cu")
		(net "M_D_CPU1_SB_CA<4>")
	)
	(segment
		(start 13.619988 -248.741692)
		(end 14.04493 -249.166634)
		(width 0.20066)
		(layer "F.Cu")
		(net "M_D_CPU1_SB_CA<4>")
	)
	(segment
		(start 10.19048 -249.377962)
		(end 10.344912 -249.22353)
		(width 0.20066)
		(layer "F.Cu")
		(net "M_D_CPU1_SB_CA<4>")
	)
	(segment
		(start 11.11631 -248.732802)
		(end 11.1252 -248.741692)
		(width 0.1016)
		(layer "F.Cu")
		(net "M_D_CPU1_SB_CA<4>")
	)
	(segment
		(start 16.789146 -249.166634)
		(end 15.684246 -249.166634)
		(width 0.20066)
		(layer "F.Cu")
		(net "M_D_CPU1_SB_CA<4>")
	)
	(segment
		(start 9.474708 -249.166634)
		(end 9.686036 -249.377962)
		(width 0.20066)
		(layer "F.Cu")
		(net "M_D_CPU1_SB_CA<4>")
	)
	(segment
		(start 13.441426 -248.741692)
		(end 13.619988 -248.741692)
		(width 0.20066)
		(layer "F.Cu")
		(net "M_D_CPU1_SB_CA<4>")
	)
	(segment
		(start 13.110718 -248.741692)
		(end 13.441426 -248.741692)
		(width 0.101854)
		(layer "F.Cu")
		(net "M_D_CPU1_SB_CA<4>")
	)
	(segment
		(start 9.686036 -249.377962)
		(end 10.19048 -249.377962)
		(width 0.20066)
		(layer "F.Cu")
		(net "M_D_CPU1_SB_CA<4>")
	)
	(segment
		(start 8.140446 -249.166634)
		(end 9.474708 -249.166634)
		(width 0.20066)
		(layer "F.Cu")
		(net "M_D_CPU1_SB_CA<4>")
	)
	(segment
		(start 10.344912 -249.22353)
		(end 10.344912 -248.895362)
		(width 0.20066)
		(layer "F.Cu")
		(net "M_D_CPU1_SB_CA<4>")
	)
	(segment
		(start 10.507472 -248.732802)
		(end 11.11631 -248.732802)
		(width 0.20066)
		(layer "F.Cu")
		(net "M_D_CPU1_SB_CA<4>")
	)
	(segment
		(start 95.193866 -248.528078)
		(end 95.193612 -248.527824)
		(width 0.20066)
		(layer "F.Cu")
		(net "M_D_CPU1_SB_CA<4>")
	)
	(segment
		(start 11.1252 -248.741692)
		(end 13.110718 -248.741692)
		(width 0.1016)
		(layer "F.Cu")
		(net "M_D_CPU1_SB_CA<4>")
	)
	(segment
		(start 95.193612 -248.527824)
		(end 95.193612 -247.992138)
		(width 0.20066)
		(layer "F.Cu")
		(net "M_D_CPU1_SB_CA<4>")
	)
	(segment
		(start 55.877206 -248.538746)
		(end 54.975506 -249.440446)
		(width 0.18288)
		(layer "In11.Cu")
		(net "M_D_CPU1_SB_CA<4>")
	)
	(segment
		(start 62.697106 -247.819926)
		(end 61.521086 -247.819926)
		(width 0.18288)
		(layer "In11.Cu")
		(net "M_D_CPU1_SB_CA<4>")
	)
	(segment
		(start 33.452308 -249.712226)
		(end 33.33115 -249.591068)
		(width 0.18288)
		(layer "In11.Cu")
		(net "M_D_CPU1_SB_CA<4>")
	)
	(segment
		(start 57.1119 -248.731786)
		(end 56.91886 -248.538746)
		(width 0.18288)
		(layer "In11.Cu")
		(net "M_D_CPU1_SB_CA<4>")
	)
	(segment
		(start 44.130468 -249.432826)
		(end 43.892724 -249.67057)
		(width 0.18288)
		(layer "In11.Cu")
		(net "M_D_CPU1_SB_CA<4>")
	)
	(segment
		(start 17.987264 -250.570492)
		(end 17.794224 -250.377452)
		(width 0.18288)
		(layer "In11.Cu")
		(net "M_D_CPU1_SB_CA<4>")
	)
	(segment
		(start 92.106496 -248.490486)
		(end 92.091764 -248.48185)
		(width 0.088646)
		(layer "In11.Cu")
		(net "M_D_CPU1_SB_CA<4>")
	)
	(segment
		(start 30.389068 -249.591068)
		(end 30.205426 -249.407426)
		(width 0.18288)
		(layer "In11.Cu")
		(net "M_D_CPU1_SB_CA<4>")
	)
	(segment
		(start 26.53792 -249.704352)
		(end 24.774652 -249.704352)
		(width 0.18288)
		(layer "In11.Cu")
		(net "M_D_CPU1_SB_CA<4>")
	)
	(segment
		(start 33.33115 -249.591068)
		(end 30.389068 -249.591068)
		(width 0.18288)
		(layer "In11.Cu")
		(net "M_D_CPU1_SB_CA<4>")
	)
	(segment
		(start 63.522606 -246.994426)
		(end 62.697106 -247.819926)
		(width 0.18288)
		(layer "In11.Cu")
		(net "M_D_CPU1_SB_CA<4>")
	)
	(segment
		(start 17.794224 -250.377452)
		(end 17.794224 -249.783854)
		(width 0.18288)
		(layer "In11.Cu")
		(net "M_D_CPU1_SB_CA<4>")
	)
	(segment
		(start 19.196304 -249.802904)
		(end 19.003264 -249.609864)
		(width 0.18288)
		(layer "In11.Cu")
		(net "M_D_CPU1_SB_CA<4>")
	)
	(segment
		(start 57.6199 -249.301762)
		(end 57.30494 -249.301762)
		(width 0.18288)
		(layer "In11.Cu")
		(net "M_D_CPU1_SB_CA<4>")
	)
	(segment
		(start 52.055268 -249.440446)
		(end 51.904646 -249.591068)
		(width 0.18288)
		(layer "In11.Cu")
		(net "M_D_CPU1_SB_CA<4>")
	)
	(segment
		(start 74.261726 -248.58853)
		(end 67.898518 -248.58853)
		(width 0.18288)
		(layer "In11.Cu")
		(net "M_D_CPU1_SB_CA<4>")
	)
	(segment
		(start 51.904646 -249.591068)
		(end 49.427384 -249.591068)
		(width 0.18288)
		(layer "In11.Cu")
		(net "M_D_CPU1_SB_CA<4>")
	)
	(segment
		(start 19.704304 -250.570492)
		(end 19.389344 -250.570492)
		(width 0.18288)
		(layer "In11.Cu")
		(net "M_D_CPU1_SB_CA<4>")
	)
	(segment
		(start 21.794216 -249.590814)
		(end 20.090384 -249.590814)
		(width 0.18288)
		(layer "In11.Cu")
		(net "M_D_CPU1_SB_CA<4>")
	)
	(segment
		(start 84.308696 -248.24436)
		(end 83.67395 -248.24436)
		(width 0.088646)
		(layer "In11.Cu")
		(net "M_D_CPU1_SB_CA<4>")
	)
	(segment
		(start 21.876004 -249.509026)
		(end 21.794216 -249.590814)
		(width 0.18288)
		(layer "In11.Cu")
		(net "M_D_CPU1_SB_CA<4>")
	)
	(segment
		(start 40.441626 -249.458226)
		(end 36.840668 -249.458226)
		(width 0.18288)
		(layer "In11.Cu")
		(net "M_D_CPU1_SB_CA<4>")
	)
	(segment
		(start 24.774652 -249.704352)
		(end 24.579326 -249.509026)
		(width 0.18288)
		(layer "In11.Cu")
		(net "M_D_CPU1_SB_CA<4>")
	)
	(segment
		(start 93.046296 -248.490486)
		(end 93.031564 -248.48185)
		(width 0.088646)
		(layer "In11.Cu")
		(net "M_D_CPU1_SB_CA<4>")
	)
	(segment
		(start 88.347296 -248.490486)
		(end 88.332564 -248.48185)
		(width 0.088646)
		(layer "In11.Cu")
		(net "M_D_CPU1_SB_CA<4>")
	)
	(segment
		(start 57.30494 -249.301762)
		(end 57.1119 -249.108722)
		(width 0.18288)
		(layer "In11.Cu")
		(net "M_D_CPU1_SB_CA<4>")
	)
	(segment
		(start 58.930286 -248.538746)
		(end 58.00598 -248.538746)
		(width 0.18288)
		(layer "In11.Cu")
		(net "M_D_CPU1_SB_CA<4>")
	)
	(segment
		(start 66.304414 -246.994426)
		(end 63.522606 -246.994426)
		(width 0.18288)
		(layer "In11.Cu")
		(net "M_D_CPU1_SB_CA<4>")
	)
	(segment
		(start 19.389344 -250.570492)
		(end 19.196304 -250.377452)
		(width 0.18288)
		(layer "In11.Cu")
		(net "M_D_CPU1_SB_CA<4>")
	)
	(segment
		(start 30.205426 -249.407426)
		(end 29.296868 -249.407426)
		(width 0.18288)
		(layer "In11.Cu")
		(net "M_D_CPU1_SB_CA<4>")
	)
	(segment
		(start 17.794224 -249.783854)
		(end 17.601184 -249.590814)
		(width 0.18288)
		(layer "In11.Cu")
		(net "M_D_CPU1_SB_CA<4>")
	)
	(segment
		(start 54.975506 -249.440446)
		(end 52.055268 -249.440446)
		(width 0.18288)
		(layer "In11.Cu")
		(net "M_D_CPU1_SB_CA<4>")
	)
	(segment
		(start 47.997364 -249.704606)
		(end 47.883826 -249.591068)
		(width 0.18288)
		(layer "In11.Cu")
		(net "M_D_CPU1_SB_CA<4>")
	)
	(segment
		(start 27.63393 -250.050554)
		(end 26.884122 -250.050554)
		(width 0.18288)
		(layer "In11.Cu")
		(net "M_D_CPU1_SB_CA<4>")
	)
	(segment
		(start 17.601184 -249.590814)
		(end 17.213326 -249.590814)
		(width 0.18288)
		(layer "In11.Cu")
		(net "M_D_CPU1_SB_CA<4>")
	)
	(segment
		(start 34.269426 -249.712226)
		(end 33.452308 -249.712226)
		(width 0.18288)
		(layer "In11.Cu")
		(net "M_D_CPU1_SB_CA<4>")
	)
	(segment
		(start 29.040328 -249.663966)
		(end 28.020518 -249.663966)
		(width 0.18288)
		(layer "In11.Cu")
		(net "M_D_CPU1_SB_CA<4>")
	)
	(segment
		(start 20.090384 -249.590814)
		(end 19.897344 -249.783854)
		(width 0.18288)
		(layer "In11.Cu")
		(net "M_D_CPU1_SB_CA<4>")
	)
	(segment
		(start 19.897344 -249.783854)
		(end 19.897344 -250.377452)
		(width 0.18288)
		(layer "In11.Cu")
		(net "M_D_CPU1_SB_CA<4>")
	)
	(segment
		(start 18.495264 -250.377452)
		(end 18.302224 -250.570492)
		(width 0.18288)
		(layer "In11.Cu")
		(net "M_D_CPU1_SB_CA<4>")
	)
	(segment
		(start 18.302224 -250.570492)
		(end 17.987264 -250.570492)
		(width 0.18288)
		(layer "In11.Cu")
		(net "M_D_CPU1_SB_CA<4>")
	)
	(segment
		(start 46.6598 -249.591068)
		(end 46.501558 -249.432826)
		(width 0.18288)
		(layer "In11.Cu")
		(net "M_D_CPU1_SB_CA<4>")
	)
	(segment
		(start 59.257946 -248.866406)
		(end 58.930286 -248.538746)
		(width 0.18288)
		(layer "In11.Cu")
		(net "M_D_CPU1_SB_CA<4>")
	)
	(segment
		(start 18.495264 -249.802904)
		(end 18.495264 -250.377452)
		(width 0.18288)
		(layer "In11.Cu")
		(net "M_D_CPU1_SB_CA<4>")
	)
	(segment
		(start 58.00598 -248.538746)
		(end 57.81294 -248.731786)
		(width 0.18288)
		(layer "In11.Cu")
		(net "M_D_CPU1_SB_CA<4>")
	)
	(segment
		(start 47.883826 -249.591068)
		(end 46.6598 -249.591068)
		(width 0.18288)
		(layer "In11.Cu")
		(net "M_D_CPU1_SB_CA<4>")
	)
	(segment
		(start 56.91886 -248.538746)
		(end 55.877206 -248.538746)
		(width 0.18288)
		(layer "In11.Cu")
		(net "M_D_CPU1_SB_CA<4>")
	)
	(segment
		(start 40.65397 -249.67057)
		(end 40.441626 -249.458226)
		(width 0.18288)
		(layer "In11.Cu")
		(net "M_D_CPU1_SB_CA<4>")
	)
	(segment
		(start 46.501558 -249.432826)
		(end 44.130468 -249.432826)
		(width 0.18288)
		(layer "In11.Cu")
		(net "M_D_CPU1_SB_CA<4>")
	)
	(segment
		(start 29.296868 -249.407426)
		(end 29.040328 -249.663966)
		(width 0.18288)
		(layer "In11.Cu")
		(net "M_D_CPU1_SB_CA<4>")
	)
	(segment
		(start 19.196304 -250.377452)
		(end 19.196304 -249.802904)
		(width 0.18288)
		(layer "In11.Cu")
		(net "M_D_CPU1_SB_CA<4>")
	)
	(segment
		(start 80.071468 -247.654826)
		(end 75.19543 -247.654826)
		(width 0.18288)
		(layer "In11.Cu")
		(net "M_D_CPU1_SB_CA<4>")
	)
	(segment
		(start 49.427384 -249.591068)
		(end 49.313846 -249.704606)
		(width 0.18288)
		(layer "In11.Cu")
		(net "M_D_CPU1_SB_CA<4>")
	)
	(segment
		(start 18.688304 -249.609864)
		(end 18.495264 -249.802904)
		(width 0.18288)
		(layer "In11.Cu")
		(net "M_D_CPU1_SB_CA<4>")
	)
	(segment
		(start 19.897344 -250.377452)
		(end 19.704304 -250.570492)
		(width 0.18288)
		(layer "In11.Cu")
		(net "M_D_CPU1_SB_CA<4>")
	)
	(segment
		(start 36.707826 -249.591068)
		(end 34.390584 -249.591068)
		(width 0.18288)
		(layer "In11.Cu")
		(net "M_D_CPU1_SB_CA<4>")
	)
	(segment
		(start 17.213326 -249.590814)
		(end 16.789146 -249.166634)
		(width 0.18288)
		(layer "In11.Cu")
		(net "M_D_CPU1_SB_CA<4>")
	)
	(segment
		(start 19.003264 -249.609864)
		(end 18.688304 -249.609864)
		(width 0.18288)
		(layer "In11.Cu")
		(net "M_D_CPU1_SB_CA<4>")
	)
	(segment
		(start 57.1119 -249.108722)
		(end 57.1119 -248.731786)
		(width 0.18288)
		(layer "In11.Cu")
		(net "M_D_CPU1_SB_CA<4>")
	)
	(segment
		(start 80.661002 -248.24436)
		(end 80.071468 -247.654826)
		(width 0.18288)
		(layer "In11.Cu")
		(net "M_D_CPU1_SB_CA<4>")
	)
	(segment
		(start 83.67395 -248.24436)
		(end 80.661002 -248.24436)
		(width 0.18288)
		(layer "In11.Cu")
		(net "M_D_CPU1_SB_CA<4>")
	)
	(segment
		(start 57.81294 -248.731786)
		(end 57.81294 -249.108722)
		(width 0.18288)
		(layer "In11.Cu")
		(net "M_D_CPU1_SB_CA<4>")
	)
	(segment
		(start 57.81294 -249.108722)
		(end 57.6199 -249.301762)
		(width 0.18288)
		(layer "In11.Cu")
		(net "M_D_CPU1_SB_CA<4>")
	)
	(segment
		(start 24.579326 -249.509026)
		(end 21.876004 -249.509026)
		(width 0.18288)
		(layer "In11.Cu")
		(net "M_D_CPU1_SB_CA<4>")
	)
	(segment
		(start 94.612714 -248.437908)
		(end 94.536514 -248.48185)
		(width 0.088646)
		(layer "In11.Cu")
		(net "M_D_CPU1_SB_CA<4>")
	)
	(segment
		(start 28.020518 -249.663966)
		(end 27.63393 -250.050554)
		(width 0.18288)
		(layer "In11.Cu")
		(net "M_D_CPU1_SB_CA<4>")
	)
	(segment
		(start 60.474606 -248.866406)
		(end 59.257946 -248.866406)
		(width 0.18288)
		(layer "In11.Cu")
		(net "M_D_CPU1_SB_CA<4>")
	)
	(segment
		(start 43.892724 -249.67057)
		(end 40.65397 -249.67057)
		(width 0.18288)
		(layer "In11.Cu")
		(net "M_D_CPU1_SB_CA<4>")
	)
	(segment
		(start 49.313846 -249.704606)
		(end 47.997364 -249.704606)
		(width 0.18288)
		(layer "In11.Cu")
		(net "M_D_CPU1_SB_CA<4>")
	)
	(segment
		(start 26.884122 -250.050554)
		(end 26.53792 -249.704352)
		(width 0.18288)
		(layer "In11.Cu")
		(net "M_D_CPU1_SB_CA<4>")
	)
	(segment
		(start 61.521086 -247.819926)
		(end 60.474606 -248.866406)
		(width 0.18288)
		(layer "In11.Cu")
		(net "M_D_CPU1_SB_CA<4>")
	)
	(segment
		(start 84.45627 -248.391934)
		(end 84.308696 -248.24436)
		(width 0.088646)
		(layer "In11.Cu")
		(net "M_D_CPU1_SB_CA<4>")
	)
	(segment
		(start 36.840668 -249.458226)
		(end 36.707826 -249.591068)
		(width 0.18288)
		(layer "In11.Cu")
		(net "M_D_CPU1_SB_CA<4>")
	)
	(segment
		(start 75.19543 -247.654826)
		(end 74.261726 -248.58853)
		(width 0.18288)
		(layer "In11.Cu")
		(net "M_D_CPU1_SB_CA<4>")
	)
	(segment
		(start 34.390584 -249.591068)
		(end 34.269426 -249.712226)
		(width 0.18288)
		(layer "In11.Cu")
		(net "M_D_CPU1_SB_CA<4>")
	)
	(segment
		(start 90.226896 -248.490486)
		(end 90.212164 -248.48185)
		(width 0.088646)
		(layer "In11.Cu")
		(net "M_D_CPU1_SB_CA<4>")
	)
	(segment
		(start 93.981778 -248.487946)
		(end 93.971364 -248.48185)
		(width 0.088646)
		(layer "In11.Cu")
		(net "M_D_CPU1_SB_CA<4>")
	)
	(segment
		(start 67.898518 -248.58853)
		(end 66.304414 -246.994426)
		(width 0.18288)
		(layer "In11.Cu")
		(net "M_D_CPU1_SB_CA<4>")
	)
	(arc
		(start 91.151964 -248.48185)
		(mid 90.964766 -248.431707)
		(end 90.777568 -248.48185)
		(width 0.088646)
		(layer "In11.Cu")
		(net "M_D_CPU1_SB_CA<4>")
	)
	(arc
		(start 93.596968 -248.48185)
		(mid 93.322739 -248.557775)
		(end 93.046296 -248.490486)
		(width 0.088646)
		(layer "In11.Cu")
		(net "M_D_CPU1_SB_CA<4>")
	)
	(arc
		(start 88.332564 -248.48185)
		(mid 88.145366 -248.431707)
		(end 87.958168 -248.48185)
		(width 0.088646)
		(layer "In11.Cu")
		(net "M_D_CPU1_SB_CA<4>")
	)
	(arc
		(start 92.091764 -248.48185)
		(mid 91.904566 -248.431707)
		(end 91.717368 -248.48185)
		(width 0.088646)
		(layer "In11.Cu")
		(net "M_D_CPU1_SB_CA<4>")
	)
	(arc
		(start 85.513164 -248.48185)
		(mid 85.325966 -248.431707)
		(end 85.138768 -248.48185)
		(width 0.088646)
		(layer "In11.Cu")
		(net "M_D_CPU1_SB_CA<4>")
	)
	(arc
		(start 93.031564 -248.48185)
		(mid 92.844366 -248.431707)
		(end 92.657168 -248.48185)
		(width 0.088646)
		(layer "In11.Cu")
		(net "M_D_CPU1_SB_CA<4>")
	)
	(arc
		(start 85.138768 -248.48185)
		(mid 84.782245 -248.552753)
		(end 84.45627 -248.391934)
		(width 0.088646)
		(layer "In11.Cu")
		(net "M_D_CPU1_SB_CA<4>")
	)
	(arc
		(start 92.657168 -248.48185)
		(mid 92.382939 -248.557775)
		(end 92.106496 -248.490486)
		(width 0.088646)
		(layer "In11.Cu")
		(net "M_D_CPU1_SB_CA<4>")
	)
	(arc
		(start 89.272364 -248.48185)
		(mid 89.085166 -248.431707)
		(end 88.897968 -248.48185)
		(width 0.088646)
		(layer "In11.Cu")
		(net "M_D_CPU1_SB_CA<4>")
	)
	(arc
		(start 93.971364 -248.48185)
		(mid 93.784166 -248.431707)
		(end 93.596968 -248.48185)
		(width 0.088646)
		(layer "In11.Cu")
		(net "M_D_CPU1_SB_CA<4>")
	)
	(arc
		(start 95.193612 -247.992138)
		(mid 94.917776 -248.234067)
		(end 94.612714 -248.437908)
		(width 0.088646)
		(layer "In11.Cu")
		(net "M_D_CPU1_SB_CA<4>")
	)
	(arc
		(start 89.837768 -248.48185)
		(mid 89.555066 -248.557592)
		(end 89.272364 -248.48185)
		(width 0.088646)
		(layer "In11.Cu")
		(net "M_D_CPU1_SB_CA<4>")
	)
	(arc
		(start 90.777568 -248.48185)
		(mid 90.503339 -248.557775)
		(end 90.226896 -248.490486)
		(width 0.088646)
		(layer "In11.Cu")
		(net "M_D_CPU1_SB_CA<4>")
	)
	(arc
		(start 87.018368 -248.48185)
		(mid 86.735666 -248.557592)
		(end 86.452964 -248.48185)
		(width 0.088646)
		(layer "In11.Cu")
		(net "M_D_CPU1_SB_CA<4>")
	)
	(arc
		(start 87.958168 -248.48185)
		(mid 87.675466 -248.557592)
		(end 87.392764 -248.48185)
		(width 0.088646)
		(layer "In11.Cu")
		(net "M_D_CPU1_SB_CA<4>")
	)
	(arc
		(start 87.392764 -248.48185)
		(mid 87.205566 -248.431707)
		(end 87.018368 -248.48185)
		(width 0.088646)
		(layer "In11.Cu")
		(net "M_D_CPU1_SB_CA<4>")
	)
	(arc
		(start 94.536514 -248.48185)
		(mid 94.259955 -248.557559)
		(end 93.981778 -248.487946)
		(width 0.088646)
		(layer "In11.Cu")
		(net "M_D_CPU1_SB_CA<4>")
	)
	(arc
		(start 90.212164 -248.48185)
		(mid 90.024966 -248.431707)
		(end 89.837768 -248.48185)
		(width 0.088646)
		(layer "In11.Cu")
		(net "M_D_CPU1_SB_CA<4>")
	)
	(arc
		(start 88.897968 -248.48185)
		(mid 88.623739 -248.557775)
		(end 88.347296 -248.490486)
		(width 0.088646)
		(layer "In11.Cu")
		(net "M_D_CPU1_SB_CA<4>")
	)
	(arc
		(start 91.717368 -248.48185)
		(mid 91.434666 -248.557592)
		(end 91.151964 -248.48185)
		(width 0.088646)
		(layer "In11.Cu")
		(net "M_D_CPU1_SB_CA<4>")
	)
	(arc
		(start 86.078568 -248.48185)
		(mid 85.795866 -248.557592)
		(end 85.513164 -248.48185)
		(width 0.088646)
		(layer "In11.Cu")
		(net "M_D_CPU1_SB_CA<4>")
	)
	(arc
		(start 86.452964 -248.48185)
		(mid 86.265766 -248.431707)
		(end 86.078568 -248.48185)
		(width 0.088646)
		(layer "In11.Cu")
		(net "M_D_CPU1_SB_CA<4>")
	)
	(segment
		(start 17.42948 -250.441714)
		(end 17.578578 -250.292616)
		(width 0.20066)
		(layer "F.Cu")
		(net "M_D_CPU1_SB_CA<3>")
	)
	(segment
		(start 14.560042 -250.455938)
		(end 14.574266 -250.441714)
		(width 0.101854)
		(layer "F.Cu")
		(net "M_D_CPU1_SB_CA<3>")
	)
	(segment
		(start 14.574266 -250.441714)
		(end 14.812264 -250.441714)
		(width 0.101854)
		(layer "F.Cu")
		(net "M_D_CPU1_SB_CA<3>")
	)
	(segment
		(start 14.063726 -250.313444)
		(end 14.20622 -250.455938)
		(width 0.20066)
		(layer "F.Cu")
		(net "M_D_CPU1_SB_CA<3>")
	)
	(segment
		(start 18.760694 -250.22429)
		(end 18.968212 -250.016772)
		(width 0.20066)
		(layer "F.Cu")
		(net "M_D_CPU1_SB_CA<3>")
	)
	(segment
		(start 20.889214 -250.016772)
		(end 19.784314 -250.016772)
		(width 0.20066)
		(layer "F.Cu")
		(net "M_D_CPU1_SB_CA<3>")
	)
	(segment
		(start 17.578578 -250.140978)
		(end 17.707102 -250.012454)
		(width 0.20066)
		(layer "F.Cu")
		(net "M_D_CPU1_SB_CA<3>")
	)
	(segment
		(start 13.937742 -250.016772)
		(end 14.063726 -250.142756)
		(width 0.20066)
		(layer "F.Cu")
		(net "M_D_CPU1_SB_CA<3>")
	)
	(segment
		(start 18.314162 -250.22429)
		(end 18.760694 -250.22429)
		(width 0.20066)
		(layer "F.Cu")
		(net "M_D_CPU1_SB_CA<3>")
	)
	(segment
		(start 17.707102 -250.012454)
		(end 18.102326 -250.012454)
		(width 0.20066)
		(layer "F.Cu")
		(net "M_D_CPU1_SB_CA<3>")
	)
	(segment
		(start 14.063726 -250.142756)
		(end 14.063726 -250.313444)
		(width 0.20066)
		(layer "F.Cu")
		(net "M_D_CPU1_SB_CA<3>")
	)
	(segment
		(start 96.603312 -249.342148)
		(end 96.603566 -249.341894)
		(width 0.20066)
		(layer "F.Cu")
		(net "M_D_CPU1_SB_CA<3>")
	)
	(segment
		(start 96.603566 -249.341894)
		(end 96.603566 -248.806208)
		(width 0.20066)
		(layer "F.Cu")
		(net "M_D_CPU1_SB_CA<3>")
	)
	(segment
		(start 18.968212 -250.016772)
		(end 19.784314 -250.016772)
		(width 0.20066)
		(layer "F.Cu")
		(net "M_D_CPU1_SB_CA<3>")
	)
	(segment
		(start 18.102326 -250.012454)
		(end 18.314162 -250.22429)
		(width 0.20066)
		(layer "F.Cu")
		(net "M_D_CPU1_SB_CA<3>")
	)
	(segment
		(start 17.578578 -250.292616)
		(end 17.578578 -250.140978)
		(width 0.20066)
		(layer "F.Cu")
		(net "M_D_CPU1_SB_CA<3>")
	)
	(segment
		(start 12.240514 -250.016772)
		(end 13.937742 -250.016772)
		(width 0.20066)
		(layer "F.Cu")
		(net "M_D_CPU1_SB_CA<3>")
	)
	(segment
		(start 14.20622 -250.455938)
		(end 14.560042 -250.455938)
		(width 0.20066)
		(layer "F.Cu")
		(net "M_D_CPU1_SB_CA<3>")
	)
	(segment
		(start 14.812264 -250.441714)
		(end 16.885158 -250.441714)
		(width 0.1016)
		(layer "F.Cu")
		(net "M_D_CPU1_SB_CA<3>")
	)
	(segment
		(start 16.885158 -250.441714)
		(end 17.42948 -250.441714)
		(width 0.20066)
		(layer "F.Cu")
		(net "M_D_CPU1_SB_CA<3>")
	)
	(segment
		(start 67.556888 -249.110246)
		(end 66.546984 -248.100342)
		(width 0.18288)
		(layer "In11.Cu")
		(net "M_D_CPU1_SB_CA<3>")
	)
	(segment
		(start 22.711156 -250.56211)
		(end 21.434552 -250.56211)
		(width 0.18288)
		(layer "In11.Cu")
		(net "M_D_CPU1_SB_CA<3>")
	)
	(segment
		(start 34.293302 -250.574556)
		(end 34.293302 -250.413266)
		(width 0.18288)
		(layer "In11.Cu")
		(net "M_D_CPU1_SB_CA<3>")
	)
	(segment
		(start 61.246766 -248.899426)
		(end 60.685426 -249.460766)
		(width 0.18288)
		(layer "In11.Cu")
		(net "M_D_CPU1_SB_CA<3>")
	)
	(segment
		(start 32.478472 -250.220226)
		(end 32.257492 -250.441206)
		(width 0.18288)
		(layer "In11.Cu")
		(net "M_D_CPU1_SB_CA<3>")
	)
	(segment
		(start 95.098362 -248.791984)
		(end 95.098362 -248.806208)
		(width 0.088646)
		(layer "In11.Cu")
		(net "M_D_CPU1_SB_CA<3>")
	)
	(segment
		(start 23.798276 -250.56211)
		(end 23.605236 -250.36907)
		(width 0.18288)
		(layer "In11.Cu")
		(net "M_D_CPU1_SB_CA<3>")
	)
	(segment
		(start 25.404826 -250.245626)
		(end 25.088342 -250.56211)
		(width 0.18288)
		(layer "In11.Cu")
		(net "M_D_CPU1_SB_CA<3>")
	)
	(segment
		(start 31.122366 -250.629928)
		(end 30.929326 -250.436888)
		(width 0.18288)
		(layer "In11.Cu")
		(net "M_D_CPU1_SB_CA<3>")
	)
	(segment
		(start 26.695908 -250.685808)
		(end 26.255726 -250.245626)
		(width 0.18288)
		(layer "In11.Cu")
		(net "M_D_CPU1_SB_CA<3>")
	)
	(segment
		(start 22.904196 -250.36907)
		(end 22.711156 -250.56211)
		(width 0.18288)
		(layer "In11.Cu")
		(net "M_D_CPU1_SB_CA<3>")
	)
	(segment
		(start 85.527896 -249.12193)
		(end 85.513164 -249.130566)
		(width 0.088646)
		(layer "In11.Cu")
		(net "M_D_CPU1_SB_CA<3>")
	)
	(segment
		(start 23.605236 -250.227846)
		(end 23.412196 -250.034806)
		(width 0.18288)
		(layer "In11.Cu")
		(net "M_D_CPU1_SB_CA<3>")
	)
	(segment
		(start 30.035246 -250.629928)
		(end 29.301948 -250.629928)
		(width 0.18288)
		(layer "In11.Cu")
		(net "M_D_CPU1_SB_CA<3>")
	)
	(segment
		(start 85.059012 -249.181112)
		(end 84.943442 -249.065542)
		(width 0.088646)
		(layer "In11.Cu")
		(net "M_D_CPU1_SB_CA<3>")
	)
	(segment
		(start 30.228286 -250.30557)
		(end 30.228286 -250.436888)
		(width 0.18288)
		(layer "In11.Cu")
		(net "M_D_CPU1_SB_CA<3>")
	)
	(segment
		(start 45.150278 -250.601226)
		(end 44.411646 -250.601226)
		(width 0.18288)
		(layer "In11.Cu")
		(net "M_D_CPU1_SB_CA<3>")
	)
	(segment
		(start 22.904196 -250.227846)
		(end 22.904196 -250.36907)
		(width 0.18288)
		(layer "In11.Cu")
		(net "M_D_CPU1_SB_CA<3>")
	)
	(segment
		(start 38.605968 -250.171458)
		(end 38.412928 -249.978418)
		(width 0.18288)
		(layer "In11.Cu")
		(net "M_D_CPU1_SB_CA<3>")
	)
	(segment
		(start 58.001662 -249.806206)
		(end 57.708546 -250.099322)
		(width 0.18288)
		(layer "In11.Cu")
		(net "M_D_CPU1_SB_CA<3>")
	)
	(segment
		(start 38.799008 -250.601226)
		(end 38.605968 -250.408186)
		(width 0.18288)
		(layer "In11.Cu")
		(net "M_D_CPU1_SB_CA<3>")
	)
	(segment
		(start 47.960026 -250.440952)
		(end 47.017432 -250.440952)
		(width 0.18288)
		(layer "In11.Cu")
		(net "M_D_CPU1_SB_CA<3>")
	)
	(segment
		(start 34.994342 -250.574556)
		(end 34.801302 -250.767596)
		(width 0.18288)
		(layer "In11.Cu")
		(net "M_D_CPU1_SB_CA<3>")
	)
	(segment
		(start 34.293302 -250.413266)
		(end 34.100262 -250.220226)
		(width 0.18288)
		(layer "In11.Cu")
		(net "M_D_CPU1_SB_CA<3>")
	)
	(segment
		(start 84.739734 -249.065542)
		(end 80.993234 -249.065542)
		(width 0.18288)
		(layer "In11.Cu")
		(net "M_D_CPU1_SB_CA<3>")
	)
	(segment
		(start 25.088342 -250.56211)
		(end 23.798276 -250.56211)
		(width 0.18288)
		(layer "In11.Cu")
		(net "M_D_CPU1_SB_CA<3>")
	)
	(segment
		(start 96.040956 -248.371868)
		(end 95.936054 -248.3104)
		(width 0.088646)
		(layer "In11.Cu")
		(net "M_D_CPU1_SB_CA<3>")
	)
	(segment
		(start 47.017178 -250.441206)
		(end 46.335696 -250.441206)
		(width 0.18288)
		(layer "In11.Cu")
		(net "M_D_CPU1_SB_CA<3>")
	)
	(segment
		(start 87.407496 -249.12193)
		(end 87.392764 -249.130566)
		(width 0.088646)
		(layer "In11.Cu")
		(net "M_D_CPU1_SB_CA<3>")
	)
	(segment
		(start 64.73063 -247.707658)
		(end 64.73063 -247.907302)
		(width 0.18288)
		(layer "In11.Cu")
		(net "M_D_CPU1_SB_CA<3>")
	)
	(segment
		(start 31.65221 -250.441206)
		(end 31.463488 -250.629928)
		(width 0.18288)
		(layer "In11.Cu")
		(net "M_D_CPU1_SB_CA<3>")
	)
	(segment
		(start 45.851318 -249.956828)
		(end 45.536358 -249.956828)
		(width 0.18288)
		(layer "In11.Cu")
		(net "M_D_CPU1_SB_CA<3>")
	)
	(segment
		(start 53.538374 -249.969528)
		(end 53.223414 -249.969528)
		(width 0.18288)
		(layer "In11.Cu")
		(net "M_D_CPU1_SB_CA<3>")
	)
	(segment
		(start 59.123326 -249.806206)
		(end 58.001662 -249.806206)
		(width 0.18288)
		(layer "In11.Cu")
		(net "M_D_CPU1_SB_CA<3>")
	)
	(segment
		(start 42.724578 -250.639834)
		(end 42.531538 -250.832874)
		(width 0.18288)
		(layer "In11.Cu")
		(net "M_D_CPU1_SB_CA<3>")
	)
	(segment
		(start 34.486342 -250.767596)
		(end 34.293302 -250.574556)
		(width 0.18288)
		(layer "In11.Cu")
		(net "M_D_CPU1_SB_CA<3>")
	)
	(segment
		(start 93.046296 -249.12193)
		(end 93.031564 -249.130566)
		(width 0.088646)
		(layer "In11.Cu")
		(net "M_D_CPU1_SB_CA<3>")
	)
	(segment
		(start 57.708546 -250.099322)
		(end 57.331102 -250.099322)
		(width 0.18288)
		(layer "In11.Cu")
		(net "M_D_CPU1_SB_CA<3>")
	)
	(segment
		(start 30.228286 -250.436888)
		(end 30.035246 -250.629928)
		(width 0.18288)
		(layer "In11.Cu")
		(net "M_D_CPU1_SB_CA<3>")
	)
	(segment
		(start 35.187382 -250.220226)
		(end 34.994342 -250.413266)
		(width 0.18288)
		(layer "In11.Cu")
		(net "M_D_CPU1_SB_CA<3>")
	)
	(segment
		(start 57.331102 -250.099322)
		(end 57.037986 -249.806206)
		(width 0.18288)
		(layer "In11.Cu")
		(net "M_D_CPU1_SB_CA<3>")
	)
	(segment
		(start 37.711888 -250.601226)
		(end 36.817046 -250.601226)
		(width 0.18288)
		(layer "In11.Cu")
		(net "M_D_CPU1_SB_CA<3>")
	)
	(segment
		(start 42.531538 -250.832874)
		(end 42.216578 -250.832874)
		(width 0.18288)
		(layer "In11.Cu")
		(net "M_D_CPU1_SB_CA<3>")
	)
	(segment
		(start 85.325966 -249.181112)
		(end 85.059012 -249.181112)
		(width 0.088646)
		(layer "In11.Cu")
		(net "M_D_CPU1_SB_CA<3>")
	)
	(segment
		(start 42.023538 -250.387866)
		(end 41.830498 -250.194826)
		(width 0.18288)
		(layer "In11.Cu")
		(net "M_D_CPU1_SB_CA<3>")
	)
	(segment
		(start 59.468766 -249.460766)
		(end 59.123326 -249.806206)
		(width 0.18288)
		(layer "In11.Cu")
		(net "M_D_CPU1_SB_CA<3>")
	)
	(segment
		(start 45.343318 -250.408186)
		(end 45.150278 -250.601226)
		(width 0.18288)
		(layer "In11.Cu")
		(net "M_D_CPU1_SB_CA<3>")
	)
	(segment
		(start 44.005246 -250.194826)
		(end 42.917618 -250.194826)
		(width 0.18288)
		(layer "In11.Cu")
		(net "M_D_CPU1_SB_CA<3>")
	)
	(segment
		(start 93.981778 -249.12447)
		(end 93.971364 -249.130566)
		(width 0.088646)
		(layer "In11.Cu")
		(net "M_D_CPU1_SB_CA<3>")
	)
	(segment
		(start 28.16606 -250.367546)
		(end 27.847798 -250.685808)
		(width 0.18288)
		(layer "In11.Cu")
		(net "M_D_CPU1_SB_CA<3>")
	)
	(segment
		(start 42.216578 -250.832874)
		(end 42.023538 -250.639834)
		(width 0.18288)
		(layer "In11.Cu")
		(net "M_D_CPU1_SB_CA<3>")
	)
	(segment
		(start 53.030374 -250.162568)
		(end 53.030374 -250.408186)
		(width 0.18288)
		(layer "In11.Cu")
		(net "M_D_CPU1_SB_CA<3>")
	)
	(segment
		(start 30.929326 -250.436888)
		(end 30.929326 -250.30557)
		(width 0.18288)
		(layer "In11.Cu")
		(net "M_D_CPU1_SB_CA<3>")
	)
	(segment
		(start 40.594026 -250.194826)
		(end 40.187626 -250.601226)
		(width 0.18288)
		(layer "In11.Cu")
		(net "M_D_CPU1_SB_CA<3>")
	)
	(segment
		(start 32.257492 -250.441206)
		(end 31.65221 -250.441206)
		(width 0.18288)
		(layer "In11.Cu")
		(net "M_D_CPU1_SB_CA<3>")
	)
	(segment
		(start 41.830498 -250.194826)
		(end 40.594026 -250.194826)
		(width 0.18288)
		(layer "In11.Cu")
		(net "M_D_CPU1_SB_CA<3>")
	)
	(segment
		(start 36.817046 -250.601226)
		(end 36.657026 -250.441206)
		(width 0.18288)
		(layer "In11.Cu")
		(net "M_D_CPU1_SB_CA<3>")
	)
	(segment
		(start 21.434552 -250.56211)
		(end 20.889214 -250.016772)
		(width 0.18288)
		(layer "In11.Cu")
		(net "M_D_CPU1_SB_CA<3>")
	)
	(segment
		(start 45.536358 -249.956828)
		(end 45.343318 -250.149868)
		(width 0.18288)
		(layer "In11.Cu")
		(net "M_D_CPU1_SB_CA<3>")
	)
	(segment
		(start 38.097968 -249.978418)
		(end 37.904928 -250.171458)
		(width 0.18288)
		(layer "In11.Cu")
		(net "M_D_CPU1_SB_CA<3>")
	)
	(segment
		(start 53.924454 -250.601226)
		(end 53.731414 -250.408186)
		(width 0.18288)
		(layer "In11.Cu")
		(net "M_D_CPU1_SB_CA<3>")
	)
	(segment
		(start 46.335696 -250.441206)
		(end 45.851318 -249.956828)
		(width 0.18288)
		(layer "In11.Cu")
		(net "M_D_CPU1_SB_CA<3>")
	)
	(segment
		(start 42.917618 -250.194826)
		(end 42.724578 -250.387866)
		(width 0.18288)
		(layer "In11.Cu")
		(net "M_D_CPU1_SB_CA<3>")
	)
	(segment
		(start 63.23203 -248.100342)
		(end 62.432946 -248.899426)
		(width 0.18288)
		(layer "In11.Cu")
		(net "M_D_CPU1_SB_CA<3>")
	)
	(segment
		(start 44.411646 -250.601226)
		(end 44.005246 -250.194826)
		(width 0.18288)
		(layer "In11.Cu")
		(net "M_D_CPU1_SB_CA<3>")
	)
	(segment
		(start 52.1335 -250.601226)
		(end 51.973226 -250.440952)
		(width 0.18288)
		(layer "In11.Cu")
		(net "M_D_CPU1_SB_CA<3>")
	)
	(segment
		(start 89.287096 -249.12193)
		(end 89.272364 -249.130566)
		(width 0.088646)
		(layer "In11.Cu")
		(net "M_D_CPU1_SB_CA<3>")
	)
	(segment
		(start 88.347296 -249.12193)
		(end 88.332564 -249.130566)
		(width 0.088646)
		(layer "In11.Cu")
		(net "M_D_CPU1_SB_CA<3>")
	)
	(segment
		(start 57.037986 -249.806206)
		(end 55.460646 -249.806206)
		(width 0.18288)
		(layer "In11.Cu")
		(net "M_D_CPU1_SB_CA<3>")
	)
	(segment
		(start 26.255726 -250.245626)
		(end 25.404826 -250.245626)
		(width 0.18288)
		(layer "In11.Cu")
		(net "M_D_CPU1_SB_CA<3>")
	)
	(segment
		(start 53.731414 -250.408186)
		(end 53.731414 -250.162568)
		(width 0.18288)
		(layer "In11.Cu")
		(net "M_D_CPU1_SB_CA<3>")
	)
	(segment
		(start 30.421326 -250.11253)
		(end 30.228286 -250.30557)
		(width 0.18288)
		(layer "In11.Cu")
		(net "M_D_CPU1_SB_CA<3>")
	)
	(segment
		(start 65.23863 -247.514618)
		(end 64.92367 -247.514618)
		(width 0.18288)
		(layer "In11.Cu")
		(net "M_D_CPU1_SB_CA<3>")
	)
	(segment
		(start 34.801302 -250.767596)
		(end 34.486342 -250.767596)
		(width 0.18288)
		(layer "In11.Cu")
		(net "M_D_CPU1_SB_CA<3>")
	)
	(segment
		(start 31.463488 -250.629928)
		(end 31.122366 -250.629928)
		(width 0.18288)
		(layer "In11.Cu")
		(net "M_D_CPU1_SB_CA<3>")
	)
	(segment
		(start 42.023538 -250.639834)
		(end 42.023538 -250.387866)
		(width 0.18288)
		(layer "In11.Cu")
		(net "M_D_CPU1_SB_CA<3>")
	)
	(segment
		(start 66.546984 -248.100342)
		(end 65.62471 -248.100342)
		(width 0.18288)
		(layer "In11.Cu")
		(net "M_D_CPU1_SB_CA<3>")
	)
	(segment
		(start 30.929326 -250.30557)
		(end 30.736286 -250.11253)
		(width 0.18288)
		(layer "In11.Cu")
		(net "M_D_CPU1_SB_CA<3>")
	)
	(segment
		(start 91.166696 -249.12193)
		(end 91.151964 -249.130566)
		(width 0.088646)
		(layer "In11.Cu")
		(net "M_D_CPU1_SB_CA<3>")
	)
	(segment
		(start 35.77336 -250.441206)
		(end 35.55238 -250.220226)
		(width 0.18288)
		(layer "In11.Cu")
		(net "M_D_CPU1_SB_CA<3>")
	)
	(segment
		(start 37.904928 -250.171458)
		(end 37.904928 -250.408186)
		(width 0.18288)
		(layer "In11.Cu")
		(net "M_D_CPU1_SB_CA<3>")
	)
	(segment
		(start 27.847798 -250.685808)
		(end 26.695908 -250.685808)
		(width 0.18288)
		(layer "In11.Cu")
		(net "M_D_CPU1_SB_CA<3>")
	)
	(segment
		(start 79.927958 -248.000266)
		(end 75.568556 -248.000266)
		(width 0.18288)
		(layer "In11.Cu")
		(net "M_D_CPU1_SB_CA<3>")
	)
	(segment
		(start 47.017432 -250.440952)
		(end 47.017178 -250.441206)
		(width 0.18288)
		(layer "In11.Cu")
		(net "M_D_CPU1_SB_CA<3>")
	)
	(segment
		(start 29.301948 -250.629928)
		(end 29.039566 -250.367546)
		(width 0.18288)
		(layer "In11.Cu")
		(net "M_D_CPU1_SB_CA<3>")
	)
	(segment
		(start 49.39284 -250.25604)
		(end 48.144938 -250.25604)
		(width 0.18288)
		(layer "In11.Cu")
		(net "M_D_CPU1_SB_CA<3>")
	)
	(segment
		(start 38.605968 -250.408186)
		(end 38.605968 -250.171458)
		(width 0.18288)
		(layer "In11.Cu")
		(net "M_D_CPU1_SB_CA<3>")
	)
	(segment
		(start 34.100262 -250.220226)
		(end 32.478472 -250.220226)
		(width 0.18288)
		(layer "In11.Cu")
		(net "M_D_CPU1_SB_CA<3>")
	)
	(segment
		(start 80.993234 -249.065542)
		(end 79.927958 -248.000266)
		(width 0.18288)
		(layer "In11.Cu")
		(net "M_D_CPU1_SB_CA<3>")
	)
	(segment
		(start 38.412928 -249.978418)
		(end 38.097968 -249.978418)
		(width 0.18288)
		(layer "In11.Cu")
		(net "M_D_CPU1_SB_CA<3>")
	)
	(segment
		(start 29.039566 -250.367546)
		(end 28.16606 -250.367546)
		(width 0.18288)
		(layer "In11.Cu")
		(net "M_D_CPU1_SB_CA<3>")
	)
	(segment
		(start 35.55238 -250.220226)
		(end 35.187382 -250.220226)
		(width 0.18288)
		(layer "In11.Cu")
		(net "M_D_CPU1_SB_CA<3>")
	)
	(segment
		(start 60.685426 -249.460766)
		(end 59.468766 -249.460766)
		(width 0.18288)
		(layer "In11.Cu")
		(net "M_D_CPU1_SB_CA<3>")
	)
	(segment
		(start 62.432946 -248.899426)
		(end 61.246766 -248.899426)
		(width 0.18288)
		(layer "In11.Cu")
		(net "M_D_CPU1_SB_CA<3>")
	)
	(segment
		(start 34.994342 -250.413266)
		(end 34.994342 -250.574556)
		(width 0.18288)
		(layer "In11.Cu")
		(net "M_D_CPU1_SB_CA<3>")
	)
	(segment
		(start 49.577752 -250.440952)
		(end 49.39284 -250.25604)
		(width 0.18288)
		(layer "In11.Cu")
		(net "M_D_CPU1_SB_CA<3>")
	)
	(segment
		(start 64.92367 -247.514618)
		(end 64.73063 -247.707658)
		(width 0.18288)
		(layer "In11.Cu")
		(net "M_D_CPU1_SB_CA<3>")
	)
	(segment
		(start 23.412196 -250.034806)
		(end 23.097236 -250.034806)
		(width 0.18288)
		(layer "In11.Cu")
		(net "M_D_CPU1_SB_CA<3>")
	)
	(segment
		(start 65.43167 -247.907302)
		(end 65.43167 -247.707658)
		(width 0.18288)
		(layer "In11.Cu")
		(net "M_D_CPU1_SB_CA<3>")
	)
	(segment
		(start 52.837334 -250.601226)
		(end 52.1335 -250.601226)
		(width 0.18288)
		(layer "In11.Cu")
		(net "M_D_CPU1_SB_CA<3>")
	)
	(segment
		(start 23.605236 -250.36907)
		(end 23.605236 -250.227846)
		(width 0.18288)
		(layer "In11.Cu")
		(net "M_D_CPU1_SB_CA<3>")
	)
	(segment
		(start 75.568556 -248.000266)
		(end 74.458576 -249.110246)
		(width 0.18288)
		(layer "In11.Cu")
		(net "M_D_CPU1_SB_CA<3>")
	)
	(segment
		(start 54.665626 -250.601226)
		(end 53.924454 -250.601226)
		(width 0.18288)
		(layer "In11.Cu")
		(net "M_D_CPU1_SB_CA<3>")
	)
	(segment
		(start 64.53759 -248.100342)
		(end 63.23203 -248.100342)
		(width 0.18288)
		(layer "In11.Cu")
		(net "M_D_CPU1_SB_CA<3>")
	)
	(segment
		(start 53.030374 -250.408186)
		(end 52.837334 -250.601226)
		(width 0.18288)
		(layer "In11.Cu")
		(net "M_D_CPU1_SB_CA<3>")
	)
	(segment
		(start 37.904928 -250.408186)
		(end 37.711888 -250.601226)
		(width 0.18288)
		(layer "In11.Cu")
		(net "M_D_CPU1_SB_CA<3>")
	)
	(segment
		(start 86.467696 -249.12193)
		(end 86.452964 -249.130566)
		(width 0.088646)
		(layer "In11.Cu")
		(net "M_D_CPU1_SB_CA<3>")
	)
	(segment
		(start 51.973226 -250.440952)
		(end 49.577752 -250.440952)
		(width 0.18288)
		(layer "In11.Cu")
		(net "M_D_CPU1_SB_CA<3>")
	)
	(segment
		(start 92.106496 -249.12193)
		(end 92.091764 -249.130566)
		(width 0.088646)
		(layer "In11.Cu")
		(net "M_D_CPU1_SB_CA<3>")
	)
	(segment
		(start 53.731414 -250.162568)
		(end 53.538374 -249.969528)
		(width 0.18288)
		(layer "In11.Cu")
		(net "M_D_CPU1_SB_CA<3>")
	)
	(segment
		(start 74.458576 -249.110246)
		(end 67.556888 -249.110246)
		(width 0.18288)
		(layer "In11.Cu")
		(net "M_D_CPU1_SB_CA<3>")
	)
	(segment
		(start 30.736286 -250.11253)
		(end 30.421326 -250.11253)
		(width 0.18288)
		(layer "In11.Cu")
		(net "M_D_CPU1_SB_CA<3>")
	)
	(segment
		(start 64.73063 -247.907302)
		(end 64.53759 -248.100342)
		(width 0.18288)
		(layer "In11.Cu")
		(net "M_D_CPU1_SB_CA<3>")
	)
	(segment
		(start 36.657026 -250.441206)
		(end 35.77336 -250.441206)
		(width 0.18288)
		(layer "In11.Cu")
		(net "M_D_CPU1_SB_CA<3>")
	)
	(segment
		(start 45.343318 -250.149868)
		(end 45.343318 -250.408186)
		(width 0.18288)
		(layer "In11.Cu")
		(net "M_D_CPU1_SB_CA<3>")
	)
	(segment
		(start 40.187626 -250.601226)
		(end 38.799008 -250.601226)
		(width 0.18288)
		(layer "In11.Cu")
		(net "M_D_CPU1_SB_CA<3>")
	)
	(segment
		(start 65.62471 -248.100342)
		(end 65.43167 -247.907302)
		(width 0.18288)
		(layer "In11.Cu")
		(net "M_D_CPU1_SB_CA<3>")
	)
	(segment
		(start 42.724578 -250.387866)
		(end 42.724578 -250.639834)
		(width 0.18288)
		(layer "In11.Cu")
		(net "M_D_CPU1_SB_CA<3>")
	)
	(segment
		(start 94.9198 -249.125486)
		(end 94.91091 -249.130566)
		(width 0.088646)
		(layer "In11.Cu")
		(net "M_D_CPU1_SB_CA<3>")
	)
	(segment
		(start 55.460646 -249.806206)
		(end 54.665626 -250.601226)
		(width 0.18288)
		(layer "In11.Cu")
		(net "M_D_CPU1_SB_CA<3>")
	)
	(segment
		(start 53.223414 -249.969528)
		(end 53.030374 -250.162568)
		(width 0.18288)
		(layer "In11.Cu")
		(net "M_D_CPU1_SB_CA<3>")
	)
	(segment
		(start 23.097236 -250.034806)
		(end 22.904196 -250.227846)
		(width 0.18288)
		(layer "In11.Cu")
		(net "M_D_CPU1_SB_CA<3>")
	)
	(segment
		(start 48.144938 -250.25604)
		(end 47.960026 -250.440952)
		(width 0.18288)
		(layer "In11.Cu")
		(net "M_D_CPU1_SB_CA<3>")
	)
	(segment
		(start 65.43167 -247.707658)
		(end 65.23863 -247.514618)
		(width 0.18288)
		(layer "In11.Cu")
		(net "M_D_CPU1_SB_CA<3>")
	)
	(segment
		(start 84.943442 -249.065542)
		(end 84.739734 -249.065542)
		(width 0.088646)
		(layer "In11.Cu")
		(net "M_D_CPU1_SB_CA<3>")
	)
	(arc
		(start 87.392764 -249.130566)
		(mid 87.205566 -249.180709)
		(end 87.018368 -249.130566)
		(width 0.088646)
		(layer "In11.Cu")
		(net "M_D_CPU1_SB_CA<3>")
	)
	(arc
		(start 92.657168 -249.130566)
		(mid 92.382969 -249.054731)
		(end 92.106496 -249.12193)
		(width 0.088646)
		(layer "In11.Cu")
		(net "M_D_CPU1_SB_CA<3>")
	)
	(arc
		(start 86.452964 -249.130566)
		(mid 86.265766 -249.180709)
		(end 86.078568 -249.130566)
		(width 0.088646)
		(layer "In11.Cu")
		(net "M_D_CPU1_SB_CA<3>")
	)
	(arc
		(start 93.596968 -249.130566)
		(mid 93.322769 -249.054731)
		(end 93.046296 -249.12193)
		(width 0.088646)
		(layer "In11.Cu")
		(net "M_D_CPU1_SB_CA<3>")
	)
	(arc
		(start 91.717368 -249.130566)
		(mid 91.443169 -249.054731)
		(end 91.166696 -249.12193)
		(width 0.088646)
		(layer "In11.Cu")
		(net "M_D_CPU1_SB_CA<3>")
	)
	(arc
		(start 94.536514 -249.130566)
		(mid 94.259955 -249.054823)
		(end 93.981778 -249.12447)
		(width 0.088646)
		(layer "In11.Cu")
		(net "M_D_CPU1_SB_CA<3>")
	)
	(arc
		(start 89.837768 -249.130566)
		(mid 89.563569 -249.054731)
		(end 89.287096 -249.12193)
		(width 0.088646)
		(layer "In11.Cu")
		(net "M_D_CPU1_SB_CA<3>")
	)
	(arc
		(start 90.212164 -249.130566)
		(mid 90.024966 -249.180709)
		(end 89.837768 -249.130566)
		(width 0.088646)
		(layer "In11.Cu")
		(net "M_D_CPU1_SB_CA<3>")
	)
	(arc
		(start 87.958168 -249.130566)
		(mid 87.683969 -249.054731)
		(end 87.407496 -249.12193)
		(width 0.088646)
		(layer "In11.Cu")
		(net "M_D_CPU1_SB_CA<3>")
	)
	(arc
		(start 85.513164 -249.130566)
		(mid 85.422892 -249.168165)
		(end 85.325966 -249.181112)
		(width 0.088646)
		(layer "In11.Cu")
		(net "M_D_CPU1_SB_CA<3>")
	)
	(arc
		(start 96.603566 -248.806208)
		(mid 96.336169 -248.571023)
		(end 96.040956 -248.371868)
		(width 0.088646)
		(layer "In11.Cu")
		(net "M_D_CPU1_SB_CA<3>")
	)
	(arc
		(start 93.031564 -249.130566)
		(mid 92.844366 -249.180709)
		(end 92.657168 -249.130566)
		(width 0.088646)
		(layer "In11.Cu")
		(net "M_D_CPU1_SB_CA<3>")
	)
	(arc
		(start 89.272364 -249.130566)
		(mid 89.085166 -249.180709)
		(end 88.897968 -249.130566)
		(width 0.088646)
		(layer "In11.Cu")
		(net "M_D_CPU1_SB_CA<3>")
	)
	(arc
		(start 86.078568 -249.130566)
		(mid 85.804369 -249.054731)
		(end 85.527896 -249.12193)
		(width 0.088646)
		(layer "In11.Cu")
		(net "M_D_CPU1_SB_CA<3>")
	)
	(arc
		(start 95.936054 -248.3104)
		(mid 95.381861 -248.315804)
		(end 95.098362 -248.791984)
		(width 0.088646)
		(layer "In11.Cu")
		(net "M_D_CPU1_SB_CA<3>")
	)
	(arc
		(start 94.91091 -249.130566)
		(mid 94.723712 -249.180709)
		(end 94.536514 -249.130566)
		(width 0.088646)
		(layer "In11.Cu")
		(net "M_D_CPU1_SB_CA<3>")
	)
	(arc
		(start 88.332564 -249.130566)
		(mid 88.145366 -249.180709)
		(end 87.958168 -249.130566)
		(width 0.088646)
		(layer "In11.Cu")
		(net "M_D_CPU1_SB_CA<3>")
	)
	(arc
		(start 91.151964 -249.130566)
		(mid 90.964766 -249.180709)
		(end 90.777568 -249.130566)
		(width 0.088646)
		(layer "In11.Cu")
		(net "M_D_CPU1_SB_CA<3>")
	)
	(arc
		(start 90.777568 -249.130566)
		(mid 90.494866 -249.05479)
		(end 90.212164 -249.130566)
		(width 0.088646)
		(layer "In11.Cu")
		(net "M_D_CPU1_SB_CA<3>")
	)
	(arc
		(start 92.091764 -249.130566)
		(mid 91.904566 -249.180709)
		(end 91.717368 -249.130566)
		(width 0.088646)
		(layer "In11.Cu")
		(net "M_D_CPU1_SB_CA<3>")
	)
	(arc
		(start 95.098362 -248.806208)
		(mid 95.050683 -248.989108)
		(end 94.9198 -249.125486)
		(width 0.088646)
		(layer "In11.Cu")
		(net "M_D_CPU1_SB_CA<3>")
	)
	(arc
		(start 88.897968 -249.130566)
		(mid 88.623769 -249.054731)
		(end 88.347296 -249.12193)
		(width 0.088646)
		(layer "In11.Cu")
		(net "M_D_CPU1_SB_CA<3>")
	)
	(arc
		(start 93.971364 -249.130566)
		(mid 93.784166 -249.180709)
		(end 93.596968 -249.130566)
		(width 0.088646)
		(layer "In11.Cu")
		(net "M_D_CPU1_SB_CA<3>")
	)
	(arc
		(start 87.018368 -249.130566)
		(mid 86.744169 -249.054731)
		(end 86.467696 -249.12193)
		(width 0.088646)
		(layer "In11.Cu")
		(net "M_D_CPU1_SB_CA<3>")
	)
	(segment
		(start 13.441426 -250.441714)
		(end 13.619988 -250.441714)
		(width 0.20066)
		(layer "F.Cu")
		(net "M_D_CPU1_SB_CA<2>")
	)
	(segment
		(start 95.663512 -249.342148)
		(end 95.663766 -249.341894)
		(width 0.20066)
		(layer "F.Cu")
		(net "M_D_CPU1_SB_CA<2>")
	)
	(segment
		(start 95.663766 -249.341894)
		(end 95.663766 -248.806208)
		(width 0.20066)
		(layer "F.Cu")
		(net "M_D_CPU1_SB_CA<2>")
	)
	(segment
		(start 9.474708 -250.866656)
		(end 9.686036 -251.077984)
		(width 0.20066)
		(layer "F.Cu")
		(net "M_D_CPU1_SB_CA<2>")
	)
	(segment
		(start 11.1252 -250.441714)
		(end 13.110718 -250.441714)
		(width 0.1016)
		(layer "F.Cu")
		(net "M_D_CPU1_SB_CA<2>")
	)
	(segment
		(start 11.11631 -250.432824)
		(end 11.1252 -250.441714)
		(width 0.1016)
		(layer "F.Cu")
		(net "M_D_CPU1_SB_CA<2>")
	)
	(segment
		(start 16.789146 -250.866656)
		(end 15.684246 -250.866656)
		(width 0.20066)
		(layer "F.Cu")
		(net "M_D_CPU1_SB_CA<2>")
	)
	(segment
		(start 10.507472 -250.432824)
		(end 11.11631 -250.432824)
		(width 0.20066)
		(layer "F.Cu")
		(net "M_D_CPU1_SB_CA<2>")
	)
	(segment
		(start 10.344912 -250.923552)
		(end 10.344912 -250.595384)
		(width 0.20066)
		(layer "F.Cu")
		(net "M_D_CPU1_SB_CA<2>")
	)
	(segment
		(start 10.19048 -251.077984)
		(end 10.344912 -250.923552)
		(width 0.20066)
		(layer "F.Cu")
		(net "M_D_CPU1_SB_CA<2>")
	)
	(segment
		(start 10.344912 -250.595384)
		(end 10.507472 -250.432824)
		(width 0.20066)
		(layer "F.Cu")
		(net "M_D_CPU1_SB_CA<2>")
	)
	(segment
		(start 8.140446 -250.866656)
		(end 9.474708 -250.866656)
		(width 0.20066)
		(layer "F.Cu")
		(net "M_D_CPU1_SB_CA<2>")
	)
	(segment
		(start 13.110718 -250.441714)
		(end 13.441426 -250.441714)
		(width 0.101854)
		(layer "F.Cu")
		(net "M_D_CPU1_SB_CA<2>")
	)
	(segment
		(start 9.686036 -251.077984)
		(end 10.19048 -251.077984)
		(width 0.20066)
		(layer "F.Cu")
		(net "M_D_CPU1_SB_CA<2>")
	)
	(segment
		(start 14.04493 -250.866656)
		(end 15.684246 -250.866656)
		(width 0.20066)
		(layer "F.Cu")
		(net "M_D_CPU1_SB_CA<2>")
	)
	(segment
		(start 13.619988 -250.441714)
		(end 14.04493 -250.866656)
		(width 0.20066)
		(layer "F.Cu")
		(net "M_D_CPU1_SB_CA<2>")
	)
	(segment
		(start 19.111214 -252.038358)
		(end 18.918174 -251.845318)
		(width 0.18288)
		(layer "In11.Cu")
		(net "M_D_CPU1_SB_CA<2>")
	)
	(segment
		(start 56.66613 -250.370086)
		(end 55.811166 -250.370086)
		(width 0.18288)
		(layer "In11.Cu")
		(net "M_D_CPU1_SB_CA<2>")
	)
	(segment
		(start 52.91455 -251.109226)
		(end 52.10429 -251.109226)
		(width 0.18288)
		(layer "In11.Cu")
		(net "M_D_CPU1_SB_CA<2>")
	)
	(segment
		(start 86.548214 -249.295666)
		(end 86.533482 -249.304302)
		(width 0.088646)
		(layer "In11.Cu")
		(net "M_D_CPU1_SB_CA<2>")
	)
	(segment
		(start 19.812254 -251.290836)
		(end 19.619214 -251.483876)
		(width 0.18288)
		(layer "In11.Cu")
		(net "M_D_CPU1_SB_CA<2>")
	)
	(segment
		(start 29.208222 -251.170694)
		(end 28.96489 -251.414026)
		(width 0.18288)
		(layer "In11.Cu")
		(net "M_D_CPU1_SB_CA<2>")
	)
	(segment
		(start 37.97173 -251.302266)
		(end 37.77869 -251.109226)
		(width 0.18288)
		(layer "In11.Cu")
		(net "M_D_CPU1_SB_CA<2>")
	)
	(segment
		(start 55.072026 -251.109226)
		(end 54.00167 -251.109226)
		(width 0.18288)
		(layer "In11.Cu")
		(net "M_D_CPU1_SB_CA<2>")
	)
	(segment
		(start 61.668406 -249.470926)
		(end 60.591446 -250.547886)
		(width 0.18288)
		(layer "In11.Cu")
		(net "M_D_CPU1_SB_CA<2>")
	)
	(segment
		(start 53.30063 -251.947426)
		(end 53.10759 -251.754386)
		(width 0.18288)
		(layer "In11.Cu")
		(net "M_D_CPU1_SB_CA<2>")
	)
	(segment
		(start 74.668888 -249.618754)
		(end 67.333876 -249.618754)
		(width 0.18288)
		(layer "In11.Cu")
		(net "M_D_CPU1_SB_CA<2>")
	)
	(segment
		(start 17.213326 -251.290836)
		(end 16.789146 -250.866656)
		(width 0.18288)
		(layer "In11.Cu")
		(net "M_D_CPU1_SB_CA<2>")
	)
	(segment
		(start 38.67277 -251.302266)
		(end 38.67277 -251.6632)
		(width 0.18288)
		(layer "In11.Cu")
		(net "M_D_CPU1_SB_CA<2>")
	)
	(segment
		(start 18.217134 -251.845318)
		(end 18.024094 -252.038358)
		(width 0.18288)
		(layer "In11.Cu")
		(net "M_D_CPU1_SB_CA<2>")
	)
	(segment
		(start 80.872076 -249.433334)
		(end 79.784448 -248.345706)
		(width 0.18288)
		(layer "In11.Cu")
		(net "M_D_CPU1_SB_CA<2>")
	)
	(segment
		(start 54.00167 -251.109226)
		(end 53.80863 -251.302266)
		(width 0.18288)
		(layer "In11.Cu")
		(net "M_D_CPU1_SB_CA<2>")
	)
	(segment
		(start 48.336962 -251.591826)
		(end 48.036226 -251.29109)
		(width 0.18288)
		(layer "In11.Cu")
		(net "M_D_CPU1_SB_CA<2>")
	)
	(segment
		(start 37.77869 -251.109226)
		(end 36.68649 -251.109226)
		(width 0.18288)
		(layer "In11.Cu")
		(net "M_D_CPU1_SB_CA<2>")
	)
	(segment
		(start 17.516094 -251.845318)
		(end 17.516094 -251.483876)
		(width 0.18288)
		(layer "In11.Cu")
		(net "M_D_CPU1_SB_CA<2>")
	)
	(segment
		(start 21.925026 -251.160026)
		(end 21.794216 -251.290836)
		(width 0.18288)
		(layer "In11.Cu")
		(net "M_D_CPU1_SB_CA<2>")
	)
	(segment
		(start 44.097194 -251.343922)
		(end 40.930322 -251.343922)
		(width 0.18288)
		(layer "In11.Cu")
		(net "M_D_CPU1_SB_CA<2>")
	)
	(segment
		(start 34.239962 -251.29109)
		(end 34.066226 -251.464826)
		(width 0.18288)
		(layer "In11.Cu")
		(net "M_D_CPU1_SB_CA<2>")
	)
	(segment
		(start 59.278266 -250.547886)
		(end 59.100466 -250.370086)
		(width 0.18288)
		(layer "In11.Cu")
		(net "M_D_CPU1_SB_CA<2>")
	)
	(segment
		(start 53.80863 -251.754386)
		(end 53.61559 -251.947426)
		(width 0.18288)
		(layer "In11.Cu")
		(net "M_D_CPU1_SB_CA<2>")
	)
	(segment
		(start 92.187014 -249.295666)
		(end 92.172282 -249.304302)
		(width 0.088646)
		(layer "In11.Cu")
		(net "M_D_CPU1_SB_CA<2>")
	)
	(segment
		(start 84.739734 -249.433334)
		(end 80.872076 -249.433334)
		(width 0.18288)
		(layer "In11.Cu")
		(net "M_D_CPU1_SB_CA<2>")
	)
	(segment
		(start 91.247214 -249.295666)
		(end 91.2368 -249.301762)
		(width 0.088646)
		(layer "In11.Cu")
		(net "M_D_CPU1_SB_CA<2>")
	)
	(segment
		(start 66.354706 -248.639584)
		(end 63.561468 -248.639584)
		(width 0.18288)
		(layer "In11.Cu")
		(net "M_D_CPU1_SB_CA<2>")
	)
	(segment
		(start 48.036226 -251.29109)
		(end 45.50029 -251.29109)
		(width 0.18288)
		(layer "In11.Cu")
		(net "M_D_CPU1_SB_CA<2>")
	)
	(segment
		(start 18.217134 -251.50064)
		(end 18.217134 -251.845318)
		(width 0.18288)
		(layer "In11.Cu")
		(net "M_D_CPU1_SB_CA<2>")
	)
	(segment
		(start 45.50029 -251.29109)
		(end 45.318426 -251.109226)
		(width 0.18288)
		(layer "In11.Cu")
		(net "M_D_CPU1_SB_CA<2>")
	)
	(segment
		(start 36.504626 -251.29109)
		(end 34.239962 -251.29109)
		(width 0.18288)
		(layer "In11.Cu")
		(net "M_D_CPU1_SB_CA<2>")
	)
	(segment
		(start 60.591446 -250.547886)
		(end 59.278266 -250.547886)
		(width 0.18288)
		(layer "In11.Cu")
		(net "M_D_CPU1_SB_CA<2>")
	)
	(segment
		(start 67.333876 -249.618754)
		(end 66.354706 -248.639584)
		(width 0.18288)
		(layer "In11.Cu")
		(net "M_D_CPU1_SB_CA<2>")
	)
	(segment
		(start 53.61559 -251.947426)
		(end 53.30063 -251.947426)
		(width 0.18288)
		(layer "In11.Cu")
		(net "M_D_CPU1_SB_CA<2>")
	)
	(segment
		(start 89.367614 -249.295666)
		(end 89.352882 -249.304302)
		(width 0.088646)
		(layer "In11.Cu")
		(net "M_D_CPU1_SB_CA<2>")
	)
	(segment
		(start 30.18409 -251.29109)
		(end 30.063694 -251.170694)
		(width 0.18288)
		(layer "In11.Cu")
		(net "M_D_CPU1_SB_CA<2>")
	)
	(segment
		(start 85.172804 -249.433334)
		(end 84.739734 -249.433334)
		(width 0.088646)
		(layer "In11.Cu")
		(net "M_D_CPU1_SB_CA<2>")
	)
	(segment
		(start 18.024094 -252.038358)
		(end 17.709134 -252.038358)
		(width 0.18288)
		(layer "In11.Cu")
		(net "M_D_CPU1_SB_CA<2>")
	)
	(segment
		(start 59.100466 -250.370086)
		(end 58.360056 -250.370086)
		(width 0.18288)
		(layer "In11.Cu")
		(net "M_D_CPU1_SB_CA<2>")
	)
	(segment
		(start 17.323054 -251.290836)
		(end 17.213326 -251.290836)
		(width 0.18288)
		(layer "In11.Cu")
		(net "M_D_CPU1_SB_CA<2>")
	)
	(segment
		(start 21.794216 -251.290836)
		(end 19.812254 -251.290836)
		(width 0.18288)
		(layer "In11.Cu")
		(net "M_D_CPU1_SB_CA<2>")
	)
	(segment
		(start 30.063694 -251.170694)
		(end 29.208222 -251.170694)
		(width 0.18288)
		(layer "In11.Cu")
		(net "M_D_CPU1_SB_CA<2>")
	)
	(segment
		(start 56.925972 -250.629928)
		(end 56.66613 -250.370086)
		(width 0.18288)
		(layer "In11.Cu")
		(net "M_D_CPU1_SB_CA<2>")
	)
	(segment
		(start 90.307668 -249.295666)
		(end 90.297254 -249.301762)
		(width 0.088646)
		(layer "In11.Cu")
		(net "M_D_CPU1_SB_CA<2>")
	)
	(segment
		(start 55.811166 -250.370086)
		(end 55.072026 -251.109226)
		(width 0.18288)
		(layer "In11.Cu")
		(net "M_D_CPU1_SB_CA<2>")
	)
	(segment
		(start 49.077626 -251.591826)
		(end 48.336962 -251.591826)
		(width 0.18288)
		(layer "In11.Cu")
		(net "M_D_CPU1_SB_CA<2>")
	)
	(segment
		(start 38.16477 -251.85624)
		(end 37.97173 -251.6632)
		(width 0.18288)
		(layer "In11.Cu")
		(net "M_D_CPU1_SB_CA<2>")
	)
	(segment
		(start 18.918174 -251.50064)
		(end 18.725134 -251.3076)
		(width 0.18288)
		(layer "In11.Cu")
		(net "M_D_CPU1_SB_CA<2>")
	)
	(segment
		(start 85.23478 -249.371358)
		(end 85.172804 -249.433334)
		(width 0.088646)
		(layer "In11.Cu")
		(net "M_D_CPU1_SB_CA<2>")
	)
	(segment
		(start 25.404826 -251.160026)
		(end 21.925026 -251.160026)
		(width 0.18288)
		(layer "In11.Cu")
		(net "M_D_CPU1_SB_CA<2>")
	)
	(segment
		(start 62.730126 -249.470926)
		(end 61.668406 -249.470926)
		(width 0.18288)
		(layer "In11.Cu")
		(net "M_D_CPU1_SB_CA<2>")
	)
	(segment
		(start 53.10759 -251.754386)
		(end 53.10759 -251.302266)
		(width 0.18288)
		(layer "In11.Cu")
		(net "M_D_CPU1_SB_CA<2>")
	)
	(segment
		(start 51.922426 -251.29109)
		(end 49.378362 -251.29109)
		(width 0.18288)
		(layer "In11.Cu")
		(net "M_D_CPU1_SB_CA<2>")
	)
	(segment
		(start 36.68649 -251.109226)
		(end 36.504626 -251.29109)
		(width 0.18288)
		(layer "In11.Cu")
		(net "M_D_CPU1_SB_CA<2>")
	)
	(segment
		(start 53.80863 -251.302266)
		(end 53.80863 -251.754386)
		(width 0.18288)
		(layer "In11.Cu")
		(net "M_D_CPU1_SB_CA<2>")
	)
	(segment
		(start 93.126814 -249.295666)
		(end 93.112082 -249.304302)
		(width 0.088646)
		(layer "In11.Cu")
		(net "M_D_CPU1_SB_CA<2>")
	)
	(segment
		(start 49.378362 -251.29109)
		(end 49.077626 -251.591826)
		(width 0.18288)
		(layer "In11.Cu")
		(net "M_D_CPU1_SB_CA<2>")
	)
	(segment
		(start 87.488014 -249.295666)
		(end 87.473282 -249.304302)
		(width 0.088646)
		(layer "In11.Cu")
		(net "M_D_CPU1_SB_CA<2>")
	)
	(segment
		(start 17.516094 -251.483876)
		(end 17.323054 -251.290836)
		(width 0.18288)
		(layer "In11.Cu")
		(net "M_D_CPU1_SB_CA<2>")
	)
	(segment
		(start 25.658826 -251.414026)
		(end 25.404826 -251.160026)
		(width 0.18288)
		(layer "In11.Cu")
		(net "M_D_CPU1_SB_CA<2>")
	)
	(segment
		(start 17.709134 -252.038358)
		(end 17.516094 -251.845318)
		(width 0.18288)
		(layer "In11.Cu")
		(net "M_D_CPU1_SB_CA<2>")
	)
	(segment
		(start 52.10429 -251.109226)
		(end 51.922426 -251.29109)
		(width 0.18288)
		(layer "In11.Cu")
		(net "M_D_CPU1_SB_CA<2>")
	)
	(segment
		(start 85.32622 -249.371358)
		(end 85.23478 -249.371358)
		(width 0.088646)
		(layer "In11.Cu")
		(net "M_D_CPU1_SB_CA<2>")
	)
	(segment
		(start 75.941936 -248.345706)
		(end 74.668888 -249.618754)
		(width 0.18288)
		(layer "In11.Cu")
		(net "M_D_CPU1_SB_CA<2>")
	)
	(segment
		(start 53.10759 -251.302266)
		(end 52.91455 -251.109226)
		(width 0.18288)
		(layer "In11.Cu")
		(net "M_D_CPU1_SB_CA<2>")
	)
	(segment
		(start 38.47973 -251.85624)
		(end 38.16477 -251.85624)
		(width 0.18288)
		(layer "In11.Cu")
		(net "M_D_CPU1_SB_CA<2>")
	)
	(segment
		(start 40.930322 -251.343922)
		(end 40.695626 -251.109226)
		(width 0.18288)
		(layer "In11.Cu")
		(net "M_D_CPU1_SB_CA<2>")
	)
	(segment
		(start 58.360056 -250.370086)
		(end 58.100214 -250.629928)
		(width 0.18288)
		(layer "In11.Cu")
		(net "M_D_CPU1_SB_CA<2>")
	)
	(segment
		(start 19.619214 -251.483876)
		(end 19.619214 -251.845318)
		(width 0.18288)
		(layer "In11.Cu")
		(net "M_D_CPU1_SB_CA<2>")
	)
	(segment
		(start 79.784448 -248.345706)
		(end 75.941936 -248.345706)
		(width 0.18288)
		(layer "In11.Cu")
		(net "M_D_CPU1_SB_CA<2>")
	)
	(segment
		(start 94.066614 -249.295666)
		(end 94.051882 -249.304302)
		(width 0.088646)
		(layer "In11.Cu")
		(net "M_D_CPU1_SB_CA<2>")
	)
	(segment
		(start 88.427814 -249.295666)
		(end 88.413082 -249.304302)
		(width 0.088646)
		(layer "In11.Cu")
		(net "M_D_CPU1_SB_CA<2>")
	)
	(segment
		(start 38.67277 -251.6632)
		(end 38.47973 -251.85624)
		(width 0.18288)
		(layer "In11.Cu")
		(net "M_D_CPU1_SB_CA<2>")
	)
	(segment
		(start 95.085662 -249.249946)
		(end 95.006414 -249.295666)
		(width 0.088646)
		(layer "In11.Cu")
		(net "M_D_CPU1_SB_CA<2>")
	)
	(segment
		(start 38.86581 -251.109226)
		(end 38.67277 -251.302266)
		(width 0.18288)
		(layer "In11.Cu")
		(net "M_D_CPU1_SB_CA<2>")
	)
	(segment
		(start 37.97173 -251.6632)
		(end 37.97173 -251.302266)
		(width 0.18288)
		(layer "In11.Cu")
		(net "M_D_CPU1_SB_CA<2>")
	)
	(segment
		(start 44.33189 -251.109226)
		(end 44.097194 -251.343922)
		(width 0.18288)
		(layer "In11.Cu")
		(net "M_D_CPU1_SB_CA<2>")
	)
	(segment
		(start 18.725134 -251.3076)
		(end 18.410174 -251.3076)
		(width 0.18288)
		(layer "In11.Cu")
		(net "M_D_CPU1_SB_CA<2>")
	)
	(segment
		(start 19.619214 -251.845318)
		(end 19.426174 -252.038358)
		(width 0.18288)
		(layer "In11.Cu")
		(net "M_D_CPU1_SB_CA<2>")
	)
	(segment
		(start 33.33115 -251.29109)
		(end 30.18409 -251.29109)
		(width 0.18288)
		(layer "In11.Cu")
		(net "M_D_CPU1_SB_CA<2>")
	)
	(segment
		(start 34.066226 -251.464826)
		(end 33.504886 -251.464826)
		(width 0.18288)
		(layer "In11.Cu")
		(net "M_D_CPU1_SB_CA<2>")
	)
	(segment
		(start 40.695626 -251.109226)
		(end 38.86581 -251.109226)
		(width 0.18288)
		(layer "In11.Cu")
		(net "M_D_CPU1_SB_CA<2>")
	)
	(segment
		(start 18.410174 -251.3076)
		(end 18.217134 -251.50064)
		(width 0.18288)
		(layer "In11.Cu")
		(net "M_D_CPU1_SB_CA<2>")
	)
	(segment
		(start 33.504886 -251.464826)
		(end 33.33115 -251.29109)
		(width 0.18288)
		(layer "In11.Cu")
		(net "M_D_CPU1_SB_CA<2>")
	)
	(segment
		(start 18.918174 -251.845318)
		(end 18.918174 -251.50064)
		(width 0.18288)
		(layer "In11.Cu")
		(net "M_D_CPU1_SB_CA<2>")
	)
	(segment
		(start 45.318426 -251.109226)
		(end 44.33189 -251.109226)
		(width 0.18288)
		(layer "In11.Cu")
		(net "M_D_CPU1_SB_CA<2>")
	)
	(segment
		(start 58.100214 -250.629928)
		(end 56.925972 -250.629928)
		(width 0.18288)
		(layer "In11.Cu")
		(net "M_D_CPU1_SB_CA<2>")
	)
	(segment
		(start 28.96489 -251.414026)
		(end 25.658826 -251.414026)
		(width 0.18288)
		(layer "In11.Cu")
		(net "M_D_CPU1_SB_CA<2>")
	)
	(segment
		(start 63.561468 -248.639584)
		(end 62.730126 -249.470926)
		(width 0.18288)
		(layer "In11.Cu")
		(net "M_D_CPU1_SB_CA<2>")
	)
	(segment
		(start 19.426174 -252.038358)
		(end 19.111214 -252.038358)
		(width 0.18288)
		(layer "In11.Cu")
		(net "M_D_CPU1_SB_CA<2>")
	)
	(arc
		(start 86.92261 -249.295666)
		(mid 86.735412 -249.245523)
		(end 86.548214 -249.295666)
		(width 0.088646)
		(layer "In11.Cu")
		(net "M_D_CPU1_SB_CA<2>")
	)
	(arc
		(start 90.682064 -249.295666)
		(mid 90.494866 -249.245523)
		(end 90.307668 -249.295666)
		(width 0.088646)
		(layer "In11.Cu")
		(net "M_D_CPU1_SB_CA<2>")
	)
	(arc
		(start 86.533482 -249.304302)
		(mid 86.257007 -249.371622)
		(end 85.98281 -249.295666)
		(width 0.088646)
		(layer "In11.Cu")
		(net "M_D_CPU1_SB_CA<2>")
	)
	(arc
		(start 85.362542 -249.370342)
		(mid 85.344389 -249.371145)
		(end 85.32622 -249.371358)
		(width 0.088646)
		(layer "In11.Cu")
		(net "M_D_CPU1_SB_CA<2>")
	)
	(arc
		(start 85.98281 -249.295666)
		(mid 85.795612 -249.245523)
		(end 85.608414 -249.295666)
		(width 0.088646)
		(layer "In11.Cu")
		(net "M_D_CPU1_SB_CA<2>")
	)
	(arc
		(start 92.172282 -249.304302)
		(mid 91.895807 -249.371622)
		(end 91.62161 -249.295666)
		(width 0.088646)
		(layer "In11.Cu")
		(net "M_D_CPU1_SB_CA<2>")
	)
	(arc
		(start 87.473282 -249.304302)
		(mid 87.196807 -249.371622)
		(end 86.92261 -249.295666)
		(width 0.088646)
		(layer "In11.Cu")
		(net "M_D_CPU1_SB_CA<2>")
	)
	(arc
		(start 87.86241 -249.295666)
		(mid 87.675212 -249.245523)
		(end 87.488014 -249.295666)
		(width 0.088646)
		(layer "In11.Cu")
		(net "M_D_CPU1_SB_CA<2>")
	)
	(arc
		(start 89.74201 -249.295666)
		(mid 89.554812 -249.245523)
		(end 89.367614 -249.295666)
		(width 0.088646)
		(layer "In11.Cu")
		(net "M_D_CPU1_SB_CA<2>")
	)
	(arc
		(start 91.62161 -249.295666)
		(mid 91.434412 -249.245523)
		(end 91.247214 -249.295666)
		(width 0.088646)
		(layer "In11.Cu")
		(net "M_D_CPU1_SB_CA<2>")
	)
	(arc
		(start 95.663766 -248.806208)
		(mid 95.389246 -249.04701)
		(end 95.085662 -249.249946)
		(width 0.088646)
		(layer "In11.Cu")
		(net "M_D_CPU1_SB_CA<2>")
	)
	(arc
		(start 94.051882 -249.304302)
		(mid 93.775407 -249.371622)
		(end 93.50121 -249.295666)
		(width 0.088646)
		(layer "In11.Cu")
		(net "M_D_CPU1_SB_CA<2>")
	)
	(arc
		(start 93.50121 -249.295666)
		(mid 93.314012 -249.245523)
		(end 93.126814 -249.295666)
		(width 0.088646)
		(layer "In11.Cu")
		(net "M_D_CPU1_SB_CA<2>")
	)
	(arc
		(start 94.44101 -249.295666)
		(mid 94.253812 -249.245523)
		(end 94.066614 -249.295666)
		(width 0.088646)
		(layer "In11.Cu")
		(net "M_D_CPU1_SB_CA<2>")
	)
	(arc
		(start 95.006414 -249.295666)
		(mid 94.723712 -249.371442)
		(end 94.44101 -249.295666)
		(width 0.088646)
		(layer "In11.Cu")
		(net "M_D_CPU1_SB_CA<2>")
	)
	(arc
		(start 92.56141 -249.295666)
		(mid 92.374212 -249.245523)
		(end 92.187014 -249.295666)
		(width 0.088646)
		(layer "In11.Cu")
		(net "M_D_CPU1_SB_CA<2>")
	)
	(arc
		(start 88.80221 -249.295666)
		(mid 88.615012 -249.245523)
		(end 88.427814 -249.295666)
		(width 0.088646)
		(layer "In11.Cu")
		(net "M_D_CPU1_SB_CA<2>")
	)
	(arc
		(start 91.2368 -249.301762)
		(mid 90.958622 -249.371485)
		(end 90.682064 -249.295666)
		(width 0.088646)
		(layer "In11.Cu")
		(net "M_D_CPU1_SB_CA<2>")
	)
	(arc
		(start 89.352882 -249.304302)
		(mid 89.076407 -249.371622)
		(end 88.80221 -249.295666)
		(width 0.088646)
		(layer "In11.Cu")
		(net "M_D_CPU1_SB_CA<2>")
	)
	(arc
		(start 85.608414 -249.295666)
		(mid 85.489783 -249.347186)
		(end 85.362542 -249.370342)
		(width 0.088646)
		(layer "In11.Cu")
		(net "M_D_CPU1_SB_CA<2>")
	)
	(arc
		(start 90.297254 -249.301762)
		(mid 90.018822 -249.371608)
		(end 89.74201 -249.295666)
		(width 0.088646)
		(layer "In11.Cu")
		(net "M_D_CPU1_SB_CA<2>")
	)
	(arc
		(start 88.413082 -249.304302)
		(mid 88.136607 -249.371622)
		(end 87.86241 -249.295666)
		(width 0.088646)
		(layer "In11.Cu")
		(net "M_D_CPU1_SB_CA<2>")
	)
	(arc
		(start 93.112082 -249.304302)
		(mid 92.835607 -249.371622)
		(end 92.56141 -249.295666)
		(width 0.088646)
		(layer "In11.Cu")
		(net "M_D_CPU1_SB_CA<2>")
	)
	(segment
		(start 20.889214 -251.716794)
		(end 19.784314 -251.716794)
		(width 0.20066)
		(layer "F.Cu")
		(net "M_D_CPU1_SB_CA<1>")
	)
	(segment
		(start 18.968212 -251.716794)
		(end 19.784314 -251.716794)
		(width 0.20066)
		(layer "F.Cu")
		(net "M_D_CPU1_SB_CA<1>")
	)
	(segment
		(start 14.063726 -252.013466)
		(end 14.20622 -252.15596)
		(width 0.20066)
		(layer "F.Cu")
		(net "M_D_CPU1_SB_CA<1>")
	)
	(segment
		(start 17.578578 -251.992638)
		(end 17.578578 -251.841)
		(width 0.20066)
		(layer "F.Cu")
		(net "M_D_CPU1_SB_CA<1>")
	)
	(segment
		(start 18.314162 -251.924312)
		(end 18.760694 -251.924312)
		(width 0.20066)
		(layer "F.Cu")
		(net "M_D_CPU1_SB_CA<1>")
	)
	(segment
		(start 12.240514 -251.716794)
		(end 13.937742 -251.716794)
		(width 0.20066)
		(layer "F.Cu")
		(net "M_D_CPU1_SB_CA<1>")
	)
	(segment
		(start 18.760694 -251.924312)
		(end 18.968212 -251.716794)
		(width 0.20066)
		(layer "F.Cu")
		(net "M_D_CPU1_SB_CA<1>")
	)
	(segment
		(start 14.063726 -251.842778)
		(end 14.063726 -252.013466)
		(width 0.20066)
		(layer "F.Cu")
		(net "M_D_CPU1_SB_CA<1>")
	)
	(segment
		(start 14.560042 -252.15596)
		(end 14.574266 -252.141736)
		(width 0.101854)
		(layer "F.Cu")
		(net "M_D_CPU1_SB_CA<1>")
	)
	(segment
		(start 14.20622 -252.15596)
		(end 14.560042 -252.15596)
		(width 0.20066)
		(layer "F.Cu")
		(net "M_D_CPU1_SB_CA<1>")
	)
	(segment
		(start 98.953066 -247.992138)
		(end 98.953066 -248.528078)
		(width 0.20066)
		(layer "F.Cu")
		(net "M_D_CPU1_SB_CA<1>")
	)
	(segment
		(start 17.42948 -252.141736)
		(end 17.578578 -251.992638)
		(width 0.20066)
		(layer "F.Cu")
		(net "M_D_CPU1_SB_CA<1>")
	)
	(segment
		(start 16.885158 -252.141736)
		(end 17.42948 -252.141736)
		(width 0.20066)
		(layer "F.Cu")
		(net "M_D_CPU1_SB_CA<1>")
	)
	(segment
		(start 18.102326 -251.712476)
		(end 18.314162 -251.924312)
		(width 0.20066)
		(layer "F.Cu")
		(net "M_D_CPU1_SB_CA<1>")
	)
	(segment
		(start 17.707102 -251.712476)
		(end 18.102326 -251.712476)
		(width 0.20066)
		(layer "F.Cu")
		(net "M_D_CPU1_SB_CA<1>")
	)
	(segment
		(start 17.578578 -251.841)
		(end 17.707102 -251.712476)
		(width 0.20066)
		(layer "F.Cu")
		(net "M_D_CPU1_SB_CA<1>")
	)
	(segment
		(start 13.937742 -251.716794)
		(end 14.063726 -251.842778)
		(width 0.20066)
		(layer "F.Cu")
		(net "M_D_CPU1_SB_CA<1>")
	)
	(segment
		(start 14.812264 -252.141736)
		(end 16.885158 -252.141736)
		(width 0.1016)
		(layer "F.Cu")
		(net "M_D_CPU1_SB_CA<1>")
	)
	(segment
		(start 14.574266 -252.141736)
		(end 14.812264 -252.141736)
		(width 0.101854)
		(layer "F.Cu")
		(net "M_D_CPU1_SB_CA<1>")
	)
	(segment
		(start 21.602446 -252.430026)
		(end 20.889214 -251.716794)
		(width 0.18288)
		(layer "In11.Cu")
		(net "M_D_CPU1_SB_CA<1>")
	)
	(segment
		(start 63.467234 -249.798078)
		(end 62.742826 -250.522486)
		(width 0.18288)
		(layer "In11.Cu")
		(net "M_D_CPU1_SB_CA<1>")
	)
	(segment
		(start 97.730564 -249.130566)
		(end 97.724468 -249.134122)
		(width 0.088646)
		(layer "In11.Cu")
		(net "M_D_CPU1_SB_CA<1>")
	)
	(segment
		(start 47.703232 -252.455426)
		(end 47.389034 -252.141228)
		(width 0.18288)
		(layer "In11.Cu")
		(net "M_D_CPU1_SB_CA<1>")
	)
	(segment
		(start 29.412946 -252.415548)
		(end 28.921456 -251.924058)
		(width 0.18288)
		(layer "In11.Cu")
		(net "M_D_CPU1_SB_CA<1>")
	)
	(segment
		(start 52.160678 -252.480826)
		(end 51.820826 -252.140974)
		(width 0.18288)
		(layer "In11.Cu")
		(net "M_D_CPU1_SB_CA<1>")
	)
	(segment
		(start 27.383486 -252.571758)
		(end 27.068526 -252.571758)
		(width 0.18288)
		(layer "In11.Cu")
		(net "M_D_CPU1_SB_CA<1>")
	)
	(segment
		(start 48.717708 -252.140974)
		(end 48.343312 -252.140974)
		(width 0.18288)
		(layer "In11.Cu")
		(net "M_D_CPU1_SB_CA<1>")
	)
	(segment
		(start 60.976002 -251.15901)
		(end 59.347862 -251.15901)
		(width 0.18288)
		(layer "In11.Cu")
		(net "M_D_CPU1_SB_CA<1>")
	)
	(segment
		(start 38.803326 -252.379226)
		(end 36.945824 -252.379226)
		(width 0.18288)
		(layer "In11.Cu")
		(net "M_D_CPU1_SB_CA<1>")
	)
	(segment
		(start 97.918016 -248.787666)
		(end 97.918016 -248.806208)
		(width 0.088646)
		(layer "In11.Cu")
		(net "M_D_CPU1_SB_CA<1>")
	)
	(segment
		(start 97.739454 -249.125486)
		(end 97.730564 -249.130566)
		(width 0.088646)
		(layer "In11.Cu")
		(net "M_D_CPU1_SB_CA<1>")
	)
	(segment
		(start 36.707826 -252.141228)
		(end 35.020504 -252.141228)
		(width 0.18288)
		(layer "In11.Cu")
		(net "M_D_CPU1_SB_CA<1>")
	)
	(segment
		(start 26.682446 -251.924058)
		(end 25.656794 -251.924058)
		(width 0.18288)
		(layer "In11.Cu")
		(net "M_D_CPU1_SB_CA<1>")
	)
	(segment
		(start 88.363044 -250.057666)
		(end 88.235282 -249.929904)
		(width 0.18288)
		(layer "In11.Cu")
		(net "M_D_CPU1_SB_CA<1>")
	)
	(segment
		(start 43.35272 -252.0315)
		(end 42.977054 -252.407166)
		(width 0.18288)
		(layer "In11.Cu")
		(net "M_D_CPU1_SB_CA<1>")
	)
	(segment
		(start 88.235282 -249.929904)
		(end 80.864964 -249.929904)
		(width 0.18288)
		(layer "In11.Cu")
		(net "M_D_CPU1_SB_CA<1>")
	)
	(segment
		(start 48.343312 -252.140974)
		(end 48.02886 -252.455426)
		(width 0.18288)
		(layer "In11.Cu")
		(net "M_D_CPU1_SB_CA<1>")
	)
	(segment
		(start 49.785778 -252.140974)
		(end 49.471326 -252.455426)
		(width 0.18288)
		(layer "In11.Cu")
		(net "M_D_CPU1_SB_CA<1>")
	)
	(segment
		(start 40.281352 -252.0315)
		(end 40.086026 -252.226826)
		(width 0.18288)
		(layer "In11.Cu")
		(net "M_D_CPU1_SB_CA<1>")
	)
	(segment
		(start 22.87397 -252.430026)
		(end 21.602446 -252.430026)
		(width 0.18288)
		(layer "In11.Cu")
		(net "M_D_CPU1_SB_CA<1>")
	)
	(segment
		(start 43.862498 -252.0315)
		(end 43.35272 -252.0315)
		(width 0.18288)
		(layer "In11.Cu")
		(net "M_D_CPU1_SB_CA<1>")
	)
	(segment
		(start 80.864964 -249.929904)
		(end 79.626206 -248.691146)
		(width 0.18288)
		(layer "In11.Cu")
		(net "M_D_CPU1_SB_CA<1>")
	)
	(segment
		(start 51.820826 -252.140974)
		(end 49.785778 -252.140974)
		(width 0.18288)
		(layer "In11.Cu")
		(net "M_D_CPU1_SB_CA<1>")
	)
	(segment
		(start 45.369226 -252.480826)
		(end 44.311824 -252.480826)
		(width 0.18288)
		(layer "In11.Cu")
		(net "M_D_CPU1_SB_CA<1>")
	)
	(segment
		(start 33.97758 -252.017022)
		(end 33.54959 -252.017022)
		(width 0.18288)
		(layer "In11.Cu")
		(net "M_D_CPU1_SB_CA<1>")
	)
	(segment
		(start 49.03216 -252.455426)
		(end 48.717708 -252.140974)
		(width 0.18288)
		(layer "In11.Cu")
		(net "M_D_CPU1_SB_CA<1>")
	)
	(segment
		(start 42.977054 -252.407166)
		(end 42.425112 -252.407166)
		(width 0.18288)
		(layer "In11.Cu")
		(net "M_D_CPU1_SB_CA<1>")
	)
	(segment
		(start 98.953066 -247.992392)
		(end 98.796348 -248.263156)
		(width 0.088646)
		(layer "In11.Cu")
		(net "M_D_CPU1_SB_CA<1>")
	)
	(segment
		(start 32.506666 -252.141228)
		(end 30.40888 -252.141228)
		(width 0.18288)
		(layer "In11.Cu")
		(net "M_D_CPU1_SB_CA<1>")
	)
	(segment
		(start 49.471326 -252.455426)
		(end 49.03216 -252.455426)
		(width 0.18288)
		(layer "In11.Cu")
		(net "M_D_CPU1_SB_CA<1>")
	)
	(segment
		(start 25.656794 -251.924058)
		(end 25.150826 -252.430026)
		(width 0.18288)
		(layer "In11.Cu")
		(net "M_D_CPU1_SB_CA<1>")
	)
	(segment
		(start 23.26005 -251.686314)
		(end 23.06701 -251.879354)
		(width 0.18288)
		(layer "In11.Cu")
		(net "M_D_CPU1_SB_CA<1>")
	)
	(segment
		(start 79.626206 -248.691146)
		(end 76.315316 -248.691146)
		(width 0.18288)
		(layer "In11.Cu")
		(net "M_D_CPU1_SB_CA<1>")
	)
	(segment
		(start 42.425112 -252.407166)
		(end 42.049446 -252.0315)
		(width 0.18288)
		(layer "In11.Cu")
		(net "M_D_CPU1_SB_CA<1>")
	)
	(segment
		(start 62.742826 -250.522486)
		(end 61.612526 -250.522486)
		(width 0.18288)
		(layer "In11.Cu")
		(net "M_D_CPU1_SB_CA<1>")
	)
	(segment
		(start 30.13456 -252.415548)
		(end 29.412946 -252.415548)
		(width 0.18288)
		(layer "In11.Cu")
		(net "M_D_CPU1_SB_CA<1>")
	)
	(segment
		(start 94.34449 -250.057666)
		(end 88.363044 -250.057666)
		(width 0.18288)
		(layer "In11.Cu")
		(net "M_D_CPU1_SB_CA<1>")
	)
	(segment
		(start 36.945824 -252.379226)
		(end 36.707826 -252.141228)
		(width 0.18288)
		(layer "In11.Cu")
		(net "M_D_CPU1_SB_CA<1>")
	)
	(segment
		(start 26.875486 -252.117098)
		(end 26.682446 -251.924058)
		(width 0.18288)
		(layer "In11.Cu")
		(net "M_D_CPU1_SB_CA<1>")
	)
	(segment
		(start 48.02886 -252.455426)
		(end 47.703232 -252.455426)
		(width 0.18288)
		(layer "In11.Cu")
		(net "M_D_CPU1_SB_CA<1>")
	)
	(segment
		(start 59.100466 -251.406406)
		(end 55.943246 -251.406406)
		(width 0.18288)
		(layer "In11.Cu")
		(net "M_D_CPU1_SB_CA<1>")
	)
	(segment
		(start 38.955726 -252.226826)
		(end 38.803326 -252.379226)
		(width 0.18288)
		(layer "In11.Cu")
		(net "M_D_CPU1_SB_CA<1>")
	)
	(segment
		(start 61.612526 -250.522486)
		(end 60.976002 -251.15901)
		(width 0.18288)
		(layer "In11.Cu")
		(net "M_D_CPU1_SB_CA<1>")
	)
	(segment
		(start 33.54959 -252.017022)
		(end 33.177226 -252.389386)
		(width 0.18288)
		(layer "In11.Cu")
		(net "M_D_CPU1_SB_CA<1>")
	)
	(segment
		(start 23.96109 -252.430026)
		(end 23.76805 -252.236986)
		(width 0.18288)
		(layer "In11.Cu")
		(net "M_D_CPU1_SB_CA<1>")
	)
	(segment
		(start 66.847466 -250.14047)
		(end 66.505074 -249.798078)
		(width 0.18288)
		(layer "In11.Cu")
		(net "M_D_CPU1_SB_CA<1>")
	)
	(segment
		(start 97.447862 -249.620024)
		(end 97.447862 -249.90933)
		(width 0.088646)
		(layer "In11.Cu")
		(net "M_D_CPU1_SB_CA<1>")
	)
	(segment
		(start 30.40888 -252.141228)
		(end 30.13456 -252.415548)
		(width 0.18288)
		(layer "In11.Cu")
		(net "M_D_CPU1_SB_CA<1>")
	)
	(segment
		(start 23.76805 -251.879354)
		(end 23.57501 -251.686314)
		(width 0.18288)
		(layer "In11.Cu")
		(net "M_D_CPU1_SB_CA<1>")
	)
	(segment
		(start 33.177226 -252.389386)
		(end 32.754824 -252.389386)
		(width 0.18288)
		(layer "In11.Cu")
		(net "M_D_CPU1_SB_CA<1>")
	)
	(segment
		(start 23.57501 -251.686314)
		(end 23.26005 -251.686314)
		(width 0.18288)
		(layer "In11.Cu")
		(net "M_D_CPU1_SB_CA<1>")
	)
	(segment
		(start 76.315316 -248.691146)
		(end 74.865992 -250.14047)
		(width 0.18288)
		(layer "In11.Cu")
		(net "M_D_CPU1_SB_CA<1>")
	)
	(segment
		(start 59.347862 -251.15901)
		(end 59.100466 -251.406406)
		(width 0.18288)
		(layer "In11.Cu")
		(net "M_D_CPU1_SB_CA<1>")
	)
	(segment
		(start 74.865992 -250.14047)
		(end 66.847466 -250.14047)
		(width 0.18288)
		(layer "In11.Cu")
		(net "M_D_CPU1_SB_CA<1>")
	)
	(segment
		(start 28.921456 -251.924058)
		(end 27.769566 -251.924058)
		(width 0.18288)
		(layer "In11.Cu")
		(net "M_D_CPU1_SB_CA<1>")
	)
	(segment
		(start 47.389034 -252.141228)
		(end 45.708824 -252.141228)
		(width 0.18288)
		(layer "In11.Cu")
		(net "M_D_CPU1_SB_CA<1>")
	)
	(segment
		(start 42.049446 -252.0315)
		(end 40.281352 -252.0315)
		(width 0.18288)
		(layer "In11.Cu")
		(net "M_D_CPU1_SB_CA<1>")
	)
	(segment
		(start 23.06701 -252.236986)
		(end 22.87397 -252.430026)
		(width 0.18288)
		(layer "In11.Cu")
		(net "M_D_CPU1_SB_CA<1>")
	)
	(segment
		(start 27.769566 -251.924058)
		(end 27.576526 -252.117098)
		(width 0.18288)
		(layer "In11.Cu")
		(net "M_D_CPU1_SB_CA<1>")
	)
	(segment
		(start 23.06701 -251.879354)
		(end 23.06701 -252.236986)
		(width 0.18288)
		(layer "In11.Cu")
		(net "M_D_CPU1_SB_CA<1>")
	)
	(segment
		(start 98.796348 -248.263156)
		(end 98.707448 -248.287032)
		(width 0.088646)
		(layer "In11.Cu")
		(net "M_D_CPU1_SB_CA<1>")
	)
	(segment
		(start 25.150826 -252.430026)
		(end 23.96109 -252.430026)
		(width 0.18288)
		(layer "In11.Cu")
		(net "M_D_CPU1_SB_CA<1>")
	)
	(segment
		(start 44.311824 -252.480826)
		(end 43.862498 -252.0315)
		(width 0.18288)
		(layer "In11.Cu")
		(net "M_D_CPU1_SB_CA<1>")
	)
	(segment
		(start 34.349944 -252.389386)
		(end 33.97758 -252.017022)
		(width 0.18288)
		(layer "In11.Cu")
		(net "M_D_CPU1_SB_CA<1>")
	)
	(segment
		(start 54.868826 -252.480826)
		(end 52.160678 -252.480826)
		(width 0.18288)
		(layer "In11.Cu")
		(net "M_D_CPU1_SB_CA<1>")
	)
	(segment
		(start 32.754824 -252.389386)
		(end 32.506666 -252.141228)
		(width 0.18288)
		(layer "In11.Cu")
		(net "M_D_CPU1_SB_CA<1>")
	)
	(segment
		(start 27.068526 -252.571758)
		(end 26.875486 -252.378718)
		(width 0.18288)
		(layer "In11.Cu")
		(net "M_D_CPU1_SB_CA<1>")
	)
	(segment
		(start 66.505074 -249.798078)
		(end 63.467234 -249.798078)
		(width 0.18288)
		(layer "In11.Cu")
		(net "M_D_CPU1_SB_CA<1>")
	)
	(segment
		(start 97.254314 -250.057666)
		(end 94.34449 -250.057666)
		(width 0.088646)
		(layer "In11.Cu")
		(net "M_D_CPU1_SB_CA<1>")
	)
	(segment
		(start 40.086026 -252.226826)
		(end 38.955726 -252.226826)
		(width 0.18288)
		(layer "In11.Cu")
		(net "M_D_CPU1_SB_CA<1>")
	)
	(segment
		(start 45.708824 -252.141228)
		(end 45.369226 -252.480826)
		(width 0.18288)
		(layer "In11.Cu")
		(net "M_D_CPU1_SB_CA<1>")
	)
	(segment
		(start 55.943246 -251.406406)
		(end 54.868826 -252.480826)
		(width 0.18288)
		(layer "In11.Cu")
		(net "M_D_CPU1_SB_CA<1>")
	)
	(segment
		(start 27.576526 -252.378718)
		(end 27.383486 -252.571758)
		(width 0.18288)
		(layer "In11.Cu")
		(net "M_D_CPU1_SB_CA<1>")
	)
	(segment
		(start 27.576526 -252.117098)
		(end 27.576526 -252.378718)
		(width 0.18288)
		(layer "In11.Cu")
		(net "M_D_CPU1_SB_CA<1>")
	)
	(segment
		(start 23.76805 -252.236986)
		(end 23.76805 -251.879354)
		(width 0.18288)
		(layer "In11.Cu")
		(net "M_D_CPU1_SB_CA<1>")
	)
	(segment
		(start 26.875486 -252.378718)
		(end 26.875486 -252.117098)
		(width 0.18288)
		(layer "In11.Cu")
		(net "M_D_CPU1_SB_CA<1>")
	)
	(segment
		(start 98.953066 -247.992138)
		(end 98.953066 -247.992392)
		(width 0.088646)
		(layer "In11.Cu")
		(net "M_D_CPU1_SB_CA<1>")
	)
	(segment
		(start 34.772346 -252.389386)
		(end 34.349944 -252.389386)
		(width 0.18288)
		(layer "In11.Cu")
		(net "M_D_CPU1_SB_CA<1>")
	)
	(segment
		(start 35.020504 -252.141228)
		(end 34.772346 -252.389386)
		(width 0.18288)
		(layer "In11.Cu")
		(net "M_D_CPU1_SB_CA<1>")
	)
	(arc
		(start 98.707448 -248.287032)
		(mid 98.450449 -248.241606)
		(end 98.200464 -248.316496)
		(width 0.088646)
		(layer "In11.Cu")
		(net "M_D_CPU1_SB_CA<1>")
	)
	(arc
		(start 98.200464 -248.316496)
		(mid 97.998178 -248.515477)
		(end 97.918016 -248.787666)
		(width 0.088646)
		(layer "In11.Cu")
		(net "M_D_CPU1_SB_CA<1>")
	)
	(arc
		(start 97.413826 -249.991626)
		(mid 97.340641 -250.040526)
		(end 97.254314 -250.057666)
		(width 0.088646)
		(layer "In11.Cu")
		(net "M_D_CPU1_SB_CA<1>")
	)
	(arc
		(start 97.724468 -249.134122)
		(mid 97.521881 -249.340473)
		(end 97.447862 -249.620024)
		(width 0.088646)
		(layer "In11.Cu")
		(net "M_D_CPU1_SB_CA<1>")
	)
	(arc
		(start 97.447862 -249.90933)
		(mid 97.439007 -249.953848)
		(end 97.413826 -249.991626)
		(width 0.088646)
		(layer "In11.Cu")
		(net "M_D_CPU1_SB_CA<1>")
	)
	(arc
		(start 97.918016 -248.806208)
		(mid 97.870337 -248.989108)
		(end 97.739454 -249.125486)
		(width 0.088646)
		(layer "In11.Cu")
		(net "M_D_CPU1_SB_CA<1>")
	)
	(segment
		(start 10.19048 -252.778006)
		(end 10.344912 -252.623574)
		(width 0.20066)
		(layer "F.Cu")
		(net "M_D_CPU1_SB_CA<0>")
	)
	(segment
		(start 13.110718 -252.141736)
		(end 13.441426 -252.141736)
		(width 0.101854)
		(layer "F.Cu")
		(net "M_D_CPU1_SB_CA<0>")
	)
	(segment
		(start 98.483166 -249.341894)
		(end 98.483166 -248.806208)
		(width 0.20066)
		(layer "F.Cu")
		(net "M_D_CPU1_SB_CA<0>")
	)
	(segment
		(start 9.686036 -252.778006)
		(end 10.19048 -252.778006)
		(width 0.20066)
		(layer "F.Cu")
		(net "M_D_CPU1_SB_CA<0>")
	)
	(segment
		(start 9.474708 -252.566678)
		(end 9.686036 -252.778006)
		(width 0.20066)
		(layer "F.Cu")
		(net "M_D_CPU1_SB_CA<0>")
	)
	(segment
		(start 13.441426 -252.141736)
		(end 13.619988 -252.141736)
		(width 0.20066)
		(layer "F.Cu")
		(net "M_D_CPU1_SB_CA<0>")
	)
	(segment
		(start 98.482912 -249.342148)
		(end 98.483166 -249.341894)
		(width 0.20066)
		(layer "F.Cu")
		(net "M_D_CPU1_SB_CA<0>")
	)
	(segment
		(start 14.04493 -252.566678)
		(end 15.684246 -252.566678)
		(width 0.20066)
		(layer "F.Cu")
		(net "M_D_CPU1_SB_CA<0>")
	)
	(segment
		(start 13.619988 -252.141736)
		(end 14.04493 -252.566678)
		(width 0.20066)
		(layer "F.Cu")
		(net "M_D_CPU1_SB_CA<0>")
	)
	(segment
		(start 11.11631 -252.132846)
		(end 11.1252 -252.141736)
		(width 0.1016)
		(layer "F.Cu")
		(net "M_D_CPU1_SB_CA<0>")
	)
	(segment
		(start 15.684246 -252.566678)
		(end 16.789146 -252.566678)
		(width 0.20066)
		(layer "F.Cu")
		(net "M_D_CPU1_SB_CA<0>")
	)
	(segment
		(start 10.344912 -252.623574)
		(end 10.344912 -252.295406)
		(width 0.20066)
		(layer "F.Cu")
		(net "M_D_CPU1_SB_CA<0>")
	)
	(segment
		(start 8.140446 -252.566678)
		(end 9.474708 -252.566678)
		(width 0.20066)
		(layer "F.Cu")
		(net "M_D_CPU1_SB_CA<0>")
	)
	(segment
		(start 10.507472 -252.132846)
		(end 11.11631 -252.132846)
		(width 0.20066)
		(layer "F.Cu")
		(net "M_D_CPU1_SB_CA<0>")
	)
	(segment
		(start 10.344912 -252.295406)
		(end 10.507472 -252.132846)
		(width 0.20066)
		(layer "F.Cu")
		(net "M_D_CPU1_SB_CA<0>")
	)
	(segment
		(start 11.1252 -252.141736)
		(end 13.110718 -252.141736)
		(width 0.1016)
		(layer "F.Cu")
		(net "M_D_CPU1_SB_CA<0>")
	)
	(segment
		(start 21.250402 -253.10465)
		(end 20.31365 -253.10465)
		(width 0.18288)
		(layer "In11.Cu")
		(net "M_D_CPU1_SB_CA<0>")
	)
	(segment
		(start 85.318346 -250.913646)
		(end 81.355946 -250.913646)
		(width 0.18288)
		(layer "In11.Cu")
		(net "M_D_CPU1_SB_CA<0>")
	)
	(segment
		(start 36.146232 -253.081028)
		(end 35.872928 -253.081028)
		(width 0.18288)
		(layer "In11.Cu")
		(net "M_D_CPU1_SB_CA<0>")
	)
	(segment
		(start 46.784514 -253.045214)
		(end 46.730412 -252.991112)
		(width 0.18288)
		(layer "In11.Cu")
		(net "M_D_CPU1_SB_CA<0>")
	)
	(segment
		(start 47.129446 -253.045214)
		(end 46.784514 -253.045214)
		(width 0.18288)
		(layer "In11.Cu")
		(net "M_D_CPU1_SB_CA<0>")
	)
	(segment
		(start 19.918426 -252.709426)
		(end 18.121122 -252.709426)
		(width 0.18288)
		(layer "In11.Cu")
		(net "M_D_CPU1_SB_CA<0>")
	)
	(segment
		(start 41.78554 -252.991112)
		(end 41.737026 -253.039626)
		(width 0.18288)
		(layer "In11.Cu")
		(net "M_D_CPU1_SB_CA<0>")
	)
	(segment
		(start 25.635712 -252.991112)
		(end 21.36394 -252.991112)
		(width 0.18288)
		(layer "In11.Cu")
		(net "M_D_CPU1_SB_CA<0>")
	)
	(segment
		(start 28.032202 -252.991112)
		(end 27.907488 -253.115826)
		(width 0.18288)
		(layer "In11.Cu")
		(net "M_D_CPU1_SB_CA<0>")
	)
	(segment
		(start 39.05758 -252.887226)
		(end 38.953694 -252.991112)
		(width 0.18288)
		(layer "In11.Cu")
		(net "M_D_CPU1_SB_CA<0>")
	)
	(segment
		(start 17.978374 -252.566678)
		(end 16.789146 -252.566678)
		(width 0.18288)
		(layer "In11.Cu")
		(net "M_D_CPU1_SB_CA<0>")
	)
	(segment
		(start 94.679008 -250.580398)
		(end 94.34449 -250.580398)
		(width 0.088646)
		(layer "In11.Cu")
		(net "M_D_CPU1_SB_CA<0>")
	)
	(segment
		(start 18.121122 -252.709426)
		(end 17.978374 -252.566678)
		(width 0.18288)
		(layer "In11.Cu")
		(net "M_D_CPU1_SB_CA<0>")
	)
	(segment
		(start 97.638616 -250.059444)
		(end 97.42678 -250.27128)
		(width 0.088646)
		(layer "In11.Cu")
		(net "M_D_CPU1_SB_CA<0>")
	)
	(segment
		(start 56.253126 -251.924566)
		(end 55.18658 -252.991112)
		(width 0.18288)
		(layer "In11.Cu")
		(net "M_D_CPU1_SB_CA<0>")
	)
	(segment
		(start 35.872928 -253.081028)
		(end 35.783012 -252.991112)
		(width 0.18288)
		(layer "In11.Cu")
		(net "M_D_CPU1_SB_CA<0>")
	)
	(segment
		(start 31.64459 -253.09449)
		(end 31.541212 -252.991112)
		(width 0.18288)
		(layer "In11.Cu")
		(net "M_D_CPU1_SB_CA<0>")
	)
	(segment
		(start 98.295968 -248.48185)
		(end 98.287078 -248.48693)
		(width 0.088646)
		(layer "In11.Cu")
		(net "M_D_CPU1_SB_CA<0>")
	)
	(segment
		(start 94.988126 -250.27128)
		(end 94.679008 -250.580398)
		(width 0.088646)
		(layer "In11.Cu")
		(net "M_D_CPU1_SB_CA<0>")
	)
	(segment
		(start 32.128968 -252.991112)
		(end 32.02559 -253.09449)
		(width 0.18288)
		(layer "In11.Cu")
		(net "M_D_CPU1_SB_CA<0>")
	)
	(segment
		(start 97.42678 -250.27128)
		(end 94.988126 -250.27128)
		(width 0.088646)
		(layer "In11.Cu")
		(net "M_D_CPU1_SB_CA<0>")
	)
	(segment
		(start 38.953694 -252.991112)
		(end 36.236148 -252.991112)
		(width 0.18288)
		(layer "In11.Cu")
		(net "M_D_CPU1_SB_CA<0>")
	)
	(segment
		(start 62.914784 -251.267468)
		(end 61.698124 -251.267468)
		(width 0.18288)
		(layer "In11.Cu")
		(net "M_D_CPU1_SB_CA<0>")
	)
	(segment
		(start 36.236148 -252.991112)
		(end 36.146232 -253.081028)
		(width 0.18288)
		(layer "In11.Cu")
		(net "M_D_CPU1_SB_CA<0>")
	)
	(segment
		(start 50.868326 -253.039626)
		(end 50.819812 -252.991112)
		(width 0.18288)
		(layer "In11.Cu")
		(net "M_D_CPU1_SB_CA<0>")
	)
	(segment
		(start 61.698124 -251.267468)
		(end 61.231526 -251.734066)
		(width 0.18288)
		(layer "In11.Cu")
		(net "M_D_CPU1_SB_CA<0>")
	)
	(segment
		(start 60.091066 -252.221746)
		(end 57.873646 -252.221746)
		(width 0.18288)
		(layer "In11.Cu")
		(net "M_D_CPU1_SB_CA<0>")
	)
	(segment
		(start 66.39306 -250.408186)
		(end 63.774066 -250.408186)
		(width 0.18288)
		(layer "In11.Cu")
		(net "M_D_CPU1_SB_CA<0>")
	)
	(segment
		(start 51.316636 -252.991112)
		(end 51.268122 -253.039626)
		(width 0.18288)
		(layer "In11.Cu")
		(net "M_D_CPU1_SB_CA<0>")
	)
	(segment
		(start 76.688442 -249.036586)
		(end 75.062588 -250.66244)
		(width 0.18288)
		(layer "In11.Cu")
		(net "M_D_CPU1_SB_CA<0>")
	)
	(segment
		(start 55.18658 -252.991112)
		(end 51.316636 -252.991112)
		(width 0.18288)
		(layer "In11.Cu")
		(net "M_D_CPU1_SB_CA<0>")
	)
	(segment
		(start 40.987726 -252.887226)
		(end 39.05758 -252.887226)
		(width 0.18288)
		(layer "In11.Cu")
		(net "M_D_CPU1_SB_CA<0>")
	)
	(segment
		(start 79.478886 -249.036586)
		(end 76.688442 -249.036586)
		(width 0.18288)
		(layer "In11.Cu")
		(net "M_D_CPU1_SB_CA<0>")
	)
	(segment
		(start 94.34449 -250.580398)
		(end 85.651594 -250.580398)
		(width 0.18288)
		(layer "In11.Cu")
		(net "M_D_CPU1_SB_CA<0>")
	)
	(segment
		(start 66.647314 -250.66244)
		(end 66.39306 -250.408186)
		(width 0.18288)
		(layer "In11.Cu")
		(net "M_D_CPU1_SB_CA<0>")
	)
	(segment
		(start 20.31365 -253.10465)
		(end 19.918426 -252.709426)
		(width 0.18288)
		(layer "In11.Cu")
		(net "M_D_CPU1_SB_CA<0>")
	)
	(segment
		(start 81.355946 -250.913646)
		(end 79.478886 -249.036586)
		(width 0.18288)
		(layer "In11.Cu")
		(net "M_D_CPU1_SB_CA<0>")
	)
	(segment
		(start 27.907488 -253.115826)
		(end 25.760426 -253.115826)
		(width 0.18288)
		(layer "In11.Cu")
		(net "M_D_CPU1_SB_CA<0>")
	)
	(segment
		(start 97.638616 -249.611388)
		(end 97.638616 -250.059444)
		(width 0.088646)
		(layer "In11.Cu")
		(net "M_D_CPU1_SB_CA<0>")
	)
	(segment
		(start 61.231526 -251.734066)
		(end 60.578746 -251.734066)
		(width 0.18288)
		(layer "In11.Cu")
		(net "M_D_CPU1_SB_CA<0>")
	)
	(segment
		(start 35.783012 -252.991112)
		(end 32.128968 -252.991112)
		(width 0.18288)
		(layer "In11.Cu")
		(net "M_D_CPU1_SB_CA<0>")
	)
	(segment
		(start 21.36394 -252.991112)
		(end 21.250402 -253.10465)
		(width 0.18288)
		(layer "In11.Cu")
		(net "M_D_CPU1_SB_CA<0>")
	)
	(segment
		(start 97.83191 -249.29211)
		(end 97.825814 -249.295666)
		(width 0.088646)
		(layer "In11.Cu")
		(net "M_D_CPU1_SB_CA<0>")
	)
	(segment
		(start 98.63963 -248.53519)
		(end 98.618548 -248.457212)
		(width 0.088646)
		(layer "In11.Cu")
		(net "M_D_CPU1_SB_CA<0>")
	)
	(segment
		(start 41.140126 -253.039626)
		(end 40.987726 -252.887226)
		(width 0.18288)
		(layer "In11.Cu")
		(net "M_D_CPU1_SB_CA<0>")
	)
	(segment
		(start 57.873646 -252.221746)
		(end 57.576466 -251.924566)
		(width 0.18288)
		(layer "In11.Cu")
		(net "M_D_CPU1_SB_CA<0>")
	)
	(segment
		(start 25.760426 -253.115826)
		(end 25.635712 -252.991112)
		(width 0.18288)
		(layer "In11.Cu")
		(net "M_D_CPU1_SB_CA<0>")
	)
	(segment
		(start 51.268122 -253.039626)
		(end 50.868326 -253.039626)
		(width 0.18288)
		(layer "In11.Cu")
		(net "M_D_CPU1_SB_CA<0>")
	)
	(segment
		(start 63.774066 -250.408186)
		(end 62.914784 -251.267468)
		(width 0.18288)
		(layer "In11.Cu")
		(net "M_D_CPU1_SB_CA<0>")
	)
	(segment
		(start 41.737026 -253.039626)
		(end 41.140126 -253.039626)
		(width 0.18288)
		(layer "In11.Cu")
		(net "M_D_CPU1_SB_CA<0>")
	)
	(segment
		(start 75.062588 -250.66244)
		(end 66.647314 -250.66244)
		(width 0.18288)
		(layer "In11.Cu")
		(net "M_D_CPU1_SB_CA<0>")
	)
	(segment
		(start 31.541212 -252.991112)
		(end 28.032202 -252.991112)
		(width 0.18288)
		(layer "In11.Cu")
		(net "M_D_CPU1_SB_CA<0>")
	)
	(segment
		(start 50.819812 -252.991112)
		(end 47.183548 -252.991112)
		(width 0.18288)
		(layer "In11.Cu")
		(net "M_D_CPU1_SB_CA<0>")
	)
	(segment
		(start 46.730412 -252.991112)
		(end 41.78554 -252.991112)
		(width 0.18288)
		(layer "In11.Cu")
		(net "M_D_CPU1_SB_CA<0>")
	)
	(segment
		(start 98.483166 -248.806208)
		(end 98.63963 -248.53519)
		(width 0.088646)
		(layer "In11.Cu")
		(net "M_D_CPU1_SB_CA<0>")
	)
	(segment
		(start 57.576466 -251.924566)
		(end 56.253126 -251.924566)
		(width 0.18288)
		(layer "In11.Cu")
		(net "M_D_CPU1_SB_CA<0>")
	)
	(segment
		(start 85.651594 -250.580398)
		(end 85.318346 -250.913646)
		(width 0.18288)
		(layer "In11.Cu")
		(net "M_D_CPU1_SB_CA<0>")
	)
	(segment
		(start 32.02559 -253.09449)
		(end 31.64459 -253.09449)
		(width 0.18288)
		(layer "In11.Cu")
		(net "M_D_CPU1_SB_CA<0>")
	)
	(segment
		(start 47.183548 -252.991112)
		(end 47.129446 -253.045214)
		(width 0.18288)
		(layer "In11.Cu")
		(net "M_D_CPU1_SB_CA<0>")
	)
	(segment
		(start 60.578746 -251.734066)
		(end 60.091066 -252.221746)
		(width 0.18288)
		(layer "In11.Cu")
		(net "M_D_CPU1_SB_CA<0>")
	)
	(arc
		(start 98.108516 -248.806208)
		(mid 98.034525 -249.085774)
		(end 97.83191 -249.29211)
		(width 0.088646)
		(layer "In11.Cu")
		(net "M_D_CPU1_SB_CA<0>")
	)
	(arc
		(start 97.825814 -249.295666)
		(mid 97.690881 -249.42902)
		(end 97.638616 -249.611388)
		(width 0.088646)
		(layer "In11.Cu")
		(net "M_D_CPU1_SB_CA<0>")
	)
	(arc
		(start 98.618548 -248.457212)
		(mid 98.454452 -248.432865)
		(end 98.295968 -248.48185)
		(width 0.088646)
		(layer "In11.Cu")
		(net "M_D_CPU1_SB_CA<0>")
	)
	(arc
		(start 98.287078 -248.48693)
		(mid 98.156164 -248.62329)
		(end 98.108516 -248.806208)
		(width 0.088646)
		(layer "In11.Cu")
		(net "M_D_CPU1_SB_CA<0>")
	)
	(segment
		(start 95.303848 -256.361184)
		(end 95.303594 -256.361438)
		(width 0.20066)
		(layer "F.Cu")
		(net "M_D_CPU1_SA_RSP<1>")
	)
	(segment
		(start 95.303848 -255.825498)
		(end 95.303848 -256.361184)
		(width 0.20066)
		(layer "F.Cu")
		(net "M_D_CPU1_SA_RSP<1>")
	)
	(segment
		(start 15.684246 -244.066568)
		(end 16.789146 -244.066568)
		(width 0.20066)
		(layer "F.Cu")
		(net "M_D_CPU1_SA_RSP<1>")
	)
	(segment
		(start 83.6422 -255.841246)
		(end 83.088734 -255.841246)
		(width 0.088646)
		(layer "In6.Cu")
		(net "M_D_CPU1_SA_RSP<1>")
	)
	(segment
		(start 16.422878 -256.028444)
		(end 15.455646 -255.061212)
		(width 0.18288)
		(layer "In6.Cu")
		(net "M_D_CPU1_SA_RSP<1>")
	)
	(segment
		(start 20.539456 -256.79146)
		(end 19.77644 -256.028444)
		(width 0.18288)
		(layer "In6.Cu")
		(net "M_D_CPU1_SA_RSP<1>")
	)
	(segment
		(start 89.477596 -256.03708)
		(end 89.462864 -256.045716)
		(width 0.088646)
		(layer "In6.Cu")
		(net "M_D_CPU1_SA_RSP<1>")
	)
	(segment
		(start 71.129398 -256.79146)
		(end 71.129144 -256.791206)
		(width 0.18288)
		(layer "In6.Cu")
		(net "M_D_CPU1_SA_RSP<1>")
	)
	(segment
		(start 81.132934 -255.841246)
		(end 78.838806 -256.79146)
		(width 0.18288)
		(layer "In6.Cu")
		(net "M_D_CPU1_SA_RSP<1>")
	)
	(segment
		(start 91.357196 -256.03708)
		(end 91.342464 -256.045716)
		(width 0.088646)
		(layer "In6.Cu")
		(net "M_D_CPU1_SA_RSP<1>")
	)
	(segment
		(start 15.272766 -254.239776)
		(end 14.264132 -254.239776)
		(width 0.18288)
		(layer "In6.Cu")
		(net "M_D_CPU1_SA_RSP<1>")
	)
	(segment
		(start 15.272766 -252.167136)
		(end 15.455646 -251.984256)
		(width 0.18288)
		(layer "In6.Cu")
		(net "M_D_CPU1_SA_RSP<1>")
	)
	(segment
		(start 66.475102 -256.79146)
		(end 20.539456 -256.79146)
		(width 0.18288)
		(layer "In6.Cu")
		(net "M_D_CPU1_SA_RSP<1>")
	)
	(segment
		(start 15.455646 -254.422656)
		(end 15.272766 -254.239776)
		(width 0.18288)
		(layer "In6.Cu")
		(net "M_D_CPU1_SA_RSP<1>")
	)
	(segment
		(start 15.272766 -252.858016)
		(end 14.264132 -252.858016)
		(width 0.18288)
		(layer "In6.Cu")
		(net "M_D_CPU1_SA_RSP<1>")
	)
	(segment
		(start 15.455646 -253.040896)
		(end 15.272766 -252.858016)
		(width 0.18288)
		(layer "In6.Cu")
		(net "M_D_CPU1_SA_RSP<1>")
	)
	(segment
		(start 15.455646 -255.061212)
		(end 15.455646 -254.422656)
		(width 0.18288)
		(layer "In6.Cu")
		(net "M_D_CPU1_SA_RSP<1>")
	)
	(segment
		(start 15.455646 -253.366016)
		(end 15.455646 -253.040896)
		(width 0.18288)
		(layer "In6.Cu")
		(net "M_D_CPU1_SA_RSP<1>")
	)
	(segment
		(start 14.264132 -254.239776)
		(end 14.081252 -254.056896)
		(width 0.18288)
		(layer "In6.Cu")
		(net "M_D_CPU1_SA_RSP<1>")
	)
	(segment
		(start 16.034512 -244.066568)
		(end 16.789146 -244.066568)
		(width 0.18288)
		(layer "In6.Cu")
		(net "M_D_CPU1_SA_RSP<1>")
	)
	(segment
		(start 14.081252 -254.056896)
		(end 14.081252 -253.731776)
		(width 0.18288)
		(layer "In6.Cu")
		(net "M_D_CPU1_SA_RSP<1>")
	)
	(segment
		(start 15.272766 -253.548896)
		(end 15.455646 -253.366016)
		(width 0.18288)
		(layer "In6.Cu")
		(net "M_D_CPU1_SA_RSP<1>")
	)
	(segment
		(start 66.475356 -256.791206)
		(end 66.475102 -256.79146)
		(width 0.18288)
		(layer "In6.Cu")
		(net "M_D_CPU1_SA_RSP<1>")
	)
	(segment
		(start 14.081252 -253.731776)
		(end 14.264132 -253.548896)
		(width 0.18288)
		(layer "In6.Cu")
		(net "M_D_CPU1_SA_RSP<1>")
	)
	(segment
		(start 15.455646 -244.645434)
		(end 16.034512 -244.066568)
		(width 0.18288)
		(layer "In6.Cu")
		(net "M_D_CPU1_SA_RSP<1>")
	)
	(segment
		(start 83.088734 -255.841246)
		(end 81.132934 -255.841246)
		(width 0.18288)
		(layer "In6.Cu")
		(net "M_D_CPU1_SA_RSP<1>")
	)
	(segment
		(start 83.787488 -255.986534)
		(end 83.6422 -255.841246)
		(width 0.088646)
		(layer "In6.Cu")
		(net "M_D_CPU1_SA_RSP<1>")
	)
	(segment
		(start 94.17685 -256.03708)
		(end 94.166436 -256.043176)
		(width 0.088646)
		(layer "In6.Cu")
		(net "M_D_CPU1_SA_RSP<1>")
	)
	(segment
		(start 14.081252 -252.675136)
		(end 14.081252 -252.350016)
		(width 0.18288)
		(layer "In6.Cu")
		(net "M_D_CPU1_SA_RSP<1>")
	)
	(segment
		(start 71.129144 -256.791206)
		(end 66.475356 -256.791206)
		(width 0.18288)
		(layer "In6.Cu")
		(net "M_D_CPU1_SA_RSP<1>")
	)
	(segment
		(start 14.264132 -252.858016)
		(end 14.081252 -252.675136)
		(width 0.18288)
		(layer "In6.Cu")
		(net "M_D_CPU1_SA_RSP<1>")
	)
	(segment
		(start 14.264132 -252.167136)
		(end 15.272766 -252.167136)
		(width 0.18288)
		(layer "In6.Cu")
		(net "M_D_CPU1_SA_RSP<1>")
	)
	(segment
		(start 14.264132 -253.548896)
		(end 15.272766 -253.548896)
		(width 0.18288)
		(layer "In6.Cu")
		(net "M_D_CPU1_SA_RSP<1>")
	)
	(segment
		(start 19.77644 -256.028444)
		(end 16.422878 -256.028444)
		(width 0.18288)
		(layer "In6.Cu")
		(net "M_D_CPU1_SA_RSP<1>")
	)
	(segment
		(start 95.303594 -256.361438)
		(end 94.920816 -256.21996)
		(width 0.088646)
		(layer "In6.Cu")
		(net "M_D_CPU1_SA_RSP<1>")
	)
	(segment
		(start 78.838806 -256.79146)
		(end 71.129398 -256.79146)
		(width 0.18288)
		(layer "In6.Cu")
		(net "M_D_CPU1_SA_RSP<1>")
	)
	(segment
		(start 93.236796 -256.03708)
		(end 93.222064 -256.045716)
		(width 0.088646)
		(layer "In6.Cu")
		(net "M_D_CPU1_SA_RSP<1>")
	)
	(segment
		(start 14.081252 -252.350016)
		(end 14.264132 -252.167136)
		(width 0.18288)
		(layer "In6.Cu")
		(net "M_D_CPU1_SA_RSP<1>")
	)
	(segment
		(start 15.455646 -251.984256)
		(end 15.455646 -244.645434)
		(width 0.18288)
		(layer "In6.Cu")
		(net "M_D_CPU1_SA_RSP<1>")
	)
	(segment
		(start 94.639384 -256.08788)
		(end 94.551246 -256.03708)
		(width 0.088646)
		(layer "In6.Cu")
		(net "M_D_CPU1_SA_RSP<1>")
	)
	(segment
		(start 84.025994 -255.986534)
		(end 83.787488 -255.986534)
		(width 0.088646)
		(layer "In6.Cu")
		(net "M_D_CPU1_SA_RSP<1>")
	)
	(arc
		(start 93.222064 -256.045716)
		(mid 92.945589 -256.113036)
		(end 92.671392 -256.03708)
		(width 0.088646)
		(layer "In6.Cu")
		(net "M_D_CPU1_SA_RSP<1>")
	)
	(arc
		(start 88.537796 -256.03708)
		(mid 88.255094 -256.112856)
		(end 87.972392 -256.03708)
		(width 0.088646)
		(layer "In6.Cu")
		(net "M_D_CPU1_SA_RSP<1>")
	)
	(arc
		(start 91.342464 -256.045716)
		(mid 91.065989 -256.113036)
		(end 90.791792 -256.03708)
		(width 0.088646)
		(layer "In6.Cu")
		(net "M_D_CPU1_SA_RSP<1>")
	)
	(arc
		(start 90.791792 -256.03708)
		(mid 90.604594 -255.986937)
		(end 90.417396 -256.03708)
		(width 0.088646)
		(layer "In6.Cu")
		(net "M_D_CPU1_SA_RSP<1>")
	)
	(arc
		(start 87.032592 -256.03708)
		(mid 86.845394 -255.986937)
		(end 86.658196 -256.03708)
		(width 0.088646)
		(layer "In6.Cu")
		(net "M_D_CPU1_SA_RSP<1>")
	)
	(arc
		(start 92.671392 -256.03708)
		(mid 92.484194 -255.986937)
		(end 92.296996 -256.03708)
		(width 0.088646)
		(layer "In6.Cu")
		(net "M_D_CPU1_SA_RSP<1>")
	)
	(arc
		(start 84.778596 -256.03708)
		(mid 84.495894 -256.112856)
		(end 84.213192 -256.03708)
		(width 0.088646)
		(layer "In6.Cu")
		(net "M_D_CPU1_SA_RSP<1>")
	)
	(arc
		(start 94.551246 -256.03708)
		(mid 94.364048 -255.986937)
		(end 94.17685 -256.03708)
		(width 0.088646)
		(layer "In6.Cu")
		(net "M_D_CPU1_SA_RSP<1>")
	)
	(arc
		(start 90.417396 -256.03708)
		(mid 90.134694 -256.112856)
		(end 89.851992 -256.03708)
		(width 0.088646)
		(layer "In6.Cu")
		(net "M_D_CPU1_SA_RSP<1>")
	)
	(arc
		(start 88.912192 -256.03708)
		(mid 88.724994 -255.986937)
		(end 88.537796 -256.03708)
		(width 0.088646)
		(layer "In6.Cu")
		(net "M_D_CPU1_SA_RSP<1>")
	)
	(arc
		(start 86.092792 -256.03708)
		(mid 85.905594 -255.986937)
		(end 85.718396 -256.03708)
		(width 0.088646)
		(layer "In6.Cu")
		(net "M_D_CPU1_SA_RSP<1>")
	)
	(arc
		(start 87.597996 -256.03708)
		(mid 87.315294 -256.112856)
		(end 87.032592 -256.03708)
		(width 0.088646)
		(layer "In6.Cu")
		(net "M_D_CPU1_SA_RSP<1>")
	)
	(arc
		(start 93.611192 -256.03708)
		(mid 93.423994 -255.986937)
		(end 93.236796 -256.03708)
		(width 0.088646)
		(layer "In6.Cu")
		(net "M_D_CPU1_SA_RSP<1>")
	)
	(arc
		(start 94.920816 -256.21996)
		(mid 94.777316 -256.159852)
		(end 94.639384 -256.08788)
		(width 0.088646)
		(layer "In6.Cu")
		(net "M_D_CPU1_SA_RSP<1>")
	)
	(arc
		(start 89.851992 -256.03708)
		(mid 89.664794 -255.986937)
		(end 89.477596 -256.03708)
		(width 0.088646)
		(layer "In6.Cu")
		(net "M_D_CPU1_SA_RSP<1>")
	)
	(arc
		(start 91.731592 -256.03708)
		(mid 91.544394 -255.986937)
		(end 91.357196 -256.03708)
		(width 0.088646)
		(layer "In6.Cu")
		(net "M_D_CPU1_SA_RSP<1>")
	)
	(arc
		(start 89.462864 -256.045716)
		(mid 89.186389 -256.113036)
		(end 88.912192 -256.03708)
		(width 0.088646)
		(layer "In6.Cu")
		(net "M_D_CPU1_SA_RSP<1>")
	)
	(arc
		(start 87.972392 -256.03708)
		(mid 87.785194 -255.986937)
		(end 87.597996 -256.03708)
		(width 0.088646)
		(layer "In6.Cu")
		(net "M_D_CPU1_SA_RSP<1>")
	)
	(arc
		(start 92.296996 -256.03708)
		(mid 92.014294 -256.112856)
		(end 91.731592 -256.03708)
		(width 0.088646)
		(layer "In6.Cu")
		(net "M_D_CPU1_SA_RSP<1>")
	)
	(arc
		(start 85.718396 -256.03708)
		(mid 85.435694 -256.112856)
		(end 85.152992 -256.03708)
		(width 0.088646)
		(layer "In6.Cu")
		(net "M_D_CPU1_SA_RSP<1>")
	)
	(arc
		(start 85.152992 -256.03708)
		(mid 84.965794 -255.986937)
		(end 84.778596 -256.03708)
		(width 0.088646)
		(layer "In6.Cu")
		(net "M_D_CPU1_SA_RSP<1>")
	)
	(arc
		(start 86.658196 -256.03708)
		(mid 86.375494 -256.112856)
		(end 86.092792 -256.03708)
		(width 0.088646)
		(layer "In6.Cu")
		(net "M_D_CPU1_SA_RSP<1>")
	)
	(arc
		(start 84.213192 -256.03708)
		(mid 84.12292 -255.999481)
		(end 84.025994 -255.986534)
		(width 0.088646)
		(layer "In6.Cu")
		(net "M_D_CPU1_SA_RSP<1>")
	)
	(arc
		(start 94.166436 -256.043176)
		(mid 93.888004 -256.113022)
		(end 93.611192 -256.03708)
		(width 0.088646)
		(layer "In6.Cu")
		(net "M_D_CPU1_SA_RSP<1>")
	)
	(segment
		(start 8.140446 -244.066568)
		(end 9.245346 -244.066568)
		(width 0.20066)
		(layer "F.Cu")
		(net "M_D_CPU1_SA_RSP<0>")
	)
	(segment
		(start 95.773494 -257.175)
		(end 95.773748 -257.175254)
		(width 0.20066)
		(layer "F.Cu")
		(net "M_D_CPU1_SA_RSP<0>")
	)
	(segment
		(start 95.773494 -256.639314)
		(end 95.773494 -257.175)
		(width 0.20066)
		(layer "F.Cu")
		(net "M_D_CPU1_SA_RSP<0>")
	)
	(segment
		(start 80.627728 -256.83718)
		(end 78.22311 -257.833114)
		(width 0.18288)
		(layer "In6.Cu")
		(net "M_D_CPU1_SA_RSP<0>")
	)
	(segment
		(start 96.086422 -257.175254)
		(end 96.143826 -257.11785)
		(width 0.088646)
		(layer "In6.Cu")
		(net "M_D_CPU1_SA_RSP<0>")
	)
	(segment
		(start 14.894814 -257.833114)
		(end 12.28598 -255.22428)
		(width 0.18288)
		(layer "In6.Cu")
		(net "M_D_CPU1_SA_RSP<0>")
	)
	(segment
		(start 95.773748 -257.175254)
		(end 96.086422 -257.175254)
		(width 0.088646)
		(layer "In6.Cu")
		(net "M_D_CPU1_SA_RSP<0>")
	)
	(segment
		(start 66.475356 -257.83286)
		(end 66.475102 -257.833114)
		(width 0.18288)
		(layer "In6.Cu")
		(net "M_D_CPU1_SA_RSP<0>")
	)
	(segment
		(start 7.94258 -249.58548)
		(end 7.94258 -245.369334)
		(width 0.18288)
		(layer "In6.Cu")
		(net "M_D_CPU1_SA_RSP<0>")
	)
	(segment
		(start 71.351648 -258.055364)
		(end 71.129144 -257.83286)
		(width 0.18288)
		(layer "In6.Cu")
		(net "M_D_CPU1_SA_RSP<0>")
	)
	(segment
		(start 71.129144 -257.83286)
		(end 66.475356 -257.83286)
		(width 0.18288)
		(layer "In6.Cu")
		(net "M_D_CPU1_SA_RSP<0>")
	)
	(segment
		(start 9.08558 -250.72848)
		(end 7.94258 -249.58548)
		(width 0.18288)
		(layer "In6.Cu")
		(net "M_D_CPU1_SA_RSP<0>")
	)
	(segment
		(start 77.220064 -258.055364)
		(end 71.351648 -258.055364)
		(width 0.18288)
		(layer "In6.Cu")
		(net "M_D_CPU1_SA_RSP<0>")
	)
	(segment
		(start 77.442314 -257.833114)
		(end 77.220064 -258.055364)
		(width 0.18288)
		(layer "In6.Cu")
		(net "M_D_CPU1_SA_RSP<0>")
	)
	(segment
		(start 12.28598 -252.91288)
		(end 10.10158 -250.72848)
		(width 0.18288)
		(layer "In6.Cu")
		(net "M_D_CPU1_SA_RSP<0>")
	)
	(segment
		(start 66.475102 -257.833114)
		(end 14.894814 -257.833114)
		(width 0.18288)
		(layer "In6.Cu")
		(net "M_D_CPU1_SA_RSP<0>")
	)
	(segment
		(start 84.025994 -256.926588)
		(end 83.569302 -256.926588)
		(width 0.088646)
		(layer "In6.Cu")
		(net "M_D_CPU1_SA_RSP<0>")
	)
	(segment
		(start 95.035878 -256.859532)
		(end 95.021146 -256.850896)
		(width 0.088646)
		(layer "In6.Cu")
		(net "M_D_CPU1_SA_RSP<0>")
	)
	(segment
		(start 10.10158 -250.72848)
		(end 9.08558 -250.72848)
		(width 0.18288)
		(layer "In6.Cu")
		(net "M_D_CPU1_SA_RSP<0>")
	)
	(segment
		(start 91.272106 -256.856992)
		(end 91.261692 -256.850896)
		(width 0.088646)
		(layer "In6.Cu")
		(net "M_D_CPU1_SA_RSP<0>")
	)
	(segment
		(start 83.04276 -256.83718)
		(end 80.627728 -256.83718)
		(width 0.18288)
		(layer "In6.Cu")
		(net "M_D_CPU1_SA_RSP<0>")
	)
	(segment
		(start 78.22311 -257.833114)
		(end 77.442314 -257.833114)
		(width 0.18288)
		(layer "In6.Cu")
		(net "M_D_CPU1_SA_RSP<0>")
	)
	(segment
		(start 83.479894 -256.83718)
		(end 83.04276 -256.83718)
		(width 0.088646)
		(layer "In6.Cu")
		(net "M_D_CPU1_SA_RSP<0>")
	)
	(segment
		(start 95.969836 -256.855976)
		(end 95.960946 -256.850896)
		(width 0.088646)
		(layer "In6.Cu")
		(net "M_D_CPU1_SA_RSP<0>")
	)
	(segment
		(start 92.21216 -256.856992)
		(end 92.201746 -256.850896)
		(width 0.088646)
		(layer "In6.Cu")
		(net "M_D_CPU1_SA_RSP<0>")
	)
	(segment
		(start 12.28598 -255.22428)
		(end 12.28598 -252.91288)
		(width 0.18288)
		(layer "In6.Cu")
		(net "M_D_CPU1_SA_RSP<0>")
	)
	(segment
		(start 7.94258 -245.369334)
		(end 9.245346 -244.066568)
		(width 0.18288)
		(layer "In6.Cu")
		(net "M_D_CPU1_SA_RSP<0>")
	)
	(segment
		(start 93.151706 -256.856992)
		(end 93.141292 -256.850896)
		(width 0.088646)
		(layer "In6.Cu")
		(net "M_D_CPU1_SA_RSP<0>")
	)
	(segment
		(start 83.569302 -256.926588)
		(end 83.479894 -256.83718)
		(width 0.088646)
		(layer "In6.Cu")
		(net "M_D_CPU1_SA_RSP<0>")
	)
	(arc
		(start 92.766896 -256.850896)
		(mid 92.490337 -256.926639)
		(end 92.21216 -256.856992)
		(width 0.088646)
		(layer "In6.Cu")
		(net "M_D_CPU1_SA_RSP<0>")
	)
	(arc
		(start 87.502492 -256.850896)
		(mid 87.315294 -256.800753)
		(end 87.128096 -256.850896)
		(width 0.088646)
		(layer "In6.Cu")
		(net "M_D_CPU1_SA_RSP<0>")
	)
	(arc
		(start 95.021146 -256.850896)
		(mid 94.833948 -256.800753)
		(end 94.64675 -256.850896)
		(width 0.088646)
		(layer "In6.Cu")
		(net "M_D_CPU1_SA_RSP<0>")
	)
	(arc
		(start 96.143826 -257.11785)
		(mid 96.08567 -256.967737)
		(end 95.969836 -256.855976)
		(width 0.088646)
		(layer "In6.Cu")
		(net "M_D_CPU1_SA_RSP<0>")
	)
	(arc
		(start 86.188296 -256.850896)
		(mid 85.905594 -256.926672)
		(end 85.622892 -256.850896)
		(width 0.088646)
		(layer "In6.Cu")
		(net "M_D_CPU1_SA_RSP<0>")
	)
	(arc
		(start 85.248496 -256.850896)
		(mid 84.965794 -256.926672)
		(end 84.683092 -256.850896)
		(width 0.088646)
		(layer "In6.Cu")
		(net "M_D_CPU1_SA_RSP<0>")
	)
	(arc
		(start 87.128096 -256.850896)
		(mid 86.845394 -256.926672)
		(end 86.562692 -256.850896)
		(width 0.088646)
		(layer "In6.Cu")
		(net "M_D_CPU1_SA_RSP<0>")
	)
	(arc
		(start 91.82735 -256.850896)
		(mid 91.550537 -256.926766)
		(end 91.272106 -256.856992)
		(width 0.088646)
		(layer "In6.Cu")
		(net "M_D_CPU1_SA_RSP<0>")
	)
	(arc
		(start 94.081346 -256.850896)
		(mid 93.894148 -256.800753)
		(end 93.70695 -256.850896)
		(width 0.088646)
		(layer "In6.Cu")
		(net "M_D_CPU1_SA_RSP<0>")
	)
	(arc
		(start 89.947496 -256.850896)
		(mid 89.664794 -256.926672)
		(end 89.382092 -256.850896)
		(width 0.088646)
		(layer "In6.Cu")
		(net "M_D_CPU1_SA_RSP<0>")
	)
	(arc
		(start 90.887296 -256.850896)
		(mid 90.604594 -256.926672)
		(end 90.321892 -256.850896)
		(width 0.088646)
		(layer "In6.Cu")
		(net "M_D_CPU1_SA_RSP<0>")
	)
	(arc
		(start 89.382092 -256.850896)
		(mid 89.194894 -256.800753)
		(end 89.007696 -256.850896)
		(width 0.088646)
		(layer "In6.Cu")
		(net "M_D_CPU1_SA_RSP<0>")
	)
	(arc
		(start 88.442292 -256.850896)
		(mid 88.255094 -256.800753)
		(end 88.067896 -256.850896)
		(width 0.088646)
		(layer "In6.Cu")
		(net "M_D_CPU1_SA_RSP<0>")
	)
	(arc
		(start 93.70695 -256.850896)
		(mid 93.430137 -256.926766)
		(end 93.151706 -256.856992)
		(width 0.088646)
		(layer "In6.Cu")
		(net "M_D_CPU1_SA_RSP<0>")
	)
	(arc
		(start 92.201746 -256.850896)
		(mid 92.014548 -256.800753)
		(end 91.82735 -256.850896)
		(width 0.088646)
		(layer "In6.Cu")
		(net "M_D_CPU1_SA_RSP<0>")
	)
	(arc
		(start 84.683092 -256.850896)
		(mid 84.495894 -256.800753)
		(end 84.308696 -256.850896)
		(width 0.088646)
		(layer "In6.Cu")
		(net "M_D_CPU1_SA_RSP<0>")
	)
	(arc
		(start 88.067896 -256.850896)
		(mid 87.785194 -256.926672)
		(end 87.502492 -256.850896)
		(width 0.088646)
		(layer "In6.Cu")
		(net "M_D_CPU1_SA_RSP<0>")
	)
	(arc
		(start 91.261692 -256.850896)
		(mid 91.074494 -256.800753)
		(end 90.887296 -256.850896)
		(width 0.088646)
		(layer "In6.Cu")
		(net "M_D_CPU1_SA_RSP<0>")
	)
	(arc
		(start 86.562692 -256.850896)
		(mid 86.375494 -256.800753)
		(end 86.188296 -256.850896)
		(width 0.088646)
		(layer "In6.Cu")
		(net "M_D_CPU1_SA_RSP<0>")
	)
	(arc
		(start 95.58655 -256.850896)
		(mid 95.312351 -256.926731)
		(end 95.035878 -256.859532)
		(width 0.088646)
		(layer "In6.Cu")
		(net "M_D_CPU1_SA_RSP<0>")
	)
	(arc
		(start 89.007696 -256.850896)
		(mid 88.724994 -256.926672)
		(end 88.442292 -256.850896)
		(width 0.088646)
		(layer "In6.Cu")
		(net "M_D_CPU1_SA_RSP<0>")
	)
	(arc
		(start 90.321892 -256.850896)
		(mid 90.134694 -256.800753)
		(end 89.947496 -256.850896)
		(width 0.088646)
		(layer "In6.Cu")
		(net "M_D_CPU1_SA_RSP<0>")
	)
	(arc
		(start 84.308696 -256.850896)
		(mid 84.172327 -256.907338)
		(end 84.025994 -256.926588)
		(width 0.088646)
		(layer "In6.Cu")
		(net "M_D_CPU1_SA_RSP<0>")
	)
	(arc
		(start 85.622892 -256.850896)
		(mid 85.435694 -256.800753)
		(end 85.248496 -256.850896)
		(width 0.088646)
		(layer "In6.Cu")
		(net "M_D_CPU1_SA_RSP<0>")
	)
	(arc
		(start 95.960946 -256.850896)
		(mid 95.773748 -256.800753)
		(end 95.58655 -256.850896)
		(width 0.088646)
		(layer "In6.Cu")
		(net "M_D_CPU1_SA_RSP<0>")
	)
	(arc
		(start 93.141292 -256.850896)
		(mid 92.954094 -256.800753)
		(end 92.766896 -256.850896)
		(width 0.088646)
		(layer "In6.Cu")
		(net "M_D_CPU1_SA_RSP<0>")
	)
	(arc
		(start 94.64675 -256.850896)
		(mid 94.364048 -256.926672)
		(end 94.081346 -256.850896)
		(width 0.088646)
		(layer "In6.Cu")
		(net "M_D_CPU1_SA_RSP<0>")
	)
	(segment
		(start 100.362512 -249.342148)
		(end 100.362766 -249.341894)
		(width 0.20066)
		(layer "F.Cu")
		(net "M_D_CPU1_SA_PAR")
	)
	(segment
		(start 10.344912 -259.095494)
		(end 10.48512 -258.955286)
		(width 0.20066)
		(layer "F.Cu")
		(net "M_D_CPU1_SA_PAR")
	)
	(segment
		(start 11.138662 -258.941824)
		(end 13.110718 -258.941824)
		(width 0.1016)
		(layer "F.Cu")
		(net "M_D_CPU1_SA_PAR")
	)
	(segment
		(start 10.485374 -258.95554)
		(end 11.11631 -258.95554)
		(width 0.20066)
		(layer "F.Cu")
		(net "M_D_CPU1_SA_PAR")
	)
	(segment
		(start 13.110718 -258.941824)
		(end 13.441426 -258.941824)
		(width 0.101854)
		(layer "F.Cu")
		(net "M_D_CPU1_SA_PAR")
	)
	(segment
		(start 13.552932 -258.941824)
		(end 13.977874 -259.366766)
		(width 0.20066)
		(layer "F.Cu")
		(net "M_D_CPU1_SA_PAR")
	)
	(segment
		(start 16.789146 -259.366766)
		(end 15.684246 -259.366766)
		(width 0.20066)
		(layer "F.Cu")
		(net "M_D_CPU1_SA_PAR")
	)
	(segment
		(start 10.48512 -258.955286)
		(end 10.485374 -258.95554)
		(width 0.20066)
		(layer "F.Cu")
		(net "M_D_CPU1_SA_PAR")
	)
	(segment
		(start 10.344912 -259.402326)
		(end 10.344912 -259.095494)
		(width 0.20066)
		(layer "F.Cu")
		(net "M_D_CPU1_SA_PAR")
	)
	(segment
		(start 11.124946 -258.95554)
		(end 11.138662 -258.941824)
		(width 0.101854)
		(layer "F.Cu")
		(net "M_D_CPU1_SA_PAR")
	)
	(segment
		(start 9.713722 -259.60578)
		(end 10.141458 -259.60578)
		(width 0.20066)
		(layer "F.Cu")
		(net "M_D_CPU1_SA_PAR")
	)
	(segment
		(start 11.11631 -258.95554)
		(end 11.124946 -258.95554)
		(width 0.101854)
		(layer "F.Cu")
		(net "M_D_CPU1_SA_PAR")
	)
	(segment
		(start 13.441426 -258.941824)
		(end 13.552932 -258.941824)
		(width 0.20066)
		(layer "F.Cu")
		(net "M_D_CPU1_SA_PAR")
	)
	(segment
		(start 100.362766 -249.341894)
		(end 100.362766 -248.806208)
		(width 0.20066)
		(layer "F.Cu")
		(net "M_D_CPU1_SA_PAR")
	)
	(segment
		(start 9.474708 -259.366766)
		(end 9.713722 -259.60578)
		(width 0.20066)
		(layer "F.Cu")
		(net "M_D_CPU1_SA_PAR")
	)
	(segment
		(start 13.977874 -259.366766)
		(end 15.684246 -259.366766)
		(width 0.20066)
		(layer "F.Cu")
		(net "M_D_CPU1_SA_PAR")
	)
	(segment
		(start 10.141458 -259.60578)
		(end 10.344912 -259.402326)
		(width 0.20066)
		(layer "F.Cu")
		(net "M_D_CPU1_SA_PAR")
	)
	(segment
		(start 8.140446 -259.366766)
		(end 9.474708 -259.366766)
		(width 0.20066)
		(layer "F.Cu")
		(net "M_D_CPU1_SA_PAR")
	)
	(segment
		(start 26.93797 -257.052826)
		(end 26.6446 -257.052826)
		(width 0.18288)
		(layer "In11.Cu")
		(net "M_D_CPU1_SA_PAR")
	)
	(segment
		(start 59.446414 -256.265426)
		(end 57.545224 -257.052826)
		(width 0.18288)
		(layer "In11.Cu")
		(net "M_D_CPU1_SA_PAR")
	)
	(segment
		(start 95.149924 -252.721364)
		(end 94.948756 -252.922532)
		(width 0.088646)
		(layer "In11.Cu")
		(net "M_D_CPU1_SA_PAR")
	)
	(segment
		(start 80.027272 -255.58115)
		(end 75.544172 -255.58115)
		(width 0.18288)
		(layer "In11.Cu")
		(net "M_D_CPU1_SA_PAR")
	)
	(segment
		(start 86.930484 -252.922532)
		(end 86.311232 -253.541784)
		(width 0.18288)
		(layer "In11.Cu")
		(net "M_D_CPU1_SA_PAR")
	)
	(segment
		(start 84.448904 -253.91364)
		(end 81.694782 -253.91364)
		(width 0.18288)
		(layer "In11.Cu")
		(net "M_D_CPU1_SA_PAR")
	)
	(segment
		(start 21.700236 -260.030976)
		(end 21.700236 -260.138672)
		(width 0.18288)
		(layer "In11.Cu")
		(net "M_D_CPU1_SA_PAR")
	)
	(segment
		(start 101.207062 -249.620024)
		(end 101.207062 -250.681744)
		(width 0.088646)
		(layer "In11.Cu")
		(net "M_D_CPU1_SA_PAR")
	)
	(segment
		(start 50.008536 -256.565908)
		(end 49.639474 -256.93497)
		(width 0.18288)
		(layer "In11.Cu")
		(net "M_D_CPU1_SA_PAR")
	)
	(segment
		(start 42.00525 -257.052826)
		(end 38.692836 -257.052826)
		(width 0.18288)
		(layer "In11.Cu")
		(net "M_D_CPU1_SA_PAR")
	)
	(segment
		(start 100.206302 -248.53519)
		(end 100.227384 -248.457212)
		(width 0.088646)
		(layer "In11.Cu")
		(net "M_D_CPU1_SA_PAR")
	)
	(segment
		(start 30.631892 -256.556002)
		(end 27.434794 -256.556002)
		(width 0.18288)
		(layer "In11.Cu")
		(net "M_D_CPU1_SA_PAR")
	)
	(segment
		(start 31.128716 -257.052826)
		(end 30.631892 -256.556002)
		(width 0.18288)
		(layer "In11.Cu")
		(net "M_D_CPU1_SA_PAR")
	)
	(segment
		(start 63.8683 -256.265426)
		(end 59.446414 -256.265426)
		(width 0.18288)
		(layer "In11.Cu")
		(net "M_D_CPU1_SA_PAR")
	)
	(segment
		(start 22.119082 -259.61213)
		(end 21.700236 -260.030976)
		(width 0.18288)
		(layer "In11.Cu")
		(net "M_D_CPU1_SA_PAR")
	)
	(segment
		(start 35.032696 -256.565908)
		(end 34.545778 -257.052826)
		(width 0.18288)
		(layer "In11.Cu")
		(net "M_D_CPU1_SA_PAR")
	)
	(segment
		(start 38.692836 -257.052826)
		(end 38.205918 -256.565908)
		(width 0.18288)
		(layer "In11.Cu")
		(net "M_D_CPU1_SA_PAR")
	)
	(segment
		(start 22.356318 -259.61213)
		(end 22.119082 -259.61213)
		(width 0.18288)
		(layer "In11.Cu")
		(net "M_D_CPU1_SA_PAR")
	)
	(segment
		(start 27.434794 -256.556002)
		(end 26.93797 -257.052826)
		(width 0.18288)
		(layer "In11.Cu")
		(net "M_D_CPU1_SA_PAR")
	)
	(segment
		(start 17.17167 -259.525262)
		(end 16.789146 -259.366766)
		(width 0.18288)
		(layer "In11.Cu")
		(net "M_D_CPU1_SA_PAR")
	)
	(segment
		(start 53.626004 -257.052826)
		(end 53.139086 -256.565908)
		(width 0.18288)
		(layer "In11.Cu")
		(net "M_D_CPU1_SA_PAR")
	)
	(segment
		(start 19.867626 -260.641846)
		(end 17.17167 -259.525262)
		(width 0.18288)
		(layer "In11.Cu")
		(net "M_D_CPU1_SA_PAR")
	)
	(segment
		(start 46.069504 -256.93497)
		(end 45.687996 -256.553462)
		(width 0.18288)
		(layer "In11.Cu")
		(net "M_D_CPU1_SA_PAR")
	)
	(segment
		(start 38.205918 -256.565908)
		(end 35.032696 -256.565908)
		(width 0.18288)
		(layer "In11.Cu")
		(net "M_D_CPU1_SA_PAR")
	)
	(segment
		(start 66.996056 -254.969772)
		(end 63.8683 -256.265426)
		(width 0.18288)
		(layer "In11.Cu")
		(net "M_D_CPU1_SA_PAR")
	)
	(segment
		(start 23.692866 -258.275582)
		(end 22.356318 -259.61213)
		(width 0.18288)
		(layer "In11.Cu")
		(net "M_D_CPU1_SA_PAR")
	)
	(segment
		(start 53.139086 -256.565908)
		(end 50.008536 -256.565908)
		(width 0.18288)
		(layer "In11.Cu")
		(net "M_D_CPU1_SA_PAR")
	)
	(segment
		(start 81.694782 -253.91364)
		(end 80.027272 -255.58115)
		(width 0.18288)
		(layer "In11.Cu")
		(net "M_D_CPU1_SA_PAR")
	)
	(segment
		(start 100.737162 -248.797572)
		(end 100.737162 -248.816114)
		(width 0.088646)
		(layer "In11.Cu")
		(net "M_D_CPU1_SA_PAR")
	)
	(segment
		(start 101.207062 -250.681744)
		(end 99.167442 -252.721364)
		(width 0.088646)
		(layer "In11.Cu")
		(net "M_D_CPU1_SA_PAR")
	)
	(segment
		(start 84.82076 -253.541784)
		(end 84.448904 -253.91364)
		(width 0.18288)
		(layer "In11.Cu")
		(net "M_D_CPU1_SA_PAR")
	)
	(segment
		(start 42.504614 -256.553462)
		(end 42.00525 -257.052826)
		(width 0.18288)
		(layer "In11.Cu")
		(net "M_D_CPU1_SA_PAR")
	)
	(segment
		(start 86.311232 -253.541784)
		(end 84.82076 -253.541784)
		(width 0.18288)
		(layer "In11.Cu")
		(net "M_D_CPU1_SA_PAR")
	)
	(segment
		(start 101.01961 -249.295666)
		(end 101.0285 -249.300746)
		(width 0.088646)
		(layer "In11.Cu")
		(net "M_D_CPU1_SA_PAR")
	)
	(segment
		(start 57.545224 -257.052826)
		(end 53.626004 -257.052826)
		(width 0.18288)
		(layer "In11.Cu")
		(net "M_D_CPU1_SA_PAR")
	)
	(segment
		(start 45.687996 -256.553462)
		(end 42.504614 -256.553462)
		(width 0.18288)
		(layer "In11.Cu")
		(net "M_D_CPU1_SA_PAR")
	)
	(segment
		(start 26.6446 -257.052826)
		(end 23.692866 -258.275582)
		(width 0.18288)
		(layer "In11.Cu")
		(net "M_D_CPU1_SA_PAR")
	)
	(segment
		(start 94.32163 -252.922532)
		(end 86.930484 -252.922532)
		(width 0.18288)
		(layer "In11.Cu")
		(net "M_D_CPU1_SA_PAR")
	)
	(segment
		(start 21.700236 -260.138672)
		(end 21.197062 -260.641846)
		(width 0.18288)
		(layer "In11.Cu")
		(net "M_D_CPU1_SA_PAR")
	)
	(segment
		(start 100.362766 -248.806208)
		(end 100.206302 -248.53519)
		(width 0.088646)
		(layer "In11.Cu")
		(net "M_D_CPU1_SA_PAR")
	)
	(segment
		(start 75.544172 -255.58115)
		(end 74.932794 -254.969772)
		(width 0.18288)
		(layer "In11.Cu")
		(net "M_D_CPU1_SA_PAR")
	)
	(segment
		(start 49.639474 -256.93497)
		(end 46.069504 -256.93497)
		(width 0.18288)
		(layer "In11.Cu")
		(net "M_D_CPU1_SA_PAR")
	)
	(segment
		(start 74.932794 -254.969772)
		(end 66.996056 -254.969772)
		(width 0.18288)
		(layer "In11.Cu")
		(net "M_D_CPU1_SA_PAR")
	)
	(segment
		(start 21.197062 -260.641846)
		(end 19.867626 -260.641846)
		(width 0.18288)
		(layer "In11.Cu")
		(net "M_D_CPU1_SA_PAR")
	)
	(segment
		(start 34.545778 -257.052826)
		(end 31.128716 -257.052826)
		(width 0.18288)
		(layer "In11.Cu")
		(net "M_D_CPU1_SA_PAR")
	)
	(segment
		(start 94.948756 -252.922532)
		(end 94.32163 -252.922532)
		(width 0.088646)
		(layer "In11.Cu")
		(net "M_D_CPU1_SA_PAR")
	)
	(segment
		(start 99.167442 -252.721364)
		(end 95.149924 -252.721364)
		(width 0.088646)
		(layer "In11.Cu")
		(net "M_D_CPU1_SA_PAR")
	)
	(arc
		(start 100.549964 -248.48185)
		(mid 100.684897 -248.615204)
		(end 100.737162 -248.797572)
		(width 0.088646)
		(layer "In11.Cu")
		(net "M_D_CPU1_SA_PAR")
	)
	(arc
		(start 100.737162 -248.816114)
		(mid 100.815273 -249.093063)
		(end 101.01961 -249.295666)
		(width 0.088646)
		(layer "In11.Cu")
		(net "M_D_CPU1_SA_PAR")
	)
	(arc
		(start 100.227384 -248.457212)
		(mid 100.39148 -248.432865)
		(end 100.549964 -248.48185)
		(width 0.088646)
		(layer "In11.Cu")
		(net "M_D_CPU1_SA_PAR")
	)
	(arc
		(start 101.0285 -249.300746)
		(mid 101.159414 -249.437106)
		(end 101.207062 -249.620024)
		(width 0.088646)
		(layer "In11.Cu")
		(net "M_D_CPU1_SA_PAR")
	)
	(segment
		(start 20.889214 -273.816572)
		(end 19.784314 -273.816572)
		(width 0.20066)
		(layer "F.Cu")
		(net "M_D_CPU1_SA_DQS_DP<9>")
	)
	(segment
		(start 14.56563 -273.39163)
		(end 14.560042 -273.386042)
		(width 0.101854)
		(layer "F.Cu")
		(net "M_D_CPU1_SA_DQS_DP<9>")
	)
	(segment
		(start 19.784314 -273.816572)
		(end 19.294602 -273.816572)
		(width 0.20066)
		(layer "F.Cu")
		(net "M_D_CPU1_SA_DQS_DP<9>")
	)
	(segment
		(start 14.09319 -273.655536)
		(end 13.733018 -273.655536)
		(width 0.20066)
		(layer "F.Cu")
		(net "M_D_CPU1_SA_DQS_DP<9>")
	)
	(segment
		(start 18.428716 -274.077938)
		(end 17.7927 -273.652996)
		(width 0.20066)
		(layer "F.Cu")
		(net "M_D_CPU1_SA_DQS_DP<9>")
	)
	(segment
		(start 13.310616 -274.077938)
		(end 12.976352 -274.077938)
		(width 0.20066)
		(layer "F.Cu")
		(net "M_D_CPU1_SA_DQS_DP<9>")
	)
	(segment
		(start 14.560042 -273.386042)
		(end 14.362684 -273.386042)
		(width 0.20066)
		(layer "F.Cu")
		(net "M_D_CPU1_SA_DQS_DP<9>")
	)
	(segment
		(start 17.026636 -273.391884)
		(end 16.885158 -273.391884)
		(width 0.20066)
		(layer "F.Cu")
		(net "M_D_CPU1_SA_DQS_DP<9>")
	)
	(segment
		(start 19.294602 -273.816572)
		(end 19.033236 -274.077938)
		(width 0.20066)
		(layer "F.Cu")
		(net "M_D_CPU1_SA_DQS_DP<9>")
	)
	(segment
		(start 16.885158 -273.391884)
		(end 16.884904 -273.39163)
		(width 0.1016)
		(layer "F.Cu")
		(net "M_D_CPU1_SA_DQS_DP<9>")
	)
	(segment
		(start 14.362684 -273.386042)
		(end 14.09319 -273.655536)
		(width 0.20066)
		(layer "F.Cu")
		(net "M_D_CPU1_SA_DQS_DP<9>")
	)
	(segment
		(start 12.976352 -274.077938)
		(end 12.714986 -273.816572)
		(width 0.20066)
		(layer "F.Cu")
		(net "M_D_CPU1_SA_DQS_DP<9>")
	)
	(segment
		(start 17.287748 -273.652996)
		(end 17.026636 -273.391884)
		(width 0.20066)
		(layer "F.Cu")
		(net "M_D_CPU1_SA_DQS_DP<9>")
	)
	(segment
		(start 16.884904 -273.39163)
		(end 14.80693 -273.39163)
		(width 0.1016)
		(layer "F.Cu")
		(net "M_D_CPU1_SA_DQS_DP<9>")
	)
	(segment
		(start 12.714986 -273.816572)
		(end 12.240514 -273.816572)
		(width 0.20066)
		(layer "F.Cu")
		(net "M_D_CPU1_SA_DQS_DP<9>")
	)
	(segment
		(start 13.733018 -273.655536)
		(end 13.310616 -274.077938)
		(width 0.20066)
		(layer "F.Cu")
		(net "M_D_CPU1_SA_DQS_DP<9>")
	)
	(segment
		(start 17.7927 -273.652996)
		(end 17.287748 -273.652996)
		(width 0.20066)
		(layer "F.Cu")
		(net "M_D_CPU1_SA_DQS_DP<9>")
	)
	(segment
		(start 100.942648 -262.87222)
		(end 100.942394 -262.872474)
		(width 0.20066)
		(layer "F.Cu")
		(net "M_D_CPU1_SA_DQS_DP<9>")
	)
	(segment
		(start 14.80693 -273.39163)
		(end 14.56563 -273.39163)
		(width 0.101854)
		(layer "F.Cu")
		(net "M_D_CPU1_SA_DQS_DP<9>")
	)
	(segment
		(start 19.033236 -274.077938)
		(end 18.428716 -274.077938)
		(width 0.20066)
		(layer "F.Cu")
		(net "M_D_CPU1_SA_DQS_DP<9>")
	)
	(segment
		(start 100.942648 -262.336534)
		(end 100.942648 -262.87222)
		(width 0.20066)
		(layer "F.Cu")
		(net "M_D_CPU1_SA_DQS_DP<9>")
	)
	(segment
		(start 75.060302 -262.74903)
		(end 67.456812 -270.35252)
		(width 0.18288)
		(layer "In11.Cu")
		(net "M_D_CPU1_SA_DQS_DP<9>")
	)
	(segment
		(start 91.832938 -262.386318)
		(end 91.821254 -262.379714)
		(width 0.088646)
		(layer "In11.Cu")
		(net "M_D_CPU1_SA_DQS_DP<9>")
	)
	(segment
		(start 83.320128 -262.808974)
		(end 83.073748 -262.808974)
		(width 0.088646)
		(layer "In11.Cu")
		(net "M_D_CPU1_SA_DQS_DP<9>")
	)
	(segment
		(start 22.566376 -274.423886)
		(end 21.953474 -274.423886)
		(width 0.18288)
		(layer "In11.Cu")
		(net "M_D_CPU1_SA_DQS_DP<9>")
	)
	(segment
		(start 35.46602 -271.171416)
		(end 34.714688 -271.171416)
		(width 0.18288)
		(layer "In11.Cu")
		(net "M_D_CPU1_SA_DQS_DP<9>")
	)
	(segment
		(start 55.23865 -271.371314)
		(end 52.910994 -271.371314)
		(width 0.18288)
		(layer "In11.Cu")
		(net "M_D_CPU1_SA_DQS_DP<9>")
	)
	(segment
		(start 83.073748 -262.808974)
		(end 83.013804 -262.74903)
		(width 0.088646)
		(layer "In11.Cu")
		(net "M_D_CPU1_SA_DQS_DP<9>")
	)
	(segment
		(start 32.349694 -271.974818)
		(end 32.065722 -271.690846)
		(width 0.18288)
		(layer "In11.Cu")
		(net "M_D_CPU1_SA_DQS_DP<9>")
	)
	(segment
		(start 89.951814 -262.385556)
		(end 89.947496 -262.383016)
		(width 0.088646)
		(layer "In11.Cu")
		(net "M_D_CPU1_SA_DQS_DP<9>")
	)
	(segment
		(start 94.652338 -262.386318)
		(end 94.640654 -262.379714)
		(width 0.088646)
		(layer "In11.Cu")
		(net "M_D_CPU1_SA_DQS_DP<9>")
	)
	(segment
		(start 47.427134 -271.963134)
		(end 47.154846 -271.690846)
		(width 0.18288)
		(layer "In11.Cu")
		(net "M_D_CPU1_SA_DQS_DP<9>")
	)
	(segment
		(start 97.471738 -262.386318)
		(end 97.460054 -262.379714)
		(width 0.088646)
		(layer "In11.Cu")
		(net "M_D_CPU1_SA_DQS_DP<9>")
	)
	(segment
		(start 98.411538 -262.386318)
		(end 98.399854 -262.379714)
		(width 0.088646)
		(layer "In11.Cu")
		(net "M_D_CPU1_SA_DQS_DP<9>")
	)
	(segment
		(start 49.26584 -271.608296)
		(end 48.40859 -271.963134)
		(width 0.18288)
		(layer "In11.Cu")
		(net "M_D_CPU1_SA_DQS_DP<9>")
	)
	(segment
		(start 46.773846 -271.690846)
		(end 46.51248 -271.952212)
		(width 0.18288)
		(layer "In11.Cu")
		(net "M_D_CPU1_SA_DQS_DP<9>")
	)
	(segment
		(start 35.796474 -270.840962)
		(end 35.46602 -271.171416)
		(width 0.18288)
		(layer "In11.Cu")
		(net "M_D_CPU1_SA_DQS_DP<9>")
	)
	(segment
		(start 50.608484 -271.106392)
		(end 49.767998 -271.106392)
		(width 0.18288)
		(layer "In11.Cu")
		(net "M_D_CPU1_SA_DQS_DP<9>")
	)
	(segment
		(start 36.448746 -271.124934)
		(end 36.164774 -270.840962)
		(width 0.18288)
		(layer "In11.Cu")
		(net "M_D_CPU1_SA_DQS_DP<9>")
	)
	(segment
		(start 44.491656 -272.620232)
		(end 43.883072 -272.011648)
		(width 0.18288)
		(layer "In11.Cu")
		(net "M_D_CPU1_SA_DQS_DP<9>")
	)
	(segment
		(start 37.678868 -271.36598)
		(end 37.437822 -271.124934)
		(width 0.18288)
		(layer "In11.Cu")
		(net "M_D_CPU1_SA_DQS_DP<9>")
	)
	(segment
		(start 92.772738 -262.386318)
		(end 92.761054 -262.379714)
		(width 0.088646)
		(layer "In11.Cu")
		(net "M_D_CPU1_SA_DQS_DP<9>")
	)
	(segment
		(start 84.299806 -262.410448)
		(end 84.205826 -262.384286)
		(width 0.088646)
		(layer "In11.Cu")
		(net "M_D_CPU1_SA_DQS_DP<9>")
	)
	(segment
		(start 52.646072 -271.106392)
		(end 51.517804 -271.106392)
		(width 0.18288)
		(layer "In11.Cu")
		(net "M_D_CPU1_SA_DQS_DP<9>")
	)
	(segment
		(start 96.531938 -262.386318)
		(end 96.520254 -262.379714)
		(width 0.088646)
		(layer "In11.Cu")
		(net "M_D_CPU1_SA_DQS_DP<9>")
	)
	(segment
		(start 100.62972 -262.872474)
		(end 100.564188 -262.806942)
		(width 0.088646)
		(layer "In11.Cu")
		(net "M_D_CPU1_SA_DQS_DP<9>")
	)
	(segment
		(start 83.579208 -262.54964)
		(end 83.320128 -262.808974)
		(width 0.088646)
		(layer "In11.Cu")
		(net "M_D_CPU1_SA_DQS_DP<9>")
	)
	(segment
		(start 100.942394 -262.872474)
		(end 100.62972 -262.872474)
		(width 0.088646)
		(layer "In11.Cu")
		(net "M_D_CPU1_SA_DQS_DP<9>")
	)
	(segment
		(start 25.841706 -272.22323)
		(end 24.9936 -273.071336)
		(width 0.18288)
		(layer "In11.Cu")
		(net "M_D_CPU1_SA_DQS_DP<9>")
	)
	(segment
		(start 21.140674 -274.068032)
		(end 20.889214 -273.816572)
		(width 0.18288)
		(layer "In11.Cu")
		(net "M_D_CPU1_SA_DQS_DP<9>")
	)
	(segment
		(start 36.164774 -270.840962)
		(end 35.796474 -270.840962)
		(width 0.18288)
		(layer "In11.Cu")
		(net "M_D_CPU1_SA_DQS_DP<9>")
	)
	(segment
		(start 23.918926 -273.071336)
		(end 22.566376 -274.423886)
		(width 0.18288)
		(layer "In11.Cu")
		(net "M_D_CPU1_SA_DQS_DP<9>")
	)
	(segment
		(start 21.953474 -274.423886)
		(end 21.59762 -274.068032)
		(width 0.18288)
		(layer "In11.Cu")
		(net "M_D_CPU1_SA_DQS_DP<9>")
	)
	(segment
		(start 95.592138 -262.386318)
		(end 95.580454 -262.379714)
		(width 0.088646)
		(layer "In11.Cu")
		(net "M_D_CPU1_SA_DQS_DP<9>")
	)
	(segment
		(start 93.712538 -262.386318)
		(end 93.700854 -262.379714)
		(width 0.088646)
		(layer "In11.Cu")
		(net "M_D_CPU1_SA_DQS_DP<9>")
	)
	(segment
		(start 47.154846 -271.690846)
		(end 46.773846 -271.690846)
		(width 0.18288)
		(layer "In11.Cu")
		(net "M_D_CPU1_SA_DQS_DP<9>")
	)
	(segment
		(start 31.43123 -271.945862)
		(end 30.903926 -271.945862)
		(width 0.18288)
		(layer "In11.Cu")
		(net "M_D_CPU1_SA_DQS_DP<9>")
	)
	(segment
		(start 40.016176 -271.36598)
		(end 37.678868 -271.36598)
		(width 0.18288)
		(layer "In11.Cu")
		(net "M_D_CPU1_SA_DQS_DP<9>")
	)
	(segment
		(start 58.984896 -270.523208)
		(end 56.086756 -270.523208)
		(width 0.18288)
		(layer "In11.Cu")
		(net "M_D_CPU1_SA_DQS_DP<9>")
	)
	(segment
		(start 62.657736 -270.969486)
		(end 59.431174 -270.969486)
		(width 0.18288)
		(layer "In11.Cu")
		(net "M_D_CPU1_SA_DQS_DP<9>")
	)
	(segment
		(start 50.871628 -270.843248)
		(end 50.608484 -271.106392)
		(width 0.18288)
		(layer "In11.Cu")
		(net "M_D_CPU1_SA_DQS_DP<9>")
	)
	(segment
		(start 46.51248 -271.952212)
		(end 45.92447 -271.952212)
		(width 0.18288)
		(layer "In11.Cu")
		(net "M_D_CPU1_SA_DQS_DP<9>")
	)
	(segment
		(start 45.25645 -272.620232)
		(end 44.491656 -272.620232)
		(width 0.18288)
		(layer "In11.Cu")
		(net "M_D_CPU1_SA_DQS_DP<9>")
	)
	(segment
		(start 43.883072 -272.011648)
		(end 40.661844 -272.011648)
		(width 0.18288)
		(layer "In11.Cu")
		(net "M_D_CPU1_SA_DQS_DP<9>")
	)
	(segment
		(start 56.086756 -270.523208)
		(end 55.23865 -271.371314)
		(width 0.18288)
		(layer "In11.Cu")
		(net "M_D_CPU1_SA_DQS_DP<9>")
	)
	(segment
		(start 49.767998 -271.106392)
		(end 49.26584 -271.608296)
		(width 0.18288)
		(layer "In11.Cu")
		(net "M_D_CPU1_SA_DQS_DP<9>")
	)
	(segment
		(start 21.59762 -274.068032)
		(end 21.140674 -274.068032)
		(width 0.18288)
		(layer "In11.Cu")
		(net "M_D_CPU1_SA_DQS_DP<9>")
	)
	(segment
		(start 83.013804 -262.74903)
		(end 75.060302 -262.74903)
		(width 0.18288)
		(layer "In11.Cu")
		(net "M_D_CPU1_SA_DQS_DP<9>")
	)
	(segment
		(start 51.25466 -270.843248)
		(end 50.871628 -270.843248)
		(width 0.18288)
		(layer "In11.Cu")
		(net "M_D_CPU1_SA_DQS_DP<9>")
	)
	(segment
		(start 59.431174 -270.969486)
		(end 58.984896 -270.523208)
		(width 0.18288)
		(layer "In11.Cu")
		(net "M_D_CPU1_SA_DQS_DP<9>")
	)
	(segment
		(start 52.910994 -271.371314)
		(end 52.646072 -271.106392)
		(width 0.18288)
		(layer "In11.Cu")
		(net "M_D_CPU1_SA_DQS_DP<9>")
	)
	(segment
		(start 30.247082 -272.602706)
		(end 29.279596 -272.602706)
		(width 0.18288)
		(layer "In11.Cu")
		(net "M_D_CPU1_SA_DQS_DP<9>")
	)
	(segment
		(start 33.911286 -271.974818)
		(end 32.349694 -271.974818)
		(width 0.18288)
		(layer "In11.Cu")
		(net "M_D_CPU1_SA_DQS_DP<9>")
	)
	(segment
		(start 32.065722 -271.690846)
		(end 31.686246 -271.690846)
		(width 0.18288)
		(layer "In11.Cu")
		(net "M_D_CPU1_SA_DQS_DP<9>")
	)
	(segment
		(start 28.90012 -272.22323)
		(end 25.841706 -272.22323)
		(width 0.18288)
		(layer "In11.Cu")
		(net "M_D_CPU1_SA_DQS_DP<9>")
	)
	(segment
		(start 88.452706 -262.37692)
		(end 88.442292 -262.383016)
		(width 0.088646)
		(layer "In11.Cu")
		(net "M_D_CPU1_SA_DQS_DP<9>")
	)
	(segment
		(start 45.92447 -271.952212)
		(end 45.25645 -272.620232)
		(width 0.18288)
		(layer "In11.Cu")
		(net "M_D_CPU1_SA_DQS_DP<9>")
	)
	(segment
		(start 31.686246 -271.690846)
		(end 31.43123 -271.945862)
		(width 0.18288)
		(layer "In11.Cu")
		(net "M_D_CPU1_SA_DQS_DP<9>")
	)
	(segment
		(start 63.274702 -270.35252)
		(end 62.657736 -270.969486)
		(width 0.18288)
		(layer "In11.Cu")
		(net "M_D_CPU1_SA_DQS_DP<9>")
	)
	(segment
		(start 29.279596 -272.602706)
		(end 28.90012 -272.22323)
		(width 0.18288)
		(layer "In11.Cu")
		(net "M_D_CPU1_SA_DQS_DP<9>")
	)
	(segment
		(start 67.456812 -270.35252)
		(end 63.274702 -270.35252)
		(width 0.18288)
		(layer "In11.Cu")
		(net "M_D_CPU1_SA_DQS_DP<9>")
	)
	(segment
		(start 24.9936 -273.071336)
		(end 23.918926 -273.071336)
		(width 0.18288)
		(layer "In11.Cu")
		(net "M_D_CPU1_SA_DQS_DP<9>")
	)
	(segment
		(start 34.714688 -271.171416)
		(end 33.911286 -271.974818)
		(width 0.18288)
		(layer "In11.Cu")
		(net "M_D_CPU1_SA_DQS_DP<9>")
	)
	(segment
		(start 37.437822 -271.124934)
		(end 36.448746 -271.124934)
		(width 0.18288)
		(layer "In11.Cu")
		(net "M_D_CPU1_SA_DQS_DP<9>")
	)
	(segment
		(start 48.40859 -271.963134)
		(end 47.427134 -271.963134)
		(width 0.18288)
		(layer "In11.Cu")
		(net "M_D_CPU1_SA_DQS_DP<9>")
	)
	(segment
		(start 51.517804 -271.106392)
		(end 51.25466 -270.843248)
		(width 0.18288)
		(layer "In11.Cu")
		(net "M_D_CPU1_SA_DQS_DP<9>")
	)
	(segment
		(start 40.661844 -272.011648)
		(end 40.016176 -271.36598)
		(width 0.18288)
		(layer "In11.Cu")
		(net "M_D_CPU1_SA_DQS_DP<9>")
	)
	(segment
		(start 99.351338 -262.386318)
		(end 99.339654 -262.379714)
		(width 0.088646)
		(layer "In11.Cu")
		(net "M_D_CPU1_SA_DQS_DP<9>")
	)
	(segment
		(start 90.893138 -262.386318)
		(end 90.881454 -262.379714)
		(width 0.088646)
		(layer "In11.Cu")
		(net "M_D_CPU1_SA_DQS_DP<9>")
	)
	(segment
		(start 30.903926 -271.945862)
		(end 30.247082 -272.602706)
		(width 0.18288)
		(layer "In11.Cu")
		(net "M_D_CPU1_SA_DQS_DP<9>")
	)
	(arc
		(start 90.881454 -262.379714)
		(mid 90.601349 -262.307272)
		(end 90.322146 -262.383016)
		(width 0.088646)
		(layer "In11.Cu")
		(net "M_D_CPU1_SA_DQS_DP<9>")
	)
	(arc
		(start 87.502492 -262.383016)
		(mid 87.315294 -262.433159)
		(end 87.128096 -262.383016)
		(width 0.088646)
		(layer "In11.Cu")
		(net "M_D_CPU1_SA_DQS_DP<9>")
	)
	(arc
		(start 85.248496 -262.383016)
		(mid 84.980146 -262.307267)
		(end 84.708238 -262.369046)
		(width 0.088646)
		(layer "In11.Cu")
		(net "M_D_CPU1_SA_DQS_DP<9>")
	)
	(arc
		(start 95.960946 -262.383016)
		(mid 95.776992 -262.433145)
		(end 95.592138 -262.386318)
		(width 0.088646)
		(layer "In11.Cu")
		(net "M_D_CPU1_SA_DQS_DP<9>")
	)
	(arc
		(start 92.761054 -262.379714)
		(mid 92.480949 -262.307272)
		(end 92.201746 -262.383016)
		(width 0.088646)
		(layer "In11.Cu")
		(net "M_D_CPU1_SA_DQS_DP<9>")
	)
	(arc
		(start 97.840546 -262.383016)
		(mid 97.656592 -262.433145)
		(end 97.471738 -262.386318)
		(width 0.088646)
		(layer "In11.Cu")
		(net "M_D_CPU1_SA_DQS_DP<9>")
	)
	(arc
		(start 98.399854 -262.379714)
		(mid 98.119749 -262.307272)
		(end 97.840546 -262.383016)
		(width 0.088646)
		(layer "In11.Cu")
		(net "M_D_CPU1_SA_DQS_DP<9>")
	)
	(arc
		(start 86.188296 -262.383016)
		(mid 85.905594 -262.30724)
		(end 85.622892 -262.383016)
		(width 0.088646)
		(layer "In11.Cu")
		(net "M_D_CPU1_SA_DQS_DP<9>")
	)
	(arc
		(start 84.708238 -262.369046)
		(mid 84.507915 -262.428137)
		(end 84.299806 -262.410448)
		(width 0.088646)
		(layer "In11.Cu")
		(net "M_D_CPU1_SA_DQS_DP<9>")
	)
	(arc
		(start 86.562692 -262.383016)
		(mid 86.375494 -262.433159)
		(end 86.188296 -262.383016)
		(width 0.088646)
		(layer "In11.Cu")
		(net "M_D_CPU1_SA_DQS_DP<9>")
	)
	(arc
		(start 94.081346 -262.383016)
		(mid 93.897392 -262.433145)
		(end 93.712538 -262.386318)
		(width 0.088646)
		(layer "In11.Cu")
		(net "M_D_CPU1_SA_DQS_DP<9>")
	)
	(arc
		(start 89.00795 -262.383016)
		(mid 88.731137 -262.307146)
		(end 88.452706 -262.37692)
		(width 0.088646)
		(layer "In11.Cu")
		(net "M_D_CPU1_SA_DQS_DP<9>")
	)
	(arc
		(start 90.322146 -262.383016)
		(mid 90.137309 -262.433277)
		(end 89.951814 -262.385556)
		(width 0.088646)
		(layer "In11.Cu")
		(net "M_D_CPU1_SA_DQS_DP<9>")
	)
	(arc
		(start 92.201746 -262.383016)
		(mid 92.017792 -262.433145)
		(end 91.832938 -262.386318)
		(width 0.088646)
		(layer "In11.Cu")
		(net "M_D_CPU1_SA_DQS_DP<9>")
	)
	(arc
		(start 89.382346 -262.383016)
		(mid 89.195148 -262.433159)
		(end 89.00795 -262.383016)
		(width 0.088646)
		(layer "In11.Cu")
		(net "M_D_CPU1_SA_DQS_DP<9>")
	)
	(arc
		(start 98.780346 -262.383016)
		(mid 98.596392 -262.433145)
		(end 98.411538 -262.386318)
		(width 0.088646)
		(layer "In11.Cu")
		(net "M_D_CPU1_SA_DQS_DP<9>")
	)
	(arc
		(start 96.900746 -262.383016)
		(mid 96.716792 -262.433145)
		(end 96.531938 -262.386318)
		(width 0.088646)
		(layer "In11.Cu")
		(net "M_D_CPU1_SA_DQS_DP<9>")
	)
	(arc
		(start 89.947496 -262.383016)
		(mid 89.664938 -262.307367)
		(end 89.382346 -262.383016)
		(width 0.088646)
		(layer "In11.Cu")
		(net "M_D_CPU1_SA_DQS_DP<9>")
	)
	(arc
		(start 87.128096 -262.383016)
		(mid 86.845394 -262.30724)
		(end 86.562692 -262.383016)
		(width 0.088646)
		(layer "In11.Cu")
		(net "M_D_CPU1_SA_DQS_DP<9>")
	)
	(arc
		(start 91.261946 -262.383016)
		(mid 91.077992 -262.433145)
		(end 90.893138 -262.386318)
		(width 0.088646)
		(layer "In11.Cu")
		(net "M_D_CPU1_SA_DQS_DP<9>")
	)
	(arc
		(start 95.580454 -262.379714)
		(mid 95.300349 -262.307272)
		(end 95.021146 -262.383016)
		(width 0.088646)
		(layer "In11.Cu")
		(net "M_D_CPU1_SA_DQS_DP<9>")
	)
	(arc
		(start 95.021146 -262.383016)
		(mid 94.837192 -262.433145)
		(end 94.652338 -262.386318)
		(width 0.088646)
		(layer "In11.Cu")
		(net "M_D_CPU1_SA_DQS_DP<9>")
	)
	(arc
		(start 88.442292 -262.383016)
		(mid 88.255094 -262.433159)
		(end 88.067896 -262.383016)
		(width 0.088646)
		(layer "In11.Cu")
		(net "M_D_CPU1_SA_DQS_DP<9>")
	)
	(arc
		(start 94.640654 -262.379714)
		(mid 94.360549 -262.307272)
		(end 94.081346 -262.383016)
		(width 0.088646)
		(layer "In11.Cu")
		(net "M_D_CPU1_SA_DQS_DP<9>")
	)
	(arc
		(start 93.700854 -262.379714)
		(mid 93.420749 -262.307272)
		(end 93.141546 -262.383016)
		(width 0.088646)
		(layer "In11.Cu")
		(net "M_D_CPU1_SA_DQS_DP<9>")
	)
	(arc
		(start 84.205826 -262.384286)
		(mid 83.870199 -262.38232)
		(end 83.579208 -262.54964)
		(width 0.088646)
		(layer "In11.Cu")
		(net "M_D_CPU1_SA_DQS_DP<9>")
	)
	(arc
		(start 85.622892 -262.383016)
		(mid 85.435694 -262.433159)
		(end 85.248496 -262.383016)
		(width 0.088646)
		(layer "In11.Cu")
		(net "M_D_CPU1_SA_DQS_DP<9>")
	)
	(arc
		(start 91.821254 -262.379714)
		(mid 91.541149 -262.307272)
		(end 91.261946 -262.383016)
		(width 0.088646)
		(layer "In11.Cu")
		(net "M_D_CPU1_SA_DQS_DP<9>")
	)
	(arc
		(start 100.564188 -262.806942)
		(mid 100.562889 -262.796388)
		(end 100.561394 -262.78586)
		(width 0.088646)
		(layer "In11.Cu")
		(net "M_D_CPU1_SA_DQS_DP<9>")
	)
	(arc
		(start 93.141546 -262.383016)
		(mid 92.957592 -262.433145)
		(end 92.772738 -262.386318)
		(width 0.088646)
		(layer "In11.Cu")
		(net "M_D_CPU1_SA_DQS_DP<9>")
	)
	(arc
		(start 99.339654 -262.379714)
		(mid 99.059549 -262.307272)
		(end 98.780346 -262.383016)
		(width 0.088646)
		(layer "In11.Cu")
		(net "M_D_CPU1_SA_DQS_DP<9>")
	)
	(arc
		(start 97.460054 -262.379714)
		(mid 97.179949 -262.307272)
		(end 96.900746 -262.383016)
		(width 0.088646)
		(layer "In11.Cu")
		(net "M_D_CPU1_SA_DQS_DP<9>")
	)
	(arc
		(start 100.561394 -262.78586)
		(mid 100.246963 -262.362686)
		(end 99.720146 -262.383016)
		(width 0.088646)
		(layer "In11.Cu")
		(net "M_D_CPU1_SA_DQS_DP<9>")
	)
	(arc
		(start 96.520254 -262.379714)
		(mid 96.240149 -262.307272)
		(end 95.960946 -262.383016)
		(width 0.088646)
		(layer "In11.Cu")
		(net "M_D_CPU1_SA_DQS_DP<9>")
	)
	(arc
		(start 88.067896 -262.383016)
		(mid 87.785194 -262.30724)
		(end 87.502492 -262.383016)
		(width 0.088646)
		(layer "In11.Cu")
		(net "M_D_CPU1_SA_DQS_DP<9>")
	)
	(arc
		(start 99.720146 -262.383016)
		(mid 99.536192 -262.433145)
		(end 99.351338 -262.386318)
		(width 0.088646)
		(layer "In11.Cu")
		(net "M_D_CPU1_SA_DQS_DP<9>")
	)
	(segment
		(start 12.976352 -283.427932)
		(end 12.714986 -283.166566)
		(width 0.20066)
		(layer "F.Cu")
		(net "M_D_CPU1_SA_DQS_DP<8>")
	)
	(segment
		(start 14.56563 -282.741624)
		(end 14.560042 -282.736036)
		(width 0.101854)
		(layer "F.Cu")
		(net "M_D_CPU1_SA_DQS_DP<8>")
	)
	(segment
		(start 14.80693 -282.741624)
		(end 14.56563 -282.741624)
		(width 0.101854)
		(layer "F.Cu")
		(net "M_D_CPU1_SA_DQS_DP<8>")
	)
	(segment
		(start 13.733018 -283.00553)
		(end 13.310616 -283.427932)
		(width 0.20066)
		(layer "F.Cu")
		(net "M_D_CPU1_SA_DQS_DP<8>")
	)
	(segment
		(start 12.714986 -283.166566)
		(end 12.240514 -283.166566)
		(width 0.20066)
		(layer "F.Cu")
		(net "M_D_CPU1_SA_DQS_DP<8>")
	)
	(segment
		(start 17.7927 -283.00299)
		(end 17.287748 -283.00299)
		(width 0.20066)
		(layer "F.Cu")
		(net "M_D_CPU1_SA_DQS_DP<8>")
	)
	(segment
		(start 100.942648 -267.219938)
		(end 100.942394 -267.220192)
		(width 0.20066)
		(layer "F.Cu")
		(net "M_D_CPU1_SA_DQS_DP<8>")
	)
	(segment
		(start 14.362684 -282.736036)
		(end 14.09319 -283.00553)
		(width 0.20066)
		(layer "F.Cu")
		(net "M_D_CPU1_SA_DQS_DP<8>")
	)
	(segment
		(start 13.310616 -283.427932)
		(end 12.976352 -283.427932)
		(width 0.20066)
		(layer "F.Cu")
		(net "M_D_CPU1_SA_DQS_DP<8>")
	)
	(segment
		(start 19.784314 -283.166566)
		(end 19.294602 -283.166566)
		(width 0.20066)
		(layer "F.Cu")
		(net "M_D_CPU1_SA_DQS_DP<8>")
	)
	(segment
		(start 18.428716 -283.427932)
		(end 17.7927 -283.00299)
		(width 0.20066)
		(layer "F.Cu")
		(net "M_D_CPU1_SA_DQS_DP<8>")
	)
	(segment
		(start 16.885158 -282.741878)
		(end 16.884904 -282.741624)
		(width 0.1016)
		(layer "F.Cu")
		(net "M_D_CPU1_SA_DQS_DP<8>")
	)
	(segment
		(start 100.942394 -267.220192)
		(end 100.942394 -267.755878)
		(width 0.20066)
		(layer "F.Cu")
		(net "M_D_CPU1_SA_DQS_DP<8>")
	)
	(segment
		(start 14.560042 -282.736036)
		(end 14.362684 -282.736036)
		(width 0.20066)
		(layer "F.Cu")
		(net "M_D_CPU1_SA_DQS_DP<8>")
	)
	(segment
		(start 20.889214 -283.166566)
		(end 19.784314 -283.166566)
		(width 0.20066)
		(layer "F.Cu")
		(net "M_D_CPU1_SA_DQS_DP<8>")
	)
	(segment
		(start 16.884904 -282.741624)
		(end 14.80693 -282.741624)
		(width 0.1016)
		(layer "F.Cu")
		(net "M_D_CPU1_SA_DQS_DP<8>")
	)
	(segment
		(start 17.026636 -282.741878)
		(end 16.885158 -282.741878)
		(width 0.20066)
		(layer "F.Cu")
		(net "M_D_CPU1_SA_DQS_DP<8>")
	)
	(segment
		(start 19.033236 -283.427932)
		(end 18.428716 -283.427932)
		(width 0.20066)
		(layer "F.Cu")
		(net "M_D_CPU1_SA_DQS_DP<8>")
	)
	(segment
		(start 14.09319 -283.00553)
		(end 13.733018 -283.00553)
		(width 0.20066)
		(layer "F.Cu")
		(net "M_D_CPU1_SA_DQS_DP<8>")
	)
	(segment
		(start 19.294602 -283.166566)
		(end 19.033236 -283.427932)
		(width 0.20066)
		(layer "F.Cu")
		(net "M_D_CPU1_SA_DQS_DP<8>")
	)
	(segment
		(start 17.287748 -283.00299)
		(end 17.026636 -282.741878)
		(width 0.20066)
		(layer "F.Cu")
		(net "M_D_CPU1_SA_DQS_DP<8>")
	)
	(segment
		(start 66.705226 -279.681432)
		(end 63.3349 -279.681432)
		(width 0.18288)
		(layer "In11.Cu")
		(net "M_D_CPU1_SA_DQS_DP<8>")
	)
	(segment
		(start 45.883322 -283.003752)
		(end 45.301916 -282.422346)
		(width 0.18288)
		(layer "In11.Cu")
		(net "M_D_CPU1_SA_DQS_DP<8>")
	)
	(segment
		(start 83.258914 -268.830044)
		(end 83.022694 -268.830044)
		(width 0.088646)
		(layer "In11.Cu")
		(net "M_D_CPU1_SA_DQS_DP<8>")
	)
	(segment
		(start 51.247802 -281.890724)
		(end 50.868834 -281.890724)
		(width 0.18288)
		(layer "In11.Cu")
		(net "M_D_CPU1_SA_DQS_DP<8>")
	)
	(segment
		(start 49.71923 -282.152852)
		(end 48.872902 -282.99918)
		(width 0.18288)
		(layer "In11.Cu")
		(net "M_D_CPU1_SA_DQS_DP<8>")
	)
	(segment
		(start 31.410148 -283.023818)
		(end 30.790388 -283.023818)
		(width 0.18288)
		(layer "In11.Cu")
		(net "M_D_CPU1_SA_DQS_DP<8>")
	)
	(segment
		(start 48.872902 -282.99918)
		(end 47.411894 -282.99918)
		(width 0.18288)
		(layer "In11.Cu")
		(net "M_D_CPU1_SA_DQS_DP<8>")
	)
	(segment
		(start 95.035878 -267.25753)
		(end 95.021146 -267.266166)
		(width 0.088646)
		(layer "In11.Cu")
		(net "M_D_CPU1_SA_DQS_DP<8>")
	)
	(segment
		(start 83.3628 -268.603222)
		(end 83.3628 -268.726158)
		(width 0.088646)
		(layer "In11.Cu")
		(net "M_D_CPU1_SA_DQS_DP<8>")
	)
	(segment
		(start 47.154338 -282.741624)
		(end 46.763686 -282.741624)
		(width 0.18288)
		(layer "In11.Cu")
		(net "M_D_CPU1_SA_DQS_DP<8>")
	)
	(segment
		(start 21.1455 -283.422852)
		(end 20.889214 -283.166566)
		(width 0.18288)
		(layer "In11.Cu")
		(net "M_D_CPU1_SA_DQS_DP<8>")
	)
	(segment
		(start 29.368496 -282.423362)
		(end 28.170378 -282.919424)
		(width 0.18288)
		(layer "In11.Cu")
		(net "M_D_CPU1_SA_DQS_DP<8>")
	)
	(segment
		(start 50.868834 -281.890724)
		(end 50.606706 -282.152852)
		(width 0.18288)
		(layer "In11.Cu")
		(net "M_D_CPU1_SA_DQS_DP<8>")
	)
	(segment
		(start 55.858664 -281.4193)
		(end 55.10403 -282.173934)
		(width 0.18288)
		(layer "In11.Cu")
		(net "M_D_CPU1_SA_DQS_DP<8>")
	)
	(segment
		(start 89.007696 -267.266166)
		(end 89.007188 -267.266674)
		(width 0.088646)
		(layer "In11.Cu")
		(net "M_D_CPU1_SA_DQS_DP<8>")
	)
	(segment
		(start 21.694902 -283.422852)
		(end 21.1455 -283.422852)
		(width 0.18288)
		(layer "In11.Cu")
		(net "M_D_CPU1_SA_DQS_DP<8>")
	)
	(segment
		(start 84.212176 -267.316966)
		(end 84.008722 -267.401294)
		(width 0.088646)
		(layer "In11.Cu")
		(net "M_D_CPU1_SA_DQS_DP<8>")
	)
	(segment
		(start 90.887296 -267.266166)
		(end 90.872564 -267.25753)
		(width 0.088646)
		(layer "In11.Cu")
		(net "M_D_CPU1_SA_DQS_DP<8>")
	)
	(segment
		(start 59.45505 -280.717498)
		(end 58.753248 -281.4193)
		(width 0.18288)
		(layer "In11.Cu")
		(net "M_D_CPU1_SA_DQS_DP<8>")
	)
	(segment
		(start 35.154108 -282.16225)
		(end 34.755582 -282.560776)
		(width 0.18288)
		(layer "In11.Cu")
		(net "M_D_CPU1_SA_DQS_DP<8>")
	)
	(segment
		(start 43.198288 -283.118306)
		(end 41.83126 -283.118306)
		(width 0.18288)
		(layer "In11.Cu")
		(net "M_D_CPU1_SA_DQS_DP<8>")
	)
	(segment
		(start 36.158678 -281.890724)
		(end 35.786314 -281.890724)
		(width 0.18288)
		(layer "In11.Cu")
		(net "M_D_CPU1_SA_DQS_DP<8>")
	)
	(segment
		(start 88.4428 -267.266674)
		(end 88.442292 -267.266166)
		(width 0.088646)
		(layer "In11.Cu")
		(net "M_D_CPU1_SA_DQS_DP<8>")
	)
	(segment
		(start 84.496148 -267.316966)
		(end 84.212176 -267.316966)
		(width 0.088646)
		(layer "In11.Cu")
		(net "M_D_CPU1_SA_DQS_DP<8>")
	)
	(segment
		(start 99.734878 -267.25753)
		(end 99.720146 -267.266166)
		(width 0.088646)
		(layer "In11.Cu")
		(net "M_D_CPU1_SA_DQS_DP<8>")
	)
	(segment
		(start 51.531012 -282.173934)
		(end 51.247802 -281.890724)
		(width 0.18288)
		(layer "In11.Cu")
		(net "M_D_CPU1_SA_DQS_DP<8>")
	)
	(segment
		(start 30.790388 -283.023818)
		(end 30.189932 -282.423362)
		(width 0.18288)
		(layer "In11.Cu")
		(net "M_D_CPU1_SA_DQS_DP<8>")
	)
	(segment
		(start 82.963004 -268.770354)
		(end 77.616304 -268.770354)
		(width 0.18288)
		(layer "In11.Cu")
		(net "M_D_CPU1_SA_DQS_DP<8>")
	)
	(segment
		(start 83.657694 -268.308328)
		(end 83.3628 -268.603222)
		(width 0.088646)
		(layer "In11.Cu")
		(net "M_D_CPU1_SA_DQS_DP<8>")
	)
	(segment
		(start 32.061658 -282.740608)
		(end 31.693358 -282.740608)
		(width 0.18288)
		(layer "In11.Cu")
		(net "M_D_CPU1_SA_DQS_DP<8>")
	)
	(segment
		(start 34.755582 -282.560776)
		(end 33.67024 -283.01061)
		(width 0.18288)
		(layer "In11.Cu")
		(net "M_D_CPU1_SA_DQS_DP<8>")
	)
	(segment
		(start 97.465896 -267.266166)
		(end 97.455482 -267.26007)
		(width 0.088646)
		(layer "In11.Cu")
		(net "M_D_CPU1_SA_DQS_DP<8>")
	)
	(segment
		(start 84.683346 -267.265912)
		(end 84.6836 -267.266674)
		(width 0.088646)
		(layer "In11.Cu")
		(net "M_D_CPU1_SA_DQS_DP<8>")
	)
	(segment
		(start 44.242736 -282.422346)
		(end 43.792902 -282.871926)
		(width 0.18288)
		(layer "In11.Cu")
		(net "M_D_CPU1_SA_DQS_DP<8>")
	)
	(segment
		(start 94.096078 -267.25753)
		(end 94.081346 -267.266166)
		(width 0.088646)
		(layer "In11.Cu")
		(net "M_D_CPU1_SA_DQS_DP<8>")
	)
	(segment
		(start 43.792902 -282.871926)
		(end 43.198288 -283.118306)
		(width 0.18288)
		(layer "In11.Cu")
		(net "M_D_CPU1_SA_DQS_DP<8>")
	)
	(segment
		(start 36.412932 -282.144978)
		(end 36.158678 -281.890724)
		(width 0.18288)
		(layer "In11.Cu")
		(net "M_D_CPU1_SA_DQS_DP<8>")
	)
	(segment
		(start 61.408056 -280.413968)
		(end 61.104526 -280.717498)
		(width 0.18288)
		(layer "In11.Cu")
		(net "M_D_CPU1_SA_DQS_DP<8>")
	)
	(segment
		(start 50.606706 -282.152852)
		(end 49.71923 -282.152852)
		(width 0.18288)
		(layer "In11.Cu")
		(net "M_D_CPU1_SA_DQS_DP<8>")
	)
	(segment
		(start 33.67024 -283.01061)
		(end 32.33166 -283.01061)
		(width 0.18288)
		(layer "In11.Cu")
		(net "M_D_CPU1_SA_DQS_DP<8>")
	)
	(segment
		(start 63.3349 -279.681432)
		(end 62.602364 -280.413968)
		(width 0.18288)
		(layer "In11.Cu")
		(net "M_D_CPU1_SA_DQS_DP<8>")
	)
	(segment
		(start 47.411894 -282.99918)
		(end 47.154338 -282.741624)
		(width 0.18288)
		(layer "In11.Cu")
		(net "M_D_CPU1_SA_DQS_DP<8>")
	)
	(segment
		(start 100.62972 -267.755878)
		(end 100.564442 -267.6906)
		(width 0.088646)
		(layer "In11.Cu")
		(net "M_D_CPU1_SA_DQS_DP<8>")
	)
	(segment
		(start 46.501558 -283.003752)
		(end 45.883322 -283.003752)
		(width 0.18288)
		(layer "In11.Cu")
		(net "M_D_CPU1_SA_DQS_DP<8>")
	)
	(segment
		(start 83.022694 -268.830044)
		(end 82.963004 -268.770354)
		(width 0.088646)
		(layer "In11.Cu")
		(net "M_D_CPU1_SA_DQS_DP<8>")
	)
	(segment
		(start 21.93417 -283.66212)
		(end 21.694902 -283.422852)
		(width 0.18288)
		(layer "In11.Cu")
		(net "M_D_CPU1_SA_DQS_DP<8>")
	)
	(segment
		(start 93.156278 -267.25753)
		(end 93.141546 -267.266166)
		(width 0.088646)
		(layer "In11.Cu")
		(net "M_D_CPU1_SA_DQS_DP<8>")
	)
	(segment
		(start 58.753248 -281.4193)
		(end 55.858664 -281.4193)
		(width 0.18288)
		(layer "In11.Cu")
		(net "M_D_CPU1_SA_DQS_DP<8>")
	)
	(segment
		(start 100.942394 -267.755878)
		(end 100.62972 -267.755878)
		(width 0.088646)
		(layer "In11.Cu")
		(net "M_D_CPU1_SA_DQS_DP<8>")
	)
	(segment
		(start 32.33166 -283.01061)
		(end 32.061658 -282.740608)
		(width 0.18288)
		(layer "In11.Cu")
		(net "M_D_CPU1_SA_DQS_DP<8>")
	)
	(segment
		(start 95.975678 -267.25753)
		(end 95.960946 -267.266166)
		(width 0.088646)
		(layer "In11.Cu")
		(net "M_D_CPU1_SA_DQS_DP<8>")
	)
	(segment
		(start 61.104526 -280.717498)
		(end 59.45505 -280.717498)
		(width 0.18288)
		(layer "In11.Cu")
		(net "M_D_CPU1_SA_DQS_DP<8>")
	)
	(segment
		(start 77.616304 -268.770354)
		(end 66.705226 -279.681432)
		(width 0.18288)
		(layer "In11.Cu")
		(net "M_D_CPU1_SA_DQS_DP<8>")
	)
	(segment
		(start 91.272106 -267.26007)
		(end 91.261692 -267.266166)
		(width 0.088646)
		(layer "In11.Cu")
		(net "M_D_CPU1_SA_DQS_DP<8>")
	)
	(segment
		(start 62.602364 -280.413968)
		(end 61.408056 -280.413968)
		(width 0.18288)
		(layer "In11.Cu")
		(net "M_D_CPU1_SA_DQS_DP<8>")
	)
	(segment
		(start 30.189932 -282.423362)
		(end 29.368496 -282.423362)
		(width 0.18288)
		(layer "In11.Cu")
		(net "M_D_CPU1_SA_DQS_DP<8>")
	)
	(segment
		(start 83.657694 -267.752322)
		(end 83.657694 -268.308328)
		(width 0.088646)
		(layer "In11.Cu")
		(net "M_D_CPU1_SA_DQS_DP<8>")
	)
	(segment
		(start 46.763686 -282.741624)
		(end 46.501558 -283.003752)
		(width 0.18288)
		(layer "In11.Cu")
		(net "M_D_CPU1_SA_DQS_DP<8>")
	)
	(segment
		(start 26.377138 -282.919424)
		(end 24.583898 -283.66212)
		(width 0.18288)
		(layer "In11.Cu")
		(net "M_D_CPU1_SA_DQS_DP<8>")
	)
	(segment
		(start 41.83126 -283.118306)
		(end 39.48303 -282.144978)
		(width 0.18288)
		(layer "In11.Cu")
		(net "M_D_CPU1_SA_DQS_DP<8>")
	)
	(segment
		(start 55.10403 -282.173934)
		(end 51.531012 -282.173934)
		(width 0.18288)
		(layer "In11.Cu")
		(net "M_D_CPU1_SA_DQS_DP<8>")
	)
	(segment
		(start 31.693358 -282.740608)
		(end 31.410148 -283.023818)
		(width 0.18288)
		(layer "In11.Cu")
		(net "M_D_CPU1_SA_DQS_DP<8>")
	)
	(segment
		(start 39.48303 -282.144978)
		(end 36.412932 -282.144978)
		(width 0.18288)
		(layer "In11.Cu")
		(net "M_D_CPU1_SA_DQS_DP<8>")
	)
	(segment
		(start 97.850706 -267.26007)
		(end 97.840292 -267.266166)
		(width 0.088646)
		(layer "In11.Cu")
		(net "M_D_CPU1_SA_DQS_DP<8>")
	)
	(segment
		(start 28.170378 -282.919424)
		(end 26.377138 -282.919424)
		(width 0.18288)
		(layer "In11.Cu")
		(net "M_D_CPU1_SA_DQS_DP<8>")
	)
	(segment
		(start 24.583898 -283.66212)
		(end 21.93417 -283.66212)
		(width 0.18288)
		(layer "In11.Cu")
		(net "M_D_CPU1_SA_DQS_DP<8>")
	)
	(segment
		(start 45.301916 -282.422346)
		(end 44.242736 -282.422346)
		(width 0.18288)
		(layer "In11.Cu")
		(net "M_D_CPU1_SA_DQS_DP<8>")
	)
	(segment
		(start 84.008722 -267.401294)
		(end 83.657694 -267.752322)
		(width 0.088646)
		(layer "In11.Cu")
		(net "M_D_CPU1_SA_DQS_DP<8>")
	)
	(segment
		(start 35.514788 -282.16225)
		(end 35.154108 -282.16225)
		(width 0.18288)
		(layer "In11.Cu")
		(net "M_D_CPU1_SA_DQS_DP<8>")
	)
	(segment
		(start 98.795078 -267.25753)
		(end 98.780346 -267.266166)
		(width 0.088646)
		(layer "In11.Cu")
		(net "M_D_CPU1_SA_DQS_DP<8>")
	)
	(segment
		(start 35.786314 -281.890724)
		(end 35.514788 -282.16225)
		(width 0.18288)
		(layer "In11.Cu")
		(net "M_D_CPU1_SA_DQS_DP<8>")
	)
	(segment
		(start 92.216478 -267.25753)
		(end 92.201746 -267.266166)
		(width 0.088646)
		(layer "In11.Cu")
		(net "M_D_CPU1_SA_DQS_DP<8>")
	)
	(segment
		(start 83.3628 -268.726158)
		(end 83.258914 -268.830044)
		(width 0.088646)
		(layer "In11.Cu")
		(net "M_D_CPU1_SA_DQS_DP<8>")
	)
	(arc
		(start 93.70695 -267.266166)
		(mid 93.432721 -267.190241)
		(end 93.156278 -267.25753)
		(width 0.088646)
		(layer "In11.Cu")
		(net "M_D_CPU1_SA_DQS_DP<8>")
	)
	(arc
		(start 89.382092 -267.266166)
		(mid 89.194894 -267.316309)
		(end 89.007696 -267.266166)
		(width 0.088646)
		(layer "In11.Cu")
		(net "M_D_CPU1_SA_DQS_DP<8>")
	)
	(arc
		(start 84.6836 -267.266674)
		(mid 84.593185 -267.30417)
		(end 84.496148 -267.316966)
		(width 0.088646)
		(layer "In11.Cu")
		(net "M_D_CPU1_SA_DQS_DP<8>")
	)
	(arc
		(start 97.840292 -267.266166)
		(mid 97.653094 -267.316309)
		(end 97.465896 -267.266166)
		(width 0.088646)
		(layer "In11.Cu")
		(net "M_D_CPU1_SA_DQS_DP<8>")
	)
	(arc
		(start 93.141546 -267.266166)
		(mid 92.954348 -267.316309)
		(end 92.76715 -267.266166)
		(width 0.088646)
		(layer "In11.Cu")
		(net "M_D_CPU1_SA_DQS_DP<8>")
	)
	(arc
		(start 95.960946 -267.266166)
		(mid 95.773748 -267.316309)
		(end 95.58655 -267.266166)
		(width 0.088646)
		(layer "In11.Cu")
		(net "M_D_CPU1_SA_DQS_DP<8>")
	)
	(arc
		(start 97.455482 -267.26007)
		(mid 97.177304 -267.190378)
		(end 96.900746 -267.266166)
		(width 0.088646)
		(layer "In11.Cu")
		(net "M_D_CPU1_SA_DQS_DP<8>")
	)
	(arc
		(start 87.128096 -267.266166)
		(mid 86.845394 -267.190424)
		(end 86.562692 -267.266166)
		(width 0.088646)
		(layer "In11.Cu")
		(net "M_D_CPU1_SA_DQS_DP<8>")
	)
	(arc
		(start 96.900746 -267.266166)
		(mid 96.713548 -267.316309)
		(end 96.52635 -267.266166)
		(width 0.088646)
		(layer "In11.Cu")
		(net "M_D_CPU1_SA_DQS_DP<8>")
	)
	(arc
		(start 98.40595 -267.266166)
		(mid 98.129137 -267.19033)
		(end 97.850706 -267.26007)
		(width 0.088646)
		(layer "In11.Cu")
		(net "M_D_CPU1_SA_DQS_DP<8>")
	)
	(arc
		(start 89.947496 -267.266166)
		(mid 89.664794 -267.190424)
		(end 89.382092 -267.266166)
		(width 0.088646)
		(layer "In11.Cu")
		(net "M_D_CPU1_SA_DQS_DP<8>")
	)
	(arc
		(start 94.64675 -267.266166)
		(mid 94.372521 -267.190241)
		(end 94.096078 -267.25753)
		(width 0.088646)
		(layer "In11.Cu")
		(net "M_D_CPU1_SA_DQS_DP<8>")
	)
	(arc
		(start 85.622892 -267.266166)
		(mid 85.435694 -267.316309)
		(end 85.248496 -267.266166)
		(width 0.088646)
		(layer "In11.Cu")
		(net "M_D_CPU1_SA_DQS_DP<8>")
	)
	(arc
		(start 95.021146 -267.266166)
		(mid 94.833948 -267.316309)
		(end 94.64675 -267.266166)
		(width 0.088646)
		(layer "In11.Cu")
		(net "M_D_CPU1_SA_DQS_DP<8>")
	)
	(arc
		(start 86.188296 -267.266166)
		(mid 85.905594 -267.190424)
		(end 85.622892 -267.266166)
		(width 0.088646)
		(layer "In11.Cu")
		(net "M_D_CPU1_SA_DQS_DP<8>")
	)
	(arc
		(start 91.261692 -267.266166)
		(mid 91.074494 -267.316309)
		(end 90.887296 -267.266166)
		(width 0.088646)
		(layer "In11.Cu")
		(net "M_D_CPU1_SA_DQS_DP<8>")
	)
	(arc
		(start 95.58655 -267.266166)
		(mid 95.312321 -267.190241)
		(end 95.035878 -267.25753)
		(width 0.088646)
		(layer "In11.Cu")
		(net "M_D_CPU1_SA_DQS_DP<8>")
	)
	(arc
		(start 86.562692 -267.266166)
		(mid 86.375494 -267.316309)
		(end 86.188296 -267.266166)
		(width 0.088646)
		(layer "In11.Cu")
		(net "M_D_CPU1_SA_DQS_DP<8>")
	)
	(arc
		(start 88.067896 -267.266166)
		(mid 87.785194 -267.190424)
		(end 87.502492 -267.266166)
		(width 0.088646)
		(layer "In11.Cu")
		(net "M_D_CPU1_SA_DQS_DP<8>")
	)
	(arc
		(start 85.248496 -267.266166)
		(mid 84.965967 -267.190424)
		(end 84.683346 -267.265912)
		(width 0.088646)
		(layer "In11.Cu")
		(net "M_D_CPU1_SA_DQS_DP<8>")
	)
	(arc
		(start 87.502492 -267.266166)
		(mid 87.315294 -267.316309)
		(end 87.128096 -267.266166)
		(width 0.088646)
		(layer "In11.Cu")
		(net "M_D_CPU1_SA_DQS_DP<8>")
	)
	(arc
		(start 98.780346 -267.266166)
		(mid 98.593148 -267.316309)
		(end 98.40595 -267.266166)
		(width 0.088646)
		(layer "In11.Cu")
		(net "M_D_CPU1_SA_DQS_DP<8>")
	)
	(arc
		(start 100.561648 -267.669264)
		(mid 100.25479 -267.249478)
		(end 99.734878 -267.25753)
		(width 0.088646)
		(layer "In11.Cu")
		(net "M_D_CPU1_SA_DQS_DP<8>")
	)
	(arc
		(start 100.564442 -267.6906)
		(mid 100.563147 -267.679919)
		(end 100.561648 -267.669264)
		(width 0.088646)
		(layer "In11.Cu")
		(net "M_D_CPU1_SA_DQS_DP<8>")
	)
	(arc
		(start 90.321892 -267.266166)
		(mid 90.134694 -267.316309)
		(end 89.947496 -267.266166)
		(width 0.088646)
		(layer "In11.Cu")
		(net "M_D_CPU1_SA_DQS_DP<8>")
	)
	(arc
		(start 91.82735 -267.266166)
		(mid 91.550537 -267.19033)
		(end 91.272106 -267.26007)
		(width 0.088646)
		(layer "In11.Cu")
		(net "M_D_CPU1_SA_DQS_DP<8>")
	)
	(arc
		(start 89.007188 -267.266674)
		(mid 88.724994 -267.191118)
		(end 88.4428 -267.266674)
		(width 0.088646)
		(layer "In11.Cu")
		(net "M_D_CPU1_SA_DQS_DP<8>")
	)
	(arc
		(start 94.081346 -267.266166)
		(mid 93.894148 -267.316309)
		(end 93.70695 -267.266166)
		(width 0.088646)
		(layer "In11.Cu")
		(net "M_D_CPU1_SA_DQS_DP<8>")
	)
	(arc
		(start 99.720146 -267.266166)
		(mid 99.532948 -267.316309)
		(end 99.34575 -267.266166)
		(width 0.088646)
		(layer "In11.Cu")
		(net "M_D_CPU1_SA_DQS_DP<8>")
	)
	(arc
		(start 90.872564 -267.25753)
		(mid 90.596123 -267.190364)
		(end 90.321892 -267.266166)
		(width 0.088646)
		(layer "In11.Cu")
		(net "M_D_CPU1_SA_DQS_DP<8>")
	)
	(arc
		(start 92.201746 -267.266166)
		(mid 92.014548 -267.316309)
		(end 91.82735 -267.266166)
		(width 0.088646)
		(layer "In11.Cu")
		(net "M_D_CPU1_SA_DQS_DP<8>")
	)
	(arc
		(start 88.442292 -267.266166)
		(mid 88.255094 -267.316309)
		(end 88.067896 -267.266166)
		(width 0.088646)
		(layer "In11.Cu")
		(net "M_D_CPU1_SA_DQS_DP<8>")
	)
	(arc
		(start 92.76715 -267.266166)
		(mid 92.492921 -267.190241)
		(end 92.216478 -267.25753)
		(width 0.088646)
		(layer "In11.Cu")
		(net "M_D_CPU1_SA_DQS_DP<8>")
	)
	(arc
		(start 96.52635 -267.266166)
		(mid 96.252121 -267.190241)
		(end 95.975678 -267.25753)
		(width 0.088646)
		(layer "In11.Cu")
		(net "M_D_CPU1_SA_DQS_DP<8>")
	)
	(arc
		(start 99.34575 -267.266166)
		(mid 99.071521 -267.190241)
		(end 98.795078 -267.25753)
		(width 0.088646)
		(layer "In11.Cu")
		(net "M_D_CPU1_SA_DQS_DP<8>")
	)
	(segment
		(start 14.362684 -292.08603)
		(end 14.09319 -292.355524)
		(width 0.20066)
		(layer "F.Cu")
		(net "M_D_CPU1_SA_DQS_DP<7>")
	)
	(segment
		(start 13.733018 -292.355524)
		(end 13.310616 -292.777926)
		(width 0.20066)
		(layer "F.Cu")
		(net "M_D_CPU1_SA_DQS_DP<7>")
	)
	(segment
		(start 19.033236 -292.777926)
		(end 18.428716 -292.777926)
		(width 0.20066)
		(layer "F.Cu")
		(net "M_D_CPU1_SA_DQS_DP<7>")
	)
	(segment
		(start 16.885158 -292.091872)
		(end 14.806676 -292.091872)
		(width 0.1016)
		(layer "F.Cu")
		(net "M_D_CPU1_SA_DQS_DP<7>")
	)
	(segment
		(start 20.889214 -292.516814)
		(end 19.784314 -292.516814)
		(width 0.20066)
		(layer "F.Cu")
		(net "M_D_CPU1_SA_DQS_DP<7>")
	)
	(segment
		(start 13.310616 -292.777926)
		(end 12.976352 -292.777926)
		(width 0.20066)
		(layer "F.Cu")
		(net "M_D_CPU1_SA_DQS_DP<7>")
	)
	(segment
		(start 17.287748 -292.352984)
		(end 17.026636 -292.091872)
		(width 0.20066)
		(layer "F.Cu")
		(net "M_D_CPU1_SA_DQS_DP<7>")
	)
	(segment
		(start 14.09319 -292.355524)
		(end 13.733018 -292.355524)
		(width 0.20066)
		(layer "F.Cu")
		(net "M_D_CPU1_SA_DQS_DP<7>")
	)
	(segment
		(start 12.71524 -292.516814)
		(end 12.240514 -292.516814)
		(width 0.20066)
		(layer "F.Cu")
		(net "M_D_CPU1_SA_DQS_DP<7>")
	)
	(segment
		(start 17.026636 -292.091872)
		(end 16.885158 -292.091872)
		(width 0.20066)
		(layer "F.Cu")
		(net "M_D_CPU1_SA_DQS_DP<7>")
	)
	(segment
		(start 18.428716 -292.777926)
		(end 17.7927 -292.352984)
		(width 0.20066)
		(layer "F.Cu")
		(net "M_D_CPU1_SA_DQS_DP<7>")
	)
	(segment
		(start 14.560042 -292.08603)
		(end 14.362684 -292.08603)
		(width 0.20066)
		(layer "F.Cu")
		(net "M_D_CPU1_SA_DQS_DP<7>")
	)
	(segment
		(start 14.806676 -292.091872)
		(end 14.565884 -292.091872)
		(width 0.101854)
		(layer "F.Cu")
		(net "M_D_CPU1_SA_DQS_DP<7>")
	)
	(segment
		(start 19.784314 -292.516814)
		(end 19.294348 -292.516814)
		(width 0.20066)
		(layer "F.Cu")
		(net "M_D_CPU1_SA_DQS_DP<7>")
	)
	(segment
		(start 17.7927 -292.352984)
		(end 17.287748 -292.352984)
		(width 0.20066)
		(layer "F.Cu")
		(net "M_D_CPU1_SA_DQS_DP<7>")
	)
	(segment
		(start 12.976352 -292.777926)
		(end 12.71524 -292.516814)
		(width 0.20066)
		(layer "F.Cu")
		(net "M_D_CPU1_SA_DQS_DP<7>")
	)
	(segment
		(start 14.565884 -292.091872)
		(end 14.560042 -292.08603)
		(width 0.101854)
		(layer "F.Cu")
		(net "M_D_CPU1_SA_DQS_DP<7>")
	)
	(segment
		(start 19.294348 -292.516814)
		(end 19.033236 -292.777926)
		(width 0.20066)
		(layer "F.Cu")
		(net "M_D_CPU1_SA_DQS_DP<7>")
	)
	(arc
		(start 100.942648 -272.103342)
		(mid 100.942584 -272.371312)
		(end 100.942394 -272.639282)
		(width 0.20066)
		(layer "F.Cu")
		(net "M_D_CPU1_SA_DQS_DP<7>")
	)
	(segment
		(start 47.193962 -294.641016)
		(end 46.773846 -294.641016)
		(width 0.18288)
		(layer "In11.Cu")
		(net "M_D_CPU1_SA_DQS_DP<7>")
	)
	(segment
		(start 100.942394 -272.639282)
		(end 100.62972 -272.639282)
		(width 0.088646)
		(layer "In11.Cu")
		(net "M_D_CPU1_SA_DQS_DP<7>")
	)
	(segment
		(start 48.785018 -294.913304)
		(end 47.46625 -294.913304)
		(width 0.18288)
		(layer "In11.Cu")
		(net "M_D_CPU1_SA_DQS_DP<7>")
	)
	(segment
		(start 43.396154 -294.74287)
		(end 42.851324 -294.546782)
		(width 0.18288)
		(layer "In11.Cu")
		(net "M_D_CPU1_SA_DQS_DP<7>")
	)
	(segment
		(start 30.74035 -294.908732)
		(end 30.11297 -295.536112)
		(width 0.18288)
		(layer "In11.Cu")
		(net "M_D_CPU1_SA_DQS_DP<7>")
	)
	(segment
		(start 95.035878 -272.140934)
		(end 95.021146 -272.14957)
		(width 0.088646)
		(layer "In11.Cu")
		(net "M_D_CPU1_SA_DQS_DP<7>")
	)
	(segment
		(start 90.887296 -272.14957)
		(end 90.872564 -272.140934)
		(width 0.088646)
		(layer "In11.Cu")
		(net "M_D_CPU1_SA_DQS_DP<7>")
	)
	(segment
		(start 31.684214 -294.641016)
		(end 31.416498 -294.908732)
		(width 0.18288)
		(layer "In11.Cu")
		(net "M_D_CPU1_SA_DQS_DP<7>")
	)
	(segment
		(start 51.538378 -294.07485)
		(end 51.254406 -293.790878)
		(width 0.18288)
		(layer "In11.Cu")
		(net "M_D_CPU1_SA_DQS_DP<7>")
	)
	(segment
		(start 51.254406 -293.790878)
		(end 50.873914 -293.790878)
		(width 0.18288)
		(layer "In11.Cu")
		(net "M_D_CPU1_SA_DQS_DP<7>")
	)
	(segment
		(start 84.28482 -272.527776)
		(end 84.28482 -272.665444)
		(width 0.088646)
		(layer "In11.Cu")
		(net "M_D_CPU1_SA_DQS_DP<7>")
	)
	(segment
		(start 40.187372 -293.890192)
		(end 38.003226 -293.890192)
		(width 0.18288)
		(layer "In11.Cu")
		(net "M_D_CPU1_SA_DQS_DP<7>")
	)
	(segment
		(start 95.975678 -272.140934)
		(end 95.960946 -272.14957)
		(width 0.088646)
		(layer "In11.Cu")
		(net "M_D_CPU1_SA_DQS_DP<7>")
	)
	(segment
		(start 30.11297 -295.536112)
		(end 29.2608 -295.536112)
		(width 0.18288)
		(layer "In11.Cu")
		(net "M_D_CPU1_SA_DQS_DP<7>")
	)
	(segment
		(start 84.284566 -272.665698)
		(end 84.28482 -272.665952)
		(width 0.088646)
		(layer "In11.Cu")
		(net "M_D_CPU1_SA_DQS_DP<7>")
	)
	(segment
		(start 21.154136 -292.781736)
		(end 20.889214 -292.516814)
		(width 0.18288)
		(layer "In11.Cu")
		(net "M_D_CPU1_SA_DQS_DP<7>")
	)
	(segment
		(start 66.157094 -288.984436)
		(end 63.688468 -288.984436)
		(width 0.18288)
		(layer "In11.Cu")
		(net "M_D_CPU1_SA_DQS_DP<7>")
	)
	(segment
		(start 89.00795 -272.14957)
		(end 88.997536 -272.143474)
		(width 0.088646)
		(layer "In11.Cu")
		(net "M_D_CPU1_SA_DQS_DP<7>")
	)
	(segment
		(start 43.855894 -294.74287)
		(end 43.396154 -294.74287)
		(width 0.18288)
		(layer "In11.Cu")
		(net "M_D_CPU1_SA_DQS_DP<7>")
	)
	(segment
		(start 27.042364 -293.683944)
		(end 25.411684 -293.008812)
		(width 0.18288)
		(layer "In11.Cu")
		(net "M_D_CPU1_SA_DQS_DP<7>")
	)
	(segment
		(start 29.2608 -295.536112)
		(end 28.806394 -295.081706)
		(width 0.18288)
		(layer "In11.Cu")
		(net "M_D_CPU1_SA_DQS_DP<7>")
	)
	(segment
		(start 59.421522 -290.07308)
		(end 58.586116 -290.908486)
		(width 0.18288)
		(layer "In11.Cu")
		(net "M_D_CPU1_SA_DQS_DP<7>")
	)
	(segment
		(start 35.51682 -294.054784)
		(end 34.86658 -294.054784)
		(width 0.18288)
		(layer "In11.Cu")
		(net "M_D_CPU1_SA_DQS_DP<7>")
	)
	(segment
		(start 100.62972 -272.639282)
		(end 100.564442 -272.574004)
		(width 0.088646)
		(layer "In11.Cu")
		(net "M_D_CPU1_SA_DQS_DP<7>")
	)
	(segment
		(start 83.402932 -274.723098)
		(end 83.281266 -274.844764)
		(width 0.088646)
		(layer "In11.Cu")
		(net "M_D_CPU1_SA_DQS_DP<7>")
	)
	(segment
		(start 36.159694 -293.790878)
		(end 35.780726 -293.790878)
		(width 0.18288)
		(layer "In11.Cu")
		(net "M_D_CPU1_SA_DQS_DP<7>")
	)
	(segment
		(start 84.966048 -272.073878)
		(end 84.738718 -272.073878)
		(width 0.088646)
		(layer "In11.Cu")
		(net "M_D_CPU1_SA_DQS_DP<7>")
	)
	(segment
		(start 84.28482 -273.502628)
		(end 83.402932 -274.384516)
		(width 0.088646)
		(layer "In11.Cu")
		(net "M_D_CPU1_SA_DQS_DP<7>")
	)
	(segment
		(start 63.688468 -288.984436)
		(end 62.599824 -290.07308)
		(width 0.18288)
		(layer "In11.Cu")
		(net "M_D_CPU1_SA_DQS_DP<7>")
	)
	(segment
		(start 84.738718 -272.073878)
		(end 84.28482 -272.527776)
		(width 0.088646)
		(layer "In11.Cu")
		(net "M_D_CPU1_SA_DQS_DP<7>")
	)
	(segment
		(start 89.39276 -272.143474)
		(end 89.382346 -272.14957)
		(width 0.088646)
		(layer "In11.Cu")
		(net "M_D_CPU1_SA_DQS_DP<7>")
	)
	(segment
		(start 56.608726 -292.209474)
		(end 54.801008 -292.958266)
		(width 0.18288)
		(layer "In11.Cu")
		(net "M_D_CPU1_SA_DQS_DP<7>")
	)
	(segment
		(start 38.003226 -293.890192)
		(end 37.974778 -293.91864)
		(width 0.18288)
		(layer "In11.Cu")
		(net "M_D_CPU1_SA_DQS_DP<7>")
	)
	(segment
		(start 93.156278 -272.140934)
		(end 93.141546 -272.14957)
		(width 0.088646)
		(layer "In11.Cu")
		(net "M_D_CPU1_SA_DQS_DP<7>")
	)
	(segment
		(start 97.850706 -272.143474)
		(end 97.840292 -272.14957)
		(width 0.088646)
		(layer "In11.Cu")
		(net "M_D_CPU1_SA_DQS_DP<7>")
	)
	(segment
		(start 52.377086 -294.07485)
		(end 51.538378 -294.07485)
		(width 0.18288)
		(layer "In11.Cu")
		(net "M_D_CPU1_SA_DQS_DP<7>")
	)
	(segment
		(start 34.011362 -294.910002)
		(end 32.416496 -294.910002)
		(width 0.18288)
		(layer "In11.Cu")
		(net "M_D_CPU1_SA_DQS_DP<7>")
	)
	(segment
		(start 44.291758 -294.307006)
		(end 43.855894 -294.74287)
		(width 0.18288)
		(layer "In11.Cu")
		(net "M_D_CPU1_SA_DQS_DP<7>")
	)
	(segment
		(start 40.625776 -293.451788)
		(end 40.187372 -293.890192)
		(width 0.18288)
		(layer "In11.Cu")
		(net "M_D_CPU1_SA_DQS_DP<7>")
	)
	(segment
		(start 83.064858 -274.785074)
		(end 80.356456 -274.785074)
		(width 0.18288)
		(layer "In11.Cu")
		(net "M_D_CPU1_SA_DQS_DP<7>")
	)
	(segment
		(start 46.773846 -294.641016)
		(end 46.502574 -294.912288)
		(width 0.18288)
		(layer "In11.Cu")
		(net "M_D_CPU1_SA_DQS_DP<7>")
	)
	(segment
		(start 45.278294 -294.307006)
		(end 44.291758 -294.307006)
		(width 0.18288)
		(layer "In11.Cu")
		(net "M_D_CPU1_SA_DQS_DP<7>")
	)
	(segment
		(start 87.128096 -272.14957)
		(end 87.113364 -272.140934)
		(width 0.088646)
		(layer "In11.Cu")
		(net "M_D_CPU1_SA_DQS_DP<7>")
	)
	(segment
		(start 83.124548 -274.844764)
		(end 83.064858 -274.785074)
		(width 0.088646)
		(layer "In11.Cu")
		(net "M_D_CPU1_SA_DQS_DP<7>")
	)
	(segment
		(start 98.795078 -272.140934)
		(end 98.780346 -272.14957)
		(width 0.088646)
		(layer "In11.Cu")
		(net "M_D_CPU1_SA_DQS_DP<7>")
	)
	(segment
		(start 99.734878 -272.140934)
		(end 99.720146 -272.14957)
		(width 0.088646)
		(layer "In11.Cu")
		(net "M_D_CPU1_SA_DQS_DP<7>")
	)
	(segment
		(start 54.801008 -292.958266)
		(end 53.493924 -292.958266)
		(width 0.18288)
		(layer "In11.Cu")
		(net "M_D_CPU1_SA_DQS_DP<7>")
	)
	(segment
		(start 50.135282 -294.121332)
		(end 48.785018 -294.913304)
		(width 0.18288)
		(layer "In11.Cu")
		(net "M_D_CPU1_SA_DQS_DP<7>")
	)
	(segment
		(start 35.780726 -293.790878)
		(end 35.51682 -294.054784)
		(width 0.18288)
		(layer "In11.Cu")
		(net "M_D_CPU1_SA_DQS_DP<7>")
	)
	(segment
		(start 50.54346 -294.121332)
		(end 50.135282 -294.121332)
		(width 0.18288)
		(layer "In11.Cu")
		(net "M_D_CPU1_SA_DQS_DP<7>")
	)
	(segment
		(start 84.28482 -272.665952)
		(end 84.28482 -273.502628)
		(width 0.088646)
		(layer "In11.Cu")
		(net "M_D_CPU1_SA_DQS_DP<7>")
	)
	(segment
		(start 53.493924 -292.958266)
		(end 52.377086 -294.07485)
		(width 0.18288)
		(layer "In11.Cu")
		(net "M_D_CPU1_SA_DQS_DP<7>")
	)
	(segment
		(start 32.14751 -294.641016)
		(end 31.684214 -294.641016)
		(width 0.18288)
		(layer "In11.Cu")
		(net "M_D_CPU1_SA_DQS_DP<7>")
	)
	(segment
		(start 36.430204 -294.061388)
		(end 36.159694 -293.790878)
		(width 0.18288)
		(layer "In11.Cu")
		(net "M_D_CPU1_SA_DQS_DP<7>")
	)
	(segment
		(start 45.883576 -294.912288)
		(end 45.278294 -294.307006)
		(width 0.18288)
		(layer "In11.Cu")
		(net "M_D_CPU1_SA_DQS_DP<7>")
	)
	(segment
		(start 94.096078 -272.140934)
		(end 94.081346 -272.14957)
		(width 0.088646)
		(layer "In11.Cu")
		(net "M_D_CPU1_SA_DQS_DP<7>")
	)
	(segment
		(start 37.974778 -293.91864)
		(end 37.6301 -294.061388)
		(width 0.18288)
		(layer "In11.Cu")
		(net "M_D_CPU1_SA_DQS_DP<7>")
	)
	(segment
		(start 28.806394 -295.081706)
		(end 28.439872 -295.081706)
		(width 0.18288)
		(layer "In11.Cu")
		(net "M_D_CPU1_SA_DQS_DP<7>")
	)
	(segment
		(start 32.416496 -294.910002)
		(end 32.14751 -294.641016)
		(width 0.18288)
		(layer "In11.Cu")
		(net "M_D_CPU1_SA_DQS_DP<7>")
	)
	(segment
		(start 37.6301 -294.061388)
		(end 36.430204 -294.061388)
		(width 0.18288)
		(layer "In11.Cu")
		(net "M_D_CPU1_SA_DQS_DP<7>")
	)
	(segment
		(start 21.608796 -292.781736)
		(end 21.154136 -292.781736)
		(width 0.18288)
		(layer "In11.Cu")
		(net "M_D_CPU1_SA_DQS_DP<7>")
	)
	(segment
		(start 22.157436 -293.008812)
		(end 21.608796 -292.781736)
		(width 0.18288)
		(layer "In11.Cu")
		(net "M_D_CPU1_SA_DQS_DP<7>")
	)
	(segment
		(start 46.502574 -294.912288)
		(end 45.883576 -294.912288)
		(width 0.18288)
		(layer "In11.Cu")
		(net "M_D_CPU1_SA_DQS_DP<7>")
	)
	(segment
		(start 83.281266 -274.844764)
		(end 83.124548 -274.844764)
		(width 0.088646)
		(layer "In11.Cu")
		(net "M_D_CPU1_SA_DQS_DP<7>")
	)
	(segment
		(start 92.216478 -272.140934)
		(end 92.201746 -272.14957)
		(width 0.088646)
		(layer "In11.Cu")
		(net "M_D_CPU1_SA_DQS_DP<7>")
	)
	(segment
		(start 34.86658 -294.054784)
		(end 34.011362 -294.910002)
		(width 0.18288)
		(layer "In11.Cu")
		(net "M_D_CPU1_SA_DQS_DP<7>")
	)
	(segment
		(start 41.75633 -293.451788)
		(end 40.625776 -293.451788)
		(width 0.18288)
		(layer "In11.Cu")
		(net "M_D_CPU1_SA_DQS_DP<7>")
	)
	(segment
		(start 31.416498 -294.908732)
		(end 30.74035 -294.908732)
		(width 0.18288)
		(layer "In11.Cu")
		(net "M_D_CPU1_SA_DQS_DP<7>")
	)
	(segment
		(start 42.851324 -294.546782)
		(end 41.75633 -293.451788)
		(width 0.18288)
		(layer "In11.Cu")
		(net "M_D_CPU1_SA_DQS_DP<7>")
	)
	(segment
		(start 80.356456 -274.785074)
		(end 66.157094 -288.984436)
		(width 0.18288)
		(layer "In11.Cu")
		(net "M_D_CPU1_SA_DQS_DP<7>")
	)
	(segment
		(start 25.411684 -293.008812)
		(end 22.157436 -293.008812)
		(width 0.18288)
		(layer "In11.Cu")
		(net "M_D_CPU1_SA_DQS_DP<7>")
	)
	(segment
		(start 58.586116 -290.908486)
		(end 57.909714 -290.908486)
		(width 0.18288)
		(layer "In11.Cu")
		(net "M_D_CPU1_SA_DQS_DP<7>")
	)
	(segment
		(start 83.402932 -274.384516)
		(end 83.402932 -274.723098)
		(width 0.088646)
		(layer "In11.Cu")
		(net "M_D_CPU1_SA_DQS_DP<7>")
	)
	(segment
		(start 62.599824 -290.07308)
		(end 59.421522 -290.07308)
		(width 0.18288)
		(layer "In11.Cu")
		(net "M_D_CPU1_SA_DQS_DP<7>")
	)
	(segment
		(start 47.46625 -294.913304)
		(end 47.193962 -294.641016)
		(width 0.18288)
		(layer "In11.Cu")
		(net "M_D_CPU1_SA_DQS_DP<7>")
	)
	(segment
		(start 57.909714 -290.908486)
		(end 56.608726 -292.209474)
		(width 0.18288)
		(layer "In11.Cu")
		(net "M_D_CPU1_SA_DQS_DP<7>")
	)
	(segment
		(start 97.465896 -272.14957)
		(end 97.455482 -272.143474)
		(width 0.088646)
		(layer "In11.Cu")
		(net "M_D_CPU1_SA_DQS_DP<7>")
	)
	(segment
		(start 28.439872 -295.081706)
		(end 27.042364 -293.683944)
		(width 0.18288)
		(layer "In11.Cu")
		(net "M_D_CPU1_SA_DQS_DP<7>")
	)
	(segment
		(start 91.272106 -272.143474)
		(end 91.261692 -272.14957)
		(width 0.088646)
		(layer "In11.Cu")
		(net "M_D_CPU1_SA_DQS_DP<7>")
	)
	(segment
		(start 84.28482 -272.665444)
		(end 84.284566 -272.665698)
		(width 0.088646)
		(layer "In11.Cu")
		(net "M_D_CPU1_SA_DQS_DP<7>")
	)
	(segment
		(start 50.873914 -293.790878)
		(end 50.54346 -294.121332)
		(width 0.18288)
		(layer "In11.Cu")
		(net "M_D_CPU1_SA_DQS_DP<7>")
	)
	(arc
		(start 86.188296 -272.14957)
		(mid 85.905594 -272.073828)
		(end 85.622892 -272.14957)
		(width 0.088646)
		(layer "In11.Cu")
		(net "M_D_CPU1_SA_DQS_DP<7>")
	)
	(arc
		(start 88.067896 -272.14957)
		(mid 87.785194 -272.073828)
		(end 87.502492 -272.14957)
		(width 0.088646)
		(layer "In11.Cu")
		(net "M_D_CPU1_SA_DQS_DP<7>")
	)
	(arc
		(start 99.34575 -272.14957)
		(mid 99.071521 -272.073645)
		(end 98.795078 -272.140934)
		(width 0.088646)
		(layer "In11.Cu")
		(net "M_D_CPU1_SA_DQS_DP<7>")
	)
	(arc
		(start 90.321892 -272.14957)
		(mid 90.134694 -272.199713)
		(end 89.947496 -272.14957)
		(width 0.088646)
		(layer "In11.Cu")
		(net "M_D_CPU1_SA_DQS_DP<7>")
	)
	(arc
		(start 96.52635 -272.14957)
		(mid 96.252121 -272.073645)
		(end 95.975678 -272.140934)
		(width 0.088646)
		(layer "In11.Cu")
		(net "M_D_CPU1_SA_DQS_DP<7>")
	)
	(arc
		(start 97.840292 -272.14957)
		(mid 97.653094 -272.199713)
		(end 97.465896 -272.14957)
		(width 0.088646)
		(layer "In11.Cu")
		(net "M_D_CPU1_SA_DQS_DP<7>")
	)
	(arc
		(start 93.70695 -272.14957)
		(mid 93.432721 -272.073645)
		(end 93.156278 -272.140934)
		(width 0.088646)
		(layer "In11.Cu")
		(net "M_D_CPU1_SA_DQS_DP<7>")
	)
	(arc
		(start 97.455482 -272.143474)
		(mid 97.177304 -272.073782)
		(end 96.900746 -272.14957)
		(width 0.088646)
		(layer "In11.Cu")
		(net "M_D_CPU1_SA_DQS_DP<7>")
	)
	(arc
		(start 87.113364 -272.140934)
		(mid 86.836923 -272.073768)
		(end 86.562692 -272.14957)
		(width 0.088646)
		(layer "In11.Cu")
		(net "M_D_CPU1_SA_DQS_DP<7>")
	)
	(arc
		(start 92.76715 -272.14957)
		(mid 92.492921 -272.073645)
		(end 92.216478 -272.140934)
		(width 0.088646)
		(layer "In11.Cu")
		(net "M_D_CPU1_SA_DQS_DP<7>")
	)
	(arc
		(start 86.562692 -272.14957)
		(mid 86.375494 -272.199713)
		(end 86.188296 -272.14957)
		(width 0.088646)
		(layer "In11.Cu")
		(net "M_D_CPU1_SA_DQS_DP<7>")
	)
	(arc
		(start 95.58655 -272.14957)
		(mid 95.312321 -272.073645)
		(end 95.035878 -272.140934)
		(width 0.088646)
		(layer "In11.Cu")
		(net "M_D_CPU1_SA_DQS_DP<7>")
	)
	(arc
		(start 89.947496 -272.14957)
		(mid 89.670937 -272.073861)
		(end 89.39276 -272.143474)
		(width 0.088646)
		(layer "In11.Cu")
		(net "M_D_CPU1_SA_DQS_DP<7>")
	)
	(arc
		(start 88.997536 -272.143474)
		(mid 88.719104 -272.07366)
		(end 88.442292 -272.14957)
		(width 0.088646)
		(layer "In11.Cu")
		(net "M_D_CPU1_SA_DQS_DP<7>")
	)
	(arc
		(start 91.261692 -272.14957)
		(mid 91.074494 -272.199713)
		(end 90.887296 -272.14957)
		(width 0.088646)
		(layer "In11.Cu")
		(net "M_D_CPU1_SA_DQS_DP<7>")
	)
	(arc
		(start 91.82735 -272.14957)
		(mid 91.550537 -272.073734)
		(end 91.272106 -272.143474)
		(width 0.088646)
		(layer "In11.Cu")
		(net "M_D_CPU1_SA_DQS_DP<7>")
	)
	(arc
		(start 95.021146 -272.14957)
		(mid 94.833948 -272.199713)
		(end 94.64675 -272.14957)
		(width 0.088646)
		(layer "In11.Cu")
		(net "M_D_CPU1_SA_DQS_DP<7>")
	)
	(arc
		(start 89.382346 -272.14957)
		(mid 89.195148 -272.199713)
		(end 89.00795 -272.14957)
		(width 0.088646)
		(layer "In11.Cu")
		(net "M_D_CPU1_SA_DQS_DP<7>")
	)
	(arc
		(start 96.900746 -272.14957)
		(mid 96.713548 -272.199713)
		(end 96.52635 -272.14957)
		(width 0.088646)
		(layer "In11.Cu")
		(net "M_D_CPU1_SA_DQS_DP<7>")
	)
	(arc
		(start 92.201746 -272.14957)
		(mid 92.014548 -272.199713)
		(end 91.82735 -272.14957)
		(width 0.088646)
		(layer "In11.Cu")
		(net "M_D_CPU1_SA_DQS_DP<7>")
	)
	(arc
		(start 85.622892 -272.14957)
		(mid 85.435694 -272.199713)
		(end 85.248496 -272.14957)
		(width 0.088646)
		(layer "In11.Cu")
		(net "M_D_CPU1_SA_DQS_DP<7>")
	)
	(arc
		(start 87.502492 -272.14957)
		(mid 87.315294 -272.199713)
		(end 87.128096 -272.14957)
		(width 0.088646)
		(layer "In11.Cu")
		(net "M_D_CPU1_SA_DQS_DP<7>")
	)
	(arc
		(start 95.960946 -272.14957)
		(mid 95.773748 -272.199713)
		(end 95.58655 -272.14957)
		(width 0.088646)
		(layer "In11.Cu")
		(net "M_D_CPU1_SA_DQS_DP<7>")
	)
	(arc
		(start 88.442292 -272.14957)
		(mid 88.255094 -272.199713)
		(end 88.067896 -272.14957)
		(width 0.088646)
		(layer "In11.Cu")
		(net "M_D_CPU1_SA_DQS_DP<7>")
	)
	(arc
		(start 99.720146 -272.14957)
		(mid 99.532948 -272.199713)
		(end 99.34575 -272.14957)
		(width 0.088646)
		(layer "In11.Cu")
		(net "M_D_CPU1_SA_DQS_DP<7>")
	)
	(arc
		(start 94.081346 -272.14957)
		(mid 93.894148 -272.199713)
		(end 93.70695 -272.14957)
		(width 0.088646)
		(layer "In11.Cu")
		(net "M_D_CPU1_SA_DQS_DP<7>")
	)
	(arc
		(start 90.872564 -272.140934)
		(mid 90.596123 -272.073768)
		(end 90.321892 -272.14957)
		(width 0.088646)
		(layer "In11.Cu")
		(net "M_D_CPU1_SA_DQS_DP<7>")
	)
	(arc
		(start 100.564442 -272.574004)
		(mid 100.563147 -272.563323)
		(end 100.561648 -272.552668)
		(width 0.088646)
		(layer "In11.Cu")
		(net "M_D_CPU1_SA_DQS_DP<7>")
	)
	(arc
		(start 100.561648 -272.552668)
		(mid 100.25479 -272.132882)
		(end 99.734878 -272.140934)
		(width 0.088646)
		(layer "In11.Cu")
		(net "M_D_CPU1_SA_DQS_DP<7>")
	)
	(arc
		(start 98.40595 -272.14957)
		(mid 98.129137 -272.073734)
		(end 97.850706 -272.143474)
		(width 0.088646)
		(layer "In11.Cu")
		(net "M_D_CPU1_SA_DQS_DP<7>")
	)
	(arc
		(start 85.248496 -272.14957)
		(mid 85.112253 -272.093124)
		(end 84.966048 -272.073878)
		(width 0.088646)
		(layer "In11.Cu")
		(net "M_D_CPU1_SA_DQS_DP<7>")
	)
	(arc
		(start 93.141546 -272.14957)
		(mid 92.954348 -272.199713)
		(end 92.76715 -272.14957)
		(width 0.088646)
		(layer "In11.Cu")
		(net "M_D_CPU1_SA_DQS_DP<7>")
	)
	(arc
		(start 94.64675 -272.14957)
		(mid 94.372521 -272.073645)
		(end 94.096078 -272.140934)
		(width 0.088646)
		(layer "In11.Cu")
		(net "M_D_CPU1_SA_DQS_DP<7>")
	)
	(arc
		(start 98.780346 -272.14957)
		(mid 98.593148 -272.199713)
		(end 98.40595 -272.14957)
		(width 0.088646)
		(layer "In11.Cu")
		(net "M_D_CPU1_SA_DQS_DP<7>")
	)
	(segment
		(start 19.294348 -301.866808)
		(end 19.033236 -302.12792)
		(width 0.20066)
		(layer "F.Cu")
		(net "M_D_CPU1_SA_DQS_DP<6>")
	)
	(segment
		(start 19.033236 -302.12792)
		(end 18.428716 -302.12792)
		(width 0.20066)
		(layer "F.Cu")
		(net "M_D_CPU1_SA_DQS_DP<6>")
	)
	(segment
		(start 17.7927 -301.702978)
		(end 17.287748 -301.702978)
		(width 0.20066)
		(layer "F.Cu")
		(net "M_D_CPU1_SA_DQS_DP<6>")
	)
	(segment
		(start 17.026636 -301.441866)
		(end 16.885158 -301.441866)
		(width 0.20066)
		(layer "F.Cu")
		(net "M_D_CPU1_SA_DQS_DP<6>")
	)
	(segment
		(start 18.428716 -302.12792)
		(end 17.7927 -301.702978)
		(width 0.20066)
		(layer "F.Cu")
		(net "M_D_CPU1_SA_DQS_DP<6>")
	)
	(segment
		(start 13.733018 -301.705518)
		(end 13.310616 -302.12792)
		(width 0.20066)
		(layer "F.Cu")
		(net "M_D_CPU1_SA_DQS_DP<6>")
	)
	(segment
		(start 16.885158 -301.441866)
		(end 14.806676 -301.441866)
		(width 0.1016)
		(layer "F.Cu")
		(net "M_D_CPU1_SA_DQS_DP<6>")
	)
	(segment
		(start 12.976352 -302.12792)
		(end 12.71524 -301.866808)
		(width 0.20066)
		(layer "F.Cu")
		(net "M_D_CPU1_SA_DQS_DP<6>")
	)
	(segment
		(start 20.889214 -301.866808)
		(end 19.784314 -301.866808)
		(width 0.20066)
		(layer "F.Cu")
		(net "M_D_CPU1_SA_DQS_DP<6>")
	)
	(segment
		(start 17.287748 -301.702978)
		(end 17.026636 -301.441866)
		(width 0.20066)
		(layer "F.Cu")
		(net "M_D_CPU1_SA_DQS_DP<6>")
	)
	(segment
		(start 12.71524 -301.866808)
		(end 12.240514 -301.866808)
		(width 0.20066)
		(layer "F.Cu")
		(net "M_D_CPU1_SA_DQS_DP<6>")
	)
	(segment
		(start 19.784314 -301.866808)
		(end 19.294348 -301.866808)
		(width 0.20066)
		(layer "F.Cu")
		(net "M_D_CPU1_SA_DQS_DP<6>")
	)
	(segment
		(start 14.362684 -301.436024)
		(end 14.09319 -301.705518)
		(width 0.20066)
		(layer "F.Cu")
		(net "M_D_CPU1_SA_DQS_DP<6>")
	)
	(segment
		(start 14.09319 -301.705518)
		(end 13.733018 -301.705518)
		(width 0.20066)
		(layer "F.Cu")
		(net "M_D_CPU1_SA_DQS_DP<6>")
	)
	(segment
		(start 14.806676 -301.441866)
		(end 14.565884 -301.441866)
		(width 0.101854)
		(layer "F.Cu")
		(net "M_D_CPU1_SA_DQS_DP<6>")
	)
	(segment
		(start 14.565884 -301.441866)
		(end 14.560042 -301.436024)
		(width 0.101854)
		(layer "F.Cu")
		(net "M_D_CPU1_SA_DQS_DP<6>")
	)
	(segment
		(start 14.560042 -301.436024)
		(end 14.362684 -301.436024)
		(width 0.20066)
		(layer "F.Cu")
		(net "M_D_CPU1_SA_DQS_DP<6>")
	)
	(segment
		(start 13.310616 -302.12792)
		(end 12.976352 -302.12792)
		(width 0.20066)
		(layer "F.Cu")
		(net "M_D_CPU1_SA_DQS_DP<6>")
	)
	(arc
		(start 100.942648 -276.986492)
		(mid 100.942584 -277.254462)
		(end 100.942394 -277.522432)
		(width 0.20066)
		(layer "F.Cu")
		(net "M_D_CPU1_SA_DQS_DP<6>")
	)
	(segment
		(start 47.43196 -307.669692)
		(end 47.153322 -307.391054)
		(width 0.18288)
		(layer "In11.Cu")
		(net "M_D_CPU1_SA_DQS_DP<6>")
	)
	(segment
		(start 50.873914 -306.540916)
		(end 50.620676 -306.794154)
		(width 0.18288)
		(layer "In11.Cu")
		(net "M_D_CPU1_SA_DQS_DP<6>")
	)
	(segment
		(start 34.896806 -306.818792)
		(end 34.054542 -307.661056)
		(width 0.18288)
		(layer "In11.Cu")
		(net "M_D_CPU1_SA_DQS_DP<6>")
	)
	(segment
		(start 93.156278 -277.024338)
		(end 93.141546 -277.032974)
		(width 0.088646)
		(layer "In11.Cu")
		(net "M_D_CPU1_SA_DQS_DP<6>")
	)
	(segment
		(start 85.576918 -278.85009)
		(end 84.43214 -279.994868)
		(width 0.088646)
		(layer "In11.Cu")
		(net "M_D_CPU1_SA_DQS_DP<6>")
	)
	(segment
		(start 65.371726 -299.18279)
		(end 64.566038 -299.988478)
		(width 0.18288)
		(layer "In11.Cu")
		(net "M_D_CPU1_SA_DQS_DP<6>")
	)
	(segment
		(start 26.004266 -304.388266)
		(end 25.485852 -304.173382)
		(width 0.18288)
		(layer "In11.Cu")
		(net "M_D_CPU1_SA_DQS_DP<6>")
	)
	(segment
		(start 34.054542 -307.661056)
		(end 32.33674 -307.661056)
		(width 0.18288)
		(layer "In11.Cu")
		(net "M_D_CPU1_SA_DQS_DP<6>")
	)
	(segment
		(start 59.446922 -301.050706)
		(end 58.662062 -301.835566)
		(width 0.18288)
		(layer "In11.Cu")
		(net "M_D_CPU1_SA_DQS_DP<6>")
	)
	(segment
		(start 84.43214 -280.185876)
		(end 83.630008 -280.988008)
		(width 0.088646)
		(layer "In11.Cu")
		(net "M_D_CPU1_SA_DQS_DP<6>")
	)
	(segment
		(start 52.45481 -306.832)
		(end 51.585622 -306.832)
		(width 0.18288)
		(layer "In11.Cu")
		(net "M_D_CPU1_SA_DQS_DP<6>")
	)
	(segment
		(start 98.795078 -277.024338)
		(end 98.780346 -277.032974)
		(width 0.088646)
		(layer "In11.Cu")
		(net "M_D_CPU1_SA_DQS_DP<6>")
	)
	(segment
		(start 66.616834 -299.16628)
		(end 66.345562 -298.895008)
		(width 0.18288)
		(layer "In11.Cu")
		(net "M_D_CPU1_SA_DQS_DP<6>")
	)
	(segment
		(start 46.47057 -307.688234)
		(end 45.75175 -307.688234)
		(width 0.18288)
		(layer "In11.Cu")
		(net "M_D_CPU1_SA_DQS_DP<6>")
	)
	(segment
		(start 60.742068 -300.036738)
		(end 59.7281 -301.050706)
		(width 0.18288)
		(layer "In11.Cu")
		(net "M_D_CPU1_SA_DQS_DP<6>")
	)
	(segment
		(start 24.697944 -303.385728)
		(end 22.682708 -302.550068)
		(width 0.18288)
		(layer "In11.Cu")
		(net "M_D_CPU1_SA_DQS_DP<6>")
	)
	(segment
		(start 22.04593 -302.550068)
		(end 21.641308 -302.145446)
		(width 0.18288)
		(layer "In11.Cu")
		(net "M_D_CPU1_SA_DQS_DP<6>")
	)
	(segment
		(start 97.850706 -277.026878)
		(end 97.840292 -277.032974)
		(width 0.088646)
		(layer "In11.Cu")
		(net "M_D_CPU1_SA_DQS_DP<6>")
	)
	(segment
		(start 91.272106 -277.026878)
		(end 91.261692 -277.032974)
		(width 0.088646)
		(layer "In11.Cu")
		(net "M_D_CPU1_SA_DQS_DP<6>")
	)
	(segment
		(start 51.163982 -306.54244)
		(end 51.162458 -306.540916)
		(width 0.18288)
		(layer "In11.Cu")
		(net "M_D_CPU1_SA_DQS_DP<6>")
	)
	(segment
		(start 32.33674 -307.661056)
		(end 32.066738 -307.391054)
		(width 0.18288)
		(layer "In11.Cu")
		(net "M_D_CPU1_SA_DQS_DP<6>")
	)
	(segment
		(start 84.43214 -279.994868)
		(end 84.43214 -280.185876)
		(width 0.088646)
		(layer "In11.Cu")
		(net "M_D_CPU1_SA_DQS_DP<6>")
	)
	(segment
		(start 22.682708 -302.550068)
		(end 22.04593 -302.550068)
		(width 0.18288)
		(layer "In11.Cu")
		(net "M_D_CPU1_SA_DQS_DP<6>")
	)
	(segment
		(start 31.686246 -307.391054)
		(end 31.429452 -307.647848)
		(width 0.18288)
		(layer "In11.Cu")
		(net "M_D_CPU1_SA_DQS_DP<6>")
	)
	(segment
		(start 31.429452 -307.647848)
		(end 30.715204 -307.647848)
		(width 0.18288)
		(layer "In11.Cu")
		(net "M_D_CPU1_SA_DQS_DP<6>")
	)
	(segment
		(start 83.630008 -280.988008)
		(end 83.545934 -280.988008)
		(width 0.088646)
		(layer "In11.Cu")
		(net "M_D_CPU1_SA_DQS_DP<6>")
	)
	(segment
		(start 71.954136 -291.71011)
		(end 71.954136 -292.44925)
		(width 0.18288)
		(layer "In11.Cu")
		(net "M_D_CPU1_SA_DQS_DP<6>")
	)
	(segment
		(start 54.357524 -304.929286)
		(end 52.45481 -306.832)
		(width 0.18288)
		(layer "In11.Cu")
		(net "M_D_CPU1_SA_DQS_DP<6>")
	)
	(segment
		(start 61.830458 -299.741082)
		(end 61.534802 -300.036738)
		(width 0.18288)
		(layer "In11.Cu")
		(net "M_D_CPU1_SA_DQS_DP<6>")
	)
	(segment
		(start 30.088586 -308.274466)
		(end 29.585158 -308.274466)
		(width 0.18288)
		(layer "In11.Cu")
		(net "M_D_CPU1_SA_DQS_DP<6>")
	)
	(segment
		(start 44.388532 -307.012086)
		(end 43.761152 -307.639466)
		(width 0.18288)
		(layer "In11.Cu")
		(net "M_D_CPU1_SA_DQS_DP<6>")
	)
	(segment
		(start 25.485852 -304.173382)
		(end 24.697944 -303.385728)
		(width 0.18288)
		(layer "In11.Cu")
		(net "M_D_CPU1_SA_DQS_DP<6>")
	)
	(segment
		(start 59.7281 -301.050706)
		(end 59.446922 -301.050706)
		(width 0.18288)
		(layer "In11.Cu")
		(net "M_D_CPU1_SA_DQS_DP<6>")
	)
	(segment
		(start 68.232274 -297.937936)
		(end 67.00393 -299.16628)
		(width 0.18288)
		(layer "In11.Cu")
		(net "M_D_CPU1_SA_DQS_DP<6>")
	)
	(segment
		(start 95.975678 -277.024338)
		(end 95.960946 -277.032974)
		(width 0.088646)
		(layer "In11.Cu")
		(net "M_D_CPU1_SA_DQS_DP<6>")
	)
	(segment
		(start 83.419696 -281.114246)
		(end 82.55 -281.114246)
		(width 0.18288)
		(layer "In11.Cu")
		(net "M_D_CPU1_SA_DQS_DP<6>")
	)
	(segment
		(start 35.501326 -306.818792)
		(end 34.896806 -306.818792)
		(width 0.18288)
		(layer "In11.Cu")
		(net "M_D_CPU1_SA_DQS_DP<6>")
	)
	(segment
		(start 94.096078 -277.024338)
		(end 94.081346 -277.032974)
		(width 0.088646)
		(layer "In11.Cu")
		(net "M_D_CPU1_SA_DQS_DP<6>")
	)
	(segment
		(start 39.786814 -306.803298)
		(end 36.444936 -306.803298)
		(width 0.18288)
		(layer "In11.Cu")
		(net "M_D_CPU1_SA_DQS_DP<6>")
	)
	(segment
		(start 47.153322 -307.391054)
		(end 46.76775 -307.391054)
		(width 0.18288)
		(layer "In11.Cu")
		(net "M_D_CPU1_SA_DQS_DP<6>")
	)
	(segment
		(start 88.457024 -277.024338)
		(end 88.442292 -277.032974)
		(width 0.088646)
		(layer "In11.Cu")
		(net "M_D_CPU1_SA_DQS_DP<6>")
	)
	(segment
		(start 99.734878 -277.024338)
		(end 99.720146 -277.032974)
		(width 0.088646)
		(layer "In11.Cu")
		(net "M_D_CPU1_SA_DQS_DP<6>")
	)
	(segment
		(start 90.887296 -277.032974)
		(end 90.872564 -277.024338)
		(width 0.088646)
		(layer "In11.Cu")
		(net "M_D_CPU1_SA_DQS_DP<6>")
	)
	(segment
		(start 36.182554 -306.540916)
		(end 35.779202 -306.540916)
		(width 0.18288)
		(layer "In11.Cu")
		(net "M_D_CPU1_SA_DQS_DP<6>")
	)
	(segment
		(start 95.035878 -277.024338)
		(end 95.021146 -277.032974)
		(width 0.088646)
		(layer "In11.Cu")
		(net "M_D_CPU1_SA_DQS_DP<6>")
	)
	(segment
		(start 68.232274 -296.171112)
		(end 68.232274 -297.937936)
		(width 0.18288)
		(layer "In11.Cu")
		(net "M_D_CPU1_SA_DQS_DP<6>")
	)
	(segment
		(start 36.444936 -306.803298)
		(end 36.182554 -306.540916)
		(width 0.18288)
		(layer "In11.Cu")
		(net "M_D_CPU1_SA_DQS_DP<6>")
	)
	(segment
		(start 86.095078 -277.741634)
		(end 85.576918 -278.259794)
		(width 0.088646)
		(layer "In11.Cu")
		(net "M_D_CPU1_SA_DQS_DP<6>")
	)
	(segment
		(start 27.959558 -306.998878)
		(end 27.959558 -305.682142)
		(width 0.18288)
		(layer "In11.Cu")
		(net "M_D_CPU1_SA_DQS_DP<6>")
	)
	(segment
		(start 28.167584 -307.500528)
		(end 27.959558 -306.998878)
		(width 0.18288)
		(layer "In11.Cu")
		(net "M_D_CPU1_SA_DQS_DP<6>")
	)
	(segment
		(start 54.913022 -304.929286)
		(end 54.357524 -304.929286)
		(width 0.18288)
		(layer "In11.Cu")
		(net "M_D_CPU1_SA_DQS_DP<6>")
	)
	(segment
		(start 67.00393 -299.16628)
		(end 66.616834 -299.16628)
		(width 0.18288)
		(layer "In11.Cu")
		(net "M_D_CPU1_SA_DQS_DP<6>")
	)
	(segment
		(start 62.32271 -299.741082)
		(end 61.830458 -299.741082)
		(width 0.18288)
		(layer "In11.Cu")
		(net "M_D_CPU1_SA_DQS_DP<6>")
	)
	(segment
		(start 86.913212 -277.741634)
		(end 86.095078 -277.741634)
		(width 0.088646)
		(layer "In11.Cu")
		(net "M_D_CPU1_SA_DQS_DP<6>")
	)
	(segment
		(start 65.962022 -298.895008)
		(end 65.67424 -299.18279)
		(width 0.18288)
		(layer "In11.Cu")
		(net "M_D_CPU1_SA_DQS_DP<6>")
	)
	(segment
		(start 28.486354 -307.819044)
		(end 28.167584 -307.500528)
		(width 0.18288)
		(layer "In11.Cu")
		(net "M_D_CPU1_SA_DQS_DP<6>")
	)
	(segment
		(start 51.585622 -306.832)
		(end 51.296062 -306.54244)
		(width 0.18288)
		(layer "In11.Cu")
		(net "M_D_CPU1_SA_DQS_DP<6>")
	)
	(segment
		(start 100.942394 -277.522432)
		(end 100.62972 -277.522432)
		(width 0.088646)
		(layer "In11.Cu")
		(net "M_D_CPU1_SA_DQS_DP<6>")
	)
	(segment
		(start 100.62972 -277.522432)
		(end 100.564188 -277.4569)
		(width 0.088646)
		(layer "In11.Cu")
		(net "M_D_CPU1_SA_DQS_DP<6>")
	)
	(segment
		(start 45.75175 -307.688234)
		(end 45.075602 -307.012086)
		(width 0.18288)
		(layer "In11.Cu")
		(net "M_D_CPU1_SA_DQS_DP<6>")
	)
	(segment
		(start 71.954136 -292.44925)
		(end 68.232274 -296.171112)
		(width 0.18288)
		(layer "In11.Cu")
		(net "M_D_CPU1_SA_DQS_DP<6>")
	)
	(segment
		(start 51.296062 -306.54244)
		(end 51.163982 -306.54244)
		(width 0.18288)
		(layer "In11.Cu")
		(net "M_D_CPU1_SA_DQS_DP<6>")
	)
	(segment
		(start 58.662062 -301.835566)
		(end 57.07253 -301.835566)
		(width 0.18288)
		(layer "In11.Cu")
		(net "M_D_CPU1_SA_DQS_DP<6>")
	)
	(segment
		(start 83.545934 -280.988008)
		(end 83.419696 -281.114246)
		(width 0.18288)
		(layer "In11.Cu")
		(net "M_D_CPU1_SA_DQS_DP<6>")
	)
	(segment
		(start 50.620676 -306.794154)
		(end 49.848516 -306.794154)
		(width 0.18288)
		(layer "In11.Cu")
		(net "M_D_CPU1_SA_DQS_DP<6>")
	)
	(segment
		(start 55.55742 -303.350676)
		(end 55.55742 -304.284888)
		(width 0.18288)
		(layer "In11.Cu")
		(net "M_D_CPU1_SA_DQS_DP<6>")
	)
	(segment
		(start 27.959558 -305.682142)
		(end 26.665682 -304.388266)
		(width 0.18288)
		(layer "In11.Cu")
		(net "M_D_CPU1_SA_DQS_DP<6>")
	)
	(segment
		(start 55.55742 -304.284888)
		(end 54.913022 -304.929286)
		(width 0.18288)
		(layer "In11.Cu")
		(net "M_D_CPU1_SA_DQS_DP<6>")
	)
	(segment
		(start 48.972978 -307.669692)
		(end 47.43196 -307.669692)
		(width 0.18288)
		(layer "In11.Cu")
		(net "M_D_CPU1_SA_DQS_DP<6>")
	)
	(segment
		(start 49.848516 -306.794154)
		(end 48.972978 -307.669692)
		(width 0.18288)
		(layer "In11.Cu")
		(net "M_D_CPU1_SA_DQS_DP<6>")
	)
	(segment
		(start 96.91116 -277.026878)
		(end 96.900746 -277.032974)
		(width 0.088646)
		(layer "In11.Cu")
		(net "M_D_CPU1_SA_DQS_DP<6>")
	)
	(segment
		(start 29.585158 -308.274466)
		(end 28.486354 -307.819044)
		(width 0.18288)
		(layer "In11.Cu")
		(net "M_D_CPU1_SA_DQS_DP<6>")
	)
	(segment
		(start 30.715204 -307.647848)
		(end 30.088586 -308.274466)
		(width 0.18288)
		(layer "In11.Cu")
		(net "M_D_CPU1_SA_DQS_DP<6>")
	)
	(segment
		(start 43.761152 -307.639466)
		(end 40.622982 -307.639466)
		(width 0.18288)
		(layer "In11.Cu")
		(net "M_D_CPU1_SA_DQS_DP<6>")
	)
	(segment
		(start 64.566038 -299.988478)
		(end 62.570106 -299.988478)
		(width 0.18288)
		(layer "In11.Cu")
		(net "M_D_CPU1_SA_DQS_DP<6>")
	)
	(segment
		(start 46.76775 -307.391054)
		(end 46.47057 -307.688234)
		(width 0.18288)
		(layer "In11.Cu")
		(net "M_D_CPU1_SA_DQS_DP<6>")
	)
	(segment
		(start 51.162458 -306.540916)
		(end 50.873914 -306.540916)
		(width 0.18288)
		(layer "In11.Cu")
		(net "M_D_CPU1_SA_DQS_DP<6>")
	)
	(segment
		(start 92.216478 -277.024338)
		(end 92.201746 -277.032974)
		(width 0.088646)
		(layer "In11.Cu")
		(net "M_D_CPU1_SA_DQS_DP<6>")
	)
	(segment
		(start 45.075602 -307.012086)
		(end 44.388532 -307.012086)
		(width 0.18288)
		(layer "In11.Cu")
		(net "M_D_CPU1_SA_DQS_DP<6>")
	)
	(segment
		(start 61.534802 -300.036738)
		(end 60.742068 -300.036738)
		(width 0.18288)
		(layer "In11.Cu")
		(net "M_D_CPU1_SA_DQS_DP<6>")
	)
	(segment
		(start 65.67424 -299.18279)
		(end 65.371726 -299.18279)
		(width 0.18288)
		(layer "In11.Cu")
		(net "M_D_CPU1_SA_DQS_DP<6>")
	)
	(segment
		(start 85.576918 -278.259794)
		(end 85.576918 -278.85009)
		(width 0.088646)
		(layer "In11.Cu")
		(net "M_D_CPU1_SA_DQS_DP<6>")
	)
	(segment
		(start 21.641308 -302.145446)
		(end 21.167852 -302.145446)
		(width 0.18288)
		(layer "In11.Cu")
		(net "M_D_CPU1_SA_DQS_DP<6>")
	)
	(segment
		(start 32.066738 -307.391054)
		(end 31.686246 -307.391054)
		(width 0.18288)
		(layer "In11.Cu")
		(net "M_D_CPU1_SA_DQS_DP<6>")
	)
	(segment
		(start 35.779202 -306.540916)
		(end 35.501326 -306.818792)
		(width 0.18288)
		(layer "In11.Cu")
		(net "M_D_CPU1_SA_DQS_DP<6>")
	)
	(segment
		(start 82.55 -281.114246)
		(end 71.954136 -291.71011)
		(width 0.18288)
		(layer "In11.Cu")
		(net "M_D_CPU1_SA_DQS_DP<6>")
	)
	(segment
		(start 88.101424 -277.17877)
		(end 87.607394 -277.50897)
		(width 0.088646)
		(layer "In11.Cu")
		(net "M_D_CPU1_SA_DQS_DP<6>")
	)
	(segment
		(start 40.622982 -307.639466)
		(end 39.786814 -306.803298)
		(width 0.18288)
		(layer "In11.Cu")
		(net "M_D_CPU1_SA_DQS_DP<6>")
	)
	(segment
		(start 57.07253 -301.835566)
		(end 55.55742 -303.350676)
		(width 0.18288)
		(layer "In11.Cu")
		(net "M_D_CPU1_SA_DQS_DP<6>")
	)
	(segment
		(start 26.665682 -304.388266)
		(end 26.004266 -304.388266)
		(width 0.18288)
		(layer "In11.Cu")
		(net "M_D_CPU1_SA_DQS_DP<6>")
	)
	(segment
		(start 62.570106 -299.988478)
		(end 62.32271 -299.741082)
		(width 0.18288)
		(layer "In11.Cu")
		(net "M_D_CPU1_SA_DQS_DP<6>")
	)
	(segment
		(start 21.167852 -302.145446)
		(end 20.889214 -301.866808)
		(width 0.18288)
		(layer "In11.Cu")
		(net "M_D_CPU1_SA_DQS_DP<6>")
	)
	(segment
		(start 66.345562 -298.895008)
		(end 65.962022 -298.895008)
		(width 0.18288)
		(layer "In11.Cu")
		(net "M_D_CPU1_SA_DQS_DP<6>")
	)
	(arc
		(start 91.261692 -277.032974)
		(mid 91.074494 -277.083117)
		(end 90.887296 -277.032974)
		(width 0.088646)
		(layer "In11.Cu")
		(net "M_D_CPU1_SA_DQS_DP<6>")
	)
	(arc
		(start 100.564188 -277.4569)
		(mid 100.56289 -277.446346)
		(end 100.561394 -277.435818)
		(width 0.088646)
		(layer "In11.Cu")
		(net "M_D_CPU1_SA_DQS_DP<6>")
	)
	(arc
		(start 89.382092 -277.032974)
		(mid 89.194894 -277.083117)
		(end 89.007696 -277.032974)
		(width 0.088646)
		(layer "In11.Cu")
		(net "M_D_CPU1_SA_DQS_DP<6>")
	)
	(arc
		(start 95.58655 -277.032974)
		(mid 95.312351 -276.957139)
		(end 95.035878 -277.024338)
		(width 0.088646)
		(layer "In11.Cu")
		(net "M_D_CPU1_SA_DQS_DP<6>")
	)
	(arc
		(start 98.780346 -277.032974)
		(mid 98.593148 -277.083117)
		(end 98.40595 -277.032974)
		(width 0.088646)
		(layer "In11.Cu")
		(net "M_D_CPU1_SA_DQS_DP<6>")
	)
	(arc
		(start 94.081346 -277.032974)
		(mid 93.894148 -277.083117)
		(end 93.70695 -277.032974)
		(width 0.088646)
		(layer "In11.Cu")
		(net "M_D_CPU1_SA_DQS_DP<6>")
	)
	(arc
		(start 95.021146 -277.032974)
		(mid 94.833948 -277.083117)
		(end 94.64675 -277.032974)
		(width 0.088646)
		(layer "In11.Cu")
		(net "M_D_CPU1_SA_DQS_DP<6>")
	)
	(arc
		(start 92.76715 -277.032974)
		(mid 92.492951 -276.957139)
		(end 92.216478 -277.024338)
		(width 0.088646)
		(layer "In11.Cu")
		(net "M_D_CPU1_SA_DQS_DP<6>")
	)
	(arc
		(start 97.840292 -277.032974)
		(mid 97.653094 -277.083117)
		(end 97.465896 -277.032974)
		(width 0.088646)
		(layer "In11.Cu")
		(net "M_D_CPU1_SA_DQS_DP<6>")
	)
	(arc
		(start 99.34575 -277.032974)
		(mid 99.071551 -276.957139)
		(end 98.795078 -277.024338)
		(width 0.088646)
		(layer "In11.Cu")
		(net "M_D_CPU1_SA_DQS_DP<6>")
	)
	(arc
		(start 88.442292 -277.032974)
		(mid 88.394063 -277.056466)
		(end 88.342978 -277.072852)
		(width 0.088646)
		(layer "In11.Cu")
		(net "M_D_CPU1_SA_DQS_DP<6>")
	)
	(arc
		(start 90.321892 -277.032974)
		(mid 90.134694 -277.083117)
		(end 89.947496 -277.032974)
		(width 0.088646)
		(layer "In11.Cu")
		(net "M_D_CPU1_SA_DQS_DP<6>")
	)
	(arc
		(start 96.52635 -277.032974)
		(mid 96.252151 -276.957139)
		(end 95.975678 -277.024338)
		(width 0.088646)
		(layer "In11.Cu")
		(net "M_D_CPU1_SA_DQS_DP<6>")
	)
	(arc
		(start 95.960946 -277.032974)
		(mid 95.773748 -277.083117)
		(end 95.58655 -277.032974)
		(width 0.088646)
		(layer "In11.Cu")
		(net "M_D_CPU1_SA_DQS_DP<6>")
	)
	(arc
		(start 87.607394 -277.50897)
		(mid 87.587001 -277.522577)
		(end 87.566754 -277.536402)
		(width 0.088646)
		(layer "In11.Cu")
		(net "M_D_CPU1_SA_DQS_DP<6>")
	)
	(arc
		(start 89.007696 -277.032974)
		(mid 88.733467 -276.957049)
		(end 88.457024 -277.024338)
		(width 0.088646)
		(layer "In11.Cu")
		(net "M_D_CPU1_SA_DQS_DP<6>")
	)
	(arc
		(start 90.872564 -277.024338)
		(mid 90.596089 -276.957018)
		(end 90.321892 -277.032974)
		(width 0.088646)
		(layer "In11.Cu")
		(net "M_D_CPU1_SA_DQS_DP<6>")
	)
	(arc
		(start 92.201746 -277.032974)
		(mid 92.014548 -277.083117)
		(end 91.82735 -277.032974)
		(width 0.088646)
		(layer "In11.Cu")
		(net "M_D_CPU1_SA_DQS_DP<6>")
	)
	(arc
		(start 93.141546 -277.032974)
		(mid 92.954348 -277.083117)
		(end 92.76715 -277.032974)
		(width 0.088646)
		(layer "In11.Cu")
		(net "M_D_CPU1_SA_DQS_DP<6>")
	)
	(arc
		(start 99.720146 -277.032974)
		(mid 99.532948 -277.083117)
		(end 99.34575 -277.032974)
		(width 0.088646)
		(layer "In11.Cu")
		(net "M_D_CPU1_SA_DQS_DP<6>")
	)
	(arc
		(start 89.947496 -277.032974)
		(mid 89.664794 -276.957198)
		(end 89.382092 -277.032974)
		(width 0.088646)
		(layer "In11.Cu")
		(net "M_D_CPU1_SA_DQS_DP<6>")
	)
	(arc
		(start 88.342978 -277.072852)
		(mid 88.217543 -277.115187)
		(end 88.101424 -277.17877)
		(width 0.088646)
		(layer "In11.Cu")
		(net "M_D_CPU1_SA_DQS_DP<6>")
	)
	(arc
		(start 100.28555 -277.032974)
		(mid 100.011351 -276.957139)
		(end 99.734878 -277.024338)
		(width 0.088646)
		(layer "In11.Cu")
		(net "M_D_CPU1_SA_DQS_DP<6>")
	)
	(arc
		(start 91.82735 -277.032974)
		(mid 91.550537 -276.957104)
		(end 91.272106 -277.026878)
		(width 0.088646)
		(layer "In11.Cu")
		(net "M_D_CPU1_SA_DQS_DP<6>")
	)
	(arc
		(start 93.70695 -277.032974)
		(mid 93.432751 -276.957139)
		(end 93.156278 -277.024338)
		(width 0.088646)
		(layer "In11.Cu")
		(net "M_D_CPU1_SA_DQS_DP<6>")
	)
	(arc
		(start 96.900746 -277.032974)
		(mid 96.713548 -277.083117)
		(end 96.52635 -277.032974)
		(width 0.088646)
		(layer "In11.Cu")
		(net "M_D_CPU1_SA_DQS_DP<6>")
	)
	(arc
		(start 87.566754 -277.536402)
		(mid 87.255715 -277.689111)
		(end 86.913212 -277.741634)
		(width 0.088646)
		(layer "In11.Cu")
		(net "M_D_CPU1_SA_DQS_DP<6>")
	)
	(arc
		(start 97.465896 -277.032974)
		(mid 97.189337 -276.957231)
		(end 96.91116 -277.026878)
		(width 0.088646)
		(layer "In11.Cu")
		(net "M_D_CPU1_SA_DQS_DP<6>")
	)
	(arc
		(start 100.561394 -277.435818)
		(mid 100.469233 -277.203046)
		(end 100.28555 -277.032974)
		(width 0.088646)
		(layer "In11.Cu")
		(net "M_D_CPU1_SA_DQS_DP<6>")
	)
	(arc
		(start 98.40595 -277.032974)
		(mid 98.129137 -276.957104)
		(end 97.850706 -277.026878)
		(width 0.088646)
		(layer "In11.Cu")
		(net "M_D_CPU1_SA_DQS_DP<6>")
	)
	(arc
		(start 94.64675 -277.032974)
		(mid 94.372551 -276.957139)
		(end 94.096078 -277.024338)
		(width 0.088646)
		(layer "In11.Cu")
		(net "M_D_CPU1_SA_DQS_DP<6>")
	)
	(segment
		(start 14.362684 -310.786018)
		(end 14.09319 -311.055512)
		(width 0.20066)
		(layer "F.Cu")
		(net "M_D_CPU1_SA_DQS_DP<5>")
	)
	(segment
		(start 20.889214 -311.216802)
		(end 19.784314 -311.216802)
		(width 0.20066)
		(layer "F.Cu")
		(net "M_D_CPU1_SA_DQS_DP<5>")
	)
	(segment
		(start 17.026636 -310.79186)
		(end 16.885158 -310.79186)
		(width 0.20066)
		(layer "F.Cu")
		(net "M_D_CPU1_SA_DQS_DP<5>")
	)
	(segment
		(start 14.806676 -310.79186)
		(end 14.565884 -310.79186)
		(width 0.101854)
		(layer "F.Cu")
		(net "M_D_CPU1_SA_DQS_DP<5>")
	)
	(segment
		(start 19.294348 -311.216802)
		(end 19.033236 -311.477914)
		(width 0.20066)
		(layer "F.Cu")
		(net "M_D_CPU1_SA_DQS_DP<5>")
	)
	(segment
		(start 14.565884 -310.79186)
		(end 14.560042 -310.786018)
		(width 0.101854)
		(layer "F.Cu")
		(net "M_D_CPU1_SA_DQS_DP<5>")
	)
	(segment
		(start 13.310616 -311.477914)
		(end 12.976352 -311.477914)
		(width 0.20066)
		(layer "F.Cu")
		(net "M_D_CPU1_SA_DQS_DP<5>")
	)
	(segment
		(start 12.976352 -311.477914)
		(end 12.71524 -311.216802)
		(width 0.20066)
		(layer "F.Cu")
		(net "M_D_CPU1_SA_DQS_DP<5>")
	)
	(segment
		(start 19.784314 -311.216802)
		(end 19.294348 -311.216802)
		(width 0.20066)
		(layer "F.Cu")
		(net "M_D_CPU1_SA_DQS_DP<5>")
	)
	(segment
		(start 18.428716 -311.477914)
		(end 17.7927 -311.052972)
		(width 0.20066)
		(layer "F.Cu")
		(net "M_D_CPU1_SA_DQS_DP<5>")
	)
	(segment
		(start 16.885158 -310.79186)
		(end 14.806676 -310.79186)
		(width 0.1016)
		(layer "F.Cu")
		(net "M_D_CPU1_SA_DQS_DP<5>")
	)
	(segment
		(start 14.560042 -310.786018)
		(end 14.362684 -310.786018)
		(width 0.20066)
		(layer "F.Cu")
		(net "M_D_CPU1_SA_DQS_DP<5>")
	)
	(segment
		(start 13.733018 -311.055512)
		(end 13.310616 -311.477914)
		(width 0.20066)
		(layer "F.Cu")
		(net "M_D_CPU1_SA_DQS_DP<5>")
	)
	(segment
		(start 17.7927 -311.052972)
		(end 17.287748 -311.052972)
		(width 0.20066)
		(layer "F.Cu")
		(net "M_D_CPU1_SA_DQS_DP<5>")
	)
	(segment
		(start 12.71524 -311.216802)
		(end 12.240514 -311.216802)
		(width 0.20066)
		(layer "F.Cu")
		(net "M_D_CPU1_SA_DQS_DP<5>")
	)
	(segment
		(start 17.287748 -311.052972)
		(end 17.026636 -310.79186)
		(width 0.20066)
		(layer "F.Cu")
		(net "M_D_CPU1_SA_DQS_DP<5>")
	)
	(segment
		(start 19.033236 -311.477914)
		(end 18.428716 -311.477914)
		(width 0.20066)
		(layer "F.Cu")
		(net "M_D_CPU1_SA_DQS_DP<5>")
	)
	(segment
		(start 14.09319 -311.055512)
		(end 13.733018 -311.055512)
		(width 0.20066)
		(layer "F.Cu")
		(net "M_D_CPU1_SA_DQS_DP<5>")
	)
	(arc
		(start 96.713294 -274.54479)
		(mid 96.713357 -274.81276)
		(end 96.713548 -275.08073)
		(width 0.20066)
		(layer "F.Cu")
		(net "M_D_CPU1_SA_DQS_DP<5>")
	)
	(segment
		(start 85.207348 -277.421086)
		(end 85.207348 -277.833074)
		(width 0.088646)
		(layer "In6.Cu")
		(net "M_D_CPU1_SA_DQS_DP<5>")
	)
	(segment
		(start 78.374748 -283.673042)
		(end 78.374748 -283.849064)
		(width 0.18288)
		(layer "In6.Cu")
		(net "M_D_CPU1_SA_DQS_DP<5>")
	)
	(segment
		(start 74.178922 -288.04489)
		(end 74.0029 -288.04489)
		(width 0.18288)
		(layer "In6.Cu")
		(net "M_D_CPU1_SA_DQS_DP<5>")
	)
	(segment
		(start 77.034898 -285.188914)
		(end 76.858876 -285.188914)
		(width 0.18288)
		(layer "In6.Cu")
		(net "M_D_CPU1_SA_DQS_DP<5>")
	)
	(segment
		(start 32.08274 -310.79186)
		(end 31.678118 -310.79186)
		(width 0.18288)
		(layer "In6.Cu")
		(net "M_D_CPU1_SA_DQS_DP<5>")
	)
	(segment
		(start 74.56678 -287.657032)
		(end 74.178922 -288.04489)
		(width 0.18288)
		(layer "In6.Cu")
		(net "M_D_CPU1_SA_DQS_DP<5>")
	)
	(segment
		(start 57.77103 -301.281592)
		(end 56.767476 -302.285146)
		(width 0.18288)
		(layer "In6.Cu")
		(net "M_D_CPU1_SA_DQS_DP<5>")
	)
	(segment
		(start 81.230724 -280.993088)
		(end 80.842866 -281.380946)
		(width 0.18288)
		(layer "In6.Cu")
		(net "M_D_CPU1_SA_DQS_DP<5>")
	)
	(segment
		(start 73.614788 -288.433002)
		(end 73.614788 -288.609024)
		(width 0.18288)
		(layer "In6.Cu")
		(net "M_D_CPU1_SA_DQS_DP<5>")
	)
	(segment
		(start 57.77103 -300.763686)
		(end 57.77103 -301.281592)
		(width 0.18288)
		(layer "In6.Cu")
		(net "M_D_CPU1_SA_DQS_DP<5>")
	)
	(segment
		(start 61.592968 -297.73372)
		(end 60.201048 -299.12564)
		(width 0.18288)
		(layer "In6.Cu")
		(net "M_D_CPU1_SA_DQS_DP<5>")
	)
	(segment
		(start 75.130914 -287.092898)
		(end 74.954892 -287.092898)
		(width 0.18288)
		(layer "In6.Cu")
		(net "M_D_CPU1_SA_DQS_DP<5>")
	)
	(segment
		(start 75.518772 -286.70504)
		(end 75.130914 -287.092898)
		(width 0.18288)
		(layer "In6.Cu")
		(net "M_D_CPU1_SA_DQS_DP<5>")
	)
	(segment
		(start 94.176596 -274.591272)
		(end 94.161864 -274.582636)
		(width 0.088646)
		(layer "In6.Cu")
		(net "M_D_CPU1_SA_DQS_DP<5>")
	)
	(segment
		(start 68.057776 -294.16629)
		(end 68.057776 -294.76827)
		(width 0.18288)
		(layer "In6.Cu")
		(net "M_D_CPU1_SA_DQS_DP<5>")
	)
	(segment
		(start 81.230724 -280.817066)
		(end 81.230724 -280.993088)
		(width 0.18288)
		(layer "In6.Cu")
		(net "M_D_CPU1_SA_DQS_DP<5>")
	)
	(segment
		(start 35.227514 -312.741056)
		(end 34.13379 -311.647332)
		(width 0.18288)
		(layer "In6.Cu")
		(net "M_D_CPU1_SA_DQS_DP<5>")
	)
	(segment
		(start 31.678118 -310.79186)
		(end 31.4071 -311.062878)
		(width 0.18288)
		(layer "In6.Cu")
		(net "M_D_CPU1_SA_DQS_DP<5>")
	)
	(segment
		(start 29.104844 -310.45531)
		(end 28.487116 -311.073038)
		(width 0.18288)
		(layer "In6.Cu")
		(net "M_D_CPU1_SA_DQS_DP<5>")
	)
	(segment
		(start 30.781244 -311.073292)
		(end 30.163262 -310.45531)
		(width 0.18288)
		(layer "In6.Cu")
		(net "M_D_CPU1_SA_DQS_DP<5>")
	)
	(segment
		(start 83.57997 -279.856692)
		(end 83.520026 -279.796748)
		(width 0.088646)
		(layer "In6.Cu")
		(net "M_D_CPU1_SA_DQS_DP<5>")
	)
	(segment
		(start 24.468074 -311.737756)
		(end 21.914866 -311.737756)
		(width 0.18288)
		(layer "In6.Cu")
		(net "M_D_CPU1_SA_DQS_DP<5>")
	)
	(segment
		(start 82.182716 -280.041096)
		(end 81.794858 -280.428954)
		(width 0.18288)
		(layer "In6.Cu")
		(net "M_D_CPU1_SA_DQS_DP<5>")
	)
	(segment
		(start 56.767476 -302.285146)
		(end 56.38165 -302.285146)
		(width 0.18288)
		(layer "In6.Cu")
		(net "M_D_CPU1_SA_DQS_DP<5>")
	)
	(segment
		(start 51.602894 -305.10226)
		(end 51.34229 -304.841656)
		(width 0.18288)
		(layer "In6.Cu")
		(net "M_D_CPU1_SA_DQS_DP<5>")
	)
	(segment
		(start 68.057776 -294.76827)
		(end 66.116454 -296.709592)
		(width 0.18288)
		(layer "In6.Cu")
		(net "M_D_CPU1_SA_DQS_DP<5>")
	)
	(segment
		(start 26.072846 -311.073038)
		(end 24.468074 -311.737756)
		(width 0.18288)
		(layer "In6.Cu")
		(net "M_D_CPU1_SA_DQS_DP<5>")
	)
	(segment
		(start 56.38165 -302.285146)
		(end 55.097934 -303.568862)
		(width 0.18288)
		(layer "In6.Cu")
		(net "M_D_CPU1_SA_DQS_DP<5>")
	)
	(segment
		(start 79.714852 -282.332938)
		(end 79.32674 -282.72105)
		(width 0.18288)
		(layer "In6.Cu")
		(net "M_D_CPU1_SA_DQS_DP<5>")
	)
	(segment
		(start 31.40202 -311.062878)
		(end 31.391606 -311.073292)
		(width 0.18288)
		(layer "In6.Cu")
		(net "M_D_CPU1_SA_DQS_DP<5>")
	)
	(segment
		(start 74.0029 -288.04489)
		(end 73.614788 -288.433002)
		(width 0.18288)
		(layer "In6.Cu")
		(net "M_D_CPU1_SA_DQS_DP<5>")
	)
	(segment
		(start 72.662796 -289.561016)
		(end 72.274938 -289.948874)
		(width 0.18288)
		(layer "In6.Cu")
		(net "M_D_CPU1_SA_DQS_DP<5>")
	)
	(segment
		(start 72.098916 -289.948874)
		(end 71.710804 -290.336986)
		(width 0.18288)
		(layer "In6.Cu")
		(net "M_D_CPU1_SA_DQS_DP<5>")
	)
	(segment
		(start 71.322946 -290.900866)
		(end 71.146924 -290.900866)
		(width 0.18288)
		(layer "In6.Cu")
		(net "M_D_CPU1_SA_DQS_DP<5>")
	)
	(segment
		(start 96.713548 -275.08073)
		(end 96.71304 -275.08073)
		(width 0.088646)
		(layer "In6.Cu")
		(net "M_D_CPU1_SA_DQS_DP<5>")
	)
	(segment
		(start 47.63643 -307.652166)
		(end 47.502826 -307.652166)
		(width 0.18288)
		(layer "In6.Cu")
		(net "M_D_CPU1_SA_DQS_DP<5>")
	)
	(segment
		(start 77.810868 -284.236922)
		(end 77.422756 -284.625034)
		(width 0.18288)
		(layer "In6.Cu")
		(net "M_D_CPU1_SA_DQS_DP<5>")
	)
	(segment
		(start 71.146924 -290.900866)
		(end 70.758812 -291.288978)
		(width 0.18288)
		(layer "In6.Cu")
		(net "M_D_CPU1_SA_DQS_DP<5>")
	)
	(segment
		(start 58.577734 -299.956982)
		(end 57.77103 -300.763686)
		(width 0.18288)
		(layer "In6.Cu")
		(net "M_D_CPU1_SA_DQS_DP<5>")
	)
	(segment
		(start 72.274938 -289.948874)
		(end 72.098916 -289.948874)
		(width 0.18288)
		(layer "In6.Cu")
		(net "M_D_CPU1_SA_DQS_DP<5>")
	)
	(segment
		(start 35.754056 -312.491628)
		(end 35.504628 -312.741056)
		(width 0.18288)
		(layer "In6.Cu")
		(net "M_D_CPU1_SA_DQS_DP<5>")
	)
	(segment
		(start 95.116396 -274.591272)
		(end 95.101664 -274.582636)
		(width 0.088646)
		(layer "In6.Cu")
		(net "M_D_CPU1_SA_DQS_DP<5>")
	)
	(segment
		(start 76.470764 -285.577026)
		(end 76.470764 -285.753048)
		(width 0.18288)
		(layer "In6.Cu")
		(net "M_D_CPU1_SA_DQS_DP<5>")
	)
	(segment
		(start 88.921082 -276.214078)
		(end 88.912192 -276.219158)
		(width 0.088646)
		(layer "In6.Cu")
		(net "M_D_CPU1_SA_DQS_DP<5>")
	)
	(segment
		(start 80.278732 -281.94508)
		(end 79.890874 -282.332938)
		(width 0.18288)
		(layer "In6.Cu")
		(net "M_D_CPU1_SA_DQS_DP<5>")
	)
	(segment
		(start 74.954892 -287.092898)
		(end 74.56678 -287.48101)
		(width 0.18288)
		(layer "In6.Cu")
		(net "M_D_CPU1_SA_DQS_DP<5>")
	)
	(segment
		(start 31.391606 -311.073292)
		(end 30.781244 -311.073292)
		(width 0.18288)
		(layer "In6.Cu")
		(net "M_D_CPU1_SA_DQS_DP<5>")
	)
	(segment
		(start 89.390982 -275.400008)
		(end 89.382854 -275.40458)
		(width 0.088646)
		(layer "In6.Cu")
		(net "M_D_CPU1_SA_DQS_DP<5>")
	)
	(segment
		(start 50.06721 -305.091084)
		(end 49.318672 -305.839622)
		(width 0.18288)
		(layer "In6.Cu")
		(net "M_D_CPU1_SA_DQS_DP<5>")
	)
	(segment
		(start 88.537796 -276.219158)
		(end 88.527382 -276.213062)
		(width 0.088646)
		(layer "In6.Cu")
		(net "M_D_CPU1_SA_DQS_DP<5>")
	)
	(segment
		(start 84.099654 -279.620218)
		(end 83.86318 -279.856692)
		(width 0.088646)
		(layer "In6.Cu")
		(net "M_D_CPU1_SA_DQS_DP<5>")
	)
	(segment
		(start 43.439588 -309.60822)
		(end 42.996612 -309.60822)
		(width 0.18288)
		(layer "In6.Cu")
		(net "M_D_CPU1_SA_DQS_DP<5>")
	)
	(segment
		(start 44.769532 -308.278276)
		(end 43.439588 -309.60822)
		(width 0.18288)
		(layer "In6.Cu")
		(net "M_D_CPU1_SA_DQS_DP<5>")
	)
	(segment
		(start 76.082906 -286.140906)
		(end 75.906884 -286.140906)
		(width 0.18288)
		(layer "In6.Cu")
		(net "M_D_CPU1_SA_DQS_DP<5>")
	)
	(segment
		(start 84.099654 -278.940768)
		(end 84.099654 -279.620218)
		(width 0.088646)
		(layer "In6.Cu")
		(net "M_D_CPU1_SA_DQS_DP<5>")
	)
	(segment
		(start 32.34309 -311.05221)
		(end 32.08274 -310.79186)
		(width 0.18288)
		(layer "In6.Cu")
		(net "M_D_CPU1_SA_DQS_DP<5>")
	)
	(segment
		(start 91.35745 -274.591272)
		(end 91.347036 -274.585176)
		(width 0.088646)
		(layer "In6.Cu")
		(net "M_D_CPU1_SA_DQS_DP<5>")
	)
	(segment
		(start 86.750144 -276.693122)
		(end 86.750144 -276.708616)
		(width 0.088646)
		(layer "In6.Cu")
		(net "M_D_CPU1_SA_DQS_DP<5>")
	)
	(segment
		(start 30.163262 -310.45531)
		(end 29.104844 -310.45531)
		(width 0.18288)
		(layer "In6.Cu")
		(net "M_D_CPU1_SA_DQS_DP<5>")
	)
	(segment
		(start 79.32674 -282.72105)
		(end 79.32674 -282.897072)
		(width 0.18288)
		(layer "In6.Cu")
		(net "M_D_CPU1_SA_DQS_DP<5>")
	)
	(segment
		(start 89.099644 -275.876258)
		(end 89.099644 -275.8948)
		(width 0.088646)
		(layer "In6.Cu")
		(net "M_D_CPU1_SA_DQS_DP<5>")
	)
	(segment
		(start 63.504826 -298.138088)
		(end 63.100458 -297.73372)
		(width 0.18288)
		(layer "In6.Cu")
		(net "M_D_CPU1_SA_DQS_DP<5>")
	)
	(segment
		(start 36.453318 -312.752232)
		(end 36.192714 -312.491628)
		(width 0.18288)
		(layer "In6.Cu")
		(net "M_D_CPU1_SA_DQS_DP<5>")
	)
	(segment
		(start 80.278732 -281.769058)
		(end 80.278732 -281.94508)
		(width 0.18288)
		(layer "In6.Cu")
		(net "M_D_CPU1_SA_DQS_DP<5>")
	)
	(segment
		(start 48.853598 -305.839622)
		(end 47.964852 -306.728368)
		(width 0.18288)
		(layer "In6.Cu")
		(net "M_D_CPU1_SA_DQS_DP<5>")
	)
	(segment
		(start 42.996612 -309.60822)
		(end 41.74363 -310.860948)
		(width 0.18288)
		(layer "In6.Cu")
		(net "M_D_CPU1_SA_DQS_DP<5>")
	)
	(segment
		(start 78.76286 -283.28493)
		(end 78.374748 -283.673042)
		(width 0.18288)
		(layer "In6.Cu")
		(net "M_D_CPU1_SA_DQS_DP<5>")
	)
	(segment
		(start 46.741334 -307.391816)
		(end 46.481746 -307.651404)
		(width 0.18288)
		(layer "In6.Cu")
		(net "M_D_CPU1_SA_DQS_DP<5>")
	)
	(segment
		(start 58.838846 -299.956982)
		(end 58.577734 -299.956982)
		(width 0.18288)
		(layer "In6.Cu")
		(net "M_D_CPU1_SA_DQS_DP<5>")
	)
	(segment
		(start 80.666844 -281.380946)
		(end 80.278732 -281.769058)
		(width 0.18288)
		(layer "In6.Cu")
		(net "M_D_CPU1_SA_DQS_DP<5>")
	)
	(segment
		(start 47.242476 -307.391816)
		(end 46.741334 -307.391816)
		(width 0.18288)
		(layer "In6.Cu")
		(net "M_D_CPU1_SA_DQS_DP<5>")
	)
	(segment
		(start 59.670188 -299.12564)
		(end 58.838846 -299.956982)
		(width 0.18288)
		(layer "In6.Cu")
		(net "M_D_CPU1_SA_DQS_DP<5>")
	)
	(segment
		(start 96.057212 -274.59178)
		(end 96.056196 -274.591272)
		(width 0.088646)
		(layer "In6.Cu")
		(net "M_D_CPU1_SA_DQS_DP<5>")
	)
	(segment
		(start 28.487116 -311.073038)
		(end 26.072846 -311.073038)
		(width 0.18288)
		(layer "In6.Cu")
		(net "M_D_CPU1_SA_DQS_DP<5>")
	)
	(segment
		(start 21.914866 -311.737756)
		(end 21.6535 -311.47639)
		(width 0.18288)
		(layer "In6.Cu")
		(net "M_D_CPU1_SA_DQS_DP<5>")
	)
	(segment
		(start 83.86318 -279.856692)
		(end 83.57997 -279.856692)
		(width 0.088646)
		(layer "In6.Cu")
		(net "M_D_CPU1_SA_DQS_DP<5>")
	)
	(segment
		(start 50.592228 -305.091084)
		(end 50.06721 -305.091084)
		(width 0.18288)
		(layer "In6.Cu")
		(net "M_D_CPU1_SA_DQS_DP<5>")
	)
	(segment
		(start 93.236796 -274.591272)
		(end 93.222064 -274.582636)
		(width 0.088646)
		(layer "In6.Cu")
		(net "M_D_CPU1_SA_DQS_DP<5>")
	)
	(segment
		(start 51.34229 -304.841656)
		(end 50.841656 -304.841656)
		(width 0.18288)
		(layer "In6.Cu")
		(net "M_D_CPU1_SA_DQS_DP<5>")
	)
	(segment
		(start 77.422756 -284.801056)
		(end 77.034898 -285.188914)
		(width 0.18288)
		(layer "In6.Cu")
		(net "M_D_CPU1_SA_DQS_DP<5>")
	)
	(segment
		(start 79.890874 -282.332938)
		(end 79.714852 -282.332938)
		(width 0.18288)
		(layer "In6.Cu")
		(net "M_D_CPU1_SA_DQS_DP<5>")
	)
	(segment
		(start 65.787016 -296.709592)
		(end 64.35852 -298.138088)
		(width 0.18288)
		(layer "In6.Cu")
		(net "M_D_CPU1_SA_DQS_DP<5>")
	)
	(segment
		(start 82.773012 -279.796748)
		(end 82.182716 -280.041096)
		(width 0.18288)
		(layer "In6.Cu")
		(net "M_D_CPU1_SA_DQS_DP<5>")
	)
	(segment
		(start 79.32674 -282.897072)
		(end 78.938882 -283.28493)
		(width 0.18288)
		(layer "In6.Cu")
		(net "M_D_CPU1_SA_DQS_DP<5>")
	)
	(segment
		(start 45.907706 -307.651404)
		(end 45.280834 -308.278276)
		(width 0.18288)
		(layer "In6.Cu")
		(net "M_D_CPU1_SA_DQS_DP<5>")
	)
	(segment
		(start 76.858876 -285.188914)
		(end 76.470764 -285.577026)
		(width 0.18288)
		(layer "In6.Cu")
		(net "M_D_CPU1_SA_DQS_DP<5>")
	)
	(segment
		(start 41.74363 -310.860948)
		(end 37.179504 -312.752232)
		(width 0.18288)
		(layer "In6.Cu")
		(net "M_D_CPU1_SA_DQS_DP<5>")
	)
	(segment
		(start 76.470764 -285.753048)
		(end 76.082906 -286.140906)
		(width 0.18288)
		(layer "In6.Cu")
		(net "M_D_CPU1_SA_DQS_DP<5>")
	)
	(segment
		(start 46.481746 -307.651404)
		(end 45.907706 -307.651404)
		(width 0.18288)
		(layer "In6.Cu")
		(net "M_D_CPU1_SA_DQS_DP<5>")
	)
	(segment
		(start 85.207348 -277.833074)
		(end 84.099654 -278.940768)
		(width 0.088646)
		(layer "In6.Cu")
		(net "M_D_CPU1_SA_DQS_DP<5>")
	)
	(segment
		(start 21.148802 -311.47639)
		(end 20.889214 -311.216802)
		(width 0.18288)
		(layer "In6.Cu")
		(net "M_D_CPU1_SA_DQS_DP<5>")
	)
	(segment
		(start 80.842866 -281.380946)
		(end 80.666844 -281.380946)
		(width 0.18288)
		(layer "In6.Cu")
		(net "M_D_CPU1_SA_DQS_DP<5>")
	)
	(segment
		(start 96.433894 -274.809966)
		(end 96.060768 -274.594066)
		(width 0.088646)
		(layer "In6.Cu")
		(net "M_D_CPU1_SA_DQS_DP<5>")
	)
	(segment
		(start 73.614788 -288.609024)
		(end 73.22693 -288.996882)
		(width 0.18288)
		(layer "In6.Cu")
		(net "M_D_CPU1_SA_DQS_DP<5>")
	)
	(segment
		(start 96.060768 -274.594066)
		(end 96.058482 -274.592542)
		(width 0.088646)
		(layer "In6.Cu")
		(net "M_D_CPU1_SA_DQS_DP<5>")
	)
	(segment
		(start 35.504628 -312.741056)
		(end 35.227514 -312.741056)
		(width 0.18288)
		(layer "In6.Cu")
		(net "M_D_CPU1_SA_DQS_DP<5>")
	)
	(segment
		(start 70.758812 -291.465)
		(end 68.057776 -294.16629)
		(width 0.18288)
		(layer "In6.Cu")
		(net "M_D_CPU1_SA_DQS_DP<5>")
	)
	(segment
		(start 45.280834 -308.278276)
		(end 44.769532 -308.278276)
		(width 0.18288)
		(layer "In6.Cu")
		(net "M_D_CPU1_SA_DQS_DP<5>")
	)
	(segment
		(start 64.35852 -298.138088)
		(end 63.504826 -298.138088)
		(width 0.18288)
		(layer "In6.Cu")
		(net "M_D_CPU1_SA_DQS_DP<5>")
	)
	(segment
		(start 96.056196 -274.591272)
		(end 96.041464 -274.582636)
		(width 0.088646)
		(layer "In6.Cu")
		(net "M_D_CPU1_SA_DQS_DP<5>")
	)
	(segment
		(start 75.518772 -286.529018)
		(end 75.518772 -286.70504)
		(width 0.18288)
		(layer "In6.Cu")
		(net "M_D_CPU1_SA_DQS_DP<5>")
	)
	(segment
		(start 89.569544 -275.070824)
		(end 89.569544 -275.08073)
		(width 0.088646)
		(layer "In6.Cu")
		(net "M_D_CPU1_SA_DQS_DP<5>")
	)
	(segment
		(start 63.100458 -297.73372)
		(end 61.592968 -297.73372)
		(width 0.18288)
		(layer "In6.Cu")
		(net "M_D_CPU1_SA_DQS_DP<5>")
	)
	(segment
		(start 47.964852 -306.728368)
		(end 47.965614 -307.322982)
		(width 0.18288)
		(layer "In6.Cu")
		(net "M_D_CPU1_SA_DQS_DP<5>")
	)
	(segment
		(start 55.097934 -303.568862)
		(end 54.003702 -303.568862)
		(width 0.18288)
		(layer "In6.Cu")
		(net "M_D_CPU1_SA_DQS_DP<5>")
	)
	(segment
		(start 37.179504 -312.752232)
		(end 36.453318 -312.752232)
		(width 0.18288)
		(layer "In6.Cu")
		(net "M_D_CPU1_SA_DQS_DP<5>")
	)
	(segment
		(start 86.571582 -277.027894)
		(end 86.562692 -277.032974)
		(width 0.088646)
		(layer "In6.Cu")
		(net "M_D_CPU1_SA_DQS_DP<5>")
	)
	(segment
		(start 89.382854 -275.40458)
		(end 89.382092 -275.405088)
		(width 0.088646)
		(layer "In6.Cu")
		(net "M_D_CPU1_SA_DQS_DP<5>")
	)
	(segment
		(start 32.696658 -311.05221)
		(end 32.34309 -311.05221)
		(width 0.18288)
		(layer "In6.Cu")
		(net "M_D_CPU1_SA_DQS_DP<5>")
	)
	(segment
		(start 50.841656 -304.841656)
		(end 50.592228 -305.091084)
		(width 0.18288)
		(layer "In6.Cu")
		(net "M_D_CPU1_SA_DQS_DP<5>")
	)
	(segment
		(start 77.422756 -284.625034)
		(end 77.422756 -284.801056)
		(width 0.18288)
		(layer "In6.Cu")
		(net "M_D_CPU1_SA_DQS_DP<5>")
	)
	(segment
		(start 75.906884 -286.140906)
		(end 75.518772 -286.529018)
		(width 0.18288)
		(layer "In6.Cu")
		(net "M_D_CPU1_SA_DQS_DP<5>")
	)
	(segment
		(start 81.794858 -280.428954)
		(end 81.618836 -280.428954)
		(width 0.18288)
		(layer "In6.Cu")
		(net "M_D_CPU1_SA_DQS_DP<5>")
	)
	(segment
		(start 47.502826 -307.652166)
		(end 47.242476 -307.391816)
		(width 0.18288)
		(layer "In6.Cu")
		(net "M_D_CPU1_SA_DQS_DP<5>")
	)
	(segment
		(start 52.470304 -305.10226)
		(end 51.602894 -305.10226)
		(width 0.18288)
		(layer "In6.Cu")
		(net "M_D_CPU1_SA_DQS_DP<5>")
	)
	(segment
		(start 71.710804 -290.336986)
		(end 71.710804 -290.513008)
		(width 0.18288)
		(layer "In6.Cu")
		(net "M_D_CPU1_SA_DQS_DP<5>")
	)
	(segment
		(start 77.98689 -284.236922)
		(end 77.810868 -284.236922)
		(width 0.18288)
		(layer "In6.Cu")
		(net "M_D_CPU1_SA_DQS_DP<5>")
	)
	(segment
		(start 78.374748 -283.849064)
		(end 77.98689 -284.236922)
		(width 0.18288)
		(layer "In6.Cu")
		(net "M_D_CPU1_SA_DQS_DP<5>")
	)
	(segment
		(start 66.116454 -296.709592)
		(end 65.787016 -296.709592)
		(width 0.18288)
		(layer "In6.Cu")
		(net "M_D_CPU1_SA_DQS_DP<5>")
	)
	(segment
		(start 21.6535 -311.47639)
		(end 21.148802 -311.47639)
		(width 0.18288)
		(layer "In6.Cu")
		(net "M_D_CPU1_SA_DQS_DP<5>")
	)
	(segment
		(start 47.965614 -307.322982)
		(end 47.63643 -307.652166)
		(width 0.18288)
		(layer "In6.Cu")
		(net "M_D_CPU1_SA_DQS_DP<5>")
	)
	(segment
		(start 96.71304 -275.08073)
		(end 96.433894 -274.809966)
		(width 0.088646)
		(layer "In6.Cu")
		(net "M_D_CPU1_SA_DQS_DP<5>")
	)
	(segment
		(start 36.192714 -312.491628)
		(end 35.754056 -312.491628)
		(width 0.18288)
		(layer "In6.Cu")
		(net "M_D_CPU1_SA_DQS_DP<5>")
	)
	(segment
		(start 71.710804 -290.513008)
		(end 71.322946 -290.900866)
		(width 0.18288)
		(layer "In6.Cu")
		(net "M_D_CPU1_SA_DQS_DP<5>")
	)
	(segment
		(start 81.618836 -280.428954)
		(end 81.230724 -280.817066)
		(width 0.18288)
		(layer "In6.Cu")
		(net "M_D_CPU1_SA_DQS_DP<5>")
	)
	(segment
		(start 34.13379 -311.647332)
		(end 32.696658 -311.05221)
		(width 0.18288)
		(layer "In6.Cu")
		(net "M_D_CPU1_SA_DQS_DP<5>")
	)
	(segment
		(start 85.505798 -277.122382)
		(end 85.207348 -277.421086)
		(width 0.088646)
		(layer "In6.Cu")
		(net "M_D_CPU1_SA_DQS_DP<5>")
	)
	(segment
		(start 78.938882 -283.28493)
		(end 78.76286 -283.28493)
		(width 0.18288)
		(layer "In6.Cu")
		(net "M_D_CPU1_SA_DQS_DP<5>")
	)
	(segment
		(start 87.597742 -276.219158)
		(end 87.58301 -276.210522)
		(width 0.088646)
		(layer "In6.Cu")
		(net "M_D_CPU1_SA_DQS_DP<5>")
	)
	(segment
		(start 96.058482 -274.592542)
		(end 96.057212 -274.59178)
		(width 0.088646)
		(layer "In6.Cu")
		(net "M_D_CPU1_SA_DQS_DP<5>")
	)
	(segment
		(start 73.050908 -288.996882)
		(end 72.662796 -289.384994)
		(width 0.18288)
		(layer "In6.Cu")
		(net "M_D_CPU1_SA_DQS_DP<5>")
	)
	(segment
		(start 60.201048 -299.12564)
		(end 59.670188 -299.12564)
		(width 0.18288)
		(layer "In6.Cu")
		(net "M_D_CPU1_SA_DQS_DP<5>")
	)
	(segment
		(start 70.758812 -291.288978)
		(end 70.758812 -291.465)
		(width 0.18288)
		(layer "In6.Cu")
		(net "M_D_CPU1_SA_DQS_DP<5>")
	)
	(segment
		(start 83.520026 -279.796748)
		(end 83.496658 -279.796748)
		(width 0.088646)
		(layer "In6.Cu")
		(net "M_D_CPU1_SA_DQS_DP<5>")
	)
	(segment
		(start 83.496658 -279.796748)
		(end 82.773012 -279.796748)
		(width 0.18288)
		(layer "In6.Cu")
		(net "M_D_CPU1_SA_DQS_DP<5>")
	)
	(segment
		(start 49.318672 -305.839622)
		(end 48.853598 -305.839622)
		(width 0.18288)
		(layer "In6.Cu")
		(net "M_D_CPU1_SA_DQS_DP<5>")
	)
	(segment
		(start 74.56678 -287.48101)
		(end 74.56678 -287.657032)
		(width 0.18288)
		(layer "In6.Cu")
		(net "M_D_CPU1_SA_DQS_DP<5>")
	)
	(segment
		(start 91.74226 -274.585176)
		(end 91.731846 -274.591272)
		(width 0.088646)
		(layer "In6.Cu")
		(net "M_D_CPU1_SA_DQS_DP<5>")
	)
	(segment
		(start 73.22693 -288.996882)
		(end 73.050908 -288.996882)
		(width 0.18288)
		(layer "In6.Cu")
		(net "M_D_CPU1_SA_DQS_DP<5>")
	)
	(segment
		(start 31.4071 -311.062878)
		(end 31.40202 -311.062878)
		(width 0.18288)
		(layer "In6.Cu")
		(net "M_D_CPU1_SA_DQS_DP<5>")
	)
	(segment
		(start 54.003702 -303.568862)
		(end 52.470304 -305.10226)
		(width 0.18288)
		(layer "In6.Cu")
		(net "M_D_CPU1_SA_DQS_DP<5>")
	)
	(segment
		(start 72.662796 -289.384994)
		(end 72.662796 -289.561016)
		(width 0.18288)
		(layer "In6.Cu")
		(net "M_D_CPU1_SA_DQS_DP<5>")
	)
	(arc
		(start 86.750144 -276.708616)
		(mid 86.702465 -276.891516)
		(end 86.571582 -277.027894)
		(width 0.088646)
		(layer "In6.Cu")
		(net "M_D_CPU1_SA_DQS_DP<5>")
	)
	(arc
		(start 90.791792 -274.591272)
		(mid 90.604594 -274.641415)
		(end 90.417396 -274.591272)
		(width 0.088646)
		(layer "In6.Cu")
		(net "M_D_CPU1_SA_DQS_DP<5>")
	)
	(arc
		(start 88.527382 -276.213062)
		(mid 88.24895 -276.143216)
		(end 87.972138 -276.219158)
		(width 0.088646)
		(layer "In6.Cu")
		(net "M_D_CPU1_SA_DQS_DP<5>")
	)
	(arc
		(start 92.296996 -274.591272)
		(mid 92.020437 -274.515529)
		(end 91.74226 -274.585176)
		(width 0.088646)
		(layer "In6.Cu")
		(net "M_D_CPU1_SA_DQS_DP<5>")
	)
	(arc
		(start 87.032338 -276.219158)
		(mid 86.829515 -276.419389)
		(end 86.750144 -276.693122)
		(width 0.088646)
		(layer "In6.Cu")
		(net "M_D_CPU1_SA_DQS_DP<5>")
	)
	(arc
		(start 89.382092 -275.405088)
		(mid 89.179806 -275.604069)
		(end 89.099644 -275.876258)
		(width 0.088646)
		(layer "In6.Cu")
		(net "M_D_CPU1_SA_DQS_DP<5>")
	)
	(arc
		(start 93.611192 -274.591272)
		(mid 93.423994 -274.641415)
		(end 93.236796 -274.591272)
		(width 0.088646)
		(layer "In6.Cu")
		(net "M_D_CPU1_SA_DQS_DP<5>")
	)
	(arc
		(start 85.529928 -277.099776)
		(mid 85.517696 -277.110901)
		(end 85.505798 -277.122382)
		(width 0.088646)
		(layer "In6.Cu")
		(net "M_D_CPU1_SA_DQS_DP<5>")
	)
	(arc
		(start 87.58301 -276.210522)
		(mid 87.306535 -276.143202)
		(end 87.032338 -276.219158)
		(width 0.088646)
		(layer "In6.Cu")
		(net "M_D_CPU1_SA_DQS_DP<5>")
	)
	(arc
		(start 87.972138 -276.219158)
		(mid 87.78494 -276.269301)
		(end 87.597742 -276.219158)
		(width 0.088646)
		(layer "In6.Cu")
		(net "M_D_CPU1_SA_DQS_DP<5>")
	)
	(arc
		(start 95.101664 -274.582636)
		(mid 94.825189 -274.515316)
		(end 94.550992 -274.591272)
		(width 0.088646)
		(layer "In6.Cu")
		(net "M_D_CPU1_SA_DQS_DP<5>")
	)
	(arc
		(start 86.188296 -277.032974)
		(mid 85.848304 -276.959988)
		(end 85.529928 -277.099776)
		(width 0.088646)
		(layer "In6.Cu")
		(net "M_D_CPU1_SA_DQS_DP<5>")
	)
	(arc
		(start 91.347036 -274.585176)
		(mid 91.068604 -274.51533)
		(end 90.791792 -274.591272)
		(width 0.088646)
		(layer "In6.Cu")
		(net "M_D_CPU1_SA_DQS_DP<5>")
	)
	(arc
		(start 89.851992 -274.591272)
		(mid 89.647657 -274.793877)
		(end 89.569544 -275.070824)
		(width 0.088646)
		(layer "In6.Cu")
		(net "M_D_CPU1_SA_DQS_DP<5>")
	)
	(arc
		(start 95.490792 -274.591272)
		(mid 95.303594 -274.641415)
		(end 95.116396 -274.591272)
		(width 0.088646)
		(layer "In6.Cu")
		(net "M_D_CPU1_SA_DQS_DP<5>")
	)
	(arc
		(start 93.222064 -274.582636)
		(mid 92.945589 -274.515316)
		(end 92.671392 -274.591272)
		(width 0.088646)
		(layer "In6.Cu")
		(net "M_D_CPU1_SA_DQS_DP<5>")
	)
	(arc
		(start 89.569544 -275.08073)
		(mid 89.521865 -275.26363)
		(end 89.390982 -275.400008)
		(width 0.088646)
		(layer "In6.Cu")
		(net "M_D_CPU1_SA_DQS_DP<5>")
	)
	(arc
		(start 90.417396 -274.591272)
		(mid 90.134694 -274.515496)
		(end 89.851992 -274.591272)
		(width 0.088646)
		(layer "In6.Cu")
		(net "M_D_CPU1_SA_DQS_DP<5>")
	)
	(arc
		(start 88.912192 -276.219158)
		(mid 88.724994 -276.269301)
		(end 88.537796 -276.219158)
		(width 0.088646)
		(layer "In6.Cu")
		(net "M_D_CPU1_SA_DQS_DP<5>")
	)
	(arc
		(start 96.041464 -274.582636)
		(mid 95.764989 -274.515316)
		(end 95.490792 -274.591272)
		(width 0.088646)
		(layer "In6.Cu")
		(net "M_D_CPU1_SA_DQS_DP<5>")
	)
	(arc
		(start 92.671392 -274.591272)
		(mid 92.484194 -274.641415)
		(end 92.296996 -274.591272)
		(width 0.088646)
		(layer "In6.Cu")
		(net "M_D_CPU1_SA_DQS_DP<5>")
	)
	(arc
		(start 94.550992 -274.591272)
		(mid 94.363794 -274.641415)
		(end 94.176596 -274.591272)
		(width 0.088646)
		(layer "In6.Cu")
		(net "M_D_CPU1_SA_DQS_DP<5>")
	)
	(arc
		(start 89.099644 -275.8948)
		(mid 89.051965 -276.0777)
		(end 88.921082 -276.214078)
		(width 0.088646)
		(layer "In6.Cu")
		(net "M_D_CPU1_SA_DQS_DP<5>")
	)
	(arc
		(start 94.161864 -274.582636)
		(mid 93.885389 -274.515316)
		(end 93.611192 -274.591272)
		(width 0.088646)
		(layer "In6.Cu")
		(net "M_D_CPU1_SA_DQS_DP<5>")
	)
	(arc
		(start 91.731846 -274.591272)
		(mid 91.544648 -274.641415)
		(end 91.35745 -274.591272)
		(width 0.088646)
		(layer "In6.Cu")
		(net "M_D_CPU1_SA_DQS_DP<5>")
	)
	(arc
		(start 86.562692 -277.032974)
		(mid 86.375494 -277.083117)
		(end 86.188296 -277.032974)
		(width 0.088646)
		(layer "In6.Cu")
		(net "M_D_CPU1_SA_DQS_DP<5>")
	)
	(segment
		(start 11.36269 -275.94179)
		(end 11.125708 -275.94179)
		(width 0.101854)
		(layer "F.Cu")
		(net "M_D_CPU1_SA_DQS_DP<4>")
	)
	(segment
		(start 13.593572 -275.94179)
		(end 13.441426 -275.94179)
		(width 0.20066)
		(layer "F.Cu")
		(net "M_D_CPU1_SA_DQS_DP<4>")
	)
	(segment
		(start 10.627614 -275.680678)
		(end 10.000488 -275.680678)
		(width 0.20066)
		(layer "F.Cu")
		(net "M_D_CPU1_SA_DQS_DP<4>")
	)
	(segment
		(start 11.125708 -275.94179)
		(end 11.11631 -275.951188)
		(width 0.101854)
		(layer "F.Cu")
		(net "M_D_CPU1_SA_DQS_DP<4>")
	)
	(segment
		(start 10.000488 -275.680678)
		(end 9.364472 -275.255482)
		(width 0.20066)
		(layer "F.Cu")
		(net "M_D_CPU1_SA_DQS_DP<4>")
	)
	(segment
		(start 15.135606 -275.516594)
		(end 14.874494 -275.255482)
		(width 0.20066)
		(layer "F.Cu")
		(net "M_D_CPU1_SA_DQS_DP<4>")
	)
	(segment
		(start 8.93953 -275.255482)
		(end 8.678418 -275.516594)
		(width 0.20066)
		(layer "F.Cu")
		(net "M_D_CPU1_SA_DQS_DP<4>")
	)
	(segment
		(start 13.118084 -275.94179)
		(end 11.36269 -275.94179)
		(width 0.1016)
		(layer "F.Cu")
		(net "M_D_CPU1_SA_DQS_DP<4>")
	)
	(segment
		(start 11.11631 -275.951188)
		(end 10.898124 -275.951188)
		(width 0.20066)
		(layer "F.Cu")
		(net "M_D_CPU1_SA_DQS_DP<4>")
	)
	(segment
		(start 13.441426 -275.94179)
		(end 13.118084 -275.94179)
		(width 0.101854)
		(layer "F.Cu")
		(net "M_D_CPU1_SA_DQS_DP<4>")
	)
	(segment
		(start 9.364472 -275.255482)
		(end 8.93953 -275.255482)
		(width 0.20066)
		(layer "F.Cu")
		(net "M_D_CPU1_SA_DQS_DP<4>")
	)
	(segment
		(start 16.789146 -275.516594)
		(end 15.684246 -275.516594)
		(width 0.20066)
		(layer "F.Cu")
		(net "M_D_CPU1_SA_DQS_DP<4>")
	)
	(segment
		(start 14.605762 -275.255482)
		(end 14.180566 -275.680678)
		(width 0.20066)
		(layer "F.Cu")
		(net "M_D_CPU1_SA_DQS_DP<4>")
	)
	(segment
		(start 14.180566 -275.680678)
		(end 13.854684 -275.680678)
		(width 0.20066)
		(layer "F.Cu")
		(net "M_D_CPU1_SA_DQS_DP<4>")
	)
	(segment
		(start 15.684246 -275.516594)
		(end 15.135606 -275.516594)
		(width 0.20066)
		(layer "F.Cu")
		(net "M_D_CPU1_SA_DQS_DP<4>")
	)
	(segment
		(start 13.854684 -275.680678)
		(end 13.593572 -275.94179)
		(width 0.20066)
		(layer "F.Cu")
		(net "M_D_CPU1_SA_DQS_DP<4>")
	)
	(segment
		(start 8.678418 -275.516594)
		(end 8.140446 -275.516594)
		(width 0.20066)
		(layer "F.Cu")
		(net "M_D_CPU1_SA_DQS_DP<4>")
	)
	(segment
		(start 99.063048 -262.336534)
		(end 99.063048 -262.87222)
		(width 0.20066)
		(layer "F.Cu")
		(net "M_D_CPU1_SA_DQS_DP<4>")
	)
	(segment
		(start 10.898124 -275.951188)
		(end 10.627614 -275.680678)
		(width 0.20066)
		(layer "F.Cu")
		(net "M_D_CPU1_SA_DQS_DP<4>")
	)
	(segment
		(start 99.063048 -262.87222)
		(end 99.062794 -262.872474)
		(width 0.20066)
		(layer "F.Cu")
		(net "M_D_CPU1_SA_DQS_DP<4>")
	)
	(segment
		(start 14.874494 -275.255482)
		(end 14.605762 -275.255482)
		(width 0.20066)
		(layer "F.Cu")
		(net "M_D_CPU1_SA_DQS_DP<4>")
	)
	(segment
		(start 98.092768 -263.245854)
		(end 98.035618 -263.238996)
		(width 0.088646)
		(layer "In11.Cu")
		(net "M_D_CPU1_SA_DQS_DP<4>")
	)
	(segment
		(start 25.269444 -274.657566)
		(end 23.97252 -274.657566)
		(width 0.18288)
		(layer "In11.Cu")
		(net "M_D_CPU1_SA_DQS_DP<4>")
	)
	(segment
		(start 51.24831 -273.390868)
		(end 50.87239 -273.390868)
		(width 0.18288)
		(layer "In11.Cu")
		(net "M_D_CPU1_SA_DQS_DP<4>")
	)
	(segment
		(start 30.29712 -274.657566)
		(end 29.376116 -274.657566)
		(width 0.18288)
		(layer "In11.Cu")
		(net "M_D_CPU1_SA_DQS_DP<4>")
	)
	(segment
		(start 45.877988 -273.979132)
		(end 45.199554 -274.657566)
		(width 0.18288)
		(layer "In11.Cu")
		(net "M_D_CPU1_SA_DQS_DP<4>")
	)
	(segment
		(start 91.276678 -263.370822)
		(end 91.261946 -263.362186)
		(width 0.088646)
		(layer "In11.Cu")
		(net "M_D_CPU1_SA_DQS_DP<4>")
	)
	(segment
		(start 51.535584 -273.103594)
		(end 51.24831 -273.390868)
		(width 0.18288)
		(layer "In11.Cu")
		(net "M_D_CPU1_SA_DQS_DP<4>")
	)
	(segment
		(start 62.762638 -272.87601)
		(end 59.497976 -272.87601)
		(width 0.18288)
		(layer "In11.Cu")
		(net "M_D_CPU1_SA_DQS_DP<4>")
	)
	(segment
		(start 45.199554 -274.657566)
		(end 44.410884 -274.657566)
		(width 0.18288)
		(layer "In11.Cu")
		(net "M_D_CPU1_SA_DQS_DP<4>")
	)
	(segment
		(start 44.410884 -274.657566)
		(end 43.620182 -273.866864)
		(width 0.18288)
		(layer "In11.Cu")
		(net "M_D_CPU1_SA_DQS_DP<4>")
	)
	(segment
		(start 50.87239 -273.390868)
		(end 50.610008 -273.128486)
		(width 0.18288)
		(layer "In11.Cu")
		(net "M_D_CPU1_SA_DQS_DP<4>")
	)
	(segment
		(start 20.710144 -275.942806)
		(end 20.421092 -275.653754)
		(width 0.18288)
		(layer "In11.Cu")
		(net "M_D_CPU1_SA_DQS_DP<4>")
	)
	(segment
		(start 30.988 -273.966686)
		(end 30.29712 -274.657566)
		(width 0.18288)
		(layer "In11.Cu")
		(net "M_D_CPU1_SA_DQS_DP<4>")
	)
	(segment
		(start 55.964836 -272.396966)
		(end 55.258208 -273.103594)
		(width 0.18288)
		(layer "In11.Cu")
		(net "M_D_CPU1_SA_DQS_DP<4>")
	)
	(segment
		(start 83.494626 -263.83361)
		(end 83.097116 -263.83361)
		(width 0.088646)
		(layer "In11.Cu")
		(net "M_D_CPU1_SA_DQS_DP<4>")
	)
	(segment
		(start 25.760934 -274.166076)
		(end 25.269444 -274.657566)
		(width 0.18288)
		(layer "In11.Cu")
		(net "M_D_CPU1_SA_DQS_DP<4>")
	)
	(segment
		(start 21.340064 -275.67128)
		(end 21.068538 -275.942806)
		(width 0.18288)
		(layer "In11.Cu")
		(net "M_D_CPU1_SA_DQS_DP<4>")
	)
	(segment
		(start 83.890358 -263.437878)
		(end 83.494626 -263.83361)
		(width 0.088646)
		(layer "In11.Cu")
		(net "M_D_CPU1_SA_DQS_DP<4>")
	)
	(segment
		(start 55.258208 -273.103594)
		(end 51.535584 -273.103594)
		(width 0.18288)
		(layer "In11.Cu")
		(net "M_D_CPU1_SA_DQS_DP<4>")
	)
	(segment
		(start 34.20237 -273.95805)
		(end 32.343852 -273.95805)
		(width 0.18288)
		(layer "In11.Cu")
		(net "M_D_CPU1_SA_DQS_DP<4>")
	)
	(segment
		(start 90.88755 -263.362186)
		(end 90.877136 -263.368282)
		(width 0.088646)
		(layer "In11.Cu")
		(net "M_D_CPU1_SA_DQS_DP<4>")
	)
	(segment
		(start 20.421092 -275.653754)
		(end 19.80692 -275.653754)
		(width 0.18288)
		(layer "In11.Cu")
		(net "M_D_CPU1_SA_DQS_DP<4>")
	)
	(segment
		(start 46.510702 -273.979132)
		(end 45.877988 -273.979132)
		(width 0.18288)
		(layer "In11.Cu")
		(net "M_D_CPU1_SA_DQS_DP<4>")
	)
	(segment
		(start 35.065462 -273.094958)
		(end 34.20237 -273.95805)
		(width 0.18288)
		(layer "In11.Cu")
		(net "M_D_CPU1_SA_DQS_DP<4>")
	)
	(segment
		(start 95.975678 -263.370822)
		(end 95.960946 -263.362186)
		(width 0.088646)
		(layer "In11.Cu")
		(net "M_D_CPU1_SA_DQS_DP<4>")
	)
	(segment
		(start 98.030792 -263.241536)
		(end 97.675192 -263.241536)
		(width 0.088646)
		(layer "In11.Cu")
		(net "M_D_CPU1_SA_DQS_DP<4>")
	)
	(segment
		(start 83.013804 -263.893554)
		(end 75.5523 -263.893554)
		(width 0.18288)
		(layer "In11.Cu")
		(net "M_D_CPU1_SA_DQS_DP<4>")
	)
	(segment
		(start 94.09176 -263.368282)
		(end 94.081346 -263.362186)
		(width 0.088646)
		(layer "In11.Cu")
		(net "M_D_CPU1_SA_DQS_DP<4>")
	)
	(segment
		(start 50.610008 -273.128486)
		(end 49.885854 -273.128486)
		(width 0.18288)
		(layer "In11.Cu")
		(net "M_D_CPU1_SA_DQS_DP<4>")
	)
	(segment
		(start 32.343852 -273.95805)
		(end 32.06115 -274.240752)
		(width 0.18288)
		(layer "In11.Cu")
		(net "M_D_CPU1_SA_DQS_DP<4>")
	)
	(segment
		(start 21.068538 -275.942806)
		(end 20.710144 -275.942806)
		(width 0.18288)
		(layer "In11.Cu")
		(net "M_D_CPU1_SA_DQS_DP<4>")
	)
	(segment
		(start 31.376112 -273.966686)
		(end 30.988 -273.966686)
		(width 0.18288)
		(layer "In11.Cu")
		(net "M_D_CPU1_SA_DQS_DP<4>")
	)
	(segment
		(start 23.97252 -274.657566)
		(end 22.958806 -275.67128)
		(width 0.18288)
		(layer "In11.Cu")
		(net "M_D_CPU1_SA_DQS_DP<4>")
	)
	(segment
		(start 17.940782 -275.246084)
		(end 17.059656 -275.246084)
		(width 0.18288)
		(layer "In11.Cu")
		(net "M_D_CPU1_SA_DQS_DP<4>")
	)
	(segment
		(start 22.958806 -275.67128)
		(end 21.340064 -275.67128)
		(width 0.18288)
		(layer "In11.Cu")
		(net "M_D_CPU1_SA_DQS_DP<4>")
	)
	(segment
		(start 49.070768 -273.943572)
		(end 47.46879 -273.943572)
		(width 0.18288)
		(layer "In11.Cu")
		(net "M_D_CPU1_SA_DQS_DP<4>")
	)
	(segment
		(start 43.620182 -273.866864)
		(end 40.117014 -273.866864)
		(width 0.18288)
		(layer "In11.Cu")
		(net "M_D_CPU1_SA_DQS_DP<4>")
	)
	(segment
		(start 92.216478 -263.370822)
		(end 92.201746 -263.362186)
		(width 0.088646)
		(layer "In11.Cu")
		(net "M_D_CPU1_SA_DQS_DP<4>")
	)
	(segment
		(start 39.36238 -273.11223)
		(end 36.445952 -273.11223)
		(width 0.18288)
		(layer "In11.Cu")
		(net "M_D_CPU1_SA_DQS_DP<4>")
	)
	(segment
		(start 46.772322 -274.240752)
		(end 46.510702 -273.979132)
		(width 0.18288)
		(layer "In11.Cu")
		(net "M_D_CPU1_SA_DQS_DP<4>")
	)
	(segment
		(start 35.78479 -273.390868)
		(end 35.48888 -273.094958)
		(width 0.18288)
		(layer "In11.Cu")
		(net "M_D_CPU1_SA_DQS_DP<4>")
	)
	(segment
		(start 84.025994 -263.437878)
		(end 83.890358 -263.437878)
		(width 0.088646)
		(layer "In11.Cu")
		(net "M_D_CPU1_SA_DQS_DP<4>")
	)
	(segment
		(start 47.46879 -273.943572)
		(end 47.17161 -274.240752)
		(width 0.18288)
		(layer "In11.Cu")
		(net "M_D_CPU1_SA_DQS_DP<4>")
	)
	(segment
		(start 98.722434 -262.96239)
		(end 98.297238 -263.204198)
		(width 0.088646)
		(layer "In11.Cu")
		(net "M_D_CPU1_SA_DQS_DP<4>")
	)
	(segment
		(start 35.48888 -273.094958)
		(end 35.065462 -273.094958)
		(width 0.18288)
		(layer "In11.Cu")
		(net "M_D_CPU1_SA_DQS_DP<4>")
	)
	(segment
		(start 59.018932 -272.396966)
		(end 55.964836 -272.396966)
		(width 0.18288)
		(layer "In11.Cu")
		(net "M_D_CPU1_SA_DQS_DP<4>")
	)
	(segment
		(start 18.3007 -274.886166)
		(end 17.940782 -275.246084)
		(width 0.18288)
		(layer "In11.Cu")
		(net "M_D_CPU1_SA_DQS_DP<4>")
	)
	(segment
		(start 97.675192 -263.241536)
		(end 97.451672 -263.370314)
		(width 0.088646)
		(layer "In11.Cu")
		(net "M_D_CPU1_SA_DQS_DP<4>")
	)
	(segment
		(start 36.167314 -273.390868)
		(end 35.78479 -273.390868)
		(width 0.18288)
		(layer "In11.Cu")
		(net "M_D_CPU1_SA_DQS_DP<4>")
	)
	(segment
		(start 31.650178 -274.240752)
		(end 31.376112 -273.966686)
		(width 0.18288)
		(layer "In11.Cu")
		(net "M_D_CPU1_SA_DQS_DP<4>")
	)
	(segment
		(start 59.497976 -272.87601)
		(end 59.018932 -272.396966)
		(width 0.18288)
		(layer "In11.Cu")
		(net "M_D_CPU1_SA_DQS_DP<4>")
	)
	(segment
		(start 40.117014 -273.866864)
		(end 39.36238 -273.11223)
		(width 0.18288)
		(layer "In11.Cu")
		(net "M_D_CPU1_SA_DQS_DP<4>")
	)
	(segment
		(start 83.037172 -263.893554)
		(end 83.013804 -263.893554)
		(width 0.088646)
		(layer "In11.Cu")
		(net "M_D_CPU1_SA_DQS_DP<4>")
	)
	(segment
		(start 29.376116 -274.657566)
		(end 28.884626 -274.166076)
		(width 0.18288)
		(layer "In11.Cu")
		(net "M_D_CPU1_SA_DQS_DP<4>")
	)
	(segment
		(start 98.035618 -263.238996)
		(end 98.030792 -263.241536)
		(width 0.088646)
		(layer "In11.Cu")
		(net "M_D_CPU1_SA_DQS_DP<4>")
	)
	(segment
		(start 17.059656 -275.246084)
		(end 16.789146 -275.516594)
		(width 0.18288)
		(layer "In11.Cu")
		(net "M_D_CPU1_SA_DQS_DP<4>")
	)
	(segment
		(start 19.80692 -275.653754)
		(end 19.039332 -274.886166)
		(width 0.18288)
		(layer "In11.Cu")
		(net "M_D_CPU1_SA_DQS_DP<4>")
	)
	(segment
		(start 47.17161 -274.240752)
		(end 46.772322 -274.240752)
		(width 0.18288)
		(layer "In11.Cu")
		(net "M_D_CPU1_SA_DQS_DP<4>")
	)
	(segment
		(start 96.900492 -263.361932)
		(end 96.900746 -263.362186)
		(width 0.088646)
		(layer "In11.Cu")
		(net "M_D_CPU1_SA_DQS_DP<4>")
	)
	(segment
		(start 67.399408 -272.046446)
		(end 63.592202 -272.046446)
		(width 0.18288)
		(layer "In11.Cu")
		(net "M_D_CPU1_SA_DQS_DP<4>")
	)
	(segment
		(start 63.592202 -272.046446)
		(end 62.762638 -272.87601)
		(width 0.18288)
		(layer "In11.Cu")
		(net "M_D_CPU1_SA_DQS_DP<4>")
	)
	(segment
		(start 19.039332 -274.886166)
		(end 18.3007 -274.886166)
		(width 0.18288)
		(layer "In11.Cu")
		(net "M_D_CPU1_SA_DQS_DP<4>")
	)
	(segment
		(start 32.06115 -274.240752)
		(end 31.650178 -274.240752)
		(width 0.18288)
		(layer "In11.Cu")
		(net "M_D_CPU1_SA_DQS_DP<4>")
	)
	(segment
		(start 49.885854 -273.128486)
		(end 49.070768 -273.943572)
		(width 0.18288)
		(layer "In11.Cu")
		(net "M_D_CPU1_SA_DQS_DP<4>")
	)
	(segment
		(start 75.5523 -263.893554)
		(end 67.399408 -272.046446)
		(width 0.18288)
		(layer "In11.Cu")
		(net "M_D_CPU1_SA_DQS_DP<4>")
	)
	(segment
		(start 95.031306 -263.368282)
		(end 95.020892 -263.362186)
		(width 0.088646)
		(layer "In11.Cu")
		(net "M_D_CPU1_SA_DQS_DP<4>")
	)
	(segment
		(start 83.097116 -263.83361)
		(end 83.037172 -263.893554)
		(width 0.088646)
		(layer "In11.Cu")
		(net "M_D_CPU1_SA_DQS_DP<4>")
	)
	(segment
		(start 36.445952 -273.11223)
		(end 36.167314 -273.390868)
		(width 0.18288)
		(layer "In11.Cu")
		(net "M_D_CPU1_SA_DQS_DP<4>")
	)
	(segment
		(start 93.156278 -263.370822)
		(end 93.141546 -263.362186)
		(width 0.088646)
		(layer "In11.Cu")
		(net "M_D_CPU1_SA_DQS_DP<4>")
	)
	(segment
		(start 28.884626 -274.166076)
		(end 25.760934 -274.166076)
		(width 0.18288)
		(layer "In11.Cu")
		(net "M_D_CPU1_SA_DQS_DP<4>")
	)
	(arc
		(start 86.562692 -263.362186)
		(mid 86.375494 -263.312043)
		(end 86.188296 -263.362186)
		(width 0.088646)
		(layer "In11.Cu")
		(net "M_D_CPU1_SA_DQS_DP<4>")
	)
	(arc
		(start 91.261946 -263.362186)
		(mid 91.074748 -263.312043)
		(end 90.88755 -263.362186)
		(width 0.088646)
		(layer "In11.Cu")
		(net "M_D_CPU1_SA_DQS_DP<4>")
	)
	(arc
		(start 90.321892 -263.362186)
		(mid 90.134694 -263.312043)
		(end 89.947496 -263.362186)
		(width 0.088646)
		(layer "In11.Cu")
		(net "M_D_CPU1_SA_DQS_DP<4>")
	)
	(arc
		(start 98.297238 -263.204198)
		(mid 98.198396 -263.241708)
		(end 98.092768 -263.245854)
		(width 0.088646)
		(layer "In11.Cu")
		(net "M_D_CPU1_SA_DQS_DP<4>")
	)
	(arc
		(start 87.128096 -263.362186)
		(mid 86.845394 -263.437928)
		(end 86.562692 -263.362186)
		(width 0.088646)
		(layer "In11.Cu")
		(net "M_D_CPU1_SA_DQS_DP<4>")
	)
	(arc
		(start 93.70695 -263.362186)
		(mid 93.432721 -263.438111)
		(end 93.156278 -263.370822)
		(width 0.088646)
		(layer "In11.Cu")
		(net "M_D_CPU1_SA_DQS_DP<4>")
	)
	(arc
		(start 89.382092 -263.362186)
		(mid 89.194894 -263.312043)
		(end 89.007696 -263.362186)
		(width 0.088646)
		(layer "In11.Cu")
		(net "M_D_CPU1_SA_DQS_DP<4>")
	)
	(arc
		(start 94.081346 -263.362186)
		(mid 93.894148 -263.312043)
		(end 93.70695 -263.362186)
		(width 0.088646)
		(layer "In11.Cu")
		(net "M_D_CPU1_SA_DQS_DP<4>")
	)
	(arc
		(start 85.248496 -263.362186)
		(mid 84.965794 -263.437928)
		(end 84.683092 -263.362186)
		(width 0.088646)
		(layer "In11.Cu")
		(net "M_D_CPU1_SA_DQS_DP<4>")
	)
	(arc
		(start 90.877136 -263.368282)
		(mid 90.598704 -263.438096)
		(end 90.321892 -263.362186)
		(width 0.088646)
		(layer "In11.Cu")
		(net "M_D_CPU1_SA_DQS_DP<4>")
	)
	(arc
		(start 95.58655 -263.362186)
		(mid 95.309737 -263.438022)
		(end 95.031306 -263.368282)
		(width 0.088646)
		(layer "In11.Cu")
		(net "M_D_CPU1_SA_DQS_DP<4>")
	)
	(arc
		(start 99.062794 -262.872474)
		(mid 98.886773 -262.895311)
		(end 98.722434 -262.96239)
		(width 0.088646)
		(layer "In11.Cu")
		(net "M_D_CPU1_SA_DQS_DP<4>")
	)
	(arc
		(start 95.960946 -263.362186)
		(mid 95.773748 -263.312043)
		(end 95.58655 -263.362186)
		(width 0.088646)
		(layer "In11.Cu")
		(net "M_D_CPU1_SA_DQS_DP<4>")
	)
	(arc
		(start 92.201746 -263.362186)
		(mid 92.014548 -263.312043)
		(end 91.82735 -263.362186)
		(width 0.088646)
		(layer "In11.Cu")
		(net "M_D_CPU1_SA_DQS_DP<4>")
	)
	(arc
		(start 86.188296 -263.362186)
		(mid 85.905594 -263.437928)
		(end 85.622892 -263.362186)
		(width 0.088646)
		(layer "In11.Cu")
		(net "M_D_CPU1_SA_DQS_DP<4>")
	)
	(arc
		(start 84.683092 -263.362186)
		(mid 84.495894 -263.312043)
		(end 84.308696 -263.362186)
		(width 0.088646)
		(layer "In11.Cu")
		(net "M_D_CPU1_SA_DQS_DP<4>")
	)
	(arc
		(start 94.646496 -263.362186)
		(mid 94.369937 -263.437895)
		(end 94.09176 -263.368282)
		(width 0.088646)
		(layer "In11.Cu")
		(net "M_D_CPU1_SA_DQS_DP<4>")
	)
	(arc
		(start 93.141546 -263.362186)
		(mid 92.954348 -263.312043)
		(end 92.76715 -263.362186)
		(width 0.088646)
		(layer "In11.Cu")
		(net "M_D_CPU1_SA_DQS_DP<4>")
	)
	(arc
		(start 87.502492 -263.362186)
		(mid 87.315294 -263.312043)
		(end 87.128096 -263.362186)
		(width 0.088646)
		(layer "In11.Cu")
		(net "M_D_CPU1_SA_DQS_DP<4>")
	)
	(arc
		(start 95.020892 -263.362186)
		(mid 94.833694 -263.312043)
		(end 94.646496 -263.362186)
		(width 0.088646)
		(layer "In11.Cu")
		(net "M_D_CPU1_SA_DQS_DP<4>")
	)
	(arc
		(start 88.067896 -263.362186)
		(mid 87.785194 -263.437928)
		(end 87.502492 -263.362186)
		(width 0.088646)
		(layer "In11.Cu")
		(net "M_D_CPU1_SA_DQS_DP<4>")
	)
	(arc
		(start 88.442292 -263.362186)
		(mid 88.255094 -263.312043)
		(end 88.067896 -263.362186)
		(width 0.088646)
		(layer "In11.Cu")
		(net "M_D_CPU1_SA_DQS_DP<4>")
	)
	(arc
		(start 92.76715 -263.362186)
		(mid 92.492921 -263.438111)
		(end 92.216478 -263.370822)
		(width 0.088646)
		(layer "In11.Cu")
		(net "M_D_CPU1_SA_DQS_DP<4>")
	)
	(arc
		(start 84.308696 -263.362186)
		(mid 84.17233 -263.418664)
		(end 84.025994 -263.437878)
		(width 0.088646)
		(layer "In11.Cu")
		(net "M_D_CPU1_SA_DQS_DP<4>")
	)
	(arc
		(start 91.82735 -263.362186)
		(mid 91.553121 -263.438111)
		(end 91.276678 -263.370822)
		(width 0.088646)
		(layer "In11.Cu")
		(net "M_D_CPU1_SA_DQS_DP<4>")
	)
	(arc
		(start 89.007696 -263.362186)
		(mid 88.724994 -263.437928)
		(end 88.442292 -263.362186)
		(width 0.088646)
		(layer "In11.Cu")
		(net "M_D_CPU1_SA_DQS_DP<4>")
	)
	(arc
		(start 85.622892 -263.362186)
		(mid 85.435694 -263.312043)
		(end 85.248496 -263.362186)
		(width 0.088646)
		(layer "In11.Cu")
		(net "M_D_CPU1_SA_DQS_DP<4>")
	)
	(arc
		(start 96.52635 -263.362186)
		(mid 96.252121 -263.438111)
		(end 95.975678 -263.370822)
		(width 0.088646)
		(layer "In11.Cu")
		(net "M_D_CPU1_SA_DQS_DP<4>")
	)
	(arc
		(start 97.451672 -263.370314)
		(mid 97.175007 -263.437785)
		(end 96.900492 -263.361932)
		(width 0.088646)
		(layer "In11.Cu")
		(net "M_D_CPU1_SA_DQS_DP<4>")
	)
	(arc
		(start 89.947496 -263.362186)
		(mid 89.664794 -263.437928)
		(end 89.382092 -263.362186)
		(width 0.088646)
		(layer "In11.Cu")
		(net "M_D_CPU1_SA_DQS_DP<4>")
	)
	(arc
		(start 96.900746 -263.362186)
		(mid 96.713548 -263.312043)
		(end 96.52635 -263.362186)
		(width 0.088646)
		(layer "In11.Cu")
		(net "M_D_CPU1_SA_DQS_DP<4>")
	)
	(segment
		(start 10.898124 -285.301182)
		(end 10.627614 -285.030672)
		(width 0.20066)
		(layer "F.Cu")
		(net "M_D_CPU1_SA_DQS_DP<3>")
	)
	(segment
		(start 13.441426 -285.291784)
		(end 13.118084 -285.291784)
		(width 0.101854)
		(layer "F.Cu")
		(net "M_D_CPU1_SA_DQS_DP<3>")
	)
	(segment
		(start 8.678418 -284.866588)
		(end 8.140446 -284.866588)
		(width 0.20066)
		(layer "F.Cu")
		(net "M_D_CPU1_SA_DQS_DP<3>")
	)
	(segment
		(start 8.93953 -284.605476)
		(end 8.678418 -284.866588)
		(width 0.20066)
		(layer "F.Cu")
		(net "M_D_CPU1_SA_DQS_DP<3>")
	)
	(segment
		(start 14.874494 -284.605476)
		(end 14.605762 -284.605476)
		(width 0.20066)
		(layer "F.Cu")
		(net "M_D_CPU1_SA_DQS_DP<3>")
	)
	(segment
		(start 11.125708 -285.291784)
		(end 11.11631 -285.301182)
		(width 0.101854)
		(layer "F.Cu")
		(net "M_D_CPU1_SA_DQS_DP<3>")
	)
	(segment
		(start 15.135606 -284.866588)
		(end 14.874494 -284.605476)
		(width 0.20066)
		(layer "F.Cu")
		(net "M_D_CPU1_SA_DQS_DP<3>")
	)
	(segment
		(start 10.627614 -285.030672)
		(end 10.000488 -285.030672)
		(width 0.20066)
		(layer "F.Cu")
		(net "M_D_CPU1_SA_DQS_DP<3>")
	)
	(segment
		(start 11.11631 -285.301182)
		(end 10.898124 -285.301182)
		(width 0.20066)
		(layer "F.Cu")
		(net "M_D_CPU1_SA_DQS_DP<3>")
	)
	(segment
		(start 14.605762 -284.605476)
		(end 14.180566 -285.030672)
		(width 0.20066)
		(layer "F.Cu")
		(net "M_D_CPU1_SA_DQS_DP<3>")
	)
	(segment
		(start 13.118084 -285.291784)
		(end 11.36269 -285.291784)
		(width 0.1016)
		(layer "F.Cu")
		(net "M_D_CPU1_SA_DQS_DP<3>")
	)
	(segment
		(start 13.854684 -285.030672)
		(end 13.593572 -285.291784)
		(width 0.20066)
		(layer "F.Cu")
		(net "M_D_CPU1_SA_DQS_DP<3>")
	)
	(segment
		(start 10.000488 -285.030672)
		(end 9.364472 -284.605476)
		(width 0.20066)
		(layer "F.Cu")
		(net "M_D_CPU1_SA_DQS_DP<3>")
	)
	(segment
		(start 15.684246 -284.866588)
		(end 16.789146 -284.866588)
		(width 0.20066)
		(layer "F.Cu")
		(net "M_D_CPU1_SA_DQS_DP<3>")
	)
	(segment
		(start 14.180566 -285.030672)
		(end 13.854684 -285.030672)
		(width 0.20066)
		(layer "F.Cu")
		(net "M_D_CPU1_SA_DQS_DP<3>")
	)
	(segment
		(start 99.062794 -267.220192)
		(end 99.062794 -267.755878)
		(width 0.20066)
		(layer "F.Cu")
		(net "M_D_CPU1_SA_DQS_DP<3>")
	)
	(segment
		(start 99.063048 -267.219938)
		(end 99.062794 -267.220192)
		(width 0.20066)
		(layer "F.Cu")
		(net "M_D_CPU1_SA_DQS_DP<3>")
	)
	(segment
		(start 15.684246 -284.866588)
		(end 15.135606 -284.866588)
		(width 0.20066)
		(layer "F.Cu")
		(net "M_D_CPU1_SA_DQS_DP<3>")
	)
	(segment
		(start 13.593572 -285.291784)
		(end 13.441426 -285.291784)
		(width 0.20066)
		(layer "F.Cu")
		(net "M_D_CPU1_SA_DQS_DP<3>")
	)
	(segment
		(start 9.364472 -284.605476)
		(end 8.93953 -284.605476)
		(width 0.20066)
		(layer "F.Cu")
		(net "M_D_CPU1_SA_DQS_DP<3>")
	)
	(segment
		(start 11.36269 -285.291784)
		(end 11.125708 -285.291784)
		(width 0.101854)
		(layer "F.Cu")
		(net "M_D_CPU1_SA_DQS_DP<3>")
	)
	(segment
		(start 32.35579 -285.853632)
		(end 32.066738 -286.142684)
		(width 0.18288)
		(layer "In11.Cu")
		(net "M_D_CPU1_SA_DQS_DP<3>")
	)
	(segment
		(start 52.063396 -285.022036)
		(end 51.520344 -285.022036)
		(width 0.18288)
		(layer "In11.Cu")
		(net "M_D_CPU1_SA_DQS_DP<3>")
	)
	(segment
		(start 38.666928 -284.310074)
		(end 36.970462 -285.012892)
		(width 0.18288)
		(layer "In11.Cu")
		(net "M_D_CPU1_SA_DQS_DP<3>")
	)
	(segment
		(start 20.020788 -285.000192)
		(end 19.329654 -284.713934)
		(width 0.18288)
		(layer "In11.Cu")
		(net "M_D_CPU1_SA_DQS_DP<3>")
	)
	(segment
		(start 21.075142 -285.2928)
		(end 20.69338 -285.2928)
		(width 0.18288)
		(layer "In11.Cu")
		(net "M_D_CPU1_SA_DQS_DP<3>")
	)
	(segment
		(start 17.06372 -284.592014)
		(end 16.789146 -284.866588)
		(width 0.18288)
		(layer "In11.Cu")
		(net "M_D_CPU1_SA_DQS_DP<3>")
	)
	(segment
		(start 98.035618 -268.1224)
		(end 98.030792 -268.12494)
		(width 0.088646)
		(layer "In11.Cu")
		(net "M_D_CPU1_SA_DQS_DP<3>")
	)
	(segment
		(start 29.391356 -284.34919)
		(end 25.95753 -284.34919)
		(width 0.18288)
		(layer "In11.Cu")
		(net "M_D_CPU1_SA_DQS_DP<3>")
	)
	(segment
		(start 21.35505 -285.012892)
		(end 21.075142 -285.2928)
		(width 0.18288)
		(layer "In11.Cu")
		(net "M_D_CPU1_SA_DQS_DP<3>")
	)
	(segment
		(start 83.676744 -269.614142)
		(end 83.442556 -269.84833)
		(width 0.088646)
		(layer "In11.Cu")
		(net "M_D_CPU1_SA_DQS_DP<3>")
	)
	(segment
		(start 36.440872 -285.012892)
		(end 36.160964 -285.2928)
		(width 0.18288)
		(layer "In11.Cu")
		(net "M_D_CPU1_SA_DQS_DP<3>")
	)
	(segment
		(start 61.752734 -282.658566)
		(end 59.63412 -282.658566)
		(width 0.18288)
		(layer "In11.Cu")
		(net "M_D_CPU1_SA_DQS_DP<3>")
	)
	(segment
		(start 59.63412 -282.658566)
		(end 59.154568 -283.138118)
		(width 0.18288)
		(layer "In11.Cu")
		(net "M_D_CPU1_SA_DQS_DP<3>")
	)
	(segment
		(start 96.900492 -268.245336)
		(end 96.900746 -268.245336)
		(width 0.088646)
		(layer "In11.Cu")
		(net "M_D_CPU1_SA_DQS_DP<3>")
	)
	(segment
		(start 63.287656 -281.358594)
		(end 62.153292 -282.492958)
		(width 0.18288)
		(layer "In11.Cu")
		(net "M_D_CPU1_SA_DQS_DP<3>")
	)
	(segment
		(start 46.499272 -285.86811)
		(end 45.931836 -285.86811)
		(width 0.18288)
		(layer "In11.Cu")
		(net "M_D_CPU1_SA_DQS_DP<3>")
	)
	(segment
		(start 30.922468 -285.880302)
		(end 29.391356 -284.34919)
		(width 0.18288)
		(layer "In11.Cu")
		(net "M_D_CPU1_SA_DQS_DP<3>")
	)
	(segment
		(start 95.975678 -268.253972)
		(end 95.960946 -268.245336)
		(width 0.088646)
		(layer "In11.Cu")
		(net "M_D_CPU1_SA_DQS_DP<3>")
	)
	(segment
		(start 83.676744 -269.388844)
		(end 83.676744 -269.614142)
		(width 0.088646)
		(layer "In11.Cu")
		(net "M_D_CPU1_SA_DQS_DP<3>")
	)
	(segment
		(start 93.156278 -268.253972)
		(end 93.141546 -268.245336)
		(width 0.088646)
		(layer "In11.Cu")
		(net "M_D_CPU1_SA_DQS_DP<3>")
	)
	(segment
		(start 35.334702 -285.030164)
		(end 33.34893 -285.853632)
		(width 0.18288)
		(layer "In11.Cu")
		(net "M_D_CPU1_SA_DQS_DP<3>")
	)
	(segment
		(start 94.09176 -268.251432)
		(end 94.081346 -268.245336)
		(width 0.088646)
		(layer "In11.Cu")
		(net "M_D_CPU1_SA_DQS_DP<3>")
	)
	(segment
		(start 51.520344 -285.022036)
		(end 51.251866 -285.290514)
		(width 0.18288)
		(layer "In11.Cu")
		(net "M_D_CPU1_SA_DQS_DP<3>")
	)
	(segment
		(start 98.030792 -268.12494)
		(end 97.675192 -268.12494)
		(width 0.088646)
		(layer "In11.Cu")
		(net "M_D_CPU1_SA_DQS_DP<3>")
	)
	(segment
		(start 56.565292 -283.138118)
		(end 54.605682 -283.949648)
		(width 0.18288)
		(layer "In11.Cu")
		(net "M_D_CPU1_SA_DQS_DP<3>")
	)
	(segment
		(start 95.031306 -268.251432)
		(end 95.020892 -268.245336)
		(width 0.088646)
		(layer "In11.Cu")
		(net "M_D_CPU1_SA_DQS_DP<3>")
	)
	(segment
		(start 20.69338 -285.2928)
		(end 20.400772 -285.000192)
		(width 0.18288)
		(layer "In11.Cu")
		(net "M_D_CPU1_SA_DQS_DP<3>")
	)
	(segment
		(start 90.88755 -268.245336)
		(end 90.877136 -268.251432)
		(width 0.088646)
		(layer "In11.Cu")
		(net "M_D_CPU1_SA_DQS_DP<3>")
	)
	(segment
		(start 83.442556 -269.84833)
		(end 83.022948 -269.84833)
		(width 0.088646)
		(layer "In11.Cu")
		(net "M_D_CPU1_SA_DQS_DP<3>")
	)
	(segment
		(start 66.688462 -281.358594)
		(end 63.287656 -281.358594)
		(width 0.18288)
		(layer "In11.Cu")
		(net "M_D_CPU1_SA_DQS_DP<3>")
	)
	(segment
		(start 45.080428 -285.016956)
		(end 43.374056 -284.310074)
		(width 0.18288)
		(layer "In11.Cu")
		(net "M_D_CPU1_SA_DQS_DP<3>")
	)
	(segment
		(start 50.60696 -285.025592)
		(end 50.200814 -285.025592)
		(width 0.18288)
		(layer "In11.Cu")
		(net "M_D_CPU1_SA_DQS_DP<3>")
	)
	(segment
		(start 19.329654 -284.713934)
		(end 19.035014 -284.419294)
		(width 0.18288)
		(layer "In11.Cu")
		(net "M_D_CPU1_SA_DQS_DP<3>")
	)
	(segment
		(start 46.771814 -286.140652)
		(end 46.499272 -285.86811)
		(width 0.18288)
		(layer "In11.Cu")
		(net "M_D_CPU1_SA_DQS_DP<3>")
	)
	(segment
		(start 36.970462 -285.012892)
		(end 36.440872 -285.012892)
		(width 0.18288)
		(layer "In11.Cu")
		(net "M_D_CPU1_SA_DQS_DP<3>")
	)
	(segment
		(start 83.984592 -269.080996)
		(end 83.676744 -269.388844)
		(width 0.088646)
		(layer "In11.Cu")
		(net "M_D_CPU1_SA_DQS_DP<3>")
	)
	(segment
		(start 47.423578 -285.872428)
		(end 47.155354 -286.140652)
		(width 0.18288)
		(layer "In11.Cu")
		(net "M_D_CPU1_SA_DQS_DP<3>")
	)
	(segment
		(start 33.34893 -285.853632)
		(end 32.35579 -285.853632)
		(width 0.18288)
		(layer "In11.Cu")
		(net "M_D_CPU1_SA_DQS_DP<3>")
	)
	(segment
		(start 92.216478 -268.253972)
		(end 92.201746 -268.245336)
		(width 0.088646)
		(layer "In11.Cu")
		(net "M_D_CPU1_SA_DQS_DP<3>")
	)
	(segment
		(start 84.26577 -268.551914)
		(end 83.984592 -268.833092)
		(width 0.088646)
		(layer "In11.Cu")
		(net "M_D_CPU1_SA_DQS_DP<3>")
	)
	(segment
		(start 78.138782 -269.908274)
		(end 66.688462 -281.358594)
		(width 0.18288)
		(layer "In11.Cu")
		(net "M_D_CPU1_SA_DQS_DP<3>")
	)
	(segment
		(start 50.200814 -285.025592)
		(end 49.353978 -285.872428)
		(width 0.18288)
		(layer "In11.Cu")
		(net "M_D_CPU1_SA_DQS_DP<3>")
	)
	(segment
		(start 83.022948 -269.84833)
		(end 82.963004 -269.908274)
		(width 0.088646)
		(layer "In11.Cu")
		(net "M_D_CPU1_SA_DQS_DP<3>")
	)
	(segment
		(start 24.35606 -285.012892)
		(end 21.35505 -285.012892)
		(width 0.18288)
		(layer "In11.Cu")
		(net "M_D_CPU1_SA_DQS_DP<3>")
	)
	(segment
		(start 47.155354 -286.140652)
		(end 46.771814 -286.140652)
		(width 0.18288)
		(layer "In11.Cu")
		(net "M_D_CPU1_SA_DQS_DP<3>")
	)
	(segment
		(start 43.374056 -284.310074)
		(end 38.666928 -284.310074)
		(width 0.18288)
		(layer "In11.Cu")
		(net "M_D_CPU1_SA_DQS_DP<3>")
	)
	(segment
		(start 51.251866 -285.290514)
		(end 50.871882 -285.290514)
		(width 0.18288)
		(layer "In11.Cu")
		(net "M_D_CPU1_SA_DQS_DP<3>")
	)
	(segment
		(start 18.217642 -284.419294)
		(end 17.800574 -284.592014)
		(width 0.18288)
		(layer "In11.Cu")
		(net "M_D_CPU1_SA_DQS_DP<3>")
	)
	(segment
		(start 25.95753 -284.34919)
		(end 24.35606 -285.012892)
		(width 0.18288)
		(layer "In11.Cu")
		(net "M_D_CPU1_SA_DQS_DP<3>")
	)
	(segment
		(start 50.871882 -285.290514)
		(end 50.60696 -285.025592)
		(width 0.18288)
		(layer "In11.Cu")
		(net "M_D_CPU1_SA_DQS_DP<3>")
	)
	(segment
		(start 59.154568 -283.138118)
		(end 56.565292 -283.138118)
		(width 0.18288)
		(layer "In11.Cu")
		(net "M_D_CPU1_SA_DQS_DP<3>")
	)
	(segment
		(start 52.64785 -284.437836)
		(end 52.063396 -285.022036)
		(width 0.18288)
		(layer "In11.Cu")
		(net "M_D_CPU1_SA_DQS_DP<3>")
	)
	(segment
		(start 31.423864 -285.880302)
		(end 30.922468 -285.880302)
		(width 0.18288)
		(layer "In11.Cu")
		(net "M_D_CPU1_SA_DQS_DP<3>")
	)
	(segment
		(start 32.066738 -286.142684)
		(end 31.686246 -286.142684)
		(width 0.18288)
		(layer "In11.Cu")
		(net "M_D_CPU1_SA_DQS_DP<3>")
	)
	(segment
		(start 98.722434 -267.845794)
		(end 98.297238 -268.087602)
		(width 0.088646)
		(layer "In11.Cu")
		(net "M_D_CPU1_SA_DQS_DP<3>")
	)
	(segment
		(start 36.160964 -285.2928)
		(end 35.786568 -285.2928)
		(width 0.18288)
		(layer "In11.Cu")
		(net "M_D_CPU1_SA_DQS_DP<3>")
	)
	(segment
		(start 35.523932 -285.030164)
		(end 35.334702 -285.030164)
		(width 0.18288)
		(layer "In11.Cu")
		(net "M_D_CPU1_SA_DQS_DP<3>")
	)
	(segment
		(start 84.26577 -268.324076)
		(end 84.26577 -268.551914)
		(width 0.088646)
		(layer "In11.Cu")
		(net "M_D_CPU1_SA_DQS_DP<3>")
	)
	(segment
		(start 62.153292 -282.492958)
		(end 61.752734 -282.658566)
		(width 0.18288)
		(layer "In11.Cu")
		(net "M_D_CPU1_SA_DQS_DP<3>")
	)
	(segment
		(start 45.931836 -285.86811)
		(end 45.080936 -285.017464)
		(width 0.18288)
		(layer "In11.Cu")
		(net "M_D_CPU1_SA_DQS_DP<3>")
	)
	(segment
		(start 49.353978 -285.872428)
		(end 47.423578 -285.872428)
		(width 0.18288)
		(layer "In11.Cu")
		(net "M_D_CPU1_SA_DQS_DP<3>")
	)
	(segment
		(start 45.080936 -285.017464)
		(end 45.080428 -285.016956)
		(width 0.18288)
		(layer "In11.Cu")
		(net "M_D_CPU1_SA_DQS_DP<3>")
	)
	(segment
		(start 54.605682 -283.949648)
		(end 53.824886 -283.949648)
		(width 0.18288)
		(layer "In11.Cu")
		(net "M_D_CPU1_SA_DQS_DP<3>")
	)
	(segment
		(start 82.963004 -269.908274)
		(end 78.138782 -269.908274)
		(width 0.18288)
		(layer "In11.Cu")
		(net "M_D_CPU1_SA_DQS_DP<3>")
	)
	(segment
		(start 35.786568 -285.2928)
		(end 35.523932 -285.030164)
		(width 0.18288)
		(layer "In11.Cu")
		(net "M_D_CPU1_SA_DQS_DP<3>")
	)
	(segment
		(start 98.092768 -268.129258)
		(end 98.035618 -268.1224)
		(width 0.088646)
		(layer "In11.Cu")
		(net "M_D_CPU1_SA_DQS_DP<3>")
	)
	(segment
		(start 17.800574 -284.592014)
		(end 17.06372 -284.592014)
		(width 0.18288)
		(layer "In11.Cu")
		(net "M_D_CPU1_SA_DQS_DP<3>")
	)
	(segment
		(start 91.276678 -268.253972)
		(end 91.261946 -268.245336)
		(width 0.088646)
		(layer "In11.Cu")
		(net "M_D_CPU1_SA_DQS_DP<3>")
	)
	(segment
		(start 83.984592 -268.833092)
		(end 83.984592 -269.080996)
		(width 0.088646)
		(layer "In11.Cu")
		(net "M_D_CPU1_SA_DQS_DP<3>")
	)
	(segment
		(start 31.686246 -286.142684)
		(end 31.423864 -285.880302)
		(width 0.18288)
		(layer "In11.Cu")
		(net "M_D_CPU1_SA_DQS_DP<3>")
	)
	(segment
		(start 53.824886 -283.949648)
		(end 52.64785 -284.437836)
		(width 0.18288)
		(layer "In11.Cu")
		(net "M_D_CPU1_SA_DQS_DP<3>")
	)
	(segment
		(start 97.675192 -268.12494)
		(end 97.451672 -268.253718)
		(width 0.088646)
		(layer "In11.Cu")
		(net "M_D_CPU1_SA_DQS_DP<3>")
	)
	(segment
		(start 20.400772 -285.000192)
		(end 20.020788 -285.000192)
		(width 0.18288)
		(layer "In11.Cu")
		(net "M_D_CPU1_SA_DQS_DP<3>")
	)
	(segment
		(start 19.035014 -284.419294)
		(end 18.217642 -284.419294)
		(width 0.18288)
		(layer "In11.Cu")
		(net "M_D_CPU1_SA_DQS_DP<3>")
	)
	(arc
		(start 88.067896 -268.245336)
		(mid 87.785194 -268.321112)
		(end 87.502492 -268.245336)
		(width 0.088646)
		(layer "In11.Cu")
		(net "M_D_CPU1_SA_DQS_DP<3>")
	)
	(arc
		(start 96.52635 -268.245336)
		(mid 96.252151 -268.321171)
		(end 95.975678 -268.253972)
		(width 0.088646)
		(layer "In11.Cu")
		(net "M_D_CPU1_SA_DQS_DP<3>")
	)
	(arc
		(start 94.081346 -268.245336)
		(mid 93.894148 -268.195193)
		(end 93.70695 -268.245336)
		(width 0.088646)
		(layer "In11.Cu")
		(net "M_D_CPU1_SA_DQS_DP<3>")
	)
	(arc
		(start 97.451672 -268.253718)
		(mid 97.175007 -268.321189)
		(end 96.900492 -268.245336)
		(width 0.088646)
		(layer "In11.Cu")
		(net "M_D_CPU1_SA_DQS_DP<3>")
	)
	(arc
		(start 87.502492 -268.245336)
		(mid 87.315294 -268.195193)
		(end 87.128096 -268.245336)
		(width 0.088646)
		(layer "In11.Cu")
		(net "M_D_CPU1_SA_DQS_DP<3>")
	)
	(arc
		(start 95.960946 -268.245336)
		(mid 95.773748 -268.195193)
		(end 95.58655 -268.245336)
		(width 0.088646)
		(layer "In11.Cu")
		(net "M_D_CPU1_SA_DQS_DP<3>")
	)
	(arc
		(start 85.622892 -268.245336)
		(mid 85.450555 -268.195137)
		(end 85.274658 -268.230858)
		(width 0.088646)
		(layer "In11.Cu")
		(net "M_D_CPU1_SA_DQS_DP<3>")
	)
	(arc
		(start 90.321892 -268.245336)
		(mid 90.134694 -268.195193)
		(end 89.947496 -268.245336)
		(width 0.088646)
		(layer "In11.Cu")
		(net "M_D_CPU1_SA_DQS_DP<3>")
	)
	(arc
		(start 95.020892 -268.245336)
		(mid 94.833694 -268.195193)
		(end 94.646496 -268.245336)
		(width 0.088646)
		(layer "In11.Cu")
		(net "M_D_CPU1_SA_DQS_DP<3>")
	)
	(arc
		(start 99.062794 -267.755878)
		(mid 98.886773 -267.778715)
		(end 98.722434 -267.845794)
		(width 0.088646)
		(layer "In11.Cu")
		(net "M_D_CPU1_SA_DQS_DP<3>")
	)
	(arc
		(start 84.713572 -268.264386)
		(mid 84.527972 -268.227178)
		(end 84.338922 -268.2367)
		(width 0.088646)
		(layer "In11.Cu")
		(net "M_D_CPU1_SA_DQS_DP<3>")
	)
	(arc
		(start 93.141546 -268.245336)
		(mid 92.954348 -268.195193)
		(end 92.76715 -268.245336)
		(width 0.088646)
		(layer "In11.Cu")
		(net "M_D_CPU1_SA_DQS_DP<3>")
	)
	(arc
		(start 90.877136 -268.251432)
		(mid 90.598704 -268.321278)
		(end 90.321892 -268.245336)
		(width 0.088646)
		(layer "In11.Cu")
		(net "M_D_CPU1_SA_DQS_DP<3>")
	)
	(arc
		(start 86.188296 -268.245336)
		(mid 85.905594 -268.321112)
		(end 85.622892 -268.245336)
		(width 0.088646)
		(layer "In11.Cu")
		(net "M_D_CPU1_SA_DQS_DP<3>")
	)
	(arc
		(start 91.261946 -268.245336)
		(mid 91.074748 -268.195193)
		(end 90.88755 -268.245336)
		(width 0.088646)
		(layer "In11.Cu")
		(net "M_D_CPU1_SA_DQS_DP<3>")
	)
	(arc
		(start 93.70695 -268.245336)
		(mid 93.432751 -268.321171)
		(end 93.156278 -268.253972)
		(width 0.088646)
		(layer "In11.Cu")
		(net "M_D_CPU1_SA_DQS_DP<3>")
	)
	(arc
		(start 86.562692 -268.245336)
		(mid 86.375494 -268.195193)
		(end 86.188296 -268.245336)
		(width 0.088646)
		(layer "In11.Cu")
		(net "M_D_CPU1_SA_DQS_DP<3>")
	)
	(arc
		(start 94.646496 -268.245336)
		(mid 94.369937 -268.321079)
		(end 94.09176 -268.251432)
		(width 0.088646)
		(layer "In11.Cu")
		(net "M_D_CPU1_SA_DQS_DP<3>")
	)
	(arc
		(start 89.947496 -268.245336)
		(mid 89.664794 -268.321112)
		(end 89.382092 -268.245336)
		(width 0.088646)
		(layer "In11.Cu")
		(net "M_D_CPU1_SA_DQS_DP<3>")
	)
	(arc
		(start 92.201746 -268.245336)
		(mid 92.014548 -268.195193)
		(end 91.82735 -268.245336)
		(width 0.088646)
		(layer "In11.Cu")
		(net "M_D_CPU1_SA_DQS_DP<3>")
	)
	(arc
		(start 98.297238 -268.087602)
		(mid 98.198396 -268.125112)
		(end 98.092768 -268.129258)
		(width 0.088646)
		(layer "In11.Cu")
		(net "M_D_CPU1_SA_DQS_DP<3>")
	)
	(arc
		(start 85.274658 -268.230858)
		(mid 84.997352 -268.301752)
		(end 84.713572 -268.264386)
		(width 0.088646)
		(layer "In11.Cu")
		(net "M_D_CPU1_SA_DQS_DP<3>")
	)
	(arc
		(start 89.382092 -268.245336)
		(mid 89.194894 -268.195193)
		(end 89.007696 -268.245336)
		(width 0.088646)
		(layer "In11.Cu")
		(net "M_D_CPU1_SA_DQS_DP<3>")
	)
	(arc
		(start 96.900746 -268.245336)
		(mid 96.713548 -268.195193)
		(end 96.52635 -268.245336)
		(width 0.088646)
		(layer "In11.Cu")
		(net "M_D_CPU1_SA_DQS_DP<3>")
	)
	(arc
		(start 95.58655 -268.245336)
		(mid 95.309737 -268.321206)
		(end 95.031306 -268.251432)
		(width 0.088646)
		(layer "In11.Cu")
		(net "M_D_CPU1_SA_DQS_DP<3>")
	)
	(arc
		(start 89.007696 -268.245336)
		(mid 88.724994 -268.321112)
		(end 88.442292 -268.245336)
		(width 0.088646)
		(layer "In11.Cu")
		(net "M_D_CPU1_SA_DQS_DP<3>")
	)
	(arc
		(start 87.128096 -268.245336)
		(mid 86.845394 -268.321112)
		(end 86.562692 -268.245336)
		(width 0.088646)
		(layer "In11.Cu")
		(net "M_D_CPU1_SA_DQS_DP<3>")
	)
	(arc
		(start 91.82735 -268.245336)
		(mid 91.553151 -268.321171)
		(end 91.276678 -268.253972)
		(width 0.088646)
		(layer "In11.Cu")
		(net "M_D_CPU1_SA_DQS_DP<3>")
	)
	(arc
		(start 88.442292 -268.245336)
		(mid 88.255094 -268.195193)
		(end 88.067896 -268.245336)
		(width 0.088646)
		(layer "In11.Cu")
		(net "M_D_CPU1_SA_DQS_DP<3>")
	)
	(arc
		(start 84.338922 -268.2367)
		(mid 84.28641 -268.267069)
		(end 84.26577 -268.324076)
		(width 0.088646)
		(layer "In11.Cu")
		(net "M_D_CPU1_SA_DQS_DP<3>")
	)
	(arc
		(start 92.76715 -268.245336)
		(mid 92.492951 -268.321171)
		(end 92.216478 -268.253972)
		(width 0.088646)
		(layer "In11.Cu")
		(net "M_D_CPU1_SA_DQS_DP<3>")
	)
	(segment
		(start 11.125708 -294.641778)
		(end 11.11631 -294.651176)
		(width 0.101854)
		(layer "F.Cu")
		(net "M_D_CPU1_SA_DQS_DP<2>")
	)
	(segment
		(start 11.11631 -294.651176)
		(end 10.898124 -294.651176)
		(width 0.20066)
		(layer "F.Cu")
		(net "M_D_CPU1_SA_DQS_DP<2>")
	)
	(segment
		(start 13.854684 -294.380666)
		(end 13.593572 -294.641778)
		(width 0.20066)
		(layer "F.Cu")
		(net "M_D_CPU1_SA_DQS_DP<2>")
	)
	(segment
		(start 11.36269 -294.641778)
		(end 11.125708 -294.641778)
		(width 0.101854)
		(layer "F.Cu")
		(net "M_D_CPU1_SA_DQS_DP<2>")
	)
	(segment
		(start 14.605762 -293.95547)
		(end 14.180566 -294.380666)
		(width 0.20066)
		(layer "F.Cu")
		(net "M_D_CPU1_SA_DQS_DP<2>")
	)
	(segment
		(start 15.684246 -294.216582)
		(end 15.135606 -294.216582)
		(width 0.20066)
		(layer "F.Cu")
		(net "M_D_CPU1_SA_DQS_DP<2>")
	)
	(segment
		(start 10.627614 -294.380666)
		(end 10.000488 -294.380666)
		(width 0.20066)
		(layer "F.Cu")
		(net "M_D_CPU1_SA_DQS_DP<2>")
	)
	(segment
		(start 14.874494 -293.95547)
		(end 14.605762 -293.95547)
		(width 0.20066)
		(layer "F.Cu")
		(net "M_D_CPU1_SA_DQS_DP<2>")
	)
	(segment
		(start 13.441426 -294.641778)
		(end 13.118084 -294.641778)
		(width 0.101854)
		(layer "F.Cu")
		(net "M_D_CPU1_SA_DQS_DP<2>")
	)
	(segment
		(start 13.593572 -294.641778)
		(end 13.441426 -294.641778)
		(width 0.20066)
		(layer "F.Cu")
		(net "M_D_CPU1_SA_DQS_DP<2>")
	)
	(segment
		(start 15.135606 -294.216582)
		(end 14.874494 -293.95547)
		(width 0.20066)
		(layer "F.Cu")
		(net "M_D_CPU1_SA_DQS_DP<2>")
	)
	(segment
		(start 8.678418 -294.216582)
		(end 8.140446 -294.216582)
		(width 0.20066)
		(layer "F.Cu")
		(net "M_D_CPU1_SA_DQS_DP<2>")
	)
	(segment
		(start 8.93953 -293.95547)
		(end 8.678418 -294.216582)
		(width 0.20066)
		(layer "F.Cu")
		(net "M_D_CPU1_SA_DQS_DP<2>")
	)
	(segment
		(start 9.364472 -293.95547)
		(end 8.93953 -293.95547)
		(width 0.20066)
		(layer "F.Cu")
		(net "M_D_CPU1_SA_DQS_DP<2>")
	)
	(segment
		(start 15.684246 -294.216582)
		(end 16.789146 -294.216582)
		(width 0.20066)
		(layer "F.Cu")
		(net "M_D_CPU1_SA_DQS_DP<2>")
	)
	(segment
		(start 10.000488 -294.380666)
		(end 9.364472 -293.95547)
		(width 0.20066)
		(layer "F.Cu")
		(net "M_D_CPU1_SA_DQS_DP<2>")
	)
	(segment
		(start 14.180566 -294.380666)
		(end 13.854684 -294.380666)
		(width 0.20066)
		(layer "F.Cu")
		(net "M_D_CPU1_SA_DQS_DP<2>")
	)
	(segment
		(start 13.118084 -294.641778)
		(end 11.36269 -294.641778)
		(width 0.1016)
		(layer "F.Cu")
		(net "M_D_CPU1_SA_DQS_DP<2>")
	)
	(segment
		(start 10.898124 -294.651176)
		(end 10.627614 -294.380666)
		(width 0.20066)
		(layer "F.Cu")
		(net "M_D_CPU1_SA_DQS_DP<2>")
	)
	(arc
		(start 99.063048 -272.103342)
		(mid 99.062984 -272.371312)
		(end 99.062794 -272.639282)
		(width 0.20066)
		(layer "F.Cu")
		(net "M_D_CPU1_SA_DQS_DP<2>")
	)
	(segment
		(start 29.327602 -297.510454)
		(end 28.53309 -297.181778)
		(width 0.18288)
		(layer "In11.Cu")
		(net "M_D_CPU1_SA_DQS_DP<2>")
	)
	(segment
		(start 52.136802 -296.065194)
		(end 51.527456 -296.065194)
		(width 0.18288)
		(layer "In11.Cu")
		(net "M_D_CPU1_SA_DQS_DP<2>")
	)
	(segment
		(start 46.480222 -296.933366)
		(end 45.988478 -296.933366)
		(width 0.18288)
		(layer "In11.Cu")
		(net "M_D_CPU1_SA_DQS_DP<2>")
	)
	(segment
		(start 51.527456 -296.065194)
		(end 51.251866 -296.340784)
		(width 0.18288)
		(layer "In11.Cu")
		(net "M_D_CPU1_SA_DQS_DP<2>")
	)
	(segment
		(start 27.277314 -295.925748)
		(end 26.293572 -295.268396)
		(width 0.18288)
		(layer "In11.Cu")
		(net "M_D_CPU1_SA_DQS_DP<2>")
	)
	(segment
		(start 32.433514 -296.896282)
		(end 32.138874 -297.190922)
		(width 0.18288)
		(layer "In11.Cu")
		(net "M_D_CPU1_SA_DQS_DP<2>")
	)
	(segment
		(start 31.650178 -297.190922)
		(end 31.401512 -296.942256)
		(width 0.18288)
		(layer "In11.Cu")
		(net "M_D_CPU1_SA_DQS_DP<2>")
	)
	(segment
		(start 83.98256 -275.331936)
		(end 83.451192 -275.863304)
		(width 0.088646)
		(layer "In11.Cu")
		(net "M_D_CPU1_SA_DQS_DP<2>")
	)
	(segment
		(start 94.09176 -273.134836)
		(end 94.081346 -273.12874)
		(width 0.088646)
		(layer "In11.Cu")
		(net "M_D_CPU1_SA_DQS_DP<2>")
	)
	(segment
		(start 28.53309 -297.181778)
		(end 27.277314 -295.925748)
		(width 0.18288)
		(layer "In11.Cu")
		(net "M_D_CPU1_SA_DQS_DP<2>")
	)
	(segment
		(start 17.466818 -293.94277)
		(end 17.062958 -293.94277)
		(width 0.18288)
		(layer "In11.Cu")
		(net "M_D_CPU1_SA_DQS_DP<2>")
	)
	(segment
		(start 59.128914 -292.420548)
		(end 55.484522 -293.931086)
		(width 0.18288)
		(layer "In11.Cu")
		(net "M_D_CPU1_SA_DQS_DP<2>")
	)
	(segment
		(start 98.722434 -272.729198)
		(end 98.297238 -272.971006)
		(width 0.088646)
		(layer "In11.Cu")
		(net "M_D_CPU1_SA_DQS_DP<2>")
	)
	(segment
		(start 93.156278 -273.137376)
		(end 93.141546 -273.12874)
		(width 0.088646)
		(layer "In11.Cu")
		(net "M_D_CPU1_SA_DQS_DP<2>")
	)
	(segment
		(start 98.030792 -273.008344)
		(end 97.675192 -273.008344)
		(width 0.088646)
		(layer "In11.Cu")
		(net "M_D_CPU1_SA_DQS_DP<2>")
	)
	(segment
		(start 40.316658 -295.346628)
		(end 39.887144 -295.776142)
		(width 0.18288)
		(layer "In11.Cu")
		(net "M_D_CPU1_SA_DQS_DP<2>")
	)
	(segment
		(start 50.837846 -296.340784)
		(end 50.569114 -296.072052)
		(width 0.18288)
		(layer "In11.Cu")
		(net "M_D_CPU1_SA_DQS_DP<2>")
	)
	(segment
		(start 53.589936 -295.197276)
		(end 53.135784 -295.651428)
		(width 0.18288)
		(layer "In11.Cu")
		(net "M_D_CPU1_SA_DQS_DP<2>")
	)
	(segment
		(start 95.975678 -273.137376)
		(end 95.960946 -273.12874)
		(width 0.088646)
		(layer "In11.Cu")
		(net "M_D_CPU1_SA_DQS_DP<2>")
	)
	(segment
		(start 83.98256 -274.64004)
		(end 83.98256 -275.331936)
		(width 0.088646)
		(layer "In11.Cu")
		(net "M_D_CPU1_SA_DQS_DP<2>")
	)
	(segment
		(start 47.429166 -296.916094)
		(end 47.154338 -297.190922)
		(width 0.18288)
		(layer "In11.Cu")
		(net "M_D_CPU1_SA_DQS_DP<2>")
	)
	(segment
		(start 59.987688 -291.561774)
		(end 59.128914 -292.420548)
		(width 0.18288)
		(layer "In11.Cu")
		(net "M_D_CPU1_SA_DQS_DP<2>")
	)
	(segment
		(start 85.170772 -273.187922)
		(end 84.859114 -273.49958)
		(width 0.088646)
		(layer "In11.Cu")
		(net "M_D_CPU1_SA_DQS_DP<2>")
	)
	(segment
		(start 44.478194 -296.2275)
		(end 43.899328 -296.806366)
		(width 0.18288)
		(layer "In11.Cu")
		(net "M_D_CPU1_SA_DQS_DP<2>")
	)
	(segment
		(start 39.887144 -295.776142)
		(end 39.152576 -296.080434)
		(width 0.18288)
		(layer "In11.Cu")
		(net "M_D_CPU1_SA_DQS_DP<2>")
	)
	(segment
		(start 89.007696 -273.12874)
		(end 88.992964 -273.137376)
		(width 0.088646)
		(layer "In11.Cu")
		(net "M_D_CPU1_SA_DQS_DP<2>")
	)
	(segment
		(start 67.004184 -290.258246)
		(end 66.541904 -290.720526)
		(width 0.18288)
		(layer "In11.Cu")
		(net "M_D_CPU1_SA_DQS_DP<2>")
	)
	(segment
		(start 44.840398 -296.2275)
		(end 44.478194 -296.2275)
		(width 0.18288)
		(layer "In11.Cu")
		(net "M_D_CPU1_SA_DQS_DP<2>")
	)
	(segment
		(start 36.46932 -296.080434)
		(end 36.20897 -296.340784)
		(width 0.18288)
		(layer "In11.Cu")
		(net "M_D_CPU1_SA_DQS_DP<2>")
	)
	(segment
		(start 39.152576 -296.080434)
		(end 36.46932 -296.080434)
		(width 0.18288)
		(layer "In11.Cu")
		(net "M_D_CPU1_SA_DQS_DP<2>")
	)
	(segment
		(start 43.133772 -296.806366)
		(end 41.674034 -295.346628)
		(width 0.18288)
		(layer "In11.Cu")
		(net "M_D_CPU1_SA_DQS_DP<2>")
	)
	(segment
		(start 64.619124 -290.720526)
		(end 62.585346 -291.561774)
		(width 0.18288)
		(layer "In11.Cu")
		(net "M_D_CPU1_SA_DQS_DP<2>")
	)
	(segment
		(start 96.900492 -273.12874)
		(end 96.900746 -273.12874)
		(width 0.088646)
		(layer "In11.Cu")
		(net "M_D_CPU1_SA_DQS_DP<2>")
	)
	(segment
		(start 47.154338 -297.190922)
		(end 46.737778 -297.190922)
		(width 0.18288)
		(layer "In11.Cu")
		(net "M_D_CPU1_SA_DQS_DP<2>")
	)
	(segment
		(start 48.478186 -296.916094)
		(end 47.429166 -296.916094)
		(width 0.18288)
		(layer "In11.Cu")
		(net "M_D_CPU1_SA_DQS_DP<2>")
	)
	(segment
		(start 29.831284 -297.510454)
		(end 29.327602 -297.510454)
		(width 0.18288)
		(layer "In11.Cu")
		(net "M_D_CPU1_SA_DQS_DP<2>")
	)
	(segment
		(start 85.637878 -273.137376)
		(end 85.623146 -273.12874)
		(width 0.088646)
		(layer "In11.Cu")
		(net "M_D_CPU1_SA_DQS_DP<2>")
	)
	(segment
		(start 21.166074 -294.642794)
		(end 20.710144 -294.642794)
		(width 0.18288)
		(layer "In11.Cu")
		(net "M_D_CPU1_SA_DQS_DP<2>")
	)
	(segment
		(start 98.035618 -273.005804)
		(end 98.030792 -273.008344)
		(width 0.088646)
		(layer "In11.Cu")
		(net "M_D_CPU1_SA_DQS_DP<2>")
	)
	(segment
		(start 90.88755 -273.12874)
		(end 90.877136 -273.134836)
		(width 0.088646)
		(layer "In11.Cu")
		(net "M_D_CPU1_SA_DQS_DP<2>")
	)
	(segment
		(start 18.742406 -293.699184)
		(end 18.054828 -293.699184)
		(width 0.18288)
		(layer "In11.Cu")
		(net "M_D_CPU1_SA_DQS_DP<2>")
	)
	(segment
		(start 19.782536 -294.375586)
		(end 19.362674 -293.955978)
		(width 0.18288)
		(layer "In11.Cu")
		(net "M_D_CPU1_SA_DQS_DP<2>")
	)
	(segment
		(start 41.674034 -295.346628)
		(end 40.316658 -295.346628)
		(width 0.18288)
		(layer "In11.Cu")
		(net "M_D_CPU1_SA_DQS_DP<2>")
	)
	(segment
		(start 98.092768 -273.012662)
		(end 98.035618 -273.005804)
		(width 0.088646)
		(layer "In11.Cu")
		(net "M_D_CPU1_SA_DQS_DP<2>")
	)
	(segment
		(start 55.484522 -293.931086)
		(end 53.589936 -295.197276)
		(width 0.18288)
		(layer "In11.Cu")
		(net "M_D_CPU1_SA_DQS_DP<2>")
	)
	(segment
		(start 87.128096 -273.12874)
		(end 87.117682 -273.134836)
		(width 0.088646)
		(layer "In11.Cu")
		(net "M_D_CPU1_SA_DQS_DP<2>")
	)
	(segment
		(start 95.031306 -273.134836)
		(end 95.020892 -273.12874)
		(width 0.088646)
		(layer "In11.Cu")
		(net "M_D_CPU1_SA_DQS_DP<2>")
	)
	(segment
		(start 35.78479 -296.340784)
		(end 35.526218 -296.082212)
		(width 0.18288)
		(layer "In11.Cu")
		(net "M_D_CPU1_SA_DQS_DP<2>")
	)
	(segment
		(start 32.138874 -297.190922)
		(end 31.650178 -297.190922)
		(width 0.18288)
		(layer "In11.Cu")
		(net "M_D_CPU1_SA_DQS_DP<2>")
	)
	(segment
		(start 24.060404 -294.34409)
		(end 21.464778 -294.34409)
		(width 0.18288)
		(layer "In11.Cu")
		(net "M_D_CPU1_SA_DQS_DP<2>")
	)
	(segment
		(start 97.675192 -273.008344)
		(end 97.451672 -273.137122)
		(width 0.088646)
		(layer "In11.Cu")
		(net "M_D_CPU1_SA_DQS_DP<2>")
	)
	(segment
		(start 80.842104 -275.923248)
		(end 67.004184 -289.761168)
		(width 0.18288)
		(layer "In11.Cu")
		(net "M_D_CPU1_SA_DQS_DP<2>")
	)
	(segment
		(start 92.216478 -273.137376)
		(end 92.201746 -273.12874)
		(width 0.088646)
		(layer "In11.Cu")
		(net "M_D_CPU1_SA_DQS_DP<2>")
	)
	(segment
		(start 66.541904 -290.720526)
		(end 64.619124 -290.720526)
		(width 0.18288)
		(layer "In11.Cu")
		(net "M_D_CPU1_SA_DQS_DP<2>")
	)
	(segment
		(start 83.451192 -275.863304)
		(end 83.124802 -275.863304)
		(width 0.088646)
		(layer "In11.Cu")
		(net "M_D_CPU1_SA_DQS_DP<2>")
	)
	(segment
		(start 35.343846 -296.082212)
		(end 33.378902 -296.896282)
		(width 0.18288)
		(layer "In11.Cu")
		(net "M_D_CPU1_SA_DQS_DP<2>")
	)
	(segment
		(start 51.251866 -296.340784)
		(end 50.837846 -296.340784)
		(width 0.18288)
		(layer "In11.Cu")
		(net "M_D_CPU1_SA_DQS_DP<2>")
	)
	(segment
		(start 49.283112 -296.582846)
		(end 48.478186 -296.916094)
		(width 0.18288)
		(layer "In11.Cu")
		(net "M_D_CPU1_SA_DQS_DP<2>")
	)
	(segment
		(start 20.442936 -294.375586)
		(end 19.782536 -294.375586)
		(width 0.18288)
		(layer "In11.Cu")
		(net "M_D_CPU1_SA_DQS_DP<2>")
	)
	(segment
		(start 49.64303 -296.222928)
		(end 49.283112 -296.582846)
		(width 0.18288)
		(layer "In11.Cu")
		(net "M_D_CPU1_SA_DQS_DP<2>")
	)
	(segment
		(start 20.710144 -294.642794)
		(end 20.442936 -294.375586)
		(width 0.18288)
		(layer "In11.Cu")
		(net "M_D_CPU1_SA_DQS_DP<2>")
	)
	(segment
		(start 21.464778 -294.34409)
		(end 21.166074 -294.642794)
		(width 0.18288)
		(layer "In11.Cu")
		(net "M_D_CPU1_SA_DQS_DP<2>")
	)
	(segment
		(start 67.004184 -289.761168)
		(end 67.004184 -290.258246)
		(width 0.18288)
		(layer "In11.Cu")
		(net "M_D_CPU1_SA_DQS_DP<2>")
	)
	(segment
		(start 43.899328 -296.806366)
		(end 43.133772 -296.806366)
		(width 0.18288)
		(layer "In11.Cu")
		(net "M_D_CPU1_SA_DQS_DP<2>")
	)
	(segment
		(start 31.401512 -296.942256)
		(end 31.06293 -296.942256)
		(width 0.18288)
		(layer "In11.Cu")
		(net "M_D_CPU1_SA_DQS_DP<2>")
	)
	(segment
		(start 33.378902 -296.896282)
		(end 32.433514 -296.896282)
		(width 0.18288)
		(layer "In11.Cu")
		(net "M_D_CPU1_SA_DQS_DP<2>")
	)
	(segment
		(start 50.007012 -296.072052)
		(end 49.64303 -296.222928)
		(width 0.18288)
		(layer "In11.Cu")
		(net "M_D_CPU1_SA_DQS_DP<2>")
	)
	(segment
		(start 18.054828 -293.699184)
		(end 17.466818 -293.94277)
		(width 0.18288)
		(layer "In11.Cu")
		(net "M_D_CPU1_SA_DQS_DP<2>")
	)
	(segment
		(start 36.20897 -296.340784)
		(end 35.78479 -296.340784)
		(width 0.18288)
		(layer "In11.Cu")
		(net "M_D_CPU1_SA_DQS_DP<2>")
	)
	(segment
		(start 46.737778 -297.190922)
		(end 46.480222 -296.933366)
		(width 0.18288)
		(layer "In11.Cu")
		(net "M_D_CPU1_SA_DQS_DP<2>")
	)
	(segment
		(start 50.569114 -296.072052)
		(end 50.007012 -296.072052)
		(width 0.18288)
		(layer "In11.Cu")
		(net "M_D_CPU1_SA_DQS_DP<2>")
	)
	(segment
		(start 45.988478 -296.933366)
		(end 45.596048 -296.540936)
		(width 0.18288)
		(layer "In11.Cu")
		(net "M_D_CPU1_SA_DQS_DP<2>")
	)
	(segment
		(start 19.362674 -293.955978)
		(end 18.742406 -293.699184)
		(width 0.18288)
		(layer "In11.Cu")
		(net "M_D_CPU1_SA_DQS_DP<2>")
	)
	(segment
		(start 45.596048 -296.540936)
		(end 44.840398 -296.2275)
		(width 0.18288)
		(layer "In11.Cu")
		(net "M_D_CPU1_SA_DQS_DP<2>")
	)
	(segment
		(start 26.293572 -295.268396)
		(end 24.060404 -294.34409)
		(width 0.18288)
		(layer "In11.Cu")
		(net "M_D_CPU1_SA_DQS_DP<2>")
	)
	(segment
		(start 84.859114 -273.763486)
		(end 83.98256 -274.64004)
		(width 0.088646)
		(layer "In11.Cu")
		(net "M_D_CPU1_SA_DQS_DP<2>")
	)
	(segment
		(start 84.859114 -273.49958)
		(end 84.859114 -273.763486)
		(width 0.088646)
		(layer "In11.Cu")
		(net "M_D_CPU1_SA_DQS_DP<2>")
	)
	(segment
		(start 83.064858 -275.923248)
		(end 80.842104 -275.923248)
		(width 0.18288)
		(layer "In11.Cu")
		(net "M_D_CPU1_SA_DQS_DP<2>")
	)
	(segment
		(start 83.124802 -275.863304)
		(end 83.064858 -275.923248)
		(width 0.088646)
		(layer "In11.Cu")
		(net "M_D_CPU1_SA_DQS_DP<2>")
	)
	(segment
		(start 35.526218 -296.082212)
		(end 35.343846 -296.082212)
		(width 0.18288)
		(layer "In11.Cu")
		(net "M_D_CPU1_SA_DQS_DP<2>")
	)
	(segment
		(start 62.585346 -291.561774)
		(end 59.987688 -291.561774)
		(width 0.18288)
		(layer "In11.Cu")
		(net "M_D_CPU1_SA_DQS_DP<2>")
	)
	(segment
		(start 53.135784 -295.651428)
		(end 52.136802 -296.065194)
		(width 0.18288)
		(layer "In11.Cu")
		(net "M_D_CPU1_SA_DQS_DP<2>")
	)
	(segment
		(start 17.062958 -293.94277)
		(end 16.789146 -294.216582)
		(width 0.18288)
		(layer "In11.Cu")
		(net "M_D_CPU1_SA_DQS_DP<2>")
	)
	(segment
		(start 31.06293 -296.942256)
		(end 29.831284 -297.510454)
		(width 0.18288)
		(layer "In11.Cu")
		(net "M_D_CPU1_SA_DQS_DP<2>")
	)
	(segment
		(start 91.276678 -273.137376)
		(end 91.261946 -273.12874)
		(width 0.088646)
		(layer "In11.Cu")
		(net "M_D_CPU1_SA_DQS_DP<2>")
	)
	(arc
		(start 96.52635 -273.12874)
		(mid 96.252151 -273.204575)
		(end 95.975678 -273.137376)
		(width 0.088646)
		(layer "In11.Cu")
		(net "M_D_CPU1_SA_DQS_DP<2>")
	)
	(arc
		(start 86.562946 -273.12874)
		(mid 86.375748 -273.078597)
		(end 86.18855 -273.12874)
		(width 0.088646)
		(layer "In11.Cu")
		(net "M_D_CPU1_SA_DQS_DP<2>")
	)
	(arc
		(start 95.960946 -273.12874)
		(mid 95.773748 -273.078597)
		(end 95.58655 -273.12874)
		(width 0.088646)
		(layer "In11.Cu")
		(net "M_D_CPU1_SA_DQS_DP<2>")
	)
	(arc
		(start 99.062794 -272.639282)
		(mid 98.886773 -272.662119)
		(end 98.722434 -272.729198)
		(width 0.088646)
		(layer "In11.Cu")
		(net "M_D_CPU1_SA_DQS_DP<2>")
	)
	(arc
		(start 96.900746 -273.12874)
		(mid 96.713548 -273.078597)
		(end 96.52635 -273.12874)
		(width 0.088646)
		(layer "In11.Cu")
		(net "M_D_CPU1_SA_DQS_DP<2>")
	)
	(arc
		(start 94.081346 -273.12874)
		(mid 93.894148 -273.078597)
		(end 93.70695 -273.12874)
		(width 0.088646)
		(layer "In11.Cu")
		(net "M_D_CPU1_SA_DQS_DP<2>")
	)
	(arc
		(start 94.646496 -273.12874)
		(mid 94.369937 -273.204483)
		(end 94.09176 -273.134836)
		(width 0.088646)
		(layer "In11.Cu")
		(net "M_D_CPU1_SA_DQS_DP<2>")
	)
	(arc
		(start 90.877136 -273.134836)
		(mid 90.598704 -273.204682)
		(end 90.321892 -273.12874)
		(width 0.088646)
		(layer "In11.Cu")
		(net "M_D_CPU1_SA_DQS_DP<2>")
	)
	(arc
		(start 86.18855 -273.12874)
		(mid 85.914351 -273.204575)
		(end 85.637878 -273.137376)
		(width 0.088646)
		(layer "In11.Cu")
		(net "M_D_CPU1_SA_DQS_DP<2>")
	)
	(arc
		(start 89.382092 -273.12874)
		(mid 89.194894 -273.078597)
		(end 89.007696 -273.12874)
		(width 0.088646)
		(layer "In11.Cu")
		(net "M_D_CPU1_SA_DQS_DP<2>")
	)
	(arc
		(start 92.201746 -273.12874)
		(mid 92.014548 -273.078597)
		(end 91.82735 -273.12874)
		(width 0.088646)
		(layer "In11.Cu")
		(net "M_D_CPU1_SA_DQS_DP<2>")
	)
	(arc
		(start 85.24875 -273.12874)
		(mid 85.21979 -273.147017)
		(end 85.192616 -273.167856)
		(width 0.088646)
		(layer "In11.Cu")
		(net "M_D_CPU1_SA_DQS_DP<2>")
	)
	(arc
		(start 92.76715 -273.12874)
		(mid 92.492951 -273.204575)
		(end 92.216478 -273.137376)
		(width 0.088646)
		(layer "In11.Cu")
		(net "M_D_CPU1_SA_DQS_DP<2>")
	)
	(arc
		(start 93.70695 -273.12874)
		(mid 93.432751 -273.204575)
		(end 93.156278 -273.137376)
		(width 0.088646)
		(layer "In11.Cu")
		(net "M_D_CPU1_SA_DQS_DP<2>")
	)
	(arc
		(start 91.82735 -273.12874)
		(mid 91.553151 -273.204575)
		(end 91.276678 -273.137376)
		(width 0.088646)
		(layer "In11.Cu")
		(net "M_D_CPU1_SA_DQS_DP<2>")
	)
	(arc
		(start 85.623146 -273.12874)
		(mid 85.435948 -273.078597)
		(end 85.24875 -273.12874)
		(width 0.088646)
		(layer "In11.Cu")
		(net "M_D_CPU1_SA_DQS_DP<2>")
	)
	(arc
		(start 91.261946 -273.12874)
		(mid 91.074748 -273.078597)
		(end 90.88755 -273.12874)
		(width 0.088646)
		(layer "In11.Cu")
		(net "M_D_CPU1_SA_DQS_DP<2>")
	)
	(arc
		(start 98.297238 -272.971006)
		(mid 98.198396 -273.008516)
		(end 98.092768 -273.012662)
		(width 0.088646)
		(layer "In11.Cu")
		(net "M_D_CPU1_SA_DQS_DP<2>")
	)
	(arc
		(start 87.117682 -273.134836)
		(mid 86.839504 -273.204559)
		(end 86.562946 -273.12874)
		(width 0.088646)
		(layer "In11.Cu")
		(net "M_D_CPU1_SA_DQS_DP<2>")
	)
	(arc
		(start 88.992964 -273.137376)
		(mid 88.716489 -273.204696)
		(end 88.442292 -273.12874)
		(width 0.088646)
		(layer "In11.Cu")
		(net "M_D_CPU1_SA_DQS_DP<2>")
	)
	(arc
		(start 89.947496 -273.12874)
		(mid 89.664794 -273.204516)
		(end 89.382092 -273.12874)
		(width 0.088646)
		(layer "In11.Cu")
		(net "M_D_CPU1_SA_DQS_DP<2>")
	)
	(arc
		(start 95.58655 -273.12874)
		(mid 95.309737 -273.20461)
		(end 95.031306 -273.134836)
		(width 0.088646)
		(layer "In11.Cu")
		(net "M_D_CPU1_SA_DQS_DP<2>")
	)
	(arc
		(start 87.502492 -273.12874)
		(mid 87.315294 -273.078597)
		(end 87.128096 -273.12874)
		(width 0.088646)
		(layer "In11.Cu")
		(net "M_D_CPU1_SA_DQS_DP<2>")
	)
	(arc
		(start 85.192616 -273.167856)
		(mid 85.181495 -273.177672)
		(end 85.170772 -273.187922)
		(width 0.088646)
		(layer "In11.Cu")
		(net "M_D_CPU1_SA_DQS_DP<2>")
	)
	(arc
		(start 90.321892 -273.12874)
		(mid 90.134694 -273.078597)
		(end 89.947496 -273.12874)
		(width 0.088646)
		(layer "In11.Cu")
		(net "M_D_CPU1_SA_DQS_DP<2>")
	)
	(arc
		(start 88.067896 -273.12874)
		(mid 87.785194 -273.204516)
		(end 87.502492 -273.12874)
		(width 0.088646)
		(layer "In11.Cu")
		(net "M_D_CPU1_SA_DQS_DP<2>")
	)
	(arc
		(start 97.451672 -273.137122)
		(mid 97.175007 -273.204593)
		(end 96.900492 -273.12874)
		(width 0.088646)
		(layer "In11.Cu")
		(net "M_D_CPU1_SA_DQS_DP<2>")
	)
	(arc
		(start 95.020892 -273.12874)
		(mid 94.833694 -273.078597)
		(end 94.646496 -273.12874)
		(width 0.088646)
		(layer "In11.Cu")
		(net "M_D_CPU1_SA_DQS_DP<2>")
	)
	(arc
		(start 93.141546 -273.12874)
		(mid 92.954348 -273.078597)
		(end 92.76715 -273.12874)
		(width 0.088646)
		(layer "In11.Cu")
		(net "M_D_CPU1_SA_DQS_DP<2>")
	)
	(arc
		(start 88.442292 -273.12874)
		(mid 88.255094 -273.078597)
		(end 88.067896 -273.12874)
		(width 0.088646)
		(layer "In11.Cu")
		(net "M_D_CPU1_SA_DQS_DP<2>")
	)
	(segment
		(start 14.605762 -303.305464)
		(end 14.180566 -303.73066)
		(width 0.20066)
		(layer "F.Cu")
		(net "M_D_CPU1_SA_DQS_DP<1>")
	)
	(segment
		(start 14.874494 -303.305464)
		(end 14.605762 -303.305464)
		(width 0.20066)
		(layer "F.Cu")
		(net "M_D_CPU1_SA_DQS_DP<1>")
	)
	(segment
		(start 15.135606 -303.566576)
		(end 14.874494 -303.305464)
		(width 0.20066)
		(layer "F.Cu")
		(net "M_D_CPU1_SA_DQS_DP<1>")
	)
	(segment
		(start 13.854684 -303.73066)
		(end 13.593572 -303.991772)
		(width 0.20066)
		(layer "F.Cu")
		(net "M_D_CPU1_SA_DQS_DP<1>")
	)
	(segment
		(start 15.684246 -303.566576)
		(end 15.135606 -303.566576)
		(width 0.20066)
		(layer "F.Cu")
		(net "M_D_CPU1_SA_DQS_DP<1>")
	)
	(segment
		(start 10.000488 -303.73066)
		(end 9.364472 -303.305464)
		(width 0.20066)
		(layer "F.Cu")
		(net "M_D_CPU1_SA_DQS_DP<1>")
	)
	(segment
		(start 10.898124 -304.00117)
		(end 10.627614 -303.73066)
		(width 0.20066)
		(layer "F.Cu")
		(net "M_D_CPU1_SA_DQS_DP<1>")
	)
	(segment
		(start 9.364472 -303.305464)
		(end 8.93953 -303.305464)
		(width 0.20066)
		(layer "F.Cu")
		(net "M_D_CPU1_SA_DQS_DP<1>")
	)
	(segment
		(start 8.678418 -303.566576)
		(end 8.140446 -303.566576)
		(width 0.20066)
		(layer "F.Cu")
		(net "M_D_CPU1_SA_DQS_DP<1>")
	)
	(segment
		(start 15.684246 -303.566576)
		(end 16.789146 -303.566576)
		(width 0.20066)
		(layer "F.Cu")
		(net "M_D_CPU1_SA_DQS_DP<1>")
	)
	(segment
		(start 11.125708 -303.991772)
		(end 11.11631 -304.00117)
		(width 0.101854)
		(layer "F.Cu")
		(net "M_D_CPU1_SA_DQS_DP<1>")
	)
	(segment
		(start 13.118084 -303.991772)
		(end 11.36269 -303.991772)
		(width 0.1016)
		(layer "F.Cu")
		(net "M_D_CPU1_SA_DQS_DP<1>")
	)
	(segment
		(start 10.627614 -303.73066)
		(end 10.000488 -303.73066)
		(width 0.20066)
		(layer "F.Cu")
		(net "M_D_CPU1_SA_DQS_DP<1>")
	)
	(segment
		(start 11.36269 -303.991772)
		(end 11.125708 -303.991772)
		(width 0.101854)
		(layer "F.Cu")
		(net "M_D_CPU1_SA_DQS_DP<1>")
	)
	(segment
		(start 8.93953 -303.305464)
		(end 8.678418 -303.566576)
		(width 0.20066)
		(layer "F.Cu")
		(net "M_D_CPU1_SA_DQS_DP<1>")
	)
	(segment
		(start 13.441426 -303.991772)
		(end 13.118084 -303.991772)
		(width 0.101854)
		(layer "F.Cu")
		(net "M_D_CPU1_SA_DQS_DP<1>")
	)
	(segment
		(start 13.593572 -303.991772)
		(end 13.441426 -303.991772)
		(width 0.20066)
		(layer "F.Cu")
		(net "M_D_CPU1_SA_DQS_DP<1>")
	)
	(segment
		(start 14.180566 -303.73066)
		(end 13.854684 -303.73066)
		(width 0.20066)
		(layer "F.Cu")
		(net "M_D_CPU1_SA_DQS_DP<1>")
	)
	(segment
		(start 11.11631 -304.00117)
		(end 10.898124 -304.00117)
		(width 0.20066)
		(layer "F.Cu")
		(net "M_D_CPU1_SA_DQS_DP<1>")
	)
	(arc
		(start 99.063048 -276.986492)
		(mid 99.062984 -277.254462)
		(end 99.062794 -277.522432)
		(width 0.20066)
		(layer "F.Cu")
		(net "M_D_CPU1_SA_DQS_DP<1>")
	)
	(segment
		(start 17.069562 -303.28616)
		(end 16.789146 -303.566576)
		(width 0.18288)
		(layer "In11.Cu")
		(net "M_D_CPU1_SA_DQS_DP<1>")
	)
	(segment
		(start 45.673264 -309.364634)
		(end 44.99229 -309.082694)
		(width 0.18288)
		(layer "In11.Cu")
		(net "M_D_CPU1_SA_DQS_DP<1>")
	)
	(segment
		(start 20.400518 -303.684432)
		(end 20.000214 -303.684432)
		(width 0.18288)
		(layer "In11.Cu")
		(net "M_D_CPU1_SA_DQS_DP<1>")
	)
	(segment
		(start 29.476954 -310.260746)
		(end 28.273502 -309.762398)
		(width 0.18288)
		(layer "In11.Cu")
		(net "M_D_CPU1_SA_DQS_DP<1>")
	)
	(segment
		(start 84.355178 -281.710892)
		(end 84.355178 -281.795728)
		(width 0.088646)
		(layer "In11.Cu")
		(net "M_D_CPU1_SA_DQS_DP<1>")
	)
	(segment
		(start 36.170362 -309.090822)
		(end 35.776662 -309.090822)
		(width 0.18288)
		(layer "In11.Cu")
		(net "M_D_CPU1_SA_DQS_DP<1>")
	)
	(segment
		(start 50.603404 -308.822852)
		(end 50.542952 -308.822852)
		(width 0.18288)
		(layer "In11.Cu")
		(net "M_D_CPU1_SA_DQS_DP<1>")
	)
	(segment
		(start 86.580218 -278.885142)
		(end 86.442804 -279.022302)
		(width 0.088646)
		(layer "In11.Cu")
		(net "M_D_CPU1_SA_DQS_DP<1>")
	)
	(segment
		(start 86.442804 -279.022302)
		(end 86.23808 -279.022302)
		(width 0.088646)
		(layer "In11.Cu")
		(net "M_D_CPU1_SA_DQS_DP<1>")
	)
	(segment
		(start 30.046422 -310.260746)
		(end 29.476954 -310.260746)
		(width 0.18288)
		(layer "In11.Cu")
		(net "M_D_CPU1_SA_DQS_DP<1>")
	)
	(segment
		(start 35.776662 -309.090822)
		(end 35.488372 -308.802532)
		(width 0.18288)
		(layer "In11.Cu")
		(net "M_D_CPU1_SA_DQS_DP<1>")
	)
	(segment
		(start 46.495208 -309.69839)
		(end 46.007274 -309.69839)
		(width 0.18288)
		(layer "In11.Cu")
		(net "M_D_CPU1_SA_DQS_DP<1>")
	)
	(segment
		(start 69.411596 -298.884086)
		(end 67.15379 -301.141892)
		(width 0.18288)
		(layer "In11.Cu")
		(net "M_D_CPU1_SA_DQS_DP<1>")
	)
	(segment
		(start 24.353266 -305.4604)
		(end 24.353266 -305.460654)
		(width 0.18288)
		(layer "In11.Cu")
		(net "M_D_CPU1_SA_DQS_DP<1>")
	)
	(segment
		(start 19.723608 -303.961038)
		(end 18.861024 -304.318416)
		(width 0.18288)
		(layer "In11.Cu")
		(net "M_D_CPU1_SA_DQS_DP<1>")
	)
	(segment
		(start 66.656966 -301.141892)
		(end 66.35877 -301.440088)
		(width 0.18288)
		(layer "In11.Cu")
		(net "M_D_CPU1_SA_DQS_DP<1>")
	)
	(segment
		(start 21.988272 -303.762156)
		(end 21.988272 -303.761902)
		(width 0.18288)
		(layer "In11.Cu")
		(net "M_D_CPU1_SA_DQS_DP<1>")
	)
	(segment
		(start 52.359052 -308.831488)
		(end 51.537616 -308.831488)
		(width 0.18288)
		(layer "In11.Cu")
		(net "M_D_CPU1_SA_DQS_DP<1>")
	)
	(segment
		(start 69.411596 -296.682922)
		(end 69.411596 -298.884086)
		(width 0.18288)
		(layer "In11.Cu")
		(net "M_D_CPU1_SA_DQS_DP<1>")
	)
	(segment
		(start 88.457024 -278.02078)
		(end 88.442292 -278.012144)
		(width 0.088646)
		(layer "In11.Cu")
		(net "M_D_CPU1_SA_DQS_DP<1>")
	)
	(segment
		(start 51.278282 -309.090822)
		(end 50.871374 -309.090822)
		(width 0.18288)
		(layer "In11.Cu")
		(net "M_D_CPU1_SA_DQS_DP<1>")
	)
	(segment
		(start 65.654174 -301.159672)
		(end 65.288414 -301.159672)
		(width 0.18288)
		(layer "In11.Cu")
		(net "M_D_CPU1_SA_DQS_DP<1>")
	)
	(segment
		(start 46.007274 -309.69839)
		(end 45.673264 -309.364634)
		(width 0.18288)
		(layer "In11.Cu")
		(net "M_D_CPU1_SA_DQS_DP<1>")
	)
	(segment
		(start 47.43196 -309.673498)
		(end 47.164498 -309.94096)
		(width 0.18288)
		(layer "In11.Cu")
		(net "M_D_CPU1_SA_DQS_DP<1>")
	)
	(segment
		(start 90.887296 -278.012144)
		(end 90.872564 -278.02078)
		(width 0.088646)
		(layer "In11.Cu")
		(net "M_D_CPU1_SA_DQS_DP<1>")
	)
	(segment
		(start 90.88755 -278.01189)
		(end 90.887296 -278.012144)
		(width 0.088646)
		(layer "In11.Cu")
		(net "M_D_CPU1_SA_DQS_DP<1>")
	)
	(segment
		(start 18.522442 -304.318416)
		(end 18.250662 -304.205386)
		(width 0.18288)
		(layer "In11.Cu")
		(net "M_D_CPU1_SA_DQS_DP<1>")
	)
	(segment
		(start 92.216478 -278.02078)
		(end 92.201746 -278.012144)
		(width 0.088646)
		(layer "In11.Cu")
		(net "M_D_CPU1_SA_DQS_DP<1>")
	)
	(segment
		(start 87.880444 -278.336502)
		(end 87.880444 -278.346408)
		(width 0.088646)
		(layer "In11.Cu")
		(net "M_D_CPU1_SA_DQS_DP<1>")
	)
	(segment
		(start 43.905424 -309.512716)
		(end 41.309036 -309.512716)
		(width 0.18288)
		(layer "In11.Cu")
		(net "M_D_CPU1_SA_DQS_DP<1>")
	)
	(segment
		(start 57.15635 -305.602386)
		(end 56.294274 -306.464462)
		(width 0.18288)
		(layer "In11.Cu")
		(net "M_D_CPU1_SA_DQS_DP<1>")
	)
	(segment
		(start 84.355178 -281.795728)
		(end 83.816444 -282.334462)
		(width 0.18288)
		(layer "In11.Cu")
		(net "M_D_CPU1_SA_DQS_DP<1>")
	)
	(segment
		(start 44.188126 -309.230014)
		(end 43.905424 -309.512716)
		(width 0.18288)
		(layer "In11.Cu")
		(net "M_D_CPU1_SA_DQS_DP<1>")
	)
	(segment
		(start 26.735532 -306.915566)
		(end 26.617422 -306.630832)
		(width 0.18288)
		(layer "In11.Cu")
		(net "M_D_CPU1_SA_DQS_DP<1>")
	)
	(segment
		(start 85.111844 -280.954226)
		(end 84.355178 -281.710892)
		(width 0.088646)
		(layer "In11.Cu")
		(net "M_D_CPU1_SA_DQS_DP<1>")
	)
	(segment
		(start 31.684722 -309.94096)
		(end 31.424372 -309.68061)
		(width 0.18288)
		(layer "In11.Cu")
		(net "M_D_CPU1_SA_DQS_DP<1>")
	)
	(segment
		(start 31.424372 -309.68061)
		(end 30.886146 -309.68061)
		(width 0.18288)
		(layer "In11.Cu")
		(net "M_D_CPU1_SA_DQS_DP<1>")
	)
	(segment
		(start 18.861024 -304.318416)
		(end 18.522442 -304.318416)
		(width 0.18288)
		(layer "In11.Cu")
		(net "M_D_CPU1_SA_DQS_DP<1>")
	)
	(segment
		(start 62.314074 -302.290734)
		(end 61.825378 -302.290734)
		(width 0.18288)
		(layer "In11.Cu")
		(net "M_D_CPU1_SA_DQS_DP<1>")
	)
	(segment
		(start 47.164498 -309.94096)
		(end 46.737778 -309.94096)
		(width 0.18288)
		(layer "In11.Cu")
		(net "M_D_CPU1_SA_DQS_DP<1>")
	)
	(segment
		(start 39.654734 -308.827424)
		(end 36.43376 -308.827424)
		(width 0.18288)
		(layer "In11.Cu")
		(net "M_D_CPU1_SA_DQS_DP<1>")
	)
	(segment
		(start 50.542952 -308.822852)
		(end 48.490124 -309.673498)
		(width 0.18288)
		(layer "In11.Cu")
		(net "M_D_CPU1_SA_DQS_DP<1>")
	)
	(segment
		(start 17.331436 -303.28616)
		(end 17.069562 -303.28616)
		(width 0.18288)
		(layer "In11.Cu")
		(net "M_D_CPU1_SA_DQS_DP<1>")
	)
	(segment
		(start 83.816444 -282.334462)
		(end 82.989928 -282.334462)
		(width 0.18288)
		(layer "In11.Cu")
		(net "M_D_CPU1_SA_DQS_DP<1>")
	)
	(segment
		(start 44.543726 -309.082694)
		(end 44.188126 -309.230014)
		(width 0.18288)
		(layer "In11.Cu")
		(net "M_D_CPU1_SA_DQS_DP<1>")
	)
	(segment
		(start 94.096078 -278.02078)
		(end 94.081346 -278.012144)
		(width 0.088646)
		(layer "In11.Cu")
		(net "M_D_CPU1_SA_DQS_DP<1>")
	)
	(segment
		(start 41.309036 -309.512716)
		(end 39.654734 -308.827424)
		(width 0.18288)
		(layer "In11.Cu")
		(net "M_D_CPU1_SA_DQS_DP<1>")
	)
	(segment
		(start 58.428382 -303.03724)
		(end 58.071766 -303.393856)
		(width 0.18288)
		(layer "In11.Cu")
		(net "M_D_CPU1_SA_DQS_DP<1>")
	)
	(segment
		(start 66.35877 -301.440088)
		(end 65.93459 -301.440088)
		(width 0.18288)
		(layer "In11.Cu")
		(net "M_D_CPU1_SA_DQS_DP<1>")
	)
	(segment
		(start 65.93459 -301.440088)
		(end 65.654174 -301.159672)
		(width 0.18288)
		(layer "In11.Cu")
		(net "M_D_CPU1_SA_DQS_DP<1>")
	)
	(segment
		(start 62.570106 -302.034702)
		(end 62.314074 -302.290734)
		(width 0.18288)
		(layer "In11.Cu")
		(net "M_D_CPU1_SA_DQS_DP<1>")
	)
	(segment
		(start 30.489652 -310.077104)
		(end 30.046422 -310.260746)
		(width 0.18288)
		(layer "In11.Cu")
		(net "M_D_CPU1_SA_DQS_DP<1>")
	)
	(segment
		(start 67.15379 -301.141892)
		(end 66.656966 -301.141892)
		(width 0.18288)
		(layer "In11.Cu")
		(net "M_D_CPU1_SA_DQS_DP<1>")
	)
	(segment
		(start 86.23808 -279.022302)
		(end 85.111844 -280.148538)
		(width 0.088646)
		(layer "In11.Cu")
		(net "M_D_CPU1_SA_DQS_DP<1>")
	)
	(segment
		(start 51.537616 -308.831488)
		(end 51.278282 -309.090822)
		(width 0.18288)
		(layer "In11.Cu")
		(net "M_D_CPU1_SA_DQS_DP<1>")
	)
	(segment
		(start 46.737778 -309.94096)
		(end 46.495208 -309.69839)
		(width 0.18288)
		(layer "In11.Cu")
		(net "M_D_CPU1_SA_DQS_DP<1>")
	)
	(segment
		(start 63.651384 -302.034702)
		(end 62.570106 -302.034702)
		(width 0.18288)
		(layer "In11.Cu")
		(net "M_D_CPU1_SA_DQS_DP<1>")
	)
	(segment
		(start 98.092768 -277.895812)
		(end 98.035618 -277.888954)
		(width 0.088646)
		(layer "In11.Cu")
		(net "M_D_CPU1_SA_DQS_DP<1>")
	)
	(segment
		(start 85.111844 -280.148538)
		(end 85.111844 -280.954226)
		(width 0.088646)
		(layer "In11.Cu")
		(net "M_D_CPU1_SA_DQS_DP<1>")
	)
	(segment
		(start 33.274762 -309.677562)
		(end 32.324548 -309.677562)
		(width 0.18288)
		(layer "In11.Cu")
		(net "M_D_CPU1_SA_DQS_DP<1>")
	)
	(segment
		(start 56.294274 -306.464462)
		(end 53.617114 -307.573426)
		(width 0.18288)
		(layer "In11.Cu")
		(net "M_D_CPU1_SA_DQS_DP<1>")
	)
	(segment
		(start 26.617422 -306.630832)
		(end 26.220928 -306.234084)
		(width 0.18288)
		(layer "In11.Cu")
		(net "M_D_CPU1_SA_DQS_DP<1>")
	)
	(segment
		(start 96.900492 -278.01189)
		(end 96.900746 -278.012144)
		(width 0.088646)
		(layer "In11.Cu")
		(net "M_D_CPU1_SA_DQS_DP<1>")
	)
	(segment
		(start 36.43376 -308.827424)
		(end 36.170362 -309.090822)
		(width 0.18288)
		(layer "In11.Cu")
		(net "M_D_CPU1_SA_DQS_DP<1>")
	)
	(segment
		(start 65.288414 -301.159672)
		(end 64.952118 -301.495968)
		(width 0.18288)
		(layer "In11.Cu")
		(net "M_D_CPU1_SA_DQS_DP<1>")
	)
	(segment
		(start 32.324548 -309.677562)
		(end 32.06115 -309.94096)
		(width 0.18288)
		(layer "In11.Cu")
		(net "M_D_CPU1_SA_DQS_DP<1>")
	)
	(segment
		(start 24.353266 -305.460654)
		(end 23.996142 -305.10353)
		(width 0.18288)
		(layer "In11.Cu")
		(net "M_D_CPU1_SA_DQS_DP<1>")
	)
	(segment
		(start 21.818092 -303.71034)
		(end 21.356828 -303.71034)
		(width 0.18288)
		(layer "In11.Cu")
		(net "M_D_CPU1_SA_DQS_DP<1>")
	)
	(segment
		(start 21.356828 -303.71034)
		(end 21.07438 -303.992788)
		(width 0.18288)
		(layer "In11.Cu")
		(net "M_D_CPU1_SA_DQS_DP<1>")
	)
	(segment
		(start 86.658196 -278.82596)
		(end 86.657688 -278.826214)
		(width 0.088646)
		(layer "In11.Cu")
		(net "M_D_CPU1_SA_DQS_DP<1>")
	)
	(segment
		(start 44.99229 -309.082694)
		(end 44.543726 -309.082694)
		(width 0.18288)
		(layer "In11.Cu")
		(net "M_D_CPU1_SA_DQS_DP<1>")
	)
	(segment
		(start 50.871374 -309.090822)
		(end 50.603404 -308.822852)
		(width 0.18288)
		(layer "In11.Cu")
		(net "M_D_CPU1_SA_DQS_DP<1>")
	)
	(segment
		(start 98.035618 -277.888954)
		(end 98.030792 -277.891494)
		(width 0.088646)
		(layer "In11.Cu")
		(net "M_D_CPU1_SA_DQS_DP<1>")
	)
	(segment
		(start 58.071766 -303.393856)
		(end 57.15635 -305.602386)
		(width 0.18288)
		(layer "In11.Cu")
		(net "M_D_CPU1_SA_DQS_DP<1>")
	)
	(segment
		(start 21.988526 -303.762156)
		(end 21.988272 -303.762156)
		(width 0.18288)
		(layer "In11.Cu")
		(net "M_D_CPU1_SA_DQS_DP<1>")
	)
	(segment
		(start 21.07438 -303.992788)
		(end 20.708874 -303.992788)
		(width 0.18288)
		(layer "In11.Cu")
		(net "M_D_CPU1_SA_DQS_DP<1>")
	)
	(segment
		(start 18.250662 -304.205386)
		(end 17.331436 -303.28616)
		(width 0.18288)
		(layer "In11.Cu")
		(net "M_D_CPU1_SA_DQS_DP<1>")
	)
	(segment
		(start 35.387534 -308.802532)
		(end 33.274762 -309.677562)
		(width 0.18288)
		(layer "In11.Cu")
		(net "M_D_CPU1_SA_DQS_DP<1>")
	)
	(segment
		(start 60.854844 -302.063404)
		(end 60.30595 -302.612552)
		(width 0.18288)
		(layer "In11.Cu")
		(net "M_D_CPU1_SA_DQS_DP<1>")
	)
	(segment
		(start 88.067896 -278.012144)
		(end 88.059006 -278.017224)
		(width 0.088646)
		(layer "In11.Cu")
		(net "M_D_CPU1_SA_DQS_DP<1>")
	)
	(segment
		(start 27.285442 -308.77383)
		(end 26.735532 -307.447442)
		(width 0.18288)
		(layer "In11.Cu")
		(net "M_D_CPU1_SA_DQS_DP<1>")
	)
	(segment
		(start 61.825378 -302.290734)
		(end 61.598048 -302.063404)
		(width 0.18288)
		(layer "In11.Cu")
		(net "M_D_CPU1_SA_DQS_DP<1>")
	)
	(segment
		(start 98.722434 -277.612348)
		(end 98.297238 -277.854156)
		(width 0.088646)
		(layer "In11.Cu")
		(net "M_D_CPU1_SA_DQS_DP<1>")
	)
	(segment
		(start 59.280806 -303.03724)
		(end 58.428382 -303.03724)
		(width 0.18288)
		(layer "In11.Cu")
		(net "M_D_CPU1_SA_DQS_DP<1>")
	)
	(segment
		(start 60.30595 -302.612552)
		(end 59.280806 -303.03724)
		(width 0.18288)
		(layer "In11.Cu")
		(net "M_D_CPU1_SA_DQS_DP<1>")
	)
	(segment
		(start 48.490124 -309.673498)
		(end 47.43196 -309.673498)
		(width 0.18288)
		(layer "In11.Cu")
		(net "M_D_CPU1_SA_DQS_DP<1>")
	)
	(segment
		(start 32.06115 -309.94096)
		(end 31.684722 -309.94096)
		(width 0.18288)
		(layer "In11.Cu")
		(net "M_D_CPU1_SA_DQS_DP<1>")
	)
	(segment
		(start 35.488372 -308.802532)
		(end 35.387534 -308.802532)
		(width 0.18288)
		(layer "In11.Cu")
		(net "M_D_CPU1_SA_DQS_DP<1>")
	)
	(segment
		(start 20.708874 -303.992788)
		(end 20.400518 -303.684432)
		(width 0.18288)
		(layer "In11.Cu")
		(net "M_D_CPU1_SA_DQS_DP<1>")
	)
	(segment
		(start 23.996142 -305.10353)
		(end 21.988526 -303.762156)
		(width 0.18288)
		(layer "In11.Cu")
		(net "M_D_CPU1_SA_DQS_DP<1>")
	)
	(segment
		(start 93.156278 -278.02078)
		(end 93.141546 -278.012144)
		(width 0.088646)
		(layer "In11.Cu")
		(net "M_D_CPU1_SA_DQS_DP<1>")
	)
	(segment
		(start 26.735532 -307.447442)
		(end 26.735532 -306.915566)
		(width 0.18288)
		(layer "In11.Cu")
		(net "M_D_CPU1_SA_DQS_DP<1>")
	)
	(segment
		(start 91.272106 -278.01824)
		(end 91.261692 -278.012144)
		(width 0.088646)
		(layer "In11.Cu")
		(net "M_D_CPU1_SA_DQS_DP<1>")
	)
	(segment
		(start 28.273502 -309.762398)
		(end 27.285442 -308.77383)
		(width 0.18288)
		(layer "In11.Cu")
		(net "M_D_CPU1_SA_DQS_DP<1>")
	)
	(segment
		(start 73.10374 -292.22065)
		(end 73.10374 -292.990778)
		(width 0.18288)
		(layer "In11.Cu")
		(net "M_D_CPU1_SA_DQS_DP<1>")
	)
	(segment
		(start 20.000214 -303.684432)
		(end 19.723608 -303.961038)
		(width 0.18288)
		(layer "In11.Cu")
		(net "M_D_CPU1_SA_DQS_DP<1>")
	)
	(segment
		(start 95.035878 -278.02078)
		(end 95.021146 -278.012144)
		(width 0.088646)
		(layer "In11.Cu")
		(net "M_D_CPU1_SA_DQS_DP<1>")
	)
	(segment
		(start 95.975678 -278.02078)
		(end 95.960946 -278.012144)
		(width 0.088646)
		(layer "In11.Cu")
		(net "M_D_CPU1_SA_DQS_DP<1>")
	)
	(segment
		(start 97.675192 -277.891494)
		(end 97.451672 -278.020272)
		(width 0.088646)
		(layer "In11.Cu")
		(net "M_D_CPU1_SA_DQS_DP<1>")
	)
	(segment
		(start 30.886146 -309.68061)
		(end 30.489652 -310.077104)
		(width 0.18288)
		(layer "In11.Cu")
		(net "M_D_CPU1_SA_DQS_DP<1>")
	)
	(segment
		(start 21.988272 -303.761902)
		(end 21.818092 -303.71034)
		(width 0.18288)
		(layer "In11.Cu")
		(net "M_D_CPU1_SA_DQS_DP<1>")
	)
	(segment
		(start 73.10374 -292.990778)
		(end 69.411596 -296.682922)
		(width 0.18288)
		(layer "In11.Cu")
		(net "M_D_CPU1_SA_DQS_DP<1>")
	)
	(segment
		(start 53.617114 -307.573426)
		(end 52.359052 -308.831488)
		(width 0.18288)
		(layer "In11.Cu")
		(net "M_D_CPU1_SA_DQS_DP<1>")
	)
	(segment
		(start 98.030792 -277.891494)
		(end 97.675192 -277.891494)
		(width 0.088646)
		(layer "In11.Cu")
		(net "M_D_CPU1_SA_DQS_DP<1>")
	)
	(segment
		(start 64.952118 -301.495968)
		(end 63.651384 -302.034702)
		(width 0.18288)
		(layer "In11.Cu")
		(net "M_D_CPU1_SA_DQS_DP<1>")
	)
	(segment
		(start 26.220928 -306.234084)
		(end 24.353266 -305.4604)
		(width 0.18288)
		(layer "In11.Cu")
		(net "M_D_CPU1_SA_DQS_DP<1>")
	)
	(segment
		(start 61.598048 -302.063404)
		(end 60.854844 -302.063404)
		(width 0.18288)
		(layer "In11.Cu")
		(net "M_D_CPU1_SA_DQS_DP<1>")
	)
	(segment
		(start 82.989928 -282.334462)
		(end 73.10374 -292.22065)
		(width 0.18288)
		(layer "In11.Cu")
		(net "M_D_CPU1_SA_DQS_DP<1>")
	)
	(arc
		(start 95.960946 -278.012144)
		(mid 95.773748 -277.962001)
		(end 95.58655 -278.012144)
		(width 0.088646)
		(layer "In11.Cu")
		(net "M_D_CPU1_SA_DQS_DP<1>")
	)
	(arc
		(start 86.657688 -278.826214)
		(mid 86.617033 -278.853153)
		(end 86.580218 -278.885142)
		(width 0.088646)
		(layer "In11.Cu")
		(net "M_D_CPU1_SA_DQS_DP<1>")
	)
	(arc
		(start 93.70695 -278.012144)
		(mid 93.432721 -278.088069)
		(end 93.156278 -278.02078)
		(width 0.088646)
		(layer "In11.Cu")
		(net "M_D_CPU1_SA_DQS_DP<1>")
	)
	(arc
		(start 87.597996 -278.82596)
		(mid 87.315294 -278.901736)
		(end 87.032592 -278.82596)
		(width 0.088646)
		(layer "In11.Cu")
		(net "M_D_CPU1_SA_DQS_DP<1>")
	)
	(arc
		(start 91.261692 -278.012144)
		(mid 91.074667 -277.962001)
		(end 90.88755 -278.01189)
		(width 0.088646)
		(layer "In11.Cu")
		(net "M_D_CPU1_SA_DQS_DP<1>")
	)
	(arc
		(start 87.032592 -278.82596)
		(mid 86.845394 -278.775817)
		(end 86.658196 -278.82596)
		(width 0.088646)
		(layer "In11.Cu")
		(net "M_D_CPU1_SA_DQS_DP<1>")
	)
	(arc
		(start 92.201746 -278.012144)
		(mid 92.014548 -277.962001)
		(end 91.82735 -278.012144)
		(width 0.088646)
		(layer "In11.Cu")
		(net "M_D_CPU1_SA_DQS_DP<1>")
	)
	(arc
		(start 90.872564 -278.02078)
		(mid 90.596123 -278.087946)
		(end 90.321892 -278.012144)
		(width 0.088646)
		(layer "In11.Cu")
		(net "M_D_CPU1_SA_DQS_DP<1>")
	)
	(arc
		(start 96.52635 -278.012144)
		(mid 96.252121 -278.088069)
		(end 95.975678 -278.02078)
		(width 0.088646)
		(layer "In11.Cu")
		(net "M_D_CPU1_SA_DQS_DP<1>")
	)
	(arc
		(start 98.297238 -277.854156)
		(mid 98.198396 -277.891666)
		(end 98.092768 -277.895812)
		(width 0.088646)
		(layer "In11.Cu")
		(net "M_D_CPU1_SA_DQS_DP<1>")
	)
	(arc
		(start 87.880444 -278.346408)
		(mid 87.802333 -278.623357)
		(end 87.597996 -278.82596)
		(width 0.088646)
		(layer "In11.Cu")
		(net "M_D_CPU1_SA_DQS_DP<1>")
	)
	(arc
		(start 92.76715 -278.012144)
		(mid 92.492921 -278.088069)
		(end 92.216478 -278.02078)
		(width 0.088646)
		(layer "In11.Cu")
		(net "M_D_CPU1_SA_DQS_DP<1>")
	)
	(arc
		(start 97.451672 -278.020272)
		(mid 97.175007 -278.087743)
		(end 96.900492 -278.01189)
		(width 0.088646)
		(layer "In11.Cu")
		(net "M_D_CPU1_SA_DQS_DP<1>")
	)
	(arc
		(start 89.382092 -278.012144)
		(mid 89.194894 -277.962001)
		(end 89.007696 -278.012144)
		(width 0.088646)
		(layer "In11.Cu")
		(net "M_D_CPU1_SA_DQS_DP<1>")
	)
	(arc
		(start 88.442292 -278.012144)
		(mid 88.255094 -277.962001)
		(end 88.067896 -278.012144)
		(width 0.088646)
		(layer "In11.Cu")
		(net "M_D_CPU1_SA_DQS_DP<1>")
	)
	(arc
		(start 94.081346 -278.012144)
		(mid 93.894148 -277.962001)
		(end 93.70695 -278.012144)
		(width 0.088646)
		(layer "In11.Cu")
		(net "M_D_CPU1_SA_DQS_DP<1>")
	)
	(arc
		(start 95.021146 -278.012144)
		(mid 94.833948 -277.962001)
		(end 94.64675 -278.012144)
		(width 0.088646)
		(layer "In11.Cu")
		(net "M_D_CPU1_SA_DQS_DP<1>")
	)
	(arc
		(start 95.58655 -278.012144)
		(mid 95.312321 -278.088069)
		(end 95.035878 -278.02078)
		(width 0.088646)
		(layer "In11.Cu")
		(net "M_D_CPU1_SA_DQS_DP<1>")
	)
	(arc
		(start 96.900746 -278.012144)
		(mid 96.713548 -277.962001)
		(end 96.52635 -278.012144)
		(width 0.088646)
		(layer "In11.Cu")
		(net "M_D_CPU1_SA_DQS_DP<1>")
	)
	(arc
		(start 94.64675 -278.012144)
		(mid 94.372521 -278.088069)
		(end 94.096078 -278.02078)
		(width 0.088646)
		(layer "In11.Cu")
		(net "M_D_CPU1_SA_DQS_DP<1>")
	)
	(arc
		(start 89.007696 -278.012144)
		(mid 88.733497 -278.087979)
		(end 88.457024 -278.02078)
		(width 0.088646)
		(layer "In11.Cu")
		(net "M_D_CPU1_SA_DQS_DP<1>")
	)
	(arc
		(start 89.947496 -278.012144)
		(mid 89.664794 -278.087886)
		(end 89.382092 -278.012144)
		(width 0.088646)
		(layer "In11.Cu")
		(net "M_D_CPU1_SA_DQS_DP<1>")
	)
	(arc
		(start 91.82735 -278.012144)
		(mid 91.550537 -278.08798)
		(end 91.272106 -278.01824)
		(width 0.088646)
		(layer "In11.Cu")
		(net "M_D_CPU1_SA_DQS_DP<1>")
	)
	(arc
		(start 99.062794 -277.522432)
		(mid 98.886773 -277.545269)
		(end 98.722434 -277.612348)
		(width 0.088646)
		(layer "In11.Cu")
		(net "M_D_CPU1_SA_DQS_DP<1>")
	)
	(arc
		(start 93.141546 -278.012144)
		(mid 92.954348 -277.962001)
		(end 92.76715 -278.012144)
		(width 0.088646)
		(layer "In11.Cu")
		(net "M_D_CPU1_SA_DQS_DP<1>")
	)
	(arc
		(start 88.059006 -278.017224)
		(mid 87.928092 -278.153584)
		(end 87.880444 -278.336502)
		(width 0.088646)
		(layer "In11.Cu")
		(net "M_D_CPU1_SA_DQS_DP<1>")
	)
	(arc
		(start 90.321892 -278.012144)
		(mid 90.134694 -277.962001)
		(end 89.947496 -278.012144)
		(width 0.088646)
		(layer "In11.Cu")
		(net "M_D_CPU1_SA_DQS_DP<1>")
	)
	(segment
		(start 15.684246 -312.91657)
		(end 15.135606 -312.91657)
		(width 0.20066)
		(layer "F.Cu")
		(net "M_D_CPU1_SA_DQS_DP<0>")
	)
	(segment
		(start 13.593572 -313.341766)
		(end 13.441426 -313.341766)
		(width 0.20066)
		(layer "F.Cu")
		(net "M_D_CPU1_SA_DQS_DP<0>")
	)
	(segment
		(start 10.000488 -313.080654)
		(end 9.364472 -312.655458)
		(width 0.20066)
		(layer "F.Cu")
		(net "M_D_CPU1_SA_DQS_DP<0>")
	)
	(segment
		(start 14.874494 -312.655458)
		(end 14.605762 -312.655458)
		(width 0.20066)
		(layer "F.Cu")
		(net "M_D_CPU1_SA_DQS_DP<0>")
	)
	(segment
		(start 15.135606 -312.91657)
		(end 14.874494 -312.655458)
		(width 0.20066)
		(layer "F.Cu")
		(net "M_D_CPU1_SA_DQS_DP<0>")
	)
	(segment
		(start 15.684246 -312.91657)
		(end 16.789146 -312.91657)
		(width 0.20066)
		(layer "F.Cu")
		(net "M_D_CPU1_SA_DQS_DP<0>")
	)
	(segment
		(start 14.605762 -312.655458)
		(end 14.180566 -313.080654)
		(width 0.20066)
		(layer "F.Cu")
		(net "M_D_CPU1_SA_DQS_DP<0>")
	)
	(segment
		(start 14.180566 -313.080654)
		(end 13.854684 -313.080654)
		(width 0.20066)
		(layer "F.Cu")
		(net "M_D_CPU1_SA_DQS_DP<0>")
	)
	(segment
		(start 13.441426 -313.341766)
		(end 13.118084 -313.341766)
		(width 0.101854)
		(layer "F.Cu")
		(net "M_D_CPU1_SA_DQS_DP<0>")
	)
	(segment
		(start 10.627614 -313.080654)
		(end 10.000488 -313.080654)
		(width 0.20066)
		(layer "F.Cu")
		(net "M_D_CPU1_SA_DQS_DP<0>")
	)
	(segment
		(start 11.11631 -313.351164)
		(end 10.898124 -313.351164)
		(width 0.20066)
		(layer "F.Cu")
		(net "M_D_CPU1_SA_DQS_DP<0>")
	)
	(segment
		(start 10.898124 -313.351164)
		(end 10.627614 -313.080654)
		(width 0.20066)
		(layer "F.Cu")
		(net "M_D_CPU1_SA_DQS_DP<0>")
	)
	(segment
		(start 13.854684 -313.080654)
		(end 13.593572 -313.341766)
		(width 0.20066)
		(layer "F.Cu")
		(net "M_D_CPU1_SA_DQS_DP<0>")
	)
	(segment
		(start 13.118084 -313.341766)
		(end 11.36269 -313.341766)
		(width 0.1016)
		(layer "F.Cu")
		(net "M_D_CPU1_SA_DQS_DP<0>")
	)
	(segment
		(start 8.93953 -312.655458)
		(end 8.678418 -312.91657)
		(width 0.20066)
		(layer "F.Cu")
		(net "M_D_CPU1_SA_DQS_DP<0>")
	)
	(segment
		(start 9.364472 -312.655458)
		(end 8.93953 -312.655458)
		(width 0.20066)
		(layer "F.Cu")
		(net "M_D_CPU1_SA_DQS_DP<0>")
	)
	(segment
		(start 11.125708 -313.341766)
		(end 11.11631 -313.351164)
		(width 0.101854)
		(layer "F.Cu")
		(net "M_D_CPU1_SA_DQS_DP<0>")
	)
	(segment
		(start 8.678418 -312.91657)
		(end 8.140446 -312.91657)
		(width 0.20066)
		(layer "F.Cu")
		(net "M_D_CPU1_SA_DQS_DP<0>")
	)
	(segment
		(start 11.36269 -313.341766)
		(end 11.125708 -313.341766)
		(width 0.101854)
		(layer "F.Cu")
		(net "M_D_CPU1_SA_DQS_DP<0>")
	)
	(arc
		(start 95.773494 -274.54479)
		(mid 95.773557 -274.81276)
		(end 95.773748 -275.08073)
		(width 0.20066)
		(layer "F.Cu")
		(net "M_D_CPU1_SA_DQS_DP<0>")
	)
	(segment
		(start 31.38424 -313.89701)
		(end 30.90418 -313.89701)
		(width 0.18288)
		(layer "In6.Cu")
		(net "M_D_CPU1_SA_DQS_DP<0>")
	)
	(segment
		(start 94.386146 -275.449792)
		(end 94.162626 -275.57857)
		(width 0.088646)
		(layer "In6.Cu")
		(net "M_D_CPU1_SA_DQS_DP<0>")
	)
	(segment
		(start 35.778694 -315.041788)
		(end 35.481514 -314.744608)
		(width 0.18288)
		(layer "In6.Cu")
		(net "M_D_CPU1_SA_DQS_DP<0>")
	)
	(segment
		(start 36.17595 -315.041788)
		(end 35.778694 -315.041788)
		(width 0.18288)
		(layer "In6.Cu")
		(net "M_D_CPU1_SA_DQS_DP<0>")
	)
	(segment
		(start 45.77588 -310.116982)
		(end 44.829476 -310.508904)
		(width 0.18288)
		(layer "In6.Cu")
		(net "M_D_CPU1_SA_DQS_DP<0>")
	)
	(segment
		(start 86.577424 -278.02078)
		(end 86.562692 -278.012144)
		(width 0.088646)
		(layer "In6.Cu")
		(net "M_D_CPU1_SA_DQS_DP<0>")
	)
	(segment
		(start 46.475396 -309.650892)
		(end 46.24197 -309.650892)
		(width 0.18288)
		(layer "In6.Cu")
		(net "M_D_CPU1_SA_DQS_DP<0>")
	)
	(segment
		(start 47.524416 -309.662068)
		(end 47.244508 -309.941976)
		(width 0.18288)
		(layer "In6.Cu")
		(net "M_D_CPU1_SA_DQS_DP<0>")
	)
	(segment
		(start 93.236796 -275.570442)
		(end 93.222064 -275.579078)
		(width 0.088646)
		(layer "In6.Cu")
		(net "M_D_CPU1_SA_DQS_DP<0>")
	)
	(segment
		(start 62.57544 -300.32325)
		(end 62.306962 -300.591728)
		(width 0.18288)
		(layer "In6.Cu")
		(net "M_D_CPU1_SA_DQS_DP<0>")
	)
	(segment
		(start 95.209868 -275.297646)
		(end 95.008192 -275.412454)
		(width 0.088646)
		(layer "In6.Cu")
		(net "M_D_CPU1_SA_DQS_DP<0>")
	)
	(segment
		(start 24.552656 -313.07659)
		(end 21.366734 -313.07659)
		(width 0.18288)
		(layer "In6.Cu")
		(net "M_D_CPU1_SA_DQS_DP<0>")
	)
	(segment
		(start 90.417396 -275.570442)
		(end 90.408506 -275.575522)
		(width 0.088646)
		(layer "In6.Cu")
		(net "M_D_CPU1_SA_DQS_DP<0>")
	)
	(segment
		(start 64.845438 -299.499528)
		(end 64.280542 -300.064424)
		(width 0.18288)
		(layer "In6.Cu")
		(net "M_D_CPU1_SA_DQS_DP<0>")
	)
	(segment
		(start 85.908134 -278.27351)
		(end 85.908134 -278.88565)
		(width 0.088646)
		(layer "In6.Cu")
		(net "M_D_CPU1_SA_DQS_DP<0>")
	)
	(segment
		(start 26.188416 -312.399172)
		(end 24.552656 -313.07659)
		(width 0.18288)
		(layer "In6.Cu")
		(net "M_D_CPU1_SA_DQS_DP<0>")
	)
	(segment
		(start 89.947496 -276.384258)
		(end 89.938606 -276.389338)
		(width 0.088646)
		(layer "In6.Cu")
		(net "M_D_CPU1_SA_DQS_DP<0>")
	)
	(segment
		(start 85.908134 -278.88565)
		(end 84.718144 -280.07564)
		(width 0.088646)
		(layer "In6.Cu")
		(net "M_D_CPU1_SA_DQS_DP<0>")
	)
	(segment
		(start 29.900372 -312.893202)
		(end 28.707588 -312.399172)
		(width 0.18288)
		(layer "In6.Cu")
		(net "M_D_CPU1_SA_DQS_DP<0>")
	)
	(segment
		(start 67.057524 -299.449236)
		(end 66.631566 -299.449236)
		(width 0.18288)
		(layer "In6.Cu")
		(net "M_D_CPU1_SA_DQS_DP<0>")
	)
	(segment
		(start 59.81954 -301.20082)
		(end 58.668158 -302.352202)
		(width 0.18288)
		(layer "In6.Cu")
		(net "M_D_CPU1_SA_DQS_DP<0>")
	)
	(segment
		(start 56.769 -304.541936)
		(end 54.173374 -305.618134)
		(width 0.18288)
		(layer "In6.Cu")
		(net "M_D_CPU1_SA_DQS_DP<0>")
	)
	(segment
		(start 21.101558 -313.341766)
		(end 20.709382 -313.341766)
		(width 0.18288)
		(layer "In6.Cu")
		(net "M_D_CPU1_SA_DQS_DP<0>")
	)
	(segment
		(start 44.172378 -311.165494)
		(end 39.054278 -313.285632)
		(width 0.18288)
		(layer "In6.Cu")
		(net "M_D_CPU1_SA_DQS_DP<0>")
	)
	(segment
		(start 52.240942 -307.111908)
		(end 51.624484 -307.111908)
		(width 0.18288)
		(layer "In6.Cu")
		(net "M_D_CPU1_SA_DQS_DP<0>")
	)
	(segment
		(start 64.280542 -300.064424)
		(end 63.430912 -300.064424)
		(width 0.18288)
		(layer "In6.Cu")
		(net "M_D_CPU1_SA_DQS_DP<0>")
	)
	(segment
		(start 48.33874 -308.566058)
		(end 48.33874 -309.209694)
		(width 0.18288)
		(layer "In6.Cu")
		(net "M_D_CPU1_SA_DQS_DP<0>")
	)
	(segment
		(start 49.571656 -307.700934)
		(end 48.943768 -307.96103)
		(width 0.18288)
		(layer "In6.Cu")
		(net "M_D_CPU1_SA_DQS_DP<0>")
	)
	(segment
		(start 87.517224 -278.02078)
		(end 87.502492 -278.012144)
		(width 0.088646)
		(layer "In6.Cu")
		(net "M_D_CPU1_SA_DQS_DP<0>")
	)
	(segment
		(start 19.152108 -312.52668)
		(end 18.906236 -312.424826)
		(width 0.18288)
		(layer "In6.Cu")
		(net "M_D_CPU1_SA_DQS_DP<0>")
	)
	(segment
		(start 39.054278 -313.285632)
		(end 37.947092 -314.392818)
		(width 0.18288)
		(layer "In6.Cu")
		(net "M_D_CPU1_SA_DQS_DP<0>")
	)
	(segment
		(start 84.07781 -280.960576)
		(end 84.054442 -280.960576)
		(width 0.088646)
		(layer "In6.Cu")
		(net "M_D_CPU1_SA_DQS_DP<0>")
	)
	(segment
		(start 50.563526 -307.088794)
		(end 50.183796 -307.088794)
		(width 0.18288)
		(layer "In6.Cu")
		(net "M_D_CPU1_SA_DQS_DP<0>")
	)
	(segment
		(start 46.76648 -309.941976)
		(end 46.475396 -309.650892)
		(width 0.18288)
		(layer "In6.Cu")
		(net "M_D_CPU1_SA_DQS_DP<0>")
	)
	(segment
		(start 19.689064 -313.063636)
		(end 19.152108 -312.52668)
		(width 0.18288)
		(layer "In6.Cu")
		(net "M_D_CPU1_SA_DQS_DP<0>")
	)
	(segment
		(start 52.989988 -306.80152)
		(end 52.240942 -307.111908)
		(width 0.18288)
		(layer "In6.Cu")
		(net "M_D_CPU1_SA_DQS_DP<0>")
	)
	(segment
		(start 37.055044 -314.762134)
		(end 36.455604 -314.762134)
		(width 0.18288)
		(layer "In6.Cu")
		(net "M_D_CPU1_SA_DQS_DP<0>")
	)
	(segment
		(start 94.803722 -275.45411)
		(end 94.746572 -275.447252)
		(width 0.088646)
		(layer "In6.Cu")
		(net "M_D_CPU1_SA_DQS_DP<0>")
	)
	(segment
		(start 36.455604 -314.762134)
		(end 36.17595 -315.041788)
		(width 0.18288)
		(layer "In6.Cu")
		(net "M_D_CPU1_SA_DQS_DP<0>")
	)
	(segment
		(start 47.244508 -309.941976)
		(end 46.76648 -309.941976)
		(width 0.18288)
		(layer "In6.Cu")
		(net "M_D_CPU1_SA_DQS_DP<0>")
	)
	(segment
		(start 89.469468 -277.202646)
		(end 89.468706 -277.203154)
		(width 0.088646)
		(layer "In6.Cu")
		(net "M_D_CPU1_SA_DQS_DP<0>")
	)
	(segment
		(start 34.353246 -314.045854)
		(end 34.110168 -313.945016)
		(width 0.18288)
		(layer "In6.Cu")
		(net "M_D_CPU1_SA_DQS_DP<0>")
	)
	(segment
		(start 44.829476 -310.508904)
		(end 44.172378 -311.165494)
		(width 0.18288)
		(layer "In6.Cu")
		(net "M_D_CPU1_SA_DQS_DP<0>")
	)
	(segment
		(start 17.058894 -312.646822)
		(end 16.789146 -312.91657)
		(width 0.18288)
		(layer "In6.Cu")
		(net "M_D_CPU1_SA_DQS_DP<0>")
	)
	(segment
		(start 86.110318 -278.071326)
		(end 85.908134 -278.27351)
		(width 0.088646)
		(layer "In6.Cu")
		(net "M_D_CPU1_SA_DQS_DP<0>")
	)
	(segment
		(start 89.476834 -277.198582)
		(end 89.475056 -277.199598)
		(width 0.088646)
		(layer "In6.Cu")
		(net "M_D_CPU1_SA_DQS_DP<0>")
	)
	(segment
		(start 67.877944 -298.628816)
		(end 67.057524 -299.449236)
		(width 0.18288)
		(layer "In6.Cu")
		(net "M_D_CPU1_SA_DQS_DP<0>")
	)
	(segment
		(start 32.111442 -314.191396)
		(end 31.678626 -314.191396)
		(width 0.18288)
		(layer "In6.Cu")
		(net "M_D_CPU1_SA_DQS_DP<0>")
	)
	(segment
		(start 58.668158 -302.352202)
		(end 58.462418 -302.848518)
		(width 0.18288)
		(layer "In6.Cu")
		(net "M_D_CPU1_SA_DQS_DP<0>")
	)
	(segment
		(start 20.431252 -313.063636)
		(end 19.689064 -313.063636)
		(width 0.18288)
		(layer "In6.Cu")
		(net "M_D_CPU1_SA_DQS_DP<0>")
	)
	(segment
		(start 89.760044 -276.708616)
		(end 89.760044 -276.718522)
		(width 0.088646)
		(layer "In6.Cu")
		(net "M_D_CPU1_SA_DQS_DP<0>")
	)
	(segment
		(start 65.717674 -299.499528)
		(end 64.845438 -299.499528)
		(width 0.18288)
		(layer "In6.Cu")
		(net "M_D_CPU1_SA_DQS_DP<0>")
	)
	(segment
		(start 18.377154 -312.424826)
		(end 17.84096 -312.646822)
		(width 0.18288)
		(layer "In6.Cu")
		(net "M_D_CPU1_SA_DQS_DP<0>")
	)
	(segment
		(start 30.90418 -313.89701)
		(end 29.900372 -312.893202)
		(width 0.18288)
		(layer "In6.Cu")
		(net "M_D_CPU1_SA_DQS_DP<0>")
	)
	(segment
		(start 94.741746 -275.449792)
		(end 94.386146 -275.449792)
		(width 0.088646)
		(layer "In6.Cu")
		(net "M_D_CPU1_SA_DQS_DP<0>")
	)
	(segment
		(start 20.709382 -313.341766)
		(end 20.431252 -313.063636)
		(width 0.18288)
		(layer "In6.Cu")
		(net "M_D_CPU1_SA_DQS_DP<0>")
	)
	(segment
		(start 32.357822 -313.945016)
		(end 32.111442 -314.191396)
		(width 0.18288)
		(layer "In6.Cu")
		(net "M_D_CPU1_SA_DQS_DP<0>")
	)
	(segment
		(start 89.013792 -278.008588)
		(end 89.007696 -278.012144)
		(width 0.088646)
		(layer "In6.Cu")
		(net "M_D_CPU1_SA_DQS_DP<0>")
	)
	(segment
		(start 89.474294 -277.200106)
		(end 89.469468 -277.202646)
		(width 0.088646)
		(layer "In6.Cu")
		(net "M_D_CPU1_SA_DQS_DP<0>")
	)
	(segment
		(start 18.906236 -312.424826)
		(end 18.377154 -312.424826)
		(width 0.18288)
		(layer "In6.Cu")
		(net "M_D_CPU1_SA_DQS_DP<0>")
	)
	(segment
		(start 50.866294 -307.391562)
		(end 50.563526 -307.088794)
		(width 0.18288)
		(layer "In6.Cu")
		(net "M_D_CPU1_SA_DQS_DP<0>")
	)
	(segment
		(start 46.24197 -309.650892)
		(end 45.77588 -310.116982)
		(width 0.18288)
		(layer "In6.Cu")
		(net "M_D_CPU1_SA_DQS_DP<0>")
	)
	(segment
		(start 89.477596 -277.198074)
		(end 89.476834 -277.198582)
		(width 0.088646)
		(layer "In6.Cu")
		(net "M_D_CPU1_SA_DQS_DP<0>")
	)
	(segment
		(start 60.545472 -300.900084)
		(end 59.81954 -301.20082)
		(width 0.18288)
		(layer "In6.Cu")
		(net "M_D_CPU1_SA_DQS_DP<0>")
	)
	(segment
		(start 94.746572 -275.447252)
		(end 94.741746 -275.449792)
		(width 0.088646)
		(layer "In6.Cu")
		(net "M_D_CPU1_SA_DQS_DP<0>")
	)
	(segment
		(start 28.707588 -312.399172)
		(end 26.188416 -312.399172)
		(width 0.18288)
		(layer "In6.Cu")
		(net "M_D_CPU1_SA_DQS_DP<0>")
	)
	(segment
		(start 61.144658 -300.300898)
		(end 60.545472 -300.900084)
		(width 0.18288)
		(layer "In6.Cu")
		(net "M_D_CPU1_SA_DQS_DP<0>")
	)
	(segment
		(start 66.631566 -299.449236)
		(end 66.33718 -299.743622)
		(width 0.18288)
		(layer "In6.Cu")
		(net "M_D_CPU1_SA_DQS_DP<0>")
	)
	(segment
		(start 50.183796 -307.088794)
		(end 49.571656 -307.700934)
		(width 0.18288)
		(layer "In6.Cu")
		(net "M_D_CPU1_SA_DQS_DP<0>")
	)
	(segment
		(start 95.589852 -275.134578)
		(end 95.28937 -275.258784)
		(width 0.088646)
		(layer "In6.Cu")
		(net "M_D_CPU1_SA_DQS_DP<0>")
	)
	(segment
		(start 47.886366 -309.662068)
		(end 47.524416 -309.662068)
		(width 0.18288)
		(layer "In6.Cu")
		(net "M_D_CPU1_SA_DQS_DP<0>")
	)
	(segment
		(start 34.110168 -313.945016)
		(end 32.357822 -313.945016)
		(width 0.18288)
		(layer "In6.Cu")
		(net "M_D_CPU1_SA_DQS_DP<0>")
	)
	(segment
		(start 58.462418 -302.848518)
		(end 56.769 -304.541936)
		(width 0.18288)
		(layer "In6.Cu")
		(net "M_D_CPU1_SA_DQS_DP<0>")
	)
	(segment
		(start 67.877944 -296.595292)
		(end 67.877944 -298.628816)
		(width 0.18288)
		(layer "In6.Cu")
		(net "M_D_CPU1_SA_DQS_DP<0>")
	)
	(segment
		(start 89.475056 -277.199598)
		(end 89.474294 -277.200106)
		(width 0.088646)
		(layer "In6.Cu")
		(net "M_D_CPU1_SA_DQS_DP<0>")
	)
	(segment
		(start 83.51266 -280.960576)
		(end 67.877944 -296.595292)
		(width 0.18288)
		(layer "In6.Cu")
		(net "M_D_CPU1_SA_DQS_DP<0>")
	)
	(segment
		(start 17.84096 -312.646822)
		(end 17.058894 -312.646822)
		(width 0.18288)
		(layer "In6.Cu")
		(net "M_D_CPU1_SA_DQS_DP<0>")
	)
	(segment
		(start 61.537596 -300.300898)
		(end 61.144658 -300.300898)
		(width 0.18288)
		(layer "In6.Cu")
		(net "M_D_CPU1_SA_DQS_DP<0>")
	)
	(segment
		(start 84.718144 -280.63317)
		(end 84.450682 -280.900632)
		(width 0.088646)
		(layer "In6.Cu")
		(net "M_D_CPU1_SA_DQS_DP<0>")
	)
	(segment
		(start 31.678626 -314.191396)
		(end 31.38424 -313.89701)
		(width 0.18288)
		(layer "In6.Cu")
		(net "M_D_CPU1_SA_DQS_DP<0>")
	)
	(segment
		(start 93.611446 -275.570188)
		(end 93.611192 -275.570442)
		(width 0.088646)
		(layer "In6.Cu")
		(net "M_D_CPU1_SA_DQS_DP<0>")
	)
	(segment
		(start 92.671392 -275.570442)
		(end 92.671392 -275.570188)
		(width 0.088646)
		(layer "In6.Cu")
		(net "M_D_CPU1_SA_DQS_DP<0>")
	)
	(segment
		(start 84.137754 -280.900632)
		(end 84.07781 -280.960576)
		(width 0.088646)
		(layer "In6.Cu")
		(net "M_D_CPU1_SA_DQS_DP<0>")
	)
	(segment
		(start 61.828426 -300.591728)
		(end 61.537596 -300.300898)
		(width 0.18288)
		(layer "In6.Cu")
		(net "M_D_CPU1_SA_DQS_DP<0>")
	)
	(segment
		(start 90.229944 -275.8948)
		(end 90.229944 -275.904706)
		(width 0.088646)
		(layer "In6.Cu")
		(net "M_D_CPU1_SA_DQS_DP<0>")
	)
	(segment
		(start 37.947092 -314.392818)
		(end 37.055044 -314.762134)
		(width 0.18288)
		(layer "In6.Cu")
		(net "M_D_CPU1_SA_DQS_DP<0>")
	)
	(segment
		(start 63.430912 -300.064424)
		(end 63.172086 -300.32325)
		(width 0.18288)
		(layer "In6.Cu")
		(net "M_D_CPU1_SA_DQS_DP<0>")
	)
	(segment
		(start 66.33718 -299.743622)
		(end 65.961768 -299.743622)
		(width 0.18288)
		(layer "In6.Cu")
		(net "M_D_CPU1_SA_DQS_DP<0>")
	)
	(segment
		(start 65.961768 -299.743622)
		(end 65.717674 -299.499528)
		(width 0.18288)
		(layer "In6.Cu")
		(net "M_D_CPU1_SA_DQS_DP<0>")
	)
	(segment
		(start 35.052 -314.744608)
		(end 34.353246 -314.045854)
		(width 0.18288)
		(layer "In6.Cu")
		(net "M_D_CPU1_SA_DQS_DP<0>")
	)
	(segment
		(start 48.33874 -309.209694)
		(end 47.886366 -309.662068)
		(width 0.18288)
		(layer "In6.Cu")
		(net "M_D_CPU1_SA_DQS_DP<0>")
	)
	(segment
		(start 62.306962 -300.591728)
		(end 61.828426 -300.591728)
		(width 0.18288)
		(layer "In6.Cu")
		(net "M_D_CPU1_SA_DQS_DP<0>")
	)
	(segment
		(start 84.450682 -280.900632)
		(end 84.137754 -280.900632)
		(width 0.088646)
		(layer "In6.Cu")
		(net "M_D_CPU1_SA_DQS_DP<0>")
	)
	(segment
		(start 21.366734 -313.07659)
		(end 21.101558 -313.341766)
		(width 0.18288)
		(layer "In6.Cu")
		(net "M_D_CPU1_SA_DQS_DP<0>")
	)
	(segment
		(start 51.624484 -307.111908)
		(end 51.34483 -307.391562)
		(width 0.18288)
		(layer "In6.Cu")
		(net "M_D_CPU1_SA_DQS_DP<0>")
	)
	(segment
		(start 84.718144 -280.07564)
		(end 84.718144 -280.63317)
		(width 0.088646)
		(layer "In6.Cu")
		(net "M_D_CPU1_SA_DQS_DP<0>")
	)
	(segment
		(start 35.481514 -314.744608)
		(end 35.052 -314.744608)
		(width 0.18288)
		(layer "In6.Cu")
		(net "M_D_CPU1_SA_DQS_DP<0>")
	)
	(segment
		(start 88.457024 -278.02078)
		(end 88.442292 -278.012144)
		(width 0.088646)
		(layer "In6.Cu")
		(net "M_D_CPU1_SA_DQS_DP<0>")
	)
	(segment
		(start 84.054442 -280.960576)
		(end 83.51266 -280.960576)
		(width 0.18288)
		(layer "In6.Cu")
		(net "M_D_CPU1_SA_DQS_DP<0>")
	)
	(segment
		(start 91.357196 -275.570188)
		(end 91.342464 -275.578824)
		(width 0.088646)
		(layer "In6.Cu")
		(net "M_D_CPU1_SA_DQS_DP<0>")
	)
	(segment
		(start 48.943768 -307.96103)
		(end 48.33874 -308.566058)
		(width 0.18288)
		(layer "In6.Cu")
		(net "M_D_CPU1_SA_DQS_DP<0>")
	)
	(segment
		(start 54.173374 -305.618134)
		(end 52.989988 -306.80152)
		(width 0.18288)
		(layer "In6.Cu")
		(net "M_D_CPU1_SA_DQS_DP<0>")
	)
	(segment
		(start 90.417396 -275.570188)
		(end 90.417396 -275.570442)
		(width 0.088646)
		(layer "In6.Cu")
		(net "M_D_CPU1_SA_DQS_DP<0>")
	)
	(segment
		(start 51.34483 -307.391562)
		(end 50.866294 -307.391562)
		(width 0.18288)
		(layer "In6.Cu")
		(net "M_D_CPU1_SA_DQS_DP<0>")
	)
	(segment
		(start 63.172086 -300.32325)
		(end 62.57544 -300.32325)
		(width 0.18288)
		(layer "In6.Cu")
		(net "M_D_CPU1_SA_DQS_DP<0>")
	)
	(arc
		(start 87.128096 -278.012144)
		(mid 86.853897 -278.087979)
		(end 86.577424 -278.02078)
		(width 0.088646)
		(layer "In6.Cu")
		(net "M_D_CPU1_SA_DQS_DP<0>")
	)
	(arc
		(start 89.468706 -277.203154)
		(mid 89.337792 -277.339514)
		(end 89.290144 -277.522432)
		(width 0.088646)
		(layer "In6.Cu")
		(net "M_D_CPU1_SA_DQS_DP<0>")
	)
	(arc
		(start 92.296996 -275.570188)
		(mid 92.014294 -275.645964)
		(end 91.731592 -275.570188)
		(width 0.088646)
		(layer "In6.Cu")
		(net "M_D_CPU1_SA_DQS_DP<0>")
	)
	(arc
		(start 89.938606 -276.389338)
		(mid 89.807692 -276.525698)
		(end 89.760044 -276.708616)
		(width 0.088646)
		(layer "In6.Cu")
		(net "M_D_CPU1_SA_DQS_DP<0>")
	)
	(arc
		(start 92.671392 -275.570188)
		(mid 92.484194 -275.520045)
		(end 92.296996 -275.570188)
		(width 0.088646)
		(layer "In6.Cu")
		(net "M_D_CPU1_SA_DQS_DP<0>")
	)
	(arc
		(start 89.007696 -278.012144)
		(mid 88.733497 -278.087979)
		(end 88.457024 -278.02078)
		(width 0.088646)
		(layer "In6.Cu")
		(net "M_D_CPU1_SA_DQS_DP<0>")
	)
	(arc
		(start 87.502492 -278.012144)
		(mid 87.315294 -277.962001)
		(end 87.128096 -278.012144)
		(width 0.088646)
		(layer "In6.Cu")
		(net "M_D_CPU1_SA_DQS_DP<0>")
	)
	(arc
		(start 94.162626 -275.57857)
		(mid 93.885961 -275.646041)
		(end 93.611446 -275.570188)
		(width 0.088646)
		(layer "In6.Cu")
		(net "M_D_CPU1_SA_DQS_DP<0>")
	)
	(arc
		(start 95.773748 -275.08073)
		(mid 95.723819 -275.093358)
		(end 95.673926 -275.10613)
		(width 0.088646)
		(layer "In6.Cu")
		(net "M_D_CPU1_SA_DQS_DP<0>")
	)
	(arc
		(start 88.442292 -278.012144)
		(mid 88.255094 -277.962001)
		(end 88.067896 -278.012144)
		(width 0.088646)
		(layer "In6.Cu")
		(net "M_D_CPU1_SA_DQS_DP<0>")
	)
	(arc
		(start 89.290144 -277.522432)
		(mid 89.216291 -277.802078)
		(end 89.013792 -278.008588)
		(width 0.088646)
		(layer "In6.Cu")
		(net "M_D_CPU1_SA_DQS_DP<0>")
	)
	(arc
		(start 95.28937 -275.258784)
		(mid 95.249015 -275.276979)
		(end 95.209868 -275.297646)
		(width 0.088646)
		(layer "In6.Cu")
		(net "M_D_CPU1_SA_DQS_DP<0>")
	)
	(arc
		(start 95.673926 -275.10613)
		(mid 95.631396 -275.118897)
		(end 95.589852 -275.134578)
		(width 0.088646)
		(layer "In6.Cu")
		(net "M_D_CPU1_SA_DQS_DP<0>")
	)
	(arc
		(start 91.731592 -275.570188)
		(mid 91.544394 -275.520045)
		(end 91.357196 -275.570188)
		(width 0.088646)
		(layer "In6.Cu")
		(net "M_D_CPU1_SA_DQS_DP<0>")
	)
	(arc
		(start 91.342464 -275.578824)
		(mid 91.065989 -275.646144)
		(end 90.791792 -275.570188)
		(width 0.088646)
		(layer "In6.Cu")
		(net "M_D_CPU1_SA_DQS_DP<0>")
	)
	(arc
		(start 93.611192 -275.570442)
		(mid 93.423994 -275.520299)
		(end 93.236796 -275.570442)
		(width 0.088646)
		(layer "In6.Cu")
		(net "M_D_CPU1_SA_DQS_DP<0>")
	)
	(arc
		(start 95.008192 -275.412454)
		(mid 94.90935 -275.449964)
		(end 94.803722 -275.45411)
		(width 0.088646)
		(layer "In6.Cu")
		(net "M_D_CPU1_SA_DQS_DP<0>")
	)
	(arc
		(start 86.562692 -278.012144)
		(mid 86.375494 -277.962001)
		(end 86.188296 -278.012144)
		(width 0.088646)
		(layer "In6.Cu")
		(net "M_D_CPU1_SA_DQS_DP<0>")
	)
	(arc
		(start 89.760044 -276.718522)
		(mid 89.681933 -276.995471)
		(end 89.477596 -277.198074)
		(width 0.088646)
		(layer "In6.Cu")
		(net "M_D_CPU1_SA_DQS_DP<0>")
	)
	(arc
		(start 90.791792 -275.570188)
		(mid 90.604594 -275.520045)
		(end 90.417396 -275.570188)
		(width 0.088646)
		(layer "In6.Cu")
		(net "M_D_CPU1_SA_DQS_DP<0>")
	)
	(arc
		(start 88.067896 -278.012144)
		(mid 87.793697 -278.087979)
		(end 87.517224 -278.02078)
		(width 0.088646)
		(layer "In6.Cu")
		(net "M_D_CPU1_SA_DQS_DP<0>")
	)
	(arc
		(start 93.222064 -275.579078)
		(mid 92.945623 -275.646244)
		(end 92.671392 -275.570442)
		(width 0.088646)
		(layer "In6.Cu")
		(net "M_D_CPU1_SA_DQS_DP<0>")
	)
	(arc
		(start 90.408506 -275.575522)
		(mid 90.277592 -275.711882)
		(end 90.229944 -275.8948)
		(width 0.088646)
		(layer "In6.Cu")
		(net "M_D_CPU1_SA_DQS_DP<0>")
	)
	(arc
		(start 90.229944 -275.904706)
		(mid 90.151833 -276.181655)
		(end 89.947496 -276.384258)
		(width 0.088646)
		(layer "In6.Cu")
		(net "M_D_CPU1_SA_DQS_DP<0>")
	)
	(arc
		(start 86.188296 -278.012144)
		(mid 86.147366 -278.039177)
		(end 86.110318 -278.071326)
		(width 0.088646)
		(layer "In6.Cu")
		(net "M_D_CPU1_SA_DQS_DP<0>")
	)
	(segment
		(start 16.885412 -274.241768)
		(end 14.807692 -274.241768)
		(width 0.1016)
		(layer "F.Cu")
		(net "M_D_CPU1_SA_DQS_DN<9>")
	)
	(segment
		(start 100.002848 -262.336534)
		(end 100.002848 -262.87222)
		(width 0.20066)
		(layer "F.Cu")
		(net "M_D_CPU1_SA_DQS_DN<9>")
	)
	(segment
		(start 17.693132 -273.980656)
		(end 17.28851 -273.980656)
		(width 0.20066)
		(layer "F.Cu")
		(net "M_D_CPU1_SA_DQS_DN<9>")
	)
	(segment
		(start 12.973304 -274.405598)
		(end 12.712192 -274.66671)
		(width 0.20066)
		(layer "F.Cu")
		(net "M_D_CPU1_SA_DQS_DN<9>")
	)
	(segment
		(start 19.29384 -274.66671)
		(end 19.032728 -274.405598)
		(width 0.20066)
		(layer "F.Cu")
		(net "M_D_CPU1_SA_DQS_DN<9>")
	)
	(segment
		(start 14.108684 -273.983196)
		(end 13.868908 -273.983196)
		(width 0.20066)
		(layer "F.Cu")
		(net "M_D_CPU1_SA_DQS_DN<9>")
	)
	(segment
		(start 18.329148 -274.405598)
		(end 17.693132 -273.980656)
		(width 0.20066)
		(layer "F.Cu")
		(net "M_D_CPU1_SA_DQS_DN<9>")
	)
	(segment
		(start 14.569948 -274.241768)
		(end 14.560296 -274.25142)
		(width 0.101854)
		(layer "F.Cu")
		(net "M_D_CPU1_SA_DQS_DN<9>")
	)
	(segment
		(start 14.807692 -274.241768)
		(end 14.569948 -274.241768)
		(width 0.101854)
		(layer "F.Cu")
		(net "M_D_CPU1_SA_DQS_DN<9>")
	)
	(segment
		(start 17.027398 -274.241768)
		(end 16.885412 -274.241768)
		(width 0.20066)
		(layer "F.Cu")
		(net "M_D_CPU1_SA_DQS_DN<9>")
	)
	(segment
		(start 20.889214 -274.66671)
		(end 19.784314 -274.66671)
		(width 0.20066)
		(layer "F.Cu")
		(net "M_D_CPU1_SA_DQS_DN<9>")
	)
	(segment
		(start 17.28851 -273.980656)
		(end 17.027398 -274.241768)
		(width 0.20066)
		(layer "F.Cu")
		(net "M_D_CPU1_SA_DQS_DN<9>")
	)
	(segment
		(start 13.868908 -273.983196)
		(end 13.446506 -274.405598)
		(width 0.20066)
		(layer "F.Cu")
		(net "M_D_CPU1_SA_DQS_DN<9>")
	)
	(segment
		(start 19.784314 -274.66671)
		(end 19.29384 -274.66671)
		(width 0.20066)
		(layer "F.Cu")
		(net "M_D_CPU1_SA_DQS_DN<9>")
	)
	(segment
		(start 12.712192 -274.66671)
		(end 12.240514 -274.66671)
		(width 0.20066)
		(layer "F.Cu")
		(net "M_D_CPU1_SA_DQS_DN<9>")
	)
	(segment
		(start 19.032728 -274.405598)
		(end 18.329148 -274.405598)
		(width 0.20066)
		(layer "F.Cu")
		(net "M_D_CPU1_SA_DQS_DN<9>")
	)
	(segment
		(start 13.446506 -274.405598)
		(end 12.973304 -274.405598)
		(width 0.20066)
		(layer "F.Cu")
		(net "M_D_CPU1_SA_DQS_DN<9>")
	)
	(segment
		(start 100.002848 -262.87222)
		(end 100.002594 -262.872474)
		(width 0.20066)
		(layer "F.Cu")
		(net "M_D_CPU1_SA_DQS_DN<9>")
	)
	(segment
		(start 14.560296 -274.25142)
		(end 14.376908 -274.25142)
		(width 0.20066)
		(layer "F.Cu")
		(net "M_D_CPU1_SA_DQS_DN<9>")
	)
	(segment
		(start 14.376908 -274.25142)
		(end 14.108684 -273.983196)
		(width 0.20066)
		(layer "F.Cu")
		(net "M_D_CPU1_SA_DQS_DN<9>")
	)
	(segment
		(start 21.178012 -274.377912)
		(end 20.889214 -274.66671)
		(width 0.18288)
		(layer "In11.Cu")
		(net "M_D_CPU1_SA_DQS_DN<9>")
	)
	(segment
		(start 40.53332 -272.321528)
		(end 39.887652 -271.67586)
		(width 0.18288)
		(layer "In11.Cu")
		(net "M_D_CPU1_SA_DQS_DN<9>")
	)
	(segment
		(start 36.173156 -271.694148)
		(end 35.788092 -271.694148)
		(width 0.18288)
		(layer "In11.Cu")
		(net "M_D_CPU1_SA_DQS_DN<9>")
	)
	(segment
		(start 49.896522 -271.416272)
		(end 49.4411 -271.871694)
		(width 0.18288)
		(layer "In11.Cu")
		(net "M_D_CPU1_SA_DQS_DN<9>")
	)
	(segment
		(start 83.714082 -262.68426)
		(end 83.399122 -262.99922)
		(width 0.088646)
		(layer "In11.Cu")
		(net "M_D_CPU1_SA_DQS_DN<9>")
	)
	(segment
		(start 61.44006 -271.279366)
		(end 59.30265 -271.279366)
		(width 0.18288)
		(layer "In11.Cu")
		(net "M_D_CPU1_SA_DQS_DN<9>")
	)
	(segment
		(start 55.367174 -271.681194)
		(end 52.78247 -271.681194)
		(width 0.18288)
		(layer "In11.Cu")
		(net "M_D_CPU1_SA_DQS_DN<9>")
	)
	(segment
		(start 34.843212 -271.481296)
		(end 34.03981 -272.284698)
		(width 0.18288)
		(layer "In11.Cu")
		(net "M_D_CPU1_SA_DQS_DN<9>")
	)
	(segment
		(start 30.375606 -272.912586)
		(end 29.151072 -272.912586)
		(width 0.18288)
		(layer "In11.Cu")
		(net "M_D_CPU1_SA_DQS_DN<9>")
	)
	(segment
		(start 25.97023 -272.53311)
		(end 25.122124 -273.381216)
		(width 0.18288)
		(layer "In11.Cu")
		(net "M_D_CPU1_SA_DQS_DN<9>")
	)
	(segment
		(start 52.517548 -271.416272)
		(end 51.525424 -271.416272)
		(width 0.18288)
		(layer "In11.Cu")
		(net "M_D_CPU1_SA_DQS_DN<9>")
	)
	(segment
		(start 83.073494 -262.99922)
		(end 83.013804 -263.05891)
		(width 0.088646)
		(layer "In11.Cu")
		(net "M_D_CPU1_SA_DQS_DN<9>")
	)
	(segment
		(start 49.4411 -271.871694)
		(end 48.471074 -272.273014)
		(width 0.18288)
		(layer "In11.Cu")
		(net "M_D_CPU1_SA_DQS_DN<9>")
	)
	(segment
		(start 83.399122 -262.99922)
		(end 83.073494 -262.99922)
		(width 0.088646)
		(layer "In11.Cu")
		(net "M_D_CPU1_SA_DQS_DN<9>")
	)
	(segment
		(start 29.151072 -272.912586)
		(end 28.771596 -272.53311)
		(width 0.18288)
		(layer "In11.Cu")
		(net "M_D_CPU1_SA_DQS_DN<9>")
	)
	(segment
		(start 83.013804 -263.05891)
		(end 75.188826 -263.05891)
		(width 0.18288)
		(layer "In11.Cu")
		(net "M_D_CPU1_SA_DQS_DN<9>")
	)
	(segment
		(start 43.754548 -272.321528)
		(end 40.53332 -272.321528)
		(width 0.18288)
		(layer "In11.Cu")
		(net "M_D_CPU1_SA_DQS_DN<9>")
	)
	(segment
		(start 66.09969 -270.6624)
		(end 65.462658 -270.6624)
		(width 0.18288)
		(layer "In11.Cu")
		(net "M_D_CPU1_SA_DQS_DN<9>")
	)
	(segment
		(start 31.399226 -272.255742)
		(end 31.03245 -272.255742)
		(width 0.18288)
		(layer "In11.Cu")
		(net "M_D_CPU1_SA_DQS_DN<9>")
	)
	(segment
		(start 58.856372 -270.833088)
		(end 56.21528 -270.833088)
		(width 0.18288)
		(layer "In11.Cu")
		(net "M_D_CPU1_SA_DQS_DN<9>")
	)
	(segment
		(start 59.30265 -271.279366)
		(end 58.856372 -270.833088)
		(width 0.18288)
		(layer "In11.Cu")
		(net "M_D_CPU1_SA_DQS_DN<9>")
	)
	(segment
		(start 52.78247 -271.681194)
		(end 52.517548 -271.416272)
		(width 0.18288)
		(layer "In11.Cu")
		(net "M_D_CPU1_SA_DQS_DN<9>")
	)
	(segment
		(start 100.008182 -262.878062)
		(end 100.309934 -262.878062)
		(width 0.088646)
		(layer "In11.Cu")
		(net "M_D_CPU1_SA_DQS_DN<9>")
	)
	(segment
		(start 63.403226 -270.6624)
		(end 62.78626 -271.279366)
		(width 0.18288)
		(layer "In11.Cu")
		(net "M_D_CPU1_SA_DQS_DN<9>")
	)
	(segment
		(start 32.320738 -272.284698)
		(end 32.064706 -272.54073)
		(width 0.18288)
		(layer "In11.Cu")
		(net "M_D_CPU1_SA_DQS_DN<9>")
	)
	(segment
		(start 89.855802 -262.550148)
		(end 89.854278 -262.549386)
		(width 0.088646)
		(layer "In11.Cu")
		(net "M_D_CPU1_SA_DQS_DN<9>")
	)
	(segment
		(start 64.789558 -270.78686)
		(end 64.665098 -270.6624)
		(width 0.18288)
		(layer "In11.Cu")
		(net "M_D_CPU1_SA_DQS_DN<9>")
	)
	(segment
		(start 91.737688 -262.551418)
		(end 91.726004 -262.544814)
		(width 0.088646)
		(layer "In11.Cu")
		(net "M_D_CPU1_SA_DQS_DN<9>")
	)
	(segment
		(start 62.11316 -271.403826)
		(end 61.56452 -271.403826)
		(width 0.18288)
		(layer "In11.Cu")
		(net "M_D_CPU1_SA_DQS_DN<9>")
	)
	(segment
		(start 89.852246 -262.548116)
		(end 89.851738 -262.547862)
		(width 0.088646)
		(layer "In11.Cu")
		(net "M_D_CPU1_SA_DQS_DN<9>")
	)
	(segment
		(start 46.052994 -272.262092)
		(end 45.384974 -272.930112)
		(width 0.18288)
		(layer "In11.Cu")
		(net "M_D_CPU1_SA_DQS_DN<9>")
	)
	(segment
		(start 48.471074 -272.273014)
		(end 47.423578 -272.273014)
		(width 0.18288)
		(layer "In11.Cu")
		(net "M_D_CPU1_SA_DQS_DN<9>")
	)
	(segment
		(start 66.22415 -270.78686)
		(end 66.09969 -270.6624)
		(width 0.18288)
		(layer "In11.Cu")
		(net "M_D_CPU1_SA_DQS_DN<9>")
	)
	(segment
		(start 28.771596 -272.53311)
		(end 25.97023 -272.53311)
		(width 0.18288)
		(layer "In11.Cu")
		(net "M_D_CPU1_SA_DQS_DN<9>")
	)
	(segment
		(start 93.617288 -262.551418)
		(end 93.605604 -262.544814)
		(width 0.088646)
		(layer "In11.Cu")
		(net "M_D_CPU1_SA_DQS_DN<9>")
	)
	(segment
		(start 45.384974 -272.930112)
		(end 44.363132 -272.930112)
		(width 0.18288)
		(layer "In11.Cu")
		(net "M_D_CPU1_SA_DQS_DN<9>")
	)
	(segment
		(start 31.684214 -272.54073)
		(end 31.399226 -272.255742)
		(width 0.18288)
		(layer "In11.Cu")
		(net "M_D_CPU1_SA_DQS_DN<9>")
	)
	(segment
		(start 88.9127 -262.547862)
		(end 88.912192 -262.548116)
		(width 0.088646)
		(layer "In11.Cu")
		(net "M_D_CPU1_SA_DQS_DN<9>")
	)
	(segment
		(start 31.03245 -272.255742)
		(end 30.375606 -272.912586)
		(width 0.18288)
		(layer "In11.Cu")
		(net "M_D_CPU1_SA_DQS_DN<9>")
	)
	(segment
		(start 39.887652 -271.67586)
		(end 37.550344 -271.67586)
		(width 0.18288)
		(layer "In11.Cu")
		(net "M_D_CPU1_SA_DQS_DN<9>")
	)
	(segment
		(start 21.469096 -274.377912)
		(end 21.178012 -274.377912)
		(width 0.18288)
		(layer "In11.Cu")
		(net "M_D_CPU1_SA_DQS_DN<9>")
	)
	(segment
		(start 90.797888 -262.551418)
		(end 90.786204 -262.544814)
		(width 0.088646)
		(layer "In11.Cu")
		(net "M_D_CPU1_SA_DQS_DN<9>")
	)
	(segment
		(start 65.338198 -270.78686)
		(end 64.789558 -270.78686)
		(width 0.18288)
		(layer "In11.Cu")
		(net "M_D_CPU1_SA_DQS_DN<9>")
	)
	(segment
		(start 56.21528 -270.833088)
		(end 55.367174 -271.681194)
		(width 0.18288)
		(layer "In11.Cu")
		(net "M_D_CPU1_SA_DQS_DN<9>")
	)
	(segment
		(start 67.585336 -270.6624)
		(end 66.89725 -270.6624)
		(width 0.18288)
		(layer "In11.Cu")
		(net "M_D_CPU1_SA_DQS_DN<9>")
	)
	(segment
		(start 47.15383 -272.542762)
		(end 46.773846 -272.542762)
		(width 0.18288)
		(layer "In11.Cu")
		(net "M_D_CPU1_SA_DQS_DN<9>")
	)
	(segment
		(start 25.122124 -273.381216)
		(end 24.04745 -273.381216)
		(width 0.18288)
		(layer "In11.Cu")
		(net "M_D_CPU1_SA_DQS_DN<9>")
	)
	(segment
		(start 100.309934 -262.878062)
		(end 100.372926 -262.81507)
		(width 0.088646)
		(layer "In11.Cu")
		(net "M_D_CPU1_SA_DQS_DN<9>")
	)
	(segment
		(start 89.851738 -262.547862)
		(end 89.851738 -262.547608)
		(width 0.088646)
		(layer "In11.Cu")
		(net "M_D_CPU1_SA_DQS_DN<9>")
	)
	(segment
		(start 62.23762 -271.279366)
		(end 62.11316 -271.403826)
		(width 0.18288)
		(layer "In11.Cu")
		(net "M_D_CPU1_SA_DQS_DN<9>")
	)
	(segment
		(start 21.82495 -274.733766)
		(end 21.469096 -274.377912)
		(width 0.18288)
		(layer "In11.Cu")
		(net "M_D_CPU1_SA_DQS_DN<9>")
	)
	(segment
		(start 50.597816 -271.416272)
		(end 49.896522 -271.416272)
		(width 0.18288)
		(layer "In11.Cu")
		(net "M_D_CPU1_SA_DQS_DN<9>")
	)
	(segment
		(start 98.316288 -262.551418)
		(end 98.304604 -262.544814)
		(width 0.088646)
		(layer "In11.Cu")
		(net "M_D_CPU1_SA_DQS_DN<9>")
	)
	(segment
		(start 46.493176 -272.262092)
		(end 46.052994 -272.262092)
		(width 0.18288)
		(layer "In11.Cu")
		(net "M_D_CPU1_SA_DQS_DN<9>")
	)
	(segment
		(start 66.77279 -270.78686)
		(end 66.22415 -270.78686)
		(width 0.18288)
		(layer "In11.Cu")
		(net "M_D_CPU1_SA_DQS_DN<9>")
	)
	(segment
		(start 50.875692 -271.694148)
		(end 50.597816 -271.416272)
		(width 0.18288)
		(layer "In11.Cu")
		(net "M_D_CPU1_SA_DQS_DN<9>")
	)
	(segment
		(start 61.56452 -271.403826)
		(end 61.44006 -271.279366)
		(width 0.18288)
		(layer "In11.Cu")
		(net "M_D_CPU1_SA_DQS_DN<9>")
	)
	(segment
		(start 100.002594 -262.872474)
		(end 100.008182 -262.878062)
		(width 0.088646)
		(layer "In11.Cu")
		(net "M_D_CPU1_SA_DQS_DN<9>")
	)
	(segment
		(start 35.788092 -271.694148)
		(end 35.57524 -271.481296)
		(width 0.18288)
		(layer "In11.Cu")
		(net "M_D_CPU1_SA_DQS_DN<9>")
	)
	(segment
		(start 89.854278 -262.549386)
		(end 89.852246 -262.548116)
		(width 0.088646)
		(layer "In11.Cu")
		(net "M_D_CPU1_SA_DQS_DN<9>")
	)
	(segment
		(start 37.309298 -271.434814)
		(end 36.43249 -271.434814)
		(width 0.18288)
		(layer "In11.Cu")
		(net "M_D_CPU1_SA_DQS_DN<9>")
	)
	(segment
		(start 47.423578 -272.273014)
		(end 47.15383 -272.542762)
		(width 0.18288)
		(layer "In11.Cu")
		(net "M_D_CPU1_SA_DQS_DN<9>")
	)
	(segment
		(start 24.04745 -273.381216)
		(end 22.6949 -274.733766)
		(width 0.18288)
		(layer "In11.Cu")
		(net "M_D_CPU1_SA_DQS_DN<9>")
	)
	(segment
		(start 35.57524 -271.481296)
		(end 34.843212 -271.481296)
		(width 0.18288)
		(layer "In11.Cu")
		(net "M_D_CPU1_SA_DQS_DN<9>")
	)
	(segment
		(start 51.247548 -271.694148)
		(end 50.875692 -271.694148)
		(width 0.18288)
		(layer "In11.Cu")
		(net "M_D_CPU1_SA_DQS_DN<9>")
	)
	(segment
		(start 51.525424 -271.416272)
		(end 51.247548 -271.694148)
		(width 0.18288)
		(layer "In11.Cu")
		(net "M_D_CPU1_SA_DQS_DN<9>")
	)
	(segment
		(start 95.496888 -262.551418)
		(end 95.485204 -262.544814)
		(width 0.088646)
		(layer "In11.Cu")
		(net "M_D_CPU1_SA_DQS_DN<9>")
	)
	(segment
		(start 32.064706 -272.54073)
		(end 31.684214 -272.54073)
		(width 0.18288)
		(layer "In11.Cu")
		(net "M_D_CPU1_SA_DQS_DN<9>")
	)
	(segment
		(start 84.248752 -262.593836)
		(end 84.155026 -262.567674)
		(width 0.088646)
		(layer "In11.Cu")
		(net "M_D_CPU1_SA_DQS_DN<9>")
	)
	(segment
		(start 75.188826 -263.05891)
		(end 67.585336 -270.6624)
		(width 0.18288)
		(layer "In11.Cu")
		(net "M_D_CPU1_SA_DQS_DN<9>")
	)
	(segment
		(start 97.376488 -262.551418)
		(end 97.364804 -262.544814)
		(width 0.088646)
		(layer "In11.Cu")
		(net "M_D_CPU1_SA_DQS_DN<9>")
	)
	(segment
		(start 37.550344 -271.67586)
		(end 37.309298 -271.434814)
		(width 0.18288)
		(layer "In11.Cu")
		(net "M_D_CPU1_SA_DQS_DN<9>")
	)
	(segment
		(start 34.03981 -272.284698)
		(end 32.320738 -272.284698)
		(width 0.18288)
		(layer "In11.Cu")
		(net "M_D_CPU1_SA_DQS_DN<9>")
	)
	(segment
		(start 94.557088 -262.551418)
		(end 94.545404 -262.544814)
		(width 0.088646)
		(layer "In11.Cu")
		(net "M_D_CPU1_SA_DQS_DN<9>")
	)
	(segment
		(start 22.6949 -274.733766)
		(end 21.82495 -274.733766)
		(width 0.18288)
		(layer "In11.Cu")
		(net "M_D_CPU1_SA_DQS_DN<9>")
	)
	(segment
		(start 65.462658 -270.6624)
		(end 65.338198 -270.78686)
		(width 0.18288)
		(layer "In11.Cu")
		(net "M_D_CPU1_SA_DQS_DN<9>")
	)
	(segment
		(start 66.89725 -270.6624)
		(end 66.77279 -270.78686)
		(width 0.18288)
		(layer "In11.Cu")
		(net "M_D_CPU1_SA_DQS_DN<9>")
	)
	(segment
		(start 36.43249 -271.434814)
		(end 36.173156 -271.694148)
		(width 0.18288)
		(layer "In11.Cu")
		(net "M_D_CPU1_SA_DQS_DN<9>")
	)
	(segment
		(start 99.256088 -262.551418)
		(end 99.244404 -262.544814)
		(width 0.088646)
		(layer "In11.Cu")
		(net "M_D_CPU1_SA_DQS_DN<9>")
	)
	(segment
		(start 46.773846 -272.542762)
		(end 46.493176 -272.262092)
		(width 0.18288)
		(layer "In11.Cu")
		(net "M_D_CPU1_SA_DQS_DN<9>")
	)
	(segment
		(start 64.665098 -270.6624)
		(end 63.403226 -270.6624)
		(width 0.18288)
		(layer "In11.Cu")
		(net "M_D_CPU1_SA_DQS_DN<9>")
	)
	(segment
		(start 62.78626 -271.279366)
		(end 62.23762 -271.279366)
		(width 0.18288)
		(layer "In11.Cu")
		(net "M_D_CPU1_SA_DQS_DN<9>")
	)
	(segment
		(start 92.677488 -262.551418)
		(end 92.665804 -262.544814)
		(width 0.088646)
		(layer "In11.Cu")
		(net "M_D_CPU1_SA_DQS_DN<9>")
	)
	(segment
		(start 44.363132 -272.930112)
		(end 43.754548 -272.321528)
		(width 0.18288)
		(layer "In11.Cu")
		(net "M_D_CPU1_SA_DQS_DN<9>")
	)
	(segment
		(start 96.436688 -262.551418)
		(end 96.425004 -262.544814)
		(width 0.088646)
		(layer "In11.Cu")
		(net "M_D_CPU1_SA_DQS_DN<9>")
	)
	(arc
		(start 90.417396 -262.548116)
		(mid 90.136885 -262.623762)
		(end 89.855802 -262.550148)
		(width 0.088646)
		(layer "In11.Cu")
		(net "M_D_CPU1_SA_DQS_DN<9>")
	)
	(arc
		(start 95.116396 -262.548116)
		(mid 94.837193 -262.623756)
		(end 94.557088 -262.551418)
		(width 0.088646)
		(layer "In11.Cu")
		(net "M_D_CPU1_SA_DQS_DN<9>")
	)
	(arc
		(start 97.364804 -262.544814)
		(mid 97.179949 -262.497864)
		(end 96.995996 -262.548116)
		(width 0.088646)
		(layer "In11.Cu")
		(net "M_D_CPU1_SA_DQS_DN<9>")
	)
	(arc
		(start 88.537796 -262.548116)
		(mid 88.255094 -262.623892)
		(end 87.972392 -262.548116)
		(width 0.088646)
		(layer "In11.Cu")
		(net "M_D_CPU1_SA_DQS_DN<9>")
	)
	(arc
		(start 94.545404 -262.544814)
		(mid 94.360549 -262.497864)
		(end 94.176596 -262.548116)
		(width 0.088646)
		(layer "In11.Cu")
		(net "M_D_CPU1_SA_DQS_DN<9>")
	)
	(arc
		(start 96.995996 -262.548116)
		(mid 96.716793 -262.623756)
		(end 96.436688 -262.551418)
		(width 0.088646)
		(layer "In11.Cu")
		(net "M_D_CPU1_SA_DQS_DN<9>")
	)
	(arc
		(start 84.794852 -262.538464)
		(mid 84.527014 -262.617477)
		(end 84.248752 -262.593836)
		(width 0.088646)
		(layer "In11.Cu")
		(net "M_D_CPU1_SA_DQS_DN<9>")
	)
	(arc
		(start 97.935796 -262.548116)
		(mid 97.656593 -262.623756)
		(end 97.376488 -262.551418)
		(width 0.088646)
		(layer "In11.Cu")
		(net "M_D_CPU1_SA_DQS_DN<9>")
	)
	(arc
		(start 96.425004 -262.544814)
		(mid 96.240149 -262.497864)
		(end 96.056196 -262.548116)
		(width 0.088646)
		(layer "In11.Cu")
		(net "M_D_CPU1_SA_DQS_DN<9>")
	)
	(arc
		(start 91.726004 -262.544814)
		(mid 91.541149 -262.497864)
		(end 91.357196 -262.548116)
		(width 0.088646)
		(layer "In11.Cu")
		(net "M_D_CPU1_SA_DQS_DN<9>")
	)
	(arc
		(start 99.815396 -262.548116)
		(mid 99.536193 -262.623756)
		(end 99.256088 -262.551418)
		(width 0.088646)
		(layer "In11.Cu")
		(net "M_D_CPU1_SA_DQS_DN<9>")
	)
	(arc
		(start 84.155026 -262.567674)
		(mid 83.918828 -262.566432)
		(end 83.714082 -262.68426)
		(width 0.088646)
		(layer "In11.Cu")
		(net "M_D_CPU1_SA_DQS_DN<9>")
	)
	(arc
		(start 87.032592 -262.548116)
		(mid 86.845394 -262.497973)
		(end 86.658196 -262.548116)
		(width 0.088646)
		(layer "In11.Cu")
		(net "M_D_CPU1_SA_DQS_DN<9>")
	)
	(arc
		(start 95.485204 -262.544814)
		(mid 95.300349 -262.497864)
		(end 95.116396 -262.548116)
		(width 0.088646)
		(layer "In11.Cu")
		(net "M_D_CPU1_SA_DQS_DN<9>")
	)
	(arc
		(start 98.875596 -262.548116)
		(mid 98.596393 -262.623756)
		(end 98.316288 -262.551418)
		(width 0.088646)
		(layer "In11.Cu")
		(net "M_D_CPU1_SA_DQS_DN<9>")
	)
	(arc
		(start 98.304604 -262.544814)
		(mid 98.119749 -262.497864)
		(end 97.935796 -262.548116)
		(width 0.088646)
		(layer "In11.Cu")
		(net "M_D_CPU1_SA_DQS_DN<9>")
	)
	(arc
		(start 100.372926 -262.81507)
		(mid 100.164544 -262.534676)
		(end 99.815396 -262.548116)
		(width 0.088646)
		(layer "In11.Cu")
		(net "M_D_CPU1_SA_DQS_DN<9>")
	)
	(arc
		(start 89.477342 -262.547862)
		(mid 89.195038 -262.623418)
		(end 88.9127 -262.547862)
		(width 0.088646)
		(layer "In11.Cu")
		(net "M_D_CPU1_SA_DQS_DN<9>")
	)
	(arc
		(start 87.597996 -262.548116)
		(mid 87.315294 -262.623892)
		(end 87.032592 -262.548116)
		(width 0.088646)
		(layer "In11.Cu")
		(net "M_D_CPU1_SA_DQS_DN<9>")
	)
	(arc
		(start 94.176596 -262.548116)
		(mid 93.897393 -262.623756)
		(end 93.617288 -262.551418)
		(width 0.088646)
		(layer "In11.Cu")
		(net "M_D_CPU1_SA_DQS_DN<9>")
	)
	(arc
		(start 92.665804 -262.544814)
		(mid 92.480949 -262.497864)
		(end 92.296996 -262.548116)
		(width 0.088646)
		(layer "In11.Cu")
		(net "M_D_CPU1_SA_DQS_DN<9>")
	)
	(arc
		(start 92.296996 -262.548116)
		(mid 92.017793 -262.623756)
		(end 91.737688 -262.551418)
		(width 0.088646)
		(layer "In11.Cu")
		(net "M_D_CPU1_SA_DQS_DN<9>")
	)
	(arc
		(start 90.786204 -262.544814)
		(mid 90.601349 -262.497864)
		(end 90.417396 -262.548116)
		(width 0.088646)
		(layer "In11.Cu")
		(net "M_D_CPU1_SA_DQS_DN<9>")
	)
	(arc
		(start 93.605604 -262.544814)
		(mid 93.420749 -262.497864)
		(end 93.236796 -262.548116)
		(width 0.088646)
		(layer "In11.Cu")
		(net "M_D_CPU1_SA_DQS_DN<9>")
	)
	(arc
		(start 96.056196 -262.548116)
		(mid 95.776993 -262.623756)
		(end 95.496888 -262.551418)
		(width 0.088646)
		(layer "In11.Cu")
		(net "M_D_CPU1_SA_DQS_DN<9>")
	)
	(arc
		(start 86.658196 -262.548116)
		(mid 86.375494 -262.623892)
		(end 86.092792 -262.548116)
		(width 0.088646)
		(layer "In11.Cu")
		(net "M_D_CPU1_SA_DQS_DN<9>")
	)
	(arc
		(start 88.912192 -262.548116)
		(mid 88.724994 -262.497973)
		(end 88.537796 -262.548116)
		(width 0.088646)
		(layer "In11.Cu")
		(net "M_D_CPU1_SA_DQS_DN<9>")
	)
	(arc
		(start 85.718396 -262.548116)
		(mid 85.435694 -262.623892)
		(end 85.152992 -262.548116)
		(width 0.088646)
		(layer "In11.Cu")
		(net "M_D_CPU1_SA_DQS_DN<9>")
	)
	(arc
		(start 93.236796 -262.548116)
		(mid 92.957593 -262.623756)
		(end 92.677488 -262.551418)
		(width 0.088646)
		(layer "In11.Cu")
		(net "M_D_CPU1_SA_DQS_DN<9>")
	)
	(arc
		(start 87.972392 -262.548116)
		(mid 87.785194 -262.497973)
		(end 87.597996 -262.548116)
		(width 0.088646)
		(layer "In11.Cu")
		(net "M_D_CPU1_SA_DQS_DN<9>")
	)
	(arc
		(start 89.851738 -262.547608)
		(mid 89.664511 -262.49766)
		(end 89.477342 -262.547862)
		(width 0.088646)
		(layer "In11.Cu")
		(net "M_D_CPU1_SA_DQS_DN<9>")
	)
	(arc
		(start 91.357196 -262.548116)
		(mid 91.077993 -262.623756)
		(end 90.797888 -262.551418)
		(width 0.088646)
		(layer "In11.Cu")
		(net "M_D_CPU1_SA_DQS_DN<9>")
	)
	(arc
		(start 85.152992 -262.548116)
		(mid 84.975148 -262.497728)
		(end 84.794852 -262.538464)
		(width 0.088646)
		(layer "In11.Cu")
		(net "M_D_CPU1_SA_DQS_DN<9>")
	)
	(arc
		(start 86.092792 -262.548116)
		(mid 85.905594 -262.497973)
		(end 85.718396 -262.548116)
		(width 0.088646)
		(layer "In11.Cu")
		(net "M_D_CPU1_SA_DQS_DN<9>")
	)
	(arc
		(start 99.244404 -262.544814)
		(mid 99.059549 -262.497864)
		(end 98.875596 -262.548116)
		(width 0.088646)
		(layer "In11.Cu")
		(net "M_D_CPU1_SA_DQS_DN<9>")
	)
	(segment
		(start 18.329148 -283.755592)
		(end 17.693132 -283.33065)
		(width 0.20066)
		(layer "F.Cu")
		(net "M_D_CPU1_SA_DQS_DN<8>")
	)
	(segment
		(start 19.032728 -283.755592)
		(end 18.329148 -283.755592)
		(width 0.20066)
		(layer "F.Cu")
		(net "M_D_CPU1_SA_DQS_DN<8>")
	)
	(segment
		(start 14.569694 -283.591762)
		(end 14.560042 -283.601414)
		(width 0.101854)
		(layer "F.Cu")
		(net "M_D_CPU1_SA_DQS_DN<8>")
	)
	(segment
		(start 19.784314 -284.016704)
		(end 19.29384 -284.016704)
		(width 0.20066)
		(layer "F.Cu")
		(net "M_D_CPU1_SA_DQS_DN<8>")
	)
	(segment
		(start 17.693132 -283.33065)
		(end 17.28851 -283.33065)
		(width 0.20066)
		(layer "F.Cu")
		(net "M_D_CPU1_SA_DQS_DN<8>")
	)
	(segment
		(start 17.28851 -283.33065)
		(end 17.027398 -283.591762)
		(width 0.20066)
		(layer "F.Cu")
		(net "M_D_CPU1_SA_DQS_DN<8>")
	)
	(segment
		(start 17.027398 -283.591762)
		(end 16.885158 -283.591762)
		(width 0.20066)
		(layer "F.Cu")
		(net "M_D_CPU1_SA_DQS_DN<8>")
	)
	(segment
		(start 16.885158 -283.591762)
		(end 14.807692 -283.591762)
		(width 0.1016)
		(layer "F.Cu")
		(net "M_D_CPU1_SA_DQS_DN<8>")
	)
	(segment
		(start 14.376908 -283.601414)
		(end 14.108684 -283.33319)
		(width 0.20066)
		(layer "F.Cu")
		(net "M_D_CPU1_SA_DQS_DN<8>")
	)
	(segment
		(start 100.002848 -267.219938)
		(end 100.002594 -267.220192)
		(width 0.20066)
		(layer "F.Cu")
		(net "M_D_CPU1_SA_DQS_DN<8>")
	)
	(segment
		(start 13.868908 -283.33319)
		(end 13.446506 -283.755592)
		(width 0.20066)
		(layer "F.Cu")
		(net "M_D_CPU1_SA_DQS_DN<8>")
	)
	(segment
		(start 19.29384 -284.016704)
		(end 19.032728 -283.755592)
		(width 0.20066)
		(layer "F.Cu")
		(net "M_D_CPU1_SA_DQS_DN<8>")
	)
	(segment
		(start 14.108684 -283.33319)
		(end 13.868908 -283.33319)
		(width 0.20066)
		(layer "F.Cu")
		(net "M_D_CPU1_SA_DQS_DN<8>")
	)
	(segment
		(start 20.889214 -284.016704)
		(end 19.784314 -284.016704)
		(width 0.20066)
		(layer "F.Cu")
		(net "M_D_CPU1_SA_DQS_DN<8>")
	)
	(segment
		(start 100.002594 -267.220192)
		(end 100.002594 -267.755878)
		(width 0.20066)
		(layer "F.Cu")
		(net "M_D_CPU1_SA_DQS_DN<8>")
	)
	(segment
		(start 12.712192 -284.016704)
		(end 12.240514 -284.016704)
		(width 0.20066)
		(layer "F.Cu")
		(net "M_D_CPU1_SA_DQS_DN<8>")
	)
	(segment
		(start 12.973304 -283.755592)
		(end 12.712192 -284.016704)
		(width 0.20066)
		(layer "F.Cu")
		(net "M_D_CPU1_SA_DQS_DN<8>")
	)
	(segment
		(start 14.560042 -283.601414)
		(end 14.376908 -283.601414)
		(width 0.20066)
		(layer "F.Cu")
		(net "M_D_CPU1_SA_DQS_DN<8>")
	)
	(segment
		(start 13.446506 -283.755592)
		(end 12.973304 -283.755592)
		(width 0.20066)
		(layer "F.Cu")
		(net "M_D_CPU1_SA_DQS_DN<8>")
	)
	(segment
		(start 14.807692 -283.591762)
		(end 14.569694 -283.591762)
		(width 0.101854)
		(layer "F.Cu")
		(net "M_D_CPU1_SA_DQS_DN<8>")
	)
	(segment
		(start 61.23305 -281.027378)
		(end 59.583574 -281.027378)
		(width 0.18288)
		(layer "In11.Cu")
		(net "M_D_CPU1_SA_DQS_DN<8>")
	)
	(segment
		(start 83.337908 -269.02029)
		(end 83.022948 -269.02029)
		(width 0.088646)
		(layer "In11.Cu")
		(net "M_D_CPU1_SA_DQS_DN<8>")
	)
	(segment
		(start 47.144178 -283.590492)
		(end 46.766226 -283.590492)
		(width 0.18288)
		(layer "In11.Cu")
		(net "M_D_CPU1_SA_DQS_DN<8>")
	)
	(segment
		(start 55.232554 -282.483814)
		(end 51.519328 -282.483814)
		(width 0.18288)
		(layer "In11.Cu")
		(net "M_D_CPU1_SA_DQS_DN<8>")
	)
	(segment
		(start 28.233116 -283.229304)
		(end 26.439876 -283.229304)
		(width 0.18288)
		(layer "In11.Cu")
		(net "M_D_CPU1_SA_DQS_DN<8>")
	)
	(segment
		(start 100.315268 -267.755878)
		(end 100.372672 -267.698474)
		(width 0.088646)
		(layer "In11.Cu")
		(net "M_D_CPU1_SA_DQS_DN<8>")
	)
	(segment
		(start 84.496402 -267.507212)
		(end 84.250276 -267.507212)
		(width 0.088646)
		(layer "In11.Cu")
		(net "M_D_CPU1_SA_DQS_DN<8>")
	)
	(segment
		(start 94.176596 -267.43152)
		(end 94.161864 -267.440156)
		(width 0.088646)
		(layer "In11.Cu")
		(net "M_D_CPU1_SA_DQS_DN<8>")
	)
	(segment
		(start 45.754798 -283.313632)
		(end 45.173392 -282.732226)
		(width 0.18288)
		(layer "In11.Cu")
		(net "M_D_CPU1_SA_DQS_DN<8>")
	)
	(segment
		(start 44.37126 -282.732226)
		(end 43.968162 -283.135324)
		(width 0.18288)
		(layer "In11.Cu")
		(net "M_D_CPU1_SA_DQS_DN<8>")
	)
	(segment
		(start 66.83375 -279.991312)
		(end 65.475104 -279.991312)
		(width 0.18288)
		(layer "In11.Cu")
		(net "M_D_CPU1_SA_DQS_DN<8>")
	)
	(segment
		(start 30.661864 -283.333698)
		(end 30.061408 -282.733242)
		(width 0.18288)
		(layer "In11.Cu")
		(net "M_D_CPU1_SA_DQS_DN<8>")
	)
	(segment
		(start 57.317132 -281.85364)
		(end 57.192672 -281.72918)
		(width 0.18288)
		(layer "In11.Cu")
		(net "M_D_CPU1_SA_DQS_DN<8>")
	)
	(segment
		(start 35.282632 -282.47213)
		(end 34.930842 -282.82392)
		(width 0.18288)
		(layer "In11.Cu")
		(net "M_D_CPU1_SA_DQS_DN<8>")
	)
	(segment
		(start 93.236796 -267.43152)
		(end 93.222064 -267.440156)
		(width 0.088646)
		(layer "In11.Cu")
		(net "M_D_CPU1_SA_DQS_DN<8>")
	)
	(segment
		(start 33.732978 -283.32049)
		(end 32.343852 -283.32049)
		(width 0.18288)
		(layer "In11.Cu")
		(net "M_D_CPU1_SA_DQS_DN<8>")
	)
	(segment
		(start 99.815396 -267.43152)
		(end 99.800664 -267.440156)
		(width 0.088646)
		(layer "In11.Cu")
		(net "M_D_CPU1_SA_DQS_DN<8>")
	)
	(segment
		(start 46.766226 -283.590492)
		(end 46.489366 -283.313632)
		(width 0.18288)
		(layer "In11.Cu")
		(net "M_D_CPU1_SA_DQS_DN<8>")
	)
	(segment
		(start 57.865772 -281.85364)
		(end 57.317132 -281.85364)
		(width 0.18288)
		(layer "In11.Cu")
		(net "M_D_CPU1_SA_DQS_DN<8>")
	)
	(segment
		(start 62.730888 -280.723848)
		(end 61.53658 -280.723848)
		(width 0.18288)
		(layer "In11.Cu")
		(net "M_D_CPU1_SA_DQS_DN<8>")
	)
	(segment
		(start 21.805646 -283.972)
		(end 21.566378 -283.732732)
		(width 0.18288)
		(layer "In11.Cu")
		(net "M_D_CPU1_SA_DQS_DN<8>")
	)
	(segment
		(start 55.987188 -281.72918)
		(end 55.232554 -282.483814)
		(width 0.18288)
		(layer "In11.Cu")
		(net "M_D_CPU1_SA_DQS_DN<8>")
	)
	(segment
		(start 36.44646 -282.454858)
		(end 36.158678 -282.74264)
		(width 0.18288)
		(layer "In11.Cu")
		(net "M_D_CPU1_SA_DQS_DN<8>")
	)
	(segment
		(start 77.744828 -269.080234)
		(end 66.83375 -279.991312)
		(width 0.18288)
		(layer "In11.Cu")
		(net "M_D_CPU1_SA_DQS_DN<8>")
	)
	(segment
		(start 21.173186 -283.732732)
		(end 20.889214 -284.016704)
		(width 0.18288)
		(layer "In11.Cu")
		(net "M_D_CPU1_SA_DQS_DN<8>")
	)
	(segment
		(start 31.6865 -283.592778)
		(end 31.42742 -283.333698)
		(width 0.18288)
		(layer "In11.Cu")
		(net "M_D_CPU1_SA_DQS_DN<8>")
	)
	(segment
		(start 64.802004 -280.115772)
		(end 64.677544 -279.991312)
		(width 0.18288)
		(layer "In11.Cu")
		(net "M_D_CPU1_SA_DQS_DN<8>")
	)
	(segment
		(start 92.296996 -267.43152)
		(end 92.282264 -267.440156)
		(width 0.088646)
		(layer "In11.Cu")
		(net "M_D_CPU1_SA_DQS_DN<8>")
	)
	(segment
		(start 64.677544 -279.991312)
		(end 63.463424 -279.991312)
		(width 0.18288)
		(layer "In11.Cu")
		(net "M_D_CPU1_SA_DQS_DN<8>")
	)
	(segment
		(start 35.786314 -282.74264)
		(end 35.515804 -282.47213)
		(width 0.18288)
		(layer "In11.Cu")
		(net "M_D_CPU1_SA_DQS_DN<8>")
	)
	(segment
		(start 26.439876 -283.229304)
		(end 24.646636 -283.972)
		(width 0.18288)
		(layer "In11.Cu")
		(net "M_D_CPU1_SA_DQS_DN<8>")
	)
	(segment
		(start 32.071564 -283.592778)
		(end 31.6865 -283.592778)
		(width 0.18288)
		(layer "In11.Cu")
		(net "M_D_CPU1_SA_DQS_DN<8>")
	)
	(segment
		(start 61.53658 -280.723848)
		(end 61.23305 -281.027378)
		(width 0.18288)
		(layer "In11.Cu")
		(net "M_D_CPU1_SA_DQS_DN<8>")
	)
	(segment
		(start 88.538304 -267.431266)
		(end 88.537796 -267.43152)
		(width 0.088646)
		(layer "In11.Cu")
		(net "M_D_CPU1_SA_DQS_DN<8>")
	)
	(segment
		(start 96.99625 -267.43152)
		(end 96.985836 -267.437616)
		(width 0.088646)
		(layer "In11.Cu")
		(net "M_D_CPU1_SA_DQS_DN<8>")
	)
	(segment
		(start 57.192672 -281.72918)
		(end 55.987188 -281.72918)
		(width 0.18288)
		(layer "In11.Cu")
		(net "M_D_CPU1_SA_DQS_DN<8>")
	)
	(segment
		(start 34.930842 -282.82392)
		(end 33.732978 -283.32049)
		(width 0.18288)
		(layer "In11.Cu")
		(net "M_D_CPU1_SA_DQS_DN<8>")
	)
	(segment
		(start 90.80246 -267.437616)
		(end 90.792046 -267.43152)
		(width 0.088646)
		(layer "In11.Cu")
		(net "M_D_CPU1_SA_DQS_DN<8>")
	)
	(segment
		(start 49.001426 -283.30906)
		(end 47.42561 -283.30906)
		(width 0.18288)
		(layer "In11.Cu")
		(net "M_D_CPU1_SA_DQS_DN<8>")
	)
	(segment
		(start 43.968162 -283.135324)
		(end 43.261026 -283.428186)
		(width 0.18288)
		(layer "In11.Cu")
		(net "M_D_CPU1_SA_DQS_DN<8>")
	)
	(segment
		(start 49.847754 -282.462732)
		(end 49.001426 -283.30906)
		(width 0.18288)
		(layer "In11.Cu")
		(net "M_D_CPU1_SA_DQS_DN<8>")
	)
	(segment
		(start 83.84794 -267.831316)
		(end 83.84794 -268.387322)
		(width 0.088646)
		(layer "In11.Cu")
		(net "M_D_CPU1_SA_DQS_DN<8>")
	)
	(segment
		(start 39.420292 -282.454858)
		(end 36.44646 -282.454858)
		(width 0.18288)
		(layer "In11.Cu")
		(net "M_D_CPU1_SA_DQS_DN<8>")
	)
	(segment
		(start 31.42742 -283.333698)
		(end 30.661864 -283.333698)
		(width 0.18288)
		(layer "In11.Cu")
		(net "M_D_CPU1_SA_DQS_DN<8>")
	)
	(segment
		(start 89.862406 -267.437616)
		(end 89.851992 -267.43152)
		(width 0.088646)
		(layer "In11.Cu")
		(net "M_D_CPU1_SA_DQS_DN<8>")
	)
	(segment
		(start 63.463424 -279.991312)
		(end 62.730888 -280.723848)
		(width 0.18288)
		(layer "In11.Cu")
		(net "M_D_CPU1_SA_DQS_DN<8>")
	)
	(segment
		(start 57.990232 -281.72918)
		(end 57.865772 -281.85364)
		(width 0.18288)
		(layer "In11.Cu")
		(net "M_D_CPU1_SA_DQS_DN<8>")
	)
	(segment
		(start 96.056196 -267.43152)
		(end 96.041464 -267.440156)
		(width 0.088646)
		(layer "In11.Cu")
		(net "M_D_CPU1_SA_DQS_DN<8>")
	)
	(segment
		(start 65.350644 -280.115772)
		(end 64.802004 -280.115772)
		(width 0.18288)
		(layer "In11.Cu")
		(net "M_D_CPU1_SA_DQS_DN<8>")
	)
	(segment
		(start 47.42561 -283.30906)
		(end 47.144178 -283.590492)
		(width 0.18288)
		(layer "In11.Cu")
		(net "M_D_CPU1_SA_DQS_DN<8>")
	)
	(segment
		(start 95.116396 -267.43152)
		(end 95.101664 -267.440156)
		(width 0.088646)
		(layer "In11.Cu")
		(net "M_D_CPU1_SA_DQS_DN<8>")
	)
	(segment
		(start 41.768522 -283.428186)
		(end 39.420292 -282.454858)
		(width 0.18288)
		(layer "In11.Cu")
		(net "M_D_CPU1_SA_DQS_DN<8>")
	)
	(segment
		(start 30.061408 -282.733242)
		(end 29.431234 -282.733242)
		(width 0.18288)
		(layer "In11.Cu")
		(net "M_D_CPU1_SA_DQS_DN<8>")
	)
	(segment
		(start 43.261026 -283.428186)
		(end 41.768522 -283.428186)
		(width 0.18288)
		(layer "In11.Cu")
		(net "M_D_CPU1_SA_DQS_DN<8>")
	)
	(segment
		(start 24.646636 -283.972)
		(end 21.805646 -283.972)
		(width 0.18288)
		(layer "In11.Cu")
		(net "M_D_CPU1_SA_DQS_DN<8>")
	)
	(segment
		(start 51.262534 -282.740608)
		(end 50.861214 -282.740608)
		(width 0.18288)
		(layer "In11.Cu")
		(net "M_D_CPU1_SA_DQS_DN<8>")
	)
	(segment
		(start 51.519328 -282.483814)
		(end 51.262534 -282.740608)
		(width 0.18288)
		(layer "In11.Cu")
		(net "M_D_CPU1_SA_DQS_DN<8>")
	)
	(segment
		(start 83.553046 -268.682216)
		(end 83.553046 -268.805152)
		(width 0.088646)
		(layer "In11.Cu")
		(net "M_D_CPU1_SA_DQS_DN<8>")
	)
	(segment
		(start 84.116672 -267.562838)
		(end 83.84794 -267.831316)
		(width 0.088646)
		(layer "In11.Cu")
		(net "M_D_CPU1_SA_DQS_DN<8>")
	)
	(segment
		(start 65.475104 -279.991312)
		(end 65.350644 -280.115772)
		(width 0.18288)
		(layer "In11.Cu")
		(net "M_D_CPU1_SA_DQS_DN<8>")
	)
	(segment
		(start 45.173392 -282.732226)
		(end 44.37126 -282.732226)
		(width 0.18288)
		(layer "In11.Cu")
		(net "M_D_CPU1_SA_DQS_DN<8>")
	)
	(segment
		(start 46.489366 -283.313632)
		(end 45.754798 -283.313632)
		(width 0.18288)
		(layer "In11.Cu")
		(net "M_D_CPU1_SA_DQS_DN<8>")
	)
	(segment
		(start 97.38106 -267.437616)
		(end 97.370646 -267.43152)
		(width 0.088646)
		(layer "In11.Cu")
		(net "M_D_CPU1_SA_DQS_DN<8>")
	)
	(segment
		(start 36.158678 -282.74264)
		(end 35.786314 -282.74264)
		(width 0.18288)
		(layer "In11.Cu")
		(net "M_D_CPU1_SA_DQS_DN<8>")
	)
	(segment
		(start 83.84794 -268.387322)
		(end 83.553046 -268.682216)
		(width 0.088646)
		(layer "In11.Cu")
		(net "M_D_CPU1_SA_DQS_DN<8>")
	)
	(segment
		(start 29.431234 -282.733242)
		(end 28.233116 -283.229304)
		(width 0.18288)
		(layer "In11.Cu")
		(net "M_D_CPU1_SA_DQS_DN<8>")
	)
	(segment
		(start 35.515804 -282.47213)
		(end 35.282632 -282.47213)
		(width 0.18288)
		(layer "In11.Cu")
		(net "M_D_CPU1_SA_DQS_DN<8>")
	)
	(segment
		(start 83.022948 -269.02029)
		(end 82.963004 -269.080234)
		(width 0.088646)
		(layer "In11.Cu")
		(net "M_D_CPU1_SA_DQS_DN<8>")
	)
	(segment
		(start 32.343852 -283.32049)
		(end 32.071564 -283.592778)
		(width 0.18288)
		(layer "In11.Cu")
		(net "M_D_CPU1_SA_DQS_DN<8>")
	)
	(segment
		(start 84.250276 -267.507212)
		(end 84.116672 -267.562838)
		(width 0.088646)
		(layer "In11.Cu")
		(net "M_D_CPU1_SA_DQS_DN<8>")
	)
	(segment
		(start 98.875596 -267.43152)
		(end 98.860864 -267.440156)
		(width 0.088646)
		(layer "In11.Cu")
		(net "M_D_CPU1_SA_DQS_DN<8>")
	)
	(segment
		(start 58.881772 -281.72918)
		(end 57.990232 -281.72918)
		(width 0.18288)
		(layer "In11.Cu")
		(net "M_D_CPU1_SA_DQS_DN<8>")
	)
	(segment
		(start 59.583574 -281.027378)
		(end 58.881772 -281.72918)
		(width 0.18288)
		(layer "In11.Cu")
		(net "M_D_CPU1_SA_DQS_DN<8>")
	)
	(segment
		(start 83.553046 -268.805152)
		(end 83.337908 -269.02029)
		(width 0.088646)
		(layer "In11.Cu")
		(net "M_D_CPU1_SA_DQS_DN<8>")
	)
	(segment
		(start 50.583338 -282.462732)
		(end 49.847754 -282.462732)
		(width 0.18288)
		(layer "In11.Cu")
		(net "M_D_CPU1_SA_DQS_DN<8>")
	)
	(segment
		(start 21.566378 -283.732732)
		(end 21.173186 -283.732732)
		(width 0.18288)
		(layer "In11.Cu")
		(net "M_D_CPU1_SA_DQS_DN<8>")
	)
	(segment
		(start 50.861214 -282.740608)
		(end 50.583338 -282.462732)
		(width 0.18288)
		(layer "In11.Cu")
		(net "M_D_CPU1_SA_DQS_DN<8>")
	)
	(segment
		(start 100.002594 -267.755878)
		(end 100.315268 -267.755878)
		(width 0.088646)
		(layer "In11.Cu")
		(net "M_D_CPU1_SA_DQS_DN<8>")
	)
	(segment
		(start 82.963004 -269.080234)
		(end 77.744828 -269.080234)
		(width 0.18288)
		(layer "In11.Cu")
		(net "M_D_CPU1_SA_DQS_DN<8>")
	)
	(arc
		(start 92.282264 -267.440156)
		(mid 92.005823 -267.507322)
		(end 91.731592 -267.43152)
		(width 0.088646)
		(layer "In11.Cu")
		(net "M_D_CPU1_SA_DQS_DN<8>")
	)
	(arc
		(start 100.372672 -267.698474)
		(mid 100.164389 -267.418128)
		(end 99.815396 -267.43152)
		(width 0.088646)
		(layer "In11.Cu")
		(net "M_D_CPU1_SA_DQS_DN<8>")
	)
	(arc
		(start 89.851992 -267.43152)
		(mid 89.664794 -267.381377)
		(end 89.477596 -267.43152)
		(width 0.088646)
		(layer "In11.Cu")
		(net "M_D_CPU1_SA_DQS_DN<8>")
	)
	(arc
		(start 91.731592 -267.43152)
		(mid 91.544394 -267.381377)
		(end 91.357196 -267.43152)
		(width 0.088646)
		(layer "In11.Cu")
		(net "M_D_CPU1_SA_DQS_DN<8>")
	)
	(arc
		(start 96.041464 -267.440156)
		(mid 95.765023 -267.507322)
		(end 95.490792 -267.43152)
		(width 0.088646)
		(layer "In11.Cu")
		(net "M_D_CPU1_SA_DQS_DN<8>")
	)
	(arc
		(start 89.477596 -267.43152)
		(mid 89.194894 -267.507262)
		(end 88.912192 -267.43152)
		(width 0.088646)
		(layer "In11.Cu")
		(net "M_D_CPU1_SA_DQS_DN<8>")
	)
	(arc
		(start 87.972392 -267.43152)
		(mid 87.785194 -267.381377)
		(end 87.597996 -267.43152)
		(width 0.088646)
		(layer "In11.Cu")
		(net "M_D_CPU1_SA_DQS_DN<8>")
	)
	(arc
		(start 94.161864 -267.440156)
		(mid 93.885423 -267.507322)
		(end 93.611192 -267.43152)
		(width 0.088646)
		(layer "In11.Cu")
		(net "M_D_CPU1_SA_DQS_DN<8>")
	)
	(arc
		(start 93.222064 -267.440156)
		(mid 92.945623 -267.507322)
		(end 92.671392 -267.43152)
		(width 0.088646)
		(layer "In11.Cu")
		(net "M_D_CPU1_SA_DQS_DN<8>")
	)
	(arc
		(start 99.249992 -267.43152)
		(mid 99.062794 -267.381377)
		(end 98.875596 -267.43152)
		(width 0.088646)
		(layer "In11.Cu")
		(net "M_D_CPU1_SA_DQS_DN<8>")
	)
	(arc
		(start 84.778596 -267.43152)
		(mid 84.642476 -267.487933)
		(end 84.496402 -267.507212)
		(width 0.088646)
		(layer "In11.Cu")
		(net "M_D_CPU1_SA_DQS_DN<8>")
	)
	(arc
		(start 92.671392 -267.43152)
		(mid 92.484194 -267.381377)
		(end 92.296996 -267.43152)
		(width 0.088646)
		(layer "In11.Cu")
		(net "M_D_CPU1_SA_DQS_DN<8>")
	)
	(arc
		(start 96.430592 -267.43152)
		(mid 96.243394 -267.381377)
		(end 96.056196 -267.43152)
		(width 0.088646)
		(layer "In11.Cu")
		(net "M_D_CPU1_SA_DQS_DN<8>")
	)
	(arc
		(start 86.092792 -267.43152)
		(mid 85.905594 -267.381377)
		(end 85.718396 -267.43152)
		(width 0.088646)
		(layer "In11.Cu")
		(net "M_D_CPU1_SA_DQS_DN<8>")
	)
	(arc
		(start 97.935796 -267.43152)
		(mid 97.659237 -267.507229)
		(end 97.38106 -267.437616)
		(width 0.088646)
		(layer "In11.Cu")
		(net "M_D_CPU1_SA_DQS_DN<8>")
	)
	(arc
		(start 99.800664 -267.440156)
		(mid 99.524223 -267.507322)
		(end 99.249992 -267.43152)
		(width 0.088646)
		(layer "In11.Cu")
		(net "M_D_CPU1_SA_DQS_DN<8>")
	)
	(arc
		(start 87.597996 -267.43152)
		(mid 87.315294 -267.507262)
		(end 87.032592 -267.43152)
		(width 0.088646)
		(layer "In11.Cu")
		(net "M_D_CPU1_SA_DQS_DN<8>")
	)
	(arc
		(start 85.718396 -267.43152)
		(mid 85.435694 -267.507262)
		(end 85.152992 -267.43152)
		(width 0.088646)
		(layer "In11.Cu")
		(net "M_D_CPU1_SA_DQS_DN<8>")
	)
	(arc
		(start 85.152992 -267.43152)
		(mid 84.965794 -267.381377)
		(end 84.778596 -267.43152)
		(width 0.088646)
		(layer "In11.Cu")
		(net "M_D_CPU1_SA_DQS_DN<8>")
	)
	(arc
		(start 94.550992 -267.43152)
		(mid 94.363794 -267.381377)
		(end 94.176596 -267.43152)
		(width 0.088646)
		(layer "In11.Cu")
		(net "M_D_CPU1_SA_DQS_DN<8>")
	)
	(arc
		(start 95.490792 -267.43152)
		(mid 95.303594 -267.381377)
		(end 95.116396 -267.43152)
		(width 0.088646)
		(layer "In11.Cu")
		(net "M_D_CPU1_SA_DQS_DN<8>")
	)
	(arc
		(start 97.370646 -267.43152)
		(mid 97.183448 -267.381377)
		(end 96.99625 -267.43152)
		(width 0.088646)
		(layer "In11.Cu")
		(net "M_D_CPU1_SA_DQS_DN<8>")
	)
	(arc
		(start 90.792046 -267.43152)
		(mid 90.604848 -267.381377)
		(end 90.41765 -267.43152)
		(width 0.088646)
		(layer "In11.Cu")
		(net "M_D_CPU1_SA_DQS_DN<8>")
	)
	(arc
		(start 93.611192 -267.43152)
		(mid 93.423994 -267.381377)
		(end 93.236796 -267.43152)
		(width 0.088646)
		(layer "In11.Cu")
		(net "M_D_CPU1_SA_DQS_DN<8>")
	)
	(arc
		(start 87.032592 -267.43152)
		(mid 86.845394 -267.381377)
		(end 86.658196 -267.43152)
		(width 0.088646)
		(layer "In11.Cu")
		(net "M_D_CPU1_SA_DQS_DN<8>")
	)
	(arc
		(start 88.912192 -267.43152)
		(mid 88.725277 -267.381377)
		(end 88.538304 -267.431266)
		(width 0.088646)
		(layer "In11.Cu")
		(net "M_D_CPU1_SA_DQS_DN<8>")
	)
	(arc
		(start 98.310192 -267.43152)
		(mid 98.122994 -267.381377)
		(end 97.935796 -267.43152)
		(width 0.088646)
		(layer "In11.Cu")
		(net "M_D_CPU1_SA_DQS_DN<8>")
	)
	(arc
		(start 86.658196 -267.43152)
		(mid 86.375494 -267.507262)
		(end 86.092792 -267.43152)
		(width 0.088646)
		(layer "In11.Cu")
		(net "M_D_CPU1_SA_DQS_DN<8>")
	)
	(arc
		(start 90.41765 -267.43152)
		(mid 90.140837 -267.507356)
		(end 89.862406 -267.437616)
		(width 0.088646)
		(layer "In11.Cu")
		(net "M_D_CPU1_SA_DQS_DN<8>")
	)
	(arc
		(start 95.101664 -267.440156)
		(mid 94.825223 -267.507322)
		(end 94.550992 -267.43152)
		(width 0.088646)
		(layer "In11.Cu")
		(net "M_D_CPU1_SA_DQS_DN<8>")
	)
	(arc
		(start 96.985836 -267.437616)
		(mid 96.707404 -267.50743)
		(end 96.430592 -267.43152)
		(width 0.088646)
		(layer "In11.Cu")
		(net "M_D_CPU1_SA_DQS_DN<8>")
	)
	(arc
		(start 91.357196 -267.43152)
		(mid 91.080637 -267.507229)
		(end 90.80246 -267.437616)
		(width 0.088646)
		(layer "In11.Cu")
		(net "M_D_CPU1_SA_DQS_DN<8>")
	)
	(arc
		(start 98.860864 -267.440156)
		(mid 98.584423 -267.507322)
		(end 98.310192 -267.43152)
		(width 0.088646)
		(layer "In11.Cu")
		(net "M_D_CPU1_SA_DQS_DN<8>")
	)
	(arc
		(start 88.537796 -267.43152)
		(mid 88.255094 -267.507262)
		(end 87.972392 -267.43152)
		(width 0.088646)
		(layer "In11.Cu")
		(net "M_D_CPU1_SA_DQS_DN<8>")
	)
	(segment
		(start 14.560042 -292.951408)
		(end 14.376908 -292.951408)
		(width 0.20066)
		(layer "F.Cu")
		(net "M_D_CPU1_SA_DQS_DN<7>")
	)
	(segment
		(start 17.693132 -292.680644)
		(end 17.28851 -292.680644)
		(width 0.20066)
		(layer "F.Cu")
		(net "M_D_CPU1_SA_DQS_DN<7>")
	)
	(segment
		(start 13.446506 -293.105586)
		(end 12.973304 -293.105586)
		(width 0.20066)
		(layer "F.Cu")
		(net "M_D_CPU1_SA_DQS_DN<7>")
	)
	(segment
		(start 14.571218 -292.941756)
		(end 14.561566 -292.951408)
		(width 0.101854)
		(layer "F.Cu")
		(net "M_D_CPU1_SA_DQS_DN<7>")
	)
	(segment
		(start 14.561566 -292.951408)
		(end 14.560042 -292.951408)
		(width 0.101854)
		(layer "F.Cu")
		(net "M_D_CPU1_SA_DQS_DN<7>")
	)
	(segment
		(start 19.784314 -293.366698)
		(end 19.29384 -293.366698)
		(width 0.20066)
		(layer "F.Cu")
		(net "M_D_CPU1_SA_DQS_DN<7>")
	)
	(segment
		(start 12.712192 -293.366698)
		(end 12.240514 -293.366698)
		(width 0.20066)
		(layer "F.Cu")
		(net "M_D_CPU1_SA_DQS_DN<7>")
	)
	(segment
		(start 12.973304 -293.105586)
		(end 12.712192 -293.366698)
		(width 0.20066)
		(layer "F.Cu")
		(net "M_D_CPU1_SA_DQS_DN<7>")
	)
	(segment
		(start 14.376908 -292.951408)
		(end 14.108684 -292.683184)
		(width 0.20066)
		(layer "F.Cu")
		(net "M_D_CPU1_SA_DQS_DN<7>")
	)
	(segment
		(start 19.29384 -293.366698)
		(end 19.032728 -293.105586)
		(width 0.20066)
		(layer "F.Cu")
		(net "M_D_CPU1_SA_DQS_DN<7>")
	)
	(segment
		(start 20.889214 -293.366698)
		(end 19.784314 -293.366698)
		(width 0.20066)
		(layer "F.Cu")
		(net "M_D_CPU1_SA_DQS_DN<7>")
	)
	(segment
		(start 16.885158 -292.941756)
		(end 14.807692 -292.941756)
		(width 0.1016)
		(layer "F.Cu")
		(net "M_D_CPU1_SA_DQS_DN<7>")
	)
	(segment
		(start 18.329148 -293.105586)
		(end 17.693132 -292.680644)
		(width 0.20066)
		(layer "F.Cu")
		(net "M_D_CPU1_SA_DQS_DN<7>")
	)
	(segment
		(start 17.027398 -292.941756)
		(end 16.885158 -292.941756)
		(width 0.20066)
		(layer "F.Cu")
		(net "M_D_CPU1_SA_DQS_DN<7>")
	)
	(segment
		(start 19.032728 -293.105586)
		(end 18.329148 -293.105586)
		(width 0.20066)
		(layer "F.Cu")
		(net "M_D_CPU1_SA_DQS_DN<7>")
	)
	(segment
		(start 14.807692 -292.941756)
		(end 14.571218 -292.941756)
		(width 0.101854)
		(layer "F.Cu")
		(net "M_D_CPU1_SA_DQS_DN<7>")
	)
	(segment
		(start 13.868908 -292.683184)
		(end 13.446506 -293.105586)
		(width 0.20066)
		(layer "F.Cu")
		(net "M_D_CPU1_SA_DQS_DN<7>")
	)
	(segment
		(start 17.28851 -292.680644)
		(end 17.027398 -292.941756)
		(width 0.20066)
		(layer "F.Cu")
		(net "M_D_CPU1_SA_DQS_DN<7>")
	)
	(segment
		(start 14.108684 -292.683184)
		(end 13.868908 -292.683184)
		(width 0.20066)
		(layer "F.Cu")
		(net "M_D_CPU1_SA_DQS_DN<7>")
	)
	(arc
		(start 100.002848 -272.103342)
		(mid 100.002784 -272.371312)
		(end 100.002594 -272.639282)
		(width 0.20066)
		(layer "F.Cu")
		(net "M_D_CPU1_SA_DQS_DN<7>")
	)
	(segment
		(start 99.815396 -272.314924)
		(end 99.800664 -272.32356)
		(width 0.088646)
		(layer "In11.Cu")
		(net "M_D_CPU1_SA_DQS_DN<7>")
	)
	(segment
		(start 25.348946 -293.318692)
		(end 22.094698 -293.318692)
		(width 0.18288)
		(layer "In11.Cu")
		(net "M_D_CPU1_SA_DQS_DN<7>")
	)
	(segment
		(start 65.614804 -289.294316)
		(end 65.490344 -289.418776)
		(width 0.18288)
		(layer "In11.Cu")
		(net "M_D_CPU1_SA_DQS_DN<7>")
	)
	(segment
		(start 31.37789 -295.218612)
		(end 30.868874 -295.218612)
		(width 0.18288)
		(layer "In11.Cu")
		(net "M_D_CPU1_SA_DQS_DN<7>")
	)
	(segment
		(start 95.116396 -272.314924)
		(end 95.101664 -272.32356)
		(width 0.088646)
		(layer "In11.Cu")
		(net "M_D_CPU1_SA_DQS_DN<7>")
	)
	(segment
		(start 40.7543 -293.761668)
		(end 40.315896 -294.200072)
		(width 0.18288)
		(layer "In11.Cu")
		(net "M_D_CPU1_SA_DQS_DN<7>")
	)
	(segment
		(start 44.420282 -294.616886)
		(end 43.984418 -295.05275)
		(width 0.18288)
		(layer "In11.Cu")
		(net "M_D_CPU1_SA_DQS_DN<7>")
	)
	(segment
		(start 60.449968 -290.38296)
		(end 59.550046 -290.38296)
		(width 0.18288)
		(layer "In11.Cu")
		(net "M_D_CPU1_SA_DQS_DN<7>")
	)
	(segment
		(start 32.138874 -295.4909)
		(end 31.650178 -295.4909)
		(width 0.18288)
		(layer "In11.Cu")
		(net "M_D_CPU1_SA_DQS_DN<7>")
	)
	(segment
		(start 83.593178 -274.802092)
		(end 83.36026 -275.03501)
		(width 0.088646)
		(layer "In11.Cu")
		(net "M_D_CPU1_SA_DQS_DN<7>")
	)
	(segment
		(start 84.475066 -272.60677)
		(end 84.475066 -273.581622)
		(width 0.088646)
		(layer "In11.Cu")
		(net "M_D_CPU1_SA_DQS_DN<7>")
	)
	(segment
		(start 83.064858 -275.094954)
		(end 80.48498 -275.094954)
		(width 0.18288)
		(layer "In11.Cu")
		(net "M_D_CPU1_SA_DQS_DN<7>")
	)
	(segment
		(start 83.36026 -275.03501)
		(end 83.124802 -275.03501)
		(width 0.088646)
		(layer "In11.Cu")
		(net "M_D_CPU1_SA_DQS_DN<7>")
	)
	(segment
		(start 97.38106 -272.32102)
		(end 97.370646 -272.314924)
		(width 0.088646)
		(layer "In11.Cu")
		(net "M_D_CPU1_SA_DQS_DN<7>")
	)
	(segment
		(start 35.489388 -294.385492)
		(end 35.46856 -294.364664)
		(width 0.18288)
		(layer "In11.Cu")
		(net "M_D_CPU1_SA_DQS_DN<7>")
	)
	(segment
		(start 50.219864 -294.431212)
		(end 48.8696 -295.223184)
		(width 0.18288)
		(layer "In11.Cu")
		(net "M_D_CPU1_SA_DQS_DN<7>")
	)
	(segment
		(start 90.80246 -272.32102)
		(end 90.792046 -272.314924)
		(width 0.088646)
		(layer "In11.Cu")
		(net "M_D_CPU1_SA_DQS_DN<7>")
	)
	(segment
		(start 66.285618 -289.294316)
		(end 65.614804 -289.294316)
		(width 0.18288)
		(layer "In11.Cu")
		(net "M_D_CPU1_SA_DQS_DN<7>")
	)
	(segment
		(start 84.965794 -272.264124)
		(end 84.817712 -272.264124)
		(width 0.088646)
		(layer "In11.Cu")
		(net "M_D_CPU1_SA_DQS_DN<7>")
	)
	(segment
		(start 28.67787 -295.391586)
		(end 28.311348 -295.391586)
		(width 0.18288)
		(layer "In11.Cu")
		(net "M_D_CPU1_SA_DQS_DN<7>")
	)
	(segment
		(start 43.340274 -295.05275)
		(end 42.68216 -294.816276)
		(width 0.18288)
		(layer "In11.Cu")
		(net "M_D_CPU1_SA_DQS_DN<7>")
	)
	(segment
		(start 53.622448 -293.268146)
		(end 52.50561 -294.38473)
		(width 0.18288)
		(layer "In11.Cu")
		(net "M_D_CPU1_SA_DQS_DN<7>")
	)
	(segment
		(start 54.863746 -293.268146)
		(end 53.622448 -293.268146)
		(width 0.18288)
		(layer "In11.Cu")
		(net "M_D_CPU1_SA_DQS_DN<7>")
	)
	(segment
		(start 62.728348 -290.38296)
		(end 61.247528 -290.38296)
		(width 0.18288)
		(layer "In11.Cu")
		(net "M_D_CPU1_SA_DQS_DN<7>")
	)
	(segment
		(start 92.296996 -272.314924)
		(end 92.282264 -272.32356)
		(width 0.088646)
		(layer "In11.Cu")
		(net "M_D_CPU1_SA_DQS_DN<7>")
	)
	(segment
		(start 30.868874 -295.218612)
		(end 30.241494 -295.845992)
		(width 0.18288)
		(layer "In11.Cu")
		(net "M_D_CPU1_SA_DQS_DN<7>")
	)
	(segment
		(start 39.42715 -294.324532)
		(end 38.87851 -294.324532)
		(width 0.18288)
		(layer "In11.Cu")
		(net "M_D_CPU1_SA_DQS_DN<7>")
	)
	(segment
		(start 98.875596 -272.314924)
		(end 98.860864 -272.32356)
		(width 0.088646)
		(layer "In11.Cu")
		(net "M_D_CPU1_SA_DQS_DN<7>")
	)
	(segment
		(start 93.236796 -272.314924)
		(end 93.222064 -272.32356)
		(width 0.088646)
		(layer "In11.Cu")
		(net "M_D_CPU1_SA_DQS_DN<7>")
	)
	(segment
		(start 61.247528 -290.38296)
		(end 61.123068 -290.50742)
		(width 0.18288)
		(layer "In11.Cu")
		(net "M_D_CPU1_SA_DQS_DN<7>")
	)
	(segment
		(start 36.164266 -294.640762)
		(end 35.750246 -294.640762)
		(width 0.18288)
		(layer "In11.Cu")
		(net "M_D_CPU1_SA_DQS_DN<7>")
	)
	(segment
		(start 48.8696 -295.223184)
		(end 47.42053 -295.223184)
		(width 0.18288)
		(layer "In11.Cu")
		(net "M_D_CPU1_SA_DQS_DN<7>")
	)
	(segment
		(start 51.51501 -294.38473)
		(end 51.258978 -294.640762)
		(width 0.18288)
		(layer "In11.Cu")
		(net "M_D_CPU1_SA_DQS_DN<7>")
	)
	(segment
		(start 32.409892 -295.219882)
		(end 32.138874 -295.4909)
		(width 0.18288)
		(layer "In11.Cu")
		(net "M_D_CPU1_SA_DQS_DN<7>")
	)
	(segment
		(start 56.783986 -292.472872)
		(end 54.863746 -293.268146)
		(width 0.18288)
		(layer "In11.Cu")
		(net "M_D_CPU1_SA_DQS_DN<7>")
	)
	(segment
		(start 59.550046 -290.38296)
		(end 58.71464 -291.218366)
		(width 0.18288)
		(layer "In11.Cu")
		(net "M_D_CPU1_SA_DQS_DN<7>")
	)
	(segment
		(start 38.106096 -294.200072)
		(end 37.692838 -294.371268)
		(width 0.18288)
		(layer "In11.Cu")
		(net "M_D_CPU1_SA_DQS_DN<7>")
	)
	(segment
		(start 58.038238 -291.218366)
		(end 56.783986 -292.472872)
		(width 0.18288)
		(layer "In11.Cu")
		(net "M_D_CPU1_SA_DQS_DN<7>")
	)
	(segment
		(start 50.837846 -294.640762)
		(end 50.628296 -294.431212)
		(width 0.18288)
		(layer "In11.Cu")
		(net "M_D_CPU1_SA_DQS_DN<7>")
	)
	(segment
		(start 46.50359 -295.222168)
		(end 45.755052 -295.222168)
		(width 0.18288)
		(layer "In11.Cu")
		(net "M_D_CPU1_SA_DQS_DN<7>")
	)
	(segment
		(start 41.627806 -293.761668)
		(end 40.7543 -293.761668)
		(width 0.18288)
		(layer "In11.Cu")
		(net "M_D_CPU1_SA_DQS_DN<7>")
	)
	(segment
		(start 42.68216 -294.816276)
		(end 41.627806 -293.761668)
		(width 0.18288)
		(layer "In11.Cu")
		(net "M_D_CPU1_SA_DQS_DN<7>")
	)
	(segment
		(start 84.475066 -273.581622)
		(end 83.593178 -274.46351)
		(width 0.088646)
		(layer "In11.Cu")
		(net "M_D_CPU1_SA_DQS_DN<7>")
	)
	(segment
		(start 36.43376 -294.371268)
		(end 36.164266 -294.640762)
		(width 0.18288)
		(layer "In11.Cu")
		(net "M_D_CPU1_SA_DQS_DN<7>")
	)
	(segment
		(start 34.995104 -294.364664)
		(end 34.139886 -295.219882)
		(width 0.18288)
		(layer "In11.Cu")
		(net "M_D_CPU1_SA_DQS_DN<7>")
	)
	(segment
		(start 28.311348 -295.391586)
		(end 26.867104 -293.947342)
		(width 0.18288)
		(layer "In11.Cu")
		(net "M_D_CPU1_SA_DQS_DN<7>")
	)
	(segment
		(start 83.593178 -274.46351)
		(end 83.593178 -274.802092)
		(width 0.088646)
		(layer "In11.Cu")
		(net "M_D_CPU1_SA_DQS_DN<7>")
	)
	(segment
		(start 96.99625 -272.314924)
		(end 96.985836 -272.32102)
		(width 0.088646)
		(layer "In11.Cu")
		(net "M_D_CPU1_SA_DQS_DN<7>")
	)
	(segment
		(start 84.817712 -272.264124)
		(end 84.475066 -272.60677)
		(width 0.088646)
		(layer "In11.Cu")
		(net "M_D_CPU1_SA_DQS_DN<7>")
	)
	(segment
		(start 31.650178 -295.4909)
		(end 31.37789 -295.218612)
		(width 0.18288)
		(layer "In11.Cu")
		(net "M_D_CPU1_SA_DQS_DN<7>")
	)
	(segment
		(start 35.46856 -294.364664)
		(end 34.995104 -294.364664)
		(width 0.18288)
		(layer "In11.Cu")
		(net "M_D_CPU1_SA_DQS_DN<7>")
	)
	(segment
		(start 87.04326 -272.32102)
		(end 87.032846 -272.314924)
		(width 0.088646)
		(layer "In11.Cu")
		(net "M_D_CPU1_SA_DQS_DN<7>")
	)
	(segment
		(start 86.103206 -272.32102)
		(end 86.092792 -272.314924)
		(width 0.088646)
		(layer "In11.Cu")
		(net "M_D_CPU1_SA_DQS_DN<7>")
	)
	(segment
		(start 89.477596 -272.314924)
		(end 89.467182 -272.32102)
		(width 0.088646)
		(layer "In11.Cu")
		(net "M_D_CPU1_SA_DQS_DN<7>")
	)
	(segment
		(start 50.628296 -294.431212)
		(end 50.219864 -294.431212)
		(width 0.18288)
		(layer "In11.Cu")
		(net "M_D_CPU1_SA_DQS_DN<7>")
	)
	(segment
		(start 85.16366 -272.32102)
		(end 85.153246 -272.314924)
		(width 0.088646)
		(layer "In11.Cu")
		(net "M_D_CPU1_SA_DQS_DN<7>")
	)
	(segment
		(start 47.152814 -295.4909)
		(end 46.772322 -295.4909)
		(width 0.18288)
		(layer "In11.Cu")
		(net "M_D_CPU1_SA_DQS_DN<7>")
	)
	(segment
		(start 52.50561 -294.38473)
		(end 51.51501 -294.38473)
		(width 0.18288)
		(layer "In11.Cu")
		(net "M_D_CPU1_SA_DQS_DN<7>")
	)
	(segment
		(start 45.14977 -294.616886)
		(end 44.420282 -294.616886)
		(width 0.18288)
		(layer "In11.Cu")
		(net "M_D_CPU1_SA_DQS_DN<7>")
	)
	(segment
		(start 94.176596 -272.314924)
		(end 94.161864 -272.32356)
		(width 0.088646)
		(layer "In11.Cu")
		(net "M_D_CPU1_SA_DQS_DN<7>")
	)
	(segment
		(start 46.772322 -295.4909)
		(end 46.50359 -295.222168)
		(width 0.18288)
		(layer "In11.Cu")
		(net "M_D_CPU1_SA_DQS_DN<7>")
	)
	(segment
		(start 45.755052 -295.222168)
		(end 45.14977 -294.616886)
		(width 0.18288)
		(layer "In11.Cu")
		(net "M_D_CPU1_SA_DQS_DN<7>")
	)
	(segment
		(start 58.71464 -291.218366)
		(end 58.038238 -291.218366)
		(width 0.18288)
		(layer "In11.Cu")
		(net "M_D_CPU1_SA_DQS_DN<7>")
	)
	(segment
		(start 29.132276 -295.845992)
		(end 28.67787 -295.391586)
		(width 0.18288)
		(layer "In11.Cu")
		(net "M_D_CPU1_SA_DQS_DN<7>")
	)
	(segment
		(start 22.094698 -293.318692)
		(end 21.546058 -293.091616)
		(width 0.18288)
		(layer "In11.Cu")
		(net "M_D_CPU1_SA_DQS_DN<7>")
	)
	(segment
		(start 38.75405 -294.200072)
		(end 38.106096 -294.200072)
		(width 0.18288)
		(layer "In11.Cu")
		(net "M_D_CPU1_SA_DQS_DN<7>")
	)
	(segment
		(start 47.42053 -295.223184)
		(end 47.152814 -295.4909)
		(width 0.18288)
		(layer "In11.Cu")
		(net "M_D_CPU1_SA_DQS_DN<7>")
	)
	(segment
		(start 21.164296 -293.091616)
		(end 20.889214 -293.366698)
		(width 0.18288)
		(layer "In11.Cu")
		(net "M_D_CPU1_SA_DQS_DN<7>")
	)
	(segment
		(start 30.241494 -295.845992)
		(end 29.132276 -295.845992)
		(width 0.18288)
		(layer "In11.Cu")
		(net "M_D_CPU1_SA_DQS_DN<7>")
	)
	(segment
		(start 80.48498 -275.094954)
		(end 66.285618 -289.294316)
		(width 0.18288)
		(layer "In11.Cu")
		(net "M_D_CPU1_SA_DQS_DN<7>")
	)
	(segment
		(start 60.574428 -290.50742)
		(end 60.449968 -290.38296)
		(width 0.18288)
		(layer "In11.Cu")
		(net "M_D_CPU1_SA_DQS_DN<7>")
	)
	(segment
		(start 43.984418 -295.05275)
		(end 43.340274 -295.05275)
		(width 0.18288)
		(layer "In11.Cu")
		(net "M_D_CPU1_SA_DQS_DN<7>")
	)
	(segment
		(start 37.692838 -294.371268)
		(end 36.43376 -294.371268)
		(width 0.18288)
		(layer "In11.Cu")
		(net "M_D_CPU1_SA_DQS_DN<7>")
	)
	(segment
		(start 64.941704 -289.418776)
		(end 64.817244 -289.294316)
		(width 0.18288)
		(layer "In11.Cu")
		(net "M_D_CPU1_SA_DQS_DN<7>")
	)
	(segment
		(start 26.867104 -293.947342)
		(end 25.348946 -293.318692)
		(width 0.18288)
		(layer "In11.Cu")
		(net "M_D_CPU1_SA_DQS_DN<7>")
	)
	(segment
		(start 87.982806 -272.32102)
		(end 87.972392 -272.314924)
		(width 0.088646)
		(layer "In11.Cu")
		(net "M_D_CPU1_SA_DQS_DN<7>")
	)
	(segment
		(start 96.056196 -272.314924)
		(end 96.041464 -272.32356)
		(width 0.088646)
		(layer "In11.Cu")
		(net "M_D_CPU1_SA_DQS_DN<7>")
	)
	(segment
		(start 83.124802 -275.03501)
		(end 83.064858 -275.094954)
		(width 0.088646)
		(layer "In11.Cu")
		(net "M_D_CPU1_SA_DQS_DN<7>")
	)
	(segment
		(start 64.817244 -289.294316)
		(end 63.816992 -289.294316)
		(width 0.18288)
		(layer "In11.Cu")
		(net "M_D_CPU1_SA_DQS_DN<7>")
	)
	(segment
		(start 40.315896 -294.200072)
		(end 39.55161 -294.200072)
		(width 0.18288)
		(layer "In11.Cu")
		(net "M_D_CPU1_SA_DQS_DN<7>")
	)
	(segment
		(start 34.139886 -295.219882)
		(end 32.409892 -295.219882)
		(width 0.18288)
		(layer "In11.Cu")
		(net "M_D_CPU1_SA_DQS_DN<7>")
	)
	(segment
		(start 35.494976 -294.385492)
		(end 35.489388 -294.385492)
		(width 0.18288)
		(layer "In11.Cu")
		(net "M_D_CPU1_SA_DQS_DN<7>")
	)
	(segment
		(start 61.123068 -290.50742)
		(end 60.574428 -290.50742)
		(width 0.18288)
		(layer "In11.Cu")
		(net "M_D_CPU1_SA_DQS_DN<7>")
	)
	(segment
		(start 21.546058 -293.091616)
		(end 21.164296 -293.091616)
		(width 0.18288)
		(layer "In11.Cu")
		(net "M_D_CPU1_SA_DQS_DN<7>")
	)
	(segment
		(start 100.002594 -272.639282)
		(end 100.315268 -272.639282)
		(width 0.088646)
		(layer "In11.Cu")
		(net "M_D_CPU1_SA_DQS_DN<7>")
	)
	(segment
		(start 38.87851 -294.324532)
		(end 38.75405 -294.200072)
		(width 0.18288)
		(layer "In11.Cu")
		(net "M_D_CPU1_SA_DQS_DN<7>")
	)
	(segment
		(start 39.55161 -294.200072)
		(end 39.42715 -294.324532)
		(width 0.18288)
		(layer "In11.Cu")
		(net "M_D_CPU1_SA_DQS_DN<7>")
	)
	(segment
		(start 51.258978 -294.640762)
		(end 50.837846 -294.640762)
		(width 0.18288)
		(layer "In11.Cu")
		(net "M_D_CPU1_SA_DQS_DN<7>")
	)
	(segment
		(start 89.862406 -272.32102)
		(end 89.851992 -272.314924)
		(width 0.088646)
		(layer "In11.Cu")
		(net "M_D_CPU1_SA_DQS_DN<7>")
	)
	(segment
		(start 65.490344 -289.418776)
		(end 64.941704 -289.418776)
		(width 0.18288)
		(layer "In11.Cu")
		(net "M_D_CPU1_SA_DQS_DN<7>")
	)
	(segment
		(start 63.816992 -289.294316)
		(end 62.728348 -290.38296)
		(width 0.18288)
		(layer "In11.Cu")
		(net "M_D_CPU1_SA_DQS_DN<7>")
	)
	(segment
		(start 100.315268 -272.639282)
		(end 100.372672 -272.581878)
		(width 0.088646)
		(layer "In11.Cu")
		(net "M_D_CPU1_SA_DQS_DN<7>")
	)
	(segment
		(start 35.750246 -294.640762)
		(end 35.494976 -294.385492)
		(width 0.18288)
		(layer "In11.Cu")
		(net "M_D_CPU1_SA_DQS_DN<7>")
	)
	(arc
		(start 89.467182 -272.32102)
		(mid 89.189004 -272.390712)
		(end 88.912446 -272.314924)
		(width 0.088646)
		(layer "In11.Cu")
		(net "M_D_CPU1_SA_DQS_DN<7>")
	)
	(arc
		(start 99.800664 -272.32356)
		(mid 99.524223 -272.390726)
		(end 99.249992 -272.314924)
		(width 0.088646)
		(layer "In11.Cu")
		(net "M_D_CPU1_SA_DQS_DN<7>")
	)
	(arc
		(start 97.370646 -272.314924)
		(mid 97.183448 -272.264781)
		(end 96.99625 -272.314924)
		(width 0.088646)
		(layer "In11.Cu")
		(net "M_D_CPU1_SA_DQS_DN<7>")
	)
	(arc
		(start 95.490792 -272.314924)
		(mid 95.303594 -272.264781)
		(end 95.116396 -272.314924)
		(width 0.088646)
		(layer "In11.Cu")
		(net "M_D_CPU1_SA_DQS_DN<7>")
	)
	(arc
		(start 96.041464 -272.32356)
		(mid 95.765023 -272.390726)
		(end 95.490792 -272.314924)
		(width 0.088646)
		(layer "In11.Cu")
		(net "M_D_CPU1_SA_DQS_DN<7>")
	)
	(arc
		(start 90.41765 -272.314924)
		(mid 90.140837 -272.39076)
		(end 89.862406 -272.32102)
		(width 0.088646)
		(layer "In11.Cu")
		(net "M_D_CPU1_SA_DQS_DN<7>")
	)
	(arc
		(start 92.671392 -272.314924)
		(mid 92.484194 -272.264781)
		(end 92.296996 -272.314924)
		(width 0.088646)
		(layer "In11.Cu")
		(net "M_D_CPU1_SA_DQS_DN<7>")
	)
	(arc
		(start 91.357196 -272.314924)
		(mid 91.080637 -272.390633)
		(end 90.80246 -272.32102)
		(width 0.088646)
		(layer "In11.Cu")
		(net "M_D_CPU1_SA_DQS_DN<7>")
	)
	(arc
		(start 93.611192 -272.314924)
		(mid 93.423994 -272.264781)
		(end 93.236796 -272.314924)
		(width 0.088646)
		(layer "In11.Cu")
		(net "M_D_CPU1_SA_DQS_DN<7>")
	)
	(arc
		(start 86.65845 -272.314924)
		(mid 86.381637 -272.39076)
		(end 86.103206 -272.32102)
		(width 0.088646)
		(layer "In11.Cu")
		(net "M_D_CPU1_SA_DQS_DN<7>")
	)
	(arc
		(start 98.860864 -272.32356)
		(mid 98.584423 -272.390726)
		(end 98.310192 -272.314924)
		(width 0.088646)
		(layer "In11.Cu")
		(net "M_D_CPU1_SA_DQS_DN<7>")
	)
	(arc
		(start 87.597996 -272.314924)
		(mid 87.321437 -272.390633)
		(end 87.04326 -272.32102)
		(width 0.088646)
		(layer "In11.Cu")
		(net "M_D_CPU1_SA_DQS_DN<7>")
	)
	(arc
		(start 98.310192 -272.314924)
		(mid 98.122994 -272.264781)
		(end 97.935796 -272.314924)
		(width 0.088646)
		(layer "In11.Cu")
		(net "M_D_CPU1_SA_DQS_DN<7>")
	)
	(arc
		(start 94.161864 -272.32356)
		(mid 93.885423 -272.390726)
		(end 93.611192 -272.314924)
		(width 0.088646)
		(layer "In11.Cu")
		(net "M_D_CPU1_SA_DQS_DN<7>")
	)
	(arc
		(start 88.912446 -272.314924)
		(mid 88.725248 -272.264781)
		(end 88.53805 -272.314924)
		(width 0.088646)
		(layer "In11.Cu")
		(net "M_D_CPU1_SA_DQS_DN<7>")
	)
	(arc
		(start 92.282264 -272.32356)
		(mid 92.005823 -272.390726)
		(end 91.731592 -272.314924)
		(width 0.088646)
		(layer "In11.Cu")
		(net "M_D_CPU1_SA_DQS_DN<7>")
	)
	(arc
		(start 87.972392 -272.314924)
		(mid 87.785194 -272.264781)
		(end 87.597996 -272.314924)
		(width 0.088646)
		(layer "In11.Cu")
		(net "M_D_CPU1_SA_DQS_DN<7>")
	)
	(arc
		(start 99.249992 -272.314924)
		(mid 99.062794 -272.264781)
		(end 98.875596 -272.314924)
		(width 0.088646)
		(layer "In11.Cu")
		(net "M_D_CPU1_SA_DQS_DN<7>")
	)
	(arc
		(start 93.222064 -272.32356)
		(mid 92.945623 -272.390726)
		(end 92.671392 -272.314924)
		(width 0.088646)
		(layer "In11.Cu")
		(net "M_D_CPU1_SA_DQS_DN<7>")
	)
	(arc
		(start 96.985836 -272.32102)
		(mid 96.707404 -272.390834)
		(end 96.430592 -272.314924)
		(width 0.088646)
		(layer "In11.Cu")
		(net "M_D_CPU1_SA_DQS_DN<7>")
	)
	(arc
		(start 95.101664 -272.32356)
		(mid 94.825223 -272.390726)
		(end 94.550992 -272.314924)
		(width 0.088646)
		(layer "In11.Cu")
		(net "M_D_CPU1_SA_DQS_DN<7>")
	)
	(arc
		(start 85.153246 -272.314924)
		(mid 85.062867 -272.277169)
		(end 84.965794 -272.264124)
		(width 0.088646)
		(layer "In11.Cu")
		(net "M_D_CPU1_SA_DQS_DN<7>")
	)
	(arc
		(start 97.935796 -272.314924)
		(mid 97.659237 -272.390633)
		(end 97.38106 -272.32102)
		(width 0.088646)
		(layer "In11.Cu")
		(net "M_D_CPU1_SA_DQS_DN<7>")
	)
	(arc
		(start 85.718396 -272.314924)
		(mid 85.441837 -272.390633)
		(end 85.16366 -272.32102)
		(width 0.088646)
		(layer "In11.Cu")
		(net "M_D_CPU1_SA_DQS_DN<7>")
	)
	(arc
		(start 90.792046 -272.314924)
		(mid 90.604848 -272.264781)
		(end 90.41765 -272.314924)
		(width 0.088646)
		(layer "In11.Cu")
		(net "M_D_CPU1_SA_DQS_DN<7>")
	)
	(arc
		(start 87.032846 -272.314924)
		(mid 86.845648 -272.264781)
		(end 86.65845 -272.314924)
		(width 0.088646)
		(layer "In11.Cu")
		(net "M_D_CPU1_SA_DQS_DN<7>")
	)
	(arc
		(start 100.372672 -272.581878)
		(mid 100.164389 -272.301532)
		(end 99.815396 -272.314924)
		(width 0.088646)
		(layer "In11.Cu")
		(net "M_D_CPU1_SA_DQS_DN<7>")
	)
	(arc
		(start 94.550992 -272.314924)
		(mid 94.363794 -272.264781)
		(end 94.176596 -272.314924)
		(width 0.088646)
		(layer "In11.Cu")
		(net "M_D_CPU1_SA_DQS_DN<7>")
	)
	(arc
		(start 88.53805 -272.314924)
		(mid 88.261237 -272.39076)
		(end 87.982806 -272.32102)
		(width 0.088646)
		(layer "In11.Cu")
		(net "M_D_CPU1_SA_DQS_DN<7>")
	)
	(arc
		(start 91.731592 -272.314924)
		(mid 91.544394 -272.264781)
		(end 91.357196 -272.314924)
		(width 0.088646)
		(layer "In11.Cu")
		(net "M_D_CPU1_SA_DQS_DN<7>")
	)
	(arc
		(start 96.430592 -272.314924)
		(mid 96.243394 -272.264781)
		(end 96.056196 -272.314924)
		(width 0.088646)
		(layer "In11.Cu")
		(net "M_D_CPU1_SA_DQS_DN<7>")
	)
	(arc
		(start 89.851992 -272.314924)
		(mid 89.664794 -272.264781)
		(end 89.477596 -272.314924)
		(width 0.088646)
		(layer "In11.Cu")
		(net "M_D_CPU1_SA_DQS_DN<7>")
	)
	(arc
		(start 86.092792 -272.314924)
		(mid 85.905594 -272.264781)
		(end 85.718396 -272.314924)
		(width 0.088646)
		(layer "In11.Cu")
		(net "M_D_CPU1_SA_DQS_DN<7>")
	)
	(segment
		(start 16.885158 -302.29175)
		(end 14.807692 -302.29175)
		(width 0.1016)
		(layer "F.Cu")
		(net "M_D_CPU1_SA_DQS_DN<6>")
	)
	(segment
		(start 14.571218 -302.29175)
		(end 14.561566 -302.301402)
		(width 0.101854)
		(layer "F.Cu")
		(net "M_D_CPU1_SA_DQS_DN<6>")
	)
	(segment
		(start 18.329148 -302.45558)
		(end 17.693132 -302.030638)
		(width 0.20066)
		(layer "F.Cu")
		(net "M_D_CPU1_SA_DQS_DN<6>")
	)
	(segment
		(start 17.28851 -302.030638)
		(end 17.027398 -302.29175)
		(width 0.20066)
		(layer "F.Cu")
		(net "M_D_CPU1_SA_DQS_DN<6>")
	)
	(segment
		(start 19.784314 -302.716692)
		(end 19.29384 -302.716692)
		(width 0.20066)
		(layer "F.Cu")
		(net "M_D_CPU1_SA_DQS_DN<6>")
	)
	(segment
		(start 19.032728 -302.45558)
		(end 18.329148 -302.45558)
		(width 0.20066)
		(layer "F.Cu")
		(net "M_D_CPU1_SA_DQS_DN<6>")
	)
	(segment
		(start 14.108684 -302.033178)
		(end 13.868908 -302.033178)
		(width 0.20066)
		(layer "F.Cu")
		(net "M_D_CPU1_SA_DQS_DN<6>")
	)
	(segment
		(start 17.027398 -302.29175)
		(end 16.885158 -302.29175)
		(width 0.20066)
		(layer "F.Cu")
		(net "M_D_CPU1_SA_DQS_DN<6>")
	)
	(segment
		(start 13.446506 -302.45558)
		(end 12.973304 -302.45558)
		(width 0.20066)
		(layer "F.Cu")
		(net "M_D_CPU1_SA_DQS_DN<6>")
	)
	(segment
		(start 14.561566 -302.301402)
		(end 14.560042 -302.301402)
		(width 0.101854)
		(layer "F.Cu")
		(net "M_D_CPU1_SA_DQS_DN<6>")
	)
	(segment
		(start 14.560042 -302.301402)
		(end 14.376908 -302.301402)
		(width 0.20066)
		(layer "F.Cu")
		(net "M_D_CPU1_SA_DQS_DN<6>")
	)
	(segment
		(start 12.973304 -302.45558)
		(end 12.712192 -302.716692)
		(width 0.20066)
		(layer "F.Cu")
		(net "M_D_CPU1_SA_DQS_DN<6>")
	)
	(segment
		(start 20.889214 -302.716692)
		(end 19.784314 -302.716692)
		(width 0.20066)
		(layer "F.Cu")
		(net "M_D_CPU1_SA_DQS_DN<6>")
	)
	(segment
		(start 13.868908 -302.033178)
		(end 13.446506 -302.45558)
		(width 0.20066)
		(layer "F.Cu")
		(net "M_D_CPU1_SA_DQS_DN<6>")
	)
	(segment
		(start 12.712192 -302.716692)
		(end 12.240514 -302.716692)
		(width 0.20066)
		(layer "F.Cu")
		(net "M_D_CPU1_SA_DQS_DN<6>")
	)
	(segment
		(start 14.807692 -302.29175)
		(end 14.571218 -302.29175)
		(width 0.101854)
		(layer "F.Cu")
		(net "M_D_CPU1_SA_DQS_DN<6>")
	)
	(segment
		(start 17.693132 -302.030638)
		(end 17.28851 -302.030638)
		(width 0.20066)
		(layer "F.Cu")
		(net "M_D_CPU1_SA_DQS_DN<6>")
	)
	(segment
		(start 14.376908 -302.301402)
		(end 14.108684 -302.033178)
		(width 0.20066)
		(layer "F.Cu")
		(net "M_D_CPU1_SA_DQS_DN<6>")
	)
	(segment
		(start 19.29384 -302.716692)
		(end 19.032728 -302.45558)
		(width 0.20066)
		(layer "F.Cu")
		(net "M_D_CPU1_SA_DQS_DN<6>")
	)
	(arc
		(start 100.002848 -276.986492)
		(mid 100.002784 -277.254462)
		(end 100.002594 -277.522432)
		(width 0.20066)
		(layer "F.Cu")
		(net "M_D_CPU1_SA_DQS_DN<6>")
	)
	(segment
		(start 40.494458 -307.949346)
		(end 39.65829 -307.113178)
		(width 0.18288)
		(layer "In11.Cu")
		(net "M_D_CPU1_SA_DQS_DN<6>")
	)
	(segment
		(start 66.65595 -299.47616)
		(end 66.391282 -299.740828)
		(width 0.18288)
		(layer "In11.Cu")
		(net "M_D_CPU1_SA_DQS_DN<6>")
	)
	(segment
		(start 52.583334 -307.14188)
		(end 51.561238 -307.14188)
		(width 0.18288)
		(layer "In11.Cu")
		(net "M_D_CPU1_SA_DQS_DN<6>")
	)
	(segment
		(start 59.856624 -301.360586)
		(end 59.575446 -301.360586)
		(width 0.18288)
		(layer "In11.Cu")
		(net "M_D_CPU1_SA_DQS_DN<6>")
	)
	(segment
		(start 85.767164 -278.338788)
		(end 85.767164 -278.929084)
		(width 0.088646)
		(layer "In11.Cu")
		(net "M_D_CPU1_SA_DQS_DN<6>")
	)
	(segment
		(start 54.486048 -305.239166)
		(end 52.583334 -307.14188)
		(width 0.18288)
		(layer "In11.Cu")
		(net "M_D_CPU1_SA_DQS_DN<6>")
	)
	(segment
		(start 46.494954 -307.998114)
		(end 45.623226 -307.998114)
		(width 0.18288)
		(layer "In11.Cu")
		(net "M_D_CPU1_SA_DQS_DN<6>")
	)
	(segment
		(start 31.423864 -307.98008)
		(end 31.411164 -307.98008)
		(width 0.18288)
		(layer "In11.Cu")
		(net "M_D_CPU1_SA_DQS_DN<6>")
	)
	(segment
		(start 35.78479 -307.3908)
		(end 35.522662 -307.128672)
		(width 0.18288)
		(layer "In11.Cu")
		(net "M_D_CPU1_SA_DQS_DN<6>")
	)
	(segment
		(start 67.590162 -299.018452)
		(end 67.132454 -299.47616)
		(width 0.18288)
		(layer "In11.Cu")
		(net "M_D_CPU1_SA_DQS_DN<6>")
	)
	(segment
		(start 31.388812 -307.957728)
		(end 30.843728 -307.957728)
		(width 0.18288)
		(layer "In11.Cu")
		(net "M_D_CPU1_SA_DQS_DN<6>")
	)
	(segment
		(start 30.843728 -307.957728)
		(end 30.21711 -308.584346)
		(width 0.18288)
		(layer "In11.Cu")
		(net "M_D_CPU1_SA_DQS_DN<6>")
	)
	(segment
		(start 58.790586 -302.145446)
		(end 57.201054 -302.145446)
		(width 0.18288)
		(layer "In11.Cu")
		(net "M_D_CPU1_SA_DQS_DN<6>")
	)
	(segment
		(start 30.21711 -308.584346)
		(end 29.52242 -308.584346)
		(width 0.18288)
		(layer "In11.Cu")
		(net "M_D_CPU1_SA_DQS_DN<6>")
	)
	(segment
		(start 96.995996 -277.198074)
		(end 96.981264 -277.20671)
		(width 0.088646)
		(layer "In11.Cu")
		(net "M_D_CPU1_SA_DQS_DN<6>")
	)
	(segment
		(start 36.164774 -307.3908)
		(end 35.78479 -307.3908)
		(width 0.18288)
		(layer "In11.Cu")
		(net "M_D_CPU1_SA_DQS_DN<6>")
	)
	(segment
		(start 28.31084 -308.082188)
		(end 27.90444 -307.675788)
		(width 0.18288)
		(layer "In11.Cu")
		(net "M_D_CPU1_SA_DQS_DN<6>")
	)
	(segment
		(start 47.180754 -308.240938)
		(end 46.737778 -308.240938)
		(width 0.18288)
		(layer "In11.Cu")
		(net "M_D_CPU1_SA_DQS_DN<6>")
	)
	(segment
		(start 83.765136 -281.20721)
		(end 83.54822 -281.424126)
		(width 0.18288)
		(layer "In11.Cu")
		(net "M_D_CPU1_SA_DQS_DN<6>")
	)
	(segment
		(start 67.766184 -299.018452)
		(end 67.590162 -299.018452)
		(width 0.18288)
		(layer "In11.Cu")
		(net "M_D_CPU1_SA_DQS_DN<6>")
	)
	(segment
		(start 31.684722 -308.240938)
		(end 31.423864 -307.98008)
		(width 0.18288)
		(layer "In11.Cu")
		(net "M_D_CPU1_SA_DQS_DN<6>")
	)
	(segment
		(start 49.97704 -307.104034)
		(end 49.101502 -307.979572)
		(width 0.18288)
		(layer "In11.Cu")
		(net "M_D_CPU1_SA_DQS_DN<6>")
	)
	(segment
		(start 89.862406 -277.20417)
		(end 89.851992 -277.198074)
		(width 0.088646)
		(layer "In11.Cu")
		(net "M_D_CPU1_SA_DQS_DN<6>")
	)
	(segment
		(start 83.54822 -281.424126)
		(end 82.678524 -281.424126)
		(width 0.18288)
		(layer "In11.Cu")
		(net "M_D_CPU1_SA_DQS_DN<6>")
	)
	(segment
		(start 66.391282 -299.740828)
		(end 65.933066 -299.740828)
		(width 0.18288)
		(layer "In11.Cu")
		(net "M_D_CPU1_SA_DQS_DN<6>")
	)
	(segment
		(start 68.154296 -298.63034)
		(end 67.766184 -299.018452)
		(width 0.18288)
		(layer "In11.Cu")
		(net "M_D_CPU1_SA_DQS_DN<6>")
	)
	(segment
		(start 32.059626 -308.240938)
		(end 31.684722 -308.240938)
		(width 0.18288)
		(layer "In11.Cu")
		(net "M_D_CPU1_SA_DQS_DN<6>")
	)
	(segment
		(start 27.90444 -307.675788)
		(end 27.649678 -307.061616)
		(width 0.18288)
		(layer "In11.Cu")
		(net "M_D_CPU1_SA_DQS_DN<6>")
	)
	(segment
		(start 55.8673 -303.4792)
		(end 55.8673 -304.413412)
		(width 0.18288)
		(layer "In11.Cu")
		(net "M_D_CPU1_SA_DQS_DN<6>")
	)
	(segment
		(start 68.154296 -298.454318)
		(end 68.154296 -298.63034)
		(width 0.18288)
		(layer "In11.Cu")
		(net "M_D_CPU1_SA_DQS_DN<6>")
	)
	(segment
		(start 26.537158 -304.698146)
		(end 25.941528 -304.698146)
		(width 0.18288)
		(layer "In11.Cu")
		(net "M_D_CPU1_SA_DQS_DN<6>")
	)
	(segment
		(start 27.649678 -307.061616)
		(end 27.649678 -305.810666)
		(width 0.18288)
		(layer "In11.Cu")
		(net "M_D_CPU1_SA_DQS_DN<6>")
	)
	(segment
		(start 21.512784 -302.455326)
		(end 21.15058 -302.455326)
		(width 0.18288)
		(layer "In11.Cu")
		(net "M_D_CPU1_SA_DQS_DN<6>")
	)
	(segment
		(start 55.8673 -304.413412)
		(end 55.041546 -305.239166)
		(width 0.18288)
		(layer "In11.Cu")
		(net "M_D_CPU1_SA_DQS_DN<6>")
	)
	(segment
		(start 44.517056 -307.321966)
		(end 43.889676 -307.949346)
		(width 0.18288)
		(layer "In11.Cu")
		(net "M_D_CPU1_SA_DQS_DN<6>")
	)
	(segment
		(start 83.765136 -281.12212)
		(end 83.765136 -281.20721)
		(width 0.088646)
		(layer "In11.Cu")
		(net "M_D_CPU1_SA_DQS_DN<6>")
	)
	(segment
		(start 90.80246 -277.20417)
		(end 90.792046 -277.198074)
		(width 0.088646)
		(layer "In11.Cu")
		(net "M_D_CPU1_SA_DQS_DN<6>")
	)
	(segment
		(start 86.174072 -277.93188)
		(end 85.767164 -278.338788)
		(width 0.088646)
		(layer "In11.Cu")
		(net "M_D_CPU1_SA_DQS_DN<6>")
	)
	(segment
		(start 24.522684 -303.648872)
		(end 22.61997 -302.859948)
		(width 0.18288)
		(layer "In11.Cu")
		(net "M_D_CPU1_SA_DQS_DN<6>")
	)
	(segment
		(start 61.58103 -300.346618)
		(end 60.870592 -300.346618)
		(width 0.18288)
		(layer "In11.Cu")
		(net "M_D_CPU1_SA_DQS_DN<6>")
	)
	(segment
		(start 35.522662 -307.128672)
		(end 35.02533 -307.128672)
		(width 0.18288)
		(layer "In11.Cu")
		(net "M_D_CPU1_SA_DQS_DN<6>")
	)
	(segment
		(start 63.173102 -300.298358)
		(end 62.606682 -300.298358)
		(width 0.18288)
		(layer "In11.Cu")
		(net "M_D_CPU1_SA_DQS_DN<6>")
	)
	(segment
		(start 21.917406 -302.859948)
		(end 21.512784 -302.455326)
		(width 0.18288)
		(layer "In11.Cu")
		(net "M_D_CPU1_SA_DQS_DN<6>")
	)
	(segment
		(start 60.870592 -300.346618)
		(end 59.856624 -301.360586)
		(width 0.18288)
		(layer "In11.Cu")
		(net "M_D_CPU1_SA_DQS_DN<6>")
	)
	(segment
		(start 88.912446 -277.198074)
		(end 88.911938 -277.198328)
		(width 0.088646)
		(layer "In11.Cu")
		(net "M_D_CPU1_SA_DQS_DN<6>")
	)
	(segment
		(start 64.694562 -300.298358)
		(end 63.970662 -300.298358)
		(width 0.18288)
		(layer "In11.Cu")
		(net "M_D_CPU1_SA_DQS_DN<6>")
	)
	(segment
		(start 68.542154 -296.299636)
		(end 68.542154 -298.06646)
		(width 0.18288)
		(layer "In11.Cu")
		(net "M_D_CPU1_SA_DQS_DN<6>")
	)
	(segment
		(start 95.116396 -277.198074)
		(end 95.101664 -277.20671)
		(width 0.088646)
		(layer "In11.Cu")
		(net "M_D_CPU1_SA_DQS_DN<6>")
	)
	(segment
		(start 22.61997 -302.859948)
		(end 21.917406 -302.859948)
		(width 0.18288)
		(layer "In11.Cu")
		(net "M_D_CPU1_SA_DQS_DN<6>")
	)
	(segment
		(start 63.297562 -300.422818)
		(end 63.173102 -300.298358)
		(width 0.18288)
		(layer "In11.Cu")
		(net "M_D_CPU1_SA_DQS_DN<6>")
	)
	(segment
		(start 39.65829 -307.113178)
		(end 36.442396 -307.113178)
		(width 0.18288)
		(layer "In11.Cu")
		(net "M_D_CPU1_SA_DQS_DN<6>")
	)
	(segment
		(start 31.411164 -307.98008)
		(end 31.388812 -307.957728)
		(width 0.18288)
		(layer "In11.Cu")
		(net "M_D_CPU1_SA_DQS_DN<6>")
	)
	(segment
		(start 88.92286 -277.20417)
		(end 88.912446 -277.198074)
		(width 0.088646)
		(layer "In11.Cu")
		(net "M_D_CPU1_SA_DQS_DN<6>")
	)
	(segment
		(start 61.825378 -300.590966)
		(end 61.58103 -300.346618)
		(width 0.18288)
		(layer "In11.Cu")
		(net "M_D_CPU1_SA_DQS_DN<6>")
	)
	(segment
		(start 59.575446 -301.360586)
		(end 58.790586 -302.145446)
		(width 0.18288)
		(layer "In11.Cu")
		(net "M_D_CPU1_SA_DQS_DN<6>")
	)
	(segment
		(start 67.132454 -299.47616)
		(end 66.65595 -299.47616)
		(width 0.18288)
		(layer "In11.Cu")
		(net "M_D_CPU1_SA_DQS_DN<6>")
	)
	(segment
		(start 44.947078 -307.321966)
		(end 44.517056 -307.321966)
		(width 0.18288)
		(layer "In11.Cu")
		(net "M_D_CPU1_SA_DQS_DN<6>")
	)
	(segment
		(start 29.52242 -308.584346)
		(end 28.31084 -308.082188)
		(width 0.18288)
		(layer "In11.Cu")
		(net "M_D_CPU1_SA_DQS_DN<6>")
	)
	(segment
		(start 65.684908 -299.49267)
		(end 65.50025 -299.49267)
		(width 0.18288)
		(layer "In11.Cu")
		(net "M_D_CPU1_SA_DQS_DN<6>")
	)
	(segment
		(start 50.866294 -307.3908)
		(end 50.579528 -307.104034)
		(width 0.18288)
		(layer "In11.Cu")
		(net "M_D_CPU1_SA_DQS_DN<6>")
	)
	(segment
		(start 82.678524 -281.424126)
		(end 72.264016 -291.838634)
		(width 0.18288)
		(layer "In11.Cu")
		(net "M_D_CPU1_SA_DQS_DN<6>")
	)
	(segment
		(start 47.44212 -307.979572)
		(end 47.180754 -308.240938)
		(width 0.18288)
		(layer "In11.Cu")
		(net "M_D_CPU1_SA_DQS_DN<6>")
	)
	(segment
		(start 93.236796 -277.198074)
		(end 93.222064 -277.20671)
		(width 0.088646)
		(layer "In11.Cu")
		(net "M_D_CPU1_SA_DQS_DN<6>")
	)
	(segment
		(start 35.02533 -307.128672)
		(end 34.183066 -307.970936)
		(width 0.18288)
		(layer "In11.Cu")
		(net "M_D_CPU1_SA_DQS_DN<6>")
	)
	(segment
		(start 85.767164 -278.929084)
		(end 84.622386 -280.073862)
		(width 0.088646)
		(layer "In11.Cu")
		(net "M_D_CPU1_SA_DQS_DN<6>")
	)
	(segment
		(start 88.207088 -277.337012)
		(end 87.712804 -277.667466)
		(width 0.088646)
		(layer "In11.Cu")
		(net "M_D_CPU1_SA_DQS_DN<6>")
	)
	(segment
		(start 50.579528 -307.104034)
		(end 49.97704 -307.104034)
		(width 0.18288)
		(layer "In11.Cu")
		(net "M_D_CPU1_SA_DQS_DN<6>")
	)
	(segment
		(start 49.101502 -307.979572)
		(end 47.44212 -307.979572)
		(width 0.18288)
		(layer "In11.Cu")
		(net "M_D_CPU1_SA_DQS_DN<6>")
	)
	(segment
		(start 21.15058 -302.455326)
		(end 20.889214 -302.716692)
		(width 0.18288)
		(layer "In11.Cu")
		(net "M_D_CPU1_SA_DQS_DN<6>")
	)
	(segment
		(start 99.815396 -277.198074)
		(end 99.800664 -277.20671)
		(width 0.088646)
		(layer "In11.Cu")
		(net "M_D_CPU1_SA_DQS_DN<6>")
	)
	(segment
		(start 65.50025 -299.49267)
		(end 64.694562 -300.298358)
		(width 0.18288)
		(layer "In11.Cu")
		(net "M_D_CPU1_SA_DQS_DN<6>")
	)
	(segment
		(start 68.542154 -298.06646)
		(end 68.154296 -298.454318)
		(width 0.18288)
		(layer "In11.Cu")
		(net "M_D_CPU1_SA_DQS_DN<6>")
	)
	(segment
		(start 94.176596 -277.198074)
		(end 94.161864 -277.20671)
		(width 0.088646)
		(layer "In11.Cu")
		(net "M_D_CPU1_SA_DQS_DN<6>")
	)
	(segment
		(start 63.970662 -300.298358)
		(end 63.846202 -300.422818)
		(width 0.18288)
		(layer "In11.Cu")
		(net "M_D_CPU1_SA_DQS_DN<6>")
	)
	(segment
		(start 34.183066 -307.970936)
		(end 32.329628 -307.970936)
		(width 0.18288)
		(layer "In11.Cu")
		(net "M_D_CPU1_SA_DQS_DN<6>")
	)
	(segment
		(start 100.002594 -277.522432)
		(end 100.315268 -277.522432)
		(width 0.088646)
		(layer "In11.Cu")
		(net "M_D_CPU1_SA_DQS_DN<6>")
	)
	(segment
		(start 84.622386 -280.26487)
		(end 83.765136 -281.12212)
		(width 0.088646)
		(layer "In11.Cu")
		(net "M_D_CPU1_SA_DQS_DN<6>")
	)
	(segment
		(start 72.264016 -292.577774)
		(end 68.542154 -296.299636)
		(width 0.18288)
		(layer "In11.Cu")
		(net "M_D_CPU1_SA_DQS_DN<6>")
	)
	(segment
		(start 65.933066 -299.740828)
		(end 65.684908 -299.49267)
		(width 0.18288)
		(layer "In11.Cu")
		(net "M_D_CPU1_SA_DQS_DN<6>")
	)
	(segment
		(start 27.649678 -305.810666)
		(end 26.537158 -304.698146)
		(width 0.18288)
		(layer "In11.Cu")
		(net "M_D_CPU1_SA_DQS_DN<6>")
	)
	(segment
		(start 92.296996 -277.198074)
		(end 92.282264 -277.20671)
		(width 0.088646)
		(layer "In11.Cu")
		(net "M_D_CPU1_SA_DQS_DN<6>")
	)
	(segment
		(start 51.312318 -307.3908)
		(end 50.866294 -307.3908)
		(width 0.18288)
		(layer "In11.Cu")
		(net "M_D_CPU1_SA_DQS_DN<6>")
	)
	(segment
		(start 72.264016 -291.838634)
		(end 72.264016 -292.577774)
		(width 0.18288)
		(layer "In11.Cu")
		(net "M_D_CPU1_SA_DQS_DN<6>")
	)
	(segment
		(start 88.537542 -277.198328)
		(end 88.537288 -277.19782)
		(width 0.088646)
		(layer "In11.Cu")
		(net "M_D_CPU1_SA_DQS_DN<6>")
	)
	(segment
		(start 84.622386 -280.073862)
		(end 84.622386 -280.26487)
		(width 0.088646)
		(layer "In11.Cu")
		(net "M_D_CPU1_SA_DQS_DN<6>")
	)
	(segment
		(start 55.041546 -305.239166)
		(end 54.486048 -305.239166)
		(width 0.18288)
		(layer "In11.Cu")
		(net "M_D_CPU1_SA_DQS_DN<6>")
	)
	(segment
		(start 32.329628 -307.970936)
		(end 32.059626 -308.240938)
		(width 0.18288)
		(layer "In11.Cu")
		(net "M_D_CPU1_SA_DQS_DN<6>")
	)
	(segment
		(start 98.875596 -277.198074)
		(end 98.860864 -277.20671)
		(width 0.088646)
		(layer "In11.Cu")
		(net "M_D_CPU1_SA_DQS_DN<6>")
	)
	(segment
		(start 96.056196 -277.198074)
		(end 96.041464 -277.20671)
		(width 0.088646)
		(layer "In11.Cu")
		(net "M_D_CPU1_SA_DQS_DN<6>")
	)
	(segment
		(start 100.315268 -277.522432)
		(end 100.372672 -277.465028)
		(width 0.088646)
		(layer "In11.Cu")
		(net "M_D_CPU1_SA_DQS_DN<6>")
	)
	(segment
		(start 46.737778 -308.240938)
		(end 46.494954 -307.998114)
		(width 0.18288)
		(layer "In11.Cu")
		(net "M_D_CPU1_SA_DQS_DN<6>")
	)
	(segment
		(start 62.606682 -300.298358)
		(end 62.314074 -300.590966)
		(width 0.18288)
		(layer "In11.Cu")
		(net "M_D_CPU1_SA_DQS_DN<6>")
	)
	(segment
		(start 43.889676 -307.949346)
		(end 40.494458 -307.949346)
		(width 0.18288)
		(layer "In11.Cu")
		(net "M_D_CPU1_SA_DQS_DN<6>")
	)
	(segment
		(start 25.941528 -304.698146)
		(end 25.310592 -304.43678)
		(width 0.18288)
		(layer "In11.Cu")
		(net "M_D_CPU1_SA_DQS_DN<6>")
	)
	(segment
		(start 25.310592 -304.43678)
		(end 24.522684 -303.648872)
		(width 0.18288)
		(layer "In11.Cu")
		(net "M_D_CPU1_SA_DQS_DN<6>")
	)
	(segment
		(start 63.846202 -300.422818)
		(end 63.297562 -300.422818)
		(width 0.18288)
		(layer "In11.Cu")
		(net "M_D_CPU1_SA_DQS_DN<6>")
	)
	(segment
		(start 51.561238 -307.14188)
		(end 51.312318 -307.3908)
		(width 0.18288)
		(layer "In11.Cu")
		(net "M_D_CPU1_SA_DQS_DN<6>")
	)
	(segment
		(start 62.314074 -300.590966)
		(end 61.825378 -300.590966)
		(width 0.18288)
		(layer "In11.Cu")
		(net "M_D_CPU1_SA_DQS_DN<6>")
	)
	(segment
		(start 86.913466 -277.93188)
		(end 86.174072 -277.93188)
		(width 0.088646)
		(layer "In11.Cu")
		(net "M_D_CPU1_SA_DQS_DN<6>")
	)
	(segment
		(start 57.201054 -302.145446)
		(end 55.8673 -303.4792)
		(width 0.18288)
		(layer "In11.Cu")
		(net "M_D_CPU1_SA_DQS_DN<6>")
	)
	(segment
		(start 36.442396 -307.113178)
		(end 36.164774 -307.3908)
		(width 0.18288)
		(layer "In11.Cu")
		(net "M_D_CPU1_SA_DQS_DN<6>")
	)
	(segment
		(start 45.623226 -307.998114)
		(end 44.947078 -307.321966)
		(width 0.18288)
		(layer "In11.Cu")
		(net "M_D_CPU1_SA_DQS_DN<6>")
	)
	(arc
		(start 91.357196 -277.198074)
		(mid 91.080637 -277.273817)
		(end 90.80246 -277.20417)
		(width 0.088646)
		(layer "In11.Cu")
		(net "M_D_CPU1_SA_DQS_DN<6>")
	)
	(arc
		(start 97.935796 -277.198074)
		(mid 97.653094 -277.27385)
		(end 97.370392 -277.198074)
		(width 0.088646)
		(layer "In11.Cu")
		(net "M_D_CPU1_SA_DQS_DN<6>")
	)
	(arc
		(start 100.372672 -277.465028)
		(mid 100.16435 -277.184874)
		(end 99.815396 -277.198074)
		(width 0.088646)
		(layer "In11.Cu")
		(net "M_D_CPU1_SA_DQS_DN<6>")
	)
	(arc
		(start 99.249992 -277.198074)
		(mid 99.062794 -277.147931)
		(end 98.875596 -277.198074)
		(width 0.088646)
		(layer "In11.Cu")
		(net "M_D_CPU1_SA_DQS_DN<6>")
	)
	(arc
		(start 97.370392 -277.198074)
		(mid 97.183194 -277.147931)
		(end 96.995996 -277.198074)
		(width 0.088646)
		(layer "In11.Cu")
		(net "M_D_CPU1_SA_DQS_DN<6>")
	)
	(arc
		(start 99.800664 -277.20671)
		(mid 99.524189 -277.27403)
		(end 99.249992 -277.198074)
		(width 0.088646)
		(layer "In11.Cu")
		(net "M_D_CPU1_SA_DQS_DN<6>")
	)
	(arc
		(start 93.222064 -277.20671)
		(mid 92.945589 -277.27403)
		(end 92.671392 -277.198074)
		(width 0.088646)
		(layer "In11.Cu")
		(net "M_D_CPU1_SA_DQS_DN<6>")
	)
	(arc
		(start 88.537288 -277.19782)
		(mid 88.464758 -277.233138)
		(end 88.387936 -277.257764)
		(width 0.088646)
		(layer "In11.Cu")
		(net "M_D_CPU1_SA_DQS_DN<6>")
	)
	(arc
		(start 87.67572 -277.692358)
		(mid 87.312954 -277.870549)
		(end 86.913466 -277.93188)
		(width 0.088646)
		(layer "In11.Cu")
		(net "M_D_CPU1_SA_DQS_DN<6>")
	)
	(arc
		(start 93.611192 -277.198074)
		(mid 93.423994 -277.147931)
		(end 93.236796 -277.198074)
		(width 0.088646)
		(layer "In11.Cu")
		(net "M_D_CPU1_SA_DQS_DN<6>")
	)
	(arc
		(start 95.101664 -277.20671)
		(mid 94.825189 -277.27403)
		(end 94.550992 -277.198074)
		(width 0.088646)
		(layer "In11.Cu")
		(net "M_D_CPU1_SA_DQS_DN<6>")
	)
	(arc
		(start 96.430592 -277.198074)
		(mid 96.243394 -277.147931)
		(end 96.056196 -277.198074)
		(width 0.088646)
		(layer "In11.Cu")
		(net "M_D_CPU1_SA_DQS_DN<6>")
	)
	(arc
		(start 90.41765 -277.198074)
		(mid 90.140837 -277.273944)
		(end 89.862406 -277.20417)
		(width 0.088646)
		(layer "In11.Cu")
		(net "M_D_CPU1_SA_DQS_DN<6>")
	)
	(arc
		(start 88.911938 -277.198328)
		(mid 88.72474 -277.148185)
		(end 88.537542 -277.198328)
		(width 0.088646)
		(layer "In11.Cu")
		(net "M_D_CPU1_SA_DQS_DN<6>")
	)
	(arc
		(start 96.981264 -277.20671)
		(mid 96.704789 -277.27403)
		(end 96.430592 -277.198074)
		(width 0.088646)
		(layer "In11.Cu")
		(net "M_D_CPU1_SA_DQS_DN<6>")
	)
	(arc
		(start 89.851992 -277.198074)
		(mid 89.664794 -277.147931)
		(end 89.477596 -277.198074)
		(width 0.088646)
		(layer "In11.Cu")
		(net "M_D_CPU1_SA_DQS_DN<6>")
	)
	(arc
		(start 92.282264 -277.20671)
		(mid 92.005789 -277.27403)
		(end 91.731592 -277.198074)
		(width 0.088646)
		(layer "In11.Cu")
		(net "M_D_CPU1_SA_DQS_DN<6>")
	)
	(arc
		(start 98.860864 -277.20671)
		(mid 98.584389 -277.27403)
		(end 98.310192 -277.198074)
		(width 0.088646)
		(layer "In11.Cu")
		(net "M_D_CPU1_SA_DQS_DN<6>")
	)
	(arc
		(start 89.477596 -277.198074)
		(mid 89.201037 -277.273817)
		(end 88.92286 -277.20417)
		(width 0.088646)
		(layer "In11.Cu")
		(net "M_D_CPU1_SA_DQS_DN<6>")
	)
	(arc
		(start 92.671392 -277.198074)
		(mid 92.484194 -277.147931)
		(end 92.296996 -277.198074)
		(width 0.088646)
		(layer "In11.Cu")
		(net "M_D_CPU1_SA_DQS_DN<6>")
	)
	(arc
		(start 96.041464 -277.20671)
		(mid 95.764989 -277.27403)
		(end 95.490792 -277.198074)
		(width 0.088646)
		(layer "In11.Cu")
		(net "M_D_CPU1_SA_DQS_DN<6>")
	)
	(arc
		(start 87.712804 -277.667466)
		(mid 87.694195 -277.679812)
		(end 87.67572 -277.692358)
		(width 0.088646)
		(layer "In11.Cu")
		(net "M_D_CPU1_SA_DQS_DN<6>")
	)
	(arc
		(start 90.792046 -277.198074)
		(mid 90.604848 -277.147931)
		(end 90.41765 -277.198074)
		(width 0.088646)
		(layer "In11.Cu")
		(net "M_D_CPU1_SA_DQS_DN<6>")
	)
	(arc
		(start 98.310192 -277.198074)
		(mid 98.122994 -277.147931)
		(end 97.935796 -277.198074)
		(width 0.088646)
		(layer "In11.Cu")
		(net "M_D_CPU1_SA_DQS_DN<6>")
	)
	(arc
		(start 95.490792 -277.198074)
		(mid 95.303594 -277.147931)
		(end 95.116396 -277.198074)
		(width 0.088646)
		(layer "In11.Cu")
		(net "M_D_CPU1_SA_DQS_DN<6>")
	)
	(arc
		(start 91.731592 -277.198074)
		(mid 91.544394 -277.147931)
		(end 91.357196 -277.198074)
		(width 0.088646)
		(layer "In11.Cu")
		(net "M_D_CPU1_SA_DQS_DN<6>")
	)
	(arc
		(start 88.387936 -277.257764)
		(mid 88.29403 -277.289438)
		(end 88.207088 -277.337012)
		(width 0.088646)
		(layer "In11.Cu")
		(net "M_D_CPU1_SA_DQS_DN<6>")
	)
	(arc
		(start 94.550992 -277.198074)
		(mid 94.363794 -277.147931)
		(end 94.176596 -277.198074)
		(width 0.088646)
		(layer "In11.Cu")
		(net "M_D_CPU1_SA_DQS_DN<6>")
	)
	(arc
		(start 94.161864 -277.20671)
		(mid 93.885389 -277.27403)
		(end 93.611192 -277.198074)
		(width 0.088646)
		(layer "In11.Cu")
		(net "M_D_CPU1_SA_DQS_DN<6>")
	)
	(segment
		(start 13.868908 -311.383172)
		(end 13.446506 -311.805574)
		(width 0.20066)
		(layer "F.Cu")
		(net "M_D_CPU1_SA_DQS_DN<5>")
	)
	(segment
		(start 14.560042 -311.651396)
		(end 14.376908 -311.651396)
		(width 0.20066)
		(layer "F.Cu")
		(net "M_D_CPU1_SA_DQS_DN<5>")
	)
	(segment
		(start 14.807692 -311.641744)
		(end 14.571218 -311.641744)
		(width 0.101854)
		(layer "F.Cu")
		(net "M_D_CPU1_SA_DQS_DN<5>")
	)
	(segment
		(start 19.032728 -311.805574)
		(end 18.329148 -311.805574)
		(width 0.20066)
		(layer "F.Cu")
		(net "M_D_CPU1_SA_DQS_DN<5>")
	)
	(segment
		(start 14.376908 -311.651396)
		(end 14.108684 -311.383172)
		(width 0.20066)
		(layer "F.Cu")
		(net "M_D_CPU1_SA_DQS_DN<5>")
	)
	(segment
		(start 14.571218 -311.641744)
		(end 14.561566 -311.651396)
		(width 0.101854)
		(layer "F.Cu")
		(net "M_D_CPU1_SA_DQS_DN<5>")
	)
	(segment
		(start 17.027398 -311.641744)
		(end 16.885158 -311.641744)
		(width 0.20066)
		(layer "F.Cu")
		(net "M_D_CPU1_SA_DQS_DN<5>")
	)
	(segment
		(start 16.885158 -311.641744)
		(end 14.807692 -311.641744)
		(width 0.1016)
		(layer "F.Cu")
		(net "M_D_CPU1_SA_DQS_DN<5>")
	)
	(segment
		(start 13.446506 -311.805574)
		(end 12.973304 -311.805574)
		(width 0.20066)
		(layer "F.Cu")
		(net "M_D_CPU1_SA_DQS_DN<5>")
	)
	(segment
		(start 19.29384 -312.066686)
		(end 19.032728 -311.805574)
		(width 0.20066)
		(layer "F.Cu")
		(net "M_D_CPU1_SA_DQS_DN<5>")
	)
	(segment
		(start 18.329148 -311.805574)
		(end 17.693132 -311.380632)
		(width 0.20066)
		(layer "F.Cu")
		(net "M_D_CPU1_SA_DQS_DN<5>")
	)
	(segment
		(start 14.561566 -311.651396)
		(end 14.560042 -311.651396)
		(width 0.101854)
		(layer "F.Cu")
		(net "M_D_CPU1_SA_DQS_DN<5>")
	)
	(segment
		(start 14.108684 -311.383172)
		(end 13.868908 -311.383172)
		(width 0.20066)
		(layer "F.Cu")
		(net "M_D_CPU1_SA_DQS_DN<5>")
	)
	(segment
		(start 20.889214 -312.066686)
		(end 19.784314 -312.066686)
		(width 0.20066)
		(layer "F.Cu")
		(net "M_D_CPU1_SA_DQS_DN<5>")
	)
	(segment
		(start 12.712192 -312.066686)
		(end 12.240514 -312.066686)
		(width 0.20066)
		(layer "F.Cu")
		(net "M_D_CPU1_SA_DQS_DN<5>")
	)
	(segment
		(start 17.693132 -311.380632)
		(end 17.28851 -311.380632)
		(width 0.20066)
		(layer "F.Cu")
		(net "M_D_CPU1_SA_DQS_DN<5>")
	)
	(segment
		(start 19.784314 -312.066686)
		(end 19.29384 -312.066686)
		(width 0.20066)
		(layer "F.Cu")
		(net "M_D_CPU1_SA_DQS_DN<5>")
	)
	(segment
		(start 12.973304 -311.805574)
		(end 12.712192 -312.066686)
		(width 0.20066)
		(layer "F.Cu")
		(net "M_D_CPU1_SA_DQS_DN<5>")
	)
	(segment
		(start 17.28851 -311.380632)
		(end 17.027398 -311.641744)
		(width 0.20066)
		(layer "F.Cu")
		(net "M_D_CPU1_SA_DQS_DN<5>")
	)
	(arc
		(start 97.653094 -274.54479)
		(mid 97.653157 -274.81276)
		(end 97.653348 -275.08073)
		(width 0.20066)
		(layer "F.Cu")
		(net "M_D_CPU1_SA_DQS_DN<5>")
	)
	(segment
		(start 83.496658 -280.106628)
		(end 82.834734 -280.106628)
		(width 0.18288)
		(layer "In6.Cu")
		(net "M_D_CPU1_SA_DQS_DN<5>")
	)
	(segment
		(start 84.2899 -279.019762)
		(end 84.2899 -279.699212)
		(width 0.088646)
		(layer "In6.Cu")
		(net "M_D_CPU1_SA_DQS_DN<5>")
	)
	(segment
		(start 28.61564 -311.382918)
		(end 26.134568 -311.382918)
		(width 0.18288)
		(layer "In6.Cu")
		(net "M_D_CPU1_SA_DQS_DN<5>")
	)
	(segment
		(start 33.958022 -311.910222)
		(end 32.634936 -311.36209)
		(width 0.18288)
		(layer "In6.Cu")
		(net "M_D_CPU1_SA_DQS_DN<5>")
	)
	(segment
		(start 93.156278 -274.765008)
		(end 93.141546 -274.756372)
		(width 0.088646)
		(layer "In6.Cu")
		(net "M_D_CPU1_SA_DQS_DN<5>")
	)
	(segment
		(start 51.34483 -305.691794)
		(end 50.866294 -305.691794)
		(width 0.18288)
		(layer "In6.Cu")
		(net "M_D_CPU1_SA_DQS_DN<5>")
	)
	(segment
		(start 46.48581 -307.961284)
		(end 46.03623 -307.961284)
		(width 0.18288)
		(layer "In6.Cu")
		(net "M_D_CPU1_SA_DQS_DN<5>")
	)
	(segment
		(start 85.397594 -277.50008)
		(end 85.397594 -277.912068)
		(width 0.088646)
		(layer "In6.Cu")
		(net "M_D_CPU1_SA_DQS_DN<5>")
	)
	(segment
		(start 86.940644 -276.708616)
		(end 86.940644 -276.72284)
		(width 0.088646)
		(layer "In6.Cu")
		(net "M_D_CPU1_SA_DQS_DN<5>")
	)
	(segment
		(start 43.125136 -309.9181)
		(end 41.919398 -311.123838)
		(width 0.18288)
		(layer "In6.Cu")
		(net "M_D_CPU1_SA_DQS_DN<5>")
	)
	(segment
		(start 68.367656 -294.294814)
		(end 68.367656 -294.896794)
		(width 0.18288)
		(layer "In6.Cu")
		(net "M_D_CPU1_SA_DQS_DN<5>")
	)
	(segment
		(start 90.332306 -274.762468)
		(end 90.321892 -274.756372)
		(width 0.088646)
		(layer "In6.Cu")
		(net "M_D_CPU1_SA_DQS_DN<5>")
	)
	(segment
		(start 95.960692 -274.756372)
		(end 95.960946 -274.756372)
		(width 0.088646)
		(layer "In6.Cu")
		(net "M_D_CPU1_SA_DQS_DN<5>")
	)
	(segment
		(start 96.338898 -274.983194)
		(end 96.31807 -274.963128)
		(width 0.088646)
		(layer "In6.Cu")
		(net "M_D_CPU1_SA_DQS_DN<5>")
	)
	(segment
		(start 49.447196 -306.149502)
		(end 48.982122 -306.149502)
		(width 0.18288)
		(layer "In6.Cu")
		(net "M_D_CPU1_SA_DQS_DN<5>")
	)
	(segment
		(start 35.098736 -313.050936)
		(end 33.958022 -311.910222)
		(width 0.18288)
		(layer "In6.Cu")
		(net "M_D_CPU1_SA_DQS_DN<5>")
	)
	(segment
		(start 97.653348 -275.08073)
		(end 96.930718 -275.387816)
		(width 0.088646)
		(layer "In6.Cu")
		(net "M_D_CPU1_SA_DQS_DN<5>")
	)
	(segment
		(start 85.397594 -277.912068)
		(end 84.2899 -279.019762)
		(width 0.088646)
		(layer "In6.Cu")
		(net "M_D_CPU1_SA_DQS_DN<5>")
	)
	(segment
		(start 58.08091 -301.410116)
		(end 56.896 -302.595026)
		(width 0.18288)
		(layer "In6.Cu")
		(net "M_D_CPU1_SA_DQS_DN<5>")
	)
	(segment
		(start 51.624484 -305.41214)
		(end 51.34483 -305.691794)
		(width 0.18288)
		(layer "In6.Cu")
		(net "M_D_CPU1_SA_DQS_DN<5>")
	)
	(segment
		(start 61.721492 -298.0436)
		(end 60.329572 -299.43552)
		(width 0.18288)
		(layer "In6.Cu")
		(net "M_D_CPU1_SA_DQS_DN<5>")
	)
	(segment
		(start 58.08091 -300.89221)
		(end 58.08091 -301.410116)
		(width 0.18288)
		(layer "In6.Cu")
		(net "M_D_CPU1_SA_DQS_DN<5>")
	)
	(segment
		(start 96.902778 -275.404072)
		(end 96.900746 -275.405088)
		(width 0.088646)
		(layer "In6.Cu")
		(net "M_D_CPU1_SA_DQS_DN<5>")
	)
	(segment
		(start 29.233368 -310.76519)
		(end 28.61564 -311.382918)
		(width 0.18288)
		(layer "In6.Cu")
		(net "M_D_CPU1_SA_DQS_DN<5>")
	)
	(segment
		(start 36.451032 -313.062112)
		(end 36.171378 -313.341766)
		(width 0.18288)
		(layer "In6.Cu")
		(net "M_D_CPU1_SA_DQS_DN<5>")
	)
	(segment
		(start 47.524416 -307.962046)
		(end 47.244508 -308.241954)
		(width 0.18288)
		(layer "In6.Cu")
		(net "M_D_CPU1_SA_DQS_DN<5>")
	)
	(segment
		(start 94.096078 -274.765008)
		(end 94.081346 -274.756372)
		(width 0.088646)
		(layer "In6.Cu")
		(net "M_D_CPU1_SA_DQS_DN<5>")
	)
	(segment
		(start 83.579716 -280.046938)
		(end 83.520026 -280.106628)
		(width 0.088646)
		(layer "In6.Cu")
		(net "M_D_CPU1_SA_DQS_DN<5>")
	)
	(segment
		(start 48.982122 -306.149502)
		(end 48.274986 -306.856638)
		(width 0.18288)
		(layer "In6.Cu")
		(net "M_D_CPU1_SA_DQS_DN<5>")
	)
	(segment
		(start 50.575464 -305.400964)
		(end 50.195734 -305.400964)
		(width 0.18288)
		(layer "In6.Cu")
		(net "M_D_CPU1_SA_DQS_DN<5>")
	)
	(segment
		(start 83.520026 -280.106628)
		(end 83.496658 -280.106628)
		(width 0.088646)
		(layer "In6.Cu")
		(net "M_D_CPU1_SA_DQS_DN<5>")
	)
	(segment
		(start 89.760044 -275.08073)
		(end 89.760044 -275.099272)
		(width 0.088646)
		(layer "In6.Cu")
		(net "M_D_CPU1_SA_DQS_DN<5>")
	)
	(segment
		(start 64.487044 -298.447968)
		(end 63.376302 -298.447968)
		(width 0.18288)
		(layer "In6.Cu")
		(net "M_D_CPU1_SA_DQS_DN<5>")
	)
	(segment
		(start 21.524976 -311.78627)
		(end 21.16963 -311.78627)
		(width 0.18288)
		(layer "In6.Cu")
		(net "M_D_CPU1_SA_DQS_DN<5>")
	)
	(segment
		(start 87.128096 -276.384258)
		(end 87.119206 -276.389338)
		(width 0.088646)
		(layer "In6.Cu")
		(net "M_D_CPU1_SA_DQS_DN<5>")
	)
	(segment
		(start 58.96737 -300.266862)
		(end 58.706258 -300.266862)
		(width 0.18288)
		(layer "In6.Cu")
		(net "M_D_CPU1_SA_DQS_DN<5>")
	)
	(segment
		(start 85.640164 -277.25751)
		(end 85.397594 -277.50008)
		(width 0.088646)
		(layer "In6.Cu")
		(net "M_D_CPU1_SA_DQS_DN<5>")
	)
	(segment
		(start 86.657942 -277.198328)
		(end 86.64321 -277.206964)
		(width 0.088646)
		(layer "In6.Cu")
		(net "M_D_CPU1_SA_DQS_DN<5>")
	)
	(segment
		(start 32.34436 -311.36209)
		(end 32.064706 -311.641744)
		(width 0.18288)
		(layer "In6.Cu")
		(net "M_D_CPU1_SA_DQS_DN<5>")
	)
	(segment
		(start 63.376302 -298.447968)
		(end 62.971934 -298.0436)
		(width 0.18288)
		(layer "In6.Cu")
		(net "M_D_CPU1_SA_DQS_DN<5>")
	)
	(segment
		(start 82.834734 -280.106628)
		(end 82.358484 -280.303986)
		(width 0.18288)
		(layer "In6.Cu")
		(net "M_D_CPU1_SA_DQS_DN<5>")
	)
	(segment
		(start 56.896 -302.595026)
		(end 56.510174 -302.595026)
		(width 0.18288)
		(layer "In6.Cu")
		(net "M_D_CPU1_SA_DQS_DN<5>")
	)
	(segment
		(start 37.241226 -313.062112)
		(end 36.451032 -313.062112)
		(width 0.18288)
		(layer "In6.Cu")
		(net "M_D_CPU1_SA_DQS_DN<5>")
	)
	(segment
		(start 21.16963 -311.78627)
		(end 20.889214 -312.066686)
		(width 0.18288)
		(layer "In6.Cu")
		(net "M_D_CPU1_SA_DQS_DN<5>")
	)
	(segment
		(start 35.487864 -313.050936)
		(end 35.098736 -313.050936)
		(width 0.18288)
		(layer "In6.Cu")
		(net "M_D_CPU1_SA_DQS_DN<5>")
	)
	(segment
		(start 26.134568 -311.382918)
		(end 24.529796 -312.047636)
		(width 0.18288)
		(layer "In6.Cu")
		(net "M_D_CPU1_SA_DQS_DN<5>")
	)
	(segment
		(start 62.971934 -298.0436)
		(end 61.721492 -298.0436)
		(width 0.18288)
		(layer "In6.Cu")
		(net "M_D_CPU1_SA_DQS_DN<5>")
	)
	(segment
		(start 44.898056 -308.588156)
		(end 43.568112 -309.9181)
		(width 0.18288)
		(layer "In6.Cu")
		(net "M_D_CPU1_SA_DQS_DN<5>")
	)
	(segment
		(start 89.290144 -275.8948)
		(end 89.290144 -275.904706)
		(width 0.088646)
		(layer "In6.Cu")
		(net "M_D_CPU1_SA_DQS_DN<5>")
	)
	(segment
		(start 36.171378 -313.341766)
		(end 35.778694 -313.341766)
		(width 0.18288)
		(layer "In6.Cu")
		(net "M_D_CPU1_SA_DQS_DN<5>")
	)
	(segment
		(start 96.338898 -275.08073)
		(end 96.338898 -274.983194)
		(width 0.088646)
		(layer "In6.Cu")
		(net "M_D_CPU1_SA_DQS_DN<5>")
	)
	(segment
		(start 96.52635 -275.405088)
		(end 96.51746 -275.400008)
		(width 0.088646)
		(layer "In6.Cu")
		(net "M_D_CPU1_SA_DQS_DN<5>")
	)
	(segment
		(start 50.866294 -305.691794)
		(end 50.575464 -305.400964)
		(width 0.18288)
		(layer "In6.Cu")
		(net "M_D_CPU1_SA_DQS_DN<5>")
	)
	(segment
		(start 32.634936 -311.36209)
		(end 32.34436 -311.36209)
		(width 0.18288)
		(layer "In6.Cu")
		(net "M_D_CPU1_SA_DQS_DN<5>")
	)
	(segment
		(start 55.226458 -303.878742)
		(end 54.132226 -303.878742)
		(width 0.18288)
		(layer "In6.Cu")
		(net "M_D_CPU1_SA_DQS_DN<5>")
	)
	(segment
		(start 84.2899 -279.699212)
		(end 83.942174 -280.046938)
		(width 0.088646)
		(layer "In6.Cu")
		(net "M_D_CPU1_SA_DQS_DN<5>")
	)
	(segment
		(start 68.367656 -294.896794)
		(end 66.244978 -297.019472)
		(width 0.18288)
		(layer "In6.Cu")
		(net "M_D_CPU1_SA_DQS_DN<5>")
	)
	(segment
		(start 59.798712 -299.43552)
		(end 58.96737 -300.266862)
		(width 0.18288)
		(layer "In6.Cu")
		(net "M_D_CPU1_SA_DQS_DN<5>")
	)
	(segment
		(start 66.244978 -297.019472)
		(end 65.91554 -297.019472)
		(width 0.18288)
		(layer "In6.Cu")
		(net "M_D_CPU1_SA_DQS_DN<5>")
	)
	(segment
		(start 46.76648 -308.241954)
		(end 46.48581 -307.961284)
		(width 0.18288)
		(layer "In6.Cu")
		(net "M_D_CPU1_SA_DQS_DN<5>")
	)
	(segment
		(start 35.778694 -313.341766)
		(end 35.487864 -313.050936)
		(width 0.18288)
		(layer "In6.Cu")
		(net "M_D_CPU1_SA_DQS_DN<5>")
	)
	(segment
		(start 95.986854 -274.771358)
		(end 95.964248 -274.758404)
		(width 0.088646)
		(layer "In6.Cu")
		(net "M_D_CPU1_SA_DQS_DN<5>")
	)
	(segment
		(start 95.035878 -274.765008)
		(end 95.021146 -274.756372)
		(width 0.088646)
		(layer "In6.Cu")
		(net "M_D_CPU1_SA_DQS_DN<5>")
	)
	(segment
		(start 60.329572 -299.43552)
		(end 59.798712 -299.43552)
		(width 0.18288)
		(layer "In6.Cu")
		(net "M_D_CPU1_SA_DQS_DN<5>")
	)
	(segment
		(start 24.529796 -312.047636)
		(end 21.786342 -312.047636)
		(width 0.18288)
		(layer "In6.Cu")
		(net "M_D_CPU1_SA_DQS_DN<5>")
	)
	(segment
		(start 31.678626 -311.641744)
		(end 31.420054 -311.383172)
		(width 0.18288)
		(layer "In6.Cu")
		(net "M_D_CPU1_SA_DQS_DN<5>")
	)
	(segment
		(start 89.947496 -274.756372)
		(end 89.938606 -274.761452)
		(width 0.088646)
		(layer "In6.Cu")
		(net "M_D_CPU1_SA_DQS_DN<5>")
	)
	(segment
		(start 56.510174 -302.595026)
		(end 55.226458 -303.878742)
		(width 0.18288)
		(layer "In6.Cu")
		(net "M_D_CPU1_SA_DQS_DN<5>")
	)
	(segment
		(start 50.195734 -305.400964)
		(end 49.447196 -306.149502)
		(width 0.18288)
		(layer "In6.Cu")
		(net "M_D_CPU1_SA_DQS_DN<5>")
	)
	(segment
		(start 89.477596 -275.570442)
		(end 89.468706 -275.575522)
		(width 0.088646)
		(layer "In6.Cu")
		(net "M_D_CPU1_SA_DQS_DN<5>")
	)
	(segment
		(start 96.31807 -274.963128)
		(end 95.986854 -274.771358)
		(width 0.088646)
		(layer "In6.Cu")
		(net "M_D_CPU1_SA_DQS_DN<5>")
	)
	(segment
		(start 95.964248 -274.758404)
		(end 95.962724 -274.757388)
		(width 0.088646)
		(layer "In6.Cu")
		(net "M_D_CPU1_SA_DQS_DN<5>")
	)
	(segment
		(start 47.764954 -307.962046)
		(end 47.524416 -307.962046)
		(width 0.18288)
		(layer "In6.Cu")
		(net "M_D_CPU1_SA_DQS_DN<5>")
	)
	(segment
		(start 46.03623 -307.961284)
		(end 45.409358 -308.588156)
		(width 0.18288)
		(layer "In6.Cu")
		(net "M_D_CPU1_SA_DQS_DN<5>")
	)
	(segment
		(start 41.919398 -311.123838)
		(end 37.241226 -313.062112)
		(width 0.18288)
		(layer "In6.Cu")
		(net "M_D_CPU1_SA_DQS_DN<5>")
	)
	(segment
		(start 47.244508 -308.241954)
		(end 46.76648 -308.241954)
		(width 0.18288)
		(layer "In6.Cu")
		(net "M_D_CPU1_SA_DQS_DN<5>")
	)
	(segment
		(start 82.358484 -280.303986)
		(end 68.367656 -294.294814)
		(width 0.18288)
		(layer "In6.Cu")
		(net "M_D_CPU1_SA_DQS_DN<5>")
	)
	(segment
		(start 58.706258 -300.266862)
		(end 58.08091 -300.89221)
		(width 0.18288)
		(layer "In6.Cu")
		(net "M_D_CPU1_SA_DQS_DN<5>")
	)
	(segment
		(start 65.91554 -297.019472)
		(end 64.487044 -298.447968)
		(width 0.18288)
		(layer "In6.Cu")
		(net "M_D_CPU1_SA_DQS_DN<5>")
	)
	(segment
		(start 95.962724 -274.757388)
		(end 95.960692 -274.756372)
		(width 0.088646)
		(layer "In6.Cu")
		(net "M_D_CPU1_SA_DQS_DN<5>")
	)
	(segment
		(start 92.211906 -274.762468)
		(end 92.201492 -274.756372)
		(width 0.088646)
		(layer "In6.Cu")
		(net "M_D_CPU1_SA_DQS_DN<5>")
	)
	(segment
		(start 30.034738 -310.76519)
		(end 29.233368 -310.76519)
		(width 0.18288)
		(layer "In6.Cu")
		(net "M_D_CPU1_SA_DQS_DN<5>")
	)
	(segment
		(start 96.930718 -275.387816)
		(end 96.902778 -275.404072)
		(width 0.088646)
		(layer "In6.Cu")
		(net "M_D_CPU1_SA_DQS_DN<5>")
	)
	(segment
		(start 48.275748 -307.451252)
		(end 47.764954 -307.962046)
		(width 0.18288)
		(layer "In6.Cu")
		(net "M_D_CPU1_SA_DQS_DN<5>")
	)
	(segment
		(start 48.274986 -306.856638)
		(end 48.275748 -307.451252)
		(width 0.18288)
		(layer "In6.Cu")
		(net "M_D_CPU1_SA_DQS_DN<5>")
	)
	(segment
		(start 31.420054 -311.383172)
		(end 30.65272 -311.383172)
		(width 0.18288)
		(layer "In6.Cu")
		(net "M_D_CPU1_SA_DQS_DN<5>")
	)
	(segment
		(start 52.598828 -305.41214)
		(end 51.624484 -305.41214)
		(width 0.18288)
		(layer "In6.Cu")
		(net "M_D_CPU1_SA_DQS_DN<5>")
	)
	(segment
		(start 45.409358 -308.588156)
		(end 44.898056 -308.588156)
		(width 0.18288)
		(layer "In6.Cu")
		(net "M_D_CPU1_SA_DQS_DN<5>")
	)
	(segment
		(start 43.568112 -309.9181)
		(end 43.125136 -309.9181)
		(width 0.18288)
		(layer "In6.Cu")
		(net "M_D_CPU1_SA_DQS_DN<5>")
	)
	(segment
		(start 54.132226 -303.878742)
		(end 52.598828 -305.41214)
		(width 0.18288)
		(layer "In6.Cu")
		(net "M_D_CPU1_SA_DQS_DN<5>")
	)
	(segment
		(start 87.517224 -276.392894)
		(end 87.502492 -276.384258)
		(width 0.088646)
		(layer "In6.Cu")
		(net "M_D_CPU1_SA_DQS_DN<5>")
	)
	(segment
		(start 21.786342 -312.047636)
		(end 21.524976 -311.78627)
		(width 0.18288)
		(layer "In6.Cu")
		(net "M_D_CPU1_SA_DQS_DN<5>")
	)
	(segment
		(start 32.064706 -311.641744)
		(end 31.678626 -311.641744)
		(width 0.18288)
		(layer "In6.Cu")
		(net "M_D_CPU1_SA_DQS_DN<5>")
	)
	(segment
		(start 91.827096 -274.756372)
		(end 91.816682 -274.762468)
		(width 0.088646)
		(layer "In6.Cu")
		(net "M_D_CPU1_SA_DQS_DN<5>")
	)
	(segment
		(start 30.65272 -311.383172)
		(end 30.034738 -310.76519)
		(width 0.18288)
		(layer "In6.Cu")
		(net "M_D_CPU1_SA_DQS_DN<5>")
	)
	(segment
		(start 83.942174 -280.046938)
		(end 83.579716 -280.046938)
		(width 0.088646)
		(layer "In6.Cu")
		(net "M_D_CPU1_SA_DQS_DN<5>")
	)
	(arc
		(start 88.442292 -276.384258)
		(mid 88.255094 -276.334115)
		(end 88.067896 -276.384258)
		(width 0.088646)
		(layer "In6.Cu")
		(net "M_D_CPU1_SA_DQS_DN<5>")
	)
	(arc
		(start 89.290144 -275.904706)
		(mid 89.212033 -276.181655)
		(end 89.007696 -276.384258)
		(width 0.088646)
		(layer "In6.Cu")
		(net "M_D_CPU1_SA_DQS_DN<5>")
	)
	(arc
		(start 85.718142 -277.198328)
		(mid 85.677212 -277.225361)
		(end 85.640164 -277.25751)
		(width 0.088646)
		(layer "In6.Cu")
		(net "M_D_CPU1_SA_DQS_DN<5>")
	)
	(arc
		(start 86.092538 -277.198328)
		(mid 85.90534 -277.148185)
		(end 85.718142 -277.198328)
		(width 0.088646)
		(layer "In6.Cu")
		(net "M_D_CPU1_SA_DQS_DN<5>")
	)
	(arc
		(start 88.067896 -276.384258)
		(mid 87.793697 -276.460093)
		(end 87.517224 -276.392894)
		(width 0.088646)
		(layer "In6.Cu")
		(net "M_D_CPU1_SA_DQS_DN<5>")
	)
	(arc
		(start 91.816682 -274.762468)
		(mid 91.538504 -274.832191)
		(end 91.261946 -274.756372)
		(width 0.088646)
		(layer "In6.Cu")
		(net "M_D_CPU1_SA_DQS_DN<5>")
	)
	(arc
		(start 91.261946 -274.756372)
		(mid 91.074748 -274.706229)
		(end 90.88755 -274.756372)
		(width 0.088646)
		(layer "In6.Cu")
		(net "M_D_CPU1_SA_DQS_DN<5>")
	)
	(arc
		(start 87.119206 -276.389338)
		(mid 86.988292 -276.525698)
		(end 86.940644 -276.708616)
		(width 0.088646)
		(layer "In6.Cu")
		(net "M_D_CPU1_SA_DQS_DN<5>")
	)
	(arc
		(start 86.940644 -276.72284)
		(mid 86.861425 -276.997525)
		(end 86.657942 -277.198328)
		(width 0.088646)
		(layer "In6.Cu")
		(net "M_D_CPU1_SA_DQS_DN<5>")
	)
	(arc
		(start 95.58655 -274.756372)
		(mid 95.312351 -274.832207)
		(end 95.035878 -274.765008)
		(width 0.088646)
		(layer "In6.Cu")
		(net "M_D_CPU1_SA_DQS_DN<5>")
	)
	(arc
		(start 89.007696 -276.384258)
		(mid 88.724994 -276.460034)
		(end 88.442292 -276.384258)
		(width 0.088646)
		(layer "In6.Cu")
		(net "M_D_CPU1_SA_DQS_DN<5>")
	)
	(arc
		(start 94.64675 -274.756372)
		(mid 94.372551 -274.832207)
		(end 94.096078 -274.765008)
		(width 0.088646)
		(layer "In6.Cu")
		(net "M_D_CPU1_SA_DQS_DN<5>")
	)
	(arc
		(start 95.021146 -274.756372)
		(mid 94.833948 -274.706229)
		(end 94.64675 -274.756372)
		(width 0.088646)
		(layer "In6.Cu")
		(net "M_D_CPU1_SA_DQS_DN<5>")
	)
	(arc
		(start 95.960946 -274.756372)
		(mid 95.773748 -274.706229)
		(end 95.58655 -274.756372)
		(width 0.088646)
		(layer "In6.Cu")
		(net "M_D_CPU1_SA_DQS_DN<5>")
	)
	(arc
		(start 89.468706 -275.575522)
		(mid 89.337792 -275.711882)
		(end 89.290144 -275.8948)
		(width 0.088646)
		(layer "In6.Cu")
		(net "M_D_CPU1_SA_DQS_DN<5>")
	)
	(arc
		(start 90.88755 -274.756372)
		(mid 90.610737 -274.832242)
		(end 90.332306 -274.762468)
		(width 0.088646)
		(layer "In6.Cu")
		(net "M_D_CPU1_SA_DQS_DN<5>")
	)
	(arc
		(start 89.760044 -275.099272)
		(mid 89.679882 -275.371461)
		(end 89.477596 -275.570442)
		(width 0.088646)
		(layer "In6.Cu")
		(net "M_D_CPU1_SA_DQS_DN<5>")
	)
	(arc
		(start 86.64321 -277.206964)
		(mid 86.366769 -277.27413)
		(end 86.092538 -277.198328)
		(width 0.088646)
		(layer "In6.Cu")
		(net "M_D_CPU1_SA_DQS_DN<5>")
	)
	(arc
		(start 92.76715 -274.756372)
		(mid 92.490337 -274.832242)
		(end 92.211906 -274.762468)
		(width 0.088646)
		(layer "In6.Cu")
		(net "M_D_CPU1_SA_DQS_DN<5>")
	)
	(arc
		(start 96.51746 -275.400008)
		(mid 96.386546 -275.263648)
		(end 96.338898 -275.08073)
		(width 0.088646)
		(layer "In6.Cu")
		(net "M_D_CPU1_SA_DQS_DN<5>")
	)
	(arc
		(start 93.70695 -274.756372)
		(mid 93.432751 -274.832207)
		(end 93.156278 -274.765008)
		(width 0.088646)
		(layer "In6.Cu")
		(net "M_D_CPU1_SA_DQS_DN<5>")
	)
	(arc
		(start 96.900746 -275.405088)
		(mid 96.713548 -275.455231)
		(end 96.52635 -275.405088)
		(width 0.088646)
		(layer "In6.Cu")
		(net "M_D_CPU1_SA_DQS_DN<5>")
	)
	(arc
		(start 94.081346 -274.756372)
		(mid 93.894148 -274.706229)
		(end 93.70695 -274.756372)
		(width 0.088646)
		(layer "In6.Cu")
		(net "M_D_CPU1_SA_DQS_DN<5>")
	)
	(arc
		(start 93.141546 -274.756372)
		(mid 92.954348 -274.706229)
		(end 92.76715 -274.756372)
		(width 0.088646)
		(layer "In6.Cu")
		(net "M_D_CPU1_SA_DQS_DN<5>")
	)
	(arc
		(start 90.321892 -274.756372)
		(mid 90.134694 -274.706229)
		(end 89.947496 -274.756372)
		(width 0.088646)
		(layer "In6.Cu")
		(net "M_D_CPU1_SA_DQS_DN<5>")
	)
	(arc
		(start 87.502492 -276.384258)
		(mid 87.315294 -276.334115)
		(end 87.128096 -276.384258)
		(width 0.088646)
		(layer "In6.Cu")
		(net "M_D_CPU1_SA_DQS_DN<5>")
	)
	(arc
		(start 89.938606 -274.761452)
		(mid 89.807692 -274.897812)
		(end 89.760044 -275.08073)
		(width 0.088646)
		(layer "In6.Cu")
		(net "M_D_CPU1_SA_DQS_DN<5>")
	)
	(arc
		(start 92.201492 -274.756372)
		(mid 92.014294 -274.706229)
		(end 91.827096 -274.756372)
		(width 0.088646)
		(layer "In6.Cu")
		(net "M_D_CPU1_SA_DQS_DN<5>")
	)
	(segment
		(start 10.912094 -275.080984)
		(end 10.64006 -275.353018)
		(width 0.20066)
		(layer "F.Cu")
		(net "M_D_CPU1_SA_DQS_DN<4>")
	)
	(segment
		(start 13.441426 -275.091652)
		(end 11.12774 -275.091652)
		(width 0.1016)
		(layer "F.Cu")
		(net "M_D_CPU1_SA_DQS_DN<4>")
	)
	(segment
		(start 14.469872 -274.927822)
		(end 14.044676 -275.353018)
		(width 0.20066)
		(layer "F.Cu")
		(net "M_D_CPU1_SA_DQS_DN<4>")
	)
	(segment
		(start 16.789146 -274.66671)
		(end 15.684246 -274.66671)
		(width 0.20066)
		(layer "F.Cu")
		(net "M_D_CPU1_SA_DQS_DN<4>")
	)
	(segment
		(start 13.857986 -275.353018)
		(end 13.59662 -275.091652)
		(width 0.20066)
		(layer "F.Cu")
		(net "M_D_CPU1_SA_DQS_DN<4>")
	)
	(segment
		(start 98.123248 -262.87222)
		(end 98.122994 -262.872474)
		(width 0.20066)
		(layer "F.Cu")
		(net "M_D_CPU1_SA_DQS_DN<4>")
	)
	(segment
		(start 11.12774 -275.091652)
		(end 11.117072 -275.080984)
		(width 0.101854)
		(layer "F.Cu")
		(net "M_D_CPU1_SA_DQS_DN<4>")
	)
	(segment
		(start 15.137638 -274.66671)
		(end 14.876526 -274.927822)
		(width 0.20066)
		(layer "F.Cu")
		(net "M_D_CPU1_SA_DQS_DN<4>")
	)
	(segment
		(start 14.044676 -275.353018)
		(end 13.857986 -275.353018)
		(width 0.20066)
		(layer "F.Cu")
		(net "M_D_CPU1_SA_DQS_DN<4>")
	)
	(segment
		(start 8.689086 -274.66671)
		(end 8.140446 -274.66671)
		(width 0.20066)
		(layer "F.Cu")
		(net "M_D_CPU1_SA_DQS_DN<4>")
	)
	(segment
		(start 9.46404 -274.927822)
		(end 8.950198 -274.927822)
		(width 0.20066)
		(layer "F.Cu")
		(net "M_D_CPU1_SA_DQS_DN<4>")
	)
	(segment
		(start 11.11631 -275.080984)
		(end 10.912094 -275.080984)
		(width 0.20066)
		(layer "F.Cu")
		(net "M_D_CPU1_SA_DQS_DN<4>")
	)
	(segment
		(start 10.100056 -275.353018)
		(end 9.46404 -274.927822)
		(width 0.20066)
		(layer "F.Cu")
		(net "M_D_CPU1_SA_DQS_DN<4>")
	)
	(segment
		(start 10.64006 -275.353018)
		(end 10.100056 -275.353018)
		(width 0.20066)
		(layer "F.Cu")
		(net "M_D_CPU1_SA_DQS_DN<4>")
	)
	(segment
		(start 8.950198 -274.927822)
		(end 8.689086 -274.66671)
		(width 0.20066)
		(layer "F.Cu")
		(net "M_D_CPU1_SA_DQS_DN<4>")
	)
	(segment
		(start 13.59662 -275.091652)
		(end 13.441426 -275.091652)
		(width 0.20066)
		(layer "F.Cu")
		(net "M_D_CPU1_SA_DQS_DN<4>")
	)
	(segment
		(start 15.684246 -274.66671)
		(end 15.137638 -274.66671)
		(width 0.20066)
		(layer "F.Cu")
		(net "M_D_CPU1_SA_DQS_DN<4>")
	)
	(segment
		(start 14.876526 -274.927822)
		(end 14.469872 -274.927822)
		(width 0.20066)
		(layer "F.Cu")
		(net "M_D_CPU1_SA_DQS_DN<4>")
	)
	(segment
		(start 11.117072 -275.080984)
		(end 11.11631 -275.080984)
		(width 0.101854)
		(layer "F.Cu")
		(net "M_D_CPU1_SA_DQS_DN<4>")
	)
	(segment
		(start 98.123248 -262.336534)
		(end 98.123248 -262.87222)
		(width 0.20066)
		(layer "F.Cu")
		(net "M_D_CPU1_SA_DQS_DN<4>")
	)
	(segment
		(start 83.811364 -263.247632)
		(end 83.415632 -263.643364)
		(width 0.088646)
		(layer "In11.Cu")
		(net "M_D_CPU1_SA_DQS_DN<4>")
	)
	(segment
		(start 32.075374 -273.392392)
		(end 31.668466 -273.392392)
		(width 0.18288)
		(layer "In11.Cu")
		(net "M_D_CPU1_SA_DQS_DN<4>")
	)
	(segment
		(start 60.650628 -272.44167)
		(end 60.526168 -272.56613)
		(width 0.18288)
		(layer "In11.Cu")
		(net "M_D_CPU1_SA_DQS_DN<4>")
	)
	(segment
		(start 97.3709 -263.197086)
		(end 97.370646 -263.196832)
		(width 0.088646)
		(layer "In11.Cu")
		(net "M_D_CPU1_SA_DQS_DN<4>")
	)
	(segment
		(start 47.194978 -273.392392)
		(end 46.772322 -273.392392)
		(width 0.18288)
		(layer "In11.Cu")
		(net "M_D_CPU1_SA_DQS_DN<4>")
	)
	(segment
		(start 31.668466 -273.392392)
		(end 31.404052 -273.656806)
		(width 0.18288)
		(layer "In11.Cu")
		(net "M_D_CPU1_SA_DQS_DN<4>")
	)
	(segment
		(start 58.598816 -272.087086)
		(end 58.474356 -271.962626)
		(width 0.18288)
		(layer "In11.Cu")
		(net "M_D_CPU1_SA_DQS_DN<4>")
	)
	(segment
		(start 22.830282 -275.3614)
		(end 21.349462 -275.3614)
		(width 0.18288)
		(layer "In11.Cu")
		(net "M_D_CPU1_SA_DQS_DN<4>")
	)
	(segment
		(start 64.383158 -271.612106)
		(end 64.258698 -271.736566)
		(width 0.18288)
		(layer "In11.Cu")
		(net "M_D_CPU1_SA_DQS_DN<4>")
	)
	(segment
		(start 44.539408 -274.347686)
		(end 43.748706 -273.556984)
		(width 0.18288)
		(layer "In11.Cu")
		(net "M_D_CPU1_SA_DQS_DN<4>")
	)
	(segment
		(start 42.402506 -273.556984)
		(end 41.853866 -273.556984)
		(width 0.18288)
		(layer "In11.Cu")
		(net "M_D_CPU1_SA_DQS_DN<4>")
	)
	(segment
		(start 54.581044 -272.793714)
		(end 54.456584 -272.669254)
		(width 0.18288)
		(layer "In11.Cu")
		(net "M_D_CPU1_SA_DQS_DN<4>")
	)
	(segment
		(start 38.878764 -272.80235)
		(end 38.754304 -272.67789)
		(width 0.18288)
		(layer "In11.Cu")
		(net "M_D_CPU1_SA_DQS_DN<4>")
	)
	(segment
		(start 96.056196 -263.196832)
		(end 96.041464 -263.188196)
		(width 0.088646)
		(layer "In11.Cu")
		(net "M_D_CPU1_SA_DQS_DN<4>")
	)
	(segment
		(start 51.523392 -272.793714)
		(end 51.270662 -272.540984)
		(width 0.18288)
		(layer "In11.Cu")
		(net "M_D_CPU1_SA_DQS_DN<4>")
	)
	(segment
		(start 21.349462 -275.3614)
		(end 21.080476 -275.092414)
		(width 0.18288)
		(layer "In11.Cu")
		(net "M_D_CPU1_SA_DQS_DN<4>")
	)
	(segment
		(start 17.812258 -274.936204)
		(end 17.05864 -274.936204)
		(width 0.18288)
		(layer "In11.Cu")
		(net "M_D_CPU1_SA_DQS_DN<4>")
	)
	(segment
		(start 92.296996 -263.196832)
		(end 92.282264 -263.188196)
		(width 0.088646)
		(layer "In11.Cu")
		(net "M_D_CPU1_SA_DQS_DN<4>")
	)
	(segment
		(start 59.6265 -272.56613)
		(end 59.147456 -272.087086)
		(width 0.18288)
		(layer "In11.Cu")
		(net "M_D_CPU1_SA_DQS_DN<4>")
	)
	(segment
		(start 38.205664 -272.67789)
		(end 38.081204 -272.80235)
		(width 0.18288)
		(layer "In11.Cu")
		(net "M_D_CPU1_SA_DQS_DN<4>")
	)
	(segment
		(start 61.199268 -272.44167)
		(end 60.650628 -272.44167)
		(width 0.18288)
		(layer "In11.Cu")
		(net "M_D_CPU1_SA_DQS_DN<4>")
	)
	(segment
		(start 83.415632 -263.643364)
		(end 83.096862 -263.643364)
		(width 0.088646)
		(layer "In11.Cu")
		(net "M_D_CPU1_SA_DQS_DN<4>")
	)
	(segment
		(start 45.07103 -274.347686)
		(end 44.539408 -274.347686)
		(width 0.18288)
		(layer "In11.Cu")
		(net "M_D_CPU1_SA_DQS_DN<4>")
	)
	(segment
		(start 97.624138 -263.05129)
		(end 97.3709 -263.197086)
		(width 0.088646)
		(layer "In11.Cu")
		(net "M_D_CPU1_SA_DQS_DN<4>")
	)
	(segment
		(start 38.754304 -272.67789)
		(end 38.205664 -272.67789)
		(width 0.18288)
		(layer "In11.Cu")
		(net "M_D_CPU1_SA_DQS_DN<4>")
	)
	(segment
		(start 36.181538 -272.540984)
		(end 35.77717 -272.540984)
		(width 0.18288)
		(layer "In11.Cu")
		(net "M_D_CPU1_SA_DQS_DN<4>")
	)
	(segment
		(start 61.323728 -272.56613)
		(end 61.199268 -272.44167)
		(width 0.18288)
		(layer "In11.Cu")
		(net "M_D_CPU1_SA_DQS_DN<4>")
	)
	(segment
		(start 48.942244 -273.633692)
		(end 47.436278 -273.633692)
		(width 0.18288)
		(layer "In11.Cu")
		(net "M_D_CPU1_SA_DQS_DN<4>")
	)
	(segment
		(start 20.429474 -275.343874)
		(end 19.935444 -275.343874)
		(width 0.18288)
		(layer "In11.Cu")
		(net "M_D_CPU1_SA_DQS_DN<4>")
	)
	(segment
		(start 20.680934 -275.092414)
		(end 20.429474 -275.343874)
		(width 0.18288)
		(layer "In11.Cu")
		(net "M_D_CPU1_SA_DQS_DN<4>")
	)
	(segment
		(start 83.013804 -263.583674)
		(end 75.423776 -263.583674)
		(width 0.18288)
		(layer "In11.Cu")
		(net "M_D_CPU1_SA_DQS_DN<4>")
	)
	(segment
		(start 54.456584 -272.669254)
		(end 53.907944 -272.669254)
		(width 0.18288)
		(layer "In11.Cu")
		(net "M_D_CPU1_SA_DQS_DN<4>")
	)
	(segment
		(start 42.526966 -273.432524)
		(end 42.402506 -273.556984)
		(width 0.18288)
		(layer "In11.Cu")
		(net "M_D_CPU1_SA_DQS_DN<4>")
	)
	(segment
		(start 25.14092 -274.347686)
		(end 23.843996 -274.347686)
		(width 0.18288)
		(layer "In11.Cu")
		(net "M_D_CPU1_SA_DQS_DN<4>")
	)
	(segment
		(start 53.110384 -272.669254)
		(end 52.561744 -272.669254)
		(width 0.18288)
		(layer "In11.Cu")
		(net "M_D_CPU1_SA_DQS_DN<4>")
	)
	(segment
		(start 52.437284 -272.793714)
		(end 51.523392 -272.793714)
		(width 0.18288)
		(layer "In11.Cu")
		(net "M_D_CPU1_SA_DQS_DN<4>")
	)
	(segment
		(start 47.436278 -273.633692)
		(end 47.194978 -273.392392)
		(width 0.18288)
		(layer "In11.Cu")
		(net "M_D_CPU1_SA_DQS_DN<4>")
	)
	(segment
		(start 53.907944 -272.669254)
		(end 53.783484 -272.793714)
		(width 0.18288)
		(layer "In11.Cu")
		(net "M_D_CPU1_SA_DQS_DN<4>")
	)
	(segment
		(start 21.080476 -275.092414)
		(end 20.680934 -275.092414)
		(width 0.18288)
		(layer "In11.Cu")
		(net "M_D_CPU1_SA_DQS_DN<4>")
	)
	(segment
		(start 29.01315 -273.856196)
		(end 25.63241 -273.856196)
		(width 0.18288)
		(layer "In11.Cu")
		(net "M_D_CPU1_SA_DQS_DN<4>")
	)
	(segment
		(start 49.75733 -272.818606)
		(end 48.942244 -273.633692)
		(width 0.18288)
		(layer "In11.Cu")
		(net "M_D_CPU1_SA_DQS_DN<4>")
	)
	(segment
		(start 98.091244 -262.988298)
		(end 98.052382 -263.010396)
		(width 0.088646)
		(layer "In11.Cu")
		(net "M_D_CPU1_SA_DQS_DN<4>")
	)
	(segment
		(start 51.270662 -272.540984)
		(end 50.873914 -272.540984)
		(width 0.18288)
		(layer "In11.Cu")
		(net "M_D_CPU1_SA_DQS_DN<4>")
	)
	(segment
		(start 53.783484 -272.793714)
		(end 53.234844 -272.793714)
		(width 0.18288)
		(layer "In11.Cu")
		(net "M_D_CPU1_SA_DQS_DN<4>")
	)
	(segment
		(start 67.270884 -271.736566)
		(end 65.056258 -271.736566)
		(width 0.18288)
		(layer "In11.Cu")
		(net "M_D_CPU1_SA_DQS_DN<4>")
	)
	(segment
		(start 43.075606 -273.432524)
		(end 42.526966 -273.432524)
		(width 0.18288)
		(layer "In11.Cu")
		(net "M_D_CPU1_SA_DQS_DN<4>")
	)
	(segment
		(start 89.862406 -263.190736)
		(end 89.851992 -263.196832)
		(width 0.088646)
		(layer "In11.Cu")
		(net "M_D_CPU1_SA_DQS_DN<4>")
	)
	(segment
		(start 63.463678 -271.736566)
		(end 62.634114 -272.56613)
		(width 0.18288)
		(layer "In11.Cu")
		(net "M_D_CPU1_SA_DQS_DN<4>")
	)
	(segment
		(start 43.200066 -273.556984)
		(end 43.075606 -273.432524)
		(width 0.18288)
		(layer "In11.Cu")
		(net "M_D_CPU1_SA_DQS_DN<4>")
	)
	(segment
		(start 41.853866 -273.556984)
		(end 41.729406 -273.432524)
		(width 0.18288)
		(layer "In11.Cu")
		(net "M_D_CPU1_SA_DQS_DN<4>")
	)
	(segment
		(start 64.931798 -271.612106)
		(end 64.383158 -271.612106)
		(width 0.18288)
		(layer "In11.Cu")
		(net "M_D_CPU1_SA_DQS_DN<4>")
	)
	(segment
		(start 60.526168 -272.56613)
		(end 59.6265 -272.56613)
		(width 0.18288)
		(layer "In11.Cu")
		(net "M_D_CPU1_SA_DQS_DN<4>")
	)
	(segment
		(start 50.596292 -272.818606)
		(end 49.75733 -272.818606)
		(width 0.18288)
		(layer "In11.Cu")
		(net "M_D_CPU1_SA_DQS_DN<4>")
	)
	(segment
		(start 43.748706 -273.556984)
		(end 43.200066 -273.556984)
		(width 0.18288)
		(layer "In11.Cu")
		(net "M_D_CPU1_SA_DQS_DN<4>")
	)
	(segment
		(start 93.236796 -263.196832)
		(end 93.222064 -263.188196)
		(width 0.088646)
		(layer "In11.Cu")
		(net "M_D_CPU1_SA_DQS_DN<4>")
	)
	(segment
		(start 31.404052 -273.656806)
		(end 30.859476 -273.656806)
		(width 0.18288)
		(layer "In11.Cu")
		(net "M_D_CPU1_SA_DQS_DN<4>")
	)
	(segment
		(start 19.935444 -275.343874)
		(end 19.167856 -274.576286)
		(width 0.18288)
		(layer "In11.Cu")
		(net "M_D_CPU1_SA_DQS_DN<4>")
	)
	(segment
		(start 35.533076 -272.785078)
		(end 34.936938 -272.785078)
		(width 0.18288)
		(layer "In11.Cu")
		(net "M_D_CPU1_SA_DQS_DN<4>")
	)
	(segment
		(start 57.801256 -272.087086)
		(end 57.252616 -272.087086)
		(width 0.18288)
		(layer "In11.Cu")
		(net "M_D_CPU1_SA_DQS_DN<4>")
	)
	(segment
		(start 50.873914 -272.540984)
		(end 50.596292 -272.818606)
		(width 0.18288)
		(layer "In11.Cu")
		(net "M_D_CPU1_SA_DQS_DN<4>")
	)
	(segment
		(start 29.50464 -274.347686)
		(end 29.01315 -273.856196)
		(width 0.18288)
		(layer "In11.Cu")
		(net "M_D_CPU1_SA_DQS_DN<4>")
	)
	(segment
		(start 41.056306 -273.556984)
		(end 40.245538 -273.556984)
		(width 0.18288)
		(layer "In11.Cu")
		(net "M_D_CPU1_SA_DQS_DN<4>")
	)
	(segment
		(start 30.859476 -273.656806)
		(end 30.168596 -274.347686)
		(width 0.18288)
		(layer "In11.Cu")
		(net "M_D_CPU1_SA_DQS_DN<4>")
	)
	(segment
		(start 59.147456 -272.087086)
		(end 58.598816 -272.087086)
		(width 0.18288)
		(layer "In11.Cu")
		(net "M_D_CPU1_SA_DQS_DN<4>")
	)
	(segment
		(start 18.172176 -274.576286)
		(end 17.812258 -274.936204)
		(width 0.18288)
		(layer "In11.Cu")
		(net "M_D_CPU1_SA_DQS_DN<4>")
	)
	(segment
		(start 41.729406 -273.432524)
		(end 41.180766 -273.432524)
		(width 0.18288)
		(layer "In11.Cu")
		(net "M_D_CPU1_SA_DQS_DN<4>")
	)
	(segment
		(start 38.081204 -272.80235)
		(end 36.442904 -272.80235)
		(width 0.18288)
		(layer "In11.Cu")
		(net "M_D_CPU1_SA_DQS_DN<4>")
	)
	(segment
		(start 34.073846 -273.64817)
		(end 32.331152 -273.64817)
		(width 0.18288)
		(layer "In11.Cu")
		(net "M_D_CPU1_SA_DQS_DN<4>")
	)
	(segment
		(start 30.168596 -274.347686)
		(end 29.50464 -274.347686)
		(width 0.18288)
		(layer "In11.Cu")
		(net "M_D_CPU1_SA_DQS_DN<4>")
	)
	(segment
		(start 91.357196 -263.196832)
		(end 91.346782 -263.190736)
		(width 0.088646)
		(layer "In11.Cu")
		(net "M_D_CPU1_SA_DQS_DN<4>")
	)
	(segment
		(start 46.495462 -273.669252)
		(end 45.749464 -273.669252)
		(width 0.18288)
		(layer "In11.Cu")
		(net "M_D_CPU1_SA_DQS_DN<4>")
	)
	(segment
		(start 25.63241 -273.856196)
		(end 25.14092 -274.347686)
		(width 0.18288)
		(layer "In11.Cu")
		(net "M_D_CPU1_SA_DQS_DN<4>")
	)
	(segment
		(start 58.474356 -271.962626)
		(end 57.925716 -271.962626)
		(width 0.18288)
		(layer "In11.Cu")
		(net "M_D_CPU1_SA_DQS_DN<4>")
	)
	(segment
		(start 32.331152 -273.64817)
		(end 32.075374 -273.392392)
		(width 0.18288)
		(layer "In11.Cu")
		(net "M_D_CPU1_SA_DQS_DN<4>")
	)
	(segment
		(start 46.772322 -273.392392)
		(end 46.495462 -273.669252)
		(width 0.18288)
		(layer "In11.Cu")
		(net "M_D_CPU1_SA_DQS_DN<4>")
	)
	(segment
		(start 83.096862 -263.643364)
		(end 83.037172 -263.583674)
		(width 0.088646)
		(layer "In11.Cu")
		(net "M_D_CPU1_SA_DQS_DN<4>")
	)
	(segment
		(start 34.936938 -272.785078)
		(end 34.073846 -273.64817)
		(width 0.18288)
		(layer "In11.Cu")
		(net "M_D_CPU1_SA_DQS_DN<4>")
	)
	(segment
		(start 40.245538 -273.556984)
		(end 39.490904 -272.80235)
		(width 0.18288)
		(layer "In11.Cu")
		(net "M_D_CPU1_SA_DQS_DN<4>")
	)
	(segment
		(start 52.561744 -272.669254)
		(end 52.437284 -272.793714)
		(width 0.18288)
		(layer "In11.Cu")
		(net "M_D_CPU1_SA_DQS_DN<4>")
	)
	(segment
		(start 19.167856 -274.576286)
		(end 18.172176 -274.576286)
		(width 0.18288)
		(layer "In11.Cu")
		(net "M_D_CPU1_SA_DQS_DN<4>")
	)
	(segment
		(start 45.749464 -273.669252)
		(end 45.07103 -274.347686)
		(width 0.18288)
		(layer "In11.Cu")
		(net "M_D_CPU1_SA_DQS_DN<4>")
	)
	(segment
		(start 39.490904 -272.80235)
		(end 38.878764 -272.80235)
		(width 0.18288)
		(layer "In11.Cu")
		(net "M_D_CPU1_SA_DQS_DN<4>")
	)
	(segment
		(start 17.05864 -274.936204)
		(end 16.789146 -274.66671)
		(width 0.18288)
		(layer "In11.Cu")
		(net "M_D_CPU1_SA_DQS_DN<4>")
	)
	(segment
		(start 64.258698 -271.736566)
		(end 63.463678 -271.736566)
		(width 0.18288)
		(layer "In11.Cu")
		(net "M_D_CPU1_SA_DQS_DN<4>")
	)
	(segment
		(start 55.836312 -272.087086)
		(end 55.129684 -272.793714)
		(width 0.18288)
		(layer "In11.Cu")
		(net "M_D_CPU1_SA_DQS_DN<4>")
	)
	(segment
		(start 57.252616 -272.087086)
		(end 57.128156 -271.962626)
		(width 0.18288)
		(layer "In11.Cu")
		(net "M_D_CPU1_SA_DQS_DN<4>")
	)
	(segment
		(start 53.234844 -272.793714)
		(end 53.110384 -272.669254)
		(width 0.18288)
		(layer "In11.Cu")
		(net "M_D_CPU1_SA_DQS_DN<4>")
	)
	(segment
		(start 36.442904 -272.80235)
		(end 36.181538 -272.540984)
		(width 0.18288)
		(layer "In11.Cu")
		(net "M_D_CPU1_SA_DQS_DN<4>")
	)
	(segment
		(start 35.77717 -272.540984)
		(end 35.533076 -272.785078)
		(width 0.18288)
		(layer "In11.Cu")
		(net "M_D_CPU1_SA_DQS_DN<4>")
	)
	(segment
		(start 56.579516 -271.962626)
		(end 56.455056 -272.087086)
		(width 0.18288)
		(layer "In11.Cu")
		(net "M_D_CPU1_SA_DQS_DN<4>")
	)
	(segment
		(start 94.176596 -263.196832)
		(end 94.161864 -263.188196)
		(width 0.088646)
		(layer "In11.Cu")
		(net "M_D_CPU1_SA_DQS_DN<4>")
	)
	(segment
		(start 62.634114 -272.56613)
		(end 61.323728 -272.56613)
		(width 0.18288)
		(layer "In11.Cu")
		(net "M_D_CPU1_SA_DQS_DN<4>")
	)
	(segment
		(start 57.128156 -271.962626)
		(end 56.579516 -271.962626)
		(width 0.18288)
		(layer "In11.Cu")
		(net "M_D_CPU1_SA_DQS_DN<4>")
	)
	(segment
		(start 97.897696 -263.05129)
		(end 97.624138 -263.05129)
		(width 0.088646)
		(layer "In11.Cu")
		(net "M_D_CPU1_SA_DQS_DN<4>")
	)
	(segment
		(start 75.423776 -263.583674)
		(end 67.270884 -271.736566)
		(width 0.18288)
		(layer "In11.Cu")
		(net "M_D_CPU1_SA_DQS_DN<4>")
	)
	(segment
		(start 65.056258 -271.736566)
		(end 64.931798 -271.612106)
		(width 0.18288)
		(layer "In11.Cu")
		(net "M_D_CPU1_SA_DQS_DN<4>")
	)
	(segment
		(start 57.925716 -271.962626)
		(end 57.801256 -272.087086)
		(width 0.18288)
		(layer "In11.Cu")
		(net "M_D_CPU1_SA_DQS_DN<4>")
	)
	(segment
		(start 23.843996 -274.347686)
		(end 22.830282 -275.3614)
		(width 0.18288)
		(layer "In11.Cu")
		(net "M_D_CPU1_SA_DQS_DN<4>")
	)
	(segment
		(start 56.455056 -272.087086)
		(end 55.836312 -272.087086)
		(width 0.18288)
		(layer "In11.Cu")
		(net "M_D_CPU1_SA_DQS_DN<4>")
	)
	(segment
		(start 83.037172 -263.583674)
		(end 83.013804 -263.583674)
		(width 0.088646)
		(layer "In11.Cu")
		(net "M_D_CPU1_SA_DQS_DN<4>")
	)
	(segment
		(start 41.180766 -273.432524)
		(end 41.056306 -273.556984)
		(width 0.18288)
		(layer "In11.Cu")
		(net "M_D_CPU1_SA_DQS_DN<4>")
	)
	(segment
		(start 96.99625 -263.196832)
		(end 96.985836 -263.190736)
		(width 0.088646)
		(layer "In11.Cu")
		(net "M_D_CPU1_SA_DQS_DN<4>")
	)
	(segment
		(start 55.129684 -272.793714)
		(end 54.581044 -272.793714)
		(width 0.18288)
		(layer "In11.Cu")
		(net "M_D_CPU1_SA_DQS_DN<4>")
	)
	(segment
		(start 98.122994 -262.872474)
		(end 98.091244 -262.988298)
		(width 0.088646)
		(layer "In11.Cu")
		(net "M_D_CPU1_SA_DQS_DN<4>")
	)
	(segment
		(start 84.025994 -263.247632)
		(end 83.811364 -263.247632)
		(width 0.088646)
		(layer "In11.Cu")
		(net "M_D_CPU1_SA_DQS_DN<4>")
	)
	(arc
		(start 87.032592 -263.196832)
		(mid 86.845394 -263.246975)
		(end 86.658196 -263.196832)
		(width 0.088646)
		(layer "In11.Cu")
		(net "M_D_CPU1_SA_DQS_DN<4>")
	)
	(arc
		(start 87.597996 -263.196832)
		(mid 87.315294 -263.12109)
		(end 87.032592 -263.196832)
		(width 0.088646)
		(layer "In11.Cu")
		(net "M_D_CPU1_SA_DQS_DN<4>")
	)
	(arc
		(start 91.346782 -263.190736)
		(mid 91.068604 -263.121044)
		(end 90.792046 -263.196832)
		(width 0.088646)
		(layer "In11.Cu")
		(net "M_D_CPU1_SA_DQS_DN<4>")
	)
	(arc
		(start 84.213192 -263.196832)
		(mid 84.122936 -263.234554)
		(end 84.025994 -263.247632)
		(width 0.088646)
		(layer "In11.Cu")
		(net "M_D_CPU1_SA_DQS_DN<4>")
	)
	(arc
		(start 90.792046 -263.196832)
		(mid 90.604848 -263.246975)
		(end 90.41765 -263.196832)
		(width 0.088646)
		(layer "In11.Cu")
		(net "M_D_CPU1_SA_DQS_DN<4>")
	)
	(arc
		(start 90.41765 -263.196832)
		(mid 90.140837 -263.120996)
		(end 89.862406 -263.190736)
		(width 0.088646)
		(layer "In11.Cu")
		(net "M_D_CPU1_SA_DQS_DN<4>")
	)
	(arc
		(start 95.490792 -263.196832)
		(mid 95.303594 -263.246975)
		(end 95.116396 -263.196832)
		(width 0.088646)
		(layer "In11.Cu")
		(net "M_D_CPU1_SA_DQS_DN<4>")
	)
	(arc
		(start 89.851992 -263.196832)
		(mid 89.664794 -263.246975)
		(end 89.477596 -263.196832)
		(width 0.088646)
		(layer "In11.Cu")
		(net "M_D_CPU1_SA_DQS_DN<4>")
	)
	(arc
		(start 92.282264 -263.188196)
		(mid 92.005823 -263.12103)
		(end 91.731592 -263.196832)
		(width 0.088646)
		(layer "In11.Cu")
		(net "M_D_CPU1_SA_DQS_DN<4>")
	)
	(arc
		(start 88.537796 -263.196832)
		(mid 88.255094 -263.12109)
		(end 87.972392 -263.196832)
		(width 0.088646)
		(layer "In11.Cu")
		(net "M_D_CPU1_SA_DQS_DN<4>")
	)
	(arc
		(start 94.161864 -263.188196)
		(mid 93.885423 -263.12103)
		(end 93.611192 -263.196832)
		(width 0.088646)
		(layer "In11.Cu")
		(net "M_D_CPU1_SA_DQS_DN<4>")
	)
	(arc
		(start 91.731592 -263.196832)
		(mid 91.544394 -263.246975)
		(end 91.357196 -263.196832)
		(width 0.088646)
		(layer "In11.Cu")
		(net "M_D_CPU1_SA_DQS_DN<4>")
	)
	(arc
		(start 86.092792 -263.196832)
		(mid 85.905594 -263.246975)
		(end 85.718396 -263.196832)
		(width 0.088646)
		(layer "In11.Cu")
		(net "M_D_CPU1_SA_DQS_DN<4>")
	)
	(arc
		(start 95.116396 -263.196832)
		(mid 94.833694 -263.12109)
		(end 94.550992 -263.196832)
		(width 0.088646)
		(layer "In11.Cu")
		(net "M_D_CPU1_SA_DQS_DN<4>")
	)
	(arc
		(start 96.985836 -263.190736)
		(mid 96.707404 -263.120922)
		(end 96.430592 -263.196832)
		(width 0.088646)
		(layer "In11.Cu")
		(net "M_D_CPU1_SA_DQS_DN<4>")
	)
	(arc
		(start 97.370646 -263.196832)
		(mid 97.183448 -263.246975)
		(end 96.99625 -263.196832)
		(width 0.088646)
		(layer "In11.Cu")
		(net "M_D_CPU1_SA_DQS_DN<4>")
	)
	(arc
		(start 94.550992 -263.196832)
		(mid 94.363794 -263.246975)
		(end 94.176596 -263.196832)
		(width 0.088646)
		(layer "In11.Cu")
		(net "M_D_CPU1_SA_DQS_DN<4>")
	)
	(arc
		(start 86.658196 -263.196832)
		(mid 86.375494 -263.12109)
		(end 86.092792 -263.196832)
		(width 0.088646)
		(layer "In11.Cu")
		(net "M_D_CPU1_SA_DQS_DN<4>")
	)
	(arc
		(start 96.430592 -263.196832)
		(mid 96.243394 -263.246975)
		(end 96.056196 -263.196832)
		(width 0.088646)
		(layer "In11.Cu")
		(net "M_D_CPU1_SA_DQS_DN<4>")
	)
	(arc
		(start 96.041464 -263.188196)
		(mid 95.765023 -263.12103)
		(end 95.490792 -263.196832)
		(width 0.088646)
		(layer "In11.Cu")
		(net "M_D_CPU1_SA_DQS_DN<4>")
	)
	(arc
		(start 89.477596 -263.196832)
		(mid 89.194894 -263.12109)
		(end 88.912192 -263.196832)
		(width 0.088646)
		(layer "In11.Cu")
		(net "M_D_CPU1_SA_DQS_DN<4>")
	)
	(arc
		(start 87.972392 -263.196832)
		(mid 87.785194 -263.246975)
		(end 87.597996 -263.196832)
		(width 0.088646)
		(layer "In11.Cu")
		(net "M_D_CPU1_SA_DQS_DN<4>")
	)
	(arc
		(start 93.222064 -263.188196)
		(mid 92.945623 -263.12103)
		(end 92.671392 -263.196832)
		(width 0.088646)
		(layer "In11.Cu")
		(net "M_D_CPU1_SA_DQS_DN<4>")
	)
	(arc
		(start 85.152992 -263.196832)
		(mid 84.965794 -263.246975)
		(end 84.778596 -263.196832)
		(width 0.088646)
		(layer "In11.Cu")
		(net "M_D_CPU1_SA_DQS_DN<4>")
	)
	(arc
		(start 88.912192 -263.196832)
		(mid 88.724994 -263.246975)
		(end 88.537796 -263.196832)
		(width 0.088646)
		(layer "In11.Cu")
		(net "M_D_CPU1_SA_DQS_DN<4>")
	)
	(arc
		(start 84.778596 -263.196832)
		(mid 84.495894 -263.12109)
		(end 84.213192 -263.196832)
		(width 0.088646)
		(layer "In11.Cu")
		(net "M_D_CPU1_SA_DQS_DN<4>")
	)
	(arc
		(start 92.671392 -263.196832)
		(mid 92.484194 -263.246975)
		(end 92.296996 -263.196832)
		(width 0.088646)
		(layer "In11.Cu")
		(net "M_D_CPU1_SA_DQS_DN<4>")
	)
	(arc
		(start 98.052382 -263.010396)
		(mid 97.977697 -263.040901)
		(end 97.897696 -263.05129)
		(width 0.088646)
		(layer "In11.Cu")
		(net "M_D_CPU1_SA_DQS_DN<4>")
	)
	(arc
		(start 85.718396 -263.196832)
		(mid 85.435694 -263.12109)
		(end 85.152992 -263.196832)
		(width 0.088646)
		(layer "In11.Cu")
		(net "M_D_CPU1_SA_DQS_DN<4>")
	)
	(arc
		(start 93.611192 -263.196832)
		(mid 93.423994 -263.246975)
		(end 93.236796 -263.196832)
		(width 0.088646)
		(layer "In11.Cu")
		(net "M_D_CPU1_SA_DQS_DN<4>")
	)
	(segment
		(start 14.044676 -284.703012)
		(end 13.857986 -284.703012)
		(width 0.20066)
		(layer "F.Cu")
		(net "M_D_CPU1_SA_DQS_DN<3>")
	)
	(segment
		(start 14.876526 -284.277816)
		(end 14.469872 -284.277816)
		(width 0.20066)
		(layer "F.Cu")
		(net "M_D_CPU1_SA_DQS_DN<3>")
	)
	(segment
		(start 9.46404 -284.277816)
		(end 8.950198 -284.277816)
		(width 0.20066)
		(layer "F.Cu")
		(net "M_D_CPU1_SA_DQS_DN<3>")
	)
	(segment
		(start 13.59662 -284.441646)
		(end 13.441426 -284.441646)
		(width 0.20066)
		(layer "F.Cu")
		(net "M_D_CPU1_SA_DQS_DN<3>")
	)
	(segment
		(start 15.684246 -284.016704)
		(end 16.789146 -284.016704)
		(width 0.20066)
		(layer "F.Cu")
		(net "M_D_CPU1_SA_DQS_DN<3>")
	)
	(segment
		(start 10.64006 -284.703012)
		(end 10.100056 -284.703012)
		(width 0.20066)
		(layer "F.Cu")
		(net "M_D_CPU1_SA_DQS_DN<3>")
	)
	(segment
		(start 14.469872 -284.277816)
		(end 14.044676 -284.703012)
		(width 0.20066)
		(layer "F.Cu")
		(net "M_D_CPU1_SA_DQS_DN<3>")
	)
	(segment
		(start 15.137638 -284.016704)
		(end 14.876526 -284.277816)
		(width 0.20066)
		(layer "F.Cu")
		(net "M_D_CPU1_SA_DQS_DN<3>")
	)
	(segment
		(start 10.912094 -284.430978)
		(end 10.64006 -284.703012)
		(width 0.20066)
		(layer "F.Cu")
		(net "M_D_CPU1_SA_DQS_DN<3>")
	)
	(segment
		(start 98.122994 -267.220192)
		(end 98.122994 -267.755878)
		(width 0.20066)
		(layer "F.Cu")
		(net "M_D_CPU1_SA_DQS_DN<3>")
	)
	(segment
		(start 13.857986 -284.703012)
		(end 13.59662 -284.441646)
		(width 0.20066)
		(layer "F.Cu")
		(net "M_D_CPU1_SA_DQS_DN<3>")
	)
	(segment
		(start 8.950198 -284.277816)
		(end 8.689086 -284.016704)
		(width 0.20066)
		(layer "F.Cu")
		(net "M_D_CPU1_SA_DQS_DN<3>")
	)
	(segment
		(start 11.117072 -284.430978)
		(end 11.11631 -284.430978)
		(width 0.101854)
		(layer "F.Cu")
		(net "M_D_CPU1_SA_DQS_DN<3>")
	)
	(segment
		(start 10.100056 -284.703012)
		(end 9.46404 -284.277816)
		(width 0.20066)
		(layer "F.Cu")
		(net "M_D_CPU1_SA_DQS_DN<3>")
	)
	(segment
		(start 98.123248 -267.219938)
		(end 98.122994 -267.220192)
		(width 0.20066)
		(layer "F.Cu")
		(net "M_D_CPU1_SA_DQS_DN<3>")
	)
	(segment
		(start 11.11631 -284.430978)
		(end 10.912094 -284.430978)
		(width 0.20066)
		(layer "F.Cu")
		(net "M_D_CPU1_SA_DQS_DN<3>")
	)
	(segment
		(start 13.441426 -284.441646)
		(end 11.12774 -284.441646)
		(width 0.1016)
		(layer "F.Cu")
		(net "M_D_CPU1_SA_DQS_DN<3>")
	)
	(segment
		(start 11.12774 -284.441646)
		(end 11.117072 -284.430978)
		(width 0.101854)
		(layer "F.Cu")
		(net "M_D_CPU1_SA_DQS_DN<3>")
	)
	(segment
		(start 15.684246 -284.016704)
		(end 15.137638 -284.016704)
		(width 0.20066)
		(layer "F.Cu")
		(net "M_D_CPU1_SA_DQS_DN<3>")
	)
	(segment
		(start 8.689086 -284.016704)
		(end 8.140446 -284.016704)
		(width 0.20066)
		(layer "F.Cu")
		(net "M_D_CPU1_SA_DQS_DN<3>")
	)
	(segment
		(start 97.897696 -267.934694)
		(end 97.624138 -267.934694)
		(width 0.088646)
		(layer "In11.Cu")
		(net "M_D_CPU1_SA_DQS_DN<3>")
	)
	(segment
		(start 21.336508 -284.703012)
		(end 21.076412 -284.442916)
		(width 0.18288)
		(layer "In11.Cu")
		(net "M_D_CPU1_SA_DQS_DN<3>")
	)
	(segment
		(start 83.363562 -269.658084)
		(end 83.022694 -269.658084)
		(width 0.088646)
		(layer "In11.Cu")
		(net "M_D_CPU1_SA_DQS_DN<3>")
	)
	(segment
		(start 59.026044 -282.828238)
		(end 58.035698 -282.828238)
		(width 0.18288)
		(layer "In11.Cu")
		(net "M_D_CPU1_SA_DQS_DN<3>")
	)
	(segment
		(start 46.773846 -285.290768)
		(end 46.506384 -285.55823)
		(width 0.18288)
		(layer "In11.Cu")
		(net "M_D_CPU1_SA_DQS_DN<3>")
	)
	(segment
		(start 93.236796 -268.080236)
		(end 93.222064 -268.0716)
		(width 0.088646)
		(layer "In11.Cu")
		(net "M_D_CPU1_SA_DQS_DN<3>")
	)
	(segment
		(start 17.054576 -284.282134)
		(end 16.789146 -284.016704)
		(width 0.18288)
		(layer "In11.Cu")
		(net "M_D_CPU1_SA_DQS_DN<3>")
	)
	(segment
		(start 91.357196 -268.080236)
		(end 91.346782 -268.07414)
		(width 0.088646)
		(layer "In11.Cu")
		(net "M_D_CPU1_SA_DQS_DN<3>")
	)
	(segment
		(start 60.269882 -282.224226)
		(end 60.145422 -282.348686)
		(width 0.18288)
		(layer "In11.Cu")
		(net "M_D_CPU1_SA_DQS_DN<3>")
	)
	(segment
		(start 61.978286 -282.22956)
		(end 61.69025 -282.348686)
		(width 0.18288)
		(layer "In11.Cu")
		(net "M_D_CPU1_SA_DQS_DN<3>")
	)
	(segment
		(start 48.650906 -285.438088)
		(end 48.102266 -285.438088)
		(width 0.18288)
		(layer "In11.Cu")
		(net "M_D_CPU1_SA_DQS_DN<3>")
	)
	(segment
		(start 52.47259 -284.174692)
		(end 51.934872 -284.712156)
		(width 0.18288)
		(layer "In11.Cu")
		(net "M_D_CPU1_SA_DQS_DN<3>")
	)
	(segment
		(start 65.350644 -280.924254)
		(end 64.802004 -280.924254)
		(width 0.18288)
		(layer "In11.Cu")
		(net "M_D_CPU1_SA_DQS_DN<3>")
	)
	(segment
		(start 83.794346 -268.754098)
		(end 83.794346 -269.002002)
		(width 0.088646)
		(layer "In11.Cu")
		(net "M_D_CPU1_SA_DQS_DN<3>")
	)
	(segment
		(start 78.010258 -269.598394)
		(end 66.559938 -281.048714)
		(width 0.18288)
		(layer "In11.Cu")
		(net "M_D_CPU1_SA_DQS_DN<3>")
	)
	(segment
		(start 57.911238 -282.703778)
		(end 57.362598 -282.703778)
		(width 0.18288)
		(layer "In11.Cu")
		(net "M_D_CPU1_SA_DQS_DN<3>")
	)
	(segment
		(start 31.050992 -285.570422)
		(end 30.590744 -285.110174)
		(width 0.18288)
		(layer "In11.Cu")
		(net "M_D_CPU1_SA_DQS_DN<3>")
	)
	(segment
		(start 38.60419 -284.000194)
		(end 36.907724 -284.703012)
		(width 0.18288)
		(layer "In11.Cu")
		(net "M_D_CPU1_SA_DQS_DN<3>")
	)
	(segment
		(start 48.775366 -285.562548)
		(end 48.650906 -285.438088)
		(width 0.18288)
		(layer "In11.Cu")
		(net "M_D_CPU1_SA_DQS_DN<3>")
	)
	(segment
		(start 89.862406 -268.07414)
		(end 89.851992 -268.080236)
		(width 0.088646)
		(layer "In11.Cu")
		(net "M_D_CPU1_SA_DQS_DN<3>")
	)
	(segment
		(start 51.254406 -284.44063)
		(end 50.873914 -284.44063)
		(width 0.18288)
		(layer "In11.Cu")
		(net "M_D_CPU1_SA_DQS_DN<3>")
	)
	(segment
		(start 28.089606 -284.03931)
		(end 27.540966 -284.03931)
		(width 0.18288)
		(layer "In11.Cu")
		(net "M_D_CPU1_SA_DQS_DN<3>")
	)
	(segment
		(start 65.475104 -281.048714)
		(end 65.350644 -280.924254)
		(width 0.18288)
		(layer "In11.Cu")
		(net "M_D_CPU1_SA_DQS_DN<3>")
	)
	(segment
		(start 27.540966 -284.03931)
		(end 27.416506 -283.91485)
		(width 0.18288)
		(layer "In11.Cu")
		(net "M_D_CPU1_SA_DQS_DN<3>")
	)
	(segment
		(start 51.525932 -284.712156)
		(end 51.254406 -284.44063)
		(width 0.18288)
		(layer "In11.Cu")
		(net "M_D_CPU1_SA_DQS_DN<3>")
	)
	(segment
		(start 84.075524 -268.47292)
		(end 83.794346 -268.754098)
		(width 0.088646)
		(layer "In11.Cu")
		(net "M_D_CPU1_SA_DQS_DN<3>")
	)
	(segment
		(start 83.486498 -269.535148)
		(end 83.363562 -269.658084)
		(width 0.088646)
		(layer "In11.Cu")
		(net "M_D_CPU1_SA_DQS_DN<3>")
	)
	(segment
		(start 19.163538 -284.109414)
		(end 18.154904 -284.109414)
		(width 0.18288)
		(layer "In11.Cu")
		(net "M_D_CPU1_SA_DQS_DN<3>")
	)
	(segment
		(start 57.238138 -282.828238)
		(end 56.502554 -282.828238)
		(width 0.18288)
		(layer "In11.Cu")
		(net "M_D_CPU1_SA_DQS_DN<3>")
	)
	(segment
		(start 50.598832 -284.715712)
		(end 50.07229 -284.715712)
		(width 0.18288)
		(layer "In11.Cu")
		(net "M_D_CPU1_SA_DQS_DN<3>")
	)
	(segment
		(start 25.894792 -284.03931)
		(end 24.293322 -284.703012)
		(width 0.18288)
		(layer "In11.Cu")
		(net "M_D_CPU1_SA_DQS_DN<3>")
	)
	(segment
		(start 19.504914 -284.450536)
		(end 19.163538 -284.109414)
		(width 0.18288)
		(layer "In11.Cu")
		(net "M_D_CPU1_SA_DQS_DN<3>")
	)
	(segment
		(start 30.590744 -285.110174)
		(end 30.590744 -284.934152)
		(width 0.18288)
		(layer "In11.Cu")
		(net "M_D_CPU1_SA_DQS_DN<3>")
	)
	(segment
		(start 28.214066 -283.91485)
		(end 28.089606 -284.03931)
		(width 0.18288)
		(layer "In11.Cu")
		(net "M_D_CPU1_SA_DQS_DN<3>")
	)
	(segment
		(start 44.174918 -284.17139)
		(end 44.012358 -284.238954)
		(width 0.18288)
		(layer "In11.Cu")
		(net "M_D_CPU1_SA_DQS_DN<3>")
	)
	(segment
		(start 30.202378 -284.545786)
		(end 30.026356 -284.545786)
		(width 0.18288)
		(layer "In11.Cu")
		(net "M_D_CPU1_SA_DQS_DN<3>")
	)
	(segment
		(start 30.026356 -284.545786)
		(end 29.51988 -284.03931)
		(width 0.18288)
		(layer "In11.Cu")
		(net "M_D_CPU1_SA_DQS_DN<3>")
	)
	(segment
		(start 59.505596 -282.348686)
		(end 59.026044 -282.828238)
		(width 0.18288)
		(layer "In11.Cu")
		(net "M_D_CPU1_SA_DQS_DN<3>")
	)
	(segment
		(start 32.328358 -285.543752)
		(end 32.075374 -285.290768)
		(width 0.18288)
		(layer "In11.Cu")
		(net "M_D_CPU1_SA_DQS_DN<3>")
	)
	(segment
		(start 35.50666 -284.720284)
		(end 35.271964 -284.720284)
		(width 0.18288)
		(layer "In11.Cu")
		(net "M_D_CPU1_SA_DQS_DN<3>")
	)
	(segment
		(start 31.686246 -285.290768)
		(end 31.406592 -285.570422)
		(width 0.18288)
		(layer "In11.Cu")
		(net "M_D_CPU1_SA_DQS_DN<3>")
	)
	(segment
		(start 20.422616 -284.690312)
		(end 20.083526 -284.690312)
		(width 0.18288)
		(layer "In11.Cu")
		(net "M_D_CPU1_SA_DQS_DN<3>")
	)
	(segment
		(start 98.091244 -267.871702)
		(end 98.052382 -267.8938)
		(width 0.088646)
		(layer "In11.Cu")
		(net "M_D_CPU1_SA_DQS_DN<3>")
	)
	(segment
		(start 44.749466 -284.544262)
		(end 44.682156 -284.381448)
		(width 0.18288)
		(layer "In11.Cu")
		(net "M_D_CPU1_SA_DQS_DN<3>")
	)
	(segment
		(start 49.225454 -285.562548)
		(end 48.775366 -285.562548)
		(width 0.18288)
		(layer "In11.Cu")
		(net "M_D_CPU1_SA_DQS_DN<3>")
	)
	(segment
		(start 53.762148 -283.639768)
		(end 52.47259 -284.174692)
		(width 0.18288)
		(layer "In11.Cu")
		(net "M_D_CPU1_SA_DQS_DN<3>")
	)
	(segment
		(start 98.122994 -267.755878)
		(end 98.091244 -267.871702)
		(width 0.088646)
		(layer "In11.Cu")
		(net "M_D_CPU1_SA_DQS_DN<3>")
	)
	(segment
		(start 35.271964 -284.720284)
		(end 33.286192 -285.543752)
		(width 0.18288)
		(layer "In11.Cu")
		(net "M_D_CPU1_SA_DQS_DN<3>")
	)
	(segment
		(start 83.486498 -269.30985)
		(end 83.486498 -269.535148)
		(width 0.088646)
		(layer "In11.Cu")
		(net "M_D_CPU1_SA_DQS_DN<3>")
	)
	(segment
		(start 45.256196 -284.754066)
		(end 44.749466 -284.544262)
		(width 0.18288)
		(layer "In11.Cu")
		(net "M_D_CPU1_SA_DQS_DN<3>")
	)
	(segment
		(start 17.737836 -284.282134)
		(end 17.054576 -284.282134)
		(width 0.18288)
		(layer "In11.Cu")
		(net "M_D_CPU1_SA_DQS_DN<3>")
	)
	(segment
		(start 39.95039 -284.000194)
		(end 39.82593 -283.875734)
		(width 0.18288)
		(layer "In11.Cu")
		(net "M_D_CPU1_SA_DQS_DN<3>")
	)
	(segment
		(start 26.867866 -283.91485)
		(end 26.743406 -284.03931)
		(width 0.18288)
		(layer "In11.Cu")
		(net "M_D_CPU1_SA_DQS_DN<3>")
	)
	(segment
		(start 82.963004 -269.598394)
		(end 78.010258 -269.598394)
		(width 0.18288)
		(layer "In11.Cu")
		(net "M_D_CPU1_SA_DQS_DN<3>")
	)
	(segment
		(start 28.762706 -283.91485)
		(end 28.214066 -283.91485)
		(width 0.18288)
		(layer "In11.Cu")
		(net "M_D_CPU1_SA_DQS_DN<3>")
	)
	(segment
		(start 56.502554 -282.828238)
		(end 54.542944 -283.639768)
		(width 0.18288)
		(layer "In11.Cu")
		(net "M_D_CPU1_SA_DQS_DN<3>")
	)
	(segment
		(start 40.49903 -284.000194)
		(end 39.95039 -284.000194)
		(width 0.18288)
		(layer "In11.Cu")
		(net "M_D_CPU1_SA_DQS_DN<3>")
	)
	(segment
		(start 94.176596 -268.080236)
		(end 94.161864 -268.0716)
		(width 0.088646)
		(layer "In11.Cu")
		(net "M_D_CPU1_SA_DQS_DN<3>")
	)
	(segment
		(start 60.942982 -282.348686)
		(end 60.818522 -282.224226)
		(width 0.18288)
		(layer "In11.Cu")
		(net "M_D_CPU1_SA_DQS_DN<3>")
	)
	(segment
		(start 29.51988 -284.03931)
		(end 28.887166 -284.03931)
		(width 0.18288)
		(layer "In11.Cu")
		(net "M_D_CPU1_SA_DQS_DN<3>")
	)
	(segment
		(start 47.977806 -285.562548)
		(end 47.429166 -285.562548)
		(width 0.18288)
		(layer "In11.Cu")
		(net "M_D_CPU1_SA_DQS_DN<3>")
	)
	(segment
		(start 96.056196 -268.080236)
		(end 96.041464 -268.0716)
		(width 0.088646)
		(layer "In11.Cu")
		(net "M_D_CPU1_SA_DQS_DN<3>")
	)
	(segment
		(start 60.818522 -282.224226)
		(end 60.269882 -282.224226)
		(width 0.18288)
		(layer "In11.Cu")
		(net "M_D_CPU1_SA_DQS_DN<3>")
	)
	(segment
		(start 24.293322 -284.703012)
		(end 21.336508 -284.703012)
		(width 0.18288)
		(layer "In11.Cu")
		(net "M_D_CPU1_SA_DQS_DN<3>")
	)
	(segment
		(start 84.075524 -268.324076)
		(end 84.075524 -268.47292)
		(width 0.088646)
		(layer "In11.Cu")
		(net "M_D_CPU1_SA_DQS_DN<3>")
	)
	(segment
		(start 51.934872 -284.712156)
		(end 51.525932 -284.712156)
		(width 0.18288)
		(layer "In11.Cu")
		(net "M_D_CPU1_SA_DQS_DN<3>")
	)
	(segment
		(start 97.3709 -268.08049)
		(end 97.370646 -268.080236)
		(width 0.088646)
		(layer "In11.Cu")
		(net "M_D_CPU1_SA_DQS_DN<3>")
	)
	(segment
		(start 46.06036 -285.55823)
		(end 45.256196 -284.754066)
		(width 0.18288)
		(layer "In11.Cu")
		(net "M_D_CPU1_SA_DQS_DN<3>")
	)
	(segment
		(start 46.506384 -285.55823)
		(end 46.06036 -285.55823)
		(width 0.18288)
		(layer "In11.Cu")
		(net "M_D_CPU1_SA_DQS_DN<3>")
	)
	(segment
		(start 26.743406 -284.03931)
		(end 25.894792 -284.03931)
		(width 0.18288)
		(layer "In11.Cu")
		(net "M_D_CPU1_SA_DQS_DN<3>")
	)
	(segment
		(start 41.17213 -283.875734)
		(end 40.62349 -283.875734)
		(width 0.18288)
		(layer "In11.Cu")
		(net "M_D_CPU1_SA_DQS_DN<3>")
	)
	(segment
		(start 33.286192 -285.543752)
		(end 32.328358 -285.543752)
		(width 0.18288)
		(layer "In11.Cu")
		(net "M_D_CPU1_SA_DQS_DN<3>")
	)
	(segment
		(start 47.157386 -285.290768)
		(end 46.773846 -285.290768)
		(width 0.18288)
		(layer "In11.Cu")
		(net "M_D_CPU1_SA_DQS_DN<3>")
	)
	(segment
		(start 60.145422 -282.348686)
		(end 59.505596 -282.348686)
		(width 0.18288)
		(layer "In11.Cu")
		(net "M_D_CPU1_SA_DQS_DN<3>")
	)
	(segment
		(start 83.794346 -269.002002)
		(end 83.486498 -269.30985)
		(width 0.088646)
		(layer "In11.Cu")
		(net "M_D_CPU1_SA_DQS_DN<3>")
	)
	(segment
		(start 66.559938 -281.048714)
		(end 65.475104 -281.048714)
		(width 0.18288)
		(layer "In11.Cu")
		(net "M_D_CPU1_SA_DQS_DN<3>")
	)
	(segment
		(start 61.69025 -282.348686)
		(end 60.942982 -282.348686)
		(width 0.18288)
		(layer "In11.Cu")
		(net "M_D_CPU1_SA_DQS_DN<3>")
	)
	(segment
		(start 32.075374 -285.290768)
		(end 31.686246 -285.290768)
		(width 0.18288)
		(layer "In11.Cu")
		(net "M_D_CPU1_SA_DQS_DN<3>")
	)
	(segment
		(start 27.416506 -283.91485)
		(end 26.867866 -283.91485)
		(width 0.18288)
		(layer "In11.Cu")
		(net "M_D_CPU1_SA_DQS_DN<3>")
	)
	(segment
		(start 39.27729 -283.875734)
		(end 39.15283 -284.000194)
		(width 0.18288)
		(layer "In11.Cu")
		(net "M_D_CPU1_SA_DQS_DN<3>")
	)
	(segment
		(start 36.43122 -284.703012)
		(end 36.168838 -284.44063)
		(width 0.18288)
		(layer "In11.Cu")
		(net "M_D_CPU1_SA_DQS_DN<3>")
	)
	(segment
		(start 50.07229 -284.715712)
		(end 49.225454 -285.562548)
		(width 0.18288)
		(layer "In11.Cu")
		(net "M_D_CPU1_SA_DQS_DN<3>")
	)
	(segment
		(start 41.29659 -284.000194)
		(end 41.17213 -283.875734)
		(width 0.18288)
		(layer "In11.Cu")
		(net "M_D_CPU1_SA_DQS_DN<3>")
	)
	(segment
		(start 57.362598 -282.703778)
		(end 57.238138 -282.828238)
		(width 0.18288)
		(layer "In11.Cu")
		(net "M_D_CPU1_SA_DQS_DN<3>")
	)
	(segment
		(start 47.429166 -285.562548)
		(end 47.157386 -285.290768)
		(width 0.18288)
		(layer "In11.Cu")
		(net "M_D_CPU1_SA_DQS_DN<3>")
	)
	(segment
		(start 28.887166 -284.03931)
		(end 28.762706 -283.91485)
		(width 0.18288)
		(layer "In11.Cu")
		(net "M_D_CPU1_SA_DQS_DN<3>")
	)
	(segment
		(start 96.99625 -268.080236)
		(end 96.985836 -268.07414)
		(width 0.088646)
		(layer "In11.Cu")
		(net "M_D_CPU1_SA_DQS_DN<3>")
	)
	(segment
		(start 35.786314 -284.44063)
		(end 35.50666 -284.720284)
		(width 0.18288)
		(layer "In11.Cu")
		(net "M_D_CPU1_SA_DQS_DN<3>")
	)
	(segment
		(start 83.022694 -269.658084)
		(end 82.963004 -269.598394)
		(width 0.088646)
		(layer "In11.Cu")
		(net "M_D_CPU1_SA_DQS_DN<3>")
	)
	(segment
		(start 31.406592 -285.570422)
		(end 31.050992 -285.570422)
		(width 0.18288)
		(layer "In11.Cu")
		(net "M_D_CPU1_SA_DQS_DN<3>")
	)
	(segment
		(start 54.542944 -283.639768)
		(end 53.762148 -283.639768)
		(width 0.18288)
		(layer "In11.Cu")
		(net "M_D_CPU1_SA_DQS_DN<3>")
	)
	(segment
		(start 50.873914 -284.44063)
		(end 50.598832 -284.715712)
		(width 0.18288)
		(layer "In11.Cu")
		(net "M_D_CPU1_SA_DQS_DN<3>")
	)
	(segment
		(start 36.168838 -284.44063)
		(end 35.786314 -284.44063)
		(width 0.18288)
		(layer "In11.Cu")
		(net "M_D_CPU1_SA_DQS_DN<3>")
	)
	(segment
		(start 30.590744 -284.934152)
		(end 30.202378 -284.545786)
		(width 0.18288)
		(layer "In11.Cu")
		(net "M_D_CPU1_SA_DQS_DN<3>")
	)
	(segment
		(start 44.682156 -284.381448)
		(end 44.174918 -284.17139)
		(width 0.18288)
		(layer "In11.Cu")
		(net "M_D_CPU1_SA_DQS_DN<3>")
	)
	(segment
		(start 39.82593 -283.875734)
		(end 39.27729 -283.875734)
		(width 0.18288)
		(layer "In11.Cu")
		(net "M_D_CPU1_SA_DQS_DN<3>")
	)
	(segment
		(start 43.435778 -284.000194)
		(end 41.29659 -284.000194)
		(width 0.18288)
		(layer "In11.Cu")
		(net "M_D_CPU1_SA_DQS_DN<3>")
	)
	(segment
		(start 39.15283 -284.000194)
		(end 38.60419 -284.000194)
		(width 0.18288)
		(layer "In11.Cu")
		(net "M_D_CPU1_SA_DQS_DN<3>")
	)
	(segment
		(start 64.802004 -280.924254)
		(end 64.677544 -281.048714)
		(width 0.18288)
		(layer "In11.Cu")
		(net "M_D_CPU1_SA_DQS_DN<3>")
	)
	(segment
		(start 20.083526 -284.690312)
		(end 19.504914 -284.450536)
		(width 0.18288)
		(layer "In11.Cu")
		(net "M_D_CPU1_SA_DQS_DN<3>")
	)
	(segment
		(start 58.035698 -282.828238)
		(end 57.911238 -282.703778)
		(width 0.18288)
		(layer "In11.Cu")
		(net "M_D_CPU1_SA_DQS_DN<3>")
	)
	(segment
		(start 36.907724 -284.703012)
		(end 36.43122 -284.703012)
		(width 0.18288)
		(layer "In11.Cu")
		(net "M_D_CPU1_SA_DQS_DN<3>")
	)
	(segment
		(start 63.159132 -281.048714)
		(end 61.978286 -282.22956)
		(width 0.18288)
		(layer "In11.Cu")
		(net "M_D_CPU1_SA_DQS_DN<3>")
	)
	(segment
		(start 92.296996 -268.080236)
		(end 92.282264 -268.0716)
		(width 0.088646)
		(layer "In11.Cu")
		(net "M_D_CPU1_SA_DQS_DN<3>")
	)
	(segment
		(start 64.677544 -281.048714)
		(end 63.159132 -281.048714)
		(width 0.18288)
		(layer "In11.Cu")
		(net "M_D_CPU1_SA_DQS_DN<3>")
	)
	(segment
		(start 21.076412 -284.442916)
		(end 20.670012 -284.442916)
		(width 0.18288)
		(layer "In11.Cu")
		(net "M_D_CPU1_SA_DQS_DN<3>")
	)
	(segment
		(start 18.154904 -284.109414)
		(end 17.737836 -284.282134)
		(width 0.18288)
		(layer "In11.Cu")
		(net "M_D_CPU1_SA_DQS_DN<3>")
	)
	(segment
		(start 20.670012 -284.442916)
		(end 20.422616 -284.690312)
		(width 0.18288)
		(layer "In11.Cu")
		(net "M_D_CPU1_SA_DQS_DN<3>")
	)
	(segment
		(start 97.624138 -267.934694)
		(end 97.3709 -268.08049)
		(width 0.088646)
		(layer "In11.Cu")
		(net "M_D_CPU1_SA_DQS_DN<3>")
	)
	(segment
		(start 48.102266 -285.438088)
		(end 47.977806 -285.562548)
		(width 0.18288)
		(layer "In11.Cu")
		(net "M_D_CPU1_SA_DQS_DN<3>")
	)
	(segment
		(start 40.62349 -283.875734)
		(end 40.49903 -284.000194)
		(width 0.18288)
		(layer "In11.Cu")
		(net "M_D_CPU1_SA_DQS_DN<3>")
	)
	(segment
		(start 44.012358 -284.238954)
		(end 43.435778 -284.000194)
		(width 0.18288)
		(layer "In11.Cu")
		(net "M_D_CPU1_SA_DQS_DN<3>")
	)
	(arc
		(start 91.346782 -268.07414)
		(mid 91.068604 -268.004417)
		(end 90.792046 -268.080236)
		(width 0.088646)
		(layer "In11.Cu")
		(net "M_D_CPU1_SA_DQS_DN<3>")
	)
	(arc
		(start 85.193632 -268.058646)
		(mid 84.986007 -268.111745)
		(end 84.773516 -268.083792)
		(width 0.088646)
		(layer "In11.Cu")
		(net "M_D_CPU1_SA_DQS_DN<3>")
	)
	(arc
		(start 94.161864 -268.0716)
		(mid 93.885389 -268.00428)
		(end 93.611192 -268.080236)
		(width 0.088646)
		(layer "In11.Cu")
		(net "M_D_CPU1_SA_DQS_DN<3>")
	)
	(arc
		(start 93.222064 -268.0716)
		(mid 92.945589 -268.00428)
		(end 92.671392 -268.080236)
		(width 0.088646)
		(layer "In11.Cu")
		(net "M_D_CPU1_SA_DQS_DN<3>")
	)
	(arc
		(start 88.537796 -268.080236)
		(mid 88.255094 -268.00446)
		(end 87.972392 -268.080236)
		(width 0.088646)
		(layer "In11.Cu")
		(net "M_D_CPU1_SA_DQS_DN<3>")
	)
	(arc
		(start 96.985836 -268.07414)
		(mid 96.707404 -268.004294)
		(end 96.430592 -268.080236)
		(width 0.088646)
		(layer "In11.Cu")
		(net "M_D_CPU1_SA_DQS_DN<3>")
	)
	(arc
		(start 84.306156 -268.049248)
		(mid 84.140867 -268.144709)
		(end 84.075524 -268.324076)
		(width 0.088646)
		(layer "In11.Cu")
		(net "M_D_CPU1_SA_DQS_DN<3>")
	)
	(arc
		(start 89.477596 -268.080236)
		(mid 89.194894 -268.00446)
		(end 88.912192 -268.080236)
		(width 0.088646)
		(layer "In11.Cu")
		(net "M_D_CPU1_SA_DQS_DN<3>")
	)
	(arc
		(start 85.718396 -268.080236)
		(mid 85.458674 -268.00481)
		(end 85.193632 -268.058646)
		(width 0.088646)
		(layer "In11.Cu")
		(net "M_D_CPU1_SA_DQS_DN<3>")
	)
	(arc
		(start 91.731592 -268.080236)
		(mid 91.544394 -268.130379)
		(end 91.357196 -268.080236)
		(width 0.088646)
		(layer "In11.Cu")
		(net "M_D_CPU1_SA_DQS_DN<3>")
	)
	(arc
		(start 92.282264 -268.0716)
		(mid 92.005789 -268.00428)
		(end 91.731592 -268.080236)
		(width 0.088646)
		(layer "In11.Cu")
		(net "M_D_CPU1_SA_DQS_DN<3>")
	)
	(arc
		(start 93.611192 -268.080236)
		(mid 93.423994 -268.130379)
		(end 93.236796 -268.080236)
		(width 0.088646)
		(layer "In11.Cu")
		(net "M_D_CPU1_SA_DQS_DN<3>")
	)
	(arc
		(start 96.430592 -268.080236)
		(mid 96.243394 -268.130379)
		(end 96.056196 -268.080236)
		(width 0.088646)
		(layer "In11.Cu")
		(net "M_D_CPU1_SA_DQS_DN<3>")
	)
	(arc
		(start 90.792046 -268.080236)
		(mid 90.604848 -268.130379)
		(end 90.41765 -268.080236)
		(width 0.088646)
		(layer "In11.Cu")
		(net "M_D_CPU1_SA_DQS_DN<3>")
	)
	(arc
		(start 90.41765 -268.080236)
		(mid 90.140837 -268.004366)
		(end 89.862406 -268.07414)
		(width 0.088646)
		(layer "In11.Cu")
		(net "M_D_CPU1_SA_DQS_DN<3>")
	)
	(arc
		(start 96.041464 -268.0716)
		(mid 95.764989 -268.00428)
		(end 95.490792 -268.080236)
		(width 0.088646)
		(layer "In11.Cu")
		(net "M_D_CPU1_SA_DQS_DN<3>")
	)
	(arc
		(start 95.490792 -268.080236)
		(mid 95.303594 -268.130379)
		(end 95.116396 -268.080236)
		(width 0.088646)
		(layer "In11.Cu")
		(net "M_D_CPU1_SA_DQS_DN<3>")
	)
	(arc
		(start 86.658196 -268.080236)
		(mid 86.375494 -268.00446)
		(end 86.092792 -268.080236)
		(width 0.088646)
		(layer "In11.Cu")
		(net "M_D_CPU1_SA_DQS_DN<3>")
	)
	(arc
		(start 87.597996 -268.080236)
		(mid 87.315294 -268.00446)
		(end 87.032592 -268.080236)
		(width 0.088646)
		(layer "In11.Cu")
		(net "M_D_CPU1_SA_DQS_DN<3>")
	)
	(arc
		(start 89.851992 -268.080236)
		(mid 89.664794 -268.130379)
		(end 89.477596 -268.080236)
		(width 0.088646)
		(layer "In11.Cu")
		(net "M_D_CPU1_SA_DQS_DN<3>")
	)
	(arc
		(start 88.912192 -268.080236)
		(mid 88.724994 -268.130379)
		(end 88.537796 -268.080236)
		(width 0.088646)
		(layer "In11.Cu")
		(net "M_D_CPU1_SA_DQS_DN<3>")
	)
	(arc
		(start 95.116396 -268.080236)
		(mid 94.833694 -268.00446)
		(end 94.550992 -268.080236)
		(width 0.088646)
		(layer "In11.Cu")
		(net "M_D_CPU1_SA_DQS_DN<3>")
	)
	(arc
		(start 87.972392 -268.080236)
		(mid 87.785194 -268.130379)
		(end 87.597996 -268.080236)
		(width 0.088646)
		(layer "In11.Cu")
		(net "M_D_CPU1_SA_DQS_DN<3>")
	)
	(arc
		(start 87.032592 -268.080236)
		(mid 86.845394 -268.130379)
		(end 86.658196 -268.080236)
		(width 0.088646)
		(layer "In11.Cu")
		(net "M_D_CPU1_SA_DQS_DN<3>")
	)
	(arc
		(start 86.092792 -268.080236)
		(mid 85.905594 -268.130379)
		(end 85.718396 -268.080236)
		(width 0.088646)
		(layer "In11.Cu")
		(net "M_D_CPU1_SA_DQS_DN<3>")
	)
	(arc
		(start 98.052382 -267.8938)
		(mid 97.977697 -267.924305)
		(end 97.897696 -267.934694)
		(width 0.088646)
		(layer "In11.Cu")
		(net "M_D_CPU1_SA_DQS_DN<3>")
	)
	(arc
		(start 94.550992 -268.080236)
		(mid 94.363794 -268.130379)
		(end 94.176596 -268.080236)
		(width 0.088646)
		(layer "In11.Cu")
		(net "M_D_CPU1_SA_DQS_DN<3>")
	)
	(arc
		(start 92.671392 -268.080236)
		(mid 92.484194 -268.130379)
		(end 92.296996 -268.080236)
		(width 0.088646)
		(layer "In11.Cu")
		(net "M_D_CPU1_SA_DQS_DN<3>")
	)
	(arc
		(start 84.773516 -268.083792)
		(mid 84.541986 -268.037412)
		(end 84.306156 -268.049248)
		(width 0.088646)
		(layer "In11.Cu")
		(net "M_D_CPU1_SA_DQS_DN<3>")
	)
	(arc
		(start 97.370646 -268.080236)
		(mid 97.183448 -268.130379)
		(end 96.99625 -268.080236)
		(width 0.088646)
		(layer "In11.Cu")
		(net "M_D_CPU1_SA_DQS_DN<3>")
	)
	(segment
		(start 14.469872 -293.62781)
		(end 14.044676 -294.053006)
		(width 0.20066)
		(layer "F.Cu")
		(net "M_D_CPU1_SA_DQS_DN<2>")
	)
	(segment
		(start 10.64006 -294.053006)
		(end 10.100056 -294.053006)
		(width 0.20066)
		(layer "F.Cu")
		(net "M_D_CPU1_SA_DQS_DN<2>")
	)
	(segment
		(start 11.12774 -293.79164)
		(end 11.117072 -293.780972)
		(width 0.101854)
		(layer "F.Cu")
		(net "M_D_CPU1_SA_DQS_DN<2>")
	)
	(segment
		(start 15.684246 -293.366698)
		(end 16.789146 -293.366698)
		(width 0.20066)
		(layer "F.Cu")
		(net "M_D_CPU1_SA_DQS_DN<2>")
	)
	(segment
		(start 8.950198 -293.62781)
		(end 8.689086 -293.366698)
		(width 0.20066)
		(layer "F.Cu")
		(net "M_D_CPU1_SA_DQS_DN<2>")
	)
	(segment
		(start 13.441426 -293.79164)
		(end 11.12774 -293.79164)
		(width 0.1016)
		(layer "F.Cu")
		(net "M_D_CPU1_SA_DQS_DN<2>")
	)
	(segment
		(start 9.46404 -293.62781)
		(end 8.950198 -293.62781)
		(width 0.20066)
		(layer "F.Cu")
		(net "M_D_CPU1_SA_DQS_DN<2>")
	)
	(segment
		(start 15.684246 -293.366698)
		(end 15.137638 -293.366698)
		(width 0.20066)
		(layer "F.Cu")
		(net "M_D_CPU1_SA_DQS_DN<2>")
	)
	(segment
		(start 15.137638 -293.366698)
		(end 14.876526 -293.62781)
		(width 0.20066)
		(layer "F.Cu")
		(net "M_D_CPU1_SA_DQS_DN<2>")
	)
	(segment
		(start 10.912094 -293.780972)
		(end 10.64006 -294.053006)
		(width 0.20066)
		(layer "F.Cu")
		(net "M_D_CPU1_SA_DQS_DN<2>")
	)
	(segment
		(start 14.044676 -294.053006)
		(end 13.857986 -294.053006)
		(width 0.20066)
		(layer "F.Cu")
		(net "M_D_CPU1_SA_DQS_DN<2>")
	)
	(segment
		(start 13.59662 -293.79164)
		(end 13.441426 -293.79164)
		(width 0.20066)
		(layer "F.Cu")
		(net "M_D_CPU1_SA_DQS_DN<2>")
	)
	(segment
		(start 14.876526 -293.62781)
		(end 14.469872 -293.62781)
		(width 0.20066)
		(layer "F.Cu")
		(net "M_D_CPU1_SA_DQS_DN<2>")
	)
	(segment
		(start 8.689086 -293.366698)
		(end 8.140446 -293.366698)
		(width 0.20066)
		(layer "F.Cu")
		(net "M_D_CPU1_SA_DQS_DN<2>")
	)
	(segment
		(start 11.117072 -293.780972)
		(end 11.11631 -293.780972)
		(width 0.101854)
		(layer "F.Cu")
		(net "M_D_CPU1_SA_DQS_DN<2>")
	)
	(segment
		(start 10.100056 -294.053006)
		(end 9.46404 -293.62781)
		(width 0.20066)
		(layer "F.Cu")
		(net "M_D_CPU1_SA_DQS_DN<2>")
	)
	(segment
		(start 11.11631 -293.780972)
		(end 10.912094 -293.780972)
		(width 0.20066)
		(layer "F.Cu")
		(net "M_D_CPU1_SA_DQS_DN<2>")
	)
	(segment
		(start 13.857986 -294.053006)
		(end 13.59662 -293.79164)
		(width 0.20066)
		(layer "F.Cu")
		(net "M_D_CPU1_SA_DQS_DN<2>")
	)
	(arc
		(start 98.123248 -272.103342)
		(mid 98.123184 -272.371312)
		(end 98.122994 -272.639282)
		(width 0.20066)
		(layer "F.Cu")
		(net "M_D_CPU1_SA_DQS_DN<2>")
	)
	(segment
		(start 50.86477 -295.4909)
		(end 50.593498 -295.762172)
		(width 0.18288)
		(layer "In11.Cu")
		(net "M_D_CPU1_SA_DQS_DN<2>")
	)
	(segment
		(start 94.176596 -272.96364)
		(end 94.161864 -272.955004)
		(width 0.088646)
		(layer "In11.Cu")
		(net "M_D_CPU1_SA_DQS_DN<2>")
	)
	(segment
		(start 57.709308 -292.673278)
		(end 55.33898 -293.655496)
		(width 0.18288)
		(layer "In11.Cu")
		(net "M_D_CPU1_SA_DQS_DN<2>")
	)
	(segment
		(start 44.903136 -295.91762)
		(end 44.34967 -295.91762)
		(width 0.18288)
		(layer "In11.Cu")
		(net "M_D_CPU1_SA_DQS_DN<2>")
	)
	(segment
		(start 49.107852 -296.319448)
		(end 48.415448 -296.606214)
		(width 0.18288)
		(layer "In11.Cu")
		(net "M_D_CPU1_SA_DQS_DN<2>")
	)
	(segment
		(start 25.366218 -294.549068)
		(end 25.298654 -294.386254)
		(width 0.18288)
		(layer "In11.Cu")
		(net "M_D_CPU1_SA_DQS_DN<2>")
	)
	(segment
		(start 43.770804 -296.496486)
		(end 43.262296 -296.496486)
		(width 0.18288)
		(layer "In11.Cu")
		(net "M_D_CPU1_SA_DQS_DN<2>")
	)
	(segment
		(start 20.67179 -293.791132)
		(end 20.397216 -294.065706)
		(width 0.18288)
		(layer "In11.Cu")
		(net "M_D_CPU1_SA_DQS_DN<2>")
	)
	(segment
		(start 22.900386 -293.90975)
		(end 22.775926 -294.03421)
		(width 0.18288)
		(layer "In11.Cu")
		(net "M_D_CPU1_SA_DQS_DN<2>")
	)
	(segment
		(start 63.030354 -291.042344)
		(end 62.523624 -291.251894)
		(width 0.18288)
		(layer "In11.Cu")
		(net "M_D_CPU1_SA_DQS_DN<2>")
	)
	(segment
		(start 37.811964 -295.646094)
		(end 37.687504 -295.770554)
		(width 0.18288)
		(layer "In11.Cu")
		(net "M_D_CPU1_SA_DQS_DN<2>")
	)
	(segment
		(start 85.036152 -273.053302)
		(end 84.668868 -273.420586)
		(width 0.088646)
		(layer "In11.Cu")
		(net "M_D_CPU1_SA_DQS_DN<2>")
	)
	(segment
		(start 36.44392 -295.770554)
		(end 36.16579 -295.492424)
		(width 0.18288)
		(layer "In11.Cu")
		(net "M_D_CPU1_SA_DQS_DN<2>")
	)
	(segment
		(start 17.99209 -293.389304)
		(end 17.40408 -293.63289)
		(width 0.18288)
		(layer "In11.Cu")
		(net "M_D_CPU1_SA_DQS_DN<2>")
	)
	(segment
		(start 31.678626 -296.341038)
		(end 31.387288 -296.632376)
		(width 0.18288)
		(layer "In11.Cu")
		(net "M_D_CPU1_SA_DQS_DN<2>")
	)
	(segment
		(start 84.668868 -273.684492)
		(end 83.792314 -274.561046)
		(width 0.088646)
		(layer "In11.Cu")
		(net "M_D_CPU1_SA_DQS_DN<2>")
	)
	(segment
		(start 98.091244 -272.755106)
		(end 98.052382 -272.777204)
		(width 0.088646)
		(layer "In11.Cu")
		(net "M_D_CPU1_SA_DQS_DN<2>")
	)
	(segment
		(start 46.768766 -296.341038)
		(end 46.486318 -296.623486)
		(width 0.18288)
		(layer "In11.Cu")
		(net "M_D_CPU1_SA_DQS_DN<2>")
	)
	(segment
		(start 47.42053 -296.606214)
		(end 47.155354 -296.341038)
		(width 0.18288)
		(layer "In11.Cu")
		(net "M_D_CPU1_SA_DQS_DN<2>")
	)
	(segment
		(start 42.190416 -295.424606)
		(end 41.802558 -295.036748)
		(width 0.18288)
		(layer "In11.Cu")
		(net "M_D_CPU1_SA_DQS_DN<2>")
	)
	(segment
		(start 40.188134 -295.036748)
		(end 39.711884 -295.512744)
		(width 0.18288)
		(layer "In11.Cu")
		(net "M_D_CPU1_SA_DQS_DN<2>")
	)
	(segment
		(start 42.366438 -295.424606)
		(end 42.190416 -295.424606)
		(width 0.18288)
		(layer "In11.Cu")
		(net "M_D_CPU1_SA_DQS_DN<2>")
	)
	(segment
		(start 29.389324 -297.200574)
		(end 28.708858 -296.918888)
		(width 0.18288)
		(layer "In11.Cu")
		(net "M_D_CPU1_SA_DQS_DN<2>")
	)
	(segment
		(start 30.994858 -296.632376)
		(end 29.763212 -297.200574)
		(width 0.18288)
		(layer "In11.Cu")
		(net "M_D_CPU1_SA_DQS_DN<2>")
	)
	(segment
		(start 61.186568 -291.127434)
		(end 60.637928 -291.127434)
		(width 0.18288)
		(layer "In11.Cu")
		(net "M_D_CPU1_SA_DQS_DN<2>")
	)
	(segment
		(start 50.593498 -295.762172)
		(end 49.944274 -295.762172)
		(width 0.18288)
		(layer "In11.Cu")
		(net "M_D_CPU1_SA_DQS_DN<2>")
	)
	(segment
		(start 32.14751 -296.341038)
		(end 31.678626 -296.341038)
		(width 0.18288)
		(layer "In11.Cu")
		(net "M_D_CPU1_SA_DQS_DN<2>")
	)
	(segment
		(start 42.75455 -295.812718)
		(end 42.366438 -295.424606)
		(width 0.18288)
		(layer "In11.Cu")
		(net "M_D_CPU1_SA_DQS_DN<2>")
	)
	(segment
		(start 27.474164 -295.684194)
		(end 26.441146 -294.993822)
		(width 0.18288)
		(layer "In11.Cu")
		(net "M_D_CPU1_SA_DQS_DN<2>")
	)
	(segment
		(start 21.179282 -293.791132)
		(end 20.67179 -293.791132)
		(width 0.18288)
		(layer "In11.Cu")
		(net "M_D_CPU1_SA_DQS_DN<2>")
	)
	(segment
		(start 64.556894 -290.410646)
		(end 63.767716 -290.737036)
		(width 0.18288)
		(layer "In11.Cu")
		(net "M_D_CPU1_SA_DQS_DN<2>")
	)
	(segment
		(start 54.559962 -294.175942)
		(end 54.387242 -294.141652)
		(width 0.18288)
		(layer "In11.Cu")
		(net "M_D_CPU1_SA_DQS_DN<2>")
	)
	(segment
		(start 48.415448 -296.606214)
		(end 47.42053 -296.606214)
		(width 0.18288)
		(layer "In11.Cu")
		(net "M_D_CPU1_SA_DQS_DN<2>")
	)
	(segment
		(start 26.440384 -294.993568)
		(end 25.366218 -294.549068)
		(width 0.18288)
		(layer "In11.Cu")
		(net "M_D_CPU1_SA_DQS_DN<2>")
	)
	(segment
		(start 51.275234 -295.4909)
		(end 50.86477 -295.4909)
		(width 0.18288)
		(layer "In11.Cu")
		(net "M_D_CPU1_SA_DQS_DN<2>")
	)
	(segment
		(start 97.897696 -272.818098)
		(end 97.624138 -272.818098)
		(width 0.088646)
		(layer "In11.Cu")
		(net "M_D_CPU1_SA_DQS_DN<2>")
	)
	(segment
		(start 52.960524 -295.38803)
		(end 52.074064 -295.755314)
		(width 0.18288)
		(layer "In11.Cu")
		(net "M_D_CPU1_SA_DQS_DN<2>")
	)
	(segment
		(start 91.357196 -272.96364)
		(end 91.346782 -272.957544)
		(width 0.088646)
		(layer "In11.Cu")
		(net "M_D_CPU1_SA_DQS_DN<2>")
	)
	(segment
		(start 97.3709 -272.963894)
		(end 97.370646 -272.96364)
		(width 0.088646)
		(layer "In11.Cu")
		(net "M_D_CPU1_SA_DQS_DN<2>")
	)
	(segment
		(start 55.33898 -293.655496)
		(end 55.337456 -293.656258)
		(width 0.18288)
		(layer "In11.Cu")
		(net "M_D_CPU1_SA_DQS_DN<2>")
	)
	(segment
		(start 41.802558 -295.036748)
		(end 40.188134 -295.036748)
		(width 0.18288)
		(layer "In11.Cu")
		(net "M_D_CPU1_SA_DQS_DN<2>")
	)
	(segment
		(start 23.449026 -293.90975)
		(end 22.900386 -293.90975)
		(width 0.18288)
		(layer "In11.Cu")
		(net "M_D_CPU1_SA_DQS_DN<2>")
	)
	(segment
		(start 96.056196 -272.96364)
		(end 96.041464 -272.955004)
		(width 0.088646)
		(layer "In11.Cu")
		(net "M_D_CPU1_SA_DQS_DN<2>")
	)
	(segment
		(start 83.792314 -274.561046)
		(end 83.792314 -275.252942)
		(width 0.088646)
		(layer "In11.Cu")
		(net "M_D_CPU1_SA_DQS_DN<2>")
	)
	(segment
		(start 18.80489 -293.389304)
		(end 17.99209 -293.389304)
		(width 0.18288)
		(layer "In11.Cu")
		(net "M_D_CPU1_SA_DQS_DN<2>")
	)
	(segment
		(start 57.776618 -292.51021)
		(end 57.709308 -292.673278)
		(width 0.18288)
		(layer "In11.Cu")
		(net "M_D_CPU1_SA_DQS_DN<2>")
	)
	(segment
		(start 53.896514 -294.619172)
		(end 53.393086 -294.955722)
		(width 0.18288)
		(layer "In11.Cu")
		(net "M_D_CPU1_SA_DQS_DN<2>")
	)
	(segment
		(start 46.486318 -296.623486)
		(end 46.117002 -296.623486)
		(width 0.18288)
		(layer "In11.Cu")
		(net "M_D_CPU1_SA_DQS_DN<2>")
	)
	(segment
		(start 63.767716 -290.737036)
		(end 63.605156 -290.669726)
		(width 0.18288)
		(layer "In11.Cu")
		(net "M_D_CPU1_SA_DQS_DN<2>")
	)
	(segment
		(start 89.862406 -272.957544)
		(end 89.851992 -272.96364)
		(width 0.088646)
		(layer "In11.Cu")
		(net "M_D_CPU1_SA_DQS_DN<2>")
	)
	(segment
		(start 19.537934 -293.69258)
		(end 18.80489 -293.389304)
		(width 0.18288)
		(layer "In11.Cu")
		(net "M_D_CPU1_SA_DQS_DN<2>")
	)
	(segment
		(start 17.055338 -293.63289)
		(end 16.789146 -293.366698)
		(width 0.18288)
		(layer "In11.Cu")
		(net "M_D_CPU1_SA_DQS_DN<2>")
	)
	(segment
		(start 61.311028 -291.251894)
		(end 61.186568 -291.127434)
		(width 0.18288)
		(layer "In11.Cu")
		(net "M_D_CPU1_SA_DQS_DN<2>")
	)
	(segment
		(start 66.41338 -290.410646)
		(end 64.556894 -290.410646)
		(width 0.18288)
		(layer "In11.Cu")
		(net "M_D_CPU1_SA_DQS_DN<2>")
	)
	(segment
		(start 42.75455 -295.98874)
		(end 42.75455 -295.812718)
		(width 0.18288)
		(layer "In11.Cu")
		(net "M_D_CPU1_SA_DQS_DN<2>")
	)
	(segment
		(start 98.122994 -272.639282)
		(end 98.091244 -272.755106)
		(width 0.088646)
		(layer "In11.Cu")
		(net "M_D_CPU1_SA_DQS_DN<2>")
	)
	(segment
		(start 39.089838 -295.770554)
		(end 38.485064 -295.770554)
		(width 0.18288)
		(layer "In11.Cu")
		(net "M_D_CPU1_SA_DQS_DN<2>")
	)
	(segment
		(start 60.637928 -291.127434)
		(end 60.513468 -291.251894)
		(width 0.18288)
		(layer "In11.Cu")
		(net "M_D_CPU1_SA_DQS_DN<2>")
	)
	(segment
		(start 24.791416 -294.17645)
		(end 24.628856 -294.24376)
		(width 0.18288)
		(layer "In11.Cu")
		(net "M_D_CPU1_SA_DQS_DN<2>")
	)
	(segment
		(start 22.775926 -294.03421)
		(end 21.42236 -294.03421)
		(width 0.18288)
		(layer "In11.Cu")
		(net "M_D_CPU1_SA_DQS_DN<2>")
	)
	(segment
		(start 62.523624 -291.251894)
		(end 61.311028 -291.251894)
		(width 0.18288)
		(layer "In11.Cu")
		(net "M_D_CPU1_SA_DQS_DN<2>")
	)
	(segment
		(start 83.372198 -275.673058)
		(end 83.124548 -275.673058)
		(width 0.088646)
		(layer "In11.Cu")
		(net "M_D_CPU1_SA_DQS_DN<2>")
	)
	(segment
		(start 83.064858 -275.613368)
		(end 80.71358 -275.613368)
		(width 0.18288)
		(layer "In11.Cu")
		(net "M_D_CPU1_SA_DQS_DN<2>")
	)
	(segment
		(start 96.99625 -272.96364)
		(end 96.985836 -272.957544)
		(width 0.088646)
		(layer "In11.Cu")
		(net "M_D_CPU1_SA_DQS_DN<2>")
	)
	(segment
		(start 37.687504 -295.770554)
		(end 36.44392 -295.770554)
		(width 0.18288)
		(layer "In11.Cu")
		(net "M_D_CPU1_SA_DQS_DN<2>")
	)
	(segment
		(start 25.298654 -294.386254)
		(end 24.791416 -294.17645)
		(width 0.18288)
		(layer "In11.Cu")
		(net "M_D_CPU1_SA_DQS_DN<2>")
	)
	(segment
		(start 53.393086 -294.955722)
		(end 52.960524 -295.38803)
		(width 0.18288)
		(layer "In11.Cu")
		(net "M_D_CPU1_SA_DQS_DN<2>")
	)
	(segment
		(start 24.628856 -294.24376)
		(end 24.122126 -294.03421)
		(width 0.18288)
		(layer "In11.Cu")
		(net "M_D_CPU1_SA_DQS_DN<2>")
	)
	(segment
		(start 58.446416 -292.367462)
		(end 58.283856 -292.300152)
		(width 0.18288)
		(layer "In11.Cu")
		(net "M_D_CPU1_SA_DQS_DN<2>")
	)
	(segment
		(start 38.360604 -295.646094)
		(end 37.811964 -295.646094)
		(width 0.18288)
		(layer "In11.Cu")
		(net "M_D_CPU1_SA_DQS_DN<2>")
	)
	(segment
		(start 21.42236 -294.03421)
		(end 21.179282 -293.791132)
		(width 0.18288)
		(layer "In11.Cu")
		(net "M_D_CPU1_SA_DQS_DN<2>")
	)
	(segment
		(start 38.485064 -295.770554)
		(end 38.360604 -295.646094)
		(width 0.18288)
		(layer "In11.Cu")
		(net "M_D_CPU1_SA_DQS_DN<2>")
	)
	(segment
		(start 28.708858 -296.918888)
		(end 27.474164 -295.684194)
		(width 0.18288)
		(layer "In11.Cu")
		(net "M_D_CPU1_SA_DQS_DN<2>")
	)
	(segment
		(start 55.337456 -293.656258)
		(end 54.559962 -294.175942)
		(width 0.18288)
		(layer "In11.Cu")
		(net "M_D_CPU1_SA_DQS_DN<2>")
	)
	(segment
		(start 83.124548 -275.673058)
		(end 83.064858 -275.613368)
		(width 0.088646)
		(layer "In11.Cu")
		(net "M_D_CPU1_SA_DQS_DN<2>")
	)
	(segment
		(start 29.763212 -297.200574)
		(end 29.389324 -297.200574)
		(width 0.18288)
		(layer "In11.Cu")
		(net "M_D_CPU1_SA_DQS_DN<2>")
	)
	(segment
		(start 46.117002 -296.623486)
		(end 45.771308 -296.277792)
		(width 0.18288)
		(layer "In11.Cu")
		(net "M_D_CPU1_SA_DQS_DN<2>")
	)
	(segment
		(start 17.40408 -293.63289)
		(end 17.055338 -293.63289)
		(width 0.18288)
		(layer "In11.Cu")
		(net "M_D_CPU1_SA_DQS_DN<2>")
	)
	(segment
		(start 63.097918 -290.87953)
		(end 63.030354 -291.042344)
		(width 0.18288)
		(layer "In11.Cu")
		(net "M_D_CPU1_SA_DQS_DN<2>")
	)
	(segment
		(start 35.281108 -295.772332)
		(end 33.316164 -296.586402)
		(width 0.18288)
		(layer "In11.Cu")
		(net "M_D_CPU1_SA_DQS_DN<2>")
	)
	(segment
		(start 80.71358 -275.613368)
		(end 66.694304 -289.632644)
		(width 0.18288)
		(layer "In11.Cu")
		(net "M_D_CPU1_SA_DQS_DN<2>")
	)
	(segment
		(start 43.262296 -296.496486)
		(end 42.75455 -295.98874)
		(width 0.18288)
		(layer "In11.Cu")
		(net "M_D_CPU1_SA_DQS_DN<2>")
	)
	(segment
		(start 47.155354 -296.341038)
		(end 46.768766 -296.341038)
		(width 0.18288)
		(layer "In11.Cu")
		(net "M_D_CPU1_SA_DQS_DN<2>")
	)
	(segment
		(start 87.982806 -272.957544)
		(end 87.972392 -272.96364)
		(width 0.088646)
		(layer "In11.Cu")
		(net "M_D_CPU1_SA_DQS_DN<2>")
	)
	(segment
		(start 49.46777 -295.959784)
		(end 49.107852 -296.319448)
		(width 0.18288)
		(layer "In11.Cu")
		(net "M_D_CPU1_SA_DQS_DN<2>")
	)
	(segment
		(start 63.605156 -290.669726)
		(end 63.097918 -290.87953)
		(width 0.18288)
		(layer "In11.Cu")
		(net "M_D_CPU1_SA_DQS_DN<2>")
	)
	(segment
		(start 66.694304 -289.632644)
		(end 66.694304 -290.129722)
		(width 0.18288)
		(layer "In11.Cu")
		(net "M_D_CPU1_SA_DQS_DN<2>")
	)
	(segment
		(start 66.694304 -290.129722)
		(end 66.41338 -290.410646)
		(width 0.18288)
		(layer "In11.Cu")
		(net "M_D_CPU1_SA_DQS_DN<2>")
	)
	(segment
		(start 31.387288 -296.632376)
		(end 30.994858 -296.632376)
		(width 0.18288)
		(layer "In11.Cu")
		(net "M_D_CPU1_SA_DQS_DN<2>")
	)
	(segment
		(start 35.78479 -295.492424)
		(end 35.504882 -295.772332)
		(width 0.18288)
		(layer "In11.Cu")
		(net "M_D_CPU1_SA_DQS_DN<2>")
	)
	(segment
		(start 36.16579 -295.492424)
		(end 35.78479 -295.492424)
		(width 0.18288)
		(layer "In11.Cu")
		(net "M_D_CPU1_SA_DQS_DN<2>")
	)
	(segment
		(start 32.392874 -296.586402)
		(end 32.14751 -296.341038)
		(width 0.18288)
		(layer "In11.Cu")
		(net "M_D_CPU1_SA_DQS_DN<2>")
	)
	(segment
		(start 60.513468 -291.251894)
		(end 59.859164 -291.251894)
		(width 0.18288)
		(layer "In11.Cu")
		(net "M_D_CPU1_SA_DQS_DN<2>")
	)
	(segment
		(start 52.074064 -295.755314)
		(end 51.539648 -295.755314)
		(width 0.18288)
		(layer "In11.Cu")
		(net "M_D_CPU1_SA_DQS_DN<2>")
	)
	(segment
		(start 35.504882 -295.772332)
		(end 35.281108 -295.772332)
		(width 0.18288)
		(layer "In11.Cu")
		(net "M_D_CPU1_SA_DQS_DN<2>")
	)
	(segment
		(start 85.718396 -272.96364)
		(end 85.707982 -272.957544)
		(width 0.088646)
		(layer "In11.Cu")
		(net "M_D_CPU1_SA_DQS_DN<2>")
	)
	(segment
		(start 59.859164 -291.251894)
		(end 58.953654 -292.15715)
		(width 0.18288)
		(layer "In11.Cu")
		(net "M_D_CPU1_SA_DQS_DN<2>")
	)
	(segment
		(start 58.953654 -292.15715)
		(end 58.953146 -292.157658)
		(width 0.18288)
		(layer "In11.Cu")
		(net "M_D_CPU1_SA_DQS_DN<2>")
	)
	(segment
		(start 87.04326 -272.957544)
		(end 87.032846 -272.96364)
		(width 0.088646)
		(layer "In11.Cu")
		(net "M_D_CPU1_SA_DQS_DN<2>")
	)
	(segment
		(start 39.711884 -295.512744)
		(end 39.089838 -295.770554)
		(width 0.18288)
		(layer "In11.Cu")
		(net "M_D_CPU1_SA_DQS_DN<2>")
	)
	(segment
		(start 53.930804 -294.446706)
		(end 53.896514 -294.619172)
		(width 0.18288)
		(layer "In11.Cu")
		(net "M_D_CPU1_SA_DQS_DN<2>")
	)
	(segment
		(start 86.65845 -272.96364)
		(end 86.648036 -272.957544)
		(width 0.088646)
		(layer "In11.Cu")
		(net "M_D_CPU1_SA_DQS_DN<2>")
	)
	(segment
		(start 88.92286 -272.957544)
		(end 88.912446 -272.96364)
		(width 0.088646)
		(layer "In11.Cu")
		(net "M_D_CPU1_SA_DQS_DN<2>")
	)
	(segment
		(start 20.397216 -294.065706)
		(end 19.91106 -294.065706)
		(width 0.18288)
		(layer "In11.Cu")
		(net "M_D_CPU1_SA_DQS_DN<2>")
	)
	(segment
		(start 92.296996 -272.96364)
		(end 92.282264 -272.955004)
		(width 0.088646)
		(layer "In11.Cu")
		(net "M_D_CPU1_SA_DQS_DN<2>")
	)
	(segment
		(start 24.122126 -294.03421)
		(end 23.573486 -294.03421)
		(width 0.18288)
		(layer "In11.Cu")
		(net "M_D_CPU1_SA_DQS_DN<2>")
	)
	(segment
		(start 19.91106 -294.065706)
		(end 19.537934 -293.69258)
		(width 0.18288)
		(layer "In11.Cu")
		(net "M_D_CPU1_SA_DQS_DN<2>")
	)
	(segment
		(start 23.573486 -294.03421)
		(end 23.449026 -293.90975)
		(width 0.18288)
		(layer "In11.Cu")
		(net "M_D_CPU1_SA_DQS_DN<2>")
	)
	(segment
		(start 49.944274 -295.762172)
		(end 49.46777 -295.959784)
		(width 0.18288)
		(layer "In11.Cu")
		(net "M_D_CPU1_SA_DQS_DN<2>")
	)
	(segment
		(start 85.036406 -273.052794)
		(end 85.036152 -273.053302)
		(width 0.088646)
		(layer "In11.Cu")
		(net "M_D_CPU1_SA_DQS_DN<2>")
	)
	(segment
		(start 44.34967 -295.91762)
		(end 43.770804 -296.496486)
		(width 0.18288)
		(layer "In11.Cu")
		(net "M_D_CPU1_SA_DQS_DN<2>")
	)
	(segment
		(start 84.668868 -273.420586)
		(end 84.668868 -273.684492)
		(width 0.088646)
		(layer "In11.Cu")
		(net "M_D_CPU1_SA_DQS_DN<2>")
	)
	(segment
		(start 45.771308 -296.277792)
		(end 44.903136 -295.91762)
		(width 0.18288)
		(layer "In11.Cu")
		(net "M_D_CPU1_SA_DQS_DN<2>")
	)
	(segment
		(start 58.953146 -292.157658)
		(end 58.446416 -292.367462)
		(width 0.18288)
		(layer "In11.Cu")
		(net "M_D_CPU1_SA_DQS_DN<2>")
	)
	(segment
		(start 97.624138 -272.818098)
		(end 97.3709 -272.963894)
		(width 0.088646)
		(layer "In11.Cu")
		(net "M_D_CPU1_SA_DQS_DN<2>")
	)
	(segment
		(start 33.316164 -296.586402)
		(end 32.392874 -296.586402)
		(width 0.18288)
		(layer "In11.Cu")
		(net "M_D_CPU1_SA_DQS_DN<2>")
	)
	(segment
		(start 83.792314 -275.252942)
		(end 83.372198 -275.673058)
		(width 0.088646)
		(layer "In11.Cu")
		(net "M_D_CPU1_SA_DQS_DN<2>")
	)
	(segment
		(start 54.387242 -294.141652)
		(end 53.930804 -294.446706)
		(width 0.18288)
		(layer "In11.Cu")
		(net "M_D_CPU1_SA_DQS_DN<2>")
	)
	(segment
		(start 26.441146 -294.993822)
		(end 26.440384 -294.993568)
		(width 0.18288)
		(layer "In11.Cu")
		(net "M_D_CPU1_SA_DQS_DN<2>")
	)
	(segment
		(start 58.283856 -292.300152)
		(end 57.776618 -292.51021)
		(width 0.18288)
		(layer "In11.Cu")
		(net "M_D_CPU1_SA_DQS_DN<2>")
	)
	(segment
		(start 93.236796 -272.96364)
		(end 93.222064 -272.955004)
		(width 0.088646)
		(layer "In11.Cu")
		(net "M_D_CPU1_SA_DQS_DN<2>")
	)
	(segment
		(start 51.539648 -295.755314)
		(end 51.275234 -295.4909)
		(width 0.18288)
		(layer "In11.Cu")
		(net "M_D_CPU1_SA_DQS_DN<2>")
	)
	(arc
		(start 85.06968 -273.022314)
		(mid 85.052735 -273.037218)
		(end 85.036406 -273.052794)
		(width 0.088646)
		(layer "In11.Cu")
		(net "M_D_CPU1_SA_DQS_DN<2>")
	)
	(arc
		(start 90.792046 -272.96364)
		(mid 90.604848 -273.013783)
		(end 90.41765 -272.96364)
		(width 0.088646)
		(layer "In11.Cu")
		(net "M_D_CPU1_SA_DQS_DN<2>")
	)
	(arc
		(start 91.346782 -272.957544)
		(mid 91.068604 -272.887821)
		(end 90.792046 -272.96364)
		(width 0.088646)
		(layer "In11.Cu")
		(net "M_D_CPU1_SA_DQS_DN<2>")
	)
	(arc
		(start 90.41765 -272.96364)
		(mid 90.140837 -272.88777)
		(end 89.862406 -272.957544)
		(width 0.088646)
		(layer "In11.Cu")
		(net "M_D_CPU1_SA_DQS_DN<2>")
	)
	(arc
		(start 98.052382 -272.777204)
		(mid 97.977697 -272.807709)
		(end 97.897696 -272.818098)
		(width 0.088646)
		(layer "In11.Cu")
		(net "M_D_CPU1_SA_DQS_DN<2>")
	)
	(arc
		(start 92.282264 -272.955004)
		(mid 92.005789 -272.887684)
		(end 91.731592 -272.96364)
		(width 0.088646)
		(layer "In11.Cu")
		(net "M_D_CPU1_SA_DQS_DN<2>")
	)
	(arc
		(start 92.671392 -272.96364)
		(mid 92.484194 -273.013783)
		(end 92.296996 -272.96364)
		(width 0.088646)
		(layer "In11.Cu")
		(net "M_D_CPU1_SA_DQS_DN<2>")
	)
	(arc
		(start 94.550992 -272.96364)
		(mid 94.363794 -273.013783)
		(end 94.176596 -272.96364)
		(width 0.088646)
		(layer "In11.Cu")
		(net "M_D_CPU1_SA_DQS_DN<2>")
	)
	(arc
		(start 95.490792 -272.96364)
		(mid 95.303594 -273.013783)
		(end 95.116396 -272.96364)
		(width 0.088646)
		(layer "In11.Cu")
		(net "M_D_CPU1_SA_DQS_DN<2>")
	)
	(arc
		(start 89.851992 -272.96364)
		(mid 89.664794 -273.013783)
		(end 89.477596 -272.96364)
		(width 0.088646)
		(layer "In11.Cu")
		(net "M_D_CPU1_SA_DQS_DN<2>")
	)
	(arc
		(start 96.985836 -272.957544)
		(mid 96.707404 -272.887698)
		(end 96.430592 -272.96364)
		(width 0.088646)
		(layer "In11.Cu")
		(net "M_D_CPU1_SA_DQS_DN<2>")
	)
	(arc
		(start 93.222064 -272.955004)
		(mid 92.945589 -272.887684)
		(end 92.671392 -272.96364)
		(width 0.088646)
		(layer "In11.Cu")
		(net "M_D_CPU1_SA_DQS_DN<2>")
	)
	(arc
		(start 95.116396 -272.96364)
		(mid 94.833694 -272.887864)
		(end 94.550992 -272.96364)
		(width 0.088646)
		(layer "In11.Cu")
		(net "M_D_CPU1_SA_DQS_DN<2>")
	)
	(arc
		(start 87.032846 -272.96364)
		(mid 86.845648 -273.013783)
		(end 86.65845 -272.96364)
		(width 0.088646)
		(layer "In11.Cu")
		(net "M_D_CPU1_SA_DQS_DN<2>")
	)
	(arc
		(start 87.597996 -272.96364)
		(mid 87.321437 -272.887897)
		(end 87.04326 -272.957544)
		(width 0.088646)
		(layer "In11.Cu")
		(net "M_D_CPU1_SA_DQS_DN<2>")
	)
	(arc
		(start 88.912446 -272.96364)
		(mid 88.725248 -273.013783)
		(end 88.53805 -272.96364)
		(width 0.088646)
		(layer "In11.Cu")
		(net "M_D_CPU1_SA_DQS_DN<2>")
	)
	(arc
		(start 85.153246 -272.96364)
		(mid 85.11013 -272.991079)
		(end 85.06968 -273.022314)
		(width 0.088646)
		(layer "In11.Cu")
		(net "M_D_CPU1_SA_DQS_DN<2>")
	)
	(arc
		(start 91.731592 -272.96364)
		(mid 91.544394 -273.013783)
		(end 91.357196 -272.96364)
		(width 0.088646)
		(layer "In11.Cu")
		(net "M_D_CPU1_SA_DQS_DN<2>")
	)
	(arc
		(start 85.707982 -272.957544)
		(mid 85.429804 -272.887821)
		(end 85.153246 -272.96364)
		(width 0.088646)
		(layer "In11.Cu")
		(net "M_D_CPU1_SA_DQS_DN<2>")
	)
	(arc
		(start 89.477596 -272.96364)
		(mid 89.201037 -272.887897)
		(end 88.92286 -272.957544)
		(width 0.088646)
		(layer "In11.Cu")
		(net "M_D_CPU1_SA_DQS_DN<2>")
	)
	(arc
		(start 88.53805 -272.96364)
		(mid 88.261237 -272.88777)
		(end 87.982806 -272.957544)
		(width 0.088646)
		(layer "In11.Cu")
		(net "M_D_CPU1_SA_DQS_DN<2>")
	)
	(arc
		(start 96.041464 -272.955004)
		(mid 95.764989 -272.887684)
		(end 95.490792 -272.96364)
		(width 0.088646)
		(layer "In11.Cu")
		(net "M_D_CPU1_SA_DQS_DN<2>")
	)
	(arc
		(start 87.972392 -272.96364)
		(mid 87.785194 -273.013783)
		(end 87.597996 -272.96364)
		(width 0.088646)
		(layer "In11.Cu")
		(net "M_D_CPU1_SA_DQS_DN<2>")
	)
	(arc
		(start 96.430592 -272.96364)
		(mid 96.243394 -273.013783)
		(end 96.056196 -272.96364)
		(width 0.088646)
		(layer "In11.Cu")
		(net "M_D_CPU1_SA_DQS_DN<2>")
	)
	(arc
		(start 86.092792 -272.96364)
		(mid 85.905594 -273.013783)
		(end 85.718396 -272.96364)
		(width 0.088646)
		(layer "In11.Cu")
		(net "M_D_CPU1_SA_DQS_DN<2>")
	)
	(arc
		(start 94.161864 -272.955004)
		(mid 93.885389 -272.887684)
		(end 93.611192 -272.96364)
		(width 0.088646)
		(layer "In11.Cu")
		(net "M_D_CPU1_SA_DQS_DN<2>")
	)
	(arc
		(start 93.611192 -272.96364)
		(mid 93.423994 -273.013783)
		(end 93.236796 -272.96364)
		(width 0.088646)
		(layer "In11.Cu")
		(net "M_D_CPU1_SA_DQS_DN<2>")
	)
	(arc
		(start 97.370646 -272.96364)
		(mid 97.183448 -273.013783)
		(end 96.99625 -272.96364)
		(width 0.088646)
		(layer "In11.Cu")
		(net "M_D_CPU1_SA_DQS_DN<2>")
	)
	(arc
		(start 86.648036 -272.957544)
		(mid 86.369604 -272.887698)
		(end 86.092792 -272.96364)
		(width 0.088646)
		(layer "In11.Cu")
		(net "M_D_CPU1_SA_DQS_DN<2>")
	)
	(segment
		(start 8.689086 -302.716692)
		(end 8.140446 -302.716692)
		(width 0.20066)
		(layer "F.Cu")
		(net "M_D_CPU1_SA_DQS_DN<1>")
	)
	(segment
		(start 13.59662 -303.141634)
		(end 13.441426 -303.141634)
		(width 0.20066)
		(layer "F.Cu")
		(net "M_D_CPU1_SA_DQS_DN<1>")
	)
	(segment
		(start 10.912094 -303.130966)
		(end 10.64006 -303.403)
		(width 0.20066)
		(layer "F.Cu")
		(net "M_D_CPU1_SA_DQS_DN<1>")
	)
	(segment
		(start 14.876526 -302.977804)
		(end 14.469872 -302.977804)
		(width 0.20066)
		(layer "F.Cu")
		(net "M_D_CPU1_SA_DQS_DN<1>")
	)
	(segment
		(start 14.469872 -302.977804)
		(end 14.044676 -303.403)
		(width 0.20066)
		(layer "F.Cu")
		(net "M_D_CPU1_SA_DQS_DN<1>")
	)
	(segment
		(start 9.46404 -302.977804)
		(end 8.950198 -302.977804)
		(width 0.20066)
		(layer "F.Cu")
		(net "M_D_CPU1_SA_DQS_DN<1>")
	)
	(segment
		(start 15.684246 -302.716692)
		(end 15.137638 -302.716692)
		(width 0.20066)
		(layer "F.Cu")
		(net "M_D_CPU1_SA_DQS_DN<1>")
	)
	(segment
		(start 15.684246 -302.716692)
		(end 16.789146 -302.716692)
		(width 0.20066)
		(layer "F.Cu")
		(net "M_D_CPU1_SA_DQS_DN<1>")
	)
	(segment
		(start 11.12774 -303.141634)
		(end 11.117072 -303.130966)
		(width 0.101854)
		(layer "F.Cu")
		(net "M_D_CPU1_SA_DQS_DN<1>")
	)
	(segment
		(start 14.044676 -303.403)
		(end 13.857986 -303.403)
		(width 0.20066)
		(layer "F.Cu")
		(net "M_D_CPU1_SA_DQS_DN<1>")
	)
	(segment
		(start 13.441426 -303.141634)
		(end 11.12774 -303.141634)
		(width 0.1016)
		(layer "F.Cu")
		(net "M_D_CPU1_SA_DQS_DN<1>")
	)
	(segment
		(start 11.117072 -303.130966)
		(end 11.11631 -303.130966)
		(width 0.101854)
		(layer "F.Cu")
		(net "M_D_CPU1_SA_DQS_DN<1>")
	)
	(segment
		(start 11.11631 -303.130966)
		(end 10.912094 -303.130966)
		(width 0.20066)
		(layer "F.Cu")
		(net "M_D_CPU1_SA_DQS_DN<1>")
	)
	(segment
		(start 13.857986 -303.403)
		(end 13.59662 -303.141634)
		(width 0.20066)
		(layer "F.Cu")
		(net "M_D_CPU1_SA_DQS_DN<1>")
	)
	(segment
		(start 15.137638 -302.716692)
		(end 14.876526 -302.977804)
		(width 0.20066)
		(layer "F.Cu")
		(net "M_D_CPU1_SA_DQS_DN<1>")
	)
	(segment
		(start 10.64006 -303.403)
		(end 10.100056 -303.403)
		(width 0.20066)
		(layer "F.Cu")
		(net "M_D_CPU1_SA_DQS_DN<1>")
	)
	(segment
		(start 10.100056 -303.403)
		(end 9.46404 -302.977804)
		(width 0.20066)
		(layer "F.Cu")
		(net "M_D_CPU1_SA_DQS_DN<1>")
	)
	(segment
		(start 8.950198 -302.977804)
		(end 8.689086 -302.716692)
		(width 0.20066)
		(layer "F.Cu")
		(net "M_D_CPU1_SA_DQS_DN<1>")
	)
	(arc
		(start 98.123248 -276.986492)
		(mid 98.123184 -277.254462)
		(end 98.122994 -277.522432)
		(width 0.20066)
		(layer "F.Cu")
		(net "M_D_CPU1_SA_DQS_DN<1>")
	)
	(segment
		(start 22.122638 -303.478692)
		(end 21.864574 -303.40046)
		(width 0.18288)
		(layer "In11.Cu")
		(net "M_D_CPU1_SA_DQS_DN<1>")
	)
	(segment
		(start 62.606682 -301.724822)
		(end 62.32271 -301.44085)
		(width 0.18288)
		(layer "In11.Cu")
		(net "M_D_CPU1_SA_DQS_DN<1>")
	)
	(segment
		(start 65.671446 -300.849792)
		(end 65.15989 -300.849792)
		(width 0.18288)
		(layer "In11.Cu")
		(net "M_D_CPU1_SA_DQS_DN<1>")
	)
	(segment
		(start 47.446184 -309.363618)
		(end 47.173642 -309.091076)
		(width 0.18288)
		(layer "In11.Cu")
		(net "M_D_CPU1_SA_DQS_DN<1>")
	)
	(segment
		(start 45.84827 -309.101236)
		(end 45.055028 -308.772814)
		(width 0.18288)
		(layer "In11.Cu")
		(net "M_D_CPU1_SA_DQS_DN<1>")
	)
	(segment
		(start 67.025266 -300.832012)
		(end 66.644266 -300.832012)
		(width 0.18288)
		(layer "In11.Cu")
		(net "M_D_CPU1_SA_DQS_DN<1>")
	)
	(segment
		(start 45.055028 -308.772814)
		(end 44.480988 -308.772814)
		(width 0.18288)
		(layer "In11.Cu")
		(net "M_D_CPU1_SA_DQS_DN<1>")
	)
	(segment
		(start 23.67661 -304.367438)
		(end 23.220172 -304.062384)
		(width 0.18288)
		(layer "In11.Cu")
		(net "M_D_CPU1_SA_DQS_DN<1>")
	)
	(segment
		(start 98.091244 -277.638256)
		(end 98.052382 -277.660354)
		(width 0.088646)
		(layer "In11.Cu")
		(net "M_D_CPU1_SA_DQS_DN<1>")
	)
	(segment
		(start 57.178956 -304.412142)
		(end 57.24652 -304.574702)
		(width 0.18288)
		(layer "In11.Cu")
		(net "M_D_CPU1_SA_DQS_DN<1>")
	)
	(segment
		(start 84.220304 -281.576526)
		(end 84.135976 -281.576526)
		(width 0.088646)
		(layer "In11.Cu")
		(net "M_D_CPU1_SA_DQS_DN<1>")
	)
	(segment
		(start 50.871374 -308.240938)
		(end 50.59934 -308.512972)
		(width 0.18288)
		(layer "In11.Cu")
		(net "M_D_CPU1_SA_DQS_DN<1>")
	)
	(segment
		(start 24.193754 -304.862738)
		(end 23.7109 -304.540158)
		(width 0.18288)
		(layer "In11.Cu")
		(net "M_D_CPU1_SA_DQS_DN<1>")
	)
	(segment
		(start 31.682182 -309.091076)
		(end 31.402528 -309.37073)
		(width 0.18288)
		(layer "In11.Cu")
		(net "M_D_CPU1_SA_DQS_DN<1>")
	)
	(segment
		(start 27.045412 -307.38445)
		(end 27.045412 -306.852828)
		(width 0.18288)
		(layer "In11.Cu")
		(net "M_D_CPU1_SA_DQS_DN<1>")
	)
	(segment
		(start 57.552082 -303.837848)
		(end 57.389014 -303.905158)
		(width 0.18288)
		(layer "In11.Cu")
		(net "M_D_CPU1_SA_DQS_DN<1>")
	)
	(segment
		(start 37.149532 -308.393084)
		(end 37.025072 -308.517544)
		(width 0.18288)
		(layer "In11.Cu")
		(net "M_D_CPU1_SA_DQS_DN<1>")
	)
	(segment
		(start 86.362794 -278.832056)
		(end 86.159086 -278.832056)
		(width 0.088646)
		(layer "In11.Cu")
		(net "M_D_CPU1_SA_DQS_DN<1>")
	)
	(segment
		(start 30.314646 -309.813706)
		(end 29.983684 -309.950866)
		(width 0.18288)
		(layer "In11.Cu")
		(net "M_D_CPU1_SA_DQS_DN<1>")
	)
	(segment
		(start 54.941978 -306.554124)
		(end 54.874668 -306.716938)
		(width 0.18288)
		(layer "In11.Cu")
		(net "M_D_CPU1_SA_DQS_DN<1>")
	)
	(segment
		(start 27.548586 -308.59857)
		(end 27.045412 -307.38445)
		(width 0.18288)
		(layer "In11.Cu")
		(net "M_D_CPU1_SA_DQS_DN<1>")
	)
	(segment
		(start 38.371272 -308.517544)
		(end 37.822632 -308.517544)
		(width 0.18288)
		(layer "In11.Cu")
		(net "M_D_CPU1_SA_DQS_DN<1>")
	)
	(segment
		(start 55.611776 -306.411376)
		(end 55.449216 -306.344066)
		(width 0.18288)
		(layer "In11.Cu")
		(net "M_D_CPU1_SA_DQS_DN<1>")
	)
	(segment
		(start 19.548348 -303.69764)
		(end 18.798286 -304.008536)
		(width 0.18288)
		(layer "In11.Cu")
		(net "M_D_CPU1_SA_DQS_DN<1>")
	)
	(segment
		(start 46.467268 -309.38851)
		(end 46.135798 -309.38851)
		(width 0.18288)
		(layer "In11.Cu")
		(net "M_D_CPU1_SA_DQS_DN<1>")
	)
	(segment
		(start 51.53914 -308.521608)
		(end 51.25847 -308.240938)
		(width 0.18288)
		(layer "In11.Cu")
		(net "M_D_CPU1_SA_DQS_DN<1>")
	)
	(segment
		(start 44.480988 -308.772814)
		(end 44.012866 -308.966616)
		(width 0.18288)
		(layer "In11.Cu")
		(net "M_D_CPU1_SA_DQS_DN<1>")
	)
	(segment
		(start 52.230528 -308.521608)
		(end 51.53914 -308.521608)
		(width 0.18288)
		(layer "In11.Cu")
		(net "M_D_CPU1_SA_DQS_DN<1>")
	)
	(segment
		(start 97.624138 -277.701248)
		(end 97.3709 -277.847044)
		(width 0.088646)
		(layer "In11.Cu")
		(net "M_D_CPU1_SA_DQS_DN<1>")
	)
	(segment
		(start 66.644266 -300.832012)
		(end 66.406522 -300.594268)
		(width 0.18288)
		(layer "In11.Cu")
		(net "M_D_CPU1_SA_DQS_DN<1>")
	)
	(segment
		(start 35.324796 -308.492652)
		(end 33.212024 -309.367682)
		(width 0.18288)
		(layer "In11.Cu")
		(net "M_D_CPU1_SA_DQS_DN<1>")
	)
	(segment
		(start 68.509134 -299.172122)
		(end 68.121022 -299.560234)
		(width 0.18288)
		(layer "In11.Cu")
		(net "M_D_CPU1_SA_DQS_DN<1>")
	)
	(segment
		(start 57.389014 -303.905158)
		(end 57.178956 -304.412142)
		(width 0.18288)
		(layer "In11.Cu")
		(net "M_D_CPU1_SA_DQS_DN<1>")
	)
	(segment
		(start 50.59934 -308.512972)
		(end 50.48123 -308.512972)
		(width 0.18288)
		(layer "In11.Cu")
		(net "M_D_CPU1_SA_DQS_DN<1>")
	)
	(segment
		(start 69.101716 -298.755562)
		(end 68.685156 -299.172122)
		(width 0.18288)
		(layer "In11.Cu")
		(net "M_D_CPU1_SA_DQS_DN<1>")
	)
	(segment
		(start 41.371774 -309.202836)
		(end 39.717472 -308.517544)
		(width 0.18288)
		(layer "In11.Cu")
		(net "M_D_CPU1_SA_DQS_DN<1>")
	)
	(segment
		(start 63.588646 -301.724822)
		(end 62.606682 -301.724822)
		(width 0.18288)
		(layer "In11.Cu")
		(net "M_D_CPU1_SA_DQS_DN<1>")
	)
	(segment
		(start 19.87169 -303.374552)
		(end 19.548348 -303.69764)
		(width 0.18288)
		(layer "In11.Cu")
		(net "M_D_CPU1_SA_DQS_DN<1>")
	)
	(segment
		(start 41.965372 -309.202836)
		(end 41.371774 -309.202836)
		(width 0.18288)
		(layer "In11.Cu")
		(net "M_D_CPU1_SA_DQS_DN<1>")
	)
	(segment
		(start 39.168832 -308.517544)
		(end 39.044372 -308.393084)
		(width 0.18288)
		(layer "In11.Cu")
		(net "M_D_CPU1_SA_DQS_DN<1>")
	)
	(segment
		(start 42.638472 -309.078376)
		(end 42.089832 -309.078376)
		(width 0.18288)
		(layer "In11.Cu")
		(net "M_D_CPU1_SA_DQS_DN<1>")
	)
	(segment
		(start 20.668742 -303.142904)
		(end 20.437094 -303.374552)
		(width 0.18288)
		(layer "In11.Cu")
		(net "M_D_CPU1_SA_DQS_DN<1>")
	)
	(segment
		(start 61.558424 -301.753524)
		(end 60.72632 -301.753524)
		(width 0.18288)
		(layer "In11.Cu")
		(net "M_D_CPU1_SA_DQS_DN<1>")
	)
	(segment
		(start 51.25847 -308.240938)
		(end 50.871374 -308.240938)
		(width 0.18288)
		(layer "In11.Cu")
		(net "M_D_CPU1_SA_DQS_DN<1>")
	)
	(segment
		(start 84.135976 -281.576526)
		(end 83.68792 -282.024582)
		(width 0.18288)
		(layer "In11.Cu")
		(net "M_D_CPU1_SA_DQS_DN<1>")
	)
	(segment
		(start 98.122994 -277.522432)
		(end 98.091244 -277.638256)
		(width 0.088646)
		(layer "In11.Cu")
		(net "M_D_CPU1_SA_DQS_DN<1>")
	)
	(segment
		(start 30.757622 -309.37073)
		(end 30.314646 -309.813706)
		(width 0.18288)
		(layer "In11.Cu")
		(net "M_D_CPU1_SA_DQS_DN<1>")
	)
	(segment
		(start 17.048734 -302.97628)
		(end 16.789146 -302.716692)
		(width 0.18288)
		(layer "In11.Cu")
		(net "M_D_CPU1_SA_DQS_DN<1>")
	)
	(segment
		(start 29.983684 -309.950866)
		(end 29.539692 -309.950866)
		(width 0.18288)
		(layer "In11.Cu")
		(net "M_D_CPU1_SA_DQS_DN<1>")
	)
	(segment
		(start 31.402528 -309.37073)
		(end 30.757622 -309.37073)
		(width 0.18288)
		(layer "In11.Cu")
		(net "M_D_CPU1_SA_DQS_DN<1>")
	)
	(segment
		(start 90.80246 -277.840694)
		(end 90.792046 -277.84679)
		(width 0.088646)
		(layer "In11.Cu")
		(net "M_D_CPU1_SA_DQS_DN<1>")
	)
	(segment
		(start 46.135798 -309.38851)
		(end 45.84827 -309.101236)
		(width 0.18288)
		(layer "In11.Cu")
		(net "M_D_CPU1_SA_DQS_DN<1>")
	)
	(segment
		(start 36.176458 -308.240938)
		(end 35.783266 -308.240938)
		(width 0.18288)
		(layer "In11.Cu")
		(net "M_D_CPU1_SA_DQS_DN<1>")
	)
	(segment
		(start 95.116396 -277.84679)
		(end 95.101664 -277.838154)
		(width 0.088646)
		(layer "In11.Cu")
		(net "M_D_CPU1_SA_DQS_DN<1>")
	)
	(segment
		(start 58.299858 -302.72736)
		(end 57.80786 -303.219358)
		(width 0.18288)
		(layer "In11.Cu")
		(net "M_D_CPU1_SA_DQS_DN<1>")
	)
	(segment
		(start 59.218068 -302.72736)
		(end 58.299858 -302.72736)
		(width 0.18288)
		(layer "In11.Cu")
		(net "M_D_CPU1_SA_DQS_DN<1>")
	)
	(segment
		(start 72.79386 -292.092126)
		(end 72.79386 -292.862254)
		(width 0.18288)
		(layer "In11.Cu")
		(net "M_D_CPU1_SA_DQS_DN<1>")
	)
	(segment
		(start 39.717472 -308.517544)
		(end 39.168832 -308.517544)
		(width 0.18288)
		(layer "In11.Cu")
		(net "M_D_CPU1_SA_DQS_DN<1>")
	)
	(segment
		(start 42.762932 -309.202836)
		(end 42.638472 -309.078376)
		(width 0.18288)
		(layer "In11.Cu")
		(net "M_D_CPU1_SA_DQS_DN<1>")
	)
	(segment
		(start 20.437094 -303.374552)
		(end 19.87169 -303.374552)
		(width 0.18288)
		(layer "In11.Cu")
		(net "M_D_CPU1_SA_DQS_DN<1>")
	)
	(segment
		(start 43.7769 -309.202836)
		(end 42.762932 -309.202836)
		(width 0.18288)
		(layer "In11.Cu")
		(net "M_D_CPU1_SA_DQS_DN<1>")
	)
	(segment
		(start 21.342858 -303.40046)
		(end 21.085302 -303.142904)
		(width 0.18288)
		(layer "In11.Cu")
		(net "M_D_CPU1_SA_DQS_DN<1>")
	)
	(segment
		(start 53.441854 -307.310282)
		(end 53.441854 -307.310028)
		(width 0.18288)
		(layer "In11.Cu")
		(net "M_D_CPU1_SA_DQS_DN<1>")
	)
	(segment
		(start 33.212024 -309.367682)
		(end 32.3342 -309.367682)
		(width 0.18288)
		(layer "In11.Cu")
		(net "M_D_CPU1_SA_DQS_DN<1>")
	)
	(segment
		(start 37.025072 -308.517544)
		(end 36.453064 -308.517544)
		(width 0.18288)
		(layer "In11.Cu")
		(net "M_D_CPU1_SA_DQS_DN<1>")
	)
	(segment
		(start 96.995996 -277.84679)
		(end 96.981264 -277.838154)
		(width 0.088646)
		(layer "In11.Cu")
		(net "M_D_CPU1_SA_DQS_DN<1>")
	)
	(segment
		(start 60.13069 -302.349154)
		(end 59.218068 -302.72736)
		(width 0.18288)
		(layer "In11.Cu")
		(net "M_D_CPU1_SA_DQS_DN<1>")
	)
	(segment
		(start 68.685156 -299.172122)
		(end 68.509134 -299.172122)
		(width 0.18288)
		(layer "In11.Cu")
		(net "M_D_CPU1_SA_DQS_DN<1>")
	)
	(segment
		(start 65.15989 -300.849792)
		(end 64.776858 -301.23257)
		(width 0.18288)
		(layer "In11.Cu")
		(net "M_D_CPU1_SA_DQS_DN<1>")
	)
	(segment
		(start 89.862406 -277.840694)
		(end 89.851992 -277.84679)
		(width 0.088646)
		(layer "In11.Cu")
		(net "M_D_CPU1_SA_DQS_DN<1>")
	)
	(segment
		(start 60.72632 -301.753524)
		(end 60.13069 -302.349154)
		(width 0.18288)
		(layer "In11.Cu")
		(net "M_D_CPU1_SA_DQS_DN<1>")
	)
	(segment
		(start 46.764702 -309.091076)
		(end 46.467268 -309.38851)
		(width 0.18288)
		(layer "In11.Cu")
		(net "M_D_CPU1_SA_DQS_DN<1>")
	)
	(segment
		(start 94.176596 -277.84679)
		(end 94.161864 -277.838154)
		(width 0.088646)
		(layer "In11.Cu")
		(net "M_D_CPU1_SA_DQS_DN<1>")
	)
	(segment
		(start 28.448762 -309.499)
		(end 27.548586 -308.59857)
		(width 0.18288)
		(layer "In11.Cu")
		(net "M_D_CPU1_SA_DQS_DN<1>")
	)
	(segment
		(start 18.585434 -304.008536)
		(end 18.425922 -303.942242)
		(width 0.18288)
		(layer "In11.Cu")
		(net "M_D_CPU1_SA_DQS_DN<1>")
	)
	(segment
		(start 64.776858 -301.23257)
		(end 63.588646 -301.724822)
		(width 0.18288)
		(layer "In11.Cu")
		(net "M_D_CPU1_SA_DQS_DN<1>")
	)
	(segment
		(start 37.822632 -308.517544)
		(end 37.698172 -308.393084)
		(width 0.18288)
		(layer "In11.Cu")
		(net "M_D_CPU1_SA_DQS_DN<1>")
	)
	(segment
		(start 36.453064 -308.517544)
		(end 36.176458 -308.240938)
		(width 0.18288)
		(layer "In11.Cu")
		(net "M_D_CPU1_SA_DQS_DN<1>")
	)
	(segment
		(start 86.445852 -278.750014)
		(end 86.362794 -278.832056)
		(width 0.088646)
		(layer "In11.Cu")
		(net "M_D_CPU1_SA_DQS_DN<1>")
	)
	(segment
		(start 84.921598 -280.069544)
		(end 84.921598 -280.875232)
		(width 0.088646)
		(layer "In11.Cu")
		(net "M_D_CPU1_SA_DQS_DN<1>")
	)
	(segment
		(start 96.056196 -277.84679)
		(end 96.041464 -277.838154)
		(width 0.088646)
		(layer "In11.Cu")
		(net "M_D_CPU1_SA_DQS_DN<1>")
	)
	(segment
		(start 97.897696 -277.701248)
		(end 97.624138 -277.701248)
		(width 0.088646)
		(layer "In11.Cu")
		(net "M_D_CPU1_SA_DQS_DN<1>")
	)
	(segment
		(start 18.425922 -303.942242)
		(end 17.45996 -302.97628)
		(width 0.18288)
		(layer "In11.Cu")
		(net "M_D_CPU1_SA_DQS_DN<1>")
	)
	(segment
		(start 39.044372 -308.393084)
		(end 38.495732 -308.393084)
		(width 0.18288)
		(layer "In11.Cu")
		(net "M_D_CPU1_SA_DQS_DN<1>")
	)
	(segment
		(start 53.441854 -307.310028)
		(end 52.230528 -308.521608)
		(width 0.18288)
		(layer "In11.Cu")
		(net "M_D_CPU1_SA_DQS_DN<1>")
	)
	(segment
		(start 82.861404 -282.024582)
		(end 72.79386 -292.092126)
		(width 0.18288)
		(layer "In11.Cu")
		(net "M_D_CPU1_SA_DQS_DN<1>")
	)
	(segment
		(start 49.304702 -308.86527)
		(end 49.237392 -309.028084)
		(width 0.18288)
		(layer "In11.Cu")
		(net "M_D_CPU1_SA_DQS_DN<1>")
	)
	(segment
		(start 87.511382 -278.65578)
		(end 87.502492 -278.66086)
		(width 0.088646)
		(layer "In11.Cu")
		(net "M_D_CPU1_SA_DQS_DN<1>")
	)
	(segment
		(start 23.047452 -304.096674)
		(end 22.122638 -303.478692)
		(width 0.18288)
		(layer "In11.Cu")
		(net "M_D_CPU1_SA_DQS_DN<1>")
	)
	(segment
		(start 87.689944 -278.321008)
		(end 87.689944 -278.336502)
		(width 0.088646)
		(layer "In11.Cu")
		(net "M_D_CPU1_SA_DQS_DN<1>")
	)
	(segment
		(start 66.406522 -300.594268)
		(end 65.92697 -300.594268)
		(width 0.18288)
		(layer "In11.Cu")
		(net "M_D_CPU1_SA_DQS_DN<1>")
	)
	(segment
		(start 49.237392 -309.028084)
		(end 48.426878 -309.363618)
		(width 0.18288)
		(layer "In11.Cu")
		(net "M_D_CPU1_SA_DQS_DN<1>")
	)
	(segment
		(start 57.808114 -303.219612)
		(end 57.552082 -303.837848)
		(width 0.18288)
		(layer "In11.Cu")
		(net "M_D_CPU1_SA_DQS_DN<1>")
	)
	(segment
		(start 69.101716 -296.554398)
		(end 69.101716 -298.755562)
		(width 0.18288)
		(layer "In11.Cu")
		(net "M_D_CPU1_SA_DQS_DN<1>")
	)
	(segment
		(start 61.871098 -301.44085)
		(end 61.558424 -301.753524)
		(width 0.18288)
		(layer "In11.Cu")
		(net "M_D_CPU1_SA_DQS_DN<1>")
	)
	(segment
		(start 42.089832 -309.078376)
		(end 41.965372 -309.202836)
		(width 0.18288)
		(layer "In11.Cu")
		(net "M_D_CPU1_SA_DQS_DN<1>")
	)
	(segment
		(start 21.864574 -303.40046)
		(end 21.342858 -303.40046)
		(width 0.18288)
		(layer "In11.Cu")
		(net "M_D_CPU1_SA_DQS_DN<1>")
	)
	(segment
		(start 57.24652 -304.574702)
		(end 56.89346 -305.426618)
		(width 0.18288)
		(layer "In11.Cu")
		(net "M_D_CPU1_SA_DQS_DN<1>")
	)
	(segment
		(start 97.3709 -277.847044)
		(end 97.370646 -277.84679)
		(width 0.088646)
		(layer "In11.Cu")
		(net "M_D_CPU1_SA_DQS_DN<1>")
	)
	(segment
		(start 49.81194 -308.655466)
		(end 49.304702 -308.86527)
		(width 0.18288)
		(layer "In11.Cu")
		(net "M_D_CPU1_SA_DQS_DN<1>")
	)
	(segment
		(start 83.68792 -282.024582)
		(end 82.861404 -282.024582)
		(width 0.18288)
		(layer "In11.Cu")
		(net "M_D_CPU1_SA_DQS_DN<1>")
	)
	(segment
		(start 27.045412 -306.852828)
		(end 26.880566 -306.455572)
		(width 0.18288)
		(layer "In11.Cu")
		(net "M_D_CPU1_SA_DQS_DN<1>")
	)
	(segment
		(start 56.89346 -305.426618)
		(end 56.118506 -306.201572)
		(width 0.18288)
		(layer "In11.Cu")
		(net "M_D_CPU1_SA_DQS_DN<1>")
	)
	(segment
		(start 21.085302 -303.142904)
		(end 20.668742 -303.142904)
		(width 0.18288)
		(layer "In11.Cu")
		(net "M_D_CPU1_SA_DQS_DN<1>")
	)
	(segment
		(start 44.012866 -308.966616)
		(end 43.7769 -309.202836)
		(width 0.18288)
		(layer "In11.Cu")
		(net "M_D_CPU1_SA_DQS_DN<1>")
	)
	(segment
		(start 18.798286 -304.008536)
		(end 18.585434 -304.008536)
		(width 0.18288)
		(layer "In11.Cu")
		(net "M_D_CPU1_SA_DQS_DN<1>")
	)
	(segment
		(start 54.874668 -306.716938)
		(end 53.441854 -307.310282)
		(width 0.18288)
		(layer "In11.Cu")
		(net "M_D_CPU1_SA_DQS_DN<1>")
	)
	(segment
		(start 29.539692 -309.950866)
		(end 28.448762 -309.499)
		(width 0.18288)
		(layer "In11.Cu")
		(net "M_D_CPU1_SA_DQS_DN<1>")
	)
	(segment
		(start 57.80786 -303.219358)
		(end 57.808114 -303.219612)
		(width 0.18288)
		(layer "In11.Cu")
		(net "M_D_CPU1_SA_DQS_DN<1>")
	)
	(segment
		(start 26.397458 -305.971702)
		(end 25.771856 -305.712622)
		(width 0.18288)
		(layer "In11.Cu")
		(net "M_D_CPU1_SA_DQS_DN<1>")
	)
	(segment
		(start 23.7109 -304.540158)
		(end 23.67661 -304.367438)
		(width 0.18288)
		(layer "In11.Cu")
		(net "M_D_CPU1_SA_DQS_DN<1>")
	)
	(segment
		(start 38.495732 -308.393084)
		(end 38.371272 -308.517544)
		(width 0.18288)
		(layer "In11.Cu")
		(net "M_D_CPU1_SA_DQS_DN<1>")
	)
	(segment
		(start 87.128096 -278.66086)
		(end 87.127588 -278.661114)
		(width 0.088646)
		(layer "In11.Cu")
		(net "M_D_CPU1_SA_DQS_DN<1>")
	)
	(segment
		(start 48.426878 -309.363618)
		(end 47.446184 -309.363618)
		(width 0.18288)
		(layer "In11.Cu")
		(net "M_D_CPU1_SA_DQS_DN<1>")
	)
	(segment
		(start 17.45996 -302.97628)
		(end 17.048734 -302.97628)
		(width 0.18288)
		(layer "In11.Cu")
		(net "M_D_CPU1_SA_DQS_DN<1>")
	)
	(segment
		(start 92.296996 -277.84679)
		(end 92.282264 -277.838154)
		(width 0.088646)
		(layer "In11.Cu")
		(net "M_D_CPU1_SA_DQS_DN<1>")
	)
	(segment
		(start 72.79386 -292.862254)
		(end 69.101716 -296.554398)
		(width 0.18288)
		(layer "In11.Cu")
		(net "M_D_CPU1_SA_DQS_DN<1>")
	)
	(segment
		(start 88.920828 -277.84171)
		(end 88.911938 -277.847044)
		(width 0.088646)
		(layer "In11.Cu")
		(net "M_D_CPU1_SA_DQS_DN<1>")
	)
	(segment
		(start 55.449216 -306.344066)
		(end 54.941978 -306.554124)
		(width 0.18288)
		(layer "In11.Cu")
		(net "M_D_CPU1_SA_DQS_DN<1>")
	)
	(segment
		(start 25.197308 -305.339496)
		(end 25.034748 -305.406806)
		(width 0.18288)
		(layer "In11.Cu")
		(net "M_D_CPU1_SA_DQS_DN<1>")
	)
	(segment
		(start 32.057594 -309.091076)
		(end 31.682182 -309.091076)
		(width 0.18288)
		(layer "In11.Cu")
		(net "M_D_CPU1_SA_DQS_DN<1>")
	)
	(segment
		(start 25.771856 -305.712622)
		(end 25.704546 -305.549554)
		(width 0.18288)
		(layer "In11.Cu")
		(net "M_D_CPU1_SA_DQS_DN<1>")
	)
	(segment
		(start 68.121022 -299.736256)
		(end 67.025266 -300.832012)
		(width 0.18288)
		(layer "In11.Cu")
		(net "M_D_CPU1_SA_DQS_DN<1>")
	)
	(segment
		(start 25.704546 -305.549554)
		(end 25.197308 -305.339496)
		(width 0.18288)
		(layer "In11.Cu")
		(net "M_D_CPU1_SA_DQS_DN<1>")
	)
	(segment
		(start 84.921598 -280.875232)
		(end 84.220304 -281.576526)
		(width 0.088646)
		(layer "In11.Cu")
		(net "M_D_CPU1_SA_DQS_DN<1>")
	)
	(segment
		(start 37.698172 -308.393084)
		(end 37.149532 -308.393084)
		(width 0.18288)
		(layer "In11.Cu")
		(net "M_D_CPU1_SA_DQS_DN<1>")
	)
	(segment
		(start 50.48123 -308.512972)
		(end 49.9745 -308.722776)
		(width 0.18288)
		(layer "In11.Cu")
		(net "M_D_CPU1_SA_DQS_DN<1>")
	)
	(segment
		(start 23.220172 -304.062384)
		(end 23.047452 -304.096674)
		(width 0.18288)
		(layer "In11.Cu")
		(net "M_D_CPU1_SA_DQS_DN<1>")
	)
	(segment
		(start 26.880566 -306.455572)
		(end 26.397458 -305.971702)
		(width 0.18288)
		(layer "In11.Cu")
		(net "M_D_CPU1_SA_DQS_DN<1>")
	)
	(segment
		(start 86.159086 -278.832056)
		(end 84.921598 -280.069544)
		(width 0.088646)
		(layer "In11.Cu")
		(net "M_D_CPU1_SA_DQS_DN<1>")
	)
	(segment
		(start 47.173642 -309.091076)
		(end 46.764702 -309.091076)
		(width 0.18288)
		(layer "In11.Cu")
		(net "M_D_CPU1_SA_DQS_DN<1>")
	)
	(segment
		(start 56.118506 -306.201572)
		(end 55.611776 -306.411376)
		(width 0.18288)
		(layer "In11.Cu")
		(net "M_D_CPU1_SA_DQS_DN<1>")
	)
	(segment
		(start 65.92697 -300.594268)
		(end 65.671446 -300.849792)
		(width 0.18288)
		(layer "In11.Cu")
		(net "M_D_CPU1_SA_DQS_DN<1>")
	)
	(segment
		(start 35.783266 -308.240938)
		(end 35.531552 -308.492652)
		(width 0.18288)
		(layer "In11.Cu")
		(net "M_D_CPU1_SA_DQS_DN<1>")
	)
	(segment
		(start 32.3342 -309.367682)
		(end 32.057594 -309.091076)
		(width 0.18288)
		(layer "In11.Cu")
		(net "M_D_CPU1_SA_DQS_DN<1>")
	)
	(segment
		(start 62.32271 -301.44085)
		(end 61.871098 -301.44085)
		(width 0.18288)
		(layer "In11.Cu")
		(net "M_D_CPU1_SA_DQS_DN<1>")
	)
	(segment
		(start 93.236796 -277.84679)
		(end 93.222064 -277.838154)
		(width 0.088646)
		(layer "In11.Cu")
		(net "M_D_CPU1_SA_DQS_DN<1>")
	)
	(segment
		(start 49.9745 -308.722776)
		(end 49.81194 -308.655466)
		(width 0.18288)
		(layer "In11.Cu")
		(net "M_D_CPU1_SA_DQS_DN<1>")
	)
	(segment
		(start 68.121022 -299.560234)
		(end 68.121022 -299.736256)
		(width 0.18288)
		(layer "In11.Cu")
		(net "M_D_CPU1_SA_DQS_DN<1>")
	)
	(segment
		(start 35.531552 -308.492652)
		(end 35.324796 -308.492652)
		(width 0.18288)
		(layer "In11.Cu")
		(net "M_D_CPU1_SA_DQS_DN<1>")
	)
	(segment
		(start 96.99625 -277.84679)
		(end 96.995996 -277.84679)
		(width 0.088646)
		(layer "In11.Cu")
		(net "M_D_CPU1_SA_DQS_DN<1>")
	)
	(segment
		(start 24.528018 -305.197002)
		(end 24.193754 -304.862738)
		(width 0.18288)
		(layer "In11.Cu")
		(net "M_D_CPU1_SA_DQS_DN<1>")
	)
	(segment
		(start 88.537542 -277.847044)
		(end 88.52281 -277.838408)
		(width 0.088646)
		(layer "In11.Cu")
		(net "M_D_CPU1_SA_DQS_DN<1>")
	)
	(segment
		(start 25.034748 -305.406806)
		(end 24.528018 -305.197002)
		(width 0.18288)
		(layer "In11.Cu")
		(net "M_D_CPU1_SA_DQS_DN<1>")
	)
	(arc
		(start 90.41765 -277.84679)
		(mid 90.140837 -277.770954)
		(end 89.862406 -277.840694)
		(width 0.088646)
		(layer "In11.Cu")
		(net "M_D_CPU1_SA_DQS_DN<1>")
	)
	(arc
		(start 97.370646 -277.84679)
		(mid 97.183448 -277.896933)
		(end 96.99625 -277.84679)
		(width 0.088646)
		(layer "In11.Cu")
		(net "M_D_CPU1_SA_DQS_DN<1>")
	)
	(arc
		(start 93.222064 -277.838154)
		(mid 92.945623 -277.770988)
		(end 92.671392 -277.84679)
		(width 0.088646)
		(layer "In11.Cu")
		(net "M_D_CPU1_SA_DQS_DN<1>")
	)
	(arc
		(start 95.490792 -277.84679)
		(mid 95.303594 -277.896933)
		(end 95.116396 -277.84679)
		(width 0.088646)
		(layer "In11.Cu")
		(net "M_D_CPU1_SA_DQS_DN<1>")
	)
	(arc
		(start 91.731592 -277.84679)
		(mid 91.544394 -277.896933)
		(end 91.357196 -277.84679)
		(width 0.088646)
		(layer "In11.Cu")
		(net "M_D_CPU1_SA_DQS_DN<1>")
	)
	(arc
		(start 96.041464 -277.838154)
		(mid 95.765023 -277.770988)
		(end 95.490792 -277.84679)
		(width 0.088646)
		(layer "In11.Cu")
		(net "M_D_CPU1_SA_DQS_DN<1>")
	)
	(arc
		(start 87.689944 -278.336502)
		(mid 87.642265 -278.519402)
		(end 87.511382 -278.65578)
		(width 0.088646)
		(layer "In11.Cu")
		(net "M_D_CPU1_SA_DQS_DN<1>")
	)
	(arc
		(start 98.052382 -277.660354)
		(mid 97.977697 -277.690859)
		(end 97.897696 -277.701248)
		(width 0.088646)
		(layer "In11.Cu")
		(net "M_D_CPU1_SA_DQS_DN<1>")
	)
	(arc
		(start 91.357196 -277.84679)
		(mid 91.080637 -277.771081)
		(end 90.80246 -277.840694)
		(width 0.088646)
		(layer "In11.Cu")
		(net "M_D_CPU1_SA_DQS_DN<1>")
	)
	(arc
		(start 87.127588 -278.661114)
		(mid 86.845567 -278.585558)
		(end 86.563454 -278.66086)
		(width 0.088646)
		(layer "In11.Cu")
		(net "M_D_CPU1_SA_DQS_DN<1>")
	)
	(arc
		(start 88.911938 -277.847044)
		(mid 88.72474 -277.897187)
		(end 88.537542 -277.847044)
		(width 0.088646)
		(layer "In11.Cu")
		(net "M_D_CPU1_SA_DQS_DN<1>")
	)
	(arc
		(start 86.563454 -278.66086)
		(mid 86.501732 -278.701584)
		(end 86.445852 -278.750014)
		(width 0.088646)
		(layer "In11.Cu")
		(net "M_D_CPU1_SA_DQS_DN<1>")
	)
	(arc
		(start 92.671392 -277.84679)
		(mid 92.484194 -277.896933)
		(end 92.296996 -277.84679)
		(width 0.088646)
		(layer "In11.Cu")
		(net "M_D_CPU1_SA_DQS_DN<1>")
	)
	(arc
		(start 96.430592 -277.84679)
		(mid 96.243394 -277.896933)
		(end 96.056196 -277.84679)
		(width 0.088646)
		(layer "In11.Cu")
		(net "M_D_CPU1_SA_DQS_DN<1>")
	)
	(arc
		(start 88.52281 -277.838408)
		(mid 88.246335 -277.771088)
		(end 87.972138 -277.847044)
		(width 0.088646)
		(layer "In11.Cu")
		(net "M_D_CPU1_SA_DQS_DN<1>")
	)
	(arc
		(start 93.611192 -277.84679)
		(mid 93.423994 -277.896933)
		(end 93.236796 -277.84679)
		(width 0.088646)
		(layer "In11.Cu")
		(net "M_D_CPU1_SA_DQS_DN<1>")
	)
	(arc
		(start 87.972138 -277.847044)
		(mid 87.769315 -278.047275)
		(end 87.689944 -278.321008)
		(width 0.088646)
		(layer "In11.Cu")
		(net "M_D_CPU1_SA_DQS_DN<1>")
	)
	(arc
		(start 94.161864 -277.838154)
		(mid 93.885423 -277.770988)
		(end 93.611192 -277.84679)
		(width 0.088646)
		(layer "In11.Cu")
		(net "M_D_CPU1_SA_DQS_DN<1>")
	)
	(arc
		(start 87.502492 -278.66086)
		(mid 87.315294 -278.711003)
		(end 87.128096 -278.66086)
		(width 0.088646)
		(layer "In11.Cu")
		(net "M_D_CPU1_SA_DQS_DN<1>")
	)
	(arc
		(start 92.282264 -277.838154)
		(mid 92.005823 -277.770988)
		(end 91.731592 -277.84679)
		(width 0.088646)
		(layer "In11.Cu")
		(net "M_D_CPU1_SA_DQS_DN<1>")
	)
	(arc
		(start 94.550992 -277.84679)
		(mid 94.363794 -277.896933)
		(end 94.176596 -277.84679)
		(width 0.088646)
		(layer "In11.Cu")
		(net "M_D_CPU1_SA_DQS_DN<1>")
	)
	(arc
		(start 96.981264 -277.838154)
		(mid 96.704823 -277.770988)
		(end 96.430592 -277.84679)
		(width 0.088646)
		(layer "In11.Cu")
		(net "M_D_CPU1_SA_DQS_DN<1>")
	)
	(arc
		(start 90.792046 -277.84679)
		(mid 90.604848 -277.896933)
		(end 90.41765 -277.84679)
		(width 0.088646)
		(layer "In11.Cu")
		(net "M_D_CPU1_SA_DQS_DN<1>")
	)
	(arc
		(start 89.477596 -277.84679)
		(mid 89.19987 -277.770945)
		(end 88.920828 -277.84171)
		(width 0.088646)
		(layer "In11.Cu")
		(net "M_D_CPU1_SA_DQS_DN<1>")
	)
	(arc
		(start 89.851992 -277.84679)
		(mid 89.664794 -277.896933)
		(end 89.477596 -277.84679)
		(width 0.088646)
		(layer "In11.Cu")
		(net "M_D_CPU1_SA_DQS_DN<1>")
	)
	(arc
		(start 95.101664 -277.838154)
		(mid 94.825223 -277.770988)
		(end 94.550992 -277.84679)
		(width 0.088646)
		(layer "In11.Cu")
		(net "M_D_CPU1_SA_DQS_DN<1>")
	)
	(segment
		(start 15.137638 -312.066686)
		(end 14.876526 -312.327798)
		(width 0.20066)
		(layer "F.Cu")
		(net "M_D_CPU1_SA_DQS_DN<0>")
	)
	(segment
		(start 14.469872 -312.327798)
		(end 14.044676 -312.752994)
		(width 0.20066)
		(layer "F.Cu")
		(net "M_D_CPU1_SA_DQS_DN<0>")
	)
	(segment
		(start 13.441426 -312.491628)
		(end 11.12774 -312.491628)
		(width 0.1016)
		(layer "F.Cu")
		(net "M_D_CPU1_SA_DQS_DN<0>")
	)
	(segment
		(start 13.857986 -312.752994)
		(end 13.59662 -312.491628)
		(width 0.20066)
		(layer "F.Cu")
		(net "M_D_CPU1_SA_DQS_DN<0>")
	)
	(segment
		(start 10.64006 -312.752994)
		(end 10.100056 -312.752994)
		(width 0.20066)
		(layer "F.Cu")
		(net "M_D_CPU1_SA_DQS_DN<0>")
	)
	(segment
		(start 8.689086 -312.066686)
		(end 8.140446 -312.066686)
		(width 0.20066)
		(layer "F.Cu")
		(net "M_D_CPU1_SA_DQS_DN<0>")
	)
	(segment
		(start 14.044676 -312.752994)
		(end 13.857986 -312.752994)
		(width 0.20066)
		(layer "F.Cu")
		(net "M_D_CPU1_SA_DQS_DN<0>")
	)
	(segment
		(start 10.912094 -312.48096)
		(end 10.64006 -312.752994)
		(width 0.20066)
		(layer "F.Cu")
		(net "M_D_CPU1_SA_DQS_DN<0>")
	)
	(segment
		(start 11.12774 -312.491628)
		(end 11.117072 -312.48096)
		(width 0.101854)
		(layer "F.Cu")
		(net "M_D_CPU1_SA_DQS_DN<0>")
	)
	(segment
		(start 15.684246 -312.066686)
		(end 16.789146 -312.066686)
		(width 0.20066)
		(layer "F.Cu")
		(net "M_D_CPU1_SA_DQS_DN<0>")
	)
	(segment
		(start 15.684246 -312.066686)
		(end 15.137638 -312.066686)
		(width 0.20066)
		(layer "F.Cu")
		(net "M_D_CPU1_SA_DQS_DN<0>")
	)
	(segment
		(start 11.117072 -312.48096)
		(end 11.11631 -312.48096)
		(width 0.101854)
		(layer "F.Cu")
		(net "M_D_CPU1_SA_DQS_DN<0>")
	)
	(segment
		(start 13.59662 -312.491628)
		(end 13.441426 -312.491628)
		(width 0.20066)
		(layer "F.Cu")
		(net "M_D_CPU1_SA_DQS_DN<0>")
	)
	(segment
		(start 11.11631 -312.48096)
		(end 10.912094 -312.48096)
		(width 0.20066)
		(layer "F.Cu")
		(net "M_D_CPU1_SA_DQS_DN<0>")
	)
	(segment
		(start 9.46404 -312.327798)
		(end 8.950198 -312.327798)
		(width 0.20066)
		(layer "F.Cu")
		(net "M_D_CPU1_SA_DQS_DN<0>")
	)
	(segment
		(start 8.950198 -312.327798)
		(end 8.689086 -312.066686)
		(width 0.20066)
		(layer "F.Cu")
		(net "M_D_CPU1_SA_DQS_DN<0>")
	)
	(segment
		(start 10.100056 -312.752994)
		(end 9.46404 -312.327798)
		(width 0.20066)
		(layer "F.Cu")
		(net "M_D_CPU1_SA_DQS_DN<0>")
	)
	(segment
		(start 14.876526 -312.327798)
		(end 14.469872 -312.327798)
		(width 0.20066)
		(layer "F.Cu")
		(net "M_D_CPU1_SA_DQS_DN<0>")
	)
	(arc
		(start 94.833694 -274.54479)
		(mid 94.833757 -274.81276)
		(end 94.833948 -275.08073)
		(width 0.20066)
		(layer "F.Cu")
		(net "M_D_CPU1_SA_DQS_DN<0>")
	)
	(segment
		(start 81.612232 -282.4226)
		(end 81.43621 -282.4226)
		(width 0.18288)
		(layer "In6.Cu")
		(net "M_D_CPU1_SA_DQS_DN<0>")
	)
	(segment
		(start 46.113446 -309.341012)
		(end 45.600112 -309.854092)
		(width 0.18288)
		(layer "In6.Cu")
		(net "M_D_CPU1_SA_DQS_DN<0>")
	)
	(segment
		(start 36.993322 -314.452254)
		(end 36.454334 -314.452254)
		(width 0.18288)
		(layer "In6.Cu")
		(net "M_D_CPU1_SA_DQS_DN<0>")
	)
	(segment
		(start 85.717888 -278.806656)
		(end 84.527898 -279.996646)
		(width 0.088646)
		(layer "In6.Cu")
		(net "M_D_CPU1_SA_DQS_DN<0>")
	)
	(segment
		(start 35.754056 -314.19165)
		(end 35.510978 -314.434728)
		(width 0.18288)
		(layer "In6.Cu")
		(net "M_D_CPU1_SA_DQS_DN<0>")
	)
	(segment
		(start 34.172144 -313.635136)
		(end 32.391096 -313.635136)
		(width 0.18288)
		(layer "In6.Cu")
		(net "M_D_CPU1_SA_DQS_DN<0>")
	)
	(segment
		(start 82.00009 -281.85872)
		(end 82.00009 -282.034742)
		(width 0.18288)
		(layer "In6.Cu")
		(net "M_D_CPU1_SA_DQS_DN<0>")
	)
	(segment
		(start 61.803788 -299.74159)
		(end 61.55436 -299.991018)
		(width 0.18288)
		(layer "In6.Cu")
		(net "M_D_CPU1_SA_DQS_DN<0>")
	)
	(segment
		(start 93.156278 -275.396452)
		(end 93.141546 -275.405088)
		(width 0.088646)
		(layer "In6.Cu")
		(net "M_D_CPU1_SA_DQS_DN<0>")
	)
	(segment
		(start 63.302388 -299.754544)
		(end 63.043562 -300.01337)
		(width 0.18288)
		(layer "In6.Cu")
		(net "M_D_CPU1_SA_DQS_DN<0>")
	)
	(segment
		(start 32.391096 -313.635136)
		(end 32.097472 -313.341512)
		(width 0.18288)
		(layer "In6.Cu")
		(net "M_D_CPU1_SA_DQS_DN<0>")
	)
	(segment
		(start 83.384136 -280.650696)
		(end 82.564224 -281.470608)
		(width 0.18288)
		(layer "In6.Cu")
		(net "M_D_CPU1_SA_DQS_DN<0>")
	)
	(segment
		(start 36.19373 -314.19165)
		(end 35.754056 -314.19165)
		(width 0.18288)
		(layer "In6.Cu")
		(net "M_D_CPU1_SA_DQS_DN<0>")
	)
	(segment
		(start 51.602894 -306.802028)
		(end 51.342544 -306.541678)
		(width 0.18288)
		(layer "In6.Cu")
		(net "M_D_CPU1_SA_DQS_DN<0>")
	)
	(segment
		(start 77.24013 -286.794702)
		(end 76.852272 -287.18256)
		(width 0.18288)
		(layer "In6.Cu")
		(net "M_D_CPU1_SA_DQS_DN<0>")
	)
	(segment
		(start 35.180524 -314.434728)
		(end 34.529014 -313.782964)
		(width 0.18288)
		(layer "In6.Cu")
		(net "M_D_CPU1_SA_DQS_DN<0>")
	)
	(segment
		(start 46.49216 -309.341012)
		(end 46.113446 -309.341012)
		(width 0.18288)
		(layer "In6.Cu")
		(net "M_D_CPU1_SA_DQS_DN<0>")
	)
	(segment
		(start 90.332306 -275.398992)
		(end 90.321892 -275.405088)
		(width 0.088646)
		(layer "In6.Cu")
		(net "M_D_CPU1_SA_DQS_DN<0>")
	)
	(segment
		(start 89.390982 -277.027894)
		(end 89.382092 -277.032974)
		(width 0.088646)
		(layer "In6.Cu")
		(net "M_D_CPU1_SA_DQS_DN<0>")
	)
	(segment
		(start 31.653734 -313.341512)
		(end 31.408116 -313.58713)
		(width 0.18288)
		(layer "In6.Cu")
		(net "M_D_CPU1_SA_DQS_DN<0>")
	)
	(segment
		(start 17.778984 -312.336942)
		(end 17.059402 -312.336942)
		(width 0.18288)
		(layer "In6.Cu")
		(net "M_D_CPU1_SA_DQS_DN<0>")
	)
	(segment
		(start 66.361056 -298.892468)
		(end 65.965832 -298.892468)
		(width 0.18288)
		(layer "In6.Cu")
		(net "M_D_CPU1_SA_DQS_DN<0>")
	)
	(segment
		(start 75.336146 -288.698686)
		(end 74.948288 -289.086544)
		(width 0.18288)
		(layer "In6.Cu")
		(net "M_D_CPU1_SA_DQS_DN<0>")
	)
	(segment
		(start 21.385784 -312.76671)
		(end 21.110702 -312.491628)
		(width 0.18288)
		(layer "In6.Cu")
		(net "M_D_CPU1_SA_DQS_DN<0>")
	)
	(segment
		(start 84.054442 -280.650696)
		(end 83.384136 -280.650696)
		(width 0.18288)
		(layer "In6.Cu")
		(net "M_D_CPU1_SA_DQS_DN<0>")
	)
	(segment
		(start 82.388202 -281.470608)
		(end 82.00009 -281.85872)
		(width 0.18288)
		(layer "In6.Cu")
		(net "M_D_CPU1_SA_DQS_DN<0>")
	)
	(segment
		(start 89.569544 -276.69871)
		(end 89.569544 -276.708616)
		(width 0.088646)
		(layer "In6.Cu")
		(net "M_D_CPU1_SA_DQS_DN<0>")
	)
	(segment
		(start 94.833948 -275.08073)
		(end 94.802198 -275.196554)
		(width 0.088646)
		(layer "In6.Cu")
		(net "M_D_CPU1_SA_DQS_DN<0>")
	)
	(segment
		(start 45.600112 -309.854092)
		(end 44.653962 -310.246014)
		(width 0.18288)
		(layer "In6.Cu")
		(net "M_D_CPU1_SA_DQS_DN<0>")
	)
	(segment
		(start 36.454334 -314.452254)
		(end 36.19373 -314.19165)
		(width 0.18288)
		(layer "In6.Cu")
		(net "M_D_CPU1_SA_DQS_DN<0>")
	)
	(segment
		(start 26.126694 -312.089292)
		(end 24.490934 -312.76671)
		(width 0.18288)
		(layer "In6.Cu")
		(net "M_D_CPU1_SA_DQS_DN<0>")
	)
	(segment
		(start 66.607944 -299.139356)
		(end 66.361056 -298.892468)
		(width 0.18288)
		(layer "In6.Cu")
		(net "M_D_CPU1_SA_DQS_DN<0>")
	)
	(segment
		(start 52.17922 -306.802028)
		(end 51.602894 -306.802028)
		(width 0.18288)
		(layer "In6.Cu")
		(net "M_D_CPU1_SA_DQS_DN<0>")
	)
	(segment
		(start 79.532226 -284.326584)
		(end 79.144114 -284.714696)
		(width 0.18288)
		(layer "In6.Cu")
		(net "M_D_CPU1_SA_DQS_DN<0>")
	)
	(segment
		(start 50.841402 -306.541678)
		(end 50.604166 -306.778914)
		(width 0.18288)
		(layer "In6.Cu")
		(net "M_D_CPU1_SA_DQS_DN<0>")
	)
	(segment
		(start 78.756256 -285.278576)
		(end 78.580234 -285.278576)
		(width 0.18288)
		(layer "In6.Cu")
		(net "M_D_CPU1_SA_DQS_DN<0>")
	)
	(segment
		(start 61.55436 -299.991018)
		(end 61.016134 -299.991018)
		(width 0.18288)
		(layer "In6.Cu")
		(net "M_D_CPU1_SA_DQS_DN<0>")
	)
	(segment
		(start 81.048098 -282.986734)
		(end 80.66024 -283.374592)
		(width 0.18288)
		(layer "In6.Cu")
		(net "M_D_CPU1_SA_DQS_DN<0>")
	)
	(segment
		(start 80.096106 -283.762704)
		(end 80.096106 -283.938726)
		(width 0.18288)
		(layer "In6.Cu")
		(net "M_D_CPU1_SA_DQS_DN<0>")
	)
	(segment
		(start 64.152018 -299.754544)
		(end 63.302388 -299.754544)
		(width 0.18288)
		(layer "In6.Cu")
		(net "M_D_CPU1_SA_DQS_DN<0>")
	)
	(segment
		(start 20.694904 -312.491628)
		(end 20.432776 -312.753756)
		(width 0.18288)
		(layer "In6.Cu")
		(net "M_D_CPU1_SA_DQS_DN<0>")
	)
	(segment
		(start 91.27236 -275.398992)
		(end 91.261946 -275.405088)
		(width 0.088646)
		(layer "In6.Cu")
		(net "M_D_CPU1_SA_DQS_DN<0>")
	)
	(segment
		(start 73.044304 -290.990528)
		(end 72.868282 -290.990528)
		(width 0.18288)
		(layer "In6.Cu")
		(net "M_D_CPU1_SA_DQS_DN<0>")
	)
	(segment
		(start 93.707204 -275.405088)
		(end 93.70695 -275.405088)
		(width 0.088646)
		(layer "In6.Cu")
		(net "M_D_CPU1_SA_DQS_DN<0>")
	)
	(segment
		(start 74.948288 -289.086544)
		(end 74.772266 -289.086544)
		(width 0.18288)
		(layer "In6.Cu")
		(net "M_D_CPU1_SA_DQS_DN<0>")
	)
	(segment
		(start 35.510978 -314.434728)
		(end 35.180524 -314.434728)
		(width 0.18288)
		(layer "In6.Cu")
		(net "M_D_CPU1_SA_DQS_DN<0>")
	)
	(segment
		(start 77.628242 -286.230568)
		(end 77.24013 -286.61868)
		(width 0.18288)
		(layer "In6.Cu")
		(net "M_D_CPU1_SA_DQS_DN<0>")
	)
	(segment
		(start 89.860882 -276.214078)
		(end 89.852754 -276.21865)
		(width 0.088646)
		(layer "In6.Cu")
		(net "M_D_CPU1_SA_DQS_DN<0>")
	)
	(segment
		(start 90.039444 -275.876258)
		(end 90.039444 -275.8948)
		(width 0.088646)
		(layer "In6.Cu")
		(net "M_D_CPU1_SA_DQS_DN<0>")
	)
	(segment
		(start 80.484218 -283.374592)
		(end 80.096106 -283.762704)
		(width 0.18288)
		(layer "In6.Cu")
		(net "M_D_CPU1_SA_DQS_DN<0>")
	)
	(segment
		(start 94.081854 -275.405342)
		(end 94.0816 -275.405088)
		(width 0.088646)
		(layer "In6.Cu")
		(net "M_D_CPU1_SA_DQS_DN<0>")
	)
	(segment
		(start 28.76931 -312.089292)
		(end 26.126694 -312.089292)
		(width 0.18288)
		(layer "In6.Cu")
		(net "M_D_CPU1_SA_DQS_DN<0>")
	)
	(segment
		(start 62.304422 -299.74159)
		(end 61.803788 -299.74159)
		(width 0.18288)
		(layer "In6.Cu")
		(net "M_D_CPU1_SA_DQS_DN<0>")
	)
	(segment
		(start 82.00009 -282.034742)
		(end 81.612232 -282.4226)
		(width 0.18288)
		(layer "In6.Cu")
		(net "M_D_CPU1_SA_DQS_DN<0>")
	)
	(segment
		(start 73.820274 -290.038536)
		(end 73.432162 -290.426648)
		(width 0.18288)
		(layer "In6.Cu")
		(net "M_D_CPU1_SA_DQS_DN<0>")
	)
	(segment
		(start 67.568064 -298.500292)
		(end 66.929 -299.139356)
		(width 0.18288)
		(layer "In6.Cu")
		(net "M_D_CPU1_SA_DQS_DN<0>")
	)
	(segment
		(start 62.576202 -300.01337)
		(end 62.304422 -299.74159)
		(width 0.18288)
		(layer "In6.Cu")
		(net "M_D_CPU1_SA_DQS_DN<0>")
	)
	(segment
		(start 65.668652 -299.189648)
		(end 64.716914 -299.189648)
		(width 0.18288)
		(layer "In6.Cu")
		(net "M_D_CPU1_SA_DQS_DN<0>")
	)
	(segment
		(start 81.048098 -282.810712)
		(end 81.048098 -282.986734)
		(width 0.18288)
		(layer "In6.Cu")
		(net "M_D_CPU1_SA_DQS_DN<0>")
	)
	(segment
		(start 58.405268 -302.176434)
		(end 58.19902 -302.673258)
		(width 0.18288)
		(layer "In6.Cu")
		(net "M_D_CPU1_SA_DQS_DN<0>")
	)
	(segment
		(start 50.604166 -306.778914)
		(end 50.055272 -306.778914)
		(width 0.18288)
		(layer "In6.Cu")
		(net "M_D_CPU1_SA_DQS_DN<0>")
	)
	(segment
		(start 76.288138 -287.746694)
		(end 75.90028 -288.134552)
		(width 0.18288)
		(layer "In6.Cu")
		(net "M_D_CPU1_SA_DQS_DN<0>")
	)
	(segment
		(start 84.527898 -279.996646)
		(end 84.527898 -280.554176)
		(width 0.088646)
		(layer "In6.Cu")
		(net "M_D_CPU1_SA_DQS_DN<0>")
	)
	(segment
		(start 46.741334 -309.091838)
		(end 46.49216 -309.341012)
		(width 0.18288)
		(layer "In6.Cu")
		(net "M_D_CPU1_SA_DQS_DN<0>")
	)
	(segment
		(start 48.02886 -309.08117)
		(end 47.757842 -309.352188)
		(width 0.18288)
		(layer "In6.Cu")
		(net "M_D_CPU1_SA_DQS_DN<0>")
	)
	(segment
		(start 88.537542 -277.847044)
		(end 88.52281 -277.838408)
		(width 0.088646)
		(layer "In6.Cu")
		(net "M_D_CPU1_SA_DQS_DN<0>")
	)
	(segment
		(start 51.342544 -306.541678)
		(end 50.841402 -306.541678)
		(width 0.18288)
		(layer "In6.Cu")
		(net "M_D_CPU1_SA_DQS_DN<0>")
	)
	(segment
		(start 89.852754 -276.21865)
		(end 89.851992 -276.219158)
		(width 0.088646)
		(layer "In6.Cu")
		(net "M_D_CPU1_SA_DQS_DN<0>")
	)
	(segment
		(start 58.19902 -302.673258)
		(end 56.593232 -304.279046)
		(width 0.18288)
		(layer "In6.Cu")
		(net "M_D_CPU1_SA_DQS_DN<0>")
	)
	(segment
		(start 24.490934 -312.76671)
		(end 21.385784 -312.76671)
		(width 0.18288)
		(layer "In6.Cu")
		(net "M_D_CPU1_SA_DQS_DN<0>")
	)
	(segment
		(start 75.336146 -288.522664)
		(end 75.336146 -288.698686)
		(width 0.18288)
		(layer "In6.Cu")
		(net "M_D_CPU1_SA_DQS_DN<0>")
	)
	(segment
		(start 88.920828 -277.841964)
		(end 88.911938 -277.847044)
		(width 0.088646)
		(layer "In6.Cu")
		(net "M_D_CPU1_SA_DQS_DN<0>")
	)
	(segment
		(start 38.87851 -313.022742)
		(end 37.77107 -314.130182)
		(width 0.18288)
		(layer "In6.Cu")
		(net "M_D_CPU1_SA_DQS_DN<0>")
	)
	(segment
		(start 80.66024 -283.374592)
		(end 80.484218 -283.374592)
		(width 0.18288)
		(layer "In6.Cu")
		(net "M_D_CPU1_SA_DQS_DN<0>")
	)
	(segment
		(start 75.90028 -288.134552)
		(end 75.724258 -288.134552)
		(width 0.18288)
		(layer "In6.Cu")
		(net "M_D_CPU1_SA_DQS_DN<0>")
	)
	(segment
		(start 34.529014 -313.782964)
		(end 34.172144 -313.635136)
		(width 0.18288)
		(layer "In6.Cu")
		(net "M_D_CPU1_SA_DQS_DN<0>")
	)
	(segment
		(start 49.395888 -307.438044)
		(end 48.768 -307.69814)
		(width 0.18288)
		(layer "In6.Cu")
		(net "M_D_CPU1_SA_DQS_DN<0>")
	)
	(segment
		(start 60.369704 -300.637194)
		(end 59.643772 -300.93793)
		(width 0.18288)
		(layer "In6.Cu")
		(net "M_D_CPU1_SA_DQS_DN<0>")
	)
	(segment
		(start 73.996296 -290.038536)
		(end 73.820274 -290.038536)
		(width 0.18288)
		(layer "In6.Cu")
		(net "M_D_CPU1_SA_DQS_DN<0>")
	)
	(segment
		(start 47.502826 -309.352188)
		(end 47.242476 -309.091838)
		(width 0.18288)
		(layer "In6.Cu")
		(net "M_D_CPU1_SA_DQS_DN<0>")
	)
	(segment
		(start 61.016134 -299.991018)
		(end 60.369704 -300.637194)
		(width 0.18288)
		(layer "In6.Cu")
		(net "M_D_CPU1_SA_DQS_DN<0>")
	)
	(segment
		(start 44.653962 -310.246014)
		(end 43.996864 -310.902604)
		(width 0.18288)
		(layer "In6.Cu")
		(net "M_D_CPU1_SA_DQS_DN<0>")
	)
	(segment
		(start 79.144114 -284.890718)
		(end 78.756256 -285.278576)
		(width 0.18288)
		(layer "In6.Cu")
		(net "M_D_CPU1_SA_DQS_DN<0>")
	)
	(segment
		(start 64.716914 -299.189648)
		(end 64.152018 -299.754544)
		(width 0.18288)
		(layer "In6.Cu")
		(net "M_D_CPU1_SA_DQS_DN<0>")
	)
	(segment
		(start 53.997606 -305.355244)
		(end 52.813966 -306.538884)
		(width 0.18288)
		(layer "In6.Cu")
		(net "M_D_CPU1_SA_DQS_DN<0>")
	)
	(segment
		(start 85.975698 -277.936706)
		(end 85.717888 -278.194516)
		(width 0.088646)
		(layer "In6.Cu")
		(net "M_D_CPU1_SA_DQS_DN<0>")
	)
	(segment
		(start 18.967958 -312.114946)
		(end 18.315432 -312.114946)
		(width 0.18288)
		(layer "In6.Cu")
		(net "M_D_CPU1_SA_DQS_DN<0>")
	)
	(segment
		(start 63.043562 -300.01337)
		(end 62.576202 -300.01337)
		(width 0.18288)
		(layer "In6.Cu")
		(net "M_D_CPU1_SA_DQS_DN<0>")
	)
	(segment
		(start 94.802198 -275.196554)
		(end 94.763336 -275.218652)
		(width 0.088646)
		(layer "In6.Cu")
		(net "M_D_CPU1_SA_DQS_DN<0>")
	)
	(segment
		(start 80.096106 -283.938726)
		(end 79.708248 -284.326584)
		(width 0.18288)
		(layer "In6.Cu")
		(net "M_D_CPU1_SA_DQS_DN<0>")
	)
	(segment
		(start 66.929 -299.139356)
		(end 66.607944 -299.139356)
		(width 0.18288)
		(layer "In6.Cu")
		(net "M_D_CPU1_SA_DQS_DN<0>")
	)
	(segment
		(start 67.568064 -296.466768)
		(end 67.568064 -298.500292)
		(width 0.18288)
		(layer "In6.Cu")
		(net "M_D_CPU1_SA_DQS_DN<0>")
	)
	(segment
		(start 32.097472 -313.341512)
		(end 31.653734 -313.341512)
		(width 0.18288)
		(layer "In6.Cu")
		(net "M_D_CPU1_SA_DQS_DN<0>")
	)
	(segment
		(start 84.07781 -280.650696)
		(end 84.054442 -280.650696)
		(width 0.088646)
		(layer "In6.Cu")
		(net "M_D_CPU1_SA_DQS_DN<0>")
	)
	(segment
		(start 19.817588 -312.753756)
		(end 19.327876 -312.26379)
		(width 0.18288)
		(layer "In6.Cu")
		(net "M_D_CPU1_SA_DQS_DN<0>")
	)
	(segment
		(start 78.192122 -285.666688)
		(end 78.192122 -285.84271)
		(width 0.18288)
		(layer "In6.Cu")
		(net "M_D_CPU1_SA_DQS_DN<0>")
	)
	(segment
		(start 73.432162 -290.60267)
		(end 73.044304 -290.990528)
		(width 0.18288)
		(layer "In6.Cu")
		(net "M_D_CPU1_SA_DQS_DN<0>")
	)
	(segment
		(start 84.371688 -280.710386)
		(end 84.1375 -280.710386)
		(width 0.088646)
		(layer "In6.Cu")
		(net "M_D_CPU1_SA_DQS_DN<0>")
	)
	(segment
		(start 76.852272 -287.18256)
		(end 76.67625 -287.18256)
		(width 0.18288)
		(layer "In6.Cu")
		(net "M_D_CPU1_SA_DQS_DN<0>")
	)
	(segment
		(start 72.48017 -291.37864)
		(end 72.48017 -291.554662)
		(width 0.18288)
		(layer "In6.Cu")
		(net "M_D_CPU1_SA_DQS_DN<0>")
	)
	(segment
		(start 94.60865 -275.259546)
		(end 94.335092 -275.259546)
		(width 0.088646)
		(layer "In6.Cu")
		(net "M_D_CPU1_SA_DQS_DN<0>")
	)
	(segment
		(start 21.110702 -312.491628)
		(end 20.694904 -312.491628)
		(width 0.18288)
		(layer "In6.Cu")
		(net "M_D_CPU1_SA_DQS_DN<0>")
	)
	(segment
		(start 20.432776 -312.753756)
		(end 19.817588 -312.753756)
		(width 0.18288)
		(layer "In6.Cu")
		(net "M_D_CPU1_SA_DQS_DN<0>")
	)
	(segment
		(start 37.77107 -314.130182)
		(end 36.993322 -314.452254)
		(width 0.18288)
		(layer "In6.Cu")
		(net "M_D_CPU1_SA_DQS_DN<0>")
	)
	(segment
		(start 84.1375 -280.710386)
		(end 84.07781 -280.650696)
		(width 0.088646)
		(layer "In6.Cu")
		(net "M_D_CPU1_SA_DQS_DN<0>")
	)
	(segment
		(start 31.032704 -313.58713)
		(end 30.07614 -312.630312)
		(width 0.18288)
		(layer "In6.Cu")
		(net "M_D_CPU1_SA_DQS_DN<0>")
	)
	(segment
		(start 65.965832 -298.892468)
		(end 65.668652 -299.189648)
		(width 0.18288)
		(layer "In6.Cu")
		(net "M_D_CPU1_SA_DQS_DN<0>")
	)
	(segment
		(start 48.02886 -308.437534)
		(end 48.02886 -309.08117)
		(width 0.18288)
		(layer "In6.Cu")
		(net "M_D_CPU1_SA_DQS_DN<0>")
	)
	(segment
		(start 47.757842 -309.352188)
		(end 47.502826 -309.352188)
		(width 0.18288)
		(layer "In6.Cu")
		(net "M_D_CPU1_SA_DQS_DN<0>")
	)
	(segment
		(start 30.07614 -312.630312)
		(end 28.76931 -312.089292)
		(width 0.18288)
		(layer "In6.Cu")
		(net "M_D_CPU1_SA_DQS_DN<0>")
	)
	(segment
		(start 78.192122 -285.84271)
		(end 77.804264 -286.230568)
		(width 0.18288)
		(layer "In6.Cu")
		(net "M_D_CPU1_SA_DQS_DN<0>")
	)
	(segment
		(start 74.384154 -289.650678)
		(end 73.996296 -290.038536)
		(width 0.18288)
		(layer "In6.Cu")
		(net "M_D_CPU1_SA_DQS_DN<0>")
	)
	(segment
		(start 31.408116 -313.58713)
		(end 31.032704 -313.58713)
		(width 0.18288)
		(layer "In6.Cu")
		(net "M_D_CPU1_SA_DQS_DN<0>")
	)
	(segment
		(start 79.708248 -284.326584)
		(end 79.532226 -284.326584)
		(width 0.18288)
		(layer "In6.Cu")
		(net "M_D_CPU1_SA_DQS_DN<0>")
	)
	(segment
		(start 18.315432 -312.114946)
		(end 17.778984 -312.336942)
		(width 0.18288)
		(layer "In6.Cu")
		(net "M_D_CPU1_SA_DQS_DN<0>")
	)
	(segment
		(start 56.593232 -304.279046)
		(end 53.997606 -305.355244)
		(width 0.18288)
		(layer "In6.Cu")
		(net "M_D_CPU1_SA_DQS_DN<0>")
	)
	(segment
		(start 17.059402 -312.336942)
		(end 16.789146 -312.066686)
		(width 0.18288)
		(layer "In6.Cu")
		(net "M_D_CPU1_SA_DQS_DN<0>")
	)
	(segment
		(start 76.67625 -287.18256)
		(end 76.288138 -287.570672)
		(width 0.18288)
		(layer "In6.Cu")
		(net "M_D_CPU1_SA_DQS_DN<0>")
	)
	(segment
		(start 19.327876 -312.26379)
		(end 18.967958 -312.114946)
		(width 0.18288)
		(layer "In6.Cu")
		(net "M_D_CPU1_SA_DQS_DN<0>")
	)
	(segment
		(start 86.657942 -277.847044)
		(end 86.64321 -277.838408)
		(width 0.088646)
		(layer "In6.Cu")
		(net "M_D_CPU1_SA_DQS_DN<0>")
	)
	(segment
		(start 74.772266 -289.086544)
		(end 74.384154 -289.474656)
		(width 0.18288)
		(layer "In6.Cu")
		(net "M_D_CPU1_SA_DQS_DN<0>")
	)
	(segment
		(start 73.432162 -290.426648)
		(end 73.432162 -290.60267)
		(width 0.18288)
		(layer "In6.Cu")
		(net "M_D_CPU1_SA_DQS_DN<0>")
	)
	(segment
		(start 48.768 -307.69814)
		(end 48.02886 -308.437534)
		(width 0.18288)
		(layer "In6.Cu")
		(net "M_D_CPU1_SA_DQS_DN<0>")
	)
	(segment
		(start 89.382092 -277.032974)
		(end 89.3699 -277.040086)
		(width 0.088646)
		(layer "In6.Cu")
		(net "M_D_CPU1_SA_DQS_DN<0>")
	)
	(segment
		(start 59.643772 -300.93793)
		(end 58.405268 -302.176434)
		(width 0.18288)
		(layer "In6.Cu")
		(net "M_D_CPU1_SA_DQS_DN<0>")
	)
	(segment
		(start 47.242476 -309.091838)
		(end 46.741334 -309.091838)
		(width 0.18288)
		(layer "In6.Cu")
		(net "M_D_CPU1_SA_DQS_DN<0>")
	)
	(segment
		(start 78.580234 -285.278576)
		(end 78.192122 -285.666688)
		(width 0.18288)
		(layer "In6.Cu")
		(net "M_D_CPU1_SA_DQS_DN<0>")
	)
	(segment
		(start 72.48017 -291.554662)
		(end 67.568064 -296.466768)
		(width 0.18288)
		(layer "In6.Cu")
		(net "M_D_CPU1_SA_DQS_DN<0>")
	)
	(segment
		(start 43.996864 -310.902604)
		(end 38.87851 -313.022742)
		(width 0.18288)
		(layer "In6.Cu")
		(net "M_D_CPU1_SA_DQS_DN<0>")
	)
	(segment
		(start 79.144114 -284.714696)
		(end 79.144114 -284.890718)
		(width 0.18288)
		(layer "In6.Cu")
		(net "M_D_CPU1_SA_DQS_DN<0>")
	)
	(segment
		(start 84.527898 -280.554176)
		(end 84.371688 -280.710386)
		(width 0.088646)
		(layer "In6.Cu")
		(net "M_D_CPU1_SA_DQS_DN<0>")
	)
	(segment
		(start 77.24013 -286.61868)
		(end 77.24013 -286.794702)
		(width 0.18288)
		(layer "In6.Cu")
		(net "M_D_CPU1_SA_DQS_DN<0>")
	)
	(segment
		(start 85.717888 -278.194516)
		(end 85.717888 -278.806656)
		(width 0.088646)
		(layer "In6.Cu")
		(net "M_D_CPU1_SA_DQS_DN<0>")
	)
	(segment
		(start 74.384154 -289.474656)
		(end 74.384154 -289.650678)
		(width 0.18288)
		(layer "In6.Cu")
		(net "M_D_CPU1_SA_DQS_DN<0>")
	)
	(segment
		(start 92.211906 -275.398992)
		(end 92.201492 -275.405088)
		(width 0.088646)
		(layer "In6.Cu")
		(net "M_D_CPU1_SA_DQS_DN<0>")
	)
	(segment
		(start 87.597742 -277.847044)
		(end 87.58301 -277.838408)
		(width 0.088646)
		(layer "In6.Cu")
		(net "M_D_CPU1_SA_DQS_DN<0>")
	)
	(segment
		(start 77.804264 -286.230568)
		(end 77.628242 -286.230568)
		(width 0.18288)
		(layer "In6.Cu")
		(net "M_D_CPU1_SA_DQS_DN<0>")
	)
	(segment
		(start 82.564224 -281.470608)
		(end 82.388202 -281.470608)
		(width 0.18288)
		(layer "In6.Cu")
		(net "M_D_CPU1_SA_DQS_DN<0>")
	)
	(segment
		(start 75.724258 -288.134552)
		(end 75.336146 -288.522664)
		(width 0.18288)
		(layer "In6.Cu")
		(net "M_D_CPU1_SA_DQS_DN<0>")
	)
	(segment
		(start 94.335092 -275.259546)
		(end 94.081854 -275.405342)
		(width 0.088646)
		(layer "In6.Cu")
		(net "M_D_CPU1_SA_DQS_DN<0>")
	)
	(segment
		(start 72.868282 -290.990528)
		(end 72.48017 -291.37864)
		(width 0.18288)
		(layer "In6.Cu")
		(net "M_D_CPU1_SA_DQS_DN<0>")
	)
	(segment
		(start 50.055272 -306.778914)
		(end 49.395888 -307.438044)
		(width 0.18288)
		(layer "In6.Cu")
		(net "M_D_CPU1_SA_DQS_DN<0>")
	)
	(segment
		(start 52.813966 -306.538884)
		(end 52.17922 -306.802028)
		(width 0.18288)
		(layer "In6.Cu")
		(net "M_D_CPU1_SA_DQS_DN<0>")
	)
	(segment
		(start 81.43621 -282.4226)
		(end 81.048098 -282.810712)
		(width 0.18288)
		(layer "In6.Cu")
		(net "M_D_CPU1_SA_DQS_DN<0>")
	)
	(segment
		(start 76.288138 -287.570672)
		(end 76.288138 -287.746694)
		(width 0.18288)
		(layer "In6.Cu")
		(net "M_D_CPU1_SA_DQS_DN<0>")
	)
	(arc
		(start 90.88755 -275.405088)
		(mid 90.610737 -275.329218)
		(end 90.332306 -275.398992)
		(width 0.088646)
		(layer "In6.Cu")
		(net "M_D_CPU1_SA_DQS_DN<0>")
	)
	(arc
		(start 92.76715 -275.405088)
		(mid 92.490337 -275.329218)
		(end 92.211906 -275.398992)
		(width 0.088646)
		(layer "In6.Cu")
		(net "M_D_CPU1_SA_DQS_DN<0>")
	)
	(arc
		(start 89.3699 -277.040086)
		(mid 89.17161 -277.246045)
		(end 89.09939 -277.522686)
		(width 0.088646)
		(layer "In6.Cu")
		(net "M_D_CPU1_SA_DQS_DN<0>")
	)
	(arc
		(start 88.52281 -277.838408)
		(mid 88.246335 -277.771088)
		(end 87.972138 -277.847044)
		(width 0.088646)
		(layer "In6.Cu")
		(net "M_D_CPU1_SA_DQS_DN<0>")
	)
	(arc
		(start 86.64321 -277.838408)
		(mid 86.366735 -277.771088)
		(end 86.092538 -277.847044)
		(width 0.088646)
		(layer "In6.Cu")
		(net "M_D_CPU1_SA_DQS_DN<0>")
	)
	(arc
		(start 93.141546 -275.405088)
		(mid 92.954348 -275.455231)
		(end 92.76715 -275.405088)
		(width 0.088646)
		(layer "In6.Cu")
		(net "M_D_CPU1_SA_DQS_DN<0>")
	)
	(arc
		(start 91.261946 -275.405088)
		(mid 91.074748 -275.455231)
		(end 90.88755 -275.405088)
		(width 0.088646)
		(layer "In6.Cu")
		(net "M_D_CPU1_SA_DQS_DN<0>")
	)
	(arc
		(start 90.321892 -275.405088)
		(mid 90.119606 -275.604069)
		(end 90.039444 -275.876258)
		(width 0.088646)
		(layer "In6.Cu")
		(net "M_D_CPU1_SA_DQS_DN<0>")
	)
	(arc
		(start 94.0816 -275.405088)
		(mid 93.894402 -275.455231)
		(end 93.707204 -275.405088)
		(width 0.088646)
		(layer "In6.Cu")
		(net "M_D_CPU1_SA_DQS_DN<0>")
	)
	(arc
		(start 87.972138 -277.847044)
		(mid 87.78494 -277.897187)
		(end 87.597742 -277.847044)
		(width 0.088646)
		(layer "In6.Cu")
		(net "M_D_CPU1_SA_DQS_DN<0>")
	)
	(arc
		(start 91.827096 -275.405088)
		(mid 91.550537 -275.329345)
		(end 91.27236 -275.398992)
		(width 0.088646)
		(layer "In6.Cu")
		(net "M_D_CPU1_SA_DQS_DN<0>")
	)
	(arc
		(start 93.70695 -275.405088)
		(mid 93.432721 -275.329163)
		(end 93.156278 -275.396452)
		(width 0.088646)
		(layer "In6.Cu")
		(net "M_D_CPU1_SA_DQS_DN<0>")
	)
	(arc
		(start 89.09939 -277.522686)
		(mid 89.051711 -277.705586)
		(end 88.920828 -277.841964)
		(width 0.088646)
		(layer "In6.Cu")
		(net "M_D_CPU1_SA_DQS_DN<0>")
	)
	(arc
		(start 87.032338 -277.847044)
		(mid 86.84514 -277.897187)
		(end 86.657942 -277.847044)
		(width 0.088646)
		(layer "In6.Cu")
		(net "M_D_CPU1_SA_DQS_DN<0>")
	)
	(arc
		(start 92.201492 -275.405088)
		(mid 92.014294 -275.455231)
		(end 91.827096 -275.405088)
		(width 0.088646)
		(layer "In6.Cu")
		(net "M_D_CPU1_SA_DQS_DN<0>")
	)
	(arc
		(start 89.569544 -276.708616)
		(mid 89.521865 -276.891516)
		(end 89.390982 -277.027894)
		(width 0.088646)
		(layer "In6.Cu")
		(net "M_D_CPU1_SA_DQS_DN<0>")
	)
	(arc
		(start 90.039444 -275.8948)
		(mid 89.991765 -276.0777)
		(end 89.860882 -276.214078)
		(width 0.088646)
		(layer "In6.Cu")
		(net "M_D_CPU1_SA_DQS_DN<0>")
	)
	(arc
		(start 88.911938 -277.847044)
		(mid 88.72474 -277.897187)
		(end 88.537542 -277.847044)
		(width 0.088646)
		(layer "In6.Cu")
		(net "M_D_CPU1_SA_DQS_DN<0>")
	)
	(arc
		(start 89.851992 -276.219158)
		(mid 89.647657 -276.421763)
		(end 89.569544 -276.69871)
		(width 0.088646)
		(layer "In6.Cu")
		(net "M_D_CPU1_SA_DQS_DN<0>")
	)
	(arc
		(start 86.092538 -277.847044)
		(mid 86.031198 -277.888068)
		(end 85.975698 -277.936706)
		(width 0.088646)
		(layer "In6.Cu")
		(net "M_D_CPU1_SA_DQS_DN<0>")
	)
	(arc
		(start 87.58301 -277.838408)
		(mid 87.306535 -277.771088)
		(end 87.032338 -277.847044)
		(width 0.088646)
		(layer "In6.Cu")
		(net "M_D_CPU1_SA_DQS_DN<0>")
	)
	(arc
		(start 94.763336 -275.218652)
		(mid 94.688651 -275.249157)
		(end 94.60865 -275.259546)
		(width 0.088646)
		(layer "In6.Cu")
		(net "M_D_CPU1_SA_DQS_DN<0>")
	)
	(segment
		(start 11.11631 -304.832766)
		(end 11.1252 -304.841656)
		(width 0.1016)
		(layer "F.Cu")
		(net "M_D_CPU1_SA_DQ<9>")
	)
	(segment
		(start 14.04493 -305.266598)
		(end 15.684246 -305.266598)
		(width 0.20066)
		(layer "F.Cu")
		(net "M_D_CPU1_SA_DQ<9>")
	)
	(segment
		(start 13.441426 -304.841656)
		(end 13.619988 -304.841656)
		(width 0.20066)
		(layer "F.Cu")
		(net "M_D_CPU1_SA_DQ<9>")
	)
	(segment
		(start 10.19048 -305.477926)
		(end 10.344912 -305.323494)
		(width 0.20066)
		(layer "F.Cu")
		(net "M_D_CPU1_SA_DQ<9>")
	)
	(segment
		(start 8.140446 -305.266598)
		(end 9.474708 -305.266598)
		(width 0.20066)
		(layer "F.Cu")
		(net "M_D_CPU1_SA_DQ<9>")
	)
	(segment
		(start 13.110718 -304.841656)
		(end 13.441426 -304.841656)
		(width 0.101854)
		(layer "F.Cu")
		(net "M_D_CPU1_SA_DQ<9>")
	)
	(segment
		(start 10.344912 -305.323494)
		(end 10.344912 -304.995326)
		(width 0.20066)
		(layer "F.Cu")
		(net "M_D_CPU1_SA_DQ<9>")
	)
	(segment
		(start 98.592894 -278.336248)
		(end 98.593148 -278.336502)
		(width 0.20066)
		(layer "F.Cu")
		(net "M_D_CPU1_SA_DQ<9>")
	)
	(segment
		(start 15.684246 -305.266598)
		(end 16.789146 -305.266598)
		(width 0.20066)
		(layer "F.Cu")
		(net "M_D_CPU1_SA_DQ<9>")
	)
	(segment
		(start 98.592894 -277.800562)
		(end 98.592894 -278.336248)
		(width 0.20066)
		(layer "F.Cu")
		(net "M_D_CPU1_SA_DQ<9>")
	)
	(segment
		(start 11.1252 -304.841656)
		(end 13.110718 -304.841656)
		(width 0.1016)
		(layer "F.Cu")
		(net "M_D_CPU1_SA_DQ<9>")
	)
	(segment
		(start 10.344912 -304.995326)
		(end 10.507472 -304.832766)
		(width 0.20066)
		(layer "F.Cu")
		(net "M_D_CPU1_SA_DQ<9>")
	)
	(segment
		(start 9.474708 -305.266598)
		(end 9.686036 -305.477926)
		(width 0.20066)
		(layer "F.Cu")
		(net "M_D_CPU1_SA_DQ<9>")
	)
	(segment
		(start 13.619988 -304.841656)
		(end 14.04493 -305.266598)
		(width 0.20066)
		(layer "F.Cu")
		(net "M_D_CPU1_SA_DQ<9>")
	)
	(segment
		(start 9.686036 -305.477926)
		(end 10.19048 -305.477926)
		(width 0.20066)
		(layer "F.Cu")
		(net "M_D_CPU1_SA_DQ<9>")
	)
	(segment
		(start 10.507472 -304.832766)
		(end 11.11631 -304.832766)
		(width 0.20066)
		(layer "F.Cu")
		(net "M_D_CPU1_SA_DQ<9>")
	)
	(segment
		(start 95.116396 -278.82596)
		(end 95.105982 -278.832056)
		(width 0.088646)
		(layer "In11.Cu")
		(net "M_D_CPU1_SA_DQ<9>")
	)
	(segment
		(start 34.492692 -311.641998)
		(end 31.272734 -311.641998)
		(width 0.18288)
		(layer "In11.Cu")
		(net "M_D_CPU1_SA_DQ<9>")
	)
	(segment
		(start 52.67198 -310.670448)
		(end 51.62169 -310.670448)
		(width 0.18288)
		(layer "In11.Cu")
		(net "M_D_CPU1_SA_DQ<9>")
	)
	(segment
		(start 51.500024 -310.792114)
		(end 50.430176 -310.792114)
		(width 0.18288)
		(layer "In11.Cu")
		(net "M_D_CPU1_SA_DQ<9>")
	)
	(segment
		(start 70.450964 -297.194224)
		(end 70.450964 -299.830744)
		(width 0.18288)
		(layer "In11.Cu")
		(net "M_D_CPU1_SA_DQ<9>")
	)
	(segment
		(start 56.653684 -308.133496)
		(end 55.660544 -308.133496)
		(width 0.18288)
		(layer "In11.Cu")
		(net "M_D_CPU1_SA_DQ<9>")
	)
	(segment
		(start 74.283316 -292.491922)
		(end 74.283316 -293.361872)
		(width 0.18288)
		(layer "In11.Cu")
		(net "M_D_CPU1_SA_DQ<9>")
	)
	(segment
		(start 60.78474 -304.840894)
		(end 60.126118 -305.499516)
		(width 0.18288)
		(layer "In11.Cu")
		(net "M_D_CPU1_SA_DQ<9>")
	)
	(segment
		(start 24.056848 -310.648096)
		(end 23.258526 -309.849774)
		(width 0.18288)
		(layer "In11.Cu")
		(net "M_D_CPU1_SA_DQ<9>")
	)
	(segment
		(start 21.579078 -305.691286)
		(end 20.05203 -305.691286)
		(width 0.18288)
		(layer "In11.Cu")
		(net "M_D_CPU1_SA_DQ<9>")
	)
	(segment
		(start 98.593148 -278.336502)
		(end 97.96526 -278.809196)
		(width 0.088646)
		(layer "In11.Cu")
		(net "M_D_CPU1_SA_DQ<9>")
	)
	(segment
		(start 51.62169 -310.670448)
		(end 51.500024 -310.792114)
		(width 0.18288)
		(layer "In11.Cu")
		(net "M_D_CPU1_SA_DQ<9>")
	)
	(segment
		(start 18.32102 -305.902614)
		(end 16.789146 -305.266598)
		(width 0.18288)
		(layer "In11.Cu")
		(net "M_D_CPU1_SA_DQ<9>")
	)
	(segment
		(start 85.718396 -280.453846)
		(end 85.709506 -280.458926)
		(width 0.088646)
		(layer "In11.Cu")
		(net "M_D_CPU1_SA_DQ<9>")
	)
	(segment
		(start 39.891462 -310.655462)
		(end 36.797742 -310.655462)
		(width 0.18288)
		(layer "In11.Cu")
		(net "M_D_CPU1_SA_DQ<9>")
	)
	(segment
		(start 23.258526 -306.345082)
		(end 22.44725 -305.533806)
		(width 0.18288)
		(layer "In11.Cu")
		(net "M_D_CPU1_SA_DQ<9>")
	)
	(segment
		(start 94.17685 -278.82596)
		(end 94.176596 -278.82596)
		(width 0.088646)
		(layer "In11.Cu")
		(net "M_D_CPU1_SA_DQ<9>")
	)
	(segment
		(start 35.342576 -310.792114)
		(end 34.492692 -311.641998)
		(width 0.18288)
		(layer "In11.Cu")
		(net "M_D_CPU1_SA_DQ<9>")
	)
	(segment
		(start 36.797742 -310.655462)
		(end 36.66109 -310.792114)
		(width 0.18288)
		(layer "In11.Cu")
		(net "M_D_CPU1_SA_DQ<9>")
	)
	(segment
		(start 88.537796 -278.82596)
		(end 88.528906 -278.83104)
		(width 0.088646)
		(layer "In11.Cu")
		(net "M_D_CPU1_SA_DQ<9>")
	)
	(segment
		(start 83.394042 -283.381196)
		(end 74.283316 -292.491922)
		(width 0.18288)
		(layer "In11.Cu")
		(net "M_D_CPU1_SA_DQ<9>")
	)
	(segment
		(start 86.188296 -279.639776)
		(end 86.179406 -279.644856)
		(width 0.088646)
		(layer "In11.Cu")
		(net "M_D_CPU1_SA_DQ<9>")
	)
	(segment
		(start 50.430176 -310.792114)
		(end 49.580292 -311.641998)
		(width 0.18288)
		(layer "In11.Cu")
		(net "M_D_CPU1_SA_DQ<9>")
	)
	(segment
		(start 83.769454 -283.381196)
		(end 83.394042 -283.381196)
		(width 0.18288)
		(layer "In11.Cu")
		(net "M_D_CPU1_SA_DQ<9>")
	)
	(segment
		(start 84.954364 -282.309062)
		(end 83.88223 -283.381196)
		(width 0.088646)
		(layer "In11.Cu")
		(net "M_D_CPU1_SA_DQ<9>")
	)
	(segment
		(start 96.995996 -278.82596)
		(end 96.981264 -278.834596)
		(width 0.088646)
		(layer "In11.Cu")
		(net "M_D_CPU1_SA_DQ<9>")
	)
	(segment
		(start 20.05203 -305.691286)
		(end 18.975578 -305.902614)
		(width 0.18288)
		(layer "In11.Cu")
		(net "M_D_CPU1_SA_DQ<9>")
	)
	(segment
		(start 85.530944 -281.585416)
		(end 84.954364 -282.161996)
		(width 0.088646)
		(layer "In11.Cu")
		(net "M_D_CPU1_SA_DQ<9>")
	)
	(segment
		(start 28.614878 -311.637426)
		(end 25.779984 -311.637426)
		(width 0.18288)
		(layer "In11.Cu")
		(net "M_D_CPU1_SA_DQ<9>")
	)
	(segment
		(start 65.02527 -304.73904)
		(end 62.67577 -304.73904)
		(width 0.18288)
		(layer "In11.Cu")
		(net "M_D_CPU1_SA_DQ<9>")
	)
	(segment
		(start 25.779984 -311.637426)
		(end 24.790654 -310.648096)
		(width 0.18288)
		(layer "In11.Cu")
		(net "M_D_CPU1_SA_DQ<9>")
	)
	(segment
		(start 97.93605 -278.82596)
		(end 97.935796 -278.82596)
		(width 0.088646)
		(layer "In11.Cu")
		(net "M_D_CPU1_SA_DQ<9>")
	)
	(segment
		(start 46.23308 -311.739026)
		(end 40.975026 -311.739026)
		(width 0.18288)
		(layer "In11.Cu")
		(net "M_D_CPU1_SA_DQ<9>")
	)
	(segment
		(start 59.287664 -305.499516)
		(end 56.653684 -308.133496)
		(width 0.18288)
		(layer "In11.Cu")
		(net "M_D_CPU1_SA_DQ<9>")
	)
	(segment
		(start 22.44725 -305.533806)
		(end 21.736558 -305.533806)
		(width 0.18288)
		(layer "In11.Cu")
		(net "M_D_CPU1_SA_DQ<9>")
	)
	(segment
		(start 46.330108 -311.641998)
		(end 46.23308 -311.739026)
		(width 0.18288)
		(layer "In11.Cu")
		(net "M_D_CPU1_SA_DQ<9>")
	)
	(segment
		(start 96.99625 -278.82596)
		(end 96.995996 -278.82596)
		(width 0.088646)
		(layer "In11.Cu")
		(net "M_D_CPU1_SA_DQ<9>")
	)
	(segment
		(start 54.399942 -308.942486)
		(end 52.67198 -310.670448)
		(width 0.18288)
		(layer "In11.Cu")
		(net "M_D_CPU1_SA_DQ<9>")
	)
	(segment
		(start 40.975026 -311.739026)
		(end 39.891462 -310.655462)
		(width 0.18288)
		(layer "In11.Cu")
		(net "M_D_CPU1_SA_DQ<9>")
	)
	(segment
		(start 66.665602 -303.760886)
		(end 66.433446 -303.993042)
		(width 0.18288)
		(layer "In11.Cu")
		(net "M_D_CPU1_SA_DQ<9>")
	)
	(segment
		(start 83.88223 -283.381196)
		(end 83.769454 -283.381196)
		(width 0.088646)
		(layer "In11.Cu")
		(net "M_D_CPU1_SA_DQ<9>")
	)
	(segment
		(start 60.126118 -305.499516)
		(end 59.287664 -305.499516)
		(width 0.18288)
		(layer "In11.Cu")
		(net "M_D_CPU1_SA_DQ<9>")
	)
	(segment
		(start 66.665602 -303.616106)
		(end 66.665602 -303.760886)
		(width 0.18288)
		(layer "In11.Cu")
		(net "M_D_CPU1_SA_DQ<9>")
	)
	(segment
		(start 85.530944 -280.778204)
		(end 85.530944 -281.585416)
		(width 0.088646)
		(layer "In11.Cu")
		(net "M_D_CPU1_SA_DQ<9>")
	)
	(segment
		(start 97.96526 -278.809196)
		(end 97.93605 -278.82596)
		(width 0.088646)
		(layer "In11.Cu")
		(net "M_D_CPU1_SA_DQ<9>")
	)
	(segment
		(start 96.056196 -278.82596)
		(end 96.041464 -278.834596)
		(width 0.088646)
		(layer "In11.Cu")
		(net "M_D_CPU1_SA_DQ<9>")
	)
	(segment
		(start 18.975578 -305.902614)
		(end 18.32102 -305.902614)
		(width 0.18288)
		(layer "In11.Cu")
		(net "M_D_CPU1_SA_DQ<9>")
	)
	(segment
		(start 88.350344 -279.150318)
		(end 88.350344 -279.160224)
		(width 0.088646)
		(layer "In11.Cu")
		(net "M_D_CPU1_SA_DQ<9>")
	)
	(segment
		(start 36.66109 -310.792114)
		(end 35.342576 -310.792114)
		(width 0.18288)
		(layer "In11.Cu")
		(net "M_D_CPU1_SA_DQ<9>")
	)
	(segment
		(start 54.851554 -308.942486)
		(end 54.399942 -308.942486)
		(width 0.18288)
		(layer "In11.Cu")
		(net "M_D_CPU1_SA_DQ<9>")
	)
	(segment
		(start 92.296996 -278.82596)
		(end 92.282264 -278.834596)
		(width 0.088646)
		(layer "In11.Cu")
		(net "M_D_CPU1_SA_DQ<9>")
	)
	(segment
		(start 74.283316 -293.361872)
		(end 70.450964 -297.194224)
		(width 0.18288)
		(layer "In11.Cu")
		(net "M_D_CPU1_SA_DQ<9>")
	)
	(segment
		(start 49.580292 -311.641998)
		(end 46.330108 -311.641998)
		(width 0.18288)
		(layer "In11.Cu")
		(net "M_D_CPU1_SA_DQ<9>")
	)
	(segment
		(start 62.67577 -304.73904)
		(end 62.573916 -304.840894)
		(width 0.18288)
		(layer "In11.Cu")
		(net "M_D_CPU1_SA_DQ<9>")
	)
	(segment
		(start 29.172662 -312.19521)
		(end 28.614878 -311.637426)
		(width 0.18288)
		(layer "In11.Cu")
		(net "M_D_CPU1_SA_DQ<9>")
	)
	(segment
		(start 86.000844 -279.964134)
		(end 86.000844 -279.982676)
		(width 0.088646)
		(layer "In11.Cu")
		(net "M_D_CPU1_SA_DQ<9>")
	)
	(segment
		(start 84.954364 -282.161996)
		(end 84.954364 -282.309062)
		(width 0.088646)
		(layer "In11.Cu")
		(net "M_D_CPU1_SA_DQ<9>")
	)
	(segment
		(start 65.771268 -303.993042)
		(end 65.02527 -304.73904)
		(width 0.18288)
		(layer "In11.Cu")
		(net "M_D_CPU1_SA_DQ<9>")
	)
	(segment
		(start 62.573916 -304.840894)
		(end 60.78474 -304.840894)
		(width 0.18288)
		(layer "In11.Cu")
		(net "M_D_CPU1_SA_DQ<9>")
	)
	(segment
		(start 55.660544 -308.133496)
		(end 54.851554 -308.942486)
		(width 0.18288)
		(layer "In11.Cu")
		(net "M_D_CPU1_SA_DQ<9>")
	)
	(segment
		(start 21.736558 -305.533806)
		(end 21.579078 -305.691286)
		(width 0.18288)
		(layer "In11.Cu")
		(net "M_D_CPU1_SA_DQ<9>")
	)
	(segment
		(start 30.719522 -312.19521)
		(end 29.172662 -312.19521)
		(width 0.18288)
		(layer "In11.Cu")
		(net "M_D_CPU1_SA_DQ<9>")
	)
	(segment
		(start 31.272734 -311.641998)
		(end 30.719522 -312.19521)
		(width 0.18288)
		(layer "In11.Cu")
		(net "M_D_CPU1_SA_DQ<9>")
	)
	(segment
		(start 66.433446 -303.993042)
		(end 65.771268 -303.993042)
		(width 0.18288)
		(layer "In11.Cu")
		(net "M_D_CPU1_SA_DQ<9>")
	)
	(segment
		(start 23.258526 -309.849774)
		(end 23.258526 -306.345082)
		(width 0.18288)
		(layer "In11.Cu")
		(net "M_D_CPU1_SA_DQ<9>")
	)
	(segment
		(start 93.236796 -278.82596)
		(end 93.222064 -278.834596)
		(width 0.088646)
		(layer "In11.Cu")
		(net "M_D_CPU1_SA_DQ<9>")
	)
	(segment
		(start 24.790654 -310.648096)
		(end 24.056848 -310.648096)
		(width 0.18288)
		(layer "In11.Cu")
		(net "M_D_CPU1_SA_DQ<9>")
	)
	(segment
		(start 70.450964 -299.830744)
		(end 66.665602 -303.616106)
		(width 0.18288)
		(layer "In11.Cu")
		(net "M_D_CPU1_SA_DQ<9>")
	)
	(arc
		(start 90.791792 -278.82596)
		(mid 90.604594 -278.775817)
		(end 90.417396 -278.82596)
		(width 0.088646)
		(layer "In11.Cu")
		(net "M_D_CPU1_SA_DQ<9>")
	)
	(arc
		(start 88.067896 -279.639776)
		(mid 87.785194 -279.715552)
		(end 87.502492 -279.639776)
		(width 0.088646)
		(layer "In11.Cu")
		(net "M_D_CPU1_SA_DQ<9>")
	)
	(arc
		(start 87.502492 -279.639776)
		(mid 87.315294 -279.589633)
		(end 87.128096 -279.639776)
		(width 0.088646)
		(layer "In11.Cu")
		(net "M_D_CPU1_SA_DQ<9>")
	)
	(arc
		(start 91.357196 -278.82596)
		(mid 91.074494 -278.901736)
		(end 90.791792 -278.82596)
		(width 0.088646)
		(layer "In11.Cu")
		(net "M_D_CPU1_SA_DQ<9>")
	)
	(arc
		(start 88.912192 -278.82596)
		(mid 88.724994 -278.775817)
		(end 88.537796 -278.82596)
		(width 0.088646)
		(layer "In11.Cu")
		(net "M_D_CPU1_SA_DQ<9>")
	)
	(arc
		(start 91.731592 -278.82596)
		(mid 91.544394 -278.775817)
		(end 91.357196 -278.82596)
		(width 0.088646)
		(layer "In11.Cu")
		(net "M_D_CPU1_SA_DQ<9>")
	)
	(arc
		(start 93.611192 -278.82596)
		(mid 93.423994 -278.775817)
		(end 93.236796 -278.82596)
		(width 0.088646)
		(layer "In11.Cu")
		(net "M_D_CPU1_SA_DQ<9>")
	)
	(arc
		(start 95.490792 -278.82596)
		(mid 95.303594 -278.775817)
		(end 95.116396 -278.82596)
		(width 0.088646)
		(layer "In11.Cu")
		(net "M_D_CPU1_SA_DQ<9>")
	)
	(arc
		(start 95.105982 -278.832056)
		(mid 94.827804 -278.901779)
		(end 94.551246 -278.82596)
		(width 0.088646)
		(layer "In11.Cu")
		(net "M_D_CPU1_SA_DQ<9>")
	)
	(arc
		(start 89.851992 -278.82596)
		(mid 89.664794 -278.775817)
		(end 89.477596 -278.82596)
		(width 0.088646)
		(layer "In11.Cu")
		(net "M_D_CPU1_SA_DQ<9>")
	)
	(arc
		(start 97.370392 -278.82596)
		(mid 97.183338 -278.77591)
		(end 96.99625 -278.82596)
		(width 0.088646)
		(layer "In11.Cu")
		(net "M_D_CPU1_SA_DQ<9>")
	)
	(arc
		(start 96.981264 -278.834596)
		(mid 96.704789 -278.901916)
		(end 96.430592 -278.82596)
		(width 0.088646)
		(layer "In11.Cu")
		(net "M_D_CPU1_SA_DQ<9>")
	)
	(arc
		(start 88.528906 -278.83104)
		(mid 88.397992 -278.9674)
		(end 88.350344 -279.150318)
		(width 0.088646)
		(layer "In11.Cu")
		(net "M_D_CPU1_SA_DQ<9>")
	)
	(arc
		(start 92.671392 -278.82596)
		(mid 92.484194 -278.775817)
		(end 92.296996 -278.82596)
		(width 0.088646)
		(layer "In11.Cu")
		(net "M_D_CPU1_SA_DQ<9>")
	)
	(arc
		(start 94.176596 -278.82596)
		(mid 93.893894 -278.901736)
		(end 93.611192 -278.82596)
		(width 0.088646)
		(layer "In11.Cu")
		(net "M_D_CPU1_SA_DQ<9>")
	)
	(arc
		(start 96.041464 -278.834596)
		(mid 95.764989 -278.901916)
		(end 95.490792 -278.82596)
		(width 0.088646)
		(layer "In11.Cu")
		(net "M_D_CPU1_SA_DQ<9>")
	)
	(arc
		(start 94.551246 -278.82596)
		(mid 94.364048 -278.775817)
		(end 94.17685 -278.82596)
		(width 0.088646)
		(layer "In11.Cu")
		(net "M_D_CPU1_SA_DQ<9>")
	)
	(arc
		(start 93.222064 -278.834596)
		(mid 92.945589 -278.901916)
		(end 92.671392 -278.82596)
		(width 0.088646)
		(layer "In11.Cu")
		(net "M_D_CPU1_SA_DQ<9>")
	)
	(arc
		(start 86.562692 -279.639776)
		(mid 86.375494 -279.589633)
		(end 86.188296 -279.639776)
		(width 0.088646)
		(layer "In11.Cu")
		(net "M_D_CPU1_SA_DQ<9>")
	)
	(arc
		(start 92.282264 -278.834596)
		(mid 92.005789 -278.901916)
		(end 91.731592 -278.82596)
		(width 0.088646)
		(layer "In11.Cu")
		(net "M_D_CPU1_SA_DQ<9>")
	)
	(arc
		(start 87.128096 -279.639776)
		(mid 86.845394 -279.715552)
		(end 86.562692 -279.639776)
		(width 0.088646)
		(layer "In11.Cu")
		(net "M_D_CPU1_SA_DQ<9>")
	)
	(arc
		(start 85.709506 -280.458926)
		(mid 85.578592 -280.595286)
		(end 85.530944 -280.778204)
		(width 0.088646)
		(layer "In11.Cu")
		(net "M_D_CPU1_SA_DQ<9>")
	)
	(arc
		(start 88.350344 -279.160224)
		(mid 88.272233 -279.437173)
		(end 88.067896 -279.639776)
		(width 0.088646)
		(layer "In11.Cu")
		(net "M_D_CPU1_SA_DQ<9>")
	)
	(arc
		(start 96.430592 -278.82596)
		(mid 96.243394 -278.775817)
		(end 96.056196 -278.82596)
		(width 0.088646)
		(layer "In11.Cu")
		(net "M_D_CPU1_SA_DQ<9>")
	)
	(arc
		(start 86.000844 -279.982676)
		(mid 85.920682 -280.254865)
		(end 85.718396 -280.453846)
		(width 0.088646)
		(layer "In11.Cu")
		(net "M_D_CPU1_SA_DQ<9>")
	)
	(arc
		(start 89.477596 -278.82596)
		(mid 89.194894 -278.901736)
		(end 88.912192 -278.82596)
		(width 0.088646)
		(layer "In11.Cu")
		(net "M_D_CPU1_SA_DQ<9>")
	)
	(arc
		(start 97.935796 -278.82596)
		(mid 97.653094 -278.901736)
		(end 97.370392 -278.82596)
		(width 0.088646)
		(layer "In11.Cu")
		(net "M_D_CPU1_SA_DQ<9>")
	)
	(arc
		(start 86.179406 -279.644856)
		(mid 86.048492 -279.781216)
		(end 86.000844 -279.964134)
		(width 0.088646)
		(layer "In11.Cu")
		(net "M_D_CPU1_SA_DQ<9>")
	)
	(arc
		(start 90.417396 -278.82596)
		(mid 90.134694 -278.901736)
		(end 89.851992 -278.82596)
		(width 0.088646)
		(layer "In11.Cu")
		(net "M_D_CPU1_SA_DQ<9>")
	)
	(segment
		(start 9.474708 -306.96662)
		(end 9.713468 -307.20538)
		(width 0.20066)
		(layer "F.Cu")
		(net "M_D_CPU1_SA_DQ<8>")
	)
	(segment
		(start 13.890244 -306.541678)
		(end 14.315186 -306.96662)
		(width 0.20066)
		(layer "F.Cu")
		(net "M_D_CPU1_SA_DQ<8>")
	)
	(segment
		(start 9.713468 -307.20538)
		(end 10.172192 -307.20538)
		(width 0.20066)
		(layer "F.Cu")
		(net "M_D_CPU1_SA_DQ<8>")
	)
	(segment
		(start 99.063048 -278.614378)
		(end 99.063048 -279.150064)
		(width 0.20066)
		(layer "F.Cu")
		(net "M_D_CPU1_SA_DQ<8>")
	)
	(segment
		(start 10.344912 -307.03266)
		(end 10.344912 -306.7431)
		(width 0.20066)
		(layer "F.Cu")
		(net "M_D_CPU1_SA_DQ<8>")
	)
	(segment
		(start 11.124438 -306.541678)
		(end 11.372342 -306.541678)
		(width 0.101854)
		(layer "F.Cu")
		(net "M_D_CPU1_SA_DQ<8>")
	)
	(segment
		(start 99.063048 -279.150064)
		(end 99.062794 -279.150318)
		(width 0.20066)
		(layer "F.Cu")
		(net "M_D_CPU1_SA_DQ<8>")
	)
	(segment
		(start 11.372342 -306.541678)
		(end 13.441426 -306.541678)
		(width 0.1016)
		(layer "F.Cu")
		(net "M_D_CPU1_SA_DQ<8>")
	)
	(segment
		(start 10.344912 -306.7431)
		(end 10.554462 -306.53355)
		(width 0.20066)
		(layer "F.Cu")
		(net "M_D_CPU1_SA_DQ<8>")
	)
	(segment
		(start 8.140446 -306.96662)
		(end 9.474708 -306.96662)
		(width 0.20066)
		(layer "F.Cu")
		(net "M_D_CPU1_SA_DQ<8>")
	)
	(segment
		(start 15.684246 -306.96662)
		(end 16.789146 -306.96662)
		(width 0.20066)
		(layer "F.Cu")
		(net "M_D_CPU1_SA_DQ<8>")
	)
	(segment
		(start 13.441426 -306.541678)
		(end 13.890244 -306.541678)
		(width 0.20066)
		(layer "F.Cu")
		(net "M_D_CPU1_SA_DQ<8>")
	)
	(segment
		(start 10.554462 -306.53355)
		(end 11.11631 -306.53355)
		(width 0.20066)
		(layer "F.Cu")
		(net "M_D_CPU1_SA_DQ<8>")
	)
	(segment
		(start 11.11631 -306.53355)
		(end 11.124438 -306.541678)
		(width 0.101854)
		(layer "F.Cu")
		(net "M_D_CPU1_SA_DQ<8>")
	)
	(segment
		(start 14.315186 -306.96662)
		(end 15.684246 -306.96662)
		(width 0.20066)
		(layer "F.Cu")
		(net "M_D_CPU1_SA_DQ<8>")
	)
	(segment
		(start 10.172192 -307.20538)
		(end 10.344912 -307.03266)
		(width 0.20066)
		(layer "F.Cu")
		(net "M_D_CPU1_SA_DQ<8>")
	)
	(segment
		(start 85.433154 -282.673044)
		(end 84.24799 -283.858208)
		(width 0.088646)
		(layer "In11.Cu")
		(net "M_D_CPU1_SA_DQ<8>")
	)
	(segment
		(start 43.616626 -313.466226)
		(end 41.483026 -313.466226)
		(width 0.18288)
		(layer "In11.Cu")
		(net "M_D_CPU1_SA_DQ<8>")
	)
	(segment
		(start 31.473902 -314.19165)
		(end 30.828488 -314.267596)
		(width 0.18288)
		(layer "In11.Cu")
		(net "M_D_CPU1_SA_DQ<8>")
	)
	(segment
		(start 37.53739 -313.125358)
		(end 36.662106 -313.168284)
		(width 0.18288)
		(layer "In11.Cu")
		(net "M_D_CPU1_SA_DQ<8>")
	)
	(segment
		(start 30.828488 -314.267596)
		(end 29.500576 -314.216542)
		(width 0.18288)
		(layer "In11.Cu")
		(net "M_D_CPU1_SA_DQ<8>")
	)
	(segment
		(start 95.975678 -279.648412)
		(end 95.960946 -279.639776)
		(width 0.088646)
		(layer "In11.Cu")
		(net "M_D_CPU1_SA_DQ<8>")
	)
	(segment
		(start 24.961342 -313.265312)
		(end 21.516086 -309.820056)
		(width 0.18288)
		(layer "In11.Cu")
		(net "M_D_CPU1_SA_DQ<8>")
	)
	(segment
		(start 65.720976 -305.692048)
		(end 65.033906 -306.379118)
		(width 0.18288)
		(layer "In11.Cu")
		(net "M_D_CPU1_SA_DQ<8>")
	)
	(segment
		(start 48.256444 -313.411108)
		(end 48.063404 -313.604148)
		(width 0.18288)
		(layer "In11.Cu")
		(net "M_D_CPU1_SA_DQ<8>")
	)
	(segment
		(start 48.571404 -313.411108)
		(end 48.256444 -313.411108)
		(width 0.18288)
		(layer "In11.Cu")
		(net "M_D_CPU1_SA_DQ<8>")
	)
	(segment
		(start 48.764444 -313.986672)
		(end 48.764444 -313.604148)
		(width 0.18288)
		(layer "In11.Cu")
		(net "M_D_CPU1_SA_DQ<8>")
	)
	(segment
		(start 21.516086 -309.820056)
		(end 21.516086 -309.400448)
		(width 0.18288)
		(layer "In11.Cu")
		(net "M_D_CPU1_SA_DQ<8>")
	)
	(segment
		(start 19.48688 -308.0512)
		(end 17.873726 -308.0512)
		(width 0.18288)
		(layer "In11.Cu")
		(net "M_D_CPU1_SA_DQ<8>")
	)
	(segment
		(start 54.406546 -310.783986)
		(end 51.848258 -313.342274)
		(width 0.18288)
		(layer "In11.Cu")
		(net "M_D_CPU1_SA_DQ<8>")
	)
	(segment
		(start 93.15196 -279.645872)
		(end 93.141546 -279.639776)
		(width 0.088646)
		(layer "In11.Cu")
		(net "M_D_CPU1_SA_DQ<8>")
	)
	(segment
		(start 91.276678 -279.648412)
		(end 91.261946 -279.639776)
		(width 0.088646)
		(layer "In11.Cu")
		(net "M_D_CPU1_SA_DQ<8>")
	)
	(segment
		(start 86.000844 -281.746198)
		(end 85.433154 -282.313888)
		(width 0.088646)
		(layer "In11.Cu")
		(net "M_D_CPU1_SA_DQ<8>")
	)
	(segment
		(start 65.033906 -306.379118)
		(end 62.65037 -306.379118)
		(width 0.18288)
		(layer "In11.Cu")
		(net "M_D_CPU1_SA_DQ<8>")
	)
	(segment
		(start 98.64725 -279.379426)
		(end 98.60153 -279.451816)
		(width 0.088646)
		(layer "In11.Cu")
		(net "M_D_CPU1_SA_DQ<8>")
	)
	(segment
		(start 60.842652 -306.54244)
		(end 60.108846 -307.276246)
		(width 0.18288)
		(layer "In11.Cu")
		(net "M_D_CPU1_SA_DQ<8>")
	)
	(segment
		(start 48.957484 -314.179712)
		(end 48.764444 -313.986672)
		(width 0.18288)
		(layer "In11.Cu")
		(net "M_D_CPU1_SA_DQ<8>")
	)
	(segment
		(start 48.063404 -313.976004)
		(end 47.844456 -314.194952)
		(width 0.18288)
		(layer "In11.Cu")
		(net "M_D_CPU1_SA_DQ<8>")
	)
	(segment
		(start 46.255686 -314.194952)
		(end 45.37456 -313.313826)
		(width 0.18288)
		(layer "In11.Cu")
		(net "M_D_CPU1_SA_DQ<8>")
	)
	(segment
		(start 59.009026 -308.005226)
		(end 58.234326 -308.271926)
		(width 0.18288)
		(layer "In11.Cu")
		(net "M_D_CPU1_SA_DQ<8>")
	)
	(segment
		(start 20.52701 -309.09133)
		(end 19.48688 -308.0512)
		(width 0.18288)
		(layer "In11.Cu")
		(net "M_D_CPU1_SA_DQ<8>")
	)
	(segment
		(start 89.007696 -279.639776)
		(end 88.998806 -279.644856)
		(width 0.088646)
		(layer "In11.Cu")
		(net "M_D_CPU1_SA_DQ<8>")
	)
	(segment
		(start 84.24799 -283.858208)
		(end 84.24799 -283.964888)
		(width 0.088646)
		(layer "In11.Cu")
		(net "M_D_CPU1_SA_DQ<8>")
	)
	(segment
		(start 40.263826 -313.263026)
		(end 38.988746 -313.263026)
		(width 0.18288)
		(layer "In11.Cu")
		(net "M_D_CPU1_SA_DQ<8>")
	)
	(segment
		(start 48.764444 -313.604148)
		(end 48.571404 -313.411108)
		(width 0.18288)
		(layer "In11.Cu")
		(net "M_D_CPU1_SA_DQ<8>")
	)
	(segment
		(start 55.241444 -310.283352)
		(end 54.907942 -310.616854)
		(width 0.18288)
		(layer "In11.Cu")
		(net "M_D_CPU1_SA_DQ<8>")
	)
	(segment
		(start 21.516086 -309.400448)
		(end 21.206968 -309.09133)
		(width 0.18288)
		(layer "In11.Cu")
		(net "M_D_CPU1_SA_DQ<8>")
	)
	(segment
		(start 86.188296 -281.267662)
		(end 86.179406 -281.272742)
		(width 0.088646)
		(layer "In11.Cu")
		(net "M_D_CPU1_SA_DQ<8>")
	)
	(segment
		(start 58.234326 -308.271926)
		(end 56.917082 -309.58917)
		(width 0.18288)
		(layer "In11.Cu")
		(net "M_D_CPU1_SA_DQ<8>")
	)
	(segment
		(start 36.662106 -313.168284)
		(end 36.631372 -313.18073)
		(width 0.18288)
		(layer "In11.Cu")
		(net "M_D_CPU1_SA_DQ<8>")
	)
	(segment
		(start 85.433154 -282.313888)
		(end 85.433154 -282.673044)
		(width 0.088646)
		(layer "In11.Cu")
		(net "M_D_CPU1_SA_DQ<8>")
	)
	(segment
		(start 90.332306 -279.645872)
		(end 90.321892 -279.639776)
		(width 0.088646)
		(layer "In11.Cu")
		(net "M_D_CPU1_SA_DQ<8>")
	)
	(segment
		(start 41.483026 -313.466226)
		(end 40.263826 -313.263026)
		(width 0.18288)
		(layer "In11.Cu")
		(net "M_D_CPU1_SA_DQ<8>")
	)
	(segment
		(start 75.299316 -292.913562)
		(end 75.299316 -293.917624)
		(width 0.18288)
		(layer "In11.Cu")
		(net "M_D_CPU1_SA_DQ<8>")
	)
	(segment
		(start 36.631372 -313.18073)
		(end 36.387786 -313.341766)
		(width 0.18288)
		(layer "In11.Cu")
		(net "M_D_CPU1_SA_DQ<8>")
	)
	(segment
		(start 50.813208 -313.342274)
		(end 49.97577 -314.179712)
		(width 0.18288)
		(layer "In11.Cu")
		(net "M_D_CPU1_SA_DQ<8>")
	)
	(segment
		(start 44.446444 -313.313826)
		(end 43.616626 -313.466226)
		(width 0.18288)
		(layer "In11.Cu")
		(net "M_D_CPU1_SA_DQ<8>")
	)
	(segment
		(start 36.387786 -313.341766)
		(end 35.689286 -313.341766)
		(width 0.18288)
		(layer "In11.Cu")
		(net "M_D_CPU1_SA_DQ<8>")
	)
	(segment
		(start 51.848258 -313.342274)
		(end 50.813208 -313.342274)
		(width 0.18288)
		(layer "In11.Cu")
		(net "M_D_CPU1_SA_DQ<8>")
	)
	(segment
		(start 56.917082 -309.58917)
		(end 55.241444 -310.283352)
		(width 0.18288)
		(layer "In11.Cu")
		(net "M_D_CPU1_SA_DQ<8>")
	)
	(segment
		(start 66.347086 -305.692048)
		(end 65.720976 -305.692048)
		(width 0.18288)
		(layer "In11.Cu")
		(net "M_D_CPU1_SA_DQ<8>")
	)
	(segment
		(start 92.216478 -279.648412)
		(end 92.201746 -279.639776)
		(width 0.088646)
		(layer "In11.Cu")
		(net "M_D_CPU1_SA_DQ<8>")
	)
	(segment
		(start 83.761326 -284.451552)
		(end 75.299316 -292.913562)
		(width 0.18288)
		(layer "In11.Cu")
		(net "M_D_CPU1_SA_DQ<8>")
	)
	(segment
		(start 86.470744 -280.778204)
		(end 86.470744 -280.78811)
		(width 0.088646)
		(layer "In11.Cu")
		(net "M_D_CPU1_SA_DQ<8>")
	)
	(segment
		(start 38.988746 -313.263026)
		(end 37.53739 -313.125358)
		(width 0.18288)
		(layer "In11.Cu")
		(net "M_D_CPU1_SA_DQ<8>")
	)
	(segment
		(start 86.000844 -281.59202)
		(end 86.000844 -281.746198)
		(width 0.088646)
		(layer "In11.Cu")
		(net "M_D_CPU1_SA_DQ<8>")
	)
	(segment
		(start 45.37456 -313.313826)
		(end 44.446444 -313.313826)
		(width 0.18288)
		(layer "In11.Cu")
		(net "M_D_CPU1_SA_DQ<8>")
	)
	(segment
		(start 75.299316 -293.917624)
		(end 71.50227 -297.71467)
		(width 0.18288)
		(layer "In11.Cu")
		(net "M_D_CPU1_SA_DQ<8>")
	)
	(segment
		(start 29.500576 -314.216542)
		(end 24.961342 -313.265312)
		(width 0.18288)
		(layer "In11.Cu")
		(net "M_D_CPU1_SA_DQ<8>")
	)
	(segment
		(start 86.658196 -280.453846)
		(end 86.649306 -280.458926)
		(width 0.088646)
		(layer "In11.Cu")
		(net "M_D_CPU1_SA_DQ<8>")
	)
	(segment
		(start 35.689286 -313.341766)
		(end 32.392366 -314.19165)
		(width 0.18288)
		(layer "In11.Cu")
		(net "M_D_CPU1_SA_DQ<8>")
	)
	(segment
		(start 48.063404 -313.604148)
		(end 48.063404 -313.976004)
		(width 0.18288)
		(layer "In11.Cu")
		(net "M_D_CPU1_SA_DQ<8>")
	)
	(segment
		(start 17.873726 -308.0512)
		(end 16.789146 -306.96662)
		(width 0.18288)
		(layer "In11.Cu")
		(net "M_D_CPU1_SA_DQ<8>")
	)
	(segment
		(start 96.915478 -279.648412)
		(end 96.900746 -279.639776)
		(width 0.088646)
		(layer "In11.Cu")
		(net "M_D_CPU1_SA_DQ<8>")
	)
	(segment
		(start 84.24799 -283.964888)
		(end 83.761326 -284.451552)
		(width 0.088646)
		(layer "In11.Cu")
		(net "M_D_CPU1_SA_DQ<8>")
	)
	(segment
		(start 60.108846 -307.276246)
		(end 59.738006 -307.276246)
		(width 0.18288)
		(layer "In11.Cu")
		(net "M_D_CPU1_SA_DQ<8>")
	)
	(segment
		(start 49.97577 -314.179712)
		(end 48.957484 -314.179712)
		(width 0.18288)
		(layer "In11.Cu")
		(net "M_D_CPU1_SA_DQ<8>")
	)
	(segment
		(start 54.907942 -310.616854)
		(end 54.406546 -310.783986)
		(width 0.18288)
		(layer "In11.Cu")
		(net "M_D_CPU1_SA_DQ<8>")
	)
	(segment
		(start 21.206968 -309.09133)
		(end 20.52701 -309.09133)
		(width 0.18288)
		(layer "In11.Cu")
		(net "M_D_CPU1_SA_DQ<8>")
	)
	(segment
		(start 71.50227 -297.71467)
		(end 71.50227 -300.536864)
		(width 0.18288)
		(layer "In11.Cu")
		(net "M_D_CPU1_SA_DQ<8>")
	)
	(segment
		(start 47.844456 -314.194952)
		(end 46.255686 -314.194952)
		(width 0.18288)
		(layer "In11.Cu")
		(net "M_D_CPU1_SA_DQ<8>")
	)
	(segment
		(start 71.50227 -300.536864)
		(end 66.347086 -305.692048)
		(width 0.18288)
		(layer "In11.Cu")
		(net "M_D_CPU1_SA_DQ<8>")
	)
	(segment
		(start 62.65037 -306.379118)
		(end 62.487048 -306.54244)
		(width 0.18288)
		(layer "In11.Cu")
		(net "M_D_CPU1_SA_DQ<8>")
	)
	(segment
		(start 32.392366 -314.19165)
		(end 31.473902 -314.19165)
		(width 0.18288)
		(layer "In11.Cu")
		(net "M_D_CPU1_SA_DQ<8>")
	)
	(segment
		(start 88.820244 -279.964134)
		(end 88.820244 -279.982676)
		(width 0.088646)
		(layer "In11.Cu")
		(net "M_D_CPU1_SA_DQ<8>")
	)
	(segment
		(start 62.487048 -306.54244)
		(end 60.842652 -306.54244)
		(width 0.18288)
		(layer "In11.Cu")
		(net "M_D_CPU1_SA_DQ<8>")
	)
	(segment
		(start 95.031306 -279.645872)
		(end 95.020892 -279.639776)
		(width 0.088646)
		(layer "In11.Cu")
		(net "M_D_CPU1_SA_DQ<8>")
	)
	(segment
		(start 59.738006 -307.276246)
		(end 59.009026 -308.005226)
		(width 0.18288)
		(layer "In11.Cu")
		(net "M_D_CPU1_SA_DQ<8>")
	)
	(segment
		(start 94.646496 -279.639776)
		(end 94.631764 -279.648412)
		(width 0.088646)
		(layer "In11.Cu")
		(net "M_D_CPU1_SA_DQ<8>")
	)
	(arc
		(start 98.60153 -279.451816)
		(mid 98.515173 -279.55769)
		(end 98.40595 -279.639776)
		(width 0.088646)
		(layer "In11.Cu")
		(net "M_D_CPU1_SA_DQ<8>")
	)
	(arc
		(start 88.537796 -280.453846)
		(mid 88.255094 -280.529588)
		(end 87.972392 -280.453846)
		(width 0.088646)
		(layer "In11.Cu")
		(net "M_D_CPU1_SA_DQ<8>")
	)
	(arc
		(start 86.649306 -280.458926)
		(mid 86.518392 -280.595286)
		(end 86.470744 -280.778204)
		(width 0.088646)
		(layer "In11.Cu")
		(net "M_D_CPU1_SA_DQ<8>")
	)
	(arc
		(start 88.820244 -279.982676)
		(mid 88.740082 -280.254865)
		(end 88.537796 -280.453846)
		(width 0.088646)
		(layer "In11.Cu")
		(net "M_D_CPU1_SA_DQ<8>")
	)
	(arc
		(start 86.179406 -281.272742)
		(mid 86.048492 -281.409102)
		(end 86.000844 -281.59202)
		(width 0.088646)
		(layer "In11.Cu")
		(net "M_D_CPU1_SA_DQ<8>")
	)
	(arc
		(start 87.597996 -280.453846)
		(mid 87.315294 -280.529588)
		(end 87.032592 -280.453846)
		(width 0.088646)
		(layer "In11.Cu")
		(net "M_D_CPU1_SA_DQ<8>")
	)
	(arc
		(start 92.201746 -279.639776)
		(mid 92.014548 -279.589633)
		(end 91.82735 -279.639776)
		(width 0.088646)
		(layer "In11.Cu")
		(net "M_D_CPU1_SA_DQ<8>")
	)
	(arc
		(start 92.76715 -279.639776)
		(mid 92.492951 -279.715611)
		(end 92.216478 -279.648412)
		(width 0.088646)
		(layer "In11.Cu")
		(net "M_D_CPU1_SA_DQ<8>")
	)
	(arc
		(start 94.631764 -279.648412)
		(mid 94.355289 -279.715732)
		(end 94.081092 -279.639776)
		(width 0.088646)
		(layer "In11.Cu")
		(net "M_D_CPU1_SA_DQ<8>")
	)
	(arc
		(start 97.46615 -279.639776)
		(mid 97.191951 -279.715611)
		(end 96.915478 -279.648412)
		(width 0.088646)
		(layer "In11.Cu")
		(net "M_D_CPU1_SA_DQ<8>")
	)
	(arc
		(start 90.321892 -279.639776)
		(mid 90.134694 -279.589633)
		(end 89.947496 -279.639776)
		(width 0.088646)
		(layer "In11.Cu")
		(net "M_D_CPU1_SA_DQ<8>")
	)
	(arc
		(start 89.382092 -279.639776)
		(mid 89.194894 -279.589633)
		(end 89.007696 -279.639776)
		(width 0.088646)
		(layer "In11.Cu")
		(net "M_D_CPU1_SA_DQ<8>")
	)
	(arc
		(start 87.032592 -280.453846)
		(mid 86.845394 -280.403703)
		(end 86.658196 -280.453846)
		(width 0.088646)
		(layer "In11.Cu")
		(net "M_D_CPU1_SA_DQ<8>")
	)
	(arc
		(start 90.88755 -279.639776)
		(mid 90.610737 -279.715646)
		(end 90.332306 -279.645872)
		(width 0.088646)
		(layer "In11.Cu")
		(net "M_D_CPU1_SA_DQ<8>")
	)
	(arc
		(start 96.900746 -279.639776)
		(mid 96.713548 -279.589633)
		(end 96.52635 -279.639776)
		(width 0.088646)
		(layer "In11.Cu")
		(net "M_D_CPU1_SA_DQ<8>")
	)
	(arc
		(start 91.82735 -279.639776)
		(mid 91.553151 -279.715611)
		(end 91.276678 -279.648412)
		(width 0.088646)
		(layer "In11.Cu")
		(net "M_D_CPU1_SA_DQ<8>")
	)
	(arc
		(start 99.062794 -279.150318)
		(mid 98.825525 -279.211383)
		(end 98.64725 -279.379426)
		(width 0.088646)
		(layer "In11.Cu")
		(net "M_D_CPU1_SA_DQ<8>")
	)
	(arc
		(start 93.706696 -279.639776)
		(mid 93.430137 -279.715519)
		(end 93.15196 -279.645872)
		(width 0.088646)
		(layer "In11.Cu")
		(net "M_D_CPU1_SA_DQ<8>")
	)
	(arc
		(start 89.947496 -279.639776)
		(mid 89.664794 -279.715552)
		(end 89.382092 -279.639776)
		(width 0.088646)
		(layer "In11.Cu")
		(net "M_D_CPU1_SA_DQ<8>")
	)
	(arc
		(start 95.020892 -279.639776)
		(mid 94.833694 -279.589633)
		(end 94.646496 -279.639776)
		(width 0.088646)
		(layer "In11.Cu")
		(net "M_D_CPU1_SA_DQ<8>")
	)
	(arc
		(start 98.40595 -279.639776)
		(mid 98.123248 -279.715552)
		(end 97.840546 -279.639776)
		(width 0.088646)
		(layer "In11.Cu")
		(net "M_D_CPU1_SA_DQ<8>")
	)
	(arc
		(start 95.960946 -279.639776)
		(mid 95.773748 -279.589633)
		(end 95.58655 -279.639776)
		(width 0.088646)
		(layer "In11.Cu")
		(net "M_D_CPU1_SA_DQ<8>")
	)
	(arc
		(start 87.972392 -280.453846)
		(mid 87.785194 -280.403703)
		(end 87.597996 -280.453846)
		(width 0.088646)
		(layer "In11.Cu")
		(net "M_D_CPU1_SA_DQ<8>")
	)
	(arc
		(start 93.141546 -279.639776)
		(mid 92.954348 -279.589633)
		(end 92.76715 -279.639776)
		(width 0.088646)
		(layer "In11.Cu")
		(net "M_D_CPU1_SA_DQ<8>")
	)
	(arc
		(start 88.998806 -279.644856)
		(mid 88.867892 -279.781216)
		(end 88.820244 -279.964134)
		(width 0.088646)
		(layer "In11.Cu")
		(net "M_D_CPU1_SA_DQ<8>")
	)
	(arc
		(start 96.52635 -279.639776)
		(mid 96.252151 -279.715611)
		(end 95.975678 -279.648412)
		(width 0.088646)
		(layer "In11.Cu")
		(net "M_D_CPU1_SA_DQ<8>")
	)
	(arc
		(start 91.261946 -279.639776)
		(mid 91.074748 -279.589633)
		(end 90.88755 -279.639776)
		(width 0.088646)
		(layer "In11.Cu")
		(net "M_D_CPU1_SA_DQ<8>")
	)
	(arc
		(start 86.470744 -280.78811)
		(mid 86.392633 -281.065059)
		(end 86.188296 -281.267662)
		(width 0.088646)
		(layer "In11.Cu")
		(net "M_D_CPU1_SA_DQ<8>")
	)
	(arc
		(start 95.58655 -279.639776)
		(mid 95.309737 -279.715646)
		(end 95.031306 -279.645872)
		(width 0.088646)
		(layer "In11.Cu")
		(net "M_D_CPU1_SA_DQ<8>")
	)
	(arc
		(start 94.081092 -279.639776)
		(mid 93.893894 -279.589633)
		(end 93.706696 -279.639776)
		(width 0.088646)
		(layer "In11.Cu")
		(net "M_D_CPU1_SA_DQ<8>")
	)
	(arc
		(start 97.840546 -279.639776)
		(mid 97.653348 -279.589633)
		(end 97.46615 -279.639776)
		(width 0.088646)
		(layer "In11.Cu")
		(net "M_D_CPU1_SA_DQ<8>")
	)
	(segment
		(start 18.968212 -307.816758)
		(end 19.784314 -307.816758)
		(width 0.20066)
		(layer "F.Cu")
		(net "M_D_CPU1_SA_DQ<7>")
	)
	(segment
		(start 14.560042 -308.255924)
		(end 14.574266 -308.2417)
		(width 0.101854)
		(layer "F.Cu")
		(net "M_D_CPU1_SA_DQ<7>")
	)
	(segment
		(start 14.574266 -308.2417)
		(end 14.812264 -308.2417)
		(width 0.101854)
		(layer "F.Cu")
		(net "M_D_CPU1_SA_DQ<7>")
	)
	(segment
		(start 12.240514 -307.816758)
		(end 13.937742 -307.816758)
		(width 0.20066)
		(layer "F.Cu")
		(net "M_D_CPU1_SA_DQ<7>")
	)
	(segment
		(start 14.063726 -308.11343)
		(end 14.20622 -308.255924)
		(width 0.20066)
		(layer "F.Cu")
		(net "M_D_CPU1_SA_DQ<7>")
	)
	(segment
		(start 20.889214 -307.816758)
		(end 19.784314 -307.816758)
		(width 0.20066)
		(layer "F.Cu")
		(net "M_D_CPU1_SA_DQ<7>")
	)
	(segment
		(start 14.812264 -308.2417)
		(end 16.885158 -308.2417)
		(width 0.1016)
		(layer "F.Cu")
		(net "M_D_CPU1_SA_DQ<7>")
	)
	(segment
		(start 18.102326 -307.81244)
		(end 18.314162 -308.024276)
		(width 0.20066)
		(layer "F.Cu")
		(net "M_D_CPU1_SA_DQ<7>")
	)
	(segment
		(start 14.20622 -308.255924)
		(end 14.560042 -308.255924)
		(width 0.20066)
		(layer "F.Cu")
		(net "M_D_CPU1_SA_DQ<7>")
	)
	(segment
		(start 17.578578 -308.092602)
		(end 17.578578 -307.940964)
		(width 0.20066)
		(layer "F.Cu")
		(net "M_D_CPU1_SA_DQ<7>")
	)
	(segment
		(start 13.937742 -307.816758)
		(end 14.063726 -307.942742)
		(width 0.20066)
		(layer "F.Cu")
		(net "M_D_CPU1_SA_DQ<7>")
	)
	(segment
		(start 17.707102 -307.81244)
		(end 18.102326 -307.81244)
		(width 0.20066)
		(layer "F.Cu")
		(net "M_D_CPU1_SA_DQ<7>")
	)
	(segment
		(start 18.760694 -308.024276)
		(end 18.968212 -307.816758)
		(width 0.20066)
		(layer "F.Cu")
		(net "M_D_CPU1_SA_DQ<7>")
	)
	(segment
		(start 14.063726 -307.942742)
		(end 14.063726 -308.11343)
		(width 0.20066)
		(layer "F.Cu")
		(net "M_D_CPU1_SA_DQ<7>")
	)
	(segment
		(start 16.885158 -308.2417)
		(end 17.42948 -308.2417)
		(width 0.20066)
		(layer "F.Cu")
		(net "M_D_CPU1_SA_DQ<7>")
	)
	(segment
		(start 18.314162 -308.024276)
		(end 18.760694 -308.024276)
		(width 0.20066)
		(layer "F.Cu")
		(net "M_D_CPU1_SA_DQ<7>")
	)
	(segment
		(start 17.578578 -307.940964)
		(end 17.707102 -307.81244)
		(width 0.20066)
		(layer "F.Cu")
		(net "M_D_CPU1_SA_DQ<7>")
	)
	(segment
		(start 17.42948 -308.2417)
		(end 17.578578 -308.092602)
		(width 0.20066)
		(layer "F.Cu")
		(net "M_D_CPU1_SA_DQ<7>")
	)
	(arc
		(start 96.713294 -272.917158)
		(mid 96.713357 -273.185128)
		(end 96.713548 -273.453098)
		(width 0.20066)
		(layer "F.Cu")
		(net "M_D_CPU1_SA_DQ<7>")
	)
	(segment
		(start 84.40039 -275.876258)
		(end 84.40039 -275.8948)
		(width 0.088646)
		(layer "In6.Cu")
		(net "M_D_CPU1_SA_DQ<7>")
	)
	(segment
		(start 87.041482 -274.586192)
		(end 87.032592 -274.591272)
		(width 0.088646)
		(layer "In6.Cu")
		(net "M_D_CPU1_SA_DQ<7>")
	)
	(segment
		(start 84.221828 -276.214078)
		(end 84.20481 -276.214078)
		(width 0.088646)
		(layer "In6.Cu")
		(net "M_D_CPU1_SA_DQ<7>")
	)
	(segment
		(start 29.40558 -306.814982)
		(end 29.40558 -307.208428)
		(width 0.18288)
		(layer "In6.Cu")
		(net "M_D_CPU1_SA_DQ<7>")
	)
	(segment
		(start 24.064722 -306.531772)
		(end 23.691342 -306.531772)
		(width 0.18288)
		(layer "In6.Cu")
		(net "M_D_CPU1_SA_DQ<7>")
	)
	(segment
		(start 21.314664 -307.391308)
		(end 20.889214 -307.816758)
		(width 0.18288)
		(layer "In6.Cu")
		(net "M_D_CPU1_SA_DQ<7>")
	)
	(segment
		(start 24.918162 -306.691792)
		(end 24.918162 -307.161692)
		(width 0.18288)
		(layer "In6.Cu")
		(net "M_D_CPU1_SA_DQ<7>")
	)
	(segment
		(start 22.304502 -306.531772)
		(end 22.144482 -306.691792)
		(width 0.18288)
		(layer "In6.Cu")
		(net "M_D_CPU1_SA_DQ<7>")
	)
	(segment
		(start 55.695342 -298.267882)
		(end 54.607968 -299.355256)
		(width 0.18288)
		(layer "In6.Cu")
		(net "M_D_CPU1_SA_DQ<7>")
	)
	(segment
		(start 22.677882 -306.531772)
		(end 22.304502 -306.531772)
		(width 0.18288)
		(layer "In6.Cu")
		(net "M_D_CPU1_SA_DQ<7>")
	)
	(segment
		(start 30.09646 -307.204872)
		(end 30.09646 -306.814982)
		(width 0.18288)
		(layer "In6.Cu")
		(net "M_D_CPU1_SA_DQ<7>")
	)
	(segment
		(start 56.501538 -298.267882)
		(end 55.695342 -298.267882)
		(width 0.18288)
		(layer "In6.Cu")
		(net "M_D_CPU1_SA_DQ<7>")
	)
	(segment
		(start 30.284928 -307.39334)
		(end 30.09646 -307.204872)
		(width 0.18288)
		(layer "In6.Cu")
		(net "M_D_CPU1_SA_DQ<7>")
	)
	(segment
		(start 53.8607 -299.843952)
		(end 53.8607 -300.102524)
		(width 0.18288)
		(layer "In6.Cu")
		(net "M_D_CPU1_SA_DQ<7>")
	)
	(segment
		(start 32.633666 -307.39334)
		(end 30.284928 -307.39334)
		(width 0.18288)
		(layer "In6.Cu")
		(net "M_D_CPU1_SA_DQ<7>")
	)
	(segment
		(start 40.981122 -307.45811)
		(end 40.197278 -308.241954)
		(width 0.18288)
		(layer "In6.Cu")
		(net "M_D_CPU1_SA_DQ<7>")
	)
	(segment
		(start 93.236796 -272.96364)
		(end 93.222064 -272.955004)
		(width 0.088646)
		(layer "In6.Cu")
		(net "M_D_CPU1_SA_DQ<7>")
	)
	(segment
		(start 23.531322 -307.231288)
		(end 23.371302 -307.391308)
		(width 0.18288)
		(layer "In6.Cu")
		(net "M_D_CPU1_SA_DQ<7>")
	)
	(segment
		(start 62.777878 -294.60952)
		(end 61.343032 -294.60952)
		(width 0.18288)
		(layer "In6.Cu")
		(net "M_D_CPU1_SA_DQ<7>")
	)
	(segment
		(start 29.58846 -306.632102)
		(end 29.40558 -306.814982)
		(width 0.18288)
		(layer "In6.Cu")
		(net "M_D_CPU1_SA_DQ<7>")
	)
	(segment
		(start 41.475406 -307.45811)
		(end 40.981122 -307.45811)
		(width 0.18288)
		(layer "In6.Cu")
		(net "M_D_CPU1_SA_DQ<7>")
	)
	(segment
		(start 63.795148 -293.59225)
		(end 62.777878 -294.60952)
		(width 0.18288)
		(layer "In6.Cu")
		(net "M_D_CPU1_SA_DQ<7>")
	)
	(segment
		(start 80.282796 -278.446738)
		(end 66.178938 -292.550596)
		(width 0.18288)
		(layer "In6.Cu")
		(net "M_D_CPU1_SA_DQ<7>")
	)
	(segment
		(start 25.771602 -307.391308)
		(end 25.611582 -307.231288)
		(width 0.18288)
		(layer "In6.Cu")
		(net "M_D_CPU1_SA_DQ<7>")
	)
	(segment
		(start 26.999946 -307.208428)
		(end 26.817066 -307.391308)
		(width 0.18288)
		(layer "In6.Cu")
		(net "M_D_CPU1_SA_DQ<7>")
	)
	(segment
		(start 58.70067 -296.494454)
		(end 58.274966 -296.494454)
		(width 0.18288)
		(layer "In6.Cu")
		(net "M_D_CPU1_SA_DQ<7>")
	)
	(segment
		(start 27.690826 -307.208428)
		(end 27.690826 -306.059586)
		(width 0.18288)
		(layer "In6.Cu")
		(net "M_D_CPU1_SA_DQ<7>")
	)
	(segment
		(start 44.501308 -304.952908)
		(end 43.61561 -305.838606)
		(width 0.18288)
		(layer "In6.Cu")
		(net "M_D_CPU1_SA_DQ<7>")
	)
	(segment
		(start 91.357196 -272.96364)
		(end 91.346782 -272.957544)
		(width 0.088646)
		(layer "In6.Cu")
		(net "M_D_CPU1_SA_DQ<7>")
	)
	(segment
		(start 26.817066 -307.391308)
		(end 25.771602 -307.391308)
		(width 0.18288)
		(layer "In6.Cu")
		(net "M_D_CPU1_SA_DQ<7>")
	)
	(segment
		(start 43.09491 -305.838606)
		(end 41.475406 -307.45811)
		(width 0.18288)
		(layer "In6.Cu")
		(net "M_D_CPU1_SA_DQ<7>")
	)
	(segment
		(start 54.607968 -299.355256)
		(end 54.349396 -299.355256)
		(width 0.18288)
		(layer "In6.Cu")
		(net "M_D_CPU1_SA_DQ<7>")
	)
	(segment
		(start 96.062292 -272.967196)
		(end 96.056196 -272.96364)
		(width 0.088646)
		(layer "In6.Cu")
		(net "M_D_CPU1_SA_DQ<7>")
	)
	(segment
		(start 66.178938 -292.550596)
		(end 65.632838 -292.550596)
		(width 0.18288)
		(layer "In6.Cu")
		(net "M_D_CPU1_SA_DQ<7>")
	)
	(segment
		(start 24.224742 -306.691792)
		(end 24.064722 -306.531772)
		(width 0.18288)
		(layer "In6.Cu")
		(net "M_D_CPU1_SA_DQ<7>")
	)
	(segment
		(start 83.987132 -276.431756)
		(end 83.987132 -276.879812)
		(width 0.088646)
		(layer "In6.Cu")
		(net "M_D_CPU1_SA_DQ<7>")
	)
	(segment
		(start 94.176596 -272.96364)
		(end 94.161864 -272.955004)
		(width 0.088646)
		(layer "In6.Cu")
		(net "M_D_CPU1_SA_DQ<7>")
	)
	(segment
		(start 29.40558 -307.208428)
		(end 29.2227 -307.391308)
		(width 0.18288)
		(layer "In6.Cu")
		(net "M_D_CPU1_SA_DQ<7>")
	)
	(segment
		(start 53.763672 -299.488352)
		(end 53.763672 -299.746924)
		(width 0.18288)
		(layer "In6.Cu")
		(net "M_D_CPU1_SA_DQ<7>")
	)
	(segment
		(start 83.987132 -276.879812)
		(end 83.886802 -276.980142)
		(width 0.088646)
		(layer "In6.Cu")
		(net "M_D_CPU1_SA_DQ<7>")
	)
	(segment
		(start 40.197278 -308.241954)
		(end 33.48228 -308.241954)
		(width 0.18288)
		(layer "In6.Cu")
		(net "M_D_CPU1_SA_DQ<7>")
	)
	(segment
		(start 24.384762 -307.321712)
		(end 24.224742 -307.161692)
		(width 0.18288)
		(layer "In6.Cu")
		(net "M_D_CPU1_SA_DQ<7>")
	)
	(segment
		(start 83.585812 -276.980142)
		(end 83.343242 -277.222712)
		(width 0.088646)
		(layer "In6.Cu")
		(net "M_D_CPU1_SA_DQ<7>")
	)
	(segment
		(start 46.424088 -303.991772)
		(end 45.462952 -304.952908)
		(width 0.18288)
		(layer "In6.Cu")
		(net "M_D_CPU1_SA_DQ<7>")
	)
	(segment
		(start 59.661806 -295.533318)
		(end 58.70067 -296.494454)
		(width 0.18288)
		(layer "In6.Cu")
		(net "M_D_CPU1_SA_DQ<7>")
	)
	(segment
		(start 30.09646 -306.814982)
		(end 29.91358 -306.632102)
		(width 0.18288)
		(layer "In6.Cu")
		(net "M_D_CPU1_SA_DQ<7>")
	)
	(segment
		(start 22.144482 -307.231288)
		(end 21.984462 -307.391308)
		(width 0.18288)
		(layer "In6.Cu")
		(net "M_D_CPU1_SA_DQ<7>")
	)
	(segment
		(start 89.862406 -272.957544)
		(end 89.851992 -272.96364)
		(width 0.088646)
		(layer "In6.Cu")
		(net "M_D_CPU1_SA_DQ<7>")
	)
	(segment
		(start 22.997922 -307.391308)
		(end 22.837902 -307.231288)
		(width 0.18288)
		(layer "In6.Cu")
		(net "M_D_CPU1_SA_DQ<7>")
	)
	(segment
		(start 92.296996 -272.96364)
		(end 92.282264 -272.955004)
		(width 0.088646)
		(layer "In6.Cu")
		(net "M_D_CPU1_SA_DQ<7>")
	)
	(segment
		(start 96.713548 -273.453098)
		(end 96.400874 -273.453098)
		(width 0.088646)
		(layer "In6.Cu")
		(net "M_D_CPU1_SA_DQ<7>")
	)
	(segment
		(start 53.993796 -299.258228)
		(end 53.763672 -299.488352)
		(width 0.18288)
		(layer "In6.Cu")
		(net "M_D_CPU1_SA_DQ<7>")
	)
	(segment
		(start 96.056196 -272.96364)
		(end 96.041464 -272.955004)
		(width 0.088646)
		(layer "In6.Cu")
		(net "M_D_CPU1_SA_DQ<7>")
	)
	(segment
		(start 33.48228 -308.241954)
		(end 32.633666 -307.39334)
		(width 0.18288)
		(layer "In6.Cu")
		(net "M_D_CPU1_SA_DQ<7>")
	)
	(segment
		(start 23.531322 -306.691792)
		(end 23.531322 -307.231288)
		(width 0.18288)
		(layer "In6.Cu")
		(net "M_D_CPU1_SA_DQ<7>")
	)
	(segment
		(start 85.631528 -275.400008)
		(end 85.622638 -275.405088)
		(width 0.088646)
		(layer "In6.Cu")
		(net "M_D_CPU1_SA_DQ<7>")
	)
	(segment
		(start 65.632838 -292.550596)
		(end 64.591184 -293.59225)
		(width 0.18288)
		(layer "In6.Cu")
		(net "M_D_CPU1_SA_DQ<7>")
	)
	(segment
		(start 47.626524 -303.576482)
		(end 47.211234 -303.991772)
		(width 0.18288)
		(layer "In6.Cu")
		(net "M_D_CPU1_SA_DQ<7>")
	)
	(segment
		(start 26.999946 -306.10302)
		(end 26.999946 -307.208428)
		(width 0.18288)
		(layer "In6.Cu")
		(net "M_D_CPU1_SA_DQ<7>")
	)
	(segment
		(start 25.611582 -307.231288)
		(end 25.611582 -306.691792)
		(width 0.18288)
		(layer "In6.Cu")
		(net "M_D_CPU1_SA_DQ<7>")
	)
	(segment
		(start 47.211234 -303.991772)
		(end 46.424088 -303.991772)
		(width 0.18288)
		(layer "In6.Cu")
		(net "M_D_CPU1_SA_DQ<7>")
	)
	(segment
		(start 27.507946 -305.876706)
		(end 27.22626 -305.876706)
		(width 0.18288)
		(layer "In6.Cu")
		(net "M_D_CPU1_SA_DQ<7>")
	)
	(segment
		(start 86.092792 -274.591272)
		(end 86.086696 -274.594828)
		(width 0.088646)
		(layer "In6.Cu")
		(net "M_D_CPU1_SA_DQ<7>")
	)
	(segment
		(start 21.984462 -307.391308)
		(end 21.314664 -307.391308)
		(width 0.18288)
		(layer "In6.Cu")
		(net "M_D_CPU1_SA_DQ<7>")
	)
	(segment
		(start 83.237578 -277.222712)
		(end 80.282796 -278.446738)
		(width 0.18288)
		(layer "In6.Cu")
		(net "M_D_CPU1_SA_DQ<7>")
	)
	(segment
		(start 60.419234 -295.533318)
		(end 59.661806 -295.533318)
		(width 0.18288)
		(layer "In6.Cu")
		(net "M_D_CPU1_SA_DQ<7>")
	)
	(segment
		(start 87.220044 -274.257008)
		(end 87.220044 -274.266914)
		(width 0.088646)
		(layer "In6.Cu")
		(net "M_D_CPU1_SA_DQ<7>")
	)
	(segment
		(start 24.918162 -307.161692)
		(end 24.758142 -307.321712)
		(width 0.18288)
		(layer "In6.Cu")
		(net "M_D_CPU1_SA_DQ<7>")
	)
	(segment
		(start 23.691342 -306.531772)
		(end 23.531322 -306.691792)
		(width 0.18288)
		(layer "In6.Cu")
		(net "M_D_CPU1_SA_DQ<7>")
	)
	(segment
		(start 54.252368 -299.258228)
		(end 53.993796 -299.258228)
		(width 0.18288)
		(layer "In6.Cu")
		(net "M_D_CPU1_SA_DQ<7>")
	)
	(segment
		(start 25.078182 -306.531772)
		(end 24.918162 -306.691792)
		(width 0.18288)
		(layer "In6.Cu")
		(net "M_D_CPU1_SA_DQ<7>")
	)
	(segment
		(start 49.951132 -300.591728)
		(end 47.626524 -302.916336)
		(width 0.18288)
		(layer "In6.Cu")
		(net "M_D_CPU1_SA_DQ<7>")
	)
	(segment
		(start 24.224742 -307.161692)
		(end 24.224742 -306.691792)
		(width 0.18288)
		(layer "In6.Cu")
		(net "M_D_CPU1_SA_DQ<7>")
	)
	(segment
		(start 22.837902 -306.691792)
		(end 22.677882 -306.531772)
		(width 0.18288)
		(layer "In6.Cu")
		(net "M_D_CPU1_SA_DQ<7>")
	)
	(segment
		(start 86.107524 -274.582636)
		(end 86.092792 -274.591272)
		(width 0.088646)
		(layer "In6.Cu")
		(net "M_D_CPU1_SA_DQ<7>")
	)
	(segment
		(start 88.912446 -272.96364)
		(end 88.90635 -272.967196)
		(width 0.088646)
		(layer "In6.Cu")
		(net "M_D_CPU1_SA_DQ<7>")
	)
	(segment
		(start 27.22626 -305.876706)
		(end 26.999946 -306.10302)
		(width 0.18288)
		(layer "In6.Cu")
		(net "M_D_CPU1_SA_DQ<7>")
	)
	(segment
		(start 43.61561 -305.838606)
		(end 43.09491 -305.838606)
		(width 0.18288)
		(layer "In6.Cu")
		(net "M_D_CPU1_SA_DQ<7>")
	)
	(segment
		(start 88.451182 -273.772376)
		(end 88.442292 -273.777456)
		(width 0.088646)
		(layer "In6.Cu")
		(net "M_D_CPU1_SA_DQ<7>")
	)
	(segment
		(start 88.92286 -272.957544)
		(end 88.912446 -272.96364)
		(width 0.088646)
		(layer "In6.Cu")
		(net "M_D_CPU1_SA_DQ<7>")
	)
	(segment
		(start 53.371496 -300.591728)
		(end 49.951132 -300.591728)
		(width 0.18288)
		(layer "In6.Cu")
		(net "M_D_CPU1_SA_DQ<7>")
	)
	(segment
		(start 58.274966 -296.494454)
		(end 56.501538 -298.267882)
		(width 0.18288)
		(layer "In6.Cu")
		(net "M_D_CPU1_SA_DQ<7>")
	)
	(segment
		(start 22.837902 -307.231288)
		(end 22.837902 -306.691792)
		(width 0.18288)
		(layer "In6.Cu")
		(net "M_D_CPU1_SA_DQ<7>")
	)
	(segment
		(start 83.343242 -277.222712)
		(end 83.237578 -277.222712)
		(width 0.18288)
		(layer "In6.Cu")
		(net "M_D_CPU1_SA_DQ<7>")
	)
	(segment
		(start 54.349396 -299.355256)
		(end 54.252368 -299.258228)
		(width 0.18288)
		(layer "In6.Cu")
		(net "M_D_CPU1_SA_DQ<7>")
	)
	(segment
		(start 47.626524 -302.916336)
		(end 47.626524 -303.576482)
		(width 0.18288)
		(layer "In6.Cu")
		(net "M_D_CPU1_SA_DQ<7>")
	)
	(segment
		(start 45.462952 -304.952908)
		(end 44.501308 -304.952908)
		(width 0.18288)
		(layer "In6.Cu")
		(net "M_D_CPU1_SA_DQ<7>")
	)
	(segment
		(start 83.886802 -276.980142)
		(end 83.585812 -276.980142)
		(width 0.088646)
		(layer "In6.Cu")
		(net "M_D_CPU1_SA_DQ<7>")
	)
	(segment
		(start 25.451562 -306.531772)
		(end 25.078182 -306.531772)
		(width 0.18288)
		(layer "In6.Cu")
		(net "M_D_CPU1_SA_DQ<7>")
	)
	(segment
		(start 27.873706 -307.391308)
		(end 27.690826 -307.208428)
		(width 0.18288)
		(layer "In6.Cu")
		(net "M_D_CPU1_SA_DQ<7>")
	)
	(segment
		(start 61.343032 -294.60952)
		(end 60.419234 -295.533318)
		(width 0.18288)
		(layer "In6.Cu")
		(net "M_D_CPU1_SA_DQ<7>")
	)
	(segment
		(start 23.371302 -307.391308)
		(end 22.997922 -307.391308)
		(width 0.18288)
		(layer "In6.Cu")
		(net "M_D_CPU1_SA_DQ<7>")
	)
	(segment
		(start 29.2227 -307.391308)
		(end 27.873706 -307.391308)
		(width 0.18288)
		(layer "In6.Cu")
		(net "M_D_CPU1_SA_DQ<7>")
	)
	(segment
		(start 27.690826 -306.059586)
		(end 27.507946 -305.876706)
		(width 0.18288)
		(layer "In6.Cu")
		(net "M_D_CPU1_SA_DQ<7>")
	)
	(segment
		(start 53.8607 -300.102524)
		(end 53.371496 -300.591728)
		(width 0.18288)
		(layer "In6.Cu")
		(net "M_D_CPU1_SA_DQ<7>")
	)
	(segment
		(start 84.20481 -276.214078)
		(end 83.987132 -276.431756)
		(width 0.088646)
		(layer "In6.Cu")
		(net "M_D_CPU1_SA_DQ<7>")
	)
	(segment
		(start 64.591184 -293.59225)
		(end 63.795148 -293.59225)
		(width 0.18288)
		(layer "In6.Cu")
		(net "M_D_CPU1_SA_DQ<7>")
	)
	(segment
		(start 53.763672 -299.746924)
		(end 53.8607 -299.843952)
		(width 0.18288)
		(layer "In6.Cu")
		(net "M_D_CPU1_SA_DQ<7>")
	)
	(segment
		(start 25.611582 -306.691792)
		(end 25.451562 -306.531772)
		(width 0.18288)
		(layer "In6.Cu")
		(net "M_D_CPU1_SA_DQ<7>")
	)
	(segment
		(start 24.758142 -307.321712)
		(end 24.384762 -307.321712)
		(width 0.18288)
		(layer "In6.Cu")
		(net "M_D_CPU1_SA_DQ<7>")
	)
	(segment
		(start 29.91358 -306.632102)
		(end 29.58846 -306.632102)
		(width 0.18288)
		(layer "In6.Cu")
		(net "M_D_CPU1_SA_DQ<7>")
	)
	(segment
		(start 22.144482 -306.691792)
		(end 22.144482 -307.231288)
		(width 0.18288)
		(layer "In6.Cu")
		(net "M_D_CPU1_SA_DQ<7>")
	)
	(segment
		(start 96.400874 -273.453098)
		(end 96.335088 -273.387312)
		(width 0.088646)
		(layer "In6.Cu")
		(net "M_D_CPU1_SA_DQ<7>")
	)
	(arc
		(start 85.622638 -275.405088)
		(mid 85.43544 -275.455231)
		(end 85.248242 -275.405088)
		(width 0.088646)
		(layer "In6.Cu")
		(net "M_D_CPU1_SA_DQ<7>")
	)
	(arc
		(start 92.282264 -272.955004)
		(mid 92.005789 -272.887684)
		(end 91.731592 -272.96364)
		(width 0.088646)
		(layer "In6.Cu")
		(net "M_D_CPU1_SA_DQ<7>")
	)
	(arc
		(start 85.248242 -275.405088)
		(mid 84.96554 -275.329346)
		(end 84.682838 -275.405088)
		(width 0.088646)
		(layer "In6.Cu")
		(net "M_D_CPU1_SA_DQ<7>")
	)
	(arc
		(start 87.502492 -273.777456)
		(mid 87.298157 -273.980061)
		(end 87.220044 -274.257008)
		(width 0.088646)
		(layer "In6.Cu")
		(net "M_D_CPU1_SA_DQ<7>")
	)
	(arc
		(start 90.792046 -272.96364)
		(mid 90.604848 -273.013783)
		(end 90.41765 -272.96364)
		(width 0.088646)
		(layer "In6.Cu")
		(net "M_D_CPU1_SA_DQ<7>")
	)
	(arc
		(start 94.550992 -272.96364)
		(mid 94.363794 -273.013783)
		(end 94.176596 -272.96364)
		(width 0.088646)
		(layer "In6.Cu")
		(net "M_D_CPU1_SA_DQ<7>")
	)
	(arc
		(start 86.658196 -274.591272)
		(mid 86.383997 -274.515437)
		(end 86.107524 -274.582636)
		(width 0.088646)
		(layer "In6.Cu")
		(net "M_D_CPU1_SA_DQ<7>")
	)
	(arc
		(start 91.346782 -272.957544)
		(mid 91.068604 -272.887821)
		(end 90.792046 -272.96364)
		(width 0.088646)
		(layer "In6.Cu")
		(net "M_D_CPU1_SA_DQ<7>")
	)
	(arc
		(start 93.611192 -272.96364)
		(mid 93.423994 -273.013783)
		(end 93.236796 -272.96364)
		(width 0.088646)
		(layer "In6.Cu")
		(net "M_D_CPU1_SA_DQ<7>")
	)
	(arc
		(start 87.032592 -274.591272)
		(mid 86.845394 -274.641415)
		(end 86.658196 -274.591272)
		(width 0.088646)
		(layer "In6.Cu")
		(net "M_D_CPU1_SA_DQ<7>")
	)
	(arc
		(start 88.067896 -273.777456)
		(mid 87.785194 -273.70168)
		(end 87.502492 -273.777456)
		(width 0.088646)
		(layer "In6.Cu")
		(net "M_D_CPU1_SA_DQ<7>")
	)
	(arc
		(start 88.442292 -273.777456)
		(mid 88.255094 -273.827599)
		(end 88.067896 -273.777456)
		(width 0.088646)
		(layer "In6.Cu")
		(net "M_D_CPU1_SA_DQ<7>")
	)
	(arc
		(start 84.40039 -275.8948)
		(mid 84.352711 -276.0777)
		(end 84.221828 -276.214078)
		(width 0.088646)
		(layer "In6.Cu")
		(net "M_D_CPU1_SA_DQ<7>")
	)
	(arc
		(start 91.731592 -272.96364)
		(mid 91.544394 -273.013783)
		(end 91.357196 -272.96364)
		(width 0.088646)
		(layer "In6.Cu")
		(net "M_D_CPU1_SA_DQ<7>")
	)
	(arc
		(start 95.116396 -272.96364)
		(mid 94.833694 -272.887864)
		(end 94.550992 -272.96364)
		(width 0.088646)
		(layer "In6.Cu")
		(net "M_D_CPU1_SA_DQ<7>")
	)
	(arc
		(start 88.629744 -273.453098)
		(mid 88.582065 -273.635998)
		(end 88.451182 -273.772376)
		(width 0.088646)
		(layer "In6.Cu")
		(net "M_D_CPU1_SA_DQ<7>")
	)
	(arc
		(start 96.041464 -272.955004)
		(mid 95.764989 -272.887684)
		(end 95.490792 -272.96364)
		(width 0.088646)
		(layer "In6.Cu")
		(net "M_D_CPU1_SA_DQ<7>")
	)
	(arc
		(start 94.161864 -272.955004)
		(mid 93.885389 -272.887684)
		(end 93.611192 -272.96364)
		(width 0.088646)
		(layer "In6.Cu")
		(net "M_D_CPU1_SA_DQ<7>")
	)
	(arc
		(start 85.81009 -275.08073)
		(mid 85.762411 -275.26363)
		(end 85.631528 -275.400008)
		(width 0.088646)
		(layer "In6.Cu")
		(net "M_D_CPU1_SA_DQ<7>")
	)
	(arc
		(start 89.851992 -272.96364)
		(mid 89.664794 -273.013783)
		(end 89.477596 -272.96364)
		(width 0.088646)
		(layer "In6.Cu")
		(net "M_D_CPU1_SA_DQ<7>")
	)
	(arc
		(start 96.335088 -273.387312)
		(mid 96.2478 -273.145356)
		(end 96.062292 -272.967196)
		(width 0.088646)
		(layer "In6.Cu")
		(net "M_D_CPU1_SA_DQ<7>")
	)
	(arc
		(start 93.222064 -272.955004)
		(mid 92.945589 -272.887684)
		(end 92.671392 -272.96364)
		(width 0.088646)
		(layer "In6.Cu")
		(net "M_D_CPU1_SA_DQ<7>")
	)
	(arc
		(start 95.490792 -272.96364)
		(mid 95.303594 -273.013783)
		(end 95.116396 -272.96364)
		(width 0.088646)
		(layer "In6.Cu")
		(net "M_D_CPU1_SA_DQ<7>")
	)
	(arc
		(start 86.086696 -274.594828)
		(mid 85.884109 -274.801179)
		(end 85.81009 -275.08073)
		(width 0.088646)
		(layer "In6.Cu")
		(net "M_D_CPU1_SA_DQ<7>")
	)
	(arc
		(start 88.90635 -272.967196)
		(mid 88.703763 -273.173547)
		(end 88.629744 -273.453098)
		(width 0.088646)
		(layer "In6.Cu")
		(net "M_D_CPU1_SA_DQ<7>")
	)
	(arc
		(start 90.41765 -272.96364)
		(mid 90.140837 -272.88777)
		(end 89.862406 -272.957544)
		(width 0.088646)
		(layer "In6.Cu")
		(net "M_D_CPU1_SA_DQ<7>")
	)
	(arc
		(start 84.682838 -275.405088)
		(mid 84.480552 -275.604069)
		(end 84.40039 -275.876258)
		(width 0.088646)
		(layer "In6.Cu")
		(net "M_D_CPU1_SA_DQ<7>")
	)
	(arc
		(start 89.477596 -272.96364)
		(mid 89.201037 -272.887897)
		(end 88.92286 -272.957544)
		(width 0.088646)
		(layer "In6.Cu")
		(net "M_D_CPU1_SA_DQ<7>")
	)
	(arc
		(start 87.220044 -274.266914)
		(mid 87.172365 -274.449814)
		(end 87.041482 -274.586192)
		(width 0.088646)
		(layer "In6.Cu")
		(net "M_D_CPU1_SA_DQ<7>")
	)
	(arc
		(start 92.671392 -272.96364)
		(mid 92.484194 -273.013783)
		(end 92.296996 -272.96364)
		(width 0.088646)
		(layer "In6.Cu")
		(net "M_D_CPU1_SA_DQ<7>")
	)
	(segment
		(start 97.183448 -274.26666)
		(end 97.183194 -274.266914)
		(width 0.20066)
		(layer "F.Cu")
		(net "M_D_CPU1_SA_DQ<6>")
	)
	(segment
		(start 17.518126 -309.091838)
		(end 17.66189 -309.235602)
		(width 0.20066)
		(layer "F.Cu")
		(net "M_D_CPU1_SA_DQ<6>")
	)
	(segment
		(start 17.66189 -309.235602)
		(end 17.66189 -309.56123)
		(width 0.20066)
		(layer "F.Cu")
		(net "M_D_CPU1_SA_DQ<6>")
	)
	(segment
		(start 18.46961 -309.51678)
		(end 19.784314 -309.51678)
		(width 0.20066)
		(layer "F.Cu")
		(net "M_D_CPU1_SA_DQ<6>")
	)
	(segment
		(start 17.66189 -309.56123)
		(end 17.829276 -309.728616)
		(width 0.20066)
		(layer "F.Cu")
		(net "M_D_CPU1_SA_DQ<6>")
	)
	(segment
		(start 14.825218 -309.091838)
		(end 16.885158 -309.091838)
		(width 0.1016)
		(layer "F.Cu")
		(net "M_D_CPU1_SA_DQ<6>")
	)
	(segment
		(start 16.885158 -309.091838)
		(end 17.518126 -309.091838)
		(width 0.20066)
		(layer "F.Cu")
		(net "M_D_CPU1_SA_DQ<6>")
	)
	(segment
		(start 14.560042 -309.081678)
		(end 14.570202 -309.091838)
		(width 0.101854)
		(layer "F.Cu")
		(net "M_D_CPU1_SA_DQ<6>")
	)
	(segment
		(start 14.570202 -309.091838)
		(end 14.825218 -309.091838)
		(width 0.101854)
		(layer "F.Cu")
		(net "M_D_CPU1_SA_DQ<6>")
	)
	(segment
		(start 12.240514 -309.51678)
		(end 13.387578 -309.51678)
		(width 0.20066)
		(layer "F.Cu")
		(net "M_D_CPU1_SA_DQ<6>")
	)
	(segment
		(start 13.387578 -309.51678)
		(end 13.82268 -309.081678)
		(width 0.20066)
		(layer "F.Cu")
		(net "M_D_CPU1_SA_DQ<6>")
	)
	(segment
		(start 13.82268 -309.081678)
		(end 14.560042 -309.081678)
		(width 0.20066)
		(layer "F.Cu")
		(net "M_D_CPU1_SA_DQ<6>")
	)
	(segment
		(start 20.889214 -309.51678)
		(end 19.784314 -309.51678)
		(width 0.20066)
		(layer "F.Cu")
		(net "M_D_CPU1_SA_DQ<6>")
	)
	(segment
		(start 97.183448 -273.730974)
		(end 97.183448 -274.26666)
		(width 0.20066)
		(layer "F.Cu")
		(net "M_D_CPU1_SA_DQ<6>")
	)
	(segment
		(start 17.829276 -309.728616)
		(end 18.257774 -309.728616)
		(width 0.20066)
		(layer "F.Cu")
		(net "M_D_CPU1_SA_DQ<6>")
	)
	(segment
		(start 18.257774 -309.728616)
		(end 18.46961 -309.51678)
		(width 0.20066)
		(layer "F.Cu")
		(net "M_D_CPU1_SA_DQ<6>")
	)
	(segment
		(start 86.27999 -275.876258)
		(end 86.27999 -275.8948)
		(width 0.088646)
		(layer "In6.Cu")
		(net "M_D_CPU1_SA_DQ<6>")
	)
	(segment
		(start 83.943698 -278.421592)
		(end 83.343242 -278.421592)
		(width 0.088646)
		(layer "In6.Cu")
		(net "M_D_CPU1_SA_DQ<6>")
	)
	(segment
		(start 48.907192 -304.189892)
		(end 48.562768 -304.189892)
		(width 0.18288)
		(layer "In6.Cu")
		(net "M_D_CPU1_SA_DQ<6>")
	)
	(segment
		(start 23.724108 -308.812438)
		(end 23.541228 -308.995318)
		(width 0.18288)
		(layer "In6.Cu")
		(net "M_D_CPU1_SA_DQ<6>")
	)
	(segment
		(start 49.821846 -302.202342)
		(end 49.821846 -302.981614)
		(width 0.18288)
		(layer "In6.Cu")
		(net "M_D_CPU1_SA_DQ<6>")
	)
	(segment
		(start 34.642806 -309.653686)
		(end 34.354516 -309.941976)
		(width 0.18288)
		(layer "In6.Cu")
		(net "M_D_CPU1_SA_DQ<6>")
	)
	(segment
		(start 55.69331 -300.812454)
		(end 55.174388 -301.331376)
		(width 0.18288)
		(layer "In6.Cu")
		(net "M_D_CPU1_SA_DQ<6>")
	)
	(segment
		(start 34.354516 -309.941976)
		(end 33.321752 -309.941976)
		(width 0.18288)
		(layer "In6.Cu")
		(net "M_D_CPU1_SA_DQ<6>")
	)
	(segment
		(start 26.742644 -309.418482)
		(end 25.654 -309.418482)
		(width 0.18288)
		(layer "In6.Cu")
		(net "M_D_CPU1_SA_DQ<6>")
	)
	(segment
		(start 26.902664 -309.258462)
		(end 26.742644 -309.418482)
		(width 0.18288)
		(layer "In6.Cu")
		(net "M_D_CPU1_SA_DQ<6>")
	)
	(segment
		(start 63.095124 -296.246296)
		(end 61.214508 -296.246296)
		(width 0.18288)
		(layer "In6.Cu")
		(net "M_D_CPU1_SA_DQ<6>")
	)
	(segment
		(start 94.09176 -273.77136)
		(end 94.081346 -273.777456)
		(width 0.088646)
		(layer "In6.Cu")
		(net "M_D_CPU1_SA_DQ<6>")
	)
	(segment
		(start 27.436064 -308.791356)
		(end 27.062684 -308.791356)
		(width 0.18288)
		(layer "In6.Cu")
		(net "M_D_CPU1_SA_DQ<6>")
	)
	(segment
		(start 66.809874 -293.551864)
		(end 66.809874 -294.284908)
		(width 0.18288)
		(layer "In6.Cu")
		(net "M_D_CPU1_SA_DQ<6>")
	)
	(segment
		(start 93.156278 -273.76882)
		(end 93.141546 -273.777456)
		(width 0.088646)
		(layer "In6.Cu")
		(net "M_D_CPU1_SA_DQ<6>")
	)
	(segment
		(start 49.999138 -302.02505)
		(end 49.821846 -302.202342)
		(width 0.18288)
		(layer "In6.Cu")
		(net "M_D_CPU1_SA_DQ<6>")
	)
	(segment
		(start 65.817496 -294.744394)
		(end 65.378076 -295.183814)
		(width 0.18288)
		(layer "In6.Cu")
		(net "M_D_CPU1_SA_DQ<6>")
	)
	(segment
		(start 64.128396 -296.444924)
		(end 63.293752 -296.444924)
		(width 0.18288)
		(layer "In6.Cu")
		(net "M_D_CPU1_SA_DQ<6>")
	)
	(segment
		(start 63.293752 -296.444924)
		(end 63.095124 -296.246296)
		(width 0.18288)
		(layer "In6.Cu")
		(net "M_D_CPU1_SA_DQ<6>")
	)
	(segment
		(start 47.599092 -305.153568)
		(end 47.599092 -305.497992)
		(width 0.18288)
		(layer "In6.Cu")
		(net "M_D_CPU1_SA_DQ<6>")
	)
	(segment
		(start 92.216478 -273.76882)
		(end 92.201746 -273.777456)
		(width 0.088646)
		(layer "In6.Cu")
		(net "M_D_CPU1_SA_DQ<6>")
	)
	(segment
		(start 30.377892 -309.388256)
		(end 30.055058 -309.065422)
		(width 0.18288)
		(layer "In6.Cu")
		(net "M_D_CPU1_SA_DQ<6>")
	)
	(segment
		(start 33.321752 -309.941976)
		(end 32.471106 -309.09133)
		(width 0.18288)
		(layer "In6.Cu")
		(net "M_D_CPU1_SA_DQ<6>")
	)
	(segment
		(start 83.054698 -278.421592)
		(end 81.153508 -279.20823)
		(width 0.18288)
		(layer "In6.Cu")
		(net "M_D_CPU1_SA_DQ<6>")
	)
	(segment
		(start 38.773608 -309.941976)
		(end 38.593776 -309.762144)
		(width 0.18288)
		(layer "In6.Cu")
		(net "M_D_CPU1_SA_DQ<6>")
	)
	(segment
		(start 43.55211 -307.552852)
		(end 43.204384 -307.552852)
		(width 0.18288)
		(layer "In6.Cu")
		(net "M_D_CPU1_SA_DQ<6>")
	)
	(segment
		(start 26.902664 -308.951376)
		(end 26.902664 -309.258462)
		(width 0.18288)
		(layer "In6.Cu")
		(net "M_D_CPU1_SA_DQ<6>")
	)
	(segment
		(start 89.099644 -274.257008)
		(end 89.099644 -274.266914)
		(width 0.088646)
		(layer "In6.Cu")
		(net "M_D_CPU1_SA_DQ<6>")
	)
	(segment
		(start 29.056838 -309.065422)
		(end 28.703778 -309.418482)
		(width 0.18288)
		(layer "In6.Cu")
		(net "M_D_CPU1_SA_DQ<6>")
	)
	(segment
		(start 43.204384 -307.552852)
		(end 41.525698 -309.231538)
		(width 0.18288)
		(layer "In6.Cu")
		(net "M_D_CPU1_SA_DQ<6>")
	)
	(segment
		(start 54.294024 -301.331376)
		(end 52.483766 -303.141634)
		(width 0.18288)
		(layer "In6.Cu")
		(net "M_D_CPU1_SA_DQ<6>")
	)
	(segment
		(start 87.511128 -275.400008)
		(end 87.502238 -275.405088)
		(width 0.088646)
		(layer "In6.Cu")
		(net "M_D_CPU1_SA_DQ<6>")
	)
	(segment
		(start 66.809874 -294.284908)
		(end 66.350388 -294.744394)
		(width 0.18288)
		(layer "In6.Cu")
		(net "M_D_CPU1_SA_DQ<6>")
	)
	(segment
		(start 66.350388 -294.744394)
		(end 65.817496 -294.744394)
		(width 0.18288)
		(layer "In6.Cu")
		(net "M_D_CPU1_SA_DQ<6>")
	)
	(segment
		(start 65.378076 -295.195244)
		(end 64.128396 -296.444924)
		(width 0.18288)
		(layer "In6.Cu")
		(net "M_D_CPU1_SA_DQ<6>")
	)
	(segment
		(start 56.388762 -300.117002)
		(end 55.97525 -300.117002)
		(width 0.18288)
		(layer "In6.Cu")
		(net "M_D_CPU1_SA_DQ<6>")
	)
	(segment
		(start 22.850348 -310.05399)
		(end 22.850348 -308.995318)
		(width 0.18288)
		(layer "In6.Cu")
		(net "M_D_CPU1_SA_DQ<6>")
	)
	(segment
		(start 86.101428 -276.214078)
		(end 86.092538 -276.219158)
		(width 0.088646)
		(layer "In6.Cu")
		(net "M_D_CPU1_SA_DQ<6>")
	)
	(segment
		(start 23.358348 -310.23687)
		(end 23.033228 -310.23687)
		(width 0.18288)
		(layer "In6.Cu")
		(net "M_D_CPU1_SA_DQ<6>")
	)
	(segment
		(start 25.047956 -308.812438)
		(end 23.724108 -308.812438)
		(width 0.18288)
		(layer "In6.Cu")
		(net "M_D_CPU1_SA_DQ<6>")
	)
	(segment
		(start 84.746846 -276.78253)
		(end 84.746846 -277.618444)
		(width 0.088646)
		(layer "In6.Cu")
		(net "M_D_CPU1_SA_DQ<6>")
	)
	(segment
		(start 47.40529 -305.691794)
		(end 46.222666 -305.691794)
		(width 0.18288)
		(layer "In6.Cu")
		(net "M_D_CPU1_SA_DQ<6>")
	)
	(segment
		(start 84.746846 -277.618444)
		(end 83.943698 -278.421592)
		(width 0.088646)
		(layer "In6.Cu")
		(net "M_D_CPU1_SA_DQ<6>")
	)
	(segment
		(start 46.222666 -305.691794)
		(end 45.25645 -306.65801)
		(width 0.18288)
		(layer "In6.Cu")
		(net "M_D_CPU1_SA_DQ<6>")
	)
	(segment
		(start 58.274966 -298.230798)
		(end 56.388762 -300.117002)
		(width 0.18288)
		(layer "In6.Cu")
		(net "M_D_CPU1_SA_DQ<6>")
	)
	(segment
		(start 48.562768 -304.189892)
		(end 47.599092 -305.153568)
		(width 0.18288)
		(layer "In6.Cu")
		(net "M_D_CPU1_SA_DQ<6>")
	)
	(segment
		(start 49.348644 -303.312068)
		(end 49.348644 -303.74844)
		(width 0.18288)
		(layer "In6.Cu")
		(net "M_D_CPU1_SA_DQ<6>")
	)
	(segment
		(start 55.69331 -300.398942)
		(end 55.69331 -300.812454)
		(width 0.18288)
		(layer "In6.Cu")
		(net "M_D_CPU1_SA_DQ<6>")
	)
	(segment
		(start 31.354268 -309.09133)
		(end 31.057342 -309.388256)
		(width 0.18288)
		(layer "In6.Cu")
		(net "M_D_CPU1_SA_DQ<6>")
	)
	(segment
		(start 96.624902 -273.835368)
		(end 96.541844 -273.7866)
		(width 0.088646)
		(layer "In6.Cu")
		(net "M_D_CPU1_SA_DQ<6>")
	)
	(segment
		(start 49.661826 -303.141634)
		(end 49.519078 -303.141634)
		(width 0.18288)
		(layer "In6.Cu")
		(net "M_D_CPU1_SA_DQ<6>")
	)
	(segment
		(start 55.97525 -300.117002)
		(end 55.69331 -300.398942)
		(width 0.18288)
		(layer "In6.Cu")
		(net "M_D_CPU1_SA_DQ<6>")
	)
	(segment
		(start 47.599092 -305.497992)
		(end 47.40529 -305.691794)
		(width 0.18288)
		(layer "In6.Cu")
		(net "M_D_CPU1_SA_DQ<6>")
	)
	(segment
		(start 22.850348 -308.995318)
		(end 22.667468 -308.812438)
		(width 0.18288)
		(layer "In6.Cu")
		(net "M_D_CPU1_SA_DQ<6>")
	)
	(segment
		(start 30.055058 -309.065422)
		(end 29.056838 -309.065422)
		(width 0.18288)
		(layer "In6.Cu")
		(net "M_D_CPU1_SA_DQ<6>")
	)
	(segment
		(start 27.756104 -309.418482)
		(end 27.596084 -309.258462)
		(width 0.18288)
		(layer "In6.Cu")
		(net "M_D_CPU1_SA_DQ<6>")
	)
	(segment
		(start 49.821846 -302.981614)
		(end 49.661826 -303.141634)
		(width 0.18288)
		(layer "In6.Cu")
		(net "M_D_CPU1_SA_DQ<6>")
	)
	(segment
		(start 90.332306 -273.77136)
		(end 90.321892 -273.777456)
		(width 0.088646)
		(layer "In6.Cu")
		(net "M_D_CPU1_SA_DQ<6>")
	)
	(segment
		(start 59.614816 -297.288204)
		(end 58.672222 -298.230798)
		(width 0.18288)
		(layer "In6.Cu")
		(net "M_D_CPU1_SA_DQ<6>")
	)
	(segment
		(start 95.597218 -273.783806)
		(end 95.571564 -273.76882)
		(width 0.088646)
		(layer "In6.Cu")
		(net "M_D_CPU1_SA_DQ<6>")
	)
	(segment
		(start 23.033228 -310.23687)
		(end 22.850348 -310.05399)
		(width 0.18288)
		(layer "In6.Cu")
		(net "M_D_CPU1_SA_DQ<6>")
	)
	(segment
		(start 25.654 -309.418482)
		(end 25.047956 -308.812438)
		(width 0.18288)
		(layer "In6.Cu")
		(net "M_D_CPU1_SA_DQ<6>")
	)
	(segment
		(start 60.1726 -297.288204)
		(end 59.614816 -297.288204)
		(width 0.18288)
		(layer "In6.Cu")
		(net "M_D_CPU1_SA_DQ<6>")
	)
	(segment
		(start 27.596084 -308.951376)
		(end 27.436064 -308.791356)
		(width 0.18288)
		(layer "In6.Cu")
		(net "M_D_CPU1_SA_DQ<6>")
	)
	(segment
		(start 65.378076 -295.183814)
		(end 65.378076 -295.195244)
		(width 0.18288)
		(layer "In6.Cu")
		(net "M_D_CPU1_SA_DQ<6>")
	)
	(segment
		(start 32.471106 -309.09133)
		(end 31.354268 -309.09133)
		(width 0.18288)
		(layer "In6.Cu")
		(net "M_D_CPU1_SA_DQ<6>")
	)
	(segment
		(start 50.355246 -302.02505)
		(end 49.999138 -302.02505)
		(width 0.18288)
		(layer "In6.Cu")
		(net "M_D_CPU1_SA_DQ<6>")
	)
	(segment
		(start 21.593556 -308.812438)
		(end 20.889214 -309.51678)
		(width 0.18288)
		(layer "In6.Cu")
		(net "M_D_CPU1_SA_DQ<6>")
	)
	(segment
		(start 27.596084 -309.258462)
		(end 27.596084 -308.951376)
		(width 0.18288)
		(layer "In6.Cu")
		(net "M_D_CPU1_SA_DQ<6>")
	)
	(segment
		(start 88.921082 -274.586192)
		(end 88.912192 -274.591272)
		(width 0.088646)
		(layer "In6.Cu")
		(net "M_D_CPU1_SA_DQ<6>")
	)
	(segment
		(start 44.446952 -306.65801)
		(end 43.55211 -307.552852)
		(width 0.18288)
		(layer "In6.Cu")
		(net "M_D_CPU1_SA_DQ<6>")
	)
	(segment
		(start 35.336226 -309.941976)
		(end 35.047936 -309.653686)
		(width 0.18288)
		(layer "In6.Cu")
		(net "M_D_CPU1_SA_DQ<6>")
	)
	(segment
		(start 28.703778 -309.418482)
		(end 27.756104 -309.418482)
		(width 0.18288)
		(layer "In6.Cu")
		(net "M_D_CPU1_SA_DQ<6>")
	)
	(segment
		(start 27.062684 -308.791356)
		(end 26.902664 -308.951376)
		(width 0.18288)
		(layer "In6.Cu")
		(net "M_D_CPU1_SA_DQ<6>")
	)
	(segment
		(start 97.183194 -274.266914)
		(end 96.624902 -273.835368)
		(width 0.088646)
		(layer "In6.Cu")
		(net "M_D_CPU1_SA_DQ<6>")
	)
	(segment
		(start 40.762174 -309.231538)
		(end 40.051736 -309.941976)
		(width 0.18288)
		(layer "In6.Cu")
		(net "M_D_CPU1_SA_DQ<6>")
	)
	(segment
		(start 37.900356 -309.941976)
		(end 35.336226 -309.941976)
		(width 0.18288)
		(layer "In6.Cu")
		(net "M_D_CPU1_SA_DQ<6>")
	)
	(segment
		(start 50.675286 -303.141634)
		(end 50.515266 -302.981614)
		(width 0.18288)
		(layer "In6.Cu")
		(net "M_D_CPU1_SA_DQ<6>")
	)
	(segment
		(start 49.519078 -303.141634)
		(end 49.348644 -303.312068)
		(width 0.18288)
		(layer "In6.Cu")
		(net "M_D_CPU1_SA_DQ<6>")
	)
	(segment
		(start 50.515266 -302.981614)
		(end 50.515266 -302.18507)
		(width 0.18288)
		(layer "In6.Cu")
		(net "M_D_CPU1_SA_DQ<6>")
	)
	(segment
		(start 23.541228 -308.995318)
		(end 23.541228 -310.05399)
		(width 0.18288)
		(layer "In6.Cu")
		(net "M_D_CPU1_SA_DQ<6>")
	)
	(segment
		(start 41.525698 -309.231538)
		(end 40.762174 -309.231538)
		(width 0.18288)
		(layer "In6.Cu")
		(net "M_D_CPU1_SA_DQ<6>")
	)
	(segment
		(start 52.483766 -303.141634)
		(end 50.675286 -303.141634)
		(width 0.18288)
		(layer "In6.Cu")
		(net "M_D_CPU1_SA_DQ<6>")
	)
	(segment
		(start 38.080188 -309.762144)
		(end 37.900356 -309.941976)
		(width 0.18288)
		(layer "In6.Cu")
		(net "M_D_CPU1_SA_DQ<6>")
	)
	(segment
		(start 58.672222 -298.230798)
		(end 58.274966 -298.230798)
		(width 0.18288)
		(layer "In6.Cu")
		(net "M_D_CPU1_SA_DQ<6>")
	)
	(segment
		(start 23.541228 -310.05399)
		(end 23.358348 -310.23687)
		(width 0.18288)
		(layer "In6.Cu")
		(net "M_D_CPU1_SA_DQ<6>")
	)
	(segment
		(start 87.972392 -274.591272)
		(end 87.9602 -274.598384)
		(width 0.088646)
		(layer "In6.Cu")
		(net "M_D_CPU1_SA_DQ<6>")
	)
	(segment
		(start 83.343242 -278.421592)
		(end 83.054698 -278.421592)
		(width 0.18288)
		(layer "In6.Cu")
		(net "M_D_CPU1_SA_DQ<6>")
	)
	(segment
		(start 35.047936 -309.653686)
		(end 34.642806 -309.653686)
		(width 0.18288)
		(layer "In6.Cu")
		(net "M_D_CPU1_SA_DQ<6>")
	)
	(segment
		(start 55.174388 -301.331376)
		(end 54.294024 -301.331376)
		(width 0.18288)
		(layer "In6.Cu")
		(net "M_D_CPU1_SA_DQ<6>")
	)
	(segment
		(start 61.214508 -296.246296)
		(end 60.1726 -297.288204)
		(width 0.18288)
		(layer "In6.Cu")
		(net "M_D_CPU1_SA_DQ<6>")
	)
	(segment
		(start 85.718142 -276.219158)
		(end 85.70341 -276.210522)
		(width 0.088646)
		(layer "In6.Cu")
		(net "M_D_CPU1_SA_DQ<6>")
	)
	(segment
		(start 45.25645 -306.65801)
		(end 44.446952 -306.65801)
		(width 0.18288)
		(layer "In6.Cu")
		(net "M_D_CPU1_SA_DQ<6>")
	)
	(segment
		(start 22.667468 -308.812438)
		(end 21.593556 -308.812438)
		(width 0.18288)
		(layer "In6.Cu")
		(net "M_D_CPU1_SA_DQ<6>")
	)
	(segment
		(start 81.153508 -279.20823)
		(end 66.809874 -293.551864)
		(width 0.18288)
		(layer "In6.Cu")
		(net "M_D_CPU1_SA_DQ<6>")
	)
	(segment
		(start 31.057342 -309.388256)
		(end 30.377892 -309.388256)
		(width 0.18288)
		(layer "In6.Cu")
		(net "M_D_CPU1_SA_DQ<6>")
	)
	(segment
		(start 49.348644 -303.74844)
		(end 48.907192 -304.189892)
		(width 0.18288)
		(layer "In6.Cu")
		(net "M_D_CPU1_SA_DQ<6>")
	)
	(segment
		(start 38.593776 -309.762144)
		(end 38.080188 -309.762144)
		(width 0.18288)
		(layer "In6.Cu")
		(net "M_D_CPU1_SA_DQ<6>")
	)
	(segment
		(start 50.515266 -302.18507)
		(end 50.355246 -302.02505)
		(width 0.18288)
		(layer "In6.Cu")
		(net "M_D_CPU1_SA_DQ<6>")
	)
	(segment
		(start 40.051736 -309.941976)
		(end 38.773608 -309.941976)
		(width 0.18288)
		(layer "In6.Cu")
		(net "M_D_CPU1_SA_DQ<6>")
	)
	(arc
		(start 95.972884 -273.785076)
		(mid 95.784887 -273.835065)
		(end 95.597218 -273.783806)
		(width 0.088646)
		(layer "In6.Cu")
		(net "M_D_CPU1_SA_DQ<6>")
	)
	(arc
		(start 92.76715 -273.777456)
		(mid 92.492951 -273.701621)
		(end 92.216478 -273.76882)
		(width 0.088646)
		(layer "In6.Cu")
		(net "M_D_CPU1_SA_DQ<6>")
	)
	(arc
		(start 87.68969 -275.08073)
		(mid 87.642011 -275.26363)
		(end 87.511128 -275.400008)
		(width 0.088646)
		(layer "In6.Cu")
		(net "M_D_CPU1_SA_DQ<6>")
	)
	(arc
		(start 94.081346 -273.777456)
		(mid 93.894148 -273.827599)
		(end 93.70695 -273.777456)
		(width 0.088646)
		(layer "In6.Cu")
		(net "M_D_CPU1_SA_DQ<6>")
	)
	(arc
		(start 87.502238 -275.405088)
		(mid 87.31504 -275.455231)
		(end 87.127842 -275.405088)
		(width 0.088646)
		(layer "In6.Cu")
		(net "M_D_CPU1_SA_DQ<6>")
	)
	(arc
		(start 91.82735 -273.777456)
		(mid 91.544648 -273.70168)
		(end 91.261946 -273.777456)
		(width 0.088646)
		(layer "In6.Cu")
		(net "M_D_CPU1_SA_DQ<6>")
	)
	(arc
		(start 89.099644 -274.266914)
		(mid 89.051965 -274.449814)
		(end 88.921082 -274.586192)
		(width 0.088646)
		(layer "In6.Cu")
		(net "M_D_CPU1_SA_DQ<6>")
	)
	(arc
		(start 89.947496 -273.777456)
		(mid 89.664794 -273.70168)
		(end 89.382092 -273.777456)
		(width 0.088646)
		(layer "In6.Cu")
		(net "M_D_CPU1_SA_DQ<6>")
	)
	(arc
		(start 95.020892 -273.777456)
		(mid 94.833694 -273.827599)
		(end 94.646496 -273.777456)
		(width 0.088646)
		(layer "In6.Cu")
		(net "M_D_CPU1_SA_DQ<6>")
	)
	(arc
		(start 86.092538 -276.219158)
		(mid 85.90534 -276.269301)
		(end 85.718142 -276.219158)
		(width 0.088646)
		(layer "In6.Cu")
		(net "M_D_CPU1_SA_DQ<6>")
	)
	(arc
		(start 92.201746 -273.777456)
		(mid 92.014548 -273.827599)
		(end 91.82735 -273.777456)
		(width 0.088646)
		(layer "In6.Cu")
		(net "M_D_CPU1_SA_DQ<6>")
	)
	(arc
		(start 88.912192 -274.591272)
		(mid 88.724994 -274.641415)
		(end 88.537796 -274.591272)
		(width 0.088646)
		(layer "In6.Cu")
		(net "M_D_CPU1_SA_DQ<6>")
	)
	(arc
		(start 88.537796 -274.591272)
		(mid 88.255094 -274.515496)
		(end 87.972392 -274.591272)
		(width 0.088646)
		(layer "In6.Cu")
		(net "M_D_CPU1_SA_DQ<6>")
	)
	(arc
		(start 90.88755 -273.777456)
		(mid 90.610737 -273.701586)
		(end 90.332306 -273.77136)
		(width 0.088646)
		(layer "In6.Cu")
		(net "M_D_CPU1_SA_DQ<6>")
	)
	(arc
		(start 89.382092 -273.777456)
		(mid 89.177757 -273.980061)
		(end 89.099644 -274.257008)
		(width 0.088646)
		(layer "In6.Cu")
		(net "M_D_CPU1_SA_DQ<6>")
	)
	(arc
		(start 96.541844 -273.7866)
		(mid 96.257575 -273.709087)
		(end 95.972884 -273.785076)
		(width 0.088646)
		(layer "In6.Cu")
		(net "M_D_CPU1_SA_DQ<6>")
	)
	(arc
		(start 90.321892 -273.777456)
		(mid 90.134694 -273.827599)
		(end 89.947496 -273.777456)
		(width 0.088646)
		(layer "In6.Cu")
		(net "M_D_CPU1_SA_DQ<6>")
	)
	(arc
		(start 91.261946 -273.777456)
		(mid 91.074748 -273.827599)
		(end 90.88755 -273.777456)
		(width 0.088646)
		(layer "In6.Cu")
		(net "M_D_CPU1_SA_DQ<6>")
	)
	(arc
		(start 94.646496 -273.777456)
		(mid 94.369937 -273.701713)
		(end 94.09176 -273.77136)
		(width 0.088646)
		(layer "In6.Cu")
		(net "M_D_CPU1_SA_DQ<6>")
	)
	(arc
		(start 86.27999 -275.8948)
		(mid 86.232311 -276.0777)
		(end 86.101428 -276.214078)
		(width 0.088646)
		(layer "In6.Cu")
		(net "M_D_CPU1_SA_DQ<6>")
	)
	(arc
		(start 86.562438 -275.405088)
		(mid 86.360152 -275.604069)
		(end 86.27999 -275.876258)
		(width 0.088646)
		(layer "In6.Cu")
		(net "M_D_CPU1_SA_DQ<6>")
	)
	(arc
		(start 87.9602 -274.598384)
		(mid 87.761972 -274.804232)
		(end 87.68969 -275.08073)
		(width 0.088646)
		(layer "In6.Cu")
		(net "M_D_CPU1_SA_DQ<6>")
	)
	(arc
		(start 95.571564 -273.76882)
		(mid 95.295089 -273.7015)
		(end 95.020892 -273.777456)
		(width 0.088646)
		(layer "In6.Cu")
		(net "M_D_CPU1_SA_DQ<6>")
	)
	(arc
		(start 93.141546 -273.777456)
		(mid 92.954348 -273.827599)
		(end 92.76715 -273.777456)
		(width 0.088646)
		(layer "In6.Cu")
		(net "M_D_CPU1_SA_DQ<6>")
	)
	(arc
		(start 87.127842 -275.405088)
		(mid 86.84514 -275.329346)
		(end 86.562438 -275.405088)
		(width 0.088646)
		(layer "In6.Cu")
		(net "M_D_CPU1_SA_DQ<6>")
	)
	(arc
		(start 93.70695 -273.777456)
		(mid 93.432751 -273.701621)
		(end 93.156278 -273.76882)
		(width 0.088646)
		(layer "In6.Cu")
		(net "M_D_CPU1_SA_DQ<6>")
	)
	(arc
		(start 85.70341 -276.210522)
		(mid 85.062843 -276.225205)
		(end 84.746846 -276.78253)
		(width 0.088646)
		(layer "In6.Cu")
		(net "M_D_CPU1_SA_DQ<6>")
	)
	(segment
		(start 10.507472 -308.23281)
		(end 11.11631 -308.23281)
		(width 0.20066)
		(layer "F.Cu")
		(net "M_D_CPU1_SA_DQ<5>")
	)
	(segment
		(start 11.1252 -308.2417)
		(end 13.110718 -308.2417)
		(width 0.1016)
		(layer "F.Cu")
		(net "M_D_CPU1_SA_DQ<5>")
	)
	(segment
		(start 14.04493 -308.666642)
		(end 15.684246 -308.666642)
		(width 0.20066)
		(layer "F.Cu")
		(net "M_D_CPU1_SA_DQ<5>")
	)
	(segment
		(start 13.619988 -308.2417)
		(end 14.04493 -308.666642)
		(width 0.20066)
		(layer "F.Cu")
		(net "M_D_CPU1_SA_DQ<5>")
	)
	(segment
		(start 13.441426 -308.2417)
		(end 13.619988 -308.2417)
		(width 0.20066)
		(layer "F.Cu")
		(net "M_D_CPU1_SA_DQ<5>")
	)
	(segment
		(start 10.344912 -308.723538)
		(end 10.344912 -308.39537)
		(width 0.20066)
		(layer "F.Cu")
		(net "M_D_CPU1_SA_DQ<5>")
	)
	(segment
		(start 13.110718 -308.2417)
		(end 13.441426 -308.2417)
		(width 0.101854)
		(layer "F.Cu")
		(net "M_D_CPU1_SA_DQ<5>")
	)
	(segment
		(start 8.140446 -308.666642)
		(end 9.474708 -308.666642)
		(width 0.20066)
		(layer "F.Cu")
		(net "M_D_CPU1_SA_DQ<5>")
	)
	(segment
		(start 9.474708 -308.666642)
		(end 9.686036 -308.87797)
		(width 0.20066)
		(layer "F.Cu")
		(net "M_D_CPU1_SA_DQ<5>")
	)
	(segment
		(start 10.344912 -308.39537)
		(end 10.507472 -308.23281)
		(width 0.20066)
		(layer "F.Cu")
		(net "M_D_CPU1_SA_DQ<5>")
	)
	(segment
		(start 15.684246 -308.666642)
		(end 16.789146 -308.666642)
		(width 0.20066)
		(layer "F.Cu")
		(net "M_D_CPU1_SA_DQ<5>")
	)
	(segment
		(start 9.686036 -308.87797)
		(end 10.19048 -308.87797)
		(width 0.20066)
		(layer "F.Cu")
		(net "M_D_CPU1_SA_DQ<5>")
	)
	(segment
		(start 11.11631 -308.23281)
		(end 11.1252 -308.2417)
		(width 0.1016)
		(layer "F.Cu")
		(net "M_D_CPU1_SA_DQ<5>")
	)
	(segment
		(start 10.19048 -308.87797)
		(end 10.344912 -308.723538)
		(width 0.20066)
		(layer "F.Cu")
		(net "M_D_CPU1_SA_DQ<5>")
	)
	(arc
		(start 95.773494 -272.917158)
		(mid 95.773557 -273.185128)
		(end 95.773748 -273.453098)
		(width 0.20066)
		(layer "F.Cu")
		(net "M_D_CPU1_SA_DQ<5>")
	)
	(segment
		(start 48.15078 -303.12868)
		(end 48.15078 -303.865534)
		(width 0.18288)
		(layer "In6.Cu")
		(net "M_D_CPU1_SA_DQ<5>")
	)
	(segment
		(start 39.373302 -309.092092)
		(end 39.059866 -308.778656)
		(width 0.18288)
		(layer "In6.Cu")
		(net "M_D_CPU1_SA_DQ<5>")
	)
	(segment
		(start 19.469862 -308.058566)
		(end 19.286982 -308.241446)
		(width 0.18288)
		(layer "In6.Cu")
		(net "M_D_CPU1_SA_DQ<5>")
	)
	(segment
		(start 18.778982 -307.61432)
		(end 18.596102 -307.43144)
		(width 0.18288)
		(layer "In6.Cu")
		(net "M_D_CPU1_SA_DQ<5>")
	)
	(segment
		(start 93.156278 -273.137376)
		(end 93.141546 -273.12874)
		(width 0.088646)
		(layer "In6.Cu")
		(net "M_D_CPU1_SA_DQ<5>")
	)
	(segment
		(start 41.167304 -308.072028)
		(end 40.14724 -309.092092)
		(width 0.18288)
		(layer "In6.Cu")
		(net "M_D_CPU1_SA_DQ<5>")
	)
	(segment
		(start 88.820244 -273.453098)
		(end 88.820244 -273.463004)
		(width 0.088646)
		(layer "In6.Cu")
		(net "M_D_CPU1_SA_DQ<5>")
	)
	(segment
		(start 92.216478 -273.137376)
		(end 92.201746 -273.12874)
		(width 0.088646)
		(layer "In6.Cu")
		(net "M_D_CPU1_SA_DQ<5>")
	)
	(segment
		(start 65.861184 -293.205916)
		(end 63.322962 -295.744138)
		(width 0.18288)
		(layer "In6.Cu")
		(net "M_D_CPU1_SA_DQ<5>")
	)
	(segment
		(start 46.310804 -304.841656)
		(end 45.610526 -305.541934)
		(width 0.18288)
		(layer "In6.Cu")
		(net "M_D_CPU1_SA_DQ<5>")
	)
	(segment
		(start 18.088102 -307.61432)
		(end 18.088102 -308.058566)
		(width 0.18288)
		(layer "In6.Cu")
		(net "M_D_CPU1_SA_DQ<5>")
	)
	(segment
		(start 95.773748 -273.453098)
		(end 96.086422 -273.453098)
		(width 0.088646)
		(layer "In6.Cu")
		(net "M_D_CPU1_SA_DQ<5>")
	)
	(segment
		(start 19.286982 -308.241446)
		(end 18.961862 -308.241446)
		(width 0.18288)
		(layer "In6.Cu")
		(net "M_D_CPU1_SA_DQ<5>")
	)
	(segment
		(start 90.88755 -273.12874)
		(end 90.877136 -273.134836)
		(width 0.088646)
		(layer "In6.Cu")
		(net "M_D_CPU1_SA_DQ<5>")
	)
	(segment
		(start 58.852054 -297.08983)
		(end 58.398918 -297.08983)
		(width 0.18288)
		(layer "In6.Cu")
		(net "M_D_CPU1_SA_DQ<5>")
	)
	(segment
		(start 43.772074 -306.415186)
		(end 43.352466 -306.415186)
		(width 0.18288)
		(layer "In6.Cu")
		(net "M_D_CPU1_SA_DQ<5>")
	)
	(segment
		(start 59.900312 -296.041572)
		(end 58.852054 -297.08983)
		(width 0.18288)
		(layer "In6.Cu")
		(net "M_D_CPU1_SA_DQ<5>")
	)
	(segment
		(start 39.059866 -308.778656)
		(end 38.682422 -308.778656)
		(width 0.18288)
		(layer "In6.Cu")
		(net "M_D_CPU1_SA_DQ<5>")
	)
	(segment
		(start 60.64758 -296.041572)
		(end 59.900312 -296.041572)
		(width 0.18288)
		(layer "In6.Cu")
		(net "M_D_CPU1_SA_DQ<5>")
	)
	(segment
		(start 56.043068 -298.801028)
		(end 55.13578 -299.708316)
		(width 0.18288)
		(layer "In6.Cu")
		(net "M_D_CPU1_SA_DQ<5>")
	)
	(segment
		(start 47.174658 -304.841656)
		(end 46.310804 -304.841656)
		(width 0.18288)
		(layer "In6.Cu")
		(net "M_D_CPU1_SA_DQ<5>")
	)
	(segment
		(start 86.00059 -275.08073)
		(end 86.00059 -275.099272)
		(width 0.088646)
		(layer "In6.Cu")
		(net "M_D_CPU1_SA_DQ<5>")
	)
	(segment
		(start 83.145376 -277.816818)
		(end 80.677258 -278.839168)
		(width 0.18288)
		(layer "In6.Cu")
		(net "M_D_CPU1_SA_DQ<5>")
	)
	(segment
		(start 18.596102 -307.43144)
		(end 18.270982 -307.43144)
		(width 0.18288)
		(layer "In6.Cu")
		(net "M_D_CPU1_SA_DQ<5>")
	)
	(segment
		(start 37.678106 -308.778656)
		(end 37.300662 -308.778656)
		(width 0.18288)
		(layer "In6.Cu")
		(net "M_D_CPU1_SA_DQ<5>")
	)
	(segment
		(start 18.088102 -308.058566)
		(end 17.905222 -308.241446)
		(width 0.18288)
		(layer "In6.Cu")
		(net "M_D_CPU1_SA_DQ<5>")
	)
	(segment
		(start 83.343242 -277.816818)
		(end 83.145376 -277.816818)
		(width 0.18288)
		(layer "In6.Cu")
		(net "M_D_CPU1_SA_DQ<5>")
	)
	(segment
		(start 20.160742 -308.058566)
		(end 20.160742 -307.076094)
		(width 0.18288)
		(layer "In6.Cu")
		(net "M_D_CPU1_SA_DQ<5>")
	)
	(segment
		(start 37.991542 -309.092092)
		(end 37.678106 -308.778656)
		(width 0.18288)
		(layer "In6.Cu")
		(net "M_D_CPU1_SA_DQ<5>")
	)
	(segment
		(start 19.977862 -306.893214)
		(end 19.670268 -306.893214)
		(width 0.18288)
		(layer "In6.Cu")
		(net "M_D_CPU1_SA_DQ<5>")
	)
	(segment
		(start 89.007696 -273.12874)
		(end 88.998806 -273.13382)
		(width 0.088646)
		(layer "In6.Cu")
		(net "M_D_CPU1_SA_DQ<5>")
	)
	(segment
		(start 96.086422 -273.453098)
		(end 96.143826 -273.395694)
		(width 0.088646)
		(layer "In6.Cu")
		(net "M_D_CPU1_SA_DQ<5>")
	)
	(segment
		(start 91.276678 -273.137376)
		(end 91.261946 -273.12874)
		(width 0.088646)
		(layer "In6.Cu")
		(net "M_D_CPU1_SA_DQ<5>")
	)
	(segment
		(start 87.127842 -274.756372)
		(end 87.11311 -274.765008)
		(width 0.088646)
		(layer "In6.Cu")
		(net "M_D_CPU1_SA_DQ<5>")
	)
	(segment
		(start 84.033614 -277.816818)
		(end 83.343242 -277.816818)
		(width 0.088646)
		(layer "In6.Cu")
		(net "M_D_CPU1_SA_DQ<5>")
	)
	(segment
		(start 86.188042 -274.756372)
		(end 86.179152 -274.761452)
		(width 0.088646)
		(layer "In6.Cu")
		(net "M_D_CPU1_SA_DQ<5>")
	)
	(segment
		(start 58.398918 -297.08983)
		(end 56.68772 -298.801028)
		(width 0.18288)
		(layer "In6.Cu")
		(net "M_D_CPU1_SA_DQ<5>")
	)
	(segment
		(start 38.368986 -309.092092)
		(end 37.991542 -309.092092)
		(width 0.18288)
		(layer "In6.Cu")
		(net "M_D_CPU1_SA_DQ<5>")
	)
	(segment
		(start 56.68772 -298.801028)
		(end 56.043068 -298.801028)
		(width 0.18288)
		(layer "In6.Cu")
		(net "M_D_CPU1_SA_DQ<5>")
	)
	(segment
		(start 54.219602 -300.649386)
		(end 53.427122 -301.441866)
		(width 0.18288)
		(layer "In6.Cu")
		(net "M_D_CPU1_SA_DQ<5>")
	)
	(segment
		(start 84.308696 -276.384258)
		(end 84.308696 -277.541736)
		(width 0.088646)
		(layer "In6.Cu")
		(net "M_D_CPU1_SA_DQ<5>")
	)
	(segment
		(start 19.670268 -306.893214)
		(end 19.469862 -307.09362)
		(width 0.18288)
		(layer "In6.Cu")
		(net "M_D_CPU1_SA_DQ<5>")
	)
	(segment
		(start 44.645326 -305.541934)
		(end 43.772074 -306.415186)
		(width 0.18288)
		(layer "In6.Cu")
		(net "M_D_CPU1_SA_DQ<5>")
	)
	(segment
		(start 60.945014 -295.744138)
		(end 60.64758 -296.041572)
		(width 0.18288)
		(layer "In6.Cu")
		(net "M_D_CPU1_SA_DQ<5>")
	)
	(segment
		(start 33.262824 -309.092092)
		(end 32.412178 -308.241446)
		(width 0.18288)
		(layer "In6.Cu")
		(net "M_D_CPU1_SA_DQ<5>")
	)
	(segment
		(start 19.469862 -307.09362)
		(end 19.469862 -308.058566)
		(width 0.18288)
		(layer "In6.Cu")
		(net "M_D_CPU1_SA_DQ<5>")
	)
	(segment
		(start 54.723538 -300.649386)
		(end 54.219602 -300.649386)
		(width 0.18288)
		(layer "In6.Cu")
		(net "M_D_CPU1_SA_DQ<5>")
	)
	(segment
		(start 18.961862 -308.241446)
		(end 18.778982 -308.058566)
		(width 0.18288)
		(layer "In6.Cu")
		(net "M_D_CPU1_SA_DQ<5>")
	)
	(segment
		(start 55.13578 -299.708316)
		(end 55.13578 -300.237144)
		(width 0.18288)
		(layer "In6.Cu")
		(net "M_D_CPU1_SA_DQ<5>")
	)
	(segment
		(start 41.695624 -308.072028)
		(end 41.167304 -308.072028)
		(width 0.18288)
		(layer "In6.Cu")
		(net "M_D_CPU1_SA_DQ<5>")
	)
	(segment
		(start 63.322962 -295.744138)
		(end 60.945014 -295.744138)
		(width 0.18288)
		(layer "In6.Cu")
		(net "M_D_CPU1_SA_DQ<5>")
	)
	(segment
		(start 95.031306 -273.134836)
		(end 95.020892 -273.12874)
		(width 0.088646)
		(layer "In6.Cu")
		(net "M_D_CPU1_SA_DQ<5>")
	)
	(segment
		(start 32.412178 -308.241446)
		(end 20.343622 -308.241446)
		(width 0.18288)
		(layer "In6.Cu")
		(net "M_D_CPU1_SA_DQ<5>")
	)
	(segment
		(start 18.778982 -308.058566)
		(end 18.778982 -307.61432)
		(width 0.18288)
		(layer "In6.Cu")
		(net "M_D_CPU1_SA_DQ<5>")
	)
	(segment
		(start 49.837594 -301.441866)
		(end 48.15078 -303.12868)
		(width 0.18288)
		(layer "In6.Cu")
		(net "M_D_CPU1_SA_DQ<5>")
	)
	(segment
		(start 87.597996 -273.942556)
		(end 87.589106 -273.947636)
		(width 0.088646)
		(layer "In6.Cu")
		(net "M_D_CPU1_SA_DQ<5>")
	)
	(segment
		(start 84.59089 -275.8948)
		(end 84.59089 -275.910294)
		(width 0.088646)
		(layer "In6.Cu")
		(net "M_D_CPU1_SA_DQ<5>")
	)
	(segment
		(start 55.13578 -300.237144)
		(end 54.723538 -300.649386)
		(width 0.18288)
		(layer "In6.Cu")
		(net "M_D_CPU1_SA_DQ<5>")
	)
	(segment
		(start 80.677258 -278.839168)
		(end 66.31051 -293.205916)
		(width 0.18288)
		(layer "In6.Cu")
		(net "M_D_CPU1_SA_DQ<5>")
	)
	(segment
		(start 53.427122 -301.441866)
		(end 49.837594 -301.441866)
		(width 0.18288)
		(layer "In6.Cu")
		(net "M_D_CPU1_SA_DQ<5>")
	)
	(segment
		(start 84.778342 -275.570442)
		(end 84.769452 -275.575522)
		(width 0.088646)
		(layer "In6.Cu")
		(net "M_D_CPU1_SA_DQ<5>")
	)
	(segment
		(start 38.682422 -308.778656)
		(end 38.368986 -309.092092)
		(width 0.18288)
		(layer "In6.Cu")
		(net "M_D_CPU1_SA_DQ<5>")
	)
	(segment
		(start 20.160742 -307.076094)
		(end 19.977862 -306.893214)
		(width 0.18288)
		(layer "In6.Cu")
		(net "M_D_CPU1_SA_DQ<5>")
	)
	(segment
		(start 36.987226 -309.092092)
		(end 33.262824 -309.092092)
		(width 0.18288)
		(layer "In6.Cu")
		(net "M_D_CPU1_SA_DQ<5>")
	)
	(segment
		(start 87.133938 -274.752816)
		(end 87.127842 -274.756372)
		(width 0.088646)
		(layer "In6.Cu")
		(net "M_D_CPU1_SA_DQ<5>")
	)
	(segment
		(start 66.31051 -293.205916)
		(end 65.861184 -293.205916)
		(width 0.18288)
		(layer "In6.Cu")
		(net "M_D_CPU1_SA_DQ<5>")
	)
	(segment
		(start 37.300662 -308.778656)
		(end 36.987226 -309.092092)
		(width 0.18288)
		(layer "In6.Cu")
		(net "M_D_CPU1_SA_DQ<5>")
	)
	(segment
		(start 43.352466 -306.415186)
		(end 41.695624 -308.072028)
		(width 0.18288)
		(layer "In6.Cu")
		(net "M_D_CPU1_SA_DQ<5>")
	)
	(segment
		(start 40.14724 -309.092092)
		(end 39.373302 -309.092092)
		(width 0.18288)
		(layer "In6.Cu")
		(net "M_D_CPU1_SA_DQ<5>")
	)
	(segment
		(start 18.270982 -307.43144)
		(end 18.088102 -307.61432)
		(width 0.18288)
		(layer "In6.Cu")
		(net "M_D_CPU1_SA_DQ<5>")
	)
	(segment
		(start 17.214342 -308.241446)
		(end 16.789146 -308.666642)
		(width 0.18288)
		(layer "In6.Cu")
		(net "M_D_CPU1_SA_DQ<5>")
	)
	(segment
		(start 94.09176 -273.134836)
		(end 94.081346 -273.12874)
		(width 0.088646)
		(layer "In6.Cu")
		(net "M_D_CPU1_SA_DQ<5>")
	)
	(segment
		(start 17.905222 -308.241446)
		(end 17.214342 -308.241446)
		(width 0.18288)
		(layer "In6.Cu")
		(net "M_D_CPU1_SA_DQ<5>")
	)
	(segment
		(start 20.343622 -308.241446)
		(end 20.160742 -308.058566)
		(width 0.18288)
		(layer "In6.Cu")
		(net "M_D_CPU1_SA_DQ<5>")
	)
	(segment
		(start 84.308696 -277.541736)
		(end 84.033614 -277.816818)
		(width 0.088646)
		(layer "In6.Cu")
		(net "M_D_CPU1_SA_DQ<5>")
	)
	(segment
		(start 48.15078 -303.865534)
		(end 47.174658 -304.841656)
		(width 0.18288)
		(layer "In6.Cu")
		(net "M_D_CPU1_SA_DQ<5>")
	)
	(segment
		(start 45.610526 -305.541934)
		(end 44.645326 -305.541934)
		(width 0.18288)
		(layer "In6.Cu")
		(net "M_D_CPU1_SA_DQ<5>")
	)
	(arc
		(start 93.141546 -273.12874)
		(mid 92.954348 -273.078597)
		(end 92.76715 -273.12874)
		(width 0.088646)
		(layer "In6.Cu")
		(net "M_D_CPU1_SA_DQ<5>")
	)
	(arc
		(start 85.152738 -275.570442)
		(mid 84.96554 -275.520299)
		(end 84.778342 -275.570442)
		(width 0.088646)
		(layer "In6.Cu")
		(net "M_D_CPU1_SA_DQ<5>")
	)
	(arc
		(start 86.179152 -274.761452)
		(mid 86.048238 -274.897812)
		(end 86.00059 -275.08073)
		(width 0.088646)
		(layer "In6.Cu")
		(net "M_D_CPU1_SA_DQ<5>")
	)
	(arc
		(start 93.70695 -273.12874)
		(mid 93.432751 -273.204575)
		(end 93.156278 -273.137376)
		(width 0.088646)
		(layer "In6.Cu")
		(net "M_D_CPU1_SA_DQ<5>")
	)
	(arc
		(start 88.820244 -273.463004)
		(mid 88.742133 -273.739953)
		(end 88.537796 -273.942556)
		(width 0.088646)
		(layer "In6.Cu")
		(net "M_D_CPU1_SA_DQ<5>")
	)
	(arc
		(start 84.59089 -275.910294)
		(mid 84.51152 -276.184028)
		(end 84.308696 -276.384258)
		(width 0.088646)
		(layer "In6.Cu")
		(net "M_D_CPU1_SA_DQ<5>")
	)
	(arc
		(start 95.58655 -273.12874)
		(mid 95.309737 -273.20461)
		(end 95.031306 -273.134836)
		(width 0.088646)
		(layer "In6.Cu")
		(net "M_D_CPU1_SA_DQ<5>")
	)
	(arc
		(start 85.718142 -275.570442)
		(mid 85.43544 -275.646184)
		(end 85.152738 -275.570442)
		(width 0.088646)
		(layer "In6.Cu")
		(net "M_D_CPU1_SA_DQ<5>")
	)
	(arc
		(start 86.00059 -275.099272)
		(mid 85.920428 -275.371461)
		(end 85.718142 -275.570442)
		(width 0.088646)
		(layer "In6.Cu")
		(net "M_D_CPU1_SA_DQ<5>")
	)
	(arc
		(start 94.646496 -273.12874)
		(mid 94.369937 -273.204483)
		(end 94.09176 -273.134836)
		(width 0.088646)
		(layer "In6.Cu")
		(net "M_D_CPU1_SA_DQ<5>")
	)
	(arc
		(start 87.589106 -273.947636)
		(mid 87.458192 -274.083996)
		(end 87.410544 -274.266914)
		(width 0.088646)
		(layer "In6.Cu")
		(net "M_D_CPU1_SA_DQ<5>")
	)
	(arc
		(start 96.143826 -273.395694)
		(mid 95.935543 -273.115348)
		(end 95.58655 -273.12874)
		(width 0.088646)
		(layer "In6.Cu")
		(net "M_D_CPU1_SA_DQ<5>")
	)
	(arc
		(start 91.82735 -273.12874)
		(mid 91.553151 -273.204575)
		(end 91.276678 -273.137376)
		(width 0.088646)
		(layer "In6.Cu")
		(net "M_D_CPU1_SA_DQ<5>")
	)
	(arc
		(start 91.261946 -273.12874)
		(mid 91.074748 -273.078597)
		(end 90.88755 -273.12874)
		(width 0.088646)
		(layer "In6.Cu")
		(net "M_D_CPU1_SA_DQ<5>")
	)
	(arc
		(start 89.382092 -273.12874)
		(mid 89.194894 -273.078597)
		(end 89.007696 -273.12874)
		(width 0.088646)
		(layer "In6.Cu")
		(net "M_D_CPU1_SA_DQ<5>")
	)
	(arc
		(start 87.972392 -273.942556)
		(mid 87.785194 -273.892413)
		(end 87.597996 -273.942556)
		(width 0.088646)
		(layer "In6.Cu")
		(net "M_D_CPU1_SA_DQ<5>")
	)
	(arc
		(start 95.020892 -273.12874)
		(mid 94.833694 -273.078597)
		(end 94.646496 -273.12874)
		(width 0.088646)
		(layer "In6.Cu")
		(net "M_D_CPU1_SA_DQ<5>")
	)
	(arc
		(start 90.321892 -273.12874)
		(mid 90.134694 -273.078597)
		(end 89.947496 -273.12874)
		(width 0.088646)
		(layer "In6.Cu")
		(net "M_D_CPU1_SA_DQ<5>")
	)
	(arc
		(start 92.201746 -273.12874)
		(mid 92.014548 -273.078597)
		(end 91.82735 -273.12874)
		(width 0.088646)
		(layer "In6.Cu")
		(net "M_D_CPU1_SA_DQ<5>")
	)
	(arc
		(start 88.537796 -273.942556)
		(mid 88.255094 -274.018332)
		(end 87.972392 -273.942556)
		(width 0.088646)
		(layer "In6.Cu")
		(net "M_D_CPU1_SA_DQ<5>")
	)
	(arc
		(start 92.76715 -273.12874)
		(mid 92.492951 -273.204575)
		(end 92.216478 -273.137376)
		(width 0.088646)
		(layer "In6.Cu")
		(net "M_D_CPU1_SA_DQ<5>")
	)
	(arc
		(start 84.769452 -275.575522)
		(mid 84.638538 -275.711882)
		(end 84.59089 -275.8948)
		(width 0.088646)
		(layer "In6.Cu")
		(net "M_D_CPU1_SA_DQ<5>")
	)
	(arc
		(start 87.410544 -274.266914)
		(mid 87.336553 -274.54648)
		(end 87.133938 -274.752816)
		(width 0.088646)
		(layer "In6.Cu")
		(net "M_D_CPU1_SA_DQ<5>")
	)
	(arc
		(start 88.998806 -273.13382)
		(mid 88.867892 -273.27018)
		(end 88.820244 -273.453098)
		(width 0.088646)
		(layer "In6.Cu")
		(net "M_D_CPU1_SA_DQ<5>")
	)
	(arc
		(start 89.947496 -273.12874)
		(mid 89.664794 -273.204516)
		(end 89.382092 -273.12874)
		(width 0.088646)
		(layer "In6.Cu")
		(net "M_D_CPU1_SA_DQ<5>")
	)
	(arc
		(start 94.081346 -273.12874)
		(mid 93.894148 -273.078597)
		(end 93.70695 -273.12874)
		(width 0.088646)
		(layer "In6.Cu")
		(net "M_D_CPU1_SA_DQ<5>")
	)
	(arc
		(start 86.562438 -274.756372)
		(mid 86.37524 -274.706229)
		(end 86.188042 -274.756372)
		(width 0.088646)
		(layer "In6.Cu")
		(net "M_D_CPU1_SA_DQ<5>")
	)
	(arc
		(start 90.877136 -273.134836)
		(mid 90.598704 -273.204682)
		(end 90.321892 -273.12874)
		(width 0.088646)
		(layer "In6.Cu")
		(net "M_D_CPU1_SA_DQ<5>")
	)
	(arc
		(start 87.11311 -274.765008)
		(mid 86.836635 -274.832328)
		(end 86.562438 -274.756372)
		(width 0.088646)
		(layer "In6.Cu")
		(net "M_D_CPU1_SA_DQ<5>")
	)
	(segment
		(start 9.474708 -310.366664)
		(end 9.713468 -310.605424)
		(width 0.20066)
		(layer "F.Cu")
		(net "M_D_CPU1_SA_DQ<4>")
	)
	(segment
		(start 10.172192 -310.605424)
		(end 10.344912 -310.432704)
		(width 0.20066)
		(layer "F.Cu")
		(net "M_D_CPU1_SA_DQ<4>")
	)
	(segment
		(start 10.344912 -310.143144)
		(end 10.554462 -309.933594)
		(width 0.20066)
		(layer "F.Cu")
		(net "M_D_CPU1_SA_DQ<4>")
	)
	(segment
		(start 13.441426 -309.941722)
		(end 13.890244 -309.941722)
		(width 0.20066)
		(layer "F.Cu")
		(net "M_D_CPU1_SA_DQ<4>")
	)
	(segment
		(start 10.554462 -309.933594)
		(end 11.11631 -309.933594)
		(width 0.20066)
		(layer "F.Cu")
		(net "M_D_CPU1_SA_DQ<4>")
	)
	(segment
		(start 10.344912 -310.432704)
		(end 10.344912 -310.143144)
		(width 0.20066)
		(layer "F.Cu")
		(net "M_D_CPU1_SA_DQ<4>")
	)
	(segment
		(start 95.303848 -273.730974)
		(end 95.303848 -274.26666)
		(width 0.20066)
		(layer "F.Cu")
		(net "M_D_CPU1_SA_DQ<4>")
	)
	(segment
		(start 95.303848 -274.26666)
		(end 95.303594 -274.266914)
		(width 0.20066)
		(layer "F.Cu")
		(net "M_D_CPU1_SA_DQ<4>")
	)
	(segment
		(start 11.124438 -309.941722)
		(end 11.372342 -309.941722)
		(width 0.101854)
		(layer "F.Cu")
		(net "M_D_CPU1_SA_DQ<4>")
	)
	(segment
		(start 14.315186 -310.366664)
		(end 15.684246 -310.366664)
		(width 0.20066)
		(layer "F.Cu")
		(net "M_D_CPU1_SA_DQ<4>")
	)
	(segment
		(start 13.890244 -309.941722)
		(end 14.315186 -310.366664)
		(width 0.20066)
		(layer "F.Cu")
		(net "M_D_CPU1_SA_DQ<4>")
	)
	(segment
		(start 11.11631 -309.933594)
		(end 11.124438 -309.941722)
		(width 0.101854)
		(layer "F.Cu")
		(net "M_D_CPU1_SA_DQ<4>")
	)
	(segment
		(start 15.684246 -310.366664)
		(end 16.789146 -310.366664)
		(width 0.20066)
		(layer "F.Cu")
		(net "M_D_CPU1_SA_DQ<4>")
	)
	(segment
		(start 11.372342 -309.941722)
		(end 13.441426 -309.941722)
		(width 0.1016)
		(layer "F.Cu")
		(net "M_D_CPU1_SA_DQ<4>")
	)
	(segment
		(start 9.713468 -310.605424)
		(end 10.172192 -310.605424)
		(width 0.20066)
		(layer "F.Cu")
		(net "M_D_CPU1_SA_DQ<4>")
	)
	(segment
		(start 8.140446 -310.366664)
		(end 9.474708 -310.366664)
		(width 0.20066)
		(layer "F.Cu")
		(net "M_D_CPU1_SA_DQ<4>")
	)
	(segment
		(start 57.084468 -300.128432)
		(end 57.084468 -301.034196)
		(width 0.18288)
		(layer "In6.Cu")
		(net "M_D_CPU1_SA_DQ<4>")
	)
	(segment
		(start 21.466048 -309.941468)
		(end 20.157694 -309.941468)
		(width 0.18288)
		(layer "In6.Cu")
		(net "M_D_CPU1_SA_DQ<4>")
	)
	(segment
		(start 34.509456 -310.792114)
		(end 33.431988 -310.792114)
		(width 0.18288)
		(layer "In6.Cu")
		(net "M_D_CPU1_SA_DQ<4>")
	)
	(segment
		(start 33.431988 -310.792114)
		(end 33.094676 -310.652414)
		(width 0.18288)
		(layer "In6.Cu")
		(net "M_D_CPU1_SA_DQ<4>")
	)
	(segment
		(start 60.37072 -297.920664)
		(end 59.708034 -297.920664)
		(width 0.18288)
		(layer "In6.Cu")
		(net "M_D_CPU1_SA_DQ<4>")
	)
	(segment
		(start 46.109382 -306.541678)
		(end 45.379132 -307.271928)
		(width 0.18288)
		(layer "In6.Cu")
		(net "M_D_CPU1_SA_DQ<4>")
	)
	(segment
		(start 22.25929 -310.73471)
		(end 21.466048 -309.941468)
		(width 0.18288)
		(layer "In6.Cu")
		(net "M_D_CPU1_SA_DQ<4>")
	)
	(segment
		(start 48.27778 -305.199796)
		(end 48.27778 -305.669188)
		(width 0.18288)
		(layer "In6.Cu")
		(net "M_D_CPU1_SA_DQ<4>")
	)
	(segment
		(start 58.889392 -298.739306)
		(end 58.473594 -298.739306)
		(width 0.18288)
		(layer "In6.Cu")
		(net "M_D_CPU1_SA_DQ<4>")
	)
	(segment
		(start 43.702224 -308.127908)
		(end 43.41114 -308.127908)
		(width 0.18288)
		(layer "In6.Cu")
		(net "M_D_CPU1_SA_DQ<4>")
	)
	(segment
		(start 38.499542 -311.02808)
		(end 38.067488 -311.02808)
		(width 0.18288)
		(layer "In6.Cu")
		(net "M_D_CPU1_SA_DQ<4>")
	)
	(segment
		(start 61.065156 -297.226228)
		(end 60.37072 -297.920664)
		(width 0.18288)
		(layer "In6.Cu")
		(net "M_D_CPU1_SA_DQ<4>")
	)
	(segment
		(start 63.20663 -297.114722)
		(end 63.095124 -297.226228)
		(width 0.18288)
		(layer "In6.Cu")
		(net "M_D_CPU1_SA_DQ<4>")
	)
	(segment
		(start 89.477596 -273.942556)
		(end 89.468706 -273.947636)
		(width 0.088646)
		(layer "In6.Cu")
		(net "M_D_CPU1_SA_DQ<4>")
	)
	(segment
		(start 64.202564 -297.114722)
		(end 63.20663 -297.114722)
		(width 0.18288)
		(layer "In6.Cu")
		(net "M_D_CPU1_SA_DQ<4>")
	)
	(segment
		(start 19.974814 -311.33034)
		(end 19.791934 -311.51322)
		(width 0.18288)
		(layer "In6.Cu")
		(net "M_D_CPU1_SA_DQ<4>")
	)
	(segment
		(start 86.47049 -275.8948)
		(end 86.47049 -275.910294)
		(width 0.088646)
		(layer "In6.Cu")
		(net "M_D_CPU1_SA_DQ<4>")
	)
	(segment
		(start 85.316568 -276.424644)
		(end 84.937092 -276.80412)
		(width 0.088646)
		(layer "In6.Cu")
		(net "M_D_CPU1_SA_DQ<4>")
	)
	(segment
		(start 59.708034 -297.920664)
		(end 58.889392 -298.739306)
		(width 0.18288)
		(layer "In6.Cu")
		(net "M_D_CPU1_SA_DQ<4>")
	)
	(segment
		(start 81.407762 -279.690322)
		(end 67.438778 -293.659306)
		(width 0.18288)
		(layer "In6.Cu")
		(net "M_D_CPU1_SA_DQ<4>")
	)
	(segment
		(start 25.635458 -309.941468)
		(end 24.842216 -310.73471)
		(width 0.18288)
		(layer "In6.Cu")
		(net "M_D_CPU1_SA_DQ<4>")
	)
	(segment
		(start 55.826152 -301.597822)
		(end 54.914292 -302.509682)
		(width 0.18288)
		(layer "In6.Cu")
		(net "M_D_CPU1_SA_DQ<4>")
	)
	(segment
		(start 19.101054 -309.941468)
		(end 17.214342 -309.941468)
		(width 0.18288)
		(layer "In6.Cu")
		(net "M_D_CPU1_SA_DQ<4>")
	)
	(segment
		(start 87.880444 -275.08073)
		(end 87.880444 -275.08835)
		(width 0.088646)
		(layer "In6.Cu")
		(net "M_D_CPU1_SA_DQ<4>")
	)
	(segment
		(start 34.829496 -311.32272)
		(end 34.669476 -311.1627)
		(width 0.18288)
		(layer "In6.Cu")
		(net "M_D_CPU1_SA_DQ<4>")
	)
	(segment
		(start 85.637624 -276.392894)
		(end 85.622892 -276.384258)
		(width 0.088646)
		(layer "In6.Cu")
		(net "M_D_CPU1_SA_DQ<4>")
	)
	(segment
		(start 48.738282 -304.739294)
		(end 48.27778 -305.199796)
		(width 0.18288)
		(layer "In6.Cu")
		(net "M_D_CPU1_SA_DQ<4>")
	)
	(segment
		(start 41.01592 -309.808372)
		(end 40.032178 -310.792114)
		(width 0.18288)
		(layer "In6.Cu")
		(net "M_D_CPU1_SA_DQ<4>")
	)
	(segment
		(start 67.438778 -294.443404)
		(end 66.5988 -295.283382)
		(width 0.18288)
		(layer "In6.Cu")
		(net "M_D_CPU1_SA_DQ<4>")
	)
	(segment
		(start 35.202876 -311.32272)
		(end 34.829496 -311.32272)
		(width 0.18288)
		(layer "In6.Cu")
		(net "M_D_CPU1_SA_DQ<4>")
	)
	(segment
		(start 38.067488 -311.02808)
		(end 37.831522 -310.792114)
		(width 0.18288)
		(layer "In6.Cu")
		(net "M_D_CPU1_SA_DQ<4>")
	)
	(segment
		(start 52.40274 -303.991772)
		(end 50.234088 -303.991772)
		(width 0.18288)
		(layer "In6.Cu")
		(net "M_D_CPU1_SA_DQ<4>")
	)
	(segment
		(start 53.88483 -302.509682)
		(end 52.40274 -303.991772)
		(width 0.18288)
		(layer "In6.Cu")
		(net "M_D_CPU1_SA_DQ<4>")
	)
	(segment
		(start 24.842216 -310.73471)
		(end 22.25929 -310.73471)
		(width 0.18288)
		(layer "In6.Cu")
		(net "M_D_CPU1_SA_DQ<4>")
	)
	(segment
		(start 58.473594 -298.739306)
		(end 57.084468 -300.128432)
		(width 0.18288)
		(layer "In6.Cu")
		(net "M_D_CPU1_SA_DQ<4>")
	)
	(segment
		(start 91.35745 -273.942556)
		(end 91.347036 -273.948652)
		(width 0.088646)
		(layer "In6.Cu")
		(net "M_D_CPU1_SA_DQ<4>")
	)
	(segment
		(start 84.937092 -277.697438)
		(end 83.69808 -278.93645)
		(width 0.088646)
		(layer "In6.Cu")
		(net "M_D_CPU1_SA_DQ<4>")
	)
	(segment
		(start 35.362896 -311.1627)
		(end 35.202876 -311.32272)
		(width 0.18288)
		(layer "In6.Cu")
		(net "M_D_CPU1_SA_DQ<4>")
	)
	(segment
		(start 20.157694 -309.941468)
		(end 19.974814 -310.124348)
		(width 0.18288)
		(layer "In6.Cu")
		(net "M_D_CPU1_SA_DQ<4>")
	)
	(segment
		(start 17.214342 -309.941468)
		(end 16.789146 -310.366664)
		(width 0.18288)
		(layer "In6.Cu")
		(net "M_D_CPU1_SA_DQ<4>")
	)
	(segment
		(start 19.791934 -311.51322)
		(end 19.466814 -311.51322)
		(width 0.18288)
		(layer "In6.Cu")
		(net "M_D_CPU1_SA_DQ<4>")
	)
	(segment
		(start 19.466814 -311.51322)
		(end 19.283934 -311.33034)
		(width 0.18288)
		(layer "In6.Cu")
		(net "M_D_CPU1_SA_DQ<4>")
	)
	(segment
		(start 92.296996 -273.942556)
		(end 92.286582 -273.948652)
		(width 0.088646)
		(layer "In6.Cu")
		(net "M_D_CPU1_SA_DQ<4>")
	)
	(segment
		(start 89.290144 -274.266914)
		(end 89.290144 -274.27682)
		(width 0.088646)
		(layer "In6.Cu")
		(net "M_D_CPU1_SA_DQ<4>")
	)
	(segment
		(start 94.176596 -273.942556)
		(end 94.161864 -273.951192)
		(width 0.088646)
		(layer "In6.Cu")
		(net "M_D_CPU1_SA_DQ<4>")
	)
	(segment
		(start 54.914292 -302.509682)
		(end 53.88483 -302.509682)
		(width 0.18288)
		(layer "In6.Cu")
		(net "M_D_CPU1_SA_DQ<4>")
	)
	(segment
		(start 83.227672 -278.93645)
		(end 81.407762 -279.690322)
		(width 0.18288)
		(layer "In6.Cu")
		(net "M_D_CPU1_SA_DQ<4>")
	)
	(segment
		(start 34.669476 -310.952134)
		(end 34.509456 -310.792114)
		(width 0.18288)
		(layer "In6.Cu")
		(net "M_D_CPU1_SA_DQ<4>")
	)
	(segment
		(start 48.27778 -305.669188)
		(end 47.40529 -306.541678)
		(width 0.18288)
		(layer "In6.Cu")
		(net "M_D_CPU1_SA_DQ<4>")
	)
	(segment
		(start 33.094676 -310.652414)
		(end 32.38373 -309.941468)
		(width 0.18288)
		(layer "In6.Cu")
		(net "M_D_CPU1_SA_DQ<4>")
	)
	(segment
		(start 93.236796 -273.942556)
		(end 93.222064 -273.951192)
		(width 0.088646)
		(layer "In6.Cu")
		(net "M_D_CPU1_SA_DQ<4>")
	)
	(segment
		(start 86.657942 -275.570442)
		(end 86.649052 -275.575522)
		(width 0.088646)
		(layer "In6.Cu")
		(net "M_D_CPU1_SA_DQ<4>")
	)
	(segment
		(start 84.937092 -276.80412)
		(end 84.937092 -277.697438)
		(width 0.088646)
		(layer "In6.Cu")
		(net "M_D_CPU1_SA_DQ<4>")
	)
	(segment
		(start 34.669476 -311.1627)
		(end 34.669476 -310.952134)
		(width 0.18288)
		(layer "In6.Cu")
		(net "M_D_CPU1_SA_DQ<4>")
	)
	(segment
		(start 50.234088 -303.991772)
		(end 49.486566 -304.739294)
		(width 0.18288)
		(layer "In6.Cu")
		(net "M_D_CPU1_SA_DQ<4>")
	)
	(segment
		(start 56.520842 -301.597822)
		(end 55.826152 -301.597822)
		(width 0.18288)
		(layer "In6.Cu")
		(net "M_D_CPU1_SA_DQ<4>")
	)
	(segment
		(start 66.5988 -295.283382)
		(end 66.033904 -295.283382)
		(width 0.18288)
		(layer "In6.Cu")
		(net "M_D_CPU1_SA_DQ<4>")
	)
	(segment
		(start 83.496658 -278.93645)
		(end 83.227672 -278.93645)
		(width 0.18288)
		(layer "In6.Cu")
		(net "M_D_CPU1_SA_DQ<4>")
	)
	(segment
		(start 88.067896 -274.756372)
		(end 88.059006 -274.761452)
		(width 0.088646)
		(layer "In6.Cu")
		(net "M_D_CPU1_SA_DQ<4>")
	)
	(segment
		(start 35.362896 -310.952134)
		(end 35.362896 -311.1627)
		(width 0.18288)
		(layer "In6.Cu")
		(net "M_D_CPU1_SA_DQ<4>")
	)
	(segment
		(start 40.032178 -310.792114)
		(end 38.735508 -310.792114)
		(width 0.18288)
		(layer "In6.Cu")
		(net "M_D_CPU1_SA_DQ<4>")
	)
	(segment
		(start 35.522916 -310.792114)
		(end 35.362896 -310.952134)
		(width 0.18288)
		(layer "In6.Cu")
		(net "M_D_CPU1_SA_DQ<4>")
	)
	(segment
		(start 49.486566 -304.739294)
		(end 48.738282 -304.739294)
		(width 0.18288)
		(layer "In6.Cu")
		(net "M_D_CPU1_SA_DQ<4>")
	)
	(segment
		(start 83.69808 -278.93645)
		(end 83.496658 -278.93645)
		(width 0.088646)
		(layer "In6.Cu")
		(net "M_D_CPU1_SA_DQ<4>")
	)
	(segment
		(start 19.283934 -310.124348)
		(end 19.101054 -309.941468)
		(width 0.18288)
		(layer "In6.Cu")
		(net "M_D_CPU1_SA_DQ<4>")
	)
	(segment
		(start 63.095124 -297.226228)
		(end 61.065156 -297.226228)
		(width 0.18288)
		(layer "In6.Cu")
		(net "M_D_CPU1_SA_DQ<4>")
	)
	(segment
		(start 43.41114 -308.127908)
		(end 41.730676 -309.808372)
		(width 0.18288)
		(layer "In6.Cu")
		(net "M_D_CPU1_SA_DQ<4>")
	)
	(segment
		(start 45.379132 -307.271928)
		(end 44.558204 -307.271928)
		(width 0.18288)
		(layer "In6.Cu")
		(net "M_D_CPU1_SA_DQ<4>")
	)
	(segment
		(start 19.974814 -310.124348)
		(end 19.974814 -311.33034)
		(width 0.18288)
		(layer "In6.Cu")
		(net "M_D_CPU1_SA_DQ<4>")
	)
	(segment
		(start 44.558204 -307.271928)
		(end 43.702224 -308.127908)
		(width 0.18288)
		(layer "In6.Cu")
		(net "M_D_CPU1_SA_DQ<4>")
	)
	(segment
		(start 41.730676 -309.808372)
		(end 41.01592 -309.808372)
		(width 0.18288)
		(layer "In6.Cu")
		(net "M_D_CPU1_SA_DQ<4>")
	)
	(segment
		(start 67.438778 -293.659306)
		(end 67.438778 -294.443404)
		(width 0.18288)
		(layer "In6.Cu")
		(net "M_D_CPU1_SA_DQ<4>")
	)
	(segment
		(start 32.38373 -309.941468)
		(end 25.635458 -309.941468)
		(width 0.18288)
		(layer "In6.Cu")
		(net "M_D_CPU1_SA_DQ<4>")
	)
	(segment
		(start 47.40529 -306.541678)
		(end 46.109382 -306.541678)
		(width 0.18288)
		(layer "In6.Cu")
		(net "M_D_CPU1_SA_DQ<4>")
	)
	(segment
		(start 95.303594 -274.266914)
		(end 94.9325 -274.166076)
		(width 0.088646)
		(layer "In6.Cu")
		(net "M_D_CPU1_SA_DQ<4>")
	)
	(segment
		(start 66.033904 -295.283382)
		(end 64.202564 -297.114722)
		(width 0.18288)
		(layer "In6.Cu")
		(net "M_D_CPU1_SA_DQ<4>")
	)
	(segment
		(start 37.831522 -310.792114)
		(end 35.522916 -310.792114)
		(width 0.18288)
		(layer "In6.Cu")
		(net "M_D_CPU1_SA_DQ<4>")
	)
	(segment
		(start 19.283934 -311.33034)
		(end 19.283934 -310.124348)
		(width 0.18288)
		(layer "In6.Cu")
		(net "M_D_CPU1_SA_DQ<4>")
	)
	(segment
		(start 57.084468 -301.034196)
		(end 56.520842 -301.597822)
		(width 0.18288)
		(layer "In6.Cu")
		(net "M_D_CPU1_SA_DQ<4>")
	)
	(segment
		(start 38.735508 -310.792114)
		(end 38.499542 -311.02808)
		(width 0.18288)
		(layer "In6.Cu")
		(net "M_D_CPU1_SA_DQ<4>")
	)
	(segment
		(start 94.9325 -274.166076)
		(end 94.550992 -273.942556)
		(width 0.088646)
		(layer "In6.Cu")
		(net "M_D_CPU1_SA_DQ<4>")
	)
	(arc
		(start 89.851992 -273.942556)
		(mid 89.664794 -273.892413)
		(end 89.477596 -273.942556)
		(width 0.088646)
		(layer "In6.Cu")
		(net "M_D_CPU1_SA_DQ<4>")
	)
	(arc
		(start 89.007696 -274.756372)
		(mid 88.724994 -274.832148)
		(end 88.442292 -274.756372)
		(width 0.088646)
		(layer "In6.Cu")
		(net "M_D_CPU1_SA_DQ<4>")
	)
	(arc
		(start 94.161864 -273.951192)
		(mid 93.885389 -274.018512)
		(end 93.611192 -273.942556)
		(width 0.088646)
		(layer "In6.Cu")
		(net "M_D_CPU1_SA_DQ<4>")
	)
	(arc
		(start 92.286582 -273.948652)
		(mid 92.008404 -274.018375)
		(end 91.731846 -273.942556)
		(width 0.088646)
		(layer "In6.Cu")
		(net "M_D_CPU1_SA_DQ<4>")
	)
	(arc
		(start 87.597742 -275.570442)
		(mid 87.31504 -275.646184)
		(end 87.032338 -275.570442)
		(width 0.088646)
		(layer "In6.Cu")
		(net "M_D_CPU1_SA_DQ<4>")
	)
	(arc
		(start 87.880444 -275.08835)
		(mid 87.802815 -275.366763)
		(end 87.597742 -275.570442)
		(width 0.088646)
		(layer "In6.Cu")
		(net "M_D_CPU1_SA_DQ<4>")
	)
	(arc
		(start 92.671392 -273.942556)
		(mid 92.484194 -273.892413)
		(end 92.296996 -273.942556)
		(width 0.088646)
		(layer "In6.Cu")
		(net "M_D_CPU1_SA_DQ<4>")
	)
	(arc
		(start 87.032338 -275.570442)
		(mid 86.84514 -275.520299)
		(end 86.657942 -275.570442)
		(width 0.088646)
		(layer "In6.Cu")
		(net "M_D_CPU1_SA_DQ<4>")
	)
	(arc
		(start 89.468706 -273.947636)
		(mid 89.337792 -274.083996)
		(end 89.290144 -274.266914)
		(width 0.088646)
		(layer "In6.Cu")
		(net "M_D_CPU1_SA_DQ<4>")
	)
	(arc
		(start 91.347036 -273.948652)
		(mid 91.068604 -274.018498)
		(end 90.791792 -273.942556)
		(width 0.088646)
		(layer "In6.Cu")
		(net "M_D_CPU1_SA_DQ<4>")
	)
	(arc
		(start 94.550992 -273.942556)
		(mid 94.363794 -273.892413)
		(end 94.176596 -273.942556)
		(width 0.088646)
		(layer "In6.Cu")
		(net "M_D_CPU1_SA_DQ<4>")
	)
	(arc
		(start 86.649052 -275.575522)
		(mid 86.518138 -275.711882)
		(end 86.47049 -275.8948)
		(width 0.088646)
		(layer "In6.Cu")
		(net "M_D_CPU1_SA_DQ<4>")
	)
	(arc
		(start 93.611192 -273.942556)
		(mid 93.423994 -273.892413)
		(end 93.236796 -273.942556)
		(width 0.088646)
		(layer "In6.Cu")
		(net "M_D_CPU1_SA_DQ<4>")
	)
	(arc
		(start 88.059006 -274.761452)
		(mid 87.928092 -274.897812)
		(end 87.880444 -275.08073)
		(width 0.088646)
		(layer "In6.Cu")
		(net "M_D_CPU1_SA_DQ<4>")
	)
	(arc
		(start 86.47049 -275.910294)
		(mid 86.39112 -276.184028)
		(end 86.188296 -276.384258)
		(width 0.088646)
		(layer "In6.Cu")
		(net "M_D_CPU1_SA_DQ<4>")
	)
	(arc
		(start 88.442292 -274.756372)
		(mid 88.255094 -274.706229)
		(end 88.067896 -274.756372)
		(width 0.088646)
		(layer "In6.Cu")
		(net "M_D_CPU1_SA_DQ<4>")
	)
	(arc
		(start 91.731846 -273.942556)
		(mid 91.544648 -273.892413)
		(end 91.35745 -273.942556)
		(width 0.088646)
		(layer "In6.Cu")
		(net "M_D_CPU1_SA_DQ<4>")
	)
	(arc
		(start 86.188296 -276.384258)
		(mid 85.914097 -276.460093)
		(end 85.637624 -276.392894)
		(width 0.088646)
		(layer "In6.Cu")
		(net "M_D_CPU1_SA_DQ<4>")
	)
	(arc
		(start 90.417396 -273.942556)
		(mid 90.134694 -274.018332)
		(end 89.851992 -273.942556)
		(width 0.088646)
		(layer "In6.Cu")
		(net "M_D_CPU1_SA_DQ<4>")
	)
	(arc
		(start 89.290144 -274.27682)
		(mid 89.212033 -274.553769)
		(end 89.007696 -274.756372)
		(width 0.088646)
		(layer "In6.Cu")
		(net "M_D_CPU1_SA_DQ<4>")
	)
	(arc
		(start 90.791792 -273.942556)
		(mid 90.604594 -273.892413)
		(end 90.417396 -273.942556)
		(width 0.088646)
		(layer "In6.Cu")
		(net "M_D_CPU1_SA_DQ<4>")
	)
	(arc
		(start 85.622892 -276.384258)
		(mid 85.462905 -276.352508)
		(end 85.316568 -276.424644)
		(width 0.088646)
		(layer "In6.Cu")
		(net "M_D_CPU1_SA_DQ<4>")
	)
	(arc
		(start 93.222064 -273.951192)
		(mid 92.945589 -274.018512)
		(end 92.671392 -273.942556)
		(width 0.088646)
		(layer "In6.Cu")
		(net "M_D_CPU1_SA_DQ<4>")
	)
	(segment
		(start 18.968212 -313.766708)
		(end 19.784314 -313.766708)
		(width 0.20066)
		(layer "F.Cu")
		(net "M_D_CPU1_SA_DQ<3>")
	)
	(segment
		(start 18.314162 -313.974226)
		(end 18.760694 -313.974226)
		(width 0.20066)
		(layer "F.Cu")
		(net "M_D_CPU1_SA_DQ<3>")
	)
	(segment
		(start 14.812264 -314.19165)
		(end 16.885158 -314.19165)
		(width 0.1016)
		(layer "F.Cu")
		(net "M_D_CPU1_SA_DQ<3>")
	)
	(segment
		(start 14.20622 -314.205874)
		(end 14.560042 -314.205874)
		(width 0.20066)
		(layer "F.Cu")
		(net "M_D_CPU1_SA_DQ<3>")
	)
	(segment
		(start 17.578578 -314.042552)
		(end 17.578578 -313.890914)
		(width 0.20066)
		(layer "F.Cu")
		(net "M_D_CPU1_SA_DQ<3>")
	)
	(segment
		(start 17.42948 -314.19165)
		(end 17.578578 -314.042552)
		(width 0.20066)
		(layer "F.Cu")
		(net "M_D_CPU1_SA_DQ<3>")
	)
	(segment
		(start 14.063726 -314.06338)
		(end 14.20622 -314.205874)
		(width 0.20066)
		(layer "F.Cu")
		(net "M_D_CPU1_SA_DQ<3>")
	)
	(segment
		(start 17.707102 -313.76239)
		(end 18.102326 -313.76239)
		(width 0.20066)
		(layer "F.Cu")
		(net "M_D_CPU1_SA_DQ<3>")
	)
	(segment
		(start 12.240514 -313.766708)
		(end 13.937742 -313.766708)
		(width 0.20066)
		(layer "F.Cu")
		(net "M_D_CPU1_SA_DQ<3>")
	)
	(segment
		(start 14.574266 -314.19165)
		(end 14.812264 -314.19165)
		(width 0.101854)
		(layer "F.Cu")
		(net "M_D_CPU1_SA_DQ<3>")
	)
	(segment
		(start 18.102326 -313.76239)
		(end 18.314162 -313.974226)
		(width 0.20066)
		(layer "F.Cu")
		(net "M_D_CPU1_SA_DQ<3>")
	)
	(segment
		(start 13.937742 -313.766708)
		(end 14.063726 -313.892692)
		(width 0.20066)
		(layer "F.Cu")
		(net "M_D_CPU1_SA_DQ<3>")
	)
	(segment
		(start 17.578578 -313.890914)
		(end 17.707102 -313.76239)
		(width 0.20066)
		(layer "F.Cu")
		(net "M_D_CPU1_SA_DQ<3>")
	)
	(segment
		(start 16.885158 -314.19165)
		(end 17.42948 -314.19165)
		(width 0.20066)
		(layer "F.Cu")
		(net "M_D_CPU1_SA_DQ<3>")
	)
	(segment
		(start 14.560042 -314.205874)
		(end 14.574266 -314.19165)
		(width 0.101854)
		(layer "F.Cu")
		(net "M_D_CPU1_SA_DQ<3>")
	)
	(segment
		(start 18.760694 -313.974226)
		(end 18.968212 -313.766708)
		(width 0.20066)
		(layer "F.Cu")
		(net "M_D_CPU1_SA_DQ<3>")
	)
	(segment
		(start 20.889214 -313.766708)
		(end 19.784314 -313.766708)
		(width 0.20066)
		(layer "F.Cu")
		(net "M_D_CPU1_SA_DQ<3>")
	)
	(segment
		(start 14.063726 -313.892692)
		(end 14.063726 -314.06338)
		(width 0.20066)
		(layer "F.Cu")
		(net "M_D_CPU1_SA_DQ<3>")
	)
	(arc
		(start 97.183448 -275.35886)
		(mid 97.183384 -275.62683)
		(end 97.183194 -275.8948)
		(width 0.20066)
		(layer "F.Cu")
		(net "M_D_CPU1_SA_DQ<3>")
	)
	(segment
		(start 83.901788 -281.478736)
		(end 68.693284 -296.68724)
		(width 0.18288)
		(layer "In6.Cu")
		(net "M_D_CPU1_SA_DQ<3>")
	)
	(segment
		(start 90.330782 -277.027894)
		(end 90.321892 -277.032974)
		(width 0.088646)
		(layer "In6.Cu")
		(net "M_D_CPU1_SA_DQ<3>")
	)
	(segment
		(start 23.068026 -313.649614)
		(end 22.885146 -313.832494)
		(width 0.18288)
		(layer "In6.Cu")
		(net "M_D_CPU1_SA_DQ<3>")
	)
	(segment
		(start 49.61001 -309.562754)
		(end 49.38395 -309.562754)
		(width 0.18288)
		(layer "In6.Cu")
		(net "M_D_CPU1_SA_DQ<3>")
	)
	(segment
		(start 85.231732 -281.294332)
		(end 85.047328 -281.478736)
		(width 0.088646)
		(layer "In6.Cu")
		(net "M_D_CPU1_SA_DQ<3>")
	)
	(segment
		(start 68.693284 -296.68724)
		(end 68.693284 -298.64304)
		(width 0.18288)
		(layer "In6.Cu")
		(net "M_D_CPU1_SA_DQ<3>")
	)
	(segment
		(start 63.680848 -301.93488)
		(end 63.18758 -301.441612)
		(width 0.18288)
		(layer "In6.Cu")
		(net "M_D_CPU1_SA_DQ<3>")
	)
	(segment
		(start 27.579574 -313.085734)
		(end 27.396694 -312.902854)
		(width 0.18288)
		(layer "In6.Cu")
		(net "M_D_CPU1_SA_DQ<3>")
	)
	(segment
		(start 28.772358 -313.59729)
		(end 27.762454 -313.59729)
		(width 0.18288)
		(layer "In6.Cu")
		(net "M_D_CPU1_SA_DQ<3>")
	)
	(segment
		(start 23.576026 -313.832494)
		(end 23.393146 -313.649614)
		(width 0.18288)
		(layer "In6.Cu")
		(net "M_D_CPU1_SA_DQ<3>")
	)
	(segment
		(start 34.122868 -315.041534)
		(end 31.54172 -315.041534)
		(width 0.18288)
		(layer "In6.Cu")
		(net "M_D_CPU1_SA_DQ<3>")
	)
	(segment
		(start 49.38395 -309.562754)
		(end 49.151286 -309.33009)
		(width 0.18288)
		(layer "In6.Cu")
		(net "M_D_CPU1_SA_DQ<3>")
	)
	(segment
		(start 58.132726 -304.169826)
		(end 56.382412 -305.92014)
		(width 0.18288)
		(layer "In6.Cu")
		(net "M_D_CPU1_SA_DQ<3>")
	)
	(segment
		(start 96.84893 -275.806916)
		(end 96.425004 -275.56714)
		(width 0.088646)
		(layer "In6.Cu")
		(net "M_D_CPU1_SA_DQ<3>")
	)
	(segment
		(start 34.972752 -315.891418)
		(end 34.122868 -315.041534)
		(width 0.18288)
		(layer "In6.Cu")
		(net "M_D_CPU1_SA_DQ<3>")
	)
	(segment
		(start 26.888694 -313.41441)
		(end 26.705814 -313.59729)
		(width 0.18288)
		(layer "In6.Cu")
		(net "M_D_CPU1_SA_DQ<3>")
	)
	(segment
		(start 94.17685 -276.219158)
		(end 94.166436 -276.213062)
		(width 0.088646)
		(layer "In6.Cu")
		(net "M_D_CPU1_SA_DQ<3>")
	)
	(segment
		(start 54.072282 -306.737004)
		(end 52.567586 -308.2417)
		(width 0.18288)
		(layer "In6.Cu")
		(net "M_D_CPU1_SA_DQ<3>")
	)
	(segment
		(start 26.888694 -313.085734)
		(end 26.888694 -313.41441)
		(width 0.18288)
		(layer "In6.Cu")
		(net "M_D_CPU1_SA_DQ<3>")
	)
	(segment
		(start 52.567586 -308.2417)
		(end 50.013616 -308.2417)
		(width 0.18288)
		(layer "In6.Cu")
		(net "M_D_CPU1_SA_DQ<3>")
	)
	(segment
		(start 90.509344 -276.69871)
		(end 90.509344 -276.708616)
		(width 0.088646)
		(layer "In6.Cu")
		(net "M_D_CPU1_SA_DQ<3>")
	)
	(segment
		(start 26.705814 -313.59729)
		(end 25.407112 -313.59729)
		(width 0.18288)
		(layer "In6.Cu")
		(net "M_D_CPU1_SA_DQ<3>")
	)
	(segment
		(start 90.321892 -277.032974)
		(end 90.315796 -277.03653)
		(width 0.088646)
		(layer "In6.Cu")
		(net "M_D_CPU1_SA_DQ<3>")
	)
	(segment
		(start 27.579574 -313.41441)
		(end 27.579574 -313.085734)
		(width 0.18288)
		(layer "In6.Cu")
		(net "M_D_CPU1_SA_DQ<3>")
	)
	(segment
		(start 89.860882 -277.84171)
		(end 89.851992 -277.84679)
		(width 0.088646)
		(layer "In6.Cu")
		(net "M_D_CPU1_SA_DQ<3>")
	)
	(segment
		(start 50.013616 -308.2417)
		(end 49.64176 -308.613556)
		(width 0.18288)
		(layer "In6.Cu")
		(net "M_D_CPU1_SA_DQ<3>")
	)
	(segment
		(start 27.071574 -312.902854)
		(end 26.888694 -313.085734)
		(width 0.18288)
		(layer "In6.Cu")
		(net "M_D_CPU1_SA_DQ<3>")
	)
	(segment
		(start 85.231732 -280.652474)
		(end 85.231732 -281.294332)
		(width 0.088646)
		(layer "In6.Cu")
		(net "M_D_CPU1_SA_DQ<3>")
	)
	(segment
		(start 59.287156 -303.581308)
		(end 58.698638 -304.169826)
		(width 0.18288)
		(layer "In6.Cu")
		(net "M_D_CPU1_SA_DQ<3>")
	)
	(segment
		(start 48.925226 -309.33009)
		(end 47.463456 -310.79186)
		(width 0.18288)
		(layer "In6.Cu")
		(net "M_D_CPU1_SA_DQ<3>")
	)
	(segment
		(start 40.552116 -313.448446)
		(end 39.621714 -314.378848)
		(width 0.18288)
		(layer "In6.Cu")
		(net "M_D_CPU1_SA_DQ<3>")
	)
	(segment
		(start 85.047328 -281.478736)
		(end 84.562442 -281.478736)
		(width 0.088646)
		(layer "In6.Cu")
		(net "M_D_CPU1_SA_DQ<3>")
	)
	(segment
		(start 58.698638 -304.169826)
		(end 58.132726 -304.169826)
		(width 0.18288)
		(layer "In6.Cu")
		(net "M_D_CPU1_SA_DQ<3>")
	)
	(segment
		(start 46.048676 -310.79186)
		(end 44.905168 -311.935368)
		(width 0.18288)
		(layer "In6.Cu")
		(net "M_D_CPU1_SA_DQ<3>")
	)
	(segment
		(start 27.396694 -312.902854)
		(end 27.071574 -312.902854)
		(width 0.18288)
		(layer "In6.Cu")
		(net "M_D_CPU1_SA_DQ<3>")
	)
	(segment
		(start 23.758906 -314.355226)
		(end 23.576026 -314.172346)
		(width 0.18288)
		(layer "In6.Cu")
		(net "M_D_CPU1_SA_DQ<3>")
	)
	(segment
		(start 31.54172 -315.041534)
		(end 30.909006 -314.40882)
		(width 0.18288)
		(layer "In6.Cu")
		(net "M_D_CPU1_SA_DQ<3>")
	)
	(segment
		(start 61.042296 -301.441612)
		(end 59.287156 -303.196752)
		(width 0.18288)
		(layer "In6.Cu")
		(net "M_D_CPU1_SA_DQ<3>")
	)
	(segment
		(start 89.569544 -278.31796)
		(end 89.569544 -278.336502)
		(width 0.088646)
		(layer "In6.Cu")
		(net "M_D_CPU1_SA_DQ<3>")
	)
	(segment
		(start 84.562442 -281.478736)
		(end 83.901788 -281.478736)
		(width 0.18288)
		(layer "In6.Cu")
		(net "M_D_CPU1_SA_DQ<3>")
	)
	(segment
		(start 86.101682 -279.469596)
		(end 86.092792 -279.474676)
		(width 0.088646)
		(layer "In6.Cu")
		(net "M_D_CPU1_SA_DQ<3>")
	)
	(segment
		(start 42.540936 -312.580528)
		(end 41.673018 -313.448446)
		(width 0.18288)
		(layer "In6.Cu")
		(net "M_D_CPU1_SA_DQ<3>")
	)
	(segment
		(start 94.551754 -276.218904)
		(end 94.551246 -276.219158)
		(width 0.088646)
		(layer "In6.Cu")
		(net "M_D_CPU1_SA_DQ<3>")
	)
	(segment
		(start 94.856554 -275.82241)
		(end 94.828106 -275.891244)
		(width 0.088646)
		(layer "In6.Cu")
		(net "M_D_CPU1_SA_DQ<3>")
	)
	(segment
		(start 54.729634 -306.737004)
		(end 54.072282 -306.737004)
		(width 0.18288)
		(layer "In6.Cu")
		(net "M_D_CPU1_SA_DQ<3>")
	)
	(segment
		(start 85.810344 -279.954228)
		(end 85.810344 -279.964134)
		(width 0.088646)
		(layer "In6.Cu")
		(net "M_D_CPU1_SA_DQ<3>")
	)
	(segment
		(start 95.496888 -275.573744)
		(end 95.485204 -275.56714)
		(width 0.088646)
		(layer "In6.Cu")
		(net "M_D_CPU1_SA_DQ<3>")
	)
	(segment
		(start 63.18758 -301.441612)
		(end 61.042296 -301.441612)
		(width 0.18288)
		(layer "In6.Cu")
		(net "M_D_CPU1_SA_DQ<3>")
	)
	(segment
		(start 23.576026 -314.172346)
		(end 23.576026 -313.832494)
		(width 0.18288)
		(layer "In6.Cu")
		(net "M_D_CPU1_SA_DQ<3>")
	)
	(segment
		(start 44.905168 -311.935368)
		(end 44.098718 -311.935368)
		(width 0.18288)
		(layer "In6.Cu")
		(net "M_D_CPU1_SA_DQ<3>")
	)
	(segment
		(start 47.463456 -310.79186)
		(end 46.048676 -310.79186)
		(width 0.18288)
		(layer "In6.Cu")
		(net "M_D_CPU1_SA_DQ<3>")
	)
	(segment
		(start 27.762454 -313.59729)
		(end 27.579574 -313.41441)
		(width 0.18288)
		(layer "In6.Cu")
		(net "M_D_CPU1_SA_DQ<3>")
	)
	(segment
		(start 44.098718 -311.935368)
		(end 42.540936 -312.580528)
		(width 0.18288)
		(layer "In6.Cu")
		(net "M_D_CPU1_SA_DQ<3>")
	)
	(segment
		(start 41.673018 -313.448446)
		(end 40.552116 -313.448446)
		(width 0.18288)
		(layer "In6.Cu")
		(net "M_D_CPU1_SA_DQ<3>")
	)
	(segment
		(start 49.874424 -309.07228)
		(end 49.874424 -309.29834)
		(width 0.18288)
		(layer "In6.Cu")
		(net "M_D_CPU1_SA_DQ<3>")
	)
	(segment
		(start 23.393146 -313.649614)
		(end 23.068026 -313.649614)
		(width 0.18288)
		(layer "In6.Cu")
		(net "M_D_CPU1_SA_DQ<3>")
	)
	(segment
		(start 59.287156 -303.196752)
		(end 59.287156 -303.581308)
		(width 0.18288)
		(layer "In6.Cu")
		(net "M_D_CPU1_SA_DQ<3>")
	)
	(segment
		(start 37.513514 -315.891418)
		(end 34.972752 -315.891418)
		(width 0.18288)
		(layer "In6.Cu")
		(net "M_D_CPU1_SA_DQ<3>")
	)
	(segment
		(start 68.693284 -298.64304)
		(end 66.74358 -300.592744)
		(width 0.18288)
		(layer "In6.Cu")
		(net "M_D_CPU1_SA_DQ<3>")
	)
	(segment
		(start 92.296996 -276.219158)
		(end 92.282264 -276.210522)
		(width 0.088646)
		(layer "In6.Cu")
		(net "M_D_CPU1_SA_DQ<3>")
	)
	(segment
		(start 89.390982 -278.65578)
		(end 89.382092 -278.66086)
		(width 0.088646)
		(layer "In6.Cu")
		(net "M_D_CPU1_SA_DQ<3>")
	)
	(segment
		(start 49.151286 -309.33009)
		(end 48.925226 -309.33009)
		(width 0.18288)
		(layer "In6.Cu")
		(net "M_D_CPU1_SA_DQ<3>")
	)
	(segment
		(start 86.280244 -279.140412)
		(end 86.280244 -279.150318)
		(width 0.088646)
		(layer "In6.Cu")
		(net "M_D_CPU1_SA_DQ<3>")
	)
	(segment
		(start 30.909006 -314.40882)
		(end 29.583888 -314.40882)
		(width 0.18288)
		(layer "In6.Cu")
		(net "M_D_CPU1_SA_DQ<3>")
	)
	(segment
		(start 22.885146 -314.172346)
		(end 22.702266 -314.355226)
		(width 0.18288)
		(layer "In6.Cu")
		(net "M_D_CPU1_SA_DQ<3>")
	)
	(segment
		(start 24.649176 -314.355226)
		(end 23.758906 -314.355226)
		(width 0.18288)
		(layer "In6.Cu")
		(net "M_D_CPU1_SA_DQ<3>")
	)
	(segment
		(start 85.505798 -280.378408)
		(end 85.231732 -280.652474)
		(width 0.088646)
		(layer "In6.Cu")
		(net "M_D_CPU1_SA_DQ<3>")
	)
	(segment
		(start 64.304926 -301.93488)
		(end 63.680848 -301.93488)
		(width 0.18288)
		(layer "In6.Cu")
		(net "M_D_CPU1_SA_DQ<3>")
	)
	(segment
		(start 93.236796 -276.219158)
		(end 93.222064 -276.210522)
		(width 0.088646)
		(layer "In6.Cu")
		(net "M_D_CPU1_SA_DQ<3>")
	)
	(segment
		(start 85.631782 -280.283412)
		(end 85.622892 -280.288492)
		(width 0.088646)
		(layer "In6.Cu")
		(net "M_D_CPU1_SA_DQ<3>")
	)
	(segment
		(start 65.647062 -300.592744)
		(end 64.304926 -301.93488)
		(width 0.18288)
		(layer "In6.Cu")
		(net "M_D_CPU1_SA_DQ<3>")
	)
	(segment
		(start 22.702266 -314.355226)
		(end 21.477732 -314.355226)
		(width 0.18288)
		(layer "In6.Cu")
		(net "M_D_CPU1_SA_DQ<3>")
	)
	(segment
		(start 94.762574 -276.049486)
		(end 94.730824 -276.08149)
		(width 0.088646)
		(layer "In6.Cu")
		(net "M_D_CPU1_SA_DQ<3>")
	)
	(segment
		(start 39.621714 -314.378848)
		(end 39.026084 -314.378848)
		(width 0.18288)
		(layer "In6.Cu")
		(net "M_D_CPU1_SA_DQ<3>")
	)
	(segment
		(start 21.477732 -314.355226)
		(end 20.889214 -313.766708)
		(width 0.18288)
		(layer "In6.Cu")
		(net "M_D_CPU1_SA_DQ<3>")
	)
	(segment
		(start 49.874424 -309.29834)
		(end 49.61001 -309.562754)
		(width 0.18288)
		(layer "In6.Cu")
		(net "M_D_CPU1_SA_DQ<3>")
	)
	(segment
		(start 39.026084 -314.378848)
		(end 37.513514 -315.891418)
		(width 0.18288)
		(layer "In6.Cu")
		(net "M_D_CPU1_SA_DQ<3>")
	)
	(segment
		(start 56.382412 -305.92014)
		(end 55.546498 -305.92014)
		(width 0.18288)
		(layer "In6.Cu")
		(net "M_D_CPU1_SA_DQ<3>")
	)
	(segment
		(start 25.407112 -313.59729)
		(end 24.649176 -314.355226)
		(width 0.18288)
		(layer "In6.Cu")
		(net "M_D_CPU1_SA_DQ<3>")
	)
	(segment
		(start 49.64176 -308.839616)
		(end 49.874424 -309.07228)
		(width 0.18288)
		(layer "In6.Cu")
		(net "M_D_CPU1_SA_DQ<3>")
	)
	(segment
		(start 55.546498 -305.92014)
		(end 54.729634 -306.737004)
		(width 0.18288)
		(layer "In6.Cu")
		(net "M_D_CPU1_SA_DQ<3>")
	)
	(segment
		(start 29.583888 -314.40882)
		(end 28.772358 -313.59729)
		(width 0.18288)
		(layer "In6.Cu")
		(net "M_D_CPU1_SA_DQ<3>")
	)
	(segment
		(start 49.64176 -308.613556)
		(end 49.64176 -308.839616)
		(width 0.18288)
		(layer "In6.Cu")
		(net "M_D_CPU1_SA_DQ<3>")
	)
	(segment
		(start 22.885146 -313.832494)
		(end 22.885146 -314.172346)
		(width 0.18288)
		(layer "In6.Cu")
		(net "M_D_CPU1_SA_DQ<3>")
	)
	(segment
		(start 66.74358 -300.592744)
		(end 65.647062 -300.592744)
		(width 0.18288)
		(layer "In6.Cu")
		(net "M_D_CPU1_SA_DQ<3>")
	)
	(arc
		(start 86.280244 -279.150318)
		(mid 86.232565 -279.333218)
		(end 86.101682 -279.469596)
		(width 0.088646)
		(layer "In6.Cu")
		(net "M_D_CPU1_SA_DQ<3>")
	)
	(arc
		(start 89.569544 -278.336502)
		(mid 89.521865 -278.519402)
		(end 89.390982 -278.65578)
		(width 0.088646)
		(layer "In6.Cu")
		(net "M_D_CPU1_SA_DQ<3>")
	)
	(arc
		(start 89.382092 -278.66086)
		(mid 89.194894 -278.711003)
		(end 89.007696 -278.66086)
		(width 0.088646)
		(layer "In6.Cu")
		(net "M_D_CPU1_SA_DQ<3>")
	)
	(arc
		(start 88.442292 -278.66086)
		(mid 88.255094 -278.711003)
		(end 88.067896 -278.66086)
		(width 0.088646)
		(layer "In6.Cu")
		(net "M_D_CPU1_SA_DQ<3>")
	)
	(arc
		(start 90.791792 -276.219158)
		(mid 90.587457 -276.421763)
		(end 90.509344 -276.69871)
		(width 0.088646)
		(layer "In6.Cu")
		(net "M_D_CPU1_SA_DQ<3>")
	)
	(arc
		(start 94.551246 -276.219158)
		(mid 94.364048 -276.269301)
		(end 94.17685 -276.219158)
		(width 0.088646)
		(layer "In6.Cu")
		(net "M_D_CPU1_SA_DQ<3>")
	)
	(arc
		(start 94.928944 -275.714206)
		(mid 94.887419 -275.764743)
		(end 94.856554 -275.82241)
		(width 0.088646)
		(layer "In6.Cu")
		(net "M_D_CPU1_SA_DQ<3>")
	)
	(arc
		(start 97.183194 -275.8948)
		(mid 97.010381 -275.87248)
		(end 96.84893 -275.806916)
		(width 0.088646)
		(layer "In6.Cu")
		(net "M_D_CPU1_SA_DQ<3>")
	)
	(arc
		(start 87.128096 -278.66086)
		(mid 86.845394 -278.585084)
		(end 86.562692 -278.66086)
		(width 0.088646)
		(layer "In6.Cu")
		(net "M_D_CPU1_SA_DQ<3>")
	)
	(arc
		(start 89.851992 -277.84679)
		(mid 89.649706 -278.045771)
		(end 89.569544 -278.31796)
		(width 0.088646)
		(layer "In6.Cu")
		(net "M_D_CPU1_SA_DQ<3>")
	)
	(arc
		(start 87.502492 -278.66086)
		(mid 87.315294 -278.711003)
		(end 87.128096 -278.66086)
		(width 0.088646)
		(layer "In6.Cu")
		(net "M_D_CPU1_SA_DQ<3>")
	)
	(arc
		(start 85.622892 -280.288492)
		(mid 85.561397 -280.329611)
		(end 85.505798 -280.378408)
		(width 0.088646)
		(layer "In6.Cu")
		(net "M_D_CPU1_SA_DQ<3>")
	)
	(arc
		(start 88.067896 -278.66086)
		(mid 87.785194 -278.585084)
		(end 87.502492 -278.66086)
		(width 0.088646)
		(layer "In6.Cu")
		(net "M_D_CPU1_SA_DQ<3>")
	)
	(arc
		(start 85.810344 -279.964134)
		(mid 85.762665 -280.147034)
		(end 85.631782 -280.283412)
		(width 0.088646)
		(layer "In6.Cu")
		(net "M_D_CPU1_SA_DQ<3>")
	)
	(arc
		(start 86.092792 -279.474676)
		(mid 85.888457 -279.677281)
		(end 85.810344 -279.954228)
		(width 0.088646)
		(layer "In6.Cu")
		(net "M_D_CPU1_SA_DQ<3>")
	)
	(arc
		(start 90.315796 -277.03653)
		(mid 90.113383 -277.242943)
		(end 90.039444 -277.522432)
		(width 0.088646)
		(layer "In6.Cu")
		(net "M_D_CPU1_SA_DQ<3>")
	)
	(arc
		(start 93.611192 -276.219158)
		(mid 93.423994 -276.269301)
		(end 93.236796 -276.219158)
		(width 0.088646)
		(layer "In6.Cu")
		(net "M_D_CPU1_SA_DQ<3>")
	)
	(arc
		(start 89.007696 -278.66086)
		(mid 88.724994 -278.585084)
		(end 88.442292 -278.66086)
		(width 0.088646)
		(layer "In6.Cu")
		(net "M_D_CPU1_SA_DQ<3>")
	)
	(arc
		(start 94.166436 -276.213062)
		(mid 93.888004 -276.143216)
		(end 93.611192 -276.219158)
		(width 0.088646)
		(layer "In6.Cu")
		(net "M_D_CPU1_SA_DQ<3>")
	)
	(arc
		(start 95.116396 -275.570442)
		(mid 95.01797 -275.636194)
		(end 94.928944 -275.714206)
		(width 0.088646)
		(layer "In6.Cu")
		(net "M_D_CPU1_SA_DQ<3>")
	)
	(arc
		(start 96.425004 -275.56714)
		(mid 96.240149 -275.52019)
		(end 96.056196 -275.570442)
		(width 0.088646)
		(layer "In6.Cu")
		(net "M_D_CPU1_SA_DQ<3>")
	)
	(arc
		(start 90.509344 -276.708616)
		(mid 90.461665 -276.891516)
		(end 90.330782 -277.027894)
		(width 0.088646)
		(layer "In6.Cu")
		(net "M_D_CPU1_SA_DQ<3>")
	)
	(arc
		(start 93.222064 -276.210522)
		(mid 92.945589 -276.143202)
		(end 92.671392 -276.219158)
		(width 0.088646)
		(layer "In6.Cu")
		(net "M_D_CPU1_SA_DQ<3>")
	)
	(arc
		(start 91.357196 -276.219158)
		(mid 91.074494 -276.143382)
		(end 90.791792 -276.219158)
		(width 0.088646)
		(layer "In6.Cu")
		(net "M_D_CPU1_SA_DQ<3>")
	)
	(arc
		(start 95.485204 -275.56714)
		(mid 95.300349 -275.52019)
		(end 95.116396 -275.570442)
		(width 0.088646)
		(layer "In6.Cu")
		(net "M_D_CPU1_SA_DQ<3>")
	)
	(arc
		(start 86.562692 -278.66086)
		(mid 86.358357 -278.863465)
		(end 86.280244 -279.140412)
		(width 0.088646)
		(layer "In6.Cu")
		(net "M_D_CPU1_SA_DQ<3>")
	)
	(arc
		(start 94.730824 -276.08149)
		(mid 94.645787 -276.156057)
		(end 94.551754 -276.218904)
		(width 0.088646)
		(layer "In6.Cu")
		(net "M_D_CPU1_SA_DQ<3>")
	)
	(arc
		(start 91.731592 -276.219158)
		(mid 91.544394 -276.269301)
		(end 91.357196 -276.219158)
		(width 0.088646)
		(layer "In6.Cu")
		(net "M_D_CPU1_SA_DQ<3>")
	)
	(arc
		(start 92.671392 -276.219158)
		(mid 92.484194 -276.269301)
		(end 92.296996 -276.219158)
		(width 0.088646)
		(layer "In6.Cu")
		(net "M_D_CPU1_SA_DQ<3>")
	)
	(arc
		(start 92.282264 -276.210522)
		(mid 92.005789 -276.143202)
		(end 91.731592 -276.219158)
		(width 0.088646)
		(layer "In6.Cu")
		(net "M_D_CPU1_SA_DQ<3>")
	)
	(arc
		(start 94.828106 -275.891244)
		(mid 94.811072 -275.976879)
		(end 94.762574 -276.049486)
		(width 0.088646)
		(layer "In6.Cu")
		(net "M_D_CPU1_SA_DQ<3>")
	)
	(arc
		(start 96.056196 -275.570442)
		(mid 95.776993 -275.646082)
		(end 95.496888 -275.573744)
		(width 0.088646)
		(layer "In6.Cu")
		(net "M_D_CPU1_SA_DQ<3>")
	)
	(arc
		(start 90.039444 -277.522432)
		(mid 89.991765 -277.705332)
		(end 89.860882 -277.84171)
		(width 0.088646)
		(layer "In6.Cu")
		(net "M_D_CPU1_SA_DQ<3>")
	)
	(segment
		(start 18.760694 -279.974294)
		(end 18.968212 -279.766776)
		(width 0.20066)
		(layer "F.Cu")
		(net "M_D_CPU1_SA_DQ<31>")
	)
	(segment
		(start 18.314162 -279.974294)
		(end 18.760694 -279.974294)
		(width 0.20066)
		(layer "F.Cu")
		(net "M_D_CPU1_SA_DQ<31>")
	)
	(segment
		(start 14.560042 -280.205942)
		(end 14.574266 -280.191718)
		(width 0.101854)
		(layer "F.Cu")
		(net "M_D_CPU1_SA_DQ<31>")
	)
	(segment
		(start 14.574266 -280.191718)
		(end 14.812264 -280.191718)
		(width 0.101854)
		(layer "F.Cu")
		(net "M_D_CPU1_SA_DQ<31>")
	)
	(segment
		(start 18.102326 -279.762458)
		(end 18.314162 -279.974294)
		(width 0.20066)
		(layer "F.Cu")
		(net "M_D_CPU1_SA_DQ<31>")
	)
	(segment
		(start 14.063726 -280.063448)
		(end 14.20622 -280.205942)
		(width 0.20066)
		(layer "F.Cu")
		(net "M_D_CPU1_SA_DQ<31>")
	)
	(segment
		(start 18.968212 -279.766776)
		(end 19.784314 -279.766776)
		(width 0.20066)
		(layer "F.Cu")
		(net "M_D_CPU1_SA_DQ<31>")
	)
	(segment
		(start 14.20622 -280.205942)
		(end 14.560042 -280.205942)
		(width 0.20066)
		(layer "F.Cu")
		(net "M_D_CPU1_SA_DQ<31>")
	)
	(segment
		(start 14.063726 -279.89276)
		(end 14.063726 -280.063448)
		(width 0.20066)
		(layer "F.Cu")
		(net "M_D_CPU1_SA_DQ<31>")
	)
	(segment
		(start 14.812264 -280.191718)
		(end 16.885158 -280.191718)
		(width 0.1016)
		(layer "F.Cu")
		(net "M_D_CPU1_SA_DQ<31>")
	)
	(segment
		(start 17.578578 -279.890982)
		(end 17.707102 -279.762458)
		(width 0.20066)
		(layer "F.Cu")
		(net "M_D_CPU1_SA_DQ<31>")
	)
	(segment
		(start 17.707102 -279.762458)
		(end 18.102326 -279.762458)
		(width 0.20066)
		(layer "F.Cu")
		(net "M_D_CPU1_SA_DQ<31>")
	)
	(segment
		(start 17.578578 -280.04262)
		(end 17.578578 -279.890982)
		(width 0.20066)
		(layer "F.Cu")
		(net "M_D_CPU1_SA_DQ<31>")
	)
	(segment
		(start 20.889214 -279.766776)
		(end 19.784314 -279.766776)
		(width 0.20066)
		(layer "F.Cu")
		(net "M_D_CPU1_SA_DQ<31>")
	)
	(segment
		(start 13.937742 -279.766776)
		(end 14.063726 -279.89276)
		(width 0.20066)
		(layer "F.Cu")
		(net "M_D_CPU1_SA_DQ<31>")
	)
	(segment
		(start 12.240514 -279.766776)
		(end 13.937742 -279.766776)
		(width 0.20066)
		(layer "F.Cu")
		(net "M_D_CPU1_SA_DQ<31>")
	)
	(segment
		(start 17.42948 -280.191718)
		(end 17.578578 -280.04262)
		(width 0.20066)
		(layer "F.Cu")
		(net "M_D_CPU1_SA_DQ<31>")
	)
	(segment
		(start 100.002594 -265.592306)
		(end 100.002848 -265.592306)
		(width 0.20066)
		(layer "F.Cu")
		(net "M_D_CPU1_SA_DQ<31>")
	)
	(segment
		(start 16.885158 -280.191718)
		(end 17.42948 -280.191718)
		(width 0.20066)
		(layer "F.Cu")
		(net "M_D_CPU1_SA_DQ<31>")
	)
	(segment
		(start 100.002594 -266.128246)
		(end 100.002594 -265.592306)
		(width 0.20066)
		(layer "F.Cu")
		(net "M_D_CPU1_SA_DQ<31>")
	)
	(segment
		(start 40.252142 -277.623778)
		(end 40.059102 -277.816818)
		(width 0.18288)
		(layer "In11.Cu")
		(net "M_D_CPU1_SA_DQ<31>")
	)
	(segment
		(start 76.771754 -266.733274)
		(end 67.277742 -276.227286)
		(width 0.18288)
		(layer "In11.Cu")
		(net "M_D_CPU1_SA_DQ<31>")
	)
	(segment
		(start 82.963004 -266.733274)
		(end 76.771754 -266.733274)
		(width 0.18288)
		(layer "In11.Cu")
		(net "M_D_CPU1_SA_DQ<31>")
	)
	(segment
		(start 96.915478 -265.629898)
		(end 96.900746 -265.638534)
		(width 0.088646)
		(layer "In11.Cu")
		(net "M_D_CPU1_SA_DQ<31>")
	)
	(segment
		(start 67.277742 -276.227286)
		(end 63.528956 -276.227286)
		(width 0.18288)
		(layer "In11.Cu")
		(net "M_D_CPU1_SA_DQ<31>")
	)
	(segment
		(start 100.00234 -266.127992)
		(end 99.68992 -266.127992)
		(width 0.088646)
		(layer "In11.Cu")
		(net "M_D_CPU1_SA_DQ<31>")
	)
	(segment
		(start 22.66188 -280.268426)
		(end 21.390864 -280.268426)
		(width 0.18288)
		(layer "In11.Cu")
		(net "M_D_CPU1_SA_DQ<31>")
	)
	(segment
		(start 40.760142 -277.816818)
		(end 40.567102 -277.623778)
		(width 0.18288)
		(layer "In11.Cu")
		(net "M_D_CPU1_SA_DQ<31>")
	)
	(segment
		(start 38.501574 -278.013922)
		(end 38.186614 -278.013922)
		(width 0.18288)
		(layer "In11.Cu")
		(net "M_D_CPU1_SA_DQ<31>")
	)
	(segment
		(start 84.495894 -265.689334)
		(end 83.932014 -265.689334)
		(width 0.088646)
		(layer "In11.Cu")
		(net "M_D_CPU1_SA_DQ<31>")
	)
	(segment
		(start 95.035878 -265.629898)
		(end 95.021146 -265.638534)
		(width 0.088646)
		(layer "In11.Cu")
		(net "M_D_CPU1_SA_DQ<31>")
	)
	(segment
		(start 27.77617 -279.262586)
		(end 27.77617 -279.065736)
		(width 0.18288)
		(layer "In11.Cu")
		(net "M_D_CPU1_SA_DQ<31>")
	)
	(segment
		(start 39.866062 -278.517604)
		(end 38.887654 -278.517604)
		(width 0.18288)
		(layer "In11.Cu")
		(net "M_D_CPU1_SA_DQ<31>")
	)
	(segment
		(start 29.393388 -278.997664)
		(end 28.935426 -279.455626)
		(width 0.18288)
		(layer "In11.Cu")
		(net "M_D_CPU1_SA_DQ<31>")
	)
	(segment
		(start 54.99354 -278.605996)
		(end 54.154578 -278.605996)
		(width 0.18288)
		(layer "In11.Cu")
		(net "M_D_CPU1_SA_DQ<31>")
	)
	(segment
		(start 53.453538 -277.901146)
		(end 53.260498 -278.094186)
		(width 0.18288)
		(layer "In11.Cu")
		(net "M_D_CPU1_SA_DQ<31>")
	)
	(segment
		(start 41.969182 -277.623778)
		(end 41.654222 -277.623778)
		(width 0.18288)
		(layer "In11.Cu")
		(net "M_D_CPU1_SA_DQ<31>")
	)
	(segment
		(start 40.059102 -278.324564)
		(end 39.866062 -278.517604)
		(width 0.18288)
		(layer "In11.Cu")
		(net "M_D_CPU1_SA_DQ<31>")
	)
	(segment
		(start 98.790506 -265.632438)
		(end 98.780092 -265.638534)
		(width 0.088646)
		(layer "In11.Cu")
		(net "M_D_CPU1_SA_DQ<31>")
	)
	(segment
		(start 29.666438 -278.997664)
		(end 29.393388 -278.997664)
		(width 0.18288)
		(layer "In11.Cu")
		(net "M_D_CPU1_SA_DQ<31>")
	)
	(segment
		(start 42.162222 -278.324564)
		(end 42.162222 -277.816818)
		(width 0.18288)
		(layer "In11.Cu")
		(net "M_D_CPU1_SA_DQ<31>")
	)
	(segment
		(start 51.348386 -278.492712)
		(end 51.121818 -278.492712)
		(width 0.18288)
		(layer "In11.Cu")
		(net "M_D_CPU1_SA_DQ<31>")
	)
	(segment
		(start 100.002594 -266.128246)
		(end 100.00234 -266.127992)
		(width 0.088646)
		(layer "In11.Cu")
		(net "M_D_CPU1_SA_DQ<31>")
	)
	(segment
		(start 36.653978 -278.491442)
		(end 35.37966 -278.491442)
		(width 0.18288)
		(layer "In11.Cu")
		(net "M_D_CPU1_SA_DQ<31>")
	)
	(segment
		(start 37.643308 -278.67483)
		(end 36.837366 -278.67483)
		(width 0.18288)
		(layer "In11.Cu")
		(net "M_D_CPU1_SA_DQ<31>")
	)
	(segment
		(start 59.009026 -277.830026)
		(end 55.76951 -277.830026)
		(width 0.18288)
		(layer "In11.Cu")
		(net "M_D_CPU1_SA_DQ<31>")
	)
	(segment
		(start 40.953182 -278.473662)
		(end 40.760142 -278.280622)
		(width 0.18288)
		(layer "In11.Cu")
		(net "M_D_CPU1_SA_DQ<31>")
	)
	(segment
		(start 28.935426 -279.455626)
		(end 27.96921 -279.455626)
		(width 0.18288)
		(layer "In11.Cu")
		(net "M_D_CPU1_SA_DQ<31>")
	)
	(segment
		(start 51.121818 -278.492712)
		(end 51.120294 -278.491188)
		(width 0.18288)
		(layer "In11.Cu")
		(net "M_D_CPU1_SA_DQ<31>")
	)
	(segment
		(start 37.993574 -278.206962)
		(end 37.993574 -278.324564)
		(width 0.18288)
		(layer "In11.Cu")
		(net "M_D_CPU1_SA_DQ<31>")
	)
	(segment
		(start 53.961538 -278.094186)
		(end 53.768498 -277.901146)
		(width 0.18288)
		(layer "In11.Cu")
		(net "M_D_CPU1_SA_DQ<31>")
	)
	(segment
		(start 41.654222 -277.623778)
		(end 41.461182 -277.816818)
		(width 0.18288)
		(layer "In11.Cu")
		(net "M_D_CPU1_SA_DQ<31>")
	)
	(segment
		(start 51.120294 -278.491188)
		(end 50.994818 -278.491188)
		(width 0.18288)
		(layer "In11.Cu")
		(net "M_D_CPU1_SA_DQ<31>")
	)
	(segment
		(start 59.82589 -277.013162)
		(end 59.009026 -277.830026)
		(width 0.18288)
		(layer "In11.Cu")
		(net "M_D_CPU1_SA_DQ<31>")
	)
	(segment
		(start 30.540198 -278.887428)
		(end 30.321504 -279.106122)
		(width 0.18288)
		(layer "In11.Cu")
		(net "M_D_CPU1_SA_DQ<31>")
	)
	(segment
		(start 53.067458 -278.605996)
		(end 51.46167 -278.605996)
		(width 0.18288)
		(layer "In11.Cu")
		(net "M_D_CPU1_SA_DQ<31>")
	)
	(segment
		(start 23.55596 -280.075386)
		(end 23.55596 -279.97658)
		(width 0.18288)
		(layer "In11.Cu")
		(net "M_D_CPU1_SA_DQ<31>")
	)
	(segment
		(start 51.46167 -278.605996)
		(end 51.348386 -278.492712)
		(width 0.18288)
		(layer "In11.Cu")
		(net "M_D_CPU1_SA_DQ<31>")
	)
	(segment
		(start 25.811226 -279.455626)
		(end 24.998426 -280.268426)
		(width 0.18288)
		(layer "In11.Cu")
		(net "M_D_CPU1_SA_DQ<31>")
	)
	(segment
		(start 27.58313 -278.872696)
		(end 27.26817 -278.872696)
		(width 0.18288)
		(layer "In11.Cu")
		(net "M_D_CPU1_SA_DQ<31>")
	)
	(segment
		(start 44.39031 -278.820118)
		(end 43.778424 -279.432004)
		(width 0.18288)
		(layer "In11.Cu")
		(net "M_D_CPU1_SA_DQ<31>")
	)
	(segment
		(start 38.694614 -278.324564)
		(end 38.694614 -278.206962)
		(width 0.18288)
		(layer "In11.Cu")
		(net "M_D_CPU1_SA_DQ<31>")
	)
	(segment
		(start 40.567102 -277.623778)
		(end 40.252142 -277.623778)
		(width 0.18288)
		(layer "In11.Cu")
		(net "M_D_CPU1_SA_DQ<31>")
	)
	(segment
		(start 53.260498 -278.412956)
		(end 53.067458 -278.605996)
		(width 0.18288)
		(layer "In11.Cu")
		(net "M_D_CPU1_SA_DQ<31>")
	)
	(segment
		(start 83.217004 -266.404344)
		(end 83.217004 -266.644628)
		(width 0.088646)
		(layer "In11.Cu")
		(net "M_D_CPU1_SA_DQ<31>")
	)
	(segment
		(start 41.461182 -278.280622)
		(end 41.268142 -278.473662)
		(width 0.18288)
		(layer "In11.Cu")
		(net "M_D_CPU1_SA_DQ<31>")
	)
	(segment
		(start 27.07513 -279.262586)
		(end 26.88209 -279.455626)
		(width 0.18288)
		(layer "In11.Cu")
		(net "M_D_CPU1_SA_DQ<31>")
	)
	(segment
		(start 53.768498 -277.901146)
		(end 53.453538 -277.901146)
		(width 0.18288)
		(layer "In11.Cu")
		(net "M_D_CPU1_SA_DQ<31>")
	)
	(segment
		(start 23.04796 -279.78354)
		(end 22.85492 -279.97658)
		(width 0.18288)
		(layer "In11.Cu")
		(net "M_D_CPU1_SA_DQ<31>")
	)
	(segment
		(start 34.52622 -279.344882)
		(end 31.270702 -279.344882)
		(width 0.18288)
		(layer "In11.Cu")
		(net "M_D_CPU1_SA_DQ<31>")
	)
	(segment
		(start 43.778424 -279.432004)
		(end 43.269662 -279.432004)
		(width 0.18288)
		(layer "In11.Cu")
		(net "M_D_CPU1_SA_DQ<31>")
	)
	(segment
		(start 83.932014 -265.689334)
		(end 83.217004 -266.404344)
		(width 0.088646)
		(layer "In11.Cu")
		(net "M_D_CPU1_SA_DQ<31>")
	)
	(segment
		(start 63.528956 -276.227286)
		(end 62.74308 -277.013162)
		(width 0.18288)
		(layer "In11.Cu")
		(net "M_D_CPU1_SA_DQ<31>")
	)
	(segment
		(start 55.76951 -277.830026)
		(end 54.99354 -278.605996)
		(width 0.18288)
		(layer "In11.Cu")
		(net "M_D_CPU1_SA_DQ<31>")
	)
	(segment
		(start 49.16297 -279.344882)
		(end 45.461682 -279.344882)
		(width 0.18288)
		(layer "In11.Cu")
		(net "M_D_CPU1_SA_DQ<31>")
	)
	(segment
		(start 45.461682 -279.344882)
		(end 44.936918 -278.820118)
		(width 0.18288)
		(layer "In11.Cu")
		(net "M_D_CPU1_SA_DQ<31>")
	)
	(segment
		(start 30.321504 -279.106122)
		(end 30.321504 -279.106376)
		(width 0.18288)
		(layer "In11.Cu")
		(net "M_D_CPU1_SA_DQ<31>")
	)
	(segment
		(start 92.211906 -265.632438)
		(end 92.201492 -265.638534)
		(width 0.088646)
		(layer "In11.Cu")
		(net "M_D_CPU1_SA_DQ<31>")
	)
	(segment
		(start 24.998426 -280.268426)
		(end 23.749 -280.268426)
		(width 0.18288)
		(layer "In11.Cu")
		(net "M_D_CPU1_SA_DQ<31>")
	)
	(segment
		(start 31.270702 -279.344882)
		(end 30.813248 -278.887428)
		(width 0.18288)
		(layer "In11.Cu")
		(net "M_D_CPU1_SA_DQ<31>")
	)
	(segment
		(start 30.161484 -279.266396)
		(end 29.93517 -279.266396)
		(width 0.18288)
		(layer "In11.Cu")
		(net "M_D_CPU1_SA_DQ<31>")
	)
	(segment
		(start 38.186614 -278.013922)
		(end 37.993574 -278.206962)
		(width 0.18288)
		(layer "In11.Cu")
		(net "M_D_CPU1_SA_DQ<31>")
	)
	(segment
		(start 40.059102 -277.816818)
		(end 40.059102 -278.324564)
		(width 0.18288)
		(layer "In11.Cu")
		(net "M_D_CPU1_SA_DQ<31>")
	)
	(segment
		(start 53.260498 -278.094186)
		(end 53.260498 -278.412956)
		(width 0.18288)
		(layer "In11.Cu")
		(net "M_D_CPU1_SA_DQ<31>")
	)
	(segment
		(start 41.268142 -278.473662)
		(end 40.953182 -278.473662)
		(width 0.18288)
		(layer "In11.Cu")
		(net "M_D_CPU1_SA_DQ<31>")
	)
	(segment
		(start 38.887654 -278.517604)
		(end 38.694614 -278.324564)
		(width 0.18288)
		(layer "In11.Cu")
		(net "M_D_CPU1_SA_DQ<31>")
	)
	(segment
		(start 95.975678 -265.629898)
		(end 95.960946 -265.638534)
		(width 0.088646)
		(layer "In11.Cu")
		(net "M_D_CPU1_SA_DQ<31>")
	)
	(segment
		(start 62.74308 -277.013162)
		(end 59.82589 -277.013162)
		(width 0.18288)
		(layer "In11.Cu")
		(net "M_D_CPU1_SA_DQ<31>")
	)
	(segment
		(start 27.77617 -279.065736)
		(end 27.58313 -278.872696)
		(width 0.18288)
		(layer "In11.Cu")
		(net "M_D_CPU1_SA_DQ<31>")
	)
	(segment
		(start 83.128358 -266.733274)
		(end 82.963004 -266.733274)
		(width 0.088646)
		(layer "In11.Cu")
		(net "M_D_CPU1_SA_DQ<31>")
	)
	(segment
		(start 23.36292 -279.78354)
		(end 23.04796 -279.78354)
		(width 0.18288)
		(layer "In11.Cu")
		(net "M_D_CPU1_SA_DQ<31>")
	)
	(segment
		(start 83.217004 -266.644628)
		(end 83.128358 -266.733274)
		(width 0.088646)
		(layer "In11.Cu")
		(net "M_D_CPU1_SA_DQ<31>")
	)
	(segment
		(start 30.813248 -278.887428)
		(end 30.540198 -278.887428)
		(width 0.18288)
		(layer "In11.Cu")
		(net "M_D_CPU1_SA_DQ<31>")
	)
	(segment
		(start 97.85096 -265.632438)
		(end 97.840546 -265.638534)
		(width 0.088646)
		(layer "In11.Cu")
		(net "M_D_CPU1_SA_DQ<31>")
	)
	(segment
		(start 27.26817 -278.872696)
		(end 27.07513 -279.065736)
		(width 0.18288)
		(layer "In11.Cu")
		(net "M_D_CPU1_SA_DQ<31>")
	)
	(segment
		(start 29.93517 -279.266396)
		(end 29.666438 -278.997664)
		(width 0.18288)
		(layer "In11.Cu")
		(net "M_D_CPU1_SA_DQ<31>")
	)
	(segment
		(start 93.156278 -265.629898)
		(end 93.141546 -265.638534)
		(width 0.088646)
		(layer "In11.Cu")
		(net "M_D_CPU1_SA_DQ<31>")
	)
	(segment
		(start 30.321504 -279.106376)
		(end 30.161484 -279.266396)
		(width 0.18288)
		(layer "In11.Cu")
		(net "M_D_CPU1_SA_DQ<31>")
	)
	(segment
		(start 41.461182 -277.816818)
		(end 41.461182 -278.280622)
		(width 0.18288)
		(layer "In11.Cu")
		(net "M_D_CPU1_SA_DQ<31>")
	)
	(segment
		(start 54.154578 -278.605996)
		(end 53.961538 -278.412956)
		(width 0.18288)
		(layer "In11.Cu")
		(net "M_D_CPU1_SA_DQ<31>")
	)
	(segment
		(start 94.096078 -265.629898)
		(end 94.081346 -265.638534)
		(width 0.088646)
		(layer "In11.Cu")
		(net "M_D_CPU1_SA_DQ<31>")
	)
	(segment
		(start 90.332306 -265.632438)
		(end 90.321892 -265.638534)
		(width 0.088646)
		(layer "In11.Cu")
		(net "M_D_CPU1_SA_DQ<31>")
	)
	(segment
		(start 44.936918 -278.820118)
		(end 44.39031 -278.820118)
		(width 0.18288)
		(layer "In11.Cu")
		(net "M_D_CPU1_SA_DQ<31>")
	)
	(segment
		(start 27.07513 -279.065736)
		(end 27.07513 -279.262586)
		(width 0.18288)
		(layer "In11.Cu")
		(net "M_D_CPU1_SA_DQ<31>")
	)
	(segment
		(start 22.85492 -280.075386)
		(end 22.66188 -280.268426)
		(width 0.18288)
		(layer "In11.Cu")
		(net "M_D_CPU1_SA_DQ<31>")
	)
	(segment
		(start 43.269662 -279.432004)
		(end 42.162222 -278.324564)
		(width 0.18288)
		(layer "In11.Cu")
		(net "M_D_CPU1_SA_DQ<31>")
	)
	(segment
		(start 27.96921 -279.455626)
		(end 27.77617 -279.262586)
		(width 0.18288)
		(layer "In11.Cu")
		(net "M_D_CPU1_SA_DQ<31>")
	)
	(segment
		(start 21.390864 -280.268426)
		(end 20.889214 -279.766776)
		(width 0.18288)
		(layer "In11.Cu")
		(net "M_D_CPU1_SA_DQ<31>")
	)
	(segment
		(start 50.01514 -278.492712)
		(end 49.16297 -279.344882)
		(width 0.18288)
		(layer "In11.Cu")
		(net "M_D_CPU1_SA_DQ<31>")
	)
	(segment
		(start 23.749 -280.268426)
		(end 23.55596 -280.075386)
		(width 0.18288)
		(layer "In11.Cu")
		(net "M_D_CPU1_SA_DQ<31>")
	)
	(segment
		(start 38.694614 -278.206962)
		(end 38.501574 -278.013922)
		(width 0.18288)
		(layer "In11.Cu")
		(net "M_D_CPU1_SA_DQ<31>")
	)
	(segment
		(start 42.162222 -277.816818)
		(end 41.969182 -277.623778)
		(width 0.18288)
		(layer "In11.Cu")
		(net "M_D_CPU1_SA_DQ<31>")
	)
	(segment
		(start 40.760142 -278.280622)
		(end 40.760142 -277.816818)
		(width 0.18288)
		(layer "In11.Cu")
		(net "M_D_CPU1_SA_DQ<31>")
	)
	(segment
		(start 91.27236 -265.632438)
		(end 91.261946 -265.638534)
		(width 0.088646)
		(layer "In11.Cu")
		(net "M_D_CPU1_SA_DQ<31>")
	)
	(segment
		(start 23.55596 -279.97658)
		(end 23.36292 -279.78354)
		(width 0.18288)
		(layer "In11.Cu")
		(net "M_D_CPU1_SA_DQ<31>")
	)
	(segment
		(start 22.85492 -279.97658)
		(end 22.85492 -280.075386)
		(width 0.18288)
		(layer "In11.Cu")
		(net "M_D_CPU1_SA_DQ<31>")
	)
	(segment
		(start 35.37966 -278.491442)
		(end 34.52622 -279.344882)
		(width 0.18288)
		(layer "In11.Cu")
		(net "M_D_CPU1_SA_DQ<31>")
	)
	(segment
		(start 26.88209 -279.455626)
		(end 25.811226 -279.455626)
		(width 0.18288)
		(layer "In11.Cu")
		(net "M_D_CPU1_SA_DQ<31>")
	)
	(segment
		(start 50.994818 -278.491188)
		(end 50.993294 -278.492712)
		(width 0.18288)
		(layer "In11.Cu")
		(net "M_D_CPU1_SA_DQ<31>")
	)
	(segment
		(start 36.837366 -278.67483)
		(end 36.653978 -278.491442)
		(width 0.18288)
		(layer "In11.Cu")
		(net "M_D_CPU1_SA_DQ<31>")
	)
	(segment
		(start 50.993294 -278.492712)
		(end 50.01514 -278.492712)
		(width 0.18288)
		(layer "In11.Cu")
		(net "M_D_CPU1_SA_DQ<31>")
	)
	(segment
		(start 99.68992 -266.127992)
		(end 99.624388 -266.06246)
		(width 0.088646)
		(layer "In11.Cu")
		(net "M_D_CPU1_SA_DQ<31>")
	)
	(segment
		(start 53.961538 -278.412956)
		(end 53.961538 -278.094186)
		(width 0.18288)
		(layer "In11.Cu")
		(net "M_D_CPU1_SA_DQ<31>")
	)
	(segment
		(start 37.993574 -278.324564)
		(end 37.643308 -278.67483)
		(width 0.18288)
		(layer "In11.Cu")
		(net "M_D_CPU1_SA_DQ<31>")
	)
	(arc
		(start 87.502492 -265.638534)
		(mid 87.315294 -265.688677)
		(end 87.128096 -265.638534)
		(width 0.088646)
		(layer "In11.Cu")
		(net "M_D_CPU1_SA_DQ<31>")
	)
	(arc
		(start 86.562692 -265.638534)
		(mid 86.375494 -265.688677)
		(end 86.188296 -265.638534)
		(width 0.088646)
		(layer "In11.Cu")
		(net "M_D_CPU1_SA_DQ<31>")
	)
	(arc
		(start 97.46615 -265.638534)
		(mid 97.191951 -265.562699)
		(end 96.915478 -265.629898)
		(width 0.088646)
		(layer "In11.Cu")
		(net "M_D_CPU1_SA_DQ<31>")
	)
	(arc
		(start 87.128096 -265.638534)
		(mid 86.845394 -265.562792)
		(end 86.562692 -265.638534)
		(width 0.088646)
		(layer "In11.Cu")
		(net "M_D_CPU1_SA_DQ<31>")
	)
	(arc
		(start 95.58655 -265.638534)
		(mid 95.312351 -265.562699)
		(end 95.035878 -265.629898)
		(width 0.088646)
		(layer "In11.Cu")
		(net "M_D_CPU1_SA_DQ<31>")
	)
	(arc
		(start 91.261946 -265.638534)
		(mid 91.074748 -265.688677)
		(end 90.88755 -265.638534)
		(width 0.088646)
		(layer "In11.Cu")
		(net "M_D_CPU1_SA_DQ<31>")
	)
	(arc
		(start 93.70695 -265.638534)
		(mid 93.432751 -265.562699)
		(end 93.156278 -265.629898)
		(width 0.088646)
		(layer "In11.Cu")
		(net "M_D_CPU1_SA_DQ<31>")
	)
	(arc
		(start 99.624388 -266.06246)
		(mid 99.5353 -265.817475)
		(end 99.34575 -265.638534)
		(width 0.088646)
		(layer "In11.Cu")
		(net "M_D_CPU1_SA_DQ<31>")
	)
	(arc
		(start 92.201492 -265.638534)
		(mid 92.014294 -265.688677)
		(end 91.827096 -265.638534)
		(width 0.088646)
		(layer "In11.Cu")
		(net "M_D_CPU1_SA_DQ<31>")
	)
	(arc
		(start 89.382092 -265.638534)
		(mid 89.194894 -265.688677)
		(end 89.007696 -265.638534)
		(width 0.088646)
		(layer "In11.Cu")
		(net "M_D_CPU1_SA_DQ<31>")
	)
	(arc
		(start 88.442292 -265.638534)
		(mid 88.255094 -265.688677)
		(end 88.067896 -265.638534)
		(width 0.088646)
		(layer "In11.Cu")
		(net "M_D_CPU1_SA_DQ<31>")
	)
	(arc
		(start 93.141546 -265.638534)
		(mid 92.954348 -265.688677)
		(end 92.76715 -265.638534)
		(width 0.088646)
		(layer "In11.Cu")
		(net "M_D_CPU1_SA_DQ<31>")
	)
	(arc
		(start 98.405696 -265.638534)
		(mid 98.129137 -265.562791)
		(end 97.85096 -265.632438)
		(width 0.088646)
		(layer "In11.Cu")
		(net "M_D_CPU1_SA_DQ<31>")
	)
	(arc
		(start 86.188296 -265.638534)
		(mid 85.905594 -265.562792)
		(end 85.622892 -265.638534)
		(width 0.088646)
		(layer "In11.Cu")
		(net "M_D_CPU1_SA_DQ<31>")
	)
	(arc
		(start 88.067896 -265.638534)
		(mid 87.785194 -265.562792)
		(end 87.502492 -265.638534)
		(width 0.088646)
		(layer "In11.Cu")
		(net "M_D_CPU1_SA_DQ<31>")
	)
	(arc
		(start 98.780092 -265.638534)
		(mid 98.592894 -265.688677)
		(end 98.405696 -265.638534)
		(width 0.088646)
		(layer "In11.Cu")
		(net "M_D_CPU1_SA_DQ<31>")
	)
	(arc
		(start 94.081346 -265.638534)
		(mid 93.894148 -265.688677)
		(end 93.70695 -265.638534)
		(width 0.088646)
		(layer "In11.Cu")
		(net "M_D_CPU1_SA_DQ<31>")
	)
	(arc
		(start 85.248496 -265.638534)
		(mid 84.965794 -265.562792)
		(end 84.683092 -265.638534)
		(width 0.088646)
		(layer "In11.Cu")
		(net "M_D_CPU1_SA_DQ<31>")
	)
	(arc
		(start 94.64675 -265.638534)
		(mid 94.372551 -265.562699)
		(end 94.096078 -265.629898)
		(width 0.088646)
		(layer "In11.Cu")
		(net "M_D_CPU1_SA_DQ<31>")
	)
	(arc
		(start 95.021146 -265.638534)
		(mid 94.833948 -265.688677)
		(end 94.64675 -265.638534)
		(width 0.088646)
		(layer "In11.Cu")
		(net "M_D_CPU1_SA_DQ<31>")
	)
	(arc
		(start 89.007696 -265.638534)
		(mid 88.724994 -265.562758)
		(end 88.442292 -265.638534)
		(width 0.088646)
		(layer "In11.Cu")
		(net "M_D_CPU1_SA_DQ<31>")
	)
	(arc
		(start 91.827096 -265.638534)
		(mid 91.550537 -265.562791)
		(end 91.27236 -265.632438)
		(width 0.088646)
		(layer "In11.Cu")
		(net "M_D_CPU1_SA_DQ<31>")
	)
	(arc
		(start 85.622892 -265.638534)
		(mid 85.435694 -265.688677)
		(end 85.248496 -265.638534)
		(width 0.088646)
		(layer "In11.Cu")
		(net "M_D_CPU1_SA_DQ<31>")
	)
	(arc
		(start 89.947496 -265.638534)
		(mid 89.664794 -265.562758)
		(end 89.382092 -265.638534)
		(width 0.088646)
		(layer "In11.Cu")
		(net "M_D_CPU1_SA_DQ<31>")
	)
	(arc
		(start 90.88755 -265.638534)
		(mid 90.610737 -265.562664)
		(end 90.332306 -265.632438)
		(width 0.088646)
		(layer "In11.Cu")
		(net "M_D_CPU1_SA_DQ<31>")
	)
	(arc
		(start 90.321892 -265.638534)
		(mid 90.134694 -265.688677)
		(end 89.947496 -265.638534)
		(width 0.088646)
		(layer "In11.Cu")
		(net "M_D_CPU1_SA_DQ<31>")
	)
	(arc
		(start 97.840546 -265.638534)
		(mid 97.653348 -265.688677)
		(end 97.46615 -265.638534)
		(width 0.088646)
		(layer "In11.Cu")
		(net "M_D_CPU1_SA_DQ<31>")
	)
	(arc
		(start 84.683092 -265.638534)
		(mid 84.592836 -265.676256)
		(end 84.495894 -265.689334)
		(width 0.088646)
		(layer "In11.Cu")
		(net "M_D_CPU1_SA_DQ<31>")
	)
	(arc
		(start 92.76715 -265.638534)
		(mid 92.490337 -265.562664)
		(end 92.211906 -265.632438)
		(width 0.088646)
		(layer "In11.Cu")
		(net "M_D_CPU1_SA_DQ<31>")
	)
	(arc
		(start 95.960946 -265.638534)
		(mid 95.773748 -265.688677)
		(end 95.58655 -265.638534)
		(width 0.088646)
		(layer "In11.Cu")
		(net "M_D_CPU1_SA_DQ<31>")
	)
	(arc
		(start 99.34575 -265.638534)
		(mid 99.068937 -265.562664)
		(end 98.790506 -265.632438)
		(width 0.088646)
		(layer "In11.Cu")
		(net "M_D_CPU1_SA_DQ<31>")
	)
	(arc
		(start 96.52635 -265.638534)
		(mid 96.252151 -265.562699)
		(end 95.975678 -265.629898)
		(width 0.088646)
		(layer "In11.Cu")
		(net "M_D_CPU1_SA_DQ<31>")
	)
	(arc
		(start 96.900746 -265.638534)
		(mid 96.713548 -265.688677)
		(end 96.52635 -265.638534)
		(width 0.088646)
		(layer "In11.Cu")
		(net "M_D_CPU1_SA_DQ<31>")
	)
	(segment
		(start 20.889214 -281.466798)
		(end 19.784314 -281.466798)
		(width 0.20066)
		(layer "F.Cu")
		(net "M_D_CPU1_SA_DQ<30>")
	)
	(segment
		(start 17.66189 -281.511248)
		(end 17.829276 -281.678634)
		(width 0.20066)
		(layer "F.Cu")
		(net "M_D_CPU1_SA_DQ<30>")
	)
	(segment
		(start 18.257774 -281.678634)
		(end 18.46961 -281.466798)
		(width 0.20066)
		(layer "F.Cu")
		(net "M_D_CPU1_SA_DQ<30>")
	)
	(segment
		(start 16.885158 -281.041856)
		(end 17.518126 -281.041856)
		(width 0.20066)
		(layer "F.Cu")
		(net "M_D_CPU1_SA_DQ<30>")
	)
	(segment
		(start 14.560042 -281.031696)
		(end 14.570202 -281.041856)
		(width 0.101854)
		(layer "F.Cu")
		(net "M_D_CPU1_SA_DQ<30>")
	)
	(segment
		(start 17.518126 -281.041856)
		(end 17.66189 -281.18562)
		(width 0.20066)
		(layer "F.Cu")
		(net "M_D_CPU1_SA_DQ<30>")
	)
	(segment
		(start 13.82268 -281.031696)
		(end 14.560042 -281.031696)
		(width 0.20066)
		(layer "F.Cu")
		(net "M_D_CPU1_SA_DQ<30>")
	)
	(segment
		(start 18.46961 -281.466798)
		(end 19.784314 -281.466798)
		(width 0.20066)
		(layer "F.Cu")
		(net "M_D_CPU1_SA_DQ<30>")
	)
	(segment
		(start 17.66189 -281.18562)
		(end 17.66189 -281.511248)
		(width 0.20066)
		(layer "F.Cu")
		(net "M_D_CPU1_SA_DQ<30>")
	)
	(segment
		(start 12.240514 -281.466798)
		(end 13.387578 -281.466798)
		(width 0.20066)
		(layer "F.Cu")
		(net "M_D_CPU1_SA_DQ<30>")
	)
	(segment
		(start 13.387578 -281.466798)
		(end 13.82268 -281.031696)
		(width 0.20066)
		(layer "F.Cu")
		(net "M_D_CPU1_SA_DQ<30>")
	)
	(segment
		(start 14.570202 -281.041856)
		(end 14.825218 -281.041856)
		(width 0.101854)
		(layer "F.Cu")
		(net "M_D_CPU1_SA_DQ<30>")
	)
	(segment
		(start 14.825218 -281.041856)
		(end 16.885158 -281.041856)
		(width 0.1016)
		(layer "F.Cu")
		(net "M_D_CPU1_SA_DQ<30>")
	)
	(segment
		(start 17.829276 -281.678634)
		(end 18.257774 -281.678634)
		(width 0.20066)
		(layer "F.Cu")
		(net "M_D_CPU1_SA_DQ<30>")
	)
	(arc
		(start 100.472494 -266.405868)
		(mid 100.472557 -266.673838)
		(end 100.472748 -266.941808)
		(width 0.20066)
		(layer "F.Cu")
		(net "M_D_CPU1_SA_DQ<30>")
	)
	(segment
		(start 98.897948 -266.4841)
		(end 98.897694 -266.4841)
		(width 0.088646)
		(layer "In11.Cu")
		(net "M_D_CPU1_SA_DQ<30>")
	)
	(segment
		(start 50.995072 -280.190956)
		(end 50.993294 -280.192734)
		(width 0.18288)
		(layer "In11.Cu")
		(net "M_D_CPU1_SA_DQ<30>")
	)
	(segment
		(start 83.168236 -267.749274)
		(end 82.963004 -267.749274)
		(width 0.088646)
		(layer "In11.Cu")
		(net "M_D_CPU1_SA_DQ<30>")
	)
	(segment
		(start 40.16375 -280.368502)
		(end 38.929564 -280.368502)
		(width 0.18288)
		(layer "In11.Cu")
		(net "M_D_CPU1_SA_DQ<30>")
	)
	(segment
		(start 30.733238 -281.372564)
		(end 30.37205 -281.372564)
		(width 0.18288)
		(layer "In11.Cu")
		(net "M_D_CPU1_SA_DQ<30>")
	)
	(segment
		(start 36.52266 -280.19248)
		(end 35.498278 -280.19248)
		(width 0.18288)
		(layer "In11.Cu")
		(net "M_D_CPU1_SA_DQ<30>")
	)
	(segment
		(start 83.606386 -267.208508)
		(end 83.256882 -267.558012)
		(width 0.088646)
		(layer "In11.Cu")
		(net "M_D_CPU1_SA_DQ<30>")
	)
	(segment
		(start 27.70251 -281.065986)
		(end 27.70251 -280.86558)
		(width 0.18288)
		(layer "In11.Cu")
		(net "M_D_CPU1_SA_DQ<30>")
	)
	(segment
		(start 38.736524 -280.175462)
		(end 38.736524 -279.929082)
		(width 0.18288)
		(layer "In11.Cu")
		(net "M_D_CPU1_SA_DQ<30>")
	)
	(segment
		(start 54.894226 -280.370026)
		(end 53.990494 -280.370026)
		(width 0.18288)
		(layer "In11.Cu")
		(net "M_D_CPU1_SA_DQ<30>")
	)
	(segment
		(start 50.270918 -280.192734)
		(end 49.339754 -281.123898)
		(width 0.18288)
		(layer "In11.Cu")
		(net "M_D_CPU1_SA_DQ<30>")
	)
	(segment
		(start 98.897694 -266.4841)
		(end 98.824796 -266.444222)
		(width 0.088646)
		(layer "In11.Cu")
		(net "M_D_CPU1_SA_DQ<30>")
	)
	(segment
		(start 27.70251 -280.86558)
		(end 27.50947 -280.67254)
		(width 0.18288)
		(layer "In11.Cu")
		(net "M_D_CPU1_SA_DQ<30>")
	)
	(segment
		(start 27.89555 -281.259026)
		(end 27.70251 -281.065986)
		(width 0.18288)
		(layer "In11.Cu")
		(net "M_D_CPU1_SA_DQ<30>")
	)
	(segment
		(start 53.604414 -279.713944)
		(end 53.289454 -279.713944)
		(width 0.18288)
		(layer "In11.Cu")
		(net "M_D_CPU1_SA_DQ<30>")
	)
	(segment
		(start 66.826384 -277.277322)
		(end 66.171572 -277.932134)
		(width 0.18288)
		(layer "In11.Cu")
		(net "M_D_CPU1_SA_DQ<30>")
	)
	(segment
		(start 96.056196 -266.45235)
		(end 96.041464 -266.443714)
		(width 0.088646)
		(layer "In11.Cu")
		(net "M_D_CPU1_SA_DQ<30>")
	)
	(segment
		(start 77.19314 -267.749274)
		(end 67.665092 -277.277322)
		(width 0.18288)
		(layer "In11.Cu")
		(net "M_D_CPU1_SA_DQ<30>")
	)
	(segment
		(start 66.171572 -277.932134)
		(end 63.495174 -277.932134)
		(width 0.18288)
		(layer "In11.Cu")
		(net "M_D_CPU1_SA_DQ<30>")
	)
	(segment
		(start 27.50947 -280.67254)
		(end 27.19451 -280.67254)
		(width 0.18288)
		(layer "In11.Cu")
		(net "M_D_CPU1_SA_DQ<30>")
	)
	(segment
		(start 59.186826 -279.404826)
		(end 57.946544 -279.404826)
		(width 0.18288)
		(layer "In11.Cu")
		(net "M_D_CPU1_SA_DQ<30>")
	)
	(segment
		(start 60.129674 -279.150826)
		(end 59.440826 -279.150826)
		(width 0.18288)
		(layer "In11.Cu")
		(net "M_D_CPU1_SA_DQ<30>")
	)
	(segment
		(start 30.018736 -280.852626)
		(end 29.164026 -280.852626)
		(width 0.18288)
		(layer "In11.Cu")
		(net "M_D_CPU1_SA_DQ<30>")
	)
	(segment
		(start 52.903374 -280.370026)
		(end 52.100226 -280.370026)
		(width 0.18288)
		(layer "In11.Cu")
		(net "M_D_CPU1_SA_DQ<30>")
	)
	(segment
		(start 61.432948 -278.18334)
		(end 61.09716 -278.18334)
		(width 0.18288)
		(layer "In11.Cu")
		(net "M_D_CPU1_SA_DQ<30>")
	)
	(segment
		(start 53.797454 -280.176986)
		(end 53.797454 -279.906984)
		(width 0.18288)
		(layer "In11.Cu")
		(net "M_D_CPU1_SA_DQ<30>")
	)
	(segment
		(start 53.096414 -279.906984)
		(end 53.096414 -280.176986)
		(width 0.18288)
		(layer "In11.Cu")
		(net "M_D_CPU1_SA_DQ<30>")
	)
	(segment
		(start 84.101686 -266.376658)
		(end 83.606386 -266.871958)
		(width 0.088646)
		(layer "In11.Cu")
		(net "M_D_CPU1_SA_DQ<30>")
	)
	(segment
		(start 30.893258 -281.212544)
		(end 30.733238 -281.372564)
		(width 0.18288)
		(layer "In11.Cu")
		(net "M_D_CPU1_SA_DQ<30>")
	)
	(segment
		(start 37.842444 -280.368502)
		(end 36.698682 -280.368502)
		(width 0.18288)
		(layer "In11.Cu")
		(net "M_D_CPU1_SA_DQ<30>")
	)
	(segment
		(start 99.249992 -266.45235)
		(end 99.195128 -266.4841)
		(width 0.088646)
		(layer "In11.Cu")
		(net "M_D_CPU1_SA_DQ<30>")
	)
	(segment
		(start 46.578266 -280.929334)
		(end 46.28515 -280.929334)
		(width 0.18288)
		(layer "In11.Cu")
		(net "M_D_CPU1_SA_DQ<30>")
	)
	(segment
		(start 50.993294 -280.192734)
		(end 50.270918 -280.192734)
		(width 0.18288)
		(layer "In11.Cu")
		(net "M_D_CPU1_SA_DQ<30>")
	)
	(segment
		(start 93.236796 -266.45235)
		(end 93.222064 -266.443714)
		(width 0.088646)
		(layer "In11.Cu")
		(net "M_D_CPU1_SA_DQ<30>")
	)
	(segment
		(start 31.053278 -280.852626)
		(end 30.893258 -281.012646)
		(width 0.18288)
		(layer "In11.Cu")
		(net "M_D_CPU1_SA_DQ<30>")
	)
	(segment
		(start 24.70531 -282.064206)
		(end 21.486622 -282.064206)
		(width 0.18288)
		(layer "In11.Cu")
		(net "M_D_CPU1_SA_DQ<30>")
	)
	(segment
		(start 46.69155 -281.042618)
		(end 46.578266 -280.929334)
		(width 0.18288)
		(layer "In11.Cu")
		(net "M_D_CPU1_SA_DQ<30>")
	)
	(segment
		(start 49.339754 -281.123898)
		(end 47.802038 -281.123898)
		(width 0.18288)
		(layer "In11.Cu")
		(net "M_D_CPU1_SA_DQ<30>")
	)
	(segment
		(start 53.096414 -280.176986)
		(end 52.903374 -280.370026)
		(width 0.18288)
		(layer "In11.Cu")
		(net "M_D_CPU1_SA_DQ<30>")
	)
	(segment
		(start 42.24274 -281.182826)
		(end 41.815004 -280.75509)
		(width 0.18288)
		(layer "In11.Cu")
		(net "M_D_CPU1_SA_DQ<30>")
	)
	(segment
		(start 28.757626 -281.259026)
		(end 27.89555 -281.259026)
		(width 0.18288)
		(layer "In11.Cu")
		(net "M_D_CPU1_SA_DQ<30>")
	)
	(segment
		(start 51.922934 -280.192734)
		(end 51.138836 -280.192734)
		(width 0.18288)
		(layer "In11.Cu")
		(net "M_D_CPU1_SA_DQ<30>")
	)
	(segment
		(start 61.09716 -278.18334)
		(end 60.129674 -279.150826)
		(width 0.18288)
		(layer "In11.Cu")
		(net "M_D_CPU1_SA_DQ<30>")
	)
	(segment
		(start 83.256882 -267.558012)
		(end 83.256882 -267.660628)
		(width 0.088646)
		(layer "In11.Cu")
		(net "M_D_CPU1_SA_DQ<30>")
	)
	(segment
		(start 62.658498 -278.76881)
		(end 62.018418 -278.76881)
		(width 0.18288)
		(layer "In11.Cu")
		(net "M_D_CPU1_SA_DQ<30>")
	)
	(segment
		(start 27.19451 -280.67254)
		(end 27.00147 -280.86558)
		(width 0.18288)
		(layer "In11.Cu")
		(net "M_D_CPU1_SA_DQ<30>")
	)
	(segment
		(start 57.052464 -279.048718)
		(end 57.052464 -279.211786)
		(width 0.18288)
		(layer "In11.Cu")
		(net "M_D_CPU1_SA_DQ<30>")
	)
	(segment
		(start 53.289454 -279.713944)
		(end 53.096414 -279.906984)
		(width 0.18288)
		(layer "In11.Cu")
		(net "M_D_CPU1_SA_DQ<30>")
	)
	(segment
		(start 52.100226 -280.370026)
		(end 51.922934 -280.192734)
		(width 0.18288)
		(layer "In11.Cu")
		(net "M_D_CPU1_SA_DQ<30>")
	)
	(segment
		(start 57.753504 -279.048718)
		(end 57.560464 -278.855678)
		(width 0.18288)
		(layer "In11.Cu")
		(net "M_D_CPU1_SA_DQ<30>")
	)
	(segment
		(start 41.577514 -280.116026)
		(end 40.416226 -280.116026)
		(width 0.18288)
		(layer "In11.Cu")
		(net "M_D_CPU1_SA_DQ<30>")
	)
	(segment
		(start 94.176596 -266.45235)
		(end 94.161864 -266.443714)
		(width 0.088646)
		(layer "In11.Cu")
		(net "M_D_CPU1_SA_DQ<30>")
	)
	(segment
		(start 62.018418 -278.76881)
		(end 61.432948 -278.18334)
		(width 0.18288)
		(layer "In11.Cu")
		(net "M_D_CPU1_SA_DQ<30>")
	)
	(segment
		(start 27.00147 -281.065986)
		(end 26.80843 -281.259026)
		(width 0.18288)
		(layer "In11.Cu")
		(net "M_D_CPU1_SA_DQ<30>")
	)
	(segment
		(start 41.815004 -280.75509)
		(end 41.815004 -280.353516)
		(width 0.18288)
		(layer "In11.Cu")
		(net "M_D_CPU1_SA_DQ<30>")
	)
	(segment
		(start 51.138836 -280.192734)
		(end 51.137058 -280.190956)
		(width 0.18288)
		(layer "In11.Cu")
		(net "M_D_CPU1_SA_DQ<30>")
	)
	(segment
		(start 38.543484 -279.736042)
		(end 38.228524 -279.736042)
		(width 0.18288)
		(layer "In11.Cu")
		(net "M_D_CPU1_SA_DQ<30>")
	)
	(segment
		(start 99.815396 -266.45235)
		(end 99.800664 -266.443714)
		(width 0.088646)
		(layer "In11.Cu")
		(net "M_D_CPU1_SA_DQ<30>")
	)
	(segment
		(start 84.778596 -266.45235)
		(end 84.657184 -266.382246)
		(width 0.088646)
		(layer "In11.Cu")
		(net "M_D_CPU1_SA_DQ<30>")
	)
	(segment
		(start 53.797454 -279.906984)
		(end 53.604414 -279.713944)
		(width 0.18288)
		(layer "In11.Cu")
		(net "M_D_CPU1_SA_DQ<30>")
	)
	(segment
		(start 47.720758 -281.042618)
		(end 46.69155 -281.042618)
		(width 0.18288)
		(layer "In11.Cu")
		(net "M_D_CPU1_SA_DQ<30>")
	)
	(segment
		(start 32.706056 -281.042618)
		(end 31.603442 -281.042618)
		(width 0.18288)
		(layer "In11.Cu")
		(net "M_D_CPU1_SA_DQ<30>")
	)
	(segment
		(start 53.990494 -280.370026)
		(end 53.797454 -280.176986)
		(width 0.18288)
		(layer "In11.Cu")
		(net "M_D_CPU1_SA_DQ<30>")
	)
	(segment
		(start 38.736524 -279.929082)
		(end 38.543484 -279.736042)
		(width 0.18288)
		(layer "In11.Cu")
		(net "M_D_CPU1_SA_DQ<30>")
	)
	(segment
		(start 44.428918 -280.929334)
		(end 44.175426 -281.182826)
		(width 0.18288)
		(layer "In11.Cu")
		(net "M_D_CPU1_SA_DQ<30>")
	)
	(segment
		(start 30.37205 -281.372564)
		(end 30.178756 -281.17927)
		(width 0.18288)
		(layer "In11.Cu")
		(net "M_D_CPU1_SA_DQ<30>")
	)
	(segment
		(start 40.416226 -280.116026)
		(end 40.16375 -280.368502)
		(width 0.18288)
		(layer "In11.Cu")
		(net "M_D_CPU1_SA_DQ<30>")
	)
	(segment
		(start 84.657184 -266.382246)
		(end 84.651596 -266.376658)
		(width 0.088646)
		(layer "In11.Cu")
		(net "M_D_CPU1_SA_DQ<30>")
	)
	(segment
		(start 83.256882 -267.660628)
		(end 83.168236 -267.749274)
		(width 0.088646)
		(layer "In11.Cu")
		(net "M_D_CPU1_SA_DQ<30>")
	)
	(segment
		(start 57.753504 -279.211786)
		(end 57.753504 -279.048718)
		(width 0.18288)
		(layer "In11.Cu")
		(net "M_D_CPU1_SA_DQ<30>")
	)
	(segment
		(start 30.178756 -281.17927)
		(end 30.178756 -281.012646)
		(width 0.18288)
		(layer "In11.Cu")
		(net "M_D_CPU1_SA_DQ<30>")
	)
	(segment
		(start 51.137058 -280.190956)
		(end 50.995072 -280.190956)
		(width 0.18288)
		(layer "In11.Cu")
		(net "M_D_CPU1_SA_DQ<30>")
	)
	(segment
		(start 63.495174 -277.932134)
		(end 62.658498 -278.76881)
		(width 0.18288)
		(layer "In11.Cu")
		(net "M_D_CPU1_SA_DQ<30>")
	)
	(segment
		(start 32.909256 -281.245818)
		(end 32.706056 -281.042618)
		(width 0.18288)
		(layer "In11.Cu")
		(net "M_D_CPU1_SA_DQ<30>")
	)
	(segment
		(start 25.51049 -281.259026)
		(end 24.70531 -282.064206)
		(width 0.18288)
		(layer "In11.Cu")
		(net "M_D_CPU1_SA_DQ<30>")
	)
	(segment
		(start 57.052464 -279.211786)
		(end 56.859424 -279.404826)
		(width 0.18288)
		(layer "In11.Cu")
		(net "M_D_CPU1_SA_DQ<30>")
	)
	(segment
		(start 84.651596 -266.376658)
		(end 84.101686 -266.376658)
		(width 0.088646)
		(layer "In11.Cu")
		(net "M_D_CPU1_SA_DQ<30>")
	)
	(segment
		(start 47.802038 -281.123898)
		(end 47.720758 -281.042618)
		(width 0.18288)
		(layer "In11.Cu")
		(net "M_D_CPU1_SA_DQ<30>")
	)
	(segment
		(start 55.859426 -279.404826)
		(end 54.894226 -280.370026)
		(width 0.18288)
		(layer "In11.Cu")
		(net "M_D_CPU1_SA_DQ<30>")
	)
	(segment
		(start 56.859424 -279.404826)
		(end 55.859426 -279.404826)
		(width 0.18288)
		(layer "In11.Cu")
		(net "M_D_CPU1_SA_DQ<30>")
	)
	(segment
		(start 57.245504 -278.855678)
		(end 57.052464 -279.048718)
		(width 0.18288)
		(layer "In11.Cu")
		(net "M_D_CPU1_SA_DQ<30>")
	)
	(segment
		(start 21.486622 -282.064206)
		(end 20.889214 -281.466798)
		(width 0.18288)
		(layer "In11.Cu")
		(net "M_D_CPU1_SA_DQ<30>")
	)
	(segment
		(start 36.698682 -280.368502)
		(end 36.52266 -280.19248)
		(width 0.18288)
		(layer "In11.Cu")
		(net "M_D_CPU1_SA_DQ<30>")
	)
	(segment
		(start 45.604938 -281.336242)
		(end 45.19803 -280.929334)
		(width 0.18288)
		(layer "In11.Cu")
		(net "M_D_CPU1_SA_DQ<30>")
	)
	(segment
		(start 96.995996 -266.45235)
		(end 96.981264 -266.443714)
		(width 0.088646)
		(layer "In11.Cu")
		(net "M_D_CPU1_SA_DQ<30>")
	)
	(segment
		(start 27.00147 -280.86558)
		(end 27.00147 -281.065986)
		(width 0.18288)
		(layer "In11.Cu")
		(net "M_D_CPU1_SA_DQ<30>")
	)
	(segment
		(start 92.296996 -266.45235)
		(end 92.282264 -266.443714)
		(width 0.088646)
		(layer "In11.Cu")
		(net "M_D_CPU1_SA_DQ<30>")
	)
	(segment
		(start 44.175426 -281.182826)
		(end 42.24274 -281.182826)
		(width 0.18288)
		(layer "In11.Cu")
		(net "M_D_CPU1_SA_DQ<30>")
	)
	(segment
		(start 34.44494 -281.245818)
		(end 32.909256 -281.245818)
		(width 0.18288)
		(layer "In11.Cu")
		(net "M_D_CPU1_SA_DQ<30>")
	)
	(segment
		(start 31.41345 -280.852626)
		(end 31.053278 -280.852626)
		(width 0.18288)
		(layer "In11.Cu")
		(net "M_D_CPU1_SA_DQ<30>")
	)
	(segment
		(start 30.178756 -281.012646)
		(end 30.018736 -280.852626)
		(width 0.18288)
		(layer "In11.Cu")
		(net "M_D_CPU1_SA_DQ<30>")
	)
	(segment
		(start 67.665092 -277.277322)
		(end 66.826384 -277.277322)
		(width 0.18288)
		(layer "In11.Cu")
		(net "M_D_CPU1_SA_DQ<30>")
	)
	(segment
		(start 83.606386 -266.871958)
		(end 83.606386 -267.208508)
		(width 0.088646)
		(layer "In11.Cu")
		(net "M_D_CPU1_SA_DQ<30>")
	)
	(segment
		(start 29.164026 -280.852626)
		(end 28.757626 -281.259026)
		(width 0.18288)
		(layer "In11.Cu")
		(net "M_D_CPU1_SA_DQ<30>")
	)
	(segment
		(start 41.815004 -280.353516)
		(end 41.577514 -280.116026)
		(width 0.18288)
		(layer "In11.Cu")
		(net "M_D_CPU1_SA_DQ<30>")
	)
	(segment
		(start 82.963004 -267.749274)
		(end 77.19314 -267.749274)
		(width 0.18288)
		(layer "In11.Cu")
		(net "M_D_CPU1_SA_DQ<30>")
	)
	(segment
		(start 95.116396 -266.45235)
		(end 95.101664 -266.443714)
		(width 0.088646)
		(layer "In11.Cu")
		(net "M_D_CPU1_SA_DQ<30>")
	)
	(segment
		(start 38.228524 -279.736042)
		(end 38.035484 -279.929082)
		(width 0.18288)
		(layer "In11.Cu")
		(net "M_D_CPU1_SA_DQ<30>")
	)
	(segment
		(start 45.19803 -280.929334)
		(end 44.428918 -280.929334)
		(width 0.18288)
		(layer "In11.Cu")
		(net "M_D_CPU1_SA_DQ<30>")
	)
	(segment
		(start 30.893258 -281.012646)
		(end 30.893258 -281.212544)
		(width 0.18288)
		(layer "In11.Cu")
		(net "M_D_CPU1_SA_DQ<30>")
	)
	(segment
		(start 38.035484 -279.929082)
		(end 38.035484 -280.175462)
		(width 0.18288)
		(layer "In11.Cu")
		(net "M_D_CPU1_SA_DQ<30>")
	)
	(segment
		(start 26.80843 -281.259026)
		(end 25.51049 -281.259026)
		(width 0.18288)
		(layer "In11.Cu")
		(net "M_D_CPU1_SA_DQ<30>")
	)
	(segment
		(start 99.907598 -266.506198)
		(end 99.815396 -266.45235)
		(width 0.088646)
		(layer "In11.Cu")
		(net "M_D_CPU1_SA_DQ<30>")
	)
	(segment
		(start 57.560464 -278.855678)
		(end 57.245504 -278.855678)
		(width 0.18288)
		(layer "In11.Cu")
		(net "M_D_CPU1_SA_DQ<30>")
	)
	(segment
		(start 31.603442 -281.042618)
		(end 31.41345 -280.852626)
		(width 0.18288)
		(layer "In11.Cu")
		(net "M_D_CPU1_SA_DQ<30>")
	)
	(segment
		(start 57.946544 -279.404826)
		(end 57.753504 -279.211786)
		(width 0.18288)
		(layer "In11.Cu")
		(net "M_D_CPU1_SA_DQ<30>")
	)
	(segment
		(start 46.28515 -280.929334)
		(end 45.878242 -281.336242)
		(width 0.18288)
		(layer "In11.Cu")
		(net "M_D_CPU1_SA_DQ<30>")
	)
	(segment
		(start 59.440826 -279.150826)
		(end 59.186826 -279.404826)
		(width 0.18288)
		(layer "In11.Cu")
		(net "M_D_CPU1_SA_DQ<30>")
	)
	(segment
		(start 35.498278 -280.19248)
		(end 34.44494 -281.245818)
		(width 0.18288)
		(layer "In11.Cu")
		(net "M_D_CPU1_SA_DQ<30>")
	)
	(segment
		(start 45.878242 -281.336242)
		(end 45.604938 -281.336242)
		(width 0.18288)
		(layer "In11.Cu")
		(net "M_D_CPU1_SA_DQ<30>")
	)
	(segment
		(start 38.929564 -280.368502)
		(end 38.736524 -280.175462)
		(width 0.18288)
		(layer "In11.Cu")
		(net "M_D_CPU1_SA_DQ<30>")
	)
	(segment
		(start 38.035484 -280.175462)
		(end 37.842444 -280.368502)
		(width 0.18288)
		(layer "In11.Cu")
		(net "M_D_CPU1_SA_DQ<30>")
	)
	(arc
		(start 90.417396 -266.45235)
		(mid 90.134694 -266.376574)
		(end 89.851992 -266.45235)
		(width 0.088646)
		(layer "In11.Cu")
		(net "M_D_CPU1_SA_DQ<30>")
	)
	(arc
		(start 89.851992 -266.45235)
		(mid 89.664794 -266.502527)
		(end 89.477596 -266.45235)
		(width 0.088646)
		(layer "In11.Cu")
		(net "M_D_CPU1_SA_DQ<30>")
	)
	(arc
		(start 85.718396 -266.45235)
		(mid 85.435694 -266.376574)
		(end 85.152992 -266.45235)
		(width 0.088646)
		(layer "In11.Cu")
		(net "M_D_CPU1_SA_DQ<30>")
	)
	(arc
		(start 98.824796 -266.444222)
		(mid 98.566448 -266.381444)
		(end 98.310192 -266.45235)
		(width 0.088646)
		(layer "In11.Cu")
		(net "M_D_CPU1_SA_DQ<30>")
	)
	(arc
		(start 90.791792 -266.45235)
		(mid 90.604594 -266.502527)
		(end 90.417396 -266.45235)
		(width 0.088646)
		(layer "In11.Cu")
		(net "M_D_CPU1_SA_DQ<30>")
	)
	(arc
		(start 100.472748 -266.941808)
		(mid 100.204205 -266.705798)
		(end 99.907598 -266.506198)
		(width 0.088646)
		(layer "In11.Cu")
		(net "M_D_CPU1_SA_DQ<30>")
	)
	(arc
		(start 95.490792 -266.45235)
		(mid 95.303594 -266.502527)
		(end 95.116396 -266.45235)
		(width 0.088646)
		(layer "In11.Cu")
		(net "M_D_CPU1_SA_DQ<30>")
	)
	(arc
		(start 95.101664 -266.443714)
		(mid 94.825189 -266.376394)
		(end 94.550992 -266.45235)
		(width 0.088646)
		(layer "In11.Cu")
		(net "M_D_CPU1_SA_DQ<30>")
	)
	(arc
		(start 86.092792 -266.45235)
		(mid 85.905594 -266.502527)
		(end 85.718396 -266.45235)
		(width 0.088646)
		(layer "In11.Cu")
		(net "M_D_CPU1_SA_DQ<30>")
	)
	(arc
		(start 88.912192 -266.45235)
		(mid 88.724994 -266.502527)
		(end 88.537796 -266.45235)
		(width 0.088646)
		(layer "In11.Cu")
		(net "M_D_CPU1_SA_DQ<30>")
	)
	(arc
		(start 96.981264 -266.443714)
		(mid 96.704789 -266.376394)
		(end 96.430592 -266.45235)
		(width 0.088646)
		(layer "In11.Cu")
		(net "M_D_CPU1_SA_DQ<30>")
	)
	(arc
		(start 88.537796 -266.45235)
		(mid 88.255094 -266.376574)
		(end 87.972392 -266.45235)
		(width 0.088646)
		(layer "In11.Cu")
		(net "M_D_CPU1_SA_DQ<30>")
	)
	(arc
		(start 98.310192 -266.45235)
		(mid 98.122994 -266.502527)
		(end 97.935796 -266.45235)
		(width 0.088646)
		(layer "In11.Cu")
		(net "M_D_CPU1_SA_DQ<30>")
	)
	(arc
		(start 97.935796 -266.45235)
		(mid 97.653094 -266.376574)
		(end 97.370392 -266.45235)
		(width 0.088646)
		(layer "In11.Cu")
		(net "M_D_CPU1_SA_DQ<30>")
	)
	(arc
		(start 96.430592 -266.45235)
		(mid 96.243394 -266.502527)
		(end 96.056196 -266.45235)
		(width 0.088646)
		(layer "In11.Cu")
		(net "M_D_CPU1_SA_DQ<30>")
	)
	(arc
		(start 87.972392 -266.45235)
		(mid 87.785194 -266.502527)
		(end 87.597996 -266.45235)
		(width 0.088646)
		(layer "In11.Cu")
		(net "M_D_CPU1_SA_DQ<30>")
	)
	(arc
		(start 86.658196 -266.45235)
		(mid 86.375494 -266.376574)
		(end 86.092792 -266.45235)
		(width 0.088646)
		(layer "In11.Cu")
		(net "M_D_CPU1_SA_DQ<30>")
	)
	(arc
		(start 89.477596 -266.45235)
		(mid 89.194894 -266.376574)
		(end 88.912192 -266.45235)
		(width 0.088646)
		(layer "In11.Cu")
		(net "M_D_CPU1_SA_DQ<30>")
	)
	(arc
		(start 97.370392 -266.45235)
		(mid 97.183194 -266.502527)
		(end 96.995996 -266.45235)
		(width 0.088646)
		(layer "In11.Cu")
		(net "M_D_CPU1_SA_DQ<30>")
	)
	(arc
		(start 99.800664 -266.443714)
		(mid 99.524189 -266.376394)
		(end 99.249992 -266.45235)
		(width 0.088646)
		(layer "In11.Cu")
		(net "M_D_CPU1_SA_DQ<30>")
	)
	(arc
		(start 87.032592 -266.45235)
		(mid 86.845394 -266.502527)
		(end 86.658196 -266.45235)
		(width 0.088646)
		(layer "In11.Cu")
		(net "M_D_CPU1_SA_DQ<30>")
	)
	(arc
		(start 92.671392 -266.45235)
		(mid 92.484194 -266.502527)
		(end 92.296996 -266.45235)
		(width 0.088646)
		(layer "In11.Cu")
		(net "M_D_CPU1_SA_DQ<30>")
	)
	(arc
		(start 94.550992 -266.45235)
		(mid 94.363794 -266.502527)
		(end 94.176596 -266.45235)
		(width 0.088646)
		(layer "In11.Cu")
		(net "M_D_CPU1_SA_DQ<30>")
	)
	(arc
		(start 96.041464 -266.443714)
		(mid 95.764989 -266.376394)
		(end 95.490792 -266.45235)
		(width 0.088646)
		(layer "In11.Cu")
		(net "M_D_CPU1_SA_DQ<30>")
	)
	(arc
		(start 92.282264 -266.443714)
		(mid 92.005789 -266.376394)
		(end 91.731592 -266.45235)
		(width 0.088646)
		(layer "In11.Cu")
		(net "M_D_CPU1_SA_DQ<30>")
	)
	(arc
		(start 99.195128 -266.4841)
		(mid 99.046538 -266.523923)
		(end 98.897948 -266.4841)
		(width 0.088646)
		(layer "In11.Cu")
		(net "M_D_CPU1_SA_DQ<30>")
	)
	(arc
		(start 91.357196 -266.45235)
		(mid 91.074494 -266.376574)
		(end 90.791792 -266.45235)
		(width 0.088646)
		(layer "In11.Cu")
		(net "M_D_CPU1_SA_DQ<30>")
	)
	(arc
		(start 87.597996 -266.45235)
		(mid 87.315294 -266.376574)
		(end 87.032592 -266.45235)
		(width 0.088646)
		(layer "In11.Cu")
		(net "M_D_CPU1_SA_DQ<30>")
	)
	(arc
		(start 93.222064 -266.443714)
		(mid 92.945589 -266.376394)
		(end 92.671392 -266.45235)
		(width 0.088646)
		(layer "In11.Cu")
		(net "M_D_CPU1_SA_DQ<30>")
	)
	(arc
		(start 93.611192 -266.45235)
		(mid 93.423994 -266.502527)
		(end 93.236796 -266.45235)
		(width 0.088646)
		(layer "In11.Cu")
		(net "M_D_CPU1_SA_DQ<30>")
	)
	(arc
		(start 91.731592 -266.45235)
		(mid 91.544394 -266.502527)
		(end 91.357196 -266.45235)
		(width 0.088646)
		(layer "In11.Cu")
		(net "M_D_CPU1_SA_DQ<30>")
	)
	(arc
		(start 94.161864 -266.443714)
		(mid 93.885389 -266.376394)
		(end 93.611192 -266.45235)
		(width 0.088646)
		(layer "In11.Cu")
		(net "M_D_CPU1_SA_DQ<30>")
	)
	(arc
		(start 85.152992 -266.45235)
		(mid 84.965794 -266.502527)
		(end 84.778596 -266.45235)
		(width 0.088646)
		(layer "In11.Cu")
		(net "M_D_CPU1_SA_DQ<30>")
	)
	(segment
		(start 13.387578 -315.46673)
		(end 13.82268 -315.031628)
		(width 0.20066)
		(layer "F.Cu")
		(net "M_D_CPU1_SA_DQ<2>")
	)
	(segment
		(start 17.518126 -315.041788)
		(end 17.66189 -315.185552)
		(width 0.20066)
		(layer "F.Cu")
		(net "M_D_CPU1_SA_DQ<2>")
	)
	(segment
		(start 16.885158 -315.041788)
		(end 17.518126 -315.041788)
		(width 0.20066)
		(layer "F.Cu")
		(net "M_D_CPU1_SA_DQ<2>")
	)
	(segment
		(start 13.82268 -315.031628)
		(end 14.560042 -315.031628)
		(width 0.20066)
		(layer "F.Cu")
		(net "M_D_CPU1_SA_DQ<2>")
	)
	(segment
		(start 14.560042 -315.031628)
		(end 14.570202 -315.041788)
		(width 0.101854)
		(layer "F.Cu")
		(net "M_D_CPU1_SA_DQ<2>")
	)
	(segment
		(start 17.829276 -315.678566)
		(end 18.257774 -315.678566)
		(width 0.20066)
		(layer "F.Cu")
		(net "M_D_CPU1_SA_DQ<2>")
	)
	(segment
		(start 12.240514 -315.46673)
		(end 13.387578 -315.46673)
		(width 0.20066)
		(layer "F.Cu")
		(net "M_D_CPU1_SA_DQ<2>")
	)
	(segment
		(start 14.825218 -315.041788)
		(end 16.885158 -315.041788)
		(width 0.1016)
		(layer "F.Cu")
		(net "M_D_CPU1_SA_DQ<2>")
	)
	(segment
		(start 20.889214 -315.46673)
		(end 19.784314 -315.46673)
		(width 0.20066)
		(layer "F.Cu")
		(net "M_D_CPU1_SA_DQ<2>")
	)
	(segment
		(start 14.570202 -315.041788)
		(end 14.825218 -315.041788)
		(width 0.101854)
		(layer "F.Cu")
		(net "M_D_CPU1_SA_DQ<2>")
	)
	(segment
		(start 18.46961 -315.46673)
		(end 19.784314 -315.46673)
		(width 0.20066)
		(layer "F.Cu")
		(net "M_D_CPU1_SA_DQ<2>")
	)
	(segment
		(start 18.257774 -315.678566)
		(end 18.46961 -315.46673)
		(width 0.20066)
		(layer "F.Cu")
		(net "M_D_CPU1_SA_DQ<2>")
	)
	(segment
		(start 96.713294 -276.708362)
		(end 96.713548 -276.708616)
		(width 0.20066)
		(layer "F.Cu")
		(net "M_D_CPU1_SA_DQ<2>")
	)
	(segment
		(start 17.66189 -315.51118)
		(end 17.829276 -315.678566)
		(width 0.20066)
		(layer "F.Cu")
		(net "M_D_CPU1_SA_DQ<2>")
	)
	(segment
		(start 17.66189 -315.185552)
		(end 17.66189 -315.51118)
		(width 0.20066)
		(layer "F.Cu")
		(net "M_D_CPU1_SA_DQ<2>")
	)
	(segment
		(start 96.713294 -276.172676)
		(end 96.713294 -276.708362)
		(width 0.20066)
		(layer "F.Cu")
		(net "M_D_CPU1_SA_DQ<2>")
	)
	(segment
		(start 46.339252 -313.34202)
		(end 46.179232 -313.182)
		(width 0.18288)
		(layer "In6.Cu")
		(net "M_D_CPU1_SA_DQ<2>")
	)
	(segment
		(start 59.676284 -304.90922)
		(end 58.801762 -305.783742)
		(width 0.18288)
		(layer "In6.Cu")
		(net "M_D_CPU1_SA_DQ<2>")
	)
	(segment
		(start 45.325792 -313.34202)
		(end 44.536868 -313.34202)
		(width 0.18288)
		(layer "In6.Cu")
		(net "M_D_CPU1_SA_DQ<2>")
	)
	(segment
		(start 85.340444 -282.438094)
		(end 84.902548 -282.87599)
		(width 0.088646)
		(layer "In6.Cu")
		(net "M_D_CPU1_SA_DQ<2>")
	)
	(segment
		(start 83.946492 -282.87599)
		(end 69.80428 -297.018202)
		(width 0.18288)
		(layer "In6.Cu")
		(net "M_D_CPU1_SA_DQ<2>")
	)
	(segment
		(start 60.885578 -303.991772)
		(end 59.96813 -304.90922)
		(width 0.18288)
		(layer "In6.Cu")
		(net "M_D_CPU1_SA_DQ<2>")
	)
	(segment
		(start 96.062292 -276.222714)
		(end 96.056196 -276.219158)
		(width 0.088646)
		(layer "In6.Cu")
		(net "M_D_CPU1_SA_DQ<2>")
	)
	(segment
		(start 26.879804 -314.891928)
		(end 26.879804 -315.503814)
		(width 0.18288)
		(layer "In6.Cu")
		(net "M_D_CPU1_SA_DQ<2>")
	)
	(segment
		(start 23.11146 -315.539628)
		(end 22.92858 -315.722508)
		(width 0.18288)
		(layer "In6.Cu")
		(net "M_D_CPU1_SA_DQ<2>")
	)
	(segment
		(start 95.208598 -276.693122)
		(end 95.208598 -276.708616)
		(width 0.088646)
		(layer "In6.Cu")
		(net "M_D_CPU1_SA_DQ<2>")
	)
	(segment
		(start 46.019212 -312.735722)
		(end 45.645832 -312.735722)
		(width 0.18288)
		(layer "In6.Cu")
		(net "M_D_CPU1_SA_DQ<2>")
	)
	(segment
		(start 26.879804 -315.503814)
		(end 26.696924 -315.686694)
		(width 0.18288)
		(layer "In6.Cu")
		(net "M_D_CPU1_SA_DQ<2>")
	)
	(segment
		(start 34.868612 -317.646812)
		(end 33.963356 -316.741556)
		(width 0.18288)
		(layer "In6.Cu")
		(net "M_D_CPU1_SA_DQ<2>")
	)
	(segment
		(start 46.179232 -313.182)
		(end 46.179232 -312.895742)
		(width 0.18288)
		(layer "In6.Cu")
		(net "M_D_CPU1_SA_DQ<2>")
	)
	(segment
		(start 21.486368 -316.063884)
		(end 20.889214 -315.46673)
		(width 0.18288)
		(layer "In6.Cu")
		(net "M_D_CPU1_SA_DQ<2>")
	)
	(segment
		(start 43.145456 -313.990228)
		(end 42.000678 -315.135006)
		(width 0.18288)
		(layer "In6.Cu")
		(net "M_D_CPU1_SA_DQ<2>")
	)
	(segment
		(start 90.039444 -279.140412)
		(end 90.039444 -279.150318)
		(width 0.088646)
		(layer "In6.Cu")
		(net "M_D_CPU1_SA_DQ<2>")
	)
	(segment
		(start 40.584628 -315.135006)
		(end 38.072822 -317.646812)
		(width 0.18288)
		(layer "In6.Cu")
		(net "M_D_CPU1_SA_DQ<2>")
	)
	(segment
		(start 54.055518 -308.47792)
		(end 52.591716 -309.941722)
		(width 0.18288)
		(layer "In6.Cu")
		(net "M_D_CPU1_SA_DQ<2>")
	)
	(segment
		(start 48.660812 -312.176668)
		(end 48.434752 -312.176668)
		(width 0.18288)
		(layer "In6.Cu")
		(net "M_D_CPU1_SA_DQ<2>")
	)
	(segment
		(start 42.000678 -315.135006)
		(end 40.584628 -315.135006)
		(width 0.18288)
		(layer "In6.Cu")
		(net "M_D_CPU1_SA_DQ<2>")
	)
	(segment
		(start 47.2694 -313.34202)
		(end 46.339252 -313.34202)
		(width 0.18288)
		(layer "In6.Cu")
		(net "M_D_CPU1_SA_DQ<2>")
	)
	(segment
		(start 49.073816 -312.363612)
		(end 48.847756 -312.363612)
		(width 0.18288)
		(layer "In6.Cu")
		(net "M_D_CPU1_SA_DQ<2>")
	)
	(segment
		(start 27.387804 -314.709048)
		(end 27.062684 -314.709048)
		(width 0.18288)
		(layer "In6.Cu")
		(net "M_D_CPU1_SA_DQ<2>")
	)
	(segment
		(start 22.7457 -316.063884)
		(end 21.486368 -316.063884)
		(width 0.18288)
		(layer "In6.Cu")
		(net "M_D_CPU1_SA_DQ<2>")
	)
	(segment
		(start 45.485812 -312.895742)
		(end 45.485812 -313.182)
		(width 0.18288)
		(layer "In6.Cu")
		(net "M_D_CPU1_SA_DQ<2>")
	)
	(segment
		(start 90.509344 -278.322278)
		(end 90.509344 -278.336502)
		(width 0.088646)
		(layer "In6.Cu")
		(net "M_D_CPU1_SA_DQ<2>")
	)
	(segment
		(start 84.109814 -282.87599)
		(end 83.946492 -282.87599)
		(width 0.18288)
		(layer "In6.Cu")
		(net "M_D_CPU1_SA_DQ<2>")
	)
	(segment
		(start 85.810344 -281.582114)
		(end 85.810344 -281.59202)
		(width 0.088646)
		(layer "In6.Cu")
		(net "M_D_CPU1_SA_DQ<2>")
	)
	(segment
		(start 90.330782 -278.65578)
		(end 90.321892 -278.66086)
		(width 0.088646)
		(layer "In6.Cu")
		(net "M_D_CPU1_SA_DQ<2>")
	)
	(segment
		(start 86.571582 -280.283412)
		(end 86.562692 -280.288492)
		(width 0.088646)
		(layer "In6.Cu")
		(net "M_D_CPU1_SA_DQ<2>")
	)
	(segment
		(start 86.280244 -280.759662)
		(end 86.280244 -280.778204)
		(width 0.088646)
		(layer "In6.Cu")
		(net "M_D_CPU1_SA_DQ<2>")
	)
	(segment
		(start 27.570684 -314.891928)
		(end 27.387804 -314.709048)
		(width 0.18288)
		(layer "In6.Cu")
		(net "M_D_CPU1_SA_DQ<2>")
	)
	(segment
		(start 52.591716 -309.941722)
		(end 50.733706 -309.941722)
		(width 0.18288)
		(layer "In6.Cu")
		(net "M_D_CPU1_SA_DQ<2>")
	)
	(segment
		(start 67.197478 -302.494442)
		(end 66.550032 -303.141888)
		(width 0.18288)
		(layer "In6.Cu")
		(net "M_D_CPU1_SA_DQ<2>")
	)
	(segment
		(start 25.283922 -315.686694)
		(end 24.906732 -316.063884)
		(width 0.18288)
		(layer "In6.Cu")
		(net "M_D_CPU1_SA_DQ<2>")
	)
	(segment
		(start 56.74487 -307.363368)
		(end 54.055518 -308.47792)
		(width 0.18288)
		(layer "In6.Cu")
		(net "M_D_CPU1_SA_DQ<2>")
	)
	(segment
		(start 49.18329 -311.718198)
		(end 49.33823 -311.873138)
		(width 0.18288)
		(layer "In6.Cu")
		(net "M_D_CPU1_SA_DQ<2>")
	)
	(segment
		(start 28.710382 -315.686694)
		(end 27.753564 -315.686694)
		(width 0.18288)
		(layer "In6.Cu")
		(net "M_D_CPU1_SA_DQ<2>")
	)
	(segment
		(start 49.18329 -311.492138)
		(end 49.18329 -311.718198)
		(width 0.18288)
		(layer "In6.Cu")
		(net "M_D_CPU1_SA_DQ<2>")
	)
	(segment
		(start 58.324496 -305.783742)
		(end 56.74487 -307.363368)
		(width 0.18288)
		(layer "In6.Cu")
		(net "M_D_CPU1_SA_DQ<2>")
	)
	(segment
		(start 85.631782 -281.911298)
		(end 85.622892 -281.916378)
		(width 0.088646)
		(layer "In6.Cu")
		(net "M_D_CPU1_SA_DQ<2>")
	)
	(segment
		(start 45.645832 -312.735722)
		(end 45.485812 -312.895742)
		(width 0.18288)
		(layer "In6.Cu")
		(net "M_D_CPU1_SA_DQ<2>")
	)
	(segment
		(start 96.713548 -276.708616)
		(end 96.400874 -276.708616)
		(width 0.088646)
		(layer "In6.Cu")
		(net "M_D_CPU1_SA_DQ<2>")
	)
	(segment
		(start 64.667638 -303.991772)
		(end 60.885578 -303.991772)
		(width 0.18288)
		(layer "In6.Cu")
		(net "M_D_CPU1_SA_DQ<2>")
	)
	(segment
		(start 96.400874 -276.708616)
		(end 96.335088 -276.64283)
		(width 0.088646)
		(layer "In6.Cu")
		(net "M_D_CPU1_SA_DQ<2>")
	)
	(segment
		(start 58.801762 -305.783742)
		(end 58.324496 -305.783742)
		(width 0.18288)
		(layer "In6.Cu")
		(net "M_D_CPU1_SA_DQ<2>")
	)
	(segment
		(start 69.80428 -297.018202)
		(end 69.80428 -299.122592)
		(width 0.18288)
		(layer "In6.Cu")
		(net "M_D_CPU1_SA_DQ<2>")
	)
	(segment
		(start 96.056196 -276.219158)
		(end 96.041464 -276.210522)
		(width 0.088646)
		(layer "In6.Cu")
		(net "M_D_CPU1_SA_DQ<2>")
	)
	(segment
		(start 86.101682 -281.097482)
		(end 86.092792 -281.102562)
		(width 0.088646)
		(layer "In6.Cu")
		(net "M_D_CPU1_SA_DQ<2>")
	)
	(segment
		(start 59.96813 -304.90922)
		(end 59.676284 -304.90922)
		(width 0.18288)
		(layer "In6.Cu")
		(net "M_D_CPU1_SA_DQ<2>")
	)
	(segment
		(start 91.272106 -277.026878)
		(end 91.261692 -277.032974)
		(width 0.088646)
		(layer "In6.Cu")
		(net "M_D_CPU1_SA_DQ<2>")
	)
	(segment
		(start 33.963356 -316.741556)
		(end 29.765244 -316.741556)
		(width 0.18288)
		(layer "In6.Cu")
		(net "M_D_CPU1_SA_DQ<2>")
	)
	(segment
		(start 90.979244 -277.512526)
		(end 90.979244 -277.531068)
		(width 0.088646)
		(layer "In6.Cu")
		(net "M_D_CPU1_SA_DQ<2>")
	)
	(segment
		(start 85.34019 -282.396438)
		(end 85.340444 -282.406344)
		(width 0.088646)
		(layer "In6.Cu")
		(net "M_D_CPU1_SA_DQ<2>")
	)
	(segment
		(start 92.216478 -277.024338)
		(end 92.201746 -277.032974)
		(width 0.088646)
		(layer "In6.Cu")
		(net "M_D_CPU1_SA_DQ<2>")
	)
	(segment
		(start 27.062684 -314.709048)
		(end 26.879804 -314.891928)
		(width 0.18288)
		(layer "In6.Cu")
		(net "M_D_CPU1_SA_DQ<2>")
	)
	(segment
		(start 65.517522 -303.141888)
		(end 64.667638 -303.991772)
		(width 0.18288)
		(layer "In6.Cu")
		(net "M_D_CPU1_SA_DQ<2>")
	)
	(segment
		(start 27.753564 -315.686694)
		(end 27.570684 -315.503814)
		(width 0.18288)
		(layer "In6.Cu")
		(net "M_D_CPU1_SA_DQ<2>")
	)
	(segment
		(start 22.92858 -315.722508)
		(end 22.92858 -315.881004)
		(width 0.18288)
		(layer "In6.Cu")
		(net "M_D_CPU1_SA_DQ<2>")
	)
	(segment
		(start 23.61946 -315.881004)
		(end 23.61946 -315.722508)
		(width 0.18288)
		(layer "In6.Cu")
		(net "M_D_CPU1_SA_DQ<2>")
	)
	(segment
		(start 43.88866 -313.990228)
		(end 43.145456 -313.990228)
		(width 0.18288)
		(layer "In6.Cu")
		(net "M_D_CPU1_SA_DQ<2>")
	)
	(segment
		(start 94.096078 -277.024338)
		(end 94.081346 -277.032974)
		(width 0.088646)
		(layer "In6.Cu")
		(net "M_D_CPU1_SA_DQ<2>")
	)
	(segment
		(start 23.80234 -316.063884)
		(end 23.61946 -315.881004)
		(width 0.18288)
		(layer "In6.Cu")
		(net "M_D_CPU1_SA_DQ<2>")
	)
	(segment
		(start 46.179232 -312.895742)
		(end 46.019212 -312.735722)
		(width 0.18288)
		(layer "In6.Cu")
		(net "M_D_CPU1_SA_DQ<2>")
	)
	(segment
		(start 86.750144 -279.954228)
		(end 86.750144 -279.964134)
		(width 0.088646)
		(layer "In6.Cu")
		(net "M_D_CPU1_SA_DQ<2>")
	)
	(segment
		(start 89.860882 -279.469596)
		(end 89.851992 -279.474676)
		(width 0.088646)
		(layer "In6.Cu")
		(net "M_D_CPU1_SA_DQ<2>")
	)
	(segment
		(start 27.570684 -315.503814)
		(end 27.570684 -314.891928)
		(width 0.18288)
		(layer "In6.Cu")
		(net "M_D_CPU1_SA_DQ<2>")
	)
	(segment
		(start 22.92858 -315.881004)
		(end 22.7457 -316.063884)
		(width 0.18288)
		(layer "In6.Cu")
		(net "M_D_CPU1_SA_DQ<2>")
	)
	(segment
		(start 66.550032 -303.141888)
		(end 65.517522 -303.141888)
		(width 0.18288)
		(layer "In6.Cu")
		(net "M_D_CPU1_SA_DQ<2>")
	)
	(segment
		(start 49.33823 -312.099198)
		(end 49.073816 -312.363612)
		(width 0.18288)
		(layer "In6.Cu")
		(net "M_D_CPU1_SA_DQ<2>")
	)
	(segment
		(start 93.156278 -277.024338)
		(end 93.141546 -277.032974)
		(width 0.088646)
		(layer "In6.Cu")
		(net "M_D_CPU1_SA_DQ<2>")
	)
	(segment
		(start 23.43658 -315.539628)
		(end 23.11146 -315.539628)
		(width 0.18288)
		(layer "In6.Cu")
		(net "M_D_CPU1_SA_DQ<2>")
	)
	(segment
		(start 26.696924 -315.686694)
		(end 25.283922 -315.686694)
		(width 0.18288)
		(layer "In6.Cu")
		(net "M_D_CPU1_SA_DQ<2>")
	)
	(segment
		(start 24.906732 -316.063884)
		(end 23.80234 -316.063884)
		(width 0.18288)
		(layer "In6.Cu")
		(net "M_D_CPU1_SA_DQ<2>")
	)
	(segment
		(start 85.340444 -282.406344)
		(end 85.340444 -282.438094)
		(width 0.088646)
		(layer "In6.Cu")
		(net "M_D_CPU1_SA_DQ<2>")
	)
	(segment
		(start 45.485812 -313.182)
		(end 45.325792 -313.34202)
		(width 0.18288)
		(layer "In6.Cu")
		(net "M_D_CPU1_SA_DQ<2>")
	)
	(segment
		(start 38.072822 -317.646812)
		(end 34.868612 -317.646812)
		(width 0.18288)
		(layer "In6.Cu")
		(net "M_D_CPU1_SA_DQ<2>")
	)
	(segment
		(start 48.847756 -312.363612)
		(end 48.660812 -312.176668)
		(width 0.18288)
		(layer "In6.Cu")
		(net "M_D_CPU1_SA_DQ<2>")
	)
	(segment
		(start 44.536868 -313.34202)
		(end 43.88866 -313.990228)
		(width 0.18288)
		(layer "In6.Cu")
		(net "M_D_CPU1_SA_DQ<2>")
	)
	(segment
		(start 49.33823 -311.873138)
		(end 49.33823 -312.099198)
		(width 0.18288)
		(layer "In6.Cu")
		(net "M_D_CPU1_SA_DQ<2>")
	)
	(segment
		(start 67.197478 -301.729394)
		(end 67.197478 -302.494442)
		(width 0.18288)
		(layer "In6.Cu")
		(net "M_D_CPU1_SA_DQ<2>")
	)
	(segment
		(start 50.733706 -309.941722)
		(end 49.18329 -311.492138)
		(width 0.18288)
		(layer "In6.Cu")
		(net "M_D_CPU1_SA_DQ<2>")
	)
	(segment
		(start 84.902548 -282.87599)
		(end 84.109814 -282.87599)
		(width 0.088646)
		(layer "In6.Cu")
		(net "M_D_CPU1_SA_DQ<2>")
	)
	(segment
		(start 29.765244 -316.741556)
		(end 28.710382 -315.686694)
		(width 0.18288)
		(layer "In6.Cu")
		(net "M_D_CPU1_SA_DQ<2>")
	)
	(segment
		(start 48.434752 -312.176668)
		(end 47.2694 -313.34202)
		(width 0.18288)
		(layer "In6.Cu")
		(net "M_D_CPU1_SA_DQ<2>")
	)
	(segment
		(start 23.61946 -315.722508)
		(end 23.43658 -315.539628)
		(width 0.18288)
		(layer "In6.Cu")
		(net "M_D_CPU1_SA_DQ<2>")
	)
	(segment
		(start 95.030036 -277.027894)
		(end 95.021146 -277.032974)
		(width 0.088646)
		(layer "In6.Cu")
		(net "M_D_CPU1_SA_DQ<2>")
	)
	(segment
		(start 69.80428 -299.122592)
		(end 67.197478 -301.729394)
		(width 0.18288)
		(layer "In6.Cu")
		(net "M_D_CPU1_SA_DQ<2>")
	)
	(arc
		(start 91.82735 -277.032974)
		(mid 91.550537 -276.957104)
		(end 91.272106 -277.026878)
		(width 0.088646)
		(layer "In6.Cu")
		(net "M_D_CPU1_SA_DQ<2>")
	)
	(arc
		(start 90.321892 -278.66086)
		(mid 90.117557 -278.863465)
		(end 90.039444 -279.140412)
		(width 0.088646)
		(layer "In6.Cu")
		(net "M_D_CPU1_SA_DQ<2>")
	)
	(arc
		(start 92.76715 -277.032974)
		(mid 92.492951 -276.957139)
		(end 92.216478 -277.024338)
		(width 0.088646)
		(layer "In6.Cu")
		(net "M_D_CPU1_SA_DQ<2>")
	)
	(arc
		(start 95.208598 -276.708616)
		(mid 95.160919 -276.891516)
		(end 95.030036 -277.027894)
		(width 0.088646)
		(layer "In6.Cu")
		(net "M_D_CPU1_SA_DQ<2>")
	)
	(arc
		(start 96.041464 -276.210522)
		(mid 95.764989 -276.143202)
		(end 95.490792 -276.219158)
		(width 0.088646)
		(layer "In6.Cu")
		(net "M_D_CPU1_SA_DQ<2>")
	)
	(arc
		(start 86.092792 -281.102562)
		(mid 85.888457 -281.305167)
		(end 85.810344 -281.582114)
		(width 0.088646)
		(layer "In6.Cu")
		(net "M_D_CPU1_SA_DQ<2>")
	)
	(arc
		(start 86.280244 -280.778204)
		(mid 86.232565 -280.961104)
		(end 86.101682 -281.097482)
		(width 0.088646)
		(layer "In6.Cu")
		(net "M_D_CPU1_SA_DQ<2>")
	)
	(arc
		(start 85.622892 -281.916378)
		(mid 85.418247 -282.119149)
		(end 85.34019 -282.396438)
		(width 0.088646)
		(layer "In6.Cu")
		(net "M_D_CPU1_SA_DQ<2>")
	)
	(arc
		(start 95.021146 -277.032974)
		(mid 94.833948 -277.083117)
		(end 94.64675 -277.032974)
		(width 0.088646)
		(layer "In6.Cu")
		(net "M_D_CPU1_SA_DQ<2>")
	)
	(arc
		(start 87.032592 -279.474676)
		(mid 86.828257 -279.677281)
		(end 86.750144 -279.954228)
		(width 0.088646)
		(layer "In6.Cu")
		(net "M_D_CPU1_SA_DQ<2>")
	)
	(arc
		(start 94.081346 -277.032974)
		(mid 93.894148 -277.083117)
		(end 93.70695 -277.032974)
		(width 0.088646)
		(layer "In6.Cu")
		(net "M_D_CPU1_SA_DQ<2>")
	)
	(arc
		(start 88.912192 -279.474676)
		(mid 88.724994 -279.524819)
		(end 88.537796 -279.474676)
		(width 0.088646)
		(layer "In6.Cu")
		(net "M_D_CPU1_SA_DQ<2>")
	)
	(arc
		(start 90.039444 -279.150318)
		(mid 89.991765 -279.333218)
		(end 89.860882 -279.469596)
		(width 0.088646)
		(layer "In6.Cu")
		(net "M_D_CPU1_SA_DQ<2>")
	)
	(arc
		(start 93.70695 -277.032974)
		(mid 93.432751 -276.957139)
		(end 93.156278 -277.024338)
		(width 0.088646)
		(layer "In6.Cu")
		(net "M_D_CPU1_SA_DQ<2>")
	)
	(arc
		(start 89.477596 -279.474676)
		(mid 89.194894 -279.3989)
		(end 88.912192 -279.474676)
		(width 0.088646)
		(layer "In6.Cu")
		(net "M_D_CPU1_SA_DQ<2>")
	)
	(arc
		(start 95.490792 -276.219158)
		(mid 95.287969 -276.419389)
		(end 95.208598 -276.693122)
		(width 0.088646)
		(layer "In6.Cu")
		(net "M_D_CPU1_SA_DQ<2>")
	)
	(arc
		(start 92.201746 -277.032974)
		(mid 92.014548 -277.083117)
		(end 91.82735 -277.032974)
		(width 0.088646)
		(layer "In6.Cu")
		(net "M_D_CPU1_SA_DQ<2>")
	)
	(arc
		(start 87.597996 -279.474676)
		(mid 87.315294 -279.3989)
		(end 87.032592 -279.474676)
		(width 0.088646)
		(layer "In6.Cu")
		(net "M_D_CPU1_SA_DQ<2>")
	)
	(arc
		(start 93.141546 -277.032974)
		(mid 92.954348 -277.083117)
		(end 92.76715 -277.032974)
		(width 0.088646)
		(layer "In6.Cu")
		(net "M_D_CPU1_SA_DQ<2>")
	)
	(arc
		(start 96.335088 -276.64283)
		(mid 96.2478 -276.400874)
		(end 96.062292 -276.222714)
		(width 0.088646)
		(layer "In6.Cu")
		(net "M_D_CPU1_SA_DQ<2>")
	)
	(arc
		(start 86.562692 -280.288492)
		(mid 86.360406 -280.487473)
		(end 86.280244 -280.759662)
		(width 0.088646)
		(layer "In6.Cu")
		(net "M_D_CPU1_SA_DQ<2>")
	)
	(arc
		(start 85.810344 -281.59202)
		(mid 85.762665 -281.77492)
		(end 85.631782 -281.911298)
		(width 0.088646)
		(layer "In6.Cu")
		(net "M_D_CPU1_SA_DQ<2>")
	)
	(arc
		(start 90.979244 -277.531068)
		(mid 90.926974 -277.713433)
		(end 90.792046 -277.84679)
		(width 0.088646)
		(layer "In6.Cu")
		(net "M_D_CPU1_SA_DQ<2>")
	)
	(arc
		(start 86.750144 -279.964134)
		(mid 86.702465 -280.147034)
		(end 86.571582 -280.283412)
		(width 0.088646)
		(layer "In6.Cu")
		(net "M_D_CPU1_SA_DQ<2>")
	)
	(arc
		(start 90.792046 -277.84679)
		(mid 90.588565 -278.047594)
		(end 90.509344 -278.322278)
		(width 0.088646)
		(layer "In6.Cu")
		(net "M_D_CPU1_SA_DQ<2>")
	)
	(arc
		(start 88.537796 -279.474676)
		(mid 88.255094 -279.3989)
		(end 87.972392 -279.474676)
		(width 0.088646)
		(layer "In6.Cu")
		(net "M_D_CPU1_SA_DQ<2>")
	)
	(arc
		(start 89.851992 -279.474676)
		(mid 89.664794 -279.524819)
		(end 89.477596 -279.474676)
		(width 0.088646)
		(layer "In6.Cu")
		(net "M_D_CPU1_SA_DQ<2>")
	)
	(arc
		(start 90.509344 -278.336502)
		(mid 90.461665 -278.519402)
		(end 90.330782 -278.65578)
		(width 0.088646)
		(layer "In6.Cu")
		(net "M_D_CPU1_SA_DQ<2>")
	)
	(arc
		(start 91.261692 -277.032974)
		(mid 91.057357 -277.235579)
		(end 90.979244 -277.512526)
		(width 0.088646)
		(layer "In6.Cu")
		(net "M_D_CPU1_SA_DQ<2>")
	)
	(arc
		(start 94.64675 -277.032974)
		(mid 94.372551 -276.957139)
		(end 94.096078 -277.024338)
		(width 0.088646)
		(layer "In6.Cu")
		(net "M_D_CPU1_SA_DQ<2>")
	)
	(arc
		(start 87.972392 -279.474676)
		(mid 87.785194 -279.524819)
		(end 87.597996 -279.474676)
		(width 0.088646)
		(layer "In6.Cu")
		(net "M_D_CPU1_SA_DQ<2>")
	)
	(segment
		(start 11.1252 -280.191718)
		(end 13.110718 -280.191718)
		(width 0.1016)
		(layer "F.Cu")
		(net "M_D_CPU1_SA_DQ<29>")
	)
	(segment
		(start 13.110718 -280.191718)
		(end 13.441426 -280.191718)
		(width 0.101854)
		(layer "F.Cu")
		(net "M_D_CPU1_SA_DQ<29>")
	)
	(segment
		(start 11.11631 -280.182828)
		(end 11.1252 -280.191718)
		(width 0.1016)
		(layer "F.Cu")
		(net "M_D_CPU1_SA_DQ<29>")
	)
	(segment
		(start 99.062794 -265.592306)
		(end 99.063048 -265.592306)
		(width 0.20066)
		(layer "F.Cu")
		(net "M_D_CPU1_SA_DQ<29>")
	)
	(segment
		(start 10.344912 -280.345388)
		(end 10.507472 -280.182828)
		(width 0.20066)
		(layer "F.Cu")
		(net "M_D_CPU1_SA_DQ<29>")
	)
	(segment
		(start 9.474708 -280.61666)
		(end 9.686036 -280.827988)
		(width 0.20066)
		(layer "F.Cu")
		(net "M_D_CPU1_SA_DQ<29>")
	)
	(segment
		(start 99.062794 -266.128246)
		(end 99.062794 -265.592306)
		(width 0.20066)
		(layer "F.Cu")
		(net "M_D_CPU1_SA_DQ<29>")
	)
	(segment
		(start 13.619988 -280.191718)
		(end 14.04493 -280.61666)
		(width 0.20066)
		(layer "F.Cu")
		(net "M_D_CPU1_SA_DQ<29>")
	)
	(segment
		(start 16.789146 -280.61666)
		(end 15.684246 -280.61666)
		(width 0.20066)
		(layer "F.Cu")
		(net "M_D_CPU1_SA_DQ<29>")
	)
	(segment
		(start 13.441426 -280.191718)
		(end 13.619988 -280.191718)
		(width 0.20066)
		(layer "F.Cu")
		(net "M_D_CPU1_SA_DQ<29>")
	)
	(segment
		(start 14.04493 -280.61666)
		(end 15.684246 -280.61666)
		(width 0.20066)
		(layer "F.Cu")
		(net "M_D_CPU1_SA_DQ<29>")
	)
	(segment
		(start 10.19048 -280.827988)
		(end 10.344912 -280.673556)
		(width 0.20066)
		(layer "F.Cu")
		(net "M_D_CPU1_SA_DQ<29>")
	)
	(segment
		(start 10.507472 -280.182828)
		(end 11.11631 -280.182828)
		(width 0.20066)
		(layer "F.Cu")
		(net "M_D_CPU1_SA_DQ<29>")
	)
	(segment
		(start 10.344912 -280.673556)
		(end 10.344912 -280.345388)
		(width 0.20066)
		(layer "F.Cu")
		(net "M_D_CPU1_SA_DQ<29>")
	)
	(segment
		(start 8.140446 -280.61666)
		(end 9.474708 -280.61666)
		(width 0.20066)
		(layer "F.Cu")
		(net "M_D_CPU1_SA_DQ<29>")
	)
	(segment
		(start 9.686036 -280.827988)
		(end 10.19048 -280.827988)
		(width 0.20066)
		(layer "F.Cu")
		(net "M_D_CPU1_SA_DQ<29>")
	)
	(segment
		(start 22.984968 -281.078686)
		(end 22.791928 -280.885646)
		(width 0.18288)
		(layer "In11.Cu")
		(net "M_D_CPU1_SA_DQ<29>")
	)
	(segment
		(start 84.011262 -265.87958)
		(end 83.415378 -266.475464)
		(width 0.088646)
		(layer "In11.Cu")
		(net "M_D_CPU1_SA_DQ<29>")
	)
	(segment
		(start 51.947826 -279.176226)
		(end 51.781456 -279.342596)
		(width 0.18288)
		(layer "In11.Cu")
		(net "M_D_CPU1_SA_DQ<29>")
	)
	(segment
		(start 96.056196 -265.803634)
		(end 96.041464 -265.81227)
		(width 0.088646)
		(layer "In11.Cu")
		(net "M_D_CPU1_SA_DQ<29>")
	)
	(segment
		(start 42.422826 -280.166826)
		(end 41.762426 -279.506426)
		(width 0.18288)
		(layer "In11.Cu")
		(net "M_D_CPU1_SA_DQ<29>")
	)
	(segment
		(start 18.335752 -281.322272)
		(end 18.142712 -281.129232)
		(width 0.18288)
		(layer "In11.Cu")
		(net "M_D_CPU1_SA_DQ<29>")
	)
	(segment
		(start 21.532088 -281.042364)
		(end 19.851624 -281.042364)
		(width 0.18288)
		(layer "In11.Cu")
		(net "M_D_CPU1_SA_DQ<29>")
	)
	(segment
		(start 22.791928 -280.885646)
		(end 21.688806 -280.885646)
		(width 0.18288)
		(layer "In11.Cu")
		(net "M_D_CPU1_SA_DQ<29>")
	)
	(segment
		(start 65.214246 -277.406862)
		(end 64.899286 -277.406862)
		(width 0.18288)
		(layer "In11.Cu")
		(net "M_D_CPU1_SA_DQ<29>")
	)
	(segment
		(start 21.688806 -280.885646)
		(end 21.532088 -281.042364)
		(width 0.18288)
		(layer "In11.Cu")
		(net "M_D_CPU1_SA_DQ<29>")
	)
	(segment
		(start 49.901856 -279.342596)
		(end 49.331626 -279.912826)
		(width 0.18288)
		(layer "In11.Cu")
		(net "M_D_CPU1_SA_DQ<29>")
	)
	(segment
		(start 95.116396 -265.803634)
		(end 95.101664 -265.81227)
		(width 0.088646)
		(layer "In11.Cu")
		(net "M_D_CPU1_SA_DQ<29>")
	)
	(segment
		(start 40.187626 -279.506426)
		(end 39.908226 -279.227026)
		(width 0.18288)
		(layer "In11.Cu")
		(net "M_D_CPU1_SA_DQ<29>")
	)
	(segment
		(start 64.706246 -277.213822)
		(end 64.706246 -276.962362)
		(width 0.18288)
		(layer "In11.Cu")
		(net "M_D_CPU1_SA_DQ<29>")
	)
	(segment
		(start 88.537796 -265.803634)
		(end 88.537796 -265.803888)
		(width 0.088646)
		(layer "In11.Cu")
		(net "M_D_CPU1_SA_DQ<29>")
	)
	(segment
		(start 29.468826 -280.344626)
		(end 29.265626 -280.141426)
		(width 0.18288)
		(layer "In11.Cu")
		(net "M_D_CPU1_SA_DQ<29>")
	)
	(segment
		(start 99.258882 -265.808714)
		(end 99.249992 -265.803634)
		(width 0.088646)
		(layer "In11.Cu")
		(net "M_D_CPU1_SA_DQ<29>")
	)
	(segment
		(start 32.455358 -280.19248)
		(end 30.689042 -280.19248)
		(width 0.18288)
		(layer "In11.Cu")
		(net "M_D_CPU1_SA_DQ<29>")
	)
	(segment
		(start 35.480752 -279.342596)
		(end 34.70275 -280.120598)
		(width 0.18288)
		(layer "In11.Cu")
		(net "M_D_CPU1_SA_DQ<29>")
	)
	(segment
		(start 97.935796 -265.803634)
		(end 97.921064 -265.81227)
		(width 0.088646)
		(layer "In11.Cu")
		(net "M_D_CPU1_SA_DQ<29>")
	)
	(segment
		(start 18.528792 -281.8003)
		(end 18.335752 -281.60726)
		(width 0.18288)
		(layer "In11.Cu")
		(net "M_D_CPU1_SA_DQ<29>")
	)
	(segment
		(start 47.822612 -279.912826)
		(end 47.542958 -280.19248)
		(width 0.18288)
		(layer "In11.Cu")
		(net "M_D_CPU1_SA_DQ<29>")
	)
	(segment
		(start 18.142712 -281.129232)
		(end 17.629632 -281.129232)
		(width 0.18288)
		(layer "In11.Cu")
		(net "M_D_CPU1_SA_DQ<29>")
	)
	(segment
		(start 91.357196 -265.803634)
		(end 91.342464 -265.81227)
		(width 0.088646)
		(layer "In11.Cu")
		(net "M_D_CPU1_SA_DQ<29>")
	)
	(segment
		(start 84.495894 -265.87958)
		(end 84.011262 -265.87958)
		(width 0.088646)
		(layer "In11.Cu")
		(net "M_D_CPU1_SA_DQ<29>")
	)
	(segment
		(start 43.870626 -279.963626)
		(end 43.235626 -279.963626)
		(width 0.18288)
		(layer "In11.Cu")
		(net "M_D_CPU1_SA_DQ<29>")
	)
	(segment
		(start 60.626752 -277.53564)
		(end 60.453016 -277.709376)
		(width 0.18288)
		(layer "In11.Cu")
		(net "M_D_CPU1_SA_DQ<29>")
	)
	(segment
		(start 23.492968 -281.531314)
		(end 23.178008 -281.531314)
		(width 0.18288)
		(layer "In11.Cu")
		(net "M_D_CPU1_SA_DQ<29>")
	)
	(segment
		(start 36.795456 -279.342596)
		(end 35.480752 -279.342596)
		(width 0.18288)
		(layer "In11.Cu")
		(net "M_D_CPU1_SA_DQ<29>")
	)
	(segment
		(start 43.235626 -279.963626)
		(end 43.032426 -280.166826)
		(width 0.18288)
		(layer "In11.Cu")
		(net "M_D_CPU1_SA_DQ<29>")
	)
	(segment
		(start 30.536896 -280.344626)
		(end 29.468826 -280.344626)
		(width 0.18288)
		(layer "In11.Cu")
		(net "M_D_CPU1_SA_DQ<29>")
	)
	(segment
		(start 17.629632 -281.129232)
		(end 17.11706 -280.61666)
		(width 0.18288)
		(layer "In11.Cu")
		(net "M_D_CPU1_SA_DQ<29>")
	)
	(segment
		(start 39.908226 -279.227026)
		(end 36.911026 -279.227026)
		(width 0.18288)
		(layer "In11.Cu")
		(net "M_D_CPU1_SA_DQ<29>")
	)
	(segment
		(start 19.229832 -281.129232)
		(end 19.036792 -281.322272)
		(width 0.18288)
		(layer "In11.Cu")
		(net "M_D_CPU1_SA_DQ<29>")
	)
	(segment
		(start 62.991746 -277.53564)
		(end 60.626752 -277.53564)
		(width 0.18288)
		(layer "In11.Cu")
		(net "M_D_CPU1_SA_DQ<29>")
	)
	(segment
		(start 60.453016 -277.709376)
		(end 60.453016 -278.088852)
		(width 0.18288)
		(layer "In11.Cu")
		(net "M_D_CPU1_SA_DQ<29>")
	)
	(segment
		(start 25.117806 -280.885646)
		(end 23.879048 -280.885646)
		(width 0.18288)
		(layer "In11.Cu")
		(net "M_D_CPU1_SA_DQ<29>")
	)
	(segment
		(start 65.407286 -277.213822)
		(end 65.214246 -277.406862)
		(width 0.18288)
		(layer "In11.Cu")
		(net "M_D_CPU1_SA_DQ<29>")
	)
	(segment
		(start 17.11706 -280.61666)
		(end 16.789146 -280.61666)
		(width 0.18288)
		(layer "In11.Cu")
		(net "M_D_CPU1_SA_DQ<29>")
	)
	(segment
		(start 64.899286 -277.406862)
		(end 64.706246 -277.213822)
		(width 0.18288)
		(layer "In11.Cu")
		(net "M_D_CPU1_SA_DQ<29>")
	)
	(segment
		(start 65.600326 -276.769322)
		(end 65.407286 -276.962362)
		(width 0.18288)
		(layer "In11.Cu")
		(net "M_D_CPU1_SA_DQ<29>")
	)
	(segment
		(start 99.375468 -266.127992)
		(end 99.432872 -266.070588)
		(width 0.088646)
		(layer "In11.Cu")
		(net "M_D_CPU1_SA_DQ<29>")
	)
	(segment
		(start 99.063048 -266.127992)
		(end 99.375468 -266.127992)
		(width 0.088646)
		(layer "In11.Cu")
		(net "M_D_CPU1_SA_DQ<29>")
	)
	(segment
		(start 99.062794 -266.128246)
		(end 99.063048 -266.127992)
		(width 0.088646)
		(layer "In11.Cu")
		(net "M_D_CPU1_SA_DQ<29>")
	)
	(segment
		(start 23.686008 -281.078686)
		(end 23.686008 -281.338274)
		(width 0.18288)
		(layer "In11.Cu")
		(net "M_D_CPU1_SA_DQ<29>")
	)
	(segment
		(start 65.407286 -276.962362)
		(end 65.407286 -277.213822)
		(width 0.18288)
		(layer "In11.Cu")
		(net "M_D_CPU1_SA_DQ<29>")
	)
	(segment
		(start 18.843752 -281.8003)
		(end 18.528792 -281.8003)
		(width 0.18288)
		(layer "In11.Cu")
		(net "M_D_CPU1_SA_DQ<29>")
	)
	(segment
		(start 83.415378 -266.475464)
		(end 83.415378 -267.048234)
		(width 0.088646)
		(layer "In11.Cu")
		(net "M_D_CPU1_SA_DQ<29>")
	)
	(segment
		(start 22.984968 -281.338274)
		(end 22.984968 -281.078686)
		(width 0.18288)
		(layer "In11.Cu")
		(net "M_D_CPU1_SA_DQ<29>")
	)
	(segment
		(start 93.236796 -265.803634)
		(end 93.222064 -265.81227)
		(width 0.088646)
		(layer "In11.Cu")
		(net "M_D_CPU1_SA_DQ<29>")
	)
	(segment
		(start 44.315126 -280.408126)
		(end 43.870626 -279.963626)
		(width 0.18288)
		(layer "In11.Cu")
		(net "M_D_CPU1_SA_DQ<29>")
	)
	(segment
		(start 32.52724 -280.120598)
		(end 32.455358 -280.19248)
		(width 0.18288)
		(layer "In11.Cu")
		(net "M_D_CPU1_SA_DQ<29>")
	)
	(segment
		(start 18.335752 -281.60726)
		(end 18.335752 -281.322272)
		(width 0.18288)
		(layer "In11.Cu")
		(net "M_D_CPU1_SA_DQ<29>")
	)
	(segment
		(start 51.781456 -279.342596)
		(end 49.901856 -279.342596)
		(width 0.18288)
		(layer "In11.Cu")
		(net "M_D_CPU1_SA_DQ<29>")
	)
	(segment
		(start 59.288426 -278.541226)
		(end 59.085226 -278.338026)
		(width 0.18288)
		(layer "In11.Cu")
		(net "M_D_CPU1_SA_DQ<29>")
	)
	(segment
		(start 60.000642 -278.541226)
		(end 59.288426 -278.541226)
		(width 0.18288)
		(layer "In11.Cu")
		(net "M_D_CPU1_SA_DQ<29>")
	)
	(segment
		(start 36.911026 -279.227026)
		(end 36.795456 -279.342596)
		(width 0.18288)
		(layer "In11.Cu")
		(net "M_D_CPU1_SA_DQ<29>")
	)
	(segment
		(start 19.036792 -281.60726)
		(end 18.843752 -281.8003)
		(width 0.18288)
		(layer "In11.Cu")
		(net "M_D_CPU1_SA_DQ<29>")
	)
	(segment
		(start 30.689042 -280.19248)
		(end 30.536896 -280.344626)
		(width 0.18288)
		(layer "In11.Cu")
		(net "M_D_CPU1_SA_DQ<29>")
	)
	(segment
		(start 64.706246 -276.962362)
		(end 64.513206 -276.769322)
		(width 0.18288)
		(layer "In11.Cu")
		(net "M_D_CPU1_SA_DQ<29>")
	)
	(segment
		(start 45.560996 -280.408126)
		(end 44.315126 -280.408126)
		(width 0.18288)
		(layer "In11.Cu")
		(net "M_D_CPU1_SA_DQ<29>")
	)
	(segment
		(start 83.415378 -267.048234)
		(end 83.222338 -267.241274)
		(width 0.088646)
		(layer "In11.Cu")
		(net "M_D_CPU1_SA_DQ<29>")
	)
	(segment
		(start 43.032426 -280.166826)
		(end 42.422826 -280.166826)
		(width 0.18288)
		(layer "In11.Cu")
		(net "M_D_CPU1_SA_DQ<29>")
	)
	(segment
		(start 76.98232 -267.241274)
		(end 67.454272 -276.769322)
		(width 0.18288)
		(layer "In11.Cu")
		(net "M_D_CPU1_SA_DQ<29>")
	)
	(segment
		(start 19.036792 -281.322272)
		(end 19.036792 -281.60726)
		(width 0.18288)
		(layer "In11.Cu")
		(net "M_D_CPU1_SA_DQ<29>")
	)
	(segment
		(start 60.453016 -278.088852)
		(end 60.000642 -278.541226)
		(width 0.18288)
		(layer "In11.Cu")
		(net "M_D_CPU1_SA_DQ<29>")
	)
	(segment
		(start 55.199026 -279.176226)
		(end 51.947826 -279.176226)
		(width 0.18288)
		(layer "In11.Cu")
		(net "M_D_CPU1_SA_DQ<29>")
	)
	(segment
		(start 67.454272 -276.769322)
		(end 65.600326 -276.769322)
		(width 0.18288)
		(layer "In11.Cu")
		(net "M_D_CPU1_SA_DQ<29>")
	)
	(segment
		(start 23.686008 -281.338274)
		(end 23.492968 -281.531314)
		(width 0.18288)
		(layer "In11.Cu")
		(net "M_D_CPU1_SA_DQ<29>")
	)
	(segment
		(start 49.331626 -279.912826)
		(end 47.822612 -279.912826)
		(width 0.18288)
		(layer "In11.Cu")
		(net "M_D_CPU1_SA_DQ<29>")
	)
	(segment
		(start 63.758064 -276.769322)
		(end 62.991746 -277.53564)
		(width 0.18288)
		(layer "In11.Cu")
		(net "M_D_CPU1_SA_DQ<29>")
	)
	(segment
		(start 64.513206 -276.769322)
		(end 63.758064 -276.769322)
		(width 0.18288)
		(layer "In11.Cu")
		(net "M_D_CPU1_SA_DQ<29>")
	)
	(segment
		(start 94.176596 -265.803634)
		(end 94.161864 -265.81227)
		(width 0.088646)
		(layer "In11.Cu")
		(net "M_D_CPU1_SA_DQ<29>")
	)
	(segment
		(start 19.764756 -281.129232)
		(end 19.229832 -281.129232)
		(width 0.18288)
		(layer "In11.Cu")
		(net "M_D_CPU1_SA_DQ<29>")
	)
	(segment
		(start 23.178008 -281.531314)
		(end 22.984968 -281.338274)
		(width 0.18288)
		(layer "In11.Cu")
		(net "M_D_CPU1_SA_DQ<29>")
	)
	(segment
		(start 59.085226 -278.338026)
		(end 56.037226 -278.338026)
		(width 0.18288)
		(layer "In11.Cu")
		(net "M_D_CPU1_SA_DQ<29>")
	)
	(segment
		(start 19.851624 -281.042364)
		(end 19.764756 -281.129232)
		(width 0.18288)
		(layer "In11.Cu")
		(net "M_D_CPU1_SA_DQ<29>")
	)
	(segment
		(start 45.776642 -280.19248)
		(end 45.560996 -280.408126)
		(width 0.18288)
		(layer "In11.Cu")
		(net "M_D_CPU1_SA_DQ<29>")
	)
	(segment
		(start 83.222338 -267.241274)
		(end 82.963004 -267.241274)
		(width 0.088646)
		(layer "In11.Cu")
		(net "M_D_CPU1_SA_DQ<29>")
	)
	(segment
		(start 41.762426 -279.506426)
		(end 40.187626 -279.506426)
		(width 0.18288)
		(layer "In11.Cu")
		(net "M_D_CPU1_SA_DQ<29>")
	)
	(segment
		(start 34.70275 -280.120598)
		(end 32.52724 -280.120598)
		(width 0.18288)
		(layer "In11.Cu")
		(net "M_D_CPU1_SA_DQ<29>")
	)
	(segment
		(start 82.963004 -267.241274)
		(end 76.98232 -267.241274)
		(width 0.18288)
		(layer "In11.Cu")
		(net "M_D_CPU1_SA_DQ<29>")
	)
	(segment
		(start 56.037226 -278.338026)
		(end 55.199026 -279.176226)
		(width 0.18288)
		(layer "In11.Cu")
		(net "M_D_CPU1_SA_DQ<29>")
	)
	(segment
		(start 23.879048 -280.885646)
		(end 23.686008 -281.078686)
		(width 0.18288)
		(layer "In11.Cu")
		(net "M_D_CPU1_SA_DQ<29>")
	)
	(segment
		(start 29.265626 -280.141426)
		(end 25.862026 -280.141426)
		(width 0.18288)
		(layer "In11.Cu")
		(net "M_D_CPU1_SA_DQ<29>")
	)
	(segment
		(start 96.995996 -265.803634)
		(end 96.981264 -265.81227)
		(width 0.088646)
		(layer "In11.Cu")
		(net "M_D_CPU1_SA_DQ<29>")
	)
	(segment
		(start 47.542958 -280.19248)
		(end 45.776642 -280.19248)
		(width 0.18288)
		(layer "In11.Cu")
		(net "M_D_CPU1_SA_DQ<29>")
	)
	(segment
		(start 25.862026 -280.141426)
		(end 25.117806 -280.885646)
		(width 0.18288)
		(layer "In11.Cu")
		(net "M_D_CPU1_SA_DQ<29>")
	)
	(arc
		(start 96.981264 -265.81227)
		(mid 96.704789 -265.87959)
		(end 96.430592 -265.803634)
		(width 0.088646)
		(layer "In11.Cu")
		(net "M_D_CPU1_SA_DQ<29>")
	)
	(arc
		(start 95.490792 -265.803634)
		(mid 95.303594 -265.753491)
		(end 95.116396 -265.803634)
		(width 0.088646)
		(layer "In11.Cu")
		(net "M_D_CPU1_SA_DQ<29>")
	)
	(arc
		(start 90.791792 -265.803634)
		(mid 90.604594 -265.753491)
		(end 90.417396 -265.803634)
		(width 0.088646)
		(layer "In11.Cu")
		(net "M_D_CPU1_SA_DQ<29>")
	)
	(arc
		(start 87.972392 -265.803888)
		(mid 87.785194 -265.753745)
		(end 87.597996 -265.803888)
		(width 0.088646)
		(layer "In11.Cu")
		(net "M_D_CPU1_SA_DQ<29>")
	)
	(arc
		(start 93.222064 -265.81227)
		(mid 92.945589 -265.87959)
		(end 92.671392 -265.803634)
		(width 0.088646)
		(layer "In11.Cu")
		(net "M_D_CPU1_SA_DQ<29>")
	)
	(arc
		(start 96.430592 -265.803634)
		(mid 96.243394 -265.753491)
		(end 96.056196 -265.803634)
		(width 0.088646)
		(layer "In11.Cu")
		(net "M_D_CPU1_SA_DQ<29>")
	)
	(arc
		(start 89.477596 -265.803634)
		(mid 89.194894 -265.87941)
		(end 88.912192 -265.803634)
		(width 0.088646)
		(layer "In11.Cu")
		(net "M_D_CPU1_SA_DQ<29>")
	)
	(arc
		(start 97.370392 -265.803634)
		(mid 97.183194 -265.753491)
		(end 96.995996 -265.803634)
		(width 0.088646)
		(layer "In11.Cu")
		(net "M_D_CPU1_SA_DQ<29>")
	)
	(arc
		(start 99.432872 -266.070588)
		(mid 99.374716 -265.920475)
		(end 99.258882 -265.808714)
		(width 0.088646)
		(layer "In11.Cu")
		(net "M_D_CPU1_SA_DQ<29>")
	)
	(arc
		(start 86.658196 -265.803888)
		(mid 86.375494 -265.87963)
		(end 86.092792 -265.803888)
		(width 0.088646)
		(layer "In11.Cu")
		(net "M_D_CPU1_SA_DQ<29>")
	)
	(arc
		(start 94.161864 -265.81227)
		(mid 93.885389 -265.87959)
		(end 93.611192 -265.803634)
		(width 0.088646)
		(layer "In11.Cu")
		(net "M_D_CPU1_SA_DQ<29>")
	)
	(arc
		(start 98.310192 -265.803634)
		(mid 98.122994 -265.753491)
		(end 97.935796 -265.803634)
		(width 0.088646)
		(layer "In11.Cu")
		(net "M_D_CPU1_SA_DQ<29>")
	)
	(arc
		(start 85.718396 -265.803888)
		(mid 85.435694 -265.87963)
		(end 85.152992 -265.803888)
		(width 0.088646)
		(layer "In11.Cu")
		(net "M_D_CPU1_SA_DQ<29>")
	)
	(arc
		(start 95.101664 -265.81227)
		(mid 94.825189 -265.87959)
		(end 94.550992 -265.803634)
		(width 0.088646)
		(layer "In11.Cu")
		(net "M_D_CPU1_SA_DQ<29>")
	)
	(arc
		(start 88.912192 -265.803634)
		(mid 88.724994 -265.753491)
		(end 88.537796 -265.803634)
		(width 0.088646)
		(layer "In11.Cu")
		(net "M_D_CPU1_SA_DQ<29>")
	)
	(arc
		(start 90.417396 -265.803634)
		(mid 90.134694 -265.87941)
		(end 89.851992 -265.803634)
		(width 0.088646)
		(layer "In11.Cu")
		(net "M_D_CPU1_SA_DQ<29>")
	)
	(arc
		(start 88.537796 -265.803888)
		(mid 88.255094 -265.87963)
		(end 87.972392 -265.803888)
		(width 0.088646)
		(layer "In11.Cu")
		(net "M_D_CPU1_SA_DQ<29>")
	)
	(arc
		(start 93.611192 -265.803634)
		(mid 93.423994 -265.753491)
		(end 93.236796 -265.803634)
		(width 0.088646)
		(layer "In11.Cu")
		(net "M_D_CPU1_SA_DQ<29>")
	)
	(arc
		(start 92.296996 -265.803634)
		(mid 92.014294 -265.87941)
		(end 91.731592 -265.803634)
		(width 0.088646)
		(layer "In11.Cu")
		(net "M_D_CPU1_SA_DQ<29>")
	)
	(arc
		(start 94.550992 -265.803634)
		(mid 94.363794 -265.753491)
		(end 94.176596 -265.803634)
		(width 0.088646)
		(layer "In11.Cu")
		(net "M_D_CPU1_SA_DQ<29>")
	)
	(arc
		(start 86.092792 -265.803888)
		(mid 85.905594 -265.753745)
		(end 85.718396 -265.803888)
		(width 0.088646)
		(layer "In11.Cu")
		(net "M_D_CPU1_SA_DQ<29>")
	)
	(arc
		(start 97.921064 -265.81227)
		(mid 97.644589 -265.87959)
		(end 97.370392 -265.803634)
		(width 0.088646)
		(layer "In11.Cu")
		(net "M_D_CPU1_SA_DQ<29>")
	)
	(arc
		(start 84.778596 -265.803888)
		(mid 84.64223 -265.860366)
		(end 84.495894 -265.87958)
		(width 0.088646)
		(layer "In11.Cu")
		(net "M_D_CPU1_SA_DQ<29>")
	)
	(arc
		(start 98.875596 -265.803634)
		(mid 98.592894 -265.87941)
		(end 98.310192 -265.803634)
		(width 0.088646)
		(layer "In11.Cu")
		(net "M_D_CPU1_SA_DQ<29>")
	)
	(arc
		(start 99.249992 -265.803634)
		(mid 99.062794 -265.753491)
		(end 98.875596 -265.803634)
		(width 0.088646)
		(layer "In11.Cu")
		(net "M_D_CPU1_SA_DQ<29>")
	)
	(arc
		(start 91.731592 -265.803634)
		(mid 91.544394 -265.753491)
		(end 91.357196 -265.803634)
		(width 0.088646)
		(layer "In11.Cu")
		(net "M_D_CPU1_SA_DQ<29>")
	)
	(arc
		(start 92.671392 -265.803634)
		(mid 92.484194 -265.753491)
		(end 92.296996 -265.803634)
		(width 0.088646)
		(layer "In11.Cu")
		(net "M_D_CPU1_SA_DQ<29>")
	)
	(arc
		(start 91.342464 -265.81227)
		(mid 91.065989 -265.87959)
		(end 90.791792 -265.803634)
		(width 0.088646)
		(layer "In11.Cu")
		(net "M_D_CPU1_SA_DQ<29>")
	)
	(arc
		(start 85.152992 -265.803888)
		(mid 84.965794 -265.753745)
		(end 84.778596 -265.803888)
		(width 0.088646)
		(layer "In11.Cu")
		(net "M_D_CPU1_SA_DQ<29>")
	)
	(arc
		(start 87.597996 -265.803888)
		(mid 87.315294 -265.87963)
		(end 87.032592 -265.803888)
		(width 0.088646)
		(layer "In11.Cu")
		(net "M_D_CPU1_SA_DQ<29>")
	)
	(arc
		(start 87.032592 -265.803888)
		(mid 86.845394 -265.753745)
		(end 86.658196 -265.803888)
		(width 0.088646)
		(layer "In11.Cu")
		(net "M_D_CPU1_SA_DQ<29>")
	)
	(arc
		(start 89.851992 -265.803634)
		(mid 89.664794 -265.753491)
		(end 89.477596 -265.803634)
		(width 0.088646)
		(layer "In11.Cu")
		(net "M_D_CPU1_SA_DQ<29>")
	)
	(arc
		(start 96.041464 -265.81227)
		(mid 95.764989 -265.87959)
		(end 95.490792 -265.803634)
		(width 0.088646)
		(layer "In11.Cu")
		(net "M_D_CPU1_SA_DQ<29>")
	)
	(segment
		(start 8.140446 -282.316682)
		(end 9.474708 -282.316682)
		(width 0.20066)
		(layer "F.Cu")
		(net "M_D_CPU1_SA_DQ<28>")
	)
	(segment
		(start 9.713468 -282.555442)
		(end 10.172192 -282.555442)
		(width 0.20066)
		(layer "F.Cu")
		(net "M_D_CPU1_SA_DQ<28>")
	)
	(segment
		(start 14.315186 -282.316682)
		(end 15.684246 -282.316682)
		(width 0.20066)
		(layer "F.Cu")
		(net "M_D_CPU1_SA_DQ<28>")
	)
	(segment
		(start 13.441426 -281.89174)
		(end 13.890244 -281.89174)
		(width 0.20066)
		(layer "F.Cu")
		(net "M_D_CPU1_SA_DQ<28>")
	)
	(segment
		(start 10.344912 -282.382722)
		(end 10.344912 -282.093162)
		(width 0.20066)
		(layer "F.Cu")
		(net "M_D_CPU1_SA_DQ<28>")
	)
	(segment
		(start 10.172192 -282.555442)
		(end 10.344912 -282.382722)
		(width 0.20066)
		(layer "F.Cu")
		(net "M_D_CPU1_SA_DQ<28>")
	)
	(segment
		(start 13.890244 -281.89174)
		(end 14.315186 -282.316682)
		(width 0.20066)
		(layer "F.Cu")
		(net "M_D_CPU1_SA_DQ<28>")
	)
	(segment
		(start 11.372342 -281.89174)
		(end 13.441426 -281.89174)
		(width 0.1016)
		(layer "F.Cu")
		(net "M_D_CPU1_SA_DQ<28>")
	)
	(segment
		(start 11.11631 -281.883612)
		(end 11.124438 -281.89174)
		(width 0.101854)
		(layer "F.Cu")
		(net "M_D_CPU1_SA_DQ<28>")
	)
	(segment
		(start 10.554462 -281.883612)
		(end 11.11631 -281.883612)
		(width 0.20066)
		(layer "F.Cu")
		(net "M_D_CPU1_SA_DQ<28>")
	)
	(segment
		(start 16.789146 -282.316682)
		(end 15.684246 -282.316682)
		(width 0.20066)
		(layer "F.Cu")
		(net "M_D_CPU1_SA_DQ<28>")
	)
	(segment
		(start 11.124438 -281.89174)
		(end 11.372342 -281.89174)
		(width 0.101854)
		(layer "F.Cu")
		(net "M_D_CPU1_SA_DQ<28>")
	)
	(segment
		(start 10.344912 -282.093162)
		(end 10.554462 -281.883612)
		(width 0.20066)
		(layer "F.Cu")
		(net "M_D_CPU1_SA_DQ<28>")
	)
	(segment
		(start 9.474708 -282.316682)
		(end 9.713468 -282.555442)
		(width 0.20066)
		(layer "F.Cu")
		(net "M_D_CPU1_SA_DQ<28>")
	)
	(arc
		(start 98.592894 -266.405868)
		(mid 98.592957 -266.673838)
		(end 98.593148 -266.941808)
		(width 0.20066)
		(layer "F.Cu")
		(net "M_D_CPU1_SA_DQ<28>")
	)
	(segment
		(start 92.216478 -266.62634)
		(end 92.201746 -266.617704)
		(width 0.088646)
		(layer "In11.Cu")
		(net "M_D_CPU1_SA_DQ<28>")
	)
	(segment
		(start 59.263026 -279.963626)
		(end 58.097928 -279.963626)
		(width 0.18288)
		(layer "In11.Cu")
		(net "M_D_CPU1_SA_DQ<28>")
	)
	(segment
		(start 47.674022 -281.892502)
		(end 45.449744 -281.892502)
		(width 0.18288)
		(layer "In11.Cu")
		(net "M_D_CPU1_SA_DQ<28>")
	)
	(segment
		(start 60.069476 -280.195528)
		(end 59.494928 -280.195528)
		(width 0.18288)
		(layer "In11.Cu")
		(net "M_D_CPU1_SA_DQ<28>")
	)
	(segment
		(start 47.93107 -281.635454)
		(end 47.674022 -281.892502)
		(width 0.18288)
		(layer "In11.Cu")
		(net "M_D_CPU1_SA_DQ<28>")
	)
	(segment
		(start 94.096078 -266.62634)
		(end 94.081346 -266.617704)
		(width 0.088646)
		(layer "In11.Cu")
		(net "M_D_CPU1_SA_DQ<28>")
	)
	(segment
		(start 24.903684 -282.598368)
		(end 21.677884 -282.598368)
		(width 0.18288)
		(layer "In11.Cu")
		(net "M_D_CPU1_SA_DQ<28>")
	)
	(segment
		(start 82.963004 -268.257274)
		(end 77.403706 -268.257274)
		(width 0.18288)
		(layer "In11.Cu")
		(net "M_D_CPU1_SA_DQ<28>")
	)
	(segment
		(start 65.615566 -278.605996)
		(end 64.922146 -278.605996)
		(width 0.18288)
		(layer "In11.Cu")
		(net "M_D_CPU1_SA_DQ<28>")
	)
	(segment
		(start 64.922146 -278.605996)
		(end 64.762126 -278.445976)
		(width 0.18288)
		(layer "In11.Cu")
		(net "M_D_CPU1_SA_DQ<28>")
	)
	(segment
		(start 95.975678 -266.62634)
		(end 95.960946 -266.617704)
		(width 0.088646)
		(layer "In11.Cu")
		(net "M_D_CPU1_SA_DQ<28>")
	)
	(segment
		(start 37.749226 -280.979626)
		(end 37.681154 -280.911554)
		(width 0.18288)
		(layer "In11.Cu")
		(net "M_D_CPU1_SA_DQ<28>")
	)
	(segment
		(start 32.586422 -281.892502)
		(end 30.66542 -281.892502)
		(width 0.18288)
		(layer "In11.Cu")
		(net "M_D_CPU1_SA_DQ<28>")
	)
	(segment
		(start 53.573426 -281.639772)
		(end 53.258466 -281.639772)
		(width 0.18288)
		(layer "In11.Cu")
		(net "M_D_CPU1_SA_DQ<28>")
	)
	(segment
		(start 50.335434 -281.042618)
		(end 49.742598 -281.635454)
		(width 0.18288)
		(layer "In11.Cu")
		(net "M_D_CPU1_SA_DQ<28>")
	)
	(segment
		(start 84.191348 -266.566904)
		(end 83.797394 -266.960858)
		(width 0.088646)
		(layer "In11.Cu")
		(net "M_D_CPU1_SA_DQ<28>")
	)
	(segment
		(start 83.797394 -266.960858)
		(end 83.797394 -267.328142)
		(width 0.088646)
		(layer "In11.Cu")
		(net "M_D_CPU1_SA_DQ<28>")
	)
	(segment
		(start 83.27136 -268.257274)
		(end 82.963004 -268.257274)
		(width 0.088646)
		(layer "In11.Cu")
		(net "M_D_CPU1_SA_DQ<28>")
	)
	(segment
		(start 53.959506 -280.928826)
		(end 53.766466 -281.121866)
		(width 0.18288)
		(layer "In11.Cu")
		(net "M_D_CPU1_SA_DQ<28>")
	)
	(segment
		(start 63.703708 -278.445976)
		(end 62.856872 -279.292812)
		(width 0.18288)
		(layer "In11.Cu")
		(net "M_D_CPU1_SA_DQ<28>")
	)
	(segment
		(start 49.742598 -281.635454)
		(end 47.93107 -281.635454)
		(width 0.18288)
		(layer "In11.Cu")
		(net "M_D_CPU1_SA_DQ<28>")
	)
	(segment
		(start 57.203848 -280.622502)
		(end 57.203848 -280.156666)
		(width 0.18288)
		(layer "In11.Cu")
		(net "M_D_CPU1_SA_DQ<28>")
	)
	(segment
		(start 36.924234 -281.042618)
		(end 35.46221 -281.042618)
		(width 0.18288)
		(layer "In11.Cu")
		(net "M_D_CPU1_SA_DQ<28>")
	)
	(segment
		(start 30.66542 -281.892502)
		(end 30.652466 -281.905456)
		(width 0.18288)
		(layer "In11.Cu")
		(net "M_D_CPU1_SA_DQ<28>")
	)
	(segment
		(start 21.533866 -282.742386)
		(end 20.162266 -282.742386)
		(width 0.18288)
		(layer "In11.Cu")
		(net "M_D_CPU1_SA_DQ<28>")
	)
	(segment
		(start 25.658826 -281.843226)
		(end 24.903684 -282.598368)
		(width 0.18288)
		(layer "In11.Cu")
		(net "M_D_CPU1_SA_DQ<28>")
	)
	(segment
		(start 51.922426 -280.928826)
		(end 51.808634 -281.042618)
		(width 0.18288)
		(layer "In11.Cu")
		(net "M_D_CPU1_SA_DQ<28>")
	)
	(segment
		(start 41.759886 -281.462226)
		(end 40.924226 -281.462226)
		(width 0.18288)
		(layer "In11.Cu")
		(net "M_D_CPU1_SA_DQ<28>")
	)
	(segment
		(start 57.711848 -280.815542)
		(end 57.396888 -280.815542)
		(width 0.18288)
		(layer "In11.Cu")
		(net "M_D_CPU1_SA_DQ<28>")
	)
	(segment
		(start 53.766466 -281.121866)
		(end 53.766466 -281.446732)
		(width 0.18288)
		(layer "In11.Cu")
		(net "M_D_CPU1_SA_DQ<28>")
	)
	(segment
		(start 43.934126 -281.906726)
		(end 43.794426 -281.767026)
		(width 0.18288)
		(layer "In11.Cu")
		(net "M_D_CPU1_SA_DQ<28>")
	)
	(segment
		(start 65.775586 -278.445976)
		(end 65.615566 -278.605996)
		(width 0.18288)
		(layer "In11.Cu")
		(net "M_D_CPU1_SA_DQ<28>")
	)
	(segment
		(start 93.156278 -266.62634)
		(end 93.141546 -266.617704)
		(width 0.088646)
		(layer "In11.Cu")
		(net "M_D_CPU1_SA_DQ<28>")
	)
	(segment
		(start 83.4644 -267.661136)
		(end 83.4644 -268.064234)
		(width 0.088646)
		(layer "In11.Cu")
		(net "M_D_CPU1_SA_DQ<28>")
	)
	(segment
		(start 53.766466 -281.446732)
		(end 53.573426 -281.639772)
		(width 0.18288)
		(layer "In11.Cu")
		(net "M_D_CPU1_SA_DQ<28>")
	)
	(segment
		(start 64.762126 -278.445976)
		(end 63.703708 -278.445976)
		(width 0.18288)
		(layer "In11.Cu")
		(net "M_D_CPU1_SA_DQ<28>")
	)
	(segment
		(start 40.441626 -280.979626)
		(end 37.749226 -280.979626)
		(width 0.18288)
		(layer "In11.Cu")
		(net "M_D_CPU1_SA_DQ<28>")
	)
	(segment
		(start 45.43552 -281.906726)
		(end 43.934126 -281.906726)
		(width 0.18288)
		(layer "In11.Cu")
		(net "M_D_CPU1_SA_DQ<28>")
	)
	(segment
		(start 95.035878 -266.62634)
		(end 95.021146 -266.617704)
		(width 0.088646)
		(layer "In11.Cu")
		(net "M_D_CPU1_SA_DQ<28>")
	)
	(segment
		(start 60.972192 -279.292812)
		(end 60.069476 -280.195528)
		(width 0.18288)
		(layer "In11.Cu")
		(net "M_D_CPU1_SA_DQ<28>")
	)
	(segment
		(start 42.838624 -282.550616)
		(end 42.523664 -282.550616)
		(width 0.18288)
		(layer "In11.Cu")
		(net "M_D_CPU1_SA_DQ<28>")
	)
	(segment
		(start 21.677884 -282.598368)
		(end 21.533866 -282.742386)
		(width 0.18288)
		(layer "In11.Cu")
		(net "M_D_CPU1_SA_DQ<28>")
	)
	(segment
		(start 59.494928 -280.195528)
		(end 59.263026 -279.963626)
		(width 0.18288)
		(layer "In11.Cu")
		(net "M_D_CPU1_SA_DQ<28>")
	)
	(segment
		(start 17.45869 -282.986226)
		(end 16.789146 -282.316682)
		(width 0.18288)
		(layer "In11.Cu")
		(net "M_D_CPU1_SA_DQ<28>")
	)
	(segment
		(start 98.134678 -266.704064)
		(end 97.927668 -266.66825)
		(width 0.088646)
		(layer "In11.Cu")
		(net "M_D_CPU1_SA_DQ<28>")
	)
	(segment
		(start 45.449744 -281.892502)
		(end 45.43552 -281.906726)
		(width 0.18288)
		(layer "In11.Cu")
		(net "M_D_CPU1_SA_DQ<28>")
	)
	(segment
		(start 97.927668 -266.66825)
		(end 97.840292 -266.617704)
		(width 0.088646)
		(layer "In11.Cu")
		(net "M_D_CPU1_SA_DQ<28>")
	)
	(segment
		(start 37.681154 -280.911554)
		(end 37.055298 -280.911554)
		(width 0.18288)
		(layer "In11.Cu")
		(net "M_D_CPU1_SA_DQ<28>")
	)
	(segment
		(start 37.055298 -280.911554)
		(end 36.924234 -281.042618)
		(width 0.18288)
		(layer "In11.Cu")
		(net "M_D_CPU1_SA_DQ<28>")
	)
	(segment
		(start 66.376296 -278.445976)
		(end 65.775586 -278.445976)
		(width 0.18288)
		(layer "In11.Cu")
		(net "M_D_CPU1_SA_DQ<28>")
	)
	(segment
		(start 53.065426 -281.121866)
		(end 52.872386 -280.928826)
		(width 0.18288)
		(layer "In11.Cu")
		(net "M_D_CPU1_SA_DQ<28>")
	)
	(segment
		(start 67.03695 -277.785322)
		(end 66.376296 -278.445976)
		(width 0.18288)
		(layer "In11.Cu")
		(net "M_D_CPU1_SA_DQ<28>")
	)
	(segment
		(start 51.808634 -281.042618)
		(end 50.335434 -281.042618)
		(width 0.18288)
		(layer "In11.Cu")
		(net "M_D_CPU1_SA_DQ<28>")
	)
	(segment
		(start 57.904888 -280.156666)
		(end 57.904888 -280.622502)
		(width 0.18288)
		(layer "In11.Cu")
		(net "M_D_CPU1_SA_DQ<28>")
	)
	(segment
		(start 29.164026 -281.843226)
		(end 25.658826 -281.843226)
		(width 0.18288)
		(layer "In11.Cu")
		(net "M_D_CPU1_SA_DQ<28>")
	)
	(segment
		(start 55.122826 -280.928826)
		(end 53.959506 -280.928826)
		(width 0.18288)
		(layer "In11.Cu")
		(net "M_D_CPU1_SA_DQ<28>")
	)
	(segment
		(start 77.403706 -268.257274)
		(end 67.875658 -277.785322)
		(width 0.18288)
		(layer "In11.Cu")
		(net "M_D_CPU1_SA_DQ<28>")
	)
	(segment
		(start 42.523664 -282.550616)
		(end 42.330624 -282.357576)
		(width 0.18288)
		(layer "In11.Cu")
		(net "M_D_CPU1_SA_DQ<28>")
	)
	(segment
		(start 30.652466 -281.905456)
		(end 29.226256 -281.905456)
		(width 0.18288)
		(layer "In11.Cu")
		(net "M_D_CPU1_SA_DQ<28>")
	)
	(segment
		(start 43.031664 -281.960066)
		(end 43.031664 -282.357576)
		(width 0.18288)
		(layer "In11.Cu")
		(net "M_D_CPU1_SA_DQ<28>")
	)
	(segment
		(start 84.495894 -266.566904)
		(end 84.191348 -266.566904)
		(width 0.088646)
		(layer "In11.Cu")
		(net "M_D_CPU1_SA_DQ<28>")
	)
	(segment
		(start 19.918426 -282.986226)
		(end 17.45869 -282.986226)
		(width 0.18288)
		(layer "In11.Cu")
		(net "M_D_CPU1_SA_DQ<28>")
	)
	(segment
		(start 53.065426 -281.446732)
		(end 53.065426 -281.121866)
		(width 0.18288)
		(layer "In11.Cu")
		(net "M_D_CPU1_SA_DQ<28>")
	)
	(segment
		(start 96.91116 -266.6238)
		(end 96.900746 -266.617704)
		(width 0.088646)
		(layer "In11.Cu")
		(net "M_D_CPU1_SA_DQ<28>")
	)
	(segment
		(start 53.258466 -281.639772)
		(end 53.065426 -281.446732)
		(width 0.18288)
		(layer "In11.Cu")
		(net "M_D_CPU1_SA_DQ<28>")
	)
	(segment
		(start 40.924226 -281.462226)
		(end 40.441626 -280.979626)
		(width 0.18288)
		(layer "In11.Cu")
		(net "M_D_CPU1_SA_DQ<28>")
	)
	(segment
		(start 58.097928 -279.963626)
		(end 57.904888 -280.156666)
		(width 0.18288)
		(layer "In11.Cu")
		(net "M_D_CPU1_SA_DQ<28>")
	)
	(segment
		(start 83.4644 -268.064234)
		(end 83.27136 -268.257274)
		(width 0.088646)
		(layer "In11.Cu")
		(net "M_D_CPU1_SA_DQ<28>")
	)
	(segment
		(start 29.226256 -281.905456)
		(end 29.164026 -281.843226)
		(width 0.18288)
		(layer "In11.Cu")
		(net "M_D_CPU1_SA_DQ<28>")
	)
	(segment
		(start 52.872386 -280.928826)
		(end 51.922426 -280.928826)
		(width 0.18288)
		(layer "In11.Cu")
		(net "M_D_CPU1_SA_DQ<28>")
	)
	(segment
		(start 35.46221 -281.042618)
		(end 34.6964 -281.808428)
		(width 0.18288)
		(layer "In11.Cu")
		(net "M_D_CPU1_SA_DQ<28>")
	)
	(segment
		(start 34.6964 -281.808428)
		(end 32.670496 -281.808428)
		(width 0.18288)
		(layer "In11.Cu")
		(net "M_D_CPU1_SA_DQ<28>")
	)
	(segment
		(start 43.031664 -282.357576)
		(end 42.838624 -282.550616)
		(width 0.18288)
		(layer "In11.Cu")
		(net "M_D_CPU1_SA_DQ<28>")
	)
	(segment
		(start 56.088026 -279.963626)
		(end 55.122826 -280.928826)
		(width 0.18288)
		(layer "In11.Cu")
		(net "M_D_CPU1_SA_DQ<28>")
	)
	(segment
		(start 57.203848 -280.156666)
		(end 57.010808 -279.963626)
		(width 0.18288)
		(layer "In11.Cu")
		(net "M_D_CPU1_SA_DQ<28>")
	)
	(segment
		(start 42.330624 -282.032964)
		(end 41.759886 -281.462226)
		(width 0.18288)
		(layer "In11.Cu")
		(net "M_D_CPU1_SA_DQ<28>")
	)
	(segment
		(start 20.162266 -282.742386)
		(end 19.918426 -282.986226)
		(width 0.18288)
		(layer "In11.Cu")
		(net "M_D_CPU1_SA_DQ<28>")
	)
	(segment
		(start 62.856872 -279.292812)
		(end 60.972192 -279.292812)
		(width 0.18288)
		(layer "In11.Cu")
		(net "M_D_CPU1_SA_DQ<28>")
	)
	(segment
		(start 83.797394 -267.328142)
		(end 83.4644 -267.661136)
		(width 0.088646)
		(layer "In11.Cu")
		(net "M_D_CPU1_SA_DQ<28>")
	)
	(segment
		(start 91.272106 -266.6238)
		(end 91.261692 -266.617704)
		(width 0.088646)
		(layer "In11.Cu")
		(net "M_D_CPU1_SA_DQ<28>")
	)
	(segment
		(start 32.670496 -281.808428)
		(end 32.586422 -281.892502)
		(width 0.18288)
		(layer "In11.Cu")
		(net "M_D_CPU1_SA_DQ<28>")
	)
	(segment
		(start 57.904888 -280.622502)
		(end 57.711848 -280.815542)
		(width 0.18288)
		(layer "In11.Cu")
		(net "M_D_CPU1_SA_DQ<28>")
	)
	(segment
		(start 57.396888 -280.815542)
		(end 57.203848 -280.622502)
		(width 0.18288)
		(layer "In11.Cu")
		(net "M_D_CPU1_SA_DQ<28>")
	)
	(segment
		(start 67.875658 -277.785322)
		(end 67.03695 -277.785322)
		(width 0.18288)
		(layer "In11.Cu")
		(net "M_D_CPU1_SA_DQ<28>")
	)
	(segment
		(start 42.330624 -282.357576)
		(end 42.330624 -282.032964)
		(width 0.18288)
		(layer "In11.Cu")
		(net "M_D_CPU1_SA_DQ<28>")
	)
	(segment
		(start 57.010808 -279.963626)
		(end 56.088026 -279.963626)
		(width 0.18288)
		(layer "In11.Cu")
		(net "M_D_CPU1_SA_DQ<28>")
	)
	(segment
		(start 43.794426 -281.767026)
		(end 43.224704 -281.767026)
		(width 0.18288)
		(layer "In11.Cu")
		(net "M_D_CPU1_SA_DQ<28>")
	)
	(segment
		(start 43.224704 -281.767026)
		(end 43.031664 -281.960066)
		(width 0.18288)
		(layer "In11.Cu")
		(net "M_D_CPU1_SA_DQ<28>")
	)
	(arc
		(start 96.52635 -266.617704)
		(mid 96.252151 -266.693539)
		(end 95.975678 -266.62634)
		(width 0.088646)
		(layer "In11.Cu")
		(net "M_D_CPU1_SA_DQ<28>")
	)
	(arc
		(start 94.081346 -266.617704)
		(mid 93.894148 -266.567527)
		(end 93.70695 -266.617704)
		(width 0.088646)
		(layer "In11.Cu")
		(net "M_D_CPU1_SA_DQ<28>")
	)
	(arc
		(start 98.593148 -266.941808)
		(mid 98.38231 -266.787445)
		(end 98.134678 -266.704064)
		(width 0.088646)
		(layer "In11.Cu")
		(net "M_D_CPU1_SA_DQ<28>")
	)
	(arc
		(start 88.067896 -266.617704)
		(mid 87.785194 -266.69348)
		(end 87.502492 -266.617704)
		(width 0.088646)
		(layer "In11.Cu")
		(net "M_D_CPU1_SA_DQ<28>")
	)
	(arc
		(start 94.64675 -266.617704)
		(mid 94.372551 -266.693539)
		(end 94.096078 -266.62634)
		(width 0.088646)
		(layer "In11.Cu")
		(net "M_D_CPU1_SA_DQ<28>")
	)
	(arc
		(start 92.201746 -266.617704)
		(mid 92.014548 -266.567527)
		(end 91.82735 -266.617704)
		(width 0.088646)
		(layer "In11.Cu")
		(net "M_D_CPU1_SA_DQ<28>")
	)
	(arc
		(start 88.442292 -266.617704)
		(mid 88.255094 -266.567527)
		(end 88.067896 -266.617704)
		(width 0.088646)
		(layer "In11.Cu")
		(net "M_D_CPU1_SA_DQ<28>")
	)
	(arc
		(start 86.188296 -266.617704)
		(mid 85.905594 -266.69348)
		(end 85.622892 -266.617704)
		(width 0.088646)
		(layer "In11.Cu")
		(net "M_D_CPU1_SA_DQ<28>")
	)
	(arc
		(start 89.007696 -266.617704)
		(mid 88.724994 -266.69348)
		(end 88.442292 -266.617704)
		(width 0.088646)
		(layer "In11.Cu")
		(net "M_D_CPU1_SA_DQ<28>")
	)
	(arc
		(start 85.248496 -266.617704)
		(mid 84.965794 -266.69348)
		(end 84.683092 -266.617704)
		(width 0.088646)
		(layer "In11.Cu")
		(net "M_D_CPU1_SA_DQ<28>")
	)
	(arc
		(start 96.900746 -266.617704)
		(mid 96.713548 -266.567527)
		(end 96.52635 -266.617704)
		(width 0.088646)
		(layer "In11.Cu")
		(net "M_D_CPU1_SA_DQ<28>")
	)
	(arc
		(start 87.502492 -266.617704)
		(mid 87.315294 -266.567527)
		(end 87.128096 -266.617704)
		(width 0.088646)
		(layer "In11.Cu")
		(net "M_D_CPU1_SA_DQ<28>")
	)
	(arc
		(start 84.683092 -266.617704)
		(mid 84.592841 -266.579957)
		(end 84.495894 -266.566904)
		(width 0.088646)
		(layer "In11.Cu")
		(net "M_D_CPU1_SA_DQ<28>")
	)
	(arc
		(start 87.128096 -266.617704)
		(mid 86.845394 -266.69348)
		(end 86.562692 -266.617704)
		(width 0.088646)
		(layer "In11.Cu")
		(net "M_D_CPU1_SA_DQ<28>")
	)
	(arc
		(start 95.960946 -266.617704)
		(mid 95.773748 -266.567527)
		(end 95.58655 -266.617704)
		(width 0.088646)
		(layer "In11.Cu")
		(net "M_D_CPU1_SA_DQ<28>")
	)
	(arc
		(start 85.622892 -266.617704)
		(mid 85.435694 -266.567527)
		(end 85.248496 -266.617704)
		(width 0.088646)
		(layer "In11.Cu")
		(net "M_D_CPU1_SA_DQ<28>")
	)
	(arc
		(start 95.58655 -266.617704)
		(mid 95.312351 -266.693539)
		(end 95.035878 -266.62634)
		(width 0.088646)
		(layer "In11.Cu")
		(net "M_D_CPU1_SA_DQ<28>")
	)
	(arc
		(start 90.887296 -266.617704)
		(mid 90.604594 -266.69348)
		(end 90.321892 -266.617704)
		(width 0.088646)
		(layer "In11.Cu")
		(net "M_D_CPU1_SA_DQ<28>")
	)
	(arc
		(start 93.141546 -266.617704)
		(mid 92.954348 -266.567527)
		(end 92.76715 -266.617704)
		(width 0.088646)
		(layer "In11.Cu")
		(net "M_D_CPU1_SA_DQ<28>")
	)
	(arc
		(start 93.70695 -266.617704)
		(mid 93.432751 -266.693539)
		(end 93.156278 -266.62634)
		(width 0.088646)
		(layer "In11.Cu")
		(net "M_D_CPU1_SA_DQ<28>")
	)
	(arc
		(start 91.82735 -266.617704)
		(mid 91.550537 -266.693574)
		(end 91.272106 -266.6238)
		(width 0.088646)
		(layer "In11.Cu")
		(net "M_D_CPU1_SA_DQ<28>")
	)
	(arc
		(start 97.840292 -266.617704)
		(mid 97.653094 -266.567527)
		(end 97.465896 -266.617704)
		(width 0.088646)
		(layer "In11.Cu")
		(net "M_D_CPU1_SA_DQ<28>")
	)
	(arc
		(start 92.76715 -266.617704)
		(mid 92.492951 -266.693539)
		(end 92.216478 -266.62634)
		(width 0.088646)
		(layer "In11.Cu")
		(net "M_D_CPU1_SA_DQ<28>")
	)
	(arc
		(start 89.947496 -266.617704)
		(mid 89.664794 -266.69348)
		(end 89.382092 -266.617704)
		(width 0.088646)
		(layer "In11.Cu")
		(net "M_D_CPU1_SA_DQ<28>")
	)
	(arc
		(start 97.465896 -266.617704)
		(mid 97.189337 -266.693447)
		(end 96.91116 -266.6238)
		(width 0.088646)
		(layer "In11.Cu")
		(net "M_D_CPU1_SA_DQ<28>")
	)
	(arc
		(start 90.321892 -266.617704)
		(mid 90.134694 -266.567527)
		(end 89.947496 -266.617704)
		(width 0.088646)
		(layer "In11.Cu")
		(net "M_D_CPU1_SA_DQ<28>")
	)
	(arc
		(start 86.562692 -266.617704)
		(mid 86.375494 -266.567527)
		(end 86.188296 -266.617704)
		(width 0.088646)
		(layer "In11.Cu")
		(net "M_D_CPU1_SA_DQ<28>")
	)
	(arc
		(start 95.021146 -266.617704)
		(mid 94.833948 -266.567527)
		(end 94.64675 -266.617704)
		(width 0.088646)
		(layer "In11.Cu")
		(net "M_D_CPU1_SA_DQ<28>")
	)
	(arc
		(start 91.261692 -266.617704)
		(mid 91.074494 -266.567527)
		(end 90.887296 -266.617704)
		(width 0.088646)
		(layer "In11.Cu")
		(net "M_D_CPU1_SA_DQ<28>")
	)
	(arc
		(start 89.382092 -266.617704)
		(mid 89.194894 -266.567527)
		(end 89.007696 -266.617704)
		(width 0.088646)
		(layer "In11.Cu")
		(net "M_D_CPU1_SA_DQ<28>")
	)
	(segment
		(start 18.968212 -285.716726)
		(end 19.784314 -285.716726)
		(width 0.20066)
		(layer "F.Cu")
		(net "M_D_CPU1_SA_DQ<27>")
	)
	(segment
		(start 17.578578 -285.99257)
		(end 17.578578 -285.840932)
		(width 0.20066)
		(layer "F.Cu")
		(net "M_D_CPU1_SA_DQ<27>")
	)
	(segment
		(start 14.574266 -286.141668)
		(end 14.812264 -286.141668)
		(width 0.101854)
		(layer "F.Cu")
		(net "M_D_CPU1_SA_DQ<27>")
	)
	(segment
		(start 20.889214 -285.716726)
		(end 19.784314 -285.716726)
		(width 0.20066)
		(layer "F.Cu")
		(net "M_D_CPU1_SA_DQ<27>")
	)
	(segment
		(start 18.314162 -285.924244)
		(end 18.760694 -285.924244)
		(width 0.20066)
		(layer "F.Cu")
		(net "M_D_CPU1_SA_DQ<27>")
	)
	(segment
		(start 18.102326 -285.712408)
		(end 18.314162 -285.924244)
		(width 0.20066)
		(layer "F.Cu")
		(net "M_D_CPU1_SA_DQ<27>")
	)
	(segment
		(start 14.560042 -286.155892)
		(end 14.574266 -286.141668)
		(width 0.101854)
		(layer "F.Cu")
		(net "M_D_CPU1_SA_DQ<27>")
	)
	(segment
		(start 18.760694 -285.924244)
		(end 18.968212 -285.716726)
		(width 0.20066)
		(layer "F.Cu")
		(net "M_D_CPU1_SA_DQ<27>")
	)
	(segment
		(start 13.937742 -285.716726)
		(end 14.063726 -285.84271)
		(width 0.20066)
		(layer "F.Cu")
		(net "M_D_CPU1_SA_DQ<27>")
	)
	(segment
		(start 14.063726 -285.84271)
		(end 14.063726 -286.013398)
		(width 0.20066)
		(layer "F.Cu")
		(net "M_D_CPU1_SA_DQ<27>")
	)
	(segment
		(start 16.885158 -286.141668)
		(end 17.42948 -286.141668)
		(width 0.20066)
		(layer "F.Cu")
		(net "M_D_CPU1_SA_DQ<27>")
	)
	(segment
		(start 12.240514 -285.716726)
		(end 13.937742 -285.716726)
		(width 0.20066)
		(layer "F.Cu")
		(net "M_D_CPU1_SA_DQ<27>")
	)
	(segment
		(start 17.42948 -286.141668)
		(end 17.578578 -285.99257)
		(width 0.20066)
		(layer "F.Cu")
		(net "M_D_CPU1_SA_DQ<27>")
	)
	(segment
		(start 17.578578 -285.840932)
		(end 17.707102 -285.712408)
		(width 0.20066)
		(layer "F.Cu")
		(net "M_D_CPU1_SA_DQ<27>")
	)
	(segment
		(start 14.812264 -286.141668)
		(end 16.885158 -286.141668)
		(width 0.1016)
		(layer "F.Cu")
		(net "M_D_CPU1_SA_DQ<27>")
	)
	(segment
		(start 17.707102 -285.712408)
		(end 18.102326 -285.712408)
		(width 0.20066)
		(layer "F.Cu")
		(net "M_D_CPU1_SA_DQ<27>")
	)
	(segment
		(start 14.063726 -286.013398)
		(end 14.20622 -286.155892)
		(width 0.20066)
		(layer "F.Cu")
		(net "M_D_CPU1_SA_DQ<27>")
	)
	(segment
		(start 100.472748 -268.034008)
		(end 100.472748 -268.569694)
		(width 0.20066)
		(layer "F.Cu")
		(net "M_D_CPU1_SA_DQ<27>")
	)
	(segment
		(start 100.472494 -268.033754)
		(end 100.472748 -268.034008)
		(width 0.20066)
		(layer "F.Cu")
		(net "M_D_CPU1_SA_DQ<27>")
	)
	(segment
		(start 14.20622 -286.155892)
		(end 14.560042 -286.155892)
		(width 0.20066)
		(layer "F.Cu")
		(net "M_D_CPU1_SA_DQ<27>")
	)
	(segment
		(start 98.795078 -268.253972)
		(end 98.780346 -268.245336)
		(width 0.088646)
		(layer "In11.Cu")
		(net "M_D_CPU1_SA_DQ<27>")
	)
	(segment
		(start 63.143384 -282.680664)
		(end 62.296548 -283.5275)
		(width 0.18288)
		(layer "In11.Cu")
		(net "M_D_CPU1_SA_DQ<27>")
	)
	(segment
		(start 22.779736 -286.111696)
		(end 22.586696 -286.304736)
		(width 0.18288)
		(layer "In11.Cu")
		(net "M_D_CPU1_SA_DQ<27>")
	)
	(segment
		(start 95.592138 -268.897608)
		(end 95.586296 -268.894052)
		(width 0.088646)
		(layer "In11.Cu")
		(net "M_D_CPU1_SA_DQ<27>")
	)
	(segment
		(start 83.94446 -269.925292)
		(end 83.448398 -270.421354)
		(width 0.088646)
		(layer "In11.Cu")
		(net "M_D_CPU1_SA_DQ<27>")
	)
	(segment
		(start 26.94178 -285.115762)
		(end 26.94178 -285.358586)
		(width 0.18288)
		(layer "In11.Cu")
		(net "M_D_CPU1_SA_DQ<27>")
	)
	(segment
		(start 51.015138 -286.14116)
		(end 51.013614 -286.142684)
		(width 0.18288)
		(layer "In11.Cu")
		(net "M_D_CPU1_SA_DQ<27>")
	)
	(segment
		(start 36.033202 -286.142684)
		(end 36.031678 -286.14116)
		(width 0.18288)
		(layer "In11.Cu")
		(net "M_D_CPU1_SA_DQ<27>")
	)
	(segment
		(start 38.409118 -285.221426)
		(end 37.374576 -286.255968)
		(width 0.18288)
		(layer "In11.Cu")
		(net "M_D_CPU1_SA_DQ<27>")
	)
	(segment
		(start 95.586296 -268.894052)
		(end 95.580454 -268.89075)
		(width 0.088646)
		(layer "In11.Cu")
		(net "M_D_CPU1_SA_DQ<27>")
	)
	(segment
		(start 66.933572 -281.885644)
		(end 63.494412 -281.885644)
		(width 0.18288)
		(layer "In11.Cu")
		(net "M_D_CPU1_SA_DQ<27>")
	)
	(segment
		(start 23.673816 -286.304736)
		(end 23.480776 -286.111696)
		(width 0.18288)
		(layer "In11.Cu")
		(net "M_D_CPU1_SA_DQ<27>")
	)
	(segment
		(start 47.248318 -286.992568)
		(end 45.661326 -286.992568)
		(width 0.18288)
		(layer "In11.Cu")
		(net "M_D_CPU1_SA_DQ<27>")
	)
	(segment
		(start 45.388784 -286.720026)
		(end 44.759626 -286.720026)
		(width 0.18288)
		(layer "In11.Cu")
		(net "M_D_CPU1_SA_DQ<27>")
	)
	(segment
		(start 51.726084 -286.142684)
		(end 51.118262 -286.142684)
		(width 0.18288)
		(layer "In11.Cu")
		(net "M_D_CPU1_SA_DQ<27>")
	)
	(segment
		(start 29.570426 -286.593026)
		(end 28.529026 -285.551626)
		(width 0.18288)
		(layer "In11.Cu")
		(net "M_D_CPU1_SA_DQ<27>")
	)
	(segment
		(start 21.477224 -286.304736)
		(end 20.889214 -285.716726)
		(width 0.18288)
		(layer "In11.Cu")
		(net "M_D_CPU1_SA_DQ<27>")
	)
	(segment
		(start 49.307242 -287.056068)
		(end 47.311818 -287.056068)
		(width 0.18288)
		(layer "In11.Cu")
		(net "M_D_CPU1_SA_DQ<27>")
	)
	(segment
		(start 44.759626 -286.720026)
		(end 43.616626 -285.577026)
		(width 0.18288)
		(layer "In11.Cu")
		(net "M_D_CPU1_SA_DQ<27>")
	)
	(segment
		(start 27.64282 -285.358586)
		(end 27.64282 -285.115762)
		(width 0.18288)
		(layer "In11.Cu")
		(net "M_D_CPU1_SA_DQ<27>")
	)
	(segment
		(start 56.764682 -283.748226)
		(end 55.951882 -284.561026)
		(width 0.18288)
		(layer "In11.Cu")
		(net "M_D_CPU1_SA_DQ<27>")
	)
	(segment
		(start 53.040026 -285.678626)
		(end 52.430426 -286.288226)
		(width 0.18288)
		(layer "In11.Cu")
		(net "M_D_CPU1_SA_DQ<27>")
	)
	(segment
		(start 96.531938 -268.897608)
		(end 96.526096 -268.894052)
		(width 0.088646)
		(layer "In11.Cu")
		(net "M_D_CPU1_SA_DQ<27>")
	)
	(segment
		(start 24.499316 -286.304736)
		(end 23.673816 -286.304736)
		(width 0.18288)
		(layer "In11.Cu")
		(net "M_D_CPU1_SA_DQ<27>")
	)
	(segment
		(start 36.740084 -286.142684)
		(end 36.033202 -286.142684)
		(width 0.18288)
		(layer "In11.Cu")
		(net "M_D_CPU1_SA_DQ<27>")
	)
	(segment
		(start 52.430426 -286.288226)
		(end 51.871626 -286.288226)
		(width 0.18288)
		(layer "In11.Cu")
		(net "M_D_CPU1_SA_DQ<27>")
	)
	(segment
		(start 51.116738 -286.14116)
		(end 51.015138 -286.14116)
		(width 0.18288)
		(layer "In11.Cu")
		(net "M_D_CPU1_SA_DQ<27>")
	)
	(segment
		(start 42.744136 -285.06801)
		(end 42.551096 -284.87497)
		(width 0.18288)
		(layer "In11.Cu")
		(net "M_D_CPU1_SA_DQ<27>")
	)
	(segment
		(start 53.040026 -285.272226)
		(end 53.040026 -285.678626)
		(width 0.18288)
		(layer "In11.Cu")
		(net "M_D_CPU1_SA_DQ<27>")
	)
	(segment
		(start 97.465896 -268.894052)
		(end 97.460054 -268.89075)
		(width 0.088646)
		(layer "In11.Cu")
		(net "M_D_CPU1_SA_DQ<27>")
	)
	(segment
		(start 27.13482 -284.922722)
		(end 26.94178 -285.115762)
		(width 0.18288)
		(layer "In11.Cu")
		(net "M_D_CPU1_SA_DQ<27>")
	)
	(segment
		(start 43.616626 -285.577026)
		(end 42.937176 -285.577026)
		(width 0.18288)
		(layer "In11.Cu")
		(net "M_D_CPU1_SA_DQ<27>")
	)
	(segment
		(start 93.712538 -268.897608)
		(end 93.706696 -268.894052)
		(width 0.088646)
		(layer "In11.Cu")
		(net "M_D_CPU1_SA_DQ<27>")
	)
	(segment
		(start 83.448398 -270.421354)
		(end 82.963004 -270.421354)
		(width 0.088646)
		(layer "In11.Cu")
		(net "M_D_CPU1_SA_DQ<27>")
	)
	(segment
		(start 84.495894 -268.944598)
		(end 84.39277 -268.944598)
		(width 0.088646)
		(layer "In11.Cu")
		(net "M_D_CPU1_SA_DQ<27>")
	)
	(segment
		(start 32.243776 -287.075626)
		(end 32.160718 -286.992568)
		(width 0.18288)
		(layer "In11.Cu")
		(net "M_D_CPU1_SA_DQ<27>")
	)
	(segment
		(start 35.919918 -286.14116)
		(end 35.918394 -286.142684)
		(width 0.18288)
		(layer "In11.Cu")
		(net "M_D_CPU1_SA_DQ<27>")
	)
	(segment
		(start 36.031678 -286.14116)
		(end 35.919918 -286.14116)
		(width 0.18288)
		(layer "In11.Cu")
		(net "M_D_CPU1_SA_DQ<27>")
	)
	(segment
		(start 26.74874 -285.551626)
		(end 25.709626 -285.551626)
		(width 0.18288)
		(layer "In11.Cu")
		(net "M_D_CPU1_SA_DQ<27>")
	)
	(segment
		(start 24.973026 -285.831026)
		(end 24.499316 -286.304736)
		(width 0.18288)
		(layer "In11.Cu")
		(net "M_D_CPU1_SA_DQ<27>")
	)
	(segment
		(start 97.471738 -268.897608)
		(end 97.465896 -268.894052)
		(width 0.088646)
		(layer "In11.Cu")
		(net "M_D_CPU1_SA_DQ<27>")
	)
	(segment
		(start 27.83586 -285.551626)
		(end 27.64282 -285.358586)
		(width 0.18288)
		(layer "In11.Cu")
		(net "M_D_CPU1_SA_DQ<27>")
	)
	(segment
		(start 25.430226 -285.831026)
		(end 24.973026 -285.831026)
		(width 0.18288)
		(layer "In11.Cu")
		(net "M_D_CPU1_SA_DQ<27>")
	)
	(segment
		(start 23.480776 -285.72333)
		(end 23.287736 -285.53029)
		(width 0.18288)
		(layer "In11.Cu")
		(net "M_D_CPU1_SA_DQ<27>")
	)
	(segment
		(start 47.311818 -287.056068)
		(end 47.248318 -286.992568)
		(width 0.18288)
		(layer "In11.Cu")
		(net "M_D_CPU1_SA_DQ<27>")
	)
	(segment
		(start 27.44978 -284.922722)
		(end 27.13482 -284.922722)
		(width 0.18288)
		(layer "In11.Cu")
		(net "M_D_CPU1_SA_DQ<27>")
	)
	(segment
		(start 90.332306 -268.887956)
		(end 90.321892 -268.894052)
		(width 0.088646)
		(layer "In11.Cu")
		(net "M_D_CPU1_SA_DQ<27>")
	)
	(segment
		(start 35.918394 -286.142684)
		(end 35.075368 -286.142684)
		(width 0.18288)
		(layer "In11.Cu")
		(net "M_D_CPU1_SA_DQ<27>")
	)
	(segment
		(start 100.472748 -268.569694)
		(end 100.217732 -268.569694)
		(width 0.088646)
		(layer "In11.Cu")
		(net "M_D_CPU1_SA_DQ<27>")
	)
	(segment
		(start 51.871626 -286.288226)
		(end 51.726084 -286.142684)
		(width 0.18288)
		(layer "In11.Cu")
		(net "M_D_CPU1_SA_DQ<27>")
	)
	(segment
		(start 22.779736 -285.72333)
		(end 22.779736 -286.111696)
		(width 0.18288)
		(layer "In11.Cu")
		(net "M_D_CPU1_SA_DQ<27>")
	)
	(segment
		(start 23.480776 -286.111696)
		(end 23.480776 -285.72333)
		(width 0.18288)
		(layer "In11.Cu")
		(net "M_D_CPU1_SA_DQ<27>")
	)
	(segment
		(start 50.220626 -286.142684)
		(end 49.307242 -287.056068)
		(width 0.18288)
		(layer "In11.Cu")
		(net "M_D_CPU1_SA_DQ<27>")
	)
	(segment
		(start 22.972776 -285.53029)
		(end 22.779736 -285.72333)
		(width 0.18288)
		(layer "In11.Cu")
		(net "M_D_CPU1_SA_DQ<27>")
	)
	(segment
		(start 51.118262 -286.142684)
		(end 51.116738 -286.14116)
		(width 0.18288)
		(layer "In11.Cu")
		(net "M_D_CPU1_SA_DQ<27>")
	)
	(segment
		(start 32.160718 -286.992568)
		(end 30.757368 -286.992568)
		(width 0.18288)
		(layer "In11.Cu")
		(net "M_D_CPU1_SA_DQ<27>")
	)
	(segment
		(start 42.744136 -285.383986)
		(end 42.744136 -285.06801)
		(width 0.18288)
		(layer "In11.Cu")
		(net "M_D_CPU1_SA_DQ<27>")
	)
	(segment
		(start 94.652338 -268.897608)
		(end 94.646496 -268.894052)
		(width 0.088646)
		(layer "In11.Cu")
		(net "M_D_CPU1_SA_DQ<27>")
	)
	(segment
		(start 42.551096 -284.87497)
		(end 42.236136 -284.87497)
		(width 0.18288)
		(layer "In11.Cu")
		(net "M_D_CPU1_SA_DQ<27>")
	)
	(segment
		(start 42.043096 -285.383986)
		(end 41.850056 -285.577026)
		(width 0.18288)
		(layer "In11.Cu")
		(net "M_D_CPU1_SA_DQ<27>")
	)
	(segment
		(start 92.216478 -268.885416)
		(end 92.201746 -268.894052)
		(width 0.088646)
		(layer "In11.Cu")
		(net "M_D_CPU1_SA_DQ<27>")
	)
	(segment
		(start 51.013614 -286.142684)
		(end 50.220626 -286.142684)
		(width 0.18288)
		(layer "In11.Cu")
		(net "M_D_CPU1_SA_DQ<27>")
	)
	(segment
		(start 42.236136 -284.87497)
		(end 42.043096 -285.06801)
		(width 0.18288)
		(layer "In11.Cu")
		(net "M_D_CPU1_SA_DQ<27>")
	)
	(segment
		(start 23.287736 -285.53029)
		(end 22.972776 -285.53029)
		(width 0.18288)
		(layer "In11.Cu")
		(net "M_D_CPU1_SA_DQ<27>")
	)
	(segment
		(start 98.40595 -268.245336)
		(end 98.354388 -268.275054)
		(width 0.088646)
		(layer "In11.Cu")
		(net "M_D_CPU1_SA_DQ<27>")
	)
	(segment
		(start 37.374576 -286.255968)
		(end 36.853368 -286.255968)
		(width 0.18288)
		(layer "In11.Cu")
		(net "M_D_CPU1_SA_DQ<27>")
	)
	(segment
		(start 30.757368 -286.992568)
		(end 30.357826 -286.593026)
		(width 0.18288)
		(layer "In11.Cu")
		(net "M_D_CPU1_SA_DQ<27>")
	)
	(segment
		(start 63.494412 -281.885644)
		(end 63.143384 -282.236672)
		(width 0.18288)
		(layer "In11.Cu")
		(net "M_D_CPU1_SA_DQ<27>")
	)
	(segment
		(start 26.94178 -285.358586)
		(end 26.74874 -285.551626)
		(width 0.18288)
		(layer "In11.Cu")
		(net "M_D_CPU1_SA_DQ<27>")
	)
	(segment
		(start 35.075368 -286.142684)
		(end 34.142426 -287.075626)
		(width 0.18288)
		(layer "In11.Cu")
		(net "M_D_CPU1_SA_DQ<27>")
	)
	(segment
		(start 30.357826 -286.593026)
		(end 29.570426 -286.593026)
		(width 0.18288)
		(layer "In11.Cu")
		(net "M_D_CPU1_SA_DQ<27>")
	)
	(segment
		(start 40.492426 -285.221426)
		(end 38.409118 -285.221426)
		(width 0.18288)
		(layer "In11.Cu")
		(net "M_D_CPU1_SA_DQ<27>")
	)
	(segment
		(start 28.529026 -285.551626)
		(end 27.83586 -285.551626)
		(width 0.18288)
		(layer "In11.Cu")
		(net "M_D_CPU1_SA_DQ<27>")
	)
	(segment
		(start 98.19386 -268.471904)
		(end 98.161094 -268.570456)
		(width 0.088646)
		(layer "In11.Cu")
		(net "M_D_CPU1_SA_DQ<27>")
	)
	(segment
		(start 63.143384 -282.236672)
		(end 63.143384 -282.680664)
		(width 0.18288)
		(layer "In11.Cu")
		(net "M_D_CPU1_SA_DQ<27>")
	)
	(segment
		(start 96.526096 -268.894052)
		(end 96.520254 -268.89075)
		(width 0.088646)
		(layer "In11.Cu")
		(net "M_D_CPU1_SA_DQ<27>")
	)
	(segment
		(start 78.397862 -270.421354)
		(end 66.933572 -281.885644)
		(width 0.18288)
		(layer "In11.Cu")
		(net "M_D_CPU1_SA_DQ<27>")
	)
	(segment
		(start 84.39277 -268.944598)
		(end 83.94446 -269.392908)
		(width 0.088646)
		(layer "In11.Cu")
		(net "M_D_CPU1_SA_DQ<27>")
	)
	(segment
		(start 27.64282 -285.115762)
		(end 27.44978 -284.922722)
		(width 0.18288)
		(layer "In11.Cu")
		(net "M_D_CPU1_SA_DQ<27>")
	)
	(segment
		(start 99.729036 -268.250416)
		(end 99.720146 -268.245336)
		(width 0.088646)
		(layer "In11.Cu")
		(net "M_D_CPU1_SA_DQ<27>")
	)
	(segment
		(start 41.850056 -285.577026)
		(end 40.848026 -285.577026)
		(width 0.18288)
		(layer "In11.Cu")
		(net "M_D_CPU1_SA_DQ<27>")
	)
	(segment
		(start 53.751226 -284.561026)
		(end 53.040026 -285.272226)
		(width 0.18288)
		(layer "In11.Cu")
		(net "M_D_CPU1_SA_DQ<27>")
	)
	(segment
		(start 42.043096 -285.06801)
		(end 42.043096 -285.383986)
		(width 0.18288)
		(layer "In11.Cu")
		(net "M_D_CPU1_SA_DQ<27>")
	)
	(segment
		(start 55.951882 -284.561026)
		(end 53.751226 -284.561026)
		(width 0.18288)
		(layer "In11.Cu")
		(net "M_D_CPU1_SA_DQ<27>")
	)
	(segment
		(start 45.661326 -286.992568)
		(end 45.388784 -286.720026)
		(width 0.18288)
		(layer "In11.Cu")
		(net "M_D_CPU1_SA_DQ<27>")
	)
	(segment
		(start 82.963004 -270.421354)
		(end 78.397862 -270.421354)
		(width 0.18288)
		(layer "In11.Cu")
		(net "M_D_CPU1_SA_DQ<27>")
	)
	(segment
		(start 61.76391 -283.748226)
		(end 56.764682 -283.748226)
		(width 0.18288)
		(layer "In11.Cu")
		(net "M_D_CPU1_SA_DQ<27>")
	)
	(segment
		(start 25.709626 -285.551626)
		(end 25.430226 -285.831026)
		(width 0.18288)
		(layer "In11.Cu")
		(net "M_D_CPU1_SA_DQ<27>")
	)
	(segment
		(start 34.142426 -287.075626)
		(end 32.243776 -287.075626)
		(width 0.18288)
		(layer "In11.Cu")
		(net "M_D_CPU1_SA_DQ<27>")
	)
	(segment
		(start 36.853368 -286.255968)
		(end 36.740084 -286.142684)
		(width 0.18288)
		(layer "In11.Cu")
		(net "M_D_CPU1_SA_DQ<27>")
	)
	(segment
		(start 40.848026 -285.577026)
		(end 40.492426 -285.221426)
		(width 0.18288)
		(layer "In11.Cu")
		(net "M_D_CPU1_SA_DQ<27>")
	)
	(segment
		(start 93.706696 -268.894052)
		(end 93.700854 -268.89075)
		(width 0.088646)
		(layer "In11.Cu")
		(net "M_D_CPU1_SA_DQ<27>")
	)
	(segment
		(start 62.296548 -283.5275)
		(end 61.76391 -283.748226)
		(width 0.18288)
		(layer "In11.Cu")
		(net "M_D_CPU1_SA_DQ<27>")
	)
	(segment
		(start 83.94446 -269.392908)
		(end 83.94446 -269.925292)
		(width 0.088646)
		(layer "In11.Cu")
		(net "M_D_CPU1_SA_DQ<27>")
	)
	(segment
		(start 94.646496 -268.894052)
		(end 94.640654 -268.89075)
		(width 0.088646)
		(layer "In11.Cu")
		(net "M_D_CPU1_SA_DQ<27>")
	)
	(segment
		(start 42.937176 -285.577026)
		(end 42.744136 -285.383986)
		(width 0.18288)
		(layer "In11.Cu")
		(net "M_D_CPU1_SA_DQ<27>")
	)
	(segment
		(start 22.586696 -286.304736)
		(end 21.477224 -286.304736)
		(width 0.18288)
		(layer "In11.Cu")
		(net "M_D_CPU1_SA_DQ<27>")
	)
	(arc
		(start 92.76715 -268.894052)
		(mid 92.492951 -268.818217)
		(end 92.216478 -268.885416)
		(width 0.088646)
		(layer "In11.Cu")
		(net "M_D_CPU1_SA_DQ<27>")
	)
	(arc
		(start 95.580454 -268.89075)
		(mid 95.300349 -268.818308)
		(end 95.021146 -268.894052)
		(width 0.088646)
		(layer "In11.Cu")
		(net "M_D_CPU1_SA_DQ<27>")
	)
	(arc
		(start 94.640654 -268.89075)
		(mid 94.360549 -268.818308)
		(end 94.081346 -268.894052)
		(width 0.088646)
		(layer "In11.Cu")
		(net "M_D_CPU1_SA_DQ<27>")
	)
	(arc
		(start 89.947496 -268.894052)
		(mid 89.664794 -268.818276)
		(end 89.382092 -268.894052)
		(width 0.088646)
		(layer "In11.Cu")
		(net "M_D_CPU1_SA_DQ<27>")
	)
	(arc
		(start 88.067896 -268.894052)
		(mid 87.785194 -268.818276)
		(end 87.502492 -268.894052)
		(width 0.088646)
		(layer "In11.Cu")
		(net "M_D_CPU1_SA_DQ<27>")
	)
	(arc
		(start 86.562692 -268.894052)
		(mid 86.375494 -268.944195)
		(end 86.188296 -268.894052)
		(width 0.088646)
		(layer "In11.Cu")
		(net "M_D_CPU1_SA_DQ<27>")
	)
	(arc
		(start 90.88755 -268.894052)
		(mid 90.610737 -268.818182)
		(end 90.332306 -268.887956)
		(width 0.088646)
		(layer "In11.Cu")
		(net "M_D_CPU1_SA_DQ<27>")
	)
	(arc
		(start 99.848162 -268.36751)
		(mid 99.795197 -268.302254)
		(end 99.729036 -268.250416)
		(width 0.088646)
		(layer "In11.Cu")
		(net "M_D_CPU1_SA_DQ<27>")
	)
	(arc
		(start 89.007696 -268.894052)
		(mid 88.724994 -268.818276)
		(end 88.442292 -268.894052)
		(width 0.088646)
		(layer "In11.Cu")
		(net "M_D_CPU1_SA_DQ<27>")
	)
	(arc
		(start 93.700854 -268.89075)
		(mid 93.420749 -268.818308)
		(end 93.141546 -268.894052)
		(width 0.088646)
		(layer "In11.Cu")
		(net "M_D_CPU1_SA_DQ<27>")
	)
	(arc
		(start 85.622892 -268.894052)
		(mid 85.435694 -268.944195)
		(end 85.248496 -268.894052)
		(width 0.088646)
		(layer "In11.Cu")
		(net "M_D_CPU1_SA_DQ<27>")
	)
	(arc
		(start 98.354388 -268.275054)
		(mid 98.256067 -268.358746)
		(end 98.19386 -268.471904)
		(width 0.088646)
		(layer "In11.Cu")
		(net "M_D_CPU1_SA_DQ<27>")
	)
	(arc
		(start 85.248496 -268.894052)
		(mid 84.965794 -268.818276)
		(end 84.683092 -268.894052)
		(width 0.088646)
		(layer "In11.Cu")
		(net "M_D_CPU1_SA_DQ<27>")
	)
	(arc
		(start 93.141546 -268.894052)
		(mid 92.954348 -268.944195)
		(end 92.76715 -268.894052)
		(width 0.088646)
		(layer "In11.Cu")
		(net "M_D_CPU1_SA_DQ<27>")
	)
	(arc
		(start 96.520254 -268.89075)
		(mid 96.240149 -268.818308)
		(end 95.960946 -268.894052)
		(width 0.088646)
		(layer "In11.Cu")
		(net "M_D_CPU1_SA_DQ<27>")
	)
	(arc
		(start 97.460054 -268.89075)
		(mid 97.179949 -268.818308)
		(end 96.900746 -268.894052)
		(width 0.088646)
		(layer "In11.Cu")
		(net "M_D_CPU1_SA_DQ<27>")
	)
	(arc
		(start 98.069908 -268.718284)
		(mid 97.960988 -268.813686)
		(end 97.840546 -268.894052)
		(width 0.088646)
		(layer "In11.Cu")
		(net "M_D_CPU1_SA_DQ<27>")
	)
	(arc
		(start 99.34575 -268.245336)
		(mid 99.071551 -268.321171)
		(end 98.795078 -268.253972)
		(width 0.088646)
		(layer "In11.Cu")
		(net "M_D_CPU1_SA_DQ<27>")
	)
	(arc
		(start 96.900746 -268.894052)
		(mid 96.716822 -268.944306)
		(end 96.531938 -268.897608)
		(width 0.088646)
		(layer "In11.Cu")
		(net "M_D_CPU1_SA_DQ<27>")
	)
	(arc
		(start 86.188296 -268.894052)
		(mid 85.905594 -268.818276)
		(end 85.622892 -268.894052)
		(width 0.088646)
		(layer "In11.Cu")
		(net "M_D_CPU1_SA_DQ<27>")
	)
	(arc
		(start 89.382092 -268.894052)
		(mid 89.194894 -268.944195)
		(end 89.007696 -268.894052)
		(width 0.088646)
		(layer "In11.Cu")
		(net "M_D_CPU1_SA_DQ<27>")
	)
	(arc
		(start 99.720146 -268.245336)
		(mid 99.532948 -268.195193)
		(end 99.34575 -268.245336)
		(width 0.088646)
		(layer "In11.Cu")
		(net "M_D_CPU1_SA_DQ<27>")
	)
	(arc
		(start 91.82735 -268.894052)
		(mid 91.544648 -268.818276)
		(end 91.261946 -268.894052)
		(width 0.088646)
		(layer "In11.Cu")
		(net "M_D_CPU1_SA_DQ<27>")
	)
	(arc
		(start 100.217732 -268.569694)
		(mid 100.007124 -268.515828)
		(end 99.848162 -268.36751)
		(width 0.088646)
		(layer "In11.Cu")
		(net "M_D_CPU1_SA_DQ<27>")
	)
	(arc
		(start 90.321892 -268.894052)
		(mid 90.134694 -268.944195)
		(end 89.947496 -268.894052)
		(width 0.088646)
		(layer "In11.Cu")
		(net "M_D_CPU1_SA_DQ<27>")
	)
	(arc
		(start 98.780346 -268.245336)
		(mid 98.593148 -268.195193)
		(end 98.40595 -268.245336)
		(width 0.088646)
		(layer "In11.Cu")
		(net "M_D_CPU1_SA_DQ<27>")
	)
	(arc
		(start 87.502492 -268.894052)
		(mid 87.315294 -268.944195)
		(end 87.128096 -268.894052)
		(width 0.088646)
		(layer "In11.Cu")
		(net "M_D_CPU1_SA_DQ<27>")
	)
	(arc
		(start 91.261946 -268.894052)
		(mid 91.074748 -268.944195)
		(end 90.88755 -268.894052)
		(width 0.088646)
		(layer "In11.Cu")
		(net "M_D_CPU1_SA_DQ<27>")
	)
	(arc
		(start 95.960946 -268.894052)
		(mid 95.777022 -268.944306)
		(end 95.592138 -268.897608)
		(width 0.088646)
		(layer "In11.Cu")
		(net "M_D_CPU1_SA_DQ<27>")
	)
	(arc
		(start 88.442292 -268.894052)
		(mid 88.255094 -268.944195)
		(end 88.067896 -268.894052)
		(width 0.088646)
		(layer "In11.Cu")
		(net "M_D_CPU1_SA_DQ<27>")
	)
	(arc
		(start 97.840546 -268.894052)
		(mid 97.656622 -268.944306)
		(end 97.471738 -268.897608)
		(width 0.088646)
		(layer "In11.Cu")
		(net "M_D_CPU1_SA_DQ<27>")
	)
	(arc
		(start 84.683092 -268.894052)
		(mid 84.59282 -268.931651)
		(end 84.495894 -268.944598)
		(width 0.088646)
		(layer "In11.Cu")
		(net "M_D_CPU1_SA_DQ<27>")
	)
	(arc
		(start 92.201746 -268.894052)
		(mid 92.014548 -268.944195)
		(end 91.82735 -268.894052)
		(width 0.088646)
		(layer "In11.Cu")
		(net "M_D_CPU1_SA_DQ<27>")
	)
	(arc
		(start 87.128096 -268.894052)
		(mid 86.845394 -268.818276)
		(end 86.562692 -268.894052)
		(width 0.088646)
		(layer "In11.Cu")
		(net "M_D_CPU1_SA_DQ<27>")
	)
	(arc
		(start 94.081346 -268.894052)
		(mid 93.897422 -268.944306)
		(end 93.712538 -268.897608)
		(width 0.088646)
		(layer "In11.Cu")
		(net "M_D_CPU1_SA_DQ<27>")
	)
	(arc
		(start 98.161094 -268.570456)
		(mid 98.124104 -268.649672)
		(end 98.069908 -268.718284)
		(width 0.088646)
		(layer "In11.Cu")
		(net "M_D_CPU1_SA_DQ<27>")
	)
	(arc
		(start 95.021146 -268.894052)
		(mid 94.837222 -268.944306)
		(end 94.652338 -268.897608)
		(width 0.088646)
		(layer "In11.Cu")
		(net "M_D_CPU1_SA_DQ<27>")
	)
	(segment
		(start 16.885158 -286.991806)
		(end 17.518126 -286.991806)
		(width 0.20066)
		(layer "F.Cu")
		(net "M_D_CPU1_SA_DQ<26>")
	)
	(segment
		(start 17.66189 -287.461198)
		(end 17.829276 -287.628584)
		(width 0.20066)
		(layer "F.Cu")
		(net "M_D_CPU1_SA_DQ<26>")
	)
	(segment
		(start 14.825218 -286.991806)
		(end 16.885158 -286.991806)
		(width 0.1016)
		(layer "F.Cu")
		(net "M_D_CPU1_SA_DQ<26>")
	)
	(segment
		(start 13.387578 -287.416748)
		(end 13.82268 -286.981646)
		(width 0.20066)
		(layer "F.Cu")
		(net "M_D_CPU1_SA_DQ<26>")
	)
	(segment
		(start 18.46961 -287.416748)
		(end 19.784314 -287.416748)
		(width 0.20066)
		(layer "F.Cu")
		(net "M_D_CPU1_SA_DQ<26>")
	)
	(segment
		(start 14.570202 -286.991806)
		(end 14.825218 -286.991806)
		(width 0.101854)
		(layer "F.Cu")
		(net "M_D_CPU1_SA_DQ<26>")
	)
	(segment
		(start 19.784314 -287.416748)
		(end 20.889214 -287.416748)
		(width 0.20066)
		(layer "F.Cu")
		(net "M_D_CPU1_SA_DQ<26>")
	)
	(segment
		(start 13.82268 -286.981646)
		(end 14.560042 -286.981646)
		(width 0.20066)
		(layer "F.Cu")
		(net "M_D_CPU1_SA_DQ<26>")
	)
	(segment
		(start 14.560042 -286.981646)
		(end 14.570202 -286.991806)
		(width 0.101854)
		(layer "F.Cu")
		(net "M_D_CPU1_SA_DQ<26>")
	)
	(segment
		(start 17.518126 -286.991806)
		(end 17.66189 -287.13557)
		(width 0.20066)
		(layer "F.Cu")
		(net "M_D_CPU1_SA_DQ<26>")
	)
	(segment
		(start 17.66189 -287.13557)
		(end 17.66189 -287.461198)
		(width 0.20066)
		(layer "F.Cu")
		(net "M_D_CPU1_SA_DQ<26>")
	)
	(segment
		(start 18.257774 -287.628584)
		(end 18.46961 -287.416748)
		(width 0.20066)
		(layer "F.Cu")
		(net "M_D_CPU1_SA_DQ<26>")
	)
	(segment
		(start 17.829276 -287.628584)
		(end 18.257774 -287.628584)
		(width 0.20066)
		(layer "F.Cu")
		(net "M_D_CPU1_SA_DQ<26>")
	)
	(segment
		(start 100.002594 -268.847824)
		(end 100.002594 -269.38351)
		(width 0.20066)
		(layer "F.Cu")
		(net "M_D_CPU1_SA_DQ<26>")
	)
	(segment
		(start 12.240514 -287.416748)
		(end 13.387578 -287.416748)
		(width 0.20066)
		(layer "F.Cu")
		(net "M_D_CPU1_SA_DQ<26>")
	)
	(segment
		(start 100.002848 -268.84757)
		(end 100.002594 -268.847824)
		(width 0.20066)
		(layer "F.Cu")
		(net "M_D_CPU1_SA_DQ<26>")
	)
	(segment
		(start 35.23107 -287.841182)
		(end 34.244026 -288.828226)
		(width 0.18288)
		(layer "In11.Cu")
		(net "M_D_CPU1_SA_DQ<26>")
	)
	(segment
		(start 84.374736 -270.29791)
		(end 83.235292 -271.437354)
		(width 0.088646)
		(layer "In11.Cu")
		(net "M_D_CPU1_SA_DQ<26>")
	)
	(segment
		(start 28.148026 -288.777426)
		(end 27.030426 -287.659826)
		(width 0.18288)
		(layer "In11.Cu")
		(net "M_D_CPU1_SA_DQ<26>")
	)
	(segment
		(start 25.201626 -287.659826)
		(end 24.92629 -287.935162)
		(width 0.18288)
		(layer "In11.Cu")
		(net "M_D_CPU1_SA_DQ<26>")
	)
	(segment
		(start 98.529902 -269.269972)
		(end 98.48977 -269.460726)
		(width 0.088646)
		(layer "In11.Cu")
		(net "M_D_CPU1_SA_DQ<26>")
	)
	(segment
		(start 94.176596 -269.707868)
		(end 94.161864 -269.699232)
		(width 0.088646)
		(layer "In11.Cu")
		(net "M_D_CPU1_SA_DQ<26>")
	)
	(segment
		(start 40.183562 -287.466786)
		(end 39.678356 -287.971992)
		(width 0.18288)
		(layer "In11.Cu")
		(net "M_D_CPU1_SA_DQ<26>")
	)
	(segment
		(start 84.601812 -269.535656)
		(end 84.374736 -269.762732)
		(width 0.088646)
		(layer "In11.Cu")
		(net "M_D_CPU1_SA_DQ<26>")
	)
	(segment
		(start 51.71821 -287.91281)
		(end 51.648106 -287.842706)
		(width 0.18288)
		(layer "In11.Cu")
		(net "M_D_CPU1_SA_DQ<26>")
	)
	(segment
		(start 61.999622 -284.764226)
		(end 59.331098 -284.764226)
		(width 0.18288)
		(layer "In11.Cu")
		(net "M_D_CPU1_SA_DQ<26>")
	)
	(segment
		(start 95.116396 -269.707868)
		(end 95.101664 -269.699232)
		(width 0.088646)
		(layer "In11.Cu")
		(net "M_D_CPU1_SA_DQ<26>")
	)
	(segment
		(start 38.642544 -287.778952)
		(end 38.642544 -287.455102)
		(width 0.18288)
		(layer "In11.Cu")
		(net "M_D_CPU1_SA_DQ<26>")
	)
	(segment
		(start 40.884602 -287.151064)
		(end 40.691562 -286.958024)
		(width 0.18288)
		(layer "In11.Cu")
		(net "M_D_CPU1_SA_DQ<26>")
	)
	(segment
		(start 41.077642 -287.659826)
		(end 40.884602 -287.466786)
		(width 0.18288)
		(layer "In11.Cu")
		(net "M_D_CPU1_SA_DQ<26>")
	)
	(segment
		(start 78.824074 -271.437354)
		(end 66.801238 -283.46019)
		(width 0.18288)
		(layer "In11.Cu")
		(net "M_D_CPU1_SA_DQ<26>")
	)
	(segment
		(start 58.735214 -285.36011)
		(end 57.562242 -285.36011)
		(width 0.18288)
		(layer "In11.Cu")
		(net "M_D_CPU1_SA_DQ<26>")
	)
	(segment
		(start 43.15333 -288.777426)
		(end 42.931842 -288.555938)
		(width 0.18288)
		(layer "In11.Cu")
		(net "M_D_CPU1_SA_DQ<26>")
	)
	(segment
		(start 96.995996 -269.707868)
		(end 96.981264 -269.699232)
		(width 0.088646)
		(layer "In11.Cu")
		(net "M_D_CPU1_SA_DQ<26>")
	)
	(segment
		(start 56.875426 -286.046926)
		(end 54.906926 -286.046926)
		(width 0.18288)
		(layer "In11.Cu")
		(net "M_D_CPU1_SA_DQ<26>")
	)
	(segment
		(start 96.056196 -269.707868)
		(end 96.041464 -269.699232)
		(width 0.088646)
		(layer "In11.Cu")
		(net "M_D_CPU1_SA_DQ<26>")
	)
	(segment
		(start 41.585642 -287.151064)
		(end 41.585642 -287.466786)
		(width 0.18288)
		(layer "In11.Cu")
		(net "M_D_CPU1_SA_DQ<26>")
	)
	(segment
		(start 100.002594 -269.38351)
		(end 99.647756 -269.288514)
		(width 0.088646)
		(layer "In11.Cu")
		(net "M_D_CPU1_SA_DQ<26>")
	)
	(segment
		(start 42.479722 -287.659826)
		(end 42.286682 -287.466786)
		(width 0.18288)
		(layer "In11.Cu")
		(net "M_D_CPU1_SA_DQ<26>")
	)
	(segment
		(start 46.150784 -288.523426)
		(end 44.124626 -288.523426)
		(width 0.18288)
		(layer "In11.Cu")
		(net "M_D_CPU1_SA_DQ<26>")
	)
	(segment
		(start 38.134544 -287.262062)
		(end 37.941504 -287.455102)
		(width 0.18288)
		(layer "In11.Cu")
		(net "M_D_CPU1_SA_DQ<26>")
	)
	(segment
		(start 91.74226 -269.701772)
		(end 91.731846 -269.707868)
		(width 0.088646)
		(layer "In11.Cu")
		(net "M_D_CPU1_SA_DQ<26>")
	)
	(segment
		(start 42.931842 -288.555938)
		(end 42.931842 -287.921954)
		(width 0.18288)
		(layer "In11.Cu")
		(net "M_D_CPU1_SA_DQ<26>")
	)
	(segment
		(start 93.236796 -269.707868)
		(end 93.222064 -269.699232)
		(width 0.088646)
		(layer "In11.Cu")
		(net "M_D_CPU1_SA_DQ<26>")
	)
	(segment
		(start 54.906926 -286.046926)
		(end 53.041042 -287.91281)
		(width 0.18288)
		(layer "In11.Cu")
		(net "M_D_CPU1_SA_DQ<26>")
	)
	(segment
		(start 32.768794 -288.828226)
		(end 32.633158 -288.69259)
		(width 0.18288)
		(layer "In11.Cu")
		(net "M_D_CPU1_SA_DQ<26>")
	)
	(segment
		(start 27.030426 -287.659826)
		(end 25.201626 -287.659826)
		(width 0.18288)
		(layer "In11.Cu")
		(net "M_D_CPU1_SA_DQ<26>")
	)
	(segment
		(start 84.374736 -269.762732)
		(end 84.374736 -270.29791)
		(width 0.088646)
		(layer "In11.Cu")
		(net "M_D_CPU1_SA_DQ<26>")
	)
	(segment
		(start 99.647756 -269.288514)
		(end 99.218242 -269.04061)
		(width 0.088646)
		(layer "In11.Cu")
		(net "M_D_CPU1_SA_DQ<26>")
	)
	(segment
		(start 59.331098 -284.764226)
		(end 58.735214 -285.36011)
		(width 0.18288)
		(layer "In11.Cu")
		(net "M_D_CPU1_SA_DQ<26>")
	)
	(segment
		(start 42.669714 -287.659826)
		(end 42.479722 -287.659826)
		(width 0.18288)
		(layer "In11.Cu")
		(net "M_D_CPU1_SA_DQ<26>")
	)
	(segment
		(start 42.286682 -287.151064)
		(end 42.093642 -286.958024)
		(width 0.18288)
		(layer "In11.Cu")
		(net "M_D_CPU1_SA_DQ<26>")
	)
	(segment
		(start 37.941504 -287.455102)
		(end 37.941504 -287.778952)
		(width 0.18288)
		(layer "In11.Cu")
		(net "M_D_CPU1_SA_DQ<26>")
	)
	(segment
		(start 53.041042 -287.91281)
		(end 51.71821 -287.91281)
		(width 0.18288)
		(layer "In11.Cu")
		(net "M_D_CPU1_SA_DQ<26>")
	)
	(segment
		(start 48.80356 -288.828226)
		(end 47.452026 -288.828226)
		(width 0.18288)
		(layer "In11.Cu")
		(net "M_D_CPU1_SA_DQ<26>")
	)
	(segment
		(start 83.235292 -271.437354)
		(end 83.064604 -271.437354)
		(width 0.088646)
		(layer "In11.Cu")
		(net "M_D_CPU1_SA_DQ<26>")
	)
	(segment
		(start 62.860682 -284.40761)
		(end 61.999622 -284.764226)
		(width 0.18288)
		(layer "In11.Cu")
		(net "M_D_CPU1_SA_DQ<26>")
	)
	(segment
		(start 38.449504 -287.262062)
		(end 38.134544 -287.262062)
		(width 0.18288)
		(layer "In11.Cu")
		(net "M_D_CPU1_SA_DQ<26>")
	)
	(segment
		(start 31.232348 -288.69259)
		(end 31.037784 -288.498026)
		(width 0.18288)
		(layer "In11.Cu")
		(net "M_D_CPU1_SA_DQ<26>")
	)
	(segment
		(start 41.392602 -287.659826)
		(end 41.077642 -287.659826)
		(width 0.18288)
		(layer "In11.Cu")
		(net "M_D_CPU1_SA_DQ<26>")
	)
	(segment
		(start 91.35745 -269.707868)
		(end 91.347036 -269.701772)
		(width 0.088646)
		(layer "In11.Cu")
		(net "M_D_CPU1_SA_DQ<26>")
	)
	(segment
		(start 47.452026 -288.828226)
		(end 47.31639 -288.69259)
		(width 0.18288)
		(layer "In11.Cu")
		(net "M_D_CPU1_SA_DQ<26>")
	)
	(segment
		(start 21.485606 -287.416748)
		(end 20.889214 -287.416748)
		(width 0.18288)
		(layer "In11.Cu")
		(net "M_D_CPU1_SA_DQ<26>")
	)
	(segment
		(start 84.986876 -269.535656)
		(end 84.601812 -269.535656)
		(width 0.088646)
		(layer "In11.Cu")
		(net "M_D_CPU1_SA_DQ<26>")
	)
	(segment
		(start 40.376602 -286.958024)
		(end 40.183562 -287.151064)
		(width 0.18288)
		(layer "In11.Cu")
		(net "M_D_CPU1_SA_DQ<26>")
	)
	(segment
		(start 40.691562 -286.958024)
		(end 40.376602 -286.958024)
		(width 0.18288)
		(layer "In11.Cu")
		(net "M_D_CPU1_SA_DQ<26>")
	)
	(segment
		(start 50.139346 -287.842706)
		(end 49.401476 -288.580576)
		(width 0.18288)
		(layer "In11.Cu")
		(net "M_D_CPU1_SA_DQ<26>")
	)
	(segment
		(start 38.642544 -287.455102)
		(end 38.449504 -287.262062)
		(width 0.18288)
		(layer "In11.Cu")
		(net "M_D_CPU1_SA_DQ<26>")
	)
	(segment
		(start 66.801238 -283.46019)
		(end 63.808102 -283.46019)
		(width 0.18288)
		(layer "In11.Cu")
		(net "M_D_CPU1_SA_DQ<26>")
	)
	(segment
		(start 42.286682 -287.466786)
		(end 42.286682 -287.151064)
		(width 0.18288)
		(layer "In11.Cu")
		(net "M_D_CPU1_SA_DQ<26>")
	)
	(segment
		(start 57.562242 -285.36011)
		(end 56.875426 -286.046926)
		(width 0.18288)
		(layer "In11.Cu")
		(net "M_D_CPU1_SA_DQ<26>")
	)
	(segment
		(start 49.401476 -288.580576)
		(end 48.80356 -288.828226)
		(width 0.18288)
		(layer "In11.Cu")
		(net "M_D_CPU1_SA_DQ<26>")
	)
	(segment
		(start 22.00402 -287.935162)
		(end 21.485606 -287.416748)
		(width 0.18288)
		(layer "In11.Cu")
		(net "M_D_CPU1_SA_DQ<26>")
	)
	(segment
		(start 29.138626 -288.777426)
		(end 28.148026 -288.777426)
		(width 0.18288)
		(layer "In11.Cu")
		(net "M_D_CPU1_SA_DQ<26>")
	)
	(segment
		(start 37.941504 -287.778952)
		(end 37.748464 -287.971992)
		(width 0.18288)
		(layer "In11.Cu")
		(net "M_D_CPU1_SA_DQ<26>")
	)
	(segment
		(start 98.633026 -269.117826)
		(end 98.587814 -269.163038)
		(width 0.088646)
		(layer "In11.Cu")
		(net "M_D_CPU1_SA_DQ<26>")
	)
	(segment
		(start 38.835584 -287.971992)
		(end 38.642544 -287.778952)
		(width 0.18288)
		(layer "In11.Cu")
		(net "M_D_CPU1_SA_DQ<26>")
	)
	(segment
		(start 97.93605 -269.707868)
		(end 97.925636 -269.701772)
		(width 0.088646)
		(layer "In11.Cu")
		(net "M_D_CPU1_SA_DQ<26>")
	)
	(segment
		(start 31.037784 -288.498026)
		(end 29.418026 -288.498026)
		(width 0.18288)
		(layer "In11.Cu")
		(net "M_D_CPU1_SA_DQ<26>")
	)
	(segment
		(start 34.244026 -288.828226)
		(end 32.768794 -288.828226)
		(width 0.18288)
		(layer "In11.Cu")
		(net "M_D_CPU1_SA_DQ<26>")
	)
	(segment
		(start 46.319948 -288.69259)
		(end 46.150784 -288.523426)
		(width 0.18288)
		(layer "In11.Cu")
		(net "M_D_CPU1_SA_DQ<26>")
	)
	(segment
		(start 37.748464 -287.971992)
		(end 36.994592 -287.971992)
		(width 0.18288)
		(layer "In11.Cu")
		(net "M_D_CPU1_SA_DQ<26>")
	)
	(segment
		(start 40.884602 -287.466786)
		(end 40.884602 -287.151064)
		(width 0.18288)
		(layer "In11.Cu")
		(net "M_D_CPU1_SA_DQ<26>")
	)
	(segment
		(start 29.418026 -288.498026)
		(end 29.138626 -288.777426)
		(width 0.18288)
		(layer "In11.Cu")
		(net "M_D_CPU1_SA_DQ<26>")
	)
	(segment
		(start 85.209888 -269.758668)
		(end 84.986876 -269.535656)
		(width 0.088646)
		(layer "In11.Cu")
		(net "M_D_CPU1_SA_DQ<26>")
	)
	(segment
		(start 40.183562 -287.151064)
		(end 40.183562 -287.466786)
		(width 0.18288)
		(layer "In11.Cu")
		(net "M_D_CPU1_SA_DQ<26>")
	)
	(segment
		(start 41.585642 -287.466786)
		(end 41.392602 -287.659826)
		(width 0.18288)
		(layer "In11.Cu")
		(net "M_D_CPU1_SA_DQ<26>")
	)
	(segment
		(start 41.778682 -286.958024)
		(end 41.585642 -287.151064)
		(width 0.18288)
		(layer "In11.Cu")
		(net "M_D_CPU1_SA_DQ<26>")
	)
	(segment
		(start 44.124626 -288.523426)
		(end 43.870626 -288.777426)
		(width 0.18288)
		(layer "In11.Cu")
		(net "M_D_CPU1_SA_DQ<26>")
	)
	(segment
		(start 43.870626 -288.777426)
		(end 43.15333 -288.777426)
		(width 0.18288)
		(layer "In11.Cu")
		(net "M_D_CPU1_SA_DQ<26>")
	)
	(segment
		(start 32.633158 -288.69259)
		(end 31.232348 -288.69259)
		(width 0.18288)
		(layer "In11.Cu")
		(net "M_D_CPU1_SA_DQ<26>")
	)
	(segment
		(start 42.931842 -287.921954)
		(end 42.669714 -287.659826)
		(width 0.18288)
		(layer "In11.Cu")
		(net "M_D_CPU1_SA_DQ<26>")
	)
	(segment
		(start 51.648106 -287.842706)
		(end 50.139346 -287.842706)
		(width 0.18288)
		(layer "In11.Cu")
		(net "M_D_CPU1_SA_DQ<26>")
	)
	(segment
		(start 83.064604 -271.437354)
		(end 78.824074 -271.437354)
		(width 0.18288)
		(layer "In11.Cu")
		(net "M_D_CPU1_SA_DQ<26>")
	)
	(segment
		(start 63.808102 -283.46019)
		(end 62.860682 -284.40761)
		(width 0.18288)
		(layer "In11.Cu")
		(net "M_D_CPU1_SA_DQ<26>")
	)
	(segment
		(start 39.678356 -287.971992)
		(end 38.835584 -287.971992)
		(width 0.18288)
		(layer "In11.Cu")
		(net "M_D_CPU1_SA_DQ<26>")
	)
	(segment
		(start 36.863782 -287.841182)
		(end 35.23107 -287.841182)
		(width 0.18288)
		(layer "In11.Cu")
		(net "M_D_CPU1_SA_DQ<26>")
	)
	(segment
		(start 42.093642 -286.958024)
		(end 41.778682 -286.958024)
		(width 0.18288)
		(layer "In11.Cu")
		(net "M_D_CPU1_SA_DQ<26>")
	)
	(segment
		(start 36.994592 -287.971992)
		(end 36.863782 -287.841182)
		(width 0.18288)
		(layer "In11.Cu")
		(net "M_D_CPU1_SA_DQ<26>")
	)
	(segment
		(start 24.92629 -287.935162)
		(end 22.00402 -287.935162)
		(width 0.18288)
		(layer "In11.Cu")
		(net "M_D_CPU1_SA_DQ<26>")
	)
	(segment
		(start 85.905594 -269.758668)
		(end 85.209888 -269.758668)
		(width 0.088646)
		(layer "In11.Cu")
		(net "M_D_CPU1_SA_DQ<26>")
	)
	(segment
		(start 47.31639 -288.69259)
		(end 46.319948 -288.69259)
		(width 0.18288)
		(layer "In11.Cu")
		(net "M_D_CPU1_SA_DQ<26>")
	)
	(arc
		(start 93.222064 -269.699232)
		(mid 92.945623 -269.632066)
		(end 92.671392 -269.707868)
		(width 0.088646)
		(layer "In11.Cu")
		(net "M_D_CPU1_SA_DQ<26>")
	)
	(arc
		(start 88.537796 -269.707868)
		(mid 88.255094 -269.632126)
		(end 87.972392 -269.707868)
		(width 0.088646)
		(layer "In11.Cu")
		(net "M_D_CPU1_SA_DQ<26>")
	)
	(arc
		(start 97.925636 -269.701772)
		(mid 97.647204 -269.631958)
		(end 97.370392 -269.707868)
		(width 0.088646)
		(layer "In11.Cu")
		(net "M_D_CPU1_SA_DQ<26>")
	)
	(arc
		(start 96.981264 -269.699232)
		(mid 96.704823 -269.632066)
		(end 96.430592 -269.707868)
		(width 0.088646)
		(layer "In11.Cu")
		(net "M_D_CPU1_SA_DQ<26>")
	)
	(arc
		(start 98.587814 -269.163038)
		(mid 98.551074 -269.21229)
		(end 98.529902 -269.269972)
		(width 0.088646)
		(layer "In11.Cu")
		(net "M_D_CPU1_SA_DQ<26>")
	)
	(arc
		(start 90.417396 -269.707868)
		(mid 90.134694 -269.632126)
		(end 89.851992 -269.707868)
		(width 0.088646)
		(layer "In11.Cu")
		(net "M_D_CPU1_SA_DQ<26>")
	)
	(arc
		(start 94.161864 -269.699232)
		(mid 93.885423 -269.632066)
		(end 93.611192 -269.707868)
		(width 0.088646)
		(layer "In11.Cu")
		(net "M_D_CPU1_SA_DQ<26>")
	)
	(arc
		(start 98.48977 -269.460726)
		(mid 98.429901 -269.598602)
		(end 98.320606 -269.701772)
		(width 0.088646)
		(layer "In11.Cu")
		(net "M_D_CPU1_SA_DQ<26>")
	)
	(arc
		(start 90.791792 -269.707868)
		(mid 90.604594 -269.758011)
		(end 90.417396 -269.707868)
		(width 0.088646)
		(layer "In11.Cu")
		(net "M_D_CPU1_SA_DQ<26>")
	)
	(arc
		(start 94.550992 -269.707868)
		(mid 94.363794 -269.758011)
		(end 94.176596 -269.707868)
		(width 0.088646)
		(layer "In11.Cu")
		(net "M_D_CPU1_SA_DQ<26>")
	)
	(arc
		(start 95.490792 -269.707868)
		(mid 95.303594 -269.758011)
		(end 95.116396 -269.707868)
		(width 0.088646)
		(layer "In11.Cu")
		(net "M_D_CPU1_SA_DQ<26>")
	)
	(arc
		(start 98.320606 -269.701772)
		(mid 98.315565 -269.704885)
		(end 98.310446 -269.707868)
		(width 0.088646)
		(layer "In11.Cu")
		(net "M_D_CPU1_SA_DQ<26>")
	)
	(arc
		(start 97.370392 -269.707868)
		(mid 97.183194 -269.758011)
		(end 96.995996 -269.707868)
		(width 0.088646)
		(layer "In11.Cu")
		(net "M_D_CPU1_SA_DQ<26>")
	)
	(arc
		(start 88.912192 -269.707868)
		(mid 88.724994 -269.758011)
		(end 88.537796 -269.707868)
		(width 0.088646)
		(layer "In11.Cu")
		(net "M_D_CPU1_SA_DQ<26>")
	)
	(arc
		(start 92.296996 -269.707868)
		(mid 92.020437 -269.632159)
		(end 91.74226 -269.701772)
		(width 0.088646)
		(layer "In11.Cu")
		(net "M_D_CPU1_SA_DQ<26>")
	)
	(arc
		(start 93.611192 -269.707868)
		(mid 93.423994 -269.758011)
		(end 93.236796 -269.707868)
		(width 0.088646)
		(layer "In11.Cu")
		(net "M_D_CPU1_SA_DQ<26>")
	)
	(arc
		(start 96.430592 -269.707868)
		(mid 96.243394 -269.758011)
		(end 96.056196 -269.707868)
		(width 0.088646)
		(layer "In11.Cu")
		(net "M_D_CPU1_SA_DQ<26>")
	)
	(arc
		(start 87.597996 -269.707868)
		(mid 87.315294 -269.632126)
		(end 87.032592 -269.707868)
		(width 0.088646)
		(layer "In11.Cu")
		(net "M_D_CPU1_SA_DQ<26>")
	)
	(arc
		(start 87.032592 -269.707868)
		(mid 86.845394 -269.758011)
		(end 86.658196 -269.707868)
		(width 0.088646)
		(layer "In11.Cu")
		(net "M_D_CPU1_SA_DQ<26>")
	)
	(arc
		(start 87.972392 -269.707868)
		(mid 87.785194 -269.758011)
		(end 87.597996 -269.707868)
		(width 0.088646)
		(layer "In11.Cu")
		(net "M_D_CPU1_SA_DQ<26>")
	)
	(arc
		(start 98.310446 -269.707868)
		(mid 98.123248 -269.758011)
		(end 97.93605 -269.707868)
		(width 0.088646)
		(layer "In11.Cu")
		(net "M_D_CPU1_SA_DQ<26>")
	)
	(arc
		(start 86.092792 -269.707868)
		(mid 86.002536 -269.74559)
		(end 85.905594 -269.758668)
		(width 0.088646)
		(layer "In11.Cu")
		(net "M_D_CPU1_SA_DQ<26>")
	)
	(arc
		(start 96.041464 -269.699232)
		(mid 95.765023 -269.632066)
		(end 95.490792 -269.707868)
		(width 0.088646)
		(layer "In11.Cu")
		(net "M_D_CPU1_SA_DQ<26>")
	)
	(arc
		(start 92.671392 -269.707868)
		(mid 92.484194 -269.758011)
		(end 92.296996 -269.707868)
		(width 0.088646)
		(layer "In11.Cu")
		(net "M_D_CPU1_SA_DQ<26>")
	)
	(arc
		(start 86.658196 -269.707868)
		(mid 86.375494 -269.632126)
		(end 86.092792 -269.707868)
		(width 0.088646)
		(layer "In11.Cu")
		(net "M_D_CPU1_SA_DQ<26>")
	)
	(arc
		(start 89.851992 -269.707868)
		(mid 89.664794 -269.758011)
		(end 89.477596 -269.707868)
		(width 0.088646)
		(layer "In11.Cu")
		(net "M_D_CPU1_SA_DQ<26>")
	)
	(arc
		(start 95.101664 -269.699232)
		(mid 94.825223 -269.632066)
		(end 94.550992 -269.707868)
		(width 0.088646)
		(layer "In11.Cu")
		(net "M_D_CPU1_SA_DQ<26>")
	)
	(arc
		(start 91.347036 -269.701772)
		(mid 91.068604 -269.631958)
		(end 90.791792 -269.707868)
		(width 0.088646)
		(layer "In11.Cu")
		(net "M_D_CPU1_SA_DQ<26>")
	)
	(arc
		(start 89.477596 -269.707868)
		(mid 89.194894 -269.632126)
		(end 88.912192 -269.707868)
		(width 0.088646)
		(layer "In11.Cu")
		(net "M_D_CPU1_SA_DQ<26>")
	)
	(arc
		(start 91.731846 -269.707868)
		(mid 91.544648 -269.758011)
		(end 91.35745 -269.707868)
		(width 0.088646)
		(layer "In11.Cu")
		(net "M_D_CPU1_SA_DQ<26>")
	)
	(arc
		(start 99.218242 -269.04061)
		(mid 98.91252 -268.979899)
		(end 98.633026 -269.117826)
		(width 0.088646)
		(layer "In11.Cu")
		(net "M_D_CPU1_SA_DQ<26>")
	)
	(segment
		(start 11.1252 -286.141668)
		(end 13.110718 -286.141668)
		(width 0.1016)
		(layer "F.Cu")
		(net "M_D_CPU1_SA_DQ<25>")
	)
	(segment
		(start 10.344912 -286.295338)
		(end 10.507472 -286.132778)
		(width 0.20066)
		(layer "F.Cu")
		(net "M_D_CPU1_SA_DQ<25>")
	)
	(segment
		(start 13.619988 -286.141668)
		(end 14.04493 -286.56661)
		(width 0.20066)
		(layer "F.Cu")
		(net "M_D_CPU1_SA_DQ<25>")
	)
	(segment
		(start 13.110718 -286.141668)
		(end 13.441426 -286.141668)
		(width 0.101854)
		(layer "F.Cu")
		(net "M_D_CPU1_SA_DQ<25>")
	)
	(segment
		(start 10.507472 -286.132778)
		(end 11.11631 -286.132778)
		(width 0.20066)
		(layer "F.Cu")
		(net "M_D_CPU1_SA_DQ<25>")
	)
	(segment
		(start 98.592894 -268.033754)
		(end 98.593148 -268.034008)
		(width 0.20066)
		(layer "F.Cu")
		(net "M_D_CPU1_SA_DQ<25>")
	)
	(segment
		(start 10.344912 -286.623506)
		(end 10.344912 -286.295338)
		(width 0.20066)
		(layer "F.Cu")
		(net "M_D_CPU1_SA_DQ<25>")
	)
	(segment
		(start 98.593148 -268.034008)
		(end 98.593148 -268.569694)
		(width 0.20066)
		(layer "F.Cu")
		(net "M_D_CPU1_SA_DQ<25>")
	)
	(segment
		(start 11.11631 -286.132778)
		(end 11.1252 -286.141668)
		(width 0.1016)
		(layer "F.Cu")
		(net "M_D_CPU1_SA_DQ<25>")
	)
	(segment
		(start 14.04493 -286.56661)
		(end 15.684246 -286.56661)
		(width 0.20066)
		(layer "F.Cu")
		(net "M_D_CPU1_SA_DQ<25>")
	)
	(segment
		(start 15.684246 -286.56661)
		(end 16.789146 -286.56661)
		(width 0.20066)
		(layer "F.Cu")
		(net "M_D_CPU1_SA_DQ<25>")
	)
	(segment
		(start 8.140446 -286.56661)
		(end 9.474708 -286.56661)
		(width 0.20066)
		(layer "F.Cu")
		(net "M_D_CPU1_SA_DQ<25>")
	)
	(segment
		(start 13.441426 -286.141668)
		(end 13.619988 -286.141668)
		(width 0.20066)
		(layer "F.Cu")
		(net "M_D_CPU1_SA_DQ<25>")
	)
	(segment
		(start 10.19048 -286.777938)
		(end 10.344912 -286.623506)
		(width 0.20066)
		(layer "F.Cu")
		(net "M_D_CPU1_SA_DQ<25>")
	)
	(segment
		(start 9.686036 -286.777938)
		(end 10.19048 -286.777938)
		(width 0.20066)
		(layer "F.Cu")
		(net "M_D_CPU1_SA_DQ<25>")
	)
	(segment
		(start 9.474708 -286.56661)
		(end 9.686036 -286.777938)
		(width 0.20066)
		(layer "F.Cu")
		(net "M_D_CPU1_SA_DQ<25>")
	)
	(segment
		(start 95.496888 -269.062708)
		(end 95.491046 -269.059152)
		(width 0.088646)
		(layer "In11.Cu")
		(net "M_D_CPU1_SA_DQ<25>")
	)
	(segment
		(start 17.959832 -287.202626)
		(end 17.323816 -286.56661)
		(width 0.18288)
		(layer "In11.Cu")
		(net "M_D_CPU1_SA_DQ<25>")
	)
	(segment
		(start 93.617288 -269.062708)
		(end 93.611446 -269.059152)
		(width 0.088646)
		(layer "In11.Cu")
		(net "M_D_CPU1_SA_DQ<25>")
	)
	(segment
		(start 56.723534 -285.373826)
		(end 55.402226 -285.373826)
		(width 0.18288)
		(layer "In11.Cu")
		(net "M_D_CPU1_SA_DQ<25>")
	)
	(segment
		(start 44.454826 -288.015426)
		(end 43.819826 -287.380426)
		(width 0.18288)
		(layer "In11.Cu")
		(net "M_D_CPU1_SA_DQ<25>")
	)
	(segment
		(start 19.126708 -286.991298)
		(end 18.91538 -287.202626)
		(width 0.18288)
		(layer "In11.Cu")
		(net "M_D_CPU1_SA_DQ<25>")
	)
	(segment
		(start 39.022528 -286.072834)
		(end 38.707568 -286.072834)
		(width 0.18288)
		(layer "In11.Cu")
		(net "M_D_CPU1_SA_DQ<25>")
	)
	(segment
		(start 38.707568 -286.072834)
		(end 38.514528 -286.265874)
		(width 0.18288)
		(layer "In11.Cu")
		(net "M_D_CPU1_SA_DQ<25>")
	)
	(segment
		(start 39.215568 -286.265874)
		(end 39.022528 -286.072834)
		(width 0.18288)
		(layer "In11.Cu")
		(net "M_D_CPU1_SA_DQ<25>")
	)
	(segment
		(start 47.752 -287.842452)
		(end 46.0502 -287.842452)
		(width 0.18288)
		(layer "In11.Cu")
		(net "M_D_CPU1_SA_DQ<25>")
	)
	(segment
		(start 96.430846 -269.059152)
		(end 96.425004 -269.05585)
		(width 0.088646)
		(layer "In11.Cu")
		(net "M_D_CPU1_SA_DQ<25>")
	)
	(segment
		(start 96.436688 -269.062708)
		(end 96.430846 -269.059152)
		(width 0.088646)
		(layer "In11.Cu")
		(net "M_D_CPU1_SA_DQ<25>")
	)
	(segment
		(start 37.444426 -286.948626)
		(end 36.599368 -286.948626)
		(width 0.18288)
		(layer "In11.Cu")
		(net "M_D_CPU1_SA_DQ<25>")
	)
	(segment
		(start 53.725826 -285.485586)
		(end 53.725826 -286.062674)
		(width 0.18288)
		(layer "In11.Cu")
		(net "M_D_CPU1_SA_DQ<25>")
	)
	(segment
		(start 83.301586 -270.929354)
		(end 82.963004 -270.929354)
		(width 0.088646)
		(layer "In11.Cu")
		(net "M_D_CPU1_SA_DQ<25>")
	)
	(segment
		(start 35.190684 -286.992568)
		(end 34.548826 -287.634426)
		(width 0.18288)
		(layer "In11.Cu")
		(net "M_D_CPU1_SA_DQ<25>")
	)
	(segment
		(start 61.88964 -284.256226)
		(end 57.351168 -284.256226)
		(width 0.18288)
		(layer "In11.Cu")
		(net "M_D_CPU1_SA_DQ<25>")
	)
	(segment
		(start 21.364702 -286.888936)
		(end 21.26234 -286.991298)
		(width 0.18288)
		(layer "In11.Cu")
		(net "M_D_CPU1_SA_DQ<25>")
	)
	(segment
		(start 55.224426 -285.196026)
		(end 54.015386 -285.196026)
		(width 0.18288)
		(layer "In11.Cu")
		(net "M_D_CPU1_SA_DQ<25>")
	)
	(segment
		(start 48.010826 -287.583626)
		(end 47.752 -287.842452)
		(width 0.18288)
		(layer "In11.Cu")
		(net "M_D_CPU1_SA_DQ<25>")
	)
	(segment
		(start 92.296996 -269.059152)
		(end 92.286582 -269.065248)
		(width 0.088646)
		(layer "In11.Cu")
		(net "M_D_CPU1_SA_DQ<25>")
	)
	(segment
		(start 40.470582 -286.085026)
		(end 39.810182 -286.745426)
		(width 0.18288)
		(layer "In11.Cu")
		(net "M_D_CPU1_SA_DQ<25>")
	)
	(segment
		(start 46.0502 -287.842452)
		(end 45.877226 -288.015426)
		(width 0.18288)
		(layer "In11.Cu")
		(net "M_D_CPU1_SA_DQ<25>")
	)
	(segment
		(start 93.611446 -269.059152)
		(end 93.605604 -269.05585)
		(width 0.088646)
		(layer "In11.Cu")
		(net "M_D_CPU1_SA_DQ<25>")
	)
	(segment
		(start 53.725826 -286.062674)
		(end 52.865274 -286.923226)
		(width 0.18288)
		(layer "In11.Cu")
		(net "M_D_CPU1_SA_DQ<25>")
	)
	(segment
		(start 50.15103 -286.992568)
		(end 49.559972 -287.583626)
		(width 0.18288)
		(layer "In11.Cu")
		(net "M_D_CPU1_SA_DQ<25>")
	)
	(segment
		(start 98.015806 -269.012924)
		(end 97.935796 -269.059152)
		(width 0.088646)
		(layer "In11.Cu")
		(net "M_D_CPU1_SA_DQ<25>")
	)
	(segment
		(start 32.92348 -287.634426)
		(end 32.715454 -287.842452)
		(width 0.18288)
		(layer "In11.Cu")
		(net "M_D_CPU1_SA_DQ<25>")
	)
	(segment
		(start 52.865274 -286.923226)
		(end 51.712368 -286.923226)
		(width 0.18288)
		(layer "In11.Cu")
		(net "M_D_CPU1_SA_DQ<25>")
	)
	(segment
		(start 57.351168 -284.256226)
		(end 57.12714 -284.480254)
		(width 0.18288)
		(layer "In11.Cu")
		(net "M_D_CPU1_SA_DQ<25>")
	)
	(segment
		(start 25.472136 -286.888936)
		(end 21.364702 -286.888936)
		(width 0.18288)
		(layer "In11.Cu")
		(net "M_D_CPU1_SA_DQ<25>")
	)
	(segment
		(start 55.402226 -285.373826)
		(end 55.224426 -285.196026)
		(width 0.18288)
		(layer "In11.Cu")
		(net "M_D_CPU1_SA_DQ<25>")
	)
	(segment
		(start 91.35745 -269.059152)
		(end 91.347036 -269.065248)
		(width 0.088646)
		(layer "In11.Cu")
		(net "M_D_CPU1_SA_DQ<25>")
	)
	(segment
		(start 63.617602 -282.92679)
		(end 62.569852 -283.97454)
		(width 0.18288)
		(layer "In11.Cu")
		(net "M_D_CPU1_SA_DQ<25>")
	)
	(segment
		(start 21.26234 -286.991298)
		(end 19.126708 -286.991298)
		(width 0.18288)
		(layer "In11.Cu")
		(net "M_D_CPU1_SA_DQ<25>")
	)
	(segment
		(start 17.323816 -286.56661)
		(end 16.789146 -286.56661)
		(width 0.18288)
		(layer "In11.Cu")
		(net "M_D_CPU1_SA_DQ<25>")
	)
	(segment
		(start 30.5054 -287.842452)
		(end 30.391862 -287.95599)
		(width 0.18288)
		(layer "In11.Cu")
		(net "M_D_CPU1_SA_DQ<25>")
	)
	(segment
		(start 25.684226 -287.101026)
		(end 25.472136 -286.888936)
		(width 0.18288)
		(layer "In11.Cu")
		(net "M_D_CPU1_SA_DQ<25>")
	)
	(segment
		(start 95.491046 -269.059152)
		(end 95.485204 -269.05585)
		(width 0.088646)
		(layer "In11.Cu")
		(net "M_D_CPU1_SA_DQ<25>")
	)
	(segment
		(start 78.608428 -270.929354)
		(end 66.610992 -282.92679)
		(width 0.18288)
		(layer "In11.Cu")
		(net "M_D_CPU1_SA_DQ<25>")
	)
	(segment
		(start 93.236796 -269.059152)
		(end 93.222064 -269.067788)
		(width 0.088646)
		(layer "In11.Cu")
		(net "M_D_CPU1_SA_DQ<25>")
	)
	(segment
		(start 84.495894 -269.134844)
		(end 84.134706 -269.496032)
		(width 0.088646)
		(layer "In11.Cu")
		(net "M_D_CPU1_SA_DQ<25>")
	)
	(segment
		(start 43.819826 -287.380426)
		(end 43.517058 -287.380426)
		(width 0.18288)
		(layer "In11.Cu")
		(net "M_D_CPU1_SA_DQ<25>")
	)
	(segment
		(start 38.514528 -286.552386)
		(end 38.321488 -286.745426)
		(width 0.18288)
		(layer "In11.Cu")
		(net "M_D_CPU1_SA_DQ<25>")
	)
	(segment
		(start 45.877226 -288.015426)
		(end 44.454826 -288.015426)
		(width 0.18288)
		(layer "In11.Cu")
		(net "M_D_CPU1_SA_DQ<25>")
	)
	(segment
		(start 39.215568 -286.552386)
		(end 39.215568 -286.265874)
		(width 0.18288)
		(layer "In11.Cu")
		(net "M_D_CPU1_SA_DQ<25>")
	)
	(segment
		(start 62.569852 -283.97454)
		(end 61.88964 -284.256226)
		(width 0.18288)
		(layer "In11.Cu")
		(net "M_D_CPU1_SA_DQ<25>")
	)
	(segment
		(start 37.647626 -286.745426)
		(end 37.444426 -286.948626)
		(width 0.18288)
		(layer "In11.Cu")
		(net "M_D_CPU1_SA_DQ<25>")
	)
	(segment
		(start 66.610992 -282.92679)
		(end 63.617602 -282.92679)
		(width 0.18288)
		(layer "In11.Cu")
		(net "M_D_CPU1_SA_DQ<25>")
	)
	(segment
		(start 38.321488 -286.745426)
		(end 37.647626 -286.745426)
		(width 0.18288)
		(layer "In11.Cu")
		(net "M_D_CPU1_SA_DQ<25>")
	)
	(segment
		(start 51.643026 -286.992568)
		(end 50.15103 -286.992568)
		(width 0.18288)
		(layer "In11.Cu")
		(net "M_D_CPU1_SA_DQ<25>")
	)
	(segment
		(start 94.551246 -269.059152)
		(end 94.545404 -269.05585)
		(width 0.088646)
		(layer "In11.Cu")
		(net "M_D_CPU1_SA_DQ<25>")
	)
	(segment
		(start 39.408608 -286.745426)
		(end 39.215568 -286.552386)
		(width 0.18288)
		(layer "In11.Cu")
		(net "M_D_CPU1_SA_DQ<25>")
	)
	(segment
		(start 54.015386 -285.196026)
		(end 53.725826 -285.485586)
		(width 0.18288)
		(layer "In11.Cu")
		(net "M_D_CPU1_SA_DQ<25>")
	)
	(segment
		(start 32.715454 -287.842452)
		(end 30.5054 -287.842452)
		(width 0.18288)
		(layer "In11.Cu")
		(net "M_D_CPU1_SA_DQ<25>")
	)
	(segment
		(start 28.325826 -287.101026)
		(end 25.684226 -287.101026)
		(width 0.18288)
		(layer "In11.Cu")
		(net "M_D_CPU1_SA_DQ<25>")
	)
	(segment
		(start 94.557088 -269.062708)
		(end 94.551246 -269.059152)
		(width 0.088646)
		(layer "In11.Cu")
		(net "M_D_CPU1_SA_DQ<25>")
	)
	(segment
		(start 57.12714 -284.480254)
		(end 57.12714 -284.97022)
		(width 0.18288)
		(layer "In11.Cu")
		(net "M_D_CPU1_SA_DQ<25>")
	)
	(segment
		(start 97.370646 -269.059152)
		(end 97.364804 -269.05585)
		(width 0.088646)
		(layer "In11.Cu")
		(net "M_D_CPU1_SA_DQ<25>")
	)
	(segment
		(start 82.963004 -270.929354)
		(end 78.608428 -270.929354)
		(width 0.18288)
		(layer "In11.Cu")
		(net "M_D_CPU1_SA_DQ<25>")
	)
	(segment
		(start 29.18079 -287.95599)
		(end 28.325826 -287.101026)
		(width 0.18288)
		(layer "In11.Cu")
		(net "M_D_CPU1_SA_DQ<25>")
	)
	(segment
		(start 42.221658 -286.085026)
		(end 40.470582 -286.085026)
		(width 0.18288)
		(layer "In11.Cu")
		(net "M_D_CPU1_SA_DQ<25>")
	)
	(segment
		(start 39.810182 -286.745426)
		(end 39.408608 -286.745426)
		(width 0.18288)
		(layer "In11.Cu")
		(net "M_D_CPU1_SA_DQ<25>")
	)
	(segment
		(start 51.712368 -286.923226)
		(end 51.643026 -286.992568)
		(width 0.18288)
		(layer "In11.Cu")
		(net "M_D_CPU1_SA_DQ<25>")
	)
	(segment
		(start 38.514528 -286.265874)
		(end 38.514528 -286.552386)
		(width 0.18288)
		(layer "In11.Cu")
		(net "M_D_CPU1_SA_DQ<25>")
	)
	(segment
		(start 18.91538 -287.202626)
		(end 17.959832 -287.202626)
		(width 0.18288)
		(layer "In11.Cu")
		(net "M_D_CPU1_SA_DQ<25>")
	)
	(segment
		(start 36.555426 -286.992568)
		(end 35.190684 -286.992568)
		(width 0.18288)
		(layer "In11.Cu")
		(net "M_D_CPU1_SA_DQ<25>")
	)
	(segment
		(start 57.12714 -284.97022)
		(end 56.723534 -285.373826)
		(width 0.18288)
		(layer "In11.Cu")
		(net "M_D_CPU1_SA_DQ<25>")
	)
	(segment
		(start 84.134706 -270.096234)
		(end 83.301586 -270.929354)
		(width 0.088646)
		(layer "In11.Cu")
		(net "M_D_CPU1_SA_DQ<25>")
	)
	(segment
		(start 84.134706 -269.496032)
		(end 84.134706 -270.096234)
		(width 0.088646)
		(layer "In11.Cu")
		(net "M_D_CPU1_SA_DQ<25>")
	)
	(segment
		(start 34.548826 -287.634426)
		(end 32.92348 -287.634426)
		(width 0.18288)
		(layer "In11.Cu")
		(net "M_D_CPU1_SA_DQ<25>")
	)
	(segment
		(start 36.599368 -286.948626)
		(end 36.555426 -286.992568)
		(width 0.18288)
		(layer "In11.Cu")
		(net "M_D_CPU1_SA_DQ<25>")
	)
	(segment
		(start 49.559972 -287.583626)
		(end 48.010826 -287.583626)
		(width 0.18288)
		(layer "In11.Cu")
		(net "M_D_CPU1_SA_DQ<25>")
	)
	(segment
		(start 43.517058 -287.380426)
		(end 42.221658 -286.085026)
		(width 0.18288)
		(layer "In11.Cu")
		(net "M_D_CPU1_SA_DQ<25>")
	)
	(segment
		(start 30.391862 -287.95599)
		(end 29.18079 -287.95599)
		(width 0.18288)
		(layer "In11.Cu")
		(net "M_D_CPU1_SA_DQ<25>")
	)
	(segment
		(start 97.376488 -269.062708)
		(end 97.370646 -269.059152)
		(width 0.088646)
		(layer "In11.Cu")
		(net "M_D_CPU1_SA_DQ<25>")
	)
	(arc
		(start 87.032592 -269.059152)
		(mid 86.845394 -269.009009)
		(end 86.658196 -269.059152)
		(width 0.088646)
		(layer "In11.Cu")
		(net "M_D_CPU1_SA_DQ<25>")
	)
	(arc
		(start 84.778596 -269.059152)
		(mid 84.642227 -269.115594)
		(end 84.495894 -269.134844)
		(width 0.088646)
		(layer "In11.Cu")
		(net "M_D_CPU1_SA_DQ<25>")
	)
	(arc
		(start 98.593148 -268.569694)
		(mid 98.318986 -268.81021)
		(end 98.015806 -269.012924)
		(width 0.088646)
		(layer "In11.Cu")
		(net "M_D_CPU1_SA_DQ<25>")
	)
	(arc
		(start 92.286582 -269.065248)
		(mid 92.008404 -269.134971)
		(end 91.731846 -269.059152)
		(width 0.088646)
		(layer "In11.Cu")
		(net "M_D_CPU1_SA_DQ<25>")
	)
	(arc
		(start 93.605604 -269.05585)
		(mid 93.420749 -269.0089)
		(end 93.236796 -269.059152)
		(width 0.088646)
		(layer "In11.Cu")
		(net "M_D_CPU1_SA_DQ<25>")
	)
	(arc
		(start 96.425004 -269.05585)
		(mid 96.240149 -269.0089)
		(end 96.056196 -269.059152)
		(width 0.088646)
		(layer "In11.Cu")
		(net "M_D_CPU1_SA_DQ<25>")
	)
	(arc
		(start 96.995996 -269.059152)
		(mid 96.716822 -269.134917)
		(end 96.436688 -269.062708)
		(width 0.088646)
		(layer "In11.Cu")
		(net "M_D_CPU1_SA_DQ<25>")
	)
	(arc
		(start 88.912192 -269.059152)
		(mid 88.724994 -269.009009)
		(end 88.537796 -269.059152)
		(width 0.088646)
		(layer "In11.Cu")
		(net "M_D_CPU1_SA_DQ<25>")
	)
	(arc
		(start 94.176596 -269.059152)
		(mid 93.897422 -269.134917)
		(end 93.617288 -269.062708)
		(width 0.088646)
		(layer "In11.Cu")
		(net "M_D_CPU1_SA_DQ<25>")
	)
	(arc
		(start 85.718396 -269.059152)
		(mid 85.435694 -269.134928)
		(end 85.152992 -269.059152)
		(width 0.088646)
		(layer "In11.Cu")
		(net "M_D_CPU1_SA_DQ<25>")
	)
	(arc
		(start 97.364804 -269.05585)
		(mid 97.179949 -269.0089)
		(end 96.995996 -269.059152)
		(width 0.088646)
		(layer "In11.Cu")
		(net "M_D_CPU1_SA_DQ<25>")
	)
	(arc
		(start 86.092792 -269.059152)
		(mid 85.905594 -269.009009)
		(end 85.718396 -269.059152)
		(width 0.088646)
		(layer "In11.Cu")
		(net "M_D_CPU1_SA_DQ<25>")
	)
	(arc
		(start 96.056196 -269.059152)
		(mid 95.777022 -269.134917)
		(end 95.496888 -269.062708)
		(width 0.088646)
		(layer "In11.Cu")
		(net "M_D_CPU1_SA_DQ<25>")
	)
	(arc
		(start 87.597996 -269.059152)
		(mid 87.315294 -269.134928)
		(end 87.032592 -269.059152)
		(width 0.088646)
		(layer "In11.Cu")
		(net "M_D_CPU1_SA_DQ<25>")
	)
	(arc
		(start 91.347036 -269.065248)
		(mid 91.068604 -269.135094)
		(end 90.791792 -269.059152)
		(width 0.088646)
		(layer "In11.Cu")
		(net "M_D_CPU1_SA_DQ<25>")
	)
	(arc
		(start 94.545404 -269.05585)
		(mid 94.360549 -269.0089)
		(end 94.176596 -269.059152)
		(width 0.088646)
		(layer "In11.Cu")
		(net "M_D_CPU1_SA_DQ<25>")
	)
	(arc
		(start 87.972392 -269.059152)
		(mid 87.785194 -269.009009)
		(end 87.597996 -269.059152)
		(width 0.088646)
		(layer "In11.Cu")
		(net "M_D_CPU1_SA_DQ<25>")
	)
	(arc
		(start 97.935796 -269.059152)
		(mid 97.656622 -269.134917)
		(end 97.376488 -269.062708)
		(width 0.088646)
		(layer "In11.Cu")
		(net "M_D_CPU1_SA_DQ<25>")
	)
	(arc
		(start 92.671392 -269.059152)
		(mid 92.484194 -269.009009)
		(end 92.296996 -269.059152)
		(width 0.088646)
		(layer "In11.Cu")
		(net "M_D_CPU1_SA_DQ<25>")
	)
	(arc
		(start 85.152992 -269.059152)
		(mid 84.965794 -269.009009)
		(end 84.778596 -269.059152)
		(width 0.088646)
		(layer "In11.Cu")
		(net "M_D_CPU1_SA_DQ<25>")
	)
	(arc
		(start 95.116396 -269.059152)
		(mid 94.837222 -269.134917)
		(end 94.557088 -269.062708)
		(width 0.088646)
		(layer "In11.Cu")
		(net "M_D_CPU1_SA_DQ<25>")
	)
	(arc
		(start 86.658196 -269.059152)
		(mid 86.375494 -269.134928)
		(end 86.092792 -269.059152)
		(width 0.088646)
		(layer "In11.Cu")
		(net "M_D_CPU1_SA_DQ<25>")
	)
	(arc
		(start 88.537796 -269.059152)
		(mid 88.255094 -269.134928)
		(end 87.972392 -269.059152)
		(width 0.088646)
		(layer "In11.Cu")
		(net "M_D_CPU1_SA_DQ<25>")
	)
	(arc
		(start 89.851992 -269.059152)
		(mid 89.664794 -269.009009)
		(end 89.477596 -269.059152)
		(width 0.088646)
		(layer "In11.Cu")
		(net "M_D_CPU1_SA_DQ<25>")
	)
	(arc
		(start 90.417396 -269.059152)
		(mid 90.134694 -269.134928)
		(end 89.851992 -269.059152)
		(width 0.088646)
		(layer "In11.Cu")
		(net "M_D_CPU1_SA_DQ<25>")
	)
	(arc
		(start 90.791792 -269.059152)
		(mid 90.604594 -269.009009)
		(end 90.417396 -269.059152)
		(width 0.088646)
		(layer "In11.Cu")
		(net "M_D_CPU1_SA_DQ<25>")
	)
	(arc
		(start 91.731846 -269.059152)
		(mid 91.544648 -269.009009)
		(end 91.35745 -269.059152)
		(width 0.088646)
		(layer "In11.Cu")
		(net "M_D_CPU1_SA_DQ<25>")
	)
	(arc
		(start 95.485204 -269.05585)
		(mid 95.300349 -269.0089)
		(end 95.116396 -269.059152)
		(width 0.088646)
		(layer "In11.Cu")
		(net "M_D_CPU1_SA_DQ<25>")
	)
	(arc
		(start 89.477596 -269.059152)
		(mid 89.194894 -269.134928)
		(end 88.912192 -269.059152)
		(width 0.088646)
		(layer "In11.Cu")
		(net "M_D_CPU1_SA_DQ<25>")
	)
	(arc
		(start 93.222064 -269.067788)
		(mid 92.945589 -269.135108)
		(end 92.671392 -269.059152)
		(width 0.088646)
		(layer "In11.Cu")
		(net "M_D_CPU1_SA_DQ<25>")
	)
	(segment
		(start 10.344912 -288.332672)
		(end 10.344912 -288.043112)
		(width 0.20066)
		(layer "F.Cu")
		(net "M_D_CPU1_SA_DQ<24>")
	)
	(segment
		(start 13.890244 -287.84169)
		(end 14.315186 -288.266632)
		(width 0.20066)
		(layer "F.Cu")
		(net "M_D_CPU1_SA_DQ<24>")
	)
	(segment
		(start 10.172192 -288.505392)
		(end 10.344912 -288.332672)
		(width 0.20066)
		(layer "F.Cu")
		(net "M_D_CPU1_SA_DQ<24>")
	)
	(segment
		(start 99.062794 -268.847824)
		(end 99.062794 -269.38351)
		(width 0.20066)
		(layer "F.Cu")
		(net "M_D_CPU1_SA_DQ<24>")
	)
	(segment
		(start 13.441426 -287.84169)
		(end 13.890244 -287.84169)
		(width 0.20066)
		(layer "F.Cu")
		(net "M_D_CPU1_SA_DQ<24>")
	)
	(segment
		(start 9.713468 -288.505392)
		(end 10.172192 -288.505392)
		(width 0.20066)
		(layer "F.Cu")
		(net "M_D_CPU1_SA_DQ<24>")
	)
	(segment
		(start 10.344912 -288.043112)
		(end 10.554462 -287.833562)
		(width 0.20066)
		(layer "F.Cu")
		(net "M_D_CPU1_SA_DQ<24>")
	)
	(segment
		(start 9.474708 -288.266632)
		(end 9.713468 -288.505392)
		(width 0.20066)
		(layer "F.Cu")
		(net "M_D_CPU1_SA_DQ<24>")
	)
	(segment
		(start 11.124438 -287.84169)
		(end 11.372342 -287.84169)
		(width 0.101854)
		(layer "F.Cu")
		(net "M_D_CPU1_SA_DQ<24>")
	)
	(segment
		(start 15.684246 -288.266632)
		(end 16.789146 -288.266632)
		(width 0.20066)
		(layer "F.Cu")
		(net "M_D_CPU1_SA_DQ<24>")
	)
	(segment
		(start 99.063048 -268.84757)
		(end 99.062794 -268.847824)
		(width 0.20066)
		(layer "F.Cu")
		(net "M_D_CPU1_SA_DQ<24>")
	)
	(segment
		(start 14.315186 -288.266632)
		(end 15.684246 -288.266632)
		(width 0.20066)
		(layer "F.Cu")
		(net "M_D_CPU1_SA_DQ<24>")
	)
	(segment
		(start 8.140446 -288.266632)
		(end 9.474708 -288.266632)
		(width 0.20066)
		(layer "F.Cu")
		(net "M_D_CPU1_SA_DQ<24>")
	)
	(segment
		(start 11.11631 -287.833562)
		(end 11.124438 -287.84169)
		(width 0.101854)
		(layer "F.Cu")
		(net "M_D_CPU1_SA_DQ<24>")
	)
	(segment
		(start 11.372342 -287.84169)
		(end 13.441426 -287.84169)
		(width 0.1016)
		(layer "F.Cu")
		(net "M_D_CPU1_SA_DQ<24>")
	)
	(segment
		(start 10.554462 -287.833562)
		(end 11.11631 -287.833562)
		(width 0.20066)
		(layer "F.Cu")
		(net "M_D_CPU1_SA_DQ<24>")
	)
	(segment
		(start 67.011804 -283.96819)
		(end 64.020446 -283.96819)
		(width 0.18288)
		(layer "In11.Cu")
		(net "M_D_CPU1_SA_DQ<24>")
	)
	(segment
		(start 17.842738 -289.599878)
		(end 17.649698 -289.406838)
		(width 0.18288)
		(layer "In11.Cu")
		(net "M_D_CPU1_SA_DQ<24>")
	)
	(segment
		(start 83.514184 -271.469612)
		(end 83.514184 -271.752314)
		(width 0.088646)
		(layer "In11.Cu")
		(net "M_D_CPU1_SA_DQ<24>")
	)
	(segment
		(start 50.423572 -288.69259)
		(end 49.280826 -289.336226)
		(width 0.18288)
		(layer "In11.Cu")
		(net "M_D_CPU1_SA_DQ<24>")
	)
	(segment
		(start 58.827162 -285.958026)
		(end 58.492136 -285.958026)
		(width 0.18288)
		(layer "In11.Cu")
		(net "M_D_CPU1_SA_DQ<24>")
	)
	(segment
		(start 95.975678 -269.881858)
		(end 95.960946 -269.873222)
		(width 0.088646)
		(layer "In11.Cu")
		(net "M_D_CPU1_SA_DQ<24>")
	)
	(segment
		(start 43.565826 -289.361626)
		(end 43.034966 -289.361626)
		(width 0.18288)
		(layer "In11.Cu")
		(net "M_D_CPU1_SA_DQ<24>")
	)
	(segment
		(start 18.350738 -289.406838)
		(end 18.157698 -289.599878)
		(width 0.18288)
		(layer "In11.Cu")
		(net "M_D_CPU1_SA_DQ<24>")
	)
	(segment
		(start 19.051778 -288.91611)
		(end 18.858738 -288.72307)
		(width 0.18288)
		(layer "In11.Cu")
		(net "M_D_CPU1_SA_DQ<24>")
	)
	(segment
		(start 84.95538 -270.35887)
		(end 84.624926 -270.35887)
		(width 0.088646)
		(layer "In11.Cu")
		(net "M_D_CPU1_SA_DQ<24>")
	)
	(segment
		(start 83.064604 -271.945354)
		(end 79.03464 -271.945354)
		(width 0.18288)
		(layer "In11.Cu")
		(net "M_D_CPU1_SA_DQ<24>")
	)
	(segment
		(start 19.975068 -287.842706)
		(end 19.752818 -288.064956)
		(width 0.18288)
		(layer "In11.Cu")
		(net "M_D_CPU1_SA_DQ<24>")
	)
	(segment
		(start 40.674798 -288.538158)
		(end 36.811458 -288.538158)
		(width 0.18288)
		(layer "In11.Cu")
		(net "M_D_CPU1_SA_DQ<24>")
	)
	(segment
		(start 30.000194 -289.666426)
		(end 29.595826 -289.666426)
		(width 0.18288)
		(layer "In11.Cu")
		(net "M_D_CPU1_SA_DQ<24>")
	)
	(segment
		(start 36.811458 -288.538158)
		(end 36.657026 -288.69259)
		(width 0.18288)
		(layer "In11.Cu")
		(net "M_D_CPU1_SA_DQ<24>")
	)
	(segment
		(start 85.905594 -269.948914)
		(end 85.365336 -269.948914)
		(width 0.088646)
		(layer "In11.Cu")
		(net "M_D_CPU1_SA_DQ<24>")
	)
	(segment
		(start 45.086524 -289.641026)
		(end 44.459906 -289.641026)
		(width 0.18288)
		(layer "In11.Cu")
		(net "M_D_CPU1_SA_DQ<24>")
	)
	(segment
		(start 63.123064 -284.865572)
		(end 62.115446 -285.282894)
		(width 0.18288)
		(layer "In11.Cu")
		(net "M_D_CPU1_SA_DQ<24>")
	)
	(segment
		(start 30.124146 -289.542474)
		(end 30.000194 -289.666426)
		(width 0.18288)
		(layer "In11.Cu")
		(net "M_D_CPU1_SA_DQ<24>")
	)
	(segment
		(start 44.459906 -289.641026)
		(end 43.565826 -289.361626)
		(width 0.18288)
		(layer "In11.Cu")
		(net "M_D_CPU1_SA_DQ<24>")
	)
	(segment
		(start 18.543778 -288.72307)
		(end 18.350738 -288.91611)
		(width 0.18288)
		(layer "In11.Cu")
		(net "M_D_CPU1_SA_DQ<24>")
	)
	(segment
		(start 18.157698 -289.599878)
		(end 17.842738 -289.599878)
		(width 0.18288)
		(layer "In11.Cu")
		(net "M_D_CPU1_SA_DQ<24>")
	)
	(segment
		(start 60.731654 -285.282894)
		(end 59.856624 -286.157924)
		(width 0.18288)
		(layer "In11.Cu")
		(net "M_D_CPU1_SA_DQ<24>")
	)
	(segment
		(start 17.456658 -288.69132)
		(end 17.213834 -288.69132)
		(width 0.18288)
		(layer "In11.Cu")
		(net "M_D_CPU1_SA_DQ<24>")
	)
	(segment
		(start 85.365336 -269.948914)
		(end 84.95538 -270.35887)
		(width 0.088646)
		(layer "In11.Cu")
		(net "M_D_CPU1_SA_DQ<24>")
	)
	(segment
		(start 93.156278 -269.881858)
		(end 93.141546 -269.873222)
		(width 0.088646)
		(layer "In11.Cu")
		(net "M_D_CPU1_SA_DQ<24>")
	)
	(segment
		(start 83.321144 -271.945354)
		(end 83.064604 -271.945354)
		(width 0.088646)
		(layer "In11.Cu")
		(net "M_D_CPU1_SA_DQ<24>")
	)
	(segment
		(start 19.051778 -289.406838)
		(end 19.051778 -288.91611)
		(width 0.18288)
		(layer "In11.Cu")
		(net "M_D_CPU1_SA_DQ<24>")
	)
	(segment
		(start 94.096078 -269.881858)
		(end 94.081346 -269.873222)
		(width 0.088646)
		(layer "In11.Cu")
		(net "M_D_CPU1_SA_DQ<24>")
	)
	(segment
		(start 45.83684 -289.542474)
		(end 45.086524 -289.641026)
		(width 0.18288)
		(layer "In11.Cu")
		(net "M_D_CPU1_SA_DQ<24>")
	)
	(segment
		(start 18.858738 -288.72307)
		(end 18.543778 -288.72307)
		(width 0.18288)
		(layer "In11.Cu")
		(net "M_D_CPU1_SA_DQ<24>")
	)
	(segment
		(start 54.26456 -288.243264)
		(end 54.249574 -288.246058)
		(width 0.18288)
		(layer "In11.Cu")
		(net "M_D_CPU1_SA_DQ<24>")
	)
	(segment
		(start 35.150806 -288.69259)
		(end 34.615628 -289.227768)
		(width 0.18288)
		(layer "In11.Cu")
		(net "M_D_CPU1_SA_DQ<24>")
	)
	(segment
		(start 54.868826 -288.015426)
		(end 54.26456 -288.243264)
		(width 0.18288)
		(layer "In11.Cu")
		(net "M_D_CPU1_SA_DQ<24>")
	)
	(segment
		(start 43.034966 -289.361626)
		(end 41.19499 -289.05835)
		(width 0.18288)
		(layer "In11.Cu")
		(net "M_D_CPU1_SA_DQ<24>")
	)
	(segment
		(start 91.827096 -269.873222)
		(end 91.816682 -269.879318)
		(width 0.088646)
		(layer "In11.Cu")
		(net "M_D_CPU1_SA_DQ<24>")
	)
	(segment
		(start 58.492136 -285.958026)
		(end 57.424828 -286.39643)
		(width 0.18288)
		(layer "In11.Cu")
		(net "M_D_CPU1_SA_DQ<24>")
	)
	(segment
		(start 95.035878 -269.881858)
		(end 95.021146 -269.873222)
		(width 0.088646)
		(layer "In11.Cu")
		(net "M_D_CPU1_SA_DQ<24>")
	)
	(segment
		(start 92.211906 -269.879318)
		(end 92.201492 -269.873222)
		(width 0.088646)
		(layer "In11.Cu")
		(net "M_D_CPU1_SA_DQ<24>")
	)
	(segment
		(start 79.03464 -271.945354)
		(end 67.011804 -283.96819)
		(width 0.18288)
		(layer "In11.Cu")
		(net "M_D_CPU1_SA_DQ<24>")
	)
	(segment
		(start 19.559778 -289.599878)
		(end 19.244818 -289.599878)
		(width 0.18288)
		(layer "In11.Cu")
		(net "M_D_CPU1_SA_DQ<24>")
	)
	(segment
		(start 17.649698 -289.406838)
		(end 17.649698 -288.88436)
		(width 0.18288)
		(layer "In11.Cu")
		(net "M_D_CPU1_SA_DQ<24>")
	)
	(segment
		(start 19.752818 -288.064956)
		(end 19.752818 -289.406838)
		(width 0.18288)
		(layer "In11.Cu")
		(net "M_D_CPU1_SA_DQ<24>")
	)
	(segment
		(start 56.3245 -287.316672)
		(end 54.868826 -288.015426)
		(width 0.18288)
		(layer "In11.Cu")
		(net "M_D_CPU1_SA_DQ<24>")
	)
	(segment
		(start 54.249574 -288.246058)
		(end 52.405026 -288.599626)
		(width 0.18288)
		(layer "In11.Cu")
		(net "M_D_CPU1_SA_DQ<24>")
	)
	(segment
		(start 32.364426 -289.542474)
		(end 30.124146 -289.542474)
		(width 0.18288)
		(layer "In11.Cu")
		(net "M_D_CPU1_SA_DQ<24>")
	)
	(segment
		(start 19.244818 -289.599878)
		(end 19.051778 -289.406838)
		(width 0.18288)
		(layer "In11.Cu")
		(net "M_D_CPU1_SA_DQ<24>")
	)
	(segment
		(start 59.856624 -286.157924)
		(end 59.02706 -286.157924)
		(width 0.18288)
		(layer "In11.Cu")
		(net "M_D_CPU1_SA_DQ<24>")
	)
	(segment
		(start 17.649698 -288.88436)
		(end 17.456658 -288.69132)
		(width 0.18288)
		(layer "In11.Cu")
		(net "M_D_CPU1_SA_DQ<24>")
	)
	(segment
		(start 83.514184 -271.752314)
		(end 83.321144 -271.945354)
		(width 0.088646)
		(layer "In11.Cu")
		(net "M_D_CPU1_SA_DQ<24>")
	)
	(segment
		(start 96.915478 -269.881858)
		(end 96.900746 -269.873222)
		(width 0.088646)
		(layer "In11.Cu")
		(net "M_D_CPU1_SA_DQ<24>")
	)
	(segment
		(start 36.657026 -288.69259)
		(end 35.150806 -288.69259)
		(width 0.18288)
		(layer "In11.Cu")
		(net "M_D_CPU1_SA_DQ<24>")
	)
	(segment
		(start 25.570942 -288.50082)
		(end 21.819616 -288.50082)
		(width 0.18288)
		(layer "In11.Cu")
		(net "M_D_CPU1_SA_DQ<24>")
	)
	(segment
		(start 26.05024 -288.980118)
		(end 25.570942 -288.50082)
		(width 0.18288)
		(layer "In11.Cu")
		(net "M_D_CPU1_SA_DQ<24>")
	)
	(segment
		(start 27.575002 -288.980118)
		(end 26.05024 -288.980118)
		(width 0.18288)
		(layer "In11.Cu")
		(net "M_D_CPU1_SA_DQ<24>")
	)
	(segment
		(start 49.280826 -289.336226)
		(end 48.899826 -289.336226)
		(width 0.18288)
		(layer "In11.Cu")
		(net "M_D_CPU1_SA_DQ<24>")
	)
	(segment
		(start 98.500184 -269.81785)
		(end 98.395282 -269.879318)
		(width 0.088646)
		(layer "In11.Cu")
		(net "M_D_CPU1_SA_DQ<24>")
	)
	(segment
		(start 64.020446 -283.96819)
		(end 63.123064 -284.865572)
		(width 0.18288)
		(layer "In11.Cu")
		(net "M_D_CPU1_SA_DQ<24>")
	)
	(segment
		(start 18.350738 -288.91611)
		(end 18.350738 -289.406838)
		(width 0.18288)
		(layer "In11.Cu")
		(net "M_D_CPU1_SA_DQ<24>")
	)
	(segment
		(start 19.752818 -289.406838)
		(end 19.559778 -289.599878)
		(width 0.18288)
		(layer "In11.Cu")
		(net "M_D_CPU1_SA_DQ<24>")
	)
	(segment
		(start 90.332306 -269.879318)
		(end 90.321892 -269.873222)
		(width 0.088646)
		(layer "In11.Cu")
		(net "M_D_CPU1_SA_DQ<24>")
	)
	(segment
		(start 34.615628 -289.227768)
		(end 34.193226 -289.412426)
		(width 0.18288)
		(layer "In11.Cu")
		(net "M_D_CPU1_SA_DQ<24>")
	)
	(segment
		(start 48.899826 -289.336226)
		(end 47.502826 -289.542474)
		(width 0.18288)
		(layer "In11.Cu")
		(net "M_D_CPU1_SA_DQ<24>")
	)
	(segment
		(start 34.193226 -289.412426)
		(end 33.278826 -289.412426)
		(width 0.18288)
		(layer "In11.Cu")
		(net "M_D_CPU1_SA_DQ<24>")
	)
	(segment
		(start 28.402026 -289.336226)
		(end 27.93111 -289.336226)
		(width 0.18288)
		(layer "In11.Cu")
		(net "M_D_CPU1_SA_DQ<24>")
	)
	(segment
		(start 84.624926 -270.35887)
		(end 83.514184 -271.469612)
		(width 0.088646)
		(layer "In11.Cu")
		(net "M_D_CPU1_SA_DQ<24>")
	)
	(segment
		(start 57.424828 -286.39643)
		(end 56.3245 -287.316672)
		(width 0.18288)
		(layer "In11.Cu")
		(net "M_D_CPU1_SA_DQ<24>")
	)
	(segment
		(start 21.819616 -288.50082)
		(end 21.161502 -287.842706)
		(width 0.18288)
		(layer "In11.Cu")
		(net "M_D_CPU1_SA_DQ<24>")
	)
	(segment
		(start 47.502826 -289.542474)
		(end 45.83684 -289.542474)
		(width 0.18288)
		(layer "In11.Cu")
		(net "M_D_CPU1_SA_DQ<24>")
	)
	(segment
		(start 62.115446 -285.282894)
		(end 60.731654 -285.282894)
		(width 0.18288)
		(layer "In11.Cu")
		(net "M_D_CPU1_SA_DQ<24>")
	)
	(segment
		(start 33.278826 -289.412426)
		(end 32.364426 -289.542474)
		(width 0.18288)
		(layer "In11.Cu")
		(net "M_D_CPU1_SA_DQ<24>")
	)
	(segment
		(start 29.595826 -289.666426)
		(end 28.402026 -289.336226)
		(width 0.18288)
		(layer "In11.Cu")
		(net "M_D_CPU1_SA_DQ<24>")
	)
	(segment
		(start 59.02706 -286.157924)
		(end 58.827162 -285.958026)
		(width 0.18288)
		(layer "In11.Cu")
		(net "M_D_CPU1_SA_DQ<24>")
	)
	(segment
		(start 52.405026 -288.599626)
		(end 51.566826 -288.69259)
		(width 0.18288)
		(layer "In11.Cu")
		(net "M_D_CPU1_SA_DQ<24>")
	)
	(segment
		(start 17.213834 -288.69132)
		(end 16.789146 -288.266632)
		(width 0.18288)
		(layer "In11.Cu")
		(net "M_D_CPU1_SA_DQ<24>")
	)
	(segment
		(start 41.19499 -289.05835)
		(end 40.674798 -288.538158)
		(width 0.18288)
		(layer "In11.Cu")
		(net "M_D_CPU1_SA_DQ<24>")
	)
	(segment
		(start 27.93111 -289.336226)
		(end 27.575002 -288.980118)
		(width 0.18288)
		(layer "In11.Cu")
		(net "M_D_CPU1_SA_DQ<24>")
	)
	(segment
		(start 51.566826 -288.69259)
		(end 50.423572 -288.69259)
		(width 0.18288)
		(layer "In11.Cu")
		(net "M_D_CPU1_SA_DQ<24>")
	)
	(segment
		(start 21.161502 -287.842706)
		(end 19.975068 -287.842706)
		(width 0.18288)
		(layer "In11.Cu")
		(net "M_D_CPU1_SA_DQ<24>")
	)
	(arc
		(start 92.201492 -269.873222)
		(mid 92.014294 -269.823079)
		(end 91.827096 -269.873222)
		(width 0.088646)
		(layer "In11.Cu")
		(net "M_D_CPU1_SA_DQ<24>")
	)
	(arc
		(start 96.52635 -269.873222)
		(mid 96.252121 -269.949147)
		(end 95.975678 -269.881858)
		(width 0.088646)
		(layer "In11.Cu")
		(net "M_D_CPU1_SA_DQ<24>")
	)
	(arc
		(start 97.46615 -269.873222)
		(mid 97.191921 -269.949147)
		(end 96.915478 -269.881858)
		(width 0.088646)
		(layer "In11.Cu")
		(net "M_D_CPU1_SA_DQ<24>")
	)
	(arc
		(start 99.062794 -269.38351)
		(mid 98.795397 -269.618695)
		(end 98.500184 -269.81785)
		(width 0.088646)
		(layer "In11.Cu")
		(net "M_D_CPU1_SA_DQ<24>")
	)
	(arc
		(start 97.840546 -269.873222)
		(mid 97.653348 -269.823079)
		(end 97.46615 -269.873222)
		(width 0.088646)
		(layer "In11.Cu")
		(net "M_D_CPU1_SA_DQ<24>")
	)
	(arc
		(start 86.188296 -269.873222)
		(mid 86.05193 -269.9297)
		(end 85.905594 -269.948914)
		(width 0.088646)
		(layer "In11.Cu")
		(net "M_D_CPU1_SA_DQ<24>")
	)
	(arc
		(start 95.960946 -269.873222)
		(mid 95.773748 -269.823079)
		(end 95.58655 -269.873222)
		(width 0.088646)
		(layer "In11.Cu")
		(net "M_D_CPU1_SA_DQ<24>")
	)
	(arc
		(start 91.816682 -269.879318)
		(mid 91.538504 -269.94901)
		(end 91.261946 -269.873222)
		(width 0.088646)
		(layer "In11.Cu")
		(net "M_D_CPU1_SA_DQ<24>")
	)
	(arc
		(start 94.64675 -269.873222)
		(mid 94.372521 -269.949147)
		(end 94.096078 -269.881858)
		(width 0.088646)
		(layer "In11.Cu")
		(net "M_D_CPU1_SA_DQ<24>")
	)
	(arc
		(start 88.067896 -269.873222)
		(mid 87.785194 -269.948964)
		(end 87.502492 -269.873222)
		(width 0.088646)
		(layer "In11.Cu")
		(net "M_D_CPU1_SA_DQ<24>")
	)
	(arc
		(start 93.70695 -269.873222)
		(mid 93.432721 -269.949147)
		(end 93.156278 -269.881858)
		(width 0.088646)
		(layer "In11.Cu")
		(net "M_D_CPU1_SA_DQ<24>")
	)
	(arc
		(start 87.128096 -269.873222)
		(mid 86.845394 -269.948964)
		(end 86.562692 -269.873222)
		(width 0.088646)
		(layer "In11.Cu")
		(net "M_D_CPU1_SA_DQ<24>")
	)
	(arc
		(start 87.502492 -269.873222)
		(mid 87.315294 -269.823079)
		(end 87.128096 -269.873222)
		(width 0.088646)
		(layer "In11.Cu")
		(net "M_D_CPU1_SA_DQ<24>")
	)
	(arc
		(start 88.442292 -269.873222)
		(mid 88.255094 -269.823079)
		(end 88.067896 -269.873222)
		(width 0.088646)
		(layer "In11.Cu")
		(net "M_D_CPU1_SA_DQ<24>")
	)
	(arc
		(start 89.007696 -269.873222)
		(mid 88.724994 -269.948964)
		(end 88.442292 -269.873222)
		(width 0.088646)
		(layer "In11.Cu")
		(net "M_D_CPU1_SA_DQ<24>")
	)
	(arc
		(start 91.261946 -269.873222)
		(mid 91.074748 -269.823079)
		(end 90.88755 -269.873222)
		(width 0.088646)
		(layer "In11.Cu")
		(net "M_D_CPU1_SA_DQ<24>")
	)
	(arc
		(start 92.76715 -269.873222)
		(mid 92.490337 -269.949058)
		(end 92.211906 -269.879318)
		(width 0.088646)
		(layer "In11.Cu")
		(net "M_D_CPU1_SA_DQ<24>")
	)
	(arc
		(start 89.947496 -269.873222)
		(mid 89.664794 -269.948964)
		(end 89.382092 -269.873222)
		(width 0.088646)
		(layer "In11.Cu")
		(net "M_D_CPU1_SA_DQ<24>")
	)
	(arc
		(start 96.900746 -269.873222)
		(mid 96.713548 -269.823079)
		(end 96.52635 -269.873222)
		(width 0.088646)
		(layer "In11.Cu")
		(net "M_D_CPU1_SA_DQ<24>")
	)
	(arc
		(start 98.395282 -269.879318)
		(mid 98.117104 -269.94901)
		(end 97.840546 -269.873222)
		(width 0.088646)
		(layer "In11.Cu")
		(net "M_D_CPU1_SA_DQ<24>")
	)
	(arc
		(start 90.88755 -269.873222)
		(mid 90.610737 -269.949058)
		(end 90.332306 -269.879318)
		(width 0.088646)
		(layer "In11.Cu")
		(net "M_D_CPU1_SA_DQ<24>")
	)
	(arc
		(start 89.382092 -269.873222)
		(mid 89.194894 -269.823079)
		(end 89.007696 -269.873222)
		(width 0.088646)
		(layer "In11.Cu")
		(net "M_D_CPU1_SA_DQ<24>")
	)
	(arc
		(start 86.562692 -269.873222)
		(mid 86.375494 -269.823079)
		(end 86.188296 -269.873222)
		(width 0.088646)
		(layer "In11.Cu")
		(net "M_D_CPU1_SA_DQ<24>")
	)
	(arc
		(start 95.58655 -269.873222)
		(mid 95.312321 -269.949147)
		(end 95.035878 -269.881858)
		(width 0.088646)
		(layer "In11.Cu")
		(net "M_D_CPU1_SA_DQ<24>")
	)
	(arc
		(start 90.321892 -269.873222)
		(mid 90.134694 -269.823079)
		(end 89.947496 -269.873222)
		(width 0.088646)
		(layer "In11.Cu")
		(net "M_D_CPU1_SA_DQ<24>")
	)
	(arc
		(start 95.021146 -269.873222)
		(mid 94.833948 -269.823079)
		(end 94.64675 -269.873222)
		(width 0.088646)
		(layer "In11.Cu")
		(net "M_D_CPU1_SA_DQ<24>")
	)
	(arc
		(start 94.081346 -269.873222)
		(mid 93.894148 -269.823079)
		(end 93.70695 -269.873222)
		(width 0.088646)
		(layer "In11.Cu")
		(net "M_D_CPU1_SA_DQ<24>")
	)
	(arc
		(start 93.141546 -269.873222)
		(mid 92.954348 -269.823079)
		(end 92.76715 -269.873222)
		(width 0.088646)
		(layer "In11.Cu")
		(net "M_D_CPU1_SA_DQ<24>")
	)
	(segment
		(start 16.885158 -289.541712)
		(end 17.42948 -289.541712)
		(width 0.20066)
		(layer "F.Cu")
		(net "M_D_CPU1_SA_DQ<23>")
	)
	(segment
		(start 18.760694 -289.324288)
		(end 18.968212 -289.11677)
		(width 0.20066)
		(layer "F.Cu")
		(net "M_D_CPU1_SA_DQ<23>")
	)
	(segment
		(start 18.968212 -289.11677)
		(end 19.784314 -289.11677)
		(width 0.20066)
		(layer "F.Cu")
		(net "M_D_CPU1_SA_DQ<23>")
	)
	(segment
		(start 14.20622 -289.555936)
		(end 14.560042 -289.555936)
		(width 0.20066)
		(layer "F.Cu")
		(net "M_D_CPU1_SA_DQ<23>")
	)
	(segment
		(start 17.578578 -289.240976)
		(end 17.707102 -289.112452)
		(width 0.20066)
		(layer "F.Cu")
		(net "M_D_CPU1_SA_DQ<23>")
	)
	(segment
		(start 17.707102 -289.112452)
		(end 18.102326 -289.112452)
		(width 0.20066)
		(layer "F.Cu")
		(net "M_D_CPU1_SA_DQ<23>")
	)
	(segment
		(start 17.578578 -289.392614)
		(end 17.578578 -289.240976)
		(width 0.20066)
		(layer "F.Cu")
		(net "M_D_CPU1_SA_DQ<23>")
	)
	(segment
		(start 14.574266 -289.541712)
		(end 14.812264 -289.541712)
		(width 0.101854)
		(layer "F.Cu")
		(net "M_D_CPU1_SA_DQ<23>")
	)
	(segment
		(start 17.42948 -289.541712)
		(end 17.578578 -289.392614)
		(width 0.20066)
		(layer "F.Cu")
		(net "M_D_CPU1_SA_DQ<23>")
	)
	(segment
		(start 20.889214 -289.11677)
		(end 19.784314 -289.11677)
		(width 0.20066)
		(layer "F.Cu")
		(net "M_D_CPU1_SA_DQ<23>")
	)
	(segment
		(start 14.063726 -289.413442)
		(end 14.20622 -289.555936)
		(width 0.20066)
		(layer "F.Cu")
		(net "M_D_CPU1_SA_DQ<23>")
	)
	(segment
		(start 18.102326 -289.112452)
		(end 18.314162 -289.324288)
		(width 0.20066)
		(layer "F.Cu")
		(net "M_D_CPU1_SA_DQ<23>")
	)
	(segment
		(start 18.314162 -289.324288)
		(end 18.760694 -289.324288)
		(width 0.20066)
		(layer "F.Cu")
		(net "M_D_CPU1_SA_DQ<23>")
	)
	(segment
		(start 13.937742 -289.11677)
		(end 14.063726 -289.242754)
		(width 0.20066)
		(layer "F.Cu")
		(net "M_D_CPU1_SA_DQ<23>")
	)
	(segment
		(start 14.063726 -289.242754)
		(end 14.063726 -289.413442)
		(width 0.20066)
		(layer "F.Cu")
		(net "M_D_CPU1_SA_DQ<23>")
	)
	(segment
		(start 14.560042 -289.555936)
		(end 14.574266 -289.541712)
		(width 0.101854)
		(layer "F.Cu")
		(net "M_D_CPU1_SA_DQ<23>")
	)
	(segment
		(start 12.240514 -289.11677)
		(end 13.937742 -289.11677)
		(width 0.20066)
		(layer "F.Cu")
		(net "M_D_CPU1_SA_DQ<23>")
	)
	(segment
		(start 14.812264 -289.541712)
		(end 16.885158 -289.541712)
		(width 0.1016)
		(layer "F.Cu")
		(net "M_D_CPU1_SA_DQ<23>")
	)
	(arc
		(start 100.002848 -270.475456)
		(mid 100.002784 -270.743426)
		(end 100.002594 -271.011396)
		(width 0.20066)
		(layer "F.Cu")
		(net "M_D_CPU1_SA_DQ<23>")
	)
	(segment
		(start 48.804322 -290.49091)
		(end 48.705516 -290.392104)
		(width 0.18288)
		(layer "In11.Cu")
		(net "M_D_CPU1_SA_DQ<23>")
	)
	(segment
		(start 30.598618 -291.04082)
		(end 30.598618 -291.313616)
		(width 0.18288)
		(layer "In11.Cu")
		(net "M_D_CPU1_SA_DQ<23>")
	)
	(segment
		(start 57.274968 -287.650936)
		(end 57.011824 -287.91408)
		(width 0.18288)
		(layer "In11.Cu")
		(net "M_D_CPU1_SA_DQ<23>")
	)
	(segment
		(start 26.531824 -290.555426)
		(end 26.09215 -290.555426)
		(width 0.18288)
		(layer "In11.Cu")
		(net "M_D_CPU1_SA_DQ<23>")
	)
	(segment
		(start 36.561014 -289.660838)
		(end 36.442142 -289.541966)
		(width 0.18288)
		(layer "In11.Cu")
		(net "M_D_CPU1_SA_DQ<23>")
	)
	(segment
		(start 55.529226 -288.828226)
		(end 54.533038 -289.824414)
		(width 0.18288)
		(layer "In11.Cu")
		(net "M_D_CPU1_SA_DQ<23>")
	)
	(segment
		(start 93.156278 -270.513302)
		(end 93.141546 -270.521938)
		(width 0.088646)
		(layer "In11.Cu")
		(net "M_D_CPU1_SA_DQ<23>")
	)
	(segment
		(start 42.481754 -291.233098)
		(end 42.288714 -291.040058)
		(width 0.18288)
		(layer "In11.Cu")
		(net "M_D_CPU1_SA_DQ<23>")
	)
	(segment
		(start 36.442142 -289.541966)
		(end 35.554666 -289.541966)
		(width 0.18288)
		(layer "In11.Cu")
		(net "M_D_CPU1_SA_DQ<23>")
	)
	(segment
		(start 58.170826 -287.177226)
		(end 57.697116 -287.650936)
		(width 0.18288)
		(layer "In11.Cu")
		(net "M_D_CPU1_SA_DQ<23>")
	)
	(segment
		(start 54.09565 -289.824414)
		(end 53.90261 -289.631374)
		(width 0.18288)
		(layer "In11.Cu")
		(net "M_D_CPU1_SA_DQ<23>")
	)
	(segment
		(start 57.011824 -288.336228)
		(end 56.519826 -288.828226)
		(width 0.18288)
		(layer "In11.Cu")
		(net "M_D_CPU1_SA_DQ<23>")
	)
	(segment
		(start 60.245498 -286.960818)
		(end 59.144916 -286.960818)
		(width 0.18288)
		(layer "In11.Cu")
		(net "M_D_CPU1_SA_DQ<23>")
	)
	(segment
		(start 79.387954 -272.747994)
		(end 66.703956 -285.431992)
		(width 0.18288)
		(layer "In11.Cu")
		(net "M_D_CPU1_SA_DQ<23>")
	)
	(segment
		(start 35.554666 -289.541966)
		(end 34.567622 -290.52901)
		(width 0.18288)
		(layer "In11.Cu")
		(net "M_D_CPU1_SA_DQ<23>")
	)
	(segment
		(start 60.752482 -286.453834)
		(end 60.245498 -286.960818)
		(width 0.18288)
		(layer "In11.Cu")
		(net "M_D_CPU1_SA_DQ<23>")
	)
	(segment
		(start 26.917904 -289.839908)
		(end 26.724864 -290.032948)
		(width 0.18288)
		(layer "In11.Cu")
		(net "M_D_CPU1_SA_DQ<23>")
	)
	(segment
		(start 44.153328 -290.6903)
		(end 43.979084 -290.516056)
		(width 0.18288)
		(layer "In11.Cu")
		(net "M_D_CPU1_SA_DQ<23>")
	)
	(segment
		(start 56.519826 -288.828226)
		(end 55.529226 -288.828226)
		(width 0.18288)
		(layer "In11.Cu")
		(net "M_D_CPU1_SA_DQ<23>")
	)
	(segment
		(start 28.694126 -290.555426)
		(end 27.618944 -290.555426)
		(width 0.18288)
		(layer "In11.Cu")
		(net "M_D_CPU1_SA_DQ<23>")
	)
	(segment
		(start 99.345496 -270.521938)
		(end 99.339654 -270.518636)
		(width 0.088646)
		(layer "In11.Cu")
		(net "M_D_CPU1_SA_DQ<23>")
	)
	(segment
		(start 26.09215 -290.555426)
		(end 25.24252 -289.705796)
		(width 0.18288)
		(layer "In11.Cu")
		(net "M_D_CPU1_SA_DQ<23>")
	)
	(segment
		(start 53.90261 -289.631374)
		(end 53.90261 -289.415982)
		(width 0.18288)
		(layer "In11.Cu")
		(net "M_D_CPU1_SA_DQ<23>")
	)
	(segment
		(start 53.00853 -289.824414)
		(end 51.967384 -289.824414)
		(width 0.18288)
		(layer "In11.Cu")
		(net "M_D_CPU1_SA_DQ<23>")
	)
	(segment
		(start 26.724864 -290.362386)
		(end 26.531824 -290.555426)
		(width 0.18288)
		(layer "In11.Cu")
		(net "M_D_CPU1_SA_DQ<23>")
	)
	(segment
		(start 64.100202 -285.431992)
		(end 61.633862 -286.453834)
		(width 0.18288)
		(layer "In11.Cu")
		(net "M_D_CPU1_SA_DQ<23>")
	)
	(segment
		(start 95.035878 -270.513302)
		(end 95.021146 -270.521938)
		(width 0.088646)
		(layer "In11.Cu")
		(net "M_D_CPU1_SA_DQ<23>")
	)
	(segment
		(start 25.24252 -289.705796)
		(end 23.824184 -289.705796)
		(width 0.18288)
		(layer "In11.Cu")
		(net "M_D_CPU1_SA_DQ<23>")
	)
	(segment
		(start 44.153328 -291.142928)
		(end 44.153328 -290.6903)
		(width 0.18288)
		(layer "In11.Cu")
		(net "M_D_CPU1_SA_DQ<23>")
	)
	(segment
		(start 65.689988 -285.238952)
		(end 65.689988 -284.989778)
		(width 0.18288)
		(layer "In11.Cu")
		(net "M_D_CPU1_SA_DQ<23>")
	)
	(segment
		(start 42.796714 -291.233098)
		(end 42.481754 -291.233098)
		(width 0.18288)
		(layer "In11.Cu")
		(net "M_D_CPU1_SA_DQ<23>")
	)
	(segment
		(start 65.689988 -284.989778)
		(end 65.496948 -284.796738)
		(width 0.18288)
		(layer "In11.Cu")
		(net "M_D_CPU1_SA_DQ<23>")
	)
	(segment
		(start 65.496948 -284.796738)
		(end 65.181988 -284.796738)
		(width 0.18288)
		(layer "In11.Cu")
		(net "M_D_CPU1_SA_DQ<23>")
	)
	(segment
		(start 57.697116 -287.650936)
		(end 57.274968 -287.650936)
		(width 0.18288)
		(layer "In11.Cu")
		(net "M_D_CPU1_SA_DQ<23>")
	)
	(segment
		(start 30.420056 -290.589462)
		(end 30.420056 -290.862258)
		(width 0.18288)
		(layer "In11.Cu")
		(net "M_D_CPU1_SA_DQ<23>")
	)
	(segment
		(start 23.824184 -289.705796)
		(end 23.467822 -289.349434)
		(width 0.18288)
		(layer "In11.Cu")
		(net "M_D_CPU1_SA_DQ<23>")
	)
	(segment
		(start 22.766782 -289.705796)
		(end 21.47824 -289.705796)
		(width 0.18288)
		(layer "In11.Cu")
		(net "M_D_CPU1_SA_DQ<23>")
	)
	(segment
		(start 92.211906 -270.515842)
		(end 92.201492 -270.521938)
		(width 0.088646)
		(layer "In11.Cu")
		(net "M_D_CPU1_SA_DQ<23>")
	)
	(segment
		(start 23.467822 -289.349434)
		(end 23.123144 -289.349434)
		(width 0.18288)
		(layer "In11.Cu")
		(net "M_D_CPU1_SA_DQ<23>")
	)
	(segment
		(start 100.002594 -271.011396)
		(end 99.68992 -271.011396)
		(width 0.088646)
		(layer "In11.Cu")
		(net "M_D_CPU1_SA_DQ<23>")
	)
	(segment
		(start 65.181988 -284.796738)
		(end 64.988948 -284.989778)
		(width 0.18288)
		(layer "In11.Cu")
		(net "M_D_CPU1_SA_DQ<23>")
	)
	(segment
		(start 57.011824 -287.91408)
		(end 57.011824 -288.336228)
		(width 0.18288)
		(layer "In11.Cu")
		(net "M_D_CPU1_SA_DQ<23>")
	)
	(segment
		(start 83.30692 -272.747994)
		(end 83.064604 -272.747994)
		(width 0.088646)
		(layer "In11.Cu")
		(net "M_D_CPU1_SA_DQ<23>")
	)
	(segment
		(start 42.989754 -291.040058)
		(end 42.796714 -291.233098)
		(width 0.18288)
		(layer "In11.Cu")
		(net "M_D_CPU1_SA_DQ<23>")
	)
	(segment
		(start 32.430974 -290.52901)
		(end 32.294068 -290.392104)
		(width 0.18288)
		(layer "In11.Cu")
		(net "M_D_CPU1_SA_DQ<23>")
	)
	(segment
		(start 50.102008 -289.858704)
		(end 49.469802 -290.49091)
		(width 0.18288)
		(layer "In11.Cu")
		(net "M_D_CPU1_SA_DQ<23>")
	)
	(segment
		(start 97.471738 -270.52524)
		(end 97.460054 -270.518636)
		(width 0.088646)
		(layer "In11.Cu")
		(net "M_D_CPU1_SA_DQ<23>")
	)
	(segment
		(start 85.435694 -270.572484)
		(end 84.680806 -270.572484)
		(width 0.088646)
		(layer "In11.Cu")
		(net "M_D_CPU1_SA_DQ<23>")
	)
	(segment
		(start 42.288714 -290.709096)
		(end 42.095674 -290.516056)
		(width 0.18288)
		(layer "In11.Cu")
		(net "M_D_CPU1_SA_DQ<23>")
	)
	(segment
		(start 64.795908 -285.431992)
		(end 64.100202 -285.431992)
		(width 0.18288)
		(layer "In11.Cu")
		(net "M_D_CPU1_SA_DQ<23>")
	)
	(segment
		(start 53.70957 -289.222942)
		(end 53.41747 -289.222942)
		(width 0.18288)
		(layer "In11.Cu")
		(net "M_D_CPU1_SA_DQ<23>")
	)
	(segment
		(start 53.90261 -289.415982)
		(end 53.70957 -289.222942)
		(width 0.18288)
		(layer "In11.Cu")
		(net "M_D_CPU1_SA_DQ<23>")
	)
	(segment
		(start 30.920182 -290.370768)
		(end 30.63875 -290.370768)
		(width 0.18288)
		(layer "In11.Cu")
		(net "M_D_CPU1_SA_DQ<23>")
	)
	(segment
		(start 83.70443 -271.54886)
		(end 83.70443 -271.99336)
		(width 0.088646)
		(layer "In11.Cu")
		(net "M_D_CPU1_SA_DQ<23>")
	)
	(segment
		(start 44.404026 -291.393626)
		(end 44.153328 -291.142928)
		(width 0.18288)
		(layer "In11.Cu")
		(net "M_D_CPU1_SA_DQ<23>")
	)
	(segment
		(start 91.27236 -270.515842)
		(end 91.261946 -270.521938)
		(width 0.088646)
		(layer "In11.Cu")
		(net "M_D_CPU1_SA_DQ<23>")
	)
	(segment
		(start 51.967384 -289.824414)
		(end 51.684936 -289.541966)
		(width 0.18288)
		(layer "In11.Cu")
		(net "M_D_CPU1_SA_DQ<23>")
	)
	(segment
		(start 30.598618 -291.313616)
		(end 30.430724 -291.48151)
		(width 0.18288)
		(layer "In11.Cu")
		(net "M_D_CPU1_SA_DQ<23>")
	)
	(segment
		(start 31.094426 -290.545012)
		(end 30.920182 -290.370768)
		(width 0.18288)
		(layer "In11.Cu")
		(net "M_D_CPU1_SA_DQ<23>")
	)
	(segment
		(start 59.144916 -286.960818)
		(end 58.928508 -287.177226)
		(width 0.18288)
		(layer "In11.Cu")
		(net "M_D_CPU1_SA_DQ<23>")
	)
	(segment
		(start 30.430724 -291.48151)
		(end 29.62021 -291.48151)
		(width 0.18288)
		(layer "In11.Cu")
		(net "M_D_CPU1_SA_DQ<23>")
	)
	(segment
		(start 30.420056 -290.862258)
		(end 30.598618 -291.04082)
		(width 0.18288)
		(layer "In11.Cu")
		(net "M_D_CPU1_SA_DQ<23>")
	)
	(segment
		(start 45.017944 -291.393626)
		(end 44.404026 -291.393626)
		(width 0.18288)
		(layer "In11.Cu")
		(net "M_D_CPU1_SA_DQ<23>")
	)
	(segment
		(start 27.232864 -289.839908)
		(end 26.917904 -289.839908)
		(width 0.18288)
		(layer "In11.Cu")
		(net "M_D_CPU1_SA_DQ<23>")
	)
	(segment
		(start 53.20157 -289.631374)
		(end 53.00853 -289.824414)
		(width 0.18288)
		(layer "In11.Cu")
		(net "M_D_CPU1_SA_DQ<23>")
	)
	(segment
		(start 64.988948 -285.238952)
		(end 64.795908 -285.431992)
		(width 0.18288)
		(layer "In11.Cu")
		(net "M_D_CPU1_SA_DQ<23>")
	)
	(segment
		(start 90.332306 -270.515842)
		(end 90.321892 -270.521938)
		(width 0.088646)
		(layer "In11.Cu")
		(net "M_D_CPU1_SA_DQ<23>")
	)
	(segment
		(start 98.411538 -270.52524)
		(end 98.399854 -270.518636)
		(width 0.088646)
		(layer "In11.Cu")
		(net "M_D_CPU1_SA_DQ<23>")
	)
	(segment
		(start 31.367222 -290.545012)
		(end 31.094426 -290.545012)
		(width 0.18288)
		(layer "In11.Cu")
		(net "M_D_CPU1_SA_DQ<23>")
	)
	(segment
		(start 50.821844 -289.560508)
		(end 50.102008 -289.858704)
		(width 0.18288)
		(layer "In11.Cu")
		(net "M_D_CPU1_SA_DQ<23>")
	)
	(segment
		(start 66.703956 -285.431992)
		(end 65.883028 -285.431992)
		(width 0.18288)
		(layer "In11.Cu")
		(net "M_D_CPU1_SA_DQ<23>")
	)
	(segment
		(start 83.064604 -272.747994)
		(end 79.387954 -272.747994)
		(width 0.18288)
		(layer "In11.Cu")
		(net "M_D_CPU1_SA_DQ<23>")
	)
	(segment
		(start 83.487514 -272.210276)
		(end 83.487514 -272.5674)
		(width 0.088646)
		(layer "In11.Cu")
		(net "M_D_CPU1_SA_DQ<23>")
	)
	(segment
		(start 42.095674 -290.516056)
		(end 40.692324 -290.516056)
		(width 0.18288)
		(layer "In11.Cu")
		(net "M_D_CPU1_SA_DQ<23>")
	)
	(segment
		(start 45.83811 -290.57346)
		(end 45.017944 -291.393626)
		(width 0.18288)
		(layer "In11.Cu")
		(net "M_D_CPU1_SA_DQ<23>")
	)
	(segment
		(start 49.469802 -290.49091)
		(end 48.804322 -290.49091)
		(width 0.18288)
		(layer "In11.Cu")
		(net "M_D_CPU1_SA_DQ<23>")
	)
	(segment
		(start 26.724864 -290.032948)
		(end 26.724864 -290.362386)
		(width 0.18288)
		(layer "In11.Cu")
		(net "M_D_CPU1_SA_DQ<23>")
	)
	(segment
		(start 50.866802 -289.541966)
		(end 50.821844 -289.560508)
		(width 0.18288)
		(layer "In11.Cu")
		(net "M_D_CPU1_SA_DQ<23>")
	)
	(segment
		(start 51.684936 -289.541966)
		(end 50.866802 -289.541966)
		(width 0.18288)
		(layer "In11.Cu")
		(net "M_D_CPU1_SA_DQ<23>")
	)
	(segment
		(start 65.883028 -285.431992)
		(end 65.689988 -285.238952)
		(width 0.18288)
		(layer "In11.Cu")
		(net "M_D_CPU1_SA_DQ<23>")
	)
	(segment
		(start 39.837106 -289.660838)
		(end 36.561014 -289.660838)
		(width 0.18288)
		(layer "In11.Cu")
		(net "M_D_CPU1_SA_DQ<23>")
	)
	(segment
		(start 27.425904 -290.362386)
		(end 27.425904 -290.032948)
		(width 0.18288)
		(layer "In11.Cu")
		(net "M_D_CPU1_SA_DQ<23>")
	)
	(segment
		(start 42.989754 -290.709096)
		(end 42.989754 -291.040058)
		(width 0.18288)
		(layer "In11.Cu")
		(net "M_D_CPU1_SA_DQ<23>")
	)
	(segment
		(start 32.294068 -290.392104)
		(end 31.52013 -290.392104)
		(width 0.18288)
		(layer "In11.Cu")
		(net "M_D_CPU1_SA_DQ<23>")
	)
	(segment
		(start 34.567622 -290.52901)
		(end 32.430974 -290.52901)
		(width 0.18288)
		(layer "In11.Cu")
		(net "M_D_CPU1_SA_DQ<23>")
	)
	(segment
		(start 31.52013 -290.392104)
		(end 31.367222 -290.545012)
		(width 0.18288)
		(layer "In11.Cu")
		(net "M_D_CPU1_SA_DQ<23>")
	)
	(segment
		(start 27.618944 -290.555426)
		(end 27.425904 -290.362386)
		(width 0.18288)
		(layer "In11.Cu")
		(net "M_D_CPU1_SA_DQ<23>")
	)
	(segment
		(start 84.680806 -270.572484)
		(end 83.70443 -271.54886)
		(width 0.088646)
		(layer "In11.Cu")
		(net "M_D_CPU1_SA_DQ<23>")
	)
	(segment
		(start 30.63875 -290.370768)
		(end 30.420056 -290.589462)
		(width 0.18288)
		(layer "In11.Cu")
		(net "M_D_CPU1_SA_DQ<23>")
	)
	(segment
		(start 61.633862 -286.453834)
		(end 60.752482 -286.453834)
		(width 0.18288)
		(layer "In11.Cu")
		(net "M_D_CPU1_SA_DQ<23>")
	)
	(segment
		(start 42.288714 -291.040058)
		(end 42.288714 -290.709096)
		(width 0.18288)
		(layer "In11.Cu")
		(net "M_D_CPU1_SA_DQ<23>")
	)
	(segment
		(start 64.988948 -284.989778)
		(end 64.988948 -285.238952)
		(width 0.18288)
		(layer "In11.Cu")
		(net "M_D_CPU1_SA_DQ<23>")
	)
	(segment
		(start 58.928508 -287.177226)
		(end 58.170826 -287.177226)
		(width 0.18288)
		(layer "In11.Cu")
		(net "M_D_CPU1_SA_DQ<23>")
	)
	(segment
		(start 99.68992 -271.011396)
		(end 99.624388 -270.945864)
		(width 0.088646)
		(layer "In11.Cu")
		(net "M_D_CPU1_SA_DQ<23>")
	)
	(segment
		(start 53.20157 -289.438842)
		(end 53.20157 -289.631374)
		(width 0.18288)
		(layer "In11.Cu")
		(net "M_D_CPU1_SA_DQ<23>")
	)
	(segment
		(start 43.979084 -290.516056)
		(end 43.182794 -290.516056)
		(width 0.18288)
		(layer "In11.Cu")
		(net "M_D_CPU1_SA_DQ<23>")
	)
	(segment
		(start 99.347528 -270.523208)
		(end 99.345496 -270.521938)
		(width 0.088646)
		(layer "In11.Cu")
		(net "M_D_CPU1_SA_DQ<23>")
	)
	(segment
		(start 46.275752 -290.392104)
		(end 45.83811 -290.57346)
		(width 0.18288)
		(layer "In11.Cu")
		(net "M_D_CPU1_SA_DQ<23>")
	)
	(segment
		(start 54.533038 -289.824414)
		(end 54.09565 -289.824414)
		(width 0.18288)
		(layer "In11.Cu")
		(net "M_D_CPU1_SA_DQ<23>")
	)
	(segment
		(start 40.692324 -290.516056)
		(end 39.837106 -289.660838)
		(width 0.18288)
		(layer "In11.Cu")
		(net "M_D_CPU1_SA_DQ<23>")
	)
	(segment
		(start 43.182794 -290.516056)
		(end 42.989754 -290.709096)
		(width 0.18288)
		(layer "In11.Cu")
		(net "M_D_CPU1_SA_DQ<23>")
	)
	(segment
		(start 27.425904 -290.032948)
		(end 27.232864 -289.839908)
		(width 0.18288)
		(layer "In11.Cu")
		(net "M_D_CPU1_SA_DQ<23>")
	)
	(segment
		(start 23.123144 -289.349434)
		(end 22.766782 -289.705796)
		(width 0.18288)
		(layer "In11.Cu")
		(net "M_D_CPU1_SA_DQ<23>")
	)
	(segment
		(start 83.487514 -272.5674)
		(end 83.30692 -272.747994)
		(width 0.088646)
		(layer "In11.Cu")
		(net "M_D_CPU1_SA_DQ<23>")
	)
	(segment
		(start 29.62021 -291.48151)
		(end 28.694126 -290.555426)
		(width 0.18288)
		(layer "In11.Cu")
		(net "M_D_CPU1_SA_DQ<23>")
	)
	(segment
		(start 21.47824 -289.705796)
		(end 20.889214 -289.11677)
		(width 0.18288)
		(layer "In11.Cu")
		(net "M_D_CPU1_SA_DQ<23>")
	)
	(segment
		(start 48.705516 -290.392104)
		(end 46.275752 -290.392104)
		(width 0.18288)
		(layer "In11.Cu")
		(net "M_D_CPU1_SA_DQ<23>")
	)
	(segment
		(start 96.531938 -270.52524)
		(end 96.520254 -270.518636)
		(width 0.088646)
		(layer "In11.Cu")
		(net "M_D_CPU1_SA_DQ<23>")
	)
	(segment
		(start 53.41747 -289.222942)
		(end 53.20157 -289.438842)
		(width 0.18288)
		(layer "In11.Cu")
		(net "M_D_CPU1_SA_DQ<23>")
	)
	(segment
		(start 83.70443 -271.99336)
		(end 83.487514 -272.210276)
		(width 0.088646)
		(layer "In11.Cu")
		(net "M_D_CPU1_SA_DQ<23>")
	)
	(arc
		(start 86.188296 -270.521938)
		(mid 85.905594 -270.446162)
		(end 85.622892 -270.521938)
		(width 0.088646)
		(layer "In11.Cu")
		(net "M_D_CPU1_SA_DQ<23>")
	)
	(arc
		(start 90.321892 -270.521938)
		(mid 90.134694 -270.572081)
		(end 89.947496 -270.521938)
		(width 0.088646)
		(layer "In11.Cu")
		(net "M_D_CPU1_SA_DQ<23>")
	)
	(arc
		(start 99.624388 -270.945864)
		(mid 99.535792 -270.701902)
		(end 99.347528 -270.523208)
		(width 0.088646)
		(layer "In11.Cu")
		(net "M_D_CPU1_SA_DQ<23>")
	)
	(arc
		(start 90.88755 -270.521938)
		(mid 90.610737 -270.446068)
		(end 90.332306 -270.515842)
		(width 0.088646)
		(layer "In11.Cu")
		(net "M_D_CPU1_SA_DQ<23>")
	)
	(arc
		(start 96.900746 -270.521938)
		(mid 96.716792 -270.572067)
		(end 96.531938 -270.52524)
		(width 0.088646)
		(layer "In11.Cu")
		(net "M_D_CPU1_SA_DQ<23>")
	)
	(arc
		(start 92.201492 -270.521938)
		(mid 92.014294 -270.572081)
		(end 91.827096 -270.521938)
		(width 0.088646)
		(layer "In11.Cu")
		(net "M_D_CPU1_SA_DQ<23>")
	)
	(arc
		(start 96.520254 -270.518636)
		(mid 96.240149 -270.446194)
		(end 95.960946 -270.521938)
		(width 0.088646)
		(layer "In11.Cu")
		(net "M_D_CPU1_SA_DQ<23>")
	)
	(arc
		(start 99.339654 -270.518636)
		(mid 99.059549 -270.446194)
		(end 98.780346 -270.521938)
		(width 0.088646)
		(layer "In11.Cu")
		(net "M_D_CPU1_SA_DQ<23>")
	)
	(arc
		(start 87.502492 -270.521938)
		(mid 87.315294 -270.572081)
		(end 87.128096 -270.521938)
		(width 0.088646)
		(layer "In11.Cu")
		(net "M_D_CPU1_SA_DQ<23>")
	)
	(arc
		(start 88.067896 -270.521938)
		(mid 87.785194 -270.446162)
		(end 87.502492 -270.521938)
		(width 0.088646)
		(layer "In11.Cu")
		(net "M_D_CPU1_SA_DQ<23>")
	)
	(arc
		(start 85.622892 -270.521938)
		(mid 85.532616 -270.559512)
		(end 85.435694 -270.572484)
		(width 0.088646)
		(layer "In11.Cu")
		(net "M_D_CPU1_SA_DQ<23>")
	)
	(arc
		(start 91.827096 -270.521938)
		(mid 91.550537 -270.446195)
		(end 91.27236 -270.515842)
		(width 0.088646)
		(layer "In11.Cu")
		(net "M_D_CPU1_SA_DQ<23>")
	)
	(arc
		(start 92.76715 -270.521938)
		(mid 92.490337 -270.446068)
		(end 92.211906 -270.515842)
		(width 0.088646)
		(layer "In11.Cu")
		(net "M_D_CPU1_SA_DQ<23>")
	)
	(arc
		(start 89.382092 -270.521938)
		(mid 89.194894 -270.572081)
		(end 89.007696 -270.521938)
		(width 0.088646)
		(layer "In11.Cu")
		(net "M_D_CPU1_SA_DQ<23>")
	)
	(arc
		(start 94.081346 -270.521938)
		(mid 93.894148 -270.572081)
		(end 93.70695 -270.521938)
		(width 0.088646)
		(layer "In11.Cu")
		(net "M_D_CPU1_SA_DQ<23>")
	)
	(arc
		(start 88.442292 -270.521938)
		(mid 88.255094 -270.572081)
		(end 88.067896 -270.521938)
		(width 0.088646)
		(layer "In11.Cu")
		(net "M_D_CPU1_SA_DQ<23>")
	)
	(arc
		(start 98.399854 -270.518636)
		(mid 98.119749 -270.446194)
		(end 97.840546 -270.521938)
		(width 0.088646)
		(layer "In11.Cu")
		(net "M_D_CPU1_SA_DQ<23>")
	)
	(arc
		(start 95.960946 -270.521938)
		(mid 95.773748 -270.572081)
		(end 95.58655 -270.521938)
		(width 0.088646)
		(layer "In11.Cu")
		(net "M_D_CPU1_SA_DQ<23>")
	)
	(arc
		(start 87.128096 -270.521938)
		(mid 86.845394 -270.446162)
		(end 86.562692 -270.521938)
		(width 0.088646)
		(layer "In11.Cu")
		(net "M_D_CPU1_SA_DQ<23>")
	)
	(arc
		(start 97.460054 -270.518636)
		(mid 97.179949 -270.446194)
		(end 96.900746 -270.521938)
		(width 0.088646)
		(layer "In11.Cu")
		(net "M_D_CPU1_SA_DQ<23>")
	)
	(arc
		(start 91.261946 -270.521938)
		(mid 91.074748 -270.572081)
		(end 90.88755 -270.521938)
		(width 0.088646)
		(layer "In11.Cu")
		(net "M_D_CPU1_SA_DQ<23>")
	)
	(arc
		(start 97.840546 -270.521938)
		(mid 97.656592 -270.572067)
		(end 97.471738 -270.52524)
		(width 0.088646)
		(layer "In11.Cu")
		(net "M_D_CPU1_SA_DQ<23>")
	)
	(arc
		(start 95.021146 -270.521938)
		(mid 94.833948 -270.572081)
		(end 94.64675 -270.521938)
		(width 0.088646)
		(layer "In11.Cu")
		(net "M_D_CPU1_SA_DQ<23>")
	)
	(arc
		(start 98.780346 -270.521938)
		(mid 98.596392 -270.572067)
		(end 98.411538 -270.52524)
		(width 0.088646)
		(layer "In11.Cu")
		(net "M_D_CPU1_SA_DQ<23>")
	)
	(arc
		(start 89.947496 -270.521938)
		(mid 89.664794 -270.446162)
		(end 89.382092 -270.521938)
		(width 0.088646)
		(layer "In11.Cu")
		(net "M_D_CPU1_SA_DQ<23>")
	)
	(arc
		(start 89.007696 -270.521938)
		(mid 88.724994 -270.446162)
		(end 88.442292 -270.521938)
		(width 0.088646)
		(layer "In11.Cu")
		(net "M_D_CPU1_SA_DQ<23>")
	)
	(arc
		(start 94.64675 -270.521938)
		(mid 94.364048 -270.446162)
		(end 94.081346 -270.521938)
		(width 0.088646)
		(layer "In11.Cu")
		(net "M_D_CPU1_SA_DQ<23>")
	)
	(arc
		(start 86.562692 -270.521938)
		(mid 86.375494 -270.572081)
		(end 86.188296 -270.521938)
		(width 0.088646)
		(layer "In11.Cu")
		(net "M_D_CPU1_SA_DQ<23>")
	)
	(arc
		(start 93.141546 -270.521938)
		(mid 92.954348 -270.572081)
		(end 92.76715 -270.521938)
		(width 0.088646)
		(layer "In11.Cu")
		(net "M_D_CPU1_SA_DQ<23>")
	)
	(arc
		(start 95.58655 -270.521938)
		(mid 95.312351 -270.446103)
		(end 95.035878 -270.513302)
		(width 0.088646)
		(layer "In11.Cu")
		(net "M_D_CPU1_SA_DQ<23>")
	)
	(arc
		(start 93.70695 -270.521938)
		(mid 93.432751 -270.446103)
		(end 93.156278 -270.513302)
		(width 0.088646)
		(layer "In11.Cu")
		(net "M_D_CPU1_SA_DQ<23>")
	)
	(segment
		(start 18.257774 -291.028628)
		(end 18.46961 -290.816792)
		(width 0.20066)
		(layer "F.Cu")
		(net "M_D_CPU1_SA_DQ<22>")
	)
	(segment
		(start 12.240514 -290.816792)
		(end 13.387578 -290.816792)
		(width 0.20066)
		(layer "F.Cu")
		(net "M_D_CPU1_SA_DQ<22>")
	)
	(segment
		(start 17.518126 -290.39185)
		(end 17.66189 -290.535614)
		(width 0.20066)
		(layer "F.Cu")
		(net "M_D_CPU1_SA_DQ<22>")
	)
	(segment
		(start 13.82268 -290.38169)
		(end 14.560042 -290.38169)
		(width 0.20066)
		(layer "F.Cu")
		(net "M_D_CPU1_SA_DQ<22>")
	)
	(segment
		(start 14.570202 -290.39185)
		(end 14.825218 -290.39185)
		(width 0.101854)
		(layer "F.Cu")
		(net "M_D_CPU1_SA_DQ<22>")
	)
	(segment
		(start 16.885158 -290.39185)
		(end 17.518126 -290.39185)
		(width 0.20066)
		(layer "F.Cu")
		(net "M_D_CPU1_SA_DQ<22>")
	)
	(segment
		(start 13.387578 -290.816792)
		(end 13.82268 -290.38169)
		(width 0.20066)
		(layer "F.Cu")
		(net "M_D_CPU1_SA_DQ<22>")
	)
	(segment
		(start 14.825218 -290.39185)
		(end 16.885158 -290.39185)
		(width 0.1016)
		(layer "F.Cu")
		(net "M_D_CPU1_SA_DQ<22>")
	)
	(segment
		(start 20.889214 -290.816792)
		(end 19.784314 -290.816792)
		(width 0.20066)
		(layer "F.Cu")
		(net "M_D_CPU1_SA_DQ<22>")
	)
	(segment
		(start 17.66189 -290.861242)
		(end 17.829276 -291.028628)
		(width 0.20066)
		(layer "F.Cu")
		(net "M_D_CPU1_SA_DQ<22>")
	)
	(segment
		(start 100.472494 -271.289272)
		(end 100.472748 -271.289526)
		(width 0.20066)
		(layer "F.Cu")
		(net "M_D_CPU1_SA_DQ<22>")
	)
	(segment
		(start 17.66189 -290.535614)
		(end 17.66189 -290.861242)
		(width 0.20066)
		(layer "F.Cu")
		(net "M_D_CPU1_SA_DQ<22>")
	)
	(segment
		(start 100.472748 -271.289526)
		(end 100.472748 -271.825212)
		(width 0.20066)
		(layer "F.Cu")
		(net "M_D_CPU1_SA_DQ<22>")
	)
	(segment
		(start 17.829276 -291.028628)
		(end 18.257774 -291.028628)
		(width 0.20066)
		(layer "F.Cu")
		(net "M_D_CPU1_SA_DQ<22>")
	)
	(segment
		(start 18.46961 -290.816792)
		(end 19.784314 -290.816792)
		(width 0.20066)
		(layer "F.Cu")
		(net "M_D_CPU1_SA_DQ<22>")
	)
	(segment
		(start 14.560042 -290.38169)
		(end 14.570202 -290.39185)
		(width 0.101854)
		(layer "F.Cu")
		(net "M_D_CPU1_SA_DQ<22>")
	)
	(segment
		(start 99.250246 -271.335754)
		(end 99.244404 -271.33931)
		(width 0.088646)
		(layer "In11.Cu")
		(net "M_D_CPU1_SA_DQ<22>")
	)
	(segment
		(start 98.316288 -271.332452)
		(end 98.310446 -271.335754)
		(width 0.088646)
		(layer "In11.Cu")
		(net "M_D_CPU1_SA_DQ<22>")
	)
	(segment
		(start 99.256088 -271.332452)
		(end 99.250246 -271.335754)
		(width 0.088646)
		(layer "In11.Cu")
		(net "M_D_CPU1_SA_DQ<22>")
	)
	(segment
		(start 93.236796 -271.335754)
		(end 93.222064 -271.327118)
		(width 0.088646)
		(layer "In11.Cu")
		(net "M_D_CPU1_SA_DQ<22>")
	)
	(segment
		(start 48.771302 -292.319456)
		(end 48.327818 -292.319456)
		(width 0.18288)
		(layer "In11.Cu")
		(net "M_D_CPU1_SA_DQ<22>")
	)
	(segment
		(start 96.056196 -271.335754)
		(end 96.041464 -271.327118)
		(width 0.088646)
		(layer "In11.Cu")
		(net "M_D_CPU1_SA_DQ<22>")
	)
	(segment
		(start 84.965794 -271.3863)
		(end 84.527644 -271.3863)
		(width 0.088646)
		(layer "In11.Cu")
		(net "M_D_CPU1_SA_DQ<22>")
	)
	(segment
		(start 38.751002 -291.282628)
		(end 38.557962 -291.089588)
		(width 0.18288)
		(layer "In11.Cu")
		(net "M_D_CPU1_SA_DQ<22>")
	)
	(segment
		(start 22.759924 -291.00526)
		(end 22.759924 -291.144198)
		(width 0.18288)
		(layer "In11.Cu")
		(net "M_D_CPU1_SA_DQ<22>")
	)
	(segment
		(start 89.477596 -271.335754)
		(end 89.462864 -271.327118)
		(width 0.088646)
		(layer "In11.Cu")
		(net "M_D_CPU1_SA_DQ<22>")
	)
	(segment
		(start 61.13018 -287.537652)
		(end 60.929012 -287.73882)
		(width 0.18288)
		(layer "In11.Cu")
		(net "M_D_CPU1_SA_DQ<22>")
	)
	(segment
		(start 26.759662 -292.205664)
		(end 26.265886 -292.205664)
		(width 0.18288)
		(layer "In11.Cu")
		(net "M_D_CPU1_SA_DQ<22>")
	)
	(segment
		(start 23.460964 -291.00526)
		(end 23.267924 -290.81222)
		(width 0.18288)
		(layer "In11.Cu")
		(net "M_D_CPU1_SA_DQ<22>")
	)
	(segment
		(start 43.367706 -292.993826)
		(end 42.656506 -292.282626)
		(width 0.18288)
		(layer "In11.Cu")
		(net "M_D_CPU1_SA_DQ<22>")
	)
	(segment
		(start 98.310446 -271.335754)
		(end 98.304604 -271.33931)
		(width 0.088646)
		(layer "In11.Cu")
		(net "M_D_CPU1_SA_DQ<22>")
	)
	(segment
		(start 61.63818 -288.414206)
		(end 61.63818 -287.697672)
		(width 0.18288)
		(layer "In11.Cu")
		(net "M_D_CPU1_SA_DQ<22>")
	)
	(segment
		(start 83.882484 -273.333464)
		(end 83.451954 -273.763994)
		(width 0.088646)
		(layer "In11.Cu")
		(net "M_D_CPU1_SA_DQ<22>")
	)
	(segment
		(start 36.69919 -291.282628)
		(end 36.658804 -291.242242)
		(width 0.18288)
		(layer "In11.Cu")
		(net "M_D_CPU1_SA_DQ<22>")
	)
	(segment
		(start 83.064858 -273.763994)
		(end 79.868268 -273.763994)
		(width 0.18288)
		(layer "In11.Cu")
		(net "M_D_CPU1_SA_DQ<22>")
	)
	(segment
		(start 49.518824 -292.09238)
		(end 48.998378 -292.09238)
		(width 0.18288)
		(layer "In11.Cu")
		(net "M_D_CPU1_SA_DQ<22>")
	)
	(segment
		(start 27.653742 -291.855906)
		(end 27.460702 -291.662866)
		(width 0.18288)
		(layer "In11.Cu")
		(net "M_D_CPU1_SA_DQ<22>")
	)
	(segment
		(start 48.998378 -292.09238)
		(end 48.771302 -292.319456)
		(width 0.18288)
		(layer "In11.Cu")
		(net "M_D_CPU1_SA_DQ<22>")
	)
	(segment
		(start 62.474602 -288.367978)
		(end 62.268354 -288.574226)
		(width 0.18288)
		(layer "In11.Cu")
		(net "M_D_CPU1_SA_DQ<22>")
	)
	(segment
		(start 79.868268 -273.763994)
		(end 66.516504 -287.115758)
		(width 0.18288)
		(layer "In11.Cu")
		(net "M_D_CPU1_SA_DQ<22>")
	)
	(segment
		(start 38.049962 -290.820856)
		(end 37.856922 -291.013896)
		(width 0.18288)
		(layer "In11.Cu")
		(net "M_D_CPU1_SA_DQ<22>")
	)
	(segment
		(start 62.268354 -288.574226)
		(end 61.7982 -288.574226)
		(width 0.18288)
		(layer "In11.Cu")
		(net "M_D_CPU1_SA_DQ<22>")
	)
	(segment
		(start 37.856922 -291.013896)
		(end 37.856922 -291.089588)
		(width 0.18288)
		(layer "In11.Cu")
		(net "M_D_CPU1_SA_DQ<22>")
	)
	(segment
		(start 83.882484 -272.376646)
		(end 83.882484 -273.333464)
		(width 0.088646)
		(layer "In11.Cu")
		(net "M_D_CPU1_SA_DQ<22>")
	)
	(segment
		(start 23.460964 -291.144198)
		(end 23.460964 -291.00526)
		(width 0.18288)
		(layer "In11.Cu")
		(net "M_D_CPU1_SA_DQ<22>")
	)
	(segment
		(start 25.88895 -292.049454)
		(end 25.176734 -291.337238)
		(width 0.18288)
		(layer "In11.Cu")
		(net "M_D_CPU1_SA_DQ<22>")
	)
	(segment
		(start 83.451954 -273.763994)
		(end 83.064858 -273.763994)
		(width 0.088646)
		(layer "In11.Cu")
		(net "M_D_CPU1_SA_DQ<22>")
	)
	(segment
		(start 62.474602 -287.829244)
		(end 62.474602 -288.367978)
		(width 0.18288)
		(layer "In11.Cu")
		(net "M_D_CPU1_SA_DQ<22>")
	)
	(segment
		(start 22.566884 -291.337238)
		(end 21.40966 -291.337238)
		(width 0.18288)
		(layer "In11.Cu")
		(net "M_D_CPU1_SA_DQ<22>")
	)
	(segment
		(start 84.527644 -271.3863)
		(end 84.084922 -271.829022)
		(width 0.088646)
		(layer "In11.Cu")
		(net "M_D_CPU1_SA_DQ<22>")
	)
	(segment
		(start 60.929012 -288.414206)
		(end 60.768992 -288.574226)
		(width 0.18288)
		(layer "In11.Cu")
		(net "M_D_CPU1_SA_DQ<22>")
	)
	(segment
		(start 27.460702 -291.662866)
		(end 27.145742 -291.662866)
		(width 0.18288)
		(layer "In11.Cu")
		(net "M_D_CPU1_SA_DQ<22>")
	)
	(segment
		(start 63.188088 -287.115758)
		(end 62.474602 -287.829244)
		(width 0.18288)
		(layer "In11.Cu")
		(net "M_D_CPU1_SA_DQ<22>")
	)
	(segment
		(start 97.376488 -271.332452)
		(end 97.349564 -271.347438)
		(width 0.088646)
		(layer "In11.Cu")
		(net "M_D_CPU1_SA_DQ<22>")
	)
	(segment
		(start 26.952702 -291.855906)
		(end 26.952702 -292.012624)
		(width 0.18288)
		(layer "In11.Cu")
		(net "M_D_CPU1_SA_DQ<22>")
	)
	(segment
		(start 29.293312 -293.081456)
		(end 28.41752 -292.205664)
		(width 0.18288)
		(layer "In11.Cu")
		(net "M_D_CPU1_SA_DQ<22>")
	)
	(segment
		(start 32.320484 -292.09238)
		(end 31.351982 -292.09238)
		(width 0.18288)
		(layer "In11.Cu")
		(net "M_D_CPU1_SA_DQ<22>")
	)
	(segment
		(start 34.45002 -292.328854)
		(end 33.898078 -292.328854)
		(width 0.18288)
		(layer "In11.Cu")
		(net "M_D_CPU1_SA_DQ<22>")
	)
	(segment
		(start 55.757826 -290.530026)
		(end 54.893972 -291.39388)
		(width 0.18288)
		(layer "In11.Cu")
		(net "M_D_CPU1_SA_DQ<22>")
	)
	(segment
		(start 84.084922 -271.829022)
		(end 84.084922 -272.174208)
		(width 0.088646)
		(layer "In11.Cu")
		(net "M_D_CPU1_SA_DQ<22>")
	)
	(segment
		(start 28.41752 -292.205664)
		(end 27.846782 -292.205664)
		(width 0.18288)
		(layer "In11.Cu")
		(net "M_D_CPU1_SA_DQ<22>")
	)
	(segment
		(start 35.536632 -291.242242)
		(end 34.45002 -292.328854)
		(width 0.18288)
		(layer "In11.Cu")
		(net "M_D_CPU1_SA_DQ<22>")
	)
	(segment
		(start 42.656506 -292.282626)
		(end 40.771826 -292.282626)
		(width 0.18288)
		(layer "In11.Cu")
		(net "M_D_CPU1_SA_DQ<22>")
	)
	(segment
		(start 27.653742 -292.012624)
		(end 27.653742 -291.855906)
		(width 0.18288)
		(layer "In11.Cu")
		(net "M_D_CPU1_SA_DQ<22>")
	)
	(segment
		(start 39.771828 -291.282628)
		(end 38.751002 -291.282628)
		(width 0.18288)
		(layer "In11.Cu")
		(net "M_D_CPU1_SA_DQ<22>")
	)
	(segment
		(start 51.784758 -291.242242)
		(end 50.368962 -291.242242)
		(width 0.18288)
		(layer "In11.Cu")
		(net "M_D_CPU1_SA_DQ<22>")
	)
	(segment
		(start 60.929012 -287.73882)
		(end 60.929012 -288.414206)
		(width 0.18288)
		(layer "In11.Cu")
		(net "M_D_CPU1_SA_DQ<22>")
	)
	(segment
		(start 61.47816 -287.537652)
		(end 61.13018 -287.537652)
		(width 0.18288)
		(layer "In11.Cu")
		(net "M_D_CPU1_SA_DQ<22>")
	)
	(segment
		(start 38.364922 -290.820856)
		(end 38.049962 -290.820856)
		(width 0.18288)
		(layer "In11.Cu")
		(net "M_D_CPU1_SA_DQ<22>")
	)
	(segment
		(start 61.7982 -288.574226)
		(end 61.63818 -288.414206)
		(width 0.18288)
		(layer "In11.Cu")
		(net "M_D_CPU1_SA_DQ<22>")
	)
	(segment
		(start 60.768992 -288.574226)
		(end 59.136026 -288.574226)
		(width 0.18288)
		(layer "In11.Cu")
		(net "M_D_CPU1_SA_DQ<22>")
	)
	(segment
		(start 22.759924 -291.144198)
		(end 22.566884 -291.337238)
		(width 0.18288)
		(layer "In11.Cu")
		(net "M_D_CPU1_SA_DQ<22>")
	)
	(segment
		(start 22.952964 -290.81222)
		(end 22.759924 -291.00526)
		(width 0.18288)
		(layer "In11.Cu")
		(net "M_D_CPU1_SA_DQ<22>")
	)
	(segment
		(start 48.100742 -292.09238)
		(end 46.361096 -292.09238)
		(width 0.18288)
		(layer "In11.Cu")
		(net "M_D_CPU1_SA_DQ<22>")
	)
	(segment
		(start 54.893972 -291.39388)
		(end 51.936396 -291.39388)
		(width 0.18288)
		(layer "In11.Cu")
		(net "M_D_CPU1_SA_DQ<22>")
	)
	(segment
		(start 32.556958 -292.328854)
		(end 32.320484 -292.09238)
		(width 0.18288)
		(layer "In11.Cu")
		(net "M_D_CPU1_SA_DQ<22>")
	)
	(segment
		(start 48.327818 -292.319456)
		(end 48.100742 -292.09238)
		(width 0.18288)
		(layer "In11.Cu")
		(net "M_D_CPU1_SA_DQ<22>")
	)
	(segment
		(start 27.846782 -292.205664)
		(end 27.653742 -292.012624)
		(width 0.18288)
		(layer "In11.Cu")
		(net "M_D_CPU1_SA_DQ<22>")
	)
	(segment
		(start 25.176734 -291.337238)
		(end 23.654004 -291.337238)
		(width 0.18288)
		(layer "In11.Cu")
		(net "M_D_CPU1_SA_DQ<22>")
	)
	(segment
		(start 92.296996 -271.335754)
		(end 92.282264 -271.327118)
		(width 0.088646)
		(layer "In11.Cu")
		(net "M_D_CPU1_SA_DQ<22>")
	)
	(segment
		(start 37.663882 -291.282628)
		(end 36.69919 -291.282628)
		(width 0.18288)
		(layer "In11.Cu")
		(net "M_D_CPU1_SA_DQ<22>")
	)
	(segment
		(start 46.361096 -292.09238)
		(end 45.45965 -292.993826)
		(width 0.18288)
		(layer "In11.Cu")
		(net "M_D_CPU1_SA_DQ<22>")
	)
	(segment
		(start 26.265886 -292.205664)
		(end 25.88895 -292.049454)
		(width 0.18288)
		(layer "In11.Cu")
		(net "M_D_CPU1_SA_DQ<22>")
	)
	(segment
		(start 45.45965 -292.993826)
		(end 43.367706 -292.993826)
		(width 0.18288)
		(layer "In11.Cu")
		(net "M_D_CPU1_SA_DQ<22>")
	)
	(segment
		(start 38.557962 -291.089588)
		(end 38.557962 -291.013896)
		(width 0.18288)
		(layer "In11.Cu")
		(net "M_D_CPU1_SA_DQ<22>")
	)
	(segment
		(start 58.223658 -288.777426)
		(end 56.471058 -290.530026)
		(width 0.18288)
		(layer "In11.Cu")
		(net "M_D_CPU1_SA_DQ<22>")
	)
	(segment
		(start 84.084922 -272.174208)
		(end 83.882484 -272.376646)
		(width 0.088646)
		(layer "In11.Cu")
		(net "M_D_CPU1_SA_DQ<22>")
	)
	(segment
		(start 99.895914 -271.38249)
		(end 99.815396 -271.336008)
		(width 0.088646)
		(layer "In11.Cu")
		(net "M_D_CPU1_SA_DQ<22>")
	)
	(segment
		(start 40.771826 -292.282626)
		(end 39.771828 -291.282628)
		(width 0.18288)
		(layer "In11.Cu")
		(net "M_D_CPU1_SA_DQ<22>")
	)
	(segment
		(start 33.661604 -292.09238)
		(end 33.227518 -292.09238)
		(width 0.18288)
		(layer "In11.Cu")
		(net "M_D_CPU1_SA_DQ<22>")
	)
	(segment
		(start 59.136026 -288.574226)
		(end 58.932826 -288.777426)
		(width 0.18288)
		(layer "In11.Cu")
		(net "M_D_CPU1_SA_DQ<22>")
	)
	(segment
		(start 38.557962 -291.013896)
		(end 38.364922 -290.820856)
		(width 0.18288)
		(layer "In11.Cu")
		(net "M_D_CPU1_SA_DQ<22>")
	)
	(segment
		(start 37.856922 -291.089588)
		(end 37.663882 -291.282628)
		(width 0.18288)
		(layer "In11.Cu")
		(net "M_D_CPU1_SA_DQ<22>")
	)
	(segment
		(start 61.63818 -287.697672)
		(end 61.47816 -287.537652)
		(width 0.18288)
		(layer "In11.Cu")
		(net "M_D_CPU1_SA_DQ<22>")
	)
	(segment
		(start 21.40966 -291.337238)
		(end 20.889214 -290.816792)
		(width 0.18288)
		(layer "In11.Cu")
		(net "M_D_CPU1_SA_DQ<22>")
	)
	(segment
		(start 36.658804 -291.242242)
		(end 35.536632 -291.242242)
		(width 0.18288)
		(layer "In11.Cu")
		(net "M_D_CPU1_SA_DQ<22>")
	)
	(segment
		(start 30.362906 -293.081456)
		(end 29.293312 -293.081456)
		(width 0.18288)
		(layer "In11.Cu")
		(net "M_D_CPU1_SA_DQ<22>")
	)
	(segment
		(start 27.145742 -291.662866)
		(end 26.952702 -291.855906)
		(width 0.18288)
		(layer "In11.Cu")
		(net "M_D_CPU1_SA_DQ<22>")
	)
	(segment
		(start 23.267924 -290.81222)
		(end 22.952964 -290.81222)
		(width 0.18288)
		(layer "In11.Cu")
		(net "M_D_CPU1_SA_DQ<22>")
	)
	(segment
		(start 95.116396 -271.335754)
		(end 95.105982 -271.329658)
		(width 0.088646)
		(layer "In11.Cu")
		(net "M_D_CPU1_SA_DQ<22>")
	)
	(segment
		(start 50.368962 -291.242242)
		(end 49.518824 -292.09238)
		(width 0.18288)
		(layer "In11.Cu")
		(net "M_D_CPU1_SA_DQ<22>")
	)
	(segment
		(start 26.952702 -292.012624)
		(end 26.759662 -292.205664)
		(width 0.18288)
		(layer "In11.Cu")
		(net "M_D_CPU1_SA_DQ<22>")
	)
	(segment
		(start 23.654004 -291.337238)
		(end 23.460964 -291.144198)
		(width 0.18288)
		(layer "In11.Cu")
		(net "M_D_CPU1_SA_DQ<22>")
	)
	(segment
		(start 66.516504 -287.115758)
		(end 63.188088 -287.115758)
		(width 0.18288)
		(layer "In11.Cu")
		(net "M_D_CPU1_SA_DQ<22>")
	)
	(segment
		(start 56.471058 -290.530026)
		(end 55.757826 -290.530026)
		(width 0.18288)
		(layer "In11.Cu")
		(net "M_D_CPU1_SA_DQ<22>")
	)
	(segment
		(start 33.227518 -292.09238)
		(end 32.991044 -292.328854)
		(width 0.18288)
		(layer "In11.Cu")
		(net "M_D_CPU1_SA_DQ<22>")
	)
	(segment
		(start 32.991044 -292.328854)
		(end 32.556958 -292.328854)
		(width 0.18288)
		(layer "In11.Cu")
		(net "M_D_CPU1_SA_DQ<22>")
	)
	(segment
		(start 96.431354 -271.335754)
		(end 96.430592 -271.335754)
		(width 0.088646)
		(layer "In11.Cu")
		(net "M_D_CPU1_SA_DQ<22>")
	)
	(segment
		(start 51.936396 -291.39388)
		(end 51.784758 -291.242242)
		(width 0.18288)
		(layer "In11.Cu")
		(net "M_D_CPU1_SA_DQ<22>")
	)
	(segment
		(start 58.932826 -288.777426)
		(end 58.223658 -288.777426)
		(width 0.18288)
		(layer "In11.Cu")
		(net "M_D_CPU1_SA_DQ<22>")
	)
	(segment
		(start 31.351982 -292.09238)
		(end 30.362906 -293.081456)
		(width 0.18288)
		(layer "In11.Cu")
		(net "M_D_CPU1_SA_DQ<22>")
	)
	(segment
		(start 33.898078 -292.328854)
		(end 33.661604 -292.09238)
		(width 0.18288)
		(layer "In11.Cu")
		(net "M_D_CPU1_SA_DQ<22>")
	)
	(segment
		(start 94.17685 -271.335754)
		(end 94.166436 -271.329658)
		(width 0.088646)
		(layer "In11.Cu")
		(net "M_D_CPU1_SA_DQ<22>")
	)
	(arc
		(start 97.935796 -271.336008)
		(mid 97.656622 -271.260209)
		(end 97.376488 -271.332452)
		(width 0.088646)
		(layer "In11.Cu")
		(net "M_D_CPU1_SA_DQ<22>")
	)
	(arc
		(start 89.851992 -271.335754)
		(mid 89.664794 -271.385897)
		(end 89.477596 -271.335754)
		(width 0.088646)
		(layer "In11.Cu")
		(net "M_D_CPU1_SA_DQ<22>")
	)
	(arc
		(start 94.551246 -271.335754)
		(mid 94.364048 -271.385897)
		(end 94.17685 -271.335754)
		(width 0.088646)
		(layer "In11.Cu")
		(net "M_D_CPU1_SA_DQ<22>")
	)
	(arc
		(start 87.032592 -271.335754)
		(mid 86.845394 -271.385897)
		(end 86.658196 -271.335754)
		(width 0.088646)
		(layer "In11.Cu")
		(net "M_D_CPU1_SA_DQ<22>")
	)
	(arc
		(start 91.731592 -271.335754)
		(mid 91.544394 -271.385897)
		(end 91.357196 -271.335754)
		(width 0.088646)
		(layer "In11.Cu")
		(net "M_D_CPU1_SA_DQ<22>")
	)
	(arc
		(start 96.041464 -271.327118)
		(mid 95.764989 -271.259798)
		(end 95.490792 -271.335754)
		(width 0.088646)
		(layer "In11.Cu")
		(net "M_D_CPU1_SA_DQ<22>")
	)
	(arc
		(start 85.718396 -271.335754)
		(mid 85.435694 -271.259978)
		(end 85.152992 -271.335754)
		(width 0.088646)
		(layer "In11.Cu")
		(net "M_D_CPU1_SA_DQ<22>")
	)
	(arc
		(start 85.152992 -271.335754)
		(mid 85.06272 -271.373353)
		(end 84.965794 -271.3863)
		(width 0.088646)
		(layer "In11.Cu")
		(net "M_D_CPU1_SA_DQ<22>")
	)
	(arc
		(start 100.472748 -271.825212)
		(mid 100.19879 -271.585013)
		(end 99.895914 -271.38249)
		(width 0.088646)
		(layer "In11.Cu")
		(net "M_D_CPU1_SA_DQ<22>")
	)
	(arc
		(start 95.490792 -271.335754)
		(mid 95.303594 -271.385897)
		(end 95.116396 -271.335754)
		(width 0.088646)
		(layer "In11.Cu")
		(net "M_D_CPU1_SA_DQ<22>")
	)
	(arc
		(start 91.357196 -271.335754)
		(mid 91.074494 -271.259978)
		(end 90.791792 -271.335754)
		(width 0.088646)
		(layer "In11.Cu")
		(net "M_D_CPU1_SA_DQ<22>")
	)
	(arc
		(start 90.417396 -271.335754)
		(mid 90.134694 -271.259978)
		(end 89.851992 -271.335754)
		(width 0.088646)
		(layer "In11.Cu")
		(net "M_D_CPU1_SA_DQ<22>")
	)
	(arc
		(start 87.972392 -271.335754)
		(mid 87.785194 -271.385897)
		(end 87.597996 -271.335754)
		(width 0.088646)
		(layer "In11.Cu")
		(net "M_D_CPU1_SA_DQ<22>")
	)
	(arc
		(start 88.537796 -271.335754)
		(mid 88.255094 -271.259978)
		(end 87.972392 -271.335754)
		(width 0.088646)
		(layer "In11.Cu")
		(net "M_D_CPU1_SA_DQ<22>")
	)
	(arc
		(start 98.875596 -271.336008)
		(mid 98.596422 -271.260209)
		(end 98.316288 -271.332452)
		(width 0.088646)
		(layer "In11.Cu")
		(net "M_D_CPU1_SA_DQ<22>")
	)
	(arc
		(start 93.222064 -271.327118)
		(mid 92.945589 -271.259798)
		(end 92.671392 -271.335754)
		(width 0.088646)
		(layer "In11.Cu")
		(net "M_D_CPU1_SA_DQ<22>")
	)
	(arc
		(start 87.597996 -271.335754)
		(mid 87.315294 -271.259978)
		(end 87.032592 -271.335754)
		(width 0.088646)
		(layer "In11.Cu")
		(net "M_D_CPU1_SA_DQ<22>")
	)
	(arc
		(start 88.912192 -271.335754)
		(mid 88.724994 -271.385897)
		(end 88.537796 -271.335754)
		(width 0.088646)
		(layer "In11.Cu")
		(net "M_D_CPU1_SA_DQ<22>")
	)
	(arc
		(start 93.611192 -271.335754)
		(mid 93.423994 -271.385897)
		(end 93.236796 -271.335754)
		(width 0.088646)
		(layer "In11.Cu")
		(net "M_D_CPU1_SA_DQ<22>")
	)
	(arc
		(start 94.166436 -271.329658)
		(mid 93.888004 -271.259812)
		(end 93.611192 -271.335754)
		(width 0.088646)
		(layer "In11.Cu")
		(net "M_D_CPU1_SA_DQ<22>")
	)
	(arc
		(start 90.791792 -271.335754)
		(mid 90.604594 -271.385897)
		(end 90.417396 -271.335754)
		(width 0.088646)
		(layer "In11.Cu")
		(net "M_D_CPU1_SA_DQ<22>")
	)
	(arc
		(start 98.304604 -271.33931)
		(mid 98.119749 -271.386228)
		(end 97.935796 -271.336008)
		(width 0.088646)
		(layer "In11.Cu")
		(net "M_D_CPU1_SA_DQ<22>")
	)
	(arc
		(start 92.282264 -271.327118)
		(mid 92.005789 -271.259798)
		(end 91.731592 -271.335754)
		(width 0.088646)
		(layer "In11.Cu")
		(net "M_D_CPU1_SA_DQ<22>")
	)
	(arc
		(start 96.995996 -271.336008)
		(mid 96.713721 -271.260325)
		(end 96.431354 -271.335754)
		(width 0.088646)
		(layer "In11.Cu")
		(net "M_D_CPU1_SA_DQ<22>")
	)
	(arc
		(start 86.658196 -271.335754)
		(mid 86.375494 -271.259978)
		(end 86.092792 -271.335754)
		(width 0.088646)
		(layer "In11.Cu")
		(net "M_D_CPU1_SA_DQ<22>")
	)
	(arc
		(start 86.092792 -271.335754)
		(mid 85.905594 -271.385897)
		(end 85.718396 -271.335754)
		(width 0.088646)
		(layer "In11.Cu")
		(net "M_D_CPU1_SA_DQ<22>")
	)
	(arc
		(start 95.105982 -271.329658)
		(mid 94.827804 -271.259935)
		(end 94.551246 -271.335754)
		(width 0.088646)
		(layer "In11.Cu")
		(net "M_D_CPU1_SA_DQ<22>")
	)
	(arc
		(start 99.244404 -271.33931)
		(mid 99.059549 -271.386228)
		(end 98.875596 -271.336008)
		(width 0.088646)
		(layer "In11.Cu")
		(net "M_D_CPU1_SA_DQ<22>")
	)
	(arc
		(start 96.430592 -271.335754)
		(mid 96.243394 -271.385897)
		(end 96.056196 -271.335754)
		(width 0.088646)
		(layer "In11.Cu")
		(net "M_D_CPU1_SA_DQ<22>")
	)
	(arc
		(start 92.671392 -271.335754)
		(mid 92.484194 -271.385897)
		(end 92.296996 -271.335754)
		(width 0.088646)
		(layer "In11.Cu")
		(net "M_D_CPU1_SA_DQ<22>")
	)
	(arc
		(start 97.349564 -271.347438)
		(mid 97.171345 -271.386059)
		(end 96.995996 -271.336008)
		(width 0.088646)
		(layer "In11.Cu")
		(net "M_D_CPU1_SA_DQ<22>")
	)
	(arc
		(start 99.815396 -271.336008)
		(mid 99.536222 -271.260209)
		(end 99.256088 -271.332452)
		(width 0.088646)
		(layer "In11.Cu")
		(net "M_D_CPU1_SA_DQ<22>")
	)
	(arc
		(start 89.462864 -271.327118)
		(mid 89.186389 -271.259798)
		(end 88.912192 -271.335754)
		(width 0.088646)
		(layer "In11.Cu")
		(net "M_D_CPU1_SA_DQ<22>")
	)
	(segment
		(start 8.140446 -289.966654)
		(end 9.474708 -289.966654)
		(width 0.20066)
		(layer "F.Cu")
		(net "M_D_CPU1_SA_DQ<21>")
	)
	(segment
		(start 10.507472 -289.532822)
		(end 11.11631 -289.532822)
		(width 0.20066)
		(layer "F.Cu")
		(net "M_D_CPU1_SA_DQ<21>")
	)
	(segment
		(start 9.686036 -290.177982)
		(end 10.19048 -290.177982)
		(width 0.20066)
		(layer "F.Cu")
		(net "M_D_CPU1_SA_DQ<21>")
	)
	(segment
		(start 15.684246 -289.966654)
		(end 16.789146 -289.966654)
		(width 0.20066)
		(layer "F.Cu")
		(net "M_D_CPU1_SA_DQ<21>")
	)
	(segment
		(start 10.344912 -290.02355)
		(end 10.344912 -289.695382)
		(width 0.20066)
		(layer "F.Cu")
		(net "M_D_CPU1_SA_DQ<21>")
	)
	(segment
		(start 10.19048 -290.177982)
		(end 10.344912 -290.02355)
		(width 0.20066)
		(layer "F.Cu")
		(net "M_D_CPU1_SA_DQ<21>")
	)
	(segment
		(start 9.474708 -289.966654)
		(end 9.686036 -290.177982)
		(width 0.20066)
		(layer "F.Cu")
		(net "M_D_CPU1_SA_DQ<21>")
	)
	(segment
		(start 14.04493 -289.966654)
		(end 15.684246 -289.966654)
		(width 0.20066)
		(layer "F.Cu")
		(net "M_D_CPU1_SA_DQ<21>")
	)
	(segment
		(start 13.441426 -289.541712)
		(end 13.619988 -289.541712)
		(width 0.20066)
		(layer "F.Cu")
		(net "M_D_CPU1_SA_DQ<21>")
	)
	(segment
		(start 13.619988 -289.541712)
		(end 14.04493 -289.966654)
		(width 0.20066)
		(layer "F.Cu")
		(net "M_D_CPU1_SA_DQ<21>")
	)
	(segment
		(start 11.1252 -289.541712)
		(end 13.110718 -289.541712)
		(width 0.1016)
		(layer "F.Cu")
		(net "M_D_CPU1_SA_DQ<21>")
	)
	(segment
		(start 13.110718 -289.541712)
		(end 13.441426 -289.541712)
		(width 0.101854)
		(layer "F.Cu")
		(net "M_D_CPU1_SA_DQ<21>")
	)
	(segment
		(start 10.344912 -289.695382)
		(end 10.507472 -289.532822)
		(width 0.20066)
		(layer "F.Cu")
		(net "M_D_CPU1_SA_DQ<21>")
	)
	(segment
		(start 11.11631 -289.532822)
		(end 11.1252 -289.541712)
		(width 0.1016)
		(layer "F.Cu")
		(net "M_D_CPU1_SA_DQ<21>")
	)
	(arc
		(start 99.063048 -270.475456)
		(mid 99.062984 -270.743426)
		(end 99.062794 -271.011396)
		(width 0.20066)
		(layer "F.Cu")
		(net "M_D_CPU1_SA_DQ<21>")
	)
	(segment
		(start 18.331434 -291.276532)
		(end 18.016474 -291.276532)
		(width 0.18288)
		(layer "In11.Cu")
		(net "M_D_CPU1_SA_DQ<21>")
	)
	(segment
		(start 42.943526 -291.749226)
		(end 42.098976 -291.749226)
		(width 0.18288)
		(layer "In11.Cu")
		(net "M_D_CPU1_SA_DQ<21>")
	)
	(segment
		(start 34.765234 -291.163756)
		(end 32.367474 -291.163756)
		(width 0.18288)
		(layer "In11.Cu")
		(net "M_D_CPU1_SA_DQ<21>")
	)
	(segment
		(start 36.750498 -290.30422)
		(end 36.66236 -290.392358)
		(width 0.18288)
		(layer "In11.Cu")
		(net "M_D_CPU1_SA_DQ<21>")
	)
	(segment
		(start 55.948326 -289.374326)
		(end 54.978046 -290.344606)
		(width 0.18288)
		(layer "In11.Cu")
		(net "M_D_CPU1_SA_DQ<21>")
	)
	(segment
		(start 56.761126 -289.374326)
		(end 55.948326 -289.374326)
		(width 0.18288)
		(layer "In11.Cu")
		(net "M_D_CPU1_SA_DQ<21>")
	)
	(segment
		(start 51.922172 -290.344606)
		(end 51.87442 -290.392358)
		(width 0.18288)
		(layer "In11.Cu")
		(net "M_D_CPU1_SA_DQ<21>")
	)
	(segment
		(start 98.316288 -270.69034)
		(end 98.304604 -270.683736)
		(width 0.088646)
		(layer "In11.Cu")
		(net "M_D_CPU1_SA_DQ<21>")
	)
	(segment
		(start 36.66236 -290.392358)
		(end 35.536632 -290.392358)
		(width 0.18288)
		(layer "In11.Cu")
		(net "M_D_CPU1_SA_DQ<21>")
	)
	(segment
		(start 58.399426 -287.736026)
		(end 56.761126 -289.374326)
		(width 0.18288)
		(layer "In11.Cu")
		(net "M_D_CPU1_SA_DQ<21>")
	)
	(segment
		(start 42.098976 -291.749226)
		(end 41.514776 -291.165026)
		(width 0.18288)
		(layer "In11.Cu")
		(net "M_D_CPU1_SA_DQ<21>")
	)
	(segment
		(start 19.032474 -290.392358)
		(end 18.717514 -290.392358)
		(width 0.18288)
		(layer "In11.Cu")
		(net "M_D_CPU1_SA_DQ<21>")
	)
	(segment
		(start 28.54452 -291.139626)
		(end 25.899364 -291.139626)
		(width 0.18288)
		(layer "In11.Cu")
		(net "M_D_CPU1_SA_DQ<21>")
	)
	(segment
		(start 48.34636 -291.242496)
		(end 46.013878 -291.242496)
		(width 0.18288)
		(layer "In11.Cu")
		(net "M_D_CPU1_SA_DQ<21>")
	)
	(segment
		(start 19.225514 -291.083492)
		(end 19.225514 -290.585398)
		(width 0.18288)
		(layer "In11.Cu")
		(net "M_D_CPU1_SA_DQ<21>")
	)
	(segment
		(start 91.357196 -270.687038)
		(end 91.342464 -270.695674)
		(width 0.088646)
		(layer "In11.Cu")
		(net "M_D_CPU1_SA_DQ<21>")
	)
	(segment
		(start 18.016474 -291.276532)
		(end 17.823434 -291.083492)
		(width 0.18288)
		(layer "In11.Cu")
		(net "M_D_CPU1_SA_DQ<21>")
	)
	(segment
		(start 83.064604 -273.255994)
		(end 79.616046 -273.255994)
		(width 0.18288)
		(layer "In11.Cu")
		(net "M_D_CPU1_SA_DQ<21>")
	)
	(segment
		(start 21.638514 -290.285932)
		(end 21.532088 -290.392358)
		(width 0.18288)
		(layer "In11.Cu")
		(net "M_D_CPU1_SA_DQ<21>")
	)
	(segment
		(start 19.418554 -291.276532)
		(end 19.225514 -291.083492)
		(width 0.18288)
		(layer "In11.Cu")
		(net "M_D_CPU1_SA_DQ<21>")
	)
	(segment
		(start 35.536632 -290.392358)
		(end 34.765234 -291.163756)
		(width 0.18288)
		(layer "In11.Cu")
		(net "M_D_CPU1_SA_DQ<21>")
	)
	(segment
		(start 46.013878 -291.242496)
		(end 45.230288 -292.026086)
		(width 0.18288)
		(layer "In11.Cu")
		(net "M_D_CPU1_SA_DQ<21>")
	)
	(segment
		(start 25.04567 -290.285932)
		(end 21.638514 -290.285932)
		(width 0.18288)
		(layer "In11.Cu")
		(net "M_D_CPU1_SA_DQ<21>")
	)
	(segment
		(start 99.062794 -271.011396)
		(end 99.375722 -271.011396)
		(width 0.088646)
		(layer "In11.Cu")
		(net "M_D_CPU1_SA_DQ<21>")
	)
	(segment
		(start 17.630394 -290.392358)
		(end 17.21485 -290.392358)
		(width 0.18288)
		(layer "In11.Cu")
		(net "M_D_CPU1_SA_DQ<21>")
	)
	(segment
		(start 93.236796 -270.687038)
		(end 93.222064 -270.695674)
		(width 0.088646)
		(layer "In11.Cu")
		(net "M_D_CPU1_SA_DQ<21>")
	)
	(segment
		(start 17.21485 -290.392358)
		(end 16.789146 -289.966654)
		(width 0.18288)
		(layer "In11.Cu")
		(net "M_D_CPU1_SA_DQ<21>")
	)
	(segment
		(start 32.288734 -291.242496)
		(end 31.402528 -291.242496)
		(width 0.18288)
		(layer "In11.Cu")
		(net "M_D_CPU1_SA_DQ<21>")
	)
	(segment
		(start 19.733514 -291.276532)
		(end 19.418554 -291.276532)
		(width 0.18288)
		(layer "In11.Cu")
		(net "M_D_CPU1_SA_DQ<21>")
	)
	(segment
		(start 97.376488 -270.69034)
		(end 97.364804 -270.683736)
		(width 0.088646)
		(layer "In11.Cu")
		(net "M_D_CPU1_SA_DQ<21>")
	)
	(segment
		(start 85.435948 -270.76273)
		(end 84.7598 -270.76273)
		(width 0.088646)
		(layer "In11.Cu")
		(net "M_D_CPU1_SA_DQ<21>")
	)
	(segment
		(start 83.68157 -273.04111)
		(end 83.466686 -273.255994)
		(width 0.088646)
		(layer "In11.Cu")
		(net "M_D_CPU1_SA_DQ<21>")
	)
	(segment
		(start 48.481488 -291.107368)
		(end 48.34636 -291.242496)
		(width 0.18288)
		(layer "In11.Cu")
		(net "M_D_CPU1_SA_DQ<21>")
	)
	(segment
		(start 94.17685 -270.687038)
		(end 94.166436 -270.693134)
		(width 0.088646)
		(layer "In11.Cu")
		(net "M_D_CPU1_SA_DQ<21>")
	)
	(segment
		(start 49.746916 -291.107368)
		(end 48.481488 -291.107368)
		(width 0.18288)
		(layer "In11.Cu")
		(net "M_D_CPU1_SA_DQ<21>")
	)
	(segment
		(start 40.568626 -291.165026)
		(end 39.70782 -290.30422)
		(width 0.18288)
		(layer "In11.Cu")
		(net "M_D_CPU1_SA_DQ<21>")
	)
	(segment
		(start 96.436688 -270.69034)
		(end 96.425004 -270.683736)
		(width 0.088646)
		(layer "In11.Cu")
		(net "M_D_CPU1_SA_DQ<21>")
	)
	(segment
		(start 60.962032 -286.984186)
		(end 60.005468 -287.94075)
		(width 0.18288)
		(layer "In11.Cu")
		(net "M_D_CPU1_SA_DQ<21>")
	)
	(segment
		(start 79.616046 -273.255994)
		(end 66.918078 -285.953962)
		(width 0.18288)
		(layer "In11.Cu")
		(net "M_D_CPU1_SA_DQ<21>")
	)
	(segment
		(start 19.225514 -290.585398)
		(end 19.032474 -290.392358)
		(width 0.18288)
		(layer "In11.Cu")
		(net "M_D_CPU1_SA_DQ<21>")
	)
	(segment
		(start 83.466686 -273.255994)
		(end 83.064604 -273.255994)
		(width 0.088646)
		(layer "In11.Cu")
		(net "M_D_CPU1_SA_DQ<21>")
	)
	(segment
		(start 17.823434 -290.585398)
		(end 17.630394 -290.392358)
		(width 0.18288)
		(layer "In11.Cu")
		(net "M_D_CPU1_SA_DQ<21>")
	)
	(segment
		(start 59.139328 -287.736026)
		(end 58.399426 -287.736026)
		(width 0.18288)
		(layer "In11.Cu")
		(net "M_D_CPU1_SA_DQ<21>")
	)
	(segment
		(start 18.524474 -291.083492)
		(end 18.331434 -291.276532)
		(width 0.18288)
		(layer "In11.Cu")
		(net "M_D_CPU1_SA_DQ<21>")
	)
	(segment
		(start 25.899364 -291.139626)
		(end 25.04567 -290.285932)
		(width 0.18288)
		(layer "In11.Cu")
		(net "M_D_CPU1_SA_DQ<21>")
	)
	(segment
		(start 45.230288 -292.026086)
		(end 44.355766 -292.026086)
		(width 0.18288)
		(layer "In11.Cu")
		(net "M_D_CPU1_SA_DQ<21>")
	)
	(segment
		(start 18.524474 -290.585398)
		(end 18.524474 -291.083492)
		(width 0.18288)
		(layer "In11.Cu")
		(net "M_D_CPU1_SA_DQ<21>")
	)
	(segment
		(start 83.894676 -271.627854)
		(end 83.894676 -272.07845)
		(width 0.088646)
		(layer "In11.Cu")
		(net "M_D_CPU1_SA_DQ<21>")
	)
	(segment
		(start 39.70782 -290.30422)
		(end 36.750498 -290.30422)
		(width 0.18288)
		(layer "In11.Cu")
		(net "M_D_CPU1_SA_DQ<21>")
	)
	(segment
		(start 41.514776 -291.165026)
		(end 40.568626 -291.165026)
		(width 0.18288)
		(layer "In11.Cu")
		(net "M_D_CPU1_SA_DQ<21>")
	)
	(segment
		(start 99.250246 -270.687038)
		(end 99.244404 -270.683736)
		(width 0.088646)
		(layer "In11.Cu")
		(net "M_D_CPU1_SA_DQ<21>")
	)
	(segment
		(start 66.918078 -285.953962)
		(end 64.216788 -285.953962)
		(width 0.18288)
		(layer "In11.Cu")
		(net "M_D_CPU1_SA_DQ<21>")
	)
	(segment
		(start 30.645608 -291.999416)
		(end 29.40431 -291.999416)
		(width 0.18288)
		(layer "In11.Cu")
		(net "M_D_CPU1_SA_DQ<21>")
	)
	(segment
		(start 43.344338 -292.150038)
		(end 42.943526 -291.749226)
		(width 0.18288)
		(layer "In11.Cu")
		(net "M_D_CPU1_SA_DQ<21>")
	)
	(segment
		(start 95.116396 -270.687038)
		(end 95.105982 -270.693134)
		(width 0.088646)
		(layer "In11.Cu")
		(net "M_D_CPU1_SA_DQ<21>")
	)
	(segment
		(start 51.87442 -290.392358)
		(end 50.461926 -290.392358)
		(width 0.18288)
		(layer "In11.Cu")
		(net "M_D_CPU1_SA_DQ<21>")
	)
	(segment
		(start 54.978046 -290.344606)
		(end 51.922172 -290.344606)
		(width 0.18288)
		(layer "In11.Cu")
		(net "M_D_CPU1_SA_DQ<21>")
	)
	(segment
		(start 59.344052 -287.94075)
		(end 59.139328 -287.736026)
		(width 0.18288)
		(layer "In11.Cu")
		(net "M_D_CPU1_SA_DQ<21>")
	)
	(segment
		(start 19.926554 -290.585398)
		(end 19.926554 -291.083492)
		(width 0.18288)
		(layer "In11.Cu")
		(net "M_D_CPU1_SA_DQ<21>")
	)
	(segment
		(start 21.532088 -290.392358)
		(end 20.119594 -290.392358)
		(width 0.18288)
		(layer "In11.Cu")
		(net "M_D_CPU1_SA_DQ<21>")
	)
	(segment
		(start 32.367474 -291.163756)
		(end 32.288734 -291.242496)
		(width 0.18288)
		(layer "In11.Cu")
		(net "M_D_CPU1_SA_DQ<21>")
	)
	(segment
		(start 29.40431 -291.999416)
		(end 28.54452 -291.139626)
		(width 0.18288)
		(layer "In11.Cu")
		(net "M_D_CPU1_SA_DQ<21>")
	)
	(segment
		(start 84.7598 -270.76273)
		(end 83.894676 -271.627854)
		(width 0.088646)
		(layer "In11.Cu")
		(net "M_D_CPU1_SA_DQ<21>")
	)
	(segment
		(start 20.119594 -290.392358)
		(end 19.926554 -290.585398)
		(width 0.18288)
		(layer "In11.Cu")
		(net "M_D_CPU1_SA_DQ<21>")
	)
	(segment
		(start 31.402528 -291.242496)
		(end 30.645608 -291.999416)
		(width 0.18288)
		(layer "In11.Cu")
		(net "M_D_CPU1_SA_DQ<21>")
	)
	(segment
		(start 50.461926 -290.392358)
		(end 49.746916 -291.107368)
		(width 0.18288)
		(layer "In11.Cu")
		(net "M_D_CPU1_SA_DQ<21>")
	)
	(segment
		(start 44.355766 -292.026086)
		(end 44.231814 -292.150038)
		(width 0.18288)
		(layer "In11.Cu")
		(net "M_D_CPU1_SA_DQ<21>")
	)
	(segment
		(start 99.255326 -270.689832)
		(end 99.250246 -270.687038)
		(width 0.088646)
		(layer "In11.Cu")
		(net "M_D_CPU1_SA_DQ<21>")
	)
	(segment
		(start 18.717514 -290.392358)
		(end 18.524474 -290.585398)
		(width 0.18288)
		(layer "In11.Cu")
		(net "M_D_CPU1_SA_DQ<21>")
	)
	(segment
		(start 83.68157 -272.291556)
		(end 83.68157 -273.04111)
		(width 0.088646)
		(layer "In11.Cu")
		(net "M_D_CPU1_SA_DQ<21>")
	)
	(segment
		(start 64.216788 -285.953962)
		(end 61.728604 -286.984186)
		(width 0.18288)
		(layer "In11.Cu")
		(net "M_D_CPU1_SA_DQ<21>")
	)
	(segment
		(start 60.005468 -287.94075)
		(end 59.344052 -287.94075)
		(width 0.18288)
		(layer "In11.Cu")
		(net "M_D_CPU1_SA_DQ<21>")
	)
	(segment
		(start 44.231814 -292.150038)
		(end 43.344338 -292.150038)
		(width 0.18288)
		(layer "In11.Cu")
		(net "M_D_CPU1_SA_DQ<21>")
	)
	(segment
		(start 99.375722 -271.011396)
		(end 99.433126 -270.953992)
		(width 0.088646)
		(layer "In11.Cu")
		(net "M_D_CPU1_SA_DQ<21>")
	)
	(segment
		(start 61.728604 -286.984186)
		(end 60.962032 -286.984186)
		(width 0.18288)
		(layer "In11.Cu")
		(net "M_D_CPU1_SA_DQ<21>")
	)
	(segment
		(start 17.823434 -291.083492)
		(end 17.823434 -290.585398)
		(width 0.18288)
		(layer "In11.Cu")
		(net "M_D_CPU1_SA_DQ<21>")
	)
	(segment
		(start 83.894676 -272.07845)
		(end 83.68157 -272.291556)
		(width 0.088646)
		(layer "In11.Cu")
		(net "M_D_CPU1_SA_DQ<21>")
	)
	(segment
		(start 19.926554 -291.083492)
		(end 19.733514 -291.276532)
		(width 0.18288)
		(layer "In11.Cu")
		(net "M_D_CPU1_SA_DQ<21>")
	)
	(segment
		(start 96.056196 -270.687038)
		(end 96.041464 -270.695674)
		(width 0.088646)
		(layer "In11.Cu")
		(net "M_D_CPU1_SA_DQ<21>")
	)
	(arc
		(start 98.875596 -270.687038)
		(mid 98.596393 -270.762678)
		(end 98.316288 -270.69034)
		(width 0.088646)
		(layer "In11.Cu")
		(net "M_D_CPU1_SA_DQ<21>")
	)
	(arc
		(start 87.972392 -270.687038)
		(mid 87.785194 -270.636895)
		(end 87.597996 -270.687038)
		(width 0.088646)
		(layer "In11.Cu")
		(net "M_D_CPU1_SA_DQ<21>")
	)
	(arc
		(start 95.490792 -270.687038)
		(mid 95.303594 -270.636895)
		(end 95.116396 -270.687038)
		(width 0.088646)
		(layer "In11.Cu")
		(net "M_D_CPU1_SA_DQ<21>")
	)
	(arc
		(start 96.425004 -270.683736)
		(mid 96.240149 -270.636786)
		(end 96.056196 -270.687038)
		(width 0.088646)
		(layer "In11.Cu")
		(net "M_D_CPU1_SA_DQ<21>")
	)
	(arc
		(start 99.433126 -270.953992)
		(mid 99.373661 -270.802105)
		(end 99.255326 -270.689832)
		(width 0.088646)
		(layer "In11.Cu")
		(net "M_D_CPU1_SA_DQ<21>")
	)
	(arc
		(start 86.092792 -270.687038)
		(mid 85.905594 -270.636895)
		(end 85.718396 -270.687038)
		(width 0.088646)
		(layer "In11.Cu")
		(net "M_D_CPU1_SA_DQ<21>")
	)
	(arc
		(start 92.296996 -270.687038)
		(mid 92.014294 -270.762814)
		(end 91.731592 -270.687038)
		(width 0.088646)
		(layer "In11.Cu")
		(net "M_D_CPU1_SA_DQ<21>")
	)
	(arc
		(start 98.304604 -270.683736)
		(mid 98.119749 -270.636786)
		(end 97.935796 -270.687038)
		(width 0.088646)
		(layer "In11.Cu")
		(net "M_D_CPU1_SA_DQ<21>")
	)
	(arc
		(start 87.032592 -270.687038)
		(mid 86.845394 -270.636895)
		(end 86.658196 -270.687038)
		(width 0.088646)
		(layer "In11.Cu")
		(net "M_D_CPU1_SA_DQ<21>")
	)
	(arc
		(start 89.477596 -270.687038)
		(mid 89.194894 -270.762814)
		(end 88.912192 -270.687038)
		(width 0.088646)
		(layer "In11.Cu")
		(net "M_D_CPU1_SA_DQ<21>")
	)
	(arc
		(start 97.364804 -270.683736)
		(mid 97.179949 -270.636786)
		(end 96.995996 -270.687038)
		(width 0.088646)
		(layer "In11.Cu")
		(net "M_D_CPU1_SA_DQ<21>")
	)
	(arc
		(start 94.551246 -270.687038)
		(mid 94.364048 -270.636895)
		(end 94.17685 -270.687038)
		(width 0.088646)
		(layer "In11.Cu")
		(net "M_D_CPU1_SA_DQ<21>")
	)
	(arc
		(start 93.222064 -270.695674)
		(mid 92.945589 -270.762994)
		(end 92.671392 -270.687038)
		(width 0.088646)
		(layer "In11.Cu")
		(net "M_D_CPU1_SA_DQ<21>")
	)
	(arc
		(start 92.671392 -270.687038)
		(mid 92.484194 -270.636895)
		(end 92.296996 -270.687038)
		(width 0.088646)
		(layer "In11.Cu")
		(net "M_D_CPU1_SA_DQ<21>")
	)
	(arc
		(start 88.537796 -270.687038)
		(mid 88.255094 -270.762814)
		(end 87.972392 -270.687038)
		(width 0.088646)
		(layer "In11.Cu")
		(net "M_D_CPU1_SA_DQ<21>")
	)
	(arc
		(start 99.244404 -270.683736)
		(mid 99.059549 -270.636786)
		(end 98.875596 -270.687038)
		(width 0.088646)
		(layer "In11.Cu")
		(net "M_D_CPU1_SA_DQ<21>")
	)
	(arc
		(start 97.935796 -270.687038)
		(mid 97.656593 -270.762678)
		(end 97.376488 -270.69034)
		(width 0.088646)
		(layer "In11.Cu")
		(net "M_D_CPU1_SA_DQ<21>")
	)
	(arc
		(start 90.417396 -270.687038)
		(mid 90.134694 -270.762814)
		(end 89.851992 -270.687038)
		(width 0.088646)
		(layer "In11.Cu")
		(net "M_D_CPU1_SA_DQ<21>")
	)
	(arc
		(start 96.041464 -270.695674)
		(mid 95.764989 -270.762994)
		(end 95.490792 -270.687038)
		(width 0.088646)
		(layer "In11.Cu")
		(net "M_D_CPU1_SA_DQ<21>")
	)
	(arc
		(start 86.658196 -270.687038)
		(mid 86.375494 -270.762814)
		(end 86.092792 -270.687038)
		(width 0.088646)
		(layer "In11.Cu")
		(net "M_D_CPU1_SA_DQ<21>")
	)
	(arc
		(start 87.597996 -270.687038)
		(mid 87.315294 -270.762814)
		(end 87.032592 -270.687038)
		(width 0.088646)
		(layer "In11.Cu")
		(net "M_D_CPU1_SA_DQ<21>")
	)
	(arc
		(start 93.611192 -270.687038)
		(mid 93.423994 -270.636895)
		(end 93.236796 -270.687038)
		(width 0.088646)
		(layer "In11.Cu")
		(net "M_D_CPU1_SA_DQ<21>")
	)
	(arc
		(start 88.912192 -270.687038)
		(mid 88.724994 -270.636895)
		(end 88.537796 -270.687038)
		(width 0.088646)
		(layer "In11.Cu")
		(net "M_D_CPU1_SA_DQ<21>")
	)
	(arc
		(start 95.105982 -270.693134)
		(mid 94.827804 -270.762857)
		(end 94.551246 -270.687038)
		(width 0.088646)
		(layer "In11.Cu")
		(net "M_D_CPU1_SA_DQ<21>")
	)
	(arc
		(start 85.718396 -270.687038)
		(mid 85.582153 -270.743484)
		(end 85.435948 -270.76273)
		(width 0.088646)
		(layer "In11.Cu")
		(net "M_D_CPU1_SA_DQ<21>")
	)
	(arc
		(start 94.166436 -270.693134)
		(mid 93.888004 -270.76298)
		(end 93.611192 -270.687038)
		(width 0.088646)
		(layer "In11.Cu")
		(net "M_D_CPU1_SA_DQ<21>")
	)
	(arc
		(start 91.342464 -270.695674)
		(mid 91.065989 -270.762994)
		(end 90.791792 -270.687038)
		(width 0.088646)
		(layer "In11.Cu")
		(net "M_D_CPU1_SA_DQ<21>")
	)
	(arc
		(start 96.995996 -270.687038)
		(mid 96.716793 -270.762678)
		(end 96.436688 -270.69034)
		(width 0.088646)
		(layer "In11.Cu")
		(net "M_D_CPU1_SA_DQ<21>")
	)
	(arc
		(start 91.731592 -270.687038)
		(mid 91.544394 -270.636895)
		(end 91.357196 -270.687038)
		(width 0.088646)
		(layer "In11.Cu")
		(net "M_D_CPU1_SA_DQ<21>")
	)
	(arc
		(start 90.791792 -270.687038)
		(mid 90.604594 -270.636895)
		(end 90.417396 -270.687038)
		(width 0.088646)
		(layer "In11.Cu")
		(net "M_D_CPU1_SA_DQ<21>")
	)
	(arc
		(start 89.851992 -270.687038)
		(mid 89.664794 -270.636895)
		(end 89.477596 -270.687038)
		(width 0.088646)
		(layer "In11.Cu")
		(net "M_D_CPU1_SA_DQ<21>")
	)
	(segment
		(start 10.344912 -291.443156)
		(end 10.554462 -291.233606)
		(width 0.20066)
		(layer "F.Cu")
		(net "M_D_CPU1_SA_DQ<20>")
	)
	(segment
		(start 9.474708 -291.666676)
		(end 9.713468 -291.905436)
		(width 0.20066)
		(layer "F.Cu")
		(net "M_D_CPU1_SA_DQ<20>")
	)
	(segment
		(start 13.441426 -291.241734)
		(end 13.890244 -291.241734)
		(width 0.20066)
		(layer "F.Cu")
		(net "M_D_CPU1_SA_DQ<20>")
	)
	(segment
		(start 98.592894 -271.289272)
		(end 98.593148 -271.289526)
		(width 0.20066)
		(layer "F.Cu")
		(net "M_D_CPU1_SA_DQ<20>")
	)
	(segment
		(start 98.593148 -271.289526)
		(end 98.593148 -271.825212)
		(width 0.20066)
		(layer "F.Cu")
		(net "M_D_CPU1_SA_DQ<20>")
	)
	(segment
		(start 11.11631 -291.233606)
		(end 11.124438 -291.241734)
		(width 0.101854)
		(layer "F.Cu")
		(net "M_D_CPU1_SA_DQ<20>")
	)
	(segment
		(start 15.684246 -291.666676)
		(end 16.789146 -291.666676)
		(width 0.20066)
		(layer "F.Cu")
		(net "M_D_CPU1_SA_DQ<20>")
	)
	(segment
		(start 11.372342 -291.241734)
		(end 13.441426 -291.241734)
		(width 0.1016)
		(layer "F.Cu")
		(net "M_D_CPU1_SA_DQ<20>")
	)
	(segment
		(start 8.140446 -291.666676)
		(end 9.474708 -291.666676)
		(width 0.20066)
		(layer "F.Cu")
		(net "M_D_CPU1_SA_DQ<20>")
	)
	(segment
		(start 9.713468 -291.905436)
		(end 10.172192 -291.905436)
		(width 0.20066)
		(layer "F.Cu")
		(net "M_D_CPU1_SA_DQ<20>")
	)
	(segment
		(start 11.124438 -291.241734)
		(end 11.372342 -291.241734)
		(width 0.101854)
		(layer "F.Cu")
		(net "M_D_CPU1_SA_DQ<20>")
	)
	(segment
		(start 10.172192 -291.905436)
		(end 10.344912 -291.732716)
		(width 0.20066)
		(layer "F.Cu")
		(net "M_D_CPU1_SA_DQ<20>")
	)
	(segment
		(start 13.890244 -291.241734)
		(end 14.315186 -291.666676)
		(width 0.20066)
		(layer "F.Cu")
		(net "M_D_CPU1_SA_DQ<20>")
	)
	(segment
		(start 14.315186 -291.666676)
		(end 15.684246 -291.666676)
		(width 0.20066)
		(layer "F.Cu")
		(net "M_D_CPU1_SA_DQ<20>")
	)
	(segment
		(start 10.554462 -291.233606)
		(end 11.11631 -291.233606)
		(width 0.20066)
		(layer "F.Cu")
		(net "M_D_CPU1_SA_DQ<20>")
	)
	(segment
		(start 10.344912 -291.732716)
		(end 10.344912 -291.443156)
		(width 0.20066)
		(layer "F.Cu")
		(net "M_D_CPU1_SA_DQ<20>")
	)
	(segment
		(start 63.24981 -288.098484)
		(end 63.24981 -288.654998)
		(width 0.18288)
		(layer "In11.Cu")
		(net "M_D_CPU1_SA_DQ<20>")
	)
	(segment
		(start 25.575514 -292.474904)
		(end 25.00503 -291.90442)
		(width 0.18288)
		(layer "In11.Cu")
		(net "M_D_CPU1_SA_DQ<20>")
	)
	(segment
		(start 48.68545 -293.135558)
		(end 48.68545 -293.579042)
		(width 0.18288)
		(layer "In11.Cu")
		(net "M_D_CPU1_SA_DQ<20>")
	)
	(segment
		(start 95.035878 -271.50949)
		(end 95.021146 -271.500854)
		(width 0.088646)
		(layer "In11.Cu")
		(net "M_D_CPU1_SA_DQ<20>")
	)
	(segment
		(start 65.618106 -287.654492)
		(end 65.425066 -287.847532)
		(width 0.18288)
		(layer "In11.Cu")
		(net "M_D_CPU1_SA_DQ<20>")
	)
	(segment
		(start 45.776388 -293.527226)
		(end 43.076622 -293.527226)
		(width 0.18288)
		(layer "In11.Cu")
		(net "M_D_CPU1_SA_DQ<20>")
	)
	(segment
		(start 64.721486 -287.847532)
		(end 64.528446 -287.654492)
		(width 0.18288)
		(layer "In11.Cu")
		(net "M_D_CPU1_SA_DQ<20>")
	)
	(segment
		(start 83.064858 -274.271994)
		(end 80.086454 -274.271994)
		(width 0.18288)
		(layer "In11.Cu")
		(net "M_D_CPU1_SA_DQ<20>")
	)
	(segment
		(start 47.98441 -293.579042)
		(end 47.98441 -293.135558)
		(width 0.18288)
		(layer "In11.Cu")
		(net "M_D_CPU1_SA_DQ<20>")
	)
	(segment
		(start 47.79137 -292.942518)
		(end 46.361096 -292.942518)
		(width 0.18288)
		(layer "In11.Cu")
		(net "M_D_CPU1_SA_DQ<20>")
	)
	(segment
		(start 84.275168 -272.263108)
		(end 84.079842 -272.458434)
		(width 0.088646)
		(layer "In11.Cu")
		(net "M_D_CPU1_SA_DQ<20>")
	)
	(segment
		(start 55.045102 -292.001194)
		(end 51.905916 -292.001194)
		(width 0.18288)
		(layer "In11.Cu")
		(net "M_D_CPU1_SA_DQ<20>")
	)
	(segment
		(start 62.359794 -289.545014)
		(end 59.217814 -289.545014)
		(width 0.18288)
		(layer "In11.Cu")
		(net "M_D_CPU1_SA_DQ<20>")
	)
	(segment
		(start 51.905916 -292.001194)
		(end 51.81473 -292.09238)
		(width 0.18288)
		(layer "In11.Cu")
		(net "M_D_CPU1_SA_DQ<20>")
	)
	(segment
		(start 64.721486 -288.201608)
		(end 64.721486 -287.847532)
		(width 0.18288)
		(layer "In11.Cu")
		(net "M_D_CPU1_SA_DQ<20>")
	)
	(segment
		(start 84.80298 -271.576546)
		(end 84.795868 -271.583658)
		(width 0.088646)
		(layer "In11.Cu")
		(net "M_D_CPU1_SA_DQ<20>")
	)
	(segment
		(start 43.076622 -293.527226)
		(end 42.416222 -292.866826)
		(width 0.18288)
		(layer "In11.Cu")
		(net "M_D_CPU1_SA_DQ<20>")
	)
	(segment
		(start 89.39276 -271.50695)
		(end 89.382346 -271.500854)
		(width 0.088646)
		(layer "In11.Cu")
		(net "M_D_CPU1_SA_DQ<20>")
	)
	(segment
		(start 48.17745 -293.772082)
		(end 47.98441 -293.579042)
		(width 0.18288)
		(layer "In11.Cu")
		(net "M_D_CPU1_SA_DQ<20>")
	)
	(segment
		(start 64.528446 -287.654492)
		(end 63.693802 -287.654492)
		(width 0.18288)
		(layer "In11.Cu")
		(net "M_D_CPU1_SA_DQ<20>")
	)
	(segment
		(start 50.368962 -292.09238)
		(end 49.518824 -292.942518)
		(width 0.18288)
		(layer "In11.Cu")
		(net "M_D_CPU1_SA_DQ<20>")
	)
	(segment
		(start 58.299858 -289.488626)
		(end 56.674258 -291.114226)
		(width 0.18288)
		(layer "In11.Cu")
		(net "M_D_CPU1_SA_DQ<20>")
	)
	(segment
		(start 48.87849 -292.942518)
		(end 48.68545 -293.135558)
		(width 0.18288)
		(layer "In11.Cu")
		(net "M_D_CPU1_SA_DQ<20>")
	)
	(segment
		(start 35.536632 -292.09238)
		(end 34.686494 -292.942518)
		(width 0.18288)
		(layer "In11.Cu")
		(net "M_D_CPU1_SA_DQ<20>")
	)
	(segment
		(start 56.674258 -291.114226)
		(end 55.93207 -291.114226)
		(width 0.18288)
		(layer "In11.Cu")
		(net "M_D_CPU1_SA_DQ<20>")
	)
	(segment
		(start 31.351982 -292.942518)
		(end 30.502098 -293.792402)
		(width 0.18288)
		(layer "In11.Cu")
		(net "M_D_CPU1_SA_DQ<20>")
	)
	(segment
		(start 80.086454 -274.271994)
		(end 66.703956 -287.654492)
		(width 0.18288)
		(layer "In11.Cu")
		(net "M_D_CPU1_SA_DQ<20>")
	)
	(segment
		(start 59.217814 -289.545014)
		(end 59.161426 -289.488626)
		(width 0.18288)
		(layer "In11.Cu")
		(net "M_D_CPU1_SA_DQ<20>")
	)
	(segment
		(start 91.272106 -271.50695)
		(end 91.261692 -271.500854)
		(width 0.088646)
		(layer "In11.Cu")
		(net "M_D_CPU1_SA_DQ<20>")
	)
	(segment
		(start 55.93207 -291.114226)
		(end 55.045102 -292.001194)
		(width 0.18288)
		(layer "In11.Cu")
		(net "M_D_CPU1_SA_DQ<20>")
	)
	(segment
		(start 29.022802 -293.792402)
		(end 27.968194 -292.737794)
		(width 0.18288)
		(layer "In11.Cu")
		(net "M_D_CPU1_SA_DQ<20>")
	)
	(segment
		(start 59.161426 -289.488626)
		(end 58.299858 -289.488626)
		(width 0.18288)
		(layer "In11.Cu")
		(net "M_D_CPU1_SA_DQ<20>")
	)
	(segment
		(start 48.68545 -293.579042)
		(end 48.49241 -293.772082)
		(width 0.18288)
		(layer "In11.Cu")
		(net "M_D_CPU1_SA_DQ<20>")
	)
	(segment
		(start 84.795868 -271.583658)
		(end 84.609432 -271.583658)
		(width 0.088646)
		(layer "In11.Cu")
		(net "M_D_CPU1_SA_DQ<20>")
	)
	(segment
		(start 21.533866 -292.09238)
		(end 20.162266 -292.09238)
		(width 0.18288)
		(layer "In11.Cu")
		(net "M_D_CPU1_SA_DQ<20>")
	)
	(segment
		(start 25.00503 -291.90442)
		(end 21.721826 -291.90442)
		(width 0.18288)
		(layer "In11.Cu")
		(net "M_D_CPU1_SA_DQ<20>")
	)
	(segment
		(start 66.703956 -287.654492)
		(end 65.618106 -287.654492)
		(width 0.18288)
		(layer "In11.Cu")
		(net "M_D_CPU1_SA_DQ<20>")
	)
	(segment
		(start 39.652956 -291.997384)
		(end 36.84143 -291.997384)
		(width 0.18288)
		(layer "In11.Cu")
		(net "M_D_CPU1_SA_DQ<20>")
	)
	(segment
		(start 20.162266 -292.09238)
		(end 19.918426 -292.33622)
		(width 0.18288)
		(layer "In11.Cu")
		(net "M_D_CPU1_SA_DQ<20>")
	)
	(segment
		(start 17.45869 -292.33622)
		(end 16.789146 -291.666676)
		(width 0.18288)
		(layer "In11.Cu")
		(net "M_D_CPU1_SA_DQ<20>")
	)
	(segment
		(start 27.968194 -292.737794)
		(end 26.210514 -292.737794)
		(width 0.18288)
		(layer "In11.Cu")
		(net "M_D_CPU1_SA_DQ<20>")
	)
	(segment
		(start 36.84143 -291.997384)
		(end 36.746434 -292.09238)
		(width 0.18288)
		(layer "In11.Cu")
		(net "M_D_CPU1_SA_DQ<20>")
	)
	(segment
		(start 26.210514 -292.737794)
		(end 25.575514 -292.474904)
		(width 0.18288)
		(layer "In11.Cu")
		(net "M_D_CPU1_SA_DQ<20>")
	)
	(segment
		(start 65.425066 -287.847532)
		(end 65.425066 -288.201608)
		(width 0.18288)
		(layer "In11.Cu")
		(net "M_D_CPU1_SA_DQ<20>")
	)
	(segment
		(start 88.452706 -271.50695)
		(end 88.442292 -271.500854)
		(width 0.088646)
		(layer "In11.Cu")
		(net "M_D_CPU1_SA_DQ<20>")
	)
	(segment
		(start 65.232026 -288.394648)
		(end 64.914526 -288.394648)
		(width 0.18288)
		(layer "In11.Cu")
		(net "M_D_CPU1_SA_DQ<20>")
	)
	(segment
		(start 63.24981 -288.654998)
		(end 62.359794 -289.545014)
		(width 0.18288)
		(layer "In11.Cu")
		(net "M_D_CPU1_SA_DQ<20>")
	)
	(segment
		(start 40.522398 -292.866826)
		(end 39.652956 -291.997384)
		(width 0.18288)
		(layer "In11.Cu")
		(net "M_D_CPU1_SA_DQ<20>")
	)
	(segment
		(start 84.079842 -273.407378)
		(end 83.215226 -274.271994)
		(width 0.088646)
		(layer "In11.Cu")
		(net "M_D_CPU1_SA_DQ<20>")
	)
	(segment
		(start 93.156278 -271.50949)
		(end 93.141546 -271.500854)
		(width 0.088646)
		(layer "In11.Cu")
		(net "M_D_CPU1_SA_DQ<20>")
	)
	(segment
		(start 83.215226 -274.271994)
		(end 83.064858 -274.271994)
		(width 0.088646)
		(layer "In11.Cu")
		(net "M_D_CPU1_SA_DQ<20>")
	)
	(segment
		(start 98.237802 -271.729962)
		(end 97.840546 -271.500854)
		(width 0.088646)
		(layer "In11.Cu")
		(net "M_D_CPU1_SA_DQ<20>")
	)
	(segment
		(start 21.721826 -291.90442)
		(end 21.533866 -292.09238)
		(width 0.18288)
		(layer "In11.Cu")
		(net "M_D_CPU1_SA_DQ<20>")
	)
	(segment
		(start 92.216478 -271.50949)
		(end 92.201746 -271.500854)
		(width 0.088646)
		(layer "In11.Cu")
		(net "M_D_CPU1_SA_DQ<20>")
	)
	(segment
		(start 64.914526 -288.394648)
		(end 64.721486 -288.201608)
		(width 0.18288)
		(layer "In11.Cu")
		(net "M_D_CPU1_SA_DQ<20>")
	)
	(segment
		(start 97.465896 -271.500854)
		(end 97.460054 -271.50441)
		(width 0.088646)
		(layer "In11.Cu")
		(net "M_D_CPU1_SA_DQ<20>")
	)
	(segment
		(start 84.275168 -271.917922)
		(end 84.275168 -272.263108)
		(width 0.088646)
		(layer "In11.Cu")
		(net "M_D_CPU1_SA_DQ<20>")
	)
	(segment
		(start 98.593148 -271.825212)
		(end 98.592894 -271.824958)
		(width 0.088646)
		(layer "In11.Cu")
		(net "M_D_CPU1_SA_DQ<20>")
	)
	(segment
		(start 19.918426 -292.33622)
		(end 17.45869 -292.33622)
		(width 0.18288)
		(layer "In11.Cu")
		(net "M_D_CPU1_SA_DQ<20>")
	)
	(segment
		(start 97.471738 -271.497552)
		(end 97.465896 -271.500854)
		(width 0.088646)
		(layer "In11.Cu")
		(net "M_D_CPU1_SA_DQ<20>")
	)
	(segment
		(start 84.079842 -272.458434)
		(end 84.079842 -273.407378)
		(width 0.088646)
		(layer "In11.Cu")
		(net "M_D_CPU1_SA_DQ<20>")
	)
	(segment
		(start 46.361096 -292.942518)
		(end 45.776388 -293.527226)
		(width 0.18288)
		(layer "In11.Cu")
		(net "M_D_CPU1_SA_DQ<20>")
	)
	(segment
		(start 84.965794 -271.576546)
		(end 84.80298 -271.576546)
		(width 0.088646)
		(layer "In11.Cu")
		(net "M_D_CPU1_SA_DQ<20>")
	)
	(segment
		(start 49.518824 -292.942518)
		(end 48.87849 -292.942518)
		(width 0.18288)
		(layer "In11.Cu")
		(net "M_D_CPU1_SA_DQ<20>")
	)
	(segment
		(start 34.686494 -292.942518)
		(end 31.351982 -292.942518)
		(width 0.18288)
		(layer "In11.Cu")
		(net "M_D_CPU1_SA_DQ<20>")
	)
	(segment
		(start 42.416222 -292.866826)
		(end 40.522398 -292.866826)
		(width 0.18288)
		(layer "In11.Cu")
		(net "M_D_CPU1_SA_DQ<20>")
	)
	(segment
		(start 36.746434 -292.09238)
		(end 35.536632 -292.09238)
		(width 0.18288)
		(layer "In11.Cu")
		(net "M_D_CPU1_SA_DQ<20>")
	)
	(segment
		(start 65.425066 -288.201608)
		(end 65.232026 -288.394648)
		(width 0.18288)
		(layer "In11.Cu")
		(net "M_D_CPU1_SA_DQ<20>")
	)
	(segment
		(start 47.98441 -293.135558)
		(end 47.79137 -292.942518)
		(width 0.18288)
		(layer "In11.Cu")
		(net "M_D_CPU1_SA_DQ<20>")
	)
	(segment
		(start 51.81473 -292.09238)
		(end 50.368962 -292.09238)
		(width 0.18288)
		(layer "In11.Cu")
		(net "M_D_CPU1_SA_DQ<20>")
	)
	(segment
		(start 48.49241 -293.772082)
		(end 48.17745 -293.772082)
		(width 0.18288)
		(layer "In11.Cu")
		(net "M_D_CPU1_SA_DQ<20>")
	)
	(segment
		(start 84.609432 -271.583658)
		(end 84.275168 -271.917922)
		(width 0.088646)
		(layer "In11.Cu")
		(net "M_D_CPU1_SA_DQ<20>")
	)
	(segment
		(start 30.502098 -293.792402)
		(end 29.022802 -293.792402)
		(width 0.18288)
		(layer "In11.Cu")
		(net "M_D_CPU1_SA_DQ<20>")
	)
	(segment
		(start 63.693802 -287.654492)
		(end 63.24981 -288.098484)
		(width 0.18288)
		(layer "In11.Cu")
		(net "M_D_CPU1_SA_DQ<20>")
	)
	(segment
		(start 95.975678 -271.50949)
		(end 95.960946 -271.500854)
		(width 0.088646)
		(layer "In11.Cu")
		(net "M_D_CPU1_SA_DQ<20>")
	)
	(arc
		(start 96.52635 -271.500854)
		(mid 96.252151 -271.576689)
		(end 95.975678 -271.50949)
		(width 0.088646)
		(layer "In11.Cu")
		(net "M_D_CPU1_SA_DQ<20>")
	)
	(arc
		(start 87.502492 -271.500854)
		(mid 87.315294 -271.450711)
		(end 87.128096 -271.500854)
		(width 0.088646)
		(layer "In11.Cu")
		(net "M_D_CPU1_SA_DQ<20>")
	)
	(arc
		(start 85.248496 -271.500854)
		(mid 85.112127 -271.557296)
		(end 84.965794 -271.576546)
		(width 0.088646)
		(layer "In11.Cu")
		(net "M_D_CPU1_SA_DQ<20>")
	)
	(arc
		(start 94.64675 -271.500854)
		(mid 94.364048 -271.57663)
		(end 94.081346 -271.500854)
		(width 0.088646)
		(layer "In11.Cu")
		(net "M_D_CPU1_SA_DQ<20>")
	)
	(arc
		(start 90.321892 -271.500854)
		(mid 90.134694 -271.450711)
		(end 89.947496 -271.500854)
		(width 0.088646)
		(layer "In11.Cu")
		(net "M_D_CPU1_SA_DQ<20>")
	)
	(arc
		(start 88.067896 -271.500854)
		(mid 87.785194 -271.57663)
		(end 87.502492 -271.500854)
		(width 0.088646)
		(layer "In11.Cu")
		(net "M_D_CPU1_SA_DQ<20>")
	)
	(arc
		(start 91.261692 -271.500854)
		(mid 91.074494 -271.450711)
		(end 90.887296 -271.500854)
		(width 0.088646)
		(layer "In11.Cu")
		(net "M_D_CPU1_SA_DQ<20>")
	)
	(arc
		(start 95.58655 -271.500854)
		(mid 95.312351 -271.576689)
		(end 95.035878 -271.50949)
		(width 0.088646)
		(layer "In11.Cu")
		(net "M_D_CPU1_SA_DQ<20>")
	)
	(arc
		(start 89.947496 -271.500854)
		(mid 89.670937 -271.576597)
		(end 89.39276 -271.50695)
		(width 0.088646)
		(layer "In11.Cu")
		(net "M_D_CPU1_SA_DQ<20>")
	)
	(arc
		(start 93.141546 -271.500854)
		(mid 92.954348 -271.450711)
		(end 92.76715 -271.500854)
		(width 0.088646)
		(layer "In11.Cu")
		(net "M_D_CPU1_SA_DQ<20>")
	)
	(arc
		(start 95.960946 -271.500854)
		(mid 95.773748 -271.450711)
		(end 95.58655 -271.500854)
		(width 0.088646)
		(layer "In11.Cu")
		(net "M_D_CPU1_SA_DQ<20>")
	)
	(arc
		(start 92.201746 -271.500854)
		(mid 92.014548 -271.450711)
		(end 91.82735 -271.500854)
		(width 0.088646)
		(layer "In11.Cu")
		(net "M_D_CPU1_SA_DQ<20>")
	)
	(arc
		(start 91.82735 -271.500854)
		(mid 91.550537 -271.576724)
		(end 91.272106 -271.50695)
		(width 0.088646)
		(layer "In11.Cu")
		(net "M_D_CPU1_SA_DQ<20>")
	)
	(arc
		(start 94.081346 -271.500854)
		(mid 93.894148 -271.450711)
		(end 93.70695 -271.500854)
		(width 0.088646)
		(layer "In11.Cu")
		(net "M_D_CPU1_SA_DQ<20>")
	)
	(arc
		(start 88.442292 -271.500854)
		(mid 88.255094 -271.450711)
		(end 88.067896 -271.500854)
		(width 0.088646)
		(layer "In11.Cu")
		(net "M_D_CPU1_SA_DQ<20>")
	)
	(arc
		(start 97.460054 -271.50441)
		(mid 97.179919 -271.576693)
		(end 96.900746 -271.500854)
		(width 0.088646)
		(layer "In11.Cu")
		(net "M_D_CPU1_SA_DQ<20>")
	)
	(arc
		(start 98.592894 -271.824958)
		(mid 98.409087 -271.800846)
		(end 98.237802 -271.729962)
		(width 0.088646)
		(layer "In11.Cu")
		(net "M_D_CPU1_SA_DQ<20>")
	)
	(arc
		(start 95.021146 -271.500854)
		(mid 94.833948 -271.450711)
		(end 94.64675 -271.500854)
		(width 0.088646)
		(layer "In11.Cu")
		(net "M_D_CPU1_SA_DQ<20>")
	)
	(arc
		(start 86.562692 -271.500854)
		(mid 86.375494 -271.450711)
		(end 86.188296 -271.500854)
		(width 0.088646)
		(layer "In11.Cu")
		(net "M_D_CPU1_SA_DQ<20>")
	)
	(arc
		(start 93.70695 -271.500854)
		(mid 93.432751 -271.576689)
		(end 93.156278 -271.50949)
		(width 0.088646)
		(layer "In11.Cu")
		(net "M_D_CPU1_SA_DQ<20>")
	)
	(arc
		(start 86.188296 -271.500854)
		(mid 85.905594 -271.57663)
		(end 85.622892 -271.500854)
		(width 0.088646)
		(layer "In11.Cu")
		(net "M_D_CPU1_SA_DQ<20>")
	)
	(arc
		(start 96.900746 -271.500854)
		(mid 96.713548 -271.450711)
		(end 96.52635 -271.500854)
		(width 0.088646)
		(layer "In11.Cu")
		(net "M_D_CPU1_SA_DQ<20>")
	)
	(arc
		(start 92.76715 -271.500854)
		(mid 92.492951 -271.576689)
		(end 92.216478 -271.50949)
		(width 0.088646)
		(layer "In11.Cu")
		(net "M_D_CPU1_SA_DQ<20>")
	)
	(arc
		(start 90.887296 -271.500854)
		(mid 90.604594 -271.57663)
		(end 90.321892 -271.500854)
		(width 0.088646)
		(layer "In11.Cu")
		(net "M_D_CPU1_SA_DQ<20>")
	)
	(arc
		(start 97.840546 -271.500854)
		(mid 97.656592 -271.450725)
		(end 97.471738 -271.497552)
		(width 0.088646)
		(layer "In11.Cu")
		(net "M_D_CPU1_SA_DQ<20>")
	)
	(arc
		(start 85.622892 -271.500854)
		(mid 85.435694 -271.450711)
		(end 85.248496 -271.500854)
		(width 0.088646)
		(layer "In11.Cu")
		(net "M_D_CPU1_SA_DQ<20>")
	)
	(arc
		(start 87.128096 -271.500854)
		(mid 86.845394 -271.57663)
		(end 86.562692 -271.500854)
		(width 0.088646)
		(layer "In11.Cu")
		(net "M_D_CPU1_SA_DQ<20>")
	)
	(arc
		(start 89.382346 -271.500854)
		(mid 89.195148 -271.450711)
		(end 89.00795 -271.500854)
		(width 0.088646)
		(layer "In11.Cu")
		(net "M_D_CPU1_SA_DQ<20>")
	)
	(arc
		(start 89.00795 -271.500854)
		(mid 88.731137 -271.576724)
		(end 88.452706 -271.50695)
		(width 0.088646)
		(layer "In11.Cu")
		(net "M_D_CPU1_SA_DQ<20>")
	)
	(segment
		(start 11.11631 -314.18276)
		(end 11.1252 -314.19165)
		(width 0.1016)
		(layer "F.Cu")
		(net "M_D_CPU1_SA_DQ<1>")
	)
	(segment
		(start 9.686036 -314.82792)
		(end 10.19048 -314.82792)
		(width 0.20066)
		(layer "F.Cu")
		(net "M_D_CPU1_SA_DQ<1>")
	)
	(segment
		(start 13.110718 -314.19165)
		(end 13.441426 -314.19165)
		(width 0.101854)
		(layer "F.Cu")
		(net "M_D_CPU1_SA_DQ<1>")
	)
	(segment
		(start 8.140446 -314.616592)
		(end 9.474708 -314.616592)
		(width 0.20066)
		(layer "F.Cu")
		(net "M_D_CPU1_SA_DQ<1>")
	)
	(segment
		(start 10.344912 -314.673488)
		(end 10.344912 -314.34532)
		(width 0.20066)
		(layer "F.Cu")
		(net "M_D_CPU1_SA_DQ<1>")
	)
	(segment
		(start 15.684246 -314.616592)
		(end 16.789146 -314.616592)
		(width 0.20066)
		(layer "F.Cu")
		(net "M_D_CPU1_SA_DQ<1>")
	)
	(segment
		(start 10.19048 -314.82792)
		(end 10.344912 -314.673488)
		(width 0.20066)
		(layer "F.Cu")
		(net "M_D_CPU1_SA_DQ<1>")
	)
	(segment
		(start 13.619988 -314.19165)
		(end 14.04493 -314.616592)
		(width 0.20066)
		(layer "F.Cu")
		(net "M_D_CPU1_SA_DQ<1>")
	)
	(segment
		(start 11.1252 -314.19165)
		(end 13.110718 -314.19165)
		(width 0.1016)
		(layer "F.Cu")
		(net "M_D_CPU1_SA_DQ<1>")
	)
	(segment
		(start 13.441426 -314.19165)
		(end 13.619988 -314.19165)
		(width 0.20066)
		(layer "F.Cu")
		(net "M_D_CPU1_SA_DQ<1>")
	)
	(segment
		(start 10.507472 -314.18276)
		(end 11.11631 -314.18276)
		(width 0.20066)
		(layer "F.Cu")
		(net "M_D_CPU1_SA_DQ<1>")
	)
	(segment
		(start 14.04493 -314.616592)
		(end 15.684246 -314.616592)
		(width 0.20066)
		(layer "F.Cu")
		(net "M_D_CPU1_SA_DQ<1>")
	)
	(segment
		(start 9.474708 -314.616592)
		(end 9.686036 -314.82792)
		(width 0.20066)
		(layer "F.Cu")
		(net "M_D_CPU1_SA_DQ<1>")
	)
	(segment
		(start 10.344912 -314.34532)
		(end 10.507472 -314.18276)
		(width 0.20066)
		(layer "F.Cu")
		(net "M_D_CPU1_SA_DQ<1>")
	)
	(arc
		(start 95.303848 -275.35886)
		(mid 95.303784 -275.62683)
		(end 95.303594 -275.8948)
		(width 0.20066)
		(layer "F.Cu")
		(net "M_D_CPU1_SA_DQ<1>")
	)
	(segment
		(start 91.272106 -276.390354)
		(end 91.261692 -276.384258)
		(width 0.088646)
		(layer "In6.Cu")
		(net "M_D_CPU1_SA_DQ<1>")
	)
	(segment
		(start 44.713144 -312.443876)
		(end 43.707304 -313.449716)
		(width 0.18288)
		(layer "In6.Cu")
		(net "M_D_CPU1_SA_DQ<1>")
	)
	(segment
		(start 69.195696 -296.89552)
		(end 69.195696 -298.922186)
		(width 0.18288)
		(layer "In6.Cu")
		(net "M_D_CPU1_SA_DQ<1>")
	)
	(segment
		(start 58.872374 -304.703226)
		(end 58.425588 -304.703226)
		(width 0.18288)
		(layer "In6.Cu")
		(net "M_D_CPU1_SA_DQ<1>")
	)
	(segment
		(start 50.8254 -309.091838)
		(end 48.275494 -311.641744)
		(width 0.18288)
		(layer "In6.Cu")
		(net "M_D_CPU1_SA_DQ<1>")
	)
	(segment
		(start 90.230198 -277.522432)
		(end 90.230198 -277.530052)
		(width 0.088646)
		(layer "In6.Cu")
		(net "M_D_CPU1_SA_DQ<1>")
	)
	(segment
		(start 89.760044 -278.336502)
		(end 89.760044 -278.346408)
		(width 0.088646)
		(layer "In6.Cu")
		(net "M_D_CPU1_SA_DQ<1>")
	)
	(segment
		(start 61.117988 -303.213008)
		(end 60.853574 -303.477422)
		(width 0.18288)
		(layer "In6.Cu")
		(net "M_D_CPU1_SA_DQ<1>")
	)
	(segment
		(start 45.159676 -312.443876)
		(end 44.713144 -312.443876)
		(width 0.18288)
		(layer "In6.Cu")
		(net "M_D_CPU1_SA_DQ<1>")
	)
	(segment
		(start 52.523644 -309.091838)
		(end 50.8254 -309.091838)
		(width 0.18288)
		(layer "In6.Cu")
		(net "M_D_CPU1_SA_DQ<1>")
	)
	(segment
		(start 31.176468 -315.891672)
		(end 30.203648 -314.918852)
		(width 0.18288)
		(layer "In6.Cu")
		(net "M_D_CPU1_SA_DQ<1>")
	)
	(segment
		(start 54.331108 -307.284374)
		(end 52.523644 -309.091838)
		(width 0.18288)
		(layer "In6.Cu")
		(net "M_D_CPU1_SA_DQ<1>")
	)
	(segment
		(start 89.947496 -278.012144)
		(end 89.938606 -278.017224)
		(width 0.088646)
		(layer "In6.Cu")
		(net "M_D_CPU1_SA_DQ<1>")
	)
	(segment
		(start 85.640418 -280.513028)
		(end 85.421978 -280.731468)
		(width 0.088646)
		(layer "In6.Cu")
		(net "M_D_CPU1_SA_DQ<1>")
	)
	(segment
		(start 19.554952 -315.041788)
		(end 18.93316 -315.66358)
		(width 0.18288)
		(layer "In6.Cu")
		(net "M_D_CPU1_SA_DQ<1>")
	)
	(segment
		(start 95.303594 -275.8948)
		(end 94.73565 -276.33168)
		(width 0.088646)
		(layer "In6.Cu")
		(net "M_D_CPU1_SA_DQ<1>")
	)
	(segment
		(start 37.420296 -316.741556)
		(end 34.900362 -316.741556)
		(width 0.18288)
		(layer "In6.Cu")
		(net "M_D_CPU1_SA_DQ<1>")
	)
	(segment
		(start 60.249816 -303.325784)
		(end 58.872374 -304.703226)
		(width 0.18288)
		(layer "In6.Cu")
		(net "M_D_CPU1_SA_DQ<1>")
	)
	(segment
		(start 48.275494 -311.641744)
		(end 45.961808 -311.641744)
		(width 0.18288)
		(layer "In6.Cu")
		(net "M_D_CPU1_SA_DQ<1>")
	)
	(segment
		(start 39.2684 -314.893452)
		(end 37.420296 -316.741556)
		(width 0.18288)
		(layer "In6.Cu")
		(net "M_D_CPU1_SA_DQ<1>")
	)
	(segment
		(start 85.421978 -281.373326)
		(end 84.818728 -281.976576)
		(width 0.088646)
		(layer "In6.Cu")
		(net "M_D_CPU1_SA_DQ<1>")
	)
	(segment
		(start 85.421978 -280.731468)
		(end 85.421978 -281.373326)
		(width 0.088646)
		(layer "In6.Cu")
		(net "M_D_CPU1_SA_DQ<1>")
	)
	(segment
		(start 66.678556 -301.439326)
		(end 65.765934 -301.439326)
		(width 0.18288)
		(layer "In6.Cu")
		(net "M_D_CPU1_SA_DQ<1>")
	)
	(segment
		(start 34.900362 -316.741556)
		(end 34.050478 -315.891672)
		(width 0.18288)
		(layer "In6.Cu")
		(net "M_D_CPU1_SA_DQ<1>")
	)
	(segment
		(start 86.658196 -278.82596)
		(end 86.649306 -278.83104)
		(width 0.088646)
		(layer "In6.Cu")
		(net "M_D_CPU1_SA_DQ<1>")
	)
	(segment
		(start 84.11464 -281.976576)
		(end 69.195696 -296.89552)
		(width 0.18288)
		(layer "In6.Cu")
		(net "M_D_CPU1_SA_DQ<1>")
	)
	(segment
		(start 58.425588 -304.703226)
		(end 56.662828 -306.465986)
		(width 0.18288)
		(layer "In6.Cu")
		(net "M_D_CPU1_SA_DQ<1>")
	)
	(segment
		(start 55.06339 -307.284374)
		(end 54.331108 -307.284374)
		(width 0.18288)
		(layer "In6.Cu")
		(net "M_D_CPU1_SA_DQ<1>")
	)
	(segment
		(start 60.96635 -302.60925)
		(end 60.96635 -302.83531)
		(width 0.18288)
		(layer "In6.Cu")
		(net "M_D_CPU1_SA_DQ<1>")
	)
	(segment
		(start 42.544492 -313.449716)
		(end 41.944544 -314.049664)
		(width 0.18288)
		(layer "In6.Cu")
		(net "M_D_CPU1_SA_DQ<1>")
	)
	(segment
		(start 90.41765 -277.198074)
		(end 90.40876 -277.203154)
		(width 0.088646)
		(layer "In6.Cu")
		(net "M_D_CPU1_SA_DQ<1>")
	)
	(segment
		(start 69.195696 -298.922186)
		(end 66.678556 -301.439326)
		(width 0.18288)
		(layer "In6.Cu")
		(net "M_D_CPU1_SA_DQ<1>")
	)
	(segment
		(start 65.765934 -301.439326)
		(end 64.66078 -302.54448)
		(width 0.18288)
		(layer "In6.Cu")
		(net "M_D_CPU1_SA_DQ<1>")
	)
	(segment
		(start 17.836134 -315.66358)
		(end 16.789146 -314.616592)
		(width 0.18288)
		(layer "In6.Cu")
		(net "M_D_CPU1_SA_DQ<1>")
	)
	(segment
		(start 86.470744 -279.150318)
		(end 86.470744 -279.160224)
		(width 0.088646)
		(layer "In6.Cu")
		(net "M_D_CPU1_SA_DQ<1>")
	)
	(segment
		(start 84.562188 -281.976576)
		(end 84.11464 -281.976576)
		(width 0.18288)
		(layer "In6.Cu")
		(net "M_D_CPU1_SA_DQ<1>")
	)
	(segment
		(start 62.775592 -302.29175)
		(end 61.28385 -302.29175)
		(width 0.18288)
		(layer "In6.Cu")
		(net "M_D_CPU1_SA_DQ<1>")
	)
	(segment
		(start 40.807132 -314.049664)
		(end 39.963344 -314.893452)
		(width 0.18288)
		(layer "In6.Cu")
		(net "M_D_CPU1_SA_DQ<1>")
	)
	(segment
		(start 18.93316 -315.66358)
		(end 17.836134 -315.66358)
		(width 0.18288)
		(layer "In6.Cu")
		(net "M_D_CPU1_SA_DQ<1>")
	)
	(segment
		(start 93.156278 -276.392894)
		(end 93.141546 -276.384258)
		(width 0.088646)
		(layer "In6.Cu")
		(net "M_D_CPU1_SA_DQ<1>")
	)
	(segment
		(start 86.000844 -279.964134)
		(end 86.000844 -279.982676)
		(width 0.088646)
		(layer "In6.Cu")
		(net "M_D_CPU1_SA_DQ<1>")
	)
	(segment
		(start 90.699844 -276.708616)
		(end 90.699844 -276.72411)
		(width 0.088646)
		(layer "In6.Cu")
		(net "M_D_CPU1_SA_DQ<1>")
	)
	(segment
		(start 55.881778 -306.465986)
		(end 55.06339 -307.284374)
		(width 0.18288)
		(layer "In6.Cu")
		(net "M_D_CPU1_SA_DQ<1>")
	)
	(segment
		(start 24.869902 -315.041788)
		(end 19.554952 -315.041788)
		(width 0.18288)
		(layer "In6.Cu")
		(net "M_D_CPU1_SA_DQ<1>")
	)
	(segment
		(start 43.707304 -313.449716)
		(end 42.544492 -313.449716)
		(width 0.18288)
		(layer "In6.Cu")
		(net "M_D_CPU1_SA_DQ<1>")
	)
	(segment
		(start 61.117988 -302.986948)
		(end 61.117988 -303.213008)
		(width 0.18288)
		(layer "In6.Cu")
		(net "M_D_CPU1_SA_DQ<1>")
	)
	(segment
		(start 64.66078 -302.54448)
		(end 63.028322 -302.54448)
		(width 0.18288)
		(layer "In6.Cu")
		(net "M_D_CPU1_SA_DQ<1>")
	)
	(segment
		(start 39.963344 -314.893452)
		(end 39.2684 -314.893452)
		(width 0.18288)
		(layer "In6.Cu")
		(net "M_D_CPU1_SA_DQ<1>")
	)
	(segment
		(start 25.78735 -314.12434)
		(end 24.869902 -315.041788)
		(width 0.18288)
		(layer "In6.Cu")
		(net "M_D_CPU1_SA_DQ<1>")
	)
	(segment
		(start 45.961808 -311.641744)
		(end 45.159676 -312.443876)
		(width 0.18288)
		(layer "In6.Cu")
		(net "M_D_CPU1_SA_DQ<1>")
	)
	(segment
		(start 28.592018 -314.12434)
		(end 25.78735 -314.12434)
		(width 0.18288)
		(layer "In6.Cu")
		(net "M_D_CPU1_SA_DQ<1>")
	)
	(segment
		(start 60.853574 -303.477422)
		(end 60.627514 -303.477422)
		(width 0.18288)
		(layer "In6.Cu")
		(net "M_D_CPU1_SA_DQ<1>")
	)
	(segment
		(start 63.028322 -302.54448)
		(end 62.775592 -302.29175)
		(width 0.18288)
		(layer "In6.Cu")
		(net "M_D_CPU1_SA_DQ<1>")
	)
	(segment
		(start 84.818728 -281.976576)
		(end 84.562188 -281.976576)
		(width 0.088646)
		(layer "In6.Cu")
		(net "M_D_CPU1_SA_DQ<1>")
	)
	(segment
		(start 41.944544 -314.049664)
		(end 40.807132 -314.049664)
		(width 0.18288)
		(layer "In6.Cu")
		(net "M_D_CPU1_SA_DQ<1>")
	)
	(segment
		(start 60.96635 -302.83531)
		(end 61.117988 -302.986948)
		(width 0.18288)
		(layer "In6.Cu")
		(net "M_D_CPU1_SA_DQ<1>")
	)
	(segment
		(start 60.475876 -303.325784)
		(end 60.249816 -303.325784)
		(width 0.18288)
		(layer "In6.Cu")
		(net "M_D_CPU1_SA_DQ<1>")
	)
	(segment
		(start 86.188296 -279.639776)
		(end 86.179406 -279.644856)
		(width 0.088646)
		(layer "In6.Cu")
		(net "M_D_CPU1_SA_DQ<1>")
	)
	(segment
		(start 90.887296 -276.384258)
		(end 90.878406 -276.389338)
		(width 0.088646)
		(layer "In6.Cu")
		(net "M_D_CPU1_SA_DQ<1>")
	)
	(segment
		(start 92.216478 -276.392894)
		(end 92.201746 -276.384258)
		(width 0.088646)
		(layer "In6.Cu")
		(net "M_D_CPU1_SA_DQ<1>")
	)
	(segment
		(start 60.627514 -303.477422)
		(end 60.475876 -303.325784)
		(width 0.18288)
		(layer "In6.Cu")
		(net "M_D_CPU1_SA_DQ<1>")
	)
	(segment
		(start 29.38653 -314.918852)
		(end 28.592018 -314.12434)
		(width 0.18288)
		(layer "In6.Cu")
		(net "M_D_CPU1_SA_DQ<1>")
	)
	(segment
		(start 61.28385 -302.29175)
		(end 60.96635 -302.60925)
		(width 0.18288)
		(layer "In6.Cu")
		(net "M_D_CPU1_SA_DQ<1>")
	)
	(segment
		(start 30.203648 -314.918852)
		(end 29.38653 -314.918852)
		(width 0.18288)
		(layer "In6.Cu")
		(net "M_D_CPU1_SA_DQ<1>")
	)
	(segment
		(start 34.050478 -315.891672)
		(end 31.176468 -315.891672)
		(width 0.18288)
		(layer "In6.Cu")
		(net "M_D_CPU1_SA_DQ<1>")
	)
	(segment
		(start 94.73565 -276.33168)
		(end 94.64675 -276.384258)
		(width 0.088646)
		(layer "In6.Cu")
		(net "M_D_CPU1_SA_DQ<1>")
	)
	(segment
		(start 56.662828 -306.465986)
		(end 55.881778 -306.465986)
		(width 0.18288)
		(layer "In6.Cu")
		(net "M_D_CPU1_SA_DQ<1>")
	)
	(arc
		(start 91.82735 -276.384258)
		(mid 91.550537 -276.460128)
		(end 91.272106 -276.390354)
		(width 0.088646)
		(layer "In6.Cu")
		(net "M_D_CPU1_SA_DQ<1>")
	)
	(arc
		(start 88.537796 -278.82596)
		(mid 88.255094 -278.901736)
		(end 87.972392 -278.82596)
		(width 0.088646)
		(layer "In6.Cu")
		(net "M_D_CPU1_SA_DQ<1>")
	)
	(arc
		(start 92.76715 -276.384258)
		(mid 92.492951 -276.460093)
		(end 92.216478 -276.392894)
		(width 0.088646)
		(layer "In6.Cu")
		(net "M_D_CPU1_SA_DQ<1>")
	)
	(arc
		(start 86.000844 -279.982676)
		(mid 85.920682 -280.254865)
		(end 85.718396 -280.453846)
		(width 0.088646)
		(layer "In6.Cu")
		(net "M_D_CPU1_SA_DQ<1>")
	)
	(arc
		(start 90.230198 -277.530052)
		(mid 90.152569 -277.808465)
		(end 89.947496 -278.012144)
		(width 0.088646)
		(layer "In6.Cu")
		(net "M_D_CPU1_SA_DQ<1>")
	)
	(arc
		(start 92.201746 -276.384258)
		(mid 92.014548 -276.334115)
		(end 91.82735 -276.384258)
		(width 0.088646)
		(layer "In6.Cu")
		(net "M_D_CPU1_SA_DQ<1>")
	)
	(arc
		(start 93.70695 -276.384258)
		(mid 93.432751 -276.460093)
		(end 93.156278 -276.392894)
		(width 0.088646)
		(layer "In6.Cu")
		(net "M_D_CPU1_SA_DQ<1>")
	)
	(arc
		(start 86.470744 -279.160224)
		(mid 86.392633 -279.437173)
		(end 86.188296 -279.639776)
		(width 0.088646)
		(layer "In6.Cu")
		(net "M_D_CPU1_SA_DQ<1>")
	)
	(arc
		(start 87.597996 -278.82596)
		(mid 87.315294 -278.901736)
		(end 87.032592 -278.82596)
		(width 0.088646)
		(layer "In6.Cu")
		(net "M_D_CPU1_SA_DQ<1>")
	)
	(arc
		(start 89.760044 -278.346408)
		(mid 89.681933 -278.623357)
		(end 89.477596 -278.82596)
		(width 0.088646)
		(layer "In6.Cu")
		(net "M_D_CPU1_SA_DQ<1>")
	)
	(arc
		(start 87.972392 -278.82596)
		(mid 87.785194 -278.775817)
		(end 87.597996 -278.82596)
		(width 0.088646)
		(layer "In6.Cu")
		(net "M_D_CPU1_SA_DQ<1>")
	)
	(arc
		(start 90.878406 -276.389338)
		(mid 90.747492 -276.525698)
		(end 90.699844 -276.708616)
		(width 0.088646)
		(layer "In6.Cu")
		(net "M_D_CPU1_SA_DQ<1>")
	)
	(arc
		(start 94.64675 -276.384258)
		(mid 94.364048 -276.460034)
		(end 94.081346 -276.384258)
		(width 0.088646)
		(layer "In6.Cu")
		(net "M_D_CPU1_SA_DQ<1>")
	)
	(arc
		(start 85.718396 -280.453846)
		(mid 85.677466 -280.480879)
		(end 85.640418 -280.513028)
		(width 0.088646)
		(layer "In6.Cu")
		(net "M_D_CPU1_SA_DQ<1>")
	)
	(arc
		(start 87.032592 -278.82596)
		(mid 86.845394 -278.775817)
		(end 86.658196 -278.82596)
		(width 0.088646)
		(layer "In6.Cu")
		(net "M_D_CPU1_SA_DQ<1>")
	)
	(arc
		(start 88.912192 -278.82596)
		(mid 88.724994 -278.775817)
		(end 88.537796 -278.82596)
		(width 0.088646)
		(layer "In6.Cu")
		(net "M_D_CPU1_SA_DQ<1>")
	)
	(arc
		(start 86.649306 -278.83104)
		(mid 86.518392 -278.9674)
		(end 86.470744 -279.150318)
		(width 0.088646)
		(layer "In6.Cu")
		(net "M_D_CPU1_SA_DQ<1>")
	)
	(arc
		(start 94.081346 -276.384258)
		(mid 93.894148 -276.334115)
		(end 93.70695 -276.384258)
		(width 0.088646)
		(layer "In6.Cu")
		(net "M_D_CPU1_SA_DQ<1>")
	)
	(arc
		(start 89.938606 -278.017224)
		(mid 89.807692 -278.153584)
		(end 89.760044 -278.336502)
		(width 0.088646)
		(layer "In6.Cu")
		(net "M_D_CPU1_SA_DQ<1>")
	)
	(arc
		(start 91.261692 -276.384258)
		(mid 91.074494 -276.334115)
		(end 90.887296 -276.384258)
		(width 0.088646)
		(layer "In6.Cu")
		(net "M_D_CPU1_SA_DQ<1>")
	)
	(arc
		(start 90.699844 -276.72411)
		(mid 90.620474 -276.997844)
		(end 90.41765 -277.198074)
		(width 0.088646)
		(layer "In6.Cu")
		(net "M_D_CPU1_SA_DQ<1>")
	)
	(arc
		(start 86.179406 -279.644856)
		(mid 86.048492 -279.781216)
		(end 86.000844 -279.964134)
		(width 0.088646)
		(layer "In6.Cu")
		(net "M_D_CPU1_SA_DQ<1>")
	)
	(arc
		(start 90.40876 -277.203154)
		(mid 90.277846 -277.339514)
		(end 90.230198 -277.522432)
		(width 0.088646)
		(layer "In6.Cu")
		(net "M_D_CPU1_SA_DQ<1>")
	)
	(arc
		(start 89.477596 -278.82596)
		(mid 89.194894 -278.901736)
		(end 88.912192 -278.82596)
		(width 0.088646)
		(layer "In6.Cu")
		(net "M_D_CPU1_SA_DQ<1>")
	)
	(arc
		(start 93.141546 -276.384258)
		(mid 92.954348 -276.334115)
		(end 92.76715 -276.384258)
		(width 0.088646)
		(layer "In6.Cu")
		(net "M_D_CPU1_SA_DQ<1>")
	)
	(segment
		(start 17.578578 -295.342564)
		(end 17.578578 -295.190926)
		(width 0.20066)
		(layer "F.Cu")
		(net "M_D_CPU1_SA_DQ<19>")
	)
	(segment
		(start 14.812264 -295.491662)
		(end 16.885158 -295.491662)
		(width 0.1016)
		(layer "F.Cu")
		(net "M_D_CPU1_SA_DQ<19>")
	)
	(segment
		(start 18.968212 -295.06672)
		(end 19.784314 -295.06672)
		(width 0.20066)
		(layer "F.Cu")
		(net "M_D_CPU1_SA_DQ<19>")
	)
	(segment
		(start 13.937742 -295.06672)
		(end 14.063726 -295.192704)
		(width 0.20066)
		(layer "F.Cu")
		(net "M_D_CPU1_SA_DQ<19>")
	)
	(segment
		(start 17.578578 -295.190926)
		(end 17.707102 -295.062402)
		(width 0.20066)
		(layer "F.Cu")
		(net "M_D_CPU1_SA_DQ<19>")
	)
	(segment
		(start 17.707102 -295.062402)
		(end 18.102326 -295.062402)
		(width 0.20066)
		(layer "F.Cu")
		(net "M_D_CPU1_SA_DQ<19>")
	)
	(segment
		(start 17.42948 -295.491662)
		(end 17.578578 -295.342564)
		(width 0.20066)
		(layer "F.Cu")
		(net "M_D_CPU1_SA_DQ<19>")
	)
	(segment
		(start 18.760694 -295.274238)
		(end 18.968212 -295.06672)
		(width 0.20066)
		(layer "F.Cu")
		(net "M_D_CPU1_SA_DQ<19>")
	)
	(segment
		(start 16.885158 -295.491662)
		(end 17.42948 -295.491662)
		(width 0.20066)
		(layer "F.Cu")
		(net "M_D_CPU1_SA_DQ<19>")
	)
	(segment
		(start 14.574266 -295.491662)
		(end 14.812264 -295.491662)
		(width 0.101854)
		(layer "F.Cu")
		(net "M_D_CPU1_SA_DQ<19>")
	)
	(segment
		(start 18.102326 -295.062402)
		(end 18.314162 -295.274238)
		(width 0.20066)
		(layer "F.Cu")
		(net "M_D_CPU1_SA_DQ<19>")
	)
	(segment
		(start 14.20622 -295.505886)
		(end 14.560042 -295.505886)
		(width 0.20066)
		(layer "F.Cu")
		(net "M_D_CPU1_SA_DQ<19>")
	)
	(segment
		(start 14.560042 -295.505886)
		(end 14.574266 -295.491662)
		(width 0.101854)
		(layer "F.Cu")
		(net "M_D_CPU1_SA_DQ<19>")
	)
	(segment
		(start 18.314162 -295.274238)
		(end 18.760694 -295.274238)
		(width 0.20066)
		(layer "F.Cu")
		(net "M_D_CPU1_SA_DQ<19>")
	)
	(segment
		(start 12.240514 -295.06672)
		(end 13.937742 -295.06672)
		(width 0.20066)
		(layer "F.Cu")
		(net "M_D_CPU1_SA_DQ<19>")
	)
	(segment
		(start 14.063726 -295.192704)
		(end 14.063726 -295.363392)
		(width 0.20066)
		(layer "F.Cu")
		(net "M_D_CPU1_SA_DQ<19>")
	)
	(segment
		(start 14.063726 -295.363392)
		(end 14.20622 -295.505886)
		(width 0.20066)
		(layer "F.Cu")
		(net "M_D_CPU1_SA_DQ<19>")
	)
	(segment
		(start 20.889214 -295.06672)
		(end 19.784314 -295.06672)
		(width 0.20066)
		(layer "F.Cu")
		(net "M_D_CPU1_SA_DQ<19>")
	)
	(arc
		(start 100.472494 -272.917158)
		(mid 100.472557 -273.185128)
		(end 100.472748 -273.453098)
		(width 0.20066)
		(layer "F.Cu")
		(net "M_D_CPU1_SA_DQ<19>")
	)
	(segment
		(start 62.534038 -292.076886)
		(end 60.945522 -292.076886)
		(width 0.18288)
		(layer "In11.Cu")
		(net "M_D_CPU1_SA_DQ<19>")
	)
	(segment
		(start 37.801804 -297.340528)
		(end 36.787582 -297.340528)
		(width 0.18288)
		(layer "In11.Cu")
		(net "M_D_CPU1_SA_DQ<19>")
	)
	(segment
		(start 54.349396 -295.518078)
		(end 52.526946 -297.340528)
		(width 0.18288)
		(layer "In11.Cu")
		(net "M_D_CPU1_SA_DQ<19>")
	)
	(segment
		(start 44.150026 -297.692826)
		(end 43.667426 -298.175426)
		(width 0.18288)
		(layer "In11.Cu")
		(net "M_D_CPU1_SA_DQ<19>")
	)
	(segment
		(start 22.92477 -295.46169)
		(end 22.73173 -295.65473)
		(width 0.18288)
		(layer "In11.Cu")
		(net "M_D_CPU1_SA_DQ<19>")
	)
	(segment
		(start 92.216478 -273.76882)
		(end 92.201746 -273.777456)
		(width 0.088646)
		(layer "In11.Cu")
		(net "M_D_CPU1_SA_DQ<19>")
	)
	(segment
		(start 40.467026 -296.880026)
		(end 40.006524 -297.340528)
		(width 0.18288)
		(layer "In11.Cu")
		(net "M_D_CPU1_SA_DQ<19>")
	)
	(segment
		(start 38.888924 -297.340528)
		(end 38.695884 -297.147488)
		(width 0.18288)
		(layer "In11.Cu")
		(net "M_D_CPU1_SA_DQ<19>")
	)
	(segment
		(start 58.772552 -293.125906)
		(end 57.844944 -293.510208)
		(width 0.18288)
		(layer "In11.Cu")
		(net "M_D_CPU1_SA_DQ<19>")
	)
	(segment
		(start 98.12528 -273.517106)
		(end 97.945194 -273.697192)
		(width 0.088646)
		(layer "In11.Cu")
		(net "M_D_CPU1_SA_DQ<19>")
	)
	(segment
		(start 21.477224 -295.65473)
		(end 20.889214 -295.06672)
		(width 0.18288)
		(layer "In11.Cu")
		(net "M_D_CPU1_SA_DQ<19>")
	)
	(segment
		(start 23.81885 -295.65473)
		(end 23.62581 -295.46169)
		(width 0.18288)
		(layer "In11.Cu")
		(net "M_D_CPU1_SA_DQ<19>")
	)
	(segment
		(start 33.016952 -298.099226)
		(end 32.960056 -298.04233)
		(width 0.18288)
		(layer "In11.Cu")
		(net "M_D_CPU1_SA_DQ<19>")
	)
	(segment
		(start 47.775114 -298.190666)
		(end 47.626778 -298.04233)
		(width 0.18288)
		(layer "In11.Cu")
		(net "M_D_CPU1_SA_DQ<19>")
	)
	(segment
		(start 25.705308 -296.393108)
		(end 24.96693 -295.65473)
		(width 0.18288)
		(layer "In11.Cu")
		(net "M_D_CPU1_SA_DQ<19>")
	)
	(segment
		(start 32.960056 -298.04233)
		(end 30.582362 -298.04233)
		(width 0.18288)
		(layer "In11.Cu")
		(net "M_D_CPU1_SA_DQ<19>")
	)
	(segment
		(start 67.521582 -290.543234)
		(end 66.827146 -291.23767)
		(width 0.18288)
		(layer "In11.Cu")
		(net "M_D_CPU1_SA_DQ<19>")
	)
	(segment
		(start 59.896502 -293.125906)
		(end 58.772552 -293.125906)
		(width 0.18288)
		(layer "In11.Cu")
		(net "M_D_CPU1_SA_DQ<19>")
	)
	(segment
		(start 40.006524 -297.340528)
		(end 38.888924 -297.340528)
		(width 0.18288)
		(layer "In11.Cu")
		(net "M_D_CPU1_SA_DQ<19>")
	)
	(segment
		(start 23.43277 -294.883332)
		(end 23.11781 -294.883332)
		(width 0.18288)
		(layer "In11.Cu")
		(net "M_D_CPU1_SA_DQ<19>")
	)
	(segment
		(start 41.914826 -296.880026)
		(end 40.467026 -296.880026)
		(width 0.18288)
		(layer "In11.Cu")
		(net "M_D_CPU1_SA_DQ<19>")
	)
	(segment
		(start 95.031306 -273.77136)
		(end 95.020892 -273.777456)
		(width 0.088646)
		(layer "In11.Cu")
		(net "M_D_CPU1_SA_DQ<19>")
	)
	(segment
		(start 30.567884 -298.027852)
		(end 28.9814 -298.027852)
		(width 0.18288)
		(layer "In11.Cu")
		(net "M_D_CPU1_SA_DQ<19>")
	)
	(segment
		(start 38.695884 -296.847006)
		(end 38.502844 -296.653966)
		(width 0.18288)
		(layer "In11.Cu")
		(net "M_D_CPU1_SA_DQ<19>")
	)
	(segment
		(start 54.986428 -295.518078)
		(end 54.349396 -295.518078)
		(width 0.18288)
		(layer "In11.Cu")
		(net "M_D_CPU1_SA_DQ<19>")
	)
	(segment
		(start 46.126908 -298.04233)
		(end 45.777404 -297.692826)
		(width 0.18288)
		(layer "In11.Cu")
		(net "M_D_CPU1_SA_DQ<19>")
	)
	(segment
		(start 67.521582 -289.969448)
		(end 67.521582 -290.543234)
		(width 0.18288)
		(layer "In11.Cu")
		(net "M_D_CPU1_SA_DQ<19>")
	)
	(segment
		(start 64.977518 -291.23767)
		(end 63.893192 -292.321996)
		(width 0.18288)
		(layer "In11.Cu")
		(net "M_D_CPU1_SA_DQ<19>")
	)
	(segment
		(start 38.502844 -296.653966)
		(end 38.187884 -296.653966)
		(width 0.18288)
		(layer "In11.Cu")
		(net "M_D_CPU1_SA_DQ<19>")
	)
	(segment
		(start 52.526946 -297.340528)
		(end 51.875182 -297.340528)
		(width 0.18288)
		(layer "In11.Cu")
		(net "M_D_CPU1_SA_DQ<19>")
	)
	(segment
		(start 23.62581 -295.46169)
		(end 23.62581 -295.076372)
		(width 0.18288)
		(layer "In11.Cu")
		(net "M_D_CPU1_SA_DQ<19>")
	)
	(segment
		(start 50.226976 -297.192192)
		(end 49.228502 -298.190666)
		(width 0.18288)
		(layer "In11.Cu")
		(net "M_D_CPU1_SA_DQ<19>")
	)
	(segment
		(start 51.726846 -297.192192)
		(end 50.226976 -297.192192)
		(width 0.18288)
		(layer "In11.Cu")
		(net "M_D_CPU1_SA_DQ<19>")
	)
	(segment
		(start 84.222082 -274.68449)
		(end 84.222082 -275.87321)
		(width 0.088646)
		(layer "In11.Cu")
		(net "M_D_CPU1_SA_DQ<19>")
	)
	(segment
		(start 49.228502 -298.190666)
		(end 47.775114 -298.190666)
		(width 0.18288)
		(layer "In11.Cu")
		(net "M_D_CPU1_SA_DQ<19>")
	)
	(segment
		(start 90.332306 -273.77136)
		(end 90.321892 -273.777456)
		(width 0.088646)
		(layer "In11.Cu")
		(net "M_D_CPU1_SA_DQ<19>")
	)
	(segment
		(start 81.052416 -276.438614)
		(end 67.521582 -289.969448)
		(width 0.18288)
		(layer "In11.Cu")
		(net "M_D_CPU1_SA_DQ<19>")
	)
	(segment
		(start 38.187884 -296.653966)
		(end 37.994844 -296.847006)
		(width 0.18288)
		(layer "In11.Cu")
		(net "M_D_CPU1_SA_DQ<19>")
	)
	(segment
		(start 96.915478 -273.76882)
		(end 96.900746 -273.777456)
		(width 0.088646)
		(layer "In11.Cu")
		(net "M_D_CPU1_SA_DQ<19>")
	)
	(segment
		(start 37.994844 -297.147488)
		(end 37.801804 -297.340528)
		(width 0.18288)
		(layer "In11.Cu")
		(net "M_D_CPU1_SA_DQ<19>")
	)
	(segment
		(start 23.11781 -294.883332)
		(end 22.92477 -295.076372)
		(width 0.18288)
		(layer "In11.Cu")
		(net "M_D_CPU1_SA_DQ<19>")
	)
	(segment
		(start 100.472748 -273.453098)
		(end 100.117148 -273.357848)
		(width 0.088646)
		(layer "In11.Cu")
		(net "M_D_CPU1_SA_DQ<19>")
	)
	(segment
		(start 60.945522 -292.076886)
		(end 59.896502 -293.125906)
		(width 0.18288)
		(layer "In11.Cu")
		(net "M_D_CPU1_SA_DQ<19>")
	)
	(segment
		(start 93.156278 -273.76882)
		(end 93.141546 -273.777456)
		(width 0.088646)
		(layer "In11.Cu")
		(net "M_D_CPU1_SA_DQ<19>")
	)
	(segment
		(start 55.748428 -294.756078)
		(end 54.986428 -295.518078)
		(width 0.18288)
		(layer "In11.Cu")
		(net "M_D_CPU1_SA_DQ<19>")
	)
	(segment
		(start 22.73173 -295.65473)
		(end 21.477224 -295.65473)
		(width 0.18288)
		(layer "In11.Cu")
		(net "M_D_CPU1_SA_DQ<19>")
	)
	(segment
		(start 98.411538 -273.125438)
		(end 98.350578 -273.160236)
		(width 0.088646)
		(layer "In11.Cu")
		(net "M_D_CPU1_SA_DQ<19>")
	)
	(segment
		(start 62.779148 -292.321996)
		(end 62.534038 -292.076886)
		(width 0.18288)
		(layer "In11.Cu")
		(net "M_D_CPU1_SA_DQ<19>")
	)
	(segment
		(start 30.582362 -298.04233)
		(end 30.567884 -298.027852)
		(width 0.18288)
		(layer "In11.Cu")
		(net "M_D_CPU1_SA_DQ<19>")
	)
	(segment
		(start 26.492708 -296.393108)
		(end 25.705308 -296.393108)
		(width 0.18288)
		(layer "In11.Cu")
		(net "M_D_CPU1_SA_DQ<19>")
	)
	(segment
		(start 28.262326 -298.162726)
		(end 26.492708 -296.393108)
		(width 0.18288)
		(layer "In11.Cu")
		(net "M_D_CPU1_SA_DQ<19>")
	)
	(segment
		(start 51.875182 -297.340528)
		(end 51.726846 -297.192192)
		(width 0.18288)
		(layer "In11.Cu")
		(net "M_D_CPU1_SA_DQ<19>")
	)
	(segment
		(start 94.09176 -273.77136)
		(end 94.081346 -273.777456)
		(width 0.088646)
		(layer "In11.Cu")
		(net "M_D_CPU1_SA_DQ<19>")
	)
	(segment
		(start 37.994844 -296.847006)
		(end 37.994844 -297.147488)
		(width 0.18288)
		(layer "In11.Cu")
		(net "M_D_CPU1_SA_DQ<19>")
	)
	(segment
		(start 43.210226 -298.175426)
		(end 41.914826 -296.880026)
		(width 0.18288)
		(layer "In11.Cu")
		(net "M_D_CPU1_SA_DQ<19>")
	)
	(segment
		(start 85.039454 -273.867118)
		(end 84.222082 -274.68449)
		(width 0.088646)
		(layer "In11.Cu")
		(net "M_D_CPU1_SA_DQ<19>")
	)
	(segment
		(start 43.667426 -298.175426)
		(end 43.210226 -298.175426)
		(width 0.18288)
		(layer "In11.Cu")
		(net "M_D_CPU1_SA_DQ<19>")
	)
	(segment
		(start 85.505798 -273.867118)
		(end 85.039454 -273.867118)
		(width 0.088646)
		(layer "In11.Cu")
		(net "M_D_CPU1_SA_DQ<19>")
	)
	(segment
		(start 56.599074 -294.756078)
		(end 55.748428 -294.756078)
		(width 0.18288)
		(layer "In11.Cu")
		(net "M_D_CPU1_SA_DQ<19>")
	)
	(segment
		(start 83.471258 -276.438614)
		(end 81.052416 -276.438614)
		(width 0.18288)
		(layer "In11.Cu")
		(net "M_D_CPU1_SA_DQ<19>")
	)
	(segment
		(start 22.92477 -295.076372)
		(end 22.92477 -295.46169)
		(width 0.18288)
		(layer "In11.Cu")
		(net "M_D_CPU1_SA_DQ<19>")
	)
	(segment
		(start 28.9814 -298.027852)
		(end 28.846526 -298.162726)
		(width 0.18288)
		(layer "In11.Cu")
		(net "M_D_CPU1_SA_DQ<19>")
	)
	(segment
		(start 100.117148 -273.357848)
		(end 99.720146 -273.12874)
		(width 0.088646)
		(layer "In11.Cu")
		(net "M_D_CPU1_SA_DQ<19>")
	)
	(segment
		(start 57.844944 -293.510208)
		(end 56.599074 -294.756078)
		(width 0.18288)
		(layer "In11.Cu")
		(net "M_D_CPU1_SA_DQ<19>")
	)
	(segment
		(start 66.827146 -291.23767)
		(end 64.977518 -291.23767)
		(width 0.18288)
		(layer "In11.Cu")
		(net "M_D_CPU1_SA_DQ<19>")
	)
	(segment
		(start 86.57336 -273.77136)
		(end 86.562946 -273.777456)
		(width 0.088646)
		(layer "In11.Cu")
		(net "M_D_CPU1_SA_DQ<19>")
	)
	(segment
		(start 36.639246 -297.192192)
		(end 35.02406 -297.192192)
		(width 0.18288)
		(layer "In11.Cu")
		(net "M_D_CPU1_SA_DQ<19>")
	)
	(segment
		(start 47.626778 -298.04233)
		(end 46.126908 -298.04233)
		(width 0.18288)
		(layer "In11.Cu")
		(net "M_D_CPU1_SA_DQ<19>")
	)
	(segment
		(start 34.117026 -298.099226)
		(end 33.016952 -298.099226)
		(width 0.18288)
		(layer "In11.Cu")
		(net "M_D_CPU1_SA_DQ<19>")
	)
	(segment
		(start 23.62581 -295.076372)
		(end 23.43277 -294.883332)
		(width 0.18288)
		(layer "In11.Cu")
		(net "M_D_CPU1_SA_DQ<19>")
	)
	(segment
		(start 98.288348 -273.222212)
		(end 98.221038 -273.338544)
		(width 0.088646)
		(layer "In11.Cu")
		(net "M_D_CPU1_SA_DQ<19>")
	)
	(segment
		(start 95.975678 -273.76882)
		(end 95.960946 -273.777456)
		(width 0.088646)
		(layer "In11.Cu")
		(net "M_D_CPU1_SA_DQ<19>")
	)
	(segment
		(start 63.893192 -292.321996)
		(end 62.779148 -292.321996)
		(width 0.18288)
		(layer "In11.Cu")
		(net "M_D_CPU1_SA_DQ<19>")
	)
	(segment
		(start 35.02406 -297.192192)
		(end 34.117026 -298.099226)
		(width 0.18288)
		(layer "In11.Cu")
		(net "M_D_CPU1_SA_DQ<19>")
	)
	(segment
		(start 99.351338 -273.125438)
		(end 99.339654 -273.132042)
		(width 0.088646)
		(layer "In11.Cu")
		(net "M_D_CPU1_SA_DQ<19>")
	)
	(segment
		(start 28.846526 -298.162726)
		(end 28.262326 -298.162726)
		(width 0.18288)
		(layer "In11.Cu")
		(net "M_D_CPU1_SA_DQ<19>")
	)
	(segment
		(start 24.96693 -295.65473)
		(end 23.81885 -295.65473)
		(width 0.18288)
		(layer "In11.Cu")
		(net "M_D_CPU1_SA_DQ<19>")
	)
	(segment
		(start 38.695884 -297.147488)
		(end 38.695884 -296.847006)
		(width 0.18288)
		(layer "In11.Cu")
		(net "M_D_CPU1_SA_DQ<19>")
	)
	(segment
		(start 45.777404 -297.692826)
		(end 44.150026 -297.692826)
		(width 0.18288)
		(layer "In11.Cu")
		(net "M_D_CPU1_SA_DQ<19>")
	)
	(segment
		(start 84.222082 -275.87321)
		(end 83.656678 -276.438614)
		(width 0.088646)
		(layer "In11.Cu")
		(net "M_D_CPU1_SA_DQ<19>")
	)
	(segment
		(start 83.656678 -276.438614)
		(end 83.471258 -276.438614)
		(width 0.088646)
		(layer "In11.Cu")
		(net "M_D_CPU1_SA_DQ<19>")
	)
	(segment
		(start 36.787582 -297.340528)
		(end 36.639246 -297.192192)
		(width 0.18288)
		(layer "In11.Cu")
		(net "M_D_CPU1_SA_DQ<19>")
	)
	(segment
		(start 85.637878 -273.76882)
		(end 85.634068 -273.771106)
		(width 0.088646)
		(layer "In11.Cu")
		(net "M_D_CPU1_SA_DQ<19>")
	)
	(arc
		(start 97.840546 -273.777456)
		(mid 97.653348 -273.827599)
		(end 97.46615 -273.777456)
		(width 0.088646)
		(layer "In11.Cu")
		(net "M_D_CPU1_SA_DQ<19>")
	)
	(arc
		(start 87.128096 -273.777456)
		(mid 86.851537 -273.701713)
		(end 86.57336 -273.77136)
		(width 0.088646)
		(layer "In11.Cu")
		(net "M_D_CPU1_SA_DQ<19>")
	)
	(arc
		(start 92.76715 -273.777456)
		(mid 92.492951 -273.701621)
		(end 92.216478 -273.76882)
		(width 0.088646)
		(layer "In11.Cu")
		(net "M_D_CPU1_SA_DQ<19>")
	)
	(arc
		(start 93.141546 -273.777456)
		(mid 92.954348 -273.827599)
		(end 92.76715 -273.777456)
		(width 0.088646)
		(layer "In11.Cu")
		(net "M_D_CPU1_SA_DQ<19>")
	)
	(arc
		(start 86.18855 -273.777456)
		(mid 85.914351 -273.701621)
		(end 85.637878 -273.76882)
		(width 0.088646)
		(layer "In11.Cu")
		(net "M_D_CPU1_SA_DQ<19>")
	)
	(arc
		(start 99.339654 -273.132042)
		(mid 99.059549 -273.204484)
		(end 98.780346 -273.12874)
		(width 0.088646)
		(layer "In11.Cu")
		(net "M_D_CPU1_SA_DQ<19>")
	)
	(arc
		(start 85.634068 -273.771106)
		(mid 85.566517 -273.814548)
		(end 85.505798 -273.867118)
		(width 0.088646)
		(layer "In11.Cu")
		(net "M_D_CPU1_SA_DQ<19>")
	)
	(arc
		(start 87.502492 -273.777456)
		(mid 87.315294 -273.827599)
		(end 87.128096 -273.777456)
		(width 0.088646)
		(layer "In11.Cu")
		(net "M_D_CPU1_SA_DQ<19>")
	)
	(arc
		(start 91.261946 -273.777456)
		(mid 91.074748 -273.827599)
		(end 90.88755 -273.777456)
		(width 0.088646)
		(layer "In11.Cu")
		(net "M_D_CPU1_SA_DQ<19>")
	)
	(arc
		(start 95.960946 -273.777456)
		(mid 95.773748 -273.827599)
		(end 95.58655 -273.777456)
		(width 0.088646)
		(layer "In11.Cu")
		(net "M_D_CPU1_SA_DQ<19>")
	)
	(arc
		(start 97.46615 -273.777456)
		(mid 97.191951 -273.701621)
		(end 96.915478 -273.76882)
		(width 0.088646)
		(layer "In11.Cu")
		(net "M_D_CPU1_SA_DQ<19>")
	)
	(arc
		(start 97.945194 -273.697192)
		(mid 97.895497 -273.740749)
		(end 97.840546 -273.777456)
		(width 0.088646)
		(layer "In11.Cu")
		(net "M_D_CPU1_SA_DQ<19>")
	)
	(arc
		(start 89.947496 -273.777456)
		(mid 89.664794 -273.70168)
		(end 89.382092 -273.777456)
		(width 0.088646)
		(layer "In11.Cu")
		(net "M_D_CPU1_SA_DQ<19>")
	)
	(arc
		(start 88.442292 -273.777456)
		(mid 88.255094 -273.827599)
		(end 88.067896 -273.777456)
		(width 0.088646)
		(layer "In11.Cu")
		(net "M_D_CPU1_SA_DQ<19>")
	)
	(arc
		(start 95.020892 -273.777456)
		(mid 94.833694 -273.827599)
		(end 94.646496 -273.777456)
		(width 0.088646)
		(layer "In11.Cu")
		(net "M_D_CPU1_SA_DQ<19>")
	)
	(arc
		(start 94.081346 -273.777456)
		(mid 93.894148 -273.827599)
		(end 93.70695 -273.777456)
		(width 0.088646)
		(layer "In11.Cu")
		(net "M_D_CPU1_SA_DQ<19>")
	)
	(arc
		(start 94.646496 -273.777456)
		(mid 94.369937 -273.701713)
		(end 94.09176 -273.77136)
		(width 0.088646)
		(layer "In11.Cu")
		(net "M_D_CPU1_SA_DQ<19>")
	)
	(arc
		(start 89.382092 -273.777456)
		(mid 89.194894 -273.827599)
		(end 89.007696 -273.777456)
		(width 0.088646)
		(layer "In11.Cu")
		(net "M_D_CPU1_SA_DQ<19>")
	)
	(arc
		(start 98.350578 -273.160236)
		(mid 98.315388 -273.187129)
		(end 98.288348 -273.222212)
		(width 0.088646)
		(layer "In11.Cu")
		(net "M_D_CPU1_SA_DQ<19>")
	)
	(arc
		(start 93.70695 -273.777456)
		(mid 93.432751 -273.701621)
		(end 93.156278 -273.76882)
		(width 0.088646)
		(layer "In11.Cu")
		(net "M_D_CPU1_SA_DQ<19>")
	)
	(arc
		(start 90.88755 -273.777456)
		(mid 90.610737 -273.701586)
		(end 90.332306 -273.77136)
		(width 0.088646)
		(layer "In11.Cu")
		(net "M_D_CPU1_SA_DQ<19>")
	)
	(arc
		(start 88.067896 -273.777456)
		(mid 87.785194 -273.70168)
		(end 87.502492 -273.777456)
		(width 0.088646)
		(layer "In11.Cu")
		(net "M_D_CPU1_SA_DQ<19>")
	)
	(arc
		(start 90.321892 -273.777456)
		(mid 90.134694 -273.827599)
		(end 89.947496 -273.777456)
		(width 0.088646)
		(layer "In11.Cu")
		(net "M_D_CPU1_SA_DQ<19>")
	)
	(arc
		(start 91.82735 -273.777456)
		(mid 91.544648 -273.70168)
		(end 91.261946 -273.777456)
		(width 0.088646)
		(layer "In11.Cu")
		(net "M_D_CPU1_SA_DQ<19>")
	)
	(arc
		(start 92.201746 -273.777456)
		(mid 92.014548 -273.827599)
		(end 91.82735 -273.777456)
		(width 0.088646)
		(layer "In11.Cu")
		(net "M_D_CPU1_SA_DQ<19>")
	)
	(arc
		(start 98.221038 -273.338544)
		(mid 98.200847 -273.378227)
		(end 98.18497 -273.419824)
		(width 0.088646)
		(layer "In11.Cu")
		(net "M_D_CPU1_SA_DQ<19>")
	)
	(arc
		(start 98.780346 -273.12874)
		(mid 98.596392 -273.078611)
		(end 98.411538 -273.125438)
		(width 0.088646)
		(layer "In11.Cu")
		(net "M_D_CPU1_SA_DQ<19>")
	)
	(arc
		(start 96.900746 -273.777456)
		(mid 96.713548 -273.827599)
		(end 96.52635 -273.777456)
		(width 0.088646)
		(layer "In11.Cu")
		(net "M_D_CPU1_SA_DQ<19>")
	)
	(arc
		(start 99.720146 -273.12874)
		(mid 99.536192 -273.078611)
		(end 99.351338 -273.125438)
		(width 0.088646)
		(layer "In11.Cu")
		(net "M_D_CPU1_SA_DQ<19>")
	)
	(arc
		(start 86.562946 -273.777456)
		(mid 86.375748 -273.827599)
		(end 86.18855 -273.777456)
		(width 0.088646)
		(layer "In11.Cu")
		(net "M_D_CPU1_SA_DQ<19>")
	)
	(arc
		(start 95.58655 -273.777456)
		(mid 95.309737 -273.701586)
		(end 95.031306 -273.77136)
		(width 0.088646)
		(layer "In11.Cu")
		(net "M_D_CPU1_SA_DQ<19>")
	)
	(arc
		(start 89.007696 -273.777456)
		(mid 88.724994 -273.70168)
		(end 88.442292 -273.777456)
		(width 0.088646)
		(layer "In11.Cu")
		(net "M_D_CPU1_SA_DQ<19>")
	)
	(arc
		(start 96.52635 -273.777456)
		(mid 96.252151 -273.701621)
		(end 95.975678 -273.76882)
		(width 0.088646)
		(layer "In11.Cu")
		(net "M_D_CPU1_SA_DQ<19>")
	)
	(arc
		(start 98.18497 -273.419824)
		(mid 98.160899 -273.47201)
		(end 98.12528 -273.517106)
		(width 0.088646)
		(layer "In11.Cu")
		(net "M_D_CPU1_SA_DQ<19>")
	)
	(segment
		(start 18.257774 -296.978578)
		(end 18.46961 -296.766742)
		(width 0.20066)
		(layer "F.Cu")
		(net "M_D_CPU1_SA_DQ<18>")
	)
	(segment
		(start 14.825218 -296.3418)
		(end 16.885158 -296.3418)
		(width 0.1016)
		(layer "F.Cu")
		(net "M_D_CPU1_SA_DQ<18>")
	)
	(segment
		(start 17.518126 -296.3418)
		(end 17.66189 -296.485564)
		(width 0.20066)
		(layer "F.Cu")
		(net "M_D_CPU1_SA_DQ<18>")
	)
	(segment
		(start 20.889214 -296.766742)
		(end 19.784314 -296.766742)
		(width 0.20066)
		(layer "F.Cu")
		(net "M_D_CPU1_SA_DQ<18>")
	)
	(segment
		(start 13.387578 -296.766742)
		(end 13.82268 -296.33164)
		(width 0.20066)
		(layer "F.Cu")
		(net "M_D_CPU1_SA_DQ<18>")
	)
	(segment
		(start 16.885158 -296.3418)
		(end 17.518126 -296.3418)
		(width 0.20066)
		(layer "F.Cu")
		(net "M_D_CPU1_SA_DQ<18>")
	)
	(segment
		(start 100.002594 -273.731228)
		(end 100.002594 -274.266914)
		(width 0.20066)
		(layer "F.Cu")
		(net "M_D_CPU1_SA_DQ<18>")
	)
	(segment
		(start 100.002848 -273.730974)
		(end 100.002594 -273.731228)
		(width 0.20066)
		(layer "F.Cu")
		(net "M_D_CPU1_SA_DQ<18>")
	)
	(segment
		(start 17.66189 -296.485564)
		(end 17.66189 -296.811192)
		(width 0.20066)
		(layer "F.Cu")
		(net "M_D_CPU1_SA_DQ<18>")
	)
	(segment
		(start 14.570202 -296.3418)
		(end 14.825218 -296.3418)
		(width 0.101854)
		(layer "F.Cu")
		(net "M_D_CPU1_SA_DQ<18>")
	)
	(segment
		(start 13.82268 -296.33164)
		(end 14.560042 -296.33164)
		(width 0.20066)
		(layer "F.Cu")
		(net "M_D_CPU1_SA_DQ<18>")
	)
	(segment
		(start 12.240514 -296.766742)
		(end 13.387578 -296.766742)
		(width 0.20066)
		(layer "F.Cu")
		(net "M_D_CPU1_SA_DQ<18>")
	)
	(segment
		(start 17.829276 -296.978578)
		(end 18.257774 -296.978578)
		(width 0.20066)
		(layer "F.Cu")
		(net "M_D_CPU1_SA_DQ<18>")
	)
	(segment
		(start 17.66189 -296.811192)
		(end 17.829276 -296.978578)
		(width 0.20066)
		(layer "F.Cu")
		(net "M_D_CPU1_SA_DQ<18>")
	)
	(segment
		(start 14.560042 -296.33164)
		(end 14.570202 -296.3418)
		(width 0.101854)
		(layer "F.Cu")
		(net "M_D_CPU1_SA_DQ<18>")
	)
	(segment
		(start 18.46961 -296.766742)
		(end 19.784314 -296.766742)
		(width 0.20066)
		(layer "F.Cu")
		(net "M_D_CPU1_SA_DQ<18>")
	)
	(segment
		(start 60.191142 -294.360346)
		(end 59.303666 -294.360346)
		(width 0.18288)
		(layer "In11.Cu")
		(net "M_D_CPU1_SA_DQ<18>")
	)
	(segment
		(start 62.94247 -294.17137)
		(end 62.74943 -293.97833)
		(width 0.18288)
		(layer "In11.Cu")
		(net "M_D_CPU1_SA_DQ<18>")
	)
	(segment
		(start 94.176596 -274.591272)
		(end 94.161864 -274.582636)
		(width 0.088646)
		(layer "In11.Cu")
		(net "M_D_CPU1_SA_DQ<18>")
	)
	(segment
		(start 84.664804 -277.052786)
		(end 83.908646 -277.808944)
		(width 0.088646)
		(layer "In11.Cu")
		(net "M_D_CPU1_SA_DQ<18>")
	)
	(segment
		(start 23.469854 -296.877486)
		(end 23.276814 -296.684446)
		(width 0.18288)
		(layer "In11.Cu")
		(net "M_D_CPU1_SA_DQ<18>")
	)
	(segment
		(start 45.680376 -299.547026)
		(end 44.302426 -299.547026)
		(width 0.18288)
		(layer "In11.Cu")
		(net "M_D_CPU1_SA_DQ<18>")
	)
	(segment
		(start 38.495224 -298.450762)
		(end 38.180264 -298.450762)
		(width 0.18288)
		(layer "In11.Cu")
		(net "M_D_CPU1_SA_DQ<18>")
	)
	(segment
		(start 91.35745 -274.591272)
		(end 91.347036 -274.585176)
		(width 0.088646)
		(layer "In11.Cu")
		(net "M_D_CPU1_SA_DQ<18>")
	)
	(segment
		(start 98.605594 -274.217384)
		(end 98.435922 -274.47367)
		(width 0.088646)
		(layer "In11.Cu")
		(net "M_D_CPU1_SA_DQ<18>")
	)
	(segment
		(start 68.548758 -290.95319)
		(end 66.511932 -292.990016)
		(width 0.18288)
		(layer "In11.Cu")
		(net "M_D_CPU1_SA_DQ<18>")
	)
	(segment
		(start 87.047324 -274.582636)
		(end 87.032592 -274.591272)
		(width 0.088646)
		(layer "In11.Cu")
		(net "M_D_CPU1_SA_DQ<18>")
	)
	(segment
		(start 49.36871 -299.611542)
		(end 48.911256 -299.801026)
		(width 0.18288)
		(layer "In11.Cu")
		(net "M_D_CPU1_SA_DQ<18>")
	)
	(segment
		(start 34.410142 -299.81271)
		(end 32.711898 -299.81271)
		(width 0.18288)
		(layer "In11.Cu")
		(net "M_D_CPU1_SA_DQ<18>")
	)
	(segment
		(start 25.039574 -297.360594)
		(end 23.662894 -297.360594)
		(width 0.18288)
		(layer "In11.Cu")
		(net "M_D_CPU1_SA_DQ<18>")
	)
	(segment
		(start 81.473548 -277.454868)
		(end 68.548758 -290.379658)
		(width 0.18288)
		(layer "In11.Cu")
		(net "M_D_CPU1_SA_DQ<18>")
	)
	(segment
		(start 91.74226 -274.585176)
		(end 91.731846 -274.591272)
		(width 0.088646)
		(layer "In11.Cu")
		(net "M_D_CPU1_SA_DQ<18>")
	)
	(segment
		(start 38.180264 -298.450762)
		(end 37.987224 -298.643802)
		(width 0.18288)
		(layer "In11.Cu")
		(net "M_D_CPU1_SA_DQ<18>")
	)
	(segment
		(start 83.287616 -277.454868)
		(end 83.18119 -277.454868)
		(width 0.088646)
		(layer "In11.Cu")
		(net "M_D_CPU1_SA_DQ<18>")
	)
	(segment
		(start 22.768814 -297.167554)
		(end 22.575774 -297.360594)
		(width 0.18288)
		(layer "In11.Cu")
		(net "M_D_CPU1_SA_DQ<18>")
	)
	(segment
		(start 63.45047 -293.696136)
		(end 63.45047 -293.97833)
		(width 0.18288)
		(layer "In11.Cu")
		(net "M_D_CPU1_SA_DQ<18>")
	)
	(segment
		(start 22.768814 -296.877486)
		(end 22.768814 -297.167554)
		(width 0.18288)
		(layer "In11.Cu")
		(net "M_D_CPU1_SA_DQ<18>")
	)
	(segment
		(start 42.799 -299.5676)
		(end 41.838626 -298.607226)
		(width 0.18288)
		(layer "In11.Cu")
		(net "M_D_CPU1_SA_DQ<18>")
	)
	(segment
		(start 51.643026 -299.013626)
		(end 51.521106 -298.891706)
		(width 0.18288)
		(layer "In11.Cu")
		(net "M_D_CPU1_SA_DQ<18>")
	)
	(segment
		(start 30.787594 -299.741844)
		(end 30.694376 -299.648626)
		(width 0.18288)
		(layer "In11.Cu")
		(net "M_D_CPU1_SA_DQ<18>")
	)
	(segment
		(start 23.469854 -297.167554)
		(end 23.469854 -296.877486)
		(width 0.18288)
		(layer "In11.Cu")
		(net "M_D_CPU1_SA_DQ<18>")
	)
	(segment
		(start 43.362626 -299.801026)
		(end 42.799 -299.5676)
		(width 0.18288)
		(layer "In11.Cu")
		(net "M_D_CPU1_SA_DQ<18>")
	)
	(segment
		(start 40.314626 -298.607226)
		(end 39.857426 -299.064426)
		(width 0.18288)
		(layer "In11.Cu")
		(net "M_D_CPU1_SA_DQ<18>")
	)
	(segment
		(start 58.849006 -294.815006)
		(end 58.117486 -294.815006)
		(width 0.18288)
		(layer "In11.Cu")
		(net "M_D_CPU1_SA_DQ<18>")
	)
	(segment
		(start 30.694376 -299.648626)
		(end 29.138626 -299.648626)
		(width 0.18288)
		(layer "In11.Cu")
		(net "M_D_CPU1_SA_DQ<18>")
	)
	(segment
		(start 23.276814 -296.684446)
		(end 22.961854 -296.684446)
		(width 0.18288)
		(layer "In11.Cu")
		(net "M_D_CPU1_SA_DQ<18>")
	)
	(segment
		(start 61.048392 -293.503096)
		(end 60.191142 -294.360346)
		(width 0.18288)
		(layer "In11.Cu")
		(net "M_D_CPU1_SA_DQ<18>")
	)
	(segment
		(start 63.25743 -294.17137)
		(end 62.94247 -294.17137)
		(width 0.18288)
		(layer "In11.Cu")
		(net "M_D_CPU1_SA_DQ<18>")
	)
	(segment
		(start 55.461916 -296.838624)
		(end 54.85257 -297.245786)
		(width 0.18288)
		(layer "In11.Cu")
		(net "M_D_CPU1_SA_DQ<18>")
	)
	(segment
		(start 56.540908 -296.391584)
		(end 55.461916 -296.838624)
		(width 0.18288)
		(layer "In11.Cu")
		(net "M_D_CPU1_SA_DQ<18>")
	)
	(segment
		(start 86.107524 -274.582636)
		(end 86.092792 -274.591272)
		(width 0.088646)
		(layer "In11.Cu")
		(net "M_D_CPU1_SA_DQ<18>")
	)
	(segment
		(start 22.575774 -297.360594)
		(end 22.062186 -297.360594)
		(width 0.18288)
		(layer "In11.Cu")
		(net "M_D_CPU1_SA_DQ<18>")
	)
	(segment
		(start 50.088546 -298.891706)
		(end 49.36871 -299.611542)
		(width 0.18288)
		(layer "In11.Cu")
		(net "M_D_CPU1_SA_DQ<18>")
	)
	(segment
		(start 37.987224 -298.871386)
		(end 37.794184 -299.064426)
		(width 0.18288)
		(layer "In11.Cu")
		(net "M_D_CPU1_SA_DQ<18>")
	)
	(segment
		(start 37.088826 -299.064426)
		(end 36.916106 -298.891706)
		(width 0.18288)
		(layer "In11.Cu")
		(net "M_D_CPU1_SA_DQ<18>")
	)
	(segment
		(start 22.062186 -297.360594)
		(end 21.468334 -296.766742)
		(width 0.18288)
		(layer "In11.Cu")
		(net "M_D_CPU1_SA_DQ<18>")
	)
	(segment
		(start 62.74943 -293.696136)
		(end 62.55639 -293.503096)
		(width 0.18288)
		(layer "In11.Cu")
		(net "M_D_CPU1_SA_DQ<18>")
	)
	(segment
		(start 100.002594 -274.266914)
		(end 99.705922 -274.266914)
		(width 0.088646)
		(layer "In11.Cu")
		(net "M_D_CPU1_SA_DQ<18>")
	)
	(segment
		(start 51.521106 -298.891706)
		(end 50.088546 -298.891706)
		(width 0.18288)
		(layer "In11.Cu")
		(net "M_D_CPU1_SA_DQ<18>")
	)
	(segment
		(start 29.138626 -299.648626)
		(end 28.986226 -299.801026)
		(width 0.18288)
		(layer "In11.Cu")
		(net "M_D_CPU1_SA_DQ<18>")
	)
	(segment
		(start 35.331146 -298.891706)
		(end 34.410142 -299.81271)
		(width 0.18288)
		(layer "In11.Cu")
		(net "M_D_CPU1_SA_DQ<18>")
	)
	(segment
		(start 83.908646 -277.808944)
		(end 83.482942 -277.808944)
		(width 0.088646)
		(layer "In11.Cu")
		(net "M_D_CPU1_SA_DQ<18>")
	)
	(segment
		(start 95.116396 -274.591272)
		(end 95.101664 -274.582636)
		(width 0.088646)
		(layer "In11.Cu")
		(net "M_D_CPU1_SA_DQ<18>")
	)
	(segment
		(start 53.753004 -297.701208)
		(end 52.440586 -299.013626)
		(width 0.18288)
		(layer "In11.Cu")
		(net "M_D_CPU1_SA_DQ<18>")
	)
	(segment
		(start 52.440586 -299.013626)
		(end 51.643026 -299.013626)
		(width 0.18288)
		(layer "In11.Cu")
		(net "M_D_CPU1_SA_DQ<18>")
	)
	(segment
		(start 83.482942 -277.808944)
		(end 83.376516 -277.702518)
		(width 0.088646)
		(layer "In11.Cu")
		(net "M_D_CPU1_SA_DQ<18>")
	)
	(segment
		(start 26.591006 -298.200826)
		(end 26.3017 -298.200826)
		(width 0.18288)
		(layer "In11.Cu")
		(net "M_D_CPU1_SA_DQ<18>")
	)
	(segment
		(start 38.688264 -298.871386)
		(end 38.688264 -298.643802)
		(width 0.18288)
		(layer "In11.Cu")
		(net "M_D_CPU1_SA_DQ<18>")
	)
	(segment
		(start 47.728632 -299.741844)
		(end 45.875194 -299.741844)
		(width 0.18288)
		(layer "In11.Cu")
		(net "M_D_CPU1_SA_DQ<18>")
	)
	(segment
		(start 28.36164 -299.801026)
		(end 28.070556 -299.680376)
		(width 0.18288)
		(layer "In11.Cu")
		(net "M_D_CPU1_SA_DQ<18>")
	)
	(segment
		(start 32.711898 -299.81271)
		(end 32.641032 -299.741844)
		(width 0.18288)
		(layer "In11.Cu")
		(net "M_D_CPU1_SA_DQ<18>")
	)
	(segment
		(start 58.117486 -294.815006)
		(end 56.540908 -296.391584)
		(width 0.18288)
		(layer "In11.Cu")
		(net "M_D_CPU1_SA_DQ<18>")
	)
	(segment
		(start 38.881304 -299.064426)
		(end 38.688264 -298.871386)
		(width 0.18288)
		(layer "In11.Cu")
		(net "M_D_CPU1_SA_DQ<18>")
	)
	(segment
		(start 62.55639 -293.503096)
		(end 61.048392 -293.503096)
		(width 0.18288)
		(layer "In11.Cu")
		(net "M_D_CPU1_SA_DQ<18>")
	)
	(segment
		(start 83.18119 -277.454868)
		(end 81.473548 -277.454868)
		(width 0.18288)
		(layer "In11.Cu")
		(net "M_D_CPU1_SA_DQ<18>")
	)
	(segment
		(start 23.662894 -297.360594)
		(end 23.469854 -297.167554)
		(width 0.18288)
		(layer "In11.Cu")
		(net "M_D_CPU1_SA_DQ<18>")
	)
	(segment
		(start 36.916106 -298.891706)
		(end 35.331146 -298.891706)
		(width 0.18288)
		(layer "In11.Cu")
		(net "M_D_CPU1_SA_DQ<18>")
	)
	(segment
		(start 63.45047 -293.97833)
		(end 63.25743 -294.17137)
		(width 0.18288)
		(layer "In11.Cu")
		(net "M_D_CPU1_SA_DQ<18>")
	)
	(segment
		(start 28.986226 -299.801026)
		(end 28.36164 -299.801026)
		(width 0.18288)
		(layer "In11.Cu")
		(net "M_D_CPU1_SA_DQ<18>")
	)
	(segment
		(start 97.935796 -274.591272)
		(end 97.921064 -274.582636)
		(width 0.088646)
		(layer "In11.Cu")
		(net "M_D_CPU1_SA_DQ<18>")
	)
	(segment
		(start 22.961854 -296.684446)
		(end 22.768814 -296.877486)
		(width 0.18288)
		(layer "In11.Cu")
		(net "M_D_CPU1_SA_DQ<18>")
	)
	(segment
		(start 93.236796 -274.591272)
		(end 93.222064 -274.582636)
		(width 0.088646)
		(layer "In11.Cu")
		(net "M_D_CPU1_SA_DQ<18>")
	)
	(segment
		(start 44.302426 -299.547026)
		(end 44.048426 -299.801026)
		(width 0.18288)
		(layer "In11.Cu")
		(net "M_D_CPU1_SA_DQ<18>")
	)
	(segment
		(start 26.3017 -298.200826)
		(end 25.618694 -297.939714)
		(width 0.18288)
		(layer "In11.Cu")
		(net "M_D_CPU1_SA_DQ<18>")
	)
	(segment
		(start 38.688264 -298.643802)
		(end 38.495224 -298.450762)
		(width 0.18288)
		(layer "In11.Cu")
		(net "M_D_CPU1_SA_DQ<18>")
	)
	(segment
		(start 62.74943 -293.97833)
		(end 62.74943 -293.696136)
		(width 0.18288)
		(layer "In11.Cu")
		(net "M_D_CPU1_SA_DQ<18>")
	)
	(segment
		(start 85.43544 -274.515326)
		(end 85.00364 -274.515326)
		(width 0.088646)
		(layer "In11.Cu")
		(net "M_D_CPU1_SA_DQ<18>")
	)
	(segment
		(start 21.468334 -296.766742)
		(end 20.889214 -296.766742)
		(width 0.18288)
		(layer "In11.Cu")
		(net "M_D_CPU1_SA_DQ<18>")
	)
	(segment
		(start 83.376516 -277.702518)
		(end 83.376516 -277.543768)
		(width 0.088646)
		(layer "In11.Cu")
		(net "M_D_CPU1_SA_DQ<18>")
	)
	(segment
		(start 44.048426 -299.801026)
		(end 43.362626 -299.801026)
		(width 0.18288)
		(layer "In11.Cu")
		(net "M_D_CPU1_SA_DQ<18>")
	)
	(segment
		(start 47.787814 -299.801026)
		(end 47.728632 -299.741844)
		(width 0.18288)
		(layer "In11.Cu")
		(net "M_D_CPU1_SA_DQ<18>")
	)
	(segment
		(start 48.911256 -299.801026)
		(end 47.787814 -299.801026)
		(width 0.18288)
		(layer "In11.Cu")
		(net "M_D_CPU1_SA_DQ<18>")
	)
	(segment
		(start 98.311716 -274.59051)
		(end 98.310192 -274.591272)
		(width 0.088646)
		(layer "In11.Cu")
		(net "M_D_CPU1_SA_DQ<18>")
	)
	(segment
		(start 28.070556 -299.680376)
		(end 26.591006 -298.200826)
		(width 0.18288)
		(layer "In11.Cu")
		(net "M_D_CPU1_SA_DQ<18>")
	)
	(segment
		(start 83.376516 -277.543768)
		(end 83.287616 -277.454868)
		(width 0.088646)
		(layer "In11.Cu")
		(net "M_D_CPU1_SA_DQ<18>")
	)
	(segment
		(start 96.995996 -274.591272)
		(end 96.981264 -274.582636)
		(width 0.088646)
		(layer "In11.Cu")
		(net "M_D_CPU1_SA_DQ<18>")
	)
	(segment
		(start 37.794184 -299.064426)
		(end 37.088826 -299.064426)
		(width 0.18288)
		(layer "In11.Cu")
		(net "M_D_CPU1_SA_DQ<18>")
	)
	(segment
		(start 32.641032 -299.741844)
		(end 30.787594 -299.741844)
		(width 0.18288)
		(layer "In11.Cu")
		(net "M_D_CPU1_SA_DQ<18>")
	)
	(segment
		(start 37.987224 -298.643802)
		(end 37.987224 -298.871386)
		(width 0.18288)
		(layer "In11.Cu")
		(net "M_D_CPU1_SA_DQ<18>")
	)
	(segment
		(start 45.875194 -299.741844)
		(end 45.680376 -299.547026)
		(width 0.18288)
		(layer "In11.Cu")
		(net "M_D_CPU1_SA_DQ<18>")
	)
	(segment
		(start 25.618694 -297.939714)
		(end 25.039574 -297.360594)
		(width 0.18288)
		(layer "In11.Cu")
		(net "M_D_CPU1_SA_DQ<18>")
	)
	(segment
		(start 84.664804 -274.854162)
		(end 84.664804 -277.052786)
		(width 0.088646)
		(layer "In11.Cu")
		(net "M_D_CPU1_SA_DQ<18>")
	)
	(segment
		(start 59.303666 -294.360346)
		(end 58.849006 -294.815006)
		(width 0.18288)
		(layer "In11.Cu")
		(net "M_D_CPU1_SA_DQ<18>")
	)
	(segment
		(start 96.056196 -274.591272)
		(end 96.041464 -274.582636)
		(width 0.088646)
		(layer "In11.Cu")
		(net "M_D_CPU1_SA_DQ<18>")
	)
	(segment
		(start 66.511932 -292.990016)
		(end 65.273174 -293.503096)
		(width 0.18288)
		(layer "In11.Cu")
		(net "M_D_CPU1_SA_DQ<18>")
	)
	(segment
		(start 39.857426 -299.064426)
		(end 38.881304 -299.064426)
		(width 0.18288)
		(layer "In11.Cu")
		(net "M_D_CPU1_SA_DQ<18>")
	)
	(segment
		(start 54.85257 -297.245786)
		(end 53.753004 -297.701208)
		(width 0.18288)
		(layer "In11.Cu")
		(net "M_D_CPU1_SA_DQ<18>")
	)
	(segment
		(start 41.838626 -298.607226)
		(end 40.314626 -298.607226)
		(width 0.18288)
		(layer "In11.Cu")
		(net "M_D_CPU1_SA_DQ<18>")
	)
	(segment
		(start 68.548758 -290.379658)
		(end 68.548758 -290.95319)
		(width 0.18288)
		(layer "In11.Cu")
		(net "M_D_CPU1_SA_DQ<18>")
	)
	(segment
		(start 63.64351 -293.503096)
		(end 63.45047 -293.696136)
		(width 0.18288)
		(layer "In11.Cu")
		(net "M_D_CPU1_SA_DQ<18>")
	)
	(segment
		(start 85.00364 -274.515326)
		(end 84.664804 -274.854162)
		(width 0.088646)
		(layer "In11.Cu")
		(net "M_D_CPU1_SA_DQ<18>")
	)
	(segment
		(start 65.273174 -293.503096)
		(end 63.64351 -293.503096)
		(width 0.18288)
		(layer "In11.Cu")
		(net "M_D_CPU1_SA_DQ<18>")
	)
	(arc
		(start 99.705922 -274.266914)
		(mid 99.522274 -274.217239)
		(end 99.388422 -274.082002)
		(width 0.088646)
		(layer "In11.Cu")
		(net "M_D_CPU1_SA_DQ<18>")
	)
	(arc
		(start 96.430592 -274.591272)
		(mid 96.243394 -274.641415)
		(end 96.056196 -274.591272)
		(width 0.088646)
		(layer "In11.Cu")
		(net "M_D_CPU1_SA_DQ<18>")
	)
	(arc
		(start 98.786442 -274.014184)
		(mid 98.735734 -274.068478)
		(end 98.683826 -274.121626)
		(width 0.088646)
		(layer "In11.Cu")
		(net "M_D_CPU1_SA_DQ<18>")
	)
	(arc
		(start 97.921064 -274.582636)
		(mid 97.644589 -274.515316)
		(end 97.370392 -274.591272)
		(width 0.088646)
		(layer "In11.Cu")
		(net "M_D_CPU1_SA_DQ<18>")
	)
	(arc
		(start 96.041464 -274.582636)
		(mid 95.764989 -274.515316)
		(end 95.490792 -274.591272)
		(width 0.088646)
		(layer "In11.Cu")
		(net "M_D_CPU1_SA_DQ<18>")
	)
	(arc
		(start 85.718396 -274.591272)
		(mid 85.581924 -274.534649)
		(end 85.43544 -274.515326)
		(width 0.088646)
		(layer "In11.Cu")
		(net "M_D_CPU1_SA_DQ<18>")
	)
	(arc
		(start 90.791792 -274.591272)
		(mid 90.604594 -274.641415)
		(end 90.417396 -274.591272)
		(width 0.088646)
		(layer "In11.Cu")
		(net "M_D_CPU1_SA_DQ<18>")
	)
	(arc
		(start 95.101664 -274.582636)
		(mid 94.825189 -274.515316)
		(end 94.550992 -274.591272)
		(width 0.088646)
		(layer "In11.Cu")
		(net "M_D_CPU1_SA_DQ<18>")
	)
	(arc
		(start 96.981264 -274.582636)
		(mid 96.704789 -274.515316)
		(end 96.430592 -274.591272)
		(width 0.088646)
		(layer "In11.Cu")
		(net "M_D_CPU1_SA_DQ<18>")
	)
	(arc
		(start 88.537796 -274.591272)
		(mid 88.255094 -274.515496)
		(end 87.972392 -274.591272)
		(width 0.088646)
		(layer "In11.Cu")
		(net "M_D_CPU1_SA_DQ<18>")
	)
	(arc
		(start 88.912192 -274.591272)
		(mid 88.724994 -274.641415)
		(end 88.537796 -274.591272)
		(width 0.088646)
		(layer "In11.Cu")
		(net "M_D_CPU1_SA_DQ<18>")
	)
	(arc
		(start 95.490792 -274.591272)
		(mid 95.303594 -274.641415)
		(end 95.116396 -274.591272)
		(width 0.088646)
		(layer "In11.Cu")
		(net "M_D_CPU1_SA_DQ<18>")
	)
	(arc
		(start 97.370392 -274.591272)
		(mid 97.183194 -274.641415)
		(end 96.995996 -274.591272)
		(width 0.088646)
		(layer "In11.Cu")
		(net "M_D_CPU1_SA_DQ<18>")
	)
	(arc
		(start 98.435922 -274.47367)
		(mid 98.380618 -274.539317)
		(end 98.311716 -274.59051)
		(width 0.088646)
		(layer "In11.Cu")
		(net "M_D_CPU1_SA_DQ<18>")
	)
	(arc
		(start 94.550992 -274.591272)
		(mid 94.363794 -274.641415)
		(end 94.176596 -274.591272)
		(width 0.088646)
		(layer "In11.Cu")
		(net "M_D_CPU1_SA_DQ<18>")
	)
	(arc
		(start 87.032592 -274.591272)
		(mid 86.845394 -274.641415)
		(end 86.658196 -274.591272)
		(width 0.088646)
		(layer "In11.Cu")
		(net "M_D_CPU1_SA_DQ<18>")
	)
	(arc
		(start 92.296996 -274.591272)
		(mid 92.020437 -274.515529)
		(end 91.74226 -274.585176)
		(width 0.088646)
		(layer "In11.Cu")
		(net "M_D_CPU1_SA_DQ<18>")
	)
	(arc
		(start 91.347036 -274.585176)
		(mid 91.068604 -274.51533)
		(end 90.791792 -274.591272)
		(width 0.088646)
		(layer "In11.Cu")
		(net "M_D_CPU1_SA_DQ<18>")
	)
	(arc
		(start 99.388422 -274.082002)
		(mid 99.104708 -273.894799)
		(end 98.786442 -274.014184)
		(width 0.088646)
		(layer "In11.Cu")
		(net "M_D_CPU1_SA_DQ<18>")
	)
	(arc
		(start 89.851992 -274.591272)
		(mid 89.664794 -274.641415)
		(end 89.477596 -274.591272)
		(width 0.088646)
		(layer "In11.Cu")
		(net "M_D_CPU1_SA_DQ<18>")
	)
	(arc
		(start 91.731846 -274.591272)
		(mid 91.544648 -274.641415)
		(end 91.35745 -274.591272)
		(width 0.088646)
		(layer "In11.Cu")
		(net "M_D_CPU1_SA_DQ<18>")
	)
	(arc
		(start 98.683826 -274.121626)
		(mid 98.642304 -274.167539)
		(end 98.605594 -274.217384)
		(width 0.088646)
		(layer "In11.Cu")
		(net "M_D_CPU1_SA_DQ<18>")
	)
	(arc
		(start 87.597996 -274.591272)
		(mid 87.323797 -274.515437)
		(end 87.047324 -274.582636)
		(width 0.088646)
		(layer "In11.Cu")
		(net "M_D_CPU1_SA_DQ<18>")
	)
	(arc
		(start 86.092792 -274.591272)
		(mid 85.905594 -274.641415)
		(end 85.718396 -274.591272)
		(width 0.088646)
		(layer "In11.Cu")
		(net "M_D_CPU1_SA_DQ<18>")
	)
	(arc
		(start 90.417396 -274.591272)
		(mid 90.134694 -274.515496)
		(end 89.851992 -274.591272)
		(width 0.088646)
		(layer "In11.Cu")
		(net "M_D_CPU1_SA_DQ<18>")
	)
	(arc
		(start 98.310192 -274.591272)
		(mid 98.122994 -274.641415)
		(end 97.935796 -274.591272)
		(width 0.088646)
		(layer "In11.Cu")
		(net "M_D_CPU1_SA_DQ<18>")
	)
	(arc
		(start 93.222064 -274.582636)
		(mid 92.945589 -274.515316)
		(end 92.671392 -274.591272)
		(width 0.088646)
		(layer "In11.Cu")
		(net "M_D_CPU1_SA_DQ<18>")
	)
	(arc
		(start 92.671392 -274.591272)
		(mid 92.484194 -274.641415)
		(end 92.296996 -274.591272)
		(width 0.088646)
		(layer "In11.Cu")
		(net "M_D_CPU1_SA_DQ<18>")
	)
	(arc
		(start 86.658196 -274.591272)
		(mid 86.383997 -274.515437)
		(end 86.107524 -274.582636)
		(width 0.088646)
		(layer "In11.Cu")
		(net "M_D_CPU1_SA_DQ<18>")
	)
	(arc
		(start 94.161864 -274.582636)
		(mid 93.885389 -274.515316)
		(end 93.611192 -274.591272)
		(width 0.088646)
		(layer "In11.Cu")
		(net "M_D_CPU1_SA_DQ<18>")
	)
	(arc
		(start 89.477596 -274.591272)
		(mid 89.194894 -274.515496)
		(end 88.912192 -274.591272)
		(width 0.088646)
		(layer "In11.Cu")
		(net "M_D_CPU1_SA_DQ<18>")
	)
	(arc
		(start 93.611192 -274.591272)
		(mid 93.423994 -274.641415)
		(end 93.236796 -274.591272)
		(width 0.088646)
		(layer "In11.Cu")
		(net "M_D_CPU1_SA_DQ<18>")
	)
	(arc
		(start 87.972392 -274.591272)
		(mid 87.785194 -274.641415)
		(end 87.597996 -274.591272)
		(width 0.088646)
		(layer "In11.Cu")
		(net "M_D_CPU1_SA_DQ<18>")
	)
	(segment
		(start 10.19048 -296.127932)
		(end 10.344912 -295.9735)
		(width 0.20066)
		(layer "F.Cu")
		(net "M_D_CPU1_SA_DQ<17>")
	)
	(segment
		(start 10.507472 -295.482772)
		(end 11.11631 -295.482772)
		(width 0.20066)
		(layer "F.Cu")
		(net "M_D_CPU1_SA_DQ<17>")
	)
	(segment
		(start 8.140446 -295.916604)
		(end 9.474708 -295.916604)
		(width 0.20066)
		(layer "F.Cu")
		(net "M_D_CPU1_SA_DQ<17>")
	)
	(segment
		(start 14.04493 -295.916604)
		(end 15.684246 -295.916604)
		(width 0.20066)
		(layer "F.Cu")
		(net "M_D_CPU1_SA_DQ<17>")
	)
	(segment
		(start 10.344912 -295.9735)
		(end 10.344912 -295.645332)
		(width 0.20066)
		(layer "F.Cu")
		(net "M_D_CPU1_SA_DQ<17>")
	)
	(segment
		(start 9.686036 -296.127932)
		(end 10.19048 -296.127932)
		(width 0.20066)
		(layer "F.Cu")
		(net "M_D_CPU1_SA_DQ<17>")
	)
	(segment
		(start 15.684246 -295.916604)
		(end 16.789146 -295.916604)
		(width 0.20066)
		(layer "F.Cu")
		(net "M_D_CPU1_SA_DQ<17>")
	)
	(segment
		(start 11.11631 -295.482772)
		(end 11.1252 -295.491662)
		(width 0.1016)
		(layer "F.Cu")
		(net "M_D_CPU1_SA_DQ<17>")
	)
	(segment
		(start 11.1252 -295.491662)
		(end 13.110718 -295.491662)
		(width 0.1016)
		(layer "F.Cu")
		(net "M_D_CPU1_SA_DQ<17>")
	)
	(segment
		(start 9.474708 -295.916604)
		(end 9.686036 -296.127932)
		(width 0.20066)
		(layer "F.Cu")
		(net "M_D_CPU1_SA_DQ<17>")
	)
	(segment
		(start 13.619988 -295.491662)
		(end 14.04493 -295.916604)
		(width 0.20066)
		(layer "F.Cu")
		(net "M_D_CPU1_SA_DQ<17>")
	)
	(segment
		(start 13.110718 -295.491662)
		(end 13.441426 -295.491662)
		(width 0.101854)
		(layer "F.Cu")
		(net "M_D_CPU1_SA_DQ<17>")
	)
	(segment
		(start 13.441426 -295.491662)
		(end 13.619988 -295.491662)
		(width 0.20066)
		(layer "F.Cu")
		(net "M_D_CPU1_SA_DQ<17>")
	)
	(segment
		(start 10.344912 -295.645332)
		(end 10.507472 -295.482772)
		(width 0.20066)
		(layer "F.Cu")
		(net "M_D_CPU1_SA_DQ<17>")
	)
	(arc
		(start 98.592894 -272.917158)
		(mid 98.592957 -273.185128)
		(end 98.593148 -273.453098)
		(width 0.20066)
		(layer "F.Cu")
		(net "M_D_CPU1_SA_DQ<17>")
	)
	(segment
		(start 94.176596 -273.942556)
		(end 94.161864 -273.951192)
		(width 0.088646)
		(layer "In11.Cu")
		(net "M_D_CPU1_SA_DQ<17>")
	)
	(segment
		(start 44.378626 -299.013626)
		(end 44.08932 -298.72432)
		(width 0.18288)
		(layer "In11.Cu")
		(net "M_D_CPU1_SA_DQ<17>")
	)
	(segment
		(start 32.960056 -298.892214)
		(end 30.555692 -298.892214)
		(width 0.18288)
		(layer "In11.Cu")
		(net "M_D_CPU1_SA_DQ<17>")
	)
	(segment
		(start 86.658196 -273.942556)
		(end 86.643464 -273.951192)
		(width 0.088646)
		(layer "In11.Cu")
		(net "M_D_CPU1_SA_DQ<17>")
	)
	(segment
		(start 68.040758 -290.742624)
		(end 66.40322 -292.380162)
		(width 0.18288)
		(layer "In11.Cu")
		(net "M_D_CPU1_SA_DQ<17>")
	)
	(segment
		(start 66.13652 -292.490652)
		(end 65.62344 -292.278054)
		(width 0.18288)
		(layer "In11.Cu")
		(net "M_D_CPU1_SA_DQ<17>")
	)
	(segment
		(start 65.62344 -292.278054)
		(end 65.48247 -291.937948)
		(width 0.18288)
		(layer "In11.Cu")
		(net "M_D_CPU1_SA_DQ<17>")
	)
	(segment
		(start 36.979606 -297.884342)
		(end 36.821872 -298.042076)
		(width 0.18288)
		(layer "In11.Cu")
		(net "M_D_CPU1_SA_DQ<17>")
	)
	(segment
		(start 65.48247 -291.937948)
		(end 65.273428 -291.851334)
		(width 0.18288)
		(layer "In11.Cu")
		(net "M_D_CPU1_SA_DQ<17>")
	)
	(segment
		(start 19.926046 -295.785794)
		(end 19.633438 -295.785794)
		(width 0.18288)
		(layer "In11.Cu")
		(net "M_D_CPU1_SA_DQ<17>")
	)
	(segment
		(start 98.014028 -273.897344)
		(end 97.935796 -273.942556)
		(width 0.088646)
		(layer "In11.Cu")
		(net "M_D_CPU1_SA_DQ<17>")
	)
	(segment
		(start 96.056196 -273.942556)
		(end 96.041464 -273.951192)
		(width 0.088646)
		(layer "In11.Cu")
		(net "M_D_CPU1_SA_DQ<17>")
	)
	(segment
		(start 55.097426 -296.219626)
		(end 54.411626 -296.219626)
		(width 0.18288)
		(layer "In11.Cu")
		(net "M_D_CPU1_SA_DQ<17>")
	)
	(segment
		(start 19.633438 -295.785794)
		(end 18.866612 -296.55262)
		(width 0.18288)
		(layer "In11.Cu")
		(net "M_D_CPU1_SA_DQ<17>")
	)
	(segment
		(start 58.66638 -293.720266)
		(end 58.277506 -293.881302)
		(width 0.18288)
		(layer "In11.Cu")
		(net "M_D_CPU1_SA_DQ<17>")
	)
	(segment
		(start 65.273428 -291.851334)
		(end 64.951864 -291.984684)
		(width 0.18288)
		(layer "In11.Cu")
		(net "M_D_CPU1_SA_DQ<17>")
	)
	(segment
		(start 25.277826 -296.905426)
		(end 24.544528 -296.172128)
		(width 0.18288)
		(layer "In11.Cu")
		(net "M_D_CPU1_SA_DQ<17>")
	)
	(segment
		(start 34.472626 -298.632626)
		(end 33.219644 -298.632626)
		(width 0.18288)
		(layer "In11.Cu")
		(net "M_D_CPU1_SA_DQ<17>")
	)
	(segment
		(start 29.05125 -298.67225)
		(end 27.983942 -298.67225)
		(width 0.18288)
		(layer "In11.Cu")
		(net "M_D_CPU1_SA_DQ<17>")
	)
	(segment
		(start 50.150776 -298.042076)
		(end 49.484026 -298.708826)
		(width 0.18288)
		(layer "In11.Cu")
		(net "M_D_CPU1_SA_DQ<17>")
	)
	(segment
		(start 81.262982 -276.946868)
		(end 68.040758 -290.169092)
		(width 0.18288)
		(layer "In11.Cu")
		(net "M_D_CPU1_SA_DQ<17>")
	)
	(segment
		(start 96.995996 -273.942556)
		(end 96.981264 -273.951192)
		(width 0.088646)
		(layer "In11.Cu")
		(net "M_D_CPU1_SA_DQ<17>")
	)
	(segment
		(start 36.821872 -298.042076)
		(end 35.063176 -298.042076)
		(width 0.18288)
		(layer "In11.Cu")
		(net "M_D_CPU1_SA_DQ<17>")
	)
	(segment
		(start 55.961026 -295.356026)
		(end 55.097426 -296.219626)
		(width 0.18288)
		(layer "In11.Cu")
		(net "M_D_CPU1_SA_DQ<17>")
	)
	(segment
		(start 85.640418 -274.001738)
		(end 85.578188 -274.063968)
		(width 0.088646)
		(layer "In11.Cu")
		(net "M_D_CPU1_SA_DQ<17>")
	)
	(segment
		(start 84.454746 -274.759674)
		(end 84.454746 -276.153118)
		(width 0.088646)
		(layer "In11.Cu")
		(net "M_D_CPU1_SA_DQ<17>")
	)
	(segment
		(start 65.00622 -292.534086)
		(end 64.91986 -292.742874)
		(width 0.18288)
		(layer "In11.Cu")
		(net "M_D_CPU1_SA_DQ<17>")
	)
	(segment
		(start 26.217118 -296.905426)
		(end 25.277826 -296.905426)
		(width 0.18288)
		(layer "In11.Cu")
		(net "M_D_CPU1_SA_DQ<17>")
	)
	(segment
		(start 58.277506 -293.881302)
		(end 56.802782 -295.356026)
		(width 0.18288)
		(layer "In11.Cu")
		(net "M_D_CPU1_SA_DQ<17>")
	)
	(segment
		(start 60.790582 -292.985698)
		(end 60.056014 -293.720266)
		(width 0.18288)
		(layer "In11.Cu")
		(net "M_D_CPU1_SA_DQ<17>")
	)
	(segment
		(start 16.7894 -295.916858)
		(end 16.789146 -295.916604)
		(width 0.18288)
		(layer "In11.Cu")
		(net "M_D_CPU1_SA_DQ<17>")
	)
	(segment
		(start 27.983942 -298.67225)
		(end 26.217118 -296.905426)
		(width 0.18288)
		(layer "In11.Cu")
		(net "M_D_CPU1_SA_DQ<17>")
	)
	(segment
		(start 42.245026 -298.117006)
		(end 42.212006 -298.117006)
		(width 0.18288)
		(layer "In11.Cu")
		(net "M_D_CPU1_SA_DQ<17>")
	)
	(segment
		(start 84.454746 -276.153118)
		(end 83.660996 -276.946868)
		(width 0.088646)
		(layer "In11.Cu")
		(net "M_D_CPU1_SA_DQ<17>")
	)
	(segment
		(start 51.693826 -297.896026)
		(end 51.547776 -298.042076)
		(width 0.18288)
		(layer "In11.Cu")
		(net "M_D_CPU1_SA_DQ<17>")
	)
	(segment
		(start 92.296996 -273.942556)
		(end 92.286582 -273.948652)
		(width 0.088646)
		(layer "In11.Cu")
		(net "M_D_CPU1_SA_DQ<17>")
	)
	(segment
		(start 18.866612 -296.55262)
		(end 17.959832 -296.55262)
		(width 0.18288)
		(layer "In11.Cu")
		(net "M_D_CPU1_SA_DQ<17>")
	)
	(segment
		(start 40.404542 -297.884342)
		(end 36.979606 -297.884342)
		(width 0.18288)
		(layer "In11.Cu")
		(net "M_D_CPU1_SA_DQ<17>")
	)
	(segment
		(start 17.32407 -295.916858)
		(end 16.7894 -295.916858)
		(width 0.18288)
		(layer "In11.Cu")
		(net "M_D_CPU1_SA_DQ<17>")
	)
	(segment
		(start 98.593148 -273.453098)
		(end 98.014028 -273.897344)
		(width 0.088646)
		(layer "In11.Cu")
		(net "M_D_CPU1_SA_DQ<17>")
	)
	(segment
		(start 48.231044 -298.708826)
		(end 48.047656 -298.892214)
		(width 0.18288)
		(layer "In11.Cu")
		(net "M_D_CPU1_SA_DQ<17>")
	)
	(segment
		(start 20.260564 -296.341292)
		(end 20.086066 -296.166794)
		(width 0.18288)
		(layer "In11.Cu")
		(net "M_D_CPU1_SA_DQ<17>")
	)
	(segment
		(start 93.236796 -273.942556)
		(end 93.222064 -273.951192)
		(width 0.088646)
		(layer "In11.Cu")
		(net "M_D_CPU1_SA_DQ<17>")
	)
	(segment
		(start 42.194226 -298.099226)
		(end 40.619426 -298.099226)
		(width 0.18288)
		(layer "In11.Cu")
		(net "M_D_CPU1_SA_DQ<17>")
	)
	(segment
		(start 33.219644 -298.632626)
		(end 32.960056 -298.892214)
		(width 0.18288)
		(layer "In11.Cu")
		(net "M_D_CPU1_SA_DQ<17>")
	)
	(segment
		(start 85.150452 -274.063968)
		(end 84.454746 -274.759674)
		(width 0.088646)
		(layer "In11.Cu")
		(net "M_D_CPU1_SA_DQ<17>")
	)
	(segment
		(start 54.411626 -296.219626)
		(end 52.735226 -297.896026)
		(width 0.18288)
		(layer "In11.Cu")
		(net "M_D_CPU1_SA_DQ<17>")
	)
	(segment
		(start 64.951864 -291.984684)
		(end 64.86525 -292.193726)
		(width 0.18288)
		(layer "In11.Cu")
		(net "M_D_CPU1_SA_DQ<17>")
	)
	(segment
		(start 29.443426 -299.064426)
		(end 29.05125 -298.67225)
		(width 0.18288)
		(layer "In11.Cu")
		(net "M_D_CPU1_SA_DQ<17>")
	)
	(segment
		(start 64.91986 -292.742874)
		(end 64.333374 -292.985698)
		(width 0.18288)
		(layer "In11.Cu")
		(net "M_D_CPU1_SA_DQ<17>")
	)
	(segment
		(start 64.86525 -292.193726)
		(end 65.00622 -292.534086)
		(width 0.18288)
		(layer "In11.Cu")
		(net "M_D_CPU1_SA_DQ<17>")
	)
	(segment
		(start 60.056014 -293.720266)
		(end 58.66638 -293.720266)
		(width 0.18288)
		(layer "In11.Cu")
		(net "M_D_CPU1_SA_DQ<17>")
	)
	(segment
		(start 21.749512 -296.172128)
		(end 21.580348 -296.341292)
		(width 0.18288)
		(layer "In11.Cu")
		(net "M_D_CPU1_SA_DQ<17>")
	)
	(segment
		(start 44.08932 -298.72432)
		(end 42.85234 -298.72432)
		(width 0.18288)
		(layer "In11.Cu")
		(net "M_D_CPU1_SA_DQ<17>")
	)
	(segment
		(start 45.643038 -298.892214)
		(end 45.521626 -299.013626)
		(width 0.18288)
		(layer "In11.Cu")
		(net "M_D_CPU1_SA_DQ<17>")
	)
	(segment
		(start 40.619426 -298.099226)
		(end 40.404542 -297.884342)
		(width 0.18288)
		(layer "In11.Cu")
		(net "M_D_CPU1_SA_DQ<17>")
	)
	(segment
		(start 30.555692 -298.892214)
		(end 30.38348 -299.064426)
		(width 0.18288)
		(layer "In11.Cu")
		(net "M_D_CPU1_SA_DQ<17>")
	)
	(segment
		(start 51.547776 -298.042076)
		(end 50.150776 -298.042076)
		(width 0.18288)
		(layer "In11.Cu")
		(net "M_D_CPU1_SA_DQ<17>")
	)
	(segment
		(start 42.85234 -298.72432)
		(end 42.245026 -298.117006)
		(width 0.18288)
		(layer "In11.Cu")
		(net "M_D_CPU1_SA_DQ<17>")
	)
	(segment
		(start 85.578188 -274.063968)
		(end 85.150452 -274.063968)
		(width 0.088646)
		(layer "In11.Cu")
		(net "M_D_CPU1_SA_DQ<17>")
	)
	(segment
		(start 30.38348 -299.064426)
		(end 29.443426 -299.064426)
		(width 0.18288)
		(layer "In11.Cu")
		(net "M_D_CPU1_SA_DQ<17>")
	)
	(segment
		(start 24.544528 -296.172128)
		(end 21.749512 -296.172128)
		(width 0.18288)
		(layer "In11.Cu")
		(net "M_D_CPU1_SA_DQ<17>")
	)
	(segment
		(start 20.086066 -296.166794)
		(end 20.086066 -295.945814)
		(width 0.18288)
		(layer "In11.Cu")
		(net "M_D_CPU1_SA_DQ<17>")
	)
	(segment
		(start 52.735226 -297.896026)
		(end 51.693826 -297.896026)
		(width 0.18288)
		(layer "In11.Cu")
		(net "M_D_CPU1_SA_DQ<17>")
	)
	(segment
		(start 66.40322 -292.380162)
		(end 66.13652 -292.490652)
		(width 0.18288)
		(layer "In11.Cu")
		(net "M_D_CPU1_SA_DQ<17>")
	)
	(segment
		(start 45.521626 -299.013626)
		(end 44.378626 -299.013626)
		(width 0.18288)
		(layer "In11.Cu")
		(net "M_D_CPU1_SA_DQ<17>")
	)
	(segment
		(start 42.212006 -298.117006)
		(end 42.194226 -298.099226)
		(width 0.18288)
		(layer "In11.Cu")
		(net "M_D_CPU1_SA_DQ<17>")
	)
	(segment
		(start 20.086066 -295.945814)
		(end 19.926046 -295.785794)
		(width 0.18288)
		(layer "In11.Cu")
		(net "M_D_CPU1_SA_DQ<17>")
	)
	(segment
		(start 35.063176 -298.042076)
		(end 34.472626 -298.632626)
		(width 0.18288)
		(layer "In11.Cu")
		(net "M_D_CPU1_SA_DQ<17>")
	)
	(segment
		(start 17.959832 -296.55262)
		(end 17.32407 -295.916858)
		(width 0.18288)
		(layer "In11.Cu")
		(net "M_D_CPU1_SA_DQ<17>")
	)
	(segment
		(start 56.802782 -295.356026)
		(end 55.961026 -295.356026)
		(width 0.18288)
		(layer "In11.Cu")
		(net "M_D_CPU1_SA_DQ<17>")
	)
	(segment
		(start 21.580348 -296.341292)
		(end 20.260564 -296.341292)
		(width 0.18288)
		(layer "In11.Cu")
		(net "M_D_CPU1_SA_DQ<17>")
	)
	(segment
		(start 83.660996 -276.946868)
		(end 83.471258 -276.946868)
		(width 0.088646)
		(layer "In11.Cu")
		(net "M_D_CPU1_SA_DQ<17>")
	)
	(segment
		(start 91.35745 -273.942556)
		(end 91.347036 -273.948652)
		(width 0.088646)
		(layer "In11.Cu")
		(net "M_D_CPU1_SA_DQ<17>")
	)
	(segment
		(start 68.040758 -290.169092)
		(end 68.040758 -290.742624)
		(width 0.18288)
		(layer "In11.Cu")
		(net "M_D_CPU1_SA_DQ<17>")
	)
	(segment
		(start 64.333374 -292.985698)
		(end 60.790582 -292.985698)
		(width 0.18288)
		(layer "In11.Cu")
		(net "M_D_CPU1_SA_DQ<17>")
	)
	(segment
		(start 49.484026 -298.708826)
		(end 48.231044 -298.708826)
		(width 0.18288)
		(layer "In11.Cu")
		(net "M_D_CPU1_SA_DQ<17>")
	)
	(segment
		(start 97.935796 -273.942556)
		(end 97.921064 -273.951192)
		(width 0.088646)
		(layer "In11.Cu")
		(net "M_D_CPU1_SA_DQ<17>")
	)
	(segment
		(start 83.471258 -276.946868)
		(end 81.262982 -276.946868)
		(width 0.18288)
		(layer "In11.Cu")
		(net "M_D_CPU1_SA_DQ<17>")
	)
	(segment
		(start 48.047656 -298.892214)
		(end 45.643038 -298.892214)
		(width 0.18288)
		(layer "In11.Cu")
		(net "M_D_CPU1_SA_DQ<17>")
	)
	(arc
		(start 87.972392 -273.942556)
		(mid 87.785194 -273.892413)
		(end 87.597996 -273.942556)
		(width 0.088646)
		(layer "In11.Cu")
		(net "M_D_CPU1_SA_DQ<17>")
	)
	(arc
		(start 95.116396 -273.942556)
		(mid 94.833694 -274.018332)
		(end 94.550992 -273.942556)
		(width 0.088646)
		(layer "In11.Cu")
		(net "M_D_CPU1_SA_DQ<17>")
	)
	(arc
		(start 86.643464 -273.951192)
		(mid 86.366989 -274.018512)
		(end 86.092792 -273.942556)
		(width 0.088646)
		(layer "In11.Cu")
		(net "M_D_CPU1_SA_DQ<17>")
	)
	(arc
		(start 88.537796 -273.942556)
		(mid 88.255094 -274.018332)
		(end 87.972392 -273.942556)
		(width 0.088646)
		(layer "In11.Cu")
		(net "M_D_CPU1_SA_DQ<17>")
	)
	(arc
		(start 94.550992 -273.942556)
		(mid 94.363794 -273.892413)
		(end 94.176596 -273.942556)
		(width 0.088646)
		(layer "In11.Cu")
		(net "M_D_CPU1_SA_DQ<17>")
	)
	(arc
		(start 85.718396 -273.942556)
		(mid 85.677466 -273.969589)
		(end 85.640418 -274.001738)
		(width 0.088646)
		(layer "In11.Cu")
		(net "M_D_CPU1_SA_DQ<17>")
	)
	(arc
		(start 89.851992 -273.942556)
		(mid 89.664794 -273.892413)
		(end 89.477596 -273.942556)
		(width 0.088646)
		(layer "In11.Cu")
		(net "M_D_CPU1_SA_DQ<17>")
	)
	(arc
		(start 89.477596 -273.942556)
		(mid 89.194894 -274.018332)
		(end 88.912192 -273.942556)
		(width 0.088646)
		(layer "In11.Cu")
		(net "M_D_CPU1_SA_DQ<17>")
	)
	(arc
		(start 88.912192 -273.942556)
		(mid 88.724994 -273.892413)
		(end 88.537796 -273.942556)
		(width 0.088646)
		(layer "In11.Cu")
		(net "M_D_CPU1_SA_DQ<17>")
	)
	(arc
		(start 96.430592 -273.942556)
		(mid 96.243394 -273.892413)
		(end 96.056196 -273.942556)
		(width 0.088646)
		(layer "In11.Cu")
		(net "M_D_CPU1_SA_DQ<17>")
	)
	(arc
		(start 86.092792 -273.942556)
		(mid 85.905594 -273.892413)
		(end 85.718396 -273.942556)
		(width 0.088646)
		(layer "In11.Cu")
		(net "M_D_CPU1_SA_DQ<17>")
	)
	(arc
		(start 87.597996 -273.942556)
		(mid 87.315294 -274.018332)
		(end 87.032592 -273.942556)
		(width 0.088646)
		(layer "In11.Cu")
		(net "M_D_CPU1_SA_DQ<17>")
	)
	(arc
		(start 92.671392 -273.942556)
		(mid 92.484194 -273.892413)
		(end 92.296996 -273.942556)
		(width 0.088646)
		(layer "In11.Cu")
		(net "M_D_CPU1_SA_DQ<17>")
	)
	(arc
		(start 91.347036 -273.948652)
		(mid 91.068604 -274.018498)
		(end 90.791792 -273.942556)
		(width 0.088646)
		(layer "In11.Cu")
		(net "M_D_CPU1_SA_DQ<17>")
	)
	(arc
		(start 93.611192 -273.942556)
		(mid 93.423994 -273.892413)
		(end 93.236796 -273.942556)
		(width 0.088646)
		(layer "In11.Cu")
		(net "M_D_CPU1_SA_DQ<17>")
	)
	(arc
		(start 93.222064 -273.951192)
		(mid 92.945589 -274.018512)
		(end 92.671392 -273.942556)
		(width 0.088646)
		(layer "In11.Cu")
		(net "M_D_CPU1_SA_DQ<17>")
	)
	(arc
		(start 87.032592 -273.942556)
		(mid 86.845394 -273.892413)
		(end 86.658196 -273.942556)
		(width 0.088646)
		(layer "In11.Cu")
		(net "M_D_CPU1_SA_DQ<17>")
	)
	(arc
		(start 92.286582 -273.948652)
		(mid 92.008404 -274.018375)
		(end 91.731846 -273.942556)
		(width 0.088646)
		(layer "In11.Cu")
		(net "M_D_CPU1_SA_DQ<17>")
	)
	(arc
		(start 90.791792 -273.942556)
		(mid 90.604594 -273.892413)
		(end 90.417396 -273.942556)
		(width 0.088646)
		(layer "In11.Cu")
		(net "M_D_CPU1_SA_DQ<17>")
	)
	(arc
		(start 96.041464 -273.951192)
		(mid 95.764989 -274.018512)
		(end 95.490792 -273.942556)
		(width 0.088646)
		(layer "In11.Cu")
		(net "M_D_CPU1_SA_DQ<17>")
	)
	(arc
		(start 95.490792 -273.942556)
		(mid 95.303594 -273.892413)
		(end 95.116396 -273.942556)
		(width 0.088646)
		(layer "In11.Cu")
		(net "M_D_CPU1_SA_DQ<17>")
	)
	(arc
		(start 94.161864 -273.951192)
		(mid 93.885389 -274.018512)
		(end 93.611192 -273.942556)
		(width 0.088646)
		(layer "In11.Cu")
		(net "M_D_CPU1_SA_DQ<17>")
	)
	(arc
		(start 90.417396 -273.942556)
		(mid 90.134694 -274.018332)
		(end 89.851992 -273.942556)
		(width 0.088646)
		(layer "In11.Cu")
		(net "M_D_CPU1_SA_DQ<17>")
	)
	(arc
		(start 97.921064 -273.951192)
		(mid 97.644589 -274.018512)
		(end 97.370392 -273.942556)
		(width 0.088646)
		(layer "In11.Cu")
		(net "M_D_CPU1_SA_DQ<17>")
	)
	(arc
		(start 91.731846 -273.942556)
		(mid 91.544648 -273.892413)
		(end 91.35745 -273.942556)
		(width 0.088646)
		(layer "In11.Cu")
		(net "M_D_CPU1_SA_DQ<17>")
	)
	(arc
		(start 96.981264 -273.951192)
		(mid 96.704789 -274.018512)
		(end 96.430592 -273.942556)
		(width 0.088646)
		(layer "In11.Cu")
		(net "M_D_CPU1_SA_DQ<17>")
	)
	(arc
		(start 97.370392 -273.942556)
		(mid 97.183194 -273.892413)
		(end 96.995996 -273.942556)
		(width 0.088646)
		(layer "In11.Cu")
		(net "M_D_CPU1_SA_DQ<17>")
	)
	(segment
		(start 9.713468 -297.855386)
		(end 10.172192 -297.855386)
		(width 0.20066)
		(layer "F.Cu")
		(net "M_D_CPU1_SA_DQ<16>")
	)
	(segment
		(start 13.890244 -297.191684)
		(end 14.315186 -297.616626)
		(width 0.20066)
		(layer "F.Cu")
		(net "M_D_CPU1_SA_DQ<16>")
	)
	(segment
		(start 14.315186 -297.616626)
		(end 15.684246 -297.616626)
		(width 0.20066)
		(layer "F.Cu")
		(net "M_D_CPU1_SA_DQ<16>")
	)
	(segment
		(start 13.441426 -297.191684)
		(end 13.890244 -297.191684)
		(width 0.20066)
		(layer "F.Cu")
		(net "M_D_CPU1_SA_DQ<16>")
	)
	(segment
		(start 11.124438 -297.191684)
		(end 11.372342 -297.191684)
		(width 0.101854)
		(layer "F.Cu")
		(net "M_D_CPU1_SA_DQ<16>")
	)
	(segment
		(start 10.344912 -297.682666)
		(end 10.344912 -297.393106)
		(width 0.20066)
		(layer "F.Cu")
		(net "M_D_CPU1_SA_DQ<16>")
	)
	(segment
		(start 99.063048 -273.730974)
		(end 99.063048 -274.26666)
		(width 0.20066)
		(layer "F.Cu")
		(net "M_D_CPU1_SA_DQ<16>")
	)
	(segment
		(start 11.372342 -297.191684)
		(end 13.441426 -297.191684)
		(width 0.1016)
		(layer "F.Cu")
		(net "M_D_CPU1_SA_DQ<16>")
	)
	(segment
		(start 10.344912 -297.393106)
		(end 10.554462 -297.183556)
		(width 0.20066)
		(layer "F.Cu")
		(net "M_D_CPU1_SA_DQ<16>")
	)
	(segment
		(start 10.554462 -297.183556)
		(end 11.11631 -297.183556)
		(width 0.20066)
		(layer "F.Cu")
		(net "M_D_CPU1_SA_DQ<16>")
	)
	(segment
		(start 9.474708 -297.616626)
		(end 9.713468 -297.855386)
		(width 0.20066)
		(layer "F.Cu")
		(net "M_D_CPU1_SA_DQ<16>")
	)
	(segment
		(start 8.140446 -297.616626)
		(end 9.474708 -297.616626)
		(width 0.20066)
		(layer "F.Cu")
		(net "M_D_CPU1_SA_DQ<16>")
	)
	(segment
		(start 15.684246 -297.616626)
		(end 16.789146 -297.616626)
		(width 0.20066)
		(layer "F.Cu")
		(net "M_D_CPU1_SA_DQ<16>")
	)
	(segment
		(start 10.172192 -297.855386)
		(end 10.344912 -297.682666)
		(width 0.20066)
		(layer "F.Cu")
		(net "M_D_CPU1_SA_DQ<16>")
	)
	(segment
		(start 99.063048 -274.26666)
		(end 99.062794 -274.266914)
		(width 0.20066)
		(layer "F.Cu")
		(net "M_D_CPU1_SA_DQ<16>")
	)
	(segment
		(start 11.11631 -297.183556)
		(end 11.124438 -297.191684)
		(width 0.101854)
		(layer "F.Cu")
		(net "M_D_CPU1_SA_DQ<16>")
	)
	(segment
		(start 50.830226 -299.74159)
		(end 49.179226 -300.334426)
		(width 0.18288)
		(layer "In11.Cu")
		(net "M_D_CPU1_SA_DQ<16>")
	)
	(segment
		(start 21.156422 -297.19397)
		(end 20.533868 -297.19397)
		(width 0.18288)
		(layer "In11.Cu")
		(net "M_D_CPU1_SA_DQ<16>")
	)
	(segment
		(start 19.233134 -298.242482)
		(end 17.415002 -298.242482)
		(width 0.18288)
		(layer "In11.Cu")
		(net "M_D_CPU1_SA_DQ<16>")
	)
	(segment
		(start 19.639788 -297.835828)
		(end 19.233134 -298.242482)
		(width 0.18288)
		(layer "In11.Cu")
		(net "M_D_CPU1_SA_DQ<16>")
	)
	(segment
		(start 93.156278 -274.765008)
		(end 93.141546 -274.756372)
		(width 0.088646)
		(layer "In11.Cu")
		(net "M_D_CPU1_SA_DQ<16>")
	)
	(segment
		(start 20.201636 -296.861738)
		(end 19.832828 -296.861738)
		(width 0.18288)
		(layer "In11.Cu")
		(net "M_D_CPU1_SA_DQ<16>")
	)
	(segment
		(start 62.566804 -294.711882)
		(end 62.366906 -294.591486)
		(width 0.18288)
		(layer "In11.Cu")
		(net "M_D_CPU1_SA_DQ<16>")
	)
	(segment
		(start 62.366906 -294.591486)
		(end 61.810646 -294.591486)
		(width 0.18288)
		(layer "In11.Cu")
		(net "M_D_CPU1_SA_DQ<16>")
	)
	(segment
		(start 64.260476 -294.711882)
		(end 62.566804 -294.711882)
		(width 0.18288)
		(layer "In11.Cu")
		(net "M_D_CPU1_SA_DQ<16>")
	)
	(segment
		(start 28.673044 -300.468792)
		(end 27.70378 -300.10862)
		(width 0.18288)
		(layer "In11.Cu")
		(net "M_D_CPU1_SA_DQ<16>")
	)
	(segment
		(start 88.067896 -274.756372)
		(end 88.057482 -274.762468)
		(width 0.088646)
		(layer "In11.Cu")
		(net "M_D_CPU1_SA_DQ<16>")
	)
	(segment
		(start 65.10274 -294.137588)
		(end 64.71793 -294.522398)
		(width 0.18288)
		(layer "In11.Cu")
		(net "M_D_CPU1_SA_DQ<16>")
	)
	(segment
		(start 85.082634 -274.705572)
		(end 84.85505 -274.933156)
		(width 0.088646)
		(layer "In11.Cu")
		(net "M_D_CPU1_SA_DQ<16>")
	)
	(segment
		(start 66.777108 -293.44366)
		(end 65.10274 -294.137588)
		(width 0.18288)
		(layer "In11.Cu")
		(net "M_D_CPU1_SA_DQ<16>")
	)
	(segment
		(start 85.43544 -274.705572)
		(end 85.082634 -274.705572)
		(width 0.088646)
		(layer "In11.Cu")
		(net "M_D_CPU1_SA_DQ<16>")
	)
	(segment
		(start 17.415002 -298.242482)
		(end 16.789146 -297.616626)
		(width 0.18288)
		(layer "In11.Cu")
		(net "M_D_CPU1_SA_DQ<16>")
	)
	(segment
		(start 69.056758 -291.16401)
		(end 66.777108 -293.44366)
		(width 0.18288)
		(layer "In11.Cu")
		(net "M_D_CPU1_SA_DQ<16>")
	)
	(segment
		(start 56.957722 -296.790618)
		(end 55.551578 -297.500802)
		(width 0.18288)
		(layer "In11.Cu")
		(net "M_D_CPU1_SA_DQ<16>")
	)
	(segment
		(start 52.446936 -299.623226)
		(end 52.067206 -299.623226)
		(width 0.18288)
		(layer "In11.Cu")
		(net "M_D_CPU1_SA_DQ<16>")
	)
	(segment
		(start 20.533868 -297.19397)
		(end 20.201636 -296.861738)
		(width 0.18288)
		(layer "In11.Cu")
		(net "M_D_CPU1_SA_DQ<16>")
	)
	(segment
		(start 55.551578 -297.500802)
		(end 55.084218 -297.80484)
		(width 0.18288)
		(layer "In11.Cu")
		(net "M_D_CPU1_SA_DQ<16>")
	)
	(segment
		(start 60.933076 -294.650922)
		(end 60.615068 -294.81272)
		(width 0.18288)
		(layer "In11.Cu")
		(net "M_D_CPU1_SA_DQ<16>")
	)
	(segment
		(start 90.332306 -274.762468)
		(end 90.321892 -274.756372)
		(width 0.088646)
		(layer "In11.Cu")
		(net "M_D_CPU1_SA_DQ<16>")
	)
	(segment
		(start 49.179226 -300.334426)
		(end 47.299626 -300.591728)
		(width 0.18288)
		(layer "In11.Cu")
		(net "M_D_CPU1_SA_DQ<16>")
	)
	(segment
		(start 55.084218 -297.80484)
		(end 54.217316 -298.067476)
		(width 0.18288)
		(layer "In11.Cu")
		(net "M_D_CPU1_SA_DQ<16>")
	)
	(segment
		(start 58.89498 -295.47566)
		(end 58.27268 -295.47566)
		(width 0.18288)
		(layer "In11.Cu")
		(net "M_D_CPU1_SA_DQ<16>")
	)
	(segment
		(start 54.217316 -298.067476)
		(end 52.796948 -299.487844)
		(width 0.18288)
		(layer "In11.Cu")
		(net "M_D_CPU1_SA_DQ<16>")
	)
	(segment
		(start 84.85505 -274.933156)
		(end 84.85505 -277.149052)
		(width 0.088646)
		(layer "In11.Cu")
		(net "M_D_CPU1_SA_DQ<16>")
	)
	(segment
		(start 98.483928 -274.71116)
		(end 98.405696 -274.756372)
		(width 0.088646)
		(layer "In11.Cu")
		(net "M_D_CPU1_SA_DQ<16>")
	)
	(segment
		(start 46.690026 -300.591728)
		(end 45.872654 -300.715426)
		(width 0.18288)
		(layer "In11.Cu")
		(net "M_D_CPU1_SA_DQ<16>")
	)
	(segment
		(start 87.127842 -274.756372)
		(end 87.11311 -274.765008)
		(width 0.088646)
		(layer "In11.Cu")
		(net "M_D_CPU1_SA_DQ<16>")
	)
	(segment
		(start 27.70378 -300.10862)
		(end 26.515568 -298.920408)
		(width 0.18288)
		(layer "In11.Cu")
		(net "M_D_CPU1_SA_DQ<16>")
	)
	(segment
		(start 92.211906 -274.762468)
		(end 92.201492 -274.756372)
		(width 0.088646)
		(layer "In11.Cu")
		(net "M_D_CPU1_SA_DQ<16>")
	)
	(segment
		(start 60.464192 -295.276016)
		(end 59.997086 -295.513506)
		(width 0.18288)
		(layer "In11.Cu")
		(net "M_D_CPU1_SA_DQ<16>")
	)
	(segment
		(start 58.932826 -295.513506)
		(end 58.89498 -295.47566)
		(width 0.18288)
		(layer "In11.Cu")
		(net "M_D_CPU1_SA_DQ<16>")
	)
	(segment
		(start 21.840444 -297.877992)
		(end 21.156422 -297.19397)
		(width 0.18288)
		(layer "In11.Cu")
		(net "M_D_CPU1_SA_DQ<16>")
	)
	(segment
		(start 84.85505 -277.149052)
		(end 83.850734 -278.153368)
		(width 0.088646)
		(layer "In11.Cu")
		(net "M_D_CPU1_SA_DQ<16>")
	)
	(segment
		(start 52.067206 -299.623226)
		(end 51.575462 -299.74159)
		(width 0.18288)
		(layer "In11.Cu")
		(net "M_D_CPU1_SA_DQ<16>")
	)
	(segment
		(start 44.004484 -300.538388)
		(end 43.032426 -300.309026)
		(width 0.18288)
		(layer "In11.Cu")
		(net "M_D_CPU1_SA_DQ<16>")
	)
	(segment
		(start 58.27268 -295.47566)
		(end 56.957722 -296.790618)
		(width 0.18288)
		(layer "In11.Cu")
		(net "M_D_CPU1_SA_DQ<16>")
	)
	(segment
		(start 36.657026 -299.74159)
		(end 35.737546 -299.74159)
		(width 0.18288)
		(layer "In11.Cu")
		(net "M_D_CPU1_SA_DQ<16>")
	)
	(segment
		(start 52.796948 -299.487844)
		(end 52.446936 -299.623226)
		(width 0.18288)
		(layer "In11.Cu")
		(net "M_D_CPU1_SA_DQ<16>")
	)
	(segment
		(start 44.656756 -300.715426)
		(end 44.004484 -300.538388)
		(width 0.18288)
		(layer "In11.Cu")
		(net "M_D_CPU1_SA_DQ<16>")
	)
	(segment
		(start 60.615068 -294.81272)
		(end 60.464192 -295.276016)
		(width 0.18288)
		(layer "In11.Cu")
		(net "M_D_CPU1_SA_DQ<16>")
	)
	(segment
		(start 64.71793 -294.522398)
		(end 64.260476 -294.711882)
		(width 0.18288)
		(layer "In11.Cu")
		(net "M_D_CPU1_SA_DQ<16>")
	)
	(segment
		(start 95.975678 -274.765008)
		(end 95.960946 -274.756372)
		(width 0.088646)
		(layer "In11.Cu")
		(net "M_D_CPU1_SA_DQ<16>")
	)
	(segment
		(start 45.872654 -300.715426)
		(end 44.656756 -300.715426)
		(width 0.18288)
		(layer "In11.Cu")
		(net "M_D_CPU1_SA_DQ<16>")
	)
	(segment
		(start 43.032426 -300.309026)
		(end 40.080946 -299.776388)
		(width 0.18288)
		(layer "In11.Cu")
		(net "M_D_CPU1_SA_DQ<16>")
	)
	(segment
		(start 32.262826 -300.591728)
		(end 29.859478 -300.591728)
		(width 0.18288)
		(layer "In11.Cu")
		(net "M_D_CPU1_SA_DQ<16>")
	)
	(segment
		(start 29.487622 -300.602396)
		(end 28.673044 -300.468792)
		(width 0.18288)
		(layer "In11.Cu")
		(net "M_D_CPU1_SA_DQ<16>")
	)
	(segment
		(start 33.350708 -300.436534)
		(end 32.262826 -300.591728)
		(width 0.18288)
		(layer "In11.Cu")
		(net "M_D_CPU1_SA_DQ<16>")
	)
	(segment
		(start 61.810646 -294.591486)
		(end 61.396372 -294.802306)
		(width 0.18288)
		(layer "In11.Cu")
		(net "M_D_CPU1_SA_DQ<16>")
	)
	(segment
		(start 24.305768 -297.964098)
		(end 23.245826 -297.964098)
		(width 0.18288)
		(layer "In11.Cu")
		(net "M_D_CPU1_SA_DQ<16>")
	)
	(segment
		(start 19.639788 -297.054778)
		(end 19.639788 -297.835828)
		(width 0.18288)
		(layer "In11.Cu")
		(net "M_D_CPU1_SA_DQ<16>")
	)
	(segment
		(start 34.475674 -300.34992)
		(end 33.350708 -300.436534)
		(width 0.18288)
		(layer "In11.Cu")
		(net "M_D_CPU1_SA_DQ<16>")
	)
	(segment
		(start 23.245826 -297.964098)
		(end 22.512274 -297.877992)
		(width 0.18288)
		(layer "In11.Cu")
		(net "M_D_CPU1_SA_DQ<16>")
	)
	(segment
		(start 86.188042 -274.756372)
		(end 86.17331 -274.765008)
		(width 0.088646)
		(layer "In11.Cu")
		(net "M_D_CPU1_SA_DQ<16>")
	)
	(segment
		(start 29.859478 -300.591728)
		(end 29.84881 -300.602396)
		(width 0.18288)
		(layer "In11.Cu")
		(net "M_D_CPU1_SA_DQ<16>")
	)
	(segment
		(start 96.915478 -274.765008)
		(end 96.900746 -274.756372)
		(width 0.088646)
		(layer "In11.Cu")
		(net "M_D_CPU1_SA_DQ<16>")
	)
	(segment
		(start 22.512274 -297.877992)
		(end 21.840444 -297.877992)
		(width 0.18288)
		(layer "In11.Cu")
		(net "M_D_CPU1_SA_DQ<16>")
	)
	(segment
		(start 83.219036 -278.153368)
		(end 83.034378 -277.96871)
		(width 0.088646)
		(layer "In11.Cu")
		(net "M_D_CPU1_SA_DQ<16>")
	)
	(segment
		(start 61.396372 -294.802306)
		(end 60.933076 -294.650922)
		(width 0.18288)
		(layer "In11.Cu")
		(net "M_D_CPU1_SA_DQ<16>")
	)
	(segment
		(start 83.034378 -277.96871)
		(end 82.667602 -277.96871)
		(width 0.088646)
		(layer "In11.Cu")
		(net "M_D_CPU1_SA_DQ<16>")
	)
	(segment
		(start 95.035878 -274.765008)
		(end 95.021146 -274.756372)
		(width 0.088646)
		(layer "In11.Cu")
		(net "M_D_CPU1_SA_DQ<16>")
	)
	(segment
		(start 94.096078 -274.765008)
		(end 94.081346 -274.756372)
		(width 0.088646)
		(layer "In11.Cu")
		(net "M_D_CPU1_SA_DQ<16>")
	)
	(segment
		(start 82.667602 -277.96871)
		(end 81.678272 -277.96871)
		(width 0.18288)
		(layer "In11.Cu")
		(net "M_D_CPU1_SA_DQ<16>")
	)
	(segment
		(start 35.737546 -299.74159)
		(end 34.475674 -300.34992)
		(width 0.18288)
		(layer "In11.Cu")
		(net "M_D_CPU1_SA_DQ<16>")
	)
	(segment
		(start 39.400226 -299.623226)
		(end 37.469826 -299.623226)
		(width 0.18288)
		(layer "In11.Cu")
		(net "M_D_CPU1_SA_DQ<16>")
	)
	(segment
		(start 69.056758 -290.590224)
		(end 69.056758 -291.16401)
		(width 0.18288)
		(layer "In11.Cu")
		(net "M_D_CPU1_SA_DQ<16>")
	)
	(segment
		(start 40.080946 -299.776388)
		(end 39.400226 -299.623226)
		(width 0.18288)
		(layer "In11.Cu")
		(net "M_D_CPU1_SA_DQ<16>")
	)
	(segment
		(start 19.832828 -296.861738)
		(end 19.639788 -297.054778)
		(width 0.18288)
		(layer "In11.Cu")
		(net "M_D_CPU1_SA_DQ<16>")
	)
	(segment
		(start 51.575462 -299.74159)
		(end 50.830226 -299.74159)
		(width 0.18288)
		(layer "In11.Cu")
		(net "M_D_CPU1_SA_DQ<16>")
	)
	(segment
		(start 91.827096 -274.756372)
		(end 91.816682 -274.762468)
		(width 0.088646)
		(layer "In11.Cu")
		(net "M_D_CPU1_SA_DQ<16>")
	)
	(segment
		(start 37.469826 -299.623226)
		(end 36.657026 -299.74159)
		(width 0.18288)
		(layer "In11.Cu")
		(net "M_D_CPU1_SA_DQ<16>")
	)
	(segment
		(start 81.678272 -277.96871)
		(end 69.056758 -290.590224)
		(width 0.18288)
		(layer "In11.Cu")
		(net "M_D_CPU1_SA_DQ<16>")
	)
	(segment
		(start 29.84881 -300.602396)
		(end 29.487622 -300.602396)
		(width 0.18288)
		(layer "In11.Cu")
		(net "M_D_CPU1_SA_DQ<16>")
	)
	(segment
		(start 47.299626 -300.591728)
		(end 46.690026 -300.591728)
		(width 0.18288)
		(layer "In11.Cu")
		(net "M_D_CPU1_SA_DQ<16>")
	)
	(segment
		(start 83.850734 -278.153368)
		(end 83.219036 -278.153368)
		(width 0.088646)
		(layer "In11.Cu")
		(net "M_D_CPU1_SA_DQ<16>")
	)
	(segment
		(start 26.515568 -298.920408)
		(end 24.305768 -297.964098)
		(width 0.18288)
		(layer "In11.Cu")
		(net "M_D_CPU1_SA_DQ<16>")
	)
	(segment
		(start 59.997086 -295.513506)
		(end 58.932826 -295.513506)
		(width 0.18288)
		(layer "In11.Cu")
		(net "M_D_CPU1_SA_DQ<16>")
	)
	(segment
		(start 97.85096 -274.762468)
		(end 97.840546 -274.756372)
		(width 0.088646)
		(layer "In11.Cu")
		(net "M_D_CPU1_SA_DQ<16>")
	)
	(arc
		(start 94.081346 -274.756372)
		(mid 93.894148 -274.706229)
		(end 93.70695 -274.756372)
		(width 0.088646)
		(layer "In11.Cu")
		(net "M_D_CPU1_SA_DQ<16>")
	)
	(arc
		(start 87.11311 -274.765008)
		(mid 86.836635 -274.832328)
		(end 86.562438 -274.756372)
		(width 0.088646)
		(layer "In11.Cu")
		(net "M_D_CPU1_SA_DQ<16>")
	)
	(arc
		(start 88.442292 -274.756372)
		(mid 88.255094 -274.706229)
		(end 88.067896 -274.756372)
		(width 0.088646)
		(layer "In11.Cu")
		(net "M_D_CPU1_SA_DQ<16>")
	)
	(arc
		(start 96.52635 -274.756372)
		(mid 96.252151 -274.832207)
		(end 95.975678 -274.765008)
		(width 0.088646)
		(layer "In11.Cu")
		(net "M_D_CPU1_SA_DQ<16>")
	)
	(arc
		(start 89.007696 -274.756372)
		(mid 88.724994 -274.832148)
		(end 88.442292 -274.756372)
		(width 0.088646)
		(layer "In11.Cu")
		(net "M_D_CPU1_SA_DQ<16>")
	)
	(arc
		(start 85.622638 -274.756372)
		(mid 85.532382 -274.71865)
		(end 85.43544 -274.705572)
		(width 0.088646)
		(layer "In11.Cu")
		(net "M_D_CPU1_SA_DQ<16>")
	)
	(arc
		(start 97.46615 -274.756372)
		(mid 97.191951 -274.832207)
		(end 96.915478 -274.765008)
		(width 0.088646)
		(layer "In11.Cu")
		(net "M_D_CPU1_SA_DQ<16>")
	)
	(arc
		(start 98.405696 -274.756372)
		(mid 98.129137 -274.832115)
		(end 97.85096 -274.762468)
		(width 0.088646)
		(layer "In11.Cu")
		(net "M_D_CPU1_SA_DQ<16>")
	)
	(arc
		(start 86.17331 -274.765008)
		(mid 85.896835 -274.832328)
		(end 85.622638 -274.756372)
		(width 0.088646)
		(layer "In11.Cu")
		(net "M_D_CPU1_SA_DQ<16>")
	)
	(arc
		(start 95.021146 -274.756372)
		(mid 94.833948 -274.706229)
		(end 94.64675 -274.756372)
		(width 0.088646)
		(layer "In11.Cu")
		(net "M_D_CPU1_SA_DQ<16>")
	)
	(arc
		(start 95.960946 -274.756372)
		(mid 95.773748 -274.706229)
		(end 95.58655 -274.756372)
		(width 0.088646)
		(layer "In11.Cu")
		(net "M_D_CPU1_SA_DQ<16>")
	)
	(arc
		(start 93.141546 -274.756372)
		(mid 92.954348 -274.706229)
		(end 92.76715 -274.756372)
		(width 0.088646)
		(layer "In11.Cu")
		(net "M_D_CPU1_SA_DQ<16>")
	)
	(arc
		(start 89.947496 -274.756372)
		(mid 89.664794 -274.832148)
		(end 89.382092 -274.756372)
		(width 0.088646)
		(layer "In11.Cu")
		(net "M_D_CPU1_SA_DQ<16>")
	)
	(arc
		(start 97.840546 -274.756372)
		(mid 97.653348 -274.706229)
		(end 97.46615 -274.756372)
		(width 0.088646)
		(layer "In11.Cu")
		(net "M_D_CPU1_SA_DQ<16>")
	)
	(arc
		(start 89.382092 -274.756372)
		(mid 89.194894 -274.706229)
		(end 89.007696 -274.756372)
		(width 0.088646)
		(layer "In11.Cu")
		(net "M_D_CPU1_SA_DQ<16>")
	)
	(arc
		(start 93.70695 -274.756372)
		(mid 93.432751 -274.832207)
		(end 93.156278 -274.765008)
		(width 0.088646)
		(layer "In11.Cu")
		(net "M_D_CPU1_SA_DQ<16>")
	)
	(arc
		(start 96.900746 -274.756372)
		(mid 96.713548 -274.706229)
		(end 96.52635 -274.756372)
		(width 0.088646)
		(layer "In11.Cu")
		(net "M_D_CPU1_SA_DQ<16>")
	)
	(arc
		(start 95.58655 -274.756372)
		(mid 95.312351 -274.832207)
		(end 95.035878 -274.765008)
		(width 0.088646)
		(layer "In11.Cu")
		(net "M_D_CPU1_SA_DQ<16>")
	)
	(arc
		(start 91.816682 -274.762468)
		(mid 91.538504 -274.832191)
		(end 91.261946 -274.756372)
		(width 0.088646)
		(layer "In11.Cu")
		(net "M_D_CPU1_SA_DQ<16>")
	)
	(arc
		(start 91.261946 -274.756372)
		(mid 91.074748 -274.706229)
		(end 90.88755 -274.756372)
		(width 0.088646)
		(layer "In11.Cu")
		(net "M_D_CPU1_SA_DQ<16>")
	)
	(arc
		(start 99.062794 -274.266914)
		(mid 98.787901 -274.507982)
		(end 98.483928 -274.71116)
		(width 0.088646)
		(layer "In11.Cu")
		(net "M_D_CPU1_SA_DQ<16>")
	)
	(arc
		(start 87.502238 -274.756372)
		(mid 87.31504 -274.706229)
		(end 87.127842 -274.756372)
		(width 0.088646)
		(layer "In11.Cu")
		(net "M_D_CPU1_SA_DQ<16>")
	)
	(arc
		(start 92.76715 -274.756372)
		(mid 92.490337 -274.832242)
		(end 92.211906 -274.762468)
		(width 0.088646)
		(layer "In11.Cu")
		(net "M_D_CPU1_SA_DQ<16>")
	)
	(arc
		(start 92.201492 -274.756372)
		(mid 92.014294 -274.706229)
		(end 91.827096 -274.756372)
		(width 0.088646)
		(layer "In11.Cu")
		(net "M_D_CPU1_SA_DQ<16>")
	)
	(arc
		(start 90.321892 -274.756372)
		(mid 90.134694 -274.706229)
		(end 89.947496 -274.756372)
		(width 0.088646)
		(layer "In11.Cu")
		(net "M_D_CPU1_SA_DQ<16>")
	)
	(arc
		(start 88.057482 -274.762468)
		(mid 87.77905 -274.832314)
		(end 87.502238 -274.756372)
		(width 0.088646)
		(layer "In11.Cu")
		(net "M_D_CPU1_SA_DQ<16>")
	)
	(arc
		(start 90.88755 -274.756372)
		(mid 90.610737 -274.832242)
		(end 90.332306 -274.762468)
		(width 0.088646)
		(layer "In11.Cu")
		(net "M_D_CPU1_SA_DQ<16>")
	)
	(arc
		(start 94.64675 -274.756372)
		(mid 94.372551 -274.832207)
		(end 94.096078 -274.765008)
		(width 0.088646)
		(layer "In11.Cu")
		(net "M_D_CPU1_SA_DQ<16>")
	)
	(arc
		(start 86.562438 -274.756372)
		(mid 86.37524 -274.706229)
		(end 86.188042 -274.756372)
		(width 0.088646)
		(layer "In11.Cu")
		(net "M_D_CPU1_SA_DQ<16>")
	)
	(segment
		(start 17.578578 -298.59097)
		(end 17.707102 -298.462446)
		(width 0.20066)
		(layer "F.Cu")
		(net "M_D_CPU1_SA_DQ<15>")
	)
	(segment
		(start 17.707102 -298.462446)
		(end 18.102326 -298.462446)
		(width 0.20066)
		(layer "F.Cu")
		(net "M_D_CPU1_SA_DQ<15>")
	)
	(segment
		(start 14.574266 -298.891706)
		(end 14.812264 -298.891706)
		(width 0.101854)
		(layer "F.Cu")
		(net "M_D_CPU1_SA_DQ<15>")
	)
	(segment
		(start 18.102326 -298.462446)
		(end 18.314162 -298.674282)
		(width 0.20066)
		(layer "F.Cu")
		(net "M_D_CPU1_SA_DQ<15>")
	)
	(segment
		(start 14.560042 -298.90593)
		(end 14.574266 -298.891706)
		(width 0.101854)
		(layer "F.Cu")
		(net "M_D_CPU1_SA_DQ<15>")
	)
	(segment
		(start 14.063726 -298.763436)
		(end 14.20622 -298.90593)
		(width 0.20066)
		(layer "F.Cu")
		(net "M_D_CPU1_SA_DQ<15>")
	)
	(segment
		(start 18.760694 -298.674282)
		(end 18.968212 -298.466764)
		(width 0.20066)
		(layer "F.Cu")
		(net "M_D_CPU1_SA_DQ<15>")
	)
	(segment
		(start 14.812264 -298.891706)
		(end 16.885158 -298.891706)
		(width 0.1016)
		(layer "F.Cu")
		(net "M_D_CPU1_SA_DQ<15>")
	)
	(segment
		(start 14.20622 -298.90593)
		(end 14.560042 -298.90593)
		(width 0.20066)
		(layer "F.Cu")
		(net "M_D_CPU1_SA_DQ<15>")
	)
	(segment
		(start 14.063726 -298.592748)
		(end 14.063726 -298.763436)
		(width 0.20066)
		(layer "F.Cu")
		(net "M_D_CPU1_SA_DQ<15>")
	)
	(segment
		(start 12.240514 -298.466764)
		(end 13.937742 -298.466764)
		(width 0.20066)
		(layer "F.Cu")
		(net "M_D_CPU1_SA_DQ<15>")
	)
	(segment
		(start 13.937742 -298.466764)
		(end 14.063726 -298.592748)
		(width 0.20066)
		(layer "F.Cu")
		(net "M_D_CPU1_SA_DQ<15>")
	)
	(segment
		(start 17.42948 -298.891706)
		(end 17.578578 -298.742608)
		(width 0.20066)
		(layer "F.Cu")
		(net "M_D_CPU1_SA_DQ<15>")
	)
	(segment
		(start 18.968212 -298.466764)
		(end 19.784314 -298.466764)
		(width 0.20066)
		(layer "F.Cu")
		(net "M_D_CPU1_SA_DQ<15>")
	)
	(segment
		(start 17.578578 -298.742608)
		(end 17.578578 -298.59097)
		(width 0.20066)
		(layer "F.Cu")
		(net "M_D_CPU1_SA_DQ<15>")
	)
	(segment
		(start 20.889214 -298.466764)
		(end 19.784314 -298.466764)
		(width 0.20066)
		(layer "F.Cu")
		(net "M_D_CPU1_SA_DQ<15>")
	)
	(segment
		(start 16.885158 -298.891706)
		(end 17.42948 -298.891706)
		(width 0.20066)
		(layer "F.Cu")
		(net "M_D_CPU1_SA_DQ<15>")
	)
	(segment
		(start 18.314162 -298.674282)
		(end 18.760694 -298.674282)
		(width 0.20066)
		(layer "F.Cu")
		(net "M_D_CPU1_SA_DQ<15>")
	)
	(arc
		(start 100.002848 -275.35886)
		(mid 100.002784 -275.62683)
		(end 100.002594 -275.8948)
		(width 0.20066)
		(layer "F.Cu")
		(net "M_D_CPU1_SA_DQ<15>")
	)
	(segment
		(start 30.43682 -303.060862)
		(end 29.463746 -303.060862)
		(width 0.18288)
		(layer "In11.Cu")
		(net "M_D_CPU1_SA_DQ<15>")
	)
	(segment
		(start 42.854626 -302.710342)
		(end 42.661586 -302.903382)
		(width 0.18288)
		(layer "In11.Cu")
		(net "M_D_CPU1_SA_DQ<15>")
	)
	(segment
		(start 38.09619 -302.32858)
		(end 37.894514 -302.530256)
		(width 0.18288)
		(layer "In11.Cu")
		(net "M_D_CPU1_SA_DQ<15>")
	)
	(segment
		(start 93.156278 -275.396452)
		(end 93.141546 -275.405088)
		(width 0.088646)
		(layer "In11.Cu")
		(net "M_D_CPU1_SA_DQ<15>")
	)
	(segment
		(start 58.444638 -297.136566)
		(end 57.220358 -298.360846)
		(width 0.18288)
		(layer "In11.Cu")
		(net "M_D_CPU1_SA_DQ<15>")
	)
	(segment
		(start 44.97705 -303.432718)
		(end 44.66209 -303.432718)
		(width 0.18288)
		(layer "In11.Cu")
		(net "M_D_CPU1_SA_DQ<15>")
	)
	(segment
		(start 44.46905 -303.239678)
		(end 44.46905 -302.903382)
		(width 0.18288)
		(layer "In11.Cu")
		(net "M_D_CPU1_SA_DQ<15>")
	)
	(segment
		(start 61.180726 -296.130726)
		(end 59.933586 -297.377866)
		(width 0.18288)
		(layer "In11.Cu")
		(net "M_D_CPU1_SA_DQ<15>")
	)
	(segment
		(start 62.747906 -296.130726)
		(end 61.180726 -296.130726)
		(width 0.18288)
		(layer "In11.Cu")
		(net "M_D_CPU1_SA_DQ<15>")
	)
	(segment
		(start 49.106582 -303.103026)
		(end 48.086518 -303.103026)
		(width 0.18288)
		(layer "In11.Cu")
		(net "M_D_CPU1_SA_DQ<15>")
	)
	(segment
		(start 42.661586 -303.36998)
		(end 42.468546 -303.56302)
		(width 0.18288)
		(layer "In11.Cu")
		(net "M_D_CPU1_SA_DQ<15>")
	)
	(segment
		(start 37.894514 -303.083468)
		(end 37.701474 -303.276508)
		(width 0.18288)
		(layer "In11.Cu")
		(net "M_D_CPU1_SA_DQ<15>")
	)
	(segment
		(start 52.970176 -301.039276)
		(end 52.211224 -301.039276)
		(width 0.18288)
		(layer "In11.Cu")
		(net "M_D_CPU1_SA_DQ<15>")
	)
	(segment
		(start 45.17009 -303.239678)
		(end 44.97705 -303.432718)
		(width 0.18288)
		(layer "In11.Cu")
		(net "M_D_CPU1_SA_DQ<15>")
	)
	(segment
		(start 41.960546 -302.903382)
		(end 41.767506 -302.710342)
		(width 0.18288)
		(layer "In11.Cu")
		(net "M_D_CPU1_SA_DQ<15>")
	)
	(segment
		(start 37.894514 -302.530256)
		(end 37.894514 -303.083468)
		(width 0.18288)
		(layer "In11.Cu")
		(net "M_D_CPU1_SA_DQ<15>")
	)
	(segment
		(start 86.101428 -276.214078)
		(end 86.092538 -276.219158)
		(width 0.088646)
		(layer "In11.Cu")
		(net "M_D_CPU1_SA_DQ<15>")
	)
	(segment
		(start 39.997634 -303.083468)
		(end 39.997634 -302.903382)
		(width 0.18288)
		(layer "In11.Cu")
		(net "M_D_CPU1_SA_DQ<15>")
	)
	(segment
		(start 45.17009 -302.903382)
		(end 45.17009 -303.239678)
		(width 0.18288)
		(layer "In11.Cu")
		(net "M_D_CPU1_SA_DQ<15>")
	)
	(segment
		(start 42.153586 -303.56302)
		(end 41.960546 -303.36998)
		(width 0.18288)
		(layer "In11.Cu")
		(net "M_D_CPU1_SA_DQ<15>")
	)
	(segment
		(start 82.982054 -278.666702)
		(end 82.877406 -278.77135)
		(width 0.18288)
		(layer "In11.Cu")
		(net "M_D_CPU1_SA_DQ<15>")
	)
	(segment
		(start 39.296594 -302.903382)
		(end 39.296594 -303.083468)
		(width 0.18288)
		(layer "In11.Cu")
		(net "M_D_CPU1_SA_DQ<15>")
	)
	(segment
		(start 37.193474 -302.903382)
		(end 37.000434 -302.710342)
		(width 0.18288)
		(layer "In11.Cu")
		(net "M_D_CPU1_SA_DQ<15>")
	)
	(segment
		(start 69.859398 -290.92271)
		(end 69.859398 -291.49929)
		(width 0.18288)
		(layer "In11.Cu")
		(net "M_D_CPU1_SA_DQ<15>")
	)
	(segment
		(start 37.701474 -303.276508)
		(end 37.386514 -303.276508)
		(width 0.18288)
		(layer "In11.Cu")
		(net "M_D_CPU1_SA_DQ<15>")
	)
	(segment
		(start 57.220358 -298.360846)
		(end 56.664606 -298.360846)
		(width 0.18288)
		(layer "In11.Cu")
		(net "M_D_CPU1_SA_DQ<15>")
	)
	(segment
		(start 38.595554 -303.083468)
		(end 38.595554 -302.52162)
		(width 0.18288)
		(layer "In11.Cu")
		(net "M_D_CPU1_SA_DQ<15>")
	)
	(segment
		(start 59.397646 -297.377866)
		(end 59.156346 -297.136566)
		(width 0.18288)
		(layer "In11.Cu")
		(net "M_D_CPU1_SA_DQ<15>")
	)
	(segment
		(start 37.193474 -303.083468)
		(end 37.193474 -302.903382)
		(width 0.18288)
		(layer "In11.Cu")
		(net "M_D_CPU1_SA_DQ<15>")
	)
	(segment
		(start 52.211224 -301.039276)
		(end 51.666648 -301.583852)
		(width 0.18288)
		(layer "In11.Cu")
		(net "M_D_CPU1_SA_DQ<15>")
	)
	(segment
		(start 59.933586 -297.377866)
		(end 59.397646 -297.377866)
		(width 0.18288)
		(layer "In11.Cu")
		(net "M_D_CPU1_SA_DQ<15>")
	)
	(segment
		(start 32.516826 -303.788826)
		(end 32.313626 -303.992026)
		(width 0.18288)
		(layer "In11.Cu")
		(net "M_D_CPU1_SA_DQ<15>")
	)
	(segment
		(start 99.68992 -275.8948)
		(end 99.624642 -275.829522)
		(width 0.088646)
		(layer "In11.Cu")
		(net "M_D_CPU1_SA_DQ<15>")
	)
	(segment
		(start 39.804594 -302.710342)
		(end 39.489634 -302.710342)
		(width 0.18288)
		(layer "In11.Cu")
		(net "M_D_CPU1_SA_DQ<15>")
	)
	(segment
		(start 44.27601 -302.710342)
		(end 42.854626 -302.710342)
		(width 0.18288)
		(layer "In11.Cu")
		(net "M_D_CPU1_SA_DQ<15>")
	)
	(segment
		(start 40.698674 -302.903382)
		(end 40.698674 -303.083468)
		(width 0.18288)
		(layer "In11.Cu")
		(net "M_D_CPU1_SA_DQ<15>")
	)
	(segment
		(start 26.86431 -300.461426)
		(end 25.595326 -300.461426)
		(width 0.18288)
		(layer "In11.Cu")
		(net "M_D_CPU1_SA_DQ<15>")
	)
	(segment
		(start 38.402514 -302.32858)
		(end 38.09619 -302.32858)
		(width 0.18288)
		(layer "In11.Cu")
		(net "M_D_CPU1_SA_DQ<15>")
	)
	(segment
		(start 51.666648 -302.94072)
		(end 51.465226 -303.142142)
		(width 0.18288)
		(layer "In11.Cu")
		(net "M_D_CPU1_SA_DQ<15>")
	)
	(segment
		(start 35.426142 -303.142142)
		(end 35.234626 -302.950626)
		(width 0.18288)
		(layer "In11.Cu")
		(net "M_D_CPU1_SA_DQ<15>")
	)
	(segment
		(start 50.009298 -303.912524)
		(end 49.816258 -304.105564)
		(width 0.18288)
		(layer "In11.Cu")
		(net "M_D_CPU1_SA_DQ<15>")
	)
	(segment
		(start 42.468546 -303.56302)
		(end 42.153586 -303.56302)
		(width 0.18288)
		(layer "In11.Cu")
		(net "M_D_CPU1_SA_DQ<15>")
	)
	(segment
		(start 37.386514 -303.276508)
		(end 37.193474 -303.083468)
		(width 0.18288)
		(layer "In11.Cu")
		(net "M_D_CPU1_SA_DQ<15>")
	)
	(segment
		(start 40.891714 -302.710342)
		(end 40.698674 -302.903382)
		(width 0.18288)
		(layer "In11.Cu")
		(net "M_D_CPU1_SA_DQ<15>")
	)
	(segment
		(start 39.489634 -302.710342)
		(end 39.296594 -302.903382)
		(width 0.18288)
		(layer "In11.Cu")
		(net "M_D_CPU1_SA_DQ<15>")
	)
	(segment
		(start 91.27236 -275.398992)
		(end 91.261946 -275.405088)
		(width 0.088646)
		(layer "In11.Cu")
		(net "M_D_CPU1_SA_DQ<15>")
	)
	(segment
		(start 50.009298 -303.343818)
		(end 50.009298 -303.912524)
		(width 0.18288)
		(layer "In11.Cu")
		(net "M_D_CPU1_SA_DQ<15>")
	)
	(segment
		(start 40.698674 -303.083468)
		(end 40.505634 -303.276508)
		(width 0.18288)
		(layer "In11.Cu")
		(net "M_D_CPU1_SA_DQ<15>")
	)
	(segment
		(start 69.859398 -291.49929)
		(end 65.939416 -295.419272)
		(width 0.18288)
		(layer "In11.Cu")
		(net "M_D_CPU1_SA_DQ<15>")
	)
	(segment
		(start 56.664606 -298.360846)
		(end 56.011826 -299.013626)
		(width 0.18288)
		(layer "In11.Cu")
		(net "M_D_CPU1_SA_DQ<15>")
	)
	(segment
		(start 49.308258 -303.912524)
		(end 49.308258 -303.304702)
		(width 0.18288)
		(layer "In11.Cu")
		(net "M_D_CPU1_SA_DQ<15>")
	)
	(segment
		(start 36.694618 -302.710342)
		(end 36.262818 -303.142142)
		(width 0.18288)
		(layer "In11.Cu")
		(net "M_D_CPU1_SA_DQ<15>")
	)
	(segment
		(start 41.767506 -302.710342)
		(end 40.891714 -302.710342)
		(width 0.18288)
		(layer "In11.Cu")
		(net "M_D_CPU1_SA_DQ<15>")
	)
	(segment
		(start 39.103554 -303.276508)
		(end 38.788594 -303.276508)
		(width 0.18288)
		(layer "In11.Cu")
		(net "M_D_CPU1_SA_DQ<15>")
	)
	(segment
		(start 25.595326 -300.461426)
		(end 24.2189 -299.085)
		(width 0.18288)
		(layer "In11.Cu")
		(net "M_D_CPU1_SA_DQ<15>")
	)
	(segment
		(start 54.995826 -299.013626)
		(end 52.970176 -301.039276)
		(width 0.18288)
		(layer "In11.Cu")
		(net "M_D_CPU1_SA_DQ<15>")
	)
	(segment
		(start 82.010758 -278.77135)
		(end 69.859398 -290.92271)
		(width 0.18288)
		(layer "In11.Cu")
		(net "M_D_CPU1_SA_DQ<15>")
	)
	(segment
		(start 48.086518 -303.103026)
		(end 47.197518 -303.992026)
		(width 0.18288)
		(layer "In11.Cu")
		(net "M_D_CPU1_SA_DQ<15>")
	)
	(segment
		(start 38.595554 -302.52162)
		(end 38.402514 -302.32858)
		(width 0.18288)
		(layer "In11.Cu")
		(net "M_D_CPU1_SA_DQ<15>")
	)
	(segment
		(start 63.100966 -296.483786)
		(end 62.747906 -296.130726)
		(width 0.18288)
		(layer "In11.Cu")
		(net "M_D_CPU1_SA_DQ<15>")
	)
	(segment
		(start 100.002594 -275.8948)
		(end 99.68992 -275.8948)
		(width 0.088646)
		(layer "In11.Cu")
		(net "M_D_CPU1_SA_DQ<15>")
	)
	(segment
		(start 95.975678 -275.396452)
		(end 95.960946 -275.405088)
		(width 0.088646)
		(layer "In11.Cu")
		(net "M_D_CPU1_SA_DQ<15>")
	)
	(segment
		(start 86.27999 -275.876258)
		(end 86.27999 -275.8948)
		(width 0.088646)
		(layer "In11.Cu")
		(net "M_D_CPU1_SA_DQ<15>")
	)
	(segment
		(start 46.137322 -302.710342)
		(end 45.36313 -302.710342)
		(width 0.18288)
		(layer "In11.Cu")
		(net "M_D_CPU1_SA_DQ<15>")
	)
	(segment
		(start 32.516826 -303.280826)
		(end 32.516826 -303.788826)
		(width 0.18288)
		(layer "In11.Cu")
		(net "M_D_CPU1_SA_DQ<15>")
	)
	(segment
		(start 98.790506 -275.398992)
		(end 98.780092 -275.405088)
		(width 0.088646)
		(layer "In11.Cu")
		(net "M_D_CPU1_SA_DQ<15>")
	)
	(segment
		(start 44.46905 -302.903382)
		(end 44.27601 -302.710342)
		(width 0.18288)
		(layer "In11.Cu")
		(net "M_D_CPU1_SA_DQ<15>")
	)
	(segment
		(start 46.570646 -303.992026)
		(end 46.441106 -303.862486)
		(width 0.18288)
		(layer "In11.Cu")
		(net "M_D_CPU1_SA_DQ<15>")
	)
	(segment
		(start 49.308258 -303.304702)
		(end 49.106582 -303.103026)
		(width 0.18288)
		(layer "In11.Cu")
		(net "M_D_CPU1_SA_DQ<15>")
	)
	(segment
		(start 49.501298 -304.105564)
		(end 49.308258 -303.912524)
		(width 0.18288)
		(layer "In11.Cu")
		(net "M_D_CPU1_SA_DQ<15>")
	)
	(segment
		(start 44.66209 -303.432718)
		(end 44.46905 -303.239678)
		(width 0.18288)
		(layer "In11.Cu")
		(net "M_D_CPU1_SA_DQ<15>")
	)
	(segment
		(start 24.2189 -299.085)
		(end 21.50745 -299.085)
		(width 0.18288)
		(layer "In11.Cu")
		(net "M_D_CPU1_SA_DQ<15>")
	)
	(segment
		(start 40.190674 -303.276508)
		(end 39.997634 -303.083468)
		(width 0.18288)
		(layer "In11.Cu")
		(net "M_D_CPU1_SA_DQ<15>")
	)
	(segment
		(start 50.210974 -303.142142)
		(end 50.009298 -303.343818)
		(width 0.18288)
		(layer "In11.Cu")
		(net "M_D_CPU1_SA_DQ<15>")
	)
	(segment
		(start 39.997634 -302.903382)
		(end 39.804594 -302.710342)
		(width 0.18288)
		(layer "In11.Cu")
		(net "M_D_CPU1_SA_DQ<15>")
	)
	(segment
		(start 39.296594 -303.083468)
		(end 39.103554 -303.276508)
		(width 0.18288)
		(layer "In11.Cu")
		(net "M_D_CPU1_SA_DQ<15>")
	)
	(segment
		(start 37.000434 -302.710342)
		(end 36.694618 -302.710342)
		(width 0.18288)
		(layer "In11.Cu")
		(net "M_D_CPU1_SA_DQ<15>")
	)
	(segment
		(start 35.234626 -302.950626)
		(end 32.847026 -302.950626)
		(width 0.18288)
		(layer "In11.Cu")
		(net "M_D_CPU1_SA_DQ<15>")
	)
	(segment
		(start 36.262818 -303.142142)
		(end 35.426142 -303.142142)
		(width 0.18288)
		(layer "In11.Cu")
		(net "M_D_CPU1_SA_DQ<15>")
	)
	(segment
		(start 97.85096 -275.398992)
		(end 97.840546 -275.405088)
		(width 0.088646)
		(layer "In11.Cu")
		(net "M_D_CPU1_SA_DQ<15>")
	)
	(segment
		(start 49.816258 -304.105564)
		(end 49.501298 -304.105564)
		(width 0.18288)
		(layer "In11.Cu")
		(net "M_D_CPU1_SA_DQ<15>")
	)
	(segment
		(start 83.036918 -278.611838)
		(end 82.982054 -278.666702)
		(width 0.088646)
		(layer "In11.Cu")
		(net "M_D_CPU1_SA_DQ<15>")
	)
	(segment
		(start 96.915478 -275.396452)
		(end 96.900746 -275.405088)
		(width 0.088646)
		(layer "In11.Cu")
		(net "M_D_CPU1_SA_DQ<15>")
	)
	(segment
		(start 42.661586 -302.903382)
		(end 42.661586 -303.36998)
		(width 0.18288)
		(layer "In11.Cu")
		(net "M_D_CPU1_SA_DQ<15>")
	)
	(segment
		(start 41.960546 -303.36998)
		(end 41.960546 -302.903382)
		(width 0.18288)
		(layer "In11.Cu")
		(net "M_D_CPU1_SA_DQ<15>")
	)
	(segment
		(start 65.54216 -295.419272)
		(end 64.477646 -296.483786)
		(width 0.18288)
		(layer "In11.Cu")
		(net "M_D_CPU1_SA_DQ<15>")
	)
	(segment
		(start 64.477646 -296.483786)
		(end 63.100966 -296.483786)
		(width 0.18288)
		(layer "In11.Cu")
		(net "M_D_CPU1_SA_DQ<15>")
	)
	(segment
		(start 56.011826 -299.013626)
		(end 54.995826 -299.013626)
		(width 0.18288)
		(layer "In11.Cu")
		(net "M_D_CPU1_SA_DQ<15>")
	)
	(segment
		(start 29.463746 -303.060862)
		(end 26.86431 -300.461426)
		(width 0.18288)
		(layer "In11.Cu")
		(net "M_D_CPU1_SA_DQ<15>")
	)
	(segment
		(start 38.788594 -303.276508)
		(end 38.595554 -303.083468)
		(width 0.18288)
		(layer "In11.Cu")
		(net "M_D_CPU1_SA_DQ<15>")
	)
	(segment
		(start 85.504782 -276.244558)
		(end 85.047582 -276.701758)
		(width 0.088646)
		(layer "In11.Cu")
		(net "M_D_CPU1_SA_DQ<15>")
	)
	(segment
		(start 32.847026 -302.950626)
		(end 32.516826 -303.280826)
		(width 0.18288)
		(layer "In11.Cu")
		(net "M_D_CPU1_SA_DQ<15>")
	)
	(segment
		(start 82.877406 -278.77135)
		(end 82.010758 -278.77135)
		(width 0.18288)
		(layer "In11.Cu")
		(net "M_D_CPU1_SA_DQ<15>")
	)
	(segment
		(start 87.512652 -275.398992)
		(end 87.502238 -275.405088)
		(width 0.088646)
		(layer "In11.Cu")
		(net "M_D_CPU1_SA_DQ<15>")
	)
	(segment
		(start 31.367984 -303.992026)
		(end 30.43682 -303.060862)
		(width 0.18288)
		(layer "In11.Cu")
		(net "M_D_CPU1_SA_DQ<15>")
	)
	(segment
		(start 85.047582 -276.701758)
		(end 85.047582 -277.236682)
		(width 0.088646)
		(layer "In11.Cu")
		(net "M_D_CPU1_SA_DQ<15>")
	)
	(segment
		(start 47.197518 -303.992026)
		(end 46.570646 -303.992026)
		(width 0.18288)
		(layer "In11.Cu")
		(net "M_D_CPU1_SA_DQ<15>")
	)
	(segment
		(start 45.36313 -302.710342)
		(end 45.17009 -302.903382)
		(width 0.18288)
		(layer "In11.Cu")
		(net "M_D_CPU1_SA_DQ<15>")
	)
	(segment
		(start 95.035878 -275.396452)
		(end 95.021146 -275.405088)
		(width 0.088646)
		(layer "In11.Cu")
		(net "M_D_CPU1_SA_DQ<15>")
	)
	(segment
		(start 65.939416 -295.419272)
		(end 65.54216 -295.419272)
		(width 0.18288)
		(layer "In11.Cu")
		(net "M_D_CPU1_SA_DQ<15>")
	)
	(segment
		(start 46.441106 -303.862486)
		(end 46.441106 -303.014126)
		(width 0.18288)
		(layer "In11.Cu")
		(net "M_D_CPU1_SA_DQ<15>")
	)
	(segment
		(start 32.313626 -303.992026)
		(end 31.367984 -303.992026)
		(width 0.18288)
		(layer "In11.Cu")
		(net "M_D_CPU1_SA_DQ<15>")
	)
	(segment
		(start 51.465226 -303.142142)
		(end 50.210974 -303.142142)
		(width 0.18288)
		(layer "In11.Cu")
		(net "M_D_CPU1_SA_DQ<15>")
	)
	(segment
		(start 83.672426 -278.611838)
		(end 83.036918 -278.611838)
		(width 0.088646)
		(layer "In11.Cu")
		(net "M_D_CPU1_SA_DQ<15>")
	)
	(segment
		(start 59.156346 -297.136566)
		(end 58.444638 -297.136566)
		(width 0.18288)
		(layer "In11.Cu")
		(net "M_D_CPU1_SA_DQ<15>")
	)
	(segment
		(start 46.441106 -303.014126)
		(end 46.137322 -302.710342)
		(width 0.18288)
		(layer "In11.Cu")
		(net "M_D_CPU1_SA_DQ<15>")
	)
	(segment
		(start 92.211906 -275.398992)
		(end 92.201492 -275.405088)
		(width 0.088646)
		(layer "In11.Cu")
		(net "M_D_CPU1_SA_DQ<15>")
	)
	(segment
		(start 90.332306 -275.398992)
		(end 90.321892 -275.405088)
		(width 0.088646)
		(layer "In11.Cu")
		(net "M_D_CPU1_SA_DQ<15>")
	)
	(segment
		(start 85.047582 -277.236682)
		(end 83.672426 -278.611838)
		(width 0.088646)
		(layer "In11.Cu")
		(net "M_D_CPU1_SA_DQ<15>")
	)
	(segment
		(start 85.714332 -276.244558)
		(end 85.504782 -276.244558)
		(width 0.088646)
		(layer "In11.Cu")
		(net "M_D_CPU1_SA_DQ<15>")
	)
	(segment
		(start 21.50745 -299.085)
		(end 20.889214 -298.466764)
		(width 0.18288)
		(layer "In11.Cu")
		(net "M_D_CPU1_SA_DQ<15>")
	)
	(segment
		(start 40.505634 -303.276508)
		(end 40.190674 -303.276508)
		(width 0.18288)
		(layer "In11.Cu")
		(net "M_D_CPU1_SA_DQ<15>")
	)
	(segment
		(start 51.666648 -301.583852)
		(end 51.666648 -302.94072)
		(width 0.18288)
		(layer "In11.Cu")
		(net "M_D_CPU1_SA_DQ<15>")
	)
	(arc
		(start 96.900746 -275.405088)
		(mid 96.713548 -275.455231)
		(end 96.52635 -275.405088)
		(width 0.088646)
		(layer "In11.Cu")
		(net "M_D_CPU1_SA_DQ<15>")
	)
	(arc
		(start 92.76715 -275.405088)
		(mid 92.490337 -275.329252)
		(end 92.211906 -275.398992)
		(width 0.088646)
		(layer "In11.Cu")
		(net "M_D_CPU1_SA_DQ<15>")
	)
	(arc
		(start 88.067896 -275.405088)
		(mid 87.791083 -275.329252)
		(end 87.512652 -275.398992)
		(width 0.088646)
		(layer "In11.Cu")
		(net "M_D_CPU1_SA_DQ<15>")
	)
	(arc
		(start 87.127842 -275.405088)
		(mid 86.84514 -275.329346)
		(end 86.562438 -275.405088)
		(width 0.088646)
		(layer "In11.Cu")
		(net "M_D_CPU1_SA_DQ<15>")
	)
	(arc
		(start 94.64675 -275.405088)
		(mid 94.364048 -275.329346)
		(end 94.081346 -275.405088)
		(width 0.088646)
		(layer "In11.Cu")
		(net "M_D_CPU1_SA_DQ<15>")
	)
	(arc
		(start 96.52635 -275.405088)
		(mid 96.252121 -275.329163)
		(end 95.975678 -275.396452)
		(width 0.088646)
		(layer "In11.Cu")
		(net "M_D_CPU1_SA_DQ<15>")
	)
	(arc
		(start 91.261946 -275.405088)
		(mid 91.074748 -275.455231)
		(end 90.88755 -275.405088)
		(width 0.088646)
		(layer "In11.Cu")
		(net "M_D_CPU1_SA_DQ<15>")
	)
	(arc
		(start 92.201492 -275.405088)
		(mid 92.014294 -275.455231)
		(end 91.827096 -275.405088)
		(width 0.088646)
		(layer "In11.Cu")
		(net "M_D_CPU1_SA_DQ<15>")
	)
	(arc
		(start 86.562438 -275.405088)
		(mid 86.360152 -275.604069)
		(end 86.27999 -275.876258)
		(width 0.088646)
		(layer "In11.Cu")
		(net "M_D_CPU1_SA_DQ<15>")
	)
	(arc
		(start 86.092538 -276.219158)
		(mid 85.954933 -276.266003)
		(end 85.809836 -276.257004)
		(width 0.088646)
		(layer "In11.Cu")
		(net "M_D_CPU1_SA_DQ<15>")
	)
	(arc
		(start 88.442292 -275.405088)
		(mid 88.255094 -275.455231)
		(end 88.067896 -275.405088)
		(width 0.088646)
		(layer "In11.Cu")
		(net "M_D_CPU1_SA_DQ<15>")
	)
	(arc
		(start 91.827096 -275.405088)
		(mid 91.550537 -275.329379)
		(end 91.27236 -275.398992)
		(width 0.088646)
		(layer "In11.Cu")
		(net "M_D_CPU1_SA_DQ<15>")
	)
	(arc
		(start 87.502238 -275.405088)
		(mid 87.31504 -275.455231)
		(end 87.127842 -275.405088)
		(width 0.088646)
		(layer "In11.Cu")
		(net "M_D_CPU1_SA_DQ<15>")
	)
	(arc
		(start 86.27999 -275.8948)
		(mid 86.232311 -276.0777)
		(end 86.101428 -276.214078)
		(width 0.088646)
		(layer "In11.Cu")
		(net "M_D_CPU1_SA_DQ<15>")
	)
	(arc
		(start 85.809836 -276.257004)
		(mid 85.762486 -276.247694)
		(end 85.714332 -276.244558)
		(width 0.088646)
		(layer "In11.Cu")
		(net "M_D_CPU1_SA_DQ<15>")
	)
	(arc
		(start 89.007696 -275.405088)
		(mid 88.724994 -275.329346)
		(end 88.442292 -275.405088)
		(width 0.088646)
		(layer "In11.Cu")
		(net "M_D_CPU1_SA_DQ<15>")
	)
	(arc
		(start 90.321892 -275.405088)
		(mid 90.134694 -275.455231)
		(end 89.947496 -275.405088)
		(width 0.088646)
		(layer "In11.Cu")
		(net "M_D_CPU1_SA_DQ<15>")
	)
	(arc
		(start 89.382092 -275.405088)
		(mid 89.194894 -275.455231)
		(end 89.007696 -275.405088)
		(width 0.088646)
		(layer "In11.Cu")
		(net "M_D_CPU1_SA_DQ<15>")
	)
	(arc
		(start 98.780092 -275.405088)
		(mid 98.592894 -275.455231)
		(end 98.405696 -275.405088)
		(width 0.088646)
		(layer "In11.Cu")
		(net "M_D_CPU1_SA_DQ<15>")
	)
	(arc
		(start 97.46615 -275.405088)
		(mid 97.191921 -275.329163)
		(end 96.915478 -275.396452)
		(width 0.088646)
		(layer "In11.Cu")
		(net "M_D_CPU1_SA_DQ<15>")
	)
	(arc
		(start 99.624642 -275.829522)
		(mid 99.535528 -275.584225)
		(end 99.34575 -275.405088)
		(width 0.088646)
		(layer "In11.Cu")
		(net "M_D_CPU1_SA_DQ<15>")
	)
	(arc
		(start 93.70695 -275.405088)
		(mid 93.432721 -275.329163)
		(end 93.156278 -275.396452)
		(width 0.088646)
		(layer "In11.Cu")
		(net "M_D_CPU1_SA_DQ<15>")
	)
	(arc
		(start 95.58655 -275.405088)
		(mid 95.312321 -275.329163)
		(end 95.035878 -275.396452)
		(width 0.088646)
		(layer "In11.Cu")
		(net "M_D_CPU1_SA_DQ<15>")
	)
	(arc
		(start 94.081346 -275.405088)
		(mid 93.894148 -275.455231)
		(end 93.70695 -275.405088)
		(width 0.088646)
		(layer "In11.Cu")
		(net "M_D_CPU1_SA_DQ<15>")
	)
	(arc
		(start 89.947496 -275.405088)
		(mid 89.664794 -275.329346)
		(end 89.382092 -275.405088)
		(width 0.088646)
		(layer "In11.Cu")
		(net "M_D_CPU1_SA_DQ<15>")
	)
	(arc
		(start 90.88755 -275.405088)
		(mid 90.610737 -275.329252)
		(end 90.332306 -275.398992)
		(width 0.088646)
		(layer "In11.Cu")
		(net "M_D_CPU1_SA_DQ<15>")
	)
	(arc
		(start 93.141546 -275.405088)
		(mid 92.954348 -275.455231)
		(end 92.76715 -275.405088)
		(width 0.088646)
		(layer "In11.Cu")
		(net "M_D_CPU1_SA_DQ<15>")
	)
	(arc
		(start 95.021146 -275.405088)
		(mid 94.833948 -275.455231)
		(end 94.64675 -275.405088)
		(width 0.088646)
		(layer "In11.Cu")
		(net "M_D_CPU1_SA_DQ<15>")
	)
	(arc
		(start 95.960946 -275.405088)
		(mid 95.773748 -275.455231)
		(end 95.58655 -275.405088)
		(width 0.088646)
		(layer "In11.Cu")
		(net "M_D_CPU1_SA_DQ<15>")
	)
	(arc
		(start 97.840546 -275.405088)
		(mid 97.653348 -275.455231)
		(end 97.46615 -275.405088)
		(width 0.088646)
		(layer "In11.Cu")
		(net "M_D_CPU1_SA_DQ<15>")
	)
	(arc
		(start 98.405696 -275.405088)
		(mid 98.129137 -275.329379)
		(end 97.85096 -275.398992)
		(width 0.088646)
		(layer "In11.Cu")
		(net "M_D_CPU1_SA_DQ<15>")
	)
	(arc
		(start 99.34575 -275.405088)
		(mid 99.068937 -275.329252)
		(end 98.790506 -275.398992)
		(width 0.088646)
		(layer "In11.Cu")
		(net "M_D_CPU1_SA_DQ<15>")
	)
	(segment
		(start 100.472494 -276.708362)
		(end 100.472748 -276.708616)
		(width 0.20066)
		(layer "F.Cu")
		(net "M_D_CPU1_SA_DQ<14>")
	)
	(segment
		(start 17.829276 -300.378622)
		(end 18.257774 -300.378622)
		(width 0.20066)
		(layer "F.Cu")
		(net "M_D_CPU1_SA_DQ<14>")
	)
	(segment
		(start 14.560042 -299.731684)
		(end 14.570202 -299.741844)
		(width 0.101854)
		(layer "F.Cu")
		(net "M_D_CPU1_SA_DQ<14>")
	)
	(segment
		(start 13.82268 -299.731684)
		(end 14.560042 -299.731684)
		(width 0.20066)
		(layer "F.Cu")
		(net "M_D_CPU1_SA_DQ<14>")
	)
	(segment
		(start 14.825218 -299.741844)
		(end 16.885158 -299.741844)
		(width 0.1016)
		(layer "F.Cu")
		(net "M_D_CPU1_SA_DQ<14>")
	)
	(segment
		(start 16.885158 -299.741844)
		(end 17.518126 -299.741844)
		(width 0.20066)
		(layer "F.Cu")
		(net "M_D_CPU1_SA_DQ<14>")
	)
	(segment
		(start 18.257774 -300.378622)
		(end 18.46961 -300.166786)
		(width 0.20066)
		(layer "F.Cu")
		(net "M_D_CPU1_SA_DQ<14>")
	)
	(segment
		(start 17.518126 -299.741844)
		(end 17.66189 -299.885608)
		(width 0.20066)
		(layer "F.Cu")
		(net "M_D_CPU1_SA_DQ<14>")
	)
	(segment
		(start 20.889214 -300.166786)
		(end 19.784314 -300.166786)
		(width 0.20066)
		(layer "F.Cu")
		(net "M_D_CPU1_SA_DQ<14>")
	)
	(segment
		(start 17.66189 -299.885608)
		(end 17.66189 -300.211236)
		(width 0.20066)
		(layer "F.Cu")
		(net "M_D_CPU1_SA_DQ<14>")
	)
	(segment
		(start 100.472494 -276.172676)
		(end 100.472494 -276.708362)
		(width 0.20066)
		(layer "F.Cu")
		(net "M_D_CPU1_SA_DQ<14>")
	)
	(segment
		(start 13.387578 -300.166786)
		(end 13.82268 -299.731684)
		(width 0.20066)
		(layer "F.Cu")
		(net "M_D_CPU1_SA_DQ<14>")
	)
	(segment
		(start 18.46961 -300.166786)
		(end 19.784314 -300.166786)
		(width 0.20066)
		(layer "F.Cu")
		(net "M_D_CPU1_SA_DQ<14>")
	)
	(segment
		(start 12.240514 -300.166786)
		(end 13.387578 -300.166786)
		(width 0.20066)
		(layer "F.Cu")
		(net "M_D_CPU1_SA_DQ<14>")
	)
	(segment
		(start 17.66189 -300.211236)
		(end 17.829276 -300.378622)
		(width 0.20066)
		(layer "F.Cu")
		(net "M_D_CPU1_SA_DQ<14>")
	)
	(segment
		(start 14.570202 -299.741844)
		(end 14.825218 -299.741844)
		(width 0.101854)
		(layer "F.Cu")
		(net "M_D_CPU1_SA_DQ<14>")
	)
	(segment
		(start 55.986426 -300.486826)
		(end 55.249826 -301.223426)
		(width 0.18288)
		(layer "In11.Cu")
		(net "M_D_CPU1_SA_DQ<14>")
	)
	(segment
		(start 21.486622 -300.764194)
		(end 20.889214 -300.166786)
		(width 0.18288)
		(layer "In11.Cu")
		(net "M_D_CPU1_SA_DQ<14>")
	)
	(segment
		(start 25.265126 -302.010826)
		(end 24.475186 -301.220886)
		(width 0.18288)
		(layer "In11.Cu")
		(net "M_D_CPU1_SA_DQ<14>")
	)
	(segment
		(start 29.522674 -304.928016)
		(end 28.716986 -304.122328)
		(width 0.18288)
		(layer "In11.Cu")
		(net "M_D_CPU1_SA_DQ<14>")
	)
	(segment
		(start 42.106088 -305.579018)
		(end 41.913048 -305.772058)
		(width 0.18288)
		(layer "In11.Cu")
		(net "M_D_CPU1_SA_DQ<14>")
	)
	(segment
		(start 53.911754 -301.791878)
		(end 53.911754 -302.064674)
		(width 0.18288)
		(layer "In11.Cu")
		(net "M_D_CPU1_SA_DQ<14>")
	)
	(segment
		(start 42.299128 -304.704496)
		(end 42.106088 -304.897536)
		(width 0.18288)
		(layer "In11.Cu")
		(net "M_D_CPU1_SA_DQ<14>")
	)
	(segment
		(start 51.550062 -304.978308)
		(end 51.41341 -304.841656)
		(width 0.18288)
		(layer "In11.Cu")
		(net "M_D_CPU1_SA_DQ<14>")
	)
	(segment
		(start 54.480206 -301.223426)
		(end 53.911754 -301.791878)
		(width 0.18288)
		(layer "In11.Cu")
		(net "M_D_CPU1_SA_DQ<14>")
	)
	(segment
		(start 58.335926 -298.835826)
		(end 56.684926 -300.486826)
		(width 0.18288)
		(layer "In11.Cu")
		(net "M_D_CPU1_SA_DQ<14>")
	)
	(segment
		(start 95.116396 -276.219158)
		(end 95.105982 -276.213062)
		(width 0.088646)
		(layer "In11.Cu")
		(net "M_D_CPU1_SA_DQ<14>")
	)
	(segment
		(start 86.750144 -276.693122)
		(end 86.750144 -276.708616)
		(width 0.088646)
		(layer "In11.Cu")
		(net "M_D_CPU1_SA_DQ<14>")
	)
	(segment
		(start 52.434744 -304.978308)
		(end 51.550062 -304.978308)
		(width 0.18288)
		(layer "In11.Cu")
		(net "M_D_CPU1_SA_DQ<14>")
	)
	(segment
		(start 88.537796 -276.219158)
		(end 88.527382 -276.213062)
		(width 0.088646)
		(layer "In11.Cu")
		(net "M_D_CPU1_SA_DQ<14>")
	)
	(segment
		(start 85.446108 -277.10638)
		(end 85.446108 -277.427436)
		(width 0.088646)
		(layer "In11.Cu")
		(net "M_D_CPU1_SA_DQ<14>")
	)
	(segment
		(start 33.136586 -306.018946)
		(end 32.565086 -306.018946)
		(width 0.18288)
		(layer "In11.Cu")
		(net "M_D_CPU1_SA_DQ<14>")
	)
	(segment
		(start 85.59546 -276.957028)
		(end 85.446108 -277.10638)
		(width 0.088646)
		(layer "In11.Cu")
		(net "M_D_CPU1_SA_DQ<14>")
	)
	(segment
		(start 52.913026 -302.790606)
		(end 52.913026 -304.500026)
		(width 0.18288)
		(layer "In11.Cu")
		(net "M_D_CPU1_SA_DQ<14>")
	)
	(segment
		(start 62.877446 -297.888406)
		(end 61.216286 -297.888406)
		(width 0.18288)
		(layer "In11.Cu")
		(net "M_D_CPU1_SA_DQ<14>")
	)
	(segment
		(start 65.393062 -297.073066)
		(end 64.290702 -298.175426)
		(width 0.18288)
		(layer "In11.Cu")
		(net "M_D_CPU1_SA_DQ<14>")
	)
	(segment
		(start 96.056196 -276.219158)
		(end 96.041464 -276.210522)
		(width 0.088646)
		(layer "In11.Cu")
		(net "M_D_CPU1_SA_DQ<14>")
	)
	(segment
		(start 54.171088 -303.042828)
		(end 53.898292 -303.042828)
		(width 0.18288)
		(layer "In11.Cu")
		(net "M_D_CPU1_SA_DQ<14>")
	)
	(segment
		(start 67.191128 -296.621454)
		(end 66.739516 -297.073066)
		(width 0.18288)
		(layer "In11.Cu")
		(net "M_D_CPU1_SA_DQ<14>")
	)
	(segment
		(start 99.914202 -276.27707)
		(end 99.800664 -276.210522)
		(width 0.088646)
		(layer "In11.Cu")
		(net "M_D_CPU1_SA_DQ<14>")
	)
	(segment
		(start 23.636986 -301.220886)
		(end 23.180294 -300.764194)
		(width 0.18288)
		(layer "In11.Cu")
		(net "M_D_CPU1_SA_DQ<14>")
	)
	(segment
		(start 36.465256 -304.841656)
		(end 35.582352 -304.841656)
		(width 0.18288)
		(layer "In11.Cu")
		(net "M_D_CPU1_SA_DQ<14>")
	)
	(segment
		(start 35.582352 -304.841656)
		(end 35.418522 -304.677826)
		(width 0.18288)
		(layer "In11.Cu")
		(net "M_D_CPU1_SA_DQ<14>")
	)
	(segment
		(start 63.164466 -298.175426)
		(end 62.877446 -297.888406)
		(width 0.18288)
		(layer "In11.Cu")
		(net "M_D_CPU1_SA_DQ<14>")
	)
	(segment
		(start 55.249826 -301.223426)
		(end 54.480206 -301.223426)
		(width 0.18288)
		(layer "In11.Cu")
		(net "M_D_CPU1_SA_DQ<14>")
	)
	(segment
		(start 86.571582 -277.027894)
		(end 86.562692 -277.032974)
		(width 0.088646)
		(layer "In11.Cu")
		(net "M_D_CPU1_SA_DQ<14>")
	)
	(segment
		(start 29.972508 -305.69154)
		(end 29.522674 -305.241706)
		(width 0.18288)
		(layer "In11.Cu")
		(net "M_D_CPU1_SA_DQ<14>")
	)
	(segment
		(start 43.000168 -305.772058)
		(end 42.807128 -305.579018)
		(width 0.18288)
		(layer "In11.Cu")
		(net "M_D_CPU1_SA_DQ<14>")
	)
	(segment
		(start 40.673782 -305.772058)
		(end 39.93642 -305.034696)
		(width 0.18288)
		(layer "In11.Cu")
		(net "M_D_CPU1_SA_DQ<14>")
	)
	(segment
		(start 33.482026 -304.677826)
		(end 33.149286 -305.010566)
		(width 0.18288)
		(layer "In11.Cu")
		(net "M_D_CPU1_SA_DQ<14>")
	)
	(segment
		(start 30.292294 -305.69154)
		(end 29.972508 -305.69154)
		(width 0.18288)
		(layer "In11.Cu")
		(net "M_D_CPU1_SA_DQ<14>")
	)
	(segment
		(start 60.119006 -298.985686)
		(end 59.499246 -298.985686)
		(width 0.18288)
		(layer "In11.Cu")
		(net "M_D_CPU1_SA_DQ<14>")
	)
	(segment
		(start 35.418522 -304.677826)
		(end 33.482026 -304.677826)
		(width 0.18288)
		(layer "In11.Cu")
		(net "M_D_CPU1_SA_DQ<14>")
	)
	(segment
		(start 47.78502 -305.69154)
		(end 46.232826 -305.69154)
		(width 0.18288)
		(layer "In11.Cu")
		(net "M_D_CPU1_SA_DQ<14>")
	)
	(segment
		(start 93.236796 -276.219158)
		(end 93.222064 -276.210522)
		(width 0.088646)
		(layer "In11.Cu")
		(net "M_D_CPU1_SA_DQ<14>")
	)
	(segment
		(start 53.415946 -302.560482)
		(end 53.14315 -302.560482)
		(width 0.18288)
		(layer "In11.Cu")
		(net "M_D_CPU1_SA_DQ<14>")
	)
	(segment
		(start 42.614088 -304.704496)
		(end 42.299128 -304.704496)
		(width 0.18288)
		(layer "In11.Cu")
		(net "M_D_CPU1_SA_DQ<14>")
	)
	(segment
		(start 94.17685 -276.219158)
		(end 94.166436 -276.213062)
		(width 0.088646)
		(layer "In11.Cu")
		(net "M_D_CPU1_SA_DQ<14>")
	)
	(segment
		(start 53.911754 -302.064674)
		(end 54.3941 -302.54702)
		(width 0.18288)
		(layer "In11.Cu")
		(net "M_D_CPU1_SA_DQ<14>")
	)
	(segment
		(start 83.250786 -279.837896)
		(end 82.381852 -279.837896)
		(width 0.18288)
		(layer "In11.Cu")
		(net "M_D_CPU1_SA_DQ<14>")
	)
	(segment
		(start 29.522674 -305.241706)
		(end 29.522674 -304.928016)
		(width 0.18288)
		(layer "In11.Cu")
		(net "M_D_CPU1_SA_DQ<14>")
	)
	(segment
		(start 46.232826 -305.69154)
		(end 45.536612 -304.995326)
		(width 0.18288)
		(layer "In11.Cu")
		(net "M_D_CPU1_SA_DQ<14>")
	)
	(segment
		(start 59.349386 -298.835826)
		(end 58.335926 -298.835826)
		(width 0.18288)
		(layer "In11.Cu")
		(net "M_D_CPU1_SA_DQ<14>")
	)
	(segment
		(start 43.716194 -305.772058)
		(end 43.000168 -305.772058)
		(width 0.18288)
		(layer "In11.Cu")
		(net "M_D_CPU1_SA_DQ<14>")
	)
	(segment
		(start 49.048924 -305.828192)
		(end 47.921672 -305.828192)
		(width 0.18288)
		(layer "In11.Cu")
		(net "M_D_CPU1_SA_DQ<14>")
	)
	(segment
		(start 52.913026 -304.500026)
		(end 52.434744 -304.978308)
		(width 0.18288)
		(layer "In11.Cu")
		(net "M_D_CPU1_SA_DQ<14>")
	)
	(segment
		(start 64.290702 -298.175426)
		(end 63.164466 -298.175426)
		(width 0.18288)
		(layer "In11.Cu")
		(net "M_D_CPU1_SA_DQ<14>")
	)
	(segment
		(start 33.294066 -305.861466)
		(end 33.136586 -306.018946)
		(width 0.18288)
		(layer "In11.Cu")
		(net "M_D_CPU1_SA_DQ<14>")
	)
	(segment
		(start 39.93642 -305.034696)
		(end 36.658296 -305.034696)
		(width 0.18288)
		(layer "In11.Cu")
		(net "M_D_CPU1_SA_DQ<14>")
	)
	(segment
		(start 41.913048 -305.772058)
		(end 40.673782 -305.772058)
		(width 0.18288)
		(layer "In11.Cu")
		(net "M_D_CPU1_SA_DQ<14>")
	)
	(segment
		(start 42.106088 -304.897536)
		(end 42.106088 -305.579018)
		(width 0.18288)
		(layer "In11.Cu")
		(net "M_D_CPU1_SA_DQ<14>")
	)
	(segment
		(start 61.216286 -297.888406)
		(end 60.119006 -298.985686)
		(width 0.18288)
		(layer "In11.Cu")
		(net "M_D_CPU1_SA_DQ<14>")
	)
	(segment
		(start 96.995996 -276.219158)
		(end 96.981264 -276.210522)
		(width 0.088646)
		(layer "In11.Cu")
		(net "M_D_CPU1_SA_DQ<14>")
	)
	(segment
		(start 33.149286 -305.424586)
		(end 33.294066 -305.569366)
		(width 0.18288)
		(layer "In11.Cu")
		(net "M_D_CPU1_SA_DQ<14>")
	)
	(segment
		(start 59.499246 -298.985686)
		(end 59.349386 -298.835826)
		(width 0.18288)
		(layer "In11.Cu")
		(net "M_D_CPU1_SA_DQ<14>")
	)
	(segment
		(start 83.868768 -279.004776)
		(end 83.868768 -279.219914)
		(width 0.088646)
		(layer "In11.Cu")
		(net "M_D_CPU1_SA_DQ<14>")
	)
	(segment
		(start 87.597742 -276.219158)
		(end 87.58301 -276.210522)
		(width 0.088646)
		(layer "In11.Cu")
		(net "M_D_CPU1_SA_DQ<14>")
	)
	(segment
		(start 44.492926 -304.995326)
		(end 43.716194 -305.772058)
		(width 0.18288)
		(layer "In11.Cu")
		(net "M_D_CPU1_SA_DQ<14>")
	)
	(segment
		(start 56.684926 -300.486826)
		(end 55.986426 -300.486826)
		(width 0.18288)
		(layer "In11.Cu")
		(net "M_D_CPU1_SA_DQ<14>")
	)
	(segment
		(start 27.965146 -303.306226)
		(end 26.669746 -302.010826)
		(width 0.18288)
		(layer "In11.Cu")
		(net "M_D_CPU1_SA_DQ<14>")
	)
	(segment
		(start 31.186374 -306.078636)
		(end 30.993334 -306.271676)
		(width 0.18288)
		(layer "In11.Cu")
		(net "M_D_CPU1_SA_DQ<14>")
	)
	(segment
		(start 24.475186 -301.220886)
		(end 23.636986 -301.220886)
		(width 0.18288)
		(layer "In11.Cu")
		(net "M_D_CPU1_SA_DQ<14>")
	)
	(segment
		(start 36.658296 -305.034696)
		(end 36.465256 -304.841656)
		(width 0.18288)
		(layer "In11.Cu")
		(net "M_D_CPU1_SA_DQ<14>")
	)
	(segment
		(start 53.14315 -302.560482)
		(end 52.913026 -302.790606)
		(width 0.18288)
		(layer "In11.Cu")
		(net "M_D_CPU1_SA_DQ<14>")
	)
	(segment
		(start 83.868768 -279.219914)
		(end 83.636866 -279.451816)
		(width 0.088646)
		(layer "In11.Cu")
		(net "M_D_CPU1_SA_DQ<14>")
	)
	(segment
		(start 30.678374 -306.271676)
		(end 30.485334 -306.078636)
		(width 0.18288)
		(layer "In11.Cu")
		(net "M_D_CPU1_SA_DQ<14>")
	)
	(segment
		(start 51.41341 -304.841656)
		(end 50.623216 -304.841656)
		(width 0.18288)
		(layer "In11.Cu")
		(net "M_D_CPU1_SA_DQ<14>")
	)
	(segment
		(start 47.921672 -305.828192)
		(end 47.78502 -305.69154)
		(width 0.18288)
		(layer "In11.Cu")
		(net "M_D_CPU1_SA_DQ<14>")
	)
	(segment
		(start 50.623216 -304.841656)
		(end 50.052224 -305.412648)
		(width 0.18288)
		(layer "In11.Cu")
		(net "M_D_CPU1_SA_DQ<14>")
	)
	(segment
		(start 85.446108 -277.427436)
		(end 83.868768 -279.004776)
		(width 0.088646)
		(layer "In11.Cu")
		(net "M_D_CPU1_SA_DQ<14>")
	)
	(segment
		(start 67.191128 -295.7322)
		(end 67.191128 -296.621454)
		(width 0.18288)
		(layer "In11.Cu")
		(net "M_D_CPU1_SA_DQ<14>")
	)
	(segment
		(start 50.052224 -305.412648)
		(end 49.048924 -305.828192)
		(width 0.18288)
		(layer "In11.Cu")
		(net "M_D_CPU1_SA_DQ<14>")
	)
	(segment
		(start 30.485334 -305.88458)
		(end 30.292294 -305.69154)
		(width 0.18288)
		(layer "In11.Cu")
		(net "M_D_CPU1_SA_DQ<14>")
	)
	(segment
		(start 30.485334 -306.078636)
		(end 30.485334 -305.88458)
		(width 0.18288)
		(layer "In11.Cu")
		(net "M_D_CPU1_SA_DQ<14>")
	)
	(segment
		(start 92.296996 -276.219158)
		(end 92.282264 -276.210522)
		(width 0.088646)
		(layer "In11.Cu")
		(net "M_D_CPU1_SA_DQ<14>")
	)
	(segment
		(start 31.379414 -305.69154)
		(end 31.186374 -305.88458)
		(width 0.18288)
		(layer "In11.Cu")
		(net "M_D_CPU1_SA_DQ<14>")
	)
	(segment
		(start 31.186374 -305.88458)
		(end 31.186374 -306.078636)
		(width 0.18288)
		(layer "In11.Cu")
		(net "M_D_CPU1_SA_DQ<14>")
	)
	(segment
		(start 33.294066 -305.569366)
		(end 33.294066 -305.861466)
		(width 0.18288)
		(layer "In11.Cu")
		(net "M_D_CPU1_SA_DQ<14>")
	)
	(segment
		(start 32.565086 -306.018946)
		(end 32.23768 -305.69154)
		(width 0.18288)
		(layer "In11.Cu")
		(net "M_D_CPU1_SA_DQ<14>")
	)
	(segment
		(start 66.739516 -297.073066)
		(end 65.393062 -297.073066)
		(width 0.18288)
		(layer "In11.Cu")
		(net "M_D_CPU1_SA_DQ<14>")
	)
	(segment
		(start 82.381852 -279.837896)
		(end 70.933056 -291.286692)
		(width 0.18288)
		(layer "In11.Cu")
		(net "M_D_CPU1_SA_DQ<14>")
	)
	(segment
		(start 28.324048 -304.122328)
		(end 27.965146 -303.763426)
		(width 0.18288)
		(layer "In11.Cu")
		(net "M_D_CPU1_SA_DQ<14>")
	)
	(segment
		(start 27.965146 -303.763426)
		(end 27.965146 -303.306226)
		(width 0.18288)
		(layer "In11.Cu")
		(net "M_D_CPU1_SA_DQ<14>")
	)
	(segment
		(start 26.669746 -302.010826)
		(end 25.265126 -302.010826)
		(width 0.18288)
		(layer "In11.Cu")
		(net "M_D_CPU1_SA_DQ<14>")
	)
	(segment
		(start 70.933056 -291.286692)
		(end 70.933056 -291.990272)
		(width 0.18288)
		(layer "In11.Cu")
		(net "M_D_CPU1_SA_DQ<14>")
	)
	(segment
		(start 53.898292 -303.042828)
		(end 53.415946 -302.560482)
		(width 0.18288)
		(layer "In11.Cu")
		(net "M_D_CPU1_SA_DQ<14>")
	)
	(segment
		(start 33.149286 -305.010566)
		(end 33.149286 -305.424586)
		(width 0.18288)
		(layer "In11.Cu")
		(net "M_D_CPU1_SA_DQ<14>")
	)
	(segment
		(start 42.807128 -305.579018)
		(end 42.807128 -304.897536)
		(width 0.18288)
		(layer "In11.Cu")
		(net "M_D_CPU1_SA_DQ<14>")
	)
	(segment
		(start 98.875596 -276.219158)
		(end 98.860864 -276.210522)
		(width 0.088646)
		(layer "In11.Cu")
		(net "M_D_CPU1_SA_DQ<14>")
	)
	(segment
		(start 54.3941 -302.54702)
		(end 54.3941 -302.819816)
		(width 0.18288)
		(layer "In11.Cu")
		(net "M_D_CPU1_SA_DQ<14>")
	)
	(segment
		(start 70.933056 -291.990272)
		(end 67.191128 -295.7322)
		(width 0.18288)
		(layer "In11.Cu")
		(net "M_D_CPU1_SA_DQ<14>")
	)
	(segment
		(start 83.636866 -279.451816)
		(end 83.250786 -279.837896)
		(width 0.18288)
		(layer "In11.Cu")
		(net "M_D_CPU1_SA_DQ<14>")
	)
	(segment
		(start 23.180294 -300.764194)
		(end 21.486622 -300.764194)
		(width 0.18288)
		(layer "In11.Cu")
		(net "M_D_CPU1_SA_DQ<14>")
	)
	(segment
		(start 85.90534 -276.957028)
		(end 85.59546 -276.957028)
		(width 0.088646)
		(layer "In11.Cu")
		(net "M_D_CPU1_SA_DQ<14>")
	)
	(segment
		(start 32.23768 -305.69154)
		(end 31.379414 -305.69154)
		(width 0.18288)
		(layer "In11.Cu")
		(net "M_D_CPU1_SA_DQ<14>")
	)
	(segment
		(start 30.993334 -306.271676)
		(end 30.678374 -306.271676)
		(width 0.18288)
		(layer "In11.Cu")
		(net "M_D_CPU1_SA_DQ<14>")
	)
	(segment
		(start 54.3941 -302.819816)
		(end 54.171088 -303.042828)
		(width 0.18288)
		(layer "In11.Cu")
		(net "M_D_CPU1_SA_DQ<14>")
	)
	(segment
		(start 45.536612 -304.995326)
		(end 44.492926 -304.995326)
		(width 0.18288)
		(layer "In11.Cu")
		(net "M_D_CPU1_SA_DQ<14>")
	)
	(segment
		(start 28.716986 -304.122328)
		(end 28.324048 -304.122328)
		(width 0.18288)
		(layer "In11.Cu")
		(net "M_D_CPU1_SA_DQ<14>")
	)
	(segment
		(start 42.807128 -304.897536)
		(end 42.614088 -304.704496)
		(width 0.18288)
		(layer "In11.Cu")
		(net "M_D_CPU1_SA_DQ<14>")
	)
	(arc
		(start 97.935796 -276.219158)
		(mid 97.653094 -276.143382)
		(end 97.370392 -276.219158)
		(width 0.088646)
		(layer "In11.Cu")
		(net "M_D_CPU1_SA_DQ<14>")
	)
	(arc
		(start 96.430592 -276.219158)
		(mid 96.243394 -276.269301)
		(end 96.056196 -276.219158)
		(width 0.088646)
		(layer "In11.Cu")
		(net "M_D_CPU1_SA_DQ<14>")
	)
	(arc
		(start 91.357196 -276.219158)
		(mid 91.074494 -276.143382)
		(end 90.791792 -276.219158)
		(width 0.088646)
		(layer "In11.Cu")
		(net "M_D_CPU1_SA_DQ<14>")
	)
	(arc
		(start 88.912192 -276.219158)
		(mid 88.724994 -276.269301)
		(end 88.537796 -276.219158)
		(width 0.088646)
		(layer "In11.Cu")
		(net "M_D_CPU1_SA_DQ<14>")
	)
	(arc
		(start 99.800664 -276.210522)
		(mid 99.524189 -276.143202)
		(end 99.249992 -276.219158)
		(width 0.088646)
		(layer "In11.Cu")
		(net "M_D_CPU1_SA_DQ<14>")
	)
	(arc
		(start 91.731592 -276.219158)
		(mid 91.544394 -276.269301)
		(end 91.357196 -276.219158)
		(width 0.088646)
		(layer "In11.Cu")
		(net "M_D_CPU1_SA_DQ<14>")
	)
	(arc
		(start 87.58301 -276.210522)
		(mid 87.306535 -276.143202)
		(end 87.032338 -276.219158)
		(width 0.088646)
		(layer "In11.Cu")
		(net "M_D_CPU1_SA_DQ<14>")
	)
	(arc
		(start 89.477596 -276.219158)
		(mid 89.194894 -276.143382)
		(end 88.912192 -276.219158)
		(width 0.088646)
		(layer "In11.Cu")
		(net "M_D_CPU1_SA_DQ<14>")
	)
	(arc
		(start 98.860864 -276.210522)
		(mid 98.584389 -276.143202)
		(end 98.310192 -276.219158)
		(width 0.088646)
		(layer "In11.Cu")
		(net "M_D_CPU1_SA_DQ<14>")
	)
	(arc
		(start 86.750144 -276.708616)
		(mid 86.702465 -276.891516)
		(end 86.571582 -277.027894)
		(width 0.088646)
		(layer "In11.Cu")
		(net "M_D_CPU1_SA_DQ<14>")
	)
	(arc
		(start 86.562692 -277.032974)
		(mid 86.375494 -277.083117)
		(end 86.188296 -277.032974)
		(width 0.088646)
		(layer "In11.Cu")
		(net "M_D_CPU1_SA_DQ<14>")
	)
	(arc
		(start 87.972138 -276.219158)
		(mid 87.78494 -276.269301)
		(end 87.597742 -276.219158)
		(width 0.088646)
		(layer "In11.Cu")
		(net "M_D_CPU1_SA_DQ<14>")
	)
	(arc
		(start 93.222064 -276.210522)
		(mid 92.945589 -276.143202)
		(end 92.671392 -276.219158)
		(width 0.088646)
		(layer "In11.Cu")
		(net "M_D_CPU1_SA_DQ<14>")
	)
	(arc
		(start 86.188296 -277.032974)
		(mid 86.051823 -276.97634)
		(end 85.90534 -276.957028)
		(width 0.088646)
		(layer "In11.Cu")
		(net "M_D_CPU1_SA_DQ<14>")
	)
	(arc
		(start 96.041464 -276.210522)
		(mid 95.764989 -276.143202)
		(end 95.490792 -276.219158)
		(width 0.088646)
		(layer "In11.Cu")
		(net "M_D_CPU1_SA_DQ<14>")
	)
	(arc
		(start 97.370392 -276.219158)
		(mid 97.183194 -276.269301)
		(end 96.995996 -276.219158)
		(width 0.088646)
		(layer "In11.Cu")
		(net "M_D_CPU1_SA_DQ<14>")
	)
	(arc
		(start 90.791792 -276.219158)
		(mid 90.604594 -276.269301)
		(end 90.417396 -276.219158)
		(width 0.088646)
		(layer "In11.Cu")
		(net "M_D_CPU1_SA_DQ<14>")
	)
	(arc
		(start 95.490792 -276.219158)
		(mid 95.303594 -276.269301)
		(end 95.116396 -276.219158)
		(width 0.088646)
		(layer "In11.Cu")
		(net "M_D_CPU1_SA_DQ<14>")
	)
	(arc
		(start 95.105982 -276.213062)
		(mid 94.827804 -276.143339)
		(end 94.551246 -276.219158)
		(width 0.088646)
		(layer "In11.Cu")
		(net "M_D_CPU1_SA_DQ<14>")
	)
	(arc
		(start 92.671392 -276.219158)
		(mid 92.484194 -276.269301)
		(end 92.296996 -276.219158)
		(width 0.088646)
		(layer "In11.Cu")
		(net "M_D_CPU1_SA_DQ<14>")
	)
	(arc
		(start 93.611192 -276.219158)
		(mid 93.423994 -276.269301)
		(end 93.236796 -276.219158)
		(width 0.088646)
		(layer "In11.Cu")
		(net "M_D_CPU1_SA_DQ<14>")
	)
	(arc
		(start 88.527382 -276.213062)
		(mid 88.24895 -276.143216)
		(end 87.972138 -276.219158)
		(width 0.088646)
		(layer "In11.Cu")
		(net "M_D_CPU1_SA_DQ<14>")
	)
	(arc
		(start 99.249992 -276.219158)
		(mid 99.062794 -276.269301)
		(end 98.875596 -276.219158)
		(width 0.088646)
		(layer "In11.Cu")
		(net "M_D_CPU1_SA_DQ<14>")
	)
	(arc
		(start 98.310192 -276.219158)
		(mid 98.122994 -276.269301)
		(end 97.935796 -276.219158)
		(width 0.088646)
		(layer "In11.Cu")
		(net "M_D_CPU1_SA_DQ<14>")
	)
	(arc
		(start 96.981264 -276.210522)
		(mid 96.704789 -276.143202)
		(end 96.430592 -276.219158)
		(width 0.088646)
		(layer "In11.Cu")
		(net "M_D_CPU1_SA_DQ<14>")
	)
	(arc
		(start 90.417396 -276.219158)
		(mid 90.134694 -276.143382)
		(end 89.851992 -276.219158)
		(width 0.088646)
		(layer "In11.Cu")
		(net "M_D_CPU1_SA_DQ<14>")
	)
	(arc
		(start 89.851992 -276.219158)
		(mid 89.664794 -276.269301)
		(end 89.477596 -276.219158)
		(width 0.088646)
		(layer "In11.Cu")
		(net "M_D_CPU1_SA_DQ<14>")
	)
	(arc
		(start 94.166436 -276.213062)
		(mid 93.888004 -276.143216)
		(end 93.611192 -276.219158)
		(width 0.088646)
		(layer "In11.Cu")
		(net "M_D_CPU1_SA_DQ<14>")
	)
	(arc
		(start 92.282264 -276.210522)
		(mid 92.005789 -276.143202)
		(end 91.731592 -276.219158)
		(width 0.088646)
		(layer "In11.Cu")
		(net "M_D_CPU1_SA_DQ<14>")
	)
	(arc
		(start 100.472748 -276.708616)
		(mid 100.207257 -276.475005)
		(end 99.914202 -276.27707)
		(width 0.088646)
		(layer "In11.Cu")
		(net "M_D_CPU1_SA_DQ<14>")
	)
	(arc
		(start 87.032338 -276.219158)
		(mid 86.829515 -276.419389)
		(end 86.750144 -276.693122)
		(width 0.088646)
		(layer "In11.Cu")
		(net "M_D_CPU1_SA_DQ<14>")
	)
	(arc
		(start 94.551246 -276.219158)
		(mid 94.364048 -276.269301)
		(end 94.17685 -276.219158)
		(width 0.088646)
		(layer "In11.Cu")
		(net "M_D_CPU1_SA_DQ<14>")
	)
	(segment
		(start 9.474708 -299.316648)
		(end 9.686036 -299.527976)
		(width 0.20066)
		(layer "F.Cu")
		(net "M_D_CPU1_SA_DQ<13>")
	)
	(segment
		(start 10.19048 -299.527976)
		(end 10.344912 -299.373544)
		(width 0.20066)
		(layer "F.Cu")
		(net "M_D_CPU1_SA_DQ<13>")
	)
	(segment
		(start 9.686036 -299.527976)
		(end 10.19048 -299.527976)
		(width 0.20066)
		(layer "F.Cu")
		(net "M_D_CPU1_SA_DQ<13>")
	)
	(segment
		(start 15.684246 -299.316648)
		(end 16.789146 -299.316648)
		(width 0.20066)
		(layer "F.Cu")
		(net "M_D_CPU1_SA_DQ<13>")
	)
	(segment
		(start 13.619988 -298.891706)
		(end 14.04493 -299.316648)
		(width 0.20066)
		(layer "F.Cu")
		(net "M_D_CPU1_SA_DQ<13>")
	)
	(segment
		(start 14.04493 -299.316648)
		(end 15.684246 -299.316648)
		(width 0.20066)
		(layer "F.Cu")
		(net "M_D_CPU1_SA_DQ<13>")
	)
	(segment
		(start 10.344912 -299.373544)
		(end 10.344912 -299.045376)
		(width 0.20066)
		(layer "F.Cu")
		(net "M_D_CPU1_SA_DQ<13>")
	)
	(segment
		(start 11.11631 -298.882816)
		(end 11.1252 -298.891706)
		(width 0.1016)
		(layer "F.Cu")
		(net "M_D_CPU1_SA_DQ<13>")
	)
	(segment
		(start 10.344912 -299.045376)
		(end 10.507472 -298.882816)
		(width 0.20066)
		(layer "F.Cu")
		(net "M_D_CPU1_SA_DQ<13>")
	)
	(segment
		(start 10.507472 -298.882816)
		(end 11.11631 -298.882816)
		(width 0.20066)
		(layer "F.Cu")
		(net "M_D_CPU1_SA_DQ<13>")
	)
	(segment
		(start 13.110718 -298.891706)
		(end 13.441426 -298.891706)
		(width 0.101854)
		(layer "F.Cu")
		(net "M_D_CPU1_SA_DQ<13>")
	)
	(segment
		(start 8.140446 -299.316648)
		(end 9.474708 -299.316648)
		(width 0.20066)
		(layer "F.Cu")
		(net "M_D_CPU1_SA_DQ<13>")
	)
	(segment
		(start 13.441426 -298.891706)
		(end 13.619988 -298.891706)
		(width 0.20066)
		(layer "F.Cu")
		(net "M_D_CPU1_SA_DQ<13>")
	)
	(segment
		(start 11.1252 -298.891706)
		(end 13.110718 -298.891706)
		(width 0.1016)
		(layer "F.Cu")
		(net "M_D_CPU1_SA_DQ<13>")
	)
	(arc
		(start 99.063048 -275.35886)
		(mid 99.062984 -275.62683)
		(end 99.062794 -275.8948)
		(width 0.20066)
		(layer "F.Cu")
		(net "M_D_CPU1_SA_DQ<13>")
	)
	(segment
		(start 62.554866 -297.248326)
		(end 61.124846 -297.248326)
		(width 0.18288)
		(layer "In11.Cu")
		(net "M_D_CPU1_SA_DQ<13>")
	)
	(segment
		(start 64.68237 -297.007026)
		(end 62.796166 -297.007026)
		(width 0.18288)
		(layer "In11.Cu")
		(net "M_D_CPU1_SA_DQ<13>")
	)
	(segment
		(start 45.342302 -303.951386)
		(end 44.114466 -303.951386)
		(width 0.18288)
		(layer "In11.Cu")
		(net "M_D_CPU1_SA_DQ<13>")
	)
	(segment
		(start 85.237828 -277.021036)
		(end 85.237828 -277.315676)
		(width 0.088646)
		(layer "In11.Cu")
		(net "M_D_CPU1_SA_DQ<13>")
	)
	(segment
		(start 36.702746 -303.793906)
		(end 36.504626 -303.992026)
		(width 0.18288)
		(layer "In11.Cu")
		(net "M_D_CPU1_SA_DQ<13>")
	)
	(segment
		(start 19.07794 -299.901864)
		(end 18.76298 -299.901864)
		(width 0.18288)
		(layer "In11.Cu")
		(net "M_D_CPU1_SA_DQ<13>")
	)
	(segment
		(start 24.726646 -300.679866)
		(end 23.959566 -300.679866)
		(width 0.18288)
		(layer "In11.Cu")
		(net "M_D_CPU1_SA_DQ<13>")
	)
	(segment
		(start 86.657942 -275.570442)
		(end 86.649052 -275.575522)
		(width 0.088646)
		(layer "In11.Cu")
		(net "M_D_CPU1_SA_DQ<13>")
	)
	(segment
		(start 44.114466 -303.951386)
		(end 43.954446 -304.111406)
		(width 0.18288)
		(layer "In11.Cu")
		(net "M_D_CPU1_SA_DQ<13>")
	)
	(segment
		(start 60.428886 -297.944286)
		(end 59.471306 -297.944286)
		(width 0.18288)
		(layer "In11.Cu")
		(net "M_D_CPU1_SA_DQ<13>")
	)
	(segment
		(start 65.29197 -296.397426)
		(end 64.68237 -297.007026)
		(width 0.18288)
		(layer "In11.Cu")
		(net "M_D_CPU1_SA_DQ<13>")
	)
	(segment
		(start 58.145426 -298.287186)
		(end 56.479186 -299.953426)
		(width 0.18288)
		(layer "In11.Cu")
		(net "M_D_CPU1_SA_DQ<13>")
	)
	(segment
		(start 17.67586 -299.901864)
		(end 17.374362 -299.901864)
		(width 0.18288)
		(layer "In11.Cu")
		(net "M_D_CPU1_SA_DQ<13>")
	)
	(segment
		(start 33.228026 -304.068226)
		(end 32.454342 -304.84191)
		(width 0.18288)
		(layer "In11.Cu")
		(net "M_D_CPU1_SA_DQ<13>")
	)
	(segment
		(start 83.276186 -279.091136)
		(end 83.087972 -279.27935)
		(width 0.18288)
		(layer "In11.Cu")
		(net "M_D_CPU1_SA_DQ<13>")
	)
	(segment
		(start 48.468534 -304.216054)
		(end 48.275494 -304.023014)
		(width 0.18288)
		(layer "In11.Cu")
		(net "M_D_CPU1_SA_DQ<13>")
	)
	(segment
		(start 19.97202 -300.666404)
		(end 19.770344 -300.86808)
		(width 0.18288)
		(layer "In11.Cu")
		(net "M_D_CPU1_SA_DQ<13>")
	)
	(segment
		(start 94.17685 -275.570442)
		(end 94.166436 -275.576538)
		(width 0.088646)
		(layer "In11.Cu")
		(net "M_D_CPU1_SA_DQ<13>")
	)
	(segment
		(start 41.416224 -304.456846)
		(end 41.070784 -304.111406)
		(width 0.18288)
		(layer "In11.Cu")
		(net "M_D_CPU1_SA_DQ<13>")
	)
	(segment
		(start 20.16506 -299.901864)
		(end 19.97202 -300.094904)
		(width 0.18288)
		(layer "In11.Cu")
		(net "M_D_CPU1_SA_DQ<13>")
	)
	(segment
		(start 19.97202 -300.094904)
		(end 19.97202 -300.666404)
		(width 0.18288)
		(layer "In11.Cu")
		(net "M_D_CPU1_SA_DQ<13>")
	)
	(segment
		(start 31.310326 -304.84191)
		(end 30.130242 -303.661826)
		(width 0.18288)
		(layer "In11.Cu")
		(net "M_D_CPU1_SA_DQ<13>")
	)
	(segment
		(start 48.275494 -304.023014)
		(end 47.960534 -304.023014)
		(width 0.18288)
		(layer "In11.Cu")
		(net "M_D_CPU1_SA_DQ<13>")
	)
	(segment
		(start 32.454342 -304.84191)
		(end 31.310326 -304.84191)
		(width 0.18288)
		(layer "In11.Cu")
		(net "M_D_CPU1_SA_DQ<13>")
	)
	(segment
		(start 83.445858 -278.921464)
		(end 83.276186 -279.091136)
		(width 0.088646)
		(layer "In11.Cu")
		(net "M_D_CPU1_SA_DQ<13>")
	)
	(segment
		(start 59.128406 -298.287186)
		(end 58.145426 -298.287186)
		(width 0.18288)
		(layer "In11.Cu")
		(net "M_D_CPU1_SA_DQ<13>")
	)
	(segment
		(start 42.117264 -304.111406)
		(end 41.771824 -304.456846)
		(width 0.18288)
		(layer "In11.Cu")
		(net "M_D_CPU1_SA_DQ<13>")
	)
	(segment
		(start 18.56994 -300.31055)
		(end 18.3769 -300.50359)
		(width 0.18288)
		(layer "In11.Cu")
		(net "M_D_CPU1_SA_DQ<13>")
	)
	(segment
		(start 49.953926 -304.713386)
		(end 48.587914 -304.713386)
		(width 0.18288)
		(layer "In11.Cu")
		(net "M_D_CPU1_SA_DQ<13>")
	)
	(segment
		(start 47.960534 -304.023014)
		(end 47.767494 -304.216054)
		(width 0.18288)
		(layer "In11.Cu")
		(net "M_D_CPU1_SA_DQ<13>")
	)
	(segment
		(start 47.767494 -304.64887)
		(end 47.574454 -304.84191)
		(width 0.18288)
		(layer "In11.Cu")
		(net "M_D_CPU1_SA_DQ<13>")
	)
	(segment
		(start 70.425056 -291.075872)
		(end 70.425056 -291.721286)
		(width 0.18288)
		(layer "In11.Cu")
		(net "M_D_CPU1_SA_DQ<13>")
	)
	(segment
		(start 85.237828 -277.315676)
		(end 83.63204 -278.921464)
		(width 0.088646)
		(layer "In11.Cu")
		(net "M_D_CPU1_SA_DQ<13>")
	)
	(segment
		(start 41.070784 -304.111406)
		(end 40.688514 -304.111406)
		(width 0.18288)
		(layer "In11.Cu")
		(net "M_D_CPU1_SA_DQ<13>")
	)
	(segment
		(start 52.379626 -302.569626)
		(end 52.379626 -303.077626)
		(width 0.18288)
		(layer "In11.Cu")
		(net "M_D_CPU1_SA_DQ<13>")
	)
	(segment
		(start 38.74897 -303.969166)
		(end 38.55593 -304.162206)
		(width 0.18288)
		(layer "In11.Cu")
		(net "M_D_CPU1_SA_DQ<13>")
	)
	(segment
		(start 38.55593 -304.316384)
		(end 38.36289 -304.509424)
		(width 0.18288)
		(layer "In11.Cu")
		(net "M_D_CPU1_SA_DQ<13>")
	)
	(segment
		(start 38.04793 -304.509424)
		(end 37.85489 -304.316384)
		(width 0.18288)
		(layer "In11.Cu")
		(net "M_D_CPU1_SA_DQ<13>")
	)
	(segment
		(start 88.537796 -275.570442)
		(end 88.527382 -275.576538)
		(width 0.088646)
		(layer "In11.Cu")
		(net "M_D_CPU1_SA_DQ<13>")
	)
	(segment
		(start 19.46402 -300.86808)
		(end 19.27098 -300.67504)
		(width 0.18288)
		(layer "In11.Cu")
		(net "M_D_CPU1_SA_DQ<13>")
	)
	(segment
		(start 37.85489 -304.162206)
		(end 37.66185 -303.969166)
		(width 0.18288)
		(layer "In11.Cu")
		(net "M_D_CPU1_SA_DQ<13>")
	)
	(segment
		(start 50.675286 -303.992026)
		(end 49.953926 -304.713386)
		(width 0.18288)
		(layer "In11.Cu")
		(net "M_D_CPU1_SA_DQ<13>")
	)
	(segment
		(start 66.677032 -295.46931)
		(end 66.677032 -296.204386)
		(width 0.18288)
		(layer "In11.Cu")
		(net "M_D_CPU1_SA_DQ<13>")
	)
	(segment
		(start 28.466542 -303.026826)
		(end 26.909522 -301.469806)
		(width 0.18288)
		(layer "In11.Cu")
		(net "M_D_CPU1_SA_DQ<13>")
	)
	(segment
		(start 83.087972 -279.27935)
		(end 82.221578 -279.27935)
		(width 0.18288)
		(layer "In11.Cu")
		(net "M_D_CPU1_SA_DQ<13>")
	)
	(segment
		(start 20.58797 -299.742352)
		(end 20.428458 -299.901864)
		(width 0.18288)
		(layer "In11.Cu")
		(net "M_D_CPU1_SA_DQ<13>")
	)
	(segment
		(start 30.130242 -303.661826)
		(end 29.303726 -303.661826)
		(width 0.18288)
		(layer "In11.Cu")
		(net "M_D_CPU1_SA_DQ<13>")
	)
	(segment
		(start 95.116396 -275.570442)
		(end 95.105982 -275.576538)
		(width 0.088646)
		(layer "In11.Cu")
		(net "M_D_CPU1_SA_DQ<13>")
	)
	(segment
		(start 38.55593 -304.162206)
		(end 38.55593 -304.316384)
		(width 0.18288)
		(layer "In11.Cu")
		(net "M_D_CPU1_SA_DQ<13>")
	)
	(segment
		(start 19.27098 -300.094904)
		(end 19.07794 -299.901864)
		(width 0.18288)
		(layer "In11.Cu")
		(net "M_D_CPU1_SA_DQ<13>")
	)
	(segment
		(start 96.995996 -275.570442)
		(end 96.981264 -275.579078)
		(width 0.088646)
		(layer "In11.Cu")
		(net "M_D_CPU1_SA_DQ<13>")
	)
	(segment
		(start 21.530818 -299.742352)
		(end 20.58797 -299.742352)
		(width 0.18288)
		(layer "In11.Cu")
		(net "M_D_CPU1_SA_DQ<13>")
	)
	(segment
		(start 66.483992 -296.397426)
		(end 65.29197 -296.397426)
		(width 0.18288)
		(layer "In11.Cu")
		(net "M_D_CPU1_SA_DQ<13>")
	)
	(segment
		(start 37.85489 -304.316384)
		(end 37.85489 -304.162206)
		(width 0.18288)
		(layer "In11.Cu")
		(net "M_D_CPU1_SA_DQ<13>")
	)
	(segment
		(start 91.357196 -275.570442)
		(end 91.342464 -275.579078)
		(width 0.088646)
		(layer "In11.Cu")
		(net "M_D_CPU1_SA_DQ<13>")
	)
	(segment
		(start 17.374362 -299.901864)
		(end 16.789146 -299.316648)
		(width 0.18288)
		(layer "In11.Cu")
		(net "M_D_CPU1_SA_DQ<13>")
	)
	(segment
		(start 37.068506 -303.793906)
		(end 36.702746 -303.793906)
		(width 0.18288)
		(layer "In11.Cu")
		(net "M_D_CPU1_SA_DQ<13>")
	)
	(segment
		(start 25.516586 -301.469806)
		(end 24.726646 -300.679866)
		(width 0.18288)
		(layer "In11.Cu")
		(net "M_D_CPU1_SA_DQ<13>")
	)
	(segment
		(start 55.765446 -299.953426)
		(end 55.028846 -300.690026)
		(width 0.18288)
		(layer "In11.Cu")
		(net "M_D_CPU1_SA_DQ<13>")
	)
	(segment
		(start 43.954446 -304.111406)
		(end 42.117264 -304.111406)
		(width 0.18288)
		(layer "In11.Cu")
		(net "M_D_CPU1_SA_DQ<13>")
	)
	(segment
		(start 61.124846 -297.248326)
		(end 60.428886 -297.944286)
		(width 0.18288)
		(layer "In11.Cu")
		(net "M_D_CPU1_SA_DQ<13>")
	)
	(segment
		(start 96.056196 -275.570442)
		(end 96.041464 -275.579078)
		(width 0.088646)
		(layer "In11.Cu")
		(net "M_D_CPU1_SA_DQ<13>")
	)
	(segment
		(start 18.56994 -300.094904)
		(end 18.56994 -300.31055)
		(width 0.18288)
		(layer "In11.Cu")
		(net "M_D_CPU1_SA_DQ<13>")
	)
	(segment
		(start 83.63204 -278.921464)
		(end 83.445858 -278.921464)
		(width 0.088646)
		(layer "In11.Cu")
		(net "M_D_CPU1_SA_DQ<13>")
	)
	(segment
		(start 41.771824 -304.456846)
		(end 41.416224 -304.456846)
		(width 0.18288)
		(layer "In11.Cu")
		(net "M_D_CPU1_SA_DQ<13>")
	)
	(segment
		(start 35.342576 -303.992026)
		(end 35.266376 -304.068226)
		(width 0.18288)
		(layer "In11.Cu")
		(net "M_D_CPU1_SA_DQ<13>")
	)
	(segment
		(start 59.471306 -297.944286)
		(end 59.128406 -298.287186)
		(width 0.18288)
		(layer "In11.Cu")
		(net "M_D_CPU1_SA_DQ<13>")
	)
	(segment
		(start 37.243766 -303.969166)
		(end 37.068506 -303.793906)
		(width 0.18288)
		(layer "In11.Cu")
		(net "M_D_CPU1_SA_DQ<13>")
	)
	(segment
		(start 38.36289 -304.509424)
		(end 38.04793 -304.509424)
		(width 0.18288)
		(layer "In11.Cu")
		(net "M_D_CPU1_SA_DQ<13>")
	)
	(segment
		(start 28.668726 -303.026826)
		(end 28.466542 -303.026826)
		(width 0.18288)
		(layer "In11.Cu")
		(net "M_D_CPU1_SA_DQ<13>")
	)
	(segment
		(start 54.259226 -300.690026)
		(end 52.379626 -302.569626)
		(width 0.18288)
		(layer "In11.Cu")
		(net "M_D_CPU1_SA_DQ<13>")
	)
	(segment
		(start 29.303726 -303.661826)
		(end 28.668726 -303.026826)
		(width 0.18288)
		(layer "In11.Cu")
		(net "M_D_CPU1_SA_DQ<13>")
	)
	(segment
		(start 40.546274 -303.969166)
		(end 38.74897 -303.969166)
		(width 0.18288)
		(layer "In11.Cu")
		(net "M_D_CPU1_SA_DQ<13>")
	)
	(segment
		(start 26.909522 -301.469806)
		(end 25.516586 -301.469806)
		(width 0.18288)
		(layer "In11.Cu")
		(net "M_D_CPU1_SA_DQ<13>")
	)
	(segment
		(start 18.06194 -300.50359)
		(end 17.8689 -300.31055)
		(width 0.18288)
		(layer "In11.Cu")
		(net "M_D_CPU1_SA_DQ<13>")
	)
	(segment
		(start 99.258882 -275.575522)
		(end 99.249992 -275.570442)
		(width 0.088646)
		(layer "In11.Cu")
		(net "M_D_CPU1_SA_DQ<13>")
	)
	(segment
		(start 40.688514 -304.111406)
		(end 40.546274 -303.969166)
		(width 0.18288)
		(layer "In11.Cu")
		(net "M_D_CPU1_SA_DQ<13>")
	)
	(segment
		(start 17.8689 -300.31055)
		(end 17.8689 -300.094904)
		(width 0.18288)
		(layer "In11.Cu")
		(net "M_D_CPU1_SA_DQ<13>")
	)
	(segment
		(start 46.232826 -304.84191)
		(end 45.342302 -303.951386)
		(width 0.18288)
		(layer "In11.Cu")
		(net "M_D_CPU1_SA_DQ<13>")
	)
	(segment
		(start 52.379626 -303.077626)
		(end 51.465226 -303.992026)
		(width 0.18288)
		(layer "In11.Cu")
		(net "M_D_CPU1_SA_DQ<13>")
	)
	(segment
		(start 56.479186 -299.953426)
		(end 55.765446 -299.953426)
		(width 0.18288)
		(layer "In11.Cu")
		(net "M_D_CPU1_SA_DQ<13>")
	)
	(segment
		(start 55.028846 -300.690026)
		(end 54.259226 -300.690026)
		(width 0.18288)
		(layer "In11.Cu")
		(net "M_D_CPU1_SA_DQ<13>")
	)
	(segment
		(start 47.767494 -304.216054)
		(end 47.767494 -304.64887)
		(width 0.18288)
		(layer "In11.Cu")
		(net "M_D_CPU1_SA_DQ<13>")
	)
	(segment
		(start 35.266376 -304.068226)
		(end 33.228026 -304.068226)
		(width 0.18288)
		(layer "In11.Cu")
		(net "M_D_CPU1_SA_DQ<13>")
	)
	(segment
		(start 99.062794 -275.8948)
		(end 99.375468 -275.8948)
		(width 0.088646)
		(layer "In11.Cu")
		(net "M_D_CPU1_SA_DQ<13>")
	)
	(segment
		(start 51.465226 -303.992026)
		(end 50.675286 -303.992026)
		(width 0.18288)
		(layer "In11.Cu")
		(net "M_D_CPU1_SA_DQ<13>")
	)
	(segment
		(start 18.3769 -300.50359)
		(end 18.06194 -300.50359)
		(width 0.18288)
		(layer "In11.Cu")
		(net "M_D_CPU1_SA_DQ<13>")
	)
	(segment
		(start 93.236796 -275.570442)
		(end 93.222064 -275.579078)
		(width 0.088646)
		(layer "In11.Cu")
		(net "M_D_CPU1_SA_DQ<13>")
	)
	(segment
		(start 99.375468 -275.8948)
		(end 99.432872 -275.837396)
		(width 0.088646)
		(layer "In11.Cu")
		(net "M_D_CPU1_SA_DQ<13>")
	)
	(segment
		(start 82.221578 -279.27935)
		(end 70.425056 -291.075872)
		(width 0.18288)
		(layer "In11.Cu")
		(net "M_D_CPU1_SA_DQ<13>")
	)
	(segment
		(start 62.796166 -297.007026)
		(end 62.554866 -297.248326)
		(width 0.18288)
		(layer "In11.Cu")
		(net "M_D_CPU1_SA_DQ<13>")
	)
	(segment
		(start 37.66185 -303.969166)
		(end 37.243766 -303.969166)
		(width 0.18288)
		(layer "In11.Cu")
		(net "M_D_CPU1_SA_DQ<13>")
	)
	(segment
		(start 18.76298 -299.901864)
		(end 18.56994 -300.094904)
		(width 0.18288)
		(layer "In11.Cu")
		(net "M_D_CPU1_SA_DQ<13>")
	)
	(segment
		(start 70.425056 -291.721286)
		(end 66.677032 -295.46931)
		(width 0.18288)
		(layer "In11.Cu")
		(net "M_D_CPU1_SA_DQ<13>")
	)
	(segment
		(start 17.8689 -300.094904)
		(end 17.67586 -299.901864)
		(width 0.18288)
		(layer "In11.Cu")
		(net "M_D_CPU1_SA_DQ<13>")
	)
	(segment
		(start 36.504626 -303.992026)
		(end 35.342576 -303.992026)
		(width 0.18288)
		(layer "In11.Cu")
		(net "M_D_CPU1_SA_DQ<13>")
	)
	(segment
		(start 48.587914 -304.713386)
		(end 48.468534 -304.594006)
		(width 0.18288)
		(layer "In11.Cu")
		(net "M_D_CPU1_SA_DQ<13>")
	)
	(segment
		(start 47.574454 -304.84191)
		(end 46.232826 -304.84191)
		(width 0.18288)
		(layer "In11.Cu")
		(net "M_D_CPU1_SA_DQ<13>")
	)
	(segment
		(start 19.27098 -300.67504)
		(end 19.27098 -300.094904)
		(width 0.18288)
		(layer "In11.Cu")
		(net "M_D_CPU1_SA_DQ<13>")
	)
	(segment
		(start 23.959566 -300.679866)
		(end 22.915118 -299.635418)
		(width 0.18288)
		(layer "In11.Cu")
		(net "M_D_CPU1_SA_DQ<13>")
	)
	(segment
		(start 20.428458 -299.901864)
		(end 20.16506 -299.901864)
		(width 0.18288)
		(layer "In11.Cu")
		(net "M_D_CPU1_SA_DQ<13>")
	)
	(segment
		(start 66.677032 -296.204386)
		(end 66.483992 -296.397426)
		(width 0.18288)
		(layer "In11.Cu")
		(net "M_D_CPU1_SA_DQ<13>")
	)
	(segment
		(start 48.468534 -304.594006)
		(end 48.468534 -304.216054)
		(width 0.18288)
		(layer "In11.Cu")
		(net "M_D_CPU1_SA_DQ<13>")
	)
	(segment
		(start 21.637752 -299.635418)
		(end 21.530818 -299.742352)
		(width 0.18288)
		(layer "In11.Cu")
		(net "M_D_CPU1_SA_DQ<13>")
	)
	(segment
		(start 22.915118 -299.635418)
		(end 21.637752 -299.635418)
		(width 0.18288)
		(layer "In11.Cu")
		(net "M_D_CPU1_SA_DQ<13>")
	)
	(segment
		(start 97.935796 -275.570442)
		(end 97.921064 -275.579078)
		(width 0.088646)
		(layer "In11.Cu")
		(net "M_D_CPU1_SA_DQ<13>")
	)
	(segment
		(start 19.770344 -300.86808)
		(end 19.46402 -300.86808)
		(width 0.18288)
		(layer "In11.Cu")
		(net "M_D_CPU1_SA_DQ<13>")
	)
	(segment
		(start 86.47049 -275.8948)
		(end 86.47049 -275.910294)
		(width 0.088646)
		(layer "In11.Cu")
		(net "M_D_CPU1_SA_DQ<13>")
	)
	(arc
		(start 86.188296 -276.384258)
		(mid 86.026892 -276.447117)
		(end 85.854032 -276.458172)
		(width 0.088646)
		(layer "In11.Cu")
		(net "M_D_CPU1_SA_DQ<13>")
	)
	(arc
		(start 94.551246 -275.570442)
		(mid 94.364048 -275.520299)
		(end 94.17685 -275.570442)
		(width 0.088646)
		(layer "In11.Cu")
		(net "M_D_CPU1_SA_DQ<13>")
	)
	(arc
		(start 86.47049 -275.910294)
		(mid 86.39112 -276.184028)
		(end 86.188296 -276.384258)
		(width 0.088646)
		(layer "In11.Cu")
		(net "M_D_CPU1_SA_DQ<13>")
	)
	(arc
		(start 99.249992 -275.570442)
		(mid 99.062794 -275.520299)
		(end 98.875596 -275.570442)
		(width 0.088646)
		(layer "In11.Cu")
		(net "M_D_CPU1_SA_DQ<13>")
	)
	(arc
		(start 92.296996 -275.570442)
		(mid 92.014294 -275.646184)
		(end 91.731592 -275.570442)
		(width 0.088646)
		(layer "In11.Cu")
		(net "M_D_CPU1_SA_DQ<13>")
	)
	(arc
		(start 88.527382 -275.576538)
		(mid 88.24895 -275.646352)
		(end 87.972138 -275.570442)
		(width 0.088646)
		(layer "In11.Cu")
		(net "M_D_CPU1_SA_DQ<13>")
	)
	(arc
		(start 89.851992 -275.570442)
		(mid 89.664794 -275.520299)
		(end 89.477596 -275.570442)
		(width 0.088646)
		(layer "In11.Cu")
		(net "M_D_CPU1_SA_DQ<13>")
	)
	(arc
		(start 97.370392 -275.570442)
		(mid 97.183194 -275.520299)
		(end 96.995996 -275.570442)
		(width 0.088646)
		(layer "In11.Cu")
		(net "M_D_CPU1_SA_DQ<13>")
	)
	(arc
		(start 91.731592 -275.570442)
		(mid 91.544394 -275.520299)
		(end 91.357196 -275.570442)
		(width 0.088646)
		(layer "In11.Cu")
		(net "M_D_CPU1_SA_DQ<13>")
	)
	(arc
		(start 98.310192 -275.570442)
		(mid 98.122994 -275.520299)
		(end 97.935796 -275.570442)
		(width 0.088646)
		(layer "In11.Cu")
		(net "M_D_CPU1_SA_DQ<13>")
	)
	(arc
		(start 87.032338 -275.570442)
		(mid 86.84514 -275.520299)
		(end 86.657942 -275.570442)
		(width 0.088646)
		(layer "In11.Cu")
		(net "M_D_CPU1_SA_DQ<13>")
	)
	(arc
		(start 96.981264 -275.579078)
		(mid 96.704823 -275.646244)
		(end 96.430592 -275.570442)
		(width 0.088646)
		(layer "In11.Cu")
		(net "M_D_CPU1_SA_DQ<13>")
	)
	(arc
		(start 87.597742 -275.570442)
		(mid 87.31504 -275.646184)
		(end 87.032338 -275.570442)
		(width 0.088646)
		(layer "In11.Cu")
		(net "M_D_CPU1_SA_DQ<13>")
	)
	(arc
		(start 94.166436 -275.576538)
		(mid 93.888004 -275.646352)
		(end 93.611192 -275.570442)
		(width 0.088646)
		(layer "In11.Cu")
		(net "M_D_CPU1_SA_DQ<13>")
	)
	(arc
		(start 87.972138 -275.570442)
		(mid 87.78494 -275.520299)
		(end 87.597742 -275.570442)
		(width 0.088646)
		(layer "In11.Cu")
		(net "M_D_CPU1_SA_DQ<13>")
	)
	(arc
		(start 93.222064 -275.579078)
		(mid 92.945623 -275.646244)
		(end 92.671392 -275.570442)
		(width 0.088646)
		(layer "In11.Cu")
		(net "M_D_CPU1_SA_DQ<13>")
	)
	(arc
		(start 86.649052 -275.575522)
		(mid 86.518138 -275.711882)
		(end 86.47049 -275.8948)
		(width 0.088646)
		(layer "In11.Cu")
		(net "M_D_CPU1_SA_DQ<13>")
	)
	(arc
		(start 97.921064 -275.579078)
		(mid 97.644623 -275.646244)
		(end 97.370392 -275.570442)
		(width 0.088646)
		(layer "In11.Cu")
		(net "M_D_CPU1_SA_DQ<13>")
	)
	(arc
		(start 95.105982 -275.576538)
		(mid 94.827804 -275.64623)
		(end 94.551246 -275.570442)
		(width 0.088646)
		(layer "In11.Cu")
		(net "M_D_CPU1_SA_DQ<13>")
	)
	(arc
		(start 96.041464 -275.579078)
		(mid 95.765023 -275.646244)
		(end 95.490792 -275.570442)
		(width 0.088646)
		(layer "In11.Cu")
		(net "M_D_CPU1_SA_DQ<13>")
	)
	(arc
		(start 96.430592 -275.570442)
		(mid 96.243394 -275.520299)
		(end 96.056196 -275.570442)
		(width 0.088646)
		(layer "In11.Cu")
		(net "M_D_CPU1_SA_DQ<13>")
	)
	(arc
		(start 88.912192 -275.570442)
		(mid 88.724994 -275.520299)
		(end 88.537796 -275.570442)
		(width 0.088646)
		(layer "In11.Cu")
		(net "M_D_CPU1_SA_DQ<13>")
	)
	(arc
		(start 92.671392 -275.570442)
		(mid 92.484194 -275.520299)
		(end 92.296996 -275.570442)
		(width 0.088646)
		(layer "In11.Cu")
		(net "M_D_CPU1_SA_DQ<13>")
	)
	(arc
		(start 89.477596 -275.570442)
		(mid 89.194894 -275.646184)
		(end 88.912192 -275.570442)
		(width 0.088646)
		(layer "In11.Cu")
		(net "M_D_CPU1_SA_DQ<13>")
	)
	(arc
		(start 90.417396 -275.570442)
		(mid 90.134694 -275.646184)
		(end 89.851992 -275.570442)
		(width 0.088646)
		(layer "In11.Cu")
		(net "M_D_CPU1_SA_DQ<13>")
	)
	(arc
		(start 90.791792 -275.570442)
		(mid 90.604594 -275.520299)
		(end 90.417396 -275.570442)
		(width 0.088646)
		(layer "In11.Cu")
		(net "M_D_CPU1_SA_DQ<13>")
	)
	(arc
		(start 95.490792 -275.570442)
		(mid 95.303594 -275.520299)
		(end 95.116396 -275.570442)
		(width 0.088646)
		(layer "In11.Cu")
		(net "M_D_CPU1_SA_DQ<13>")
	)
	(arc
		(start 99.432872 -275.837396)
		(mid 99.374716 -275.687283)
		(end 99.258882 -275.575522)
		(width 0.088646)
		(layer "In11.Cu")
		(net "M_D_CPU1_SA_DQ<13>")
	)
	(arc
		(start 91.342464 -275.579078)
		(mid 91.066023 -275.646244)
		(end 90.791792 -275.570442)
		(width 0.088646)
		(layer "In11.Cu")
		(net "M_D_CPU1_SA_DQ<13>")
	)
	(arc
		(start 93.611192 -275.570442)
		(mid 93.423994 -275.520299)
		(end 93.236796 -275.570442)
		(width 0.088646)
		(layer "In11.Cu")
		(net "M_D_CPU1_SA_DQ<13>")
	)
	(arc
		(start 98.875596 -275.570442)
		(mid 98.592894 -275.646184)
		(end 98.310192 -275.570442)
		(width 0.088646)
		(layer "In11.Cu")
		(net "M_D_CPU1_SA_DQ<13>")
	)
	(arc
		(start 85.854032 -276.458172)
		(mid 85.421817 -276.603737)
		(end 85.237828 -277.021036)
		(width 0.088646)
		(layer "In11.Cu")
		(net "M_D_CPU1_SA_DQ<13>")
	)
	(segment
		(start 10.554462 -300.5836)
		(end 11.11631 -300.5836)
		(width 0.20066)
		(layer "F.Cu")
		(net "M_D_CPU1_SA_DQ<12>")
	)
	(segment
		(start 9.474708 -301.01667)
		(end 9.713468 -301.25543)
		(width 0.20066)
		(layer "F.Cu")
		(net "M_D_CPU1_SA_DQ<12>")
	)
	(segment
		(start 11.124438 -300.591728)
		(end 11.372342 -300.591728)
		(width 0.101854)
		(layer "F.Cu")
		(net "M_D_CPU1_SA_DQ<12>")
	)
	(segment
		(start 15.684246 -301.01667)
		(end 16.789146 -301.01667)
		(width 0.20066)
		(layer "F.Cu")
		(net "M_D_CPU1_SA_DQ<12>")
	)
	(segment
		(start 11.372342 -300.591728)
		(end 13.441426 -300.591728)
		(width 0.1016)
		(layer "F.Cu")
		(net "M_D_CPU1_SA_DQ<12>")
	)
	(segment
		(start 13.441426 -300.591728)
		(end 13.890244 -300.591728)
		(width 0.20066)
		(layer "F.Cu")
		(net "M_D_CPU1_SA_DQ<12>")
	)
	(segment
		(start 10.344912 -301.08271)
		(end 10.344912 -300.79315)
		(width 0.20066)
		(layer "F.Cu")
		(net "M_D_CPU1_SA_DQ<12>")
	)
	(segment
		(start 9.713468 -301.25543)
		(end 10.172192 -301.25543)
		(width 0.20066)
		(layer "F.Cu")
		(net "M_D_CPU1_SA_DQ<12>")
	)
	(segment
		(start 10.172192 -301.25543)
		(end 10.344912 -301.08271)
		(width 0.20066)
		(layer "F.Cu")
		(net "M_D_CPU1_SA_DQ<12>")
	)
	(segment
		(start 10.344912 -300.79315)
		(end 10.554462 -300.5836)
		(width 0.20066)
		(layer "F.Cu")
		(net "M_D_CPU1_SA_DQ<12>")
	)
	(segment
		(start 13.890244 -300.591728)
		(end 14.315186 -301.01667)
		(width 0.20066)
		(layer "F.Cu")
		(net "M_D_CPU1_SA_DQ<12>")
	)
	(segment
		(start 14.315186 -301.01667)
		(end 15.684246 -301.01667)
		(width 0.20066)
		(layer "F.Cu")
		(net "M_D_CPU1_SA_DQ<12>")
	)
	(segment
		(start 8.140446 -301.01667)
		(end 9.474708 -301.01667)
		(width 0.20066)
		(layer "F.Cu")
		(net "M_D_CPU1_SA_DQ<12>")
	)
	(segment
		(start 98.592894 -276.172676)
		(end 98.592894 -276.708362)
		(width 0.20066)
		(layer "F.Cu")
		(net "M_D_CPU1_SA_DQ<12>")
	)
	(segment
		(start 11.11631 -300.5836)
		(end 11.124438 -300.591728)
		(width 0.101854)
		(layer "F.Cu")
		(net "M_D_CPU1_SA_DQ<12>")
	)
	(segment
		(start 98.592894 -276.708362)
		(end 98.593148 -276.708616)
		(width 0.20066)
		(layer "F.Cu")
		(net "M_D_CPU1_SA_DQ<12>")
	)
	(segment
		(start 21.672804 -301.302166)
		(end 21.532596 -301.442374)
		(width 0.18288)
		(layer "In11.Cu")
		(net "M_D_CPU1_SA_DQ<12>")
	)
	(segment
		(start 84.318602 -278.861012)
		(end 84.318602 -279.505156)
		(width 0.088646)
		(layer "In11.Cu")
		(net "M_D_CPU1_SA_DQ<12>")
	)
	(segment
		(start 20.0152 -301.833026)
		(end 20.0152 -302.267874)
		(width 0.18288)
		(layer "In11.Cu")
		(net "M_D_CPU1_SA_DQ<12>")
	)
	(segment
		(start 19.12112 -301.639986)
		(end 18.80616 -301.639986)
		(width 0.18288)
		(layer "In11.Cu")
		(net "M_D_CPU1_SA_DQ<12>")
	)
	(segment
		(start 41.906444 -306.354226)
		(end 40.416226 -306.354226)
		(width 0.18288)
		(layer "In11.Cu")
		(net "M_D_CPU1_SA_DQ<12>")
	)
	(segment
		(start 47.810166 -306.377086)
		(end 47.645828 -306.541424)
		(width 0.18288)
		(layer "In11.Cu")
		(net "M_D_CPU1_SA_DQ<12>")
	)
	(segment
		(start 28.948126 -305.11877)
		(end 28.507182 -304.677826)
		(width 0.18288)
		(layer "In11.Cu")
		(net "M_D_CPU1_SA_DQ<12>")
	)
	(segment
		(start 49.361344 -306.377086)
		(end 47.810166 -306.377086)
		(width 0.18288)
		(layer "In11.Cu")
		(net "M_D_CPU1_SA_DQ<12>")
	)
	(segment
		(start 17.91208 -302.267874)
		(end 17.91208 -301.833026)
		(width 0.18288)
		(layer "In11.Cu")
		(net "M_D_CPU1_SA_DQ<12>")
	)
	(segment
		(start 36.873942 -305.627024)
		(end 36.809426 -305.69154)
		(width 0.18288)
		(layer "In11.Cu")
		(net "M_D_CPU1_SA_DQ<12>")
	)
	(segment
		(start 44.600622 -305.643026)
		(end 43.889422 -306.354226)
		(width 0.18288)
		(layer "In11.Cu")
		(net "M_D_CPU1_SA_DQ<12>")
	)
	(segment
		(start 82.556096 -280.382218)
		(end 71.441056 -291.497258)
		(width 0.18288)
		(layer "In11.Cu")
		(net "M_D_CPU1_SA_DQ<12>")
	)
	(segment
		(start 85.650324 -277.52929)
		(end 84.318602 -278.861012)
		(width 0.088646)
		(layer "In11.Cu")
		(net "M_D_CPU1_SA_DQ<12>")
	)
	(segment
		(start 51.376326 -305.69154)
		(end 50.702718 -305.69154)
		(width 0.18288)
		(layer "In11.Cu")
		(net "M_D_CPU1_SA_DQ<12>")
	)
	(segment
		(start 50.702718 -305.69154)
		(end 50.141632 -306.252626)
		(width 0.18288)
		(layer "In11.Cu")
		(net "M_D_CPU1_SA_DQ<12>")
	)
	(segment
		(start 28.948126 -306.468526)
		(end 28.948126 -305.11877)
		(width 0.18288)
		(layer "In11.Cu")
		(net "M_D_CPU1_SA_DQ<12>")
	)
	(segment
		(start 66.512186 -298.042076)
		(end 65.220596 -298.042076)
		(width 0.18288)
		(layer "In11.Cu")
		(net "M_D_CPU1_SA_DQ<12>")
	)
	(segment
		(start 33.434528 -306.541424)
		(end 31.610554 -306.541424)
		(width 0.18288)
		(layer "In11.Cu")
		(net "M_D_CPU1_SA_DQ<12>")
	)
	(segment
		(start 85.905086 -277.147274)
		(end 85.763354 -277.147274)
		(width 0.088646)
		(layer "In11.Cu")
		(net "M_D_CPU1_SA_DQ<12>")
	)
	(segment
		(start 98.593148 -276.708616)
		(end 98.533458 -276.648926)
		(width 0.088646)
		(layer "In11.Cu")
		(net "M_D_CPU1_SA_DQ<12>")
	)
	(segment
		(start 52.577492 -305.59756)
		(end 51.470306 -305.59756)
		(width 0.18288)
		(layer "In11.Cu")
		(net "M_D_CPU1_SA_DQ<12>")
	)
	(segment
		(start 84.318602 -279.505156)
		(end 84.004404 -279.819354)
		(width 0.088646)
		(layer "In11.Cu")
		(net "M_D_CPU1_SA_DQ<12>")
	)
	(segment
		(start 46.064424 -306.541424)
		(end 45.166026 -305.643026)
		(width 0.18288)
		(layer "In11.Cu")
		(net "M_D_CPU1_SA_DQ<12>")
	)
	(segment
		(start 64.564006 -298.698666)
		(end 63.262256 -298.698666)
		(width 0.18288)
		(layer "In11.Cu")
		(net "M_D_CPU1_SA_DQ<12>")
	)
	(segment
		(start 42.800524 -306.859686)
		(end 42.607484 -307.052726)
		(width 0.18288)
		(layer "In11.Cu")
		(net "M_D_CPU1_SA_DQ<12>")
	)
	(segment
		(start 18.80616 -301.639986)
		(end 18.61312 -301.833026)
		(width 0.18288)
		(layer "In11.Cu")
		(net "M_D_CPU1_SA_DQ<12>")
	)
	(segment
		(start 49.485804 -306.252626)
		(end 49.361344 -306.377086)
		(width 0.18288)
		(layer "In11.Cu")
		(net "M_D_CPU1_SA_DQ<12>")
	)
	(segment
		(start 27.25801 -304.070766)
		(end 27.25801 -303.49571)
		(width 0.18288)
		(layer "In11.Cu")
		(net "M_D_CPU1_SA_DQ<12>")
	)
	(segment
		(start 39.689024 -305.627024)
		(end 36.873942 -305.627024)
		(width 0.18288)
		(layer "In11.Cu")
		(net "M_D_CPU1_SA_DQ<12>")
	)
	(segment
		(start 21.532596 -301.442374)
		(end 20.609814 -301.442374)
		(width 0.18288)
		(layer "In11.Cu")
		(net "M_D_CPU1_SA_DQ<12>")
	)
	(segment
		(start 87.128096 -276.384258)
		(end 87.119206 -276.389338)
		(width 0.088646)
		(layer "In11.Cu")
		(net "M_D_CPU1_SA_DQ<12>")
	)
	(segment
		(start 35.611562 -305.69154)
		(end 35.406076 -305.897026)
		(width 0.18288)
		(layer "In11.Cu")
		(net "M_D_CPU1_SA_DQ<12>")
	)
	(segment
		(start 20.609814 -301.442374)
		(end 20.412202 -301.639986)
		(width 0.18288)
		(layer "In11.Cu")
		(net "M_D_CPU1_SA_DQ<12>")
	)
	(segment
		(start 67.705732 -295.964102)
		(end 67.705732 -296.84853)
		(width 0.18288)
		(layer "In11.Cu")
		(net "M_D_CPU1_SA_DQ<12>")
	)
	(segment
		(start 43.889422 -306.354226)
		(end 42.993564 -306.354226)
		(width 0.18288)
		(layer "In11.Cu")
		(net "M_D_CPU1_SA_DQ<12>")
	)
	(segment
		(start 42.993564 -306.354226)
		(end 42.800524 -306.547266)
		(width 0.18288)
		(layer "In11.Cu")
		(net "M_D_CPU1_SA_DQ<12>")
	)
	(segment
		(start 71.441056 -291.497258)
		(end 71.441056 -292.228778)
		(width 0.18288)
		(layer "In11.Cu")
		(net "M_D_CPU1_SA_DQ<12>")
	)
	(segment
		(start 22.932898 -301.901606)
		(end 22.333458 -301.302166)
		(width 0.18288)
		(layer "In11.Cu")
		(net "M_D_CPU1_SA_DQ<12>")
	)
	(segment
		(start 93.156278 -276.392894)
		(end 93.141546 -276.384258)
		(width 0.088646)
		(layer "In11.Cu")
		(net "M_D_CPU1_SA_DQ<12>")
	)
	(segment
		(start 71.441056 -292.228778)
		(end 67.705732 -295.964102)
		(width 0.18288)
		(layer "In11.Cu")
		(net "M_D_CPU1_SA_DQ<12>")
	)
	(segment
		(start 87.517224 -276.392894)
		(end 87.502492 -276.384258)
		(width 0.088646)
		(layer "In11.Cu")
		(net "M_D_CPU1_SA_DQ<12>")
	)
	(segment
		(start 31.365952 -306.786026)
		(end 29.265626 -306.786026)
		(width 0.18288)
		(layer "In11.Cu")
		(net "M_D_CPU1_SA_DQ<12>")
	)
	(segment
		(start 18.10512 -302.460914)
		(end 17.91208 -302.267874)
		(width 0.18288)
		(layer "In11.Cu")
		(net "M_D_CPU1_SA_DQ<12>")
	)
	(segment
		(start 40.416226 -306.354226)
		(end 39.689024 -305.627024)
		(width 0.18288)
		(layer "In11.Cu")
		(net "M_D_CPU1_SA_DQ<12>")
	)
	(segment
		(start 57.675526 -300.499526)
		(end 52.577492 -305.59756)
		(width 0.18288)
		(layer "In11.Cu")
		(net "M_D_CPU1_SA_DQ<12>")
	)
	(segment
		(start 42.607484 -307.052726)
		(end 42.292524 -307.052726)
		(width 0.18288)
		(layer "In11.Cu")
		(net "M_D_CPU1_SA_DQ<12>")
	)
	(segment
		(start 20.20824 -301.639986)
		(end 20.0152 -301.833026)
		(width 0.18288)
		(layer "In11.Cu")
		(net "M_D_CPU1_SA_DQ<12>")
	)
	(segment
		(start 91.272106 -276.390354)
		(end 91.261692 -276.384258)
		(width 0.088646)
		(layer "In11.Cu")
		(net "M_D_CPU1_SA_DQ<12>")
	)
	(segment
		(start 20.0152 -302.267874)
		(end 19.82216 -302.460914)
		(width 0.18288)
		(layer "In11.Cu")
		(net "M_D_CPU1_SA_DQ<12>")
	)
	(segment
		(start 85.763354 -277.147274)
		(end 85.650324 -277.260304)
		(width 0.088646)
		(layer "In11.Cu")
		(net "M_D_CPU1_SA_DQ<12>")
	)
	(segment
		(start 35.406076 -305.897026)
		(end 34.078926 -305.897026)
		(width 0.18288)
		(layer "In11.Cu")
		(net "M_D_CPU1_SA_DQ<12>")
	)
	(segment
		(start 83.44154 -280.382218)
		(end 82.556096 -280.382218)
		(width 0.18288)
		(layer "In11.Cu")
		(net "M_D_CPU1_SA_DQ<12>")
	)
	(segment
		(start 27.86507 -304.677826)
		(end 27.25801 -304.070766)
		(width 0.18288)
		(layer "In11.Cu")
		(net "M_D_CPU1_SA_DQ<12>")
	)
	(segment
		(start 92.216478 -276.392894)
		(end 92.201746 -276.384258)
		(width 0.088646)
		(layer "In11.Cu")
		(net "M_D_CPU1_SA_DQ<12>")
	)
	(segment
		(start 29.265626 -306.786026)
		(end 28.948126 -306.468526)
		(width 0.18288)
		(layer "In11.Cu")
		(net "M_D_CPU1_SA_DQ<12>")
	)
	(segment
		(start 25.64892 -303.026826)
		(end 22.932898 -301.901606)
		(width 0.18288)
		(layer "In11.Cu")
		(net "M_D_CPU1_SA_DQ<12>")
	)
	(segment
		(start 17.412462 -301.639986)
		(end 16.789146 -301.01667)
		(width 0.18288)
		(layer "In11.Cu")
		(net "M_D_CPU1_SA_DQ<12>")
	)
	(segment
		(start 18.61312 -302.267874)
		(end 18.42008 -302.460914)
		(width 0.18288)
		(layer "In11.Cu")
		(net "M_D_CPU1_SA_DQ<12>")
	)
	(segment
		(start 20.412202 -301.639986)
		(end 20.20824 -301.639986)
		(width 0.18288)
		(layer "In11.Cu")
		(net "M_D_CPU1_SA_DQ<12>")
	)
	(segment
		(start 26.789126 -303.026826)
		(end 25.64892 -303.026826)
		(width 0.18288)
		(layer "In11.Cu")
		(net "M_D_CPU1_SA_DQ<12>")
	)
	(segment
		(start 34.078926 -305.897026)
		(end 33.434528 -306.541424)
		(width 0.18288)
		(layer "In11.Cu")
		(net "M_D_CPU1_SA_DQ<12>")
	)
	(segment
		(start 17.91208 -301.833026)
		(end 17.71904 -301.639986)
		(width 0.18288)
		(layer "In11.Cu")
		(net "M_D_CPU1_SA_DQ<12>")
	)
	(segment
		(start 86.940644 -276.708616)
		(end 86.940644 -276.72284)
		(width 0.088646)
		(layer "In11.Cu")
		(net "M_D_CPU1_SA_DQ<12>")
	)
	(segment
		(start 95.035878 -276.392894)
		(end 95.021146 -276.384258)
		(width 0.088646)
		(layer "In11.Cu")
		(net "M_D_CPU1_SA_DQ<12>")
	)
	(segment
		(start 51.470306 -305.59756)
		(end 51.376326 -305.69154)
		(width 0.18288)
		(layer "In11.Cu")
		(net "M_D_CPU1_SA_DQ<12>")
	)
	(segment
		(start 67.705732 -296.84853)
		(end 66.512186 -298.042076)
		(width 0.18288)
		(layer "In11.Cu")
		(net "M_D_CPU1_SA_DQ<12>")
	)
	(segment
		(start 45.166026 -305.643026)
		(end 44.600622 -305.643026)
		(width 0.18288)
		(layer "In11.Cu")
		(net "M_D_CPU1_SA_DQ<12>")
	)
	(segment
		(start 42.099484 -306.859686)
		(end 42.099484 -306.547266)
		(width 0.18288)
		(layer "In11.Cu")
		(net "M_D_CPU1_SA_DQ<12>")
	)
	(segment
		(start 96.91116 -276.390354)
		(end 96.900746 -276.384258)
		(width 0.088646)
		(layer "In11.Cu")
		(net "M_D_CPU1_SA_DQ<12>")
	)
	(segment
		(start 84.004404 -279.819354)
		(end 83.44154 -280.382218)
		(width 0.18288)
		(layer "In11.Cu")
		(net "M_D_CPU1_SA_DQ<12>")
	)
	(segment
		(start 59.120786 -299.595286)
		(end 58.216546 -300.499526)
		(width 0.18288)
		(layer "In11.Cu")
		(net "M_D_CPU1_SA_DQ<12>")
	)
	(segment
		(start 19.31416 -302.267874)
		(end 19.31416 -301.833026)
		(width 0.18288)
		(layer "In11.Cu")
		(net "M_D_CPU1_SA_DQ<12>")
	)
	(segment
		(start 97.850706 -276.390354)
		(end 97.840292 -276.384258)
		(width 0.088646)
		(layer "In11.Cu")
		(net "M_D_CPU1_SA_DQ<12>")
	)
	(segment
		(start 65.220596 -298.042076)
		(end 64.564006 -298.698666)
		(width 0.18288)
		(layer "In11.Cu")
		(net "M_D_CPU1_SA_DQ<12>")
	)
	(segment
		(start 47.645828 -306.541424)
		(end 46.064424 -306.541424)
		(width 0.18288)
		(layer "In11.Cu")
		(net "M_D_CPU1_SA_DQ<12>")
	)
	(segment
		(start 42.292524 -307.052726)
		(end 42.099484 -306.859686)
		(width 0.18288)
		(layer "In11.Cu")
		(net "M_D_CPU1_SA_DQ<12>")
	)
	(segment
		(start 95.975678 -276.392894)
		(end 95.960946 -276.384258)
		(width 0.088646)
		(layer "In11.Cu")
		(net "M_D_CPU1_SA_DQ<12>")
	)
	(segment
		(start 63.068708 -298.892214)
		(end 61.131958 -298.892214)
		(width 0.18288)
		(layer "In11.Cu")
		(net "M_D_CPU1_SA_DQ<12>")
	)
	(segment
		(start 63.262256 -298.698666)
		(end 63.068708 -298.892214)
		(width 0.18288)
		(layer "In11.Cu")
		(net "M_D_CPU1_SA_DQ<12>")
	)
	(segment
		(start 61.131958 -298.892214)
		(end 60.428886 -299.595286)
		(width 0.18288)
		(layer "In11.Cu")
		(net "M_D_CPU1_SA_DQ<12>")
	)
	(segment
		(start 19.5072 -302.460914)
		(end 19.31416 -302.267874)
		(width 0.18288)
		(layer "In11.Cu")
		(net "M_D_CPU1_SA_DQ<12>")
	)
	(segment
		(start 19.31416 -301.833026)
		(end 19.12112 -301.639986)
		(width 0.18288)
		(layer "In11.Cu")
		(net "M_D_CPU1_SA_DQ<12>")
	)
	(segment
		(start 85.650324 -277.260304)
		(end 85.650324 -277.52929)
		(width 0.088646)
		(layer "In11.Cu")
		(net "M_D_CPU1_SA_DQ<12>")
	)
	(segment
		(start 22.333458 -301.302166)
		(end 21.672804 -301.302166)
		(width 0.18288)
		(layer "In11.Cu")
		(net "M_D_CPU1_SA_DQ<12>")
	)
	(segment
		(start 60.428886 -299.595286)
		(end 59.120786 -299.595286)
		(width 0.18288)
		(layer "In11.Cu")
		(net "M_D_CPU1_SA_DQ<12>")
	)
	(segment
		(start 36.809426 -305.69154)
		(end 35.611562 -305.69154)
		(width 0.18288)
		(layer "In11.Cu")
		(net "M_D_CPU1_SA_DQ<12>")
	)
	(segment
		(start 42.099484 -306.547266)
		(end 41.906444 -306.354226)
		(width 0.18288)
		(layer "In11.Cu")
		(net "M_D_CPU1_SA_DQ<12>")
	)
	(segment
		(start 19.82216 -302.460914)
		(end 19.5072 -302.460914)
		(width 0.18288)
		(layer "In11.Cu")
		(net "M_D_CPU1_SA_DQ<12>")
	)
	(segment
		(start 42.800524 -306.547266)
		(end 42.800524 -306.859686)
		(width 0.18288)
		(layer "In11.Cu")
		(net "M_D_CPU1_SA_DQ<12>")
	)
	(segment
		(start 18.61312 -301.833026)
		(end 18.61312 -302.267874)
		(width 0.18288)
		(layer "In11.Cu")
		(net "M_D_CPU1_SA_DQ<12>")
	)
	(segment
		(start 28.507182 -304.677826)
		(end 27.86507 -304.677826)
		(width 0.18288)
		(layer "In11.Cu")
		(net "M_D_CPU1_SA_DQ<12>")
	)
	(segment
		(start 86.657942 -277.198328)
		(end 86.64321 -277.206964)
		(width 0.088646)
		(layer "In11.Cu")
		(net "M_D_CPU1_SA_DQ<12>")
	)
	(segment
		(start 27.25801 -303.49571)
		(end 26.789126 -303.026826)
		(width 0.18288)
		(layer "In11.Cu")
		(net "M_D_CPU1_SA_DQ<12>")
	)
	(segment
		(start 50.141632 -306.252626)
		(end 49.485804 -306.252626)
		(width 0.18288)
		(layer "In11.Cu")
		(net "M_D_CPU1_SA_DQ<12>")
	)
	(segment
		(start 31.610554 -306.541424)
		(end 31.365952 -306.786026)
		(width 0.18288)
		(layer "In11.Cu")
		(net "M_D_CPU1_SA_DQ<12>")
	)
	(segment
		(start 18.42008 -302.460914)
		(end 18.10512 -302.460914)
		(width 0.18288)
		(layer "In11.Cu")
		(net "M_D_CPU1_SA_DQ<12>")
	)
	(segment
		(start 58.216546 -300.499526)
		(end 57.675526 -300.499526)
		(width 0.18288)
		(layer "In11.Cu")
		(net "M_D_CPU1_SA_DQ<12>")
	)
	(segment
		(start 17.71904 -301.639986)
		(end 17.412462 -301.639986)
		(width 0.18288)
		(layer "In11.Cu")
		(net "M_D_CPU1_SA_DQ<12>")
	)
	(arc
		(start 93.141546 -276.384258)
		(mid 92.954348 -276.334115)
		(end 92.76715 -276.384258)
		(width 0.088646)
		(layer "In11.Cu")
		(net "M_D_CPU1_SA_DQ<12>")
	)
	(arc
		(start 94.64675 -276.384258)
		(mid 94.364048 -276.460034)
		(end 94.081346 -276.384258)
		(width 0.088646)
		(layer "In11.Cu")
		(net "M_D_CPU1_SA_DQ<12>")
	)
	(arc
		(start 97.465896 -276.384258)
		(mid 97.189337 -276.460001)
		(end 96.91116 -276.390354)
		(width 0.088646)
		(layer "In11.Cu")
		(net "M_D_CPU1_SA_DQ<12>")
	)
	(arc
		(start 88.067896 -276.384258)
		(mid 87.793697 -276.460093)
		(end 87.517224 -276.392894)
		(width 0.088646)
		(layer "In11.Cu")
		(net "M_D_CPU1_SA_DQ<12>")
	)
	(arc
		(start 86.092538 -277.198328)
		(mid 86.00218 -277.160425)
		(end 85.905086 -277.147274)
		(width 0.088646)
		(layer "In11.Cu")
		(net "M_D_CPU1_SA_DQ<12>")
	)
	(arc
		(start 91.261692 -276.384258)
		(mid 91.074494 -276.334115)
		(end 90.887296 -276.384258)
		(width 0.088646)
		(layer "In11.Cu")
		(net "M_D_CPU1_SA_DQ<12>")
	)
	(arc
		(start 96.52635 -276.384258)
		(mid 96.252151 -276.460093)
		(end 95.975678 -276.392894)
		(width 0.088646)
		(layer "In11.Cu")
		(net "M_D_CPU1_SA_DQ<12>")
	)
	(arc
		(start 95.021146 -276.384258)
		(mid 94.833948 -276.334115)
		(end 94.64675 -276.384258)
		(width 0.088646)
		(layer "In11.Cu")
		(net "M_D_CPU1_SA_DQ<12>")
	)
	(arc
		(start 95.960946 -276.384258)
		(mid 95.773748 -276.334115)
		(end 95.58655 -276.384258)
		(width 0.088646)
		(layer "In11.Cu")
		(net "M_D_CPU1_SA_DQ<12>")
	)
	(arc
		(start 89.382092 -276.384258)
		(mid 89.194894 -276.334115)
		(end 89.007696 -276.384258)
		(width 0.088646)
		(layer "In11.Cu")
		(net "M_D_CPU1_SA_DQ<12>")
	)
	(arc
		(start 87.119206 -276.389338)
		(mid 86.988292 -276.525698)
		(end 86.940644 -276.708616)
		(width 0.088646)
		(layer "In11.Cu")
		(net "M_D_CPU1_SA_DQ<12>")
	)
	(arc
		(start 89.947496 -276.384258)
		(mid 89.664794 -276.460034)
		(end 89.382092 -276.384258)
		(width 0.088646)
		(layer "In11.Cu")
		(net "M_D_CPU1_SA_DQ<12>")
	)
	(arc
		(start 96.900746 -276.384258)
		(mid 96.713548 -276.334115)
		(end 96.52635 -276.384258)
		(width 0.088646)
		(layer "In11.Cu")
		(net "M_D_CPU1_SA_DQ<12>")
	)
	(arc
		(start 98.533458 -276.648926)
		(mid 98.334916 -276.513431)
		(end 98.100642 -276.459696)
		(width 0.088646)
		(layer "In11.Cu")
		(net "M_D_CPU1_SA_DQ<12>")
	)
	(arc
		(start 97.840292 -276.384258)
		(mid 97.653094 -276.334115)
		(end 97.465896 -276.384258)
		(width 0.088646)
		(layer "In11.Cu")
		(net "M_D_CPU1_SA_DQ<12>")
	)
	(arc
		(start 90.887296 -276.384258)
		(mid 90.604594 -276.460034)
		(end 90.321892 -276.384258)
		(width 0.088646)
		(layer "In11.Cu")
		(net "M_D_CPU1_SA_DQ<12>")
	)
	(arc
		(start 92.76715 -276.384258)
		(mid 92.492951 -276.460093)
		(end 92.216478 -276.392894)
		(width 0.088646)
		(layer "In11.Cu")
		(net "M_D_CPU1_SA_DQ<12>")
	)
	(arc
		(start 89.007696 -276.384258)
		(mid 88.724994 -276.460034)
		(end 88.442292 -276.384258)
		(width 0.088646)
		(layer "In11.Cu")
		(net "M_D_CPU1_SA_DQ<12>")
	)
	(arc
		(start 86.940644 -276.72284)
		(mid 86.861425 -276.997525)
		(end 86.657942 -277.198328)
		(width 0.088646)
		(layer "In11.Cu")
		(net "M_D_CPU1_SA_DQ<12>")
	)
	(arc
		(start 93.70695 -276.384258)
		(mid 93.432751 -276.460093)
		(end 93.156278 -276.392894)
		(width 0.088646)
		(layer "In11.Cu")
		(net "M_D_CPU1_SA_DQ<12>")
	)
	(arc
		(start 87.502492 -276.384258)
		(mid 87.315294 -276.334115)
		(end 87.128096 -276.384258)
		(width 0.088646)
		(layer "In11.Cu")
		(net "M_D_CPU1_SA_DQ<12>")
	)
	(arc
		(start 92.201746 -276.384258)
		(mid 92.014548 -276.334115)
		(end 91.82735 -276.384258)
		(width 0.088646)
		(layer "In11.Cu")
		(net "M_D_CPU1_SA_DQ<12>")
	)
	(arc
		(start 91.82735 -276.384258)
		(mid 91.550537 -276.460128)
		(end 91.272106 -276.390354)
		(width 0.088646)
		(layer "In11.Cu")
		(net "M_D_CPU1_SA_DQ<12>")
	)
	(arc
		(start 90.321892 -276.384258)
		(mid 90.134694 -276.334115)
		(end 89.947496 -276.384258)
		(width 0.088646)
		(layer "In11.Cu")
		(net "M_D_CPU1_SA_DQ<12>")
	)
	(arc
		(start 88.442292 -276.384258)
		(mid 88.255094 -276.334115)
		(end 88.067896 -276.384258)
		(width 0.088646)
		(layer "In11.Cu")
		(net "M_D_CPU1_SA_DQ<12>")
	)
	(arc
		(start 94.081346 -276.384258)
		(mid 93.894148 -276.334115)
		(end 93.70695 -276.384258)
		(width 0.088646)
		(layer "In11.Cu")
		(net "M_D_CPU1_SA_DQ<12>")
	)
	(arc
		(start 95.58655 -276.384258)
		(mid 95.312351 -276.460093)
		(end 95.035878 -276.392894)
		(width 0.088646)
		(layer "In11.Cu")
		(net "M_D_CPU1_SA_DQ<12>")
	)
	(arc
		(start 98.100642 -276.459696)
		(mid 97.97164 -276.439561)
		(end 97.850706 -276.390354)
		(width 0.088646)
		(layer "In11.Cu")
		(net "M_D_CPU1_SA_DQ<12>")
	)
	(arc
		(start 86.64321 -277.206964)
		(mid 86.366769 -277.27413)
		(end 86.092538 -277.198328)
		(width 0.088646)
		(layer "In11.Cu")
		(net "M_D_CPU1_SA_DQ<12>")
	)
	(segment
		(start 12.240514 -304.416714)
		(end 13.937742 -304.416714)
		(width 0.20066)
		(layer "F.Cu")
		(net "M_D_CPU1_SA_DQ<11>")
	)
	(segment
		(start 100.472494 -278.336248)
		(end 100.472748 -278.336502)
		(width 0.20066)
		(layer "F.Cu")
		(net "M_D_CPU1_SA_DQ<11>")
	)
	(segment
		(start 14.812264 -304.841656)
		(end 16.885158 -304.841656)
		(width 0.1016)
		(layer "F.Cu")
		(net "M_D_CPU1_SA_DQ<11>")
	)
	(segment
		(start 17.578578 -304.54092)
		(end 17.707102 -304.412396)
		(width 0.20066)
		(layer "F.Cu")
		(net "M_D_CPU1_SA_DQ<11>")
	)
	(segment
		(start 14.574266 -304.841656)
		(end 14.812264 -304.841656)
		(width 0.101854)
		(layer "F.Cu")
		(net "M_D_CPU1_SA_DQ<11>")
	)
	(segment
		(start 18.102326 -304.412396)
		(end 18.314162 -304.624232)
		(width 0.20066)
		(layer "F.Cu")
		(net "M_D_CPU1_SA_DQ<11>")
	)
	(segment
		(start 14.063726 -304.542698)
		(end 14.063726 -304.713386)
		(width 0.20066)
		(layer "F.Cu")
		(net "M_D_CPU1_SA_DQ<11>")
	)
	(segment
		(start 16.885158 -304.841656)
		(end 17.42948 -304.841656)
		(width 0.20066)
		(layer "F.Cu")
		(net "M_D_CPU1_SA_DQ<11>")
	)
	(segment
		(start 18.968212 -304.416714)
		(end 19.784314 -304.416714)
		(width 0.20066)
		(layer "F.Cu")
		(net "M_D_CPU1_SA_DQ<11>")
	)
	(segment
		(start 17.578578 -304.692558)
		(end 17.578578 -304.54092)
		(width 0.20066)
		(layer "F.Cu")
		(net "M_D_CPU1_SA_DQ<11>")
	)
	(segment
		(start 100.472494 -277.800562)
		(end 100.472494 -278.336248)
		(width 0.20066)
		(layer "F.Cu")
		(net "M_D_CPU1_SA_DQ<11>")
	)
	(segment
		(start 13.937742 -304.416714)
		(end 14.063726 -304.542698)
		(width 0.20066)
		(layer "F.Cu")
		(net "M_D_CPU1_SA_DQ<11>")
	)
	(segment
		(start 14.560042 -304.85588)
		(end 14.574266 -304.841656)
		(width 0.101854)
		(layer "F.Cu")
		(net "M_D_CPU1_SA_DQ<11>")
	)
	(segment
		(start 14.063726 -304.713386)
		(end 14.20622 -304.85588)
		(width 0.20066)
		(layer "F.Cu")
		(net "M_D_CPU1_SA_DQ<11>")
	)
	(segment
		(start 17.42948 -304.841656)
		(end 17.578578 -304.692558)
		(width 0.20066)
		(layer "F.Cu")
		(net "M_D_CPU1_SA_DQ<11>")
	)
	(segment
		(start 14.20622 -304.85588)
		(end 14.560042 -304.85588)
		(width 0.20066)
		(layer "F.Cu")
		(net "M_D_CPU1_SA_DQ<11>")
	)
	(segment
		(start 17.707102 -304.412396)
		(end 18.102326 -304.412396)
		(width 0.20066)
		(layer "F.Cu")
		(net "M_D_CPU1_SA_DQ<11>")
	)
	(segment
		(start 20.889214 -304.416714)
		(end 19.784314 -304.416714)
		(width 0.20066)
		(layer "F.Cu")
		(net "M_D_CPU1_SA_DQ<11>")
	)
	(segment
		(start 18.314162 -304.624232)
		(end 18.760694 -304.624232)
		(width 0.20066)
		(layer "F.Cu")
		(net "M_D_CPU1_SA_DQ<11>")
	)
	(segment
		(start 18.760694 -304.624232)
		(end 18.968212 -304.416714)
		(width 0.20066)
		(layer "F.Cu")
		(net "M_D_CPU1_SA_DQ<11>")
	)
	(segment
		(start 96.915478 -278.652224)
		(end 96.900746 -278.66086)
		(width 0.088646)
		(layer "In11.Cu")
		(net "M_D_CPU1_SA_DQ<11>")
	)
	(segment
		(start 98.795078 -278.02078)
		(end 98.780346 -278.012144)
		(width 0.088646)
		(layer "In11.Cu")
		(net "M_D_CPU1_SA_DQ<11>")
	)
	(segment
		(start 83.191858 -282.860242)
		(end 73.732136 -292.319964)
		(width 0.18288)
		(layer "In11.Cu")
		(net "M_D_CPU1_SA_DQ<11>")
	)
	(segment
		(start 30.253686 -311.675526)
		(end 29.460698 -311.675526)
		(width 0.18288)
		(layer "In11.Cu")
		(net "M_D_CPU1_SA_DQ<11>")
	)
	(segment
		(start 28.861512 -311.07634)
		(end 25.987502 -311.07634)
		(width 0.18288)
		(layer "In11.Cu")
		(net "M_D_CPU1_SA_DQ<11>")
	)
	(segment
		(start 55.498746 -307.52796)
		(end 54.660546 -308.36616)
		(width 0.18288)
		(layer "In11.Cu")
		(net "M_D_CPU1_SA_DQ<11>")
	)
	(segment
		(start 23.799546 -309.609744)
		(end 23.799546 -305.891184)
		(width 0.18288)
		(layer "In11.Cu")
		(net "M_D_CPU1_SA_DQ<11>")
	)
	(segment
		(start 91.272106 -278.654764)
		(end 91.261692 -278.66086)
		(width 0.088646)
		(layer "In11.Cu")
		(net "M_D_CPU1_SA_DQ<11>")
	)
	(segment
		(start 99.720146 -278.012144)
		(end 99.719892 -278.012144)
		(width 0.088646)
		(layer "In11.Cu")
		(net "M_D_CPU1_SA_DQ<11>")
	)
	(segment
		(start 83.975448 -282.860242)
		(end 83.769454 -282.860242)
		(width 0.088646)
		(layer "In11.Cu")
		(net "M_D_CPU1_SA_DQ<11>")
	)
	(segment
		(start 29.460698 -311.675526)
		(end 28.861512 -311.07634)
		(width 0.18288)
		(layer "In11.Cu")
		(net "M_D_CPU1_SA_DQ<11>")
	)
	(segment
		(start 43.972226 -310.900826)
		(end 40.92829 -310.900826)
		(width 0.18288)
		(layer "In11.Cu")
		(net "M_D_CPU1_SA_DQ<11>")
	)
	(segment
		(start 34.15284 -310.928766)
		(end 32.375856 -310.928766)
		(width 0.18288)
		(layer "In11.Cu")
		(net "M_D_CPU1_SA_DQ<11>")
	)
	(segment
		(start 85.810344 -279.954228)
		(end 85.810344 -279.964134)
		(width 0.088646)
		(layer "In11.Cu")
		(net "M_D_CPU1_SA_DQ<11>")
	)
	(segment
		(start 21.477224 -305.004724)
		(end 20.889214 -304.416714)
		(width 0.18288)
		(layer "In11.Cu")
		(net "M_D_CPU1_SA_DQ<11>")
	)
	(segment
		(start 73.732136 -292.319964)
		(end 73.732136 -293.133526)
		(width 0.18288)
		(layer "In11.Cu")
		(net "M_D_CPU1_SA_DQ<11>")
	)
	(segment
		(start 64.787526 -304.127662)
		(end 63.225172 -304.127662)
		(width 0.18288)
		(layer "In11.Cu")
		(net "M_D_CPU1_SA_DQ<11>")
	)
	(segment
		(start 23.799546 -305.891184)
		(end 22.913086 -305.004724)
		(width 0.18288)
		(layer "In11.Cu")
		(net "M_D_CPU1_SA_DQ<11>")
	)
	(segment
		(start 44.582588 -310.290464)
		(end 43.972226 -310.900826)
		(width 0.18288)
		(layer "In11.Cu")
		(net "M_D_CPU1_SA_DQ<11>")
	)
	(segment
		(start 51.358038 -309.94223)
		(end 50.226976 -309.94223)
		(width 0.18288)
		(layer "In11.Cu")
		(net "M_D_CPU1_SA_DQ<11>")
	)
	(segment
		(start 66.420238 -303.142904)
		(end 65.772284 -303.142904)
		(width 0.18288)
		(layer "In11.Cu")
		(net "M_D_CPU1_SA_DQ<11>")
	)
	(segment
		(start 36.459668 -309.94223)
		(end 35.139376 -309.94223)
		(width 0.18288)
		(layer "In11.Cu")
		(net "M_D_CPU1_SA_DQ<11>")
	)
	(segment
		(start 97.8408 -278.660606)
		(end 97.840546 -278.66086)
		(width 0.088646)
		(layer "In11.Cu")
		(net "M_D_CPU1_SA_DQ<11>")
	)
	(segment
		(start 93.156278 -278.652224)
		(end 93.141546 -278.66086)
		(width 0.088646)
		(layer "In11.Cu")
		(net "M_D_CPU1_SA_DQ<11>")
	)
	(segment
		(start 99.749356 -278.029162)
		(end 99.720146 -278.012144)
		(width 0.088646)
		(layer "In11.Cu")
		(net "M_D_CPU1_SA_DQ<11>")
	)
	(segment
		(start 59.285632 -303.83226)
		(end 57.962546 -305.155346)
		(width 0.18288)
		(layer "In11.Cu")
		(net "M_D_CPU1_SA_DQ<11>")
	)
	(segment
		(start 45.625258 -310.290464)
		(end 44.582588 -310.290464)
		(width 0.18288)
		(layer "In11.Cu")
		(net "M_D_CPU1_SA_DQ<11>")
	)
	(segment
		(start 88.159844 -279.140412)
		(end 88.159844 -279.150318)
		(width 0.088646)
		(layer "In11.Cu")
		(net "M_D_CPU1_SA_DQ<11>")
	)
	(segment
		(start 50.226976 -309.94223)
		(end 49.19218 -310.977026)
		(width 0.18288)
		(layer "In11.Cu")
		(net "M_D_CPU1_SA_DQ<11>")
	)
	(segment
		(start 40.92829 -310.900826)
		(end 40.086788 -310.059324)
		(width 0.18288)
		(layer "In11.Cu")
		(net "M_D_CPU1_SA_DQ<11>")
	)
	(segment
		(start 69.939408 -296.926254)
		(end 69.939408 -299.623734)
		(width 0.18288)
		(layer "In11.Cu")
		(net "M_D_CPU1_SA_DQ<11>")
	)
	(segment
		(start 36.576762 -310.059324)
		(end 36.459668 -309.94223)
		(width 0.18288)
		(layer "In11.Cu")
		(net "M_D_CPU1_SA_DQ<11>")
	)
	(segment
		(start 52.465224 -310.078882)
		(end 51.49469 -310.078882)
		(width 0.18288)
		(layer "In11.Cu")
		(net "M_D_CPU1_SA_DQ<11>")
	)
	(segment
		(start 95.035878 -278.652224)
		(end 95.021146 -278.66086)
		(width 0.088646)
		(layer "In11.Cu")
		(net "M_D_CPU1_SA_DQ<11>")
	)
	(segment
		(start 40.086788 -310.059324)
		(end 36.576762 -310.059324)
		(width 0.18288)
		(layer "In11.Cu")
		(net "M_D_CPU1_SA_DQ<11>")
	)
	(segment
		(start 32.375856 -310.928766)
		(end 32.239204 -310.792114)
		(width 0.18288)
		(layer "In11.Cu")
		(net "M_D_CPU1_SA_DQ<11>")
	)
	(segment
		(start 48.163226 -310.977026)
		(end 47.978314 -310.792114)
		(width 0.18288)
		(layer "In11.Cu")
		(net "M_D_CPU1_SA_DQ<11>")
	)
	(segment
		(start 85.631782 -280.283412)
		(end 85.622892 -280.288492)
		(width 0.088646)
		(layer "In11.Cu")
		(net "M_D_CPU1_SA_DQ<11>")
	)
	(segment
		(start 100.472748 -278.336502)
		(end 99.749356 -278.029162)
		(width 0.088646)
		(layer "In11.Cu")
		(net "M_D_CPU1_SA_DQ<11>")
	)
	(segment
		(start 54.660546 -308.36616)
		(end 54.177946 -308.36616)
		(width 0.18288)
		(layer "In11.Cu")
		(net "M_D_CPU1_SA_DQ<11>")
	)
	(segment
		(start 85.340444 -281.495246)
		(end 83.975448 -282.860242)
		(width 0.088646)
		(layer "In11.Cu")
		(net "M_D_CPU1_SA_DQ<11>")
	)
	(segment
		(start 92.216478 -278.652224)
		(end 92.201746 -278.66086)
		(width 0.088646)
		(layer "In11.Cu")
		(net "M_D_CPU1_SA_DQ<11>")
	)
	(segment
		(start 95.975678 -278.652224)
		(end 95.960946 -278.66086)
		(width 0.088646)
		(layer "In11.Cu")
		(net "M_D_CPU1_SA_DQ<11>")
	)
	(segment
		(start 57.962546 -305.155346)
		(end 57.962546 -306.02936)
		(width 0.18288)
		(layer "In11.Cu")
		(net "M_D_CPU1_SA_DQ<11>")
	)
	(segment
		(start 57.962546 -306.02936)
		(end 56.463946 -307.52796)
		(width 0.18288)
		(layer "In11.Cu")
		(net "M_D_CPU1_SA_DQ<11>")
	)
	(segment
		(start 69.939408 -299.623734)
		(end 66.420238 -303.142904)
		(width 0.18288)
		(layer "In11.Cu")
		(net "M_D_CPU1_SA_DQ<11>")
	)
	(segment
		(start 73.732136 -293.133526)
		(end 69.939408 -296.926254)
		(width 0.18288)
		(layer "In11.Cu")
		(net "M_D_CPU1_SA_DQ<11>")
	)
	(segment
		(start 22.913086 -305.004724)
		(end 21.477224 -305.004724)
		(width 0.18288)
		(layer "In11.Cu")
		(net "M_D_CPU1_SA_DQ<11>")
	)
	(segment
		(start 47.978314 -310.792114)
		(end 46.126908 -310.792114)
		(width 0.18288)
		(layer "In11.Cu")
		(net "M_D_CPU1_SA_DQ<11>")
	)
	(segment
		(start 54.177946 -308.36616)
		(end 52.465224 -310.078882)
		(width 0.18288)
		(layer "In11.Cu")
		(net "M_D_CPU1_SA_DQ<11>")
	)
	(segment
		(start 65.772284 -303.142904)
		(end 64.787526 -304.127662)
		(width 0.18288)
		(layer "In11.Cu")
		(net "M_D_CPU1_SA_DQ<11>")
	)
	(segment
		(start 51.49469 -310.078882)
		(end 51.358038 -309.94223)
		(width 0.18288)
		(layer "In11.Cu")
		(net "M_D_CPU1_SA_DQ<11>")
	)
	(segment
		(start 49.19218 -310.977026)
		(end 48.163226 -310.977026)
		(width 0.18288)
		(layer "In11.Cu")
		(net "M_D_CPU1_SA_DQ<11>")
	)
	(segment
		(start 85.340444 -280.759662)
		(end 85.340444 -281.495246)
		(width 0.088646)
		(layer "In11.Cu")
		(net "M_D_CPU1_SA_DQ<11>")
	)
	(segment
		(start 63.08852 -303.99101)
		(end 60.23864 -303.99101)
		(width 0.18288)
		(layer "In11.Cu")
		(net "M_D_CPU1_SA_DQ<11>")
	)
	(segment
		(start 46.126908 -310.792114)
		(end 45.625258 -310.290464)
		(width 0.18288)
		(layer "In11.Cu")
		(net "M_D_CPU1_SA_DQ<11>")
	)
	(segment
		(start 87.981282 -279.469596)
		(end 87.972392 -279.474676)
		(width 0.088646)
		(layer "In11.Cu")
		(net "M_D_CPU1_SA_DQ<11>")
	)
	(segment
		(start 97.840546 -278.66086)
		(end 97.840292 -278.66086)
		(width 0.088646)
		(layer "In11.Cu")
		(net "M_D_CPU1_SA_DQ<11>")
	)
	(segment
		(start 32.239204 -310.792114)
		(end 31.137098 -310.792114)
		(width 0.18288)
		(layer "In11.Cu")
		(net "M_D_CPU1_SA_DQ<11>")
	)
	(segment
		(start 98.780346 -278.012144)
		(end 98.780092 -278.012144)
		(width 0.088646)
		(layer "In11.Cu")
		(net "M_D_CPU1_SA_DQ<11>")
	)
	(segment
		(start 83.769454 -282.860242)
		(end 83.191858 -282.860242)
		(width 0.18288)
		(layer "In11.Cu")
		(net "M_D_CPU1_SA_DQ<11>")
	)
	(segment
		(start 24.291544 -310.101742)
		(end 23.799546 -309.609744)
		(width 0.18288)
		(layer "In11.Cu")
		(net "M_D_CPU1_SA_DQ<11>")
	)
	(segment
		(start 31.137098 -310.792114)
		(end 30.253686 -311.675526)
		(width 0.18288)
		(layer "In11.Cu")
		(net "M_D_CPU1_SA_DQ<11>")
	)
	(segment
		(start 60.23864 -303.99101)
		(end 60.07989 -303.83226)
		(width 0.18288)
		(layer "In11.Cu")
		(net "M_D_CPU1_SA_DQ<11>")
	)
	(segment
		(start 60.07989 -303.83226)
		(end 59.285632 -303.83226)
		(width 0.18288)
		(layer "In11.Cu")
		(net "M_D_CPU1_SA_DQ<11>")
	)
	(segment
		(start 63.225172 -304.127662)
		(end 63.08852 -303.99101)
		(width 0.18288)
		(layer "In11.Cu")
		(net "M_D_CPU1_SA_DQ<11>")
	)
	(segment
		(start 25.012904 -310.101742)
		(end 24.291544 -310.101742)
		(width 0.18288)
		(layer "In11.Cu")
		(net "M_D_CPU1_SA_DQ<11>")
	)
	(segment
		(start 35.139376 -309.94223)
		(end 34.15284 -310.928766)
		(width 0.18288)
		(layer "In11.Cu")
		(net "M_D_CPU1_SA_DQ<11>")
	)
	(segment
		(start 25.987502 -311.07634)
		(end 25.012904 -310.101742)
		(width 0.18288)
		(layer "In11.Cu")
		(net "M_D_CPU1_SA_DQ<11>")
	)
	(segment
		(start 98.40595 -278.012144)
		(end 98.119946 -278.177498)
		(width 0.088646)
		(layer "In11.Cu")
		(net "M_D_CPU1_SA_DQ<11>")
	)
	(segment
		(start 56.463946 -307.52796)
		(end 55.498746 -307.52796)
		(width 0.18288)
		(layer "In11.Cu")
		(net "M_D_CPU1_SA_DQ<11>")
	)
	(arc
		(start 97.46615 -278.66086)
		(mid 97.191951 -278.585025)
		(end 96.915478 -278.652224)
		(width 0.088646)
		(layer "In11.Cu")
		(net "M_D_CPU1_SA_DQ<11>")
	)
	(arc
		(start 88.159844 -279.150318)
		(mid 88.112165 -279.333218)
		(end 87.981282 -279.469596)
		(width 0.088646)
		(layer "In11.Cu")
		(net "M_D_CPU1_SA_DQ<11>")
	)
	(arc
		(start 89.947496 -278.66086)
		(mid 89.664794 -278.585084)
		(end 89.382092 -278.66086)
		(width 0.088646)
		(layer "In11.Cu")
		(net "M_D_CPU1_SA_DQ<11>")
	)
	(arc
		(start 90.887296 -278.66086)
		(mid 90.604594 -278.585084)
		(end 90.321892 -278.66086)
		(width 0.088646)
		(layer "In11.Cu")
		(net "M_D_CPU1_SA_DQ<11>")
	)
	(arc
		(start 92.201746 -278.66086)
		(mid 92.014548 -278.711003)
		(end 91.82735 -278.66086)
		(width 0.088646)
		(layer "In11.Cu")
		(net "M_D_CPU1_SA_DQ<11>")
	)
	(arc
		(start 88.442292 -278.66086)
		(mid 88.237957 -278.863465)
		(end 88.159844 -279.140412)
		(width 0.088646)
		(layer "In11.Cu")
		(net "M_D_CPU1_SA_DQ<11>")
	)
	(arc
		(start 87.597996 -279.474676)
		(mid 87.315294 -279.3989)
		(end 87.032592 -279.474676)
		(width 0.088646)
		(layer "In11.Cu")
		(net "M_D_CPU1_SA_DQ<11>")
	)
	(arc
		(start 93.70695 -278.66086)
		(mid 93.432751 -278.585025)
		(end 93.156278 -278.652224)
		(width 0.088646)
		(layer "In11.Cu")
		(net "M_D_CPU1_SA_DQ<11>")
	)
	(arc
		(start 91.261692 -278.66086)
		(mid 91.074494 -278.711003)
		(end 90.887296 -278.66086)
		(width 0.088646)
		(layer "In11.Cu")
		(net "M_D_CPU1_SA_DQ<11>")
	)
	(arc
		(start 85.622892 -280.288492)
		(mid 85.420606 -280.487473)
		(end 85.340444 -280.759662)
		(width 0.088646)
		(layer "In11.Cu")
		(net "M_D_CPU1_SA_DQ<11>")
	)
	(arc
		(start 89.007696 -278.66086)
		(mid 88.724994 -278.585084)
		(end 88.442292 -278.66086)
		(width 0.088646)
		(layer "In11.Cu")
		(net "M_D_CPU1_SA_DQ<11>")
	)
	(arc
		(start 94.64675 -278.66086)
		(mid 94.364048 -278.585084)
		(end 94.081346 -278.66086)
		(width 0.088646)
		(layer "In11.Cu")
		(net "M_D_CPU1_SA_DQ<11>")
	)
	(arc
		(start 94.081346 -278.66086)
		(mid 93.894148 -278.711003)
		(end 93.70695 -278.66086)
		(width 0.088646)
		(layer "In11.Cu")
		(net "M_D_CPU1_SA_DQ<11>")
	)
	(arc
		(start 90.321892 -278.66086)
		(mid 90.134694 -278.711003)
		(end 89.947496 -278.66086)
		(width 0.088646)
		(layer "In11.Cu")
		(net "M_D_CPU1_SA_DQ<11>")
	)
	(arc
		(start 91.82735 -278.66086)
		(mid 91.550537 -278.58499)
		(end 91.272106 -278.654764)
		(width 0.088646)
		(layer "In11.Cu")
		(net "M_D_CPU1_SA_DQ<11>")
	)
	(arc
		(start 97.840292 -278.66086)
		(mid 97.653238 -278.710944)
		(end 97.46615 -278.66086)
		(width 0.088646)
		(layer "In11.Cu")
		(net "M_D_CPU1_SA_DQ<11>")
	)
	(arc
		(start 96.52635 -278.66086)
		(mid 96.252151 -278.585025)
		(end 95.975678 -278.652224)
		(width 0.088646)
		(layer "In11.Cu")
		(net "M_D_CPU1_SA_DQ<11>")
	)
	(arc
		(start 89.382092 -278.66086)
		(mid 89.194894 -278.711003)
		(end 89.007696 -278.66086)
		(width 0.088646)
		(layer "In11.Cu")
		(net "M_D_CPU1_SA_DQ<11>")
	)
	(arc
		(start 99.719892 -278.012144)
		(mid 99.532838 -277.962094)
		(end 99.34575 -278.012144)
		(width 0.088646)
		(layer "In11.Cu")
		(net "M_D_CPU1_SA_DQ<11>")
	)
	(arc
		(start 96.900746 -278.66086)
		(mid 96.713548 -278.711003)
		(end 96.52635 -278.66086)
		(width 0.088646)
		(layer "In11.Cu")
		(net "M_D_CPU1_SA_DQ<11>")
	)
	(arc
		(start 95.960946 -278.66086)
		(mid 95.773748 -278.711003)
		(end 95.58655 -278.66086)
		(width 0.088646)
		(layer "In11.Cu")
		(net "M_D_CPU1_SA_DQ<11>")
	)
	(arc
		(start 93.141546 -278.66086)
		(mid 92.954348 -278.711003)
		(end 92.76715 -278.66086)
		(width 0.088646)
		(layer "In11.Cu")
		(net "M_D_CPU1_SA_DQ<11>")
	)
	(arc
		(start 92.76715 -278.66086)
		(mid 92.492951 -278.585025)
		(end 92.216478 -278.652224)
		(width 0.088646)
		(layer "In11.Cu")
		(net "M_D_CPU1_SA_DQ<11>")
	)
	(arc
		(start 98.119946 -278.177498)
		(mid 98.052616 -278.244656)
		(end 98.027998 -278.336502)
		(width 0.088646)
		(layer "In11.Cu")
		(net "M_D_CPU1_SA_DQ<11>")
	)
	(arc
		(start 87.972392 -279.474676)
		(mid 87.785194 -279.524819)
		(end 87.597996 -279.474676)
		(width 0.088646)
		(layer "In11.Cu")
		(net "M_D_CPU1_SA_DQ<11>")
	)
	(arc
		(start 98.027998 -278.336502)
		(mid 97.977834 -278.52364)
		(end 97.8408 -278.660606)
		(width 0.088646)
		(layer "In11.Cu")
		(net "M_D_CPU1_SA_DQ<11>")
	)
	(arc
		(start 85.810344 -279.964134)
		(mid 85.762665 -280.147034)
		(end 85.631782 -280.283412)
		(width 0.088646)
		(layer "In11.Cu")
		(net "M_D_CPU1_SA_DQ<11>")
	)
	(arc
		(start 95.58655 -278.66086)
		(mid 95.312351 -278.585025)
		(end 95.035878 -278.652224)
		(width 0.088646)
		(layer "In11.Cu")
		(net "M_D_CPU1_SA_DQ<11>")
	)
	(arc
		(start 87.032592 -279.474676)
		(mid 86.845394 -279.524819)
		(end 86.658196 -279.474676)
		(width 0.088646)
		(layer "In11.Cu")
		(net "M_D_CPU1_SA_DQ<11>")
	)
	(arc
		(start 95.021146 -278.66086)
		(mid 94.833948 -278.711003)
		(end 94.64675 -278.66086)
		(width 0.088646)
		(layer "In11.Cu")
		(net "M_D_CPU1_SA_DQ<11>")
	)
	(arc
		(start 86.658196 -279.474676)
		(mid 86.375494 -279.3989)
		(end 86.092792 -279.474676)
		(width 0.088646)
		(layer "In11.Cu")
		(net "M_D_CPU1_SA_DQ<11>")
	)
	(arc
		(start 98.780092 -278.012144)
		(mid 98.593038 -277.962094)
		(end 98.40595 -278.012144)
		(width 0.088646)
		(layer "In11.Cu")
		(net "M_D_CPU1_SA_DQ<11>")
	)
	(arc
		(start 99.34575 -278.012144)
		(mid 99.071521 -278.088069)
		(end 98.795078 -278.02078)
		(width 0.088646)
		(layer "In11.Cu")
		(net "M_D_CPU1_SA_DQ<11>")
	)
	(arc
		(start 86.092792 -279.474676)
		(mid 85.888457 -279.677281)
		(end 85.810344 -279.954228)
		(width 0.088646)
		(layer "In11.Cu")
		(net "M_D_CPU1_SA_DQ<11>")
	)
	(segment
		(start 100.002848 -278.614378)
		(end 100.002848 -279.150064)
		(width 0.20066)
		(layer "F.Cu")
		(net "M_D_CPU1_SA_DQ<10>")
	)
	(segment
		(start 13.82268 -305.681634)
		(end 14.560042 -305.681634)
		(width 0.20066)
		(layer "F.Cu")
		(net "M_D_CPU1_SA_DQ<10>")
	)
	(segment
		(start 13.387578 -306.116736)
		(end 13.82268 -305.681634)
		(width 0.20066)
		(layer "F.Cu")
		(net "M_D_CPU1_SA_DQ<10>")
	)
	(segment
		(start 17.829276 -306.328572)
		(end 18.257774 -306.328572)
		(width 0.20066)
		(layer "F.Cu")
		(net "M_D_CPU1_SA_DQ<10>")
	)
	(segment
		(start 20.889214 -306.116736)
		(end 19.784314 -306.116736)
		(width 0.20066)
		(layer "F.Cu")
		(net "M_D_CPU1_SA_DQ<10>")
	)
	(segment
		(start 14.560042 -305.681634)
		(end 14.570202 -305.691794)
		(width 0.101854)
		(layer "F.Cu")
		(net "M_D_CPU1_SA_DQ<10>")
	)
	(segment
		(start 100.002848 -279.150064)
		(end 100.002594 -279.150318)
		(width 0.20066)
		(layer "F.Cu")
		(net "M_D_CPU1_SA_DQ<10>")
	)
	(segment
		(start 16.885158 -305.691794)
		(end 17.518126 -305.691794)
		(width 0.20066)
		(layer "F.Cu")
		(net "M_D_CPU1_SA_DQ<10>")
	)
	(segment
		(start 12.240514 -306.116736)
		(end 13.387578 -306.116736)
		(width 0.20066)
		(layer "F.Cu")
		(net "M_D_CPU1_SA_DQ<10>")
	)
	(segment
		(start 18.257774 -306.328572)
		(end 18.46961 -306.116736)
		(width 0.20066)
		(layer "F.Cu")
		(net "M_D_CPU1_SA_DQ<10>")
	)
	(segment
		(start 17.66189 -305.835558)
		(end 17.66189 -306.161186)
		(width 0.20066)
		(layer "F.Cu")
		(net "M_D_CPU1_SA_DQ<10>")
	)
	(segment
		(start 14.570202 -305.691794)
		(end 14.825218 -305.691794)
		(width 0.101854)
		(layer "F.Cu")
		(net "M_D_CPU1_SA_DQ<10>")
	)
	(segment
		(start 14.825218 -305.691794)
		(end 16.885158 -305.691794)
		(width 0.1016)
		(layer "F.Cu")
		(net "M_D_CPU1_SA_DQ<10>")
	)
	(segment
		(start 17.518126 -305.691794)
		(end 17.66189 -305.835558)
		(width 0.20066)
		(layer "F.Cu")
		(net "M_D_CPU1_SA_DQ<10>")
	)
	(segment
		(start 17.66189 -306.161186)
		(end 17.829276 -306.328572)
		(width 0.20066)
		(layer "F.Cu")
		(net "M_D_CPU1_SA_DQ<10>")
	)
	(segment
		(start 18.46961 -306.116736)
		(end 19.784314 -306.116736)
		(width 0.20066)
		(layer "F.Cu")
		(net "M_D_CPU1_SA_DQ<10>")
	)
	(segment
		(start 27.054556 -313.076844)
		(end 26.861516 -312.883804)
		(width 0.18288)
		(layer "In11.Cu")
		(net "M_D_CPU1_SA_DQ<10>")
	)
	(segment
		(start 86.280244 -280.759662)
		(end 86.280244 -280.778204)
		(width 0.088646)
		(layer "In11.Cu")
		(net "M_D_CPU1_SA_DQ<10>")
	)
	(segment
		(start 50.127154 -313.244484)
		(end 49.934114 -313.437524)
		(width 0.18288)
		(layer "In11.Cu")
		(net "M_D_CPU1_SA_DQ<10>")
	)
	(segment
		(start 53.822854 -310.473598)
		(end 51.803554 -312.492898)
		(width 0.18288)
		(layer "In11.Cu")
		(net "M_D_CPU1_SA_DQ<10>")
	)
	(segment
		(start 40.946324 -312.463688)
		(end 40.293544 -311.810908)
		(width 0.18288)
		(layer "In11.Cu")
		(net "M_D_CPU1_SA_DQ<10>")
	)
	(segment
		(start 85.810344 -281.667204)
		(end 85.242908 -282.23464)
		(width 0.088646)
		(layer "In11.Cu")
		(net "M_D_CPU1_SA_DQ<10>")
	)
	(segment
		(start 49.426114 -313.244484)
		(end 49.426114 -312.670698)
		(width 0.18288)
		(layer "In11.Cu")
		(net "M_D_CPU1_SA_DQ<10>")
	)
	(segment
		(start 57.921906 -307.847746)
		(end 56.616854 -309.152798)
		(width 0.18288)
		(layer "In11.Cu")
		(net "M_D_CPU1_SA_DQ<10>")
	)
	(segment
		(start 60.913264 -305.69408)
		(end 60.047378 -306.559966)
		(width 0.18288)
		(layer "In11.Cu")
		(net "M_D_CPU1_SA_DQ<10>")
	)
	(segment
		(start 27.755596 -312.339228)
		(end 27.562556 -312.532268)
		(width 0.18288)
		(layer "In11.Cu")
		(net "M_D_CPU1_SA_DQ<10>")
	)
	(segment
		(start 22.822916 -310.384444)
		(end 22.750526 -310.293258)
		(width 0.18288)
		(layer "In11.Cu")
		(net "M_D_CPU1_SA_DQ<10>")
	)
	(segment
		(start 59.718194 -306.559966)
		(end 58.790078 -307.488082)
		(width 0.18288)
		(layer "In11.Cu")
		(net "M_D_CPU1_SA_DQ<10>")
	)
	(segment
		(start 26.861516 -312.532268)
		(end 26.668476 -312.339228)
		(width 0.18288)
		(layer "In11.Cu")
		(net "M_D_CPU1_SA_DQ<10>")
	)
	(segment
		(start 49.619154 -313.437524)
		(end 49.426114 -313.244484)
		(width 0.18288)
		(layer "In11.Cu")
		(net "M_D_CPU1_SA_DQ<10>")
	)
	(segment
		(start 32.28594 -313.341512)
		(end 31.117794 -313.341512)
		(width 0.18288)
		(layer "In11.Cu")
		(net "M_D_CPU1_SA_DQ<10>")
	)
	(segment
		(start 30.836108 -313.059826)
		(end 29.285946 -313.059826)
		(width 0.18288)
		(layer "In11.Cu")
		(net "M_D_CPU1_SA_DQ<10>")
	)
	(segment
		(start 50.320194 -312.492898)
		(end 50.127154 -312.685938)
		(width 0.18288)
		(layer "In11.Cu")
		(net "M_D_CPU1_SA_DQ<10>")
	)
	(segment
		(start 29.285946 -313.059826)
		(end 28.565348 -312.339228)
		(width 0.18288)
		(layer "In11.Cu")
		(net "M_D_CPU1_SA_DQ<10>")
	)
	(segment
		(start 58.790078 -307.488082)
		(end 57.921906 -307.847746)
		(width 0.18288)
		(layer "In11.Cu")
		(net "M_D_CPU1_SA_DQ<10>")
	)
	(segment
		(start 88.451182 -280.283412)
		(end 88.442292 -280.288492)
		(width 0.088646)
		(layer "In11.Cu")
		(net "M_D_CPU1_SA_DQ<10>")
	)
	(segment
		(start 27.369516 -313.076844)
		(end 27.054556 -313.076844)
		(width 0.18288)
		(layer "In11.Cu")
		(net "M_D_CPU1_SA_DQ<10>")
	)
	(segment
		(start 46.205394 -313.341512)
		(end 45.32757 -312.463688)
		(width 0.18288)
		(layer "In11.Cu")
		(net "M_D_CPU1_SA_DQ<10>")
	)
	(segment
		(start 98.780346 -278.66086)
		(end 98.77425 -278.664416)
		(width 0.088646)
		(layer "In11.Cu")
		(net "M_D_CPU1_SA_DQ<10>")
	)
	(segment
		(start 50.127154 -312.685938)
		(end 50.127154 -313.244484)
		(width 0.18288)
		(layer "In11.Cu")
		(net "M_D_CPU1_SA_DQ<10>")
	)
	(segment
		(start 24.7777 -312.339228)
		(end 22.822916 -310.384444)
		(width 0.18288)
		(layer "In11.Cu")
		(net "M_D_CPU1_SA_DQ<10>")
	)
	(segment
		(start 36.38804 -312.489596)
		(end 33.137856 -312.489596)
		(width 0.18288)
		(layer "In11.Cu")
		(net "M_D_CPU1_SA_DQ<10>")
	)
	(segment
		(start 93.236796 -279.474676)
		(end 93.222064 -279.46604)
		(width 0.088646)
		(layer "In11.Cu")
		(net "M_D_CPU1_SA_DQ<10>")
	)
	(segment
		(start 92.296996 -279.474676)
		(end 92.282264 -279.46604)
		(width 0.088646)
		(layer "In11.Cu")
		(net "M_D_CPU1_SA_DQ<10>")
	)
	(segment
		(start 54.80431 -309.903622)
		(end 54.525418 -310.182514)
		(width 0.18288)
		(layer "In11.Cu")
		(net "M_D_CPU1_SA_DQ<10>")
	)
	(segment
		(start 98.497644 -279.150318)
		(end 98.497644 -279.158954)
		(width 0.088646)
		(layer "In11.Cu")
		(net "M_D_CPU1_SA_DQ<10>")
	)
	(segment
		(start 54.525418 -310.182514)
		(end 53.822854 -310.473598)
		(width 0.18288)
		(layer "In11.Cu")
		(net "M_D_CPU1_SA_DQ<10>")
	)
	(segment
		(start 70.981316 -300.256702)
		(end 66.395092 -304.842926)
		(width 0.18288)
		(layer "In11.Cu")
		(net "M_D_CPU1_SA_DQ<10>")
	)
	(segment
		(start 85.810344 -281.582114)
		(end 85.810344 -281.667204)
		(width 0.088646)
		(layer "In11.Cu")
		(net "M_D_CPU1_SA_DQ<10>")
	)
	(segment
		(start 70.981316 -297.47718)
		(end 70.981316 -300.256702)
		(width 0.18288)
		(layer "In11.Cu")
		(net "M_D_CPU1_SA_DQ<10>")
	)
	(segment
		(start 86.101682 -281.097482)
		(end 86.092792 -281.102562)
		(width 0.088646)
		(layer "In11.Cu")
		(net "M_D_CPU1_SA_DQ<10>")
	)
	(segment
		(start 27.562556 -312.532268)
		(end 27.562556 -312.883804)
		(width 0.18288)
		(layer "In11.Cu")
		(net "M_D_CPU1_SA_DQ<10>")
	)
	(segment
		(start 49.934114 -313.437524)
		(end 49.619154 -313.437524)
		(width 0.18288)
		(layer "In11.Cu")
		(net "M_D_CPU1_SA_DQ<10>")
	)
	(segment
		(start 85.242908 -282.23464)
		(end 85.242908 -282.443428)
		(width 0.088646)
		(layer "In11.Cu")
		(net "M_D_CPU1_SA_DQ<10>")
	)
	(segment
		(start 96.056196 -279.474676)
		(end 96.041464 -279.46604)
		(width 0.088646)
		(layer "In11.Cu")
		(net "M_D_CPU1_SA_DQ<10>")
	)
	(segment
		(start 74.791316 -292.702742)
		(end 74.791316 -293.66718)
		(width 0.18288)
		(layer "In11.Cu")
		(net "M_D_CPU1_SA_DQ<10>")
	)
	(segment
		(start 66.395092 -304.842926)
		(end 65.771268 -304.842926)
		(width 0.18288)
		(layer "In11.Cu")
		(net "M_D_CPU1_SA_DQ<10>")
	)
	(segment
		(start 22.750526 -310.293258)
		(end 22.750526 -307.421026)
		(width 0.18288)
		(layer "In11.Cu")
		(net "M_D_CPU1_SA_DQ<10>")
	)
	(segment
		(start 37.066728 -311.810908)
		(end 36.38804 -312.489596)
		(width 0.18288)
		(layer "In11.Cu")
		(net "M_D_CPU1_SA_DQ<10>")
	)
	(segment
		(start 83.469734 -284.024324)
		(end 74.791316 -292.702742)
		(width 0.18288)
		(layer "In11.Cu")
		(net "M_D_CPU1_SA_DQ<10>")
	)
	(segment
		(start 96.995996 -279.474676)
		(end 96.981264 -279.46604)
		(width 0.088646)
		(layer "In11.Cu")
		(net "M_D_CPU1_SA_DQ<10>")
	)
	(segment
		(start 91.357196 -279.474676)
		(end 91.342464 -279.46604)
		(width 0.088646)
		(layer "In11.Cu")
		(net "M_D_CPU1_SA_DQ<10>")
	)
	(segment
		(start 49.233074 -312.477658)
		(end 48.186594 -312.477658)
		(width 0.18288)
		(layer "In11.Cu")
		(net "M_D_CPU1_SA_DQ<10>")
	)
	(segment
		(start 51.803554 -312.492898)
		(end 50.320194 -312.492898)
		(width 0.18288)
		(layer "In11.Cu")
		(net "M_D_CPU1_SA_DQ<10>")
	)
	(segment
		(start 45.32757 -312.463688)
		(end 40.946324 -312.463688)
		(width 0.18288)
		(layer "In11.Cu")
		(net "M_D_CPU1_SA_DQ<10>")
	)
	(segment
		(start 26.861516 -312.883804)
		(end 26.861516 -312.532268)
		(width 0.18288)
		(layer "In11.Cu")
		(net "M_D_CPU1_SA_DQ<10>")
	)
	(segment
		(start 97.93605 -279.474676)
		(end 97.925636 -279.46858)
		(width 0.088646)
		(layer "In11.Cu")
		(net "M_D_CPU1_SA_DQ<10>")
	)
	(segment
		(start 94.56166 -279.46858)
		(end 94.551246 -279.474676)
		(width 0.088646)
		(layer "In11.Cu")
		(net "M_D_CPU1_SA_DQ<10>")
	)
	(segment
		(start 83.840066 -283.84627)
		(end 83.647788 -283.84627)
		(width 0.088646)
		(layer "In11.Cu")
		(net "M_D_CPU1_SA_DQ<10>")
	)
	(segment
		(start 31.117794 -313.341512)
		(end 30.836108 -313.059826)
		(width 0.18288)
		(layer "In11.Cu")
		(net "M_D_CPU1_SA_DQ<10>")
	)
	(segment
		(start 28.565348 -312.339228)
		(end 27.755596 -312.339228)
		(width 0.18288)
		(layer "In11.Cu")
		(net "M_D_CPU1_SA_DQ<10>")
	)
	(segment
		(start 22.750526 -307.421026)
		(end 22.040088 -306.710588)
		(width 0.18288)
		(layer "In11.Cu")
		(net "M_D_CPU1_SA_DQ<10>")
	)
	(segment
		(start 83.647788 -283.84627)
		(end 83.469734 -284.024324)
		(width 0.088646)
		(layer "In11.Cu")
		(net "M_D_CPU1_SA_DQ<10>")
	)
	(segment
		(start 56.616854 -309.152798)
		(end 54.80431 -309.903622)
		(width 0.18288)
		(layer "In11.Cu")
		(net "M_D_CPU1_SA_DQ<10>")
	)
	(segment
		(start 85.242908 -282.443428)
		(end 83.840066 -283.84627)
		(width 0.088646)
		(layer "In11.Cu")
		(net "M_D_CPU1_SA_DQ<10>")
	)
	(segment
		(start 22.040088 -306.710588)
		(end 21.483066 -306.710588)
		(width 0.18288)
		(layer "In11.Cu")
		(net "M_D_CPU1_SA_DQ<10>")
	)
	(segment
		(start 47.32274 -313.341512)
		(end 46.205394 -313.341512)
		(width 0.18288)
		(layer "In11.Cu")
		(net "M_D_CPU1_SA_DQ<10>")
	)
	(segment
		(start 49.426114 -312.670698)
		(end 49.233074 -312.477658)
		(width 0.18288)
		(layer "In11.Cu")
		(net "M_D_CPU1_SA_DQ<10>")
	)
	(segment
		(start 26.668476 -312.339228)
		(end 24.7777 -312.339228)
		(width 0.18288)
		(layer "In11.Cu")
		(net "M_D_CPU1_SA_DQ<10>")
	)
	(segment
		(start 93.621606 -279.46858)
		(end 93.611192 -279.474676)
		(width 0.088646)
		(layer "In11.Cu")
		(net "M_D_CPU1_SA_DQ<10>")
	)
	(segment
		(start 98.795078 -278.652224)
		(end 98.780346 -278.66086)
		(width 0.088646)
		(layer "In11.Cu")
		(net "M_D_CPU1_SA_DQ<10>")
	)
	(segment
		(start 60.047378 -306.559966)
		(end 59.718194 -306.559966)
		(width 0.18288)
		(layer "In11.Cu")
		(net "M_D_CPU1_SA_DQ<10>")
	)
	(segment
		(start 64.920114 -305.69408)
		(end 60.913264 -305.69408)
		(width 0.18288)
		(layer "In11.Cu")
		(net "M_D_CPU1_SA_DQ<10>")
	)
	(segment
		(start 33.137856 -312.489596)
		(end 32.28594 -313.341512)
		(width 0.18288)
		(layer "In11.Cu")
		(net "M_D_CPU1_SA_DQ<10>")
	)
	(segment
		(start 99.423982 -278.706072)
		(end 99.34575 -278.66086)
		(width 0.088646)
		(layer "In11.Cu")
		(net "M_D_CPU1_SA_DQ<10>")
	)
	(segment
		(start 74.791316 -293.66718)
		(end 70.981316 -297.47718)
		(width 0.18288)
		(layer "In11.Cu")
		(net "M_D_CPU1_SA_DQ<10>")
	)
	(segment
		(start 21.483066 -306.710588)
		(end 20.889214 -306.116736)
		(width 0.18288)
		(layer "In11.Cu")
		(net "M_D_CPU1_SA_DQ<10>")
	)
	(segment
		(start 27.562556 -312.883804)
		(end 27.369516 -313.076844)
		(width 0.18288)
		(layer "In11.Cu")
		(net "M_D_CPU1_SA_DQ<10>")
	)
	(segment
		(start 40.293544 -311.810908)
		(end 37.066728 -311.810908)
		(width 0.18288)
		(layer "In11.Cu")
		(net "M_D_CPU1_SA_DQ<10>")
	)
	(segment
		(start 48.186594 -312.477658)
		(end 47.32274 -313.341512)
		(width 0.18288)
		(layer "In11.Cu")
		(net "M_D_CPU1_SA_DQ<10>")
	)
	(segment
		(start 88.629744 -279.954228)
		(end 88.629744 -279.964134)
		(width 0.088646)
		(layer "In11.Cu")
		(net "M_D_CPU1_SA_DQ<10>")
	)
	(segment
		(start 65.771268 -304.842926)
		(end 64.920114 -305.69408)
		(width 0.18288)
		(layer "In11.Cu")
		(net "M_D_CPU1_SA_DQ<10>")
	)
	(arc
		(start 100.002594 -279.150318)
		(mid 99.727813 -278.909277)
		(end 99.423982 -278.706072)
		(width 0.088646)
		(layer "In11.Cu")
		(net "M_D_CPU1_SA_DQ<10>")
	)
	(arc
		(start 97.925636 -279.46858)
		(mid 97.647204 -279.398734)
		(end 97.370392 -279.474676)
		(width 0.088646)
		(layer "In11.Cu")
		(net "M_D_CPU1_SA_DQ<10>")
	)
	(arc
		(start 96.041464 -279.46604)
		(mid 95.764989 -279.39872)
		(end 95.490792 -279.474676)
		(width 0.088646)
		(layer "In11.Cu")
		(net "M_D_CPU1_SA_DQ<10>")
	)
	(arc
		(start 86.562692 -280.288492)
		(mid 86.360406 -280.487473)
		(end 86.280244 -280.759662)
		(width 0.088646)
		(layer "In11.Cu")
		(net "M_D_CPU1_SA_DQ<10>")
	)
	(arc
		(start 93.611192 -279.474676)
		(mid 93.423994 -279.524819)
		(end 93.236796 -279.474676)
		(width 0.088646)
		(layer "In11.Cu")
		(net "M_D_CPU1_SA_DQ<10>")
	)
	(arc
		(start 94.551246 -279.474676)
		(mid 94.364048 -279.524819)
		(end 94.17685 -279.474676)
		(width 0.088646)
		(layer "In11.Cu")
		(net "M_D_CPU1_SA_DQ<10>")
	)
	(arc
		(start 97.370392 -279.474676)
		(mid 97.183194 -279.524819)
		(end 96.995996 -279.474676)
		(width 0.088646)
		(layer "In11.Cu")
		(net "M_D_CPU1_SA_DQ<10>")
	)
	(arc
		(start 86.280244 -280.778204)
		(mid 86.232565 -280.961104)
		(end 86.101682 -281.097482)
		(width 0.088646)
		(layer "In11.Cu")
		(net "M_D_CPU1_SA_DQ<10>")
	)
	(arc
		(start 95.116396 -279.474676)
		(mid 94.839837 -279.398933)
		(end 94.56166 -279.46858)
		(width 0.088646)
		(layer "In11.Cu")
		(net "M_D_CPU1_SA_DQ<10>")
	)
	(arc
		(start 93.222064 -279.46604)
		(mid 92.945589 -279.39872)
		(end 92.671392 -279.474676)
		(width 0.088646)
		(layer "In11.Cu")
		(net "M_D_CPU1_SA_DQ<10>")
	)
	(arc
		(start 87.128096 -280.288492)
		(mid 86.845394 -280.21275)
		(end 86.562692 -280.288492)
		(width 0.088646)
		(layer "In11.Cu")
		(net "M_D_CPU1_SA_DQ<10>")
	)
	(arc
		(start 96.981264 -279.46604)
		(mid 96.704789 -279.39872)
		(end 96.430592 -279.474676)
		(width 0.088646)
		(layer "In11.Cu")
		(net "M_D_CPU1_SA_DQ<10>")
	)
	(arc
		(start 98.310446 -279.474676)
		(mid 98.123248 -279.524819)
		(end 97.93605 -279.474676)
		(width 0.088646)
		(layer "In11.Cu")
		(net "M_D_CPU1_SA_DQ<10>")
	)
	(arc
		(start 98.77425 -278.664416)
		(mid 98.571663 -278.870767)
		(end 98.497644 -279.150318)
		(width 0.088646)
		(layer "In11.Cu")
		(net "M_D_CPU1_SA_DQ<10>")
	)
	(arc
		(start 89.851992 -279.474676)
		(mid 89.664794 -279.524819)
		(end 89.477596 -279.474676)
		(width 0.088646)
		(layer "In11.Cu")
		(net "M_D_CPU1_SA_DQ<10>")
	)
	(arc
		(start 89.477596 -279.474676)
		(mid 89.194894 -279.3989)
		(end 88.912192 -279.474676)
		(width 0.088646)
		(layer "In11.Cu")
		(net "M_D_CPU1_SA_DQ<10>")
	)
	(arc
		(start 98.497644 -279.158954)
		(mid 98.445374 -279.341319)
		(end 98.310446 -279.474676)
		(width 0.088646)
		(layer "In11.Cu")
		(net "M_D_CPU1_SA_DQ<10>")
	)
	(arc
		(start 90.791792 -279.474676)
		(mid 90.604594 -279.524819)
		(end 90.417396 -279.474676)
		(width 0.088646)
		(layer "In11.Cu")
		(net "M_D_CPU1_SA_DQ<10>")
	)
	(arc
		(start 99.34575 -278.66086)
		(mid 99.071551 -278.585025)
		(end 98.795078 -278.652224)
		(width 0.088646)
		(layer "In11.Cu")
		(net "M_D_CPU1_SA_DQ<10>")
	)
	(arc
		(start 88.629744 -279.964134)
		(mid 88.582065 -280.147034)
		(end 88.451182 -280.283412)
		(width 0.088646)
		(layer "In11.Cu")
		(net "M_D_CPU1_SA_DQ<10>")
	)
	(arc
		(start 91.731592 -279.474676)
		(mid 91.544394 -279.524819)
		(end 91.357196 -279.474676)
		(width 0.088646)
		(layer "In11.Cu")
		(net "M_D_CPU1_SA_DQ<10>")
	)
	(arc
		(start 94.17685 -279.474676)
		(mid 93.900037 -279.398806)
		(end 93.621606 -279.46858)
		(width 0.088646)
		(layer "In11.Cu")
		(net "M_D_CPU1_SA_DQ<10>")
	)
	(arc
		(start 95.490792 -279.474676)
		(mid 95.303594 -279.524819)
		(end 95.116396 -279.474676)
		(width 0.088646)
		(layer "In11.Cu")
		(net "M_D_CPU1_SA_DQ<10>")
	)
	(arc
		(start 88.912192 -279.474676)
		(mid 88.707857 -279.677281)
		(end 88.629744 -279.954228)
		(width 0.088646)
		(layer "In11.Cu")
		(net "M_D_CPU1_SA_DQ<10>")
	)
	(arc
		(start 91.342464 -279.46604)
		(mid 91.065989 -279.39872)
		(end 90.791792 -279.474676)
		(width 0.088646)
		(layer "In11.Cu")
		(net "M_D_CPU1_SA_DQ<10>")
	)
	(arc
		(start 88.442292 -280.288492)
		(mid 88.255094 -280.338635)
		(end 88.067896 -280.288492)
		(width 0.088646)
		(layer "In11.Cu")
		(net "M_D_CPU1_SA_DQ<10>")
	)
	(arc
		(start 90.417396 -279.474676)
		(mid 90.134694 -279.3989)
		(end 89.851992 -279.474676)
		(width 0.088646)
		(layer "In11.Cu")
		(net "M_D_CPU1_SA_DQ<10>")
	)
	(arc
		(start 92.671392 -279.474676)
		(mid 92.484194 -279.524819)
		(end 92.296996 -279.474676)
		(width 0.088646)
		(layer "In11.Cu")
		(net "M_D_CPU1_SA_DQ<10>")
	)
	(arc
		(start 87.502492 -280.288492)
		(mid 87.315294 -280.338635)
		(end 87.128096 -280.288492)
		(width 0.088646)
		(layer "In11.Cu")
		(net "M_D_CPU1_SA_DQ<10>")
	)
	(arc
		(start 88.067896 -280.288492)
		(mid 87.785194 -280.21275)
		(end 87.502492 -280.288492)
		(width 0.088646)
		(layer "In11.Cu")
		(net "M_D_CPU1_SA_DQ<10>")
	)
	(arc
		(start 92.282264 -279.46604)
		(mid 92.005789 -279.39872)
		(end 91.731592 -279.474676)
		(width 0.088646)
		(layer "In11.Cu")
		(net "M_D_CPU1_SA_DQ<10>")
	)
	(arc
		(start 86.092792 -281.102562)
		(mid 85.888457 -281.305167)
		(end 85.810344 -281.582114)
		(width 0.088646)
		(layer "In11.Cu")
		(net "M_D_CPU1_SA_DQ<10>")
	)
	(arc
		(start 96.430592 -279.474676)
		(mid 96.243394 -279.524819)
		(end 96.056196 -279.474676)
		(width 0.088646)
		(layer "In11.Cu")
		(net "M_D_CPU1_SA_DQ<10>")
	)
	(segment
		(start 95.773494 -276.172676)
		(end 95.773494 -276.708362)
		(width 0.20066)
		(layer "F.Cu")
		(net "M_D_CPU1_SA_DQ<0>")
	)
	(segment
		(start 11.11631 -315.883544)
		(end 11.124438 -315.891672)
		(width 0.101854)
		(layer "F.Cu")
		(net "M_D_CPU1_SA_DQ<0>")
	)
	(segment
		(start 9.713468 -316.555374)
		(end 10.172192 -316.555374)
		(width 0.20066)
		(layer "F.Cu")
		(net "M_D_CPU1_SA_DQ<0>")
	)
	(segment
		(start 11.372342 -315.891672)
		(end 13.441426 -315.891672)
		(width 0.1016)
		(layer "F.Cu")
		(net "M_D_CPU1_SA_DQ<0>")
	)
	(segment
		(start 14.315186 -316.316614)
		(end 15.684246 -316.316614)
		(width 0.20066)
		(layer "F.Cu")
		(net "M_D_CPU1_SA_DQ<0>")
	)
	(segment
		(start 9.474708 -316.316614)
		(end 9.713468 -316.555374)
		(width 0.20066)
		(layer "F.Cu")
		(net "M_D_CPU1_SA_DQ<0>")
	)
	(segment
		(start 15.684246 -316.316614)
		(end 16.789146 -316.316614)
		(width 0.20066)
		(layer "F.Cu")
		(net "M_D_CPU1_SA_DQ<0>")
	)
	(segment
		(start 10.344912 -316.093094)
		(end 10.554462 -315.883544)
		(width 0.20066)
		(layer "F.Cu")
		(net "M_D_CPU1_SA_DQ<0>")
	)
	(segment
		(start 10.554462 -315.883544)
		(end 11.11631 -315.883544)
		(width 0.20066)
		(layer "F.Cu")
		(net "M_D_CPU1_SA_DQ<0>")
	)
	(segment
		(start 8.140446 -316.316614)
		(end 9.474708 -316.316614)
		(width 0.20066)
		(layer "F.Cu")
		(net "M_D_CPU1_SA_DQ<0>")
	)
	(segment
		(start 95.773494 -276.708362)
		(end 95.773748 -276.708616)
		(width 0.20066)
		(layer "F.Cu")
		(net "M_D_CPU1_SA_DQ<0>")
	)
	(segment
		(start 13.890244 -315.891672)
		(end 14.315186 -316.316614)
		(width 0.20066)
		(layer "F.Cu")
		(net "M_D_CPU1_SA_DQ<0>")
	)
	(segment
		(start 10.344912 -316.382654)
		(end 10.344912 -316.093094)
		(width 0.20066)
		(layer "F.Cu")
		(net "M_D_CPU1_SA_DQ<0>")
	)
	(segment
		(start 11.124438 -315.891672)
		(end 11.372342 -315.891672)
		(width 0.101854)
		(layer "F.Cu")
		(net "M_D_CPU1_SA_DQ<0>")
	)
	(segment
		(start 10.172192 -316.555374)
		(end 10.344912 -316.382654)
		(width 0.20066)
		(layer "F.Cu")
		(net "M_D_CPU1_SA_DQ<0>")
	)
	(segment
		(start 13.441426 -315.891672)
		(end 13.890244 -315.891672)
		(width 0.20066)
		(layer "F.Cu")
		(net "M_D_CPU1_SA_DQ<0>")
	)
	(segment
		(start 95.116396 -277.198074)
		(end 95.101664 -277.20671)
		(width 0.088646)
		(layer "In6.Cu")
		(net "M_D_CPU1_SA_DQ<0>")
	)
	(segment
		(start 70.30212 -299.334936)
		(end 67.784218 -301.852838)
		(width 0.18288)
		(layer "In6.Cu")
		(net "M_D_CPU1_SA_DQ<0>")
	)
	(segment
		(start 58.472324 -306.372006)
		(end 57.04205 -307.80228)
		(width 0.18288)
		(layer "In6.Cu")
		(net "M_D_CPU1_SA_DQ<0>")
	)
	(segment
		(start 50.866548 -310.79186)
		(end 50.120042 -311.538366)
		(width 0.18288)
		(layer "In6.Cu")
		(net "M_D_CPU1_SA_DQ<0>")
	)
	(segment
		(start 41.017698 -315.693044)
		(end 40.05707 -316.653672)
		(width 0.18288)
		(layer "In6.Cu")
		(net "M_D_CPU1_SA_DQ<0>")
	)
	(segment
		(start 95.122492 -277.194518)
		(end 95.116396 -277.198074)
		(width 0.088646)
		(layer "In6.Cu")
		(net "M_D_CPU1_SA_DQ<0>")
	)
	(segment
		(start 92.296996 -277.198074)
		(end 92.282264 -277.20671)
		(width 0.088646)
		(layer "In6.Cu")
		(net "M_D_CPU1_SA_DQ<0>")
	)
	(segment
		(start 90.887296 -278.012144)
		(end 90.878406 -278.017224)
		(width 0.088646)
		(layer "In6.Cu")
		(net "M_D_CPU1_SA_DQ<0>")
	)
	(segment
		(start 48.097186 -314.192158)
		(end 45.054774 -314.192158)
		(width 0.18288)
		(layer "In6.Cu")
		(net "M_D_CPU1_SA_DQ<0>")
	)
	(segment
		(start 66.455798 -303.991772)
		(end 65.753488 -303.991772)
		(width 0.18288)
		(layer "In6.Cu")
		(net "M_D_CPU1_SA_DQ<0>")
	)
	(segment
		(start 52.472844 -310.79186)
		(end 50.866548 -310.79186)
		(width 0.18288)
		(layer "In6.Cu")
		(net "M_D_CPU1_SA_DQ<0>")
	)
	(segment
		(start 50.120042 -311.538366)
		(end 50.120042 -312.169302)
		(width 0.18288)
		(layer "In6.Cu")
		(net "M_D_CPU1_SA_DQ<0>")
	)
	(segment
		(start 34.58591 -318.18453)
		(end 33.994852 -317.593472)
		(width 0.18288)
		(layer "In6.Cu")
		(net "M_D_CPU1_SA_DQ<0>")
	)
	(segment
		(start 91.169998 -277.513796)
		(end 91.169998 -277.536656)
		(width 0.088646)
		(layer "In6.Cu")
		(net "M_D_CPU1_SA_DQ<0>")
	)
	(segment
		(start 39.080694 -318.18453)
		(end 34.58591 -318.18453)
		(width 0.18288)
		(layer "In6.Cu")
		(net "M_D_CPU1_SA_DQ<0>")
	)
	(segment
		(start 85.718396 -282.081478)
		(end 85.718396 -282.081732)
		(width 0.088646)
		(layer "In6.Cu")
		(net "M_D_CPU1_SA_DQ<0>")
	)
	(segment
		(start 26.79827 -316.74181)
		(end 17.214342 -316.74181)
		(width 0.18288)
		(layer "In6.Cu")
		(net "M_D_CPU1_SA_DQ<0>")
	)
	(segment
		(start 60.82919 -304.84191)
		(end 60.367418 -305.303682)
		(width 0.18288)
		(layer "In6.Cu")
		(net "M_D_CPU1_SA_DQ<0>")
	)
	(segment
		(start 86.470744 -280.778204)
		(end 86.470744 -280.78811)
		(width 0.088646)
		(layer "In6.Cu")
		(net "M_D_CPU1_SA_DQ<0>")
	)
	(segment
		(start 54.330854 -308.925468)
		(end 54.330854 -308.93385)
		(width 0.18288)
		(layer "In6.Cu")
		(net "M_D_CPU1_SA_DQ<0>")
	)
	(segment
		(start 93.236796 -277.198074)
		(end 93.222064 -277.20671)
		(width 0.088646)
		(layer "In6.Cu")
		(net "M_D_CPU1_SA_DQ<0>")
	)
	(segment
		(start 50.120042 -312.169302)
		(end 48.097186 -314.192158)
		(width 0.18288)
		(layer "In6.Cu")
		(net "M_D_CPU1_SA_DQ<0>")
	)
	(segment
		(start 90.229944 -279.150318)
		(end 90.229944 -279.160224)
		(width 0.088646)
		(layer "In6.Cu")
		(net "M_D_CPU1_SA_DQ<0>")
	)
	(segment
		(start 95.773748 -276.708616)
		(end 96.086422 -276.708616)
		(width 0.088646)
		(layer "In6.Cu")
		(net "M_D_CPU1_SA_DQ<0>")
	)
	(segment
		(start 33.994852 -317.593472)
		(end 27.649932 -317.593472)
		(width 0.18288)
		(layer "In6.Cu")
		(net "M_D_CPU1_SA_DQ<0>")
	)
	(segment
		(start 60.367418 -305.303682)
		(end 59.741562 -305.563016)
		(width 0.18288)
		(layer "In6.Cu")
		(net "M_D_CPU1_SA_DQ<0>")
	)
	(segment
		(start 86.940644 -279.964134)
		(end 86.940644 -279.982676)
		(width 0.088646)
		(layer "In6.Cu")
		(net "M_D_CPU1_SA_DQ<0>")
	)
	(segment
		(start 40.05707 -316.653672)
		(end 40.05707 -317.208154)
		(width 0.18288)
		(layer "In6.Cu")
		(net "M_D_CPU1_SA_DQ<0>")
	)
	(segment
		(start 64.90335 -304.84191)
		(end 60.82919 -304.84191)
		(width 0.18288)
		(layer "In6.Cu")
		(net "M_D_CPU1_SA_DQ<0>")
	)
	(segment
		(start 95.58655 -276.384258)
		(end 95.57766 -276.389338)
		(width 0.088646)
		(layer "In6.Cu")
		(net "M_D_CPU1_SA_DQ<0>")
	)
	(segment
		(start 90.417396 -278.82596)
		(end 90.408506 -278.83104)
		(width 0.088646)
		(layer "In6.Cu")
		(net "M_D_CPU1_SA_DQ<0>")
	)
	(segment
		(start 54.330854 -308.93385)
		(end 52.472844 -310.79186)
		(width 0.18288)
		(layer "In6.Cu")
		(net "M_D_CPU1_SA_DQ<0>")
	)
	(segment
		(start 84.23148 -283.29509)
		(end 84.012532 -283.514038)
		(width 0.088646)
		(layer "In6.Cu")
		(net "M_D_CPU1_SA_DQ<0>")
	)
	(segment
		(start 45.054774 -314.192158)
		(end 43.553888 -315.693044)
		(width 0.18288)
		(layer "In6.Cu")
		(net "M_D_CPU1_SA_DQ<0>")
	)
	(segment
		(start 43.553888 -315.693044)
		(end 41.017698 -315.693044)
		(width 0.18288)
		(layer "In6.Cu")
		(net "M_D_CPU1_SA_DQ<0>")
	)
	(segment
		(start 57.04205 -307.80228)
		(end 54.330854 -308.925468)
		(width 0.18288)
		(layer "In6.Cu")
		(net "M_D_CPU1_SA_DQ<0>")
	)
	(segment
		(start 58.932572 -306.372006)
		(end 58.472324 -306.372006)
		(width 0.18288)
		(layer "In6.Cu")
		(net "M_D_CPU1_SA_DQ<0>")
	)
	(segment
		(start 87.128096 -279.639776)
		(end 87.119206 -279.644856)
		(width 0.088646)
		(layer "In6.Cu")
		(net "M_D_CPU1_SA_DQ<0>")
	)
	(segment
		(start 59.741562 -305.563016)
		(end 58.932572 -306.372006)
		(width 0.18288)
		(layer "In6.Cu")
		(net "M_D_CPU1_SA_DQ<0>")
	)
	(segment
		(start 96.086422 -276.708616)
		(end 96.143826 -276.651212)
		(width 0.088646)
		(layer "In6.Cu")
		(net "M_D_CPU1_SA_DQ<0>")
	)
	(segment
		(start 67.784218 -302.663352)
		(end 66.455798 -303.991772)
		(width 0.18288)
		(layer "In6.Cu")
		(net "M_D_CPU1_SA_DQ<0>")
	)
	(segment
		(start 94.176596 -277.198074)
		(end 94.161864 -277.20671)
		(width 0.088646)
		(layer "In6.Cu")
		(net "M_D_CPU1_SA_DQ<0>")
	)
	(segment
		(start 90.699844 -278.336502)
		(end 90.699844 -278.346408)
		(width 0.088646)
		(layer "In6.Cu")
		(net "M_D_CPU1_SA_DQ<0>")
	)
	(segment
		(start 27.649932 -317.593472)
		(end 26.79827 -316.74181)
		(width 0.18288)
		(layer "In6.Cu")
		(net "M_D_CPU1_SA_DQ<0>")
	)
	(segment
		(start 84.752688 -283.29509)
		(end 84.23148 -283.29509)
		(width 0.088646)
		(layer "In6.Cu")
		(net "M_D_CPU1_SA_DQ<0>")
	)
	(segment
		(start 85.530944 -282.39593)
		(end 85.530944 -282.516834)
		(width 0.088646)
		(layer "In6.Cu")
		(net "M_D_CPU1_SA_DQ<0>")
	)
	(segment
		(start 86.658196 -280.453846)
		(end 86.649306 -280.458926)
		(width 0.088646)
		(layer "In6.Cu")
		(net "M_D_CPU1_SA_DQ<0>")
	)
	(segment
		(start 65.753488 -303.991772)
		(end 64.90335 -304.84191)
		(width 0.18288)
		(layer "In6.Cu")
		(net "M_D_CPU1_SA_DQ<0>")
	)
	(segment
		(start 86.188296 -281.267662)
		(end 86.179406 -281.272742)
		(width 0.088646)
		(layer "In6.Cu")
		(net "M_D_CPU1_SA_DQ<0>")
	)
	(segment
		(start 95.969836 -276.389338)
		(end 95.960946 -276.384258)
		(width 0.088646)
		(layer "In6.Cu")
		(net "M_D_CPU1_SA_DQ<0>")
	)
	(segment
		(start 84.012532 -283.514038)
		(end 70.30212 -297.22445)
		(width 0.18288)
		(layer "In6.Cu")
		(net "M_D_CPU1_SA_DQ<0>")
	)
	(segment
		(start 85.530944 -282.516834)
		(end 84.752688 -283.29509)
		(width 0.088646)
		(layer "In6.Cu")
		(net "M_D_CPU1_SA_DQ<0>")
	)
	(segment
		(start 67.784218 -301.852838)
		(end 67.784218 -302.663352)
		(width 0.18288)
		(layer "In6.Cu")
		(net "M_D_CPU1_SA_DQ<0>")
	)
	(segment
		(start 17.214342 -316.74181)
		(end 16.789146 -316.316614)
		(width 0.18288)
		(layer "In6.Cu")
		(net "M_D_CPU1_SA_DQ<0>")
	)
	(segment
		(start 85.718396 -282.081732)
		(end 85.704172 -282.08986)
		(width 0.088646)
		(layer "In6.Cu")
		(net "M_D_CPU1_SA_DQ<0>")
	)
	(segment
		(start 86.000844 -281.59202)
		(end 86.000844 -281.601926)
		(width 0.088646)
		(layer "In6.Cu")
		(net "M_D_CPU1_SA_DQ<0>")
	)
	(segment
		(start 40.05707 -317.208154)
		(end 39.080694 -318.18453)
		(width 0.18288)
		(layer "In6.Cu")
		(net "M_D_CPU1_SA_DQ<0>")
	)
	(segment
		(start 70.30212 -297.22445)
		(end 70.30212 -299.334936)
		(width 0.18288)
		(layer "In6.Cu")
		(net "M_D_CPU1_SA_DQ<0>")
	)
	(arc
		(start 86.179406 -281.272742)
		(mid 86.048492 -281.409102)
		(end 86.000844 -281.59202)
		(width 0.088646)
		(layer "In6.Cu")
		(net "M_D_CPU1_SA_DQ<0>")
	)
	(arc
		(start 86.649306 -280.458926)
		(mid 86.518392 -280.595286)
		(end 86.470744 -280.778204)
		(width 0.088646)
		(layer "In6.Cu")
		(net "M_D_CPU1_SA_DQ<0>")
	)
	(arc
		(start 93.222064 -277.20671)
		(mid 92.945589 -277.27403)
		(end 92.671392 -277.198074)
		(width 0.088646)
		(layer "In6.Cu")
		(net "M_D_CPU1_SA_DQ<0>")
	)
	(arc
		(start 89.382092 -279.639776)
		(mid 89.194894 -279.589633)
		(end 89.007696 -279.639776)
		(width 0.088646)
		(layer "In6.Cu")
		(net "M_D_CPU1_SA_DQ<0>")
	)
	(arc
		(start 89.947496 -279.639776)
		(mid 89.664794 -279.715552)
		(end 89.382092 -279.639776)
		(width 0.088646)
		(layer "In6.Cu")
		(net "M_D_CPU1_SA_DQ<0>")
	)
	(arc
		(start 90.229944 -279.160224)
		(mid 90.151833 -279.437173)
		(end 89.947496 -279.639776)
		(width 0.088646)
		(layer "In6.Cu")
		(net "M_D_CPU1_SA_DQ<0>")
	)
	(arc
		(start 86.940644 -279.982676)
		(mid 86.860482 -280.254865)
		(end 86.658196 -280.453846)
		(width 0.088646)
		(layer "In6.Cu")
		(net "M_D_CPU1_SA_DQ<0>")
	)
	(arc
		(start 85.704172 -282.08986)
		(mid 85.630451 -282.151594)
		(end 85.574886 -282.230068)
		(width 0.088646)
		(layer "In6.Cu")
		(net "M_D_CPU1_SA_DQ<0>")
	)
	(arc
		(start 95.960946 -276.384258)
		(mid 95.773748 -276.334115)
		(end 95.58655 -276.384258)
		(width 0.088646)
		(layer "In6.Cu")
		(net "M_D_CPU1_SA_DQ<0>")
	)
	(arc
		(start 95.399098 -276.708616)
		(mid 95.325107 -276.988182)
		(end 95.122492 -277.194518)
		(width 0.088646)
		(layer "In6.Cu")
		(net "M_D_CPU1_SA_DQ<0>")
	)
	(arc
		(start 94.161864 -277.20671)
		(mid 93.885389 -277.27403)
		(end 93.611192 -277.198074)
		(width 0.088646)
		(layer "In6.Cu")
		(net "M_D_CPU1_SA_DQ<0>")
	)
	(arc
		(start 86.470744 -280.78811)
		(mid 86.392633 -281.065059)
		(end 86.188296 -281.267662)
		(width 0.088646)
		(layer "In6.Cu")
		(net "M_D_CPU1_SA_DQ<0>")
	)
	(arc
		(start 95.57766 -276.389338)
		(mid 95.446746 -276.525698)
		(end 95.399098 -276.708616)
		(width 0.088646)
		(layer "In6.Cu")
		(net "M_D_CPU1_SA_DQ<0>")
	)
	(arc
		(start 92.282264 -277.20671)
		(mid 92.005789 -277.27403)
		(end 91.731592 -277.198074)
		(width 0.088646)
		(layer "In6.Cu")
		(net "M_D_CPU1_SA_DQ<0>")
	)
	(arc
		(start 91.731592 -277.198074)
		(mid 91.544394 -277.147931)
		(end 91.357196 -277.198074)
		(width 0.088646)
		(layer "In6.Cu")
		(net "M_D_CPU1_SA_DQ<0>")
	)
	(arc
		(start 94.550992 -277.198074)
		(mid 94.363794 -277.147931)
		(end 94.176596 -277.198074)
		(width 0.088646)
		(layer "In6.Cu")
		(net "M_D_CPU1_SA_DQ<0>")
	)
	(arc
		(start 91.169998 -277.536656)
		(mid 91.090779 -277.811341)
		(end 90.887296 -278.012144)
		(width 0.088646)
		(layer "In6.Cu")
		(net "M_D_CPU1_SA_DQ<0>")
	)
	(arc
		(start 91.357196 -277.198074)
		(mid 91.222263 -277.331428)
		(end 91.169998 -277.513796)
		(width 0.088646)
		(layer "In6.Cu")
		(net "M_D_CPU1_SA_DQ<0>")
	)
	(arc
		(start 92.671392 -277.198074)
		(mid 92.484194 -277.147931)
		(end 92.296996 -277.198074)
		(width 0.088646)
		(layer "In6.Cu")
		(net "M_D_CPU1_SA_DQ<0>")
	)
	(arc
		(start 87.119206 -279.644856)
		(mid 86.988292 -279.781216)
		(end 86.940644 -279.964134)
		(width 0.088646)
		(layer "In6.Cu")
		(net "M_D_CPU1_SA_DQ<0>")
	)
	(arc
		(start 88.067896 -279.639776)
		(mid 87.785194 -279.715552)
		(end 87.502492 -279.639776)
		(width 0.088646)
		(layer "In6.Cu")
		(net "M_D_CPU1_SA_DQ<0>")
	)
	(arc
		(start 90.408506 -278.83104)
		(mid 90.277592 -278.9674)
		(end 90.229944 -279.150318)
		(width 0.088646)
		(layer "In6.Cu")
		(net "M_D_CPU1_SA_DQ<0>")
	)
	(arc
		(start 90.878406 -278.017224)
		(mid 90.747492 -278.153584)
		(end 90.699844 -278.336502)
		(width 0.088646)
		(layer "In6.Cu")
		(net "M_D_CPU1_SA_DQ<0>")
	)
	(arc
		(start 89.007696 -279.639776)
		(mid 88.724994 -279.715552)
		(end 88.442292 -279.639776)
		(width 0.088646)
		(layer "In6.Cu")
		(net "M_D_CPU1_SA_DQ<0>")
	)
	(arc
		(start 93.611192 -277.198074)
		(mid 93.423994 -277.147931)
		(end 93.236796 -277.198074)
		(width 0.088646)
		(layer "In6.Cu")
		(net "M_D_CPU1_SA_DQ<0>")
	)
	(arc
		(start 96.143826 -276.651212)
		(mid 96.08567 -276.501099)
		(end 95.969836 -276.389338)
		(width 0.088646)
		(layer "In6.Cu")
		(net "M_D_CPU1_SA_DQ<0>")
	)
	(arc
		(start 95.101664 -277.20671)
		(mid 94.825189 -277.27403)
		(end 94.550992 -277.198074)
		(width 0.088646)
		(layer "In6.Cu")
		(net "M_D_CPU1_SA_DQ<0>")
	)
	(arc
		(start 90.699844 -278.346408)
		(mid 90.621733 -278.623357)
		(end 90.417396 -278.82596)
		(width 0.088646)
		(layer "In6.Cu")
		(net "M_D_CPU1_SA_DQ<0>")
	)
	(arc
		(start 85.574886 -282.230068)
		(mid 85.543294 -282.310449)
		(end 85.530944 -282.39593)
		(width 0.088646)
		(layer "In6.Cu")
		(net "M_D_CPU1_SA_DQ<0>")
	)
	(arc
		(start 88.442292 -279.639776)
		(mid 88.255094 -279.589633)
		(end 88.067896 -279.639776)
		(width 0.088646)
		(layer "In6.Cu")
		(net "M_D_CPU1_SA_DQ<0>")
	)
	(arc
		(start 86.000844 -281.601926)
		(mid 85.922733 -281.878875)
		(end 85.718396 -282.081478)
		(width 0.088646)
		(layer "In6.Cu")
		(net "M_D_CPU1_SA_DQ<0>")
	)
	(arc
		(start 87.502492 -279.639776)
		(mid 87.315294 -279.589633)
		(end 87.128096 -279.639776)
		(width 0.088646)
		(layer "In6.Cu")
		(net "M_D_CPU1_SA_DQ<0>")
	)
	(segment
		(start 100.472494 -258.802886)
		(end 100.472748 -258.80314)
		(width 0.20066)
		(layer "F.Cu")
		(net "M_D_CPU1_SA_CS_N<3>")
	)
	(segment
		(start 100.472494 -258.2672)
		(end 100.472494 -258.802886)
		(width 0.20066)
		(layer "F.Cu")
		(net "M_D_CPU1_SA_CS_N<3>")
	)
	(segment
		(start 19.784314 -267.016738)
		(end 20.889214 -267.016738)
		(width 0.20066)
		(layer "F.Cu")
		(net "M_D_CPU1_SA_CS_N<3>")
	)
	(segment
		(start 36.62299 -264.159492)
		(end 36.504626 -264.041128)
		(width 0.18288)
		(layer "In11.Cu")
		(net "M_D_CPU1_SA_CS_N<3>")
	)
	(segment
		(start 47.913798 -263.87171)
		(end 47.745142 -264.040366)
		(width 0.18288)
		(layer "In11.Cu")
		(net "M_D_CPU1_SA_CS_N<3>")
	)
	(segment
		(start 71.723758 -260.01853)
		(end 70.536562 -260.01853)
		(width 0.18288)
		(layer "In11.Cu")
		(net "M_D_CPU1_SA_CS_N<3>")
	)
	(segment
		(start 54.955186 -264.187686)
		(end 51.734212 -264.187686)
		(width 0.18288)
		(layer "In11.Cu")
		(net "M_D_CPU1_SA_CS_N<3>")
	)
	(segment
		(start 93.156278 -258.487418)
		(end 93.141546 -258.478782)
		(width 0.088646)
		(layer "In11.Cu")
		(net "M_D_CPU1_SA_CS_N<3>")
	)
	(segment
		(start 98.795078 -259.118862)
		(end 98.780346 -259.127498)
		(width 0.088646)
		(layer "In11.Cu")
		(net "M_D_CPU1_SA_CS_N<3>")
	)
	(segment
		(start 99.778312 -259.093462)
		(end 99.720146 -259.127498)
		(width 0.088646)
		(layer "In11.Cu")
		(net "M_D_CPU1_SA_CS_N<3>")
	)
	(segment
		(start 67.433952 -261.694422)
		(end 66.962274 -261.498842)
		(width 0.18288)
		(layer "In11.Cu")
		(net "M_D_CPU1_SA_CS_N<3>")
	)
	(segment
		(start 30.557978 -263.736074)
		(end 30.078426 -264.215626)
		(width 0.18288)
		(layer "In11.Cu")
		(net "M_D_CPU1_SA_CS_N<3>")
	)
	(segment
		(start 67.943476 -261.092442)
		(end 67.74815 -261.56412)
		(width 0.18288)
		(layer "In11.Cu")
		(net "M_D_CPU1_SA_CS_N<3>")
	)
	(segment
		(start 83.926426 -258.234434)
		(end 82.978498 -258.234434)
		(width 0.088646)
		(layer "In11.Cu")
		(net "M_D_CPU1_SA_CS_N<3>")
	)
	(segment
		(start 40.358314 -264.159492)
		(end 36.62299 -264.159492)
		(width 0.18288)
		(layer "In11.Cu")
		(net "M_D_CPU1_SA_CS_N<3>")
	)
	(segment
		(start 24.998426 -265.866626)
		(end 23.995126 -265.866626)
		(width 0.18288)
		(layer "In11.Cu")
		(net "M_D_CPU1_SA_CS_N<3>")
	)
	(segment
		(start 68.729352 -261.157466)
		(end 68.257928 -260.96214)
		(width 0.18288)
		(layer "In11.Cu")
		(net "M_D_CPU1_SA_CS_N<3>")
	)
	(segment
		(start 84.495894 -258.427982)
		(end 84.119974 -258.427982)
		(width 0.088646)
		(layer "In11.Cu")
		(net "M_D_CPU1_SA_CS_N<3>")
	)
	(segment
		(start 84.119974 -258.427982)
		(end 83.926426 -258.234434)
		(width 0.088646)
		(layer "In11.Cu")
		(net "M_D_CPU1_SA_CS_N<3>")
	)
	(segment
		(start 44.299124 -263.987026)
		(end 40.53078 -263.987026)
		(width 0.18288)
		(layer "In11.Cu")
		(net "M_D_CPU1_SA_CS_N<3>")
	)
	(segment
		(start 45.620686 -264.040366)
		(end 45.496226 -264.164826)
		(width 0.18288)
		(layer "In11.Cu")
		(net "M_D_CPU1_SA_CS_N<3>")
	)
	(segment
		(start 34.197798 -264.938256)
		(end 33.274254 -264.938256)
		(width 0.18288)
		(layer "In11.Cu")
		(net "M_D_CPU1_SA_CS_N<3>")
	)
	(segment
		(start 29.468826 -264.215626)
		(end 29.189426 -263.936226)
		(width 0.18288)
		(layer "In11.Cu")
		(net "M_D_CPU1_SA_CS_N<3>")
	)
	(segment
		(start 22.331426 -267.530326)
		(end 21.948902 -267.530326)
		(width 0.18288)
		(layer "In11.Cu")
		(net "M_D_CPU1_SA_CS_N<3>")
	)
	(segment
		(start 82.978498 -258.234434)
		(end 81.788508 -258.234434)
		(width 0.18288)
		(layer "In11.Cu")
		(net "M_D_CPU1_SA_CS_N<3>")
	)
	(segment
		(start 98.40595 -259.127498)
		(end 98.119946 -258.962144)
		(width 0.088646)
		(layer "In11.Cu")
		(net "M_D_CPU1_SA_CS_N<3>")
	)
	(segment
		(start 31.07055 -263.736074)
		(end 30.557978 -263.736074)
		(width 0.18288)
		(layer "In11.Cu")
		(net "M_D_CPU1_SA_CS_N<3>")
	)
	(segment
		(start 67.74815 -261.56412)
		(end 67.433952 -261.694422)
		(width 0.18288)
		(layer "In11.Cu")
		(net "M_D_CPU1_SA_CS_N<3>")
	)
	(segment
		(start 66.962274 -261.498842)
		(end 66.577718 -261.658354)
		(width 0.18288)
		(layer "In11.Cu")
		(net "M_D_CPU1_SA_CS_N<3>")
	)
	(segment
		(start 50.051462 -263.87171)
		(end 47.913798 -263.87171)
		(width 0.18288)
		(layer "In11.Cu")
		(net "M_D_CPU1_SA_CS_N<3>")
	)
	(segment
		(start 73.036176 -258.706112)
		(end 71.723758 -260.01853)
		(width 0.18288)
		(layer "In11.Cu")
		(net "M_D_CPU1_SA_CS_N<3>")
	)
	(segment
		(start 45.496226 -264.164826)
		(end 44.476924 -264.164826)
		(width 0.18288)
		(layer "In11.Cu")
		(net "M_D_CPU1_SA_CS_N<3>")
	)
	(segment
		(start 81.31683 -258.706112)
		(end 73.036176 -258.706112)
		(width 0.18288)
		(layer "In11.Cu")
		(net "M_D_CPU1_SA_CS_N<3>")
	)
	(segment
		(start 29.189426 -263.936226)
		(end 28.021026 -263.936226)
		(width 0.18288)
		(layer "In11.Cu")
		(net "M_D_CPU1_SA_CS_N<3>")
	)
	(segment
		(start 69.238876 -260.55574)
		(end 69.04355 -261.027164)
		(width 0.18288)
		(layer "In11.Cu")
		(net "M_D_CPU1_SA_CS_N<3>")
	)
	(segment
		(start 91.276678 -258.487418)
		(end 91.261946 -258.478782)
		(width 0.088646)
		(layer "In11.Cu")
		(net "M_D_CPU1_SA_CS_N<3>")
	)
	(segment
		(start 65.392046 -261.658354)
		(end 64.943228 -262.107172)
		(width 0.18288)
		(layer "In11.Cu")
		(net "M_D_CPU1_SA_CS_N<3>")
	)
	(segment
		(start 50.222658 -264.042906)
		(end 50.051462 -263.87171)
		(width 0.18288)
		(layer "In11.Cu")
		(net "M_D_CPU1_SA_CS_N<3>")
	)
	(segment
		(start 21.948902 -267.530326)
		(end 21.435314 -267.016738)
		(width 0.18288)
		(layer "In11.Cu")
		(net "M_D_CPU1_SA_CS_N<3>")
	)
	(segment
		(start 40.53078 -263.987026)
		(end 40.358314 -264.159492)
		(width 0.18288)
		(layer "In11.Cu")
		(net "M_D_CPU1_SA_CS_N<3>")
	)
	(segment
		(start 25.887426 -264.977626)
		(end 24.998426 -265.866626)
		(width 0.18288)
		(layer "In11.Cu")
		(net "M_D_CPU1_SA_CS_N<3>")
	)
	(segment
		(start 59.101736 -263.047226)
		(end 58.678826 -263.470136)
		(width 0.18288)
		(layer "In11.Cu")
		(net "M_D_CPU1_SA_CS_N<3>")
	)
	(segment
		(start 68.257928 -260.96214)
		(end 67.943476 -261.092442)
		(width 0.18288)
		(layer "In11.Cu")
		(net "M_D_CPU1_SA_CS_N<3>")
	)
	(segment
		(start 23.995126 -265.866626)
		(end 22.331426 -267.530326)
		(width 0.18288)
		(layer "In11.Cu")
		(net "M_D_CPU1_SA_CS_N<3>")
	)
	(segment
		(start 66.577718 -261.658354)
		(end 65.392046 -261.658354)
		(width 0.18288)
		(layer "In11.Cu")
		(net "M_D_CPU1_SA_CS_N<3>")
	)
	(segment
		(start 58.678826 -263.470136)
		(end 55.672736 -263.470136)
		(width 0.18288)
		(layer "In11.Cu")
		(net "M_D_CPU1_SA_CS_N<3>")
	)
	(segment
		(start 47.745142 -264.040366)
		(end 45.620686 -264.040366)
		(width 0.18288)
		(layer "In11.Cu")
		(net "M_D_CPU1_SA_CS_N<3>")
	)
	(segment
		(start 51.589432 -264.042906)
		(end 50.222658 -264.042906)
		(width 0.18288)
		(layer "In11.Cu")
		(net "M_D_CPU1_SA_CS_N<3>")
	)
	(segment
		(start 97.840546 -258.479036)
		(end 97.840546 -258.478782)
		(width 0.088646)
		(layer "In11.Cu")
		(net "M_D_CPU1_SA_CS_N<3>")
	)
	(segment
		(start 95.975678 -258.487418)
		(end 95.960946 -258.478782)
		(width 0.088646)
		(layer "In11.Cu")
		(net "M_D_CPU1_SA_CS_N<3>")
	)
	(segment
		(start 63.666116 -262.107172)
		(end 62.726062 -263.047226)
		(width 0.18288)
		(layer "In11.Cu")
		(net "M_D_CPU1_SA_CS_N<3>")
	)
	(segment
		(start 51.734212 -264.187686)
		(end 51.589432 -264.042906)
		(width 0.18288)
		(layer "In11.Cu")
		(net "M_D_CPU1_SA_CS_N<3>")
	)
	(segment
		(start 100.1014 -258.903978)
		(end 99.778312 -259.093462)
		(width 0.088646)
		(layer "In11.Cu")
		(net "M_D_CPU1_SA_CS_N<3>")
	)
	(segment
		(start 95.031306 -258.484878)
		(end 95.020892 -258.478782)
		(width 0.088646)
		(layer "In11.Cu")
		(net "M_D_CPU1_SA_CS_N<3>")
	)
	(segment
		(start 33.274254 -264.938256)
		(end 32.377126 -264.041128)
		(width 0.18288)
		(layer "In11.Cu")
		(net "M_D_CPU1_SA_CS_N<3>")
	)
	(segment
		(start 64.943228 -262.107172)
		(end 63.666116 -262.107172)
		(width 0.18288)
		(layer "In11.Cu")
		(net "M_D_CPU1_SA_CS_N<3>")
	)
	(segment
		(start 55.672736 -263.470136)
		(end 54.955186 -264.187686)
		(width 0.18288)
		(layer "In11.Cu")
		(net "M_D_CPU1_SA_CS_N<3>")
	)
	(segment
		(start 69.04355 -261.027164)
		(end 68.729352 -261.157466)
		(width 0.18288)
		(layer "In11.Cu")
		(net "M_D_CPU1_SA_CS_N<3>")
	)
	(segment
		(start 31.375604 -264.041128)
		(end 31.07055 -263.736074)
		(width 0.18288)
		(layer "In11.Cu")
		(net "M_D_CPU1_SA_CS_N<3>")
	)
	(segment
		(start 44.476924 -264.164826)
		(end 44.299124 -263.987026)
		(width 0.18288)
		(layer "In11.Cu")
		(net "M_D_CPU1_SA_CS_N<3>")
	)
	(segment
		(start 30.078426 -264.215626)
		(end 29.468826 -264.215626)
		(width 0.18288)
		(layer "In11.Cu")
		(net "M_D_CPU1_SA_CS_N<3>")
	)
	(segment
		(start 62.726062 -263.047226)
		(end 59.101736 -263.047226)
		(width 0.18288)
		(layer "In11.Cu")
		(net "M_D_CPU1_SA_CS_N<3>")
	)
	(segment
		(start 81.788508 -258.234434)
		(end 81.31683 -258.706112)
		(width 0.18288)
		(layer "In11.Cu")
		(net "M_D_CPU1_SA_CS_N<3>")
	)
	(segment
		(start 26.979626 -264.977626)
		(end 25.887426 -264.977626)
		(width 0.18288)
		(layer "In11.Cu")
		(net "M_D_CPU1_SA_CS_N<3>")
	)
	(segment
		(start 94.09176 -258.484878)
		(end 94.081346 -258.478782)
		(width 0.088646)
		(layer "In11.Cu")
		(net "M_D_CPU1_SA_CS_N<3>")
	)
	(segment
		(start 36.504626 -264.041128)
		(end 35.094926 -264.041128)
		(width 0.18288)
		(layer "In11.Cu")
		(net "M_D_CPU1_SA_CS_N<3>")
	)
	(segment
		(start 35.094926 -264.041128)
		(end 34.197798 -264.938256)
		(width 0.18288)
		(layer "In11.Cu")
		(net "M_D_CPU1_SA_CS_N<3>")
	)
	(segment
		(start 21.435314 -267.016738)
		(end 20.889214 -267.016738)
		(width 0.18288)
		(layer "In11.Cu")
		(net "M_D_CPU1_SA_CS_N<3>")
	)
	(segment
		(start 90.88755 -258.478782)
		(end 90.877136 -258.484878)
		(width 0.088646)
		(layer "In11.Cu")
		(net "M_D_CPU1_SA_CS_N<3>")
	)
	(segment
		(start 28.021026 -263.936226)
		(end 26.979626 -264.977626)
		(width 0.18288)
		(layer "In11.Cu")
		(net "M_D_CPU1_SA_CS_N<3>")
	)
	(segment
		(start 70.536562 -260.01853)
		(end 69.238876 -260.55574)
		(width 0.18288)
		(layer "In11.Cu")
		(net "M_D_CPU1_SA_CS_N<3>")
	)
	(segment
		(start 32.377126 -264.041128)
		(end 31.375604 -264.041128)
		(width 0.18288)
		(layer "In11.Cu")
		(net "M_D_CPU1_SA_CS_N<3>")
	)
	(arc
		(start 99.34575 -259.127498)
		(mid 99.071551 -259.051663)
		(end 98.795078 -259.118862)
		(width 0.088646)
		(layer "In11.Cu")
		(net "M_D_CPU1_SA_CS_N<3>")
	)
	(arc
		(start 97.46615 -258.478782)
		(mid 97.183448 -258.554524)
		(end 96.900746 -258.478782)
		(width 0.088646)
		(layer "In11.Cu")
		(net "M_D_CPU1_SA_CS_N<3>")
	)
	(arc
		(start 90.877136 -258.484878)
		(mid 90.598704 -258.554692)
		(end 90.321892 -258.478782)
		(width 0.088646)
		(layer "In11.Cu")
		(net "M_D_CPU1_SA_CS_N<3>")
	)
	(arc
		(start 96.900746 -258.478782)
		(mid 96.713548 -258.428639)
		(end 96.52635 -258.478782)
		(width 0.088646)
		(layer "In11.Cu")
		(net "M_D_CPU1_SA_CS_N<3>")
	)
	(arc
		(start 92.201746 -258.478782)
		(mid 92.014548 -258.428639)
		(end 91.82735 -258.478782)
		(width 0.088646)
		(layer "In11.Cu")
		(net "M_D_CPU1_SA_CS_N<3>")
	)
	(arc
		(start 89.007696 -258.478782)
		(mid 88.724994 -258.554524)
		(end 88.442292 -258.478782)
		(width 0.088646)
		(layer "In11.Cu")
		(net "M_D_CPU1_SA_CS_N<3>")
	)
	(arc
		(start 94.081346 -258.478782)
		(mid 93.894148 -258.428639)
		(end 93.70695 -258.478782)
		(width 0.088646)
		(layer "In11.Cu")
		(net "M_D_CPU1_SA_CS_N<3>")
	)
	(arc
		(start 92.76715 -258.478782)
		(mid 92.484448 -258.554524)
		(end 92.201746 -258.478782)
		(width 0.088646)
		(layer "In11.Cu")
		(net "M_D_CPU1_SA_CS_N<3>")
	)
	(arc
		(start 100.472748 -258.80314)
		(mid 100.280352 -258.828802)
		(end 100.1014 -258.903978)
		(width 0.088646)
		(layer "In11.Cu")
		(net "M_D_CPU1_SA_CS_N<3>")
	)
	(arc
		(start 98.027998 -258.80314)
		(mid 97.977705 -258.615964)
		(end 97.840546 -258.479036)
		(width 0.088646)
		(layer "In11.Cu")
		(net "M_D_CPU1_SA_CS_N<3>")
	)
	(arc
		(start 98.119946 -258.962144)
		(mid 98.052616 -258.894986)
		(end 98.027998 -258.80314)
		(width 0.088646)
		(layer "In11.Cu")
		(net "M_D_CPU1_SA_CS_N<3>")
	)
	(arc
		(start 99.720146 -259.127498)
		(mid 99.532948 -259.177641)
		(end 99.34575 -259.127498)
		(width 0.088646)
		(layer "In11.Cu")
		(net "M_D_CPU1_SA_CS_N<3>")
	)
	(arc
		(start 95.020892 -258.478782)
		(mid 94.833694 -258.428639)
		(end 94.646496 -258.478782)
		(width 0.088646)
		(layer "In11.Cu")
		(net "M_D_CPU1_SA_CS_N<3>")
	)
	(arc
		(start 84.683092 -258.478782)
		(mid 84.592836 -258.44106)
		(end 84.495894 -258.427982)
		(width 0.088646)
		(layer "In11.Cu")
		(net "M_D_CPU1_SA_CS_N<3>")
	)
	(arc
		(start 98.780346 -259.127498)
		(mid 98.593148 -259.177641)
		(end 98.40595 -259.127498)
		(width 0.088646)
		(layer "In11.Cu")
		(net "M_D_CPU1_SA_CS_N<3>")
	)
	(arc
		(start 87.128096 -258.478782)
		(mid 86.845394 -258.554524)
		(end 86.562692 -258.478782)
		(width 0.088646)
		(layer "In11.Cu")
		(net "M_D_CPU1_SA_CS_N<3>")
	)
	(arc
		(start 91.261946 -258.478782)
		(mid 91.074748 -258.428639)
		(end 90.88755 -258.478782)
		(width 0.088646)
		(layer "In11.Cu")
		(net "M_D_CPU1_SA_CS_N<3>")
	)
	(arc
		(start 89.947496 -258.478782)
		(mid 89.664794 -258.554524)
		(end 89.382092 -258.478782)
		(width 0.088646)
		(layer "In11.Cu")
		(net "M_D_CPU1_SA_CS_N<3>")
	)
	(arc
		(start 87.502492 -258.478782)
		(mid 87.315294 -258.428639)
		(end 87.128096 -258.478782)
		(width 0.088646)
		(layer "In11.Cu")
		(net "M_D_CPU1_SA_CS_N<3>")
	)
	(arc
		(start 96.52635 -258.478782)
		(mid 96.252121 -258.554707)
		(end 95.975678 -258.487418)
		(width 0.088646)
		(layer "In11.Cu")
		(net "M_D_CPU1_SA_CS_N<3>")
	)
	(arc
		(start 95.960946 -258.478782)
		(mid 95.773748 -258.428639)
		(end 95.58655 -258.478782)
		(width 0.088646)
		(layer "In11.Cu")
		(net "M_D_CPU1_SA_CS_N<3>")
	)
	(arc
		(start 86.562692 -258.478782)
		(mid 86.375494 -258.428639)
		(end 86.188296 -258.478782)
		(width 0.088646)
		(layer "In11.Cu")
		(net "M_D_CPU1_SA_CS_N<3>")
	)
	(arc
		(start 88.067896 -258.478782)
		(mid 87.785194 -258.554524)
		(end 87.502492 -258.478782)
		(width 0.088646)
		(layer "In11.Cu")
		(net "M_D_CPU1_SA_CS_N<3>")
	)
	(arc
		(start 89.382092 -258.478782)
		(mid 89.194894 -258.428639)
		(end 89.007696 -258.478782)
		(width 0.088646)
		(layer "In11.Cu")
		(net "M_D_CPU1_SA_CS_N<3>")
	)
	(arc
		(start 91.82735 -258.478782)
		(mid 91.553121 -258.554707)
		(end 91.276678 -258.487418)
		(width 0.088646)
		(layer "In11.Cu")
		(net "M_D_CPU1_SA_CS_N<3>")
	)
	(arc
		(start 93.141546 -258.478782)
		(mid 92.954348 -258.428639)
		(end 92.76715 -258.478782)
		(width 0.088646)
		(layer "In11.Cu")
		(net "M_D_CPU1_SA_CS_N<3>")
	)
	(arc
		(start 90.321892 -258.478782)
		(mid 90.134694 -258.428639)
		(end 89.947496 -258.478782)
		(width 0.088646)
		(layer "In11.Cu")
		(net "M_D_CPU1_SA_CS_N<3>")
	)
	(arc
		(start 93.70695 -258.478782)
		(mid 93.432721 -258.554707)
		(end 93.156278 -258.487418)
		(width 0.088646)
		(layer "In11.Cu")
		(net "M_D_CPU1_SA_CS_N<3>")
	)
	(arc
		(start 94.646496 -258.478782)
		(mid 94.369937 -258.554491)
		(end 94.09176 -258.484878)
		(width 0.088646)
		(layer "In11.Cu")
		(net "M_D_CPU1_SA_CS_N<3>")
	)
	(arc
		(start 85.248496 -258.478782)
		(mid 84.965794 -258.554524)
		(end 84.683092 -258.478782)
		(width 0.088646)
		(layer "In11.Cu")
		(net "M_D_CPU1_SA_CS_N<3>")
	)
	(arc
		(start 86.188296 -258.478782)
		(mid 85.905594 -258.554524)
		(end 85.622892 -258.478782)
		(width 0.088646)
		(layer "In11.Cu")
		(net "M_D_CPU1_SA_CS_N<3>")
	)
	(arc
		(start 88.442292 -258.478782)
		(mid 88.255094 -258.428639)
		(end 88.067896 -258.478782)
		(width 0.088646)
		(layer "In11.Cu")
		(net "M_D_CPU1_SA_CS_N<3>")
	)
	(arc
		(start 85.622892 -258.478782)
		(mid 85.435694 -258.428639)
		(end 85.248496 -258.478782)
		(width 0.088646)
		(layer "In11.Cu")
		(net "M_D_CPU1_SA_CS_N<3>")
	)
	(arc
		(start 95.58655 -258.478782)
		(mid 95.309737 -258.554618)
		(end 95.031306 -258.484878)
		(width 0.088646)
		(layer "In11.Cu")
		(net "M_D_CPU1_SA_CS_N<3>")
	)
	(arc
		(start 97.840546 -258.478782)
		(mid 97.653348 -258.428639)
		(end 97.46615 -258.478782)
		(width 0.088646)
		(layer "In11.Cu")
		(net "M_D_CPU1_SA_CS_N<3>")
	)
	(segment
		(start 100.002848 -259.081016)
		(end 100.002848 -259.616702)
		(width 0.20066)
		(layer "F.Cu")
		(net "M_D_CPU1_SA_CS_N<2>")
	)
	(segment
		(start 15.684246 -267.866622)
		(end 16.789146 -267.866622)
		(width 0.20066)
		(layer "F.Cu")
		(net "M_D_CPU1_SA_CS_N<2>")
	)
	(segment
		(start 100.002848 -259.616702)
		(end 100.002594 -259.616956)
		(width 0.20066)
		(layer "F.Cu")
		(net "M_D_CPU1_SA_CS_N<2>")
	)
	(segment
		(start 22.257258 -269.219426)
		(end 21.947886 -269.219426)
		(width 0.18288)
		(layer "In11.Cu")
		(net "M_D_CPU1_SA_CS_N<2>")
	)
	(segment
		(start 96.995996 -259.292598)
		(end 96.981264 -259.301234)
		(width 0.088646)
		(layer "In11.Cu")
		(net "M_D_CPU1_SA_CS_N<2>")
	)
	(segment
		(start 24.033734 -267.44295)
		(end 22.257258 -269.219426)
		(width 0.18288)
		(layer "In11.Cu")
		(net "M_D_CPU1_SA_CS_N<2>")
	)
	(segment
		(start 82.067654 -258.933188)
		(end 81.589372 -259.41147)
		(width 0.18288)
		(layer "In11.Cu")
		(net "M_D_CPU1_SA_CS_N<2>")
	)
	(segment
		(start 38.758114 -265.446764)
		(end 38.565074 -265.253724)
		(width 0.18288)
		(layer "In11.Cu")
		(net "M_D_CPU1_SA_CS_N<2>")
	)
	(segment
		(start 53.675534 -265.637518)
		(end 53.675534 -265.44143)
		(width 0.18288)
		(layer "In11.Cu")
		(net "M_D_CPU1_SA_CS_N<2>")
	)
	(segment
		(start 25.047702 -267.44295)
		(end 24.033734 -267.44295)
		(width 0.18288)
		(layer "In11.Cu")
		(net "M_D_CPU1_SA_CS_N<2>")
	)
	(segment
		(start 38.951154 -265.886692)
		(end 38.758114 -265.693652)
		(width 0.18288)
		(layer "In11.Cu")
		(net "M_D_CPU1_SA_CS_N<2>")
	)
	(segment
		(start 52.778914 -265.830558)
		(end 51.884834 -265.830558)
		(width 0.18288)
		(layer "In11.Cu")
		(net "M_D_CPU1_SA_CS_N<2>")
	)
	(segment
		(start 27.309826 -266.146026)
		(end 26.243026 -266.679426)
		(width 0.18288)
		(layer "In11.Cu")
		(net "M_D_CPU1_SA_CS_N<2>")
	)
	(segment
		(start 83.826096 -258.933188)
		(end 82.987134 -258.933188)
		(width 0.088646)
		(layer "In11.Cu")
		(net "M_D_CPU1_SA_CS_N<2>")
	)
	(segment
		(start 38.565074 -265.253724)
		(end 38.250114 -265.253724)
		(width 0.18288)
		(layer "In11.Cu")
		(net "M_D_CPU1_SA_CS_N<2>")
	)
	(segment
		(start 38.057074 -265.446764)
		(end 38.057074 -265.693652)
		(width 0.18288)
		(layer "In11.Cu")
		(net "M_D_CPU1_SA_CS_N<2>")
	)
	(segment
		(start 20.130516 -268.15796)
		(end 19.937476 -267.96492)
		(width 0.18288)
		(layer "In11.Cu")
		(net "M_D_CPU1_SA_CS_N<2>")
	)
	(segment
		(start 29.464254 -265.892026)
		(end 29.134054 -265.561826)
		(width 0.18288)
		(layer "In11.Cu")
		(net "M_D_CPU1_SA_CS_N<2>")
	)
	(segment
		(start 62.82309 -264.723626)
		(end 59.275726 -264.723626)
		(width 0.18288)
		(layer "In11.Cu")
		(net "M_D_CPU1_SA_CS_N<2>")
	)
	(segment
		(start 55.072026 -265.830558)
		(end 53.868574 -265.830558)
		(width 0.18288)
		(layer "In11.Cu")
		(net "M_D_CPU1_SA_CS_N<2>")
	)
	(segment
		(start 53.868574 -265.830558)
		(end 53.675534 -265.637518)
		(width 0.18288)
		(layer "In11.Cu")
		(net "M_D_CPU1_SA_CS_N<2>")
	)
	(segment
		(start 98.32086 -259.935218)
		(end 98.310446 -259.941314)
		(width 0.088646)
		(layer "In11.Cu")
		(net "M_D_CPU1_SA_CS_N<2>")
	)
	(segment
		(start 53.675534 -265.44143)
		(end 53.482494 -265.24839)
		(width 0.18288)
		(layer "In11.Cu")
		(net "M_D_CPU1_SA_CS_N<2>")
	)
	(segment
		(start 49.146968 -265.632692)
		(end 48.509936 -265.632692)
		(width 0.18288)
		(layer "In11.Cu")
		(net "M_D_CPU1_SA_CS_N<2>")
	)
	(segment
		(start 37.864034 -265.886692)
		(end 36.802568 -265.886692)
		(width 0.18288)
		(layer "In11.Cu")
		(net "M_D_CPU1_SA_CS_N<2>")
	)
	(segment
		(start 28.656026 -265.561826)
		(end 27.309826 -266.146026)
		(width 0.18288)
		(layer "In11.Cu")
		(net "M_D_CPU1_SA_CS_N<2>")
	)
	(segment
		(start 32.32785 -265.74115)
		(end 30.280102 -265.74115)
		(width 0.18288)
		(layer "In11.Cu")
		(net "M_D_CPU1_SA_CS_N<2>")
	)
	(segment
		(start 96.056196 -259.292598)
		(end 96.041464 -259.301234)
		(width 0.088646)
		(layer "In11.Cu")
		(net "M_D_CPU1_SA_CS_N<2>")
	)
	(segment
		(start 33.198054 -266.611354)
		(end 32.32785 -265.74115)
		(width 0.18288)
		(layer "In11.Cu")
		(net "M_D_CPU1_SA_CS_N<2>")
	)
	(segment
		(start 45.342302 -265.74115)
		(end 45.270928 -265.812524)
		(width 0.18288)
		(layer "In11.Cu")
		(net "M_D_CPU1_SA_CS_N<2>")
	)
	(segment
		(start 21.947886 -269.219426)
		(end 21.160486 -268.432026)
		(width 0.18288)
		(layer "In11.Cu")
		(net "M_D_CPU1_SA_CS_N<2>")
	)
	(segment
		(start 65.767966 -263.250426)
		(end 65.183766 -263.834626)
		(width 0.18288)
		(layer "In11.Cu")
		(net "M_D_CPU1_SA_CS_N<2>")
	)
	(segment
		(start 73.612502 -259.41147)
		(end 71.989442 -261.03453)
		(width 0.18288)
		(layer "In11.Cu")
		(net "M_D_CPU1_SA_CS_N<2>")
	)
	(segment
		(start 30.129226 -265.892026)
		(end 29.464254 -265.892026)
		(width 0.18288)
		(layer "In11.Cu")
		(net "M_D_CPU1_SA_CS_N<2>")
	)
	(segment
		(start 53.482494 -265.24839)
		(end 53.164994 -265.24839)
		(width 0.18288)
		(layer "In11.Cu")
		(net "M_D_CPU1_SA_CS_N<2>")
	)
	(segment
		(start 66.514472 -263.250426)
		(end 65.767966 -263.250426)
		(width 0.18288)
		(layer "In11.Cu")
		(net "M_D_CPU1_SA_CS_N<2>")
	)
	(segment
		(start 51.884834 -265.830558)
		(end 51.795426 -265.74115)
		(width 0.18288)
		(layer "In11.Cu")
		(net "M_D_CPU1_SA_CS_N<2>")
	)
	(segment
		(start 99.646994 -259.712206)
		(end 99.249992 -259.941314)
		(width 0.088646)
		(layer "In11.Cu")
		(net "M_D_CPU1_SA_CS_N<2>")
	)
	(segment
		(start 97.93605 -259.941314)
		(end 97.649792 -259.775706)
		(width 0.088646)
		(layer "In11.Cu")
		(net "M_D_CPU1_SA_CS_N<2>")
	)
	(segment
		(start 59.275726 -264.723626)
		(end 58.973466 -265.025886)
		(width 0.18288)
		(layer "In11.Cu")
		(net "M_D_CPU1_SA_CS_N<2>")
	)
	(segment
		(start 84.096352 -259.203444)
		(end 83.826096 -258.933188)
		(width 0.088646)
		(layer "In11.Cu")
		(net "M_D_CPU1_SA_CS_N<2>")
	)
	(segment
		(start 52.971954 -265.637518)
		(end 52.778914 -265.830558)
		(width 0.18288)
		(layer "In11.Cu")
		(net "M_D_CPU1_SA_CS_N<2>")
	)
	(segment
		(start 53.164994 -265.24839)
		(end 52.971954 -265.44143)
		(width 0.18288)
		(layer "In11.Cu")
		(net "M_D_CPU1_SA_CS_N<2>")
	)
	(segment
		(start 30.280102 -265.74115)
		(end 30.129226 -265.892026)
		(width 0.18288)
		(layer "In11.Cu")
		(net "M_D_CPU1_SA_CS_N<2>")
	)
	(segment
		(start 92.296996 -259.292598)
		(end 92.286582 -259.298694)
		(width 0.088646)
		(layer "In11.Cu")
		(net "M_D_CPU1_SA_CS_N<2>")
	)
	(segment
		(start 40.410892 -265.587226)
		(end 40.111426 -265.886692)
		(width 0.18288)
		(layer "In11.Cu")
		(net "M_D_CPU1_SA_CS_N<2>")
	)
	(segment
		(start 36.657026 -265.74115)
		(end 35.224466 -265.74115)
		(width 0.18288)
		(layer "In11.Cu")
		(net "M_D_CPU1_SA_CS_N<2>")
	)
	(segment
		(start 17.35455 -268.432026)
		(end 16.789146 -267.866622)
		(width 0.18288)
		(layer "In11.Cu")
		(net "M_D_CPU1_SA_CS_N<2>")
	)
	(segment
		(start 38.758114 -265.693652)
		(end 38.758114 -265.446764)
		(width 0.18288)
		(layer "In11.Cu")
		(net "M_D_CPU1_SA_CS_N<2>")
	)
	(segment
		(start 44.323 -265.812524)
		(end 44.097702 -265.587226)
		(width 0.18288)
		(layer "In11.Cu")
		(net "M_D_CPU1_SA_CS_N<2>")
	)
	(segment
		(start 19.937476 -267.96492)
		(end 19.622516 -267.96492)
		(width 0.18288)
		(layer "In11.Cu")
		(net "M_D_CPU1_SA_CS_N<2>")
	)
	(segment
		(start 97.370646 -259.292852)
		(end 97.370392 -259.292598)
		(width 0.088646)
		(layer "In11.Cu")
		(net "M_D_CPU1_SA_CS_N<2>")
	)
	(segment
		(start 55.876698 -265.025886)
		(end 55.072026 -265.830558)
		(width 0.18288)
		(layer "In11.Cu")
		(net "M_D_CPU1_SA_CS_N<2>")
	)
	(segment
		(start 51.795426 -265.74115)
		(end 49.255426 -265.74115)
		(width 0.18288)
		(layer "In11.Cu")
		(net "M_D_CPU1_SA_CS_N<2>")
	)
	(segment
		(start 93.236796 -259.292598)
		(end 93.222064 -259.301234)
		(width 0.088646)
		(layer "In11.Cu")
		(net "M_D_CPU1_SA_CS_N<2>")
	)
	(segment
		(start 82.987134 -258.933188)
		(end 82.067654 -258.933188)
		(width 0.18288)
		(layer "In11.Cu")
		(net "M_D_CPU1_SA_CS_N<2>")
	)
	(segment
		(start 94.176596 -259.292598)
		(end 94.161864 -259.301234)
		(width 0.088646)
		(layer "In11.Cu")
		(net "M_D_CPU1_SA_CS_N<2>")
	)
	(segment
		(start 65.183766 -263.834626)
		(end 63.71209 -263.834626)
		(width 0.18288)
		(layer "In11.Cu")
		(net "M_D_CPU1_SA_CS_N<2>")
	)
	(segment
		(start 20.323556 -268.432026)
		(end 20.130516 -268.238986)
		(width 0.18288)
		(layer "In11.Cu")
		(net "M_D_CPU1_SA_CS_N<2>")
	)
	(segment
		(start 19.236436 -268.432026)
		(end 17.35455 -268.432026)
		(width 0.18288)
		(layer "In11.Cu")
		(net "M_D_CPU1_SA_CS_N<2>")
	)
	(segment
		(start 71.863966 -261.03453)
		(end 66.514472 -263.250426)
		(width 0.18288)
		(layer "In11.Cu")
		(net "M_D_CPU1_SA_CS_N<2>")
	)
	(segment
		(start 52.971954 -265.44143)
		(end 52.971954 -265.637518)
		(width 0.18288)
		(layer "In11.Cu")
		(net "M_D_CPU1_SA_CS_N<2>")
	)
	(segment
		(start 45.270928 -265.812524)
		(end 44.323 -265.812524)
		(width 0.18288)
		(layer "In11.Cu")
		(net "M_D_CPU1_SA_CS_N<2>")
	)
	(segment
		(start 34.354262 -266.611354)
		(end 33.198054 -266.611354)
		(width 0.18288)
		(layer "In11.Cu")
		(net "M_D_CPU1_SA_CS_N<2>")
	)
	(segment
		(start 81.589372 -259.41147)
		(end 73.612502 -259.41147)
		(width 0.18288)
		(layer "In11.Cu")
		(net "M_D_CPU1_SA_CS_N<2>")
	)
	(segment
		(start 19.429476 -268.15796)
		(end 19.429476 -268.238986)
		(width 0.18288)
		(layer "In11.Cu")
		(net "M_D_CPU1_SA_CS_N<2>")
	)
	(segment
		(start 38.057074 -265.693652)
		(end 37.864034 -265.886692)
		(width 0.18288)
		(layer "In11.Cu")
		(net "M_D_CPU1_SA_CS_N<2>")
	)
	(segment
		(start 19.622516 -267.96492)
		(end 19.429476 -268.15796)
		(width 0.18288)
		(layer "In11.Cu")
		(net "M_D_CPU1_SA_CS_N<2>")
	)
	(segment
		(start 48.509936 -265.632692)
		(end 48.401478 -265.74115)
		(width 0.18288)
		(layer "In11.Cu")
		(net "M_D_CPU1_SA_CS_N<2>")
	)
	(segment
		(start 58.973466 -265.025886)
		(end 55.876698 -265.025886)
		(width 0.18288)
		(layer "In11.Cu")
		(net "M_D_CPU1_SA_CS_N<2>")
	)
	(segment
		(start 38.250114 -265.253724)
		(end 38.057074 -265.446764)
		(width 0.18288)
		(layer "In11.Cu")
		(net "M_D_CPU1_SA_CS_N<2>")
	)
	(segment
		(start 26.243026 -266.679426)
		(end 25.811226 -266.679426)
		(width 0.18288)
		(layer "In11.Cu")
		(net "M_D_CPU1_SA_CS_N<2>")
	)
	(segment
		(start 63.71209 -263.834626)
		(end 62.82309 -264.723626)
		(width 0.18288)
		(layer "In11.Cu")
		(net "M_D_CPU1_SA_CS_N<2>")
	)
	(segment
		(start 36.802568 -265.886692)
		(end 36.657026 -265.74115)
		(width 0.18288)
		(layer "In11.Cu")
		(net "M_D_CPU1_SA_CS_N<2>")
	)
	(segment
		(start 44.097702 -265.587226)
		(end 40.410892 -265.587226)
		(width 0.18288)
		(layer "In11.Cu")
		(net "M_D_CPU1_SA_CS_N<2>")
	)
	(segment
		(start 21.160486 -268.432026)
		(end 20.323556 -268.432026)
		(width 0.18288)
		(layer "In11.Cu")
		(net "M_D_CPU1_SA_CS_N<2>")
	)
	(segment
		(start 25.811226 -266.679426)
		(end 25.047702 -267.44295)
		(width 0.18288)
		(layer "In11.Cu")
		(net "M_D_CPU1_SA_CS_N<2>")
	)
	(segment
		(start 20.130516 -268.238986)
		(end 20.130516 -268.15796)
		(width 0.18288)
		(layer "In11.Cu")
		(net "M_D_CPU1_SA_CS_N<2>")
	)
	(segment
		(start 29.134054 -265.561826)
		(end 28.656026 -265.561826)
		(width 0.18288)
		(layer "In11.Cu")
		(net "M_D_CPU1_SA_CS_N<2>")
	)
	(segment
		(start 91.35745 -259.292598)
		(end 91.347036 -259.298694)
		(width 0.088646)
		(layer "In11.Cu")
		(net "M_D_CPU1_SA_CS_N<2>")
	)
	(segment
		(start 40.111426 -265.886692)
		(end 38.951154 -265.886692)
		(width 0.18288)
		(layer "In11.Cu")
		(net "M_D_CPU1_SA_CS_N<2>")
	)
	(segment
		(start 71.989442 -261.03453)
		(end 71.863966 -261.03453)
		(width 0.18288)
		(layer "In11.Cu")
		(net "M_D_CPU1_SA_CS_N<2>")
	)
	(segment
		(start 49.255426 -265.74115)
		(end 49.146968 -265.632692)
		(width 0.18288)
		(layer "In11.Cu")
		(net "M_D_CPU1_SA_CS_N<2>")
	)
	(segment
		(start 19.429476 -268.238986)
		(end 19.236436 -268.432026)
		(width 0.18288)
		(layer "In11.Cu")
		(net "M_D_CPU1_SA_CS_N<2>")
	)
	(segment
		(start 35.224466 -265.74115)
		(end 34.354262 -266.611354)
		(width 0.18288)
		(layer "In11.Cu")
		(net "M_D_CPU1_SA_CS_N<2>")
	)
	(segment
		(start 48.401478 -265.74115)
		(end 45.342302 -265.74115)
		(width 0.18288)
		(layer "In11.Cu")
		(net "M_D_CPU1_SA_CS_N<2>")
	)
	(arc
		(start 98.875596 -259.941314)
		(mid 98.599037 -259.865571)
		(end 98.32086 -259.935218)
		(width 0.088646)
		(layer "In11.Cu")
		(net "M_D_CPU1_SA_CS_N<2>")
	)
	(arc
		(start 85.152992 -259.292598)
		(mid 84.965794 -259.242455)
		(end 84.778596 -259.292598)
		(width 0.088646)
		(layer "In11.Cu")
		(net "M_D_CPU1_SA_CS_N<2>")
	)
	(arc
		(start 96.041464 -259.301234)
		(mid 95.764989 -259.368554)
		(end 95.490792 -259.292598)
		(width 0.088646)
		(layer "In11.Cu")
		(net "M_D_CPU1_SA_CS_N<2>")
	)
	(arc
		(start 97.557844 -259.616956)
		(mid 97.50768 -259.429818)
		(end 97.370646 -259.292852)
		(width 0.088646)
		(layer "In11.Cu")
		(net "M_D_CPU1_SA_CS_N<2>")
	)
	(arc
		(start 85.718396 -259.292598)
		(mid 85.435694 -259.368374)
		(end 85.152992 -259.292598)
		(width 0.088646)
		(layer "In11.Cu")
		(net "M_D_CPU1_SA_CS_N<2>")
	)
	(arc
		(start 96.430592 -259.292598)
		(mid 96.243394 -259.242455)
		(end 96.056196 -259.292598)
		(width 0.088646)
		(layer "In11.Cu")
		(net "M_D_CPU1_SA_CS_N<2>")
	)
	(arc
		(start 94.550992 -259.292598)
		(mid 94.363794 -259.242455)
		(end 94.176596 -259.292598)
		(width 0.088646)
		(layer "In11.Cu")
		(net "M_D_CPU1_SA_CS_N<2>")
	)
	(arc
		(start 90.791792 -259.292598)
		(mid 90.604594 -259.242455)
		(end 90.417396 -259.292598)
		(width 0.088646)
		(layer "In11.Cu")
		(net "M_D_CPU1_SA_CS_N<2>")
	)
	(arc
		(start 93.611192 -259.292598)
		(mid 93.423994 -259.242455)
		(end 93.236796 -259.292598)
		(width 0.088646)
		(layer "In11.Cu")
		(net "M_D_CPU1_SA_CS_N<2>")
	)
	(arc
		(start 96.981264 -259.301234)
		(mid 96.704789 -259.368554)
		(end 96.430592 -259.292598)
		(width 0.088646)
		(layer "In11.Cu")
		(net "M_D_CPU1_SA_CS_N<2>")
	)
	(arc
		(start 99.249992 -259.941314)
		(mid 99.062794 -259.991457)
		(end 98.875596 -259.941314)
		(width 0.088646)
		(layer "In11.Cu")
		(net "M_D_CPU1_SA_CS_N<2>")
	)
	(arc
		(start 92.286582 -259.298694)
		(mid 92.008404 -259.368417)
		(end 91.731846 -259.292598)
		(width 0.088646)
		(layer "In11.Cu")
		(net "M_D_CPU1_SA_CS_N<2>")
	)
	(arc
		(start 98.310446 -259.941314)
		(mid 98.123248 -259.991457)
		(end 97.93605 -259.941314)
		(width 0.088646)
		(layer "In11.Cu")
		(net "M_D_CPU1_SA_CS_N<2>")
	)
	(arc
		(start 84.778596 -259.292598)
		(mid 84.495894 -259.368374)
		(end 84.213192 -259.292598)
		(width 0.088646)
		(layer "In11.Cu")
		(net "M_D_CPU1_SA_CS_N<2>")
	)
	(arc
		(start 87.032592 -259.292598)
		(mid 86.845394 -259.242455)
		(end 86.658196 -259.292598)
		(width 0.088646)
		(layer "In11.Cu")
		(net "M_D_CPU1_SA_CS_N<2>")
	)
	(arc
		(start 87.597996 -259.292598)
		(mid 87.315294 -259.368374)
		(end 87.032592 -259.292598)
		(width 0.088646)
		(layer "In11.Cu")
		(net "M_D_CPU1_SA_CS_N<2>")
	)
	(arc
		(start 94.161864 -259.301234)
		(mid 93.885389 -259.368554)
		(end 93.611192 -259.292598)
		(width 0.088646)
		(layer "In11.Cu")
		(net "M_D_CPU1_SA_CS_N<2>")
	)
	(arc
		(start 93.222064 -259.301234)
		(mid 92.945589 -259.368554)
		(end 92.671392 -259.292598)
		(width 0.088646)
		(layer "In11.Cu")
		(net "M_D_CPU1_SA_CS_N<2>")
	)
	(arc
		(start 84.213192 -259.292598)
		(mid 84.180322 -259.272108)
		(end 84.14893 -259.249418)
		(width 0.088646)
		(layer "In11.Cu")
		(net "M_D_CPU1_SA_CS_N<2>")
	)
	(arc
		(start 95.490792 -259.292598)
		(mid 95.303594 -259.242455)
		(end 95.116396 -259.292598)
		(width 0.088646)
		(layer "In11.Cu")
		(net "M_D_CPU1_SA_CS_N<2>")
	)
	(arc
		(start 87.972392 -259.292598)
		(mid 87.785194 -259.242455)
		(end 87.597996 -259.292598)
		(width 0.088646)
		(layer "In11.Cu")
		(net "M_D_CPU1_SA_CS_N<2>")
	)
	(arc
		(start 86.092792 -259.292598)
		(mid 85.905594 -259.242455)
		(end 85.718396 -259.292598)
		(width 0.088646)
		(layer "In11.Cu")
		(net "M_D_CPU1_SA_CS_N<2>")
	)
	(arc
		(start 88.912192 -259.292598)
		(mid 88.724994 -259.242455)
		(end 88.537796 -259.292598)
		(width 0.088646)
		(layer "In11.Cu")
		(net "M_D_CPU1_SA_CS_N<2>")
	)
	(arc
		(start 91.347036 -259.298694)
		(mid 91.068604 -259.36854)
		(end 90.791792 -259.292598)
		(width 0.088646)
		(layer "In11.Cu")
		(net "M_D_CPU1_SA_CS_N<2>")
	)
	(arc
		(start 97.370392 -259.292598)
		(mid 97.183194 -259.242455)
		(end 96.995996 -259.292598)
		(width 0.088646)
		(layer "In11.Cu")
		(net "M_D_CPU1_SA_CS_N<2>")
	)
	(arc
		(start 84.14893 -259.249418)
		(mid 84.121931 -259.227243)
		(end 84.096352 -259.203444)
		(width 0.088646)
		(layer "In11.Cu")
		(net "M_D_CPU1_SA_CS_N<2>")
	)
	(arc
		(start 91.731846 -259.292598)
		(mid 91.544648 -259.242455)
		(end 91.35745 -259.292598)
		(width 0.088646)
		(layer "In11.Cu")
		(net "M_D_CPU1_SA_CS_N<2>")
	)
	(arc
		(start 89.477596 -259.292598)
		(mid 89.194894 -259.368374)
		(end 88.912192 -259.292598)
		(width 0.088646)
		(layer "In11.Cu")
		(net "M_D_CPU1_SA_CS_N<2>")
	)
	(arc
		(start 90.417396 -259.292598)
		(mid 90.134694 -259.368374)
		(end 89.851992 -259.292598)
		(width 0.088646)
		(layer "In11.Cu")
		(net "M_D_CPU1_SA_CS_N<2>")
	)
	(arc
		(start 95.116396 -259.292598)
		(mid 94.833694 -259.368374)
		(end 94.550992 -259.292598)
		(width 0.088646)
		(layer "In11.Cu")
		(net "M_D_CPU1_SA_CS_N<2>")
	)
	(arc
		(start 86.658196 -259.292598)
		(mid 86.375494 -259.368374)
		(end 86.092792 -259.292598)
		(width 0.088646)
		(layer "In11.Cu")
		(net "M_D_CPU1_SA_CS_N<2>")
	)
	(arc
		(start 97.649792 -259.775706)
		(mid 97.582526 -259.708658)
		(end 97.557844 -259.616956)
		(width 0.088646)
		(layer "In11.Cu")
		(net "M_D_CPU1_SA_CS_N<2>")
	)
	(arc
		(start 92.671392 -259.292598)
		(mid 92.484194 -259.242455)
		(end 92.296996 -259.292598)
		(width 0.088646)
		(layer "In11.Cu")
		(net "M_D_CPU1_SA_CS_N<2>")
	)
	(arc
		(start 100.002594 -259.616956)
		(mid 99.818525 -259.64118)
		(end 99.646994 -259.712206)
		(width 0.088646)
		(layer "In11.Cu")
		(net "M_D_CPU1_SA_CS_N<2>")
	)
	(arc
		(start 89.851992 -259.292598)
		(mid 89.664794 -259.242455)
		(end 89.477596 -259.292598)
		(width 0.088646)
		(layer "In11.Cu")
		(net "M_D_CPU1_SA_CS_N<2>")
	)
	(arc
		(start 88.537796 -259.292598)
		(mid 88.255094 -259.368374)
		(end 87.972392 -259.292598)
		(width 0.088646)
		(layer "In11.Cu")
		(net "M_D_CPU1_SA_CS_N<2>")
	)
	(segment
		(start 98.592894 -258.802886)
		(end 98.593148 -258.80314)
		(width 0.20066)
		(layer "F.Cu")
		(net "M_D_CPU1_SA_CS_N<1>")
	)
	(segment
		(start 98.592894 -258.2672)
		(end 98.592894 -258.802886)
		(width 0.20066)
		(layer "F.Cu")
		(net "M_D_CPU1_SA_CS_N<1>")
	)
	(segment
		(start 12.240514 -267.016738)
		(end 13.345414 -267.016738)
		(width 0.20066)
		(layer "F.Cu")
		(net "M_D_CPU1_SA_CS_N<1>")
	)
	(segment
		(start 32.485584 -263.19226)
		(end 30.297374 -263.19226)
		(width 0.18288)
		(layer "In11.Cu")
		(net "M_D_CPU1_SA_CS_N<1>")
	)
	(segment
		(start 37.045138 -263.058656)
		(end 36.912804 -263.19099)
		(width 0.18288)
		(layer "In11.Cu")
		(net "M_D_CPU1_SA_CS_N<1>")
	)
	(segment
		(start 21.227796 -266.592812)
		(end 19.539458 -266.592812)
		(width 0.18288)
		(layer "In11.Cu")
		(net "M_D_CPU1_SA_CS_N<1>")
	)
	(segment
		(start 89.862406 -258.307332)
		(end 89.851992 -258.313428)
		(width 0.088646)
		(layer "In11.Cu")
		(net "M_D_CPU1_SA_CS_N<1>")
	)
	(segment
		(start 40.197278 -263.058656)
		(end 38.864032 -263.058656)
		(width 0.18288)
		(layer "In11.Cu")
		(net "M_D_CPU1_SA_CS_N<1>")
	)
	(segment
		(start 38.864032 -263.058656)
		(end 38.670992 -263.251696)
		(width 0.18288)
		(layer "In11.Cu")
		(net "M_D_CPU1_SA_CS_N<1>")
	)
	(segment
		(start 38.162992 -263.640316)
		(end 37.969952 -263.447276)
		(width 0.18288)
		(layer "In11.Cu")
		(net "M_D_CPU1_SA_CS_N<1>")
	)
	(segment
		(start 60.590176 -262.244586)
		(end 60.397136 -262.437626)
		(width 0.18288)
		(layer "In11.Cu")
		(net "M_D_CPU1_SA_CS_N<1>")
	)
	(segment
		(start 15.805658 -265.594592)
		(end 15.612618 -265.401552)
		(width 0.18288)
		(layer "In11.Cu")
		(net "M_D_CPU1_SA_CS_N<1>")
	)
	(segment
		(start 15.998698 -266.592812)
		(end 15.805658 -266.399772)
		(width 0.18288)
		(layer "In11.Cu")
		(net "M_D_CPU1_SA_CS_N<1>")
	)
	(segment
		(start 44.477686 -262.958326)
		(end 43.99534 -263.440672)
		(width 0.18288)
		(layer "In11.Cu")
		(net "M_D_CPU1_SA_CS_N<1>")
	)
	(segment
		(start 15.612618 -265.401552)
		(end 15.297658 -265.401552)
		(width 0.18288)
		(layer "In11.Cu")
		(net "M_D_CPU1_SA_CS_N<1>")
	)
	(segment
		(start 57.930542 -262.744712)
		(end 57.737502 -262.937752)
		(width 0.18288)
		(layer "In11.Cu")
		(net "M_D_CPU1_SA_CS_N<1>")
	)
	(segment
		(start 61.098176 -261.914386)
		(end 60.783216 -261.914386)
		(width 0.18288)
		(layer "In11.Cu")
		(net "M_D_CPU1_SA_CS_N<1>")
	)
	(segment
		(start 57.036462 -262.328914)
		(end 55.790338 -262.328914)
		(width 0.18288)
		(layer "In11.Cu")
		(net "M_D_CPU1_SA_CS_N<1>")
	)
	(segment
		(start 82.987134 -257.870198)
		(end 81.664048 -257.870198)
		(width 0.18288)
		(layer "In11.Cu")
		(net "M_D_CPU1_SA_CS_N<1>")
	)
	(segment
		(start 63.382652 -261.5692)
		(end 62.514226 -262.437626)
		(width 0.18288)
		(layer "In11.Cu")
		(net "M_D_CPU1_SA_CS_N<1>")
	)
	(segment
		(start 18.096738 -266.592812)
		(end 15.998698 -266.592812)
		(width 0.18288)
		(layer "In11.Cu")
		(net "M_D_CPU1_SA_CS_N<1>")
	)
	(segment
		(start 45.411644 -263.191244)
		(end 45.178726 -262.958326)
		(width 0.18288)
		(layer "In11.Cu")
		(net "M_D_CPU1_SA_CS_N<1>")
	)
	(segment
		(start 37.776912 -263.058656)
		(end 37.045138 -263.058656)
		(width 0.18288)
		(layer "In11.Cu")
		(net "M_D_CPU1_SA_CS_N<1>")
	)
	(segment
		(start 97.96526 -258.330446)
		(end 97.935796 -258.313682)
		(width 0.088646)
		(layer "In11.Cu")
		(net "M_D_CPU1_SA_CS_N<1>")
	)
	(segment
		(start 57.930542 -262.521954)
		(end 57.930542 -262.744712)
		(width 0.18288)
		(layer "In11.Cu")
		(net "M_D_CPU1_SA_CS_N<1>")
	)
	(segment
		(start 40.579294 -263.440672)
		(end 40.197278 -263.058656)
		(width 0.18288)
		(layer "In11.Cu")
		(net "M_D_CPU1_SA_CS_N<1>")
	)
	(segment
		(start 43.99534 -263.440672)
		(end 40.579294 -263.440672)
		(width 0.18288)
		(layer "In11.Cu")
		(net "M_D_CPU1_SA_CS_N<1>")
	)
	(segment
		(start 38.670992 -263.251696)
		(end 38.670992 -263.447276)
		(width 0.18288)
		(layer "In11.Cu")
		(net "M_D_CPU1_SA_CS_N<1>")
	)
	(segment
		(start 21.439124 -266.381484)
		(end 21.227796 -266.592812)
		(width 0.18288)
		(layer "In11.Cu")
		(net "M_D_CPU1_SA_CS_N<1>")
	)
	(segment
		(start 60.783216 -261.914386)
		(end 60.590176 -262.107426)
		(width 0.18288)
		(layer "In11.Cu")
		(net "M_D_CPU1_SA_CS_N<1>")
	)
	(segment
		(start 19.37258 -266.75969)
		(end 18.263616 -266.75969)
		(width 0.18288)
		(layer "In11.Cu")
		(net "M_D_CPU1_SA_CS_N<1>")
	)
	(segment
		(start 68.142358 -259.51053)
		(end 67.023234 -260.629654)
		(width 0.18288)
		(layer "In11.Cu")
		(net "M_D_CPU1_SA_CS_N<1>")
	)
	(segment
		(start 45.178726 -262.958326)
		(end 44.477686 -262.958326)
		(width 0.18288)
		(layer "In11.Cu")
		(net "M_D_CPU1_SA_CS_N<1>")
	)
	(segment
		(start 38.670992 -263.447276)
		(end 38.477952 -263.640316)
		(width 0.18288)
		(layer "In11.Cu")
		(net "M_D_CPU1_SA_CS_N<1>")
	)
	(segment
		(start 93.236796 -258.313428)
		(end 93.226382 -258.307332)
		(width 0.088646)
		(layer "In11.Cu")
		(net "M_D_CPU1_SA_CS_N<1>")
	)
	(segment
		(start 94.176596 -258.313428)
		(end 94.161864 -258.304792)
		(width 0.088646)
		(layer "In11.Cu")
		(net "M_D_CPU1_SA_CS_N<1>")
	)
	(segment
		(start 67.023234 -260.629654)
		(end 65.675002 -260.629654)
		(width 0.18288)
		(layer "In11.Cu")
		(net "M_D_CPU1_SA_CS_N<1>")
	)
	(segment
		(start 33.12795 -263.834626)
		(end 32.485584 -263.19226)
		(width 0.18288)
		(layer "In11.Cu")
		(net "M_D_CPU1_SA_CS_N<1>")
	)
	(segment
		(start 15.805658 -266.399772)
		(end 15.805658 -265.594592)
		(width 0.18288)
		(layer "In11.Cu")
		(net "M_D_CPU1_SA_CS_N<1>")
	)
	(segment
		(start 81.173574 -258.360672)
		(end 72.81926 -258.360672)
		(width 0.18288)
		(layer "In11.Cu")
		(net "M_D_CPU1_SA_CS_N<1>")
	)
	(segment
		(start 59.034426 -262.437626)
		(end 58.925714 -262.328914)
		(width 0.18288)
		(layer "In11.Cu")
		(net "M_D_CPU1_SA_CS_N<1>")
	)
	(segment
		(start 24.126952 -264.77468)
		(end 22.520148 -266.381484)
		(width 0.18288)
		(layer "In11.Cu")
		(net "M_D_CPU1_SA_CS_N<1>")
	)
	(segment
		(start 65.675002 -260.629654)
		(end 64.735456 -261.5692)
		(width 0.18288)
		(layer "In11.Cu")
		(net "M_D_CPU1_SA_CS_N<1>")
	)
	(segment
		(start 26.012394 -263.860026)
		(end 25.09774 -264.77468)
		(width 0.18288)
		(layer "In11.Cu")
		(net "M_D_CPU1_SA_CS_N<1>")
	)
	(segment
		(start 98.593148 -258.80314)
		(end 97.96526 -258.330446)
		(width 0.088646)
		(layer "In11.Cu")
		(net "M_D_CPU1_SA_CS_N<1>")
	)
	(segment
		(start 60.590176 -262.107426)
		(end 60.590176 -262.244586)
		(width 0.18288)
		(layer "In11.Cu")
		(net "M_D_CPU1_SA_CS_N<1>")
	)
	(segment
		(start 58.925714 -262.328914)
		(end 58.123582 -262.328914)
		(width 0.18288)
		(layer "In11.Cu")
		(net "M_D_CPU1_SA_CS_N<1>")
	)
	(segment
		(start 47.67834 -263.326626)
		(end 47.542958 -263.191244)
		(width 0.18288)
		(layer "In11.Cu")
		(net "M_D_CPU1_SA_CS_N<1>")
	)
	(segment
		(start 51.792378 -263.041892)
		(end 51.643026 -263.191244)
		(width 0.18288)
		(layer "In11.Cu")
		(net "M_D_CPU1_SA_CS_N<1>")
	)
	(segment
		(start 19.539458 -266.592812)
		(end 19.37258 -266.75969)
		(width 0.18288)
		(layer "In11.Cu")
		(net "M_D_CPU1_SA_CS_N<1>")
	)
	(segment
		(start 92.29725 -258.313428)
		(end 92.286836 -258.307332)
		(width 0.088646)
		(layer "In11.Cu")
		(net "M_D_CPU1_SA_CS_N<1>")
	)
	(segment
		(start 57.737502 -262.937752)
		(end 57.422542 -262.937752)
		(width 0.18288)
		(layer "In11.Cu")
		(net "M_D_CPU1_SA_CS_N<1>")
	)
	(segment
		(start 37.969952 -263.447276)
		(end 37.969952 -263.251696)
		(width 0.18288)
		(layer "In11.Cu")
		(net "M_D_CPU1_SA_CS_N<1>")
	)
	(segment
		(start 64.735456 -261.5692)
		(end 63.382652 -261.5692)
		(width 0.18288)
		(layer "In11.Cu")
		(net "M_D_CPU1_SA_CS_N<1>")
	)
	(segment
		(start 60.397136 -262.437626)
		(end 59.034426 -262.437626)
		(width 0.18288)
		(layer "In11.Cu")
		(net "M_D_CPU1_SA_CS_N<1>")
	)
	(segment
		(start 34.536126 -263.834626)
		(end 33.12795 -263.834626)
		(width 0.18288)
		(layer "In11.Cu")
		(net "M_D_CPU1_SA_CS_N<1>")
	)
	(segment
		(start 84.495894 -258.237736)
		(end 84.198968 -258.237736)
		(width 0.088646)
		(layer "In11.Cu")
		(net "M_D_CPU1_SA_CS_N<1>")
	)
	(segment
		(start 38.477952 -263.640316)
		(end 38.162992 -263.640316)
		(width 0.18288)
		(layer "In11.Cu")
		(net "M_D_CPU1_SA_CS_N<1>")
	)
	(segment
		(start 18.263616 -266.75969)
		(end 18.096738 -266.592812)
		(width 0.18288)
		(layer "In11.Cu")
		(net "M_D_CPU1_SA_CS_N<1>")
	)
	(segment
		(start 72.81926 -258.360672)
		(end 71.669402 -259.51053)
		(width 0.18288)
		(layer "In11.Cu")
		(net "M_D_CPU1_SA_CS_N<1>")
	)
	(segment
		(start 97.935796 -258.313682)
		(end 97.935034 -258.313428)
		(width 0.088646)
		(layer "In11.Cu")
		(net "M_D_CPU1_SA_CS_N<1>")
	)
	(segment
		(start 57.229502 -262.521954)
		(end 57.036462 -262.328914)
		(width 0.18288)
		(layer "In11.Cu")
		(net "M_D_CPU1_SA_CS_N<1>")
	)
	(segment
		(start 55.07736 -263.041892)
		(end 51.792378 -263.041892)
		(width 0.18288)
		(layer "In11.Cu")
		(net "M_D_CPU1_SA_CS_N<1>")
	)
	(segment
		(start 13.798296 -266.563856)
		(end 13.345414 -267.016738)
		(width 0.18288)
		(layer "In11.Cu")
		(net "M_D_CPU1_SA_CS_N<1>")
	)
	(segment
		(start 47.542958 -263.191244)
		(end 45.411644 -263.191244)
		(width 0.18288)
		(layer "In11.Cu")
		(net "M_D_CPU1_SA_CS_N<1>")
	)
	(segment
		(start 57.422542 -262.937752)
		(end 57.229502 -262.744712)
		(width 0.18288)
		(layer "In11.Cu")
		(net "M_D_CPU1_SA_CS_N<1>")
	)
	(segment
		(start 30.297374 -263.19226)
		(end 30.173168 -263.068054)
		(width 0.18288)
		(layer "In11.Cu")
		(net "M_D_CPU1_SA_CS_N<1>")
	)
	(segment
		(start 37.969952 -263.251696)
		(end 37.776912 -263.058656)
		(width 0.18288)
		(layer "In11.Cu")
		(net "M_D_CPU1_SA_CS_N<1>")
	)
	(segment
		(start 61.484256 -262.437626)
		(end 61.291216 -262.244586)
		(width 0.18288)
		(layer "In11.Cu")
		(net "M_D_CPU1_SA_CS_N<1>")
	)
	(segment
		(start 62.514226 -262.437626)
		(end 61.484256 -262.437626)
		(width 0.18288)
		(layer "In11.Cu")
		(net "M_D_CPU1_SA_CS_N<1>")
	)
	(segment
		(start 96.056196 -258.313428)
		(end 96.041464 -258.304792)
		(width 0.088646)
		(layer "In11.Cu")
		(net "M_D_CPU1_SA_CS_N<1>")
	)
	(segment
		(start 15.104618 -266.370816)
		(end 14.911578 -266.563856)
		(width 0.18288)
		(layer "In11.Cu")
		(net "M_D_CPU1_SA_CS_N<1>")
	)
	(segment
		(start 25.09774 -264.77468)
		(end 24.126952 -264.77468)
		(width 0.18288)
		(layer "In11.Cu")
		(net "M_D_CPU1_SA_CS_N<1>")
	)
	(segment
		(start 58.123582 -262.328914)
		(end 57.930542 -262.521954)
		(width 0.18288)
		(layer "In11.Cu")
		(net "M_D_CPU1_SA_CS_N<1>")
	)
	(segment
		(start 84.198968 -258.237736)
		(end 83.83143 -257.870198)
		(width 0.088646)
		(layer "In11.Cu")
		(net "M_D_CPU1_SA_CS_N<1>")
	)
	(segment
		(start 27.233118 -263.860026)
		(end 26.012394 -263.860026)
		(width 0.18288)
		(layer "In11.Cu")
		(net "M_D_CPU1_SA_CS_N<1>")
	)
	(segment
		(start 27.890724 -263.20242)
		(end 27.233118 -263.860026)
		(width 0.18288)
		(layer "In11.Cu")
		(net "M_D_CPU1_SA_CS_N<1>")
	)
	(segment
		(start 55.790338 -262.328914)
		(end 55.07736 -263.041892)
		(width 0.18288)
		(layer "In11.Cu")
		(net "M_D_CPU1_SA_CS_N<1>")
	)
	(segment
		(start 15.104618 -265.594592)
		(end 15.104618 -266.370816)
		(width 0.18288)
		(layer "In11.Cu")
		(net "M_D_CPU1_SA_CS_N<1>")
	)
	(segment
		(start 14.911578 -266.563856)
		(end 13.798296 -266.563856)
		(width 0.18288)
		(layer "In11.Cu")
		(net "M_D_CPU1_SA_CS_N<1>")
	)
	(segment
		(start 57.229502 -262.744712)
		(end 57.229502 -262.521954)
		(width 0.18288)
		(layer "In11.Cu")
		(net "M_D_CPU1_SA_CS_N<1>")
	)
	(segment
		(start 29.204158 -263.20242)
		(end 27.890724 -263.20242)
		(width 0.18288)
		(layer "In11.Cu")
		(net "M_D_CPU1_SA_CS_N<1>")
	)
	(segment
		(start 96.99625 -258.313428)
		(end 96.985836 -258.307332)
		(width 0.088646)
		(layer "In11.Cu")
		(net "M_D_CPU1_SA_CS_N<1>")
	)
	(segment
		(start 15.297658 -265.401552)
		(end 15.104618 -265.594592)
		(width 0.18288)
		(layer "In11.Cu")
		(net "M_D_CPU1_SA_CS_N<1>")
	)
	(segment
		(start 22.520148 -266.381484)
		(end 21.439124 -266.381484)
		(width 0.18288)
		(layer "In11.Cu")
		(net "M_D_CPU1_SA_CS_N<1>")
	)
	(segment
		(start 51.643026 -263.191244)
		(end 49.568608 -263.191244)
		(width 0.18288)
		(layer "In11.Cu")
		(net "M_D_CPU1_SA_CS_N<1>")
	)
	(segment
		(start 83.83143 -257.870198)
		(end 82.987134 -257.870198)
		(width 0.088646)
		(layer "In11.Cu")
		(net "M_D_CPU1_SA_CS_N<1>")
	)
	(segment
		(start 61.291216 -262.244586)
		(end 61.291216 -262.107426)
		(width 0.18288)
		(layer "In11.Cu")
		(net "M_D_CPU1_SA_CS_N<1>")
	)
	(segment
		(start 71.669402 -259.51053)
		(end 68.142358 -259.51053)
		(width 0.18288)
		(layer "In11.Cu")
		(net "M_D_CPU1_SA_CS_N<1>")
	)
	(segment
		(start 61.291216 -262.107426)
		(end 61.098176 -261.914386)
		(width 0.18288)
		(layer "In11.Cu")
		(net "M_D_CPU1_SA_CS_N<1>")
	)
	(segment
		(start 30.173168 -263.068054)
		(end 29.338524 -263.068054)
		(width 0.18288)
		(layer "In11.Cu")
		(net "M_D_CPU1_SA_CS_N<1>")
	)
	(segment
		(start 36.912804 -263.19099)
		(end 35.179762 -263.19099)
		(width 0.18288)
		(layer "In11.Cu")
		(net "M_D_CPU1_SA_CS_N<1>")
	)
	(segment
		(start 29.338524 -263.068054)
		(end 29.204158 -263.20242)
		(width 0.18288)
		(layer "In11.Cu")
		(net "M_D_CPU1_SA_CS_N<1>")
	)
	(segment
		(start 91.357196 -258.313428)
		(end 91.346782 -258.307332)
		(width 0.088646)
		(layer "In11.Cu")
		(net "M_D_CPU1_SA_CS_N<1>")
	)
	(segment
		(start 81.664048 -257.870198)
		(end 81.173574 -258.360672)
		(width 0.18288)
		(layer "In11.Cu")
		(net "M_D_CPU1_SA_CS_N<1>")
	)
	(segment
		(start 35.179762 -263.19099)
		(end 34.536126 -263.834626)
		(width 0.18288)
		(layer "In11.Cu")
		(net "M_D_CPU1_SA_CS_N<1>")
	)
	(segment
		(start 49.433226 -263.326626)
		(end 47.67834 -263.326626)
		(width 0.18288)
		(layer "In11.Cu")
		(net "M_D_CPU1_SA_CS_N<1>")
	)
	(segment
		(start 49.568608 -263.191244)
		(end 49.433226 -263.326626)
		(width 0.18288)
		(layer "In11.Cu")
		(net "M_D_CPU1_SA_CS_N<1>")
	)
	(arc
		(start 96.041464 -258.304792)
		(mid 95.765023 -258.237626)
		(end 95.490792 -258.313428)
		(width 0.088646)
		(layer "In11.Cu")
		(net "M_D_CPU1_SA_CS_N<1>")
	)
	(arc
		(start 88.537796 -258.313428)
		(mid 88.255094 -258.237686)
		(end 87.972392 -258.313428)
		(width 0.088646)
		(layer "In11.Cu")
		(net "M_D_CPU1_SA_CS_N<1>")
	)
	(arc
		(start 87.032592 -258.313428)
		(mid 86.845394 -258.363571)
		(end 86.658196 -258.313428)
		(width 0.088646)
		(layer "In11.Cu")
		(net "M_D_CPU1_SA_CS_N<1>")
	)
	(arc
		(start 85.152992 -258.313428)
		(mid 84.965794 -258.363571)
		(end 84.778596 -258.313428)
		(width 0.088646)
		(layer "In11.Cu")
		(net "M_D_CPU1_SA_CS_N<1>")
	)
	(arc
		(start 89.477596 -258.313428)
		(mid 89.194894 -258.237686)
		(end 88.912192 -258.313428)
		(width 0.088646)
		(layer "In11.Cu")
		(net "M_D_CPU1_SA_CS_N<1>")
	)
	(arc
		(start 86.092792 -258.313428)
		(mid 85.905594 -258.363571)
		(end 85.718396 -258.313428)
		(width 0.088646)
		(layer "In11.Cu")
		(net "M_D_CPU1_SA_CS_N<1>")
	)
	(arc
		(start 84.778596 -258.313428)
		(mid 84.64223 -258.25695)
		(end 84.495894 -258.237736)
		(width 0.088646)
		(layer "In11.Cu")
		(net "M_D_CPU1_SA_CS_N<1>")
	)
	(arc
		(start 92.671646 -258.313428)
		(mid 92.484448 -258.363571)
		(end 92.29725 -258.313428)
		(width 0.088646)
		(layer "In11.Cu")
		(net "M_D_CPU1_SA_CS_N<1>")
	)
	(arc
		(start 91.731592 -258.313428)
		(mid 91.544394 -258.363571)
		(end 91.357196 -258.313428)
		(width 0.088646)
		(layer "In11.Cu")
		(net "M_D_CPU1_SA_CS_N<1>")
	)
	(arc
		(start 93.226382 -258.307332)
		(mid 92.948204 -258.23764)
		(end 92.671646 -258.313428)
		(width 0.088646)
		(layer "In11.Cu")
		(net "M_D_CPU1_SA_CS_N<1>")
	)
	(arc
		(start 94.550992 -258.313428)
		(mid 94.363794 -258.363571)
		(end 94.176596 -258.313428)
		(width 0.088646)
		(layer "In11.Cu")
		(net "M_D_CPU1_SA_CS_N<1>")
	)
	(arc
		(start 88.912192 -258.313428)
		(mid 88.724994 -258.363571)
		(end 88.537796 -258.313428)
		(width 0.088646)
		(layer "In11.Cu")
		(net "M_D_CPU1_SA_CS_N<1>")
	)
	(arc
		(start 91.346782 -258.307332)
		(mid 91.068604 -258.23764)
		(end 90.792046 -258.313428)
		(width 0.088646)
		(layer "In11.Cu")
		(net "M_D_CPU1_SA_CS_N<1>")
	)
	(arc
		(start 92.286836 -258.307332)
		(mid 92.008404 -258.237518)
		(end 91.731592 -258.313428)
		(width 0.088646)
		(layer "In11.Cu")
		(net "M_D_CPU1_SA_CS_N<1>")
	)
	(arc
		(start 87.972392 -258.313428)
		(mid 87.785194 -258.363571)
		(end 87.597996 -258.313428)
		(width 0.088646)
		(layer "In11.Cu")
		(net "M_D_CPU1_SA_CS_N<1>")
	)
	(arc
		(start 95.490792 -258.313428)
		(mid 95.303594 -258.363571)
		(end 95.116396 -258.313428)
		(width 0.088646)
		(layer "In11.Cu")
		(net "M_D_CPU1_SA_CS_N<1>")
	)
	(arc
		(start 94.161864 -258.304792)
		(mid 93.885423 -258.237626)
		(end 93.611192 -258.313428)
		(width 0.088646)
		(layer "In11.Cu")
		(net "M_D_CPU1_SA_CS_N<1>")
	)
	(arc
		(start 90.792046 -258.313428)
		(mid 90.604848 -258.363571)
		(end 90.41765 -258.313428)
		(width 0.088646)
		(layer "In11.Cu")
		(net "M_D_CPU1_SA_CS_N<1>")
	)
	(arc
		(start 96.430592 -258.313428)
		(mid 96.243394 -258.363571)
		(end 96.056196 -258.313428)
		(width 0.088646)
		(layer "In11.Cu")
		(net "M_D_CPU1_SA_CS_N<1>")
	)
	(arc
		(start 97.370646 -258.313428)
		(mid 97.183448 -258.363571)
		(end 96.99625 -258.313428)
		(width 0.088646)
		(layer "In11.Cu")
		(net "M_D_CPU1_SA_CS_N<1>")
	)
	(arc
		(start 97.935034 -258.313428)
		(mid 97.65284 -258.237838)
		(end 97.370646 -258.313428)
		(width 0.088646)
		(layer "In11.Cu")
		(net "M_D_CPU1_SA_CS_N<1>")
	)
	(arc
		(start 87.597996 -258.313428)
		(mid 87.315294 -258.237686)
		(end 87.032592 -258.313428)
		(width 0.088646)
		(layer "In11.Cu")
		(net "M_D_CPU1_SA_CS_N<1>")
	)
	(arc
		(start 86.658196 -258.313428)
		(mid 86.375494 -258.237686)
		(end 86.092792 -258.313428)
		(width 0.088646)
		(layer "In11.Cu")
		(net "M_D_CPU1_SA_CS_N<1>")
	)
	(arc
		(start 96.985836 -258.307332)
		(mid 96.707404 -258.237518)
		(end 96.430592 -258.313428)
		(width 0.088646)
		(layer "In11.Cu")
		(net "M_D_CPU1_SA_CS_N<1>")
	)
	(arc
		(start 95.116396 -258.313428)
		(mid 94.833694 -258.237686)
		(end 94.550992 -258.313428)
		(width 0.088646)
		(layer "In11.Cu")
		(net "M_D_CPU1_SA_CS_N<1>")
	)
	(arc
		(start 90.41765 -258.313428)
		(mid 90.140837 -258.237592)
		(end 89.862406 -258.307332)
		(width 0.088646)
		(layer "In11.Cu")
		(net "M_D_CPU1_SA_CS_N<1>")
	)
	(arc
		(start 93.611192 -258.313428)
		(mid 93.423994 -258.363571)
		(end 93.236796 -258.313428)
		(width 0.088646)
		(layer "In11.Cu")
		(net "M_D_CPU1_SA_CS_N<1>")
	)
	(arc
		(start 89.851992 -258.313428)
		(mid 89.664794 -258.363571)
		(end 89.477596 -258.313428)
		(width 0.088646)
		(layer "In11.Cu")
		(net "M_D_CPU1_SA_CS_N<1>")
	)
	(arc
		(start 85.718396 -258.313428)
		(mid 85.435694 -258.237686)
		(end 85.152992 -258.313428)
		(width 0.088646)
		(layer "In11.Cu")
		(net "M_D_CPU1_SA_CS_N<1>")
	)
	(segment
		(start 99.063048 -259.616702)
		(end 99.062794 -259.616956)
		(width 0.20066)
		(layer "F.Cu")
		(net "M_D_CPU1_SA_CS_N<0>")
	)
	(segment
		(start 99.063048 -259.081016)
		(end 99.063048 -259.616702)
		(width 0.20066)
		(layer "F.Cu")
		(net "M_D_CPU1_SA_CS_N<0>")
	)
	(segment
		(start 8.140446 -267.866622)
		(end 9.245346 -267.866622)
		(width 0.20066)
		(layer "F.Cu")
		(net "M_D_CPU1_SA_CS_N<0>")
	)
	(segment
		(start 81.924144 -258.587748)
		(end 81.450942 -259.06095)
		(width 0.18288)
		(layer "In11.Cu")
		(net "M_D_CPU1_SA_CS_N<0>")
	)
	(segment
		(start 95.031306 -259.121402)
		(end 95.020892 -259.127498)
		(width 0.088646)
		(layer "In11.Cu")
		(net "M_D_CPU1_SA_CS_N<0>")
	)
	(segment
		(start 21.77542 -268.086078)
		(end 21.131022 -267.44168)
		(width 0.18288)
		(layer "In11.Cu")
		(net "M_D_CPU1_SA_CS_N<0>")
	)
	(segment
		(start 64.771016 -263.243314)
		(end 63.751714 -263.243314)
		(width 0.18288)
		(layer "In11.Cu")
		(net "M_D_CPU1_SA_CS_N<0>")
	)
	(segment
		(start 14.093952 -267.948918)
		(end 13.73632 -268.30655)
		(width 0.18288)
		(layer "In11.Cu")
		(net "M_D_CPU1_SA_CS_N<0>")
	)
	(segment
		(start 34.428684 -265.50747)
		(end 32.93237 -265.50747)
		(width 0.18288)
		(layer "In11.Cu")
		(net "M_D_CPU1_SA_CS_N<0>")
	)
	(segment
		(start 45.470826 -264.749026)
		(end 44.190666 -264.749026)
		(width 0.18288)
		(layer "In11.Cu")
		(net "M_D_CPU1_SA_CS_N<0>")
	)
	(segment
		(start 17.653 -267.441934)
		(end 15.810484 -267.441934)
		(width 0.18288)
		(layer "In11.Cu")
		(net "M_D_CPU1_SA_CS_N<0>")
	)
	(segment
		(start 51.768756 -264.714736)
		(end 51.592226 -264.891266)
		(width 0.18288)
		(layer "In11.Cu")
		(net "M_D_CPU1_SA_CS_N<0>")
	)
	(segment
		(start 83.75015 -258.587748)
		(end 82.987134 -258.587748)
		(width 0.088646)
		(layer "In11.Cu")
		(net "M_D_CPU1_SA_CS_N<0>")
	)
	(segment
		(start 67.475354 -262.230108)
		(end 65.784222 -262.230108)
		(width 0.18288)
		(layer "In11.Cu")
		(net "M_D_CPU1_SA_CS_N<0>")
	)
	(segment
		(start 48.077882 -265.03757)
		(end 47.931578 -264.891266)
		(width 0.18288)
		(layer "In11.Cu")
		(net "M_D_CPU1_SA_CS_N<0>")
	)
	(segment
		(start 25.049226 -266.552426)
		(end 24.096726 -266.552426)
		(width 0.18288)
		(layer "In11.Cu")
		(net "M_D_CPU1_SA_CS_N<0>")
	)
	(segment
		(start 65.784222 -262.230108)
		(end 64.771016 -263.243314)
		(width 0.18288)
		(layer "In11.Cu")
		(net "M_D_CPU1_SA_CS_N<0>")
	)
	(segment
		(start 94.09176 -259.121402)
		(end 94.081346 -259.127498)
		(width 0.088646)
		(layer "In11.Cu")
		(net "M_D_CPU1_SA_CS_N<0>")
	)
	(segment
		(start 82.987134 -258.587748)
		(end 81.924144 -258.587748)
		(width 0.18288)
		(layer "In11.Cu")
		(net "M_D_CPU1_SA_CS_N<0>")
	)
	(segment
		(start 73.350374 -259.06095)
		(end 71.884794 -260.52653)
		(width 0.18288)
		(layer "In11.Cu")
		(net "M_D_CPU1_SA_CS_N<0>")
	)
	(segment
		(start 51.592226 -264.891266)
		(end 50.296318 -264.891266)
		(width 0.18288)
		(layer "In11.Cu")
		(net "M_D_CPU1_SA_CS_N<0>")
	)
	(segment
		(start 59.00166 -264.114026)
		(end 58.88609 -263.998456)
		(width 0.18288)
		(layer "In11.Cu")
		(net "M_D_CPU1_SA_CS_N<0>")
	)
	(segment
		(start 19.585178 -267.44168)
		(end 19.432778 -267.28928)
		(width 0.18288)
		(layer "In11.Cu")
		(net "M_D_CPU1_SA_CS_N<0>")
	)
	(segment
		(start 36.707826 -264.891012)
		(end 35.045142 -264.891012)
		(width 0.18288)
		(layer "In11.Cu")
		(net "M_D_CPU1_SA_CS_N<0>")
	)
	(segment
		(start 35.045142 -264.891012)
		(end 34.428684 -265.50747)
		(width 0.18288)
		(layer "In11.Cu")
		(net "M_D_CPU1_SA_CS_N<0>")
	)
	(segment
		(start 43.860466 -265.079226)
		(end 40.414448 -265.079226)
		(width 0.18288)
		(layer "In11.Cu")
		(net "M_D_CPU1_SA_CS_N<0>")
	)
	(segment
		(start 21.131022 -267.44168)
		(end 19.585178 -267.44168)
		(width 0.18288)
		(layer "In11.Cu")
		(net "M_D_CPU1_SA_CS_N<0>")
	)
	(segment
		(start 17.805654 -267.28928)
		(end 17.653 -267.441934)
		(width 0.18288)
		(layer "In11.Cu")
		(net "M_D_CPU1_SA_CS_N<0>")
	)
	(segment
		(start 15.3035 -267.948918)
		(end 14.093952 -267.948918)
		(width 0.18288)
		(layer "In11.Cu")
		(net "M_D_CPU1_SA_CS_N<0>")
	)
	(segment
		(start 27.208226 -265.536426)
		(end 26.065226 -265.536426)
		(width 0.18288)
		(layer "In11.Cu")
		(net "M_D_CPU1_SA_CS_N<0>")
	)
	(segment
		(start 40.414448 -265.079226)
		(end 40.078914 -264.743692)
		(width 0.18288)
		(layer "In11.Cu")
		(net "M_D_CPU1_SA_CS_N<0>")
	)
	(segment
		(start 50.296318 -264.891266)
		(end 50.150014 -265.03757)
		(width 0.18288)
		(layer "In11.Cu")
		(net "M_D_CPU1_SA_CS_N<0>")
	)
	(segment
		(start 9.685274 -268.30655)
		(end 9.245346 -267.866622)
		(width 0.18288)
		(layer "In11.Cu")
		(net "M_D_CPU1_SA_CS_N<0>")
	)
	(segment
		(start 47.931578 -264.891266)
		(end 45.613066 -264.891266)
		(width 0.18288)
		(layer "In11.Cu")
		(net "M_D_CPU1_SA_CS_N<0>")
	)
	(segment
		(start 93.156278 -259.118862)
		(end 93.141546 -259.127498)
		(width 0.088646)
		(layer "In11.Cu")
		(net "M_D_CPU1_SA_CS_N<0>")
	)
	(segment
		(start 50.150014 -265.03757)
		(end 48.077882 -265.03757)
		(width 0.18288)
		(layer "In11.Cu")
		(net "M_D_CPU1_SA_CS_N<0>")
	)
	(segment
		(start 55.199026 -264.714736)
		(end 51.768756 -264.714736)
		(width 0.18288)
		(layer "In11.Cu")
		(net "M_D_CPU1_SA_CS_N<0>")
	)
	(segment
		(start 55.915306 -263.998456)
		(end 55.199026 -264.714736)
		(width 0.18288)
		(layer "In11.Cu")
		(net "M_D_CPU1_SA_CS_N<0>")
	)
	(segment
		(start 98.310446 -259.292598)
		(end 98.024442 -259.127498)
		(width 0.088646)
		(layer "In11.Cu")
		(net "M_D_CPU1_SA_CS_N<0>")
	)
	(segment
		(start 24.096726 -266.552426)
		(end 22.563074 -268.086078)
		(width 0.18288)
		(layer "In11.Cu")
		(net "M_D_CPU1_SA_CS_N<0>")
	)
	(segment
		(start 28.681426 -265.053826)
		(end 27.690826 -265.053826)
		(width 0.18288)
		(layer "In11.Cu")
		(net "M_D_CPU1_SA_CS_N<0>")
	)
	(segment
		(start 95.975678 -259.118862)
		(end 95.960946 -259.127498)
		(width 0.088646)
		(layer "In11.Cu")
		(net "M_D_CPU1_SA_CS_N<0>")
	)
	(segment
		(start 32.31388 -264.88898)
		(end 28.846272 -264.88898)
		(width 0.18288)
		(layer "In11.Cu")
		(net "M_D_CPU1_SA_CS_N<0>")
	)
	(segment
		(start 92.216478 -259.118862)
		(end 92.201746 -259.127498)
		(width 0.088646)
		(layer "In11.Cu")
		(net "M_D_CPU1_SA_CS_N<0>")
	)
	(segment
		(start 22.563074 -268.086078)
		(end 21.77542 -268.086078)
		(width 0.18288)
		(layer "In11.Cu")
		(net "M_D_CPU1_SA_CS_N<0>")
	)
	(segment
		(start 45.613066 -264.891266)
		(end 45.470826 -264.749026)
		(width 0.18288)
		(layer "In11.Cu")
		(net "M_D_CPU1_SA_CS_N<0>")
	)
	(segment
		(start 27.690826 -265.053826)
		(end 27.208226 -265.536426)
		(width 0.18288)
		(layer "In11.Cu")
		(net "M_D_CPU1_SA_CS_N<0>")
	)
	(segment
		(start 32.93237 -265.50747)
		(end 32.31388 -264.88898)
		(width 0.18288)
		(layer "In11.Cu")
		(net "M_D_CPU1_SA_CS_N<0>")
	)
	(segment
		(start 96.915478 -259.118862)
		(end 96.900746 -259.127498)
		(width 0.088646)
		(layer "In11.Cu")
		(net "M_D_CPU1_SA_CS_N<0>")
	)
	(segment
		(start 90.332306 -259.121402)
		(end 90.321892 -259.127498)
		(width 0.088646)
		(layer "In11.Cu")
		(net "M_D_CPU1_SA_CS_N<0>")
	)
	(segment
		(start 84.230718 -259.068316)
		(end 83.75015 -258.587748)
		(width 0.088646)
		(layer "In11.Cu")
		(net "M_D_CPU1_SA_CS_N<0>")
	)
	(segment
		(start 13.73632 -268.30655)
		(end 9.685274 -268.30655)
		(width 0.18288)
		(layer "In11.Cu")
		(net "M_D_CPU1_SA_CS_N<0>")
	)
	(segment
		(start 44.190666 -264.749026)
		(end 43.860466 -265.079226)
		(width 0.18288)
		(layer "In11.Cu")
		(net "M_D_CPU1_SA_CS_N<0>")
	)
	(segment
		(start 71.884794 -260.52653)
		(end 71.588122 -260.52653)
		(width 0.18288)
		(layer "In11.Cu")
		(net "M_D_CPU1_SA_CS_N<0>")
	)
	(segment
		(start 81.450942 -259.06095)
		(end 73.350374 -259.06095)
		(width 0.18288)
		(layer "In11.Cu")
		(net "M_D_CPU1_SA_CS_N<0>")
	)
	(segment
		(start 97.840546 -259.127498)
		(end 97.840292 -259.127498)
		(width 0.088646)
		(layer "In11.Cu")
		(net "M_D_CPU1_SA_CS_N<0>")
	)
	(segment
		(start 63.751714 -263.243314)
		(end 62.648084 -263.700768)
		(width 0.18288)
		(layer "In11.Cu")
		(net "M_D_CPU1_SA_CS_N<0>")
	)
	(segment
		(start 40.078914 -264.743692)
		(end 36.855146 -264.743692)
		(width 0.18288)
		(layer "In11.Cu")
		(net "M_D_CPU1_SA_CS_N<0>")
	)
	(segment
		(start 36.855146 -264.743692)
		(end 36.707826 -264.891012)
		(width 0.18288)
		(layer "In11.Cu")
		(net "M_D_CPU1_SA_CS_N<0>")
	)
	(segment
		(start 62.234826 -264.114026)
		(end 59.00166 -264.114026)
		(width 0.18288)
		(layer "In11.Cu")
		(net "M_D_CPU1_SA_CS_N<0>")
	)
	(segment
		(start 15.810484 -267.441934)
		(end 15.3035 -267.948918)
		(width 0.18288)
		(layer "In11.Cu")
		(net "M_D_CPU1_SA_CS_N<0>")
	)
	(segment
		(start 28.846272 -264.88898)
		(end 28.681426 -265.053826)
		(width 0.18288)
		(layer "In11.Cu")
		(net "M_D_CPU1_SA_CS_N<0>")
	)
	(segment
		(start 62.648084 -263.700768)
		(end 62.234826 -264.114026)
		(width 0.18288)
		(layer "In11.Cu")
		(net "M_D_CPU1_SA_CS_N<0>")
	)
	(segment
		(start 26.065226 -265.536426)
		(end 25.049226 -266.552426)
		(width 0.18288)
		(layer "In11.Cu")
		(net "M_D_CPU1_SA_CS_N<0>")
	)
	(segment
		(start 58.88609 -263.998456)
		(end 55.915306 -263.998456)
		(width 0.18288)
		(layer "In11.Cu")
		(net "M_D_CPU1_SA_CS_N<0>")
	)
	(segment
		(start 19.432778 -267.28928)
		(end 17.805654 -267.28928)
		(width 0.18288)
		(layer "In11.Cu")
		(net "M_D_CPU1_SA_CS_N<0>")
	)
	(segment
		(start 71.588122 -260.52653)
		(end 67.475354 -262.230108)
		(width 0.18288)
		(layer "In11.Cu")
		(net "M_D_CPU1_SA_CS_N<0>")
	)
	(arc
		(start 89.947496 -259.127498)
		(mid 89.664794 -259.051722)
		(end 89.382092 -259.127498)
		(width 0.088646)
		(layer "In11.Cu")
		(net "M_D_CPU1_SA_CS_N<0>")
	)
	(arc
		(start 94.081346 -259.127498)
		(mid 93.894148 -259.177641)
		(end 93.70695 -259.127498)
		(width 0.088646)
		(layer "In11.Cu")
		(net "M_D_CPU1_SA_CS_N<0>")
	)
	(arc
		(start 84.308696 -259.127498)
		(mid 84.267766 -259.100465)
		(end 84.230718 -259.068316)
		(width 0.088646)
		(layer "In11.Cu")
		(net "M_D_CPU1_SA_CS_N<0>")
	)
	(arc
		(start 87.502492 -259.127498)
		(mid 87.315294 -259.177641)
		(end 87.128096 -259.127498)
		(width 0.088646)
		(layer "In11.Cu")
		(net "M_D_CPU1_SA_CS_N<0>")
	)
	(arc
		(start 95.58655 -259.127498)
		(mid 95.309737 -259.051628)
		(end 95.031306 -259.121402)
		(width 0.088646)
		(layer "In11.Cu")
		(net "M_D_CPU1_SA_CS_N<0>")
	)
	(arc
		(start 98.558096 -259.367274)
		(mid 98.429944 -259.344287)
		(end 98.310446 -259.292598)
		(width 0.088646)
		(layer "In11.Cu")
		(net "M_D_CPU1_SA_CS_N<0>")
	)
	(arc
		(start 90.321892 -259.127498)
		(mid 90.134694 -259.177641)
		(end 89.947496 -259.127498)
		(width 0.088646)
		(layer "In11.Cu")
		(net "M_D_CPU1_SA_CS_N<0>")
	)
	(arc
		(start 89.382092 -259.127498)
		(mid 89.194894 -259.177641)
		(end 89.007696 -259.127498)
		(width 0.088646)
		(layer "In11.Cu")
		(net "M_D_CPU1_SA_CS_N<0>")
	)
	(arc
		(start 87.128096 -259.127498)
		(mid 86.845394 -259.051722)
		(end 86.562692 -259.127498)
		(width 0.088646)
		(layer "In11.Cu")
		(net "M_D_CPU1_SA_CS_N<0>")
	)
	(arc
		(start 92.76715 -259.127498)
		(mid 92.492951 -259.051663)
		(end 92.216478 -259.118862)
		(width 0.088646)
		(layer "In11.Cu")
		(net "M_D_CPU1_SA_CS_N<0>")
	)
	(arc
		(start 96.52635 -259.127498)
		(mid 96.252151 -259.051663)
		(end 95.975678 -259.118862)
		(width 0.088646)
		(layer "In11.Cu")
		(net "M_D_CPU1_SA_CS_N<0>")
	)
	(arc
		(start 96.900746 -259.127498)
		(mid 96.713548 -259.177641)
		(end 96.52635 -259.127498)
		(width 0.088646)
		(layer "In11.Cu")
		(net "M_D_CPU1_SA_CS_N<0>")
	)
	(arc
		(start 91.82735 -259.127498)
		(mid 91.544648 -259.051722)
		(end 91.261946 -259.127498)
		(width 0.088646)
		(layer "In11.Cu")
		(net "M_D_CPU1_SA_CS_N<0>")
	)
	(arc
		(start 91.261946 -259.127498)
		(mid 91.074748 -259.177641)
		(end 90.88755 -259.127498)
		(width 0.088646)
		(layer "In11.Cu")
		(net "M_D_CPU1_SA_CS_N<0>")
	)
	(arc
		(start 84.683092 -259.127498)
		(mid 84.495894 -259.177641)
		(end 84.308696 -259.127498)
		(width 0.088646)
		(layer "In11.Cu")
		(net "M_D_CPU1_SA_CS_N<0>")
	)
	(arc
		(start 93.141546 -259.127498)
		(mid 92.954348 -259.177641)
		(end 92.76715 -259.127498)
		(width 0.088646)
		(layer "In11.Cu")
		(net "M_D_CPU1_SA_CS_N<0>")
	)
	(arc
		(start 98.024442 -259.127498)
		(mid 97.932494 -259.102861)
		(end 97.840546 -259.127498)
		(width 0.088646)
		(layer "In11.Cu")
		(net "M_D_CPU1_SA_CS_N<0>")
	)
	(arc
		(start 89.007696 -259.127498)
		(mid 88.724994 -259.051722)
		(end 88.442292 -259.127498)
		(width 0.088646)
		(layer "In11.Cu")
		(net "M_D_CPU1_SA_CS_N<0>")
	)
	(arc
		(start 88.067896 -259.127498)
		(mid 87.785194 -259.051722)
		(end 87.502492 -259.127498)
		(width 0.088646)
		(layer "In11.Cu")
		(net "M_D_CPU1_SA_CS_N<0>")
	)
	(arc
		(start 97.46615 -259.127498)
		(mid 97.191951 -259.051663)
		(end 96.915478 -259.118862)
		(width 0.088646)
		(layer "In11.Cu")
		(net "M_D_CPU1_SA_CS_N<0>")
	)
	(arc
		(start 97.840292 -259.127498)
		(mid 97.653238 -259.177582)
		(end 97.46615 -259.127498)
		(width 0.088646)
		(layer "In11.Cu")
		(net "M_D_CPU1_SA_CS_N<0>")
	)
	(arc
		(start 94.646496 -259.127498)
		(mid 94.369937 -259.051755)
		(end 94.09176 -259.121402)
		(width 0.088646)
		(layer "In11.Cu")
		(net "M_D_CPU1_SA_CS_N<0>")
	)
	(arc
		(start 90.88755 -259.127498)
		(mid 90.610737 -259.051628)
		(end 90.332306 -259.121402)
		(width 0.088646)
		(layer "In11.Cu")
		(net "M_D_CPU1_SA_CS_N<0>")
	)
	(arc
		(start 86.562692 -259.127498)
		(mid 86.375494 -259.177641)
		(end 86.188296 -259.127498)
		(width 0.088646)
		(layer "In11.Cu")
		(net "M_D_CPU1_SA_CS_N<0>")
	)
	(arc
		(start 95.960946 -259.127498)
		(mid 95.773748 -259.177641)
		(end 95.58655 -259.127498)
		(width 0.088646)
		(layer "In11.Cu")
		(net "M_D_CPU1_SA_CS_N<0>")
	)
	(arc
		(start 99.062794 -259.616956)
		(mid 98.830974 -259.450624)
		(end 98.558096 -259.367274)
		(width 0.088646)
		(layer "In11.Cu")
		(net "M_D_CPU1_SA_CS_N<0>")
	)
	(arc
		(start 88.442292 -259.127498)
		(mid 88.255094 -259.177641)
		(end 88.067896 -259.127498)
		(width 0.088646)
		(layer "In11.Cu")
		(net "M_D_CPU1_SA_CS_N<0>")
	)
	(arc
		(start 86.188296 -259.127498)
		(mid 85.905594 -259.051722)
		(end 85.622892 -259.127498)
		(width 0.088646)
		(layer "In11.Cu")
		(net "M_D_CPU1_SA_CS_N<0>")
	)
	(arc
		(start 85.622892 -259.127498)
		(mid 85.435694 -259.177641)
		(end 85.248496 -259.127498)
		(width 0.088646)
		(layer "In11.Cu")
		(net "M_D_CPU1_SA_CS_N<0>")
	)
	(arc
		(start 95.020892 -259.127498)
		(mid 94.833694 -259.177641)
		(end 94.646496 -259.127498)
		(width 0.088646)
		(layer "In11.Cu")
		(net "M_D_CPU1_SA_CS_N<0>")
	)
	(arc
		(start 92.201746 -259.127498)
		(mid 92.014548 -259.177641)
		(end 91.82735 -259.127498)
		(width 0.088646)
		(layer "In11.Cu")
		(net "M_D_CPU1_SA_CS_N<0>")
	)
	(arc
		(start 93.70695 -259.127498)
		(mid 93.432751 -259.051663)
		(end 93.156278 -259.118862)
		(width 0.088646)
		(layer "In11.Cu")
		(net "M_D_CPU1_SA_CS_N<0>")
	)
	(arc
		(start 85.248496 -259.127498)
		(mid 84.965794 -259.051722)
		(end 84.683092 -259.127498)
		(width 0.088646)
		(layer "In11.Cu")
		(net "M_D_CPU1_SA_CS_N<0>")
	)
	(segment
		(start 17.578578 -270.540988)
		(end 17.707102 -270.412464)
		(width 0.20066)
		(layer "F.Cu")
		(net "M_D_CPU1_SA_CB<7>")
	)
	(segment
		(start 13.937742 -270.416782)
		(end 14.063726 -270.542766)
		(width 0.20066)
		(layer "F.Cu")
		(net "M_D_CPU1_SA_CB<7>")
	)
	(segment
		(start 14.812264 -270.841724)
		(end 16.885158 -270.841724)
		(width 0.1016)
		(layer "F.Cu")
		(net "M_D_CPU1_SA_CB<7>")
	)
	(segment
		(start 14.560042 -270.855948)
		(end 14.574266 -270.841724)
		(width 0.101854)
		(layer "F.Cu")
		(net "M_D_CPU1_SA_CB<7>")
	)
	(segment
		(start 18.102326 -270.412464)
		(end 18.314162 -270.6243)
		(width 0.20066)
		(layer "F.Cu")
		(net "M_D_CPU1_SA_CB<7>")
	)
	(segment
		(start 100.002848 -261.244588)
		(end 100.002594 -261.244842)
		(width 0.20066)
		(layer "F.Cu")
		(net "M_D_CPU1_SA_CB<7>")
	)
	(segment
		(start 17.578578 -270.692626)
		(end 17.578578 -270.540988)
		(width 0.20066)
		(layer "F.Cu")
		(net "M_D_CPU1_SA_CB<7>")
	)
	(segment
		(start 17.707102 -270.412464)
		(end 18.102326 -270.412464)
		(width 0.20066)
		(layer "F.Cu")
		(net "M_D_CPU1_SA_CB<7>")
	)
	(segment
		(start 17.42948 -270.841724)
		(end 17.578578 -270.692626)
		(width 0.20066)
		(layer "F.Cu")
		(net "M_D_CPU1_SA_CB<7>")
	)
	(segment
		(start 14.20622 -270.855948)
		(end 14.560042 -270.855948)
		(width 0.20066)
		(layer "F.Cu")
		(net "M_D_CPU1_SA_CB<7>")
	)
	(segment
		(start 100.002848 -260.708902)
		(end 100.002848 -261.244588)
		(width 0.20066)
		(layer "F.Cu")
		(net "M_D_CPU1_SA_CB<7>")
	)
	(segment
		(start 14.574266 -270.841724)
		(end 14.812264 -270.841724)
		(width 0.101854)
		(layer "F.Cu")
		(net "M_D_CPU1_SA_CB<7>")
	)
	(segment
		(start 16.885158 -270.841724)
		(end 17.42948 -270.841724)
		(width 0.20066)
		(layer "F.Cu")
		(net "M_D_CPU1_SA_CB<7>")
	)
	(segment
		(start 14.063726 -270.542766)
		(end 14.063726 -270.713454)
		(width 0.20066)
		(layer "F.Cu")
		(net "M_D_CPU1_SA_CB<7>")
	)
	(segment
		(start 18.760694 -270.6243)
		(end 18.968212 -270.416782)
		(width 0.20066)
		(layer "F.Cu")
		(net "M_D_CPU1_SA_CB<7>")
	)
	(segment
		(start 12.240514 -270.416782)
		(end 13.937742 -270.416782)
		(width 0.20066)
		(layer "F.Cu")
		(net "M_D_CPU1_SA_CB<7>")
	)
	(segment
		(start 20.889214 -270.416782)
		(end 19.784314 -270.416782)
		(width 0.20066)
		(layer "F.Cu")
		(net "M_D_CPU1_SA_CB<7>")
	)
	(segment
		(start 18.968212 -270.416782)
		(end 19.784314 -270.416782)
		(width 0.20066)
		(layer "F.Cu")
		(net "M_D_CPU1_SA_CB<7>")
	)
	(segment
		(start 18.314162 -270.6243)
		(end 18.760694 -270.6243)
		(width 0.20066)
		(layer "F.Cu")
		(net "M_D_CPU1_SA_CB<7>")
	)
	(segment
		(start 14.063726 -270.713454)
		(end 14.20622 -270.855948)
		(width 0.20066)
		(layer "F.Cu")
		(net "M_D_CPU1_SA_CB<7>")
	)
	(segment
		(start 57.099454 -267.431266)
		(end 56.906414 -267.238226)
		(width 0.18288)
		(layer "In11.Cu")
		(net "M_D_CPU1_SA_CB<7>")
	)
	(segment
		(start 61.20384 -266.953746)
		(end 60.88888 -266.953746)
		(width 0.18288)
		(layer "In11.Cu")
		(net "M_D_CPU1_SA_CB<7>")
	)
	(segment
		(start 42.939462 -267.845286)
		(end 42.779442 -267.685266)
		(width 0.18288)
		(layer "In11.Cu")
		(net "M_D_CPU1_SA_CB<7>")
	)
	(segment
		(start 38.176454 -267.82776)
		(end 38.176454 -267.621258)
		(width 0.18288)
		(layer "In11.Cu")
		(net "M_D_CPU1_SA_CB<7>")
	)
	(segment
		(start 74.179938 -260.71195)
		(end 71.230236 -263.661652)
		(width 0.18288)
		(layer "In11.Cu")
		(net "M_D_CPU1_SA_CB<7>")
	)
	(segment
		(start 53.522626 -268.203426)
		(end 52.963826 -267.644626)
		(width 0.18288)
		(layer "In11.Cu")
		(net "M_D_CPU1_SA_CB<7>")
	)
	(segment
		(start 50.835814 -267.442442)
		(end 49.94783 -268.330426)
		(width 0.18288)
		(layer "In11.Cu")
		(net "M_D_CPU1_SA_CB<7>")
	)
	(segment
		(start 83.01355 -260.71195)
		(end 74.179938 -260.71195)
		(width 0.18288)
		(layer "In11.Cu")
		(net "M_D_CPU1_SA_CB<7>")
	)
	(segment
		(start 47.509684 -268.330426)
		(end 47.286418 -268.330426)
		(width 0.18288)
		(layer "In11.Cu")
		(net "M_D_CPU1_SA_CB<7>")
	)
	(segment
		(start 65.454022 -265.712702)
		(end 64.436498 -266.730226)
		(width 0.18288)
		(layer "In11.Cu")
		(net "M_D_CPU1_SA_CB<7>")
	)
	(segment
		(start 28.046426 -269.067026)
		(end 27.860498 -269.067026)
		(width 0.18288)
		(layer "In11.Cu")
		(net "M_D_CPU1_SA_CB<7>")
	)
	(segment
		(start 34.713164 -268.478508)
		(end 32.3469 -268.478508)
		(width 0.18288)
		(layer "In11.Cu")
		(net "M_D_CPU1_SA_CB<7>")
	)
	(segment
		(start 97.85096 -260.749034)
		(end 97.840546 -260.75513)
		(width 0.088646)
		(layer "In11.Cu")
		(net "M_D_CPU1_SA_CB<7>")
	)
	(segment
		(start 64.436498 -266.730226)
		(end 63.322962 -266.730226)
		(width 0.18288)
		(layer "In11.Cu")
		(net "M_D_CPU1_SA_CB<7>")
	)
	(segment
		(start 57.292494 -267.942822)
		(end 57.099454 -267.749782)
		(width 0.18288)
		(layer "In11.Cu")
		(net "M_D_CPU1_SA_CB<7>")
	)
	(segment
		(start 61.39688 -267.146786)
		(end 61.20384 -266.953746)
		(width 0.18288)
		(layer "In11.Cu")
		(net "M_D_CPU1_SA_CB<7>")
	)
	(segment
		(start 27.474418 -269.703296)
		(end 27.159458 -269.703296)
		(width 0.18288)
		(layer "In11.Cu")
		(net "M_D_CPU1_SA_CB<7>")
	)
	(segment
		(start 54.944772 -268.203426)
		(end 53.522626 -268.203426)
		(width 0.18288)
		(layer "In11.Cu")
		(net "M_D_CPU1_SA_CB<7>")
	)
	(segment
		(start 48.596804 -268.330426)
		(end 48.403764 -268.137386)
		(width 0.18288)
		(layer "In11.Cu")
		(net "M_D_CPU1_SA_CB<7>")
	)
	(segment
		(start 27.667458 -269.260066)
		(end 27.667458 -269.510256)
		(width 0.18288)
		(layer "In11.Cu")
		(net "M_D_CPU1_SA_CB<7>")
	)
	(segment
		(start 59.110626 -267.238226)
		(end 57.993534 -267.238226)
		(width 0.18288)
		(layer "In11.Cu")
		(net "M_D_CPU1_SA_CB<7>")
	)
	(segment
		(start 56.906414 -267.238226)
		(end 55.909972 -267.238226)
		(width 0.18288)
		(layer "In11.Cu")
		(net "M_D_CPU1_SA_CB<7>")
	)
	(segment
		(start 37.520118 -267.442696)
		(end 37.390324 -267.57249)
		(width 0.18288)
		(layer "In11.Cu")
		(net "M_D_CPU1_SA_CB<7>")
	)
	(segment
		(start 30.573726 -268.292326)
		(end 30.357826 -268.076426)
		(width 0.18288)
		(layer "In11.Cu")
		(net "M_D_CPU1_SA_CB<7>")
	)
	(segment
		(start 98.790506 -260.749034)
		(end 98.780092 -260.75513)
		(width 0.088646)
		(layer "In11.Cu")
		(net "M_D_CPU1_SA_CB<7>")
	)
	(segment
		(start 21.367242 -270.89481)
		(end 20.889214 -270.416782)
		(width 0.18288)
		(layer "In11.Cu")
		(net "M_D_CPU1_SA_CB<7>")
	)
	(segment
		(start 48.403764 -267.979652)
		(end 48.210724 -267.786612)
		(width 0.18288)
		(layer "In11.Cu")
		(net "M_D_CPU1_SA_CB<7>")
	)
	(segment
		(start 61.39688 -267.426186)
		(end 61.39688 -267.146786)
		(width 0.18288)
		(layer "In11.Cu")
		(net "M_D_CPU1_SA_CB<7>")
	)
	(segment
		(start 44.251626 -268.101826)
		(end 44.023026 -268.330426)
		(width 0.18288)
		(layer "In11.Cu")
		(net "M_D_CPU1_SA_CB<7>")
	)
	(segment
		(start 51.693826 -267.644626)
		(end 51.491642 -267.442442)
		(width 0.18288)
		(layer "In11.Cu")
		(net "M_D_CPU1_SA_CB<7>")
	)
	(segment
		(start 45.095668 -268.292326)
		(end 44.905168 -268.101826)
		(width 0.18288)
		(layer "In11.Cu")
		(net "M_D_CPU1_SA_CB<7>")
	)
	(segment
		(start 42.779442 -267.685266)
		(end 42.431462 -267.685266)
		(width 0.18288)
		(layer "In11.Cu")
		(net "M_D_CPU1_SA_CB<7>")
	)
	(segment
		(start 42.231564 -267.885164)
		(end 42.231564 -268.170406)
		(width 0.18288)
		(layer "In11.Cu")
		(net "M_D_CPU1_SA_CB<7>")
	)
	(segment
		(start 45.562774 -267.756386)
		(end 45.562774 -268.132306)
		(width 0.18288)
		(layer "In11.Cu")
		(net "M_D_CPU1_SA_CB<7>")
	)
	(segment
		(start 38.359842 -268.011148)
		(end 38.176454 -267.82776)
		(width 0.18288)
		(layer "In11.Cu")
		(net "M_D_CPU1_SA_CB<7>")
	)
	(segment
		(start 45.402754 -268.292326)
		(end 45.095668 -268.292326)
		(width 0.18288)
		(layer "In11.Cu")
		(net "M_D_CPU1_SA_CB<7>")
	)
	(segment
		(start 62.433962 -267.619226)
		(end 61.58992 -267.619226)
		(width 0.18288)
		(layer "In11.Cu")
		(net "M_D_CPU1_SA_CB<7>")
	)
	(segment
		(start 27.159458 -269.703296)
		(end 26.966418 -269.510256)
		(width 0.18288)
		(layer "In11.Cu")
		(net "M_D_CPU1_SA_CB<7>")
	)
	(segment
		(start 66.27876 -265.712702)
		(end 65.454022 -265.712702)
		(width 0.18288)
		(layer "In11.Cu")
		(net "M_D_CPU1_SA_CB<7>")
	)
	(segment
		(start 25.151842 -269.455646)
		(end 24.406098 -269.455646)
		(width 0.18288)
		(layer "In11.Cu")
		(net "M_D_CPU1_SA_CB<7>")
	)
	(segment
		(start 27.667458 -269.510256)
		(end 27.474418 -269.703296)
		(width 0.18288)
		(layer "In11.Cu")
		(net "M_D_CPU1_SA_CB<7>")
	)
	(segment
		(start 55.909972 -267.238226)
		(end 54.944772 -268.203426)
		(width 0.18288)
		(layer "In11.Cu")
		(net "M_D_CPU1_SA_CB<7>")
	)
	(segment
		(start 36.280598 -267.442696)
		(end 35.748976 -267.442696)
		(width 0.18288)
		(layer "In11.Cu")
		(net "M_D_CPU1_SA_CB<7>")
	)
	(segment
		(start 38.893242 -267.60551)
		(end 38.893242 -267.851128)
		(width 0.18288)
		(layer "In11.Cu")
		(net "M_D_CPU1_SA_CB<7>")
	)
	(segment
		(start 51.491642 -267.442442)
		(end 50.835814 -267.442442)
		(width 0.18288)
		(layer "In11.Cu")
		(net "M_D_CPU1_SA_CB<7>")
	)
	(segment
		(start 83.692238 -260.679438)
		(end 83.659726 -260.71195)
		(width 0.088646)
		(layer "In11.Cu")
		(net "M_D_CPU1_SA_CB<7>")
	)
	(segment
		(start 93.156278 -260.746494)
		(end 93.141546 -260.75513)
		(width 0.088646)
		(layer "In11.Cu")
		(net "M_D_CPU1_SA_CB<7>")
	)
	(segment
		(start 37.997892 -267.442696)
		(end 37.520118 -267.442696)
		(width 0.18288)
		(layer "In11.Cu")
		(net "M_D_CPU1_SA_CB<7>")
	)
	(segment
		(start 45.74032 -267.57884)
		(end 45.562774 -267.756386)
		(width 0.18288)
		(layer "In11.Cu")
		(net "M_D_CPU1_SA_CB<7>")
	)
	(segment
		(start 42.231564 -268.170406)
		(end 42.071544 -268.330426)
		(width 0.18288)
		(layer "In11.Cu")
		(net "M_D_CPU1_SA_CB<7>")
	)
	(segment
		(start 32.3469 -268.478508)
		(end 32.160718 -268.292326)
		(width 0.18288)
		(layer "In11.Cu")
		(net "M_D_CPU1_SA_CB<7>")
	)
	(segment
		(start 46.284642 -268.132306)
		(end 46.284642 -267.77188)
		(width 0.18288)
		(layer "In11.Cu")
		(net "M_D_CPU1_SA_CB<7>")
	)
	(segment
		(start 47.286418 -268.330426)
		(end 47.248318 -268.292326)
		(width 0.18288)
		(layer "In11.Cu")
		(net "M_D_CPU1_SA_CB<7>")
	)
	(segment
		(start 92.211906 -260.749034)
		(end 92.201492 -260.75513)
		(width 0.088646)
		(layer "In11.Cu")
		(net "M_D_CPU1_SA_CB<7>")
	)
	(segment
		(start 57.800494 -267.431266)
		(end 57.800494 -267.749782)
		(width 0.18288)
		(layer "In11.Cu")
		(net "M_D_CPU1_SA_CB<7>")
	)
	(segment
		(start 30.357826 -268.076426)
		(end 29.037026 -268.076426)
		(width 0.18288)
		(layer "In11.Cu")
		(net "M_D_CPU1_SA_CB<7>")
	)
	(segment
		(start 60.88888 -266.953746)
		(end 60.69584 -267.146786)
		(width 0.18288)
		(layer "In11.Cu")
		(net "M_D_CPU1_SA_CB<7>")
	)
	(segment
		(start 29.037026 -268.076426)
		(end 28.046426 -269.067026)
		(width 0.18288)
		(layer "In11.Cu")
		(net "M_D_CPU1_SA_CB<7>")
	)
	(segment
		(start 46.091602 -267.57884)
		(end 45.74032 -267.57884)
		(width 0.18288)
		(layer "In11.Cu")
		(net "M_D_CPU1_SA_CB<7>")
	)
	(segment
		(start 71.230236 -263.661652)
		(end 66.27876 -265.712702)
		(width 0.18288)
		(layer "In11.Cu")
		(net "M_D_CPU1_SA_CB<7>")
	)
	(segment
		(start 60.69584 -267.426186)
		(end 60.5028 -267.619226)
		(width 0.18288)
		(layer "In11.Cu")
		(net "M_D_CPU1_SA_CB<7>")
	)
	(segment
		(start 39.691818 -267.44295)
		(end 39.055802 -267.44295)
		(width 0.18288)
		(layer "In11.Cu")
		(net "M_D_CPU1_SA_CB<7>")
	)
	(segment
		(start 39.887398 -267.63853)
		(end 39.691818 -267.44295)
		(width 0.18288)
		(layer "In11.Cu")
		(net "M_D_CPU1_SA_CB<7>")
	)
	(segment
		(start 44.905168 -268.101826)
		(end 44.251626 -268.101826)
		(width 0.18288)
		(layer "In11.Cu")
		(net "M_D_CPU1_SA_CB<7>")
	)
	(segment
		(start 38.893242 -267.851128)
		(end 38.733222 -268.011148)
		(width 0.18288)
		(layer "In11.Cu")
		(net "M_D_CPU1_SA_CB<7>")
	)
	(segment
		(start 26.773378 -269.067026)
		(end 25.540462 -269.067026)
		(width 0.18288)
		(layer "In11.Cu")
		(net "M_D_CPU1_SA_CB<7>")
	)
	(segment
		(start 36.410392 -267.57249)
		(end 36.280598 -267.442696)
		(width 0.18288)
		(layer "In11.Cu")
		(net "M_D_CPU1_SA_CB<7>")
	)
	(segment
		(start 27.860498 -269.067026)
		(end 27.667458 -269.260066)
		(width 0.18288)
		(layer "In11.Cu")
		(net "M_D_CPU1_SA_CB<7>")
	)
	(segment
		(start 24.406098 -269.455646)
		(end 22.966934 -270.89481)
		(width 0.18288)
		(layer "In11.Cu")
		(net "M_D_CPU1_SA_CB<7>")
	)
	(segment
		(start 91.27236 -260.749034)
		(end 91.261946 -260.75513)
		(width 0.088646)
		(layer "In11.Cu")
		(net "M_D_CPU1_SA_CB<7>")
	)
	(segment
		(start 39.887398 -268.068806)
		(end 39.887398 -267.63853)
		(width 0.18288)
		(layer "In11.Cu")
		(net "M_D_CPU1_SA_CB<7>")
	)
	(segment
		(start 38.176454 -267.621258)
		(end 37.997892 -267.442696)
		(width 0.18288)
		(layer "In11.Cu")
		(net "M_D_CPU1_SA_CB<7>")
	)
	(segment
		(start 83.659726 -260.71195)
		(end 83.01355 -260.71195)
		(width 0.088646)
		(layer "In11.Cu")
		(net "M_D_CPU1_SA_CB<7>")
	)
	(segment
		(start 32.160718 -268.292326)
		(end 30.573726 -268.292326)
		(width 0.18288)
		(layer "In11.Cu")
		(net "M_D_CPU1_SA_CB<7>")
	)
	(segment
		(start 48.403764 -268.137386)
		(end 48.403764 -267.979652)
		(width 0.18288)
		(layer "In11.Cu")
		(net "M_D_CPU1_SA_CB<7>")
	)
	(segment
		(start 89.39276 -260.749034)
		(end 89.382346 -260.75513)
		(width 0.088646)
		(layer "In11.Cu")
		(net "M_D_CPU1_SA_CB<7>")
	)
	(segment
		(start 49.94783 -268.330426)
		(end 48.596804 -268.330426)
		(width 0.18288)
		(layer "In11.Cu")
		(net "M_D_CPU1_SA_CB<7>")
	)
	(segment
		(start 59.491626 -267.619226)
		(end 59.110626 -267.238226)
		(width 0.18288)
		(layer "In11.Cu")
		(net "M_D_CPU1_SA_CB<7>")
	)
	(segment
		(start 47.702724 -268.137386)
		(end 47.509684 -268.330426)
		(width 0.18288)
		(layer "In11.Cu")
		(net "M_D_CPU1_SA_CB<7>")
	)
	(segment
		(start 42.431462 -267.685266)
		(end 42.231564 -267.885164)
		(width 0.18288)
		(layer "In11.Cu")
		(net "M_D_CPU1_SA_CB<7>")
	)
	(segment
		(start 46.284642 -267.77188)
		(end 46.091602 -267.57884)
		(width 0.18288)
		(layer "In11.Cu")
		(net "M_D_CPU1_SA_CB<7>")
	)
	(segment
		(start 100.002594 -261.244842)
		(end 99.725226 -260.979412)
		(width 0.088646)
		(layer "In11.Cu")
		(net "M_D_CPU1_SA_CB<7>")
	)
	(segment
		(start 57.607454 -267.942822)
		(end 57.292494 -267.942822)
		(width 0.18288)
		(layer "In11.Cu")
		(net "M_D_CPU1_SA_CB<7>")
	)
	(segment
		(start 38.733222 -268.011148)
		(end 38.359842 -268.011148)
		(width 0.18288)
		(layer "In11.Cu")
		(net "M_D_CPU1_SA_CB<7>")
	)
	(segment
		(start 57.800494 -267.749782)
		(end 57.607454 -267.942822)
		(width 0.18288)
		(layer "In11.Cu")
		(net "M_D_CPU1_SA_CB<7>")
	)
	(segment
		(start 84.025994 -260.679438)
		(end 83.692238 -260.679438)
		(width 0.088646)
		(layer "In11.Cu")
		(net "M_D_CPU1_SA_CB<7>")
	)
	(segment
		(start 35.748976 -267.442696)
		(end 34.713164 -268.478508)
		(width 0.18288)
		(layer "In11.Cu")
		(net "M_D_CPU1_SA_CB<7>")
	)
	(segment
		(start 61.58992 -267.619226)
		(end 61.39688 -267.426186)
		(width 0.18288)
		(layer "In11.Cu")
		(net "M_D_CPU1_SA_CB<7>")
	)
	(segment
		(start 22.966934 -270.89481)
		(end 21.367242 -270.89481)
		(width 0.18288)
		(layer "In11.Cu")
		(net "M_D_CPU1_SA_CB<7>")
	)
	(segment
		(start 46.444662 -268.292326)
		(end 46.284642 -268.132306)
		(width 0.18288)
		(layer "In11.Cu")
		(net "M_D_CPU1_SA_CB<7>")
	)
	(segment
		(start 39.055802 -267.44295)
		(end 38.893242 -267.60551)
		(width 0.18288)
		(layer "In11.Cu")
		(net "M_D_CPU1_SA_CB<7>")
	)
	(segment
		(start 88.452706 -260.749034)
		(end 88.442292 -260.75513)
		(width 0.088646)
		(layer "In11.Cu")
		(net "M_D_CPU1_SA_CB<7>")
	)
	(segment
		(start 37.390324 -267.57249)
		(end 36.410392 -267.57249)
		(width 0.18288)
		(layer "In11.Cu")
		(net "M_D_CPU1_SA_CB<7>")
	)
	(segment
		(start 43.099482 -268.330426)
		(end 42.939462 -268.170406)
		(width 0.18288)
		(layer "In11.Cu")
		(net "M_D_CPU1_SA_CB<7>")
	)
	(segment
		(start 57.993534 -267.238226)
		(end 57.800494 -267.431266)
		(width 0.18288)
		(layer "In11.Cu")
		(net "M_D_CPU1_SA_CB<7>")
	)
	(segment
		(start 48.210724 -267.786612)
		(end 47.895764 -267.786612)
		(width 0.18288)
		(layer "In11.Cu")
		(net "M_D_CPU1_SA_CB<7>")
	)
	(segment
		(start 45.562774 -268.132306)
		(end 45.402754 -268.292326)
		(width 0.18288)
		(layer "In11.Cu")
		(net "M_D_CPU1_SA_CB<7>")
	)
	(segment
		(start 90.332306 -260.749034)
		(end 90.321892 -260.75513)
		(width 0.088646)
		(layer "In11.Cu")
		(net "M_D_CPU1_SA_CB<7>")
	)
	(segment
		(start 47.702724 -267.979652)
		(end 47.702724 -268.137386)
		(width 0.18288)
		(layer "In11.Cu")
		(net "M_D_CPU1_SA_CB<7>")
	)
	(segment
		(start 42.071544 -268.330426)
		(end 40.149018 -268.330426)
		(width 0.18288)
		(layer "In11.Cu")
		(net "M_D_CPU1_SA_CB<7>")
	)
	(segment
		(start 47.248318 -268.292326)
		(end 46.444662 -268.292326)
		(width 0.18288)
		(layer "In11.Cu")
		(net "M_D_CPU1_SA_CB<7>")
	)
	(segment
		(start 60.5028 -267.619226)
		(end 59.491626 -267.619226)
		(width 0.18288)
		(layer "In11.Cu")
		(net "M_D_CPU1_SA_CB<7>")
	)
	(segment
		(start 25.540462 -269.067026)
		(end 25.151842 -269.455646)
		(width 0.18288)
		(layer "In11.Cu")
		(net "M_D_CPU1_SA_CB<7>")
	)
	(segment
		(start 52.963826 -267.644626)
		(end 51.693826 -267.644626)
		(width 0.18288)
		(layer "In11.Cu")
		(net "M_D_CPU1_SA_CB<7>")
	)
	(segment
		(start 44.023026 -268.330426)
		(end 43.099482 -268.330426)
		(width 0.18288)
		(layer "In11.Cu")
		(net "M_D_CPU1_SA_CB<7>")
	)
	(segment
		(start 57.099454 -267.749782)
		(end 57.099454 -267.431266)
		(width 0.18288)
		(layer "In11.Cu")
		(net "M_D_CPU1_SA_CB<7>")
	)
	(segment
		(start 47.895764 -267.786612)
		(end 47.702724 -267.979652)
		(width 0.18288)
		(layer "In11.Cu")
		(net "M_D_CPU1_SA_CB<7>")
	)
	(segment
		(start 60.69584 -267.146786)
		(end 60.69584 -267.426186)
		(width 0.18288)
		(layer "In11.Cu")
		(net "M_D_CPU1_SA_CB<7>")
	)
	(segment
		(start 63.322962 -266.730226)
		(end 62.433962 -267.619226)
		(width 0.18288)
		(layer "In11.Cu")
		(net "M_D_CPU1_SA_CB<7>")
	)
	(segment
		(start 99.725226 -260.979412)
		(end 99.34575 -260.75513)
		(width 0.088646)
		(layer "In11.Cu")
		(net "M_D_CPU1_SA_CB<7>")
	)
	(segment
		(start 42.939462 -268.170406)
		(end 42.939462 -267.845286)
		(width 0.18288)
		(layer "In11.Cu")
		(net "M_D_CPU1_SA_CB<7>")
	)
	(segment
		(start 40.149018 -268.330426)
		(end 39.887398 -268.068806)
		(width 0.18288)
		(layer "In11.Cu")
		(net "M_D_CPU1_SA_CB<7>")
	)
	(segment
		(start 26.966418 -269.260066)
		(end 26.773378 -269.067026)
		(width 0.18288)
		(layer "In11.Cu")
		(net "M_D_CPU1_SA_CB<7>")
	)
	(segment
		(start 26.966418 -269.510256)
		(end 26.966418 -269.260066)
		(width 0.18288)
		(layer "In11.Cu")
		(net "M_D_CPU1_SA_CB<7>")
	)
	(arc
		(start 92.201492 -260.75513)
		(mid 92.014294 -260.805273)
		(end 91.827096 -260.75513)
		(width 0.088646)
		(layer "In11.Cu")
		(net "M_D_CPU1_SA_CB<7>")
	)
	(arc
		(start 86.562692 -260.75513)
		(mid 86.375494 -260.805273)
		(end 86.188296 -260.75513)
		(width 0.088646)
		(layer "In11.Cu")
		(net "M_D_CPU1_SA_CB<7>")
	)
	(arc
		(start 85.622892 -260.75513)
		(mid 85.435694 -260.805273)
		(end 85.248496 -260.75513)
		(width 0.088646)
		(layer "In11.Cu")
		(net "M_D_CPU1_SA_CB<7>")
	)
	(arc
		(start 97.840546 -260.75513)
		(mid 97.653348 -260.805273)
		(end 97.46615 -260.75513)
		(width 0.088646)
		(layer "In11.Cu")
		(net "M_D_CPU1_SA_CB<7>")
	)
	(arc
		(start 88.442292 -260.75513)
		(mid 88.255094 -260.805273)
		(end 88.067896 -260.75513)
		(width 0.088646)
		(layer "In11.Cu")
		(net "M_D_CPU1_SA_CB<7>")
	)
	(arc
		(start 89.947496 -260.75513)
		(mid 89.670937 -260.679421)
		(end 89.39276 -260.749034)
		(width 0.088646)
		(layer "In11.Cu")
		(net "M_D_CPU1_SA_CB<7>")
	)
	(arc
		(start 89.00795 -260.75513)
		(mid 88.731137 -260.679294)
		(end 88.452706 -260.749034)
		(width 0.088646)
		(layer "In11.Cu")
		(net "M_D_CPU1_SA_CB<7>")
	)
	(arc
		(start 91.827096 -260.75513)
		(mid 91.550537 -260.679421)
		(end 91.27236 -260.749034)
		(width 0.088646)
		(layer "In11.Cu")
		(net "M_D_CPU1_SA_CB<7>")
	)
	(arc
		(start 95.58655 -260.75513)
		(mid 95.303594 -260.679261)
		(end 95.020638 -260.75513)
		(width 0.088646)
		(layer "In11.Cu")
		(net "M_D_CPU1_SA_CB<7>")
	)
	(arc
		(start 89.382346 -260.75513)
		(mid 89.195148 -260.805273)
		(end 89.00795 -260.75513)
		(width 0.088646)
		(layer "In11.Cu")
		(net "M_D_CPU1_SA_CB<7>")
	)
	(arc
		(start 90.321892 -260.75513)
		(mid 90.134694 -260.805273)
		(end 89.947496 -260.75513)
		(width 0.088646)
		(layer "In11.Cu")
		(net "M_D_CPU1_SA_CB<7>")
	)
	(arc
		(start 87.128096 -260.75513)
		(mid 86.845394 -260.679388)
		(end 86.562692 -260.75513)
		(width 0.088646)
		(layer "In11.Cu")
		(net "M_D_CPU1_SA_CB<7>")
	)
	(arc
		(start 93.70695 -260.75513)
		(mid 93.432721 -260.679205)
		(end 93.156278 -260.746494)
		(width 0.088646)
		(layer "In11.Cu")
		(net "M_D_CPU1_SA_CB<7>")
	)
	(arc
		(start 95.020638 -260.75513)
		(mid 94.83344 -260.805273)
		(end 94.646242 -260.75513)
		(width 0.088646)
		(layer "In11.Cu")
		(net "M_D_CPU1_SA_CB<7>")
	)
	(arc
		(start 98.780092 -260.75513)
		(mid 98.592894 -260.805273)
		(end 98.405696 -260.75513)
		(width 0.088646)
		(layer "In11.Cu")
		(net "M_D_CPU1_SA_CB<7>")
	)
	(arc
		(start 95.960946 -260.75513)
		(mid 95.773748 -260.805273)
		(end 95.58655 -260.75513)
		(width 0.088646)
		(layer "In11.Cu")
		(net "M_D_CPU1_SA_CB<7>")
	)
	(arc
		(start 88.067896 -260.75513)
		(mid 87.785194 -260.679388)
		(end 87.502492 -260.75513)
		(width 0.088646)
		(layer "In11.Cu")
		(net "M_D_CPU1_SA_CB<7>")
	)
	(arc
		(start 96.900238 -260.75513)
		(mid 96.71304 -260.805273)
		(end 96.525842 -260.75513)
		(width 0.088646)
		(layer "In11.Cu")
		(net "M_D_CPU1_SA_CB<7>")
	)
	(arc
		(start 98.405696 -260.75513)
		(mid 98.129137 -260.679421)
		(end 97.85096 -260.749034)
		(width 0.088646)
		(layer "In11.Cu")
		(net "M_D_CPU1_SA_CB<7>")
	)
	(arc
		(start 96.525842 -260.75513)
		(mid 96.243394 -260.679515)
		(end 95.960946 -260.75513)
		(width 0.088646)
		(layer "In11.Cu")
		(net "M_D_CPU1_SA_CB<7>")
	)
	(arc
		(start 92.76715 -260.75513)
		(mid 92.490337 -260.679294)
		(end 92.211906 -260.749034)
		(width 0.088646)
		(layer "In11.Cu")
		(net "M_D_CPU1_SA_CB<7>")
	)
	(arc
		(start 94.646242 -260.75513)
		(mid 94.363794 -260.679515)
		(end 94.081346 -260.75513)
		(width 0.088646)
		(layer "In11.Cu")
		(net "M_D_CPU1_SA_CB<7>")
	)
	(arc
		(start 86.188296 -260.75513)
		(mid 85.905594 -260.679388)
		(end 85.622892 -260.75513)
		(width 0.088646)
		(layer "In11.Cu")
		(net "M_D_CPU1_SA_CB<7>")
	)
	(arc
		(start 85.248496 -260.75513)
		(mid 84.965794 -260.679388)
		(end 84.683092 -260.75513)
		(width 0.088646)
		(layer "In11.Cu")
		(net "M_D_CPU1_SA_CB<7>")
	)
	(arc
		(start 91.261946 -260.75513)
		(mid 91.074748 -260.805273)
		(end 90.88755 -260.75513)
		(width 0.088646)
		(layer "In11.Cu")
		(net "M_D_CPU1_SA_CB<7>")
	)
	(arc
		(start 84.683092 -260.75513)
		(mid 84.495894 -260.805273)
		(end 84.308696 -260.75513)
		(width 0.088646)
		(layer "In11.Cu")
		(net "M_D_CPU1_SA_CB<7>")
	)
	(arc
		(start 97.46615 -260.75513)
		(mid 97.183194 -260.679261)
		(end 96.900238 -260.75513)
		(width 0.088646)
		(layer "In11.Cu")
		(net "M_D_CPU1_SA_CB<7>")
	)
	(arc
		(start 99.34575 -260.75513)
		(mid 99.068937 -260.679294)
		(end 98.790506 -260.749034)
		(width 0.088646)
		(layer "In11.Cu")
		(net "M_D_CPU1_SA_CB<7>")
	)
	(arc
		(start 94.081346 -260.75513)
		(mid 93.894148 -260.805273)
		(end 93.70695 -260.75513)
		(width 0.088646)
		(layer "In11.Cu")
		(net "M_D_CPU1_SA_CB<7>")
	)
	(arc
		(start 90.88755 -260.75513)
		(mid 90.610737 -260.679294)
		(end 90.332306 -260.749034)
		(width 0.088646)
		(layer "In11.Cu")
		(net "M_D_CPU1_SA_CB<7>")
	)
	(arc
		(start 93.141546 -260.75513)
		(mid 92.954348 -260.805273)
		(end 92.76715 -260.75513)
		(width 0.088646)
		(layer "In11.Cu")
		(net "M_D_CPU1_SA_CB<7>")
	)
	(arc
		(start 87.502492 -260.75513)
		(mid 87.315294 -260.805273)
		(end 87.128096 -260.75513)
		(width 0.088646)
		(layer "In11.Cu")
		(net "M_D_CPU1_SA_CB<7>")
	)
	(arc
		(start 84.308696 -260.75513)
		(mid 84.17233 -260.698652)
		(end 84.025994 -260.679438)
		(width 0.088646)
		(layer "In11.Cu")
		(net "M_D_CPU1_SA_CB<7>")
	)
	(segment
		(start 17.66189 -271.835626)
		(end 17.66189 -272.161254)
		(width 0.20066)
		(layer "F.Cu")
		(net "M_D_CPU1_SA_CB<6>")
	)
	(segment
		(start 100.472494 -262.058404)
		(end 100.472748 -262.058658)
		(width 0.20066)
		(layer "F.Cu")
		(net "M_D_CPU1_SA_CB<6>")
	)
	(segment
		(start 17.66189 -272.161254)
		(end 17.829276 -272.32864)
		(width 0.20066)
		(layer "F.Cu")
		(net "M_D_CPU1_SA_CB<6>")
	)
	(segment
		(start 18.257774 -272.32864)
		(end 18.46961 -272.116804)
		(width 0.20066)
		(layer "F.Cu")
		(net "M_D_CPU1_SA_CB<6>")
	)
	(segment
		(start 18.46961 -272.116804)
		(end 19.784314 -272.116804)
		(width 0.20066)
		(layer "F.Cu")
		(net "M_D_CPU1_SA_CB<6>")
	)
	(segment
		(start 17.829276 -272.32864)
		(end 18.257774 -272.32864)
		(width 0.20066)
		(layer "F.Cu")
		(net "M_D_CPU1_SA_CB<6>")
	)
	(segment
		(start 14.825218 -271.691862)
		(end 16.885158 -271.691862)
		(width 0.1016)
		(layer "F.Cu")
		(net "M_D_CPU1_SA_CB<6>")
	)
	(segment
		(start 14.560042 -271.681702)
		(end 14.570202 -271.691862)
		(width 0.101854)
		(layer "F.Cu")
		(net "M_D_CPU1_SA_CB<6>")
	)
	(segment
		(start 13.387578 -272.116804)
		(end 13.82268 -271.681702)
		(width 0.20066)
		(layer "F.Cu")
		(net "M_D_CPU1_SA_CB<6>")
	)
	(segment
		(start 16.885158 -271.691862)
		(end 17.518126 -271.691862)
		(width 0.20066)
		(layer "F.Cu")
		(net "M_D_CPU1_SA_CB<6>")
	)
	(segment
		(start 12.240514 -272.116804)
		(end 13.387578 -272.116804)
		(width 0.20066)
		(layer "F.Cu")
		(net "M_D_CPU1_SA_CB<6>")
	)
	(segment
		(start 13.82268 -271.681702)
		(end 14.560042 -271.681702)
		(width 0.20066)
		(layer "F.Cu")
		(net "M_D_CPU1_SA_CB<6>")
	)
	(segment
		(start 14.570202 -271.691862)
		(end 14.825218 -271.691862)
		(width 0.101854)
		(layer "F.Cu")
		(net "M_D_CPU1_SA_CB<6>")
	)
	(segment
		(start 17.518126 -271.691862)
		(end 17.66189 -271.835626)
		(width 0.20066)
		(layer "F.Cu")
		(net "M_D_CPU1_SA_CB<6>")
	)
	(segment
		(start 20.889214 -272.116804)
		(end 19.784314 -272.116804)
		(width 0.20066)
		(layer "F.Cu")
		(net "M_D_CPU1_SA_CB<6>")
	)
	(segment
		(start 100.472494 -261.522718)
		(end 100.472494 -262.058404)
		(width 0.20066)
		(layer "F.Cu")
		(net "M_D_CPU1_SA_CB<6>")
	)
	(segment
		(start 69.052186 -267.053314)
		(end 68.800472 -266.948666)
		(width 0.18288)
		(layer "In11.Cu")
		(net "M_D_CPU1_SA_CB<6>")
	)
	(segment
		(start 96.995996 -261.5692)
		(end 96.981264 -261.560564)
		(width 0.088646)
		(layer "In11.Cu")
		(net "M_D_CPU1_SA_CB<6>")
	)
	(segment
		(start 74.60107 -261.72795)
		(end 70.56628 -265.76274)
		(width 0.18288)
		(layer "In11.Cu")
		(net "M_D_CPU1_SA_CB<6>")
	)
	(segment
		(start 29.634434 -269.804134)
		(end 28.667964 -270.770604)
		(width 0.18288)
		(layer "In11.Cu")
		(net "M_D_CPU1_SA_CB<6>")
	)
	(segment
		(start 88.912192 -261.568946)
		(end 88.912192 -261.5692)
		(width 0.088646)
		(layer "In11.Cu")
		(net "M_D_CPU1_SA_CB<6>")
	)
	(segment
		(start 47.720758 -269.992348)
		(end 46.615096 -269.992348)
		(width 0.18288)
		(layer "In11.Cu")
		(net "M_D_CPU1_SA_CB<6>")
	)
	(segment
		(start 51.61026 -269.18666)
		(end 51.439826 -269.016226)
		(width 0.18288)
		(layer "In11.Cu")
		(net "M_D_CPU1_SA_CB<6>")
	)
	(segment
		(start 41.104566 -270.083026)
		(end 40.78605 -269.76451)
		(width 0.18288)
		(layer "In11.Cu")
		(net "M_D_CPU1_SA_CB<6>")
	)
	(segment
		(start 42.641774 -269.35684)
		(end 42.326814 -269.35684)
		(width 0.18288)
		(layer "In11.Cu")
		(net "M_D_CPU1_SA_CB<6>")
	)
	(segment
		(start 34.905696 -269.99438)
		(end 31.660592 -269.99438)
		(width 0.18288)
		(layer "In11.Cu")
		(net "M_D_CPU1_SA_CB<6>")
	)
	(segment
		(start 67.935856 -266.188698)
		(end 67.831208 -266.44092)
		(width 0.18288)
		(layer "In11.Cu")
		(net "M_D_CPU1_SA_CB<6>")
	)
	(segment
		(start 38.37051 -269.76451)
		(end 37.952426 -269.346426)
		(width 0.18288)
		(layer "In11.Cu")
		(net "M_D_CPU1_SA_CB<6>")
	)
	(segment
		(start 92.296996 -261.5692)
		(end 92.282264 -261.560564)
		(width 0.088646)
		(layer "In11.Cu")
		(net "M_D_CPU1_SA_CB<6>")
	)
	(segment
		(start 83.01355 -261.72795)
		(end 74.60107 -261.72795)
		(width 0.18288)
		(layer "In11.Cu")
		(net "M_D_CPU1_SA_CB<6>")
	)
	(segment
		(start 45.52315 -269.992348)
		(end 45.385228 -269.854426)
		(width 0.18288)
		(layer "In11.Cu")
		(net "M_D_CPU1_SA_CB<6>")
	)
	(segment
		(start 49.824386 -270.06931)
		(end 48.405796 -270.06931)
		(width 0.18288)
		(layer "In11.Cu")
		(net "M_D_CPU1_SA_CB<6>")
	)
	(segment
		(start 62.610238 -269.141702)
		(end 60.78855 -269.141702)
		(width 0.18288)
		(layer "In11.Cu")
		(net "M_D_CPU1_SA_CB<6>")
	)
	(segment
		(start 48.188626 -269.85214)
		(end 47.860966 -269.85214)
		(width 0.18288)
		(layer "In11.Cu")
		(net "M_D_CPU1_SA_CB<6>")
	)
	(segment
		(start 67.885564 -267.790168)
		(end 67.578478 -267.66266)
		(width 0.18288)
		(layer "In11.Cu")
		(net "M_D_CPU1_SA_CB<6>")
	)
	(segment
		(start 69.126608 -265.903964)
		(end 69.448172 -266.680188)
		(width 0.18288)
		(layer "In11.Cu")
		(net "M_D_CPU1_SA_CB<6>")
	)
	(segment
		(start 89.488518 -261.575296)
		(end 89.477596 -261.568946)
		(width 0.088646)
		(layer "In11.Cu")
		(net "M_D_CPU1_SA_CB<6>")
	)
	(segment
		(start 42.834814 -269.889986)
		(end 42.834814 -269.54988)
		(width 0.18288)
		(layer "In11.Cu")
		(net "M_D_CPU1_SA_CB<6>")
	)
	(segment
		(start 64.259714 -268.602206)
		(end 63.149734 -268.602206)
		(width 0.18288)
		(layer "In11.Cu")
		(net "M_D_CPU1_SA_CB<6>")
	)
	(segment
		(start 65.417446 -268.229842)
		(end 65.194434 -268.452854)
		(width 0.18288)
		(layer "In11.Cu")
		(net "M_D_CPU1_SA_CB<6>")
	)
	(segment
		(start 43.027854 -270.083026)
		(end 42.834814 -269.889986)
		(width 0.18288)
		(layer "In11.Cu")
		(net "M_D_CPU1_SA_CB<6>")
	)
	(segment
		(start 89.477596 -261.568946)
		(end 89.462864 -261.56031)
		(width 0.088646)
		(layer "In11.Cu")
		(net "M_D_CPU1_SA_CB<6>")
	)
	(segment
		(start 69.522594 -265.530838)
		(end 69.231256 -265.651742)
		(width 0.18288)
		(layer "In11.Cu")
		(net "M_D_CPU1_SA_CB<6>")
	)
	(segment
		(start 60.720478 -269.209774)
		(end 59.253374 -269.209774)
		(width 0.18288)
		(layer "In11.Cu")
		(net "M_D_CPU1_SA_CB<6>")
	)
	(segment
		(start 41.940734 -270.083026)
		(end 41.104566 -270.083026)
		(width 0.18288)
		(layer "In11.Cu")
		(net "M_D_CPU1_SA_CB<6>")
	)
	(segment
		(start 31.660592 -269.99438)
		(end 31.470346 -269.804134)
		(width 0.18288)
		(layer "In11.Cu")
		(net "M_D_CPU1_SA_CB<6>")
	)
	(segment
		(start 67.831208 -266.44092)
		(end 68.24218 -267.433044)
		(width 0.18288)
		(layer "In11.Cu")
		(net "M_D_CPU1_SA_CB<6>")
	)
	(segment
		(start 66.556128 -267.4239)
		(end 65.43802 -267.4239)
		(width 0.18288)
		(layer "In11.Cu")
		(net "M_D_CPU1_SA_CB<6>")
	)
	(segment
		(start 67.578478 -267.66266)
		(end 67.41795 -267.275818)
		(width 0.18288)
		(layer "In11.Cu")
		(net "M_D_CPU1_SA_CB<6>")
	)
	(segment
		(start 35.757612 -269.142464)
		(end 34.905696 -269.99438)
		(width 0.18288)
		(layer "In11.Cu")
		(net "M_D_CPU1_SA_CB<6>")
	)
	(segment
		(start 69.448172 -266.680188)
		(end 69.343524 -266.93241)
		(width 0.18288)
		(layer "In11.Cu")
		(net "M_D_CPU1_SA_CB<6>")
	)
	(segment
		(start 68.24218 -267.433044)
		(end 68.137786 -267.68552)
		(width 0.18288)
		(layer "In11.Cu")
		(net "M_D_CPU1_SA_CB<6>")
	)
	(segment
		(start 68.800472 -266.948666)
		(end 68.478908 -266.172442)
		(width 0.18288)
		(layer "In11.Cu")
		(net "M_D_CPU1_SA_CB<6>")
	)
	(segment
		(start 84.025994 -261.619746)
		(end 83.308444 -261.619746)
		(width 0.088646)
		(layer "In11.Cu")
		(net "M_D_CPU1_SA_CB<6>")
	)
	(segment
		(start 37.952426 -269.346426)
		(end 36.810188 -269.346426)
		(width 0.18288)
		(layer "In11.Cu")
		(net "M_D_CPU1_SA_CB<6>")
	)
	(segment
		(start 70.56628 -265.76274)
		(end 70.113398 -265.949938)
		(width 0.18288)
		(layer "In11.Cu")
		(net "M_D_CPU1_SA_CB<6>")
	)
	(segment
		(start 65.43802 -267.4239)
		(end 65.297558 -267.564362)
		(width 0.18288)
		(layer "In11.Cu")
		(net "M_D_CPU1_SA_CB<6>")
	)
	(segment
		(start 45.619416 -269.992348)
		(end 45.52315 -269.992348)
		(width 0.18288)
		(layer "In11.Cu")
		(net "M_D_CPU1_SA_CB<6>")
	)
	(segment
		(start 53.548026 -269.803626)
		(end 52.93106 -269.18666)
		(width 0.18288)
		(layer "In11.Cu")
		(net "M_D_CPU1_SA_CB<6>")
	)
	(segment
		(start 65.194434 -268.452854)
		(end 64.921638 -268.452854)
		(width 0.18288)
		(layer "In11.Cu")
		(net "M_D_CPU1_SA_CB<6>")
	)
	(segment
		(start 68.227194 -266.067794)
		(end 67.935856 -266.188698)
		(width 0.18288)
		(layer "In11.Cu")
		(net "M_D_CPU1_SA_CB<6>")
	)
	(segment
		(start 42.326814 -269.35684)
		(end 42.133774 -269.54988)
		(width 0.18288)
		(layer "In11.Cu")
		(net "M_D_CPU1_SA_CB<6>")
	)
	(segment
		(start 65.297558 -267.564362)
		(end 65.297558 -267.837158)
		(width 0.18288)
		(layer "In11.Cu")
		(net "M_D_CPU1_SA_CB<6>")
	)
	(segment
		(start 42.133774 -269.54988)
		(end 42.133774 -269.889986)
		(width 0.18288)
		(layer "In11.Cu")
		(net "M_D_CPU1_SA_CB<6>")
	)
	(segment
		(start 25.657048 -270.770604)
		(end 24.827738 -271.599914)
		(width 0.18288)
		(layer "In11.Cu")
		(net "M_D_CPU1_SA_CB<6>")
	)
	(segment
		(start 99.425506 -261.624826)
		(end 98.032062 -261.624826)
		(width 0.088646)
		(layer "In11.Cu")
		(net "M_D_CPU1_SA_CB<6>")
	)
	(segment
		(start 59.253374 -269.209774)
		(end 59.079384 -269.035784)
		(width 0.18288)
		(layer "In11.Cu")
		(net "M_D_CPU1_SA_CB<6>")
	)
	(segment
		(start 36.810188 -269.346426)
		(end 36.606226 -269.142464)
		(width 0.18288)
		(layer "In11.Cu")
		(net "M_D_CPU1_SA_CB<6>")
	)
	(segment
		(start 65.417446 -267.957046)
		(end 65.417446 -268.229842)
		(width 0.18288)
		(layer "In11.Cu")
		(net "M_D_CPU1_SA_CB<6>")
	)
	(segment
		(start 52.93106 -269.18666)
		(end 51.61026 -269.18666)
		(width 0.18288)
		(layer "In11.Cu")
		(net "M_D_CPU1_SA_CB<6>")
	)
	(segment
		(start 63.149734 -268.602206)
		(end 62.610238 -269.141702)
		(width 0.18288)
		(layer "In11.Cu")
		(net "M_D_CPU1_SA_CB<6>")
	)
	(segment
		(start 70.113398 -265.949938)
		(end 69.86143 -265.84529)
		(width 0.18288)
		(layer "In11.Cu")
		(net "M_D_CPU1_SA_CB<6>")
	)
	(segment
		(start 67.41795 -267.275818)
		(end 67.165982 -267.17117)
		(width 0.18288)
		(layer "In11.Cu")
		(net "M_D_CPU1_SA_CB<6>")
	)
	(segment
		(start 43.972226 -270.083026)
		(end 43.027854 -270.083026)
		(width 0.18288)
		(layer "In11.Cu")
		(net "M_D_CPU1_SA_CB<6>")
	)
	(segment
		(start 48.405796 -270.06931)
		(end 48.188626 -269.85214)
		(width 0.18288)
		(layer "In11.Cu")
		(net "M_D_CPU1_SA_CB<6>")
	)
	(segment
		(start 40.78605 -269.76451)
		(end 38.37051 -269.76451)
		(width 0.18288)
		(layer "In11.Cu")
		(net "M_D_CPU1_SA_CB<6>")
	)
	(segment
		(start 65.297558 -267.837158)
		(end 65.417446 -267.957046)
		(width 0.18288)
		(layer "In11.Cu")
		(net "M_D_CPU1_SA_CB<6>")
	)
	(segment
		(start 98.032062 -261.624826)
		(end 97.935796 -261.5692)
		(width 0.088646)
		(layer "In11.Cu")
		(net "M_D_CPU1_SA_CB<6>")
	)
	(segment
		(start 83.20024 -261.72795)
		(end 83.01355 -261.72795)
		(width 0.088646)
		(layer "In11.Cu")
		(net "M_D_CPU1_SA_CB<6>")
	)
	(segment
		(start 31.470346 -269.804134)
		(end 29.634434 -269.804134)
		(width 0.18288)
		(layer "In11.Cu")
		(net "M_D_CPU1_SA_CB<6>")
	)
	(segment
		(start 68.137786 -267.68552)
		(end 67.885564 -267.790168)
		(width 0.18288)
		(layer "In11.Cu")
		(net "M_D_CPU1_SA_CB<6>")
	)
	(segment
		(start 42.834814 -269.54988)
		(end 42.641774 -269.35684)
		(width 0.18288)
		(layer "In11.Cu")
		(net "M_D_CPU1_SA_CB<6>")
	)
	(segment
		(start 94.176596 -261.5692)
		(end 94.161864 -261.560564)
		(width 0.088646)
		(layer "In11.Cu")
		(net "M_D_CPU1_SA_CB<6>")
	)
	(segment
		(start 46.312836 -270.294608)
		(end 45.921676 -270.294608)
		(width 0.18288)
		(layer "In11.Cu")
		(net "M_D_CPU1_SA_CB<6>")
	)
	(segment
		(start 46.615096 -269.992348)
		(end 46.312836 -270.294608)
		(width 0.18288)
		(layer "In11.Cu")
		(net "M_D_CPU1_SA_CB<6>")
	)
	(segment
		(start 69.774308 -265.635486)
		(end 69.522594 -265.530838)
		(width 0.18288)
		(layer "In11.Cu")
		(net "M_D_CPU1_SA_CB<6>")
	)
	(segment
		(start 83.308444 -261.619746)
		(end 83.20024 -261.72795)
		(width 0.088646)
		(layer "In11.Cu")
		(net "M_D_CPU1_SA_CB<6>")
	)
	(segment
		(start 51.439826 -269.016226)
		(end 50.87747 -269.016226)
		(width 0.18288)
		(layer "In11.Cu")
		(net "M_D_CPU1_SA_CB<6>")
	)
	(segment
		(start 24.827738 -271.599914)
		(end 23.772114 -271.599914)
		(width 0.18288)
		(layer "In11.Cu")
		(net "M_D_CPU1_SA_CB<6>")
	)
	(segment
		(start 59.079384 -269.035784)
		(end 55.992268 -269.035784)
		(width 0.18288)
		(layer "In11.Cu")
		(net "M_D_CPU1_SA_CB<6>")
	)
	(segment
		(start 36.606226 -269.142464)
		(end 35.757612 -269.142464)
		(width 0.18288)
		(layer "In11.Cu")
		(net "M_D_CPU1_SA_CB<6>")
	)
	(segment
		(start 21.477224 -272.704814)
		(end 20.889214 -272.116804)
		(width 0.18288)
		(layer "In11.Cu")
		(net "M_D_CPU1_SA_CB<6>")
	)
	(segment
		(start 67.165982 -267.17117)
		(end 66.556128 -267.4239)
		(width 0.18288)
		(layer "In11.Cu")
		(net "M_D_CPU1_SA_CB<6>")
	)
	(segment
		(start 68.478908 -266.172442)
		(end 68.227194 -266.067794)
		(width 0.18288)
		(layer "In11.Cu")
		(net "M_D_CPU1_SA_CB<6>")
	)
	(segment
		(start 23.772114 -271.599914)
		(end 22.667214 -272.704814)
		(width 0.18288)
		(layer "In11.Cu")
		(net "M_D_CPU1_SA_CB<6>")
	)
	(segment
		(start 60.78855 -269.141702)
		(end 60.720478 -269.209774)
		(width 0.18288)
		(layer "In11.Cu")
		(net "M_D_CPU1_SA_CB<6>")
	)
	(segment
		(start 64.80175 -268.332966)
		(end 64.528954 -268.332966)
		(width 0.18288)
		(layer "In11.Cu")
		(net "M_D_CPU1_SA_CB<6>")
	)
	(segment
		(start 47.860966 -269.85214)
		(end 47.720758 -269.992348)
		(width 0.18288)
		(layer "In11.Cu")
		(net "M_D_CPU1_SA_CB<6>")
	)
	(segment
		(start 69.343524 -266.93241)
		(end 69.052186 -267.053314)
		(width 0.18288)
		(layer "In11.Cu")
		(net "M_D_CPU1_SA_CB<6>")
	)
	(segment
		(start 50.87747 -269.016226)
		(end 49.824386 -270.06931)
		(width 0.18288)
		(layer "In11.Cu")
		(net "M_D_CPU1_SA_CB<6>")
	)
	(segment
		(start 93.236796 -261.5692)
		(end 93.222064 -261.560564)
		(width 0.088646)
		(layer "In11.Cu")
		(net "M_D_CPU1_SA_CB<6>")
	)
	(segment
		(start 42.133774 -269.889986)
		(end 41.940734 -270.083026)
		(width 0.18288)
		(layer "In11.Cu")
		(net "M_D_CPU1_SA_CB<6>")
	)
	(segment
		(start 28.667964 -270.770604)
		(end 25.657048 -270.770604)
		(width 0.18288)
		(layer "In11.Cu")
		(net "M_D_CPU1_SA_CB<6>")
	)
	(segment
		(start 64.528954 -268.332966)
		(end 64.259714 -268.602206)
		(width 0.18288)
		(layer "In11.Cu")
		(net "M_D_CPU1_SA_CB<6>")
	)
	(segment
		(start 22.667214 -272.704814)
		(end 21.477224 -272.704814)
		(width 0.18288)
		(layer "In11.Cu")
		(net "M_D_CPU1_SA_CB<6>")
	)
	(segment
		(start 69.86143 -265.84529)
		(end 69.774308 -265.635486)
		(width 0.18288)
		(layer "In11.Cu")
		(net "M_D_CPU1_SA_CB<6>")
	)
	(segment
		(start 45.921676 -270.294608)
		(end 45.619416 -269.992348)
		(width 0.18288)
		(layer "In11.Cu")
		(net "M_D_CPU1_SA_CB<6>")
	)
	(segment
		(start 64.921638 -268.452854)
		(end 64.80175 -268.332966)
		(width 0.18288)
		(layer "In11.Cu")
		(net "M_D_CPU1_SA_CB<6>")
	)
	(segment
		(start 55.224426 -269.803626)
		(end 53.548026 -269.803626)
		(width 0.18288)
		(layer "In11.Cu")
		(net "M_D_CPU1_SA_CB<6>")
	)
	(segment
		(start 45.385228 -269.854426)
		(end 44.200826 -269.854426)
		(width 0.18288)
		(layer "In11.Cu")
		(net "M_D_CPU1_SA_CB<6>")
	)
	(segment
		(start 69.231256 -265.651742)
		(end 69.126608 -265.903964)
		(width 0.18288)
		(layer "In11.Cu")
		(net "M_D_CPU1_SA_CB<6>")
	)
	(segment
		(start 55.992268 -269.035784)
		(end 55.224426 -269.803626)
		(width 0.18288)
		(layer "In11.Cu")
		(net "M_D_CPU1_SA_CB<6>")
	)
	(segment
		(start 95.116396 -261.5692)
		(end 95.101664 -261.560564)
		(width 0.088646)
		(layer "In11.Cu")
		(net "M_D_CPU1_SA_CB<6>")
	)
	(segment
		(start 96.056196 -261.5692)
		(end 96.041464 -261.560564)
		(width 0.088646)
		(layer "In11.Cu")
		(net "M_D_CPU1_SA_CB<6>")
	)
	(segment
		(start 44.200826 -269.854426)
		(end 43.972226 -270.083026)
		(width 0.18288)
		(layer "In11.Cu")
		(net "M_D_CPU1_SA_CB<6>")
	)
	(arc
		(start 95.101664 -261.560564)
		(mid 94.825189 -261.493244)
		(end 94.550992 -261.5692)
		(width 0.088646)
		(layer "In11.Cu")
		(net "M_D_CPU1_SA_CB<6>")
	)
	(arc
		(start 100.472748 -262.058658)
		(mid 99.992269 -261.737612)
		(end 99.425506 -261.624826)
		(width 0.088646)
		(layer "In11.Cu")
		(net "M_D_CPU1_SA_CB<6>")
	)
	(arc
		(start 88.537796 -261.5692)
		(mid 88.255094 -261.493424)
		(end 87.972392 -261.5692)
		(width 0.088646)
		(layer "In11.Cu")
		(net "M_D_CPU1_SA_CB<6>")
	)
	(arc
		(start 91.731592 -261.5692)
		(mid 91.544394 -261.619343)
		(end 91.357196 -261.5692)
		(width 0.088646)
		(layer "In11.Cu")
		(net "M_D_CPU1_SA_CB<6>")
	)
	(arc
		(start 92.671392 -261.5692)
		(mid 92.484194 -261.619343)
		(end 92.296996 -261.5692)
		(width 0.088646)
		(layer "In11.Cu")
		(net "M_D_CPU1_SA_CB<6>")
	)
	(arc
		(start 84.213192 -261.5692)
		(mid 84.12292 -261.606799)
		(end 84.025994 -261.619746)
		(width 0.088646)
		(layer "In11.Cu")
		(net "M_D_CPU1_SA_CB<6>")
	)
	(arc
		(start 87.972392 -261.5692)
		(mid 87.785194 -261.619343)
		(end 87.597996 -261.5692)
		(width 0.088646)
		(layer "In11.Cu")
		(net "M_D_CPU1_SA_CB<6>")
	)
	(arc
		(start 95.490792 -261.5692)
		(mid 95.303594 -261.619343)
		(end 95.116396 -261.5692)
		(width 0.088646)
		(layer "In11.Cu")
		(net "M_D_CPU1_SA_CB<6>")
	)
	(arc
		(start 97.935796 -261.5692)
		(mid 97.653094 -261.493424)
		(end 97.370392 -261.5692)
		(width 0.088646)
		(layer "In11.Cu")
		(net "M_D_CPU1_SA_CB<6>")
	)
	(arc
		(start 96.041464 -261.560564)
		(mid 95.764989 -261.493244)
		(end 95.490792 -261.5692)
		(width 0.088646)
		(layer "In11.Cu")
		(net "M_D_CPU1_SA_CB<6>")
	)
	(arc
		(start 96.430592 -261.5692)
		(mid 96.243394 -261.619343)
		(end 96.056196 -261.5692)
		(width 0.088646)
		(layer "In11.Cu")
		(net "M_D_CPU1_SA_CB<6>")
	)
	(arc
		(start 90.791792 -261.5692)
		(mid 90.604594 -261.619343)
		(end 90.417396 -261.5692)
		(width 0.088646)
		(layer "In11.Cu")
		(net "M_D_CPU1_SA_CB<6>")
	)
	(arc
		(start 93.222064 -261.560564)
		(mid 92.945589 -261.493244)
		(end 92.671392 -261.5692)
		(width 0.088646)
		(layer "In11.Cu")
		(net "M_D_CPU1_SA_CB<6>")
	)
	(arc
		(start 94.550992 -261.5692)
		(mid 94.363794 -261.619343)
		(end 94.176596 -261.5692)
		(width 0.088646)
		(layer "In11.Cu")
		(net "M_D_CPU1_SA_CB<6>")
	)
	(arc
		(start 87.032592 -261.5692)
		(mid 86.845394 -261.619343)
		(end 86.658196 -261.5692)
		(width 0.088646)
		(layer "In11.Cu")
		(net "M_D_CPU1_SA_CB<6>")
	)
	(arc
		(start 88.912192 -261.5692)
		(mid 88.724994 -261.619343)
		(end 88.537796 -261.5692)
		(width 0.088646)
		(layer "In11.Cu")
		(net "M_D_CPU1_SA_CB<6>")
	)
	(arc
		(start 92.282264 -261.560564)
		(mid 92.005789 -261.493244)
		(end 91.731592 -261.5692)
		(width 0.088646)
		(layer "In11.Cu")
		(net "M_D_CPU1_SA_CB<6>")
	)
	(arc
		(start 93.611192 -261.5692)
		(mid 93.423994 -261.619343)
		(end 93.236796 -261.5692)
		(width 0.088646)
		(layer "In11.Cu")
		(net "M_D_CPU1_SA_CB<6>")
	)
	(arc
		(start 85.718396 -261.5692)
		(mid 85.435694 -261.493424)
		(end 85.152992 -261.5692)
		(width 0.088646)
		(layer "In11.Cu")
		(net "M_D_CPU1_SA_CB<6>")
	)
	(arc
		(start 86.658196 -261.5692)
		(mid 86.375494 -261.493424)
		(end 86.092792 -261.5692)
		(width 0.088646)
		(layer "In11.Cu")
		(net "M_D_CPU1_SA_CB<6>")
	)
	(arc
		(start 96.981264 -261.560564)
		(mid 96.704789 -261.493244)
		(end 96.430592 -261.5692)
		(width 0.088646)
		(layer "In11.Cu")
		(net "M_D_CPU1_SA_CB<6>")
	)
	(arc
		(start 94.161864 -261.560564)
		(mid 93.885389 -261.493244)
		(end 93.611192 -261.5692)
		(width 0.088646)
		(layer "In11.Cu")
		(net "M_D_CPU1_SA_CB<6>")
	)
	(arc
		(start 97.370392 -261.5692)
		(mid 97.183194 -261.619343)
		(end 96.995996 -261.5692)
		(width 0.088646)
		(layer "In11.Cu")
		(net "M_D_CPU1_SA_CB<6>")
	)
	(arc
		(start 90.417396 -261.5692)
		(mid 90.134694 -261.493424)
		(end 89.851992 -261.5692)
		(width 0.088646)
		(layer "In11.Cu")
		(net "M_D_CPU1_SA_CB<6>")
	)
	(arc
		(start 87.597996 -261.5692)
		(mid 87.315294 -261.493424)
		(end 87.032592 -261.5692)
		(width 0.088646)
		(layer "In11.Cu")
		(net "M_D_CPU1_SA_CB<6>")
	)
	(arc
		(start 85.152992 -261.5692)
		(mid 84.965794 -261.619343)
		(end 84.778596 -261.5692)
		(width 0.088646)
		(layer "In11.Cu")
		(net "M_D_CPU1_SA_CB<6>")
	)
	(arc
		(start 84.778596 -261.5692)
		(mid 84.495894 -261.493424)
		(end 84.213192 -261.5692)
		(width 0.088646)
		(layer "In11.Cu")
		(net "M_D_CPU1_SA_CB<6>")
	)
	(arc
		(start 86.092792 -261.5692)
		(mid 85.905594 -261.619343)
		(end 85.718396 -261.5692)
		(width 0.088646)
		(layer "In11.Cu")
		(net "M_D_CPU1_SA_CB<6>")
	)
	(arc
		(start 91.357196 -261.5692)
		(mid 91.074494 -261.493424)
		(end 90.791792 -261.5692)
		(width 0.088646)
		(layer "In11.Cu")
		(net "M_D_CPU1_SA_CB<6>")
	)
	(arc
		(start 89.851992 -261.5692)
		(mid 89.671048 -261.619291)
		(end 89.488518 -261.575296)
		(width 0.088646)
		(layer "In11.Cu")
		(net "M_D_CPU1_SA_CB<6>")
	)
	(arc
		(start 89.462864 -261.56031)
		(mid 89.186389 -261.49299)
		(end 88.912192 -261.568946)
		(width 0.088646)
		(layer "In11.Cu")
		(net "M_D_CPU1_SA_CB<6>")
	)
	(segment
		(start 99.063048 -261.244588)
		(end 99.062794 -261.244842)
		(width 0.20066)
		(layer "F.Cu")
		(net "M_D_CPU1_SA_CB<5>")
	)
	(segment
		(start 13.441426 -270.841724)
		(end 13.619988 -270.841724)
		(width 0.20066)
		(layer "F.Cu")
		(net "M_D_CPU1_SA_CB<5>")
	)
	(segment
		(start 13.110718 -270.841724)
		(end 13.441426 -270.841724)
		(width 0.101854)
		(layer "F.Cu")
		(net "M_D_CPU1_SA_CB<5>")
	)
	(segment
		(start 99.063048 -260.708902)
		(end 99.063048 -261.244588)
		(width 0.20066)
		(layer "F.Cu")
		(net "M_D_CPU1_SA_CB<5>")
	)
	(segment
		(start 9.686036 -271.477994)
		(end 10.19048 -271.477994)
		(width 0.20066)
		(layer "F.Cu")
		(net "M_D_CPU1_SA_CB<5>")
	)
	(segment
		(start 13.619988 -270.841724)
		(end 14.04493 -271.266666)
		(width 0.20066)
		(layer "F.Cu")
		(net "M_D_CPU1_SA_CB<5>")
	)
	(segment
		(start 10.344912 -270.995394)
		(end 10.507472 -270.832834)
		(width 0.20066)
		(layer "F.Cu")
		(net "M_D_CPU1_SA_CB<5>")
	)
	(segment
		(start 10.507472 -270.832834)
		(end 11.11631 -270.832834)
		(width 0.20066)
		(layer "F.Cu")
		(net "M_D_CPU1_SA_CB<5>")
	)
	(segment
		(start 10.344912 -271.323562)
		(end 10.344912 -270.995394)
		(width 0.20066)
		(layer "F.Cu")
		(net "M_D_CPU1_SA_CB<5>")
	)
	(segment
		(start 14.04493 -271.266666)
		(end 15.684246 -271.266666)
		(width 0.20066)
		(layer "F.Cu")
		(net "M_D_CPU1_SA_CB<5>")
	)
	(segment
		(start 8.140446 -271.266666)
		(end 9.474708 -271.266666)
		(width 0.20066)
		(layer "F.Cu")
		(net "M_D_CPU1_SA_CB<5>")
	)
	(segment
		(start 11.1252 -270.841724)
		(end 13.110718 -270.841724)
		(width 0.1016)
		(layer "F.Cu")
		(net "M_D_CPU1_SA_CB<5>")
	)
	(segment
		(start 16.789146 -271.266666)
		(end 15.684246 -271.266666)
		(width 0.20066)
		(layer "F.Cu")
		(net "M_D_CPU1_SA_CB<5>")
	)
	(segment
		(start 11.11631 -270.832834)
		(end 11.1252 -270.841724)
		(width 0.1016)
		(layer "F.Cu")
		(net "M_D_CPU1_SA_CB<5>")
	)
	(segment
		(start 9.474708 -271.266666)
		(end 9.686036 -271.477994)
		(width 0.20066)
		(layer "F.Cu")
		(net "M_D_CPU1_SA_CB<5>")
	)
	(segment
		(start 10.19048 -271.477994)
		(end 10.344912 -271.323562)
		(width 0.20066)
		(layer "F.Cu")
		(net "M_D_CPU1_SA_CB<5>")
	)
	(segment
		(start 41.229026 -268.838426)
		(end 40.860726 -269.206726)
		(width 0.18288)
		(layer "In11.Cu")
		(net "M_D_CPU1_SA_CB<5>")
	)
	(segment
		(start 18.379948 -272.518886)
		(end 18.064988 -272.518886)
		(width 0.18288)
		(layer "In11.Cu")
		(net "M_D_CPU1_SA_CB<5>")
	)
	(segment
		(start 30.543246 -269.288006)
		(end 29.399992 -269.288006)
		(width 0.18288)
		(layer "In11.Cu")
		(net "M_D_CPU1_SA_CB<5>")
	)
	(segment
		(start 50.824638 -268.330426)
		(end 50.265838 -268.889226)
		(width 0.18288)
		(layer "In11.Cu")
		(net "M_D_CPU1_SA_CB<5>")
	)
	(segment
		(start 66.251074 -266.791694)
		(end 65.094104 -266.791694)
		(width 0.18288)
		(layer "In11.Cu")
		(net "M_D_CPU1_SA_CB<5>")
	)
	(segment
		(start 94.565724 -260.92912)
		(end 94.550992 -260.920484)
		(width 0.088646)
		(layer "In11.Cu")
		(net "M_D_CPU1_SA_CB<5>")
	)
	(segment
		(start 62.80785 -268.152626)
		(end 61.174122 -268.152626)
		(width 0.18288)
		(layer "In11.Cu")
		(net "M_D_CPU1_SA_CB<5>")
	)
	(segment
		(start 63.56985 -267.390626)
		(end 62.80785 -268.152626)
		(width 0.18288)
		(layer "In11.Cu")
		(net "M_D_CPU1_SA_CB<5>")
	)
	(segment
		(start 48.620426 -268.889226)
		(end 48.367442 -269.14221)
		(width 0.18288)
		(layer "In11.Cu")
		(net "M_D_CPU1_SA_CB<5>")
	)
	(segment
		(start 20.168108 -271.69237)
		(end 19.975068 -271.88541)
		(width 0.18288)
		(layer "In11.Cu")
		(net "M_D_CPU1_SA_CB<5>")
	)
	(segment
		(start 30.691328 -269.139924)
		(end 30.543246 -269.288006)
		(width 0.18288)
		(layer "In11.Cu")
		(net "M_D_CPU1_SA_CB<5>")
	)
	(segment
		(start 18.766028 -271.69237)
		(end 18.572988 -271.88541)
		(width 0.18288)
		(layer "In11.Cu")
		(net "M_D_CPU1_SA_CB<5>")
	)
	(segment
		(start 40.860726 -269.206726)
		(end 38.625526 -269.206726)
		(width 0.18288)
		(layer "In11.Cu")
		(net "M_D_CPU1_SA_CB<5>")
	)
	(segment
		(start 59.186826 -268.482826)
		(end 55.707026 -268.482826)
		(width 0.18288)
		(layer "In11.Cu")
		(net "M_D_CPU1_SA_CB<5>")
	)
	(segment
		(start 59.517026 -268.152626)
		(end 59.186826 -268.482826)
		(width 0.18288)
		(layer "In11.Cu")
		(net "M_D_CPU1_SA_CB<5>")
	)
	(segment
		(start 17.678908 -271.69237)
		(end 17.21485 -271.69237)
		(width 0.18288)
		(layer "In11.Cu")
		(net "M_D_CPU1_SA_CB<5>")
	)
	(segment
		(start 23.645622 -270.994886)
		(end 23.135082 -271.505426)
		(width 0.18288)
		(layer "In11.Cu")
		(net "M_D_CPU1_SA_CB<5>")
	)
	(segment
		(start 19.975068 -272.325846)
		(end 19.782028 -272.518886)
		(width 0.18288)
		(layer "In11.Cu")
		(net "M_D_CPU1_SA_CB<5>")
	)
	(segment
		(start 17.21485 -271.69237)
		(end 16.789146 -271.266666)
		(width 0.18288)
		(layer "In11.Cu")
		(net "M_D_CPU1_SA_CB<5>")
	)
	(segment
		(start 71.518018 -264.092436)
		(end 67.13474 -265.908028)
		(width 0.18288)
		(layer "In11.Cu")
		(net "M_D_CPU1_SA_CB<5>")
	)
	(segment
		(start 18.572988 -272.325846)
		(end 18.379948 -272.518886)
		(width 0.18288)
		(layer "In11.Cu")
		(net "M_D_CPU1_SA_CB<5>")
	)
	(segment
		(start 25.381458 -270.227806)
		(end 24.614378 -270.994886)
		(width 0.18288)
		(layer "In11.Cu")
		(net "M_D_CPU1_SA_CB<5>")
	)
	(segment
		(start 29.399992 -269.288006)
		(end 28.460192 -270.227806)
		(width 0.18288)
		(layer "In11.Cu")
		(net "M_D_CPU1_SA_CB<5>")
	)
	(segment
		(start 51.719226 -268.330426)
		(end 50.824638 -268.330426)
		(width 0.18288)
		(layer "In11.Cu")
		(net "M_D_CPU1_SA_CB<5>")
	)
	(segment
		(start 96.445324 -260.92912)
		(end 96.430592 -260.920484)
		(width 0.088646)
		(layer "In11.Cu")
		(net "M_D_CPU1_SA_CB<5>")
	)
	(segment
		(start 37.596826 -268.178026)
		(end 36.936426 -268.178026)
		(width 0.18288)
		(layer "In11.Cu")
		(net "M_D_CPU1_SA_CB<5>")
	)
	(segment
		(start 97.935796 -260.920484)
		(end 97.921064 -260.92912)
		(width 0.088646)
		(layer "In11.Cu")
		(net "M_D_CPU1_SA_CB<5>")
	)
	(segment
		(start 28.460192 -270.227806)
		(end 25.381458 -270.227806)
		(width 0.18288)
		(layer "In11.Cu")
		(net "M_D_CPU1_SA_CB<5>")
	)
	(segment
		(start 50.265838 -268.889226)
		(end 48.620426 -268.889226)
		(width 0.18288)
		(layer "In11.Cu")
		(net "M_D_CPU1_SA_CB<5>")
	)
	(segment
		(start 17.871948 -272.325846)
		(end 17.871948 -271.88541)
		(width 0.18288)
		(layer "In11.Cu")
		(net "M_D_CPU1_SA_CB<5>")
	)
	(segment
		(start 74.390504 -261.21995)
		(end 71.518018 -264.092436)
		(width 0.18288)
		(layer "In11.Cu")
		(net "M_D_CPU1_SA_CB<5>")
	)
	(segment
		(start 19.975068 -271.88541)
		(end 19.975068 -272.325846)
		(width 0.18288)
		(layer "In11.Cu")
		(net "M_D_CPU1_SA_CB<5>")
	)
	(segment
		(start 19.467068 -272.518886)
		(end 19.274028 -272.325846)
		(width 0.18288)
		(layer "In11.Cu")
		(net "M_D_CPU1_SA_CB<5>")
	)
	(segment
		(start 60.480702 -268.413738)
		(end 60.21959 -268.152626)
		(width 0.18288)
		(layer "In11.Cu")
		(net "M_D_CPU1_SA_CB<5>")
	)
	(segment
		(start 96.056196 -260.920484)
		(end 96.041464 -260.92912)
		(width 0.088646)
		(layer "In11.Cu")
		(net "M_D_CPU1_SA_CB<5>")
	)
	(segment
		(start 99.062794 -261.244842)
		(end 99.375468 -261.244842)
		(width 0.088646)
		(layer "In11.Cu")
		(net "M_D_CPU1_SA_CB<5>")
	)
	(segment
		(start 89.477596 -260.920484)
		(end 89.462864 -260.92912)
		(width 0.088646)
		(layer "In11.Cu")
		(net "M_D_CPU1_SA_CB<5>")
	)
	(segment
		(start 55.707026 -268.482826)
		(end 54.945026 -269.244826)
		(width 0.18288)
		(layer "In11.Cu")
		(net "M_D_CPU1_SA_CB<5>")
	)
	(segment
		(start 21.34743 -271.505426)
		(end 21.160486 -271.69237)
		(width 0.18288)
		(layer "In11.Cu")
		(net "M_D_CPU1_SA_CB<5>")
	)
	(segment
		(start 60.21959 -268.152626)
		(end 59.517026 -268.152626)
		(width 0.18288)
		(layer "In11.Cu")
		(net "M_D_CPU1_SA_CB<5>")
	)
	(segment
		(start 64.495172 -267.390626)
		(end 63.56985 -267.390626)
		(width 0.18288)
		(layer "In11.Cu")
		(net "M_D_CPU1_SA_CB<5>")
	)
	(segment
		(start 93.236796 -260.920484)
		(end 93.222064 -260.92912)
		(width 0.088646)
		(layer "In11.Cu")
		(net "M_D_CPU1_SA_CB<5>")
	)
	(segment
		(start 34.946844 -269.139924)
		(end 30.691328 -269.139924)
		(width 0.18288)
		(layer "In11.Cu")
		(net "M_D_CPU1_SA_CB<5>")
	)
	(segment
		(start 99.375468 -261.244842)
		(end 99.432872 -261.187438)
		(width 0.088646)
		(layer "In11.Cu")
		(net "M_D_CPU1_SA_CB<5>")
	)
	(segment
		(start 17.871948 -271.88541)
		(end 17.678908 -271.69237)
		(width 0.18288)
		(layer "In11.Cu")
		(net "M_D_CPU1_SA_CB<5>")
	)
	(segment
		(start 54.945026 -269.244826)
		(end 53.827426 -269.244826)
		(width 0.18288)
		(layer "In11.Cu")
		(net "M_D_CPU1_SA_CB<5>")
	)
	(segment
		(start 18.064988 -272.518886)
		(end 17.871948 -272.325846)
		(width 0.18288)
		(layer "In11.Cu")
		(net "M_D_CPU1_SA_CB<5>")
	)
	(segment
		(start 83.420966 -261.21995)
		(end 83.01355 -261.21995)
		(width 0.088646)
		(layer "In11.Cu")
		(net "M_D_CPU1_SA_CB<5>")
	)
	(segment
		(start 36.822126 -268.292326)
		(end 35.794442 -268.292326)
		(width 0.18288)
		(layer "In11.Cu")
		(net "M_D_CPU1_SA_CB<5>")
	)
	(segment
		(start 83.01355 -261.21995)
		(end 74.390504 -261.21995)
		(width 0.18288)
		(layer "In11.Cu")
		(net "M_D_CPU1_SA_CB<5>")
	)
	(segment
		(start 51.83251 -268.217142)
		(end 51.719226 -268.330426)
		(width 0.18288)
		(layer "In11.Cu")
		(net "M_D_CPU1_SA_CB<5>")
	)
	(segment
		(start 38.625526 -269.206726)
		(end 37.596826 -268.178026)
		(width 0.18288)
		(layer "In11.Cu")
		(net "M_D_CPU1_SA_CB<5>")
	)
	(segment
		(start 67.13474 -265.908028)
		(end 66.251074 -266.791694)
		(width 0.18288)
		(layer "In11.Cu")
		(net "M_D_CPU1_SA_CB<5>")
	)
	(segment
		(start 19.782028 -272.518886)
		(end 19.467068 -272.518886)
		(width 0.18288)
		(layer "In11.Cu")
		(net "M_D_CPU1_SA_CB<5>")
	)
	(segment
		(start 99.258882 -260.925564)
		(end 99.249992 -260.920484)
		(width 0.088646)
		(layer "In11.Cu")
		(net "M_D_CPU1_SA_CB<5>")
	)
	(segment
		(start 35.794442 -268.292326)
		(end 34.946844 -269.139924)
		(width 0.18288)
		(layer "In11.Cu")
		(net "M_D_CPU1_SA_CB<5>")
	)
	(segment
		(start 24.614378 -270.994886)
		(end 23.645622 -270.994886)
		(width 0.18288)
		(layer "In11.Cu")
		(net "M_D_CPU1_SA_CB<5>")
	)
	(segment
		(start 45.369226 -269.346426)
		(end 44.603162 -269.346426)
		(width 0.18288)
		(layer "In11.Cu")
		(net "M_D_CPU1_SA_CB<5>")
	)
	(segment
		(start 60.91301 -268.413738)
		(end 60.480702 -268.413738)
		(width 0.18288)
		(layer "In11.Cu")
		(net "M_D_CPU1_SA_CB<5>")
	)
	(segment
		(start 84.025994 -260.869684)
		(end 83.771232 -260.869684)
		(width 0.088646)
		(layer "In11.Cu")
		(net "M_D_CPU1_SA_CB<5>")
	)
	(segment
		(start 61.174122 -268.152626)
		(end 60.91301 -268.413738)
		(width 0.18288)
		(layer "In11.Cu")
		(net "M_D_CPU1_SA_CB<5>")
	)
	(segment
		(start 45.573442 -269.14221)
		(end 45.369226 -269.346426)
		(width 0.18288)
		(layer "In11.Cu")
		(net "M_D_CPU1_SA_CB<5>")
	)
	(segment
		(start 44.603162 -269.346426)
		(end 44.095162 -268.838426)
		(width 0.18288)
		(layer "In11.Cu")
		(net "M_D_CPU1_SA_CB<5>")
	)
	(segment
		(start 18.572988 -271.88541)
		(end 18.572988 -272.325846)
		(width 0.18288)
		(layer "In11.Cu")
		(net "M_D_CPU1_SA_CB<5>")
	)
	(segment
		(start 83.771232 -260.869684)
		(end 83.420966 -261.21995)
		(width 0.088646)
		(layer "In11.Cu")
		(net "M_D_CPU1_SA_CB<5>")
	)
	(segment
		(start 53.827426 -269.244826)
		(end 52.799742 -268.217142)
		(width 0.18288)
		(layer "In11.Cu")
		(net "M_D_CPU1_SA_CB<5>")
	)
	(segment
		(start 65.094104 -266.791694)
		(end 64.495172 -267.390626)
		(width 0.18288)
		(layer "In11.Cu")
		(net "M_D_CPU1_SA_CB<5>")
	)
	(segment
		(start 19.274028 -272.325846)
		(end 19.274028 -271.88541)
		(width 0.18288)
		(layer "In11.Cu")
		(net "M_D_CPU1_SA_CB<5>")
	)
	(segment
		(start 23.135082 -271.505426)
		(end 21.34743 -271.505426)
		(width 0.18288)
		(layer "In11.Cu")
		(net "M_D_CPU1_SA_CB<5>")
	)
	(segment
		(start 48.367442 -269.14221)
		(end 45.573442 -269.14221)
		(width 0.18288)
		(layer "In11.Cu")
		(net "M_D_CPU1_SA_CB<5>")
	)
	(segment
		(start 52.799742 -268.217142)
		(end 51.83251 -268.217142)
		(width 0.18288)
		(layer "In11.Cu")
		(net "M_D_CPU1_SA_CB<5>")
	)
	(segment
		(start 19.080988 -271.69237)
		(end 18.766028 -271.69237)
		(width 0.18288)
		(layer "In11.Cu")
		(net "M_D_CPU1_SA_CB<5>")
	)
	(segment
		(start 21.160486 -271.69237)
		(end 20.168108 -271.69237)
		(width 0.18288)
		(layer "In11.Cu")
		(net "M_D_CPU1_SA_CB<5>")
	)
	(segment
		(start 91.357196 -260.920484)
		(end 91.342464 -260.92912)
		(width 0.088646)
		(layer "In11.Cu")
		(net "M_D_CPU1_SA_CB<5>")
	)
	(segment
		(start 19.274028 -271.88541)
		(end 19.080988 -271.69237)
		(width 0.18288)
		(layer "In11.Cu")
		(net "M_D_CPU1_SA_CB<5>")
	)
	(segment
		(start 44.095162 -268.838426)
		(end 41.229026 -268.838426)
		(width 0.18288)
		(layer "In11.Cu")
		(net "M_D_CPU1_SA_CB<5>")
	)
	(segment
		(start 36.936426 -268.178026)
		(end 36.822126 -268.292326)
		(width 0.18288)
		(layer "In11.Cu")
		(net "M_D_CPU1_SA_CB<5>")
	)
	(segment
		(start 94.176596 -260.920484)
		(end 94.161864 -260.92912)
		(width 0.088646)
		(layer "In11.Cu")
		(net "M_D_CPU1_SA_CB<5>")
	)
	(arc
		(start 98.310192 -260.920484)
		(mid 98.122994 -260.870341)
		(end 97.935796 -260.920484)
		(width 0.088646)
		(layer "In11.Cu")
		(net "M_D_CPU1_SA_CB<5>")
	)
	(arc
		(start 87.032592 -260.920484)
		(mid 86.845394 -260.870341)
		(end 86.658196 -260.920484)
		(width 0.088646)
		(layer "In11.Cu")
		(net "M_D_CPU1_SA_CB<5>")
	)
	(arc
		(start 95.490792 -260.920484)
		(mid 95.303594 -260.870341)
		(end 95.116396 -260.920484)
		(width 0.088646)
		(layer "In11.Cu")
		(net "M_D_CPU1_SA_CB<5>")
	)
	(arc
		(start 97.370392 -260.920484)
		(mid 97.183194 -260.870341)
		(end 96.995996 -260.920484)
		(width 0.088646)
		(layer "In11.Cu")
		(net "M_D_CPU1_SA_CB<5>")
	)
	(arc
		(start 91.342464 -260.92912)
		(mid 91.066023 -260.996286)
		(end 90.791792 -260.920484)
		(width 0.088646)
		(layer "In11.Cu")
		(net "M_D_CPU1_SA_CB<5>")
	)
	(arc
		(start 90.791792 -260.920484)
		(mid 90.604594 -260.870341)
		(end 90.417396 -260.920484)
		(width 0.088646)
		(layer "In11.Cu")
		(net "M_D_CPU1_SA_CB<5>")
	)
	(arc
		(start 96.430592 -260.920484)
		(mid 96.243394 -260.870341)
		(end 96.056196 -260.920484)
		(width 0.088646)
		(layer "In11.Cu")
		(net "M_D_CPU1_SA_CB<5>")
	)
	(arc
		(start 98.875596 -260.920484)
		(mid 98.592894 -260.996226)
		(end 98.310192 -260.920484)
		(width 0.088646)
		(layer "In11.Cu")
		(net "M_D_CPU1_SA_CB<5>")
	)
	(arc
		(start 88.912192 -260.920484)
		(mid 88.724994 -260.870341)
		(end 88.537796 -260.920484)
		(width 0.088646)
		(layer "In11.Cu")
		(net "M_D_CPU1_SA_CB<5>")
	)
	(arc
		(start 84.213192 -260.920484)
		(mid 84.122936 -260.882762)
		(end 84.025994 -260.869684)
		(width 0.088646)
		(layer "In11.Cu")
		(net "M_D_CPU1_SA_CB<5>")
	)
	(arc
		(start 89.851992 -260.920484)
		(mid 89.664794 -260.870341)
		(end 89.477596 -260.920484)
		(width 0.088646)
		(layer "In11.Cu")
		(net "M_D_CPU1_SA_CB<5>")
	)
	(arc
		(start 93.611192 -260.920484)
		(mid 93.423994 -260.870341)
		(end 93.236796 -260.920484)
		(width 0.088646)
		(layer "In11.Cu")
		(net "M_D_CPU1_SA_CB<5>")
	)
	(arc
		(start 92.296996 -260.920484)
		(mid 92.014294 -260.996226)
		(end 91.731592 -260.920484)
		(width 0.088646)
		(layer "In11.Cu")
		(net "M_D_CPU1_SA_CB<5>")
	)
	(arc
		(start 86.658196 -260.920484)
		(mid 86.375494 -260.996226)
		(end 86.092792 -260.920484)
		(width 0.088646)
		(layer "In11.Cu")
		(net "M_D_CPU1_SA_CB<5>")
	)
	(arc
		(start 96.995996 -260.920484)
		(mid 96.721767 -260.996409)
		(end 96.445324 -260.92912)
		(width 0.088646)
		(layer "In11.Cu")
		(net "M_D_CPU1_SA_CB<5>")
	)
	(arc
		(start 87.972392 -260.920484)
		(mid 87.785194 -260.870341)
		(end 87.597996 -260.920484)
		(width 0.088646)
		(layer "In11.Cu")
		(net "M_D_CPU1_SA_CB<5>")
	)
	(arc
		(start 97.921064 -260.92912)
		(mid 97.644623 -260.996286)
		(end 97.370392 -260.920484)
		(width 0.088646)
		(layer "In11.Cu")
		(net "M_D_CPU1_SA_CB<5>")
	)
	(arc
		(start 96.041464 -260.92912)
		(mid 95.765023 -260.996286)
		(end 95.490792 -260.920484)
		(width 0.088646)
		(layer "In11.Cu")
		(net "M_D_CPU1_SA_CB<5>")
	)
	(arc
		(start 86.092792 -260.920484)
		(mid 85.905594 -260.870341)
		(end 85.718396 -260.920484)
		(width 0.088646)
		(layer "In11.Cu")
		(net "M_D_CPU1_SA_CB<5>")
	)
	(arc
		(start 94.161864 -260.92912)
		(mid 93.885423 -260.996286)
		(end 93.611192 -260.920484)
		(width 0.088646)
		(layer "In11.Cu")
		(net "M_D_CPU1_SA_CB<5>")
	)
	(arc
		(start 99.249992 -260.920484)
		(mid 99.062794 -260.870341)
		(end 98.875596 -260.920484)
		(width 0.088646)
		(layer "In11.Cu")
		(net "M_D_CPU1_SA_CB<5>")
	)
	(arc
		(start 87.597996 -260.920484)
		(mid 87.315294 -260.996226)
		(end 87.032592 -260.920484)
		(width 0.088646)
		(layer "In11.Cu")
		(net "M_D_CPU1_SA_CB<5>")
	)
	(arc
		(start 85.152992 -260.920484)
		(mid 84.965794 -260.870341)
		(end 84.778596 -260.920484)
		(width 0.088646)
		(layer "In11.Cu")
		(net "M_D_CPU1_SA_CB<5>")
	)
	(arc
		(start 91.731592 -260.920484)
		(mid 91.544394 -260.870341)
		(end 91.357196 -260.920484)
		(width 0.088646)
		(layer "In11.Cu")
		(net "M_D_CPU1_SA_CB<5>")
	)
	(arc
		(start 92.671392 -260.920484)
		(mid 92.484194 -260.870341)
		(end 92.296996 -260.920484)
		(width 0.088646)
		(layer "In11.Cu")
		(net "M_D_CPU1_SA_CB<5>")
	)
	(arc
		(start 85.718396 -260.920484)
		(mid 85.435694 -260.996226)
		(end 85.152992 -260.920484)
		(width 0.088646)
		(layer "In11.Cu")
		(net "M_D_CPU1_SA_CB<5>")
	)
	(arc
		(start 95.116396 -260.920484)
		(mid 94.842167 -260.996409)
		(end 94.565724 -260.92912)
		(width 0.088646)
		(layer "In11.Cu")
		(net "M_D_CPU1_SA_CB<5>")
	)
	(arc
		(start 93.222064 -260.92912)
		(mid 92.945623 -260.996286)
		(end 92.671392 -260.920484)
		(width 0.088646)
		(layer "In11.Cu")
		(net "M_D_CPU1_SA_CB<5>")
	)
	(arc
		(start 99.432872 -261.187438)
		(mid 99.374716 -261.037325)
		(end 99.258882 -260.925564)
		(width 0.088646)
		(layer "In11.Cu")
		(net "M_D_CPU1_SA_CB<5>")
	)
	(arc
		(start 90.417396 -260.920484)
		(mid 90.134694 -260.996226)
		(end 89.851992 -260.920484)
		(width 0.088646)
		(layer "In11.Cu")
		(net "M_D_CPU1_SA_CB<5>")
	)
	(arc
		(start 94.550992 -260.920484)
		(mid 94.363794 -260.870341)
		(end 94.176596 -260.920484)
		(width 0.088646)
		(layer "In11.Cu")
		(net "M_D_CPU1_SA_CB<5>")
	)
	(arc
		(start 89.462864 -260.92912)
		(mid 89.186423 -260.996286)
		(end 88.912192 -260.920484)
		(width 0.088646)
		(layer "In11.Cu")
		(net "M_D_CPU1_SA_CB<5>")
	)
	(arc
		(start 84.778596 -260.920484)
		(mid 84.495894 -260.996226)
		(end 84.213192 -260.920484)
		(width 0.088646)
		(layer "In11.Cu")
		(net "M_D_CPU1_SA_CB<5>")
	)
	(arc
		(start 88.537796 -260.920484)
		(mid 88.255094 -260.996226)
		(end 87.972392 -260.920484)
		(width 0.088646)
		(layer "In11.Cu")
		(net "M_D_CPU1_SA_CB<5>")
	)
	(segment
		(start 16.789146 -272.966688)
		(end 15.684246 -272.966688)
		(width 0.20066)
		(layer "F.Cu")
		(net "M_D_CPU1_SA_CB<4>")
	)
	(segment
		(start 10.344912 -273.032728)
		(end 10.344912 -272.743168)
		(width 0.20066)
		(layer "F.Cu")
		(net "M_D_CPU1_SA_CB<4>")
	)
	(segment
		(start 9.474708 -272.966688)
		(end 9.713468 -273.205448)
		(width 0.20066)
		(layer "F.Cu")
		(net "M_D_CPU1_SA_CB<4>")
	)
	(segment
		(start 8.140446 -272.966688)
		(end 9.474708 -272.966688)
		(width 0.20066)
		(layer "F.Cu")
		(net "M_D_CPU1_SA_CB<4>")
	)
	(segment
		(start 14.315186 -272.966688)
		(end 15.684246 -272.966688)
		(width 0.20066)
		(layer "F.Cu")
		(net "M_D_CPU1_SA_CB<4>")
	)
	(segment
		(start 98.592894 -262.058404)
		(end 98.593148 -262.058658)
		(width 0.20066)
		(layer "F.Cu")
		(net "M_D_CPU1_SA_CB<4>")
	)
	(segment
		(start 10.344912 -272.743168)
		(end 10.554462 -272.533618)
		(width 0.20066)
		(layer "F.Cu")
		(net "M_D_CPU1_SA_CB<4>")
	)
	(segment
		(start 98.592894 -261.522718)
		(end 98.592894 -262.058404)
		(width 0.20066)
		(layer "F.Cu")
		(net "M_D_CPU1_SA_CB<4>")
	)
	(segment
		(start 13.890244 -272.541746)
		(end 14.315186 -272.966688)
		(width 0.20066)
		(layer "F.Cu")
		(net "M_D_CPU1_SA_CB<4>")
	)
	(segment
		(start 11.11631 -272.533618)
		(end 11.124438 -272.541746)
		(width 0.101854)
		(layer "F.Cu")
		(net "M_D_CPU1_SA_CB<4>")
	)
	(segment
		(start 11.372342 -272.541746)
		(end 13.441426 -272.541746)
		(width 0.1016)
		(layer "F.Cu")
		(net "M_D_CPU1_SA_CB<4>")
	)
	(segment
		(start 11.124438 -272.541746)
		(end 11.372342 -272.541746)
		(width 0.101854)
		(layer "F.Cu")
		(net "M_D_CPU1_SA_CB<4>")
	)
	(segment
		(start 10.172192 -273.205448)
		(end 10.344912 -273.032728)
		(width 0.20066)
		(layer "F.Cu")
		(net "M_D_CPU1_SA_CB<4>")
	)
	(segment
		(start 10.554462 -272.533618)
		(end 11.11631 -272.533618)
		(width 0.20066)
		(layer "F.Cu")
		(net "M_D_CPU1_SA_CB<4>")
	)
	(segment
		(start 13.441426 -272.541746)
		(end 13.890244 -272.541746)
		(width 0.20066)
		(layer "F.Cu")
		(net "M_D_CPU1_SA_CB<4>")
	)
	(segment
		(start 9.713468 -273.205448)
		(end 10.172192 -273.205448)
		(width 0.20066)
		(layer "F.Cu")
		(net "M_D_CPU1_SA_CB<4>")
	)
	(segment
		(start 18.92808 -273.5961)
		(end 18.92808 -273.787362)
		(width 0.18288)
		(layer "In11.Cu")
		(net "M_D_CPU1_SA_CB<4>")
	)
	(segment
		(start 44.556426 -271.073626)
		(end 44.200826 -270.718026)
		(width 0.18288)
		(layer "In11.Cu")
		(net "M_D_CPU1_SA_CB<4>")
	)
	(segment
		(start 17.225518 -273.40306)
		(end 16.789146 -272.966688)
		(width 0.18288)
		(layer "In11.Cu")
		(net "M_D_CPU1_SA_CB<4>")
	)
	(segment
		(start 52.64404 -269.85214)
		(end 51.878992 -269.85214)
		(width 0.18288)
		(layer "In11.Cu")
		(net "M_D_CPU1_SA_CB<4>")
	)
	(segment
		(start 42.849546 -271.289018)
		(end 42.656506 -271.482058)
		(width 0.18288)
		(layer "In11.Cu")
		(net "M_D_CPU1_SA_CB<4>")
	)
	(segment
		(start 43.042586 -270.718026)
		(end 42.849546 -270.911066)
		(width 0.18288)
		(layer "In11.Cu")
		(net "M_D_CPU1_SA_CB<4>")
	)
	(segment
		(start 31.43885 -271.022826)
		(end 29.672026 -271.022826)
		(width 0.18288)
		(layer "In11.Cu")
		(net "M_D_CPU1_SA_CB<4>")
	)
	(segment
		(start 61.807852 -269.994126)
		(end 61.643768 -269.830042)
		(width 0.18288)
		(layer "In11.Cu")
		(net "M_D_CPU1_SA_CB<4>")
	)
	(segment
		(start 54.943502 -270.857726)
		(end 53.649626 -270.857726)
		(width 0.18288)
		(layer "In11.Cu")
		(net "M_D_CPU1_SA_CB<4>")
	)
	(segment
		(start 21.72589 -273.228562)
		(end 21.564092 -273.39036)
		(width 0.18288)
		(layer "In11.Cu")
		(net "M_D_CPU1_SA_CB<4>")
	)
	(segment
		(start 41.310052 -270.718026)
		(end 41.175686 -270.852392)
		(width 0.18288)
		(layer "In11.Cu")
		(net "M_D_CPU1_SA_CB<4>")
	)
	(segment
		(start 51.738784 -269.992348)
		(end 50.88636 -269.992348)
		(width 0.18288)
		(layer "In11.Cu")
		(net "M_D_CPU1_SA_CB<4>")
	)
	(segment
		(start 45.470826 -271.073626)
		(end 44.556426 -271.073626)
		(width 0.18288)
		(layer "In11.Cu")
		(net "M_D_CPU1_SA_CB<4>")
	)
	(segment
		(start 96.91116 -261.740396)
		(end 96.900746 -261.7343)
		(width 0.088646)
		(layer "In11.Cu")
		(net "M_D_CPU1_SA_CB<4>")
	)
	(segment
		(start 89.39276 -261.740396)
		(end 89.382346 -261.7343)
		(width 0.088646)
		(layer "In11.Cu")
		(net "M_D_CPU1_SA_CB<4>")
	)
	(segment
		(start 19.13382 -273.39036)
		(end 18.92808 -273.5961)
		(width 0.18288)
		(layer "In11.Cu")
		(net "M_D_CPU1_SA_CB<4>")
	)
	(segment
		(start 22.961346 -273.228562)
		(end 21.72589 -273.228562)
		(width 0.18288)
		(layer "In11.Cu")
		(net "M_D_CPU1_SA_CB<4>")
	)
	(segment
		(start 47.938944 -270.57731)
		(end 47.674022 -270.842232)
		(width 0.18288)
		(layer "In11.Cu")
		(net "M_D_CPU1_SA_CB<4>")
	)
	(segment
		(start 63.63208 -269.139162)
		(end 62.777116 -269.994126)
		(width 0.18288)
		(layer "In11.Cu")
		(net "M_D_CPU1_SA_CB<4>")
	)
	(segment
		(start 32.586422 -270.842232)
		(end 31.619444 -270.842232)
		(width 0.18288)
		(layer "In11.Cu")
		(net "M_D_CPU1_SA_CB<4>")
	)
	(segment
		(start 98.236786 -261.963154)
		(end 97.840292 -261.7343)
		(width 0.088646)
		(layer "In11.Cu")
		(net "M_D_CPU1_SA_CB<4>")
	)
	(segment
		(start 60.275724 -269.811246)
		(end 59.382406 -269.811246)
		(width 0.18288)
		(layer "In11.Cu")
		(net "M_D_CPU1_SA_CB<4>")
	)
	(segment
		(start 61.362844 -269.830042)
		(end 61.169804 -270.023082)
		(width 0.18288)
		(layer "In11.Cu")
		(net "M_D_CPU1_SA_CB<4>")
	)
	(segment
		(start 18.42008 -273.980402)
		(end 18.22704 -273.787362)
		(width 0.18288)
		(layer "In11.Cu")
		(net "M_D_CPU1_SA_CB<4>")
	)
	(segment
		(start 28.989274 -271.705578)
		(end 25.540462 -271.705578)
		(width 0.18288)
		(layer "In11.Cu")
		(net "M_D_CPU1_SA_CB<4>")
	)
	(segment
		(start 60.468764 -270.004286)
		(end 60.275724 -269.811246)
		(width 0.18288)
		(layer "In11.Cu")
		(net "M_D_CPU1_SA_CB<4>")
	)
	(segment
		(start 94.096078 -261.742936)
		(end 94.081346 -261.7343)
		(width 0.088646)
		(layer "In11.Cu")
		(net "M_D_CPU1_SA_CB<4>")
	)
	(segment
		(start 60.976764 -270.432784)
		(end 60.661804 -270.432784)
		(width 0.18288)
		(layer "In11.Cu")
		(net "M_D_CPU1_SA_CB<4>")
	)
	(segment
		(start 18.73504 -273.980402)
		(end 18.42008 -273.980402)
		(width 0.18288)
		(layer "In11.Cu")
		(net "M_D_CPU1_SA_CB<4>")
	)
	(segment
		(start 60.468764 -270.239744)
		(end 60.468764 -270.004286)
		(width 0.18288)
		(layer "In11.Cu")
		(net "M_D_CPU1_SA_CB<4>")
	)
	(segment
		(start 45.70222 -270.842232)
		(end 45.470826 -271.073626)
		(width 0.18288)
		(layer "In11.Cu")
		(net "M_D_CPU1_SA_CB<4>")
	)
	(segment
		(start 50.88636 -269.992348)
		(end 50.301398 -270.57731)
		(width 0.18288)
		(layer "In11.Cu")
		(net "M_D_CPU1_SA_CB<4>")
	)
	(segment
		(start 67.925188 -269.139162)
		(end 63.63208 -269.139162)
		(width 0.18288)
		(layer "In11.Cu")
		(net "M_D_CPU1_SA_CB<4>")
	)
	(segment
		(start 83.312508 -262.23595)
		(end 83.01355 -262.23595)
		(width 0.088646)
		(layer "In11.Cu")
		(net "M_D_CPU1_SA_CB<4>")
	)
	(segment
		(start 18.034 -273.40306)
		(end 17.225518 -273.40306)
		(width 0.18288)
		(layer "In11.Cu")
		(net "M_D_CPU1_SA_CB<4>")
	)
	(segment
		(start 50.301398 -270.57731)
		(end 47.938944 -270.57731)
		(width 0.18288)
		(layer "In11.Cu")
		(net "M_D_CPU1_SA_CB<4>")
	)
	(segment
		(start 18.22704 -273.5961)
		(end 18.034 -273.40306)
		(width 0.18288)
		(layer "In11.Cu")
		(net "M_D_CPU1_SA_CB<4>")
	)
	(segment
		(start 42.341546 -271.482058)
		(end 42.148506 -271.289018)
		(width 0.18288)
		(layer "In11.Cu")
		(net "M_D_CPU1_SA_CB<4>")
	)
	(segment
		(start 21.564092 -273.39036)
		(end 19.13382 -273.39036)
		(width 0.18288)
		(layer "In11.Cu")
		(net "M_D_CPU1_SA_CB<4>")
	)
	(segment
		(start 36.68649 -269.992348)
		(end 35.736784 -269.992348)
		(width 0.18288)
		(layer "In11.Cu")
		(net "M_D_CPU1_SA_CB<4>")
	)
	(segment
		(start 51.878992 -269.85214)
		(end 51.738784 -269.992348)
		(width 0.18288)
		(layer "In11.Cu")
		(net "M_D_CPU1_SA_CB<4>")
	)
	(segment
		(start 23.633684 -272.556224)
		(end 22.961346 -273.228562)
		(width 0.18288)
		(layer "In11.Cu")
		(net "M_D_CPU1_SA_CB<4>")
	)
	(segment
		(start 29.672026 -271.022826)
		(end 28.989274 -271.705578)
		(width 0.18288)
		(layer "In11.Cu")
		(net "M_D_CPU1_SA_CB<4>")
	)
	(segment
		(start 83.738466 -261.809992)
		(end 83.312508 -262.23595)
		(width 0.088646)
		(layer "In11.Cu")
		(net "M_D_CPU1_SA_CB<4>")
	)
	(segment
		(start 62.777116 -269.994126)
		(end 61.807852 -269.994126)
		(width 0.18288)
		(layer "In11.Cu")
		(net "M_D_CPU1_SA_CB<4>")
	)
	(segment
		(start 53.649626 -270.857726)
		(end 52.64404 -269.85214)
		(width 0.18288)
		(layer "In11.Cu")
		(net "M_D_CPU1_SA_CB<4>")
	)
	(segment
		(start 32.831278 -270.597376)
		(end 32.586422 -270.842232)
		(width 0.18288)
		(layer "In11.Cu")
		(net "M_D_CPU1_SA_CB<4>")
	)
	(segment
		(start 41.955466 -270.718026)
		(end 41.310052 -270.718026)
		(width 0.18288)
		(layer "In11.Cu")
		(net "M_D_CPU1_SA_CB<4>")
	)
	(segment
		(start 88.452706 -261.740396)
		(end 88.442292 -261.7343)
		(width 0.088646)
		(layer "In11.Cu")
		(net "M_D_CPU1_SA_CB<4>")
	)
	(segment
		(start 24.689816 -272.556224)
		(end 23.633684 -272.556224)
		(width 0.18288)
		(layer "In11.Cu")
		(net "M_D_CPU1_SA_CB<4>")
	)
	(segment
		(start 42.148506 -270.911066)
		(end 41.955466 -270.718026)
		(width 0.18288)
		(layer "In11.Cu")
		(net "M_D_CPU1_SA_CB<4>")
	)
	(segment
		(start 95.035878 -261.742936)
		(end 95.021146 -261.7343)
		(width 0.088646)
		(layer "In11.Cu")
		(net "M_D_CPU1_SA_CB<4>")
	)
	(segment
		(start 31.619444 -270.842232)
		(end 31.43885 -271.022826)
		(width 0.18288)
		(layer "In11.Cu")
		(net "M_D_CPU1_SA_CB<4>")
	)
	(segment
		(start 59.382406 -269.811246)
		(end 59.190128 -270.003524)
		(width 0.18288)
		(layer "In11.Cu")
		(net "M_D_CPU1_SA_CB<4>")
	)
	(segment
		(start 95.975678 -261.742936)
		(end 95.960946 -261.7343)
		(width 0.088646)
		(layer "In11.Cu")
		(net "M_D_CPU1_SA_CB<4>")
	)
	(segment
		(start 92.216478 -261.742936)
		(end 92.201746 -261.7343)
		(width 0.088646)
		(layer "In11.Cu")
		(net "M_D_CPU1_SA_CB<4>")
	)
	(segment
		(start 74.8284 -262.23595)
		(end 67.925188 -269.139162)
		(width 0.18288)
		(layer "In11.Cu")
		(net "M_D_CPU1_SA_CB<4>")
	)
	(segment
		(start 61.643768 -269.830042)
		(end 61.362844 -269.830042)
		(width 0.18288)
		(layer "In11.Cu")
		(net "M_D_CPU1_SA_CB<4>")
	)
	(segment
		(start 36.799012 -269.879826)
		(end 36.68649 -269.992348)
		(width 0.18288)
		(layer "In11.Cu")
		(net "M_D_CPU1_SA_CB<4>")
	)
	(segment
		(start 35.131756 -270.597376)
		(end 32.831278 -270.597376)
		(width 0.18288)
		(layer "In11.Cu")
		(net "M_D_CPU1_SA_CB<4>")
	)
	(segment
		(start 35.736784 -269.992348)
		(end 35.131756 -270.597376)
		(width 0.18288)
		(layer "In11.Cu")
		(net "M_D_CPU1_SA_CB<4>")
	)
	(segment
		(start 55.797704 -270.003524)
		(end 54.943502 -270.857726)
		(width 0.18288)
		(layer "In11.Cu")
		(net "M_D_CPU1_SA_CB<4>")
	)
	(segment
		(start 37.510466 -269.879826)
		(end 36.799012 -269.879826)
		(width 0.18288)
		(layer "In11.Cu")
		(net "M_D_CPU1_SA_CB<4>")
	)
	(segment
		(start 25.540462 -271.705578)
		(end 24.689816 -272.556224)
		(width 0.18288)
		(layer "In11.Cu")
		(net "M_D_CPU1_SA_CB<4>")
	)
	(segment
		(start 42.148506 -271.289018)
		(end 42.148506 -270.911066)
		(width 0.18288)
		(layer "In11.Cu")
		(net "M_D_CPU1_SA_CB<4>")
	)
	(segment
		(start 47.674022 -270.842232)
		(end 45.70222 -270.842232)
		(width 0.18288)
		(layer "In11.Cu")
		(net "M_D_CPU1_SA_CB<4>")
	)
	(segment
		(start 44.200826 -270.718026)
		(end 43.042586 -270.718026)
		(width 0.18288)
		(layer "In11.Cu")
		(net "M_D_CPU1_SA_CB<4>")
	)
	(segment
		(start 83.01355 -262.23595)
		(end 74.8284 -262.23595)
		(width 0.18288)
		(layer "In11.Cu")
		(net "M_D_CPU1_SA_CB<4>")
	)
	(segment
		(start 42.656506 -271.482058)
		(end 42.341546 -271.482058)
		(width 0.18288)
		(layer "In11.Cu")
		(net "M_D_CPU1_SA_CB<4>")
	)
	(segment
		(start 41.175686 -270.852392)
		(end 38.483032 -270.852392)
		(width 0.18288)
		(layer "In11.Cu")
		(net "M_D_CPU1_SA_CB<4>")
	)
	(segment
		(start 38.483032 -270.852392)
		(end 37.510466 -269.879826)
		(width 0.18288)
		(layer "In11.Cu")
		(net "M_D_CPU1_SA_CB<4>")
	)
	(segment
		(start 61.169804 -270.023082)
		(end 61.169804 -270.239744)
		(width 0.18288)
		(layer "In11.Cu")
		(net "M_D_CPU1_SA_CB<4>")
	)
	(segment
		(start 84.025994 -261.809992)
		(end 83.738466 -261.809992)
		(width 0.088646)
		(layer "In11.Cu")
		(net "M_D_CPU1_SA_CB<4>")
	)
	(segment
		(start 18.22704 -273.787362)
		(end 18.22704 -273.5961)
		(width 0.18288)
		(layer "In11.Cu")
		(net "M_D_CPU1_SA_CB<4>")
	)
	(segment
		(start 61.169804 -270.239744)
		(end 60.976764 -270.432784)
		(width 0.18288)
		(layer "In11.Cu")
		(net "M_D_CPU1_SA_CB<4>")
	)
	(segment
		(start 93.156278 -261.742936)
		(end 93.141546 -261.7343)
		(width 0.088646)
		(layer "In11.Cu")
		(net "M_D_CPU1_SA_CB<4>")
	)
	(segment
		(start 60.661804 -270.432784)
		(end 60.468764 -270.239744)
		(width 0.18288)
		(layer "In11.Cu")
		(net "M_D_CPU1_SA_CB<4>")
	)
	(segment
		(start 91.272106 -261.740396)
		(end 91.261692 -261.7343)
		(width 0.088646)
		(layer "In11.Cu")
		(net "M_D_CPU1_SA_CB<4>")
	)
	(segment
		(start 59.190128 -270.003524)
		(end 55.797704 -270.003524)
		(width 0.18288)
		(layer "In11.Cu")
		(net "M_D_CPU1_SA_CB<4>")
	)
	(segment
		(start 42.849546 -270.911066)
		(end 42.849546 -271.289018)
		(width 0.18288)
		(layer "In11.Cu")
		(net "M_D_CPU1_SA_CB<4>")
	)
	(segment
		(start 18.92808 -273.787362)
		(end 18.73504 -273.980402)
		(width 0.18288)
		(layer "In11.Cu")
		(net "M_D_CPU1_SA_CB<4>")
	)
	(arc
		(start 95.960946 -261.7343)
		(mid 95.773748 -261.684157)
		(end 95.58655 -261.7343)
		(width 0.088646)
		(layer "In11.Cu")
		(net "M_D_CPU1_SA_CB<4>")
	)
	(arc
		(start 90.887296 -261.7343)
		(mid 90.604594 -261.810076)
		(end 90.321892 -261.7343)
		(width 0.088646)
		(layer "In11.Cu")
		(net "M_D_CPU1_SA_CB<4>")
	)
	(arc
		(start 94.081346 -261.7343)
		(mid 93.894148 -261.684157)
		(end 93.70695 -261.7343)
		(width 0.088646)
		(layer "In11.Cu")
		(net "M_D_CPU1_SA_CB<4>")
	)
	(arc
		(start 88.442292 -261.7343)
		(mid 88.255094 -261.684157)
		(end 88.067896 -261.7343)
		(width 0.088646)
		(layer "In11.Cu")
		(net "M_D_CPU1_SA_CB<4>")
	)
	(arc
		(start 88.067896 -261.7343)
		(mid 87.785194 -261.810076)
		(end 87.502492 -261.7343)
		(width 0.088646)
		(layer "In11.Cu")
		(net "M_D_CPU1_SA_CB<4>")
	)
	(arc
		(start 91.82735 -261.7343)
		(mid 91.550537 -261.81017)
		(end 91.272106 -261.740396)
		(width 0.088646)
		(layer "In11.Cu")
		(net "M_D_CPU1_SA_CB<4>")
	)
	(arc
		(start 92.201746 -261.7343)
		(mid 92.014548 -261.684157)
		(end 91.82735 -261.7343)
		(width 0.088646)
		(layer "In11.Cu")
		(net "M_D_CPU1_SA_CB<4>")
	)
	(arc
		(start 89.382346 -261.7343)
		(mid 89.195148 -261.684123)
		(end 89.00795 -261.7343)
		(width 0.088646)
		(layer "In11.Cu")
		(net "M_D_CPU1_SA_CB<4>")
	)
	(arc
		(start 95.021146 -261.7343)
		(mid 94.833948 -261.684157)
		(end 94.64675 -261.7343)
		(width 0.088646)
		(layer "In11.Cu")
		(net "M_D_CPU1_SA_CB<4>")
	)
	(arc
		(start 85.248496 -261.7343)
		(mid 84.965794 -261.810076)
		(end 84.683092 -261.7343)
		(width 0.088646)
		(layer "In11.Cu")
		(net "M_D_CPU1_SA_CB<4>")
	)
	(arc
		(start 91.261692 -261.7343)
		(mid 91.074494 -261.684157)
		(end 90.887296 -261.7343)
		(width 0.088646)
		(layer "In11.Cu")
		(net "M_D_CPU1_SA_CB<4>")
	)
	(arc
		(start 95.58655 -261.7343)
		(mid 95.312351 -261.810135)
		(end 95.035878 -261.742936)
		(width 0.088646)
		(layer "In11.Cu")
		(net "M_D_CPU1_SA_CB<4>")
	)
	(arc
		(start 97.465896 -261.7343)
		(mid 97.189337 -261.810043)
		(end 96.91116 -261.740396)
		(width 0.088646)
		(layer "In11.Cu")
		(net "M_D_CPU1_SA_CB<4>")
	)
	(arc
		(start 98.593148 -262.058658)
		(mid 98.408677 -262.034371)
		(end 98.236786 -261.963154)
		(width 0.088646)
		(layer "In11.Cu")
		(net "M_D_CPU1_SA_CB<4>")
	)
	(arc
		(start 84.683092 -261.7343)
		(mid 84.495894 -261.684157)
		(end 84.308696 -261.7343)
		(width 0.088646)
		(layer "In11.Cu")
		(net "M_D_CPU1_SA_CB<4>")
	)
	(arc
		(start 87.128096 -261.7343)
		(mid 86.845394 -261.810076)
		(end 86.562692 -261.7343)
		(width 0.088646)
		(layer "In11.Cu")
		(net "M_D_CPU1_SA_CB<4>")
	)
	(arc
		(start 93.141546 -261.7343)
		(mid 92.954348 -261.684157)
		(end 92.76715 -261.7343)
		(width 0.088646)
		(layer "In11.Cu")
		(net "M_D_CPU1_SA_CB<4>")
	)
	(arc
		(start 86.562692 -261.7343)
		(mid 86.375494 -261.684157)
		(end 86.188296 -261.7343)
		(width 0.088646)
		(layer "In11.Cu")
		(net "M_D_CPU1_SA_CB<4>")
	)
	(arc
		(start 94.64675 -261.7343)
		(mid 94.372551 -261.810135)
		(end 94.096078 -261.742936)
		(width 0.088646)
		(layer "In11.Cu")
		(net "M_D_CPU1_SA_CB<4>")
	)
	(arc
		(start 90.321892 -261.7343)
		(mid 90.134694 -261.684157)
		(end 89.947496 -261.7343)
		(width 0.088646)
		(layer "In11.Cu")
		(net "M_D_CPU1_SA_CB<4>")
	)
	(arc
		(start 96.900746 -261.7343)
		(mid 96.713548 -261.684157)
		(end 96.52635 -261.7343)
		(width 0.088646)
		(layer "In11.Cu")
		(net "M_D_CPU1_SA_CB<4>")
	)
	(arc
		(start 97.840292 -261.7343)
		(mid 97.653094 -261.684157)
		(end 97.465896 -261.7343)
		(width 0.088646)
		(layer "In11.Cu")
		(net "M_D_CPU1_SA_CB<4>")
	)
	(arc
		(start 85.622892 -261.7343)
		(mid 85.435694 -261.684157)
		(end 85.248496 -261.7343)
		(width 0.088646)
		(layer "In11.Cu")
		(net "M_D_CPU1_SA_CB<4>")
	)
	(arc
		(start 89.947496 -261.7343)
		(mid 89.670937 -261.810043)
		(end 89.39276 -261.740396)
		(width 0.088646)
		(layer "In11.Cu")
		(net "M_D_CPU1_SA_CB<4>")
	)
	(arc
		(start 89.00795 -261.7343)
		(mid 88.731137 -261.81017)
		(end 88.452706 -261.740396)
		(width 0.088646)
		(layer "In11.Cu")
		(net "M_D_CPU1_SA_CB<4>")
	)
	(arc
		(start 92.76715 -261.7343)
		(mid 92.492951 -261.810135)
		(end 92.216478 -261.742936)
		(width 0.088646)
		(layer "In11.Cu")
		(net "M_D_CPU1_SA_CB<4>")
	)
	(arc
		(start 87.502492 -261.7343)
		(mid 87.315294 -261.684157)
		(end 87.128096 -261.7343)
		(width 0.088646)
		(layer "In11.Cu")
		(net "M_D_CPU1_SA_CB<4>")
	)
	(arc
		(start 86.188296 -261.7343)
		(mid 85.905594 -261.810076)
		(end 85.622892 -261.7343)
		(width 0.088646)
		(layer "In11.Cu")
		(net "M_D_CPU1_SA_CB<4>")
	)
	(arc
		(start 84.308696 -261.7343)
		(mid 84.172327 -261.790742)
		(end 84.025994 -261.809992)
		(width 0.088646)
		(layer "In11.Cu")
		(net "M_D_CPU1_SA_CB<4>")
	)
	(arc
		(start 93.70695 -261.7343)
		(mid 93.432751 -261.810135)
		(end 93.156278 -261.742936)
		(width 0.088646)
		(layer "In11.Cu")
		(net "M_D_CPU1_SA_CB<4>")
	)
	(arc
		(start 96.52635 -261.7343)
		(mid 96.252151 -261.810135)
		(end 95.975678 -261.742936)
		(width 0.088646)
		(layer "In11.Cu")
		(net "M_D_CPU1_SA_CB<4>")
	)
	(segment
		(start 14.063726 -276.492716)
		(end 14.063726 -276.663404)
		(width 0.20066)
		(layer "F.Cu")
		(net "M_D_CPU1_SA_CB<3>")
	)
	(segment
		(start 14.063726 -276.663404)
		(end 14.20622 -276.805898)
		(width 0.20066)
		(layer "F.Cu")
		(net "M_D_CPU1_SA_CB<3>")
	)
	(segment
		(start 12.240514 -276.366732)
		(end 13.937742 -276.366732)
		(width 0.20066)
		(layer "F.Cu")
		(net "M_D_CPU1_SA_CB<3>")
	)
	(segment
		(start 14.812264 -276.791674)
		(end 16.885158 -276.791674)
		(width 0.1016)
		(layer "F.Cu")
		(net "M_D_CPU1_SA_CB<3>")
	)
	(segment
		(start 17.578578 -276.490938)
		(end 17.707102 -276.362414)
		(width 0.20066)
		(layer "F.Cu")
		(net "M_D_CPU1_SA_CB<3>")
	)
	(segment
		(start 16.885158 -276.791674)
		(end 17.42948 -276.791674)
		(width 0.20066)
		(layer "F.Cu")
		(net "M_D_CPU1_SA_CB<3>")
	)
	(segment
		(start 17.707102 -276.362414)
		(end 18.102326 -276.362414)
		(width 0.20066)
		(layer "F.Cu")
		(net "M_D_CPU1_SA_CB<3>")
	)
	(segment
		(start 18.102326 -276.362414)
		(end 18.314162 -276.57425)
		(width 0.20066)
		(layer "F.Cu")
		(net "M_D_CPU1_SA_CB<3>")
	)
	(segment
		(start 20.889214 -276.366732)
		(end 19.784314 -276.366732)
		(width 0.20066)
		(layer "F.Cu")
		(net "M_D_CPU1_SA_CB<3>")
	)
	(segment
		(start 13.937742 -276.366732)
		(end 14.063726 -276.492716)
		(width 0.20066)
		(layer "F.Cu")
		(net "M_D_CPU1_SA_CB<3>")
	)
	(segment
		(start 18.968212 -276.366732)
		(end 19.784314 -276.366732)
		(width 0.20066)
		(layer "F.Cu")
		(net "M_D_CPU1_SA_CB<3>")
	)
	(segment
		(start 18.760694 -276.57425)
		(end 18.968212 -276.366732)
		(width 0.20066)
		(layer "F.Cu")
		(net "M_D_CPU1_SA_CB<3>")
	)
	(segment
		(start 14.574266 -276.791674)
		(end 14.812264 -276.791674)
		(width 0.101854)
		(layer "F.Cu")
		(net "M_D_CPU1_SA_CB<3>")
	)
	(segment
		(start 18.314162 -276.57425)
		(end 18.760694 -276.57425)
		(width 0.20066)
		(layer "F.Cu")
		(net "M_D_CPU1_SA_CB<3>")
	)
	(segment
		(start 17.42948 -276.791674)
		(end 17.578578 -276.642576)
		(width 0.20066)
		(layer "F.Cu")
		(net "M_D_CPU1_SA_CB<3>")
	)
	(segment
		(start 100.472494 -263.150604)
		(end 100.472494 -263.68629)
		(width 0.20066)
		(layer "F.Cu")
		(net "M_D_CPU1_SA_CB<3>")
	)
	(segment
		(start 100.472494 -263.68629)
		(end 100.472748 -263.686544)
		(width 0.20066)
		(layer "F.Cu")
		(net "M_D_CPU1_SA_CB<3>")
	)
	(segment
		(start 14.20622 -276.805898)
		(end 14.560042 -276.805898)
		(width 0.20066)
		(layer "F.Cu")
		(net "M_D_CPU1_SA_CB<3>")
	)
	(segment
		(start 17.578578 -276.642576)
		(end 17.578578 -276.490938)
		(width 0.20066)
		(layer "F.Cu")
		(net "M_D_CPU1_SA_CB<3>")
	)
	(segment
		(start 14.560042 -276.805898)
		(end 14.574266 -276.791674)
		(width 0.101854)
		(layer "F.Cu")
		(net "M_D_CPU1_SA_CB<3>")
	)
	(segment
		(start 53.433726 -274.197572)
		(end 52.539138 -275.09216)
		(width 0.18288)
		(layer "In11.Cu")
		(net "M_D_CPU1_SA_CB<3>")
	)
	(segment
		(start 21.400008 -276.877526)
		(end 20.889214 -276.366732)
		(width 0.18288)
		(layer "In11.Cu")
		(net "M_D_CPU1_SA_CB<3>")
	)
	(segment
		(start 29.011626 -275.264626)
		(end 28.529026 -274.782026)
		(width 0.18288)
		(layer "In11.Cu")
		(net "M_D_CPU1_SA_CB<3>")
	)
	(segment
		(start 27.60853 -275.392134)
		(end 27.41549 -275.585174)
		(width 0.18288)
		(layer "In11.Cu")
		(net "M_D_CPU1_SA_CB<3>")
	)
	(segment
		(start 39.004748 -274.390612)
		(end 38.811708 -274.197572)
		(width 0.18288)
		(layer "In11.Cu")
		(net "M_D_CPU1_SA_CB<3>")
	)
	(segment
		(start 47.393606 -275.942044)
		(end 46.298358 -275.942044)
		(width 0.18288)
		(layer "In11.Cu")
		(net "M_D_CPU1_SA_CB<3>")
	)
	(segment
		(start 53.433726 -273.817588)
		(end 53.433726 -274.197572)
		(width 0.18288)
		(layer "In11.Cu")
		(net "M_D_CPU1_SA_CB<3>")
	)
	(segment
		(start 47.553626 -275.782024)
		(end 47.393606 -275.942044)
		(width 0.18288)
		(layer "In11.Cu")
		(net "M_D_CPU1_SA_CB<3>")
	)
	(segment
		(start 83.309968 -264.406634)
		(end 83.013804 -264.406634)
		(width 0.088646)
		(layer "In11.Cu")
		(net "M_D_CPU1_SA_CB<3>")
	)
	(segment
		(start 25.963626 -274.782026)
		(end 25.557226 -275.188426)
		(width 0.18288)
		(layer "In11.Cu")
		(net "M_D_CPU1_SA_CB<3>")
	)
	(segment
		(start 54.134766 -274.197572)
		(end 54.134766 -273.817588)
		(width 0.18288)
		(layer "In11.Cu")
		(net "M_D_CPU1_SA_CB<3>")
	)
	(segment
		(start 100.117148 -263.59104)
		(end 99.720146 -263.361932)
		(width 0.088646)
		(layer "In11.Cu")
		(net "M_D_CPU1_SA_CB<3>")
	)
	(segment
		(start 27.60853 -274.975066)
		(end 27.60853 -275.392134)
		(width 0.18288)
		(layer "In11.Cu")
		(net "M_D_CPU1_SA_CB<3>")
	)
	(segment
		(start 38.811708 -273.835114)
		(end 38.618668 -273.642074)
		(width 0.18288)
		(layer "In11.Cu")
		(net "M_D_CPU1_SA_CB<3>")
	)
	(segment
		(start 99.374452 -263.326626)
		(end 98.767392 -263.326626)
		(width 0.088646)
		(layer "In11.Cu")
		(net "M_D_CPU1_SA_CB<3>")
	)
	(segment
		(start 30.873192 -275.264626)
		(end 29.011626 -275.264626)
		(width 0.18288)
		(layer "In11.Cu")
		(net "M_D_CPU1_SA_CB<3>")
	)
	(segment
		(start 38.303708 -273.642074)
		(end 38.110668 -273.835114)
		(width 0.18288)
		(layer "In11.Cu")
		(net "M_D_CPU1_SA_CB<3>")
	)
	(segment
		(start 90.332306 -264.004806)
		(end 90.321892 -264.010902)
		(width 0.088646)
		(layer "In11.Cu")
		(net "M_D_CPU1_SA_CB<3>")
	)
	(segment
		(start 26.90749 -274.975066)
		(end 26.71445 -274.782026)
		(width 0.18288)
		(layer "In11.Cu")
		(net "M_D_CPU1_SA_CB<3>")
	)
	(segment
		(start 96.915478 -264.002266)
		(end 96.900746 -264.010902)
		(width 0.088646)
		(layer "In11.Cu")
		(net "M_D_CPU1_SA_CB<3>")
	)
	(segment
		(start 37.21608 -275.09216)
		(end 34.981388 -275.09216)
		(width 0.18288)
		(layer "In11.Cu")
		(net "M_D_CPU1_SA_CB<3>")
	)
	(segment
		(start 38.110668 -274.197572)
		(end 37.21608 -275.09216)
		(width 0.18288)
		(layer "In11.Cu")
		(net "M_D_CPU1_SA_CB<3>")
	)
	(segment
		(start 53.941726 -273.624548)
		(end 53.626766 -273.624548)
		(width 0.18288)
		(layer "In11.Cu")
		(net "M_D_CPU1_SA_CB<3>")
	)
	(segment
		(start 83.013804 -264.406634)
		(end 75.776328 -264.406634)
		(width 0.18288)
		(layer "In11.Cu")
		(net "M_D_CPU1_SA_CB<3>")
	)
	(segment
		(start 84.025994 -263.93521)
		(end 83.781392 -263.93521)
		(width 0.088646)
		(layer "In11.Cu")
		(net "M_D_CPU1_SA_CB<3>")
	)
	(segment
		(start 38.110668 -273.835114)
		(end 38.110668 -274.197572)
		(width 0.18288)
		(layer "In11.Cu")
		(net "M_D_CPU1_SA_CB<3>")
	)
	(segment
		(start 43.26128 -274.390612)
		(end 39.004748 -274.390612)
		(width 0.18288)
		(layer "In11.Cu")
		(net "M_D_CPU1_SA_CB<3>")
	)
	(segment
		(start 92.216478 -264.002266)
		(end 92.201746 -264.010902)
		(width 0.088646)
		(layer "In11.Cu")
		(net "M_D_CPU1_SA_CB<3>")
	)
	(segment
		(start 95.031306 -264.004806)
		(end 95.020892 -264.010902)
		(width 0.088646)
		(layer "In11.Cu")
		(net "M_D_CPU1_SA_CB<3>")
	)
	(segment
		(start 54.134766 -273.817588)
		(end 53.941726 -273.624548)
		(width 0.18288)
		(layer "In11.Cu")
		(net "M_D_CPU1_SA_CB<3>")
	)
	(segment
		(start 26.90749 -275.392134)
		(end 26.90749 -274.975066)
		(width 0.18288)
		(layer "In11.Cu")
		(net "M_D_CPU1_SA_CB<3>")
	)
	(segment
		(start 53.626766 -273.624548)
		(end 53.433726 -273.817588)
		(width 0.18288)
		(layer "In11.Cu")
		(net "M_D_CPU1_SA_CB<3>")
	)
	(segment
		(start 50.37201 -275.09216)
		(end 50.103278 -274.823428)
		(width 0.18288)
		(layer "In11.Cu")
		(net "M_D_CPU1_SA_CB<3>")
	)
	(segment
		(start 58.819542 -273.639026)
		(end 55.656226 -273.639026)
		(width 0.18288)
		(layer "In11.Cu")
		(net "M_D_CPU1_SA_CB<3>")
	)
	(segment
		(start 24.363426 -275.188426)
		(end 22.674326 -276.877526)
		(width 0.18288)
		(layer "In11.Cu")
		(net "M_D_CPU1_SA_CB<3>")
	)
	(segment
		(start 94.09176 -264.004806)
		(end 94.081346 -264.010902)
		(width 0.088646)
		(layer "In11.Cu")
		(net "M_D_CPU1_SA_CB<3>")
	)
	(segment
		(start 66.747136 -273.435826)
		(end 63.27013 -273.435826)
		(width 0.18288)
		(layer "In11.Cu")
		(net "M_D_CPU1_SA_CB<3>")
	)
	(segment
		(start 93.156278 -264.002266)
		(end 93.141546 -264.010902)
		(width 0.088646)
		(layer "In11.Cu")
		(net "M_D_CPU1_SA_CB<3>")
	)
	(segment
		(start 31.55315 -275.944584)
		(end 30.873192 -275.264626)
		(width 0.18288)
		(layer "In11.Cu")
		(net "M_D_CPU1_SA_CB<3>")
	)
	(segment
		(start 83.781392 -263.93521)
		(end 83.309968 -264.406634)
		(width 0.088646)
		(layer "In11.Cu")
		(net "M_D_CPU1_SA_CB<3>")
	)
	(segment
		(start 75.776328 -264.406634)
		(end 66.747136 -273.435826)
		(width 0.18288)
		(layer "In11.Cu")
		(net "M_D_CPU1_SA_CB<3>")
	)
	(segment
		(start 97.935542 -263.95553)
		(end 97.841308 -264.010648)
		(width 0.088646)
		(layer "In11.Cu")
		(net "M_D_CPU1_SA_CB<3>")
	)
	(segment
		(start 50.103278 -274.823428)
		(end 48.170592 -274.823428)
		(width 0.18288)
		(layer "In11.Cu")
		(net "M_D_CPU1_SA_CB<3>")
	)
	(segment
		(start 27.10053 -275.585174)
		(end 26.90749 -275.392134)
		(width 0.18288)
		(layer "In11.Cu")
		(net "M_D_CPU1_SA_CB<3>")
	)
	(segment
		(start 95.975678 -264.002266)
		(end 95.960946 -264.010902)
		(width 0.088646)
		(layer "In11.Cu")
		(net "M_D_CPU1_SA_CB<3>")
	)
	(segment
		(start 22.674326 -276.877526)
		(end 21.400008 -276.877526)
		(width 0.18288)
		(layer "In11.Cu")
		(net "M_D_CPU1_SA_CB<3>")
	)
	(segment
		(start 28.529026 -274.782026)
		(end 27.80157 -274.782026)
		(width 0.18288)
		(layer "In11.Cu")
		(net "M_D_CPU1_SA_CB<3>")
	)
	(segment
		(start 27.41549 -275.585174)
		(end 27.10053 -275.585174)
		(width 0.18288)
		(layer "In11.Cu")
		(net "M_D_CPU1_SA_CB<3>")
	)
	(segment
		(start 46.298358 -275.942044)
		(end 45.67174 -275.315426)
		(width 0.18288)
		(layer "In11.Cu")
		(net "M_D_CPU1_SA_CB<3>")
	)
	(segment
		(start 34.128964 -275.944584)
		(end 31.55315 -275.944584)
		(width 0.18288)
		(layer "In11.Cu")
		(net "M_D_CPU1_SA_CB<3>")
	)
	(segment
		(start 63.224156 -273.389852)
		(end 59.068716 -273.389852)
		(width 0.18288)
		(layer "In11.Cu")
		(net "M_D_CPU1_SA_CB<3>")
	)
	(segment
		(start 38.618668 -273.642074)
		(end 38.303708 -273.642074)
		(width 0.18288)
		(layer "In11.Cu")
		(net "M_D_CPU1_SA_CB<3>")
	)
	(segment
		(start 54.327806 -274.390612)
		(end 54.134766 -274.197572)
		(width 0.18288)
		(layer "In11.Cu")
		(net "M_D_CPU1_SA_CB<3>")
	)
	(segment
		(start 55.656226 -273.639026)
		(end 54.90464 -274.390612)
		(width 0.18288)
		(layer "In11.Cu")
		(net "M_D_CPU1_SA_CB<3>")
	)
	(segment
		(start 48.170592 -274.823428)
		(end 47.553626 -275.440394)
		(width 0.18288)
		(layer "In11.Cu")
		(net "M_D_CPU1_SA_CB<3>")
	)
	(segment
		(start 26.71445 -274.782026)
		(end 25.963626 -274.782026)
		(width 0.18288)
		(layer "In11.Cu")
		(net "M_D_CPU1_SA_CB<3>")
	)
	(segment
		(start 59.068716 -273.389852)
		(end 58.819542 -273.639026)
		(width 0.18288)
		(layer "In11.Cu")
		(net "M_D_CPU1_SA_CB<3>")
	)
	(segment
		(start 27.80157 -274.782026)
		(end 27.60853 -274.975066)
		(width 0.18288)
		(layer "In11.Cu")
		(net "M_D_CPU1_SA_CB<3>")
	)
	(segment
		(start 38.811708 -274.197572)
		(end 38.811708 -273.835114)
		(width 0.18288)
		(layer "In11.Cu")
		(net "M_D_CPU1_SA_CB<3>")
	)
	(segment
		(start 52.539138 -275.09216)
		(end 50.37201 -275.09216)
		(width 0.18288)
		(layer "In11.Cu")
		(net "M_D_CPU1_SA_CB<3>")
	)
	(segment
		(start 63.27013 -273.435826)
		(end 63.224156 -273.389852)
		(width 0.18288)
		(layer "In11.Cu")
		(net "M_D_CPU1_SA_CB<3>")
	)
	(segment
		(start 47.553626 -275.440394)
		(end 47.553626 -275.782024)
		(width 0.18288)
		(layer "In11.Cu")
		(net "M_D_CPU1_SA_CB<3>")
	)
	(segment
		(start 34.981388 -275.09216)
		(end 34.128964 -275.944584)
		(width 0.18288)
		(layer "In11.Cu")
		(net "M_D_CPU1_SA_CB<3>")
	)
	(segment
		(start 44.186094 -275.315426)
		(end 43.26128 -274.390612)
		(width 0.18288)
		(layer "In11.Cu")
		(net "M_D_CPU1_SA_CB<3>")
	)
	(segment
		(start 54.90464 -274.390612)
		(end 54.327806 -274.390612)
		(width 0.18288)
		(layer "In11.Cu")
		(net "M_D_CPU1_SA_CB<3>")
	)
	(segment
		(start 45.67174 -275.315426)
		(end 44.186094 -275.315426)
		(width 0.18288)
		(layer "In11.Cu")
		(net "M_D_CPU1_SA_CB<3>")
	)
	(segment
		(start 25.557226 -275.188426)
		(end 24.363426 -275.188426)
		(width 0.18288)
		(layer "In11.Cu")
		(net "M_D_CPU1_SA_CB<3>")
	)
	(arc
		(start 88.442292 -264.010902)
		(mid 88.255094 -264.061045)
		(end 88.067896 -264.010902)
		(width 0.088646)
		(layer "In11.Cu")
		(net "M_D_CPU1_SA_CB<3>")
	)
	(arc
		(start 88.067896 -264.010902)
		(mid 87.785194 -263.935126)
		(end 87.502492 -264.010902)
		(width 0.088646)
		(layer "In11.Cu")
		(net "M_D_CPU1_SA_CB<3>")
	)
	(arc
		(start 84.683092 -264.010902)
		(mid 84.495894 -264.061045)
		(end 84.308696 -264.010902)
		(width 0.088646)
		(layer "In11.Cu")
		(net "M_D_CPU1_SA_CB<3>")
	)
	(arc
		(start 94.081346 -264.010902)
		(mid 93.894148 -264.061045)
		(end 93.70695 -264.010902)
		(width 0.088646)
		(layer "In11.Cu")
		(net "M_D_CPU1_SA_CB<3>")
	)
	(arc
		(start 99.462844 -263.318244)
		(mid 99.418845 -263.324511)
		(end 99.374452 -263.326626)
		(width 0.088646)
		(layer "In11.Cu")
		(net "M_D_CPU1_SA_CB<3>")
	)
	(arc
		(start 98.678492 -263.32053)
		(mid 98.662867 -263.31827)
		(end 98.64725 -263.315958)
		(width 0.088646)
		(layer "In11.Cu")
		(net "M_D_CPU1_SA_CB<3>")
	)
	(arc
		(start 95.020892 -264.010902)
		(mid 94.833694 -264.061045)
		(end 94.646496 -264.010902)
		(width 0.088646)
		(layer "In11.Cu")
		(net "M_D_CPU1_SA_CB<3>")
	)
	(arc
		(start 86.188296 -264.010902)
		(mid 85.905594 -263.935126)
		(end 85.622892 -264.010902)
		(width 0.088646)
		(layer "In11.Cu")
		(net "M_D_CPU1_SA_CB<3>")
	)
	(arc
		(start 89.382092 -264.010902)
		(mid 89.194894 -264.061045)
		(end 89.007696 -264.010902)
		(width 0.088646)
		(layer "In11.Cu")
		(net "M_D_CPU1_SA_CB<3>")
	)
	(arc
		(start 98.219006 -263.663684)
		(mid 98.191228 -263.75904)
		(end 98.125026 -263.833102)
		(width 0.088646)
		(layer "In11.Cu")
		(net "M_D_CPU1_SA_CB<3>")
	)
	(arc
		(start 92.201746 -264.010902)
		(mid 92.014548 -264.061045)
		(end 91.82735 -264.010902)
		(width 0.088646)
		(layer "In11.Cu")
		(net "M_D_CPU1_SA_CB<3>")
	)
	(arc
		(start 96.52635 -264.010902)
		(mid 96.252151 -263.935067)
		(end 95.975678 -264.002266)
		(width 0.088646)
		(layer "In11.Cu")
		(net "M_D_CPU1_SA_CB<3>")
	)
	(arc
		(start 98.64725 -263.315958)
		(mid 98.522561 -263.318656)
		(end 98.405696 -263.362186)
		(width 0.088646)
		(layer "In11.Cu")
		(net "M_D_CPU1_SA_CB<3>")
	)
	(arc
		(start 84.308696 -264.010902)
		(mid 84.172327 -263.95446)
		(end 84.025994 -263.93521)
		(width 0.088646)
		(layer "In11.Cu")
		(net "M_D_CPU1_SA_CB<3>")
	)
	(arc
		(start 99.720146 -263.361932)
		(mid 99.595422 -263.316951)
		(end 99.462844 -263.318244)
		(width 0.088646)
		(layer "In11.Cu")
		(net "M_D_CPU1_SA_CB<3>")
	)
	(arc
		(start 95.960946 -264.010902)
		(mid 95.773748 -264.061045)
		(end 95.58655 -264.010902)
		(width 0.088646)
		(layer "In11.Cu")
		(net "M_D_CPU1_SA_CB<3>")
	)
	(arc
		(start 87.128096 -264.010902)
		(mid 86.845394 -263.935126)
		(end 86.562692 -264.010902)
		(width 0.088646)
		(layer "In11.Cu")
		(net "M_D_CPU1_SA_CB<3>")
	)
	(arc
		(start 93.70695 -264.010902)
		(mid 93.432751 -263.935067)
		(end 93.156278 -264.002266)
		(width 0.088646)
		(layer "In11.Cu")
		(net "M_D_CPU1_SA_CB<3>")
	)
	(arc
		(start 92.76715 -264.010902)
		(mid 92.492951 -263.935067)
		(end 92.216478 -264.002266)
		(width 0.088646)
		(layer "In11.Cu")
		(net "M_D_CPU1_SA_CB<3>")
	)
	(arc
		(start 86.562692 -264.010902)
		(mid 86.375494 -264.061045)
		(end 86.188296 -264.010902)
		(width 0.088646)
		(layer "In11.Cu")
		(net "M_D_CPU1_SA_CB<3>")
	)
	(arc
		(start 98.381312 -263.37768)
		(mid 98.267101 -263.501921)
		(end 98.219006 -263.663684)
		(width 0.088646)
		(layer "In11.Cu")
		(net "M_D_CPU1_SA_CB<3>")
	)
	(arc
		(start 97.841308 -264.010648)
		(mid 97.840948 -264.010837)
		(end 97.840546 -264.010902)
		(width 0.088646)
		(layer "In11.Cu")
		(net "M_D_CPU1_SA_CB<3>")
	)
	(arc
		(start 85.622892 -264.010902)
		(mid 85.435694 -264.061045)
		(end 85.248496 -264.010902)
		(width 0.088646)
		(layer "In11.Cu")
		(net "M_D_CPU1_SA_CB<3>")
	)
	(arc
		(start 90.321892 -264.010902)
		(mid 90.134694 -264.061045)
		(end 89.947496 -264.010902)
		(width 0.088646)
		(layer "In11.Cu")
		(net "M_D_CPU1_SA_CB<3>")
	)
	(arc
		(start 89.947496 -264.010902)
		(mid 89.664794 -263.935126)
		(end 89.382092 -264.010902)
		(width 0.088646)
		(layer "In11.Cu")
		(net "M_D_CPU1_SA_CB<3>")
	)
	(arc
		(start 96.900746 -264.010902)
		(mid 96.713548 -264.061045)
		(end 96.52635 -264.010902)
		(width 0.088646)
		(layer "In11.Cu")
		(net "M_D_CPU1_SA_CB<3>")
	)
	(arc
		(start 98.767392 -263.326626)
		(mid 98.722836 -263.325128)
		(end 98.678492 -263.32053)
		(width 0.088646)
		(layer "In11.Cu")
		(net "M_D_CPU1_SA_CB<3>")
	)
	(arc
		(start 95.58655 -264.010902)
		(mid 95.309737 -263.935032)
		(end 95.031306 -264.004806)
		(width 0.088646)
		(layer "In11.Cu")
		(net "M_D_CPU1_SA_CB<3>")
	)
	(arc
		(start 89.007696 -264.010902)
		(mid 88.724994 -263.935126)
		(end 88.442292 -264.010902)
		(width 0.088646)
		(layer "In11.Cu")
		(net "M_D_CPU1_SA_CB<3>")
	)
	(arc
		(start 91.261946 -264.010902)
		(mid 91.074748 -264.061045)
		(end 90.88755 -264.010902)
		(width 0.088646)
		(layer "In11.Cu")
		(net "M_D_CPU1_SA_CB<3>")
	)
	(arc
		(start 93.141546 -264.010902)
		(mid 92.954348 -264.061045)
		(end 92.76715 -264.010902)
		(width 0.088646)
		(layer "In11.Cu")
		(net "M_D_CPU1_SA_CB<3>")
	)
	(arc
		(start 98.405696 -263.362186)
		(mid 98.393319 -263.369643)
		(end 98.381312 -263.37768)
		(width 0.088646)
		(layer "In11.Cu")
		(net "M_D_CPU1_SA_CB<3>")
	)
	(arc
		(start 97.840546 -264.010902)
		(mid 97.653348 -264.061045)
		(end 97.46615 -264.010902)
		(width 0.088646)
		(layer "In11.Cu")
		(net "M_D_CPU1_SA_CB<3>")
	)
	(arc
		(start 87.502492 -264.010902)
		(mid 87.315294 -264.061045)
		(end 87.128096 -264.010902)
		(width 0.088646)
		(layer "In11.Cu")
		(net "M_D_CPU1_SA_CB<3>")
	)
	(arc
		(start 100.472748 -263.686544)
		(mid 100.288683 -263.662121)
		(end 100.117148 -263.59104)
		(width 0.088646)
		(layer "In11.Cu")
		(net "M_D_CPU1_SA_CB<3>")
	)
	(arc
		(start 97.46615 -264.010902)
		(mid 97.191951 -263.935067)
		(end 96.915478 -264.002266)
		(width 0.088646)
		(layer "In11.Cu")
		(net "M_D_CPU1_SA_CB<3>")
	)
	(arc
		(start 85.248496 -264.010902)
		(mid 84.965794 -263.935126)
		(end 84.683092 -264.010902)
		(width 0.088646)
		(layer "In11.Cu")
		(net "M_D_CPU1_SA_CB<3>")
	)
	(arc
		(start 90.88755 -264.010902)
		(mid 90.610737 -263.935032)
		(end 90.332306 -264.004806)
		(width 0.088646)
		(layer "In11.Cu")
		(net "M_D_CPU1_SA_CB<3>")
	)
	(arc
		(start 94.646496 -264.010902)
		(mid 94.369937 -263.935159)
		(end 94.09176 -264.004806)
		(width 0.088646)
		(layer "In11.Cu")
		(net "M_D_CPU1_SA_CB<3>")
	)
	(arc
		(start 91.82735 -264.010902)
		(mid 91.544648 -263.935126)
		(end 91.261946 -264.010902)
		(width 0.088646)
		(layer "In11.Cu")
		(net "M_D_CPU1_SA_CB<3>")
	)
	(arc
		(start 98.125026 -263.833102)
		(mid 98.031619 -263.896382)
		(end 97.935542 -263.95553)
		(width 0.088646)
		(layer "In11.Cu")
		(net "M_D_CPU1_SA_CB<3>")
	)
	(segment
		(start 16.885158 -277.641812)
		(end 17.518126 -277.641812)
		(width 0.20066)
		(layer "F.Cu")
		(net "M_D_CPU1_SA_CB<2>")
	)
	(segment
		(start 100.002594 -263.964674)
		(end 100.002594 -264.50036)
		(width 0.20066)
		(layer "F.Cu")
		(net "M_D_CPU1_SA_CB<2>")
	)
	(segment
		(start 17.66189 -277.785576)
		(end 17.66189 -278.111204)
		(width 0.20066)
		(layer "F.Cu")
		(net "M_D_CPU1_SA_CB<2>")
	)
	(segment
		(start 14.560042 -277.631652)
		(end 14.570202 -277.641812)
		(width 0.101854)
		(layer "F.Cu")
		(net "M_D_CPU1_SA_CB<2>")
	)
	(segment
		(start 17.66189 -278.111204)
		(end 17.829276 -278.27859)
		(width 0.20066)
		(layer "F.Cu")
		(net "M_D_CPU1_SA_CB<2>")
	)
	(segment
		(start 13.82268 -277.631652)
		(end 14.560042 -277.631652)
		(width 0.20066)
		(layer "F.Cu")
		(net "M_D_CPU1_SA_CB<2>")
	)
	(segment
		(start 14.825218 -277.641812)
		(end 16.885158 -277.641812)
		(width 0.1016)
		(layer "F.Cu")
		(net "M_D_CPU1_SA_CB<2>")
	)
	(segment
		(start 18.46961 -278.066754)
		(end 19.784314 -278.066754)
		(width 0.20066)
		(layer "F.Cu")
		(net "M_D_CPU1_SA_CB<2>")
	)
	(segment
		(start 18.257774 -278.27859)
		(end 18.46961 -278.066754)
		(width 0.20066)
		(layer "F.Cu")
		(net "M_D_CPU1_SA_CB<2>")
	)
	(segment
		(start 14.570202 -277.641812)
		(end 14.825218 -277.641812)
		(width 0.101854)
		(layer "F.Cu")
		(net "M_D_CPU1_SA_CB<2>")
	)
	(segment
		(start 17.829276 -278.27859)
		(end 18.257774 -278.27859)
		(width 0.20066)
		(layer "F.Cu")
		(net "M_D_CPU1_SA_CB<2>")
	)
	(segment
		(start 17.518126 -277.641812)
		(end 17.66189 -277.785576)
		(width 0.20066)
		(layer "F.Cu")
		(net "M_D_CPU1_SA_CB<2>")
	)
	(segment
		(start 20.889214 -278.066754)
		(end 19.784314 -278.066754)
		(width 0.20066)
		(layer "F.Cu")
		(net "M_D_CPU1_SA_CB<2>")
	)
	(segment
		(start 13.387578 -278.066754)
		(end 13.82268 -277.631652)
		(width 0.20066)
		(layer "F.Cu")
		(net "M_D_CPU1_SA_CB<2>")
	)
	(segment
		(start 100.002848 -263.96442)
		(end 100.002594 -263.964674)
		(width 0.20066)
		(layer "F.Cu")
		(net "M_D_CPU1_SA_CB<2>")
	)
	(segment
		(start 12.240514 -278.066754)
		(end 13.387578 -278.066754)
		(width 0.20066)
		(layer "F.Cu")
		(net "M_D_CPU1_SA_CB<2>")
	)
	(segment
		(start 83.215988 -265.422634)
		(end 83.013804 -265.422634)
		(width 0.088646)
		(layer "In11.Cu")
		(net "M_D_CPU1_SA_CB<2>")
	)
	(segment
		(start 57.580276 -275.827998)
		(end 57.265316 -275.827998)
		(width 0.18288)
		(layer "In11.Cu")
		(net "M_D_CPU1_SA_CB<2>")
	)
	(segment
		(start 53.689758 -276.11324)
		(end 53.378354 -276.424644)
		(width 0.18288)
		(layer "In11.Cu")
		(net "M_D_CPU1_SA_CB<2>")
	)
	(segment
		(start 57.966356 -274.934426)
		(end 57.773316 -275.127466)
		(width 0.18288)
		(layer "In11.Cu")
		(net "M_D_CPU1_SA_CB<2>")
	)
	(segment
		(start 21.96211 -278.512778)
		(end 21.516086 -278.066754)
		(width 0.18288)
		(layer "In11.Cu")
		(net "M_D_CPU1_SA_CB<2>")
	)
	(segment
		(start 57.773316 -275.127466)
		(end 57.773316 -275.634958)
		(width 0.18288)
		(layer "In11.Cu")
		(net "M_D_CPU1_SA_CB<2>")
	)
	(segment
		(start 100.002594 -264.50036)
		(end 99.68992 -264.50036)
		(width 0.088646)
		(layer "In11.Cu")
		(net "M_D_CPU1_SA_CB<2>")
	)
	(segment
		(start 51.528726 -276.792944)
		(end 50.406808 -276.792944)
		(width 0.18288)
		(layer "In11.Cu")
		(net "M_D_CPU1_SA_CB<2>")
	)
	(segment
		(start 53.849778 -275.493226)
		(end 53.689758 -275.653246)
		(width 0.18288)
		(layer "In11.Cu")
		(net "M_D_CPU1_SA_CB<2>")
	)
	(segment
		(start 47.385986 -277.642066)
		(end 46.588172 -277.642066)
		(width 0.18288)
		(layer "In11.Cu")
		(net "M_D_CPU1_SA_CB<2>")
	)
	(segment
		(start 40.543226 -275.696426)
		(end 38.615112 -275.696426)
		(width 0.18288)
		(layer "In11.Cu")
		(net "M_D_CPU1_SA_CB<2>")
	)
	(segment
		(start 96.056196 -264.824718)
		(end 96.041464 -264.816082)
		(width 0.088646)
		(layer "In11.Cu")
		(net "M_D_CPU1_SA_CB<2>")
	)
	(segment
		(start 56.879236 -274.934426)
		(end 55.935626 -274.934426)
		(width 0.18288)
		(layer "In11.Cu")
		(net "M_D_CPU1_SA_CB<2>")
	)
	(segment
		(start 95.116396 -264.824718)
		(end 95.101664 -264.816082)
		(width 0.088646)
		(layer "In11.Cu")
		(net "M_D_CPU1_SA_CB<2>")
	)
	(segment
		(start 27.06497 -277.239222)
		(end 27.06497 -276.880066)
		(width 0.18288)
		(layer "In11.Cu")
		(net "M_D_CPU1_SA_CB<2>")
	)
	(segment
		(start 50.126392 -277.07336)
		(end 49.718468 -277.07336)
		(width 0.18288)
		(layer "In11.Cu")
		(net "M_D_CPU1_SA_CB<2>")
	)
	(segment
		(start 96.995996 -264.824718)
		(end 96.981264 -264.816082)
		(width 0.088646)
		(layer "In11.Cu")
		(net "M_D_CPU1_SA_CB<2>")
	)
	(segment
		(start 53.689758 -275.653246)
		(end 53.689758 -276.11324)
		(width 0.18288)
		(layer "In11.Cu")
		(net "M_D_CPU1_SA_CB<2>")
	)
	(segment
		(start 30.844998 -276.890226)
		(end 29.240226 -276.890226)
		(width 0.18288)
		(layer "In11.Cu")
		(net "M_D_CPU1_SA_CB<2>")
	)
	(segment
		(start 29.240226 -276.890226)
		(end 29.037026 -276.687026)
		(width 0.18288)
		(layer "In11.Cu")
		(net "M_D_CPU1_SA_CB<2>")
	)
	(segment
		(start 97.93605 -264.824718)
		(end 97.925636 -264.818622)
		(width 0.088646)
		(layer "In11.Cu")
		(net "M_D_CPU1_SA_CB<2>")
	)
	(segment
		(start 29.037026 -276.687026)
		(end 27.95905 -276.687026)
		(width 0.18288)
		(layer "In11.Cu")
		(net "M_D_CPU1_SA_CB<2>")
	)
	(segment
		(start 48.724312 -276.780244)
		(end 48.247808 -276.780244)
		(width 0.18288)
		(layer "In11.Cu")
		(net "M_D_CPU1_SA_CB<2>")
	)
	(segment
		(start 37.518086 -276.793452)
		(end 34.97961 -276.793452)
		(width 0.18288)
		(layer "In11.Cu")
		(net "M_D_CPU1_SA_CB<2>")
	)
	(segment
		(start 31.599378 -277.644606)
		(end 30.844998 -276.890226)
		(width 0.18288)
		(layer "In11.Cu")
		(net "M_D_CPU1_SA_CB<2>")
	)
	(segment
		(start 93.236796 -264.824718)
		(end 93.222064 -264.816082)
		(width 0.088646)
		(layer "In11.Cu")
		(net "M_D_CPU1_SA_CB<2>")
	)
	(segment
		(start 67.174618 -274.461986)
		(end 63.267082 -274.461986)
		(width 0.18288)
		(layer "In11.Cu")
		(net "M_D_CPU1_SA_CB<2>")
	)
	(segment
		(start 62.794642 -274.934426)
		(end 57.966356 -274.934426)
		(width 0.18288)
		(layer "In11.Cu")
		(net "M_D_CPU1_SA_CB<2>")
	)
	(segment
		(start 49.017428 -276.487128)
		(end 48.724312 -276.780244)
		(width 0.18288)
		(layer "In11.Cu")
		(net "M_D_CPU1_SA_CB<2>")
	)
	(segment
		(start 76.21397 -265.422634)
		(end 67.174618 -274.461986)
		(width 0.18288)
		(layer "In11.Cu")
		(net "M_D_CPU1_SA_CB<2>")
	)
	(segment
		(start 94.176596 -264.824718)
		(end 94.161864 -264.816082)
		(width 0.088646)
		(layer "In11.Cu")
		(net "M_D_CPU1_SA_CB<2>")
	)
	(segment
		(start 27.57297 -277.432262)
		(end 27.25801 -277.432262)
		(width 0.18288)
		(layer "In11.Cu")
		(net "M_D_CPU1_SA_CB<2>")
	)
	(segment
		(start 51.691032 -276.95525)
		(end 51.528726 -276.792944)
		(width 0.18288)
		(layer "In11.Cu")
		(net "M_D_CPU1_SA_CB<2>")
	)
	(segment
		(start 53.378354 -276.424644)
		(end 52.824126 -276.424644)
		(width 0.18288)
		(layer "In11.Cu")
		(net "M_D_CPU1_SA_CB<2>")
	)
	(segment
		(start 98.795078 -264.002266)
		(end 98.780346 -264.010902)
		(width 0.088646)
		(layer "In11.Cu")
		(net "M_D_CPU1_SA_CB<2>")
	)
	(segment
		(start 42.52341 -276.102826)
		(end 40.949626 -276.102826)
		(width 0.18288)
		(layer "In11.Cu")
		(net "M_D_CPU1_SA_CB<2>")
	)
	(segment
		(start 57.265316 -275.827998)
		(end 57.072276 -275.634958)
		(width 0.18288)
		(layer "In11.Cu")
		(net "M_D_CPU1_SA_CB<2>")
	)
	(segment
		(start 38.615112 -275.696426)
		(end 37.518086 -276.793452)
		(width 0.18288)
		(layer "In11.Cu")
		(net "M_D_CPU1_SA_CB<2>")
	)
	(segment
		(start 50.406808 -276.792944)
		(end 50.126392 -277.07336)
		(width 0.18288)
		(layer "In11.Cu")
		(net "M_D_CPU1_SA_CB<2>")
	)
	(segment
		(start 52.29352 -276.95525)
		(end 51.691032 -276.95525)
		(width 0.18288)
		(layer "In11.Cu")
		(net "M_D_CPU1_SA_CB<2>")
	)
	(segment
		(start 43.972226 -276.560026)
		(end 42.98061 -276.560026)
		(width 0.18288)
		(layer "In11.Cu")
		(net "M_D_CPU1_SA_CB<2>")
	)
	(segment
		(start 91.74226 -264.818622)
		(end 91.731846 -264.824718)
		(width 0.088646)
		(layer "In11.Cu")
		(net "M_D_CPU1_SA_CB<2>")
	)
	(segment
		(start 27.76601 -277.239222)
		(end 27.57297 -277.432262)
		(width 0.18288)
		(layer "In11.Cu")
		(net "M_D_CPU1_SA_CB<2>")
	)
	(segment
		(start 49.718468 -277.07336)
		(end 49.57191 -276.926802)
		(width 0.18288)
		(layer "In11.Cu")
		(net "M_D_CPU1_SA_CB<2>")
	)
	(segment
		(start 83.013804 -265.422634)
		(end 76.21397 -265.422634)
		(width 0.18288)
		(layer "In11.Cu")
		(net "M_D_CPU1_SA_CB<2>")
	)
	(segment
		(start 49.425352 -276.487128)
		(end 49.017428 -276.487128)
		(width 0.18288)
		(layer "In11.Cu")
		(net "M_D_CPU1_SA_CB<2>")
	)
	(segment
		(start 46.063408 -277.424642)
		(end 45.554392 -276.915626)
		(width 0.18288)
		(layer "In11.Cu")
		(net "M_D_CPU1_SA_CB<2>")
	)
	(segment
		(start 99.68992 -264.50036)
		(end 99.624388 -264.434828)
		(width 0.088646)
		(layer "In11.Cu")
		(net "M_D_CPU1_SA_CB<2>")
	)
	(segment
		(start 44.327826 -276.915626)
		(end 43.972226 -276.560026)
		(width 0.18288)
		(layer "In11.Cu")
		(net "M_D_CPU1_SA_CB<2>")
	)
	(segment
		(start 45.554392 -276.915626)
		(end 44.327826 -276.915626)
		(width 0.18288)
		(layer "In11.Cu")
		(net "M_D_CPU1_SA_CB<2>")
	)
	(segment
		(start 52.824126 -276.424644)
		(end 52.29352 -276.95525)
		(width 0.18288)
		(layer "In11.Cu")
		(net "M_D_CPU1_SA_CB<2>")
	)
	(segment
		(start 57.773316 -275.634958)
		(end 57.580276 -275.827998)
		(width 0.18288)
		(layer "In11.Cu")
		(net "M_D_CPU1_SA_CB<2>")
	)
	(segment
		(start 98.780346 -264.010902)
		(end 98.77425 -264.014458)
		(width 0.088646)
		(layer "In11.Cu")
		(net "M_D_CPU1_SA_CB<2>")
	)
	(segment
		(start 91.35745 -264.824718)
		(end 91.347036 -264.818622)
		(width 0.088646)
		(layer "In11.Cu")
		(net "M_D_CPU1_SA_CB<2>")
	)
	(segment
		(start 25.811226 -276.687026)
		(end 24.998426 -277.499826)
		(width 0.18288)
		(layer "In11.Cu")
		(net "M_D_CPU1_SA_CB<2>")
	)
	(segment
		(start 48.247808 -276.780244)
		(end 47.385986 -277.642066)
		(width 0.18288)
		(layer "In11.Cu")
		(net "M_D_CPU1_SA_CB<2>")
	)
	(segment
		(start 57.072276 -275.127466)
		(end 56.879236 -274.934426)
		(width 0.18288)
		(layer "In11.Cu")
		(net "M_D_CPU1_SA_CB<2>")
	)
	(segment
		(start 24.998426 -277.499826)
		(end 23.52294 -277.499826)
		(width 0.18288)
		(layer "In11.Cu")
		(net "M_D_CPU1_SA_CB<2>")
	)
	(segment
		(start 27.06497 -276.880066)
		(end 26.87193 -276.687026)
		(width 0.18288)
		(layer "In11.Cu")
		(net "M_D_CPU1_SA_CB<2>")
	)
	(segment
		(start 55.935626 -274.934426)
		(end 55.376826 -275.493226)
		(width 0.18288)
		(layer "In11.Cu")
		(net "M_D_CPU1_SA_CB<2>")
	)
	(segment
		(start 83.763358 -264.875264)
		(end 83.215988 -265.422634)
		(width 0.088646)
		(layer "In11.Cu")
		(net "M_D_CPU1_SA_CB<2>")
	)
	(segment
		(start 22.509988 -278.512778)
		(end 21.96211 -278.512778)
		(width 0.18288)
		(layer "In11.Cu")
		(net "M_D_CPU1_SA_CB<2>")
	)
	(segment
		(start 84.025994 -264.875264)
		(end 83.763358 -264.875264)
		(width 0.088646)
		(layer "In11.Cu")
		(net "M_D_CPU1_SA_CB<2>")
	)
	(segment
		(start 49.57191 -276.926802)
		(end 49.57191 -276.633686)
		(width 0.18288)
		(layer "In11.Cu")
		(net "M_D_CPU1_SA_CB<2>")
	)
	(segment
		(start 21.516086 -278.066754)
		(end 20.889214 -278.066754)
		(width 0.18288)
		(layer "In11.Cu")
		(net "M_D_CPU1_SA_CB<2>")
	)
	(segment
		(start 27.25801 -277.432262)
		(end 27.06497 -277.239222)
		(width 0.18288)
		(layer "In11.Cu")
		(net "M_D_CPU1_SA_CB<2>")
	)
	(segment
		(start 27.76601 -276.880066)
		(end 27.76601 -277.239222)
		(width 0.18288)
		(layer "In11.Cu")
		(net "M_D_CPU1_SA_CB<2>")
	)
	(segment
		(start 23.52294 -277.499826)
		(end 22.509988 -278.512778)
		(width 0.18288)
		(layer "In11.Cu")
		(net "M_D_CPU1_SA_CB<2>")
	)
	(segment
		(start 57.072276 -275.634958)
		(end 57.072276 -275.127466)
		(width 0.18288)
		(layer "In11.Cu")
		(net "M_D_CPU1_SA_CB<2>")
	)
	(segment
		(start 49.57191 -276.633686)
		(end 49.425352 -276.487128)
		(width 0.18288)
		(layer "In11.Cu")
		(net "M_D_CPU1_SA_CB<2>")
	)
	(segment
		(start 46.588172 -277.642066)
		(end 46.063408 -277.424642)
		(width 0.18288)
		(layer "In11.Cu")
		(net "M_D_CPU1_SA_CB<2>")
	)
	(segment
		(start 40.949626 -276.102826)
		(end 40.543226 -275.696426)
		(width 0.18288)
		(layer "In11.Cu")
		(net "M_D_CPU1_SA_CB<2>")
	)
	(segment
		(start 98.497644 -264.50036)
		(end 98.497644 -264.508996)
		(width 0.088646)
		(layer "In11.Cu")
		(net "M_D_CPU1_SA_CB<2>")
	)
	(segment
		(start 34.97961 -276.793452)
		(end 34.128456 -277.644606)
		(width 0.18288)
		(layer "In11.Cu")
		(net "M_D_CPU1_SA_CB<2>")
	)
	(segment
		(start 34.128456 -277.644606)
		(end 31.599378 -277.644606)
		(width 0.18288)
		(layer "In11.Cu")
		(net "M_D_CPU1_SA_CB<2>")
	)
	(segment
		(start 63.267082 -274.461986)
		(end 62.794642 -274.934426)
		(width 0.18288)
		(layer "In11.Cu")
		(net "M_D_CPU1_SA_CB<2>")
	)
	(segment
		(start 26.87193 -276.687026)
		(end 25.811226 -276.687026)
		(width 0.18288)
		(layer "In11.Cu")
		(net "M_D_CPU1_SA_CB<2>")
	)
	(segment
		(start 42.98061 -276.560026)
		(end 42.52341 -276.102826)
		(width 0.18288)
		(layer "In11.Cu")
		(net "M_D_CPU1_SA_CB<2>")
	)
	(segment
		(start 55.376826 -275.493226)
		(end 53.849778 -275.493226)
		(width 0.18288)
		(layer "In11.Cu")
		(net "M_D_CPU1_SA_CB<2>")
	)
	(segment
		(start 27.95905 -276.687026)
		(end 27.76601 -276.880066)
		(width 0.18288)
		(layer "In11.Cu")
		(net "M_D_CPU1_SA_CB<2>")
	)
	(arc
		(start 95.490792 -264.824718)
		(mid 95.303594 -264.874861)
		(end 95.116396 -264.824718)
		(width 0.088646)
		(layer "In11.Cu")
		(net "M_D_CPU1_SA_CB<2>")
	)
	(arc
		(start 98.77425 -264.014458)
		(mid 98.571663 -264.220809)
		(end 98.497644 -264.50036)
		(width 0.088646)
		(layer "In11.Cu")
		(net "M_D_CPU1_SA_CB<2>")
	)
	(arc
		(start 88.537796 -264.824718)
		(mid 88.255094 -264.748942)
		(end 87.972392 -264.824718)
		(width 0.088646)
		(layer "In11.Cu")
		(net "M_D_CPU1_SA_CB<2>")
	)
	(arc
		(start 85.152992 -264.824718)
		(mid 84.965794 -264.874861)
		(end 84.778596 -264.824718)
		(width 0.088646)
		(layer "In11.Cu")
		(net "M_D_CPU1_SA_CB<2>")
	)
	(arc
		(start 92.671392 -264.824718)
		(mid 92.484194 -264.874861)
		(end 92.296996 -264.824718)
		(width 0.088646)
		(layer "In11.Cu")
		(net "M_D_CPU1_SA_CB<2>")
	)
	(arc
		(start 87.972392 -264.824718)
		(mid 87.785194 -264.874861)
		(end 87.597996 -264.824718)
		(width 0.088646)
		(layer "In11.Cu")
		(net "M_D_CPU1_SA_CB<2>")
	)
	(arc
		(start 84.213192 -264.824718)
		(mid 84.12292 -264.862317)
		(end 84.025994 -264.875264)
		(width 0.088646)
		(layer "In11.Cu")
		(net "M_D_CPU1_SA_CB<2>")
	)
	(arc
		(start 98.497644 -264.508996)
		(mid 98.445374 -264.691361)
		(end 98.310446 -264.824718)
		(width 0.088646)
		(layer "In11.Cu")
		(net "M_D_CPU1_SA_CB<2>")
	)
	(arc
		(start 89.851992 -264.824718)
		(mid 89.664794 -264.874861)
		(end 89.477596 -264.824718)
		(width 0.088646)
		(layer "In11.Cu")
		(net "M_D_CPU1_SA_CB<2>")
	)
	(arc
		(start 96.430592 -264.824718)
		(mid 96.243394 -264.874861)
		(end 96.056196 -264.824718)
		(width 0.088646)
		(layer "In11.Cu")
		(net "M_D_CPU1_SA_CB<2>")
	)
	(arc
		(start 96.981264 -264.816082)
		(mid 96.704789 -264.748762)
		(end 96.430592 -264.824718)
		(width 0.088646)
		(layer "In11.Cu")
		(net "M_D_CPU1_SA_CB<2>")
	)
	(arc
		(start 87.032592 -264.824718)
		(mid 86.845394 -264.874861)
		(end 86.658196 -264.824718)
		(width 0.088646)
		(layer "In11.Cu")
		(net "M_D_CPU1_SA_CB<2>")
	)
	(arc
		(start 86.092792 -264.824718)
		(mid 85.905594 -264.874861)
		(end 85.718396 -264.824718)
		(width 0.088646)
		(layer "In11.Cu")
		(net "M_D_CPU1_SA_CB<2>")
	)
	(arc
		(start 94.550992 -264.824718)
		(mid 94.363794 -264.874861)
		(end 94.176596 -264.824718)
		(width 0.088646)
		(layer "In11.Cu")
		(net "M_D_CPU1_SA_CB<2>")
	)
	(arc
		(start 99.624388 -264.434828)
		(mid 99.5353 -264.189843)
		(end 99.34575 -264.010902)
		(width 0.088646)
		(layer "In11.Cu")
		(net "M_D_CPU1_SA_CB<2>")
	)
	(arc
		(start 84.778596 -264.824718)
		(mid 84.495894 -264.748942)
		(end 84.213192 -264.824718)
		(width 0.088646)
		(layer "In11.Cu")
		(net "M_D_CPU1_SA_CB<2>")
	)
	(arc
		(start 89.477596 -264.824718)
		(mid 89.194894 -264.748942)
		(end 88.912192 -264.824718)
		(width 0.088646)
		(layer "In11.Cu")
		(net "M_D_CPU1_SA_CB<2>")
	)
	(arc
		(start 87.597996 -264.824718)
		(mid 87.315294 -264.748942)
		(end 87.032592 -264.824718)
		(width 0.088646)
		(layer "In11.Cu")
		(net "M_D_CPU1_SA_CB<2>")
	)
	(arc
		(start 94.161864 -264.816082)
		(mid 93.885389 -264.748762)
		(end 93.611192 -264.824718)
		(width 0.088646)
		(layer "In11.Cu")
		(net "M_D_CPU1_SA_CB<2>")
	)
	(arc
		(start 99.34575 -264.010902)
		(mid 99.071551 -263.935067)
		(end 98.795078 -264.002266)
		(width 0.088646)
		(layer "In11.Cu")
		(net "M_D_CPU1_SA_CB<2>")
	)
	(arc
		(start 91.731846 -264.824718)
		(mid 91.544648 -264.874861)
		(end 91.35745 -264.824718)
		(width 0.088646)
		(layer "In11.Cu")
		(net "M_D_CPU1_SA_CB<2>")
	)
	(arc
		(start 93.222064 -264.816082)
		(mid 92.945589 -264.748762)
		(end 92.671392 -264.824718)
		(width 0.088646)
		(layer "In11.Cu")
		(net "M_D_CPU1_SA_CB<2>")
	)
	(arc
		(start 98.310446 -264.824718)
		(mid 98.123248 -264.874861)
		(end 97.93605 -264.824718)
		(width 0.088646)
		(layer "In11.Cu")
		(net "M_D_CPU1_SA_CB<2>")
	)
	(arc
		(start 88.912192 -264.824718)
		(mid 88.724994 -264.874861)
		(end 88.537796 -264.824718)
		(width 0.088646)
		(layer "In11.Cu")
		(net "M_D_CPU1_SA_CB<2>")
	)
	(arc
		(start 91.347036 -264.818622)
		(mid 91.068604 -264.748776)
		(end 90.791792 -264.824718)
		(width 0.088646)
		(layer "In11.Cu")
		(net "M_D_CPU1_SA_CB<2>")
	)
	(arc
		(start 90.791792 -264.824718)
		(mid 90.604594 -264.874861)
		(end 90.417396 -264.824718)
		(width 0.088646)
		(layer "In11.Cu")
		(net "M_D_CPU1_SA_CB<2>")
	)
	(arc
		(start 92.296996 -264.824718)
		(mid 92.020437 -264.748975)
		(end 91.74226 -264.818622)
		(width 0.088646)
		(layer "In11.Cu")
		(net "M_D_CPU1_SA_CB<2>")
	)
	(arc
		(start 90.417396 -264.824718)
		(mid 90.134694 -264.748942)
		(end 89.851992 -264.824718)
		(width 0.088646)
		(layer "In11.Cu")
		(net "M_D_CPU1_SA_CB<2>")
	)
	(arc
		(start 97.370392 -264.824718)
		(mid 97.183194 -264.874861)
		(end 96.995996 -264.824718)
		(width 0.088646)
		(layer "In11.Cu")
		(net "M_D_CPU1_SA_CB<2>")
	)
	(arc
		(start 96.041464 -264.816082)
		(mid 95.764989 -264.748762)
		(end 95.490792 -264.824718)
		(width 0.088646)
		(layer "In11.Cu")
		(net "M_D_CPU1_SA_CB<2>")
	)
	(arc
		(start 93.611192 -264.824718)
		(mid 93.423994 -264.874861)
		(end 93.236796 -264.824718)
		(width 0.088646)
		(layer "In11.Cu")
		(net "M_D_CPU1_SA_CB<2>")
	)
	(arc
		(start 86.658196 -264.824718)
		(mid 86.375494 -264.748942)
		(end 86.092792 -264.824718)
		(width 0.088646)
		(layer "In11.Cu")
		(net "M_D_CPU1_SA_CB<2>")
	)
	(arc
		(start 85.718396 -264.824718)
		(mid 85.435694 -264.748942)
		(end 85.152992 -264.824718)
		(width 0.088646)
		(layer "In11.Cu")
		(net "M_D_CPU1_SA_CB<2>")
	)
	(arc
		(start 95.101664 -264.816082)
		(mid 94.825189 -264.748762)
		(end 94.550992 -264.824718)
		(width 0.088646)
		(layer "In11.Cu")
		(net "M_D_CPU1_SA_CB<2>")
	)
	(arc
		(start 97.925636 -264.818622)
		(mid 97.647204 -264.748776)
		(end 97.370392 -264.824718)
		(width 0.088646)
		(layer "In11.Cu")
		(net "M_D_CPU1_SA_CB<2>")
	)
	(segment
		(start 10.344912 -276.945344)
		(end 10.507472 -276.782784)
		(width 0.20066)
		(layer "F.Cu")
		(net "M_D_CPU1_SA_CB<1>")
	)
	(segment
		(start 16.789146 -277.216616)
		(end 15.684246 -277.216616)
		(width 0.20066)
		(layer "F.Cu")
		(net "M_D_CPU1_SA_CB<1>")
	)
	(segment
		(start 13.110718 -276.791674)
		(end 13.441426 -276.791674)
		(width 0.101854)
		(layer "F.Cu")
		(net "M_D_CPU1_SA_CB<1>")
	)
	(segment
		(start 10.507472 -276.782784)
		(end 11.11631 -276.782784)
		(width 0.20066)
		(layer "F.Cu")
		(net "M_D_CPU1_SA_CB<1>")
	)
	(segment
		(start 13.441426 -276.791674)
		(end 13.619988 -276.791674)
		(width 0.20066)
		(layer "F.Cu")
		(net "M_D_CPU1_SA_CB<1>")
	)
	(segment
		(start 13.619988 -276.791674)
		(end 14.04493 -277.216616)
		(width 0.20066)
		(layer "F.Cu")
		(net "M_D_CPU1_SA_CB<1>")
	)
	(segment
		(start 9.686036 -277.427944)
		(end 10.19048 -277.427944)
		(width 0.20066)
		(layer "F.Cu")
		(net "M_D_CPU1_SA_CB<1>")
	)
	(segment
		(start 9.474708 -277.216616)
		(end 9.686036 -277.427944)
		(width 0.20066)
		(layer "F.Cu")
		(net "M_D_CPU1_SA_CB<1>")
	)
	(segment
		(start 10.19048 -277.427944)
		(end 10.344912 -277.273512)
		(width 0.20066)
		(layer "F.Cu")
		(net "M_D_CPU1_SA_CB<1>")
	)
	(segment
		(start 11.1252 -276.791674)
		(end 13.110718 -276.791674)
		(width 0.1016)
		(layer "F.Cu")
		(net "M_D_CPU1_SA_CB<1>")
	)
	(segment
		(start 14.04493 -277.216616)
		(end 15.684246 -277.216616)
		(width 0.20066)
		(layer "F.Cu")
		(net "M_D_CPU1_SA_CB<1>")
	)
	(segment
		(start 11.11631 -276.782784)
		(end 11.1252 -276.791674)
		(width 0.1016)
		(layer "F.Cu")
		(net "M_D_CPU1_SA_CB<1>")
	)
	(segment
		(start 8.140446 -277.216616)
		(end 9.474708 -277.216616)
		(width 0.20066)
		(layer "F.Cu")
		(net "M_D_CPU1_SA_CB<1>")
	)
	(segment
		(start 98.592894 -263.68629)
		(end 98.593148 -263.686544)
		(width 0.20066)
		(layer "F.Cu")
		(net "M_D_CPU1_SA_CB<1>")
	)
	(segment
		(start 10.344912 -277.273512)
		(end 10.344912 -276.945344)
		(width 0.20066)
		(layer "F.Cu")
		(net "M_D_CPU1_SA_CB<1>")
	)
	(segment
		(start 98.592894 -263.150604)
		(end 98.592894 -263.68629)
		(width 0.20066)
		(layer "F.Cu")
		(net "M_D_CPU1_SA_CB<1>")
	)
	(segment
		(start 18.579084 -278.317452)
		(end 18.264124 -278.317452)
		(width 0.18288)
		(layer "In11.Cu")
		(net "M_D_CPU1_SA_CB<1>")
	)
	(segment
		(start 34.982912 -275.940266)
		(end 34.134806 -276.788372)
		(width 0.18288)
		(layer "In11.Cu")
		(net "M_D_CPU1_SA_CB<1>")
	)
	(segment
		(start 91.35745 -264.176002)
		(end 91.347036 -264.182098)
		(width 0.088646)
		(layer "In11.Cu")
		(net "M_D_CPU1_SA_CB<1>")
	)
	(segment
		(start 30.627828 -275.823426)
		(end 29.519626 -275.823426)
		(width 0.18288)
		(layer "In11.Cu")
		(net "M_D_CPU1_SA_CB<1>")
	)
	(segment
		(start 21.430234 -277.449026)
		(end 21.237956 -277.641304)
		(width 0.18288)
		(layer "In11.Cu")
		(net "M_D_CPU1_SA_CB<1>")
	)
	(segment
		(start 31.592774 -276.788372)
		(end 30.627828 -275.823426)
		(width 0.18288)
		(layer "In11.Cu")
		(net "M_D_CPU1_SA_CB<1>")
	)
	(segment
		(start 18.965164 -277.641304)
		(end 18.772124 -277.834344)
		(width 0.18288)
		(layer "In11.Cu")
		(net "M_D_CPU1_SA_CB<1>")
	)
	(segment
		(start 55.737252 -274.3708)
		(end 55.148226 -274.959826)
		(width 0.18288)
		(layer "In11.Cu")
		(net "M_D_CPU1_SA_CB<1>")
	)
	(segment
		(start 46.280832 -276.791928)
		(end 45.351446 -275.862542)
		(width 0.18288)
		(layer "In11.Cu")
		(net "M_D_CPU1_SA_CB<1>")
	)
	(segment
		(start 51.714908 -275.780754)
		(end 51.552348 -275.943314)
		(width 0.18288)
		(layer "In11.Cu")
		(net "M_D_CPU1_SA_CB<1>")
	)
	(segment
		(start 18.772124 -277.834344)
		(end 18.772124 -278.124412)
		(width 0.18288)
		(layer "In11.Cu")
		(net "M_D_CPU1_SA_CB<1>")
	)
	(segment
		(start 98.031808 -264.119868)
		(end 97.925636 -264.182098)
		(width 0.088646)
		(layer "In11.Cu")
		(net "M_D_CPU1_SA_CB<1>")
	)
	(segment
		(start 62.551056 -274.3708)
		(end 55.737252 -274.3708)
		(width 0.18288)
		(layer "In11.Cu")
		(net "M_D_CPU1_SA_CB<1>")
	)
	(segment
		(start 48.29683 -275.943314)
		(end 47.448216 -276.791928)
		(width 0.18288)
		(layer "In11.Cu")
		(net "M_D_CPU1_SA_CB<1>")
	)
	(segment
		(start 18.071084 -278.124412)
		(end 18.071084 -277.834344)
		(width 0.18288)
		(layer "In11.Cu")
		(net "M_D_CPU1_SA_CB<1>")
	)
	(segment
		(start 44.31411 -275.862542)
		(end 44.163996 -276.012656)
		(width 0.18288)
		(layer "In11.Cu")
		(net "M_D_CPU1_SA_CB<1>")
	)
	(segment
		(start 34.134806 -276.788372)
		(end 31.592774 -276.788372)
		(width 0.18288)
		(layer "In11.Cu")
		(net "M_D_CPU1_SA_CB<1>")
	)
	(segment
		(start 53.487574 -274.959826)
		(end 52.666646 -275.780754)
		(width 0.18288)
		(layer "In11.Cu")
		(net "M_D_CPU1_SA_CB<1>")
	)
	(segment
		(start 29.519626 -275.823426)
		(end 29.240226 -276.102826)
		(width 0.18288)
		(layer "In11.Cu")
		(net "M_D_CPU1_SA_CB<1>")
	)
	(segment
		(start 43.198288 -276.012656)
		(end 42.109644 -274.924012)
		(width 0.18288)
		(layer "In11.Cu")
		(net "M_D_CPU1_SA_CB<1>")
	)
	(segment
		(start 55.148226 -274.959826)
		(end 53.487574 -274.959826)
		(width 0.18288)
		(layer "In11.Cu")
		(net "M_D_CPU1_SA_CB<1>")
	)
	(segment
		(start 92.296996 -264.176002)
		(end 92.286582 -264.182098)
		(width 0.088646)
		(layer "In11.Cu")
		(net "M_D_CPU1_SA_CB<1>")
	)
	(segment
		(start 96.056196 -264.176002)
		(end 96.041464 -264.184638)
		(width 0.088646)
		(layer "In11.Cu")
		(net "M_D_CPU1_SA_CB<1>")
	)
	(segment
		(start 36.855654 -275.67509)
		(end 36.590478 -275.940266)
		(width 0.18288)
		(layer "In11.Cu")
		(net "M_D_CPU1_SA_CB<1>")
	)
	(segment
		(start 17.878044 -277.641304)
		(end 17.213834 -277.641304)
		(width 0.18288)
		(layer "In11.Cu")
		(net "M_D_CPU1_SA_CB<1>")
	)
	(segment
		(start 38.526466 -274.924012)
		(end 37.775388 -275.67509)
		(width 0.18288)
		(layer "In11.Cu")
		(net "M_D_CPU1_SA_CB<1>")
	)
	(segment
		(start 40.033702 -275.118068)
		(end 39.534338 -275.118068)
		(width 0.18288)
		(layer "In11.Cu")
		(net "M_D_CPU1_SA_CB<1>")
	)
	(segment
		(start 66.957702 -273.943826)
		(end 62.97803 -273.943826)
		(width 0.18288)
		(layer "In11.Cu")
		(net "M_D_CPU1_SA_CB<1>")
	)
	(segment
		(start 84.025994 -264.125456)
		(end 83.93557 -264.125456)
		(width 0.088646)
		(layer "In11.Cu")
		(net "M_D_CPU1_SA_CB<1>")
	)
	(segment
		(start 37.775388 -275.67509)
		(end 36.855654 -275.67509)
		(width 0.18288)
		(layer "In11.Cu")
		(net "M_D_CPU1_SA_CB<1>")
	)
	(segment
		(start 94.176596 -264.176002)
		(end 94.161864 -264.184638)
		(width 0.088646)
		(layer "In11.Cu")
		(net "M_D_CPU1_SA_CB<1>")
	)
	(segment
		(start 18.071084 -277.834344)
		(end 17.878044 -277.641304)
		(width 0.18288)
		(layer "In11.Cu")
		(net "M_D_CPU1_SA_CB<1>")
	)
	(segment
		(start 44.163996 -276.012656)
		(end 43.198288 -276.012656)
		(width 0.18288)
		(layer "In11.Cu")
		(net "M_D_CPU1_SA_CB<1>")
	)
	(segment
		(start 45.351446 -275.862542)
		(end 44.31411 -275.862542)
		(width 0.18288)
		(layer "In11.Cu")
		(net "M_D_CPU1_SA_CB<1>")
	)
	(segment
		(start 83.406488 -264.825988)
		(end 83.317842 -264.914634)
		(width 0.088646)
		(layer "In11.Cu")
		(net "M_D_CPU1_SA_CB<1>")
	)
	(segment
		(start 42.109644 -274.924012)
		(end 40.227758 -274.924012)
		(width 0.18288)
		(layer "In11.Cu")
		(net "M_D_CPU1_SA_CB<1>")
	)
	(segment
		(start 17.213834 -277.641304)
		(end 16.789146 -277.216616)
		(width 0.18288)
		(layer "In11.Cu")
		(net "M_D_CPU1_SA_CB<1>")
	)
	(segment
		(start 22.839426 -277.449026)
		(end 21.430234 -277.449026)
		(width 0.18288)
		(layer "In11.Cu")
		(net "M_D_CPU1_SA_CB<1>")
	)
	(segment
		(start 83.93557 -264.125456)
		(end 83.406488 -264.654538)
		(width 0.088646)
		(layer "In11.Cu")
		(net "M_D_CPU1_SA_CB<1>")
	)
	(segment
		(start 29.240226 -276.102826)
		(end 25.608026 -276.102826)
		(width 0.18288)
		(layer "In11.Cu")
		(net "M_D_CPU1_SA_CB<1>")
	)
	(segment
		(start 21.237956 -277.641304)
		(end 18.965164 -277.641304)
		(width 0.18288)
		(layer "In11.Cu")
		(net "M_D_CPU1_SA_CB<1>")
	)
	(segment
		(start 83.317842 -264.914634)
		(end 83.013804 -264.914634)
		(width 0.088646)
		(layer "In11.Cu")
		(net "M_D_CPU1_SA_CB<1>")
	)
	(segment
		(start 39.340282 -274.924012)
		(end 38.526466 -274.924012)
		(width 0.18288)
		(layer "In11.Cu")
		(net "M_D_CPU1_SA_CB<1>")
	)
	(segment
		(start 23.372826 -276.915626)
		(end 22.839426 -277.449026)
		(width 0.18288)
		(layer "In11.Cu")
		(net "M_D_CPU1_SA_CB<1>")
	)
	(segment
		(start 39.534338 -275.118068)
		(end 39.340282 -274.924012)
		(width 0.18288)
		(layer "In11.Cu")
		(net "M_D_CPU1_SA_CB<1>")
	)
	(segment
		(start 75.986894 -264.914634)
		(end 66.957702 -273.943826)
		(width 0.18288)
		(layer "In11.Cu")
		(net "M_D_CPU1_SA_CB<1>")
	)
	(segment
		(start 18.264124 -278.317452)
		(end 18.071084 -278.124412)
		(width 0.18288)
		(layer "In11.Cu")
		(net "M_D_CPU1_SA_CB<1>")
	)
	(segment
		(start 47.448216 -276.791928)
		(end 46.280832 -276.791928)
		(width 0.18288)
		(layer "In11.Cu")
		(net "M_D_CPU1_SA_CB<1>")
	)
	(segment
		(start 52.666646 -275.780754)
		(end 51.714908 -275.780754)
		(width 0.18288)
		(layer "In11.Cu")
		(net "M_D_CPU1_SA_CB<1>")
	)
	(segment
		(start 83.013804 -264.914634)
		(end 75.986894 -264.914634)
		(width 0.18288)
		(layer "In11.Cu")
		(net "M_D_CPU1_SA_CB<1>")
	)
	(segment
		(start 36.590478 -275.940266)
		(end 34.982912 -275.940266)
		(width 0.18288)
		(layer "In11.Cu")
		(net "M_D_CPU1_SA_CB<1>")
	)
	(segment
		(start 96.995996 -264.176002)
		(end 96.981264 -264.184638)
		(width 0.088646)
		(layer "In11.Cu")
		(net "M_D_CPU1_SA_CB<1>")
	)
	(segment
		(start 40.227758 -274.924012)
		(end 40.033702 -275.118068)
		(width 0.18288)
		(layer "In11.Cu")
		(net "M_D_CPU1_SA_CB<1>")
	)
	(segment
		(start 93.236796 -264.176002)
		(end 93.222064 -264.184638)
		(width 0.088646)
		(layer "In11.Cu")
		(net "M_D_CPU1_SA_CB<1>")
	)
	(segment
		(start 51.552348 -275.943314)
		(end 48.29683 -275.943314)
		(width 0.18288)
		(layer "In11.Cu")
		(net "M_D_CPU1_SA_CB<1>")
	)
	(segment
		(start 62.97803 -273.943826)
		(end 62.551056 -274.3708)
		(width 0.18288)
		(layer "In11.Cu")
		(net "M_D_CPU1_SA_CB<1>")
	)
	(segment
		(start 25.608026 -276.102826)
		(end 24.795226 -276.915626)
		(width 0.18288)
		(layer "In11.Cu")
		(net "M_D_CPU1_SA_CB<1>")
	)
	(segment
		(start 83.406488 -264.654538)
		(end 83.406488 -264.825988)
		(width 0.088646)
		(layer "In11.Cu")
		(net "M_D_CPU1_SA_CB<1>")
	)
	(segment
		(start 18.772124 -278.124412)
		(end 18.579084 -278.317452)
		(width 0.18288)
		(layer "In11.Cu")
		(net "M_D_CPU1_SA_CB<1>")
	)
	(segment
		(start 24.795226 -276.915626)
		(end 23.372826 -276.915626)
		(width 0.18288)
		(layer "In11.Cu")
		(net "M_D_CPU1_SA_CB<1>")
	)
	(arc
		(start 88.537796 -264.176002)
		(mid 88.255094 -264.251778)
		(end 87.972392 -264.176002)
		(width 0.088646)
		(layer "In11.Cu")
		(net "M_D_CPU1_SA_CB<1>")
	)
	(arc
		(start 86.658196 -264.176002)
		(mid 86.375494 -264.251778)
		(end 86.092792 -264.176002)
		(width 0.088646)
		(layer "In11.Cu")
		(net "M_D_CPU1_SA_CB<1>")
	)
	(arc
		(start 97.925636 -264.182098)
		(mid 97.647204 -264.251944)
		(end 97.370392 -264.176002)
		(width 0.088646)
		(layer "In11.Cu")
		(net "M_D_CPU1_SA_CB<1>")
	)
	(arc
		(start 96.041464 -264.184638)
		(mid 95.764989 -264.251958)
		(end 95.490792 -264.176002)
		(width 0.088646)
		(layer "In11.Cu")
		(net "M_D_CPU1_SA_CB<1>")
	)
	(arc
		(start 87.972392 -264.176002)
		(mid 87.785194 -264.125859)
		(end 87.597996 -264.176002)
		(width 0.088646)
		(layer "In11.Cu")
		(net "M_D_CPU1_SA_CB<1>")
	)
	(arc
		(start 93.611192 -264.176002)
		(mid 93.423994 -264.125859)
		(end 93.236796 -264.176002)
		(width 0.088646)
		(layer "In11.Cu")
		(net "M_D_CPU1_SA_CB<1>")
	)
	(arc
		(start 84.778596 -264.176002)
		(mid 84.495894 -264.251778)
		(end 84.213192 -264.176002)
		(width 0.088646)
		(layer "In11.Cu")
		(net "M_D_CPU1_SA_CB<1>")
	)
	(arc
		(start 98.593148 -263.686544)
		(mid 98.420569 -263.845088)
		(end 98.235262 -263.98855)
		(width 0.088646)
		(layer "In11.Cu")
		(net "M_D_CPU1_SA_CB<1>")
	)
	(arc
		(start 89.851992 -264.176002)
		(mid 89.664794 -264.125859)
		(end 89.477596 -264.176002)
		(width 0.088646)
		(layer "In11.Cu")
		(net "M_D_CPU1_SA_CB<1>")
	)
	(arc
		(start 88.912192 -264.176002)
		(mid 88.724994 -264.125859)
		(end 88.537796 -264.176002)
		(width 0.088646)
		(layer "In11.Cu")
		(net "M_D_CPU1_SA_CB<1>")
	)
	(arc
		(start 94.550992 -264.176002)
		(mid 94.363794 -264.125859)
		(end 94.176596 -264.176002)
		(width 0.088646)
		(layer "In11.Cu")
		(net "M_D_CPU1_SA_CB<1>")
	)
	(arc
		(start 87.597996 -264.176002)
		(mid 87.315294 -264.251778)
		(end 87.032592 -264.176002)
		(width 0.088646)
		(layer "In11.Cu")
		(net "M_D_CPU1_SA_CB<1>")
	)
	(arc
		(start 90.417396 -264.176002)
		(mid 90.134694 -264.251778)
		(end 89.851992 -264.176002)
		(width 0.088646)
		(layer "In11.Cu")
		(net "M_D_CPU1_SA_CB<1>")
	)
	(arc
		(start 92.286582 -264.182098)
		(mid 92.008404 -264.251821)
		(end 91.731846 -264.176002)
		(width 0.088646)
		(layer "In11.Cu")
		(net "M_D_CPU1_SA_CB<1>")
	)
	(arc
		(start 89.477596 -264.176002)
		(mid 89.194894 -264.251778)
		(end 88.912192 -264.176002)
		(width 0.088646)
		(layer "In11.Cu")
		(net "M_D_CPU1_SA_CB<1>")
	)
	(arc
		(start 92.671392 -264.176002)
		(mid 92.484194 -264.125859)
		(end 92.296996 -264.176002)
		(width 0.088646)
		(layer "In11.Cu")
		(net "M_D_CPU1_SA_CB<1>")
	)
	(arc
		(start 87.032592 -264.176002)
		(mid 86.845394 -264.125859)
		(end 86.658196 -264.176002)
		(width 0.088646)
		(layer "In11.Cu")
		(net "M_D_CPU1_SA_CB<1>")
	)
	(arc
		(start 94.161864 -264.184638)
		(mid 93.885389 -264.251958)
		(end 93.611192 -264.176002)
		(width 0.088646)
		(layer "In11.Cu")
		(net "M_D_CPU1_SA_CB<1>")
	)
	(arc
		(start 85.718396 -264.176002)
		(mid 85.435694 -264.251778)
		(end 85.152992 -264.176002)
		(width 0.088646)
		(layer "In11.Cu")
		(net "M_D_CPU1_SA_CB<1>")
	)
	(arc
		(start 91.731846 -264.176002)
		(mid 91.544648 -264.125859)
		(end 91.35745 -264.176002)
		(width 0.088646)
		(layer "In11.Cu")
		(net "M_D_CPU1_SA_CB<1>")
	)
	(arc
		(start 93.222064 -264.184638)
		(mid 92.945589 -264.251958)
		(end 92.671392 -264.176002)
		(width 0.088646)
		(layer "In11.Cu")
		(net "M_D_CPU1_SA_CB<1>")
	)
	(arc
		(start 95.116396 -264.176002)
		(mid 94.833694 -264.251778)
		(end 94.550992 -264.176002)
		(width 0.088646)
		(layer "In11.Cu")
		(net "M_D_CPU1_SA_CB<1>")
	)
	(arc
		(start 85.152992 -264.176002)
		(mid 84.965794 -264.125859)
		(end 84.778596 -264.176002)
		(width 0.088646)
		(layer "In11.Cu")
		(net "M_D_CPU1_SA_CB<1>")
	)
	(arc
		(start 90.791792 -264.176002)
		(mid 90.604594 -264.125859)
		(end 90.417396 -264.176002)
		(width 0.088646)
		(layer "In11.Cu")
		(net "M_D_CPU1_SA_CB<1>")
	)
	(arc
		(start 86.092792 -264.176002)
		(mid 85.905594 -264.125859)
		(end 85.718396 -264.176002)
		(width 0.088646)
		(layer "In11.Cu")
		(net "M_D_CPU1_SA_CB<1>")
	)
	(arc
		(start 91.347036 -264.182098)
		(mid 91.068604 -264.251944)
		(end 90.791792 -264.176002)
		(width 0.088646)
		(layer "In11.Cu")
		(net "M_D_CPU1_SA_CB<1>")
	)
	(arc
		(start 96.430592 -264.176002)
		(mid 96.243394 -264.125859)
		(end 96.056196 -264.176002)
		(width 0.088646)
		(layer "In11.Cu")
		(net "M_D_CPU1_SA_CB<1>")
	)
	(arc
		(start 98.235262 -263.98855)
		(mid 98.134966 -264.056426)
		(end 98.031808 -264.119868)
		(width 0.088646)
		(layer "In11.Cu")
		(net "M_D_CPU1_SA_CB<1>")
	)
	(arc
		(start 95.490792 -264.176002)
		(mid 95.303594 -264.125859)
		(end 95.116396 -264.176002)
		(width 0.088646)
		(layer "In11.Cu")
		(net "M_D_CPU1_SA_CB<1>")
	)
	(arc
		(start 96.981264 -264.184638)
		(mid 96.704789 -264.251958)
		(end 96.430592 -264.176002)
		(width 0.088646)
		(layer "In11.Cu")
		(net "M_D_CPU1_SA_CB<1>")
	)
	(arc
		(start 84.213192 -264.176002)
		(mid 84.12292 -264.138403)
		(end 84.025994 -264.125456)
		(width 0.088646)
		(layer "In11.Cu")
		(net "M_D_CPU1_SA_CB<1>")
	)
	(arc
		(start 97.370392 -264.176002)
		(mid 97.183194 -264.125859)
		(end 96.995996 -264.176002)
		(width 0.088646)
		(layer "In11.Cu")
		(net "M_D_CPU1_SA_CB<1>")
	)
	(segment
		(start 8.140446 -278.916638)
		(end 9.474708 -278.916638)
		(width 0.20066)
		(layer "F.Cu")
		(net "M_D_CPU1_SA_CB<0>")
	)
	(segment
		(start 13.441426 -278.491696)
		(end 13.890244 -278.491696)
		(width 0.20066)
		(layer "F.Cu")
		(net "M_D_CPU1_SA_CB<0>")
	)
	(segment
		(start 16.789146 -278.916638)
		(end 15.684246 -278.916638)
		(width 0.20066)
		(layer "F.Cu")
		(net "M_D_CPU1_SA_CB<0>")
	)
	(segment
		(start 10.344912 -278.982678)
		(end 10.344912 -278.693118)
		(width 0.20066)
		(layer "F.Cu")
		(net "M_D_CPU1_SA_CB<0>")
	)
	(segment
		(start 13.890244 -278.491696)
		(end 14.315186 -278.916638)
		(width 0.20066)
		(layer "F.Cu")
		(net "M_D_CPU1_SA_CB<0>")
	)
	(segment
		(start 99.062794 -263.964674)
		(end 99.062794 -264.50036)
		(width 0.20066)
		(layer "F.Cu")
		(net "M_D_CPU1_SA_CB<0>")
	)
	(segment
		(start 10.172192 -279.155398)
		(end 10.344912 -278.982678)
		(width 0.20066)
		(layer "F.Cu")
		(net "M_D_CPU1_SA_CB<0>")
	)
	(segment
		(start 11.372342 -278.491696)
		(end 13.441426 -278.491696)
		(width 0.1016)
		(layer "F.Cu")
		(net "M_D_CPU1_SA_CB<0>")
	)
	(segment
		(start 11.124438 -278.491696)
		(end 11.372342 -278.491696)
		(width 0.101854)
		(layer "F.Cu")
		(net "M_D_CPU1_SA_CB<0>")
	)
	(segment
		(start 9.713468 -279.155398)
		(end 10.172192 -279.155398)
		(width 0.20066)
		(layer "F.Cu")
		(net "M_D_CPU1_SA_CB<0>")
	)
	(segment
		(start 99.063048 -263.96442)
		(end 99.062794 -263.964674)
		(width 0.20066)
		(layer "F.Cu")
		(net "M_D_CPU1_SA_CB<0>")
	)
	(segment
		(start 9.474708 -278.916638)
		(end 9.713468 -279.155398)
		(width 0.20066)
		(layer "F.Cu")
		(net "M_D_CPU1_SA_CB<0>")
	)
	(segment
		(start 14.315186 -278.916638)
		(end 15.684246 -278.916638)
		(width 0.20066)
		(layer "F.Cu")
		(net "M_D_CPU1_SA_CB<0>")
	)
	(segment
		(start 10.554462 -278.483568)
		(end 11.11631 -278.483568)
		(width 0.20066)
		(layer "F.Cu")
		(net "M_D_CPU1_SA_CB<0>")
	)
	(segment
		(start 11.11631 -278.483568)
		(end 11.124438 -278.491696)
		(width 0.101854)
		(layer "F.Cu")
		(net "M_D_CPU1_SA_CB<0>")
	)
	(segment
		(start 10.344912 -278.693118)
		(end 10.554462 -278.483568)
		(width 0.20066)
		(layer "F.Cu")
		(net "M_D_CPU1_SA_CB<0>")
	)
	(segment
		(start 44.53382 -277.550626)
		(end 43.743626 -277.728426)
		(width 0.18288)
		(layer "In11.Cu")
		(net "M_D_CPU1_SA_CB<0>")
	)
	(segment
		(start 58.739532 -276.14372)
		(end 54.10073 -276.990302)
		(width 0.18288)
		(layer "In11.Cu")
		(net "M_D_CPU1_SA_CB<0>")
	)
	(segment
		(start 21.818346 -279.106884)
		(end 21.205698 -278.494236)
		(width 0.18288)
		(layer "In11.Cu")
		(net "M_D_CPU1_SA_CB<0>")
	)
	(segment
		(start 95.975678 -264.998454)
		(end 95.960946 -264.989818)
		(width 0.088646)
		(layer "In11.Cu")
		(net "M_D_CPU1_SA_CB<0>")
	)
	(segment
		(start 21.205698 -278.494236)
		(end 19.933666 -278.494236)
		(width 0.18288)
		(layer "In11.Cu")
		(net "M_D_CPU1_SA_CB<0>")
	)
	(segment
		(start 30.647894 -277.576026)
		(end 29.595826 -277.576026)
		(width 0.18288)
		(layer "In11.Cu")
		(net "M_D_CPU1_SA_CB<0>")
	)
	(segment
		(start 59.043824 -275.913342)
		(end 58.920126 -275.963126)
		(width 0.18288)
		(layer "In11.Cu")
		(net "M_D_CPU1_SA_CB<0>")
	)
	(segment
		(start 63.574168 -274.969986)
		(end 62.630812 -275.913342)
		(width 0.18288)
		(layer "In11.Cu")
		(net "M_D_CPU1_SA_CB<0>")
	)
	(segment
		(start 83.272122 -265.650218)
		(end 83.272122 -265.841988)
		(width 0.088646)
		(layer "In11.Cu")
		(net "M_D_CPU1_SA_CB<0>")
	)
	(segment
		(start 19.933666 -278.494236)
		(end 18.893536 -279.534366)
		(width 0.18288)
		(layer "In11.Cu")
		(net "M_D_CPU1_SA_CB<0>")
	)
	(segment
		(start 62.630812 -275.913342)
		(end 59.043824 -275.913342)
		(width 0.18288)
		(layer "In11.Cu")
		(net "M_D_CPU1_SA_CB<0>")
	)
	(segment
		(start 67.392296 -274.969986)
		(end 63.574168 -274.969986)
		(width 0.18288)
		(layer "In11.Cu")
		(net "M_D_CPU1_SA_CB<0>")
	)
	(segment
		(start 18.385536 -279.896316)
		(end 18.192496 -279.703276)
		(width 0.18288)
		(layer "In11.Cu")
		(net "M_D_CPU1_SA_CB<0>")
	)
	(segment
		(start 18.893536 -279.703276)
		(end 18.700496 -279.896316)
		(width 0.18288)
		(layer "In11.Cu")
		(net "M_D_CPU1_SA_CB<0>")
	)
	(segment
		(start 99.375468 -264.50036)
		(end 99.432872 -264.442956)
		(width 0.088646)
		(layer "In11.Cu")
		(net "M_D_CPU1_SA_CB<0>")
	)
	(segment
		(start 83.85683 -265.06551)
		(end 83.272122 -265.650218)
		(width 0.088646)
		(layer "In11.Cu")
		(net "M_D_CPU1_SA_CB<0>")
	)
	(segment
		(start 42.285412 -276.749256)
		(end 40.537892 -276.749256)
		(width 0.18288)
		(layer "In11.Cu")
		(net "M_D_CPU1_SA_CB<0>")
	)
	(segment
		(start 44.879514 -277.550626)
		(end 44.53382 -277.550626)
		(width 0.18288)
		(layer "In11.Cu")
		(net "M_D_CPU1_SA_CB<0>")
	)
	(segment
		(start 98.405696 -264.989818)
		(end 98.395282 -264.995914)
		(width 0.088646)
		(layer "In11.Cu")
		(net "M_D_CPU1_SA_CB<0>")
	)
	(segment
		(start 17.999456 -279.341326)
		(end 17.213834 -279.341326)
		(width 0.18288)
		(layer "In11.Cu")
		(net "M_D_CPU1_SA_CB<0>")
	)
	(segment
		(start 83.183476 -265.930634)
		(end 82.963004 -265.930634)
		(width 0.088646)
		(layer "In11.Cu")
		(net "M_D_CPU1_SA_CB<0>")
	)
	(segment
		(start 43.743626 -277.728426)
		(end 43.413426 -277.728426)
		(width 0.18288)
		(layer "In11.Cu")
		(net "M_D_CPU1_SA_CB<0>")
	)
	(segment
		(start 36.935664 -277.40483)
		(end 36.699698 -277.640796)
		(width 0.18288)
		(layer "In11.Cu")
		(net "M_D_CPU1_SA_CB<0>")
	)
	(segment
		(start 76.431648 -265.930634)
		(end 67.392296 -274.969986)
		(width 0.18288)
		(layer "In11.Cu")
		(net "M_D_CPU1_SA_CB<0>")
	)
	(segment
		(start 84.025994 -265.06551)
		(end 83.85683 -265.06551)
		(width 0.088646)
		(layer "In11.Cu")
		(net "M_D_CPU1_SA_CB<0>")
	)
	(segment
		(start 48.135794 -277.982426)
		(end 47.62627 -278.49195)
		(width 0.18288)
		(layer "In11.Cu")
		(net "M_D_CPU1_SA_CB<0>")
	)
	(segment
		(start 90.332306 -264.995914)
		(end 90.321892 -264.989818)
		(width 0.088646)
		(layer "In11.Cu")
		(net "M_D_CPU1_SA_CB<0>")
	)
	(segment
		(start 38.140132 -276.914864)
		(end 37.650166 -277.40483)
		(width 0.18288)
		(layer "In11.Cu")
		(net "M_D_CPU1_SA_CB<0>")
	)
	(segment
		(start 98.411792 -264.986262)
		(end 98.405696 -264.989818)
		(width 0.088646)
		(layer "In11.Cu")
		(net "M_D_CPU1_SA_CB<0>")
	)
	(segment
		(start 95.035878 -264.998454)
		(end 95.021146 -264.989818)
		(width 0.088646)
		(layer "In11.Cu")
		(net "M_D_CPU1_SA_CB<0>")
	)
	(segment
		(start 96.915478 -264.998454)
		(end 96.900746 -264.989818)
		(width 0.088646)
		(layer "In11.Cu")
		(net "M_D_CPU1_SA_CB<0>")
	)
	(segment
		(start 47.62627 -278.49195)
		(end 46.614334 -278.49195)
		(width 0.18288)
		(layer "In11.Cu")
		(net "M_D_CPU1_SA_CB<0>")
	)
	(segment
		(start 91.827096 -264.989818)
		(end 91.816682 -264.995914)
		(width 0.088646)
		(layer "In11.Cu")
		(net "M_D_CPU1_SA_CB<0>")
	)
	(segment
		(start 93.156278 -264.998454)
		(end 93.141546 -264.989818)
		(width 0.088646)
		(layer "In11.Cu")
		(net "M_D_CPU1_SA_CB<0>")
	)
	(segment
		(start 29.595826 -277.576026)
		(end 28.681426 -277.779226)
		(width 0.18288)
		(layer "In11.Cu")
		(net "M_D_CPU1_SA_CB<0>")
	)
	(segment
		(start 82.963004 -265.930634)
		(end 76.431648 -265.930634)
		(width 0.18288)
		(layer "In11.Cu")
		(net "M_D_CPU1_SA_CB<0>")
	)
	(segment
		(start 99.258882 -264.181082)
		(end 99.249992 -264.176002)
		(width 0.088646)
		(layer "In11.Cu")
		(net "M_D_CPU1_SA_CB<0>")
	)
	(segment
		(start 25.480264 -278.342344)
		(end 22.345904 -279.106884)
		(width 0.18288)
		(layer "In11.Cu")
		(net "M_D_CPU1_SA_CB<0>")
	)
	(segment
		(start 43.085258 -277.549102)
		(end 42.285412 -276.749256)
		(width 0.18288)
		(layer "In11.Cu")
		(net "M_D_CPU1_SA_CB<0>")
	)
	(segment
		(start 18.700496 -279.896316)
		(end 18.385536 -279.896316)
		(width 0.18288)
		(layer "In11.Cu")
		(net "M_D_CPU1_SA_CB<0>")
	)
	(segment
		(start 18.192496 -279.534366)
		(end 17.999456 -279.341326)
		(width 0.18288)
		(layer "In11.Cu")
		(net "M_D_CPU1_SA_CB<0>")
	)
	(segment
		(start 49.65446 -277.639018)
		(end 49.311052 -277.982426)
		(width 0.18288)
		(layer "In11.Cu")
		(net "M_D_CPU1_SA_CB<0>")
	)
	(segment
		(start 17.213834 -279.341326)
		(end 16.789146 -278.916638)
		(width 0.18288)
		(layer "In11.Cu")
		(net "M_D_CPU1_SA_CB<0>")
	)
	(segment
		(start 35.05708 -277.640796)
		(end 34.209228 -278.488648)
		(width 0.18288)
		(layer "In11.Cu")
		(net "M_D_CPU1_SA_CB<0>")
	)
	(segment
		(start 49.311052 -277.982426)
		(end 48.135794 -277.982426)
		(width 0.18288)
		(layer "In11.Cu")
		(net "M_D_CPU1_SA_CB<0>")
	)
	(segment
		(start 98.688398 -264.491724)
		(end 98.688398 -264.50036)
		(width 0.088646)
		(layer "In11.Cu")
		(net "M_D_CPU1_SA_CB<0>")
	)
	(segment
		(start 99.062794 -264.50036)
		(end 99.375468 -264.50036)
		(width 0.088646)
		(layer "In11.Cu")
		(net "M_D_CPU1_SA_CB<0>")
	)
	(segment
		(start 22.345904 -279.106884)
		(end 21.818346 -279.106884)
		(width 0.18288)
		(layer "In11.Cu")
		(net "M_D_CPU1_SA_CB<0>")
	)
	(segment
		(start 53.192172 -276.990302)
		(end 52.543456 -277.639018)
		(width 0.18288)
		(layer "In11.Cu")
		(net "M_D_CPU1_SA_CB<0>")
	)
	(segment
		(start 45.236384 -277.751794)
		(end 44.879514 -277.550626)
		(width 0.18288)
		(layer "In11.Cu")
		(net "M_D_CPU1_SA_CB<0>")
	)
	(segment
		(start 83.272122 -265.841988)
		(end 83.183476 -265.930634)
		(width 0.088646)
		(layer "In11.Cu")
		(net "M_D_CPU1_SA_CB<0>")
	)
	(segment
		(start 37.650166 -277.40483)
		(end 36.935664 -277.40483)
		(width 0.18288)
		(layer "In11.Cu")
		(net "M_D_CPU1_SA_CB<0>")
	)
	(segment
		(start 18.893536 -279.534366)
		(end 18.893536 -279.703276)
		(width 0.18288)
		(layer "In11.Cu")
		(net "M_D_CPU1_SA_CB<0>")
	)
	(segment
		(start 92.211906 -264.995914)
		(end 92.201492 -264.989818)
		(width 0.088646)
		(layer "In11.Cu")
		(net "M_D_CPU1_SA_CB<0>")
	)
	(segment
		(start 40.537892 -276.749256)
		(end 39.451026 -276.914864)
		(width 0.18288)
		(layer "In11.Cu")
		(net "M_D_CPU1_SA_CB<0>")
	)
	(segment
		(start 34.209228 -278.488648)
		(end 31.560516 -278.488648)
		(width 0.18288)
		(layer "In11.Cu")
		(net "M_D_CPU1_SA_CB<0>")
	)
	(segment
		(start 18.192496 -279.703276)
		(end 18.192496 -279.534366)
		(width 0.18288)
		(layer "In11.Cu")
		(net "M_D_CPU1_SA_CB<0>")
	)
	(segment
		(start 94.096078 -264.998454)
		(end 94.081346 -264.989818)
		(width 0.088646)
		(layer "In11.Cu")
		(net "M_D_CPU1_SA_CB<0>")
	)
	(segment
		(start 58.920126 -275.963126)
		(end 58.739532 -276.14372)
		(width 0.18288)
		(layer "In11.Cu")
		(net "M_D_CPU1_SA_CB<0>")
	)
	(segment
		(start 52.543456 -277.639018)
		(end 49.65446 -277.639018)
		(width 0.18288)
		(layer "In11.Cu")
		(net "M_D_CPU1_SA_CB<0>")
	)
	(segment
		(start 46.614334 -278.49195)
		(end 45.236384 -277.751794)
		(width 0.18288)
		(layer "In11.Cu")
		(net "M_D_CPU1_SA_CB<0>")
	)
	(segment
		(start 28.681426 -277.779226)
		(end 25.480264 -278.342344)
		(width 0.18288)
		(layer "In11.Cu")
		(net "M_D_CPU1_SA_CB<0>")
	)
	(segment
		(start 39.451026 -276.914864)
		(end 38.140132 -276.914864)
		(width 0.18288)
		(layer "In11.Cu")
		(net "M_D_CPU1_SA_CB<0>")
	)
	(segment
		(start 31.560516 -278.488648)
		(end 30.647894 -277.576026)
		(width 0.18288)
		(layer "In11.Cu")
		(net "M_D_CPU1_SA_CB<0>")
	)
	(segment
		(start 54.10073 -276.990302)
		(end 53.192172 -276.990302)
		(width 0.18288)
		(layer "In11.Cu")
		(net "M_D_CPU1_SA_CB<0>")
	)
	(segment
		(start 36.699698 -277.640796)
		(end 35.05708 -277.640796)
		(width 0.18288)
		(layer "In11.Cu")
		(net "M_D_CPU1_SA_CB<0>")
	)
	(segment
		(start 43.413426 -277.728426)
		(end 43.085258 -277.549102)
		(width 0.18288)
		(layer "In11.Cu")
		(net "M_D_CPU1_SA_CB<0>")
	)
	(arc
		(start 89.947496 -264.989818)
		(mid 89.664794 -265.065594)
		(end 89.382092 -264.989818)
		(width 0.088646)
		(layer "In11.Cu")
		(net "M_D_CPU1_SA_CB<0>")
	)
	(arc
		(start 90.321892 -264.989818)
		(mid 90.134694 -264.939675)
		(end 89.947496 -264.989818)
		(width 0.088646)
		(layer "In11.Cu")
		(net "M_D_CPU1_SA_CB<0>")
	)
	(arc
		(start 95.58655 -264.989818)
		(mid 95.312351 -265.065653)
		(end 95.035878 -264.998454)
		(width 0.088646)
		(layer "In11.Cu")
		(net "M_D_CPU1_SA_CB<0>")
	)
	(arc
		(start 88.442292 -264.989818)
		(mid 88.255094 -264.939675)
		(end 88.067896 -264.989818)
		(width 0.088646)
		(layer "In11.Cu")
		(net "M_D_CPU1_SA_CB<0>")
	)
	(arc
		(start 91.261946 -264.989818)
		(mid 91.074748 -264.939675)
		(end 90.88755 -264.989818)
		(width 0.088646)
		(layer "In11.Cu")
		(net "M_D_CPU1_SA_CB<0>")
	)
	(arc
		(start 94.081346 -264.989818)
		(mid 93.894148 -264.939675)
		(end 93.70695 -264.989818)
		(width 0.088646)
		(layer "In11.Cu")
		(net "M_D_CPU1_SA_CB<0>")
	)
	(arc
		(start 92.201492 -264.989818)
		(mid 92.014294 -264.939675)
		(end 91.827096 -264.989818)
		(width 0.088646)
		(layer "In11.Cu")
		(net "M_D_CPU1_SA_CB<0>")
	)
	(arc
		(start 95.021146 -264.989818)
		(mid 94.833948 -264.939675)
		(end 94.64675 -264.989818)
		(width 0.088646)
		(layer "In11.Cu")
		(net "M_D_CPU1_SA_CB<0>")
	)
	(arc
		(start 93.141546 -264.989818)
		(mid 92.954348 -264.939675)
		(end 92.76715 -264.989818)
		(width 0.088646)
		(layer "In11.Cu")
		(net "M_D_CPU1_SA_CB<0>")
	)
	(arc
		(start 98.875596 -264.176002)
		(mid 98.740663 -264.309356)
		(end 98.688398 -264.491724)
		(width 0.088646)
		(layer "In11.Cu")
		(net "M_D_CPU1_SA_CB<0>")
	)
	(arc
		(start 96.900746 -264.989818)
		(mid 96.713548 -264.939675)
		(end 96.52635 -264.989818)
		(width 0.088646)
		(layer "In11.Cu")
		(net "M_D_CPU1_SA_CB<0>")
	)
	(arc
		(start 99.249992 -264.176002)
		(mid 99.062794 -264.125859)
		(end 98.875596 -264.176002)
		(width 0.088646)
		(layer "In11.Cu")
		(net "M_D_CPU1_SA_CB<0>")
	)
	(arc
		(start 89.007696 -264.989818)
		(mid 88.724994 -265.065594)
		(end 88.442292 -264.989818)
		(width 0.088646)
		(layer "In11.Cu")
		(net "M_D_CPU1_SA_CB<0>")
	)
	(arc
		(start 84.308696 -264.989818)
		(mid 84.172327 -265.04626)
		(end 84.025994 -265.06551)
		(width 0.088646)
		(layer "In11.Cu")
		(net "M_D_CPU1_SA_CB<0>")
	)
	(arc
		(start 93.70695 -264.989818)
		(mid 93.432751 -265.065653)
		(end 93.156278 -264.998454)
		(width 0.088646)
		(layer "In11.Cu")
		(net "M_D_CPU1_SA_CB<0>")
	)
	(arc
		(start 97.840546 -264.989818)
		(mid 97.653348 -264.939675)
		(end 97.46615 -264.989818)
		(width 0.088646)
		(layer "In11.Cu")
		(net "M_D_CPU1_SA_CB<0>")
	)
	(arc
		(start 84.683092 -264.989818)
		(mid 84.495894 -264.939675)
		(end 84.308696 -264.989818)
		(width 0.088646)
		(layer "In11.Cu")
		(net "M_D_CPU1_SA_CB<0>")
	)
	(arc
		(start 98.395282 -264.995914)
		(mid 98.117104 -265.065637)
		(end 97.840546 -264.989818)
		(width 0.088646)
		(layer "In11.Cu")
		(net "M_D_CPU1_SA_CB<0>")
	)
	(arc
		(start 99.432872 -264.442956)
		(mid 99.374716 -264.292843)
		(end 99.258882 -264.181082)
		(width 0.088646)
		(layer "In11.Cu")
		(net "M_D_CPU1_SA_CB<0>")
	)
	(arc
		(start 95.960946 -264.989818)
		(mid 95.773748 -264.939675)
		(end 95.58655 -264.989818)
		(width 0.088646)
		(layer "In11.Cu")
		(net "M_D_CPU1_SA_CB<0>")
	)
	(arc
		(start 98.688398 -264.50036)
		(mid 98.614407 -264.779926)
		(end 98.411792 -264.986262)
		(width 0.088646)
		(layer "In11.Cu")
		(net "M_D_CPU1_SA_CB<0>")
	)
	(arc
		(start 96.52635 -264.989818)
		(mid 96.252151 -265.065653)
		(end 95.975678 -264.998454)
		(width 0.088646)
		(layer "In11.Cu")
		(net "M_D_CPU1_SA_CB<0>")
	)
	(arc
		(start 85.248496 -264.989818)
		(mid 84.965794 -265.065594)
		(end 84.683092 -264.989818)
		(width 0.088646)
		(layer "In11.Cu")
		(net "M_D_CPU1_SA_CB<0>")
	)
	(arc
		(start 87.502492 -264.989818)
		(mid 87.315294 -264.939675)
		(end 87.128096 -264.989818)
		(width 0.088646)
		(layer "In11.Cu")
		(net "M_D_CPU1_SA_CB<0>")
	)
	(arc
		(start 85.622892 -264.989818)
		(mid 85.435694 -264.939675)
		(end 85.248496 -264.989818)
		(width 0.088646)
		(layer "In11.Cu")
		(net "M_D_CPU1_SA_CB<0>")
	)
	(arc
		(start 97.46615 -264.989818)
		(mid 97.191951 -265.065653)
		(end 96.915478 -264.998454)
		(width 0.088646)
		(layer "In11.Cu")
		(net "M_D_CPU1_SA_CB<0>")
	)
	(arc
		(start 87.128096 -264.989818)
		(mid 86.845394 -265.065594)
		(end 86.562692 -264.989818)
		(width 0.088646)
		(layer "In11.Cu")
		(net "M_D_CPU1_SA_CB<0>")
	)
	(arc
		(start 89.382092 -264.989818)
		(mid 89.194894 -264.939675)
		(end 89.007696 -264.989818)
		(width 0.088646)
		(layer "In11.Cu")
		(net "M_D_CPU1_SA_CB<0>")
	)
	(arc
		(start 92.76715 -264.989818)
		(mid 92.490337 -265.065688)
		(end 92.211906 -264.995914)
		(width 0.088646)
		(layer "In11.Cu")
		(net "M_D_CPU1_SA_CB<0>")
	)
	(arc
		(start 86.562692 -264.989818)
		(mid 86.375494 -264.939675)
		(end 86.188296 -264.989818)
		(width 0.088646)
		(layer "In11.Cu")
		(net "M_D_CPU1_SA_CB<0>")
	)
	(arc
		(start 94.64675 -264.989818)
		(mid 94.372551 -265.065653)
		(end 94.096078 -264.998454)
		(width 0.088646)
		(layer "In11.Cu")
		(net "M_D_CPU1_SA_CB<0>")
	)
	(arc
		(start 88.067896 -264.989818)
		(mid 87.785194 -265.065594)
		(end 87.502492 -264.989818)
		(width 0.088646)
		(layer "In11.Cu")
		(net "M_D_CPU1_SA_CB<0>")
	)
	(arc
		(start 86.188296 -264.989818)
		(mid 85.905594 -265.065594)
		(end 85.622892 -264.989818)
		(width 0.088646)
		(layer "In11.Cu")
		(net "M_D_CPU1_SA_CB<0>")
	)
	(arc
		(start 91.816682 -264.995914)
		(mid 91.538504 -265.065637)
		(end 91.261946 -264.989818)
		(width 0.088646)
		(layer "In11.Cu")
		(net "M_D_CPU1_SA_CB<0>")
	)
	(arc
		(start 90.88755 -264.989818)
		(mid 90.610737 -265.065688)
		(end 90.332306 -264.995914)
		(width 0.088646)
		(layer "In11.Cu")
		(net "M_D_CPU1_SA_CB<0>")
	)
	(segment
		(start 13.619988 -260.641846)
		(end 14.04493 -261.066788)
		(width 0.20066)
		(layer "F.Cu")
		(net "M_D_CPU1_SA_CA<6>")
	)
	(segment
		(start 10.344912 -260.795516)
		(end 10.507472 -260.632956)
		(width 0.20066)
		(layer "F.Cu")
		(net "M_D_CPU1_SA_CA<6>")
	)
	(segment
		(start 13.441426 -260.641846)
		(end 13.619988 -260.641846)
		(width 0.20066)
		(layer "F.Cu")
		(net "M_D_CPU1_SA_CA<6>")
	)
	(segment
		(start 9.474708 -261.066788)
		(end 9.686036 -261.278116)
		(width 0.20066)
		(layer "F.Cu")
		(net "M_D_CPU1_SA_CA<6>")
	)
	(segment
		(start 10.507472 -260.632956)
		(end 11.11631 -260.632956)
		(width 0.20066)
		(layer "F.Cu")
		(net "M_D_CPU1_SA_CA<6>")
	)
	(segment
		(start 11.11631 -260.632956)
		(end 11.1252 -260.641846)
		(width 0.1016)
		(layer "F.Cu")
		(net "M_D_CPU1_SA_CA<6>")
	)
	(segment
		(start 16.789146 -261.066788)
		(end 15.684246 -261.066788)
		(width 0.20066)
		(layer "F.Cu")
		(net "M_D_CPU1_SA_CA<6>")
	)
	(segment
		(start 13.110718 -260.641846)
		(end 13.441426 -260.641846)
		(width 0.101854)
		(layer "F.Cu")
		(net "M_D_CPU1_SA_CA<6>")
	)
	(segment
		(start 8.140446 -261.066788)
		(end 9.474708 -261.066788)
		(width 0.20066)
		(layer "F.Cu")
		(net "M_D_CPU1_SA_CA<6>")
	)
	(segment
		(start 11.1252 -260.641846)
		(end 13.110718 -260.641846)
		(width 0.1016)
		(layer "F.Cu")
		(net "M_D_CPU1_SA_CA<6>")
	)
	(segment
		(start 14.04493 -261.066788)
		(end 15.684246 -261.066788)
		(width 0.20066)
		(layer "F.Cu")
		(net "M_D_CPU1_SA_CA<6>")
	)
	(segment
		(start 10.19048 -261.278116)
		(end 10.344912 -261.123684)
		(width 0.20066)
		(layer "F.Cu")
		(net "M_D_CPU1_SA_CA<6>")
	)
	(segment
		(start 99.892866 -248.528078)
		(end 99.892612 -248.527824)
		(width 0.20066)
		(layer "F.Cu")
		(net "M_D_CPU1_SA_CA<6>")
	)
	(segment
		(start 9.686036 -261.278116)
		(end 10.19048 -261.278116)
		(width 0.20066)
		(layer "F.Cu")
		(net "M_D_CPU1_SA_CA<6>")
	)
	(segment
		(start 99.892612 -248.527824)
		(end 99.892612 -247.992138)
		(width 0.20066)
		(layer "F.Cu")
		(net "M_D_CPU1_SA_CA<6>")
	)
	(segment
		(start 10.344912 -261.123684)
		(end 10.344912 -260.795516)
		(width 0.20066)
		(layer "F.Cu")
		(net "M_D_CPU1_SA_CA<6>")
	)
	(segment
		(start 59.553348 -256.857246)
		(end 57.854596 -257.560826)
		(width 0.18288)
		(layer "In11.Cu")
		(net "M_D_CPU1_SA_CA<6>")
	)
	(segment
		(start 98.627184 -253.54153)
		(end 95.002604 -253.54153)
		(width 0.088646)
		(layer "In11.Cu")
		(net "M_D_CPU1_SA_CA<6>")
	)
	(segment
		(start 67.048888 -255.500632)
		(end 65.39357 -256.186178)
		(width 0.18288)
		(layer "In11.Cu")
		(net "M_D_CPU1_SA_CA<6>")
	)
	(segment
		(start 21.898102 -260.779006)
		(end 21.182838 -261.49427)
		(width 0.18288)
		(layer "In11.Cu")
		(net "M_D_CPU1_SA_CA<6>")
	)
	(segment
		(start 45.481494 -257.073908)
		(end 42.771822 -257.073908)
		(width 0.18288)
		(layer "In11.Cu")
		(net "M_D_CPU1_SA_CA<6>")
	)
	(segment
		(start 101.397816 -249.610372)
		(end 101.397816 -250.770898)
		(width 0.088646)
		(layer "In11.Cu")
		(net "M_D_CPU1_SA_CA<6>")
	)
	(segment
		(start 50.393854 -257.073908)
		(end 49.986184 -257.481578)
		(width 0.18288)
		(layer "In11.Cu")
		(net "M_D_CPU1_SA_CA<6>")
	)
	(segment
		(start 87.13216 -253.441708)
		(end 86.485222 -254.088646)
		(width 0.18288)
		(layer "In11.Cu")
		(net "M_D_CPU1_SA_CA<6>")
	)
	(segment
		(start 74.7395 -255.500632)
		(end 67.048888 -255.500632)
		(width 0.18288)
		(layer "In11.Cu")
		(net "M_D_CPU1_SA_CA<6>")
	)
	(segment
		(start 57.854596 -257.560826)
		(end 53.407056 -257.560826)
		(width 0.18288)
		(layer "In11.Cu")
		(net "M_D_CPU1_SA_CA<6>")
	)
	(segment
		(start 101.397816 -250.770898)
		(end 98.627184 -253.54153)
		(width 0.088646)
		(layer "In11.Cu")
		(net "M_D_CPU1_SA_CA<6>")
	)
	(segment
		(start 27.681428 -257.064002)
		(end 27.184604 -257.560826)
		(width 0.18288)
		(layer "In11.Cu")
		(net "M_D_CPU1_SA_CA<6>")
	)
	(segment
		(start 85.049868 -254.088646)
		(end 84.703158 -254.435356)
		(width 0.18288)
		(layer "In11.Cu")
		(net "M_D_CPU1_SA_CA<6>")
	)
	(segment
		(start 75.167998 -255.92913)
		(end 74.7395 -255.500632)
		(width 0.18288)
		(layer "In11.Cu")
		(net "M_D_CPU1_SA_CA<6>")
	)
	(segment
		(start 30.880812 -257.560826)
		(end 30.383988 -257.064002)
		(width 0.18288)
		(layer "In11.Cu")
		(net "M_D_CPU1_SA_CA<6>")
	)
	(segment
		(start 23.920196 -259.223256)
		(end 22.523196 -260.620256)
		(width 0.18288)
		(layer "In11.Cu")
		(net "M_D_CPU1_SA_CA<6>")
	)
	(segment
		(start 25.264618 -258.666234)
		(end 23.920196 -259.223256)
		(width 0.18288)
		(layer "In11.Cu")
		(net "M_D_CPU1_SA_CA<6>")
	)
	(segment
		(start 45.889164 -257.481578)
		(end 45.481494 -257.073908)
		(width 0.18288)
		(layer "In11.Cu")
		(net "M_D_CPU1_SA_CA<6>")
	)
	(segment
		(start 100.927916 -248.791984)
		(end 100.927916 -248.814844)
		(width 0.088646)
		(layer "In11.Cu")
		(net "M_D_CPU1_SA_CA<6>")
	)
	(segment
		(start 35.306254 -257.073908)
		(end 34.819336 -257.560826)
		(width 0.18288)
		(layer "In11.Cu")
		(net "M_D_CPU1_SA_CA<6>")
	)
	(segment
		(start 42.771822 -257.073908)
		(end 42.284904 -257.560826)
		(width 0.18288)
		(layer "In11.Cu")
		(net "M_D_CPU1_SA_CA<6>")
	)
	(segment
		(start 27.184604 -257.560826)
		(end 26.91003 -257.560826)
		(width 0.18288)
		(layer "In11.Cu")
		(net "M_D_CPU1_SA_CA<6>")
	)
	(segment
		(start 100.630482 -248.30786)
		(end 100.645214 -248.316496)
		(width 0.088646)
		(layer "In11.Cu")
		(net "M_D_CPU1_SA_CA<6>")
	)
	(segment
		(start 63.773304 -256.857246)
		(end 59.553348 -256.857246)
		(width 0.18288)
		(layer "In11.Cu")
		(net "M_D_CPU1_SA_CA<6>")
	)
	(segment
		(start 38.424612 -257.560826)
		(end 37.937694 -257.073908)
		(width 0.18288)
		(layer "In11.Cu")
		(net "M_D_CPU1_SA_CA<6>")
	)
	(segment
		(start 21.182838 -261.49427)
		(end 17.820894 -261.49427)
		(width 0.18288)
		(layer "In11.Cu")
		(net "M_D_CPU1_SA_CA<6>")
	)
	(segment
		(start 22.140164 -260.779006)
		(end 21.898102 -260.779006)
		(width 0.18288)
		(layer "In11.Cu")
		(net "M_D_CPU1_SA_CA<6>")
	)
	(segment
		(start 84.703158 -254.435356)
		(end 81.661762 -254.435356)
		(width 0.18288)
		(layer "In11.Cu")
		(net "M_D_CPU1_SA_CA<6>")
	)
	(segment
		(start 99.892612 -247.992138)
		(end 100.049076 -248.263156)
		(width 0.088646)
		(layer "In11.Cu")
		(net "M_D_CPU1_SA_CA<6>")
	)
	(segment
		(start 22.523196 -260.620256)
		(end 22.140164 -260.779006)
		(width 0.18288)
		(layer "In11.Cu")
		(net "M_D_CPU1_SA_CA<6>")
	)
	(segment
		(start 52.920138 -257.073908)
		(end 50.393854 -257.073908)
		(width 0.18288)
		(layer "In11.Cu")
		(net "M_D_CPU1_SA_CA<6>")
	)
	(segment
		(start 101.397562 -249.610118)
		(end 101.397816 -249.610372)
		(width 0.088646)
		(layer "In11.Cu")
		(net "M_D_CPU1_SA_CA<6>")
	)
	(segment
		(start 17.820894 -261.49427)
		(end 16.789146 -261.066788)
		(width 0.18288)
		(layer "In11.Cu")
		(net "M_D_CPU1_SA_CA<6>")
	)
	(segment
		(start 94.902782 -253.441708)
		(end 94.32163 -253.441708)
		(width 0.088646)
		(layer "In11.Cu")
		(net "M_D_CPU1_SA_CA<6>")
	)
	(segment
		(start 100.049076 -248.263156)
		(end 100.13823 -248.287032)
		(width 0.088646)
		(layer "In11.Cu")
		(net "M_D_CPU1_SA_CA<6>")
	)
	(segment
		(start 37.937694 -257.073908)
		(end 35.306254 -257.073908)
		(width 0.18288)
		(layer "In11.Cu")
		(net "M_D_CPU1_SA_CA<6>")
	)
	(segment
		(start 94.32163 -253.441708)
		(end 87.13216 -253.441708)
		(width 0.18288)
		(layer "In11.Cu")
		(net "M_D_CPU1_SA_CA<6>")
	)
	(segment
		(start 86.485222 -254.088646)
		(end 85.049868 -254.088646)
		(width 0.18288)
		(layer "In11.Cu")
		(net "M_D_CPU1_SA_CA<6>")
	)
	(segment
		(start 26.91003 -257.560826)
		(end 25.988264 -257.942588)
		(width 0.18288)
		(layer "In11.Cu")
		(net "M_D_CPU1_SA_CA<6>")
	)
	(segment
		(start 25.988264 -257.942588)
		(end 25.264618 -258.666234)
		(width 0.18288)
		(layer "In11.Cu")
		(net "M_D_CPU1_SA_CA<6>")
	)
	(segment
		(start 34.819336 -257.560826)
		(end 30.880812 -257.560826)
		(width 0.18288)
		(layer "In11.Cu")
		(net "M_D_CPU1_SA_CA<6>")
	)
	(segment
		(start 49.986184 -257.481578)
		(end 45.889164 -257.481578)
		(width 0.18288)
		(layer "In11.Cu")
		(net "M_D_CPU1_SA_CA<6>")
	)
	(segment
		(start 42.284904 -257.560826)
		(end 38.424612 -257.560826)
		(width 0.18288)
		(layer "In11.Cu")
		(net "M_D_CPU1_SA_CA<6>")
	)
	(segment
		(start 53.407056 -257.560826)
		(end 52.920138 -257.073908)
		(width 0.18288)
		(layer "In11.Cu")
		(net "M_D_CPU1_SA_CA<6>")
	)
	(segment
		(start 30.383988 -257.064002)
		(end 27.681428 -257.064002)
		(width 0.18288)
		(layer "In11.Cu")
		(net "M_D_CPU1_SA_CA<6>")
	)
	(segment
		(start 81.661762 -254.435356)
		(end 80.167988 -255.92913)
		(width 0.18288)
		(layer "In11.Cu")
		(net "M_D_CPU1_SA_CA<6>")
	)
	(segment
		(start 65.39357 -256.186178)
		(end 63.773304 -256.857246)
		(width 0.18288)
		(layer "In11.Cu")
		(net "M_D_CPU1_SA_CA<6>")
	)
	(segment
		(start 95.002604 -253.54153)
		(end 94.902782 -253.441708)
		(width 0.088646)
		(layer "In11.Cu")
		(net "M_D_CPU1_SA_CA<6>")
	)
	(segment
		(start 80.167988 -255.92913)
		(end 75.167998 -255.92913)
		(width 0.18288)
		(layer "In11.Cu")
		(net "M_D_CPU1_SA_CA<6>")
	)
	(arc
		(start 101.115114 -249.130566)
		(mid 101.319449 -249.333171)
		(end 101.397562 -249.610118)
		(width 0.088646)
		(layer "In11.Cu")
		(net "M_D_CPU1_SA_CA<6>")
	)
	(arc
		(start 100.927916 -248.814844)
		(mid 100.980186 -248.997209)
		(end 101.115114 -249.130566)
		(width 0.088646)
		(layer "In11.Cu")
		(net "M_D_CPU1_SA_CA<6>")
	)
	(arc
		(start 100.13823 -248.287032)
		(mid 100.386735 -248.241066)
		(end 100.630482 -248.30786)
		(width 0.088646)
		(layer "In11.Cu")
		(net "M_D_CPU1_SA_CA<6>")
	)
	(arc
		(start 100.645214 -248.316496)
		(mid 100.848695 -248.5173)
		(end 100.927916 -248.791984)
		(width 0.088646)
		(layer "In11.Cu")
		(net "M_D_CPU1_SA_CA<6>")
	)
	(segment
		(start 18.102326 -261.912354)
		(end 18.314162 -262.12419)
		(width 0.20066)
		(layer "F.Cu")
		(net "M_D_CPU1_SA_CA<5>")
	)
	(segment
		(start 17.578578 -262.192516)
		(end 17.578578 -262.040878)
		(width 0.20066)
		(layer "F.Cu")
		(net "M_D_CPU1_SA_CA<5>")
	)
	(segment
		(start 18.314162 -262.12419)
		(end 18.760694 -262.12419)
		(width 0.20066)
		(layer "F.Cu")
		(net "M_D_CPU1_SA_CA<5>")
	)
	(segment
		(start 100.002848 -256.361184)
		(end 100.002594 -256.361438)
		(width 0.20066)
		(layer "F.Cu")
		(net "M_D_CPU1_SA_CA<5>")
	)
	(segment
		(start 12.240514 -261.916672)
		(end 13.937742 -261.916672)
		(width 0.20066)
		(layer "F.Cu")
		(net "M_D_CPU1_SA_CA<5>")
	)
	(segment
		(start 14.574266 -262.341614)
		(end 14.812264 -262.341614)
		(width 0.101854)
		(layer "F.Cu")
		(net "M_D_CPU1_SA_CA<5>")
	)
	(segment
		(start 100.002848 -255.825498)
		(end 100.002848 -256.361184)
		(width 0.20066)
		(layer "F.Cu")
		(net "M_D_CPU1_SA_CA<5>")
	)
	(segment
		(start 14.560042 -262.355838)
		(end 14.574266 -262.341614)
		(width 0.101854)
		(layer "F.Cu")
		(net "M_D_CPU1_SA_CA<5>")
	)
	(segment
		(start 14.063726 -262.213344)
		(end 14.20622 -262.355838)
		(width 0.20066)
		(layer "F.Cu")
		(net "M_D_CPU1_SA_CA<5>")
	)
	(segment
		(start 14.20622 -262.355838)
		(end 14.560042 -262.355838)
		(width 0.20066)
		(layer "F.Cu")
		(net "M_D_CPU1_SA_CA<5>")
	)
	(segment
		(start 17.707102 -261.912354)
		(end 18.102326 -261.912354)
		(width 0.20066)
		(layer "F.Cu")
		(net "M_D_CPU1_SA_CA<5>")
	)
	(segment
		(start 14.063726 -262.042656)
		(end 14.063726 -262.213344)
		(width 0.20066)
		(layer "F.Cu")
		(net "M_D_CPU1_SA_CA<5>")
	)
	(segment
		(start 16.885158 -262.341614)
		(end 17.42948 -262.341614)
		(width 0.20066)
		(layer "F.Cu")
		(net "M_D_CPU1_SA_CA<5>")
	)
	(segment
		(start 17.578578 -262.040878)
		(end 17.707102 -261.912354)
		(width 0.20066)
		(layer "F.Cu")
		(net "M_D_CPU1_SA_CA<5>")
	)
	(segment
		(start 13.937742 -261.916672)
		(end 14.063726 -262.042656)
		(width 0.20066)
		(layer "F.Cu")
		(net "M_D_CPU1_SA_CA<5>")
	)
	(segment
		(start 18.968212 -261.916672)
		(end 19.784314 -261.916672)
		(width 0.20066)
		(layer "F.Cu")
		(net "M_D_CPU1_SA_CA<5>")
	)
	(segment
		(start 20.889214 -261.916672)
		(end 19.784314 -261.916672)
		(width 0.20066)
		(layer "F.Cu")
		(net "M_D_CPU1_SA_CA<5>")
	)
	(segment
		(start 14.812264 -262.341614)
		(end 16.885158 -262.341614)
		(width 0.1016)
		(layer "F.Cu")
		(net "M_D_CPU1_SA_CA<5>")
	)
	(segment
		(start 17.42948 -262.341614)
		(end 17.578578 -262.192516)
		(width 0.20066)
		(layer "F.Cu")
		(net "M_D_CPU1_SA_CA<5>")
	)
	(segment
		(start 18.760694 -262.12419)
		(end 18.968212 -261.916672)
		(width 0.20066)
		(layer "F.Cu")
		(net "M_D_CPU1_SA_CA<5>")
	)
	(segment
		(start 21.489924 -261.916672)
		(end 20.889214 -261.916672)
		(width 0.18288)
		(layer "In11.Cu")
		(net "M_D_CPU1_SA_CA<5>")
	)
	(segment
		(start 54.890416 -258.080002)
		(end 53.199792 -258.080002)
		(width 0.18288)
		(layer "In11.Cu")
		(net "M_D_CPU1_SA_CA<5>")
	)
	(segment
		(start 22.48154 -261.423912)
		(end 21.982684 -261.423912)
		(width 0.18288)
		(layer "In11.Cu")
		(net "M_D_CPU1_SA_CA<5>")
	)
	(segment
		(start 99.375722 -255.889252)
		(end 99.345496 -255.87198)
		(width 0.088646)
		(layer "In11.Cu")
		(net "M_D_CPU1_SA_CA<5>")
	)
	(segment
		(start 24.160226 -259.745226)
		(end 22.48154 -261.423912)
		(width 0.18288)
		(layer "In11.Cu")
		(net "M_D_CPU1_SA_CA<5>")
	)
	(segment
		(start 64.953896 -257.368802)
		(end 59.819794 -257.368802)
		(width 0.18288)
		(layer "In11.Cu")
		(net "M_D_CPU1_SA_CA<5>")
	)
	(segment
		(start 30.639258 -258.089908)
		(end 30.121352 -257.572002)
		(width 0.18288)
		(layer "In11.Cu")
		(net "M_D_CPU1_SA_CA<5>")
	)
	(segment
		(start 84.025994 -255.796288)
		(end 83.751928 -255.796288)
		(width 0.088646)
		(layer "In11.Cu")
		(net "M_D_CPU1_SA_CA<5>")
	)
	(segment
		(start 25.430226 -259.288026)
		(end 24.973026 -259.745226)
		(width 0.18288)
		(layer "In11.Cu")
		(net "M_D_CPU1_SA_CA<5>")
	)
	(segment
		(start 21.982684 -261.423912)
		(end 21.489924 -261.916672)
		(width 0.18288)
		(layer "In11.Cu")
		(net "M_D_CPU1_SA_CA<5>")
	)
	(segment
		(start 32.453326 -258.520438)
		(end 32.453326 -258.282948)
		(width 0.18288)
		(layer "In11.Cu")
		(net "M_D_CPU1_SA_CA<5>")
	)
	(segment
		(start 93.156278 -255.863344)
		(end 93.141546 -255.87198)
		(width 0.088646)
		(layer "In11.Cu")
		(net "M_D_CPU1_SA_CA<5>")
	)
	(segment
		(start 35.017964 -258.089908)
		(end 33.347406 -258.089908)
		(width 0.18288)
		(layer "In11.Cu")
		(net "M_D_CPU1_SA_CA<5>")
	)
	(segment
		(start 40.271192 -258.592066)
		(end 40.078152 -258.399026)
		(width 0.18288)
		(layer "In11.Cu")
		(net "M_D_CPU1_SA_CA<5>")
	)
	(segment
		(start 39.885112 -258.080002)
		(end 38.175692 -258.080002)
		(width 0.18288)
		(layer "In11.Cu")
		(net "M_D_CPU1_SA_CA<5>")
	)
	(segment
		(start 40.972232 -258.080002)
		(end 40.779192 -258.273042)
		(width 0.18288)
		(layer "In11.Cu")
		(net "M_D_CPU1_SA_CA<5>")
	)
	(segment
		(start 74.733912 -256.10693)
		(end 66.989198 -256.10693)
		(width 0.18288)
		(layer "In11.Cu")
		(net "M_D_CPU1_SA_CA<5>")
	)
	(segment
		(start 40.078152 -258.399026)
		(end 40.078152 -258.273042)
		(width 0.18288)
		(layer "In11.Cu")
		(net "M_D_CPU1_SA_CA<5>")
	)
	(segment
		(start 47.741078 -258.368038)
		(end 47.428658 -258.055618)
		(width 0.18288)
		(layer "In11.Cu")
		(net "M_D_CPU1_SA_CA<5>")
	)
	(segment
		(start 35.525964 -257.581908)
		(end 35.017964 -258.089908)
		(width 0.18288)
		(layer "In11.Cu")
		(net "M_D_CPU1_SA_CA<5>")
	)
	(segment
		(start 91.27236 -255.865884)
		(end 91.261946 -255.87198)
		(width 0.088646)
		(layer "In11.Cu")
		(net "M_D_CPU1_SA_CA<5>")
	)
	(segment
		(start 52.701698 -257.581908)
		(end 50.605944 -257.581908)
		(width 0.18288)
		(layer "In11.Cu")
		(net "M_D_CPU1_SA_CA<5>")
	)
	(segment
		(start 92.211906 -255.865884)
		(end 92.201492 -255.87198)
		(width 0.088646)
		(layer "In11.Cu")
		(net "M_D_CPU1_SA_CA<5>")
	)
	(segment
		(start 32.961326 -258.713478)
		(end 32.646366 -258.713478)
		(width 0.18288)
		(layer "In11.Cu")
		(net "M_D_CPU1_SA_CA<5>")
	)
	(segment
		(start 32.453326 -258.282948)
		(end 32.260286 -258.089908)
		(width 0.18288)
		(layer "In11.Cu")
		(net "M_D_CPU1_SA_CA<5>")
	)
	(segment
		(start 88.452706 -255.865884)
		(end 88.442292 -255.87198)
		(width 0.088646)
		(layer "In11.Cu")
		(net "M_D_CPU1_SA_CA<5>")
	)
	(segment
		(start 33.154366 -258.282948)
		(end 33.154366 -258.520438)
		(width 0.18288)
		(layer "In11.Cu")
		(net "M_D_CPU1_SA_CA<5>")
	)
	(segment
		(start 97.85096 -255.865884)
		(end 97.840546 -255.87198)
		(width 0.088646)
		(layer "In11.Cu")
		(net "M_D_CPU1_SA_CA<5>")
	)
	(segment
		(start 33.154366 -258.520438)
		(end 32.961326 -258.713478)
		(width 0.18288)
		(layer "In11.Cu")
		(net "M_D_CPU1_SA_CA<5>")
	)
	(segment
		(start 50.132234 -258.055618)
		(end 48.411638 -258.055618)
		(width 0.18288)
		(layer "In11.Cu")
		(net "M_D_CPU1_SA_CA<5>")
	)
	(segment
		(start 32.646366 -258.713478)
		(end 32.453326 -258.520438)
		(width 0.18288)
		(layer "In11.Cu")
		(net "M_D_CPU1_SA_CA<5>")
	)
	(segment
		(start 95.975678 -255.863344)
		(end 95.960946 -255.87198)
		(width 0.088646)
		(layer "In11.Cu")
		(net "M_D_CPU1_SA_CA<5>")
	)
	(segment
		(start 55.27675 -258.466336)
		(end 54.890416 -258.080002)
		(width 0.18288)
		(layer "In11.Cu")
		(net "M_D_CPU1_SA_CA<5>")
	)
	(segment
		(start 32.260286 -258.089908)
		(end 30.639258 -258.089908)
		(width 0.18288)
		(layer "In11.Cu")
		(net "M_D_CPU1_SA_CA<5>")
	)
	(segment
		(start 80.905604 -255.695958)
		(end 80.326992 -256.27457)
		(width 0.18288)
		(layer "In11.Cu")
		(net "M_D_CPU1_SA_CA<5>")
	)
	(segment
		(start 45.7073 -258.055618)
		(end 45.23359 -257.581908)
		(width 0.18288)
		(layer "In11.Cu")
		(net "M_D_CPU1_SA_CA<5>")
	)
	(segment
		(start 80.326992 -256.27457)
		(end 74.901552 -256.27457)
		(width 0.18288)
		(layer "In11.Cu")
		(net "M_D_CPU1_SA_CA<5>")
	)
	(segment
		(start 57.19572 -258.458208)
		(end 56.81345 -258.075938)
		(width 0.18288)
		(layer "In11.Cu")
		(net "M_D_CPU1_SA_CA<5>")
	)
	(segment
		(start 83.751928 -255.796288)
		(end 83.651598 -255.695958)
		(width 0.088646)
		(layer "In11.Cu")
		(net "M_D_CPU1_SA_CA<5>")
	)
	(segment
		(start 99.345496 -255.87198)
		(end 99.345242 -255.87198)
		(width 0.088646)
		(layer "In11.Cu")
		(net "M_D_CPU1_SA_CA<5>")
	)
	(segment
		(start 26.997152 -258.194556)
		(end 26.804112 -258.387596)
		(width 0.18288)
		(layer "In11.Cu")
		(net "M_D_CPU1_SA_CA<5>")
	)
	(segment
		(start 59.819794 -257.368802)
		(end 58.242708 -258.02209)
		(width 0.18288)
		(layer "In11.Cu")
		(net "M_D_CPU1_SA_CA<5>")
	)
	(segment
		(start 26.804112 -258.742688)
		(end 26.258774 -259.288026)
		(width 0.18288)
		(layer "In11.Cu")
		(net "M_D_CPU1_SA_CA<5>")
	)
	(segment
		(start 33.347406 -258.089908)
		(end 33.154366 -258.282948)
		(width 0.18288)
		(layer "In11.Cu")
		(net "M_D_CPU1_SA_CA<5>")
	)
	(segment
		(start 38.175692 -258.080002)
		(end 37.677598 -257.581908)
		(width 0.18288)
		(layer "In11.Cu")
		(net "M_D_CPU1_SA_CA<5>")
	)
	(segment
		(start 66.989198 -256.10693)
		(end 65.668398 -256.6543)
		(width 0.18288)
		(layer "In11.Cu")
		(net "M_D_CPU1_SA_CA<5>")
	)
	(segment
		(start 45.23359 -257.581908)
		(end 43.052492 -257.581908)
		(width 0.18288)
		(layer "In11.Cu")
		(net "M_D_CPU1_SA_CA<5>")
	)
	(segment
		(start 55.636414 -258.466336)
		(end 55.27675 -258.466336)
		(width 0.18288)
		(layer "In11.Cu")
		(net "M_D_CPU1_SA_CA<5>")
	)
	(segment
		(start 47.428658 -258.055618)
		(end 45.7073 -258.055618)
		(width 0.18288)
		(layer "In11.Cu")
		(net "M_D_CPU1_SA_CA<5>")
	)
	(segment
		(start 26.804112 -258.387596)
		(end 26.804112 -258.742688)
		(width 0.18288)
		(layer "In11.Cu")
		(net "M_D_CPU1_SA_CA<5>")
	)
	(segment
		(start 89.39276 -255.865884)
		(end 89.382346 -255.87198)
		(width 0.088646)
		(layer "In11.Cu")
		(net "M_D_CPU1_SA_CA<5>")
	)
	(segment
		(start 43.052492 -257.581908)
		(end 42.554398 -258.080002)
		(width 0.18288)
		(layer "In11.Cu")
		(net "M_D_CPU1_SA_CA<5>")
	)
	(segment
		(start 27.352244 -258.194556)
		(end 26.997152 -258.194556)
		(width 0.18288)
		(layer "In11.Cu")
		(net "M_D_CPU1_SA_CA<5>")
	)
	(segment
		(start 56.81345 -258.075938)
		(end 56.026812 -258.075938)
		(width 0.18288)
		(layer "In11.Cu")
		(net "M_D_CPU1_SA_CA<5>")
	)
	(segment
		(start 26.258774 -259.288026)
		(end 25.430226 -259.288026)
		(width 0.18288)
		(layer "In11.Cu")
		(net "M_D_CPU1_SA_CA<5>")
	)
	(segment
		(start 24.973026 -259.745226)
		(end 24.160226 -259.745226)
		(width 0.18288)
		(layer "In11.Cu")
		(net "M_D_CPU1_SA_CA<5>")
	)
	(segment
		(start 27.974798 -257.572002)
		(end 27.352244 -258.194556)
		(width 0.18288)
		(layer "In11.Cu")
		(net "M_D_CPU1_SA_CA<5>")
	)
	(segment
		(start 65.668398 -256.6543)
		(end 64.953896 -257.368802)
		(width 0.18288)
		(layer "In11.Cu")
		(net "M_D_CPU1_SA_CA<5>")
	)
	(segment
		(start 74.901552 -256.27457)
		(end 74.733912 -256.10693)
		(width 0.18288)
		(layer "In11.Cu")
		(net "M_D_CPU1_SA_CA<5>")
	)
	(segment
		(start 95.035878 -255.863344)
		(end 95.021146 -255.87198)
		(width 0.088646)
		(layer "In11.Cu")
		(net "M_D_CPU1_SA_CA<5>")
	)
	(segment
		(start 48.411638 -258.055618)
		(end 48.099218 -258.368038)
		(width 0.18288)
		(layer "In11.Cu")
		(net "M_D_CPU1_SA_CA<5>")
	)
	(segment
		(start 56.026812 -258.075938)
		(end 55.636414 -258.466336)
		(width 0.18288)
		(layer "In11.Cu")
		(net "M_D_CPU1_SA_CA<5>")
	)
	(segment
		(start 50.605944 -257.581908)
		(end 50.132234 -258.055618)
		(width 0.18288)
		(layer "In11.Cu")
		(net "M_D_CPU1_SA_CA<5>")
	)
	(segment
		(start 48.099218 -258.368038)
		(end 47.741078 -258.368038)
		(width 0.18288)
		(layer "In11.Cu")
		(net "M_D_CPU1_SA_CA<5>")
	)
	(segment
		(start 30.121352 -257.572002)
		(end 27.974798 -257.572002)
		(width 0.18288)
		(layer "In11.Cu")
		(net "M_D_CPU1_SA_CA<5>")
	)
	(segment
		(start 40.078152 -258.273042)
		(end 39.885112 -258.080002)
		(width 0.18288)
		(layer "In11.Cu")
		(net "M_D_CPU1_SA_CA<5>")
	)
	(segment
		(start 96.915478 -255.863344)
		(end 96.900746 -255.87198)
		(width 0.088646)
		(layer "In11.Cu")
		(net "M_D_CPU1_SA_CA<5>")
	)
	(segment
		(start 40.779192 -258.273042)
		(end 40.779192 -258.399026)
		(width 0.18288)
		(layer "In11.Cu")
		(net "M_D_CPU1_SA_CA<5>")
	)
	(segment
		(start 37.677598 -257.581908)
		(end 35.525964 -257.581908)
		(width 0.18288)
		(layer "In11.Cu")
		(net "M_D_CPU1_SA_CA<5>")
	)
	(segment
		(start 42.554398 -258.080002)
		(end 40.972232 -258.080002)
		(width 0.18288)
		(layer "In11.Cu")
		(net "M_D_CPU1_SA_CA<5>")
	)
	(segment
		(start 90.332306 -255.865884)
		(end 90.321892 -255.87198)
		(width 0.088646)
		(layer "In11.Cu")
		(net "M_D_CPU1_SA_CA<5>")
	)
	(segment
		(start 58.242708 -258.02209)
		(end 57.80659 -258.458208)
		(width 0.18288)
		(layer "In11.Cu")
		(net "M_D_CPU1_SA_CA<5>")
	)
	(segment
		(start 40.586152 -258.592066)
		(end 40.271192 -258.592066)
		(width 0.18288)
		(layer "In11.Cu")
		(net "M_D_CPU1_SA_CA<5>")
	)
	(segment
		(start 57.80659 -258.458208)
		(end 57.19572 -258.458208)
		(width 0.18288)
		(layer "In11.Cu")
		(net "M_D_CPU1_SA_CA<5>")
	)
	(segment
		(start 40.779192 -258.399026)
		(end 40.586152 -258.592066)
		(width 0.18288)
		(layer "In11.Cu")
		(net "M_D_CPU1_SA_CA<5>")
	)
	(segment
		(start 53.199792 -258.080002)
		(end 52.701698 -257.581908)
		(width 0.18288)
		(layer "In11.Cu")
		(net "M_D_CPU1_SA_CA<5>")
	)
	(segment
		(start 83.651598 -255.695958)
		(end 82.987134 -255.695958)
		(width 0.088646)
		(layer "In11.Cu")
		(net "M_D_CPU1_SA_CA<5>")
	)
	(segment
		(start 82.987134 -255.695958)
		(end 80.905604 -255.695958)
		(width 0.18288)
		(layer "In11.Cu")
		(net "M_D_CPU1_SA_CA<5>")
	)
	(arc
		(start 86.562692 -255.87198)
		(mid 86.375494 -255.922123)
		(end 86.188296 -255.87198)
		(width 0.088646)
		(layer "In11.Cu")
		(net "M_D_CPU1_SA_CA<5>")
	)
	(arc
		(start 97.46615 -255.87198)
		(mid 97.191951 -255.796145)
		(end 96.915478 -255.863344)
		(width 0.088646)
		(layer "In11.Cu")
		(net "M_D_CPU1_SA_CA<5>")
	)
	(arc
		(start 88.442292 -255.87198)
		(mid 88.255094 -255.922123)
		(end 88.067896 -255.87198)
		(width 0.088646)
		(layer "In11.Cu")
		(net "M_D_CPU1_SA_CA<5>")
	)
	(arc
		(start 90.88755 -255.87198)
		(mid 90.610737 -255.79611)
		(end 90.332306 -255.865884)
		(width 0.088646)
		(layer "In11.Cu")
		(net "M_D_CPU1_SA_CA<5>")
	)
	(arc
		(start 100.002594 -256.361438)
		(mid 99.704104 -256.105502)
		(end 99.375722 -255.889252)
		(width 0.088646)
		(layer "In11.Cu")
		(net "M_D_CPU1_SA_CA<5>")
	)
	(arc
		(start 94.64675 -255.87198)
		(mid 94.364048 -255.796204)
		(end 94.081346 -255.87198)
		(width 0.088646)
		(layer "In11.Cu")
		(net "M_D_CPU1_SA_CA<5>")
	)
	(arc
		(start 95.960946 -255.87198)
		(mid 95.773748 -255.922123)
		(end 95.58655 -255.87198)
		(width 0.088646)
		(layer "In11.Cu")
		(net "M_D_CPU1_SA_CA<5>")
	)
	(arc
		(start 86.188296 -255.87198)
		(mid 85.905594 -255.796204)
		(end 85.622892 -255.87198)
		(width 0.088646)
		(layer "In11.Cu")
		(net "M_D_CPU1_SA_CA<5>")
	)
	(arc
		(start 92.201492 -255.87198)
		(mid 92.014294 -255.922123)
		(end 91.827096 -255.87198)
		(width 0.088646)
		(layer "In11.Cu")
		(net "M_D_CPU1_SA_CA<5>")
	)
	(arc
		(start 94.081346 -255.87198)
		(mid 93.894148 -255.922123)
		(end 93.70695 -255.87198)
		(width 0.088646)
		(layer "In11.Cu")
		(net "M_D_CPU1_SA_CA<5>")
	)
	(arc
		(start 89.947496 -255.87198)
		(mid 89.670937 -255.796237)
		(end 89.39276 -255.865884)
		(width 0.088646)
		(layer "In11.Cu")
		(net "M_D_CPU1_SA_CA<5>")
	)
	(arc
		(start 93.70695 -255.87198)
		(mid 93.432751 -255.796145)
		(end 93.156278 -255.863344)
		(width 0.088646)
		(layer "In11.Cu")
		(net "M_D_CPU1_SA_CA<5>")
	)
	(arc
		(start 98.405696 -255.87198)
		(mid 98.129137 -255.796237)
		(end 97.85096 -255.865884)
		(width 0.088646)
		(layer "In11.Cu")
		(net "M_D_CPU1_SA_CA<5>")
	)
	(arc
		(start 84.683092 -255.87198)
		(mid 84.495894 -255.922123)
		(end 84.308696 -255.87198)
		(width 0.088646)
		(layer "In11.Cu")
		(net "M_D_CPU1_SA_CA<5>")
	)
	(arc
		(start 88.067896 -255.87198)
		(mid 87.785194 -255.796204)
		(end 87.502492 -255.87198)
		(width 0.088646)
		(layer "In11.Cu")
		(net "M_D_CPU1_SA_CA<5>")
	)
	(arc
		(start 97.840546 -255.87198)
		(mid 97.653348 -255.922123)
		(end 97.46615 -255.87198)
		(width 0.088646)
		(layer "In11.Cu")
		(net "M_D_CPU1_SA_CA<5>")
	)
	(arc
		(start 96.900746 -255.87198)
		(mid 96.713548 -255.922123)
		(end 96.52635 -255.87198)
		(width 0.088646)
		(layer "In11.Cu")
		(net "M_D_CPU1_SA_CA<5>")
	)
	(arc
		(start 99.345242 -255.87198)
		(mid 99.06265 -255.796204)
		(end 98.780092 -255.87198)
		(width 0.088646)
		(layer "In11.Cu")
		(net "M_D_CPU1_SA_CA<5>")
	)
	(arc
		(start 89.00795 -255.87198)
		(mid 88.731137 -255.79611)
		(end 88.452706 -255.865884)
		(width 0.088646)
		(layer "In11.Cu")
		(net "M_D_CPU1_SA_CA<5>")
	)
	(arc
		(start 95.58655 -255.87198)
		(mid 95.312351 -255.796145)
		(end 95.035878 -255.863344)
		(width 0.088646)
		(layer "In11.Cu")
		(net "M_D_CPU1_SA_CA<5>")
	)
	(arc
		(start 98.780092 -255.87198)
		(mid 98.592894 -255.922123)
		(end 98.405696 -255.87198)
		(width 0.088646)
		(layer "In11.Cu")
		(net "M_D_CPU1_SA_CA<5>")
	)
	(arc
		(start 96.52635 -255.87198)
		(mid 96.252151 -255.796145)
		(end 95.975678 -255.863344)
		(width 0.088646)
		(layer "In11.Cu")
		(net "M_D_CPU1_SA_CA<5>")
	)
	(arc
		(start 91.261946 -255.87198)
		(mid 91.074748 -255.922123)
		(end 90.88755 -255.87198)
		(width 0.088646)
		(layer "In11.Cu")
		(net "M_D_CPU1_SA_CA<5>")
	)
	(arc
		(start 89.382346 -255.87198)
		(mid 89.195148 -255.922123)
		(end 89.00795 -255.87198)
		(width 0.088646)
		(layer "In11.Cu")
		(net "M_D_CPU1_SA_CA<5>")
	)
	(arc
		(start 85.622892 -255.87198)
		(mid 85.435694 -255.922123)
		(end 85.248496 -255.87198)
		(width 0.088646)
		(layer "In11.Cu")
		(net "M_D_CPU1_SA_CA<5>")
	)
	(arc
		(start 87.502492 -255.87198)
		(mid 87.315294 -255.922123)
		(end 87.128096 -255.87198)
		(width 0.088646)
		(layer "In11.Cu")
		(net "M_D_CPU1_SA_CA<5>")
	)
	(arc
		(start 85.248496 -255.87198)
		(mid 84.965794 -255.796204)
		(end 84.683092 -255.87198)
		(width 0.088646)
		(layer "In11.Cu")
		(net "M_D_CPU1_SA_CA<5>")
	)
	(arc
		(start 93.141546 -255.87198)
		(mid 92.954348 -255.922123)
		(end 92.76715 -255.87198)
		(width 0.088646)
		(layer "In11.Cu")
		(net "M_D_CPU1_SA_CA<5>")
	)
	(arc
		(start 95.021146 -255.87198)
		(mid 94.833948 -255.922123)
		(end 94.64675 -255.87198)
		(width 0.088646)
		(layer "In11.Cu")
		(net "M_D_CPU1_SA_CA<5>")
	)
	(arc
		(start 91.827096 -255.87198)
		(mid 91.550537 -255.796237)
		(end 91.27236 -255.865884)
		(width 0.088646)
		(layer "In11.Cu")
		(net "M_D_CPU1_SA_CA<5>")
	)
	(arc
		(start 84.308696 -255.87198)
		(mid 84.172327 -255.815538)
		(end 84.025994 -255.796288)
		(width 0.088646)
		(layer "In11.Cu")
		(net "M_D_CPU1_SA_CA<5>")
	)
	(arc
		(start 90.321892 -255.87198)
		(mid 90.134694 -255.922123)
		(end 89.947496 -255.87198)
		(width 0.088646)
		(layer "In11.Cu")
		(net "M_D_CPU1_SA_CA<5>")
	)
	(arc
		(start 87.128096 -255.87198)
		(mid 86.845394 -255.796204)
		(end 86.562692 -255.87198)
		(width 0.088646)
		(layer "In11.Cu")
		(net "M_D_CPU1_SA_CA<5>")
	)
	(arc
		(start 92.76715 -255.87198)
		(mid 92.490337 -255.79611)
		(end 92.211906 -255.865884)
		(width 0.088646)
		(layer "In11.Cu")
		(net "M_D_CPU1_SA_CA<5>")
	)
	(segment
		(start 99.063048 -255.825498)
		(end 99.063048 -256.361184)
		(width 0.20066)
		(layer "F.Cu")
		(net "M_D_CPU1_SA_CA<4>")
	)
	(segment
		(start 99.063048 -256.361184)
		(end 99.062794 -256.361438)
		(width 0.20066)
		(layer "F.Cu")
		(net "M_D_CPU1_SA_CA<4>")
	)
	(segment
		(start 8.140446 -262.76681)
		(end 9.474708 -262.76681)
		(width 0.20066)
		(layer "F.Cu")
		(net "M_D_CPU1_SA_CA<4>")
	)
	(segment
		(start 10.507472 -262.332978)
		(end 11.11631 -262.332978)
		(width 0.20066)
		(layer "F.Cu")
		(net "M_D_CPU1_SA_CA<4>")
	)
	(segment
		(start 13.110718 -262.341868)
		(end 13.441426 -262.341868)
		(width 0.101854)
		(layer "F.Cu")
		(net "M_D_CPU1_SA_CA<4>")
	)
	(segment
		(start 11.1252 -262.341868)
		(end 13.110718 -262.341868)
		(width 0.1016)
		(layer "F.Cu")
		(net "M_D_CPU1_SA_CA<4>")
	)
	(segment
		(start 11.11631 -262.332978)
		(end 11.1252 -262.341868)
		(width 0.1016)
		(layer "F.Cu")
		(net "M_D_CPU1_SA_CA<4>")
	)
	(segment
		(start 9.686036 -262.978138)
		(end 10.19048 -262.978138)
		(width 0.20066)
		(layer "F.Cu")
		(net "M_D_CPU1_SA_CA<4>")
	)
	(segment
		(start 14.04493 -262.76681)
		(end 15.684246 -262.76681)
		(width 0.20066)
		(layer "F.Cu")
		(net "M_D_CPU1_SA_CA<4>")
	)
	(segment
		(start 13.619988 -262.341868)
		(end 14.04493 -262.76681)
		(width 0.20066)
		(layer "F.Cu")
		(net "M_D_CPU1_SA_CA<4>")
	)
	(segment
		(start 10.344912 -262.495538)
		(end 10.507472 -262.332978)
		(width 0.20066)
		(layer "F.Cu")
		(net "M_D_CPU1_SA_CA<4>")
	)
	(segment
		(start 10.344912 -262.823706)
		(end 10.344912 -262.495538)
		(width 0.20066)
		(layer "F.Cu")
		(net "M_D_CPU1_SA_CA<4>")
	)
	(segment
		(start 16.789146 -262.76681)
		(end 15.684246 -262.76681)
		(width 0.20066)
		(layer "F.Cu")
		(net "M_D_CPU1_SA_CA<4>")
	)
	(segment
		(start 9.474708 -262.76681)
		(end 9.686036 -262.978138)
		(width 0.20066)
		(layer "F.Cu")
		(net "M_D_CPU1_SA_CA<4>")
	)
	(segment
		(start 13.441426 -262.341868)
		(end 13.619988 -262.341868)
		(width 0.20066)
		(layer "F.Cu")
		(net "M_D_CPU1_SA_CA<4>")
	)
	(segment
		(start 10.19048 -262.978138)
		(end 10.344912 -262.823706)
		(width 0.20066)
		(layer "F.Cu")
		(net "M_D_CPU1_SA_CA<4>")
	)
	(segment
		(start 47.656242 -258.941062)
		(end 45.811694 -258.941062)
		(width 0.18288)
		(layer "In11.Cu")
		(net "M_D_CPU1_SA_CA<4>")
	)
	(segment
		(start 21.222462 -262.341868)
		(end 20.563078 -262.341868)
		(width 0.18288)
		(layer "In11.Cu")
		(net "M_D_CPU1_SA_CA<4>")
	)
	(segment
		(start 91.357196 -256.03708)
		(end 91.342464 -256.045716)
		(width 0.088646)
		(layer "In11.Cu")
		(net "M_D_CPU1_SA_CA<4>")
	)
	(segment
		(start 52.483258 -258.089908)
		(end 50.838608 -258.089908)
		(width 0.18288)
		(layer "In11.Cu")
		(net "M_D_CPU1_SA_CA<4>")
	)
	(segment
		(start 59.148726 -258.703826)
		(end 58.857896 -258.994656)
		(width 0.18288)
		(layer "In11.Cu")
		(net "M_D_CPU1_SA_CA<4>")
	)
	(segment
		(start 24.668226 -260.786626)
		(end 24.01443 -260.786626)
		(width 0.18288)
		(layer "In11.Cu")
		(net "M_D_CPU1_SA_CA<4>")
	)
	(segment
		(start 89.477596 -256.03708)
		(end 89.462864 -256.045716)
		(width 0.088646)
		(layer "In11.Cu")
		(net "M_D_CPU1_SA_CA<4>")
	)
	(segment
		(start 37.792152 -258.907026)
		(end 37.792152 -258.425696)
		(width 0.18288)
		(layer "In11.Cu")
		(net "M_D_CPU1_SA_CA<4>")
	)
	(segment
		(start 93.236796 -256.03708)
		(end 93.222064 -256.045716)
		(width 0.088646)
		(layer "In11.Cu")
		(net "M_D_CPU1_SA_CA<4>")
	)
	(segment
		(start 67.397376 -256.620264)
		(end 65.898268 -257.240786)
		(width 0.18288)
		(layer "In11.Cu")
		(net "M_D_CPU1_SA_CA<4>")
	)
	(segment
		(start 29.866844 -258.089908)
		(end 28.207208 -258.089908)
		(width 0.18288)
		(layer "In11.Cu")
		(net "M_D_CPU1_SA_CA<4>")
	)
	(segment
		(start 43.294808 -258.089908)
		(end 42.27449 -259.110226)
		(width 0.18288)
		(layer "In11.Cu")
		(net "M_D_CPU1_SA_CA<4>")
	)
	(segment
		(start 95.116396 -256.03708)
		(end 95.105982 -256.043176)
		(width 0.088646)
		(layer "In11.Cu")
		(net "M_D_CPU1_SA_CA<4>")
	)
	(segment
		(start 96.995996 -256.03708)
		(end 96.981264 -256.045716)
		(width 0.088646)
		(layer "In11.Cu")
		(net "M_D_CPU1_SA_CA<4>")
	)
	(segment
		(start 26.32329 -259.973826)
		(end 25.481026 -259.973826)
		(width 0.18288)
		(layer "In11.Cu")
		(net "M_D_CPU1_SA_CA<4>")
	)
	(segment
		(start 37.792152 -258.425696)
		(end 37.456364 -258.089908)
		(width 0.18288)
		(layer "In11.Cu")
		(net "M_D_CPU1_SA_CA<4>")
	)
	(segment
		(start 24.01443 -260.786626)
		(end 22.350984 -262.450072)
		(width 0.18288)
		(layer "In11.Cu")
		(net "M_D_CPU1_SA_CA<4>")
	)
	(segment
		(start 30.718252 -258.941316)
		(end 29.866844 -258.089908)
		(width 0.18288)
		(layer "In11.Cu")
		(net "M_D_CPU1_SA_CA<4>")
	)
	(segment
		(start 80.470248 -256.620264)
		(end 67.397376 -256.620264)
		(width 0.18288)
		(layer "In11.Cu")
		(net "M_D_CPU1_SA_CA<4>")
	)
	(segment
		(start 82.987134 -256.108708)
		(end 80.981804 -256.108708)
		(width 0.18288)
		(layer "In11.Cu")
		(net "M_D_CPU1_SA_CA<4>")
	)
	(segment
		(start 59.957462 -257.880612)
		(end 59.591956 -258.031996)
		(width 0.18288)
		(layer "In11.Cu")
		(net "M_D_CPU1_SA_CA<4>")
	)
	(segment
		(start 58.857896 -258.994656)
		(end 53.388006 -258.994656)
		(width 0.18288)
		(layer "In11.Cu")
		(net "M_D_CPU1_SA_CA<4>")
	)
	(segment
		(start 96.056196 -256.03708)
		(end 96.041464 -256.045716)
		(width 0.088646)
		(layer "In11.Cu")
		(net "M_D_CPU1_SA_CA<4>")
	)
	(segment
		(start 59.148726 -258.475226)
		(end 59.148726 -258.703826)
		(width 0.18288)
		(layer "In11.Cu")
		(net "M_D_CPU1_SA_CA<4>")
	)
	(segment
		(start 59.591956 -258.031996)
		(end 59.148726 -258.475226)
		(width 0.18288)
		(layer "In11.Cu")
		(net "M_D_CPU1_SA_CA<4>")
	)
	(segment
		(start 50.838608 -258.089908)
		(end 49.850802 -259.077714)
		(width 0.18288)
		(layer "In11.Cu")
		(net "M_D_CPU1_SA_CA<4>")
	)
	(segment
		(start 32.137604 -258.941316)
		(end 30.718252 -258.941316)
		(width 0.18288)
		(layer "In11.Cu")
		(net "M_D_CPU1_SA_CA<4>")
	)
	(segment
		(start 32.514032 -259.317744)
		(end 32.137604 -258.941316)
		(width 0.18288)
		(layer "In11.Cu")
		(net "M_D_CPU1_SA_CA<4>")
	)
	(segment
		(start 42.27449 -259.110226)
		(end 37.995352 -259.110226)
		(width 0.18288)
		(layer "In11.Cu")
		(net "M_D_CPU1_SA_CA<4>")
	)
	(segment
		(start 47.792894 -259.077714)
		(end 47.656242 -258.941062)
		(width 0.18288)
		(layer "In11.Cu")
		(net "M_D_CPU1_SA_CA<4>")
	)
	(segment
		(start 21.330666 -262.450072)
		(end 21.222462 -262.341868)
		(width 0.18288)
		(layer "In11.Cu")
		(net "M_D_CPU1_SA_CA<4>")
	)
	(segment
		(start 37.995352 -259.110226)
		(end 37.792152 -258.907026)
		(width 0.18288)
		(layer "In11.Cu")
		(net "M_D_CPU1_SA_CA<4>")
	)
	(segment
		(start 83.634326 -255.986534)
		(end 83.512152 -256.108708)
		(width 0.088646)
		(layer "In11.Cu")
		(net "M_D_CPU1_SA_CA<4>")
	)
	(segment
		(start 17.2593 -263.236964)
		(end 16.789146 -262.76681)
		(width 0.18288)
		(layer "In11.Cu")
		(net "M_D_CPU1_SA_CA<4>")
	)
	(segment
		(start 98.340672 -256.054606)
		(end 98.310446 -256.03708)
		(width 0.088646)
		(layer "In11.Cu")
		(net "M_D_CPU1_SA_CA<4>")
	)
	(segment
		(start 34.523172 -259.317744)
		(end 32.514032 -259.317744)
		(width 0.18288)
		(layer "In11.Cu")
		(net "M_D_CPU1_SA_CA<4>")
	)
	(segment
		(start 37.456364 -258.089908)
		(end 35.751008 -258.089908)
		(width 0.18288)
		(layer "In11.Cu")
		(net "M_D_CPU1_SA_CA<4>")
	)
	(segment
		(start 65.898268 -257.240786)
		(end 65.258442 -257.880612)
		(width 0.18288)
		(layer "In11.Cu")
		(net "M_D_CPU1_SA_CA<4>")
	)
	(segment
		(start 80.981804 -256.108708)
		(end 80.470248 -256.620264)
		(width 0.18288)
		(layer "In11.Cu")
		(net "M_D_CPU1_SA_CA<4>")
	)
	(segment
		(start 84.025994 -255.986534)
		(end 83.634326 -255.986534)
		(width 0.088646)
		(layer "In11.Cu")
		(net "M_D_CPU1_SA_CA<4>")
	)
	(segment
		(start 45.811694 -258.941062)
		(end 44.96054 -258.089908)
		(width 0.18288)
		(layer "In11.Cu")
		(net "M_D_CPU1_SA_CA<4>")
	)
	(segment
		(start 19.667982 -263.236964)
		(end 17.2593 -263.236964)
		(width 0.18288)
		(layer "In11.Cu")
		(net "M_D_CPU1_SA_CA<4>")
	)
	(segment
		(start 83.512152 -256.108708)
		(end 82.987134 -256.108708)
		(width 0.088646)
		(layer "In11.Cu")
		(net "M_D_CPU1_SA_CA<4>")
	)
	(segment
		(start 97.935796 -256.03708)
		(end 97.921064 -256.045716)
		(width 0.088646)
		(layer "In11.Cu")
		(net "M_D_CPU1_SA_CA<4>")
	)
	(segment
		(start 35.751008 -258.089908)
		(end 34.523172 -259.317744)
		(width 0.18288)
		(layer "In11.Cu")
		(net "M_D_CPU1_SA_CA<4>")
	)
	(segment
		(start 22.350984 -262.450072)
		(end 21.330666 -262.450072)
		(width 0.18288)
		(layer "In11.Cu")
		(net "M_D_CPU1_SA_CA<4>")
	)
	(segment
		(start 20.563078 -262.341868)
		(end 19.667982 -263.236964)
		(width 0.18288)
		(layer "In11.Cu")
		(net "M_D_CPU1_SA_CA<4>")
	)
	(segment
		(start 44.96054 -258.089908)
		(end 43.294808 -258.089908)
		(width 0.18288)
		(layer "In11.Cu")
		(net "M_D_CPU1_SA_CA<4>")
	)
	(segment
		(start 98.310446 -256.03708)
		(end 98.310192 -256.03708)
		(width 0.088646)
		(layer "In11.Cu")
		(net "M_D_CPU1_SA_CA<4>")
	)
	(segment
		(start 65.258442 -257.880612)
		(end 59.957462 -257.880612)
		(width 0.18288)
		(layer "In11.Cu")
		(net "M_D_CPU1_SA_CA<4>")
	)
	(segment
		(start 53.388006 -258.994656)
		(end 52.483258 -258.089908)
		(width 0.18288)
		(layer "In11.Cu")
		(net "M_D_CPU1_SA_CA<4>")
	)
	(segment
		(start 94.17685 -256.03708)
		(end 94.166436 -256.043176)
		(width 0.088646)
		(layer "In11.Cu")
		(net "M_D_CPU1_SA_CA<4>")
	)
	(segment
		(start 25.481026 -259.973826)
		(end 24.668226 -260.786626)
		(width 0.18288)
		(layer "In11.Cu")
		(net "M_D_CPU1_SA_CA<4>")
	)
	(segment
		(start 28.207208 -258.089908)
		(end 26.32329 -259.973826)
		(width 0.18288)
		(layer "In11.Cu")
		(net "M_D_CPU1_SA_CA<4>")
	)
	(segment
		(start 49.850802 -259.077714)
		(end 47.792894 -259.077714)
		(width 0.18288)
		(layer "In11.Cu")
		(net "M_D_CPU1_SA_CA<4>")
	)
	(arc
		(start 84.778596 -256.03708)
		(mid 84.495894 -256.112856)
		(end 84.213192 -256.03708)
		(width 0.088646)
		(layer "In11.Cu")
		(net "M_D_CPU1_SA_CA<4>")
	)
	(arc
		(start 87.032592 -256.03708)
		(mid 86.845394 -255.986937)
		(end 86.658196 -256.03708)
		(width 0.088646)
		(layer "In11.Cu")
		(net "M_D_CPU1_SA_CA<4>")
	)
	(arc
		(start 90.417396 -256.03708)
		(mid 90.134694 -256.112856)
		(end 89.851992 -256.03708)
		(width 0.088646)
		(layer "In11.Cu")
		(net "M_D_CPU1_SA_CA<4>")
	)
	(arc
		(start 89.462864 -256.045716)
		(mid 89.186389 -256.113036)
		(end 88.912192 -256.03708)
		(width 0.088646)
		(layer "In11.Cu")
		(net "M_D_CPU1_SA_CA<4>")
	)
	(arc
		(start 86.092792 -256.03708)
		(mid 85.905594 -255.986937)
		(end 85.718396 -256.03708)
		(width 0.088646)
		(layer "In11.Cu")
		(net "M_D_CPU1_SA_CA<4>")
	)
	(arc
		(start 96.430592 -256.03708)
		(mid 96.243394 -255.986937)
		(end 96.056196 -256.03708)
		(width 0.088646)
		(layer "In11.Cu")
		(net "M_D_CPU1_SA_CA<4>")
	)
	(arc
		(start 85.718396 -256.03708)
		(mid 85.435694 -256.112856)
		(end 85.152992 -256.03708)
		(width 0.088646)
		(layer "In11.Cu")
		(net "M_D_CPU1_SA_CA<4>")
	)
	(arc
		(start 85.152992 -256.03708)
		(mid 84.965794 -255.986937)
		(end 84.778596 -256.03708)
		(width 0.088646)
		(layer "In11.Cu")
		(net "M_D_CPU1_SA_CA<4>")
	)
	(arc
		(start 88.537796 -256.03708)
		(mid 88.255094 -256.112856)
		(end 87.972392 -256.03708)
		(width 0.088646)
		(layer "In11.Cu")
		(net "M_D_CPU1_SA_CA<4>")
	)
	(arc
		(start 84.213192 -256.03708)
		(mid 84.12292 -255.999481)
		(end 84.025994 -255.986534)
		(width 0.088646)
		(layer "In11.Cu")
		(net "M_D_CPU1_SA_CA<4>")
	)
	(arc
		(start 88.912192 -256.03708)
		(mid 88.724994 -255.986937)
		(end 88.537796 -256.03708)
		(width 0.088646)
		(layer "In11.Cu")
		(net "M_D_CPU1_SA_CA<4>")
	)
	(arc
		(start 96.981264 -256.045716)
		(mid 96.704789 -256.113036)
		(end 96.430592 -256.03708)
		(width 0.088646)
		(layer "In11.Cu")
		(net "M_D_CPU1_SA_CA<4>")
	)
	(arc
		(start 97.370392 -256.03708)
		(mid 97.183194 -255.986937)
		(end 96.995996 -256.03708)
		(width 0.088646)
		(layer "In11.Cu")
		(net "M_D_CPU1_SA_CA<4>")
	)
	(arc
		(start 87.972392 -256.03708)
		(mid 87.785194 -255.986937)
		(end 87.597996 -256.03708)
		(width 0.088646)
		(layer "In11.Cu")
		(net "M_D_CPU1_SA_CA<4>")
	)
	(arc
		(start 92.296996 -256.03708)
		(mid 92.014294 -256.112856)
		(end 91.731592 -256.03708)
		(width 0.088646)
		(layer "In11.Cu")
		(net "M_D_CPU1_SA_CA<4>")
	)
	(arc
		(start 93.611192 -256.03708)
		(mid 93.423994 -255.986937)
		(end 93.236796 -256.03708)
		(width 0.088646)
		(layer "In11.Cu")
		(net "M_D_CPU1_SA_CA<4>")
	)
	(arc
		(start 95.490792 -256.03708)
		(mid 95.303594 -255.986937)
		(end 95.116396 -256.03708)
		(width 0.088646)
		(layer "In11.Cu")
		(net "M_D_CPU1_SA_CA<4>")
	)
	(arc
		(start 89.851992 -256.03708)
		(mid 89.664794 -255.986937)
		(end 89.477596 -256.03708)
		(width 0.088646)
		(layer "In11.Cu")
		(net "M_D_CPU1_SA_CA<4>")
	)
	(arc
		(start 90.791792 -256.03708)
		(mid 90.604594 -255.986937)
		(end 90.417396 -256.03708)
		(width 0.088646)
		(layer "In11.Cu")
		(net "M_D_CPU1_SA_CA<4>")
	)
	(arc
		(start 93.222064 -256.045716)
		(mid 92.945589 -256.113036)
		(end 92.671392 -256.03708)
		(width 0.088646)
		(layer "In11.Cu")
		(net "M_D_CPU1_SA_CA<4>")
	)
	(arc
		(start 87.597996 -256.03708)
		(mid 87.315294 -256.112856)
		(end 87.032592 -256.03708)
		(width 0.088646)
		(layer "In11.Cu")
		(net "M_D_CPU1_SA_CA<4>")
	)
	(arc
		(start 94.551246 -256.03708)
		(mid 94.364048 -255.986937)
		(end 94.17685 -256.03708)
		(width 0.088646)
		(layer "In11.Cu")
		(net "M_D_CPU1_SA_CA<4>")
	)
	(arc
		(start 98.310192 -256.03708)
		(mid 98.122994 -255.986937)
		(end 97.935796 -256.03708)
		(width 0.088646)
		(layer "In11.Cu")
		(net "M_D_CPU1_SA_CA<4>")
	)
	(arc
		(start 86.658196 -256.03708)
		(mid 86.375494 -256.112856)
		(end 86.092792 -256.03708)
		(width 0.088646)
		(layer "In11.Cu")
		(net "M_D_CPU1_SA_CA<4>")
	)
	(arc
		(start 91.731592 -256.03708)
		(mid 91.544394 -255.986937)
		(end 91.357196 -256.03708)
		(width 0.088646)
		(layer "In11.Cu")
		(net "M_D_CPU1_SA_CA<4>")
	)
	(arc
		(start 99.062794 -256.361438)
		(mid 98.692239 -256.230368)
		(end 98.340672 -256.054606)
		(width 0.088646)
		(layer "In11.Cu")
		(net "M_D_CPU1_SA_CA<4>")
	)
	(arc
		(start 95.105982 -256.043176)
		(mid 94.827804 -256.112899)
		(end 94.551246 -256.03708)
		(width 0.088646)
		(layer "In11.Cu")
		(net "M_D_CPU1_SA_CA<4>")
	)
	(arc
		(start 91.342464 -256.045716)
		(mid 91.065989 -256.113036)
		(end 90.791792 -256.03708)
		(width 0.088646)
		(layer "In11.Cu")
		(net "M_D_CPU1_SA_CA<4>")
	)
	(arc
		(start 92.671392 -256.03708)
		(mid 92.484194 -255.986937)
		(end 92.296996 -256.03708)
		(width 0.088646)
		(layer "In11.Cu")
		(net "M_D_CPU1_SA_CA<4>")
	)
	(arc
		(start 94.166436 -256.043176)
		(mid 93.888004 -256.113022)
		(end 93.611192 -256.03708)
		(width 0.088646)
		(layer "In11.Cu")
		(net "M_D_CPU1_SA_CA<4>")
	)
	(arc
		(start 97.921064 -256.045716)
		(mid 97.644589 -256.113036)
		(end 97.370392 -256.03708)
		(width 0.088646)
		(layer "In11.Cu")
		(net "M_D_CPU1_SA_CA<4>")
	)
	(arc
		(start 96.041464 -256.045716)
		(mid 95.764989 -256.113036)
		(end 95.490792 -256.03708)
		(width 0.088646)
		(layer "In11.Cu")
		(net "M_D_CPU1_SA_CA<4>")
	)
	(segment
		(start 18.968212 -263.616694)
		(end 19.784314 -263.616694)
		(width 0.20066)
		(layer "F.Cu")
		(net "M_D_CPU1_SA_CA<3>")
	)
	(segment
		(start 18.314162 -263.824212)
		(end 18.760694 -263.824212)
		(width 0.20066)
		(layer "F.Cu")
		(net "M_D_CPU1_SA_CA<3>")
	)
	(segment
		(start 13.937742 -263.616694)
		(end 14.063726 -263.742678)
		(width 0.20066)
		(layer "F.Cu")
		(net "M_D_CPU1_SA_CA<3>")
	)
	(segment
		(start 14.063726 -263.742678)
		(end 14.063726 -263.913366)
		(width 0.20066)
		(layer "F.Cu")
		(net "M_D_CPU1_SA_CA<3>")
	)
	(segment
		(start 14.812264 -264.041636)
		(end 16.885158 -264.041636)
		(width 0.1016)
		(layer "F.Cu")
		(net "M_D_CPU1_SA_CA<3>")
	)
	(segment
		(start 14.20622 -264.05586)
		(end 14.560042 -264.05586)
		(width 0.20066)
		(layer "F.Cu")
		(net "M_D_CPU1_SA_CA<3>")
	)
	(segment
		(start 17.707102 -263.612376)
		(end 18.102326 -263.612376)
		(width 0.20066)
		(layer "F.Cu")
		(net "M_D_CPU1_SA_CA<3>")
	)
	(segment
		(start 18.760694 -263.824212)
		(end 18.968212 -263.616694)
		(width 0.20066)
		(layer "F.Cu")
		(net "M_D_CPU1_SA_CA<3>")
	)
	(segment
		(start 17.578578 -263.7409)
		(end 17.707102 -263.612376)
		(width 0.20066)
		(layer "F.Cu")
		(net "M_D_CPU1_SA_CA<3>")
	)
	(segment
		(start 17.578578 -263.892538)
		(end 17.578578 -263.7409)
		(width 0.20066)
		(layer "F.Cu")
		(net "M_D_CPU1_SA_CA<3>")
	)
	(segment
		(start 14.574266 -264.041636)
		(end 14.812264 -264.041636)
		(width 0.101854)
		(layer "F.Cu")
		(net "M_D_CPU1_SA_CA<3>")
	)
	(segment
		(start 14.560042 -264.05586)
		(end 14.574266 -264.041636)
		(width 0.101854)
		(layer "F.Cu")
		(net "M_D_CPU1_SA_CA<3>")
	)
	(segment
		(start 20.889214 -263.616694)
		(end 19.784314 -263.616694)
		(width 0.20066)
		(layer "F.Cu")
		(net "M_D_CPU1_SA_CA<3>")
	)
	(segment
		(start 12.240514 -263.616694)
		(end 13.937742 -263.616694)
		(width 0.20066)
		(layer "F.Cu")
		(net "M_D_CPU1_SA_CA<3>")
	)
	(segment
		(start 100.472494 -256.639314)
		(end 100.472494 -257.175)
		(width 0.20066)
		(layer "F.Cu")
		(net "M_D_CPU1_SA_CA<3>")
	)
	(segment
		(start 17.42948 -264.041636)
		(end 17.578578 -263.892538)
		(width 0.20066)
		(layer "F.Cu")
		(net "M_D_CPU1_SA_CA<3>")
	)
	(segment
		(start 14.063726 -263.913366)
		(end 14.20622 -264.05586)
		(width 0.20066)
		(layer "F.Cu")
		(net "M_D_CPU1_SA_CA<3>")
	)
	(segment
		(start 18.102326 -263.612376)
		(end 18.314162 -263.824212)
		(width 0.20066)
		(layer "F.Cu")
		(net "M_D_CPU1_SA_CA<3>")
	)
	(segment
		(start 100.472494 -257.175)
		(end 100.472748 -257.175254)
		(width 0.20066)
		(layer "F.Cu")
		(net "M_D_CPU1_SA_CA<3>")
	)
	(segment
		(start 16.885158 -264.041636)
		(end 17.42948 -264.041636)
		(width 0.20066)
		(layer "F.Cu")
		(net "M_D_CPU1_SA_CA<3>")
	)
	(segment
		(start 24.162766 -261.419086)
		(end 22.610826 -262.971026)
		(width 0.18288)
		(layer "In11.Cu")
		(net "M_D_CPU1_SA_CA<3>")
	)
	(segment
		(start 53.563266 -260.032754)
		(end 53.215286 -260.032754)
		(width 0.18288)
		(layer "In11.Cu")
		(net "M_D_CPU1_SA_CA<3>")
	)
	(segment
		(start 24.772366 -261.419086)
		(end 24.162766 -261.419086)
		(width 0.18288)
		(layer "In11.Cu")
		(net "M_D_CPU1_SA_CA<3>")
	)
	(segment
		(start 34.682176 -259.90423)
		(end 32.301688 -259.90423)
		(width 0.18288)
		(layer "In11.Cu")
		(net "M_D_CPU1_SA_CA<3>")
	)
	(segment
		(start 44.99737 -259.7912)
		(end 44.147486 -258.941316)
		(width 0.18288)
		(layer "In11.Cu")
		(net "M_D_CPU1_SA_CA<3>")
	)
	(segment
		(start 37.305234 -259.643626)
		(end 36.60267 -258.941062)
		(width 0.18288)
		(layer "In11.Cu")
		(net "M_D_CPU1_SA_CA<3>")
	)
	(segment
		(start 43.242484 -258.941316)
		(end 42.3926 -259.7912)
		(width 0.18288)
		(layer "In11.Cu")
		(net "M_D_CPU1_SA_CA<3>")
	)
	(segment
		(start 71.502524 -257.225038)
		(end 67.583812 -257.225038)
		(width 0.18288)
		(layer "In11.Cu")
		(net "M_D_CPU1_SA_CA<3>")
	)
	(segment
		(start 96.995996 -256.685796)
		(end 96.981264 -256.67716)
		(width 0.088646)
		(layer "In11.Cu")
		(net "M_D_CPU1_SA_CA<3>")
	)
	(segment
		(start 83.825842 -256.736342)
		(end 83.557618 -256.468118)
		(width 0.088646)
		(layer "In11.Cu")
		(net "M_D_CPU1_SA_CA<3>")
	)
	(segment
		(start 32.301688 -259.90423)
		(end 32.188658 -259.7912)
		(width 0.18288)
		(layer "In11.Cu")
		(net "M_D_CPU1_SA_CA<3>")
	)
	(segment
		(start 31.115 -259.7912)
		(end 30.891226 -259.567426)
		(width 0.18288)
		(layer "In11.Cu")
		(net "M_D_CPU1_SA_CA<3>")
	)
	(segment
		(start 99.907598 -256.739644)
		(end 99.815396 -256.685796)
		(width 0.088646)
		(layer "In11.Cu")
		(net "M_D_CPU1_SA_CA<3>")
	)
	(segment
		(start 53.215286 -260.032754)
		(end 53.005228 -259.822696)
		(width 0.18288)
		(layer "In11.Cu")
		(net "M_D_CPU1_SA_CA<3>")
	)
	(segment
		(start 36.60267 -258.941062)
		(end 35.645344 -258.941062)
		(width 0.18288)
		(layer "In11.Cu")
		(net "M_D_CPU1_SA_CA<3>")
	)
	(segment
		(start 53.723286 -259.872734)
		(end 53.563266 -260.032754)
		(width 0.18288)
		(layer "In11.Cu")
		(net "M_D_CPU1_SA_CA<3>")
	)
	(segment
		(start 81.11109 -256.468118)
		(end 80.613504 -256.965704)
		(width 0.18288)
		(layer "In11.Cu")
		(net "M_D_CPU1_SA_CA<3>")
	)
	(segment
		(start 82.987134 -256.468118)
		(end 81.11109 -256.468118)
		(width 0.18288)
		(layer "In11.Cu")
		(net "M_D_CPU1_SA_CA<3>")
	)
	(segment
		(start 29.04617 -258.94157)
		(end 28.111704 -258.94157)
		(width 0.18288)
		(layer "In11.Cu")
		(net "M_D_CPU1_SA_CA<3>")
	)
	(segment
		(start 21.534882 -262.971026)
		(end 20.889214 -263.616694)
		(width 0.18288)
		(layer "In11.Cu")
		(net "M_D_CPU1_SA_CA<3>")
	)
	(segment
		(start 32.188658 -259.7912)
		(end 31.115 -259.7912)
		(width 0.18288)
		(layer "In11.Cu")
		(net "M_D_CPU1_SA_CA<3>")
	)
	(segment
		(start 95.116396 -256.685796)
		(end 95.105982 -256.6797)
		(width 0.088646)
		(layer "In11.Cu")
		(net "M_D_CPU1_SA_CA<3>")
	)
	(segment
		(start 40.266112 -259.643626)
		(end 37.305234 -259.643626)
		(width 0.18288)
		(layer "In11.Cu")
		(net "M_D_CPU1_SA_CA<3>")
	)
	(segment
		(start 22.610826 -262.971026)
		(end 21.534882 -262.971026)
		(width 0.18288)
		(layer "In11.Cu")
		(net "M_D_CPU1_SA_CA<3>")
	)
	(segment
		(start 25.658826 -260.532626)
		(end 24.772366 -261.419086)
		(width 0.18288)
		(layer "In11.Cu")
		(net "M_D_CPU1_SA_CA<3>")
	)
	(segment
		(start 92.296996 -256.685796)
		(end 92.282264 -256.67716)
		(width 0.088646)
		(layer "In11.Cu")
		(net "M_D_CPU1_SA_CA<3>")
	)
	(segment
		(start 65.656206 -258.391152)
		(end 64.821562 -258.391152)
		(width 0.18288)
		(layer "In11.Cu")
		(net "M_D_CPU1_SA_CA<3>")
	)
	(segment
		(start 51.89347 -259.214112)
		(end 51.622198 -258.94284)
		(width 0.18288)
		(layer "In11.Cu")
		(net "M_D_CPU1_SA_CA<3>")
	)
	(segment
		(start 49.877218 -259.7912)
		(end 44.99737 -259.7912)
		(width 0.18288)
		(layer "In11.Cu")
		(net "M_D_CPU1_SA_CA<3>")
	)
	(segment
		(start 83.557618 -256.468118)
		(end 82.987134 -256.468118)
		(width 0.088646)
		(layer "In11.Cu")
		(net "M_D_CPU1_SA_CA<3>")
	)
	(segment
		(start 27.354276 -259.698998)
		(end 27.354276 -260.080252)
		(width 0.18288)
		(layer "In11.Cu")
		(net "M_D_CPU1_SA_CA<3>")
	)
	(segment
		(start 94.17685 -256.685796)
		(end 94.166436 -256.6797)
		(width 0.088646)
		(layer "In11.Cu")
		(net "M_D_CPU1_SA_CA<3>")
	)
	(segment
		(start 67.583812 -257.225038)
		(end 66.284602 -257.762756)
		(width 0.18288)
		(layer "In11.Cu")
		(net "M_D_CPU1_SA_CA<3>")
	)
	(segment
		(start 42.3926 -259.7912)
		(end 40.413686 -259.7912)
		(width 0.18288)
		(layer "In11.Cu")
		(net "M_D_CPU1_SA_CA<3>")
	)
	(segment
		(start 64.821562 -258.391152)
		(end 64.648588 -258.46278)
		(width 0.18288)
		(layer "In11.Cu")
		(net "M_D_CPU1_SA_CA<3>")
	)
	(segment
		(start 98.875596 -256.685796)
		(end 98.860864 -256.67716)
		(width 0.088646)
		(layer "In11.Cu")
		(net "M_D_CPU1_SA_CA<3>")
	)
	(segment
		(start 35.645344 -258.941062)
		(end 34.682176 -259.90423)
		(width 0.18288)
		(layer "In11.Cu")
		(net "M_D_CPU1_SA_CA<3>")
	)
	(segment
		(start 71.761858 -256.965704)
		(end 71.502524 -257.225038)
		(width 0.18288)
		(layer "In11.Cu")
		(net "M_D_CPU1_SA_CA<3>")
	)
	(segment
		(start 53.883306 -259.567426)
		(end 53.723286 -259.727446)
		(width 0.18288)
		(layer "In11.Cu")
		(net "M_D_CPU1_SA_CA<3>")
	)
	(segment
		(start 96.056196 -256.685796)
		(end 96.041464 -256.67716)
		(width 0.088646)
		(layer "In11.Cu")
		(net "M_D_CPU1_SA_CA<3>")
	)
	(segment
		(start 53.005228 -259.576824)
		(end 52.642516 -259.214112)
		(width 0.18288)
		(layer "In11.Cu")
		(net "M_D_CPU1_SA_CA<3>")
	)
	(segment
		(start 59.062366 -259.567426)
		(end 53.883306 -259.567426)
		(width 0.18288)
		(layer "In11.Cu")
		(net "M_D_CPU1_SA_CA<3>")
	)
	(segment
		(start 26.901902 -260.532626)
		(end 25.658826 -260.532626)
		(width 0.18288)
		(layer "In11.Cu")
		(net "M_D_CPU1_SA_CA<3>")
	)
	(segment
		(start 52.642516 -259.214112)
		(end 51.89347 -259.214112)
		(width 0.18288)
		(layer "In11.Cu")
		(net "M_D_CPU1_SA_CA<3>")
	)
	(segment
		(start 44.147486 -258.941316)
		(end 43.242484 -258.941316)
		(width 0.18288)
		(layer "In11.Cu")
		(net "M_D_CPU1_SA_CA<3>")
	)
	(segment
		(start 51.622198 -258.94284)
		(end 50.725578 -258.94284)
		(width 0.18288)
		(layer "In11.Cu")
		(net "M_D_CPU1_SA_CA<3>")
	)
	(segment
		(start 53.723286 -259.727446)
		(end 53.723286 -259.872734)
		(width 0.18288)
		(layer "In11.Cu")
		(net "M_D_CPU1_SA_CA<3>")
	)
	(segment
		(start 64.129158 -258.98221)
		(end 59.647582 -258.98221)
		(width 0.18288)
		(layer "In11.Cu")
		(net "M_D_CPU1_SA_CA<3>")
	)
	(segment
		(start 27.354276 -260.080252)
		(end 26.901902 -260.532626)
		(width 0.18288)
		(layer "In11.Cu")
		(net "M_D_CPU1_SA_CA<3>")
	)
	(segment
		(start 28.111704 -258.94157)
		(end 27.354276 -259.698998)
		(width 0.18288)
		(layer "In11.Cu")
		(net "M_D_CPU1_SA_CA<3>")
	)
	(segment
		(start 84.025994 -256.736342)
		(end 83.825842 -256.736342)
		(width 0.088646)
		(layer "In11.Cu")
		(net "M_D_CPU1_SA_CA<3>")
	)
	(segment
		(start 30.891226 -259.567426)
		(end 29.672026 -259.567426)
		(width 0.18288)
		(layer "In11.Cu")
		(net "M_D_CPU1_SA_CA<3>")
	)
	(segment
		(start 29.672026 -259.567426)
		(end 29.04617 -258.94157)
		(width 0.18288)
		(layer "In11.Cu")
		(net "M_D_CPU1_SA_CA<3>")
	)
	(segment
		(start 64.648588 -258.46278)
		(end 64.129158 -258.98221)
		(width 0.18288)
		(layer "In11.Cu")
		(net "M_D_CPU1_SA_CA<3>")
	)
	(segment
		(start 59.647582 -258.98221)
		(end 59.062366 -259.567426)
		(width 0.18288)
		(layer "In11.Cu")
		(net "M_D_CPU1_SA_CA<3>")
	)
	(segment
		(start 50.725578 -258.94284)
		(end 49.877218 -259.7912)
		(width 0.18288)
		(layer "In11.Cu")
		(net "M_D_CPU1_SA_CA<3>")
	)
	(segment
		(start 80.613504 -256.965704)
		(end 71.761858 -256.965704)
		(width 0.18288)
		(layer "In11.Cu")
		(net "M_D_CPU1_SA_CA<3>")
	)
	(segment
		(start 40.413686 -259.7912)
		(end 40.266112 -259.643626)
		(width 0.18288)
		(layer "In11.Cu")
		(net "M_D_CPU1_SA_CA<3>")
	)
	(segment
		(start 53.005228 -259.822696)
		(end 53.005228 -259.576824)
		(width 0.18288)
		(layer "In11.Cu")
		(net "M_D_CPU1_SA_CA<3>")
	)
	(segment
		(start 66.284602 -257.762756)
		(end 65.656206 -258.391152)
		(width 0.18288)
		(layer "In11.Cu")
		(net "M_D_CPU1_SA_CA<3>")
	)
	(arc
		(start 95.105982 -256.6797)
		(mid 94.827804 -256.609977)
		(end 94.551246 -256.685796)
		(width 0.088646)
		(layer "In11.Cu")
		(net "M_D_CPU1_SA_CA<3>")
	)
	(arc
		(start 84.778596 -256.685796)
		(mid 84.495894 -256.61002)
		(end 84.213192 -256.685796)
		(width 0.088646)
		(layer "In11.Cu")
		(net "M_D_CPU1_SA_CA<3>")
	)
	(arc
		(start 88.912192 -256.685796)
		(mid 88.724994 -256.735939)
		(end 88.537796 -256.685796)
		(width 0.088646)
		(layer "In11.Cu")
		(net "M_D_CPU1_SA_CA<3>")
	)
	(arc
		(start 97.370392 -256.685796)
		(mid 97.183194 -256.735939)
		(end 96.995996 -256.685796)
		(width 0.088646)
		(layer "In11.Cu")
		(net "M_D_CPU1_SA_CA<3>")
	)
	(arc
		(start 96.430592 -256.685796)
		(mid 96.243394 -256.735939)
		(end 96.056196 -256.685796)
		(width 0.088646)
		(layer "In11.Cu")
		(net "M_D_CPU1_SA_CA<3>")
	)
	(arc
		(start 90.791792 -256.685796)
		(mid 90.604594 -256.735939)
		(end 90.417396 -256.685796)
		(width 0.088646)
		(layer "In11.Cu")
		(net "M_D_CPU1_SA_CA<3>")
	)
	(arc
		(start 87.032592 -256.685796)
		(mid 86.845394 -256.735939)
		(end 86.658196 -256.685796)
		(width 0.088646)
		(layer "In11.Cu")
		(net "M_D_CPU1_SA_CA<3>")
	)
	(arc
		(start 89.851992 -256.685796)
		(mid 89.664794 -256.735939)
		(end 89.477596 -256.685796)
		(width 0.088646)
		(layer "In11.Cu")
		(net "M_D_CPU1_SA_CA<3>")
	)
	(arc
		(start 94.551246 -256.685796)
		(mid 94.364048 -256.735939)
		(end 94.17685 -256.685796)
		(width 0.088646)
		(layer "In11.Cu")
		(net "M_D_CPU1_SA_CA<3>")
	)
	(arc
		(start 95.490792 -256.685796)
		(mid 95.303594 -256.735939)
		(end 95.116396 -256.685796)
		(width 0.088646)
		(layer "In11.Cu")
		(net "M_D_CPU1_SA_CA<3>")
	)
	(arc
		(start 85.718396 -256.685796)
		(mid 85.435694 -256.61002)
		(end 85.152992 -256.685796)
		(width 0.088646)
		(layer "In11.Cu")
		(net "M_D_CPU1_SA_CA<3>")
	)
	(arc
		(start 96.981264 -256.67716)
		(mid 96.704789 -256.60984)
		(end 96.430592 -256.685796)
		(width 0.088646)
		(layer "In11.Cu")
		(net "M_D_CPU1_SA_CA<3>")
	)
	(arc
		(start 94.166436 -256.6797)
		(mid 93.888004 -256.609854)
		(end 93.611192 -256.685796)
		(width 0.088646)
		(layer "In11.Cu")
		(net "M_D_CPU1_SA_CA<3>")
	)
	(arc
		(start 99.815396 -256.685796)
		(mid 99.532694 -256.61002)
		(end 99.249992 -256.685796)
		(width 0.088646)
		(layer "In11.Cu")
		(net "M_D_CPU1_SA_CA<3>")
	)
	(arc
		(start 87.972392 -256.685796)
		(mid 87.785194 -256.735939)
		(end 87.597996 -256.685796)
		(width 0.088646)
		(layer "In11.Cu")
		(net "M_D_CPU1_SA_CA<3>")
	)
	(arc
		(start 98.860864 -256.67716)
		(mid 98.584389 -256.60984)
		(end 98.310192 -256.685796)
		(width 0.088646)
		(layer "In11.Cu")
		(net "M_D_CPU1_SA_CA<3>")
	)
	(arc
		(start 87.597996 -256.685796)
		(mid 87.315294 -256.61002)
		(end 87.032592 -256.685796)
		(width 0.088646)
		(layer "In11.Cu")
		(net "M_D_CPU1_SA_CA<3>")
	)
	(arc
		(start 91.357196 -256.685796)
		(mid 91.074494 -256.61002)
		(end 90.791792 -256.685796)
		(width 0.088646)
		(layer "In11.Cu")
		(net "M_D_CPU1_SA_CA<3>")
	)
	(arc
		(start 86.658196 -256.685796)
		(mid 86.375494 -256.61002)
		(end 86.092792 -256.685796)
		(width 0.088646)
		(layer "In11.Cu")
		(net "M_D_CPU1_SA_CA<3>")
	)
	(arc
		(start 97.935796 -256.685796)
		(mid 97.653094 -256.61002)
		(end 97.370392 -256.685796)
		(width 0.088646)
		(layer "In11.Cu")
		(net "M_D_CPU1_SA_CA<3>")
	)
	(arc
		(start 85.152992 -256.685796)
		(mid 84.965794 -256.735939)
		(end 84.778596 -256.685796)
		(width 0.088646)
		(layer "In11.Cu")
		(net "M_D_CPU1_SA_CA<3>")
	)
	(arc
		(start 92.282264 -256.67716)
		(mid 92.005789 -256.60984)
		(end 91.731592 -256.685796)
		(width 0.088646)
		(layer "In11.Cu")
		(net "M_D_CPU1_SA_CA<3>")
	)
	(arc
		(start 93.236796 -256.685796)
		(mid 92.954094 -256.61002)
		(end 92.671392 -256.685796)
		(width 0.088646)
		(layer "In11.Cu")
		(net "M_D_CPU1_SA_CA<3>")
	)
	(arc
		(start 84.213192 -256.685796)
		(mid 84.12292 -256.723395)
		(end 84.025994 -256.736342)
		(width 0.088646)
		(layer "In11.Cu")
		(net "M_D_CPU1_SA_CA<3>")
	)
	(arc
		(start 86.092792 -256.685796)
		(mid 85.905594 -256.735939)
		(end 85.718396 -256.685796)
		(width 0.088646)
		(layer "In11.Cu")
		(net "M_D_CPU1_SA_CA<3>")
	)
	(arc
		(start 100.472748 -257.175254)
		(mid 100.204205 -256.939244)
		(end 99.907598 -256.739644)
		(width 0.088646)
		(layer "In11.Cu")
		(net "M_D_CPU1_SA_CA<3>")
	)
	(arc
		(start 96.041464 -256.67716)
		(mid 95.764989 -256.60984)
		(end 95.490792 -256.685796)
		(width 0.088646)
		(layer "In11.Cu")
		(net "M_D_CPU1_SA_CA<3>")
	)
	(arc
		(start 88.537796 -256.685796)
		(mid 88.255094 -256.61002)
		(end 87.972392 -256.685796)
		(width 0.088646)
		(layer "In11.Cu")
		(net "M_D_CPU1_SA_CA<3>")
	)
	(arc
		(start 91.731592 -256.685796)
		(mid 91.544394 -256.735939)
		(end 91.357196 -256.685796)
		(width 0.088646)
		(layer "In11.Cu")
		(net "M_D_CPU1_SA_CA<3>")
	)
	(arc
		(start 89.477596 -256.685796)
		(mid 89.194894 -256.61002)
		(end 88.912192 -256.685796)
		(width 0.088646)
		(layer "In11.Cu")
		(net "M_D_CPU1_SA_CA<3>")
	)
	(arc
		(start 98.310192 -256.685796)
		(mid 98.122994 -256.735939)
		(end 97.935796 -256.685796)
		(width 0.088646)
		(layer "In11.Cu")
		(net "M_D_CPU1_SA_CA<3>")
	)
	(arc
		(start 92.671392 -256.685796)
		(mid 92.484194 -256.735939)
		(end 92.296996 -256.685796)
		(width 0.088646)
		(layer "In11.Cu")
		(net "M_D_CPU1_SA_CA<3>")
	)
	(arc
		(start 93.611192 -256.685796)
		(mid 93.423994 -256.735939)
		(end 93.236796 -256.685796)
		(width 0.088646)
		(layer "In11.Cu")
		(net "M_D_CPU1_SA_CA<3>")
	)
	(arc
		(start 90.417396 -256.685796)
		(mid 90.134694 -256.61002)
		(end 89.851992 -256.685796)
		(width 0.088646)
		(layer "In11.Cu")
		(net "M_D_CPU1_SA_CA<3>")
	)
	(arc
		(start 99.249992 -256.685796)
		(mid 99.062794 -256.735939)
		(end 98.875596 -256.685796)
		(width 0.088646)
		(layer "In11.Cu")
		(net "M_D_CPU1_SA_CA<3>")
	)
	(segment
		(start 11.11631 -264.032746)
		(end 11.1252 -264.041636)
		(width 0.1016)
		(layer "F.Cu")
		(net "M_D_CPU1_SA_CA<2>")
	)
	(segment
		(start 8.140446 -264.466578)
		(end 9.474708 -264.466578)
		(width 0.20066)
		(layer "F.Cu")
		(net "M_D_CPU1_SA_CA<2>")
	)
	(segment
		(start 9.474708 -264.466578)
		(end 9.686036 -264.677906)
		(width 0.20066)
		(layer "F.Cu")
		(net "M_D_CPU1_SA_CA<2>")
	)
	(segment
		(start 10.344912 -264.195306)
		(end 10.507472 -264.032746)
		(width 0.20066)
		(layer "F.Cu")
		(net "M_D_CPU1_SA_CA<2>")
	)
	(segment
		(start 98.592894 -257.175)
		(end 98.593148 -257.175254)
		(width 0.20066)
		(layer "F.Cu")
		(net "M_D_CPU1_SA_CA<2>")
	)
	(segment
		(start 10.344912 -264.523474)
		(end 10.344912 -264.195306)
		(width 0.20066)
		(layer "F.Cu")
		(net "M_D_CPU1_SA_CA<2>")
	)
	(segment
		(start 14.04493 -264.466578)
		(end 15.684246 -264.466578)
		(width 0.20066)
		(layer "F.Cu")
		(net "M_D_CPU1_SA_CA<2>")
	)
	(segment
		(start 13.441426 -264.041636)
		(end 13.619988 -264.041636)
		(width 0.20066)
		(layer "F.Cu")
		(net "M_D_CPU1_SA_CA<2>")
	)
	(segment
		(start 13.619988 -264.041636)
		(end 14.04493 -264.466578)
		(width 0.20066)
		(layer "F.Cu")
		(net "M_D_CPU1_SA_CA<2>")
	)
	(segment
		(start 16.789146 -264.466578)
		(end 15.684246 -264.466578)
		(width 0.20066)
		(layer "F.Cu")
		(net "M_D_CPU1_SA_CA<2>")
	)
	(segment
		(start 10.19048 -264.677906)
		(end 10.344912 -264.523474)
		(width 0.20066)
		(layer "F.Cu")
		(net "M_D_CPU1_SA_CA<2>")
	)
	(segment
		(start 11.1252 -264.041636)
		(end 13.110718 -264.041636)
		(width 0.1016)
		(layer "F.Cu")
		(net "M_D_CPU1_SA_CA<2>")
	)
	(segment
		(start 9.686036 -264.677906)
		(end 10.19048 -264.677906)
		(width 0.20066)
		(layer "F.Cu")
		(net "M_D_CPU1_SA_CA<2>")
	)
	(segment
		(start 98.592894 -256.639314)
		(end 98.592894 -257.175)
		(width 0.20066)
		(layer "F.Cu")
		(net "M_D_CPU1_SA_CA<2>")
	)
	(segment
		(start 10.507472 -264.032746)
		(end 11.11631 -264.032746)
		(width 0.20066)
		(layer "F.Cu")
		(net "M_D_CPU1_SA_CA<2>")
	)
	(segment
		(start 13.110718 -264.041636)
		(end 13.441426 -264.041636)
		(width 0.101854)
		(layer "F.Cu")
		(net "M_D_CPU1_SA_CA<2>")
	)
	(segment
		(start 45.369226 -260.786626)
		(end 44.228258 -260.786626)
		(width 0.18288)
		(layer "In11.Cu")
		(net "M_D_CPU1_SA_CA<2>")
	)
	(segment
		(start 40.575992 -260.405626)
		(end 40.213026 -260.768592)
		(width 0.18288)
		(layer "In11.Cu")
		(net "M_D_CPU1_SA_CA<2>")
	)
	(segment
		(start 64.373506 -259.524246)
		(end 61.592206 -259.524246)
		(width 0.18288)
		(layer "In11.Cu")
		(net "M_D_CPU1_SA_CA<2>")
	)
	(segment
		(start 29.334206 -260.786626)
		(end 29.189426 -260.641846)
		(width 0.18288)
		(layer "In11.Cu")
		(net "M_D_CPU1_SA_CA<2>")
	)
	(segment
		(start 25.64003 -261.599426)
		(end 24.735028 -262.504428)
		(width 0.18288)
		(layer "In11.Cu")
		(net "M_D_CPU1_SA_CA<2>")
	)
	(segment
		(start 83.567778 -256.833878)
		(end 82.987134 -256.833878)
		(width 0.088646)
		(layer "In11.Cu")
		(net "M_D_CPU1_SA_CA<2>")
	)
	(segment
		(start 42.071798 -260.641338)
		(end 41.836086 -260.405626)
		(width 0.18288)
		(layer "In11.Cu")
		(net "M_D_CPU1_SA_CA<2>")
	)
	(segment
		(start 31.138368 -260.641084)
		(end 30.992826 -260.786626)
		(width 0.18288)
		(layer "In11.Cu")
		(net "M_D_CPU1_SA_CA<2>")
	)
	(segment
		(start 40.213026 -260.768592)
		(end 36.936934 -260.768592)
		(width 0.18288)
		(layer "In11.Cu")
		(net "M_D_CPU1_SA_CA<2>")
	)
	(segment
		(start 60.698126 -260.081776)
		(end 60.698126 -259.717286)
		(width 0.18288)
		(layer "In11.Cu")
		(net "M_D_CPU1_SA_CA<2>")
	)
	(segment
		(start 59.272932 -260.083808)
		(end 55.61711 -260.083808)
		(width 0.18288)
		(layer "In11.Cu")
		(net "M_D_CPU1_SA_CA<2>")
	)
	(segment
		(start 95.035878 -256.859532)
		(end 95.021146 -256.850896)
		(width 0.088646)
		(layer "In11.Cu")
		(net "M_D_CPU1_SA_CA<2>")
	)
	(segment
		(start 60.505086 -259.524246)
		(end 59.832494 -259.524246)
		(width 0.18288)
		(layer "In11.Cu")
		(net "M_D_CPU1_SA_CA<2>")
	)
	(segment
		(start 26.71318 -261.599426)
		(end 25.64003 -261.599426)
		(width 0.18288)
		(layer "In11.Cu")
		(net "M_D_CPU1_SA_CA<2>")
	)
	(segment
		(start 59.832494 -259.524246)
		(end 59.272932 -260.083808)
		(width 0.18288)
		(layer "In11.Cu")
		(net "M_D_CPU1_SA_CA<2>")
	)
	(segment
		(start 61.206126 -260.274816)
		(end 60.891166 -260.274816)
		(width 0.18288)
		(layer "In11.Cu")
		(net "M_D_CPU1_SA_CA<2>")
	)
	(segment
		(start 44.08297 -260.641338)
		(end 42.071798 -260.641338)
		(width 0.18288)
		(layer "In11.Cu")
		(net "M_D_CPU1_SA_CA<2>")
	)
	(segment
		(start 36.809426 -260.641084)
		(end 34.967926 -260.641084)
		(width 0.18288)
		(layer "In11.Cu")
		(net "M_D_CPU1_SA_CA<2>")
	)
	(segment
		(start 61.399166 -259.717286)
		(end 61.399166 -260.081776)
		(width 0.18288)
		(layer "In11.Cu")
		(net "M_D_CPU1_SA_CA<2>")
	)
	(segment
		(start 95.975678 -256.859532)
		(end 95.960946 -256.850896)
		(width 0.088646)
		(layer "In11.Cu")
		(net "M_D_CPU1_SA_CA<2>")
	)
	(segment
		(start 55.61711 -260.083808)
		(end 54.970426 -260.730492)
		(width 0.18288)
		(layer "In11.Cu")
		(net "M_D_CPU1_SA_CA<2>")
	)
	(segment
		(start 93.151706 -256.856992)
		(end 93.141292 -256.850896)
		(width 0.088646)
		(layer "In11.Cu")
		(net "M_D_CPU1_SA_CA<2>")
	)
	(segment
		(start 49.693576 -260.641084)
		(end 49.592738 -260.540246)
		(width 0.18288)
		(layer "In11.Cu")
		(net "M_D_CPU1_SA_CA<2>")
	)
	(segment
		(start 84.025994 -256.926588)
		(end 83.660488 -256.926588)
		(width 0.088646)
		(layer "In11.Cu")
		(net "M_D_CPU1_SA_CA<2>")
	)
	(segment
		(start 33.284668 -261.624826)
		(end 32.300926 -260.641084)
		(width 0.18288)
		(layer "In11.Cu")
		(net "M_D_CPU1_SA_CA<2>")
	)
	(segment
		(start 61.592206 -259.524246)
		(end 61.399166 -259.717286)
		(width 0.18288)
		(layer "In11.Cu")
		(net "M_D_CPU1_SA_CA<2>")
	)
	(segment
		(start 54.970426 -260.730492)
		(end 51.859434 -260.730492)
		(width 0.18288)
		(layer "In11.Cu")
		(net "M_D_CPU1_SA_CA<2>")
	)
	(segment
		(start 48.380396 -260.540246)
		(end 48.279558 -260.641084)
		(width 0.18288)
		(layer "In11.Cu")
		(net "M_D_CPU1_SA_CA<2>")
	)
	(segment
		(start 30.992826 -260.786626)
		(end 29.334206 -260.786626)
		(width 0.18288)
		(layer "In11.Cu")
		(net "M_D_CPU1_SA_CA<2>")
	)
	(segment
		(start 21.950426 -264.114026)
		(end 21.875496 -264.039096)
		(width 0.18288)
		(layer "In11.Cu")
		(net "M_D_CPU1_SA_CA<2>")
	)
	(segment
		(start 22.447504 -264.114026)
		(end 21.950426 -264.114026)
		(width 0.18288)
		(layer "In11.Cu")
		(net "M_D_CPU1_SA_CA<2>")
	)
	(segment
		(start 17.216628 -264.039096)
		(end 16.789146 -264.466578)
		(width 0.18288)
		(layer "In11.Cu")
		(net "M_D_CPU1_SA_CA<2>")
	)
	(segment
		(start 92.21216 -256.856992)
		(end 92.201746 -256.850896)
		(width 0.088646)
		(layer "In11.Cu")
		(net "M_D_CPU1_SA_CA<2>")
	)
	(segment
		(start 41.836086 -260.405626)
		(end 40.575992 -260.405626)
		(width 0.18288)
		(layer "In11.Cu")
		(net "M_D_CPU1_SA_CA<2>")
	)
	(segment
		(start 60.698126 -259.717286)
		(end 60.505086 -259.524246)
		(width 0.18288)
		(layer "In11.Cu")
		(net "M_D_CPU1_SA_CA<2>")
	)
	(segment
		(start 96.91116 -256.856992)
		(end 96.900746 -256.850896)
		(width 0.088646)
		(layer "In11.Cu")
		(net "M_D_CPU1_SA_CA<2>")
	)
	(segment
		(start 51.859434 -260.730492)
		(end 51.770026 -260.641084)
		(width 0.18288)
		(layer "In11.Cu")
		(net "M_D_CPU1_SA_CA<2>")
	)
	(segment
		(start 71.50354 -257.821938)
		(end 67.543934 -257.821938)
		(width 0.18288)
		(layer "In11.Cu")
		(net "M_D_CPU1_SA_CA<2>")
	)
	(segment
		(start 44.228258 -260.786626)
		(end 44.08297 -260.641338)
		(width 0.18288)
		(layer "In11.Cu")
		(net "M_D_CPU1_SA_CA<2>")
	)
	(segment
		(start 91.272106 -256.856992)
		(end 91.261692 -256.850896)
		(width 0.088646)
		(layer "In11.Cu")
		(net "M_D_CPU1_SA_CA<2>")
	)
	(segment
		(start 29.189426 -260.641846)
		(end 27.67076 -260.641846)
		(width 0.18288)
		(layer "In11.Cu")
		(net "M_D_CPU1_SA_CA<2>")
	)
	(segment
		(start 64.932814 -258.964938)
		(end 64.373506 -259.524246)
		(width 0.18288)
		(layer "In11.Cu")
		(net "M_D_CPU1_SA_CA<2>")
	)
	(segment
		(start 61.399166 -260.081776)
		(end 61.206126 -260.274816)
		(width 0.18288)
		(layer "In11.Cu")
		(net "M_D_CPU1_SA_CA<2>")
	)
	(segment
		(start 60.891166 -260.274816)
		(end 60.698126 -260.081776)
		(width 0.18288)
		(layer "In11.Cu")
		(net "M_D_CPU1_SA_CA<2>")
	)
	(segment
		(start 34.967926 -260.641084)
		(end 33.984184 -261.624826)
		(width 0.18288)
		(layer "In11.Cu")
		(net "M_D_CPU1_SA_CA<2>")
	)
	(segment
		(start 49.592738 -260.540246)
		(end 48.380396 -260.540246)
		(width 0.18288)
		(layer "In11.Cu")
		(net "M_D_CPU1_SA_CA<2>")
	)
	(segment
		(start 33.984184 -261.624826)
		(end 33.284668 -261.624826)
		(width 0.18288)
		(layer "In11.Cu")
		(net "M_D_CPU1_SA_CA<2>")
	)
	(segment
		(start 32.300926 -260.641084)
		(end 31.138368 -260.641084)
		(width 0.18288)
		(layer "In11.Cu")
		(net "M_D_CPU1_SA_CA<2>")
	)
	(segment
		(start 83.660488 -256.926588)
		(end 83.567778 -256.833878)
		(width 0.088646)
		(layer "In11.Cu")
		(net "M_D_CPU1_SA_CA<2>")
	)
	(segment
		(start 51.770026 -260.641084)
		(end 49.693576 -260.641084)
		(width 0.18288)
		(layer "In11.Cu")
		(net "M_D_CPU1_SA_CA<2>")
	)
	(segment
		(start 45.514768 -260.641084)
		(end 45.369226 -260.786626)
		(width 0.18288)
		(layer "In11.Cu")
		(net "M_D_CPU1_SA_CA<2>")
	)
	(segment
		(start 48.279558 -260.641084)
		(end 45.514768 -260.641084)
		(width 0.18288)
		(layer "In11.Cu")
		(net "M_D_CPU1_SA_CA<2>")
	)
	(segment
		(start 81.234026 -256.833878)
		(end 80.75676 -257.311144)
		(width 0.18288)
		(layer "In11.Cu")
		(net "M_D_CPU1_SA_CA<2>")
	)
	(segment
		(start 66.400934 -258.964938)
		(end 64.932814 -258.964938)
		(width 0.18288)
		(layer "In11.Cu")
		(net "M_D_CPU1_SA_CA<2>")
	)
	(segment
		(start 80.75676 -257.311144)
		(end 72.014334 -257.311144)
		(width 0.18288)
		(layer "In11.Cu")
		(net "M_D_CPU1_SA_CA<2>")
	)
	(segment
		(start 21.875496 -264.039096)
		(end 17.216628 -264.039096)
		(width 0.18288)
		(layer "In11.Cu")
		(net "M_D_CPU1_SA_CA<2>")
	)
	(segment
		(start 27.67076 -260.641846)
		(end 26.71318 -261.599426)
		(width 0.18288)
		(layer "In11.Cu")
		(net "M_D_CPU1_SA_CA<2>")
	)
	(segment
		(start 82.987134 -256.833878)
		(end 81.234026 -256.833878)
		(width 0.18288)
		(layer "In11.Cu")
		(net "M_D_CPU1_SA_CA<2>")
	)
	(segment
		(start 36.936934 -260.768592)
		(end 36.809426 -260.641084)
		(width 0.18288)
		(layer "In11.Cu")
		(net "M_D_CPU1_SA_CA<2>")
	)
	(segment
		(start 24.057102 -262.504428)
		(end 22.447504 -264.114026)
		(width 0.18288)
		(layer "In11.Cu")
		(net "M_D_CPU1_SA_CA<2>")
	)
	(segment
		(start 72.014334 -257.311144)
		(end 71.50354 -257.821938)
		(width 0.18288)
		(layer "In11.Cu")
		(net "M_D_CPU1_SA_CA<2>")
	)
	(segment
		(start 24.735028 -262.504428)
		(end 24.057102 -262.504428)
		(width 0.18288)
		(layer "In11.Cu")
		(net "M_D_CPU1_SA_CA<2>")
	)
	(segment
		(start 67.543934 -257.821938)
		(end 66.400934 -258.964938)
		(width 0.18288)
		(layer "In11.Cu")
		(net "M_D_CPU1_SA_CA<2>")
	)
	(arc
		(start 94.64675 -256.850896)
		(mid 94.364048 -256.926672)
		(end 94.081346 -256.850896)
		(width 0.088646)
		(layer "In11.Cu")
		(net "M_D_CPU1_SA_CA<2>")
	)
	(arc
		(start 93.141292 -256.850896)
		(mid 92.954094 -256.800753)
		(end 92.766896 -256.850896)
		(width 0.088646)
		(layer "In11.Cu")
		(net "M_D_CPU1_SA_CA<2>")
	)
	(arc
		(start 84.683092 -256.850896)
		(mid 84.495894 -256.800753)
		(end 84.308696 -256.850896)
		(width 0.088646)
		(layer "In11.Cu")
		(net "M_D_CPU1_SA_CA<2>")
	)
	(arc
		(start 97.840292 -256.850896)
		(mid 97.653094 -256.800753)
		(end 97.465896 -256.850896)
		(width 0.088646)
		(layer "In11.Cu")
		(net "M_D_CPU1_SA_CA<2>")
	)
	(arc
		(start 95.960946 -256.850896)
		(mid 95.773748 -256.800753)
		(end 95.58655 -256.850896)
		(width 0.088646)
		(layer "In11.Cu")
		(net "M_D_CPU1_SA_CA<2>")
	)
	(arc
		(start 89.007696 -256.850896)
		(mid 88.724994 -256.926672)
		(end 88.442292 -256.850896)
		(width 0.088646)
		(layer "In11.Cu")
		(net "M_D_CPU1_SA_CA<2>")
	)
	(arc
		(start 88.067896 -256.850896)
		(mid 87.785194 -256.926672)
		(end 87.502492 -256.850896)
		(width 0.088646)
		(layer "In11.Cu")
		(net "M_D_CPU1_SA_CA<2>")
	)
	(arc
		(start 88.442292 -256.850896)
		(mid 88.255094 -256.800753)
		(end 88.067896 -256.850896)
		(width 0.088646)
		(layer "In11.Cu")
		(net "M_D_CPU1_SA_CA<2>")
	)
	(arc
		(start 95.58655 -256.850896)
		(mid 95.312351 -256.926731)
		(end 95.035878 -256.859532)
		(width 0.088646)
		(layer "In11.Cu")
		(net "M_D_CPU1_SA_CA<2>")
	)
	(arc
		(start 85.622892 -256.850896)
		(mid 85.435694 -256.800753)
		(end 85.248496 -256.850896)
		(width 0.088646)
		(layer "In11.Cu")
		(net "M_D_CPU1_SA_CA<2>")
	)
	(arc
		(start 98.593148 -257.175254)
		(mid 98.345646 -257.008938)
		(end 98.053652 -256.948432)
		(width 0.088646)
		(layer "In11.Cu")
		(net "M_D_CPU1_SA_CA<2>")
	)
	(arc
		(start 96.900746 -256.850896)
		(mid 96.713548 -256.800753)
		(end 96.52635 -256.850896)
		(width 0.088646)
		(layer "In11.Cu")
		(net "M_D_CPU1_SA_CA<2>")
	)
	(arc
		(start 86.562692 -256.850896)
		(mid 86.375494 -256.800753)
		(end 86.188296 -256.850896)
		(width 0.088646)
		(layer "In11.Cu")
		(net "M_D_CPU1_SA_CA<2>")
	)
	(arc
		(start 90.887296 -256.850896)
		(mid 90.604594 -256.926672)
		(end 90.321892 -256.850896)
		(width 0.088646)
		(layer "In11.Cu")
		(net "M_D_CPU1_SA_CA<2>")
	)
	(arc
		(start 87.128096 -256.850896)
		(mid 86.845394 -256.926672)
		(end 86.562692 -256.850896)
		(width 0.088646)
		(layer "In11.Cu")
		(net "M_D_CPU1_SA_CA<2>")
	)
	(arc
		(start 85.248496 -256.850896)
		(mid 84.965794 -256.926672)
		(end 84.683092 -256.850896)
		(width 0.088646)
		(layer "In11.Cu")
		(net "M_D_CPU1_SA_CA<2>")
	)
	(arc
		(start 86.188296 -256.850896)
		(mid 85.905594 -256.926672)
		(end 85.622892 -256.850896)
		(width 0.088646)
		(layer "In11.Cu")
		(net "M_D_CPU1_SA_CA<2>")
	)
	(arc
		(start 91.261692 -256.850896)
		(mid 91.074494 -256.800753)
		(end 90.887296 -256.850896)
		(width 0.088646)
		(layer "In11.Cu")
		(net "M_D_CPU1_SA_CA<2>")
	)
	(arc
		(start 90.321892 -256.850896)
		(mid 90.134694 -256.800753)
		(end 89.947496 -256.850896)
		(width 0.088646)
		(layer "In11.Cu")
		(net "M_D_CPU1_SA_CA<2>")
	)
	(arc
		(start 93.70695 -256.850896)
		(mid 93.430137 -256.926766)
		(end 93.151706 -256.856992)
		(width 0.088646)
		(layer "In11.Cu")
		(net "M_D_CPU1_SA_CA<2>")
	)
	(arc
		(start 89.947496 -256.850896)
		(mid 89.664794 -256.926672)
		(end 89.382092 -256.850896)
		(width 0.088646)
		(layer "In11.Cu")
		(net "M_D_CPU1_SA_CA<2>")
	)
	(arc
		(start 87.502492 -256.850896)
		(mid 87.315294 -256.800753)
		(end 87.128096 -256.850896)
		(width 0.088646)
		(layer "In11.Cu")
		(net "M_D_CPU1_SA_CA<2>")
	)
	(arc
		(start 92.766896 -256.850896)
		(mid 92.490337 -256.926639)
		(end 92.21216 -256.856992)
		(width 0.088646)
		(layer "In11.Cu")
		(net "M_D_CPU1_SA_CA<2>")
	)
	(arc
		(start 97.465896 -256.850896)
		(mid 97.189337 -256.926639)
		(end 96.91116 -256.856992)
		(width 0.088646)
		(layer "In11.Cu")
		(net "M_D_CPU1_SA_CA<2>")
	)
	(arc
		(start 94.081346 -256.850896)
		(mid 93.894148 -256.800753)
		(end 93.70695 -256.850896)
		(width 0.088646)
		(layer "In11.Cu")
		(net "M_D_CPU1_SA_CA<2>")
	)
	(arc
		(start 96.52635 -256.850896)
		(mid 96.252151 -256.926731)
		(end 95.975678 -256.859532)
		(width 0.088646)
		(layer "In11.Cu")
		(net "M_D_CPU1_SA_CA<2>")
	)
	(arc
		(start 95.021146 -256.850896)
		(mid 94.833948 -256.800753)
		(end 94.64675 -256.850896)
		(width 0.088646)
		(layer "In11.Cu")
		(net "M_D_CPU1_SA_CA<2>")
	)
	(arc
		(start 98.053652 -256.948432)
		(mid 97.944658 -256.904725)
		(end 97.840292 -256.850896)
		(width 0.088646)
		(layer "In11.Cu")
		(net "M_D_CPU1_SA_CA<2>")
	)
	(arc
		(start 84.308696 -256.850896)
		(mid 84.172327 -256.907338)
		(end 84.025994 -256.926588)
		(width 0.088646)
		(layer "In11.Cu")
		(net "M_D_CPU1_SA_CA<2>")
	)
	(arc
		(start 92.201746 -256.850896)
		(mid 92.014548 -256.800753)
		(end 91.82735 -256.850896)
		(width 0.088646)
		(layer "In11.Cu")
		(net "M_D_CPU1_SA_CA<2>")
	)
	(arc
		(start 89.382092 -256.850896)
		(mid 89.194894 -256.800753)
		(end 89.007696 -256.850896)
		(width 0.088646)
		(layer "In11.Cu")
		(net "M_D_CPU1_SA_CA<2>")
	)
	(arc
		(start 91.82735 -256.850896)
		(mid 91.550537 -256.926766)
		(end 91.272106 -256.856992)
		(width 0.088646)
		(layer "In11.Cu")
		(net "M_D_CPU1_SA_CA<2>")
	)
	(segment
		(start 14.20622 -265.755882)
		(end 14.560042 -265.755882)
		(width 0.20066)
		(layer "F.Cu")
		(net "M_D_CPU1_SA_CA<1>")
	)
	(segment
		(start 14.812264 -265.741658)
		(end 16.885158 -265.741658)
		(width 0.1016)
		(layer "F.Cu")
		(net "M_D_CPU1_SA_CA<1>")
	)
	(segment
		(start 100.942648 -257.45313)
		(end 100.942648 -257.988816)
		(width 0.20066)
		(layer "F.Cu")
		(net "M_D_CPU1_SA_CA<1>")
	)
	(segment
		(start 14.063726 -265.4427)
		(end 14.063726 -265.613388)
		(width 0.20066)
		(layer "F.Cu")
		(net "M_D_CPU1_SA_CA<1>")
	)
	(segment
		(start 14.063726 -265.613388)
		(end 14.20622 -265.755882)
		(width 0.20066)
		(layer "F.Cu")
		(net "M_D_CPU1_SA_CA<1>")
	)
	(segment
		(start 17.578578 -265.440922)
		(end 17.707102 -265.312398)
		(width 0.20066)
		(layer "F.Cu")
		(net "M_D_CPU1_SA_CA<1>")
	)
	(segment
		(start 14.574266 -265.741658)
		(end 14.812264 -265.741658)
		(width 0.101854)
		(layer "F.Cu")
		(net "M_D_CPU1_SA_CA<1>")
	)
	(segment
		(start 18.968212 -265.316716)
		(end 19.784314 -265.316716)
		(width 0.20066)
		(layer "F.Cu")
		(net "M_D_CPU1_SA_CA<1>")
	)
	(segment
		(start 17.578578 -265.59256)
		(end 17.578578 -265.440922)
		(width 0.20066)
		(layer "F.Cu")
		(net "M_D_CPU1_SA_CA<1>")
	)
	(segment
		(start 20.889214 -265.316716)
		(end 19.784314 -265.316716)
		(width 0.20066)
		(layer "F.Cu")
		(net "M_D_CPU1_SA_CA<1>")
	)
	(segment
		(start 18.760694 -265.524234)
		(end 18.968212 -265.316716)
		(width 0.20066)
		(layer "F.Cu")
		(net "M_D_CPU1_SA_CA<1>")
	)
	(segment
		(start 18.314162 -265.524234)
		(end 18.760694 -265.524234)
		(width 0.20066)
		(layer "F.Cu")
		(net "M_D_CPU1_SA_CA<1>")
	)
	(segment
		(start 18.102326 -265.312398)
		(end 18.314162 -265.524234)
		(width 0.20066)
		(layer "F.Cu")
		(net "M_D_CPU1_SA_CA<1>")
	)
	(segment
		(start 100.942648 -257.988816)
		(end 100.942394 -257.98907)
		(width 0.20066)
		(layer "F.Cu")
		(net "M_D_CPU1_SA_CA<1>")
	)
	(segment
		(start 17.42948 -265.741658)
		(end 17.578578 -265.59256)
		(width 0.20066)
		(layer "F.Cu")
		(net "M_D_CPU1_SA_CA<1>")
	)
	(segment
		(start 16.885158 -265.741658)
		(end 17.42948 -265.741658)
		(width 0.20066)
		(layer "F.Cu")
		(net "M_D_CPU1_SA_CA<1>")
	)
	(segment
		(start 17.707102 -265.312398)
		(end 18.102326 -265.312398)
		(width 0.20066)
		(layer "F.Cu")
		(net "M_D_CPU1_SA_CA<1>")
	)
	(segment
		(start 13.937742 -265.316716)
		(end 14.063726 -265.4427)
		(width 0.20066)
		(layer "F.Cu")
		(net "M_D_CPU1_SA_CA<1>")
	)
	(segment
		(start 12.240514 -265.316716)
		(end 13.937742 -265.316716)
		(width 0.20066)
		(layer "F.Cu")
		(net "M_D_CPU1_SA_CA<1>")
	)
	(segment
		(start 14.560042 -265.755882)
		(end 14.574266 -265.741658)
		(width 0.101854)
		(layer "F.Cu")
		(net "M_D_CPU1_SA_CA<1>")
	)
	(segment
		(start 27.792426 -261.675626)
		(end 27.284426 -262.183626)
		(width 0.18288)
		(layer "In11.Cu")
		(net "M_D_CPU1_SA_CA<1>")
	)
	(segment
		(start 49.765458 -261.49046)
		(end 49.606708 -261.64921)
		(width 0.18288)
		(layer "In11.Cu")
		(net "M_D_CPU1_SA_CA<1>")
	)
	(segment
		(start 64.59728 -260.062472)
		(end 63.00978 -260.062472)
		(width 0.18288)
		(layer "In11.Cu")
		(net "M_D_CPU1_SA_CA<1>")
	)
	(segment
		(start 84.025994 -257.42392)
		(end 83.81238 -257.42392)
		(width 0.088646)
		(layer "In11.Cu")
		(net "M_D_CPU1_SA_CA<1>")
	)
	(segment
		(start 95.035878 -257.490976)
		(end 95.021146 -257.499612)
		(width 0.088646)
		(layer "In11.Cu")
		(net "M_D_CPU1_SA_CA<1>")
	)
	(segment
		(start 34.993326 -261.490968)
		(end 34.326068 -262.158226)
		(width 0.18288)
		(layer "In11.Cu")
		(net "M_D_CPU1_SA_CA<1>")
	)
	(segment
		(start 49.606708 -261.64921)
		(end 48.387508 -261.64921)
		(width 0.18288)
		(layer "In11.Cu")
		(net "M_D_CPU1_SA_CA<1>")
	)
	(segment
		(start 36.757102 -261.340092)
		(end 36.606226 -261.490968)
		(width 0.18288)
		(layer "In11.Cu")
		(net "M_D_CPU1_SA_CA<1>")
	)
	(segment
		(start 72.336406 -257.669792)
		(end 71.642732 -258.363466)
		(width 0.18288)
		(layer "In11.Cu")
		(net "M_D_CPU1_SA_CA<1>")
	)
	(segment
		(start 52.073556 -261.314692)
		(end 51.897788 -261.49046)
		(width 0.18288)
		(layer "In11.Cu")
		(net "M_D_CPU1_SA_CA<1>")
	)
	(segment
		(start 43.896026 -261.650226)
		(end 40.516048 -261.650226)
		(width 0.18288)
		(layer "In11.Cu")
		(net "M_D_CPU1_SA_CA<1>")
	)
	(segment
		(start 57.21858 -261.04469)
		(end 57.21858 -260.787896)
		(width 0.18288)
		(layer "In11.Cu")
		(net "M_D_CPU1_SA_CA<1>")
	)
	(segment
		(start 22.610826 -264.69975)
		(end 21.50618 -264.69975)
		(width 0.18288)
		(layer "In11.Cu")
		(net "M_D_CPU1_SA_CA<1>")
	)
	(segment
		(start 66.602356 -259.511546)
		(end 65.148206 -259.511546)
		(width 0.18288)
		(layer "In11.Cu")
		(net "M_D_CPU1_SA_CA<1>")
	)
	(segment
		(start 53.145944 -261.507732)
		(end 52.952904 -261.314692)
		(width 0.18288)
		(layer "In11.Cu")
		(net "M_D_CPU1_SA_CA<1>")
	)
	(segment
		(start 71.642732 -258.363466)
		(end 67.750436 -258.363466)
		(width 0.18288)
		(layer "In11.Cu")
		(net "M_D_CPU1_SA_CA<1>")
	)
	(segment
		(start 48.387508 -261.64921)
		(end 48.231298 -261.493)
		(width 0.18288)
		(layer "In11.Cu")
		(net "M_D_CPU1_SA_CA<1>")
	)
	(segment
		(start 83.81238 -257.42392)
		(end 83.567778 -257.179318)
		(width 0.088646)
		(layer "In11.Cu")
		(net "M_D_CPU1_SA_CA<1>")
	)
	(segment
		(start 25.836626 -262.183626)
		(end 24.973026 -263.047226)
		(width 0.18288)
		(layer "In11.Cu")
		(net "M_D_CPU1_SA_CA<1>")
	)
	(segment
		(start 81.377536 -257.179318)
		(end 80.887062 -257.669792)
		(width 0.18288)
		(layer "In11.Cu")
		(net "M_D_CPU1_SA_CA<1>")
	)
	(segment
		(start 91.272106 -257.493516)
		(end 91.261692 -257.499612)
		(width 0.088646)
		(layer "In11.Cu")
		(net "M_D_CPU1_SA_CA<1>")
	)
	(segment
		(start 83.567778 -257.179318)
		(end 82.987134 -257.179318)
		(width 0.088646)
		(layer "In11.Cu")
		(net "M_D_CPU1_SA_CA<1>")
	)
	(segment
		(start 45.166026 -261.294626)
		(end 44.251626 -261.294626)
		(width 0.18288)
		(layer "In11.Cu")
		(net "M_D_CPU1_SA_CA<1>")
	)
	(segment
		(start 36.606226 -261.490968)
		(end 34.993326 -261.490968)
		(width 0.18288)
		(layer "In11.Cu")
		(net "M_D_CPU1_SA_CA<1>")
	)
	(segment
		(start 44.251626 -261.294626)
		(end 43.896026 -261.650226)
		(width 0.18288)
		(layer "In11.Cu")
		(net "M_D_CPU1_SA_CA<1>")
	)
	(segment
		(start 90.887296 -257.499612)
		(end 90.872564 -257.490976)
		(width 0.088646)
		(layer "In11.Cu")
		(net "M_D_CPU1_SA_CA<1>")
	)
	(segment
		(start 30.896814 -261.671308)
		(end 30.572456 -261.671308)
		(width 0.18288)
		(layer "In11.Cu")
		(net "M_D_CPU1_SA_CA<1>")
	)
	(segment
		(start 21.50618 -264.69975)
		(end 20.889214 -265.316716)
		(width 0.18288)
		(layer "In11.Cu")
		(net "M_D_CPU1_SA_CA<1>")
	)
	(segment
		(start 53.846984 -261.782052)
		(end 53.653944 -261.975092)
		(width 0.18288)
		(layer "In11.Cu")
		(net "M_D_CPU1_SA_CA<1>")
	)
	(segment
		(start 100.363782 -257.544824)
		(end 100.28555 -257.499612)
		(width 0.088646)
		(layer "In11.Cu")
		(net "M_D_CPU1_SA_CA<1>")
	)
	(segment
		(start 93.151706 -257.493516)
		(end 93.141292 -257.499612)
		(width 0.088646)
		(layer "In11.Cu")
		(net "M_D_CPU1_SA_CA<1>")
	)
	(segment
		(start 67.750436 -258.363466)
		(end 66.602356 -259.511546)
		(width 0.18288)
		(layer "In11.Cu")
		(net "M_D_CPU1_SA_CA<1>")
	)
	(segment
		(start 92.766896 -257.499612)
		(end 92.756482 -257.493516)
		(width 0.088646)
		(layer "In11.Cu")
		(net "M_D_CPU1_SA_CA<1>")
	)
	(segment
		(start 24.26335 -263.047226)
		(end 22.610826 -264.69975)
		(width 0.18288)
		(layer "In11.Cu")
		(net "M_D_CPU1_SA_CA<1>")
	)
	(segment
		(start 24.973026 -263.047226)
		(end 24.26335 -263.047226)
		(width 0.18288)
		(layer "In11.Cu")
		(net "M_D_CPU1_SA_CA<1>")
	)
	(segment
		(start 40.205914 -261.340092)
		(end 36.757102 -261.340092)
		(width 0.18288)
		(layer "In11.Cu")
		(net "M_D_CPU1_SA_CA<1>")
	)
	(segment
		(start 29.265626 -261.294626)
		(end 28.884626 -261.675626)
		(width 0.18288)
		(layer "In11.Cu")
		(net "M_D_CPU1_SA_CA<1>")
	)
	(segment
		(start 95.975678 -257.490976)
		(end 95.960946 -257.499612)
		(width 0.088646)
		(layer "In11.Cu")
		(net "M_D_CPU1_SA_CA<1>")
	)
	(segment
		(start 94.096078 -257.490976)
		(end 94.081346 -257.499612)
		(width 0.088646)
		(layer "In11.Cu")
		(net "M_D_CPU1_SA_CA<1>")
	)
	(segment
		(start 57.91962 -261.04469)
		(end 57.72658 -261.23773)
		(width 0.18288)
		(layer "In11.Cu")
		(net "M_D_CPU1_SA_CA<1>")
	)
	(segment
		(start 30.572456 -261.671308)
		(end 30.195774 -261.294626)
		(width 0.18288)
		(layer "In11.Cu")
		(net "M_D_CPU1_SA_CA<1>")
	)
	(segment
		(start 53.653944 -261.975092)
		(end 53.338984 -261.975092)
		(width 0.18288)
		(layer "In11.Cu")
		(net "M_D_CPU1_SA_CA<1>")
	)
	(segment
		(start 82.987134 -257.179318)
		(end 81.377536 -257.179318)
		(width 0.18288)
		(layer "In11.Cu")
		(net "M_D_CPU1_SA_CA<1>")
	)
	(segment
		(start 58.11266 -260.594856)
		(end 57.91962 -260.787896)
		(width 0.18288)
		(layer "In11.Cu")
		(net "M_D_CPU1_SA_CA<1>")
	)
	(segment
		(start 62.267592 -260.80466)
		(end 59.179714 -260.80466)
		(width 0.18288)
		(layer "In11.Cu")
		(net "M_D_CPU1_SA_CA<1>")
	)
	(segment
		(start 53.145944 -261.782052)
		(end 53.145944 -261.507732)
		(width 0.18288)
		(layer "In11.Cu")
		(net "M_D_CPU1_SA_CA<1>")
	)
	(segment
		(start 53.846984 -261.507732)
		(end 53.846984 -261.782052)
		(width 0.18288)
		(layer "In11.Cu")
		(net "M_D_CPU1_SA_CA<1>")
	)
	(segment
		(start 63.00978 -260.062472)
		(end 62.267592 -260.80466)
		(width 0.18288)
		(layer "In11.Cu")
		(net "M_D_CPU1_SA_CA<1>")
	)
	(segment
		(start 59.179714 -260.80466)
		(end 58.96991 -260.594856)
		(width 0.18288)
		(layer "In11.Cu")
		(net "M_D_CPU1_SA_CA<1>")
	)
	(segment
		(start 57.91962 -260.787896)
		(end 57.91962 -261.04469)
		(width 0.18288)
		(layer "In11.Cu")
		(net "M_D_CPU1_SA_CA<1>")
	)
	(segment
		(start 57.41162 -261.23773)
		(end 57.21858 -261.04469)
		(width 0.18288)
		(layer "In11.Cu")
		(net "M_D_CPU1_SA_CA<1>")
	)
	(segment
		(start 48.231298 -261.493)
		(end 45.3644 -261.493)
		(width 0.18288)
		(layer "In11.Cu")
		(net "M_D_CPU1_SA_CA<1>")
	)
	(segment
		(start 65.148206 -259.511546)
		(end 64.59728 -260.062472)
		(width 0.18288)
		(layer "In11.Cu")
		(net "M_D_CPU1_SA_CA<1>")
	)
	(segment
		(start 30.195774 -261.294626)
		(end 29.265626 -261.294626)
		(width 0.18288)
		(layer "In11.Cu")
		(net "M_D_CPU1_SA_CA<1>")
	)
	(segment
		(start 58.96991 -260.594856)
		(end 58.11266 -260.594856)
		(width 0.18288)
		(layer "In11.Cu")
		(net "M_D_CPU1_SA_CA<1>")
	)
	(segment
		(start 55.918862 -260.594856)
		(end 55.199026 -261.314692)
		(width 0.18288)
		(layer "In11.Cu")
		(net "M_D_CPU1_SA_CA<1>")
	)
	(segment
		(start 97.465896 -257.499612)
		(end 97.455482 -257.493516)
		(width 0.088646)
		(layer "In11.Cu")
		(net "M_D_CPU1_SA_CA<1>")
	)
	(segment
		(start 32.326326 -261.491222)
		(end 31.0769 -261.491222)
		(width 0.18288)
		(layer "In11.Cu")
		(net "M_D_CPU1_SA_CA<1>")
	)
	(segment
		(start 45.3644 -261.493)
		(end 45.166026 -261.294626)
		(width 0.18288)
		(layer "In11.Cu")
		(net "M_D_CPU1_SA_CA<1>")
	)
	(segment
		(start 97.850706 -257.493516)
		(end 97.840292 -257.499612)
		(width 0.088646)
		(layer "In11.Cu")
		(net "M_D_CPU1_SA_CA<1>")
	)
	(segment
		(start 57.02554 -260.594856)
		(end 55.918862 -260.594856)
		(width 0.18288)
		(layer "In11.Cu")
		(net "M_D_CPU1_SA_CA<1>")
	)
	(segment
		(start 99.345496 -257.499612)
		(end 99.335082 -257.493516)
		(width 0.088646)
		(layer "In11.Cu")
		(net "M_D_CPU1_SA_CA<1>")
	)
	(segment
		(start 53.338984 -261.975092)
		(end 53.145944 -261.782052)
		(width 0.18288)
		(layer "In11.Cu")
		(net "M_D_CPU1_SA_CA<1>")
	)
	(segment
		(start 51.897788 -261.49046)
		(end 49.765458 -261.49046)
		(width 0.18288)
		(layer "In11.Cu")
		(net "M_D_CPU1_SA_CA<1>")
	)
	(segment
		(start 57.72658 -261.23773)
		(end 57.41162 -261.23773)
		(width 0.18288)
		(layer "In11.Cu")
		(net "M_D_CPU1_SA_CA<1>")
	)
	(segment
		(start 54.040024 -261.314692)
		(end 53.846984 -261.507732)
		(width 0.18288)
		(layer "In11.Cu")
		(net "M_D_CPU1_SA_CA<1>")
	)
	(segment
		(start 34.326068 -262.158226)
		(end 32.99333 -262.158226)
		(width 0.18288)
		(layer "In11.Cu")
		(net "M_D_CPU1_SA_CA<1>")
	)
	(segment
		(start 27.284426 -262.183626)
		(end 25.836626 -262.183626)
		(width 0.18288)
		(layer "In11.Cu")
		(net "M_D_CPU1_SA_CA<1>")
	)
	(segment
		(start 40.516048 -261.650226)
		(end 40.205914 -261.340092)
		(width 0.18288)
		(layer "In11.Cu")
		(net "M_D_CPU1_SA_CA<1>")
	)
	(segment
		(start 52.952904 -261.314692)
		(end 52.073556 -261.314692)
		(width 0.18288)
		(layer "In11.Cu")
		(net "M_D_CPU1_SA_CA<1>")
	)
	(segment
		(start 99.730306 -257.493516)
		(end 99.719892 -257.499612)
		(width 0.088646)
		(layer "In11.Cu")
		(net "M_D_CPU1_SA_CA<1>")
	)
	(segment
		(start 32.99333 -262.158226)
		(end 32.326326 -261.491222)
		(width 0.18288)
		(layer "In11.Cu")
		(net "M_D_CPU1_SA_CA<1>")
	)
	(segment
		(start 57.21858 -260.787896)
		(end 57.02554 -260.594856)
		(width 0.18288)
		(layer "In11.Cu")
		(net "M_D_CPU1_SA_CA<1>")
	)
	(segment
		(start 55.199026 -261.314692)
		(end 54.040024 -261.314692)
		(width 0.18288)
		(layer "In11.Cu")
		(net "M_D_CPU1_SA_CA<1>")
	)
	(segment
		(start 31.0769 -261.491222)
		(end 30.896814 -261.671308)
		(width 0.18288)
		(layer "In11.Cu")
		(net "M_D_CPU1_SA_CA<1>")
	)
	(segment
		(start 80.887062 -257.669792)
		(end 72.336406 -257.669792)
		(width 0.18288)
		(layer "In11.Cu")
		(net "M_D_CPU1_SA_CA<1>")
	)
	(segment
		(start 28.884626 -261.675626)
		(end 27.792426 -261.675626)
		(width 0.18288)
		(layer "In11.Cu")
		(net "M_D_CPU1_SA_CA<1>")
	)
	(arc
		(start 96.52635 -257.499612)
		(mid 96.252151 -257.423777)
		(end 95.975678 -257.490976)
		(width 0.088646)
		(layer "In11.Cu")
		(net "M_D_CPU1_SA_CA<1>")
	)
	(arc
		(start 94.081346 -257.499612)
		(mid 93.894148 -257.549755)
		(end 93.70695 -257.499612)
		(width 0.088646)
		(layer "In11.Cu")
		(net "M_D_CPU1_SA_CA<1>")
	)
	(arc
		(start 88.067896 -257.499612)
		(mid 87.785194 -257.423836)
		(end 87.502492 -257.499612)
		(width 0.088646)
		(layer "In11.Cu")
		(net "M_D_CPU1_SA_CA<1>")
	)
	(arc
		(start 89.007696 -257.499612)
		(mid 88.724994 -257.423836)
		(end 88.442292 -257.499612)
		(width 0.088646)
		(layer "In11.Cu")
		(net "M_D_CPU1_SA_CA<1>")
	)
	(arc
		(start 98.40595 -257.499612)
		(mid 98.129137 -257.423742)
		(end 97.850706 -257.493516)
		(width 0.088646)
		(layer "In11.Cu")
		(net "M_D_CPU1_SA_CA<1>")
	)
	(arc
		(start 96.900746 -257.499612)
		(mid 96.713548 -257.549755)
		(end 96.52635 -257.499612)
		(width 0.088646)
		(layer "In11.Cu")
		(net "M_D_CPU1_SA_CA<1>")
	)
	(arc
		(start 85.248496 -257.499612)
		(mid 84.965794 -257.423836)
		(end 84.683092 -257.499612)
		(width 0.088646)
		(layer "In11.Cu")
		(net "M_D_CPU1_SA_CA<1>")
	)
	(arc
		(start 91.82735 -257.499612)
		(mid 91.550537 -257.423742)
		(end 91.272106 -257.493516)
		(width 0.088646)
		(layer "In11.Cu")
		(net "M_D_CPU1_SA_CA<1>")
	)
	(arc
		(start 90.321892 -257.499612)
		(mid 90.134694 -257.549755)
		(end 89.947496 -257.499612)
		(width 0.088646)
		(layer "In11.Cu")
		(net "M_D_CPU1_SA_CA<1>")
	)
	(arc
		(start 90.872564 -257.490976)
		(mid 90.596089 -257.423656)
		(end 90.321892 -257.499612)
		(width 0.088646)
		(layer "In11.Cu")
		(net "M_D_CPU1_SA_CA<1>")
	)
	(arc
		(start 100.28555 -257.499612)
		(mid 100.008737 -257.423742)
		(end 99.730306 -257.493516)
		(width 0.088646)
		(layer "In11.Cu")
		(net "M_D_CPU1_SA_CA<1>")
	)
	(arc
		(start 87.502492 -257.499612)
		(mid 87.315294 -257.549755)
		(end 87.128096 -257.499612)
		(width 0.088646)
		(layer "In11.Cu")
		(net "M_D_CPU1_SA_CA<1>")
	)
	(arc
		(start 86.188296 -257.499612)
		(mid 85.905594 -257.423836)
		(end 85.622892 -257.499612)
		(width 0.088646)
		(layer "In11.Cu")
		(net "M_D_CPU1_SA_CA<1>")
	)
	(arc
		(start 92.756482 -257.493516)
		(mid 92.478304 -257.423793)
		(end 92.201746 -257.499612)
		(width 0.088646)
		(layer "In11.Cu")
		(net "M_D_CPU1_SA_CA<1>")
	)
	(arc
		(start 95.58655 -257.499612)
		(mid 95.312351 -257.423777)
		(end 95.035878 -257.490976)
		(width 0.088646)
		(layer "In11.Cu")
		(net "M_D_CPU1_SA_CA<1>")
	)
	(arc
		(start 88.442292 -257.499612)
		(mid 88.255094 -257.549755)
		(end 88.067896 -257.499612)
		(width 0.088646)
		(layer "In11.Cu")
		(net "M_D_CPU1_SA_CA<1>")
	)
	(arc
		(start 97.455482 -257.493516)
		(mid 97.177304 -257.423793)
		(end 96.900746 -257.499612)
		(width 0.088646)
		(layer "In11.Cu")
		(net "M_D_CPU1_SA_CA<1>")
	)
	(arc
		(start 92.201746 -257.499612)
		(mid 92.014548 -257.549755)
		(end 91.82735 -257.499612)
		(width 0.088646)
		(layer "In11.Cu")
		(net "M_D_CPU1_SA_CA<1>")
	)
	(arc
		(start 100.942394 -257.98907)
		(mid 100.667613 -257.748029)
		(end 100.363782 -257.544824)
		(width 0.088646)
		(layer "In11.Cu")
		(net "M_D_CPU1_SA_CA<1>")
	)
	(arc
		(start 99.719892 -257.499612)
		(mid 99.532694 -257.549755)
		(end 99.345496 -257.499612)
		(width 0.088646)
		(layer "In11.Cu")
		(net "M_D_CPU1_SA_CA<1>")
	)
	(arc
		(start 87.128096 -257.499612)
		(mid 86.845394 -257.423836)
		(end 86.562692 -257.499612)
		(width 0.088646)
		(layer "In11.Cu")
		(net "M_D_CPU1_SA_CA<1>")
	)
	(arc
		(start 98.780346 -257.499612)
		(mid 98.593148 -257.549755)
		(end 98.40595 -257.499612)
		(width 0.088646)
		(layer "In11.Cu")
		(net "M_D_CPU1_SA_CA<1>")
	)
	(arc
		(start 91.261692 -257.499612)
		(mid 91.074494 -257.549755)
		(end 90.887296 -257.499612)
		(width 0.088646)
		(layer "In11.Cu")
		(net "M_D_CPU1_SA_CA<1>")
	)
	(arc
		(start 99.335082 -257.493516)
		(mid 99.056904 -257.423793)
		(end 98.780346 -257.499612)
		(width 0.088646)
		(layer "In11.Cu")
		(net "M_D_CPU1_SA_CA<1>")
	)
	(arc
		(start 93.141292 -257.499612)
		(mid 92.954094 -257.549755)
		(end 92.766896 -257.499612)
		(width 0.088646)
		(layer "In11.Cu")
		(net "M_D_CPU1_SA_CA<1>")
	)
	(arc
		(start 86.562692 -257.499612)
		(mid 86.375494 -257.549755)
		(end 86.188296 -257.499612)
		(width 0.088646)
		(layer "In11.Cu")
		(net "M_D_CPU1_SA_CA<1>")
	)
	(arc
		(start 93.70695 -257.499612)
		(mid 93.430137 -257.423742)
		(end 93.151706 -257.493516)
		(width 0.088646)
		(layer "In11.Cu")
		(net "M_D_CPU1_SA_CA<1>")
	)
	(arc
		(start 84.308696 -257.499612)
		(mid 84.172327 -257.44317)
		(end 84.025994 -257.42392)
		(width 0.088646)
		(layer "In11.Cu")
		(net "M_D_CPU1_SA_CA<1>")
	)
	(arc
		(start 85.622892 -257.499612)
		(mid 85.435694 -257.549755)
		(end 85.248496 -257.499612)
		(width 0.088646)
		(layer "In11.Cu")
		(net "M_D_CPU1_SA_CA<1>")
	)
	(arc
		(start 84.683092 -257.499612)
		(mid 84.495894 -257.549755)
		(end 84.308696 -257.499612)
		(width 0.088646)
		(layer "In11.Cu")
		(net "M_D_CPU1_SA_CA<1>")
	)
	(arc
		(start 94.64675 -257.499612)
		(mid 94.372551 -257.423777)
		(end 94.096078 -257.490976)
		(width 0.088646)
		(layer "In11.Cu")
		(net "M_D_CPU1_SA_CA<1>")
	)
	(arc
		(start 95.960946 -257.499612)
		(mid 95.773748 -257.549755)
		(end 95.58655 -257.499612)
		(width 0.088646)
		(layer "In11.Cu")
		(net "M_D_CPU1_SA_CA<1>")
	)
	(arc
		(start 95.021146 -257.499612)
		(mid 94.833948 -257.549755)
		(end 94.64675 -257.499612)
		(width 0.088646)
		(layer "In11.Cu")
		(net "M_D_CPU1_SA_CA<1>")
	)
	(arc
		(start 97.840292 -257.499612)
		(mid 97.653094 -257.549755)
		(end 97.465896 -257.499612)
		(width 0.088646)
		(layer "In11.Cu")
		(net "M_D_CPU1_SA_CA<1>")
	)
	(arc
		(start 89.382092 -257.499612)
		(mid 89.194894 -257.549755)
		(end 89.007696 -257.499612)
		(width 0.088646)
		(layer "In11.Cu")
		(net "M_D_CPU1_SA_CA<1>")
	)
	(arc
		(start 89.947496 -257.499612)
		(mid 89.664794 -257.423836)
		(end 89.382092 -257.499612)
		(width 0.088646)
		(layer "In11.Cu")
		(net "M_D_CPU1_SA_CA<1>")
	)
	(segment
		(start 9.686036 -266.377928)
		(end 10.19048 -266.377928)
		(width 0.20066)
		(layer "F.Cu")
		(net "M_D_CPU1_SA_CA<0>")
	)
	(segment
		(start 10.344912 -266.223496)
		(end 10.344912 -265.895328)
		(width 0.20066)
		(layer "F.Cu")
		(net "M_D_CPU1_SA_CA<0>")
	)
	(segment
		(start 11.1252 -265.741658)
		(end 13.110718 -265.741658)
		(width 0.1016)
		(layer "F.Cu")
		(net "M_D_CPU1_SA_CA<0>")
	)
	(segment
		(start 10.507472 -265.732768)
		(end 11.11631 -265.732768)
		(width 0.20066)
		(layer "F.Cu")
		(net "M_D_CPU1_SA_CA<0>")
	)
	(segment
		(start 13.619988 -265.741658)
		(end 14.04493 -266.1666)
		(width 0.20066)
		(layer "F.Cu")
		(net "M_D_CPU1_SA_CA<0>")
	)
	(segment
		(start 9.474708 -266.1666)
		(end 9.686036 -266.377928)
		(width 0.20066)
		(layer "F.Cu")
		(net "M_D_CPU1_SA_CA<0>")
	)
	(segment
		(start 11.11631 -265.732768)
		(end 11.1252 -265.741658)
		(width 0.1016)
		(layer "F.Cu")
		(net "M_D_CPU1_SA_CA<0>")
	)
	(segment
		(start 13.441426 -265.741658)
		(end 13.619988 -265.741658)
		(width 0.20066)
		(layer "F.Cu")
		(net "M_D_CPU1_SA_CA<0>")
	)
	(segment
		(start 8.140446 -266.1666)
		(end 9.474708 -266.1666)
		(width 0.20066)
		(layer "F.Cu")
		(net "M_D_CPU1_SA_CA<0>")
	)
	(segment
		(start 98.123248 -257.45313)
		(end 98.123248 -257.988816)
		(width 0.20066)
		(layer "F.Cu")
		(net "M_D_CPU1_SA_CA<0>")
	)
	(segment
		(start 10.344912 -265.895328)
		(end 10.507472 -265.732768)
		(width 0.20066)
		(layer "F.Cu")
		(net "M_D_CPU1_SA_CA<0>")
	)
	(segment
		(start 10.19048 -266.377928)
		(end 10.344912 -266.223496)
		(width 0.20066)
		(layer "F.Cu")
		(net "M_D_CPU1_SA_CA<0>")
	)
	(segment
		(start 16.789146 -266.1666)
		(end 15.684246 -266.1666)
		(width 0.20066)
		(layer "F.Cu")
		(net "M_D_CPU1_SA_CA<0>")
	)
	(segment
		(start 13.110718 -265.741658)
		(end 13.441426 -265.741658)
		(width 0.101854)
		(layer "F.Cu")
		(net "M_D_CPU1_SA_CA<0>")
	)
	(segment
		(start 98.123248 -257.988816)
		(end 98.122994 -257.98907)
		(width 0.20066)
		(layer "F.Cu")
		(net "M_D_CPU1_SA_CA<0>")
	)
	(segment
		(start 14.04493 -266.1666)
		(end 15.684246 -266.1666)
		(width 0.20066)
		(layer "F.Cu")
		(net "M_D_CPU1_SA_CA<0>")
	)
	(segment
		(start 59.258454 -261.393686)
		(end 58.882026 -261.770114)
		(width 0.18288)
		(layer "In11.Cu")
		(net "M_D_CPU1_SA_CA<0>")
	)
	(segment
		(start 96.99625 -257.664712)
		(end 96.985836 -257.670808)
		(width 0.088646)
		(layer "In11.Cu")
		(net "M_D_CPU1_SA_CA<0>")
	)
	(segment
		(start 28.071826 -262.209026)
		(end 26.928826 -263.352026)
		(width 0.18288)
		(layer "In11.Cu")
		(net "M_D_CPU1_SA_CA<0>")
	)
	(segment
		(start 51.855116 -262.510016)
		(end 51.686206 -262.341106)
		(width 0.18288)
		(layer "In11.Cu")
		(net "M_D_CPU1_SA_CA<0>")
	)
	(segment
		(start 82.987134 -257.524758)
		(end 81.520792 -257.524758)
		(width 0.18288)
		(layer "In11.Cu")
		(net "M_D_CPU1_SA_CA<0>")
	)
	(segment
		(start 24.084026 -264.088626)
		(end 22.312122 -265.86053)
		(width 0.18288)
		(layer "In11.Cu")
		(net "M_D_CPU1_SA_CA<0>")
	)
	(segment
		(start 45.742606 -262.343646)
		(end 45.673264 -262.412988)
		(width 0.18288)
		(layer "In11.Cu")
		(net "M_D_CPU1_SA_CA<0>")
	)
	(segment
		(start 29.062426 -262.209026)
		(end 28.071826 -262.209026)
		(width 0.18288)
		(layer "In11.Cu")
		(net "M_D_CPU1_SA_CA<0>")
	)
	(segment
		(start 21.873972 -265.739372)
		(end 17.216374 -265.739372)
		(width 0.18288)
		(layer "In11.Cu")
		(net "M_D_CPU1_SA_CA<0>")
	)
	(segment
		(start 92.68206 -257.670808)
		(end 92.671646 -257.664712)
		(width 0.088646)
		(layer "In11.Cu")
		(net "M_D_CPU1_SA_CA<0>")
	)
	(segment
		(start 30.320996 -262.525256)
		(end 29.378656 -262.525256)
		(width 0.18288)
		(layer "In11.Cu")
		(net "M_D_CPU1_SA_CA<0>")
	)
	(segment
		(start 94.176596 -257.664712)
		(end 94.161864 -257.673348)
		(width 0.088646)
		(layer "In11.Cu")
		(net "M_D_CPU1_SA_CA<0>")
	)
	(segment
		(start 72.581516 -258.015232)
		(end 71.645526 -258.951222)
		(width 0.18288)
		(layer "In11.Cu")
		(net "M_D_CPU1_SA_CA<0>")
	)
	(segment
		(start 48.308514 -262.18007)
		(end 48.144938 -262.343646)
		(width 0.18288)
		(layer "In11.Cu")
		(net "M_D_CPU1_SA_CA<0>")
	)
	(segment
		(start 62.415166 -261.393686)
		(end 59.258454 -261.393686)
		(width 0.18288)
		(layer "In11.Cu")
		(net "M_D_CPU1_SA_CA<0>")
	)
	(segment
		(start 22.312122 -265.86053)
		(end 21.99513 -265.86053)
		(width 0.18288)
		(layer "In11.Cu")
		(net "M_D_CPU1_SA_CA<0>")
	)
	(segment
		(start 55.612538 -261.770114)
		(end 54.872636 -262.510016)
		(width 0.18288)
		(layer "In11.Cu")
		(net "M_D_CPU1_SA_CA<0>")
	)
	(segment
		(start 45.673264 -262.412988)
		(end 44.221908 -262.412988)
		(width 0.18288)
		(layer "In11.Cu")
		(net "M_D_CPU1_SA_CA<0>")
	)
	(segment
		(start 83.623658 -257.524758)
		(end 82.987134 -257.524758)
		(width 0.088646)
		(layer "In11.Cu")
		(net "M_D_CPU1_SA_CA<0>")
	)
	(segment
		(start 33.396174 -263.304274)
		(end 32.433006 -262.341106)
		(width 0.18288)
		(layer "In11.Cu")
		(net "M_D_CPU1_SA_CA<0>")
	)
	(segment
		(start 58.882026 -261.770114)
		(end 55.612538 -261.770114)
		(width 0.18288)
		(layer "In11.Cu")
		(net "M_D_CPU1_SA_CA<0>")
	)
	(segment
		(start 97.38106 -257.670808)
		(end 97.370646 -257.664712)
		(width 0.088646)
		(layer "In11.Cu")
		(net "M_D_CPU1_SA_CA<0>")
	)
	(segment
		(start 44.221908 -262.412988)
		(end 44.017946 -262.209026)
		(width 0.18288)
		(layer "In11.Cu")
		(net "M_D_CPU1_SA_CA<0>")
	)
	(segment
		(start 49.780698 -262.341106)
		(end 49.619662 -262.18007)
		(width 0.18288)
		(layer "In11.Cu")
		(net "M_D_CPU1_SA_CA<0>")
	)
	(segment
		(start 92.29725 -257.664712)
		(end 92.286836 -257.670808)
		(width 0.088646)
		(layer "In11.Cu")
		(net "M_D_CPU1_SA_CA<0>")
	)
	(segment
		(start 84.025994 -257.614166)
		(end 83.713066 -257.614166)
		(width 0.088646)
		(layer "In11.Cu")
		(net "M_D_CPU1_SA_CA<0>")
	)
	(segment
		(start 36.672012 -262.457692)
		(end 36.555426 -262.341106)
		(width 0.18288)
		(layer "In11.Cu")
		(net "M_D_CPU1_SA_CA<0>")
	)
	(segment
		(start 71.645526 -258.951222)
		(end 67.929252 -258.951222)
		(width 0.18288)
		(layer "In11.Cu")
		(net "M_D_CPU1_SA_CA<0>")
	)
	(segment
		(start 83.713066 -257.614166)
		(end 83.623658 -257.524758)
		(width 0.088646)
		(layer "In11.Cu")
		(net "M_D_CPU1_SA_CA<0>")
	)
	(segment
		(start 26.928826 -263.352026)
		(end 25.684226 -263.352026)
		(width 0.18288)
		(layer "In11.Cu")
		(net "M_D_CPU1_SA_CA<0>")
	)
	(segment
		(start 29.378656 -262.525256)
		(end 29.062426 -262.209026)
		(width 0.18288)
		(layer "In11.Cu")
		(net "M_D_CPU1_SA_CA<0>")
	)
	(segment
		(start 97.594674 -257.737356)
		(end 97.59442 -257.737356)
		(width 0.088646)
		(layer "In11.Cu")
		(net "M_D_CPU1_SA_CA<0>")
	)
	(segment
		(start 34.106358 -263.304274)
		(end 33.396174 -263.304274)
		(width 0.18288)
		(layer "In11.Cu")
		(net "M_D_CPU1_SA_CA<0>")
	)
	(segment
		(start 40.65778 -262.209026)
		(end 40.409114 -262.457692)
		(width 0.18288)
		(layer "In11.Cu")
		(net "M_D_CPU1_SA_CA<0>")
	)
	(segment
		(start 21.99513 -265.86053)
		(end 21.873972 -265.739372)
		(width 0.18288)
		(layer "In11.Cu")
		(net "M_D_CPU1_SA_CA<0>")
	)
	(segment
		(start 66.813938 -260.066536)
		(end 65.396364 -260.066536)
		(width 0.18288)
		(layer "In11.Cu")
		(net "M_D_CPU1_SA_CA<0>")
	)
	(segment
		(start 54.872636 -262.510016)
		(end 51.855116 -262.510016)
		(width 0.18288)
		(layer "In11.Cu")
		(net "M_D_CPU1_SA_CA<0>")
	)
	(segment
		(start 48.144938 -262.343646)
		(end 45.742606 -262.343646)
		(width 0.18288)
		(layer "In11.Cu")
		(net "M_D_CPU1_SA_CA<0>")
	)
	(segment
		(start 25.684226 -263.352026)
		(end 24.947626 -264.088626)
		(width 0.18288)
		(layer "In11.Cu")
		(net "M_D_CPU1_SA_CA<0>")
	)
	(segment
		(start 36.555426 -262.341106)
		(end 35.069526 -262.341106)
		(width 0.18288)
		(layer "In11.Cu")
		(net "M_D_CPU1_SA_CA<0>")
	)
	(segment
		(start 17.216374 -265.739372)
		(end 16.789146 -266.1666)
		(width 0.18288)
		(layer "In11.Cu")
		(net "M_D_CPU1_SA_CA<0>")
	)
	(segment
		(start 65.396364 -260.066536)
		(end 64.868806 -260.594094)
		(width 0.18288)
		(layer "In11.Cu")
		(net "M_D_CPU1_SA_CA<0>")
	)
	(segment
		(start 35.069526 -262.341106)
		(end 34.106358 -263.304274)
		(width 0.18288)
		(layer "In11.Cu")
		(net "M_D_CPU1_SA_CA<0>")
	)
	(segment
		(start 81.030318 -258.015232)
		(end 72.581516 -258.015232)
		(width 0.18288)
		(layer "In11.Cu")
		(net "M_D_CPU1_SA_CA<0>")
	)
	(segment
		(start 67.929252 -258.951222)
		(end 66.813938 -260.066536)
		(width 0.18288)
		(layer "In11.Cu")
		(net "M_D_CPU1_SA_CA<0>")
	)
	(segment
		(start 24.947626 -264.088626)
		(end 24.084026 -264.088626)
		(width 0.18288)
		(layer "In11.Cu")
		(net "M_D_CPU1_SA_CA<0>")
	)
	(segment
		(start 81.520792 -257.524758)
		(end 81.030318 -258.015232)
		(width 0.18288)
		(layer "In11.Cu")
		(net "M_D_CPU1_SA_CA<0>")
	)
	(segment
		(start 32.433006 -262.341106)
		(end 30.505146 -262.341106)
		(width 0.18288)
		(layer "In11.Cu")
		(net "M_D_CPU1_SA_CA<0>")
	)
	(segment
		(start 44.017946 -262.209026)
		(end 40.65778 -262.209026)
		(width 0.18288)
		(layer "In11.Cu")
		(net "M_D_CPU1_SA_CA<0>")
	)
	(segment
		(start 63.214758 -260.594094)
		(end 62.415166 -261.393686)
		(width 0.18288)
		(layer "In11.Cu")
		(net "M_D_CPU1_SA_CA<0>")
	)
	(segment
		(start 89.862406 -257.670808)
		(end 89.851992 -257.664712)
		(width 0.088646)
		(layer "In11.Cu")
		(net "M_D_CPU1_SA_CA<0>")
	)
	(segment
		(start 51.686206 -262.341106)
		(end 49.780698 -262.341106)
		(width 0.18288)
		(layer "In11.Cu")
		(net "M_D_CPU1_SA_CA<0>")
	)
	(segment
		(start 90.80246 -257.670808)
		(end 90.792046 -257.664712)
		(width 0.088646)
		(layer "In11.Cu")
		(net "M_D_CPU1_SA_CA<0>")
	)
	(segment
		(start 64.868806 -260.594094)
		(end 63.214758 -260.594094)
		(width 0.18288)
		(layer "In11.Cu")
		(net "M_D_CPU1_SA_CA<0>")
	)
	(segment
		(start 96.056196 -257.664712)
		(end 96.041464 -257.673348)
		(width 0.088646)
		(layer "In11.Cu")
		(net "M_D_CPU1_SA_CA<0>")
	)
	(segment
		(start 95.116396 -257.664712)
		(end 95.101664 -257.673348)
		(width 0.088646)
		(layer "In11.Cu")
		(net "M_D_CPU1_SA_CA<0>")
	)
	(segment
		(start 30.505146 -262.341106)
		(end 30.320996 -262.525256)
		(width 0.18288)
		(layer "In11.Cu")
		(net "M_D_CPU1_SA_CA<0>")
	)
	(segment
		(start 49.619662 -262.18007)
		(end 48.308514 -262.18007)
		(width 0.18288)
		(layer "In11.Cu")
		(net "M_D_CPU1_SA_CA<0>")
	)
	(segment
		(start 40.409114 -262.457692)
		(end 36.672012 -262.457692)
		(width 0.18288)
		(layer "In11.Cu")
		(net "M_D_CPU1_SA_CA<0>")
	)
	(arc
		(start 92.286836 -257.670808)
		(mid 92.008404 -257.740654)
		(end 91.731592 -257.664712)
		(width 0.088646)
		(layer "In11.Cu")
		(net "M_D_CPU1_SA_CA<0>")
	)
	(arc
		(start 87.032592 -257.664712)
		(mid 86.845394 -257.614569)
		(end 86.658196 -257.664712)
		(width 0.088646)
		(layer "In11.Cu")
		(net "M_D_CPU1_SA_CA<0>")
	)
	(arc
		(start 85.718396 -257.664712)
		(mid 85.435694 -257.740488)
		(end 85.152992 -257.664712)
		(width 0.088646)
		(layer "In11.Cu")
		(net "M_D_CPU1_SA_CA<0>")
	)
	(arc
		(start 87.972392 -257.664712)
		(mid 87.785194 -257.614569)
		(end 87.597996 -257.664712)
		(width 0.088646)
		(layer "In11.Cu")
		(net "M_D_CPU1_SA_CA<0>")
	)
	(arc
		(start 98.122994 -257.98907)
		(mid 97.880503 -257.817722)
		(end 97.594674 -257.737356)
		(width 0.088646)
		(layer "In11.Cu")
		(net "M_D_CPU1_SA_CA<0>")
	)
	(arc
		(start 97.59442 -257.737356)
		(mid 97.484429 -257.714707)
		(end 97.38106 -257.670808)
		(width 0.088646)
		(layer "In11.Cu")
		(net "M_D_CPU1_SA_CA<0>")
	)
	(arc
		(start 94.550992 -257.664712)
		(mid 94.363794 -257.614569)
		(end 94.176596 -257.664712)
		(width 0.088646)
		(layer "In11.Cu")
		(net "M_D_CPU1_SA_CA<0>")
	)
	(arc
		(start 97.370646 -257.664712)
		(mid 97.183448 -257.614569)
		(end 96.99625 -257.664712)
		(width 0.088646)
		(layer "In11.Cu")
		(net "M_D_CPU1_SA_CA<0>")
	)
	(arc
		(start 90.792046 -257.664712)
		(mid 90.604848 -257.614569)
		(end 90.41765 -257.664712)
		(width 0.088646)
		(layer "In11.Cu")
		(net "M_D_CPU1_SA_CA<0>")
	)
	(arc
		(start 89.851992 -257.664712)
		(mid 89.664794 -257.614569)
		(end 89.477596 -257.664712)
		(width 0.088646)
		(layer "In11.Cu")
		(net "M_D_CPU1_SA_CA<0>")
	)
	(arc
		(start 91.731592 -257.664712)
		(mid 91.544394 -257.614569)
		(end 91.357196 -257.664712)
		(width 0.088646)
		(layer "In11.Cu")
		(net "M_D_CPU1_SA_CA<0>")
	)
	(arc
		(start 94.161864 -257.673348)
		(mid 93.885389 -257.740668)
		(end 93.611192 -257.664712)
		(width 0.088646)
		(layer "In11.Cu")
		(net "M_D_CPU1_SA_CA<0>")
	)
	(arc
		(start 84.213192 -257.664712)
		(mid 84.12292 -257.627113)
		(end 84.025994 -257.614166)
		(width 0.088646)
		(layer "In11.Cu")
		(net "M_D_CPU1_SA_CA<0>")
	)
	(arc
		(start 92.671646 -257.664712)
		(mid 92.484448 -257.614569)
		(end 92.29725 -257.664712)
		(width 0.088646)
		(layer "In11.Cu")
		(net "M_D_CPU1_SA_CA<0>")
	)
	(arc
		(start 90.41765 -257.664712)
		(mid 90.140837 -257.740582)
		(end 89.862406 -257.670808)
		(width 0.088646)
		(layer "In11.Cu")
		(net "M_D_CPU1_SA_CA<0>")
	)
	(arc
		(start 84.778596 -257.664712)
		(mid 84.495894 -257.740488)
		(end 84.213192 -257.664712)
		(width 0.088646)
		(layer "In11.Cu")
		(net "M_D_CPU1_SA_CA<0>")
	)
	(arc
		(start 87.597996 -257.664712)
		(mid 87.315294 -257.740488)
		(end 87.032592 -257.664712)
		(width 0.088646)
		(layer "In11.Cu")
		(net "M_D_CPU1_SA_CA<0>")
	)
	(arc
		(start 86.092792 -257.664712)
		(mid 85.905594 -257.614569)
		(end 85.718396 -257.664712)
		(width 0.088646)
		(layer "In11.Cu")
		(net "M_D_CPU1_SA_CA<0>")
	)
	(arc
		(start 93.236796 -257.664712)
		(mid 92.960237 -257.740455)
		(end 92.68206 -257.670808)
		(width 0.088646)
		(layer "In11.Cu")
		(net "M_D_CPU1_SA_CA<0>")
	)
	(arc
		(start 89.477596 -257.664712)
		(mid 89.194894 -257.740488)
		(end 88.912192 -257.664712)
		(width 0.088646)
		(layer "In11.Cu")
		(net "M_D_CPU1_SA_CA<0>")
	)
	(arc
		(start 91.357196 -257.664712)
		(mid 91.080637 -257.740455)
		(end 90.80246 -257.670808)
		(width 0.088646)
		(layer "In11.Cu")
		(net "M_D_CPU1_SA_CA<0>")
	)
	(arc
		(start 96.985836 -257.670808)
		(mid 96.707404 -257.740654)
		(end 96.430592 -257.664712)
		(width 0.088646)
		(layer "In11.Cu")
		(net "M_D_CPU1_SA_CA<0>")
	)
	(arc
		(start 96.430592 -257.664712)
		(mid 96.243394 -257.614569)
		(end 96.056196 -257.664712)
		(width 0.088646)
		(layer "In11.Cu")
		(net "M_D_CPU1_SA_CA<0>")
	)
	(arc
		(start 93.611192 -257.664712)
		(mid 93.423994 -257.614569)
		(end 93.236796 -257.664712)
		(width 0.088646)
		(layer "In11.Cu")
		(net "M_D_CPU1_SA_CA<0>")
	)
	(arc
		(start 88.537796 -257.664712)
		(mid 88.255094 -257.740488)
		(end 87.972392 -257.664712)
		(width 0.088646)
		(layer "In11.Cu")
		(net "M_D_CPU1_SA_CA<0>")
	)
	(arc
		(start 85.152992 -257.664712)
		(mid 84.965794 -257.614569)
		(end 84.778596 -257.664712)
		(width 0.088646)
		(layer "In11.Cu")
		(net "M_D_CPU1_SA_CA<0>")
	)
	(arc
		(start 96.041464 -257.673348)
		(mid 95.764989 -257.740668)
		(end 95.490792 -257.664712)
		(width 0.088646)
		(layer "In11.Cu")
		(net "M_D_CPU1_SA_CA<0>")
	)
	(arc
		(start 95.101664 -257.673348)
		(mid 94.825189 -257.740668)
		(end 94.550992 -257.664712)
		(width 0.088646)
		(layer "In11.Cu")
		(net "M_D_CPU1_SA_CA<0>")
	)
	(arc
		(start 88.912192 -257.664712)
		(mid 88.724994 -257.614569)
		(end 88.537796 -257.664712)
		(width 0.088646)
		(layer "In11.Cu")
		(net "M_D_CPU1_SA_CA<0>")
	)
	(arc
		(start 86.658196 -257.664712)
		(mid 86.375494 -257.740488)
		(end 86.092792 -257.664712)
		(width 0.088646)
		(layer "In11.Cu")
		(net "M_D_CPU1_SA_CA<0>")
	)
	(arc
		(start 95.490792 -257.664712)
		(mid 95.303594 -257.614569)
		(end 95.116396 -257.664712)
		(width 0.088646)
		(layer "In11.Cu")
		(net "M_D_CPU1_SA_CA<0>")
	)
	(segment
		(start 19.784314 -260.21665)
		(end 20.889214 -260.21665)
		(width 0.20066)
		(layer "F.Cu")
		(net "M_D_CPU1_CLK_DP<1>")
	)
	(segment
		(start 100.832412 -250.15571)
		(end 100.832412 -249.620024)
		(width 0.20066)
		(layer "F.Cu")
		(net "M_D_CPU1_CLK_DP<1>")
	)
	(segment
		(start 100.832666 -250.155964)
		(end 100.832412 -250.15571)
		(width 0.20066)
		(layer "F.Cu")
		(net "M_D_CPU1_CLK_DP<1>")
	)
	(segment
		(start 83.063334 -252.668786)
		(end 82.244692 -253.007876)
		(width 0.18288)
		(layer "In11.Cu")
		(net "M_D_CPU1_CLK_DP<1>")
	)
	(segment
		(start 81.817972 -253.18466)
		(end 79.784194 -255.218438)
		(width 0.18288)
		(layer "In11.Cu")
		(net "M_D_CPU1_CLK_DP<1>")
	)
	(segment
		(start 75.91552 -255.218438)
		(end 74.878184 -254.181102)
		(width 0.18288)
		(layer "In11.Cu")
		(net "M_D_CPU1_CLK_DP<1>")
	)
	(segment
		(start 79.784194 -255.218438)
		(end 75.91552 -255.218438)
		(width 0.18288)
		(layer "In11.Cu")
		(net "M_D_CPU1_CLK_DP<1>")
	)
	(segment
		(start 63.63462 -255.755394)
		(end 57.918858 -255.755394)
		(width 0.18288)
		(layer "In11.Cu")
		(net "M_D_CPU1_CLK_DP<1>")
	)
	(segment
		(start 21.144992 -259.834888)
		(end 21.144992 -259.960872)
		(width 0.18288)
		(layer "In11.Cu")
		(net "M_D_CPU1_CLK_DP<1>")
	)
	(segment
		(start 98.770186 -252.413008)
		(end 86.510876 -252.413008)
		(width 0.18288)
		(layer "In11.Cu")
		(net "M_D_CPU1_CLK_DP<1>")
	)
	(segment
		(start 100.53701 -249.915426)
		(end 100.53701 -250.646184)
		(width 0.18288)
		(layer "In11.Cu")
		(net "M_D_CPU1_CLK_DP<1>")
	)
	(segment
		(start 26.719022 -256.544826)
		(end 23.478998 -256.544826)
		(width 0.18288)
		(layer "In11.Cu")
		(net "M_D_CPU1_CLK_DP<1>")
	)
	(segment
		(start 53.353462 -256.057908)
		(end 49.78527 -256.057908)
		(width 0.18288)
		(layer "In11.Cu")
		(net "M_D_CPU1_CLK_DP<1>")
	)
	(segment
		(start 82.244692 -253.007876)
		(end 81.817972 -253.18466)
		(width 0.18288)
		(layer "In11.Cu")
		(net "M_D_CPU1_CLK_DP<1>")
	)
	(segment
		(start 86.510876 -252.413008)
		(end 86.255098 -252.668786)
		(width 0.18288)
		(layer "In11.Cu")
		(net "M_D_CPU1_CLK_DP<1>")
	)
	(segment
		(start 86.255098 -252.668786)
		(end 83.063334 -252.668786)
		(width 0.18288)
		(layer "In11.Cu")
		(net "M_D_CPU1_CLK_DP<1>")
	)
	(segment
		(start 100.832412 -249.620024)
		(end 100.53701 -249.915426)
		(width 0.18288)
		(layer "In11.Cu")
		(net "M_D_CPU1_CLK_DP<1>")
	)
	(segment
		(start 27.215846 -256.048002)
		(end 26.719022 -256.544826)
		(width 0.18288)
		(layer "In11.Cu")
		(net "M_D_CPU1_CLK_DP<1>")
	)
	(segment
		(start 67.431666 -254.181102)
		(end 63.63462 -255.755394)
		(width 0.18288)
		(layer "In11.Cu")
		(net "M_D_CPU1_CLK_DP<1>")
	)
	(segment
		(start 30.877256 -256.048002)
		(end 27.215846 -256.048002)
		(width 0.18288)
		(layer "In11.Cu")
		(net "M_D_CPU1_CLK_DP<1>")
	)
	(segment
		(start 42.320718 -256.001266)
		(end 41.837864 -256.48412)
		(width 0.18288)
		(layer "In11.Cu")
		(net "M_D_CPU1_CLK_DP<1>")
	)
	(segment
		(start 100.53701 -250.646184)
		(end 98.770186 -252.413008)
		(width 0.18288)
		(layer "In11.Cu")
		(net "M_D_CPU1_CLK_DP<1>")
	)
	(segment
		(start 21.673566 -259.306314)
		(end 21.144992 -259.834888)
		(width 0.18288)
		(layer "In11.Cu")
		(net "M_D_CPU1_CLK_DP<1>")
	)
	(segment
		(start 49.445926 -256.397252)
		(end 46.380908 -256.397252)
		(width 0.18288)
		(layer "In11.Cu")
		(net "M_D_CPU1_CLK_DP<1>")
	)
	(segment
		(start 23.478998 -256.544826)
		(end 21.673566 -258.350258)
		(width 0.18288)
		(layer "In11.Cu")
		(net "M_D_CPU1_CLK_DP<1>")
	)
	(segment
		(start 31.256986 -256.427732)
		(end 30.877256 -256.048002)
		(width 0.18288)
		(layer "In11.Cu")
		(net "M_D_CPU1_CLK_DP<1>")
	)
	(segment
		(start 38.347904 -255.97231)
		(end 34.86277 -255.97231)
		(width 0.18288)
		(layer "In11.Cu")
		(net "M_D_CPU1_CLK_DP<1>")
	)
	(segment
		(start 74.878184 -254.181102)
		(end 67.431666 -254.181102)
		(width 0.18288)
		(layer "In11.Cu")
		(net "M_D_CPU1_CLK_DP<1>")
	)
	(segment
		(start 21.673566 -258.350258)
		(end 21.673566 -259.306314)
		(width 0.18288)
		(layer "In11.Cu")
		(net "M_D_CPU1_CLK_DP<1>")
	)
	(segment
		(start 41.837864 -256.48412)
		(end 38.859714 -256.48412)
		(width 0.18288)
		(layer "In11.Cu")
		(net "M_D_CPU1_CLK_DP<1>")
	)
	(segment
		(start 49.78527 -256.057908)
		(end 49.445926 -256.397252)
		(width 0.18288)
		(layer "In11.Cu")
		(net "M_D_CPU1_CLK_DP<1>")
	)
	(segment
		(start 46.380908 -256.397252)
		(end 45.984922 -256.001266)
		(width 0.18288)
		(layer "In11.Cu")
		(net "M_D_CPU1_CLK_DP<1>")
	)
	(segment
		(start 57.17286 -256.501392)
		(end 53.796946 -256.501392)
		(width 0.18288)
		(layer "In11.Cu")
		(net "M_D_CPU1_CLK_DP<1>")
	)
	(segment
		(start 53.796946 -256.501392)
		(end 53.353462 -256.057908)
		(width 0.18288)
		(layer "In11.Cu")
		(net "M_D_CPU1_CLK_DP<1>")
	)
	(segment
		(start 57.918858 -255.755394)
		(end 57.17286 -256.501392)
		(width 0.18288)
		(layer "In11.Cu")
		(net "M_D_CPU1_CLK_DP<1>")
	)
	(segment
		(start 34.407348 -256.427732)
		(end 31.256986 -256.427732)
		(width 0.18288)
		(layer "In11.Cu")
		(net "M_D_CPU1_CLK_DP<1>")
	)
	(segment
		(start 45.984922 -256.001266)
		(end 42.320718 -256.001266)
		(width 0.18288)
		(layer "In11.Cu")
		(net "M_D_CPU1_CLK_DP<1>")
	)
	(segment
		(start 21.144992 -259.960872)
		(end 20.889214 -260.21665)
		(width 0.18288)
		(layer "In11.Cu")
		(net "M_D_CPU1_CLK_DP<1>")
	)
	(segment
		(start 34.86277 -255.97231)
		(end 34.407348 -256.427732)
		(width 0.18288)
		(layer "In11.Cu")
		(net "M_D_CPU1_CLK_DP<1>")
	)
	(segment
		(start 38.859714 -256.48412)
		(end 38.347904 -255.97231)
		(width 0.18288)
		(layer "In11.Cu")
		(net "M_D_CPU1_CLK_DP<1>")
	)
	(segment
		(start 12.240514 -260.21665)
		(end 13.345414 -260.21665)
		(width 0.20066)
		(layer "F.Cu")
		(net "M_D_CPU1_CLK_DP<0>")
	)
	(segment
		(start 98.953066 -250.155964)
		(end 98.953066 -249.620278)
		(width 0.20066)
		(layer "F.Cu")
		(net "M_D_CPU1_CLK_DP<0>")
	)
	(segment
		(start 98.953066 -249.620278)
		(end 98.952812 -249.620024)
		(width 0.20066)
		(layer "F.Cu")
		(net "M_D_CPU1_CLK_DP<0>")
	)
	(segment
		(start 31.607506 -255.598422)
		(end 31.000192 -254.991108)
		(width 0.18288)
		(layer "In11.Cu")
		(net "M_D_CPU1_CLK_DP<0>")
	)
	(segment
		(start 26.366978 -255.706626)
		(end 22.429724 -255.706626)
		(width 0.18288)
		(layer "In11.Cu")
		(net "M_D_CPU1_CLK_DP<0>")
	)
	(segment
		(start 59.252866 -253.936246)
		(end 57.921652 -253.936246)
		(width 0.18288)
		(layer "In11.Cu")
		(net "M_D_CPU1_CLK_DP<0>")
	)
	(segment
		(start 53.711602 -255.229868)
		(end 49.43729 -255.229868)
		(width 0.18288)
		(layer "In11.Cu")
		(net "M_D_CPU1_CLK_DP<0>")
	)
	(segment
		(start 14.960854 -259.514086)
		(end 13.89126 -259.958078)
		(width 0.18288)
		(layer "In11.Cu")
		(net "M_D_CPU1_CLK_DP<0>")
	)
	(segment
		(start 13.603986 -259.958078)
		(end 13.345414 -260.21665)
		(width 0.18288)
		(layer "In11.Cu")
		(net "M_D_CPU1_CLK_DP<0>")
	)
	(segment
		(start 27.082496 -254.991108)
		(end 26.366978 -255.706626)
		(width 0.18288)
		(layer "In11.Cu")
		(net "M_D_CPU1_CLK_DP<0>")
	)
	(segment
		(start 49.43729 -255.229868)
		(end 49.0982 -255.568958)
		(width 0.18288)
		(layer "In11.Cu")
		(net "M_D_CPU1_CLK_DP<0>")
	)
	(segment
		(start 74.870818 -252.94209)
		(end 68.014342 -252.94209)
		(width 0.18288)
		(layer "In11.Cu")
		(net "M_D_CPU1_CLK_DP<0>")
	)
	(segment
		(start 97.803208 -251.544836)
		(end 86.034626 -251.544836)
		(width 0.18288)
		(layer "In11.Cu")
		(net "M_D_CPU1_CLK_DP<0>")
	)
	(segment
		(start 82.133186 -251.779786)
		(end 79.36738 -254.545592)
		(width 0.18288)
		(layer "In11.Cu")
		(net "M_D_CPU1_CLK_DP<0>")
	)
	(segment
		(start 85.799676 -251.779786)
		(end 82.133186 -251.779786)
		(width 0.18288)
		(layer "In11.Cu")
		(net "M_D_CPU1_CLK_DP<0>")
	)
	(segment
		(start 57.497726 -254.893318)
		(end 56.760618 -255.630426)
		(width 0.18288)
		(layer "In11.Cu")
		(net "M_D_CPU1_CLK_DP<0>")
	)
	(segment
		(start 98.952812 -249.620024)
		(end 98.645218 -249.927618)
		(width 0.18288)
		(layer "In11.Cu")
		(net "M_D_CPU1_CLK_DP<0>")
	)
	(segment
		(start 98.645218 -250.702826)
		(end 97.803208 -251.544836)
		(width 0.18288)
		(layer "In11.Cu")
		(net "M_D_CPU1_CLK_DP<0>")
	)
	(segment
		(start 98.645218 -249.927618)
		(end 98.645218 -250.702826)
		(width 0.18288)
		(layer "In11.Cu")
		(net "M_D_CPU1_CLK_DP<0>")
	)
	(segment
		(start 57.497726 -254.360172)
		(end 57.497726 -254.893318)
		(width 0.18288)
		(layer "In11.Cu")
		(net "M_D_CPU1_CLK_DP<0>")
	)
	(segment
		(start 63.237618 -252.104652)
		(end 59.252866 -253.936246)
		(width 0.18288)
		(layer "In11.Cu")
		(net "M_D_CPU1_CLK_DP<0>")
	)
	(segment
		(start 13.89126 -259.958078)
		(end 13.603986 -259.958078)
		(width 0.18288)
		(layer "In11.Cu")
		(net "M_D_CPU1_CLK_DP<0>")
	)
	(segment
		(start 31.000192 -254.991108)
		(end 27.082496 -254.991108)
		(width 0.18288)
		(layer "In11.Cu")
		(net "M_D_CPU1_CLK_DP<0>")
	)
	(segment
		(start 56.760618 -255.630426)
		(end 54.11216 -255.630426)
		(width 0.18288)
		(layer "In11.Cu")
		(net "M_D_CPU1_CLK_DP<0>")
	)
	(segment
		(start 41.946322 -255.170178)
		(end 41.486074 -255.630426)
		(width 0.18288)
		(layer "In11.Cu")
		(net "M_D_CPU1_CLK_DP<0>")
	)
	(segment
		(start 20.22983 -257.90652)
		(end 16.83258 -257.90652)
		(width 0.18288)
		(layer "In11.Cu")
		(net "M_D_CPU1_CLK_DP<0>")
	)
	(segment
		(start 57.921652 -253.936246)
		(end 57.497726 -254.360172)
		(width 0.18288)
		(layer "In11.Cu")
		(net "M_D_CPU1_CLK_DP<0>")
	)
	(segment
		(start 34.039302 -255.598422)
		(end 31.607506 -255.598422)
		(width 0.18288)
		(layer "In11.Cu")
		(net "M_D_CPU1_CLK_DP<0>")
	)
	(segment
		(start 46.343316 -255.170178)
		(end 41.946322 -255.170178)
		(width 0.18288)
		(layer "In11.Cu")
		(net "M_D_CPU1_CLK_DP<0>")
	)
	(segment
		(start 79.36738 -254.545592)
		(end 76.47432 -254.545592)
		(width 0.18288)
		(layer "In11.Cu")
		(net "M_D_CPU1_CLK_DP<0>")
	)
	(segment
		(start 22.429724 -255.706626)
		(end 20.22983 -257.90652)
		(width 0.18288)
		(layer "In11.Cu")
		(net "M_D_CPU1_CLK_DP<0>")
	)
	(segment
		(start 63.928244 -252.104652)
		(end 63.237618 -252.104652)
		(width 0.18288)
		(layer "In11.Cu")
		(net "M_D_CPU1_CLK_DP<0>")
	)
	(segment
		(start 41.486074 -255.630426)
		(end 39.187374 -255.630426)
		(width 0.18288)
		(layer "In11.Cu")
		(net "M_D_CPU1_CLK_DP<0>")
	)
	(segment
		(start 76.47432 -254.545592)
		(end 74.870818 -252.94209)
		(width 0.18288)
		(layer "In11.Cu")
		(net "M_D_CPU1_CLK_DP<0>")
	)
	(segment
		(start 49.0982 -255.568958)
		(end 46.742096 -255.568958)
		(width 0.18288)
		(layer "In11.Cu")
		(net "M_D_CPU1_CLK_DP<0>")
	)
	(segment
		(start 16.83258 -257.90652)
		(end 16.381222 -258.093718)
		(width 0.18288)
		(layer "In11.Cu")
		(net "M_D_CPU1_CLK_DP<0>")
	)
	(segment
		(start 46.742096 -255.568958)
		(end 46.343316 -255.170178)
		(width 0.18288)
		(layer "In11.Cu")
		(net "M_D_CPU1_CLK_DP<0>")
	)
	(segment
		(start 34.663634 -254.97409)
		(end 34.039302 -255.598422)
		(width 0.18288)
		(layer "In11.Cu")
		(net "M_D_CPU1_CLK_DP<0>")
	)
	(segment
		(start 86.034626 -251.544836)
		(end 85.799676 -251.779786)
		(width 0.18288)
		(layer "In11.Cu")
		(net "M_D_CPU1_CLK_DP<0>")
	)
	(segment
		(start 68.014342 -252.94209)
		(end 63.928244 -252.104652)
		(width 0.18288)
		(layer "In11.Cu")
		(net "M_D_CPU1_CLK_DP<0>")
	)
	(segment
		(start 39.187374 -255.630426)
		(end 38.531038 -254.97409)
		(width 0.18288)
		(layer "In11.Cu")
		(net "M_D_CPU1_CLK_DP<0>")
	)
	(segment
		(start 54.11216 -255.630426)
		(end 53.711602 -255.229868)
		(width 0.18288)
		(layer "In11.Cu")
		(net "M_D_CPU1_CLK_DP<0>")
	)
	(segment
		(start 16.381222 -258.093718)
		(end 14.960854 -259.514086)
		(width 0.18288)
		(layer "In11.Cu")
		(net "M_D_CPU1_CLK_DP<0>")
	)
	(segment
		(start 38.531038 -254.97409)
		(end 34.663634 -254.97409)
		(width 0.18288)
		(layer "In11.Cu")
		(net "M_D_CPU1_CLK_DP<0>")
	)
	(segment
		(start 19.784314 -259.366766)
		(end 20.889214 -259.366766)
		(width 0.20066)
		(layer "F.Cu")
		(net "M_D_CPU1_CLK_DN<1>")
	)
	(segment
		(start 99.892866 -250.155964)
		(end 99.892612 -250.15571)
		(width 0.20066)
		(layer "F.Cu")
		(net "M_D_CPU1_CLK_DN<1>")
	)
	(segment
		(start 99.892612 -250.15571)
		(end 99.892612 -249.620024)
		(width 0.20066)
		(layer "F.Cu")
		(net "M_D_CPU1_CLK_DN<1>")
	)
	(segment
		(start 49.317402 -256.087372)
		(end 46.509432 -256.087372)
		(width 0.18288)
		(layer "In11.Cu")
		(net "M_D_CPU1_CLK_DN<1>")
	)
	(segment
		(start 65.004188 -254.72009)
		(end 64.511174 -254.924306)
		(width 0.18288)
		(layer "In11.Cu")
		(net "M_D_CPU1_CLK_DN<1>")
	)
	(segment
		(start 72.385428 -253.871222)
		(end 71.852028 -253.871222)
		(width 0.18288)
		(layer "In11.Cu")
		(net "M_D_CPU1_CLK_DN<1>")
	)
	(segment
		(start 98.641662 -252.103128)
		(end 86.382352 -252.103128)
		(width 0.18288)
		(layer "In11.Cu")
		(net "M_D_CPU1_CLK_DN<1>")
	)
	(segment
		(start 71.074788 -253.871222)
		(end 70.541388 -253.871222)
		(width 0.18288)
		(layer "In11.Cu")
		(net "M_D_CPU1_CLK_DN<1>")
	)
	(segment
		(start 70.419468 -253.749302)
		(end 69.886068 -253.749302)
		(width 0.18288)
		(layer "In11.Cu")
		(net "M_D_CPU1_CLK_DN<1>")
	)
	(segment
		(start 99.892612 -249.620024)
		(end 100.22713 -249.954542)
		(width 0.18288)
		(layer "In11.Cu")
		(net "M_D_CPU1_CLK_DN<1>")
	)
	(segment
		(start 53.92547 -256.191512)
		(end 53.481986 -255.748028)
		(width 0.18288)
		(layer "In11.Cu")
		(net "M_D_CPU1_CLK_DN<1>")
	)
	(segment
		(start 26.590498 -256.234946)
		(end 23.350474 -256.234946)
		(width 0.18288)
		(layer "In11.Cu")
		(net "M_D_CPU1_CLK_DN<1>")
	)
	(segment
		(start 64.511174 -254.924306)
		(end 64.445134 -255.083818)
		(width 0.18288)
		(layer "In11.Cu")
		(net "M_D_CPU1_CLK_DN<1>")
	)
	(segment
		(start 62.195964 -255.445514)
		(end 62.074044 -255.323594)
		(width 0.18288)
		(layer "In11.Cu")
		(net "M_D_CPU1_CLK_DN<1>")
	)
	(segment
		(start 81.642204 -252.92177)
		(end 79.65567 -254.908558)
		(width 0.18288)
		(layer "In11.Cu")
		(net "M_D_CPU1_CLK_DN<1>")
	)
	(segment
		(start 73.040748 -253.749302)
		(end 72.507348 -253.749302)
		(width 0.18288)
		(layer "In11.Cu")
		(net "M_D_CPU1_CLK_DN<1>")
	)
	(segment
		(start 27.087322 -255.738122)
		(end 26.590498 -256.234946)
		(width 0.18288)
		(layer "In11.Cu")
		(net "M_D_CPU1_CLK_DN<1>")
	)
	(segment
		(start 68.453508 -253.871222)
		(end 67.369944 -253.871222)
		(width 0.18288)
		(layer "In11.Cu")
		(net "M_D_CPU1_CLK_DN<1>")
	)
	(segment
		(start 86.126574 -252.358906)
		(end 83.001612 -252.358906)
		(width 0.18288)
		(layer "In11.Cu")
		(net "M_D_CPU1_CLK_DN<1>")
	)
	(segment
		(start 66.545206 -254.081026)
		(end 66.052192 -254.285242)
		(width 0.18288)
		(layer "In11.Cu")
		(net "M_D_CPU1_CLK_DN<1>")
	)
	(segment
		(start 72.507348 -253.749302)
		(end 72.385428 -253.871222)
		(width 0.18288)
		(layer "In11.Cu")
		(net "M_D_CPU1_CLK_DN<1>")
	)
	(segment
		(start 60.108084 -255.445514)
		(end 57.790334 -255.445514)
		(width 0.18288)
		(layer "In11.Cu")
		(net "M_D_CPU1_CLK_DN<1>")
	)
	(segment
		(start 73.696068 -253.871222)
		(end 73.162668 -253.871222)
		(width 0.18288)
		(layer "In11.Cu")
		(net "M_D_CPU1_CLK_DN<1>")
	)
	(segment
		(start 64.445134 -255.083818)
		(end 63.572898 -255.445514)
		(width 0.18288)
		(layer "In11.Cu")
		(net "M_D_CPU1_CLK_DN<1>")
	)
	(segment
		(start 82.126328 -252.721364)
		(end 81.642204 -252.92177)
		(width 0.18288)
		(layer "In11.Cu")
		(net "M_D_CPU1_CLK_DN<1>")
	)
	(segment
		(start 74.473308 -253.871222)
		(end 74.351388 -253.749302)
		(width 0.18288)
		(layer "In11.Cu")
		(net "M_D_CPU1_CLK_DN<1>")
	)
	(segment
		(start 57.790334 -255.445514)
		(end 57.044336 -256.191512)
		(width 0.18288)
		(layer "In11.Cu")
		(net "M_D_CPU1_CLK_DN<1>")
	)
	(segment
		(start 41.70934 -256.17424)
		(end 38.988238 -256.17424)
		(width 0.18288)
		(layer "In11.Cu")
		(net "M_D_CPU1_CLK_DN<1>")
	)
	(segment
		(start 66.052192 -254.285242)
		(end 65.986152 -254.444754)
		(width 0.18288)
		(layer "In11.Cu")
		(net "M_D_CPU1_CLK_DN<1>")
	)
	(segment
		(start 71.196708 -253.749302)
		(end 71.074788 -253.871222)
		(width 0.18288)
		(layer "In11.Cu")
		(net "M_D_CPU1_CLK_DN<1>")
	)
	(segment
		(start 21.363686 -258.221734)
		(end 21.363686 -259.17779)
		(width 0.18288)
		(layer "In11.Cu")
		(net "M_D_CPU1_CLK_DN<1>")
	)
	(segment
		(start 23.350474 -256.234946)
		(end 21.363686 -258.221734)
		(width 0.18288)
		(layer "In11.Cu")
		(net "M_D_CPU1_CLK_DN<1>")
	)
	(segment
		(start 69.764148 -253.871222)
		(end 69.230748 -253.871222)
		(width 0.18288)
		(layer "In11.Cu")
		(net "M_D_CPU1_CLK_DN<1>")
	)
	(segment
		(start 83.001612 -252.358906)
		(end 82.126328 -252.721364)
		(width 0.18288)
		(layer "In11.Cu")
		(net "M_D_CPU1_CLK_DN<1>")
	)
	(segment
		(start 66.704464 -254.147066)
		(end 66.545206 -254.081026)
		(width 0.18288)
		(layer "In11.Cu")
		(net "M_D_CPU1_CLK_DN<1>")
	)
	(segment
		(start 60.230004 -255.323594)
		(end 60.108084 -255.445514)
		(width 0.18288)
		(layer "In11.Cu")
		(net "M_D_CPU1_CLK_DN<1>")
	)
	(segment
		(start 79.65567 -254.908558)
		(end 76.044044 -254.908558)
		(width 0.18288)
		(layer "In11.Cu")
		(net "M_D_CPU1_CLK_DN<1>")
	)
	(segment
		(start 68.575428 -253.749302)
		(end 68.453508 -253.871222)
		(width 0.18288)
		(layer "In11.Cu")
		(net "M_D_CPU1_CLK_DN<1>")
	)
	(segment
		(start 69.108828 -253.749302)
		(end 68.575428 -253.749302)
		(width 0.18288)
		(layer "In11.Cu")
		(net "M_D_CPU1_CLK_DN<1>")
	)
	(segment
		(start 61.540644 -255.323594)
		(end 61.418724 -255.445514)
		(width 0.18288)
		(layer "In11.Cu")
		(net "M_D_CPU1_CLK_DN<1>")
	)
	(segment
		(start 34.734246 -255.66243)
		(end 34.278824 -256.117852)
		(width 0.18288)
		(layer "In11.Cu")
		(net "M_D_CPU1_CLK_DN<1>")
	)
	(segment
		(start 75.006708 -253.871222)
		(end 74.473308 -253.871222)
		(width 0.18288)
		(layer "In11.Cu")
		(net "M_D_CPU1_CLK_DN<1>")
	)
	(segment
		(start 86.382352 -252.103128)
		(end 86.126574 -252.358906)
		(width 0.18288)
		(layer "In11.Cu")
		(net "M_D_CPU1_CLK_DN<1>")
	)
	(segment
		(start 46.113446 -255.691386)
		(end 42.192194 -255.691386)
		(width 0.18288)
		(layer "In11.Cu")
		(net "M_D_CPU1_CLK_DN<1>")
	)
	(segment
		(start 76.044044 -254.908558)
		(end 75.006708 -253.871222)
		(width 0.18288)
		(layer "In11.Cu")
		(net "M_D_CPU1_CLK_DN<1>")
	)
	(segment
		(start 65.986152 -254.444754)
		(end 65.163446 -254.785876)
		(width 0.18288)
		(layer "In11.Cu")
		(net "M_D_CPU1_CLK_DN<1>")
	)
	(segment
		(start 21.175472 -259.366004)
		(end 20.889976 -259.366004)
		(width 0.18288)
		(layer "In11.Cu")
		(net "M_D_CPU1_CLK_DN<1>")
	)
	(segment
		(start 67.369944 -253.871222)
		(end 66.704464 -254.147066)
		(width 0.18288)
		(layer "In11.Cu")
		(net "M_D_CPU1_CLK_DN<1>")
	)
	(segment
		(start 70.541388 -253.871222)
		(end 70.419468 -253.749302)
		(width 0.18288)
		(layer "In11.Cu")
		(net "M_D_CPU1_CLK_DN<1>")
	)
	(segment
		(start 46.509432 -256.087372)
		(end 46.113446 -255.691386)
		(width 0.18288)
		(layer "In11.Cu")
		(net "M_D_CPU1_CLK_DN<1>")
	)
	(segment
		(start 21.363686 -259.17779)
		(end 21.175472 -259.366004)
		(width 0.18288)
		(layer "In11.Cu")
		(net "M_D_CPU1_CLK_DN<1>")
	)
	(segment
		(start 31.38551 -256.117852)
		(end 31.00578 -255.738122)
		(width 0.18288)
		(layer "In11.Cu")
		(net "M_D_CPU1_CLK_DN<1>")
	)
	(segment
		(start 53.481986 -255.748028)
		(end 49.656746 -255.748028)
		(width 0.18288)
		(layer "In11.Cu")
		(net "M_D_CPU1_CLK_DN<1>")
	)
	(segment
		(start 63.572898 -255.445514)
		(end 62.195964 -255.445514)
		(width 0.18288)
		(layer "In11.Cu")
		(net "M_D_CPU1_CLK_DN<1>")
	)
	(segment
		(start 100.22713 -249.954542)
		(end 100.22713 -250.51766)
		(width 0.18288)
		(layer "In11.Cu")
		(net "M_D_CPU1_CLK_DN<1>")
	)
	(segment
		(start 60.885324 -255.445514)
		(end 60.763404 -255.323594)
		(width 0.18288)
		(layer "In11.Cu")
		(net "M_D_CPU1_CLK_DN<1>")
	)
	(segment
		(start 73.817988 -253.749302)
		(end 73.696068 -253.871222)
		(width 0.18288)
		(layer "In11.Cu")
		(net "M_D_CPU1_CLK_DN<1>")
	)
	(segment
		(start 38.476428 -255.66243)
		(end 34.734246 -255.66243)
		(width 0.18288)
		(layer "In11.Cu")
		(net "M_D_CPU1_CLK_DN<1>")
	)
	(segment
		(start 71.730108 -253.749302)
		(end 71.196708 -253.749302)
		(width 0.18288)
		(layer "In11.Cu")
		(net "M_D_CPU1_CLK_DN<1>")
	)
	(segment
		(start 57.044336 -256.191512)
		(end 53.92547 -256.191512)
		(width 0.18288)
		(layer "In11.Cu")
		(net "M_D_CPU1_CLK_DN<1>")
	)
	(segment
		(start 49.656746 -255.748028)
		(end 49.317402 -256.087372)
		(width 0.18288)
		(layer "In11.Cu")
		(net "M_D_CPU1_CLK_DN<1>")
	)
	(segment
		(start 20.889976 -259.366004)
		(end 20.889214 -259.366766)
		(width 0.18288)
		(layer "In11.Cu")
		(net "M_D_CPU1_CLK_DN<1>")
	)
	(segment
		(start 31.00578 -255.738122)
		(end 27.087322 -255.738122)
		(width 0.18288)
		(layer "In11.Cu")
		(net "M_D_CPU1_CLK_DN<1>")
	)
	(segment
		(start 100.22713 -250.51766)
		(end 98.641662 -252.103128)
		(width 0.18288)
		(layer "In11.Cu")
		(net "M_D_CPU1_CLK_DN<1>")
	)
	(segment
		(start 73.162668 -253.871222)
		(end 73.040748 -253.749302)
		(width 0.18288)
		(layer "In11.Cu")
		(net "M_D_CPU1_CLK_DN<1>")
	)
	(segment
		(start 42.192194 -255.691386)
		(end 41.70934 -256.17424)
		(width 0.18288)
		(layer "In11.Cu")
		(net "M_D_CPU1_CLK_DN<1>")
	)
	(segment
		(start 69.886068 -253.749302)
		(end 69.764148 -253.871222)
		(width 0.18288)
		(layer "In11.Cu")
		(net "M_D_CPU1_CLK_DN<1>")
	)
	(segment
		(start 61.418724 -255.445514)
		(end 60.885324 -255.445514)
		(width 0.18288)
		(layer "In11.Cu")
		(net "M_D_CPU1_CLK_DN<1>")
	)
	(segment
		(start 38.988238 -256.17424)
		(end 38.476428 -255.66243)
		(width 0.18288)
		(layer "In11.Cu")
		(net "M_D_CPU1_CLK_DN<1>")
	)
	(segment
		(start 34.278824 -256.117852)
		(end 31.38551 -256.117852)
		(width 0.18288)
		(layer "In11.Cu")
		(net "M_D_CPU1_CLK_DN<1>")
	)
	(segment
		(start 74.351388 -253.749302)
		(end 73.817988 -253.749302)
		(width 0.18288)
		(layer "In11.Cu")
		(net "M_D_CPU1_CLK_DN<1>")
	)
	(segment
		(start 69.230748 -253.871222)
		(end 69.108828 -253.749302)
		(width 0.18288)
		(layer "In11.Cu")
		(net "M_D_CPU1_CLK_DN<1>")
	)
	(segment
		(start 62.074044 -255.323594)
		(end 61.540644 -255.323594)
		(width 0.18288)
		(layer "In11.Cu")
		(net "M_D_CPU1_CLK_DN<1>")
	)
	(segment
		(start 71.852028 -253.871222)
		(end 71.730108 -253.749302)
		(width 0.18288)
		(layer "In11.Cu")
		(net "M_D_CPU1_CLK_DN<1>")
	)
	(segment
		(start 65.163446 -254.785876)
		(end 65.004188 -254.72009)
		(width 0.18288)
		(layer "In11.Cu")
		(net "M_D_CPU1_CLK_DN<1>")
	)
	(segment
		(start 60.763404 -255.323594)
		(end 60.230004 -255.323594)
		(width 0.18288)
		(layer "In11.Cu")
		(net "M_D_CPU1_CLK_DN<1>")
	)
	(segment
		(start 98.013266 -249.620278)
		(end 98.013012 -249.620024)
		(width 0.20066)
		(layer "F.Cu")
		(net "M_D_CPU1_CLK_DN<0>")
	)
	(segment
		(start 12.240514 -259.366766)
		(end 13.345414 -259.366766)
		(width 0.20066)
		(layer "F.Cu")
		(net "M_D_CPU1_CLK_DN<0>")
	)
	(segment
		(start 98.013266 -250.155964)
		(end 98.013266 -249.620278)
		(width 0.20066)
		(layer "F.Cu")
		(net "M_D_CPU1_CLK_DN<0>")
	)
	(segment
		(start 14.785086 -259.251196)
		(end 13.829284 -259.648198)
		(width 0.18288)
		(layer "In11.Cu")
		(net "M_D_CPU1_CLK_DN<0>")
	)
	(segment
		(start 63.95974 -251.794772)
		(end 63.1698 -251.794772)
		(width 0.18288)
		(layer "In11.Cu")
		(net "M_D_CPU1_CLK_DN<0>")
	)
	(segment
		(start 98.027744 -249.620024)
		(end 98.335338 -249.927618)
		(width 0.18288)
		(layer "In11.Cu")
		(net "M_D_CPU1_CLK_DN<0>")
	)
	(segment
		(start 22.3012 -255.396746)
		(end 20.101306 -257.59664)
		(width 0.18288)
		(layer "In11.Cu")
		(net "M_D_CPU1_CLK_DN<0>")
	)
	(segment
		(start 59.72937 -253.242064)
		(end 59.66968 -253.403608)
		(width 0.18288)
		(layer "In11.Cu")
		(net "M_D_CPU1_CLK_DN<0>")
	)
	(segment
		(start 65.438274 -252.097794)
		(end 65.343278 -251.953776)
		(width 0.18288)
		(layer "In11.Cu")
		(net "M_D_CPU1_CLK_DN<0>")
	)
	(segment
		(start 31.73603 -255.288542)
		(end 31.128716 -254.681228)
		(width 0.18288)
		(layer "In11.Cu")
		(net "M_D_CPU1_CLK_DN<0>")
	)
	(segment
		(start 61.720984 -252.460506)
		(end 61.559186 -252.400816)
		(width 0.18288)
		(layer "In11.Cu")
		(net "M_D_CPU1_CLK_DN<0>")
	)
	(segment
		(start 64.820546 -251.846588)
		(end 64.676528 -251.941584)
		(width 0.18288)
		(layer "In11.Cu")
		(net "M_D_CPU1_CLK_DN<0>")
	)
	(segment
		(start 65.343278 -251.953776)
		(end 64.820546 -251.846588)
		(width 0.18288)
		(layer "In11.Cu")
		(net "M_D_CPU1_CLK_DN<0>")
	)
	(segment
		(start 68.877688 -252.51029)
		(end 68.755768 -252.63221)
		(width 0.18288)
		(layer "In11.Cu")
		(net "M_D_CPU1_CLK_DN<0>")
	)
	(segment
		(start 66.761868 -252.369066)
		(end 66.667126 -252.225048)
		(width 0.18288)
		(layer "In11.Cu")
		(net "M_D_CPU1_CLK_DN<0>")
	)
	(segment
		(start 31.128716 -254.681228)
		(end 26.953972 -254.681228)
		(width 0.18288)
		(layer "In11.Cu")
		(net "M_D_CPU1_CLK_DN<0>")
	)
	(segment
		(start 13.626846 -259.648198)
		(end 13.345414 -259.366766)
		(width 0.18288)
		(layer "In11.Cu")
		(net "M_D_CPU1_CLK_DN<0>")
	)
	(segment
		(start 20.101306 -257.59664)
		(end 16.770858 -257.59664)
		(width 0.18288)
		(layer "In11.Cu")
		(net "M_D_CPU1_CLK_DN<0>")
	)
	(segment
		(start 46.47184 -254.860298)
		(end 41.817798 -254.860298)
		(width 0.18288)
		(layer "In11.Cu")
		(net "M_D_CPU1_CLK_DN<0>")
	)
	(segment
		(start 54.240684 -255.320546)
		(end 53.840126 -254.919988)
		(width 0.18288)
		(layer "In11.Cu")
		(net "M_D_CPU1_CLK_DN<0>")
	)
	(segment
		(start 59.185048 -253.626366)
		(end 57.793128 -253.626366)
		(width 0.18288)
		(layer "In11.Cu")
		(net "M_D_CPU1_CLK_DN<0>")
	)
	(segment
		(start 48.969676 -255.259078)
		(end 46.87062 -255.259078)
		(width 0.18288)
		(layer "In11.Cu")
		(net "M_D_CPU1_CLK_DN<0>")
	)
	(segment
		(start 79.238856 -254.235712)
		(end 76.602844 -254.235712)
		(width 0.18288)
		(layer "In11.Cu")
		(net "M_D_CPU1_CLK_DN<0>")
	)
	(segment
		(start 98.335338 -249.927618)
		(end 98.335338 -250.574302)
		(width 0.18288)
		(layer "In11.Cu")
		(net "M_D_CPU1_CLK_DN<0>")
	)
	(segment
		(start 63.1698 -251.794772)
		(end 61.720984 -252.460506)
		(width 0.18288)
		(layer "In11.Cu")
		(net "M_D_CPU1_CLK_DN<0>")
	)
	(segment
		(start 85.906102 -251.234956)
		(end 85.671152 -251.469906)
		(width 0.18288)
		(layer "In11.Cu")
		(net "M_D_CPU1_CLK_DN<0>")
	)
	(segment
		(start 34.53511 -254.66421)
		(end 33.910778 -255.288542)
		(width 0.18288)
		(layer "In11.Cu")
		(net "M_D_CPU1_CLK_DN<0>")
	)
	(segment
		(start 60.376054 -253.078742)
		(end 60.214256 -253.019052)
		(width 0.18288)
		(layer "In11.Cu")
		(net "M_D_CPU1_CLK_DN<0>")
	)
	(segment
		(start 41.35755 -255.320546)
		(end 39.315898 -255.320546)
		(width 0.18288)
		(layer "In11.Cu")
		(net "M_D_CPU1_CLK_DN<0>")
	)
	(segment
		(start 66.667126 -252.225048)
		(end 66.14414 -252.11786)
		(width 0.18288)
		(layer "In11.Cu")
		(net "M_D_CPU1_CLK_DN<0>")
	)
	(segment
		(start 26.953972 -254.681228)
		(end 26.238454 -255.396746)
		(width 0.18288)
		(layer "In11.Cu")
		(net "M_D_CPU1_CLK_DN<0>")
	)
	(segment
		(start 61.559186 -252.400816)
		(end 61.0743 -252.623828)
		(width 0.18288)
		(layer "In11.Cu")
		(net "M_D_CPU1_CLK_DN<0>")
	)
	(segment
		(start 38.659562 -254.66421)
		(end 34.53511 -254.66421)
		(width 0.18288)
		(layer "In11.Cu")
		(net "M_D_CPU1_CLK_DN<0>")
	)
	(segment
		(start 66.000376 -252.212856)
		(end 65.438274 -252.097794)
		(width 0.18288)
		(layer "In11.Cu")
		(net "M_D_CPU1_CLK_DN<0>")
	)
	(segment
		(start 69.411088 -252.51029)
		(end 68.877688 -252.51029)
		(width 0.18288)
		(layer "In11.Cu")
		(net "M_D_CPU1_CLK_DN<0>")
	)
	(segment
		(start 64.676528 -251.941584)
		(end 63.95974 -251.794772)
		(width 0.18288)
		(layer "In11.Cu")
		(net "M_D_CPU1_CLK_DN<0>")
	)
	(segment
		(start 82.004662 -251.469906)
		(end 79.238856 -254.235712)
		(width 0.18288)
		(layer "In11.Cu")
		(net "M_D_CPU1_CLK_DN<0>")
	)
	(segment
		(start 60.214256 -253.019052)
		(end 59.72937 -253.242064)
		(width 0.18288)
		(layer "In11.Cu")
		(net "M_D_CPU1_CLK_DN<0>")
	)
	(segment
		(start 49.308766 -254.919988)
		(end 48.969676 -255.259078)
		(width 0.18288)
		(layer "In11.Cu")
		(net "M_D_CPU1_CLK_DN<0>")
	)
	(segment
		(start 76.602844 -254.235712)
		(end 74.999342 -252.63221)
		(width 0.18288)
		(layer "In11.Cu")
		(net "M_D_CPU1_CLK_DN<0>")
	)
	(segment
		(start 57.793128 -253.626366)
		(end 57.187846 -254.231648)
		(width 0.18288)
		(layer "In11.Cu")
		(net "M_D_CPU1_CLK_DN<0>")
	)
	(segment
		(start 41.817798 -254.860298)
		(end 41.35755 -255.320546)
		(width 0.18288)
		(layer "In11.Cu")
		(net "M_D_CPU1_CLK_DN<0>")
	)
	(segment
		(start 61.0743 -252.623828)
		(end 61.014356 -252.785372)
		(width 0.18288)
		(layer "In11.Cu")
		(net "M_D_CPU1_CLK_DN<0>")
	)
	(segment
		(start 39.315898 -255.320546)
		(end 38.659562 -254.66421)
		(width 0.18288)
		(layer "In11.Cu")
		(net "M_D_CPU1_CLK_DN<0>")
	)
	(segment
		(start 33.910778 -255.288542)
		(end 31.73603 -255.288542)
		(width 0.18288)
		(layer "In11.Cu")
		(net "M_D_CPU1_CLK_DN<0>")
	)
	(segment
		(start 85.671152 -251.469906)
		(end 82.004662 -251.469906)
		(width 0.18288)
		(layer "In11.Cu")
		(net "M_D_CPU1_CLK_DN<0>")
	)
	(segment
		(start 46.87062 -255.259078)
		(end 46.47184 -254.860298)
		(width 0.18288)
		(layer "In11.Cu")
		(net "M_D_CPU1_CLK_DN<0>")
	)
	(segment
		(start 56.632094 -255.320546)
		(end 54.240684 -255.320546)
		(width 0.18288)
		(layer "In11.Cu")
		(net "M_D_CPU1_CLK_DN<0>")
	)
	(segment
		(start 59.66968 -253.403608)
		(end 59.185048 -253.626366)
		(width 0.18288)
		(layer "In11.Cu")
		(net "M_D_CPU1_CLK_DN<0>")
	)
	(segment
		(start 98.013012 -249.620024)
		(end 98.027744 -249.620024)
		(width 0.18288)
		(layer "In11.Cu")
		(net "M_D_CPU1_CLK_DN<0>")
	)
	(segment
		(start 74.999342 -252.63221)
		(end 69.533008 -252.63221)
		(width 0.18288)
		(layer "In11.Cu")
		(net "M_D_CPU1_CLK_DN<0>")
	)
	(segment
		(start 13.829284 -259.648198)
		(end 13.626846 -259.648198)
		(width 0.18288)
		(layer "In11.Cu")
		(net "M_D_CPU1_CLK_DN<0>")
	)
	(segment
		(start 68.755768 -252.63221)
		(end 68.045838 -252.63221)
		(width 0.18288)
		(layer "In11.Cu")
		(net "M_D_CPU1_CLK_DN<0>")
	)
	(segment
		(start 16.205454 -257.830828)
		(end 14.785086 -259.251196)
		(width 0.18288)
		(layer "In11.Cu")
		(net "M_D_CPU1_CLK_DN<0>")
	)
	(segment
		(start 68.045838 -252.63221)
		(end 66.761868 -252.369066)
		(width 0.18288)
		(layer "In11.Cu")
		(net "M_D_CPU1_CLK_DN<0>")
	)
	(segment
		(start 16.770858 -257.59664)
		(end 16.205454 -257.830828)
		(width 0.18288)
		(layer "In11.Cu")
		(net "M_D_CPU1_CLK_DN<0>")
	)
	(segment
		(start 57.187846 -254.764794)
		(end 56.632094 -255.320546)
		(width 0.18288)
		(layer "In11.Cu")
		(net "M_D_CPU1_CLK_DN<0>")
	)
	(segment
		(start 97.674684 -251.234956)
		(end 85.906102 -251.234956)
		(width 0.18288)
		(layer "In11.Cu")
		(net "M_D_CPU1_CLK_DN<0>")
	)
	(segment
		(start 57.187846 -254.231648)
		(end 57.187846 -254.764794)
		(width 0.18288)
		(layer "In11.Cu")
		(net "M_D_CPU1_CLK_DN<0>")
	)
	(segment
		(start 66.14414 -252.11786)
		(end 66.000376 -252.212856)
		(width 0.18288)
		(layer "In11.Cu")
		(net "M_D_CPU1_CLK_DN<0>")
	)
	(segment
		(start 69.533008 -252.63221)
		(end 69.411088 -252.51029)
		(width 0.18288)
		(layer "In11.Cu")
		(net "M_D_CPU1_CLK_DN<0>")
	)
	(segment
		(start 98.335338 -250.574302)
		(end 97.674684 -251.234956)
		(width 0.18288)
		(layer "In11.Cu")
		(net "M_D_CPU1_CLK_DN<0>")
	)
	(segment
		(start 61.014356 -252.785372)
		(end 60.376054 -253.078742)
		(width 0.18288)
		(layer "In11.Cu")
		(net "M_D_CPU1_CLK_DN<0>")
	)
	(segment
		(start 53.840126 -254.919988)
		(end 49.308766 -254.919988)
		(width 0.18288)
		(layer "In11.Cu")
		(net "M_D_CPU1_CLK_DN<0>")
	)
	(segment
		(start 26.238454 -255.396746)
		(end 22.3012 -255.396746)
		(width 0.18288)
		(layer "In11.Cu")
		(net "M_D_CPU1_CLK_DN<0>")
	)
	(segment
		(start 13.441426 -269.141702)
		(end 13.643356 -269.141702)
		(width 0.20066)
		(layer "F.Cu")
		(net "M_D_CPU1_ALERT_N")
	)
	(segment
		(start 10.344912 -269.295372)
		(end 10.507472 -269.132812)
		(width 0.20066)
		(layer "F.Cu")
		(net "M_D_CPU1_ALERT_N")
	)
	(segment
		(start 14.068298 -269.566644)
		(end 15.684246 -269.566644)
		(width 0.20066)
		(layer "F.Cu")
		(net "M_D_CPU1_ALERT_N")
	)
	(segment
		(start 8.140446 -269.566644)
		(end 9.474708 -269.566644)
		(width 0.20066)
		(layer "F.Cu")
		(net "M_D_CPU1_ALERT_N")
	)
	(segment
		(start 102.352094 -253.919482)
		(end 102.352348 -253.919736)
		(width 0.20066)
		(layer "F.Cu")
		(net "M_D_CPU1_ALERT_N")
	)
	(segment
		(start 11.11631 -269.132812)
		(end 11.1252 -269.141702)
		(width 0.1016)
		(layer "F.Cu")
		(net "M_D_CPU1_ALERT_N")
	)
	(segment
		(start 9.686036 -269.777972)
		(end 10.19048 -269.777972)
		(width 0.20066)
		(layer "F.Cu")
		(net "M_D_CPU1_ALERT_N")
	)
	(segment
		(start 13.643356 -269.141702)
		(end 14.068298 -269.566644)
		(width 0.20066)
		(layer "F.Cu")
		(net "M_D_CPU1_ALERT_N")
	)
	(segment
		(start 11.1252 -269.141702)
		(end 13.410184 -269.141702)
		(width 0.1016)
		(layer "F.Cu")
		(net "M_D_CPU1_ALERT_N")
	)
	(segment
		(start 9.474708 -269.566644)
		(end 9.686036 -269.777972)
		(width 0.20066)
		(layer "F.Cu")
		(net "M_D_CPU1_ALERT_N")
	)
	(segment
		(start 16.789146 -269.566644)
		(end 15.684246 -269.566644)
		(width 0.20066)
		(layer "F.Cu")
		(net "M_D_CPU1_ALERT_N")
	)
	(segment
		(start 13.410184 -269.141702)
		(end 13.441426 -269.141702)
		(width 0.101854)
		(layer "F.Cu")
		(net "M_D_CPU1_ALERT_N")
	)
	(segment
		(start 10.19048 -269.777972)
		(end 10.344912 -269.62354)
		(width 0.20066)
		(layer "F.Cu")
		(net "M_D_CPU1_ALERT_N")
	)
	(segment
		(start 102.352094 -253.383796)
		(end 102.352094 -253.919482)
		(width 0.20066)
		(layer "F.Cu")
		(net "M_D_CPU1_ALERT_N")
	)
	(segment
		(start 10.507472 -269.132812)
		(end 11.11631 -269.132812)
		(width 0.20066)
		(layer "F.Cu")
		(net "M_D_CPU1_ALERT_N")
	)
	(segment
		(start 10.344912 -269.62354)
		(end 10.344912 -269.295372)
		(width 0.20066)
		(layer "F.Cu")
		(net "M_D_CPU1_ALERT_N")
	)
	(via
		(at 102.352348 -253.919736)
		(size 0.4572)
		(drill 0.2032)
		(layers "F.Cu" "B.Cu")
		(net "M_D_CPU1_ALERT_N")
	)
	(via
		(at 16.789146 -269.566644)
		(size 0.4572)
		(drill 0.2032)
		(layers "F.Cu" "B.Cu")
		(net "M_D_CPU1_ALERT_N")
	)
	(segment
		(start 27.2034 -267.417042)
		(end 25.851358 -267.417042)
		(width 0.18288)
		(layer "In11.Cu")
		(net "M_D_CPU1_ALERT_N")
	)
	(segment
		(start 96.491806 -260.01599)
		(end 96.478344 -260.023864)
		(width 0.18288)
		(layer "In11.Cu")
		(net "M_D_CPU1_ALERT_N")
	)
	(segment
		(start 91.779344 -260.023864)
		(end 91.769692 -260.029452)
		(width 0.18288)
		(layer "In11.Cu")
		(net "M_D_CPU1_ALERT_N")
	)
	(segment
		(start 36.664392 -266.469876)
		(end 36.541202 -266.593066)
		(width 0.18288)
		(layer "In11.Cu")
		(net "M_D_CPU1_ALERT_N")
	)
	(segment
		(start 66.482976 -263.826752)
		(end 65.967864 -263.826752)
		(width 0.18288)
		(layer "In11.Cu")
		(net "M_D_CPU1_ALERT_N")
	)
	(segment
		(start 22.571202 -269.727426)
		(end 21.704046 -269.727426)
		(width 0.18288)
		(layer "In11.Cu")
		(net "M_D_CPU1_ALERT_N")
	)
	(segment
		(start 97.840546 -260.106414)
		(end 97.760536 -260.060186)
		(width 0.088646)
		(layer "In11.Cu")
		(net "M_D_CPU1_ALERT_N")
	)
	(segment
		(start 30.174692 -266.427204)
		(end 29.284422 -266.427204)
		(width 0.18288)
		(layer "In11.Cu")
		(net "M_D_CPU1_ALERT_N")
	)
	(segment
		(start 94.128844 -260.023864)
		(end 94.115382 -260.01599)
		(width 0.18288)
		(layer "In11.Cu")
		(net "M_D_CPU1_ALERT_N")
	)
	(segment
		(start 45.044614 -266.43457)
		(end 44.144946 -266.43457)
		(width 0.18288)
		(layer "In11.Cu")
		(net "M_D_CPU1_ALERT_N")
	)
	(segment
		(start 94.612206 -260.01599)
		(end 94.598744 -260.023864)
		(width 0.18288)
		(layer "In11.Cu")
		(net "M_D_CPU1_ALERT_N")
	)
	(segment
		(start 29.284422 -266.427204)
		(end 29.1211 -266.590526)
		(width 0.18288)
		(layer "In11.Cu")
		(net "M_D_CPU1_ALERT_N")
	)
	(segment
		(start 51.528726 -266.400026)
		(end 51.337718 -266.591034)
		(width 0.18288)
		(layer "In11.Cu")
		(net "M_D_CPU1_ALERT_N")
	)
	(segment
		(start 61.063124 -265.752326)
		(end 61.021722 -265.793728)
		(width 0.18288)
		(layer "In11.Cu")
		(net "M_D_CPU1_ALERT_N")
	)
	(segment
		(start 20.93468 -268.95806)
		(end 18.022316 -268.95806)
		(width 0.18288)
		(layer "In11.Cu")
		(net "M_D_CPU1_ALERT_N")
	)
	(segment
		(start 32.396938 -266.591288)
		(end 30.338776 -266.591288)
		(width 0.18288)
		(layer "In11.Cu")
		(net "M_D_CPU1_ALERT_N")
	)
	(segment
		(start 29.1211 -266.590526)
		(end 28.029916 -266.590526)
		(width 0.18288)
		(layer "In11.Cu")
		(net "M_D_CPU1_ALERT_N")
	)
	(segment
		(start 102.352348 -253.919736)
		(end 102.329996 -254.808482)
		(width 0.088646)
		(layer "In11.Cu")
		(net "M_D_CPU1_ALERT_N")
	)
	(segment
		(start 21.704046 -269.727426)
		(end 20.93468 -268.95806)
		(width 0.18288)
		(layer "In11.Cu")
		(net "M_D_CPU1_ALERT_N")
	)
	(segment
		(start 25.851358 -267.417042)
		(end 24.976074 -268.292326)
		(width 0.18288)
		(layer "In11.Cu")
		(net "M_D_CPU1_ALERT_N")
	)
	(segment
		(start 73.783698 -259.75691)
		(end 71.998078 -261.54253)
		(width 0.18288)
		(layer "In11.Cu")
		(net "M_D_CPU1_ALERT_N")
	)
	(segment
		(start 90.369644 -260.023864)
		(end 90.356182 -260.01599)
		(width 0.18288)
		(layer "In11.Cu")
		(net "M_D_CPU1_ALERT_N")
	)
	(segment
		(start 98.405696 -260.106414)
		(end 98.395282 -260.11251)
		(width 0.088646)
		(layer "In11.Cu")
		(net "M_D_CPU1_ALERT_N")
	)
	(segment
		(start 93.189044 -260.023864)
		(end 93.175582 -260.01599)
		(width 0.18288)
		(layer "In11.Cu")
		(net "M_D_CPU1_ALERT_N")
	)
	(segment
		(start 91.309698 -260.023864)
		(end 91.300046 -260.018276)
		(width 0.18288)
		(layer "In11.Cu")
		(net "M_D_CPU1_ALERT_N")
	)
	(segment
		(start 48.530764 -266.592304)
		(end 45.202348 -266.592304)
		(width 0.18288)
		(layer "In11.Cu")
		(net "M_D_CPU1_ALERT_N")
	)
	(segment
		(start 102.329996 -254.808482)
		(end 102.214426 -255.065784)
		(width 0.088646)
		(layer "In11.Cu")
		(net "M_D_CPU1_ALERT_N")
	)
	(segment
		(start 61.021722 -265.793728)
		(end 59.14009 -265.793728)
		(width 0.18288)
		(layer "In11.Cu")
		(net "M_D_CPU1_ALERT_N")
	)
	(segment
		(start 65.967864 -263.826752)
		(end 64.87033 -264.924286)
		(width 0.18288)
		(layer "In11.Cu")
		(net "M_D_CPU1_ALERT_N")
	)
	(segment
		(start 40.157146 -266.469876)
		(end 36.664392 -266.469876)
		(width 0.18288)
		(layer "In11.Cu")
		(net "M_D_CPU1_ALERT_N")
	)
	(segment
		(start 24.006302 -268.292326)
		(end 22.571202 -269.727426)
		(width 0.18288)
		(layer "In11.Cu")
		(net "M_D_CPU1_ALERT_N")
	)
	(segment
		(start 41.94429 -266.593574)
		(end 41.811702 -266.726162)
		(width 0.18288)
		(layer "In11.Cu")
		(net "M_D_CPU1_ALERT_N")
	)
	(segment
		(start 49.060862 -266.69492)
		(end 48.63338 -266.69492)
		(width 0.18288)
		(layer "In11.Cu")
		(net "M_D_CPU1_ALERT_N")
	)
	(segment
		(start 51.337718 -266.591034)
		(end 49.164748 -266.591034)
		(width 0.18288)
		(layer "In11.Cu")
		(net "M_D_CPU1_ALERT_N")
	)
	(segment
		(start 71.998078 -261.54253)
		(end 66.482976 -263.826752)
		(width 0.18288)
		(layer "In11.Cu")
		(net "M_D_CPU1_ALERT_N")
	)
	(segment
		(start 100.24237 -260.02107)
		(end 100.237544 -260.023864)
		(width 0.088646)
		(layer "In11.Cu")
		(net "M_D_CPU1_ALERT_N")
	)
	(segment
		(start 85.670644 -260.023864)
		(end 85.090762 -260.023864)
		(width 0.18288)
		(layer "In11.Cu")
		(net "M_D_CPU1_ALERT_N")
	)
	(segment
		(start 44.144946 -266.43457)
		(end 43.985942 -266.593574)
		(width 0.18288)
		(layer "In11.Cu")
		(net "M_D_CPU1_ALERT_N")
	)
	(segment
		(start 48.63338 -266.69492)
		(end 48.530764 -266.592304)
		(width 0.18288)
		(layer "In11.Cu")
		(net "M_D_CPU1_ALERT_N")
	)
	(segment
		(start 45.202348 -266.592304)
		(end 45.044614 -266.43457)
		(width 0.18288)
		(layer "In11.Cu")
		(net "M_D_CPU1_ALERT_N")
	)
	(segment
		(start 85.090762 -260.023864)
		(end 85.023198 -259.9563)
		(width 0.18288)
		(layer "In11.Cu")
		(net "M_D_CPU1_ALERT_N")
	)
	(segment
		(start 96.008444 -260.023864)
		(end 95.994982 -260.01599)
		(width 0.18288)
		(layer "In11.Cu")
		(net "M_D_CPU1_ALERT_N")
	)
	(segment
		(start 28.029916 -266.590526)
		(end 27.2034 -267.417042)
		(width 0.18288)
		(layer "In11.Cu")
		(net "M_D_CPU1_ALERT_N")
	)
	(segment
		(start 101.177344 -257.582162)
		(end 101.18217 -257.584956)
		(width 0.088646)
		(layer "In11.Cu")
		(net "M_D_CPU1_ALERT_N")
	)
	(segment
		(start 59.14009 -265.793728)
		(end 59.026806 -265.680444)
		(width 0.18288)
		(layer "In11.Cu")
		(net "M_D_CPU1_ALERT_N")
	)
	(segment
		(start 83.914742 -259.75691)
		(end 73.783698 -259.75691)
		(width 0.18288)
		(layer "In11.Cu")
		(net "M_D_CPU1_ALERT_N")
	)
	(segment
		(start 97.183194 -260.05155)
		(end 97.051368 -260.05155)
		(width 0.18288)
		(layer "In11.Cu")
		(net "M_D_CPU1_ALERT_N")
	)
	(segment
		(start 30.338776 -266.591288)
		(end 30.174692 -266.427204)
		(width 0.18288)
		(layer "In11.Cu")
		(net "M_D_CPU1_ALERT_N")
	)
	(segment
		(start 100.718112 -259.203698)
		(end 100.707444 -259.210048)
		(width 0.088646)
		(layer "In11.Cu")
		(net "M_D_CPU1_ALERT_N")
	)
	(segment
		(start 55.379112 -266.400026)
		(end 51.528726 -266.400026)
		(width 0.18288)
		(layer "In11.Cu")
		(net "M_D_CPU1_ALERT_N")
	)
	(segment
		(start 49.164748 -266.591034)
		(end 49.060862 -266.69492)
		(width 0.18288)
		(layer "In11.Cu")
		(net "M_D_CPU1_ALERT_N")
	)
	(segment
		(start 64.87033 -264.924286)
		(end 63.531496 -264.924286)
		(width 0.18288)
		(layer "In11.Cu")
		(net "M_D_CPU1_ALERT_N")
	)
	(segment
		(start 41.811702 -266.726162)
		(end 40.413432 -266.726162)
		(width 0.18288)
		(layer "In11.Cu")
		(net "M_D_CPU1_ALERT_N")
	)
	(segment
		(start 35.183572 -266.593066)
		(end 34.501582 -267.275056)
		(width 0.18288)
		(layer "In11.Cu")
		(net "M_D_CPU1_ALERT_N")
	)
	(segment
		(start 101.182424 -256.765552)
		(end 101.172772 -256.77114)
		(width 0.088646)
		(layer "In11.Cu")
		(net "M_D_CPU1_ALERT_N")
	)
	(segment
		(start 89.429844 -260.023864)
		(end 89.416382 -260.01599)
		(width 0.18288)
		(layer "In11.Cu")
		(net "M_D_CPU1_ALERT_N")
	)
	(segment
		(start 101.412548 -256.34696)
		(end 101.412548 -256.361438)
		(width 0.088646)
		(layer "In11.Cu")
		(net "M_D_CPU1_ALERT_N")
	)
	(segment
		(start 63.531496 -264.924286)
		(end 62.703456 -265.752326)
		(width 0.18288)
		(layer "In11.Cu")
		(net "M_D_CPU1_ALERT_N")
	)
	(segment
		(start 84.114132 -259.9563)
		(end 83.914742 -259.75691)
		(width 0.18288)
		(layer "In11.Cu")
		(net "M_D_CPU1_ALERT_N")
	)
	(segment
		(start 101.657912 -255.94818)
		(end 101.647244 -255.95453)
		(width 0.088646)
		(layer "In11.Cu")
		(net "M_D_CPU1_ALERT_N")
	)
	(segment
		(start 40.413432 -266.726162)
		(end 40.157146 -266.469876)
		(width 0.18288)
		(layer "In11.Cu")
		(net "M_D_CPU1_ALERT_N")
	)
	(segment
		(start 100.237544 -260.023864)
		(end 100.094796 -260.10616)
		(width 0.088646)
		(layer "In11.Cu")
		(net "M_D_CPU1_ALERT_N")
	)
	(segment
		(start 33.080706 -267.275056)
		(end 32.396938 -266.591288)
		(width 0.18288)
		(layer "In11.Cu")
		(net "M_D_CPU1_ALERT_N")
	)
	(segment
		(start 100.707444 -259.210048)
		(end 100.702618 -259.212842)
		(width 0.088646)
		(layer "In11.Cu")
		(net "M_D_CPU1_ALERT_N")
	)
	(segment
		(start 59.026806 -265.680444)
		(end 56.098694 -265.680444)
		(width 0.18288)
		(layer "In11.Cu")
		(net "M_D_CPU1_ALERT_N")
	)
	(segment
		(start 100.942648 -258.788662)
		(end 100.942648 -258.80314)
		(width 0.088646)
		(layer "In11.Cu")
		(net "M_D_CPU1_ALERT_N")
	)
	(segment
		(start 97.728278 -260.05155)
		(end 97.183194 -260.05155)
		(width 0.088646)
		(layer "In11.Cu")
		(net "M_D_CPU1_ALERT_N")
	)
	(segment
		(start 85.023198 -259.9563)
		(end 84.114132 -259.9563)
		(width 0.18288)
		(layer "In11.Cu")
		(net "M_D_CPU1_ALERT_N")
	)
	(segment
		(start 100.942648 -257.175254)
		(end 100.942648 -257.184906)
		(width 0.088646)
		(layer "In11.Cu")
		(net "M_D_CPU1_ALERT_N")
	)
	(segment
		(start 62.703456 -265.752326)
		(end 61.063124 -265.752326)
		(width 0.18288)
		(layer "In11.Cu")
		(net "M_D_CPU1_ALERT_N")
	)
	(segment
		(start 56.098694 -265.680444)
		(end 55.379112 -266.400026)
		(width 0.18288)
		(layer "In11.Cu")
		(net "M_D_CPU1_ALERT_N")
	)
	(segment
		(start 43.985942 -266.593574)
		(end 41.94429 -266.593574)
		(width 0.18288)
		(layer "In11.Cu")
		(net "M_D_CPU1_ALERT_N")
	)
	(segment
		(start 98.790506 -260.11251)
		(end 98.780092 -260.106414)
		(width 0.088646)
		(layer "In11.Cu")
		(net "M_D_CPU1_ALERT_N")
	)
	(segment
		(start 17.413732 -269.566644)
		(end 16.789146 -269.566644)
		(width 0.18288)
		(layer "In11.Cu")
		(net "M_D_CPU1_ALERT_N")
	)
	(segment
		(start 34.501582 -267.275056)
		(end 33.080706 -267.275056)
		(width 0.18288)
		(layer "In11.Cu")
		(net "M_D_CPU1_ALERT_N")
	)
	(segment
		(start 101.412294 -257.98907)
		(end 101.412294 -258.002532)
		(width 0.088646)
		(layer "In11.Cu")
		(net "M_D_CPU1_ALERT_N")
	)
	(segment
		(start 101.882448 -255.53035)
		(end 101.882448 -255.547622)
		(width 0.088646)
		(layer "In11.Cu")
		(net "M_D_CPU1_ALERT_N")
	)
	(segment
		(start 36.541202 -266.593066)
		(end 35.183572 -266.593066)
		(width 0.18288)
		(layer "In11.Cu")
		(net "M_D_CPU1_ALERT_N")
	)
	(segment
		(start 18.022316 -268.95806)
		(end 17.413732 -269.566644)
		(width 0.18288)
		(layer "In11.Cu")
		(net "M_D_CPU1_ALERT_N")
	)
	(segment
		(start 24.976074 -268.292326)
		(end 24.006302 -268.292326)
		(width 0.18288)
		(layer "In11.Cu")
		(net "M_D_CPU1_ALERT_N")
	)
	(arc
		(start 101.412294 -258.002532)
		(mid 101.346071 -258.229969)
		(end 101.177344 -258.396232)
		(width 0.088646)
		(layer "In11.Cu")
		(net "M_D_CPU1_ALERT_N")
	)
	(arc
		(start 93.175582 -260.01599)
		(mid 92.946329 -259.960746)
		(end 92.719144 -260.023864)
		(width 0.18288)
		(layer "In11.Cu")
		(net "M_D_CPU1_ALERT_N")
	)
	(arc
		(start 88.490044 -260.023864)
		(mid 88.255094 -259.960904)
		(end 88.020144 -260.023864)
		(width 0.18288)
		(layer "In11.Cu")
		(net "M_D_CPU1_ALERT_N")
	)
	(arc
		(start 101.172772 -256.77114)
		(mid 101.004216 -256.942734)
		(end 100.942648 -257.175254)
		(width 0.088646)
		(layer "In11.Cu")
		(net "M_D_CPU1_ALERT_N")
	)
	(arc
		(start 95.538544 -260.023864)
		(mid 95.303594 -260.086824)
		(end 95.068644 -260.023864)
		(width 0.18288)
		(layer "In11.Cu")
		(net "M_D_CPU1_ALERT_N")
	)
	(arc
		(start 90.356182 -260.01599)
		(mid 90.126929 -259.960746)
		(end 89.899744 -260.023864)
		(width 0.18288)
		(layer "In11.Cu")
		(net "M_D_CPU1_ALERT_N")
	)
	(arc
		(start 96.478344 -260.023864)
		(mid 96.243394 -260.086824)
		(end 96.008444 -260.023864)
		(width 0.18288)
		(layer "In11.Cu")
		(net "M_D_CPU1_ALERT_N")
	)
	(arc
		(start 86.140544 -260.023864)
		(mid 85.905594 -260.086824)
		(end 85.670644 -260.023864)
		(width 0.18288)
		(layer "In11.Cu")
		(net "M_D_CPU1_ALERT_N")
	)
	(arc
		(start 102.117144 -255.14046)
		(mid 101.949489 -255.305122)
		(end 101.882448 -255.53035)
		(width 0.088646)
		(layer "In11.Cu")
		(net "M_D_CPU1_ALERT_N")
	)
	(arc
		(start 93.658944 -260.023864)
		(mid 93.423994 -260.086824)
		(end 93.189044 -260.023864)
		(width 0.18288)
		(layer "In11.Cu")
		(net "M_D_CPU1_ALERT_N")
	)
	(arc
		(start 102.214426 -255.065784)
		(mid 102.168226 -255.106301)
		(end 102.117144 -255.14046)
		(width 0.088646)
		(layer "In11.Cu")
		(net "M_D_CPU1_ALERT_N")
	)
	(arc
		(start 98.395282 -260.11251)
		(mid 98.117104 -260.182233)
		(end 97.840546 -260.106414)
		(width 0.088646)
		(layer "In11.Cu")
		(net "M_D_CPU1_ALERT_N")
	)
	(arc
		(start 91.769692 -260.029452)
		(mid 91.538961 -260.086813)
		(end 91.309698 -260.023864)
		(width 0.18288)
		(layer "In11.Cu")
		(net "M_D_CPU1_ALERT_N")
	)
	(arc
		(start 90.839544 -260.023864)
		(mid 90.604594 -260.086824)
		(end 90.369644 -260.023864)
		(width 0.18288)
		(layer "In11.Cu")
		(net "M_D_CPU1_ALERT_N")
	)
	(arc
		(start 95.068644 -260.023864)
		(mid 94.841457 -259.960846)
		(end 94.612206 -260.01599)
		(width 0.18288)
		(layer "In11.Cu")
		(net "M_D_CPU1_ALERT_N")
	)
	(arc
		(start 94.115382 -260.01599)
		(mid 93.886129 -259.960746)
		(end 93.658944 -260.023864)
		(width 0.18288)
		(layer "In11.Cu")
		(net "M_D_CPU1_ALERT_N")
	)
	(arc
		(start 99.34575 -260.106414)
		(mid 99.068937 -260.182284)
		(end 98.790506 -260.11251)
		(width 0.088646)
		(layer "In11.Cu")
		(net "M_D_CPU1_ALERT_N")
	)
	(arc
		(start 88.959944 -260.023864)
		(mid 88.724994 -260.086824)
		(end 88.490044 -260.023864)
		(width 0.18288)
		(layer "In11.Cu")
		(net "M_D_CPU1_ALERT_N")
	)
	(arc
		(start 101.177344 -258.396232)
		(mid 101.00904 -258.561972)
		(end 100.942648 -258.788662)
		(width 0.088646)
		(layer "In11.Cu")
		(net "M_D_CPU1_ALERT_N")
	)
	(arc
		(start 91.300046 -260.018276)
		(mid 91.069061 -259.960793)
		(end 90.839544 -260.023864)
		(width 0.18288)
		(layer "In11.Cu")
		(net "M_D_CPU1_ALERT_N")
	)
	(arc
		(start 88.020144 -260.023864)
		(mid 87.785194 -260.086824)
		(end 87.550244 -260.023864)
		(width 0.18288)
		(layer "In11.Cu")
		(net "M_D_CPU1_ALERT_N")
	)
	(arc
		(start 87.080344 -260.023864)
		(mid 86.845394 -260.086824)
		(end 86.610444 -260.023864)
		(width 0.18288)
		(layer "In11.Cu")
		(net "M_D_CPU1_ALERT_N")
	)
	(arc
		(start 101.412548 -256.361438)
		(mid 101.350985 -256.593961)
		(end 101.182424 -256.765552)
		(width 0.088646)
		(layer "In11.Cu")
		(net "M_D_CPU1_ALERT_N")
	)
	(arc
		(start 99.720146 -260.106414)
		(mid 99.532948 -260.056271)
		(end 99.34575 -260.106414)
		(width 0.088646)
		(layer "In11.Cu")
		(net "M_D_CPU1_ALERT_N")
	)
	(arc
		(start 94.598744 -260.023864)
		(mid 94.363794 -260.086824)
		(end 94.128844 -260.023864)
		(width 0.18288)
		(layer "In11.Cu")
		(net "M_D_CPU1_ALERT_N")
	)
	(arc
		(start 98.780092 -260.106414)
		(mid 98.592894 -260.056271)
		(end 98.405696 -260.106414)
		(width 0.088646)
		(layer "In11.Cu")
		(net "M_D_CPU1_ALERT_N")
	)
	(arc
		(start 92.249244 -260.023864)
		(mid 92.014294 -259.960904)
		(end 91.779344 -260.023864)
		(width 0.18288)
		(layer "In11.Cu")
		(net "M_D_CPU1_ALERT_N")
	)
	(arc
		(start 100.702618 -259.212842)
		(mid 100.534062 -259.384436)
		(end 100.472494 -259.616956)
		(width 0.088646)
		(layer "In11.Cu")
		(net "M_D_CPU1_ALERT_N")
	)
	(arc
		(start 87.550244 -260.023864)
		(mid 87.315294 -259.960904)
		(end 87.080344 -260.023864)
		(width 0.18288)
		(layer "In11.Cu")
		(net "M_D_CPU1_ALERT_N")
	)
	(arc
		(start 96.948244 -260.023864)
		(mid 96.721057 -259.960846)
		(end 96.491806 -260.01599)
		(width 0.18288)
		(layer "In11.Cu")
		(net "M_D_CPU1_ALERT_N")
	)
	(arc
		(start 101.647244 -255.95453)
		(mid 101.47894 -256.12027)
		(end 101.412548 -256.34696)
		(width 0.088646)
		(layer "In11.Cu")
		(net "M_D_CPU1_ALERT_N")
	)
	(arc
		(start 89.899744 -260.023864)
		(mid 89.664794 -260.086824)
		(end 89.429844 -260.023864)
		(width 0.18288)
		(layer "In11.Cu")
		(net "M_D_CPU1_ALERT_N")
	)
	(arc
		(start 97.760536 -260.060186)
		(mid 97.74498 -260.053716)
		(end 97.728278 -260.05155)
		(width 0.088646)
		(layer "In11.Cu")
		(net "M_D_CPU1_ALERT_N")
	)
	(arc
		(start 100.472494 -259.616956)
		(mid 100.410931 -259.849479)
		(end 100.24237 -260.02107)
		(width 0.088646)
		(layer "In11.Cu")
		(net "M_D_CPU1_ALERT_N")
	)
	(arc
		(start 100.094796 -260.10616)
		(mid 99.907517 -260.15643)
		(end 99.720146 -260.106414)
		(width 0.088646)
		(layer "In11.Cu")
		(net "M_D_CPU1_ALERT_N")
	)
	(arc
		(start 92.719144 -260.023864)
		(mid 92.484194 -260.086824)
		(end 92.249244 -260.023864)
		(width 0.18288)
		(layer "In11.Cu")
		(net "M_D_CPU1_ALERT_N")
	)
	(arc
		(start 89.416382 -260.01599)
		(mid 89.187129 -259.960746)
		(end 88.959944 -260.023864)
		(width 0.18288)
		(layer "In11.Cu")
		(net "M_D_CPU1_ALERT_N")
	)
	(arc
		(start 95.994982 -260.01599)
		(mid 95.765729 -259.960746)
		(end 95.538544 -260.023864)
		(width 0.18288)
		(layer "In11.Cu")
		(net "M_D_CPU1_ALERT_N")
	)
	(arc
		(start 101.882448 -255.547622)
		(mid 101.822493 -255.777232)
		(end 101.657912 -255.94818)
		(width 0.088646)
		(layer "In11.Cu")
		(net "M_D_CPU1_ALERT_N")
	)
	(arc
		(start 86.610444 -260.023864)
		(mid 86.375494 -259.960904)
		(end 86.140544 -260.023864)
		(width 0.18288)
		(layer "In11.Cu")
		(net "M_D_CPU1_ALERT_N")
	)
	(arc
		(start 100.942648 -258.80314)
		(mid 100.882693 -259.03275)
		(end 100.718112 -259.203698)
		(width 0.088646)
		(layer "In11.Cu")
		(net "M_D_CPU1_ALERT_N")
	)
	(arc
		(start 100.942648 -257.184906)
		(mid 101.007891 -257.414318)
		(end 101.177344 -257.582162)
		(width 0.088646)
		(layer "In11.Cu")
		(net "M_D_CPU1_ALERT_N")
	)
	(arc
		(start 97.051368 -260.05155)
		(mid 96.997974 -260.044519)
		(end 96.948244 -260.023864)
		(width 0.18288)
		(layer "In11.Cu")
		(net "M_D_CPU1_ALERT_N")
	)
	(arc
		(start 101.18217 -257.584956)
		(mid 101.350726 -257.75655)
		(end 101.412294 -257.98907)
		(width 0.088646)
		(layer "In11.Cu")
		(net "M_D_CPU1_ALERT_N")
	)
	(segment
		(start 345.123516 -255.825498)
		(end 345.123516 -256.361184)
		(width 0.20066)
		(layer "F.Cu")
		(net "M_D_CPU0_SB_RSP<1>")
	)
	(segment
		(start 264.729214 -243.216684)
		(end 263.624314 -243.216684)
		(width 0.20066)
		(layer "F.Cu")
		(net "M_D_CPU0_SB_RSP<1>")
	)
	(segment
		(start 345.123516 -256.361184)
		(end 345.123262 -256.361438)
		(width 0.20066)
		(layer "F.Cu")
		(net "M_D_CPU0_SB_RSP<1>")
	)
	(segment
		(start 270.812514 -256.258822)
		(end 270.629634 -256.075942)
		(width 0.18288)
		(layer "In6.Cu")
		(net "M_D_CPU0_SB_RSP<1>")
	)
	(segment
		(start 271.137634 -256.258822)
		(end 270.812514 -256.258822)
		(width 0.18288)
		(layer "In6.Cu")
		(net "M_D_CPU0_SB_RSP<1>")
	)
	(segment
		(start 263.920732 -245.124986)
		(end 264.55497 -244.490748)
		(width 0.18288)
		(layer "In6.Cu")
		(net "M_D_CPU0_SB_RSP<1>")
	)
	(segment
		(start 329.073002 -255.343406)
		(end 329.060048 -255.338072)
		(width 0.18288)
		(layer "In6.Cu")
		(net "M_D_CPU0_SB_RSP<1>")
	)
	(segment
		(start 270.121634 -255.559306)
		(end 269.938754 -255.742186)
		(width 0.18288)
		(layer "In6.Cu")
		(net "M_D_CPU0_SB_RSP<1>")
	)
	(segment
		(start 272.702274 -255.742186)
		(end 272.702274 -256.075942)
		(width 0.18288)
		(layer "In6.Cu")
		(net "M_D_CPU0_SB_RSP<1>")
	)
	(segment
		(start 268.145768 -255.451102)
		(end 264.538968 -255.451102)
		(width 0.18288)
		(layer "In6.Cu")
		(net "M_D_CPU0_SB_RSP<1>")
	)
	(segment
		(start 272.194274 -256.258822)
		(end 272.011394 -256.075942)
		(width 0.18288)
		(layer "In6.Cu")
		(net "M_D_CPU0_SB_RSP<1>")
	)
	(segment
		(start 272.885154 -255.559306)
		(end 272.702274 -255.742186)
		(width 0.18288)
		(layer "In6.Cu")
		(net "M_D_CPU0_SB_RSP<1>")
	)
	(segment
		(start 273.210274 -255.559306)
		(end 272.885154 -255.559306)
		(width 0.18288)
		(layer "In6.Cu")
		(net "M_D_CPU0_SB_RSP<1>")
	)
	(segment
		(start 269.755874 -256.258822)
		(end 268.953488 -256.258822)
		(width 0.18288)
		(layer "In6.Cu")
		(net "M_D_CPU0_SB_RSP<1>")
	)
	(segment
		(start 268.953488 -256.258822)
		(end 268.145768 -255.451102)
		(width 0.18288)
		(layer "In6.Cu")
		(net "M_D_CPU0_SB_RSP<1>")
	)
	(segment
		(start 270.446754 -255.559306)
		(end 270.121634 -255.559306)
		(width 0.18288)
		(layer "In6.Cu")
		(net "M_D_CPU0_SB_RSP<1>")
	)
	(segment
		(start 272.011394 -256.075942)
		(end 272.011394 -255.742186)
		(width 0.18288)
		(layer "In6.Cu")
		(net "M_D_CPU0_SB_RSP<1>")
	)
	(segment
		(start 273.393154 -256.075942)
		(end 273.393154 -255.742186)
		(width 0.18288)
		(layer "In6.Cu")
		(net "M_D_CPU0_SB_RSP<1>")
	)
	(segment
		(start 326.836786 -256.258822)
		(end 319.069466 -256.258822)
		(width 0.18288)
		(layer "In6.Cu")
		(net "M_D_CPU0_SB_RSP<1>")
	)
	(segment
		(start 329.060048 -255.338072)
		(end 326.966072 -256.205228)
		(width 0.18288)
		(layer "In6.Cu")
		(net "M_D_CPU0_SB_RSP<1>")
	)
	(segment
		(start 265.095736 -244.490748)
		(end 265.284458 -244.302026)
		(width 0.18288)
		(layer "In6.Cu")
		(net "M_D_CPU0_SB_RSP<1>")
	)
	(segment
		(start 339.212428 -255.865884)
		(end 339.202014 -255.87198)
		(width 0.088646)
		(layer "In6.Cu")
		(net "M_D_CPU0_SB_RSP<1>")
	)
	(segment
		(start 265.284458 -243.771928)
		(end 264.729214 -243.216684)
		(width 0.18288)
		(layer "In6.Cu")
		(net "M_D_CPU0_SB_RSP<1>")
	)
	(segment
		(start 270.629634 -256.075942)
		(end 270.629634 -255.742186)
		(width 0.18288)
		(layer "In6.Cu")
		(net "M_D_CPU0_SB_RSP<1>")
	)
	(segment
		(start 319.069466 -256.258822)
		(end 319.069212 -256.258568)
		(width 0.18288)
		(layer "In6.Cu")
		(net "M_D_CPU0_SB_RSP<1>")
	)
	(segment
		(start 314.41517 -256.258822)
		(end 273.576034 -256.258822)
		(width 0.18288)
		(layer "In6.Cu")
		(net "M_D_CPU0_SB_RSP<1>")
	)
	(segment
		(start 265.284458 -244.302026)
		(end 265.284458 -243.771928)
		(width 0.18288)
		(layer "In6.Cu")
		(net "M_D_CPU0_SB_RSP<1>")
	)
	(segment
		(start 329.09891 -255.332738)
		(end 329.073002 -255.343406)
		(width 0.18288)
		(layer "In6.Cu")
		(net "M_D_CPU0_SB_RSP<1>")
	)
	(segment
		(start 331.966062 -255.796288)
		(end 331.828648 -255.796288)
		(width 0.088646)
		(layer "In6.Cu")
		(net "M_D_CPU0_SB_RSP<1>")
	)
	(segment
		(start 273.393154 -255.742186)
		(end 273.210274 -255.559306)
		(width 0.18288)
		(layer "In6.Cu")
		(net "M_D_CPU0_SB_RSP<1>")
	)
	(segment
		(start 336.392774 -255.865884)
		(end 336.38236 -255.87198)
		(width 0.088646)
		(layer "In6.Cu")
		(net "M_D_CPU0_SB_RSP<1>")
	)
	(segment
		(start 343.915746 -255.863344)
		(end 343.901014 -255.87198)
		(width 0.088646)
		(layer "In6.Cu")
		(net "M_D_CPU0_SB_RSP<1>")
	)
	(segment
		(start 272.702274 -256.075942)
		(end 272.519394 -256.258822)
		(width 0.18288)
		(layer "In6.Cu")
		(net "M_D_CPU0_SB_RSP<1>")
	)
	(segment
		(start 271.503394 -255.559306)
		(end 271.320514 -255.742186)
		(width 0.18288)
		(layer "In6.Cu")
		(net "M_D_CPU0_SB_RSP<1>")
	)
	(segment
		(start 269.938754 -256.075942)
		(end 269.755874 -256.258822)
		(width 0.18288)
		(layer "In6.Cu")
		(net "M_D_CPU0_SB_RSP<1>")
	)
	(segment
		(start 342.975946 -255.863344)
		(end 342.961214 -255.87198)
		(width 0.088646)
		(layer "In6.Cu")
		(net "M_D_CPU0_SB_RSP<1>")
	)
	(segment
		(start 331.028802 -255.332738)
		(end 329.09891 -255.332738)
		(width 0.18288)
		(layer "In6.Cu")
		(net "M_D_CPU0_SB_RSP<1>")
	)
	(segment
		(start 272.519394 -256.258822)
		(end 272.194274 -256.258822)
		(width 0.18288)
		(layer "In6.Cu")
		(net "M_D_CPU0_SB_RSP<1>")
	)
	(segment
		(start 269.938754 -255.742186)
		(end 269.938754 -256.075942)
		(width 0.18288)
		(layer "In6.Cu")
		(net "M_D_CPU0_SB_RSP<1>")
	)
	(segment
		(start 272.011394 -255.742186)
		(end 271.828514 -255.559306)
		(width 0.18288)
		(layer "In6.Cu")
		(net "M_D_CPU0_SB_RSP<1>")
	)
	(segment
		(start 326.869552 -256.24536)
		(end 326.836786 -256.258822)
		(width 0.18288)
		(layer "In6.Cu")
		(net "M_D_CPU0_SB_RSP<1>")
	)
	(segment
		(start 319.069212 -256.258568)
		(end 314.415424 -256.258568)
		(width 0.18288)
		(layer "In6.Cu")
		(net "M_D_CPU0_SB_RSP<1>")
	)
	(segment
		(start 271.828514 -255.559306)
		(end 271.503394 -255.559306)
		(width 0.18288)
		(layer "In6.Cu")
		(net "M_D_CPU0_SB_RSP<1>")
	)
	(segment
		(start 271.320514 -255.742186)
		(end 271.320514 -256.075942)
		(width 0.18288)
		(layer "In6.Cu")
		(net "M_D_CPU0_SB_RSP<1>")
	)
	(segment
		(start 263.920732 -254.832866)
		(end 263.920732 -245.124986)
		(width 0.18288)
		(layer "In6.Cu")
		(net "M_D_CPU0_SB_RSP<1>")
	)
	(segment
		(start 264.55497 -244.490748)
		(end 265.095736 -244.490748)
		(width 0.18288)
		(layer "In6.Cu")
		(net "M_D_CPU0_SB_RSP<1>")
	)
	(segment
		(start 340.151974 -255.865884)
		(end 340.14156 -255.87198)
		(width 0.088646)
		(layer "In6.Cu")
		(net "M_D_CPU0_SB_RSP<1>")
	)
	(segment
		(start 341.096346 -255.863344)
		(end 341.081614 -255.87198)
		(width 0.088646)
		(layer "In6.Cu")
		(net "M_D_CPU0_SB_RSP<1>")
	)
	(segment
		(start 326.966072 -256.205228)
		(end 326.869552 -256.24536)
		(width 0.18288)
		(layer "In6.Cu")
		(net "M_D_CPU0_SB_RSP<1>")
	)
	(segment
		(start 270.629634 -255.742186)
		(end 270.446754 -255.559306)
		(width 0.18288)
		(layer "In6.Cu")
		(net "M_D_CPU0_SB_RSP<1>")
	)
	(segment
		(start 338.272374 -255.865884)
		(end 338.26196 -255.87198)
		(width 0.088646)
		(layer "In6.Cu")
		(net "M_D_CPU0_SB_RSP<1>")
	)
	(segment
		(start 331.828648 -255.796288)
		(end 331.365098 -255.332738)
		(width 0.088646)
		(layer "In6.Cu")
		(net "M_D_CPU0_SB_RSP<1>")
	)
	(segment
		(start 314.415424 -256.258568)
		(end 314.41517 -256.258822)
		(width 0.18288)
		(layer "In6.Cu")
		(net "M_D_CPU0_SB_RSP<1>")
	)
	(segment
		(start 271.320514 -256.075942)
		(end 271.137634 -256.258822)
		(width 0.18288)
		(layer "In6.Cu")
		(net "M_D_CPU0_SB_RSP<1>")
	)
	(segment
		(start 345.123262 -256.361438)
		(end 344.49131 -255.890522)
		(width 0.088646)
		(layer "In6.Cu")
		(net "M_D_CPU0_SB_RSP<1>")
	)
	(segment
		(start 337.332828 -255.865884)
		(end 337.322414 -255.87198)
		(width 0.088646)
		(layer "In6.Cu")
		(net "M_D_CPU0_SB_RSP<1>")
	)
	(segment
		(start 273.576034 -256.258822)
		(end 273.393154 -256.075942)
		(width 0.18288)
		(layer "In6.Cu")
		(net "M_D_CPU0_SB_RSP<1>")
	)
	(segment
		(start 331.365098 -255.332738)
		(end 331.028802 -255.332738)
		(width 0.088646)
		(layer "In6.Cu")
		(net "M_D_CPU0_SB_RSP<1>")
	)
	(segment
		(start 264.538968 -255.451102)
		(end 263.920732 -254.832866)
		(width 0.18288)
		(layer "In6.Cu")
		(net "M_D_CPU0_SB_RSP<1>")
	)
	(arc
		(start 343.526618 -255.87198)
		(mid 343.252419 -255.796145)
		(end 342.975946 -255.863344)
		(width 0.088646)
		(layer "In6.Cu")
		(net "M_D_CPU0_SB_RSP<1>")
	)
	(arc
		(start 342.586818 -255.87198)
		(mid 342.304116 -255.796204)
		(end 342.021414 -255.87198)
		(width 0.088646)
		(layer "In6.Cu")
		(net "M_D_CPU0_SB_RSP<1>")
	)
	(arc
		(start 336.948018 -255.87198)
		(mid 336.671205 -255.79611)
		(end 336.392774 -255.865884)
		(width 0.088646)
		(layer "In6.Cu")
		(net "M_D_CPU0_SB_RSP<1>")
	)
	(arc
		(start 342.961214 -255.87198)
		(mid 342.774016 -255.922123)
		(end 342.586818 -255.87198)
		(width 0.088646)
		(layer "In6.Cu")
		(net "M_D_CPU0_SB_RSP<1>")
	)
	(arc
		(start 336.38236 -255.87198)
		(mid 336.195162 -255.922123)
		(end 336.007964 -255.87198)
		(width 0.088646)
		(layer "In6.Cu")
		(net "M_D_CPU0_SB_RSP<1>")
	)
	(arc
		(start 334.50276 -255.87198)
		(mid 334.315562 -255.922123)
		(end 334.128364 -255.87198)
		(width 0.088646)
		(layer "In6.Cu")
		(net "M_D_CPU0_SB_RSP<1>")
	)
	(arc
		(start 335.44256 -255.87198)
		(mid 335.255362 -255.922123)
		(end 335.068164 -255.87198)
		(width 0.088646)
		(layer "In6.Cu")
		(net "M_D_CPU0_SB_RSP<1>")
	)
	(arc
		(start 335.068164 -255.87198)
		(mid 334.785462 -255.796204)
		(end 334.50276 -255.87198)
		(width 0.088646)
		(layer "In6.Cu")
		(net "M_D_CPU0_SB_RSP<1>")
	)
	(arc
		(start 333.188564 -255.87198)
		(mid 332.905862 -255.796204)
		(end 332.62316 -255.87198)
		(width 0.088646)
		(layer "In6.Cu")
		(net "M_D_CPU0_SB_RSP<1>")
	)
	(arc
		(start 338.827618 -255.87198)
		(mid 338.550805 -255.79611)
		(end 338.272374 -255.865884)
		(width 0.088646)
		(layer "In6.Cu")
		(net "M_D_CPU0_SB_RSP<1>")
	)
	(arc
		(start 344.414602 -255.84531)
		(mid 344.163071 -255.796285)
		(end 343.915746 -255.863344)
		(width 0.088646)
		(layer "In6.Cu")
		(net "M_D_CPU0_SB_RSP<1>")
	)
	(arc
		(start 341.647018 -255.87198)
		(mid 341.372819 -255.796145)
		(end 341.096346 -255.863344)
		(width 0.088646)
		(layer "In6.Cu")
		(net "M_D_CPU0_SB_RSP<1>")
	)
	(arc
		(start 344.49131 -255.890522)
		(mid 344.454196 -255.865812)
		(end 344.414602 -255.84531)
		(width 0.088646)
		(layer "In6.Cu")
		(net "M_D_CPU0_SB_RSP<1>")
	)
	(arc
		(start 339.202014 -255.87198)
		(mid 339.014816 -255.922123)
		(end 338.827618 -255.87198)
		(width 0.088646)
		(layer "In6.Cu")
		(net "M_D_CPU0_SB_RSP<1>")
	)
	(arc
		(start 334.128364 -255.87198)
		(mid 333.845662 -255.796204)
		(end 333.56296 -255.87198)
		(width 0.088646)
		(layer "In6.Cu")
		(net "M_D_CPU0_SB_RSP<1>")
	)
	(arc
		(start 339.767164 -255.87198)
		(mid 339.490605 -255.796237)
		(end 339.212428 -255.865884)
		(width 0.088646)
		(layer "In6.Cu")
		(net "M_D_CPU0_SB_RSP<1>")
	)
	(arc
		(start 340.14156 -255.87198)
		(mid 339.954362 -255.922123)
		(end 339.767164 -255.87198)
		(width 0.088646)
		(layer "In6.Cu")
		(net "M_D_CPU0_SB_RSP<1>")
	)
	(arc
		(start 337.322414 -255.87198)
		(mid 337.135216 -255.922123)
		(end 336.948018 -255.87198)
		(width 0.088646)
		(layer "In6.Cu")
		(net "M_D_CPU0_SB_RSP<1>")
	)
	(arc
		(start 332.248764 -255.87198)
		(mid 332.112395 -255.815538)
		(end 331.966062 -255.796288)
		(width 0.088646)
		(layer "In6.Cu")
		(net "M_D_CPU0_SB_RSP<1>")
	)
	(arc
		(start 340.707218 -255.87198)
		(mid 340.430405 -255.79611)
		(end 340.151974 -255.865884)
		(width 0.088646)
		(layer "In6.Cu")
		(net "M_D_CPU0_SB_RSP<1>")
	)
	(arc
		(start 332.62316 -255.87198)
		(mid 332.435962 -255.922123)
		(end 332.248764 -255.87198)
		(width 0.088646)
		(layer "In6.Cu")
		(net "M_D_CPU0_SB_RSP<1>")
	)
	(arc
		(start 341.081614 -255.87198)
		(mid 340.894416 -255.922123)
		(end 340.707218 -255.87198)
		(width 0.088646)
		(layer "In6.Cu")
		(net "M_D_CPU0_SB_RSP<1>")
	)
	(arc
		(start 333.56296 -255.87198)
		(mid 333.375762 -255.922123)
		(end 333.188564 -255.87198)
		(width 0.088646)
		(layer "In6.Cu")
		(net "M_D_CPU0_SB_RSP<1>")
	)
	(arc
		(start 343.901014 -255.87198)
		(mid 343.713816 -255.922123)
		(end 343.526618 -255.87198)
		(width 0.088646)
		(layer "In6.Cu")
		(net "M_D_CPU0_SB_RSP<1>")
	)
	(arc
		(start 337.887564 -255.87198)
		(mid 337.611005 -255.796237)
		(end 337.332828 -255.865884)
		(width 0.088646)
		(layer "In6.Cu")
		(net "M_D_CPU0_SB_RSP<1>")
	)
	(arc
		(start 336.007964 -255.87198)
		(mid 335.725262 -255.796204)
		(end 335.44256 -255.87198)
		(width 0.088646)
		(layer "In6.Cu")
		(net "M_D_CPU0_SB_RSP<1>")
	)
	(arc
		(start 338.26196 -255.87198)
		(mid 338.074762 -255.922123)
		(end 337.887564 -255.87198)
		(width 0.088646)
		(layer "In6.Cu")
		(net "M_D_CPU0_SB_RSP<1>")
	)
	(arc
		(start 342.021414 -255.87198)
		(mid 341.834216 -255.922123)
		(end 341.647018 -255.87198)
		(width 0.088646)
		(layer "In6.Cu")
		(net "M_D_CPU0_SB_RSP<1>")
	)
	(segment
		(start 344.653362 -256.639314)
		(end 344.653362 -257.175)
		(width 0.20066)
		(layer "F.Cu")
		(net "M_D_CPU0_SB_RSP<0>")
	)
	(segment
		(start 344.653362 -257.175)
		(end 344.653616 -257.175254)
		(width 0.20066)
		(layer "F.Cu")
		(net "M_D_CPU0_SB_RSP<0>")
	)
	(segment
		(start 257.185414 -243.216684)
		(end 256.080514 -243.216684)
		(width 0.20066)
		(layer "F.Cu")
		(net "M_D_CPU0_SB_RSP<0>")
	)
	(segment
		(start 258.295648 -249.30608)
		(end 257.025648 -249.30608)
		(width 0.18288)
		(layer "In6.Cu")
		(net "M_D_CPU0_SB_RSP<0>")
	)
	(segment
		(start 343.996264 -256.685796)
		(end 343.981532 -256.67716)
		(width 0.088646)
		(layer "In6.Cu")
		(net "M_D_CPU0_SB_RSP<0>")
	)
	(segment
		(start 314.415424 -257.323844)
		(end 314.41517 -257.324098)
		(width 0.18288)
		(layer "In6.Cu")
		(net "M_D_CPU0_SB_RSP<0>")
	)
	(segment
		(start 319.069212 -257.323844)
		(end 314.415424 -257.323844)
		(width 0.18288)
		(layer "In6.Cu")
		(net "M_D_CPU0_SB_RSP<0>")
	)
	(segment
		(start 331.966062 -256.736342)
		(end 331.76591 -256.736342)
		(width 0.088646)
		(layer "In6.Cu")
		(net "M_D_CPU0_SB_RSP<0>")
	)
	(segment
		(start 331.028802 -256.33934)
		(end 328.892662 -256.33934)
		(width 0.18288)
		(layer "In6.Cu")
		(net "M_D_CPU0_SB_RSP<0>")
	)
	(segment
		(start 314.41517 -257.324098)
		(end 263.165844 -257.324098)
		(width 0.18288)
		(layer "In6.Cu")
		(net "M_D_CPU0_SB_RSP<0>")
	)
	(segment
		(start 260.817106 -251.827538)
		(end 258.295648 -249.30608)
		(width 0.18288)
		(layer "In6.Cu")
		(net "M_D_CPU0_SB_RSP<0>")
	)
	(segment
		(start 260.817106 -254.97536)
		(end 260.817106 -251.827538)
		(width 0.18288)
		(layer "In6.Cu")
		(net "M_D_CPU0_SB_RSP<0>")
	)
	(segment
		(start 257.376168 -245.340886)
		(end 258.029202 -244.687852)
		(width 0.18288)
		(layer "In6.Cu")
		(net "M_D_CPU0_SB_RSP<0>")
	)
	(segment
		(start 256.517648 -248.79808)
		(end 256.517648 -245.59768)
		(width 0.18288)
		(layer "In6.Cu")
		(net "M_D_CPU0_SB_RSP<0>")
	)
	(segment
		(start 344.653616 -257.175254)
		(end 344.340942 -257.175254)
		(width 0.088646)
		(layer "In6.Cu")
		(net "M_D_CPU0_SB_RSP<0>")
	)
	(segment
		(start 340.237064 -256.685796)
		(end 340.222332 -256.67716)
		(width 0.088646)
		(layer "In6.Cu")
		(net "M_D_CPU0_SB_RSP<0>")
	)
	(segment
		(start 328.892662 -256.33934)
		(end 326.515222 -257.324098)
		(width 0.18288)
		(layer "In6.Cu")
		(net "M_D_CPU0_SB_RSP<0>")
	)
	(segment
		(start 331.76591 -256.736342)
		(end 331.368908 -256.33934)
		(width 0.088646)
		(layer "In6.Cu")
		(net "M_D_CPU0_SB_RSP<0>")
	)
	(segment
		(start 331.368908 -256.33934)
		(end 331.028802 -256.33934)
		(width 0.088646)
		(layer "In6.Cu")
		(net "M_D_CPU0_SB_RSP<0>")
	)
	(segment
		(start 258.029202 -244.687852)
		(end 258.029202 -244.060472)
		(width 0.18288)
		(layer "In6.Cu")
		(net "M_D_CPU0_SB_RSP<0>")
	)
	(segment
		(start 256.774442 -245.340886)
		(end 257.376168 -245.340886)
		(width 0.18288)
		(layer "In6.Cu")
		(net "M_D_CPU0_SB_RSP<0>")
	)
	(segment
		(start 344.00236 -256.689352)
		(end 343.996264 -256.685796)
		(width 0.088646)
		(layer "In6.Cu")
		(net "M_D_CPU0_SB_RSP<0>")
	)
	(segment
		(start 258.029202 -244.060472)
		(end 257.185414 -243.216684)
		(width 0.18288)
		(layer "In6.Cu")
		(net "M_D_CPU0_SB_RSP<0>")
	)
	(segment
		(start 343.056464 -256.685796)
		(end 343.04605 -256.6797)
		(width 0.088646)
		(layer "In6.Cu")
		(net "M_D_CPU0_SB_RSP<0>")
	)
	(segment
		(start 263.165844 -257.324098)
		(end 260.817106 -254.97536)
		(width 0.18288)
		(layer "In6.Cu")
		(net "M_D_CPU0_SB_RSP<0>")
	)
	(segment
		(start 342.116918 -256.685796)
		(end 342.106504 -256.6797)
		(width 0.088646)
		(layer "In6.Cu")
		(net "M_D_CPU0_SB_RSP<0>")
	)
	(segment
		(start 319.069466 -257.324098)
		(end 319.069212 -257.323844)
		(width 0.18288)
		(layer "In6.Cu")
		(net "M_D_CPU0_SB_RSP<0>")
	)
	(segment
		(start 326.515222 -257.324098)
		(end 319.069466 -257.324098)
		(width 0.18288)
		(layer "In6.Cu")
		(net "M_D_CPU0_SB_RSP<0>")
	)
	(segment
		(start 256.517648 -245.59768)
		(end 256.774442 -245.340886)
		(width 0.18288)
		(layer "In6.Cu")
		(net "M_D_CPU0_SB_RSP<0>")
	)
	(segment
		(start 257.025648 -249.30608)
		(end 256.517648 -248.79808)
		(width 0.18288)
		(layer "In6.Cu")
		(net "M_D_CPU0_SB_RSP<0>")
	)
	(segment
		(start 344.340942 -257.175254)
		(end 344.275156 -257.109468)
		(width 0.088646)
		(layer "In6.Cu")
		(net "M_D_CPU0_SB_RSP<0>")
	)
	(arc
		(start 343.981532 -256.67716)
		(mid 343.705057 -256.60984)
		(end 343.43086 -256.685796)
		(width 0.088646)
		(layer "In6.Cu")
		(net "M_D_CPU0_SB_RSP<0>")
	)
	(arc
		(start 344.275156 -257.109468)
		(mid 344.187868 -256.867512)
		(end 344.00236 -256.689352)
		(width 0.088646)
		(layer "In6.Cu")
		(net "M_D_CPU0_SB_RSP<0>")
	)
	(arc
		(start 333.09306 -256.685796)
		(mid 332.905862 -256.735939)
		(end 332.718664 -256.685796)
		(width 0.088646)
		(layer "In6.Cu")
		(net "M_D_CPU0_SB_RSP<0>")
	)
	(arc
		(start 336.85226 -256.685796)
		(mid 336.665062 -256.735939)
		(end 336.477864 -256.685796)
		(width 0.088646)
		(layer "In6.Cu")
		(net "M_D_CPU0_SB_RSP<0>")
	)
	(arc
		(start 338.357464 -256.685796)
		(mid 338.074762 -256.61002)
		(end 337.79206 -256.685796)
		(width 0.088646)
		(layer "In6.Cu")
		(net "M_D_CPU0_SB_RSP<0>")
	)
	(arc
		(start 335.91246 -256.685796)
		(mid 335.725262 -256.735939)
		(end 335.538064 -256.685796)
		(width 0.088646)
		(layer "In6.Cu")
		(net "M_D_CPU0_SB_RSP<0>")
	)
	(arc
		(start 340.61146 -256.685796)
		(mid 340.424262 -256.735939)
		(end 340.237064 -256.685796)
		(width 0.088646)
		(layer "In6.Cu")
		(net "M_D_CPU0_SB_RSP<0>")
	)
	(arc
		(start 332.718664 -256.685796)
		(mid 332.435962 -256.61002)
		(end 332.15326 -256.685796)
		(width 0.088646)
		(layer "In6.Cu")
		(net "M_D_CPU0_SB_RSP<0>")
	)
	(arc
		(start 334.97266 -256.685796)
		(mid 334.785462 -256.735939)
		(end 334.598264 -256.685796)
		(width 0.088646)
		(layer "In6.Cu")
		(net "M_D_CPU0_SB_RSP<0>")
	)
	(arc
		(start 343.43086 -256.685796)
		(mid 343.243662 -256.735939)
		(end 343.056464 -256.685796)
		(width 0.088646)
		(layer "In6.Cu")
		(net "M_D_CPU0_SB_RSP<0>")
	)
	(arc
		(start 332.15326 -256.685796)
		(mid 332.062988 -256.723395)
		(end 331.966062 -256.736342)
		(width 0.088646)
		(layer "In6.Cu")
		(net "M_D_CPU0_SB_RSP<0>")
	)
	(arc
		(start 335.538064 -256.685796)
		(mid 335.255362 -256.61002)
		(end 334.97266 -256.685796)
		(width 0.088646)
		(layer "In6.Cu")
		(net "M_D_CPU0_SB_RSP<0>")
	)
	(arc
		(start 336.477864 -256.685796)
		(mid 336.195162 -256.61002)
		(end 335.91246 -256.685796)
		(width 0.088646)
		(layer "In6.Cu")
		(net "M_D_CPU0_SB_RSP<0>")
	)
	(arc
		(start 337.417664 -256.685796)
		(mid 337.134962 -256.61002)
		(end 336.85226 -256.685796)
		(width 0.088646)
		(layer "In6.Cu")
		(net "M_D_CPU0_SB_RSP<0>")
	)
	(arc
		(start 339.67166 -256.685796)
		(mid 339.484462 -256.735939)
		(end 339.297264 -256.685796)
		(width 0.088646)
		(layer "In6.Cu")
		(net "M_D_CPU0_SB_RSP<0>")
	)
	(arc
		(start 341.55126 -256.685796)
		(mid 341.364062 -256.735939)
		(end 341.176864 -256.685796)
		(width 0.088646)
		(layer "In6.Cu")
		(net "M_D_CPU0_SB_RSP<0>")
	)
	(arc
		(start 342.106504 -256.6797)
		(mid 341.828072 -256.609854)
		(end 341.55126 -256.685796)
		(width 0.088646)
		(layer "In6.Cu")
		(net "M_D_CPU0_SB_RSP<0>")
	)
	(arc
		(start 342.491314 -256.685796)
		(mid 342.304116 -256.735939)
		(end 342.116918 -256.685796)
		(width 0.088646)
		(layer "In6.Cu")
		(net "M_D_CPU0_SB_RSP<0>")
	)
	(arc
		(start 343.04605 -256.6797)
		(mid 342.767872 -256.609977)
		(end 342.491314 -256.685796)
		(width 0.088646)
		(layer "In6.Cu")
		(net "M_D_CPU0_SB_RSP<0>")
	)
	(arc
		(start 340.222332 -256.67716)
		(mid 339.945857 -256.60984)
		(end 339.67166 -256.685796)
		(width 0.088646)
		(layer "In6.Cu")
		(net "M_D_CPU0_SB_RSP<0>")
	)
	(arc
		(start 341.176864 -256.685796)
		(mid 340.894162 -256.61002)
		(end 340.61146 -256.685796)
		(width 0.088646)
		(layer "In6.Cu")
		(net "M_D_CPU0_SB_RSP<0>")
	)
	(arc
		(start 334.03286 -256.685796)
		(mid 333.845662 -256.735939)
		(end 333.658464 -256.685796)
		(width 0.088646)
		(layer "In6.Cu")
		(net "M_D_CPU0_SB_RSP<0>")
	)
	(arc
		(start 339.297264 -256.685796)
		(mid 339.014562 -256.61002)
		(end 338.73186 -256.685796)
		(width 0.088646)
		(layer "In6.Cu")
		(net "M_D_CPU0_SB_RSP<0>")
	)
	(arc
		(start 334.598264 -256.685796)
		(mid 334.315562 -256.61002)
		(end 334.03286 -256.685796)
		(width 0.088646)
		(layer "In6.Cu")
		(net "M_D_CPU0_SB_RSP<0>")
	)
	(arc
		(start 338.73186 -256.685796)
		(mid 338.544662 -256.735939)
		(end 338.357464 -256.685796)
		(width 0.088646)
		(layer "In6.Cu")
		(net "M_D_CPU0_SB_RSP<0>")
	)
	(arc
		(start 333.658464 -256.685796)
		(mid 333.375762 -256.61002)
		(end 333.09306 -256.685796)
		(width 0.088646)
		(layer "In6.Cu")
		(net "M_D_CPU0_SB_RSP<0>")
	)
	(arc
		(start 337.79206 -256.685796)
		(mid 337.604862 -256.735939)
		(end 337.417664 -256.685796)
		(width 0.088646)
		(layer "In6.Cu")
		(net "M_D_CPU0_SB_RSP<0>")
	)
	(segment
		(start 265.518646 -246.892572)
		(end 265.369548 -247.04167)
		(width 0.20066)
		(layer "F.Cu")
		(net "M_D_CPU0_SB_PAR")
	)
	(segment
		(start 266.700762 -246.824246)
		(end 266.25423 -246.824246)
		(width 0.20066)
		(layer "F.Cu")
		(net "M_D_CPU0_SB_PAR")
	)
	(segment
		(start 262.003794 -246.9134)
		(end 262.003794 -246.742712)
		(width 0.20066)
		(layer "F.Cu")
		(net "M_D_CPU0_SB_PAR")
	)
	(segment
		(start 266.042394 -246.61241)
		(end 265.64717 -246.61241)
		(width 0.20066)
		(layer "F.Cu")
		(net "M_D_CPU0_SB_PAR")
	)
	(segment
		(start 261.87781 -246.616728)
		(end 260.180582 -246.616728)
		(width 0.20066)
		(layer "F.Cu")
		(net "M_D_CPU0_SB_PAR")
	)
	(segment
		(start 345.48318 -247.178576)
		(end 345.483434 -247.178322)
		(width 0.20066)
		(layer "F.Cu")
		(net "M_D_CPU0_SB_PAR")
	)
	(segment
		(start 268.829282 -246.616728)
		(end 267.724382 -246.616728)
		(width 0.20066)
		(layer "F.Cu")
		(net "M_D_CPU0_SB_PAR")
	)
	(segment
		(start 265.369548 -247.04167)
		(end 264.825226 -247.04167)
		(width 0.20066)
		(layer "F.Cu")
		(net "M_D_CPU0_SB_PAR")
	)
	(segment
		(start 267.724382 -246.616728)
		(end 266.90828 -246.616728)
		(width 0.20066)
		(layer "F.Cu")
		(net "M_D_CPU0_SB_PAR")
	)
	(segment
		(start 262.514334 -247.04167)
		(end 262.50011 -247.055894)
		(width 0.101854)
		(layer "F.Cu")
		(net "M_D_CPU0_SB_PAR")
	)
	(segment
		(start 266.90828 -246.616728)
		(end 266.700762 -246.824246)
		(width 0.20066)
		(layer "F.Cu")
		(net "M_D_CPU0_SB_PAR")
	)
	(segment
		(start 264.825226 -247.04167)
		(end 262.752332 -247.04167)
		(width 0.1016)
		(layer "F.Cu")
		(net "M_D_CPU0_SB_PAR")
	)
	(segment
		(start 262.003794 -246.742712)
		(end 261.87781 -246.616728)
		(width 0.20066)
		(layer "F.Cu")
		(net "M_D_CPU0_SB_PAR")
	)
	(segment
		(start 266.25423 -246.824246)
		(end 266.042394 -246.61241)
		(width 0.20066)
		(layer "F.Cu")
		(net "M_D_CPU0_SB_PAR")
	)
	(segment
		(start 345.48318 -247.714262)
		(end 345.48318 -247.178576)
		(width 0.20066)
		(layer "F.Cu")
		(net "M_D_CPU0_SB_PAR")
	)
	(segment
		(start 262.146288 -247.055894)
		(end 262.003794 -246.9134)
		(width 0.20066)
		(layer "F.Cu")
		(net "M_D_CPU0_SB_PAR")
	)
	(segment
		(start 262.752332 -247.04167)
		(end 262.514334 -247.04167)
		(width 0.101854)
		(layer "F.Cu")
		(net "M_D_CPU0_SB_PAR")
	)
	(segment
		(start 262.50011 -247.055894)
		(end 262.146288 -247.055894)
		(width 0.20066)
		(layer "F.Cu")
		(net "M_D_CPU0_SB_PAR")
	)
	(segment
		(start 265.64717 -246.61241)
		(end 265.518646 -246.740934)
		(width 0.20066)
		(layer "F.Cu")
		(net "M_D_CPU0_SB_PAR")
	)
	(segment
		(start 265.518646 -246.740934)
		(end 265.518646 -246.892572)
		(width 0.20066)
		(layer "F.Cu")
		(net "M_D_CPU0_SB_PAR")
	)
	(segment
		(start 290.566602 -247.926352)
		(end 290.566602 -247.551448)
		(width 0.18288)
		(layer "In11.Cu")
		(net "M_D_CPU0_SB_PAR")
	)
	(segment
		(start 274.732496 -248.035826)
		(end 272.63471 -248.035826)
		(width 0.18288)
		(layer "In11.Cu")
		(net "M_D_CPU0_SB_PAR")
	)
	(segment
		(start 345.483434 -247.178322)
		(end 344.881708 -247.442482)
		(width 0.088646)
		(layer "In11.Cu")
		(net "M_D_CPU0_SB_PAR")
	)
	(segment
		(start 337.307936 -247.66778)
		(end 337.297522 -247.673876)
		(width 0.088646)
		(layer "In11.Cu")
		(net "M_D_CPU0_SB_PAR")
	)
	(segment
		(start 294.414194 -247.680226)
		(end 292.556946 -247.680226)
		(width 0.18288)
		(layer "In11.Cu")
		(net "M_D_CPU0_SB_PAR")
	)
	(segment
		(start 309.18277 -246.10695)
		(end 308.856126 -246.242586)
		(width 0.18288)
		(layer "In11.Cu")
		(net "M_D_CPU0_SB_PAR")
	)
	(segment
		(start 342.242648 -247.61571)
		(end 342.179402 -247.617996)
		(width 0.088646)
		(layer "In11.Cu")
		(net "M_D_CPU0_SB_PAR")
	)
	(segment
		(start 286.831786 -248.169684)
		(end 286.64535 -248.35612)
		(width 0.18288)
		(layer "In11.Cu")
		(net "M_D_CPU0_SB_PAR")
	)
	(segment
		(start 274.925536 -247.842786)
		(end 274.732496 -248.035826)
		(width 0.18288)
		(layer "In11.Cu")
		(net "M_D_CPU0_SB_PAR")
	)
	(segment
		(start 306.860194 -246.963946)
		(end 303.718214 -246.963946)
		(width 0.18288)
		(layer "In11.Cu")
		(net "M_D_CPU0_SB_PAR")
	)
	(segment
		(start 312.822336 -245.923054)
		(end 312.629296 -245.730014)
		(width 0.18288)
		(layer "In11.Cu")
		(net "M_D_CPU0_SB_PAR")
	)
	(segment
		(start 283.520388 -247.888252)
		(end 283.210762 -247.578626)
		(width 0.18288)
		(layer "In11.Cu")
		(net "M_D_CPU0_SB_PAR")
	)
	(segment
		(start 312.29173 -245.203726)
		(end 311.460134 -245.203726)
		(width 0.18288)
		(layer "In11.Cu")
		(net "M_D_CPU0_SB_PAR")
	)
	(segment
		(start 310.065674 -246.118126)
		(end 309.637176 -246.295672)
		(width 0.18288)
		(layer "In11.Cu")
		(net "M_D_CPU0_SB_PAR")
	)
	(segment
		(start 297.233594 -248.010426)
		(end 296.171874 -248.010426)
		(width 0.18288)
		(layer "In11.Cu")
		(net "M_D_CPU0_SB_PAR")
	)
	(segment
		(start 308.076854 -247.078246)
		(end 306.974494 -247.078246)
		(width 0.18288)
		(layer "In11.Cu")
		(net "M_D_CPU0_SB_PAR")
	)
	(segment
		(start 297.685968 -247.558052)
		(end 297.233594 -248.010426)
		(width 0.18288)
		(layer "In11.Cu")
		(net "M_D_CPU0_SB_PAR")
	)
	(segment
		(start 292.556946 -247.680226)
		(end 292.11778 -248.119392)
		(width 0.18288)
		(layer "In11.Cu")
		(net "M_D_CPU0_SB_PAR")
	)
	(segment
		(start 271.452848 -247.195848)
		(end 271.259808 -247.002808)
		(width 0.18288)
		(layer "In11.Cu")
		(net "M_D_CPU0_SB_PAR")
	)
	(segment
		(start 312.629296 -245.40083)
		(end 312.436256 -245.20779)
		(width 0.18288)
		(layer "In11.Cu")
		(net "M_D_CPU0_SB_PAR")
	)
	(segment
		(start 312.436256 -245.20779)
		(end 312.295794 -245.20779)
		(width 0.18288)
		(layer "In11.Cu")
		(net "M_D_CPU0_SB_PAR")
	)
	(segment
		(start 289.672522 -248.119392)
		(end 288.928556 -248.119392)
		(width 0.18288)
		(layer "In11.Cu")
		(net "M_D_CPU0_SB_PAR")
	)
	(segment
		(start 285.843218 -248.35612)
		(end 285.37535 -247.888252)
		(width 0.18288)
		(layer "In11.Cu")
		(net "M_D_CPU0_SB_PAR")
	)
	(segment
		(start 296.052494 -247.891046)
		(end 294.625014 -247.891046)
		(width 0.18288)
		(layer "In11.Cu")
		(net "M_D_CPU0_SB_PAR")
	)
	(segment
		(start 328.298048 -246.963946)
		(end 322.388992 -246.963946)
		(width 0.18288)
		(layer "In11.Cu")
		(net "M_D_CPU0_SB_PAR")
	)
	(segment
		(start 331.853032 -247.517158)
		(end 331.613764 -247.517158)
		(width 0.088646)
		(layer "In11.Cu")
		(net "M_D_CPU0_SB_PAR")
	)
	(segment
		(start 344.730832 -247.50268)
		(end 344.730578 -247.50268)
		(width 0.088646)
		(layer "In11.Cu")
		(net "M_D_CPU0_SB_PAR")
	)
	(segment
		(start 269.99438 -247.781826)
		(end 268.829282 -246.616728)
		(width 0.18288)
		(layer "In11.Cu")
		(net "M_D_CPU0_SB_PAR")
	)
	(segment
		(start 275.626576 -247.594882)
		(end 275.433536 -247.401842)
		(width 0.18288)
		(layer "In11.Cu")
		(net "M_D_CPU0_SB_PAR")
	)
	(segment
		(start 290.759642 -248.119392)
		(end 290.566602 -247.926352)
		(width 0.18288)
		(layer "In11.Cu")
		(net "M_D_CPU0_SB_PAR")
	)
	(segment
		(start 281.890978 -248.036842)
		(end 281.417014 -248.036842)
		(width 0.18288)
		(layer "In11.Cu")
		(net "M_D_CPU0_SB_PAR")
	)
	(segment
		(start 312.295794 -245.20779)
		(end 312.29173 -245.203726)
		(width 0.18288)
		(layer "In11.Cu")
		(net "M_D_CPU0_SB_PAR")
	)
	(segment
		(start 290.566602 -247.551448)
		(end 290.373562 -247.358408)
		(width 0.18288)
		(layer "In11.Cu")
		(net "M_D_CPU0_SB_PAR")
	)
	(segment
		(start 303.718214 -246.963946)
		(end 302.793908 -247.888252)
		(width 0.18288)
		(layer "In11.Cu")
		(net "M_D_CPU0_SB_PAR")
	)
	(segment
		(start 341.066882 -247.66778)
		(end 341.05215 -247.676416)
		(width 0.088646)
		(layer "In11.Cu")
		(net "M_D_CPU0_SB_PAR")
	)
	(segment
		(start 331.613764 -247.517158)
		(end 328.85126 -247.517158)
		(width 0.18288)
		(layer "In11.Cu")
		(net "M_D_CPU0_SB_PAR")
	)
	(segment
		(start 302.793908 -247.888252)
		(end 298.49318 -247.888252)
		(width 0.18288)
		(layer "In11.Cu")
		(net "M_D_CPU0_SB_PAR")
	)
	(segment
		(start 308.856126 -246.242586)
		(end 308.668166 -246.696738)
		(width 0.18288)
		(layer "In11.Cu")
		(net "M_D_CPU0_SB_PAR")
	)
	(segment
		(start 281.417014 -248.036842)
		(end 281.271218 -247.891046)
		(width 0.18288)
		(layer "In11.Cu")
		(net "M_D_CPU0_SB_PAR")
	)
	(segment
		(start 275.118576 -247.401842)
		(end 274.925536 -247.594882)
		(width 0.18288)
		(layer "In11.Cu")
		(net "M_D_CPU0_SB_PAR")
	)
	(segment
		(start 290.373562 -247.358408)
		(end 290.058602 -247.358408)
		(width 0.18288)
		(layer "In11.Cu")
		(net "M_D_CPU0_SB_PAR")
	)
	(segment
		(start 289.865562 -247.926352)
		(end 289.672522 -248.119392)
		(width 0.18288)
		(layer "In11.Cu")
		(net "M_D_CPU0_SB_PAR")
	)
	(segment
		(start 274.925536 -247.594882)
		(end 274.925536 -247.842786)
		(width 0.18288)
		(layer "In11.Cu")
		(net "M_D_CPU0_SB_PAR")
	)
	(segment
		(start 308.668166 -246.696738)
		(end 308.309518 -246.845582)
		(width 0.18288)
		(layer "In11.Cu")
		(net "M_D_CPU0_SB_PAR")
	)
	(segment
		(start 277.091394 -248.035826)
		(end 275.819616 -248.035826)
		(width 0.18288)
		(layer "In11.Cu")
		(net "M_D_CPU0_SB_PAR")
	)
	(segment
		(start 313.330336 -245.730014)
		(end 313.137296 -245.923054)
		(width 0.18288)
		(layer "In11.Cu")
		(net "M_D_CPU0_SB_PAR")
	)
	(segment
		(start 339.187536 -247.66778)
		(end 339.177122 -247.673876)
		(width 0.088646)
		(layer "In11.Cu")
		(net "M_D_CPU0_SB_PAR")
	)
	(segment
		(start 337.692746 -247.673876)
		(end 337.682332 -247.66778)
		(width 0.088646)
		(layer "In11.Cu")
		(net "M_D_CPU0_SB_PAR")
	)
	(segment
		(start 288.928556 -248.119392)
		(end 288.445194 -247.63603)
		(width 0.18288)
		(layer "In11.Cu")
		(net "M_D_CPU0_SB_PAR")
	)
	(segment
		(start 286.64535 -248.35612)
		(end 285.843218 -248.35612)
		(width 0.18288)
		(layer "In11.Cu")
		(net "M_D_CPU0_SB_PAR")
	)
	(segment
		(start 270.751808 -247.195848)
		(end 270.751808 -247.588786)
		(width 0.18288)
		(layer "In11.Cu")
		(net "M_D_CPU0_SB_PAR")
	)
	(segment
		(start 271.259808 -247.002808)
		(end 270.944848 -247.002808)
		(width 0.18288)
		(layer "In11.Cu")
		(net "M_D_CPU0_SB_PAR")
	)
	(segment
		(start 298.49318 -247.888252)
		(end 298.16298 -247.558052)
		(width 0.18288)
		(layer "In11.Cu")
		(net "M_D_CPU0_SB_PAR")
	)
	(segment
		(start 342.865964 -247.494044)
		(end 342.658446 -247.61571)
		(width 0.088646)
		(layer "In11.Cu")
		(net "M_D_CPU0_SB_PAR")
	)
	(segment
		(start 322.388992 -246.963946)
		(end 322.042282 -247.310656)
		(width 0.18288)
		(layer "In11.Cu")
		(net "M_D_CPU0_SB_PAR")
	)
	(segment
		(start 313.137296 -245.923054)
		(end 312.822336 -245.923054)
		(width 0.18288)
		(layer "In11.Cu")
		(net "M_D_CPU0_SB_PAR")
	)
	(segment
		(start 289.865562 -247.551448)
		(end 289.865562 -247.926352)
		(width 0.18288)
		(layer "In11.Cu")
		(net "M_D_CPU0_SB_PAR")
	)
	(segment
		(start 279.377394 -247.756426)
		(end 277.370794 -247.756426)
		(width 0.18288)
		(layer "In11.Cu")
		(net "M_D_CPU0_SB_PAR")
	)
	(segment
		(start 322.042282 -247.310656)
		(end 316.258702 -247.310656)
		(width 0.18288)
		(layer "In11.Cu")
		(net "M_D_CPU0_SB_PAR")
	)
	(segment
		(start 332.326234 -247.743472)
		(end 332.079346 -247.743472)
		(width 0.088646)
		(layer "In11.Cu")
		(net "M_D_CPU0_SB_PAR")
	)
	(segment
		(start 306.974494 -247.078246)
		(end 306.860194 -246.963946)
		(width 0.18288)
		(layer "In11.Cu")
		(net "M_D_CPU0_SB_PAR")
	)
	(segment
		(start 312.629296 -245.730014)
		(end 312.629296 -245.40083)
		(width 0.18288)
		(layer "In11.Cu")
		(net "M_D_CPU0_SB_PAR")
	)
	(segment
		(start 314.155836 -245.20779)
		(end 313.523376 -245.20779)
		(width 0.18288)
		(layer "In11.Cu")
		(net "M_D_CPU0_SB_PAR")
	)
	(segment
		(start 271.645888 -247.781826)
		(end 271.452848 -247.588786)
		(width 0.18288)
		(layer "In11.Cu")
		(net "M_D_CPU0_SB_PAR")
	)
	(segment
		(start 270.944848 -247.002808)
		(end 270.751808 -247.195848)
		(width 0.18288)
		(layer "In11.Cu")
		(net "M_D_CPU0_SB_PAR")
	)
	(segment
		(start 272.63471 -248.035826)
		(end 272.38071 -247.781826)
		(width 0.18288)
		(layer "In11.Cu")
		(net "M_D_CPU0_SB_PAR")
	)
	(segment
		(start 270.751808 -247.588786)
		(end 270.558768 -247.781826)
		(width 0.18288)
		(layer "In11.Cu")
		(net "M_D_CPU0_SB_PAR")
	)
	(segment
		(start 275.819616 -248.035826)
		(end 275.626576 -247.842786)
		(width 0.18288)
		(layer "In11.Cu")
		(net "M_D_CPU0_SB_PAR")
	)
	(segment
		(start 298.16298 -247.558052)
		(end 297.685968 -247.558052)
		(width 0.18288)
		(layer "In11.Cu")
		(net "M_D_CPU0_SB_PAR")
	)
	(segment
		(start 313.523376 -245.20779)
		(end 313.330336 -245.40083)
		(width 0.18288)
		(layer "In11.Cu")
		(net "M_D_CPU0_SB_PAR")
	)
	(segment
		(start 342.006682 -247.66778)
		(end 341.99195 -247.676416)
		(width 0.088646)
		(layer "In11.Cu")
		(net "M_D_CPU0_SB_PAR")
	)
	(segment
		(start 309.637176 -246.295672)
		(end 309.18277 -246.10695)
		(width 0.18288)
		(layer "In11.Cu")
		(net "M_D_CPU0_SB_PAR")
	)
	(segment
		(start 281.271218 -247.891046)
		(end 279.512014 -247.891046)
		(width 0.18288)
		(layer "In11.Cu")
		(net "M_D_CPU0_SB_PAR")
	)
	(segment
		(start 336.367882 -247.66778)
		(end 336.357468 -247.673876)
		(width 0.088646)
		(layer "In11.Cu")
		(net "M_D_CPU0_SB_PAR")
	)
	(segment
		(start 311.460134 -245.203726)
		(end 310.545734 -246.118126)
		(width 0.18288)
		(layer "In11.Cu")
		(net "M_D_CPU0_SB_PAR")
	)
	(segment
		(start 310.545734 -246.118126)
		(end 310.065674 -246.118126)
		(width 0.18288)
		(layer "In11.Cu")
		(net "M_D_CPU0_SB_PAR")
	)
	(segment
		(start 283.210762 -247.578626)
		(end 282.349194 -247.578626)
		(width 0.18288)
		(layer "In11.Cu")
		(net "M_D_CPU0_SB_PAR")
	)
	(segment
		(start 277.370794 -247.756426)
		(end 277.091394 -248.035826)
		(width 0.18288)
		(layer "In11.Cu")
		(net "M_D_CPU0_SB_PAR")
	)
	(segment
		(start 290.058602 -247.358408)
		(end 289.865562 -247.551448)
		(width 0.18288)
		(layer "In11.Cu")
		(net "M_D_CPU0_SB_PAR")
	)
	(segment
		(start 279.512014 -247.891046)
		(end 279.377394 -247.756426)
		(width 0.18288)
		(layer "In11.Cu")
		(net "M_D_CPU0_SB_PAR")
	)
	(segment
		(start 332.079346 -247.743472)
		(end 331.853032 -247.517158)
		(width 0.088646)
		(layer "In11.Cu")
		(net "M_D_CPU0_SB_PAR")
	)
	(segment
		(start 344.356182 -247.50268)
		(end 344.345768 -247.496584)
		(width 0.088646)
		(layer "In11.Cu")
		(net "M_D_CPU0_SB_PAR")
	)
	(segment
		(start 282.349194 -247.578626)
		(end 281.890978 -248.036842)
		(width 0.18288)
		(layer "In11.Cu")
		(net "M_D_CPU0_SB_PAR")
	)
	(segment
		(start 275.433536 -247.401842)
		(end 275.118576 -247.401842)
		(width 0.18288)
		(layer "In11.Cu")
		(net "M_D_CPU0_SB_PAR")
	)
	(segment
		(start 271.452848 -247.588786)
		(end 271.452848 -247.195848)
		(width 0.18288)
		(layer "In11.Cu")
		(net "M_D_CPU0_SB_PAR")
	)
	(segment
		(start 270.558768 -247.781826)
		(end 269.99438 -247.781826)
		(width 0.18288)
		(layer "In11.Cu")
		(net "M_D_CPU0_SB_PAR")
	)
	(segment
		(start 342.658446 -247.61571)
		(end 342.242648 -247.61571)
		(width 0.088646)
		(layer "In11.Cu")
		(net "M_D_CPU0_SB_PAR")
	)
	(segment
		(start 296.171874 -248.010426)
		(end 296.052494 -247.891046)
		(width 0.18288)
		(layer "In11.Cu")
		(net "M_D_CPU0_SB_PAR")
	)
	(segment
		(start 339.572346 -247.673876)
		(end 339.561932 -247.66778)
		(width 0.088646)
		(layer "In11.Cu")
		(net "M_D_CPU0_SB_PAR")
	)
	(segment
		(start 328.85126 -247.517158)
		(end 328.298048 -246.963946)
		(width 0.18288)
		(layer "In11.Cu")
		(net "M_D_CPU0_SB_PAR")
	)
	(segment
		(start 294.625014 -247.891046)
		(end 294.414194 -247.680226)
		(width 0.18288)
		(layer "In11.Cu")
		(net "M_D_CPU0_SB_PAR")
	)
	(segment
		(start 287.02508 -247.63603)
		(end 286.831786 -247.829324)
		(width 0.18288)
		(layer "In11.Cu")
		(net "M_D_CPU0_SB_PAR")
	)
	(segment
		(start 316.258702 -247.310656)
		(end 314.155836 -245.20779)
		(width 0.18288)
		(layer "In11.Cu")
		(net "M_D_CPU0_SB_PAR")
	)
	(segment
		(start 292.11778 -248.119392)
		(end 290.759642 -248.119392)
		(width 0.18288)
		(layer "In11.Cu")
		(net "M_D_CPU0_SB_PAR")
	)
	(segment
		(start 313.330336 -245.40083)
		(end 313.330336 -245.730014)
		(width 0.18288)
		(layer "In11.Cu")
		(net "M_D_CPU0_SB_PAR")
	)
	(segment
		(start 288.445194 -247.63603)
		(end 287.02508 -247.63603)
		(width 0.18288)
		(layer "In11.Cu")
		(net "M_D_CPU0_SB_PAR")
	)
	(segment
		(start 308.309518 -246.845582)
		(end 308.076854 -247.078246)
		(width 0.18288)
		(layer "In11.Cu")
		(net "M_D_CPU0_SB_PAR")
	)
	(segment
		(start 272.38071 -247.781826)
		(end 271.645888 -247.781826)
		(width 0.18288)
		(layer "In11.Cu")
		(net "M_D_CPU0_SB_PAR")
	)
	(segment
		(start 275.626576 -247.842786)
		(end 275.626576 -247.594882)
		(width 0.18288)
		(layer "In11.Cu")
		(net "M_D_CPU0_SB_PAR")
	)
	(segment
		(start 285.37535 -247.888252)
		(end 283.520388 -247.888252)
		(width 0.18288)
		(layer "In11.Cu")
		(net "M_D_CPU0_SB_PAR")
	)
	(segment
		(start 286.831786 -247.829324)
		(end 286.831786 -248.169684)
		(width 0.18288)
		(layer "In11.Cu")
		(net "M_D_CPU0_SB_PAR")
	)
	(arc
		(start 344.345768 -247.496584)
		(mid 344.06759 -247.426861)
		(end 343.791032 -247.50268)
		(width 0.088646)
		(layer "In11.Cu")
		(net "M_D_CPU0_SB_PAR")
	)
	(arc
		(start 333.923132 -247.66778)
		(mid 333.735934 -247.617637)
		(end 333.548736 -247.66778)
		(width 0.088646)
		(layer "In11.Cu")
		(net "M_D_CPU0_SB_PAR")
	)
	(arc
		(start 341.441278 -247.66778)
		(mid 341.25408 -247.617637)
		(end 341.066882 -247.66778)
		(width 0.088646)
		(layer "In11.Cu")
		(net "M_D_CPU0_SB_PAR")
	)
	(arc
		(start 344.730578 -247.50268)
		(mid 344.54338 -247.552823)
		(end 344.356182 -247.50268)
		(width 0.088646)
		(layer "In11.Cu")
		(net "M_D_CPU0_SB_PAR")
	)
	(arc
		(start 338.247482 -247.66778)
		(mid 337.970923 -247.743523)
		(end 337.692746 -247.673876)
		(width 0.088646)
		(layer "In11.Cu")
		(net "M_D_CPU0_SB_PAR")
	)
	(arc
		(start 340.501478 -247.66778)
		(mid 340.31428 -247.617637)
		(end 340.127082 -247.66778)
		(width 0.088646)
		(layer "In11.Cu")
		(net "M_D_CPU0_SB_PAR")
	)
	(arc
		(start 336.357468 -247.673876)
		(mid 336.07929 -247.743599)
		(end 335.802732 -247.66778)
		(width 0.088646)
		(layer "In11.Cu")
		(net "M_D_CPU0_SB_PAR")
	)
	(arc
		(start 342.179402 -247.617996)
		(mid 342.090002 -247.632351)
		(end 342.006682 -247.66778)
		(width 0.088646)
		(layer "In11.Cu")
		(net "M_D_CPU0_SB_PAR")
	)
	(arc
		(start 339.561932 -247.66778)
		(mid 339.374734 -247.617637)
		(end 339.187536 -247.66778)
		(width 0.088646)
		(layer "In11.Cu")
		(net "M_D_CPU0_SB_PAR")
	)
	(arc
		(start 335.802732 -247.66778)
		(mid 335.615534 -247.617637)
		(end 335.428336 -247.66778)
		(width 0.088646)
		(layer "In11.Cu")
		(net "M_D_CPU0_SB_PAR")
	)
	(arc
		(start 338.621878 -247.66778)
		(mid 338.43468 -247.617637)
		(end 338.247482 -247.66778)
		(width 0.088646)
		(layer "In11.Cu")
		(net "M_D_CPU0_SB_PAR")
	)
	(arc
		(start 334.488536 -247.66778)
		(mid 334.205834 -247.743556)
		(end 333.923132 -247.66778)
		(width 0.088646)
		(layer "In11.Cu")
		(net "M_D_CPU0_SB_PAR")
	)
	(arc
		(start 332.983332 -247.66778)
		(mid 332.796134 -247.617637)
		(end 332.608936 -247.66778)
		(width 0.088646)
		(layer "In11.Cu")
		(net "M_D_CPU0_SB_PAR")
	)
	(arc
		(start 343.416636 -247.50268)
		(mid 343.142437 -247.426845)
		(end 342.865964 -247.494044)
		(width 0.088646)
		(layer "In11.Cu")
		(net "M_D_CPU0_SB_PAR")
	)
	(arc
		(start 332.608936 -247.66778)
		(mid 332.472567 -247.724222)
		(end 332.326234 -247.743472)
		(width 0.088646)
		(layer "In11.Cu")
		(net "M_D_CPU0_SB_PAR")
	)
	(arc
		(start 341.05215 -247.676416)
		(mid 340.775675 -247.743736)
		(end 340.501478 -247.66778)
		(width 0.088646)
		(layer "In11.Cu")
		(net "M_D_CPU0_SB_PAR")
	)
	(arc
		(start 336.742278 -247.66778)
		(mid 336.55508 -247.617637)
		(end 336.367882 -247.66778)
		(width 0.088646)
		(layer "In11.Cu")
		(net "M_D_CPU0_SB_PAR")
	)
	(arc
		(start 337.297522 -247.673876)
		(mid 337.01909 -247.743722)
		(end 336.742278 -247.66778)
		(width 0.088646)
		(layer "In11.Cu")
		(net "M_D_CPU0_SB_PAR")
	)
	(arc
		(start 334.862932 -247.66778)
		(mid 334.675734 -247.617637)
		(end 334.488536 -247.66778)
		(width 0.088646)
		(layer "In11.Cu")
		(net "M_D_CPU0_SB_PAR")
	)
	(arc
		(start 337.682332 -247.66778)
		(mid 337.495134 -247.617637)
		(end 337.307936 -247.66778)
		(width 0.088646)
		(layer "In11.Cu")
		(net "M_D_CPU0_SB_PAR")
	)
	(arc
		(start 340.127082 -247.66778)
		(mid 339.850523 -247.743523)
		(end 339.572346 -247.673876)
		(width 0.088646)
		(layer "In11.Cu")
		(net "M_D_CPU0_SB_PAR")
	)
	(arc
		(start 335.428336 -247.66778)
		(mid 335.145634 -247.743556)
		(end 334.862932 -247.66778)
		(width 0.088646)
		(layer "In11.Cu")
		(net "M_D_CPU0_SB_PAR")
	)
	(arc
		(start 333.548736 -247.66778)
		(mid 333.266034 -247.743556)
		(end 332.983332 -247.66778)
		(width 0.088646)
		(layer "In11.Cu")
		(net "M_D_CPU0_SB_PAR")
	)
	(arc
		(start 343.791032 -247.50268)
		(mid 343.603834 -247.552823)
		(end 343.416636 -247.50268)
		(width 0.088646)
		(layer "In11.Cu")
		(net "M_D_CPU0_SB_PAR")
	)
	(arc
		(start 341.99195 -247.676416)
		(mid 341.715475 -247.743736)
		(end 341.441278 -247.66778)
		(width 0.088646)
		(layer "In11.Cu")
		(net "M_D_CPU0_SB_PAR")
	)
	(arc
		(start 339.177122 -247.673876)
		(mid 338.89869 -247.743722)
		(end 338.621878 -247.66778)
		(width 0.088646)
		(layer "In11.Cu")
		(net "M_D_CPU0_SB_PAR")
	)
	(arc
		(start 344.881708 -247.442482)
		(mid 344.804094 -247.467129)
		(end 344.730832 -247.50268)
		(width 0.088646)
		(layer "In11.Cu")
		(net "M_D_CPU0_SB_PAR")
	)
	(segment
		(start 256.618486 -238.116618)
		(end 256.080514 -238.116618)
		(width 0.20066)
		(layer "F.Cu")
		(net "M_D_CPU0_SB_DQS_DP<9>")
	)
	(segment
		(start 256.879598 -237.855506)
		(end 256.618486 -238.116618)
		(width 0.20066)
		(layer "F.Cu")
		(net "M_D_CPU0_SB_DQS_DP<9>")
	)
	(segment
		(start 257.30454 -237.855506)
		(end 256.879598 -237.855506)
		(width 0.20066)
		(layer "F.Cu")
		(net "M_D_CPU0_SB_DQS_DP<9>")
	)
	(segment
		(start 259.065776 -238.541814)
		(end 259.056378 -238.551212)
		(width 0.101854)
		(layer "F.Cu")
		(net "M_D_CPU0_SB_DQS_DP<9>")
	)
	(segment
		(start 262.54583 -237.855506)
		(end 262.120634 -238.280702)
		(width 0.20066)
		(layer "F.Cu")
		(net "M_D_CPU0_SB_DQS_DP<9>")
	)
	(segment
		(start 258.567682 -238.280702)
		(end 257.940556 -238.280702)
		(width 0.20066)
		(layer "F.Cu")
		(net "M_D_CPU0_SB_DQS_DP<9>")
	)
	(segment
		(start 257.940556 -238.280702)
		(end 257.30454 -237.855506)
		(width 0.20066)
		(layer "F.Cu")
		(net "M_D_CPU0_SB_DQS_DP<9>")
	)
	(segment
		(start 261.794752 -238.280702)
		(end 261.53364 -238.541814)
		(width 0.20066)
		(layer "F.Cu")
		(net "M_D_CPU0_SB_DQS_DP<9>")
	)
	(segment
		(start 261.53364 -238.541814)
		(end 261.381494 -238.541814)
		(width 0.20066)
		(layer "F.Cu")
		(net "M_D_CPU0_SB_DQS_DP<9>")
	)
	(segment
		(start 346.89288 -245.272306)
		(end 346.89288 -244.73662)
		(width 0.20066)
		(layer "F.Cu")
		(net "M_D_CPU0_SB_DQS_DP<9>")
	)
	(segment
		(start 259.302758 -238.541814)
		(end 259.065776 -238.541814)
		(width 0.101854)
		(layer "F.Cu")
		(net "M_D_CPU0_SB_DQS_DP<9>")
	)
	(segment
		(start 263.624314 -238.116618)
		(end 263.075674 -238.116618)
		(width 0.20066)
		(layer "F.Cu")
		(net "M_D_CPU0_SB_DQS_DP<9>")
	)
	(segment
		(start 259.056378 -238.551212)
		(end 258.838192 -238.551212)
		(width 0.20066)
		(layer "F.Cu")
		(net "M_D_CPU0_SB_DQS_DP<9>")
	)
	(segment
		(start 263.075674 -238.116618)
		(end 262.814562 -237.855506)
		(width 0.20066)
		(layer "F.Cu")
		(net "M_D_CPU0_SB_DQS_DP<9>")
	)
	(segment
		(start 261.381494 -238.541814)
		(end 261.058152 -238.541814)
		(width 0.101854)
		(layer "F.Cu")
		(net "M_D_CPU0_SB_DQS_DP<9>")
	)
	(segment
		(start 262.120634 -238.280702)
		(end 261.794752 -238.280702)
		(width 0.20066)
		(layer "F.Cu")
		(net "M_D_CPU0_SB_DQS_DP<9>")
	)
	(segment
		(start 262.814562 -237.855506)
		(end 262.54583 -237.855506)
		(width 0.20066)
		(layer "F.Cu")
		(net "M_D_CPU0_SB_DQS_DP<9>")
	)
	(segment
		(start 261.058152 -238.541814)
		(end 259.302758 -238.541814)
		(width 0.1016)
		(layer "F.Cu")
		(net "M_D_CPU0_SB_DQS_DP<9>")
	)
	(segment
		(start 258.838192 -238.551212)
		(end 258.567682 -238.280702)
		(width 0.20066)
		(layer "F.Cu")
		(net "M_D_CPU0_SB_DQS_DP<9>")
	)
	(segment
		(start 346.893134 -245.27256)
		(end 346.89288 -245.272306)
		(width 0.20066)
		(layer "F.Cu")
		(net "M_D_CPU0_SB_DQS_DP<9>")
	)
	(segment
		(start 264.729214 -238.116618)
		(end 263.624314 -238.116618)
		(width 0.20066)
		(layer "F.Cu")
		(net "M_D_CPU0_SB_DQS_DP<9>")
	)
	(segment
		(start 311.6199 -237.616746)
		(end 301.742094 -237.616746)
		(width 0.18288)
		(layer "In11.Cu")
		(net "M_D_CPU0_SB_DQS_DP<9>")
	)
	(segment
		(start 279.611582 -239.390428)
		(end 279.35428 -239.133126)
		(width 0.18288)
		(layer "In11.Cu")
		(net "M_D_CPU0_SB_DQS_DP<9>")
	)
	(segment
		(start 333.467964 -245.234968)
		(end 333.453232 -245.226332)
		(width 0.088646)
		(layer "In11.Cu")
		(net "M_D_CPU0_SB_DQS_DP<9>")
	)
	(segment
		(start 267.854684 -238.267748)
		(end 267.216636 -237.6297)
		(width 0.18288)
		(layer "In11.Cu")
		(net "M_D_CPU0_SB_DQS_DP<9>")
	)
	(segment
		(start 291.815266 -237.664244)
		(end 288.96437 -237.664244)
		(width 0.18288)
		(layer "In11.Cu")
		(net "M_D_CPU0_SB_DQS_DP<9>")
	)
	(segment
		(start 299.480732 -238.267748)
		(end 299.208952 -238.539528)
		(width 0.18288)
		(layer "In11.Cu")
		(net "M_D_CPU0_SB_DQS_DP<9>")
	)
	(segment
		(start 333.17053 -244.750844)
		(end 333.17053 -244.73662)
		(width 0.088646)
		(layer "In11.Cu")
		(net "M_D_CPU0_SB_DQS_DP<9>")
	)
	(segment
		(start 283.116274 -238.279178)
		(end 282.935934 -238.459772)
		(width 0.18288)
		(layer "In11.Cu")
		(net "M_D_CPU0_SB_DQS_DP<9>")
	)
	(segment
		(start 269.35049 -238.262668)
		(end 269.071852 -238.541306)
		(width 0.18288)
		(layer "In11.Cu")
		(net "M_D_CPU0_SB_DQS_DP<9>")
	)
	(segment
		(start 314.343288 -238.874554)
		(end 313.542934 -238.874554)
		(width 0.18288)
		(layer "In11.Cu")
		(net "M_D_CPU0_SB_DQS_DP<9>")
	)
	(segment
		(start 268.361668 -238.267748)
		(end 267.854684 -238.267748)
		(width 0.18288)
		(layer "In11.Cu")
		(net "M_D_CPU0_SB_DQS_DP<9>")
	)
	(segment
		(start 331.696822 -244.043454)
		(end 331.637132 -244.103144)
		(width 0.088646)
		(layer "In11.Cu")
		(net "M_D_CPU0_SB_DQS_DP<9>")
	)
	(segment
		(start 340.596982 -245.226332)
		(end 340.586568 -245.232428)
		(width 0.088646)
		(layer "In11.Cu")
		(net "M_D_CPU0_SB_DQS_DP<9>")
	)
	(segment
		(start 331.637132 -244.103144)
		(end 330.448666 -244.103144)
		(width 0.18288)
		(layer "In11.Cu")
		(net "M_D_CPU0_SB_DQS_DP<9>")
	)
	(segment
		(start 283.414216 -238.279178)
		(end 283.116274 -238.279178)
		(width 0.18288)
		(layer "In11.Cu")
		(net "M_D_CPU0_SB_DQS_DP<9>")
	)
	(segment
		(start 294.427656 -239.106202)
		(end 293.871142 -239.106202)
		(width 0.18288)
		(layer "In11.Cu")
		(net "M_D_CPU0_SB_DQS_DP<9>")
	)
	(segment
		(start 330.448666 -244.103144)
		(end 329.871324 -243.525802)
		(width 0.18288)
		(layer "In11.Cu")
		(net "M_D_CPU0_SB_DQS_DP<9>")
	)
	(segment
		(start 284.166056 -238.542068)
		(end 283.677106 -238.542068)
		(width 0.18288)
		(layer "In11.Cu")
		(net "M_D_CPU0_SB_DQS_DP<9>")
	)
	(segment
		(start 335.347564 -245.234968)
		(end 335.332832 -245.226332)
		(width 0.088646)
		(layer "In11.Cu")
		(net "M_D_CPU0_SB_DQS_DP<9>")
	)
	(segment
		(start 336.287364 -245.234968)
		(end 336.272632 -245.226332)
		(width 0.088646)
		(layer "In11.Cu")
		(net "M_D_CPU0_SB_DQS_DP<9>")
	)
	(segment
		(start 284.389068 -238.319056)
		(end 284.166056 -238.542068)
		(width 0.18288)
		(layer "In11.Cu")
		(net "M_D_CPU0_SB_DQS_DP<9>")
	)
	(segment
		(start 345.922854 -245.11)
		(end 345.865704 -245.103142)
		(width 0.088646)
		(layer "In11.Cu")
		(net "M_D_CPU0_SB_DQS_DP<9>")
	)
	(segment
		(start 283.677106 -238.542068)
		(end 283.414216 -238.279178)
		(width 0.18288)
		(layer "In11.Cu")
		(net "M_D_CPU0_SB_DQS_DP<9>")
	)
	(segment
		(start 345.505278 -245.105682)
		(end 345.281758 -245.23446)
		(width 0.088646)
		(layer "In11.Cu")
		(net "M_D_CPU0_SB_DQS_DP<9>")
	)
	(segment
		(start 277.372318 -238.510064)
		(end 276.523704 -238.861346)
		(width 0.18288)
		(layer "In11.Cu")
		(net "M_D_CPU0_SB_DQS_DP<9>")
	)
	(segment
		(start 279.35428 -239.133126)
		(end 279.338024 -239.133126)
		(width 0.18288)
		(layer "In11.Cu")
		(net "M_D_CPU0_SB_DQS_DP<9>")
	)
	(segment
		(start 299.208952 -238.539528)
		(end 298.809918 -238.539528)
		(width 0.18288)
		(layer "In11.Cu")
		(net "M_D_CPU0_SB_DQS_DP<9>")
	)
	(segment
		(start 301.742094 -237.616746)
		(end 300.170342 -238.267748)
		(width 0.18288)
		(layer "In11.Cu")
		(net "M_D_CPU0_SB_DQS_DP<9>")
	)
	(segment
		(start 297.361356 -238.725456)
		(end 296.424604 -239.113822)
		(width 0.18288)
		(layer "In11.Cu")
		(net "M_D_CPU0_SB_DQS_DP<9>")
	)
	(segment
		(start 298.18076 -238.232188)
		(end 297.623992 -238.463074)
		(width 0.18288)
		(layer "In11.Cu")
		(net "M_D_CPU0_SB_DQS_DP<9>")
	)
	(segment
		(start 278.97836 -239.10798)
		(end 278.784558 -238.914178)
		(width 0.18288)
		(layer "In11.Cu")
		(net "M_D_CPU0_SB_DQS_DP<9>")
	)
	(segment
		(start 280.346912 -239.114076)
		(end 280.07056 -239.390428)
		(width 0.18288)
		(layer "In11.Cu")
		(net "M_D_CPU0_SB_DQS_DP<9>")
	)
	(segment
		(start 332.051914 -244.043454)
		(end 331.696822 -244.043454)
		(width 0.088646)
		(layer "In11.Cu")
		(net "M_D_CPU0_SB_DQS_DP<9>")
	)
	(segment
		(start 340.981792 -245.232428)
		(end 340.971378 -245.226332)
		(width 0.088646)
		(layer "In11.Cu")
		(net "M_D_CPU0_SB_DQS_DP<9>")
	)
	(segment
		(start 313.542934 -238.874554)
		(end 312.757566 -238.089186)
		(width 0.18288)
		(layer "In11.Cu")
		(net "M_D_CPU0_SB_DQS_DP<9>")
	)
	(segment
		(start 345.860878 -245.105682)
		(end 345.505278 -245.105682)
		(width 0.088646)
		(layer "In11.Cu")
		(net "M_D_CPU0_SB_DQS_DP<9>")
	)
	(segment
		(start 345.865704 -245.103142)
		(end 345.860878 -245.105682)
		(width 0.088646)
		(layer "In11.Cu")
		(net "M_D_CPU0_SB_DQS_DP<9>")
	)
	(segment
		(start 287.383474 -238.319056)
		(end 284.389068 -238.319056)
		(width 0.18288)
		(layer "In11.Cu")
		(net "M_D_CPU0_SB_DQS_DP<9>")
	)
	(segment
		(start 282.935934 -238.459772)
		(end 281.355292 -239.114076)
		(width 0.18288)
		(layer "In11.Cu")
		(net "M_D_CPU0_SB_DQS_DP<9>")
	)
	(segment
		(start 338.717382 -245.226332)
		(end 338.706968 -245.232428)
		(width 0.088646)
		(layer "In11.Cu")
		(net "M_D_CPU0_SB_DQS_DP<9>")
	)
	(segment
		(start 298.502578 -238.232188)
		(end 298.18076 -238.232188)
		(width 0.18288)
		(layer "In11.Cu")
		(net "M_D_CPU0_SB_DQS_DP<9>")
	)
	(segment
		(start 280.07056 -239.390428)
		(end 279.611582 -239.390428)
		(width 0.18288)
		(layer "In11.Cu")
		(net "M_D_CPU0_SB_DQS_DP<9>")
	)
	(segment
		(start 300.170342 -238.267748)
		(end 299.480732 -238.267748)
		(width 0.18288)
		(layer "In11.Cu")
		(net "M_D_CPU0_SB_DQS_DP<9>")
	)
	(segment
		(start 278.784558 -238.914178)
		(end 277.809706 -238.510064)
		(width 0.18288)
		(layer "In11.Cu")
		(net "M_D_CPU0_SB_DQS_DP<9>")
	)
	(segment
		(start 337.227164 -245.234968)
		(end 337.212432 -245.226332)
		(width 0.088646)
		(layer "In11.Cu")
		(net "M_D_CPU0_SB_DQS_DP<9>")
	)
	(segment
		(start 332.79588 -244.361716)
		(end 332.370176 -244.361716)
		(width 0.088646)
		(layer "In11.Cu")
		(net "M_D_CPU0_SB_DQS_DP<9>")
	)
	(segment
		(start 281.355292 -239.114076)
		(end 280.346912 -239.114076)
		(width 0.18288)
		(layer "In11.Cu")
		(net "M_D_CPU0_SB_DQS_DP<9>")
	)
	(segment
		(start 312.757566 -238.089186)
		(end 311.6199 -237.616746)
		(width 0.18288)
		(layer "In11.Cu")
		(net "M_D_CPU0_SB_DQS_DP<9>")
	)
	(segment
		(start 346.55252 -244.826536)
		(end 346.127324 -245.068344)
		(width 0.088646)
		(layer "In11.Cu")
		(net "M_D_CPU0_SB_DQS_DP<9>")
	)
	(segment
		(start 273.789648 -238.861346)
		(end 272.344388 -238.262668)
		(width 0.18288)
		(layer "In11.Cu")
		(net "M_D_CPU0_SB_DQS_DP<9>")
	)
	(segment
		(start 341.926164 -245.234968)
		(end 341.911432 -245.226332)
		(width 0.088646)
		(layer "In11.Cu")
		(net "M_D_CPU0_SB_DQS_DP<9>")
	)
	(segment
		(start 288.96437 -237.664244)
		(end 287.383474 -238.319056)
		(width 0.18288)
		(layer "In11.Cu")
		(net "M_D_CPU0_SB_DQS_DP<9>")
	)
	(segment
		(start 314.95746 -239.128554)
		(end 314.343288 -238.874554)
		(width 0.18288)
		(layer "In11.Cu")
		(net "M_D_CPU0_SB_DQS_DP<9>")
	)
	(segment
		(start 334.407764 -245.234968)
		(end 334.393032 -245.226332)
		(width 0.088646)
		(layer "In11.Cu")
		(net "M_D_CPU0_SB_DQS_DP<9>")
	)
	(segment
		(start 279.312878 -239.10798)
		(end 278.97836 -239.10798)
		(width 0.18288)
		(layer "In11.Cu")
		(net "M_D_CPU0_SB_DQS_DP<9>")
	)
	(segment
		(start 339.102192 -245.232428)
		(end 339.091778 -245.226332)
		(width 0.088646)
		(layer "In11.Cu")
		(net "M_D_CPU0_SB_DQS_DP<9>")
	)
	(segment
		(start 329.871324 -243.525802)
		(end 319.354708 -243.525802)
		(width 0.18288)
		(layer "In11.Cu")
		(net "M_D_CPU0_SB_DQS_DP<9>")
	)
	(segment
		(start 343.805764 -245.234968)
		(end 343.791032 -245.226332)
		(width 0.088646)
		(layer "In11.Cu")
		(net "M_D_CPU0_SB_DQS_DP<9>")
	)
	(segment
		(start 269.071852 -238.541306)
		(end 268.635226 -238.541306)
		(width 0.18288)
		(layer "In11.Cu")
		(net "M_D_CPU0_SB_DQS_DP<9>")
	)
	(segment
		(start 265.846814 -237.6297)
		(end 265.362182 -237.83036)
		(width 0.18288)
		(layer "In11.Cu")
		(net "M_D_CPU0_SB_DQS_DP<9>")
	)
	(segment
		(start 295.384474 -239.113822)
		(end 295.105328 -239.392968)
		(width 0.18288)
		(layer "In11.Cu")
		(net "M_D_CPU0_SB_DQS_DP<9>")
	)
	(segment
		(start 267.216636 -237.6297)
		(end 265.846814 -237.6297)
		(width 0.18288)
		(layer "In11.Cu")
		(net "M_D_CPU0_SB_DQS_DP<9>")
	)
	(segment
		(start 342.865964 -245.234968)
		(end 342.851232 -245.226332)
		(width 0.088646)
		(layer "In11.Cu")
		(net "M_D_CPU0_SB_DQS_DP<9>")
	)
	(segment
		(start 276.523704 -238.861346)
		(end 273.789648 -238.861346)
		(width 0.18288)
		(layer "In11.Cu")
		(net "M_D_CPU0_SB_DQS_DP<9>")
	)
	(segment
		(start 279.338024 -239.133126)
		(end 279.312878 -239.10798)
		(width 0.18288)
		(layer "In11.Cu")
		(net "M_D_CPU0_SB_DQS_DP<9>")
	)
	(segment
		(start 344.730578 -245.226078)
		(end 344.730832 -245.226332)
		(width 0.088646)
		(layer "In11.Cu")
		(net "M_D_CPU0_SB_DQS_DP<9>")
	)
	(segment
		(start 265.015472 -237.83036)
		(end 264.729214 -238.116618)
		(width 0.18288)
		(layer "In11.Cu")
		(net "M_D_CPU0_SB_DQS_DP<9>")
	)
	(segment
		(start 296.424604 -239.113822)
		(end 295.384474 -239.113822)
		(width 0.18288)
		(layer "In11.Cu")
		(net "M_D_CPU0_SB_DQS_DP<9>")
	)
	(segment
		(start 297.623992 -238.463074)
		(end 297.361356 -238.725456)
		(width 0.18288)
		(layer "In11.Cu")
		(net "M_D_CPU0_SB_DQS_DP<9>")
	)
	(segment
		(start 277.809706 -238.510064)
		(end 277.372318 -238.510064)
		(width 0.18288)
		(layer "In11.Cu")
		(net "M_D_CPU0_SB_DQS_DP<9>")
	)
	(segment
		(start 294.714422 -239.392968)
		(end 294.427656 -239.106202)
		(width 0.18288)
		(layer "In11.Cu")
		(net "M_D_CPU0_SB_DQS_DP<9>")
	)
	(segment
		(start 292.863778 -238.098838)
		(end 291.815266 -237.664244)
		(width 0.18288)
		(layer "In11.Cu")
		(net "M_D_CPU0_SB_DQS_DP<9>")
	)
	(segment
		(start 293.871142 -239.106202)
		(end 292.863778 -238.098838)
		(width 0.18288)
		(layer "In11.Cu")
		(net "M_D_CPU0_SB_DQS_DP<9>")
	)
	(segment
		(start 319.354708 -243.525802)
		(end 314.95746 -239.128554)
		(width 0.18288)
		(layer "In11.Cu")
		(net "M_D_CPU0_SB_DQS_DP<9>")
	)
	(segment
		(start 298.809918 -238.539528)
		(end 298.502578 -238.232188)
		(width 0.18288)
		(layer "In11.Cu")
		(net "M_D_CPU0_SB_DQS_DP<9>")
	)
	(segment
		(start 295.105328 -239.392968)
		(end 294.714422 -239.392968)
		(width 0.18288)
		(layer "In11.Cu")
		(net "M_D_CPU0_SB_DQS_DP<9>")
	)
	(segment
		(start 265.362182 -237.83036)
		(end 265.015472 -237.83036)
		(width 0.18288)
		(layer "In11.Cu")
		(net "M_D_CPU0_SB_DQS_DP<9>")
	)
	(segment
		(start 268.635226 -238.541306)
		(end 268.361668 -238.267748)
		(width 0.18288)
		(layer "In11.Cu")
		(net "M_D_CPU0_SB_DQS_DP<9>")
	)
	(segment
		(start 332.370176 -244.361716)
		(end 332.051914 -244.043454)
		(width 0.088646)
		(layer "In11.Cu")
		(net "M_D_CPU0_SB_DQS_DP<9>")
	)
	(segment
		(start 272.344388 -238.262668)
		(end 269.35049 -238.262668)
		(width 0.18288)
		(layer "In11.Cu")
		(net "M_D_CPU0_SB_DQS_DP<9>")
	)
	(arc
		(start 337.777836 -245.226332)
		(mid 337.503607 -245.302257)
		(end 337.227164 -245.234968)
		(width 0.088646)
		(layer "In11.Cu")
		(net "M_D_CPU0_SB_DQS_DP<9>")
	)
	(arc
		(start 346.127324 -245.068344)
		(mid 346.028482 -245.105854)
		(end 345.922854 -245.11)
		(width 0.088646)
		(layer "In11.Cu")
		(net "M_D_CPU0_SB_DQS_DP<9>")
	)
	(arc
		(start 335.898236 -245.226332)
		(mid 335.624007 -245.302257)
		(end 335.347564 -245.234968)
		(width 0.088646)
		(layer "In11.Cu")
		(net "M_D_CPU0_SB_DQS_DP<9>")
	)
	(arc
		(start 346.89288 -244.73662)
		(mid 346.716859 -244.759457)
		(end 346.55252 -244.826536)
		(width 0.088646)
		(layer "In11.Cu")
		(net "M_D_CPU0_SB_DQS_DP<9>")
	)
	(arc
		(start 345.281758 -245.23446)
		(mid 345.005093 -245.301931)
		(end 344.730578 -245.226078)
		(width 0.088646)
		(layer "In11.Cu")
		(net "M_D_CPU0_SB_DQS_DP<9>")
	)
	(arc
		(start 334.018636 -245.226332)
		(mid 333.744407 -245.302257)
		(end 333.467964 -245.234968)
		(width 0.088646)
		(layer "In11.Cu")
		(net "M_D_CPU0_SB_DQS_DP<9>")
	)
	(arc
		(start 338.706968 -245.232428)
		(mid 338.42879 -245.30212)
		(end 338.152232 -245.226332)
		(width 0.088646)
		(layer "In11.Cu")
		(net "M_D_CPU0_SB_DQS_DP<9>")
	)
	(arc
		(start 339.657436 -245.226332)
		(mid 339.380623 -245.302168)
		(end 339.102192 -245.232428)
		(width 0.088646)
		(layer "In11.Cu")
		(net "M_D_CPU0_SB_DQS_DP<9>")
	)
	(arc
		(start 333.453232 -245.226332)
		(mid 333.249751 -245.025528)
		(end 333.17053 -244.750844)
		(width 0.088646)
		(layer "In11.Cu")
		(net "M_D_CPU0_SB_DQS_DP<9>")
	)
	(arc
		(start 340.586568 -245.232428)
		(mid 340.30839 -245.30212)
		(end 340.031832 -245.226332)
		(width 0.088646)
		(layer "In11.Cu")
		(net "M_D_CPU0_SB_DQS_DP<9>")
	)
	(arc
		(start 338.152232 -245.226332)
		(mid 337.965034 -245.176189)
		(end 337.777836 -245.226332)
		(width 0.088646)
		(layer "In11.Cu")
		(net "M_D_CPU0_SB_DQS_DP<9>")
	)
	(arc
		(start 343.791032 -245.226332)
		(mid 343.603834 -245.176189)
		(end 343.416636 -245.226332)
		(width 0.088646)
		(layer "In11.Cu")
		(net "M_D_CPU0_SB_DQS_DP<9>")
	)
	(arc
		(start 339.091778 -245.226332)
		(mid 338.90458 -245.176189)
		(end 338.717382 -245.226332)
		(width 0.088646)
		(layer "In11.Cu")
		(net "M_D_CPU0_SB_DQS_DP<9>")
	)
	(arc
		(start 344.356436 -245.226332)
		(mid 344.082207 -245.302257)
		(end 343.805764 -245.234968)
		(width 0.088646)
		(layer "In11.Cu")
		(net "M_D_CPU0_SB_DQS_DP<9>")
	)
	(arc
		(start 344.730832 -245.226332)
		(mid 344.543634 -245.176189)
		(end 344.356436 -245.226332)
		(width 0.088646)
		(layer "In11.Cu")
		(net "M_D_CPU0_SB_DQS_DP<9>")
	)
	(arc
		(start 340.971378 -245.226332)
		(mid 340.78418 -245.176189)
		(end 340.596982 -245.226332)
		(width 0.088646)
		(layer "In11.Cu")
		(net "M_D_CPU0_SB_DQS_DP<9>")
	)
	(arc
		(start 336.838036 -245.226332)
		(mid 336.563807 -245.302257)
		(end 336.287364 -245.234968)
		(width 0.088646)
		(layer "In11.Cu")
		(net "M_D_CPU0_SB_DQS_DP<9>")
	)
	(arc
		(start 335.332832 -245.226332)
		(mid 335.145634 -245.176189)
		(end 334.958436 -245.226332)
		(width 0.088646)
		(layer "In11.Cu")
		(net "M_D_CPU0_SB_DQS_DP<9>")
	)
	(arc
		(start 334.393032 -245.226332)
		(mid 334.205834 -245.176189)
		(end 334.018636 -245.226332)
		(width 0.088646)
		(layer "In11.Cu")
		(net "M_D_CPU0_SB_DQS_DP<9>")
	)
	(arc
		(start 340.031832 -245.226332)
		(mid 339.844634 -245.176189)
		(end 339.657436 -245.226332)
		(width 0.088646)
		(layer "In11.Cu")
		(net "M_D_CPU0_SB_DQS_DP<9>")
	)
	(arc
		(start 341.911432 -245.226332)
		(mid 341.724234 -245.176189)
		(end 341.537036 -245.226332)
		(width 0.088646)
		(layer "In11.Cu")
		(net "M_D_CPU0_SB_DQS_DP<9>")
	)
	(arc
		(start 342.476836 -245.226332)
		(mid 342.202607 -245.302257)
		(end 341.926164 -245.234968)
		(width 0.088646)
		(layer "In11.Cu")
		(net "M_D_CPU0_SB_DQS_DP<9>")
	)
	(arc
		(start 334.958436 -245.226332)
		(mid 334.684207 -245.302257)
		(end 334.407764 -245.234968)
		(width 0.088646)
		(layer "In11.Cu")
		(net "M_D_CPU0_SB_DQS_DP<9>")
	)
	(arc
		(start 333.17053 -244.73662)
		(mid 333.060813 -244.471613)
		(end 332.79588 -244.361716)
		(width 0.088646)
		(layer "In11.Cu")
		(net "M_D_CPU0_SB_DQS_DP<9>")
	)
	(arc
		(start 337.212432 -245.226332)
		(mid 337.025234 -245.176189)
		(end 336.838036 -245.226332)
		(width 0.088646)
		(layer "In11.Cu")
		(net "M_D_CPU0_SB_DQS_DP<9>")
	)
	(arc
		(start 342.851232 -245.226332)
		(mid 342.664034 -245.176189)
		(end 342.476836 -245.226332)
		(width 0.088646)
		(layer "In11.Cu")
		(net "M_D_CPU0_SB_DQS_DP<9>")
	)
	(arc
		(start 336.272632 -245.226332)
		(mid 336.085434 -245.176189)
		(end 335.898236 -245.226332)
		(width 0.088646)
		(layer "In11.Cu")
		(net "M_D_CPU0_SB_DQS_DP<9>")
	)
	(arc
		(start 341.537036 -245.226332)
		(mid 341.260223 -245.302168)
		(end 340.981792 -245.232428)
		(width 0.088646)
		(layer "In11.Cu")
		(net "M_D_CPU0_SB_DQS_DP<9>")
	)
	(arc
		(start 343.416636 -245.226332)
		(mid 343.142407 -245.302257)
		(end 342.865964 -245.234968)
		(width 0.088646)
		(layer "In11.Cu")
		(net "M_D_CPU0_SB_DQS_DP<9>")
	)
	(segment
		(start 265.732768 -198.853044)
		(end 265.227816 -198.853044)
		(width 0.20066)
		(layer "F.Cu")
		(net "M_D_CPU0_SB_DQS_DP<8>")
	)
	(segment
		(start 267.23467 -199.01662)
		(end 266.973304 -199.277986)
		(width 0.20066)
		(layer "F.Cu")
		(net "M_D_CPU0_SB_DQS_DP<8>")
	)
	(segment
		(start 266.368784 -199.277986)
		(end 265.732768 -198.853044)
		(width 0.20066)
		(layer "F.Cu")
		(net "M_D_CPU0_SB_DQS_DP<8>")
	)
	(segment
		(start 261.250684 -199.277986)
		(end 260.91642 -199.277986)
		(width 0.20066)
		(layer "F.Cu")
		(net "M_D_CPU0_SB_DQS_DP<8>")
	)
	(segment
		(start 266.973304 -199.277986)
		(end 266.368784 -199.277986)
		(width 0.20066)
		(layer "F.Cu")
		(net "M_D_CPU0_SB_DQS_DP<8>")
	)
	(segment
		(start 264.825226 -198.591932)
		(end 264.824972 -198.591678)
		(width 0.1016)
		(layer "F.Cu")
		(net "M_D_CPU0_SB_DQS_DP<8>")
	)
	(segment
		(start 267.724382 -199.01662)
		(end 267.23467 -199.01662)
		(width 0.20066)
		(layer "F.Cu")
		(net "M_D_CPU0_SB_DQS_DP<8>")
	)
	(segment
		(start 262.746998 -198.591678)
		(end 262.505698 -198.591678)
		(width 0.101854)
		(layer "F.Cu")
		(net "M_D_CPU0_SB_DQS_DP<8>")
	)
	(segment
		(start 264.966704 -198.591932)
		(end 264.825226 -198.591932)
		(width 0.20066)
		(layer "F.Cu")
		(net "M_D_CPU0_SB_DQS_DP<8>")
	)
	(segment
		(start 260.91642 -199.277986)
		(end 260.655054 -199.01662)
		(width 0.20066)
		(layer "F.Cu")
		(net "M_D_CPU0_SB_DQS_DP<8>")
	)
	(segment
		(start 265.227816 -198.853044)
		(end 264.966704 -198.591932)
		(width 0.20066)
		(layer "F.Cu")
		(net "M_D_CPU0_SB_DQS_DP<8>")
	)
	(segment
		(start 262.033258 -198.855584)
		(end 261.673086 -198.855584)
		(width 0.20066)
		(layer "F.Cu")
		(net "M_D_CPU0_SB_DQS_DP<8>")
	)
	(segment
		(start 261.673086 -198.855584)
		(end 261.250684 -199.277986)
		(width 0.20066)
		(layer "F.Cu")
		(net "M_D_CPU0_SB_DQS_DP<8>")
	)
	(segment
		(start 262.505698 -198.591678)
		(end 262.50011 -198.58609)
		(width 0.101854)
		(layer "F.Cu")
		(net "M_D_CPU0_SB_DQS_DP<8>")
	)
	(segment
		(start 262.302752 -198.58609)
		(end 262.033258 -198.855584)
		(width 0.20066)
		(layer "F.Cu")
		(net "M_D_CPU0_SB_DQS_DP<8>")
	)
	(segment
		(start 262.50011 -198.58609)
		(end 262.302752 -198.58609)
		(width 0.20066)
		(layer "F.Cu")
		(net "M_D_CPU0_SB_DQS_DP<8>")
	)
	(segment
		(start 260.655054 -199.01662)
		(end 260.180582 -199.01662)
		(width 0.20066)
		(layer "F.Cu")
		(net "M_D_CPU0_SB_DQS_DP<8>")
	)
	(segment
		(start 264.824972 -198.591678)
		(end 262.746998 -198.591678)
		(width 0.1016)
		(layer "F.Cu")
		(net "M_D_CPU0_SB_DQS_DP<8>")
	)
	(segment
		(start 348.772734 -230.622602)
		(end 348.77248 -230.622348)
		(width 0.20066)
		(layer "F.Cu")
		(net "M_D_CPU0_SB_DQS_DP<8>")
	)
	(segment
		(start 268.829282 -199.01662)
		(end 267.724382 -199.01662)
		(width 0.20066)
		(layer "F.Cu")
		(net "M_D_CPU0_SB_DQS_DP<8>")
	)
	(segment
		(start 348.77248 -230.622348)
		(end 348.77248 -230.086662)
		(width 0.20066)
		(layer "F.Cu")
		(net "M_D_CPU0_SB_DQS_DP<8>")
	)
	(segment
		(start 347.564964 -229.588568)
		(end 347.550232 -229.597204)
		(width 0.088646)
		(layer "In11.Cu")
		(net "M_D_CPU0_SB_DQS_DP<8>")
	)
	(segment
		(start 295.147492 -196.891148)
		(end 294.70096 -196.891148)
		(width 0.18288)
		(layer "In11.Cu")
		(net "M_D_CPU0_SB_DQS_DP<8>")
	)
	(segment
		(start 323.48678 -216.275158)
		(end 323.48678 -212.441536)
		(width 0.18288)
		(layer "In11.Cu")
		(net "M_D_CPU0_SB_DQS_DP<8>")
	)
	(segment
		(start 283.429964 -198.03745)
		(end 283.024834 -198.03745)
		(width 0.18288)
		(layer "In11.Cu")
		(net "M_D_CPU0_SB_DQS_DP<8>")
	)
	(segment
		(start 283.726382 -197.741032)
		(end 283.429964 -198.03745)
		(width 0.18288)
		(layer "In11.Cu")
		(net "M_D_CPU0_SB_DQS_DP<8>")
	)
	(segment
		(start 275.745702 -197.62724)
		(end 275.315934 -197.913498)
		(width 0.18288)
		(layer "In11.Cu")
		(net "M_D_CPU0_SB_DQS_DP<8>")
	)
	(segment
		(start 280.051002 -196.890894)
		(end 279.623266 -196.890894)
		(width 0.18288)
		(layer "In11.Cu")
		(net "M_D_CPU0_SB_DQS_DP<8>")
	)
	(segment
		(start 272.542 -198.243444)
		(end 271.80413 -198.243444)
		(width 0.18288)
		(layer "In11.Cu")
		(net "M_D_CPU0_SB_DQS_DP<8>")
	)
	(segment
		(start 294.426386 -197.165722)
		(end 293.746428 -197.165722)
		(width 0.18288)
		(layer "In11.Cu")
		(net "M_D_CPU0_SB_DQS_DP<8>")
	)
	(segment
		(start 323.48678 -212.441536)
		(end 313.662314 -202.616816)
		(width 0.18288)
		(layer "In11.Cu")
		(net "M_D_CPU0_SB_DQS_DP<8>")
	)
	(segment
		(start 278.57323 -197.20052)
		(end 277.956264 -197.817486)
		(width 0.18288)
		(layer "In11.Cu")
		(net "M_D_CPU0_SB_DQS_DP<8>")
	)
	(segment
		(start 342.019128 -227.162868)
		(end 342.007444 -227.155756)
		(width 0.088646)
		(layer "In11.Cu")
		(net "M_D_CPU0_SB_DQS_DP<8>")
	)
	(segment
		(start 279.623266 -196.890894)
		(end 279.31364 -197.20052)
		(width 0.18288)
		(layer "In11.Cu")
		(net "M_D_CPU0_SB_DQS_DP<8>")
	)
	(segment
		(start 332.381352 -225.578416)
		(end 332.063852 -225.260916)
		(width 0.088646)
		(layer "In11.Cu")
		(net "M_D_CPU0_SB_DQS_DP<8>")
	)
	(segment
		(start 277.373588 -197.817486)
		(end 276.96033 -197.404228)
		(width 0.18288)
		(layer "In11.Cu")
		(net "M_D_CPU0_SB_DQS_DP<8>")
	)
	(segment
		(start 337.307682 -227.155502)
		(end 337.29295 -227.146866)
		(width 0.088646)
		(layer "In11.Cu")
		(net "M_D_CPU0_SB_DQS_DP<8>")
	)
	(segment
		(start 348.77248 -230.086662)
		(end 348.459552 -230.086662)
		(width 0.088646)
		(layer "In11.Cu")
		(net "M_D_CPU0_SB_DQS_DP<8>")
	)
	(segment
		(start 330.603098 -223.391476)
		(end 323.48678 -216.275158)
		(width 0.18288)
		(layer "In11.Cu")
		(net "M_D_CPU0_SB_DQS_DP<8>")
	)
	(segment
		(start 332.063852 -225.260916)
		(end 332.063852 -224.936558)
		(width 0.088646)
		(layer "In11.Cu")
		(net "M_D_CPU0_SB_DQS_DP<8>")
	)
	(segment
		(start 341.079328 -227.162868)
		(end 341.067644 -227.155756)
		(width 0.088646)
		(layer "In11.Cu")
		(net "M_D_CPU0_SB_DQS_DP<8>")
	)
	(segment
		(start 307.166518 -197.37324)
		(end 303.415192 -197.37324)
		(width 0.18288)
		(layer "In11.Cu")
		(net "M_D_CPU0_SB_DQS_DP<8>")
	)
	(segment
		(start 292.359842 -197.817486)
		(end 291.83711 -197.294754)
		(width 0.18288)
		(layer "In11.Cu")
		(net "M_D_CPU0_SB_DQS_DP<8>")
	)
	(segment
		(start 335.710784 -226.017328)
		(end 335.710784 -226.003104)
		(width 0.088646)
		(layer "In11.Cu")
		(net "M_D_CPU0_SB_DQS_DP<8>")
	)
	(segment
		(start 274.5867 -198.642732)
		(end 273.655282 -198.642732)
		(width 0.18288)
		(layer "In11.Cu")
		(net "M_D_CPU0_SB_DQS_DP<8>")
	)
	(segment
		(start 346.048584 -227.663502)
		(end 346.048584 -227.64496)
		(width 0.088646)
		(layer "In11.Cu")
		(net "M_D_CPU0_SB_DQS_DP<8>")
	)
	(segment
		(start 342.958928 -227.162868)
		(end 342.947244 -227.155756)
		(width 0.088646)
		(layer "In11.Cu")
		(net "M_D_CPU0_SB_DQS_DP<8>")
	)
	(segment
		(start 345.765374 -228.13518)
		(end 345.766136 -228.134672)
		(width 0.088646)
		(layer "In11.Cu")
		(net "M_D_CPU0_SB_DQS_DP<8>")
	)
	(segment
		(start 345.7702 -227.158042)
		(end 345.768168 -227.156772)
		(width 0.088646)
		(layer "In11.Cu")
		(net "M_D_CPU0_SB_DQS_DP<8>")
	)
	(segment
		(start 293.746428 -197.165722)
		(end 293.094664 -197.817486)
		(width 0.18288)
		(layer "In11.Cu")
		(net "M_D_CPU0_SB_DQS_DP<8>")
	)
	(segment
		(start 345.771978 -227.159058)
		(end 345.7702 -227.158042)
		(width 0.088646)
		(layer "In11.Cu")
		(net "M_D_CPU0_SB_DQS_DP<8>")
	)
	(segment
		(start 347.175836 -229.597204)
		(end 347.175582 -229.597204)
		(width 0.088646)
		(layer "In11.Cu")
		(net "M_D_CPU0_SB_DQS_DP<8>")
	)
	(segment
		(start 284.152086 -197.741032)
		(end 283.726382 -197.741032)
		(width 0.18288)
		(layer "In11.Cu")
		(net "M_D_CPU0_SB_DQS_DP<8>")
	)
	(segment
		(start 340.135972 -227.160582)
		(end 340.127336 -227.155756)
		(width 0.088646)
		(layer "In11.Cu")
		(net "M_D_CPU0_SB_DQS_DP<8>")
	)
	(segment
		(start 346.60967 -229.597458)
		(end 346.597986 -229.60457)
		(width 0.088646)
		(layer "In11.Cu")
		(net "M_D_CPU0_SB_DQS_DP<8>")
	)
	(segment
		(start 307.868828 -198.07555)
		(end 307.166518 -197.37324)
		(width 0.18288)
		(layer "In11.Cu")
		(net "M_D_CPU0_SB_DQS_DP<8>")
	)
	(segment
		(start 295.408858 -197.152514)
		(end 295.147492 -196.891148)
		(width 0.18288)
		(layer "In11.Cu")
		(net "M_D_CPU0_SB_DQS_DP<8>")
	)
	(segment
		(start 291.83711 -197.294754)
		(end 289.016186 -197.294754)
		(width 0.18288)
		(layer "In11.Cu")
		(net "M_D_CPU0_SB_DQS_DP<8>")
	)
	(segment
		(start 344.826082 -227.155502)
		(end 344.815668 -227.149406)
		(width 0.088646)
		(layer "In11.Cu")
		(net "M_D_CPU0_SB_DQS_DP<8>")
	)
	(segment
		(start 348.459552 -230.086662)
		(end 348.394274 -230.021384)
		(width 0.088646)
		(layer "In11.Cu")
		(net "M_D_CPU0_SB_DQS_DP<8>")
	)
	(segment
		(start 284.417008 -198.005954)
		(end 284.152086 -197.741032)
		(width 0.18288)
		(layer "In11.Cu")
		(net "M_D_CPU0_SB_DQS_DP<8>")
	)
	(segment
		(start 330.603098 -223.475804)
		(end 330.603098 -223.391476)
		(width 0.088646)
		(layer "In11.Cu")
		(net "M_D_CPU0_SB_DQS_DP<8>")
	)
	(segment
		(start 339.56117 -227.155756)
		(end 339.553042 -227.160582)
		(width 0.088646)
		(layer "In11.Cu")
		(net "M_D_CPU0_SB_DQS_DP<8>")
	)
	(segment
		(start 299.522642 -198.006208)
		(end 299.258482 -197.742048)
		(width 0.18288)
		(layer "In11.Cu")
		(net "M_D_CPU0_SB_DQS_DP<8>")
	)
	(segment
		(start 276.097746 -197.404228)
		(end 275.745702 -197.62724)
		(width 0.18288)
		(layer "In11.Cu")
		(net "M_D_CPU0_SB_DQS_DP<8>")
	)
	(segment
		(start 345.757246 -228.139752)
		(end 345.765374 -228.13518)
		(width 0.088646)
		(layer "In11.Cu")
		(net "M_D_CPU0_SB_DQS_DP<8>")
	)
	(segment
		(start 310.610504 -198.07555)
		(end 307.868828 -198.07555)
		(width 0.18288)
		(layer "In11.Cu")
		(net "M_D_CPU0_SB_DQS_DP<8>")
	)
	(segment
		(start 345.762834 -228.781356)
		(end 345.757246 -228.778308)
		(width 0.088646)
		(layer "In11.Cu")
		(net "M_D_CPU0_SB_DQS_DP<8>")
	)
	(segment
		(start 298.810426 -197.742048)
		(end 298.491148 -198.061326)
		(width 0.18288)
		(layer "In11.Cu")
		(net "M_D_CPU0_SB_DQS_DP<8>")
	)
	(segment
		(start 298.491148 -198.061326)
		(end 297.907964 -198.061326)
		(width 0.18288)
		(layer "In11.Cu")
		(net "M_D_CPU0_SB_DQS_DP<8>")
	)
	(segment
		(start 332.998064 -225.51898)
		(end 332.983332 -225.527616)
		(width 0.088646)
		(layer "In11.Cu")
		(net "M_D_CPU0_SB_DQS_DP<8>")
	)
	(segment
		(start 345.766136 -228.783388)
		(end 345.765374 -228.78288)
		(width 0.088646)
		(layer "In11.Cu")
		(net "M_D_CPU0_SB_DQS_DP<8>")
	)
	(segment
		(start 271.80413 -198.243444)
		(end 270.439388 -199.608186)
		(width 0.18288)
		(layer "In11.Cu")
		(net "M_D_CPU0_SB_DQS_DP<8>")
	)
	(segment
		(start 269.68196 -199.298814)
		(end 269.111476 -199.298814)
		(width 0.18288)
		(layer "In11.Cu")
		(net "M_D_CPU0_SB_DQS_DP<8>")
	)
	(segment
		(start 276.96033 -197.404228)
		(end 276.097746 -197.404228)
		(width 0.18288)
		(layer "In11.Cu")
		(net "M_D_CPU0_SB_DQS_DP<8>")
	)
	(segment
		(start 273.655282 -198.642732)
		(end 272.542 -198.243444)
		(width 0.18288)
		(layer "In11.Cu")
		(net "M_D_CPU0_SB_DQS_DP<8>")
	)
	(segment
		(start 280.30424 -197.144132)
		(end 280.051002 -196.890894)
		(width 0.18288)
		(layer "In11.Cu")
		(net "M_D_CPU0_SB_DQS_DP<8>")
	)
	(segment
		(start 313.662314 -202.616816)
		(end 312.755026 -200.220072)
		(width 0.18288)
		(layer "In11.Cu")
		(net "M_D_CPU0_SB_DQS_DP<8>")
	)
	(segment
		(start 294.70096 -196.891148)
		(end 294.426386 -197.165722)
		(width 0.18288)
		(layer "In11.Cu")
		(net "M_D_CPU0_SB_DQS_DP<8>")
	)
	(segment
		(start 303.415192 -197.37324)
		(end 302.782224 -198.006208)
		(width 0.18288)
		(layer "In11.Cu")
		(net "M_D_CPU0_SB_DQS_DP<8>")
	)
	(segment
		(start 336.180684 -226.83978)
		(end 336.180684 -226.821238)
		(width 0.088646)
		(layer "In11.Cu")
		(net "M_D_CPU0_SB_DQS_DP<8>")
	)
	(segment
		(start 270.439388 -199.608186)
		(end 269.991332 -199.608186)
		(width 0.18288)
		(layer "In11.Cu")
		(net "M_D_CPU0_SB_DQS_DP<8>")
	)
	(segment
		(start 332.796134 -225.578416)
		(end 332.381352 -225.578416)
		(width 0.088646)
		(layer "In11.Cu")
		(net "M_D_CPU0_SB_DQS_DP<8>")
	)
	(segment
		(start 345.765374 -228.78288)
		(end 345.762834 -228.781356)
		(width 0.088646)
		(layer "In11.Cu")
		(net "M_D_CPU0_SB_DQS_DP<8>")
	)
	(segment
		(start 302.782224 -198.006208)
		(end 299.522642 -198.006208)
		(width 0.18288)
		(layer "In11.Cu")
		(net "M_D_CPU0_SB_DQS_DP<8>")
	)
	(segment
		(start 289.016186 -197.294754)
		(end 288.304986 -198.005954)
		(width 0.18288)
		(layer "In11.Cu")
		(net "M_D_CPU0_SB_DQS_DP<8>")
	)
	(segment
		(start 282.620974 -197.633336)
		(end 281.440128 -197.144132)
		(width 0.18288)
		(layer "In11.Cu")
		(net "M_D_CPU0_SB_DQS_DP<8>")
	)
	(segment
		(start 279.31364 -197.20052)
		(end 278.57323 -197.20052)
		(width 0.18288)
		(layer "In11.Cu")
		(net "M_D_CPU0_SB_DQS_DP<8>")
	)
	(segment
		(start 334.877664 -225.51898)
		(end 334.862932 -225.527616)
		(width 0.088646)
		(layer "In11.Cu")
		(net "M_D_CPU0_SB_DQS_DP<8>")
	)
	(segment
		(start 281.440128 -197.144132)
		(end 280.30424 -197.144132)
		(width 0.18288)
		(layer "In11.Cu")
		(net "M_D_CPU0_SB_DQS_DP<8>")
	)
	(segment
		(start 293.094664 -197.817486)
		(end 292.359842 -197.817486)
		(width 0.18288)
		(layer "In11.Cu")
		(net "M_D_CPU0_SB_DQS_DP<8>")
	)
	(segment
		(start 277.956264 -197.817486)
		(end 277.373588 -197.817486)
		(width 0.18288)
		(layer "In11.Cu")
		(net "M_D_CPU0_SB_DQS_DP<8>")
	)
	(segment
		(start 312.755026 -200.220072)
		(end 310.610504 -198.07555)
		(width 0.18288)
		(layer "In11.Cu")
		(net "M_D_CPU0_SB_DQS_DP<8>")
	)
	(segment
		(start 332.063852 -224.936558)
		(end 330.603098 -223.475804)
		(width 0.088646)
		(layer "In11.Cu")
		(net "M_D_CPU0_SB_DQS_DP<8>")
	)
	(segment
		(start 335.898236 -226.341686)
		(end 335.889346 -226.336606)
		(width 0.088646)
		(layer "In11.Cu")
		(net "M_D_CPU0_SB_DQS_DP<8>")
	)
	(segment
		(start 288.304986 -198.005954)
		(end 284.417008 -198.005954)
		(width 0.18288)
		(layer "In11.Cu")
		(net "M_D_CPU0_SB_DQS_DP<8>")
	)
	(segment
		(start 269.111476 -199.298814)
		(end 268.829282 -199.01662)
		(width 0.18288)
		(layer "In11.Cu")
		(net "M_D_CPU0_SB_DQS_DP<8>")
	)
	(segment
		(start 345.768168 -227.156772)
		(end 345.765882 -227.155502)
		(width 0.088646)
		(layer "In11.Cu")
		(net "M_D_CPU0_SB_DQS_DP<8>")
	)
	(segment
		(start 337.320128 -227.162868)
		(end 337.307682 -227.155502)
		(width 0.088646)
		(layer "In11.Cu")
		(net "M_D_CPU0_SB_DQS_DP<8>")
	)
	(segment
		(start 283.024834 -198.03745)
		(end 282.620974 -197.633336)
		(width 0.18288)
		(layer "In11.Cu")
		(net "M_D_CPU0_SB_DQS_DP<8>")
	)
	(segment
		(start 345.765882 -227.155502)
		(end 345.75115 -227.146866)
		(width 0.088646)
		(layer "In11.Cu")
		(net "M_D_CPU0_SB_DQS_DP<8>")
	)
	(segment
		(start 299.258482 -197.742048)
		(end 298.810426 -197.742048)
		(width 0.18288)
		(layer "In11.Cu")
		(net "M_D_CPU0_SB_DQS_DP<8>")
	)
	(segment
		(start 346.048584 -229.285292)
		(end 346.048584 -229.26294)
		(width 0.088646)
		(layer "In11.Cu")
		(net "M_D_CPU0_SB_DQS_DP<8>")
	)
	(segment
		(start 269.991332 -199.608186)
		(end 269.68196 -199.298814)
		(width 0.18288)
		(layer "In11.Cu")
		(net "M_D_CPU0_SB_DQS_DP<8>")
	)
	(segment
		(start 296.999152 -197.152514)
		(end 295.408858 -197.152514)
		(width 0.18288)
		(layer "In11.Cu")
		(net "M_D_CPU0_SB_DQS_DP<8>")
	)
	(segment
		(start 297.907964 -198.061326)
		(end 296.999152 -197.152514)
		(width 0.18288)
		(layer "In11.Cu")
		(net "M_D_CPU0_SB_DQS_DP<8>")
	)
	(segment
		(start 338.259928 -227.162868)
		(end 338.248244 -227.155756)
		(width 0.088646)
		(layer "In11.Cu")
		(net "M_D_CPU0_SB_DQS_DP<8>")
	)
	(segment
		(start 275.315934 -197.913498)
		(end 274.5867 -198.642732)
		(width 0.18288)
		(layer "In11.Cu")
		(net "M_D_CPU0_SB_DQS_DP<8>")
	)
	(arc
		(start 335.710784 -226.003104)
		(mid 335.631643 -225.728481)
		(end 335.428336 -225.527616)
		(width 0.088646)
		(layer "In11.Cu")
		(net "M_D_CPU0_SB_DQS_DP<8>")
	)
	(arc
		(start 342.007444 -227.155756)
		(mid 341.724517 -227.079692)
		(end 341.441532 -227.155502)
		(width 0.088646)
		(layer "In11.Cu")
		(net "M_D_CPU0_SB_DQS_DP<8>")
	)
	(arc
		(start 348.39148 -230.000302)
		(mid 348.299358 -229.767402)
		(end 348.115636 -229.597204)
		(width 0.088646)
		(layer "In11.Cu")
		(net "M_D_CPU0_SB_DQS_DP<8>")
	)
	(arc
		(start 342.381332 -227.155502)
		(mid 342.201187 -227.205823)
		(end 342.019128 -227.162868)
		(width 0.088646)
		(layer "In11.Cu")
		(net "M_D_CPU0_SB_DQS_DP<8>")
	)
	(arc
		(start 335.889346 -226.336606)
		(mid 335.758432 -226.200246)
		(end 335.710784 -226.017328)
		(width 0.088646)
		(layer "In11.Cu")
		(net "M_D_CPU0_SB_DQS_DP<8>")
	)
	(arc
		(start 336.742278 -227.155502)
		(mid 336.55508 -227.205645)
		(end 336.367882 -227.155502)
		(width 0.088646)
		(layer "In11.Cu")
		(net "M_D_CPU0_SB_DQS_DP<8>")
	)
	(arc
		(start 333.923132 -225.527616)
		(mid 333.735934 -225.577759)
		(end 333.548736 -225.527616)
		(width 0.088646)
		(layer "In11.Cu")
		(net "M_D_CPU0_SB_DQS_DP<8>")
	)
	(arc
		(start 339.553042 -227.160582)
		(mid 339.369504 -227.205705)
		(end 339.187282 -227.155502)
		(width 0.088646)
		(layer "In11.Cu")
		(net "M_D_CPU0_SB_DQS_DP<8>")
	)
	(arc
		(start 335.428336 -225.527616)
		(mid 335.154107 -225.451691)
		(end 334.877664 -225.51898)
		(width 0.088646)
		(layer "In11.Cu")
		(net "M_D_CPU0_SB_DQS_DP<8>")
	)
	(arc
		(start 341.441532 -227.155502)
		(mid 341.261387 -227.205823)
		(end 341.079328 -227.162868)
		(width 0.088646)
		(layer "In11.Cu")
		(net "M_D_CPU0_SB_DQS_DP<8>")
	)
	(arc
		(start 346.597986 -229.60457)
		(mid 346.415926 -229.64759)
		(end 346.235782 -229.597204)
		(width 0.088646)
		(layer "In11.Cu")
		(net "M_D_CPU0_SB_DQS_DP<8>")
	)
	(arc
		(start 343.321132 -227.155502)
		(mid 343.140987 -227.205823)
		(end 342.958928 -227.162868)
		(width 0.088646)
		(layer "In11.Cu")
		(net "M_D_CPU0_SB_DQS_DP<8>")
	)
	(arc
		(start 345.757246 -228.778308)
		(mid 345.578649 -228.45903)
		(end 345.757246 -228.139752)
		(width 0.088646)
		(layer "In11.Cu")
		(net "M_D_CPU0_SB_DQS_DP<8>")
	)
	(arc
		(start 348.394274 -230.021384)
		(mid 348.392976 -230.01083)
		(end 348.39148 -230.000302)
		(width 0.088646)
		(layer "In11.Cu")
		(net "M_D_CPU0_SB_DQS_DP<8>")
	)
	(arc
		(start 338.248244 -227.155756)
		(mid 337.965317 -227.079692)
		(end 337.682332 -227.155502)
		(width 0.088646)
		(layer "In11.Cu")
		(net "M_D_CPU0_SB_DQS_DP<8>")
	)
	(arc
		(start 346.048584 -227.64496)
		(mid 345.974593 -227.365394)
		(end 345.771978 -227.159058)
		(width 0.088646)
		(layer "In11.Cu")
		(net "M_D_CPU0_SB_DQS_DP<8>")
	)
	(arc
		(start 347.175582 -229.597204)
		(mid 346.892597 -229.521428)
		(end 346.60967 -229.597458)
		(width 0.088646)
		(layer "In11.Cu")
		(net "M_D_CPU0_SB_DQS_DP<8>")
	)
	(arc
		(start 345.75115 -227.146866)
		(mid 345.474675 -227.079546)
		(end 345.200478 -227.155502)
		(width 0.088646)
		(layer "In11.Cu")
		(net "M_D_CPU0_SB_DQS_DP<8>")
	)
	(arc
		(start 348.115636 -229.597204)
		(mid 347.841437 -229.521369)
		(end 347.564964 -229.588568)
		(width 0.088646)
		(layer "In11.Cu")
		(net "M_D_CPU0_SB_DQS_DP<8>")
	)
	(arc
		(start 339.187282 -227.155502)
		(mid 338.904724 -227.079853)
		(end 338.622132 -227.155502)
		(width 0.088646)
		(layer "In11.Cu")
		(net "M_D_CPU0_SB_DQS_DP<8>")
	)
	(arc
		(start 347.550232 -229.597204)
		(mid 347.363034 -229.647347)
		(end 347.175836 -229.597204)
		(width 0.088646)
		(layer "In11.Cu")
		(net "M_D_CPU0_SB_DQS_DP<8>")
	)
	(arc
		(start 345.766136 -228.134672)
		(mid 345.968422 -227.935691)
		(end 346.048584 -227.663502)
		(width 0.088646)
		(layer "In11.Cu")
		(net "M_D_CPU0_SB_DQS_DP<8>")
	)
	(arc
		(start 338.622132 -227.155502)
		(mid 338.441987 -227.205823)
		(end 338.259928 -227.162868)
		(width 0.088646)
		(layer "In11.Cu")
		(net "M_D_CPU0_SB_DQS_DP<8>")
	)
	(arc
		(start 336.180684 -226.821238)
		(mid 336.102573 -226.544289)
		(end 335.898236 -226.341686)
		(width 0.088646)
		(layer "In11.Cu")
		(net "M_D_CPU0_SB_DQS_DP<8>")
	)
	(arc
		(start 334.488536 -225.527616)
		(mid 334.205834 -225.451874)
		(end 333.923132 -225.527616)
		(width 0.088646)
		(layer "In11.Cu")
		(net "M_D_CPU0_SB_DQS_DP<8>")
	)
	(arc
		(start 345.200478 -227.155502)
		(mid 345.01328 -227.205645)
		(end 344.826082 -227.155502)
		(width 0.088646)
		(layer "In11.Cu")
		(net "M_D_CPU0_SB_DQS_DP<8>")
	)
	(arc
		(start 334.862932 -225.527616)
		(mid 334.675734 -225.577759)
		(end 334.488536 -225.527616)
		(width 0.088646)
		(layer "In11.Cu")
		(net "M_D_CPU0_SB_DQS_DP<8>")
	)
	(arc
		(start 337.682332 -227.155502)
		(mid 337.502187 -227.205823)
		(end 337.320128 -227.162868)
		(width 0.088646)
		(layer "In11.Cu")
		(net "M_D_CPU0_SB_DQS_DP<8>")
	)
	(arc
		(start 344.260932 -227.155502)
		(mid 344.073624 -227.205645)
		(end 343.886282 -227.155502)
		(width 0.088646)
		(layer "In11.Cu")
		(net "M_D_CPU0_SB_DQS_DP<8>")
	)
	(arc
		(start 332.983332 -225.527616)
		(mid 332.893076 -225.565338)
		(end 332.796134 -225.578416)
		(width 0.088646)
		(layer "In11.Cu")
		(net "M_D_CPU0_SB_DQS_DP<8>")
	)
	(arc
		(start 346.048584 -229.26294)
		(mid 345.970473 -228.985991)
		(end 345.766136 -228.783388)
		(width 0.088646)
		(layer "In11.Cu")
		(net "M_D_CPU0_SB_DQS_DP<8>")
	)
	(arc
		(start 333.548736 -225.527616)
		(mid 333.274507 -225.451691)
		(end 332.998064 -225.51898)
		(width 0.088646)
		(layer "In11.Cu")
		(net "M_D_CPU0_SB_DQS_DP<8>")
	)
	(arc
		(start 344.815668 -227.149406)
		(mid 344.53749 -227.079683)
		(end 344.260932 -227.155502)
		(width 0.088646)
		(layer "In11.Cu")
		(net "M_D_CPU0_SB_DQS_DP<8>")
	)
	(arc
		(start 343.886282 -227.155502)
		(mid 343.603724 -227.079853)
		(end 343.321132 -227.155502)
		(width 0.088646)
		(layer "In11.Cu")
		(net "M_D_CPU0_SB_DQS_DP<8>")
	)
	(arc
		(start 341.067644 -227.155756)
		(mid 340.784861 -227.079819)
		(end 340.501986 -227.155502)
		(width 0.088646)
		(layer "In11.Cu")
		(net "M_D_CPU0_SB_DQS_DP<8>")
	)
	(arc
		(start 340.127336 -227.155756)
		(mid 339.84427 -227.079819)
		(end 339.56117 -227.155756)
		(width 0.088646)
		(layer "In11.Cu")
		(net "M_D_CPU0_SB_DQS_DP<8>")
	)
	(arc
		(start 337.29295 -227.146866)
		(mid 337.016475 -227.079546)
		(end 336.742278 -227.155502)
		(width 0.088646)
		(layer "In11.Cu")
		(net "M_D_CPU0_SB_DQS_DP<8>")
	)
	(arc
		(start 346.235782 -229.597204)
		(mid 346.10182 -229.465475)
		(end 346.048584 -229.285292)
		(width 0.088646)
		(layer "In11.Cu")
		(net "M_D_CPU0_SB_DQS_DP<8>")
	)
	(arc
		(start 336.367882 -227.155502)
		(mid 336.232949 -227.022148)
		(end 336.180684 -226.83978)
		(width 0.088646)
		(layer "In11.Cu")
		(net "M_D_CPU0_SB_DQS_DP<8>")
	)
	(arc
		(start 342.947244 -227.155756)
		(mid 342.664317 -227.079692)
		(end 342.381332 -227.155502)
		(width 0.088646)
		(layer "In11.Cu")
		(net "M_D_CPU0_SB_DQS_DP<8>")
	)
	(arc
		(start 340.501986 -227.155502)
		(mid 340.319653 -227.205737)
		(end 340.135972 -227.160582)
		(width 0.088646)
		(layer "In11.Cu")
		(net "M_D_CPU0_SB_DQS_DP<8>")
	)
	(segment
		(start 265.732768 -208.203038)
		(end 265.227816 -208.203038)
		(width 0.20066)
		(layer "F.Cu")
		(net "M_D_CPU0_SB_DQS_DP<7>")
	)
	(segment
		(start 262.746998 -207.941672)
		(end 262.505698 -207.941672)
		(width 0.101854)
		(layer "F.Cu")
		(net "M_D_CPU0_SB_DQS_DP<7>")
	)
	(segment
		(start 262.302752 -207.936084)
		(end 262.033258 -208.205578)
		(width 0.20066)
		(layer "F.Cu")
		(net "M_D_CPU0_SB_DQS_DP<7>")
	)
	(segment
		(start 345.483434 -233.06405)
		(end 345.483434 -232.528364)
		(width 0.20066)
		(layer "F.Cu")
		(net "M_D_CPU0_SB_DQS_DP<7>")
	)
	(segment
		(start 261.673086 -208.205578)
		(end 261.250684 -208.62798)
		(width 0.20066)
		(layer "F.Cu")
		(net "M_D_CPU0_SB_DQS_DP<7>")
	)
	(segment
		(start 266.368784 -208.62798)
		(end 265.732768 -208.203038)
		(width 0.20066)
		(layer "F.Cu")
		(net "M_D_CPU0_SB_DQS_DP<7>")
	)
	(segment
		(start 264.966704 -207.941926)
		(end 264.825226 -207.941926)
		(width 0.20066)
		(layer "F.Cu")
		(net "M_D_CPU0_SB_DQS_DP<7>")
	)
	(segment
		(start 262.50011 -207.936084)
		(end 262.302752 -207.936084)
		(width 0.20066)
		(layer "F.Cu")
		(net "M_D_CPU0_SB_DQS_DP<7>")
	)
	(segment
		(start 266.973304 -208.62798)
		(end 266.368784 -208.62798)
		(width 0.20066)
		(layer "F.Cu")
		(net "M_D_CPU0_SB_DQS_DP<7>")
	)
	(segment
		(start 260.91642 -208.62798)
		(end 260.655054 -208.366614)
		(width 0.20066)
		(layer "F.Cu")
		(net "M_D_CPU0_SB_DQS_DP<7>")
	)
	(segment
		(start 264.825226 -207.941926)
		(end 264.824972 -207.941672)
		(width 0.1016)
		(layer "F.Cu")
		(net "M_D_CPU0_SB_DQS_DP<7>")
	)
	(segment
		(start 345.48318 -233.064304)
		(end 345.483434 -233.06405)
		(width 0.20066)
		(layer "F.Cu")
		(net "M_D_CPU0_SB_DQS_DP<7>")
	)
	(segment
		(start 267.724382 -208.366614)
		(end 267.23467 -208.366614)
		(width 0.20066)
		(layer "F.Cu")
		(net "M_D_CPU0_SB_DQS_DP<7>")
	)
	(segment
		(start 262.505698 -207.941672)
		(end 262.50011 -207.936084)
		(width 0.101854)
		(layer "F.Cu")
		(net "M_D_CPU0_SB_DQS_DP<7>")
	)
	(segment
		(start 268.829282 -208.366614)
		(end 267.724382 -208.366614)
		(width 0.20066)
		(layer "F.Cu")
		(net "M_D_CPU0_SB_DQS_DP<7>")
	)
	(segment
		(start 262.033258 -208.205578)
		(end 261.673086 -208.205578)
		(width 0.20066)
		(layer "F.Cu")
		(net "M_D_CPU0_SB_DQS_DP<7>")
	)
	(segment
		(start 267.23467 -208.366614)
		(end 266.973304 -208.62798)
		(width 0.20066)
		(layer "F.Cu")
		(net "M_D_CPU0_SB_DQS_DP<7>")
	)
	(segment
		(start 265.227816 -208.203038)
		(end 264.966704 -207.941926)
		(width 0.20066)
		(layer "F.Cu")
		(net "M_D_CPU0_SB_DQS_DP<7>")
	)
	(segment
		(start 261.250684 -208.62798)
		(end 260.91642 -208.62798)
		(width 0.20066)
		(layer "F.Cu")
		(net "M_D_CPU0_SB_DQS_DP<7>")
	)
	(segment
		(start 260.655054 -208.366614)
		(end 260.180582 -208.366614)
		(width 0.20066)
		(layer "F.Cu")
		(net "M_D_CPU0_SB_DQS_DP<7>")
	)
	(segment
		(start 264.824972 -207.941672)
		(end 262.746998 -207.941672)
		(width 0.1016)
		(layer "F.Cu")
		(net "M_D_CPU0_SB_DQS_DP<7>")
	)
	(segment
		(start 322.871084 -225.21926)
		(end 322.871084 -222.435166)
		(width 0.18288)
		(layer "In6.Cu")
		(net "M_D_CPU0_SB_DQS_DP<7>")
	)
	(segment
		(start 342.946482 -232.038906)
		(end 342.936068 -232.03281)
		(width 0.088646)
		(layer "In6.Cu")
		(net "M_D_CPU0_SB_DQS_DP<7>")
	)
	(segment
		(start 338.247482 -232.038906)
		(end 338.245958 -232.038144)
		(width 0.088646)
		(layer "In6.Cu")
		(net "M_D_CPU0_SB_DQS_DP<7>")
	)
	(segment
		(start 284.155388 -207.091788)
		(end 283.69387 -207.091788)
		(width 0.18288)
		(layer "In6.Cu")
		(net "M_D_CPU0_SB_DQS_DP<7>")
	)
	(segment
		(start 273.377406 -208.04251)
		(end 272.602452 -208.817464)
		(width 0.18288)
		(layer "In6.Cu")
		(net "M_D_CPU0_SB_DQS_DP<7>")
	)
	(segment
		(start 342.006936 -232.038906)
		(end 341.996522 -232.03281)
		(width 0.088646)
		(layer "In6.Cu")
		(net "M_D_CPU0_SB_DQS_DP<7>")
	)
	(segment
		(start 345.483434 -232.528364)
		(end 345.170506 -232.528364)
		(width 0.088646)
		(layer "In6.Cu")
		(net "M_D_CPU0_SB_DQS_DP<7>")
	)
	(segment
		(start 330.655422 -228.407468)
		(end 330.595478 -228.347524)
		(width 0.088646)
		(layer "In6.Cu")
		(net "M_D_CPU0_SB_DQS_DP<7>")
	)
	(segment
		(start 330.95946 -228.407468)
		(end 330.655422 -228.407468)
		(width 0.088646)
		(layer "In6.Cu")
		(net "M_D_CPU0_SB_DQS_DP<7>")
	)
	(segment
		(start 297.234864 -208.20126)
		(end 295.402508 -208.20126)
		(width 0.18288)
		(layer "In6.Cu")
		(net "M_D_CPU0_SB_DQS_DP<7>")
	)
	(segment
		(start 269.873222 -208.817464)
		(end 269.688564 -208.632806)
		(width 0.18288)
		(layer "In6.Cu")
		(net "M_D_CPU0_SB_DQS_DP<7>")
	)
	(segment
		(start 311.995566 -210.73745)
		(end 311.497472 -210.73745)
		(width 0.18288)
		(layer "In6.Cu")
		(net "M_D_CPU0_SB_DQS_DP<7>")
	)
	(segment
		(start 336.287364 -231.2162)
		(end 336.272632 -231.224836)
		(width 0.088646)
		(layer "In6.Cu")
		(net "M_D_CPU0_SB_DQS_DP<7>")
	)
	(segment
		(start 333.831184 -230.900732)
		(end 333.831184 -230.890826)
		(width 0.088646)
		(layer "In6.Cu")
		(net "M_D_CPU0_SB_DQS_DP<7>")
	)
	(segment
		(start 337.227164 -231.2162)
		(end 337.212432 -231.224836)
		(width 0.088646)
		(layer "In6.Cu")
		(net "M_D_CPU0_SB_DQS_DP<7>")
	)
	(segment
		(start 314.234068 -214.206836)
		(end 313.70905 -213.681818)
		(width 0.18288)
		(layer "In6.Cu")
		(net "M_D_CPU0_SB_DQS_DP<7>")
	)
	(segment
		(start 283.443426 -207.342232)
		(end 282.579064 -207.342232)
		(width 0.18288)
		(layer "In6.Cu")
		(net "M_D_CPU0_SB_DQS_DP<7>")
	)
	(segment
		(start 332.253844 -230.335328)
		(end 331.534262 -229.615746)
		(width 0.088646)
		(layer "In6.Cu")
		(net "M_D_CPU0_SB_DQS_DP<7>")
	)
	(segment
		(start 338.06003 -231.714548)
		(end 338.06003 -231.69245)
		(width 0.088646)
		(layer "In6.Cu")
		(net "M_D_CPU0_SB_DQS_DP<7>")
	)
	(segment
		(start 269.095474 -208.632806)
		(end 268.829282 -208.366614)
		(width 0.18288)
		(layer "In6.Cu")
		(net "M_D_CPU0_SB_DQS_DP<7>")
	)
	(segment
		(start 338.245958 -232.038144)
		(end 338.238592 -232.033826)
		(width 0.088646)
		(layer "In6.Cu")
		(net "M_D_CPU0_SB_DQS_DP<7>")
	)
	(segment
		(start 282.579064 -207.342232)
		(end 281.732736 -208.18856)
		(width 0.18288)
		(layer "In6.Cu")
		(net "M_D_CPU0_SB_DQS_DP<7>")
	)
	(segment
		(start 292.264338 -207.62849)
		(end 291.844476 -208.048352)
		(width 0.18288)
		(layer "In6.Cu")
		(net "M_D_CPU0_SB_DQS_DP<7>")
	)
	(segment
		(start 295.402508 -208.20126)
		(end 295.14292 -207.941672)
		(width 0.18288)
		(layer "In6.Cu")
		(net "M_D_CPU0_SB_DQS_DP<7>")
	)
	(segment
		(start 291.844476 -208.048352)
		(end 288.621216 -208.048352)
		(width 0.18288)
		(layer "In6.Cu")
		(net "M_D_CPU0_SB_DQS_DP<7>")
	)
	(segment
		(start 295.14292 -207.941672)
		(end 294.681402 -207.941672)
		(width 0.18288)
		(layer "In6.Cu")
		(net "M_D_CPU0_SB_DQS_DP<7>")
	)
	(segment
		(start 332.32598 -230.335328)
		(end 332.253844 -230.335328)
		(width 0.088646)
		(layer "In6.Cu")
		(net "M_D_CPU0_SB_DQS_DP<7>")
	)
	(segment
		(start 335.346548 -231.216962)
		(end 335.332832 -231.22509)
		(width 0.088646)
		(layer "In6.Cu")
		(net "M_D_CPU0_SB_DQS_DP<7>")
	)
	(segment
		(start 302.583088 -209.326226)
		(end 300.609 -207.352138)
		(width 0.18288)
		(layer "In6.Cu")
		(net "M_D_CPU0_SB_DQS_DP<7>")
	)
	(segment
		(start 277.696422 -208.906364)
		(end 276.95906 -208.60131)
		(width 0.18288)
		(layer "In6.Cu")
		(net "M_D_CPU0_SB_DQS_DP<7>")
	)
	(segment
		(start 345.170506 -232.528364)
		(end 345.104974 -232.462832)
		(width 0.088646)
		(layer "In6.Cu")
		(net "M_D_CPU0_SB_DQS_DP<7>")
	)
	(segment
		(start 330.57211 -228.347524)
		(end 325.999348 -228.347524)
		(width 0.18288)
		(layer "In6.Cu")
		(net "M_D_CPU0_SB_DQS_DP<7>")
	)
	(segment
		(start 276.40026 -208.04251)
		(end 273.377406 -208.04251)
		(width 0.18288)
		(layer "In6.Cu")
		(net "M_D_CPU0_SB_DQS_DP<7>")
	)
	(segment
		(start 278.769064 -208.192116)
		(end 278.054816 -208.906364)
		(width 0.18288)
		(layer "In6.Cu")
		(net "M_D_CPU0_SB_DQS_DP<7>")
	)
	(segment
		(start 280.302208 -208.18856)
		(end 280.05532 -207.941672)
		(width 0.18288)
		(layer "In6.Cu")
		(net "M_D_CPU0_SB_DQS_DP<7>")
	)
	(segment
		(start 287.923224 -207.35036)
		(end 284.41396 -207.35036)
		(width 0.18288)
		(layer "In6.Cu")
		(net "M_D_CPU0_SB_DQS_DP<7>")
	)
	(segment
		(start 343.886282 -232.038906)
		(end 343.87155 -232.03027)
		(width 0.088646)
		(layer "In6.Cu")
		(net "M_D_CPU0_SB_DQS_DP<7>")
	)
	(segment
		(start 331.534262 -228.98227)
		(end 330.95946 -228.407468)
		(width 0.088646)
		(layer "In6.Cu")
		(net "M_D_CPU0_SB_DQS_DP<7>")
	)
	(segment
		(start 281.732736 -208.18856)
		(end 280.302208 -208.18856)
		(width 0.18288)
		(layer "In6.Cu")
		(net "M_D_CPU0_SB_DQS_DP<7>")
	)
	(segment
		(start 279.343358 -208.192116)
		(end 278.769064 -208.192116)
		(width 0.18288)
		(layer "In6.Cu")
		(net "M_D_CPU0_SB_DQS_DP<7>")
	)
	(segment
		(start 272.602452 -208.817464)
		(end 269.873222 -208.817464)
		(width 0.18288)
		(layer "In6.Cu")
		(net "M_D_CPU0_SB_DQS_DP<7>")
	)
	(segment
		(start 331.534262 -229.615746)
		(end 331.534262 -228.98227)
		(width 0.088646)
		(layer "In6.Cu")
		(net "M_D_CPU0_SB_DQS_DP<7>")
	)
	(segment
		(start 288.621216 -208.048352)
		(end 287.923224 -207.35036)
		(width 0.18288)
		(layer "In6.Cu")
		(net "M_D_CPU0_SB_DQS_DP<7>")
	)
	(segment
		(start 276.95906 -208.60131)
		(end 276.40026 -208.04251)
		(width 0.18288)
		(layer "In6.Cu")
		(net "M_D_CPU0_SB_DQS_DP<7>")
	)
	(segment
		(start 298.78147 -207.091788)
		(end 298.518834 -207.354424)
		(width 0.18288)
		(layer "In6.Cu")
		(net "M_D_CPU0_SB_DQS_DP<7>")
	)
	(segment
		(start 314.642754 -214.206836)
		(end 314.234068 -214.206836)
		(width 0.18288)
		(layer "In6.Cu")
		(net "M_D_CPU0_SB_DQS_DP<7>")
	)
	(segment
		(start 293.360856 -207.62849)
		(end 292.264338 -207.62849)
		(width 0.18288)
		(layer "In6.Cu")
		(net "M_D_CPU0_SB_DQS_DP<7>")
	)
	(segment
		(start 344.826082 -232.038906)
		(end 344.81135 -232.03027)
		(width 0.088646)
		(layer "In6.Cu")
		(net "M_D_CPU0_SB_DQS_DP<7>")
	)
	(segment
		(start 284.41396 -207.35036)
		(end 284.155388 -207.091788)
		(width 0.18288)
		(layer "In6.Cu")
		(net "M_D_CPU0_SB_DQS_DP<7>")
	)
	(segment
		(start 279.593802 -207.941672)
		(end 279.343358 -208.192116)
		(width 0.18288)
		(layer "In6.Cu")
		(net "M_D_CPU0_SB_DQS_DP<7>")
	)
	(segment
		(start 311.497472 -210.73745)
		(end 310.793638 -210.033616)
		(width 0.18288)
		(layer "In6.Cu")
		(net "M_D_CPU0_SB_DQS_DP<7>")
	)
	(segment
		(start 341.066882 -232.038906)
		(end 341.05215 -232.03027)
		(width 0.088646)
		(layer "In6.Cu")
		(net "M_D_CPU0_SB_DQS_DP<7>")
	)
	(segment
		(start 269.688564 -208.632806)
		(end 269.095474 -208.632806)
		(width 0.18288)
		(layer "In6.Cu")
		(net "M_D_CPU0_SB_DQS_DP<7>")
	)
	(segment
		(start 283.69387 -207.091788)
		(end 283.443426 -207.342232)
		(width 0.18288)
		(layer "In6.Cu")
		(net "M_D_CPU0_SB_DQS_DP<7>")
	)
	(segment
		(start 330.595478 -228.347524)
		(end 330.57211 -228.347524)
		(width 0.088646)
		(layer "In6.Cu")
		(net "M_D_CPU0_SB_DQS_DP<7>")
	)
	(segment
		(start 278.054816 -208.906364)
		(end 277.696422 -208.906364)
		(width 0.18288)
		(layer "In6.Cu")
		(net "M_D_CPU0_SB_DQS_DP<7>")
	)
	(segment
		(start 344.832178 -232.042462)
		(end 344.826844 -232.039414)
		(width 0.088646)
		(layer "In6.Cu")
		(net "M_D_CPU0_SB_DQS_DP<7>")
	)
	(segment
		(start 293.924482 -208.192116)
		(end 293.360856 -207.62849)
		(width 0.18288)
		(layer "In6.Cu")
		(net "M_D_CPU0_SB_DQS_DP<7>")
	)
	(segment
		(start 310.793638 -210.033616)
		(end 307.88483 -210.033616)
		(width 0.18288)
		(layer "In6.Cu")
		(net "M_D_CPU0_SB_DQS_DP<7>")
	)
	(segment
		(start 339.187282 -232.038906)
		(end 339.17255 -232.03027)
		(width 0.088646)
		(layer "In6.Cu")
		(net "M_D_CPU0_SB_DQS_DP<7>")
	)
	(segment
		(start 298.0817 -207.354424)
		(end 297.234864 -208.20126)
		(width 0.18288)
		(layer "In6.Cu")
		(net "M_D_CPU0_SB_DQS_DP<7>")
	)
	(segment
		(start 325.999348 -228.347524)
		(end 322.871084 -225.21926)
		(width 0.18288)
		(layer "In6.Cu")
		(net "M_D_CPU0_SB_DQS_DP<7>")
	)
	(segment
		(start 307.17744 -209.326226)
		(end 302.583088 -209.326226)
		(width 0.18288)
		(layer "In6.Cu")
		(net "M_D_CPU0_SB_DQS_DP<7>")
	)
	(segment
		(start 294.430958 -208.192116)
		(end 293.924482 -208.192116)
		(width 0.18288)
		(layer "In6.Cu")
		(net "M_D_CPU0_SB_DQS_DP<7>")
	)
	(segment
		(start 313.70905 -213.681818)
		(end 312.838084 -211.579968)
		(width 0.18288)
		(layer "In6.Cu")
		(net "M_D_CPU0_SB_DQS_DP<7>")
	)
	(segment
		(start 344.826844 -232.039414)
		(end 344.826082 -232.038906)
		(width 0.088646)
		(layer "In6.Cu")
		(net "M_D_CPU0_SB_DQS_DP<7>")
	)
	(segment
		(start 312.838084 -211.579968)
		(end 311.995566 -210.73745)
		(width 0.18288)
		(layer "In6.Cu")
		(net "M_D_CPU0_SB_DQS_DP<7>")
	)
	(segment
		(start 299.242988 -207.091788)
		(end 298.78147 -207.091788)
		(width 0.18288)
		(layer "In6.Cu")
		(net "M_D_CPU0_SB_DQS_DP<7>")
	)
	(segment
		(start 294.681402 -207.941672)
		(end 294.430958 -208.192116)
		(width 0.18288)
		(layer "In6.Cu")
		(net "M_D_CPU0_SB_DQS_DP<7>")
	)
	(segment
		(start 322.871084 -222.435166)
		(end 314.642754 -214.206836)
		(width 0.18288)
		(layer "In6.Cu")
		(net "M_D_CPU0_SB_DQS_DP<7>")
	)
	(segment
		(start 300.609 -207.352138)
		(end 299.503338 -207.352138)
		(width 0.18288)
		(layer "In6.Cu")
		(net "M_D_CPU0_SB_DQS_DP<7>")
	)
	(segment
		(start 299.503338 -207.352138)
		(end 299.242988 -207.091788)
		(width 0.18288)
		(layer "In6.Cu")
		(net "M_D_CPU0_SB_DQS_DP<7>")
	)
	(segment
		(start 298.518834 -207.354424)
		(end 298.0817 -207.354424)
		(width 0.18288)
		(layer "In6.Cu")
		(net "M_D_CPU0_SB_DQS_DP<7>")
	)
	(segment
		(start 280.05532 -207.941672)
		(end 279.593802 -207.941672)
		(width 0.18288)
		(layer "In6.Cu")
		(net "M_D_CPU0_SB_DQS_DP<7>")
	)
	(segment
		(start 307.88483 -210.033616)
		(end 307.17744 -209.326226)
		(width 0.18288)
		(layer "In6.Cu")
		(net "M_D_CPU0_SB_DQS_DP<7>")
	)
	(arc
		(start 341.996522 -232.03281)
		(mid 341.71809 -231.962964)
		(end 341.441278 -232.038906)
		(width 0.088646)
		(layer "In6.Cu")
		(net "M_D_CPU0_SB_DQS_DP<7>")
	)
	(arc
		(start 344.260678 -232.038906)
		(mid 344.07348 -232.089049)
		(end 343.886282 -232.038906)
		(width 0.088646)
		(layer "In6.Cu")
		(net "M_D_CPU0_SB_DQS_DP<7>")
	)
	(arc
		(start 344.81135 -232.03027)
		(mid 344.534875 -231.96295)
		(end 344.260678 -232.038906)
		(width 0.088646)
		(layer "In6.Cu")
		(net "M_D_CPU0_SB_DQS_DP<7>")
	)
	(arc
		(start 342.936068 -232.03281)
		(mid 342.65789 -231.963087)
		(end 342.381332 -232.038906)
		(width 0.088646)
		(layer "In6.Cu")
		(net "M_D_CPU0_SB_DQS_DP<7>")
	)
	(arc
		(start 341.05215 -232.03027)
		(mid 340.775675 -231.96295)
		(end 340.501478 -232.038906)
		(width 0.088646)
		(layer "In6.Cu")
		(net "M_D_CPU0_SB_DQS_DP<7>")
	)
	(arc
		(start 336.838036 -231.224836)
		(mid 336.563807 -231.148911)
		(end 336.287364 -231.2162)
		(width 0.088646)
		(layer "In6.Cu")
		(net "M_D_CPU0_SB_DQS_DP<7>")
	)
	(arc
		(start 338.238592 -232.033826)
		(mid 338.107678 -231.897466)
		(end 338.06003 -231.714548)
		(width 0.088646)
		(layer "In6.Cu")
		(net "M_D_CPU0_SB_DQS_DP<7>")
	)
	(arc
		(start 336.272632 -231.224836)
		(mid 336.085434 -231.274979)
		(end 335.898236 -231.224836)
		(width 0.088646)
		(layer "In6.Cu")
		(net "M_D_CPU0_SB_DQS_DP<7>")
	)
	(arc
		(start 338.06003 -231.69245)
		(mid 337.775599 -231.223549)
		(end 337.227164 -231.2162)
		(width 0.088646)
		(layer "In6.Cu")
		(net "M_D_CPU0_SB_DQS_DP<7>")
	)
	(arc
		(start 334.958436 -231.22509)
		(mid 334.675734 -231.149314)
		(end 334.393032 -231.22509)
		(width 0.088646)
		(layer "In6.Cu")
		(net "M_D_CPU0_SB_DQS_DP<7>")
	)
	(arc
		(start 341.441278 -232.038906)
		(mid 341.25408 -232.089049)
		(end 341.066882 -232.038906)
		(width 0.088646)
		(layer "In6.Cu")
		(net "M_D_CPU0_SB_DQS_DP<7>")
	)
	(arc
		(start 339.561678 -232.038906)
		(mid 339.37448 -232.089049)
		(end 339.187282 -232.038906)
		(width 0.088646)
		(layer "In6.Cu")
		(net "M_D_CPU0_SB_DQS_DP<7>")
	)
	(arc
		(start 335.332832 -231.22509)
		(mid 335.145634 -231.275233)
		(end 334.958436 -231.22509)
		(width 0.088646)
		(layer "In6.Cu")
		(net "M_D_CPU0_SB_DQS_DP<7>")
	)
	(arc
		(start 339.17255 -232.03027)
		(mid 338.896075 -231.96295)
		(end 338.621878 -232.038906)
		(width 0.088646)
		(layer "In6.Cu")
		(net "M_D_CPU0_SB_DQS_DP<7>")
	)
	(arc
		(start 337.212432 -231.224836)
		(mid 337.025234 -231.274979)
		(end 336.838036 -231.224836)
		(width 0.088646)
		(layer "In6.Cu")
		(net "M_D_CPU0_SB_DQS_DP<7>")
	)
	(arc
		(start 334.393032 -231.22509)
		(mid 334.018557 -231.225044)
		(end 333.831184 -230.900732)
		(width 0.088646)
		(layer "In6.Cu")
		(net "M_D_CPU0_SB_DQS_DP<7>")
	)
	(arc
		(start 332.983332 -230.411274)
		(mid 332.796134 -230.461417)
		(end 332.608936 -230.411274)
		(width 0.088646)
		(layer "In6.Cu")
		(net "M_D_CPU0_SB_DQS_DP<7>")
	)
	(arc
		(start 343.87155 -232.03027)
		(mid 343.595075 -231.96295)
		(end 343.320878 -232.038906)
		(width 0.088646)
		(layer "In6.Cu")
		(net "M_D_CPU0_SB_DQS_DP<7>")
	)
	(arc
		(start 342.381332 -232.038906)
		(mid 342.194134 -232.089049)
		(end 342.006936 -232.038906)
		(width 0.088646)
		(layer "In6.Cu")
		(net "M_D_CPU0_SB_DQS_DP<7>")
	)
	(arc
		(start 333.831184 -230.890826)
		(mid 333.544309 -230.408741)
		(end 332.983332 -230.411274)
		(width 0.088646)
		(layer "In6.Cu")
		(net "M_D_CPU0_SB_DQS_DP<7>")
	)
	(arc
		(start 338.621878 -232.038906)
		(mid 338.43468 -232.089049)
		(end 338.247482 -232.038906)
		(width 0.088646)
		(layer "In6.Cu")
		(net "M_D_CPU0_SB_DQS_DP<7>")
	)
	(arc
		(start 343.320878 -232.038906)
		(mid 343.13368 -232.089049)
		(end 342.946482 -232.038906)
		(width 0.088646)
		(layer "In6.Cu")
		(net "M_D_CPU0_SB_DQS_DP<7>")
	)
	(arc
		(start 335.898236 -231.224836)
		(mid 335.623409 -231.149025)
		(end 335.346548 -231.216962)
		(width 0.088646)
		(layer "In6.Cu")
		(net "M_D_CPU0_SB_DQS_DP<7>")
	)
	(arc
		(start 345.104974 -232.462832)
		(mid 345.01773 -232.220744)
		(end 344.832178 -232.042462)
		(width 0.088646)
		(layer "In6.Cu")
		(net "M_D_CPU0_SB_DQS_DP<7>")
	)
	(arc
		(start 340.501478 -232.038906)
		(mid 340.31428 -232.089049)
		(end 340.127082 -232.038906)
		(width 0.088646)
		(layer "In6.Cu")
		(net "M_D_CPU0_SB_DQS_DP<7>")
	)
	(arc
		(start 340.127082 -232.038906)
		(mid 339.84438 -231.96313)
		(end 339.561678 -232.038906)
		(width 0.088646)
		(layer "In6.Cu")
		(net "M_D_CPU0_SB_DQS_DP<7>")
	)
	(arc
		(start 332.608936 -230.411274)
		(mid 332.472464 -230.354651)
		(end 332.32598 -230.335328)
		(width 0.088646)
		(layer "In6.Cu")
		(net "M_D_CPU0_SB_DQS_DP<7>")
	)
	(segment
		(start 348.772734 -234.97032)
		(end 348.77248 -234.970066)
		(width 0.20066)
		(layer "F.Cu")
		(net "M_D_CPU0_SB_DQS_DP<6>")
	)
	(segment
		(start 260.91642 -217.977974)
		(end 260.655054 -217.716608)
		(width 0.20066)
		(layer "F.Cu")
		(net "M_D_CPU0_SB_DQS_DP<6>")
	)
	(segment
		(start 262.033258 -217.555572)
		(end 261.673086 -217.555572)
		(width 0.20066)
		(layer "F.Cu")
		(net "M_D_CPU0_SB_DQS_DP<6>")
	)
	(segment
		(start 262.505698 -217.291666)
		(end 262.50011 -217.286078)
		(width 0.101854)
		(layer "F.Cu")
		(net "M_D_CPU0_SB_DQS_DP<6>")
	)
	(segment
		(start 266.973304 -217.977974)
		(end 266.368784 -217.977974)
		(width 0.20066)
		(layer "F.Cu")
		(net "M_D_CPU0_SB_DQS_DP<6>")
	)
	(segment
		(start 265.227816 -217.553032)
		(end 264.966704 -217.29192)
		(width 0.20066)
		(layer "F.Cu")
		(net "M_D_CPU0_SB_DQS_DP<6>")
	)
	(segment
		(start 268.829282 -217.716608)
		(end 267.724382 -217.716608)
		(width 0.20066)
		(layer "F.Cu")
		(net "M_D_CPU0_SB_DQS_DP<6>")
	)
	(segment
		(start 267.724382 -217.716608)
		(end 267.23467 -217.716608)
		(width 0.20066)
		(layer "F.Cu")
		(net "M_D_CPU0_SB_DQS_DP<6>")
	)
	(segment
		(start 261.250684 -217.977974)
		(end 260.91642 -217.977974)
		(width 0.20066)
		(layer "F.Cu")
		(net "M_D_CPU0_SB_DQS_DP<6>")
	)
	(segment
		(start 264.824972 -217.291666)
		(end 262.746998 -217.291666)
		(width 0.1016)
		(layer "F.Cu")
		(net "M_D_CPU0_SB_DQS_DP<6>")
	)
	(segment
		(start 262.50011 -217.286078)
		(end 262.302752 -217.286078)
		(width 0.20066)
		(layer "F.Cu")
		(net "M_D_CPU0_SB_DQS_DP<6>")
	)
	(segment
		(start 260.655054 -217.716608)
		(end 260.180582 -217.716608)
		(width 0.20066)
		(layer "F.Cu")
		(net "M_D_CPU0_SB_DQS_DP<6>")
	)
	(segment
		(start 348.772734 -235.506006)
		(end 348.772734 -234.97032)
		(width 0.20066)
		(layer "F.Cu")
		(net "M_D_CPU0_SB_DQS_DP<6>")
	)
	(segment
		(start 265.732768 -217.553032)
		(end 265.227816 -217.553032)
		(width 0.20066)
		(layer "F.Cu")
		(net "M_D_CPU0_SB_DQS_DP<6>")
	)
	(segment
		(start 262.302752 -217.286078)
		(end 262.033258 -217.555572)
		(width 0.20066)
		(layer "F.Cu")
		(net "M_D_CPU0_SB_DQS_DP<6>")
	)
	(segment
		(start 267.23467 -217.716608)
		(end 266.973304 -217.977974)
		(width 0.20066)
		(layer "F.Cu")
		(net "M_D_CPU0_SB_DQS_DP<6>")
	)
	(segment
		(start 262.746998 -217.291666)
		(end 262.505698 -217.291666)
		(width 0.101854)
		(layer "F.Cu")
		(net "M_D_CPU0_SB_DQS_DP<6>")
	)
	(segment
		(start 261.673086 -217.555572)
		(end 261.250684 -217.977974)
		(width 0.20066)
		(layer "F.Cu")
		(net "M_D_CPU0_SB_DQS_DP<6>")
	)
	(segment
		(start 264.825226 -217.29192)
		(end 264.824972 -217.291666)
		(width 0.1016)
		(layer "F.Cu")
		(net "M_D_CPU0_SB_DQS_DP<6>")
	)
	(segment
		(start 264.966704 -217.29192)
		(end 264.825226 -217.29192)
		(width 0.20066)
		(layer "F.Cu")
		(net "M_D_CPU0_SB_DQS_DP<6>")
	)
	(segment
		(start 266.368784 -217.977974)
		(end 265.732768 -217.553032)
		(width 0.20066)
		(layer "F.Cu")
		(net "M_D_CPU0_SB_DQS_DP<6>")
	)
	(segment
		(start 342.289384 -234.15625)
		(end 342.289384 -234.155996)
		(width 0.088646)
		(layer "In11.Cu")
		(net "M_D_CPU0_SB_DQS_DP<6>")
	)
	(segment
		(start 295.121838 -210.490816)
		(end 294.696134 -210.490816)
		(width 0.18288)
		(layer "In11.Cu")
		(net "M_D_CPU0_SB_DQS_DP<6>")
	)
	(segment
		(start 337.320128 -232.046272)
		(end 337.308444 -232.03916)
		(width 0.088646)
		(layer "In11.Cu")
		(net "M_D_CPU0_SB_DQS_DP<6>")
	)
	(segment
		(start 348.459552 -234.970066)
		(end 348.394274 -234.904788)
		(width 0.088646)
		(layer "In11.Cu")
		(net "M_D_CPU0_SB_DQS_DP<6>")
	)
	(segment
		(start 330.396596 -230.30307)
		(end 330.336906 -230.24338)
		(width 0.088646)
		(layer "In11.Cu")
		(net "M_D_CPU0_SB_DQS_DP<6>")
	)
	(segment
		(start 299.230542 -209.641948)
		(end 298.782486 -209.641948)
		(width 0.18288)
		(layer "In11.Cu")
		(net "M_D_CPU0_SB_DQS_DP<6>")
	)
	(segment
		(start 284.414468 -209.933794)
		(end 284.120082 -209.639408)
		(width 0.18288)
		(layer "In11.Cu")
		(net "M_D_CPU0_SB_DQS_DP<6>")
	)
	(segment
		(start 331.573632 -231.161336)
		(end 330.715366 -230.30307)
		(width 0.088646)
		(layer "In11.Cu")
		(net "M_D_CPU0_SB_DQS_DP<6>")
	)
	(segment
		(start 341.066882 -232.038906)
		(end 341.05215 -232.03027)
		(width 0.088646)
		(layer "In11.Cu")
		(net "M_D_CPU0_SB_DQS_DP<6>")
	)
	(segment
		(start 283.418026 -209.939128)
		(end 282.634436 -209.939128)
		(width 0.18288)
		(layer "In11.Cu")
		(net "M_D_CPU0_SB_DQS_DP<6>")
	)
	(segment
		(start 275.954998 -210.814412)
		(end 274.534376 -212.23478)
		(width 0.18288)
		(layer "In11.Cu")
		(net "M_D_CPU0_SB_DQS_DP<6>")
	)
	(segment
		(start 342.006682 -233.666538)
		(end 341.997792 -233.661458)
		(width 0.088646)
		(layer "In11.Cu")
		(net "M_D_CPU0_SB_DQS_DP<6>")
	)
	(segment
		(start 269.826486 -218.209876)
		(end 269.601442 -217.984832)
		(width 0.18288)
		(layer "In11.Cu")
		(net "M_D_CPU0_SB_DQS_DP<6>")
	)
	(segment
		(start 336.368644 -232.03916)
		(end 336.367882 -232.038906)
		(width 0.088646)
		(layer "In11.Cu")
		(net "M_D_CPU0_SB_DQS_DP<6>")
	)
	(segment
		(start 338.259928 -232.046272)
		(end 338.248244 -232.03916)
		(width 0.088646)
		(layer "In11.Cu")
		(net "M_D_CPU0_SB_DQS_DP<6>")
	)
	(segment
		(start 289.15487 -210.827112)
		(end 286.998918 -209.933794)
		(width 0.18288)
		(layer "In11.Cu")
		(net "M_D_CPU0_SB_DQS_DP<6>")
	)
	(segment
		(start 276.414738 -210.814412)
		(end 275.954998 -210.814412)
		(width 0.18288)
		(layer "In11.Cu")
		(net "M_D_CPU0_SB_DQS_DP<6>")
	)
	(segment
		(start 283.717746 -209.639408)
		(end 283.418026 -209.939128)
		(width 0.18288)
		(layer "In11.Cu")
		(net "M_D_CPU0_SB_DQS_DP<6>")
	)
	(segment
		(start 310.042814 -213.485984)
		(end 308.168294 -211.611464)
		(width 0.18288)
		(layer "In11.Cu")
		(net "M_D_CPU0_SB_DQS_DP<6>")
	)
	(segment
		(start 341.537036 -232.852722)
		(end 341.528146 -232.847642)
		(width 0.088646)
		(layer "In11.Cu")
		(net "M_D_CPU0_SB_DQS_DP<6>")
	)
	(segment
		(start 336.380328 -232.046272)
		(end 336.368644 -232.03916)
		(width 0.088646)
		(layer "In11.Cu")
		(net "M_D_CPU0_SB_DQS_DP<6>")
	)
	(segment
		(start 341.072978 -232.042462)
		(end 341.0712 -232.041446)
		(width 0.088646)
		(layer "In11.Cu")
		(net "M_D_CPU0_SB_DQS_DP<6>")
	)
	(segment
		(start 273.367754 -215.661748)
		(end 273.139408 -216.212674)
		(width 0.18288)
		(layer "In11.Cu")
		(net "M_D_CPU0_SB_DQS_DP<6>")
	)
	(segment
		(start 306.732178 -211.016596)
		(end 305.05273 -211.016596)
		(width 0.18288)
		(layer "In11.Cu")
		(net "M_D_CPU0_SB_DQS_DP<6>")
	)
	(segment
		(start 297.026838 -210.774788)
		(end 295.40581 -210.774788)
		(width 0.18288)
		(layer "In11.Cu")
		(net "M_D_CPU0_SB_DQS_DP<6>")
	)
	(segment
		(start 347.564964 -234.471972)
		(end 347.550232 -234.480608)
		(width 0.088646)
		(layer "In11.Cu")
		(net "M_D_CPU0_SB_DQS_DP<6>")
	)
	(segment
		(start 280.031698 -210.490816)
		(end 279.605994 -210.490816)
		(width 0.18288)
		(layer "In11.Cu")
		(net "M_D_CPU0_SB_DQS_DP<6>")
	)
	(segment
		(start 332.998064 -232.03027)
		(end 332.983332 -232.038906)
		(width 0.088646)
		(layer "In11.Cu")
		(net "M_D_CPU0_SB_DQS_DP<6>")
	)
	(segment
		(start 302.32604 -209.886804)
		(end 299.475398 -209.886804)
		(width 0.18288)
		(layer "In11.Cu")
		(net "M_D_CPU0_SB_DQS_DP<6>")
	)
	(segment
		(start 293.605966 -210.784694)
		(end 292.999668 -211.390992)
		(width 0.18288)
		(layer "In11.Cu")
		(net "M_D_CPU0_SB_DQS_DP<6>")
	)
	(segment
		(start 314.06211 -214.277702)
		(end 311.953402 -214.277702)
		(width 0.18288)
		(layer "In11.Cu")
		(net "M_D_CPU0_SB_DQS_DP<6>")
	)
	(segment
		(start 331.573632 -231.660192)
		(end 331.573632 -231.161336)
		(width 0.088646)
		(layer "In11.Cu")
		(net "M_D_CPU0_SB_DQS_DP<6>")
	)
	(segment
		(start 291.67836 -210.827112)
		(end 289.15487 -210.827112)
		(width 0.18288)
		(layer "In11.Cu")
		(net "M_D_CPU0_SB_DQS_DP<6>")
	)
	(segment
		(start 314.534804 -214.473536)
		(end 314.06211 -214.277702)
		(width 0.18288)
		(layer "In11.Cu")
		(net "M_D_CPU0_SB_DQS_DP<6>")
	)
	(segment
		(start 277.069296 -210.159854)
		(end 276.414738 -210.814412)
		(width 0.18288)
		(layer "In11.Cu")
		(net "M_D_CPU0_SB_DQS_DP<6>")
	)
	(segment
		(start 271.783556 -216.936574)
		(end 270.682466 -218.037664)
		(width 0.18288)
		(layer "In11.Cu")
		(net "M_D_CPU0_SB_DQS_DP<6>")
	)
	(segment
		(start 280.307034 -210.766152)
		(end 280.031698 -210.490816)
		(width 0.18288)
		(layer "In11.Cu")
		(net "M_D_CPU0_SB_DQS_DP<6>")
	)
	(segment
		(start 269.097506 -217.984832)
		(end 268.829282 -217.716608)
		(width 0.18288)
		(layer "In11.Cu")
		(net "M_D_CPU0_SB_DQS_DP<6>")
	)
	(segment
		(start 278.281892 -210.159854)
		(end 277.069296 -210.159854)
		(width 0.18288)
		(layer "In11.Cu")
		(net "M_D_CPU0_SB_DQS_DP<6>")
	)
	(segment
		(start 298.782486 -209.641948)
		(end 298.463208 -209.961226)
		(width 0.18288)
		(layer "In11.Cu")
		(net "M_D_CPU0_SB_DQS_DP<6>")
	)
	(segment
		(start 278.910034 -210.787996)
		(end 278.281892 -210.159854)
		(width 0.18288)
		(layer "In11.Cu")
		(net "M_D_CPU0_SB_DQS_DP<6>")
	)
	(segment
		(start 341.069168 -232.040176)
		(end 341.066882 -232.038906)
		(width 0.088646)
		(layer "In11.Cu")
		(net "M_D_CPU0_SB_DQS_DP<6>")
	)
	(segment
		(start 282.634436 -209.939128)
		(end 281.807412 -210.766152)
		(width 0.18288)
		(layer "In11.Cu")
		(net "M_D_CPU0_SB_DQS_DP<6>")
	)
	(segment
		(start 297.8404 -209.961226)
		(end 297.026838 -210.774788)
		(width 0.18288)
		(layer "In11.Cu")
		(net "M_D_CPU0_SB_DQS_DP<6>")
	)
	(segment
		(start 330.336906 -230.24338)
		(end 328.58583 -230.24338)
		(width 0.18288)
		(layer "In11.Cu")
		(net "M_D_CPU0_SB_DQS_DP<6>")
	)
	(segment
		(start 294.402256 -210.784694)
		(end 293.605966 -210.784694)
		(width 0.18288)
		(layer "In11.Cu")
		(net "M_D_CPU0_SB_DQS_DP<6>")
	)
	(segment
		(start 343.805764 -234.471972)
		(end 343.791032 -234.480608)
		(width 0.088646)
		(layer "In11.Cu")
		(net "M_D_CPU0_SB_DQS_DP<6>")
	)
	(segment
		(start 294.696134 -210.490816)
		(end 294.402256 -210.784694)
		(width 0.18288)
		(layer "In11.Cu")
		(net "M_D_CPU0_SB_DQS_DP<6>")
	)
	(segment
		(start 272.862294 -216.489534)
		(end 271.783556 -216.936574)
		(width 0.18288)
		(layer "In11.Cu")
		(net "M_D_CPU0_SB_DQS_DP<6>")
	)
	(segment
		(start 279.308814 -210.787996)
		(end 278.910034 -210.787996)
		(width 0.18288)
		(layer "In11.Cu")
		(net "M_D_CPU0_SB_DQS_DP<6>")
	)
	(segment
		(start 299.475398 -209.886804)
		(end 299.230542 -209.641948)
		(width 0.18288)
		(layer "In11.Cu")
		(net "M_D_CPU0_SB_DQS_DP<6>")
	)
	(segment
		(start 273.975322 -212.466682)
		(end 273.367754 -213.07425)
		(width 0.18288)
		(layer "In11.Cu")
		(net "M_D_CPU0_SB_DQS_DP<6>")
	)
	(segment
		(start 308.168294 -211.611464)
		(end 306.732178 -211.016596)
		(width 0.18288)
		(layer "In11.Cu")
		(net "M_D_CPU0_SB_DQS_DP<6>")
	)
	(segment
		(start 292.999668 -211.390992)
		(end 292.24224 -211.390992)
		(width 0.18288)
		(layer "In11.Cu")
		(net "M_D_CPU0_SB_DQS_DP<6>")
	)
	(segment
		(start 269.601442 -217.984832)
		(end 269.097506 -217.984832)
		(width 0.18288)
		(layer "In11.Cu")
		(net "M_D_CPU0_SB_DQS_DP<6>")
	)
	(segment
		(start 348.77248 -234.970066)
		(end 348.459552 -234.970066)
		(width 0.088646)
		(layer "In11.Cu")
		(net "M_D_CPU0_SB_DQS_DP<6>")
	)
	(segment
		(start 270.682466 -218.037664)
		(end 270.26616 -218.209876)
		(width 0.18288)
		(layer "In11.Cu")
		(net "M_D_CPU0_SB_DQS_DP<6>")
	)
	(segment
		(start 316.027308 -215.965532)
		(end 314.534804 -214.473536)
		(width 0.18288)
		(layer "In11.Cu")
		(net "M_D_CPU0_SB_DQS_DP<6>")
	)
	(segment
		(start 311.953402 -214.277702)
		(end 310.042814 -213.485984)
		(width 0.18288)
		(layer "In11.Cu")
		(net "M_D_CPU0_SB_DQS_DP<6>")
	)
	(segment
		(start 279.605994 -210.490816)
		(end 279.308814 -210.787996)
		(width 0.18288)
		(layer "In11.Cu")
		(net "M_D_CPU0_SB_DQS_DP<6>")
	)
	(segment
		(start 273.367754 -213.07425)
		(end 273.367754 -215.661748)
		(width 0.18288)
		(layer "In11.Cu")
		(net "M_D_CPU0_SB_DQS_DP<6>")
	)
	(segment
		(start 330.715366 -230.30307)
		(end 330.396596 -230.30307)
		(width 0.088646)
		(layer "In11.Cu")
		(net "M_D_CPU0_SB_DQS_DP<6>")
	)
	(segment
		(start 332.32598 -231.96296)
		(end 331.8764 -231.96296)
		(width 0.088646)
		(layer "In11.Cu")
		(net "M_D_CPU0_SB_DQS_DP<6>")
	)
	(segment
		(start 286.998918 -209.933794)
		(end 284.414468 -209.933794)
		(width 0.18288)
		(layer "In11.Cu")
		(net "M_D_CPU0_SB_DQS_DP<6>")
	)
	(segment
		(start 346.625164 -234.471972)
		(end 346.610432 -234.480608)
		(width 0.088646)
		(layer "In11.Cu")
		(net "M_D_CPU0_SB_DQS_DP<6>")
	)
	(segment
		(start 317.241936 -218.899486)
		(end 316.027308 -215.965532)
		(width 0.18288)
		(layer "In11.Cu")
		(net "M_D_CPU0_SB_DQS_DP<6>")
	)
	(segment
		(start 336.367882 -232.038906)
		(end 336.357468 -232.03281)
		(width 0.088646)
		(layer "In11.Cu")
		(net "M_D_CPU0_SB_DQS_DP<6>")
	)
	(segment
		(start 298.463208 -209.961226)
		(end 297.8404 -209.961226)
		(width 0.18288)
		(layer "In11.Cu")
		(net "M_D_CPU0_SB_DQS_DP<6>")
	)
	(segment
		(start 339.187536 -232.038906)
		(end 339.187028 -232.038906)
		(width 0.088646)
		(layer "In11.Cu")
		(net "M_D_CPU0_SB_DQS_DP<6>")
	)
	(segment
		(start 270.26616 -218.209876)
		(end 269.826486 -218.209876)
		(width 0.18288)
		(layer "In11.Cu")
		(net "M_D_CPU0_SB_DQS_DP<6>")
	)
	(segment
		(start 341.81923 -233.34218)
		(end 341.81923 -233.326686)
		(width 0.088646)
		(layer "In11.Cu")
		(net "M_D_CPU0_SB_DQS_DP<6>")
	)
	(segment
		(start 345.685364 -234.471972)
		(end 345.670632 -234.480608)
		(width 0.088646)
		(layer "In11.Cu")
		(net "M_D_CPU0_SB_DQS_DP<6>")
	)
	(segment
		(start 341.0712 -232.041446)
		(end 341.069168 -232.040176)
		(width 0.088646)
		(layer "In11.Cu")
		(net "M_D_CPU0_SB_DQS_DP<6>")
	)
	(segment
		(start 292.24224 -211.390992)
		(end 291.67836 -210.827112)
		(width 0.18288)
		(layer "In11.Cu")
		(net "M_D_CPU0_SB_DQS_DP<6>")
	)
	(segment
		(start 284.120082 -209.639408)
		(end 283.717746 -209.639408)
		(width 0.18288)
		(layer "In11.Cu")
		(net "M_D_CPU0_SB_DQS_DP<6>")
	)
	(segment
		(start 273.139408 -216.212674)
		(end 272.862294 -216.489534)
		(width 0.18288)
		(layer "In11.Cu")
		(net "M_D_CPU0_SB_DQS_DP<6>")
	)
	(segment
		(start 281.807412 -210.766152)
		(end 280.307034 -210.766152)
		(width 0.18288)
		(layer "In11.Cu")
		(net "M_D_CPU0_SB_DQS_DP<6>")
	)
	(segment
		(start 328.58583 -230.24338)
		(end 317.241936 -218.899486)
		(width 0.18288)
		(layer "In11.Cu")
		(net "M_D_CPU0_SB_DQS_DP<6>")
	)
	(segment
		(start 305.05273 -211.016596)
		(end 302.32604 -209.886804)
		(width 0.18288)
		(layer "In11.Cu")
		(net "M_D_CPU0_SB_DQS_DP<6>")
	)
	(segment
		(start 342.861392 -234.474512)
		(end 342.850978 -234.480608)
		(width 0.088646)
		(layer "In11.Cu")
		(net "M_D_CPU0_SB_DQS_DP<6>")
	)
	(segment
		(start 331.8764 -231.96296)
		(end 331.573632 -231.660192)
		(width 0.088646)
		(layer "In11.Cu")
		(net "M_D_CPU0_SB_DQS_DP<6>")
	)
	(segment
		(start 274.534376 -212.23478)
		(end 273.975322 -212.466682)
		(width 0.18288)
		(layer "In11.Cu")
		(net "M_D_CPU0_SB_DQS_DP<6>")
	)
	(segment
		(start 295.40581 -210.774788)
		(end 295.121838 -210.490816)
		(width 0.18288)
		(layer "In11.Cu")
		(net "M_D_CPU0_SB_DQS_DP<6>")
	)
	(arc
		(start 345.670632 -234.480608)
		(mid 345.483434 -234.530751)
		(end 345.296236 -234.480608)
		(width 0.088646)
		(layer "In11.Cu")
		(net "M_D_CPU0_SB_DQS_DP<6>")
	)
	(arc
		(start 335.802732 -232.038906)
		(mid 335.615534 -232.089049)
		(end 335.428336 -232.038906)
		(width 0.088646)
		(layer "In11.Cu")
		(net "M_D_CPU0_SB_DQS_DP<6>")
	)
	(arc
		(start 346.236036 -234.480608)
		(mid 345.961837 -234.404773)
		(end 345.685364 -234.471972)
		(width 0.088646)
		(layer "In11.Cu")
		(net "M_D_CPU0_SB_DQS_DP<6>")
	)
	(arc
		(start 343.416636 -234.480608)
		(mid 343.139823 -234.404738)
		(end 342.861392 -234.474512)
		(width 0.088646)
		(layer "In11.Cu")
		(net "M_D_CPU0_SB_DQS_DP<6>")
	)
	(arc
		(start 347.550232 -234.480608)
		(mid 347.363034 -234.530751)
		(end 347.175836 -234.480608)
		(width 0.088646)
		(layer "In11.Cu")
		(net "M_D_CPU0_SB_DQS_DP<6>")
	)
	(arc
		(start 347.175836 -234.480608)
		(mid 346.901637 -234.404773)
		(end 346.625164 -234.471972)
		(width 0.088646)
		(layer "In11.Cu")
		(net "M_D_CPU0_SB_DQS_DP<6>")
	)
	(arc
		(start 332.983332 -232.038906)
		(mid 332.796134 -232.089049)
		(end 332.608936 -232.038906)
		(width 0.088646)
		(layer "In11.Cu")
		(net "M_D_CPU0_SB_DQS_DP<6>")
	)
	(arc
		(start 342.476582 -234.480608)
		(mid 342.339557 -234.343495)
		(end 342.289384 -234.15625)
		(width 0.088646)
		(layer "In11.Cu")
		(net "M_D_CPU0_SB_DQS_DP<6>")
	)
	(arc
		(start 340.501478 -232.038906)
		(mid 340.31428 -232.089049)
		(end 340.127082 -232.038906)
		(width 0.088646)
		(layer "In11.Cu")
		(net "M_D_CPU0_SB_DQS_DP<6>")
	)
	(arc
		(start 341.997792 -233.661458)
		(mid 341.866878 -233.525098)
		(end 341.81923 -233.34218)
		(width 0.088646)
		(layer "In11.Cu")
		(net "M_D_CPU0_SB_DQS_DP<6>")
	)
	(arc
		(start 337.682332 -232.038906)
		(mid 337.502187 -232.089227)
		(end 337.320128 -232.046272)
		(width 0.088646)
		(layer "In11.Cu")
		(net "M_D_CPU0_SB_DQS_DP<6>")
	)
	(arc
		(start 341.05215 -232.03027)
		(mid 340.775675 -231.96295)
		(end 340.501478 -232.038906)
		(width 0.088646)
		(layer "In11.Cu")
		(net "M_D_CPU0_SB_DQS_DP<6>")
	)
	(arc
		(start 343.791032 -234.480608)
		(mid 343.603834 -234.530751)
		(end 343.416636 -234.480608)
		(width 0.088646)
		(layer "In11.Cu")
		(net "M_D_CPU0_SB_DQS_DP<6>")
	)
	(arc
		(start 334.488536 -232.038906)
		(mid 334.205834 -231.96313)
		(end 333.923132 -232.038906)
		(width 0.088646)
		(layer "In11.Cu")
		(net "M_D_CPU0_SB_DQS_DP<6>")
	)
	(arc
		(start 348.394274 -234.904788)
		(mid 348.392976 -234.894234)
		(end 348.39148 -234.883706)
		(width 0.088646)
		(layer "In11.Cu")
		(net "M_D_CPU0_SB_DQS_DP<6>")
	)
	(arc
		(start 341.528146 -232.847642)
		(mid 341.397232 -232.711282)
		(end 341.349584 -232.528364)
		(width 0.088646)
		(layer "In11.Cu")
		(net "M_D_CPU0_SB_DQS_DP<6>")
	)
	(arc
		(start 337.308444 -232.03916)
		(mid 337.025517 -231.963096)
		(end 336.742532 -232.038906)
		(width 0.088646)
		(layer "In11.Cu")
		(net "M_D_CPU0_SB_DQS_DP<6>")
	)
	(arc
		(start 346.610432 -234.480608)
		(mid 346.423234 -234.530751)
		(end 346.236036 -234.480608)
		(width 0.088646)
		(layer "In11.Cu")
		(net "M_D_CPU0_SB_DQS_DP<6>")
	)
	(arc
		(start 332.608936 -232.038906)
		(mid 332.472464 -231.982283)
		(end 332.32598 -231.96296)
		(width 0.088646)
		(layer "In11.Cu")
		(net "M_D_CPU0_SB_DQS_DP<6>")
	)
	(arc
		(start 341.81923 -233.326686)
		(mid 341.73986 -233.052952)
		(end 341.537036 -232.852722)
		(width 0.088646)
		(layer "In11.Cu")
		(net "M_D_CPU0_SB_DQS_DP<6>")
	)
	(arc
		(start 333.548736 -232.038906)
		(mid 333.274537 -231.963071)
		(end 332.998064 -232.03027)
		(width 0.088646)
		(layer "In11.Cu")
		(net "M_D_CPU0_SB_DQS_DP<6>")
	)
	(arc
		(start 348.115636 -234.480608)
		(mid 347.841437 -234.404773)
		(end 347.564964 -234.471972)
		(width 0.088646)
		(layer "In11.Cu")
		(net "M_D_CPU0_SB_DQS_DP<6>")
	)
	(arc
		(start 338.248244 -232.03916)
		(mid 337.965317 -231.963096)
		(end 337.682332 -232.038906)
		(width 0.088646)
		(layer "In11.Cu")
		(net "M_D_CPU0_SB_DQS_DP<6>")
	)
	(arc
		(start 341.349584 -232.528364)
		(mid 341.275593 -232.248798)
		(end 341.072978 -232.042462)
		(width 0.088646)
		(layer "In11.Cu")
		(net "M_D_CPU0_SB_DQS_DP<6>")
	)
	(arc
		(start 338.622132 -232.038906)
		(mid 338.441987 -232.089227)
		(end 338.259928 -232.046272)
		(width 0.088646)
		(layer "In11.Cu")
		(net "M_D_CPU0_SB_DQS_DP<6>")
	)
	(arc
		(start 334.862932 -232.038906)
		(mid 334.675734 -232.089049)
		(end 334.488536 -232.038906)
		(width 0.088646)
		(layer "In11.Cu")
		(net "M_D_CPU0_SB_DQS_DP<6>")
	)
	(arc
		(start 342.850978 -234.480608)
		(mid 342.66378 -234.530785)
		(end 342.476582 -234.480608)
		(width 0.088646)
		(layer "In11.Cu")
		(net "M_D_CPU0_SB_DQS_DP<6>")
	)
	(arc
		(start 339.187028 -232.038906)
		(mid 338.90458 -231.963223)
		(end 338.622132 -232.038906)
		(width 0.088646)
		(layer "In11.Cu")
		(net "M_D_CPU0_SB_DQS_DP<6>")
	)
	(arc
		(start 335.428336 -232.038906)
		(mid 335.145634 -231.96313)
		(end 334.862932 -232.038906)
		(width 0.088646)
		(layer "In11.Cu")
		(net "M_D_CPU0_SB_DQS_DP<6>")
	)
	(arc
		(start 344.356436 -234.480608)
		(mid 344.082237 -234.404773)
		(end 343.805764 -234.471972)
		(width 0.088646)
		(layer "In11.Cu")
		(net "M_D_CPU0_SB_DQS_DP<6>")
	)
	(arc
		(start 340.127082 -232.038906)
		(mid 339.84438 -231.96313)
		(end 339.561678 -232.038906)
		(width 0.088646)
		(layer "In11.Cu")
		(net "M_D_CPU0_SB_DQS_DP<6>")
	)
	(arc
		(start 336.742532 -232.038906)
		(mid 336.562387 -232.089227)
		(end 336.380328 -232.046272)
		(width 0.088646)
		(layer "In11.Cu")
		(net "M_D_CPU0_SB_DQS_DP<6>")
	)
	(arc
		(start 342.289384 -234.155996)
		(mid 342.213638 -233.873368)
		(end 342.006682 -233.666538)
		(width 0.088646)
		(layer "In11.Cu")
		(net "M_D_CPU0_SB_DQS_DP<6>")
	)
	(arc
		(start 348.39148 -234.883706)
		(mid 348.299358 -234.650806)
		(end 348.115636 -234.480608)
		(width 0.088646)
		(layer "In11.Cu")
		(net "M_D_CPU0_SB_DQS_DP<6>")
	)
	(arc
		(start 336.357468 -232.03281)
		(mid 336.07929 -231.963087)
		(end 335.802732 -232.038906)
		(width 0.088646)
		(layer "In11.Cu")
		(net "M_D_CPU0_SB_DQS_DP<6>")
	)
	(arc
		(start 345.296236 -234.480608)
		(mid 345.013534 -234.404832)
		(end 344.730832 -234.480608)
		(width 0.088646)
		(layer "In11.Cu")
		(net "M_D_CPU0_SB_DQS_DP<6>")
	)
	(arc
		(start 344.730832 -234.480608)
		(mid 344.543634 -234.530751)
		(end 344.356436 -234.480608)
		(width 0.088646)
		(layer "In11.Cu")
		(net "M_D_CPU0_SB_DQS_DP<6>")
	)
	(arc
		(start 339.561678 -232.038906)
		(mid 339.374624 -232.088956)
		(end 339.187536 -232.038906)
		(width 0.088646)
		(layer "In11.Cu")
		(net "M_D_CPU0_SB_DQS_DP<6>")
	)
	(arc
		(start 333.923132 -232.038906)
		(mid 333.735934 -232.089049)
		(end 333.548736 -232.038906)
		(width 0.088646)
		(layer "In11.Cu")
		(net "M_D_CPU0_SB_DQS_DP<6>")
	)
	(segment
		(start 267.724382 -227.066602)
		(end 267.23467 -227.066602)
		(width 0.20066)
		(layer "F.Cu")
		(net "M_D_CPU0_SB_DQS_DP<5>")
	)
	(segment
		(start 348.772734 -240.389156)
		(end 348.77248 -240.388902)
		(width 0.20066)
		(layer "F.Cu")
		(net "M_D_CPU0_SB_DQS_DP<5>")
	)
	(segment
		(start 262.505698 -226.64166)
		(end 262.50011 -226.636072)
		(width 0.101854)
		(layer "F.Cu")
		(net "M_D_CPU0_SB_DQS_DP<5>")
	)
	(segment
		(start 265.227816 -226.903026)
		(end 264.966704 -226.641914)
		(width 0.20066)
		(layer "F.Cu")
		(net "M_D_CPU0_SB_DQS_DP<5>")
	)
	(segment
		(start 264.966704 -226.641914)
		(end 264.825226 -226.641914)
		(width 0.20066)
		(layer "F.Cu")
		(net "M_D_CPU0_SB_DQS_DP<5>")
	)
	(segment
		(start 262.746998 -226.64166)
		(end 262.505698 -226.64166)
		(width 0.101854)
		(layer "F.Cu")
		(net "M_D_CPU0_SB_DQS_DP<5>")
	)
	(segment
		(start 262.033258 -226.905566)
		(end 261.673086 -226.905566)
		(width 0.20066)
		(layer "F.Cu")
		(net "M_D_CPU0_SB_DQS_DP<5>")
	)
	(segment
		(start 260.91642 -227.327968)
		(end 260.655054 -227.066602)
		(width 0.20066)
		(layer "F.Cu")
		(net "M_D_CPU0_SB_DQS_DP<5>")
	)
	(segment
		(start 260.655054 -227.066602)
		(end 260.180582 -227.066602)
		(width 0.20066)
		(layer "F.Cu")
		(net "M_D_CPU0_SB_DQS_DP<5>")
	)
	(segment
		(start 264.825226 -226.641914)
		(end 264.824972 -226.64166)
		(width 0.1016)
		(layer "F.Cu")
		(net "M_D_CPU0_SB_DQS_DP<5>")
	)
	(segment
		(start 266.368784 -227.327968)
		(end 265.732768 -226.903026)
		(width 0.20066)
		(layer "F.Cu")
		(net "M_D_CPU0_SB_DQS_DP<5>")
	)
	(segment
		(start 262.302752 -226.636072)
		(end 262.033258 -226.905566)
		(width 0.20066)
		(layer "F.Cu")
		(net "M_D_CPU0_SB_DQS_DP<5>")
	)
	(segment
		(start 268.829282 -227.066602)
		(end 267.724382 -227.066602)
		(width 0.20066)
		(layer "F.Cu")
		(net "M_D_CPU0_SB_DQS_DP<5>")
	)
	(segment
		(start 265.732768 -226.903026)
		(end 265.227816 -226.903026)
		(width 0.20066)
		(layer "F.Cu")
		(net "M_D_CPU0_SB_DQS_DP<5>")
	)
	(segment
		(start 348.77248 -240.388902)
		(end 348.77248 -239.853216)
		(width 0.20066)
		(layer "F.Cu")
		(net "M_D_CPU0_SB_DQS_DP<5>")
	)
	(segment
		(start 264.824972 -226.64166)
		(end 262.746998 -226.64166)
		(width 0.1016)
		(layer "F.Cu")
		(net "M_D_CPU0_SB_DQS_DP<5>")
	)
	(segment
		(start 262.50011 -226.636072)
		(end 262.302752 -226.636072)
		(width 0.20066)
		(layer "F.Cu")
		(net "M_D_CPU0_SB_DQS_DP<5>")
	)
	(segment
		(start 261.673086 -226.905566)
		(end 261.250684 -227.327968)
		(width 0.20066)
		(layer "F.Cu")
		(net "M_D_CPU0_SB_DQS_DP<5>")
	)
	(segment
		(start 261.250684 -227.327968)
		(end 260.91642 -227.327968)
		(width 0.20066)
		(layer "F.Cu")
		(net "M_D_CPU0_SB_DQS_DP<5>")
	)
	(segment
		(start 267.23467 -227.066602)
		(end 266.973304 -227.327968)
		(width 0.20066)
		(layer "F.Cu")
		(net "M_D_CPU0_SB_DQS_DP<5>")
	)
	(segment
		(start 266.973304 -227.327968)
		(end 266.368784 -227.327968)
		(width 0.20066)
		(layer "F.Cu")
		(net "M_D_CPU0_SB_DQS_DP<5>")
	)
	(segment
		(start 336.3722 -238.552482)
		(end 336.370168 -238.551212)
		(width 0.088646)
		(layer "In11.Cu")
		(net "M_D_CPU0_SB_DQS_DP<5>")
	)
	(segment
		(start 299.240448 -222.392748)
		(end 298.788836 -222.392748)
		(width 0.18288)
		(layer "In11.Cu")
		(net "M_D_CPU0_SB_DQS_DP<5>")
	)
	(segment
		(start 342.861392 -239.357662)
		(end 342.850978 -239.363758)
		(width 0.088646)
		(layer "In11.Cu")
		(net "M_D_CPU0_SB_DQS_DP<5>")
	)
	(segment
		(start 293.623492 -223.529906)
		(end 293.053262 -224.100136)
		(width 0.18288)
		(layer "In11.Cu")
		(net "M_D_CPU0_SB_DQS_DP<5>")
	)
	(segment
		(start 335.428336 -238.549942)
		(end 335.419446 -238.544862)
		(width 0.088646)
		(layer "In11.Cu")
		(net "M_D_CPU0_SB_DQS_DP<5>")
	)
	(segment
		(start 298.788836 -222.392748)
		(end 298.513246 -222.668338)
		(width 0.18288)
		(layer "In11.Cu")
		(net "M_D_CPU0_SB_DQS_DP<5>")
	)
	(segment
		(start 336.838036 -239.363758)
		(end 336.829146 -239.358678)
		(width 0.088646)
		(layer "In11.Cu")
		(net "M_D_CPU0_SB_DQS_DP<5>")
	)
	(segment
		(start 334.9625 -237.738666)
		(end 334.960468 -237.737396)
		(width 0.088646)
		(layer "In11.Cu")
		(net "M_D_CPU0_SB_DQS_DP<5>")
	)
	(segment
		(start 334.958182 -237.736126)
		(end 334.947768 -237.73003)
		(width 0.088646)
		(layer "In11.Cu")
		(net "M_D_CPU0_SB_DQS_DP<5>")
	)
	(segment
		(start 299.493432 -222.645732)
		(end 299.240448 -222.392748)
		(width 0.18288)
		(layer "In11.Cu")
		(net "M_D_CPU0_SB_DQS_DP<5>")
	)
	(segment
		(start 340.986364 -239.355122)
		(end 340.971632 -239.363758)
		(width 0.088646)
		(layer "In11.Cu")
		(net "M_D_CPU0_SB_DQS_DP<5>")
	)
	(segment
		(start 313.833764 -225.788728)
		(end 313.58078 -226.041712)
		(width 0.18288)
		(layer "In11.Cu")
		(net "M_D_CPU0_SB_DQS_DP<5>")
	)
	(segment
		(start 286.954722 -222.678498)
		(end 284.39745 -222.678498)
		(width 0.18288)
		(layer "In11.Cu")
		(net "M_D_CPU0_SB_DQS_DP<5>")
	)
	(segment
		(start 304.404268 -223.543368)
		(end 302.236886 -222.645732)
		(width 0.18288)
		(layer "In11.Cu")
		(net "M_D_CPU0_SB_DQS_DP<5>")
	)
	(segment
		(start 269.686532 -227.339906)
		(end 269.102586 -227.339906)
		(width 0.18288)
		(layer "In11.Cu")
		(net "M_D_CPU0_SB_DQS_DP<5>")
	)
	(segment
		(start 281.969972 -223.517714)
		(end 280.363168 -223.517714)
		(width 0.18288)
		(layer "In11.Cu")
		(net "M_D_CPU0_SB_DQS_DP<5>")
	)
	(segment
		(start 289.127184 -223.578674)
		(end 286.954722 -222.678498)
		(width 0.18288)
		(layer "In11.Cu")
		(net "M_D_CPU0_SB_DQS_DP<5>")
	)
	(segment
		(start 292.323774 -224.100136)
		(end 291.802312 -223.578674)
		(width 0.18288)
		(layer "In11.Cu")
		(net "M_D_CPU0_SB_DQS_DP<5>")
	)
	(segment
		(start 314.688728 -226.128072)
		(end 314.349384 -225.788728)
		(width 0.18288)
		(layer "In11.Cu")
		(net "M_D_CPU0_SB_DQS_DP<5>")
	)
	(segment
		(start 276.048724 -225.41738)
		(end 275.01342 -226.452684)
		(width 0.18288)
		(layer "In11.Cu")
		(net "M_D_CPU0_SB_DQS_DP<5>")
	)
	(segment
		(start 341.921846 -239.357662)
		(end 341.911432 -239.363758)
		(width 0.088646)
		(layer "In11.Cu")
		(net "M_D_CPU0_SB_DQS_DP<5>")
	)
	(segment
		(start 313.58078 -226.041712)
		(end 312.98007 -226.041712)
		(width 0.18288)
		(layer "In11.Cu")
		(net "M_D_CPU0_SB_DQS_DP<5>")
	)
	(segment
		(start 277.368 -224.4852)
		(end 276.709632 -225.143568)
		(width 0.18288)
		(layer "In11.Cu")
		(net "M_D_CPU0_SB_DQS_DP<5>")
	)
	(segment
		(start 284.109922 -222.39097)
		(end 283.713174 -222.39097)
		(width 0.18288)
		(layer "In11.Cu")
		(net "M_D_CPU0_SB_DQS_DP<5>")
	)
	(segment
		(start 348.77248 -239.853216)
		(end 348.459552 -239.853216)
		(width 0.088646)
		(layer "In11.Cu")
		(net "M_D_CPU0_SB_DQS_DP<5>")
	)
	(segment
		(start 294.70477 -223.241108)
		(end 294.415972 -223.529906)
		(width 0.18288)
		(layer "In11.Cu")
		(net "M_D_CPU0_SB_DQS_DP<5>")
	)
	(segment
		(start 347.564964 -239.355122)
		(end 347.550232 -239.363758)
		(width 0.088646)
		(layer "In11.Cu")
		(net "M_D_CPU0_SB_DQS_DP<5>")
	)
	(segment
		(start 348.459552 -239.853216)
		(end 348.394274 -239.787938)
		(width 0.088646)
		(layer "In11.Cu")
		(net "M_D_CPU0_SB_DQS_DP<5>")
	)
	(segment
		(start 334.964278 -237.739682)
		(end 334.9625 -237.738666)
		(width 0.088646)
		(layer "In11.Cu")
		(net "M_D_CPU0_SB_DQS_DP<5>")
	)
	(segment
		(start 284.39745 -222.678498)
		(end 284.109922 -222.39097)
		(width 0.18288)
		(layer "In11.Cu")
		(net "M_D_CPU0_SB_DQS_DP<5>")
	)
	(segment
		(start 314.349384 -225.788728)
		(end 313.833764 -225.788728)
		(width 0.18288)
		(layer "In11.Cu")
		(net "M_D_CPU0_SB_DQS_DP<5>")
	)
	(segment
		(start 330.58735 -236.344714)
		(end 330.396596 -236.344714)
		(width 0.088646)
		(layer "In11.Cu")
		(net "M_D_CPU0_SB_DQS_DP<5>")
	)
	(segment
		(start 282.80614 -222.681546)
		(end 281.969972 -223.517714)
		(width 0.18288)
		(layer "In11.Cu")
		(net "M_D_CPU0_SB_DQS_DP<5>")
	)
	(segment
		(start 309.512462 -225.222054)
		(end 309.09006 -225.222054)
		(width 0.18288)
		(layer "In11.Cu")
		(net "M_D_CPU0_SB_DQS_DP<5>")
	)
	(segment
		(start 295.404286 -223.552258)
		(end 295.093136 -223.241108)
		(width 0.18288)
		(layer "In11.Cu")
		(net "M_D_CPU0_SB_DQS_DP<5>")
	)
	(segment
		(start 332.32598 -237.786926)
		(end 332.029562 -237.786926)
		(width 0.088646)
		(layer "In11.Cu")
		(net "M_D_CPU0_SB_DQS_DP<5>")
	)
	(segment
		(start 306.960524 -223.543368)
		(end 304.404268 -223.543368)
		(width 0.18288)
		(layer "In11.Cu")
		(net "M_D_CPU0_SB_DQS_DP<5>")
	)
	(segment
		(start 295.093136 -223.241108)
		(end 294.70477 -223.241108)
		(width 0.18288)
		(layer "In11.Cu")
		(net "M_D_CPU0_SB_DQS_DP<5>")
	)
	(segment
		(start 309.09006 -225.222054)
		(end 308.439312 -224.571306)
		(width 0.18288)
		(layer "In11.Cu")
		(net "M_D_CPU0_SB_DQS_DP<5>")
	)
	(segment
		(start 275.01342 -226.452684)
		(end 272.160746 -227.634546)
		(width 0.18288)
		(layer "In11.Cu")
		(net "M_D_CPU0_SB_DQS_DP<5>")
	)
	(segment
		(start 291.802312 -223.578674)
		(end 289.127184 -223.578674)
		(width 0.18288)
		(layer "In11.Cu")
		(net "M_D_CPU0_SB_DQS_DP<5>")
	)
	(segment
		(start 310.530748 -225.203258)
		(end 310.26862 -224.94113)
		(width 0.18288)
		(layer "In11.Cu")
		(net "M_D_CPU0_SB_DQS_DP<5>")
	)
	(segment
		(start 336.370168 -238.551212)
		(end 336.367882 -238.549942)
		(width 0.088646)
		(layer "In11.Cu")
		(net "M_D_CPU0_SB_DQS_DP<5>")
	)
	(segment
		(start 280.363168 -223.517714)
		(end 280.086562 -223.241108)
		(width 0.18288)
		(layer "In11.Cu")
		(net "M_D_CPU0_SB_DQS_DP<5>")
	)
	(segment
		(start 272.160746 -227.634546)
		(end 269.981172 -227.634546)
		(width 0.18288)
		(layer "In11.Cu")
		(net "M_D_CPU0_SB_DQS_DP<5>")
	)
	(segment
		(start 312.141616 -225.203258)
		(end 310.530748 -225.203258)
		(width 0.18288)
		(layer "In11.Cu")
		(net "M_D_CPU0_SB_DQS_DP<5>")
	)
	(segment
		(start 330.396596 -236.344714)
		(end 330.336906 -236.285024)
		(width 0.088646)
		(layer "In11.Cu")
		(net "M_D_CPU0_SB_DQS_DP<5>")
	)
	(segment
		(start 336.373978 -238.553498)
		(end 336.3722 -238.552482)
		(width 0.088646)
		(layer "In11.Cu")
		(net "M_D_CPU0_SB_DQS_DP<5>")
	)
	(segment
		(start 298.513246 -222.668338)
		(end 297.834812 -222.668338)
		(width 0.18288)
		(layer "In11.Cu")
		(net "M_D_CPU0_SB_DQS_DP<5>")
	)
	(segment
		(start 314.951872 -226.128072)
		(end 314.688728 -226.128072)
		(width 0.18288)
		(layer "In11.Cu")
		(net "M_D_CPU0_SB_DQS_DP<5>")
	)
	(segment
		(start 283.422598 -222.681546)
		(end 282.80614 -222.681546)
		(width 0.18288)
		(layer "In11.Cu")
		(net "M_D_CPU0_SB_DQS_DP<5>")
	)
	(segment
		(start 297.834812 -222.668338)
		(end 296.950892 -223.552258)
		(width 0.18288)
		(layer "In11.Cu")
		(net "M_D_CPU0_SB_DQS_DP<5>")
	)
	(segment
		(start 294.415972 -223.529906)
		(end 293.623492 -223.529906)
		(width 0.18288)
		(layer "In11.Cu")
		(net "M_D_CPU0_SB_DQS_DP<5>")
	)
	(segment
		(start 343.805764 -239.355122)
		(end 343.791032 -239.363758)
		(width 0.088646)
		(layer "In11.Cu")
		(net "M_D_CPU0_SB_DQS_DP<5>")
	)
	(segment
		(start 339.106764 -239.355122)
		(end 339.092032 -239.363758)
		(width 0.088646)
		(layer "In11.Cu")
		(net "M_D_CPU0_SB_DQS_DP<5>")
	)
	(segment
		(start 333.078582 -237.736126)
		(end 333.06385 -237.72749)
		(width 0.088646)
		(layer "In11.Cu")
		(net "M_D_CPU0_SB_DQS_DP<5>")
	)
	(segment
		(start 280.086562 -223.241108)
		(end 279.624282 -223.241108)
		(width 0.18288)
		(layer "In11.Cu")
		(net "M_D_CPU0_SB_DQS_DP<5>")
	)
	(segment
		(start 283.713174 -222.39097)
		(end 283.422598 -222.681546)
		(width 0.18288)
		(layer "In11.Cu")
		(net "M_D_CPU0_SB_DQS_DP<5>")
	)
	(segment
		(start 296.950892 -223.552258)
		(end 295.404286 -223.552258)
		(width 0.18288)
		(layer "In11.Cu")
		(net "M_D_CPU0_SB_DQS_DP<5>")
	)
	(segment
		(start 269.981172 -227.634546)
		(end 269.686532 -227.339906)
		(width 0.18288)
		(layer "In11.Cu")
		(net "M_D_CPU0_SB_DQS_DP<5>")
	)
	(segment
		(start 345.685364 -239.355122)
		(end 345.670632 -239.363758)
		(width 0.088646)
		(layer "In11.Cu")
		(net "M_D_CPU0_SB_DQS_DP<5>")
	)
	(segment
		(start 269.102586 -227.339906)
		(end 268.829282 -227.066602)
		(width 0.18288)
		(layer "In11.Cu")
		(net "M_D_CPU0_SB_DQS_DP<5>")
	)
	(segment
		(start 310.26862 -224.94113)
		(end 309.793386 -224.94113)
		(width 0.18288)
		(layer "In11.Cu")
		(net "M_D_CPU0_SB_DQS_DP<5>")
	)
	(segment
		(start 325.108824 -236.285024)
		(end 314.951872 -226.128072)
		(width 0.18288)
		(layer "In11.Cu")
		(net "M_D_CPU0_SB_DQS_DP<5>")
	)
	(segment
		(start 276.709632 -225.143568)
		(end 276.048724 -225.41738)
		(width 0.18288)
		(layer "In11.Cu")
		(net "M_D_CPU0_SB_DQS_DP<5>")
	)
	(segment
		(start 340.046564 -239.355122)
		(end 340.031832 -239.363758)
		(width 0.088646)
		(layer "In11.Cu")
		(net "M_D_CPU0_SB_DQS_DP<5>")
	)
	(segment
		(start 312.98007 -226.041712)
		(end 312.141616 -225.203258)
		(width 0.18288)
		(layer "In11.Cu")
		(net "M_D_CPU0_SB_DQS_DP<5>")
	)
	(segment
		(start 309.793386 -224.94113)
		(end 309.512462 -225.222054)
		(width 0.18288)
		(layer "In11.Cu")
		(net "M_D_CPU0_SB_DQS_DP<5>")
	)
	(segment
		(start 330.336906 -236.285024)
		(end 325.108824 -236.285024)
		(width 0.18288)
		(layer "In11.Cu")
		(net "M_D_CPU0_SB_DQS_DP<5>")
	)
	(segment
		(start 279.008586 -223.534986)
		(end 278.433276 -223.773238)
		(width 0.18288)
		(layer "In11.Cu")
		(net "M_D_CPU0_SB_DQS_DP<5>")
	)
	(segment
		(start 302.236886 -222.645732)
		(end 299.493432 -222.645732)
		(width 0.18288)
		(layer "In11.Cu")
		(net "M_D_CPU0_SB_DQS_DP<5>")
	)
	(segment
		(start 279.624282 -223.241108)
		(end 279.330404 -223.534986)
		(width 0.18288)
		(layer "In11.Cu")
		(net "M_D_CPU0_SB_DQS_DP<5>")
	)
	(segment
		(start 334.960468 -237.737396)
		(end 334.958182 -237.736126)
		(width 0.088646)
		(layer "In11.Cu")
		(net "M_D_CPU0_SB_DQS_DP<5>")
	)
	(segment
		(start 346.625164 -239.355122)
		(end 346.610432 -239.363758)
		(width 0.088646)
		(layer "In11.Cu")
		(net "M_D_CPU0_SB_DQS_DP<5>")
	)
	(segment
		(start 336.367882 -238.549942)
		(end 336.357468 -238.543846)
		(width 0.088646)
		(layer "In11.Cu")
		(net "M_D_CPU0_SB_DQS_DP<5>")
	)
	(segment
		(start 332.029562 -237.786926)
		(end 330.58735 -236.344714)
		(width 0.088646)
		(layer "In11.Cu")
		(net "M_D_CPU0_SB_DQS_DP<5>")
	)
	(segment
		(start 307.988462 -224.571306)
		(end 306.960524 -223.543368)
		(width 0.18288)
		(layer "In11.Cu")
		(net "M_D_CPU0_SB_DQS_DP<5>")
	)
	(segment
		(start 334.018636 -237.736126)
		(end 334.008222 -237.73003)
		(width 0.088646)
		(layer "In11.Cu")
		(net "M_D_CPU0_SB_DQS_DP<5>")
	)
	(segment
		(start 337.227164 -239.355122)
		(end 337.212432 -239.363758)
		(width 0.088646)
		(layer "In11.Cu")
		(net "M_D_CPU0_SB_DQS_DP<5>")
	)
	(segment
		(start 279.330404 -223.534986)
		(end 279.008586 -223.534986)
		(width 0.18288)
		(layer "In11.Cu")
		(net "M_D_CPU0_SB_DQS_DP<5>")
	)
	(segment
		(start 278.433276 -223.773238)
		(end 277.368 -224.4852)
		(width 0.18288)
		(layer "In11.Cu")
		(net "M_D_CPU0_SB_DQS_DP<5>")
	)
	(segment
		(start 308.439312 -224.571306)
		(end 307.988462 -224.571306)
		(width 0.18288)
		(layer "In11.Cu")
		(net "M_D_CPU0_SB_DQS_DP<5>")
	)
	(segment
		(start 293.053262 -224.100136)
		(end 292.323774 -224.100136)
		(width 0.18288)
		(layer "In11.Cu")
		(net "M_D_CPU0_SB_DQS_DP<5>")
	)
	(arc
		(start 340.031832 -239.363758)
		(mid 339.844634 -239.413901)
		(end 339.657436 -239.363758)
		(width 0.088646)
		(layer "In11.Cu")
		(net "M_D_CPU0_SB_DQS_DP<5>")
	)
	(arc
		(start 333.06385 -237.72749)
		(mid 332.787375 -237.66017)
		(end 332.513178 -237.736126)
		(width 0.088646)
		(layer "In11.Cu")
		(net "M_D_CPU0_SB_DQS_DP<5>")
	)
	(arc
		(start 340.597236 -239.363758)
		(mid 340.323037 -239.287923)
		(end 340.046564 -239.355122)
		(width 0.088646)
		(layer "In11.Cu")
		(net "M_D_CPU0_SB_DQS_DP<5>")
	)
	(arc
		(start 337.212432 -239.363758)
		(mid 337.025234 -239.413901)
		(end 336.838036 -239.363758)
		(width 0.088646)
		(layer "In11.Cu")
		(net "M_D_CPU0_SB_DQS_DP<5>")
	)
	(arc
		(start 337.777836 -239.363758)
		(mid 337.503637 -239.287923)
		(end 337.227164 -239.355122)
		(width 0.088646)
		(layer "In11.Cu")
		(net "M_D_CPU0_SB_DQS_DP<5>")
	)
	(arc
		(start 334.008222 -237.73003)
		(mid 333.72979 -237.660184)
		(end 333.452978 -237.736126)
		(width 0.088646)
		(layer "In11.Cu")
		(net "M_D_CPU0_SB_DQS_DP<5>")
	)
	(arc
		(start 342.476582 -239.363758)
		(mid 342.200023 -239.288015)
		(end 341.921846 -239.357662)
		(width 0.088646)
		(layer "In11.Cu")
		(net "M_D_CPU0_SB_DQS_DP<5>")
	)
	(arc
		(start 338.717636 -239.363758)
		(mid 338.434934 -239.287982)
		(end 338.152232 -239.363758)
		(width 0.088646)
		(layer "In11.Cu")
		(net "M_D_CPU0_SB_DQS_DP<5>")
	)
	(arc
		(start 346.236036 -239.363758)
		(mid 345.961837 -239.287923)
		(end 345.685364 -239.355122)
		(width 0.088646)
		(layer "In11.Cu")
		(net "M_D_CPU0_SB_DQS_DP<5>")
	)
	(arc
		(start 348.115636 -239.363758)
		(mid 347.841437 -239.287923)
		(end 347.564964 -239.355122)
		(width 0.088646)
		(layer "In11.Cu")
		(net "M_D_CPU0_SB_DQS_DP<5>")
	)
	(arc
		(start 333.452978 -237.736126)
		(mid 333.26578 -237.786269)
		(end 333.078582 -237.736126)
		(width 0.088646)
		(layer "In11.Cu")
		(net "M_D_CPU0_SB_DQS_DP<5>")
	)
	(arc
		(start 344.356436 -239.363758)
		(mid 344.082237 -239.287923)
		(end 343.805764 -239.355122)
		(width 0.088646)
		(layer "In11.Cu")
		(net "M_D_CPU0_SB_DQS_DP<5>")
	)
	(arc
		(start 338.152232 -239.363758)
		(mid 337.965034 -239.413901)
		(end 337.777836 -239.363758)
		(width 0.088646)
		(layer "In11.Cu")
		(net "M_D_CPU0_SB_DQS_DP<5>")
	)
	(arc
		(start 336.829146 -239.358678)
		(mid 336.698232 -239.222318)
		(end 336.650584 -239.0394)
		(width 0.088646)
		(layer "In11.Cu")
		(net "M_D_CPU0_SB_DQS_DP<5>")
	)
	(arc
		(start 332.513178 -237.736126)
		(mid 332.422922 -237.773848)
		(end 332.32598 -237.786926)
		(width 0.088646)
		(layer "In11.Cu")
		(net "M_D_CPU0_SB_DQS_DP<5>")
	)
	(arc
		(start 348.394274 -239.787938)
		(mid 348.392976 -239.777384)
		(end 348.39148 -239.766856)
		(width 0.088646)
		(layer "In11.Cu")
		(net "M_D_CPU0_SB_DQS_DP<5>")
	)
	(arc
		(start 336.357468 -238.543846)
		(mid 336.07929 -238.474123)
		(end 335.802732 -238.549942)
		(width 0.088646)
		(layer "In11.Cu")
		(net "M_D_CPU0_SB_DQS_DP<5>")
	)
	(arc
		(start 335.419446 -238.544862)
		(mid 335.288532 -238.408502)
		(end 335.240884 -238.225584)
		(width 0.088646)
		(layer "In11.Cu")
		(net "M_D_CPU0_SB_DQS_DP<5>")
	)
	(arc
		(start 339.657436 -239.363758)
		(mid 339.383237 -239.287923)
		(end 339.106764 -239.355122)
		(width 0.088646)
		(layer "In11.Cu")
		(net "M_D_CPU0_SB_DQS_DP<5>")
	)
	(arc
		(start 336.650584 -239.0394)
		(mid 336.576593 -238.759834)
		(end 336.373978 -238.553498)
		(width 0.088646)
		(layer "In11.Cu")
		(net "M_D_CPU0_SB_DQS_DP<5>")
	)
	(arc
		(start 346.610432 -239.363758)
		(mid 346.423234 -239.413901)
		(end 346.236036 -239.363758)
		(width 0.088646)
		(layer "In11.Cu")
		(net "M_D_CPU0_SB_DQS_DP<5>")
	)
	(arc
		(start 341.537036 -239.363758)
		(mid 341.262837 -239.287923)
		(end 340.986364 -239.355122)
		(width 0.088646)
		(layer "In11.Cu")
		(net "M_D_CPU0_SB_DQS_DP<5>")
	)
	(arc
		(start 343.791032 -239.363758)
		(mid 343.603834 -239.413901)
		(end 343.416636 -239.363758)
		(width 0.088646)
		(layer "In11.Cu")
		(net "M_D_CPU0_SB_DQS_DP<5>")
	)
	(arc
		(start 348.39148 -239.766856)
		(mid 348.299358 -239.533956)
		(end 348.115636 -239.363758)
		(width 0.088646)
		(layer "In11.Cu")
		(net "M_D_CPU0_SB_DQS_DP<5>")
	)
	(arc
		(start 334.947768 -237.73003)
		(mid 334.66959 -237.660307)
		(end 334.393032 -237.736126)
		(width 0.088646)
		(layer "In11.Cu")
		(net "M_D_CPU0_SB_DQS_DP<5>")
	)
	(arc
		(start 341.911432 -239.363758)
		(mid 341.724234 -239.413901)
		(end 341.537036 -239.363758)
		(width 0.088646)
		(layer "In11.Cu")
		(net "M_D_CPU0_SB_DQS_DP<5>")
	)
	(arc
		(start 340.971632 -239.363758)
		(mid 340.784434 -239.413901)
		(end 340.597236 -239.363758)
		(width 0.088646)
		(layer "In11.Cu")
		(net "M_D_CPU0_SB_DQS_DP<5>")
	)
	(arc
		(start 334.393032 -237.736126)
		(mid 334.205834 -237.786269)
		(end 334.018636 -237.736126)
		(width 0.088646)
		(layer "In11.Cu")
		(net "M_D_CPU0_SB_DQS_DP<5>")
	)
	(arc
		(start 347.175836 -239.363758)
		(mid 346.901637 -239.287923)
		(end 346.625164 -239.355122)
		(width 0.088646)
		(layer "In11.Cu")
		(net "M_D_CPU0_SB_DQS_DP<5>")
	)
	(arc
		(start 343.416636 -239.363758)
		(mid 343.139823 -239.287888)
		(end 342.861392 -239.357662)
		(width 0.088646)
		(layer "In11.Cu")
		(net "M_D_CPU0_SB_DQS_DP<5>")
	)
	(arc
		(start 335.240884 -238.225584)
		(mid 335.166893 -237.946018)
		(end 334.964278 -237.739682)
		(width 0.088646)
		(layer "In11.Cu")
		(net "M_D_CPU0_SB_DQS_DP<5>")
	)
	(arc
		(start 344.730832 -239.363758)
		(mid 344.543634 -239.413901)
		(end 344.356436 -239.363758)
		(width 0.088646)
		(layer "In11.Cu")
		(net "M_D_CPU0_SB_DQS_DP<5>")
	)
	(arc
		(start 347.550232 -239.363758)
		(mid 347.363034 -239.413901)
		(end 347.175836 -239.363758)
		(width 0.088646)
		(layer "In11.Cu")
		(net "M_D_CPU0_SB_DQS_DP<5>")
	)
	(arc
		(start 339.092032 -239.363758)
		(mid 338.904834 -239.413901)
		(end 338.717636 -239.363758)
		(width 0.088646)
		(layer "In11.Cu")
		(net "M_D_CPU0_SB_DQS_DP<5>")
	)
	(arc
		(start 335.802732 -238.549942)
		(mid 335.615534 -238.600085)
		(end 335.428336 -238.549942)
		(width 0.088646)
		(layer "In11.Cu")
		(net "M_D_CPU0_SB_DQS_DP<5>")
	)
	(arc
		(start 345.296236 -239.363758)
		(mid 345.013534 -239.287982)
		(end 344.730832 -239.363758)
		(width 0.088646)
		(layer "In11.Cu")
		(net "M_D_CPU0_SB_DQS_DP<5>")
	)
	(arc
		(start 345.670632 -239.363758)
		(mid 345.483434 -239.413901)
		(end 345.296236 -239.363758)
		(width 0.088646)
		(layer "In11.Cu")
		(net "M_D_CPU0_SB_DQS_DP<5>")
	)
	(arc
		(start 342.850978 -239.363758)
		(mid 342.66378 -239.413901)
		(end 342.476582 -239.363758)
		(width 0.088646)
		(layer "In11.Cu")
		(net "M_D_CPU0_SB_DQS_DP<5>")
	)
	(segment
		(start 347.83268 -245.272306)
		(end 347.83268 -244.73662)
		(width 0.20066)
		(layer "F.Cu")
		(net "M_D_CPU0_SB_DQS_DP<4>")
	)
	(segment
		(start 264.966704 -235.991908)
		(end 264.825226 -235.991908)
		(width 0.20066)
		(layer "F.Cu")
		(net "M_D_CPU0_SB_DQS_DP<4>")
	)
	(segment
		(start 264.824972 -235.991654)
		(end 262.746998 -235.991654)
		(width 0.1016)
		(layer "F.Cu")
		(net "M_D_CPU0_SB_DQS_DP<4>")
	)
	(segment
		(start 262.746998 -235.991654)
		(end 262.505698 -235.991654)
		(width 0.101854)
		(layer "F.Cu")
		(net "M_D_CPU0_SB_DQS_DP<4>")
	)
	(segment
		(start 267.724382 -236.416596)
		(end 267.23467 -236.416596)
		(width 0.20066)
		(layer "F.Cu")
		(net "M_D_CPU0_SB_DQS_DP<4>")
	)
	(segment
		(start 265.227816 -236.25302)
		(end 264.966704 -235.991908)
		(width 0.20066)
		(layer "F.Cu")
		(net "M_D_CPU0_SB_DQS_DP<4>")
	)
	(segment
		(start 347.832934 -245.27256)
		(end 347.83268 -245.272306)
		(width 0.20066)
		(layer "F.Cu")
		(net "M_D_CPU0_SB_DQS_DP<4>")
	)
	(segment
		(start 262.033258 -236.25556)
		(end 261.673086 -236.25556)
		(width 0.20066)
		(layer "F.Cu")
		(net "M_D_CPU0_SB_DQS_DP<4>")
	)
	(segment
		(start 262.302752 -235.986066)
		(end 262.033258 -236.25556)
		(width 0.20066)
		(layer "F.Cu")
		(net "M_D_CPU0_SB_DQS_DP<4>")
	)
	(segment
		(start 264.825226 -235.991908)
		(end 264.824972 -235.991654)
		(width 0.1016)
		(layer "F.Cu")
		(net "M_D_CPU0_SB_DQS_DP<4>")
	)
	(segment
		(start 261.673086 -236.25556)
		(end 261.250684 -236.677962)
		(width 0.20066)
		(layer "F.Cu")
		(net "M_D_CPU0_SB_DQS_DP<4>")
	)
	(segment
		(start 268.829282 -236.416596)
		(end 267.724382 -236.416596)
		(width 0.20066)
		(layer "F.Cu")
		(net "M_D_CPU0_SB_DQS_DP<4>")
	)
	(segment
		(start 261.250684 -236.677962)
		(end 260.91642 -236.677962)
		(width 0.20066)
		(layer "F.Cu")
		(net "M_D_CPU0_SB_DQS_DP<4>")
	)
	(segment
		(start 266.973304 -236.677962)
		(end 266.368784 -236.677962)
		(width 0.20066)
		(layer "F.Cu")
		(net "M_D_CPU0_SB_DQS_DP<4>")
	)
	(segment
		(start 262.50011 -235.986066)
		(end 262.302752 -235.986066)
		(width 0.20066)
		(layer "F.Cu")
		(net "M_D_CPU0_SB_DQS_DP<4>")
	)
	(segment
		(start 262.505698 -235.991654)
		(end 262.50011 -235.986066)
		(width 0.101854)
		(layer "F.Cu")
		(net "M_D_CPU0_SB_DQS_DP<4>")
	)
	(segment
		(start 266.368784 -236.677962)
		(end 265.732768 -236.25302)
		(width 0.20066)
		(layer "F.Cu")
		(net "M_D_CPU0_SB_DQS_DP<4>")
	)
	(segment
		(start 267.23467 -236.416596)
		(end 266.973304 -236.677962)
		(width 0.20066)
		(layer "F.Cu")
		(net "M_D_CPU0_SB_DQS_DP<4>")
	)
	(segment
		(start 260.91642 -236.677962)
		(end 260.655054 -236.416596)
		(width 0.20066)
		(layer "F.Cu")
		(net "M_D_CPU0_SB_DQS_DP<4>")
	)
	(segment
		(start 260.655054 -236.416596)
		(end 260.180582 -236.416596)
		(width 0.20066)
		(layer "F.Cu")
		(net "M_D_CPU0_SB_DQS_DP<4>")
	)
	(segment
		(start 265.732768 -236.25302)
		(end 265.227816 -236.25302)
		(width 0.20066)
		(layer "F.Cu")
		(net "M_D_CPU0_SB_DQS_DP<4>")
	)
	(segment
		(start 298.813982 -235.141008)
		(end 298.555664 -235.399326)
		(width 0.18288)
		(layer "In11.Cu")
		(net "M_D_CPU0_SB_DQS_DP<4>")
	)
	(segment
		(start 277.584662 -237.254542)
		(end 273.365722 -237.254542)
		(width 0.18288)
		(layer "In11.Cu")
		(net "M_D_CPU0_SB_DQS_DP<4>")
	)
	(segment
		(start 316.305184 -238.579914)
		(end 315.401706 -237.676182)
		(width 0.18288)
		(layer "In11.Cu")
		(net "M_D_CPU0_SB_DQS_DP<4>")
	)
	(segment
		(start 341.921846 -244.241066)
		(end 341.911432 -244.247162)
		(width 0.088646)
		(layer "In11.Cu")
		(net "M_D_CPU0_SB_DQS_DP<4>")
	)
	(segment
		(start 340.986364 -244.238526)
		(end 340.971632 -244.247162)
		(width 0.088646)
		(layer "In11.Cu")
		(net "M_D_CPU0_SB_DQS_DP<4>")
	)
	(segment
		(start 269.098776 -236.68609)
		(end 268.829282 -236.416596)
		(width 0.18288)
		(layer "In11.Cu")
		(net "M_D_CPU0_SB_DQS_DP<4>")
	)
	(segment
		(start 315.401706 -237.676182)
		(end 315.401198 -237.675928)
		(width 0.18288)
		(layer "In11.Cu")
		(net "M_D_CPU0_SB_DQS_DP<4>")
	)
	(segment
		(start 269.686024 -236.68609)
		(end 269.098776 -236.68609)
		(width 0.18288)
		(layer "In11.Cu")
		(net "M_D_CPU0_SB_DQS_DP<4>")
	)
	(segment
		(start 312.661554 -236.561884)
		(end 310.50611 -235.666026)
		(width 0.18288)
		(layer "In11.Cu")
		(net "M_D_CPU0_SB_DQS_DP<4>")
	)
	(segment
		(start 272.70583 -236.981238)
		(end 269.981172 -236.981238)
		(width 0.18288)
		(layer "In11.Cu")
		(net "M_D_CPU0_SB_DQS_DP<4>")
	)
	(segment
		(start 289.174428 -236.239558)
		(end 288.341562 -235.406692)
		(width 0.18288)
		(layer "In11.Cu")
		(net "M_D_CPU0_SB_DQS_DP<4>")
	)
	(segment
		(start 294.439086 -236.26572)
		(end 293.159942 -236.26572)
		(width 0.18288)
		(layer "In11.Cu")
		(net "M_D_CPU0_SB_DQS_DP<4>")
	)
	(segment
		(start 273.365722 -237.254542)
		(end 272.70583 -236.981238)
		(width 0.18288)
		(layer "In11.Cu")
		(net "M_D_CPU0_SB_DQS_DP<4>")
	)
	(segment
		(start 303.236376 -235.393738)
		(end 299.463714 -235.393738)
		(width 0.18288)
		(layer "In11.Cu")
		(net "M_D_CPU0_SB_DQS_DP<4>")
	)
	(segment
		(start 278.551894 -236.28731)
		(end 277.584662 -237.254542)
		(width 0.18288)
		(layer "In11.Cu")
		(net "M_D_CPU0_SB_DQS_DP<4>")
	)
	(segment
		(start 332.4098 -243.483892)
		(end 331.945996 -243.020088)
		(width 0.088646)
		(layer "In11.Cu")
		(net "M_D_CPU0_SB_DQS_DP<4>")
	)
	(segment
		(start 292.873684 -235.979462)
		(end 292.515544 -235.979462)
		(width 0.18288)
		(layer "In11.Cu")
		(net "M_D_CPU0_SB_DQS_DP<4>")
	)
	(segment
		(start 308.672992 -235.666026)
		(end 308.414166 -235.4072)
		(width 0.18288)
		(layer "In11.Cu")
		(net "M_D_CPU0_SB_DQS_DP<4>")
	)
	(segment
		(start 317.82131 -239.920018)
		(end 317.433198 -239.531906)
		(width 0.18288)
		(layer "In11.Cu")
		(net "M_D_CPU0_SB_DQS_DP<4>")
	)
	(segment
		(start 282.552902 -235.385102)
		(end 281.685492 -236.252512)
		(width 0.18288)
		(layer "In11.Cu")
		(net "M_D_CPU0_SB_DQS_DP<4>")
	)
	(segment
		(start 317.433198 -239.531906)
		(end 317.257176 -239.531906)
		(width 0.18288)
		(layer "In11.Cu")
		(net "M_D_CPU0_SB_DQS_DP<4>")
	)
	(segment
		(start 296.898822 -236.247686)
		(end 295.368472 -236.247686)
		(width 0.18288)
		(layer "In11.Cu")
		(net "M_D_CPU0_SB_DQS_DP<4>")
	)
	(segment
		(start 331.696822 -243.020088)
		(end 331.637132 -242.960398)
		(width 0.088646)
		(layer "In11.Cu")
		(net "M_D_CPU0_SB_DQS_DP<4>")
	)
	(segment
		(start 317.82131 -240.09604)
		(end 317.82131 -239.920018)
		(width 0.18288)
		(layer "In11.Cu")
		(net "M_D_CPU0_SB_DQS_DP<4>")
	)
	(segment
		(start 298.542964 -235.399326)
		(end 298.535344 -235.406946)
		(width 0.18288)
		(layer "In11.Cu")
		(net "M_D_CPU0_SB_DQS_DP<4>")
	)
	(segment
		(start 308.414166 -235.4072)
		(end 307.208428 -235.4072)
		(width 0.18288)
		(layer "In11.Cu")
		(net "M_D_CPU0_SB_DQS_DP<4>")
	)
	(segment
		(start 343.805764 -244.238526)
		(end 343.791032 -244.247162)
		(width 0.088646)
		(layer "In11.Cu")
		(net "M_D_CPU0_SB_DQS_DP<4>")
	)
	(segment
		(start 348.145608 -244.73662)
		(end 348.202758 -244.79377)
		(width 0.088646)
		(layer "In11.Cu")
		(net "M_D_CPU0_SB_DQS_DP<4>")
	)
	(segment
		(start 331.637132 -242.960398)
		(end 330.972922 -242.960398)
		(width 0.18288)
		(layer "In11.Cu")
		(net "M_D_CPU0_SB_DQS_DP<4>")
	)
	(segment
		(start 288.341562 -235.406692)
		(end 284.368494 -235.406692)
		(width 0.18288)
		(layer "In11.Cu")
		(net "M_D_CPU0_SB_DQS_DP<4>")
	)
	(segment
		(start 334.018382 -244.247162)
		(end 334.009492 -244.242082)
		(width 0.088646)
		(layer "In11.Cu")
		(net "M_D_CPU0_SB_DQS_DP<4>")
	)
	(segment
		(start 303.874424 -236.031786)
		(end 303.236376 -235.393738)
		(width 0.18288)
		(layer "In11.Cu")
		(net "M_D_CPU0_SB_DQS_DP<4>")
	)
	(segment
		(start 332.796134 -243.483892)
		(end 332.4098 -243.483892)
		(width 0.088646)
		(layer "In11.Cu")
		(net "M_D_CPU0_SB_DQS_DP<4>")
	)
	(segment
		(start 335.342992 -244.241066)
		(end 335.332578 -244.247162)
		(width 0.088646)
		(layer "In11.Cu")
		(net "M_D_CPU0_SB_DQS_DP<4>")
	)
	(segment
		(start 318.38519 -240.483898)
		(end 318.209168 -240.483898)
		(width 0.18288)
		(layer "In11.Cu")
		(net "M_D_CPU0_SB_DQS_DP<4>")
	)
	(segment
		(start 318.773302 -240.87201)
		(end 318.38519 -240.483898)
		(width 0.18288)
		(layer "In11.Cu")
		(net "M_D_CPU0_SB_DQS_DP<4>")
	)
	(segment
		(start 299.210984 -235.141008)
		(end 298.813982 -235.141008)
		(width 0.18288)
		(layer "In11.Cu")
		(net "M_D_CPU0_SB_DQS_DP<4>")
	)
	(segment
		(start 319.16116 -241.43589)
		(end 318.773302 -241.048032)
		(width 0.18288)
		(layer "In11.Cu")
		(net "M_D_CPU0_SB_DQS_DP<4>")
	)
	(segment
		(start 347.645482 -245.060978)
		(end 347.636592 -245.055898)
		(width 0.088646)
		(layer "In11.Cu")
		(net "M_D_CPU0_SB_DQS_DP<4>")
	)
	(segment
		(start 284.368494 -235.406692)
		(end 284.10281 -235.141008)
		(width 0.18288)
		(layer "In11.Cu")
		(net "M_D_CPU0_SB_DQS_DP<4>")
	)
	(segment
		(start 316.869318 -238.968026)
		(end 316.481206 -238.579914)
		(width 0.18288)
		(layer "In11.Cu")
		(net "M_D_CPU0_SB_DQS_DP<4>")
	)
	(segment
		(start 306.594764 -235.107226)
		(end 306.299108 -235.402882)
		(width 0.18288)
		(layer "In11.Cu")
		(net "M_D_CPU0_SB_DQS_DP<4>")
	)
	(segment
		(start 293.159942 -236.26572)
		(end 292.873684 -235.979462)
		(width 0.18288)
		(layer "In11.Cu")
		(net "M_D_CPU0_SB_DQS_DP<4>")
	)
	(segment
		(start 346.625164 -244.238526)
		(end 346.610432 -244.247162)
		(width 0.088646)
		(layer "In11.Cu")
		(net "M_D_CPU0_SB_DQS_DP<4>")
	)
	(segment
		(start 306.908454 -235.107226)
		(end 306.594764 -235.107226)
		(width 0.18288)
		(layer "In11.Cu")
		(net "M_D_CPU0_SB_DQS_DP<4>")
	)
	(segment
		(start 295.368472 -236.247686)
		(end 295.110154 -235.989368)
		(width 0.18288)
		(layer "In11.Cu")
		(net "M_D_CPU0_SB_DQS_DP<4>")
	)
	(segment
		(start 318.209168 -240.483898)
		(end 317.82131 -240.09604)
		(width 0.18288)
		(layer "In11.Cu")
		(net "M_D_CPU0_SB_DQS_DP<4>")
	)
	(segment
		(start 336.287364 -244.238526)
		(end 336.272632 -244.247162)
		(width 0.088646)
		(layer "In11.Cu")
		(net "M_D_CPU0_SB_DQS_DP<4>")
	)
	(segment
		(start 279.604978 -235.991908)
		(end 279.309576 -236.28731)
		(width 0.18288)
		(layer "In11.Cu")
		(net "M_D_CPU0_SB_DQS_DP<4>")
	)
	(segment
		(start 283.396436 -235.385102)
		(end 282.552902 -235.385102)
		(width 0.18288)
		(layer "In11.Cu")
		(net "M_D_CPU0_SB_DQS_DP<4>")
	)
	(segment
		(start 348.028768 -245.055898)
		(end 348.019878 -245.060978)
		(width 0.088646)
		(layer "In11.Cu")
		(net "M_D_CPU0_SB_DQS_DP<4>")
	)
	(segment
		(start 331.945996 -243.020088)
		(end 331.696822 -243.020088)
		(width 0.088646)
		(layer "In11.Cu")
		(net "M_D_CPU0_SB_DQS_DP<4>")
	)
	(segment
		(start 342.861392 -244.241066)
		(end 342.850978 -244.247162)
		(width 0.088646)
		(layer "In11.Cu")
		(net "M_D_CPU0_SB_DQS_DP<4>")
	)
	(segment
		(start 330.400406 -242.387882)
		(end 320.113152 -242.387882)
		(width 0.18288)
		(layer "In11.Cu")
		(net "M_D_CPU0_SB_DQS_DP<4>")
	)
	(segment
		(start 306.299108 -235.402882)
		(end 305.115468 -235.402882)
		(width 0.18288)
		(layer "In11.Cu")
		(net "M_D_CPU0_SB_DQS_DP<4>")
	)
	(segment
		(start 313.79541 -237.320582)
		(end 312.661554 -236.561884)
		(width 0.18288)
		(layer "In11.Cu")
		(net "M_D_CPU0_SB_DQS_DP<4>")
	)
	(segment
		(start 319.337182 -241.43589)
		(end 319.16116 -241.43589)
		(width 0.18288)
		(layer "In11.Cu")
		(net "M_D_CPU0_SB_DQS_DP<4>")
	)
	(segment
		(start 292.515544 -235.979462)
		(end 292.255448 -236.239558)
		(width 0.18288)
		(layer "In11.Cu")
		(net "M_D_CPU0_SB_DQS_DP<4>")
	)
	(segment
		(start 319.725294 -242.000024)
		(end 319.725294 -241.824002)
		(width 0.18288)
		(layer "In11.Cu")
		(net "M_D_CPU0_SB_DQS_DP<4>")
	)
	(segment
		(start 317.257176 -239.531906)
		(end 316.869318 -239.144048)
		(width 0.18288)
		(layer "In11.Cu")
		(net "M_D_CPU0_SB_DQS_DP<4>")
	)
	(segment
		(start 333.83093 -243.922804)
		(end 333.83093 -243.90731)
		(width 0.088646)
		(layer "In11.Cu")
		(net "M_D_CPU0_SB_DQS_DP<4>")
	)
	(segment
		(start 304.486564 -236.031786)
		(end 303.874424 -236.031786)
		(width 0.18288)
		(layer "In11.Cu")
		(net "M_D_CPU0_SB_DQS_DP<4>")
	)
	(segment
		(start 269.981172 -236.981238)
		(end 269.686024 -236.68609)
		(width 0.18288)
		(layer "In11.Cu")
		(net "M_D_CPU0_SB_DQS_DP<4>")
	)
	(segment
		(start 298.555664 -235.399326)
		(end 298.542964 -235.399326)
		(width 0.18288)
		(layer "In11.Cu")
		(net "M_D_CPU0_SB_DQS_DP<4>")
	)
	(segment
		(start 284.10281 -235.141008)
		(end 283.64053 -235.141008)
		(width 0.18288)
		(layer "In11.Cu")
		(net "M_D_CPU0_SB_DQS_DP<4>")
	)
	(segment
		(start 281.685492 -236.252512)
		(end 280.309066 -236.252512)
		(width 0.18288)
		(layer "In11.Cu")
		(net "M_D_CPU0_SB_DQS_DP<4>")
	)
	(segment
		(start 316.869318 -239.144048)
		(end 316.869318 -238.968026)
		(width 0.18288)
		(layer "In11.Cu")
		(net "M_D_CPU0_SB_DQS_DP<4>")
	)
	(segment
		(start 298.535344 -235.406946)
		(end 297.739562 -235.406946)
		(width 0.18288)
		(layer "In11.Cu")
		(net "M_D_CPU0_SB_DQS_DP<4>")
	)
	(segment
		(start 318.773302 -241.048032)
		(end 318.773302 -240.87201)
		(width 0.18288)
		(layer "In11.Cu")
		(net "M_D_CPU0_SB_DQS_DP<4>")
	)
	(segment
		(start 299.463714 -235.393738)
		(end 299.210984 -235.141008)
		(width 0.18288)
		(layer "In11.Cu")
		(net "M_D_CPU0_SB_DQS_DP<4>")
	)
	(segment
		(start 310.50611 -235.666026)
		(end 308.672992 -235.666026)
		(width 0.18288)
		(layer "In11.Cu")
		(net "M_D_CPU0_SB_DQS_DP<4>")
	)
	(segment
		(start 297.739562 -235.406946)
		(end 296.898822 -236.247686)
		(width 0.18288)
		(layer "In11.Cu")
		(net "M_D_CPU0_SB_DQS_DP<4>")
	)
	(segment
		(start 280.309066 -236.252512)
		(end 280.048462 -235.991908)
		(width 0.18288)
		(layer "In11.Cu")
		(net "M_D_CPU0_SB_DQS_DP<4>")
	)
	(segment
		(start 280.048462 -235.991908)
		(end 279.604978 -235.991908)
		(width 0.18288)
		(layer "In11.Cu")
		(net "M_D_CPU0_SB_DQS_DP<4>")
	)
	(segment
		(start 283.64053 -235.141008)
		(end 283.396436 -235.385102)
		(width 0.18288)
		(layer "In11.Cu")
		(net "M_D_CPU0_SB_DQS_DP<4>")
	)
	(segment
		(start 279.309576 -236.28731)
		(end 278.551894 -236.28731)
		(width 0.18288)
		(layer "In11.Cu")
		(net "M_D_CPU0_SB_DQS_DP<4>")
	)
	(segment
		(start 295.110154 -235.989368)
		(end 294.715438 -235.989368)
		(width 0.18288)
		(layer "In11.Cu")
		(net "M_D_CPU0_SB_DQS_DP<4>")
	)
	(segment
		(start 305.115468 -235.402882)
		(end 304.486564 -236.031786)
		(width 0.18288)
		(layer "In11.Cu")
		(net "M_D_CPU0_SB_DQS_DP<4>")
	)
	(segment
		(start 292.255448 -236.239558)
		(end 289.174428 -236.239558)
		(width 0.18288)
		(layer "In11.Cu")
		(net "M_D_CPU0_SB_DQS_DP<4>")
	)
	(segment
		(start 347.45803 -244.73662)
		(end 347.45803 -244.721126)
		(width 0.088646)
		(layer "In11.Cu")
		(net "M_D_CPU0_SB_DQS_DP<4>")
	)
	(segment
		(start 314.545726 -237.320582)
		(end 313.79541 -237.320582)
		(width 0.18288)
		(layer "In11.Cu")
		(net "M_D_CPU0_SB_DQS_DP<4>")
	)
	(segment
		(start 319.725294 -241.824002)
		(end 319.337182 -241.43589)
		(width 0.18288)
		(layer "In11.Cu")
		(net "M_D_CPU0_SB_DQS_DP<4>")
	)
	(segment
		(start 347.83268 -244.73662)
		(end 348.145608 -244.73662)
		(width 0.088646)
		(layer "In11.Cu")
		(net "M_D_CPU0_SB_DQS_DP<4>")
	)
	(segment
		(start 316.481206 -238.579914)
		(end 316.305184 -238.579914)
		(width 0.18288)
		(layer "In11.Cu")
		(net "M_D_CPU0_SB_DQS_DP<4>")
	)
	(segment
		(start 345.685364 -244.238526)
		(end 345.670632 -244.247162)
		(width 0.088646)
		(layer "In11.Cu")
		(net "M_D_CPU0_SB_DQS_DP<4>")
	)
	(segment
		(start 294.715438 -235.989368)
		(end 294.439086 -236.26572)
		(width 0.18288)
		(layer "In11.Cu")
		(net "M_D_CPU0_SB_DQS_DP<4>")
	)
	(segment
		(start 330.972922 -242.960398)
		(end 330.400406 -242.387882)
		(width 0.18288)
		(layer "In11.Cu")
		(net "M_D_CPU0_SB_DQS_DP<4>")
	)
	(segment
		(start 339.106764 -244.238526)
		(end 339.092032 -244.247162)
		(width 0.088646)
		(layer "In11.Cu")
		(net "M_D_CPU0_SB_DQS_DP<4>")
	)
	(segment
		(start 337.227164 -244.238526)
		(end 337.212432 -244.247162)
		(width 0.088646)
		(layer "In11.Cu")
		(net "M_D_CPU0_SB_DQS_DP<4>")
	)
	(segment
		(start 315.401198 -237.675928)
		(end 314.545726 -237.320582)
		(width 0.18288)
		(layer "In11.Cu")
		(net "M_D_CPU0_SB_DQS_DP<4>")
	)
	(segment
		(start 320.113152 -242.387882)
		(end 319.725294 -242.000024)
		(width 0.18288)
		(layer "In11.Cu")
		(net "M_D_CPU0_SB_DQS_DP<4>")
	)
	(segment
		(start 307.208428 -235.4072)
		(end 306.908454 -235.107226)
		(width 0.18288)
		(layer "In11.Cu")
		(net "M_D_CPU0_SB_DQS_DP<4>")
	)
	(arc
		(start 335.898236 -244.247162)
		(mid 335.621423 -244.171292)
		(end 335.342992 -244.241066)
		(width 0.088646)
		(layer "In11.Cu")
		(net "M_D_CPU0_SB_DQS_DP<4>")
	)
	(arc
		(start 348.202758 -244.79377)
		(mid 348.144639 -244.944011)
		(end 348.028768 -245.055898)
		(width 0.088646)
		(layer "In11.Cu")
		(net "M_D_CPU0_SB_DQS_DP<4>")
	)
	(arc
		(start 348.019878 -245.060978)
		(mid 347.83268 -245.111121)
		(end 347.645482 -245.060978)
		(width 0.088646)
		(layer "In11.Cu")
		(net "M_D_CPU0_SB_DQS_DP<4>")
	)
	(arc
		(start 340.597236 -244.247162)
		(mid 340.314534 -244.171386)
		(end 340.031832 -244.247162)
		(width 0.088646)
		(layer "In11.Cu")
		(net "M_D_CPU0_SB_DQS_DP<4>")
	)
	(arc
		(start 336.838036 -244.247162)
		(mid 336.563837 -244.171327)
		(end 336.287364 -244.238526)
		(width 0.088646)
		(layer "In11.Cu")
		(net "M_D_CPU0_SB_DQS_DP<4>")
	)
	(arc
		(start 341.537036 -244.247162)
		(mid 341.262837 -244.171327)
		(end 340.986364 -244.238526)
		(width 0.088646)
		(layer "In11.Cu")
		(net "M_D_CPU0_SB_DQS_DP<4>")
	)
	(arc
		(start 341.911432 -244.247162)
		(mid 341.724234 -244.297305)
		(end 341.537036 -244.247162)
		(width 0.088646)
		(layer "In11.Cu")
		(net "M_D_CPU0_SB_DQS_DP<4>")
	)
	(arc
		(start 342.476582 -244.247162)
		(mid 342.200023 -244.171419)
		(end 341.921846 -244.241066)
		(width 0.088646)
		(layer "In11.Cu")
		(net "M_D_CPU0_SB_DQS_DP<4>")
	)
	(arc
		(start 337.777836 -244.247162)
		(mid 337.503637 -244.171327)
		(end 337.227164 -244.238526)
		(width 0.088646)
		(layer "In11.Cu")
		(net "M_D_CPU0_SB_DQS_DP<4>")
	)
	(arc
		(start 335.332578 -244.247162)
		(mid 335.14538 -244.297305)
		(end 334.958182 -244.247162)
		(width 0.088646)
		(layer "In11.Cu")
		(net "M_D_CPU0_SB_DQS_DP<4>")
	)
	(arc
		(start 339.092032 -244.247162)
		(mid 338.904834 -244.297305)
		(end 338.717636 -244.247162)
		(width 0.088646)
		(layer "In11.Cu")
		(net "M_D_CPU0_SB_DQS_DP<4>")
	)
	(arc
		(start 333.548736 -243.433346)
		(mid 333.274537 -243.357511)
		(end 332.998064 -243.42471)
		(width 0.088646)
		(layer "In11.Cu")
		(net "M_D_CPU0_SB_DQS_DP<4>")
	)
	(arc
		(start 343.791032 -244.247162)
		(mid 343.603834 -244.297305)
		(end 343.416636 -244.247162)
		(width 0.088646)
		(layer "In11.Cu")
		(net "M_D_CPU0_SB_DQS_DP<4>")
	)
	(arc
		(start 334.958182 -244.247162)
		(mid 334.67548 -244.171386)
		(end 334.392778 -244.247162)
		(width 0.088646)
		(layer "In11.Cu")
		(net "M_D_CPU0_SB_DQS_DP<4>")
	)
	(arc
		(start 338.152232 -244.247162)
		(mid 337.965034 -244.297305)
		(end 337.777836 -244.247162)
		(width 0.088646)
		(layer "In11.Cu")
		(net "M_D_CPU0_SB_DQS_DP<4>")
	)
	(arc
		(start 347.636592 -245.055898)
		(mid 347.505678 -244.919538)
		(end 347.45803 -244.73662)
		(width 0.088646)
		(layer "In11.Cu")
		(net "M_D_CPU0_SB_DQS_DP<4>")
	)
	(arc
		(start 345.670632 -244.247162)
		(mid 345.483434 -244.297305)
		(end 345.296236 -244.247162)
		(width 0.088646)
		(layer "In11.Cu")
		(net "M_D_CPU0_SB_DQS_DP<4>")
	)
	(arc
		(start 332.998064 -243.42471)
		(mid 332.990876 -243.429238)
		(end 332.983586 -243.4336)
		(width 0.088646)
		(layer "In11.Cu")
		(net "M_D_CPU0_SB_DQS_DP<4>")
	)
	(arc
		(start 344.356436 -244.247162)
		(mid 344.082237 -244.171327)
		(end 343.805764 -244.238526)
		(width 0.088646)
		(layer "In11.Cu")
		(net "M_D_CPU0_SB_DQS_DP<4>")
	)
	(arc
		(start 334.392778 -244.247162)
		(mid 334.20558 -244.297305)
		(end 334.018382 -244.247162)
		(width 0.088646)
		(layer "In11.Cu")
		(net "M_D_CPU0_SB_DQS_DP<4>")
	)
	(arc
		(start 342.850978 -244.247162)
		(mid 342.66378 -244.297305)
		(end 342.476582 -244.247162)
		(width 0.088646)
		(layer "In11.Cu")
		(net "M_D_CPU0_SB_DQS_DP<4>")
	)
	(arc
		(start 336.272632 -244.247162)
		(mid 336.085434 -244.297305)
		(end 335.898236 -244.247162)
		(width 0.088646)
		(layer "In11.Cu")
		(net "M_D_CPU0_SB_DQS_DP<4>")
	)
	(arc
		(start 338.717636 -244.247162)
		(mid 338.434934 -244.171386)
		(end 338.152232 -244.247162)
		(width 0.088646)
		(layer "In11.Cu")
		(net "M_D_CPU0_SB_DQS_DP<4>")
	)
	(arc
		(start 346.610432 -244.247162)
		(mid 346.423234 -244.297305)
		(end 346.236036 -244.247162)
		(width 0.088646)
		(layer "In11.Cu")
		(net "M_D_CPU0_SB_DQS_DP<4>")
	)
	(arc
		(start 340.031832 -244.247162)
		(mid 339.844634 -244.297305)
		(end 339.657436 -244.247162)
		(width 0.088646)
		(layer "In11.Cu")
		(net "M_D_CPU0_SB_DQS_DP<4>")
	)
	(arc
		(start 337.212432 -244.247162)
		(mid 337.025234 -244.297305)
		(end 336.838036 -244.247162)
		(width 0.088646)
		(layer "In11.Cu")
		(net "M_D_CPU0_SB_DQS_DP<4>")
	)
	(arc
		(start 347.45803 -244.721126)
		(mid 347.37866 -244.447392)
		(end 347.175836 -244.247162)
		(width 0.088646)
		(layer "In11.Cu")
		(net "M_D_CPU0_SB_DQS_DP<4>")
	)
	(arc
		(start 345.296236 -244.247162)
		(mid 345.013534 -244.171386)
		(end 344.730832 -244.247162)
		(width 0.088646)
		(layer "In11.Cu")
		(net "M_D_CPU0_SB_DQS_DP<4>")
	)
	(arc
		(start 344.730832 -244.247162)
		(mid 344.543634 -244.297305)
		(end 344.356436 -244.247162)
		(width 0.088646)
		(layer "In11.Cu")
		(net "M_D_CPU0_SB_DQS_DP<4>")
	)
	(arc
		(start 333.83093 -243.90731)
		(mid 333.75156 -243.633576)
		(end 333.548736 -243.433346)
		(width 0.088646)
		(layer "In11.Cu")
		(net "M_D_CPU0_SB_DQS_DP<4>")
	)
	(arc
		(start 347.175836 -244.247162)
		(mid 346.901637 -244.171327)
		(end 346.625164 -244.238526)
		(width 0.088646)
		(layer "In11.Cu")
		(net "M_D_CPU0_SB_DQS_DP<4>")
	)
	(arc
		(start 332.983586 -243.4336)
		(mid 332.893176 -243.47111)
		(end 332.796134 -243.483892)
		(width 0.088646)
		(layer "In11.Cu")
		(net "M_D_CPU0_SB_DQS_DP<4>")
	)
	(arc
		(start 340.971632 -244.247162)
		(mid 340.784434 -244.297305)
		(end 340.597236 -244.247162)
		(width 0.088646)
		(layer "In11.Cu")
		(net "M_D_CPU0_SB_DQS_DP<4>")
	)
	(arc
		(start 334.009492 -244.242082)
		(mid 333.878578 -244.105722)
		(end 333.83093 -243.922804)
		(width 0.088646)
		(layer "In11.Cu")
		(net "M_D_CPU0_SB_DQS_DP<4>")
	)
	(arc
		(start 346.236036 -244.247162)
		(mid 345.961837 -244.171327)
		(end 345.685364 -244.238526)
		(width 0.088646)
		(layer "In11.Cu")
		(net "M_D_CPU0_SB_DQS_DP<4>")
	)
	(arc
		(start 339.657436 -244.247162)
		(mid 339.383237 -244.171327)
		(end 339.106764 -244.238526)
		(width 0.088646)
		(layer "In11.Cu")
		(net "M_D_CPU0_SB_DQS_DP<4>")
	)
	(arc
		(start 343.416636 -244.247162)
		(mid 343.139823 -244.171292)
		(end 342.861392 -244.241066)
		(width 0.088646)
		(layer "In11.Cu")
		(net "M_D_CPU0_SB_DQS_DP<4>")
	)
	(segment
		(start 263.075674 -200.716642)
		(end 262.814562 -200.45553)
		(width 0.20066)
		(layer "F.Cu")
		(net "M_D_CPU0_SB_DQS_DP<3>")
	)
	(segment
		(start 259.302758 -201.141838)
		(end 259.065776 -201.141838)
		(width 0.101854)
		(layer "F.Cu")
		(net "M_D_CPU0_SB_DQS_DP<3>")
	)
	(segment
		(start 262.120634 -200.880726)
		(end 261.794752 -200.880726)
		(width 0.20066)
		(layer "F.Cu")
		(net "M_D_CPU0_SB_DQS_DP<3>")
	)
	(segment
		(start 257.30454 -200.45553)
		(end 256.879598 -200.45553)
		(width 0.20066)
		(layer "F.Cu")
		(net "M_D_CPU0_SB_DQS_DP<3>")
	)
	(segment
		(start 264.729214 -200.716642)
		(end 263.624314 -200.716642)
		(width 0.20066)
		(layer "F.Cu")
		(net "M_D_CPU0_SB_DQS_DP<3>")
	)
	(segment
		(start 263.624314 -200.716642)
		(end 263.075674 -200.716642)
		(width 0.20066)
		(layer "F.Cu")
		(net "M_D_CPU0_SB_DQS_DP<3>")
	)
	(segment
		(start 346.893134 -230.622602)
		(end 346.89288 -230.622348)
		(width 0.20066)
		(layer "F.Cu")
		(net "M_D_CPU0_SB_DQS_DP<3>")
	)
	(segment
		(start 261.53364 -201.141838)
		(end 261.381494 -201.141838)
		(width 0.20066)
		(layer "F.Cu")
		(net "M_D_CPU0_SB_DQS_DP<3>")
	)
	(segment
		(start 261.794752 -200.880726)
		(end 261.53364 -201.141838)
		(width 0.20066)
		(layer "F.Cu")
		(net "M_D_CPU0_SB_DQS_DP<3>")
	)
	(segment
		(start 256.618486 -200.716642)
		(end 256.080514 -200.716642)
		(width 0.20066)
		(layer "F.Cu")
		(net "M_D_CPU0_SB_DQS_DP<3>")
	)
	(segment
		(start 256.879598 -200.45553)
		(end 256.618486 -200.716642)
		(width 0.20066)
		(layer "F.Cu")
		(net "M_D_CPU0_SB_DQS_DP<3>")
	)
	(segment
		(start 257.940556 -200.880726)
		(end 257.30454 -200.45553)
		(width 0.20066)
		(layer "F.Cu")
		(net "M_D_CPU0_SB_DQS_DP<3>")
	)
	(segment
		(start 262.814562 -200.45553)
		(end 262.54583 -200.45553)
		(width 0.20066)
		(layer "F.Cu")
		(net "M_D_CPU0_SB_DQS_DP<3>")
	)
	(segment
		(start 259.056378 -201.151236)
		(end 258.838192 -201.151236)
		(width 0.20066)
		(layer "F.Cu")
		(net "M_D_CPU0_SB_DQS_DP<3>")
	)
	(segment
		(start 258.838192 -201.151236)
		(end 258.567682 -200.880726)
		(width 0.20066)
		(layer "F.Cu")
		(net "M_D_CPU0_SB_DQS_DP<3>")
	)
	(segment
		(start 261.058152 -201.141838)
		(end 259.302758 -201.141838)
		(width 0.1016)
		(layer "F.Cu")
		(net "M_D_CPU0_SB_DQS_DP<3>")
	)
	(segment
		(start 261.381494 -201.141838)
		(end 261.058152 -201.141838)
		(width 0.101854)
		(layer "F.Cu")
		(net "M_D_CPU0_SB_DQS_DP<3>")
	)
	(segment
		(start 262.54583 -200.45553)
		(end 262.120634 -200.880726)
		(width 0.20066)
		(layer "F.Cu")
		(net "M_D_CPU0_SB_DQS_DP<3>")
	)
	(segment
		(start 259.065776 -201.141838)
		(end 259.056378 -201.151236)
		(width 0.101854)
		(layer "F.Cu")
		(net "M_D_CPU0_SB_DQS_DP<3>")
	)
	(segment
		(start 258.567682 -200.880726)
		(end 257.940556 -200.880726)
		(width 0.20066)
		(layer "F.Cu")
		(net "M_D_CPU0_SB_DQS_DP<3>")
	)
	(segment
		(start 346.89288 -230.622348)
		(end 346.89288 -230.086662)
		(width 0.20066)
		(layer "F.Cu")
		(net "M_D_CPU0_SB_DQS_DP<3>")
	)
	(segment
		(start 322.15836 -216.587324)
		(end 322.15836 -213.26475)
		(width 0.18288)
		(layer "In11.Cu")
		(net "M_D_CPU0_SB_DQS_DP<3>")
	)
	(segment
		(start 292.509956 -199.921876)
		(end 286.483552 -199.921876)
		(width 0.18288)
		(layer "In11.Cu")
		(net "M_D_CPU0_SB_DQS_DP<3>")
	)
	(segment
		(start 282.968446 -200.883012)
		(end 282.008326 -199.922892)
		(width 0.18288)
		(layer "In11.Cu")
		(net "M_D_CPU0_SB_DQS_DP<3>")
	)
	(segment
		(start 265.012424 -200.433432)
		(end 264.729214 -200.716642)
		(width 0.18288)
		(layer "In11.Cu")
		(net "M_D_CPU0_SB_DQS_DP<3>")
	)
	(segment
		(start 294.637714 -199.441308)
		(end 294.377618 -199.181212)
		(width 0.18288)
		(layer "In11.Cu")
		(net "M_D_CPU0_SB_DQS_DP<3>")
	)
	(segment
		(start 268.144752 -200.83907)
		(end 266.63777 -200.214738)
		(width 0.18288)
		(layer "In11.Cu")
		(net "M_D_CPU0_SB_DQS_DP<3>")
	)
	(segment
		(start 295.105074 -199.441308)
		(end 294.637714 -199.441308)
		(width 0.18288)
		(layer "In11.Cu")
		(net "M_D_CPU0_SB_DQS_DP<3>")
	)
	(segment
		(start 346.16898 -230.39451)
		(end 346.140532 -230.41102)
		(width 0.088646)
		(layer "In11.Cu")
		(net "M_D_CPU0_SB_DQS_DP<3>")
	)
	(segment
		(start 274.513802 -199.96531)
		(end 270.57477 -200.861168)
		(width 0.18288)
		(layer "In11.Cu")
		(net "M_D_CPU0_SB_DQS_DP<3>")
	)
	(segment
		(start 285.851346 -200.554082)
		(end 285.090616 -200.869804)
		(width 0.18288)
		(layer "In11.Cu")
		(net "M_D_CPU0_SB_DQS_DP<3>")
	)
	(segment
		(start 299.21835 -201.138282)
		(end 298.729654 -201.138282)
		(width 0.18288)
		(layer "In11.Cu")
		(net "M_D_CPU0_SB_DQS_DP<3>")
	)
	(segment
		(start 309.579772 -200.3933)
		(end 308.986174 -200.147174)
		(width 0.18288)
		(layer "In11.Cu")
		(net "M_D_CPU0_SB_DQS_DP<3>")
	)
	(segment
		(start 322.15836 -213.26475)
		(end 312.767472 -203.873862)
		(width 0.18288)
		(layer "In11.Cu")
		(net "M_D_CPU0_SB_DQS_DP<3>")
	)
	(segment
		(start 343.886282 -228.134672)
		(end 343.87155 -228.143308)
		(width 0.088646)
		(layer "In11.Cu")
		(net "M_D_CPU0_SB_DQS_DP<3>")
	)
	(segment
		(start 268.346682 -200.83907)
		(end 268.144752 -200.83907)
		(width 0.18288)
		(layer "In11.Cu")
		(net "M_D_CPU0_SB_DQS_DP<3>")
	)
	(segment
		(start 330.42352 -224.852484)
		(end 322.15836 -216.587324)
		(width 0.18288)
		(layer "In11.Cu")
		(net "M_D_CPU0_SB_DQS_DP<3>")
	)
	(segment
		(start 335.341468 -227.325682)
		(end 335.332578 -227.320602)
		(width 0.088646)
		(layer "In11.Cu")
		(net "M_D_CPU0_SB_DQS_DP<3>")
	)
	(segment
		(start 337.307682 -228.134672)
		(end 337.29295 -228.143308)
		(width 0.088646)
		(layer "In11.Cu")
		(net "M_D_CPU0_SB_DQS_DP<3>")
	)
	(segment
		(start 280.706322 -199.211438)
		(end 280.300684 -199.211438)
		(width 0.18288)
		(layer "In11.Cu")
		(net "M_D_CPU0_SB_DQS_DP<3>")
	)
	(segment
		(start 345.57843 -230.013256)
		(end 345.486228 -229.926642)
		(width 0.088646)
		(layer "In11.Cu")
		(net "M_D_CPU0_SB_DQS_DP<3>")
	)
	(segment
		(start 298.729654 -201.138282)
		(end 298.520104 -200.928732)
		(width 0.18288)
		(layer "In11.Cu")
		(net "M_D_CPU0_SB_DQS_DP<3>")
	)
	(segment
		(start 345.200478 -229.762304)
		(end 345.200732 -229.762304)
		(width 0.088646)
		(layer "In11.Cu")
		(net "M_D_CPU0_SB_DQS_DP<3>")
	)
	(segment
		(start 284.409388 -200.869804)
		(end 284.136084 -201.143108)
		(width 0.18288)
		(layer "In11.Cu")
		(net "M_D_CPU0_SB_DQS_DP<3>")
	)
	(segment
		(start 308.986174 -200.147174)
		(end 306.99964 -200.147174)
		(width 0.18288)
		(layer "In11.Cu")
		(net "M_D_CPU0_SB_DQS_DP<3>")
	)
	(segment
		(start 342.946482 -228.134672)
		(end 342.93175 -228.143308)
		(width 0.088646)
		(layer "In11.Cu")
		(net "M_D_CPU0_SB_DQS_DP<3>")
	)
	(segment
		(start 300.653958 -200.841356)
		(end 299.515276 -200.841356)
		(width 0.18288)
		(layer "In11.Cu")
		(net "M_D_CPU0_SB_DQS_DP<3>")
	)
	(segment
		(start 283.41828 -200.883012)
		(end 282.968446 -200.883012)
		(width 0.18288)
		(layer "In11.Cu")
		(net "M_D_CPU0_SB_DQS_DP<3>")
	)
	(segment
		(start 279.351232 -199.229726)
		(end 279.152858 -199.229726)
		(width 0.18288)
		(layer "In11.Cu")
		(net "M_D_CPU0_SB_DQS_DP<3>")
	)
	(segment
		(start 339.572346 -228.140768)
		(end 339.561932 -228.134672)
		(width 0.088646)
		(layer "In11.Cu")
		(net "M_D_CPU0_SB_DQS_DP<3>")
	)
	(segment
		(start 299.515276 -200.841356)
		(end 299.21835 -201.138282)
		(width 0.18288)
		(layer "In11.Cu")
		(net "M_D_CPU0_SB_DQS_DP<3>")
	)
	(segment
		(start 279.562814 -199.441308)
		(end 279.351232 -199.229726)
		(width 0.18288)
		(layer "In11.Cu")
		(net "M_D_CPU0_SB_DQS_DP<3>")
	)
	(segment
		(start 335.52003 -227.65258)
		(end 335.52003 -227.64496)
		(width 0.088646)
		(layer "In11.Cu")
		(net "M_D_CPU0_SB_DQS_DP<3>")
	)
	(segment
		(start 338.247482 -228.134672)
		(end 338.23275 -228.143308)
		(width 0.088646)
		(layer "In11.Cu")
		(net "M_D_CPU0_SB_DQS_DP<3>")
	)
	(segment
		(start 294.296592 -199.181212)
		(end 292.509956 -199.921876)
		(width 0.18288)
		(layer "In11.Cu")
		(net "M_D_CPU0_SB_DQS_DP<3>")
	)
	(segment
		(start 297.942254 -200.928732)
		(end 296.149014 -199.135492)
		(width 0.18288)
		(layer "In11.Cu")
		(net "M_D_CPU0_SB_DQS_DP<3>")
	)
	(segment
		(start 268.650212 -201.1426)
		(end 268.346682 -200.83907)
		(width 0.18288)
		(layer "In11.Cu")
		(net "M_D_CPU0_SB_DQS_DP<3>")
	)
	(segment
		(start 280.070814 -199.441308)
		(end 279.562814 -199.441308)
		(width 0.18288)
		(layer "In11.Cu")
		(net "M_D_CPU0_SB_DQS_DP<3>")
	)
	(segment
		(start 345.765882 -230.41102)
		(end 345.756992 -230.40594)
		(width 0.088646)
		(layer "In11.Cu")
		(net "M_D_CPU0_SB_DQS_DP<3>")
	)
	(segment
		(start 284.136084 -201.143108)
		(end 283.678376 -201.143108)
		(width 0.18288)
		(layer "In11.Cu")
		(net "M_D_CPU0_SB_DQS_DP<3>")
	)
	(segment
		(start 296.149014 -199.135492)
		(end 295.41089 -199.135492)
		(width 0.18288)
		(layer "In11.Cu")
		(net "M_D_CPU0_SB_DQS_DP<3>")
	)
	(segment
		(start 311.715912 -203.43876)
		(end 311.181242 -202.90409)
		(width 0.18288)
		(layer "In11.Cu")
		(net "M_D_CPU0_SB_DQS_DP<3>")
	)
	(segment
		(start 286.483552 -199.921876)
		(end 285.851346 -200.554082)
		(width 0.18288)
		(layer "In11.Cu")
		(net "M_D_CPU0_SB_DQS_DP<3>")
	)
	(segment
		(start 331.789532 -226.406456)
		(end 330.999846 -225.61677)
		(width 0.088646)
		(layer "In11.Cu")
		(net "M_D_CPU0_SB_DQS_DP<3>")
	)
	(segment
		(start 330.508356 -224.852484)
		(end 330.42352 -224.852484)
		(width 0.088646)
		(layer "In11.Cu")
		(net "M_D_CPU0_SB_DQS_DP<3>")
	)
	(segment
		(start 266.0396 -200.214738)
		(end 265.511534 -200.433432)
		(width 0.18288)
		(layer "In11.Cu")
		(net "M_D_CPU0_SB_DQS_DP<3>")
	)
	(segment
		(start 332.62189 -226.406456)
		(end 331.789532 -226.406456)
		(width 0.088646)
		(layer "In11.Cu")
		(net "M_D_CPU0_SB_DQS_DP<3>")
	)
	(segment
		(start 344.732356 -228.94925)
		(end 344.730832 -228.948488)
		(width 0.088646)
		(layer "In11.Cu")
		(net "M_D_CPU0_SB_DQS_DP<3>")
	)
	(segment
		(start 344.269568 -228.139752)
		(end 344.260678 -228.134672)
		(width 0.088646)
		(layer "In11.Cu")
		(net "M_D_CPU0_SB_DQS_DP<3>")
	)
	(segment
		(start 298.520104 -200.928732)
		(end 297.942254 -200.928732)
		(width 0.18288)
		(layer "In11.Cu")
		(net "M_D_CPU0_SB_DQS_DP<3>")
	)
	(segment
		(start 344.739722 -228.953568)
		(end 344.732356 -228.94925)
		(width 0.088646)
		(layer "In11.Cu")
		(net "M_D_CPU0_SB_DQS_DP<3>")
	)
	(segment
		(start 339.187536 -228.134672)
		(end 339.177122 -228.140768)
		(width 0.088646)
		(layer "In11.Cu")
		(net "M_D_CPU0_SB_DQS_DP<3>")
	)
	(segment
		(start 345.486228 -229.926642)
		(end 345.200478 -229.762304)
		(width 0.088646)
		(layer "In11.Cu")
		(net "M_D_CPU0_SB_DQS_DP<3>")
	)
	(segment
		(start 277.23973 -199.96531)
		(end 274.513802 -199.96531)
		(width 0.18288)
		(layer "In11.Cu")
		(net "M_D_CPU0_SB_DQS_DP<3>")
	)
	(segment
		(start 345.766136 -230.41102)
		(end 345.765882 -230.41102)
		(width 0.088646)
		(layer "In11.Cu")
		(net "M_D_CPU0_SB_DQS_DP<3>")
	)
	(segment
		(start 312.767472 -203.873862)
		(end 311.715912 -203.43876)
		(width 0.18288)
		(layer "In11.Cu")
		(net "M_D_CPU0_SB_DQS_DP<3>")
	)
	(segment
		(start 335.332578 -227.320602)
		(end 335.326482 -227.317046)
		(width 0.088646)
		(layer "In11.Cu")
		(net "M_D_CPU0_SB_DQS_DP<3>")
	)
	(segment
		(start 344.730832 -228.948488)
		(end 344.728038 -228.946964)
		(width 0.088646)
		(layer "In11.Cu")
		(net "M_D_CPU0_SB_DQS_DP<3>")
	)
	(segment
		(start 342.006682 -228.134672)
		(end 341.99195 -228.143308)
		(width 0.088646)
		(layer "In11.Cu")
		(net "M_D_CPU0_SB_DQS_DP<3>")
	)
	(segment
		(start 280.300684 -199.211438)
		(end 280.070814 -199.441308)
		(width 0.18288)
		(layer "In11.Cu")
		(net "M_D_CPU0_SB_DQS_DP<3>")
	)
	(segment
		(start 303.5427 -199.618092)
		(end 300.653958 -200.841356)
		(width 0.18288)
		(layer "In11.Cu")
		(net "M_D_CPU0_SB_DQS_DP<3>")
	)
	(segment
		(start 305.722274 -199.618092)
		(end 303.5427 -199.618092)
		(width 0.18288)
		(layer "In11.Cu")
		(net "M_D_CPU0_SB_DQS_DP<3>")
	)
	(segment
		(start 345.57843 -230.086662)
		(end 345.57843 -230.013256)
		(width 0.088646)
		(layer "In11.Cu")
		(net "M_D_CPU0_SB_DQS_DP<3>")
	)
	(segment
		(start 282.008326 -199.922892)
		(end 280.706322 -199.211438)
		(width 0.18288)
		(layer "In11.Cu")
		(net "M_D_CPU0_SB_DQS_DP<3>")
	)
	(segment
		(start 294.377618 -199.181212)
		(end 294.296592 -199.181212)
		(width 0.18288)
		(layer "In11.Cu")
		(net "M_D_CPU0_SB_DQS_DP<3>")
	)
	(segment
		(start 344.728038 -228.946964)
		(end 344.724736 -228.944932)
		(width 0.088646)
		(layer "In11.Cu")
		(net "M_D_CPU0_SB_DQS_DP<3>")
	)
	(segment
		(start 330.999846 -225.61677)
		(end 330.999846 -225.343974)
		(width 0.088646)
		(layer "In11.Cu")
		(net "M_D_CPU0_SB_DQS_DP<3>")
	)
	(segment
		(start 269.106142 -201.1426)
		(end 268.650212 -201.1426)
		(width 0.18288)
		(layer "In11.Cu")
		(net "M_D_CPU0_SB_DQS_DP<3>")
	)
	(segment
		(start 266.63777 -200.214738)
		(end 266.0396 -200.214738)
		(width 0.18288)
		(layer "In11.Cu")
		(net "M_D_CPU0_SB_DQS_DP<3>")
	)
	(segment
		(start 265.511534 -200.433432)
		(end 265.012424 -200.433432)
		(width 0.18288)
		(layer "In11.Cu")
		(net "M_D_CPU0_SB_DQS_DP<3>")
	)
	(segment
		(start 285.090616 -200.869804)
		(end 284.409388 -200.869804)
		(width 0.18288)
		(layer "In11.Cu")
		(net "M_D_CPU0_SB_DQS_DP<3>")
	)
	(segment
		(start 330.999846 -225.343974)
		(end 330.508356 -224.852484)
		(width 0.088646)
		(layer "In11.Cu")
		(net "M_D_CPU0_SB_DQS_DP<3>")
	)
	(segment
		(start 270.57477 -200.861168)
		(end 269.387574 -200.861168)
		(width 0.18288)
		(layer "In11.Cu")
		(net "M_D_CPU0_SB_DQS_DP<3>")
	)
	(segment
		(start 341.066882 -228.134672)
		(end 341.05215 -228.143308)
		(width 0.088646)
		(layer "In11.Cu")
		(net "M_D_CPU0_SB_DQS_DP<3>")
	)
	(segment
		(start 336.367882 -228.134672)
		(end 336.357468 -228.140768)
		(width 0.088646)
		(layer "In11.Cu")
		(net "M_D_CPU0_SB_DQS_DP<3>")
	)
	(segment
		(start 295.41089 -199.135492)
		(end 295.105074 -199.441308)
		(width 0.18288)
		(layer "In11.Cu")
		(net "M_D_CPU0_SB_DQS_DP<3>")
	)
	(segment
		(start 311.181242 -202.90409)
		(end 310.537606 -201.351388)
		(width 0.18288)
		(layer "In11.Cu")
		(net "M_D_CPU0_SB_DQS_DP<3>")
	)
	(segment
		(start 334.488282 -226.506786)
		(end 334.477868 -226.512882)
		(width 0.088646)
		(layer "In11.Cu")
		(net "M_D_CPU0_SB_DQS_DP<3>")
	)
	(segment
		(start 279.152858 -199.229726)
		(end 277.23973 -199.96531)
		(width 0.18288)
		(layer "In11.Cu")
		(net "M_D_CPU0_SB_DQS_DP<3>")
	)
	(segment
		(start 346.89288 -230.086662)
		(end 346.16898 -230.39451)
		(width 0.088646)
		(layer "In11.Cu")
		(net "M_D_CPU0_SB_DQS_DP<3>")
	)
	(segment
		(start 334.871568 -226.511866)
		(end 334.862678 -226.506786)
		(width 0.088646)
		(layer "In11.Cu")
		(net "M_D_CPU0_SB_DQS_DP<3>")
	)
	(segment
		(start 269.387574 -200.861168)
		(end 269.106142 -201.1426)
		(width 0.18288)
		(layer "In11.Cu")
		(net "M_D_CPU0_SB_DQS_DP<3>")
	)
	(segment
		(start 306.99964 -200.147174)
		(end 305.722274 -199.618092)
		(width 0.18288)
		(layer "In11.Cu")
		(net "M_D_CPU0_SB_DQS_DP<3>")
	)
	(segment
		(start 283.678376 -201.143108)
		(end 283.41828 -200.883012)
		(width 0.18288)
		(layer "In11.Cu")
		(net "M_D_CPU0_SB_DQS_DP<3>")
	)
	(segment
		(start 344.918284 -229.2731)
		(end 344.918284 -229.272846)
		(width 0.088646)
		(layer "In11.Cu")
		(net "M_D_CPU0_SB_DQS_DP<3>")
	)
	(segment
		(start 310.537606 -201.351388)
		(end 309.579772 -200.3933)
		(width 0.18288)
		(layer "In11.Cu")
		(net "M_D_CPU0_SB_DQS_DP<3>")
	)
	(arc
		(start 333.548736 -226.506786)
		(mid 333.271923 -226.582656)
		(end 332.993492 -226.512882)
		(width 0.088646)
		(layer "In11.Cu")
		(net "M_D_CPU0_SB_DQS_DP<3>")
	)
	(arc
		(start 344.44813 -228.45903)
		(mid 344.448078 -228.451663)
		(end 344.447876 -228.444298)
		(width 0.088646)
		(layer "In11.Cu")
		(net "M_D_CPU0_SB_DQS_DP<3>")
	)
	(arc
		(start 345.756992 -230.40594)
		(mid 345.626078 -230.26958)
		(end 345.57843 -230.086662)
		(width 0.088646)
		(layer "In11.Cu")
		(net "M_D_CPU0_SB_DQS_DP<3>")
	)
	(arc
		(start 345.200732 -229.762304)
		(mid 344.993972 -229.555541)
		(end 344.918284 -229.2731)
		(width 0.088646)
		(layer "In11.Cu")
		(net "M_D_CPU0_SB_DQS_DP<3>")
	)
	(arc
		(start 337.682078 -228.134672)
		(mid 337.49488 -228.084529)
		(end 337.307682 -228.134672)
		(width 0.088646)
		(layer "In11.Cu")
		(net "M_D_CPU0_SB_DQS_DP<3>")
	)
	(arc
		(start 334.862678 -226.506786)
		(mid 334.67548 -226.456643)
		(end 334.488282 -226.506786)
		(width 0.088646)
		(layer "In11.Cu")
		(net "M_D_CPU0_SB_DQS_DP<3>")
	)
	(arc
		(start 341.05215 -228.143308)
		(mid 340.775709 -228.210474)
		(end 340.501478 -228.134672)
		(width 0.088646)
		(layer "In11.Cu")
		(net "M_D_CPU0_SB_DQS_DP<3>")
	)
	(arc
		(start 341.99195 -228.143308)
		(mid 341.715509 -228.210474)
		(end 341.441278 -228.134672)
		(width 0.088646)
		(layer "In11.Cu")
		(net "M_D_CPU0_SB_DQS_DP<3>")
	)
	(arc
		(start 337.29295 -228.143308)
		(mid 337.016509 -228.210474)
		(end 336.742278 -228.134672)
		(width 0.088646)
		(layer "In11.Cu")
		(net "M_D_CPU0_SB_DQS_DP<3>")
	)
	(arc
		(start 343.320878 -228.134672)
		(mid 343.13368 -228.084529)
		(end 342.946482 -228.134672)
		(width 0.088646)
		(layer "In11.Cu")
		(net "M_D_CPU0_SB_DQS_DP<3>")
	)
	(arc
		(start 335.05013 -226.831144)
		(mid 335.002451 -226.648244)
		(end 334.871568 -226.511866)
		(width 0.088646)
		(layer "In11.Cu")
		(net "M_D_CPU0_SB_DQS_DP<3>")
	)
	(arc
		(start 332.993492 -226.512882)
		(mid 332.987415 -226.509042)
		(end 332.9813 -226.505262)
		(width 0.088646)
		(layer "In11.Cu")
		(net "M_D_CPU0_SB_DQS_DP<3>")
	)
	(arc
		(start 333.923132 -226.506786)
		(mid 333.735934 -226.456643)
		(end 333.548736 -226.506786)
		(width 0.088646)
		(layer "In11.Cu")
		(net "M_D_CPU0_SB_DQS_DP<3>")
	)
	(arc
		(start 344.447876 -228.444298)
		(mid 344.396822 -228.269718)
		(end 344.269568 -228.139752)
		(width 0.088646)
		(layer "In11.Cu")
		(net "M_D_CPU0_SB_DQS_DP<3>")
	)
	(arc
		(start 334.477868 -226.512882)
		(mid 334.19969 -226.582605)
		(end 333.923132 -226.506786)
		(width 0.088646)
		(layer "In11.Cu")
		(net "M_D_CPU0_SB_DQS_DP<3>")
	)
	(arc
		(start 344.260678 -228.134672)
		(mid 344.07348 -228.084529)
		(end 343.886282 -228.134672)
		(width 0.088646)
		(layer "In11.Cu")
		(net "M_D_CPU0_SB_DQS_DP<3>")
	)
	(arc
		(start 340.127082 -228.134672)
		(mid 339.850523 -228.210381)
		(end 339.572346 -228.140768)
		(width 0.088646)
		(layer "In11.Cu")
		(net "M_D_CPU0_SB_DQS_DP<3>")
	)
	(arc
		(start 338.621878 -228.134672)
		(mid 338.43468 -228.084529)
		(end 338.247482 -228.134672)
		(width 0.088646)
		(layer "In11.Cu")
		(net "M_D_CPU0_SB_DQS_DP<3>")
	)
	(arc
		(start 340.501478 -228.134672)
		(mid 340.31428 -228.084529)
		(end 340.127082 -228.134672)
		(width 0.088646)
		(layer "In11.Cu")
		(net "M_D_CPU0_SB_DQS_DP<3>")
	)
	(arc
		(start 342.93175 -228.143308)
		(mid 342.655309 -228.210474)
		(end 342.381078 -228.134672)
		(width 0.088646)
		(layer "In11.Cu")
		(net "M_D_CPU0_SB_DQS_DP<3>")
	)
	(arc
		(start 335.52003 -227.64496)
		(mid 335.472351 -227.46206)
		(end 335.341468 -227.325682)
		(width 0.088646)
		(layer "In11.Cu")
		(net "M_D_CPU0_SB_DQS_DP<3>")
	)
	(arc
		(start 343.87155 -228.143308)
		(mid 343.595109 -228.210474)
		(end 343.320878 -228.134672)
		(width 0.088646)
		(layer "In11.Cu")
		(net "M_D_CPU0_SB_DQS_DP<3>")
	)
	(arc
		(start 346.140532 -230.41102)
		(mid 345.953334 -230.461197)
		(end 345.766136 -230.41102)
		(width 0.088646)
		(layer "In11.Cu")
		(net "M_D_CPU0_SB_DQS_DP<3>")
	)
	(arc
		(start 335.326482 -227.317046)
		(mid 335.124069 -227.110633)
		(end 335.05013 -226.831144)
		(width 0.088646)
		(layer "In11.Cu")
		(net "M_D_CPU0_SB_DQS_DP<3>")
	)
	(arc
		(start 336.742278 -228.134672)
		(mid 336.55508 -228.084529)
		(end 336.367882 -228.134672)
		(width 0.088646)
		(layer "In11.Cu")
		(net "M_D_CPU0_SB_DQS_DP<3>")
	)
	(arc
		(start 335.802732 -228.134672)
		(mid 335.59766 -227.930993)
		(end 335.52003 -227.65258)
		(width 0.088646)
		(layer "In11.Cu")
		(net "M_D_CPU0_SB_DQS_DP<3>")
	)
	(arc
		(start 344.724736 -228.944932)
		(mid 344.522149 -228.738581)
		(end 344.44813 -228.45903)
		(width 0.088646)
		(layer "In11.Cu")
		(net "M_D_CPU0_SB_DQS_DP<3>")
	)
	(arc
		(start 339.561932 -228.134672)
		(mid 339.374734 -228.084529)
		(end 339.187536 -228.134672)
		(width 0.088646)
		(layer "In11.Cu")
		(net "M_D_CPU0_SB_DQS_DP<3>")
	)
	(arc
		(start 342.381078 -228.134672)
		(mid 342.19388 -228.084529)
		(end 342.006682 -228.134672)
		(width 0.088646)
		(layer "In11.Cu")
		(net "M_D_CPU0_SB_DQS_DP<3>")
	)
	(arc
		(start 338.23275 -228.143308)
		(mid 337.956309 -228.210474)
		(end 337.682078 -228.134672)
		(width 0.088646)
		(layer "In11.Cu")
		(net "M_D_CPU0_SB_DQS_DP<3>")
	)
	(arc
		(start 341.441278 -228.134672)
		(mid 341.25408 -228.084529)
		(end 341.066882 -228.134672)
		(width 0.088646)
		(layer "In11.Cu")
		(net "M_D_CPU0_SB_DQS_DP<3>")
	)
	(arc
		(start 336.357468 -228.140768)
		(mid 336.07929 -228.21046)
		(end 335.802732 -228.134672)
		(width 0.088646)
		(layer "In11.Cu")
		(net "M_D_CPU0_SB_DQS_DP<3>")
	)
	(arc
		(start 332.9813 -226.505262)
		(mid 332.808252 -226.431648)
		(end 332.62189 -226.406456)
		(width 0.088646)
		(layer "In11.Cu")
		(net "M_D_CPU0_SB_DQS_DP<3>")
	)
	(arc
		(start 339.177122 -228.140768)
		(mid 338.89869 -228.210582)
		(end 338.621878 -228.134672)
		(width 0.088646)
		(layer "In11.Cu")
		(net "M_D_CPU0_SB_DQS_DP<3>")
	)
	(arc
		(start 344.918284 -229.272846)
		(mid 344.870605 -229.089946)
		(end 344.739722 -228.953568)
		(width 0.088646)
		(layer "In11.Cu")
		(net "M_D_CPU0_SB_DQS_DP<3>")
	)
	(segment
		(start 343.60358 -233.064304)
		(end 343.603834 -233.06405)
		(width 0.20066)
		(layer "F.Cu")
		(net "M_D_CPU0_SB_DQS_DP<2>")
	)
	(segment
		(start 257.30454 -209.805524)
		(end 256.879598 -209.805524)
		(width 0.20066)
		(layer "F.Cu")
		(net "M_D_CPU0_SB_DQS_DP<2>")
	)
	(segment
		(start 256.879598 -209.805524)
		(end 256.618486 -210.066636)
		(width 0.20066)
		(layer "F.Cu")
		(net "M_D_CPU0_SB_DQS_DP<2>")
	)
	(segment
		(start 262.120634 -210.23072)
		(end 261.794752 -210.23072)
		(width 0.20066)
		(layer "F.Cu")
		(net "M_D_CPU0_SB_DQS_DP<2>")
	)
	(segment
		(start 261.058152 -210.491832)
		(end 259.302758 -210.491832)
		(width 0.1016)
		(layer "F.Cu")
		(net "M_D_CPU0_SB_DQS_DP<2>")
	)
	(segment
		(start 264.729214 -210.066636)
		(end 263.624314 -210.066636)
		(width 0.20066)
		(layer "F.Cu")
		(net "M_D_CPU0_SB_DQS_DP<2>")
	)
	(segment
		(start 261.381494 -210.491832)
		(end 261.058152 -210.491832)
		(width 0.101854)
		(layer "F.Cu")
		(net "M_D_CPU0_SB_DQS_DP<2>")
	)
	(segment
		(start 256.618486 -210.066636)
		(end 256.080514 -210.066636)
		(width 0.20066)
		(layer "F.Cu")
		(net "M_D_CPU0_SB_DQS_DP<2>")
	)
	(segment
		(start 262.814562 -209.805524)
		(end 262.54583 -209.805524)
		(width 0.20066)
		(layer "F.Cu")
		(net "M_D_CPU0_SB_DQS_DP<2>")
	)
	(segment
		(start 258.567682 -210.23072)
		(end 257.940556 -210.23072)
		(width 0.20066)
		(layer "F.Cu")
		(net "M_D_CPU0_SB_DQS_DP<2>")
	)
	(segment
		(start 261.794752 -210.23072)
		(end 261.53364 -210.491832)
		(width 0.20066)
		(layer "F.Cu")
		(net "M_D_CPU0_SB_DQS_DP<2>")
	)
	(segment
		(start 261.53364 -210.491832)
		(end 261.381494 -210.491832)
		(width 0.20066)
		(layer "F.Cu")
		(net "M_D_CPU0_SB_DQS_DP<2>")
	)
	(segment
		(start 263.624314 -210.066636)
		(end 263.075674 -210.066636)
		(width 0.20066)
		(layer "F.Cu")
		(net "M_D_CPU0_SB_DQS_DP<2>")
	)
	(segment
		(start 259.056378 -210.50123)
		(end 258.838192 -210.50123)
		(width 0.20066)
		(layer "F.Cu")
		(net "M_D_CPU0_SB_DQS_DP<2>")
	)
	(segment
		(start 343.603834 -233.06405)
		(end 343.603834 -232.528364)
		(width 0.20066)
		(layer "F.Cu")
		(net "M_D_CPU0_SB_DQS_DP<2>")
	)
	(segment
		(start 263.075674 -210.066636)
		(end 262.814562 -209.805524)
		(width 0.20066)
		(layer "F.Cu")
		(net "M_D_CPU0_SB_DQS_DP<2>")
	)
	(segment
		(start 259.302758 -210.491832)
		(end 259.065776 -210.491832)
		(width 0.101854)
		(layer "F.Cu")
		(net "M_D_CPU0_SB_DQS_DP<2>")
	)
	(segment
		(start 262.54583 -209.805524)
		(end 262.120634 -210.23072)
		(width 0.20066)
		(layer "F.Cu")
		(net "M_D_CPU0_SB_DQS_DP<2>")
	)
	(segment
		(start 259.065776 -210.491832)
		(end 259.056378 -210.50123)
		(width 0.101854)
		(layer "F.Cu")
		(net "M_D_CPU0_SB_DQS_DP<2>")
	)
	(segment
		(start 257.940556 -210.23072)
		(end 257.30454 -209.805524)
		(width 0.20066)
		(layer "F.Cu")
		(net "M_D_CPU0_SB_DQS_DP<2>")
	)
	(segment
		(start 258.838192 -210.50123)
		(end 258.567682 -210.23072)
		(width 0.20066)
		(layer "F.Cu")
		(net "M_D_CPU0_SB_DQS_DP<2>")
	)
	(segment
		(start 295.368472 -211.081874)
		(end 295.109392 -211.340954)
		(width 0.18288)
		(layer "In6.Cu")
		(net "M_D_CPU0_SB_DQS_DP<2>")
	)
	(segment
		(start 331.67193 -230.578152)
		(end 330.9493 -229.855522)
		(width 0.088646)
		(layer "In6.Cu")
		(net "M_D_CPU0_SB_DQS_DP<2>")
	)
	(segment
		(start 338.247482 -233.017822)
		(end 338.23275 -233.026458)
		(width 0.088646)
		(layer "In6.Cu")
		(net "M_D_CPU0_SB_DQS_DP<2>")
	)
	(segment
		(start 293.619428 -211.077302)
		(end 292.13175 -209.589624)
		(width 0.18288)
		(layer "In6.Cu")
		(net "M_D_CPU0_SB_DQS_DP<2>")
	)
	(segment
		(start 280.320496 -211.06384)
		(end 280.311606 -211.06384)
		(width 0.18288)
		(layer "In6.Cu")
		(net "M_D_CPU0_SB_DQS_DP<2>")
	)
	(segment
		(start 331.926438 -231.300274)
		(end 331.67193 -231.045766)
		(width 0.088646)
		(layer "In6.Cu")
		(net "M_D_CPU0_SB_DQS_DP<2>")
	)
	(segment
		(start 296.581068 -211.081874)
		(end 295.368472 -211.081874)
		(width 0.18288)
		(layer "In6.Cu")
		(net "M_D_CPU0_SB_DQS_DP<2>")
	)
	(segment
		(start 298.794932 -210.491324)
		(end 298.5135 -210.209892)
		(width 0.18288)
		(layer "In6.Cu")
		(net "M_D_CPU0_SB_DQS_DP<2>")
	)
	(segment
		(start 276.308312 -209.553302)
		(end 273.97075 -209.553302)
		(width 0.18288)
		(layer "In6.Cu")
		(net "M_D_CPU0_SB_DQS_DP<2>")
	)
	(segment
		(start 294.689022 -211.340954)
		(end 294.42537 -211.077302)
		(width 0.18288)
		(layer "In6.Cu")
		(net "M_D_CPU0_SB_DQS_DP<2>")
	)
	(segment
		(start 279.351994 -211.075016)
		(end 278.911812 -211.075016)
		(width 0.18288)
		(layer "In6.Cu")
		(net "M_D_CPU0_SB_DQS_DP<2>")
	)
	(segment
		(start 279.618694 -211.341716)
		(end 279.351994 -211.075016)
		(width 0.18288)
		(layer "In6.Cu")
		(net "M_D_CPU0_SB_DQS_DP<2>")
	)
	(segment
		(start 321.678046 -225.749104)
		(end 321.678046 -222.842328)
		(width 0.18288)
		(layer "In6.Cu")
		(net "M_D_CPU0_SB_DQS_DP<2>")
	)
	(segment
		(start 299.205142 -210.491324)
		(end 298.794932 -210.491324)
		(width 0.18288)
		(layer "In6.Cu")
		(net "M_D_CPU0_SB_DQS_DP<2>")
	)
	(segment
		(start 312.285634 -213.205568)
		(end 311.824624 -212.744304)
		(width 0.18288)
		(layer "In6.Cu")
		(net "M_D_CPU0_SB_DQS_DP<2>")
	)
	(segment
		(start 342.633808 -232.901744)
		(end 342.576658 -232.894886)
		(width 0.088646)
		(layer "In6.Cu")
		(net "M_D_CPU0_SB_DQS_DP<2>")
	)
	(segment
		(start 303.705514 -210.756754)
		(end 302.99025 -210.46059)
		(width 0.18288)
		(layer "In6.Cu")
		(net "M_D_CPU0_SB_DQS_DP<2>")
	)
	(segment
		(start 325.394066 -229.465124)
		(end 321.678046 -225.749104)
		(width 0.18288)
		(layer "In6.Cu")
		(net "M_D_CPU0_SB_DQS_DP<2>")
	)
	(segment
		(start 284.421072 -210.204304)
		(end 284.133798 -210.491578)
		(width 0.18288)
		(layer "In6.Cu")
		(net "M_D_CPU0_SB_DQS_DP<2>")
	)
	(segment
		(start 295.109392 -211.340954)
		(end 294.689022 -211.340954)
		(width 0.18288)
		(layer "In6.Cu")
		(net "M_D_CPU0_SB_DQS_DP<2>")
	)
	(segment
		(start 339.572346 -233.023918)
		(end 339.561932 -233.017822)
		(width 0.088646)
		(layer "In6.Cu")
		(net "M_D_CPU0_SB_DQS_DP<2>")
	)
	(segment
		(start 298.5135 -210.209892)
		(end 297.9547 -210.209892)
		(width 0.18288)
		(layer "In6.Cu")
		(net "M_D_CPU0_SB_DQS_DP<2>")
	)
	(segment
		(start 330.57211 -229.465124)
		(end 325.394066 -229.465124)
		(width 0.18288)
		(layer "In6.Cu")
		(net "M_D_CPU0_SB_DQS_DP<2>")
	)
	(segment
		(start 284.133798 -210.491578)
		(end 283.718762 -210.491578)
		(width 0.18288)
		(layer "In6.Cu")
		(net "M_D_CPU0_SB_DQS_DP<2>")
	)
	(segment
		(start 265.78179 -209.785204)
		(end 265.010646 -209.785204)
		(width 0.18288)
		(layer "In6.Cu")
		(net "M_D_CPU0_SB_DQS_DP<2>")
	)
	(segment
		(start 336.287364 -232.212642)
		(end 336.272632 -232.204006)
		(width 0.088646)
		(layer "In6.Cu")
		(net "M_D_CPU0_SB_DQS_DP<2>")
	)
	(segment
		(start 280.331418 -211.052918)
		(end 280.320496 -211.06384)
		(width 0.18288)
		(layer "In6.Cu")
		(net "M_D_CPU0_SB_DQS_DP<2>")
	)
	(segment
		(start 281.008328 -210.821016)
		(end 280.776426 -211.052918)
		(width 0.18288)
		(layer "In6.Cu")
		(net "M_D_CPU0_SB_DQS_DP<2>")
	)
	(segment
		(start 343.263474 -232.61828)
		(end 342.838278 -232.860088)
		(width 0.088646)
		(layer "In6.Cu")
		(net "M_D_CPU0_SB_DQS_DP<2>")
	)
	(segment
		(start 342.576658 -232.894886)
		(end 342.571832 -232.897426)
		(width 0.088646)
		(layer "In6.Cu")
		(net "M_D_CPU0_SB_DQS_DP<2>")
	)
	(segment
		(start 280.311606 -211.06384)
		(end 280.03373 -211.341716)
		(width 0.18288)
		(layer "In6.Cu")
		(net "M_D_CPU0_SB_DQS_DP<2>")
	)
	(segment
		(start 333.170784 -231.730042)
		(end 333.170784 -231.714548)
		(width 0.088646)
		(layer "In6.Cu")
		(net "M_D_CPU0_SB_DQS_DP<2>")
	)
	(segment
		(start 273.97075 -209.553302)
		(end 272.3896 -210.208876)
		(width 0.18288)
		(layer "In6.Cu")
		(net "M_D_CPU0_SB_DQS_DP<2>")
	)
	(segment
		(start 287.44164 -210.204304)
		(end 284.421072 -210.204304)
		(width 0.18288)
		(layer "In6.Cu")
		(net "M_D_CPU0_SB_DQS_DP<2>")
	)
	(segment
		(start 337.399884 -232.543858)
		(end 337.399884 -232.528364)
		(width 0.088646)
		(layer "In6.Cu")
		(net "M_D_CPU0_SB_DQS_DP<2>")
	)
	(segment
		(start 339.187536 -233.017822)
		(end 339.177122 -233.023918)
		(width 0.088646)
		(layer "In6.Cu")
		(net "M_D_CPU0_SB_DQS_DP<2>")
	)
	(segment
		(start 341.066882 -233.017822)
		(end 341.05215 -233.026458)
		(width 0.088646)
		(layer "In6.Cu")
		(net "M_D_CPU0_SB_DQS_DP<2>")
	)
	(segment
		(start 277.005796 -209.842354)
		(end 276.308312 -209.553302)
		(width 0.18288)
		(layer "In6.Cu")
		(net "M_D_CPU0_SB_DQS_DP<2>")
	)
	(segment
		(start 277.703534 -210.13166)
		(end 277.005796 -209.842354)
		(width 0.18288)
		(layer "In6.Cu")
		(net "M_D_CPU0_SB_DQS_DP<2>")
	)
	(segment
		(start 269.3289 -210.208876)
		(end 269.046198 -210.491578)
		(width 0.18288)
		(layer "In6.Cu")
		(net "M_D_CPU0_SB_DQS_DP<2>")
	)
	(segment
		(start 334.018636 -232.204006)
		(end 334.008222 -232.210102)
		(width 0.088646)
		(layer "In6.Cu")
		(net "M_D_CPU0_SB_DQS_DP<2>")
	)
	(segment
		(start 337.213956 -232.204768)
		(end 337.212432 -232.204006)
		(width 0.088646)
		(layer "In6.Cu")
		(net "M_D_CPU0_SB_DQS_DP<2>")
	)
	(segment
		(start 266.605766 -209.55635)
		(end 266.33424 -209.55635)
		(width 0.18288)
		(layer "In6.Cu")
		(net "M_D_CPU0_SB_DQS_DP<2>")
	)
	(segment
		(start 330.9493 -229.512368)
		(end 330.842112 -229.40518)
		(width 0.088646)
		(layer "In6.Cu")
		(net "M_D_CPU0_SB_DQS_DP<2>")
	)
	(segment
		(start 309.246524 -211.676234)
		(end 307.515006 -211.676234)
		(width 0.18288)
		(layer "In6.Cu")
		(net "M_D_CPU0_SB_DQS_DP<2>")
	)
	(segment
		(start 314.102242 -216.238074)
		(end 313.146186 -215.282018)
		(width 0.18288)
		(layer "In6.Cu")
		(net "M_D_CPU0_SB_DQS_DP<2>")
	)
	(segment
		(start 268.341602 -210.202018)
		(end 267.55471 -210.202018)
		(width 0.18288)
		(layer "In6.Cu")
		(net "M_D_CPU0_SB_DQS_DP<2>")
	)
	(segment
		(start 278.459946 -210.887818)
		(end 277.703534 -210.13166)
		(width 0.18288)
		(layer "In6.Cu")
		(net "M_D_CPU0_SB_DQS_DP<2>")
	)
	(segment
		(start 280.776426 -211.052918)
		(end 280.331418 -211.052918)
		(width 0.18288)
		(layer "In6.Cu")
		(net "M_D_CPU0_SB_DQS_DP<2>")
	)
	(segment
		(start 330.842112 -229.40518)
		(end 330.655422 -229.40518)
		(width 0.088646)
		(layer "In6.Cu")
		(net "M_D_CPU0_SB_DQS_DP<2>")
	)
	(segment
		(start 297.9547 -210.209892)
		(end 297.437302 -210.72729)
		(width 0.18288)
		(layer "In6.Cu")
		(net "M_D_CPU0_SB_DQS_DP<2>")
	)
	(segment
		(start 313.146186 -215.282018)
		(end 312.285634 -213.205568)
		(width 0.18288)
		(layer "In6.Cu")
		(net "M_D_CPU0_SB_DQS_DP<2>")
	)
	(segment
		(start 342.571832 -232.897426)
		(end 342.21547 -232.897426)
		(width 0.088646)
		(layer "In6.Cu")
		(net "M_D_CPU0_SB_DQS_DP<2>")
	)
	(segment
		(start 268.631162 -210.491578)
		(end 268.341602 -210.202018)
		(width 0.18288)
		(layer "In6.Cu")
		(net "M_D_CPU0_SB_DQS_DP<2>")
	)
	(segment
		(start 330.595478 -229.465124)
		(end 330.57211 -229.465124)
		(width 0.088646)
		(layer "In6.Cu")
		(net "M_D_CPU0_SB_DQS_DP<2>")
	)
	(segment
		(start 297.437302 -210.72729)
		(end 296.581068 -211.081874)
		(width 0.18288)
		(layer "In6.Cu")
		(net "M_D_CPU0_SB_DQS_DP<2>")
	)
	(segment
		(start 294.42537 -211.077302)
		(end 293.619428 -211.077302)
		(width 0.18288)
		(layer "In6.Cu")
		(net "M_D_CPU0_SB_DQS_DP<2>")
	)
	(segment
		(start 292.13175 -209.589624)
		(end 288.926016 -209.589624)
		(width 0.18288)
		(layer "In6.Cu")
		(net "M_D_CPU0_SB_DQS_DP<2>")
	)
	(segment
		(start 282.793694 -210.202018)
		(end 282.384246 -210.611466)
		(width 0.18288)
		(layer "In6.Cu")
		(net "M_D_CPU0_SB_DQS_DP<2>")
	)
	(segment
		(start 315.073792 -216.238074)
		(end 314.102242 -216.238074)
		(width 0.18288)
		(layer "In6.Cu")
		(net "M_D_CPU0_SB_DQS_DP<2>")
	)
	(segment
		(start 342.21547 -232.897426)
		(end 341.99195 -233.026458)
		(width 0.088646)
		(layer "In6.Cu")
		(net "M_D_CPU0_SB_DQS_DP<2>")
	)
	(segment
		(start 331.67193 -231.045766)
		(end 331.67193 -230.578152)
		(width 0.088646)
		(layer "In6.Cu")
		(net "M_D_CPU0_SB_DQS_DP<2>")
	)
	(segment
		(start 337.221322 -232.209086)
		(end 337.213956 -232.204768)
		(width 0.088646)
		(layer "In6.Cu")
		(net "M_D_CPU0_SB_DQS_DP<2>")
	)
	(segment
		(start 330.655422 -229.40518)
		(end 330.595478 -229.465124)
		(width 0.088646)
		(layer "In6.Cu")
		(net "M_D_CPU0_SB_DQS_DP<2>")
	)
	(segment
		(start 300.440852 -210.46059)
		(end 300.187614 -210.207352)
		(width 0.18288)
		(layer "In6.Cu")
		(net "M_D_CPU0_SB_DQS_DP<2>")
	)
	(segment
		(start 321.678046 -222.842328)
		(end 315.073792 -216.238074)
		(width 0.18288)
		(layer "In6.Cu")
		(net "M_D_CPU0_SB_DQS_DP<2>")
	)
	(segment
		(start 280.03373 -211.341716)
		(end 279.618694 -211.341716)
		(width 0.18288)
		(layer "In6.Cu")
		(net "M_D_CPU0_SB_DQS_DP<2>")
	)
	(segment
		(start 269.046198 -210.491578)
		(end 268.631162 -210.491578)
		(width 0.18288)
		(layer "In6.Cu")
		(net "M_D_CPU0_SB_DQS_DP<2>")
	)
	(segment
		(start 272.3896 -210.208876)
		(end 269.3289 -210.208876)
		(width 0.18288)
		(layer "In6.Cu")
		(net "M_D_CPU0_SB_DQS_DP<2>")
	)
	(segment
		(start 267.55471 -210.202018)
		(end 267.12291 -209.770726)
		(width 0.18288)
		(layer "In6.Cu")
		(net "M_D_CPU0_SB_DQS_DP<2>")
	)
	(segment
		(start 267.12291 -209.770726)
		(end 266.605766 -209.55635)
		(width 0.18288)
		(layer "In6.Cu")
		(net "M_D_CPU0_SB_DQS_DP<2>")
	)
	(segment
		(start 266.33424 -209.55635)
		(end 265.78179 -209.785204)
		(width 0.18288)
		(layer "In6.Cu")
		(net "M_D_CPU0_SB_DQS_DP<2>")
	)
	(segment
		(start 330.9493 -229.855522)
		(end 330.9493 -229.512368)
		(width 0.088646)
		(layer "In6.Cu")
		(net "M_D_CPU0_SB_DQS_DP<2>")
	)
	(segment
		(start 281.879294 -210.821016)
		(end 281.008328 -210.821016)
		(width 0.18288)
		(layer "In6.Cu")
		(net "M_D_CPU0_SB_DQS_DP<2>")
	)
	(segment
		(start 265.010646 -209.785204)
		(end 264.729214 -210.066636)
		(width 0.18288)
		(layer "In6.Cu")
		(net "M_D_CPU0_SB_DQS_DP<2>")
	)
	(segment
		(start 283.429202 -210.202018)
		(end 282.793694 -210.202018)
		(width 0.18288)
		(layer "In6.Cu")
		(net "M_D_CPU0_SB_DQS_DP<2>")
	)
	(segment
		(start 300.187614 -210.207352)
		(end 299.489114 -210.207352)
		(width 0.18288)
		(layer "In6.Cu")
		(net "M_D_CPU0_SB_DQS_DP<2>")
	)
	(segment
		(start 299.489114 -210.207352)
		(end 299.205142 -210.491324)
		(width 0.18288)
		(layer "In6.Cu")
		(net "M_D_CPU0_SB_DQS_DP<2>")
	)
	(segment
		(start 307.515006 -211.676234)
		(end 306.763166 -211.36483)
		(width 0.18288)
		(layer "In6.Cu")
		(net "M_D_CPU0_SB_DQS_DP<2>")
	)
	(segment
		(start 283.718762 -210.491578)
		(end 283.429202 -210.202018)
		(width 0.18288)
		(layer "In6.Cu")
		(net "M_D_CPU0_SB_DQS_DP<2>")
	)
	(segment
		(start 302.99025 -210.46059)
		(end 300.440852 -210.46059)
		(width 0.18288)
		(layer "In6.Cu")
		(net "M_D_CPU0_SB_DQS_DP<2>")
	)
	(segment
		(start 288.926016 -209.589624)
		(end 287.44164 -210.204304)
		(width 0.18288)
		(layer "In6.Cu")
		(net "M_D_CPU0_SB_DQS_DP<2>")
	)
	(segment
		(start 282.384246 -210.611466)
		(end 281.879294 -210.821016)
		(width 0.18288)
		(layer "In6.Cu")
		(net "M_D_CPU0_SB_DQS_DP<2>")
	)
	(segment
		(start 278.911812 -211.075016)
		(end 278.459946 -210.887818)
		(width 0.18288)
		(layer "In6.Cu")
		(net "M_D_CPU0_SB_DQS_DP<2>")
	)
	(segment
		(start 311.824624 -212.744304)
		(end 309.246524 -211.676234)
		(width 0.18288)
		(layer "In6.Cu")
		(net "M_D_CPU0_SB_DQS_DP<2>")
	)
	(segment
		(start 306.763166 -211.36483)
		(end 303.705514 -210.756754)
		(width 0.18288)
		(layer "In6.Cu")
		(net "M_D_CPU0_SB_DQS_DP<2>")
	)
	(arc
		(start 341.05215 -233.026458)
		(mid 340.775675 -233.093778)
		(end 340.501478 -233.017822)
		(width 0.088646)
		(layer "In6.Cu")
		(net "M_D_CPU0_SB_DQS_DP<2>")
	)
	(arc
		(start 335.332832 -232.204006)
		(mid 335.145634 -232.153863)
		(end 334.958436 -232.204006)
		(width 0.088646)
		(layer "In6.Cu")
		(net "M_D_CPU0_SB_DQS_DP<2>")
	)
	(arc
		(start 334.008222 -232.210102)
		(mid 333.454747 -232.205107)
		(end 333.170784 -231.730042)
		(width 0.088646)
		(layer "In6.Cu")
		(net "M_D_CPU0_SB_DQS_DP<2>")
	)
	(arc
		(start 343.603834 -232.528364)
		(mid 343.427813 -232.551201)
		(end 343.263474 -232.61828)
		(width 0.088646)
		(layer "In6.Cu")
		(net "M_D_CPU0_SB_DQS_DP<2>")
	)
	(arc
		(start 336.838036 -232.204006)
		(mid 336.563837 -232.279841)
		(end 336.287364 -232.212642)
		(width 0.088646)
		(layer "In6.Cu")
		(net "M_D_CPU0_SB_DQS_DP<2>")
	)
	(arc
		(start 338.23275 -233.026458)
		(mid 337.681557 -233.01766)
		(end 337.399884 -232.543858)
		(width 0.088646)
		(layer "In6.Cu")
		(net "M_D_CPU0_SB_DQS_DP<2>")
	)
	(arc
		(start 339.177122 -233.023918)
		(mid 338.89869 -233.093764)
		(end 338.621878 -233.017822)
		(width 0.088646)
		(layer "In6.Cu")
		(net "M_D_CPU0_SB_DQS_DP<2>")
	)
	(arc
		(start 332.608936 -231.39019)
		(mid 332.252413 -231.461093)
		(end 331.926438 -231.300274)
		(width 0.088646)
		(layer "In6.Cu")
		(net "M_D_CPU0_SB_DQS_DP<2>")
	)
	(arc
		(start 335.898236 -232.204006)
		(mid 335.615534 -232.279782)
		(end 335.332832 -232.204006)
		(width 0.088646)
		(layer "In6.Cu")
		(net "M_D_CPU0_SB_DQS_DP<2>")
	)
	(arc
		(start 340.501478 -233.017822)
		(mid 340.31428 -232.967679)
		(end 340.127082 -233.017822)
		(width 0.088646)
		(layer "In6.Cu")
		(net "M_D_CPU0_SB_DQS_DP<2>")
	)
	(arc
		(start 341.441278 -233.017822)
		(mid 341.25408 -232.967679)
		(end 341.066882 -233.017822)
		(width 0.088646)
		(layer "In6.Cu")
		(net "M_D_CPU0_SB_DQS_DP<2>")
	)
	(arc
		(start 342.838278 -232.860088)
		(mid 342.739436 -232.897598)
		(end 342.633808 -232.901744)
		(width 0.088646)
		(layer "In6.Cu")
		(net "M_D_CPU0_SB_DQS_DP<2>")
	)
	(arc
		(start 337.399884 -232.528364)
		(mid 337.352205 -232.345464)
		(end 337.221322 -232.209086)
		(width 0.088646)
		(layer "In6.Cu")
		(net "M_D_CPU0_SB_DQS_DP<2>")
	)
	(arc
		(start 341.99195 -233.026458)
		(mid 341.715475 -233.093778)
		(end 341.441278 -233.017822)
		(width 0.088646)
		(layer "In6.Cu")
		(net "M_D_CPU0_SB_DQS_DP<2>")
	)
	(arc
		(start 334.958436 -232.204006)
		(mid 334.675734 -232.279782)
		(end 334.393032 -232.204006)
		(width 0.088646)
		(layer "In6.Cu")
		(net "M_D_CPU0_SB_DQS_DP<2>")
	)
	(arc
		(start 334.393032 -232.204006)
		(mid 334.205834 -232.153863)
		(end 334.018636 -232.204006)
		(width 0.088646)
		(layer "In6.Cu")
		(net "M_D_CPU0_SB_DQS_DP<2>")
	)
	(arc
		(start 338.621878 -233.017822)
		(mid 338.43468 -232.967679)
		(end 338.247482 -233.017822)
		(width 0.088646)
		(layer "In6.Cu")
		(net "M_D_CPU0_SB_DQS_DP<2>")
	)
	(arc
		(start 339.561932 -233.017822)
		(mid 339.374734 -232.967679)
		(end 339.187536 -233.017822)
		(width 0.088646)
		(layer "In6.Cu")
		(net "M_D_CPU0_SB_DQS_DP<2>")
	)
	(arc
		(start 340.127082 -233.017822)
		(mid 339.850523 -233.093565)
		(end 339.572346 -233.023918)
		(width 0.088646)
		(layer "In6.Cu")
		(net "M_D_CPU0_SB_DQS_DP<2>")
	)
	(arc
		(start 337.212432 -232.204006)
		(mid 337.025234 -232.153863)
		(end 336.838036 -232.204006)
		(width 0.088646)
		(layer "In6.Cu")
		(net "M_D_CPU0_SB_DQS_DP<2>")
	)
	(arc
		(start 333.170784 -231.714548)
		(mid 332.983485 -231.390107)
		(end 332.608936 -231.39019)
		(width 0.088646)
		(layer "In6.Cu")
		(net "M_D_CPU0_SB_DQS_DP<2>")
	)
	(arc
		(start 336.272632 -232.204006)
		(mid 336.085434 -232.153863)
		(end 335.898236 -232.204006)
		(width 0.088646)
		(layer "In6.Cu")
		(net "M_D_CPU0_SB_DQS_DP<2>")
	)
	(segment
		(start 258.567682 -219.580714)
		(end 257.940556 -219.580714)
		(width 0.20066)
		(layer "F.Cu")
		(net "M_D_CPU0_SB_DQS_DP<1>")
	)
	(segment
		(start 261.381494 -219.841826)
		(end 261.058152 -219.841826)
		(width 0.101854)
		(layer "F.Cu")
		(net "M_D_CPU0_SB_DQS_DP<1>")
	)
	(segment
		(start 256.879598 -219.155518)
		(end 256.618486 -219.41663)
		(width 0.20066)
		(layer "F.Cu")
		(net "M_D_CPU0_SB_DQS_DP<1>")
	)
	(segment
		(start 257.940556 -219.580714)
		(end 257.30454 -219.155518)
		(width 0.20066)
		(layer "F.Cu")
		(net "M_D_CPU0_SB_DQS_DP<1>")
	)
	(segment
		(start 261.53364 -219.841826)
		(end 261.381494 -219.841826)
		(width 0.20066)
		(layer "F.Cu")
		(net "M_D_CPU0_SB_DQS_DP<1>")
	)
	(segment
		(start 259.065776 -219.841826)
		(end 259.056378 -219.851224)
		(width 0.101854)
		(layer "F.Cu")
		(net "M_D_CPU0_SB_DQS_DP<1>")
	)
	(segment
		(start 259.302758 -219.841826)
		(end 259.065776 -219.841826)
		(width 0.101854)
		(layer "F.Cu")
		(net "M_D_CPU0_SB_DQS_DP<1>")
	)
	(segment
		(start 263.624314 -219.41663)
		(end 263.075674 -219.41663)
		(width 0.20066)
		(layer "F.Cu")
		(net "M_D_CPU0_SB_DQS_DP<1>")
	)
	(segment
		(start 257.30454 -219.155518)
		(end 256.879598 -219.155518)
		(width 0.20066)
		(layer "F.Cu")
		(net "M_D_CPU0_SB_DQS_DP<1>")
	)
	(segment
		(start 261.058152 -219.841826)
		(end 259.302758 -219.841826)
		(width 0.1016)
		(layer "F.Cu")
		(net "M_D_CPU0_SB_DQS_DP<1>")
	)
	(segment
		(start 262.814562 -219.155518)
		(end 262.54583 -219.155518)
		(width 0.20066)
		(layer "F.Cu")
		(net "M_D_CPU0_SB_DQS_DP<1>")
	)
	(segment
		(start 259.056378 -219.851224)
		(end 258.838192 -219.851224)
		(width 0.20066)
		(layer "F.Cu")
		(net "M_D_CPU0_SB_DQS_DP<1>")
	)
	(segment
		(start 256.618486 -219.41663)
		(end 256.080514 -219.41663)
		(width 0.20066)
		(layer "F.Cu")
		(net "M_D_CPU0_SB_DQS_DP<1>")
	)
	(segment
		(start 258.838192 -219.851224)
		(end 258.567682 -219.580714)
		(width 0.20066)
		(layer "F.Cu")
		(net "M_D_CPU0_SB_DQS_DP<1>")
	)
	(segment
		(start 262.120634 -219.580714)
		(end 261.794752 -219.580714)
		(width 0.20066)
		(layer "F.Cu")
		(net "M_D_CPU0_SB_DQS_DP<1>")
	)
	(segment
		(start 264.729214 -219.41663)
		(end 263.624314 -219.41663)
		(width 0.20066)
		(layer "F.Cu")
		(net "M_D_CPU0_SB_DQS_DP<1>")
	)
	(segment
		(start 261.794752 -219.580714)
		(end 261.53364 -219.841826)
		(width 0.20066)
		(layer "F.Cu")
		(net "M_D_CPU0_SB_DQS_DP<1>")
	)
	(segment
		(start 346.893134 -235.506006)
		(end 346.89288 -235.505752)
		(width 0.20066)
		(layer "F.Cu")
		(net "M_D_CPU0_SB_DQS_DP<1>")
	)
	(segment
		(start 262.54583 -219.155518)
		(end 262.120634 -219.580714)
		(width 0.20066)
		(layer "F.Cu")
		(net "M_D_CPU0_SB_DQS_DP<1>")
	)
	(segment
		(start 263.075674 -219.41663)
		(end 262.814562 -219.155518)
		(width 0.20066)
		(layer "F.Cu")
		(net "M_D_CPU0_SB_DQS_DP<1>")
	)
	(segment
		(start 346.89288 -235.505752)
		(end 346.89288 -234.970066)
		(width 0.20066)
		(layer "F.Cu")
		(net "M_D_CPU0_SB_DQS_DP<1>")
	)
	(segment
		(start 298.739814 -212.190838)
		(end 298.530264 -211.981288)
		(width 0.18288)
		(layer "In11.Cu")
		(net "M_D_CPU0_SB_DQS_DP<1>")
	)
	(segment
		(start 298.530264 -211.981288)
		(end 297.965114 -211.981288)
		(width 0.18288)
		(layer "In11.Cu")
		(net "M_D_CPU0_SB_DQS_DP<1>")
	)
	(segment
		(start 345.860878 -235.339128)
		(end 345.505278 -235.339128)
		(width 0.088646)
		(layer "In11.Cu")
		(net "M_D_CPU0_SB_DQS_DP<1>")
	)
	(segment
		(start 295.147492 -213.040468)
		(end 294.657272 -213.040468)
		(width 0.18288)
		(layer "In11.Cu")
		(net "M_D_CPU0_SB_DQS_DP<1>")
	)
	(segment
		(start 294.398446 -212.781642)
		(end 293.95166 -212.781642)
		(width 0.18288)
		(layer "In11.Cu")
		(net "M_D_CPU0_SB_DQS_DP<1>")
	)
	(segment
		(start 275.086064 -216.734898)
		(end 274.862036 -217.275918)
		(width 0.18288)
		(layer "In11.Cu")
		(net "M_D_CPU0_SB_DQS_DP<1>")
	)
	(segment
		(start 293.95166 -212.781642)
		(end 293.51605 -213.217252)
		(width 0.18288)
		(layer "In11.Cu")
		(net "M_D_CPU0_SB_DQS_DP<1>")
	)
	(segment
		(start 315.199776 -216.997026)
		(end 314.611004 -216.408508)
		(width 0.18288)
		(layer "In11.Cu")
		(net "M_D_CPU0_SB_DQS_DP<1>")
	)
	(segment
		(start 276.823932 -212.61705)
		(end 275.796248 -213.042754)
		(width 0.18288)
		(layer "In11.Cu")
		(net "M_D_CPU0_SB_DQS_DP<1>")
	)
	(segment
		(start 304.53203 -212.917786)
		(end 302.076612 -211.901024)
		(width 0.18288)
		(layer "In11.Cu")
		(net "M_D_CPU0_SB_DQS_DP<1>")
	)
	(segment
		(start 340.986364 -235.46816)
		(end 340.986872 -235.46816)
		(width 0.088646)
		(layer "In11.Cu")
		(net "M_D_CPU0_SB_DQS_DP<1>")
	)
	(segment
		(start 342.865964 -235.46816)
		(end 342.851232 -235.459524)
		(width 0.088646)
		(layer "In11.Cu")
		(net "M_D_CPU0_SB_DQS_DP<1>")
	)
	(segment
		(start 330.39685 -231.322372)
		(end 330.336906 -231.382316)
		(width 0.088646)
		(layer "In11.Cu")
		(net "M_D_CPU0_SB_DQS_DP<1>")
	)
	(segment
		(start 274.862036 -217.275918)
		(end 274.123404 -218.01455)
		(width 0.18288)
		(layer "In11.Cu")
		(net "M_D_CPU0_SB_DQS_DP<1>")
	)
	(segment
		(start 332.326488 -233.093768)
		(end 332.00975 -233.093768)
		(width 0.088646)
		(layer "In11.Cu")
		(net "M_D_CPU0_SB_DQS_DP<1>")
	)
	(segment
		(start 330.885546 -231.969564)
		(end 330.885546 -231.488742)
		(width 0.088646)
		(layer "In11.Cu")
		(net "M_D_CPU0_SB_DQS_DP<1>")
	)
	(segment
		(start 265.027664 -219.11818)
		(end 264.729214 -219.41663)
		(width 0.18288)
		(layer "In11.Cu")
		(net "M_D_CPU0_SB_DQS_DP<1>")
	)
	(segment
		(start 306.380896 -212.917786)
		(end 304.53203 -212.917786)
		(width 0.18288)
		(layer "In11.Cu")
		(net "M_D_CPU0_SB_DQS_DP<1>")
	)
	(segment
		(start 265.402568 -219.11818)
		(end 265.027664 -219.11818)
		(width 0.18288)
		(layer "In11.Cu")
		(net "M_D_CPU0_SB_DQS_DP<1>")
	)
	(segment
		(start 345.865704 -235.336588)
		(end 345.860878 -235.339128)
		(width 0.088646)
		(layer "In11.Cu")
		(net "M_D_CPU0_SB_DQS_DP<1>")
	)
	(segment
		(start 269.091156 -219.84081)
		(end 268.602968 -219.84081)
		(width 0.18288)
		(layer "In11.Cu")
		(net "M_D_CPU0_SB_DQS_DP<1>")
	)
	(segment
		(start 289.358324 -212.735922)
		(end 287.332166 -211.896706)
		(width 0.18288)
		(layer "In11.Cu")
		(net "M_D_CPU0_SB_DQS_DP<1>")
	)
	(segment
		(start 267.52804 -219.54744)
		(end 267.082778 -219.102178)
		(width 0.18288)
		(layer "In11.Cu")
		(net "M_D_CPU0_SB_DQS_DP<1>")
	)
	(segment
		(start 270.897858 -219.569284)
		(end 269.362682 -219.569284)
		(width 0.18288)
		(layer "In11.Cu")
		(net "M_D_CPU0_SB_DQS_DP<1>")
	)
	(segment
		(start 293.083742 -213.396322)
		(end 292.425628 -213.396322)
		(width 0.18288)
		(layer "In11.Cu")
		(net "M_D_CPU0_SB_DQS_DP<1>")
	)
	(segment
		(start 275.796248 -213.042754)
		(end 275.086064 -213.752684)
		(width 0.18288)
		(layer "In11.Cu")
		(net "M_D_CPU0_SB_DQS_DP<1>")
	)
	(segment
		(start 316.258194 -219.552266)
		(end 315.199776 -216.997026)
		(width 0.18288)
		(layer "In11.Cu")
		(net "M_D_CPU0_SB_DQS_DP<1>")
	)
	(segment
		(start 338.166964 -233.840528)
		(end 338.152232 -233.831892)
		(width 0.088646)
		(layer "In11.Cu")
		(net "M_D_CPU0_SB_DQS_DP<1>")
	)
	(segment
		(start 330.885546 -231.488742)
		(end 330.719176 -231.322372)
		(width 0.088646)
		(layer "In11.Cu")
		(net "M_D_CPU0_SB_DQS_DP<1>")
	)
	(segment
		(start 284.13964 -212.192108)
		(end 283.673804 -212.192108)
		(width 0.18288)
		(layer "In11.Cu")
		(net "M_D_CPU0_SB_DQS_DP<1>")
	)
	(segment
		(start 265.863832 -218.927172)
		(end 265.402568 -219.11818)
		(width 0.18288)
		(layer "In11.Cu")
		(net "M_D_CPU0_SB_DQS_DP<1>")
	)
	(segment
		(start 279.287224 -212.78596)
		(end 278.539194 -212.78596)
		(width 0.18288)
		(layer "In11.Cu")
		(net "M_D_CPU0_SB_DQS_DP<1>")
	)
	(segment
		(start 269.362682 -219.569284)
		(end 269.091156 -219.84081)
		(width 0.18288)
		(layer "In11.Cu")
		(net "M_D_CPU0_SB_DQS_DP<1>")
	)
	(segment
		(start 295.42359 -212.76437)
		(end 295.147492 -213.040468)
		(width 0.18288)
		(layer "In11.Cu")
		(net "M_D_CPU0_SB_DQS_DP<1>")
	)
	(segment
		(start 282.913582 -211.971128)
		(end 282.120594 -212.764116)
		(width 0.18288)
		(layer "In11.Cu")
		(net "M_D_CPU0_SB_DQS_DP<1>")
	)
	(segment
		(start 268.602968 -219.84081)
		(end 268.309598 -219.54744)
		(width 0.18288)
		(layer "In11.Cu")
		(net "M_D_CPU0_SB_DQS_DP<1>")
	)
	(segment
		(start 340.986872 -235.46816)
		(end 340.965536 -235.455968)
		(width 0.088646)
		(layer "In11.Cu")
		(net "M_D_CPU0_SB_DQS_DP<1>")
	)
	(segment
		(start 287.332166 -211.896706)
		(end 284.435042 -211.896706)
		(width 0.18288)
		(layer "In11.Cu")
		(net "M_D_CPU0_SB_DQS_DP<1>")
	)
	(segment
		(start 346.55252 -235.059982)
		(end 346.127324 -235.30179)
		(width 0.088646)
		(layer "In11.Cu")
		(net "M_D_CPU0_SB_DQS_DP<1>")
	)
	(segment
		(start 311.758584 -216.195148)
		(end 309.508144 -215.263476)
		(width 0.18288)
		(layer "In11.Cu")
		(net "M_D_CPU0_SB_DQS_DP<1>")
	)
	(segment
		(start 340.219284 -234.171744)
		(end 340.219284 -234.15625)
		(width 0.088646)
		(layer "In11.Cu")
		(net "M_D_CPU0_SB_DQS_DP<1>")
	)
	(segment
		(start 345.505278 -235.339128)
		(end 345.281758 -235.467906)
		(width 0.088646)
		(layer "In11.Cu")
		(net "M_D_CPU0_SB_DQS_DP<1>")
	)
	(segment
		(start 330.336906 -231.382316)
		(end 328.088498 -231.382316)
		(width 0.18288)
		(layer "In11.Cu")
		(net "M_D_CPU0_SB_DQS_DP<1>")
	)
	(segment
		(start 343.805764 -235.46816)
		(end 343.791032 -235.459524)
		(width 0.088646)
		(layer "In11.Cu")
		(net "M_D_CPU0_SB_DQS_DP<1>")
	)
	(segment
		(start 309.508144 -215.263476)
		(end 307.715158 -213.47049)
		(width 0.18288)
		(layer "In11.Cu")
		(net "M_D_CPU0_SB_DQS_DP<1>")
	)
	(segment
		(start 268.309598 -219.54744)
		(end 267.52804 -219.54744)
		(width 0.18288)
		(layer "In11.Cu")
		(net "M_D_CPU0_SB_DQS_DP<1>")
	)
	(segment
		(start 297.59148 -212.354922)
		(end 296.603674 -212.76437)
		(width 0.18288)
		(layer "In11.Cu")
		(net "M_D_CPU0_SB_DQS_DP<1>")
	)
	(segment
		(start 274.123404 -218.01455)
		(end 271.270984 -219.196158)
		(width 0.18288)
		(layer "In11.Cu")
		(net "M_D_CPU0_SB_DQS_DP<1>")
	)
	(segment
		(start 284.435042 -211.896706)
		(end 284.13964 -212.192108)
		(width 0.18288)
		(layer "In11.Cu")
		(net "M_D_CPU0_SB_DQS_DP<1>")
	)
	(segment
		(start 294.657272 -213.040468)
		(end 294.398446 -212.781642)
		(width 0.18288)
		(layer "In11.Cu")
		(net "M_D_CPU0_SB_DQS_DP<1>")
	)
	(segment
		(start 292.425628 -213.396322)
		(end 290.831016 -212.735922)
		(width 0.18288)
		(layer "In11.Cu")
		(net "M_D_CPU0_SB_DQS_DP<1>")
	)
	(segment
		(start 280.307288 -212.764116)
		(end 280.030682 -213.040722)
		(width 0.18288)
		(layer "In11.Cu")
		(net "M_D_CPU0_SB_DQS_DP<1>")
	)
	(segment
		(start 282.120594 -212.764116)
		(end 280.307288 -212.764116)
		(width 0.18288)
		(layer "In11.Cu")
		(net "M_D_CPU0_SB_DQS_DP<1>")
	)
	(segment
		(start 266.660122 -218.927172)
		(end 265.863832 -218.927172)
		(width 0.18288)
		(layer "In11.Cu")
		(net "M_D_CPU0_SB_DQS_DP<1>")
	)
	(segment
		(start 280.030682 -213.040722)
		(end 279.541986 -213.040722)
		(width 0.18288)
		(layer "In11.Cu")
		(net "M_D_CPU0_SB_DQS_DP<1>")
	)
	(segment
		(start 307.715158 -213.47049)
		(end 306.380896 -212.917786)
		(width 0.18288)
		(layer "In11.Cu")
		(net "M_D_CPU0_SB_DQS_DP<1>")
	)
	(segment
		(start 345.922854 -235.343446)
		(end 345.865704 -235.336588)
		(width 0.088646)
		(layer "In11.Cu")
		(net "M_D_CPU0_SB_DQS_DP<1>")
	)
	(segment
		(start 296.603674 -212.76437)
		(end 295.42359 -212.76437)
		(width 0.18288)
		(layer "In11.Cu")
		(net "M_D_CPU0_SB_DQS_DP<1>")
	)
	(segment
		(start 283.452824 -211.971128)
		(end 282.913582 -211.971128)
		(width 0.18288)
		(layer "In11.Cu")
		(net "M_D_CPU0_SB_DQS_DP<1>")
	)
	(segment
		(start 277.279862 -212.160612)
		(end 276.823932 -212.61705)
		(width 0.18288)
		(layer "In11.Cu")
		(net "M_D_CPU0_SB_DQS_DP<1>")
	)
	(segment
		(start 337.227164 -233.840528)
		(end 337.212432 -233.831892)
		(width 0.088646)
		(layer "In11.Cu")
		(net "M_D_CPU0_SB_DQS_DP<1>")
	)
	(segment
		(start 314.09894 -216.195148)
		(end 311.758584 -216.195148)
		(width 0.18288)
		(layer "In11.Cu")
		(net "M_D_CPU0_SB_DQS_DP<1>")
	)
	(segment
		(start 336.367882 -233.017822)
		(end 336.357468 -233.023918)
		(width 0.088646)
		(layer "In11.Cu")
		(net "M_D_CPU0_SB_DQS_DP<1>")
	)
	(segment
		(start 330.719176 -231.322372)
		(end 330.39685 -231.322372)
		(width 0.088646)
		(layer "In11.Cu")
		(net "M_D_CPU0_SB_DQS_DP<1>")
	)
	(segment
		(start 293.51605 -213.217252)
		(end 293.083742 -213.396322)
		(width 0.18288)
		(layer "In11.Cu")
		(net "M_D_CPU0_SB_DQS_DP<1>")
	)
	(segment
		(start 277.913846 -212.160612)
		(end 277.279862 -212.160612)
		(width 0.18288)
		(layer "In11.Cu")
		(net "M_D_CPU0_SB_DQS_DP<1>")
	)
	(segment
		(start 314.611004 -216.408508)
		(end 314.09894 -216.195148)
		(width 0.18288)
		(layer "In11.Cu")
		(net "M_D_CPU0_SB_DQS_DP<1>")
	)
	(segment
		(start 299.518324 -211.901024)
		(end 299.22851 -212.190838)
		(width 0.18288)
		(layer "In11.Cu")
		(net "M_D_CPU0_SB_DQS_DP<1>")
	)
	(segment
		(start 283.673804 -212.192108)
		(end 283.452824 -211.971128)
		(width 0.18288)
		(layer "In11.Cu")
		(net "M_D_CPU0_SB_DQS_DP<1>")
	)
	(segment
		(start 336.751168 -233.022902)
		(end 336.742278 -233.017822)
		(width 0.088646)
		(layer "In11.Cu")
		(net "M_D_CPU0_SB_DQS_DP<1>")
	)
	(segment
		(start 336.92973 -233.356404)
		(end 336.92973 -233.34218)
		(width 0.088646)
		(layer "In11.Cu")
		(net "M_D_CPU0_SB_DQS_DP<1>")
	)
	(segment
		(start 302.076612 -211.901024)
		(end 299.518324 -211.901024)
		(width 0.18288)
		(layer "In11.Cu")
		(net "M_D_CPU0_SB_DQS_DP<1>")
	)
	(segment
		(start 267.082778 -219.102178)
		(end 266.660122 -218.927172)
		(width 0.18288)
		(layer "In11.Cu")
		(net "M_D_CPU0_SB_DQS_DP<1>")
	)
	(segment
		(start 299.22851 -212.190838)
		(end 298.739814 -212.190838)
		(width 0.18288)
		(layer "In11.Cu")
		(net "M_D_CPU0_SB_DQS_DP<1>")
	)
	(segment
		(start 278.539194 -212.78596)
		(end 277.913846 -212.160612)
		(width 0.18288)
		(layer "In11.Cu")
		(net "M_D_CPU0_SB_DQS_DP<1>")
	)
	(segment
		(start 297.965114 -211.981288)
		(end 297.59148 -212.354922)
		(width 0.18288)
		(layer "In11.Cu")
		(net "M_D_CPU0_SB_DQS_DP<1>")
	)
	(segment
		(start 340.510368 -234.650788)
		(end 340.501478 -234.645708)
		(width 0.088646)
		(layer "In11.Cu")
		(net "M_D_CPU0_SB_DQS_DP<1>")
	)
	(segment
		(start 332.998064 -233.026458)
		(end 332.983332 -233.017822)
		(width 0.088646)
		(layer "In11.Cu")
		(net "M_D_CPU0_SB_DQS_DP<1>")
	)
	(segment
		(start 328.088498 -231.382316)
		(end 316.258194 -219.552266)
		(width 0.18288)
		(layer "In11.Cu")
		(net "M_D_CPU0_SB_DQS_DP<1>")
	)
	(segment
		(start 279.541986 -213.040722)
		(end 279.287224 -212.78596)
		(width 0.18288)
		(layer "In11.Cu")
		(net "M_D_CPU0_SB_DQS_DP<1>")
	)
	(segment
		(start 290.831016 -212.735922)
		(end 289.358324 -212.735922)
		(width 0.18288)
		(layer "In11.Cu")
		(net "M_D_CPU0_SB_DQS_DP<1>")
	)
	(segment
		(start 275.086064 -213.752684)
		(end 275.086064 -216.734898)
		(width 0.18288)
		(layer "In11.Cu")
		(net "M_D_CPU0_SB_DQS_DP<1>")
	)
	(segment
		(start 344.730578 -235.459524)
		(end 344.730832 -235.459524)
		(width 0.088646)
		(layer "In11.Cu")
		(net "M_D_CPU0_SB_DQS_DP<1>")
	)
	(segment
		(start 341.926164 -235.46816)
		(end 341.911432 -235.459524)
		(width 0.088646)
		(layer "In11.Cu")
		(net "M_D_CPU0_SB_DQS_DP<1>")
	)
	(segment
		(start 332.00975 -233.093768)
		(end 330.885546 -231.969564)
		(width 0.088646)
		(layer "In11.Cu")
		(net "M_D_CPU0_SB_DQS_DP<1>")
	)
	(segment
		(start 340.040722 -233.836972)
		(end 340.031832 -233.831892)
		(width 0.088646)
		(layer "In11.Cu")
		(net "M_D_CPU0_SB_DQS_DP<1>")
	)
	(segment
		(start 271.270984 -219.196158)
		(end 270.897858 -219.569284)
		(width 0.18288)
		(layer "In11.Cu")
		(net "M_D_CPU0_SB_DQS_DP<1>")
	)
	(arc
		(start 335.802732 -233.017822)
		(mid 335.615534 -232.967679)
		(end 335.428336 -233.017822)
		(width 0.088646)
		(layer "In11.Cu")
		(net "M_D_CPU0_SB_DQS_DP<1>")
	)
	(arc
		(start 336.357468 -233.023918)
		(mid 336.07929 -233.093641)
		(end 335.802732 -233.017822)
		(width 0.088646)
		(layer "In11.Cu")
		(net "M_D_CPU0_SB_DQS_DP<1>")
	)
	(arc
		(start 336.92973 -233.34218)
		(mid 336.882051 -233.15928)
		(end 336.751168 -233.022902)
		(width 0.088646)
		(layer "In11.Cu")
		(net "M_D_CPU0_SB_DQS_DP<1>")
	)
	(arc
		(start 346.127324 -235.30179)
		(mid 346.028482 -235.3393)
		(end 345.922854 -235.343446)
		(width 0.088646)
		(layer "In11.Cu")
		(net "M_D_CPU0_SB_DQS_DP<1>")
	)
	(arc
		(start 333.548736 -233.017822)
		(mid 333.274537 -233.093657)
		(end 332.998064 -233.026458)
		(width 0.088646)
		(layer "In11.Cu")
		(net "M_D_CPU0_SB_DQS_DP<1>")
	)
	(arc
		(start 346.89288 -234.970066)
		(mid 346.716859 -234.992903)
		(end 346.55252 -235.059982)
		(width 0.088646)
		(layer "In11.Cu")
		(net "M_D_CPU0_SB_DQS_DP<1>")
	)
	(arc
		(start 336.742278 -233.017822)
		(mid 336.55508 -232.967679)
		(end 336.367882 -233.017822)
		(width 0.088646)
		(layer "In11.Cu")
		(net "M_D_CPU0_SB_DQS_DP<1>")
	)
	(arc
		(start 342.476836 -235.459524)
		(mid 342.202637 -235.535359)
		(end 341.926164 -235.46816)
		(width 0.088646)
		(layer "In11.Cu")
		(net "M_D_CPU0_SB_DQS_DP<1>")
	)
	(arc
		(start 339.092032 -233.831892)
		(mid 338.904834 -233.781749)
		(end 338.717636 -233.831892)
		(width 0.088646)
		(layer "In11.Cu")
		(net "M_D_CPU0_SB_DQS_DP<1>")
	)
	(arc
		(start 340.68893 -234.970066)
		(mid 340.641251 -234.787166)
		(end 340.510368 -234.650788)
		(width 0.088646)
		(layer "In11.Cu")
		(net "M_D_CPU0_SB_DQS_DP<1>")
	)
	(arc
		(start 339.657436 -233.831892)
		(mid 339.374734 -233.907634)
		(end 339.092032 -233.831892)
		(width 0.088646)
		(layer "In11.Cu")
		(net "M_D_CPU0_SB_DQS_DP<1>")
	)
	(arc
		(start 334.862932 -233.017822)
		(mid 334.675734 -232.967679)
		(end 334.488536 -233.017822)
		(width 0.088646)
		(layer "In11.Cu")
		(net "M_D_CPU0_SB_DQS_DP<1>")
	)
	(arc
		(start 338.152232 -233.831892)
		(mid 337.965034 -233.781749)
		(end 337.777836 -233.831892)
		(width 0.088646)
		(layer "In11.Cu")
		(net "M_D_CPU0_SB_DQS_DP<1>")
	)
	(arc
		(start 340.501478 -234.645708)
		(mid 340.298655 -234.445477)
		(end 340.219284 -234.171744)
		(width 0.088646)
		(layer "In11.Cu")
		(net "M_D_CPU0_SB_DQS_DP<1>")
	)
	(arc
		(start 340.219284 -234.15625)
		(mid 340.171605 -233.97335)
		(end 340.040722 -233.836972)
		(width 0.088646)
		(layer "In11.Cu")
		(net "M_D_CPU0_SB_DQS_DP<1>")
	)
	(arc
		(start 340.031832 -233.831892)
		(mid 339.844634 -233.781749)
		(end 339.657436 -233.831892)
		(width 0.088646)
		(layer "In11.Cu")
		(net "M_D_CPU0_SB_DQS_DP<1>")
	)
	(arc
		(start 341.911432 -235.459524)
		(mid 341.724234 -235.409381)
		(end 341.537036 -235.459524)
		(width 0.088646)
		(layer "In11.Cu")
		(net "M_D_CPU0_SB_DQS_DP<1>")
	)
	(arc
		(start 343.791032 -235.459524)
		(mid 343.603834 -235.409381)
		(end 343.416636 -235.459524)
		(width 0.088646)
		(layer "In11.Cu")
		(net "M_D_CPU0_SB_DQS_DP<1>")
	)
	(arc
		(start 332.608936 -233.017822)
		(mid 332.47271 -233.074379)
		(end 332.326488 -233.093768)
		(width 0.088646)
		(layer "In11.Cu")
		(net "M_D_CPU0_SB_DQS_DP<1>")
	)
	(arc
		(start 342.851232 -235.459524)
		(mid 342.664034 -235.409381)
		(end 342.476836 -235.459524)
		(width 0.088646)
		(layer "In11.Cu")
		(net "M_D_CPU0_SB_DQS_DP<1>")
	)
	(arc
		(start 345.281758 -235.467906)
		(mid 345.005093 -235.535377)
		(end 344.730578 -235.459524)
		(width 0.088646)
		(layer "In11.Cu")
		(net "M_D_CPU0_SB_DQS_DP<1>")
	)
	(arc
		(start 333.923132 -233.017822)
		(mid 333.735934 -232.967679)
		(end 333.548736 -233.017822)
		(width 0.088646)
		(layer "In11.Cu")
		(net "M_D_CPU0_SB_DQS_DP<1>")
	)
	(arc
		(start 341.537036 -235.459524)
		(mid 341.262837 -235.535359)
		(end 340.986364 -235.46816)
		(width 0.088646)
		(layer "In11.Cu")
		(net "M_D_CPU0_SB_DQS_DP<1>")
	)
	(arc
		(start 340.965536 -235.455968)
		(mid 340.762949 -235.249617)
		(end 340.68893 -234.970066)
		(width 0.088646)
		(layer "In11.Cu")
		(net "M_D_CPU0_SB_DQS_DP<1>")
	)
	(arc
		(start 343.416636 -235.459524)
		(mid 343.142437 -235.535359)
		(end 342.865964 -235.46816)
		(width 0.088646)
		(layer "In11.Cu")
		(net "M_D_CPU0_SB_DQS_DP<1>")
	)
	(arc
		(start 334.488536 -233.017822)
		(mid 334.205834 -233.093598)
		(end 333.923132 -233.017822)
		(width 0.088646)
		(layer "In11.Cu")
		(net "M_D_CPU0_SB_DQS_DP<1>")
	)
	(arc
		(start 337.777836 -233.831892)
		(mid 337.503607 -233.907817)
		(end 337.227164 -233.840528)
		(width 0.088646)
		(layer "In11.Cu")
		(net "M_D_CPU0_SB_DQS_DP<1>")
	)
	(arc
		(start 335.428336 -233.017822)
		(mid 335.145634 -233.093598)
		(end 334.862932 -233.017822)
		(width 0.088646)
		(layer "In11.Cu")
		(net "M_D_CPU0_SB_DQS_DP<1>")
	)
	(arc
		(start 344.730832 -235.459524)
		(mid 344.543634 -235.409381)
		(end 344.356436 -235.459524)
		(width 0.088646)
		(layer "In11.Cu")
		(net "M_D_CPU0_SB_DQS_DP<1>")
	)
	(arc
		(start 344.356436 -235.459524)
		(mid 344.082237 -235.535359)
		(end 343.805764 -235.46816)
		(width 0.088646)
		(layer "In11.Cu")
		(net "M_D_CPU0_SB_DQS_DP<1>")
	)
	(arc
		(start 338.717636 -233.831892)
		(mid 338.443407 -233.907817)
		(end 338.166964 -233.840528)
		(width 0.088646)
		(layer "In11.Cu")
		(net "M_D_CPU0_SB_DQS_DP<1>")
	)
	(arc
		(start 337.212432 -233.831892)
		(mid 337.008951 -233.631088)
		(end 336.92973 -233.356404)
		(width 0.088646)
		(layer "In11.Cu")
		(net "M_D_CPU0_SB_DQS_DP<1>")
	)
	(arc
		(start 332.983332 -233.017822)
		(mid 332.796134 -232.967679)
		(end 332.608936 -233.017822)
		(width 0.088646)
		(layer "In11.Cu")
		(net "M_D_CPU0_SB_DQS_DP<1>")
	)
	(segment
		(start 261.53364 -229.19182)
		(end 261.381494 -229.19182)
		(width 0.20066)
		(layer "F.Cu")
		(net "M_D_CPU0_SB_DQS_DP<0>")
	)
	(segment
		(start 346.89288 -240.388902)
		(end 346.89288 -239.853216)
		(width 0.20066)
		(layer "F.Cu")
		(net "M_D_CPU0_SB_DQS_DP<0>")
	)
	(segment
		(start 257.940556 -228.930708)
		(end 257.30454 -228.505512)
		(width 0.20066)
		(layer "F.Cu")
		(net "M_D_CPU0_SB_DQS_DP<0>")
	)
	(segment
		(start 346.893134 -240.389156)
		(end 346.89288 -240.388902)
		(width 0.20066)
		(layer "F.Cu")
		(net "M_D_CPU0_SB_DQS_DP<0>")
	)
	(segment
		(start 261.058152 -229.19182)
		(end 259.302758 -229.19182)
		(width 0.1016)
		(layer "F.Cu")
		(net "M_D_CPU0_SB_DQS_DP<0>")
	)
	(segment
		(start 262.54583 -228.505512)
		(end 262.120634 -228.930708)
		(width 0.20066)
		(layer "F.Cu")
		(net "M_D_CPU0_SB_DQS_DP<0>")
	)
	(segment
		(start 258.567682 -228.930708)
		(end 257.940556 -228.930708)
		(width 0.20066)
		(layer "F.Cu")
		(net "M_D_CPU0_SB_DQS_DP<0>")
	)
	(segment
		(start 259.065776 -229.19182)
		(end 259.056378 -229.201218)
		(width 0.101854)
		(layer "F.Cu")
		(net "M_D_CPU0_SB_DQS_DP<0>")
	)
	(segment
		(start 256.618486 -228.766624)
		(end 256.080514 -228.766624)
		(width 0.20066)
		(layer "F.Cu")
		(net "M_D_CPU0_SB_DQS_DP<0>")
	)
	(segment
		(start 259.302758 -229.19182)
		(end 259.065776 -229.19182)
		(width 0.101854)
		(layer "F.Cu")
		(net "M_D_CPU0_SB_DQS_DP<0>")
	)
	(segment
		(start 262.120634 -228.930708)
		(end 261.794752 -228.930708)
		(width 0.20066)
		(layer "F.Cu")
		(net "M_D_CPU0_SB_DQS_DP<0>")
	)
	(segment
		(start 262.814562 -228.505512)
		(end 262.54583 -228.505512)
		(width 0.20066)
		(layer "F.Cu")
		(net "M_D_CPU0_SB_DQS_DP<0>")
	)
	(segment
		(start 261.381494 -229.19182)
		(end 261.058152 -229.19182)
		(width 0.101854)
		(layer "F.Cu")
		(net "M_D_CPU0_SB_DQS_DP<0>")
	)
	(segment
		(start 263.075674 -228.766624)
		(end 262.814562 -228.505512)
		(width 0.20066)
		(layer "F.Cu")
		(net "M_D_CPU0_SB_DQS_DP<0>")
	)
	(segment
		(start 256.879598 -228.505512)
		(end 256.618486 -228.766624)
		(width 0.20066)
		(layer "F.Cu")
		(net "M_D_CPU0_SB_DQS_DP<0>")
	)
	(segment
		(start 259.056378 -229.201218)
		(end 258.838192 -229.201218)
		(width 0.20066)
		(layer "F.Cu")
		(net "M_D_CPU0_SB_DQS_DP<0>")
	)
	(segment
		(start 261.794752 -228.930708)
		(end 261.53364 -229.19182)
		(width 0.20066)
		(layer "F.Cu")
		(net "M_D_CPU0_SB_DQS_DP<0>")
	)
	(segment
		(start 257.30454 -228.505512)
		(end 256.879598 -228.505512)
		(width 0.20066)
		(layer "F.Cu")
		(net "M_D_CPU0_SB_DQS_DP<0>")
	)
	(segment
		(start 264.729214 -228.766624)
		(end 263.624314 -228.766624)
		(width 0.20066)
		(layer "F.Cu")
		(net "M_D_CPU0_SB_DQS_DP<0>")
	)
	(segment
		(start 263.624314 -228.766624)
		(end 263.075674 -228.766624)
		(width 0.20066)
		(layer "F.Cu")
		(net "M_D_CPU0_SB_DQS_DP<0>")
	)
	(segment
		(start 258.838192 -229.201218)
		(end 258.567682 -228.930708)
		(width 0.20066)
		(layer "F.Cu")
		(net "M_D_CPU0_SB_DQS_DP<0>")
	)
	(segment
		(start 340.046564 -240.351564)
		(end 340.031832 -240.342928)
		(width 0.088646)
		(layer "In11.Cu")
		(net "M_D_CPU0_SB_DQS_DP<0>")
	)
	(segment
		(start 345.922854 -240.226596)
		(end 345.865704 -240.219738)
		(width 0.088646)
		(layer "In11.Cu")
		(net "M_D_CPU0_SB_DQS_DP<0>")
	)
	(segment
		(start 332.513686 -238.715296)
		(end 332.51394 -238.714788)
		(width 0.088646)
		(layer "In11.Cu")
		(net "M_D_CPU0_SB_DQS_DP<0>")
	)
	(segment
		(start 334.401922 -238.720122)
		(end 334.393032 -238.715042)
		(width 0.088646)
		(layer "In11.Cu")
		(net "M_D_CPU0_SB_DQS_DP<0>")
	)
	(segment
		(start 310.247284 -227.491036)
		(end 309.772304 -227.491036)
		(width 0.18288)
		(layer "In11.Cu")
		(net "M_D_CPU0_SB_DQS_DP<0>")
	)
	(segment
		(start 281.922474 -225.500946)
		(end 280.36901 -225.500946)
		(width 0.18288)
		(layer "In11.Cu")
		(net "M_D_CPU0_SB_DQS_DP<0>")
	)
	(segment
		(start 337.227164 -240.351564)
		(end 337.212432 -240.342928)
		(width 0.088646)
		(layer "In11.Cu")
		(net "M_D_CPU0_SB_DQS_DP<0>")
	)
	(segment
		(start 299.504862 -224.656904)
		(end 299.221398 -224.940368)
		(width 0.18288)
		(layer "In11.Cu")
		(net "M_D_CPU0_SB_DQS_DP<0>")
	)
	(segment
		(start 308.20995 -226.515676)
		(end 307.53304 -226.23526)
		(width 0.18288)
		(layer "In11.Cu")
		(net "M_D_CPU0_SB_DQS_DP<0>")
	)
	(segment
		(start 313.532774 -228.929184)
		(end 312.965338 -228.929184)
		(width 0.18288)
		(layer "In11.Cu")
		(net "M_D_CPU0_SB_DQS_DP<0>")
	)
	(segment
		(start 272.41246 -228.886512)
		(end 269.377922 -228.886512)
		(width 0.18288)
		(layer "In11.Cu")
		(net "M_D_CPU0_SB_DQS_DP<0>")
	)
	(segment
		(start 330.636118 -237.363762)
		(end 330.39685 -237.363762)
		(width 0.088646)
		(layer "In11.Cu")
		(net "M_D_CPU0_SB_DQS_DP<0>")
	)
	(segment
		(start 304.632868 -225.56343)
		(end 302.44415 -224.656904)
		(width 0.18288)
		(layer "In11.Cu")
		(net "M_D_CPU0_SB_DQS_DP<0>")
	)
	(segment
		(start 330.39685 -237.363762)
		(end 330.336906 -237.423706)
		(width 0.088646)
		(layer "In11.Cu")
		(net "M_D_CPU0_SB_DQS_DP<0>")
	)
	(segment
		(start 341.926164 -240.351564)
		(end 341.911432 -240.342928)
		(width 0.088646)
		(layer "In11.Cu")
		(net "M_D_CPU0_SB_DQS_DP<0>")
	)
	(segment
		(start 310.876188 -227.202746)
		(end 310.535574 -227.202746)
		(width 0.18288)
		(layer "In11.Cu")
		(net "M_D_CPU0_SB_DQS_DP<0>")
	)
	(segment
		(start 346.55252 -239.943132)
		(end 346.127324 -240.18494)
		(width 0.088646)
		(layer "In11.Cu")
		(net "M_D_CPU0_SB_DQS_DP<0>")
	)
	(segment
		(start 266.703556 -228.256846)
		(end 265.970258 -228.256846)
		(width 0.18288)
		(layer "In11.Cu")
		(net "M_D_CPU0_SB_DQS_DP<0>")
	)
	(segment
		(start 343.805764 -240.351564)
		(end 343.791032 -240.342928)
		(width 0.088646)
		(layer "In11.Cu")
		(net "M_D_CPU0_SB_DQS_DP<0>")
	)
	(segment
		(start 330.336906 -237.423706)
		(end 323.748146 -237.423706)
		(width 0.18288)
		(layer "In11.Cu")
		(net "M_D_CPU0_SB_DQS_DP<0>")
	)
	(segment
		(start 267.72235 -228.67874)
		(end 266.703556 -228.256846)
		(width 0.18288)
		(layer "In11.Cu")
		(net "M_D_CPU0_SB_DQS_DP<0>")
	)
	(segment
		(start 295.451784 -225.505772)
		(end 295.166542 -225.791014)
		(width 0.18288)
		(layer "In11.Cu")
		(net "M_D_CPU0_SB_DQS_DP<0>")
	)
	(segment
		(start 344.730578 -240.342674)
		(end 344.730832 -240.342928)
		(width 0.088646)
		(layer "In11.Cu")
		(net "M_D_CPU0_SB_DQS_DP<0>")
	)
	(segment
		(start 284.439868 -224.641918)
		(end 284.14091 -224.940876)
		(width 0.18288)
		(layer "In11.Cu")
		(net "M_D_CPU0_SB_DQS_DP<0>")
	)
	(segment
		(start 323.748146 -237.423706)
		(end 315.272166 -228.947726)
		(width 0.18288)
		(layer "In11.Cu")
		(net "M_D_CPU0_SB_DQS_DP<0>")
	)
	(segment
		(start 298.50207 -224.690432)
		(end 298.055792 -224.690432)
		(width 0.18288)
		(layer "In11.Cu")
		(net "M_D_CPU0_SB_DQS_DP<0>")
	)
	(segment
		(start 335.98993 -239.86744)
		(end 335.98993 -239.853216)
		(width 0.088646)
		(layer "In11.Cu")
		(net "M_D_CPU0_SB_DQS_DP<0>")
	)
	(segment
		(start 289.144202 -225.528886)
		(end 287.00476 -224.641918)
		(width 0.18288)
		(layer "In11.Cu")
		(net "M_D_CPU0_SB_DQS_DP<0>")
	)
	(segment
		(start 342.865964 -240.351564)
		(end 342.851232 -240.342928)
		(width 0.088646)
		(layer "In11.Cu")
		(net "M_D_CPU0_SB_DQS_DP<0>")
	)
	(segment
		(start 332.326234 -238.664496)
		(end 331.936852 -238.664496)
		(width 0.088646)
		(layer "In11.Cu")
		(net "M_D_CPU0_SB_DQS_DP<0>")
	)
	(segment
		(start 283.41193 -224.700592)
		(end 283.112972 -224.700592)
		(width 0.18288)
		(layer "In11.Cu")
		(net "M_D_CPU0_SB_DQS_DP<0>")
	)
	(segment
		(start 345.865704 -240.219738)
		(end 345.860878 -240.222278)
		(width 0.088646)
		(layer "In11.Cu")
		(net "M_D_CPU0_SB_DQS_DP<0>")
	)
	(segment
		(start 268.609826 -229.192328)
		(end 268.327632 -228.910134)
		(width 0.18288)
		(layer "In11.Cu")
		(net "M_D_CPU0_SB_DQS_DP<0>")
	)
	(segment
		(start 306.377848 -225.56343)
		(end 304.632868 -225.56343)
		(width 0.18288)
		(layer "In11.Cu")
		(net "M_D_CPU0_SB_DQS_DP<0>")
	)
	(segment
		(start 315.272166 -228.947726)
		(end 314.627768 -228.947726)
		(width 0.18288)
		(layer "In11.Cu")
		(net "M_D_CPU0_SB_DQS_DP<0>")
	)
	(segment
		(start 314.385198 -229.190296)
		(end 313.793886 -229.190296)
		(width 0.18288)
		(layer "In11.Cu")
		(net "M_D_CPU0_SB_DQS_DP<0>")
	)
	(segment
		(start 269.377922 -228.886512)
		(end 269.072106 -229.192328)
		(width 0.18288)
		(layer "In11.Cu")
		(net "M_D_CPU0_SB_DQS_DP<0>")
	)
	(segment
		(start 265.970258 -228.256846)
		(end 265.43127 -228.480112)
		(width 0.18288)
		(layer "In11.Cu")
		(net "M_D_CPU0_SB_DQS_DP<0>")
	)
	(segment
		(start 334.580484 -239.054894)
		(end 334.580484 -239.0394)
		(width 0.088646)
		(layer "In11.Cu")
		(net "M_D_CPU0_SB_DQS_DP<0>")
	)
	(segment
		(start 294.677846 -225.791014)
		(end 294.425624 -225.538792)
		(width 0.18288)
		(layer "In11.Cu")
		(net "M_D_CPU0_SB_DQS_DP<0>")
	)
	(segment
		(start 309.475378 -227.19411)
		(end 308.888384 -227.19411)
		(width 0.18288)
		(layer "In11.Cu")
		(net "M_D_CPU0_SB_DQS_DP<0>")
	)
	(segment
		(start 298.055792 -224.690432)
		(end 297.712638 -225.033586)
		(width 0.18288)
		(layer "In11.Cu")
		(net "M_D_CPU0_SB_DQS_DP<0>")
	)
	(segment
		(start 307.203602 -225.905822)
		(end 306.377848 -225.56343)
		(width 0.18288)
		(layer "In11.Cu")
		(net "M_D_CPU0_SB_DQS_DP<0>")
	)
	(segment
		(start 278.265636 -225.765614)
		(end 277.076408 -226.954842)
		(width 0.18288)
		(layer "In11.Cu")
		(net "M_D_CPU0_SB_DQS_DP<0>")
	)
	(segment
		(start 307.53304 -226.23526)
		(end 307.203602 -225.905822)
		(width 0.18288)
		(layer "In11.Cu")
		(net "M_D_CPU0_SB_DQS_DP<0>")
	)
	(segment
		(start 336.287364 -240.351564)
		(end 336.272632 -240.342928)
		(width 0.088646)
		(layer "In11.Cu")
		(net "M_D_CPU0_SB_DQS_DP<0>")
	)
	(segment
		(start 309.772304 -227.491036)
		(end 309.475378 -227.19411)
		(width 0.18288)
		(layer "In11.Cu")
		(net "M_D_CPU0_SB_DQS_DP<0>")
	)
	(segment
		(start 277.076408 -226.954842)
		(end 272.41246 -228.886512)
		(width 0.18288)
		(layer "In11.Cu")
		(net "M_D_CPU0_SB_DQS_DP<0>")
	)
	(segment
		(start 310.535574 -227.202746)
		(end 310.247284 -227.491036)
		(width 0.18288)
		(layer "In11.Cu")
		(net "M_D_CPU0_SB_DQS_DP<0>")
	)
	(segment
		(start 331.936852 -238.664496)
		(end 330.636118 -237.363762)
		(width 0.088646)
		(layer "In11.Cu")
		(net "M_D_CPU0_SB_DQS_DP<0>")
	)
	(segment
		(start 299.221398 -224.940368)
		(end 298.752006 -224.940368)
		(width 0.18288)
		(layer "In11.Cu")
		(net "M_D_CPU0_SB_DQS_DP<0>")
	)
	(segment
		(start 284.14091 -224.940876)
		(end 283.652214 -224.940876)
		(width 0.18288)
		(layer "In11.Cu")
		(net "M_D_CPU0_SB_DQS_DP<0>")
	)
	(segment
		(start 295.166542 -225.791014)
		(end 294.677846 -225.791014)
		(width 0.18288)
		(layer "In11.Cu")
		(net "M_D_CPU0_SB_DQS_DP<0>")
	)
	(segment
		(start 280.36901 -225.500946)
		(end 280.078942 -225.791014)
		(width 0.18288)
		(layer "In11.Cu")
		(net "M_D_CPU0_SB_DQS_DP<0>")
	)
	(segment
		(start 314.627768 -228.947726)
		(end 314.385198 -229.190296)
		(width 0.18288)
		(layer "In11.Cu")
		(net "M_D_CPU0_SB_DQS_DP<0>")
	)
	(segment
		(start 268.327632 -228.910134)
		(end 267.953998 -228.910134)
		(width 0.18288)
		(layer "In11.Cu")
		(net "M_D_CPU0_SB_DQS_DP<0>")
	)
	(segment
		(start 280.078942 -225.791014)
		(end 279.590246 -225.791014)
		(width 0.18288)
		(layer "In11.Cu")
		(net "M_D_CPU0_SB_DQS_DP<0>")
	)
	(segment
		(start 265.015726 -228.480112)
		(end 264.729214 -228.766624)
		(width 0.18288)
		(layer "In11.Cu")
		(net "M_D_CPU0_SB_DQS_DP<0>")
	)
	(segment
		(start 293.28745 -226.1108)
		(end 292.41115 -226.1108)
		(width 0.18288)
		(layer "In11.Cu")
		(net "M_D_CPU0_SB_DQS_DP<0>")
	)
	(segment
		(start 283.652214 -224.940876)
		(end 283.41193 -224.700592)
		(width 0.18288)
		(layer "In11.Cu")
		(net "M_D_CPU0_SB_DQS_DP<0>")
	)
	(segment
		(start 335.428082 -239.528858)
		(end 335.41335 -239.537494)
		(width 0.088646)
		(layer "In11.Cu")
		(net "M_D_CPU0_SB_DQS_DP<0>")
	)
	(segment
		(start 311.49544 -227.459286)
		(end 310.876188 -227.202746)
		(width 0.18288)
		(layer "In11.Cu")
		(net "M_D_CPU0_SB_DQS_DP<0>")
	)
	(segment
		(start 339.102192 -240.349024)
		(end 339.091778 -240.342928)
		(width 0.088646)
		(layer "In11.Cu")
		(net "M_D_CPU0_SB_DQS_DP<0>")
	)
	(segment
		(start 345.860878 -240.222278)
		(end 345.505278 -240.222278)
		(width 0.088646)
		(layer "In11.Cu")
		(net "M_D_CPU0_SB_DQS_DP<0>")
	)
	(segment
		(start 298.752006 -224.940368)
		(end 298.50207 -224.690432)
		(width 0.18288)
		(layer "In11.Cu")
		(net "M_D_CPU0_SB_DQS_DP<0>")
	)
	(segment
		(start 312.965338 -228.929184)
		(end 311.49544 -227.459286)
		(width 0.18288)
		(layer "In11.Cu")
		(net "M_D_CPU0_SB_DQS_DP<0>")
	)
	(segment
		(start 282.446222 -224.977198)
		(end 281.922474 -225.500946)
		(width 0.18288)
		(layer "In11.Cu")
		(net "M_D_CPU0_SB_DQS_DP<0>")
	)
	(segment
		(start 291.007546 -225.528886)
		(end 289.144202 -225.528886)
		(width 0.18288)
		(layer "In11.Cu")
		(net "M_D_CPU0_SB_DQS_DP<0>")
	)
	(segment
		(start 279.590246 -225.791014)
		(end 279.322784 -225.523552)
		(width 0.18288)
		(layer "In11.Cu")
		(net "M_D_CPU0_SB_DQS_DP<0>")
	)
	(segment
		(start 293.859458 -225.538792)
		(end 293.28745 -226.1108)
		(width 0.18288)
		(layer "In11.Cu")
		(net "M_D_CPU0_SB_DQS_DP<0>")
	)
	(segment
		(start 265.43127 -228.480112)
		(end 265.015726 -228.480112)
		(width 0.18288)
		(layer "In11.Cu")
		(net "M_D_CPU0_SB_DQS_DP<0>")
	)
	(segment
		(start 269.072106 -229.192328)
		(end 268.609826 -229.192328)
		(width 0.18288)
		(layer "In11.Cu")
		(net "M_D_CPU0_SB_DQS_DP<0>")
	)
	(segment
		(start 302.44415 -224.656904)
		(end 299.504862 -224.656904)
		(width 0.18288)
		(layer "In11.Cu")
		(net "M_D_CPU0_SB_DQS_DP<0>")
	)
	(segment
		(start 287.00476 -224.641918)
		(end 284.439868 -224.641918)
		(width 0.18288)
		(layer "In11.Cu")
		(net "M_D_CPU0_SB_DQS_DP<0>")
	)
	(segment
		(start 340.986364 -240.351564)
		(end 340.971632 -240.342928)
		(width 0.088646)
		(layer "In11.Cu")
		(net "M_D_CPU0_SB_DQS_DP<0>")
	)
	(segment
		(start 338.717382 -240.342928)
		(end 338.706968 -240.349024)
		(width 0.088646)
		(layer "In11.Cu")
		(net "M_D_CPU0_SB_DQS_DP<0>")
	)
	(segment
		(start 297.712638 -225.033586)
		(end 296.57294 -225.505772)
		(width 0.18288)
		(layer "In11.Cu")
		(net "M_D_CPU0_SB_DQS_DP<0>")
	)
	(segment
		(start 267.953998 -228.910134)
		(end 267.72235 -228.67874)
		(width 0.18288)
		(layer "In11.Cu")
		(net "M_D_CPU0_SB_DQS_DP<0>")
	)
	(segment
		(start 308.888384 -227.19411)
		(end 308.20995 -226.515676)
		(width 0.18288)
		(layer "In11.Cu")
		(net "M_D_CPU0_SB_DQS_DP<0>")
	)
	(segment
		(start 313.793886 -229.190296)
		(end 313.532774 -228.929184)
		(width 0.18288)
		(layer "In11.Cu")
		(net "M_D_CPU0_SB_DQS_DP<0>")
	)
	(segment
		(start 283.112972 -224.700592)
		(end 282.446222 -224.977198)
		(width 0.18288)
		(layer "In11.Cu")
		(net "M_D_CPU0_SB_DQS_DP<0>")
	)
	(segment
		(start 335.811368 -239.533938)
		(end 335.802478 -239.528858)
		(width 0.088646)
		(layer "In11.Cu")
		(net "M_D_CPU0_SB_DQS_DP<0>")
	)
	(segment
		(start 278.850598 -225.523552)
		(end 278.265636 -225.765614)
		(width 0.18288)
		(layer "In11.Cu")
		(net "M_D_CPU0_SB_DQS_DP<0>")
	)
	(segment
		(start 296.57294 -225.505772)
		(end 295.451784 -225.505772)
		(width 0.18288)
		(layer "In11.Cu")
		(net "M_D_CPU0_SB_DQS_DP<0>")
	)
	(segment
		(start 294.425624 -225.538792)
		(end 293.859458 -225.538792)
		(width 0.18288)
		(layer "In11.Cu")
		(net "M_D_CPU0_SB_DQS_DP<0>")
	)
	(segment
		(start 292.41115 -226.1108)
		(end 291.007546 -225.528886)
		(width 0.18288)
		(layer "In11.Cu")
		(net "M_D_CPU0_SB_DQS_DP<0>")
	)
	(segment
		(start 345.505278 -240.222278)
		(end 345.281758 -240.351056)
		(width 0.088646)
		(layer "In11.Cu")
		(net "M_D_CPU0_SB_DQS_DP<0>")
	)
	(segment
		(start 279.322784 -225.523552)
		(end 278.850598 -225.523552)
		(width 0.18288)
		(layer "In11.Cu")
		(net "M_D_CPU0_SB_DQS_DP<0>")
	)
	(arc
		(start 336.272632 -240.342928)
		(mid 336.069151 -240.142124)
		(end 335.98993 -239.86744)
		(width 0.088646)
		(layer "In11.Cu")
		(net "M_D_CPU0_SB_DQS_DP<0>")
	)
	(arc
		(start 346.127324 -240.18494)
		(mid 346.028482 -240.22245)
		(end 345.922854 -240.226596)
		(width 0.088646)
		(layer "In11.Cu")
		(net "M_D_CPU0_SB_DQS_DP<0>")
	)
	(arc
		(start 342.851232 -240.342928)
		(mid 342.664034 -240.292785)
		(end 342.476836 -240.342928)
		(width 0.088646)
		(layer "In11.Cu")
		(net "M_D_CPU0_SB_DQS_DP<0>")
	)
	(arc
		(start 337.212432 -240.342928)
		(mid 337.025234 -240.292785)
		(end 336.838036 -240.342928)
		(width 0.088646)
		(layer "In11.Cu")
		(net "M_D_CPU0_SB_DQS_DP<0>")
	)
	(arc
		(start 332.51394 -238.714788)
		(mid 332.423399 -238.677296)
		(end 332.326234 -238.664496)
		(width 0.088646)
		(layer "In11.Cu")
		(net "M_D_CPU0_SB_DQS_DP<0>")
	)
	(arc
		(start 336.838036 -240.342928)
		(mid 336.563807 -240.418853)
		(end 336.287364 -240.351564)
		(width 0.088646)
		(layer "In11.Cu")
		(net "M_D_CPU0_SB_DQS_DP<0>")
	)
	(arc
		(start 343.416636 -240.342928)
		(mid 343.142407 -240.418853)
		(end 342.865964 -240.351564)
		(width 0.088646)
		(layer "In11.Cu")
		(net "M_D_CPU0_SB_DQS_DP<0>")
	)
	(arc
		(start 335.802478 -239.528858)
		(mid 335.61528 -239.478715)
		(end 335.428082 -239.528858)
		(width 0.088646)
		(layer "In11.Cu")
		(net "M_D_CPU0_SB_DQS_DP<0>")
	)
	(arc
		(start 340.031832 -240.342928)
		(mid 339.844634 -240.292785)
		(end 339.657436 -240.342928)
		(width 0.088646)
		(layer "In11.Cu")
		(net "M_D_CPU0_SB_DQS_DP<0>")
	)
	(arc
		(start 337.777836 -240.342928)
		(mid 337.503607 -240.418853)
		(end 337.227164 -240.351564)
		(width 0.088646)
		(layer "In11.Cu")
		(net "M_D_CPU0_SB_DQS_DP<0>")
	)
	(arc
		(start 339.091778 -240.342928)
		(mid 338.90458 -240.292785)
		(end 338.717382 -240.342928)
		(width 0.088646)
		(layer "In11.Cu")
		(net "M_D_CPU0_SB_DQS_DP<0>")
	)
	(arc
		(start 335.41335 -239.537494)
		(mid 335.136875 -239.604814)
		(end 334.862678 -239.528858)
		(width 0.088646)
		(layer "In11.Cu")
		(net "M_D_CPU0_SB_DQS_DP<0>")
	)
	(arc
		(start 335.98993 -239.853216)
		(mid 335.942251 -239.670316)
		(end 335.811368 -239.533938)
		(width 0.088646)
		(layer "In11.Cu")
		(net "M_D_CPU0_SB_DQS_DP<0>")
	)
	(arc
		(start 341.537036 -240.342928)
		(mid 341.262807 -240.418853)
		(end 340.986364 -240.351564)
		(width 0.088646)
		(layer "In11.Cu")
		(net "M_D_CPU0_SB_DQS_DP<0>")
	)
	(arc
		(start 334.393032 -238.715042)
		(mid 334.205834 -238.664899)
		(end 334.018636 -238.715042)
		(width 0.088646)
		(layer "In11.Cu")
		(net "M_D_CPU0_SB_DQS_DP<0>")
	)
	(arc
		(start 333.078836 -238.715042)
		(mid 332.796307 -238.790818)
		(end 332.513686 -238.715296)
		(width 0.088646)
		(layer "In11.Cu")
		(net "M_D_CPU0_SB_DQS_DP<0>")
	)
	(arc
		(start 342.476836 -240.342928)
		(mid 342.202607 -240.418853)
		(end 341.926164 -240.351564)
		(width 0.088646)
		(layer "In11.Cu")
		(net "M_D_CPU0_SB_DQS_DP<0>")
	)
	(arc
		(start 334.018636 -238.715042)
		(mid 333.735934 -238.790818)
		(end 333.453232 -238.715042)
		(width 0.088646)
		(layer "In11.Cu")
		(net "M_D_CPU0_SB_DQS_DP<0>")
	)
	(arc
		(start 334.580484 -239.0394)
		(mid 334.532805 -238.8565)
		(end 334.401922 -238.720122)
		(width 0.088646)
		(layer "In11.Cu")
		(net "M_D_CPU0_SB_DQS_DP<0>")
	)
	(arc
		(start 339.657436 -240.342928)
		(mid 339.380623 -240.418764)
		(end 339.102192 -240.349024)
		(width 0.088646)
		(layer "In11.Cu")
		(net "M_D_CPU0_SB_DQS_DP<0>")
	)
	(arc
		(start 343.791032 -240.342928)
		(mid 343.603834 -240.292785)
		(end 343.416636 -240.342928)
		(width 0.088646)
		(layer "In11.Cu")
		(net "M_D_CPU0_SB_DQS_DP<0>")
	)
	(arc
		(start 340.597236 -240.342928)
		(mid 340.323007 -240.418853)
		(end 340.046564 -240.351564)
		(width 0.088646)
		(layer "In11.Cu")
		(net "M_D_CPU0_SB_DQS_DP<0>")
	)
	(arc
		(start 345.281758 -240.351056)
		(mid 345.005093 -240.418527)
		(end 344.730578 -240.342674)
		(width 0.088646)
		(layer "In11.Cu")
		(net "M_D_CPU0_SB_DQS_DP<0>")
	)
	(arc
		(start 344.730832 -240.342928)
		(mid 344.543634 -240.292785)
		(end 344.356436 -240.342928)
		(width 0.088646)
		(layer "In11.Cu")
		(net "M_D_CPU0_SB_DQS_DP<0>")
	)
	(arc
		(start 344.356436 -240.342928)
		(mid 344.082207 -240.418853)
		(end 343.805764 -240.351564)
		(width 0.088646)
		(layer "In11.Cu")
		(net "M_D_CPU0_SB_DQS_DP<0>")
	)
	(arc
		(start 338.152232 -240.342928)
		(mid 337.965034 -240.292785)
		(end 337.777836 -240.342928)
		(width 0.088646)
		(layer "In11.Cu")
		(net "M_D_CPU0_SB_DQS_DP<0>")
	)
	(arc
		(start 346.89288 -239.853216)
		(mid 346.716859 -239.876053)
		(end 346.55252 -239.943132)
		(width 0.088646)
		(layer "In11.Cu")
		(net "M_D_CPU0_SB_DQS_DP<0>")
	)
	(arc
		(start 340.971632 -240.342928)
		(mid 340.784434 -240.292785)
		(end 340.597236 -240.342928)
		(width 0.088646)
		(layer "In11.Cu")
		(net "M_D_CPU0_SB_DQS_DP<0>")
	)
	(arc
		(start 334.862678 -239.528858)
		(mid 334.659855 -239.328627)
		(end 334.580484 -239.054894)
		(width 0.088646)
		(layer "In11.Cu")
		(net "M_D_CPU0_SB_DQS_DP<0>")
	)
	(arc
		(start 333.453232 -238.715042)
		(mid 333.266034 -238.664899)
		(end 333.078836 -238.715042)
		(width 0.088646)
		(layer "In11.Cu")
		(net "M_D_CPU0_SB_DQS_DP<0>")
	)
	(arc
		(start 341.911432 -240.342928)
		(mid 341.724234 -240.292785)
		(end 341.537036 -240.342928)
		(width 0.088646)
		(layer "In11.Cu")
		(net "M_D_CPU0_SB_DQS_DP<0>")
	)
	(arc
		(start 338.706968 -240.349024)
		(mid 338.42879 -240.418716)
		(end 338.152232 -240.342928)
		(width 0.088646)
		(layer "In11.Cu")
		(net "M_D_CPU0_SB_DQS_DP<0>")
	)
	(segment
		(start 262.816594 -237.527846)
		(end 262.40994 -237.527846)
		(width 0.20066)
		(layer "F.Cu")
		(net "M_D_CPU0_SB_DQS_DN<9>")
	)
	(segment
		(start 259.067808 -237.691676)
		(end 259.05714 -237.681008)
		(width 0.101854)
		(layer "F.Cu")
		(net "M_D_CPU0_SB_DQS_DN<9>")
	)
	(segment
		(start 259.05714 -237.681008)
		(end 259.056378 -237.681008)
		(width 0.101854)
		(layer "F.Cu")
		(net "M_D_CPU0_SB_DQS_DN<9>")
	)
	(segment
		(start 256.629154 -237.266734)
		(end 256.080514 -237.266734)
		(width 0.20066)
		(layer "F.Cu")
		(net "M_D_CPU0_SB_DQS_DN<9>")
	)
	(segment
		(start 345.95308 -245.272306)
		(end 345.95308 -244.73662)
		(width 0.20066)
		(layer "F.Cu")
		(net "M_D_CPU0_SB_DQS_DN<9>")
	)
	(segment
		(start 263.077706 -237.266734)
		(end 262.816594 -237.527846)
		(width 0.20066)
		(layer "F.Cu")
		(net "M_D_CPU0_SB_DQS_DN<9>")
	)
	(segment
		(start 258.580128 -237.953042)
		(end 258.040124 -237.953042)
		(width 0.20066)
		(layer "F.Cu")
		(net "M_D_CPU0_SB_DQS_DN<9>")
	)
	(segment
		(start 261.984744 -237.953042)
		(end 261.798054 -237.953042)
		(width 0.20066)
		(layer "F.Cu")
		(net "M_D_CPU0_SB_DQS_DN<9>")
	)
	(segment
		(start 256.890266 -237.527846)
		(end 256.629154 -237.266734)
		(width 0.20066)
		(layer "F.Cu")
		(net "M_D_CPU0_SB_DQS_DN<9>")
	)
	(segment
		(start 261.381494 -237.691676)
		(end 259.067808 -237.691676)
		(width 0.1016)
		(layer "F.Cu")
		(net "M_D_CPU0_SB_DQS_DN<9>")
	)
	(segment
		(start 345.953334 -245.27256)
		(end 345.95308 -245.272306)
		(width 0.20066)
		(layer "F.Cu")
		(net "M_D_CPU0_SB_DQS_DN<9>")
	)
	(segment
		(start 258.852162 -237.681008)
		(end 258.580128 -237.953042)
		(width 0.20066)
		(layer "F.Cu")
		(net "M_D_CPU0_SB_DQS_DN<9>")
	)
	(segment
		(start 258.040124 -237.953042)
		(end 257.404108 -237.527846)
		(width 0.20066)
		(layer "F.Cu")
		(net "M_D_CPU0_SB_DQS_DN<9>")
	)
	(segment
		(start 263.624314 -237.266734)
		(end 263.077706 -237.266734)
		(width 0.20066)
		(layer "F.Cu")
		(net "M_D_CPU0_SB_DQS_DN<9>")
	)
	(segment
		(start 264.729214 -237.266734)
		(end 263.624314 -237.266734)
		(width 0.20066)
		(layer "F.Cu")
		(net "M_D_CPU0_SB_DQS_DN<9>")
	)
	(segment
		(start 262.40994 -237.527846)
		(end 261.984744 -237.953042)
		(width 0.20066)
		(layer "F.Cu")
		(net "M_D_CPU0_SB_DQS_DN<9>")
	)
	(segment
		(start 257.404108 -237.527846)
		(end 256.890266 -237.527846)
		(width 0.20066)
		(layer "F.Cu")
		(net "M_D_CPU0_SB_DQS_DN<9>")
	)
	(segment
		(start 261.798054 -237.953042)
		(end 261.536688 -237.691676)
		(width 0.20066)
		(layer "F.Cu")
		(net "M_D_CPU0_SB_DQS_DN<9>")
	)
	(segment
		(start 259.056378 -237.681008)
		(end 258.852162 -237.681008)
		(width 0.20066)
		(layer "F.Cu")
		(net "M_D_CPU0_SB_DQS_DN<9>")
	)
	(segment
		(start 261.536688 -237.691676)
		(end 261.381494 -237.691676)
		(width 0.20066)
		(layer "F.Cu")
		(net "M_D_CPU0_SB_DQS_DN<9>")
	)
	(segment
		(start 304.951892 -237.306866)
		(end 304.403252 -237.306866)
		(width 0.18288)
		(layer "In11.Cu")
		(net "M_D_CPU0_SB_DQS_DN<9>")
	)
	(segment
		(start 265.784076 -237.31982)
		(end 265.299444 -237.52048)
		(width 0.18288)
		(layer "In11.Cu")
		(net "M_D_CPU0_SB_DQS_DN<9>")
	)
	(segment
		(start 331.697076 -243.853208)
		(end 331.637132 -243.793264)
		(width 0.088646)
		(layer "In11.Cu")
		(net "M_D_CPU0_SB_DQS_DN<9>")
	)
	(segment
		(start 307.768752 -237.182406)
		(end 307.644292 -237.306866)
		(width 0.18288)
		(layer "In11.Cu")
		(net "M_D_CPU0_SB_DQS_DN<9>")
	)
	(segment
		(start 305.076352 -237.182406)
		(end 304.951892 -237.306866)
		(width 0.18288)
		(layer "In11.Cu")
		(net "M_D_CPU0_SB_DQS_DN<9>")
	)
	(segment
		(start 318.53124 -242.26393)
		(end 318.143382 -241.876072)
		(width 0.18288)
		(layer "In11.Cu")
		(net "M_D_CPU0_SB_DQS_DN<9>")
	)
	(segment
		(start 296.362628 -238.803942)
		(end 295.366186 -238.803942)
		(width 0.18288)
		(layer "In11.Cu")
		(net "M_D_CPU0_SB_DQS_DN<9>")
	)
	(segment
		(start 312.932826 -237.826042)
		(end 311.682892 -237.306866)
		(width 0.18288)
		(layer "In11.Cu")
		(net "M_D_CPU0_SB_DQS_DN<9>")
	)
	(segment
		(start 319.483232 -243.215922)
		(end 319.095374 -242.828064)
		(width 0.18288)
		(layer "In11.Cu")
		(net "M_D_CPU0_SB_DQS_DN<9>")
	)
	(segment
		(start 280.327608 -238.804196)
		(end 280.06294 -238.539528)
		(width 0.18288)
		(layer "In11.Cu")
		(net "M_D_CPU0_SB_DQS_DN<9>")
	)
	(segment
		(start 280.06294 -238.539528)
		(end 279.608534 -238.539528)
		(width 0.18288)
		(layer "In11.Cu")
		(net "M_D_CPU0_SB_DQS_DN<9>")
	)
	(segment
		(start 298.537884 -237.922308)
		(end 298.118022 -237.922308)
		(width 0.18288)
		(layer "In11.Cu")
		(net "M_D_CPU0_SB_DQS_DN<9>")
	)
	(segment
		(start 268.609318 -237.690914)
		(end 268.342364 -237.957868)
		(width 0.18288)
		(layer "In11.Cu")
		(net "M_D_CPU0_SB_DQS_DN<9>")
	)
	(segment
		(start 297.448732 -238.199676)
		(end 297.185588 -238.462312)
		(width 0.18288)
		(layer "In11.Cu")
		(net "M_D_CPU0_SB_DQS_DN<9>")
	)
	(segment
		(start 329.999848 -243.215922)
		(end 319.483232 -243.215922)
		(width 0.18288)
		(layer "In11.Cu")
		(net "M_D_CPU0_SB_DQS_DN<9>")
	)
	(segment
		(start 331.637132 -243.793264)
		(end 330.57719 -243.793264)
		(width 0.18288)
		(layer "In11.Cu")
		(net "M_D_CPU0_SB_DQS_DN<9>")
	)
	(segment
		(start 305.749452 -237.306866)
		(end 305.624992 -237.182406)
		(width 0.18288)
		(layer "In11.Cu")
		(net "M_D_CPU0_SB_DQS_DN<9>")
	)
	(segment
		(start 338.632546 -245.054882)
		(end 338.622132 -245.060978)
		(width 0.088646)
		(layer "In11.Cu")
		(net "M_D_CPU0_SB_DQS_DN<9>")
	)
	(segment
		(start 284.426152 -238.009176)
		(end 284.110684 -237.693708)
		(width 0.18288)
		(layer "In11.Cu")
		(net "M_D_CPU0_SB_DQS_DN<9>")
	)
	(segment
		(start 311.134252 -237.306866)
		(end 311.009792 -237.182406)
		(width 0.18288)
		(layer "In11.Cu")
		(net "M_D_CPU0_SB_DQS_DN<9>")
	)
	(segment
		(start 334.488282 -245.060978)
		(end 334.47355 -245.052342)
		(width 0.088646)
		(layer "In11.Cu")
		(net "M_D_CPU0_SB_DQS_DN<9>")
	)
	(segment
		(start 269.087092 -237.690914)
		(end 268.609318 -237.690914)
		(width 0.18288)
		(layer "In11.Cu")
		(net "M_D_CPU0_SB_DQS_DN<9>")
	)
	(segment
		(start 345.200986 -245.061232)
		(end 345.200732 -245.060978)
		(width 0.088646)
		(layer "In11.Cu")
		(net "M_D_CPU0_SB_DQS_DN<9>")
	)
	(segment
		(start 282.760674 -238.196374)
		(end 281.292554 -238.804196)
		(width 0.18288)
		(layer "In11.Cu")
		(net "M_D_CPU0_SB_DQS_DN<9>")
	)
	(segment
		(start 342.946482 -245.060978)
		(end 342.93175 -245.052342)
		(width 0.088646)
		(layer "In11.Cu")
		(net "M_D_CPU0_SB_DQS_DN<9>")
	)
	(segment
		(start 345.95308 -244.73662)
		(end 345.92133 -244.852444)
		(width 0.088646)
		(layer "In11.Cu")
		(net "M_D_CPU0_SB_DQS_DN<9>")
	)
	(segment
		(start 297.185588 -238.462312)
		(end 296.362628 -238.803942)
		(width 0.18288)
		(layer "In11.Cu")
		(net "M_D_CPU0_SB_DQS_DN<9>")
	)
	(segment
		(start 319.095374 -242.652042)
		(end 318.707262 -242.26393)
		(width 0.18288)
		(layer "In11.Cu")
		(net "M_D_CPU0_SB_DQS_DN<9>")
	)
	(segment
		(start 299.514006 -237.957868)
		(end 299.247306 -237.691168)
		(width 0.18288)
		(layer "In11.Cu")
		(net "M_D_CPU0_SB_DQS_DN<9>")
	)
	(segment
		(start 267.34516 -237.31982)
		(end 265.784076 -237.31982)
		(width 0.18288)
		(layer "In11.Cu")
		(net "M_D_CPU0_SB_DQS_DN<9>")
	)
	(segment
		(start 283.701744 -237.693708)
		(end 283.426154 -237.969298)
		(width 0.18288)
		(layer "In11.Cu")
		(net "M_D_CPU0_SB_DQS_DN<9>")
	)
	(segment
		(start 272.407126 -237.952788)
		(end 269.348966 -237.952788)
		(width 0.18288)
		(layer "In11.Cu")
		(net "M_D_CPU0_SB_DQS_DN<9>")
	)
	(segment
		(start 273.852386 -238.551466)
		(end 272.407126 -237.952788)
		(width 0.18288)
		(layer "In11.Cu")
		(net "M_D_CPU0_SB_DQS_DN<9>")
	)
	(segment
		(start 299.247306 -237.691168)
		(end 298.769024 -237.691168)
		(width 0.18288)
		(layer "In11.Cu")
		(net "M_D_CPU0_SB_DQS_DN<9>")
	)
	(segment
		(start 316.627256 -240.359946)
		(end 315.133228 -238.865918)
		(width 0.18288)
		(layer "In11.Cu")
		(net "M_D_CPU0_SB_DQS_DN<9>")
	)
	(segment
		(start 307.095652 -237.306866)
		(end 306.971192 -237.182406)
		(width 0.18288)
		(layer "In11.Cu")
		(net "M_D_CPU0_SB_DQS_DN<9>")
	)
	(segment
		(start 277.872444 -238.200184)
		(end 277.30958 -238.200184)
		(width 0.18288)
		(layer "In11.Cu")
		(net "M_D_CPU0_SB_DQS_DN<9>")
	)
	(segment
		(start 298.769024 -237.691168)
		(end 298.537884 -237.922308)
		(width 0.18288)
		(layer "In11.Cu")
		(net "M_D_CPU0_SB_DQS_DN<9>")
	)
	(segment
		(start 306.422552 -237.182406)
		(end 306.298092 -237.306866)
		(width 0.18288)
		(layer "In11.Cu")
		(net "M_D_CPU0_SB_DQS_DN<9>")
	)
	(segment
		(start 269.348966 -237.952788)
		(end 269.087092 -237.690914)
		(width 0.18288)
		(layer "In11.Cu")
		(net "M_D_CPU0_SB_DQS_DN<9>")
	)
	(segment
		(start 307.644292 -237.306866)
		(end 307.095652 -237.306866)
		(width 0.18288)
		(layer "In11.Cu")
		(net "M_D_CPU0_SB_DQS_DN<9>")
	)
	(segment
		(start 319.095374 -242.828064)
		(end 319.095374 -242.652042)
		(width 0.18288)
		(layer "In11.Cu")
		(net "M_D_CPU0_SB_DQS_DN<9>")
	)
	(segment
		(start 342.006682 -245.060978)
		(end 341.99195 -245.052342)
		(width 0.088646)
		(layer "In11.Cu")
		(net "M_D_CPU0_SB_DQS_DN<9>")
	)
	(segment
		(start 345.92133 -244.852444)
		(end 345.882468 -244.874542)
		(width 0.088646)
		(layer "In11.Cu")
		(net "M_D_CPU0_SB_DQS_DN<9>")
	)
	(segment
		(start 305.624992 -237.182406)
		(end 305.076352 -237.182406)
		(width 0.18288)
		(layer "In11.Cu")
		(net "M_D_CPU0_SB_DQS_DN<9>")
	)
	(segment
		(start 310.461152 -237.182406)
		(end 310.336692 -237.306866)
		(width 0.18288)
		(layer "In11.Cu")
		(net "M_D_CPU0_SB_DQS_DN<9>")
	)
	(segment
		(start 336.367882 -245.060978)
		(end 336.35315 -245.052342)
		(width 0.088646)
		(layer "In11.Cu")
		(net "M_D_CPU0_SB_DQS_DN<9>")
	)
	(segment
		(start 304.403252 -237.306866)
		(end 304.278792 -237.182406)
		(width 0.18288)
		(layer "In11.Cu")
		(net "M_D_CPU0_SB_DQS_DN<9>")
	)
	(segment
		(start 279.349962 -238.7981)
		(end 279.106884 -238.7981)
		(width 0.18288)
		(layer "In11.Cu")
		(net "M_D_CPU0_SB_DQS_DN<9>")
	)
	(segment
		(start 315.133736 -238.865664)
		(end 314.405518 -238.564674)
		(width 0.18288)
		(layer "In11.Cu")
		(net "M_D_CPU0_SB_DQS_DN<9>")
	)
	(segment
		(start 332.796134 -244.17147)
		(end 332.44917 -244.17147)
		(width 0.088646)
		(layer "In11.Cu")
		(net "M_D_CPU0_SB_DQS_DN<9>")
	)
	(segment
		(start 287.320736 -238.009176)
		(end 284.426152 -238.009176)
		(width 0.18288)
		(layer "In11.Cu")
		(net "M_D_CPU0_SB_DQS_DN<9>")
	)
	(segment
		(start 300.107604 -237.957868)
		(end 299.514006 -237.957868)
		(width 0.18288)
		(layer "In11.Cu")
		(net "M_D_CPU0_SB_DQS_DN<9>")
	)
	(segment
		(start 279.106884 -238.7981)
		(end 278.959818 -238.651034)
		(width 0.18288)
		(layer "In11.Cu")
		(net "M_D_CPU0_SB_DQS_DN<9>")
	)
	(segment
		(start 340.512146 -245.054882)
		(end 340.501732 -245.060978)
		(width 0.088646)
		(layer "In11.Cu")
		(net "M_D_CPU0_SB_DQS_DN<9>")
	)
	(segment
		(start 308.317392 -237.182406)
		(end 307.768752 -237.182406)
		(width 0.18288)
		(layer "In11.Cu")
		(net "M_D_CPU0_SB_DQS_DN<9>")
	)
	(segment
		(start 279.608534 -238.539528)
		(end 279.349962 -238.7981)
		(width 0.18288)
		(layer "In11.Cu")
		(net "M_D_CPU0_SB_DQS_DN<9>")
	)
	(segment
		(start 293.999666 -238.796322)
		(end 293.039038 -237.835694)
		(width 0.18288)
		(layer "In11.Cu")
		(net "M_D_CPU0_SB_DQS_DN<9>")
	)
	(segment
		(start 291.878004 -237.354364)
		(end 288.901632 -237.354364)
		(width 0.18288)
		(layer "In11.Cu")
		(net "M_D_CPU0_SB_DQS_DN<9>")
	)
	(segment
		(start 333.36103 -244.73662)
		(end 333.36103 -244.726714)
		(width 0.088646)
		(layer "In11.Cu")
		(net "M_D_CPU0_SB_DQS_DN<9>")
	)
	(segment
		(start 316.803278 -240.359946)
		(end 316.627256 -240.359946)
		(width 0.18288)
		(layer "In11.Cu")
		(net "M_D_CPU0_SB_DQS_DN<9>")
	)
	(segment
		(start 313.671458 -238.564674)
		(end 312.932826 -237.826042)
		(width 0.18288)
		(layer "In11.Cu")
		(net "M_D_CPU0_SB_DQS_DN<9>")
	)
	(segment
		(start 340.127336 -245.060978)
		(end 340.116922 -245.054882)
		(width 0.088646)
		(layer "In11.Cu")
		(net "M_D_CPU0_SB_DQS_DN<9>")
	)
	(segment
		(start 281.292554 -238.804196)
		(end 280.327608 -238.804196)
		(width 0.18288)
		(layer "In11.Cu")
		(net "M_D_CPU0_SB_DQS_DN<9>")
	)
	(segment
		(start 308.990492 -237.306866)
		(end 308.441852 -237.306866)
		(width 0.18288)
		(layer "In11.Cu")
		(net "M_D_CPU0_SB_DQS_DN<9>")
	)
	(segment
		(start 308.441852 -237.306866)
		(end 308.317392 -237.182406)
		(width 0.18288)
		(layer "In11.Cu")
		(net "M_D_CPU0_SB_DQS_DN<9>")
	)
	(segment
		(start 309.114952 -237.182406)
		(end 308.990492 -237.306866)
		(width 0.18288)
		(layer "In11.Cu")
		(net "M_D_CPU0_SB_DQS_DN<9>")
	)
	(segment
		(start 310.336692 -237.306866)
		(end 309.788052 -237.306866)
		(width 0.18288)
		(layer "In11.Cu")
		(net "M_D_CPU0_SB_DQS_DN<9>")
	)
	(segment
		(start 311.009792 -237.182406)
		(end 310.461152 -237.182406)
		(width 0.18288)
		(layer "In11.Cu")
		(net "M_D_CPU0_SB_DQS_DN<9>")
	)
	(segment
		(start 265.299444 -237.52048)
		(end 264.98296 -237.52048)
		(width 0.18288)
		(layer "In11.Cu")
		(net "M_D_CPU0_SB_DQS_DN<9>")
	)
	(segment
		(start 330.57719 -243.793264)
		(end 329.999848 -243.215922)
		(width 0.18288)
		(layer "In11.Cu")
		(net "M_D_CPU0_SB_DQS_DN<9>")
	)
	(segment
		(start 315.133228 -238.865918)
		(end 315.133736 -238.865664)
		(width 0.18288)
		(layer "In11.Cu")
		(net "M_D_CPU0_SB_DQS_DN<9>")
	)
	(segment
		(start 335.428082 -245.060978)
		(end 335.41335 -245.052342)
		(width 0.088646)
		(layer "In11.Cu")
		(net "M_D_CPU0_SB_DQS_DN<9>")
	)
	(segment
		(start 332.130908 -243.853208)
		(end 331.697076 -243.853208)
		(width 0.088646)
		(layer "In11.Cu")
		(net "M_D_CPU0_SB_DQS_DN<9>")
	)
	(segment
		(start 318.143382 -241.70005)
		(end 317.75527 -241.311938)
		(width 0.18288)
		(layer "In11.Cu")
		(net "M_D_CPU0_SB_DQS_DN<9>")
	)
	(segment
		(start 267.983208 -237.957868)
		(end 267.34516 -237.31982)
		(width 0.18288)
		(layer "In11.Cu")
		(net "M_D_CPU0_SB_DQS_DN<9>")
	)
	(segment
		(start 294.458644 -238.796322)
		(end 293.999666 -238.796322)
		(width 0.18288)
		(layer "In11.Cu")
		(net "M_D_CPU0_SB_DQS_DN<9>")
	)
	(segment
		(start 264.98296 -237.52048)
		(end 264.729214 -237.266734)
		(width 0.18288)
		(layer "In11.Cu")
		(net "M_D_CPU0_SB_DQS_DN<9>")
	)
	(segment
		(start 277.30958 -238.200184)
		(end 276.460966 -238.551466)
		(width 0.18288)
		(layer "In11.Cu")
		(net "M_D_CPU0_SB_DQS_DN<9>")
	)
	(segment
		(start 301.679356 -237.306866)
		(end 300.107604 -237.957868)
		(width 0.18288)
		(layer "In11.Cu")
		(net "M_D_CPU0_SB_DQS_DN<9>")
	)
	(segment
		(start 288.901632 -237.354364)
		(end 287.320736 -238.009176)
		(width 0.18288)
		(layer "In11.Cu")
		(net "M_D_CPU0_SB_DQS_DN<9>")
	)
	(segment
		(start 306.971192 -237.182406)
		(end 306.422552 -237.182406)
		(width 0.18288)
		(layer "In11.Cu")
		(net "M_D_CPU0_SB_DQS_DN<9>")
	)
	(segment
		(start 298.118022 -237.922308)
		(end 297.448732 -238.199676)
		(width 0.18288)
		(layer "In11.Cu")
		(net "M_D_CPU0_SB_DQS_DN<9>")
	)
	(segment
		(start 295.106852 -238.544608)
		(end 294.710358 -238.544608)
		(width 0.18288)
		(layer "In11.Cu")
		(net "M_D_CPU0_SB_DQS_DN<9>")
	)
	(segment
		(start 309.788052 -237.306866)
		(end 309.663592 -237.182406)
		(width 0.18288)
		(layer "In11.Cu")
		(net "M_D_CPU0_SB_DQS_DN<9>")
	)
	(segment
		(start 317.75527 -241.311938)
		(end 317.579248 -241.311938)
		(width 0.18288)
		(layer "In11.Cu")
		(net "M_D_CPU0_SB_DQS_DN<9>")
	)
	(segment
		(start 333.548482 -245.060978)
		(end 333.539592 -245.055898)
		(width 0.088646)
		(layer "In11.Cu")
		(net "M_D_CPU0_SB_DQS_DN<9>")
	)
	(segment
		(start 317.19139 -240.92408)
		(end 317.19139 -240.748058)
		(width 0.18288)
		(layer "In11.Cu")
		(net "M_D_CPU0_SB_DQS_DN<9>")
	)
	(segment
		(start 345.727782 -244.915436)
		(end 345.454224 -244.915436)
		(width 0.088646)
		(layer "In11.Cu")
		(net "M_D_CPU0_SB_DQS_DN<9>")
	)
	(segment
		(start 332.44917 -244.17147)
		(end 332.130908 -243.853208)
		(width 0.088646)
		(layer "In11.Cu")
		(net "M_D_CPU0_SB_DQS_DN<9>")
	)
	(segment
		(start 303.730152 -237.182406)
		(end 303.605692 -237.306866)
		(width 0.18288)
		(layer "In11.Cu")
		(net "M_D_CPU0_SB_DQS_DN<9>")
	)
	(segment
		(start 295.366186 -238.803942)
		(end 295.106852 -238.544608)
		(width 0.18288)
		(layer "In11.Cu")
		(net "M_D_CPU0_SB_DQS_DN<9>")
	)
	(segment
		(start 338.247736 -245.060978)
		(end 338.237322 -245.054882)
		(width 0.088646)
		(layer "In11.Cu")
		(net "M_D_CPU0_SB_DQS_DN<9>")
	)
	(segment
		(start 283.426154 -237.969298)
		(end 282.98775 -237.969298)
		(width 0.18288)
		(layer "In11.Cu")
		(net "M_D_CPU0_SB_DQS_DN<9>")
	)
	(segment
		(start 314.405518 -238.564674)
		(end 313.671458 -238.564674)
		(width 0.18288)
		(layer "In11.Cu")
		(net "M_D_CPU0_SB_DQS_DN<9>")
	)
	(segment
		(start 317.19139 -240.748058)
		(end 316.803278 -240.359946)
		(width 0.18288)
		(layer "In11.Cu")
		(net "M_D_CPU0_SB_DQS_DN<9>")
	)
	(segment
		(start 276.460966 -238.551466)
		(end 273.852386 -238.551466)
		(width 0.18288)
		(layer "In11.Cu")
		(net "M_D_CPU0_SB_DQS_DN<9>")
	)
	(segment
		(start 306.298092 -237.306866)
		(end 305.749452 -237.306866)
		(width 0.18288)
		(layer "In11.Cu")
		(net "M_D_CPU0_SB_DQS_DN<9>")
	)
	(segment
		(start 337.307682 -245.060978)
		(end 337.29295 -245.052342)
		(width 0.088646)
		(layer "In11.Cu")
		(net "M_D_CPU0_SB_DQS_DN<9>")
	)
	(segment
		(start 343.886282 -245.060978)
		(end 343.87155 -245.052342)
		(width 0.088646)
		(layer "In11.Cu")
		(net "M_D_CPU0_SB_DQS_DN<9>")
	)
	(segment
		(start 268.342364 -237.957868)
		(end 267.983208 -237.957868)
		(width 0.18288)
		(layer "In11.Cu")
		(net "M_D_CPU0_SB_DQS_DN<9>")
	)
	(segment
		(start 309.663592 -237.182406)
		(end 309.114952 -237.182406)
		(width 0.18288)
		(layer "In11.Cu")
		(net "M_D_CPU0_SB_DQS_DN<9>")
	)
	(segment
		(start 344.826336 -245.060978)
		(end 344.815922 -245.054882)
		(width 0.088646)
		(layer "In11.Cu")
		(net "M_D_CPU0_SB_DQS_DN<9>")
	)
	(segment
		(start 278.959818 -238.651034)
		(end 277.872444 -238.200184)
		(width 0.18288)
		(layer "In11.Cu")
		(net "M_D_CPU0_SB_DQS_DN<9>")
	)
	(segment
		(start 294.710358 -238.544608)
		(end 294.458644 -238.796322)
		(width 0.18288)
		(layer "In11.Cu")
		(net "M_D_CPU0_SB_DQS_DN<9>")
	)
	(segment
		(start 304.278792 -237.182406)
		(end 303.730152 -237.182406)
		(width 0.18288)
		(layer "In11.Cu")
		(net "M_D_CPU0_SB_DQS_DN<9>")
	)
	(segment
		(start 318.707262 -242.26393)
		(end 318.53124 -242.26393)
		(width 0.18288)
		(layer "In11.Cu")
		(net "M_D_CPU0_SB_DQS_DN<9>")
	)
	(segment
		(start 318.143382 -241.876072)
		(end 318.143382 -241.70005)
		(width 0.18288)
		(layer "In11.Cu")
		(net "M_D_CPU0_SB_DQS_DN<9>")
	)
	(segment
		(start 311.682892 -237.306866)
		(end 311.134252 -237.306866)
		(width 0.18288)
		(layer "In11.Cu")
		(net "M_D_CPU0_SB_DQS_DN<9>")
	)
	(segment
		(start 284.110684 -237.693708)
		(end 283.701744 -237.693708)
		(width 0.18288)
		(layer "In11.Cu")
		(net "M_D_CPU0_SB_DQS_DN<9>")
	)
	(segment
		(start 345.454224 -244.915436)
		(end 345.200986 -245.061232)
		(width 0.088646)
		(layer "In11.Cu")
		(net "M_D_CPU0_SB_DQS_DN<9>")
	)
	(segment
		(start 317.579248 -241.311938)
		(end 317.19139 -240.92408)
		(width 0.18288)
		(layer "In11.Cu")
		(net "M_D_CPU0_SB_DQS_DN<9>")
	)
	(segment
		(start 293.039038 -237.835694)
		(end 291.878004 -237.354364)
		(width 0.18288)
		(layer "In11.Cu")
		(net "M_D_CPU0_SB_DQS_DN<9>")
	)
	(segment
		(start 282.98775 -237.969298)
		(end 282.760674 -238.196374)
		(width 0.18288)
		(layer "In11.Cu")
		(net "M_D_CPU0_SB_DQS_DN<9>")
	)
	(segment
		(start 303.605692 -237.306866)
		(end 301.679356 -237.306866)
		(width 0.18288)
		(layer "In11.Cu")
		(net "M_D_CPU0_SB_DQS_DN<9>")
	)
	(arc
		(start 344.815922 -245.054882)
		(mid 344.53749 -244.985068)
		(end 344.260678 -245.060978)
		(width 0.088646)
		(layer "In11.Cu")
		(net "M_D_CPU0_SB_DQS_DN<9>")
	)
	(arc
		(start 334.862678 -245.060978)
		(mid 334.67548 -245.111121)
		(end 334.488282 -245.060978)
		(width 0.088646)
		(layer "In11.Cu")
		(net "M_D_CPU0_SB_DQS_DN<9>")
	)
	(arc
		(start 343.87155 -245.052342)
		(mid 343.595109 -244.985176)
		(end 343.320878 -245.060978)
		(width 0.088646)
		(layer "In11.Cu")
		(net "M_D_CPU0_SB_DQS_DN<9>")
	)
	(arc
		(start 336.742278 -245.060978)
		(mid 336.55508 -245.111121)
		(end 336.367882 -245.060978)
		(width 0.088646)
		(layer "In11.Cu")
		(net "M_D_CPU0_SB_DQS_DN<9>")
	)
	(arc
		(start 339.187282 -245.060978)
		(mid 338.910723 -244.985269)
		(end 338.632546 -245.054882)
		(width 0.088646)
		(layer "In11.Cu")
		(net "M_D_CPU0_SB_DQS_DN<9>")
	)
	(arc
		(start 335.802478 -245.060978)
		(mid 335.61528 -245.111121)
		(end 335.428082 -245.060978)
		(width 0.088646)
		(layer "In11.Cu")
		(net "M_D_CPU0_SB_DQS_DN<9>")
	)
	(arc
		(start 333.539592 -245.055898)
		(mid 333.408678 -244.919538)
		(end 333.36103 -244.73662)
		(width 0.088646)
		(layer "In11.Cu")
		(net "M_D_CPU0_SB_DQS_DN<9>")
	)
	(arc
		(start 336.35315 -245.052342)
		(mid 336.076709 -244.985176)
		(end 335.802478 -245.060978)
		(width 0.088646)
		(layer "In11.Cu")
		(net "M_D_CPU0_SB_DQS_DN<9>")
	)
	(arc
		(start 337.29295 -245.052342)
		(mid 337.016509 -244.985176)
		(end 336.742278 -245.060978)
		(width 0.088646)
		(layer "In11.Cu")
		(net "M_D_CPU0_SB_DQS_DN<9>")
	)
	(arc
		(start 340.116922 -245.054882)
		(mid 339.83849 -244.985068)
		(end 339.561678 -245.060978)
		(width 0.088646)
		(layer "In11.Cu")
		(net "M_D_CPU0_SB_DQS_DN<9>")
	)
	(arc
		(start 343.320878 -245.060978)
		(mid 343.13368 -245.111121)
		(end 342.946482 -245.060978)
		(width 0.088646)
		(layer "In11.Cu")
		(net "M_D_CPU0_SB_DQS_DN<9>")
	)
	(arc
		(start 345.882468 -244.874542)
		(mid 345.807783 -244.905047)
		(end 345.727782 -244.915436)
		(width 0.088646)
		(layer "In11.Cu")
		(net "M_D_CPU0_SB_DQS_DN<9>")
	)
	(arc
		(start 341.441278 -245.060978)
		(mid 341.25408 -245.111121)
		(end 341.066882 -245.060978)
		(width 0.088646)
		(layer "In11.Cu")
		(net "M_D_CPU0_SB_DQS_DN<9>")
	)
	(arc
		(start 338.237322 -245.054882)
		(mid 337.95889 -244.985068)
		(end 337.682078 -245.060978)
		(width 0.088646)
		(layer "In11.Cu")
		(net "M_D_CPU0_SB_DQS_DN<9>")
	)
	(arc
		(start 334.47355 -245.052342)
		(mid 334.197109 -244.985176)
		(end 333.922878 -245.060978)
		(width 0.088646)
		(layer "In11.Cu")
		(net "M_D_CPU0_SB_DQS_DN<9>")
	)
	(arc
		(start 333.922878 -245.060978)
		(mid 333.73568 -245.111121)
		(end 333.548482 -245.060978)
		(width 0.088646)
		(layer "In11.Cu")
		(net "M_D_CPU0_SB_DQS_DN<9>")
	)
	(arc
		(start 344.260678 -245.060978)
		(mid 344.07348 -245.111121)
		(end 343.886282 -245.060978)
		(width 0.088646)
		(layer "In11.Cu")
		(net "M_D_CPU0_SB_DQS_DN<9>")
	)
	(arc
		(start 342.381078 -245.060978)
		(mid 342.19388 -245.111121)
		(end 342.006682 -245.060978)
		(width 0.088646)
		(layer "In11.Cu")
		(net "M_D_CPU0_SB_DQS_DN<9>")
	)
	(arc
		(start 340.501732 -245.060978)
		(mid 340.314534 -245.111121)
		(end 340.127336 -245.060978)
		(width 0.088646)
		(layer "In11.Cu")
		(net "M_D_CPU0_SB_DQS_DN<9>")
	)
	(arc
		(start 342.93175 -245.052342)
		(mid 342.655309 -244.985176)
		(end 342.381078 -245.060978)
		(width 0.088646)
		(layer "In11.Cu")
		(net "M_D_CPU0_SB_DQS_DN<9>")
	)
	(arc
		(start 345.200732 -245.060978)
		(mid 345.013534 -245.111121)
		(end 344.826336 -245.060978)
		(width 0.088646)
		(layer "In11.Cu")
		(net "M_D_CPU0_SB_DQS_DN<9>")
	)
	(arc
		(start 341.99195 -245.052342)
		(mid 341.715509 -244.985176)
		(end 341.441278 -245.060978)
		(width 0.088646)
		(layer "In11.Cu")
		(net "M_D_CPU0_SB_DQS_DN<9>")
	)
	(arc
		(start 339.561678 -245.060978)
		(mid 339.37448 -245.111121)
		(end 339.187282 -245.060978)
		(width 0.088646)
		(layer "In11.Cu")
		(net "M_D_CPU0_SB_DQS_DN<9>")
	)
	(arc
		(start 335.41335 -245.052342)
		(mid 335.136909 -244.985176)
		(end 334.862678 -245.060978)
		(width 0.088646)
		(layer "In11.Cu")
		(net "M_D_CPU0_SB_DQS_DN<9>")
	)
	(arc
		(start 333.36103 -244.726714)
		(mid 333.192136 -244.333539)
		(end 332.796134 -244.17147)
		(width 0.088646)
		(layer "In11.Cu")
		(net "M_D_CPU0_SB_DQS_DN<9>")
	)
	(arc
		(start 341.066882 -245.060978)
		(mid 340.790323 -244.985269)
		(end 340.512146 -245.054882)
		(width 0.088646)
		(layer "In11.Cu")
		(net "M_D_CPU0_SB_DQS_DN<9>")
	)
	(arc
		(start 338.622132 -245.060978)
		(mid 338.434934 -245.111121)
		(end 338.247736 -245.060978)
		(width 0.088646)
		(layer "In11.Cu")
		(net "M_D_CPU0_SB_DQS_DN<9>")
	)
	(arc
		(start 337.682078 -245.060978)
		(mid 337.49488 -245.111121)
		(end 337.307682 -245.060978)
		(width 0.088646)
		(layer "In11.Cu")
		(net "M_D_CPU0_SB_DQS_DN<9>")
	)
	(segment
		(start 267.233908 -199.866758)
		(end 266.972796 -199.605646)
		(width 0.20066)
		(layer "F.Cu")
		(net "M_D_CPU0_SB_DQS_DN<8>")
	)
	(segment
		(start 262.74776 -199.441816)
		(end 262.507984 -199.441816)
		(width 0.101854)
		(layer "F.Cu")
		(net "M_D_CPU0_SB_DQS_DN<8>")
	)
	(segment
		(start 260.65226 -199.866758)
		(end 260.180582 -199.866758)
		(width 0.20066)
		(layer "F.Cu")
		(net "M_D_CPU0_SB_DQS_DN<8>")
	)
	(segment
		(start 265.6332 -199.180704)
		(end 265.228578 -199.180704)
		(width 0.20066)
		(layer "F.Cu")
		(net "M_D_CPU0_SB_DQS_DN<8>")
	)
	(segment
		(start 264.825226 -199.441816)
		(end 262.74776 -199.441816)
		(width 0.1016)
		(layer "F.Cu")
		(net "M_D_CPU0_SB_DQS_DN<8>")
	)
	(segment
		(start 260.913372 -199.605646)
		(end 260.65226 -199.866758)
		(width 0.20066)
		(layer "F.Cu")
		(net "M_D_CPU0_SB_DQS_DN<8>")
	)
	(segment
		(start 266.972796 -199.605646)
		(end 266.269216 -199.605646)
		(width 0.20066)
		(layer "F.Cu")
		(net "M_D_CPU0_SB_DQS_DN<8>")
	)
	(segment
		(start 267.724382 -199.866758)
		(end 267.233908 -199.866758)
		(width 0.20066)
		(layer "F.Cu")
		(net "M_D_CPU0_SB_DQS_DN<8>")
	)
	(segment
		(start 264.967466 -199.441816)
		(end 264.825226 -199.441816)
		(width 0.20066)
		(layer "F.Cu")
		(net "M_D_CPU0_SB_DQS_DN<8>")
	)
	(segment
		(start 266.269216 -199.605646)
		(end 265.6332 -199.180704)
		(width 0.20066)
		(layer "F.Cu")
		(net "M_D_CPU0_SB_DQS_DN<8>")
	)
	(segment
		(start 262.315198 -199.44969)
		(end 262.048752 -199.183244)
		(width 0.20066)
		(layer "F.Cu")
		(net "M_D_CPU0_SB_DQS_DN<8>")
	)
	(segment
		(start 347.832934 -230.622602)
		(end 347.83268 -230.622348)
		(width 0.20066)
		(layer "F.Cu")
		(net "M_D_CPU0_SB_DQS_DN<8>")
	)
	(segment
		(start 268.829282 -199.866758)
		(end 267.724382 -199.866758)
		(width 0.20066)
		(layer "F.Cu")
		(net "M_D_CPU0_SB_DQS_DN<8>")
	)
	(segment
		(start 262.048752 -199.183244)
		(end 261.808976 -199.183244)
		(width 0.20066)
		(layer "F.Cu")
		(net "M_D_CPU0_SB_DQS_DN<8>")
	)
	(segment
		(start 265.228578 -199.180704)
		(end 264.967466 -199.441816)
		(width 0.20066)
		(layer "F.Cu")
		(net "M_D_CPU0_SB_DQS_DN<8>")
	)
	(segment
		(start 261.808976 -199.183244)
		(end 261.386574 -199.605646)
		(width 0.20066)
		(layer "F.Cu")
		(net "M_D_CPU0_SB_DQS_DN<8>")
	)
	(segment
		(start 262.50011 -199.44969)
		(end 262.315198 -199.44969)
		(width 0.20066)
		(layer "F.Cu")
		(net "M_D_CPU0_SB_DQS_DN<8>")
	)
	(segment
		(start 262.507984 -199.441816)
		(end 262.50011 -199.44969)
		(width 0.101854)
		(layer "F.Cu")
		(net "M_D_CPU0_SB_DQS_DN<8>")
	)
	(segment
		(start 261.386574 -199.605646)
		(end 260.913372 -199.605646)
		(width 0.20066)
		(layer "F.Cu")
		(net "M_D_CPU0_SB_DQS_DN<8>")
	)
	(segment
		(start 347.83268 -230.622348)
		(end 347.83268 -230.086662)
		(width 0.20066)
		(layer "F.Cu")
		(net "M_D_CPU0_SB_DQS_DN<8>")
	)
	(segment
		(start 296.870628 -197.462394)
		(end 295.396666 -197.462394)
		(width 0.18288)
		(layer "In11.Cu")
		(net "M_D_CPU0_SB_DQS_DN<8>")
	)
	(segment
		(start 330.468732 -223.610678)
		(end 330.383896 -223.610678)
		(width 0.088646)
		(layer "In11.Cu")
		(net "M_D_CPU0_SB_DQS_DN<8>")
	)
	(segment
		(start 307.740304 -198.38543)
		(end 307.037994 -197.68312)
		(width 0.18288)
		(layer "In11.Cu")
		(net "M_D_CPU0_SB_DQS_DN<8>")
	)
	(segment
		(start 289.14471 -197.604634)
		(end 288.43351 -198.315834)
		(width 0.18288)
		(layer "In11.Cu")
		(net "M_D_CPU0_SB_DQS_DN<8>")
	)
	(segment
		(start 348.028768 -229.767384)
		(end 348.019878 -229.762304)
		(width 0.088646)
		(layer "In11.Cu")
		(net "M_D_CPU0_SB_DQS_DN<8>")
	)
	(segment
		(start 337.227164 -227.329238)
		(end 337.212432 -227.320602)
		(width 0.088646)
		(layer "In11.Cu")
		(net "M_D_CPU0_SB_DQS_DN<8>")
	)
	(segment
		(start 284.14345 -198.590916)
		(end 283.71165 -198.590916)
		(width 0.18288)
		(layer "In11.Cu")
		(net "M_D_CPU0_SB_DQS_DN<8>")
	)
	(segment
		(start 310.48198 -198.38543)
		(end 307.740304 -198.38543)
		(width 0.18288)
		(layer "In11.Cu")
		(net "M_D_CPU0_SB_DQS_DN<8>")
	)
	(segment
		(start 348.145608 -230.086662)
		(end 348.202758 -230.029512)
		(width 0.088646)
		(layer "In11.Cu")
		(net "M_D_CPU0_SB_DQS_DN<8>")
	)
	(segment
		(start 347.645482 -229.762304)
		(end 347.63075 -229.77094)
		(width 0.088646)
		(layer "In11.Cu")
		(net "M_D_CPU0_SB_DQS_DN<8>")
	)
	(segment
		(start 344.745564 -227.329238)
		(end 344.730832 -227.320602)
		(width 0.088646)
		(layer "In11.Cu")
		(net "M_D_CPU0_SB_DQS_DN<8>")
	)
	(segment
		(start 275.513546 -198.154544)
		(end 274.715224 -198.952612)
		(width 0.18288)
		(layer "In11.Cu")
		(net "M_D_CPU0_SB_DQS_DN<8>")
	)
	(segment
		(start 299.229018 -198.590408)
		(end 298.759626 -198.590408)
		(width 0.18288)
		(layer "In11.Cu")
		(net "M_D_CPU0_SB_DQS_DN<8>")
	)
	(segment
		(start 322.61302 -212.182202)
		(end 322.224908 -211.79409)
		(width 0.18288)
		(layer "In11.Cu")
		(net "M_D_CPU0_SB_DQS_DN<8>")
	)
	(segment
		(start 335.98993 -226.831144)
		(end 335.98993 -226.822508)
		(width 0.088646)
		(layer "In11.Cu")
		(net "M_D_CPU0_SB_DQS_DN<8>")
	)
	(segment
		(start 273.60118 -198.952612)
		(end 272.993866 -198.734934)
		(width 0.18288)
		(layer "In11.Cu")
		(net "M_D_CPU0_SB_DQS_DN<8>")
	)
	(segment
		(start 295.396666 -197.462394)
		(end 295.117012 -197.742048)
		(width 0.18288)
		(layer "In11.Cu")
		(net "M_D_CPU0_SB_DQS_DN<8>")
	)
	(segment
		(start 272.993612 -198.735188)
		(end 272.48612 -198.553324)
		(width 0.18288)
		(layer "In11.Cu")
		(net "M_D_CPU0_SB_DQS_DN<8>")
	)
	(segment
		(start 336.272632 -227.320602)
		(end 336.266536 -227.317046)
		(width 0.088646)
		(layer "In11.Cu")
		(net "M_D_CPU0_SB_DQS_DN<8>")
	)
	(segment
		(start 332.796134 -225.768662)
		(end 332.302358 -225.768662)
		(width 0.088646)
		(layer "In11.Cu")
		(net "M_D_CPU0_SB_DQS_DN<8>")
	)
	(segment
		(start 334.958182 -225.69297)
		(end 334.947768 -225.699066)
		(width 0.088646)
		(layer "In11.Cu")
		(net "M_D_CPU0_SB_DQS_DN<8>")
	)
	(segment
		(start 275.914612 -197.887082)
		(end 275.513546 -198.154544)
		(width 0.18288)
		(layer "In11.Cu")
		(net "M_D_CPU0_SB_DQS_DN<8>")
	)
	(segment
		(start 335.802732 -226.506786)
		(end 335.79054 -226.499674)
		(width 0.088646)
		(layer "In11.Cu")
		(net "M_D_CPU0_SB_DQS_DN<8>")
	)
	(segment
		(start 332.302358 -225.768662)
		(end 331.873606 -225.33991)
		(width 0.088646)
		(layer "In11.Cu")
		(net "M_D_CPU0_SB_DQS_DN<8>")
	)
	(segment
		(start 331.873606 -225.33991)
		(end 331.873606 -225.015552)
		(width 0.088646)
		(layer "In11.Cu")
		(net "M_D_CPU0_SB_DQS_DN<8>")
	)
	(segment
		(start 334.018636 -225.69297)
		(end 334.008222 -225.699066)
		(width 0.088646)
		(layer "In11.Cu")
		(net "M_D_CPU0_SB_DQS_DN<8>")
	)
	(segment
		(start 345.67368 -227.322126)
		(end 345.670632 -227.320602)
		(width 0.088646)
		(layer "In11.Cu")
		(net "M_D_CPU0_SB_DQS_DN<8>")
	)
	(segment
		(start 336.287364 -227.329238)
		(end 336.272632 -227.320602)
		(width 0.088646)
		(layer "In11.Cu")
		(net "M_D_CPU0_SB_DQS_DN<8>")
	)
	(segment
		(start 279.554686 -197.740778)
		(end 279.324308 -197.5104)
		(width 0.18288)
		(layer "In11.Cu")
		(net "M_D_CPU0_SB_DQS_DN<8>")
	)
	(segment
		(start 282.445714 -197.896734)
		(end 281.37739 -197.454012)
		(width 0.18288)
		(layer "In11.Cu")
		(net "M_D_CPU0_SB_DQS_DN<8>")
	)
	(segment
		(start 321.661028 -211.23021)
		(end 321.272916 -210.842098)
		(width 0.18288)
		(layer "In11.Cu")
		(net "M_D_CPU0_SB_DQS_DN<8>")
	)
	(segment
		(start 282.89631 -198.34733)
		(end 282.445714 -197.896734)
		(width 0.18288)
		(layer "In11.Cu")
		(net "M_D_CPU0_SB_DQS_DN<8>")
	)
	(segment
		(start 322.789042 -212.182202)
		(end 322.61302 -212.182202)
		(width 0.18288)
		(layer "In11.Cu")
		(net "M_D_CPU0_SB_DQS_DN<8>")
	)
	(segment
		(start 313.395868 -202.789028)
		(end 313.39536 -202.788266)
		(width 0.18288)
		(layer "In11.Cu")
		(net "M_D_CPU0_SB_DQS_DN<8>")
	)
	(segment
		(start 302.910748 -198.316088)
		(end 299.503338 -198.316088)
		(width 0.18288)
		(layer "In11.Cu")
		(net "M_D_CPU0_SB_DQS_DN<8>")
	)
	(segment
		(start 295.117012 -197.742048)
		(end 294.651176 -197.742048)
		(width 0.18288)
		(layer "In11.Cu")
		(net "M_D_CPU0_SB_DQS_DN<8>")
	)
	(segment
		(start 323.1769 -212.57006)
		(end 322.789042 -212.182202)
		(width 0.18288)
		(layer "In11.Cu")
		(net "M_D_CPU0_SB_DQS_DN<8>")
	)
	(segment
		(start 345.679522 -227.325682)
		(end 345.675712 -227.323396)
		(width 0.088646)
		(layer "In11.Cu")
		(net "M_D_CPU0_SB_DQS_DN<8>")
	)
	(segment
		(start 293.874952 -197.475602)
		(end 293.223188 -198.127366)
		(width 0.18288)
		(layer "In11.Cu")
		(net "M_D_CPU0_SB_DQS_DN<8>")
	)
	(segment
		(start 276.831806 -197.714108)
		(end 276.187662 -197.714108)
		(width 0.18288)
		(layer "In11.Cu")
		(net "M_D_CPU0_SB_DQS_DN<8>")
	)
	(segment
		(start 312.488072 -200.391776)
		(end 310.48198 -198.38543)
		(width 0.18288)
		(layer "In11.Cu")
		(net "M_D_CPU0_SB_DQS_DN<8>")
	)
	(segment
		(start 297.77944 -198.371206)
		(end 296.870628 -197.462394)
		(width 0.18288)
		(layer "In11.Cu")
		(net "M_D_CPU0_SB_DQS_DN<8>")
	)
	(segment
		(start 338.166964 -227.329238)
		(end 338.152232 -227.320602)
		(width 0.088646)
		(layer "In11.Cu")
		(net "M_D_CPU0_SB_DQS_DN<8>")
	)
	(segment
		(start 278.701754 -197.5104)
		(end 278.084788 -198.127366)
		(width 0.18288)
		(layer "In11.Cu")
		(net "M_D_CPU0_SB_DQS_DN<8>")
	)
	(segment
		(start 280.043382 -197.740778)
		(end 279.554686 -197.740778)
		(width 0.18288)
		(layer "In11.Cu")
		(net "M_D_CPU0_SB_DQS_DN<8>")
	)
	(segment
		(start 280.330148 -197.454012)
		(end 280.043382 -197.740778)
		(width 0.18288)
		(layer "In11.Cu")
		(net "M_D_CPU0_SB_DQS_DN<8>")
	)
	(segment
		(start 345.858084 -229.28834)
		(end 345.858084 -229.272846)
		(width 0.088646)
		(layer "In11.Cu")
		(net "M_D_CPU0_SB_DQS_DN<8>")
	)
	(segment
		(start 335.341468 -225.69805)
		(end 335.332578 -225.69297)
		(width 0.088646)
		(layer "In11.Cu")
		(net "M_D_CPU0_SB_DQS_DN<8>")
	)
	(segment
		(start 269.553436 -199.608694)
		(end 269.087346 -199.608694)
		(width 0.18288)
		(layer "In11.Cu")
		(net "M_D_CPU0_SB_DQS_DN<8>")
	)
	(segment
		(start 345.666822 -228.946202)
		(end 345.65844 -228.941376)
		(width 0.088646)
		(layer "In11.Cu")
		(net "M_D_CPU0_SB_DQS_DN<8>")
	)
	(segment
		(start 319.368932 -208.938114)
		(end 319.368932 -208.762092)
		(width 0.18288)
		(layer "In11.Cu")
		(net "M_D_CPU0_SB_DQS_DN<8>")
	)
	(segment
		(start 346.705682 -229.762304)
		(end 346.69095 -229.77094)
		(width 0.088646)
		(layer "In11.Cu")
		(net "M_D_CPU0_SB_DQS_DN<8>")
	)
	(segment
		(start 303.543716 -197.68312)
		(end 302.910748 -198.316088)
		(width 0.18288)
		(layer "In11.Cu")
		(net "M_D_CPU0_SB_DQS_DN<8>")
	)
	(segment
		(start 269.862808 -199.918066)
		(end 269.553436 -199.608694)
		(width 0.18288)
		(layer "In11.Cu")
		(net "M_D_CPU0_SB_DQS_DN<8>")
	)
	(segment
		(start 271.932654 -198.553324)
		(end 270.567912 -199.918066)
		(width 0.18288)
		(layer "In11.Cu")
		(net "M_D_CPU0_SB_DQS_DN<8>")
	)
	(segment
		(start 345.38793 -228.45903)
		(end 345.38793 -228.45141)
		(width 0.088646)
		(layer "In11.Cu")
		(net "M_D_CPU0_SB_DQS_DN<8>")
	)
	(segment
		(start 345.671394 -228.948996)
		(end 345.670632 -228.948488)
		(width 0.088646)
		(layer "In11.Cu")
		(net "M_D_CPU0_SB_DQS_DN<8>")
	)
	(segment
		(start 281.37739 -197.454012)
		(end 280.330148 -197.454012)
		(width 0.18288)
		(layer "In11.Cu")
		(net "M_D_CPU0_SB_DQS_DN<8>")
	)
	(segment
		(start 288.43351 -198.315834)
		(end 284.418532 -198.315834)
		(width 0.18288)
		(layer "In11.Cu")
		(net "M_D_CPU0_SB_DQS_DN<8>")
	)
	(segment
		(start 345.670632 -228.948488)
		(end 345.666822 -228.946202)
		(width 0.088646)
		(layer "In11.Cu")
		(net "M_D_CPU0_SB_DQS_DN<8>")
	)
	(segment
		(start 279.324308 -197.5104)
		(end 278.701754 -197.5104)
		(width 0.18288)
		(layer "In11.Cu")
		(net "M_D_CPU0_SB_DQS_DN<8>")
	)
	(segment
		(start 269.087346 -199.608694)
		(end 268.829282 -199.866758)
		(width 0.18288)
		(layer "In11.Cu")
		(net "M_D_CPU0_SB_DQS_DN<8>")
	)
	(segment
		(start 320.320924 -209.714084)
		(end 319.933066 -209.326226)
		(width 0.18288)
		(layer "In11.Cu")
		(net "M_D_CPU0_SB_DQS_DN<8>")
	)
	(segment
		(start 341.926164 -227.329238)
		(end 341.911432 -227.320602)
		(width 0.088646)
		(layer "In11.Cu")
		(net "M_D_CPU0_SB_DQS_DN<8>")
	)
	(segment
		(start 342.865964 -227.329238)
		(end 342.851232 -227.320602)
		(width 0.088646)
		(layer "In11.Cu")
		(net "M_D_CPU0_SB_DQS_DN<8>")
	)
	(segment
		(start 292.231318 -198.127366)
		(end 291.708586 -197.604634)
		(width 0.18288)
		(layer "In11.Cu")
		(net "M_D_CPU0_SB_DQS_DN<8>")
	)
	(segment
		(start 278.084788 -198.127366)
		(end 277.245064 -198.127366)
		(width 0.18288)
		(layer "In11.Cu")
		(net "M_D_CPU0_SB_DQS_DN<8>")
	)
	(segment
		(start 347.83268 -230.086662)
		(end 348.145608 -230.086662)
		(width 0.088646)
		(layer "In11.Cu")
		(net "M_D_CPU0_SB_DQS_DN<8>")
	)
	(segment
		(start 294.38473 -197.475602)
		(end 293.874952 -197.475602)
		(width 0.18288)
		(layer "In11.Cu")
		(net "M_D_CPU0_SB_DQS_DN<8>")
	)
	(segment
		(start 339.657182 -227.320602)
		(end 339.646768 -227.326698)
		(width 0.088646)
		(layer "In11.Cu")
		(net "M_D_CPU0_SB_DQS_DN<8>")
	)
	(segment
		(start 345.679522 -228.953568)
		(end 345.671394 -228.948996)
		(width 0.088646)
		(layer "In11.Cu")
		(net "M_D_CPU0_SB_DQS_DN<8>")
	)
	(segment
		(start 298.759626 -198.590408)
		(end 298.540424 -198.371206)
		(width 0.18288)
		(layer "In11.Cu")
		(net "M_D_CPU0_SB_DQS_DN<8>")
	)
	(segment
		(start 321.272916 -210.842098)
		(end 321.272916 -210.666076)
		(width 0.18288)
		(layer "In11.Cu")
		(net "M_D_CPU0_SB_DQS_DN<8>")
	)
	(segment
		(start 276.187662 -197.714108)
		(end 275.914612 -197.887082)
		(width 0.18288)
		(layer "In11.Cu")
		(net "M_D_CPU0_SB_DQS_DN<8>")
	)
	(segment
		(start 277.245064 -198.127366)
		(end 276.831806 -197.714108)
		(width 0.18288)
		(layer "In11.Cu")
		(net "M_D_CPU0_SB_DQS_DN<8>")
	)
	(segment
		(start 270.567912 -199.918066)
		(end 269.862808 -199.918066)
		(width 0.18288)
		(layer "In11.Cu")
		(net "M_D_CPU0_SB_DQS_DN<8>")
	)
	(segment
		(start 320.885058 -210.278218)
		(end 320.709036 -210.278218)
		(width 0.18288)
		(layer "In11.Cu")
		(net "M_D_CPU0_SB_DQS_DN<8>")
	)
	(segment
		(start 319.933066 -209.326226)
		(end 319.757044 -209.326226)
		(width 0.18288)
		(layer "In11.Cu")
		(net "M_D_CPU0_SB_DQS_DN<8>")
	)
	(segment
		(start 313.39536 -202.788266)
		(end 312.488072 -200.391776)
		(width 0.18288)
		(layer "In11.Cu")
		(net "M_D_CPU0_SB_DQS_DN<8>")
	)
	(segment
		(start 340.041992 -227.326698)
		(end 340.031578 -227.320602)
		(width 0.088646)
		(layer "In11.Cu")
		(net "M_D_CPU0_SB_DQS_DN<8>")
	)
	(segment
		(start 294.651176 -197.742048)
		(end 294.38473 -197.475602)
		(width 0.18288)
		(layer "In11.Cu")
		(net "M_D_CPU0_SB_DQS_DN<8>")
	)
	(segment
		(start 299.503338 -198.316088)
		(end 299.229018 -198.590408)
		(width 0.18288)
		(layer "In11.Cu")
		(net "M_D_CPU0_SB_DQS_DN<8>")
	)
	(segment
		(start 340.986364 -227.329238)
		(end 340.971632 -227.320602)
		(width 0.088646)
		(layer "In11.Cu")
		(net "M_D_CPU0_SB_DQS_DN<8>")
	)
	(segment
		(start 307.037994 -197.68312)
		(end 303.543716 -197.68312)
		(width 0.18288)
		(layer "In11.Cu")
		(net "M_D_CPU0_SB_DQS_DN<8>")
	)
	(segment
		(start 272.48612 -198.553324)
		(end 271.932654 -198.553324)
		(width 0.18288)
		(layer "In11.Cu")
		(net "M_D_CPU0_SB_DQS_DN<8>")
	)
	(segment
		(start 293.223188 -198.127366)
		(end 292.231318 -198.127366)
		(width 0.18288)
		(layer "In11.Cu")
		(net "M_D_CPU0_SB_DQS_DN<8>")
	)
	(segment
		(start 298.540424 -198.371206)
		(end 297.77944 -198.371206)
		(width 0.18288)
		(layer "In11.Cu")
		(net "M_D_CPU0_SB_DQS_DN<8>")
	)
	(segment
		(start 274.715224 -198.952612)
		(end 273.60118 -198.952612)
		(width 0.18288)
		(layer "In11.Cu")
		(net "M_D_CPU0_SB_DQS_DN<8>")
	)
	(segment
		(start 321.272916 -210.666076)
		(end 320.885058 -210.278218)
		(width 0.18288)
		(layer "In11.Cu")
		(net "M_D_CPU0_SB_DQS_DN<8>")
	)
	(segment
		(start 291.708586 -197.604634)
		(end 289.14471 -197.604634)
		(width 0.18288)
		(layer "In11.Cu")
		(net "M_D_CPU0_SB_DQS_DN<8>")
	)
	(segment
		(start 330.383896 -223.610678)
		(end 323.1769 -216.403682)
		(width 0.18288)
		(layer "In11.Cu")
		(net "M_D_CPU0_SB_DQS_DN<8>")
	)
	(segment
		(start 319.368932 -208.762092)
		(end 313.395868 -202.789028)
		(width 0.18288)
		(layer "In11.Cu")
		(net "M_D_CPU0_SB_DQS_DN<8>")
	)
	(segment
		(start 272.993866 -198.734934)
		(end 272.993612 -198.735188)
		(width 0.18288)
		(layer "In11.Cu")
		(net "M_D_CPU0_SB_DQS_DN<8>")
	)
	(segment
		(start 322.224908 -211.618068)
		(end 321.83705 -211.23021)
		(width 0.18288)
		(layer "In11.Cu")
		(net "M_D_CPU0_SB_DQS_DN<8>")
	)
	(segment
		(start 331.873606 -225.015552)
		(end 330.468732 -223.610678)
		(width 0.088646)
		(layer "In11.Cu")
		(net "M_D_CPU0_SB_DQS_DN<8>")
	)
	(segment
		(start 345.675712 -227.323396)
		(end 345.67368 -227.322126)
		(width 0.088646)
		(layer "In11.Cu")
		(net "M_D_CPU0_SB_DQS_DN<8>")
	)
	(segment
		(start 322.224908 -211.79409)
		(end 322.224908 -211.618068)
		(width 0.18288)
		(layer "In11.Cu")
		(net "M_D_CPU0_SB_DQS_DN<8>")
	)
	(segment
		(start 320.709036 -210.278218)
		(end 320.320924 -209.890106)
		(width 0.18288)
		(layer "In11.Cu")
		(net "M_D_CPU0_SB_DQS_DN<8>")
	)
	(segment
		(start 283.71165 -198.590916)
		(end 283.468064 -198.34733)
		(width 0.18288)
		(layer "In11.Cu")
		(net "M_D_CPU0_SB_DQS_DN<8>")
	)
	(segment
		(start 319.757044 -209.326226)
		(end 319.368932 -208.938114)
		(width 0.18288)
		(layer "In11.Cu")
		(net "M_D_CPU0_SB_DQS_DN<8>")
	)
	(segment
		(start 283.468064 -198.34733)
		(end 282.89631 -198.34733)
		(width 0.18288)
		(layer "In11.Cu")
		(net "M_D_CPU0_SB_DQS_DN<8>")
	)
	(segment
		(start 284.418532 -198.315834)
		(end 284.14345 -198.590916)
		(width 0.18288)
		(layer "In11.Cu")
		(net "M_D_CPU0_SB_DQS_DN<8>")
	)
	(segment
		(start 321.83705 -211.23021)
		(end 321.661028 -211.23021)
		(width 0.18288)
		(layer "In11.Cu")
		(net "M_D_CPU0_SB_DQS_DN<8>")
	)
	(segment
		(start 323.1769 -216.403682)
		(end 323.1769 -212.57006)
		(width 0.18288)
		(layer "In11.Cu")
		(net "M_D_CPU0_SB_DQS_DN<8>")
	)
	(segment
		(start 345.670632 -227.969318)
		(end 345.679522 -227.964238)
		(width 0.088646)
		(layer "In11.Cu")
		(net "M_D_CPU0_SB_DQS_DN<8>")
	)
	(segment
		(start 320.320924 -209.890106)
		(end 320.320924 -209.714084)
		(width 0.18288)
		(layer "In11.Cu")
		(net "M_D_CPU0_SB_DQS_DN<8>")
	)
	(arc
		(start 341.911432 -227.320602)
		(mid 341.724234 -227.270459)
		(end 341.537036 -227.320602)
		(width 0.088646)
		(layer "In11.Cu")
		(net "M_D_CPU0_SB_DQS_DN<8>")
	)
	(arc
		(start 338.717636 -227.320602)
		(mid 338.443437 -227.396437)
		(end 338.166964 -227.329238)
		(width 0.088646)
		(layer "In11.Cu")
		(net "M_D_CPU0_SB_DQS_DN<8>")
	)
	(arc
		(start 341.537036 -227.320602)
		(mid 341.262837 -227.396437)
		(end 340.986364 -227.329238)
		(width 0.088646)
		(layer "In11.Cu")
		(net "M_D_CPU0_SB_DQS_DN<8>")
	)
	(arc
		(start 334.947768 -225.699066)
		(mid 334.66959 -225.768758)
		(end 334.393032 -225.69297)
		(width 0.088646)
		(layer "In11.Cu")
		(net "M_D_CPU0_SB_DQS_DN<8>")
	)
	(arc
		(start 345.296236 -227.320602)
		(mid 345.022037 -227.396437)
		(end 344.745564 -227.329238)
		(width 0.088646)
		(layer "In11.Cu")
		(net "M_D_CPU0_SB_DQS_DN<8>")
	)
	(arc
		(start 342.476836 -227.320602)
		(mid 342.202637 -227.396437)
		(end 341.926164 -227.329238)
		(width 0.088646)
		(layer "In11.Cu")
		(net "M_D_CPU0_SB_DQS_DN<8>")
	)
	(arc
		(start 335.79054 -226.499674)
		(mid 335.592312 -226.293826)
		(end 335.52003 -226.017328)
		(width 0.088646)
		(layer "In11.Cu")
		(net "M_D_CPU0_SB_DQS_DN<8>")
	)
	(arc
		(start 339.092032 -227.320602)
		(mid 338.904834 -227.270459)
		(end 338.717636 -227.320602)
		(width 0.088646)
		(layer "In11.Cu")
		(net "M_D_CPU0_SB_DQS_DN<8>")
	)
	(arc
		(start 347.080078 -229.762304)
		(mid 346.89288 -229.712161)
		(end 346.705682 -229.762304)
		(width 0.088646)
		(layer "In11.Cu")
		(net "M_D_CPU0_SB_DQS_DN<8>")
	)
	(arc
		(start 348.202758 -230.029512)
		(mid 348.144639 -229.879271)
		(end 348.028768 -229.767384)
		(width 0.088646)
		(layer "In11.Cu")
		(net "M_D_CPU0_SB_DQS_DN<8>")
	)
	(arc
		(start 338.152232 -227.320602)
		(mid 337.965034 -227.270459)
		(end 337.777836 -227.320602)
		(width 0.088646)
		(layer "In11.Cu")
		(net "M_D_CPU0_SB_DQS_DN<8>")
	)
	(arc
		(start 345.38793 -228.45141)
		(mid 345.465559 -228.172997)
		(end 345.670632 -227.969318)
		(width 0.088646)
		(layer "In11.Cu")
		(net "M_D_CPU0_SB_DQS_DN<8>")
	)
	(arc
		(start 345.679522 -227.964238)
		(mid 345.857998 -227.64496)
		(end 345.679522 -227.325682)
		(width 0.088646)
		(layer "In11.Cu")
		(net "M_D_CPU0_SB_DQS_DN<8>")
	)
	(arc
		(start 344.356436 -227.320602)
		(mid 344.073734 -227.396378)
		(end 343.791032 -227.320602)
		(width 0.088646)
		(layer "In11.Cu")
		(net "M_D_CPU0_SB_DQS_DN<8>")
	)
	(arc
		(start 347.63075 -229.77094)
		(mid 347.354275 -229.83826)
		(end 347.080078 -229.762304)
		(width 0.088646)
		(layer "In11.Cu")
		(net "M_D_CPU0_SB_DQS_DN<8>")
	)
	(arc
		(start 345.858084 -229.272846)
		(mid 345.810405 -229.089946)
		(end 345.679522 -228.953568)
		(width 0.088646)
		(layer "In11.Cu")
		(net "M_D_CPU0_SB_DQS_DN<8>")
	)
	(arc
		(start 333.078582 -225.69297)
		(mid 332.942339 -225.749416)
		(end 332.796134 -225.768662)
		(width 0.088646)
		(layer "In11.Cu")
		(net "M_D_CPU0_SB_DQS_DN<8>")
	)
	(arc
		(start 343.416636 -227.320602)
		(mid 343.142437 -227.396437)
		(end 342.865964 -227.329238)
		(width 0.088646)
		(layer "In11.Cu")
		(net "M_D_CPU0_SB_DQS_DN<8>")
	)
	(arc
		(start 343.791032 -227.320602)
		(mid 343.603834 -227.270459)
		(end 343.416636 -227.320602)
		(width 0.088646)
		(layer "In11.Cu")
		(net "M_D_CPU0_SB_DQS_DN<8>")
	)
	(arc
		(start 340.597236 -227.320602)
		(mid 340.320423 -227.396472)
		(end 340.041992 -227.326698)
		(width 0.088646)
		(layer "In11.Cu")
		(net "M_D_CPU0_SB_DQS_DN<8>")
	)
	(arc
		(start 337.212432 -227.320602)
		(mid 337.025234 -227.270459)
		(end 336.838036 -227.320602)
		(width 0.088646)
		(layer "In11.Cu")
		(net "M_D_CPU0_SB_DQS_DN<8>")
	)
	(arc
		(start 336.266536 -227.317046)
		(mid 336.063949 -227.110695)
		(end 335.98993 -226.831144)
		(width 0.088646)
		(layer "In11.Cu")
		(net "M_D_CPU0_SB_DQS_DN<8>")
	)
	(arc
		(start 340.031578 -227.320602)
		(mid 339.84438 -227.270459)
		(end 339.657182 -227.320602)
		(width 0.088646)
		(layer "In11.Cu")
		(net "M_D_CPU0_SB_DQS_DN<8>")
	)
	(arc
		(start 346.69095 -229.77094)
		(mid 346.414475 -229.83826)
		(end 346.140278 -229.762304)
		(width 0.088646)
		(layer "In11.Cu")
		(net "M_D_CPU0_SB_DQS_DN<8>")
	)
	(arc
		(start 334.393032 -225.69297)
		(mid 334.205834 -225.642827)
		(end 334.018636 -225.69297)
		(width 0.088646)
		(layer "In11.Cu")
		(net "M_D_CPU0_SB_DQS_DN<8>")
	)
	(arc
		(start 345.670632 -227.320602)
		(mid 345.483434 -227.270459)
		(end 345.296236 -227.320602)
		(width 0.088646)
		(layer "In11.Cu")
		(net "M_D_CPU0_SB_DQS_DN<8>")
	)
	(arc
		(start 348.019878 -229.762304)
		(mid 347.83268 -229.712161)
		(end 347.645482 -229.762304)
		(width 0.088646)
		(layer "In11.Cu")
		(net "M_D_CPU0_SB_DQS_DN<8>")
	)
	(arc
		(start 340.971632 -227.320602)
		(mid 340.784434 -227.270459)
		(end 340.597236 -227.320602)
		(width 0.088646)
		(layer "In11.Cu")
		(net "M_D_CPU0_SB_DQS_DN<8>")
	)
	(arc
		(start 335.332578 -225.69297)
		(mid 335.14538 -225.642827)
		(end 334.958182 -225.69297)
		(width 0.088646)
		(layer "In11.Cu")
		(net "M_D_CPU0_SB_DQS_DN<8>")
	)
	(arc
		(start 339.646768 -227.326698)
		(mid 339.36859 -227.396421)
		(end 339.092032 -227.320602)
		(width 0.088646)
		(layer "In11.Cu")
		(net "M_D_CPU0_SB_DQS_DN<8>")
	)
	(arc
		(start 335.52003 -226.017328)
		(mid 335.472351 -225.834428)
		(end 335.341468 -225.69805)
		(width 0.088646)
		(layer "In11.Cu")
		(net "M_D_CPU0_SB_DQS_DN<8>")
	)
	(arc
		(start 337.777836 -227.320602)
		(mid 337.503637 -227.396437)
		(end 337.227164 -227.329238)
		(width 0.088646)
		(layer "In11.Cu")
		(net "M_D_CPU0_SB_DQS_DN<8>")
	)
	(arc
		(start 333.452978 -225.69297)
		(mid 333.26578 -225.642827)
		(end 333.078582 -225.69297)
		(width 0.088646)
		(layer "In11.Cu")
		(net "M_D_CPU0_SB_DQS_DN<8>")
	)
	(arc
		(start 342.851232 -227.320602)
		(mid 342.664034 -227.270459)
		(end 342.476836 -227.320602)
		(width 0.088646)
		(layer "In11.Cu")
		(net "M_D_CPU0_SB_DQS_DN<8>")
	)
	(arc
		(start 335.98993 -226.822508)
		(mid 335.93766 -226.640143)
		(end 335.802732 -226.506786)
		(width 0.088646)
		(layer "In11.Cu")
		(net "M_D_CPU0_SB_DQS_DN<8>")
	)
	(arc
		(start 344.730832 -227.320602)
		(mid 344.543634 -227.270459)
		(end 344.356436 -227.320602)
		(width 0.088646)
		(layer "In11.Cu")
		(net "M_D_CPU0_SB_DQS_DN<8>")
	)
	(arc
		(start 336.838036 -227.320602)
		(mid 336.563837 -227.396437)
		(end 336.287364 -227.329238)
		(width 0.088646)
		(layer "In11.Cu")
		(net "M_D_CPU0_SB_DQS_DN<8>")
	)
	(arc
		(start 345.65844 -228.941376)
		(mid 345.460212 -228.735528)
		(end 345.38793 -228.45903)
		(width 0.088646)
		(layer "In11.Cu")
		(net "M_D_CPU0_SB_DQS_DN<8>")
	)
	(arc
		(start 346.140278 -229.762304)
		(mid 345.937455 -229.562073)
		(end 345.858084 -229.28834)
		(width 0.088646)
		(layer "In11.Cu")
		(net "M_D_CPU0_SB_DQS_DN<8>")
	)
	(arc
		(start 334.008222 -225.699066)
		(mid 333.72979 -225.76888)
		(end 333.452978 -225.69297)
		(width 0.088646)
		(layer "In11.Cu")
		(net "M_D_CPU0_SB_DQS_DN<8>")
	)
	(segment
		(start 266.972796 -208.95564)
		(end 266.269216 -208.95564)
		(width 0.20066)
		(layer "F.Cu")
		(net "M_D_CPU0_SB_DQS_DN<7>")
	)
	(segment
		(start 267.233908 -209.216752)
		(end 266.972796 -208.95564)
		(width 0.20066)
		(layer "F.Cu")
		(net "M_D_CPU0_SB_DQS_DN<7>")
	)
	(segment
		(start 260.913372 -208.95564)
		(end 260.65226 -209.216752)
		(width 0.20066)
		(layer "F.Cu")
		(net "M_D_CPU0_SB_DQS_DN<7>")
	)
	(segment
		(start 260.65226 -209.216752)
		(end 260.180582 -209.216752)
		(width 0.20066)
		(layer "F.Cu")
		(net "M_D_CPU0_SB_DQS_DN<7>")
	)
	(segment
		(start 268.829282 -209.216752)
		(end 267.724382 -209.216752)
		(width 0.20066)
		(layer "F.Cu")
		(net "M_D_CPU0_SB_DQS_DN<7>")
	)
	(segment
		(start 262.315198 -208.799684)
		(end 262.048752 -208.533238)
		(width 0.20066)
		(layer "F.Cu")
		(net "M_D_CPU0_SB_DQS_DN<7>")
	)
	(segment
		(start 344.54338 -233.064304)
		(end 344.543634 -233.06405)
		(width 0.20066)
		(layer "F.Cu")
		(net "M_D_CPU0_SB_DQS_DN<7>")
	)
	(segment
		(start 264.967466 -208.79181)
		(end 264.825226 -208.79181)
		(width 0.20066)
		(layer "F.Cu")
		(net "M_D_CPU0_SB_DQS_DN<7>")
	)
	(segment
		(start 261.808976 -208.533238)
		(end 261.386574 -208.95564)
		(width 0.20066)
		(layer "F.Cu")
		(net "M_D_CPU0_SB_DQS_DN<7>")
	)
	(segment
		(start 267.724382 -209.216752)
		(end 267.233908 -209.216752)
		(width 0.20066)
		(layer "F.Cu")
		(net "M_D_CPU0_SB_DQS_DN<7>")
	)
	(segment
		(start 264.825226 -208.79181)
		(end 262.74776 -208.79181)
		(width 0.1016)
		(layer "F.Cu")
		(net "M_D_CPU0_SB_DQS_DN<7>")
	)
	(segment
		(start 344.543634 -233.06405)
		(end 344.543634 -232.528364)
		(width 0.20066)
		(layer "F.Cu")
		(net "M_D_CPU0_SB_DQS_DN<7>")
	)
	(segment
		(start 262.74776 -208.79181)
		(end 262.507984 -208.79181)
		(width 0.101854)
		(layer "F.Cu")
		(net "M_D_CPU0_SB_DQS_DN<7>")
	)
	(segment
		(start 265.228578 -208.530698)
		(end 264.967466 -208.79181)
		(width 0.20066)
		(layer "F.Cu")
		(net "M_D_CPU0_SB_DQS_DN<7>")
	)
	(segment
		(start 265.6332 -208.530698)
		(end 265.228578 -208.530698)
		(width 0.20066)
		(layer "F.Cu")
		(net "M_D_CPU0_SB_DQS_DN<7>")
	)
	(segment
		(start 262.50011 -208.799684)
		(end 262.315198 -208.799684)
		(width 0.20066)
		(layer "F.Cu")
		(net "M_D_CPU0_SB_DQS_DN<7>")
	)
	(segment
		(start 261.386574 -208.95564)
		(end 260.913372 -208.95564)
		(width 0.20066)
		(layer "F.Cu")
		(net "M_D_CPU0_SB_DQS_DN<7>")
	)
	(segment
		(start 262.048752 -208.533238)
		(end 261.808976 -208.533238)
		(width 0.20066)
		(layer "F.Cu")
		(net "M_D_CPU0_SB_DQS_DN<7>")
	)
	(segment
		(start 262.507984 -208.79181)
		(end 262.50011 -208.799684)
		(width 0.101854)
		(layer "F.Cu")
		(net "M_D_CPU0_SB_DQS_DN<7>")
	)
	(segment
		(start 266.269216 -208.95564)
		(end 265.6332 -208.530698)
		(width 0.20066)
		(layer "F.Cu")
		(net "M_D_CPU0_SB_DQS_DN<7>")
	)
	(segment
		(start 279.329134 -208.501996)
		(end 278.897588 -208.501996)
		(width 0.18288)
		(layer "In6.Cu")
		(net "M_D_CPU0_SB_DQS_DN<7>")
	)
	(segment
		(start 331.344016 -229.061264)
		(end 330.880466 -228.597714)
		(width 0.088646)
		(layer "In6.Cu")
		(net "M_D_CPU0_SB_DQS_DN<7>")
	)
	(segment
		(start 288.492692 -208.358232)
		(end 287.7947 -207.66024)
		(width 0.18288)
		(layer "In6.Cu")
		(net "M_D_CPU0_SB_DQS_DN<7>")
	)
	(segment
		(start 332.32598 -230.525574)
		(end 332.17485 -230.525574)
		(width 0.088646)
		(layer "In6.Cu")
		(net "M_D_CPU0_SB_DQS_DN<7>")
	)
	(segment
		(start 309.343298 -210.343496)
		(end 309.218838 -210.467956)
		(width 0.18288)
		(layer "In6.Cu")
		(net "M_D_CPU0_SB_DQS_DN<7>")
	)
	(segment
		(start 305.249072 -209.760566)
		(end 305.124612 -209.636106)
		(width 0.18288)
		(layer "In6.Cu")
		(net "M_D_CPU0_SB_DQS_DN<7>")
	)
	(segment
		(start 310.665114 -210.343496)
		(end 309.343298 -210.343496)
		(width 0.18288)
		(layer "In6.Cu")
		(net "M_D_CPU0_SB_DQS_DN<7>")
	)
	(segment
		(start 283.718762 -207.941672)
		(end 283.429202 -207.652112)
		(width 0.18288)
		(layer "In6.Cu")
		(net "M_D_CPU0_SB_DQS_DN<7>")
	)
	(segment
		(start 269.56004 -208.942686)
		(end 269.103348 -208.942686)
		(width 0.18288)
		(layer "In6.Cu")
		(net "M_D_CPU0_SB_DQS_DN<7>")
	)
	(segment
		(start 339.102446 -232.210102)
		(end 339.092032 -232.204006)
		(width 0.088646)
		(layer "In6.Cu")
		(net "M_D_CPU0_SB_DQS_DN<7>")
	)
	(segment
		(start 305.124612 -209.636106)
		(end 302.454564 -209.636106)
		(width 0.18288)
		(layer "In6.Cu")
		(net "M_D_CPU0_SB_DQS_DN<7>")
	)
	(segment
		(start 330.655168 -228.597714)
		(end 330.595478 -228.657404)
		(width 0.088646)
		(layer "In6.Cu")
		(net "M_D_CPU0_SB_DQS_DN<7>")
	)
	(segment
		(start 336.367882 -231.39019)
		(end 336.357468 -231.396286)
		(width 0.088646)
		(layer "In6.Cu")
		(net "M_D_CPU0_SB_DQS_DN<7>")
	)
	(segment
		(start 311.867042 -211.04733)
		(end 311.368948 -211.04733)
		(width 0.18288)
		(layer "In6.Cu")
		(net "M_D_CPU0_SB_DQS_DN<7>")
	)
	(segment
		(start 297.363388 -208.51114)
		(end 295.401746 -208.51114)
		(width 0.18288)
		(layer "In6.Cu")
		(net "M_D_CPU0_SB_DQS_DN<7>")
	)
	(segment
		(start 276.783546 -208.8642)
		(end 276.271736 -208.35239)
		(width 0.18288)
		(layer "In6.Cu")
		(net "M_D_CPU0_SB_DQS_DN<7>")
	)
	(segment
		(start 293.795958 -208.501996)
		(end 293.232332 -207.93837)
		(width 0.18288)
		(layer "In6.Cu")
		(net "M_D_CPU0_SB_DQS_DN<7>")
	)
	(segment
		(start 287.7947 -207.66024)
		(end 284.41523 -207.66024)
		(width 0.18288)
		(layer "In6.Cu")
		(net "M_D_CPU0_SB_DQS_DN<7>")
	)
	(segment
		(start 333.078836 -230.576374)
		(end 333.068422 -230.58247)
		(width 0.088646)
		(layer "In6.Cu")
		(net "M_D_CPU0_SB_DQS_DN<7>")
	)
	(segment
		(start 314.105544 -214.516716)
		(end 313.44616 -213.857586)
		(width 0.18288)
		(layer "In6.Cu")
		(net "M_D_CPU0_SB_DQS_DN<7>")
	)
	(segment
		(start 340.041992 -232.210102)
		(end 340.031578 -232.204006)
		(width 0.088646)
		(layer "In6.Cu")
		(net "M_D_CPU0_SB_DQS_DN<7>")
	)
	(segment
		(start 337.307682 -231.39019)
		(end 337.29295 -231.398826)
		(width 0.088646)
		(layer "In6.Cu")
		(net "M_D_CPU0_SB_DQS_DN<7>")
	)
	(segment
		(start 302.454564 -209.636106)
		(end 300.480476 -207.662018)
		(width 0.18288)
		(layer "In6.Cu")
		(net "M_D_CPU0_SB_DQS_DN<7>")
	)
	(segment
		(start 282.707588 -207.652112)
		(end 281.86126 -208.49844)
		(width 0.18288)
		(layer "In6.Cu")
		(net "M_D_CPU0_SB_DQS_DN<7>")
	)
	(segment
		(start 299.221398 -207.941672)
		(end 298.797472 -207.941672)
		(width 0.18288)
		(layer "In6.Cu")
		(net "M_D_CPU0_SB_DQS_DN<7>")
	)
	(segment
		(start 279.618694 -208.791556)
		(end 279.329134 -208.501996)
		(width 0.18288)
		(layer "In6.Cu")
		(net "M_D_CPU0_SB_DQS_DN<7>")
	)
	(segment
		(start 272.730976 -209.127344)
		(end 269.744698 -209.127344)
		(width 0.18288)
		(layer "In6.Cu")
		(net "M_D_CPU0_SB_DQS_DN<7>")
	)
	(segment
		(start 295.401746 -208.51114)
		(end 295.12133 -208.791556)
		(width 0.18288)
		(layer "In6.Cu")
		(net "M_D_CPU0_SB_DQS_DN<7>")
	)
	(segment
		(start 311.368948 -211.04733)
		(end 310.665114 -210.343496)
		(width 0.18288)
		(layer "In6.Cu")
		(net "M_D_CPU0_SB_DQS_DN<7>")
	)
	(segment
		(start 313.44616 -213.857586)
		(end 312.575194 -211.755736)
		(width 0.18288)
		(layer "In6.Cu")
		(net "M_D_CPU0_SB_DQS_DN<7>")
	)
	(segment
		(start 340.986364 -232.212642)
		(end 340.971632 -232.204006)
		(width 0.088646)
		(layer "In6.Cu")
		(net "M_D_CPU0_SB_DQS_DN<7>")
	)
	(segment
		(start 344.856562 -232.528364)
		(end 344.913712 -232.471214)
		(width 0.088646)
		(layer "In6.Cu")
		(net "M_D_CPU0_SB_DQS_DN<7>")
	)
	(segment
		(start 342.865964 -232.212642)
		(end 342.851232 -232.204006)
		(width 0.088646)
		(layer "In6.Cu")
		(net "M_D_CPU0_SB_DQS_DN<7>")
	)
	(segment
		(start 269.103348 -208.942686)
		(end 268.829282 -209.216752)
		(width 0.18288)
		(layer "In6.Cu")
		(net "M_D_CPU0_SB_DQS_DN<7>")
	)
	(segment
		(start 294.416734 -208.501996)
		(end 293.795958 -208.501996)
		(width 0.18288)
		(layer "In6.Cu")
		(net "M_D_CPU0_SB_DQS_DN<7>")
	)
	(segment
		(start 307.048916 -209.636106)
		(end 305.922172 -209.636106)
		(width 0.18288)
		(layer "In6.Cu")
		(net "M_D_CPU0_SB_DQS_DN<7>")
	)
	(segment
		(start 299.501052 -207.662018)
		(end 299.221398 -207.941672)
		(width 0.18288)
		(layer "In6.Cu")
		(net "M_D_CPU0_SB_DQS_DN<7>")
	)
	(segment
		(start 298.797472 -207.941672)
		(end 298.520104 -207.664304)
		(width 0.18288)
		(layer "In6.Cu")
		(net "M_D_CPU0_SB_DQS_DN<7>")
	)
	(segment
		(start 330.595478 -228.657404)
		(end 330.57211 -228.657404)
		(width 0.088646)
		(layer "In6.Cu")
		(net "M_D_CPU0_SB_DQS_DN<7>")
	)
	(segment
		(start 314.51423 -214.516716)
		(end 314.105544 -214.516716)
		(width 0.18288)
		(layer "In6.Cu")
		(net "M_D_CPU0_SB_DQS_DN<7>")
	)
	(segment
		(start 269.744698 -209.127344)
		(end 269.56004 -208.942686)
		(width 0.18288)
		(layer "In6.Cu")
		(net "M_D_CPU0_SB_DQS_DN<7>")
	)
	(segment
		(start 280.03373 -208.791556)
		(end 279.618694 -208.791556)
		(width 0.18288)
		(layer "In6.Cu")
		(net "M_D_CPU0_SB_DQS_DN<7>")
	)
	(segment
		(start 305.797712 -209.760566)
		(end 305.249072 -209.760566)
		(width 0.18288)
		(layer "In6.Cu")
		(net "M_D_CPU0_SB_DQS_DN<7>")
	)
	(segment
		(start 281.86126 -208.49844)
		(end 280.326846 -208.49844)
		(width 0.18288)
		(layer "In6.Cu")
		(net "M_D_CPU0_SB_DQS_DN<7>")
	)
	(segment
		(start 305.922172 -209.636106)
		(end 305.797712 -209.760566)
		(width 0.18288)
		(layer "In6.Cu")
		(net "M_D_CPU0_SB_DQS_DN<7>")
	)
	(segment
		(start 284.133798 -207.941672)
		(end 283.718762 -207.941672)
		(width 0.18288)
		(layer "In6.Cu")
		(net "M_D_CPU0_SB_DQS_DN<7>")
	)
	(segment
		(start 283.429202 -207.652112)
		(end 282.707588 -207.652112)
		(width 0.18288)
		(layer "In6.Cu")
		(net "M_D_CPU0_SB_DQS_DN<7>")
	)
	(segment
		(start 273.50593 -208.35239)
		(end 272.730976 -209.127344)
		(width 0.18288)
		(layer "In6.Cu")
		(net "M_D_CPU0_SB_DQS_DN<7>")
	)
	(segment
		(start 332.17485 -230.525574)
		(end 331.344016 -229.69474)
		(width 0.088646)
		(layer "In6.Cu")
		(net "M_D_CPU0_SB_DQS_DN<7>")
	)
	(segment
		(start 284.41523 -207.66024)
		(end 284.133798 -207.941672)
		(width 0.18288)
		(layer "In6.Cu")
		(net "M_D_CPU0_SB_DQS_DN<7>")
	)
	(segment
		(start 295.12133 -208.791556)
		(end 294.706294 -208.791556)
		(width 0.18288)
		(layer "In6.Cu")
		(net "M_D_CPU0_SB_DQS_DN<7>")
	)
	(segment
		(start 343.805764 -232.212642)
		(end 343.791032 -232.204006)
		(width 0.088646)
		(layer "In6.Cu")
		(net "M_D_CPU0_SB_DQS_DN<7>")
	)
	(segment
		(start 322.561204 -225.347784)
		(end 322.561204 -222.56369)
		(width 0.18288)
		(layer "In6.Cu")
		(net "M_D_CPU0_SB_DQS_DN<7>")
	)
	(segment
		(start 308.545738 -210.343496)
		(end 307.756306 -210.343496)
		(width 0.18288)
		(layer "In6.Cu")
		(net "M_D_CPU0_SB_DQS_DN<7>")
	)
	(segment
		(start 325.870824 -228.657404)
		(end 322.561204 -225.347784)
		(width 0.18288)
		(layer "In6.Cu")
		(net "M_D_CPU0_SB_DQS_DN<7>")
	)
	(segment
		(start 298.210224 -207.664304)
		(end 297.363388 -208.51114)
		(width 0.18288)
		(layer "In6.Cu")
		(net "M_D_CPU0_SB_DQS_DN<7>")
	)
	(segment
		(start 292.392862 -207.93837)
		(end 291.973 -208.358232)
		(width 0.18288)
		(layer "In6.Cu")
		(net "M_D_CPU0_SB_DQS_DN<7>")
	)
	(segment
		(start 344.543634 -232.528364)
		(end 344.856562 -232.528364)
		(width 0.088646)
		(layer "In6.Cu")
		(net "M_D_CPU0_SB_DQS_DN<7>")
	)
	(segment
		(start 294.706294 -208.791556)
		(end 294.416734 -208.501996)
		(width 0.18288)
		(layer "In6.Cu")
		(net "M_D_CPU0_SB_DQS_DN<7>")
	)
	(segment
		(start 278.18334 -209.216244)
		(end 277.6347 -209.216244)
		(width 0.18288)
		(layer "In6.Cu")
		(net "M_D_CPU0_SB_DQS_DN<7>")
	)
	(segment
		(start 277.6347 -209.216244)
		(end 276.783546 -208.8642)
		(width 0.18288)
		(layer "In6.Cu")
		(net "M_D_CPU0_SB_DQS_DN<7>")
	)
	(segment
		(start 309.218838 -210.467956)
		(end 308.670198 -210.467956)
		(width 0.18288)
		(layer "In6.Cu")
		(net "M_D_CPU0_SB_DQS_DN<7>")
	)
	(segment
		(start 322.561204 -222.56369)
		(end 314.51423 -214.516716)
		(width 0.18288)
		(layer "In6.Cu")
		(net "M_D_CPU0_SB_DQS_DN<7>")
	)
	(segment
		(start 330.57211 -228.657404)
		(end 325.870824 -228.657404)
		(width 0.18288)
		(layer "In6.Cu")
		(net "M_D_CPU0_SB_DQS_DN<7>")
	)
	(segment
		(start 293.232332 -207.93837)
		(end 292.392862 -207.93837)
		(width 0.18288)
		(layer "In6.Cu")
		(net "M_D_CPU0_SB_DQS_DN<7>")
	)
	(segment
		(start 330.880466 -228.597714)
		(end 330.655168 -228.597714)
		(width 0.088646)
		(layer "In6.Cu")
		(net "M_D_CPU0_SB_DQS_DN<7>")
	)
	(segment
		(start 300.480476 -207.662018)
		(end 299.501052 -207.662018)
		(width 0.18288)
		(layer "In6.Cu")
		(net "M_D_CPU0_SB_DQS_DN<7>")
	)
	(segment
		(start 291.973 -208.358232)
		(end 288.492692 -208.358232)
		(width 0.18288)
		(layer "In6.Cu")
		(net "M_D_CPU0_SB_DQS_DN<7>")
	)
	(segment
		(start 312.575194 -211.755736)
		(end 311.867042 -211.04733)
		(width 0.18288)
		(layer "In6.Cu")
		(net "M_D_CPU0_SB_DQS_DN<7>")
	)
	(segment
		(start 278.897588 -208.501996)
		(end 278.18334 -209.216244)
		(width 0.18288)
		(layer "In6.Cu")
		(net "M_D_CPU0_SB_DQS_DN<7>")
	)
	(segment
		(start 308.670198 -210.467956)
		(end 308.545738 -210.343496)
		(width 0.18288)
		(layer "In6.Cu")
		(net "M_D_CPU0_SB_DQS_DN<7>")
	)
	(segment
		(start 331.344016 -229.69474)
		(end 331.344016 -229.061264)
		(width 0.088646)
		(layer "In6.Cu")
		(net "M_D_CPU0_SB_DQS_DN<7>")
	)
	(segment
		(start 333.640684 -230.910638)
		(end 333.640684 -230.900732)
		(width 0.088646)
		(layer "In6.Cu")
		(net "M_D_CPU0_SB_DQS_DN<7>")
	)
	(segment
		(start 276.271736 -208.35239)
		(end 273.50593 -208.35239)
		(width 0.18288)
		(layer "In6.Cu")
		(net "M_D_CPU0_SB_DQS_DN<7>")
	)
	(segment
		(start 307.756306 -210.343496)
		(end 307.048916 -209.636106)
		(width 0.18288)
		(layer "In6.Cu")
		(net "M_D_CPU0_SB_DQS_DN<7>")
	)
	(segment
		(start 280.326846 -208.49844)
		(end 280.03373 -208.791556)
		(width 0.18288)
		(layer "In6.Cu")
		(net "M_D_CPU0_SB_DQS_DN<7>")
	)
	(segment
		(start 298.520104 -207.664304)
		(end 298.210224 -207.664304)
		(width 0.18288)
		(layer "In6.Cu")
		(net "M_D_CPU0_SB_DQS_DN<7>")
	)
	(arc
		(start 340.971632 -232.204006)
		(mid 340.784434 -232.153863)
		(end 340.597236 -232.204006)
		(width 0.088646)
		(layer "In6.Cu")
		(net "M_D_CPU0_SB_DQS_DN<7>")
	)
	(arc
		(start 337.29295 -231.398826)
		(mid 337.016509 -231.465992)
		(end 336.742278 -231.39019)
		(width 0.088646)
		(layer "In6.Cu")
		(net "M_D_CPU0_SB_DQS_DN<7>")
	)
	(arc
		(start 339.092032 -232.204006)
		(mid 338.904834 -232.153863)
		(end 338.717636 -232.204006)
		(width 0.088646)
		(layer "In6.Cu")
		(net "M_D_CPU0_SB_DQS_DN<7>")
	)
	(arc
		(start 332.513178 -230.576374)
		(mid 332.422922 -230.538652)
		(end 332.32598 -230.525574)
		(width 0.088646)
		(layer "In6.Cu")
		(net "M_D_CPU0_SB_DQS_DN<7>")
	)
	(arc
		(start 343.416636 -232.204006)
		(mid 343.142437 -232.279841)
		(end 342.865964 -232.212642)
		(width 0.088646)
		(layer "In6.Cu")
		(net "M_D_CPU0_SB_DQS_DN<7>")
	)
	(arc
		(start 341.537036 -232.204006)
		(mid 341.262837 -232.279841)
		(end 340.986364 -232.212642)
		(width 0.088646)
		(layer "In6.Cu")
		(net "M_D_CPU0_SB_DQS_DN<7>")
	)
	(arc
		(start 336.742278 -231.39019)
		(mid 336.55508 -231.340047)
		(end 336.367882 -231.39019)
		(width 0.088646)
		(layer "In6.Cu")
		(net "M_D_CPU0_SB_DQS_DN<7>")
	)
	(arc
		(start 340.597236 -232.204006)
		(mid 340.320423 -232.279876)
		(end 340.041992 -232.210102)
		(width 0.088646)
		(layer "In6.Cu")
		(net "M_D_CPU0_SB_DQS_DN<7>")
	)
	(arc
		(start 340.031578 -232.204006)
		(mid 339.84438 -232.153863)
		(end 339.657182 -232.204006)
		(width 0.088646)
		(layer "In6.Cu")
		(net "M_D_CPU0_SB_DQS_DN<7>")
	)
	(arc
		(start 335.802732 -231.39019)
		(mid 335.615534 -231.340047)
		(end 335.428336 -231.39019)
		(width 0.088646)
		(layer "In6.Cu")
		(net "M_D_CPU0_SB_DQS_DN<7>")
	)
	(arc
		(start 336.357468 -231.396286)
		(mid 336.07929 -231.465978)
		(end 335.802732 -231.39019)
		(width 0.088646)
		(layer "In6.Cu")
		(net "M_D_CPU0_SB_DQS_DN<7>")
	)
	(arc
		(start 337.869276 -231.699816)
		(mid 337.675782 -231.386669)
		(end 337.307682 -231.39019)
		(width 0.088646)
		(layer "In6.Cu")
		(net "M_D_CPU0_SB_DQS_DN<7>")
	)
	(arc
		(start 335.428336 -231.39019)
		(mid 335.145634 -231.465966)
		(end 334.862932 -231.39019)
		(width 0.088646)
		(layer "In6.Cu")
		(net "M_D_CPU0_SB_DQS_DN<7>")
	)
	(arc
		(start 341.911432 -232.204006)
		(mid 341.724234 -232.153863)
		(end 341.537036 -232.204006)
		(width 0.088646)
		(layer "In6.Cu")
		(net "M_D_CPU0_SB_DQS_DN<7>")
	)
	(arc
		(start 338.717636 -232.204006)
		(mid 338.152137 -232.204245)
		(end 337.86953 -231.714548)
		(width 0.088646)
		(layer "In6.Cu")
		(net "M_D_CPU0_SB_DQS_DN<7>")
	)
	(arc
		(start 344.356436 -232.204006)
		(mid 344.082237 -232.279841)
		(end 343.805764 -232.212642)
		(width 0.088646)
		(layer "In6.Cu")
		(net "M_D_CPU0_SB_DQS_DN<7>")
	)
	(arc
		(start 339.657182 -232.204006)
		(mid 339.380623 -232.279749)
		(end 339.102446 -232.210102)
		(width 0.088646)
		(layer "In6.Cu")
		(net "M_D_CPU0_SB_DQS_DN<7>")
	)
	(arc
		(start 342.476836 -232.204006)
		(mid 342.194134 -232.279782)
		(end 341.911432 -232.204006)
		(width 0.088646)
		(layer "In6.Cu")
		(net "M_D_CPU0_SB_DQS_DN<7>")
	)
	(arc
		(start 334.862932 -231.39019)
		(mid 334.675734 -231.340047)
		(end 334.488536 -231.39019)
		(width 0.088646)
		(layer "In6.Cu")
		(net "M_D_CPU0_SB_DQS_DN<7>")
	)
	(arc
		(start 333.640684 -230.900732)
		(mid 333.453385 -230.576291)
		(end 333.078836 -230.576374)
		(width 0.088646)
		(layer "In6.Cu")
		(net "M_D_CPU0_SB_DQS_DN<7>")
	)
	(arc
		(start 343.791032 -232.204006)
		(mid 343.603834 -232.153863)
		(end 343.416636 -232.204006)
		(width 0.088646)
		(layer "In6.Cu")
		(net "M_D_CPU0_SB_DQS_DN<7>")
	)
	(arc
		(start 344.913712 -232.471214)
		(mid 344.705564 -232.19051)
		(end 344.356436 -232.204006)
		(width 0.088646)
		(layer "In6.Cu")
		(net "M_D_CPU0_SB_DQS_DN<7>")
	)
	(arc
		(start 337.86953 -231.714548)
		(mid 337.869478 -231.707181)
		(end 337.869276 -231.699816)
		(width 0.088646)
		(layer "In6.Cu")
		(net "M_D_CPU0_SB_DQS_DN<7>")
	)
	(arc
		(start 333.068422 -230.58247)
		(mid 332.78999 -230.652316)
		(end 332.513178 -230.576374)
		(width 0.088646)
		(layer "In6.Cu")
		(net "M_D_CPU0_SB_DQS_DN<7>")
	)
	(arc
		(start 334.488536 -231.39019)
		(mid 333.92756 -231.392721)
		(end 333.640684 -230.910638)
		(width 0.088646)
		(layer "In6.Cu")
		(net "M_D_CPU0_SB_DQS_DN<7>")
	)
	(arc
		(start 342.851232 -232.204006)
		(mid 342.664034 -232.153863)
		(end 342.476836 -232.204006)
		(width 0.088646)
		(layer "In6.Cu")
		(net "M_D_CPU0_SB_DQS_DN<7>")
	)
	(segment
		(start 266.269216 -218.305634)
		(end 265.6332 -217.880692)
		(width 0.20066)
		(layer "F.Cu")
		(net "M_D_CPU0_SB_DQS_DN<6>")
	)
	(segment
		(start 268.829282 -218.566746)
		(end 267.724382 -218.566746)
		(width 0.20066)
		(layer "F.Cu")
		(net "M_D_CPU0_SB_DQS_DN<6>")
	)
	(segment
		(start 266.972796 -218.305634)
		(end 266.269216 -218.305634)
		(width 0.20066)
		(layer "F.Cu")
		(net "M_D_CPU0_SB_DQS_DN<6>")
	)
	(segment
		(start 261.808976 -217.883232)
		(end 261.386574 -218.305634)
		(width 0.20066)
		(layer "F.Cu")
		(net "M_D_CPU0_SB_DQS_DN<6>")
	)
	(segment
		(start 265.228578 -217.880692)
		(end 264.967466 -218.141804)
		(width 0.20066)
		(layer "F.Cu")
		(net "M_D_CPU0_SB_DQS_DN<6>")
	)
	(segment
		(start 267.233908 -218.566746)
		(end 266.972796 -218.305634)
		(width 0.20066)
		(layer "F.Cu")
		(net "M_D_CPU0_SB_DQS_DN<6>")
	)
	(segment
		(start 262.315198 -218.149678)
		(end 262.048752 -217.883232)
		(width 0.20066)
		(layer "F.Cu")
		(net "M_D_CPU0_SB_DQS_DN<6>")
	)
	(segment
		(start 267.724382 -218.566746)
		(end 267.233908 -218.566746)
		(width 0.20066)
		(layer "F.Cu")
		(net "M_D_CPU0_SB_DQS_DN<6>")
	)
	(segment
		(start 347.832934 -234.97032)
		(end 347.83268 -234.970066)
		(width 0.20066)
		(layer "F.Cu")
		(net "M_D_CPU0_SB_DQS_DN<6>")
	)
	(segment
		(start 260.65226 -218.566746)
		(end 260.180582 -218.566746)
		(width 0.20066)
		(layer "F.Cu")
		(net "M_D_CPU0_SB_DQS_DN<6>")
	)
	(segment
		(start 262.507984 -218.141804)
		(end 262.50011 -218.149678)
		(width 0.101854)
		(layer "F.Cu")
		(net "M_D_CPU0_SB_DQS_DN<6>")
	)
	(segment
		(start 262.74776 -218.141804)
		(end 262.507984 -218.141804)
		(width 0.101854)
		(layer "F.Cu")
		(net "M_D_CPU0_SB_DQS_DN<6>")
	)
	(segment
		(start 264.825226 -218.141804)
		(end 262.74776 -218.141804)
		(width 0.1016)
		(layer "F.Cu")
		(net "M_D_CPU0_SB_DQS_DN<6>")
	)
	(segment
		(start 347.832934 -235.506006)
		(end 347.832934 -234.97032)
		(width 0.20066)
		(layer "F.Cu")
		(net "M_D_CPU0_SB_DQS_DN<6>")
	)
	(segment
		(start 260.913372 -218.305634)
		(end 260.65226 -218.566746)
		(width 0.20066)
		(layer "F.Cu")
		(net "M_D_CPU0_SB_DQS_DN<6>")
	)
	(segment
		(start 262.50011 -218.149678)
		(end 262.315198 -218.149678)
		(width 0.20066)
		(layer "F.Cu")
		(net "M_D_CPU0_SB_DQS_DN<6>")
	)
	(segment
		(start 262.048752 -217.883232)
		(end 261.808976 -217.883232)
		(width 0.20066)
		(layer "F.Cu")
		(net "M_D_CPU0_SB_DQS_DN<6>")
	)
	(segment
		(start 265.6332 -217.880692)
		(end 265.228578 -217.880692)
		(width 0.20066)
		(layer "F.Cu")
		(net "M_D_CPU0_SB_DQS_DN<6>")
	)
	(segment
		(start 264.967466 -218.141804)
		(end 264.825226 -218.141804)
		(width 0.20066)
		(layer "F.Cu")
		(net "M_D_CPU0_SB_DQS_DN<6>")
	)
	(segment
		(start 261.386574 -218.305634)
		(end 260.913372 -218.305634)
		(width 0.20066)
		(layer "F.Cu")
		(net "M_D_CPU0_SB_DQS_DN<6>")
	)
	(segment
		(start 330.336906 -230.55326)
		(end 328.457306 -230.55326)
		(width 0.18288)
		(layer "In11.Cu")
		(net "M_D_CPU0_SB_DQS_DN<6>")
	)
	(segment
		(start 309.867046 -213.748874)
		(end 309.273702 -213.15553)
		(width 0.18288)
		(layer "In11.Cu")
		(net "M_D_CPU0_SB_DQS_DN<6>")
	)
	(segment
		(start 301.041562 -210.321144)
		(end 300.917102 -210.196684)
		(width 0.18288)
		(layer "In11.Cu")
		(net "M_D_CPU0_SB_DQS_DN<6>")
	)
	(segment
		(start 310.61152 -214.05723)
		(end 309.867046 -213.748874)
		(width 0.18288)
		(layer "In11.Cu")
		(net "M_D_CPU0_SB_DQS_DN<6>")
	)
	(segment
		(start 297.155362 -211.084668)
		(end 295.369234 -211.084668)
		(width 0.18288)
		(layer "In11.Cu")
		(net "M_D_CPU0_SB_DQS_DN<6>")
	)
	(segment
		(start 301.590202 -210.321144)
		(end 301.041562 -210.321144)
		(width 0.18288)
		(layer "In11.Cu")
		(net "M_D_CPU0_SB_DQS_DN<6>")
	)
	(segment
		(start 331.797152 -232.153206)
		(end 331.383386 -231.73944)
		(width 0.088646)
		(layer "In11.Cu")
		(net "M_D_CPU0_SB_DQS_DN<6>")
	)
	(segment
		(start 292.113716 -211.700872)
		(end 291.549836 -211.136992)
		(width 0.18288)
		(layer "In11.Cu")
		(net "M_D_CPU0_SB_DQS_DN<6>")
	)
	(segment
		(start 301.714662 -210.196684)
		(end 301.590202 -210.321144)
		(width 0.18288)
		(layer "In11.Cu")
		(net "M_D_CPU0_SB_DQS_DN<6>")
	)
	(segment
		(start 331.383386 -231.24033)
		(end 330.636372 -230.493316)
		(width 0.088646)
		(layer "In11.Cu")
		(net "M_D_CPU0_SB_DQS_DN<6>")
	)
	(segment
		(start 336.287364 -232.212642)
		(end 336.27949 -232.20807)
		(width 0.088646)
		(layer "In11.Cu")
		(net "M_D_CPU0_SB_DQS_DN<6>")
	)
	(segment
		(start 276.083522 -211.124292)
		(end 274.709636 -212.498178)
		(width 0.18288)
		(layer "In11.Cu")
		(net "M_D_CPU0_SB_DQS_DN<6>")
	)
	(segment
		(start 269.697962 -218.519756)
		(end 269.472918 -218.294712)
		(width 0.18288)
		(layer "In11.Cu")
		(net "M_D_CPU0_SB_DQS_DN<6>")
	)
	(segment
		(start 289.092132 -211.136992)
		(end 286.93618 -210.243674)
		(width 0.18288)
		(layer "In11.Cu")
		(net "M_D_CPU0_SB_DQS_DN<6>")
	)
	(segment
		(start 316.978538 -219.074746)
		(end 315.76391 -216.140792)
		(width 0.18288)
		(layer "In11.Cu")
		(net "M_D_CPU0_SB_DQS_DN<6>")
	)
	(segment
		(start 348.145608 -234.970066)
		(end 348.202758 -234.912916)
		(width 0.088646)
		(layer "In11.Cu")
		(net "M_D_CPU0_SB_DQS_DN<6>")
	)
	(segment
		(start 341.450168 -233.022902)
		(end 341.441278 -233.017822)
		(width 0.088646)
		(layer "In11.Cu")
		(net "M_D_CPU0_SB_DQS_DN<6>")
	)
	(segment
		(start 346.705682 -234.645708)
		(end 346.69095 -234.654344)
		(width 0.088646)
		(layer "In11.Cu")
		(net "M_D_CPU0_SB_DQS_DN<6>")
	)
	(segment
		(start 313.326272 -214.712042)
		(end 312.777632 -214.712042)
		(width 0.18288)
		(layer "In11.Cu")
		(net "M_D_CPU0_SB_DQS_DN<6>")
	)
	(segment
		(start 336.275172 -232.20553)
		(end 336.273648 -232.204514)
		(width 0.088646)
		(layer "In11.Cu")
		(net "M_D_CPU0_SB_DQS_DN<6>")
	)
	(segment
		(start 278.153368 -210.469734)
		(end 277.19782 -210.469734)
		(width 0.18288)
		(layer "In11.Cu")
		(net "M_D_CPU0_SB_DQS_DN<6>")
	)
	(segment
		(start 338.166964 -232.212642)
		(end 338.152232 -232.204006)
		(width 0.088646)
		(layer "In11.Cu")
		(net "M_D_CPU0_SB_DQS_DN<6>")
	)
	(segment
		(start 347.83268 -234.970066)
		(end 348.145608 -234.970066)
		(width 0.088646)
		(layer "In11.Cu")
		(net "M_D_CPU0_SB_DQS_DN<6>")
	)
	(segment
		(start 291.549836 -211.136992)
		(end 289.092132 -211.136992)
		(width 0.18288)
		(layer "In11.Cu")
		(net "M_D_CPU0_SB_DQS_DN<6>")
	)
	(segment
		(start 330.39685 -230.493316)
		(end 330.336906 -230.55326)
		(width 0.088646)
		(layer "In11.Cu")
		(net "M_D_CPU0_SB_DQS_DN<6>")
	)
	(segment
		(start 332.32598 -232.153206)
		(end 331.797152 -232.153206)
		(width 0.088646)
		(layer "In11.Cu")
		(net "M_D_CPU0_SB_DQS_DN<6>")
	)
	(segment
		(start 300.917102 -210.196684)
		(end 299.494702 -210.196684)
		(width 0.18288)
		(layer "In11.Cu")
		(net "M_D_CPU0_SB_DQS_DN<6>")
	)
	(segment
		(start 293.128192 -211.700872)
		(end 292.113716 -211.700872)
		(width 0.18288)
		(layer "In11.Cu")
		(net "M_D_CPU0_SB_DQS_DN<6>")
	)
	(segment
		(start 273.402806 -216.38768)
		(end 273.037554 -216.752932)
		(width 0.18288)
		(layer "In11.Cu")
		(net "M_D_CPU0_SB_DQS_DN<6>")
	)
	(segment
		(start 336.277204 -232.206546)
		(end 336.275172 -232.20553)
		(width 0.088646)
		(layer "In11.Cu")
		(net "M_D_CPU0_SB_DQS_DN<6>")
	)
	(segment
		(start 295.369234 -211.084668)
		(end 295.112948 -211.340954)
		(width 0.18288)
		(layer "In11.Cu")
		(net "M_D_CPU0_SB_DQS_DN<6>")
	)
	(segment
		(start 294.37838 -211.094574)
		(end 293.73449 -211.094574)
		(width 0.18288)
		(layer "In11.Cu")
		(net "M_D_CPU0_SB_DQS_DN<6>")
	)
	(segment
		(start 277.19782 -210.469734)
		(end 276.543262 -211.124292)
		(width 0.18288)
		(layer "In11.Cu")
		(net "M_D_CPU0_SB_DQS_DN<6>")
	)
	(segment
		(start 311.185814 -214.430102)
		(end 310.67883 -214.220044)
		(width 0.18288)
		(layer "In11.Cu")
		(net "M_D_CPU0_SB_DQS_DN<6>")
	)
	(segment
		(start 313.450732 -214.587582)
		(end 313.326272 -214.712042)
		(width 0.18288)
		(layer "In11.Cu")
		(net "M_D_CPU0_SB_DQS_DN<6>")
	)
	(segment
		(start 342.09863 -234.166156)
		(end 342.09863 -234.147614)
		(width 0.088646)
		(layer "In11.Cu")
		(net "M_D_CPU0_SB_DQS_DN<6>")
	)
	(segment
		(start 339.102446 -232.210102)
		(end 339.092032 -232.204006)
		(width 0.088646)
		(layer "In11.Cu")
		(net "M_D_CPU0_SB_DQS_DN<6>")
	)
	(segment
		(start 311.891172 -214.587582)
		(end 311.348628 -214.362792)
		(width 0.18288)
		(layer "In11.Cu")
		(net "M_D_CPU0_SB_DQS_DN<6>")
	)
	(segment
		(start 270.85798 -218.300808)
		(end 270.328644 -218.519756)
		(width 0.18288)
		(layer "In11.Cu")
		(net "M_D_CPU0_SB_DQS_DN<6>")
	)
	(segment
		(start 284.131258 -210.492848)
		(end 283.626306 -210.492848)
		(width 0.18288)
		(layer "In11.Cu")
		(net "M_D_CPU0_SB_DQS_DN<6>")
	)
	(segment
		(start 307.993034 -211.874862)
		(end 306.66944 -211.326476)
		(width 0.18288)
		(layer "In11.Cu")
		(net "M_D_CPU0_SB_DQS_DN<6>")
	)
	(segment
		(start 278.78151 -211.097876)
		(end 278.153368 -210.469734)
		(width 0.18288)
		(layer "In11.Cu")
		(net "M_D_CPU0_SB_DQS_DN<6>")
	)
	(segment
		(start 273.677634 -215.72474)
		(end 273.402806 -216.38768)
		(width 0.18288)
		(layer "In11.Cu")
		(net "M_D_CPU0_SB_DQS_DN<6>")
	)
	(segment
		(start 312.777632 -214.712042)
		(end 312.653172 -214.587582)
		(width 0.18288)
		(layer "In11.Cu")
		(net "M_D_CPU0_SB_DQS_DN<6>")
	)
	(segment
		(start 281.935936 -211.076032)
		(end 280.28773 -211.076032)
		(width 0.18288)
		(layer "In11.Cu")
		(net "M_D_CPU0_SB_DQS_DN<6>")
	)
	(segment
		(start 328.457306 -230.55326)
		(end 316.978538 -219.074746)
		(width 0.18288)
		(layer "In11.Cu")
		(net "M_D_CPU0_SB_DQS_DN<6>")
	)
	(segment
		(start 280.023062 -211.3407)
		(end 279.534366 -211.3407)
		(width 0.18288)
		(layer "In11.Cu")
		(net "M_D_CPU0_SB_DQS_DN<6>")
	)
	(segment
		(start 312.653172 -214.587582)
		(end 311.891172 -214.587582)
		(width 0.18288)
		(layer "In11.Cu")
		(net "M_D_CPU0_SB_DQS_DN<6>")
	)
	(segment
		(start 344.826336 -234.645708)
		(end 344.815922 -234.651804)
		(width 0.088646)
		(layer "In11.Cu")
		(net "M_D_CPU0_SB_DQS_DN<6>")
	)
	(segment
		(start 308.709314 -212.591142)
		(end 307.993034 -211.874862)
		(width 0.18288)
		(layer "In11.Cu")
		(net "M_D_CPU0_SB_DQS_DN<6>")
	)
	(segment
		(start 340.980522 -232.209086)
		(end 340.973156 -232.204768)
		(width 0.088646)
		(layer "In11.Cu")
		(net "M_D_CPU0_SB_DQS_DN<6>")
	)
	(segment
		(start 341.62873 -233.356404)
		(end 341.62873 -233.34218)
		(width 0.088646)
		(layer "In11.Cu")
		(net "M_D_CPU0_SB_DQS_DN<6>")
	)
	(segment
		(start 273.677634 -213.202774)
		(end 273.677634 -215.72474)
		(width 0.18288)
		(layer "In11.Cu")
		(net "M_D_CPU0_SB_DQS_DN<6>")
	)
	(segment
		(start 309.273702 -213.15553)
		(end 309.09768 -213.15553)
		(width 0.18288)
		(layer "In11.Cu")
		(net "M_D_CPU0_SB_DQS_DN<6>")
	)
	(segment
		(start 306.66944 -211.326476)
		(end 304.989992 -211.326476)
		(width 0.18288)
		(layer "In11.Cu")
		(net "M_D_CPU0_SB_DQS_DN<6>")
	)
	(segment
		(start 348.028768 -234.650788)
		(end 348.019878 -234.645708)
		(width 0.088646)
		(layer "In11.Cu")
		(net "M_D_CPU0_SB_DQS_DN<6>")
	)
	(segment
		(start 273.037554 -216.752932)
		(end 271.958816 -217.199972)
		(width 0.18288)
		(layer "In11.Cu")
		(net "M_D_CPU0_SB_DQS_DN<6>")
	)
	(segment
		(start 314.35929 -214.73668)
		(end 313.999372 -214.587582)
		(width 0.18288)
		(layer "In11.Cu")
		(net "M_D_CPU0_SB_DQS_DN<6>")
	)
	(segment
		(start 274.709636 -212.498178)
		(end 274.150582 -212.729826)
		(width 0.18288)
		(layer "In11.Cu")
		(net "M_D_CPU0_SB_DQS_DN<6>")
	)
	(segment
		(start 299.494702 -210.196684)
		(end 299.201078 -210.490308)
		(width 0.18288)
		(layer "In11.Cu")
		(net "M_D_CPU0_SB_DQS_DN<6>")
	)
	(segment
		(start 294.62476 -211.340954)
		(end 294.37838 -211.094574)
		(width 0.18288)
		(layer "In11.Cu")
		(net "M_D_CPU0_SB_DQS_DN<6>")
	)
	(segment
		(start 347.645482 -234.645708)
		(end 347.63075 -234.654344)
		(width 0.088646)
		(layer "In11.Cu")
		(net "M_D_CPU0_SB_DQS_DN<6>")
	)
	(segment
		(start 293.73449 -211.094574)
		(end 293.128192 -211.700872)
		(width 0.18288)
		(layer "In11.Cu")
		(net "M_D_CPU0_SB_DQS_DN<6>")
	)
	(segment
		(start 295.112948 -211.340954)
		(end 294.62476 -211.340954)
		(width 0.18288)
		(layer "In11.Cu")
		(net "M_D_CPU0_SB_DQS_DN<6>")
	)
	(segment
		(start 333.078582 -232.204006)
		(end 333.06385 -232.212642)
		(width 0.088646)
		(layer "In11.Cu")
		(net "M_D_CPU0_SB_DQS_DN<6>")
	)
	(segment
		(start 340.973156 -232.204768)
		(end 340.971632 -232.204006)
		(width 0.088646)
		(layer "In11.Cu")
		(net "M_D_CPU0_SB_DQS_DN<6>")
	)
	(segment
		(start 298.512484 -210.271106)
		(end 297.968924 -210.271106)
		(width 0.18288)
		(layer "In11.Cu")
		(net "M_D_CPU0_SB_DQS_DN<6>")
	)
	(segment
		(start 284.380432 -210.243674)
		(end 284.131258 -210.492848)
		(width 0.18288)
		(layer "In11.Cu")
		(net "M_D_CPU0_SB_DQS_DN<6>")
	)
	(segment
		(start 341.159084 -232.543858)
		(end 341.159084 -232.528364)
		(width 0.088646)
		(layer "In11.Cu")
		(net "M_D_CPU0_SB_DQS_DN<6>")
	)
	(segment
		(start 331.383386 -231.73944)
		(end 331.383386 -231.24033)
		(width 0.088646)
		(layer "In11.Cu")
		(net "M_D_CPU0_SB_DQS_DN<6>")
	)
	(segment
		(start 279.534366 -211.3407)
		(end 279.291542 -211.097876)
		(width 0.18288)
		(layer "In11.Cu")
		(net "M_D_CPU0_SB_DQS_DN<6>")
	)
	(segment
		(start 336.273648 -232.204514)
		(end 336.272632 -232.204006)
		(width 0.088646)
		(layer "In11.Cu")
		(net "M_D_CPU0_SB_DQS_DN<6>")
	)
	(segment
		(start 269.472918 -218.294712)
		(end 269.101316 -218.294712)
		(width 0.18288)
		(layer "In11.Cu")
		(net "M_D_CPU0_SB_DQS_DN<6>")
	)
	(segment
		(start 311.348628 -214.362792)
		(end 311.185814 -214.430102)
		(width 0.18288)
		(layer "In11.Cu")
		(net "M_D_CPU0_SB_DQS_DN<6>")
	)
	(segment
		(start 274.150582 -212.729826)
		(end 273.677634 -213.202774)
		(width 0.18288)
		(layer "In11.Cu")
		(net "M_D_CPU0_SB_DQS_DN<6>")
	)
	(segment
		(start 299.201078 -210.490308)
		(end 298.731686 -210.490308)
		(width 0.18288)
		(layer "In11.Cu")
		(net "M_D_CPU0_SB_DQS_DN<6>")
	)
	(segment
		(start 283.382466 -210.249008)
		(end 282.76296 -210.249008)
		(width 0.18288)
		(layer "In11.Cu")
		(net "M_D_CPU0_SB_DQS_DN<6>")
	)
	(segment
		(start 271.958816 -217.199972)
		(end 270.85798 -218.300808)
		(width 0.18288)
		(layer "In11.Cu")
		(net "M_D_CPU0_SB_DQS_DN<6>")
	)
	(segment
		(start 309.09768 -213.15553)
		(end 308.709314 -212.767164)
		(width 0.18288)
		(layer "In11.Cu")
		(net "M_D_CPU0_SB_DQS_DN<6>")
	)
	(segment
		(start 330.636372 -230.493316)
		(end 330.39685 -230.493316)
		(width 0.088646)
		(layer "In11.Cu")
		(net "M_D_CPU0_SB_DQS_DN<6>")
	)
	(segment
		(start 345.765882 -234.645708)
		(end 345.755468 -234.651804)
		(width 0.088646)
		(layer "In11.Cu")
		(net "M_D_CPU0_SB_DQS_DN<6>")
	)
	(segment
		(start 336.27949 -232.20807)
		(end 336.277204 -232.206546)
		(width 0.088646)
		(layer "In11.Cu")
		(net "M_D_CPU0_SB_DQS_DN<6>")
	)
	(segment
		(start 315.76391 -216.140792)
		(end 314.35929 -214.73668)
		(width 0.18288)
		(layer "In11.Cu")
		(net "M_D_CPU0_SB_DQS_DN<6>")
	)
	(segment
		(start 282.76296 -210.249008)
		(end 281.935936 -211.076032)
		(width 0.18288)
		(layer "In11.Cu")
		(net "M_D_CPU0_SB_DQS_DN<6>")
	)
	(segment
		(start 270.328644 -218.519756)
		(end 269.697962 -218.519756)
		(width 0.18288)
		(layer "In11.Cu")
		(net "M_D_CPU0_SB_DQS_DN<6>")
	)
	(segment
		(start 297.968924 -210.271106)
		(end 297.155362 -211.084668)
		(width 0.18288)
		(layer "In11.Cu")
		(net "M_D_CPU0_SB_DQS_DN<6>")
	)
	(segment
		(start 313.999372 -214.587582)
		(end 313.450732 -214.587582)
		(width 0.18288)
		(layer "In11.Cu")
		(net "M_D_CPU0_SB_DQS_DN<6>")
	)
	(segment
		(start 337.227164 -232.212642)
		(end 337.212432 -232.204006)
		(width 0.088646)
		(layer "In11.Cu")
		(net "M_D_CPU0_SB_DQS_DN<6>")
	)
	(segment
		(start 343.886282 -234.645708)
		(end 343.87155 -234.654344)
		(width 0.088646)
		(layer "In11.Cu")
		(net "M_D_CPU0_SB_DQS_DN<6>")
	)
	(segment
		(start 269.101316 -218.294712)
		(end 268.829282 -218.566746)
		(width 0.18288)
		(layer "In11.Cu")
		(net "M_D_CPU0_SB_DQS_DN<6>")
	)
	(segment
		(start 308.709314 -212.767164)
		(end 308.709314 -212.591142)
		(width 0.18288)
		(layer "In11.Cu")
		(net "M_D_CPU0_SB_DQS_DN<6>")
	)
	(segment
		(start 340.041992 -232.210102)
		(end 340.031578 -232.204006)
		(width 0.088646)
		(layer "In11.Cu")
		(net "M_D_CPU0_SB_DQS_DN<6>")
	)
	(segment
		(start 276.543262 -211.124292)
		(end 276.083522 -211.124292)
		(width 0.18288)
		(layer "In11.Cu")
		(net "M_D_CPU0_SB_DQS_DN<6>")
	)
	(segment
		(start 334.018636 -232.204006)
		(end 334.008222 -232.210102)
		(width 0.088646)
		(layer "In11.Cu")
		(net "M_D_CPU0_SB_DQS_DN<6>")
	)
	(segment
		(start 304.989992 -211.326476)
		(end 302.263302 -210.196684)
		(width 0.18288)
		(layer "In11.Cu")
		(net "M_D_CPU0_SB_DQS_DN<6>")
	)
	(segment
		(start 286.93618 -210.243674)
		(end 284.380432 -210.243674)
		(width 0.18288)
		(layer "In11.Cu")
		(net "M_D_CPU0_SB_DQS_DN<6>")
	)
	(segment
		(start 280.28773 -211.076032)
		(end 280.023062 -211.3407)
		(width 0.18288)
		(layer "In11.Cu")
		(net "M_D_CPU0_SB_DQS_DN<6>")
	)
	(segment
		(start 279.291542 -211.097876)
		(end 278.78151 -211.097876)
		(width 0.18288)
		(layer "In11.Cu")
		(net "M_D_CPU0_SB_DQS_DN<6>")
	)
	(segment
		(start 298.731686 -210.490308)
		(end 298.512484 -210.271106)
		(width 0.18288)
		(layer "In11.Cu")
		(net "M_D_CPU0_SB_DQS_DN<6>")
	)
	(segment
		(start 310.67883 -214.220044)
		(end 310.61152 -214.05723)
		(width 0.18288)
		(layer "In11.Cu")
		(net "M_D_CPU0_SB_DQS_DN<6>")
	)
	(segment
		(start 283.626306 -210.492848)
		(end 283.382466 -210.249008)
		(width 0.18288)
		(layer "In11.Cu")
		(net "M_D_CPU0_SB_DQS_DN<6>")
	)
	(segment
		(start 302.263302 -210.196684)
		(end 301.714662 -210.196684)
		(width 0.18288)
		(layer "In11.Cu")
		(net "M_D_CPU0_SB_DQS_DN<6>")
	)
	(arc
		(start 339.092032 -232.204006)
		(mid 338.904834 -232.153863)
		(end 338.717636 -232.204006)
		(width 0.088646)
		(layer "In11.Cu")
		(net "M_D_CPU0_SB_DQS_DN<6>")
	)
	(arc
		(start 338.717636 -232.204006)
		(mid 338.443437 -232.279841)
		(end 338.166964 -232.212642)
		(width 0.088646)
		(layer "In11.Cu")
		(net "M_D_CPU0_SB_DQS_DN<6>")
	)
	(arc
		(start 334.393032 -232.204006)
		(mid 334.205834 -232.153863)
		(end 334.018636 -232.204006)
		(width 0.088646)
		(layer "In11.Cu")
		(net "M_D_CPU0_SB_DQS_DN<6>")
	)
	(arc
		(start 334.008222 -232.210102)
		(mid 333.72979 -232.279948)
		(end 333.452978 -232.204006)
		(width 0.088646)
		(layer "In11.Cu")
		(net "M_D_CPU0_SB_DQS_DN<6>")
	)
	(arc
		(start 338.152232 -232.204006)
		(mid 337.965034 -232.153863)
		(end 337.777836 -232.204006)
		(width 0.088646)
		(layer "In11.Cu")
		(net "M_D_CPU0_SB_DQS_DN<6>")
	)
	(arc
		(start 335.332832 -232.204006)
		(mid 335.145634 -232.153863)
		(end 334.958436 -232.204006)
		(width 0.088646)
		(layer "In11.Cu")
		(net "M_D_CPU0_SB_DQS_DN<6>")
	)
	(arc
		(start 332.513178 -232.204006)
		(mid 332.422922 -232.166284)
		(end 332.32598 -232.153206)
		(width 0.088646)
		(layer "In11.Cu")
		(net "M_D_CPU0_SB_DQS_DN<6>")
	)
	(arc
		(start 346.140278 -234.645708)
		(mid 345.95308 -234.595565)
		(end 345.765882 -234.645708)
		(width 0.088646)
		(layer "In11.Cu")
		(net "M_D_CPU0_SB_DQS_DN<6>")
	)
	(arc
		(start 347.63075 -234.654344)
		(mid 347.354275 -234.721664)
		(end 347.080078 -234.645708)
		(width 0.088646)
		(layer "In11.Cu")
		(net "M_D_CPU0_SB_DQS_DN<6>")
	)
	(arc
		(start 336.272632 -232.204006)
		(mid 336.085434 -232.153863)
		(end 335.898236 -232.204006)
		(width 0.088646)
		(layer "In11.Cu")
		(net "M_D_CPU0_SB_DQS_DN<6>")
	)
	(arc
		(start 341.911432 -233.831892)
		(mid 341.707951 -233.631088)
		(end 341.62873 -233.356404)
		(width 0.088646)
		(layer "In11.Cu")
		(net "M_D_CPU0_SB_DQS_DN<6>")
	)
	(arc
		(start 336.838036 -232.204006)
		(mid 336.563837 -232.279841)
		(end 336.287364 -232.212642)
		(width 0.088646)
		(layer "In11.Cu")
		(net "M_D_CPU0_SB_DQS_DN<6>")
	)
	(arc
		(start 333.452978 -232.204006)
		(mid 333.26578 -232.153863)
		(end 333.078582 -232.204006)
		(width 0.088646)
		(layer "In11.Cu")
		(net "M_D_CPU0_SB_DQS_DN<6>")
	)
	(arc
		(start 345.755468 -234.651804)
		(mid 345.47729 -234.721527)
		(end 345.200732 -234.645708)
		(width 0.088646)
		(layer "In11.Cu")
		(net "M_D_CPU0_SB_DQS_DN<6>")
	)
	(arc
		(start 333.06385 -232.212642)
		(mid 332.787375 -232.279962)
		(end 332.513178 -232.204006)
		(width 0.088646)
		(layer "In11.Cu")
		(net "M_D_CPU0_SB_DQS_DN<6>")
	)
	(arc
		(start 344.260678 -234.645708)
		(mid 344.07348 -234.595565)
		(end 343.886282 -234.645708)
		(width 0.088646)
		(layer "In11.Cu")
		(net "M_D_CPU0_SB_DQS_DN<6>")
	)
	(arc
		(start 348.202758 -234.912916)
		(mid 348.144639 -234.762675)
		(end 348.028768 -234.650788)
		(width 0.088646)
		(layer "In11.Cu")
		(net "M_D_CPU0_SB_DQS_DN<6>")
	)
	(arc
		(start 339.657182 -232.204006)
		(mid 339.380623 -232.279749)
		(end 339.102446 -232.210102)
		(width 0.088646)
		(layer "In11.Cu")
		(net "M_D_CPU0_SB_DQS_DN<6>")
	)
	(arc
		(start 345.200732 -234.645708)
		(mid 345.013534 -234.595565)
		(end 344.826336 -234.645708)
		(width 0.088646)
		(layer "In11.Cu")
		(net "M_D_CPU0_SB_DQS_DN<6>")
	)
	(arc
		(start 341.159084 -232.528364)
		(mid 341.111405 -232.345464)
		(end 340.980522 -232.209086)
		(width 0.088646)
		(layer "In11.Cu")
		(net "M_D_CPU0_SB_DQS_DN<6>")
	)
	(arc
		(start 347.080078 -234.645708)
		(mid 346.89288 -234.595565)
		(end 346.705682 -234.645708)
		(width 0.088646)
		(layer "In11.Cu")
		(net "M_D_CPU0_SB_DQS_DN<6>")
	)
	(arc
		(start 342.946482 -234.645708)
		(mid 342.66378 -234.721484)
		(end 342.381078 -234.645708)
		(width 0.088646)
		(layer "In11.Cu")
		(net "M_D_CPU0_SB_DQS_DN<6>")
	)
	(arc
		(start 342.09863 -234.147614)
		(mid 342.04636 -233.965249)
		(end 341.911432 -233.831892)
		(width 0.088646)
		(layer "In11.Cu")
		(net "M_D_CPU0_SB_DQS_DN<6>")
	)
	(arc
		(start 348.019878 -234.645708)
		(mid 347.83268 -234.595565)
		(end 347.645482 -234.645708)
		(width 0.088646)
		(layer "In11.Cu")
		(net "M_D_CPU0_SB_DQS_DN<6>")
	)
	(arc
		(start 337.212432 -232.204006)
		(mid 337.025234 -232.153863)
		(end 336.838036 -232.204006)
		(width 0.088646)
		(layer "In11.Cu")
		(net "M_D_CPU0_SB_DQS_DN<6>")
	)
	(arc
		(start 343.87155 -234.654344)
		(mid 343.595075 -234.721664)
		(end 343.320878 -234.645708)
		(width 0.088646)
		(layer "In11.Cu")
		(net "M_D_CPU0_SB_DQS_DN<6>")
	)
	(arc
		(start 343.320878 -234.645708)
		(mid 343.13368 -234.595565)
		(end 342.946482 -234.645708)
		(width 0.088646)
		(layer "In11.Cu")
		(net "M_D_CPU0_SB_DQS_DN<6>")
	)
	(arc
		(start 342.381078 -234.645708)
		(mid 342.176743 -234.443103)
		(end 342.09863 -234.166156)
		(width 0.088646)
		(layer "In11.Cu")
		(net "M_D_CPU0_SB_DQS_DN<6>")
	)
	(arc
		(start 340.971632 -232.204006)
		(mid 340.784434 -232.153863)
		(end 340.597236 -232.204006)
		(width 0.088646)
		(layer "In11.Cu")
		(net "M_D_CPU0_SB_DQS_DN<6>")
	)
	(arc
		(start 337.777836 -232.204006)
		(mid 337.503637 -232.279841)
		(end 337.227164 -232.212642)
		(width 0.088646)
		(layer "In11.Cu")
		(net "M_D_CPU0_SB_DQS_DN<6>")
	)
	(arc
		(start 334.958436 -232.204006)
		(mid 334.675734 -232.279782)
		(end 334.393032 -232.204006)
		(width 0.088646)
		(layer "In11.Cu")
		(net "M_D_CPU0_SB_DQS_DN<6>")
	)
	(arc
		(start 340.031578 -232.204006)
		(mid 339.84438 -232.153863)
		(end 339.657182 -232.204006)
		(width 0.088646)
		(layer "In11.Cu")
		(net "M_D_CPU0_SB_DQS_DN<6>")
	)
	(arc
		(start 346.69095 -234.654344)
		(mid 346.414475 -234.721664)
		(end 346.140278 -234.645708)
		(width 0.088646)
		(layer "In11.Cu")
		(net "M_D_CPU0_SB_DQS_DN<6>")
	)
	(arc
		(start 341.62873 -233.34218)
		(mid 341.581051 -233.15928)
		(end 341.450168 -233.022902)
		(width 0.088646)
		(layer "In11.Cu")
		(net "M_D_CPU0_SB_DQS_DN<6>")
	)
	(arc
		(start 335.898236 -232.204006)
		(mid 335.615534 -232.279782)
		(end 335.332832 -232.204006)
		(width 0.088646)
		(layer "In11.Cu")
		(net "M_D_CPU0_SB_DQS_DN<6>")
	)
	(arc
		(start 340.597236 -232.204006)
		(mid 340.320423 -232.279876)
		(end 340.041992 -232.210102)
		(width 0.088646)
		(layer "In11.Cu")
		(net "M_D_CPU0_SB_DQS_DN<6>")
	)
	(arc
		(start 341.441278 -233.017822)
		(mid 341.238455 -232.817591)
		(end 341.159084 -232.543858)
		(width 0.088646)
		(layer "In11.Cu")
		(net "M_D_CPU0_SB_DQS_DN<6>")
	)
	(arc
		(start 344.815922 -234.651804)
		(mid 344.53749 -234.72165)
		(end 344.260678 -234.645708)
		(width 0.088646)
		(layer "In11.Cu")
		(net "M_D_CPU0_SB_DQS_DN<6>")
	)
	(segment
		(start 264.825226 -227.491798)
		(end 262.74776 -227.491798)
		(width 0.1016)
		(layer "F.Cu")
		(net "M_D_CPU0_SB_DQS_DN<5>")
	)
	(segment
		(start 262.50011 -227.499672)
		(end 262.315198 -227.499672)
		(width 0.20066)
		(layer "F.Cu")
		(net "M_D_CPU0_SB_DQS_DN<5>")
	)
	(segment
		(start 268.829282 -227.91674)
		(end 267.724382 -227.91674)
		(width 0.20066)
		(layer "F.Cu")
		(net "M_D_CPU0_SB_DQS_DN<5>")
	)
	(segment
		(start 264.967466 -227.491798)
		(end 264.825226 -227.491798)
		(width 0.20066)
		(layer "F.Cu")
		(net "M_D_CPU0_SB_DQS_DN<5>")
	)
	(segment
		(start 260.913372 -227.655628)
		(end 260.65226 -227.91674)
		(width 0.20066)
		(layer "F.Cu")
		(net "M_D_CPU0_SB_DQS_DN<5>")
	)
	(segment
		(start 266.972796 -227.655628)
		(end 266.269216 -227.655628)
		(width 0.20066)
		(layer "F.Cu")
		(net "M_D_CPU0_SB_DQS_DN<5>")
	)
	(segment
		(start 347.832934 -240.389156)
		(end 347.83268 -240.388902)
		(width 0.20066)
		(layer "F.Cu")
		(net "M_D_CPU0_SB_DQS_DN<5>")
	)
	(segment
		(start 265.228578 -227.230686)
		(end 264.967466 -227.491798)
		(width 0.20066)
		(layer "F.Cu")
		(net "M_D_CPU0_SB_DQS_DN<5>")
	)
	(segment
		(start 265.6332 -227.230686)
		(end 265.228578 -227.230686)
		(width 0.20066)
		(layer "F.Cu")
		(net "M_D_CPU0_SB_DQS_DN<5>")
	)
	(segment
		(start 262.048752 -227.233226)
		(end 261.808976 -227.233226)
		(width 0.20066)
		(layer "F.Cu")
		(net "M_D_CPU0_SB_DQS_DN<5>")
	)
	(segment
		(start 260.65226 -227.91674)
		(end 260.180582 -227.91674)
		(width 0.20066)
		(layer "F.Cu")
		(net "M_D_CPU0_SB_DQS_DN<5>")
	)
	(segment
		(start 266.269216 -227.655628)
		(end 265.6332 -227.230686)
		(width 0.20066)
		(layer "F.Cu")
		(net "M_D_CPU0_SB_DQS_DN<5>")
	)
	(segment
		(start 267.233908 -227.91674)
		(end 266.972796 -227.655628)
		(width 0.20066)
		(layer "F.Cu")
		(net "M_D_CPU0_SB_DQS_DN<5>")
	)
	(segment
		(start 261.386574 -227.655628)
		(end 260.913372 -227.655628)
		(width 0.20066)
		(layer "F.Cu")
		(net "M_D_CPU0_SB_DQS_DN<5>")
	)
	(segment
		(start 262.315198 -227.499672)
		(end 262.048752 -227.233226)
		(width 0.20066)
		(layer "F.Cu")
		(net "M_D_CPU0_SB_DQS_DN<5>")
	)
	(segment
		(start 347.83268 -240.388902)
		(end 347.83268 -239.853216)
		(width 0.20066)
		(layer "F.Cu")
		(net "M_D_CPU0_SB_DQS_DN<5>")
	)
	(segment
		(start 262.507984 -227.491798)
		(end 262.50011 -227.499672)
		(width 0.101854)
		(layer "F.Cu")
		(net "M_D_CPU0_SB_DQS_DN<5>")
	)
	(segment
		(start 261.808976 -227.233226)
		(end 261.386574 -227.655628)
		(width 0.20066)
		(layer "F.Cu")
		(net "M_D_CPU0_SB_DQS_DN<5>")
	)
	(segment
		(start 267.724382 -227.91674)
		(end 267.233908 -227.91674)
		(width 0.20066)
		(layer "F.Cu")
		(net "M_D_CPU0_SB_DQS_DN<5>")
	)
	(segment
		(start 262.74776 -227.491798)
		(end 262.507984 -227.491798)
		(width 0.101854)
		(layer "F.Cu")
		(net "M_D_CPU0_SB_DQS_DN<5>")
	)
	(segment
		(start 299.495972 -222.955612)
		(end 299.210476 -223.241108)
		(width 0.18288)
		(layer "In11.Cu")
		(net "M_D_CPU0_SB_DQS_DN<5>")
	)
	(segment
		(start 308.961536 -225.531934)
		(end 308.310788 -224.881186)
		(width 0.18288)
		(layer "In11.Cu")
		(net "M_D_CPU0_SB_DQS_DN<5>")
	)
	(segment
		(start 279.590246 -224.090992)
		(end 279.34412 -223.844866)
		(width 0.18288)
		(layer "In11.Cu")
		(net "M_D_CPU0_SB_DQS_DN<5>")
	)
	(segment
		(start 347.645482 -239.528858)
		(end 347.63075 -239.537494)
		(width 0.088646)
		(layer "In11.Cu")
		(net "M_D_CPU0_SB_DQS_DN<5>")
	)
	(segment
		(start 336.281522 -238.720122)
		(end 336.274156 -238.715804)
		(width 0.088646)
		(layer "In11.Cu")
		(net "M_D_CPU0_SB_DQS_DN<5>")
	)
	(segment
		(start 291.673788 -223.888554)
		(end 289.064446 -223.888554)
		(width 0.18288)
		(layer "In11.Cu")
		(net "M_D_CPU0_SB_DQS_DN<5>")
	)
	(segment
		(start 282.934664 -222.991426)
		(end 282.098496 -223.827594)
		(width 0.18288)
		(layer "In11.Cu")
		(net "M_D_CPU0_SB_DQS_DN<5>")
	)
	(segment
		(start 348.145608 -239.853216)
		(end 348.202758 -239.796066)
		(width 0.088646)
		(layer "In11.Cu")
		(net "M_D_CPU0_SB_DQS_DN<5>")
	)
	(segment
		(start 322.124324 -233.91495)
		(end 322.124324 -233.738928)
		(width 0.18288)
		(layer "In11.Cu")
		(net "M_D_CPU0_SB_DQS_DN<5>")
	)
	(segment
		(start 283.642562 -223.238822)
		(end 283.395166 -222.991426)
		(width 0.18288)
		(layer "In11.Cu")
		(net "M_D_CPU0_SB_DQS_DN<5>")
	)
	(segment
		(start 322.512436 -234.303062)
		(end 322.124324 -233.91495)
		(width 0.18288)
		(layer "In11.Cu")
		(net "M_D_CPU0_SB_DQS_DN<5>")
	)
	(segment
		(start 307.859938 -224.881186)
		(end 306.832 -223.853248)
		(width 0.18288)
		(layer "In11.Cu")
		(net "M_D_CPU0_SB_DQS_DN<5>")
	)
	(segment
		(start 337.307682 -239.528858)
		(end 337.29295 -239.537494)
		(width 0.088646)
		(layer "In11.Cu")
		(net "M_D_CPU0_SB_DQS_DN<5>")
	)
	(segment
		(start 331.950568 -237.977172)
		(end 330.508356 -236.53496)
		(width 0.088646)
		(layer "In11.Cu")
		(net "M_D_CPU0_SB_DQS_DN<5>")
	)
	(segment
		(start 298.742608 -223.241108)
		(end 298.479718 -222.978218)
		(width 0.18288)
		(layer "In11.Cu")
		(net "M_D_CPU0_SB_DQS_DN<5>")
	)
	(segment
		(start 343.886282 -239.528858)
		(end 343.87155 -239.537494)
		(width 0.088646)
		(layer "In11.Cu")
		(net "M_D_CPU0_SB_DQS_DN<5>")
	)
	(segment
		(start 324.028308 -235.818934)
		(end 324.028308 -235.642912)
		(width 0.18288)
		(layer "In11.Cu")
		(net "M_D_CPU0_SB_DQS_DN<5>")
	)
	(segment
		(start 313.849766 -226.644708)
		(end 313.55665 -226.351592)
		(width 0.18288)
		(layer "In11.Cu")
		(net "M_D_CPU0_SB_DQS_DN<5>")
	)
	(segment
		(start 280.34234 -223.827594)
		(end 280.078942 -224.090992)
		(width 0.18288)
		(layer "In11.Cu")
		(net "M_D_CPU0_SB_DQS_DN<5>")
	)
	(segment
		(start 294.677846 -224.090992)
		(end 294.42664 -223.839786)
		(width 0.18288)
		(layer "In11.Cu")
		(net "M_D_CPU0_SB_DQS_DN<5>")
	)
	(segment
		(start 314.552838 -226.437952)
		(end 314.346082 -226.644708)
		(width 0.18288)
		(layer "In11.Cu")
		(net "M_D_CPU0_SB_DQS_DN<5>")
	)
	(segment
		(start 323.464428 -235.255054)
		(end 323.076316 -234.866942)
		(width 0.18288)
		(layer "In11.Cu")
		(net "M_D_CPU0_SB_DQS_DN<5>")
	)
	(segment
		(start 297.963336 -222.978218)
		(end 297.079416 -223.862138)
		(width 0.18288)
		(layer "In11.Cu")
		(net "M_D_CPU0_SB_DQS_DN<5>")
	)
	(segment
		(start 312.851546 -226.351592)
		(end 312.013092 -225.513138)
		(width 0.18288)
		(layer "In11.Cu")
		(net "M_D_CPU0_SB_DQS_DN<5>")
	)
	(segment
		(start 344.826336 -239.528858)
		(end 344.815922 -239.534954)
		(width 0.088646)
		(layer "In11.Cu")
		(net "M_D_CPU0_SB_DQS_DN<5>")
	)
	(segment
		(start 284.381702 -222.988378)
		(end 284.131258 -223.238822)
		(width 0.18288)
		(layer "In11.Cu")
		(net "M_D_CPU0_SB_DQS_DN<5>")
	)
	(segment
		(start 276.884892 -225.406966)
		(end 276.223984 -225.680778)
		(width 0.18288)
		(layer "In11.Cu")
		(net "M_D_CPU0_SB_DQS_DN<5>")
	)
	(segment
		(start 345.765882 -239.528858)
		(end 345.755468 -239.534954)
		(width 0.088646)
		(layer "In11.Cu")
		(net "M_D_CPU0_SB_DQS_DN<5>")
	)
	(segment
		(start 324.028308 -235.642912)
		(end 323.64045 -235.255054)
		(width 0.18288)
		(layer "In11.Cu")
		(net "M_D_CPU0_SB_DQS_DN<5>")
	)
	(segment
		(start 348.028768 -239.533938)
		(end 348.019878 -239.528858)
		(width 0.088646)
		(layer "In11.Cu")
		(net "M_D_CPU0_SB_DQS_DN<5>")
	)
	(segment
		(start 286.891984 -222.988378)
		(end 284.381702 -222.988378)
		(width 0.18288)
		(layer "In11.Cu")
		(net "M_D_CPU0_SB_DQS_DN<5>")
	)
	(segment
		(start 324.592442 -236.207046)
		(end 324.41642 -236.207046)
		(width 0.18288)
		(layer "In11.Cu")
		(net "M_D_CPU0_SB_DQS_DN<5>")
	)
	(segment
		(start 302.174148 -222.955612)
		(end 299.495972 -222.955612)
		(width 0.18288)
		(layer "In11.Cu")
		(net "M_D_CPU0_SB_DQS_DN<5>")
	)
	(segment
		(start 323.64045 -235.255054)
		(end 323.464428 -235.255054)
		(width 0.18288)
		(layer "In11.Cu")
		(net "M_D_CPU0_SB_DQS_DN<5>")
	)
	(segment
		(start 347.83268 -239.853216)
		(end 348.145608 -239.853216)
		(width 0.088646)
		(layer "In11.Cu")
		(net "M_D_CPU0_SB_DQS_DN<5>")
	)
	(segment
		(start 339.187282 -239.528858)
		(end 339.176868 -239.534954)
		(width 0.088646)
		(layer "In11.Cu")
		(net "M_D_CPU0_SB_DQS_DN<5>")
	)
	(segment
		(start 324.41642 -236.207046)
		(end 324.028308 -235.818934)
		(width 0.18288)
		(layer "In11.Cu")
		(net "M_D_CPU0_SB_DQS_DN<5>")
	)
	(segment
		(start 313.55665 -226.351592)
		(end 312.851546 -226.351592)
		(width 0.18288)
		(layer "In11.Cu")
		(net "M_D_CPU0_SB_DQS_DN<5>")
	)
	(segment
		(start 298.479718 -222.978218)
		(end 297.963336 -222.978218)
		(width 0.18288)
		(layer "In11.Cu")
		(net "M_D_CPU0_SB_DQS_DN<5>")
	)
	(segment
		(start 312.013092 -225.513138)
		(end 310.52516 -225.513138)
		(width 0.18288)
		(layer "In11.Cu")
		(net "M_D_CPU0_SB_DQS_DN<5>")
	)
	(segment
		(start 293.181786 -224.410016)
		(end 292.19525 -224.410016)
		(width 0.18288)
		(layer "In11.Cu")
		(net "M_D_CPU0_SB_DQS_DN<5>")
	)
	(segment
		(start 332.326488 -237.977172)
		(end 331.950568 -237.977172)
		(width 0.088646)
		(layer "In11.Cu")
		(net "M_D_CPU0_SB_DQS_DN<5>")
	)
	(segment
		(start 310.247284 -225.791014)
		(end 309.786528 -225.791014)
		(width 0.18288)
		(layer "In11.Cu")
		(net "M_D_CPU0_SB_DQS_DN<5>")
	)
	(segment
		(start 324.9803 -236.594904)
		(end 324.592442 -236.207046)
		(width 0.18288)
		(layer "In11.Cu")
		(net "M_D_CPU0_SB_DQS_DN<5>")
	)
	(segment
		(start 334.871822 -237.906306)
		(end 334.864456 -237.901988)
		(width 0.088646)
		(layer "In11.Cu")
		(net "M_D_CPU0_SB_DQS_DN<5>")
	)
	(segment
		(start 277.56485 -224.726754)
		(end 276.884892 -225.406966)
		(width 0.18288)
		(layer "In11.Cu")
		(net "M_D_CPU0_SB_DQS_DN<5>")
	)
	(segment
		(start 269.558008 -227.649786)
		(end 269.096236 -227.649786)
		(width 0.18288)
		(layer "In11.Cu")
		(net "M_D_CPU0_SB_DQS_DN<5>")
	)
	(segment
		(start 289.064446 -223.888554)
		(end 286.891984 -222.988378)
		(width 0.18288)
		(layer "In11.Cu")
		(net "M_D_CPU0_SB_DQS_DN<5>")
	)
	(segment
		(start 332.998064 -237.909862)
		(end 332.983332 -237.901226)
		(width 0.088646)
		(layer "In11.Cu")
		(net "M_D_CPU0_SB_DQS_DN<5>")
	)
	(segment
		(start 282.098496 -223.827594)
		(end 280.34234 -223.827594)
		(width 0.18288)
		(layer "In11.Cu")
		(net "M_D_CPU0_SB_DQS_DN<5>")
	)
	(segment
		(start 280.078942 -224.090992)
		(end 279.590246 -224.090992)
		(width 0.18288)
		(layer "In11.Cu")
		(net "M_D_CPU0_SB_DQS_DN<5>")
	)
	(segment
		(start 279.34412 -223.844866)
		(end 279.071324 -223.844866)
		(width 0.18288)
		(layer "In11.Cu")
		(net "M_D_CPU0_SB_DQS_DN<5>")
	)
	(segment
		(start 279.071324 -223.844866)
		(end 278.579834 -224.04832)
		(width 0.18288)
		(layer "In11.Cu")
		(net "M_D_CPU0_SB_DQS_DN<5>")
	)
	(segment
		(start 295.166542 -224.090992)
		(end 294.677846 -224.090992)
		(width 0.18288)
		(layer "In11.Cu")
		(net "M_D_CPU0_SB_DQS_DN<5>")
	)
	(segment
		(start 283.395166 -222.991426)
		(end 282.934664 -222.991426)
		(width 0.18288)
		(layer "In11.Cu")
		(net "M_D_CPU0_SB_DQS_DN<5>")
	)
	(segment
		(start 336.460084 -239.054894)
		(end 336.460084 -239.0394)
		(width 0.088646)
		(layer "In11.Cu")
		(net "M_D_CPU0_SB_DQS_DN<5>")
	)
	(segment
		(start 323.076316 -234.69092)
		(end 322.688458 -234.303062)
		(width 0.18288)
		(layer "In11.Cu")
		(net "M_D_CPU0_SB_DQS_DN<5>")
	)
	(segment
		(start 323.076316 -234.866942)
		(end 323.076316 -234.69092)
		(width 0.18288)
		(layer "In11.Cu")
		(net "M_D_CPU0_SB_DQS_DN<5>")
	)
	(segment
		(start 321.560444 -233.35107)
		(end 321.172332 -232.962958)
		(width 0.18288)
		(layer "In11.Cu")
		(net "M_D_CPU0_SB_DQS_DN<5>")
	)
	(segment
		(start 275.18868 -226.716082)
		(end 272.223484 -227.944426)
		(width 0.18288)
		(layer "In11.Cu")
		(net "M_D_CPU0_SB_DQS_DN<5>")
	)
	(segment
		(start 310.52516 -225.513138)
		(end 310.247284 -225.791014)
		(width 0.18288)
		(layer "In11.Cu")
		(net "M_D_CPU0_SB_DQS_DN<5>")
	)
	(segment
		(start 322.124324 -233.738928)
		(end 321.736466 -233.35107)
		(width 0.18288)
		(layer "In11.Cu")
		(net "M_D_CPU0_SB_DQS_DN<5>")
	)
	(segment
		(start 292.19525 -224.410016)
		(end 291.673788 -223.888554)
		(width 0.18288)
		(layer "In11.Cu")
		(net "M_D_CPU0_SB_DQS_DN<5>")
	)
	(segment
		(start 309.786528 -225.791014)
		(end 309.527448 -225.531934)
		(width 0.18288)
		(layer "In11.Cu")
		(net "M_D_CPU0_SB_DQS_DN<5>")
	)
	(segment
		(start 341.066882 -239.528858)
		(end 341.05215 -239.537494)
		(width 0.088646)
		(layer "In11.Cu")
		(net "M_D_CPU0_SB_DQS_DN<5>")
	)
	(segment
		(start 272.223484 -227.944426)
		(end 269.852648 -227.944426)
		(width 0.18288)
		(layer "In11.Cu")
		(net "M_D_CPU0_SB_DQS_DN<5>")
	)
	(segment
		(start 299.210476 -223.241108)
		(end 298.742608 -223.241108)
		(width 0.18288)
		(layer "In11.Cu")
		(net "M_D_CPU0_SB_DQS_DN<5>")
	)
	(segment
		(start 306.832 -223.853248)
		(end 304.34153 -223.853248)
		(width 0.18288)
		(layer "In11.Cu")
		(net "M_D_CPU0_SB_DQS_DN<5>")
	)
	(segment
		(start 276.223984 -225.680778)
		(end 275.18868 -226.716082)
		(width 0.18288)
		(layer "In11.Cu")
		(net "M_D_CPU0_SB_DQS_DN<5>")
	)
	(segment
		(start 330.39685 -236.53496)
		(end 330.336906 -236.594904)
		(width 0.088646)
		(layer "In11.Cu")
		(net "M_D_CPU0_SB_DQS_DN<5>")
	)
	(segment
		(start 321.736466 -233.35107)
		(end 321.560444 -233.35107)
		(width 0.18288)
		(layer "In11.Cu")
		(net "M_D_CPU0_SB_DQS_DN<5>")
	)
	(segment
		(start 308.310788 -224.881186)
		(end 307.859938 -224.881186)
		(width 0.18288)
		(layer "In11.Cu")
		(net "M_D_CPU0_SB_DQS_DN<5>")
	)
	(segment
		(start 269.852648 -227.944426)
		(end 269.558008 -227.649786)
		(width 0.18288)
		(layer "In11.Cu")
		(net "M_D_CPU0_SB_DQS_DN<5>")
	)
	(segment
		(start 330.336906 -236.594904)
		(end 324.9803 -236.594904)
		(width 0.18288)
		(layer "In11.Cu")
		(net "M_D_CPU0_SB_DQS_DN<5>")
	)
	(segment
		(start 297.079416 -223.862138)
		(end 295.395396 -223.862138)
		(width 0.18288)
		(layer "In11.Cu")
		(net "M_D_CPU0_SB_DQS_DN<5>")
	)
	(segment
		(start 309.527448 -225.531934)
		(end 308.961536 -225.531934)
		(width 0.18288)
		(layer "In11.Cu")
		(net "M_D_CPU0_SB_DQS_DN<5>")
	)
	(segment
		(start 304.34153 -223.853248)
		(end 302.174148 -222.955612)
		(width 0.18288)
		(layer "In11.Cu")
		(net "M_D_CPU0_SB_DQS_DN<5>")
	)
	(segment
		(start 269.096236 -227.649786)
		(end 268.829282 -227.91674)
		(width 0.18288)
		(layer "In11.Cu")
		(net "M_D_CPU0_SB_DQS_DN<5>")
	)
	(segment
		(start 336.274156 -238.715804)
		(end 336.272632 -238.715042)
		(width 0.088646)
		(layer "In11.Cu")
		(net "M_D_CPU0_SB_DQS_DN<5>")
	)
	(segment
		(start 335.050384 -238.23549)
		(end 335.050384 -238.225584)
		(width 0.088646)
		(layer "In11.Cu")
		(net "M_D_CPU0_SB_DQS_DN<5>")
	)
	(segment
		(start 293.752016 -223.839786)
		(end 293.181786 -224.410016)
		(width 0.18288)
		(layer "In11.Cu")
		(net "M_D_CPU0_SB_DQS_DN<5>")
	)
	(segment
		(start 294.42664 -223.839786)
		(end 293.752016 -223.839786)
		(width 0.18288)
		(layer "In11.Cu")
		(net "M_D_CPU0_SB_DQS_DN<5>")
	)
	(segment
		(start 314.346082 -226.644708)
		(end 313.849766 -226.644708)
		(width 0.18288)
		(layer "In11.Cu")
		(net "M_D_CPU0_SB_DQS_DN<5>")
	)
	(segment
		(start 322.688458 -234.303062)
		(end 322.512436 -234.303062)
		(width 0.18288)
		(layer "In11.Cu")
		(net "M_D_CPU0_SB_DQS_DN<5>")
	)
	(segment
		(start 284.131258 -223.238822)
		(end 283.642562 -223.238822)
		(width 0.18288)
		(layer "In11.Cu")
		(net "M_D_CPU0_SB_DQS_DN<5>")
	)
	(segment
		(start 330.508356 -236.53496)
		(end 330.39685 -236.53496)
		(width 0.088646)
		(layer "In11.Cu")
		(net "M_D_CPU0_SB_DQS_DN<5>")
	)
	(segment
		(start 321.172332 -232.962958)
		(end 321.172332 -232.786936)
		(width 0.18288)
		(layer "In11.Cu")
		(net "M_D_CPU0_SB_DQS_DN<5>")
	)
	(segment
		(start 346.705682 -239.528858)
		(end 346.69095 -239.537494)
		(width 0.088646)
		(layer "In11.Cu")
		(net "M_D_CPU0_SB_DQS_DN<5>")
	)
	(segment
		(start 338.247736 -239.528858)
		(end 338.237322 -239.534954)
		(width 0.088646)
		(layer "In11.Cu")
		(net "M_D_CPU0_SB_DQS_DN<5>")
	)
	(segment
		(start 278.579834 -224.04832)
		(end 277.56485 -224.726754)
		(width 0.18288)
		(layer "In11.Cu")
		(net "M_D_CPU0_SB_DQS_DN<5>")
	)
	(segment
		(start 334.864456 -237.901988)
		(end 334.862932 -237.901226)
		(width 0.088646)
		(layer "In11.Cu")
		(net "M_D_CPU0_SB_DQS_DN<5>")
	)
	(segment
		(start 321.172332 -232.786936)
		(end 314.823348 -226.437952)
		(width 0.18288)
		(layer "In11.Cu")
		(net "M_D_CPU0_SB_DQS_DN<5>")
	)
	(segment
		(start 314.823348 -226.437952)
		(end 314.552838 -226.437952)
		(width 0.18288)
		(layer "In11.Cu")
		(net "M_D_CPU0_SB_DQS_DN<5>")
	)
	(segment
		(start 342.006682 -239.528858)
		(end 341.99195 -239.537494)
		(width 0.088646)
		(layer "In11.Cu")
		(net "M_D_CPU0_SB_DQS_DN<5>")
	)
	(segment
		(start 295.395396 -223.862138)
		(end 295.166542 -224.090992)
		(width 0.18288)
		(layer "In11.Cu")
		(net "M_D_CPU0_SB_DQS_DN<5>")
	)
	(segment
		(start 340.127082 -239.528858)
		(end 340.11235 -239.537494)
		(width 0.088646)
		(layer "In11.Cu")
		(net "M_D_CPU0_SB_DQS_DN<5>")
	)
	(arc
		(start 333.923132 -237.901226)
		(mid 333.735934 -237.851083)
		(end 333.548736 -237.901226)
		(width 0.088646)
		(layer "In11.Cu")
		(net "M_D_CPU0_SB_DQS_DN<5>")
	)
	(arc
		(start 339.176868 -239.534954)
		(mid 338.89869 -239.604677)
		(end 338.622132 -239.528858)
		(width 0.088646)
		(layer "In11.Cu")
		(net "M_D_CPU0_SB_DQS_DN<5>")
	)
	(arc
		(start 337.682078 -239.528858)
		(mid 337.49488 -239.478715)
		(end 337.307682 -239.528858)
		(width 0.088646)
		(layer "In11.Cu")
		(net "M_D_CPU0_SB_DQS_DN<5>")
	)
	(arc
		(start 344.260678 -239.528858)
		(mid 344.07348 -239.478715)
		(end 343.886282 -239.528858)
		(width 0.088646)
		(layer "In11.Cu")
		(net "M_D_CPU0_SB_DQS_DN<5>")
	)
	(arc
		(start 344.815922 -239.534954)
		(mid 344.53749 -239.6048)
		(end 344.260678 -239.528858)
		(width 0.088646)
		(layer "In11.Cu")
		(net "M_D_CPU0_SB_DQS_DN<5>")
	)
	(arc
		(start 347.080078 -239.528858)
		(mid 346.89288 -239.478715)
		(end 346.705682 -239.528858)
		(width 0.088646)
		(layer "In11.Cu")
		(net "M_D_CPU0_SB_DQS_DN<5>")
	)
	(arc
		(start 335.898236 -238.715042)
		(mid 335.615534 -238.790818)
		(end 335.332832 -238.715042)
		(width 0.088646)
		(layer "In11.Cu")
		(net "M_D_CPU0_SB_DQS_DN<5>")
	)
	(arc
		(start 347.63075 -239.537494)
		(mid 347.354275 -239.604814)
		(end 347.080078 -239.528858)
		(width 0.088646)
		(layer "In11.Cu")
		(net "M_D_CPU0_SB_DQS_DN<5>")
	)
	(arc
		(start 341.05215 -239.537494)
		(mid 340.775675 -239.604814)
		(end 340.501478 -239.528858)
		(width 0.088646)
		(layer "In11.Cu")
		(net "M_D_CPU0_SB_DQS_DN<5>")
	)
	(arc
		(start 342.946482 -239.528858)
		(mid 342.66378 -239.604634)
		(end 342.381078 -239.528858)
		(width 0.088646)
		(layer "In11.Cu")
		(net "M_D_CPU0_SB_DQS_DN<5>")
	)
	(arc
		(start 337.29295 -239.537494)
		(mid 337.016475 -239.604814)
		(end 336.742278 -239.528858)
		(width 0.088646)
		(layer "In11.Cu")
		(net "M_D_CPU0_SB_DQS_DN<5>")
	)
	(arc
		(start 332.608936 -237.901226)
		(mid 332.47271 -237.957783)
		(end 332.326488 -237.977172)
		(width 0.088646)
		(layer "In11.Cu")
		(net "M_D_CPU0_SB_DQS_DN<5>")
	)
	(arc
		(start 346.69095 -239.537494)
		(mid 346.414475 -239.604814)
		(end 346.140278 -239.528858)
		(width 0.088646)
		(layer "In11.Cu")
		(net "M_D_CPU0_SB_DQS_DN<5>")
	)
	(arc
		(start 336.460084 -239.0394)
		(mid 336.412405 -238.8565)
		(end 336.281522 -238.720122)
		(width 0.088646)
		(layer "In11.Cu")
		(net "M_D_CPU0_SB_DQS_DN<5>")
	)
	(arc
		(start 335.050384 -238.225584)
		(mid 335.002705 -238.042684)
		(end 334.871822 -237.906306)
		(width 0.088646)
		(layer "In11.Cu")
		(net "M_D_CPU0_SB_DQS_DN<5>")
	)
	(arc
		(start 332.983332 -237.901226)
		(mid 332.796134 -237.851083)
		(end 332.608936 -237.901226)
		(width 0.088646)
		(layer "In11.Cu")
		(net "M_D_CPU0_SB_DQS_DN<5>")
	)
	(arc
		(start 333.548736 -237.901226)
		(mid 333.274537 -237.977061)
		(end 332.998064 -237.909862)
		(width 0.088646)
		(layer "In11.Cu")
		(net "M_D_CPU0_SB_DQS_DN<5>")
	)
	(arc
		(start 335.332832 -238.715042)
		(mid 335.128497 -238.512437)
		(end 335.050384 -238.23549)
		(width 0.088646)
		(layer "In11.Cu")
		(net "M_D_CPU0_SB_DQS_DN<5>")
	)
	(arc
		(start 339.561678 -239.528858)
		(mid 339.37448 -239.478715)
		(end 339.187282 -239.528858)
		(width 0.088646)
		(layer "In11.Cu")
		(net "M_D_CPU0_SB_DQS_DN<5>")
	)
	(arc
		(start 341.441278 -239.528858)
		(mid 341.25408 -239.478715)
		(end 341.066882 -239.528858)
		(width 0.088646)
		(layer "In11.Cu")
		(net "M_D_CPU0_SB_DQS_DN<5>")
	)
	(arc
		(start 334.488536 -237.901226)
		(mid 334.205834 -237.977002)
		(end 333.923132 -237.901226)
		(width 0.088646)
		(layer "In11.Cu")
		(net "M_D_CPU0_SB_DQS_DN<5>")
	)
	(arc
		(start 345.755468 -239.534954)
		(mid 345.47729 -239.604677)
		(end 345.200732 -239.528858)
		(width 0.088646)
		(layer "In11.Cu")
		(net "M_D_CPU0_SB_DQS_DN<5>")
	)
	(arc
		(start 336.742278 -239.528858)
		(mid 336.539455 -239.328627)
		(end 336.460084 -239.054894)
		(width 0.088646)
		(layer "In11.Cu")
		(net "M_D_CPU0_SB_DQS_DN<5>")
	)
	(arc
		(start 341.99195 -239.537494)
		(mid 341.715475 -239.604814)
		(end 341.441278 -239.528858)
		(width 0.088646)
		(layer "In11.Cu")
		(net "M_D_CPU0_SB_DQS_DN<5>")
	)
	(arc
		(start 340.11235 -239.537494)
		(mid 339.835875 -239.604814)
		(end 339.561678 -239.528858)
		(width 0.088646)
		(layer "In11.Cu")
		(net "M_D_CPU0_SB_DQS_DN<5>")
	)
	(arc
		(start 336.272632 -238.715042)
		(mid 336.085434 -238.664899)
		(end 335.898236 -238.715042)
		(width 0.088646)
		(layer "In11.Cu")
		(net "M_D_CPU0_SB_DQS_DN<5>")
	)
	(arc
		(start 345.200732 -239.528858)
		(mid 345.013534 -239.478715)
		(end 344.826336 -239.528858)
		(width 0.088646)
		(layer "In11.Cu")
		(net "M_D_CPU0_SB_DQS_DN<5>")
	)
	(arc
		(start 348.202758 -239.796066)
		(mid 348.144639 -239.645825)
		(end 348.028768 -239.533938)
		(width 0.088646)
		(layer "In11.Cu")
		(net "M_D_CPU0_SB_DQS_DN<5>")
	)
	(arc
		(start 338.237322 -239.534954)
		(mid 337.95889 -239.6048)
		(end 337.682078 -239.528858)
		(width 0.088646)
		(layer "In11.Cu")
		(net "M_D_CPU0_SB_DQS_DN<5>")
	)
	(arc
		(start 348.019878 -239.528858)
		(mid 347.83268 -239.478715)
		(end 347.645482 -239.528858)
		(width 0.088646)
		(layer "In11.Cu")
		(net "M_D_CPU0_SB_DQS_DN<5>")
	)
	(arc
		(start 334.862932 -237.901226)
		(mid 334.675734 -237.851083)
		(end 334.488536 -237.901226)
		(width 0.088646)
		(layer "In11.Cu")
		(net "M_D_CPU0_SB_DQS_DN<5>")
	)
	(arc
		(start 346.140278 -239.528858)
		(mid 345.95308 -239.478715)
		(end 345.765882 -239.528858)
		(width 0.088646)
		(layer "In11.Cu")
		(net "M_D_CPU0_SB_DQS_DN<5>")
	)
	(arc
		(start 342.381078 -239.528858)
		(mid 342.19388 -239.478715)
		(end 342.006682 -239.528858)
		(width 0.088646)
		(layer "In11.Cu")
		(net "M_D_CPU0_SB_DQS_DN<5>")
	)
	(arc
		(start 338.622132 -239.528858)
		(mid 338.434934 -239.478715)
		(end 338.247736 -239.528858)
		(width 0.088646)
		(layer "In11.Cu")
		(net "M_D_CPU0_SB_DQS_DN<5>")
	)
	(arc
		(start 340.501478 -239.528858)
		(mid 340.31428 -239.478715)
		(end 340.127082 -239.528858)
		(width 0.088646)
		(layer "In11.Cu")
		(net "M_D_CPU0_SB_DQS_DN<5>")
	)
	(arc
		(start 343.87155 -239.537494)
		(mid 343.595075 -239.604814)
		(end 343.320878 -239.528858)
		(width 0.088646)
		(layer "In11.Cu")
		(net "M_D_CPU0_SB_DQS_DN<5>")
	)
	(arc
		(start 343.320878 -239.528858)
		(mid 343.13368 -239.478715)
		(end 342.946482 -239.528858)
		(width 0.088646)
		(layer "In11.Cu")
		(net "M_D_CPU0_SB_DQS_DN<5>")
	)
	(segment
		(start 261.808976 -236.58322)
		(end 261.386574 -237.005622)
		(width 0.20066)
		(layer "F.Cu")
		(net "M_D_CPU0_SB_DQS_DN<4>")
	)
	(segment
		(start 268.829282 -237.266734)
		(end 267.724382 -237.266734)
		(width 0.20066)
		(layer "F.Cu")
		(net "M_D_CPU0_SB_DQS_DN<4>")
	)
	(segment
		(start 267.724382 -237.266734)
		(end 267.233908 -237.266734)
		(width 0.20066)
		(layer "F.Cu")
		(net "M_D_CPU0_SB_DQS_DN<4>")
	)
	(segment
		(start 348.772734 -245.27256)
		(end 348.77248 -245.272306)
		(width 0.20066)
		(layer "F.Cu")
		(net "M_D_CPU0_SB_DQS_DN<4>")
	)
	(segment
		(start 266.972796 -237.005622)
		(end 266.269216 -237.005622)
		(width 0.20066)
		(layer "F.Cu")
		(net "M_D_CPU0_SB_DQS_DN<4>")
	)
	(segment
		(start 261.386574 -237.005622)
		(end 260.913372 -237.005622)
		(width 0.20066)
		(layer "F.Cu")
		(net "M_D_CPU0_SB_DQS_DN<4>")
	)
	(segment
		(start 262.507984 -236.841792)
		(end 262.50011 -236.849666)
		(width 0.101854)
		(layer "F.Cu")
		(net "M_D_CPU0_SB_DQS_DN<4>")
	)
	(segment
		(start 262.74776 -236.841792)
		(end 262.507984 -236.841792)
		(width 0.101854)
		(layer "F.Cu")
		(net "M_D_CPU0_SB_DQS_DN<4>")
	)
	(segment
		(start 262.315198 -236.849666)
		(end 262.048752 -236.58322)
		(width 0.20066)
		(layer "F.Cu")
		(net "M_D_CPU0_SB_DQS_DN<4>")
	)
	(segment
		(start 265.6332 -236.58068)
		(end 265.228578 -236.58068)
		(width 0.20066)
		(layer "F.Cu")
		(net "M_D_CPU0_SB_DQS_DN<4>")
	)
	(segment
		(start 262.048752 -236.58322)
		(end 261.808976 -236.58322)
		(width 0.20066)
		(layer "F.Cu")
		(net "M_D_CPU0_SB_DQS_DN<4>")
	)
	(segment
		(start 266.269216 -237.005622)
		(end 265.6332 -236.58068)
		(width 0.20066)
		(layer "F.Cu")
		(net "M_D_CPU0_SB_DQS_DN<4>")
	)
	(segment
		(start 264.967466 -236.841792)
		(end 264.825226 -236.841792)
		(width 0.20066)
		(layer "F.Cu")
		(net "M_D_CPU0_SB_DQS_DN<4>")
	)
	(segment
		(start 264.825226 -236.841792)
		(end 262.74776 -236.841792)
		(width 0.1016)
		(layer "F.Cu")
		(net "M_D_CPU0_SB_DQS_DN<4>")
	)
	(segment
		(start 267.233908 -237.266734)
		(end 266.972796 -237.005622)
		(width 0.20066)
		(layer "F.Cu")
		(net "M_D_CPU0_SB_DQS_DN<4>")
	)
	(segment
		(start 260.65226 -237.266734)
		(end 260.180582 -237.266734)
		(width 0.20066)
		(layer "F.Cu")
		(net "M_D_CPU0_SB_DQS_DN<4>")
	)
	(segment
		(start 265.228578 -236.58068)
		(end 264.967466 -236.841792)
		(width 0.20066)
		(layer "F.Cu")
		(net "M_D_CPU0_SB_DQS_DN<4>")
	)
	(segment
		(start 348.77248 -245.272306)
		(end 348.77248 -244.73662)
		(width 0.20066)
		(layer "F.Cu")
		(net "M_D_CPU0_SB_DQS_DN<4>")
	)
	(segment
		(start 260.913372 -237.005622)
		(end 260.65226 -237.266734)
		(width 0.20066)
		(layer "F.Cu")
		(net "M_D_CPU0_SB_DQS_DN<4>")
	)
	(segment
		(start 262.50011 -236.849666)
		(end 262.315198 -236.849666)
		(width 0.20066)
		(layer "F.Cu")
		(net "M_D_CPU0_SB_DQS_DN<4>")
	)
	(segment
		(start 284.10408 -235.991146)
		(end 283.68752 -235.991146)
		(width 0.18288)
		(layer "In11.Cu")
		(net "M_D_CPU0_SB_DQS_DN<4>")
	)
	(segment
		(start 294.447214 -236.5756)
		(end 293.152068 -236.5756)
		(width 0.18288)
		(layer "In11.Cu")
		(net "M_D_CPU0_SB_DQS_DN<4>")
	)
	(segment
		(start 283.391356 -235.694982)
		(end 282.681426 -235.694982)
		(width 0.18288)
		(layer "In11.Cu")
		(net "M_D_CPU0_SB_DQS_DN<4>")
	)
	(segment
		(start 303.7459 -236.341666)
		(end 303.107852 -235.703618)
		(width 0.18288)
		(layer "In11.Cu")
		(net "M_D_CPU0_SB_DQS_DN<4>")
	)
	(segment
		(start 308.285642 -235.71708)
		(end 307.217318 -235.71708)
		(width 0.18288)
		(layer "In11.Cu")
		(net "M_D_CPU0_SB_DQS_DN<4>")
	)
	(segment
		(start 280.358342 -236.562392)
		(end 280.077926 -236.842808)
		(width 0.18288)
		(layer "In11.Cu")
		(net "M_D_CPU0_SB_DQS_DN<4>")
	)
	(segment
		(start 333.64043 -243.93271)
		(end 333.64043 -243.922804)
		(width 0.088646)
		(layer "In11.Cu")
		(net "M_D_CPU0_SB_DQS_DN<4>")
	)
	(segment
		(start 282.681426 -235.694982)
		(end 281.814016 -236.562392)
		(width 0.18288)
		(layer "In11.Cu")
		(net "M_D_CPU0_SB_DQS_DN<4>")
	)
	(segment
		(start 295.373044 -236.557566)
		(end 295.090342 -236.840268)
		(width 0.18288)
		(layer "In11.Cu")
		(net "M_D_CPU0_SB_DQS_DN<4>")
	)
	(segment
		(start 331.697076 -243.210334)
		(end 331.637132 -243.270278)
		(width 0.088646)
		(layer "In11.Cu")
		(net "M_D_CPU0_SB_DQS_DN<4>")
	)
	(segment
		(start 336.367882 -244.412262)
		(end 336.35315 -244.420898)
		(width 0.088646)
		(layer "In11.Cu")
		(net "M_D_CPU0_SB_DQS_DN<4>")
	)
	(segment
		(start 292.873938 -236.85373)
		(end 292.515544 -236.85373)
		(width 0.18288)
		(layer "In11.Cu")
		(net "M_D_CPU0_SB_DQS_DN<4>")
	)
	(segment
		(start 292.515544 -236.85373)
		(end 292.211252 -236.549438)
		(width 0.18288)
		(layer "In11.Cu")
		(net "M_D_CPU0_SB_DQS_DN<4>")
	)
	(segment
		(start 269.852648 -237.291118)
		(end 269.5575 -236.99597)
		(width 0.18288)
		(layer "In11.Cu")
		(net "M_D_CPU0_SB_DQS_DN<4>")
	)
	(segment
		(start 348.77248 -244.73662)
		(end 348.459552 -244.73662)
		(width 0.088646)
		(layer "In11.Cu")
		(net "M_D_CPU0_SB_DQS_DN<4>")
	)
	(segment
		(start 341.066882 -244.412262)
		(end 341.056468 -244.418358)
		(width 0.088646)
		(layer "In11.Cu")
		(net "M_D_CPU0_SB_DQS_DN<4>")
	)
	(segment
		(start 297.868086 -235.716826)
		(end 297.027346 -236.557566)
		(width 0.18288)
		(layer "In11.Cu")
		(net "M_D_CPU0_SB_DQS_DN<4>")
	)
	(segment
		(start 338.247736 -244.412262)
		(end 338.237322 -244.418358)
		(width 0.088646)
		(layer "In11.Cu")
		(net "M_D_CPU0_SB_DQS_DN<4>")
	)
	(segment
		(start 278.680418 -236.59719)
		(end 277.713186 -237.564422)
		(width 0.18288)
		(layer "In11.Cu")
		(net "M_D_CPU0_SB_DQS_DN<4>")
	)
	(segment
		(start 339.187282 -244.412262)
		(end 339.176868 -244.418358)
		(width 0.088646)
		(layer "In11.Cu")
		(net "M_D_CPU0_SB_DQS_DN<4>")
	)
	(segment
		(start 273.302984 -237.564422)
		(end 272.643092 -237.291118)
		(width 0.18288)
		(layer "In11.Cu")
		(net "M_D_CPU0_SB_DQS_DN<4>")
	)
	(segment
		(start 299.205142 -235.991146)
		(end 298.812458 -235.991146)
		(width 0.18288)
		(layer "In11.Cu")
		(net "M_D_CPU0_SB_DQS_DN<4>")
	)
	(segment
		(start 280.077926 -236.842808)
		(end 279.571196 -236.842808)
		(width 0.18288)
		(layer "In11.Cu")
		(net "M_D_CPU0_SB_DQS_DN<4>")
	)
	(segment
		(start 331.867002 -243.210334)
		(end 331.697076 -243.210334)
		(width 0.088646)
		(layer "In11.Cu")
		(net "M_D_CPU0_SB_DQS_DN<4>")
	)
	(segment
		(start 343.886282 -244.412262)
		(end 343.87155 -244.420898)
		(width 0.088646)
		(layer "In11.Cu")
		(net "M_D_CPU0_SB_DQS_DN<4>")
	)
	(segment
		(start 305.243992 -235.712762)
		(end 304.615088 -236.341666)
		(width 0.18288)
		(layer "In11.Cu")
		(net "M_D_CPU0_SB_DQS_DN<4>")
	)
	(segment
		(start 330.844398 -243.270278)
		(end 330.271882 -242.697762)
		(width 0.18288)
		(layer "In11.Cu")
		(net "M_D_CPU0_SB_DQS_DN<4>")
	)
	(segment
		(start 272.643092 -237.291118)
		(end 269.852648 -237.291118)
		(width 0.18288)
		(layer "In11.Cu")
		(net "M_D_CPU0_SB_DQS_DN<4>")
	)
	(segment
		(start 331.637132 -243.270278)
		(end 330.844398 -243.270278)
		(width 0.18288)
		(layer "In11.Cu")
		(net "M_D_CPU0_SB_DQS_DN<4>")
	)
	(segment
		(start 297.027346 -236.557566)
		(end 295.373044 -236.557566)
		(width 0.18288)
		(layer "In11.Cu")
		(net "M_D_CPU0_SB_DQS_DN<4>")
	)
	(segment
		(start 277.713186 -237.564422)
		(end 273.302984 -237.564422)
		(width 0.18288)
		(layer "In11.Cu")
		(net "M_D_CPU0_SB_DQS_DN<4>")
	)
	(segment
		(start 283.68752 -235.991146)
		(end 283.391356 -235.694982)
		(width 0.18288)
		(layer "In11.Cu")
		(net "M_D_CPU0_SB_DQS_DN<4>")
	)
	(segment
		(start 288.213038 -235.716572)
		(end 284.378654 -235.716572)
		(width 0.18288)
		(layer "In11.Cu")
		(net "M_D_CPU0_SB_DQS_DN<4>")
	)
	(segment
		(start 314.482734 -237.630462)
		(end 313.700668 -237.630462)
		(width 0.18288)
		(layer "In11.Cu")
		(net "M_D_CPU0_SB_DQS_DN<4>")
	)
	(segment
		(start 306.589938 -236.021626)
		(end 306.281074 -235.712762)
		(width 0.18288)
		(layer "In11.Cu")
		(net "M_D_CPU0_SB_DQS_DN<4>")
	)
	(segment
		(start 303.107852 -235.703618)
		(end 299.49267 -235.703618)
		(width 0.18288)
		(layer "In11.Cu")
		(net "M_D_CPU0_SB_DQS_DN<4>")
	)
	(segment
		(start 269.5575 -236.99597)
		(end 269.100046 -236.99597)
		(width 0.18288)
		(layer "In11.Cu")
		(net "M_D_CPU0_SB_DQS_DN<4>")
	)
	(segment
		(start 304.615088 -236.341666)
		(end 303.7459 -236.341666)
		(width 0.18288)
		(layer "In11.Cu")
		(net "M_D_CPU0_SB_DQS_DN<4>")
	)
	(segment
		(start 306.912772 -236.021626)
		(end 306.589938 -236.021626)
		(width 0.18288)
		(layer "In11.Cu")
		(net "M_D_CPU0_SB_DQS_DN<4>")
	)
	(segment
		(start 289.045904 -236.549438)
		(end 288.213038 -235.716572)
		(width 0.18288)
		(layer "In11.Cu")
		(net "M_D_CPU0_SB_DQS_DN<4>")
	)
	(segment
		(start 348.459552 -244.73662)
		(end 348.394528 -244.801644)
		(width 0.088646)
		(layer "In11.Cu")
		(net "M_D_CPU0_SB_DQS_DN<4>")
	)
	(segment
		(start 293.152068 -236.5756)
		(end 292.873938 -236.85373)
		(width 0.18288)
		(layer "In11.Cu")
		(net "M_D_CPU0_SB_DQS_DN<4>")
	)
	(segment
		(start 269.100046 -236.99597)
		(end 268.829282 -237.266734)
		(width 0.18288)
		(layer "In11.Cu")
		(net "M_D_CPU0_SB_DQS_DN<4>")
	)
	(segment
		(start 347.088968 -244.417342)
		(end 347.080078 -244.412262)
		(width 0.088646)
		(layer "In11.Cu")
		(net "M_D_CPU0_SB_DQS_DN<4>")
	)
	(segment
		(start 344.826336 -244.412262)
		(end 344.815922 -244.418358)
		(width 0.088646)
		(layer "In11.Cu")
		(net "M_D_CPU0_SB_DQS_DN<4>")
	)
	(segment
		(start 332.330806 -243.674138)
		(end 331.867002 -243.210334)
		(width 0.088646)
		(layer "In11.Cu")
		(net "M_D_CPU0_SB_DQS_DN<4>")
	)
	(segment
		(start 281.814016 -236.562392)
		(end 280.358342 -236.562392)
		(width 0.18288)
		(layer "In11.Cu")
		(net "M_D_CPU0_SB_DQS_DN<4>")
	)
	(segment
		(start 279.571196 -236.842808)
		(end 279.325578 -236.59719)
		(width 0.18288)
		(layer "In11.Cu")
		(net "M_D_CPU0_SB_DQS_DN<4>")
	)
	(segment
		(start 332.796134 -243.674138)
		(end 332.330806 -243.674138)
		(width 0.088646)
		(layer "In11.Cu")
		(net "M_D_CPU0_SB_DQS_DN<4>")
	)
	(segment
		(start 330.271882 -242.697762)
		(end 319.984628 -242.697762)
		(width 0.18288)
		(layer "In11.Cu")
		(net "M_D_CPU0_SB_DQS_DN<4>")
	)
	(segment
		(start 345.765882 -244.412262)
		(end 345.755468 -244.418358)
		(width 0.088646)
		(layer "In11.Cu")
		(net "M_D_CPU0_SB_DQS_DN<4>")
	)
	(segment
		(start 299.49267 -235.703618)
		(end 299.205142 -235.991146)
		(width 0.18288)
		(layer "In11.Cu")
		(net "M_D_CPU0_SB_DQS_DN<4>")
	)
	(segment
		(start 340.127336 -244.412262)
		(end 340.116922 -244.418358)
		(width 0.088646)
		(layer "In11.Cu")
		(net "M_D_CPU0_SB_DQS_DN<4>")
	)
	(segment
		(start 298.812458 -235.991146)
		(end 298.538138 -235.716826)
		(width 0.18288)
		(layer "In11.Cu")
		(net "M_D_CPU0_SB_DQS_DN<4>")
	)
	(segment
		(start 292.211252 -236.549438)
		(end 289.045904 -236.549438)
		(width 0.18288)
		(layer "In11.Cu")
		(net "M_D_CPU0_SB_DQS_DN<4>")
	)
	(segment
		(start 310.443118 -235.975906)
		(end 308.544468 -235.975906)
		(width 0.18288)
		(layer "In11.Cu")
		(net "M_D_CPU0_SB_DQS_DN<4>")
	)
	(segment
		(start 284.378654 -235.716572)
		(end 284.10408 -235.991146)
		(width 0.18288)
		(layer "In11.Cu")
		(net "M_D_CPU0_SB_DQS_DN<4>")
	)
	(segment
		(start 298.538138 -235.716826)
		(end 297.868086 -235.716826)
		(width 0.18288)
		(layer "In11.Cu")
		(net "M_D_CPU0_SB_DQS_DN<4>")
	)
	(segment
		(start 319.984628 -242.697762)
		(end 315.225938 -237.939072)
		(width 0.18288)
		(layer "In11.Cu")
		(net "M_D_CPU0_SB_DQS_DN<4>")
	)
	(segment
		(start 279.325578 -236.59719)
		(end 278.680418 -236.59719)
		(width 0.18288)
		(layer "In11.Cu")
		(net "M_D_CPU0_SB_DQS_DN<4>")
	)
	(segment
		(start 342.006682 -244.412262)
		(end 341.99195 -244.420898)
		(width 0.088646)
		(layer "In11.Cu")
		(net "M_D_CPU0_SB_DQS_DN<4>")
	)
	(segment
		(start 307.217318 -235.71708)
		(end 306.912772 -236.021626)
		(width 0.18288)
		(layer "In11.Cu")
		(net "M_D_CPU0_SB_DQS_DN<4>")
	)
	(segment
		(start 308.544468 -235.975906)
		(end 308.285642 -235.71708)
		(width 0.18288)
		(layer "In11.Cu")
		(net "M_D_CPU0_SB_DQS_DN<4>")
	)
	(segment
		(start 346.705682 -244.412262)
		(end 346.69095 -244.420898)
		(width 0.088646)
		(layer "In11.Cu")
		(net "M_D_CPU0_SB_DQS_DN<4>")
	)
	(segment
		(start 337.307682 -244.412262)
		(end 337.29295 -244.420898)
		(width 0.088646)
		(layer "In11.Cu")
		(net "M_D_CPU0_SB_DQS_DN<4>")
	)
	(segment
		(start 306.281074 -235.712762)
		(end 305.243992 -235.712762)
		(width 0.18288)
		(layer "In11.Cu")
		(net "M_D_CPU0_SB_DQS_DN<4>")
	)
	(segment
		(start 295.090342 -236.840268)
		(end 294.711882 -236.840268)
		(width 0.18288)
		(layer "In11.Cu")
		(net "M_D_CPU0_SB_DQS_DN<4>")
	)
	(segment
		(start 347.564964 -245.234968)
		(end 347.550232 -245.226332)
		(width 0.088646)
		(layer "In11.Cu")
		(net "M_D_CPU0_SB_DQS_DN<4>")
	)
	(segment
		(start 347.26753 -244.750844)
		(end 347.26753 -244.73662)
		(width 0.088646)
		(layer "In11.Cu")
		(net "M_D_CPU0_SB_DQS_DN<4>")
	)
	(segment
		(start 315.225938 -237.939072)
		(end 314.482734 -237.630462)
		(width 0.18288)
		(layer "In11.Cu")
		(net "M_D_CPU0_SB_DQS_DN<4>")
	)
	(segment
		(start 313.700668 -237.630462)
		(end 312.514488 -236.836712)
		(width 0.18288)
		(layer "In11.Cu")
		(net "M_D_CPU0_SB_DQS_DN<4>")
	)
	(segment
		(start 294.711882 -236.840268)
		(end 294.447214 -236.5756)
		(width 0.18288)
		(layer "In11.Cu")
		(net "M_D_CPU0_SB_DQS_DN<4>")
	)
	(segment
		(start 312.514488 -236.836712)
		(end 310.443118 -235.975906)
		(width 0.18288)
		(layer "In11.Cu")
		(net "M_D_CPU0_SB_DQS_DN<4>")
	)
	(arc
		(start 333.64043 -243.922804)
		(mid 333.453131 -243.598363)
		(end 333.078582 -243.598446)
		(width 0.088646)
		(layer "In11.Cu")
		(net "M_D_CPU0_SB_DQS_DN<4>")
	)
	(arc
		(start 338.237322 -244.418358)
		(mid 337.95889 -244.488204)
		(end 337.682078 -244.412262)
		(width 0.088646)
		(layer "In11.Cu")
		(net "M_D_CPU0_SB_DQS_DN<4>")
	)
	(arc
		(start 348.115636 -245.226332)
		(mid 347.841407 -245.302257)
		(end 347.564964 -245.234968)
		(width 0.088646)
		(layer "In11.Cu")
		(net "M_D_CPU0_SB_DQS_DN<4>")
	)
	(arc
		(start 343.87155 -244.420898)
		(mid 343.595075 -244.488218)
		(end 343.320878 -244.412262)
		(width 0.088646)
		(layer "In11.Cu")
		(net "M_D_CPU0_SB_DQS_DN<4>")
	)
	(arc
		(start 335.428082 -244.412262)
		(mid 335.14538 -244.488038)
		(end 334.862678 -244.412262)
		(width 0.088646)
		(layer "In11.Cu")
		(net "M_D_CPU0_SB_DQS_DN<4>")
	)
	(arc
		(start 338.622132 -244.412262)
		(mid 338.434934 -244.362119)
		(end 338.247736 -244.412262)
		(width 0.088646)
		(layer "In11.Cu")
		(net "M_D_CPU0_SB_DQS_DN<4>")
	)
	(arc
		(start 341.056468 -244.418358)
		(mid 340.77829 -244.488081)
		(end 340.501732 -244.412262)
		(width 0.088646)
		(layer "In11.Cu")
		(net "M_D_CPU0_SB_DQS_DN<4>")
	)
	(arc
		(start 346.140278 -244.412262)
		(mid 345.95308 -244.362119)
		(end 345.765882 -244.412262)
		(width 0.088646)
		(layer "In11.Cu")
		(net "M_D_CPU0_SB_DQS_DN<4>")
	)
	(arc
		(start 339.176868 -244.418358)
		(mid 338.89869 -244.488081)
		(end 338.622132 -244.412262)
		(width 0.088646)
		(layer "In11.Cu")
		(net "M_D_CPU0_SB_DQS_DN<4>")
	)
	(arc
		(start 339.561678 -244.412262)
		(mid 339.37448 -244.362119)
		(end 339.187282 -244.412262)
		(width 0.088646)
		(layer "In11.Cu")
		(net "M_D_CPU0_SB_DQS_DN<4>")
	)
	(arc
		(start 341.441278 -244.412262)
		(mid 341.25408 -244.362119)
		(end 341.066882 -244.412262)
		(width 0.088646)
		(layer "In11.Cu")
		(net "M_D_CPU0_SB_DQS_DN<4>")
	)
	(arc
		(start 334.488282 -244.412262)
		(mid 334.20558 -244.488038)
		(end 333.922878 -244.412262)
		(width 0.088646)
		(layer "In11.Cu")
		(net "M_D_CPU0_SB_DQS_DN<4>")
	)
	(arc
		(start 347.550232 -245.226332)
		(mid 347.346751 -245.025528)
		(end 347.26753 -244.750844)
		(width 0.088646)
		(layer "In11.Cu")
		(net "M_D_CPU0_SB_DQS_DN<4>")
	)
	(arc
		(start 343.320878 -244.412262)
		(mid 343.13368 -244.362119)
		(end 342.946482 -244.412262)
		(width 0.088646)
		(layer "In11.Cu")
		(net "M_D_CPU0_SB_DQS_DN<4>")
	)
	(arc
		(start 340.116922 -244.418358)
		(mid 339.83849 -244.488204)
		(end 339.561678 -244.412262)
		(width 0.088646)
		(layer "In11.Cu")
		(net "M_D_CPU0_SB_DQS_DN<4>")
	)
	(arc
		(start 335.802478 -244.412262)
		(mid 335.61528 -244.362119)
		(end 335.428082 -244.412262)
		(width 0.088646)
		(layer "In11.Cu")
		(net "M_D_CPU0_SB_DQS_DN<4>")
	)
	(arc
		(start 342.946482 -244.412262)
		(mid 342.66378 -244.488038)
		(end 342.381078 -244.412262)
		(width 0.088646)
		(layer "In11.Cu")
		(net "M_D_CPU0_SB_DQS_DN<4>")
	)
	(arc
		(start 337.682078 -244.412262)
		(mid 337.49488 -244.362119)
		(end 337.307682 -244.412262)
		(width 0.088646)
		(layer "In11.Cu")
		(net "M_D_CPU0_SB_DQS_DN<4>")
	)
	(arc
		(start 341.99195 -244.420898)
		(mid 341.715475 -244.488218)
		(end 341.441278 -244.412262)
		(width 0.088646)
		(layer "In11.Cu")
		(net "M_D_CPU0_SB_DQS_DN<4>")
	)
	(arc
		(start 345.755468 -244.418358)
		(mid 345.47729 -244.488081)
		(end 345.200732 -244.412262)
		(width 0.088646)
		(layer "In11.Cu")
		(net "M_D_CPU0_SB_DQS_DN<4>")
	)
	(arc
		(start 334.862678 -244.412262)
		(mid 334.67548 -244.362119)
		(end 334.488282 -244.412262)
		(width 0.088646)
		(layer "In11.Cu")
		(net "M_D_CPU0_SB_DQS_DN<4>")
	)
	(arc
		(start 342.381078 -244.412262)
		(mid 342.19388 -244.362119)
		(end 342.006682 -244.412262)
		(width 0.088646)
		(layer "In11.Cu")
		(net "M_D_CPU0_SB_DQS_DN<4>")
	)
	(arc
		(start 344.815922 -244.418358)
		(mid 344.53749 -244.488204)
		(end 344.260678 -244.412262)
		(width 0.088646)
		(layer "In11.Cu")
		(net "M_D_CPU0_SB_DQS_DN<4>")
	)
	(arc
		(start 337.29295 -244.420898)
		(mid 337.016475 -244.488218)
		(end 336.742278 -244.412262)
		(width 0.088646)
		(layer "In11.Cu")
		(net "M_D_CPU0_SB_DQS_DN<4>")
	)
	(arc
		(start 344.260678 -244.412262)
		(mid 344.07348 -244.362119)
		(end 343.886282 -244.412262)
		(width 0.088646)
		(layer "In11.Cu")
		(net "M_D_CPU0_SB_DQS_DN<4>")
	)
	(arc
		(start 346.69095 -244.420898)
		(mid 346.414475 -244.488218)
		(end 346.140278 -244.412262)
		(width 0.088646)
		(layer "In11.Cu")
		(net "M_D_CPU0_SB_DQS_DN<4>")
	)
	(arc
		(start 348.391734 -244.82298)
		(mid 348.29954 -245.056059)
		(end 348.115636 -245.226332)
		(width 0.088646)
		(layer "In11.Cu")
		(net "M_D_CPU0_SB_DQS_DN<4>")
	)
	(arc
		(start 347.080078 -244.412262)
		(mid 346.89288 -244.362119)
		(end 346.705682 -244.412262)
		(width 0.088646)
		(layer "In11.Cu")
		(net "M_D_CPU0_SB_DQS_DN<4>")
	)
	(arc
		(start 333.078582 -243.598446)
		(mid 332.94234 -243.65488)
		(end 332.796134 -243.674138)
		(width 0.088646)
		(layer "In11.Cu")
		(net "M_D_CPU0_SB_DQS_DN<4>")
	)
	(arc
		(start 340.501732 -244.412262)
		(mid 340.314534 -244.362119)
		(end 340.127336 -244.412262)
		(width 0.088646)
		(layer "In11.Cu")
		(net "M_D_CPU0_SB_DQS_DN<4>")
	)
	(arc
		(start 336.742278 -244.412262)
		(mid 336.55508 -244.362119)
		(end 336.367882 -244.412262)
		(width 0.088646)
		(layer "In11.Cu")
		(net "M_D_CPU0_SB_DQS_DN<4>")
	)
	(arc
		(start 347.26753 -244.73662)
		(mid 347.219851 -244.55372)
		(end 347.088968 -244.417342)
		(width 0.088646)
		(layer "In11.Cu")
		(net "M_D_CPU0_SB_DQS_DN<4>")
	)
	(arc
		(start 336.35315 -244.420898)
		(mid 336.076675 -244.488218)
		(end 335.802478 -244.412262)
		(width 0.088646)
		(layer "In11.Cu")
		(net "M_D_CPU0_SB_DQS_DN<4>")
	)
	(arc
		(start 333.922878 -244.412262)
		(mid 333.718543 -244.209657)
		(end 333.64043 -243.93271)
		(width 0.088646)
		(layer "In11.Cu")
		(net "M_D_CPU0_SB_DQS_DN<4>")
	)
	(arc
		(start 345.200732 -244.412262)
		(mid 345.013534 -244.362119)
		(end 344.826336 -244.412262)
		(width 0.088646)
		(layer "In11.Cu")
		(net "M_D_CPU0_SB_DQS_DN<4>")
	)
	(arc
		(start 348.394528 -244.801644)
		(mid 348.393233 -244.812325)
		(end 348.391734 -244.82298)
		(width 0.088646)
		(layer "In11.Cu")
		(net "M_D_CPU0_SB_DQS_DN<4>")
	)
	(segment
		(start 258.040124 -200.553066)
		(end 257.404108 -200.12787)
		(width 0.20066)
		(layer "F.Cu")
		(net "M_D_CPU0_SB_DQS_DN<3>")
	)
	(segment
		(start 263.077706 -199.866758)
		(end 262.816594 -200.12787)
		(width 0.20066)
		(layer "F.Cu")
		(net "M_D_CPU0_SB_DQS_DN<3>")
	)
	(segment
		(start 256.629154 -199.866758)
		(end 256.080514 -199.866758)
		(width 0.20066)
		(layer "F.Cu")
		(net "M_D_CPU0_SB_DQS_DN<3>")
	)
	(segment
		(start 257.404108 -200.12787)
		(end 256.890266 -200.12787)
		(width 0.20066)
		(layer "F.Cu")
		(net "M_D_CPU0_SB_DQS_DN<3>")
	)
	(segment
		(start 261.381494 -200.2917)
		(end 259.067808 -200.2917)
		(width 0.1016)
		(layer "F.Cu")
		(net "M_D_CPU0_SB_DQS_DN<3>")
	)
	(segment
		(start 264.729214 -199.866758)
		(end 263.624314 -199.866758)
		(width 0.20066)
		(layer "F.Cu")
		(net "M_D_CPU0_SB_DQS_DN<3>")
	)
	(segment
		(start 256.890266 -200.12787)
		(end 256.629154 -199.866758)
		(width 0.20066)
		(layer "F.Cu")
		(net "M_D_CPU0_SB_DQS_DN<3>")
	)
	(segment
		(start 262.40994 -200.12787)
		(end 261.984744 -200.553066)
		(width 0.20066)
		(layer "F.Cu")
		(net "M_D_CPU0_SB_DQS_DN<3>")
	)
	(segment
		(start 259.056378 -200.281032)
		(end 258.852162 -200.281032)
		(width 0.20066)
		(layer "F.Cu")
		(net "M_D_CPU0_SB_DQS_DN<3>")
	)
	(segment
		(start 345.953334 -230.622602)
		(end 345.95308 -230.622348)
		(width 0.20066)
		(layer "F.Cu")
		(net "M_D_CPU0_SB_DQS_DN<3>")
	)
	(segment
		(start 258.580128 -200.553066)
		(end 258.040124 -200.553066)
		(width 0.20066)
		(layer "F.Cu")
		(net "M_D_CPU0_SB_DQS_DN<3>")
	)
	(segment
		(start 259.067808 -200.2917)
		(end 259.05714 -200.281032)
		(width 0.101854)
		(layer "F.Cu")
		(net "M_D_CPU0_SB_DQS_DN<3>")
	)
	(segment
		(start 261.984744 -200.553066)
		(end 261.798054 -200.553066)
		(width 0.20066)
		(layer "F.Cu")
		(net "M_D_CPU0_SB_DQS_DN<3>")
	)
	(segment
		(start 261.536688 -200.2917)
		(end 261.381494 -200.2917)
		(width 0.20066)
		(layer "F.Cu")
		(net "M_D_CPU0_SB_DQS_DN<3>")
	)
	(segment
		(start 263.624314 -199.866758)
		(end 263.077706 -199.866758)
		(width 0.20066)
		(layer "F.Cu")
		(net "M_D_CPU0_SB_DQS_DN<3>")
	)
	(segment
		(start 345.95308 -230.622348)
		(end 345.95308 -230.086662)
		(width 0.20066)
		(layer "F.Cu")
		(net "M_D_CPU0_SB_DQS_DN<3>")
	)
	(segment
		(start 258.852162 -200.281032)
		(end 258.580128 -200.553066)
		(width 0.20066)
		(layer "F.Cu")
		(net "M_D_CPU0_SB_DQS_DN<3>")
	)
	(segment
		(start 261.798054 -200.553066)
		(end 261.536688 -200.2917)
		(width 0.20066)
		(layer "F.Cu")
		(net "M_D_CPU0_SB_DQS_DN<3>")
	)
	(segment
		(start 259.05714 -200.281032)
		(end 259.056378 -200.281032)
		(width 0.101854)
		(layer "F.Cu")
		(net "M_D_CPU0_SB_DQS_DN<3>")
	)
	(segment
		(start 262.816594 -200.12787)
		(end 262.40994 -200.12787)
		(width 0.20066)
		(layer "F.Cu")
		(net "M_D_CPU0_SB_DQS_DN<3>")
	)
	(segment
		(start 338.166964 -227.960682)
		(end 338.152232 -227.969318)
		(width 0.088646)
		(layer "In11.Cu")
		(net "M_D_CPU0_SB_DQS_DN<3>")
	)
	(segment
		(start 292.447218 -199.611996)
		(end 286.355028 -199.611996)
		(width 0.18288)
		(layer "In11.Cu")
		(net "M_D_CPU0_SB_DQS_DN<3>")
	)
	(segment
		(start 265.655552 -200.0377)
		(end 265.448796 -200.123552)
		(width 0.18288)
		(layer "In11.Cu")
		(net "M_D_CPU0_SB_DQS_DN<3>")
	)
	(segment
		(start 316.756288 -207.424274)
		(end 316.36843 -207.036416)
		(width 0.18288)
		(layer "In11.Cu")
		(net "M_D_CPU0_SB_DQS_DN<3>")
	)
	(segment
		(start 270.538702 -200.551288)
		(end 269.371064 -200.551288)
		(width 0.18288)
		(layer "In11.Cu")
		(net "M_D_CPU0_SB_DQS_DN<3>")
	)
	(segment
		(start 341.926164 -227.960682)
		(end 341.911432 -227.969318)
		(width 0.088646)
		(layer "In11.Cu")
		(net "M_D_CPU0_SB_DQS_DN<3>")
	)
	(segment
		(start 330.642976 -224.717864)
		(end 330.642976 -224.633282)
		(width 0.088646)
		(layer "In11.Cu")
		(net "M_D_CPU0_SB_DQS_DN<3>")
	)
	(segment
		(start 315.804296 -206.472282)
		(end 315.416438 -206.084424)
		(width 0.18288)
		(layer "In11.Cu")
		(net "M_D_CPU0_SB_DQS_DN<3>")
	)
	(segment
		(start 345.95308 -230.086662)
		(end 345.935046 -230.086662)
		(width 0.088646)
		(layer "In11.Cu")
		(net "M_D_CPU0_SB_DQS_DN<3>")
	)
	(segment
		(start 301.095664 -200.317608)
		(end 300.590712 -200.531476)
		(width 0.18288)
		(layer "In11.Cu")
		(net "M_D_CPU0_SB_DQS_DN<3>")
	)
	(segment
		(start 298.070778 -200.618852)
		(end 296.277538 -198.825612)
		(width 0.18288)
		(layer "In11.Cu")
		(net "M_D_CPU0_SB_DQS_DN<3>")
	)
	(segment
		(start 322.46824 -216.458546)
		(end 322.46824 -213.136226)
		(width 0.18288)
		(layer "In11.Cu")
		(net "M_D_CPU0_SB_DQS_DN<3>")
	)
	(segment
		(start 277.18131 -199.65543)
		(end 274.477734 -199.65543)
		(width 0.18288)
		(layer "In11.Cu")
		(net "M_D_CPU0_SB_DQS_DN<3>")
	)
	(segment
		(start 299.226986 -200.288398)
		(end 298.801282 -200.288398)
		(width 0.18288)
		(layer "In11.Cu")
		(net "M_D_CPU0_SB_DQS_DN<3>")
	)
	(segment
		(start 283.717492 -200.294748)
		(end 283.439108 -200.573132)
		(width 0.18288)
		(layer "In11.Cu")
		(net "M_D_CPU0_SB_DQS_DN<3>")
	)
	(segment
		(start 274.477734 -199.65543)
		(end 270.538702 -200.551288)
		(width 0.18288)
		(layer "In11.Cu")
		(net "M_D_CPU0_SB_DQS_DN<3>")
	)
	(segment
		(start 304.36566 -199.308212)
		(end 303.4792 -199.308212)
		(width 0.18288)
		(layer "In11.Cu")
		(net "M_D_CPU0_SB_DQS_DN<3>")
	)
	(segment
		(start 331.190092 -225.26498)
		(end 330.642976 -224.717864)
		(width 0.088646)
		(layer "In11.Cu")
		(net "M_D_CPU0_SB_DQS_DN<3>")
	)
	(segment
		(start 345.935046 -230.086662)
		(end 345.599766 -229.77221)
		(width 0.088646)
		(layer "In11.Cu")
		(net "M_D_CPU0_SB_DQS_DN<3>")
	)
	(segment
		(start 317.320422 -207.988408)
		(end 317.320422 -207.812386)
		(width 0.18288)
		(layer "In11.Cu")
		(net "M_D_CPU0_SB_DQS_DN<3>")
	)
	(segment
		(start 268.381226 -200.52919)
		(end 268.20749 -200.52919)
		(width 0.18288)
		(layer "In11.Cu")
		(net "M_D_CPU0_SB_DQS_DN<3>")
	)
	(segment
		(start 303.4792 -199.308212)
		(end 301.830486 -200.006458)
		(width 0.18288)
		(layer "In11.Cu")
		(net "M_D_CPU0_SB_DQS_DN<3>")
	)
	(segment
		(start 296.277538 -198.825612)
		(end 295.369234 -198.825612)
		(width 0.18288)
		(layer "In11.Cu")
		(net "M_D_CPU0_SB_DQS_DN<3>")
	)
	(segment
		(start 345.108784 -229.2731)
		(end 345.108784 -229.272846)
		(width 0.088646)
		(layer "In11.Cu")
		(net "M_D_CPU0_SB_DQS_DN<3>")
	)
	(segment
		(start 344.826844 -228.783896)
		(end 344.826082 -228.783388)
		(width 0.088646)
		(layer "In11.Cu")
		(net "M_D_CPU0_SB_DQS_DN<3>")
	)
	(segment
		(start 344.63863 -228.45903)
		(end 344.63863 -228.436932)
		(width 0.088646)
		(layer "In11.Cu")
		(net "M_D_CPU0_SB_DQS_DN<3>")
	)
	(segment
		(start 283.439108 -200.573132)
		(end 283.09697 -200.573132)
		(width 0.18288)
		(layer "In11.Cu")
		(net "M_D_CPU0_SB_DQS_DN<3>")
	)
	(segment
		(start 307.062378 -199.837294)
		(end 305.785012 -199.308212)
		(width 0.18288)
		(layer "In11.Cu")
		(net "M_D_CPU0_SB_DQS_DN<3>")
	)
	(segment
		(start 298.801282 -200.288398)
		(end 298.470828 -200.618852)
		(width 0.18288)
		(layer "In11.Cu")
		(net "M_D_CPU0_SB_DQS_DN<3>")
	)
	(segment
		(start 321.12839 -211.620354)
		(end 320.740278 -211.232242)
		(width 0.18288)
		(layer "In11.Cu")
		(net "M_D_CPU0_SB_DQS_DN<3>")
	)
	(segment
		(start 332.621636 -226.21621)
		(end 331.868526 -226.21621)
		(width 0.088646)
		(layer "In11.Cu")
		(net "M_D_CPU0_SB_DQS_DN<3>")
	)
	(segment
		(start 319.788286 -210.28025)
		(end 319.612264 -210.28025)
		(width 0.18288)
		(layer "In11.Cu")
		(net "M_D_CPU0_SB_DQS_DN<3>")
	)
	(segment
		(start 305.785012 -199.308212)
		(end 305.16322 -199.308212)
		(width 0.18288)
		(layer "In11.Cu")
		(net "M_D_CPU0_SB_DQS_DN<3>")
	)
	(segment
		(start 330.642976 -224.633282)
		(end 322.46824 -216.458546)
		(width 0.18288)
		(layer "In11.Cu")
		(net "M_D_CPU0_SB_DQS_DN<3>")
	)
	(segment
		(start 286.355028 -199.611996)
		(end 285.676086 -200.290938)
		(width 0.18288)
		(layer "In11.Cu")
		(net "M_D_CPU0_SB_DQS_DN<3>")
	)
	(segment
		(start 320.740278 -211.232242)
		(end 320.564256 -211.232242)
		(width 0.18288)
		(layer "In11.Cu")
		(net "M_D_CPU0_SB_DQS_DN<3>")
	)
	(segment
		(start 309.755032 -200.130156)
		(end 309.048912 -199.837294)
		(width 0.18288)
		(layer "In11.Cu")
		(net "M_D_CPU0_SB_DQS_DN<3>")
	)
	(segment
		(start 331.190092 -225.537776)
		(end 331.190092 -225.26498)
		(width 0.088646)
		(layer "In11.Cu")
		(net "M_D_CPU0_SB_DQS_DN<3>")
	)
	(segment
		(start 316.36843 -207.036416)
		(end 316.36843 -206.860394)
		(width 0.18288)
		(layer "In11.Cu")
		(net "M_D_CPU0_SB_DQS_DN<3>")
	)
	(segment
		(start 322.080382 -212.748368)
		(end 322.080382 -212.572346)
		(width 0.18288)
		(layer "In11.Cu")
		(net "M_D_CPU0_SB_DQS_DN<3>")
	)
	(segment
		(start 280.05913 -198.590408)
		(end 279.602946 -198.590408)
		(width 0.18288)
		(layer "In11.Cu")
		(net "M_D_CPU0_SB_DQS_DN<3>")
	)
	(segment
		(start 317.320422 -207.812386)
		(end 316.93231 -207.424274)
		(width 0.18288)
		(layer "In11.Cu")
		(net "M_D_CPU0_SB_DQS_DN<3>")
	)
	(segment
		(start 321.12839 -211.796376)
		(end 321.12839 -211.620354)
		(width 0.18288)
		(layer "In11.Cu")
		(net "M_D_CPU0_SB_DQS_DN<3>")
	)
	(segment
		(start 310.801004 -201.176128)
		(end 309.755032 -200.130156)
		(width 0.18288)
		(layer "In11.Cu")
		(net "M_D_CPU0_SB_DQS_DN<3>")
	)
	(segment
		(start 279.094438 -198.919846)
		(end 277.18131 -199.65543)
		(width 0.18288)
		(layer "In11.Cu")
		(net "M_D_CPU0_SB_DQS_DN<3>")
	)
	(segment
		(start 284.405832 -200.559924)
		(end 284.140656 -200.294748)
		(width 0.18288)
		(layer "In11.Cu")
		(net "M_D_CPU0_SB_DQS_DN<3>")
	)
	(segment
		(start 301.667418 -199.940418)
		(end 301.161958 -200.154286)
		(width 0.18288)
		(layer "In11.Cu")
		(net "M_D_CPU0_SB_DQS_DN<3>")
	)
	(segment
		(start 294.686482 -198.592948)
		(end 294.408098 -198.871332)
		(width 0.18288)
		(layer "In11.Cu")
		(net "M_D_CPU0_SB_DQS_DN<3>")
	)
	(segment
		(start 312.942224 -203.61021)
		(end 311.889648 -203.174092)
		(width 0.18288)
		(layer "In11.Cu")
		(net "M_D_CPU0_SB_DQS_DN<3>")
	)
	(segment
		(start 315.416438 -205.908402)
		(end 315.028326 -205.52029)
		(width 0.18288)
		(layer "In11.Cu")
		(net "M_D_CPU0_SB_DQS_DN<3>")
	)
	(segment
		(start 309.048912 -199.837294)
		(end 307.062378 -199.837294)
		(width 0.18288)
		(layer "In11.Cu")
		(net "M_D_CPU0_SB_DQS_DN<3>")
	)
	(segment
		(start 265.448796 -200.123552)
		(end 264.986008 -200.123552)
		(width 0.18288)
		(layer "In11.Cu")
		(net "M_D_CPU0_SB_DQS_DN<3>")
	)
	(segment
		(start 269.371064 -200.551288)
		(end 269.112238 -200.292462)
		(width 0.18288)
		(layer "In11.Cu")
		(net "M_D_CPU0_SB_DQS_DN<3>")
	)
	(segment
		(start 268.617954 -200.292462)
		(end 268.381226 -200.52919)
		(width 0.18288)
		(layer "In11.Cu")
		(net "M_D_CPU0_SB_DQS_DN<3>")
	)
	(segment
		(start 344.826082 -228.783388)
		(end 344.824558 -228.782626)
		(width 0.088646)
		(layer "In11.Cu")
		(net "M_D_CPU0_SB_DQS_DN<3>")
	)
	(segment
		(start 340.041992 -227.963222)
		(end 340.031578 -227.969318)
		(width 0.088646)
		(layer "In11.Cu")
		(net "M_D_CPU0_SB_DQS_DN<3>")
	)
	(segment
		(start 336.287364 -227.960682)
		(end 336.272632 -227.969318)
		(width 0.088646)
		(layer "In11.Cu")
		(net "M_D_CPU0_SB_DQS_DN<3>")
	)
	(segment
		(start 319.612264 -210.28025)
		(end 319.224406 -209.892392)
		(width 0.18288)
		(layer "In11.Cu")
		(net "M_D_CPU0_SB_DQS_DN<3>")
	)
	(segment
		(start 295.369234 -198.825612)
		(end 295.13657 -198.592948)
		(width 0.18288)
		(layer "In11.Cu")
		(net "M_D_CPU0_SB_DQS_DN<3>")
	)
	(segment
		(start 321.516248 -212.184234)
		(end 321.12839 -211.796376)
		(width 0.18288)
		(layer "In11.Cu")
		(net "M_D_CPU0_SB_DQS_DN<3>")
	)
	(segment
		(start 344.832178 -228.786944)
		(end 344.826844 -228.783896)
		(width 0.088646)
		(layer "In11.Cu")
		(net "M_D_CPU0_SB_DQS_DN<3>")
	)
	(segment
		(start 335.898236 -227.969318)
		(end 335.889346 -227.964238)
		(width 0.088646)
		(layer "In11.Cu")
		(net "M_D_CPU0_SB_DQS_DN<3>")
	)
	(segment
		(start 317.70828 -208.376266)
		(end 317.320422 -207.988408)
		(width 0.18288)
		(layer "In11.Cu")
		(net "M_D_CPU0_SB_DQS_DN<3>")
	)
	(segment
		(start 301.161958 -200.154286)
		(end 301.095664 -200.317608)
		(width 0.18288)
		(layer "In11.Cu")
		(net "M_D_CPU0_SB_DQS_DN<3>")
	)
	(segment
		(start 285.676086 -200.290938)
		(end 285.027624 -200.559924)
		(width 0.18288)
		(layer "In11.Cu")
		(net "M_D_CPU0_SB_DQS_DN<3>")
	)
	(segment
		(start 345.599766 -229.77221)
		(end 345.295982 -229.597458)
		(width 0.088646)
		(layer "In11.Cu")
		(net "M_D_CPU0_SB_DQS_DN<3>")
	)
	(segment
		(start 319.224406 -209.892392)
		(end 319.224406 -209.71637)
		(width 0.18288)
		(layer "In11.Cu")
		(net "M_D_CPU0_SB_DQS_DN<3>")
	)
	(segment
		(start 279.273508 -198.919846)
		(end 279.094438 -198.919846)
		(width 0.18288)
		(layer "In11.Cu")
		(net "M_D_CPU0_SB_DQS_DN<3>")
	)
	(segment
		(start 318.272414 -208.764378)
		(end 317.884302 -208.376266)
		(width 0.18288)
		(layer "In11.Cu")
		(net "M_D_CPU0_SB_DQS_DN<3>")
	)
	(segment
		(start 301.830486 -200.006458)
		(end 301.667418 -199.940418)
		(width 0.18288)
		(layer "In11.Cu")
		(net "M_D_CPU0_SB_DQS_DN<3>")
	)
	(segment
		(start 334.970374 -226.348798)
		(end 334.958182 -226.341686)
		(width 0.088646)
		(layer "In11.Cu")
		(net "M_D_CPU0_SB_DQS_DN<3>")
	)
	(segment
		(start 304.49012 -199.183752)
		(end 304.36566 -199.308212)
		(width 0.18288)
		(layer "In11.Cu")
		(net "M_D_CPU0_SB_DQS_DN<3>")
	)
	(segment
		(start 342.865964 -227.960682)
		(end 342.851232 -227.969318)
		(width 0.088646)
		(layer "In11.Cu")
		(net "M_D_CPU0_SB_DQS_DN<3>")
	)
	(segment
		(start 280.786586 -198.901558)
		(end 280.37028 -198.901558)
		(width 0.18288)
		(layer "In11.Cu")
		(net "M_D_CPU0_SB_DQS_DN<3>")
	)
	(segment
		(start 318.660272 -209.328258)
		(end 318.272414 -208.9404)
		(width 0.18288)
		(layer "In11.Cu")
		(net "M_D_CPU0_SB_DQS_DN<3>")
	)
	(segment
		(start 318.836294 -209.328258)
		(end 318.660272 -209.328258)
		(width 0.18288)
		(layer "In11.Cu")
		(net "M_D_CPU0_SB_DQS_DN<3>")
	)
	(segment
		(start 343.805764 -227.960682)
		(end 343.791032 -227.969318)
		(width 0.088646)
		(layer "In11.Cu")
		(net "M_D_CPU0_SB_DQS_DN<3>")
	)
	(segment
		(start 311.444386 -202.72883)
		(end 310.801004 -201.176128)
		(width 0.18288)
		(layer "In11.Cu")
		(net "M_D_CPU0_SB_DQS_DN<3>")
	)
	(segment
		(start 316.93231 -207.424274)
		(end 316.756288 -207.424274)
		(width 0.18288)
		(layer "In11.Cu")
		(net "M_D_CPU0_SB_DQS_DN<3>")
	)
	(segment
		(start 269.112238 -200.292462)
		(end 268.617954 -200.292462)
		(width 0.18288)
		(layer "In11.Cu")
		(net "M_D_CPU0_SB_DQS_DN<3>")
	)
	(segment
		(start 295.13657 -198.592948)
		(end 294.686482 -198.592948)
		(width 0.18288)
		(layer "In11.Cu")
		(net "M_D_CPU0_SB_DQS_DN<3>")
	)
	(segment
		(start 317.884302 -208.376266)
		(end 317.70828 -208.376266)
		(width 0.18288)
		(layer "In11.Cu")
		(net "M_D_CPU0_SB_DQS_DN<3>")
	)
	(segment
		(start 264.986008 -200.123552)
		(end 264.729214 -199.866758)
		(width 0.18288)
		(layer "In11.Cu")
		(net "M_D_CPU0_SB_DQS_DN<3>")
	)
	(segment
		(start 314.852304 -205.52029)
		(end 312.942224 -203.61021)
		(width 0.18288)
		(layer "In11.Cu")
		(net "M_D_CPU0_SB_DQS_DN<3>")
	)
	(segment
		(start 315.028326 -205.52029)
		(end 314.852304 -205.52029)
		(width 0.18288)
		(layer "In11.Cu")
		(net "M_D_CPU0_SB_DQS_DN<3>")
	)
	(segment
		(start 266.700508 -199.904858)
		(end 265.977116 -199.904858)
		(width 0.18288)
		(layer "In11.Cu")
		(net "M_D_CPU0_SB_DQS_DN<3>")
	)
	(segment
		(start 337.227164 -227.960682)
		(end 337.212432 -227.969318)
		(width 0.088646)
		(layer "In11.Cu")
		(net "M_D_CPU0_SB_DQS_DN<3>")
	)
	(segment
		(start 305.16322 -199.308212)
		(end 305.03876 -199.183752)
		(width 0.18288)
		(layer "In11.Cu")
		(net "M_D_CPU0_SB_DQS_DN<3>")
	)
	(segment
		(start 335.428336 -227.155502)
		(end 335.419446 -227.150422)
		(width 0.088646)
		(layer "In11.Cu")
		(net "M_D_CPU0_SB_DQS_DN<3>")
	)
	(segment
		(start 316.36843 -206.860394)
		(end 315.980318 -206.472282)
		(width 0.18288)
		(layer "In11.Cu")
		(net "M_D_CPU0_SB_DQS_DN<3>")
	)
	(segment
		(start 284.140656 -200.294748)
		(end 283.717492 -200.294748)
		(width 0.18288)
		(layer "In11.Cu")
		(net "M_D_CPU0_SB_DQS_DN<3>")
	)
	(segment
		(start 265.977116 -199.904858)
		(end 265.655552 -200.0377)
		(width 0.18288)
		(layer "In11.Cu")
		(net "M_D_CPU0_SB_DQS_DN<3>")
	)
	(segment
		(start 311.889648 -203.174092)
		(end 311.444386 -202.72883)
		(width 0.18288)
		(layer "In11.Cu")
		(net "M_D_CPU0_SB_DQS_DN<3>")
	)
	(segment
		(start 320.176398 -210.844384)
		(end 320.176398 -210.668362)
		(width 0.18288)
		(layer "In11.Cu")
		(net "M_D_CPU0_SB_DQS_DN<3>")
	)
	(segment
		(start 305.03876 -199.183752)
		(end 304.49012 -199.183752)
		(width 0.18288)
		(layer "In11.Cu")
		(net "M_D_CPU0_SB_DQS_DN<3>")
	)
	(segment
		(start 315.980318 -206.472282)
		(end 315.804296 -206.472282)
		(width 0.18288)
		(layer "In11.Cu")
		(net "M_D_CPU0_SB_DQS_DN<3>")
	)
	(segment
		(start 320.176398 -210.668362)
		(end 319.788286 -210.28025)
		(width 0.18288)
		(layer "In11.Cu")
		(net "M_D_CPU0_SB_DQS_DN<3>")
	)
	(segment
		(start 300.590712 -200.531476)
		(end 299.470064 -200.531476)
		(width 0.18288)
		(layer "In11.Cu")
		(net "M_D_CPU0_SB_DQS_DN<3>")
	)
	(segment
		(start 320.564256 -211.232242)
		(end 320.176398 -210.844384)
		(width 0.18288)
		(layer "In11.Cu")
		(net "M_D_CPU0_SB_DQS_DN<3>")
	)
	(segment
		(start 315.416438 -206.084424)
		(end 315.416438 -205.908402)
		(width 0.18288)
		(layer "In11.Cu")
		(net "M_D_CPU0_SB_DQS_DN<3>")
	)
	(segment
		(start 279.602946 -198.590408)
		(end 279.273508 -198.919846)
		(width 0.18288)
		(layer "In11.Cu")
		(net "M_D_CPU0_SB_DQS_DN<3>")
	)
	(segment
		(start 334.403446 -226.33559)
		(end 334.393032 -226.341686)
		(width 0.088646)
		(layer "In11.Cu")
		(net "M_D_CPU0_SB_DQS_DN<3>")
	)
	(segment
		(start 283.09697 -200.573132)
		(end 282.195016 -199.671178)
		(width 0.18288)
		(layer "In11.Cu")
		(net "M_D_CPU0_SB_DQS_DN<3>")
	)
	(segment
		(start 319.224406 -209.71637)
		(end 318.836294 -209.328258)
		(width 0.18288)
		(layer "In11.Cu")
		(net "M_D_CPU0_SB_DQS_DN<3>")
	)
	(segment
		(start 339.657182 -227.969318)
		(end 339.646768 -227.963222)
		(width 0.088646)
		(layer "In11.Cu")
		(net "M_D_CPU0_SB_DQS_DN<3>")
	)
	(segment
		(start 285.027624 -200.559924)
		(end 284.405832 -200.559924)
		(width 0.18288)
		(layer "In11.Cu")
		(net "M_D_CPU0_SB_DQS_DN<3>")
	)
	(segment
		(start 299.470064 -200.531476)
		(end 299.226986 -200.288398)
		(width 0.18288)
		(layer "In11.Cu")
		(net "M_D_CPU0_SB_DQS_DN<3>")
	)
	(segment
		(start 294.408098 -198.871332)
		(end 294.233854 -198.871332)
		(width 0.18288)
		(layer "In11.Cu")
		(net "M_D_CPU0_SB_DQS_DN<3>")
	)
	(segment
		(start 280.37028 -198.901558)
		(end 280.05913 -198.590408)
		(width 0.18288)
		(layer "In11.Cu")
		(net "M_D_CPU0_SB_DQS_DN<3>")
	)
	(segment
		(start 331.868526 -226.21621)
		(end 331.190092 -225.537776)
		(width 0.088646)
		(layer "In11.Cu")
		(net "M_D_CPU0_SB_DQS_DN<3>")
	)
	(segment
		(start 340.986364 -227.960682)
		(end 340.971632 -227.969318)
		(width 0.088646)
		(layer "In11.Cu")
		(net "M_D_CPU0_SB_DQS_DN<3>")
	)
	(segment
		(start 268.20749 -200.52919)
		(end 266.700508 -199.904858)
		(width 0.18288)
		(layer "In11.Cu")
		(net "M_D_CPU0_SB_DQS_DN<3>")
	)
	(segment
		(start 322.46824 -213.136226)
		(end 322.080382 -212.748368)
		(width 0.18288)
		(layer "In11.Cu")
		(net "M_D_CPU0_SB_DQS_DN<3>")
	)
	(segment
		(start 318.272414 -208.9404)
		(end 318.272414 -208.764378)
		(width 0.18288)
		(layer "In11.Cu")
		(net "M_D_CPU0_SB_DQS_DN<3>")
	)
	(segment
		(start 322.080382 -212.572346)
		(end 321.69227 -212.184234)
		(width 0.18288)
		(layer "In11.Cu")
		(net "M_D_CPU0_SB_DQS_DN<3>")
	)
	(segment
		(start 334.018636 -226.341686)
		(end 334.008222 -226.33559)
		(width 0.088646)
		(layer "In11.Cu")
		(net "M_D_CPU0_SB_DQS_DN<3>")
	)
	(segment
		(start 335.434432 -227.159058)
		(end 335.428336 -227.155502)
		(width 0.088646)
		(layer "In11.Cu")
		(net "M_D_CPU0_SB_DQS_DN<3>")
	)
	(segment
		(start 294.233854 -198.871332)
		(end 292.447218 -199.611996)
		(width 0.18288)
		(layer "In11.Cu")
		(net "M_D_CPU0_SB_DQS_DN<3>")
	)
	(segment
		(start 344.824558 -228.782626)
		(end 344.817192 -228.778308)
		(width 0.088646)
		(layer "In11.Cu")
		(net "M_D_CPU0_SB_DQS_DN<3>")
	)
	(segment
		(start 282.195016 -199.671178)
		(end 280.786586 -198.901558)
		(width 0.18288)
		(layer "In11.Cu")
		(net "M_D_CPU0_SB_DQS_DN<3>")
	)
	(segment
		(start 298.470828 -200.618852)
		(end 298.070778 -200.618852)
		(width 0.18288)
		(layer "In11.Cu")
		(net "M_D_CPU0_SB_DQS_DN<3>")
	)
	(segment
		(start 321.69227 -212.184234)
		(end 321.516248 -212.184234)
		(width 0.18288)
		(layer "In11.Cu")
		(net "M_D_CPU0_SB_DQS_DN<3>")
	)
	(arc
		(start 338.717636 -227.969318)
		(mid 338.443407 -227.893393)
		(end 338.166964 -227.960682)
		(width 0.088646)
		(layer "In11.Cu")
		(net "M_D_CPU0_SB_DQS_DN<3>")
	)
	(arc
		(start 339.092032 -227.969318)
		(mid 338.904834 -228.019461)
		(end 338.717636 -227.969318)
		(width 0.088646)
		(layer "In11.Cu")
		(net "M_D_CPU0_SB_DQS_DN<3>")
	)
	(arc
		(start 336.272632 -227.969318)
		(mid 336.085434 -228.019461)
		(end 335.898236 -227.969318)
		(width 0.088646)
		(layer "In11.Cu")
		(net "M_D_CPU0_SB_DQS_DN<3>")
	)
	(arc
		(start 338.152232 -227.969318)
		(mid 337.965034 -228.019461)
		(end 337.777836 -227.969318)
		(width 0.088646)
		(layer "In11.Cu")
		(net "M_D_CPU0_SB_DQS_DN<3>")
	)
	(arc
		(start 334.393032 -226.341686)
		(mid 334.205834 -226.391829)
		(end 334.018636 -226.341686)
		(width 0.088646)
		(layer "In11.Cu")
		(net "M_D_CPU0_SB_DQS_DN<3>")
	)
	(arc
		(start 345.295982 -229.597458)
		(mid 345.158957 -229.460345)
		(end 345.108784 -229.2731)
		(width 0.088646)
		(layer "In11.Cu")
		(net "M_D_CPU0_SB_DQS_DN<3>")
	)
	(arc
		(start 342.851232 -227.969318)
		(mid 342.664034 -228.019461)
		(end 342.476836 -227.969318)
		(width 0.088646)
		(layer "In11.Cu")
		(net "M_D_CPU0_SB_DQS_DN<3>")
	)
	(arc
		(start 341.911432 -227.969318)
		(mid 341.724234 -228.019461)
		(end 341.537036 -227.969318)
		(width 0.088646)
		(layer "In11.Cu")
		(net "M_D_CPU0_SB_DQS_DN<3>")
	)
	(arc
		(start 341.537036 -227.969318)
		(mid 341.262807 -227.893393)
		(end 340.986364 -227.960682)
		(width 0.088646)
		(layer "In11.Cu")
		(net "M_D_CPU0_SB_DQS_DN<3>")
	)
	(arc
		(start 344.817192 -228.778308)
		(mid 344.686278 -228.641948)
		(end 344.63863 -228.45903)
		(width 0.088646)
		(layer "In11.Cu")
		(net "M_D_CPU0_SB_DQS_DN<3>")
	)
	(arc
		(start 333.078582 -226.341686)
		(mid 332.85857 -226.24813)
		(end 332.621636 -226.21621)
		(width 0.088646)
		(layer "In11.Cu")
		(net "M_D_CPU0_SB_DQS_DN<3>")
	)
	(arc
		(start 334.958182 -226.341686)
		(mid 334.681623 -226.265943)
		(end 334.403446 -226.33559)
		(width 0.088646)
		(layer "In11.Cu")
		(net "M_D_CPU0_SB_DQS_DN<3>")
	)
	(arc
		(start 334.008222 -226.33559)
		(mid 333.72979 -226.265744)
		(end 333.452978 -226.341686)
		(width 0.088646)
		(layer "In11.Cu")
		(net "M_D_CPU0_SB_DQS_DN<3>")
	)
	(arc
		(start 336.838036 -227.969318)
		(mid 336.563807 -227.893393)
		(end 336.287364 -227.960682)
		(width 0.088646)
		(layer "In11.Cu")
		(net "M_D_CPU0_SB_DQS_DN<3>")
	)
	(arc
		(start 340.971632 -227.969318)
		(mid 340.784434 -228.019461)
		(end 340.597236 -227.969318)
		(width 0.088646)
		(layer "In11.Cu")
		(net "M_D_CPU0_SB_DQS_DN<3>")
	)
	(arc
		(start 343.416636 -227.969318)
		(mid 343.142407 -227.893393)
		(end 342.865964 -227.960682)
		(width 0.088646)
		(layer "In11.Cu")
		(net "M_D_CPU0_SB_DQS_DN<3>")
	)
	(arc
		(start 335.240884 -226.831144)
		(mid 335.168649 -226.55462)
		(end 334.970374 -226.348798)
		(width 0.088646)
		(layer "In11.Cu")
		(net "M_D_CPU0_SB_DQS_DN<3>")
	)
	(arc
		(start 337.212432 -227.969318)
		(mid 337.025234 -228.019461)
		(end 336.838036 -227.969318)
		(width 0.088646)
		(layer "In11.Cu")
		(net "M_D_CPU0_SB_DQS_DN<3>")
	)
	(arc
		(start 335.889346 -227.964238)
		(mid 335.758432 -227.827878)
		(end 335.710784 -227.64496)
		(width 0.088646)
		(layer "In11.Cu")
		(net "M_D_CPU0_SB_DQS_DN<3>")
	)
	(arc
		(start 340.597236 -227.969318)
		(mid 340.320423 -227.893482)
		(end 340.041992 -227.963222)
		(width 0.088646)
		(layer "In11.Cu")
		(net "M_D_CPU0_SB_DQS_DN<3>")
	)
	(arc
		(start 342.476836 -227.969318)
		(mid 342.202607 -227.893393)
		(end 341.926164 -227.960682)
		(width 0.088646)
		(layer "In11.Cu")
		(net "M_D_CPU0_SB_DQS_DN<3>")
	)
	(arc
		(start 335.419446 -227.150422)
		(mid 335.288532 -227.014062)
		(end 335.240884 -226.831144)
		(width 0.088646)
		(layer "In11.Cu")
		(net "M_D_CPU0_SB_DQS_DN<3>")
	)
	(arc
		(start 335.710784 -227.64496)
		(mid 335.636868 -227.365458)
		(end 335.434432 -227.159058)
		(width 0.088646)
		(layer "In11.Cu")
		(net "M_D_CPU0_SB_DQS_DN<3>")
	)
	(arc
		(start 340.031578 -227.969318)
		(mid 339.84438 -228.019461)
		(end 339.657182 -227.969318)
		(width 0.088646)
		(layer "In11.Cu")
		(net "M_D_CPU0_SB_DQS_DN<3>")
	)
	(arc
		(start 337.777836 -227.969318)
		(mid 337.503607 -227.893393)
		(end 337.227164 -227.960682)
		(width 0.088646)
		(layer "In11.Cu")
		(net "M_D_CPU0_SB_DQS_DN<3>")
	)
	(arc
		(start 339.646768 -227.963222)
		(mid 339.36859 -227.89353)
		(end 339.092032 -227.969318)
		(width 0.088646)
		(layer "In11.Cu")
		(net "M_D_CPU0_SB_DQS_DN<3>")
	)
	(arc
		(start 343.791032 -227.969318)
		(mid 343.603834 -228.019461)
		(end 343.416636 -227.969318)
		(width 0.088646)
		(layer "In11.Cu")
		(net "M_D_CPU0_SB_DQS_DN<3>")
	)
	(arc
		(start 344.63863 -228.436932)
		(mid 344.557719 -228.166804)
		(end 344.356436 -227.969318)
		(width 0.088646)
		(layer "In11.Cu")
		(net "M_D_CPU0_SB_DQS_DN<3>")
	)
	(arc
		(start 344.356436 -227.969318)
		(mid 344.082207 -227.893393)
		(end 343.805764 -227.960682)
		(width 0.088646)
		(layer "In11.Cu")
		(net "M_D_CPU0_SB_DQS_DN<3>")
	)
	(arc
		(start 345.108784 -229.272846)
		(mid 345.034793 -228.99328)
		(end 344.832178 -228.786944)
		(width 0.088646)
		(layer "In11.Cu")
		(net "M_D_CPU0_SB_DQS_DN<3>")
	)
	(arc
		(start 333.452978 -226.341686)
		(mid 333.26578 -226.391829)
		(end 333.078582 -226.341686)
		(width 0.088646)
		(layer "In11.Cu")
		(net "M_D_CPU0_SB_DQS_DN<3>")
	)
	(segment
		(start 264.729214 -209.216752)
		(end 263.624314 -209.216752)
		(width 0.20066)
		(layer "F.Cu")
		(net "M_D_CPU0_SB_DQS_DN<2>")
	)
	(segment
		(start 256.890266 -209.477864)
		(end 256.629154 -209.216752)
		(width 0.20066)
		(layer "F.Cu")
		(net "M_D_CPU0_SB_DQS_DN<2>")
	)
	(segment
		(start 262.816594 -209.477864)
		(end 262.40994 -209.477864)
		(width 0.20066)
		(layer "F.Cu")
		(net "M_D_CPU0_SB_DQS_DN<2>")
	)
	(segment
		(start 262.40994 -209.477864)
		(end 261.984744 -209.90306)
		(width 0.20066)
		(layer "F.Cu")
		(net "M_D_CPU0_SB_DQS_DN<2>")
	)
	(segment
		(start 261.984744 -209.90306)
		(end 261.798054 -209.90306)
		(width 0.20066)
		(layer "F.Cu")
		(net "M_D_CPU0_SB_DQS_DN<2>")
	)
	(segment
		(start 263.624314 -209.216752)
		(end 263.077706 -209.216752)
		(width 0.20066)
		(layer "F.Cu")
		(net "M_D_CPU0_SB_DQS_DN<2>")
	)
	(segment
		(start 261.536688 -209.641694)
		(end 261.381494 -209.641694)
		(width 0.20066)
		(layer "F.Cu")
		(net "M_D_CPU0_SB_DQS_DN<2>")
	)
	(segment
		(start 261.798054 -209.90306)
		(end 261.536688 -209.641694)
		(width 0.20066)
		(layer "F.Cu")
		(net "M_D_CPU0_SB_DQS_DN<2>")
	)
	(segment
		(start 258.852162 -209.631026)
		(end 258.580128 -209.90306)
		(width 0.20066)
		(layer "F.Cu")
		(net "M_D_CPU0_SB_DQS_DN<2>")
	)
	(segment
		(start 259.056378 -209.631026)
		(end 258.852162 -209.631026)
		(width 0.20066)
		(layer "F.Cu")
		(net "M_D_CPU0_SB_DQS_DN<2>")
	)
	(segment
		(start 342.66378 -233.064304)
		(end 342.664034 -233.06405)
		(width 0.20066)
		(layer "F.Cu")
		(net "M_D_CPU0_SB_DQS_DN<2>")
	)
	(segment
		(start 259.05714 -209.631026)
		(end 259.056378 -209.631026)
		(width 0.101854)
		(layer "F.Cu")
		(net "M_D_CPU0_SB_DQS_DN<2>")
	)
	(segment
		(start 257.404108 -209.477864)
		(end 256.890266 -209.477864)
		(width 0.20066)
		(layer "F.Cu")
		(net "M_D_CPU0_SB_DQS_DN<2>")
	)
	(segment
		(start 256.629154 -209.216752)
		(end 256.080514 -209.216752)
		(width 0.20066)
		(layer "F.Cu")
		(net "M_D_CPU0_SB_DQS_DN<2>")
	)
	(segment
		(start 259.067808 -209.641694)
		(end 259.05714 -209.631026)
		(width 0.101854)
		(layer "F.Cu")
		(net "M_D_CPU0_SB_DQS_DN<2>")
	)
	(segment
		(start 258.580128 -209.90306)
		(end 258.040124 -209.90306)
		(width 0.20066)
		(layer "F.Cu")
		(net "M_D_CPU0_SB_DQS_DN<2>")
	)
	(segment
		(start 261.381494 -209.641694)
		(end 259.067808 -209.641694)
		(width 0.1016)
		(layer "F.Cu")
		(net "M_D_CPU0_SB_DQS_DN<2>")
	)
	(segment
		(start 342.664034 -233.06405)
		(end 342.664034 -232.528364)
		(width 0.20066)
		(layer "F.Cu")
		(net "M_D_CPU0_SB_DQS_DN<2>")
	)
	(segment
		(start 258.040124 -209.90306)
		(end 257.404108 -209.477864)
		(width 0.20066)
		(layer "F.Cu")
		(net "M_D_CPU0_SB_DQS_DN<2>")
	)
	(segment
		(start 263.077706 -209.216752)
		(end 262.816594 -209.477864)
		(width 0.20066)
		(layer "F.Cu")
		(net "M_D_CPU0_SB_DQS_DN<2>")
	)
	(segment
		(start 278.973534 -210.765136)
		(end 278.635714 -210.624928)
		(width 0.18288)
		(layer "In6.Cu")
		(net "M_D_CPU0_SB_DQS_DN<2>")
	)
	(segment
		(start 336.367882 -232.038906)
		(end 336.357468 -232.03281)
		(width 0.088646)
		(layer "In6.Cu")
		(net "M_D_CPU0_SB_DQS_DN<2>")
	)
	(segment
		(start 331.862176 -230.499158)
		(end 331.139546 -229.776528)
		(width 0.088646)
		(layer "In6.Cu")
		(net "M_D_CPU0_SB_DQS_DN<2>")
	)
	(segment
		(start 279.320498 -210.765136)
		(end 278.973534 -210.765136)
		(width 0.18288)
		(layer "In6.Cu")
		(net "M_D_CPU0_SB_DQS_DN<2>")
	)
	(segment
		(start 340.041992 -232.846626)
		(end 340.031578 -232.852722)
		(width 0.088646)
		(layer "In6.Cu")
		(net "M_D_CPU0_SB_DQS_DN<2>")
	)
	(segment
		(start 300.569376 -210.15071)
		(end 300.316138 -209.897472)
		(width 0.18288)
		(layer "In6.Cu")
		(net "M_D_CPU0_SB_DQS_DN<2>")
	)
	(segment
		(start 315.202316 -215.928194)
		(end 314.230766 -215.928194)
		(width 0.18288)
		(layer "In6.Cu")
		(net "M_D_CPU0_SB_DQS_DN<2>")
	)
	(segment
		(start 290.914074 -209.279744)
		(end 290.365434 -209.279744)
		(width 0.18288)
		(layer "In6.Cu")
		(net "M_D_CPU0_SB_DQS_DN<2>")
	)
	(segment
		(start 293.28237 -210.125818)
		(end 292.894258 -209.737706)
		(width 0.18288)
		(layer "In6.Cu")
		(net "M_D_CPU0_SB_DQS_DN<2>")
	)
	(segment
		(start 301.118016 -210.15071)
		(end 300.569376 -210.15071)
		(width 0.18288)
		(layer "In6.Cu")
		(net "M_D_CPU0_SB_DQS_DN<2>")
	)
	(segment
		(start 297.826176 -209.900012)
		(end 297.261534 -210.4644)
		(width 0.18288)
		(layer "In6.Cu")
		(net "M_D_CPU0_SB_DQS_DN<2>")
	)
	(segment
		(start 283.443426 -209.892138)
		(end 282.66517 -209.892138)
		(width 0.18288)
		(layer "In6.Cu")
		(net "M_D_CPU0_SB_DQS_DN<2>")
	)
	(segment
		(start 301.791116 -210.02625)
		(end 301.242476 -210.02625)
		(width 0.18288)
		(layer "In6.Cu")
		(net "M_D_CPU0_SB_DQS_DN<2>")
	)
	(segment
		(start 331.139546 -229.776528)
		(end 331.139546 -229.433374)
		(width 0.088646)
		(layer "In6.Cu")
		(net "M_D_CPU0_SB_DQS_DN<2>")
	)
	(segment
		(start 330.921106 -229.214934)
		(end 330.655168 -229.214934)
		(width 0.088646)
		(layer "In6.Cu")
		(net "M_D_CPU0_SB_DQS_DN<2>")
	)
	(segment
		(start 341.911686 -232.852722)
		(end 341.911432 -232.852722)
		(width 0.088646)
		(layer "In6.Cu")
		(net "M_D_CPU0_SB_DQS_DN<2>")
	)
	(segment
		(start 280.879804 -210.511136)
		(end 280.647902 -210.743038)
		(width 0.18288)
		(layer "In6.Cu")
		(net "M_D_CPU0_SB_DQS_DN<2>")
	)
	(segment
		(start 272.327624 -209.898996)
		(end 271.48536 -209.898996)
		(width 0.18288)
		(layer "In6.Cu")
		(net "M_D_CPU0_SB_DQS_DN<2>")
	)
	(segment
		(start 280.05532 -210.491832)
		(end 279.593802 -210.491832)
		(width 0.18288)
		(layer "In6.Cu")
		(net "M_D_CPU0_SB_DQS_DN<2>")
	)
	(segment
		(start 306.315618 -210.9597)
		(end 306.217828 -210.813142)
		(width 0.18288)
		(layer "In6.Cu")
		(net "M_D_CPU0_SB_DQS_DN<2>")
	)
	(segment
		(start 314.230766 -215.928194)
		(end 313.409076 -215.10625)
		(width 0.18288)
		(layer "In6.Cu")
		(net "M_D_CPU0_SB_DQS_DN<2>")
	)
	(segment
		(start 267.683234 -209.892138)
		(end 267.298424 -209.507836)
		(width 0.18288)
		(layer "In6.Cu")
		(net "M_D_CPU0_SB_DQS_DN<2>")
	)
	(segment
		(start 269.067788 -209.641694)
		(end 268.60627 -209.641694)
		(width 0.18288)
		(layer "In6.Cu")
		(net "M_D_CPU0_SB_DQS_DN<2>")
	)
	(segment
		(start 283.69387 -209.641694)
		(end 283.443426 -209.892138)
		(width 0.18288)
		(layer "In6.Cu")
		(net "M_D_CPU0_SB_DQS_DN<2>")
	)
	(segment
		(start 278.635714 -210.624928)
		(end 277.879302 -209.86877)
		(width 0.18288)
		(layer "In6.Cu")
		(net "M_D_CPU0_SB_DQS_DN<2>")
	)
	(segment
		(start 266.272518 -209.24647)
		(end 265.719814 -209.475324)
		(width 0.18288)
		(layer "In6.Cu")
		(net "M_D_CPU0_SB_DQS_DN<2>")
	)
	(segment
		(start 275.409914 -209.243422)
		(end 275.285454 -209.118962)
		(width 0.18288)
		(layer "In6.Cu")
		(net "M_D_CPU0_SB_DQS_DN<2>")
	)
	(segment
		(start 286.831024 -209.894424)
		(end 286.706564 -209.769964)
		(width 0.18288)
		(layer "In6.Cu")
		(net "M_D_CPU0_SB_DQS_DN<2>")
	)
	(segment
		(start 310.614822 -211.772754)
		(end 310.452262 -211.840064)
		(width 0.18288)
		(layer "In6.Cu")
		(net "M_D_CPU0_SB_DQS_DN<2>")
	)
	(segment
		(start 298.53636 -209.900012)
		(end 297.826176 -209.900012)
		(width 0.18288)
		(layer "In6.Cu")
		(net "M_D_CPU0_SB_DQS_DN<2>")
	)
	(segment
		(start 309.308246 -211.366354)
		(end 307.576728 -211.366354)
		(width 0.18288)
		(layer "In6.Cu")
		(net "M_D_CPU0_SB_DQS_DN<2>")
	)
	(segment
		(start 333.361284 -231.714548)
		(end 333.361284 -231.696006)
		(width 0.088646)
		(layer "In6.Cu")
		(net "M_D_CPU0_SB_DQS_DN<2>")
	)
	(segment
		(start 282.208478 -210.348576)
		(end 281.817318 -210.511136)
		(width 0.18288)
		(layer "In6.Cu")
		(net "M_D_CPU0_SB_DQS_DN<2>")
	)
	(segment
		(start 291.711634 -209.279744)
		(end 291.587174 -209.155284)
		(width 0.18288)
		(layer "In6.Cu")
		(net "M_D_CPU0_SB_DQS_DN<2>")
	)
	(segment
		(start 338.166964 -232.844086)
		(end 338.152232 -232.852722)
		(width 0.088646)
		(layer "In6.Cu")
		(net "M_D_CPU0_SB_DQS_DN<2>")
	)
	(segment
		(start 342.164416 -232.70718)
		(end 341.911686 -232.852722)
		(width 0.088646)
		(layer "In6.Cu")
		(net "M_D_CPU0_SB_DQS_DN<2>")
	)
	(segment
		(start 340.986364 -232.844086)
		(end 340.971632 -232.852722)
		(width 0.088646)
		(layer "In6.Cu")
		(net "M_D_CPU0_SB_DQS_DN<2>")
	)
	(segment
		(start 293.28237 -210.30184)
		(end 293.28237 -210.125818)
		(width 0.18288)
		(layer "In6.Cu")
		(net "M_D_CPU0_SB_DQS_DN<2>")
	)
	(segment
		(start 270.81226 -209.774536)
		(end 270.6878 -209.898996)
		(width 0.18288)
		(layer "In6.Cu")
		(net "M_D_CPU0_SB_DQS_DN<2>")
	)
	(segment
		(start 337.312 -232.041446)
		(end 337.29295 -232.03027)
		(width 0.088646)
		(layer "In6.Cu")
		(net "M_D_CPU0_SB_DQS_DN<2>")
	)
	(segment
		(start 291.038534 -209.155284)
		(end 290.914074 -209.279744)
		(width 0.18288)
		(layer "In6.Cu")
		(net "M_D_CPU0_SB_DQS_DN<2>")
	)
	(segment
		(start 321.987926 -225.62058)
		(end 321.987926 -222.713804)
		(width 0.18288)
		(layer "In6.Cu")
		(net "M_D_CPU0_SB_DQS_DN<2>")
	)
	(segment
		(start 294.702484 -210.492848)
		(end 294.42791 -210.767422)
		(width 0.18288)
		(layer "In6.Cu")
		(net "M_D_CPU0_SB_DQS_DN<2>")
	)
	(segment
		(start 331.862176 -230.966772)
		(end 331.862176 -230.499158)
		(width 0.088646)
		(layer "In6.Cu")
		(net "M_D_CPU0_SB_DQS_DN<2>")
	)
	(segment
		(start 331.139546 -229.433374)
		(end 330.921106 -229.214934)
		(width 0.088646)
		(layer "In6.Cu")
		(net "M_D_CPU0_SB_DQS_DN<2>")
	)
	(segment
		(start 306.217828 -210.813142)
		(end 305.679348 -210.706208)
		(width 0.18288)
		(layer "In6.Cu")
		(net "M_D_CPU0_SB_DQS_DN<2>")
	)
	(segment
		(start 275.285454 -209.118962)
		(end 274.736814 -209.118962)
		(width 0.18288)
		(layer "In6.Cu")
		(net "M_D_CPU0_SB_DQS_DN<2>")
	)
	(segment
		(start 301.915576 -210.15071)
		(end 301.791116 -210.02625)
		(width 0.18288)
		(layer "In6.Cu")
		(net "M_D_CPU0_SB_DQS_DN<2>")
	)
	(segment
		(start 294.42791 -210.767422)
		(end 293.747952 -210.767422)
		(width 0.18288)
		(layer "In6.Cu")
		(net "M_D_CPU0_SB_DQS_DN<2>")
	)
	(segment
		(start 305.533044 -210.803998)
		(end 303.795938 -210.458558)
		(width 0.18288)
		(layer "In6.Cu")
		(net "M_D_CPU0_SB_DQS_DN<2>")
	)
	(segment
		(start 310.452262 -211.840064)
		(end 309.308246 -211.366354)
		(width 0.18288)
		(layer "In6.Cu")
		(net "M_D_CPU0_SB_DQS_DN<2>")
	)
	(segment
		(start 312.548524 -213.0298)
		(end 312.000392 -212.481414)
		(width 0.18288)
		(layer "In6.Cu")
		(net "M_D_CPU0_SB_DQS_DN<2>")
	)
	(segment
		(start 290.365434 -209.279744)
		(end 290.240974 -209.155284)
		(width 0.18288)
		(layer "In6.Cu")
		(net "M_D_CPU0_SB_DQS_DN<2>")
	)
	(segment
		(start 303.795938 -210.458558)
		(end 303.051972 -210.15071)
		(width 0.18288)
		(layer "In6.Cu")
		(net "M_D_CPU0_SB_DQS_DN<2>")
	)
	(segment
		(start 330.57211 -229.155244)
		(end 325.52259 -229.155244)
		(width 0.18288)
		(layer "In6.Cu")
		(net "M_D_CPU0_SB_DQS_DN<2>")
	)
	(segment
		(start 286.706564 -209.769964)
		(end 286.157924 -209.769964)
		(width 0.18288)
		(layer "In6.Cu")
		(net "M_D_CPU0_SB_DQS_DN<2>")
	)
	(segment
		(start 271.3609 -209.774536)
		(end 270.81226 -209.774536)
		(width 0.18288)
		(layer "In6.Cu")
		(net "M_D_CPU0_SB_DQS_DN<2>")
	)
	(segment
		(start 299.470826 -209.897472)
		(end 299.214286 -209.640932)
		(width 0.18288)
		(layer "In6.Cu")
		(net "M_D_CPU0_SB_DQS_DN<2>")
	)
	(segment
		(start 321.987926 -222.713804)
		(end 315.202316 -215.928194)
		(width 0.18288)
		(layer "In6.Cu")
		(net "M_D_CPU0_SB_DQS_DN<2>")
	)
	(segment
		(start 279.593802 -210.491832)
		(end 279.320498 -210.765136)
		(width 0.18288)
		(layer "In6.Cu")
		(net "M_D_CPU0_SB_DQS_DN<2>")
	)
	(segment
		(start 342.632284 -232.644188)
		(end 342.593422 -232.666286)
		(width 0.088646)
		(layer "In6.Cu")
		(net "M_D_CPU0_SB_DQS_DN<2>")
	)
	(segment
		(start 271.48536 -209.898996)
		(end 271.3609 -209.774536)
		(width 0.18288)
		(layer "In6.Cu")
		(net "M_D_CPU0_SB_DQS_DN<2>")
	)
	(segment
		(start 274.736814 -209.118962)
		(end 274.612354 -209.243422)
		(width 0.18288)
		(layer "In6.Cu")
		(net "M_D_CPU0_SB_DQS_DN<2>")
	)
	(segment
		(start 274.612354 -209.243422)
		(end 273.909028 -209.243422)
		(width 0.18288)
		(layer "In6.Cu")
		(net "M_D_CPU0_SB_DQS_DN<2>")
	)
	(segment
		(start 288.864294 -209.279744)
		(end 287.379664 -209.894424)
		(width 0.18288)
		(layer "In6.Cu")
		(net "M_D_CPU0_SB_DQS_DN<2>")
	)
	(segment
		(start 332.061058 -231.165654)
		(end 331.862176 -230.966772)
		(width 0.088646)
		(layer "In6.Cu")
		(net "M_D_CPU0_SB_DQS_DN<2>")
	)
	(segment
		(start 330.595478 -229.155244)
		(end 330.57211 -229.155244)
		(width 0.088646)
		(layer "In6.Cu")
		(net "M_D_CPU0_SB_DQS_DN<2>")
	)
	(segment
		(start 289.692334 -209.155284)
		(end 289.567874 -209.279744)
		(width 0.18288)
		(layer "In6.Cu")
		(net "M_D_CPU0_SB_DQS_DN<2>")
	)
	(segment
		(start 289.567874 -209.279744)
		(end 288.864294 -209.279744)
		(width 0.18288)
		(layer "In6.Cu")
		(net "M_D_CPU0_SB_DQS_DN<2>")
	)
	(segment
		(start 292.718236 -209.737706)
		(end 292.260274 -209.279744)
		(width 0.18288)
		(layer "In6.Cu")
		(net "M_D_CPU0_SB_DQS_DN<2>")
	)
	(segment
		(start 286.157924 -209.769964)
		(end 286.033464 -209.894424)
		(width 0.18288)
		(layer "In6.Cu")
		(net "M_D_CPU0_SB_DQS_DN<2>")
	)
	(segment
		(start 273.909028 -209.243422)
		(end 272.327624 -209.898996)
		(width 0.18288)
		(layer "In6.Cu")
		(net "M_D_CPU0_SB_DQS_DN<2>")
	)
	(segment
		(start 268.355826 -209.892138)
		(end 267.683234 -209.892138)
		(width 0.18288)
		(layer "In6.Cu")
		(net "M_D_CPU0_SB_DQS_DN<2>")
	)
	(segment
		(start 265.719814 -209.475324)
		(end 264.987786 -209.475324)
		(width 0.18288)
		(layer "In6.Cu")
		(net "M_D_CPU0_SB_DQS_DN<2>")
	)
	(segment
		(start 297.261534 -210.4644)
		(end 296.519346 -210.771994)
		(width 0.18288)
		(layer "In6.Cu")
		(net "M_D_CPU0_SB_DQS_DN<2>")
	)
	(segment
		(start 291.587174 -209.155284)
		(end 291.038534 -209.155284)
		(width 0.18288)
		(layer "In6.Cu")
		(net "M_D_CPU0_SB_DQS_DN<2>")
	)
	(segment
		(start 342.438736 -232.70718)
		(end 342.164416 -232.70718)
		(width 0.088646)
		(layer "In6.Cu")
		(net "M_D_CPU0_SB_DQS_DN<2>")
	)
	(segment
		(start 312.000392 -212.481414)
		(end 311.18937 -212.145626)
		(width 0.18288)
		(layer "In6.Cu")
		(net "M_D_CPU0_SB_DQS_DN<2>")
	)
	(segment
		(start 298.79544 -209.640932)
		(end 298.53636 -209.900012)
		(width 0.18288)
		(layer "In6.Cu")
		(net "M_D_CPU0_SB_DQS_DN<2>")
	)
	(segment
		(start 292.260274 -209.279744)
		(end 291.711634 -209.279744)
		(width 0.18288)
		(layer "In6.Cu")
		(net "M_D_CPU0_SB_DQS_DN<2>")
	)
	(segment
		(start 299.214286 -209.640932)
		(end 298.79544 -209.640932)
		(width 0.18288)
		(layer "In6.Cu")
		(net "M_D_CPU0_SB_DQS_DN<2>")
	)
	(segment
		(start 330.655168 -229.214934)
		(end 330.595478 -229.155244)
		(width 0.088646)
		(layer "In6.Cu")
		(net "M_D_CPU0_SB_DQS_DN<2>")
	)
	(segment
		(start 311.121806 -211.982558)
		(end 310.614822 -211.772754)
		(width 0.18288)
		(layer "In6.Cu")
		(net "M_D_CPU0_SB_DQS_DN<2>")
	)
	(segment
		(start 284.155388 -209.641694)
		(end 283.69387 -209.641694)
		(width 0.18288)
		(layer "In6.Cu")
		(net "M_D_CPU0_SB_DQS_DN<2>")
	)
	(segment
		(start 290.240974 -209.155284)
		(end 289.692334 -209.155284)
		(width 0.18288)
		(layer "In6.Cu")
		(net "M_D_CPU0_SB_DQS_DN<2>")
	)
	(segment
		(start 292.894258 -209.737706)
		(end 292.718236 -209.737706)
		(width 0.18288)
		(layer "In6.Cu")
		(net "M_D_CPU0_SB_DQS_DN<2>")
	)
	(segment
		(start 306.85359 -211.066634)
		(end 306.315618 -210.9597)
		(width 0.18288)
		(layer "In6.Cu")
		(net "M_D_CPU0_SB_DQS_DN<2>")
	)
	(segment
		(start 280.306526 -210.743038)
		(end 280.05532 -210.491832)
		(width 0.18288)
		(layer "In6.Cu")
		(net "M_D_CPU0_SB_DQS_DN<2>")
	)
	(segment
		(start 267.298424 -209.507836)
		(end 266.667742 -209.24647)
		(width 0.18288)
		(layer "In6.Cu")
		(net "M_D_CPU0_SB_DQS_DN<2>")
	)
	(segment
		(start 300.316138 -209.897472)
		(end 299.470826 -209.897472)
		(width 0.18288)
		(layer "In6.Cu")
		(net "M_D_CPU0_SB_DQS_DN<2>")
	)
	(segment
		(start 281.817318 -210.511136)
		(end 280.879804 -210.511136)
		(width 0.18288)
		(layer "In6.Cu")
		(net "M_D_CPU0_SB_DQS_DN<2>")
	)
	(segment
		(start 342.664034 -232.528364)
		(end 342.632284 -232.644188)
		(width 0.088646)
		(layer "In6.Cu")
		(net "M_D_CPU0_SB_DQS_DN<2>")
	)
	(segment
		(start 266.667742 -209.24647)
		(end 266.272518 -209.24647)
		(width 0.18288)
		(layer "In6.Cu")
		(net "M_D_CPU0_SB_DQS_DN<2>")
	)
	(segment
		(start 268.60627 -209.641694)
		(end 268.355826 -209.892138)
		(width 0.18288)
		(layer "In6.Cu")
		(net "M_D_CPU0_SB_DQS_DN<2>")
	)
	(segment
		(start 296.519346 -210.771994)
		(end 295.390062 -210.771994)
		(width 0.18288)
		(layer "In6.Cu")
		(net "M_D_CPU0_SB_DQS_DN<2>")
	)
	(segment
		(start 339.657182 -232.852722)
		(end 339.646768 -232.846626)
		(width 0.088646)
		(layer "In6.Cu")
		(net "M_D_CPU0_SB_DQS_DN<2>")
	)
	(segment
		(start 282.66517 -209.892138)
		(end 282.208478 -210.348576)
		(width 0.18288)
		(layer "In6.Cu")
		(net "M_D_CPU0_SB_DQS_DN<2>")
	)
	(segment
		(start 305.679348 -210.706208)
		(end 305.533044 -210.803998)
		(width 0.18288)
		(layer "In6.Cu")
		(net "M_D_CPU0_SB_DQS_DN<2>")
	)
	(segment
		(start 276.370034 -209.243422)
		(end 275.409914 -209.243422)
		(width 0.18288)
		(layer "In6.Cu")
		(net "M_D_CPU0_SB_DQS_DN<2>")
	)
	(segment
		(start 264.987786 -209.475324)
		(end 264.729214 -209.216752)
		(width 0.18288)
		(layer "In6.Cu")
		(net "M_D_CPU0_SB_DQS_DN<2>")
	)
	(segment
		(start 313.409076 -215.10625)
		(end 312.548524 -213.0298)
		(width 0.18288)
		(layer "In6.Cu")
		(net "M_D_CPU0_SB_DQS_DN<2>")
	)
	(segment
		(start 307.576728 -211.366354)
		(end 306.85359 -211.066634)
		(width 0.18288)
		(layer "In6.Cu")
		(net "M_D_CPU0_SB_DQS_DN<2>")
	)
	(segment
		(start 284.408118 -209.894424)
		(end 284.155388 -209.641694)
		(width 0.18288)
		(layer "In6.Cu")
		(net "M_D_CPU0_SB_DQS_DN<2>")
	)
	(segment
		(start 270.6878 -209.898996)
		(end 269.32509 -209.898996)
		(width 0.18288)
		(layer "In6.Cu")
		(net "M_D_CPU0_SB_DQS_DN<2>")
	)
	(segment
		(start 277.879302 -209.86877)
		(end 276.370034 -209.243422)
		(width 0.18288)
		(layer "In6.Cu")
		(net "M_D_CPU0_SB_DQS_DN<2>")
	)
	(segment
		(start 293.747952 -210.767422)
		(end 293.28237 -210.30184)
		(width 0.18288)
		(layer "In6.Cu")
		(net "M_D_CPU0_SB_DQS_DN<2>")
	)
	(segment
		(start 269.32509 -209.898996)
		(end 269.067788 -209.641694)
		(width 0.18288)
		(layer "In6.Cu")
		(net "M_D_CPU0_SB_DQS_DN<2>")
	)
	(segment
		(start 303.051972 -210.15071)
		(end 301.915576 -210.15071)
		(width 0.18288)
		(layer "In6.Cu")
		(net "M_D_CPU0_SB_DQS_DN<2>")
	)
	(segment
		(start 287.379664 -209.894424)
		(end 286.831024 -209.894424)
		(width 0.18288)
		(layer "In6.Cu")
		(net "M_D_CPU0_SB_DQS_DN<2>")
	)
	(segment
		(start 295.110916 -210.492848)
		(end 294.702484 -210.492848)
		(width 0.18288)
		(layer "In6.Cu")
		(net "M_D_CPU0_SB_DQS_DN<2>")
	)
	(segment
		(start 295.390062 -210.771994)
		(end 295.110916 -210.492848)
		(width 0.18288)
		(layer "In6.Cu")
		(net "M_D_CPU0_SB_DQS_DN<2>")
	)
	(segment
		(start 301.242476 -210.02625)
		(end 301.118016 -210.15071)
		(width 0.18288)
		(layer "In6.Cu")
		(net "M_D_CPU0_SB_DQS_DN<2>")
	)
	(segment
		(start 286.033464 -209.894424)
		(end 284.408118 -209.894424)
		(width 0.18288)
		(layer "In6.Cu")
		(net "M_D_CPU0_SB_DQS_DN<2>")
	)
	(segment
		(start 311.18937 -212.145626)
		(end 311.121806 -211.982558)
		(width 0.18288)
		(layer "In6.Cu")
		(net "M_D_CPU0_SB_DQS_DN<2>")
	)
	(segment
		(start 280.647902 -210.743038)
		(end 280.306526 -210.743038)
		(width 0.18288)
		(layer "In6.Cu")
		(net "M_D_CPU0_SB_DQS_DN<2>")
	)
	(segment
		(start 325.52259 -229.155244)
		(end 321.987926 -225.62058)
		(width 0.18288)
		(layer "In6.Cu")
		(net "M_D_CPU0_SB_DQS_DN<2>")
	)
	(arc
		(start 340.597236 -232.852722)
		(mid 340.320423 -232.776852)
		(end 340.041992 -232.846626)
		(width 0.088646)
		(layer "In6.Cu")
		(net "M_D_CPU0_SB_DQS_DN<2>")
	)
	(arc
		(start 335.428336 -232.038906)
		(mid 335.145634 -231.96313)
		(end 334.862932 -232.038906)
		(width 0.088646)
		(layer "In6.Cu")
		(net "M_D_CPU0_SB_DQS_DN<2>")
	)
	(arc
		(start 341.537036 -232.852722)
		(mid 341.262837 -232.776887)
		(end 340.986364 -232.844086)
		(width 0.088646)
		(layer "In6.Cu")
		(net "M_D_CPU0_SB_DQS_DN<2>")
	)
	(arc
		(start 340.031578 -232.852722)
		(mid 339.84438 -232.902865)
		(end 339.657182 -232.852722)
		(width 0.088646)
		(layer "In6.Cu")
		(net "M_D_CPU0_SB_DQS_DN<2>")
	)
	(arc
		(start 333.361284 -231.696006)
		(mid 333.070806 -231.220287)
		(end 332.513432 -231.224836)
		(width 0.088646)
		(layer "In6.Cu")
		(net "M_D_CPU0_SB_DQS_DN<2>")
	)
	(arc
		(start 336.742278 -232.038906)
		(mid 336.55508 -232.089049)
		(end 336.367882 -232.038906)
		(width 0.088646)
		(layer "In6.Cu")
		(net "M_D_CPU0_SB_DQS_DN<2>")
	)
	(arc
		(start 334.488536 -232.038906)
		(mid 334.205834 -231.96313)
		(end 333.923132 -232.038906)
		(width 0.088646)
		(layer "In6.Cu")
		(net "M_D_CPU0_SB_DQS_DN<2>")
	)
	(arc
		(start 334.862932 -232.038906)
		(mid 334.675734 -232.089049)
		(end 334.488536 -232.038906)
		(width 0.088646)
		(layer "In6.Cu")
		(net "M_D_CPU0_SB_DQS_DN<2>")
	)
	(arc
		(start 332.513432 -231.224836)
		(mid 332.326234 -231.274979)
		(end 332.139036 -231.224836)
		(width 0.088646)
		(layer "In6.Cu")
		(net "M_D_CPU0_SB_DQS_DN<2>")
	)
	(arc
		(start 332.139036 -231.224836)
		(mid 332.098106 -231.197803)
		(end 332.061058 -231.165654)
		(width 0.088646)
		(layer "In6.Cu")
		(net "M_D_CPU0_SB_DQS_DN<2>")
	)
	(arc
		(start 340.971632 -232.852722)
		(mid 340.784434 -232.902865)
		(end 340.597236 -232.852722)
		(width 0.088646)
		(layer "In6.Cu")
		(net "M_D_CPU0_SB_DQS_DN<2>")
	)
	(arc
		(start 337.29295 -232.03027)
		(mid 337.016475 -231.96295)
		(end 336.742278 -232.038906)
		(width 0.088646)
		(layer "In6.Cu")
		(net "M_D_CPU0_SB_DQS_DN<2>")
	)
	(arc
		(start 342.593422 -232.666286)
		(mid 342.518737 -232.696791)
		(end 342.438736 -232.70718)
		(width 0.088646)
		(layer "In6.Cu")
		(net "M_D_CPU0_SB_DQS_DN<2>")
	)
	(arc
		(start 339.646768 -232.846626)
		(mid 339.36859 -232.776903)
		(end 339.092032 -232.852722)
		(width 0.088646)
		(layer "In6.Cu")
		(net "M_D_CPU0_SB_DQS_DN<2>")
	)
	(arc
		(start 339.092032 -232.852722)
		(mid 338.904834 -232.902865)
		(end 338.717636 -232.852722)
		(width 0.088646)
		(layer "In6.Cu")
		(net "M_D_CPU0_SB_DQS_DN<2>")
	)
	(arc
		(start 338.152232 -232.852722)
		(mid 337.777757 -232.852676)
		(end 337.590384 -232.528364)
		(width 0.088646)
		(layer "In6.Cu")
		(net "M_D_CPU0_SB_DQS_DN<2>")
	)
	(arc
		(start 336.357468 -232.03281)
		(mid 336.07929 -231.963087)
		(end 335.802732 -232.038906)
		(width 0.088646)
		(layer "In6.Cu")
		(net "M_D_CPU0_SB_DQS_DN<2>")
	)
	(arc
		(start 338.717636 -232.852722)
		(mid 338.443437 -232.776887)
		(end 338.166964 -232.844086)
		(width 0.088646)
		(layer "In6.Cu")
		(net "M_D_CPU0_SB_DQS_DN<2>")
	)
	(arc
		(start 333.923132 -232.038906)
		(mid 333.548657 -232.03886)
		(end 333.361284 -231.714548)
		(width 0.088646)
		(layer "In6.Cu")
		(net "M_D_CPU0_SB_DQS_DN<2>")
	)
	(arc
		(start 337.590384 -232.528364)
		(mid 337.515886 -232.247908)
		(end 337.312 -232.041446)
		(width 0.088646)
		(layer "In6.Cu")
		(net "M_D_CPU0_SB_DQS_DN<2>")
	)
	(arc
		(start 341.911432 -232.852722)
		(mid 341.724234 -232.902865)
		(end 341.537036 -232.852722)
		(width 0.088646)
		(layer "In6.Cu")
		(net "M_D_CPU0_SB_DQS_DN<2>")
	)
	(arc
		(start 335.802732 -232.038906)
		(mid 335.615534 -232.089049)
		(end 335.428336 -232.038906)
		(width 0.088646)
		(layer "In6.Cu")
		(net "M_D_CPU0_SB_DQS_DN<2>")
	)
	(segment
		(start 261.381494 -218.991688)
		(end 259.067808 -218.991688)
		(width 0.1016)
		(layer "F.Cu")
		(net "M_D_CPU0_SB_DQS_DN<1>")
	)
	(segment
		(start 258.580128 -219.253054)
		(end 258.040124 -219.253054)
		(width 0.20066)
		(layer "F.Cu")
		(net "M_D_CPU0_SB_DQS_DN<1>")
	)
	(segment
		(start 263.077706 -218.566746)
		(end 262.816594 -218.827858)
		(width 0.20066)
		(layer "F.Cu")
		(net "M_D_CPU0_SB_DQS_DN<1>")
	)
	(segment
		(start 262.816594 -218.827858)
		(end 262.40994 -218.827858)
		(width 0.20066)
		(layer "F.Cu")
		(net "M_D_CPU0_SB_DQS_DN<1>")
	)
	(segment
		(start 259.056378 -218.98102)
		(end 258.852162 -218.98102)
		(width 0.20066)
		(layer "F.Cu")
		(net "M_D_CPU0_SB_DQS_DN<1>")
	)
	(segment
		(start 259.05714 -218.98102)
		(end 259.056378 -218.98102)
		(width 0.101854)
		(layer "F.Cu")
		(net "M_D_CPU0_SB_DQS_DN<1>")
	)
	(segment
		(start 345.953334 -235.506006)
		(end 345.953334 -234.97032)
		(width 0.20066)
		(layer "F.Cu")
		(net "M_D_CPU0_SB_DQS_DN<1>")
	)
	(segment
		(start 261.798054 -219.253054)
		(end 261.536688 -218.991688)
		(width 0.20066)
		(layer "F.Cu")
		(net "M_D_CPU0_SB_DQS_DN<1>")
	)
	(segment
		(start 262.40994 -218.827858)
		(end 261.984744 -219.253054)
		(width 0.20066)
		(layer "F.Cu")
		(net "M_D_CPU0_SB_DQS_DN<1>")
	)
	(segment
		(start 257.404108 -218.827858)
		(end 256.890266 -218.827858)
		(width 0.20066)
		(layer "F.Cu")
		(net "M_D_CPU0_SB_DQS_DN<1>")
	)
	(segment
		(start 259.067808 -218.991688)
		(end 259.05714 -218.98102)
		(width 0.101854)
		(layer "F.Cu")
		(net "M_D_CPU0_SB_DQS_DN<1>")
	)
	(segment
		(start 261.536688 -218.991688)
		(end 261.381494 -218.991688)
		(width 0.20066)
		(layer "F.Cu")
		(net "M_D_CPU0_SB_DQS_DN<1>")
	)
	(segment
		(start 256.890266 -218.827858)
		(end 256.629154 -218.566746)
		(width 0.20066)
		(layer "F.Cu")
		(net "M_D_CPU0_SB_DQS_DN<1>")
	)
	(segment
		(start 263.624314 -218.566746)
		(end 263.077706 -218.566746)
		(width 0.20066)
		(layer "F.Cu")
		(net "M_D_CPU0_SB_DQS_DN<1>")
	)
	(segment
		(start 256.629154 -218.566746)
		(end 256.080514 -218.566746)
		(width 0.20066)
		(layer "F.Cu")
		(net "M_D_CPU0_SB_DQS_DN<1>")
	)
	(segment
		(start 345.953334 -234.97032)
		(end 345.95308 -234.970066)
		(width 0.20066)
		(layer "F.Cu")
		(net "M_D_CPU0_SB_DQS_DN<1>")
	)
	(segment
		(start 261.984744 -219.253054)
		(end 261.798054 -219.253054)
		(width 0.20066)
		(layer "F.Cu")
		(net "M_D_CPU0_SB_DQS_DN<1>")
	)
	(segment
		(start 258.852162 -218.98102)
		(end 258.580128 -219.253054)
		(width 0.20066)
		(layer "F.Cu")
		(net "M_D_CPU0_SB_DQS_DN<1>")
	)
	(segment
		(start 258.040124 -219.253054)
		(end 257.404108 -218.827858)
		(width 0.20066)
		(layer "F.Cu")
		(net "M_D_CPU0_SB_DQS_DN<1>")
	)
	(segment
		(start 264.729214 -218.566746)
		(end 263.624314 -218.566746)
		(width 0.20066)
		(layer "F.Cu")
		(net "M_D_CPU0_SB_DQS_DN<1>")
	)
	(segment
		(start 274.776184 -213.62416)
		(end 274.776184 -215.32596)
		(width 0.18288)
		(layer "In11.Cu")
		(net "M_D_CPU0_SB_DQS_DN<1>")
	)
	(segment
		(start 344.826336 -235.294424)
		(end 344.815922 -235.288328)
		(width 0.088646)
		(layer "In11.Cu")
		(net "M_D_CPU0_SB_DQS_DN<1>")
	)
	(segment
		(start 303.63922 -212.077808)
		(end 303.132236 -211.868004)
		(width 0.18288)
		(layer "In11.Cu")
		(net "M_D_CPU0_SB_DQS_DN<1>")
	)
	(segment
		(start 275.62048 -212.779864)
		(end 274.776184 -213.62416)
		(width 0.18288)
		(layer "In11.Cu")
		(net "M_D_CPU0_SB_DQS_DN<1>")
	)
	(segment
		(start 279.328372 -212.47608)
		(end 278.667718 -212.47608)
		(width 0.18288)
		(layer "In11.Cu")
		(net "M_D_CPU0_SB_DQS_DN<1>")
	)
	(segment
		(start 312.792872 -215.760808)
		(end 312.668412 -215.885268)
		(width 0.18288)
		(layer "In11.Cu")
		(net "M_D_CPU0_SB_DQS_DN<1>")
	)
	(segment
		(start 343.886282 -235.294424)
		(end 343.87155 -235.285788)
		(width 0.088646)
		(layer "In11.Cu")
		(net "M_D_CPU0_SB_DQS_DN<1>")
	)
	(segment
		(start 345.200986 -235.294678)
		(end 345.200732 -235.294424)
		(width 0.088646)
		(layer "In11.Cu")
		(net "M_D_CPU0_SB_DQS_DN<1>")
	)
	(segment
		(start 308.688486 -213.829138)
		(end 308.512464 -213.829138)
		(width 0.18288)
		(layer "In11.Cu")
		(net "M_D_CPU0_SB_DQS_DN<1>")
	)
	(segment
		(start 308.512464 -213.829138)
		(end 307.890926 -213.2076)
		(width 0.18288)
		(layer "In11.Cu")
		(net "M_D_CPU0_SB_DQS_DN<1>")
	)
	(segment
		(start 297.41622 -212.091524)
		(end 296.540936 -212.45449)
		(width 0.18288)
		(layer "In11.Cu")
		(net "M_D_CPU0_SB_DQS_DN<1>")
	)
	(segment
		(start 310.517032 -215.210898)
		(end 310.354472 -215.278208)
		(width 0.18288)
		(layer "In11.Cu")
		(net "M_D_CPU0_SB_DQS_DN<1>")
	)
	(segment
		(start 311.820306 -215.885268)
		(end 311.09158 -215.583516)
		(width 0.18288)
		(layer "In11.Cu")
		(net "M_D_CPU0_SB_DQS_DN<1>")
	)
	(segment
		(start 279.613614 -212.190838)
		(end 279.328372 -212.47608)
		(width 0.18288)
		(layer "In11.Cu")
		(net "M_D_CPU0_SB_DQS_DN<1>")
	)
	(segment
		(start 294.710104 -212.194648)
		(end 294.43299 -212.471762)
		(width 0.18288)
		(layer "In11.Cu")
		(net "M_D_CPU0_SB_DQS_DN<1>")
	)
	(segment
		(start 293.341044 -212.953854)
		(end 293.021004 -213.086442)
		(width 0.18288)
		(layer "In11.Cu")
		(net "M_D_CPU0_SB_DQS_DN<1>")
	)
	(segment
		(start 334.018636 -232.852722)
		(end 334.008222 -232.846626)
		(width 0.088646)
		(layer "In11.Cu")
		(net "M_D_CPU0_SB_DQS_DN<1>")
	)
	(segment
		(start 274.651724 -215.45042)
		(end 274.651724 -215.99906)
		(width 0.18288)
		(layer "In11.Cu")
		(net "M_D_CPU0_SB_DQS_DN<1>")
	)
	(segment
		(start 342.006682 -235.294424)
		(end 341.99195 -235.285788)
		(width 0.088646)
		(layer "In11.Cu")
		(net "M_D_CPU0_SB_DQS_DN<1>")
	)
	(segment
		(start 311.02427 -215.420702)
		(end 310.517032 -215.210898)
		(width 0.18288)
		(layer "In11.Cu")
		(net "M_D_CPU0_SB_DQS_DN<1>")
	)
	(segment
		(start 293.021004 -213.086442)
		(end 292.48735 -213.086442)
		(width 0.18288)
		(layer "In11.Cu")
		(net "M_D_CPU0_SB_DQS_DN<1>")
	)
	(segment
		(start 295.158668 -212.194648)
		(end 294.710104 -212.194648)
		(width 0.18288)
		(layer "In11.Cu")
		(net "M_D_CPU0_SB_DQS_DN<1>")
	)
	(segment
		(start 288.725356 -212.003386)
		(end 288.218372 -211.793582)
		(width 0.18288)
		(layer "In11.Cu")
		(net "M_D_CPU0_SB_DQS_DN<1>")
	)
	(segment
		(start 289.420046 -212.426042)
		(end 288.792666 -212.1662)
		(width 0.18288)
		(layer "In11.Cu")
		(net "M_D_CPU0_SB_DQS_DN<1>")
	)
	(segment
		(start 345.95308 -234.970066)
		(end 345.92133 -235.08589)
		(width 0.088646)
		(layer "In11.Cu")
		(net "M_D_CPU0_SB_DQS_DN<1>")
	)
	(segment
		(start 340.409784 -234.15625)
		(end 340.409784 -234.142026)
		(width 0.088646)
		(layer "In11.Cu")
		(net "M_D_CPU0_SB_DQS_DN<1>")
	)
	(segment
		(start 303.706784 -212.240622)
		(end 303.63922 -212.077808)
		(width 0.18288)
		(layer "In11.Cu")
		(net "M_D_CPU0_SB_DQS_DN<1>")
	)
	(segment
		(start 284.415738 -211.586826)
		(end 284.17266 -211.343748)
		(width 0.18288)
		(layer "In11.Cu")
		(net "M_D_CPU0_SB_DQS_DN<1>")
	)
	(segment
		(start 284.17266 -211.343748)
		(end 283.721048 -211.343748)
		(width 0.18288)
		(layer "In11.Cu")
		(net "M_D_CPU0_SB_DQS_DN<1>")
	)
	(segment
		(start 264.970768 -218.8083)
		(end 264.729214 -218.566746)
		(width 0.18288)
		(layer "In11.Cu")
		(net "M_D_CPU0_SB_DQS_DN<1>")
	)
	(segment
		(start 267.656564 -219.23756)
		(end 267.258038 -218.83878)
		(width 0.18288)
		(layer "In11.Cu")
		(net "M_D_CPU0_SB_DQS_DN<1>")
	)
	(segment
		(start 345.454224 -235.148882)
		(end 345.200986 -235.294678)
		(width 0.088646)
		(layer "In11.Cu")
		(net "M_D_CPU0_SB_DQS_DN<1>")
	)
	(segment
		(start 294.43299 -212.471762)
		(end 293.823136 -212.471762)
		(width 0.18288)
		(layer "In11.Cu")
		(net "M_D_CPU0_SB_DQS_DN<1>")
	)
	(segment
		(start 311.09158 -215.583516)
		(end 311.02427 -215.420702)
		(width 0.18288)
		(layer "In11.Cu")
		(net "M_D_CPU0_SB_DQS_DN<1>")
	)
	(segment
		(start 330.336906 -231.072436)
		(end 328.217022 -231.072436)
		(width 0.18288)
		(layer "In11.Cu")
		(net "M_D_CPU0_SB_DQS_DN<1>")
	)
	(segment
		(start 309.076598 -214.21725)
		(end 308.688486 -213.829138)
		(width 0.18288)
		(layer "In11.Cu")
		(net "M_D_CPU0_SB_DQS_DN<1>")
	)
	(segment
		(start 300.859444 -211.466684)
		(end 300.734984 -211.591144)
		(width 0.18288)
		(layer "In11.Cu")
		(net "M_D_CPU0_SB_DQS_DN<1>")
	)
	(segment
		(start 265.33983 -218.8083)
		(end 264.970768 -218.8083)
		(width 0.18288)
		(layer "In11.Cu")
		(net "M_D_CPU0_SB_DQS_DN<1>")
	)
	(segment
		(start 307.890926 -213.2076)
		(end 306.442618 -212.607906)
		(width 0.18288)
		(layer "In11.Cu")
		(net "M_D_CPU0_SB_DQS_DN<1>")
	)
	(segment
		(start 267.258038 -218.83878)
		(end 266.722606 -218.617292)
		(width 0.18288)
		(layer "In11.Cu")
		(net "M_D_CPU0_SB_DQS_DN<1>")
	)
	(segment
		(start 333.078582 -232.852722)
		(end 333.06385 -232.844086)
		(width 0.088646)
		(layer "In11.Cu")
		(net "M_D_CPU0_SB_DQS_DN<1>")
	)
	(segment
		(start 306.442618 -212.607906)
		(end 304.593752 -212.607906)
		(width 0.18288)
		(layer "In11.Cu")
		(net "M_D_CPU0_SB_DQS_DN<1>")
	)
	(segment
		(start 268.628622 -218.990926)
		(end 268.381988 -219.23756)
		(width 0.18288)
		(layer "In11.Cu")
		(net "M_D_CPU0_SB_DQS_DN<1>")
	)
	(segment
		(start 277.151338 -211.850732)
		(end 276.648164 -212.35416)
		(width 0.18288)
		(layer "In11.Cu")
		(net "M_D_CPU0_SB_DQS_DN<1>")
	)
	(segment
		(start 314.162186 -215.885268)
		(end 313.465972 -215.885268)
		(width 0.18288)
		(layer "In11.Cu")
		(net "M_D_CPU0_SB_DQS_DN<1>")
	)
	(segment
		(start 340.127082 -233.666538)
		(end 340.116668 -233.660442)
		(width 0.088646)
		(layer "In11.Cu")
		(net "M_D_CPU0_SB_DQS_DN<1>")
	)
	(segment
		(start 299.237146 -211.340954)
		(end 298.811442 -211.340954)
		(width 0.18288)
		(layer "In11.Cu")
		(net "M_D_CPU0_SB_DQS_DN<1>")
	)
	(segment
		(start 280.302716 -212.454236)
		(end 280.039318 -212.190838)
		(width 0.18288)
		(layer "In11.Cu")
		(net "M_D_CPU0_SB_DQS_DN<1>")
	)
	(segment
		(start 316.521592 -219.377006)
		(end 315.463174 -216.821766)
		(width 0.18288)
		(layer "In11.Cu")
		(net "M_D_CPU0_SB_DQS_DN<1>")
	)
	(segment
		(start 302.969676 -211.935314)
		(end 302.138334 -211.591144)
		(width 0.18288)
		(layer "In11.Cu")
		(net "M_D_CPU0_SB_DQS_DN<1>")
	)
	(segment
		(start 309.683912 -215.000586)
		(end 309.076598 -214.393272)
		(width 0.18288)
		(layer "In11.Cu")
		(net "M_D_CPU0_SB_DQS_DN<1>")
	)
	(segment
		(start 314.786518 -216.145364)
		(end 314.162186 -215.885268)
		(width 0.18288)
		(layer "In11.Cu")
		(net "M_D_CPU0_SB_DQS_DN<1>")
	)
	(segment
		(start 302.138334 -211.591144)
		(end 301.532544 -211.591144)
		(width 0.18288)
		(layer "In11.Cu")
		(net "M_D_CPU0_SB_DQS_DN<1>")
	)
	(segment
		(start 286.172148 -211.462366)
		(end 286.047688 -211.586826)
		(width 0.18288)
		(layer "In11.Cu")
		(net "M_D_CPU0_SB_DQS_DN<1>")
	)
	(segment
		(start 293.823136 -212.471762)
		(end 293.341044 -212.953854)
		(width 0.18288)
		(layer "In11.Cu")
		(net "M_D_CPU0_SB_DQS_DN<1>")
	)
	(segment
		(start 341.065358 -235.293662)
		(end 341.057992 -235.289344)
		(width 0.088646)
		(layer "In11.Cu")
		(net "M_D_CPU0_SB_DQS_DN<1>")
	)
	(segment
		(start 282.785058 -211.661248)
		(end 281.99207 -212.454236)
		(width 0.18288)
		(layer "In11.Cu")
		(net "M_D_CPU0_SB_DQS_DN<1>")
	)
	(segment
		(start 286.845248 -211.586826)
		(end 286.720788 -211.462366)
		(width 0.18288)
		(layer "In11.Cu")
		(net "M_D_CPU0_SB_DQS_DN<1>")
	)
	(segment
		(start 330.396596 -231.132126)
		(end 330.336906 -231.072436)
		(width 0.088646)
		(layer "In11.Cu")
		(net "M_D_CPU0_SB_DQS_DN<1>")
	)
	(segment
		(start 301.408084 -211.466684)
		(end 300.859444 -211.466684)
		(width 0.18288)
		(layer "In11.Cu")
		(net "M_D_CPU0_SB_DQS_DN<1>")
	)
	(segment
		(start 280.039318 -212.190838)
		(end 279.613614 -212.190838)
		(width 0.18288)
		(layer "In11.Cu")
		(net "M_D_CPU0_SB_DQS_DN<1>")
	)
	(segment
		(start 292.48735 -213.086442)
		(end 290.892738 -212.426042)
		(width 0.18288)
		(layer "In11.Cu")
		(net "M_D_CPU0_SB_DQS_DN<1>")
	)
	(segment
		(start 330.79817 -231.132126)
		(end 330.396596 -231.132126)
		(width 0.088646)
		(layer "In11.Cu")
		(net "M_D_CPU0_SB_DQS_DN<1>")
	)
	(segment
		(start 266.722606 -218.617292)
		(end 265.801094 -218.617292)
		(width 0.18288)
		(layer "In11.Cu")
		(net "M_D_CPU0_SB_DQS_DN<1>")
	)
	(segment
		(start 340.597236 -234.480608)
		(end 340.588346 -234.475528)
		(width 0.088646)
		(layer "In11.Cu")
		(net "M_D_CPU0_SB_DQS_DN<1>")
	)
	(segment
		(start 288.218372 -211.793582)
		(end 288.055558 -211.860892)
		(width 0.18288)
		(layer "In11.Cu")
		(net "M_D_CPU0_SB_DQS_DN<1>")
	)
	(segment
		(start 345.92133 -235.08589)
		(end 345.882468 -235.107988)
		(width 0.088646)
		(layer "In11.Cu")
		(net "M_D_CPU0_SB_DQS_DN<1>")
	)
	(segment
		(start 269.368524 -219.259404)
		(end 269.100046 -218.990926)
		(width 0.18288)
		(layer "In11.Cu")
		(net "M_D_CPU0_SB_DQS_DN<1>")
	)
	(segment
		(start 281.99207 -212.454236)
		(end 280.302716 -212.454236)
		(width 0.18288)
		(layer "In11.Cu")
		(net "M_D_CPU0_SB_DQS_DN<1>")
	)
	(segment
		(start 340.87943 -234.970066)
		(end 340.87943 -234.954572)
		(width 0.088646)
		(layer "In11.Cu")
		(net "M_D_CPU0_SB_DQS_DN<1>")
	)
	(segment
		(start 296.540936 -212.45449)
		(end 295.41851 -212.45449)
		(width 0.18288)
		(layer "In11.Cu")
		(net "M_D_CPU0_SB_DQS_DN<1>")
	)
	(segment
		(start 278.04237 -211.850732)
		(end 277.151338 -211.850732)
		(width 0.18288)
		(layer "In11.Cu")
		(net "M_D_CPU0_SB_DQS_DN<1>")
	)
	(segment
		(start 345.727782 -235.148882)
		(end 345.454224 -235.148882)
		(width 0.088646)
		(layer "In11.Cu")
		(net "M_D_CPU0_SB_DQS_DN<1>")
	)
	(segment
		(start 270.769334 -219.259404)
		(end 269.368524 -219.259404)
		(width 0.18288)
		(layer "In11.Cu")
		(net "M_D_CPU0_SB_DQS_DN<1>")
	)
	(segment
		(start 332.088744 -232.903522)
		(end 331.075792 -231.89057)
		(width 0.088646)
		(layer "In11.Cu")
		(net "M_D_CPU0_SB_DQS_DN<1>")
	)
	(segment
		(start 276.648164 -212.35416)
		(end 275.62048 -212.779864)
		(width 0.18288)
		(layer "In11.Cu")
		(net "M_D_CPU0_SB_DQS_DN<1>")
	)
	(segment
		(start 265.801094 -218.617292)
		(end 265.33983 -218.8083)
		(width 0.18288)
		(layer "In11.Cu")
		(net "M_D_CPU0_SB_DQS_DN<1>")
	)
	(segment
		(start 274.776184 -216.67216)
		(end 274.598638 -217.100658)
		(width 0.18288)
		(layer "In11.Cu")
		(net "M_D_CPU0_SB_DQS_DN<1>")
	)
	(segment
		(start 341.066882 -235.294424)
		(end 341.065358 -235.293662)
		(width 0.088646)
		(layer "In11.Cu")
		(net "M_D_CPU0_SB_DQS_DN<1>")
	)
	(segment
		(start 290.892738 -212.426042)
		(end 289.420046 -212.426042)
		(width 0.18288)
		(layer "In11.Cu")
		(net "M_D_CPU0_SB_DQS_DN<1>")
	)
	(segment
		(start 274.598638 -217.100658)
		(end 273.948144 -217.751152)
		(width 0.18288)
		(layer "In11.Cu")
		(net "M_D_CPU0_SB_DQS_DN<1>")
	)
	(segment
		(start 309.076598 -214.393272)
		(end 309.076598 -214.21725)
		(width 0.18288)
		(layer "In11.Cu")
		(net "M_D_CPU0_SB_DQS_DN<1>")
	)
	(segment
		(start 288.792666 -212.1662)
		(end 288.725356 -212.003386)
		(width 0.18288)
		(layer "In11.Cu")
		(net "M_D_CPU0_SB_DQS_DN<1>")
	)
	(segment
		(start 313.465972 -215.885268)
		(end 313.341512 -215.760808)
		(width 0.18288)
		(layer "In11.Cu")
		(net "M_D_CPU0_SB_DQS_DN<1>")
	)
	(segment
		(start 274.776184 -215.32596)
		(end 274.651724 -215.45042)
		(width 0.18288)
		(layer "In11.Cu")
		(net "M_D_CPU0_SB_DQS_DN<1>")
	)
	(segment
		(start 332.32598 -232.903522)
		(end 332.088744 -232.903522)
		(width 0.088646)
		(layer "In11.Cu")
		(net "M_D_CPU0_SB_DQS_DN<1>")
	)
	(segment
		(start 331.075792 -231.409748)
		(end 330.79817 -231.132126)
		(width 0.088646)
		(layer "In11.Cu")
		(net "M_D_CPU0_SB_DQS_DN<1>")
	)
	(segment
		(start 300.734984 -211.591144)
		(end 299.487336 -211.591144)
		(width 0.18288)
		(layer "In11.Cu")
		(net "M_D_CPU0_SB_DQS_DN<1>")
	)
	(segment
		(start 288.055558 -211.860892)
		(end 287.393888 -211.586826)
		(width 0.18288)
		(layer "In11.Cu")
		(net "M_D_CPU0_SB_DQS_DN<1>")
	)
	(segment
		(start 301.532544 -211.591144)
		(end 301.408084 -211.466684)
		(width 0.18288)
		(layer "In11.Cu")
		(net "M_D_CPU0_SB_DQS_DN<1>")
	)
	(segment
		(start 304.593752 -212.607906)
		(end 303.706784 -212.240622)
		(width 0.18288)
		(layer "In11.Cu")
		(net "M_D_CPU0_SB_DQS_DN<1>")
	)
	(segment
		(start 295.41851 -212.45449)
		(end 295.158668 -212.194648)
		(width 0.18288)
		(layer "In11.Cu")
		(net "M_D_CPU0_SB_DQS_DN<1>")
	)
	(segment
		(start 297.83659 -211.671408)
		(end 297.41622 -212.091524)
		(width 0.18288)
		(layer "In11.Cu")
		(net "M_D_CPU0_SB_DQS_DN<1>")
	)
	(segment
		(start 274.651724 -215.99906)
		(end 274.776184 -216.12352)
		(width 0.18288)
		(layer "In11.Cu")
		(net "M_D_CPU0_SB_DQS_DN<1>")
	)
	(segment
		(start 286.720788 -211.462366)
		(end 286.172148 -211.462366)
		(width 0.18288)
		(layer "In11.Cu")
		(net "M_D_CPU0_SB_DQS_DN<1>")
	)
	(segment
		(start 278.667718 -212.47608)
		(end 278.04237 -211.850732)
		(width 0.18288)
		(layer "In11.Cu")
		(net "M_D_CPU0_SB_DQS_DN<1>")
	)
	(segment
		(start 274.776184 -216.12352)
		(end 274.776184 -216.67216)
		(width 0.18288)
		(layer "In11.Cu")
		(net "M_D_CPU0_SB_DQS_DN<1>")
	)
	(segment
		(start 287.393888 -211.586826)
		(end 286.845248 -211.586826)
		(width 0.18288)
		(layer "In11.Cu")
		(net "M_D_CPU0_SB_DQS_DN<1>")
	)
	(segment
		(start 342.946482 -235.294424)
		(end 342.93175 -235.285788)
		(width 0.088646)
		(layer "In11.Cu")
		(net "M_D_CPU0_SB_DQS_DN<1>")
	)
	(segment
		(start 271.095724 -218.93276)
		(end 270.769334 -219.259404)
		(width 0.18288)
		(layer "In11.Cu")
		(net "M_D_CPU0_SB_DQS_DN<1>")
	)
	(segment
		(start 328.217022 -231.072436)
		(end 316.521592 -219.377006)
		(width 0.18288)
		(layer "In11.Cu")
		(net "M_D_CPU0_SB_DQS_DN<1>")
	)
	(segment
		(start 338.247482 -233.666538)
		(end 338.23275 -233.657902)
		(width 0.088646)
		(layer "In11.Cu")
		(net "M_D_CPU0_SB_DQS_DN<1>")
	)
	(segment
		(start 315.463174 -216.821766)
		(end 314.786518 -216.145364)
		(width 0.18288)
		(layer "In11.Cu")
		(net "M_D_CPU0_SB_DQS_DN<1>")
	)
	(segment
		(start 283.721048 -211.343748)
		(end 283.403548 -211.661248)
		(width 0.18288)
		(layer "In11.Cu")
		(net "M_D_CPU0_SB_DQS_DN<1>")
	)
	(segment
		(start 299.487336 -211.591144)
		(end 299.237146 -211.340954)
		(width 0.18288)
		(layer "In11.Cu")
		(net "M_D_CPU0_SB_DQS_DN<1>")
	)
	(segment
		(start 286.047688 -211.586826)
		(end 284.415738 -211.586826)
		(width 0.18288)
		(layer "In11.Cu")
		(net "M_D_CPU0_SB_DQS_DN<1>")
	)
	(segment
		(start 313.341512 -215.760808)
		(end 312.792872 -215.760808)
		(width 0.18288)
		(layer "In11.Cu")
		(net "M_D_CPU0_SB_DQS_DN<1>")
	)
	(segment
		(start 312.668412 -215.885268)
		(end 311.820306 -215.885268)
		(width 0.18288)
		(layer "In11.Cu")
		(net "M_D_CPU0_SB_DQS_DN<1>")
	)
	(segment
		(start 283.403548 -211.661248)
		(end 282.785058 -211.661248)
		(width 0.18288)
		(layer "In11.Cu")
		(net "M_D_CPU0_SB_DQS_DN<1>")
	)
	(segment
		(start 269.100046 -218.990926)
		(end 268.628622 -218.990926)
		(width 0.18288)
		(layer "In11.Cu")
		(net "M_D_CPU0_SB_DQS_DN<1>")
	)
	(segment
		(start 339.187536 -233.666538)
		(end 339.177122 -233.660442)
		(width 0.088646)
		(layer "In11.Cu")
		(net "M_D_CPU0_SB_DQS_DN<1>")
	)
	(segment
		(start 298.480988 -211.671408)
		(end 297.83659 -211.671408)
		(width 0.18288)
		(layer "In11.Cu")
		(net "M_D_CPU0_SB_DQS_DN<1>")
	)
	(segment
		(start 337.307682 -233.666538)
		(end 337.298792 -233.661458)
		(width 0.088646)
		(layer "In11.Cu")
		(net "M_D_CPU0_SB_DQS_DN<1>")
	)
	(segment
		(start 310.354472 -215.278208)
		(end 309.683912 -215.000586)
		(width 0.18288)
		(layer "In11.Cu")
		(net "M_D_CPU0_SB_DQS_DN<1>")
	)
	(segment
		(start 337.12023 -233.34218)
		(end 337.12023 -233.326686)
		(width 0.088646)
		(layer "In11.Cu")
		(net "M_D_CPU0_SB_DQS_DN<1>")
	)
	(segment
		(start 273.948144 -217.751152)
		(end 271.095724 -218.93276)
		(width 0.18288)
		(layer "In11.Cu")
		(net "M_D_CPU0_SB_DQS_DN<1>")
	)
	(segment
		(start 268.381988 -219.23756)
		(end 267.656564 -219.23756)
		(width 0.18288)
		(layer "In11.Cu")
		(net "M_D_CPU0_SB_DQS_DN<1>")
	)
	(segment
		(start 331.075792 -231.89057)
		(end 331.075792 -231.409748)
		(width 0.088646)
		(layer "In11.Cu")
		(net "M_D_CPU0_SB_DQS_DN<1>")
	)
	(segment
		(start 336.287364 -232.844086)
		(end 336.272632 -232.852722)
		(width 0.088646)
		(layer "In11.Cu")
		(net "M_D_CPU0_SB_DQS_DN<1>")
	)
	(segment
		(start 303.132236 -211.868004)
		(end 302.969676 -211.935314)
		(width 0.18288)
		(layer "In11.Cu")
		(net "M_D_CPU0_SB_DQS_DN<1>")
	)
	(segment
		(start 298.811442 -211.340954)
		(end 298.480988 -211.671408)
		(width 0.18288)
		(layer "In11.Cu")
		(net "M_D_CPU0_SB_DQS_DN<1>")
	)
	(arc
		(start 340.87943 -234.954572)
		(mid 340.80006 -234.680838)
		(end 340.597236 -234.480608)
		(width 0.088646)
		(layer "In11.Cu")
		(net "M_D_CPU0_SB_DQS_DN<1>")
	)
	(arc
		(start 332.513178 -232.852722)
		(mid 332.422922 -232.890444)
		(end 332.32598 -232.903522)
		(width 0.088646)
		(layer "In11.Cu")
		(net "M_D_CPU0_SB_DQS_DN<1>")
	)
	(arc
		(start 334.393032 -232.852722)
		(mid 334.205834 -232.902865)
		(end 334.018636 -232.852722)
		(width 0.088646)
		(layer "In11.Cu")
		(net "M_D_CPU0_SB_DQS_DN<1>")
	)
	(arc
		(start 337.682078 -233.666538)
		(mid 337.49488 -233.716681)
		(end 337.307682 -233.666538)
		(width 0.088646)
		(layer "In11.Cu")
		(net "M_D_CPU0_SB_DQS_DN<1>")
	)
	(arc
		(start 345.200732 -235.294424)
		(mid 345.013534 -235.344567)
		(end 344.826336 -235.294424)
		(width 0.088646)
		(layer "In11.Cu")
		(net "M_D_CPU0_SB_DQS_DN<1>")
	)
	(arc
		(start 333.452978 -232.852722)
		(mid 333.26578 -232.902865)
		(end 333.078582 -232.852722)
		(width 0.088646)
		(layer "In11.Cu")
		(net "M_D_CPU0_SB_DQS_DN<1>")
	)
	(arc
		(start 335.898236 -232.852722)
		(mid 335.615534 -232.776946)
		(end 335.332832 -232.852722)
		(width 0.088646)
		(layer "In11.Cu")
		(net "M_D_CPU0_SB_DQS_DN<1>")
	)
	(arc
		(start 339.177122 -233.660442)
		(mid 338.89869 -233.590628)
		(end 338.621878 -233.666538)
		(width 0.088646)
		(layer "In11.Cu")
		(net "M_D_CPU0_SB_DQS_DN<1>")
	)
	(arc
		(start 345.882468 -235.107988)
		(mid 345.807783 -235.138493)
		(end 345.727782 -235.148882)
		(width 0.088646)
		(layer "In11.Cu")
		(net "M_D_CPU0_SB_DQS_DN<1>")
	)
	(arc
		(start 341.441278 -235.294424)
		(mid 341.25408 -235.344567)
		(end 341.066882 -235.294424)
		(width 0.088646)
		(layer "In11.Cu")
		(net "M_D_CPU0_SB_DQS_DN<1>")
	)
	(arc
		(start 343.87155 -235.285788)
		(mid 343.595075 -235.218468)
		(end 343.320878 -235.294424)
		(width 0.088646)
		(layer "In11.Cu")
		(net "M_D_CPU0_SB_DQS_DN<1>")
	)
	(arc
		(start 337.298792 -233.661458)
		(mid 337.167878 -233.525098)
		(end 337.12023 -233.34218)
		(width 0.088646)
		(layer "In11.Cu")
		(net "M_D_CPU0_SB_DQS_DN<1>")
	)
	(arc
		(start 340.409784 -234.142026)
		(mid 340.330565 -233.867341)
		(end 340.127082 -233.666538)
		(width 0.088646)
		(layer "In11.Cu")
		(net "M_D_CPU0_SB_DQS_DN<1>")
	)
	(arc
		(start 342.381078 -235.294424)
		(mid 342.19388 -235.344567)
		(end 342.006682 -235.294424)
		(width 0.088646)
		(layer "In11.Cu")
		(net "M_D_CPU0_SB_DQS_DN<1>")
	)
	(arc
		(start 334.958436 -232.852722)
		(mid 334.675734 -232.776946)
		(end 334.393032 -232.852722)
		(width 0.088646)
		(layer "In11.Cu")
		(net "M_D_CPU0_SB_DQS_DN<1>")
	)
	(arc
		(start 341.057992 -235.289344)
		(mid 340.927078 -235.152984)
		(end 340.87943 -234.970066)
		(width 0.088646)
		(layer "In11.Cu")
		(net "M_D_CPU0_SB_DQS_DN<1>")
	)
	(arc
		(start 343.320878 -235.294424)
		(mid 343.13368 -235.344567)
		(end 342.946482 -235.294424)
		(width 0.088646)
		(layer "In11.Cu")
		(net "M_D_CPU0_SB_DQS_DN<1>")
	)
	(arc
		(start 336.838036 -232.852722)
		(mid 336.563837 -232.776887)
		(end 336.287364 -232.844086)
		(width 0.088646)
		(layer "In11.Cu")
		(net "M_D_CPU0_SB_DQS_DN<1>")
	)
	(arc
		(start 339.561932 -233.666538)
		(mid 339.374734 -233.716681)
		(end 339.187536 -233.666538)
		(width 0.088646)
		(layer "In11.Cu")
		(net "M_D_CPU0_SB_DQS_DN<1>")
	)
	(arc
		(start 342.93175 -235.285788)
		(mid 342.655275 -235.218468)
		(end 342.381078 -235.294424)
		(width 0.088646)
		(layer "In11.Cu")
		(net "M_D_CPU0_SB_DQS_DN<1>")
	)
	(arc
		(start 333.06385 -232.844086)
		(mid 332.787375 -232.776766)
		(end 332.513178 -232.852722)
		(width 0.088646)
		(layer "In11.Cu")
		(net "M_D_CPU0_SB_DQS_DN<1>")
	)
	(arc
		(start 340.116668 -233.660442)
		(mid 339.83849 -233.59075)
		(end 339.561932 -233.666538)
		(width 0.088646)
		(layer "In11.Cu")
		(net "M_D_CPU0_SB_DQS_DN<1>")
	)
	(arc
		(start 338.621878 -233.666538)
		(mid 338.43468 -233.716681)
		(end 338.247482 -233.666538)
		(width 0.088646)
		(layer "In11.Cu")
		(net "M_D_CPU0_SB_DQS_DN<1>")
	)
	(arc
		(start 335.332832 -232.852722)
		(mid 335.145634 -232.902865)
		(end 334.958436 -232.852722)
		(width 0.088646)
		(layer "In11.Cu")
		(net "M_D_CPU0_SB_DQS_DN<1>")
	)
	(arc
		(start 341.99195 -235.285788)
		(mid 341.715475 -235.218468)
		(end 341.441278 -235.294424)
		(width 0.088646)
		(layer "In11.Cu")
		(net "M_D_CPU0_SB_DQS_DN<1>")
	)
	(arc
		(start 337.12023 -233.326686)
		(mid 337.04086 -233.052952)
		(end 336.838036 -232.852722)
		(width 0.088646)
		(layer "In11.Cu")
		(net "M_D_CPU0_SB_DQS_DN<1>")
	)
	(arc
		(start 344.260678 -235.294424)
		(mid 344.07348 -235.344567)
		(end 343.886282 -235.294424)
		(width 0.088646)
		(layer "In11.Cu")
		(net "M_D_CPU0_SB_DQS_DN<1>")
	)
	(arc
		(start 334.008222 -232.846626)
		(mid 333.72979 -232.77678)
		(end 333.452978 -232.852722)
		(width 0.088646)
		(layer "In11.Cu")
		(net "M_D_CPU0_SB_DQS_DN<1>")
	)
	(arc
		(start 336.272632 -232.852722)
		(mid 336.085434 -232.902865)
		(end 335.898236 -232.852722)
		(width 0.088646)
		(layer "In11.Cu")
		(net "M_D_CPU0_SB_DQS_DN<1>")
	)
	(arc
		(start 338.23275 -233.657902)
		(mid 337.956309 -233.590736)
		(end 337.682078 -233.666538)
		(width 0.088646)
		(layer "In11.Cu")
		(net "M_D_CPU0_SB_DQS_DN<1>")
	)
	(arc
		(start 344.815922 -235.288328)
		(mid 344.53749 -235.218482)
		(end 344.260678 -235.294424)
		(width 0.088646)
		(layer "In11.Cu")
		(net "M_D_CPU0_SB_DQS_DN<1>")
	)
	(arc
		(start 340.588346 -234.475528)
		(mid 340.457432 -234.339168)
		(end 340.409784 -234.15625)
		(width 0.088646)
		(layer "In11.Cu")
		(net "M_D_CPU0_SB_DQS_DN<1>")
	)
	(segment
		(start 345.95308 -240.388902)
		(end 345.95308 -239.853216)
		(width 0.20066)
		(layer "F.Cu")
		(net "M_D_CPU0_SB_DQS_DN<0>")
	)
	(segment
		(start 263.077706 -227.91674)
		(end 262.816594 -228.177852)
		(width 0.20066)
		(layer "F.Cu")
		(net "M_D_CPU0_SB_DQS_DN<0>")
	)
	(segment
		(start 258.852162 -228.331014)
		(end 258.580128 -228.603048)
		(width 0.20066)
		(layer "F.Cu")
		(net "M_D_CPU0_SB_DQS_DN<0>")
	)
	(segment
		(start 264.729214 -227.91674)
		(end 263.624314 -227.91674)
		(width 0.20066)
		(layer "F.Cu")
		(net "M_D_CPU0_SB_DQS_DN<0>")
	)
	(segment
		(start 259.056378 -228.331014)
		(end 258.852162 -228.331014)
		(width 0.20066)
		(layer "F.Cu")
		(net "M_D_CPU0_SB_DQS_DN<0>")
	)
	(segment
		(start 258.040124 -228.603048)
		(end 257.404108 -228.177852)
		(width 0.20066)
		(layer "F.Cu")
		(net "M_D_CPU0_SB_DQS_DN<0>")
	)
	(segment
		(start 256.890266 -228.177852)
		(end 256.629154 -227.91674)
		(width 0.20066)
		(layer "F.Cu")
		(net "M_D_CPU0_SB_DQS_DN<0>")
	)
	(segment
		(start 261.984744 -228.603048)
		(end 261.798054 -228.603048)
		(width 0.20066)
		(layer "F.Cu")
		(net "M_D_CPU0_SB_DQS_DN<0>")
	)
	(segment
		(start 261.798054 -228.603048)
		(end 261.536688 -228.341682)
		(width 0.20066)
		(layer "F.Cu")
		(net "M_D_CPU0_SB_DQS_DN<0>")
	)
	(segment
		(start 259.067808 -228.341682)
		(end 259.05714 -228.331014)
		(width 0.101854)
		(layer "F.Cu")
		(net "M_D_CPU0_SB_DQS_DN<0>")
	)
	(segment
		(start 262.40994 -228.177852)
		(end 261.984744 -228.603048)
		(width 0.20066)
		(layer "F.Cu")
		(net "M_D_CPU0_SB_DQS_DN<0>")
	)
	(segment
		(start 258.580128 -228.603048)
		(end 258.040124 -228.603048)
		(width 0.20066)
		(layer "F.Cu")
		(net "M_D_CPU0_SB_DQS_DN<0>")
	)
	(segment
		(start 256.629154 -227.91674)
		(end 256.080514 -227.91674)
		(width 0.20066)
		(layer "F.Cu")
		(net "M_D_CPU0_SB_DQS_DN<0>")
	)
	(segment
		(start 257.404108 -228.177852)
		(end 256.890266 -228.177852)
		(width 0.20066)
		(layer "F.Cu")
		(net "M_D_CPU0_SB_DQS_DN<0>")
	)
	(segment
		(start 259.05714 -228.331014)
		(end 259.056378 -228.331014)
		(width 0.101854)
		(layer "F.Cu")
		(net "M_D_CPU0_SB_DQS_DN<0>")
	)
	(segment
		(start 345.953334 -240.389156)
		(end 345.95308 -240.388902)
		(width 0.20066)
		(layer "F.Cu")
		(net "M_D_CPU0_SB_DQS_DN<0>")
	)
	(segment
		(start 261.536688 -228.341682)
		(end 261.381494 -228.341682)
		(width 0.20066)
		(layer "F.Cu")
		(net "M_D_CPU0_SB_DQS_DN<0>")
	)
	(segment
		(start 261.381494 -228.341682)
		(end 259.067808 -228.341682)
		(width 0.1016)
		(layer "F.Cu")
		(net "M_D_CPU0_SB_DQS_DN<0>")
	)
	(segment
		(start 263.624314 -227.91674)
		(end 263.077706 -227.91674)
		(width 0.20066)
		(layer "F.Cu")
		(net "M_D_CPU0_SB_DQS_DN<0>")
	)
	(segment
		(start 262.816594 -228.177852)
		(end 262.40994 -228.177852)
		(width 0.20066)
		(layer "F.Cu")
		(net "M_D_CPU0_SB_DQS_DN<0>")
	)
	(segment
		(start 293.730934 -225.228912)
		(end 293.158926 -225.80092)
		(width 0.18288)
		(layer "In11.Cu")
		(net "M_D_CPU0_SB_DQS_DN<0>")
	)
	(segment
		(start 269.073884 -228.342444)
		(end 268.610334 -228.342444)
		(width 0.18288)
		(layer "In11.Cu")
		(net "M_D_CPU0_SB_DQS_DN<0>")
	)
	(segment
		(start 269.308072 -228.576632)
		(end 269.073884 -228.342444)
		(width 0.18288)
		(layer "In11.Cu")
		(net "M_D_CPU0_SB_DQS_DN<0>")
	)
	(segment
		(start 330.336906 -237.113826)
		(end 323.87667 -237.113826)
		(width 0.18288)
		(layer "In11.Cu")
		(net "M_D_CPU0_SB_DQS_DN<0>")
	)
	(segment
		(start 310.938926 -226.892866)
		(end 310.520334 -226.892866)
		(width 0.18288)
		(layer "In11.Cu")
		(net "M_D_CPU0_SB_DQS_DN<0>")
	)
	(segment
		(start 330.715112 -237.173516)
		(end 330.396596 -237.173516)
		(width 0.088646)
		(layer "In11.Cu")
		(net "M_D_CPU0_SB_DQS_DN<0>")
	)
	(segment
		(start 319.292732 -232.353866)
		(end 319.11671 -232.353866)
		(width 0.18288)
		(layer "In11.Cu")
		(net "M_D_CPU0_SB_DQS_DN<0>")
	)
	(segment
		(start 317.212726 -230.449882)
		(end 316.824868 -230.062024)
		(width 0.18288)
		(layer "In11.Cu")
		(net "M_D_CPU0_SB_DQS_DN<0>")
	)
	(segment
		(start 282.270962 -224.714054)
		(end 281.79395 -225.191066)
		(width 0.18288)
		(layer "In11.Cu")
		(net "M_D_CPU0_SB_DQS_DN<0>")
	)
	(segment
		(start 298.802806 -224.092008)
		(end 298.514262 -224.380552)
		(width 0.18288)
		(layer "In11.Cu")
		(net "M_D_CPU0_SB_DQS_DN<0>")
	)
	(segment
		(start 314.334906 -228.341428)
		(end 313.840114 -228.341428)
		(width 0.18288)
		(layer "In11.Cu")
		(net "M_D_CPU0_SB_DQS_DN<0>")
	)
	(segment
		(start 336.18043 -239.853216)
		(end 336.18043 -239.837722)
		(width 0.088646)
		(layer "In11.Cu")
		(net "M_D_CPU0_SB_DQS_DN<0>")
	)
	(segment
		(start 313.562238 -228.619304)
		(end 313.093862 -228.619304)
		(width 0.18288)
		(layer "In11.Cu")
		(net "M_D_CPU0_SB_DQS_DN<0>")
	)
	(segment
		(start 318.728852 -231.966008)
		(end 318.728852 -231.789986)
		(width 0.18288)
		(layer "In11.Cu")
		(net "M_D_CPU0_SB_DQS_DN<0>")
	)
	(segment
		(start 334.770984 -239.0394)
		(end 334.770984 -239.029494)
		(width 0.088646)
		(layer "In11.Cu")
		(net "M_D_CPU0_SB_DQS_DN<0>")
	)
	(segment
		(start 283.723842 -224.090992)
		(end 283.424122 -224.390712)
		(width 0.18288)
		(layer "In11.Cu")
		(net "M_D_CPU0_SB_DQS_DN<0>")
	)
	(segment
		(start 315.40069 -228.637846)
		(end 314.631324 -228.637846)
		(width 0.18288)
		(layer "In11.Cu")
		(net "M_D_CPU0_SB_DQS_DN<0>")
	)
	(segment
		(start 265.90752 -227.946966)
		(end 265.368532 -228.170232)
		(width 0.18288)
		(layer "In11.Cu")
		(net "M_D_CPU0_SB_DQS_DN<0>")
	)
	(segment
		(start 312.706004 -228.231446)
		(end 312.706004 -228.055424)
		(width 0.18288)
		(layer "In11.Cu")
		(net "M_D_CPU0_SB_DQS_DN<0>")
	)
	(segment
		(start 317.77686 -230.837994)
		(end 317.388748 -230.449882)
		(width 0.18288)
		(layer "In11.Cu")
		(net "M_D_CPU0_SB_DQS_DN<0>")
	)
	(segment
		(start 332.015846 -238.47425)
		(end 330.715112 -237.173516)
		(width 0.088646)
		(layer "In11.Cu")
		(net "M_D_CPU0_SB_DQS_DN<0>")
	)
	(segment
		(start 297.927268 -224.380552)
		(end 297.537378 -224.770188)
		(width 0.18288)
		(layer "In11.Cu")
		(net "M_D_CPU0_SB_DQS_DN<0>")
	)
	(segment
		(start 280.337514 -225.191066)
		(end 280.087578 -224.94113)
		(width 0.18288)
		(layer "In11.Cu")
		(net "M_D_CPU0_SB_DQS_DN<0>")
	)
	(segment
		(start 338.632546 -240.171478)
		(end 338.622132 -240.177574)
		(width 0.088646)
		(layer "In11.Cu")
		(net "M_D_CPU0_SB_DQS_DN<0>")
	)
	(segment
		(start 299.505878 -224.347024)
		(end 299.250862 -224.092008)
		(width 0.18288)
		(layer "In11.Cu")
		(net "M_D_CPU0_SB_DQS_DN<0>")
	)
	(segment
		(start 345.200986 -240.177828)
		(end 345.200732 -240.177574)
		(width 0.088646)
		(layer "In11.Cu")
		(net "M_D_CPU0_SB_DQS_DN<0>")
	)
	(segment
		(start 267.89761 -228.415342)
		(end 266.766294 -227.946966)
		(width 0.18288)
		(layer "In11.Cu")
		(net "M_D_CPU0_SB_DQS_DN<0>")
	)
	(segment
		(start 309.767986 -226.641152)
		(end 309.524908 -226.88423)
		(width 0.18288)
		(layer "In11.Cu")
		(net "M_D_CPU0_SB_DQS_DN<0>")
	)
	(segment
		(start 342.946482 -240.177574)
		(end 342.93175 -240.168938)
		(width 0.088646)
		(layer "In11.Cu")
		(net "M_D_CPU0_SB_DQS_DN<0>")
	)
	(segment
		(start 323.488812 -236.725968)
		(end 323.488812 -236.549946)
		(width 0.18288)
		(layer "In11.Cu")
		(net "M_D_CPU0_SB_DQS_DN<0>")
	)
	(segment
		(start 294.706802 -224.94113)
		(end 294.41902 -225.228912)
		(width 0.18288)
		(layer "In11.Cu")
		(net "M_D_CPU0_SB_DQS_DN<0>")
	)
	(segment
		(start 302.505872 -224.347024)
		(end 299.505878 -224.347024)
		(width 0.18288)
		(layer "In11.Cu")
		(net "M_D_CPU0_SB_DQS_DN<0>")
	)
	(segment
		(start 289.20694 -225.219006)
		(end 287.067498 -224.332038)
		(width 0.18288)
		(layer "In11.Cu")
		(net "M_D_CPU0_SB_DQS_DN<0>")
	)
	(segment
		(start 322.53682 -235.773976)
		(end 322.53682 -235.597954)
		(width 0.18288)
		(layer "In11.Cu")
		(net "M_D_CPU0_SB_DQS_DN<0>")
	)
	(segment
		(start 279.33904 -225.213672)
		(end 278.788114 -225.213672)
		(width 0.18288)
		(layer "In11.Cu")
		(net "M_D_CPU0_SB_DQS_DN<0>")
	)
	(segment
		(start 330.396596 -237.173516)
		(end 330.336906 -237.113826)
		(width 0.088646)
		(layer "In11.Cu")
		(net "M_D_CPU0_SB_DQS_DN<0>")
	)
	(segment
		(start 340.127082 -240.177574)
		(end 340.11235 -240.168938)
		(width 0.088646)
		(layer "In11.Cu")
		(net "M_D_CPU0_SB_DQS_DN<0>")
	)
	(segment
		(start 279.611582 -224.94113)
		(end 279.33904 -225.213672)
		(width 0.18288)
		(layer "In11.Cu")
		(net "M_D_CPU0_SB_DQS_DN<0>")
	)
	(segment
		(start 283.04998 -224.390712)
		(end 282.270962 -224.714054)
		(width 0.18288)
		(layer "In11.Cu")
		(net "M_D_CPU0_SB_DQS_DN<0>")
	)
	(segment
		(start 342.006682 -240.177574)
		(end 341.99195 -240.168938)
		(width 0.088646)
		(layer "In11.Cu")
		(net "M_D_CPU0_SB_DQS_DN<0>")
	)
	(segment
		(start 268.352524 -228.600254)
		(end 268.082522 -228.600254)
		(width 0.18288)
		(layer "In11.Cu")
		(net "M_D_CPU0_SB_DQS_DN<0>")
	)
	(segment
		(start 287.067498 -224.332038)
		(end 284.390592 -224.332038)
		(width 0.18288)
		(layer "In11.Cu")
		(net "M_D_CPU0_SB_DQS_DN<0>")
	)
	(segment
		(start 322.924678 -236.161834)
		(end 322.53682 -235.773976)
		(width 0.18288)
		(layer "In11.Cu")
		(net "M_D_CPU0_SB_DQS_DN<0>")
	)
	(segment
		(start 303.790096 -224.8789)
		(end 303.722786 -224.716086)
		(width 0.18288)
		(layer "In11.Cu")
		(net "M_D_CPU0_SB_DQS_DN<0>")
	)
	(segment
		(start 268.082522 -228.600254)
		(end 267.89761 -228.415342)
		(width 0.18288)
		(layer "In11.Cu")
		(net "M_D_CPU0_SB_DQS_DN<0>")
	)
	(segment
		(start 297.537378 -224.770188)
		(end 296.510202 -225.195892)
		(width 0.18288)
		(layer "In11.Cu")
		(net "M_D_CPU0_SB_DQS_DN<0>")
	)
	(segment
		(start 316.824868 -229.886002)
		(end 316.436756 -229.49789)
		(width 0.18288)
		(layer "In11.Cu")
		(net "M_D_CPU0_SB_DQS_DN<0>")
	)
	(segment
		(start 335.347564 -239.355122)
		(end 335.332832 -239.363758)
		(width 0.088646)
		(layer "In11.Cu")
		(net "M_D_CPU0_SB_DQS_DN<0>")
	)
	(segment
		(start 299.250862 -224.092008)
		(end 298.802806 -224.092008)
		(width 0.18288)
		(layer "In11.Cu")
		(net "M_D_CPU0_SB_DQS_DN<0>")
	)
	(segment
		(start 307.37937 -225.642932)
		(end 306.43957 -225.25355)
		(width 0.18288)
		(layer "In11.Cu")
		(net "M_D_CPU0_SB_DQS_DN<0>")
	)
	(segment
		(start 322.53682 -235.597954)
		(end 322.148708 -235.209842)
		(width 0.18288)
		(layer "In11.Cu")
		(net "M_D_CPU0_SB_DQS_DN<0>")
	)
	(segment
		(start 323.488812 -236.549946)
		(end 323.1007 -236.161834)
		(width 0.18288)
		(layer "In11.Cu")
		(net "M_D_CPU0_SB_DQS_DN<0>")
	)
	(segment
		(start 311.6707 -227.195888)
		(end 310.938926 -226.892866)
		(width 0.18288)
		(layer "In11.Cu")
		(net "M_D_CPU0_SB_DQS_DN<0>")
	)
	(segment
		(start 309.016908 -226.88423)
		(end 308.38521 -226.252278)
		(width 0.18288)
		(layer "In11.Cu")
		(net "M_D_CPU0_SB_DQS_DN<0>")
	)
	(segment
		(start 317.77686 -231.014016)
		(end 317.77686 -230.837994)
		(width 0.18288)
		(layer "In11.Cu")
		(net "M_D_CPU0_SB_DQS_DN<0>")
	)
	(segment
		(start 310.520334 -226.892866)
		(end 310.26862 -226.641152)
		(width 0.18288)
		(layer "In11.Cu")
		(net "M_D_CPU0_SB_DQS_DN<0>")
	)
	(segment
		(start 322.148708 -235.209842)
		(end 321.972686 -235.209842)
		(width 0.18288)
		(layer "In11.Cu")
		(net "M_D_CPU0_SB_DQS_DN<0>")
	)
	(segment
		(start 292.473888 -225.80092)
		(end 291.070284 -225.219006)
		(width 0.18288)
		(layer "In11.Cu")
		(net "M_D_CPU0_SB_DQS_DN<0>")
	)
	(segment
		(start 344.826336 -240.177574)
		(end 344.815922 -240.171478)
		(width 0.088646)
		(layer "In11.Cu")
		(net "M_D_CPU0_SB_DQS_DN<0>")
	)
	(segment
		(start 266.766294 -227.946966)
		(end 265.90752 -227.946966)
		(width 0.18288)
		(layer "In11.Cu")
		(net "M_D_CPU0_SB_DQS_DN<0>")
	)
	(segment
		(start 310.26862 -226.641152)
		(end 309.767986 -226.641152)
		(width 0.18288)
		(layer "In11.Cu")
		(net "M_D_CPU0_SB_DQS_DN<0>")
	)
	(segment
		(start 334.958436 -239.363758)
		(end 334.949546 -239.358678)
		(width 0.088646)
		(layer "In11.Cu")
		(net "M_D_CPU0_SB_DQS_DN<0>")
	)
	(segment
		(start 280.087578 -224.94113)
		(end 279.611582 -224.94113)
		(width 0.18288)
		(layer "In11.Cu")
		(net "M_D_CPU0_SB_DQS_DN<0>")
	)
	(segment
		(start 296.510202 -225.195892)
		(end 295.42994 -225.195892)
		(width 0.18288)
		(layer "In11.Cu")
		(net "M_D_CPU0_SB_DQS_DN<0>")
	)
	(segment
		(start 341.066882 -240.177574)
		(end 341.05215 -240.168938)
		(width 0.088646)
		(layer "In11.Cu")
		(net "M_D_CPU0_SB_DQS_DN<0>")
	)
	(segment
		(start 295.175178 -224.94113)
		(end 294.706802 -224.94113)
		(width 0.18288)
		(layer "In11.Cu")
		(net "M_D_CPU0_SB_DQS_DN<0>")
	)
	(segment
		(start 268.610334 -228.342444)
		(end 268.352524 -228.600254)
		(width 0.18288)
		(layer "In11.Cu")
		(net "M_D_CPU0_SB_DQS_DN<0>")
	)
	(segment
		(start 323.87667 -237.113826)
		(end 323.488812 -236.725968)
		(width 0.18288)
		(layer "In11.Cu")
		(net "M_D_CPU0_SB_DQS_DN<0>")
	)
	(segment
		(start 312.706004 -228.055424)
		(end 312.317892 -227.667312)
		(width 0.18288)
		(layer "In11.Cu")
		(net "M_D_CPU0_SB_DQS_DN<0>")
	)
	(segment
		(start 291.070284 -225.219006)
		(end 289.20694 -225.219006)
		(width 0.18288)
		(layer "In11.Cu")
		(net "M_D_CPU0_SB_DQS_DN<0>")
	)
	(segment
		(start 293.158926 -225.80092)
		(end 292.473888 -225.80092)
		(width 0.18288)
		(layer "In11.Cu")
		(net "M_D_CPU0_SB_DQS_DN<0>")
	)
	(segment
		(start 316.260734 -229.49789)
		(end 315.40069 -228.637846)
		(width 0.18288)
		(layer "In11.Cu")
		(net "M_D_CPU0_SB_DQS_DN<0>")
	)
	(segment
		(start 306.43957 -225.25355)
		(end 304.69459 -225.25355)
		(width 0.18288)
		(layer "In11.Cu")
		(net "M_D_CPU0_SB_DQS_DN<0>")
	)
	(segment
		(start 278.788114 -225.213672)
		(end 278.090376 -225.502216)
		(width 0.18288)
		(layer "In11.Cu")
		(net "M_D_CPU0_SB_DQS_DN<0>")
	)
	(segment
		(start 319.680844 -232.918)
		(end 319.680844 -232.741978)
		(width 0.18288)
		(layer "In11.Cu")
		(net "M_D_CPU0_SB_DQS_DN<0>")
	)
	(segment
		(start 276.901148 -226.691444)
		(end 272.349722 -228.576632)
		(width 0.18288)
		(layer "In11.Cu")
		(net "M_D_CPU0_SB_DQS_DN<0>")
	)
	(segment
		(start 318.164718 -231.401874)
		(end 317.77686 -231.014016)
		(width 0.18288)
		(layer "In11.Cu")
		(net "M_D_CPU0_SB_DQS_DN<0>")
	)
	(segment
		(start 319.11671 -232.353866)
		(end 318.728852 -231.966008)
		(width 0.18288)
		(layer "In11.Cu")
		(net "M_D_CPU0_SB_DQS_DN<0>")
	)
	(segment
		(start 314.631324 -228.637846)
		(end 314.334906 -228.341428)
		(width 0.18288)
		(layer "In11.Cu")
		(net "M_D_CPU0_SB_DQS_DN<0>")
	)
	(segment
		(start 283.424122 -224.390712)
		(end 283.04998 -224.390712)
		(width 0.18288)
		(layer "In11.Cu")
		(net "M_D_CPU0_SB_DQS_DN<0>")
	)
	(segment
		(start 313.840114 -228.341428)
		(end 313.562238 -228.619304)
		(width 0.18288)
		(layer "In11.Cu")
		(net "M_D_CPU0_SB_DQS_DN<0>")
	)
	(segment
		(start 320.068702 -233.305858)
		(end 319.680844 -232.918)
		(width 0.18288)
		(layer "In11.Cu")
		(net "M_D_CPU0_SB_DQS_DN<0>")
	)
	(segment
		(start 320.244724 -233.305858)
		(end 320.068702 -233.305858)
		(width 0.18288)
		(layer "In11.Cu")
		(net "M_D_CPU0_SB_DQS_DN<0>")
	)
	(segment
		(start 321.584828 -234.821984)
		(end 321.584828 -234.645962)
		(width 0.18288)
		(layer "In11.Cu")
		(net "M_D_CPU0_SB_DQS_DN<0>")
	)
	(segment
		(start 303.722786 -224.716086)
		(end 303.215548 -224.506282)
		(width 0.18288)
		(layer "In11.Cu")
		(net "M_D_CPU0_SB_DQS_DN<0>")
	)
	(segment
		(start 321.020694 -234.25785)
		(end 320.632836 -233.869992)
		(width 0.18288)
		(layer "In11.Cu")
		(net "M_D_CPU0_SB_DQS_DN<0>")
	)
	(segment
		(start 345.454224 -240.032032)
		(end 345.200986 -240.177828)
		(width 0.088646)
		(layer "In11.Cu")
		(net "M_D_CPU0_SB_DQS_DN<0>")
	)
	(segment
		(start 284.149546 -224.090992)
		(end 283.723842 -224.090992)
		(width 0.18288)
		(layer "In11.Cu")
		(net "M_D_CPU0_SB_DQS_DN<0>")
	)
	(segment
		(start 264.982706 -228.170232)
		(end 264.729214 -227.91674)
		(width 0.18288)
		(layer "In11.Cu")
		(net "M_D_CPU0_SB_DQS_DN<0>")
	)
	(segment
		(start 298.514262 -224.380552)
		(end 297.927268 -224.380552)
		(width 0.18288)
		(layer "In11.Cu")
		(net "M_D_CPU0_SB_DQS_DN<0>")
	)
	(segment
		(start 323.1007 -236.161834)
		(end 322.924678 -236.161834)
		(width 0.18288)
		(layer "In11.Cu")
		(net "M_D_CPU0_SB_DQS_DN<0>")
	)
	(segment
		(start 304.69459 -225.25355)
		(end 303.790096 -224.8789)
		(width 0.18288)
		(layer "In11.Cu")
		(net "M_D_CPU0_SB_DQS_DN<0>")
	)
	(segment
		(start 321.196716 -234.25785)
		(end 321.020694 -234.25785)
		(width 0.18288)
		(layer "In11.Cu")
		(net "M_D_CPU0_SB_DQS_DN<0>")
	)
	(segment
		(start 336.367882 -240.177574)
		(end 336.358992 -240.172494)
		(width 0.088646)
		(layer "In11.Cu")
		(net "M_D_CPU0_SB_DQS_DN<0>")
	)
	(segment
		(start 317.388748 -230.449882)
		(end 317.212726 -230.449882)
		(width 0.18288)
		(layer "In11.Cu")
		(net "M_D_CPU0_SB_DQS_DN<0>")
	)
	(segment
		(start 343.886282 -240.177574)
		(end 343.87155 -240.168938)
		(width 0.088646)
		(layer "In11.Cu")
		(net "M_D_CPU0_SB_DQS_DN<0>")
	)
	(segment
		(start 321.972686 -235.209842)
		(end 321.584828 -234.821984)
		(width 0.18288)
		(layer "In11.Cu")
		(net "M_D_CPU0_SB_DQS_DN<0>")
	)
	(segment
		(start 309.524908 -226.88423)
		(end 309.016908 -226.88423)
		(width 0.18288)
		(layer "In11.Cu")
		(net "M_D_CPU0_SB_DQS_DN<0>")
	)
	(segment
		(start 284.390592 -224.332038)
		(end 284.149546 -224.090992)
		(width 0.18288)
		(layer "In11.Cu")
		(net "M_D_CPU0_SB_DQS_DN<0>")
	)
	(segment
		(start 316.824868 -230.062024)
		(end 316.824868 -229.886002)
		(width 0.18288)
		(layer "In11.Cu")
		(net "M_D_CPU0_SB_DQS_DN<0>")
	)
	(segment
		(start 294.41902 -225.228912)
		(end 293.730934 -225.228912)
		(width 0.18288)
		(layer "In11.Cu")
		(net "M_D_CPU0_SB_DQS_DN<0>")
	)
	(segment
		(start 345.92133 -239.96904)
		(end 345.882468 -239.991138)
		(width 0.088646)
		(layer "In11.Cu")
		(net "M_D_CPU0_SB_DQS_DN<0>")
	)
	(segment
		(start 319.680844 -232.741978)
		(end 319.292732 -232.353866)
		(width 0.18288)
		(layer "In11.Cu")
		(net "M_D_CPU0_SB_DQS_DN<0>")
	)
	(segment
		(start 303.215548 -224.506282)
		(end 303.052988 -224.573592)
		(width 0.18288)
		(layer "In11.Cu")
		(net "M_D_CPU0_SB_DQS_DN<0>")
	)
	(segment
		(start 265.368532 -228.170232)
		(end 264.982706 -228.170232)
		(width 0.18288)
		(layer "In11.Cu")
		(net "M_D_CPU0_SB_DQS_DN<0>")
	)
	(segment
		(start 272.349722 -228.576632)
		(end 269.308072 -228.576632)
		(width 0.18288)
		(layer "In11.Cu")
		(net "M_D_CPU0_SB_DQS_DN<0>")
	)
	(segment
		(start 281.79395 -225.191066)
		(end 280.337514 -225.191066)
		(width 0.18288)
		(layer "In11.Cu")
		(net "M_D_CPU0_SB_DQS_DN<0>")
	)
	(segment
		(start 338.247736 -240.177574)
		(end 338.237322 -240.171478)
		(width 0.088646)
		(layer "In11.Cu")
		(net "M_D_CPU0_SB_DQS_DN<0>")
	)
	(segment
		(start 345.727782 -240.032032)
		(end 345.454224 -240.032032)
		(width 0.088646)
		(layer "In11.Cu")
		(net "M_D_CPU0_SB_DQS_DN<0>")
	)
	(segment
		(start 345.95308 -239.853216)
		(end 345.92133 -239.96904)
		(width 0.088646)
		(layer "In11.Cu")
		(net "M_D_CPU0_SB_DQS_DN<0>")
	)
	(segment
		(start 337.307682 -240.177574)
		(end 337.29295 -240.168938)
		(width 0.088646)
		(layer "In11.Cu")
		(net "M_D_CPU0_SB_DQS_DN<0>")
	)
	(segment
		(start 313.093862 -228.619304)
		(end 312.706004 -228.231446)
		(width 0.18288)
		(layer "In11.Cu")
		(net "M_D_CPU0_SB_DQS_DN<0>")
	)
	(segment
		(start 278.090376 -225.502216)
		(end 276.901148 -226.691444)
		(width 0.18288)
		(layer "In11.Cu")
		(net "M_D_CPU0_SB_DQS_DN<0>")
	)
	(segment
		(start 295.42994 -225.195892)
		(end 295.175178 -224.94113)
		(width 0.18288)
		(layer "In11.Cu")
		(net "M_D_CPU0_SB_DQS_DN<0>")
	)
	(segment
		(start 332.32598 -238.47425)
		(end 332.015846 -238.47425)
		(width 0.088646)
		(layer "In11.Cu")
		(net "M_D_CPU0_SB_DQS_DN<0>")
	)
	(segment
		(start 312.14187 -227.667058)
		(end 311.6707 -227.195888)
		(width 0.18288)
		(layer "In11.Cu")
		(net "M_D_CPU0_SB_DQS_DN<0>")
	)
	(segment
		(start 320.632836 -233.69397)
		(end 320.244724 -233.305858)
		(width 0.18288)
		(layer "In11.Cu")
		(net "M_D_CPU0_SB_DQS_DN<0>")
	)
	(segment
		(start 316.436756 -229.49789)
		(end 316.260734 -229.49789)
		(width 0.18288)
		(layer "In11.Cu")
		(net "M_D_CPU0_SB_DQS_DN<0>")
	)
	(segment
		(start 318.728852 -231.789986)
		(end 318.34074 -231.401874)
		(width 0.18288)
		(layer "In11.Cu")
		(net "M_D_CPU0_SB_DQS_DN<0>")
	)
	(segment
		(start 308.38521 -226.252278)
		(end 307.707792 -225.971354)
		(width 0.18288)
		(layer "In11.Cu")
		(net "M_D_CPU0_SB_DQS_DN<0>")
	)
	(segment
		(start 321.584828 -234.645962)
		(end 321.196716 -234.25785)
		(width 0.18288)
		(layer "In11.Cu")
		(net "M_D_CPU0_SB_DQS_DN<0>")
	)
	(segment
		(start 303.052988 -224.573592)
		(end 302.505872 -224.347024)
		(width 0.18288)
		(layer "In11.Cu")
		(net "M_D_CPU0_SB_DQS_DN<0>")
	)
	(segment
		(start 320.632836 -233.869992)
		(end 320.632836 -233.69397)
		(width 0.18288)
		(layer "In11.Cu")
		(net "M_D_CPU0_SB_DQS_DN<0>")
	)
	(segment
		(start 307.707792 -225.971354)
		(end 307.37937 -225.642932)
		(width 0.18288)
		(layer "In11.Cu")
		(net "M_D_CPU0_SB_DQS_DN<0>")
	)
	(segment
		(start 318.34074 -231.401874)
		(end 318.164718 -231.401874)
		(width 0.18288)
		(layer "In11.Cu")
		(net "M_D_CPU0_SB_DQS_DN<0>")
	)
	(segment
		(start 312.317892 -227.667312)
		(end 312.14187 -227.667058)
		(width 0.18288)
		(layer "In11.Cu")
		(net "M_D_CPU0_SB_DQS_DN<0>")
	)
	(arc
		(start 339.561678 -240.177574)
		(mid 339.37448 -240.227717)
		(end 339.187282 -240.177574)
		(width 0.088646)
		(layer "In11.Cu")
		(net "M_D_CPU0_SB_DQS_DN<0>")
	)
	(arc
		(start 343.320878 -240.177574)
		(mid 343.13368 -240.227717)
		(end 342.946482 -240.177574)
		(width 0.088646)
		(layer "In11.Cu")
		(net "M_D_CPU0_SB_DQS_DN<0>")
	)
	(arc
		(start 340.11235 -240.168938)
		(mid 339.835909 -240.101772)
		(end 339.561678 -240.177574)
		(width 0.088646)
		(layer "In11.Cu")
		(net "M_D_CPU0_SB_DQS_DN<0>")
	)
	(arc
		(start 335.332832 -239.363758)
		(mid 335.145634 -239.413901)
		(end 334.958436 -239.363758)
		(width 0.088646)
		(layer "In11.Cu")
		(net "M_D_CPU0_SB_DQS_DN<0>")
	)
	(arc
		(start 333.548736 -238.549942)
		(mid 333.266034 -238.474166)
		(end 332.983332 -238.549942)
		(width 0.088646)
		(layer "In11.Cu")
		(net "M_D_CPU0_SB_DQS_DN<0>")
	)
	(arc
		(start 337.682078 -240.177574)
		(mid 337.49488 -240.227717)
		(end 337.307682 -240.177574)
		(width 0.088646)
		(layer "In11.Cu")
		(net "M_D_CPU0_SB_DQS_DN<0>")
	)
	(arc
		(start 334.488536 -238.549942)
		(mid 334.205834 -238.474166)
		(end 333.923132 -238.549942)
		(width 0.088646)
		(layer "In11.Cu")
		(net "M_D_CPU0_SB_DQS_DN<0>")
	)
	(arc
		(start 345.200732 -240.177574)
		(mid 345.013534 -240.227717)
		(end 344.826336 -240.177574)
		(width 0.088646)
		(layer "In11.Cu")
		(net "M_D_CPU0_SB_DQS_DN<0>")
	)
	(arc
		(start 343.87155 -240.168938)
		(mid 343.595109 -240.101772)
		(end 343.320878 -240.177574)
		(width 0.088646)
		(layer "In11.Cu")
		(net "M_D_CPU0_SB_DQS_DN<0>")
	)
	(arc
		(start 334.770984 -239.029494)
		(mid 334.692873 -238.752545)
		(end 334.488536 -238.549942)
		(width 0.088646)
		(layer "In11.Cu")
		(net "M_D_CPU0_SB_DQS_DN<0>")
	)
	(arc
		(start 333.923132 -238.549942)
		(mid 333.735934 -238.600085)
		(end 333.548736 -238.549942)
		(width 0.088646)
		(layer "In11.Cu")
		(net "M_D_CPU0_SB_DQS_DN<0>")
	)
	(arc
		(start 335.898236 -239.363758)
		(mid 335.624037 -239.287923)
		(end 335.347564 -239.355122)
		(width 0.088646)
		(layer "In11.Cu")
		(net "M_D_CPU0_SB_DQS_DN<0>")
	)
	(arc
		(start 336.742278 -240.177574)
		(mid 336.55508 -240.227717)
		(end 336.367882 -240.177574)
		(width 0.088646)
		(layer "In11.Cu")
		(net "M_D_CPU0_SB_DQS_DN<0>")
	)
	(arc
		(start 336.18043 -239.837722)
		(mid 336.10106 -239.563988)
		(end 335.898236 -239.363758)
		(width 0.088646)
		(layer "In11.Cu")
		(net "M_D_CPU0_SB_DQS_DN<0>")
	)
	(arc
		(start 338.622132 -240.177574)
		(mid 338.434934 -240.227717)
		(end 338.247736 -240.177574)
		(width 0.088646)
		(layer "In11.Cu")
		(net "M_D_CPU0_SB_DQS_DN<0>")
	)
	(arc
		(start 341.441278 -240.177574)
		(mid 341.25408 -240.227717)
		(end 341.066882 -240.177574)
		(width 0.088646)
		(layer "In11.Cu")
		(net "M_D_CPU0_SB_DQS_DN<0>")
	)
	(arc
		(start 338.237322 -240.171478)
		(mid 337.95889 -240.101664)
		(end 337.682078 -240.177574)
		(width 0.088646)
		(layer "In11.Cu")
		(net "M_D_CPU0_SB_DQS_DN<0>")
	)
	(arc
		(start 345.882468 -239.991138)
		(mid 345.807783 -240.021643)
		(end 345.727782 -240.032032)
		(width 0.088646)
		(layer "In11.Cu")
		(net "M_D_CPU0_SB_DQS_DN<0>")
	)
	(arc
		(start 344.260678 -240.177574)
		(mid 344.07348 -240.227717)
		(end 343.886282 -240.177574)
		(width 0.088646)
		(layer "In11.Cu")
		(net "M_D_CPU0_SB_DQS_DN<0>")
	)
	(arc
		(start 337.29295 -240.168938)
		(mid 337.016509 -240.101772)
		(end 336.742278 -240.177574)
		(width 0.088646)
		(layer "In11.Cu")
		(net "M_D_CPU0_SB_DQS_DN<0>")
	)
	(arc
		(start 334.949546 -239.358678)
		(mid 334.818632 -239.222318)
		(end 334.770984 -239.0394)
		(width 0.088646)
		(layer "In11.Cu")
		(net "M_D_CPU0_SB_DQS_DN<0>")
	)
	(arc
		(start 341.05215 -240.168938)
		(mid 340.775709 -240.101772)
		(end 340.501478 -240.177574)
		(width 0.088646)
		(layer "In11.Cu")
		(net "M_D_CPU0_SB_DQS_DN<0>")
	)
	(arc
		(start 336.358992 -240.172494)
		(mid 336.228078 -240.036134)
		(end 336.18043 -239.853216)
		(width 0.088646)
		(layer "In11.Cu")
		(net "M_D_CPU0_SB_DQS_DN<0>")
	)
	(arc
		(start 339.187282 -240.177574)
		(mid 338.910723 -240.101865)
		(end 338.632546 -240.171478)
		(width 0.088646)
		(layer "In11.Cu")
		(net "M_D_CPU0_SB_DQS_DN<0>")
	)
	(arc
		(start 332.608936 -238.549942)
		(mid 332.472444 -238.493467)
		(end 332.32598 -238.47425)
		(width 0.088646)
		(layer "In11.Cu")
		(net "M_D_CPU0_SB_DQS_DN<0>")
	)
	(arc
		(start 340.501478 -240.177574)
		(mid 340.31428 -240.227717)
		(end 340.127082 -240.177574)
		(width 0.088646)
		(layer "In11.Cu")
		(net "M_D_CPU0_SB_DQS_DN<0>")
	)
	(arc
		(start 344.815922 -240.171478)
		(mid 344.53749 -240.101664)
		(end 344.260678 -240.177574)
		(width 0.088646)
		(layer "In11.Cu")
		(net "M_D_CPU0_SB_DQS_DN<0>")
	)
	(arc
		(start 342.93175 -240.168938)
		(mid 342.655309 -240.101772)
		(end 342.381078 -240.177574)
		(width 0.088646)
		(layer "In11.Cu")
		(net "M_D_CPU0_SB_DQS_DN<0>")
	)
	(arc
		(start 341.99195 -240.168938)
		(mid 341.715509 -240.101772)
		(end 341.441278 -240.177574)
		(width 0.088646)
		(layer "In11.Cu")
		(net "M_D_CPU0_SB_DQS_DN<0>")
	)
	(arc
		(start 342.381078 -240.177574)
		(mid 342.19388 -240.227717)
		(end 342.006682 -240.177574)
		(width 0.088646)
		(layer "In11.Cu")
		(net "M_D_CPU0_SB_DQS_DN<0>")
	)
	(arc
		(start 332.983332 -238.549942)
		(mid 332.796134 -238.600085)
		(end 332.608936 -238.549942)
		(width 0.088646)
		(layer "In11.Cu")
		(net "M_D_CPU0_SB_DQS_DN<0>")
	)
	(segment
		(start 346.423234 -236.319568)
		(end 346.423234 -235.783882)
		(width 0.20066)
		(layer "F.Cu")
		(net "M_D_CPU0_SB_DQ<9>")
	)
	(segment
		(start 258.28498 -221.173548)
		(end 258.130548 -221.32798)
		(width 0.20066)
		(layer "F.Cu")
		(net "M_D_CPU0_SB_DQ<9>")
	)
	(segment
		(start 258.44754 -220.68282)
		(end 258.28498 -220.84538)
		(width 0.20066)
		(layer "F.Cu")
		(net "M_D_CPU0_SB_DQ<9>")
	)
	(segment
		(start 259.056378 -220.68282)
		(end 258.44754 -220.68282)
		(width 0.20066)
		(layer "F.Cu")
		(net "M_D_CPU0_SB_DQ<9>")
	)
	(segment
		(start 261.381494 -220.69171)
		(end 261.050786 -220.69171)
		(width 0.101854)
		(layer "F.Cu")
		(net "M_D_CPU0_SB_DQ<9>")
	)
	(segment
		(start 261.984998 -221.116652)
		(end 261.560056 -220.69171)
		(width 0.20066)
		(layer "F.Cu")
		(net "M_D_CPU0_SB_DQ<9>")
	)
	(segment
		(start 261.560056 -220.69171)
		(end 261.381494 -220.69171)
		(width 0.20066)
		(layer "F.Cu")
		(net "M_D_CPU0_SB_DQ<9>")
	)
	(segment
		(start 258.28498 -220.84538)
		(end 258.28498 -221.173548)
		(width 0.20066)
		(layer "F.Cu")
		(net "M_D_CPU0_SB_DQ<9>")
	)
	(segment
		(start 258.130548 -221.32798)
		(end 257.626104 -221.32798)
		(width 0.20066)
		(layer "F.Cu")
		(net "M_D_CPU0_SB_DQ<9>")
	)
	(segment
		(start 263.624314 -221.116652)
		(end 261.984998 -221.116652)
		(width 0.20066)
		(layer "F.Cu")
		(net "M_D_CPU0_SB_DQ<9>")
	)
	(segment
		(start 346.42298 -236.319822)
		(end 346.423234 -236.319568)
		(width 0.20066)
		(layer "F.Cu")
		(net "M_D_CPU0_SB_DQ<9>")
	)
	(segment
		(start 259.065268 -220.69171)
		(end 259.056378 -220.68282)
		(width 0.1016)
		(layer "F.Cu")
		(net "M_D_CPU0_SB_DQ<9>")
	)
	(segment
		(start 261.050786 -220.69171)
		(end 259.065268 -220.69171)
		(width 0.1016)
		(layer "F.Cu")
		(net "M_D_CPU0_SB_DQ<9>")
	)
	(segment
		(start 257.414776 -221.116652)
		(end 256.080514 -221.116652)
		(width 0.20066)
		(layer "F.Cu")
		(net "M_D_CPU0_SB_DQ<9>")
	)
	(segment
		(start 264.729214 -221.116652)
		(end 263.624314 -221.116652)
		(width 0.20066)
		(layer "F.Cu")
		(net "M_D_CPU0_SB_DQ<9>")
	)
	(segment
		(start 257.626104 -221.32798)
		(end 257.414776 -221.116652)
		(width 0.20066)
		(layer "F.Cu")
		(net "M_D_CPU0_SB_DQ<9>")
	)
	(segment
		(start 288.403538 -214.507826)
		(end 287.674304 -213.778592)
		(width 0.18288)
		(layer "In11.Cu")
		(net "M_D_CPU0_SB_DQ<9>")
	)
	(segment
		(start 282.336494 -214.562182)
		(end 280.736294 -214.562182)
		(width 0.18288)
		(layer "In11.Cu")
		(net "M_D_CPU0_SB_DQ<9>")
	)
	(segment
		(start 283.006546 -213.89213)
		(end 282.336494 -214.562182)
		(width 0.18288)
		(layer "In11.Cu")
		(net "M_D_CPU0_SB_DQ<9>")
	)
	(segment
		(start 308.117494 -215.523826)
		(end 307.603398 -215.523826)
		(width 0.18288)
		(layer "In11.Cu")
		(net "M_D_CPU0_SB_DQ<9>")
	)
	(segment
		(start 291.197538 -215.701626)
		(end 290.003738 -214.507826)
		(width 0.18288)
		(layer "In11.Cu")
		(net "M_D_CPU0_SB_DQ<9>")
	)
	(segment
		(start 303.01565 -213.723982)
		(end 300.25594 -213.723982)
		(width 0.18288)
		(layer "In11.Cu")
		(net "M_D_CPU0_SB_DQ<9>")
	)
	(segment
		(start 312.84672 -218.471242)
		(end 312.352182 -218.471242)
		(width 0.18288)
		(layer "In11.Cu")
		(net "M_D_CPU0_SB_DQ<9>")
	)
	(segment
		(start 274.665694 -219.232226)
		(end 274.665694 -219.562426)
		(width 0.18288)
		(layer "In11.Cu")
		(net "M_D_CPU0_SB_DQ<9>")
	)
	(segment
		(start 272.356834 -220.908626)
		(end 271.298162 -220.908626)
		(width 0.18288)
		(layer "In11.Cu")
		(net "M_D_CPU0_SB_DQ<9>")
	)
	(segment
		(start 293.204392 -215.400382)
		(end 292.188138 -215.400382)
		(width 0.18288)
		(layer "In11.Cu")
		(net "M_D_CPU0_SB_DQ<9>")
	)
	(segment
		(start 266.025122 -220.527626)
		(end 265.31824 -220.527626)
		(width 0.18288)
		(layer "In11.Cu")
		(net "M_D_CPU0_SB_DQ<9>")
	)
	(segment
		(start 315.280548 -220.16339)
		(end 314.932568 -219.323666)
		(width 0.18288)
		(layer "In11.Cu")
		(net "M_D_CPU0_SB_DQ<9>")
	)
	(segment
		(start 343.886282 -236.273594)
		(end 343.87155 -236.28223)
		(width 0.088646)
		(layer "In11.Cu")
		(net "M_D_CPU0_SB_DQ<9>")
	)
	(segment
		(start 314.080144 -218.471242)
		(end 313.844178 -218.471242)
		(width 0.18288)
		(layer "In11.Cu")
		(net "M_D_CPU0_SB_DQ<9>")
	)
	(segment
		(start 275.846794 -218.051126)
		(end 274.665694 -219.232226)
		(width 0.18288)
		(layer "In11.Cu")
		(net "M_D_CPU0_SB_DQ<9>")
	)
	(segment
		(start 312.352182 -218.471242)
		(end 311.762394 -217.881454)
		(width 0.18288)
		(layer "In11.Cu")
		(net "M_D_CPU0_SB_DQ<9>")
	)
	(segment
		(start 279.116536 -214.935308)
		(end 279.116536 -215.321642)
		(width 0.18288)
		(layer "In11.Cu")
		(net "M_D_CPU0_SB_DQ<9>")
	)
	(segment
		(start 314.932568 -219.323666)
		(end 314.080144 -218.471242)
		(width 0.18288)
		(layer "In11.Cu")
		(net "M_D_CPU0_SB_DQ<9>")
	)
	(segment
		(start 266.185142 -220.367606)
		(end 266.025122 -220.527626)
		(width 0.18288)
		(layer "In11.Cu")
		(net "M_D_CPU0_SB_DQ<9>")
	)
	(segment
		(start 266.185142 -220.194886)
		(end 266.185142 -220.367606)
		(width 0.18288)
		(layer "In11.Cu")
		(net "M_D_CPU0_SB_DQ<9>")
	)
	(segment
		(start 278.608536 -215.514682)
		(end 278.415496 -215.321642)
		(width 0.18288)
		(layer "In11.Cu")
		(net "M_D_CPU0_SB_DQ<9>")
	)
	(segment
		(start 276.684994 -218.051126)
		(end 275.846794 -218.051126)
		(width 0.18288)
		(layer "In11.Cu")
		(net "M_D_CPU0_SB_DQ<9>")
	)
	(segment
		(start 342.006936 -236.273594)
		(end 341.996522 -236.27969)
		(width 0.088646)
		(layer "In11.Cu")
		(net "M_D_CPU0_SB_DQ<9>")
	)
	(segment
		(start 336.281522 -233.836972)
		(end 336.272632 -233.831892)
		(width 0.088646)
		(layer "In11.Cu")
		(net "M_D_CPU0_SB_DQ<9>")
	)
	(segment
		(start 279.116536 -215.321642)
		(end 278.923496 -215.514682)
		(width 0.18288)
		(layer "In11.Cu")
		(net "M_D_CPU0_SB_DQ<9>")
	)
	(segment
		(start 340.127082 -236.273594)
		(end 340.11235 -236.28223)
		(width 0.088646)
		(layer "In11.Cu")
		(net "M_D_CPU0_SB_DQ<9>")
	)
	(segment
		(start 268.055598 -220.777054)
		(end 267.31341 -220.034866)
		(width 0.18288)
		(layer "In11.Cu")
		(net "M_D_CPU0_SB_DQ<9>")
	)
	(segment
		(start 269.321788 -221.37878)
		(end 269.159228 -221.54134)
		(width 0.18288)
		(layer "In11.Cu")
		(net "M_D_CPU0_SB_DQ<9>")
	)
	(segment
		(start 278.923496 -215.514682)
		(end 278.608536 -215.514682)
		(width 0.18288)
		(layer "In11.Cu")
		(net "M_D_CPU0_SB_DQ<9>")
	)
	(segment
		(start 274.360894 -219.867226)
		(end 273.398234 -219.867226)
		(width 0.18288)
		(layer "In11.Cu")
		(net "M_D_CPU0_SB_DQ<9>")
	)
	(segment
		(start 338.152232 -235.459524)
		(end 338.14004 -235.452412)
		(width 0.088646)
		(layer "In11.Cu")
		(net "M_D_CPU0_SB_DQ<9>")
	)
	(segment
		(start 336.460084 -234.171744)
		(end 336.460084 -234.15625)
		(width 0.088646)
		(layer "In11.Cu")
		(net "M_D_CPU0_SB_DQ<9>")
	)
	(segment
		(start 327.541636 -232.424478)
		(end 315.280548 -220.16339)
		(width 0.18288)
		(layer "In11.Cu")
		(net "M_D_CPU0_SB_DQ<9>")
	)
	(segment
		(start 344.826082 -236.273594)
		(end 344.81135 -236.28223)
		(width 0.088646)
		(layer "In11.Cu")
		(net "M_D_CPU0_SB_DQ<9>")
	)
	(segment
		(start 295.950894 -214.742268)
		(end 293.862506 -214.742268)
		(width 0.18288)
		(layer "In11.Cu")
		(net "M_D_CPU0_SB_DQ<9>")
	)
	(segment
		(start 276.977094 -217.759026)
		(end 276.684994 -218.051126)
		(width 0.18288)
		(layer "In11.Cu")
		(net "M_D_CPU0_SB_DQ<9>")
	)
	(segment
		(start 279.309576 -214.742268)
		(end 279.116536 -214.935308)
		(width 0.18288)
		(layer "In11.Cu")
		(net "M_D_CPU0_SB_DQ<9>")
	)
	(segment
		(start 311.762394 -217.881454)
		(end 311.179718 -217.881454)
		(width 0.18288)
		(layer "In11.Cu")
		(net "M_D_CPU0_SB_DQ<9>")
	)
	(segment
		(start 346.423234 -235.783882)
		(end 346.044774 -236.162342)
		(width 0.088646)
		(layer "In11.Cu")
		(net "M_D_CPU0_SB_DQ<9>")
	)
	(segment
		(start 271.298162 -220.908626)
		(end 270.828008 -221.37878)
		(width 0.18288)
		(layer "In11.Cu")
		(net "M_D_CPU0_SB_DQ<9>")
	)
	(segment
		(start 331.53477 -233.781092)
		(end 331.056234 -233.302556)
		(width 0.088646)
		(layer "In11.Cu")
		(net "M_D_CPU0_SB_DQ<9>")
	)
	(segment
		(start 268.387068 -221.54134)
		(end 268.055598 -221.20987)
		(width 0.18288)
		(layer "In11.Cu")
		(net "M_D_CPU0_SB_DQ<9>")
	)
	(segment
		(start 278.415496 -214.935308)
		(end 278.222456 -214.742268)
		(width 0.18288)
		(layer "In11.Cu")
		(net "M_D_CPU0_SB_DQ<9>")
	)
	(segment
		(start 270.828008 -221.37878)
		(end 269.321788 -221.37878)
		(width 0.18288)
		(layer "In11.Cu")
		(net "M_D_CPU0_SB_DQ<9>")
	)
	(segment
		(start 313.143138 -218.76766)
		(end 312.84672 -218.471242)
		(width 0.18288)
		(layer "In11.Cu")
		(net "M_D_CPU0_SB_DQ<9>")
	)
	(segment
		(start 331.056234 -233.302556)
		(end 331.056234 -232.907332)
		(width 0.088646)
		(layer "In11.Cu")
		(net "M_D_CPU0_SB_DQ<9>")
	)
	(segment
		(start 290.003738 -214.507826)
		(end 288.403538 -214.507826)
		(width 0.18288)
		(layer "In11.Cu")
		(net "M_D_CPU0_SB_DQ<9>")
	)
	(segment
		(start 337.307682 -234.645708)
		(end 337.29295 -234.654344)
		(width 0.088646)
		(layer "In11.Cu")
		(net "M_D_CPU0_SB_DQ<9>")
	)
	(segment
		(start 330.57338 -232.424478)
		(end 330.313538 -232.424478)
		(width 0.088646)
		(layer "In11.Cu")
		(net "M_D_CPU0_SB_DQ<9>")
	)
	(segment
		(start 278.415496 -215.321642)
		(end 278.415496 -214.935308)
		(width 0.18288)
		(layer "In11.Cu")
		(net "M_D_CPU0_SB_DQ<9>")
	)
	(segment
		(start 303.901094 -214.609426)
		(end 303.01565 -213.723982)
		(width 0.18288)
		(layer "In11.Cu")
		(net "M_D_CPU0_SB_DQ<9>")
	)
	(segment
		(start 265.31824 -220.527626)
		(end 264.729214 -221.116652)
		(width 0.18288)
		(layer "In11.Cu")
		(net "M_D_CPU0_SB_DQ<9>")
	)
	(segment
		(start 278.222456 -214.742268)
		(end 277.784052 -214.742268)
		(width 0.18288)
		(layer "In11.Cu")
		(net "M_D_CPU0_SB_DQ<9>")
	)
	(segment
		(start 330.313538 -232.424478)
		(end 327.541636 -232.424478)
		(width 0.18288)
		(layer "In11.Cu")
		(net "M_D_CPU0_SB_DQ<9>")
	)
	(segment
		(start 267.31341 -220.034866)
		(end 266.345162 -220.034866)
		(width 0.18288)
		(layer "In11.Cu")
		(net "M_D_CPU0_SB_DQ<9>")
	)
	(segment
		(start 309.793894 -217.200226)
		(end 308.117494 -215.523826)
		(width 0.18288)
		(layer "In11.Cu")
		(net "M_D_CPU0_SB_DQ<9>")
	)
	(segment
		(start 300.25594 -213.723982)
		(end 300.087792 -213.89213)
		(width 0.18288)
		(layer "In11.Cu")
		(net "M_D_CPU0_SB_DQ<9>")
	)
	(segment
		(start 277.784052 -214.742268)
		(end 276.977094 -215.549226)
		(width 0.18288)
		(layer "In11.Cu")
		(net "M_D_CPU0_SB_DQ<9>")
	)
	(segment
		(start 332.326234 -233.781092)
		(end 331.53477 -233.781092)
		(width 0.088646)
		(layer "In11.Cu")
		(net "M_D_CPU0_SB_DQ<9>")
	)
	(segment
		(start 274.665694 -219.562426)
		(end 274.360894 -219.867226)
		(width 0.18288)
		(layer "In11.Cu")
		(net "M_D_CPU0_SB_DQ<9>")
	)
	(segment
		(start 273.398234 -219.867226)
		(end 272.356834 -220.908626)
		(width 0.18288)
		(layer "In11.Cu")
		(net "M_D_CPU0_SB_DQ<9>")
	)
	(segment
		(start 341.066882 -236.273594)
		(end 341.05215 -236.28223)
		(width 0.088646)
		(layer "In11.Cu")
		(net "M_D_CPU0_SB_DQ<9>")
	)
	(segment
		(start 338.33943 -235.802424)
		(end 338.33943 -235.775246)
		(width 0.088646)
		(layer "In11.Cu")
		(net "M_D_CPU0_SB_DQ<9>")
	)
	(segment
		(start 266.345162 -220.034866)
		(end 266.185142 -220.194886)
		(width 0.18288)
		(layer "In11.Cu")
		(net "M_D_CPU0_SB_DQ<9>")
	)
	(segment
		(start 296.175684 -214.517478)
		(end 295.950894 -214.742268)
		(width 0.18288)
		(layer "In11.Cu")
		(net "M_D_CPU0_SB_DQ<9>")
	)
	(segment
		(start 268.055598 -221.20987)
		(end 268.055598 -220.777054)
		(width 0.18288)
		(layer "In11.Cu")
		(net "M_D_CPU0_SB_DQ<9>")
	)
	(segment
		(start 284.708346 -213.89213)
		(end 283.006546 -213.89213)
		(width 0.18288)
		(layer "In11.Cu")
		(net "M_D_CPU0_SB_DQ<9>")
	)
	(segment
		(start 313.844178 -218.471242)
		(end 313.54776 -218.76766)
		(width 0.18288)
		(layer "In11.Cu")
		(net "M_D_CPU0_SB_DQ<9>")
	)
	(segment
		(start 300.087792 -213.89213)
		(end 298.338494 -213.89213)
		(width 0.18288)
		(layer "In11.Cu")
		(net "M_D_CPU0_SB_DQ<9>")
	)
	(segment
		(start 284.821884 -213.778592)
		(end 284.708346 -213.89213)
		(width 0.18288)
		(layer "In11.Cu")
		(net "M_D_CPU0_SB_DQ<9>")
	)
	(segment
		(start 280.556208 -214.742268)
		(end 279.309576 -214.742268)
		(width 0.18288)
		(layer "In11.Cu")
		(net "M_D_CPU0_SB_DQ<9>")
	)
	(segment
		(start 342.946482 -236.273594)
		(end 342.936068 -236.27969)
		(width 0.088646)
		(layer "In11.Cu")
		(net "M_D_CPU0_SB_DQ<9>")
	)
	(segment
		(start 292.188138 -215.400382)
		(end 291.886894 -215.701626)
		(width 0.18288)
		(layer "In11.Cu")
		(net "M_D_CPU0_SB_DQ<9>")
	)
	(segment
		(start 313.54776 -218.76766)
		(end 313.143138 -218.76766)
		(width 0.18288)
		(layer "In11.Cu")
		(net "M_D_CPU0_SB_DQ<9>")
	)
	(segment
		(start 297.713146 -214.517478)
		(end 296.175684 -214.517478)
		(width 0.18288)
		(layer "In11.Cu")
		(net "M_D_CPU0_SB_DQ<9>")
	)
	(segment
		(start 293.862506 -214.742268)
		(end 293.204392 -215.400382)
		(width 0.18288)
		(layer "In11.Cu")
		(net "M_D_CPU0_SB_DQ<9>")
	)
	(segment
		(start 311.179718 -217.881454)
		(end 310.49849 -217.200226)
		(width 0.18288)
		(layer "In11.Cu")
		(net "M_D_CPU0_SB_DQ<9>")
	)
	(segment
		(start 287.674304 -213.778592)
		(end 284.821884 -213.778592)
		(width 0.18288)
		(layer "In11.Cu")
		(net "M_D_CPU0_SB_DQ<9>")
	)
	(segment
		(start 310.49849 -217.200226)
		(end 309.793894 -217.200226)
		(width 0.18288)
		(layer "In11.Cu")
		(net "M_D_CPU0_SB_DQ<9>")
	)
	(segment
		(start 276.977094 -215.549226)
		(end 276.977094 -217.759026)
		(width 0.18288)
		(layer "In11.Cu")
		(net "M_D_CPU0_SB_DQ<9>")
	)
	(segment
		(start 291.886894 -215.701626)
		(end 291.197538 -215.701626)
		(width 0.18288)
		(layer "In11.Cu")
		(net "M_D_CPU0_SB_DQ<9>")
	)
	(segment
		(start 280.736294 -214.562182)
		(end 280.556208 -214.742268)
		(width 0.18288)
		(layer "In11.Cu")
		(net "M_D_CPU0_SB_DQ<9>")
	)
	(segment
		(start 298.338494 -213.89213)
		(end 297.713146 -214.517478)
		(width 0.18288)
		(layer "In11.Cu")
		(net "M_D_CPU0_SB_DQ<9>")
	)
	(segment
		(start 307.603398 -215.523826)
		(end 306.688998 -214.609426)
		(width 0.18288)
		(layer "In11.Cu")
		(net "M_D_CPU0_SB_DQ<9>")
	)
	(segment
		(start 331.056234 -232.907332)
		(end 330.57338 -232.424478)
		(width 0.088646)
		(layer "In11.Cu")
		(net "M_D_CPU0_SB_DQ<9>")
	)
	(segment
		(start 337.690968 -234.650788)
		(end 337.682078 -234.645708)
		(width 0.088646)
		(layer "In11.Cu")
		(net "M_D_CPU0_SB_DQ<9>")
	)
	(segment
		(start 269.159228 -221.54134)
		(end 268.387068 -221.54134)
		(width 0.18288)
		(layer "In11.Cu")
		(net "M_D_CPU0_SB_DQ<9>")
	)
	(segment
		(start 306.688998 -214.609426)
		(end 303.901094 -214.609426)
		(width 0.18288)
		(layer "In11.Cu")
		(net "M_D_CPU0_SB_DQ<9>")
	)
	(arc
		(start 342.936068 -236.27969)
		(mid 342.65789 -236.349382)
		(end 342.381332 -236.273594)
		(width 0.088646)
		(layer "In11.Cu")
		(net "M_D_CPU0_SB_DQ<9>")
	)
	(arc
		(start 344.260678 -236.273594)
		(mid 344.07348 -236.223451)
		(end 343.886282 -236.273594)
		(width 0.088646)
		(layer "In11.Cu")
		(net "M_D_CPU0_SB_DQ<9>")
	)
	(arc
		(start 338.14004 -235.452412)
		(mid 337.941812 -235.246564)
		(end 337.86953 -234.970066)
		(width 0.088646)
		(layer "In11.Cu")
		(net "M_D_CPU0_SB_DQ<9>")
	)
	(arc
		(start 340.11235 -236.28223)
		(mid 339.835909 -236.349396)
		(end 339.561678 -236.273594)
		(width 0.088646)
		(layer "In11.Cu")
		(net "M_D_CPU0_SB_DQ<9>")
	)
	(arc
		(start 341.996522 -236.27969)
		(mid 341.71809 -236.349504)
		(end 341.441278 -236.273594)
		(width 0.088646)
		(layer "In11.Cu")
		(net "M_D_CPU0_SB_DQ<9>")
	)
	(arc
		(start 337.682078 -234.645708)
		(mid 337.49488 -234.595565)
		(end 337.307682 -234.645708)
		(width 0.088646)
		(layer "In11.Cu")
		(net "M_D_CPU0_SB_DQ<9>")
	)
	(arc
		(start 344.81135 -236.28223)
		(mid 344.534909 -236.349396)
		(end 344.260678 -236.273594)
		(width 0.088646)
		(layer "In11.Cu")
		(net "M_D_CPU0_SB_DQ<9>")
	)
	(arc
		(start 340.501478 -236.273594)
		(mid 340.31428 -236.223451)
		(end 340.127082 -236.273594)
		(width 0.088646)
		(layer "In11.Cu")
		(net "M_D_CPU0_SB_DQ<9>")
	)
	(arc
		(start 337.86953 -234.970066)
		(mid 337.821851 -234.787166)
		(end 337.690968 -234.650788)
		(width 0.088646)
		(layer "In11.Cu")
		(net "M_D_CPU0_SB_DQ<9>")
	)
	(arc
		(start 332.513432 -233.831892)
		(mid 332.423176 -233.79417)
		(end 332.326234 -233.781092)
		(width 0.088646)
		(layer "In11.Cu")
		(net "M_D_CPU0_SB_DQ<9>")
	)
	(arc
		(start 343.320878 -236.273594)
		(mid 343.13368 -236.223451)
		(end 342.946482 -236.273594)
		(width 0.088646)
		(layer "In11.Cu")
		(net "M_D_CPU0_SB_DQ<9>")
	)
	(arc
		(start 338.33943 -235.775246)
		(mid 338.28716 -235.592881)
		(end 338.152232 -235.459524)
		(width 0.088646)
		(layer "In11.Cu")
		(net "M_D_CPU0_SB_DQ<9>")
	)
	(arc
		(start 341.441278 -236.273594)
		(mid 341.25408 -236.223451)
		(end 341.066882 -236.273594)
		(width 0.088646)
		(layer "In11.Cu")
		(net "M_D_CPU0_SB_DQ<9>")
	)
	(arc
		(start 334.018636 -233.831892)
		(mid 333.735934 -233.907634)
		(end 333.453232 -233.831892)
		(width 0.088646)
		(layer "In11.Cu")
		(net "M_D_CPU0_SB_DQ<9>")
	)
	(arc
		(start 345.765882 -236.273594)
		(mid 345.48318 -236.349336)
		(end 345.200478 -236.273594)
		(width 0.088646)
		(layer "In11.Cu")
		(net "M_D_CPU0_SB_DQ<9>")
	)
	(arc
		(start 338.621878 -236.273594)
		(mid 338.419592 -236.074613)
		(end 338.33943 -235.802424)
		(width 0.088646)
		(layer "In11.Cu")
		(net "M_D_CPU0_SB_DQ<9>")
	)
	(arc
		(start 335.898236 -233.831892)
		(mid 335.615534 -233.907634)
		(end 335.332832 -233.831892)
		(width 0.088646)
		(layer "In11.Cu")
		(net "M_D_CPU0_SB_DQ<9>")
	)
	(arc
		(start 342.381332 -236.273594)
		(mid 342.194134 -236.223451)
		(end 342.006936 -236.273594)
		(width 0.088646)
		(layer "In11.Cu")
		(net "M_D_CPU0_SB_DQ<9>")
	)
	(arc
		(start 339.187282 -236.273594)
		(mid 338.90458 -236.349336)
		(end 338.621878 -236.273594)
		(width 0.088646)
		(layer "In11.Cu")
		(net "M_D_CPU0_SB_DQ<9>")
	)
	(arc
		(start 333.078836 -233.831892)
		(mid 332.796134 -233.907634)
		(end 332.513432 -233.831892)
		(width 0.088646)
		(layer "In11.Cu")
		(net "M_D_CPU0_SB_DQ<9>")
	)
	(arc
		(start 337.29295 -234.654344)
		(mid 337.016475 -234.721664)
		(end 336.742278 -234.645708)
		(width 0.088646)
		(layer "In11.Cu")
		(net "M_D_CPU0_SB_DQ<9>")
	)
	(arc
		(start 336.460084 -234.15625)
		(mid 336.412405 -233.97335)
		(end 336.281522 -233.836972)
		(width 0.088646)
		(layer "In11.Cu")
		(net "M_D_CPU0_SB_DQ<9>")
	)
	(arc
		(start 345.912694 -236.225588)
		(mid 345.836777 -236.241919)
		(end 345.765882 -236.273594)
		(width 0.088646)
		(layer "In11.Cu")
		(net "M_D_CPU0_SB_DQ<9>")
	)
	(arc
		(start 345.200478 -236.273594)
		(mid 345.01328 -236.223451)
		(end 344.826082 -236.273594)
		(width 0.088646)
		(layer "In11.Cu")
		(net "M_D_CPU0_SB_DQ<9>")
	)
	(arc
		(start 335.332832 -233.831892)
		(mid 335.145634 -233.781749)
		(end 334.958436 -233.831892)
		(width 0.088646)
		(layer "In11.Cu")
		(net "M_D_CPU0_SB_DQ<9>")
	)
	(arc
		(start 343.87155 -236.28223)
		(mid 343.595109 -236.349396)
		(end 343.320878 -236.273594)
		(width 0.088646)
		(layer "In11.Cu")
		(net "M_D_CPU0_SB_DQ<9>")
	)
	(arc
		(start 333.453232 -233.831892)
		(mid 333.266034 -233.781749)
		(end 333.078836 -233.831892)
		(width 0.088646)
		(layer "In11.Cu")
		(net "M_D_CPU0_SB_DQ<9>")
	)
	(arc
		(start 334.958436 -233.831892)
		(mid 334.675734 -233.907634)
		(end 334.393032 -233.831892)
		(width 0.088646)
		(layer "In11.Cu")
		(net "M_D_CPU0_SB_DQ<9>")
	)
	(arc
		(start 336.272632 -233.831892)
		(mid 336.085434 -233.781749)
		(end 335.898236 -233.831892)
		(width 0.088646)
		(layer "In11.Cu")
		(net "M_D_CPU0_SB_DQ<9>")
	)
	(arc
		(start 336.742278 -234.645708)
		(mid 336.539455 -234.445477)
		(end 336.460084 -234.171744)
		(width 0.088646)
		(layer "In11.Cu")
		(net "M_D_CPU0_SB_DQ<9>")
	)
	(arc
		(start 346.044774 -236.162342)
		(mid 345.984145 -236.205276)
		(end 345.912694 -236.225588)
		(width 0.088646)
		(layer "In11.Cu")
		(net "M_D_CPU0_SB_DQ<9>")
	)
	(arc
		(start 339.561678 -236.273594)
		(mid 339.37448 -236.223451)
		(end 339.187282 -236.273594)
		(width 0.088646)
		(layer "In11.Cu")
		(net "M_D_CPU0_SB_DQ<9>")
	)
	(arc
		(start 334.393032 -233.831892)
		(mid 334.205834 -233.781749)
		(end 334.018636 -233.831892)
		(width 0.088646)
		(layer "In11.Cu")
		(net "M_D_CPU0_SB_DQ<9>")
	)
	(arc
		(start 341.05215 -236.28223)
		(mid 340.775709 -236.349396)
		(end 340.501478 -236.273594)
		(width 0.088646)
		(layer "In11.Cu")
		(net "M_D_CPU0_SB_DQ<9>")
	)
	(segment
		(start 257.653536 -223.055434)
		(end 257.414776 -222.816674)
		(width 0.20066)
		(layer "F.Cu")
		(net "M_D_CPU0_SB_DQ<8>")
	)
	(segment
		(start 346.893134 -237.133892)
		(end 346.89288 -237.133638)
		(width 0.20066)
		(layer "F.Cu")
		(net "M_D_CPU0_SB_DQ<8>")
	)
	(segment
		(start 259.056378 -222.383604)
		(end 258.49453 -222.383604)
		(width 0.20066)
		(layer "F.Cu")
		(net "M_D_CPU0_SB_DQ<8>")
	)
	(segment
		(start 258.28498 -222.593154)
		(end 258.28498 -222.882714)
		(width 0.20066)
		(layer "F.Cu")
		(net "M_D_CPU0_SB_DQ<8>")
	)
	(segment
		(start 264.729214 -222.816674)
		(end 263.624314 -222.816674)
		(width 0.20066)
		(layer "F.Cu")
		(net "M_D_CPU0_SB_DQ<8>")
	)
	(segment
		(start 262.255254 -222.816674)
		(end 261.830312 -222.391732)
		(width 0.20066)
		(layer "F.Cu")
		(net "M_D_CPU0_SB_DQ<8>")
	)
	(segment
		(start 259.064506 -222.391732)
		(end 259.056378 -222.383604)
		(width 0.101854)
		(layer "F.Cu")
		(net "M_D_CPU0_SB_DQ<8>")
	)
	(segment
		(start 346.89288 -237.133638)
		(end 346.89288 -236.597952)
		(width 0.20066)
		(layer "F.Cu")
		(net "M_D_CPU0_SB_DQ<8>")
	)
	(segment
		(start 258.49453 -222.383604)
		(end 258.28498 -222.593154)
		(width 0.20066)
		(layer "F.Cu")
		(net "M_D_CPU0_SB_DQ<8>")
	)
	(segment
		(start 263.624314 -222.816674)
		(end 262.255254 -222.816674)
		(width 0.20066)
		(layer "F.Cu")
		(net "M_D_CPU0_SB_DQ<8>")
	)
	(segment
		(start 258.28498 -222.882714)
		(end 258.11226 -223.055434)
		(width 0.20066)
		(layer "F.Cu")
		(net "M_D_CPU0_SB_DQ<8>")
	)
	(segment
		(start 257.414776 -222.816674)
		(end 256.080514 -222.816674)
		(width 0.20066)
		(layer "F.Cu")
		(net "M_D_CPU0_SB_DQ<8>")
	)
	(segment
		(start 261.830312 -222.391732)
		(end 261.381494 -222.391732)
		(width 0.20066)
		(layer "F.Cu")
		(net "M_D_CPU0_SB_DQ<8>")
	)
	(segment
		(start 261.381494 -222.391732)
		(end 259.31241 -222.391732)
		(width 0.1016)
		(layer "F.Cu")
		(net "M_D_CPU0_SB_DQ<8>")
	)
	(segment
		(start 258.11226 -223.055434)
		(end 257.653536 -223.055434)
		(width 0.20066)
		(layer "F.Cu")
		(net "M_D_CPU0_SB_DQ<8>")
	)
	(segment
		(start 259.31241 -222.391732)
		(end 259.064506 -222.391732)
		(width 0.101854)
		(layer "F.Cu")
		(net "M_D_CPU0_SB_DQ<8>")
	)
	(segment
		(start 297.843956 -217.40495)
		(end 297.650916 -217.21191)
		(width 0.18288)
		(layer "In11.Cu")
		(net "M_D_CPU0_SB_DQ<8>")
	)
	(segment
		(start 281.498294 -216.311226)
		(end 280.517346 -217.292174)
		(width 0.18288)
		(layer "In11.Cu")
		(net "M_D_CPU0_SB_DQ<8>")
	)
	(segment
		(start 339.102446 -237.093506)
		(end 339.092032 -237.08741)
		(width 0.088646)
		(layer "In11.Cu")
		(net "M_D_CPU0_SB_DQ<8>")
	)
	(segment
		(start 265.341862 -222.204026)
		(end 264.729214 -222.816674)
		(width 0.18288)
		(layer "In11.Cu")
		(net "M_D_CPU0_SB_DQ<8>")
	)
	(segment
		(start 305.703732 -217.13698)
		(end 305.388772 -217.13698)
		(width 0.18288)
		(layer "In11.Cu")
		(net "M_D_CPU0_SB_DQ<8>")
	)
	(segment
		(start 267.396214 -222.204026)
		(end 265.341862 -222.204026)
		(width 0.18288)
		(layer "In11.Cu")
		(net "M_D_CPU0_SB_DQ<8>")
	)
	(segment
		(start 282.221686 -216.504266)
		(end 282.028646 -216.311226)
		(width 0.18288)
		(layer "In11.Cu")
		(net "M_D_CPU0_SB_DQ<8>")
	)
	(segment
		(start 295.595294 -217.292174)
		(end 293.807642 -217.292174)
		(width 0.18288)
		(layer "In11.Cu")
		(net "M_D_CPU0_SB_DQ<8>")
	)
	(segment
		(start 291.074094 -217.352626)
		(end 290.108894 -216.387426)
		(width 0.18288)
		(layer "In11.Cu")
		(net "M_D_CPU0_SB_DQ<8>")
	)
	(segment
		(start 273.692874 -221.569026)
		(end 272.603214 -222.658686)
		(width 0.18288)
		(layer "In11.Cu")
		(net "M_D_CPU0_SB_DQ<8>")
	)
	(segment
		(start 344.745564 -237.096046)
		(end 344.730832 -237.08741)
		(width 0.088646)
		(layer "In11.Cu")
		(net "M_D_CPU0_SB_DQ<8>")
	)
	(segment
		(start 297.650916 -217.21191)
		(end 297.650916 -216.635076)
		(width 0.18288)
		(layer "In11.Cu")
		(net "M_D_CPU0_SB_DQ<8>")
	)
	(segment
		(start 297.418506 -216.402666)
		(end 296.484802 -216.402666)
		(width 0.18288)
		(layer "In11.Cu")
		(net "M_D_CPU0_SB_DQ<8>")
	)
	(segment
		(start 282.028646 -216.311226)
		(end 281.498294 -216.311226)
		(width 0.18288)
		(layer "In11.Cu")
		(net "M_D_CPU0_SB_DQ<8>")
	)
	(segment
		(start 305.896772 -216.94394)
		(end 305.703732 -217.13698)
		(width 0.18288)
		(layer "In11.Cu")
		(net "M_D_CPU0_SB_DQ<8>")
	)
	(segment
		(start 293.614094 -217.098626)
		(end 292.16985 -217.098626)
		(width 0.18288)
		(layer "In11.Cu")
		(net "M_D_CPU0_SB_DQ<8>")
	)
	(segment
		(start 282.922726 -217.047064)
		(end 282.729686 -217.240104)
		(width 0.18288)
		(layer "In11.Cu")
		(net "M_D_CPU0_SB_DQ<8>")
	)
	(segment
		(start 346.314014 -237.042198)
		(end 346.235782 -237.08741)
		(width 0.088646)
		(layer "In11.Cu")
		(net "M_D_CPU0_SB_DQ<8>")
	)
	(segment
		(start 337.690968 -236.278674)
		(end 337.682078 -236.273594)
		(width 0.088646)
		(layer "In11.Cu")
		(net "M_D_CPU0_SB_DQ<8>")
	)
	(segment
		(start 269.134336 -222.393256)
		(end 267.585444 -222.393256)
		(width 0.18288)
		(layer "In11.Cu")
		(net "M_D_CPU0_SB_DQ<8>")
	)
	(segment
		(start 283.472128 -216.311226)
		(end 283.115766 -216.311226)
		(width 0.18288)
		(layer "In11.Cu")
		(net "M_D_CPU0_SB_DQ<8>")
	)
	(segment
		(start 327.029064 -233.440478)
		(end 314.116212 -220.527626)
		(width 0.18288)
		(layer "In11.Cu")
		(net "M_D_CPU0_SB_DQ<8>")
	)
	(segment
		(start 310.31307 -219.647516)
		(end 307.81498 -217.149426)
		(width 0.18288)
		(layer "In11.Cu")
		(net "M_D_CPU0_SB_DQ<8>")
	)
	(segment
		(start 338.166964 -237.096046)
		(end 338.152232 -237.08741)
		(width 0.088646)
		(layer "In11.Cu")
		(net "M_D_CPU0_SB_DQ<8>")
	)
	(segment
		(start 288.000694 -216.666826)
		(end 284.974284 -216.666826)
		(width 0.18288)
		(layer "In11.Cu")
		(net "M_D_CPU0_SB_DQ<8>")
	)
	(segment
		(start 333.548482 -234.645708)
		(end 333.53375 -234.654344)
		(width 0.088646)
		(layer "In11.Cu")
		(net "M_D_CPU0_SB_DQ<8>")
	)
	(segment
		(start 280.517346 -217.292174)
		(end 279.237694 -217.292174)
		(width 0.18288)
		(layer "In11.Cu")
		(net "M_D_CPU0_SB_DQ<8>")
	)
	(segment
		(start 298.351956 -217.21191)
		(end 298.158916 -217.40495)
		(width 0.18288)
		(layer "In11.Cu")
		(net "M_D_CPU0_SB_DQ<8>")
	)
	(segment
		(start 337.221322 -235.464604)
		(end 337.212432 -235.459524)
		(width 0.088646)
		(layer "In11.Cu")
		(net "M_D_CPU0_SB_DQ<8>")
	)
	(segment
		(start 336.272632 -235.459524)
		(end 336.266536 -235.455968)
		(width 0.088646)
		(layer "In11.Cu")
		(net "M_D_CPU0_SB_DQ<8>")
	)
	(segment
		(start 334.488282 -234.645708)
		(end 334.47355 -234.654344)
		(width 0.088646)
		(layer "In11.Cu")
		(net "M_D_CPU0_SB_DQ<8>")
	)
	(segment
		(start 305.195732 -216.453466)
		(end 305.002692 -216.260426)
		(width 0.18288)
		(layer "In11.Cu")
		(net "M_D_CPU0_SB_DQ<8>")
	)
	(segment
		(start 330.647548 -233.440478)
		(end 330.313538 -233.440478)
		(width 0.088646)
		(layer "In11.Cu")
		(net "M_D_CPU0_SB_DQ<8>")
	)
	(segment
		(start 290.108894 -216.387426)
		(end 288.280094 -216.387426)
		(width 0.18288)
		(layer "In11.Cu")
		(net "M_D_CPU0_SB_DQ<8>")
	)
	(segment
		(start 278.755094 -217.774774)
		(end 278.755094 -218.495626)
		(width 0.18288)
		(layer "In11.Cu")
		(net "M_D_CPU0_SB_DQ<8>")
	)
	(segment
		(start 271.238472 -223.078548)
		(end 269.819628 -223.078548)
		(width 0.18288)
		(layer "In11.Cu")
		(net "M_D_CPU0_SB_DQ<8>")
	)
	(segment
		(start 297.650916 -216.635076)
		(end 297.418506 -216.402666)
		(width 0.18288)
		(layer "In11.Cu")
		(net "M_D_CPU0_SB_DQ<8>")
	)
	(segment
		(start 271.658334 -222.658686)
		(end 271.238472 -223.078548)
		(width 0.18288)
		(layer "In11.Cu")
		(net "M_D_CPU0_SB_DQ<8>")
	)
	(segment
		(start 305.896772 -216.453466)
		(end 305.896772 -216.94394)
		(width 0.18288)
		(layer "In11.Cu")
		(net "M_D_CPU0_SB_DQ<8>")
	)
	(segment
		(start 277.434294 -219.194126)
		(end 276.723094 -219.905326)
		(width 0.18288)
		(layer "In11.Cu")
		(net "M_D_CPU0_SB_DQ<8>")
	)
	(segment
		(start 335.428082 -234.645708)
		(end 335.41335 -234.654344)
		(width 0.088646)
		(layer "In11.Cu")
		(net "M_D_CPU0_SB_DQ<8>")
	)
	(segment
		(start 303.72939 -216.260426)
		(end 303.42459 -216.565226)
		(width 0.18288)
		(layer "In11.Cu")
		(net "M_D_CPU0_SB_DQ<8>")
	)
	(segment
		(start 298.158916 -217.40495)
		(end 297.843956 -217.40495)
		(width 0.18288)
		(layer "In11.Cu")
		(net "M_D_CPU0_SB_DQ<8>")
	)
	(segment
		(start 335.811368 -234.650788)
		(end 335.802478 -234.645708)
		(width 0.088646)
		(layer "In11.Cu")
		(net "M_D_CPU0_SB_DQ<8>")
	)
	(segment
		(start 303.42459 -216.565226)
		(end 299.960284 -216.565226)
		(width 0.18288)
		(layer "In11.Cu")
		(net "M_D_CPU0_SB_DQ<8>")
	)
	(segment
		(start 292.16985 -217.098626)
		(end 291.91585 -217.352626)
		(width 0.18288)
		(layer "In11.Cu")
		(net "M_D_CPU0_SB_DQ<8>")
	)
	(segment
		(start 269.819628 -223.078548)
		(end 269.134336 -222.393256)
		(width 0.18288)
		(layer "In11.Cu")
		(net "M_D_CPU0_SB_DQ<8>")
	)
	(segment
		(start 342.865964 -237.096046)
		(end 342.851232 -237.08741)
		(width 0.088646)
		(layer "In11.Cu")
		(net "M_D_CPU0_SB_DQ<8>")
	)
	(segment
		(start 307.81498 -217.149426)
		(end 307.53304 -217.149426)
		(width 0.18288)
		(layer "In11.Cu")
		(net "M_D_CPU0_SB_DQ<8>")
	)
	(segment
		(start 305.388772 -217.13698)
		(end 305.195732 -216.94394)
		(width 0.18288)
		(layer "In11.Cu")
		(net "M_D_CPU0_SB_DQ<8>")
	)
	(segment
		(start 299.960284 -216.565226)
		(end 299.837094 -216.442036)
		(width 0.18288)
		(layer "In11.Cu")
		(net "M_D_CPU0_SB_DQ<8>")
	)
	(segment
		(start 307.53304 -217.149426)
		(end 306.64404 -216.260426)
		(width 0.18288)
		(layer "In11.Cu")
		(net "M_D_CPU0_SB_DQ<8>")
	)
	(segment
		(start 278.755094 -218.495626)
		(end 278.056594 -219.194126)
		(width 0.18288)
		(layer "In11.Cu")
		(net "M_D_CPU0_SB_DQ<8>")
	)
	(segment
		(start 345.681046 -237.093506)
		(end 345.670632 -237.08741)
		(width 0.088646)
		(layer "In11.Cu")
		(net "M_D_CPU0_SB_DQ<8>")
	)
	(segment
		(start 305.195732 -216.94394)
		(end 305.195732 -216.453466)
		(width 0.18288)
		(layer "In11.Cu")
		(net "M_D_CPU0_SB_DQ<8>")
	)
	(segment
		(start 306.089812 -216.260426)
		(end 305.896772 -216.453466)
		(width 0.18288)
		(layer "In11.Cu")
		(net "M_D_CPU0_SB_DQ<8>")
	)
	(segment
		(start 310.882284 -219.647516)
		(end 310.31307 -219.647516)
		(width 0.18288)
		(layer "In11.Cu")
		(net "M_D_CPU0_SB_DQ<8>")
	)
	(segment
		(start 311.762394 -220.527626)
		(end 310.882284 -219.647516)
		(width 0.18288)
		(layer "In11.Cu")
		(net "M_D_CPU0_SB_DQ<8>")
	)
	(segment
		(start 283.115766 -216.311226)
		(end 282.922726 -216.504266)
		(width 0.18288)
		(layer "In11.Cu")
		(net "M_D_CPU0_SB_DQ<8>")
	)
	(segment
		(start 338.152232 -237.08741)
		(end 338.146136 -237.083854)
		(width 0.088646)
		(layer "In11.Cu")
		(net "M_D_CPU0_SB_DQ<8>")
	)
	(segment
		(start 291.91585 -217.352626)
		(end 291.074094 -217.352626)
		(width 0.18288)
		(layer "In11.Cu")
		(net "M_D_CPU0_SB_DQ<8>")
	)
	(segment
		(start 293.807642 -217.292174)
		(end 293.614094 -217.098626)
		(width 0.18288)
		(layer "In11.Cu")
		(net "M_D_CPU0_SB_DQ<8>")
	)
	(segment
		(start 340.041992 -237.093506)
		(end 340.031578 -237.08741)
		(width 0.088646)
		(layer "In11.Cu")
		(net "M_D_CPU0_SB_DQ<8>")
	)
	(segment
		(start 296.484802 -216.402666)
		(end 295.595294 -217.292174)
		(width 0.18288)
		(layer "In11.Cu")
		(net "M_D_CPU0_SB_DQ<8>")
	)
	(segment
		(start 298.351956 -216.635076)
		(end 298.351956 -217.21191)
		(width 0.18288)
		(layer "In11.Cu")
		(net "M_D_CPU0_SB_DQ<8>")
	)
	(segment
		(start 305.002692 -216.260426)
		(end 303.72939 -216.260426)
		(width 0.18288)
		(layer "In11.Cu")
		(net "M_D_CPU0_SB_DQ<8>")
	)
	(segment
		(start 340.986364 -237.096046)
		(end 340.971632 -237.08741)
		(width 0.088646)
		(layer "In11.Cu")
		(net "M_D_CPU0_SB_DQ<8>")
	)
	(segment
		(start 276.723094 -219.905326)
		(end 275.846794 -219.905326)
		(width 0.18288)
		(layer "In11.Cu")
		(net "M_D_CPU0_SB_DQ<8>")
	)
	(segment
		(start 279.237694 -217.292174)
		(end 278.755094 -217.774774)
		(width 0.18288)
		(layer "In11.Cu")
		(net "M_D_CPU0_SB_DQ<8>")
	)
	(segment
		(start 298.544996 -216.442036)
		(end 298.351956 -216.635076)
		(width 0.18288)
		(layer "In11.Cu")
		(net "M_D_CPU0_SB_DQ<8>")
	)
	(segment
		(start 284.749494 -216.442036)
		(end 283.602938 -216.442036)
		(width 0.18288)
		(layer "In11.Cu")
		(net "M_D_CPU0_SB_DQ<8>")
	)
	(segment
		(start 314.116212 -220.527626)
		(end 311.762394 -220.527626)
		(width 0.18288)
		(layer "In11.Cu")
		(net "M_D_CPU0_SB_DQ<8>")
	)
	(segment
		(start 288.280094 -216.387426)
		(end 288.000694 -216.666826)
		(width 0.18288)
		(layer "In11.Cu")
		(net "M_D_CPU0_SB_DQ<8>")
	)
	(segment
		(start 299.837094 -216.442036)
		(end 298.544996 -216.442036)
		(width 0.18288)
		(layer "In11.Cu")
		(net "M_D_CPU0_SB_DQ<8>")
	)
	(segment
		(start 332.326488 -234.7214)
		(end 331.92847 -234.7214)
		(width 0.088646)
		(layer "In11.Cu")
		(net "M_D_CPU0_SB_DQ<8>")
	)
	(segment
		(start 274.919694 -221.213426)
		(end 274.564094 -221.569026)
		(width 0.18288)
		(layer "In11.Cu")
		(net "M_D_CPU0_SB_DQ<8>")
	)
	(segment
		(start 282.729686 -217.240104)
		(end 282.414726 -217.240104)
		(width 0.18288)
		(layer "In11.Cu")
		(net "M_D_CPU0_SB_DQ<8>")
	)
	(segment
		(start 306.64404 -216.260426)
		(end 306.089812 -216.260426)
		(width 0.18288)
		(layer "In11.Cu")
		(net "M_D_CPU0_SB_DQ<8>")
	)
	(segment
		(start 284.974284 -216.666826)
		(end 284.749494 -216.442036)
		(width 0.18288)
		(layer "In11.Cu")
		(net "M_D_CPU0_SB_DQ<8>")
	)
	(segment
		(start 272.603214 -222.658686)
		(end 271.658334 -222.658686)
		(width 0.18288)
		(layer "In11.Cu")
		(net "M_D_CPU0_SB_DQ<8>")
	)
	(segment
		(start 267.585444 -222.393256)
		(end 267.396214 -222.204026)
		(width 0.18288)
		(layer "In11.Cu")
		(net "M_D_CPU0_SB_DQ<8>")
	)
	(segment
		(start 282.922726 -216.504266)
		(end 282.922726 -217.047064)
		(width 0.18288)
		(layer "In11.Cu")
		(net "M_D_CPU0_SB_DQ<8>")
	)
	(segment
		(start 343.805764 -237.096046)
		(end 343.791032 -237.08741)
		(width 0.088646)
		(layer "In11.Cu")
		(net "M_D_CPU0_SB_DQ<8>")
	)
	(segment
		(start 282.221686 -217.047064)
		(end 282.221686 -216.504266)
		(width 0.18288)
		(layer "In11.Cu")
		(net "M_D_CPU0_SB_DQ<8>")
	)
	(segment
		(start 337.399884 -235.80598)
		(end 337.399884 -235.783882)
		(width 0.088646)
		(layer "In11.Cu")
		(net "M_D_CPU0_SB_DQ<8>")
	)
	(segment
		(start 282.414726 -217.240104)
		(end 282.221686 -217.047064)
		(width 0.18288)
		(layer "In11.Cu")
		(net "M_D_CPU0_SB_DQ<8>")
	)
	(segment
		(start 278.056594 -219.194126)
		(end 277.434294 -219.194126)
		(width 0.18288)
		(layer "In11.Cu")
		(net "M_D_CPU0_SB_DQ<8>")
	)
	(segment
		(start 283.602938 -216.442036)
		(end 283.472128 -216.311226)
		(width 0.18288)
		(layer "In11.Cu")
		(net "M_D_CPU0_SB_DQ<8>")
	)
	(segment
		(start 275.846794 -219.905326)
		(end 274.919694 -220.832426)
		(width 0.18288)
		(layer "In11.Cu")
		(net "M_D_CPU0_SB_DQ<8>")
	)
	(segment
		(start 336.287364 -235.46816)
		(end 336.272632 -235.459524)
		(width 0.088646)
		(layer "In11.Cu")
		(net "M_D_CPU0_SB_DQ<8>")
	)
	(segment
		(start 331.92847 -234.7214)
		(end 330.647548 -233.440478)
		(width 0.088646)
		(layer "In11.Cu")
		(net "M_D_CPU0_SB_DQ<8>")
	)
	(segment
		(start 274.919694 -220.832426)
		(end 274.919694 -221.213426)
		(width 0.18288)
		(layer "In11.Cu")
		(net "M_D_CPU0_SB_DQ<8>")
	)
	(segment
		(start 330.313538 -233.440478)
		(end 327.029064 -233.440478)
		(width 0.18288)
		(layer "In11.Cu")
		(net "M_D_CPU0_SB_DQ<8>")
	)
	(segment
		(start 274.564094 -221.569026)
		(end 273.692874 -221.569026)
		(width 0.18288)
		(layer "In11.Cu")
		(net "M_D_CPU0_SB_DQ<8>")
	)
	(arc
		(start 332.36281 -234.720384)
		(mid 332.344657 -234.721187)
		(end 332.326488 -234.7214)
		(width 0.088646)
		(layer "In11.Cu")
		(net "M_D_CPU0_SB_DQ<8>")
	)
	(arc
		(start 333.53375 -234.654344)
		(mid 333.257275 -234.721664)
		(end 332.983078 -234.645708)
		(width 0.088646)
		(layer "In11.Cu")
		(net "M_D_CPU0_SB_DQ<8>")
	)
	(arc
		(start 338.717636 -237.08741)
		(mid 338.443437 -237.163245)
		(end 338.166964 -237.096046)
		(width 0.088646)
		(layer "In11.Cu")
		(net "M_D_CPU0_SB_DQ<8>")
	)
	(arc
		(start 344.730832 -237.08741)
		(mid 344.543634 -237.037233)
		(end 344.356436 -237.08741)
		(width 0.088646)
		(layer "In11.Cu")
		(net "M_D_CPU0_SB_DQ<8>")
	)
	(arc
		(start 346.235782 -237.08741)
		(mid 345.959223 -237.163153)
		(end 345.681046 -237.093506)
		(width 0.088646)
		(layer "In11.Cu")
		(net "M_D_CPU0_SB_DQ<8>")
	)
	(arc
		(start 336.266536 -235.455968)
		(mid 336.063949 -235.249617)
		(end 335.98993 -234.970066)
		(width 0.088646)
		(layer "In11.Cu")
		(net "M_D_CPU0_SB_DQ<8>")
	)
	(arc
		(start 342.851232 -237.08741)
		(mid 342.664034 -237.037233)
		(end 342.476836 -237.08741)
		(width 0.088646)
		(layer "In11.Cu")
		(net "M_D_CPU0_SB_DQ<8>")
	)
	(arc
		(start 343.791032 -237.08741)
		(mid 343.603834 -237.037233)
		(end 343.416636 -237.08741)
		(width 0.088646)
		(layer "In11.Cu")
		(net "M_D_CPU0_SB_DQ<8>")
	)
	(arc
		(start 340.031578 -237.08741)
		(mid 339.84438 -237.037233)
		(end 339.657182 -237.08741)
		(width 0.088646)
		(layer "In11.Cu")
		(net "M_D_CPU0_SB_DQ<8>")
	)
	(arc
		(start 337.212432 -235.459524)
		(mid 337.025234 -235.409381)
		(end 336.838036 -235.459524)
		(width 0.088646)
		(layer "In11.Cu")
		(net "M_D_CPU0_SB_DQ<8>")
	)
	(arc
		(start 337.86953 -236.597952)
		(mid 337.821851 -236.415052)
		(end 337.690968 -236.278674)
		(width 0.088646)
		(layer "In11.Cu")
		(net "M_D_CPU0_SB_DQ<8>")
	)
	(arc
		(start 334.862678 -234.645708)
		(mid 334.67548 -234.595565)
		(end 334.488282 -234.645708)
		(width 0.088646)
		(layer "In11.Cu")
		(net "M_D_CPU0_SB_DQ<8>")
	)
	(arc
		(start 344.356436 -237.08741)
		(mid 344.082237 -237.163245)
		(end 343.805764 -237.096046)
		(width 0.088646)
		(layer "In11.Cu")
		(net "M_D_CPU0_SB_DQ<8>")
	)
	(arc
		(start 345.670632 -237.08741)
		(mid 345.483434 -237.037233)
		(end 345.296236 -237.08741)
		(width 0.088646)
		(layer "In11.Cu")
		(net "M_D_CPU0_SB_DQ<8>")
	)
	(arc
		(start 335.98993 -234.970066)
		(mid 335.942251 -234.787166)
		(end 335.811368 -234.650788)
		(width 0.088646)
		(layer "In11.Cu")
		(net "M_D_CPU0_SB_DQ<8>")
	)
	(arc
		(start 342.476836 -237.08741)
		(mid 342.194134 -237.163186)
		(end 341.911432 -237.08741)
		(width 0.088646)
		(layer "In11.Cu")
		(net "M_D_CPU0_SB_DQ<8>")
	)
	(arc
		(start 332.983078 -234.645708)
		(mid 332.79588 -234.595565)
		(end 332.608682 -234.645708)
		(width 0.088646)
		(layer "In11.Cu")
		(net "M_D_CPU0_SB_DQ<8>")
	)
	(arc
		(start 346.89288 -236.597952)
		(mid 346.617987 -236.83902)
		(end 346.314014 -237.042198)
		(width 0.088646)
		(layer "In11.Cu")
		(net "M_D_CPU0_SB_DQ<8>")
	)
	(arc
		(start 343.416636 -237.08741)
		(mid 343.142437 -237.163245)
		(end 342.865964 -237.096046)
		(width 0.088646)
		(layer "In11.Cu")
		(net "M_D_CPU0_SB_DQ<8>")
	)
	(arc
		(start 341.537036 -237.08741)
		(mid 341.262837 -237.163245)
		(end 340.986364 -237.096046)
		(width 0.088646)
		(layer "In11.Cu")
		(net "M_D_CPU0_SB_DQ<8>")
	)
	(arc
		(start 333.922878 -234.645708)
		(mid 333.73568 -234.595565)
		(end 333.548482 -234.645708)
		(width 0.088646)
		(layer "In11.Cu")
		(net "M_D_CPU0_SB_DQ<8>")
	)
	(arc
		(start 341.911432 -237.08741)
		(mid 341.724234 -237.037233)
		(end 341.537036 -237.08741)
		(width 0.088646)
		(layer "In11.Cu")
		(net "M_D_CPU0_SB_DQ<8>")
	)
	(arc
		(start 335.41335 -234.654344)
		(mid 335.136875 -234.721664)
		(end 334.862678 -234.645708)
		(width 0.088646)
		(layer "In11.Cu")
		(net "M_D_CPU0_SB_DQ<8>")
	)
	(arc
		(start 334.47355 -234.654344)
		(mid 334.197075 -234.721664)
		(end 333.922878 -234.645708)
		(width 0.088646)
		(layer "In11.Cu")
		(net "M_D_CPU0_SB_DQ<8>")
	)
	(arc
		(start 340.597236 -237.08741)
		(mid 340.320423 -237.16328)
		(end 340.041992 -237.093506)
		(width 0.088646)
		(layer "In11.Cu")
		(net "M_D_CPU0_SB_DQ<8>")
	)
	(arc
		(start 339.657182 -237.08741)
		(mid 339.380623 -237.163153)
		(end 339.102446 -237.093506)
		(width 0.088646)
		(layer "In11.Cu")
		(net "M_D_CPU0_SB_DQ<8>")
	)
	(arc
		(start 339.092032 -237.08741)
		(mid 338.904834 -237.037233)
		(end 338.717636 -237.08741)
		(width 0.088646)
		(layer "In11.Cu")
		(net "M_D_CPU0_SB_DQ<8>")
	)
	(arc
		(start 332.608682 -234.645708)
		(mid 332.490051 -234.697228)
		(end 332.36281 -234.720384)
		(width 0.088646)
		(layer "In11.Cu")
		(net "M_D_CPU0_SB_DQ<8>")
	)
	(arc
		(start 340.971632 -237.08741)
		(mid 340.784434 -237.037233)
		(end 340.597236 -237.08741)
		(width 0.088646)
		(layer "In11.Cu")
		(net "M_D_CPU0_SB_DQ<8>")
	)
	(arc
		(start 338.146136 -237.083854)
		(mid 337.943549 -236.877503)
		(end 337.86953 -236.597952)
		(width 0.088646)
		(layer "In11.Cu")
		(net "M_D_CPU0_SB_DQ<8>")
	)
	(arc
		(start 337.399884 -235.783882)
		(mid 337.352205 -235.600982)
		(end 337.221322 -235.464604)
		(width 0.088646)
		(layer "In11.Cu")
		(net "M_D_CPU0_SB_DQ<8>")
	)
	(arc
		(start 337.682078 -236.273594)
		(mid 337.480796 -236.076107)
		(end 337.399884 -235.80598)
		(width 0.088646)
		(layer "In11.Cu")
		(net "M_D_CPU0_SB_DQ<8>")
	)
	(arc
		(start 345.296236 -237.08741)
		(mid 345.022037 -237.163245)
		(end 344.745564 -237.096046)
		(width 0.088646)
		(layer "In11.Cu")
		(net "M_D_CPU0_SB_DQ<8>")
	)
	(arc
		(start 336.838036 -235.459524)
		(mid 336.563837 -235.535359)
		(end 336.287364 -235.46816)
		(width 0.088646)
		(layer "In11.Cu")
		(net "M_D_CPU0_SB_DQ<8>")
	)
	(arc
		(start 335.802478 -234.645708)
		(mid 335.61528 -234.595565)
		(end 335.428082 -234.645708)
		(width 0.088646)
		(layer "In11.Cu")
		(net "M_D_CPU0_SB_DQ<8>")
	)
	(segment
		(start 265.518646 -223.790764)
		(end 265.518646 -223.942402)
		(width 0.20066)
		(layer "F.Cu")
		(net "M_D_CPU0_SB_DQ<7>")
	)
	(segment
		(start 265.64717 -223.66224)
		(end 265.518646 -223.790764)
		(width 0.20066)
		(layer "F.Cu")
		(net "M_D_CPU0_SB_DQ<7>")
	)
	(segment
		(start 262.752332 -224.0915)
		(end 262.514334 -224.0915)
		(width 0.101854)
		(layer "F.Cu")
		(net "M_D_CPU0_SB_DQ<7>")
	)
	(segment
		(start 265.369548 -224.0915)
		(end 264.825226 -224.0915)
		(width 0.20066)
		(layer "F.Cu")
		(net "M_D_CPU0_SB_DQ<7>")
	)
	(segment
		(start 262.003794 -223.96323)
		(end 262.003794 -223.792542)
		(width 0.20066)
		(layer "F.Cu")
		(net "M_D_CPU0_SB_DQ<7>")
	)
	(segment
		(start 267.724382 -223.666558)
		(end 266.90828 -223.666558)
		(width 0.20066)
		(layer "F.Cu")
		(net "M_D_CPU0_SB_DQ<7>")
	)
	(segment
		(start 262.146288 -224.105724)
		(end 262.003794 -223.96323)
		(width 0.20066)
		(layer "F.Cu")
		(net "M_D_CPU0_SB_DQ<7>")
	)
	(segment
		(start 347.832934 -238.761524)
		(end 347.83268 -238.76127)
		(width 0.20066)
		(layer "F.Cu")
		(net "M_D_CPU0_SB_DQ<7>")
	)
	(segment
		(start 347.83268 -238.76127)
		(end 347.83268 -238.225584)
		(width 0.20066)
		(layer "F.Cu")
		(net "M_D_CPU0_SB_DQ<7>")
	)
	(segment
		(start 262.514334 -224.0915)
		(end 262.50011 -224.105724)
		(width 0.101854)
		(layer "F.Cu")
		(net "M_D_CPU0_SB_DQ<7>")
	)
	(segment
		(start 264.825226 -224.0915)
		(end 262.752332 -224.0915)
		(width 0.1016)
		(layer "F.Cu")
		(net "M_D_CPU0_SB_DQ<7>")
	)
	(segment
		(start 262.003794 -223.792542)
		(end 261.87781 -223.666558)
		(width 0.20066)
		(layer "F.Cu")
		(net "M_D_CPU0_SB_DQ<7>")
	)
	(segment
		(start 268.829282 -223.666558)
		(end 267.724382 -223.666558)
		(width 0.20066)
		(layer "F.Cu")
		(net "M_D_CPU0_SB_DQ<7>")
	)
	(segment
		(start 266.042394 -223.66224)
		(end 265.64717 -223.66224)
		(width 0.20066)
		(layer "F.Cu")
		(net "M_D_CPU0_SB_DQ<7>")
	)
	(segment
		(start 261.87781 -223.666558)
		(end 260.180582 -223.666558)
		(width 0.20066)
		(layer "F.Cu")
		(net "M_D_CPU0_SB_DQ<7>")
	)
	(segment
		(start 262.50011 -224.105724)
		(end 262.146288 -224.105724)
		(width 0.20066)
		(layer "F.Cu")
		(net "M_D_CPU0_SB_DQ<7>")
	)
	(segment
		(start 265.518646 -223.942402)
		(end 265.369548 -224.0915)
		(width 0.20066)
		(layer "F.Cu")
		(net "M_D_CPU0_SB_DQ<7>")
	)
	(segment
		(start 266.700762 -223.874076)
		(end 266.25423 -223.874076)
		(width 0.20066)
		(layer "F.Cu")
		(net "M_D_CPU0_SB_DQ<7>")
	)
	(segment
		(start 266.90828 -223.666558)
		(end 266.700762 -223.874076)
		(width 0.20066)
		(layer "F.Cu")
		(net "M_D_CPU0_SB_DQ<7>")
	)
	(segment
		(start 266.25423 -223.874076)
		(end 266.042394 -223.66224)
		(width 0.20066)
		(layer "F.Cu")
		(net "M_D_CPU0_SB_DQ<7>")
	)
	(segment
		(start 344.745564 -237.72749)
		(end 344.730832 -237.736126)
		(width 0.088646)
		(layer "In11.Cu")
		(net "M_D_CPU0_SB_DQ<7>")
	)
	(segment
		(start 346.620592 -237.73003)
		(end 346.610178 -237.736126)
		(width 0.088646)
		(layer "In11.Cu")
		(net "M_D_CPU0_SB_DQ<7>")
	)
	(segment
		(start 342.865964 -237.72749)
		(end 342.851232 -237.736126)
		(width 0.088646)
		(layer "In11.Cu")
		(net "M_D_CPU0_SB_DQ<7>")
	)
	(segment
		(start 274.379436 -223.252284)
		(end 273.497294 -223.252284)
		(width 0.18288)
		(layer "In11.Cu")
		(net "M_D_CPU0_SB_DQ<7>")
	)
	(segment
		(start 337.312508 -236.92485)
		(end 337.307682 -236.922056)
		(width 0.088646)
		(layer "In11.Cu")
		(net "M_D_CPU0_SB_DQ<7>")
	)
	(segment
		(start 337.307682 -236.922056)
		(end 337.299808 -236.917484)
		(width 0.088646)
		(layer "In11.Cu")
		(net "M_D_CPU0_SB_DQ<7>")
	)
	(segment
		(start 330.938378 -234.63377)
		(end 330.547726 -234.243118)
		(width 0.088646)
		(layer "In11.Cu")
		(net "M_D_CPU0_SB_DQ<7>")
	)
	(segment
		(start 281.405584 -218.689936)
		(end 280.761694 -219.333826)
		(width 0.18288)
		(layer "In11.Cu")
		(net "M_D_CPU0_SB_DQ<7>")
	)
	(segment
		(start 301.34687 -218.99245)
		(end 298.194476 -218.99245)
		(width 0.18288)
		(layer "In11.Cu")
		(net "M_D_CPU0_SB_DQ<7>")
	)
	(segment
		(start 330.313538 -234.243118)
		(end 326.14489 -234.243118)
		(width 0.18288)
		(layer "In11.Cu")
		(net "M_D_CPU0_SB_DQ<7>")
	)
	(segment
		(start 330.938378 -235.458762)
		(end 330.938378 -234.63377)
		(width 0.088646)
		(layer "In11.Cu")
		(net "M_D_CPU0_SB_DQ<7>")
	)
	(segment
		(start 341.537036 -237.736126)
		(end 341.537036 -237.735872)
		(width 0.088646)
		(layer "In11.Cu")
		(net "M_D_CPU0_SB_DQ<7>")
	)
	(segment
		(start 275.910294 -221.721426)
		(end 274.379436 -223.252284)
		(width 0.18288)
		(layer "In11.Cu")
		(net "M_D_CPU0_SB_DQ<7>")
	)
	(segment
		(start 326.14489 -234.243118)
		(end 313.623198 -221.721426)
		(width 0.18288)
		(layer "In11.Cu")
		(net "M_D_CPU0_SB_DQ<7>")
	)
	(segment
		(start 272.521172 -224.228406)
		(end 272.51279 -224.228406)
		(width 0.18288)
		(layer "In11.Cu")
		(net "M_D_CPU0_SB_DQ<7>")
	)
	(segment
		(start 272.486628 -224.254568)
		(end 269.417292 -224.254568)
		(width 0.18288)
		(layer "In11.Cu")
		(net "M_D_CPU0_SB_DQ<7>")
	)
	(segment
		(start 269.417292 -224.254568)
		(end 268.829282 -223.666558)
		(width 0.18288)
		(layer "In11.Cu")
		(net "M_D_CPU0_SB_DQ<7>")
	)
	(segment
		(start 337.120484 -236.597952)
		(end 337.120484 -236.57941)
		(width 0.088646)
		(layer "In11.Cu")
		(net "M_D_CPU0_SB_DQ<7>")
	)
	(segment
		(start 340.986364 -237.727236)
		(end 340.971632 -237.735872)
		(width 0.088646)
		(layer "In11.Cu")
		(net "M_D_CPU0_SB_DQ<7>")
	)
	(segment
		(start 298.194476 -218.99245)
		(end 297.60291 -218.400884)
		(width 0.18288)
		(layer "In11.Cu")
		(net "M_D_CPU0_SB_DQ<7>")
	)
	(segment
		(start 331.638656 -236.15904)
		(end 330.938378 -235.458762)
		(width 0.088646)
		(layer "In11.Cu")
		(net "M_D_CPU0_SB_DQ<7>")
	)
	(segment
		(start 277.840694 -220.781626)
		(end 277.376382 -220.781626)
		(width 0.18288)
		(layer "In11.Cu")
		(net "M_D_CPU0_SB_DQ<7>")
	)
	(segment
		(start 297.60291 -218.400884)
		(end 296.927778 -218.400884)
		(width 0.18288)
		(layer "In11.Cu")
		(net "M_D_CPU0_SB_DQ<7>")
	)
	(segment
		(start 347.83268 -238.225584)
		(end 347.520006 -238.225584)
		(width 0.088646)
		(layer "In11.Cu")
		(net "M_D_CPU0_SB_DQ<7>")
	)
	(segment
		(start 341.926164 -237.72749)
		(end 341.911432 -237.736126)
		(width 0.088646)
		(layer "In11.Cu")
		(net "M_D_CPU0_SB_DQ<7>")
	)
	(segment
		(start 307.096414 -219.966286)
		(end 305.658774 -219.966286)
		(width 0.18288)
		(layer "In11.Cu")
		(net "M_D_CPU0_SB_DQ<7>")
	)
	(segment
		(start 282.804362 -218.689936)
		(end 281.405584 -218.689936)
		(width 0.18288)
		(layer "In11.Cu")
		(net "M_D_CPU0_SB_DQ<7>")
	)
	(segment
		(start 283.106876 -218.99245)
		(end 282.804362 -218.689936)
		(width 0.18288)
		(layer "In11.Cu")
		(net "M_D_CPU0_SB_DQ<7>")
	)
	(segment
		(start 272.51279 -224.228406)
		(end 272.486628 -224.254568)
		(width 0.18288)
		(layer "In11.Cu")
		(net "M_D_CPU0_SB_DQ<7>")
	)
	(segment
		(start 346.235782 -237.736126)
		(end 346.225368 -237.73003)
		(width 0.088646)
		(layer "In11.Cu")
		(net "M_D_CPU0_SB_DQ<7>")
	)
	(segment
		(start 304.467514 -218.775026)
		(end 301.564294 -218.775026)
		(width 0.18288)
		(layer "In11.Cu")
		(net "M_D_CPU0_SB_DQ<7>")
	)
	(segment
		(start 277.376382 -220.781626)
		(end 276.436582 -221.721426)
		(width 0.18288)
		(layer "In11.Cu")
		(net "M_D_CPU0_SB_DQ<7>")
	)
	(segment
		(start 347.520006 -238.225584)
		(end 347.454474 -238.160052)
		(width 0.088646)
		(layer "In11.Cu")
		(net "M_D_CPU0_SB_DQ<7>")
	)
	(segment
		(start 280.761694 -219.479368)
		(end 280.398474 -219.842588)
		(width 0.18288)
		(layer "In11.Cu")
		(net "M_D_CPU0_SB_DQ<7>")
	)
	(segment
		(start 311.622694 -221.721426)
		(end 310.733694 -220.832426)
		(width 0.18288)
		(layer "In11.Cu")
		(net "M_D_CPU0_SB_DQ<7>")
	)
	(segment
		(start 337.777836 -237.735872)
		(end 337.768946 -237.730792)
		(width 0.088646)
		(layer "In11.Cu")
		(net "M_D_CPU0_SB_DQ<7>")
	)
	(segment
		(start 330.547726 -234.243118)
		(end 330.313538 -234.243118)
		(width 0.088646)
		(layer "In11.Cu")
		(net "M_D_CPU0_SB_DQ<7>")
	)
	(segment
		(start 280.398474 -219.842588)
		(end 278.779732 -219.842588)
		(width 0.18288)
		(layer "In11.Cu")
		(net "M_D_CPU0_SB_DQ<7>")
	)
	(segment
		(start 273.497294 -223.252284)
		(end 272.521172 -224.228406)
		(width 0.18288)
		(layer "In11.Cu")
		(net "M_D_CPU0_SB_DQ<7>")
	)
	(segment
		(start 338.166964 -237.727236)
		(end 338.152232 -237.735872)
		(width 0.088646)
		(layer "In11.Cu")
		(net "M_D_CPU0_SB_DQ<7>")
	)
	(segment
		(start 288.153094 -218.648026)
		(end 287.80867 -218.99245)
		(width 0.18288)
		(layer "In11.Cu")
		(net "M_D_CPU0_SB_DQ<7>")
	)
	(segment
		(start 307.312314 -219.750386)
		(end 307.096414 -219.966286)
		(width 0.18288)
		(layer "In11.Cu")
		(net "M_D_CPU0_SB_DQ<7>")
	)
	(segment
		(start 287.80867 -218.99245)
		(end 283.106876 -218.99245)
		(width 0.18288)
		(layer "In11.Cu")
		(net "M_D_CPU0_SB_DQ<7>")
	)
	(segment
		(start 343.805764 -237.72749)
		(end 343.791032 -237.736126)
		(width 0.088646)
		(layer "In11.Cu")
		(net "M_D_CPU0_SB_DQ<7>")
	)
	(segment
		(start 292.660324 -218.911678)
		(end 292.396672 -218.648026)
		(width 0.18288)
		(layer "In11.Cu")
		(net "M_D_CPU0_SB_DQ<7>")
	)
	(segment
		(start 309.743094 -220.832426)
		(end 308.661054 -219.750386)
		(width 0.18288)
		(layer "In11.Cu")
		(net "M_D_CPU0_SB_DQ<7>")
	)
	(segment
		(start 313.623198 -221.721426)
		(end 311.622694 -221.721426)
		(width 0.18288)
		(layer "In11.Cu")
		(net "M_D_CPU0_SB_DQ<7>")
	)
	(segment
		(start 301.564294 -218.775026)
		(end 301.34687 -218.99245)
		(width 0.18288)
		(layer "In11.Cu")
		(net "M_D_CPU0_SB_DQ<7>")
	)
	(segment
		(start 308.661054 -219.750386)
		(end 307.312314 -219.750386)
		(width 0.18288)
		(layer "In11.Cu")
		(net "M_D_CPU0_SB_DQ<7>")
	)
	(segment
		(start 292.396672 -218.648026)
		(end 288.153094 -218.648026)
		(width 0.18288)
		(layer "In11.Cu")
		(net "M_D_CPU0_SB_DQ<7>")
	)
	(segment
		(start 339.657182 -237.735872)
		(end 339.646768 -237.729776)
		(width 0.088646)
		(layer "In11.Cu")
		(net "M_D_CPU0_SB_DQ<7>")
	)
	(segment
		(start 292.925754 -219.842588)
		(end 292.660324 -219.577158)
		(width 0.18288)
		(layer "In11.Cu")
		(net "M_D_CPU0_SB_DQ<7>")
	)
	(segment
		(start 332.326234 -236.15904)
		(end 331.638656 -236.15904)
		(width 0.088646)
		(layer "In11.Cu")
		(net "M_D_CPU0_SB_DQ<7>")
	)
	(segment
		(start 296.927778 -218.400884)
		(end 295.486074 -219.842588)
		(width 0.18288)
		(layer "In11.Cu")
		(net "M_D_CPU0_SB_DQ<7>")
	)
	(segment
		(start 310.733694 -220.832426)
		(end 309.743094 -220.832426)
		(width 0.18288)
		(layer "In11.Cu")
		(net "M_D_CPU0_SB_DQ<7>")
	)
	(segment
		(start 292.660324 -219.577158)
		(end 292.660324 -218.911678)
		(width 0.18288)
		(layer "In11.Cu")
		(net "M_D_CPU0_SB_DQ<7>")
	)
	(segment
		(start 337.313778 -236.925612)
		(end 337.312508 -236.92485)
		(width 0.088646)
		(layer "In11.Cu")
		(net "M_D_CPU0_SB_DQ<7>")
	)
	(segment
		(start 276.436582 -221.721426)
		(end 275.910294 -221.721426)
		(width 0.18288)
		(layer "In11.Cu")
		(net "M_D_CPU0_SB_DQ<7>")
	)
	(segment
		(start 295.486074 -219.842588)
		(end 292.925754 -219.842588)
		(width 0.18288)
		(layer "In11.Cu")
		(net "M_D_CPU0_SB_DQ<7>")
	)
	(segment
		(start 340.041992 -237.729776)
		(end 340.031578 -237.735872)
		(width 0.088646)
		(layer "In11.Cu")
		(net "M_D_CPU0_SB_DQ<7>")
	)
	(segment
		(start 278.779732 -219.842588)
		(end 277.840694 -220.781626)
		(width 0.18288)
		(layer "In11.Cu")
		(net "M_D_CPU0_SB_DQ<7>")
	)
	(segment
		(start 305.658774 -219.966286)
		(end 304.467514 -218.775026)
		(width 0.18288)
		(layer "In11.Cu")
		(net "M_D_CPU0_SB_DQ<7>")
	)
	(segment
		(start 280.761694 -219.333826)
		(end 280.761694 -219.479368)
		(width 0.18288)
		(layer "In11.Cu")
		(net "M_D_CPU0_SB_DQ<7>")
	)
	(arc
		(start 333.078836 -236.10824)
		(mid 332.796134 -236.032498)
		(end 332.513432 -236.10824)
		(width 0.088646)
		(layer "In11.Cu")
		(net "M_D_CPU0_SB_DQ<7>")
	)
	(arc
		(start 342.476836 -237.736126)
		(mid 342.202637 -237.660291)
		(end 341.926164 -237.72749)
		(width 0.088646)
		(layer "In11.Cu")
		(net "M_D_CPU0_SB_DQ<7>")
	)
	(arc
		(start 344.356436 -237.736126)
		(mid 344.082237 -237.660291)
		(end 343.805764 -237.72749)
		(width 0.088646)
		(layer "In11.Cu")
		(net "M_D_CPU0_SB_DQ<7>")
	)
	(arc
		(start 335.898236 -236.10824)
		(mid 335.615534 -236.032498)
		(end 335.332832 -236.10824)
		(width 0.088646)
		(layer "In11.Cu")
		(net "M_D_CPU0_SB_DQ<7>")
	)
	(arc
		(start 339.646768 -237.729776)
		(mid 339.36859 -237.660084)
		(end 339.092032 -237.735872)
		(width 0.088646)
		(layer "In11.Cu")
		(net "M_D_CPU0_SB_DQ<7>")
	)
	(arc
		(start 333.453232 -236.10824)
		(mid 333.266034 -236.158383)
		(end 333.078836 -236.10824)
		(width 0.088646)
		(layer "In11.Cu")
		(net "M_D_CPU0_SB_DQ<7>")
	)
	(arc
		(start 341.911432 -237.736126)
		(mid 341.724234 -237.786269)
		(end 341.537036 -237.736126)
		(width 0.088646)
		(layer "In11.Cu")
		(net "M_D_CPU0_SB_DQ<7>")
	)
	(arc
		(start 345.296236 -237.736126)
		(mid 345.022037 -237.660291)
		(end 344.745564 -237.72749)
		(width 0.088646)
		(layer "In11.Cu")
		(net "M_D_CPU0_SB_DQ<7>")
	)
	(arc
		(start 338.152232 -237.735872)
		(mid 337.965034 -237.786015)
		(end 337.777836 -237.735872)
		(width 0.088646)
		(layer "In11.Cu")
		(net "M_D_CPU0_SB_DQ<7>")
	)
	(arc
		(start 340.031578 -237.735872)
		(mid 339.84438 -237.786015)
		(end 339.657182 -237.735872)
		(width 0.088646)
		(layer "In11.Cu")
		(net "M_D_CPU0_SB_DQ<7>")
	)
	(arc
		(start 339.092032 -237.735872)
		(mid 338.904834 -237.786015)
		(end 338.717636 -237.735872)
		(width 0.088646)
		(layer "In11.Cu")
		(net "M_D_CPU0_SB_DQ<7>")
	)
	(arc
		(start 340.597236 -237.735872)
		(mid 340.320423 -237.660036)
		(end 340.041992 -237.729776)
		(width 0.088646)
		(layer "In11.Cu")
		(net "M_D_CPU0_SB_DQ<7>")
	)
	(arc
		(start 334.018636 -236.10824)
		(mid 333.735934 -236.032498)
		(end 333.453232 -236.10824)
		(width 0.088646)
		(layer "In11.Cu")
		(net "M_D_CPU0_SB_DQ<7>")
	)
	(arc
		(start 337.299808 -236.917484)
		(mid 337.168396 -236.781152)
		(end 337.120484 -236.597952)
		(width 0.088646)
		(layer "In11.Cu")
		(net "M_D_CPU0_SB_DQ<7>")
	)
	(arc
		(start 334.393032 -236.10824)
		(mid 334.205834 -236.158383)
		(end 334.018636 -236.10824)
		(width 0.088646)
		(layer "In11.Cu")
		(net "M_D_CPU0_SB_DQ<7>")
	)
	(arc
		(start 343.791032 -237.736126)
		(mid 343.603834 -237.786269)
		(end 343.416636 -237.736126)
		(width 0.088646)
		(layer "In11.Cu")
		(net "M_D_CPU0_SB_DQ<7>")
	)
	(arc
		(start 347.175836 -237.736126)
		(mid 346.899023 -237.660256)
		(end 346.620592 -237.73003)
		(width 0.088646)
		(layer "In11.Cu")
		(net "M_D_CPU0_SB_DQ<7>")
	)
	(arc
		(start 342.851232 -237.736126)
		(mid 342.664034 -237.786269)
		(end 342.476836 -237.736126)
		(width 0.088646)
		(layer "In11.Cu")
		(net "M_D_CPU0_SB_DQ<7>")
	)
	(arc
		(start 337.590384 -237.411514)
		(mid 337.516393 -237.131948)
		(end 337.313778 -236.925612)
		(width 0.088646)
		(layer "In11.Cu")
		(net "M_D_CPU0_SB_DQ<7>")
	)
	(arc
		(start 338.717636 -237.735872)
		(mid 338.443407 -237.659947)
		(end 338.166964 -237.727236)
		(width 0.088646)
		(layer "In11.Cu")
		(net "M_D_CPU0_SB_DQ<7>")
	)
	(arc
		(start 343.416636 -237.736126)
		(mid 343.142437 -237.660291)
		(end 342.865964 -237.72749)
		(width 0.088646)
		(layer "In11.Cu")
		(net "M_D_CPU0_SB_DQ<7>")
	)
	(arc
		(start 344.730832 -237.736126)
		(mid 344.543634 -237.786269)
		(end 344.356436 -237.736126)
		(width 0.088646)
		(layer "In11.Cu")
		(net "M_D_CPU0_SB_DQ<7>")
	)
	(arc
		(start 346.610178 -237.736126)
		(mid 346.42298 -237.786269)
		(end 346.235782 -237.736126)
		(width 0.088646)
		(layer "In11.Cu")
		(net "M_D_CPU0_SB_DQ<7>")
	)
	(arc
		(start 345.670632 -237.736126)
		(mid 345.483434 -237.786269)
		(end 345.296236 -237.736126)
		(width 0.088646)
		(layer "In11.Cu")
		(net "M_D_CPU0_SB_DQ<7>")
	)
	(arc
		(start 341.537036 -237.735872)
		(mid 341.262807 -237.659947)
		(end 340.986364 -237.727236)
		(width 0.088646)
		(layer "In11.Cu")
		(net "M_D_CPU0_SB_DQ<7>")
	)
	(arc
		(start 336.838036 -236.10824)
		(mid 336.555334 -236.032498)
		(end 336.272632 -236.10824)
		(width 0.088646)
		(layer "In11.Cu")
		(net "M_D_CPU0_SB_DQ<7>")
	)
	(arc
		(start 337.120484 -236.57941)
		(mid 337.040322 -236.307221)
		(end 336.838036 -236.10824)
		(width 0.088646)
		(layer "In11.Cu")
		(net "M_D_CPU0_SB_DQ<7>")
	)
	(arc
		(start 347.454474 -238.160052)
		(mid 347.365386 -237.915067)
		(end 347.175836 -237.736126)
		(width 0.088646)
		(layer "In11.Cu")
		(net "M_D_CPU0_SB_DQ<7>")
	)
	(arc
		(start 337.768946 -237.730792)
		(mid 337.638032 -237.594432)
		(end 337.590384 -237.411514)
		(width 0.088646)
		(layer "In11.Cu")
		(net "M_D_CPU0_SB_DQ<7>")
	)
	(arc
		(start 336.272632 -236.10824)
		(mid 336.085434 -236.158383)
		(end 335.898236 -236.10824)
		(width 0.088646)
		(layer "In11.Cu")
		(net "M_D_CPU0_SB_DQ<7>")
	)
	(arc
		(start 334.958436 -236.10824)
		(mid 334.675734 -236.032498)
		(end 334.393032 -236.10824)
		(width 0.088646)
		(layer "In11.Cu")
		(net "M_D_CPU0_SB_DQ<7>")
	)
	(arc
		(start 335.332832 -236.10824)
		(mid 335.145634 -236.158383)
		(end 334.958436 -236.10824)
		(width 0.088646)
		(layer "In11.Cu")
		(net "M_D_CPU0_SB_DQ<7>")
	)
	(arc
		(start 340.971632 -237.735872)
		(mid 340.784434 -237.786015)
		(end 340.597236 -237.735872)
		(width 0.088646)
		(layer "In11.Cu")
		(net "M_D_CPU0_SB_DQ<7>")
	)
	(arc
		(start 332.513432 -236.10824)
		(mid 332.423176 -236.145962)
		(end 332.326234 -236.15904)
		(width 0.088646)
		(layer "In11.Cu")
		(net "M_D_CPU0_SB_DQ<7>")
	)
	(arc
		(start 346.225368 -237.73003)
		(mid 345.94719 -237.660307)
		(end 345.670632 -237.736126)
		(width 0.088646)
		(layer "In11.Cu")
		(net "M_D_CPU0_SB_DQ<7>")
	)
	(segment
		(start 268.829282 -225.36658)
		(end 267.724382 -225.36658)
		(width 0.20066)
		(layer "F.Cu")
		(net "M_D_CPU0_SB_DQ<6>")
	)
	(segment
		(start 262.50011 -224.931478)
		(end 261.762748 -224.931478)
		(width 0.20066)
		(layer "F.Cu")
		(net "M_D_CPU0_SB_DQ<6>")
	)
	(segment
		(start 267.724382 -225.36658)
		(end 266.409678 -225.36658)
		(width 0.20066)
		(layer "F.Cu")
		(net "M_D_CPU0_SB_DQ<6>")
	)
	(segment
		(start 265.458194 -224.941638)
		(end 264.825226 -224.941638)
		(width 0.20066)
		(layer "F.Cu")
		(net "M_D_CPU0_SB_DQ<6>")
	)
	(segment
		(start 261.327646 -225.36658)
		(end 260.180582 -225.36658)
		(width 0.20066)
		(layer "F.Cu")
		(net "M_D_CPU0_SB_DQ<6>")
	)
	(segment
		(start 348.30258 -239.57534)
		(end 348.302834 -239.575086)
		(width 0.20066)
		(layer "F.Cu")
		(net "M_D_CPU0_SB_DQ<6>")
	)
	(segment
		(start 261.762748 -224.931478)
		(end 261.327646 -225.36658)
		(width 0.20066)
		(layer "F.Cu")
		(net "M_D_CPU0_SB_DQ<6>")
	)
	(segment
		(start 264.825226 -224.941638)
		(end 262.765286 -224.941638)
		(width 0.1016)
		(layer "F.Cu")
		(net "M_D_CPU0_SB_DQ<6>")
	)
	(segment
		(start 265.601958 -225.085402)
		(end 265.458194 -224.941638)
		(width 0.20066)
		(layer "F.Cu")
		(net "M_D_CPU0_SB_DQ<6>")
	)
	(segment
		(start 266.409678 -225.36658)
		(end 266.197842 -225.578416)
		(width 0.20066)
		(layer "F.Cu")
		(net "M_D_CPU0_SB_DQ<6>")
	)
	(segment
		(start 262.765286 -224.941638)
		(end 262.51027 -224.941638)
		(width 0.101854)
		(layer "F.Cu")
		(net "M_D_CPU0_SB_DQ<6>")
	)
	(segment
		(start 348.302834 -239.575086)
		(end 348.302834 -239.0394)
		(width 0.20066)
		(layer "F.Cu")
		(net "M_D_CPU0_SB_DQ<6>")
	)
	(segment
		(start 265.769344 -225.578416)
		(end 265.601958 -225.41103)
		(width 0.20066)
		(layer "F.Cu")
		(net "M_D_CPU0_SB_DQ<6>")
	)
	(segment
		(start 266.197842 -225.578416)
		(end 265.769344 -225.578416)
		(width 0.20066)
		(layer "F.Cu")
		(net "M_D_CPU0_SB_DQ<6>")
	)
	(segment
		(start 262.51027 -224.941638)
		(end 262.50011 -224.931478)
		(width 0.101854)
		(layer "F.Cu")
		(net "M_D_CPU0_SB_DQ<6>")
	)
	(segment
		(start 265.601958 -225.41103)
		(end 265.601958 -225.085402)
		(width 0.20066)
		(layer "F.Cu")
		(net "M_D_CPU0_SB_DQ<6>")
	)
	(segment
		(start 299.989494 -220.883226)
		(end 299.79874 -220.692472)
		(width 0.18288)
		(layer "In11.Cu")
		(net "M_D_CPU0_SB_DQ<6>")
	)
	(segment
		(start 303.106074 -220.883226)
		(end 302.045878 -220.883226)
		(width 0.18288)
		(layer "In11.Cu")
		(net "M_D_CPU0_SB_DQ<6>")
	)
	(segment
		(start 291.810694 -221.569026)
		(end 290.744402 -221.569026)
		(width 0.18288)
		(layer "In11.Cu")
		(net "M_D_CPU0_SB_DQ<6>")
	)
	(segment
		(start 297.374056 -220.579188)
		(end 296.483532 -220.579188)
		(width 0.18288)
		(layer "In11.Cu")
		(net "M_D_CPU0_SB_DQ<6>")
	)
	(segment
		(start 301.852838 -220.690186)
		(end 301.852838 -220.470476)
		(width 0.18288)
		(layer "In11.Cu")
		(net "M_D_CPU0_SB_DQ<6>")
	)
	(segment
		(start 276.41677 -223.448626)
		(end 276.07895 -223.448626)
		(width 0.18288)
		(layer "In11.Cu")
		(net "M_D_CPU0_SB_DQ<6>")
	)
	(segment
		(start 297.48734 -220.692472)
		(end 297.374056 -220.579188)
		(width 0.18288)
		(layer "In11.Cu")
		(net "M_D_CPU0_SB_DQ<6>")
	)
	(segment
		(start 269.443708 -225.981006)
		(end 268.829282 -225.36658)
		(width 0.18288)
		(layer "In11.Cu")
		(net "M_D_CPU0_SB_DQ<6>")
	)
	(segment
		(start 335.434432 -236.925866)
		(end 335.432654 -236.92485)
		(width 0.088646)
		(layer "In11.Cu")
		(net "M_D_CPU0_SB_DQ<6>")
	)
	(segment
		(start 280.398474 -221.54261)
		(end 279.06599 -221.54261)
		(width 0.18288)
		(layer "In11.Cu")
		(net "M_D_CPU0_SB_DQ<6>")
	)
	(segment
		(start 271.363694 -225.312732)
		(end 271.048734 -225.312732)
		(width 0.18288)
		(layer "In11.Cu")
		(net "M_D_CPU0_SB_DQ<6>")
	)
	(segment
		(start 282.554426 -220.694758)
		(end 282.438856 -220.579188)
		(width 0.18288)
		(layer "In11.Cu")
		(net "M_D_CPU0_SB_DQ<6>")
	)
	(segment
		(start 301.344838 -220.277436)
		(end 301.151798 -220.470476)
		(width 0.18288)
		(layer "In11.Cu")
		(net "M_D_CPU0_SB_DQ<6>")
	)
	(segment
		(start 338.247482 -238.549942)
		(end 338.23275 -238.541306)
		(width 0.088646)
		(layer "In11.Cu")
		(net "M_D_CPU0_SB_DQ<6>")
	)
	(segment
		(start 345.766136 -238.549942)
		(end 345.755722 -238.543846)
		(width 0.088646)
		(layer "In11.Cu")
		(net "M_D_CPU0_SB_DQ<6>")
	)
	(segment
		(start 303.995074 -221.772226)
		(end 303.106074 -220.883226)
		(width 0.18288)
		(layer "In11.Cu")
		(net "M_D_CPU0_SB_DQ<6>")
	)
	(segment
		(start 301.852838 -220.470476)
		(end 301.659798 -220.277436)
		(width 0.18288)
		(layer "In11.Cu")
		(net "M_D_CPU0_SB_DQ<6>")
	)
	(segment
		(start 270.855694 -225.787966)
		(end 270.662654 -225.981006)
		(width 0.18288)
		(layer "In11.Cu")
		(net "M_D_CPU0_SB_DQ<6>")
	)
	(segment
		(start 335.432654 -236.92485)
		(end 335.428336 -236.92231)
		(width 0.088646)
		(layer "In11.Cu")
		(net "M_D_CPU0_SB_DQ<6>")
	)
	(segment
		(start 290.744402 -221.569026)
		(end 289.804602 -220.629226)
		(width 0.18288)
		(layer "In11.Cu")
		(net "M_D_CPU0_SB_DQ<6>")
	)
	(segment
		(start 307.999384 -221.450916)
		(end 307.366416 -221.450916)
		(width 0.18288)
		(layer "In11.Cu")
		(net "M_D_CPU0_SB_DQ<6>")
	)
	(segment
		(start 330.454762 -235.263944)
		(end 330.313538 -235.263944)
		(width 0.088646)
		(layer "In11.Cu")
		(net "M_D_CPU0_SB_DQ<6>")
	)
	(segment
		(start 271.556734 -225.505772)
		(end 271.363694 -225.312732)
		(width 0.18288)
		(layer "In11.Cu")
		(net "M_D_CPU0_SB_DQ<6>")
	)
	(segment
		(start 271.556734 -225.787966)
		(end 271.556734 -225.505772)
		(width 0.18288)
		(layer "In11.Cu")
		(net "M_D_CPU0_SB_DQ<6>")
	)
	(segment
		(start 276.07895 -223.448626)
		(end 274.40255 -225.125026)
		(width 0.18288)
		(layer "In11.Cu")
		(net "M_D_CPU0_SB_DQ<6>")
	)
	(segment
		(start 288.436304 -220.694758)
		(end 282.554426 -220.694758)
		(width 0.18288)
		(layer "In11.Cu")
		(net "M_D_CPU0_SB_DQ<6>")
	)
	(segment
		(start 334.877664 -236.913674)
		(end 334.862932 -236.92231)
		(width 0.088646)
		(layer "In11.Cu")
		(net "M_D_CPU0_SB_DQ<6>")
	)
	(segment
		(start 330.543408 -235.61929)
		(end 330.543408 -235.35259)
		(width 0.088646)
		(layer "In11.Cu")
		(net "M_D_CPU0_SB_DQ<6>")
	)
	(segment
		(start 281.361896 -220.579188)
		(end 280.398474 -221.54261)
		(width 0.18288)
		(layer "In11.Cu")
		(net "M_D_CPU0_SB_DQ<6>")
	)
	(segment
		(start 274.40255 -225.125026)
		(end 273.725894 -225.125026)
		(width 0.18288)
		(layer "In11.Cu")
		(net "M_D_CPU0_SB_DQ<6>")
	)
	(segment
		(start 282.438856 -220.579188)
		(end 281.361896 -220.579188)
		(width 0.18288)
		(layer "In11.Cu")
		(net "M_D_CPU0_SB_DQ<6>")
	)
	(segment
		(start 347.333316 -238.637826)
		(end 346.926408 -238.637826)
		(width 0.088646)
		(layer "In11.Cu")
		(net "M_D_CPU0_SB_DQ<6>")
	)
	(segment
		(start 301.659798 -220.277436)
		(end 301.344838 -220.277436)
		(width 0.18288)
		(layer "In11.Cu")
		(net "M_D_CPU0_SB_DQ<6>")
	)
	(segment
		(start 278.704294 -221.696026)
		(end 277.815294 -222.585026)
		(width 0.18288)
		(layer "In11.Cu")
		(net "M_D_CPU0_SB_DQ<6>")
	)
	(segment
		(start 314.367418 -224.090738)
		(end 313.585606 -224.090738)
		(width 0.18288)
		(layer "In11.Cu")
		(net "M_D_CPU0_SB_DQ<6>")
	)
	(segment
		(start 343.886282 -238.549942)
		(end 343.87155 -238.541306)
		(width 0.088646)
		(layer "In11.Cu")
		(net "M_D_CPU0_SB_DQ<6>")
	)
	(segment
		(start 341.066882 -238.549942)
		(end 341.05215 -238.541306)
		(width 0.088646)
		(layer "In11.Cu")
		(net "M_D_CPU0_SB_DQ<6>")
	)
	(segment
		(start 344.826082 -238.549942)
		(end 344.81135 -238.541306)
		(width 0.088646)
		(layer "In11.Cu")
		(net "M_D_CPU0_SB_DQ<6>")
	)
	(segment
		(start 309.031894 -222.483426)
		(end 307.999384 -221.450916)
		(width 0.18288)
		(layer "In11.Cu")
		(net "M_D_CPU0_SB_DQ<6>")
	)
	(segment
		(start 325.540624 -235.263944)
		(end 314.367418 -224.090738)
		(width 0.18288)
		(layer "In11.Cu")
		(net "M_D_CPU0_SB_DQ<6>")
	)
	(segment
		(start 299.79874 -220.692472)
		(end 297.48734 -220.692472)
		(width 0.18288)
		(layer "In11.Cu")
		(net "M_D_CPU0_SB_DQ<6>")
	)
	(segment
		(start 307.366416 -221.450916)
		(end 307.045106 -221.772226)
		(width 0.18288)
		(layer "In11.Cu")
		(net "M_D_CPU0_SB_DQ<6>")
	)
	(segment
		(start 270.855694 -225.505772)
		(end 270.855694 -225.787966)
		(width 0.18288)
		(layer "In11.Cu")
		(net "M_D_CPU0_SB_DQ<6>")
	)
	(segment
		(start 337.307682 -238.549942)
		(end 337.298792 -238.544862)
		(width 0.088646)
		(layer "In11.Cu")
		(net "M_D_CPU0_SB_DQ<6>")
	)
	(segment
		(start 293.791894 -221.54261)
		(end 293.207694 -221.391226)
		(width 0.18288)
		(layer "In11.Cu")
		(net "M_D_CPU0_SB_DQ<6>")
	)
	(segment
		(start 307.045106 -221.772226)
		(end 303.995074 -221.772226)
		(width 0.18288)
		(layer "In11.Cu")
		(net "M_D_CPU0_SB_DQ<6>")
	)
	(segment
		(start 300.958758 -220.883226)
		(end 299.989494 -220.883226)
		(width 0.18288)
		(layer "In11.Cu")
		(net "M_D_CPU0_SB_DQ<6>")
	)
	(segment
		(start 310.733694 -222.483426)
		(end 309.031894 -222.483426)
		(width 0.18288)
		(layer "In11.Cu")
		(net "M_D_CPU0_SB_DQ<6>")
	)
	(segment
		(start 296.483532 -220.579188)
		(end 295.52011 -221.54261)
		(width 0.18288)
		(layer "In11.Cu")
		(net "M_D_CPU0_SB_DQ<6>")
	)
	(segment
		(start 336.287364 -237.727236)
		(end 336.272632 -237.735872)
		(width 0.088646)
		(layer "In11.Cu")
		(net "M_D_CPU0_SB_DQ<6>")
	)
	(segment
		(start 270.662654 -225.981006)
		(end 269.443708 -225.981006)
		(width 0.18288)
		(layer "In11.Cu")
		(net "M_D_CPU0_SB_DQ<6>")
	)
	(segment
		(start 289.804602 -220.629226)
		(end 288.661094 -220.629226)
		(width 0.18288)
		(layer "In11.Cu")
		(net "M_D_CPU0_SB_DQ<6>")
	)
	(segment
		(start 272.869914 -225.981006)
		(end 271.749774 -225.981006)
		(width 0.18288)
		(layer "In11.Cu")
		(net "M_D_CPU0_SB_DQ<6>")
	)
	(segment
		(start 330.313538 -235.263944)
		(end 325.540624 -235.263944)
		(width 0.18288)
		(layer "In11.Cu")
		(net "M_D_CPU0_SB_DQ<6>")
	)
	(segment
		(start 330.543408 -235.35259)
		(end 330.454762 -235.263944)
		(width 0.088646)
		(layer "In11.Cu")
		(net "M_D_CPU0_SB_DQ<6>")
	)
	(segment
		(start 301.151798 -220.470476)
		(end 301.151798 -220.690186)
		(width 0.18288)
		(layer "In11.Cu")
		(net "M_D_CPU0_SB_DQ<6>")
	)
	(segment
		(start 277.28037 -222.585026)
		(end 276.41677 -223.448626)
		(width 0.18288)
		(layer "In11.Cu")
		(net "M_D_CPU0_SB_DQ<6>")
	)
	(segment
		(start 339.187536 -238.549942)
		(end 339.177122 -238.543846)
		(width 0.088646)
		(layer "In11.Cu")
		(net "M_D_CPU0_SB_DQ<6>")
	)
	(segment
		(start 271.749774 -225.981006)
		(end 271.556734 -225.787966)
		(width 0.18288)
		(layer "In11.Cu")
		(net "M_D_CPU0_SB_DQ<6>")
	)
	(segment
		(start 301.151798 -220.690186)
		(end 300.958758 -220.883226)
		(width 0.18288)
		(layer "In11.Cu")
		(net "M_D_CPU0_SB_DQ<6>")
	)
	(segment
		(start 277.815294 -222.585026)
		(end 277.28037 -222.585026)
		(width 0.18288)
		(layer "In11.Cu")
		(net "M_D_CPU0_SB_DQ<6>")
	)
	(segment
		(start 332.32598 -236.846364)
		(end 331.770482 -236.846364)
		(width 0.088646)
		(layer "In11.Cu")
		(net "M_D_CPU0_SB_DQ<6>")
	)
	(segment
		(start 302.045878 -220.883226)
		(end 301.852838 -220.690186)
		(width 0.18288)
		(layer "In11.Cu")
		(net "M_D_CPU0_SB_DQ<6>")
	)
	(segment
		(start 332.998064 -236.913674)
		(end 332.983332 -236.92231)
		(width 0.088646)
		(layer "In11.Cu")
		(net "M_D_CPU0_SB_DQ<6>")
	)
	(segment
		(start 279.064212 -221.544388)
		(end 278.704294 -221.696026)
		(width 0.18288)
		(layer "In11.Cu")
		(net "M_D_CPU0_SB_DQ<6>")
	)
	(segment
		(start 313.585606 -224.090738)
		(end 312.791094 -223.296226)
		(width 0.18288)
		(layer "In11.Cu")
		(net "M_D_CPU0_SB_DQ<6>")
	)
	(segment
		(start 292.521894 -221.391226)
		(end 291.810694 -221.569026)
		(width 0.18288)
		(layer "In11.Cu")
		(net "M_D_CPU0_SB_DQ<6>")
	)
	(segment
		(start 311.546494 -223.296226)
		(end 310.733694 -222.483426)
		(width 0.18288)
		(layer "In11.Cu")
		(net "M_D_CPU0_SB_DQ<6>")
	)
	(segment
		(start 342.006682 -238.549942)
		(end 341.99195 -238.541306)
		(width 0.088646)
		(layer "In11.Cu")
		(net "M_D_CPU0_SB_DQ<6>")
	)
	(segment
		(start 335.898236 -237.735872)
		(end 335.889346 -237.730792)
		(width 0.088646)
		(layer "In11.Cu")
		(net "M_D_CPU0_SB_DQ<6>")
	)
	(segment
		(start 331.770482 -236.846364)
		(end 330.543408 -235.61929)
		(width 0.088646)
		(layer "In11.Cu")
		(net "M_D_CPU0_SB_DQ<6>")
	)
	(segment
		(start 295.52011 -221.54261)
		(end 293.791894 -221.54261)
		(width 0.18288)
		(layer "In11.Cu")
		(net "M_D_CPU0_SB_DQ<6>")
	)
	(segment
		(start 279.06599 -221.54261)
		(end 279.064212 -221.544388)
		(width 0.18288)
		(layer "In11.Cu")
		(net "M_D_CPU0_SB_DQ<6>")
	)
	(segment
		(start 312.791094 -223.296226)
		(end 311.546494 -223.296226)
		(width 0.18288)
		(layer "In11.Cu")
		(net "M_D_CPU0_SB_DQ<6>")
	)
	(segment
		(start 271.048734 -225.312732)
		(end 270.855694 -225.505772)
		(width 0.18288)
		(layer "In11.Cu")
		(net "M_D_CPU0_SB_DQ<6>")
	)
	(segment
		(start 340.127082 -238.549942)
		(end 340.116668 -238.543846)
		(width 0.088646)
		(layer "In11.Cu")
		(net "M_D_CPU0_SB_DQ<6>")
	)
	(segment
		(start 337.12023 -238.225584)
		(end 337.12023 -238.203486)
		(width 0.088646)
		(layer "In11.Cu")
		(net "M_D_CPU0_SB_DQ<6>")
	)
	(segment
		(start 273.725894 -225.125026)
		(end 272.869914 -225.981006)
		(width 0.18288)
		(layer "In11.Cu")
		(net "M_D_CPU0_SB_DQ<6>")
	)
	(segment
		(start 288.661094 -220.629226)
		(end 288.436304 -220.694758)
		(width 0.18288)
		(layer "In11.Cu")
		(net "M_D_CPU0_SB_DQ<6>")
	)
	(segment
		(start 293.207694 -221.391226)
		(end 292.521894 -221.391226)
		(width 0.18288)
		(layer "In11.Cu")
		(net "M_D_CPU0_SB_DQ<6>")
	)
	(arc
		(start 335.428336 -236.92231)
		(mid 335.154137 -236.846475)
		(end 334.877664 -236.913674)
		(width 0.088646)
		(layer "In11.Cu")
		(net "M_D_CPU0_SB_DQ<6>")
	)
	(arc
		(start 341.99195 -238.541306)
		(mid 341.715475 -238.473986)
		(end 341.441278 -238.549942)
		(width 0.088646)
		(layer "In11.Cu")
		(net "M_D_CPU0_SB_DQ<6>")
	)
	(arc
		(start 348.302834 -239.0394)
		(mid 347.858015 -238.742182)
		(end 347.333316 -238.637826)
		(width 0.088646)
		(layer "In11.Cu")
		(net "M_D_CPU0_SB_DQ<6>")
	)
	(arc
		(start 340.116668 -238.543846)
		(mid 339.83849 -238.474123)
		(end 339.561932 -238.549942)
		(width 0.088646)
		(layer "In11.Cu")
		(net "M_D_CPU0_SB_DQ<6>")
	)
	(arc
		(start 337.298792 -238.544862)
		(mid 337.167878 -238.408502)
		(end 337.12023 -238.225584)
		(width 0.088646)
		(layer "In11.Cu")
		(net "M_D_CPU0_SB_DQ<6>")
	)
	(arc
		(start 335.710784 -237.411514)
		(mid 335.636805 -237.132155)
		(end 335.434432 -236.925866)
		(width 0.088646)
		(layer "In11.Cu")
		(net "M_D_CPU0_SB_DQ<6>")
	)
	(arc
		(start 344.81135 -238.541306)
		(mid 344.534875 -238.473986)
		(end 344.260678 -238.549942)
		(width 0.088646)
		(layer "In11.Cu")
		(net "M_D_CPU0_SB_DQ<6>")
	)
	(arc
		(start 341.441278 -238.549942)
		(mid 341.25408 -238.600085)
		(end 341.066882 -238.549942)
		(width 0.088646)
		(layer "In11.Cu")
		(net "M_D_CPU0_SB_DQ<6>")
	)
	(arc
		(start 346.926408 -238.637826)
		(mid 346.777106 -238.608128)
		(end 346.650564 -238.523526)
		(width 0.088646)
		(layer "In11.Cu")
		(net "M_D_CPU0_SB_DQ<6>")
	)
	(arc
		(start 337.682078 -238.549942)
		(mid 337.49488 -238.600085)
		(end 337.307682 -238.549942)
		(width 0.088646)
		(layer "In11.Cu")
		(net "M_D_CPU0_SB_DQ<6>")
	)
	(arc
		(start 335.889346 -237.730792)
		(mid 335.758432 -237.594432)
		(end 335.710784 -237.411514)
		(width 0.088646)
		(layer "In11.Cu")
		(net "M_D_CPU0_SB_DQ<6>")
	)
	(arc
		(start 345.200478 -238.549942)
		(mid 345.01328 -238.600085)
		(end 344.826082 -238.549942)
		(width 0.088646)
		(layer "In11.Cu")
		(net "M_D_CPU0_SB_DQ<6>")
	)
	(arc
		(start 332.608936 -236.92231)
		(mid 332.472464 -236.865687)
		(end 332.32598 -236.846364)
		(width 0.088646)
		(layer "In11.Cu")
		(net "M_D_CPU0_SB_DQ<6>")
	)
	(arc
		(start 333.923132 -236.92231)
		(mid 333.735934 -236.972453)
		(end 333.548736 -236.92231)
		(width 0.088646)
		(layer "In11.Cu")
		(net "M_D_CPU0_SB_DQ<6>")
	)
	(arc
		(start 339.177122 -238.543846)
		(mid 338.89869 -238.474)
		(end 338.621878 -238.549942)
		(width 0.088646)
		(layer "In11.Cu")
		(net "M_D_CPU0_SB_DQ<6>")
	)
	(arc
		(start 343.87155 -238.541306)
		(mid 343.595075 -238.473986)
		(end 343.320878 -238.549942)
		(width 0.088646)
		(layer "In11.Cu")
		(net "M_D_CPU0_SB_DQ<6>")
	)
	(arc
		(start 332.983332 -236.92231)
		(mid 332.796134 -236.972453)
		(end 332.608936 -236.92231)
		(width 0.088646)
		(layer "In11.Cu")
		(net "M_D_CPU0_SB_DQ<6>")
	)
	(arc
		(start 344.260678 -238.549942)
		(mid 344.07348 -238.600085)
		(end 343.886282 -238.549942)
		(width 0.088646)
		(layer "In11.Cu")
		(net "M_D_CPU0_SB_DQ<6>")
	)
	(arc
		(start 341.05215 -238.541306)
		(mid 340.775675 -238.473986)
		(end 340.501478 -238.549942)
		(width 0.088646)
		(layer "In11.Cu")
		(net "M_D_CPU0_SB_DQ<6>")
	)
	(arc
		(start 333.548736 -236.92231)
		(mid 333.274537 -236.846475)
		(end 332.998064 -236.913674)
		(width 0.088646)
		(layer "In11.Cu")
		(net "M_D_CPU0_SB_DQ<6>")
	)
	(arc
		(start 346.647516 -238.520478)
		(mid 346.390517 -238.475031)
		(end 346.140532 -238.549942)
		(width 0.088646)
		(layer "In11.Cu")
		(net "M_D_CPU0_SB_DQ<6>")
	)
	(arc
		(start 346.140532 -238.549942)
		(mid 345.953334 -238.600085)
		(end 345.766136 -238.549942)
		(width 0.088646)
		(layer "In11.Cu")
		(net "M_D_CPU0_SB_DQ<6>")
	)
	(arc
		(start 337.12023 -238.203486)
		(mid 337.039319 -237.933358)
		(end 336.838036 -237.735872)
		(width 0.088646)
		(layer "In11.Cu")
		(net "M_D_CPU0_SB_DQ<6>")
	)
	(arc
		(start 346.650564 -238.523526)
		(mid 346.649036 -238.522006)
		(end 346.647516 -238.520478)
		(width 0.088646)
		(layer "In11.Cu")
		(net "M_D_CPU0_SB_DQ<6>")
	)
	(arc
		(start 339.561932 -238.549942)
		(mid 339.374734 -238.600085)
		(end 339.187536 -238.549942)
		(width 0.088646)
		(layer "In11.Cu")
		(net "M_D_CPU0_SB_DQ<6>")
	)
	(arc
		(start 334.862932 -236.92231)
		(mid 334.675734 -236.972453)
		(end 334.488536 -236.92231)
		(width 0.088646)
		(layer "In11.Cu")
		(net "M_D_CPU0_SB_DQ<6>")
	)
	(arc
		(start 343.320878 -238.549942)
		(mid 343.13368 -238.600085)
		(end 342.946482 -238.549942)
		(width 0.088646)
		(layer "In11.Cu")
		(net "M_D_CPU0_SB_DQ<6>")
	)
	(arc
		(start 334.488536 -236.92231)
		(mid 334.205834 -236.846534)
		(end 333.923132 -236.92231)
		(width 0.088646)
		(layer "In11.Cu")
		(net "M_D_CPU0_SB_DQ<6>")
	)
	(arc
		(start 338.621878 -238.549942)
		(mid 338.43468 -238.600085)
		(end 338.247482 -238.549942)
		(width 0.088646)
		(layer "In11.Cu")
		(net "M_D_CPU0_SB_DQ<6>")
	)
	(arc
		(start 345.755722 -238.543846)
		(mid 345.47729 -238.474)
		(end 345.200478 -238.549942)
		(width 0.088646)
		(layer "In11.Cu")
		(net "M_D_CPU0_SB_DQ<6>")
	)
	(arc
		(start 336.838036 -237.735872)
		(mid 336.563807 -237.659947)
		(end 336.287364 -237.727236)
		(width 0.088646)
		(layer "In11.Cu")
		(net "M_D_CPU0_SB_DQ<6>")
	)
	(arc
		(start 342.946482 -238.549942)
		(mid 342.66378 -238.474166)
		(end 342.381078 -238.549942)
		(width 0.088646)
		(layer "In11.Cu")
		(net "M_D_CPU0_SB_DQ<6>")
	)
	(arc
		(start 338.23275 -238.541306)
		(mid 337.956275 -238.473986)
		(end 337.682078 -238.549942)
		(width 0.088646)
		(layer "In11.Cu")
		(net "M_D_CPU0_SB_DQ<6>")
	)
	(arc
		(start 336.272632 -237.735872)
		(mid 336.085434 -237.786015)
		(end 335.898236 -237.735872)
		(width 0.088646)
		(layer "In11.Cu")
		(net "M_D_CPU0_SB_DQ<6>")
	)
	(arc
		(start 342.381078 -238.549942)
		(mid 342.19388 -238.600085)
		(end 342.006682 -238.549942)
		(width 0.088646)
		(layer "In11.Cu")
		(net "M_D_CPU0_SB_DQ<6>")
	)
	(arc
		(start 340.501478 -238.549942)
		(mid 340.31428 -238.600085)
		(end 340.127082 -238.549942)
		(width 0.088646)
		(layer "In11.Cu")
		(net "M_D_CPU0_SB_DQ<6>")
	)
	(segment
		(start 263.624314 -224.516696)
		(end 261.984998 -224.516696)
		(width 0.20066)
		(layer "F.Cu")
		(net "M_D_CPU0_SB_DQ<5>")
	)
	(segment
		(start 261.560056 -224.091754)
		(end 261.381494 -224.091754)
		(width 0.20066)
		(layer "F.Cu")
		(net "M_D_CPU0_SB_DQ<5>")
	)
	(segment
		(start 259.056378 -224.082864)
		(end 258.44754 -224.082864)
		(width 0.20066)
		(layer "F.Cu")
		(net "M_D_CPU0_SB_DQ<5>")
	)
	(segment
		(start 257.626104 -224.728024)
		(end 257.414776 -224.516696)
		(width 0.20066)
		(layer "F.Cu")
		(net "M_D_CPU0_SB_DQ<5>")
	)
	(segment
		(start 261.984998 -224.516696)
		(end 261.560056 -224.091754)
		(width 0.20066)
		(layer "F.Cu")
		(net "M_D_CPU0_SB_DQ<5>")
	)
	(segment
		(start 346.89288 -238.76127)
		(end 346.89288 -238.225584)
		(width 0.20066)
		(layer "F.Cu")
		(net "M_D_CPU0_SB_DQ<5>")
	)
	(segment
		(start 346.893134 -238.761524)
		(end 346.89288 -238.76127)
		(width 0.20066)
		(layer "F.Cu")
		(net "M_D_CPU0_SB_DQ<5>")
	)
	(segment
		(start 258.44754 -224.082864)
		(end 258.28498 -224.245424)
		(width 0.20066)
		(layer "F.Cu")
		(net "M_D_CPU0_SB_DQ<5>")
	)
	(segment
		(start 264.729214 -224.516696)
		(end 263.624314 -224.516696)
		(width 0.20066)
		(layer "F.Cu")
		(net "M_D_CPU0_SB_DQ<5>")
	)
	(segment
		(start 259.065268 -224.091754)
		(end 259.056378 -224.082864)
		(width 0.1016)
		(layer "F.Cu")
		(net "M_D_CPU0_SB_DQ<5>")
	)
	(segment
		(start 261.050786 -224.091754)
		(end 259.065268 -224.091754)
		(width 0.1016)
		(layer "F.Cu")
		(net "M_D_CPU0_SB_DQ<5>")
	)
	(segment
		(start 258.28498 -224.245424)
		(end 258.28498 -224.573592)
		(width 0.20066)
		(layer "F.Cu")
		(net "M_D_CPU0_SB_DQ<5>")
	)
	(segment
		(start 258.130548 -224.728024)
		(end 257.626104 -224.728024)
		(width 0.20066)
		(layer "F.Cu")
		(net "M_D_CPU0_SB_DQ<5>")
	)
	(segment
		(start 261.381494 -224.091754)
		(end 261.050786 -224.091754)
		(width 0.101854)
		(layer "F.Cu")
		(net "M_D_CPU0_SB_DQ<5>")
	)
	(segment
		(start 257.414776 -224.516696)
		(end 256.080514 -224.516696)
		(width 0.20066)
		(layer "F.Cu")
		(net "M_D_CPU0_SB_DQ<5>")
	)
	(segment
		(start 258.28498 -224.573592)
		(end 258.130548 -224.728024)
		(width 0.20066)
		(layer "F.Cu")
		(net "M_D_CPU0_SB_DQ<5>")
	)
	(segment
		(start 314.323984 -223.241108)
		(end 313.624976 -223.241108)
		(width 0.18288)
		(layer "In11.Cu")
		(net "M_D_CPU0_SB_DQ<5>")
	)
	(segment
		(start 269.221712 -224.9424)
		(end 267.985494 -224.9424)
		(width 0.18288)
		(layer "In11.Cu")
		(net "M_D_CPU0_SB_DQ<5>")
	)
	(segment
		(start 338.247482 -237.901226)
		(end 338.23275 -237.909862)
		(width 0.088646)
		(layer "In11.Cu")
		(net "M_D_CPU0_SB_DQ<5>")
	)
	(segment
		(start 342.946482 -237.901226)
		(end 342.93175 -237.909862)
		(width 0.088646)
		(layer "In11.Cu")
		(net "M_D_CPU0_SB_DQ<5>")
	)
	(segment
		(start 279.533604 -220.690948)
		(end 277.996396 -221.391226)
		(width 0.18288)
		(layer "In11.Cu")
		(net "M_D_CPU0_SB_DQ<5>")
	)
	(segment
		(start 297.448732 -219.842334)
		(end 297.27144 -220.019626)
		(width 0.18288)
		(layer "In11.Cu")
		(net "M_D_CPU0_SB_DQ<5>")
	)
	(segment
		(start 273.725894 -223.880426)
		(end 272.836894 -224.769426)
		(width 0.18288)
		(layer "In11.Cu")
		(net "M_D_CPU0_SB_DQ<5>")
	)
	(segment
		(start 284.317694 -219.842334)
		(end 282.510992 -219.842334)
		(width 0.18288)
		(layer "In11.Cu")
		(net "M_D_CPU0_SB_DQ<5>")
	)
	(segment
		(start 282.510992 -219.842334)
		(end 282.082748 -219.943426)
		(width 0.18288)
		(layer "In11.Cu")
		(net "M_D_CPU0_SB_DQ<5>")
	)
	(segment
		(start 330.548234 -234.755944)
		(end 330.313538 -234.755944)
		(width 0.088646)
		(layer "In11.Cu")
		(net "M_D_CPU0_SB_DQ<5>")
	)
	(segment
		(start 342.006682 -237.901226)
		(end 341.99195 -237.909862)
		(width 0.088646)
		(layer "In11.Cu")
		(net "M_D_CPU0_SB_DQ<5>")
	)
	(segment
		(start 303.179734 -219.765626)
		(end 299.679106 -219.765626)
		(width 0.18288)
		(layer "In11.Cu")
		(net "M_D_CPU0_SB_DQ<5>")
	)
	(segment
		(start 332.326234 -236.349286)
		(end 331.559662 -236.349286)
		(width 0.088646)
		(layer "In11.Cu")
		(net "M_D_CPU0_SB_DQ<5>")
	)
	(segment
		(start 337.399884 -237.433612)
		(end 337.399884 -237.411514)
		(width 0.088646)
		(layer "In11.Cu")
		(net "M_D_CPU0_SB_DQ<5>")
	)
	(segment
		(start 267.985494 -224.9424)
		(end 267.46454 -225.463354)
		(width 0.18288)
		(layer "In11.Cu")
		(net "M_D_CPU0_SB_DQ<5>")
	)
	(segment
		(start 312.994294 -222.610426)
		(end 312.310526 -222.356426)
		(width 0.18288)
		(layer "In11.Cu")
		(net "M_D_CPU0_SB_DQ<5>")
	)
	(segment
		(start 306.395882 -220.502226)
		(end 303.916334 -220.502226)
		(width 0.18288)
		(layer "In11.Cu")
		(net "M_D_CPU0_SB_DQ<5>")
	)
	(segment
		(start 280.407618 -220.690948)
		(end 279.533604 -220.690948)
		(width 0.18288)
		(layer "In11.Cu")
		(net "M_D_CPU0_SB_DQ<5>")
	)
	(segment
		(start 337.226656 -237.095538)
		(end 337.212432 -237.08741)
		(width 0.088646)
		(layer "In11.Cu")
		(net "M_D_CPU0_SB_DQ<5>")
	)
	(segment
		(start 303.916334 -220.502226)
		(end 303.179734 -219.765626)
		(width 0.18288)
		(layer "In11.Cu")
		(net "M_D_CPU0_SB_DQ<5>")
	)
	(segment
		(start 331.559662 -236.349286)
		(end 330.748132 -235.537756)
		(width 0.088646)
		(layer "In11.Cu")
		(net "M_D_CPU0_SB_DQ<5>")
	)
	(segment
		(start 310.555894 -221.467426)
		(end 308.828694 -221.467426)
		(width 0.18288)
		(layer "In11.Cu")
		(net "M_D_CPU0_SB_DQ<5>")
	)
	(segment
		(start 285.003494 -219.740226)
		(end 284.317694 -219.842334)
		(width 0.18288)
		(layer "In11.Cu")
		(net "M_D_CPU0_SB_DQ<5>")
	)
	(segment
		(start 277.542498 -221.391226)
		(end 276.628098 -222.305626)
		(width 0.18288)
		(layer "In11.Cu")
		(net "M_D_CPU0_SB_DQ<5>")
	)
	(segment
		(start 308.379114 -221.017846)
		(end 306.395882 -220.502226)
		(width 0.18288)
		(layer "In11.Cu")
		(net "M_D_CPU0_SB_DQ<5>")
	)
	(segment
		(start 330.313538 -234.755944)
		(end 325.83882 -234.755944)
		(width 0.18288)
		(layer "In11.Cu")
		(net "M_D_CPU0_SB_DQ<5>")
	)
	(segment
		(start 265.675872 -225.463354)
		(end 264.729214 -224.516696)
		(width 0.18288)
		(layer "In11.Cu")
		(net "M_D_CPU0_SB_DQ<5>")
	)
	(segment
		(start 347.088968 -237.906306)
		(end 347.080078 -237.901226)
		(width 0.088646)
		(layer "In11.Cu")
		(net "M_D_CPU0_SB_DQ<5>")
	)
	(segment
		(start 290.870894 -220.121226)
		(end 289.245294 -220.121226)
		(width 0.18288)
		(layer "In11.Cu")
		(net "M_D_CPU0_SB_DQ<5>")
	)
	(segment
		(start 339.572346 -237.907322)
		(end 339.561932 -237.901226)
		(width 0.088646)
		(layer "In11.Cu")
		(net "M_D_CPU0_SB_DQ<5>")
	)
	(segment
		(start 308.828694 -221.467426)
		(end 308.379114 -221.017846)
		(width 0.18288)
		(layer "In11.Cu")
		(net "M_D_CPU0_SB_DQ<5>")
	)
	(segment
		(start 336.92973 -236.597952)
		(end 336.92973 -236.589316)
		(width 0.088646)
		(layer "In11.Cu")
		(net "M_D_CPU0_SB_DQ<5>")
	)
	(segment
		(start 325.83882 -234.755944)
		(end 314.323984 -223.241108)
		(width 0.18288)
		(layer "In11.Cu")
		(net "M_D_CPU0_SB_DQ<5>")
	)
	(segment
		(start 313.624976 -223.241108)
		(end 312.994294 -222.610426)
		(width 0.18288)
		(layer "In11.Cu")
		(net "M_D_CPU0_SB_DQ<5>")
	)
	(segment
		(start 276.068282 -222.305626)
		(end 274.493482 -223.880426)
		(width 0.18288)
		(layer "In11.Cu")
		(net "M_D_CPU0_SB_DQ<5>")
	)
	(segment
		(start 346.150946 -237.907322)
		(end 346.140532 -237.901226)
		(width 0.088646)
		(layer "In11.Cu")
		(net "M_D_CPU0_SB_DQ<5>")
	)
	(segment
		(start 299.532294 -219.842334)
		(end 297.448732 -219.842334)
		(width 0.18288)
		(layer "In11.Cu")
		(net "M_D_CPU0_SB_DQ<5>")
	)
	(segment
		(start 281.15514 -219.943426)
		(end 280.407618 -220.690948)
		(width 0.18288)
		(layer "In11.Cu")
		(net "M_D_CPU0_SB_DQ<5>")
	)
	(segment
		(start 299.679106 -219.765626)
		(end 299.532294 -219.842334)
		(width 0.18288)
		(layer "In11.Cu")
		(net "M_D_CPU0_SB_DQ<5>")
	)
	(segment
		(start 311.444894 -222.356426)
		(end 310.555894 -221.467426)
		(width 0.18288)
		(layer "In11.Cu")
		(net "M_D_CPU0_SB_DQ<5>")
	)
	(segment
		(start 295.619678 -220.693488)
		(end 292.110668 -220.693488)
		(width 0.18288)
		(layer "In11.Cu")
		(net "M_D_CPU0_SB_DQ<5>")
	)
	(segment
		(start 330.748132 -235.537756)
		(end 330.748132 -234.955842)
		(width 0.088646)
		(layer "In11.Cu")
		(net "M_D_CPU0_SB_DQ<5>")
	)
	(segment
		(start 343.886282 -237.901226)
		(end 343.87155 -237.909862)
		(width 0.088646)
		(layer "In11.Cu")
		(net "M_D_CPU0_SB_DQ<5>")
	)
	(segment
		(start 312.310526 -222.356426)
		(end 311.444894 -222.356426)
		(width 0.18288)
		(layer "In11.Cu")
		(net "M_D_CPU0_SB_DQ<5>")
	)
	(segment
		(start 269.827248 -224.769426)
		(end 269.221712 -224.9424)
		(width 0.18288)
		(layer "In11.Cu")
		(net "M_D_CPU0_SB_DQ<5>")
	)
	(segment
		(start 347.205554 -238.225584)
		(end 347.262958 -238.16818)
		(width 0.088646)
		(layer "In11.Cu")
		(net "M_D_CPU0_SB_DQ<5>")
	)
	(segment
		(start 277.996396 -221.391226)
		(end 277.542498 -221.391226)
		(width 0.18288)
		(layer "In11.Cu")
		(net "M_D_CPU0_SB_DQ<5>")
	)
	(segment
		(start 339.187536 -237.901226)
		(end 339.177122 -237.907322)
		(width 0.088646)
		(layer "In11.Cu")
		(net "M_D_CPU0_SB_DQ<5>")
	)
	(segment
		(start 282.082748 -219.943426)
		(end 281.15514 -219.943426)
		(width 0.18288)
		(layer "In11.Cu")
		(net "M_D_CPU0_SB_DQ<5>")
	)
	(segment
		(start 337.212432 -237.08741)
		(end 337.206336 -237.083854)
		(width 0.088646)
		(layer "In11.Cu")
		(net "M_D_CPU0_SB_DQ<5>")
	)
	(segment
		(start 345.766136 -237.901226)
		(end 345.755722 -237.907322)
		(width 0.088646)
		(layer "In11.Cu")
		(net "M_D_CPU0_SB_DQ<5>")
	)
	(segment
		(start 267.46454 -225.463354)
		(end 265.675872 -225.463354)
		(width 0.18288)
		(layer "In11.Cu")
		(net "M_D_CPU0_SB_DQ<5>")
	)
	(segment
		(start 296.29354 -220.019626)
		(end 295.619678 -220.693488)
		(width 0.18288)
		(layer "In11.Cu")
		(net "M_D_CPU0_SB_DQ<5>")
	)
	(segment
		(start 274.493482 -223.880426)
		(end 273.725894 -223.880426)
		(width 0.18288)
		(layer "In11.Cu")
		(net "M_D_CPU0_SB_DQ<5>")
	)
	(segment
		(start 344.826082 -237.901226)
		(end 344.81135 -237.909862)
		(width 0.088646)
		(layer "In11.Cu")
		(net "M_D_CPU0_SB_DQ<5>")
	)
	(segment
		(start 272.836894 -224.769426)
		(end 269.827248 -224.769426)
		(width 0.18288)
		(layer "In11.Cu")
		(net "M_D_CPU0_SB_DQ<5>")
	)
	(segment
		(start 289.245294 -220.121226)
		(end 287.695894 -219.740226)
		(width 0.18288)
		(layer "In11.Cu")
		(net "M_D_CPU0_SB_DQ<5>")
	)
	(segment
		(start 287.695894 -219.740226)
		(end 285.003494 -219.740226)
		(width 0.18288)
		(layer "In11.Cu")
		(net "M_D_CPU0_SB_DQ<5>")
	)
	(segment
		(start 341.066882 -237.901226)
		(end 341.05215 -237.909862)
		(width 0.088646)
		(layer "In11.Cu")
		(net "M_D_CPU0_SB_DQ<5>")
	)
	(segment
		(start 297.27144 -220.019626)
		(end 296.29354 -220.019626)
		(width 0.18288)
		(layer "In11.Cu")
		(net "M_D_CPU0_SB_DQ<5>")
	)
	(segment
		(start 276.628098 -222.305626)
		(end 276.068282 -222.305626)
		(width 0.18288)
		(layer "In11.Cu")
		(net "M_D_CPU0_SB_DQ<5>")
	)
	(segment
		(start 292.110668 -220.693488)
		(end 290.870894 -220.121226)
		(width 0.18288)
		(layer "In11.Cu")
		(net "M_D_CPU0_SB_DQ<5>")
	)
	(segment
		(start 346.89288 -238.225584)
		(end 347.205554 -238.225584)
		(width 0.088646)
		(layer "In11.Cu")
		(net "M_D_CPU0_SB_DQ<5>")
	)
	(segment
		(start 330.748132 -234.955842)
		(end 330.548234 -234.755944)
		(width 0.088646)
		(layer "In11.Cu")
		(net "M_D_CPU0_SB_DQ<5>")
	)
	(arc
		(start 344.81135 -237.909862)
		(mid 344.534875 -237.977182)
		(end 344.260678 -237.901226)
		(width 0.088646)
		(layer "In11.Cu")
		(net "M_D_CPU0_SB_DQ<5>")
	)
	(arc
		(start 340.127082 -237.901226)
		(mid 339.850523 -237.976935)
		(end 339.572346 -237.907322)
		(width 0.088646)
		(layer "In11.Cu")
		(net "M_D_CPU0_SB_DQ<5>")
	)
	(arc
		(start 335.428336 -236.273594)
		(mid 335.145634 -236.349336)
		(end 334.862932 -236.273594)
		(width 0.088646)
		(layer "In11.Cu")
		(net "M_D_CPU0_SB_DQ<5>")
	)
	(arc
		(start 336.92973 -236.589316)
		(mid 336.87746 -236.406951)
		(end 336.742532 -236.273594)
		(width 0.088646)
		(layer "In11.Cu")
		(net "M_D_CPU0_SB_DQ<5>")
	)
	(arc
		(start 338.621878 -237.901226)
		(mid 338.43468 -237.851083)
		(end 338.247482 -237.901226)
		(width 0.088646)
		(layer "In11.Cu")
		(net "M_D_CPU0_SB_DQ<5>")
	)
	(arc
		(start 345.755722 -237.907322)
		(mid 345.47729 -237.977168)
		(end 345.200478 -237.901226)
		(width 0.088646)
		(layer "In11.Cu")
		(net "M_D_CPU0_SB_DQ<5>")
	)
	(arc
		(start 339.561932 -237.901226)
		(mid 339.374734 -237.851083)
		(end 339.187536 -237.901226)
		(width 0.088646)
		(layer "In11.Cu")
		(net "M_D_CPU0_SB_DQ<5>")
	)
	(arc
		(start 346.705682 -237.901226)
		(mid 346.429123 -237.976969)
		(end 346.150946 -237.907322)
		(width 0.088646)
		(layer "In11.Cu")
		(net "M_D_CPU0_SB_DQ<5>")
	)
	(arc
		(start 347.080078 -237.901226)
		(mid 346.89288 -237.851083)
		(end 346.705682 -237.901226)
		(width 0.088646)
		(layer "In11.Cu")
		(net "M_D_CPU0_SB_DQ<5>")
	)
	(arc
		(start 338.23275 -237.909862)
		(mid 337.956309 -237.977028)
		(end 337.682078 -237.901226)
		(width 0.088646)
		(layer "In11.Cu")
		(net "M_D_CPU0_SB_DQ<5>")
	)
	(arc
		(start 343.320878 -237.901226)
		(mid 343.13368 -237.851083)
		(end 342.946482 -237.901226)
		(width 0.088646)
		(layer "In11.Cu")
		(net "M_D_CPU0_SB_DQ<5>")
	)
	(arc
		(start 341.99195 -237.909862)
		(mid 341.715475 -237.977182)
		(end 341.441278 -237.901226)
		(width 0.088646)
		(layer "In11.Cu")
		(net "M_D_CPU0_SB_DQ<5>")
	)
	(arc
		(start 333.923132 -236.273594)
		(mid 333.735934 -236.223451)
		(end 333.548736 -236.273594)
		(width 0.088646)
		(layer "In11.Cu")
		(net "M_D_CPU0_SB_DQ<5>")
	)
	(arc
		(start 336.742532 -236.273594)
		(mid 336.555334 -236.223451)
		(end 336.368136 -236.273594)
		(width 0.088646)
		(layer "In11.Cu")
		(net "M_D_CPU0_SB_DQ<5>")
	)
	(arc
		(start 332.608936 -236.273594)
		(mid 332.47257 -236.330072)
		(end 332.326234 -236.349286)
		(width 0.088646)
		(layer "In11.Cu")
		(net "M_D_CPU0_SB_DQ<5>")
	)
	(arc
		(start 337.682078 -237.901226)
		(mid 337.480796 -237.703739)
		(end 337.399884 -237.433612)
		(width 0.088646)
		(layer "In11.Cu")
		(net "M_D_CPU0_SB_DQ<5>")
	)
	(arc
		(start 334.862932 -236.273594)
		(mid 334.675734 -236.223451)
		(end 334.488536 -236.273594)
		(width 0.088646)
		(layer "In11.Cu")
		(net "M_D_CPU0_SB_DQ<5>")
	)
	(arc
		(start 346.140532 -237.901226)
		(mid 345.953334 -237.851083)
		(end 345.766136 -237.901226)
		(width 0.088646)
		(layer "In11.Cu")
		(net "M_D_CPU0_SB_DQ<5>")
	)
	(arc
		(start 335.802732 -236.273594)
		(mid 335.615534 -236.223451)
		(end 335.428336 -236.273594)
		(width 0.088646)
		(layer "In11.Cu")
		(net "M_D_CPU0_SB_DQ<5>")
	)
	(arc
		(start 341.05215 -237.909862)
		(mid 340.775709 -237.977028)
		(end 340.501478 -237.901226)
		(width 0.088646)
		(layer "In11.Cu")
		(net "M_D_CPU0_SB_DQ<5>")
	)
	(arc
		(start 341.441278 -237.901226)
		(mid 341.25408 -237.851083)
		(end 341.066882 -237.901226)
		(width 0.088646)
		(layer "In11.Cu")
		(net "M_D_CPU0_SB_DQ<5>")
	)
	(arc
		(start 345.200478 -237.901226)
		(mid 345.01328 -237.851083)
		(end 344.826082 -237.901226)
		(width 0.088646)
		(layer "In11.Cu")
		(net "M_D_CPU0_SB_DQ<5>")
	)
	(arc
		(start 344.260678 -237.901226)
		(mid 344.07348 -237.851083)
		(end 343.886282 -237.901226)
		(width 0.088646)
		(layer "In11.Cu")
		(net "M_D_CPU0_SB_DQ<5>")
	)
	(arc
		(start 339.177122 -237.907322)
		(mid 338.89869 -237.977136)
		(end 338.621878 -237.901226)
		(width 0.088646)
		(layer "In11.Cu")
		(net "M_D_CPU0_SB_DQ<5>")
	)
	(arc
		(start 342.381078 -237.901226)
		(mid 342.19388 -237.851083)
		(end 342.006682 -237.901226)
		(width 0.088646)
		(layer "In11.Cu")
		(net "M_D_CPU0_SB_DQ<5>")
	)
	(arc
		(start 336.368136 -236.273594)
		(mid 336.085434 -236.349336)
		(end 335.802732 -236.273594)
		(width 0.088646)
		(layer "In11.Cu")
		(net "M_D_CPU0_SB_DQ<5>")
	)
	(arc
		(start 343.87155 -237.909862)
		(mid 343.595075 -237.977182)
		(end 343.320878 -237.901226)
		(width 0.088646)
		(layer "In11.Cu")
		(net "M_D_CPU0_SB_DQ<5>")
	)
	(arc
		(start 334.488536 -236.273594)
		(mid 334.205834 -236.349336)
		(end 333.923132 -236.273594)
		(width 0.088646)
		(layer "In11.Cu")
		(net "M_D_CPU0_SB_DQ<5>")
	)
	(arc
		(start 332.983332 -236.273594)
		(mid 332.796134 -236.223451)
		(end 332.608936 -236.273594)
		(width 0.088646)
		(layer "In11.Cu")
		(net "M_D_CPU0_SB_DQ<5>")
	)
	(arc
		(start 337.399884 -237.411514)
		(mid 337.353745 -237.231329)
		(end 337.226656 -237.095538)
		(width 0.088646)
		(layer "In11.Cu")
		(net "M_D_CPU0_SB_DQ<5>")
	)
	(arc
		(start 347.262958 -238.16818)
		(mid 347.204802 -238.018067)
		(end 347.088968 -237.906306)
		(width 0.088646)
		(layer "In11.Cu")
		(net "M_D_CPU0_SB_DQ<5>")
	)
	(arc
		(start 337.206336 -237.083854)
		(mid 337.003749 -236.877503)
		(end 336.92973 -236.597952)
		(width 0.088646)
		(layer "In11.Cu")
		(net "M_D_CPU0_SB_DQ<5>")
	)
	(arc
		(start 340.501478 -237.901226)
		(mid 340.31428 -237.851083)
		(end 340.127082 -237.901226)
		(width 0.088646)
		(layer "In11.Cu")
		(net "M_D_CPU0_SB_DQ<5>")
	)
	(arc
		(start 333.548736 -236.273594)
		(mid 333.266034 -236.349336)
		(end 332.983332 -236.273594)
		(width 0.088646)
		(layer "In11.Cu")
		(net "M_D_CPU0_SB_DQ<5>")
	)
	(arc
		(start 342.93175 -237.909862)
		(mid 342.655275 -237.977182)
		(end 342.381078 -237.901226)
		(width 0.088646)
		(layer "In11.Cu")
		(net "M_D_CPU0_SB_DQ<5>")
	)
	(segment
		(start 346.423234 -239.575086)
		(end 346.423234 -239.0394)
		(width 0.20066)
		(layer "F.Cu")
		(net "M_D_CPU0_SB_DQ<4>")
	)
	(segment
		(start 259.056378 -225.783648)
		(end 258.49453 -225.783648)
		(width 0.20066)
		(layer "F.Cu")
		(net "M_D_CPU0_SB_DQ<4>")
	)
	(segment
		(start 261.830312 -225.791776)
		(end 261.381494 -225.791776)
		(width 0.20066)
		(layer "F.Cu")
		(net "M_D_CPU0_SB_DQ<4>")
	)
	(segment
		(start 264.729214 -226.216718)
		(end 263.624314 -226.216718)
		(width 0.20066)
		(layer "F.Cu")
		(net "M_D_CPU0_SB_DQ<4>")
	)
	(segment
		(start 257.653536 -226.455478)
		(end 257.414776 -226.216718)
		(width 0.20066)
		(layer "F.Cu")
		(net "M_D_CPU0_SB_DQ<4>")
	)
	(segment
		(start 258.28498 -225.993198)
		(end 258.28498 -226.282758)
		(width 0.20066)
		(layer "F.Cu")
		(net "M_D_CPU0_SB_DQ<4>")
	)
	(segment
		(start 258.28498 -226.282758)
		(end 258.11226 -226.455478)
		(width 0.20066)
		(layer "F.Cu")
		(net "M_D_CPU0_SB_DQ<4>")
	)
	(segment
		(start 262.255254 -226.216718)
		(end 261.830312 -225.791776)
		(width 0.20066)
		(layer "F.Cu")
		(net "M_D_CPU0_SB_DQ<4>")
	)
	(segment
		(start 259.064506 -225.791776)
		(end 259.056378 -225.783648)
		(width 0.101854)
		(layer "F.Cu")
		(net "M_D_CPU0_SB_DQ<4>")
	)
	(segment
		(start 257.414776 -226.216718)
		(end 256.080514 -226.216718)
		(width 0.20066)
		(layer "F.Cu")
		(net "M_D_CPU0_SB_DQ<4>")
	)
	(segment
		(start 263.624314 -226.216718)
		(end 262.255254 -226.216718)
		(width 0.20066)
		(layer "F.Cu")
		(net "M_D_CPU0_SB_DQ<4>")
	)
	(segment
		(start 258.11226 -226.455478)
		(end 257.653536 -226.455478)
		(width 0.20066)
		(layer "F.Cu")
		(net "M_D_CPU0_SB_DQ<4>")
	)
	(segment
		(start 259.31241 -225.791776)
		(end 259.064506 -225.791776)
		(width 0.101854)
		(layer "F.Cu")
		(net "M_D_CPU0_SB_DQ<4>")
	)
	(segment
		(start 261.381494 -225.791776)
		(end 259.31241 -225.791776)
		(width 0.1016)
		(layer "F.Cu")
		(net "M_D_CPU0_SB_DQ<4>")
	)
	(segment
		(start 346.42298 -239.57534)
		(end 346.423234 -239.575086)
		(width 0.20066)
		(layer "F.Cu")
		(net "M_D_CPU0_SB_DQ<4>")
	)
	(segment
		(start 258.49453 -225.783648)
		(end 258.28498 -225.993198)
		(width 0.20066)
		(layer "F.Cu")
		(net "M_D_CPU0_SB_DQ<4>")
	)
	(segment
		(start 299.923962 -221.542356)
		(end 297.704764 -221.542356)
		(width 0.18288)
		(layer "In11.Cu")
		(net "M_D_CPU0_SB_DQ<4>")
	)
	(segment
		(start 300.049692 -221.416626)
		(end 299.923962 -221.542356)
		(width 0.18288)
		(layer "In11.Cu")
		(net "M_D_CPU0_SB_DQ<4>")
	)
	(segment
		(start 300.836584 -221.416626)
		(end 300.049692 -221.416626)
		(width 0.18288)
		(layer "In11.Cu")
		(net "M_D_CPU0_SB_DQ<4>")
	)
	(segment
		(start 296.266362 -221.950026)
		(end 295.823894 -222.392494)
		(width 0.18288)
		(layer "In11.Cu")
		(net "M_D_CPU0_SB_DQ<4>")
	)
	(segment
		(start 267.848588 -226.804728)
		(end 265.317224 -226.804728)
		(width 0.18288)
		(layer "In11.Cu")
		(net "M_D_CPU0_SB_DQ<4>")
	)
	(segment
		(start 340.046564 -238.723678)
		(end 340.031832 -238.715042)
		(width 0.088646)
		(layer "In11.Cu")
		(net "M_D_CPU0_SB_DQ<4>")
	)
	(segment
		(start 306.872894 -222.305626)
		(end 303.741074 -222.305626)
		(width 0.18288)
		(layer "In11.Cu")
		(net "M_D_CPU0_SB_DQ<4>")
	)
	(segment
		(start 335.341468 -237.09249)
		(end 335.332578 -237.08741)
		(width 0.088646)
		(layer "In11.Cu")
		(net "M_D_CPU0_SB_DQ<4>")
	)
	(segment
		(start 277.459694 -223.143826)
		(end 276.603714 -223.999806)
		(width 0.18288)
		(layer "In11.Cu")
		(net "M_D_CPU0_SB_DQ<4>")
	)
	(segment
		(start 280.736294 -222.392494)
		(end 278.882094 -222.392494)
		(width 0.18288)
		(layer "In11.Cu")
		(net "M_D_CPU0_SB_DQ<4>")
	)
	(segment
		(start 336.751168 -237.906306)
		(end 336.742278 -237.901226)
		(width 0.088646)
		(layer "In11.Cu")
		(net "M_D_CPU0_SB_DQ<4>")
	)
	(segment
		(start 310.505094 -223.118426)
		(end 307.685694 -223.118426)
		(width 0.18288)
		(layer "In11.Cu")
		(net "M_D_CPU0_SB_DQ<4>")
	)
	(segment
		(start 265.317224 -226.804728)
		(end 264.729214 -226.216718)
		(width 0.18288)
		(layer "In11.Cu")
		(net "M_D_CPU0_SB_DQ<4>")
	)
	(segment
		(start 269.287498 -226.642422)
		(end 268.010894 -226.642422)
		(width 0.18288)
		(layer "In11.Cu")
		(net "M_D_CPU0_SB_DQ<4>")
	)
	(segment
		(start 331.691488 -237.03661)
		(end 330.426822 -235.771944)
		(width 0.088646)
		(layer "In11.Cu")
		(net "M_D_CPU0_SB_DQ<4>")
	)
	(segment
		(start 333.078582 -237.08741)
		(end 333.06385 -237.096046)
		(width 0.088646)
		(layer "In11.Cu")
		(net "M_D_CPU0_SB_DQ<4>")
	)
	(segment
		(start 302.852074 -221.416626)
		(end 301.923704 -221.416626)
		(width 0.18288)
		(layer "In11.Cu")
		(net "M_D_CPU0_SB_DQ<4>")
	)
	(segment
		(start 334.958182 -237.08741)
		(end 334.947768 -237.093506)
		(width 0.088646)
		(layer "In11.Cu")
		(net "M_D_CPU0_SB_DQ<4>")
	)
	(segment
		(start 274.640294 -225.633026)
		(end 274.005294 -225.633026)
		(width 0.18288)
		(layer "In11.Cu")
		(net "M_D_CPU0_SB_DQ<4>")
	)
	(segment
		(start 301.537624 -222.115888)
		(end 301.222664 -222.115888)
		(width 0.18288)
		(layer "In11.Cu")
		(net "M_D_CPU0_SB_DQ<4>")
	)
	(segment
		(start 269.424658 -226.505262)
		(end 269.287498 -226.642422)
		(width 0.18288)
		(layer "In11.Cu")
		(net "M_D_CPU0_SB_DQ<4>")
	)
	(segment
		(start 334.018636 -237.08741)
		(end 334.008222 -237.093506)
		(width 0.088646)
		(layer "In11.Cu")
		(net "M_D_CPU0_SB_DQ<4>")
	)
	(segment
		(start 341.921846 -238.721138)
		(end 341.911432 -238.715042)
		(width 0.088646)
		(layer "In11.Cu")
		(net "M_D_CPU0_SB_DQ<4>")
	)
	(segment
		(start 289.194494 -222.204026)
		(end 288.529776 -221.539308)
		(width 0.18288)
		(layer "In11.Cu")
		(net "M_D_CPU0_SB_DQ<4>")
	)
	(segment
		(start 297.297094 -221.950026)
		(end 296.266362 -221.950026)
		(width 0.18288)
		(layer "In11.Cu")
		(net "M_D_CPU0_SB_DQ<4>")
	)
	(segment
		(start 335.520284 -237.419388)
		(end 335.52003 -237.411768)
		(width 0.088646)
		(layer "In11.Cu")
		(net "M_D_CPU0_SB_DQ<4>")
	)
	(segment
		(start 288.529776 -221.539308)
		(end 282.467812 -221.539308)
		(width 0.18288)
		(layer "In11.Cu")
		(net "M_D_CPU0_SB_DQ<4>")
	)
	(segment
		(start 330.313538 -235.771944)
		(end 325.326756 -235.771944)
		(width 0.18288)
		(layer "In11.Cu")
		(net "M_D_CPU0_SB_DQ<4>")
	)
	(segment
		(start 301.730664 -221.609666)
		(end 301.730664 -221.922848)
		(width 0.18288)
		(layer "In11.Cu")
		(net "M_D_CPU0_SB_DQ<4>")
	)
	(segment
		(start 281.127962 -222.000826)
		(end 280.736294 -222.392494)
		(width 0.18288)
		(layer "In11.Cu")
		(net "M_D_CPU0_SB_DQ<4>")
	)
	(segment
		(start 313.524646 -224.944178)
		(end 312.486294 -223.905826)
		(width 0.18288)
		(layer "In11.Cu")
		(net "M_D_CPU0_SB_DQ<4>")
	)
	(segment
		(start 301.730664 -221.922848)
		(end 301.537624 -222.115888)
		(width 0.18288)
		(layer "In11.Cu")
		(net "M_D_CPU0_SB_DQ<4>")
	)
	(segment
		(start 311.292494 -223.905826)
		(end 310.505094 -223.118426)
		(width 0.18288)
		(layer "In11.Cu")
		(net "M_D_CPU0_SB_DQ<4>")
	)
	(segment
		(start 301.222664 -222.115888)
		(end 301.029624 -221.922848)
		(width 0.18288)
		(layer "In11.Cu")
		(net "M_D_CPU0_SB_DQ<4>")
	)
	(segment
		(start 292.115494 -222.204026)
		(end 289.194494 -222.204026)
		(width 0.18288)
		(layer "In11.Cu")
		(net "M_D_CPU0_SB_DQ<4>")
	)
	(segment
		(start 301.029624 -221.609666)
		(end 300.836584 -221.416626)
		(width 0.18288)
		(layer "In11.Cu")
		(net "M_D_CPU0_SB_DQ<4>")
	)
	(segment
		(start 325.326756 -235.771944)
		(end 314.500006 -224.944178)
		(width 0.18288)
		(layer "In11.Cu")
		(net "M_D_CPU0_SB_DQ<4>")
	)
	(segment
		(start 332.32598 -237.03661)
		(end 331.691488 -237.03661)
		(width 0.088646)
		(layer "In11.Cu")
		(net "M_D_CPU0_SB_DQ<4>")
	)
	(segment
		(start 338.166964 -238.723678)
		(end 338.152232 -238.715042)
		(width 0.088646)
		(layer "In11.Cu")
		(net "M_D_CPU0_SB_DQ<4>")
	)
	(segment
		(start 268.010894 -226.642422)
		(end 267.848588 -226.804728)
		(width 0.18288)
		(layer "In11.Cu")
		(net "M_D_CPU0_SB_DQ<4>")
	)
	(segment
		(start 346.423234 -239.0394)
		(end 346.389452 -239.005618)
		(width 0.088646)
		(layer "In11.Cu")
		(net "M_D_CPU0_SB_DQ<4>")
	)
	(segment
		(start 278.882094 -222.392494)
		(end 278.130762 -223.143826)
		(width 0.18288)
		(layer "In11.Cu")
		(net "M_D_CPU0_SB_DQ<4>")
	)
	(segment
		(start 314.500006 -224.944178)
		(end 313.524646 -224.944178)
		(width 0.18288)
		(layer "In11.Cu")
		(net "M_D_CPU0_SB_DQ<4>")
	)
	(segment
		(start 282.006294 -222.000826)
		(end 281.127962 -222.000826)
		(width 0.18288)
		(layer "In11.Cu")
		(net "M_D_CPU0_SB_DQ<4>")
	)
	(segment
		(start 342.861392 -238.721138)
		(end 342.850978 -238.715042)
		(width 0.088646)
		(layer "In11.Cu")
		(net "M_D_CPU0_SB_DQ<4>")
	)
	(segment
		(start 295.823894 -222.392494)
		(end 293.679626 -222.392494)
		(width 0.18288)
		(layer "In11.Cu")
		(net "M_D_CPU0_SB_DQ<4>")
	)
	(segment
		(start 276.603714 -223.999806)
		(end 276.273514 -223.999806)
		(width 0.18288)
		(layer "In11.Cu")
		(net "M_D_CPU0_SB_DQ<4>")
	)
	(segment
		(start 282.467812 -221.539308)
		(end 282.006294 -222.000826)
		(width 0.18288)
		(layer "In11.Cu")
		(net "M_D_CPU0_SB_DQ<4>")
	)
	(segment
		(start 340.986364 -238.723678)
		(end 340.971632 -238.715042)
		(width 0.088646)
		(layer "In11.Cu")
		(net "M_D_CPU0_SB_DQ<4>")
	)
	(segment
		(start 297.704764 -221.542356)
		(end 297.297094 -221.950026)
		(width 0.18288)
		(layer "In11.Cu")
		(net "M_D_CPU0_SB_DQ<4>")
	)
	(segment
		(start 343.805764 -238.723678)
		(end 343.791032 -238.715042)
		(width 0.088646)
		(layer "In11.Cu")
		(net "M_D_CPU0_SB_DQ<4>")
	)
	(segment
		(start 330.426822 -235.771944)
		(end 330.313538 -235.771944)
		(width 0.088646)
		(layer "In11.Cu")
		(net "M_D_CPU0_SB_DQ<4>")
	)
	(segment
		(start 293.436294 -222.635826)
		(end 292.547294 -222.635826)
		(width 0.18288)
		(layer "In11.Cu")
		(net "M_D_CPU0_SB_DQ<4>")
	)
	(segment
		(start 301.923704 -221.416626)
		(end 301.730664 -221.609666)
		(width 0.18288)
		(layer "In11.Cu")
		(net "M_D_CPU0_SB_DQ<4>")
	)
	(segment
		(start 273.133058 -226.505262)
		(end 269.424658 -226.505262)
		(width 0.18288)
		(layer "In11.Cu")
		(net "M_D_CPU0_SB_DQ<4>")
	)
	(segment
		(start 274.005294 -225.633026)
		(end 273.133058 -226.505262)
		(width 0.18288)
		(layer "In11.Cu")
		(net "M_D_CPU0_SB_DQ<4>")
	)
	(segment
		(start 292.547294 -222.635826)
		(end 292.115494 -222.204026)
		(width 0.18288)
		(layer "In11.Cu")
		(net "M_D_CPU0_SB_DQ<4>")
	)
	(segment
		(start 293.679626 -222.392494)
		(end 293.436294 -222.635826)
		(width 0.18288)
		(layer "In11.Cu")
		(net "M_D_CPU0_SB_DQ<4>")
	)
	(segment
		(start 278.130762 -223.143826)
		(end 277.459694 -223.143826)
		(width 0.18288)
		(layer "In11.Cu")
		(net "M_D_CPU0_SB_DQ<4>")
	)
	(segment
		(start 336.367882 -237.901226)
		(end 336.357468 -237.907322)
		(width 0.088646)
		(layer "In11.Cu")
		(net "M_D_CPU0_SB_DQ<4>")
	)
	(segment
		(start 301.029624 -221.922848)
		(end 301.029624 -221.609666)
		(width 0.18288)
		(layer "In11.Cu")
		(net "M_D_CPU0_SB_DQ<4>")
	)
	(segment
		(start 337.212432 -238.715042)
		(end 337.206336 -238.711486)
		(width 0.088646)
		(layer "In11.Cu")
		(net "M_D_CPU0_SB_DQ<4>")
	)
	(segment
		(start 303.741074 -222.305626)
		(end 302.852074 -221.416626)
		(width 0.18288)
		(layer "In11.Cu")
		(net "M_D_CPU0_SB_DQ<4>")
	)
	(segment
		(start 307.685694 -223.118426)
		(end 306.872894 -222.305626)
		(width 0.18288)
		(layer "In11.Cu")
		(net "M_D_CPU0_SB_DQ<4>")
	)
	(segment
		(start 276.273514 -223.999806)
		(end 274.640294 -225.633026)
		(width 0.18288)
		(layer "In11.Cu")
		(net "M_D_CPU0_SB_DQ<4>")
	)
	(segment
		(start 344.745564 -238.723678)
		(end 344.730832 -238.715042)
		(width 0.088646)
		(layer "In11.Cu")
		(net "M_D_CPU0_SB_DQ<4>")
	)
	(segment
		(start 312.486294 -223.905826)
		(end 311.292494 -223.905826)
		(width 0.18288)
		(layer "In11.Cu")
		(net "M_D_CPU0_SB_DQ<4>")
	)
	(segment
		(start 337.227164 -238.723678)
		(end 337.212432 -238.715042)
		(width 0.088646)
		(layer "In11.Cu")
		(net "M_D_CPU0_SB_DQ<4>")
	)
	(arc
		(start 340.597236 -238.715042)
		(mid 340.323037 -238.790877)
		(end 340.046564 -238.723678)
		(width 0.088646)
		(layer "In11.Cu")
		(net "M_D_CPU0_SB_DQ<4>")
	)
	(arc
		(start 336.742278 -237.901226)
		(mid 336.55508 -237.851083)
		(end 336.367882 -237.901226)
		(width 0.088646)
		(layer "In11.Cu")
		(net "M_D_CPU0_SB_DQ<4>")
	)
	(arc
		(start 341.537036 -238.715042)
		(mid 341.262837 -238.790877)
		(end 340.986364 -238.723678)
		(width 0.088646)
		(layer "In11.Cu")
		(net "M_D_CPU0_SB_DQ<4>")
	)
	(arc
		(start 337.777836 -238.715042)
		(mid 337.503637 -238.790877)
		(end 337.227164 -238.723678)
		(width 0.088646)
		(layer "In11.Cu")
		(net "M_D_CPU0_SB_DQ<4>")
	)
	(arc
		(start 345.670632 -238.715042)
		(mid 345.483434 -238.664899)
		(end 345.296236 -238.715042)
		(width 0.088646)
		(layer "In11.Cu")
		(net "M_D_CPU0_SB_DQ<4>")
	)
	(arc
		(start 337.206336 -238.711486)
		(mid 337.003749 -238.505135)
		(end 336.92973 -238.225584)
		(width 0.088646)
		(layer "In11.Cu")
		(net "M_D_CPU0_SB_DQ<4>")
	)
	(arc
		(start 346.389452 -239.005618)
		(mid 346.171537 -238.854511)
		(end 345.914472 -238.789464)
		(width 0.088646)
		(layer "In11.Cu")
		(net "M_D_CPU0_SB_DQ<4>")
	)
	(arc
		(start 344.356436 -238.715042)
		(mid 344.082237 -238.790877)
		(end 343.805764 -238.723678)
		(width 0.088646)
		(layer "In11.Cu")
		(net "M_D_CPU0_SB_DQ<4>")
	)
	(arc
		(start 333.452978 -237.08741)
		(mid 333.26578 -237.037267)
		(end 333.078582 -237.08741)
		(width 0.088646)
		(layer "In11.Cu")
		(net "M_D_CPU0_SB_DQ<4>")
	)
	(arc
		(start 336.357468 -237.907322)
		(mid 336.07929 -237.977014)
		(end 335.802732 -237.901226)
		(width 0.088646)
		(layer "In11.Cu")
		(net "M_D_CPU0_SB_DQ<4>")
	)
	(arc
		(start 335.52003 -237.411768)
		(mid 335.472351 -237.228868)
		(end 335.341468 -237.09249)
		(width 0.088646)
		(layer "In11.Cu")
		(net "M_D_CPU0_SB_DQ<4>")
	)
	(arc
		(start 338.152232 -238.715042)
		(mid 337.965034 -238.664899)
		(end 337.777836 -238.715042)
		(width 0.088646)
		(layer "In11.Cu")
		(net "M_D_CPU0_SB_DQ<4>")
	)
	(arc
		(start 344.730832 -238.715042)
		(mid 344.543634 -238.664899)
		(end 344.356436 -238.715042)
		(width 0.088646)
		(layer "In11.Cu")
		(net "M_D_CPU0_SB_DQ<4>")
	)
	(arc
		(start 341.911432 -238.715042)
		(mid 341.724234 -238.664899)
		(end 341.537036 -238.715042)
		(width 0.088646)
		(layer "In11.Cu")
		(net "M_D_CPU0_SB_DQ<4>")
	)
	(arc
		(start 334.947768 -237.093506)
		(mid 334.66959 -237.163229)
		(end 334.393032 -237.08741)
		(width 0.088646)
		(layer "In11.Cu")
		(net "M_D_CPU0_SB_DQ<4>")
	)
	(arc
		(start 342.476582 -238.715042)
		(mid 342.200023 -238.790785)
		(end 341.921846 -238.721138)
		(width 0.088646)
		(layer "In11.Cu")
		(net "M_D_CPU0_SB_DQ<4>")
	)
	(arc
		(start 332.513178 -237.08741)
		(mid 332.422922 -237.049688)
		(end 332.32598 -237.03661)
		(width 0.088646)
		(layer "In11.Cu")
		(net "M_D_CPU0_SB_DQ<4>")
	)
	(arc
		(start 334.393032 -237.08741)
		(mid 334.205834 -237.037267)
		(end 334.018636 -237.08741)
		(width 0.088646)
		(layer "In11.Cu")
		(net "M_D_CPU0_SB_DQ<4>")
	)
	(arc
		(start 338.717636 -238.715042)
		(mid 338.443437 -238.790877)
		(end 338.166964 -238.723678)
		(width 0.088646)
		(layer "In11.Cu")
		(net "M_D_CPU0_SB_DQ<4>")
	)
	(arc
		(start 334.008222 -237.093506)
		(mid 333.72979 -237.163352)
		(end 333.452978 -237.08741)
		(width 0.088646)
		(layer "In11.Cu")
		(net "M_D_CPU0_SB_DQ<4>")
	)
	(arc
		(start 335.332578 -237.08741)
		(mid 335.14538 -237.037267)
		(end 334.958182 -237.08741)
		(width 0.088646)
		(layer "In11.Cu")
		(net "M_D_CPU0_SB_DQ<4>")
	)
	(arc
		(start 340.971632 -238.715042)
		(mid 340.784434 -238.664899)
		(end 340.597236 -238.715042)
		(width 0.088646)
		(layer "In11.Cu")
		(net "M_D_CPU0_SB_DQ<4>")
	)
	(arc
		(start 345.296236 -238.715042)
		(mid 345.022037 -238.790877)
		(end 344.745564 -238.723678)
		(width 0.088646)
		(layer "In11.Cu")
		(net "M_D_CPU0_SB_DQ<4>")
	)
	(arc
		(start 333.06385 -237.096046)
		(mid 332.787375 -237.163366)
		(end 332.513178 -237.08741)
		(width 0.088646)
		(layer "In11.Cu")
		(net "M_D_CPU0_SB_DQ<4>")
	)
	(arc
		(start 340.031832 -238.715042)
		(mid 339.844634 -238.664899)
		(end 339.657436 -238.715042)
		(width 0.088646)
		(layer "In11.Cu")
		(net "M_D_CPU0_SB_DQ<4>")
	)
	(arc
		(start 343.791032 -238.715042)
		(mid 343.603834 -238.664899)
		(end 343.416636 -238.715042)
		(width 0.088646)
		(layer "In11.Cu")
		(net "M_D_CPU0_SB_DQ<4>")
	)
	(arc
		(start 343.416636 -238.715042)
		(mid 343.139823 -238.790912)
		(end 342.861392 -238.721138)
		(width 0.088646)
		(layer "In11.Cu")
		(net "M_D_CPU0_SB_DQ<4>")
	)
	(arc
		(start 336.92973 -238.225584)
		(mid 336.882051 -238.042684)
		(end 336.751168 -237.906306)
		(width 0.088646)
		(layer "In11.Cu")
		(net "M_D_CPU0_SB_DQ<4>")
	)
	(arc
		(start 339.657436 -238.715042)
		(mid 339.374734 -238.790818)
		(end 339.092032 -238.715042)
		(width 0.088646)
		(layer "In11.Cu")
		(net "M_D_CPU0_SB_DQ<4>")
	)
	(arc
		(start 345.914472 -238.789464)
		(mid 345.788305 -238.766173)
		(end 345.670632 -238.715042)
		(width 0.088646)
		(layer "In11.Cu")
		(net "M_D_CPU0_SB_DQ<4>")
	)
	(arc
		(start 342.850978 -238.715042)
		(mid 342.66378 -238.664899)
		(end 342.476582 -238.715042)
		(width 0.088646)
		(layer "In11.Cu")
		(net "M_D_CPU0_SB_DQ<4>")
	)
	(arc
		(start 335.802732 -237.901226)
		(mid 335.597906 -237.697604)
		(end 335.520284 -237.419388)
		(width 0.088646)
		(layer "In11.Cu")
		(net "M_D_CPU0_SB_DQ<4>")
	)
	(arc
		(start 339.092032 -238.715042)
		(mid 338.904834 -238.664899)
		(end 338.717636 -238.715042)
		(width 0.088646)
		(layer "In11.Cu")
		(net "M_D_CPU0_SB_DQ<4>")
	)
	(segment
		(start 262.50011 -230.055928)
		(end 262.146288 -230.055928)
		(width 0.20066)
		(layer "F.Cu")
		(net "M_D_CPU0_SB_DQ<3>")
	)
	(segment
		(start 264.825226 -230.041704)
		(end 262.752332 -230.041704)
		(width 0.1016)
		(layer "F.Cu")
		(net "M_D_CPU0_SB_DQ<3>")
	)
	(segment
		(start 266.90828 -229.616762)
		(end 266.700762 -229.82428)
		(width 0.20066)
		(layer "F.Cu")
		(net "M_D_CPU0_SB_DQ<3>")
	)
	(segment
		(start 262.003794 -229.742746)
		(end 261.87781 -229.616762)
		(width 0.20066)
		(layer "F.Cu")
		(net "M_D_CPU0_SB_DQ<3>")
	)
	(segment
		(start 262.752332 -230.041704)
		(end 262.514334 -230.041704)
		(width 0.101854)
		(layer "F.Cu")
		(net "M_D_CPU0_SB_DQ<3>")
	)
	(segment
		(start 261.87781 -229.616762)
		(end 260.180582 -229.616762)
		(width 0.20066)
		(layer "F.Cu")
		(net "M_D_CPU0_SB_DQ<3>")
	)
	(segment
		(start 266.700762 -229.82428)
		(end 266.25423 -229.82428)
		(width 0.20066)
		(layer "F.Cu")
		(net "M_D_CPU0_SB_DQ<3>")
	)
	(segment
		(start 266.25423 -229.82428)
		(end 266.042394 -229.612444)
		(width 0.20066)
		(layer "F.Cu")
		(net "M_D_CPU0_SB_DQ<3>")
	)
	(segment
		(start 265.369548 -230.041704)
		(end 264.825226 -230.041704)
		(width 0.20066)
		(layer "F.Cu")
		(net "M_D_CPU0_SB_DQ<3>")
	)
	(segment
		(start 348.302834 -241.202972)
		(end 348.302834 -240.667286)
		(width 0.20066)
		(layer "F.Cu")
		(net "M_D_CPU0_SB_DQ<3>")
	)
	(segment
		(start 348.30258 -241.203226)
		(end 348.302834 -241.202972)
		(width 0.20066)
		(layer "F.Cu")
		(net "M_D_CPU0_SB_DQ<3>")
	)
	(segment
		(start 262.514334 -230.041704)
		(end 262.50011 -230.055928)
		(width 0.101854)
		(layer "F.Cu")
		(net "M_D_CPU0_SB_DQ<3>")
	)
	(segment
		(start 265.518646 -229.892606)
		(end 265.369548 -230.041704)
		(width 0.20066)
		(layer "F.Cu")
		(net "M_D_CPU0_SB_DQ<3>")
	)
	(segment
		(start 267.724382 -229.616762)
		(end 266.90828 -229.616762)
		(width 0.20066)
		(layer "F.Cu")
		(net "M_D_CPU0_SB_DQ<3>")
	)
	(segment
		(start 266.042394 -229.612444)
		(end 265.64717 -229.612444)
		(width 0.20066)
		(layer "F.Cu")
		(net "M_D_CPU0_SB_DQ<3>")
	)
	(segment
		(start 265.518646 -229.740968)
		(end 265.518646 -229.892606)
		(width 0.20066)
		(layer "F.Cu")
		(net "M_D_CPU0_SB_DQ<3>")
	)
	(segment
		(start 265.64717 -229.612444)
		(end 265.518646 -229.740968)
		(width 0.20066)
		(layer "F.Cu")
		(net "M_D_CPU0_SB_DQ<3>")
	)
	(segment
		(start 268.829282 -229.616762)
		(end 267.724382 -229.616762)
		(width 0.20066)
		(layer "F.Cu")
		(net "M_D_CPU0_SB_DQ<3>")
	)
	(segment
		(start 262.003794 -229.913434)
		(end 262.003794 -229.742746)
		(width 0.20066)
		(layer "F.Cu")
		(net "M_D_CPU0_SB_DQ<3>")
	)
	(segment
		(start 262.146288 -230.055928)
		(end 262.003794 -229.913434)
		(width 0.20066)
		(layer "F.Cu")
		(net "M_D_CPU0_SB_DQ<3>")
	)
	(segment
		(start 346.625164 -240.351564)
		(end 346.610432 -240.342928)
		(width 0.088646)
		(layer "In11.Cu")
		(net "M_D_CPU0_SB_DQ<3>")
	)
	(segment
		(start 347.947234 -240.572036)
		(end 347.550232 -240.342928)
		(width 0.088646)
		(layer "In11.Cu")
		(net "M_D_CPU0_SB_DQ<3>")
	)
	(segment
		(start 322.573396 -237.936786)
		(end 314.83554 -230.201978)
		(width 0.18288)
		(layer "In11.Cu")
		(net "M_D_CPU0_SB_DQ<3>")
	)
	(segment
		(start 281.841448 -226.852226)
		(end 281.276044 -226.852226)
		(width 0.18288)
		(layer "In11.Cu")
		(net "M_D_CPU0_SB_DQ<3>")
	)
	(segment
		(start 287.804606 -225.912426)
		(end 286.942784 -225.912426)
		(width 0.18288)
		(layer "In11.Cu")
		(net "M_D_CPU0_SB_DQ<3>")
	)
	(segment
		(start 279.694894 -226.642676)
		(end 278.755856 -226.642676)
		(width 0.18288)
		(layer "In11.Cu")
		(net "M_D_CPU0_SB_DQ<3>")
	)
	(segment
		(start 285.855664 -225.912426)
		(end 284.901894 -225.912426)
		(width 0.18288)
		(layer "In11.Cu")
		(net "M_D_CPU0_SB_DQ<3>")
	)
	(segment
		(start 286.048704 -225.719386)
		(end 285.855664 -225.912426)
		(width 0.18288)
		(layer "In11.Cu")
		(net "M_D_CPU0_SB_DQ<3>")
	)
	(segment
		(start 284.782006 -225.792538)
		(end 282.901136 -225.792538)
		(width 0.18288)
		(layer "In11.Cu")
		(net "M_D_CPU0_SB_DQ<3>")
	)
	(segment
		(start 335.710784 -240.667286)
		(end 335.710784 -240.653062)
		(width 0.088646)
		(layer "In11.Cu")
		(net "M_D_CPU0_SB_DQ<3>")
	)
	(segment
		(start 330.68133 -237.936786)
		(end 330.313538 -237.936786)
		(width 0.088646)
		(layer "In11.Cu")
		(net "M_D_CPU0_SB_DQ<3>")
	)
	(segment
		(start 312.987436 -229.442772)
		(end 311.7088 -229.442772)
		(width 0.18288)
		(layer "In11.Cu")
		(net "M_D_CPU0_SB_DQ<3>")
	)
	(segment
		(start 343.805764 -240.983008)
		(end 343.791032 -240.991644)
		(width 0.088646)
		(layer "In11.Cu")
		(net "M_D_CPU0_SB_DQ<3>")
	)
	(segment
		(start 337.227164 -240.983008)
		(end 337.212432 -240.991644)
		(width 0.088646)
		(layer "In11.Cu")
		(net "M_D_CPU0_SB_DQ<3>")
	)
	(segment
		(start 296.090086 -226.716336)
		(end 296.016426 -226.642676)
		(width 0.18288)
		(layer "In11.Cu")
		(net "M_D_CPU0_SB_DQ<3>")
	)
	(segment
		(start 271.27962 -229.436422)
		(end 270.96466 -229.436422)
		(width 0.18288)
		(layer "In11.Cu")
		(net "M_D_CPU0_SB_DQ<3>")
	)
	(segment
		(start 288.744406 -226.852226)
		(end 287.804606 -225.912426)
		(width 0.18288)
		(layer "In11.Cu")
		(net "M_D_CPU0_SB_DQ<3>")
	)
	(segment
		(start 271.47266 -229.629462)
		(end 271.27962 -229.436422)
		(width 0.18288)
		(layer "In11.Cu")
		(net "M_D_CPU0_SB_DQ<3>")
	)
	(segment
		(start 338.162646 -240.985548)
		(end 338.152232 -240.991644)
		(width 0.088646)
		(layer "In11.Cu")
		(net "M_D_CPU0_SB_DQ<3>")
	)
	(segment
		(start 270.77162 -230.011732)
		(end 270.57858 -230.204772)
		(width 0.18288)
		(layer "In11.Cu")
		(net "M_D_CPU0_SB_DQ<3>")
	)
	(segment
		(start 335.898236 -240.991644)
		(end 335.889346 -240.986564)
		(width 0.088646)
		(layer "In11.Cu")
		(net "M_D_CPU0_SB_DQ<3>")
	)
	(segment
		(start 301.263558 -225.239072)
		(end 301.070518 -225.432112)
		(width 0.18288)
		(layer "In11.Cu")
		(net "M_D_CPU0_SB_DQ<3>")
	)
	(segment
		(start 332.528164 -239.355122)
		(end 332.513432 -239.363758)
		(width 0.088646)
		(layer "In11.Cu")
		(net "M_D_CPU0_SB_DQ<3>")
	)
	(segment
		(start 286.048704 -225.5012)
		(end 286.048704 -225.719386)
		(width 0.18288)
		(layer "In11.Cu")
		(net "M_D_CPU0_SB_DQ<3>")
	)
	(segment
		(start 314.456826 -230.045006)
		(end 313.58967 -230.045006)
		(width 0.18288)
		(layer "In11.Cu")
		(net "M_D_CPU0_SB_DQ<3>")
	)
	(segment
		(start 293.888668 -226.642676)
		(end 292.967918 -227.563426)
		(width 0.18288)
		(layer "In11.Cu")
		(net "M_D_CPU0_SB_DQ<3>")
	)
	(segment
		(start 274.398486 -229.202234)
		(end 273.766026 -229.202234)
		(width 0.18288)
		(layer "In11.Cu")
		(net "M_D_CPU0_SB_DQ<3>")
	)
	(segment
		(start 309.55996 -229.191312)
		(end 307.932074 -227.563426)
		(width 0.18288)
		(layer "In11.Cu")
		(net "M_D_CPU0_SB_DQ<3>")
	)
	(segment
		(start 339.102192 -240.985548)
		(end 339.091778 -240.991644)
		(width 0.088646)
		(layer "In11.Cu")
		(net "M_D_CPU0_SB_DQ<3>")
	)
	(segment
		(start 286.749744 -225.719386)
		(end 286.749744 -225.5012)
		(width 0.18288)
		(layer "In11.Cu")
		(net "M_D_CPU0_SB_DQ<3>")
	)
	(segment
		(start 271.47266 -230.011732)
		(end 271.47266 -229.629462)
		(width 0.18288)
		(layer "In11.Cu")
		(net "M_D_CPU0_SB_DQ<3>")
	)
	(segment
		(start 270.96466 -229.436422)
		(end 270.77162 -229.629462)
		(width 0.18288)
		(layer "In11.Cu")
		(net "M_D_CPU0_SB_DQ<3>")
	)
	(segment
		(start 279.696672 -226.640898)
		(end 279.694894 -226.642676)
		(width 0.18288)
		(layer "In11.Cu")
		(net "M_D_CPU0_SB_DQ<3>")
	)
	(segment
		(start 297.988736 -225.792538)
		(end 297.064938 -226.716336)
		(width 0.18288)
		(layer "In11.Cu")
		(net "M_D_CPU0_SB_DQ<3>")
	)
	(segment
		(start 300.877478 -225.988626)
		(end 299.862494 -225.988626)
		(width 0.18288)
		(layer "In11.Cu")
		(net "M_D_CPU0_SB_DQ<3>")
	)
	(segment
		(start 307.932074 -227.563426)
		(end 305.577494 -227.563426)
		(width 0.18288)
		(layer "In11.Cu")
		(net "M_D_CPU0_SB_DQ<3>")
	)
	(segment
		(start 282.901136 -225.792538)
		(end 281.841448 -226.852226)
		(width 0.18288)
		(layer "In11.Cu")
		(net "M_D_CPU0_SB_DQ<3>")
	)
	(segment
		(start 279.999694 -226.642676)
		(end 279.997916 -226.640898)
		(width 0.18288)
		(layer "In11.Cu")
		(net "M_D_CPU0_SB_DQ<3>")
	)
	(segment
		(start 304.815494 -226.801426)
		(end 303.977294 -226.801426)
		(width 0.18288)
		(layer "In11.Cu")
		(net "M_D_CPU0_SB_DQ<3>")
	)
	(segment
		(start 278.755856 -226.642676)
		(end 277.732236 -227.666296)
		(width 0.18288)
		(layer "In11.Cu")
		(net "M_D_CPU0_SB_DQ<3>")
	)
	(segment
		(start 297.064938 -226.716336)
		(end 296.090086 -226.716336)
		(width 0.18288)
		(layer "In11.Cu")
		(net "M_D_CPU0_SB_DQ<3>")
	)
	(segment
		(start 303.164494 -225.988626)
		(end 301.964598 -225.988626)
		(width 0.18288)
		(layer "In11.Cu")
		(net "M_D_CPU0_SB_DQ<3>")
	)
	(segment
		(start 269.417292 -230.204772)
		(end 268.829282 -229.616762)
		(width 0.18288)
		(layer "In11.Cu")
		(net "M_D_CPU0_SB_DQ<3>")
	)
	(segment
		(start 284.901894 -225.912426)
		(end 284.782006 -225.792538)
		(width 0.18288)
		(layer "In11.Cu")
		(net "M_D_CPU0_SB_DQ<3>")
	)
	(segment
		(start 335.428082 -240.177574)
		(end 335.41335 -240.168938)
		(width 0.088646)
		(layer "In11.Cu")
		(net "M_D_CPU0_SB_DQ<3>")
	)
	(segment
		(start 301.771558 -225.432112)
		(end 301.578518 -225.239072)
		(width 0.18288)
		(layer "In11.Cu")
		(net "M_D_CPU0_SB_DQ<3>")
	)
	(segment
		(start 313.58967 -230.045006)
		(end 312.987436 -229.442772)
		(width 0.18288)
		(layer "In11.Cu")
		(net "M_D_CPU0_SB_DQ<3>")
	)
	(segment
		(start 332.158848 -239.414304)
		(end 330.68133 -237.936786)
		(width 0.088646)
		(layer "In11.Cu")
		(net "M_D_CPU0_SB_DQ<3>")
	)
	(segment
		(start 342.865964 -240.983008)
		(end 342.851232 -240.991644)
		(width 0.088646)
		(layer "In11.Cu")
		(net "M_D_CPU0_SB_DQ<3>")
	)
	(segment
		(start 273.766026 -229.202234)
		(end 272.763488 -230.204772)
		(width 0.18288)
		(layer "In11.Cu")
		(net "M_D_CPU0_SB_DQ<3>")
	)
	(segment
		(start 292.967918 -227.563426)
		(end 290.718494 -227.563426)
		(width 0.18288)
		(layer "In11.Cu")
		(net "M_D_CPU0_SB_DQ<3>")
	)
	(segment
		(start 340.986364 -240.983008)
		(end 340.971632 -240.991644)
		(width 0.088646)
		(layer "In11.Cu")
		(net "M_D_CPU0_SB_DQ<3>")
	)
	(segment
		(start 270.57858 -230.204772)
		(end 269.417292 -230.204772)
		(width 0.18288)
		(layer "In11.Cu")
		(net "M_D_CPU0_SB_DQ<3>")
	)
	(segment
		(start 336.287364 -240.983008)
		(end 336.272632 -240.991644)
		(width 0.088646)
		(layer "In11.Cu")
		(net "M_D_CPU0_SB_DQ<3>")
	)
	(segment
		(start 305.577494 -227.563426)
		(end 304.815494 -226.801426)
		(width 0.18288)
		(layer "In11.Cu")
		(net "M_D_CPU0_SB_DQ<3>")
	)
	(segment
		(start 281.066494 -226.642676)
		(end 279.999694 -226.642676)
		(width 0.18288)
		(layer "In11.Cu")
		(net "M_D_CPU0_SB_DQ<3>")
	)
	(segment
		(start 270.77162 -229.629462)
		(end 270.77162 -230.011732)
		(width 0.18288)
		(layer "In11.Cu")
		(net "M_D_CPU0_SB_DQ<3>")
	)
	(segment
		(start 277.410164 -227.666296)
		(end 276.786594 -228.289866)
		(width 0.18288)
		(layer "In11.Cu")
		(net "M_D_CPU0_SB_DQ<3>")
	)
	(segment
		(start 345.948762 -240.624106)
		(end 345.910408 -240.7158)
		(width 0.088646)
		(layer "In11.Cu")
		(net "M_D_CPU0_SB_DQ<3>")
	)
	(segment
		(start 311.45734 -229.191312)
		(end 309.55996 -229.191312)
		(width 0.18288)
		(layer "In11.Cu")
		(net "M_D_CPU0_SB_DQ<3>")
	)
	(segment
		(start 340.046564 -240.983008)
		(end 340.031832 -240.991644)
		(width 0.088646)
		(layer "In11.Cu")
		(net "M_D_CPU0_SB_DQ<3>")
	)
	(segment
		(start 286.942784 -225.912426)
		(end 286.749744 -225.719386)
		(width 0.18288)
		(layer "In11.Cu")
		(net "M_D_CPU0_SB_DQ<3>")
	)
	(segment
		(start 271.6657 -230.204772)
		(end 271.47266 -230.011732)
		(width 0.18288)
		(layer "In11.Cu")
		(net "M_D_CPU0_SB_DQ<3>")
	)
	(segment
		(start 330.313538 -237.936786)
		(end 322.573396 -237.936786)
		(width 0.18288)
		(layer "In11.Cu")
		(net "M_D_CPU0_SB_DQ<3>")
	)
	(segment
		(start 311.7088 -229.442772)
		(end 311.45734 -229.191312)
		(width 0.18288)
		(layer "In11.Cu")
		(net "M_D_CPU0_SB_DQ<3>")
	)
	(segment
		(start 303.977294 -226.801426)
		(end 303.164494 -225.988626)
		(width 0.18288)
		(layer "In11.Cu")
		(net "M_D_CPU0_SB_DQ<3>")
	)
	(segment
		(start 334.30083 -239.853216)
		(end 334.30083 -239.837722)
		(width 0.088646)
		(layer "In11.Cu")
		(net "M_D_CPU0_SB_DQ<3>")
	)
	(segment
		(start 301.070518 -225.432112)
		(end 301.070518 -225.795586)
		(width 0.18288)
		(layer "In11.Cu")
		(net "M_D_CPU0_SB_DQ<3>")
	)
	(segment
		(start 281.276044 -226.852226)
		(end 281.066494 -226.642676)
		(width 0.18288)
		(layer "In11.Cu")
		(net "M_D_CPU0_SB_DQ<3>")
	)
	(segment
		(start 290.007294 -226.852226)
		(end 288.744406 -226.852226)
		(width 0.18288)
		(layer "In11.Cu")
		(net "M_D_CPU0_SB_DQ<3>")
	)
	(segment
		(start 301.578518 -225.239072)
		(end 301.263558 -225.239072)
		(width 0.18288)
		(layer "In11.Cu")
		(net "M_D_CPU0_SB_DQ<3>")
	)
	(segment
		(start 286.749744 -225.5012)
		(end 286.556704 -225.30816)
		(width 0.18288)
		(layer "In11.Cu")
		(net "M_D_CPU0_SB_DQ<3>")
	)
	(segment
		(start 290.718494 -227.563426)
		(end 290.007294 -226.852226)
		(width 0.18288)
		(layer "In11.Cu")
		(net "M_D_CPU0_SB_DQ<3>")
	)
	(segment
		(start 332.326234 -239.414304)
		(end 332.158848 -239.414304)
		(width 0.088646)
		(layer "In11.Cu")
		(net "M_D_CPU0_SB_DQ<3>")
	)
	(segment
		(start 301.070518 -225.795586)
		(end 300.877478 -225.988626)
		(width 0.18288)
		(layer "In11.Cu")
		(net "M_D_CPU0_SB_DQ<3>")
	)
	(segment
		(start 301.771558 -225.795586)
		(end 301.771558 -225.432112)
		(width 0.18288)
		(layer "In11.Cu")
		(net "M_D_CPU0_SB_DQ<3>")
	)
	(segment
		(start 301.964598 -225.988626)
		(end 301.771558 -225.795586)
		(width 0.18288)
		(layer "In11.Cu")
		(net "M_D_CPU0_SB_DQ<3>")
	)
	(segment
		(start 299.862494 -225.988626)
		(end 299.666406 -225.792538)
		(width 0.18288)
		(layer "In11.Cu")
		(net "M_D_CPU0_SB_DQ<3>")
	)
	(segment
		(start 276.786594 -228.289866)
		(end 275.310854 -228.289866)
		(width 0.18288)
		(layer "In11.Cu")
		(net "M_D_CPU0_SB_DQ<3>")
	)
	(segment
		(start 314.83554 -230.201978)
		(end 314.456826 -230.045006)
		(width 0.18288)
		(layer "In11.Cu")
		(net "M_D_CPU0_SB_DQ<3>")
	)
	(segment
		(start 286.556704 -225.30816)
		(end 286.241744 -225.30816)
		(width 0.18288)
		(layer "In11.Cu")
		(net "M_D_CPU0_SB_DQ<3>")
	)
	(segment
		(start 344.741246 -240.985548)
		(end 344.730832 -240.991644)
		(width 0.088646)
		(layer "In11.Cu")
		(net "M_D_CPU0_SB_DQ<3>")
	)
	(segment
		(start 275.310854 -228.289866)
		(end 274.398486 -229.202234)
		(width 0.18288)
		(layer "In11.Cu")
		(net "M_D_CPU0_SB_DQ<3>")
	)
	(segment
		(start 299.666406 -225.792538)
		(end 297.988736 -225.792538)
		(width 0.18288)
		(layer "In11.Cu")
		(net "M_D_CPU0_SB_DQ<3>")
	)
	(segment
		(start 277.732236 -227.666296)
		(end 277.410164 -227.666296)
		(width 0.18288)
		(layer "In11.Cu")
		(net "M_D_CPU0_SB_DQ<3>")
	)
	(segment
		(start 296.016426 -226.642676)
		(end 293.888668 -226.642676)
		(width 0.18288)
		(layer "In11.Cu")
		(net "M_D_CPU0_SB_DQ<3>")
	)
	(segment
		(start 279.997916 -226.640898)
		(end 279.696672 -226.640898)
		(width 0.18288)
		(layer "In11.Cu")
		(net "M_D_CPU0_SB_DQ<3>")
	)
	(segment
		(start 272.763488 -230.204772)
		(end 271.6657 -230.204772)
		(width 0.18288)
		(layer "In11.Cu")
		(net "M_D_CPU0_SB_DQ<3>")
	)
	(segment
		(start 334.488282 -240.177574)
		(end 334.479392 -240.172494)
		(width 0.088646)
		(layer "In11.Cu")
		(net "M_D_CPU0_SB_DQ<3>")
	)
	(segment
		(start 286.241744 -225.30816)
		(end 286.048704 -225.5012)
		(width 0.18288)
		(layer "In11.Cu")
		(net "M_D_CPU0_SB_DQ<3>")
	)
	(segment
		(start 333.467964 -239.355122)
		(end 333.453232 -239.363758)
		(width 0.088646)
		(layer "In11.Cu")
		(net "M_D_CPU0_SB_DQ<3>")
	)
	(arc
		(start 337.777836 -240.991644)
		(mid 337.503637 -240.915809)
		(end 337.227164 -240.983008)
		(width 0.088646)
		(layer "In11.Cu")
		(net "M_D_CPU0_SB_DQ<3>")
	)
	(arc
		(start 345.68003 -240.985802)
		(mid 345.67524 -240.988782)
		(end 345.670378 -240.991644)
		(width 0.088646)
		(layer "In11.Cu")
		(net "M_D_CPU0_SB_DQ<3>")
	)
	(arc
		(start 343.791032 -240.991644)
		(mid 343.603834 -241.041787)
		(end 343.416636 -240.991644)
		(width 0.088646)
		(layer "In11.Cu")
		(net "M_D_CPU0_SB_DQ<3>")
	)
	(arc
		(start 337.212432 -240.991644)
		(mid 337.025234 -241.041787)
		(end 336.838036 -240.991644)
		(width 0.088646)
		(layer "In11.Cu")
		(net "M_D_CPU0_SB_DQ<3>")
	)
	(arc
		(start 346.03309 -240.49863)
		(mid 345.984832 -240.557269)
		(end 345.948762 -240.624106)
		(width 0.088646)
		(layer "In11.Cu")
		(net "M_D_CPU0_SB_DQ<3>")
	)
	(arc
		(start 345.670378 -240.991644)
		(mid 345.48318 -241.041787)
		(end 345.295982 -240.991644)
		(width 0.088646)
		(layer "In11.Cu")
		(net "M_D_CPU0_SB_DQ<3>")
	)
	(arc
		(start 340.971632 -240.991644)
		(mid 340.784434 -241.041787)
		(end 340.597236 -240.991644)
		(width 0.088646)
		(layer "In11.Cu")
		(net "M_D_CPU0_SB_DQ<3>")
	)
	(arc
		(start 336.838036 -240.991644)
		(mid 336.563837 -240.915809)
		(end 336.287364 -240.983008)
		(width 0.088646)
		(layer "In11.Cu")
		(net "M_D_CPU0_SB_DQ<3>")
	)
	(arc
		(start 334.30083 -239.837722)
		(mid 334.22146 -239.563988)
		(end 334.018636 -239.363758)
		(width 0.088646)
		(layer "In11.Cu")
		(net "M_D_CPU0_SB_DQ<3>")
	)
	(arc
		(start 342.851232 -240.991644)
		(mid 342.664034 -241.041787)
		(end 342.476836 -240.991644)
		(width 0.088646)
		(layer "In11.Cu")
		(net "M_D_CPU0_SB_DQ<3>")
	)
	(arc
		(start 344.730832 -240.991644)
		(mid 344.543634 -241.041787)
		(end 344.356436 -240.991644)
		(width 0.088646)
		(layer "In11.Cu")
		(net "M_D_CPU0_SB_DQ<3>")
	)
	(arc
		(start 340.031832 -240.991644)
		(mid 339.844634 -241.041787)
		(end 339.657436 -240.991644)
		(width 0.088646)
		(layer "In11.Cu")
		(net "M_D_CPU0_SB_DQ<3>")
	)
	(arc
		(start 334.018636 -239.363758)
		(mid 333.744437 -239.287923)
		(end 333.467964 -239.355122)
		(width 0.088646)
		(layer "In11.Cu")
		(net "M_D_CPU0_SB_DQ<3>")
	)
	(arc
		(start 335.41335 -240.168938)
		(mid 335.136909 -240.101772)
		(end 334.862678 -240.177574)
		(width 0.088646)
		(layer "In11.Cu")
		(net "M_D_CPU0_SB_DQ<3>")
	)
	(arc
		(start 335.710784 -240.653062)
		(mid 335.631565 -240.378377)
		(end 335.428082 -240.177574)
		(width 0.088646)
		(layer "In11.Cu")
		(net "M_D_CPU0_SB_DQ<3>")
	)
	(arc
		(start 334.479392 -240.172494)
		(mid 334.348478 -240.036134)
		(end 334.30083 -239.853216)
		(width 0.088646)
		(layer "In11.Cu")
		(net "M_D_CPU0_SB_DQ<3>")
	)
	(arc
		(start 346.610432 -240.342928)
		(mid 346.423234 -240.292785)
		(end 346.236036 -240.342928)
		(width 0.088646)
		(layer "In11.Cu")
		(net "M_D_CPU0_SB_DQ<3>")
	)
	(arc
		(start 332.513432 -239.363758)
		(mid 332.42316 -239.401357)
		(end 332.326234 -239.414304)
		(width 0.088646)
		(layer "In11.Cu")
		(net "M_D_CPU0_SB_DQ<3>")
	)
	(arc
		(start 346.236036 -240.342928)
		(mid 346.129456 -240.414122)
		(end 346.03309 -240.49863)
		(width 0.088646)
		(layer "In11.Cu")
		(net "M_D_CPU0_SB_DQ<3>")
	)
	(arc
		(start 333.453232 -239.363758)
		(mid 333.266034 -239.413901)
		(end 333.078836 -239.363758)
		(width 0.088646)
		(layer "In11.Cu")
		(net "M_D_CPU0_SB_DQ<3>")
	)
	(arc
		(start 345.295982 -240.991644)
		(mid 345.019423 -240.915901)
		(end 344.741246 -240.985548)
		(width 0.088646)
		(layer "In11.Cu")
		(net "M_D_CPU0_SB_DQ<3>")
	)
	(arc
		(start 335.889346 -240.986564)
		(mid 335.758432 -240.850204)
		(end 335.710784 -240.667286)
		(width 0.088646)
		(layer "In11.Cu")
		(net "M_D_CPU0_SB_DQ<3>")
	)
	(arc
		(start 347.175836 -240.342928)
		(mid 346.901607 -240.418853)
		(end 346.625164 -240.351564)
		(width 0.088646)
		(layer "In11.Cu")
		(net "M_D_CPU0_SB_DQ<3>")
	)
	(arc
		(start 344.356436 -240.991644)
		(mid 344.082237 -240.915809)
		(end 343.805764 -240.983008)
		(width 0.088646)
		(layer "In11.Cu")
		(net "M_D_CPU0_SB_DQ<3>")
	)
	(arc
		(start 339.657436 -240.991644)
		(mid 339.380623 -240.915774)
		(end 339.102192 -240.985548)
		(width 0.088646)
		(layer "In11.Cu")
		(net "M_D_CPU0_SB_DQ<3>")
	)
	(arc
		(start 345.910408 -240.7158)
		(mid 345.816353 -240.868826)
		(end 345.68003 -240.985802)
		(width 0.088646)
		(layer "In11.Cu")
		(net "M_D_CPU0_SB_DQ<3>")
	)
	(arc
		(start 340.597236 -240.991644)
		(mid 340.323037 -240.915809)
		(end 340.046564 -240.983008)
		(width 0.088646)
		(layer "In11.Cu")
		(net "M_D_CPU0_SB_DQ<3>")
	)
	(arc
		(start 341.911432 -240.991644)
		(mid 341.724234 -241.041787)
		(end 341.537036 -240.991644)
		(width 0.088646)
		(layer "In11.Cu")
		(net "M_D_CPU0_SB_DQ<3>")
	)
	(arc
		(start 341.537036 -240.991644)
		(mid 341.262837 -240.915809)
		(end 340.986364 -240.983008)
		(width 0.088646)
		(layer "In11.Cu")
		(net "M_D_CPU0_SB_DQ<3>")
	)
	(arc
		(start 338.152232 -240.991644)
		(mid 337.965034 -241.041787)
		(end 337.777836 -240.991644)
		(width 0.088646)
		(layer "In11.Cu")
		(net "M_D_CPU0_SB_DQ<3>")
	)
	(arc
		(start 334.862678 -240.177574)
		(mid 334.67548 -240.227717)
		(end 334.488282 -240.177574)
		(width 0.088646)
		(layer "In11.Cu")
		(net "M_D_CPU0_SB_DQ<3>")
	)
	(arc
		(start 338.717382 -240.991644)
		(mid 338.440823 -240.915901)
		(end 338.162646 -240.985548)
		(width 0.088646)
		(layer "In11.Cu")
		(net "M_D_CPU0_SB_DQ<3>")
	)
	(arc
		(start 348.302834 -240.667286)
		(mid 348.118765 -240.643062)
		(end 347.947234 -240.572036)
		(width 0.088646)
		(layer "In11.Cu")
		(net "M_D_CPU0_SB_DQ<3>")
	)
	(arc
		(start 339.091778 -240.991644)
		(mid 338.90458 -241.041787)
		(end 338.717382 -240.991644)
		(width 0.088646)
		(layer "In11.Cu")
		(net "M_D_CPU0_SB_DQ<3>")
	)
	(arc
		(start 343.416636 -240.991644)
		(mid 343.142437 -240.915809)
		(end 342.865964 -240.983008)
		(width 0.088646)
		(layer "In11.Cu")
		(net "M_D_CPU0_SB_DQ<3>")
	)
	(arc
		(start 342.476836 -240.991644)
		(mid 342.194134 -240.915868)
		(end 341.911432 -240.991644)
		(width 0.088646)
		(layer "In11.Cu")
		(net "M_D_CPU0_SB_DQ<3>")
	)
	(arc
		(start 347.550232 -240.342928)
		(mid 347.363034 -240.292785)
		(end 347.175836 -240.342928)
		(width 0.088646)
		(layer "In11.Cu")
		(net "M_D_CPU0_SB_DQ<3>")
	)
	(arc
		(start 333.078836 -239.363758)
		(mid 332.804637 -239.287923)
		(end 332.528164 -239.355122)
		(width 0.088646)
		(layer "In11.Cu")
		(net "M_D_CPU0_SB_DQ<3>")
	)
	(arc
		(start 336.272632 -240.991644)
		(mid 336.085434 -241.041787)
		(end 335.898236 -240.991644)
		(width 0.088646)
		(layer "In11.Cu")
		(net "M_D_CPU0_SB_DQ<3>")
	)
	(segment
		(start 262.514334 -196.041518)
		(end 262.50011 -196.055742)
		(width 0.101854)
		(layer "F.Cu")
		(net "M_D_CPU0_SB_DQ<31>")
	)
	(segment
		(start 347.832934 -228.99497)
		(end 347.83268 -228.994716)
		(width 0.20066)
		(layer "F.Cu")
		(net "M_D_CPU0_SB_DQ<31>")
	)
	(segment
		(start 265.518646 -195.740782)
		(end 265.518646 -195.89242)
		(width 0.20066)
		(layer "F.Cu")
		(net "M_D_CPU0_SB_DQ<31>")
	)
	(segment
		(start 262.50011 -196.055742)
		(end 262.146288 -196.055742)
		(width 0.20066)
		(layer "F.Cu")
		(net "M_D_CPU0_SB_DQ<31>")
	)
	(segment
		(start 262.752332 -196.041518)
		(end 262.514334 -196.041518)
		(width 0.101854)
		(layer "F.Cu")
		(net "M_D_CPU0_SB_DQ<31>")
	)
	(segment
		(start 266.700762 -195.824094)
		(end 266.25423 -195.824094)
		(width 0.20066)
		(layer "F.Cu")
		(net "M_D_CPU0_SB_DQ<31>")
	)
	(segment
		(start 261.87781 -195.616576)
		(end 260.180582 -195.616576)
		(width 0.20066)
		(layer "F.Cu")
		(net "M_D_CPU0_SB_DQ<31>")
	)
	(segment
		(start 262.003794 -195.74256)
		(end 261.87781 -195.616576)
		(width 0.20066)
		(layer "F.Cu")
		(net "M_D_CPU0_SB_DQ<31>")
	)
	(segment
		(start 265.64717 -195.612258)
		(end 265.518646 -195.740782)
		(width 0.20066)
		(layer "F.Cu")
		(net "M_D_CPU0_SB_DQ<31>")
	)
	(segment
		(start 347.83268 -228.994716)
		(end 347.83268 -228.45903)
		(width 0.20066)
		(layer "F.Cu")
		(net "M_D_CPU0_SB_DQ<31>")
	)
	(segment
		(start 267.724382 -195.616576)
		(end 266.90828 -195.616576)
		(width 0.20066)
		(layer "F.Cu")
		(net "M_D_CPU0_SB_DQ<31>")
	)
	(segment
		(start 262.146288 -196.055742)
		(end 262.003794 -195.913248)
		(width 0.20066)
		(layer "F.Cu")
		(net "M_D_CPU0_SB_DQ<31>")
	)
	(segment
		(start 266.90828 -195.616576)
		(end 266.700762 -195.824094)
		(width 0.20066)
		(layer "F.Cu")
		(net "M_D_CPU0_SB_DQ<31>")
	)
	(segment
		(start 268.829282 -195.616576)
		(end 267.724382 -195.616576)
		(width 0.20066)
		(layer "F.Cu")
		(net "M_D_CPU0_SB_DQ<31>")
	)
	(segment
		(start 266.25423 -195.824094)
		(end 266.042394 -195.612258)
		(width 0.20066)
		(layer "F.Cu")
		(net "M_D_CPU0_SB_DQ<31>")
	)
	(segment
		(start 265.518646 -195.89242)
		(end 265.369548 -196.041518)
		(width 0.20066)
		(layer "F.Cu")
		(net "M_D_CPU0_SB_DQ<31>")
	)
	(segment
		(start 266.042394 -195.612258)
		(end 265.64717 -195.612258)
		(width 0.20066)
		(layer "F.Cu")
		(net "M_D_CPU0_SB_DQ<31>")
	)
	(segment
		(start 265.369548 -196.041518)
		(end 264.825226 -196.041518)
		(width 0.20066)
		(layer "F.Cu")
		(net "M_D_CPU0_SB_DQ<31>")
	)
	(segment
		(start 262.003794 -195.913248)
		(end 262.003794 -195.74256)
		(width 0.20066)
		(layer "F.Cu")
		(net "M_D_CPU0_SB_DQ<31>")
	)
	(segment
		(start 264.825226 -196.041518)
		(end 262.752332 -196.041518)
		(width 0.1016)
		(layer "F.Cu")
		(net "M_D_CPU0_SB_DQ<31>")
	)
	(segment
		(start 312.910474 -193.16954)
		(end 312.595514 -193.16954)
		(width 0.18288)
		(layer "In11.Cu")
		(net "M_D_CPU0_SB_DQ<31>")
	)
	(segment
		(start 336.838036 -224.7138)
		(end 336.829146 -224.70872)
		(width 0.088646)
		(layer "In11.Cu")
		(net "M_D_CPU0_SB_DQ<31>")
	)
	(segment
		(start 273.998944 -193.768472)
		(end 271.113758 -194.740022)
		(width 0.18288)
		(layer "In11.Cu")
		(net "M_D_CPU0_SB_DQ<31>")
	)
	(segment
		(start 347.519752 -228.45903)
		(end 347.462602 -228.40188)
		(width 0.088646)
		(layer "In11.Cu")
		(net "M_D_CPU0_SB_DQ<31>")
	)
	(segment
		(start 319.708784 -204.587602)
		(end 314.490354 -194.173856)
		(width 0.18288)
		(layer "In11.Cu")
		(net "M_D_CPU0_SB_DQ<31>")
	)
	(segment
		(start 332.796134 -223.95053)
		(end 332.610968 -223.95053)
		(width 0.088646)
		(layer "In11.Cu")
		(net "M_D_CPU0_SB_DQ<31>")
	)
	(segment
		(start 342.946482 -225.527616)
		(end 342.93175 -225.51898)
		(width 0.088646)
		(layer "In11.Cu")
		(net "M_D_CPU0_SB_DQ<31>")
	)
	(segment
		(start 309.791354 -193.16954)
		(end 309.598314 -193.36258)
		(width 0.18288)
		(layer "In11.Cu")
		(net "M_D_CPU0_SB_DQ<31>")
	)
	(segment
		(start 347.651832 -227.159058)
		(end 347.636846 -227.150422)
		(width 0.088646)
		(layer "In11.Cu")
		(net "M_D_CPU0_SB_DQ<31>")
	)
	(segment
		(start 331.814932 -222.5675)
		(end 331.814932 -221.595442)
		(width 0.088646)
		(layer "In11.Cu")
		(net "M_D_CPU0_SB_DQ<31>")
	)
	(segment
		(start 331.244702 -220.352874)
		(end 326.356472 -215.464644)
		(width 0.18288)
		(layer "In11.Cu")
		(net "M_D_CPU0_SB_DQ<31>")
	)
	(segment
		(start 314.490354 -194.173856)
		(end 313.834018 -193.768472)
		(width 0.18288)
		(layer "In11.Cu")
		(net "M_D_CPU0_SB_DQ<31>")
	)
	(segment
		(start 337.120484 -225.211894)
		(end 337.120484 -225.193352)
		(width 0.088646)
		(layer "In11.Cu")
		(net "M_D_CPU0_SB_DQ<31>")
	)
	(segment
		(start 311.701434 -193.36258)
		(end 311.508394 -193.16954)
		(width 0.18288)
		(layer "In11.Cu")
		(net "M_D_CPU0_SB_DQ<31>")
	)
	(segment
		(start 311.894474 -193.768472)
		(end 311.701434 -193.575432)
		(width 0.18288)
		(layer "In11.Cu")
		(net "M_D_CPU0_SB_DQ<31>")
	)
	(segment
		(start 313.834018 -193.768472)
		(end 313.296554 -193.768472)
		(width 0.18288)
		(layer "In11.Cu")
		(net "M_D_CPU0_SB_DQ<31>")
	)
	(segment
		(start 347.636592 -228.139752)
		(end 347.645482 -228.134672)
		(width 0.088646)
		(layer "In11.Cu")
		(net "M_D_CPU0_SB_DQ<31>")
	)
	(segment
		(start 313.103514 -193.36258)
		(end 312.910474 -193.16954)
		(width 0.18288)
		(layer "In11.Cu")
		(net "M_D_CPU0_SB_DQ<31>")
	)
	(segment
		(start 331.339444 -220.447616)
		(end 331.244702 -220.352874)
		(width 0.088646)
		(layer "In11.Cu")
		(net "M_D_CPU0_SB_DQ<31>")
	)
	(segment
		(start 312.402474 -193.36258)
		(end 312.402474 -193.575432)
		(width 0.18288)
		(layer "In11.Cu")
		(net "M_D_CPU0_SB_DQ<31>")
	)
	(segment
		(start 326.356472 -211.23529)
		(end 319.708784 -204.587602)
		(width 0.18288)
		(layer "In11.Cu")
		(net "M_D_CPU0_SB_DQ<31>")
	)
	(segment
		(start 338.247482 -225.527616)
		(end 338.23275 -225.51898)
		(width 0.088646)
		(layer "In11.Cu")
		(net "M_D_CPU0_SB_DQ<31>")
	)
	(segment
		(start 312.209434 -193.768472)
		(end 311.894474 -193.768472)
		(width 0.18288)
		(layer "In11.Cu")
		(net "M_D_CPU0_SB_DQ<31>")
	)
	(segment
		(start 313.296554 -193.768472)
		(end 313.103514 -193.575432)
		(width 0.18288)
		(layer "In11.Cu")
		(net "M_D_CPU0_SB_DQ<31>")
	)
	(segment
		(start 332.610968 -223.95053)
		(end 332.229968 -223.56953)
		(width 0.088646)
		(layer "In11.Cu")
		(net "M_D_CPU0_SB_DQ<31>")
	)
	(segment
		(start 312.402474 -193.575432)
		(end 312.209434 -193.768472)
		(width 0.18288)
		(layer "In11.Cu")
		(net "M_D_CPU0_SB_DQ<31>")
	)
	(segment
		(start 270.661384 -195.192396)
		(end 269.253462 -195.192396)
		(width 0.18288)
		(layer "In11.Cu")
		(net "M_D_CPU0_SB_DQ<31>")
	)
	(segment
		(start 311.000394 -193.575432)
		(end 310.807354 -193.768472)
		(width 0.18288)
		(layer "In11.Cu")
		(net "M_D_CPU0_SB_DQ<31>")
	)
	(segment
		(start 310.299354 -193.36258)
		(end 310.106314 -193.16954)
		(width 0.18288)
		(layer "In11.Cu")
		(net "M_D_CPU0_SB_DQ<31>")
	)
	(segment
		(start 310.299354 -193.575432)
		(end 310.299354 -193.36258)
		(width 0.18288)
		(layer "In11.Cu")
		(net "M_D_CPU0_SB_DQ<31>")
	)
	(segment
		(start 332.998064 -223.891348)
		(end 332.983332 -223.899984)
		(width 0.088646)
		(layer "In11.Cu")
		(net "M_D_CPU0_SB_DQ<31>")
	)
	(segment
		(start 311.193434 -193.16954)
		(end 311.000394 -193.36258)
		(width 0.18288)
		(layer "In11.Cu")
		(net "M_D_CPU0_SB_DQ<31>")
	)
	(segment
		(start 344.826082 -225.527616)
		(end 344.81135 -225.51898)
		(width 0.088646)
		(layer "In11.Cu")
		(net "M_D_CPU0_SB_DQ<31>")
	)
	(segment
		(start 326.356472 -215.464644)
		(end 326.356472 -211.23529)
		(width 0.18288)
		(layer "In11.Cu")
		(net "M_D_CPU0_SB_DQ<31>")
	)
	(segment
		(start 311.000394 -193.36258)
		(end 311.000394 -193.575432)
		(width 0.18288)
		(layer "In11.Cu")
		(net "M_D_CPU0_SB_DQ<31>")
	)
	(segment
		(start 347.83268 -228.45903)
		(end 347.519752 -228.45903)
		(width 0.088646)
		(layer "In11.Cu")
		(net "M_D_CPU0_SB_DQ<31>")
	)
	(segment
		(start 309.598314 -193.36258)
		(end 309.598314 -193.575432)
		(width 0.18288)
		(layer "In11.Cu")
		(net "M_D_CPU0_SB_DQ<31>")
	)
	(segment
		(start 311.508394 -193.16954)
		(end 311.193434 -193.16954)
		(width 0.18288)
		(layer "In11.Cu")
		(net "M_D_CPU0_SB_DQ<31>")
	)
	(segment
		(start 346.988384 -226.017328)
		(end 346.988384 -226.003104)
		(width 0.088646)
		(layer "In11.Cu")
		(net "M_D_CPU0_SB_DQ<31>")
	)
	(segment
		(start 347.458284 -226.831144)
		(end 347.458284 -226.821238)
		(width 0.088646)
		(layer "In11.Cu")
		(net "M_D_CPU0_SB_DQ<31>")
	)
	(segment
		(start 342.006682 -225.527616)
		(end 341.99195 -225.51898)
		(width 0.088646)
		(layer "In11.Cu")
		(net "M_D_CPU0_SB_DQ<31>")
	)
	(segment
		(start 309.598314 -193.575432)
		(end 309.405274 -193.768472)
		(width 0.18288)
		(layer "In11.Cu")
		(net "M_D_CPU0_SB_DQ<31>")
	)
	(segment
		(start 345.765882 -225.527616)
		(end 345.75115 -225.51898)
		(width 0.088646)
		(layer "In11.Cu")
		(net "M_D_CPU0_SB_DQ<31>")
	)
	(segment
		(start 310.492394 -193.768472)
		(end 310.299354 -193.575432)
		(width 0.18288)
		(layer "In11.Cu")
		(net "M_D_CPU0_SB_DQ<31>")
	)
	(segment
		(start 310.807354 -193.768472)
		(end 310.492394 -193.768472)
		(width 0.18288)
		(layer "In11.Cu")
		(net "M_D_CPU0_SB_DQ<31>")
	)
	(segment
		(start 311.701434 -193.575432)
		(end 311.701434 -193.36258)
		(width 0.18288)
		(layer "In11.Cu")
		(net "M_D_CPU0_SB_DQ<31>")
	)
	(segment
		(start 271.113758 -194.740022)
		(end 270.661384 -195.192396)
		(width 0.18288)
		(layer "In11.Cu")
		(net "M_D_CPU0_SB_DQ<31>")
	)
	(segment
		(start 331.814932 -221.595442)
		(end 331.339444 -220.447616)
		(width 0.088646)
		(layer "In11.Cu")
		(net "M_D_CPU0_SB_DQ<31>")
	)
	(segment
		(start 310.106314 -193.16954)
		(end 309.791354 -193.16954)
		(width 0.18288)
		(layer "In11.Cu")
		(net "M_D_CPU0_SB_DQ<31>")
	)
	(segment
		(start 340.127082 -225.527616)
		(end 340.11235 -225.51898)
		(width 0.088646)
		(layer "In11.Cu")
		(net "M_D_CPU0_SB_DQ<31>")
	)
	(segment
		(start 313.103514 -193.575432)
		(end 313.103514 -193.36258)
		(width 0.18288)
		(layer "In11.Cu")
		(net "M_D_CPU0_SB_DQ<31>")
	)
	(segment
		(start 332.229968 -223.56953)
		(end 331.814932 -222.5675)
		(width 0.088646)
		(layer "In11.Cu")
		(net "M_D_CPU0_SB_DQ<31>")
	)
	(segment
		(start 343.886282 -225.527616)
		(end 343.87155 -225.51898)
		(width 0.088646)
		(layer "In11.Cu")
		(net "M_D_CPU0_SB_DQ<31>")
	)
	(segment
		(start 347.175836 -226.341686)
		(end 347.166946 -226.336606)
		(width 0.088646)
		(layer "In11.Cu")
		(net "M_D_CPU0_SB_DQ<31>")
	)
	(segment
		(start 309.405274 -193.768472)
		(end 273.998944 -193.768472)
		(width 0.18288)
		(layer "In11.Cu")
		(net "M_D_CPU0_SB_DQ<31>")
	)
	(segment
		(start 341.066882 -225.527616)
		(end 341.05215 -225.51898)
		(width 0.088646)
		(layer "In11.Cu")
		(net "M_D_CPU0_SB_DQ<31>")
	)
	(segment
		(start 269.253462 -195.192396)
		(end 268.829282 -195.616576)
		(width 0.18288)
		(layer "In11.Cu")
		(net "M_D_CPU0_SB_DQ<31>")
	)
	(segment
		(start 312.595514 -193.16954)
		(end 312.402474 -193.36258)
		(width 0.18288)
		(layer "In11.Cu")
		(net "M_D_CPU0_SB_DQ<31>")
	)
	(arc
		(start 338.621878 -225.527616)
		(mid 338.43468 -225.577759)
		(end 338.247482 -225.527616)
		(width 0.088646)
		(layer "In11.Cu")
		(net "M_D_CPU0_SB_DQ<31>")
	)
	(arc
		(start 347.645482 -228.134672)
		(mid 347.928222 -227.648663)
		(end 347.651832 -227.159058)
		(width 0.088646)
		(layer "In11.Cu")
		(net "M_D_CPU0_SB_DQ<31>")
	)
	(arc
		(start 337.120484 -225.193352)
		(mid 337.042373 -224.916403)
		(end 336.838036 -224.7138)
		(width 0.088646)
		(layer "In11.Cu")
		(net "M_D_CPU0_SB_DQ<31>")
	)
	(arc
		(start 347.166946 -226.336606)
		(mid 347.036032 -226.200246)
		(end 346.988384 -226.017328)
		(width 0.088646)
		(layer "In11.Cu")
		(net "M_D_CPU0_SB_DQ<31>")
	)
	(arc
		(start 336.829146 -224.70872)
		(mid 336.698232 -224.57236)
		(end 336.650584 -224.389442)
		(width 0.088646)
		(layer "In11.Cu")
		(net "M_D_CPU0_SB_DQ<31>")
	)
	(arc
		(start 339.561678 -225.527616)
		(mid 339.37448 -225.577759)
		(end 339.187282 -225.527616)
		(width 0.088646)
		(layer "In11.Cu")
		(net "M_D_CPU0_SB_DQ<31>")
	)
	(arc
		(start 342.381078 -225.527616)
		(mid 342.19388 -225.577759)
		(end 342.006682 -225.527616)
		(width 0.088646)
		(layer "In11.Cu")
		(net "M_D_CPU0_SB_DQ<31>")
	)
	(arc
		(start 340.11235 -225.51898)
		(mid 339.835909 -225.451814)
		(end 339.561678 -225.527616)
		(width 0.088646)
		(layer "In11.Cu")
		(net "M_D_CPU0_SB_DQ<31>")
	)
	(arc
		(start 340.501478 -225.527616)
		(mid 340.31428 -225.577759)
		(end 340.127082 -225.527616)
		(width 0.088646)
		(layer "In11.Cu")
		(net "M_D_CPU0_SB_DQ<31>")
	)
	(arc
		(start 333.923132 -223.899984)
		(mid 333.735934 -223.950127)
		(end 333.548736 -223.899984)
		(width 0.088646)
		(layer "In11.Cu")
		(net "M_D_CPU0_SB_DQ<31>")
	)
	(arc
		(start 341.99195 -225.51898)
		(mid 341.715509 -225.451814)
		(end 341.441278 -225.527616)
		(width 0.088646)
		(layer "In11.Cu")
		(net "M_D_CPU0_SB_DQ<31>")
	)
	(arc
		(start 344.260678 -225.527616)
		(mid 344.07348 -225.577759)
		(end 343.886282 -225.527616)
		(width 0.088646)
		(layer "In11.Cu")
		(net "M_D_CPU0_SB_DQ<31>")
	)
	(arc
		(start 336.650584 -224.389442)
		(mid 336.367967 -223.899983)
		(end 335.802732 -223.899984)
		(width 0.088646)
		(layer "In11.Cu")
		(net "M_D_CPU0_SB_DQ<31>")
	)
	(arc
		(start 335.428336 -223.899984)
		(mid 335.145634 -223.824208)
		(end 334.862932 -223.899984)
		(width 0.088646)
		(layer "In11.Cu")
		(net "M_D_CPU0_SB_DQ<31>")
	)
	(arc
		(start 338.23275 -225.51898)
		(mid 337.956309 -225.451814)
		(end 337.682078 -225.527616)
		(width 0.088646)
		(layer "In11.Cu")
		(net "M_D_CPU0_SB_DQ<31>")
	)
	(arc
		(start 347.636846 -227.150422)
		(mid 347.505932 -227.014062)
		(end 347.458284 -226.831144)
		(width 0.088646)
		(layer "In11.Cu")
		(net "M_D_CPU0_SB_DQ<31>")
	)
	(arc
		(start 345.200478 -225.527616)
		(mid 345.01328 -225.577759)
		(end 344.826082 -225.527616)
		(width 0.088646)
		(layer "In11.Cu")
		(net "M_D_CPU0_SB_DQ<31>")
	)
	(arc
		(start 346.988384 -226.003104)
		(mid 346.699685 -225.523957)
		(end 346.140278 -225.527616)
		(width 0.088646)
		(layer "In11.Cu")
		(net "M_D_CPU0_SB_DQ<31>")
	)
	(arc
		(start 342.93175 -225.51898)
		(mid 342.655309 -225.451814)
		(end 342.381078 -225.527616)
		(width 0.088646)
		(layer "In11.Cu")
		(net "M_D_CPU0_SB_DQ<31>")
	)
	(arc
		(start 335.802732 -223.899984)
		(mid 335.615534 -223.950127)
		(end 335.428336 -223.899984)
		(width 0.088646)
		(layer "In11.Cu")
		(net "M_D_CPU0_SB_DQ<31>")
	)
	(arc
		(start 347.462602 -228.40188)
		(mid 347.520721 -228.251639)
		(end 347.636592 -228.139752)
		(width 0.088646)
		(layer "In11.Cu")
		(net "M_D_CPU0_SB_DQ<31>")
	)
	(arc
		(start 347.458284 -226.821238)
		(mid 347.380173 -226.544289)
		(end 347.175836 -226.341686)
		(width 0.088646)
		(layer "In11.Cu")
		(net "M_D_CPU0_SB_DQ<31>")
	)
	(arc
		(start 344.81135 -225.51898)
		(mid 344.534909 -225.451814)
		(end 344.260678 -225.527616)
		(width 0.088646)
		(layer "In11.Cu")
		(net "M_D_CPU0_SB_DQ<31>")
	)
	(arc
		(start 334.862932 -223.899984)
		(mid 334.675734 -223.950127)
		(end 334.488536 -223.899984)
		(width 0.088646)
		(layer "In11.Cu")
		(net "M_D_CPU0_SB_DQ<31>")
	)
	(arc
		(start 345.75115 -225.51898)
		(mid 345.474709 -225.451814)
		(end 345.200478 -225.527616)
		(width 0.088646)
		(layer "In11.Cu")
		(net "M_D_CPU0_SB_DQ<31>")
	)
	(arc
		(start 343.320878 -225.527616)
		(mid 343.13368 -225.577759)
		(end 342.946482 -225.527616)
		(width 0.088646)
		(layer "In11.Cu")
		(net "M_D_CPU0_SB_DQ<31>")
	)
	(arc
		(start 332.983332 -223.899984)
		(mid 332.89306 -223.937583)
		(end 332.796134 -223.95053)
		(width 0.088646)
		(layer "In11.Cu")
		(net "M_D_CPU0_SB_DQ<31>")
	)
	(arc
		(start 334.488536 -223.899984)
		(mid 334.205834 -223.824208)
		(end 333.923132 -223.899984)
		(width 0.088646)
		(layer "In11.Cu")
		(net "M_D_CPU0_SB_DQ<31>")
	)
	(arc
		(start 339.187282 -225.527616)
		(mid 338.90458 -225.451874)
		(end 338.621878 -225.527616)
		(width 0.088646)
		(layer "In11.Cu")
		(net "M_D_CPU0_SB_DQ<31>")
	)
	(arc
		(start 333.548736 -223.899984)
		(mid 333.274537 -223.824149)
		(end 332.998064 -223.891348)
		(width 0.088646)
		(layer "In11.Cu")
		(net "M_D_CPU0_SB_DQ<31>")
	)
	(arc
		(start 341.441278 -225.527616)
		(mid 341.25408 -225.577759)
		(end 341.066882 -225.527616)
		(width 0.088646)
		(layer "In11.Cu")
		(net "M_D_CPU0_SB_DQ<31>")
	)
	(arc
		(start 337.682078 -225.527616)
		(mid 337.311355 -225.529708)
		(end 337.120484 -225.211894)
		(width 0.088646)
		(layer "In11.Cu")
		(net "M_D_CPU0_SB_DQ<31>")
	)
	(arc
		(start 346.140278 -225.527616)
		(mid 345.95308 -225.577759)
		(end 345.765882 -225.527616)
		(width 0.088646)
		(layer "In11.Cu")
		(net "M_D_CPU0_SB_DQ<31>")
	)
	(arc
		(start 343.87155 -225.51898)
		(mid 343.595109 -225.451814)
		(end 343.320878 -225.527616)
		(width 0.088646)
		(layer "In11.Cu")
		(net "M_D_CPU0_SB_DQ<31>")
	)
	(arc
		(start 341.05215 -225.51898)
		(mid 340.775709 -225.451814)
		(end 340.501478 -225.527616)
		(width 0.088646)
		(layer "In11.Cu")
		(net "M_D_CPU0_SB_DQ<31>")
	)
	(segment
		(start 262.50011 -196.881496)
		(end 261.762748 -196.881496)
		(width 0.20066)
		(layer "F.Cu")
		(net "M_D_CPU0_SB_DQ<30>")
	)
	(segment
		(start 261.762748 -196.881496)
		(end 261.327646 -197.316598)
		(width 0.20066)
		(layer "F.Cu")
		(net "M_D_CPU0_SB_DQ<30>")
	)
	(segment
		(start 262.765286 -196.891656)
		(end 262.51027 -196.891656)
		(width 0.101854)
		(layer "F.Cu")
		(net "M_D_CPU0_SB_DQ<30>")
	)
	(segment
		(start 265.458194 -196.891656)
		(end 264.825226 -196.891656)
		(width 0.20066)
		(layer "F.Cu")
		(net "M_D_CPU0_SB_DQ<30>")
	)
	(segment
		(start 264.825226 -196.891656)
		(end 262.765286 -196.891656)
		(width 0.1016)
		(layer "F.Cu")
		(net "M_D_CPU0_SB_DQ<30>")
	)
	(segment
		(start 348.302834 -229.808532)
		(end 348.302834 -229.272846)
		(width 0.20066)
		(layer "F.Cu")
		(net "M_D_CPU0_SB_DQ<30>")
	)
	(segment
		(start 268.829282 -197.316598)
		(end 267.724382 -197.316598)
		(width 0.20066)
		(layer "F.Cu")
		(net "M_D_CPU0_SB_DQ<30>")
	)
	(segment
		(start 265.769344 -197.528434)
		(end 265.601958 -197.361048)
		(width 0.20066)
		(layer "F.Cu")
		(net "M_D_CPU0_SB_DQ<30>")
	)
	(segment
		(start 267.724382 -197.316598)
		(end 266.409678 -197.316598)
		(width 0.20066)
		(layer "F.Cu")
		(net "M_D_CPU0_SB_DQ<30>")
	)
	(segment
		(start 261.327646 -197.316598)
		(end 260.180582 -197.316598)
		(width 0.20066)
		(layer "F.Cu")
		(net "M_D_CPU0_SB_DQ<30>")
	)
	(segment
		(start 266.197842 -197.528434)
		(end 265.769344 -197.528434)
		(width 0.20066)
		(layer "F.Cu")
		(net "M_D_CPU0_SB_DQ<30>")
	)
	(segment
		(start 266.409678 -197.316598)
		(end 266.197842 -197.528434)
		(width 0.20066)
		(layer "F.Cu")
		(net "M_D_CPU0_SB_DQ<30>")
	)
	(segment
		(start 262.51027 -196.891656)
		(end 262.50011 -196.881496)
		(width 0.101854)
		(layer "F.Cu")
		(net "M_D_CPU0_SB_DQ<30>")
	)
	(segment
		(start 265.601958 -197.361048)
		(end 265.601958 -197.03542)
		(width 0.20066)
		(layer "F.Cu")
		(net "M_D_CPU0_SB_DQ<30>")
	)
	(segment
		(start 265.601958 -197.03542)
		(end 265.458194 -196.891656)
		(width 0.20066)
		(layer "F.Cu")
		(net "M_D_CPU0_SB_DQ<30>")
	)
	(segment
		(start 348.30258 -229.808786)
		(end 348.302834 -229.808532)
		(width 0.20066)
		(layer "F.Cu")
		(net "M_D_CPU0_SB_DQ<30>")
	)
	(segment
		(start 281.033982 -194.968114)
		(end 279.130252 -194.968114)
		(width 0.18288)
		(layer "In11.Cu")
		(net "M_D_CPU0_SB_DQ<30>")
	)
	(segment
		(start 334.018636 -224.7138)
		(end 334.008222 -224.707704)
		(width 0.088646)
		(layer "In11.Cu")
		(net "M_D_CPU0_SB_DQ<30>")
	)
	(segment
		(start 312.463434 -195.842128)
		(end 311.459118 -195.842128)
		(width 0.18288)
		(layer "In11.Cu")
		(net "M_D_CPU0_SB_DQ<30>")
	)
	(segment
		(start 302.011588 -195.052696)
		(end 301.872396 -195.191888)
		(width 0.18288)
		(layer "In11.Cu")
		(net "M_D_CPU0_SB_DQ<30>")
	)
	(segment
		(start 295.379902 -195.34251)
		(end 295.041574 -195.004182)
		(width 0.18288)
		(layer "In11.Cu")
		(net "M_D_CPU0_SB_DQ<30>")
	)
	(segment
		(start 336.838036 -226.341686)
		(end 336.829146 -226.336606)
		(width 0.088646)
		(layer "In11.Cu")
		(net "M_D_CPU0_SB_DQ<30>")
	)
	(segment
		(start 311.170828 -196.130418)
		(end 307.572918 -196.130418)
		(width 0.18288)
		(layer "In11.Cu")
		(net "M_D_CPU0_SB_DQ<30>")
	)
	(segment
		(start 294.590724 -195.004182)
		(end 294.400478 -195.194428)
		(width 0.18288)
		(layer "In11.Cu")
		(net "M_D_CPU0_SB_DQ<30>")
	)
	(segment
		(start 338.162646 -226.33559)
		(end 338.152232 -226.341686)
		(width 0.088646)
		(layer "In11.Cu")
		(net "M_D_CPU0_SB_DQ<30>")
	)
	(segment
		(start 342.865964 -226.33305)
		(end 342.851232 -226.341686)
		(width 0.088646)
		(layer "In11.Cu")
		(net "M_D_CPU0_SB_DQ<30>")
	)
	(segment
		(start 303.321212 -195.204334)
		(end 303.169574 -195.052696)
		(width 0.18288)
		(layer "In11.Cu")
		(net "M_D_CPU0_SB_DQ<30>")
	)
	(segment
		(start 324.994016 -211.800186)
		(end 317.540386 -204.346556)
		(width 0.18288)
		(layer "In11.Cu")
		(net "M_D_CPU0_SB_DQ<30>")
	)
	(segment
		(start 297.873166 -195.191888)
		(end 297.722544 -195.34251)
		(width 0.18288)
		(layer "In11.Cu")
		(net "M_D_CPU0_SB_DQ<30>")
	)
	(segment
		(start 332.518004 -224.638108)
		(end 331.367892 -223.487996)
		(width 0.088646)
		(layer "In11.Cu")
		(net "M_D_CPU0_SB_DQ<30>")
	)
	(segment
		(start 303.169574 -195.052696)
		(end 302.011588 -195.052696)
		(width 0.18288)
		(layer "In11.Cu")
		(net "M_D_CPU0_SB_DQ<30>")
	)
	(segment
		(start 317.540386 -204.346556)
		(end 314.452254 -197.830948)
		(width 0.18288)
		(layer "In11.Cu")
		(net "M_D_CPU0_SB_DQ<30>")
	)
	(segment
		(start 284.95625 -196.189092)
		(end 284.807914 -196.040756)
		(width 0.18288)
		(layer "In11.Cu")
		(net "M_D_CPU0_SB_DQ<30>")
	)
	(segment
		(start 272.653252 -196.189092)
		(end 271.434052 -196.189092)
		(width 0.18288)
		(layer "In11.Cu")
		(net "M_D_CPU0_SB_DQ<30>")
	)
	(segment
		(start 339.657436 -226.341686)
		(end 339.647022 -226.33559)
		(width 0.088646)
		(layer "In11.Cu")
		(net "M_D_CPU0_SB_DQ<30>")
	)
	(segment
		(start 332.796134 -224.638108)
		(end 332.518004 -224.638108)
		(width 0.088646)
		(layer "In11.Cu")
		(net "M_D_CPU0_SB_DQ<30>")
	)
	(segment
		(start 288.887916 -195.194428)
		(end 287.893252 -196.189092)
		(width 0.18288)
		(layer "In11.Cu")
		(net "M_D_CPU0_SB_DQ<30>")
	)
	(segment
		(start 340.046564 -226.33305)
		(end 340.031832 -226.341686)
		(width 0.088646)
		(layer "In11.Cu")
		(net "M_D_CPU0_SB_DQ<30>")
	)
	(segment
		(start 346.518484 -228.467666)
		(end 346.518484 -228.450394)
		(width 0.088646)
		(layer "In11.Cu")
		(net "M_D_CPU0_SB_DQ<30>")
	)
	(segment
		(start 347.557598 -228.912674)
		(end 346.849954 -228.83114)
		(width 0.088646)
		(layer "In11.Cu")
		(net "M_D_CPU0_SB_DQ<30>")
	)
	(segment
		(start 330.673964 -221.432882)
		(end 330.537566 -221.432882)
		(width 0.088646)
		(layer "In11.Cu")
		(net "M_D_CPU0_SB_DQ<30>")
	)
	(segment
		(start 281.371294 -195.305426)
		(end 281.033982 -194.968114)
		(width 0.18288)
		(layer "In11.Cu")
		(net "M_D_CPU0_SB_DQ<30>")
	)
	(segment
		(start 269.443454 -196.702426)
		(end 268.829282 -197.316598)
		(width 0.18288)
		(layer "In11.Cu")
		(net "M_D_CPU0_SB_DQ<30>")
	)
	(segment
		(start 295.041574 -195.004182)
		(end 294.590724 -195.004182)
		(width 0.18288)
		(layer "In11.Cu")
		(net "M_D_CPU0_SB_DQ<30>")
	)
	(segment
		(start 306.646834 -195.204334)
		(end 303.321212 -195.204334)
		(width 0.18288)
		(layer "In11.Cu")
		(net "M_D_CPU0_SB_DQ<30>")
	)
	(segment
		(start 286.102552 -195.13042)
		(end 285.909512 -195.32346)
		(width 0.18288)
		(layer "In11.Cu")
		(net "M_D_CPU0_SB_DQ<30>")
	)
	(segment
		(start 286.610552 -195.996052)
		(end 286.610552 -195.32346)
		(width 0.18288)
		(layer "In11.Cu")
		(net "M_D_CPU0_SB_DQ<30>")
	)
	(segment
		(start 346.705936 -227.155502)
		(end 346.697046 -227.150422)
		(width 0.088646)
		(layer "In11.Cu")
		(net "M_D_CPU0_SB_DQ<30>")
	)
	(segment
		(start 273.647408 -195.194936)
		(end 272.653252 -196.189092)
		(width 0.18288)
		(layer "In11.Cu")
		(net "M_D_CPU0_SB_DQ<30>")
	)
	(segment
		(start 271.434052 -196.189092)
		(end 270.920718 -196.702426)
		(width 0.18288)
		(layer "In11.Cu")
		(net "M_D_CPU0_SB_DQ<30>")
	)
	(segment
		(start 285.909512 -195.996052)
		(end 285.716472 -196.189092)
		(width 0.18288)
		(layer "In11.Cu")
		(net "M_D_CPU0_SB_DQ<30>")
	)
	(segment
		(start 336.368136 -225.527616)
		(end 336.359246 -225.522536)
		(width 0.088646)
		(layer "In11.Cu")
		(net "M_D_CPU0_SB_DQ<30>")
	)
	(segment
		(start 287.893252 -196.189092)
		(end 286.803592 -196.189092)
		(width 0.18288)
		(layer "In11.Cu")
		(net "M_D_CPU0_SB_DQ<30>")
	)
	(segment
		(start 294.400478 -195.194428)
		(end 288.887916 -195.194428)
		(width 0.18288)
		(layer "In11.Cu")
		(net "M_D_CPU0_SB_DQ<30>")
	)
	(segment
		(start 345.685364 -226.33305)
		(end 345.670632 -226.341686)
		(width 0.088646)
		(layer "In11.Cu")
		(net "M_D_CPU0_SB_DQ<30>")
	)
	(segment
		(start 278.90343 -195.194936)
		(end 273.647408 -195.194936)
		(width 0.18288)
		(layer "In11.Cu")
		(net "M_D_CPU0_SB_DQ<30>")
	)
	(segment
		(start 346.988384 -227.659184)
		(end 346.988384 -227.635054)
		(width 0.088646)
		(layer "In11.Cu")
		(net "M_D_CPU0_SB_DQ<30>")
	)
	(segment
		(start 330.39812 -221.432882)
		(end 324.994016 -216.028778)
		(width 0.18288)
		(layer "In11.Cu")
		(net "M_D_CPU0_SB_DQ<30>")
	)
	(segment
		(start 314.452254 -197.830948)
		(end 312.463434 -195.842128)
		(width 0.18288)
		(layer "In11.Cu")
		(net "M_D_CPU0_SB_DQ<30>")
	)
	(segment
		(start 286.610552 -195.32346)
		(end 286.417512 -195.13042)
		(width 0.18288)
		(layer "In11.Cu")
		(net "M_D_CPU0_SB_DQ<30>")
	)
	(segment
		(start 301.872396 -195.191888)
		(end 297.873166 -195.191888)
		(width 0.18288)
		(layer "In11.Cu")
		(net "M_D_CPU0_SB_DQ<30>")
	)
	(segment
		(start 344.745564 -226.33305)
		(end 344.730832 -226.341686)
		(width 0.088646)
		(layer "In11.Cu")
		(net "M_D_CPU0_SB_DQ<30>")
	)
	(segment
		(start 286.417512 -195.13042)
		(end 286.102552 -195.13042)
		(width 0.18288)
		(layer "In11.Cu")
		(net "M_D_CPU0_SB_DQ<30>")
	)
	(segment
		(start 307.572918 -196.130418)
		(end 306.646834 -195.204334)
		(width 0.18288)
		(layer "In11.Cu")
		(net "M_D_CPU0_SB_DQ<30>")
	)
	(segment
		(start 311.459118 -195.842128)
		(end 311.170828 -196.130418)
		(width 0.18288)
		(layer "In11.Cu")
		(net "M_D_CPU0_SB_DQ<30>")
	)
	(segment
		(start 346.242132 -226.345242)
		(end 346.236036 -226.341686)
		(width 0.088646)
		(layer "In11.Cu")
		(net "M_D_CPU0_SB_DQ<30>")
	)
	(segment
		(start 336.650584 -226.017328)
		(end 336.650584 -225.998786)
		(width 0.088646)
		(layer "In11.Cu")
		(net "M_D_CPU0_SB_DQ<30>")
	)
	(segment
		(start 341.926164 -226.33305)
		(end 341.911432 -226.341686)
		(width 0.088646)
		(layer "In11.Cu")
		(net "M_D_CPU0_SB_DQ<30>")
	)
	(segment
		(start 285.909512 -195.32346)
		(end 285.909512 -195.996052)
		(width 0.18288)
		(layer "In11.Cu")
		(net "M_D_CPU0_SB_DQ<30>")
	)
	(segment
		(start 337.227164 -226.33305)
		(end 337.212432 -226.341686)
		(width 0.088646)
		(layer "In11.Cu")
		(net "M_D_CPU0_SB_DQ<30>")
	)
	(segment
		(start 336.180684 -225.203258)
		(end 336.180684 -225.193352)
		(width 0.088646)
		(layer "In11.Cu")
		(net "M_D_CPU0_SB_DQ<30>")
	)
	(segment
		(start 340.986364 -226.33305)
		(end 340.971632 -226.341686)
		(width 0.088646)
		(layer "In11.Cu")
		(net "M_D_CPU0_SB_DQ<30>")
	)
	(segment
		(start 324.994016 -216.028778)
		(end 324.994016 -211.800186)
		(width 0.18288)
		(layer "In11.Cu")
		(net "M_D_CPU0_SB_DQ<30>")
	)
	(segment
		(start 283.402024 -196.040756)
		(end 282.666694 -195.305426)
		(width 0.18288)
		(layer "In11.Cu")
		(net "M_D_CPU0_SB_DQ<30>")
	)
	(segment
		(start 286.803592 -196.189092)
		(end 286.610552 -195.996052)
		(width 0.18288)
		(layer "In11.Cu")
		(net "M_D_CPU0_SB_DQ<30>")
	)
	(segment
		(start 284.807914 -196.040756)
		(end 283.402024 -196.040756)
		(width 0.18288)
		(layer "In11.Cu")
		(net "M_D_CPU0_SB_DQ<30>")
	)
	(segment
		(start 270.920718 -196.702426)
		(end 269.443454 -196.702426)
		(width 0.18288)
		(layer "In11.Cu")
		(net "M_D_CPU0_SB_DQ<30>")
	)
	(segment
		(start 279.130252 -194.968114)
		(end 278.90343 -195.194936)
		(width 0.18288)
		(layer "In11.Cu")
		(net "M_D_CPU0_SB_DQ<30>")
	)
	(segment
		(start 297.722544 -195.34251)
		(end 295.379902 -195.34251)
		(width 0.18288)
		(layer "In11.Cu")
		(net "M_D_CPU0_SB_DQ<30>")
	)
	(segment
		(start 330.537566 -221.432882)
		(end 330.39812 -221.432882)
		(width 0.18288)
		(layer "In11.Cu")
		(net "M_D_CPU0_SB_DQ<30>")
	)
	(segment
		(start 282.666694 -195.305426)
		(end 281.371294 -195.305426)
		(width 0.18288)
		(layer "In11.Cu")
		(net "M_D_CPU0_SB_DQ<30>")
	)
	(segment
		(start 285.716472 -196.189092)
		(end 284.95625 -196.189092)
		(width 0.18288)
		(layer "In11.Cu")
		(net "M_D_CPU0_SB_DQ<30>")
	)
	(segment
		(start 331.367892 -222.12681)
		(end 330.673964 -221.432882)
		(width 0.088646)
		(layer "In11.Cu")
		(net "M_D_CPU0_SB_DQ<30>")
	)
	(segment
		(start 331.367892 -223.487996)
		(end 331.367892 -222.12681)
		(width 0.088646)
		(layer "In11.Cu")
		(net "M_D_CPU0_SB_DQ<30>")
	)
	(arc
		(start 337.777836 -226.341686)
		(mid 337.503637 -226.265851)
		(end 337.227164 -226.33305)
		(width 0.088646)
		(layer "In11.Cu")
		(net "M_D_CPU0_SB_DQ<30>")
	)
	(arc
		(start 334.393032 -224.7138)
		(mid 334.205834 -224.763943)
		(end 334.018636 -224.7138)
		(width 0.088646)
		(layer "In11.Cu")
		(net "M_D_CPU0_SB_DQ<30>")
	)
	(arc
		(start 346.849954 -228.83114)
		(mid 346.779522 -228.816043)
		(end 346.713302 -228.787706)
		(width 0.088646)
		(layer "In11.Cu")
		(net "M_D_CPU0_SB_DQ<30>")
	)
	(arc
		(start 346.518484 -226.831144)
		(mid 346.444568 -226.551642)
		(end 346.242132 -226.345242)
		(width 0.088646)
		(layer "In11.Cu")
		(net "M_D_CPU0_SB_DQ<30>")
	)
	(arc
		(start 341.911432 -226.341686)
		(mid 341.724234 -226.391829)
		(end 341.537036 -226.341686)
		(width 0.088646)
		(layer "In11.Cu")
		(net "M_D_CPU0_SB_DQ<30>")
	)
	(arc
		(start 346.236036 -226.341686)
		(mid 345.961837 -226.265851)
		(end 345.685364 -226.33305)
		(width 0.088646)
		(layer "In11.Cu")
		(net "M_D_CPU0_SB_DQ<30>")
	)
)
